(kicad_pcb
	(version 20260206)
	(generator "pcbnew")
	(generator_version "10.0")
	(general
		(thickness 1.6)
		(legacy_teardrops no)
	)
	(paper "A4")
	(layers
		(0 "F.Cu" signal "TOP")
		(4 "In1.Cu" signal "GND")
		(6 "In2.Cu" signal "IN1")
		(8 "In3.Cu" signal "GND1")
		(10 "In4.Cu" signal "IN2")
		(12 "In5.Cu" signal "GND2")
		(14 "In6.Cu" signal "IN3")
		(16 "In7.Cu" signal "GND3")
		(18 "In8.Cu" signal "VCC")
		(20 "In9.Cu" signal "VCC1")
		(22 "In10.Cu" signal "GND4")
		(24 "In11.Cu" signal "IN4")
		(26 "In12.Cu" signal "GND5")
		(28 "In13.Cu" signal "IN5")
		(30 "In14.Cu" signal "GND6")
		(32 "In15.Cu" signal "IN6")
		(34 "In16.Cu" signal "GND7")
		(2 "B.Cu" signal "BOTTOM")
		(9 "F.Adhes" user "F.Adhesive")
		(11 "B.Adhes" user "B.Adhesive")
		(13 "F.Paste" user "Package Geometry/Pastemask Top")
		(15 "B.Paste" user "Package Geometry/Pastemask Bottom")
		(5 "F.SilkS" user "Ref Des/Silkscreen Top")
		(7 "B.SilkS" user "Ref Des/Silkscreen Bottom")
		(1 "F.Mask" user "Board Geometry/Soldermask Top")
		(3 "B.Mask" user "Board Geometry/Soldermask Bottom")
		(17 "Dwgs.User" user "User.Drawings")
		(19 "Cmts.User" user "User.Comments")
		(21 "Eco1.User" user "User.Eco1")
		(23 "Eco2.User" user "User.Eco2")
		(25 "Edge.Cuts" user "Board Geometry/Outline")
		(27 "Margin" user)
		(31 "F.CrtYd" user "Package Geometry/Place Bound Top")
		(29 "B.CrtYd" user "Package Geometry/Place Bound Bottom")
		(35 "F.Fab" user "Ref Des/Assembly Top")
		(33 "B.Fab" user "Ref Des/Assembly Bottom")
	)
	(setup
		(pad_to_mask_clearance 0)
		(allow_soldermask_bridges_in_footprints no)
		(tenting
			(front yes)
			(back yes)
		)
		(covering
			(front no)
			(back no)
		)
		(plugging
			(front no)
			(back no)
		)
		(capping no)
		(filling no)
		(pcbplotparams
			(layerselection 0x00000000_00000000_55555555_5755f5ff)
			(plot_on_all_layers_selection 0x00000000_00000000_00000000_00000000)
			(disableapertmacros no)
			(usegerberextensions no)
			(usegerberattributes yes)
			(usegerberadvancedattributes yes)
			(creategerberjobfile yes)
			(dashed_line_dash_ratio 12)
			(dashed_line_gap_ratio 3)
			(svgprecision 4)
			(plotframeref no)
			(mode 1)
			(useauxorigin no)
			(pdf_front_fp_property_popups yes)
			(pdf_back_fp_property_popups yes)
			(pdf_metadata yes)
			(pdf_single_document no)
			(dxfpolygonmode yes)
			(dxfimperialunits yes)
			(dxfusepcbnewfont yes)
			(psnegative no)
			(psa4output no)
			(plot_black_and_white yes)
			(sketchpadsonfab no)
			(plotpadnumbers no)
			(hidednponfab no)
			(sketchdnponfab yes)
			(crossoutdnponfab yes)
			(subtractmaskfromsilk no)
			(outputformat 1)
			(mirror no)
			(drillshape 1)
			(scaleselection 1)
			(outputdirectory "")
		)
	)
	(gr_poly
		(pts
			(xy 90.248994 -272.626074) (xy 90.250505 -272.598788) (xy 90.26085 -272.545131) (xy 90.279271 -272.493684)
			(xy 90.305336 -272.445655) (xy 90.338432 -272.402172) (xy 90.377782 -272.364255) (xy 90.422463 -272.332794)
			(xy 90.471426 -272.308529) (xy 90.523521 -272.292029) (xy 90.577525 -272.283681) (xy 90.632171 -272.283681)
			(xy 90.686175 -272.292029) (xy 90.73827 -272.308529) (xy 90.787233 -272.332794) (xy 90.831914 -272.364255)
			(xy 90.871264 -272.402172) (xy 90.90436 -272.445655) (xy 90.930425 -272.493684) (xy 90.948846 -272.545131)
			(xy 90.959191 -272.598788) (xy 90.960702 -272.626074) (xy 90.96248 -272.674842) (xy 91.186762 -272.674842)
			(xy 91.18854 -272.626074) (xy 91.190051 -272.598788) (xy 91.200396 -272.545131) (xy 91.218817 -272.493684)
			(xy 91.244882 -272.445655) (xy 91.277978 -272.402172) (xy 91.317328 -272.364255) (xy 91.362009 -272.332794)
			(xy 91.410972 -272.308529) (xy 91.463067 -272.292029) (xy 91.517071 -272.283681) (xy 91.571717 -272.283681)
			(xy 91.625721 -272.292029) (xy 91.677816 -272.308529) (xy 91.726779 -272.332794) (xy 91.77146 -272.364255)
			(xy 91.81081 -272.402172) (xy 91.843906 -272.445655) (xy 91.869971 -272.493684) (xy 91.888392 -272.545131)
			(xy 91.898737 -272.598788) (xy 91.900248 -272.626074) (xy 91.902026 -272.674842) (xy 92.126562 -272.674842)
			(xy 92.12834 -272.626074) (xy 92.129851 -272.598788) (xy 92.140196 -272.545131) (xy 92.158617 -272.493684)
			(xy 92.184682 -272.445655) (xy 92.217778 -272.402172) (xy 92.257128 -272.364255) (xy 92.301809 -272.332794)
			(xy 92.350772 -272.308529) (xy 92.402867 -272.292029) (xy 92.456871 -272.283681) (xy 92.511517 -272.283681)
			(xy 92.565521 -272.292029) (xy 92.617616 -272.308529) (xy 92.666579 -272.332794) (xy 92.71126 -272.364255)
			(xy 92.75061 -272.402172) (xy 92.783706 -272.445655) (xy 92.809771 -272.493684) (xy 92.828192 -272.545131)
			(xy 92.838537 -272.598788) (xy 92.840048 -272.626074) (xy 92.841826 -272.674842) (xy 93.066362 -272.674842)
			(xy 93.06814 -272.626074) (xy 93.069651 -272.598788) (xy 93.079996 -272.545131) (xy 93.098417 -272.493684)
			(xy 93.124482 -272.445655) (xy 93.157578 -272.402172) (xy 93.196928 -272.364255) (xy 93.241609 -272.332794)
			(xy 93.290572 -272.308529) (xy 93.342667 -272.292029) (xy 93.396671 -272.283681) (xy 93.451317 -272.283681)
			(xy 93.505321 -272.292029) (xy 93.557416 -272.308529) (xy 93.606379 -272.332794) (xy 93.65106 -272.364255)
			(xy 93.69041 -272.402172) (xy 93.723506 -272.445655) (xy 93.749571 -272.493684) (xy 93.767992 -272.545131)
			(xy 93.778337 -272.598788) (xy 93.779848 -272.626074) (xy 93.781626 -272.674842) (xy 94.006162 -272.674842)
			(xy 94.00794 -272.626074) (xy 94.009451 -272.598788) (xy 94.019796 -272.545131) (xy 94.038217 -272.493684)
			(xy 94.064282 -272.445655) (xy 94.097378 -272.402172) (xy 94.136728 -272.364255) (xy 94.181409 -272.332794)
			(xy 94.230372 -272.308529) (xy 94.282467 -272.292029) (xy 94.336471 -272.283681) (xy 94.391117 -272.283681)
			(xy 94.445121 -272.292029) (xy 94.497216 -272.308529) (xy 94.546179 -272.332794) (xy 94.59086 -272.364255)
			(xy 94.63021 -272.402172) (xy 94.663306 -272.445655) (xy 94.689371 -272.493684) (xy 94.707792 -272.545131)
			(xy 94.718137 -272.598788) (xy 94.719648 -272.626074) (xy 94.721426 -272.674842) (xy 94.945962 -272.674842)
			(xy 94.94774 -272.626074) (xy 94.949251 -272.598788) (xy 94.959596 -272.545131) (xy 94.978017 -272.493684)
			(xy 95.004082 -272.445655) (xy 95.037178 -272.402172) (xy 95.076528 -272.364255) (xy 95.121209 -272.332794)
			(xy 95.170172 -272.308529) (xy 95.222267 -272.292029) (xy 95.276271 -272.283681) (xy 95.330917 -272.283681)
			(xy 95.384921 -272.292029) (xy 95.437016 -272.308529) (xy 95.485979 -272.332794) (xy 95.53066 -272.364255)
			(xy 95.57001 -272.402172) (xy 95.603106 -272.445655) (xy 95.629171 -272.493684) (xy 95.647592 -272.545131)
			(xy 95.657937 -272.598788) (xy 95.659448 -272.626074) (xy 95.661226 -272.674842) (xy 95.885762 -272.674842)
			(xy 95.88754 -272.626074) (xy 95.889051 -272.598788) (xy 95.899396 -272.545131) (xy 95.917817 -272.493684)
			(xy 95.943882 -272.445655) (xy 95.976978 -272.402172) (xy 96.016328 -272.364255) (xy 96.061009 -272.332794)
			(xy 96.109972 -272.308529) (xy 96.162067 -272.292029) (xy 96.216071 -272.283681) (xy 96.270717 -272.283681)
			(xy 96.324721 -272.292029) (xy 96.376816 -272.308529) (xy 96.425779 -272.332794) (xy 96.47046 -272.364255)
			(xy 96.50981 -272.402172) (xy 96.542906 -272.445655) (xy 96.568971 -272.493684) (xy 96.587392 -272.545131)
			(xy 96.597737 -272.598788) (xy 96.599248 -272.626074) (xy 96.601026 -272.674842) (xy 96.825816 -272.674842)
			(xy 96.827594 -272.626074) (xy 96.829105 -272.598788) (xy 96.83945 -272.545131) (xy 96.857871 -272.493684)
			(xy 96.883936 -272.445655) (xy 96.917032 -272.402172) (xy 96.956382 -272.364255) (xy 97.001063 -272.332794)
			(xy 97.050026 -272.308529) (xy 97.102121 -272.292029) (xy 97.156125 -272.283681) (xy 97.210771 -272.283681)
			(xy 97.264775 -272.292029) (xy 97.31687 -272.308529) (xy 97.365833 -272.332794) (xy 97.410514 -272.364255)
			(xy 97.449864 -272.402172) (xy 97.48296 -272.445655) (xy 97.509025 -272.493684) (xy 97.527446 -272.545131)
			(xy 97.537791 -272.598788) (xy 97.539302 -272.626074) (xy 97.54108 -272.674842) (xy 97.765362 -272.674842)
			(xy 97.76714 -272.626074) (xy 97.768651 -272.598788) (xy 97.778996 -272.545131) (xy 97.797417 -272.493684)
			(xy 97.823482 -272.445655) (xy 97.856578 -272.402172) (xy 97.895928 -272.364255) (xy 97.940609 -272.332794)
			(xy 97.989572 -272.308529) (xy 98.041667 -272.292029) (xy 98.095671 -272.283681) (xy 98.150317 -272.283681)
			(xy 98.204321 -272.292029) (xy 98.256416 -272.308529) (xy 98.305379 -272.332794) (xy 98.35006 -272.364255)
			(xy 98.38941 -272.402172) (xy 98.422506 -272.445655) (xy 98.448571 -272.493684) (xy 98.466992 -272.545131)
			(xy 98.477337 -272.598788) (xy 98.478848 -272.626074) (xy 98.480626 -272.674842) (xy 98.705162 -272.674842)
			(xy 98.70694 -272.626074) (xy 98.708451 -272.598788) (xy 98.718796 -272.545131) (xy 98.737217 -272.493684)
			(xy 98.763282 -272.445655) (xy 98.796378 -272.402172) (xy 98.835728 -272.364255) (xy 98.880409 -272.332794)
			(xy 98.929372 -272.308529) (xy 98.981467 -272.292029) (xy 99.035471 -272.283681) (xy 99.090117 -272.283681)
			(xy 99.144121 -272.292029) (xy 99.196216 -272.308529) (xy 99.245179 -272.332794) (xy 99.28986 -272.364255)
			(xy 99.32921 -272.402172) (xy 99.362306 -272.445655) (xy 99.388371 -272.493684) (xy 99.406792 -272.545131)
			(xy 99.417137 -272.598788) (xy 99.418648 -272.626074) (xy 99.420426 -272.674842) (xy 99.644962 -272.674842)
			(xy 99.64674 -272.626074) (xy 99.648251 -272.598788) (xy 99.658596 -272.545131) (xy 99.677017 -272.493684)
			(xy 99.703082 -272.445655) (xy 99.736178 -272.402172) (xy 99.775528 -272.364255) (xy 99.820209 -272.332794)
			(xy 99.869172 -272.308529) (xy 99.921267 -272.292029) (xy 99.975271 -272.283681) (xy 100.029917 -272.283681)
			(xy 100.083921 -272.292029) (xy 100.136016 -272.308529) (xy 100.184979 -272.332794) (xy 100.22966 -272.364255)
			(xy 100.26901 -272.402172) (xy 100.302106 -272.445655) (xy 100.328171 -272.493684) (xy 100.346592 -272.545131)
			(xy 100.356937 -272.598788) (xy 100.358448 -272.626074) (xy 100.360226 -272.674842) (xy 100.584762 -272.674842)
			(xy 100.58654 -272.626074) (xy 100.588051 -272.598788) (xy 100.598396 -272.545131) (xy 100.616817 -272.493684)
			(xy 100.642882 -272.445655) (xy 100.675978 -272.402172) (xy 100.715328 -272.364255) (xy 100.760009 -272.332794)
			(xy 100.808972 -272.308529) (xy 100.861067 -272.292029) (xy 100.915071 -272.283681) (xy 100.969717 -272.283681)
			(xy 101.023721 -272.292029) (xy 101.075816 -272.308529) (xy 101.124779 -272.332794) (xy 101.16946 -272.364255)
			(xy 101.20881 -272.402172) (xy 101.241906 -272.445655) (xy 101.267971 -272.493684) (xy 101.286392 -272.545131)
			(xy 101.296737 -272.598788) (xy 101.298248 -272.626074) (xy 101.300026 -272.674842) (xy 101.524562 -272.674842)
			(xy 101.52634 -272.626074) (xy 101.527851 -272.598788) (xy 101.538196 -272.545131) (xy 101.556617 -272.493684)
			(xy 101.582682 -272.445655) (xy 101.615778 -272.402172) (xy 101.655128 -272.364255) (xy 101.699809 -272.332794)
			(xy 101.748772 -272.308529) (xy 101.800867 -272.292029) (xy 101.854871 -272.283681) (xy 101.909517 -272.283681)
			(xy 101.963521 -272.292029) (xy 102.015616 -272.308529) (xy 102.064579 -272.332794) (xy 102.10926 -272.364255)
			(xy 102.14861 -272.402172) (xy 102.181706 -272.445655) (xy 102.207771 -272.493684) (xy 102.226192 -272.545131)
			(xy 102.236537 -272.598788) (xy 102.238048 -272.626074) (xy 102.239826 -272.674842) (xy 102.464362 -272.674842)
			(xy 102.46614 -272.626074) (xy 102.467651 -272.598788) (xy 102.477996 -272.545131) (xy 102.496417 -272.493684)
			(xy 102.522482 -272.445655) (xy 102.555578 -272.402172) (xy 102.594928 -272.364255) (xy 102.639609 -272.332794)
			(xy 102.688572 -272.308529) (xy 102.740667 -272.292029) (xy 102.794671 -272.283681) (xy 102.849317 -272.283681)
			(xy 102.903321 -272.292029) (xy 102.955416 -272.308529) (xy 103.004379 -272.332794) (xy 103.04906 -272.364255)
			(xy 103.08841 -272.402172) (xy 103.121506 -272.445655) (xy 103.147571 -272.493684) (xy 103.165992 -272.545131)
			(xy 103.176337 -272.598788) (xy 103.177848 -272.626074) (xy 103.179626 -272.674842) (xy 103.404162 -272.674842)
			(xy 103.40594 -272.626074) (xy 103.407451 -272.598788) (xy 103.417796 -272.545131) (xy 103.436217 -272.493684)
			(xy 103.462282 -272.445655) (xy 103.495378 -272.402172) (xy 103.534728 -272.364255) (xy 103.579409 -272.332794)
			(xy 103.628372 -272.308529) (xy 103.680467 -272.292029) (xy 103.734471 -272.283681) (xy 103.789117 -272.283681)
			(xy 103.843121 -272.292029) (xy 103.895216 -272.308529) (xy 103.944179 -272.332794) (xy 103.98886 -272.364255)
			(xy 104.02821 -272.402172) (xy 104.061306 -272.445655) (xy 104.087371 -272.493684) (xy 104.105792 -272.545131)
			(xy 104.116137 -272.598788) (xy 104.117648 -272.626074) (xy 104.119426 -272.674842) (xy 104.343962 -272.674842)
			(xy 104.34574 -272.626074) (xy 104.347251 -272.598788) (xy 104.357596 -272.545131) (xy 104.376017 -272.493684)
			(xy 104.402082 -272.445655) (xy 104.435178 -272.402172) (xy 104.474528 -272.364255) (xy 104.519209 -272.332794)
			(xy 104.568172 -272.308529) (xy 104.620267 -272.292029) (xy 104.674271 -272.283681) (xy 104.728917 -272.283681)
			(xy 104.782921 -272.292029) (xy 104.835016 -272.308529) (xy 104.883979 -272.332794) (xy 104.92866 -272.364255)
			(xy 104.96801 -272.402172) (xy 105.001106 -272.445655) (xy 105.027171 -272.493684) (xy 105.045592 -272.545131)
			(xy 105.055937 -272.598788) (xy 105.057448 -272.626074) (xy 105.059226 -272.674842) (xy 105.283762 -272.674842)
			(xy 105.28554 -272.626074) (xy 105.287051 -272.598788) (xy 105.297396 -272.545131) (xy 105.315817 -272.493684)
			(xy 105.341882 -272.445655) (xy 105.374978 -272.402172) (xy 105.414328 -272.364255) (xy 105.459009 -272.332794)
			(xy 105.507972 -272.308529) (xy 105.560067 -272.292029) (xy 105.614071 -272.283681) (xy 105.668717 -272.283681)
			(xy 105.722721 -272.292029) (xy 105.774816 -272.308529) (xy 105.823779 -272.332794) (xy 105.86846 -272.364255)
			(xy 105.90781 -272.402172) (xy 105.940906 -272.445655) (xy 105.966971 -272.493684) (xy 105.985392 -272.545131)
			(xy 105.995737 -272.598788) (xy 105.997248 -272.626074) (xy 105.999026 -272.674842) (xy 106.223562 -272.674842)
			(xy 106.22534 -272.626074) (xy 106.226851 -272.598788) (xy 106.237196 -272.545131) (xy 106.255617 -272.493684)
			(xy 106.281682 -272.445655) (xy 106.314778 -272.402172) (xy 106.354128 -272.364255) (xy 106.398809 -272.332794)
			(xy 106.447772 -272.308529) (xy 106.499867 -272.292029) (xy 106.553871 -272.283681) (xy 106.608517 -272.283681)
			(xy 106.662521 -272.292029) (xy 106.714616 -272.308529) (xy 106.763579 -272.332794) (xy 106.80826 -272.364255)
			(xy 106.84761 -272.402172) (xy 106.880706 -272.445655) (xy 106.906771 -272.493684) (xy 106.925192 -272.545131)
			(xy 106.935537 -272.598788) (xy 106.937048 -272.626074) (xy 106.938826 -272.674842) (xy 107.163362 -272.674842)
			(xy 107.16514 -272.626074) (xy 107.166651 -272.598788) (xy 107.176996 -272.545131) (xy 107.195417 -272.493684)
			(xy 107.221482 -272.445655) (xy 107.254578 -272.402172) (xy 107.293928 -272.364255) (xy 107.338609 -272.332794)
			(xy 107.387572 -272.308529) (xy 107.439667 -272.292029) (xy 107.493671 -272.283681) (xy 107.548317 -272.283681)
			(xy 107.602321 -272.292029) (xy 107.654416 -272.308529) (xy 107.703379 -272.332794) (xy 107.74806 -272.364255)
			(xy 107.78741 -272.402172) (xy 107.820506 -272.445655) (xy 107.846571 -272.493684) (xy 107.864992 -272.545131)
			(xy 107.875337 -272.598788) (xy 107.876848 -272.626074) (xy 107.878626 -272.674842) (xy 108.103162 -272.674842)
			(xy 108.10494 -272.626074) (xy 108.106452 -272.598789) (xy 108.1168 -272.545134) (xy 108.135222 -272.493688)
			(xy 108.161288 -272.445661) (xy 108.194384 -272.40218) (xy 108.233734 -272.364264) (xy 108.278414 -272.332805)
			(xy 108.327375 -272.308541) (xy 108.379469 -272.292041) (xy 108.433472 -272.283692) (xy 108.460794 -272.283174)
			(xy 108.493219 -272.283886) (xy 108.556992 -272.295648) (xy 108.58754 -272.306542) (xy 108.618274 -272.318226)
			(xy 108.69803 -272.23847) (xy 108.707435 -272.228371) (xy 108.720955 -272.204328) (xy 108.727555 -272.177544)
			(xy 108.726754 -272.149972) (xy 108.71861 -272.123617) (xy 108.703717 -272.100399) (xy 108.693712 -272.090896)
			(xy 108.675356 -272.073923) (xy 108.643103 -272.035722) (xy 108.616507 -271.993389) (xy 108.596088 -271.947754)
			(xy 108.582248 -271.899713) (xy 108.575259 -271.850209) (xy 108.57484 -271.825212) (xy 108.575325 -271.798733)
			(xy 108.583169 -271.746359) (xy 108.598687 -271.695725) (xy 108.621535 -271.647949) (xy 108.651209 -271.604085)
			(xy 108.687054 -271.565102) (xy 108.72828 -271.53186) (xy 108.773975 -271.505092) (xy 108.79836 -271.494758)
			(xy 108.83011 -271.482058) (xy 108.83011 -271.38249) (xy 108.829683 -271.368514) (xy 108.822122 -271.341606)
			(xy 108.807544 -271.317759) (xy 108.787041 -271.298763) (xy 108.762153 -271.286043) (xy 108.734747 -271.280553)
			(xy 108.706879 -271.282707) (xy 108.680642 -271.292341) (xy 108.669074 -271.300194) (xy 108.646197 -271.316046)
			(xy 108.596552 -271.341199) (xy 108.543596 -271.358317) (xy 108.488621 -271.366981) (xy 108.460794 -271.367504)
			(xy 108.434145 -271.367006) (xy 108.381443 -271.359062) (xy 108.330514 -271.343351) (xy 108.282495 -271.320226)
			(xy 108.238459 -271.290202) (xy 108.199389 -271.25395) (xy 108.166159 -271.21228) (xy 108.139511 -271.166123)
			(xy 108.120039 -271.11651) (xy 108.108179 -271.064548) (xy 108.104196 -271.0114) (xy 108.108179 -270.958252)
			(xy 108.120039 -270.90629) (xy 108.139511 -270.856677) (xy 108.166159 -270.81052) (xy 108.199389 -270.76885)
			(xy 108.238459 -270.732598) (xy 108.282495 -270.702574) (xy 108.330514 -270.679449) (xy 108.381443 -270.663738)
			(xy 108.434145 -270.655794) (xy 108.460794 -270.655288) (xy 108.48862 -270.655825) (xy 108.543595 -270.664486)
			(xy 108.596551 -270.681599) (xy 108.646199 -270.706745) (xy 108.669074 -270.722598) (xy 108.680654 -270.730411)
			(xy 108.706881 -270.739999) (xy 108.734725 -270.742124) (xy 108.762103 -270.736627) (xy 108.786969 -270.723918)
			(xy 108.807462 -270.704949) (xy 108.822049 -270.681137) (xy 108.829641 -270.654264) (xy 108.83011 -270.640302)
			(xy 108.83011 -270.540988) (xy 108.798106 -270.528034) (xy 108.773715 -270.517724) (xy 108.728035 -270.490943)
			(xy 108.686824 -270.457692) (xy 108.650993 -270.418705) (xy 108.621331 -270.37484) (xy 108.598492 -270.327066)
			(xy 108.582982 -270.276437) (xy 108.57514 -270.224069) (xy 108.575141 -270.171117) (xy 108.582985 -270.118749)
			(xy 108.598498 -270.06812) (xy 108.621338 -270.020347) (xy 108.651002 -269.976484) (xy 108.686835 -269.937498)
			(xy 108.728047 -269.904249) (xy 108.773729 -269.87747) (xy 108.798106 -269.867126) (xy 108.83011 -269.854172)
			(xy 108.83011 -269.754604) (xy 108.829672 -269.740637) (xy 108.822098 -269.71375) (xy 108.807516 -269.689925)
			(xy 108.787019 -269.670948) (xy 108.762144 -269.65824) (xy 108.734754 -269.652754) (xy 108.706904 -269.654901)
			(xy 108.680679 -269.664522) (xy 108.669074 -269.672308) (xy 108.646197 -269.688159) (xy 108.596552 -269.713312)
			(xy 108.543596 -269.730429) (xy 108.488621 -269.739092) (xy 108.460794 -269.739618) (xy 108.434144 -269.73912)
			(xy 108.38144 -269.731175) (xy 108.330509 -269.715464) (xy 108.282488 -269.692338) (xy 108.23845 -269.662313)
			(xy 108.199379 -269.626059) (xy 108.166148 -269.584388) (xy 108.139498 -269.538229) (xy 108.120026 -269.488614)
			(xy 108.108166 -269.436651) (xy 108.104182 -269.3835) (xy 108.108166 -269.330349) (xy 108.120026 -269.278386)
			(xy 108.139498 -269.228771) (xy 108.166148 -269.182612) (xy 108.199379 -269.140941) (xy 108.23845 -269.104687)
			(xy 108.282488 -269.074662) (xy 108.330509 -269.051536) (xy 108.38144 -269.035825) (xy 108.434144 -269.02788)
			(xy 108.460794 -269.027402) (xy 108.48862 -269.027939) (xy 108.543595 -269.0366) (xy 108.596551 -269.053713)
			(xy 108.646198 -269.078861) (xy 108.669074 -269.094712) (xy 108.680655 -269.102524) (xy 108.706883 -269.112111)
			(xy 108.734727 -269.114236) (xy 108.762106 -269.108738) (xy 108.786972 -269.09603) (xy 108.807466 -269.077061)
			(xy 108.822056 -269.053251) (xy 108.829651 -269.026378) (xy 108.83011 -269.012416) (xy 108.83011 -268.913102)
			(xy 108.798106 -268.900148) (xy 108.773714 -268.889838) (xy 108.728031 -268.863057) (xy 108.686819 -268.829805)
			(xy 108.650986 -268.790817) (xy 108.621322 -268.746951) (xy 108.598482 -268.699176) (xy 108.58297 -268.648545)
			(xy 108.575128 -268.596175) (xy 108.575128 -268.543221) (xy 108.582971 -268.490851) (xy 108.598484 -268.44022)
			(xy 108.621324 -268.392445) (xy 108.650989 -268.34858) (xy 108.686822 -268.309592) (xy 108.728035 -268.276341)
			(xy 108.773718 -268.24956) (xy 108.798106 -268.23924) (xy 108.83011 -268.226286) (xy 108.83011 -268.126972)
			(xy 108.829681 -268.112998) (xy 108.822117 -268.086094) (xy 108.807538 -268.062252) (xy 108.787036 -268.043259)
			(xy 108.762151 -268.030542) (xy 108.734748 -268.025053) (xy 108.706884 -268.027206) (xy 108.68065 -268.036837)
			(xy 108.669074 -268.044676) (xy 108.646198 -268.060529) (xy 108.596553 -268.085683) (xy 108.543597 -268.102802)
			(xy 108.488621 -268.111466) (xy 108.460794 -268.111986) (xy 108.434147 -268.111487) (xy 108.381447 -268.103544)
			(xy 108.330521 -268.087834) (xy 108.282504 -268.06471) (xy 108.23847 -268.034687) (xy 108.199403 -267.998437)
			(xy 108.166174 -267.95677) (xy 108.139527 -267.910615) (xy 108.120057 -267.861004) (xy 108.108198 -267.809046)
			(xy 108.104215 -267.7559) (xy 108.108198 -267.702754) (xy 108.120057 -267.650796) (xy 108.139527 -267.601185)
			(xy 108.166174 -267.55503) (xy 108.199403 -267.513363) (xy 108.23847 -267.477113) (xy 108.282504 -267.44709)
			(xy 108.330521 -267.423966) (xy 108.381447 -267.408256) (xy 108.434147 -267.400313) (xy 108.460794 -267.39977)
			(xy 108.48862 -267.400307) (xy 108.543595 -267.408968) (xy 108.596552 -267.426079) (xy 108.6462 -267.451225)
			(xy 108.669074 -267.46708) (xy 108.680653 -267.474894) (xy 108.706879 -267.484484) (xy 108.734722 -267.48661)
			(xy 108.7621 -267.481112) (xy 108.786965 -267.468403) (xy 108.807456 -267.449432) (xy 108.822041 -267.42562)
			(xy 108.829629 -267.398746) (xy 108.83011 -267.384784) (xy 108.83011 -267.284962) (xy 108.79836 -267.272262)
			(xy 108.773964 -267.261954) (xy 108.728273 -267.235177) (xy 108.687053 -267.201927) (xy 108.651212 -267.162938)
			(xy 108.621542 -267.119071) (xy 108.598696 -267.071293) (xy 108.58318 -267.020658) (xy 108.575335 -266.968283)
			(xy 108.575335 -266.915323) (xy 108.583179 -266.862948) (xy 108.598694 -266.812313) (xy 108.621539 -266.764534)
			(xy 108.651208 -266.720666) (xy 108.687048 -266.681677) (xy 108.728268 -266.648426) (xy 108.773959 -266.621648)
			(xy 108.79836 -266.611354) (xy 108.83011 -266.598654) (xy 108.83011 -266.49934) (xy 108.829677 -266.48537)
			(xy 108.822108 -266.458474) (xy 108.807527 -266.434639) (xy 108.787028 -266.415654) (xy 108.762148 -266.402941)
			(xy 108.734751 -266.397454) (xy 108.706894 -266.399604) (xy 108.680664 -266.40923) (xy 108.669074 -266.417044)
			(xy 108.646198 -266.432898) (xy 108.596554 -266.458055) (xy 108.543597 -266.475175) (xy 108.488621 -266.48384)
			(xy 108.460794 -266.484354) (xy 108.434142 -266.483856) (xy 108.381432 -266.47591) (xy 108.330496 -266.460198)
			(xy 108.28247 -266.437069) (xy 108.238427 -266.407041) (xy 108.199353 -266.370784) (xy 108.166118 -266.329108)
			(xy 108.139466 -266.282945) (xy 108.119991 -266.233324) (xy 108.10813 -266.181356) (xy 108.104146 -266.1282)
			(xy 108.10813 -266.075044) (xy 108.119991 -266.023076) (xy 108.139466 -265.973455) (xy 108.166118 -265.927292)
			(xy 108.199353 -265.885616) (xy 108.238427 -265.849359) (xy 108.28247 -265.819331) (xy 108.330496 -265.796202)
			(xy 108.381432 -265.78049) (xy 108.434142 -265.772544) (xy 108.460794 -265.772138) (xy 108.488621 -265.772675)
			(xy 108.543596 -265.781335) (xy 108.596553 -265.798445) (xy 108.646203 -265.823589) (xy 108.669074 -265.839448)
			(xy 108.680652 -265.847264) (xy 108.706876 -265.856856) (xy 108.734718 -265.858984) (xy 108.762095 -265.853486)
			(xy 108.786958 -265.840776) (xy 108.807446 -265.821803) (xy 108.822026 -265.797988) (xy 108.829607 -265.771113)
			(xy 108.83011 -265.757152) (xy 108.83011 -265.65733) (xy 108.79836 -265.64463) (xy 108.773967 -265.634319)
			(xy 108.728282 -265.607536) (xy 108.687067 -265.574285) (xy 108.651229 -265.535296) (xy 108.62156 -265.491431)
			(xy 108.598713 -265.443657) (xy 108.583192 -265.393025) (xy 108.57534 -265.340654) (xy 108.57484 -265.314176)
			(xy 108.575369 -265.28599) (xy 108.584235 -265.230319) (xy 108.601757 -265.176739) (xy 108.627499 -265.126588)
			(xy 108.660817 -265.081116) (xy 108.680504 -265.060938) (xy 108.689702 -265.051249) (xy 108.703139 -265.028167)
			(xy 108.710141 -265.002394) (xy 108.71023 -264.975686) (xy 108.703401 -264.949867) (xy 108.69012 -264.926696)
			(xy 108.681012 -264.91692) (xy 108.595668 -264.831576) (xy 108.566204 -264.840466) (xy 108.540559 -264.847934)
			(xy 108.487754 -264.855965) (xy 108.461048 -264.856468) (xy 108.433061 -264.855951) (xy 108.377776 -264.847201)
			(xy 108.324541 -264.829909) (xy 108.274667 -264.804501) (xy 108.229383 -264.771602) (xy 108.189803 -264.732023)
			(xy 108.156904 -264.68674) (xy 108.131494 -264.636866) (xy 108.114201 -264.583631) (xy 108.10545 -264.528347)
			(xy 108.10494 -264.50036) (xy 108.105483 -264.473658) (xy 108.113521 -264.42086) (xy 108.120942 -264.395204)
			(xy 108.129832 -264.36574) (xy 107.86745 -264.103358) (xy 104.111298 -264.103358) (xy 104.096844 -264.103852)
			(xy 104.069091 -264.111938) (xy 104.044722 -264.127487) (xy 104.025697 -264.14925) (xy 104.013543 -264.175478)
			(xy 104.009239 -264.204063) (xy 104.01313 -264.232707) (xy 104.024903 -264.259108) (xy 104.033828 -264.27049)
			(xy 104.049627 -264.289863) (xy 104.076214 -264.332196) (xy 104.096627 -264.377829) (xy 104.110463 -264.425866)
			(xy 104.117453 -264.475365) (xy 104.117902 -264.50036) (xy 104.117404 -264.527009) (xy 104.109461 -264.579713)
			(xy 104.093751 -264.630643) (xy 104.070625 -264.678664) (xy 104.040601 -264.722701) (xy 104.004349 -264.761772)
			(xy 103.962678 -264.795003) (xy 103.91652 -264.821652) (xy 103.866906 -264.841124) (xy 103.814944 -264.852984)
			(xy 103.761794 -264.856968) (xy 103.708644 -264.852984) (xy 103.656682 -264.841124) (xy 103.607068 -264.821652)
			(xy 103.56091 -264.795003) (xy 103.519239 -264.761772) (xy 103.482987 -264.722701) (xy 103.452963 -264.678664)
			(xy 103.429837 -264.630643) (xy 103.414127 -264.579713) (xy 103.406184 -264.527009) (xy 103.405686 -264.50036)
			(xy 103.406104 -264.475362) (xy 103.413086 -264.425857) (xy 103.426922 -264.377815) (xy 103.44734 -264.332179)
			(xy 103.473938 -264.289847) (xy 103.48976 -264.27049) (xy 103.498704 -264.259131) (xy 103.510434 -264.232722)
			(xy 103.514295 -264.204084) (xy 103.509977 -264.175512) (xy 103.497827 -264.149293) (xy 103.478817 -264.127529)
			(xy 103.454471 -264.111963) (xy 103.426738 -264.103842) (xy 103.41229 -264.103358) (xy 103.171498 -264.103358)
			(xy 103.157044 -264.103852) (xy 103.129291 -264.111938) (xy 103.104922 -264.127487) (xy 103.085897 -264.14925)
			(xy 103.073743 -264.175478) (xy 103.069439 -264.204063) (xy 103.07333 -264.232707) (xy 103.085103 -264.259108)
			(xy 103.094028 -264.27049) (xy 103.109827 -264.289863) (xy 103.136414 -264.332196) (xy 103.156827 -264.377829)
			(xy 103.170663 -264.425866) (xy 103.177653 -264.475365) (xy 103.178102 -264.50036) (xy 103.177604 -264.527009)
			(xy 103.169661 -264.579713) (xy 103.153951 -264.630643) (xy 103.130825 -264.678664) (xy 103.100801 -264.722701)
			(xy 103.064549 -264.761772) (xy 103.022878 -264.795003) (xy 102.97672 -264.821652) (xy 102.927106 -264.841124)
			(xy 102.875144 -264.852984) (xy 102.821994 -264.856968) (xy 102.768844 -264.852984) (xy 102.716882 -264.841124)
			(xy 102.667268 -264.821652) (xy 102.62111 -264.795003) (xy 102.579439 -264.761772) (xy 102.543187 -264.722701)
			(xy 102.513163 -264.678664) (xy 102.490037 -264.630643) (xy 102.474327 -264.579713) (xy 102.466384 -264.527009)
			(xy 102.465886 -264.50036) (xy 102.466402 -264.473174) (xy 102.474668 -264.419435) (xy 102.491003 -264.367576)
			(xy 102.515027 -264.3188) (xy 102.546183 -264.27424) (xy 102.583747 -264.234931) (xy 102.626847 -264.201785)
			(xy 102.674482 -264.175572) (xy 102.725547 -264.156901) (xy 102.778855 -264.146204) (xy 102.805992 -264.144506)
			(xy 102.820644 -264.143341) (xy 102.848393 -264.13369) (xy 102.87225 -264.116543) (xy 102.890242 -264.093316)
			(xy 102.900882 -264.065931) (xy 102.903291 -264.03665) (xy 102.897269 -264.007894) (xy 102.883314 -263.982039)
			(xy 102.873302 -263.971278) (xy 102.790752 -263.888728) (xy 102.780146 -263.87877) (xy 102.754628 -263.864822)
			(xy 102.726213 -263.858631) (xy 102.697205 -263.8607) (xy 102.669957 -263.87086) (xy 102.646676 -263.888288)
			(xy 102.63759 -263.89965) (xy 102.620664 -263.921439) (xy 102.581221 -263.960015) (xy 102.536303 -263.99205)
			(xy 102.486984 -264.016778) (xy 102.434442 -264.033606) (xy 102.379933 -264.042134) (xy 102.352348 -264.042652)
			(xy 102.324359 -264.042136) (xy 102.269069 -264.033386) (xy 102.215828 -264.016095) (xy 102.165948 -263.990688)
			(xy 102.120657 -263.957791) (xy 102.081069 -263.918213) (xy 102.04816 -263.87293) (xy 102.02274 -263.823057)
			(xy 102.005435 -263.769821) (xy 101.996672 -263.714533) (xy 101.99624 -263.686544) (xy 101.996756 -263.658957)
			(xy 102.005265 -263.604443) (xy 102.022085 -263.551896) (xy 102.046814 -263.502574) (xy 102.07886 -263.45766)
			(xy 102.117453 -263.41823) (xy 102.139242 -263.401302) (xy 102.150548 -263.392169) (xy 102.167933 -263.368895)
			(xy 102.178065 -263.341669) (xy 102.180128 -263.312693) (xy 102.173953 -263.284306) (xy 102.16004 -263.258805)
			(xy 102.150164 -263.24814) (xy 101.297994 -262.39597) (xy 101.287834 -262.39216) (xy 101.264216 -262.382849)
			(xy 101.219672 -262.358497) (xy 101.179039 -262.328064) (xy 101.143141 -262.292167) (xy 101.112707 -262.251535)
			(xy 101.088354 -262.206991) (xy 101.079046 -262.183372) (xy 101.075236 -262.173212) (xy 100.990654 -262.08863)
			(xy 100.980758 -262.079388) (xy 100.957222 -262.066018) (xy 100.931 -262.059301) (xy 100.903934 -262.059711)
			(xy 100.877927 -262.067219) (xy 100.854807 -262.081296) (xy 100.836199 -262.100954) (xy 100.823409 -262.12481)
			(xy 100.819966 -262.137906) (xy 100.813576 -262.163787) (xy 100.794103 -262.213412) (xy 100.76745 -262.259579)
			(xy 100.734214 -262.301258) (xy 100.695135 -262.337516) (xy 100.651088 -262.367544) (xy 100.603058 -262.39067)
			(xy 100.552116 -262.406378) (xy 100.499402 -262.414317) (xy 100.472748 -262.414766) (xy 100.444761 -262.414249)
			(xy 100.389476 -262.405499) (xy 100.336241 -262.388207) (xy 100.286368 -262.362798) (xy 100.241083 -262.3299)
			(xy 100.201504 -262.290321) (xy 100.168605 -262.245038) (xy 100.143196 -262.195164) (xy 100.125902 -262.141929)
			(xy 100.117151 -262.086645) (xy 100.11664 -262.058658) (xy 100.117141 -262.032009) (xy 100.125089 -261.979308)
			(xy 100.140802 -261.92838) (xy 100.163929 -261.880361) (xy 100.193953 -261.836325) (xy 100.230204 -261.797255)
			(xy 100.271873 -261.764023) (xy 100.318028 -261.737372) (xy 100.36764 -261.717896) (xy 100.3935 -261.71144)
			(xy 100.406614 -261.70802) (xy 100.430517 -261.695266) (xy 100.450216 -261.676666) (xy 100.46432 -261.653534)
			(xy 100.471833 -261.627504) (xy 100.472224 -261.600415) (xy 100.465466 -261.574178) (xy 100.452036 -261.550649)
			(xy 100.442776 -261.540752) (xy 100.398326 -261.496302) (xy 100.388595 -261.487187) (xy 100.365514 -261.473861)
			(xy 100.33977 -261.466963) (xy 100.313118 -261.466963) (xy 100.287374 -261.473861) (xy 100.264293 -261.487187)
			(xy 100.254562 -261.496302) (xy 100.234414 -261.515777) (xy 100.189127 -261.548778) (xy 100.139229 -261.574274)
			(xy 100.085951 -261.591634) (xy 100.030611 -261.600431) (xy 100.002594 -261.60095) (xy 99.97461 -261.600401)
			(xy 99.919331 -261.591645) (xy 99.866102 -261.574351) (xy 99.816234 -261.548943) (xy 99.770953 -261.516047)
			(xy 99.731376 -261.476474) (xy 99.698476 -261.431197) (xy 99.673063 -261.381331) (xy 99.655763 -261.328104)
			(xy 99.647002 -261.272826) (xy 99.646486 -261.244842) (xy 99.647035 -261.216829) (xy 99.655856 -261.161502)
			(xy 99.673225 -261.108235) (xy 99.698714 -261.058343) (xy 99.731695 -261.013052) (xy 99.751134 -260.992874)
			(xy 99.760283 -260.983169) (xy 99.773619 -260.96008) (xy 99.780521 -260.934326) (xy 99.780519 -260.907663)
			(xy 99.773614 -260.881909) (xy 99.760276 -260.858822) (xy 99.751134 -260.84911) (xy 99.665028 -260.763004)
			(xy 99.635818 -260.77164) (xy 99.610699 -260.778761) (xy 99.559053 -260.786409) (xy 99.532948 -260.78688)
			(xy 99.504961 -260.786363) (xy 99.449675 -260.777613) (xy 99.396439 -260.760321) (xy 99.346564 -260.734913)
			(xy 99.301279 -260.702015) (xy 99.261698 -260.662436) (xy 99.228797 -260.617153) (xy 99.203387 -260.567279)
			(xy 99.186092 -260.514044) (xy 99.177339 -260.458759) (xy 99.17684 -260.430772) (xy 99.177377 -260.402966)
			(xy 99.186025 -260.348032) (xy 99.203106 -260.295108) (xy 99.228205 -260.245483) (xy 99.260712 -260.200362)
			(xy 99.299837 -260.160842) (xy 99.344629 -260.127883) (xy 99.393999 -260.102286) (xy 99.446748 -260.084674)
			(xy 99.501593 -260.075475) (xy 99.529392 -260.074664) (xy 99.579684 -260.023864) (xy 99.579684 -259.210048)
			(xy 99.529392 -259.159248) (xy 99.502911 -259.158502) (xy 99.450602 -259.15014) (xy 99.400108 -259.134123)
			(xy 99.352543 -259.110803) (xy 99.308957 -259.080696) (xy 99.270311 -259.044465) (xy 99.237458 -259.002909)
			(xy 99.211122 -258.956946) (xy 99.191884 -258.907589) (xy 99.180169 -258.855928) (xy 99.176235 -258.8031)
			(xy 99.180169 -258.750273) (xy 99.191884 -258.698611) (xy 99.211122 -258.649254) (xy 99.237458 -258.603291)
			(xy 99.270311 -258.561736) (xy 99.308957 -258.525505) (xy 99.352543 -258.495397) (xy 99.400107 -258.472078)
			(xy 99.450601 -258.45606) (xy 99.502911 -258.447698) (xy 99.529392 -258.447032) (xy 99.579684 -258.396232)
			(xy 99.579684 -257.582162) (xy 99.529392 -257.531362) (xy 99.502908 -257.53063) (xy 99.450589 -257.522293)
			(xy 99.400082 -257.506297) (xy 99.352503 -257.482994) (xy 99.308901 -257.452898) (xy 99.27024 -257.416675)
			(xy 99.237374 -257.375122) (xy 99.211026 -257.329159) (xy 99.19178 -257.279799) (xy 99.180059 -257.228133)
			(xy 99.176124 -257.1753) (xy 99.180059 -257.122467) (xy 99.19178 -257.0708) (xy 99.211027 -257.02144)
			(xy 99.237374 -256.975477) (xy 99.270241 -256.933925) (xy 99.308902 -256.897701) (xy 99.352503 -256.867606)
			(xy 99.400083 -256.844303) (xy 99.450589 -256.828306) (xy 99.502909 -256.81997) (xy 99.529392 -256.819146)
			(xy 99.579684 -256.768346) (xy 99.579684 -255.95453) (xy 99.529392 -255.90373) (xy 99.502913 -255.902984)
			(xy 99.450606 -255.894622) (xy 99.400115 -255.878606) (xy 99.352552 -255.855288) (xy 99.308969 -255.825182)
			(xy 99.270325 -255.788953) (xy 99.237473 -255.747399) (xy 99.211138 -255.701438) (xy 99.191901 -255.652084)
			(xy 99.180187 -255.600425) (xy 99.176253 -255.5476) (xy 99.180187 -255.494776) (xy 99.191901 -255.443116)
			(xy 99.211138 -255.393762) (xy 99.237473 -255.347801) (xy 99.270324 -255.306248) (xy 99.308968 -255.270019)
			(xy 99.352552 -255.239913) (xy 99.400114 -255.216594) (xy 99.450605 -255.200578) (xy 99.502912 -255.192216)
			(xy 99.529392 -255.191514) (xy 99.579684 -255.140714) (xy 99.579684 -254.326644) (xy 99.529392 -254.275844)
			(xy 99.502912 -254.275098) (xy 99.450603 -254.266736) (xy 99.400109 -254.250719) (xy 99.352545 -254.2274)
			(xy 99.30896 -254.197293) (xy 99.270314 -254.161062) (xy 99.237461 -254.119507) (xy 99.211126 -254.073545)
			(xy 99.191888 -254.024188) (xy 99.180173 -253.972527) (xy 99.176239 -253.9197) (xy 99.180173 -253.866874)
			(xy 99.191888 -253.815212) (xy 99.211125 -253.765856) (xy 99.237461 -253.719893) (xy 99.270314 -253.678338)
			(xy 99.308959 -253.642108) (xy 99.352545 -253.612001) (xy 99.400109 -253.588681) (xy 99.450602 -253.572664)
			(xy 99.502911 -253.564302) (xy 99.529392 -253.563628) (xy 99.579684 -253.512828) (xy 99.579684 -249.790458)
			(xy 99.57435 -249.77979) (xy 99.562419 -249.754865) (xy 99.545549 -249.702245) (xy 99.537011 -249.64765)
			(xy 99.537007 -249.592392) (xy 99.54554 -249.537797) (xy 99.562402 -249.485175) (xy 99.57435 -249.460258)
			(xy 99.579684 -249.44959) (xy 99.579684 -249.260614) (xy 99.579196 -249.246269) (xy 99.571219 -249.218712)
			(xy 99.55589 -249.194461) (xy 99.534421 -249.175431) (xy 99.508505 -249.163125) (xy 99.480189 -249.158515)
			(xy 99.465892 -249.159776) (xy 99.455201 -249.160975) (xy 99.433724 -249.162243) (xy 99.422966 -249.162316)
			(xy 99.396318 -249.161816) (xy 99.343617 -249.153868) (xy 99.29269 -249.138155) (xy 99.244673 -249.115027)
			(xy 99.200639 -249.085001) (xy 99.161571 -249.048748) (xy 99.128343 -249.007078) (xy 99.101696 -248.960921)
			(xy 99.082226 -248.911308) (xy 99.070367 -248.859348) (xy 99.066384 -248.8062) (xy 99.070367 -248.753052)
			(xy 99.082226 -248.701092) (xy 99.101696 -248.651479) (xy 99.128343 -248.605322) (xy 99.161571 -248.563652)
			(xy 99.200639 -248.527399) (xy 99.244673 -248.497373) (xy 99.29269 -248.474245) (xy 99.343617 -248.458532)
			(xy 99.396318 -248.450584) (xy 99.422966 -248.4501) (xy 99.433724 -248.450164) (xy 99.455202 -248.451436)
			(xy 99.465892 -248.45264) (xy 99.480189 -248.453877) (xy 99.5085 -248.449268) (xy 99.534412 -248.436965)
			(xy 99.555879 -248.417941) (xy 99.571207 -248.393696) (xy 99.579186 -248.366144) (xy 99.579684 -248.351802)
			(xy 99.579684 -248.162572) (xy 99.57435 -248.151904) (xy 99.562417 -248.126979) (xy 99.545546 -248.074358)
			(xy 99.537005 -248.019763) (xy 99.537 -247.964504) (xy 99.545531 -247.909908) (xy 99.562392 -247.857284)
			(xy 99.57435 -247.832372) (xy 99.579684 -247.821704) (xy 99.579684 -247.632728) (xy 99.579198 -247.618382)
			(xy 99.571223 -247.590821) (xy 99.555895 -247.566566) (xy 99.534425 -247.547534) (xy 99.508507 -247.535226)
			(xy 99.480188 -247.530615) (xy 99.465892 -247.53189) (xy 99.455201 -247.533089) (xy 99.433724 -247.534357)
			(xy 99.422966 -247.53443) (xy 99.396317 -247.53393) (xy 99.343614 -247.525982) (xy 99.292684 -247.510268)
			(xy 99.244666 -247.487139) (xy 99.20063 -247.457112) (xy 99.161561 -247.420858) (xy 99.128332 -247.379186)
			(xy 99.101684 -247.333027) (xy 99.082213 -247.283412) (xy 99.070353 -247.23145) (xy 99.06637 -247.1783)
			(xy 99.070353 -247.12515) (xy 99.082213 -247.073188) (xy 99.101684 -247.023573) (xy 99.128332 -246.977414)
			(xy 99.161561 -246.935742) (xy 99.20063 -246.899488) (xy 99.244666 -246.869461) (xy 99.292684 -246.846332)
			(xy 99.343614 -246.830618) (xy 99.396317 -246.82267) (xy 99.422966 -246.822214) (xy 99.433724 -246.822278)
			(xy 99.455202 -246.82355) (xy 99.465892 -246.824754) (xy 99.48019 -246.825991) (xy 99.508502 -246.821382)
			(xy 99.534415 -246.80908) (xy 99.555885 -246.790056) (xy 99.571215 -246.765811) (xy 99.579198 -246.738259)
			(xy 99.579684 -246.723916) (xy 99.579684 -246.53494) (xy 99.57435 -246.524272) (xy 99.56242 -246.499347)
			(xy 99.545554 -246.446727) (xy 99.537018 -246.392134) (xy 99.537017 -246.336877) (xy 99.545551 -246.282283)
			(xy 99.562416 -246.229663) (xy 99.57435 -246.20474) (xy 99.579684 -246.194072) (xy 99.579684 -246.005096)
			(xy 99.579194 -245.990753) (xy 99.571213 -245.9632) (xy 99.555884 -245.938953) (xy 99.534415 -245.919928)
			(xy 99.508502 -245.907625) (xy 99.480189 -245.903015) (xy 99.465892 -245.904258) (xy 99.455201 -245.905457)
			(xy 99.433724 -245.906725) (xy 99.422966 -245.906798) (xy 99.396319 -245.906298) (xy 99.343621 -245.89835)
			(xy 99.292696 -245.882638) (xy 99.244682 -245.859511) (xy 99.20065 -245.829487) (xy 99.161585 -245.793236)
			(xy 99.128358 -245.751568) (xy 99.101713 -245.705413) (xy 99.082243 -245.655803) (xy 99.070385 -245.603845)
			(xy 99.066402 -245.5507) (xy 99.070385 -245.497555) (xy 99.082243 -245.445597) (xy 99.101713 -245.395987)
			(xy 99.128358 -245.349832) (xy 99.161585 -245.308164) (xy 99.20065 -245.271913) (xy 99.244682 -245.241889)
			(xy 99.292696 -245.218762) (xy 99.343621 -245.20305) (xy 99.396319 -245.195102) (xy 99.422966 -245.194582)
			(xy 99.433724 -245.194646) (xy 99.455202 -245.195918) (xy 99.465892 -245.197122) (xy 99.480193 -245.198359)
			(xy 99.508512 -245.19375) (xy 99.534433 -245.181449) (xy 99.555912 -245.162427) (xy 99.571257 -245.138183)
			(xy 99.579256 -245.110629) (xy 99.579684 -245.096284) (xy 99.579684 -244.907054) (xy 99.57435 -244.896386)
			(xy 99.562419 -244.871461) (xy 99.54555 -244.818841) (xy 99.537012 -244.764247) (xy 99.537009 -244.708989)
			(xy 99.545542 -244.654394) (xy 99.562405 -244.601772) (xy 99.57435 -244.576854) (xy 99.579684 -244.566186)
			(xy 99.579684 -244.37721) (xy 99.579195 -244.362866) (xy 99.571218 -244.335309) (xy 99.555889 -244.311059)
			(xy 99.53442 -244.29203) (xy 99.508504 -244.279725) (xy 99.480189 -244.275115) (xy 99.465892 -244.276372)
			(xy 99.455201 -244.277571) (xy 99.433724 -244.278839) (xy 99.422966 -244.278912) (xy 99.396318 -244.278412)
			(xy 99.343618 -244.270464) (xy 99.292691 -244.254751) (xy 99.244675 -244.231623) (xy 99.200641 -244.201598)
			(xy 99.161574 -244.165346) (xy 99.128346 -244.123676) (xy 99.1017 -244.077519) (xy 99.08223 -244.027907)
			(xy 99.070371 -243.975947) (xy 99.066388 -243.9228) (xy 99.070371 -243.869653) (xy 99.08223 -243.817693)
			(xy 99.1017 -243.768081) (xy 99.128346 -243.721924) (xy 99.161574 -243.680254) (xy 99.200641 -243.644002)
			(xy 99.244675 -243.613977) (xy 99.292691 -243.590849) (xy 99.343618 -243.575136) (xy 99.396318 -243.567188)
			(xy 99.422966 -243.566696) (xy 99.433724 -243.56676) (xy 99.455202 -243.568032) (xy 99.465892 -243.569236)
			(xy 99.480189 -243.570473) (xy 99.508499 -243.565863) (xy 99.53441 -243.553561) (xy 99.555877 -243.534536)
			(xy 99.571204 -243.510291) (xy 99.579182 -243.48274) (xy 99.579684 -243.468398) (xy 99.579684 -243.279422)
			(xy 99.57435 -243.268754) (xy 99.562421 -243.243829) (xy 99.545558 -243.19121) (xy 99.537024 -243.136617)
			(xy 99.537026 -243.081362) (xy 99.545563 -243.02677) (xy 99.562429 -242.974151) (xy 99.57435 -242.949222)
			(xy 99.579684 -242.938554) (xy 99.579684 -242.749324) (xy 99.579197 -242.734978) (xy 99.571222 -242.707418)
			(xy 99.555894 -242.683165) (xy 99.534424 -242.664133) (xy 99.508506 -242.651826) (xy 99.480188 -242.647215)
			(xy 99.465892 -242.648486) (xy 99.455201 -242.649685) (xy 99.433724 -242.650953) (xy 99.422966 -242.651026)
			(xy 99.396317 -242.650526) (xy 99.343615 -242.642578) (xy 99.292686 -242.626864) (xy 99.244668 -242.603735)
			(xy 99.200632 -242.573709) (xy 99.161564 -242.537455) (xy 99.128335 -242.495784) (xy 99.101687 -242.449625)
			(xy 99.082216 -242.400011) (xy 99.070357 -242.348049) (xy 99.066374 -242.2949) (xy 99.070357 -242.241751)
			(xy 99.082216 -242.189789) (xy 99.101687 -242.140175) (xy 99.128335 -242.094016) (xy 99.161564 -242.052345)
			(xy 99.200632 -242.016091) (xy 99.244668 -241.986065) (xy 99.292686 -241.962936) (xy 99.343615 -241.947222)
			(xy 99.396317 -241.939274) (xy 99.422966 -241.93881) (xy 99.433724 -241.938874) (xy 99.455202 -241.940146)
			(xy 99.465892 -241.94135) (xy 99.480189 -241.942587) (xy 99.508501 -241.937978) (xy 99.534414 -241.925676)
			(xy 99.555883 -241.906651) (xy 99.571213 -241.882406) (xy 99.579195 -241.854854) (xy 99.579684 -241.840512)
			(xy 99.579684 -241.651536) (xy 99.57435 -241.640868) (xy 99.56242 -241.615943) (xy 99.545554 -241.563323)
			(xy 99.537019 -241.50873) (xy 99.537019 -241.453474) (xy 99.545554 -241.39888) (xy 99.562419 -241.346261)
			(xy 99.57435 -241.321336) (xy 99.579684 -241.310668) (xy 99.579684 -241.121692) (xy 99.579193 -241.10735)
			(xy 99.571212 -241.079797) (xy 99.555883 -241.055552) (xy 99.534414 -241.036527) (xy 99.508501 -241.024224)
			(xy 99.480189 -241.019615) (xy 99.465892 -241.020854) (xy 99.455201 -241.022053) (xy 99.433724 -241.023321)
			(xy 99.422966 -241.023394) (xy 99.396319 -241.022894) (xy 99.343622 -241.014946) (xy 99.292698 -240.999234)
			(xy 99.244684 -240.976108) (xy 99.200652 -240.946084) (xy 99.161587 -240.909833) (xy 99.128361 -240.868166)
			(xy 99.101716 -240.822011) (xy 99.082247 -240.772402) (xy 99.070389 -240.720444) (xy 99.066406 -240.6673)
			(xy 99.070389 -240.614156) (xy 99.082247 -240.562198) (xy 99.101716 -240.512589) (xy 99.128361 -240.466434)
			(xy 99.161587 -240.424767) (xy 99.200652 -240.388516) (xy 99.244684 -240.358492) (xy 99.292698 -240.335366)
			(xy 99.343622 -240.319654) (xy 99.396319 -240.311706) (xy 99.422966 -240.311178) (xy 99.433724 -240.311242)
			(xy 99.455202 -240.312514) (xy 99.465892 -240.313718) (xy 99.480193 -240.314955) (xy 99.508511 -240.310346)
			(xy 99.534432 -240.298045) (xy 99.555911 -240.279023) (xy 99.571254 -240.254779) (xy 99.579253 -240.227225)
			(xy 99.579684 -240.21288) (xy 99.579684 -240.02365) (xy 99.57435 -240.012982) (xy 99.562419 -239.988057)
			(xy 99.545551 -239.935438) (xy 99.537014 -239.880844) (xy 99.536504 -239.853216) (xy 99.537003 -239.826209)
			(xy 99.545156 -239.772813) (xy 99.561277 -239.721261) (xy 99.584997 -239.672733) (xy 99.615773 -239.628344)
			(xy 99.652897 -239.589109) (xy 99.69552 -239.55593) (xy 99.742664 -239.529567) (xy 99.793248 -239.510624)
			(xy 99.846112 -239.499535) (xy 99.873054 -239.497616) (xy 99.892358 -239.4966) (xy 100.104448 -239.28451)
			(xy 100.086197 -239.264542) (xy 100.055329 -239.22012) (xy 100.031534 -239.17154) (xy 100.01536 -239.11992)
			(xy 100.007179 -239.066447) (xy 100.006658 -239.0394) (xy 100.007207 -239.011416) (xy 100.015962 -238.956137)
			(xy 100.033256 -238.902908) (xy 100.058663 -238.853039) (xy 100.091559 -238.807758) (xy 100.131133 -238.768181)
			(xy 100.17641 -238.735281) (xy 100.226276 -238.709869) (xy 100.279504 -238.69257) (xy 100.334782 -238.68381)
			(xy 100.362766 -238.683292) (xy 100.389815 -238.683793) (xy 100.44329 -238.691972) (xy 100.494912 -238.708148)
			(xy 100.543493 -238.731948) (xy 100.587913 -238.762824) (xy 100.607876 -238.781082) (xy 100.68814 -238.700818)
			(xy 100.697432 -238.690944) (xy 100.710897 -238.667422) (xy 100.717686 -238.641183) (xy 100.717319 -238.614082)
			(xy 100.709822 -238.588036) (xy 100.695725 -238.564887) (xy 100.676025 -238.546272) (xy 100.664264 -238.539528)
			(xy 100.640292 -238.526115) (xy 100.596425 -238.493056) (xy 100.558156 -238.453651) (xy 100.526395 -238.408835)
			(xy 100.501894 -238.359672) (xy 100.485237 -238.307329) (xy 100.476817 -238.253049) (xy 100.476304 -238.225584)
			(xy 100.476854 -238.197602) (xy 100.485611 -238.142328) (xy 100.502907 -238.089103) (xy 100.528317 -238.03924)
			(xy 100.561213 -237.993966) (xy 100.600787 -237.954395) (xy 100.646064 -237.921502) (xy 100.695929 -237.896097)
			(xy 100.749155 -237.878805) (xy 100.80443 -237.870052) (xy 100.832412 -237.869476) (xy 100.859876 -237.869985)
			(xy 100.914153 -237.878418) (xy 100.966492 -237.895083) (xy 101.015653 -237.919585) (xy 101.06047 -237.951342)
			(xy 101.099882 -237.989603) (xy 101.132953 -238.03346) (xy 101.146356 -238.057436) (xy 101.153146 -238.06915)
			(xy 101.171788 -238.088773) (xy 101.194927 -238.102814) (xy 101.220941 -238.110287) (xy 101.248005 -238.110668)
			(xy 101.274219 -238.103931) (xy 101.297745 -238.090548) (xy 101.307646 -238.081312) (xy 101.894894 -237.494064)
			(xy 101.89083 -237.46841) (xy 101.888688 -237.454284) (xy 101.886399 -237.425801) (xy 101.886258 -237.411514)
			(xy 101.886806 -237.383529) (xy 101.895559 -237.328248) (xy 101.912852 -237.275017) (xy 101.938259 -237.225147)
			(xy 101.971154 -237.179864) (xy 102.010728 -237.140285) (xy 102.056006 -237.107384) (xy 102.105873 -237.08197)
			(xy 102.159102 -237.06467) (xy 102.214381 -237.05591) (xy 102.242366 -237.055406) (xy 102.256653 -237.055547)
			(xy 102.285136 -237.057832) (xy 102.299262 -237.059978) (xy 102.324916 -237.064042) (xy 102.67061 -236.718348)
			(xy 102.634542 -236.682026) (xy 102.634288 -236.681772) (xy 102.614201 -236.661517) (xy 102.580098 -236.615793)
			(xy 102.553723 -236.565215) (xy 102.535754 -236.511079) (xy 102.526649 -236.454769) (xy 102.526084 -236.426248)
			(xy 102.526532 -236.400549) (xy 102.533919 -236.349684) (xy 102.548545 -236.300411) (xy 102.570107 -236.253754)
			(xy 102.598155 -236.210683) (xy 102.632108 -236.172096) (xy 102.671257 -236.138793) (xy 102.714791 -236.111468)
			(xy 102.761801 -236.090689) (xy 102.786434 -236.083348) (xy 102.799034 -236.079441) (xy 102.821806 -236.066142)
			(xy 102.840399 -236.047441) (xy 102.853567 -236.024593) (xy 102.860426 -235.999129) (xy 102.860515 -235.972759)
			(xy 102.857554 -235.959904) (xy 102.852242 -235.938063) (xy 102.846506 -235.893479) (xy 102.846124 -235.871004)
			(xy 102.846644 -235.843019) (xy 102.8554 -235.787739) (xy 102.872696 -235.734509) (xy 102.898106 -235.684641)
			(xy 102.931005 -235.639362) (xy 102.970583 -235.599787) (xy 103.015865 -235.566891) (xy 103.065735 -235.541485)
			(xy 103.118966 -235.524193) (xy 103.174247 -235.515442) (xy 103.202232 -235.514896) (xy 103.229156 -235.515385)
			(xy 103.28239 -235.523484) (xy 103.333798 -235.539508) (xy 103.382206 -235.563091) (xy 103.42651 -235.593696)
			(xy 103.4657 -235.630623) (xy 103.482648 -235.651548) (xy 103.491763 -235.662422) (xy 103.514719 -235.679078)
			(xy 103.541367 -235.688786) (xy 103.569658 -235.690799) (xy 103.597413 -235.684963) (xy 103.610156 -235.678726)
			(xy 103.635937 -235.665707) (xy 103.690665 -235.647265) (xy 103.747651 -235.637891) (xy 103.776526 -235.637324)
			(xy 103.804509 -235.637847) (xy 103.859786 -235.646606) (xy 103.913011 -235.663904) (xy 103.962876 -235.689316)
			(xy 104.008151 -235.722216) (xy 104.047722 -235.761793) (xy 104.080614 -235.807074) (xy 104.106018 -235.856942)
			(xy 104.123308 -235.910171) (xy 104.132058 -235.965449) (xy 104.132634 -235.993432) (xy 104.132094 -236.021258)
			(xy 104.123428 -236.07623) (xy 104.106312 -236.129183) (xy 104.081163 -236.178828) (xy 104.065324 -236.201712)
			(xy 104.0575 -236.213294) (xy 104.047893 -236.239531) (xy 104.045755 -236.267389) (xy 104.051247 -236.294785)
			(xy 104.063958 -236.319667) (xy 104.082936 -236.340173) (xy 104.106761 -236.354769) (xy 104.13365 -236.362362)
			(xy 104.14762 -236.362748) (xy 107.06481 -236.362748) (xy 107.0791 -236.362222) (xy 107.106541 -236.354221)
			(xy 107.130691 -236.338931) (xy 107.149661 -236.317549) (xy 107.161965 -236.29175) (xy 107.166642 -236.263552)
			(xy 107.163324 -236.235161) (xy 107.158282 -236.221778) (xy 107.149522 -236.199895) (xy 107.137193 -236.154401)
			(xy 107.130973 -236.107678) (xy 107.130596 -236.08411) (xy 107.130933 -236.061684) (xy 107.136572 -236.017188)
			(xy 107.147774 -235.973757) (xy 107.155742 -235.952792) (xy 107.160557 -235.939288) (xy 107.163263 -235.910758)
			(xy 107.157916 -235.882604) (xy 107.144939 -235.857053) (xy 107.12536 -235.836127) (xy 107.113324 -235.828332)
			(xy 107.091067 -235.81443) (xy 107.050521 -235.781119) (xy 107.015298 -235.742221) (xy 106.986161 -235.698579)
			(xy 106.963739 -235.651135) (xy 106.948518 -235.600916) (xy 106.940826 -235.549008) (xy 106.94035 -235.52277)
			(xy 106.940901 -235.494787) (xy 106.94966 -235.439511) (xy 106.966956 -235.386286) (xy 106.992365 -235.33642)
			(xy 107.025261 -235.291143) (xy 107.064834 -235.251569) (xy 107.11011 -235.218672) (xy 107.159974 -235.193261)
			(xy 107.2132 -235.175962) (xy 107.268475 -235.167202) (xy 107.296458 -235.166662) (xy 107.296712 -235.166662)
			(xy 107.324013 -235.167153) (xy 107.377974 -235.175485) (xy 107.430028 -235.191966) (xy 107.478951 -235.21621)
			(xy 107.523594 -235.247647) (xy 107.5436 -235.26623) (xy 107.555222 -235.276627) (xy 107.583156 -235.290451)
			(xy 107.613958 -235.295207) (xy 107.64476 -235.290451) (xy 107.672694 -235.276627) (xy 107.684316 -235.26623)
			(xy 107.704349 -235.247682) (xy 107.749002 -235.216276) (xy 107.797921 -235.192044) (xy 107.849962 -235.175552)
			(xy 107.903909 -235.167185) (xy 107.931204 -235.166662) (xy 107.931458 -235.166662) (xy 107.959446 -235.167179)
			(xy 108.014735 -235.175929) (xy 108.067974 -235.193221) (xy 108.117852 -235.218629) (xy 108.163142 -235.251526)
			(xy 108.202727 -235.291104) (xy 108.235634 -235.336386) (xy 108.261051 -235.38626) (xy 108.278354 -235.439495)
			(xy 108.287115 -235.494782) (xy 108.287566 -235.52277) (xy 108.287231 -235.545196) (xy 108.281595 -235.589694)
			(xy 108.270398 -235.633126) (xy 108.26242 -235.654088) (xy 108.257603 -235.667594) (xy 108.254893 -235.696128)
			(xy 108.260236 -235.724287) (xy 108.273208 -235.749846) (xy 108.292783 -235.770782) (xy 108.304838 -235.778548)
			(xy 108.327098 -235.792448) (xy 108.349113 -235.810531) (xy 109.40541 -235.810531) (xy 109.40541 -235.757233)
			(xy 109.413353 -235.704529) (xy 109.429063 -235.653599) (xy 109.452189 -235.605578) (xy 109.482213 -235.561541)
			(xy 109.518465 -235.52247) (xy 109.560136 -235.489239) (xy 109.606294 -235.46259) (xy 109.655908 -235.443118)
			(xy 109.70787 -235.431258) (xy 109.76102 -235.427275) (xy 109.81417 -235.431258) (xy 109.866132 -235.443118)
			(xy 109.915746 -235.46259) (xy 109.961904 -235.489239) (xy 110.003575 -235.52247) (xy 110.039827 -235.561541)
			(xy 110.069851 -235.605578) (xy 110.092977 -235.653599) (xy 110.108687 -235.704529) (xy 110.11663 -235.757233)
			(xy 110.117128 -235.783882) (xy 110.11663 -235.810531) (xy 110.34521 -235.810531) (xy 110.34521 -235.757233)
			(xy 110.353153 -235.704529) (xy 110.368863 -235.653599) (xy 110.391989 -235.605578) (xy 110.422013 -235.561541)
			(xy 110.458265 -235.52247) (xy 110.499936 -235.489239) (xy 110.546094 -235.46259) (xy 110.595708 -235.443118)
			(xy 110.64767 -235.431258) (xy 110.70082 -235.427275) (xy 110.75397 -235.431258) (xy 110.805932 -235.443118)
			(xy 110.855546 -235.46259) (xy 110.901704 -235.489239) (xy 110.943375 -235.52247) (xy 110.979627 -235.561541)
			(xy 111.009651 -235.605578) (xy 111.032777 -235.653599) (xy 111.048487 -235.704529) (xy 111.05643 -235.757233)
			(xy 111.056928 -235.783882) (xy 111.05643 -235.810531) (xy 111.28501 -235.810531) (xy 111.28501 -235.757233)
			(xy 111.292953 -235.704529) (xy 111.308663 -235.653599) (xy 111.331789 -235.605578) (xy 111.361813 -235.561541)
			(xy 111.398065 -235.52247) (xy 111.439736 -235.489239) (xy 111.485894 -235.46259) (xy 111.535508 -235.443118)
			(xy 111.58747 -235.431258) (xy 111.64062 -235.427275) (xy 111.69377 -235.431258) (xy 111.745732 -235.443118)
			(xy 111.795346 -235.46259) (xy 111.841504 -235.489239) (xy 111.883175 -235.52247) (xy 111.919427 -235.561541)
			(xy 111.949451 -235.605578) (xy 111.972577 -235.653599) (xy 111.988287 -235.704529) (xy 111.99623 -235.757233)
			(xy 111.996728 -235.783882) (xy 111.99623 -235.810531) (xy 112.22481 -235.810531) (xy 112.22481 -235.757233)
			(xy 112.232753 -235.704529) (xy 112.248463 -235.653599) (xy 112.271589 -235.605578) (xy 112.301613 -235.561541)
			(xy 112.337865 -235.52247) (xy 112.379536 -235.489239) (xy 112.425694 -235.46259) (xy 112.475308 -235.443118)
			(xy 112.52727 -235.431258) (xy 112.58042 -235.427275) (xy 112.63357 -235.431258) (xy 112.685532 -235.443118)
			(xy 112.735146 -235.46259) (xy 112.781304 -235.489239) (xy 112.822975 -235.52247) (xy 112.859227 -235.561541)
			(xy 112.889251 -235.605578) (xy 112.912377 -235.653599) (xy 112.928087 -235.704529) (xy 112.93603 -235.757233)
			(xy 112.936528 -235.783882) (xy 112.93603 -235.810531) (xy 113.16461 -235.810531) (xy 113.16461 -235.757233)
			(xy 113.172553 -235.704529) (xy 113.188263 -235.653599) (xy 113.211389 -235.605578) (xy 113.241413 -235.561541)
			(xy 113.277665 -235.52247) (xy 113.319336 -235.489239) (xy 113.365494 -235.46259) (xy 113.415108 -235.443118)
			(xy 113.46707 -235.431258) (xy 113.52022 -235.427275) (xy 113.57337 -235.431258) (xy 113.625332 -235.443118)
			(xy 113.674946 -235.46259) (xy 113.721104 -235.489239) (xy 113.762775 -235.52247) (xy 113.799027 -235.561541)
			(xy 113.829051 -235.605578) (xy 113.852177 -235.653599) (xy 113.867887 -235.704529) (xy 113.87583 -235.757233)
			(xy 113.876328 -235.783882) (xy 113.87583 -235.810531) (xy 114.10441 -235.810531) (xy 114.10441 -235.757233)
			(xy 114.112353 -235.704529) (xy 114.128063 -235.653599) (xy 114.151189 -235.605578) (xy 114.181213 -235.561541)
			(xy 114.217465 -235.52247) (xy 114.259136 -235.489239) (xy 114.305294 -235.46259) (xy 114.354908 -235.443118)
			(xy 114.40687 -235.431258) (xy 114.46002 -235.427275) (xy 114.51317 -235.431258) (xy 114.565132 -235.443118)
			(xy 114.614746 -235.46259) (xy 114.660904 -235.489239) (xy 114.702575 -235.52247) (xy 114.738827 -235.561541)
			(xy 114.768851 -235.605578) (xy 114.791977 -235.653599) (xy 114.807687 -235.704529) (xy 114.81563 -235.757233)
			(xy 114.816128 -235.783882) (xy 114.81563 -235.810531) (xy 121.622556 -235.810531) (xy 121.622556 -235.757233)
			(xy 121.630499 -235.704529) (xy 121.646209 -235.653599) (xy 121.669335 -235.605578) (xy 121.699359 -235.561541)
			(xy 121.735611 -235.52247) (xy 121.777282 -235.489239) (xy 121.82344 -235.46259) (xy 121.873054 -235.443118)
			(xy 121.925016 -235.431258) (xy 121.978166 -235.427275) (xy 122.031316 -235.431258) (xy 122.083278 -235.443118)
			(xy 122.132892 -235.46259) (xy 122.17905 -235.489239) (xy 122.220721 -235.52247) (xy 122.256973 -235.561541)
			(xy 122.286997 -235.605578) (xy 122.310123 -235.653599) (xy 122.325833 -235.704529) (xy 122.333776 -235.757233)
			(xy 122.334274 -235.783882) (xy 122.333776 -235.810531) (xy 122.562356 -235.810531) (xy 122.562356 -235.757233)
			(xy 122.570299 -235.704529) (xy 122.586009 -235.653599) (xy 122.609135 -235.605578) (xy 122.639159 -235.561541)
			(xy 122.675411 -235.52247) (xy 122.717082 -235.489239) (xy 122.76324 -235.46259) (xy 122.812854 -235.443118)
			(xy 122.864816 -235.431258) (xy 122.917966 -235.427275) (xy 122.971116 -235.431258) (xy 123.023078 -235.443118)
			(xy 123.072692 -235.46259) (xy 123.11885 -235.489239) (xy 123.160521 -235.52247) (xy 123.196773 -235.561541)
			(xy 123.226797 -235.605578) (xy 123.249923 -235.653599) (xy 123.265633 -235.704529) (xy 123.273576 -235.757233)
			(xy 123.274074 -235.783882) (xy 123.273576 -235.810531) (xy 123.502156 -235.810531) (xy 123.502156 -235.757233)
			(xy 123.510099 -235.704529) (xy 123.525809 -235.653599) (xy 123.548935 -235.605578) (xy 123.578959 -235.561541)
			(xy 123.615211 -235.52247) (xy 123.656882 -235.489239) (xy 123.70304 -235.46259) (xy 123.752654 -235.443118)
			(xy 123.804616 -235.431258) (xy 123.857766 -235.427275) (xy 123.910916 -235.431258) (xy 123.962878 -235.443118)
			(xy 124.012492 -235.46259) (xy 124.05865 -235.489239) (xy 124.100321 -235.52247) (xy 124.136573 -235.561541)
			(xy 124.166597 -235.605578) (xy 124.189723 -235.653599) (xy 124.205433 -235.704529) (xy 124.213376 -235.757233)
			(xy 124.213874 -235.783882) (xy 124.213376 -235.810531) (xy 124.441956 -235.810531) (xy 124.441956 -235.757233)
			(xy 124.449899 -235.704529) (xy 124.465609 -235.653599) (xy 124.488735 -235.605578) (xy 124.518759 -235.561541)
			(xy 124.555011 -235.52247) (xy 124.596682 -235.489239) (xy 124.64284 -235.46259) (xy 124.692454 -235.443118)
			(xy 124.744416 -235.431258) (xy 124.797566 -235.427275) (xy 124.850716 -235.431258) (xy 124.902678 -235.443118)
			(xy 124.952292 -235.46259) (xy 124.99845 -235.489239) (xy 125.040121 -235.52247) (xy 125.076373 -235.561541)
			(xy 125.106397 -235.605578) (xy 125.129523 -235.653599) (xy 125.145233 -235.704529) (xy 125.153176 -235.757233)
			(xy 125.153674 -235.783882) (xy 125.153176 -235.810531) (xy 125.381502 -235.810531) (xy 125.381502 -235.757233)
			(xy 125.389445 -235.704529) (xy 125.405155 -235.653599) (xy 125.428281 -235.605578) (xy 125.458305 -235.561541)
			(xy 125.494557 -235.52247) (xy 125.536228 -235.489239) (xy 125.582386 -235.46259) (xy 125.632 -235.443118)
			(xy 125.683962 -235.431258) (xy 125.737112 -235.427275) (xy 125.790262 -235.431258) (xy 125.842224 -235.443118)
			(xy 125.891838 -235.46259) (xy 125.937996 -235.489239) (xy 125.979667 -235.52247) (xy 126.015919 -235.561541)
			(xy 126.045943 -235.605578) (xy 126.069069 -235.653599) (xy 126.084779 -235.704529) (xy 126.092722 -235.757233)
			(xy 126.09322 -235.783882) (xy 126.092722 -235.810531) (xy 126.321556 -235.810531) (xy 126.321556 -235.757233)
			(xy 126.329499 -235.704529) (xy 126.345209 -235.653599) (xy 126.368335 -235.605578) (xy 126.398359 -235.561541)
			(xy 126.434611 -235.52247) (xy 126.476282 -235.489239) (xy 126.52244 -235.46259) (xy 126.572054 -235.443118)
			(xy 126.624016 -235.431258) (xy 126.677166 -235.427275) (xy 126.730316 -235.431258) (xy 126.782278 -235.443118)
			(xy 126.831892 -235.46259) (xy 126.87805 -235.489239) (xy 126.919721 -235.52247) (xy 126.955973 -235.561541)
			(xy 126.985997 -235.605578) (xy 127.009123 -235.653599) (xy 127.024833 -235.704529) (xy 127.032776 -235.757233)
			(xy 127.033274 -235.783882) (xy 127.032776 -235.810531) (xy 127.261356 -235.810531) (xy 127.261356 -235.757233)
			(xy 127.269299 -235.704529) (xy 127.285009 -235.653599) (xy 127.308135 -235.605578) (xy 127.338159 -235.561541)
			(xy 127.374411 -235.52247) (xy 127.416082 -235.489239) (xy 127.46224 -235.46259) (xy 127.511854 -235.443118)
			(xy 127.563816 -235.431258) (xy 127.616966 -235.427275) (xy 127.670116 -235.431258) (xy 127.722078 -235.443118)
			(xy 127.771692 -235.46259) (xy 127.81785 -235.489239) (xy 127.859521 -235.52247) (xy 127.895773 -235.561541)
			(xy 127.925797 -235.605578) (xy 127.948923 -235.653599) (xy 127.964633 -235.704529) (xy 127.972576 -235.757233)
			(xy 127.973074 -235.783882) (xy 127.972576 -235.810531) (xy 128.201156 -235.810531) (xy 128.201156 -235.757233)
			(xy 128.209099 -235.704529) (xy 128.224809 -235.653599) (xy 128.247935 -235.605578) (xy 128.277959 -235.561541)
			(xy 128.314211 -235.52247) (xy 128.355882 -235.489239) (xy 128.40204 -235.46259) (xy 128.451654 -235.443118)
			(xy 128.503616 -235.431258) (xy 128.556766 -235.427275) (xy 128.609916 -235.431258) (xy 128.661878 -235.443118)
			(xy 128.711492 -235.46259) (xy 128.75765 -235.489239) (xy 128.799321 -235.52247) (xy 128.835573 -235.561541)
			(xy 128.865597 -235.605578) (xy 128.888723 -235.653599) (xy 128.904433 -235.704529) (xy 128.912376 -235.757233)
			(xy 128.912874 -235.783882) (xy 128.912376 -235.810531) (xy 129.140956 -235.810531) (xy 129.140956 -235.757233)
			(xy 129.148899 -235.704529) (xy 129.164609 -235.653599) (xy 129.187735 -235.605578) (xy 129.217759 -235.561541)
			(xy 129.254011 -235.52247) (xy 129.295682 -235.489239) (xy 129.34184 -235.46259) (xy 129.391454 -235.443118)
			(xy 129.443416 -235.431258) (xy 129.496566 -235.427275) (xy 129.549716 -235.431258) (xy 129.601678 -235.443118)
			(xy 129.651292 -235.46259) (xy 129.69745 -235.489239) (xy 129.739121 -235.52247) (xy 129.775373 -235.561541)
			(xy 129.805397 -235.605578) (xy 129.828523 -235.653599) (xy 129.844233 -235.704529) (xy 129.852176 -235.757233)
			(xy 129.852674 -235.783882) (xy 129.852176 -235.810531) (xy 130.080756 -235.810531) (xy 130.080756 -235.757233)
			(xy 130.088699 -235.704529) (xy 130.104409 -235.653599) (xy 130.127535 -235.605578) (xy 130.157559 -235.561541)
			(xy 130.193811 -235.52247) (xy 130.235482 -235.489239) (xy 130.28164 -235.46259) (xy 130.331254 -235.443118)
			(xy 130.383216 -235.431258) (xy 130.436366 -235.427275) (xy 130.489516 -235.431258) (xy 130.541478 -235.443118)
			(xy 130.591092 -235.46259) (xy 130.63725 -235.489239) (xy 130.678921 -235.52247) (xy 130.715173 -235.561541)
			(xy 130.745197 -235.605578) (xy 130.768323 -235.653599) (xy 130.784033 -235.704529) (xy 130.791976 -235.757233)
			(xy 130.792474 -235.783882) (xy 130.791976 -235.810531) (xy 131.020556 -235.810531) (xy 131.020556 -235.757233)
			(xy 131.028499 -235.704529) (xy 131.044209 -235.653599) (xy 131.067335 -235.605578) (xy 131.097359 -235.561541)
			(xy 131.133611 -235.52247) (xy 131.175282 -235.489239) (xy 131.22144 -235.46259) (xy 131.271054 -235.443118)
			(xy 131.323016 -235.431258) (xy 131.376166 -235.427275) (xy 131.429316 -235.431258) (xy 131.481278 -235.443118)
			(xy 131.530892 -235.46259) (xy 131.57705 -235.489239) (xy 131.618721 -235.52247) (xy 131.654973 -235.561541)
			(xy 131.684997 -235.605578) (xy 131.708123 -235.653599) (xy 131.723833 -235.704529) (xy 131.731776 -235.757233)
			(xy 131.732274 -235.783882) (xy 131.731776 -235.810531) (xy 131.960102 -235.810531) (xy 131.960102 -235.757233)
			(xy 131.968045 -235.704529) (xy 131.983755 -235.653599) (xy 132.006881 -235.605578) (xy 132.036905 -235.561541)
			(xy 132.073157 -235.52247) (xy 132.114828 -235.489239) (xy 132.160986 -235.46259) (xy 132.2106 -235.443118)
			(xy 132.262562 -235.431258) (xy 132.315712 -235.427275) (xy 132.368862 -235.431258) (xy 132.420824 -235.443118)
			(xy 132.470438 -235.46259) (xy 132.516596 -235.489239) (xy 132.558267 -235.52247) (xy 132.594519 -235.561541)
			(xy 132.624543 -235.605578) (xy 132.647669 -235.653599) (xy 132.663379 -235.704529) (xy 132.671322 -235.757233)
			(xy 132.67182 -235.783882) (xy 132.671322 -235.810531) (xy 132.900156 -235.810531) (xy 132.900156 -235.757233)
			(xy 132.908099 -235.704529) (xy 132.923809 -235.653599) (xy 132.946935 -235.605578) (xy 132.976959 -235.561541)
			(xy 133.013211 -235.52247) (xy 133.054882 -235.489239) (xy 133.10104 -235.46259) (xy 133.150654 -235.443118)
			(xy 133.202616 -235.431258) (xy 133.255766 -235.427275) (xy 133.308916 -235.431258) (xy 133.360878 -235.443118)
			(xy 133.410492 -235.46259) (xy 133.45665 -235.489239) (xy 133.498321 -235.52247) (xy 133.534573 -235.561541)
			(xy 133.564597 -235.605578) (xy 133.587723 -235.653599) (xy 133.603433 -235.704529) (xy 133.611376 -235.757233)
			(xy 133.611874 -235.783882) (xy 133.611376 -235.810531) (xy 133.839956 -235.810531) (xy 133.839956 -235.757233)
			(xy 133.847899 -235.704529) (xy 133.863609 -235.653599) (xy 133.886735 -235.605578) (xy 133.916759 -235.561541)
			(xy 133.953011 -235.52247) (xy 133.994682 -235.489239) (xy 134.04084 -235.46259) (xy 134.090454 -235.443118)
			(xy 134.142416 -235.431258) (xy 134.195566 -235.427275) (xy 134.248716 -235.431258) (xy 134.300678 -235.443118)
			(xy 134.350292 -235.46259) (xy 134.39645 -235.489239) (xy 134.438121 -235.52247) (xy 134.474373 -235.561541)
			(xy 134.504397 -235.605578) (xy 134.527523 -235.653599) (xy 134.543233 -235.704529) (xy 134.551176 -235.757233)
			(xy 134.551674 -235.783882) (xy 134.551176 -235.810531) (xy 134.543233 -235.863235) (xy 134.527523 -235.914165)
			(xy 134.504397 -235.962186) (xy 134.474373 -236.006223) (xy 134.438121 -236.045294) (xy 134.39645 -236.078525)
			(xy 134.350292 -236.105174) (xy 134.300678 -236.124646) (xy 134.248716 -236.136506) (xy 134.195566 -236.14049)
			(xy 134.142416 -236.136506) (xy 134.090454 -236.124646) (xy 134.04084 -236.105174) (xy 133.994682 -236.078525)
			(xy 133.953011 -236.045294) (xy 133.916759 -236.006223) (xy 133.886735 -235.962186) (xy 133.863609 -235.914165)
			(xy 133.847899 -235.863235) (xy 133.839956 -235.810531) (xy 133.611376 -235.810531) (xy 133.603433 -235.863235)
			(xy 133.587723 -235.914165) (xy 133.564597 -235.962186) (xy 133.534573 -236.006223) (xy 133.498321 -236.045294)
			(xy 133.45665 -236.078525) (xy 133.410492 -236.105174) (xy 133.360878 -236.124646) (xy 133.308916 -236.136506)
			(xy 133.255766 -236.14049) (xy 133.202616 -236.136506) (xy 133.150654 -236.124646) (xy 133.10104 -236.105174)
			(xy 133.054882 -236.078525) (xy 133.013211 -236.045294) (xy 132.976959 -236.006223) (xy 132.946935 -235.962186)
			(xy 132.923809 -235.914165) (xy 132.908099 -235.863235) (xy 132.900156 -235.810531) (xy 132.671322 -235.810531)
			(xy 132.663379 -235.863235) (xy 132.647669 -235.914165) (xy 132.624543 -235.962186) (xy 132.594519 -236.006223)
			(xy 132.558267 -236.045294) (xy 132.516596 -236.078525) (xy 132.470438 -236.105174) (xy 132.420824 -236.124646)
			(xy 132.368862 -236.136506) (xy 132.315712 -236.14049) (xy 132.262562 -236.136506) (xy 132.2106 -236.124646)
			(xy 132.160986 -236.105174) (xy 132.114828 -236.078525) (xy 132.073157 -236.045294) (xy 132.036905 -236.006223)
			(xy 132.006881 -235.962186) (xy 131.983755 -235.914165) (xy 131.968045 -235.863235) (xy 131.960102 -235.810531)
			(xy 131.731776 -235.810531) (xy 131.723833 -235.863235) (xy 131.708123 -235.914165) (xy 131.684997 -235.962186)
			(xy 131.654973 -236.006223) (xy 131.618721 -236.045294) (xy 131.57705 -236.078525) (xy 131.530892 -236.105174)
			(xy 131.481278 -236.124646) (xy 131.429316 -236.136506) (xy 131.376166 -236.14049) (xy 131.323016 -236.136506)
			(xy 131.271054 -236.124646) (xy 131.22144 -236.105174) (xy 131.175282 -236.078525) (xy 131.133611 -236.045294)
			(xy 131.097359 -236.006223) (xy 131.067335 -235.962186) (xy 131.044209 -235.914165) (xy 131.028499 -235.863235)
			(xy 131.020556 -235.810531) (xy 130.791976 -235.810531) (xy 130.784033 -235.863235) (xy 130.768323 -235.914165)
			(xy 130.745197 -235.962186) (xy 130.715173 -236.006223) (xy 130.678921 -236.045294) (xy 130.63725 -236.078525)
			(xy 130.591092 -236.105174) (xy 130.541478 -236.124646) (xy 130.489516 -236.136506) (xy 130.436366 -236.14049)
			(xy 130.383216 -236.136506) (xy 130.331254 -236.124646) (xy 130.28164 -236.105174) (xy 130.235482 -236.078525)
			(xy 130.193811 -236.045294) (xy 130.157559 -236.006223) (xy 130.127535 -235.962186) (xy 130.104409 -235.914165)
			(xy 130.088699 -235.863235) (xy 130.080756 -235.810531) (xy 129.852176 -235.810531) (xy 129.844233 -235.863235)
			(xy 129.828523 -235.914165) (xy 129.805397 -235.962186) (xy 129.775373 -236.006223) (xy 129.739121 -236.045294)
			(xy 129.69745 -236.078525) (xy 129.651292 -236.105174) (xy 129.601678 -236.124646) (xy 129.549716 -236.136506)
			(xy 129.496566 -236.14049) (xy 129.443416 -236.136506) (xy 129.391454 -236.124646) (xy 129.34184 -236.105174)
			(xy 129.295682 -236.078525) (xy 129.254011 -236.045294) (xy 129.217759 -236.006223) (xy 129.187735 -235.962186)
			(xy 129.164609 -235.914165) (xy 129.148899 -235.863235) (xy 129.140956 -235.810531) (xy 128.912376 -235.810531)
			(xy 128.904433 -235.863235) (xy 128.888723 -235.914165) (xy 128.865597 -235.962186) (xy 128.835573 -236.006223)
			(xy 128.799321 -236.045294) (xy 128.75765 -236.078525) (xy 128.711492 -236.105174) (xy 128.661878 -236.124646)
			(xy 128.609916 -236.136506) (xy 128.556766 -236.14049) (xy 128.503616 -236.136506) (xy 128.451654 -236.124646)
			(xy 128.40204 -236.105174) (xy 128.355882 -236.078525) (xy 128.314211 -236.045294) (xy 128.277959 -236.006223)
			(xy 128.247935 -235.962186) (xy 128.224809 -235.914165) (xy 128.209099 -235.863235) (xy 128.201156 -235.810531)
			(xy 127.972576 -235.810531) (xy 127.964633 -235.863235) (xy 127.948923 -235.914165) (xy 127.925797 -235.962186)
			(xy 127.895773 -236.006223) (xy 127.859521 -236.045294) (xy 127.81785 -236.078525) (xy 127.771692 -236.105174)
			(xy 127.722078 -236.124646) (xy 127.670116 -236.136506) (xy 127.616966 -236.14049) (xy 127.563816 -236.136506)
			(xy 127.511854 -236.124646) (xy 127.46224 -236.105174) (xy 127.416082 -236.078525) (xy 127.374411 -236.045294)
			(xy 127.338159 -236.006223) (xy 127.308135 -235.962186) (xy 127.285009 -235.914165) (xy 127.269299 -235.863235)
			(xy 127.261356 -235.810531) (xy 127.032776 -235.810531) (xy 127.024833 -235.863235) (xy 127.009123 -235.914165)
			(xy 126.985997 -235.962186) (xy 126.955973 -236.006223) (xy 126.919721 -236.045294) (xy 126.87805 -236.078525)
			(xy 126.831892 -236.105174) (xy 126.782278 -236.124646) (xy 126.730316 -236.136506) (xy 126.677166 -236.14049)
			(xy 126.624016 -236.136506) (xy 126.572054 -236.124646) (xy 126.52244 -236.105174) (xy 126.476282 -236.078525)
			(xy 126.434611 -236.045294) (xy 126.398359 -236.006223) (xy 126.368335 -235.962186) (xy 126.345209 -235.914165)
			(xy 126.329499 -235.863235) (xy 126.321556 -235.810531) (xy 126.092722 -235.810531) (xy 126.084779 -235.863235)
			(xy 126.069069 -235.914165) (xy 126.045943 -235.962186) (xy 126.015919 -236.006223) (xy 125.979667 -236.045294)
			(xy 125.937996 -236.078525) (xy 125.891838 -236.105174) (xy 125.842224 -236.124646) (xy 125.790262 -236.136506)
			(xy 125.737112 -236.14049) (xy 125.683962 -236.136506) (xy 125.632 -236.124646) (xy 125.582386 -236.105174)
			(xy 125.536228 -236.078525) (xy 125.494557 -236.045294) (xy 125.458305 -236.006223) (xy 125.428281 -235.962186)
			(xy 125.405155 -235.914165) (xy 125.389445 -235.863235) (xy 125.381502 -235.810531) (xy 125.153176 -235.810531)
			(xy 125.145233 -235.863235) (xy 125.129523 -235.914165) (xy 125.106397 -235.962186) (xy 125.076373 -236.006223)
			(xy 125.040121 -236.045294) (xy 124.99845 -236.078525) (xy 124.952292 -236.105174) (xy 124.902678 -236.124646)
			(xy 124.850716 -236.136506) (xy 124.797566 -236.14049) (xy 124.744416 -236.136506) (xy 124.692454 -236.124646)
			(xy 124.64284 -236.105174) (xy 124.596682 -236.078525) (xy 124.555011 -236.045294) (xy 124.518759 -236.006223)
			(xy 124.488735 -235.962186) (xy 124.465609 -235.914165) (xy 124.449899 -235.863235) (xy 124.441956 -235.810531)
			(xy 124.213376 -235.810531) (xy 124.205433 -235.863235) (xy 124.189723 -235.914165) (xy 124.166597 -235.962186)
			(xy 124.136573 -236.006223) (xy 124.100321 -236.045294) (xy 124.05865 -236.078525) (xy 124.012492 -236.105174)
			(xy 123.962878 -236.124646) (xy 123.910916 -236.136506) (xy 123.857766 -236.14049) (xy 123.804616 -236.136506)
			(xy 123.752654 -236.124646) (xy 123.70304 -236.105174) (xy 123.656882 -236.078525) (xy 123.615211 -236.045294)
			(xy 123.578959 -236.006223) (xy 123.548935 -235.962186) (xy 123.525809 -235.914165) (xy 123.510099 -235.863235)
			(xy 123.502156 -235.810531) (xy 123.273576 -235.810531) (xy 123.265633 -235.863235) (xy 123.249923 -235.914165)
			(xy 123.226797 -235.962186) (xy 123.196773 -236.006223) (xy 123.160521 -236.045294) (xy 123.11885 -236.078525)
			(xy 123.072692 -236.105174) (xy 123.023078 -236.124646) (xy 122.971116 -236.136506) (xy 122.917966 -236.14049)
			(xy 122.864816 -236.136506) (xy 122.812854 -236.124646) (xy 122.76324 -236.105174) (xy 122.717082 -236.078525)
			(xy 122.675411 -236.045294) (xy 122.639159 -236.006223) (xy 122.609135 -235.962186) (xy 122.586009 -235.914165)
			(xy 122.570299 -235.863235) (xy 122.562356 -235.810531) (xy 122.333776 -235.810531) (xy 122.325833 -235.863235)
			(xy 122.310123 -235.914165) (xy 122.286997 -235.962186) (xy 122.256973 -236.006223) (xy 122.220721 -236.045294)
			(xy 122.17905 -236.078525) (xy 122.132892 -236.105174) (xy 122.083278 -236.124646) (xy 122.031316 -236.136506)
			(xy 121.978166 -236.14049) (xy 121.925016 -236.136506) (xy 121.873054 -236.124646) (xy 121.82344 -236.105174)
			(xy 121.777282 -236.078525) (xy 121.735611 -236.045294) (xy 121.699359 -236.006223) (xy 121.669335 -235.962186)
			(xy 121.646209 -235.914165) (xy 121.630499 -235.863235) (xy 121.622556 -235.810531) (xy 114.81563 -235.810531)
			(xy 114.807687 -235.863235) (xy 114.791977 -235.914165) (xy 114.768851 -235.962186) (xy 114.738827 -236.006223)
			(xy 114.702575 -236.045294) (xy 114.660904 -236.078525) (xy 114.614746 -236.105174) (xy 114.565132 -236.124646)
			(xy 114.51317 -236.136506) (xy 114.46002 -236.14049) (xy 114.40687 -236.136506) (xy 114.354908 -236.124646)
			(xy 114.305294 -236.105174) (xy 114.259136 -236.078525) (xy 114.217465 -236.045294) (xy 114.181213 -236.006223)
			(xy 114.151189 -235.962186) (xy 114.128063 -235.914165) (xy 114.112353 -235.863235) (xy 114.10441 -235.810531)
			(xy 113.87583 -235.810531) (xy 113.867887 -235.863235) (xy 113.852177 -235.914165) (xy 113.829051 -235.962186)
			(xy 113.799027 -236.006223) (xy 113.762775 -236.045294) (xy 113.721104 -236.078525) (xy 113.674946 -236.105174)
			(xy 113.625332 -236.124646) (xy 113.57337 -236.136506) (xy 113.52022 -236.14049) (xy 113.46707 -236.136506)
			(xy 113.415108 -236.124646) (xy 113.365494 -236.105174) (xy 113.319336 -236.078525) (xy 113.277665 -236.045294)
			(xy 113.241413 -236.006223) (xy 113.211389 -235.962186) (xy 113.188263 -235.914165) (xy 113.172553 -235.863235)
			(xy 113.16461 -235.810531) (xy 112.93603 -235.810531) (xy 112.928087 -235.863235) (xy 112.912377 -235.914165)
			(xy 112.889251 -235.962186) (xy 112.859227 -236.006223) (xy 112.822975 -236.045294) (xy 112.781304 -236.078525)
			(xy 112.735146 -236.105174) (xy 112.685532 -236.124646) (xy 112.63357 -236.136506) (xy 112.58042 -236.14049)
			(xy 112.52727 -236.136506) (xy 112.475308 -236.124646) (xy 112.425694 -236.105174) (xy 112.379536 -236.078525)
			(xy 112.337865 -236.045294) (xy 112.301613 -236.006223) (xy 112.271589 -235.962186) (xy 112.248463 -235.914165)
			(xy 112.232753 -235.863235) (xy 112.22481 -235.810531) (xy 111.99623 -235.810531) (xy 111.988287 -235.863235)
			(xy 111.972577 -235.914165) (xy 111.949451 -235.962186) (xy 111.919427 -236.006223) (xy 111.883175 -236.045294)
			(xy 111.841504 -236.078525) (xy 111.795346 -236.105174) (xy 111.745732 -236.124646) (xy 111.69377 -236.136506)
			(xy 111.64062 -236.14049) (xy 111.58747 -236.136506) (xy 111.535508 -236.124646) (xy 111.485894 -236.105174)
			(xy 111.439736 -236.078525) (xy 111.398065 -236.045294) (xy 111.361813 -236.006223) (xy 111.331789 -235.962186)
			(xy 111.308663 -235.914165) (xy 111.292953 -235.863235) (xy 111.28501 -235.810531) (xy 111.05643 -235.810531)
			(xy 111.048487 -235.863235) (xy 111.032777 -235.914165) (xy 111.009651 -235.962186) (xy 110.979627 -236.006223)
			(xy 110.943375 -236.045294) (xy 110.901704 -236.078525) (xy 110.855546 -236.105174) (xy 110.805932 -236.124646)
			(xy 110.75397 -236.136506) (xy 110.70082 -236.14049) (xy 110.64767 -236.136506) (xy 110.595708 -236.124646)
			(xy 110.546094 -236.105174) (xy 110.499936 -236.078525) (xy 110.458265 -236.045294) (xy 110.422013 -236.006223)
			(xy 110.391989 -235.962186) (xy 110.368863 -235.914165) (xy 110.353153 -235.863235) (xy 110.34521 -235.810531)
			(xy 110.11663 -235.810531) (xy 110.108687 -235.863235) (xy 110.092977 -235.914165) (xy 110.069851 -235.962186)
			(xy 110.039827 -236.006223) (xy 110.003575 -236.045294) (xy 109.961904 -236.078525) (xy 109.915746 -236.105174)
			(xy 109.866132 -236.124646) (xy 109.81417 -236.136506) (xy 109.76102 -236.14049) (xy 109.70787 -236.136506)
			(xy 109.655908 -236.124646) (xy 109.606294 -236.105174) (xy 109.560136 -236.078525) (xy 109.518465 -236.045294)
			(xy 109.482213 -236.006223) (xy 109.452189 -235.962186) (xy 109.429063 -235.914165) (xy 109.413353 -235.863235)
			(xy 109.40541 -235.810531) (xy 108.349113 -235.810531) (xy 108.36765 -235.825757) (xy 108.402879 -235.864653)
			(xy 108.432022 -235.908295) (xy 108.454448 -235.955739) (xy 108.469674 -236.00596) (xy 108.47737 -236.057871)
			(xy 108.477812 -236.08411) (xy 108.47743 -236.107677) (xy 108.471211 -236.1544) (xy 108.458882 -236.199894)
			(xy 108.450126 -236.221778) (xy 108.445023 -236.235152) (xy 108.441674 -236.263569) (xy 108.446337 -236.291799)
			(xy 108.458646 -236.317629) (xy 108.477636 -236.339032) (xy 108.501818 -236.354328) (xy 108.529292 -236.362318)
			(xy 108.543598 -236.362748) (xy 109.02315 -236.362748) (xy 109.04172 -236.34239) (xy 109.084026 -236.307086)
			(xy 109.131262 -236.278715) (xy 109.182302 -236.257953) (xy 109.235929 -236.245294) (xy 109.290866 -236.241041)
			(xy 109.345803 -236.245294) (xy 109.39943 -236.257953) (xy 109.45047 -236.278715) (xy 109.497706 -236.307086)
			(xy 109.540012 -236.34239) (xy 109.558582 -236.362748) (xy 109.963204 -236.362748) (xy 109.981774 -236.34239)
			(xy 110.02408 -236.307086) (xy 110.071316 -236.278715) (xy 110.122356 -236.257953) (xy 110.175983 -236.245294)
			(xy 110.23092 -236.241041) (xy 110.285857 -236.245294) (xy 110.339484 -236.257953) (xy 110.390524 -236.278715)
			(xy 110.43776 -236.307086) (xy 110.480066 -236.34239) (xy 110.498636 -236.362748) (xy 110.90275 -236.362748)
			(xy 110.92132 -236.34239) (xy 110.963626 -236.307086) (xy 111.010862 -236.278715) (xy 111.061902 -236.257953)
			(xy 111.115529 -236.245294) (xy 111.170466 -236.241041) (xy 111.225403 -236.245294) (xy 111.27903 -236.257953)
			(xy 111.33007 -236.278715) (xy 111.377306 -236.307086) (xy 111.419612 -236.34239) (xy 111.438182 -236.362748)
			(xy 111.84255 -236.362748) (xy 111.86112 -236.34239) (xy 111.903426 -236.307086) (xy 111.950662 -236.278715)
			(xy 112.001702 -236.257953) (xy 112.055329 -236.245294) (xy 112.110266 -236.241041) (xy 112.165203 -236.245294)
			(xy 112.21883 -236.257953) (xy 112.26987 -236.278715) (xy 112.317106 -236.307086) (xy 112.359412 -236.34239)
			(xy 112.377982 -236.362748) (xy 112.78235 -236.362748) (xy 112.80092 -236.34239) (xy 112.843226 -236.307086)
			(xy 112.890462 -236.278715) (xy 112.941502 -236.257953) (xy 112.995129 -236.245294) (xy 113.050066 -236.241041)
			(xy 113.105003 -236.245294) (xy 113.15863 -236.257953) (xy 113.20967 -236.278715) (xy 113.256906 -236.307086)
			(xy 113.299212 -236.34239) (xy 113.317782 -236.362748) (xy 113.722404 -236.362748) (xy 113.740974 -236.34239)
			(xy 113.78328 -236.307086) (xy 113.830516 -236.278715) (xy 113.881556 -236.257953) (xy 113.935183 -236.245294)
			(xy 113.99012 -236.241041) (xy 114.045057 -236.245294) (xy 114.098684 -236.257953) (xy 114.149724 -236.278715)
			(xy 114.19696 -236.307086) (xy 114.239266 -236.34239) (xy 114.257836 -236.362748) (xy 115.0493 -236.362748)
			(xy 115.064739 -236.341239) (xy 115.100942 -236.302606) (xy 115.142469 -236.269764) (xy 115.188403 -236.243436)
			(xy 115.237731 -236.224204) (xy 115.289364 -236.212492) (xy 115.342162 -236.208559) (xy 115.39496 -236.212492)
			(xy 115.446593 -236.224204) (xy 115.495921 -236.243436) (xy 115.510862 -236.252) (xy 120.619796 -236.252)
			(xy 120.623779 -236.198852) (xy 120.635639 -236.146891) (xy 120.65511 -236.097278) (xy 120.681758 -236.051121)
			(xy 120.714988 -236.009452) (xy 120.754057 -235.9732) (xy 120.798092 -235.943176) (xy 120.846111 -235.92005)
			(xy 120.89704 -235.904339) (xy 120.949741 -235.896394) (xy 120.97639 -235.895896) (xy 121.002974 -235.896332)
			(xy 121.055553 -235.904222) (xy 121.106374 -235.919842) (xy 121.154308 -235.942846) (xy 121.198288 -235.972723)
			(xy 121.237336 -236.008807) (xy 121.270584 -236.050296) (xy 121.297293 -236.096268) (xy 121.316869 -236.1457)
			(xy 121.323354 -236.171486) (xy 121.327434 -236.186528) (xy 121.343276 -236.213348) (xy 121.366478 -236.234133)
			(xy 121.394872 -236.246941) (xy 121.425808 -236.250577) (xy 121.44121 -236.248194) (xy 121.457753 -236.245242)
			(xy 121.491209 -236.242059) (xy 121.508012 -236.241844) (xy 121.534657 -236.242439) (xy 121.587352 -236.250383)
			(xy 121.638274 -236.266092) (xy 121.686286 -236.289215) (xy 121.730316 -236.319235) (xy 121.76938 -236.355482)
			(xy 121.802605 -236.397147) (xy 121.82925 -236.443298) (xy 121.848719 -236.492905) (xy 121.860577 -236.544859)
			(xy 121.864559 -236.598) (xy 121.862566 -236.624601) (xy 122.092456 -236.624601) (xy 122.092456 -236.571303)
			(xy 122.100399 -236.518599) (xy 122.116109 -236.467669) (xy 122.139235 -236.419648) (xy 122.169259 -236.375611)
			(xy 122.205511 -236.33654) (xy 122.247182 -236.303309) (xy 122.29334 -236.27666) (xy 122.342954 -236.257188)
			(xy 122.394916 -236.245328) (xy 122.448066 -236.241345) (xy 122.501216 -236.245328) (xy 122.553178 -236.257188)
			(xy 122.602792 -236.27666) (xy 122.64895 -236.303309) (xy 122.690621 -236.33654) (xy 122.726873 -236.375611)
			(xy 122.756897 -236.419648) (xy 122.780023 -236.467669) (xy 122.795733 -236.518599) (xy 122.803676 -236.571303)
			(xy 122.804174 -236.597952) (xy 122.803676 -236.624601) (xy 123.032002 -236.624601) (xy 123.032002 -236.571303)
			(xy 123.039945 -236.518599) (xy 123.055655 -236.467669) (xy 123.078781 -236.419648) (xy 123.108805 -236.375611)
			(xy 123.145057 -236.33654) (xy 123.186728 -236.303309) (xy 123.232886 -236.27666) (xy 123.2825 -236.257188)
			(xy 123.334462 -236.245328) (xy 123.387612 -236.241345) (xy 123.440762 -236.245328) (xy 123.492724 -236.257188)
			(xy 123.542338 -236.27666) (xy 123.588496 -236.303309) (xy 123.630167 -236.33654) (xy 123.666419 -236.375611)
			(xy 123.696443 -236.419648) (xy 123.719569 -236.467669) (xy 123.735279 -236.518599) (xy 123.743222 -236.571303)
			(xy 123.74372 -236.597952) (xy 123.743222 -236.624601) (xy 123.971802 -236.624601) (xy 123.971802 -236.571303)
			(xy 123.979745 -236.518599) (xy 123.995455 -236.467669) (xy 124.018581 -236.419648) (xy 124.048605 -236.375611)
			(xy 124.084857 -236.33654) (xy 124.126528 -236.303309) (xy 124.172686 -236.27666) (xy 124.2223 -236.257188)
			(xy 124.274262 -236.245328) (xy 124.327412 -236.241345) (xy 124.380562 -236.245328) (xy 124.432524 -236.257188)
			(xy 124.482138 -236.27666) (xy 124.528296 -236.303309) (xy 124.569967 -236.33654) (xy 124.606219 -236.375611)
			(xy 124.636243 -236.419648) (xy 124.659369 -236.467669) (xy 124.675079 -236.518599) (xy 124.683022 -236.571303)
			(xy 124.68352 -236.597952) (xy 124.683022 -236.624601) (xy 124.911602 -236.624601) (xy 124.911602 -236.571303)
			(xy 124.919545 -236.518599) (xy 124.935255 -236.467669) (xy 124.958381 -236.419648) (xy 124.988405 -236.375611)
			(xy 125.024657 -236.33654) (xy 125.066328 -236.303309) (xy 125.112486 -236.27666) (xy 125.1621 -236.257188)
			(xy 125.214062 -236.245328) (xy 125.267212 -236.241345) (xy 125.320362 -236.245328) (xy 125.372324 -236.257188)
			(xy 125.421938 -236.27666) (xy 125.468096 -236.303309) (xy 125.509767 -236.33654) (xy 125.546019 -236.375611)
			(xy 125.576043 -236.419648) (xy 125.599169 -236.467669) (xy 125.614879 -236.518599) (xy 125.622822 -236.571303)
			(xy 125.62332 -236.597952) (xy 125.622822 -236.624601) (xy 125.851402 -236.624601) (xy 125.851402 -236.571303)
			(xy 125.859345 -236.518599) (xy 125.875055 -236.467669) (xy 125.898181 -236.419648) (xy 125.928205 -236.375611)
			(xy 125.964457 -236.33654) (xy 126.006128 -236.303309) (xy 126.052286 -236.27666) (xy 126.1019 -236.257188)
			(xy 126.153862 -236.245328) (xy 126.207012 -236.241345) (xy 126.260162 -236.245328) (xy 126.312124 -236.257188)
			(xy 126.361738 -236.27666) (xy 126.407896 -236.303309) (xy 126.449567 -236.33654) (xy 126.485819 -236.375611)
			(xy 126.515843 -236.419648) (xy 126.538969 -236.467669) (xy 126.554679 -236.518599) (xy 126.562622 -236.571303)
			(xy 126.56312 -236.597952) (xy 126.562622 -236.624601) (xy 126.791202 -236.624601) (xy 126.791202 -236.571303)
			(xy 126.799145 -236.518599) (xy 126.814855 -236.467669) (xy 126.837981 -236.419648) (xy 126.868005 -236.375611)
			(xy 126.904257 -236.33654) (xy 126.945928 -236.303309) (xy 126.992086 -236.27666) (xy 127.0417 -236.257188)
			(xy 127.093662 -236.245328) (xy 127.146812 -236.241345) (xy 127.199962 -236.245328) (xy 127.251924 -236.257188)
			(xy 127.301538 -236.27666) (xy 127.347696 -236.303309) (xy 127.389367 -236.33654) (xy 127.425619 -236.375611)
			(xy 127.455643 -236.419648) (xy 127.478769 -236.467669) (xy 127.494479 -236.518599) (xy 127.502422 -236.571303)
			(xy 127.50292 -236.597952) (xy 127.502422 -236.624601) (xy 127.731002 -236.624601) (xy 127.731002 -236.571303)
			(xy 127.738945 -236.518599) (xy 127.754655 -236.467669) (xy 127.777781 -236.419648) (xy 127.807805 -236.375611)
			(xy 127.844057 -236.33654) (xy 127.885728 -236.303309) (xy 127.931886 -236.27666) (xy 127.9815 -236.257188)
			(xy 128.033462 -236.245328) (xy 128.086612 -236.241345) (xy 128.139762 -236.245328) (xy 128.191724 -236.257188)
			(xy 128.241338 -236.27666) (xy 128.287496 -236.303309) (xy 128.329167 -236.33654) (xy 128.365419 -236.375611)
			(xy 128.395443 -236.419648) (xy 128.418569 -236.467669) (xy 128.434279 -236.518599) (xy 128.442222 -236.571303)
			(xy 128.44272 -236.597952) (xy 128.442222 -236.624601) (xy 128.671056 -236.624601) (xy 128.671056 -236.571303)
			(xy 128.678999 -236.518599) (xy 128.694709 -236.467669) (xy 128.717835 -236.419648) (xy 128.747859 -236.375611)
			(xy 128.784111 -236.33654) (xy 128.825782 -236.303309) (xy 128.87194 -236.27666) (xy 128.921554 -236.257188)
			(xy 128.973516 -236.245328) (xy 129.026666 -236.241345) (xy 129.079816 -236.245328) (xy 129.131778 -236.257188)
			(xy 129.181392 -236.27666) (xy 129.22755 -236.303309) (xy 129.269221 -236.33654) (xy 129.305473 -236.375611)
			(xy 129.335497 -236.419648) (xy 129.358623 -236.467669) (xy 129.374333 -236.518599) (xy 129.382276 -236.571303)
			(xy 129.382774 -236.597952) (xy 129.382276 -236.624601) (xy 129.610602 -236.624601) (xy 129.610602 -236.571303)
			(xy 129.618545 -236.518599) (xy 129.634255 -236.467669) (xy 129.657381 -236.419648) (xy 129.687405 -236.375611)
			(xy 129.723657 -236.33654) (xy 129.765328 -236.303309) (xy 129.811486 -236.27666) (xy 129.8611 -236.257188)
			(xy 129.913062 -236.245328) (xy 129.966212 -236.241345) (xy 130.019362 -236.245328) (xy 130.071324 -236.257188)
			(xy 130.120938 -236.27666) (xy 130.167096 -236.303309) (xy 130.208767 -236.33654) (xy 130.245019 -236.375611)
			(xy 130.275043 -236.419648) (xy 130.298169 -236.467669) (xy 130.313879 -236.518599) (xy 130.321822 -236.571303)
			(xy 130.32232 -236.597952) (xy 130.321822 -236.624601) (xy 130.550402 -236.624601) (xy 130.550402 -236.571303)
			(xy 130.558345 -236.518599) (xy 130.574055 -236.467669) (xy 130.597181 -236.419648) (xy 130.627205 -236.375611)
			(xy 130.663457 -236.33654) (xy 130.705128 -236.303309) (xy 130.751286 -236.27666) (xy 130.8009 -236.257188)
			(xy 130.852862 -236.245328) (xy 130.906012 -236.241345) (xy 130.959162 -236.245328) (xy 131.011124 -236.257188)
			(xy 131.060738 -236.27666) (xy 131.106896 -236.303309) (xy 131.148567 -236.33654) (xy 131.184819 -236.375611)
			(xy 131.214843 -236.419648) (xy 131.237969 -236.467669) (xy 131.253679 -236.518599) (xy 131.261622 -236.571303)
			(xy 131.26212 -236.597952) (xy 131.261622 -236.624601) (xy 131.490202 -236.624601) (xy 131.490202 -236.571303)
			(xy 131.498145 -236.518599) (xy 131.513855 -236.467669) (xy 131.536981 -236.419648) (xy 131.567005 -236.375611)
			(xy 131.603257 -236.33654) (xy 131.644928 -236.303309) (xy 131.691086 -236.27666) (xy 131.7407 -236.257188)
			(xy 131.792662 -236.245328) (xy 131.845812 -236.241345) (xy 131.898962 -236.245328) (xy 131.950924 -236.257188)
			(xy 132.000538 -236.27666) (xy 132.046696 -236.303309) (xy 132.088367 -236.33654) (xy 132.124619 -236.375611)
			(xy 132.154643 -236.419648) (xy 132.177769 -236.467669) (xy 132.193479 -236.518599) (xy 132.201422 -236.571303)
			(xy 132.20192 -236.597952) (xy 132.201422 -236.624601) (xy 132.430002 -236.624601) (xy 132.430002 -236.571303)
			(xy 132.437945 -236.518599) (xy 132.453655 -236.467669) (xy 132.476781 -236.419648) (xy 132.506805 -236.375611)
			(xy 132.543057 -236.33654) (xy 132.584728 -236.303309) (xy 132.630886 -236.27666) (xy 132.6805 -236.257188)
			(xy 132.732462 -236.245328) (xy 132.785612 -236.241345) (xy 132.838762 -236.245328) (xy 132.890724 -236.257188)
			(xy 132.940338 -236.27666) (xy 132.986496 -236.303309) (xy 133.028167 -236.33654) (xy 133.064419 -236.375611)
			(xy 133.094443 -236.419648) (xy 133.117569 -236.467669) (xy 133.133279 -236.518599) (xy 133.141222 -236.571303)
			(xy 133.14172 -236.597952) (xy 133.141222 -236.624601) (xy 133.370056 -236.624601) (xy 133.370056 -236.571303)
			(xy 133.377999 -236.518599) (xy 133.393709 -236.467669) (xy 133.416835 -236.419648) (xy 133.446859 -236.375611)
			(xy 133.483111 -236.33654) (xy 133.524782 -236.303309) (xy 133.57094 -236.27666) (xy 133.620554 -236.257188)
			(xy 133.672516 -236.245328) (xy 133.725666 -236.241345) (xy 133.778816 -236.245328) (xy 133.830778 -236.257188)
			(xy 133.880392 -236.27666) (xy 133.92655 -236.303309) (xy 133.968221 -236.33654) (xy 134.004473 -236.375611)
			(xy 134.034497 -236.419648) (xy 134.057623 -236.467669) (xy 134.073333 -236.518599) (xy 134.081276 -236.571303)
			(xy 134.081774 -236.597952) (xy 134.081276 -236.624601) (xy 134.309856 -236.624601) (xy 134.309856 -236.571303)
			(xy 134.317799 -236.518599) (xy 134.333509 -236.467669) (xy 134.356635 -236.419648) (xy 134.386659 -236.375611)
			(xy 134.422911 -236.33654) (xy 134.464582 -236.303309) (xy 134.51074 -236.27666) (xy 134.560354 -236.257188)
			(xy 134.612316 -236.245328) (xy 134.665466 -236.241345) (xy 134.718616 -236.245328) (xy 134.770578 -236.257188)
			(xy 134.820192 -236.27666) (xy 134.86635 -236.303309) (xy 134.908021 -236.33654) (xy 134.944273 -236.375611)
			(xy 134.974297 -236.419648) (xy 134.997423 -236.467669) (xy 135.013133 -236.518599) (xy 135.021076 -236.571303)
			(xy 135.021574 -236.597952) (xy 135.021076 -236.624601) (xy 135.013133 -236.677305) (xy 134.997423 -236.728235)
			(xy 134.974297 -236.776256) (xy 134.944273 -236.820293) (xy 134.908021 -236.859364) (xy 134.86635 -236.892595)
			(xy 134.820192 -236.919244) (xy 134.770578 -236.938716) (xy 134.718616 -236.950576) (xy 134.665466 -236.95456)
			(xy 134.612316 -236.950576) (xy 134.560354 -236.938716) (xy 134.51074 -236.919244) (xy 134.464582 -236.892595)
			(xy 134.422911 -236.859364) (xy 134.386659 -236.820293) (xy 134.356635 -236.776256) (xy 134.333509 -236.728235)
			(xy 134.317799 -236.677305) (xy 134.309856 -236.624601) (xy 134.081276 -236.624601) (xy 134.073333 -236.677305)
			(xy 134.057623 -236.728235) (xy 134.034497 -236.776256) (xy 134.004473 -236.820293) (xy 133.968221 -236.859364)
			(xy 133.92655 -236.892595) (xy 133.880392 -236.919244) (xy 133.830778 -236.938716) (xy 133.778816 -236.950576)
			(xy 133.725666 -236.95456) (xy 133.672516 -236.950576) (xy 133.620554 -236.938716) (xy 133.57094 -236.919244)
			(xy 133.524782 -236.892595) (xy 133.483111 -236.859364) (xy 133.446859 -236.820293) (xy 133.416835 -236.776256)
			(xy 133.393709 -236.728235) (xy 133.377999 -236.677305) (xy 133.370056 -236.624601) (xy 133.141222 -236.624601)
			(xy 133.133279 -236.677305) (xy 133.117569 -236.728235) (xy 133.094443 -236.776256) (xy 133.064419 -236.820293)
			(xy 133.028167 -236.859364) (xy 132.986496 -236.892595) (xy 132.940338 -236.919244) (xy 132.890724 -236.938716)
			(xy 132.838762 -236.950576) (xy 132.785612 -236.95456) (xy 132.732462 -236.950576) (xy 132.6805 -236.938716)
			(xy 132.630886 -236.919244) (xy 132.584728 -236.892595) (xy 132.543057 -236.859364) (xy 132.506805 -236.820293)
			(xy 132.476781 -236.776256) (xy 132.453655 -236.728235) (xy 132.437945 -236.677305) (xy 132.430002 -236.624601)
			(xy 132.201422 -236.624601) (xy 132.193479 -236.677305) (xy 132.177769 -236.728235) (xy 132.154643 -236.776256)
			(xy 132.124619 -236.820293) (xy 132.088367 -236.859364) (xy 132.046696 -236.892595) (xy 132.000538 -236.919244)
			(xy 131.950924 -236.938716) (xy 131.898962 -236.950576) (xy 131.845812 -236.95456) (xy 131.792662 -236.950576)
			(xy 131.7407 -236.938716) (xy 131.691086 -236.919244) (xy 131.644928 -236.892595) (xy 131.603257 -236.859364)
			(xy 131.567005 -236.820293) (xy 131.536981 -236.776256) (xy 131.513855 -236.728235) (xy 131.498145 -236.677305)
			(xy 131.490202 -236.624601) (xy 131.261622 -236.624601) (xy 131.253679 -236.677305) (xy 131.237969 -236.728235)
			(xy 131.214843 -236.776256) (xy 131.184819 -236.820293) (xy 131.148567 -236.859364) (xy 131.106896 -236.892595)
			(xy 131.060738 -236.919244) (xy 131.011124 -236.938716) (xy 130.959162 -236.950576) (xy 130.906012 -236.95456)
			(xy 130.852862 -236.950576) (xy 130.8009 -236.938716) (xy 130.751286 -236.919244) (xy 130.705128 -236.892595)
			(xy 130.663457 -236.859364) (xy 130.627205 -236.820293) (xy 130.597181 -236.776256) (xy 130.574055 -236.728235)
			(xy 130.558345 -236.677305) (xy 130.550402 -236.624601) (xy 130.321822 -236.624601) (xy 130.313879 -236.677305)
			(xy 130.298169 -236.728235) (xy 130.275043 -236.776256) (xy 130.245019 -236.820293) (xy 130.208767 -236.859364)
			(xy 130.167096 -236.892595) (xy 130.120938 -236.919244) (xy 130.071324 -236.938716) (xy 130.019362 -236.950576)
			(xy 129.966212 -236.95456) (xy 129.913062 -236.950576) (xy 129.8611 -236.938716) (xy 129.811486 -236.919244)
			(xy 129.765328 -236.892595) (xy 129.723657 -236.859364) (xy 129.687405 -236.820293) (xy 129.657381 -236.776256)
			(xy 129.634255 -236.728235) (xy 129.618545 -236.677305) (xy 129.610602 -236.624601) (xy 129.382276 -236.624601)
			(xy 129.374333 -236.677305) (xy 129.358623 -236.728235) (xy 129.335497 -236.776256) (xy 129.305473 -236.820293)
			(xy 129.269221 -236.859364) (xy 129.22755 -236.892595) (xy 129.181392 -236.919244) (xy 129.131778 -236.938716)
			(xy 129.079816 -236.950576) (xy 129.026666 -236.95456) (xy 128.973516 -236.950576) (xy 128.921554 -236.938716)
			(xy 128.87194 -236.919244) (xy 128.825782 -236.892595) (xy 128.784111 -236.859364) (xy 128.747859 -236.820293)
			(xy 128.717835 -236.776256) (xy 128.694709 -236.728235) (xy 128.678999 -236.677305) (xy 128.671056 -236.624601)
			(xy 128.442222 -236.624601) (xy 128.434279 -236.677305) (xy 128.418569 -236.728235) (xy 128.395443 -236.776256)
			(xy 128.365419 -236.820293) (xy 128.329167 -236.859364) (xy 128.287496 -236.892595) (xy 128.241338 -236.919244)
			(xy 128.191724 -236.938716) (xy 128.139762 -236.950576) (xy 128.086612 -236.95456) (xy 128.033462 -236.950576)
			(xy 127.9815 -236.938716) (xy 127.931886 -236.919244) (xy 127.885728 -236.892595) (xy 127.844057 -236.859364)
			(xy 127.807805 -236.820293) (xy 127.777781 -236.776256) (xy 127.754655 -236.728235) (xy 127.738945 -236.677305)
			(xy 127.731002 -236.624601) (xy 127.502422 -236.624601) (xy 127.494479 -236.677305) (xy 127.478769 -236.728235)
			(xy 127.455643 -236.776256) (xy 127.425619 -236.820293) (xy 127.389367 -236.859364) (xy 127.347696 -236.892595)
			(xy 127.301538 -236.919244) (xy 127.251924 -236.938716) (xy 127.199962 -236.950576) (xy 127.146812 -236.95456)
			(xy 127.093662 -236.950576) (xy 127.0417 -236.938716) (xy 126.992086 -236.919244) (xy 126.945928 -236.892595)
			(xy 126.904257 -236.859364) (xy 126.868005 -236.820293) (xy 126.837981 -236.776256) (xy 126.814855 -236.728235)
			(xy 126.799145 -236.677305) (xy 126.791202 -236.624601) (xy 126.562622 -236.624601) (xy 126.554679 -236.677305)
			(xy 126.538969 -236.728235) (xy 126.515843 -236.776256) (xy 126.485819 -236.820293) (xy 126.449567 -236.859364)
			(xy 126.407896 -236.892595) (xy 126.361738 -236.919244) (xy 126.312124 -236.938716) (xy 126.260162 -236.950576)
			(xy 126.207012 -236.95456) (xy 126.153862 -236.950576) (xy 126.1019 -236.938716) (xy 126.052286 -236.919244)
			(xy 126.006128 -236.892595) (xy 125.964457 -236.859364) (xy 125.928205 -236.820293) (xy 125.898181 -236.776256)
			(xy 125.875055 -236.728235) (xy 125.859345 -236.677305) (xy 125.851402 -236.624601) (xy 125.622822 -236.624601)
			(xy 125.614879 -236.677305) (xy 125.599169 -236.728235) (xy 125.576043 -236.776256) (xy 125.546019 -236.820293)
			(xy 125.509767 -236.859364) (xy 125.468096 -236.892595) (xy 125.421938 -236.919244) (xy 125.372324 -236.938716)
			(xy 125.320362 -236.950576) (xy 125.267212 -236.95456) (xy 125.214062 -236.950576) (xy 125.1621 -236.938716)
			(xy 125.112486 -236.919244) (xy 125.066328 -236.892595) (xy 125.024657 -236.859364) (xy 124.988405 -236.820293)
			(xy 124.958381 -236.776256) (xy 124.935255 -236.728235) (xy 124.919545 -236.677305) (xy 124.911602 -236.624601)
			(xy 124.683022 -236.624601) (xy 124.675079 -236.677305) (xy 124.659369 -236.728235) (xy 124.636243 -236.776256)
			(xy 124.606219 -236.820293) (xy 124.569967 -236.859364) (xy 124.528296 -236.892595) (xy 124.482138 -236.919244)
			(xy 124.432524 -236.938716) (xy 124.380562 -236.950576) (xy 124.327412 -236.95456) (xy 124.274262 -236.950576)
			(xy 124.2223 -236.938716) (xy 124.172686 -236.919244) (xy 124.126528 -236.892595) (xy 124.084857 -236.859364)
			(xy 124.048605 -236.820293) (xy 124.018581 -236.776256) (xy 123.995455 -236.728235) (xy 123.979745 -236.677305)
			(xy 123.971802 -236.624601) (xy 123.743222 -236.624601) (xy 123.735279 -236.677305) (xy 123.719569 -236.728235)
			(xy 123.696443 -236.776256) (xy 123.666419 -236.820293) (xy 123.630167 -236.859364) (xy 123.588496 -236.892595)
			(xy 123.542338 -236.919244) (xy 123.492724 -236.938716) (xy 123.440762 -236.950576) (xy 123.387612 -236.95456)
			(xy 123.334462 -236.950576) (xy 123.2825 -236.938716) (xy 123.232886 -236.919244) (xy 123.186728 -236.892595)
			(xy 123.145057 -236.859364) (xy 123.108805 -236.820293) (xy 123.078781 -236.776256) (xy 123.055655 -236.728235)
			(xy 123.039945 -236.677305) (xy 123.032002 -236.624601) (xy 122.803676 -236.624601) (xy 122.795733 -236.677305)
			(xy 122.780023 -236.728235) (xy 122.756897 -236.776256) (xy 122.726873 -236.820293) (xy 122.690621 -236.859364)
			(xy 122.64895 -236.892595) (xy 122.602792 -236.919244) (xy 122.553178 -236.938716) (xy 122.501216 -236.950576)
			(xy 122.448066 -236.95456) (xy 122.394916 -236.950576) (xy 122.342954 -236.938716) (xy 122.29334 -236.919244)
			(xy 122.247182 -236.892595) (xy 122.205511 -236.859364) (xy 122.169259 -236.820293) (xy 122.139235 -236.776256)
			(xy 122.116109 -236.728235) (xy 122.100399 -236.677305) (xy 122.092456 -236.624601) (xy 121.862566 -236.624601)
			(xy 121.860577 -236.651141) (xy 121.848719 -236.703095) (xy 121.82925 -236.752702) (xy 121.802605 -236.798853)
			(xy 121.76938 -236.840518) (xy 121.730316 -236.876765) (xy 121.686286 -236.906785) (xy 121.638274 -236.929908)
			(xy 121.587352 -236.945617) (xy 121.534657 -236.953561) (xy 121.508012 -236.95406) (xy 121.481426 -236.953656)
			(xy 121.428844 -236.945766) (xy 121.37802 -236.930143) (xy 121.330085 -236.907136) (xy 121.286104 -236.877255)
			(xy 121.247056 -236.841167) (xy 121.213809 -236.799673) (xy 121.187102 -236.753695) (xy 121.16753 -236.704258)
			(xy 121.161048 -236.67847) (xy 121.156992 -236.663421) (xy 121.14114 -236.636604) (xy 121.117932 -236.615823)
			(xy 121.089534 -236.603017) (xy 121.058595 -236.59938) (xy 121.043192 -236.601762) (xy 121.026649 -236.604714)
			(xy 120.993193 -236.607897) (xy 120.97639 -236.608112) (xy 120.949741 -236.607606) (xy 120.89704 -236.599661)
			(xy 120.846111 -236.58395) (xy 120.798092 -236.560824) (xy 120.754057 -236.5308) (xy 120.714988 -236.494548)
			(xy 120.681758 -236.452879) (xy 120.65511 -236.406722) (xy 120.635639 -236.357109) (xy 120.623779 -236.305148)
			(xy 120.619796 -236.252) (xy 115.510862 -236.252) (xy 115.541855 -236.269764) (xy 115.583382 -236.302606)
			(xy 115.619585 -236.341239) (xy 115.635024 -236.362748) (xy 120.14708 -236.362748) (xy 120.865138 -237.080806)
			(xy 120.892824 -237.074202) (xy 120.913342 -237.069584) (xy 120.955107 -237.064621) (xy 120.976136 -237.064296)
			(xy 120.97639 -237.064296) (xy 121.004376 -237.064816) (xy 121.059658 -237.07357) (xy 121.112891 -237.090865)
			(xy 121.162762 -237.116275) (xy 121.208044 -237.149174) (xy 121.247622 -237.188751) (xy 121.280522 -237.234033)
			(xy 121.305932 -237.283904) (xy 121.323228 -237.337136) (xy 121.331984 -237.392418) (xy 121.332498 -237.420404)
			(xy 121.332161 -237.438163) (xy 121.622556 -237.438163) (xy 121.622556 -237.384865) (xy 121.630499 -237.332161)
			(xy 121.646209 -237.281231) (xy 121.669335 -237.23321) (xy 121.699359 -237.189173) (xy 121.735611 -237.150102)
			(xy 121.777282 -237.116871) (xy 121.82344 -237.090222) (xy 121.873054 -237.07075) (xy 121.925016 -237.05889)
			(xy 121.978166 -237.054907) (xy 122.031316 -237.05889) (xy 122.083278 -237.07075) (xy 122.132892 -237.090222)
			(xy 122.17905 -237.116871) (xy 122.220721 -237.150102) (xy 122.256973 -237.189173) (xy 122.286997 -237.23321)
			(xy 122.310123 -237.281231) (xy 122.325833 -237.332161) (xy 122.333776 -237.384865) (xy 122.334274 -237.411514)
			(xy 122.333776 -237.438163) (xy 122.562356 -237.438163) (xy 122.562356 -237.384865) (xy 122.570299 -237.332161)
			(xy 122.586009 -237.281231) (xy 122.609135 -237.23321) (xy 122.639159 -237.189173) (xy 122.675411 -237.150102)
			(xy 122.717082 -237.116871) (xy 122.76324 -237.090222) (xy 122.812854 -237.07075) (xy 122.864816 -237.05889)
			(xy 122.917966 -237.054907) (xy 122.971116 -237.05889) (xy 123.023078 -237.07075) (xy 123.072692 -237.090222)
			(xy 123.11885 -237.116871) (xy 123.160521 -237.150102) (xy 123.196773 -237.189173) (xy 123.226797 -237.23321)
			(xy 123.249923 -237.281231) (xy 123.265633 -237.332161) (xy 123.273576 -237.384865) (xy 123.274074 -237.411514)
			(xy 123.273576 -237.438163) (xy 123.502156 -237.438163) (xy 123.502156 -237.384865) (xy 123.510099 -237.332161)
			(xy 123.525809 -237.281231) (xy 123.548935 -237.23321) (xy 123.578959 -237.189173) (xy 123.615211 -237.150102)
			(xy 123.656882 -237.116871) (xy 123.70304 -237.090222) (xy 123.752654 -237.07075) (xy 123.804616 -237.05889)
			(xy 123.857766 -237.054907) (xy 123.910916 -237.05889) (xy 123.962878 -237.07075) (xy 124.012492 -237.090222)
			(xy 124.05865 -237.116871) (xy 124.100321 -237.150102) (xy 124.136573 -237.189173) (xy 124.166597 -237.23321)
			(xy 124.189723 -237.281231) (xy 124.205433 -237.332161) (xy 124.213376 -237.384865) (xy 124.213874 -237.411514)
			(xy 124.213376 -237.438163) (xy 124.441956 -237.438163) (xy 124.441956 -237.384865) (xy 124.449899 -237.332161)
			(xy 124.465609 -237.281231) (xy 124.488735 -237.23321) (xy 124.518759 -237.189173) (xy 124.555011 -237.150102)
			(xy 124.596682 -237.116871) (xy 124.64284 -237.090222) (xy 124.692454 -237.07075) (xy 124.744416 -237.05889)
			(xy 124.797566 -237.054907) (xy 124.850716 -237.05889) (xy 124.902678 -237.07075) (xy 124.952292 -237.090222)
			(xy 124.99845 -237.116871) (xy 125.040121 -237.150102) (xy 125.076373 -237.189173) (xy 125.106397 -237.23321)
			(xy 125.129523 -237.281231) (xy 125.145233 -237.332161) (xy 125.153176 -237.384865) (xy 125.153674 -237.411514)
			(xy 125.153176 -237.438163) (xy 125.381756 -237.438163) (xy 125.381756 -237.384865) (xy 125.389699 -237.332161)
			(xy 125.405409 -237.281231) (xy 125.428535 -237.23321) (xy 125.458559 -237.189173) (xy 125.494811 -237.150102)
			(xy 125.536482 -237.116871) (xy 125.58264 -237.090222) (xy 125.632254 -237.07075) (xy 125.684216 -237.05889)
			(xy 125.737366 -237.054907) (xy 125.790516 -237.05889) (xy 125.842478 -237.07075) (xy 125.892092 -237.090222)
			(xy 125.93825 -237.116871) (xy 125.979921 -237.150102) (xy 126.016173 -237.189173) (xy 126.046197 -237.23321)
			(xy 126.069323 -237.281231) (xy 126.085033 -237.332161) (xy 126.092976 -237.384865) (xy 126.093474 -237.411514)
			(xy 126.092976 -237.438163) (xy 126.321556 -237.438163) (xy 126.321556 -237.384865) (xy 126.329499 -237.332161)
			(xy 126.345209 -237.281231) (xy 126.368335 -237.23321) (xy 126.398359 -237.189173) (xy 126.434611 -237.150102)
			(xy 126.476282 -237.116871) (xy 126.52244 -237.090222) (xy 126.572054 -237.07075) (xy 126.624016 -237.05889)
			(xy 126.677166 -237.054907) (xy 126.730316 -237.05889) (xy 126.782278 -237.07075) (xy 126.831892 -237.090222)
			(xy 126.87805 -237.116871) (xy 126.919721 -237.150102) (xy 126.955973 -237.189173) (xy 126.985997 -237.23321)
			(xy 127.009123 -237.281231) (xy 127.024833 -237.332161) (xy 127.032776 -237.384865) (xy 127.033274 -237.411514)
			(xy 127.032776 -237.438163) (xy 127.261356 -237.438163) (xy 127.261356 -237.384865) (xy 127.269299 -237.332161)
			(xy 127.285009 -237.281231) (xy 127.308135 -237.23321) (xy 127.338159 -237.189173) (xy 127.374411 -237.150102)
			(xy 127.416082 -237.116871) (xy 127.46224 -237.090222) (xy 127.511854 -237.07075) (xy 127.563816 -237.05889)
			(xy 127.616966 -237.054907) (xy 127.670116 -237.05889) (xy 127.722078 -237.07075) (xy 127.771692 -237.090222)
			(xy 127.81785 -237.116871) (xy 127.859521 -237.150102) (xy 127.895773 -237.189173) (xy 127.925797 -237.23321)
			(xy 127.948923 -237.281231) (xy 127.964633 -237.332161) (xy 127.972576 -237.384865) (xy 127.973074 -237.411514)
			(xy 127.972576 -237.438163) (xy 128.201156 -237.438163) (xy 128.201156 -237.384865) (xy 128.209099 -237.332161)
			(xy 128.224809 -237.281231) (xy 128.247935 -237.23321) (xy 128.277959 -237.189173) (xy 128.314211 -237.150102)
			(xy 128.355882 -237.116871) (xy 128.40204 -237.090222) (xy 128.451654 -237.07075) (xy 128.503616 -237.05889)
			(xy 128.556766 -237.054907) (xy 128.609916 -237.05889) (xy 128.661878 -237.07075) (xy 128.711492 -237.090222)
			(xy 128.75765 -237.116871) (xy 128.799321 -237.150102) (xy 128.835573 -237.189173) (xy 128.865597 -237.23321)
			(xy 128.888723 -237.281231) (xy 128.904433 -237.332161) (xy 128.912376 -237.384865) (xy 128.912874 -237.411514)
			(xy 128.912376 -237.438163) (xy 129.140956 -237.438163) (xy 129.140956 -237.384865) (xy 129.148899 -237.332161)
			(xy 129.164609 -237.281231) (xy 129.187735 -237.23321) (xy 129.217759 -237.189173) (xy 129.254011 -237.150102)
			(xy 129.295682 -237.116871) (xy 129.34184 -237.090222) (xy 129.391454 -237.07075) (xy 129.443416 -237.05889)
			(xy 129.496566 -237.054907) (xy 129.549716 -237.05889) (xy 129.601678 -237.07075) (xy 129.651292 -237.090222)
			(xy 129.69745 -237.116871) (xy 129.739121 -237.150102) (xy 129.775373 -237.189173) (xy 129.805397 -237.23321)
			(xy 129.828523 -237.281231) (xy 129.844233 -237.332161) (xy 129.852176 -237.384865) (xy 129.852674 -237.411514)
			(xy 129.852176 -237.438163) (xy 130.080756 -237.438163) (xy 130.080756 -237.384865) (xy 130.088699 -237.332161)
			(xy 130.104409 -237.281231) (xy 130.127535 -237.23321) (xy 130.157559 -237.189173) (xy 130.193811 -237.150102)
			(xy 130.235482 -237.116871) (xy 130.28164 -237.090222) (xy 130.331254 -237.07075) (xy 130.383216 -237.05889)
			(xy 130.436366 -237.054907) (xy 130.489516 -237.05889) (xy 130.541478 -237.07075) (xy 130.591092 -237.090222)
			(xy 130.63725 -237.116871) (xy 130.678921 -237.150102) (xy 130.715173 -237.189173) (xy 130.745197 -237.23321)
			(xy 130.768323 -237.281231) (xy 130.784033 -237.332161) (xy 130.791976 -237.384865) (xy 130.792474 -237.411514)
			(xy 130.791976 -237.438163) (xy 131.020556 -237.438163) (xy 131.020556 -237.384865) (xy 131.028499 -237.332161)
			(xy 131.044209 -237.281231) (xy 131.067335 -237.23321) (xy 131.097359 -237.189173) (xy 131.133611 -237.150102)
			(xy 131.175282 -237.116871) (xy 131.22144 -237.090222) (xy 131.271054 -237.07075) (xy 131.323016 -237.05889)
			(xy 131.376166 -237.054907) (xy 131.429316 -237.05889) (xy 131.481278 -237.07075) (xy 131.530892 -237.090222)
			(xy 131.57705 -237.116871) (xy 131.618721 -237.150102) (xy 131.654973 -237.189173) (xy 131.684997 -237.23321)
			(xy 131.708123 -237.281231) (xy 131.723833 -237.332161) (xy 131.731776 -237.384865) (xy 131.732274 -237.411514)
			(xy 131.731776 -237.438163) (xy 131.960356 -237.438163) (xy 131.960356 -237.384865) (xy 131.968299 -237.332161)
			(xy 131.984009 -237.281231) (xy 132.007135 -237.23321) (xy 132.037159 -237.189173) (xy 132.073411 -237.150102)
			(xy 132.115082 -237.116871) (xy 132.16124 -237.090222) (xy 132.210854 -237.07075) (xy 132.262816 -237.05889)
			(xy 132.315966 -237.054907) (xy 132.369116 -237.05889) (xy 132.421078 -237.07075) (xy 132.470692 -237.090222)
			(xy 132.51685 -237.116871) (xy 132.558521 -237.150102) (xy 132.594773 -237.189173) (xy 132.624797 -237.23321)
			(xy 132.647923 -237.281231) (xy 132.663633 -237.332161) (xy 132.671576 -237.384865) (xy 132.672074 -237.411514)
			(xy 132.671576 -237.438163) (xy 132.899902 -237.438163) (xy 132.899902 -237.384865) (xy 132.907845 -237.332161)
			(xy 132.923555 -237.281231) (xy 132.946681 -237.23321) (xy 132.976705 -237.189173) (xy 133.012957 -237.150102)
			(xy 133.054628 -237.116871) (xy 133.100786 -237.090222) (xy 133.1504 -237.07075) (xy 133.202362 -237.05889)
			(xy 133.255512 -237.054907) (xy 133.308662 -237.05889) (xy 133.360624 -237.07075) (xy 133.410238 -237.090222)
			(xy 133.456396 -237.116871) (xy 133.498067 -237.150102) (xy 133.534319 -237.189173) (xy 133.564343 -237.23321)
			(xy 133.587469 -237.281231) (xy 133.603179 -237.332161) (xy 133.611122 -237.384865) (xy 133.61162 -237.411514)
			(xy 133.611122 -237.438163) (xy 133.839956 -237.438163) (xy 133.839956 -237.384865) (xy 133.847899 -237.332161)
			(xy 133.863609 -237.281231) (xy 133.886735 -237.23321) (xy 133.916759 -237.189173) (xy 133.953011 -237.150102)
			(xy 133.994682 -237.116871) (xy 134.04084 -237.090222) (xy 134.090454 -237.07075) (xy 134.142416 -237.05889)
			(xy 134.195566 -237.054907) (xy 134.248716 -237.05889) (xy 134.300678 -237.07075) (xy 134.350292 -237.090222)
			(xy 134.39645 -237.116871) (xy 134.438121 -237.150102) (xy 134.474373 -237.189173) (xy 134.504397 -237.23321)
			(xy 134.527523 -237.281231) (xy 134.543233 -237.332161) (xy 134.551176 -237.384865) (xy 134.551674 -237.411514)
			(xy 134.551176 -237.438163) (xy 134.543233 -237.490867) (xy 134.527523 -237.541797) (xy 134.504397 -237.589818)
			(xy 134.474373 -237.633855) (xy 134.438121 -237.672926) (xy 134.39645 -237.706157) (xy 134.350292 -237.732806)
			(xy 134.300678 -237.752278) (xy 134.248716 -237.764138) (xy 134.195566 -237.768122) (xy 134.142416 -237.764138)
			(xy 134.090454 -237.752278) (xy 134.04084 -237.732806) (xy 133.994682 -237.706157) (xy 133.953011 -237.672926)
			(xy 133.916759 -237.633855) (xy 133.886735 -237.589818) (xy 133.863609 -237.541797) (xy 133.847899 -237.490867)
			(xy 133.839956 -237.438163) (xy 133.611122 -237.438163) (xy 133.603179 -237.490867) (xy 133.587469 -237.541797)
			(xy 133.564343 -237.589818) (xy 133.534319 -237.633855) (xy 133.498067 -237.672926) (xy 133.456396 -237.706157)
			(xy 133.410238 -237.732806) (xy 133.360624 -237.752278) (xy 133.308662 -237.764138) (xy 133.255512 -237.768122)
			(xy 133.202362 -237.764138) (xy 133.1504 -237.752278) (xy 133.100786 -237.732806) (xy 133.054628 -237.706157)
			(xy 133.012957 -237.672926) (xy 132.976705 -237.633855) (xy 132.946681 -237.589818) (xy 132.923555 -237.541797)
			(xy 132.907845 -237.490867) (xy 132.899902 -237.438163) (xy 132.671576 -237.438163) (xy 132.663633 -237.490867)
			(xy 132.647923 -237.541797) (xy 132.624797 -237.589818) (xy 132.594773 -237.633855) (xy 132.558521 -237.672926)
			(xy 132.51685 -237.706157) (xy 132.470692 -237.732806) (xy 132.421078 -237.752278) (xy 132.369116 -237.764138)
			(xy 132.315966 -237.768122) (xy 132.262816 -237.764138) (xy 132.210854 -237.752278) (xy 132.16124 -237.732806)
			(xy 132.115082 -237.706157) (xy 132.073411 -237.672926) (xy 132.037159 -237.633855) (xy 132.007135 -237.589818)
			(xy 131.984009 -237.541797) (xy 131.968299 -237.490867) (xy 131.960356 -237.438163) (xy 131.731776 -237.438163)
			(xy 131.723833 -237.490867) (xy 131.708123 -237.541797) (xy 131.684997 -237.589818) (xy 131.654973 -237.633855)
			(xy 131.618721 -237.672926) (xy 131.57705 -237.706157) (xy 131.530892 -237.732806) (xy 131.481278 -237.752278)
			(xy 131.429316 -237.764138) (xy 131.376166 -237.768122) (xy 131.323016 -237.764138) (xy 131.271054 -237.752278)
			(xy 131.22144 -237.732806) (xy 131.175282 -237.706157) (xy 131.133611 -237.672926) (xy 131.097359 -237.633855)
			(xy 131.067335 -237.589818) (xy 131.044209 -237.541797) (xy 131.028499 -237.490867) (xy 131.020556 -237.438163)
			(xy 130.791976 -237.438163) (xy 130.784033 -237.490867) (xy 130.768323 -237.541797) (xy 130.745197 -237.589818)
			(xy 130.715173 -237.633855) (xy 130.678921 -237.672926) (xy 130.63725 -237.706157) (xy 130.591092 -237.732806)
			(xy 130.541478 -237.752278) (xy 130.489516 -237.764138) (xy 130.436366 -237.768122) (xy 130.383216 -237.764138)
			(xy 130.331254 -237.752278) (xy 130.28164 -237.732806) (xy 130.235482 -237.706157) (xy 130.193811 -237.672926)
			(xy 130.157559 -237.633855) (xy 130.127535 -237.589818) (xy 130.104409 -237.541797) (xy 130.088699 -237.490867)
			(xy 130.080756 -237.438163) (xy 129.852176 -237.438163) (xy 129.844233 -237.490867) (xy 129.828523 -237.541797)
			(xy 129.805397 -237.589818) (xy 129.775373 -237.633855) (xy 129.739121 -237.672926) (xy 129.69745 -237.706157)
			(xy 129.651292 -237.732806) (xy 129.601678 -237.752278) (xy 129.549716 -237.764138) (xy 129.496566 -237.768122)
			(xy 129.443416 -237.764138) (xy 129.391454 -237.752278) (xy 129.34184 -237.732806) (xy 129.295682 -237.706157)
			(xy 129.254011 -237.672926) (xy 129.217759 -237.633855) (xy 129.187735 -237.589818) (xy 129.164609 -237.541797)
			(xy 129.148899 -237.490867) (xy 129.140956 -237.438163) (xy 128.912376 -237.438163) (xy 128.904433 -237.490867)
			(xy 128.888723 -237.541797) (xy 128.865597 -237.589818) (xy 128.835573 -237.633855) (xy 128.799321 -237.672926)
			(xy 128.75765 -237.706157) (xy 128.711492 -237.732806) (xy 128.661878 -237.752278) (xy 128.609916 -237.764138)
			(xy 128.556766 -237.768122) (xy 128.503616 -237.764138) (xy 128.451654 -237.752278) (xy 128.40204 -237.732806)
			(xy 128.355882 -237.706157) (xy 128.314211 -237.672926) (xy 128.277959 -237.633855) (xy 128.247935 -237.589818)
			(xy 128.224809 -237.541797) (xy 128.209099 -237.490867) (xy 128.201156 -237.438163) (xy 127.972576 -237.438163)
			(xy 127.964633 -237.490867) (xy 127.948923 -237.541797) (xy 127.925797 -237.589818) (xy 127.895773 -237.633855)
			(xy 127.859521 -237.672926) (xy 127.81785 -237.706157) (xy 127.771692 -237.732806) (xy 127.722078 -237.752278)
			(xy 127.670116 -237.764138) (xy 127.616966 -237.768122) (xy 127.563816 -237.764138) (xy 127.511854 -237.752278)
			(xy 127.46224 -237.732806) (xy 127.416082 -237.706157) (xy 127.374411 -237.672926) (xy 127.338159 -237.633855)
			(xy 127.308135 -237.589818) (xy 127.285009 -237.541797) (xy 127.269299 -237.490867) (xy 127.261356 -237.438163)
			(xy 127.032776 -237.438163) (xy 127.024833 -237.490867) (xy 127.009123 -237.541797) (xy 126.985997 -237.589818)
			(xy 126.955973 -237.633855) (xy 126.919721 -237.672926) (xy 126.87805 -237.706157) (xy 126.831892 -237.732806)
			(xy 126.782278 -237.752278) (xy 126.730316 -237.764138) (xy 126.677166 -237.768122) (xy 126.624016 -237.764138)
			(xy 126.572054 -237.752278) (xy 126.52244 -237.732806) (xy 126.476282 -237.706157) (xy 126.434611 -237.672926)
			(xy 126.398359 -237.633855) (xy 126.368335 -237.589818) (xy 126.345209 -237.541797) (xy 126.329499 -237.490867)
			(xy 126.321556 -237.438163) (xy 126.092976 -237.438163) (xy 126.085033 -237.490867) (xy 126.069323 -237.541797)
			(xy 126.046197 -237.589818) (xy 126.016173 -237.633855) (xy 125.979921 -237.672926) (xy 125.93825 -237.706157)
			(xy 125.892092 -237.732806) (xy 125.842478 -237.752278) (xy 125.790516 -237.764138) (xy 125.737366 -237.768122)
			(xy 125.684216 -237.764138) (xy 125.632254 -237.752278) (xy 125.58264 -237.732806) (xy 125.536482 -237.706157)
			(xy 125.494811 -237.672926) (xy 125.458559 -237.633855) (xy 125.428535 -237.589818) (xy 125.405409 -237.541797)
			(xy 125.389699 -237.490867) (xy 125.381756 -237.438163) (xy 125.153176 -237.438163) (xy 125.145233 -237.490867)
			(xy 125.129523 -237.541797) (xy 125.106397 -237.589818) (xy 125.076373 -237.633855) (xy 125.040121 -237.672926)
			(xy 124.99845 -237.706157) (xy 124.952292 -237.732806) (xy 124.902678 -237.752278) (xy 124.850716 -237.764138)
			(xy 124.797566 -237.768122) (xy 124.744416 -237.764138) (xy 124.692454 -237.752278) (xy 124.64284 -237.732806)
			(xy 124.596682 -237.706157) (xy 124.555011 -237.672926) (xy 124.518759 -237.633855) (xy 124.488735 -237.589818)
			(xy 124.465609 -237.541797) (xy 124.449899 -237.490867) (xy 124.441956 -237.438163) (xy 124.213376 -237.438163)
			(xy 124.205433 -237.490867) (xy 124.189723 -237.541797) (xy 124.166597 -237.589818) (xy 124.136573 -237.633855)
			(xy 124.100321 -237.672926) (xy 124.05865 -237.706157) (xy 124.012492 -237.732806) (xy 123.962878 -237.752278)
			(xy 123.910916 -237.764138) (xy 123.857766 -237.768122) (xy 123.804616 -237.764138) (xy 123.752654 -237.752278)
			(xy 123.70304 -237.732806) (xy 123.656882 -237.706157) (xy 123.615211 -237.672926) (xy 123.578959 -237.633855)
			(xy 123.548935 -237.589818) (xy 123.525809 -237.541797) (xy 123.510099 -237.490867) (xy 123.502156 -237.438163)
			(xy 123.273576 -237.438163) (xy 123.265633 -237.490867) (xy 123.249923 -237.541797) (xy 123.226797 -237.589818)
			(xy 123.196773 -237.633855) (xy 123.160521 -237.672926) (xy 123.11885 -237.706157) (xy 123.072692 -237.732806)
			(xy 123.023078 -237.752278) (xy 122.971116 -237.764138) (xy 122.917966 -237.768122) (xy 122.864816 -237.764138)
			(xy 122.812854 -237.752278) (xy 122.76324 -237.732806) (xy 122.717082 -237.706157) (xy 122.675411 -237.672926)
			(xy 122.639159 -237.633855) (xy 122.609135 -237.589818) (xy 122.586009 -237.541797) (xy 122.570299 -237.490867)
			(xy 122.562356 -237.438163) (xy 122.333776 -237.438163) (xy 122.325833 -237.490867) (xy 122.310123 -237.541797)
			(xy 122.286997 -237.589818) (xy 122.256973 -237.633855) (xy 122.220721 -237.672926) (xy 122.17905 -237.706157)
			(xy 122.132892 -237.732806) (xy 122.083278 -237.752278) (xy 122.031316 -237.764138) (xy 121.978166 -237.768122)
			(xy 121.925016 -237.764138) (xy 121.873054 -237.752278) (xy 121.82344 -237.732806) (xy 121.777282 -237.706157)
			(xy 121.735611 -237.672926) (xy 121.699359 -237.633855) (xy 121.669335 -237.589818) (xy 121.646209 -237.541797)
			(xy 121.630499 -237.490867) (xy 121.622556 -237.438163) (xy 121.332161 -237.438163) (xy 121.331963 -237.448582)
			(xy 121.323088 -237.504234) (xy 121.305561 -237.557795) (xy 121.279819 -237.607927) (xy 121.246504 -237.653381)
			(xy 121.206447 -237.693021) (xy 121.160648 -237.72586) (xy 121.11025 -237.751078) (xy 121.056509 -237.768045)
			(xy 121.028714 -237.772702) (xy 120.98528 -237.779052) (xy 120.98528 -238.252233) (xy 121.152402 -238.252233)
			(xy 121.152402 -238.198935) (xy 121.160345 -238.146231) (xy 121.176055 -238.095301) (xy 121.199181 -238.04728)
			(xy 121.229205 -238.003243) (xy 121.265457 -237.964172) (xy 121.307128 -237.930941) (xy 121.353286 -237.904292)
			(xy 121.4029 -237.88482) (xy 121.454862 -237.87296) (xy 121.508012 -237.868977) (xy 121.561162 -237.87296)
			(xy 121.613124 -237.88482) (xy 121.662738 -237.904292) (xy 121.708896 -237.930941) (xy 121.750567 -237.964172)
			(xy 121.786819 -238.003243) (xy 121.816843 -238.04728) (xy 121.839969 -238.095301) (xy 121.855679 -238.146231)
			(xy 121.863622 -238.198935) (xy 121.86412 -238.225584) (xy 121.863622 -238.252233) (xy 122.092202 -238.252233)
			(xy 122.092202 -238.198935) (xy 122.100145 -238.146231) (xy 122.115855 -238.095301) (xy 122.138981 -238.04728)
			(xy 122.169005 -238.003243) (xy 122.205257 -237.964172) (xy 122.246928 -237.930941) (xy 122.293086 -237.904292)
			(xy 122.3427 -237.88482) (xy 122.394662 -237.87296) (xy 122.447812 -237.868977) (xy 122.500962 -237.87296)
			(xy 122.552924 -237.88482) (xy 122.602538 -237.904292) (xy 122.648696 -237.930941) (xy 122.690367 -237.964172)
			(xy 122.726619 -238.003243) (xy 122.756643 -238.04728) (xy 122.779769 -238.095301) (xy 122.795479 -238.146231)
			(xy 122.803422 -238.198935) (xy 122.80392 -238.225584) (xy 122.803422 -238.252233) (xy 123.032002 -238.252233)
			(xy 123.032002 -238.198935) (xy 123.039945 -238.146231) (xy 123.055655 -238.095301) (xy 123.078781 -238.04728)
			(xy 123.108805 -238.003243) (xy 123.145057 -237.964172) (xy 123.186728 -237.930941) (xy 123.232886 -237.904292)
			(xy 123.2825 -237.88482) (xy 123.334462 -237.87296) (xy 123.387612 -237.868977) (xy 123.440762 -237.87296)
			(xy 123.492724 -237.88482) (xy 123.542338 -237.904292) (xy 123.588496 -237.930941) (xy 123.630167 -237.964172)
			(xy 123.666419 -238.003243) (xy 123.696443 -238.04728) (xy 123.719569 -238.095301) (xy 123.735279 -238.146231)
			(xy 123.743222 -238.198935) (xy 123.74372 -238.225584) (xy 123.743222 -238.252233) (xy 123.971802 -238.252233)
			(xy 123.971802 -238.198935) (xy 123.979745 -238.146231) (xy 123.995455 -238.095301) (xy 124.018581 -238.04728)
			(xy 124.048605 -238.003243) (xy 124.084857 -237.964172) (xy 124.126528 -237.930941) (xy 124.172686 -237.904292)
			(xy 124.2223 -237.88482) (xy 124.274262 -237.87296) (xy 124.327412 -237.868977) (xy 124.380562 -237.87296)
			(xy 124.432524 -237.88482) (xy 124.482138 -237.904292) (xy 124.528296 -237.930941) (xy 124.569967 -237.964172)
			(xy 124.606219 -238.003243) (xy 124.636243 -238.04728) (xy 124.659369 -238.095301) (xy 124.675079 -238.146231)
			(xy 124.683022 -238.198935) (xy 124.68352 -238.225584) (xy 124.683022 -238.252233) (xy 124.911602 -238.252233)
			(xy 124.911602 -238.198935) (xy 124.919545 -238.146231) (xy 124.935255 -238.095301) (xy 124.958381 -238.04728)
			(xy 124.988405 -238.003243) (xy 125.024657 -237.964172) (xy 125.066328 -237.930941) (xy 125.112486 -237.904292)
			(xy 125.1621 -237.88482) (xy 125.214062 -237.87296) (xy 125.267212 -237.868977) (xy 125.320362 -237.87296)
			(xy 125.372324 -237.88482) (xy 125.421938 -237.904292) (xy 125.468096 -237.930941) (xy 125.509767 -237.964172)
			(xy 125.546019 -238.003243) (xy 125.576043 -238.04728) (xy 125.599169 -238.095301) (xy 125.614879 -238.146231)
			(xy 125.622822 -238.198935) (xy 125.62332 -238.225584) (xy 125.622822 -238.252233) (xy 125.851656 -238.252233)
			(xy 125.851656 -238.198935) (xy 125.859599 -238.146231) (xy 125.875309 -238.095301) (xy 125.898435 -238.04728)
			(xy 125.928459 -238.003243) (xy 125.964711 -237.964172) (xy 126.006382 -237.930941) (xy 126.05254 -237.904292)
			(xy 126.102154 -237.88482) (xy 126.154116 -237.87296) (xy 126.207266 -237.868977) (xy 126.260416 -237.87296)
			(xy 126.312378 -237.88482) (xy 126.361992 -237.904292) (xy 126.40815 -237.930941) (xy 126.449821 -237.964172)
			(xy 126.486073 -238.003243) (xy 126.516097 -238.04728) (xy 126.539223 -238.095301) (xy 126.554933 -238.146231)
			(xy 126.562876 -238.198935) (xy 126.563374 -238.225584) (xy 126.562876 -238.252233) (xy 126.791202 -238.252233)
			(xy 126.791202 -238.198935) (xy 126.799145 -238.146231) (xy 126.814855 -238.095301) (xy 126.837981 -238.04728)
			(xy 126.868005 -238.003243) (xy 126.904257 -237.964172) (xy 126.945928 -237.930941) (xy 126.992086 -237.904292)
			(xy 127.0417 -237.88482) (xy 127.093662 -237.87296) (xy 127.146812 -237.868977) (xy 127.199962 -237.87296)
			(xy 127.251924 -237.88482) (xy 127.301538 -237.904292) (xy 127.347696 -237.930941) (xy 127.389367 -237.964172)
			(xy 127.425619 -238.003243) (xy 127.455643 -238.04728) (xy 127.478769 -238.095301) (xy 127.494479 -238.146231)
			(xy 127.502422 -238.198935) (xy 127.50292 -238.225584) (xy 127.502422 -238.252233) (xy 127.731002 -238.252233)
			(xy 127.731002 -238.198935) (xy 127.738945 -238.146231) (xy 127.754655 -238.095301) (xy 127.777781 -238.04728)
			(xy 127.807805 -238.003243) (xy 127.844057 -237.964172) (xy 127.885728 -237.930941) (xy 127.931886 -237.904292)
			(xy 127.9815 -237.88482) (xy 128.033462 -237.87296) (xy 128.086612 -237.868977) (xy 128.139762 -237.87296)
			(xy 128.191724 -237.88482) (xy 128.241338 -237.904292) (xy 128.287496 -237.930941) (xy 128.329167 -237.964172)
			(xy 128.365419 -238.003243) (xy 128.395443 -238.04728) (xy 128.418569 -238.095301) (xy 128.434279 -238.146231)
			(xy 128.442222 -238.198935) (xy 128.44272 -238.225584) (xy 128.442222 -238.252233) (xy 128.670802 -238.252233)
			(xy 128.670802 -238.198935) (xy 128.678745 -238.146231) (xy 128.694455 -238.095301) (xy 128.717581 -238.04728)
			(xy 128.747605 -238.003243) (xy 128.783857 -237.964172) (xy 128.825528 -237.930941) (xy 128.871686 -237.904292)
			(xy 128.9213 -237.88482) (xy 128.973262 -237.87296) (xy 129.026412 -237.868977) (xy 129.079562 -237.87296)
			(xy 129.131524 -237.88482) (xy 129.181138 -237.904292) (xy 129.227296 -237.930941) (xy 129.268967 -237.964172)
			(xy 129.305219 -238.003243) (xy 129.335243 -238.04728) (xy 129.358369 -238.095301) (xy 129.374079 -238.146231)
			(xy 129.382022 -238.198935) (xy 129.38252 -238.225584) (xy 129.382022 -238.252233) (xy 129.610602 -238.252233)
			(xy 129.610602 -238.198935) (xy 129.618545 -238.146231) (xy 129.634255 -238.095301) (xy 129.657381 -238.04728)
			(xy 129.687405 -238.003243) (xy 129.723657 -237.964172) (xy 129.765328 -237.930941) (xy 129.811486 -237.904292)
			(xy 129.8611 -237.88482) (xy 129.913062 -237.87296) (xy 129.966212 -237.868977) (xy 130.019362 -237.87296)
			(xy 130.071324 -237.88482) (xy 130.120938 -237.904292) (xy 130.167096 -237.930941) (xy 130.208767 -237.964172)
			(xy 130.245019 -238.003243) (xy 130.275043 -238.04728) (xy 130.298169 -238.095301) (xy 130.313879 -238.146231)
			(xy 130.321822 -238.198935) (xy 130.32232 -238.225584) (xy 130.321822 -238.252233) (xy 130.550402 -238.252233)
			(xy 130.550402 -238.198935) (xy 130.558345 -238.146231) (xy 130.574055 -238.095301) (xy 130.597181 -238.04728)
			(xy 130.627205 -238.003243) (xy 130.663457 -237.964172) (xy 130.705128 -237.930941) (xy 130.751286 -237.904292)
			(xy 130.8009 -237.88482) (xy 130.852862 -237.87296) (xy 130.906012 -237.868977) (xy 130.959162 -237.87296)
			(xy 131.011124 -237.88482) (xy 131.060738 -237.904292) (xy 131.106896 -237.930941) (xy 131.148567 -237.964172)
			(xy 131.184819 -238.003243) (xy 131.214843 -238.04728) (xy 131.237969 -238.095301) (xy 131.253679 -238.146231)
			(xy 131.261622 -238.198935) (xy 131.26212 -238.225584) (xy 131.261622 -238.252233) (xy 131.490202 -238.252233)
			(xy 131.490202 -238.198935) (xy 131.498145 -238.146231) (xy 131.513855 -238.095301) (xy 131.536981 -238.04728)
			(xy 131.567005 -238.003243) (xy 131.603257 -237.964172) (xy 131.644928 -237.930941) (xy 131.691086 -237.904292)
			(xy 131.7407 -237.88482) (xy 131.792662 -237.87296) (xy 131.845812 -237.868977) (xy 131.898962 -237.87296)
			(xy 131.950924 -237.88482) (xy 132.000538 -237.904292) (xy 132.046696 -237.930941) (xy 132.088367 -237.964172)
			(xy 132.124619 -238.003243) (xy 132.154643 -238.04728) (xy 132.177769 -238.095301) (xy 132.193479 -238.146231)
			(xy 132.201422 -238.198935) (xy 132.20192 -238.225584) (xy 132.201422 -238.252233) (xy 132.430256 -238.252233)
			(xy 132.430256 -238.198935) (xy 132.438199 -238.146231) (xy 132.453909 -238.095301) (xy 132.477035 -238.04728)
			(xy 132.507059 -238.003243) (xy 132.543311 -237.964172) (xy 132.584982 -237.930941) (xy 132.63114 -237.904292)
			(xy 132.680754 -237.88482) (xy 132.732716 -237.87296) (xy 132.785866 -237.868977) (xy 132.839016 -237.87296)
			(xy 132.890978 -237.88482) (xy 132.940592 -237.904292) (xy 132.98675 -237.930941) (xy 133.028421 -237.964172)
			(xy 133.064673 -238.003243) (xy 133.094697 -238.04728) (xy 133.117823 -238.095301) (xy 133.133533 -238.146231)
			(xy 133.141476 -238.198935) (xy 133.141974 -238.225584) (xy 133.141476 -238.252233) (xy 133.370056 -238.252233)
			(xy 133.370056 -238.198935) (xy 133.377999 -238.146231) (xy 133.393709 -238.095301) (xy 133.416835 -238.04728)
			(xy 133.446859 -238.003243) (xy 133.483111 -237.964172) (xy 133.524782 -237.930941) (xy 133.57094 -237.904292)
			(xy 133.620554 -237.88482) (xy 133.672516 -237.87296) (xy 133.725666 -237.868977) (xy 133.778816 -237.87296)
			(xy 133.830778 -237.88482) (xy 133.880392 -237.904292) (xy 133.92655 -237.930941) (xy 133.968221 -237.964172)
			(xy 134.004473 -238.003243) (xy 134.034497 -238.04728) (xy 134.057623 -238.095301) (xy 134.073333 -238.146231)
			(xy 134.081276 -238.198935) (xy 134.081774 -238.225584) (xy 134.081276 -238.252233) (xy 134.309856 -238.252233)
			(xy 134.309856 -238.198935) (xy 134.317799 -238.146231) (xy 134.333509 -238.095301) (xy 134.356635 -238.04728)
			(xy 134.386659 -238.003243) (xy 134.422911 -237.964172) (xy 134.464582 -237.930941) (xy 134.51074 -237.904292)
			(xy 134.560354 -237.88482) (xy 134.612316 -237.87296) (xy 134.665466 -237.868977) (xy 134.718616 -237.87296)
			(xy 134.770578 -237.88482) (xy 134.820192 -237.904292) (xy 134.86635 -237.930941) (xy 134.908021 -237.964172)
			(xy 134.944273 -238.003243) (xy 134.974297 -238.04728) (xy 134.997423 -238.095301) (xy 135.013133 -238.146231)
			(xy 135.021076 -238.198935) (xy 135.021574 -238.225584) (xy 135.021076 -238.252233) (xy 135.013133 -238.304937)
			(xy 134.997423 -238.355867) (xy 134.974297 -238.403888) (xy 134.944273 -238.447925) (xy 134.908021 -238.486996)
			(xy 134.86635 -238.520227) (xy 134.820192 -238.546876) (xy 134.770578 -238.566348) (xy 134.718616 -238.578208)
			(xy 134.665466 -238.582192) (xy 134.612316 -238.578208) (xy 134.560354 -238.566348) (xy 134.51074 -238.546876)
			(xy 134.464582 -238.520227) (xy 134.422911 -238.486996) (xy 134.386659 -238.447925) (xy 134.356635 -238.403888)
			(xy 134.333509 -238.355867) (xy 134.317799 -238.304937) (xy 134.309856 -238.252233) (xy 134.081276 -238.252233)
			(xy 134.073333 -238.304937) (xy 134.057623 -238.355867) (xy 134.034497 -238.403888) (xy 134.004473 -238.447925)
			(xy 133.968221 -238.486996) (xy 133.92655 -238.520227) (xy 133.880392 -238.546876) (xy 133.830778 -238.566348)
			(xy 133.778816 -238.578208) (xy 133.725666 -238.582192) (xy 133.672516 -238.578208) (xy 133.620554 -238.566348)
			(xy 133.57094 -238.546876) (xy 133.524782 -238.520227) (xy 133.483111 -238.486996) (xy 133.446859 -238.447925)
			(xy 133.416835 -238.403888) (xy 133.393709 -238.355867) (xy 133.377999 -238.304937) (xy 133.370056 -238.252233)
			(xy 133.141476 -238.252233) (xy 133.133533 -238.304937) (xy 133.117823 -238.355867) (xy 133.094697 -238.403888)
			(xy 133.064673 -238.447925) (xy 133.028421 -238.486996) (xy 132.98675 -238.520227) (xy 132.940592 -238.546876)
			(xy 132.890978 -238.566348) (xy 132.839016 -238.578208) (xy 132.785866 -238.582192) (xy 132.732716 -238.578208)
			(xy 132.680754 -238.566348) (xy 132.63114 -238.546876) (xy 132.584982 -238.520227) (xy 132.543311 -238.486996)
			(xy 132.507059 -238.447925) (xy 132.477035 -238.403888) (xy 132.453909 -238.355867) (xy 132.438199 -238.304937)
			(xy 132.430256 -238.252233) (xy 132.201422 -238.252233) (xy 132.193479 -238.304937) (xy 132.177769 -238.355867)
			(xy 132.154643 -238.403888) (xy 132.124619 -238.447925) (xy 132.088367 -238.486996) (xy 132.046696 -238.520227)
			(xy 132.000538 -238.546876) (xy 131.950924 -238.566348) (xy 131.898962 -238.578208) (xy 131.845812 -238.582192)
			(xy 131.792662 -238.578208) (xy 131.7407 -238.566348) (xy 131.691086 -238.546876) (xy 131.644928 -238.520227)
			(xy 131.603257 -238.486996) (xy 131.567005 -238.447925) (xy 131.536981 -238.403888) (xy 131.513855 -238.355867)
			(xy 131.498145 -238.304937) (xy 131.490202 -238.252233) (xy 131.261622 -238.252233) (xy 131.253679 -238.304937)
			(xy 131.237969 -238.355867) (xy 131.214843 -238.403888) (xy 131.184819 -238.447925) (xy 131.148567 -238.486996)
			(xy 131.106896 -238.520227) (xy 131.060738 -238.546876) (xy 131.011124 -238.566348) (xy 130.959162 -238.578208)
			(xy 130.906012 -238.582192) (xy 130.852862 -238.578208) (xy 130.8009 -238.566348) (xy 130.751286 -238.546876)
			(xy 130.705128 -238.520227) (xy 130.663457 -238.486996) (xy 130.627205 -238.447925) (xy 130.597181 -238.403888)
			(xy 130.574055 -238.355867) (xy 130.558345 -238.304937) (xy 130.550402 -238.252233) (xy 130.321822 -238.252233)
			(xy 130.313879 -238.304937) (xy 130.298169 -238.355867) (xy 130.275043 -238.403888) (xy 130.245019 -238.447925)
			(xy 130.208767 -238.486996) (xy 130.167096 -238.520227) (xy 130.120938 -238.546876) (xy 130.071324 -238.566348)
			(xy 130.019362 -238.578208) (xy 129.966212 -238.582192) (xy 129.913062 -238.578208) (xy 129.8611 -238.566348)
			(xy 129.811486 -238.546876) (xy 129.765328 -238.520227) (xy 129.723657 -238.486996) (xy 129.687405 -238.447925)
			(xy 129.657381 -238.403888) (xy 129.634255 -238.355867) (xy 129.618545 -238.304937) (xy 129.610602 -238.252233)
			(xy 129.382022 -238.252233) (xy 129.374079 -238.304937) (xy 129.358369 -238.355867) (xy 129.335243 -238.403888)
			(xy 129.305219 -238.447925) (xy 129.268967 -238.486996) (xy 129.227296 -238.520227) (xy 129.181138 -238.546876)
			(xy 129.131524 -238.566348) (xy 129.079562 -238.578208) (xy 129.026412 -238.582192) (xy 128.973262 -238.578208)
			(xy 128.9213 -238.566348) (xy 128.871686 -238.546876) (xy 128.825528 -238.520227) (xy 128.783857 -238.486996)
			(xy 128.747605 -238.447925) (xy 128.717581 -238.403888) (xy 128.694455 -238.355867) (xy 128.678745 -238.304937)
			(xy 128.670802 -238.252233) (xy 128.442222 -238.252233) (xy 128.434279 -238.304937) (xy 128.418569 -238.355867)
			(xy 128.395443 -238.403888) (xy 128.365419 -238.447925) (xy 128.329167 -238.486996) (xy 128.287496 -238.520227)
			(xy 128.241338 -238.546876) (xy 128.191724 -238.566348) (xy 128.139762 -238.578208) (xy 128.086612 -238.582192)
			(xy 128.033462 -238.578208) (xy 127.9815 -238.566348) (xy 127.931886 -238.546876) (xy 127.885728 -238.520227)
			(xy 127.844057 -238.486996) (xy 127.807805 -238.447925) (xy 127.777781 -238.403888) (xy 127.754655 -238.355867)
			(xy 127.738945 -238.304937) (xy 127.731002 -238.252233) (xy 127.502422 -238.252233) (xy 127.494479 -238.304937)
			(xy 127.478769 -238.355867) (xy 127.455643 -238.403888) (xy 127.425619 -238.447925) (xy 127.389367 -238.486996)
			(xy 127.347696 -238.520227) (xy 127.301538 -238.546876) (xy 127.251924 -238.566348) (xy 127.199962 -238.578208)
			(xy 127.146812 -238.582192) (xy 127.093662 -238.578208) (xy 127.0417 -238.566348) (xy 126.992086 -238.546876)
			(xy 126.945928 -238.520227) (xy 126.904257 -238.486996) (xy 126.868005 -238.447925) (xy 126.837981 -238.403888)
			(xy 126.814855 -238.355867) (xy 126.799145 -238.304937) (xy 126.791202 -238.252233) (xy 126.562876 -238.252233)
			(xy 126.554933 -238.304937) (xy 126.539223 -238.355867) (xy 126.516097 -238.403888) (xy 126.486073 -238.447925)
			(xy 126.449821 -238.486996) (xy 126.40815 -238.520227) (xy 126.361992 -238.546876) (xy 126.312378 -238.566348)
			(xy 126.260416 -238.578208) (xy 126.207266 -238.582192) (xy 126.154116 -238.578208) (xy 126.102154 -238.566348)
			(xy 126.05254 -238.546876) (xy 126.006382 -238.520227) (xy 125.964711 -238.486996) (xy 125.928459 -238.447925)
			(xy 125.898435 -238.403888) (xy 125.875309 -238.355867) (xy 125.859599 -238.304937) (xy 125.851656 -238.252233)
			(xy 125.622822 -238.252233) (xy 125.614879 -238.304937) (xy 125.599169 -238.355867) (xy 125.576043 -238.403888)
			(xy 125.546019 -238.447925) (xy 125.509767 -238.486996) (xy 125.468096 -238.520227) (xy 125.421938 -238.546876)
			(xy 125.372324 -238.566348) (xy 125.320362 -238.578208) (xy 125.267212 -238.582192) (xy 125.214062 -238.578208)
			(xy 125.1621 -238.566348) (xy 125.112486 -238.546876) (xy 125.066328 -238.520227) (xy 125.024657 -238.486996)
			(xy 124.988405 -238.447925) (xy 124.958381 -238.403888) (xy 124.935255 -238.355867) (xy 124.919545 -238.304937)
			(xy 124.911602 -238.252233) (xy 124.683022 -238.252233) (xy 124.675079 -238.304937) (xy 124.659369 -238.355867)
			(xy 124.636243 -238.403888) (xy 124.606219 -238.447925) (xy 124.569967 -238.486996) (xy 124.528296 -238.520227)
			(xy 124.482138 -238.546876) (xy 124.432524 -238.566348) (xy 124.380562 -238.578208) (xy 124.327412 -238.582192)
			(xy 124.274262 -238.578208) (xy 124.2223 -238.566348) (xy 124.172686 -238.546876) (xy 124.126528 -238.520227)
			(xy 124.084857 -238.486996) (xy 124.048605 -238.447925) (xy 124.018581 -238.403888) (xy 123.995455 -238.355867)
			(xy 123.979745 -238.304937) (xy 123.971802 -238.252233) (xy 123.743222 -238.252233) (xy 123.735279 -238.304937)
			(xy 123.719569 -238.355867) (xy 123.696443 -238.403888) (xy 123.666419 -238.447925) (xy 123.630167 -238.486996)
			(xy 123.588496 -238.520227) (xy 123.542338 -238.546876) (xy 123.492724 -238.566348) (xy 123.440762 -238.578208)
			(xy 123.387612 -238.582192) (xy 123.334462 -238.578208) (xy 123.2825 -238.566348) (xy 123.232886 -238.546876)
			(xy 123.186728 -238.520227) (xy 123.145057 -238.486996) (xy 123.108805 -238.447925) (xy 123.078781 -238.403888)
			(xy 123.055655 -238.355867) (xy 123.039945 -238.304937) (xy 123.032002 -238.252233) (xy 122.803422 -238.252233)
			(xy 122.795479 -238.304937) (xy 122.779769 -238.355867) (xy 122.756643 -238.403888) (xy 122.726619 -238.447925)
			(xy 122.690367 -238.486996) (xy 122.648696 -238.520227) (xy 122.602538 -238.546876) (xy 122.552924 -238.566348)
			(xy 122.500962 -238.578208) (xy 122.447812 -238.582192) (xy 122.394662 -238.578208) (xy 122.3427 -238.566348)
			(xy 122.293086 -238.546876) (xy 122.246928 -238.520227) (xy 122.205257 -238.486996) (xy 122.169005 -238.447925)
			(xy 122.138981 -238.403888) (xy 122.115855 -238.355867) (xy 122.100145 -238.304937) (xy 122.092202 -238.252233)
			(xy 121.863622 -238.252233) (xy 121.855679 -238.304937) (xy 121.839969 -238.355867) (xy 121.816843 -238.403888)
			(xy 121.786819 -238.447925) (xy 121.750567 -238.486996) (xy 121.708896 -238.520227) (xy 121.662738 -238.546876)
			(xy 121.613124 -238.566348) (xy 121.561162 -238.578208) (xy 121.508012 -238.582192) (xy 121.454862 -238.578208)
			(xy 121.4029 -238.566348) (xy 121.353286 -238.546876) (xy 121.307128 -238.520227) (xy 121.265457 -238.486996)
			(xy 121.229205 -238.447925) (xy 121.199181 -238.403888) (xy 121.176055 -238.355867) (xy 121.160345 -238.304937)
			(xy 121.152402 -238.252233) (xy 120.98528 -238.252233) (xy 120.98528 -239.066049) (xy 121.622556 -239.066049)
			(xy 121.622556 -239.012751) (xy 121.630499 -238.960047) (xy 121.646209 -238.909117) (xy 121.669335 -238.861096)
			(xy 121.699359 -238.817059) (xy 121.735611 -238.777988) (xy 121.777282 -238.744757) (xy 121.82344 -238.718108)
			(xy 121.873054 -238.698636) (xy 121.925016 -238.686776) (xy 121.978166 -238.682793) (xy 122.031316 -238.686776)
			(xy 122.083278 -238.698636) (xy 122.132892 -238.718108) (xy 122.17905 -238.744757) (xy 122.220721 -238.777988)
			(xy 122.256973 -238.817059) (xy 122.286997 -238.861096) (xy 122.310123 -238.909117) (xy 122.325833 -238.960047)
			(xy 122.333776 -239.012751) (xy 122.334274 -239.0394) (xy 122.333776 -239.066049) (xy 122.562102 -239.066049)
			(xy 122.562102 -239.012751) (xy 122.570045 -238.960047) (xy 122.585755 -238.909117) (xy 122.608881 -238.861096)
			(xy 122.638905 -238.817059) (xy 122.675157 -238.777988) (xy 122.716828 -238.744757) (xy 122.762986 -238.718108)
			(xy 122.8126 -238.698636) (xy 122.864562 -238.686776) (xy 122.917712 -238.682793) (xy 122.970862 -238.686776)
			(xy 123.022824 -238.698636) (xy 123.072438 -238.718108) (xy 123.118596 -238.744757) (xy 123.160267 -238.777988)
			(xy 123.196519 -238.817059) (xy 123.226543 -238.861096) (xy 123.249669 -238.909117) (xy 123.265379 -238.960047)
			(xy 123.273322 -239.012751) (xy 123.27382 -239.0394) (xy 123.273322 -239.066049) (xy 123.502156 -239.066049)
			(xy 123.502156 -239.012751) (xy 123.510099 -238.960047) (xy 123.525809 -238.909117) (xy 123.548935 -238.861096)
			(xy 123.578959 -238.817059) (xy 123.615211 -238.777988) (xy 123.656882 -238.744757) (xy 123.70304 -238.718108)
			(xy 123.752654 -238.698636) (xy 123.804616 -238.686776) (xy 123.857766 -238.682793) (xy 123.910916 -238.686776)
			(xy 123.962878 -238.698636) (xy 124.012492 -238.718108) (xy 124.05865 -238.744757) (xy 124.100321 -238.777988)
			(xy 124.136573 -238.817059) (xy 124.166597 -238.861096) (xy 124.189723 -238.909117) (xy 124.205433 -238.960047)
			(xy 124.213376 -239.012751) (xy 124.213874 -239.0394) (xy 124.213376 -239.066049) (xy 124.441956 -239.066049)
			(xy 124.441956 -239.012751) (xy 124.449899 -238.960047) (xy 124.465609 -238.909117) (xy 124.488735 -238.861096)
			(xy 124.518759 -238.817059) (xy 124.555011 -238.777988) (xy 124.596682 -238.744757) (xy 124.64284 -238.718108)
			(xy 124.692454 -238.698636) (xy 124.744416 -238.686776) (xy 124.797566 -238.682793) (xy 124.850716 -238.686776)
			(xy 124.902678 -238.698636) (xy 124.952292 -238.718108) (xy 124.99845 -238.744757) (xy 125.040121 -238.777988)
			(xy 125.076373 -238.817059) (xy 125.106397 -238.861096) (xy 125.129523 -238.909117) (xy 125.145233 -238.960047)
			(xy 125.153176 -239.012751) (xy 125.153674 -239.0394) (xy 125.153176 -239.066049) (xy 125.381756 -239.066049)
			(xy 125.381756 -239.012751) (xy 125.389699 -238.960047) (xy 125.405409 -238.909117) (xy 125.428535 -238.861096)
			(xy 125.458559 -238.817059) (xy 125.494811 -238.777988) (xy 125.536482 -238.744757) (xy 125.58264 -238.718108)
			(xy 125.632254 -238.698636) (xy 125.684216 -238.686776) (xy 125.737366 -238.682793) (xy 125.790516 -238.686776)
			(xy 125.842478 -238.698636) (xy 125.892092 -238.718108) (xy 125.93825 -238.744757) (xy 125.979921 -238.777988)
			(xy 126.016173 -238.817059) (xy 126.046197 -238.861096) (xy 126.069323 -238.909117) (xy 126.085033 -238.960047)
			(xy 126.092976 -239.012751) (xy 126.093474 -239.0394) (xy 126.092976 -239.066049) (xy 126.321556 -239.066049)
			(xy 126.321556 -239.012751) (xy 126.329499 -238.960047) (xy 126.345209 -238.909117) (xy 126.368335 -238.861096)
			(xy 126.398359 -238.817059) (xy 126.434611 -238.777988) (xy 126.476282 -238.744757) (xy 126.52244 -238.718108)
			(xy 126.572054 -238.698636) (xy 126.624016 -238.686776) (xy 126.677166 -238.682793) (xy 126.730316 -238.686776)
			(xy 126.782278 -238.698636) (xy 126.831892 -238.718108) (xy 126.87805 -238.744757) (xy 126.919721 -238.777988)
			(xy 126.955973 -238.817059) (xy 126.985997 -238.861096) (xy 127.009123 -238.909117) (xy 127.024833 -238.960047)
			(xy 127.032776 -239.012751) (xy 127.033274 -239.0394) (xy 127.032776 -239.066049) (xy 127.261356 -239.066049)
			(xy 127.261356 -239.012751) (xy 127.269299 -238.960047) (xy 127.285009 -238.909117) (xy 127.308135 -238.861096)
			(xy 127.338159 -238.817059) (xy 127.374411 -238.777988) (xy 127.416082 -238.744757) (xy 127.46224 -238.718108)
			(xy 127.511854 -238.698636) (xy 127.563816 -238.686776) (xy 127.616966 -238.682793) (xy 127.670116 -238.686776)
			(xy 127.722078 -238.698636) (xy 127.771692 -238.718108) (xy 127.81785 -238.744757) (xy 127.859521 -238.777988)
			(xy 127.895773 -238.817059) (xy 127.925797 -238.861096) (xy 127.948923 -238.909117) (xy 127.964633 -238.960047)
			(xy 127.972576 -239.012751) (xy 127.973074 -239.0394) (xy 127.972576 -239.066049) (xy 128.201156 -239.066049)
			(xy 128.201156 -239.012751) (xy 128.209099 -238.960047) (xy 128.224809 -238.909117) (xy 128.247935 -238.861096)
			(xy 128.277959 -238.817059) (xy 128.314211 -238.777988) (xy 128.355882 -238.744757) (xy 128.40204 -238.718108)
			(xy 128.451654 -238.698636) (xy 128.503616 -238.686776) (xy 128.556766 -238.682793) (xy 128.609916 -238.686776)
			(xy 128.661878 -238.698636) (xy 128.711492 -238.718108) (xy 128.75765 -238.744757) (xy 128.799321 -238.777988)
			(xy 128.835573 -238.817059) (xy 128.865597 -238.861096) (xy 128.888723 -238.909117) (xy 128.904433 -238.960047)
			(xy 128.912376 -239.012751) (xy 128.912874 -239.0394) (xy 128.912376 -239.066049) (xy 129.140702 -239.066049)
			(xy 129.140702 -239.012751) (xy 129.148645 -238.960047) (xy 129.164355 -238.909117) (xy 129.187481 -238.861096)
			(xy 129.217505 -238.817059) (xy 129.253757 -238.777988) (xy 129.295428 -238.744757) (xy 129.341586 -238.718108)
			(xy 129.3912 -238.698636) (xy 129.443162 -238.686776) (xy 129.496312 -238.682793) (xy 129.549462 -238.686776)
			(xy 129.601424 -238.698636) (xy 129.651038 -238.718108) (xy 129.697196 -238.744757) (xy 129.738867 -238.777988)
			(xy 129.775119 -238.817059) (xy 129.805143 -238.861096) (xy 129.828269 -238.909117) (xy 129.843979 -238.960047)
			(xy 129.851922 -239.012751) (xy 129.85242 -239.0394) (xy 129.851922 -239.066049) (xy 130.080756 -239.066049)
			(xy 130.080756 -239.012751) (xy 130.088699 -238.960047) (xy 130.104409 -238.909117) (xy 130.127535 -238.861096)
			(xy 130.157559 -238.817059) (xy 130.193811 -238.777988) (xy 130.235482 -238.744757) (xy 130.28164 -238.718108)
			(xy 130.331254 -238.698636) (xy 130.383216 -238.686776) (xy 130.436366 -238.682793) (xy 130.489516 -238.686776)
			(xy 130.541478 -238.698636) (xy 130.591092 -238.718108) (xy 130.63725 -238.744757) (xy 130.678921 -238.777988)
			(xy 130.715173 -238.817059) (xy 130.745197 -238.861096) (xy 130.768323 -238.909117) (xy 130.784033 -238.960047)
			(xy 130.791976 -239.012751) (xy 130.792474 -239.0394) (xy 130.791976 -239.066049) (xy 131.020556 -239.066049)
			(xy 131.020556 -239.012751) (xy 131.028499 -238.960047) (xy 131.044209 -238.909117) (xy 131.067335 -238.861096)
			(xy 131.097359 -238.817059) (xy 131.133611 -238.777988) (xy 131.175282 -238.744757) (xy 131.22144 -238.718108)
			(xy 131.271054 -238.698636) (xy 131.323016 -238.686776) (xy 131.376166 -238.682793) (xy 131.429316 -238.686776)
			(xy 131.481278 -238.698636) (xy 131.530892 -238.718108) (xy 131.57705 -238.744757) (xy 131.618721 -238.777988)
			(xy 131.654973 -238.817059) (xy 131.684997 -238.861096) (xy 131.708123 -238.909117) (xy 131.723833 -238.960047)
			(xy 131.731776 -239.012751) (xy 131.732274 -239.0394) (xy 131.731776 -239.066049) (xy 131.960356 -239.066049)
			(xy 131.960356 -239.012751) (xy 131.968299 -238.960047) (xy 131.984009 -238.909117) (xy 132.007135 -238.861096)
			(xy 132.037159 -238.817059) (xy 132.073411 -238.777988) (xy 132.115082 -238.744757) (xy 132.16124 -238.718108)
			(xy 132.210854 -238.698636) (xy 132.262816 -238.686776) (xy 132.315966 -238.682793) (xy 132.369116 -238.686776)
			(xy 132.421078 -238.698636) (xy 132.470692 -238.718108) (xy 132.51685 -238.744757) (xy 132.558521 -238.777988)
			(xy 132.594773 -238.817059) (xy 132.624797 -238.861096) (xy 132.647923 -238.909117) (xy 132.663633 -238.960047)
			(xy 132.671576 -239.012751) (xy 132.672074 -239.0394) (xy 132.671576 -239.066049) (xy 132.900156 -239.066049)
			(xy 132.900156 -239.012751) (xy 132.908099 -238.960047) (xy 132.923809 -238.909117) (xy 132.946935 -238.861096)
			(xy 132.976959 -238.817059) (xy 133.013211 -238.777988) (xy 133.054882 -238.744757) (xy 133.10104 -238.718108)
			(xy 133.150654 -238.698636) (xy 133.202616 -238.686776) (xy 133.255766 -238.682793) (xy 133.308916 -238.686776)
			(xy 133.360878 -238.698636) (xy 133.410492 -238.718108) (xy 133.45665 -238.744757) (xy 133.498321 -238.777988)
			(xy 133.534573 -238.817059) (xy 133.564597 -238.861096) (xy 133.587723 -238.909117) (xy 133.603433 -238.960047)
			(xy 133.611376 -239.012751) (xy 133.611874 -239.0394) (xy 133.611376 -239.066049) (xy 133.839956 -239.066049)
			(xy 133.839956 -239.012751) (xy 133.847899 -238.960047) (xy 133.863609 -238.909117) (xy 133.886735 -238.861096)
			(xy 133.916759 -238.817059) (xy 133.953011 -238.777988) (xy 133.994682 -238.744757) (xy 134.04084 -238.718108)
			(xy 134.090454 -238.698636) (xy 134.142416 -238.686776) (xy 134.195566 -238.682793) (xy 134.248716 -238.686776)
			(xy 134.300678 -238.698636) (xy 134.350292 -238.718108) (xy 134.39645 -238.744757) (xy 134.438121 -238.777988)
			(xy 134.474373 -238.817059) (xy 134.504397 -238.861096) (xy 134.527523 -238.909117) (xy 134.543233 -238.960047)
			(xy 134.551176 -239.012751) (xy 134.551674 -239.0394) (xy 134.551176 -239.066049) (xy 134.543233 -239.118753)
			(xy 134.527523 -239.169683) (xy 134.504397 -239.217704) (xy 134.474373 -239.261741) (xy 134.438121 -239.300812)
			(xy 134.39645 -239.334043) (xy 134.350292 -239.360692) (xy 134.300678 -239.380164) (xy 134.248716 -239.392024)
			(xy 134.195566 -239.396008) (xy 134.142416 -239.392024) (xy 134.090454 -239.380164) (xy 134.04084 -239.360692)
			(xy 133.994682 -239.334043) (xy 133.953011 -239.300812) (xy 133.916759 -239.261741) (xy 133.886735 -239.217704)
			(xy 133.863609 -239.169683) (xy 133.847899 -239.118753) (xy 133.839956 -239.066049) (xy 133.611376 -239.066049)
			(xy 133.603433 -239.118753) (xy 133.587723 -239.169683) (xy 133.564597 -239.217704) (xy 133.534573 -239.261741)
			(xy 133.498321 -239.300812) (xy 133.45665 -239.334043) (xy 133.410492 -239.360692) (xy 133.360878 -239.380164)
			(xy 133.308916 -239.392024) (xy 133.255766 -239.396008) (xy 133.202616 -239.392024) (xy 133.150654 -239.380164)
			(xy 133.10104 -239.360692) (xy 133.054882 -239.334043) (xy 133.013211 -239.300812) (xy 132.976959 -239.261741)
			(xy 132.946935 -239.217704) (xy 132.923809 -239.169683) (xy 132.908099 -239.118753) (xy 132.900156 -239.066049)
			(xy 132.671576 -239.066049) (xy 132.663633 -239.118753) (xy 132.647923 -239.169683) (xy 132.624797 -239.217704)
			(xy 132.594773 -239.261741) (xy 132.558521 -239.300812) (xy 132.51685 -239.334043) (xy 132.470692 -239.360692)
			(xy 132.421078 -239.380164) (xy 132.369116 -239.392024) (xy 132.315966 -239.396008) (xy 132.262816 -239.392024)
			(xy 132.210854 -239.380164) (xy 132.16124 -239.360692) (xy 132.115082 -239.334043) (xy 132.073411 -239.300812)
			(xy 132.037159 -239.261741) (xy 132.007135 -239.217704) (xy 131.984009 -239.169683) (xy 131.968299 -239.118753)
			(xy 131.960356 -239.066049) (xy 131.731776 -239.066049) (xy 131.723833 -239.118753) (xy 131.708123 -239.169683)
			(xy 131.684997 -239.217704) (xy 131.654973 -239.261741) (xy 131.618721 -239.300812) (xy 131.57705 -239.334043)
			(xy 131.530892 -239.360692) (xy 131.481278 -239.380164) (xy 131.429316 -239.392024) (xy 131.376166 -239.396008)
			(xy 131.323016 -239.392024) (xy 131.271054 -239.380164) (xy 131.22144 -239.360692) (xy 131.175282 -239.334043)
			(xy 131.133611 -239.300812) (xy 131.097359 -239.261741) (xy 131.067335 -239.217704) (xy 131.044209 -239.169683)
			(xy 131.028499 -239.118753) (xy 131.020556 -239.066049) (xy 130.791976 -239.066049) (xy 130.784033 -239.118753)
			(xy 130.768323 -239.169683) (xy 130.745197 -239.217704) (xy 130.715173 -239.261741) (xy 130.678921 -239.300812)
			(xy 130.63725 -239.334043) (xy 130.591092 -239.360692) (xy 130.541478 -239.380164) (xy 130.489516 -239.392024)
			(xy 130.436366 -239.396008) (xy 130.383216 -239.392024) (xy 130.331254 -239.380164) (xy 130.28164 -239.360692)
			(xy 130.235482 -239.334043) (xy 130.193811 -239.300812) (xy 130.157559 -239.261741) (xy 130.127535 -239.217704)
			(xy 130.104409 -239.169683) (xy 130.088699 -239.118753) (xy 130.080756 -239.066049) (xy 129.851922 -239.066049)
			(xy 129.843979 -239.118753) (xy 129.828269 -239.169683) (xy 129.805143 -239.217704) (xy 129.775119 -239.261741)
			(xy 129.738867 -239.300812) (xy 129.697196 -239.334043) (xy 129.651038 -239.360692) (xy 129.601424 -239.380164)
			(xy 129.549462 -239.392024) (xy 129.496312 -239.396008) (xy 129.443162 -239.392024) (xy 129.3912 -239.380164)
			(xy 129.341586 -239.360692) (xy 129.295428 -239.334043) (xy 129.253757 -239.300812) (xy 129.217505 -239.261741)
			(xy 129.187481 -239.217704) (xy 129.164355 -239.169683) (xy 129.148645 -239.118753) (xy 129.140702 -239.066049)
			(xy 128.912376 -239.066049) (xy 128.904433 -239.118753) (xy 128.888723 -239.169683) (xy 128.865597 -239.217704)
			(xy 128.835573 -239.261741) (xy 128.799321 -239.300812) (xy 128.75765 -239.334043) (xy 128.711492 -239.360692)
			(xy 128.661878 -239.380164) (xy 128.609916 -239.392024) (xy 128.556766 -239.396008) (xy 128.503616 -239.392024)
			(xy 128.451654 -239.380164) (xy 128.40204 -239.360692) (xy 128.355882 -239.334043) (xy 128.314211 -239.300812)
			(xy 128.277959 -239.261741) (xy 128.247935 -239.217704) (xy 128.224809 -239.169683) (xy 128.209099 -239.118753)
			(xy 128.201156 -239.066049) (xy 127.972576 -239.066049) (xy 127.964633 -239.118753) (xy 127.948923 -239.169683)
			(xy 127.925797 -239.217704) (xy 127.895773 -239.261741) (xy 127.859521 -239.300812) (xy 127.81785 -239.334043)
			(xy 127.771692 -239.360692) (xy 127.722078 -239.380164) (xy 127.670116 -239.392024) (xy 127.616966 -239.396008)
			(xy 127.563816 -239.392024) (xy 127.511854 -239.380164) (xy 127.46224 -239.360692) (xy 127.416082 -239.334043)
			(xy 127.374411 -239.300812) (xy 127.338159 -239.261741) (xy 127.308135 -239.217704) (xy 127.285009 -239.169683)
			(xy 127.269299 -239.118753) (xy 127.261356 -239.066049) (xy 127.032776 -239.066049) (xy 127.024833 -239.118753)
			(xy 127.009123 -239.169683) (xy 126.985997 -239.217704) (xy 126.955973 -239.261741) (xy 126.919721 -239.300812)
			(xy 126.87805 -239.334043) (xy 126.831892 -239.360692) (xy 126.782278 -239.380164) (xy 126.730316 -239.392024)
			(xy 126.677166 -239.396008) (xy 126.624016 -239.392024) (xy 126.572054 -239.380164) (xy 126.52244 -239.360692)
			(xy 126.476282 -239.334043) (xy 126.434611 -239.300812) (xy 126.398359 -239.261741) (xy 126.368335 -239.217704)
			(xy 126.345209 -239.169683) (xy 126.329499 -239.118753) (xy 126.321556 -239.066049) (xy 126.092976 -239.066049)
			(xy 126.085033 -239.118753) (xy 126.069323 -239.169683) (xy 126.046197 -239.217704) (xy 126.016173 -239.261741)
			(xy 125.979921 -239.300812) (xy 125.93825 -239.334043) (xy 125.892092 -239.360692) (xy 125.842478 -239.380164)
			(xy 125.790516 -239.392024) (xy 125.737366 -239.396008) (xy 125.684216 -239.392024) (xy 125.632254 -239.380164)
			(xy 125.58264 -239.360692) (xy 125.536482 -239.334043) (xy 125.494811 -239.300812) (xy 125.458559 -239.261741)
			(xy 125.428535 -239.217704) (xy 125.405409 -239.169683) (xy 125.389699 -239.118753) (xy 125.381756 -239.066049)
			(xy 125.153176 -239.066049) (xy 125.145233 -239.118753) (xy 125.129523 -239.169683) (xy 125.106397 -239.217704)
			(xy 125.076373 -239.261741) (xy 125.040121 -239.300812) (xy 124.99845 -239.334043) (xy 124.952292 -239.360692)
			(xy 124.902678 -239.380164) (xy 124.850716 -239.392024) (xy 124.797566 -239.396008) (xy 124.744416 -239.392024)
			(xy 124.692454 -239.380164) (xy 124.64284 -239.360692) (xy 124.596682 -239.334043) (xy 124.555011 -239.300812)
			(xy 124.518759 -239.261741) (xy 124.488735 -239.217704) (xy 124.465609 -239.169683) (xy 124.449899 -239.118753)
			(xy 124.441956 -239.066049) (xy 124.213376 -239.066049) (xy 124.205433 -239.118753) (xy 124.189723 -239.169683)
			(xy 124.166597 -239.217704) (xy 124.136573 -239.261741) (xy 124.100321 -239.300812) (xy 124.05865 -239.334043)
			(xy 124.012492 -239.360692) (xy 123.962878 -239.380164) (xy 123.910916 -239.392024) (xy 123.857766 -239.396008)
			(xy 123.804616 -239.392024) (xy 123.752654 -239.380164) (xy 123.70304 -239.360692) (xy 123.656882 -239.334043)
			(xy 123.615211 -239.300812) (xy 123.578959 -239.261741) (xy 123.548935 -239.217704) (xy 123.525809 -239.169683)
			(xy 123.510099 -239.118753) (xy 123.502156 -239.066049) (xy 123.273322 -239.066049) (xy 123.265379 -239.118753)
			(xy 123.249669 -239.169683) (xy 123.226543 -239.217704) (xy 123.196519 -239.261741) (xy 123.160267 -239.300812)
			(xy 123.118596 -239.334043) (xy 123.072438 -239.360692) (xy 123.022824 -239.380164) (xy 122.970862 -239.392024)
			(xy 122.917712 -239.396008) (xy 122.864562 -239.392024) (xy 122.8126 -239.380164) (xy 122.762986 -239.360692)
			(xy 122.716828 -239.334043) (xy 122.675157 -239.300812) (xy 122.638905 -239.261741) (xy 122.608881 -239.217704)
			(xy 122.585755 -239.169683) (xy 122.570045 -239.118753) (xy 122.562102 -239.066049) (xy 122.333776 -239.066049)
			(xy 122.325833 -239.118753) (xy 122.310123 -239.169683) (xy 122.286997 -239.217704) (xy 122.256973 -239.261741)
			(xy 122.220721 -239.300812) (xy 122.17905 -239.334043) (xy 122.132892 -239.360692) (xy 122.083278 -239.380164)
			(xy 122.031316 -239.392024) (xy 121.978166 -239.396008) (xy 121.925016 -239.392024) (xy 121.873054 -239.380164)
			(xy 121.82344 -239.360692) (xy 121.777282 -239.334043) (xy 121.735611 -239.300812) (xy 121.699359 -239.261741)
			(xy 121.669335 -239.217704) (xy 121.646209 -239.169683) (xy 121.630499 -239.118753) (xy 121.622556 -239.066049)
			(xy 120.98528 -239.066049) (xy 120.98528 -239.763554) (xy 121.025412 -239.77219) (xy 121.053606 -239.779556)
			(xy 121.068217 -239.783447) (xy 121.098438 -239.783439) (xy 121.127334 -239.77459) (xy 121.152377 -239.757675)
			(xy 121.171376 -239.734174) (xy 121.177558 -239.720374) (xy 121.187877 -239.695993) (xy 121.21467 -239.650334)
			(xy 121.247931 -239.609146) (xy 121.286923 -239.573338) (xy 121.330789 -239.543699) (xy 121.37856 -239.520882)
			(xy 121.429183 -239.505392) (xy 121.481542 -239.497568) (xy 121.508012 -239.497108) (xy 121.534659 -239.497607)
			(xy 121.587359 -239.505552) (xy 121.638286 -239.521262) (xy 121.686302 -239.544387) (xy 121.730336 -239.57441)
			(xy 121.769404 -239.610661) (xy 121.802632 -239.652329) (xy 121.829279 -239.698484) (xy 121.848749 -239.748095)
			(xy 121.860608 -239.800054) (xy 121.864591 -239.8532) (xy 121.862593 -239.879865) (xy 122.092456 -239.879865)
			(xy 122.092456 -239.826567) (xy 122.100399 -239.773863) (xy 122.116109 -239.722933) (xy 122.139235 -239.674912)
			(xy 122.169259 -239.630875) (xy 122.205511 -239.591804) (xy 122.247182 -239.558573) (xy 122.29334 -239.531924)
			(xy 122.342954 -239.512452) (xy 122.394916 -239.500592) (xy 122.448066 -239.496609) (xy 122.501216 -239.500592)
			(xy 122.553178 -239.512452) (xy 122.602792 -239.531924) (xy 122.64895 -239.558573) (xy 122.690621 -239.591804)
			(xy 122.726873 -239.630875) (xy 122.756897 -239.674912) (xy 122.780023 -239.722933) (xy 122.795733 -239.773863)
			(xy 122.803676 -239.826567) (xy 122.804174 -239.853216) (xy 122.803676 -239.879865) (xy 123.032002 -239.879865)
			(xy 123.032002 -239.826567) (xy 123.039945 -239.773863) (xy 123.055655 -239.722933) (xy 123.078781 -239.674912)
			(xy 123.108805 -239.630875) (xy 123.145057 -239.591804) (xy 123.186728 -239.558573) (xy 123.232886 -239.531924)
			(xy 123.2825 -239.512452) (xy 123.334462 -239.500592) (xy 123.387612 -239.496609) (xy 123.440762 -239.500592)
			(xy 123.492724 -239.512452) (xy 123.542338 -239.531924) (xy 123.588496 -239.558573) (xy 123.630167 -239.591804)
			(xy 123.666419 -239.630875) (xy 123.696443 -239.674912) (xy 123.719569 -239.722933) (xy 123.735279 -239.773863)
			(xy 123.743222 -239.826567) (xy 123.74372 -239.853216) (xy 123.743222 -239.879865) (xy 123.971802 -239.879865)
			(xy 123.971802 -239.826567) (xy 123.979745 -239.773863) (xy 123.995455 -239.722933) (xy 124.018581 -239.674912)
			(xy 124.048605 -239.630875) (xy 124.084857 -239.591804) (xy 124.126528 -239.558573) (xy 124.172686 -239.531924)
			(xy 124.2223 -239.512452) (xy 124.274262 -239.500592) (xy 124.327412 -239.496609) (xy 124.380562 -239.500592)
			(xy 124.432524 -239.512452) (xy 124.482138 -239.531924) (xy 124.528296 -239.558573) (xy 124.569967 -239.591804)
			(xy 124.606219 -239.630875) (xy 124.636243 -239.674912) (xy 124.659369 -239.722933) (xy 124.675079 -239.773863)
			(xy 124.683022 -239.826567) (xy 124.68352 -239.853216) (xy 124.683022 -239.879865) (xy 124.911856 -239.879865)
			(xy 124.911856 -239.826567) (xy 124.919799 -239.773863) (xy 124.935509 -239.722933) (xy 124.958635 -239.674912)
			(xy 124.988659 -239.630875) (xy 125.024911 -239.591804) (xy 125.066582 -239.558573) (xy 125.11274 -239.531924)
			(xy 125.162354 -239.512452) (xy 125.214316 -239.500592) (xy 125.267466 -239.496609) (xy 125.320616 -239.500592)
			(xy 125.372578 -239.512452) (xy 125.422192 -239.531924) (xy 125.46835 -239.558573) (xy 125.510021 -239.591804)
			(xy 125.546273 -239.630875) (xy 125.576297 -239.674912) (xy 125.599423 -239.722933) (xy 125.615133 -239.773863)
			(xy 125.623076 -239.826567) (xy 125.623574 -239.853216) (xy 125.623076 -239.879865) (xy 125.851402 -239.879865)
			(xy 125.851402 -239.826567) (xy 125.859345 -239.773863) (xy 125.875055 -239.722933) (xy 125.898181 -239.674912)
			(xy 125.928205 -239.630875) (xy 125.964457 -239.591804) (xy 126.006128 -239.558573) (xy 126.052286 -239.531924)
			(xy 126.1019 -239.512452) (xy 126.153862 -239.500592) (xy 126.207012 -239.496609) (xy 126.260162 -239.500592)
			(xy 126.312124 -239.512452) (xy 126.361738 -239.531924) (xy 126.407896 -239.558573) (xy 126.449567 -239.591804)
			(xy 126.485819 -239.630875) (xy 126.515843 -239.674912) (xy 126.538969 -239.722933) (xy 126.554679 -239.773863)
			(xy 126.562622 -239.826567) (xy 126.56312 -239.853216) (xy 126.562622 -239.879865) (xy 126.791202 -239.879865)
			(xy 126.791202 -239.826567) (xy 126.799145 -239.773863) (xy 126.814855 -239.722933) (xy 126.837981 -239.674912)
			(xy 126.868005 -239.630875) (xy 126.904257 -239.591804) (xy 126.945928 -239.558573) (xy 126.992086 -239.531924)
			(xy 127.0417 -239.512452) (xy 127.093662 -239.500592) (xy 127.146812 -239.496609) (xy 127.199962 -239.500592)
			(xy 127.251924 -239.512452) (xy 127.301538 -239.531924) (xy 127.347696 -239.558573) (xy 127.389367 -239.591804)
			(xy 127.425619 -239.630875) (xy 127.455643 -239.674912) (xy 127.478769 -239.722933) (xy 127.494479 -239.773863)
			(xy 127.502422 -239.826567) (xy 127.50292 -239.853216) (xy 127.502422 -239.879865) (xy 127.731002 -239.879865)
			(xy 127.731002 -239.826567) (xy 127.738945 -239.773863) (xy 127.754655 -239.722933) (xy 127.777781 -239.674912)
			(xy 127.807805 -239.630875) (xy 127.844057 -239.591804) (xy 127.885728 -239.558573) (xy 127.931886 -239.531924)
			(xy 127.9815 -239.512452) (xy 128.033462 -239.500592) (xy 128.086612 -239.496609) (xy 128.139762 -239.500592)
			(xy 128.191724 -239.512452) (xy 128.241338 -239.531924) (xy 128.287496 -239.558573) (xy 128.329167 -239.591804)
			(xy 128.365419 -239.630875) (xy 128.395443 -239.674912) (xy 128.418569 -239.722933) (xy 128.434279 -239.773863)
			(xy 128.442222 -239.826567) (xy 128.44272 -239.853216) (xy 128.442222 -239.879865) (xy 128.670802 -239.879865)
			(xy 128.670802 -239.826567) (xy 128.678745 -239.773863) (xy 128.694455 -239.722933) (xy 128.717581 -239.674912)
			(xy 128.747605 -239.630875) (xy 128.783857 -239.591804) (xy 128.825528 -239.558573) (xy 128.871686 -239.531924)
			(xy 128.9213 -239.512452) (xy 128.973262 -239.500592) (xy 129.026412 -239.496609) (xy 129.079562 -239.500592)
			(xy 129.131524 -239.512452) (xy 129.181138 -239.531924) (xy 129.227296 -239.558573) (xy 129.268967 -239.591804)
			(xy 129.305219 -239.630875) (xy 129.335243 -239.674912) (xy 129.358369 -239.722933) (xy 129.374079 -239.773863)
			(xy 129.382022 -239.826567) (xy 129.38252 -239.853216) (xy 129.382022 -239.879865) (xy 129.610602 -239.879865)
			(xy 129.610602 -239.826567) (xy 129.618545 -239.773863) (xy 129.634255 -239.722933) (xy 129.657381 -239.674912)
			(xy 129.687405 -239.630875) (xy 129.723657 -239.591804) (xy 129.765328 -239.558573) (xy 129.811486 -239.531924)
			(xy 129.8611 -239.512452) (xy 129.913062 -239.500592) (xy 129.966212 -239.496609) (xy 130.019362 -239.500592)
			(xy 130.071324 -239.512452) (xy 130.120938 -239.531924) (xy 130.167096 -239.558573) (xy 130.208767 -239.591804)
			(xy 130.245019 -239.630875) (xy 130.275043 -239.674912) (xy 130.298169 -239.722933) (xy 130.313879 -239.773863)
			(xy 130.321822 -239.826567) (xy 130.32232 -239.853216) (xy 130.321822 -239.879865) (xy 130.550402 -239.879865)
			(xy 130.550402 -239.826567) (xy 130.558345 -239.773863) (xy 130.574055 -239.722933) (xy 130.597181 -239.674912)
			(xy 130.627205 -239.630875) (xy 130.663457 -239.591804) (xy 130.705128 -239.558573) (xy 130.751286 -239.531924)
			(xy 130.8009 -239.512452) (xy 130.852862 -239.500592) (xy 130.906012 -239.496609) (xy 130.959162 -239.500592)
			(xy 131.011124 -239.512452) (xy 131.060738 -239.531924) (xy 131.106896 -239.558573) (xy 131.148567 -239.591804)
			(xy 131.184819 -239.630875) (xy 131.214843 -239.674912) (xy 131.237969 -239.722933) (xy 131.253679 -239.773863)
			(xy 131.261622 -239.826567) (xy 131.26212 -239.853216) (xy 131.261622 -239.879865) (xy 131.490456 -239.879865)
			(xy 131.490456 -239.826567) (xy 131.498399 -239.773863) (xy 131.514109 -239.722933) (xy 131.537235 -239.674912)
			(xy 131.567259 -239.630875) (xy 131.603511 -239.591804) (xy 131.645182 -239.558573) (xy 131.69134 -239.531924)
			(xy 131.740954 -239.512452) (xy 131.792916 -239.500592) (xy 131.846066 -239.496609) (xy 131.899216 -239.500592)
			(xy 131.951178 -239.512452) (xy 132.000792 -239.531924) (xy 132.04695 -239.558573) (xy 132.088621 -239.591804)
			(xy 132.124873 -239.630875) (xy 132.154897 -239.674912) (xy 132.178023 -239.722933) (xy 132.193733 -239.773863)
			(xy 132.201676 -239.826567) (xy 132.202174 -239.853216) (xy 132.201676 -239.879865) (xy 132.430002 -239.879865)
			(xy 132.430002 -239.826567) (xy 132.437945 -239.773863) (xy 132.453655 -239.722933) (xy 132.476781 -239.674912)
			(xy 132.506805 -239.630875) (xy 132.543057 -239.591804) (xy 132.584728 -239.558573) (xy 132.630886 -239.531924)
			(xy 132.6805 -239.512452) (xy 132.732462 -239.500592) (xy 132.785612 -239.496609) (xy 132.838762 -239.500592)
			(xy 132.890724 -239.512452) (xy 132.940338 -239.531924) (xy 132.986496 -239.558573) (xy 133.028167 -239.591804)
			(xy 133.064419 -239.630875) (xy 133.094443 -239.674912) (xy 133.117569 -239.722933) (xy 133.133279 -239.773863)
			(xy 133.141222 -239.826567) (xy 133.14172 -239.853216) (xy 133.141222 -239.879865) (xy 133.370056 -239.879865)
			(xy 133.370056 -239.826567) (xy 133.377999 -239.773863) (xy 133.393709 -239.722933) (xy 133.416835 -239.674912)
			(xy 133.446859 -239.630875) (xy 133.483111 -239.591804) (xy 133.524782 -239.558573) (xy 133.57094 -239.531924)
			(xy 133.620554 -239.512452) (xy 133.672516 -239.500592) (xy 133.725666 -239.496609) (xy 133.778816 -239.500592)
			(xy 133.830778 -239.512452) (xy 133.880392 -239.531924) (xy 133.92655 -239.558573) (xy 133.968221 -239.591804)
			(xy 134.004473 -239.630875) (xy 134.034497 -239.674912) (xy 134.057623 -239.722933) (xy 134.073333 -239.773863)
			(xy 134.081276 -239.826567) (xy 134.081774 -239.853216) (xy 134.081276 -239.879865) (xy 134.309602 -239.879865)
			(xy 134.309602 -239.826567) (xy 134.317545 -239.773863) (xy 134.333255 -239.722933) (xy 134.356381 -239.674912)
			(xy 134.386405 -239.630875) (xy 134.422657 -239.591804) (xy 134.464328 -239.558573) (xy 134.510486 -239.531924)
			(xy 134.5601 -239.512452) (xy 134.612062 -239.500592) (xy 134.665212 -239.496609) (xy 134.718362 -239.500592)
			(xy 134.770324 -239.512452) (xy 134.819938 -239.531924) (xy 134.866096 -239.558573) (xy 134.907767 -239.591804)
			(xy 134.944019 -239.630875) (xy 134.974043 -239.674912) (xy 134.997169 -239.722933) (xy 135.012879 -239.773863)
			(xy 135.020822 -239.826567) (xy 135.02132 -239.853216) (xy 135.020822 -239.879865) (xy 135.012879 -239.932569)
			(xy 134.997169 -239.983499) (xy 134.974043 -240.03152) (xy 134.944019 -240.075557) (xy 134.907767 -240.114628)
			(xy 134.866096 -240.147859) (xy 134.819938 -240.174508) (xy 134.770324 -240.19398) (xy 134.718362 -240.20584)
			(xy 134.665212 -240.209824) (xy 134.612062 -240.20584) (xy 134.5601 -240.19398) (xy 134.510486 -240.174508)
			(xy 134.464328 -240.147859) (xy 134.422657 -240.114628) (xy 134.386405 -240.075557) (xy 134.356381 -240.03152)
			(xy 134.333255 -239.983499) (xy 134.317545 -239.932569) (xy 134.309602 -239.879865) (xy 134.081276 -239.879865)
			(xy 134.073333 -239.932569) (xy 134.057623 -239.983499) (xy 134.034497 -240.03152) (xy 134.004473 -240.075557)
			(xy 133.968221 -240.114628) (xy 133.92655 -240.147859) (xy 133.880392 -240.174508) (xy 133.830778 -240.19398)
			(xy 133.778816 -240.20584) (xy 133.725666 -240.209824) (xy 133.672516 -240.20584) (xy 133.620554 -240.19398)
			(xy 133.57094 -240.174508) (xy 133.524782 -240.147859) (xy 133.483111 -240.114628) (xy 133.446859 -240.075557)
			(xy 133.416835 -240.03152) (xy 133.393709 -239.983499) (xy 133.377999 -239.932569) (xy 133.370056 -239.879865)
			(xy 133.141222 -239.879865) (xy 133.133279 -239.932569) (xy 133.117569 -239.983499) (xy 133.094443 -240.03152)
			(xy 133.064419 -240.075557) (xy 133.028167 -240.114628) (xy 132.986496 -240.147859) (xy 132.940338 -240.174508)
			(xy 132.890724 -240.19398) (xy 132.838762 -240.20584) (xy 132.785612 -240.209824) (xy 132.732462 -240.20584)
			(xy 132.6805 -240.19398) (xy 132.630886 -240.174508) (xy 132.584728 -240.147859) (xy 132.543057 -240.114628)
			(xy 132.506805 -240.075557) (xy 132.476781 -240.03152) (xy 132.453655 -239.983499) (xy 132.437945 -239.932569)
			(xy 132.430002 -239.879865) (xy 132.201676 -239.879865) (xy 132.193733 -239.932569) (xy 132.178023 -239.983499)
			(xy 132.154897 -240.03152) (xy 132.124873 -240.075557) (xy 132.088621 -240.114628) (xy 132.04695 -240.147859)
			(xy 132.000792 -240.174508) (xy 131.951178 -240.19398) (xy 131.899216 -240.20584) (xy 131.846066 -240.209824)
			(xy 131.792916 -240.20584) (xy 131.740954 -240.19398) (xy 131.69134 -240.174508) (xy 131.645182 -240.147859)
			(xy 131.603511 -240.114628) (xy 131.567259 -240.075557) (xy 131.537235 -240.03152) (xy 131.514109 -239.983499)
			(xy 131.498399 -239.932569) (xy 131.490456 -239.879865) (xy 131.261622 -239.879865) (xy 131.253679 -239.932569)
			(xy 131.237969 -239.983499) (xy 131.214843 -240.03152) (xy 131.184819 -240.075557) (xy 131.148567 -240.114628)
			(xy 131.106896 -240.147859) (xy 131.060738 -240.174508) (xy 131.011124 -240.19398) (xy 130.959162 -240.20584)
			(xy 130.906012 -240.209824) (xy 130.852862 -240.20584) (xy 130.8009 -240.19398) (xy 130.751286 -240.174508)
			(xy 130.705128 -240.147859) (xy 130.663457 -240.114628) (xy 130.627205 -240.075557) (xy 130.597181 -240.03152)
			(xy 130.574055 -239.983499) (xy 130.558345 -239.932569) (xy 130.550402 -239.879865) (xy 130.321822 -239.879865)
			(xy 130.313879 -239.932569) (xy 130.298169 -239.983499) (xy 130.275043 -240.03152) (xy 130.245019 -240.075557)
			(xy 130.208767 -240.114628) (xy 130.167096 -240.147859) (xy 130.120938 -240.174508) (xy 130.071324 -240.19398)
			(xy 130.019362 -240.20584) (xy 129.966212 -240.209824) (xy 129.913062 -240.20584) (xy 129.8611 -240.19398)
			(xy 129.811486 -240.174508) (xy 129.765328 -240.147859) (xy 129.723657 -240.114628) (xy 129.687405 -240.075557)
			(xy 129.657381 -240.03152) (xy 129.634255 -239.983499) (xy 129.618545 -239.932569) (xy 129.610602 -239.879865)
			(xy 129.382022 -239.879865) (xy 129.374079 -239.932569) (xy 129.358369 -239.983499) (xy 129.335243 -240.03152)
			(xy 129.305219 -240.075557) (xy 129.268967 -240.114628) (xy 129.227296 -240.147859) (xy 129.181138 -240.174508)
			(xy 129.131524 -240.19398) (xy 129.079562 -240.20584) (xy 129.026412 -240.209824) (xy 128.973262 -240.20584)
			(xy 128.9213 -240.19398) (xy 128.871686 -240.174508) (xy 128.825528 -240.147859) (xy 128.783857 -240.114628)
			(xy 128.747605 -240.075557) (xy 128.717581 -240.03152) (xy 128.694455 -239.983499) (xy 128.678745 -239.932569)
			(xy 128.670802 -239.879865) (xy 128.442222 -239.879865) (xy 128.434279 -239.932569) (xy 128.418569 -239.983499)
			(xy 128.395443 -240.03152) (xy 128.365419 -240.075557) (xy 128.329167 -240.114628) (xy 128.287496 -240.147859)
			(xy 128.241338 -240.174508) (xy 128.191724 -240.19398) (xy 128.139762 -240.20584) (xy 128.086612 -240.209824)
			(xy 128.033462 -240.20584) (xy 127.9815 -240.19398) (xy 127.931886 -240.174508) (xy 127.885728 -240.147859)
			(xy 127.844057 -240.114628) (xy 127.807805 -240.075557) (xy 127.777781 -240.03152) (xy 127.754655 -239.983499)
			(xy 127.738945 -239.932569) (xy 127.731002 -239.879865) (xy 127.502422 -239.879865) (xy 127.494479 -239.932569)
			(xy 127.478769 -239.983499) (xy 127.455643 -240.03152) (xy 127.425619 -240.075557) (xy 127.389367 -240.114628)
			(xy 127.347696 -240.147859) (xy 127.301538 -240.174508) (xy 127.251924 -240.19398) (xy 127.199962 -240.20584)
			(xy 127.146812 -240.209824) (xy 127.093662 -240.20584) (xy 127.0417 -240.19398) (xy 126.992086 -240.174508)
			(xy 126.945928 -240.147859) (xy 126.904257 -240.114628) (xy 126.868005 -240.075557) (xy 126.837981 -240.03152)
			(xy 126.814855 -239.983499) (xy 126.799145 -239.932569) (xy 126.791202 -239.879865) (xy 126.562622 -239.879865)
			(xy 126.554679 -239.932569) (xy 126.538969 -239.983499) (xy 126.515843 -240.03152) (xy 126.485819 -240.075557)
			(xy 126.449567 -240.114628) (xy 126.407896 -240.147859) (xy 126.361738 -240.174508) (xy 126.312124 -240.19398)
			(xy 126.260162 -240.20584) (xy 126.207012 -240.209824) (xy 126.153862 -240.20584) (xy 126.1019 -240.19398)
			(xy 126.052286 -240.174508) (xy 126.006128 -240.147859) (xy 125.964457 -240.114628) (xy 125.928205 -240.075557)
			(xy 125.898181 -240.03152) (xy 125.875055 -239.983499) (xy 125.859345 -239.932569) (xy 125.851402 -239.879865)
			(xy 125.623076 -239.879865) (xy 125.615133 -239.932569) (xy 125.599423 -239.983499) (xy 125.576297 -240.03152)
			(xy 125.546273 -240.075557) (xy 125.510021 -240.114628) (xy 125.46835 -240.147859) (xy 125.422192 -240.174508)
			(xy 125.372578 -240.19398) (xy 125.320616 -240.20584) (xy 125.267466 -240.209824) (xy 125.214316 -240.20584)
			(xy 125.162354 -240.19398) (xy 125.11274 -240.174508) (xy 125.066582 -240.147859) (xy 125.024911 -240.114628)
			(xy 124.988659 -240.075557) (xy 124.958635 -240.03152) (xy 124.935509 -239.983499) (xy 124.919799 -239.932569)
			(xy 124.911856 -239.879865) (xy 124.683022 -239.879865) (xy 124.675079 -239.932569) (xy 124.659369 -239.983499)
			(xy 124.636243 -240.03152) (xy 124.606219 -240.075557) (xy 124.569967 -240.114628) (xy 124.528296 -240.147859)
			(xy 124.482138 -240.174508) (xy 124.432524 -240.19398) (xy 124.380562 -240.20584) (xy 124.327412 -240.209824)
			(xy 124.274262 -240.20584) (xy 124.2223 -240.19398) (xy 124.172686 -240.174508) (xy 124.126528 -240.147859)
			(xy 124.084857 -240.114628) (xy 124.048605 -240.075557) (xy 124.018581 -240.03152) (xy 123.995455 -239.983499)
			(xy 123.979745 -239.932569) (xy 123.971802 -239.879865) (xy 123.743222 -239.879865) (xy 123.735279 -239.932569)
			(xy 123.719569 -239.983499) (xy 123.696443 -240.03152) (xy 123.666419 -240.075557) (xy 123.630167 -240.114628)
			(xy 123.588496 -240.147859) (xy 123.542338 -240.174508) (xy 123.492724 -240.19398) (xy 123.440762 -240.20584)
			(xy 123.387612 -240.209824) (xy 123.334462 -240.20584) (xy 123.2825 -240.19398) (xy 123.232886 -240.174508)
			(xy 123.186728 -240.147859) (xy 123.145057 -240.114628) (xy 123.108805 -240.075557) (xy 123.078781 -240.03152)
			(xy 123.055655 -239.983499) (xy 123.039945 -239.932569) (xy 123.032002 -239.879865) (xy 122.803676 -239.879865)
			(xy 122.795733 -239.932569) (xy 122.780023 -239.983499) (xy 122.756897 -240.03152) (xy 122.726873 -240.075557)
			(xy 122.690621 -240.114628) (xy 122.64895 -240.147859) (xy 122.602792 -240.174508) (xy 122.553178 -240.19398)
			(xy 122.501216 -240.20584) (xy 122.448066 -240.209824) (xy 122.394916 -240.20584) (xy 122.342954 -240.19398)
			(xy 122.29334 -240.174508) (xy 122.247182 -240.147859) (xy 122.205511 -240.114628) (xy 122.169259 -240.075557)
			(xy 122.139235 -240.03152) (xy 122.116109 -239.983499) (xy 122.100399 -239.932569) (xy 122.092456 -239.879865)
			(xy 121.862593 -239.879865) (xy 121.860608 -239.906346) (xy 121.848749 -239.958305) (xy 121.829279 -240.007916)
			(xy 121.802632 -240.054071) (xy 121.769404 -240.095739) (xy 121.730336 -240.13199) (xy 121.686302 -240.162013)
			(xy 121.638286 -240.185138) (xy 121.587359 -240.200848) (xy 121.534659 -240.208793) (xy 121.508012 -240.209324)
			(xy 121.481644 -240.208847) (xy 121.429486 -240.201068) (xy 121.404126 -240.19383) (xy 121.389513 -240.189934)
			(xy 121.359285 -240.189935) (xy 121.33038 -240.198778) (xy 121.305327 -240.215691) (xy 121.286317 -240.239193)
			(xy 121.280174 -240.253012) (xy 121.269361 -240.278448) (xy 121.241047 -240.325914) (xy 121.223786 -240.3475)
			(xy 121.215154 -240.358629) (xy 121.203797 -240.384392) (xy 121.199908 -240.412277) (xy 121.203784 -240.440163)
			(xy 121.215129 -240.465931) (xy 121.223786 -240.47704) (xy 121.239226 -240.496287) (xy 121.265204 -240.538235)
			(xy 121.285135 -240.583372) (xy 121.298636 -240.63083) (xy 121.305447 -240.679699) (xy 121.305667 -240.693935)
			(xy 121.622556 -240.693935) (xy 121.622556 -240.640637) (xy 121.630499 -240.587933) (xy 121.646209 -240.537003)
			(xy 121.669335 -240.488982) (xy 121.699359 -240.444945) (xy 121.735611 -240.405874) (xy 121.777282 -240.372643)
			(xy 121.82344 -240.345994) (xy 121.873054 -240.326522) (xy 121.925016 -240.314662) (xy 121.978166 -240.310679)
			(xy 122.031316 -240.314662) (xy 122.083278 -240.326522) (xy 122.132892 -240.345994) (xy 122.17905 -240.372643)
			(xy 122.220721 -240.405874) (xy 122.256973 -240.444945) (xy 122.286997 -240.488982) (xy 122.310123 -240.537003)
			(xy 122.325833 -240.587933) (xy 122.333776 -240.640637) (xy 122.334274 -240.667286) (xy 122.333776 -240.693935)
			(xy 122.562102 -240.693935) (xy 122.562102 -240.640637) (xy 122.570045 -240.587933) (xy 122.585755 -240.537003)
			(xy 122.608881 -240.488982) (xy 122.638905 -240.444945) (xy 122.675157 -240.405874) (xy 122.716828 -240.372643)
			(xy 122.762986 -240.345994) (xy 122.8126 -240.326522) (xy 122.864562 -240.314662) (xy 122.917712 -240.310679)
			(xy 122.970862 -240.314662) (xy 123.022824 -240.326522) (xy 123.072438 -240.345994) (xy 123.118596 -240.372643)
			(xy 123.160267 -240.405874) (xy 123.196519 -240.444945) (xy 123.226543 -240.488982) (xy 123.249669 -240.537003)
			(xy 123.265379 -240.587933) (xy 123.273322 -240.640637) (xy 123.27382 -240.667286) (xy 123.273322 -240.693935)
			(xy 123.502156 -240.693935) (xy 123.502156 -240.640637) (xy 123.510099 -240.587933) (xy 123.525809 -240.537003)
			(xy 123.548935 -240.488982) (xy 123.578959 -240.444945) (xy 123.615211 -240.405874) (xy 123.656882 -240.372643)
			(xy 123.70304 -240.345994) (xy 123.752654 -240.326522) (xy 123.804616 -240.314662) (xy 123.857766 -240.310679)
			(xy 123.910916 -240.314662) (xy 123.962878 -240.326522) (xy 124.012492 -240.345994) (xy 124.05865 -240.372643)
			(xy 124.100321 -240.405874) (xy 124.136573 -240.444945) (xy 124.166597 -240.488982) (xy 124.189723 -240.537003)
			(xy 124.205433 -240.587933) (xy 124.213376 -240.640637) (xy 124.213874 -240.667286) (xy 124.213376 -240.693935)
			(xy 124.441956 -240.693935) (xy 124.441956 -240.640637) (xy 124.449899 -240.587933) (xy 124.465609 -240.537003)
			(xy 124.488735 -240.488982) (xy 124.518759 -240.444945) (xy 124.555011 -240.405874) (xy 124.596682 -240.372643)
			(xy 124.64284 -240.345994) (xy 124.692454 -240.326522) (xy 124.744416 -240.314662) (xy 124.797566 -240.310679)
			(xy 124.850716 -240.314662) (xy 124.902678 -240.326522) (xy 124.952292 -240.345994) (xy 124.99845 -240.372643)
			(xy 125.040121 -240.405874) (xy 125.076373 -240.444945) (xy 125.106397 -240.488982) (xy 125.129523 -240.537003)
			(xy 125.145233 -240.587933) (xy 125.153176 -240.640637) (xy 125.153674 -240.667286) (xy 125.153176 -240.693935)
			(xy 125.381502 -240.693935) (xy 125.381502 -240.640637) (xy 125.389445 -240.587933) (xy 125.405155 -240.537003)
			(xy 125.428281 -240.488982) (xy 125.458305 -240.444945) (xy 125.494557 -240.405874) (xy 125.536228 -240.372643)
			(xy 125.582386 -240.345994) (xy 125.632 -240.326522) (xy 125.683962 -240.314662) (xy 125.737112 -240.310679)
			(xy 125.790262 -240.314662) (xy 125.842224 -240.326522) (xy 125.891838 -240.345994) (xy 125.937996 -240.372643)
			(xy 125.979667 -240.405874) (xy 126.015919 -240.444945) (xy 126.045943 -240.488982) (xy 126.069069 -240.537003)
			(xy 126.084779 -240.587933) (xy 126.092722 -240.640637) (xy 126.09322 -240.667286) (xy 126.092722 -240.693935)
			(xy 126.321556 -240.693935) (xy 126.321556 -240.640637) (xy 126.329499 -240.587933) (xy 126.345209 -240.537003)
			(xy 126.368335 -240.488982) (xy 126.398359 -240.444945) (xy 126.434611 -240.405874) (xy 126.476282 -240.372643)
			(xy 126.52244 -240.345994) (xy 126.572054 -240.326522) (xy 126.624016 -240.314662) (xy 126.677166 -240.310679)
			(xy 126.730316 -240.314662) (xy 126.782278 -240.326522) (xy 126.831892 -240.345994) (xy 126.87805 -240.372643)
			(xy 126.919721 -240.405874) (xy 126.955973 -240.444945) (xy 126.985997 -240.488982) (xy 127.009123 -240.537003)
			(xy 127.024833 -240.587933) (xy 127.032776 -240.640637) (xy 127.033274 -240.667286) (xy 127.032776 -240.693935)
			(xy 127.261356 -240.693935) (xy 127.261356 -240.640637) (xy 127.269299 -240.587933) (xy 127.285009 -240.537003)
			(xy 127.308135 -240.488982) (xy 127.338159 -240.444945) (xy 127.374411 -240.405874) (xy 127.416082 -240.372643)
			(xy 127.46224 -240.345994) (xy 127.511854 -240.326522) (xy 127.563816 -240.314662) (xy 127.616966 -240.310679)
			(xy 127.670116 -240.314662) (xy 127.722078 -240.326522) (xy 127.771692 -240.345994) (xy 127.81785 -240.372643)
			(xy 127.859521 -240.405874) (xy 127.895773 -240.444945) (xy 127.925797 -240.488982) (xy 127.948923 -240.537003)
			(xy 127.964633 -240.587933) (xy 127.972576 -240.640637) (xy 127.973074 -240.667286) (xy 127.972576 -240.693935)
			(xy 128.201156 -240.693935) (xy 128.201156 -240.640637) (xy 128.209099 -240.587933) (xy 128.224809 -240.537003)
			(xy 128.247935 -240.488982) (xy 128.277959 -240.444945) (xy 128.314211 -240.405874) (xy 128.355882 -240.372643)
			(xy 128.40204 -240.345994) (xy 128.451654 -240.326522) (xy 128.503616 -240.314662) (xy 128.556766 -240.310679)
			(xy 128.609916 -240.314662) (xy 128.661878 -240.326522) (xy 128.711492 -240.345994) (xy 128.75765 -240.372643)
			(xy 128.799321 -240.405874) (xy 128.835573 -240.444945) (xy 128.865597 -240.488982) (xy 128.888723 -240.537003)
			(xy 128.904433 -240.587933) (xy 128.912376 -240.640637) (xy 128.912874 -240.667286) (xy 128.912376 -240.693935)
			(xy 129.140956 -240.693935) (xy 129.140956 -240.640637) (xy 129.148899 -240.587933) (xy 129.164609 -240.537003)
			(xy 129.187735 -240.488982) (xy 129.217759 -240.444945) (xy 129.254011 -240.405874) (xy 129.295682 -240.372643)
			(xy 129.34184 -240.345994) (xy 129.391454 -240.326522) (xy 129.443416 -240.314662) (xy 129.496566 -240.310679)
			(xy 129.549716 -240.314662) (xy 129.601678 -240.326522) (xy 129.651292 -240.345994) (xy 129.69745 -240.372643)
			(xy 129.739121 -240.405874) (xy 129.775373 -240.444945) (xy 129.805397 -240.488982) (xy 129.828523 -240.537003)
			(xy 129.844233 -240.587933) (xy 129.852176 -240.640637) (xy 129.852674 -240.667286) (xy 129.852176 -240.693935)
			(xy 130.080756 -240.693935) (xy 130.080756 -240.640637) (xy 130.088699 -240.587933) (xy 130.104409 -240.537003)
			(xy 130.127535 -240.488982) (xy 130.157559 -240.444945) (xy 130.193811 -240.405874) (xy 130.235482 -240.372643)
			(xy 130.28164 -240.345994) (xy 130.331254 -240.326522) (xy 130.383216 -240.314662) (xy 130.436366 -240.310679)
			(xy 130.489516 -240.314662) (xy 130.541478 -240.326522) (xy 130.591092 -240.345994) (xy 130.63725 -240.372643)
			(xy 130.678921 -240.405874) (xy 130.715173 -240.444945) (xy 130.745197 -240.488982) (xy 130.768323 -240.537003)
			(xy 130.784033 -240.587933) (xy 130.791976 -240.640637) (xy 130.792474 -240.667286) (xy 130.791976 -240.693935)
			(xy 131.020556 -240.693935) (xy 131.020556 -240.640637) (xy 131.028499 -240.587933) (xy 131.044209 -240.537003)
			(xy 131.067335 -240.488982) (xy 131.097359 -240.444945) (xy 131.133611 -240.405874) (xy 131.175282 -240.372643)
			(xy 131.22144 -240.345994) (xy 131.271054 -240.326522) (xy 131.323016 -240.314662) (xy 131.376166 -240.310679)
			(xy 131.429316 -240.314662) (xy 131.481278 -240.326522) (xy 131.530892 -240.345994) (xy 131.57705 -240.372643)
			(xy 131.618721 -240.405874) (xy 131.654973 -240.444945) (xy 131.684997 -240.488982) (xy 131.708123 -240.537003)
			(xy 131.723833 -240.587933) (xy 131.731776 -240.640637) (xy 131.732274 -240.667286) (xy 131.731776 -240.693935)
			(xy 131.960102 -240.693935) (xy 131.960102 -240.640637) (xy 131.968045 -240.587933) (xy 131.983755 -240.537003)
			(xy 132.006881 -240.488982) (xy 132.036905 -240.444945) (xy 132.073157 -240.405874) (xy 132.114828 -240.372643)
			(xy 132.160986 -240.345994) (xy 132.2106 -240.326522) (xy 132.262562 -240.314662) (xy 132.315712 -240.310679)
			(xy 132.368862 -240.314662) (xy 132.420824 -240.326522) (xy 132.470438 -240.345994) (xy 132.516596 -240.372643)
			(xy 132.558267 -240.405874) (xy 132.594519 -240.444945) (xy 132.624543 -240.488982) (xy 132.647669 -240.537003)
			(xy 132.663379 -240.587933) (xy 132.671322 -240.640637) (xy 132.67182 -240.667286) (xy 132.671322 -240.693935)
			(xy 132.900156 -240.693935) (xy 132.900156 -240.640637) (xy 132.908099 -240.587933) (xy 132.923809 -240.537003)
			(xy 132.946935 -240.488982) (xy 132.976959 -240.444945) (xy 133.013211 -240.405874) (xy 133.054882 -240.372643)
			(xy 133.10104 -240.345994) (xy 133.150654 -240.326522) (xy 133.202616 -240.314662) (xy 133.255766 -240.310679)
			(xy 133.308916 -240.314662) (xy 133.360878 -240.326522) (xy 133.410492 -240.345994) (xy 133.45665 -240.372643)
			(xy 133.498321 -240.405874) (xy 133.534573 -240.444945) (xy 133.564597 -240.488982) (xy 133.587723 -240.537003)
			(xy 133.603433 -240.587933) (xy 133.611376 -240.640637) (xy 133.611874 -240.667286) (xy 133.611376 -240.693935)
			(xy 133.839956 -240.693935) (xy 133.839956 -240.640637) (xy 133.847899 -240.587933) (xy 133.863609 -240.537003)
			(xy 133.886735 -240.488982) (xy 133.916759 -240.444945) (xy 133.953011 -240.405874) (xy 133.994682 -240.372643)
			(xy 134.04084 -240.345994) (xy 134.090454 -240.326522) (xy 134.142416 -240.314662) (xy 134.195566 -240.310679)
			(xy 134.248716 -240.314662) (xy 134.300678 -240.326522) (xy 134.350292 -240.345994) (xy 134.39645 -240.372643)
			(xy 134.438121 -240.405874) (xy 134.474373 -240.444945) (xy 134.504397 -240.488982) (xy 134.527523 -240.537003)
			(xy 134.543233 -240.587933) (xy 134.551176 -240.640637) (xy 134.551674 -240.667286) (xy 134.551176 -240.693935)
			(xy 134.543233 -240.746639) (xy 134.527523 -240.797569) (xy 134.504397 -240.84559) (xy 134.474373 -240.889627)
			(xy 134.438121 -240.928698) (xy 134.39645 -240.961929) (xy 134.350292 -240.988578) (xy 134.300678 -241.00805)
			(xy 134.248716 -241.01991) (xy 134.195566 -241.023894) (xy 134.142416 -241.01991) (xy 134.090454 -241.00805)
			(xy 134.04084 -240.988578) (xy 133.994682 -240.961929) (xy 133.953011 -240.928698) (xy 133.916759 -240.889627)
			(xy 133.886735 -240.84559) (xy 133.863609 -240.797569) (xy 133.847899 -240.746639) (xy 133.839956 -240.693935)
			(xy 133.611376 -240.693935) (xy 133.603433 -240.746639) (xy 133.587723 -240.797569) (xy 133.564597 -240.84559)
			(xy 133.534573 -240.889627) (xy 133.498321 -240.928698) (xy 133.45665 -240.961929) (xy 133.410492 -240.988578)
			(xy 133.360878 -241.00805) (xy 133.308916 -241.01991) (xy 133.255766 -241.023894) (xy 133.202616 -241.01991)
			(xy 133.150654 -241.00805) (xy 133.10104 -240.988578) (xy 133.054882 -240.961929) (xy 133.013211 -240.928698)
			(xy 132.976959 -240.889627) (xy 132.946935 -240.84559) (xy 132.923809 -240.797569) (xy 132.908099 -240.746639)
			(xy 132.900156 -240.693935) (xy 132.671322 -240.693935) (xy 132.663379 -240.746639) (xy 132.647669 -240.797569)
			(xy 132.624543 -240.84559) (xy 132.594519 -240.889627) (xy 132.558267 -240.928698) (xy 132.516596 -240.961929)
			(xy 132.470438 -240.988578) (xy 132.420824 -241.00805) (xy 132.368862 -241.01991) (xy 132.315712 -241.023894)
			(xy 132.262562 -241.01991) (xy 132.2106 -241.00805) (xy 132.160986 -240.988578) (xy 132.114828 -240.961929)
			(xy 132.073157 -240.928698) (xy 132.036905 -240.889627) (xy 132.006881 -240.84559) (xy 131.983755 -240.797569)
			(xy 131.968045 -240.746639) (xy 131.960102 -240.693935) (xy 131.731776 -240.693935) (xy 131.723833 -240.746639)
			(xy 131.708123 -240.797569) (xy 131.684997 -240.84559) (xy 131.654973 -240.889627) (xy 131.618721 -240.928698)
			(xy 131.57705 -240.961929) (xy 131.530892 -240.988578) (xy 131.481278 -241.00805) (xy 131.429316 -241.01991)
			(xy 131.376166 -241.023894) (xy 131.323016 -241.01991) (xy 131.271054 -241.00805) (xy 131.22144 -240.988578)
			(xy 131.175282 -240.961929) (xy 131.133611 -240.928698) (xy 131.097359 -240.889627) (xy 131.067335 -240.84559)
			(xy 131.044209 -240.797569) (xy 131.028499 -240.746639) (xy 131.020556 -240.693935) (xy 130.791976 -240.693935)
			(xy 130.784033 -240.746639) (xy 130.768323 -240.797569) (xy 130.745197 -240.84559) (xy 130.715173 -240.889627)
			(xy 130.678921 -240.928698) (xy 130.63725 -240.961929) (xy 130.591092 -240.988578) (xy 130.541478 -241.00805)
			(xy 130.489516 -241.01991) (xy 130.436366 -241.023894) (xy 130.383216 -241.01991) (xy 130.331254 -241.00805)
			(xy 130.28164 -240.988578) (xy 130.235482 -240.961929) (xy 130.193811 -240.928698) (xy 130.157559 -240.889627)
			(xy 130.127535 -240.84559) (xy 130.104409 -240.797569) (xy 130.088699 -240.746639) (xy 130.080756 -240.693935)
			(xy 129.852176 -240.693935) (xy 129.844233 -240.746639) (xy 129.828523 -240.797569) (xy 129.805397 -240.84559)
			(xy 129.775373 -240.889627) (xy 129.739121 -240.928698) (xy 129.69745 -240.961929) (xy 129.651292 -240.988578)
			(xy 129.601678 -241.00805) (xy 129.549716 -241.01991) (xy 129.496566 -241.023894) (xy 129.443416 -241.01991)
			(xy 129.391454 -241.00805) (xy 129.34184 -240.988578) (xy 129.295682 -240.961929) (xy 129.254011 -240.928698)
			(xy 129.217759 -240.889627) (xy 129.187735 -240.84559) (xy 129.164609 -240.797569) (xy 129.148899 -240.746639)
			(xy 129.140956 -240.693935) (xy 128.912376 -240.693935) (xy 128.904433 -240.746639) (xy 128.888723 -240.797569)
			(xy 128.865597 -240.84559) (xy 128.835573 -240.889627) (xy 128.799321 -240.928698) (xy 128.75765 -240.961929)
			(xy 128.711492 -240.988578) (xy 128.661878 -241.00805) (xy 128.609916 -241.01991) (xy 128.556766 -241.023894)
			(xy 128.503616 -241.01991) (xy 128.451654 -241.00805) (xy 128.40204 -240.988578) (xy 128.355882 -240.961929)
			(xy 128.314211 -240.928698) (xy 128.277959 -240.889627) (xy 128.247935 -240.84559) (xy 128.224809 -240.797569)
			(xy 128.209099 -240.746639) (xy 128.201156 -240.693935) (xy 127.972576 -240.693935) (xy 127.964633 -240.746639)
			(xy 127.948923 -240.797569) (xy 127.925797 -240.84559) (xy 127.895773 -240.889627) (xy 127.859521 -240.928698)
			(xy 127.81785 -240.961929) (xy 127.771692 -240.988578) (xy 127.722078 -241.00805) (xy 127.670116 -241.01991)
			(xy 127.616966 -241.023894) (xy 127.563816 -241.01991) (xy 127.511854 -241.00805) (xy 127.46224 -240.988578)
			(xy 127.416082 -240.961929) (xy 127.374411 -240.928698) (xy 127.338159 -240.889627) (xy 127.308135 -240.84559)
			(xy 127.285009 -240.797569) (xy 127.269299 -240.746639) (xy 127.261356 -240.693935) (xy 127.032776 -240.693935)
			(xy 127.024833 -240.746639) (xy 127.009123 -240.797569) (xy 126.985997 -240.84559) (xy 126.955973 -240.889627)
			(xy 126.919721 -240.928698) (xy 126.87805 -240.961929) (xy 126.831892 -240.988578) (xy 126.782278 -241.00805)
			(xy 126.730316 -241.01991) (xy 126.677166 -241.023894) (xy 126.624016 -241.01991) (xy 126.572054 -241.00805)
			(xy 126.52244 -240.988578) (xy 126.476282 -240.961929) (xy 126.434611 -240.928698) (xy 126.398359 -240.889627)
			(xy 126.368335 -240.84559) (xy 126.345209 -240.797569) (xy 126.329499 -240.746639) (xy 126.321556 -240.693935)
			(xy 126.092722 -240.693935) (xy 126.084779 -240.746639) (xy 126.069069 -240.797569) (xy 126.045943 -240.84559)
			(xy 126.015919 -240.889627) (xy 125.979667 -240.928698) (xy 125.937996 -240.961929) (xy 125.891838 -240.988578)
			(xy 125.842224 -241.00805) (xy 125.790262 -241.01991) (xy 125.737112 -241.023894) (xy 125.683962 -241.01991)
			(xy 125.632 -241.00805) (xy 125.582386 -240.988578) (xy 125.536228 -240.961929) (xy 125.494557 -240.928698)
			(xy 125.458305 -240.889627) (xy 125.428281 -240.84559) (xy 125.405155 -240.797569) (xy 125.389445 -240.746639)
			(xy 125.381502 -240.693935) (xy 125.153176 -240.693935) (xy 125.145233 -240.746639) (xy 125.129523 -240.797569)
			(xy 125.106397 -240.84559) (xy 125.076373 -240.889627) (xy 125.040121 -240.928698) (xy 124.99845 -240.961929)
			(xy 124.952292 -240.988578) (xy 124.902678 -241.00805) (xy 124.850716 -241.01991) (xy 124.797566 -241.023894)
			(xy 124.744416 -241.01991) (xy 124.692454 -241.00805) (xy 124.64284 -240.988578) (xy 124.596682 -240.961929)
			(xy 124.555011 -240.928698) (xy 124.518759 -240.889627) (xy 124.488735 -240.84559) (xy 124.465609 -240.797569)
			(xy 124.449899 -240.746639) (xy 124.441956 -240.693935) (xy 124.213376 -240.693935) (xy 124.205433 -240.746639)
			(xy 124.189723 -240.797569) (xy 124.166597 -240.84559) (xy 124.136573 -240.889627) (xy 124.100321 -240.928698)
			(xy 124.05865 -240.961929) (xy 124.012492 -240.988578) (xy 123.962878 -241.00805) (xy 123.910916 -241.01991)
			(xy 123.857766 -241.023894) (xy 123.804616 -241.01991) (xy 123.752654 -241.00805) (xy 123.70304 -240.988578)
			(xy 123.656882 -240.961929) (xy 123.615211 -240.928698) (xy 123.578959 -240.889627) (xy 123.548935 -240.84559)
			(xy 123.525809 -240.797569) (xy 123.510099 -240.746639) (xy 123.502156 -240.693935) (xy 123.273322 -240.693935)
			(xy 123.265379 -240.746639) (xy 123.249669 -240.797569) (xy 123.226543 -240.84559) (xy 123.196519 -240.889627)
			(xy 123.160267 -240.928698) (xy 123.118596 -240.961929) (xy 123.072438 -240.988578) (xy 123.022824 -241.00805)
			(xy 122.970862 -241.01991) (xy 122.917712 -241.023894) (xy 122.864562 -241.01991) (xy 122.8126 -241.00805)
			(xy 122.762986 -240.988578) (xy 122.716828 -240.961929) (xy 122.675157 -240.928698) (xy 122.638905 -240.889627)
			(xy 122.608881 -240.84559) (xy 122.585755 -240.797569) (xy 122.570045 -240.746639) (xy 122.562102 -240.693935)
			(xy 122.333776 -240.693935) (xy 122.325833 -240.746639) (xy 122.310123 -240.797569) (xy 122.286997 -240.84559)
			(xy 122.256973 -240.889627) (xy 122.220721 -240.928698) (xy 122.17905 -240.961929) (xy 122.132892 -240.988578)
			(xy 122.083278 -241.00805) (xy 122.031316 -241.01991) (xy 121.978166 -241.023894) (xy 121.925016 -241.01991)
			(xy 121.873054 -241.00805) (xy 121.82344 -240.988578) (xy 121.777282 -240.961929) (xy 121.735611 -240.928698)
			(xy 121.699359 -240.889627) (xy 121.669335 -240.84559) (xy 121.646209 -240.797569) (xy 121.630499 -240.746639)
			(xy 121.622556 -240.693935) (xy 121.305667 -240.693935) (xy 121.305828 -240.70437) (xy 121.305342 -240.731225)
			(xy 121.297281 -240.784326) (xy 121.281337 -240.835614) (xy 121.257873 -240.883927) (xy 121.22742 -240.928169)
			(xy 121.190668 -240.967335) (xy 121.148452 -241.000539) (xy 121.101728 -241.027027) (xy 121.051557 -241.046198)
			(xy 121.025412 -241.05235) (xy 120.98528 -241.060986) (xy 120.98528 -241.507751) (xy 121.152402 -241.507751)
			(xy 121.152402 -241.454453) (xy 121.160345 -241.401749) (xy 121.176055 -241.350819) (xy 121.199181 -241.302798)
			(xy 121.229205 -241.258761) (xy 121.265457 -241.21969) (xy 121.307128 -241.186459) (xy 121.353286 -241.15981)
			(xy 121.4029 -241.140338) (xy 121.454862 -241.128478) (xy 121.508012 -241.124495) (xy 121.561162 -241.128478)
			(xy 121.613124 -241.140338) (xy 121.662738 -241.15981) (xy 121.708896 -241.186459) (xy 121.750567 -241.21969)
			(xy 121.786819 -241.258761) (xy 121.816843 -241.302798) (xy 121.839969 -241.350819) (xy 121.855679 -241.401749)
			(xy 121.863622 -241.454453) (xy 121.86412 -241.481102) (xy 121.863622 -241.507751) (xy 122.092456 -241.507751)
			(xy 122.092456 -241.454453) (xy 122.100399 -241.401749) (xy 122.116109 -241.350819) (xy 122.139235 -241.302798)
			(xy 122.169259 -241.258761) (xy 122.205511 -241.21969) (xy 122.247182 -241.186459) (xy 122.29334 -241.15981)
			(xy 122.342954 -241.140338) (xy 122.394916 -241.128478) (xy 122.448066 -241.124495) (xy 122.501216 -241.128478)
			(xy 122.553178 -241.140338) (xy 122.602792 -241.15981) (xy 122.64895 -241.186459) (xy 122.690621 -241.21969)
			(xy 122.726873 -241.258761) (xy 122.756897 -241.302798) (xy 122.780023 -241.350819) (xy 122.795733 -241.401749)
			(xy 122.803676 -241.454453) (xy 122.804174 -241.481102) (xy 122.803676 -241.507751) (xy 123.032002 -241.507751)
			(xy 123.032002 -241.454453) (xy 123.039945 -241.401749) (xy 123.055655 -241.350819) (xy 123.078781 -241.302798)
			(xy 123.108805 -241.258761) (xy 123.145057 -241.21969) (xy 123.186728 -241.186459) (xy 123.232886 -241.15981)
			(xy 123.2825 -241.140338) (xy 123.334462 -241.128478) (xy 123.387612 -241.124495) (xy 123.440762 -241.128478)
			(xy 123.492724 -241.140338) (xy 123.542338 -241.15981) (xy 123.588496 -241.186459) (xy 123.630167 -241.21969)
			(xy 123.666419 -241.258761) (xy 123.696443 -241.302798) (xy 123.719569 -241.350819) (xy 123.735279 -241.401749)
			(xy 123.743222 -241.454453) (xy 123.74372 -241.481102) (xy 123.743222 -241.507751) (xy 123.971802 -241.507751)
			(xy 123.971802 -241.454453) (xy 123.979745 -241.401749) (xy 123.995455 -241.350819) (xy 124.018581 -241.302798)
			(xy 124.048605 -241.258761) (xy 124.084857 -241.21969) (xy 124.126528 -241.186459) (xy 124.172686 -241.15981)
			(xy 124.2223 -241.140338) (xy 124.274262 -241.128478) (xy 124.327412 -241.124495) (xy 124.380562 -241.128478)
			(xy 124.432524 -241.140338) (xy 124.482138 -241.15981) (xy 124.528296 -241.186459) (xy 124.569967 -241.21969)
			(xy 124.606219 -241.258761) (xy 124.636243 -241.302798) (xy 124.659369 -241.350819) (xy 124.675079 -241.401749)
			(xy 124.683022 -241.454453) (xy 124.68352 -241.481102) (xy 124.683022 -241.507751) (xy 124.911602 -241.507751)
			(xy 124.911602 -241.454453) (xy 124.919545 -241.401749) (xy 124.935255 -241.350819) (xy 124.958381 -241.302798)
			(xy 124.988405 -241.258761) (xy 125.024657 -241.21969) (xy 125.066328 -241.186459) (xy 125.112486 -241.15981)
			(xy 125.1621 -241.140338) (xy 125.214062 -241.128478) (xy 125.267212 -241.124495) (xy 125.320362 -241.128478)
			(xy 125.372324 -241.140338) (xy 125.421938 -241.15981) (xy 125.468096 -241.186459) (xy 125.509767 -241.21969)
			(xy 125.546019 -241.258761) (xy 125.576043 -241.302798) (xy 125.599169 -241.350819) (xy 125.614879 -241.401749)
			(xy 125.622822 -241.454453) (xy 125.62332 -241.481102) (xy 125.622822 -241.507751) (xy 125.851402 -241.507751)
			(xy 125.851402 -241.454453) (xy 125.859345 -241.401749) (xy 125.875055 -241.350819) (xy 125.898181 -241.302798)
			(xy 125.928205 -241.258761) (xy 125.964457 -241.21969) (xy 126.006128 -241.186459) (xy 126.052286 -241.15981)
			(xy 126.1019 -241.140338) (xy 126.153862 -241.128478) (xy 126.207012 -241.124495) (xy 126.260162 -241.128478)
			(xy 126.312124 -241.140338) (xy 126.361738 -241.15981) (xy 126.407896 -241.186459) (xy 126.449567 -241.21969)
			(xy 126.485819 -241.258761) (xy 126.515843 -241.302798) (xy 126.538969 -241.350819) (xy 126.554679 -241.401749)
			(xy 126.562622 -241.454453) (xy 126.56312 -241.481102) (xy 126.562622 -241.507751) (xy 126.791202 -241.507751)
			(xy 126.791202 -241.454453) (xy 126.799145 -241.401749) (xy 126.814855 -241.350819) (xy 126.837981 -241.302798)
			(xy 126.868005 -241.258761) (xy 126.904257 -241.21969) (xy 126.945928 -241.186459) (xy 126.992086 -241.15981)
			(xy 127.0417 -241.140338) (xy 127.093662 -241.128478) (xy 127.146812 -241.124495) (xy 127.199962 -241.128478)
			(xy 127.251924 -241.140338) (xy 127.301538 -241.15981) (xy 127.347696 -241.186459) (xy 127.389367 -241.21969)
			(xy 127.425619 -241.258761) (xy 127.455643 -241.302798) (xy 127.478769 -241.350819) (xy 127.494479 -241.401749)
			(xy 127.502422 -241.454453) (xy 127.50292 -241.481102) (xy 127.502422 -241.507751) (xy 127.731002 -241.507751)
			(xy 127.731002 -241.454453) (xy 127.738945 -241.401749) (xy 127.754655 -241.350819) (xy 127.777781 -241.302798)
			(xy 127.807805 -241.258761) (xy 127.844057 -241.21969) (xy 127.885728 -241.186459) (xy 127.931886 -241.15981)
			(xy 127.9815 -241.140338) (xy 128.033462 -241.128478) (xy 128.086612 -241.124495) (xy 128.139762 -241.128478)
			(xy 128.191724 -241.140338) (xy 128.241338 -241.15981) (xy 128.287496 -241.186459) (xy 128.329167 -241.21969)
			(xy 128.365419 -241.258761) (xy 128.395443 -241.302798) (xy 128.418569 -241.350819) (xy 128.434279 -241.401749)
			(xy 128.442222 -241.454453) (xy 128.44272 -241.481102) (xy 128.442222 -241.507751) (xy 128.671056 -241.507751)
			(xy 128.671056 -241.454453) (xy 128.678999 -241.401749) (xy 128.694709 -241.350819) (xy 128.717835 -241.302798)
			(xy 128.747859 -241.258761) (xy 128.784111 -241.21969) (xy 128.825782 -241.186459) (xy 128.87194 -241.15981)
			(xy 128.921554 -241.140338) (xy 128.973516 -241.128478) (xy 129.026666 -241.124495) (xy 129.079816 -241.128478)
			(xy 129.131778 -241.140338) (xy 129.181392 -241.15981) (xy 129.22755 -241.186459) (xy 129.269221 -241.21969)
			(xy 129.305473 -241.258761) (xy 129.335497 -241.302798) (xy 129.358623 -241.350819) (xy 129.374333 -241.401749)
			(xy 129.382276 -241.454453) (xy 129.382774 -241.481102) (xy 129.382276 -241.507751) (xy 129.610602 -241.507751)
			(xy 129.610602 -241.454453) (xy 129.618545 -241.401749) (xy 129.634255 -241.350819) (xy 129.657381 -241.302798)
			(xy 129.687405 -241.258761) (xy 129.723657 -241.21969) (xy 129.765328 -241.186459) (xy 129.811486 -241.15981)
			(xy 129.8611 -241.140338) (xy 129.913062 -241.128478) (xy 129.966212 -241.124495) (xy 130.019362 -241.128478)
			(xy 130.071324 -241.140338) (xy 130.120938 -241.15981) (xy 130.167096 -241.186459) (xy 130.208767 -241.21969)
			(xy 130.245019 -241.258761) (xy 130.275043 -241.302798) (xy 130.298169 -241.350819) (xy 130.313879 -241.401749)
			(xy 130.321822 -241.454453) (xy 130.32232 -241.481102) (xy 130.321822 -241.507751) (xy 130.550402 -241.507751)
			(xy 130.550402 -241.454453) (xy 130.558345 -241.401749) (xy 130.574055 -241.350819) (xy 130.597181 -241.302798)
			(xy 130.627205 -241.258761) (xy 130.663457 -241.21969) (xy 130.705128 -241.186459) (xy 130.751286 -241.15981)
			(xy 130.8009 -241.140338) (xy 130.852862 -241.128478) (xy 130.906012 -241.124495) (xy 130.959162 -241.128478)
			(xy 131.011124 -241.140338) (xy 131.060738 -241.15981) (xy 131.106896 -241.186459) (xy 131.148567 -241.21969)
			(xy 131.184819 -241.258761) (xy 131.214843 -241.302798) (xy 131.237969 -241.350819) (xy 131.253679 -241.401749)
			(xy 131.261622 -241.454453) (xy 131.26212 -241.481102) (xy 131.261622 -241.507751) (xy 131.490202 -241.507751)
			(xy 131.490202 -241.454453) (xy 131.498145 -241.401749) (xy 131.513855 -241.350819) (xy 131.536981 -241.302798)
			(xy 131.567005 -241.258761) (xy 131.603257 -241.21969) (xy 131.644928 -241.186459) (xy 131.691086 -241.15981)
			(xy 131.7407 -241.140338) (xy 131.792662 -241.128478) (xy 131.845812 -241.124495) (xy 131.898962 -241.128478)
			(xy 131.950924 -241.140338) (xy 132.000538 -241.15981) (xy 132.046696 -241.186459) (xy 132.088367 -241.21969)
			(xy 132.124619 -241.258761) (xy 132.154643 -241.302798) (xy 132.177769 -241.350819) (xy 132.193479 -241.401749)
			(xy 132.201422 -241.454453) (xy 132.20192 -241.481102) (xy 132.201422 -241.507751) (xy 132.430002 -241.507751)
			(xy 132.430002 -241.454453) (xy 132.437945 -241.401749) (xy 132.453655 -241.350819) (xy 132.476781 -241.302798)
			(xy 132.506805 -241.258761) (xy 132.543057 -241.21969) (xy 132.584728 -241.186459) (xy 132.630886 -241.15981)
			(xy 132.6805 -241.140338) (xy 132.732462 -241.128478) (xy 132.785612 -241.124495) (xy 132.838762 -241.128478)
			(xy 132.890724 -241.140338) (xy 132.940338 -241.15981) (xy 132.986496 -241.186459) (xy 133.028167 -241.21969)
			(xy 133.064419 -241.258761) (xy 133.094443 -241.302798) (xy 133.117569 -241.350819) (xy 133.133279 -241.401749)
			(xy 133.141222 -241.454453) (xy 133.14172 -241.481102) (xy 133.141222 -241.507751) (xy 133.370056 -241.507751)
			(xy 133.370056 -241.454453) (xy 133.377999 -241.401749) (xy 133.393709 -241.350819) (xy 133.416835 -241.302798)
			(xy 133.446859 -241.258761) (xy 133.483111 -241.21969) (xy 133.524782 -241.186459) (xy 133.57094 -241.15981)
			(xy 133.620554 -241.140338) (xy 133.672516 -241.128478) (xy 133.725666 -241.124495) (xy 133.778816 -241.128478)
			(xy 133.830778 -241.140338) (xy 133.880392 -241.15981) (xy 133.92655 -241.186459) (xy 133.968221 -241.21969)
			(xy 134.004473 -241.258761) (xy 134.034497 -241.302798) (xy 134.057623 -241.350819) (xy 134.073333 -241.401749)
			(xy 134.081276 -241.454453) (xy 134.081774 -241.481102) (xy 134.081276 -241.507751) (xy 134.309602 -241.507751)
			(xy 134.309602 -241.454453) (xy 134.317545 -241.401749) (xy 134.333255 -241.350819) (xy 134.356381 -241.302798)
			(xy 134.386405 -241.258761) (xy 134.422657 -241.21969) (xy 134.464328 -241.186459) (xy 134.510486 -241.15981)
			(xy 134.5601 -241.140338) (xy 134.612062 -241.128478) (xy 134.665212 -241.124495) (xy 134.718362 -241.128478)
			(xy 134.770324 -241.140338) (xy 134.819938 -241.15981) (xy 134.866096 -241.186459) (xy 134.907767 -241.21969)
			(xy 134.944019 -241.258761) (xy 134.974043 -241.302798) (xy 134.997169 -241.350819) (xy 135.012879 -241.401749)
			(xy 135.020822 -241.454453) (xy 135.02132 -241.481102) (xy 135.020822 -241.507751) (xy 135.012879 -241.560455)
			(xy 134.997169 -241.611385) (xy 134.974043 -241.659406) (xy 134.944019 -241.703443) (xy 134.907767 -241.742514)
			(xy 134.866096 -241.775745) (xy 134.819938 -241.802394) (xy 134.770324 -241.821866) (xy 134.718362 -241.833726)
			(xy 134.665212 -241.83771) (xy 134.612062 -241.833726) (xy 134.5601 -241.821866) (xy 134.510486 -241.802394)
			(xy 134.464328 -241.775745) (xy 134.422657 -241.742514) (xy 134.386405 -241.703443) (xy 134.356381 -241.659406)
			(xy 134.333255 -241.611385) (xy 134.317545 -241.560455) (xy 134.309602 -241.507751) (xy 134.081276 -241.507751)
			(xy 134.073333 -241.560455) (xy 134.057623 -241.611385) (xy 134.034497 -241.659406) (xy 134.004473 -241.703443)
			(xy 133.968221 -241.742514) (xy 133.92655 -241.775745) (xy 133.880392 -241.802394) (xy 133.830778 -241.821866)
			(xy 133.778816 -241.833726) (xy 133.725666 -241.83771) (xy 133.672516 -241.833726) (xy 133.620554 -241.821866)
			(xy 133.57094 -241.802394) (xy 133.524782 -241.775745) (xy 133.483111 -241.742514) (xy 133.446859 -241.703443)
			(xy 133.416835 -241.659406) (xy 133.393709 -241.611385) (xy 133.377999 -241.560455) (xy 133.370056 -241.507751)
			(xy 133.141222 -241.507751) (xy 133.133279 -241.560455) (xy 133.117569 -241.611385) (xy 133.094443 -241.659406)
			(xy 133.064419 -241.703443) (xy 133.028167 -241.742514) (xy 132.986496 -241.775745) (xy 132.940338 -241.802394)
			(xy 132.890724 -241.821866) (xy 132.838762 -241.833726) (xy 132.785612 -241.83771) (xy 132.732462 -241.833726)
			(xy 132.6805 -241.821866) (xy 132.630886 -241.802394) (xy 132.584728 -241.775745) (xy 132.543057 -241.742514)
			(xy 132.506805 -241.703443) (xy 132.476781 -241.659406) (xy 132.453655 -241.611385) (xy 132.437945 -241.560455)
			(xy 132.430002 -241.507751) (xy 132.201422 -241.507751) (xy 132.193479 -241.560455) (xy 132.177769 -241.611385)
			(xy 132.154643 -241.659406) (xy 132.124619 -241.703443) (xy 132.088367 -241.742514) (xy 132.046696 -241.775745)
			(xy 132.000538 -241.802394) (xy 131.950924 -241.821866) (xy 131.898962 -241.833726) (xy 131.845812 -241.83771)
			(xy 131.792662 -241.833726) (xy 131.7407 -241.821866) (xy 131.691086 -241.802394) (xy 131.644928 -241.775745)
			(xy 131.603257 -241.742514) (xy 131.567005 -241.703443) (xy 131.536981 -241.659406) (xy 131.513855 -241.611385)
			(xy 131.498145 -241.560455) (xy 131.490202 -241.507751) (xy 131.261622 -241.507751) (xy 131.253679 -241.560455)
			(xy 131.237969 -241.611385) (xy 131.214843 -241.659406) (xy 131.184819 -241.703443) (xy 131.148567 -241.742514)
			(xy 131.106896 -241.775745) (xy 131.060738 -241.802394) (xy 131.011124 -241.821866) (xy 130.959162 -241.833726)
			(xy 130.906012 -241.83771) (xy 130.852862 -241.833726) (xy 130.8009 -241.821866) (xy 130.751286 -241.802394)
			(xy 130.705128 -241.775745) (xy 130.663457 -241.742514) (xy 130.627205 -241.703443) (xy 130.597181 -241.659406)
			(xy 130.574055 -241.611385) (xy 130.558345 -241.560455) (xy 130.550402 -241.507751) (xy 130.321822 -241.507751)
			(xy 130.313879 -241.560455) (xy 130.298169 -241.611385) (xy 130.275043 -241.659406) (xy 130.245019 -241.703443)
			(xy 130.208767 -241.742514) (xy 130.167096 -241.775745) (xy 130.120938 -241.802394) (xy 130.071324 -241.821866)
			(xy 130.019362 -241.833726) (xy 129.966212 -241.83771) (xy 129.913062 -241.833726) (xy 129.8611 -241.821866)
			(xy 129.811486 -241.802394) (xy 129.765328 -241.775745) (xy 129.723657 -241.742514) (xy 129.687405 -241.703443)
			(xy 129.657381 -241.659406) (xy 129.634255 -241.611385) (xy 129.618545 -241.560455) (xy 129.610602 -241.507751)
			(xy 129.382276 -241.507751) (xy 129.374333 -241.560455) (xy 129.358623 -241.611385) (xy 129.335497 -241.659406)
			(xy 129.305473 -241.703443) (xy 129.269221 -241.742514) (xy 129.22755 -241.775745) (xy 129.181392 -241.802394)
			(xy 129.131778 -241.821866) (xy 129.079816 -241.833726) (xy 129.026666 -241.83771) (xy 128.973516 -241.833726)
			(xy 128.921554 -241.821866) (xy 128.87194 -241.802394) (xy 128.825782 -241.775745) (xy 128.784111 -241.742514)
			(xy 128.747859 -241.703443) (xy 128.717835 -241.659406) (xy 128.694709 -241.611385) (xy 128.678999 -241.560455)
			(xy 128.671056 -241.507751) (xy 128.442222 -241.507751) (xy 128.434279 -241.560455) (xy 128.418569 -241.611385)
			(xy 128.395443 -241.659406) (xy 128.365419 -241.703443) (xy 128.329167 -241.742514) (xy 128.287496 -241.775745)
			(xy 128.241338 -241.802394) (xy 128.191724 -241.821866) (xy 128.139762 -241.833726) (xy 128.086612 -241.83771)
			(xy 128.033462 -241.833726) (xy 127.9815 -241.821866) (xy 127.931886 -241.802394) (xy 127.885728 -241.775745)
			(xy 127.844057 -241.742514) (xy 127.807805 -241.703443) (xy 127.777781 -241.659406) (xy 127.754655 -241.611385)
			(xy 127.738945 -241.560455) (xy 127.731002 -241.507751) (xy 127.502422 -241.507751) (xy 127.494479 -241.560455)
			(xy 127.478769 -241.611385) (xy 127.455643 -241.659406) (xy 127.425619 -241.703443) (xy 127.389367 -241.742514)
			(xy 127.347696 -241.775745) (xy 127.301538 -241.802394) (xy 127.251924 -241.821866) (xy 127.199962 -241.833726)
			(xy 127.146812 -241.83771) (xy 127.093662 -241.833726) (xy 127.0417 -241.821866) (xy 126.992086 -241.802394)
			(xy 126.945928 -241.775745) (xy 126.904257 -241.742514) (xy 126.868005 -241.703443) (xy 126.837981 -241.659406)
			(xy 126.814855 -241.611385) (xy 126.799145 -241.560455) (xy 126.791202 -241.507751) (xy 126.562622 -241.507751)
			(xy 126.554679 -241.560455) (xy 126.538969 -241.611385) (xy 126.515843 -241.659406) (xy 126.485819 -241.703443)
			(xy 126.449567 -241.742514) (xy 126.407896 -241.775745) (xy 126.361738 -241.802394) (xy 126.312124 -241.821866)
			(xy 126.260162 -241.833726) (xy 126.207012 -241.83771) (xy 126.153862 -241.833726) (xy 126.1019 -241.821866)
			(xy 126.052286 -241.802394) (xy 126.006128 -241.775745) (xy 125.964457 -241.742514) (xy 125.928205 -241.703443)
			(xy 125.898181 -241.659406) (xy 125.875055 -241.611385) (xy 125.859345 -241.560455) (xy 125.851402 -241.507751)
			(xy 125.622822 -241.507751) (xy 125.614879 -241.560455) (xy 125.599169 -241.611385) (xy 125.576043 -241.659406)
			(xy 125.546019 -241.703443) (xy 125.509767 -241.742514) (xy 125.468096 -241.775745) (xy 125.421938 -241.802394)
			(xy 125.372324 -241.821866) (xy 125.320362 -241.833726) (xy 125.267212 -241.83771) (xy 125.214062 -241.833726)
			(xy 125.1621 -241.821866) (xy 125.112486 -241.802394) (xy 125.066328 -241.775745) (xy 125.024657 -241.742514)
			(xy 124.988405 -241.703443) (xy 124.958381 -241.659406) (xy 124.935255 -241.611385) (xy 124.919545 -241.560455)
			(xy 124.911602 -241.507751) (xy 124.683022 -241.507751) (xy 124.675079 -241.560455) (xy 124.659369 -241.611385)
			(xy 124.636243 -241.659406) (xy 124.606219 -241.703443) (xy 124.569967 -241.742514) (xy 124.528296 -241.775745)
			(xy 124.482138 -241.802394) (xy 124.432524 -241.821866) (xy 124.380562 -241.833726) (xy 124.327412 -241.83771)
			(xy 124.274262 -241.833726) (xy 124.2223 -241.821866) (xy 124.172686 -241.802394) (xy 124.126528 -241.775745)
			(xy 124.084857 -241.742514) (xy 124.048605 -241.703443) (xy 124.018581 -241.659406) (xy 123.995455 -241.611385)
			(xy 123.979745 -241.560455) (xy 123.971802 -241.507751) (xy 123.743222 -241.507751) (xy 123.735279 -241.560455)
			(xy 123.719569 -241.611385) (xy 123.696443 -241.659406) (xy 123.666419 -241.703443) (xy 123.630167 -241.742514)
			(xy 123.588496 -241.775745) (xy 123.542338 -241.802394) (xy 123.492724 -241.821866) (xy 123.440762 -241.833726)
			(xy 123.387612 -241.83771) (xy 123.334462 -241.833726) (xy 123.2825 -241.821866) (xy 123.232886 -241.802394)
			(xy 123.186728 -241.775745) (xy 123.145057 -241.742514) (xy 123.108805 -241.703443) (xy 123.078781 -241.659406)
			(xy 123.055655 -241.611385) (xy 123.039945 -241.560455) (xy 123.032002 -241.507751) (xy 122.803676 -241.507751)
			(xy 122.795733 -241.560455) (xy 122.780023 -241.611385) (xy 122.756897 -241.659406) (xy 122.726873 -241.703443)
			(xy 122.690621 -241.742514) (xy 122.64895 -241.775745) (xy 122.602792 -241.802394) (xy 122.553178 -241.821866)
			(xy 122.501216 -241.833726) (xy 122.448066 -241.83771) (xy 122.394916 -241.833726) (xy 122.342954 -241.821866)
			(xy 122.29334 -241.802394) (xy 122.247182 -241.775745) (xy 122.205511 -241.742514) (xy 122.169259 -241.703443)
			(xy 122.139235 -241.659406) (xy 122.116109 -241.611385) (xy 122.100399 -241.560455) (xy 122.092456 -241.507751)
			(xy 121.863622 -241.507751) (xy 121.855679 -241.560455) (xy 121.839969 -241.611385) (xy 121.816843 -241.659406)
			(xy 121.786819 -241.703443) (xy 121.750567 -241.742514) (xy 121.708896 -241.775745) (xy 121.662738 -241.802394)
			(xy 121.613124 -241.821866) (xy 121.561162 -241.833726) (xy 121.508012 -241.83771) (xy 121.454862 -241.833726)
			(xy 121.4029 -241.821866) (xy 121.353286 -241.802394) (xy 121.307128 -241.775745) (xy 121.265457 -241.742514)
			(xy 121.229205 -241.703443) (xy 121.199181 -241.659406) (xy 121.176055 -241.611385) (xy 121.160345 -241.560455)
			(xy 121.152402 -241.507751) (xy 120.98528 -241.507751) (xy 120.98528 -242.321567) (xy 121.622556 -242.321567)
			(xy 121.622556 -242.268269) (xy 121.630499 -242.215565) (xy 121.646209 -242.164635) (xy 121.669335 -242.116614)
			(xy 121.699359 -242.072577) (xy 121.735611 -242.033506) (xy 121.777282 -242.000275) (xy 121.82344 -241.973626)
			(xy 121.873054 -241.954154) (xy 121.925016 -241.942294) (xy 121.978166 -241.938311) (xy 122.031316 -241.942294)
			(xy 122.083278 -241.954154) (xy 122.132892 -241.973626) (xy 122.17905 -242.000275) (xy 122.220721 -242.033506)
			(xy 122.256973 -242.072577) (xy 122.286997 -242.116614) (xy 122.310123 -242.164635) (xy 122.325833 -242.215565)
			(xy 122.333776 -242.268269) (xy 122.334274 -242.294918) (xy 122.333776 -242.321567) (xy 122.562356 -242.321567)
			(xy 122.562356 -242.268269) (xy 122.570299 -242.215565) (xy 122.586009 -242.164635) (xy 122.609135 -242.116614)
			(xy 122.639159 -242.072577) (xy 122.675411 -242.033506) (xy 122.717082 -242.000275) (xy 122.76324 -241.973626)
			(xy 122.812854 -241.954154) (xy 122.864816 -241.942294) (xy 122.917966 -241.938311) (xy 122.971116 -241.942294)
			(xy 123.023078 -241.954154) (xy 123.072692 -241.973626) (xy 123.11885 -242.000275) (xy 123.160521 -242.033506)
			(xy 123.196773 -242.072577) (xy 123.226797 -242.116614) (xy 123.249923 -242.164635) (xy 123.265633 -242.215565)
			(xy 123.273576 -242.268269) (xy 123.274074 -242.294918) (xy 123.273576 -242.321567) (xy 123.502156 -242.321567)
			(xy 123.502156 -242.268269) (xy 123.510099 -242.215565) (xy 123.525809 -242.164635) (xy 123.548935 -242.116614)
			(xy 123.578959 -242.072577) (xy 123.615211 -242.033506) (xy 123.656882 -242.000275) (xy 123.70304 -241.973626)
			(xy 123.752654 -241.954154) (xy 123.804616 -241.942294) (xy 123.857766 -241.938311) (xy 123.910916 -241.942294)
			(xy 123.962878 -241.954154) (xy 124.012492 -241.973626) (xy 124.05865 -242.000275) (xy 124.100321 -242.033506)
			(xy 124.136573 -242.072577) (xy 124.166597 -242.116614) (xy 124.189723 -242.164635) (xy 124.205433 -242.215565)
			(xy 124.213376 -242.268269) (xy 124.213874 -242.294918) (xy 124.213376 -242.321567) (xy 124.441956 -242.321567)
			(xy 124.441956 -242.268269) (xy 124.449899 -242.215565) (xy 124.465609 -242.164635) (xy 124.488735 -242.116614)
			(xy 124.518759 -242.072577) (xy 124.555011 -242.033506) (xy 124.596682 -242.000275) (xy 124.64284 -241.973626)
			(xy 124.692454 -241.954154) (xy 124.744416 -241.942294) (xy 124.797566 -241.938311) (xy 124.850716 -241.942294)
			(xy 124.902678 -241.954154) (xy 124.952292 -241.973626) (xy 124.99845 -242.000275) (xy 125.040121 -242.033506)
			(xy 125.076373 -242.072577) (xy 125.106397 -242.116614) (xy 125.129523 -242.164635) (xy 125.145233 -242.215565)
			(xy 125.153176 -242.268269) (xy 125.153674 -242.294918) (xy 125.153176 -242.321567) (xy 125.381756 -242.321567)
			(xy 125.381756 -242.268269) (xy 125.389699 -242.215565) (xy 125.405409 -242.164635) (xy 125.428535 -242.116614)
			(xy 125.458559 -242.072577) (xy 125.494811 -242.033506) (xy 125.536482 -242.000275) (xy 125.58264 -241.973626)
			(xy 125.632254 -241.954154) (xy 125.684216 -241.942294) (xy 125.737366 -241.938311) (xy 125.790516 -241.942294)
			(xy 125.842478 -241.954154) (xy 125.892092 -241.973626) (xy 125.93825 -242.000275) (xy 125.979921 -242.033506)
			(xy 126.016173 -242.072577) (xy 126.046197 -242.116614) (xy 126.069323 -242.164635) (xy 126.085033 -242.215565)
			(xy 126.092976 -242.268269) (xy 126.093474 -242.294918) (xy 126.092976 -242.321567) (xy 126.321556 -242.321567)
			(xy 126.321556 -242.268269) (xy 126.329499 -242.215565) (xy 126.345209 -242.164635) (xy 126.368335 -242.116614)
			(xy 126.398359 -242.072577) (xy 126.434611 -242.033506) (xy 126.476282 -242.000275) (xy 126.52244 -241.973626)
			(xy 126.572054 -241.954154) (xy 126.624016 -241.942294) (xy 126.677166 -241.938311) (xy 126.730316 -241.942294)
			(xy 126.782278 -241.954154) (xy 126.831892 -241.973626) (xy 126.87805 -242.000275) (xy 126.919721 -242.033506)
			(xy 126.955973 -242.072577) (xy 126.985997 -242.116614) (xy 127.009123 -242.164635) (xy 127.024833 -242.215565)
			(xy 127.032776 -242.268269) (xy 127.033274 -242.294918) (xy 127.032776 -242.321567) (xy 127.261356 -242.321567)
			(xy 127.261356 -242.268269) (xy 127.269299 -242.215565) (xy 127.285009 -242.164635) (xy 127.308135 -242.116614)
			(xy 127.338159 -242.072577) (xy 127.374411 -242.033506) (xy 127.416082 -242.000275) (xy 127.46224 -241.973626)
			(xy 127.511854 -241.954154) (xy 127.563816 -241.942294) (xy 127.616966 -241.938311) (xy 127.670116 -241.942294)
			(xy 127.722078 -241.954154) (xy 127.771692 -241.973626) (xy 127.81785 -242.000275) (xy 127.859521 -242.033506)
			(xy 127.895773 -242.072577) (xy 127.925797 -242.116614) (xy 127.948923 -242.164635) (xy 127.964633 -242.215565)
			(xy 127.972576 -242.268269) (xy 127.973074 -242.294918) (xy 127.972576 -242.321567) (xy 128.201156 -242.321567)
			(xy 128.201156 -242.268269) (xy 128.209099 -242.215565) (xy 128.224809 -242.164635) (xy 128.247935 -242.116614)
			(xy 128.277959 -242.072577) (xy 128.314211 -242.033506) (xy 128.355882 -242.000275) (xy 128.40204 -241.973626)
			(xy 128.451654 -241.954154) (xy 128.503616 -241.942294) (xy 128.556766 -241.938311) (xy 128.609916 -241.942294)
			(xy 128.661878 -241.954154) (xy 128.711492 -241.973626) (xy 128.75765 -242.000275) (xy 128.799321 -242.033506)
			(xy 128.835573 -242.072577) (xy 128.865597 -242.116614) (xy 128.888723 -242.164635) (xy 128.904433 -242.215565)
			(xy 128.912376 -242.268269) (xy 128.912874 -242.294918) (xy 128.912376 -242.321567) (xy 129.140956 -242.321567)
			(xy 129.140956 -242.268269) (xy 129.148899 -242.215565) (xy 129.164609 -242.164635) (xy 129.187735 -242.116614)
			(xy 129.217759 -242.072577) (xy 129.254011 -242.033506) (xy 129.295682 -242.000275) (xy 129.34184 -241.973626)
			(xy 129.391454 -241.954154) (xy 129.443416 -241.942294) (xy 129.496566 -241.938311) (xy 129.549716 -241.942294)
			(xy 129.601678 -241.954154) (xy 129.651292 -241.973626) (xy 129.69745 -242.000275) (xy 129.739121 -242.033506)
			(xy 129.775373 -242.072577) (xy 129.805397 -242.116614) (xy 129.828523 -242.164635) (xy 129.844233 -242.215565)
			(xy 129.852176 -242.268269) (xy 129.852674 -242.294918) (xy 129.852176 -242.321567) (xy 130.080756 -242.321567)
			(xy 130.080756 -242.268269) (xy 130.088699 -242.215565) (xy 130.104409 -242.164635) (xy 130.127535 -242.116614)
			(xy 130.157559 -242.072577) (xy 130.193811 -242.033506) (xy 130.235482 -242.000275) (xy 130.28164 -241.973626)
			(xy 130.331254 -241.954154) (xy 130.383216 -241.942294) (xy 130.436366 -241.938311) (xy 130.489516 -241.942294)
			(xy 130.541478 -241.954154) (xy 130.591092 -241.973626) (xy 130.63725 -242.000275) (xy 130.678921 -242.033506)
			(xy 130.715173 -242.072577) (xy 130.745197 -242.116614) (xy 130.768323 -242.164635) (xy 130.784033 -242.215565)
			(xy 130.791976 -242.268269) (xy 130.792474 -242.294918) (xy 130.791976 -242.321567) (xy 131.020556 -242.321567)
			(xy 131.020556 -242.268269) (xy 131.028499 -242.215565) (xy 131.044209 -242.164635) (xy 131.067335 -242.116614)
			(xy 131.097359 -242.072577) (xy 131.133611 -242.033506) (xy 131.175282 -242.000275) (xy 131.22144 -241.973626)
			(xy 131.271054 -241.954154) (xy 131.323016 -241.942294) (xy 131.376166 -241.938311) (xy 131.429316 -241.942294)
			(xy 131.481278 -241.954154) (xy 131.530892 -241.973626) (xy 131.57705 -242.000275) (xy 131.618721 -242.033506)
			(xy 131.654973 -242.072577) (xy 131.684997 -242.116614) (xy 131.708123 -242.164635) (xy 131.723833 -242.215565)
			(xy 131.731776 -242.268269) (xy 131.732274 -242.294918) (xy 131.731776 -242.321567) (xy 131.960356 -242.321567)
			(xy 131.960356 -242.268269) (xy 131.968299 -242.215565) (xy 131.984009 -242.164635) (xy 132.007135 -242.116614)
			(xy 132.037159 -242.072577) (xy 132.073411 -242.033506) (xy 132.115082 -242.000275) (xy 132.16124 -241.973626)
			(xy 132.210854 -241.954154) (xy 132.262816 -241.942294) (xy 132.315966 -241.938311) (xy 132.369116 -241.942294)
			(xy 132.421078 -241.954154) (xy 132.470692 -241.973626) (xy 132.51685 -242.000275) (xy 132.558521 -242.033506)
			(xy 132.594773 -242.072577) (xy 132.624797 -242.116614) (xy 132.647923 -242.164635) (xy 132.663633 -242.215565)
			(xy 132.671576 -242.268269) (xy 132.672074 -242.294918) (xy 132.671576 -242.321567) (xy 132.900156 -242.321567)
			(xy 132.900156 -242.268269) (xy 132.908099 -242.215565) (xy 132.923809 -242.164635) (xy 132.946935 -242.116614)
			(xy 132.976959 -242.072577) (xy 133.013211 -242.033506) (xy 133.054882 -242.000275) (xy 133.10104 -241.973626)
			(xy 133.150654 -241.954154) (xy 133.202616 -241.942294) (xy 133.255766 -241.938311) (xy 133.308916 -241.942294)
			(xy 133.360878 -241.954154) (xy 133.410492 -241.973626) (xy 133.45665 -242.000275) (xy 133.498321 -242.033506)
			(xy 133.534573 -242.072577) (xy 133.564597 -242.116614) (xy 133.587723 -242.164635) (xy 133.603433 -242.215565)
			(xy 133.611376 -242.268269) (xy 133.611874 -242.294918) (xy 133.611376 -242.321567) (xy 133.839956 -242.321567)
			(xy 133.839956 -242.268269) (xy 133.847899 -242.215565) (xy 133.863609 -242.164635) (xy 133.886735 -242.116614)
			(xy 133.916759 -242.072577) (xy 133.953011 -242.033506) (xy 133.994682 -242.000275) (xy 134.04084 -241.973626)
			(xy 134.090454 -241.954154) (xy 134.142416 -241.942294) (xy 134.195566 -241.938311) (xy 134.248716 -241.942294)
			(xy 134.300678 -241.954154) (xy 134.350292 -241.973626) (xy 134.39645 -242.000275) (xy 134.438121 -242.033506)
			(xy 134.474373 -242.072577) (xy 134.504397 -242.116614) (xy 134.527523 -242.164635) (xy 134.543233 -242.215565)
			(xy 134.551176 -242.268269) (xy 134.551674 -242.294918) (xy 134.551176 -242.321567) (xy 134.543233 -242.374271)
			(xy 134.527523 -242.425201) (xy 134.504397 -242.473222) (xy 134.474373 -242.517259) (xy 134.438121 -242.55633)
			(xy 134.39645 -242.589561) (xy 134.350292 -242.61621) (xy 134.300678 -242.635682) (xy 134.248716 -242.647542)
			(xy 134.195566 -242.651526) (xy 134.142416 -242.647542) (xy 134.090454 -242.635682) (xy 134.04084 -242.61621)
			(xy 133.994682 -242.589561) (xy 133.953011 -242.55633) (xy 133.916759 -242.517259) (xy 133.886735 -242.473222)
			(xy 133.863609 -242.425201) (xy 133.847899 -242.374271) (xy 133.839956 -242.321567) (xy 133.611376 -242.321567)
			(xy 133.603433 -242.374271) (xy 133.587723 -242.425201) (xy 133.564597 -242.473222) (xy 133.534573 -242.517259)
			(xy 133.498321 -242.55633) (xy 133.45665 -242.589561) (xy 133.410492 -242.61621) (xy 133.360878 -242.635682)
			(xy 133.308916 -242.647542) (xy 133.255766 -242.651526) (xy 133.202616 -242.647542) (xy 133.150654 -242.635682)
			(xy 133.10104 -242.61621) (xy 133.054882 -242.589561) (xy 133.013211 -242.55633) (xy 132.976959 -242.517259)
			(xy 132.946935 -242.473222) (xy 132.923809 -242.425201) (xy 132.908099 -242.374271) (xy 132.900156 -242.321567)
			(xy 132.671576 -242.321567) (xy 132.663633 -242.374271) (xy 132.647923 -242.425201) (xy 132.624797 -242.473222)
			(xy 132.594773 -242.517259) (xy 132.558521 -242.55633) (xy 132.51685 -242.589561) (xy 132.470692 -242.61621)
			(xy 132.421078 -242.635682) (xy 132.369116 -242.647542) (xy 132.315966 -242.651526) (xy 132.262816 -242.647542)
			(xy 132.210854 -242.635682) (xy 132.16124 -242.61621) (xy 132.115082 -242.589561) (xy 132.073411 -242.55633)
			(xy 132.037159 -242.517259) (xy 132.007135 -242.473222) (xy 131.984009 -242.425201) (xy 131.968299 -242.374271)
			(xy 131.960356 -242.321567) (xy 131.731776 -242.321567) (xy 131.723833 -242.374271) (xy 131.708123 -242.425201)
			(xy 131.684997 -242.473222) (xy 131.654973 -242.517259) (xy 131.618721 -242.55633) (xy 131.57705 -242.589561)
			(xy 131.530892 -242.61621) (xy 131.481278 -242.635682) (xy 131.429316 -242.647542) (xy 131.376166 -242.651526)
			(xy 131.323016 -242.647542) (xy 131.271054 -242.635682) (xy 131.22144 -242.61621) (xy 131.175282 -242.589561)
			(xy 131.133611 -242.55633) (xy 131.097359 -242.517259) (xy 131.067335 -242.473222) (xy 131.044209 -242.425201)
			(xy 131.028499 -242.374271) (xy 131.020556 -242.321567) (xy 130.791976 -242.321567) (xy 130.784033 -242.374271)
			(xy 130.768323 -242.425201) (xy 130.745197 -242.473222) (xy 130.715173 -242.517259) (xy 130.678921 -242.55633)
			(xy 130.63725 -242.589561) (xy 130.591092 -242.61621) (xy 130.541478 -242.635682) (xy 130.489516 -242.647542)
			(xy 130.436366 -242.651526) (xy 130.383216 -242.647542) (xy 130.331254 -242.635682) (xy 130.28164 -242.61621)
			(xy 130.235482 -242.589561) (xy 130.193811 -242.55633) (xy 130.157559 -242.517259) (xy 130.127535 -242.473222)
			(xy 130.104409 -242.425201) (xy 130.088699 -242.374271) (xy 130.080756 -242.321567) (xy 129.852176 -242.321567)
			(xy 129.844233 -242.374271) (xy 129.828523 -242.425201) (xy 129.805397 -242.473222) (xy 129.775373 -242.517259)
			(xy 129.739121 -242.55633) (xy 129.69745 -242.589561) (xy 129.651292 -242.61621) (xy 129.601678 -242.635682)
			(xy 129.549716 -242.647542) (xy 129.496566 -242.651526) (xy 129.443416 -242.647542) (xy 129.391454 -242.635682)
			(xy 129.34184 -242.61621) (xy 129.295682 -242.589561) (xy 129.254011 -242.55633) (xy 129.217759 -242.517259)
			(xy 129.187735 -242.473222) (xy 129.164609 -242.425201) (xy 129.148899 -242.374271) (xy 129.140956 -242.321567)
			(xy 128.912376 -242.321567) (xy 128.904433 -242.374271) (xy 128.888723 -242.425201) (xy 128.865597 -242.473222)
			(xy 128.835573 -242.517259) (xy 128.799321 -242.55633) (xy 128.75765 -242.589561) (xy 128.711492 -242.61621)
			(xy 128.661878 -242.635682) (xy 128.609916 -242.647542) (xy 128.556766 -242.651526) (xy 128.503616 -242.647542)
			(xy 128.451654 -242.635682) (xy 128.40204 -242.61621) (xy 128.355882 -242.589561) (xy 128.314211 -242.55633)
			(xy 128.277959 -242.517259) (xy 128.247935 -242.473222) (xy 128.224809 -242.425201) (xy 128.209099 -242.374271)
			(xy 128.201156 -242.321567) (xy 127.972576 -242.321567) (xy 127.964633 -242.374271) (xy 127.948923 -242.425201)
			(xy 127.925797 -242.473222) (xy 127.895773 -242.517259) (xy 127.859521 -242.55633) (xy 127.81785 -242.589561)
			(xy 127.771692 -242.61621) (xy 127.722078 -242.635682) (xy 127.670116 -242.647542) (xy 127.616966 -242.651526)
			(xy 127.563816 -242.647542) (xy 127.511854 -242.635682) (xy 127.46224 -242.61621) (xy 127.416082 -242.589561)
			(xy 127.374411 -242.55633) (xy 127.338159 -242.517259) (xy 127.308135 -242.473222) (xy 127.285009 -242.425201)
			(xy 127.269299 -242.374271) (xy 127.261356 -242.321567) (xy 127.032776 -242.321567) (xy 127.024833 -242.374271)
			(xy 127.009123 -242.425201) (xy 126.985997 -242.473222) (xy 126.955973 -242.517259) (xy 126.919721 -242.55633)
			(xy 126.87805 -242.589561) (xy 126.831892 -242.61621) (xy 126.782278 -242.635682) (xy 126.730316 -242.647542)
			(xy 126.677166 -242.651526) (xy 126.624016 -242.647542) (xy 126.572054 -242.635682) (xy 126.52244 -242.61621)
			(xy 126.476282 -242.589561) (xy 126.434611 -242.55633) (xy 126.398359 -242.517259) (xy 126.368335 -242.473222)
			(xy 126.345209 -242.425201) (xy 126.329499 -242.374271) (xy 126.321556 -242.321567) (xy 126.092976 -242.321567)
			(xy 126.085033 -242.374271) (xy 126.069323 -242.425201) (xy 126.046197 -242.473222) (xy 126.016173 -242.517259)
			(xy 125.979921 -242.55633) (xy 125.93825 -242.589561) (xy 125.892092 -242.61621) (xy 125.842478 -242.635682)
			(xy 125.790516 -242.647542) (xy 125.737366 -242.651526) (xy 125.684216 -242.647542) (xy 125.632254 -242.635682)
			(xy 125.58264 -242.61621) (xy 125.536482 -242.589561) (xy 125.494811 -242.55633) (xy 125.458559 -242.517259)
			(xy 125.428535 -242.473222) (xy 125.405409 -242.425201) (xy 125.389699 -242.374271) (xy 125.381756 -242.321567)
			(xy 125.153176 -242.321567) (xy 125.145233 -242.374271) (xy 125.129523 -242.425201) (xy 125.106397 -242.473222)
			(xy 125.076373 -242.517259) (xy 125.040121 -242.55633) (xy 124.99845 -242.589561) (xy 124.952292 -242.61621)
			(xy 124.902678 -242.635682) (xy 124.850716 -242.647542) (xy 124.797566 -242.651526) (xy 124.744416 -242.647542)
			(xy 124.692454 -242.635682) (xy 124.64284 -242.61621) (xy 124.596682 -242.589561) (xy 124.555011 -242.55633)
			(xy 124.518759 -242.517259) (xy 124.488735 -242.473222) (xy 124.465609 -242.425201) (xy 124.449899 -242.374271)
			(xy 124.441956 -242.321567) (xy 124.213376 -242.321567) (xy 124.205433 -242.374271) (xy 124.189723 -242.425201)
			(xy 124.166597 -242.473222) (xy 124.136573 -242.517259) (xy 124.100321 -242.55633) (xy 124.05865 -242.589561)
			(xy 124.012492 -242.61621) (xy 123.962878 -242.635682) (xy 123.910916 -242.647542) (xy 123.857766 -242.651526)
			(xy 123.804616 -242.647542) (xy 123.752654 -242.635682) (xy 123.70304 -242.61621) (xy 123.656882 -242.589561)
			(xy 123.615211 -242.55633) (xy 123.578959 -242.517259) (xy 123.548935 -242.473222) (xy 123.525809 -242.425201)
			(xy 123.510099 -242.374271) (xy 123.502156 -242.321567) (xy 123.273576 -242.321567) (xy 123.265633 -242.374271)
			(xy 123.249923 -242.425201) (xy 123.226797 -242.473222) (xy 123.196773 -242.517259) (xy 123.160521 -242.55633)
			(xy 123.11885 -242.589561) (xy 123.072692 -242.61621) (xy 123.023078 -242.635682) (xy 122.971116 -242.647542)
			(xy 122.917966 -242.651526) (xy 122.864816 -242.647542) (xy 122.812854 -242.635682) (xy 122.76324 -242.61621)
			(xy 122.717082 -242.589561) (xy 122.675411 -242.55633) (xy 122.639159 -242.517259) (xy 122.609135 -242.473222)
			(xy 122.586009 -242.425201) (xy 122.570299 -242.374271) (xy 122.562356 -242.321567) (xy 122.333776 -242.321567)
			(xy 122.325833 -242.374271) (xy 122.310123 -242.425201) (xy 122.286997 -242.473222) (xy 122.256973 -242.517259)
			(xy 122.220721 -242.55633) (xy 122.17905 -242.589561) (xy 122.132892 -242.61621) (xy 122.083278 -242.635682)
			(xy 122.031316 -242.647542) (xy 121.978166 -242.651526) (xy 121.925016 -242.647542) (xy 121.873054 -242.635682)
			(xy 121.82344 -242.61621) (xy 121.777282 -242.589561) (xy 121.735611 -242.55633) (xy 121.699359 -242.517259)
			(xy 121.669335 -242.473222) (xy 121.646209 -242.425201) (xy 121.630499 -242.374271) (xy 121.622556 -242.321567)
			(xy 120.98528 -242.321567) (xy 120.98528 -243.135637) (xy 121.152402 -243.135637) (xy 121.152402 -243.082339)
			(xy 121.160345 -243.029635) (xy 121.176055 -242.978705) (xy 121.199181 -242.930684) (xy 121.229205 -242.886647)
			(xy 121.265457 -242.847576) (xy 121.307128 -242.814345) (xy 121.353286 -242.787696) (xy 121.4029 -242.768224)
			(xy 121.454862 -242.756364) (xy 121.508012 -242.752381) (xy 121.561162 -242.756364) (xy 121.613124 -242.768224)
			(xy 121.662738 -242.787696) (xy 121.708896 -242.814345) (xy 121.750567 -242.847576) (xy 121.786819 -242.886647)
			(xy 121.816843 -242.930684) (xy 121.839969 -242.978705) (xy 121.855679 -243.029635) (xy 121.863622 -243.082339)
			(xy 121.86412 -243.108988) (xy 121.863622 -243.135637) (xy 122.092202 -243.135637) (xy 122.092202 -243.082339)
			(xy 122.100145 -243.029635) (xy 122.115855 -242.978705) (xy 122.138981 -242.930684) (xy 122.169005 -242.886647)
			(xy 122.205257 -242.847576) (xy 122.246928 -242.814345) (xy 122.293086 -242.787696) (xy 122.3427 -242.768224)
			(xy 122.394662 -242.756364) (xy 122.447812 -242.752381) (xy 122.500962 -242.756364) (xy 122.552924 -242.768224)
			(xy 122.602538 -242.787696) (xy 122.648696 -242.814345) (xy 122.690367 -242.847576) (xy 122.726619 -242.886647)
			(xy 122.756643 -242.930684) (xy 122.779769 -242.978705) (xy 122.795479 -243.029635) (xy 122.803422 -243.082339)
			(xy 122.80392 -243.108988) (xy 122.803422 -243.135637) (xy 123.032002 -243.135637) (xy 123.032002 -243.082339)
			(xy 123.039945 -243.029635) (xy 123.055655 -242.978705) (xy 123.078781 -242.930684) (xy 123.108805 -242.886647)
			(xy 123.145057 -242.847576) (xy 123.186728 -242.814345) (xy 123.232886 -242.787696) (xy 123.2825 -242.768224)
			(xy 123.334462 -242.756364) (xy 123.387612 -242.752381) (xy 123.440762 -242.756364) (xy 123.492724 -242.768224)
			(xy 123.542338 -242.787696) (xy 123.588496 -242.814345) (xy 123.630167 -242.847576) (xy 123.666419 -242.886647)
			(xy 123.696443 -242.930684) (xy 123.719569 -242.978705) (xy 123.735279 -243.029635) (xy 123.743222 -243.082339)
			(xy 123.74372 -243.108988) (xy 123.743222 -243.135637) (xy 123.971802 -243.135637) (xy 123.971802 -243.082339)
			(xy 123.979745 -243.029635) (xy 123.995455 -242.978705) (xy 124.018581 -242.930684) (xy 124.048605 -242.886647)
			(xy 124.084857 -242.847576) (xy 124.126528 -242.814345) (xy 124.172686 -242.787696) (xy 124.2223 -242.768224)
			(xy 124.274262 -242.756364) (xy 124.327412 -242.752381) (xy 124.380562 -242.756364) (xy 124.432524 -242.768224)
			(xy 124.482138 -242.787696) (xy 124.528296 -242.814345) (xy 124.569967 -242.847576) (xy 124.606219 -242.886647)
			(xy 124.636243 -242.930684) (xy 124.659369 -242.978705) (xy 124.675079 -243.029635) (xy 124.683022 -243.082339)
			(xy 124.68352 -243.108988) (xy 124.683022 -243.135637) (xy 124.911602 -243.135637) (xy 124.911602 -243.082339)
			(xy 124.919545 -243.029635) (xy 124.935255 -242.978705) (xy 124.958381 -242.930684) (xy 124.988405 -242.886647)
			(xy 125.024657 -242.847576) (xy 125.066328 -242.814345) (xy 125.112486 -242.787696) (xy 125.1621 -242.768224)
			(xy 125.214062 -242.756364) (xy 125.267212 -242.752381) (xy 125.320362 -242.756364) (xy 125.372324 -242.768224)
			(xy 125.421938 -242.787696) (xy 125.468096 -242.814345) (xy 125.509767 -242.847576) (xy 125.546019 -242.886647)
			(xy 125.576043 -242.930684) (xy 125.599169 -242.978705) (xy 125.614879 -243.029635) (xy 125.622822 -243.082339)
			(xy 125.62332 -243.108988) (xy 125.622822 -243.135637) (xy 125.851656 -243.135637) (xy 125.851656 -243.082339)
			(xy 125.859599 -243.029635) (xy 125.875309 -242.978705) (xy 125.898435 -242.930684) (xy 125.928459 -242.886647)
			(xy 125.964711 -242.847576) (xy 126.006382 -242.814345) (xy 126.05254 -242.787696) (xy 126.102154 -242.768224)
			(xy 126.154116 -242.756364) (xy 126.207266 -242.752381) (xy 126.260416 -242.756364) (xy 126.312378 -242.768224)
			(xy 126.361992 -242.787696) (xy 126.40815 -242.814345) (xy 126.449821 -242.847576) (xy 126.486073 -242.886647)
			(xy 126.516097 -242.930684) (xy 126.539223 -242.978705) (xy 126.554933 -243.029635) (xy 126.562876 -243.082339)
			(xy 126.563374 -243.108988) (xy 126.562876 -243.135637) (xy 126.791202 -243.135637) (xy 126.791202 -243.082339)
			(xy 126.799145 -243.029635) (xy 126.814855 -242.978705) (xy 126.837981 -242.930684) (xy 126.868005 -242.886647)
			(xy 126.904257 -242.847576) (xy 126.945928 -242.814345) (xy 126.992086 -242.787696) (xy 127.0417 -242.768224)
			(xy 127.093662 -242.756364) (xy 127.146812 -242.752381) (xy 127.199962 -242.756364) (xy 127.251924 -242.768224)
			(xy 127.301538 -242.787696) (xy 127.347696 -242.814345) (xy 127.389367 -242.847576) (xy 127.425619 -242.886647)
			(xy 127.455643 -242.930684) (xy 127.478769 -242.978705) (xy 127.494479 -243.029635) (xy 127.502422 -243.082339)
			(xy 127.50292 -243.108988) (xy 127.502422 -243.135637) (xy 127.731002 -243.135637) (xy 127.731002 -243.082339)
			(xy 127.738945 -243.029635) (xy 127.754655 -242.978705) (xy 127.777781 -242.930684) (xy 127.807805 -242.886647)
			(xy 127.844057 -242.847576) (xy 127.885728 -242.814345) (xy 127.931886 -242.787696) (xy 127.9815 -242.768224)
			(xy 128.033462 -242.756364) (xy 128.086612 -242.752381) (xy 128.139762 -242.756364) (xy 128.191724 -242.768224)
			(xy 128.241338 -242.787696) (xy 128.287496 -242.814345) (xy 128.329167 -242.847576) (xy 128.365419 -242.886647)
			(xy 128.395443 -242.930684) (xy 128.418569 -242.978705) (xy 128.434279 -243.029635) (xy 128.442222 -243.082339)
			(xy 128.44272 -243.108988) (xy 128.442222 -243.135637) (xy 128.670802 -243.135637) (xy 128.670802 -243.082339)
			(xy 128.678745 -243.029635) (xy 128.694455 -242.978705) (xy 128.717581 -242.930684) (xy 128.747605 -242.886647)
			(xy 128.783857 -242.847576) (xy 128.825528 -242.814345) (xy 128.871686 -242.787696) (xy 128.9213 -242.768224)
			(xy 128.973262 -242.756364) (xy 129.026412 -242.752381) (xy 129.079562 -242.756364) (xy 129.131524 -242.768224)
			(xy 129.181138 -242.787696) (xy 129.227296 -242.814345) (xy 129.268967 -242.847576) (xy 129.305219 -242.886647)
			(xy 129.335243 -242.930684) (xy 129.358369 -242.978705) (xy 129.374079 -243.029635) (xy 129.382022 -243.082339)
			(xy 129.38252 -243.108988) (xy 129.382022 -243.135637) (xy 129.610602 -243.135637) (xy 129.610602 -243.082339)
			(xy 129.618545 -243.029635) (xy 129.634255 -242.978705) (xy 129.657381 -242.930684) (xy 129.687405 -242.886647)
			(xy 129.723657 -242.847576) (xy 129.765328 -242.814345) (xy 129.811486 -242.787696) (xy 129.8611 -242.768224)
			(xy 129.913062 -242.756364) (xy 129.966212 -242.752381) (xy 130.019362 -242.756364) (xy 130.071324 -242.768224)
			(xy 130.120938 -242.787696) (xy 130.167096 -242.814345) (xy 130.208767 -242.847576) (xy 130.245019 -242.886647)
			(xy 130.275043 -242.930684) (xy 130.298169 -242.978705) (xy 130.313879 -243.029635) (xy 130.321822 -243.082339)
			(xy 130.32232 -243.108988) (xy 130.321822 -243.135637) (xy 130.550402 -243.135637) (xy 130.550402 -243.082339)
			(xy 130.558345 -243.029635) (xy 130.574055 -242.978705) (xy 130.597181 -242.930684) (xy 130.627205 -242.886647)
			(xy 130.663457 -242.847576) (xy 130.705128 -242.814345) (xy 130.751286 -242.787696) (xy 130.8009 -242.768224)
			(xy 130.852862 -242.756364) (xy 130.906012 -242.752381) (xy 130.959162 -242.756364) (xy 131.011124 -242.768224)
			(xy 131.060738 -242.787696) (xy 131.106896 -242.814345) (xy 131.148567 -242.847576) (xy 131.184819 -242.886647)
			(xy 131.214843 -242.930684) (xy 131.237969 -242.978705) (xy 131.253679 -243.029635) (xy 131.261622 -243.082339)
			(xy 131.26212 -243.108988) (xy 131.261622 -243.135637) (xy 131.490202 -243.135637) (xy 131.490202 -243.082339)
			(xy 131.498145 -243.029635) (xy 131.513855 -242.978705) (xy 131.536981 -242.930684) (xy 131.567005 -242.886647)
			(xy 131.603257 -242.847576) (xy 131.644928 -242.814345) (xy 131.691086 -242.787696) (xy 131.7407 -242.768224)
			(xy 131.792662 -242.756364) (xy 131.845812 -242.752381) (xy 131.898962 -242.756364) (xy 131.950924 -242.768224)
			(xy 132.000538 -242.787696) (xy 132.046696 -242.814345) (xy 132.088367 -242.847576) (xy 132.124619 -242.886647)
			(xy 132.154643 -242.930684) (xy 132.177769 -242.978705) (xy 132.193479 -243.029635) (xy 132.201422 -243.082339)
			(xy 132.20192 -243.108988) (xy 132.201422 -243.135637) (xy 132.430256 -243.135637) (xy 132.430256 -243.082339)
			(xy 132.438199 -243.029635) (xy 132.453909 -242.978705) (xy 132.477035 -242.930684) (xy 132.507059 -242.886647)
			(xy 132.543311 -242.847576) (xy 132.584982 -242.814345) (xy 132.63114 -242.787696) (xy 132.680754 -242.768224)
			(xy 132.732716 -242.756364) (xy 132.785866 -242.752381) (xy 132.839016 -242.756364) (xy 132.890978 -242.768224)
			(xy 132.940592 -242.787696) (xy 132.98675 -242.814345) (xy 133.028421 -242.847576) (xy 133.064673 -242.886647)
			(xy 133.094697 -242.930684) (xy 133.117823 -242.978705) (xy 133.133533 -243.029635) (xy 133.141476 -243.082339)
			(xy 133.141974 -243.108988) (xy 133.141476 -243.135637) (xy 133.370056 -243.135637) (xy 133.370056 -243.082339)
			(xy 133.377999 -243.029635) (xy 133.393709 -242.978705) (xy 133.416835 -242.930684) (xy 133.446859 -242.886647)
			(xy 133.483111 -242.847576) (xy 133.524782 -242.814345) (xy 133.57094 -242.787696) (xy 133.620554 -242.768224)
			(xy 133.672516 -242.756364) (xy 133.725666 -242.752381) (xy 133.778816 -242.756364) (xy 133.830778 -242.768224)
			(xy 133.880392 -242.787696) (xy 133.92655 -242.814345) (xy 133.968221 -242.847576) (xy 134.004473 -242.886647)
			(xy 134.034497 -242.930684) (xy 134.057623 -242.978705) (xy 134.073333 -243.029635) (xy 134.081276 -243.082339)
			(xy 134.081774 -243.108988) (xy 134.081276 -243.135637) (xy 134.309602 -243.135637) (xy 134.309602 -243.082339)
			(xy 134.317545 -243.029635) (xy 134.333255 -242.978705) (xy 134.356381 -242.930684) (xy 134.386405 -242.886647)
			(xy 134.422657 -242.847576) (xy 134.464328 -242.814345) (xy 134.510486 -242.787696) (xy 134.5601 -242.768224)
			(xy 134.612062 -242.756364) (xy 134.665212 -242.752381) (xy 134.718362 -242.756364) (xy 134.770324 -242.768224)
			(xy 134.819938 -242.787696) (xy 134.866096 -242.814345) (xy 134.907767 -242.847576) (xy 134.944019 -242.886647)
			(xy 134.974043 -242.930684) (xy 134.997169 -242.978705) (xy 135.012879 -243.029635) (xy 135.020822 -243.082339)
			(xy 135.02132 -243.108988) (xy 135.020822 -243.135637) (xy 135.012879 -243.188341) (xy 134.997169 -243.239271)
			(xy 134.974043 -243.287292) (xy 134.944019 -243.331329) (xy 134.907767 -243.3704) (xy 134.866096 -243.403631)
			(xy 134.819938 -243.43028) (xy 134.770324 -243.449752) (xy 134.718362 -243.461612) (xy 134.665212 -243.465596)
			(xy 134.612062 -243.461612) (xy 134.5601 -243.449752) (xy 134.510486 -243.43028) (xy 134.464328 -243.403631)
			(xy 134.422657 -243.3704) (xy 134.386405 -243.331329) (xy 134.356381 -243.287292) (xy 134.333255 -243.239271)
			(xy 134.317545 -243.188341) (xy 134.309602 -243.135637) (xy 134.081276 -243.135637) (xy 134.073333 -243.188341)
			(xy 134.057623 -243.239271) (xy 134.034497 -243.287292) (xy 134.004473 -243.331329) (xy 133.968221 -243.3704)
			(xy 133.92655 -243.403631) (xy 133.880392 -243.43028) (xy 133.830778 -243.449752) (xy 133.778816 -243.461612)
			(xy 133.725666 -243.465596) (xy 133.672516 -243.461612) (xy 133.620554 -243.449752) (xy 133.57094 -243.43028)
			(xy 133.524782 -243.403631) (xy 133.483111 -243.3704) (xy 133.446859 -243.331329) (xy 133.416835 -243.287292)
			(xy 133.393709 -243.239271) (xy 133.377999 -243.188341) (xy 133.370056 -243.135637) (xy 133.141476 -243.135637)
			(xy 133.133533 -243.188341) (xy 133.117823 -243.239271) (xy 133.094697 -243.287292) (xy 133.064673 -243.331329)
			(xy 133.028421 -243.3704) (xy 132.98675 -243.403631) (xy 132.940592 -243.43028) (xy 132.890978 -243.449752)
			(xy 132.839016 -243.461612) (xy 132.785866 -243.465596) (xy 132.732716 -243.461612) (xy 132.680754 -243.449752)
			(xy 132.63114 -243.43028) (xy 132.584982 -243.403631) (xy 132.543311 -243.3704) (xy 132.507059 -243.331329)
			(xy 132.477035 -243.287292) (xy 132.453909 -243.239271) (xy 132.438199 -243.188341) (xy 132.430256 -243.135637)
			(xy 132.201422 -243.135637) (xy 132.193479 -243.188341) (xy 132.177769 -243.239271) (xy 132.154643 -243.287292)
			(xy 132.124619 -243.331329) (xy 132.088367 -243.3704) (xy 132.046696 -243.403631) (xy 132.000538 -243.43028)
			(xy 131.950924 -243.449752) (xy 131.898962 -243.461612) (xy 131.845812 -243.465596) (xy 131.792662 -243.461612)
			(xy 131.7407 -243.449752) (xy 131.691086 -243.43028) (xy 131.644928 -243.403631) (xy 131.603257 -243.3704)
			(xy 131.567005 -243.331329) (xy 131.536981 -243.287292) (xy 131.513855 -243.239271) (xy 131.498145 -243.188341)
			(xy 131.490202 -243.135637) (xy 131.261622 -243.135637) (xy 131.253679 -243.188341) (xy 131.237969 -243.239271)
			(xy 131.214843 -243.287292) (xy 131.184819 -243.331329) (xy 131.148567 -243.3704) (xy 131.106896 -243.403631)
			(xy 131.060738 -243.43028) (xy 131.011124 -243.449752) (xy 130.959162 -243.461612) (xy 130.906012 -243.465596)
			(xy 130.852862 -243.461612) (xy 130.8009 -243.449752) (xy 130.751286 -243.43028) (xy 130.705128 -243.403631)
			(xy 130.663457 -243.3704) (xy 130.627205 -243.331329) (xy 130.597181 -243.287292) (xy 130.574055 -243.239271)
			(xy 130.558345 -243.188341) (xy 130.550402 -243.135637) (xy 130.321822 -243.135637) (xy 130.313879 -243.188341)
			(xy 130.298169 -243.239271) (xy 130.275043 -243.287292) (xy 130.245019 -243.331329) (xy 130.208767 -243.3704)
			(xy 130.167096 -243.403631) (xy 130.120938 -243.43028) (xy 130.071324 -243.449752) (xy 130.019362 -243.461612)
			(xy 129.966212 -243.465596) (xy 129.913062 -243.461612) (xy 129.8611 -243.449752) (xy 129.811486 -243.43028)
			(xy 129.765328 -243.403631) (xy 129.723657 -243.3704) (xy 129.687405 -243.331329) (xy 129.657381 -243.287292)
			(xy 129.634255 -243.239271) (xy 129.618545 -243.188341) (xy 129.610602 -243.135637) (xy 129.382022 -243.135637)
			(xy 129.374079 -243.188341) (xy 129.358369 -243.239271) (xy 129.335243 -243.287292) (xy 129.305219 -243.331329)
			(xy 129.268967 -243.3704) (xy 129.227296 -243.403631) (xy 129.181138 -243.43028) (xy 129.131524 -243.449752)
			(xy 129.079562 -243.461612) (xy 129.026412 -243.465596) (xy 128.973262 -243.461612) (xy 128.9213 -243.449752)
			(xy 128.871686 -243.43028) (xy 128.825528 -243.403631) (xy 128.783857 -243.3704) (xy 128.747605 -243.331329)
			(xy 128.717581 -243.287292) (xy 128.694455 -243.239271) (xy 128.678745 -243.188341) (xy 128.670802 -243.135637)
			(xy 128.442222 -243.135637) (xy 128.434279 -243.188341) (xy 128.418569 -243.239271) (xy 128.395443 -243.287292)
			(xy 128.365419 -243.331329) (xy 128.329167 -243.3704) (xy 128.287496 -243.403631) (xy 128.241338 -243.43028)
			(xy 128.191724 -243.449752) (xy 128.139762 -243.461612) (xy 128.086612 -243.465596) (xy 128.033462 -243.461612)
			(xy 127.9815 -243.449752) (xy 127.931886 -243.43028) (xy 127.885728 -243.403631) (xy 127.844057 -243.3704)
			(xy 127.807805 -243.331329) (xy 127.777781 -243.287292) (xy 127.754655 -243.239271) (xy 127.738945 -243.188341)
			(xy 127.731002 -243.135637) (xy 127.502422 -243.135637) (xy 127.494479 -243.188341) (xy 127.478769 -243.239271)
			(xy 127.455643 -243.287292) (xy 127.425619 -243.331329) (xy 127.389367 -243.3704) (xy 127.347696 -243.403631)
			(xy 127.301538 -243.43028) (xy 127.251924 -243.449752) (xy 127.199962 -243.461612) (xy 127.146812 -243.465596)
			(xy 127.093662 -243.461612) (xy 127.0417 -243.449752) (xy 126.992086 -243.43028) (xy 126.945928 -243.403631)
			(xy 126.904257 -243.3704) (xy 126.868005 -243.331329) (xy 126.837981 -243.287292) (xy 126.814855 -243.239271)
			(xy 126.799145 -243.188341) (xy 126.791202 -243.135637) (xy 126.562876 -243.135637) (xy 126.554933 -243.188341)
			(xy 126.539223 -243.239271) (xy 126.516097 -243.287292) (xy 126.486073 -243.331329) (xy 126.449821 -243.3704)
			(xy 126.40815 -243.403631) (xy 126.361992 -243.43028) (xy 126.312378 -243.449752) (xy 126.260416 -243.461612)
			(xy 126.207266 -243.465596) (xy 126.154116 -243.461612) (xy 126.102154 -243.449752) (xy 126.05254 -243.43028)
			(xy 126.006382 -243.403631) (xy 125.964711 -243.3704) (xy 125.928459 -243.331329) (xy 125.898435 -243.287292)
			(xy 125.875309 -243.239271) (xy 125.859599 -243.188341) (xy 125.851656 -243.135637) (xy 125.622822 -243.135637)
			(xy 125.614879 -243.188341) (xy 125.599169 -243.239271) (xy 125.576043 -243.287292) (xy 125.546019 -243.331329)
			(xy 125.509767 -243.3704) (xy 125.468096 -243.403631) (xy 125.421938 -243.43028) (xy 125.372324 -243.449752)
			(xy 125.320362 -243.461612) (xy 125.267212 -243.465596) (xy 125.214062 -243.461612) (xy 125.1621 -243.449752)
			(xy 125.112486 -243.43028) (xy 125.066328 -243.403631) (xy 125.024657 -243.3704) (xy 124.988405 -243.331329)
			(xy 124.958381 -243.287292) (xy 124.935255 -243.239271) (xy 124.919545 -243.188341) (xy 124.911602 -243.135637)
			(xy 124.683022 -243.135637) (xy 124.675079 -243.188341) (xy 124.659369 -243.239271) (xy 124.636243 -243.287292)
			(xy 124.606219 -243.331329) (xy 124.569967 -243.3704) (xy 124.528296 -243.403631) (xy 124.482138 -243.43028)
			(xy 124.432524 -243.449752) (xy 124.380562 -243.461612) (xy 124.327412 -243.465596) (xy 124.274262 -243.461612)
			(xy 124.2223 -243.449752) (xy 124.172686 -243.43028) (xy 124.126528 -243.403631) (xy 124.084857 -243.3704)
			(xy 124.048605 -243.331329) (xy 124.018581 -243.287292) (xy 123.995455 -243.239271) (xy 123.979745 -243.188341)
			(xy 123.971802 -243.135637) (xy 123.743222 -243.135637) (xy 123.735279 -243.188341) (xy 123.719569 -243.239271)
			(xy 123.696443 -243.287292) (xy 123.666419 -243.331329) (xy 123.630167 -243.3704) (xy 123.588496 -243.403631)
			(xy 123.542338 -243.43028) (xy 123.492724 -243.449752) (xy 123.440762 -243.461612) (xy 123.387612 -243.465596)
			(xy 123.334462 -243.461612) (xy 123.2825 -243.449752) (xy 123.232886 -243.43028) (xy 123.186728 -243.403631)
			(xy 123.145057 -243.3704) (xy 123.108805 -243.331329) (xy 123.078781 -243.287292) (xy 123.055655 -243.239271)
			(xy 123.039945 -243.188341) (xy 123.032002 -243.135637) (xy 122.803422 -243.135637) (xy 122.795479 -243.188341)
			(xy 122.779769 -243.239271) (xy 122.756643 -243.287292) (xy 122.726619 -243.331329) (xy 122.690367 -243.3704)
			(xy 122.648696 -243.403631) (xy 122.602538 -243.43028) (xy 122.552924 -243.449752) (xy 122.500962 -243.461612)
			(xy 122.447812 -243.465596) (xy 122.394662 -243.461612) (xy 122.3427 -243.449752) (xy 122.293086 -243.43028)
			(xy 122.246928 -243.403631) (xy 122.205257 -243.3704) (xy 122.169005 -243.331329) (xy 122.138981 -243.287292)
			(xy 122.115855 -243.239271) (xy 122.100145 -243.188341) (xy 122.092202 -243.135637) (xy 121.863622 -243.135637)
			(xy 121.855679 -243.188341) (xy 121.839969 -243.239271) (xy 121.816843 -243.287292) (xy 121.786819 -243.331329)
			(xy 121.750567 -243.3704) (xy 121.708896 -243.403631) (xy 121.662738 -243.43028) (xy 121.613124 -243.449752)
			(xy 121.561162 -243.461612) (xy 121.508012 -243.465596) (xy 121.454862 -243.461612) (xy 121.4029 -243.449752)
			(xy 121.353286 -243.43028) (xy 121.307128 -243.403631) (xy 121.265457 -243.3704) (xy 121.229205 -243.331329)
			(xy 121.199181 -243.287292) (xy 121.176055 -243.239271) (xy 121.160345 -243.188341) (xy 121.152402 -243.135637)
			(xy 120.98528 -243.135637) (xy 120.98528 -243.487956) (xy 121.028714 -243.494306) (xy 121.056507 -243.498976)
			(xy 121.110249 -243.515933) (xy 121.16065 -243.541144) (xy 121.20645 -243.57398) (xy 121.246506 -243.61362)
			(xy 121.279817 -243.659075) (xy 121.305553 -243.70921) (xy 121.32307 -243.762773) (xy 121.33193 -243.818427)
			(xy 121.332498 -243.846604) (xy 121.332078 -243.871273) (xy 121.325266 -243.920139) (xy 121.316932 -243.949453)
			(xy 121.622302 -243.949453) (xy 121.622302 -243.896155) (xy 121.630245 -243.843451) (xy 121.645955 -243.792521)
			(xy 121.669081 -243.7445) (xy 121.699105 -243.700463) (xy 121.735357 -243.661392) (xy 121.777028 -243.628161)
			(xy 121.823186 -243.601512) (xy 121.8728 -243.58204) (xy 121.924762 -243.57018) (xy 121.977912 -243.566197)
			(xy 122.031062 -243.57018) (xy 122.083024 -243.58204) (xy 122.132638 -243.601512) (xy 122.178796 -243.628161)
			(xy 122.220467 -243.661392) (xy 122.256719 -243.700463) (xy 122.286743 -243.7445) (xy 122.309869 -243.792521)
			(xy 122.325579 -243.843451) (xy 122.333522 -243.896155) (xy 122.33402 -243.922804) (xy 122.333522 -243.949453)
			(xy 122.562102 -243.949453) (xy 122.562102 -243.896155) (xy 122.570045 -243.843451) (xy 122.585755 -243.792521)
			(xy 122.608881 -243.7445) (xy 122.638905 -243.700463) (xy 122.675157 -243.661392) (xy 122.716828 -243.628161)
			(xy 122.762986 -243.601512) (xy 122.8126 -243.58204) (xy 122.864562 -243.57018) (xy 122.917712 -243.566197)
			(xy 122.970862 -243.57018) (xy 123.022824 -243.58204) (xy 123.072438 -243.601512) (xy 123.118596 -243.628161)
			(xy 123.160267 -243.661392) (xy 123.196519 -243.700463) (xy 123.226543 -243.7445) (xy 123.249669 -243.792521)
			(xy 123.265379 -243.843451) (xy 123.273322 -243.896155) (xy 123.27382 -243.922804) (xy 123.273322 -243.949453)
			(xy 123.502156 -243.949453) (xy 123.502156 -243.896155) (xy 123.510099 -243.843451) (xy 123.525809 -243.792521)
			(xy 123.548935 -243.7445) (xy 123.578959 -243.700463) (xy 123.615211 -243.661392) (xy 123.656882 -243.628161)
			(xy 123.70304 -243.601512) (xy 123.752654 -243.58204) (xy 123.804616 -243.57018) (xy 123.857766 -243.566197)
			(xy 123.910916 -243.57018) (xy 123.962878 -243.58204) (xy 124.012492 -243.601512) (xy 124.05865 -243.628161)
			(xy 124.100321 -243.661392) (xy 124.136573 -243.700463) (xy 124.166597 -243.7445) (xy 124.189723 -243.792521)
			(xy 124.205433 -243.843451) (xy 124.213376 -243.896155) (xy 124.213874 -243.922804) (xy 124.213376 -243.949453)
			(xy 124.441956 -243.949453) (xy 124.441956 -243.896155) (xy 124.449899 -243.843451) (xy 124.465609 -243.792521)
			(xy 124.488735 -243.7445) (xy 124.518759 -243.700463) (xy 124.555011 -243.661392) (xy 124.596682 -243.628161)
			(xy 124.64284 -243.601512) (xy 124.692454 -243.58204) (xy 124.744416 -243.57018) (xy 124.797566 -243.566197)
			(xy 124.850716 -243.57018) (xy 124.902678 -243.58204) (xy 124.952292 -243.601512) (xy 124.99845 -243.628161)
			(xy 125.040121 -243.661392) (xy 125.076373 -243.700463) (xy 125.106397 -243.7445) (xy 125.129523 -243.792521)
			(xy 125.145233 -243.843451) (xy 125.153176 -243.896155) (xy 125.153674 -243.922804) (xy 125.153176 -243.949453)
			(xy 125.381756 -243.949453) (xy 125.381756 -243.896155) (xy 125.389699 -243.843451) (xy 125.405409 -243.792521)
			(xy 125.428535 -243.7445) (xy 125.458559 -243.700463) (xy 125.494811 -243.661392) (xy 125.536482 -243.628161)
			(xy 125.58264 -243.601512) (xy 125.632254 -243.58204) (xy 125.684216 -243.57018) (xy 125.737366 -243.566197)
			(xy 125.790516 -243.57018) (xy 125.842478 -243.58204) (xy 125.892092 -243.601512) (xy 125.93825 -243.628161)
			(xy 125.979921 -243.661392) (xy 126.016173 -243.700463) (xy 126.046197 -243.7445) (xy 126.069323 -243.792521)
			(xy 126.085033 -243.843451) (xy 126.092976 -243.896155) (xy 126.093474 -243.922804) (xy 126.092976 -243.949453)
			(xy 126.321556 -243.949453) (xy 126.321556 -243.896155) (xy 126.329499 -243.843451) (xy 126.345209 -243.792521)
			(xy 126.368335 -243.7445) (xy 126.398359 -243.700463) (xy 126.434611 -243.661392) (xy 126.476282 -243.628161)
			(xy 126.52244 -243.601512) (xy 126.572054 -243.58204) (xy 126.624016 -243.57018) (xy 126.677166 -243.566197)
			(xy 126.730316 -243.57018) (xy 126.782278 -243.58204) (xy 126.831892 -243.601512) (xy 126.87805 -243.628161)
			(xy 126.919721 -243.661392) (xy 126.955973 -243.700463) (xy 126.985997 -243.7445) (xy 127.009123 -243.792521)
			(xy 127.024833 -243.843451) (xy 127.032776 -243.896155) (xy 127.033274 -243.922804) (xy 127.032776 -243.949453)
			(xy 127.261356 -243.949453) (xy 127.261356 -243.896155) (xy 127.269299 -243.843451) (xy 127.285009 -243.792521)
			(xy 127.308135 -243.7445) (xy 127.338159 -243.700463) (xy 127.374411 -243.661392) (xy 127.416082 -243.628161)
			(xy 127.46224 -243.601512) (xy 127.511854 -243.58204) (xy 127.563816 -243.57018) (xy 127.616966 -243.566197)
			(xy 127.670116 -243.57018) (xy 127.722078 -243.58204) (xy 127.771692 -243.601512) (xy 127.81785 -243.628161)
			(xy 127.859521 -243.661392) (xy 127.895773 -243.700463) (xy 127.925797 -243.7445) (xy 127.948923 -243.792521)
			(xy 127.964633 -243.843451) (xy 127.972576 -243.896155) (xy 127.973074 -243.922804) (xy 127.972576 -243.949453)
			(xy 128.201156 -243.949453) (xy 128.201156 -243.896155) (xy 128.209099 -243.843451) (xy 128.224809 -243.792521)
			(xy 128.247935 -243.7445) (xy 128.277959 -243.700463) (xy 128.314211 -243.661392) (xy 128.355882 -243.628161)
			(xy 128.40204 -243.601512) (xy 128.451654 -243.58204) (xy 128.503616 -243.57018) (xy 128.556766 -243.566197)
			(xy 128.609916 -243.57018) (xy 128.661878 -243.58204) (xy 128.711492 -243.601512) (xy 128.75765 -243.628161)
			(xy 128.799321 -243.661392) (xy 128.835573 -243.700463) (xy 128.865597 -243.7445) (xy 128.888723 -243.792521)
			(xy 128.904433 -243.843451) (xy 128.912376 -243.896155) (xy 128.912874 -243.922804) (xy 128.912376 -243.949453)
			(xy 129.140702 -243.949453) (xy 129.140702 -243.896155) (xy 129.148645 -243.843451) (xy 129.164355 -243.792521)
			(xy 129.187481 -243.7445) (xy 129.217505 -243.700463) (xy 129.253757 -243.661392) (xy 129.295428 -243.628161)
			(xy 129.341586 -243.601512) (xy 129.3912 -243.58204) (xy 129.443162 -243.57018) (xy 129.496312 -243.566197)
			(xy 129.549462 -243.57018) (xy 129.601424 -243.58204) (xy 129.651038 -243.601512) (xy 129.697196 -243.628161)
			(xy 129.738867 -243.661392) (xy 129.775119 -243.700463) (xy 129.805143 -243.7445) (xy 129.828269 -243.792521)
			(xy 129.843979 -243.843451) (xy 129.851922 -243.896155) (xy 129.85242 -243.922804) (xy 129.851922 -243.949453)
			(xy 130.080756 -243.949453) (xy 130.080756 -243.896155) (xy 130.088699 -243.843451) (xy 130.104409 -243.792521)
			(xy 130.127535 -243.7445) (xy 130.157559 -243.700463) (xy 130.193811 -243.661392) (xy 130.235482 -243.628161)
			(xy 130.28164 -243.601512) (xy 130.331254 -243.58204) (xy 130.383216 -243.57018) (xy 130.436366 -243.566197)
			(xy 130.489516 -243.57018) (xy 130.541478 -243.58204) (xy 130.591092 -243.601512) (xy 130.63725 -243.628161)
			(xy 130.678921 -243.661392) (xy 130.715173 -243.700463) (xy 130.745197 -243.7445) (xy 130.768323 -243.792521)
			(xy 130.784033 -243.843451) (xy 130.791976 -243.896155) (xy 130.792474 -243.922804) (xy 130.791976 -243.949453)
			(xy 131.020556 -243.949453) (xy 131.020556 -243.896155) (xy 131.028499 -243.843451) (xy 131.044209 -243.792521)
			(xy 131.067335 -243.7445) (xy 131.097359 -243.700463) (xy 131.133611 -243.661392) (xy 131.175282 -243.628161)
			(xy 131.22144 -243.601512) (xy 131.271054 -243.58204) (xy 131.323016 -243.57018) (xy 131.376166 -243.566197)
			(xy 131.429316 -243.57018) (xy 131.481278 -243.58204) (xy 131.530892 -243.601512) (xy 131.57705 -243.628161)
			(xy 131.618721 -243.661392) (xy 131.654973 -243.700463) (xy 131.684997 -243.7445) (xy 131.708123 -243.792521)
			(xy 131.723833 -243.843451) (xy 131.731776 -243.896155) (xy 131.732274 -243.922804) (xy 131.731776 -243.949453)
			(xy 131.960356 -243.949453) (xy 131.960356 -243.896155) (xy 131.968299 -243.843451) (xy 131.984009 -243.792521)
			(xy 132.007135 -243.7445) (xy 132.037159 -243.700463) (xy 132.073411 -243.661392) (xy 132.115082 -243.628161)
			(xy 132.16124 -243.601512) (xy 132.210854 -243.58204) (xy 132.262816 -243.57018) (xy 132.315966 -243.566197)
			(xy 132.369116 -243.57018) (xy 132.421078 -243.58204) (xy 132.470692 -243.601512) (xy 132.51685 -243.628161)
			(xy 132.558521 -243.661392) (xy 132.594773 -243.700463) (xy 132.624797 -243.7445) (xy 132.647923 -243.792521)
			(xy 132.663633 -243.843451) (xy 132.671576 -243.896155) (xy 132.672074 -243.922804) (xy 132.671576 -243.949453)
			(xy 132.900156 -243.949453) (xy 132.900156 -243.896155) (xy 132.908099 -243.843451) (xy 132.923809 -243.792521)
			(xy 132.946935 -243.7445) (xy 132.976959 -243.700463) (xy 133.013211 -243.661392) (xy 133.054882 -243.628161)
			(xy 133.10104 -243.601512) (xy 133.150654 -243.58204) (xy 133.202616 -243.57018) (xy 133.255766 -243.566197)
			(xy 133.308916 -243.57018) (xy 133.360878 -243.58204) (xy 133.410492 -243.601512) (xy 133.45665 -243.628161)
			(xy 133.498321 -243.661392) (xy 133.534573 -243.700463) (xy 133.564597 -243.7445) (xy 133.587723 -243.792521)
			(xy 133.603433 -243.843451) (xy 133.611376 -243.896155) (xy 133.611874 -243.922804) (xy 133.611376 -243.949453)
			(xy 133.839956 -243.949453) (xy 133.839956 -243.896155) (xy 133.847899 -243.843451) (xy 133.863609 -243.792521)
			(xy 133.886735 -243.7445) (xy 133.916759 -243.700463) (xy 133.953011 -243.661392) (xy 133.994682 -243.628161)
			(xy 134.04084 -243.601512) (xy 134.090454 -243.58204) (xy 134.142416 -243.57018) (xy 134.195566 -243.566197)
			(xy 134.248716 -243.57018) (xy 134.300678 -243.58204) (xy 134.350292 -243.601512) (xy 134.39645 -243.628161)
			(xy 134.438121 -243.661392) (xy 134.474373 -243.700463) (xy 134.504397 -243.7445) (xy 134.527523 -243.792521)
			(xy 134.543233 -243.843451) (xy 134.551176 -243.896155) (xy 134.551674 -243.922804) (xy 134.551176 -243.949453)
			(xy 134.543233 -244.002157) (xy 134.527523 -244.053087) (xy 134.504397 -244.101108) (xy 134.474373 -244.145145)
			(xy 134.438121 -244.184216) (xy 134.39645 -244.217447) (xy 134.350292 -244.244096) (xy 134.300678 -244.263568)
			(xy 134.248716 -244.275428) (xy 134.195566 -244.279412) (xy 134.142416 -244.275428) (xy 134.090454 -244.263568)
			(xy 134.04084 -244.244096) (xy 133.994682 -244.217447) (xy 133.953011 -244.184216) (xy 133.916759 -244.145145)
			(xy 133.886735 -244.101108) (xy 133.863609 -244.053087) (xy 133.847899 -244.002157) (xy 133.839956 -243.949453)
			(xy 133.611376 -243.949453) (xy 133.603433 -244.002157) (xy 133.587723 -244.053087) (xy 133.564597 -244.101108)
			(xy 133.534573 -244.145145) (xy 133.498321 -244.184216) (xy 133.45665 -244.217447) (xy 133.410492 -244.244096)
			(xy 133.360878 -244.263568) (xy 133.308916 -244.275428) (xy 133.255766 -244.279412) (xy 133.202616 -244.275428)
			(xy 133.150654 -244.263568) (xy 133.10104 -244.244096) (xy 133.054882 -244.217447) (xy 133.013211 -244.184216)
			(xy 132.976959 -244.145145) (xy 132.946935 -244.101108) (xy 132.923809 -244.053087) (xy 132.908099 -244.002157)
			(xy 132.900156 -243.949453) (xy 132.671576 -243.949453) (xy 132.663633 -244.002157) (xy 132.647923 -244.053087)
			(xy 132.624797 -244.101108) (xy 132.594773 -244.145145) (xy 132.558521 -244.184216) (xy 132.51685 -244.217447)
			(xy 132.470692 -244.244096) (xy 132.421078 -244.263568) (xy 132.369116 -244.275428) (xy 132.315966 -244.279412)
			(xy 132.262816 -244.275428) (xy 132.210854 -244.263568) (xy 132.16124 -244.244096) (xy 132.115082 -244.217447)
			(xy 132.073411 -244.184216) (xy 132.037159 -244.145145) (xy 132.007135 -244.101108) (xy 131.984009 -244.053087)
			(xy 131.968299 -244.002157) (xy 131.960356 -243.949453) (xy 131.731776 -243.949453) (xy 131.723833 -244.002157)
			(xy 131.708123 -244.053087) (xy 131.684997 -244.101108) (xy 131.654973 -244.145145) (xy 131.618721 -244.184216)
			(xy 131.57705 -244.217447) (xy 131.530892 -244.244096) (xy 131.481278 -244.263568) (xy 131.429316 -244.275428)
			(xy 131.376166 -244.279412) (xy 131.323016 -244.275428) (xy 131.271054 -244.263568) (xy 131.22144 -244.244096)
			(xy 131.175282 -244.217447) (xy 131.133611 -244.184216) (xy 131.097359 -244.145145) (xy 131.067335 -244.101108)
			(xy 131.044209 -244.053087) (xy 131.028499 -244.002157) (xy 131.020556 -243.949453) (xy 130.791976 -243.949453)
			(xy 130.784033 -244.002157) (xy 130.768323 -244.053087) (xy 130.745197 -244.101108) (xy 130.715173 -244.145145)
			(xy 130.678921 -244.184216) (xy 130.63725 -244.217447) (xy 130.591092 -244.244096) (xy 130.541478 -244.263568)
			(xy 130.489516 -244.275428) (xy 130.436366 -244.279412) (xy 130.383216 -244.275428) (xy 130.331254 -244.263568)
			(xy 130.28164 -244.244096) (xy 130.235482 -244.217447) (xy 130.193811 -244.184216) (xy 130.157559 -244.145145)
			(xy 130.127535 -244.101108) (xy 130.104409 -244.053087) (xy 130.088699 -244.002157) (xy 130.080756 -243.949453)
			(xy 129.851922 -243.949453) (xy 129.843979 -244.002157) (xy 129.828269 -244.053087) (xy 129.805143 -244.101108)
			(xy 129.775119 -244.145145) (xy 129.738867 -244.184216) (xy 129.697196 -244.217447) (xy 129.651038 -244.244096)
			(xy 129.601424 -244.263568) (xy 129.549462 -244.275428) (xy 129.496312 -244.279412) (xy 129.443162 -244.275428)
			(xy 129.3912 -244.263568) (xy 129.341586 -244.244096) (xy 129.295428 -244.217447) (xy 129.253757 -244.184216)
			(xy 129.217505 -244.145145) (xy 129.187481 -244.101108) (xy 129.164355 -244.053087) (xy 129.148645 -244.002157)
			(xy 129.140702 -243.949453) (xy 128.912376 -243.949453) (xy 128.904433 -244.002157) (xy 128.888723 -244.053087)
			(xy 128.865597 -244.101108) (xy 128.835573 -244.145145) (xy 128.799321 -244.184216) (xy 128.75765 -244.217447)
			(xy 128.711492 -244.244096) (xy 128.661878 -244.263568) (xy 128.609916 -244.275428) (xy 128.556766 -244.279412)
			(xy 128.503616 -244.275428) (xy 128.451654 -244.263568) (xy 128.40204 -244.244096) (xy 128.355882 -244.217447)
			(xy 128.314211 -244.184216) (xy 128.277959 -244.145145) (xy 128.247935 -244.101108) (xy 128.224809 -244.053087)
			(xy 128.209099 -244.002157) (xy 128.201156 -243.949453) (xy 127.972576 -243.949453) (xy 127.964633 -244.002157)
			(xy 127.948923 -244.053087) (xy 127.925797 -244.101108) (xy 127.895773 -244.145145) (xy 127.859521 -244.184216)
			(xy 127.81785 -244.217447) (xy 127.771692 -244.244096) (xy 127.722078 -244.263568) (xy 127.670116 -244.275428)
			(xy 127.616966 -244.279412) (xy 127.563816 -244.275428) (xy 127.511854 -244.263568) (xy 127.46224 -244.244096)
			(xy 127.416082 -244.217447) (xy 127.374411 -244.184216) (xy 127.338159 -244.145145) (xy 127.308135 -244.101108)
			(xy 127.285009 -244.053087) (xy 127.269299 -244.002157) (xy 127.261356 -243.949453) (xy 127.032776 -243.949453)
			(xy 127.024833 -244.002157) (xy 127.009123 -244.053087) (xy 126.985997 -244.101108) (xy 126.955973 -244.145145)
			(xy 126.919721 -244.184216) (xy 126.87805 -244.217447) (xy 126.831892 -244.244096) (xy 126.782278 -244.263568)
			(xy 126.730316 -244.275428) (xy 126.677166 -244.279412) (xy 126.624016 -244.275428) (xy 126.572054 -244.263568)
			(xy 126.52244 -244.244096) (xy 126.476282 -244.217447) (xy 126.434611 -244.184216) (xy 126.398359 -244.145145)
			(xy 126.368335 -244.101108) (xy 126.345209 -244.053087) (xy 126.329499 -244.002157) (xy 126.321556 -243.949453)
			(xy 126.092976 -243.949453) (xy 126.085033 -244.002157) (xy 126.069323 -244.053087) (xy 126.046197 -244.101108)
			(xy 126.016173 -244.145145) (xy 125.979921 -244.184216) (xy 125.93825 -244.217447) (xy 125.892092 -244.244096)
			(xy 125.842478 -244.263568) (xy 125.790516 -244.275428) (xy 125.737366 -244.279412) (xy 125.684216 -244.275428)
			(xy 125.632254 -244.263568) (xy 125.58264 -244.244096) (xy 125.536482 -244.217447) (xy 125.494811 -244.184216)
			(xy 125.458559 -244.145145) (xy 125.428535 -244.101108) (xy 125.405409 -244.053087) (xy 125.389699 -244.002157)
			(xy 125.381756 -243.949453) (xy 125.153176 -243.949453) (xy 125.145233 -244.002157) (xy 125.129523 -244.053087)
			(xy 125.106397 -244.101108) (xy 125.076373 -244.145145) (xy 125.040121 -244.184216) (xy 124.99845 -244.217447)
			(xy 124.952292 -244.244096) (xy 124.902678 -244.263568) (xy 124.850716 -244.275428) (xy 124.797566 -244.279412)
			(xy 124.744416 -244.275428) (xy 124.692454 -244.263568) (xy 124.64284 -244.244096) (xy 124.596682 -244.217447)
			(xy 124.555011 -244.184216) (xy 124.518759 -244.145145) (xy 124.488735 -244.101108) (xy 124.465609 -244.053087)
			(xy 124.449899 -244.002157) (xy 124.441956 -243.949453) (xy 124.213376 -243.949453) (xy 124.205433 -244.002157)
			(xy 124.189723 -244.053087) (xy 124.166597 -244.101108) (xy 124.136573 -244.145145) (xy 124.100321 -244.184216)
			(xy 124.05865 -244.217447) (xy 124.012492 -244.244096) (xy 123.962878 -244.263568) (xy 123.910916 -244.275428)
			(xy 123.857766 -244.279412) (xy 123.804616 -244.275428) (xy 123.752654 -244.263568) (xy 123.70304 -244.244096)
			(xy 123.656882 -244.217447) (xy 123.615211 -244.184216) (xy 123.578959 -244.145145) (xy 123.548935 -244.101108)
			(xy 123.525809 -244.053087) (xy 123.510099 -244.002157) (xy 123.502156 -243.949453) (xy 123.273322 -243.949453)
			(xy 123.265379 -244.002157) (xy 123.249669 -244.053087) (xy 123.226543 -244.101108) (xy 123.196519 -244.145145)
			(xy 123.160267 -244.184216) (xy 123.118596 -244.217447) (xy 123.072438 -244.244096) (xy 123.022824 -244.263568)
			(xy 122.970862 -244.275428) (xy 122.917712 -244.279412) (xy 122.864562 -244.275428) (xy 122.8126 -244.263568)
			(xy 122.762986 -244.244096) (xy 122.716828 -244.217447) (xy 122.675157 -244.184216) (xy 122.638905 -244.145145)
			(xy 122.608881 -244.101108) (xy 122.585755 -244.053087) (xy 122.570045 -244.002157) (xy 122.562102 -243.949453)
			(xy 122.333522 -243.949453) (xy 122.325579 -244.002157) (xy 122.309869 -244.053087) (xy 122.286743 -244.101108)
			(xy 122.256719 -244.145145) (xy 122.220467 -244.184216) (xy 122.178796 -244.217447) (xy 122.132638 -244.244096)
			(xy 122.083024 -244.263568) (xy 122.031062 -244.275428) (xy 121.977912 -244.279412) (xy 121.924762 -244.275428)
			(xy 121.8728 -244.263568) (xy 121.823186 -244.244096) (xy 121.777028 -244.217447) (xy 121.735357 -244.184216)
			(xy 121.699105 -244.145145) (xy 121.669081 -244.101108) (xy 121.645955 -244.053087) (xy 121.630245 -244.002157)
			(xy 121.622302 -243.949453) (xy 121.316932 -243.949453) (xy 121.311774 -243.967596) (xy 121.291859 -244.012737)
			(xy 121.265903 -244.054696) (xy 121.250456 -244.073934) (xy 121.241831 -244.085064) (xy 121.230486 -244.110824)
			(xy 121.226607 -244.138703) (xy 121.230488 -244.166582) (xy 121.241834 -244.192341) (xy 121.250456 -244.203474)
			(xy 121.26451 -244.220949) (xy 121.288581 -244.258789) (xy 121.30771 -244.299351) (xy 121.314972 -244.320568)
			(xy 121.320121 -244.334616) (xy 121.337244 -244.359134) (xy 121.360722 -244.377657) (xy 121.388552 -244.388603)
			(xy 121.418358 -244.391038) (xy 121.433082 -244.388386) (xy 121.451592 -244.384681) (xy 121.489136 -244.38073)
			(xy 121.508012 -244.380512) (xy 121.534659 -244.381011) (xy 121.587358 -244.388956) (xy 121.638284 -244.404666)
			(xy 121.6863 -244.427791) (xy 121.730334 -244.457813) (xy 121.769401 -244.494063) (xy 121.802629 -244.535731)
			(xy 121.829275 -244.581886) (xy 121.848746 -244.631496) (xy 121.860604 -244.683455) (xy 121.864587 -244.7366)
			(xy 121.862607 -244.763015) (xy 122.092202 -244.763015) (xy 122.092202 -244.709717) (xy 122.100145 -244.657013)
			(xy 122.115855 -244.606083) (xy 122.138981 -244.558062) (xy 122.169005 -244.514025) (xy 122.205257 -244.474954)
			(xy 122.246928 -244.441723) (xy 122.293086 -244.415074) (xy 122.3427 -244.395602) (xy 122.394662 -244.383742)
			(xy 122.447812 -244.379759) (xy 122.500962 -244.383742) (xy 122.552924 -244.395602) (xy 122.602538 -244.415074)
			(xy 122.648696 -244.441723) (xy 122.690367 -244.474954) (xy 122.726619 -244.514025) (xy 122.756643 -244.558062)
			(xy 122.779769 -244.606083) (xy 122.795479 -244.657013) (xy 122.803422 -244.709717) (xy 122.80392 -244.736366)
			(xy 122.803422 -244.763015) (xy 122.803384 -244.763269) (xy 123.032002 -244.763269) (xy 123.032002 -244.709971)
			(xy 123.039945 -244.657267) (xy 123.055655 -244.606337) (xy 123.078781 -244.558316) (xy 123.108805 -244.514279)
			(xy 123.145057 -244.475208) (xy 123.186728 -244.441977) (xy 123.232886 -244.415328) (xy 123.2825 -244.395856)
			(xy 123.334462 -244.383996) (xy 123.387612 -244.380013) (xy 123.440762 -244.383996) (xy 123.492724 -244.395856)
			(xy 123.542338 -244.415328) (xy 123.588496 -244.441977) (xy 123.630167 -244.475208) (xy 123.666419 -244.514279)
			(xy 123.696443 -244.558316) (xy 123.719569 -244.606337) (xy 123.735279 -244.657267) (xy 123.743222 -244.709971)
			(xy 123.74372 -244.73662) (xy 123.743222 -244.763269) (xy 123.971802 -244.763269) (xy 123.971802 -244.709971)
			(xy 123.979745 -244.657267) (xy 123.995455 -244.606337) (xy 124.018581 -244.558316) (xy 124.048605 -244.514279)
			(xy 124.084857 -244.475208) (xy 124.126528 -244.441977) (xy 124.172686 -244.415328) (xy 124.2223 -244.395856)
			(xy 124.274262 -244.383996) (xy 124.327412 -244.380013) (xy 124.380562 -244.383996) (xy 124.432524 -244.395856)
			(xy 124.482138 -244.415328) (xy 124.528296 -244.441977) (xy 124.569967 -244.475208) (xy 124.606219 -244.514279)
			(xy 124.636243 -244.558316) (xy 124.659369 -244.606337) (xy 124.675079 -244.657267) (xy 124.683022 -244.709971)
			(xy 124.68352 -244.73662) (xy 124.683022 -244.763269) (xy 124.911856 -244.763269) (xy 124.911856 -244.709971)
			(xy 124.919799 -244.657267) (xy 124.935509 -244.606337) (xy 124.958635 -244.558316) (xy 124.988659 -244.514279)
			(xy 125.024911 -244.475208) (xy 125.066582 -244.441977) (xy 125.11274 -244.415328) (xy 125.162354 -244.395856)
			(xy 125.214316 -244.383996) (xy 125.267466 -244.380013) (xy 125.320616 -244.383996) (xy 125.372578 -244.395856)
			(xy 125.422192 -244.415328) (xy 125.46835 -244.441977) (xy 125.510021 -244.475208) (xy 125.546273 -244.514279)
			(xy 125.576297 -244.558316) (xy 125.599423 -244.606337) (xy 125.615133 -244.657267) (xy 125.623076 -244.709971)
			(xy 125.623574 -244.73662) (xy 125.623076 -244.763269) (xy 125.851402 -244.763269) (xy 125.851402 -244.709971)
			(xy 125.859345 -244.657267) (xy 125.875055 -244.606337) (xy 125.898181 -244.558316) (xy 125.928205 -244.514279)
			(xy 125.964457 -244.475208) (xy 126.006128 -244.441977) (xy 126.052286 -244.415328) (xy 126.1019 -244.395856)
			(xy 126.153862 -244.383996) (xy 126.207012 -244.380013) (xy 126.260162 -244.383996) (xy 126.312124 -244.395856)
			(xy 126.361738 -244.415328) (xy 126.407896 -244.441977) (xy 126.449567 -244.475208) (xy 126.485819 -244.514279)
			(xy 126.515843 -244.558316) (xy 126.538969 -244.606337) (xy 126.554679 -244.657267) (xy 126.562622 -244.709971)
			(xy 126.56312 -244.73662) (xy 126.562622 -244.763269) (xy 126.791456 -244.763269) (xy 126.791456 -244.709971)
			(xy 126.799399 -244.657267) (xy 126.815109 -244.606337) (xy 126.838235 -244.558316) (xy 126.868259 -244.514279)
			(xy 126.904511 -244.475208) (xy 126.946182 -244.441977) (xy 126.99234 -244.415328) (xy 127.041954 -244.395856)
			(xy 127.093916 -244.383996) (xy 127.147066 -244.380013) (xy 127.200216 -244.383996) (xy 127.252178 -244.395856)
			(xy 127.301792 -244.415328) (xy 127.34795 -244.441977) (xy 127.389621 -244.475208) (xy 127.425873 -244.514279)
			(xy 127.455897 -244.558316) (xy 127.479023 -244.606337) (xy 127.494733 -244.657267) (xy 127.502676 -244.709971)
			(xy 127.503174 -244.73662) (xy 127.502676 -244.763269) (xy 127.731002 -244.763269) (xy 127.731002 -244.709971)
			(xy 127.738945 -244.657267) (xy 127.754655 -244.606337) (xy 127.777781 -244.558316) (xy 127.807805 -244.514279)
			(xy 127.844057 -244.475208) (xy 127.885728 -244.441977) (xy 127.931886 -244.415328) (xy 127.9815 -244.395856)
			(xy 128.033462 -244.383996) (xy 128.086612 -244.380013) (xy 128.139762 -244.383996) (xy 128.191724 -244.395856)
			(xy 128.241338 -244.415328) (xy 128.287496 -244.441977) (xy 128.329167 -244.475208) (xy 128.365419 -244.514279)
			(xy 128.395443 -244.558316) (xy 128.418569 -244.606337) (xy 128.434279 -244.657267) (xy 128.442222 -244.709971)
			(xy 128.44272 -244.73662) (xy 128.442222 -244.763269) (xy 128.670802 -244.763269) (xy 128.670802 -244.709971)
			(xy 128.678745 -244.657267) (xy 128.694455 -244.606337) (xy 128.717581 -244.558316) (xy 128.747605 -244.514279)
			(xy 128.783857 -244.475208) (xy 128.825528 -244.441977) (xy 128.871686 -244.415328) (xy 128.9213 -244.395856)
			(xy 128.973262 -244.383996) (xy 129.026412 -244.380013) (xy 129.079562 -244.383996) (xy 129.131524 -244.395856)
			(xy 129.181138 -244.415328) (xy 129.227296 -244.441977) (xy 129.268967 -244.475208) (xy 129.305219 -244.514279)
			(xy 129.335243 -244.558316) (xy 129.358369 -244.606337) (xy 129.374079 -244.657267) (xy 129.382022 -244.709971)
			(xy 129.38252 -244.73662) (xy 129.382022 -244.763269) (xy 129.610602 -244.763269) (xy 129.610602 -244.709971)
			(xy 129.618545 -244.657267) (xy 129.634255 -244.606337) (xy 129.657381 -244.558316) (xy 129.687405 -244.514279)
			(xy 129.723657 -244.475208) (xy 129.765328 -244.441977) (xy 129.811486 -244.415328) (xy 129.8611 -244.395856)
			(xy 129.913062 -244.383996) (xy 129.966212 -244.380013) (xy 130.019362 -244.383996) (xy 130.071324 -244.395856)
			(xy 130.120938 -244.415328) (xy 130.167096 -244.441977) (xy 130.208767 -244.475208) (xy 130.245019 -244.514279)
			(xy 130.275043 -244.558316) (xy 130.298169 -244.606337) (xy 130.313879 -244.657267) (xy 130.321822 -244.709971)
			(xy 130.32232 -244.73662) (xy 130.321822 -244.763269) (xy 130.550402 -244.763269) (xy 130.550402 -244.709971)
			(xy 130.558345 -244.657267) (xy 130.574055 -244.606337) (xy 130.597181 -244.558316) (xy 130.627205 -244.514279)
			(xy 130.663457 -244.475208) (xy 130.705128 -244.441977) (xy 130.751286 -244.415328) (xy 130.8009 -244.395856)
			(xy 130.852862 -244.383996) (xy 130.906012 -244.380013) (xy 130.959162 -244.383996) (xy 131.011124 -244.395856)
			(xy 131.060738 -244.415328) (xy 131.106896 -244.441977) (xy 131.148567 -244.475208) (xy 131.184819 -244.514279)
			(xy 131.214843 -244.558316) (xy 131.237969 -244.606337) (xy 131.253679 -244.657267) (xy 131.261622 -244.709971)
			(xy 131.26212 -244.73662) (xy 131.261622 -244.763269) (xy 131.490456 -244.763269) (xy 131.490456 -244.709971)
			(xy 131.498399 -244.657267) (xy 131.514109 -244.606337) (xy 131.537235 -244.558316) (xy 131.567259 -244.514279)
			(xy 131.603511 -244.475208) (xy 131.645182 -244.441977) (xy 131.69134 -244.415328) (xy 131.740954 -244.395856)
			(xy 131.792916 -244.383996) (xy 131.846066 -244.380013) (xy 131.899216 -244.383996) (xy 131.951178 -244.395856)
			(xy 132.000792 -244.415328) (xy 132.04695 -244.441977) (xy 132.088621 -244.475208) (xy 132.124873 -244.514279)
			(xy 132.154897 -244.558316) (xy 132.178023 -244.606337) (xy 132.193733 -244.657267) (xy 132.201676 -244.709971)
			(xy 132.202174 -244.73662) (xy 132.201676 -244.763269) (xy 132.430002 -244.763269) (xy 132.430002 -244.709971)
			(xy 132.437945 -244.657267) (xy 132.453655 -244.606337) (xy 132.476781 -244.558316) (xy 132.506805 -244.514279)
			(xy 132.543057 -244.475208) (xy 132.584728 -244.441977) (xy 132.630886 -244.415328) (xy 132.6805 -244.395856)
			(xy 132.732462 -244.383996) (xy 132.785612 -244.380013) (xy 132.838762 -244.383996) (xy 132.890724 -244.395856)
			(xy 132.940338 -244.415328) (xy 132.986496 -244.441977) (xy 133.028167 -244.475208) (xy 133.064419 -244.514279)
			(xy 133.094443 -244.558316) (xy 133.117569 -244.606337) (xy 133.133279 -244.657267) (xy 133.141222 -244.709971)
			(xy 133.14172 -244.73662) (xy 133.141222 -244.763269) (xy 133.370056 -244.763269) (xy 133.370056 -244.709971)
			(xy 133.377999 -244.657267) (xy 133.393709 -244.606337) (xy 133.416835 -244.558316) (xy 133.446859 -244.514279)
			(xy 133.483111 -244.475208) (xy 133.524782 -244.441977) (xy 133.57094 -244.415328) (xy 133.620554 -244.395856)
			(xy 133.672516 -244.383996) (xy 133.725666 -244.380013) (xy 133.778816 -244.383996) (xy 133.830778 -244.395856)
			(xy 133.880392 -244.415328) (xy 133.92655 -244.441977) (xy 133.968221 -244.475208) (xy 134.004473 -244.514279)
			(xy 134.034497 -244.558316) (xy 134.057623 -244.606337) (xy 134.073333 -244.657267) (xy 134.081276 -244.709971)
			(xy 134.081774 -244.73662) (xy 134.081276 -244.763269) (xy 134.309602 -244.763269) (xy 134.309602 -244.709971)
			(xy 134.317545 -244.657267) (xy 134.333255 -244.606337) (xy 134.356381 -244.558316) (xy 134.386405 -244.514279)
			(xy 134.422657 -244.475208) (xy 134.464328 -244.441977) (xy 134.510486 -244.415328) (xy 134.5601 -244.395856)
			(xy 134.612062 -244.383996) (xy 134.665212 -244.380013) (xy 134.718362 -244.383996) (xy 134.770324 -244.395856)
			(xy 134.819938 -244.415328) (xy 134.866096 -244.441977) (xy 134.907767 -244.475208) (xy 134.944019 -244.514279)
			(xy 134.974043 -244.558316) (xy 134.997169 -244.606337) (xy 135.012879 -244.657267) (xy 135.020822 -244.709971)
			(xy 135.02132 -244.73662) (xy 135.020822 -244.763269) (xy 135.012879 -244.815973) (xy 134.997169 -244.866903)
			(xy 134.974043 -244.914924) (xy 134.944019 -244.958961) (xy 134.907767 -244.998032) (xy 134.866096 -245.031263)
			(xy 134.819938 -245.057912) (xy 134.770324 -245.077384) (xy 134.718362 -245.089244) (xy 134.665212 -245.093228)
			(xy 134.612062 -245.089244) (xy 134.5601 -245.077384) (xy 134.510486 -245.057912) (xy 134.464328 -245.031263)
			(xy 134.422657 -244.998032) (xy 134.386405 -244.958961) (xy 134.356381 -244.914924) (xy 134.333255 -244.866903)
			(xy 134.317545 -244.815973) (xy 134.309602 -244.763269) (xy 134.081276 -244.763269) (xy 134.073333 -244.815973)
			(xy 134.057623 -244.866903) (xy 134.034497 -244.914924) (xy 134.004473 -244.958961) (xy 133.968221 -244.998032)
			(xy 133.92655 -245.031263) (xy 133.880392 -245.057912) (xy 133.830778 -245.077384) (xy 133.778816 -245.089244)
			(xy 133.725666 -245.093228) (xy 133.672516 -245.089244) (xy 133.620554 -245.077384) (xy 133.57094 -245.057912)
			(xy 133.524782 -245.031263) (xy 133.483111 -244.998032) (xy 133.446859 -244.958961) (xy 133.416835 -244.914924)
			(xy 133.393709 -244.866903) (xy 133.377999 -244.815973) (xy 133.370056 -244.763269) (xy 133.141222 -244.763269)
			(xy 133.133279 -244.815973) (xy 133.117569 -244.866903) (xy 133.094443 -244.914924) (xy 133.064419 -244.958961)
			(xy 133.028167 -244.998032) (xy 132.986496 -245.031263) (xy 132.940338 -245.057912) (xy 132.890724 -245.077384)
			(xy 132.838762 -245.089244) (xy 132.785612 -245.093228) (xy 132.732462 -245.089244) (xy 132.6805 -245.077384)
			(xy 132.630886 -245.057912) (xy 132.584728 -245.031263) (xy 132.543057 -244.998032) (xy 132.506805 -244.958961)
			(xy 132.476781 -244.914924) (xy 132.453655 -244.866903) (xy 132.437945 -244.815973) (xy 132.430002 -244.763269)
			(xy 132.201676 -244.763269) (xy 132.193733 -244.815973) (xy 132.178023 -244.866903) (xy 132.154897 -244.914924)
			(xy 132.124873 -244.958961) (xy 132.088621 -244.998032) (xy 132.04695 -245.031263) (xy 132.000792 -245.057912)
			(xy 131.951178 -245.077384) (xy 131.899216 -245.089244) (xy 131.846066 -245.093228) (xy 131.792916 -245.089244)
			(xy 131.740954 -245.077384) (xy 131.69134 -245.057912) (xy 131.645182 -245.031263) (xy 131.603511 -244.998032)
			(xy 131.567259 -244.958961) (xy 131.537235 -244.914924) (xy 131.514109 -244.866903) (xy 131.498399 -244.815973)
			(xy 131.490456 -244.763269) (xy 131.261622 -244.763269) (xy 131.253679 -244.815973) (xy 131.237969 -244.866903)
			(xy 131.214843 -244.914924) (xy 131.184819 -244.958961) (xy 131.148567 -244.998032) (xy 131.106896 -245.031263)
			(xy 131.060738 -245.057912) (xy 131.011124 -245.077384) (xy 130.959162 -245.089244) (xy 130.906012 -245.093228)
			(xy 130.852862 -245.089244) (xy 130.8009 -245.077384) (xy 130.751286 -245.057912) (xy 130.705128 -245.031263)
			(xy 130.663457 -244.998032) (xy 130.627205 -244.958961) (xy 130.597181 -244.914924) (xy 130.574055 -244.866903)
			(xy 130.558345 -244.815973) (xy 130.550402 -244.763269) (xy 130.321822 -244.763269) (xy 130.313879 -244.815973)
			(xy 130.298169 -244.866903) (xy 130.275043 -244.914924) (xy 130.245019 -244.958961) (xy 130.208767 -244.998032)
			(xy 130.167096 -245.031263) (xy 130.120938 -245.057912) (xy 130.071324 -245.077384) (xy 130.019362 -245.089244)
			(xy 129.966212 -245.093228) (xy 129.913062 -245.089244) (xy 129.8611 -245.077384) (xy 129.811486 -245.057912)
			(xy 129.765328 -245.031263) (xy 129.723657 -244.998032) (xy 129.687405 -244.958961) (xy 129.657381 -244.914924)
			(xy 129.634255 -244.866903) (xy 129.618545 -244.815973) (xy 129.610602 -244.763269) (xy 129.382022 -244.763269)
			(xy 129.374079 -244.815973) (xy 129.358369 -244.866903) (xy 129.335243 -244.914924) (xy 129.305219 -244.958961)
			(xy 129.268967 -244.998032) (xy 129.227296 -245.031263) (xy 129.181138 -245.057912) (xy 129.131524 -245.077384)
			(xy 129.079562 -245.089244) (xy 129.026412 -245.093228) (xy 128.973262 -245.089244) (xy 128.9213 -245.077384)
			(xy 128.871686 -245.057912) (xy 128.825528 -245.031263) (xy 128.783857 -244.998032) (xy 128.747605 -244.958961)
			(xy 128.717581 -244.914924) (xy 128.694455 -244.866903) (xy 128.678745 -244.815973) (xy 128.670802 -244.763269)
			(xy 128.442222 -244.763269) (xy 128.434279 -244.815973) (xy 128.418569 -244.866903) (xy 128.395443 -244.914924)
			(xy 128.365419 -244.958961) (xy 128.329167 -244.998032) (xy 128.287496 -245.031263) (xy 128.241338 -245.057912)
			(xy 128.191724 -245.077384) (xy 128.139762 -245.089244) (xy 128.086612 -245.093228) (xy 128.033462 -245.089244)
			(xy 127.9815 -245.077384) (xy 127.931886 -245.057912) (xy 127.885728 -245.031263) (xy 127.844057 -244.998032)
			(xy 127.807805 -244.958961) (xy 127.777781 -244.914924) (xy 127.754655 -244.866903) (xy 127.738945 -244.815973)
			(xy 127.731002 -244.763269) (xy 127.502676 -244.763269) (xy 127.494733 -244.815973) (xy 127.479023 -244.866903)
			(xy 127.455897 -244.914924) (xy 127.425873 -244.958961) (xy 127.389621 -244.998032) (xy 127.34795 -245.031263)
			(xy 127.301792 -245.057912) (xy 127.252178 -245.077384) (xy 127.200216 -245.089244) (xy 127.147066 -245.093228)
			(xy 127.093916 -245.089244) (xy 127.041954 -245.077384) (xy 126.99234 -245.057912) (xy 126.946182 -245.031263)
			(xy 126.904511 -244.998032) (xy 126.868259 -244.958961) (xy 126.838235 -244.914924) (xy 126.815109 -244.866903)
			(xy 126.799399 -244.815973) (xy 126.791456 -244.763269) (xy 126.562622 -244.763269) (xy 126.554679 -244.815973)
			(xy 126.538969 -244.866903) (xy 126.515843 -244.914924) (xy 126.485819 -244.958961) (xy 126.449567 -244.998032)
			(xy 126.407896 -245.031263) (xy 126.361738 -245.057912) (xy 126.312124 -245.077384) (xy 126.260162 -245.089244)
			(xy 126.207012 -245.093228) (xy 126.153862 -245.089244) (xy 126.1019 -245.077384) (xy 126.052286 -245.057912)
			(xy 126.006128 -245.031263) (xy 125.964457 -244.998032) (xy 125.928205 -244.958961) (xy 125.898181 -244.914924)
			(xy 125.875055 -244.866903) (xy 125.859345 -244.815973) (xy 125.851402 -244.763269) (xy 125.623076 -244.763269)
			(xy 125.615133 -244.815973) (xy 125.599423 -244.866903) (xy 125.576297 -244.914924) (xy 125.546273 -244.958961)
			(xy 125.510021 -244.998032) (xy 125.46835 -245.031263) (xy 125.422192 -245.057912) (xy 125.372578 -245.077384)
			(xy 125.320616 -245.089244) (xy 125.267466 -245.093228) (xy 125.214316 -245.089244) (xy 125.162354 -245.077384)
			(xy 125.11274 -245.057912) (xy 125.066582 -245.031263) (xy 125.024911 -244.998032) (xy 124.988659 -244.958961)
			(xy 124.958635 -244.914924) (xy 124.935509 -244.866903) (xy 124.919799 -244.815973) (xy 124.911856 -244.763269)
			(xy 124.683022 -244.763269) (xy 124.675079 -244.815973) (xy 124.659369 -244.866903) (xy 124.636243 -244.914924)
			(xy 124.606219 -244.958961) (xy 124.569967 -244.998032) (xy 124.528296 -245.031263) (xy 124.482138 -245.057912)
			(xy 124.432524 -245.077384) (xy 124.380562 -245.089244) (xy 124.327412 -245.093228) (xy 124.274262 -245.089244)
			(xy 124.2223 -245.077384) (xy 124.172686 -245.057912) (xy 124.126528 -245.031263) (xy 124.084857 -244.998032)
			(xy 124.048605 -244.958961) (xy 124.018581 -244.914924) (xy 123.995455 -244.866903) (xy 123.979745 -244.815973)
			(xy 123.971802 -244.763269) (xy 123.743222 -244.763269) (xy 123.735279 -244.815973) (xy 123.719569 -244.866903)
			(xy 123.696443 -244.914924) (xy 123.666419 -244.958961) (xy 123.630167 -244.998032) (xy 123.588496 -245.031263)
			(xy 123.542338 -245.057912) (xy 123.492724 -245.077384) (xy 123.440762 -245.089244) (xy 123.387612 -245.093228)
			(xy 123.334462 -245.089244) (xy 123.2825 -245.077384) (xy 123.232886 -245.057912) (xy 123.186728 -245.031263)
			(xy 123.145057 -244.998032) (xy 123.108805 -244.958961) (xy 123.078781 -244.914924) (xy 123.055655 -244.866903)
			(xy 123.039945 -244.815973) (xy 123.032002 -244.763269) (xy 122.803384 -244.763269) (xy 122.795479 -244.815719)
			(xy 122.779769 -244.866649) (xy 122.756643 -244.91467) (xy 122.726619 -244.958707) (xy 122.690367 -244.997778)
			(xy 122.648696 -245.031009) (xy 122.602538 -245.057658) (xy 122.552924 -245.07713) (xy 122.500962 -245.08899)
			(xy 122.447812 -245.092974) (xy 122.394662 -245.08899) (xy 122.3427 -245.07713) (xy 122.293086 -245.057658)
			(xy 122.246928 -245.031009) (xy 122.205257 -244.997778) (xy 122.169005 -244.958707) (xy 122.138981 -244.91467)
			(xy 122.115855 -244.866649) (xy 122.100145 -244.815719) (xy 122.092202 -244.763015) (xy 121.862607 -244.763015)
			(xy 121.860604 -244.789745) (xy 121.848746 -244.841704) (xy 121.829275 -244.891314) (xy 121.802629 -244.937469)
			(xy 121.769401 -244.979137) (xy 121.730334 -245.015387) (xy 121.6863 -245.045409) (xy 121.638284 -245.068534)
			(xy 121.587358 -245.084244) (xy 121.534659 -245.092189) (xy 121.508012 -245.092728) (xy 121.487307 -245.092426)
			(xy 121.44618 -245.087589) (xy 121.42597 -245.083076) (xy 121.411672 -245.080184) (xy 121.382556 -245.081764)
			(xy 121.355067 -245.091492) (xy 121.331439 -245.10858) (xy 121.31359 -245.131638) (xy 121.30786 -245.145052)
			(xy 121.296985 -245.171266) (xy 121.268149 -245.220144) (xy 121.250456 -245.242334) (xy 121.241831 -245.253464)
			(xy 121.230486 -245.279224) (xy 121.226607 -245.307103) (xy 121.230488 -245.334982) (xy 121.241834 -245.360741)
			(xy 121.250456 -245.371874) (xy 121.265891 -245.391122) (xy 121.291861 -245.433073) (xy 121.311784 -245.47821)
			(xy 121.325277 -245.525668) (xy 121.332082 -245.574535) (xy 121.332129 -245.577339) (xy 121.622556 -245.577339)
			(xy 121.622556 -245.524041) (xy 121.630499 -245.471337) (xy 121.646209 -245.420407) (xy 121.669335 -245.372386)
			(xy 121.699359 -245.328349) (xy 121.735611 -245.289278) (xy 121.777282 -245.256047) (xy 121.82344 -245.229398)
			(xy 121.873054 -245.209926) (xy 121.925016 -245.198066) (xy 121.978166 -245.194083) (xy 122.031316 -245.198066)
			(xy 122.083278 -245.209926) (xy 122.132892 -245.229398) (xy 122.17905 -245.256047) (xy 122.220721 -245.289278)
			(xy 122.256973 -245.328349) (xy 122.286997 -245.372386) (xy 122.310123 -245.420407) (xy 122.325833 -245.471337)
			(xy 122.333776 -245.524041) (xy 122.334274 -245.55069) (xy 122.333776 -245.577339) (xy 122.562356 -245.577339)
			(xy 122.562356 -245.524041) (xy 122.570299 -245.471337) (xy 122.586009 -245.420407) (xy 122.609135 -245.372386)
			(xy 122.639159 -245.328349) (xy 122.675411 -245.289278) (xy 122.717082 -245.256047) (xy 122.76324 -245.229398)
			(xy 122.812854 -245.209926) (xy 122.864816 -245.198066) (xy 122.917966 -245.194083) (xy 122.971116 -245.198066)
			(xy 123.023078 -245.209926) (xy 123.072692 -245.229398) (xy 123.11885 -245.256047) (xy 123.160521 -245.289278)
			(xy 123.196773 -245.328349) (xy 123.226797 -245.372386) (xy 123.249923 -245.420407) (xy 123.265633 -245.471337)
			(xy 123.273576 -245.524041) (xy 123.274074 -245.55069) (xy 123.273576 -245.577339) (xy 123.502156 -245.577339)
			(xy 123.502156 -245.524041) (xy 123.510099 -245.471337) (xy 123.525809 -245.420407) (xy 123.548935 -245.372386)
			(xy 123.578959 -245.328349) (xy 123.615211 -245.289278) (xy 123.656882 -245.256047) (xy 123.70304 -245.229398)
			(xy 123.752654 -245.209926) (xy 123.804616 -245.198066) (xy 123.857766 -245.194083) (xy 123.910916 -245.198066)
			(xy 123.962878 -245.209926) (xy 124.012492 -245.229398) (xy 124.05865 -245.256047) (xy 124.100321 -245.289278)
			(xy 124.136573 -245.328349) (xy 124.166597 -245.372386) (xy 124.189723 -245.420407) (xy 124.205433 -245.471337)
			(xy 124.213376 -245.524041) (xy 124.213874 -245.55069) (xy 124.213376 -245.577339) (xy 124.441956 -245.577339)
			(xy 124.441956 -245.524041) (xy 124.449899 -245.471337) (xy 124.465609 -245.420407) (xy 124.488735 -245.372386)
			(xy 124.518759 -245.328349) (xy 124.555011 -245.289278) (xy 124.596682 -245.256047) (xy 124.64284 -245.229398)
			(xy 124.692454 -245.209926) (xy 124.744416 -245.198066) (xy 124.797566 -245.194083) (xy 124.850716 -245.198066)
			(xy 124.902678 -245.209926) (xy 124.952292 -245.229398) (xy 124.99845 -245.256047) (xy 125.040121 -245.289278)
			(xy 125.076373 -245.328349) (xy 125.106397 -245.372386) (xy 125.129523 -245.420407) (xy 125.145233 -245.471337)
			(xy 125.153176 -245.524041) (xy 125.153674 -245.55069) (xy 125.153176 -245.577339) (xy 125.381502 -245.577339)
			(xy 125.381502 -245.524041) (xy 125.389445 -245.471337) (xy 125.405155 -245.420407) (xy 125.428281 -245.372386)
			(xy 125.458305 -245.328349) (xy 125.494557 -245.289278) (xy 125.536228 -245.256047) (xy 125.582386 -245.229398)
			(xy 125.632 -245.209926) (xy 125.683962 -245.198066) (xy 125.737112 -245.194083) (xy 125.790262 -245.198066)
			(xy 125.842224 -245.209926) (xy 125.891838 -245.229398) (xy 125.937996 -245.256047) (xy 125.979667 -245.289278)
			(xy 126.015919 -245.328349) (xy 126.045943 -245.372386) (xy 126.069069 -245.420407) (xy 126.084779 -245.471337)
			(xy 126.092722 -245.524041) (xy 126.09322 -245.55069) (xy 126.092722 -245.577339) (xy 126.321556 -245.577339)
			(xy 126.321556 -245.524041) (xy 126.329499 -245.471337) (xy 126.345209 -245.420407) (xy 126.368335 -245.372386)
			(xy 126.398359 -245.328349) (xy 126.434611 -245.289278) (xy 126.476282 -245.256047) (xy 126.52244 -245.229398)
			(xy 126.572054 -245.209926) (xy 126.624016 -245.198066) (xy 126.677166 -245.194083) (xy 126.730316 -245.198066)
			(xy 126.782278 -245.209926) (xy 126.831892 -245.229398) (xy 126.87805 -245.256047) (xy 126.919721 -245.289278)
			(xy 126.955973 -245.328349) (xy 126.985997 -245.372386) (xy 127.009123 -245.420407) (xy 127.024833 -245.471337)
			(xy 127.032776 -245.524041) (xy 127.033274 -245.55069) (xy 127.032776 -245.577339) (xy 127.261102 -245.577339)
			(xy 127.261102 -245.524041) (xy 127.269045 -245.471337) (xy 127.284755 -245.420407) (xy 127.307881 -245.372386)
			(xy 127.337905 -245.328349) (xy 127.374157 -245.289278) (xy 127.415828 -245.256047) (xy 127.461986 -245.229398)
			(xy 127.5116 -245.209926) (xy 127.563562 -245.198066) (xy 127.616712 -245.194083) (xy 127.669862 -245.198066)
			(xy 127.721824 -245.209926) (xy 127.771438 -245.229398) (xy 127.817596 -245.256047) (xy 127.859267 -245.289278)
			(xy 127.895519 -245.328349) (xy 127.925543 -245.372386) (xy 127.948669 -245.420407) (xy 127.964379 -245.471337)
			(xy 127.972322 -245.524041) (xy 127.97282 -245.55069) (xy 127.972322 -245.577339) (xy 128.201156 -245.577339)
			(xy 128.201156 -245.524041) (xy 128.209099 -245.471337) (xy 128.224809 -245.420407) (xy 128.247935 -245.372386)
			(xy 128.277959 -245.328349) (xy 128.314211 -245.289278) (xy 128.355882 -245.256047) (xy 128.40204 -245.229398)
			(xy 128.451654 -245.209926) (xy 128.503616 -245.198066) (xy 128.556766 -245.194083) (xy 128.609916 -245.198066)
			(xy 128.661878 -245.209926) (xy 128.711492 -245.229398) (xy 128.75765 -245.256047) (xy 128.799321 -245.289278)
			(xy 128.835573 -245.328349) (xy 128.865597 -245.372386) (xy 128.888723 -245.420407) (xy 128.904433 -245.471337)
			(xy 128.912376 -245.524041) (xy 128.912874 -245.55069) (xy 128.912376 -245.577339) (xy 129.140956 -245.577339)
			(xy 129.140956 -245.524041) (xy 129.148899 -245.471337) (xy 129.164609 -245.420407) (xy 129.187735 -245.372386)
			(xy 129.217759 -245.328349) (xy 129.254011 -245.289278) (xy 129.295682 -245.256047) (xy 129.34184 -245.229398)
			(xy 129.391454 -245.209926) (xy 129.443416 -245.198066) (xy 129.496566 -245.194083) (xy 129.549716 -245.198066)
			(xy 129.601678 -245.209926) (xy 129.651292 -245.229398) (xy 129.69745 -245.256047) (xy 129.739121 -245.289278)
			(xy 129.775373 -245.328349) (xy 129.805397 -245.372386) (xy 129.828523 -245.420407) (xy 129.844233 -245.471337)
			(xy 129.852176 -245.524041) (xy 129.852674 -245.55069) (xy 129.852176 -245.577339) (xy 130.080756 -245.577339)
			(xy 130.080756 -245.524041) (xy 130.088699 -245.471337) (xy 130.104409 -245.420407) (xy 130.127535 -245.372386)
			(xy 130.157559 -245.328349) (xy 130.193811 -245.289278) (xy 130.235482 -245.256047) (xy 130.28164 -245.229398)
			(xy 130.331254 -245.209926) (xy 130.383216 -245.198066) (xy 130.436366 -245.194083) (xy 130.489516 -245.198066)
			(xy 130.541478 -245.209926) (xy 130.591092 -245.229398) (xy 130.63725 -245.256047) (xy 130.678921 -245.289278)
			(xy 130.715173 -245.328349) (xy 130.745197 -245.372386) (xy 130.768323 -245.420407) (xy 130.784033 -245.471337)
			(xy 130.791976 -245.524041) (xy 130.792474 -245.55069) (xy 130.791976 -245.577339) (xy 131.020556 -245.577339)
			(xy 131.020556 -245.524041) (xy 131.028499 -245.471337) (xy 131.044209 -245.420407) (xy 131.067335 -245.372386)
			(xy 131.097359 -245.328349) (xy 131.133611 -245.289278) (xy 131.175282 -245.256047) (xy 131.22144 -245.229398)
			(xy 131.271054 -245.209926) (xy 131.323016 -245.198066) (xy 131.376166 -245.194083) (xy 131.429316 -245.198066)
			(xy 131.481278 -245.209926) (xy 131.530892 -245.229398) (xy 131.57705 -245.256047) (xy 131.618721 -245.289278)
			(xy 131.654973 -245.328349) (xy 131.684997 -245.372386) (xy 131.708123 -245.420407) (xy 131.723833 -245.471337)
			(xy 131.731776 -245.524041) (xy 131.732274 -245.55069) (xy 131.731776 -245.577339) (xy 131.960102 -245.577339)
			(xy 131.960102 -245.524041) (xy 131.968045 -245.471337) (xy 131.983755 -245.420407) (xy 132.006881 -245.372386)
			(xy 132.036905 -245.328349) (xy 132.073157 -245.289278) (xy 132.114828 -245.256047) (xy 132.160986 -245.229398)
			(xy 132.2106 -245.209926) (xy 132.262562 -245.198066) (xy 132.315712 -245.194083) (xy 132.368862 -245.198066)
			(xy 132.420824 -245.209926) (xy 132.470438 -245.229398) (xy 132.516596 -245.256047) (xy 132.558267 -245.289278)
			(xy 132.594519 -245.328349) (xy 132.624543 -245.372386) (xy 132.647669 -245.420407) (xy 132.663379 -245.471337)
			(xy 132.671322 -245.524041) (xy 132.67182 -245.55069) (xy 132.671322 -245.577339) (xy 132.900156 -245.577339)
			(xy 132.900156 -245.524041) (xy 132.908099 -245.471337) (xy 132.923809 -245.420407) (xy 132.946935 -245.372386)
			(xy 132.976959 -245.328349) (xy 133.013211 -245.289278) (xy 133.054882 -245.256047) (xy 133.10104 -245.229398)
			(xy 133.150654 -245.209926) (xy 133.202616 -245.198066) (xy 133.255766 -245.194083) (xy 133.308916 -245.198066)
			(xy 133.360878 -245.209926) (xy 133.410492 -245.229398) (xy 133.45665 -245.256047) (xy 133.498321 -245.289278)
			(xy 133.534573 -245.328349) (xy 133.564597 -245.372386) (xy 133.587723 -245.420407) (xy 133.603433 -245.471337)
			(xy 133.611376 -245.524041) (xy 133.611874 -245.55069) (xy 133.611376 -245.577339) (xy 133.839956 -245.577339)
			(xy 133.839956 -245.524041) (xy 133.847899 -245.471337) (xy 133.863609 -245.420407) (xy 133.886735 -245.372386)
			(xy 133.916759 -245.328349) (xy 133.953011 -245.289278) (xy 133.994682 -245.256047) (xy 134.04084 -245.229398)
			(xy 134.090454 -245.209926) (xy 134.142416 -245.198066) (xy 134.195566 -245.194083) (xy 134.248716 -245.198066)
			(xy 134.300678 -245.209926) (xy 134.350292 -245.229398) (xy 134.39645 -245.256047) (xy 134.438121 -245.289278)
			(xy 134.474373 -245.328349) (xy 134.504397 -245.372386) (xy 134.527523 -245.420407) (xy 134.543233 -245.471337)
			(xy 134.551176 -245.524041) (xy 134.551674 -245.55069) (xy 134.551176 -245.577339) (xy 134.543233 -245.630043)
			(xy 134.527523 -245.680973) (xy 134.504397 -245.728994) (xy 134.474373 -245.773031) (xy 134.438121 -245.812102)
			(xy 134.39645 -245.845333) (xy 134.350292 -245.871982) (xy 134.300678 -245.891454) (xy 134.248716 -245.903314)
			(xy 134.195566 -245.907298) (xy 134.142416 -245.903314) (xy 134.090454 -245.891454) (xy 134.04084 -245.871982)
			(xy 133.994682 -245.845333) (xy 133.953011 -245.812102) (xy 133.916759 -245.773031) (xy 133.886735 -245.728994)
			(xy 133.863609 -245.680973) (xy 133.847899 -245.630043) (xy 133.839956 -245.577339) (xy 133.611376 -245.577339)
			(xy 133.603433 -245.630043) (xy 133.587723 -245.680973) (xy 133.564597 -245.728994) (xy 133.534573 -245.773031)
			(xy 133.498321 -245.812102) (xy 133.45665 -245.845333) (xy 133.410492 -245.871982) (xy 133.360878 -245.891454)
			(xy 133.308916 -245.903314) (xy 133.255766 -245.907298) (xy 133.202616 -245.903314) (xy 133.150654 -245.891454)
			(xy 133.10104 -245.871982) (xy 133.054882 -245.845333) (xy 133.013211 -245.812102) (xy 132.976959 -245.773031)
			(xy 132.946935 -245.728994) (xy 132.923809 -245.680973) (xy 132.908099 -245.630043) (xy 132.900156 -245.577339)
			(xy 132.671322 -245.577339) (xy 132.663379 -245.630043) (xy 132.647669 -245.680973) (xy 132.624543 -245.728994)
			(xy 132.594519 -245.773031) (xy 132.558267 -245.812102) (xy 132.516596 -245.845333) (xy 132.470438 -245.871982)
			(xy 132.420824 -245.891454) (xy 132.368862 -245.903314) (xy 132.315712 -245.907298) (xy 132.262562 -245.903314)
			(xy 132.2106 -245.891454) (xy 132.160986 -245.871982) (xy 132.114828 -245.845333) (xy 132.073157 -245.812102)
			(xy 132.036905 -245.773031) (xy 132.006881 -245.728994) (xy 131.983755 -245.680973) (xy 131.968045 -245.630043)
			(xy 131.960102 -245.577339) (xy 131.731776 -245.577339) (xy 131.723833 -245.630043) (xy 131.708123 -245.680973)
			(xy 131.684997 -245.728994) (xy 131.654973 -245.773031) (xy 131.618721 -245.812102) (xy 131.57705 -245.845333)
			(xy 131.530892 -245.871982) (xy 131.481278 -245.891454) (xy 131.429316 -245.903314) (xy 131.376166 -245.907298)
			(xy 131.323016 -245.903314) (xy 131.271054 -245.891454) (xy 131.22144 -245.871982) (xy 131.175282 -245.845333)
			(xy 131.133611 -245.812102) (xy 131.097359 -245.773031) (xy 131.067335 -245.728994) (xy 131.044209 -245.680973)
			(xy 131.028499 -245.630043) (xy 131.020556 -245.577339) (xy 130.791976 -245.577339) (xy 130.784033 -245.630043)
			(xy 130.768323 -245.680973) (xy 130.745197 -245.728994) (xy 130.715173 -245.773031) (xy 130.678921 -245.812102)
			(xy 130.63725 -245.845333) (xy 130.591092 -245.871982) (xy 130.541478 -245.891454) (xy 130.489516 -245.903314)
			(xy 130.436366 -245.907298) (xy 130.383216 -245.903314) (xy 130.331254 -245.891454) (xy 130.28164 -245.871982)
			(xy 130.235482 -245.845333) (xy 130.193811 -245.812102) (xy 130.157559 -245.773031) (xy 130.127535 -245.728994)
			(xy 130.104409 -245.680973) (xy 130.088699 -245.630043) (xy 130.080756 -245.577339) (xy 129.852176 -245.577339)
			(xy 129.844233 -245.630043) (xy 129.828523 -245.680973) (xy 129.805397 -245.728994) (xy 129.775373 -245.773031)
			(xy 129.739121 -245.812102) (xy 129.69745 -245.845333) (xy 129.651292 -245.871982) (xy 129.601678 -245.891454)
			(xy 129.549716 -245.903314) (xy 129.496566 -245.907298) (xy 129.443416 -245.903314) (xy 129.391454 -245.891454)
			(xy 129.34184 -245.871982) (xy 129.295682 -245.845333) (xy 129.254011 -245.812102) (xy 129.217759 -245.773031)
			(xy 129.187735 -245.728994) (xy 129.164609 -245.680973) (xy 129.148899 -245.630043) (xy 129.140956 -245.577339)
			(xy 128.912376 -245.577339) (xy 128.904433 -245.630043) (xy 128.888723 -245.680973) (xy 128.865597 -245.728994)
			(xy 128.835573 -245.773031) (xy 128.799321 -245.812102) (xy 128.75765 -245.845333) (xy 128.711492 -245.871982)
			(xy 128.661878 -245.891454) (xy 128.609916 -245.903314) (xy 128.556766 -245.907298) (xy 128.503616 -245.903314)
			(xy 128.451654 -245.891454) (xy 128.40204 -245.871982) (xy 128.355882 -245.845333) (xy 128.314211 -245.812102)
			(xy 128.277959 -245.773031) (xy 128.247935 -245.728994) (xy 128.224809 -245.680973) (xy 128.209099 -245.630043)
			(xy 128.201156 -245.577339) (xy 127.972322 -245.577339) (xy 127.964379 -245.630043) (xy 127.948669 -245.680973)
			(xy 127.925543 -245.728994) (xy 127.895519 -245.773031) (xy 127.859267 -245.812102) (xy 127.817596 -245.845333)
			(xy 127.771438 -245.871982) (xy 127.721824 -245.891454) (xy 127.669862 -245.903314) (xy 127.616712 -245.907298)
			(xy 127.563562 -245.903314) (xy 127.5116 -245.891454) (xy 127.461986 -245.871982) (xy 127.415828 -245.845333)
			(xy 127.374157 -245.812102) (xy 127.337905 -245.773031) (xy 127.307881 -245.728994) (xy 127.284755 -245.680973)
			(xy 127.269045 -245.630043) (xy 127.261102 -245.577339) (xy 127.032776 -245.577339) (xy 127.024833 -245.630043)
			(xy 127.009123 -245.680973) (xy 126.985997 -245.728994) (xy 126.955973 -245.773031) (xy 126.919721 -245.812102)
			(xy 126.87805 -245.845333) (xy 126.831892 -245.871982) (xy 126.782278 -245.891454) (xy 126.730316 -245.903314)
			(xy 126.677166 -245.907298) (xy 126.624016 -245.903314) (xy 126.572054 -245.891454) (xy 126.52244 -245.871982)
			(xy 126.476282 -245.845333) (xy 126.434611 -245.812102) (xy 126.398359 -245.773031) (xy 126.368335 -245.728994)
			(xy 126.345209 -245.680973) (xy 126.329499 -245.630043) (xy 126.321556 -245.577339) (xy 126.092722 -245.577339)
			(xy 126.084779 -245.630043) (xy 126.069069 -245.680973) (xy 126.045943 -245.728994) (xy 126.015919 -245.773031)
			(xy 125.979667 -245.812102) (xy 125.937996 -245.845333) (xy 125.891838 -245.871982) (xy 125.842224 -245.891454)
			(xy 125.790262 -245.903314) (xy 125.737112 -245.907298) (xy 125.683962 -245.903314) (xy 125.632 -245.891454)
			(xy 125.582386 -245.871982) (xy 125.536228 -245.845333) (xy 125.494557 -245.812102) (xy 125.458305 -245.773031)
			(xy 125.428281 -245.728994) (xy 125.405155 -245.680973) (xy 125.389445 -245.630043) (xy 125.381502 -245.577339)
			(xy 125.153176 -245.577339) (xy 125.145233 -245.630043) (xy 125.129523 -245.680973) (xy 125.106397 -245.728994)
			(xy 125.076373 -245.773031) (xy 125.040121 -245.812102) (xy 124.99845 -245.845333) (xy 124.952292 -245.871982)
			(xy 124.902678 -245.891454) (xy 124.850716 -245.903314) (xy 124.797566 -245.907298) (xy 124.744416 -245.903314)
			(xy 124.692454 -245.891454) (xy 124.64284 -245.871982) (xy 124.596682 -245.845333) (xy 124.555011 -245.812102)
			(xy 124.518759 -245.773031) (xy 124.488735 -245.728994) (xy 124.465609 -245.680973) (xy 124.449899 -245.630043)
			(xy 124.441956 -245.577339) (xy 124.213376 -245.577339) (xy 124.205433 -245.630043) (xy 124.189723 -245.680973)
			(xy 124.166597 -245.728994) (xy 124.136573 -245.773031) (xy 124.100321 -245.812102) (xy 124.05865 -245.845333)
			(xy 124.012492 -245.871982) (xy 123.962878 -245.891454) (xy 123.910916 -245.903314) (xy 123.857766 -245.907298)
			(xy 123.804616 -245.903314) (xy 123.752654 -245.891454) (xy 123.70304 -245.871982) (xy 123.656882 -245.845333)
			(xy 123.615211 -245.812102) (xy 123.578959 -245.773031) (xy 123.548935 -245.728994) (xy 123.525809 -245.680973)
			(xy 123.510099 -245.630043) (xy 123.502156 -245.577339) (xy 123.273576 -245.577339) (xy 123.265633 -245.630043)
			(xy 123.249923 -245.680973) (xy 123.226797 -245.728994) (xy 123.196773 -245.773031) (xy 123.160521 -245.812102)
			(xy 123.11885 -245.845333) (xy 123.072692 -245.871982) (xy 123.023078 -245.891454) (xy 122.971116 -245.903314)
			(xy 122.917966 -245.907298) (xy 122.864816 -245.903314) (xy 122.812854 -245.891454) (xy 122.76324 -245.871982)
			(xy 122.717082 -245.845333) (xy 122.675411 -245.812102) (xy 122.639159 -245.773031) (xy 122.609135 -245.728994)
			(xy 122.586009 -245.680973) (xy 122.570299 -245.630043) (xy 122.562356 -245.577339) (xy 122.333776 -245.577339)
			(xy 122.325833 -245.630043) (xy 122.310123 -245.680973) (xy 122.286997 -245.728994) (xy 122.256973 -245.773031)
			(xy 122.220721 -245.812102) (xy 122.17905 -245.845333) (xy 122.132892 -245.871982) (xy 122.083278 -245.891454)
			(xy 122.031316 -245.903314) (xy 121.978166 -245.907298) (xy 121.925016 -245.903314) (xy 121.873054 -245.891454)
			(xy 121.82344 -245.871982) (xy 121.777282 -245.845333) (xy 121.735611 -245.812102) (xy 121.699359 -245.773031)
			(xy 121.669335 -245.728994) (xy 121.646209 -245.680973) (xy 121.630499 -245.630043) (xy 121.622556 -245.577339)
			(xy 121.332129 -245.577339) (xy 121.332498 -245.599204) (xy 121.331963 -245.627382) (xy 121.323088 -245.683034)
			(xy 121.305561 -245.736595) (xy 121.279819 -245.786727) (xy 121.246504 -245.832181) (xy 121.206447 -245.871821)
			(xy 121.160648 -245.90466) (xy 121.11025 -245.929878) (xy 121.056509 -245.946845) (xy 121.028714 -245.951502)
			(xy 120.98528 -245.957852) (xy 120.98528 -246.408956) (xy 121.028714 -246.415306) (xy 121.03608 -246.416576)
			(xy 121.049808 -246.418422) (xy 121.077344 -246.415529) (xy 121.103092 -246.405349) (xy 121.125162 -246.38863)
			(xy 121.141933 -246.366599) (xy 121.152172 -246.340875) (xy 121.15419 -246.327168) (xy 121.157388 -246.301255)
			(xy 121.170397 -246.250689) (xy 121.190648 -246.202565) (xy 121.217708 -246.157912) (xy 121.250996 -246.117688)
			(xy 121.289801 -246.082755) (xy 121.333289 -246.053862) (xy 121.38053 -246.031627) (xy 121.430511 -246.016526)
			(xy 121.48216 -246.008885) (xy 121.508266 -246.008398) (xy 121.534918 -246.008869) (xy 121.587628 -246.016809)
			(xy 121.638566 -246.032517) (xy 121.686593 -246.055641) (xy 121.730637 -246.085666) (xy 121.769714 -246.121921)
			(xy 121.802951 -246.163595) (xy 121.829605 -246.209757) (xy 121.84908 -246.259376) (xy 121.860942 -246.311344)
			(xy 121.864926 -246.3645) (xy 121.862928 -246.391155) (xy 122.092456 -246.391155) (xy 122.092456 -246.337857)
			(xy 122.100399 -246.285153) (xy 122.116109 -246.234223) (xy 122.139235 -246.186202) (xy 122.169259 -246.142165)
			(xy 122.205511 -246.103094) (xy 122.247182 -246.069863) (xy 122.29334 -246.043214) (xy 122.342954 -246.023742)
			(xy 122.394916 -246.011882) (xy 122.448066 -246.007899) (xy 122.501216 -246.011882) (xy 122.553178 -246.023742)
			(xy 122.602792 -246.043214) (xy 122.64895 -246.069863) (xy 122.690621 -246.103094) (xy 122.726873 -246.142165)
			(xy 122.756897 -246.186202) (xy 122.780023 -246.234223) (xy 122.795733 -246.285153) (xy 122.803676 -246.337857)
			(xy 122.804174 -246.364506) (xy 122.803676 -246.391155) (xy 123.032002 -246.391155) (xy 123.032002 -246.337857)
			(xy 123.039945 -246.285153) (xy 123.055655 -246.234223) (xy 123.078781 -246.186202) (xy 123.108805 -246.142165)
			(xy 123.145057 -246.103094) (xy 123.186728 -246.069863) (xy 123.232886 -246.043214) (xy 123.2825 -246.023742)
			(xy 123.334462 -246.011882) (xy 123.387612 -246.007899) (xy 123.440762 -246.011882) (xy 123.492724 -246.023742)
			(xy 123.542338 -246.043214) (xy 123.588496 -246.069863) (xy 123.630167 -246.103094) (xy 123.666419 -246.142165)
			(xy 123.696443 -246.186202) (xy 123.719569 -246.234223) (xy 123.735279 -246.285153) (xy 123.743222 -246.337857)
			(xy 123.74372 -246.364506) (xy 123.743222 -246.391155) (xy 123.971802 -246.391155) (xy 123.971802 -246.337857)
			(xy 123.979745 -246.285153) (xy 123.995455 -246.234223) (xy 124.018581 -246.186202) (xy 124.048605 -246.142165)
			(xy 124.084857 -246.103094) (xy 124.126528 -246.069863) (xy 124.172686 -246.043214) (xy 124.2223 -246.023742)
			(xy 124.274262 -246.011882) (xy 124.327412 -246.007899) (xy 124.380562 -246.011882) (xy 124.432524 -246.023742)
			(xy 124.482138 -246.043214) (xy 124.528296 -246.069863) (xy 124.569967 -246.103094) (xy 124.606219 -246.142165)
			(xy 124.636243 -246.186202) (xy 124.659369 -246.234223) (xy 124.675079 -246.285153) (xy 124.683022 -246.337857)
			(xy 124.68352 -246.364506) (xy 124.683022 -246.391155) (xy 124.911602 -246.391155) (xy 124.911602 -246.337857)
			(xy 124.919545 -246.285153) (xy 124.935255 -246.234223) (xy 124.958381 -246.186202) (xy 124.988405 -246.142165)
			(xy 125.024657 -246.103094) (xy 125.066328 -246.069863) (xy 125.112486 -246.043214) (xy 125.1621 -246.023742)
			(xy 125.214062 -246.011882) (xy 125.267212 -246.007899) (xy 125.320362 -246.011882) (xy 125.372324 -246.023742)
			(xy 125.421938 -246.043214) (xy 125.468096 -246.069863) (xy 125.509767 -246.103094) (xy 125.546019 -246.142165)
			(xy 125.576043 -246.186202) (xy 125.599169 -246.234223) (xy 125.614879 -246.285153) (xy 125.622822 -246.337857)
			(xy 125.62332 -246.364506) (xy 125.622822 -246.391155) (xy 125.851402 -246.391155) (xy 125.851402 -246.337857)
			(xy 125.859345 -246.285153) (xy 125.875055 -246.234223) (xy 125.898181 -246.186202) (xy 125.928205 -246.142165)
			(xy 125.964457 -246.103094) (xy 126.006128 -246.069863) (xy 126.052286 -246.043214) (xy 126.1019 -246.023742)
			(xy 126.153862 -246.011882) (xy 126.207012 -246.007899) (xy 126.260162 -246.011882) (xy 126.312124 -246.023742)
			(xy 126.361738 -246.043214) (xy 126.407896 -246.069863) (xy 126.449567 -246.103094) (xy 126.485819 -246.142165)
			(xy 126.515843 -246.186202) (xy 126.538969 -246.234223) (xy 126.554679 -246.285153) (xy 126.562622 -246.337857)
			(xy 126.56312 -246.364506) (xy 126.562622 -246.391155) (xy 126.791202 -246.391155) (xy 126.791202 -246.337857)
			(xy 126.799145 -246.285153) (xy 126.814855 -246.234223) (xy 126.837981 -246.186202) (xy 126.868005 -246.142165)
			(xy 126.904257 -246.103094) (xy 126.945928 -246.069863) (xy 126.992086 -246.043214) (xy 127.0417 -246.023742)
			(xy 127.093662 -246.011882) (xy 127.146812 -246.007899) (xy 127.199962 -246.011882) (xy 127.251924 -246.023742)
			(xy 127.301538 -246.043214) (xy 127.347696 -246.069863) (xy 127.389367 -246.103094) (xy 127.425619 -246.142165)
			(xy 127.455643 -246.186202) (xy 127.478769 -246.234223) (xy 127.494479 -246.285153) (xy 127.502422 -246.337857)
			(xy 127.50292 -246.364506) (xy 127.502422 -246.391155) (xy 127.731002 -246.391155) (xy 127.731002 -246.337857)
			(xy 127.738945 -246.285153) (xy 127.754655 -246.234223) (xy 127.777781 -246.186202) (xy 127.807805 -246.142165)
			(xy 127.844057 -246.103094) (xy 127.885728 -246.069863) (xy 127.931886 -246.043214) (xy 127.9815 -246.023742)
			(xy 128.033462 -246.011882) (xy 128.086612 -246.007899) (xy 128.139762 -246.011882) (xy 128.191724 -246.023742)
			(xy 128.241338 -246.043214) (xy 128.287496 -246.069863) (xy 128.329167 -246.103094) (xy 128.365419 -246.142165)
			(xy 128.395443 -246.186202) (xy 128.418569 -246.234223) (xy 128.434279 -246.285153) (xy 128.442222 -246.337857)
			(xy 128.44272 -246.364506) (xy 128.442222 -246.391155) (xy 128.671056 -246.391155) (xy 128.671056 -246.337857)
			(xy 128.678999 -246.285153) (xy 128.694709 -246.234223) (xy 128.717835 -246.186202) (xy 128.747859 -246.142165)
			(xy 128.784111 -246.103094) (xy 128.825782 -246.069863) (xy 128.87194 -246.043214) (xy 128.921554 -246.023742)
			(xy 128.973516 -246.011882) (xy 129.026666 -246.007899) (xy 129.079816 -246.011882) (xy 129.131778 -246.023742)
			(xy 129.181392 -246.043214) (xy 129.22755 -246.069863) (xy 129.269221 -246.103094) (xy 129.305473 -246.142165)
			(xy 129.335497 -246.186202) (xy 129.358623 -246.234223) (xy 129.374333 -246.285153) (xy 129.382276 -246.337857)
			(xy 129.382774 -246.364506) (xy 129.382276 -246.391155) (xy 129.610602 -246.391155) (xy 129.610602 -246.337857)
			(xy 129.618545 -246.285153) (xy 129.634255 -246.234223) (xy 129.657381 -246.186202) (xy 129.687405 -246.142165)
			(xy 129.723657 -246.103094) (xy 129.765328 -246.069863) (xy 129.811486 -246.043214) (xy 129.8611 -246.023742)
			(xy 129.913062 -246.011882) (xy 129.966212 -246.007899) (xy 130.019362 -246.011882) (xy 130.071324 -246.023742)
			(xy 130.120938 -246.043214) (xy 130.167096 -246.069863) (xy 130.208767 -246.103094) (xy 130.245019 -246.142165)
			(xy 130.275043 -246.186202) (xy 130.298169 -246.234223) (xy 130.313879 -246.285153) (xy 130.321822 -246.337857)
			(xy 130.32232 -246.364506) (xy 130.321822 -246.391155) (xy 130.550402 -246.391155) (xy 130.550402 -246.337857)
			(xy 130.558345 -246.285153) (xy 130.574055 -246.234223) (xy 130.597181 -246.186202) (xy 130.627205 -246.142165)
			(xy 130.663457 -246.103094) (xy 130.705128 -246.069863) (xy 130.751286 -246.043214) (xy 130.8009 -246.023742)
			(xy 130.852862 -246.011882) (xy 130.906012 -246.007899) (xy 130.959162 -246.011882) (xy 131.011124 -246.023742)
			(xy 131.060738 -246.043214) (xy 131.106896 -246.069863) (xy 131.148567 -246.103094) (xy 131.184819 -246.142165)
			(xy 131.214843 -246.186202) (xy 131.237969 -246.234223) (xy 131.253679 -246.285153) (xy 131.261622 -246.337857)
			(xy 131.26212 -246.364506) (xy 131.261622 -246.391155) (xy 131.490202 -246.391155) (xy 131.490202 -246.337857)
			(xy 131.498145 -246.285153) (xy 131.513855 -246.234223) (xy 131.536981 -246.186202) (xy 131.567005 -246.142165)
			(xy 131.603257 -246.103094) (xy 131.644928 -246.069863) (xy 131.691086 -246.043214) (xy 131.7407 -246.023742)
			(xy 131.792662 -246.011882) (xy 131.845812 -246.007899) (xy 131.898962 -246.011882) (xy 131.950924 -246.023742)
			(xy 132.000538 -246.043214) (xy 132.046696 -246.069863) (xy 132.088367 -246.103094) (xy 132.124619 -246.142165)
			(xy 132.154643 -246.186202) (xy 132.177769 -246.234223) (xy 132.193479 -246.285153) (xy 132.201422 -246.337857)
			(xy 132.20192 -246.364506) (xy 132.201422 -246.391155) (xy 132.430002 -246.391155) (xy 132.430002 -246.337857)
			(xy 132.437945 -246.285153) (xy 132.453655 -246.234223) (xy 132.476781 -246.186202) (xy 132.506805 -246.142165)
			(xy 132.543057 -246.103094) (xy 132.584728 -246.069863) (xy 132.630886 -246.043214) (xy 132.6805 -246.023742)
			(xy 132.732462 -246.011882) (xy 132.785612 -246.007899) (xy 132.838762 -246.011882) (xy 132.890724 -246.023742)
			(xy 132.940338 -246.043214) (xy 132.986496 -246.069863) (xy 133.028167 -246.103094) (xy 133.064419 -246.142165)
			(xy 133.094443 -246.186202) (xy 133.117569 -246.234223) (xy 133.133279 -246.285153) (xy 133.141222 -246.337857)
			(xy 133.14172 -246.364506) (xy 133.141222 -246.391155) (xy 133.370056 -246.391155) (xy 133.370056 -246.337857)
			(xy 133.377999 -246.285153) (xy 133.393709 -246.234223) (xy 133.416835 -246.186202) (xy 133.446859 -246.142165)
			(xy 133.483111 -246.103094) (xy 133.524782 -246.069863) (xy 133.57094 -246.043214) (xy 133.620554 -246.023742)
			(xy 133.672516 -246.011882) (xy 133.725666 -246.007899) (xy 133.778816 -246.011882) (xy 133.830778 -246.023742)
			(xy 133.880392 -246.043214) (xy 133.92655 -246.069863) (xy 133.968221 -246.103094) (xy 134.004473 -246.142165)
			(xy 134.034497 -246.186202) (xy 134.057623 -246.234223) (xy 134.073333 -246.285153) (xy 134.081276 -246.337857)
			(xy 134.081774 -246.364506) (xy 134.081276 -246.391155) (xy 134.309856 -246.391155) (xy 134.309856 -246.337857)
			(xy 134.317799 -246.285153) (xy 134.333509 -246.234223) (xy 134.356635 -246.186202) (xy 134.386659 -246.142165)
			(xy 134.422911 -246.103094) (xy 134.464582 -246.069863) (xy 134.51074 -246.043214) (xy 134.560354 -246.023742)
			(xy 134.612316 -246.011882) (xy 134.665466 -246.007899) (xy 134.718616 -246.011882) (xy 134.770578 -246.023742)
			(xy 134.820192 -246.043214) (xy 134.86635 -246.069863) (xy 134.908021 -246.103094) (xy 134.944273 -246.142165)
			(xy 134.974297 -246.186202) (xy 134.997423 -246.234223) (xy 135.013133 -246.285153) (xy 135.021076 -246.337857)
			(xy 135.021574 -246.364506) (xy 135.021076 -246.391155) (xy 135.013133 -246.443859) (xy 134.997423 -246.494789)
			(xy 134.974297 -246.54281) (xy 134.944273 -246.586847) (xy 134.908021 -246.625918) (xy 134.86635 -246.659149)
			(xy 134.820192 -246.685798) (xy 134.770578 -246.70527) (xy 134.718616 -246.71713) (xy 134.665466 -246.721114)
			(xy 134.612316 -246.71713) (xy 134.560354 -246.70527) (xy 134.51074 -246.685798) (xy 134.464582 -246.659149)
			(xy 134.422911 -246.625918) (xy 134.386659 -246.586847) (xy 134.356635 -246.54281) (xy 134.333509 -246.494789)
			(xy 134.317799 -246.443859) (xy 134.309856 -246.391155) (xy 134.081276 -246.391155) (xy 134.073333 -246.443859)
			(xy 134.057623 -246.494789) (xy 134.034497 -246.54281) (xy 134.004473 -246.586847) (xy 133.968221 -246.625918)
			(xy 133.92655 -246.659149) (xy 133.880392 -246.685798) (xy 133.830778 -246.70527) (xy 133.778816 -246.71713)
			(xy 133.725666 -246.721114) (xy 133.672516 -246.71713) (xy 133.620554 -246.70527) (xy 133.57094 -246.685798)
			(xy 133.524782 -246.659149) (xy 133.483111 -246.625918) (xy 133.446859 -246.586847) (xy 133.416835 -246.54281)
			(xy 133.393709 -246.494789) (xy 133.377999 -246.443859) (xy 133.370056 -246.391155) (xy 133.141222 -246.391155)
			(xy 133.133279 -246.443859) (xy 133.117569 -246.494789) (xy 133.094443 -246.54281) (xy 133.064419 -246.586847)
			(xy 133.028167 -246.625918) (xy 132.986496 -246.659149) (xy 132.940338 -246.685798) (xy 132.890724 -246.70527)
			(xy 132.838762 -246.71713) (xy 132.785612 -246.721114) (xy 132.732462 -246.71713) (xy 132.6805 -246.70527)
			(xy 132.630886 -246.685798) (xy 132.584728 -246.659149) (xy 132.543057 -246.625918) (xy 132.506805 -246.586847)
			(xy 132.476781 -246.54281) (xy 132.453655 -246.494789) (xy 132.437945 -246.443859) (xy 132.430002 -246.391155)
			(xy 132.201422 -246.391155) (xy 132.193479 -246.443859) (xy 132.177769 -246.494789) (xy 132.154643 -246.54281)
			(xy 132.124619 -246.586847) (xy 132.088367 -246.625918) (xy 132.046696 -246.659149) (xy 132.000538 -246.685798)
			(xy 131.950924 -246.70527) (xy 131.898962 -246.71713) (xy 131.845812 -246.721114) (xy 131.792662 -246.71713)
			(xy 131.7407 -246.70527) (xy 131.691086 -246.685798) (xy 131.644928 -246.659149) (xy 131.603257 -246.625918)
			(xy 131.567005 -246.586847) (xy 131.536981 -246.54281) (xy 131.513855 -246.494789) (xy 131.498145 -246.443859)
			(xy 131.490202 -246.391155) (xy 131.261622 -246.391155) (xy 131.253679 -246.443859) (xy 131.237969 -246.494789)
			(xy 131.214843 -246.54281) (xy 131.184819 -246.586847) (xy 131.148567 -246.625918) (xy 131.106896 -246.659149)
			(xy 131.060738 -246.685798) (xy 131.011124 -246.70527) (xy 130.959162 -246.71713) (xy 130.906012 -246.721114)
			(xy 130.852862 -246.71713) (xy 130.8009 -246.70527) (xy 130.751286 -246.685798) (xy 130.705128 -246.659149)
			(xy 130.663457 -246.625918) (xy 130.627205 -246.586847) (xy 130.597181 -246.54281) (xy 130.574055 -246.494789)
			(xy 130.558345 -246.443859) (xy 130.550402 -246.391155) (xy 130.321822 -246.391155) (xy 130.313879 -246.443859)
			(xy 130.298169 -246.494789) (xy 130.275043 -246.54281) (xy 130.245019 -246.586847) (xy 130.208767 -246.625918)
			(xy 130.167096 -246.659149) (xy 130.120938 -246.685798) (xy 130.071324 -246.70527) (xy 130.019362 -246.71713)
			(xy 129.966212 -246.721114) (xy 129.913062 -246.71713) (xy 129.8611 -246.70527) (xy 129.811486 -246.685798)
			(xy 129.765328 -246.659149) (xy 129.723657 -246.625918) (xy 129.687405 -246.586847) (xy 129.657381 -246.54281)
			(xy 129.634255 -246.494789) (xy 129.618545 -246.443859) (xy 129.610602 -246.391155) (xy 129.382276 -246.391155)
			(xy 129.374333 -246.443859) (xy 129.358623 -246.494789) (xy 129.335497 -246.54281) (xy 129.305473 -246.586847)
			(xy 129.269221 -246.625918) (xy 129.22755 -246.659149) (xy 129.181392 -246.685798) (xy 129.131778 -246.70527)
			(xy 129.079816 -246.71713) (xy 129.026666 -246.721114) (xy 128.973516 -246.71713) (xy 128.921554 -246.70527)
			(xy 128.87194 -246.685798) (xy 128.825782 -246.659149) (xy 128.784111 -246.625918) (xy 128.747859 -246.586847)
			(xy 128.717835 -246.54281) (xy 128.694709 -246.494789) (xy 128.678999 -246.443859) (xy 128.671056 -246.391155)
			(xy 128.442222 -246.391155) (xy 128.434279 -246.443859) (xy 128.418569 -246.494789) (xy 128.395443 -246.54281)
			(xy 128.365419 -246.586847) (xy 128.329167 -246.625918) (xy 128.287496 -246.659149) (xy 128.241338 -246.685798)
			(xy 128.191724 -246.70527) (xy 128.139762 -246.71713) (xy 128.086612 -246.721114) (xy 128.033462 -246.71713)
			(xy 127.9815 -246.70527) (xy 127.931886 -246.685798) (xy 127.885728 -246.659149) (xy 127.844057 -246.625918)
			(xy 127.807805 -246.586847) (xy 127.777781 -246.54281) (xy 127.754655 -246.494789) (xy 127.738945 -246.443859)
			(xy 127.731002 -246.391155) (xy 127.502422 -246.391155) (xy 127.494479 -246.443859) (xy 127.478769 -246.494789)
			(xy 127.455643 -246.54281) (xy 127.425619 -246.586847) (xy 127.389367 -246.625918) (xy 127.347696 -246.659149)
			(xy 127.301538 -246.685798) (xy 127.251924 -246.70527) (xy 127.199962 -246.71713) (xy 127.146812 -246.721114)
			(xy 127.093662 -246.71713) (xy 127.0417 -246.70527) (xy 126.992086 -246.685798) (xy 126.945928 -246.659149)
			(xy 126.904257 -246.625918) (xy 126.868005 -246.586847) (xy 126.837981 -246.54281) (xy 126.814855 -246.494789)
			(xy 126.799145 -246.443859) (xy 126.791202 -246.391155) (xy 126.562622 -246.391155) (xy 126.554679 -246.443859)
			(xy 126.538969 -246.494789) (xy 126.515843 -246.54281) (xy 126.485819 -246.586847) (xy 126.449567 -246.625918)
			(xy 126.407896 -246.659149) (xy 126.361738 -246.685798) (xy 126.312124 -246.70527) (xy 126.260162 -246.71713)
			(xy 126.207012 -246.721114) (xy 126.153862 -246.71713) (xy 126.1019 -246.70527) (xy 126.052286 -246.685798)
			(xy 126.006128 -246.659149) (xy 125.964457 -246.625918) (xy 125.928205 -246.586847) (xy 125.898181 -246.54281)
			(xy 125.875055 -246.494789) (xy 125.859345 -246.443859) (xy 125.851402 -246.391155) (xy 125.622822 -246.391155)
			(xy 125.614879 -246.443859) (xy 125.599169 -246.494789) (xy 125.576043 -246.54281) (xy 125.546019 -246.586847)
			(xy 125.509767 -246.625918) (xy 125.468096 -246.659149) (xy 125.421938 -246.685798) (xy 125.372324 -246.70527)
			(xy 125.320362 -246.71713) (xy 125.267212 -246.721114) (xy 125.214062 -246.71713) (xy 125.1621 -246.70527)
			(xy 125.112486 -246.685798) (xy 125.066328 -246.659149) (xy 125.024657 -246.625918) (xy 124.988405 -246.586847)
			(xy 124.958381 -246.54281) (xy 124.935255 -246.494789) (xy 124.919545 -246.443859) (xy 124.911602 -246.391155)
			(xy 124.683022 -246.391155) (xy 124.675079 -246.443859) (xy 124.659369 -246.494789) (xy 124.636243 -246.54281)
			(xy 124.606219 -246.586847) (xy 124.569967 -246.625918) (xy 124.528296 -246.659149) (xy 124.482138 -246.685798)
			(xy 124.432524 -246.70527) (xy 124.380562 -246.71713) (xy 124.327412 -246.721114) (xy 124.274262 -246.71713)
			(xy 124.2223 -246.70527) (xy 124.172686 -246.685798) (xy 124.126528 -246.659149) (xy 124.084857 -246.625918)
			(xy 124.048605 -246.586847) (xy 124.018581 -246.54281) (xy 123.995455 -246.494789) (xy 123.979745 -246.443859)
			(xy 123.971802 -246.391155) (xy 123.743222 -246.391155) (xy 123.735279 -246.443859) (xy 123.719569 -246.494789)
			(xy 123.696443 -246.54281) (xy 123.666419 -246.586847) (xy 123.630167 -246.625918) (xy 123.588496 -246.659149)
			(xy 123.542338 -246.685798) (xy 123.492724 -246.70527) (xy 123.440762 -246.71713) (xy 123.387612 -246.721114)
			(xy 123.334462 -246.71713) (xy 123.2825 -246.70527) (xy 123.232886 -246.685798) (xy 123.186728 -246.659149)
			(xy 123.145057 -246.625918) (xy 123.108805 -246.586847) (xy 123.078781 -246.54281) (xy 123.055655 -246.494789)
			(xy 123.039945 -246.443859) (xy 123.032002 -246.391155) (xy 122.803676 -246.391155) (xy 122.795733 -246.443859)
			(xy 122.780023 -246.494789) (xy 122.756897 -246.54281) (xy 122.726873 -246.586847) (xy 122.690621 -246.625918)
			(xy 122.64895 -246.659149) (xy 122.602792 -246.685798) (xy 122.553178 -246.70527) (xy 122.501216 -246.71713)
			(xy 122.448066 -246.721114) (xy 122.394916 -246.71713) (xy 122.342954 -246.70527) (xy 122.29334 -246.685798)
			(xy 122.247182 -246.659149) (xy 122.205511 -246.625918) (xy 122.169259 -246.586847) (xy 122.139235 -246.54281)
			(xy 122.116109 -246.494789) (xy 122.100399 -246.443859) (xy 122.092456 -246.391155) (xy 121.862928 -246.391155)
			(xy 121.860942 -246.417656) (xy 121.84908 -246.469624) (xy 121.829605 -246.519243) (xy 121.802951 -246.565405)
			(xy 121.769714 -246.607079) (xy 121.730637 -246.643334) (xy 121.686593 -246.673359) (xy 121.638566 -246.696483)
			(xy 121.587628 -246.712191) (xy 121.534918 -246.720131) (xy 121.508266 -246.720614) (xy 121.49327 -246.720449)
			(xy 121.463384 -246.717907) (xy 121.448576 -246.715534) (xy 121.434844 -246.713681) (xy 121.407297 -246.716562)
			(xy 121.381535 -246.726736) (xy 121.359453 -246.743455) (xy 121.342673 -246.765491) (xy 121.332429 -246.791224)
			(xy 121.330466 -246.804942) (xy 121.327261 -246.830904) (xy 121.314222 -246.881564) (xy 121.293918 -246.929773)
			(xy 121.266786 -246.974497) (xy 121.250456 -246.994934) (xy 121.241831 -247.006064) (xy 121.230486 -247.031824)
			(xy 121.226607 -247.059703) (xy 121.230488 -247.087582) (xy 121.241834 -247.113341) (xy 121.250456 -247.124474)
			(xy 121.265891 -247.143722) (xy 121.291861 -247.185673) (xy 121.300379 -247.204971) (xy 121.622556 -247.204971)
			(xy 121.622556 -247.151673) (xy 121.630499 -247.098969) (xy 121.646209 -247.048039) (xy 121.669335 -247.000018)
			(xy 121.699359 -246.955981) (xy 121.735611 -246.91691) (xy 121.777282 -246.883679) (xy 121.82344 -246.85703)
			(xy 121.873054 -246.837558) (xy 121.925016 -246.825698) (xy 121.978166 -246.821715) (xy 122.031316 -246.825698)
			(xy 122.083278 -246.837558) (xy 122.132892 -246.85703) (xy 122.17905 -246.883679) (xy 122.220721 -246.91691)
			(xy 122.256973 -246.955981) (xy 122.286997 -247.000018) (xy 122.310123 -247.048039) (xy 122.325833 -247.098969)
			(xy 122.333776 -247.151673) (xy 122.334274 -247.178322) (xy 122.333776 -247.204971) (xy 122.562356 -247.204971)
			(xy 122.562356 -247.151673) (xy 122.570299 -247.098969) (xy 122.586009 -247.048039) (xy 122.609135 -247.000018)
			(xy 122.639159 -246.955981) (xy 122.675411 -246.91691) (xy 122.717082 -246.883679) (xy 122.76324 -246.85703)
			(xy 122.812854 -246.837558) (xy 122.864816 -246.825698) (xy 122.917966 -246.821715) (xy 122.971116 -246.825698)
			(xy 123.023078 -246.837558) (xy 123.072692 -246.85703) (xy 123.11885 -246.883679) (xy 123.160521 -246.91691)
			(xy 123.196773 -246.955981) (xy 123.226797 -247.000018) (xy 123.249923 -247.048039) (xy 123.265633 -247.098969)
			(xy 123.273576 -247.151673) (xy 123.274074 -247.178322) (xy 123.273576 -247.204971) (xy 123.502156 -247.204971)
			(xy 123.502156 -247.151673) (xy 123.510099 -247.098969) (xy 123.525809 -247.048039) (xy 123.548935 -247.000018)
			(xy 123.578959 -246.955981) (xy 123.615211 -246.91691) (xy 123.656882 -246.883679) (xy 123.70304 -246.85703)
			(xy 123.752654 -246.837558) (xy 123.804616 -246.825698) (xy 123.857766 -246.821715) (xy 123.910916 -246.825698)
			(xy 123.962878 -246.837558) (xy 124.012492 -246.85703) (xy 124.05865 -246.883679) (xy 124.100321 -246.91691)
			(xy 124.136573 -246.955981) (xy 124.166597 -247.000018) (xy 124.189723 -247.048039) (xy 124.205433 -247.098969)
			(xy 124.213376 -247.151673) (xy 124.213874 -247.178322) (xy 124.213376 -247.204971) (xy 124.441956 -247.204971)
			(xy 124.441956 -247.151673) (xy 124.449899 -247.098969) (xy 124.465609 -247.048039) (xy 124.488735 -247.000018)
			(xy 124.518759 -246.955981) (xy 124.555011 -246.91691) (xy 124.596682 -246.883679) (xy 124.64284 -246.85703)
			(xy 124.692454 -246.837558) (xy 124.744416 -246.825698) (xy 124.797566 -246.821715) (xy 124.850716 -246.825698)
			(xy 124.902678 -246.837558) (xy 124.952292 -246.85703) (xy 124.99845 -246.883679) (xy 125.040121 -246.91691)
			(xy 125.076373 -246.955981) (xy 125.106397 -247.000018) (xy 125.129523 -247.048039) (xy 125.145233 -247.098969)
			(xy 125.153176 -247.151673) (xy 125.153674 -247.178322) (xy 125.153176 -247.204971) (xy 125.381756 -247.204971)
			(xy 125.381756 -247.151673) (xy 125.389699 -247.098969) (xy 125.405409 -247.048039) (xy 125.428535 -247.000018)
			(xy 125.458559 -246.955981) (xy 125.494811 -246.91691) (xy 125.536482 -246.883679) (xy 125.58264 -246.85703)
			(xy 125.632254 -246.837558) (xy 125.684216 -246.825698) (xy 125.737366 -246.821715) (xy 125.790516 -246.825698)
			(xy 125.842478 -246.837558) (xy 125.892092 -246.85703) (xy 125.93825 -246.883679) (xy 125.979921 -246.91691)
			(xy 126.016173 -246.955981) (xy 126.046197 -247.000018) (xy 126.069323 -247.048039) (xy 126.085033 -247.098969)
			(xy 126.092976 -247.151673) (xy 126.093474 -247.178322) (xy 126.092976 -247.204971) (xy 126.321302 -247.204971)
			(xy 126.321302 -247.151673) (xy 126.329245 -247.098969) (xy 126.344955 -247.048039) (xy 126.368081 -247.000018)
			(xy 126.398105 -246.955981) (xy 126.434357 -246.91691) (xy 126.476028 -246.883679) (xy 126.522186 -246.85703)
			(xy 126.5718 -246.837558) (xy 126.623762 -246.825698) (xy 126.676912 -246.821715) (xy 126.730062 -246.825698)
			(xy 126.782024 -246.837558) (xy 126.831638 -246.85703) (xy 126.877796 -246.883679) (xy 126.919467 -246.91691)
			(xy 126.955719 -246.955981) (xy 126.985743 -247.000018) (xy 127.008869 -247.048039) (xy 127.024579 -247.098969)
			(xy 127.032522 -247.151673) (xy 127.03302 -247.178322) (xy 127.032522 -247.204971) (xy 127.261356 -247.204971)
			(xy 127.261356 -247.151673) (xy 127.269299 -247.098969) (xy 127.285009 -247.048039) (xy 127.308135 -247.000018)
			(xy 127.338159 -246.955981) (xy 127.374411 -246.91691) (xy 127.416082 -246.883679) (xy 127.46224 -246.85703)
			(xy 127.511854 -246.837558) (xy 127.563816 -246.825698) (xy 127.616966 -246.821715) (xy 127.670116 -246.825698)
			(xy 127.722078 -246.837558) (xy 127.771692 -246.85703) (xy 127.81785 -246.883679) (xy 127.859521 -246.91691)
			(xy 127.895773 -246.955981) (xy 127.925797 -247.000018) (xy 127.948923 -247.048039) (xy 127.964633 -247.098969)
			(xy 127.972576 -247.151673) (xy 127.973074 -247.178322) (xy 127.972576 -247.204971) (xy 128.201156 -247.204971)
			(xy 128.201156 -247.151673) (xy 128.209099 -247.098969) (xy 128.224809 -247.048039) (xy 128.247935 -247.000018)
			(xy 128.277959 -246.955981) (xy 128.314211 -246.91691) (xy 128.355882 -246.883679) (xy 128.40204 -246.85703)
			(xy 128.451654 -246.837558) (xy 128.503616 -246.825698) (xy 128.556766 -246.821715) (xy 128.609916 -246.825698)
			(xy 128.661878 -246.837558) (xy 128.711492 -246.85703) (xy 128.75765 -246.883679) (xy 128.799321 -246.91691)
			(xy 128.835573 -246.955981) (xy 128.865597 -247.000018) (xy 128.888723 -247.048039) (xy 128.904433 -247.098969)
			(xy 128.912376 -247.151673) (xy 128.912874 -247.178322) (xy 128.912376 -247.204971) (xy 129.140956 -247.204971)
			(xy 129.140956 -247.151673) (xy 129.148899 -247.098969) (xy 129.164609 -247.048039) (xy 129.187735 -247.000018)
			(xy 129.217759 -246.955981) (xy 129.254011 -246.91691) (xy 129.295682 -246.883679) (xy 129.34184 -246.85703)
			(xy 129.391454 -246.837558) (xy 129.443416 -246.825698) (xy 129.496566 -246.821715) (xy 129.549716 -246.825698)
			(xy 129.601678 -246.837558) (xy 129.651292 -246.85703) (xy 129.69745 -246.883679) (xy 129.739121 -246.91691)
			(xy 129.775373 -246.955981) (xy 129.805397 -247.000018) (xy 129.828523 -247.048039) (xy 129.844233 -247.098969)
			(xy 129.852176 -247.151673) (xy 129.852674 -247.178322) (xy 129.852176 -247.204971) (xy 130.080756 -247.204971)
			(xy 130.080756 -247.151673) (xy 130.088699 -247.098969) (xy 130.104409 -247.048039) (xy 130.127535 -247.000018)
			(xy 130.157559 -246.955981) (xy 130.193811 -246.91691) (xy 130.235482 -246.883679) (xy 130.28164 -246.85703)
			(xy 130.331254 -246.837558) (xy 130.383216 -246.825698) (xy 130.436366 -246.821715) (xy 130.489516 -246.825698)
			(xy 130.541478 -246.837558) (xy 130.591092 -246.85703) (xy 130.63725 -246.883679) (xy 130.678921 -246.91691)
			(xy 130.715173 -246.955981) (xy 130.745197 -247.000018) (xy 130.768323 -247.048039) (xy 130.784033 -247.098969)
			(xy 130.791976 -247.151673) (xy 130.792474 -247.178322) (xy 130.791976 -247.204971) (xy 131.020302 -247.204971)
			(xy 131.020302 -247.151673) (xy 131.028245 -247.098969) (xy 131.043955 -247.048039) (xy 131.067081 -247.000018)
			(xy 131.097105 -246.955981) (xy 131.133357 -246.91691) (xy 131.175028 -246.883679) (xy 131.221186 -246.85703)
			(xy 131.2708 -246.837558) (xy 131.322762 -246.825698) (xy 131.375912 -246.821715) (xy 131.429062 -246.825698)
			(xy 131.481024 -246.837558) (xy 131.530638 -246.85703) (xy 131.576796 -246.883679) (xy 131.618467 -246.91691)
			(xy 131.654719 -246.955981) (xy 131.684743 -247.000018) (xy 131.707869 -247.048039) (xy 131.723579 -247.098969)
			(xy 131.731522 -247.151673) (xy 131.73202 -247.178322) (xy 131.731522 -247.204971) (xy 131.960356 -247.204971)
			(xy 131.960356 -247.151673) (xy 131.968299 -247.098969) (xy 131.984009 -247.048039) (xy 132.007135 -247.000018)
			(xy 132.037159 -246.955981) (xy 132.073411 -246.91691) (xy 132.115082 -246.883679) (xy 132.16124 -246.85703)
			(xy 132.210854 -246.837558) (xy 132.262816 -246.825698) (xy 132.315966 -246.821715) (xy 132.369116 -246.825698)
			(xy 132.421078 -246.837558) (xy 132.470692 -246.85703) (xy 132.51685 -246.883679) (xy 132.558521 -246.91691)
			(xy 132.594773 -246.955981) (xy 132.624797 -247.000018) (xy 132.647923 -247.048039) (xy 132.663633 -247.098969)
			(xy 132.671576 -247.151673) (xy 132.672074 -247.178322) (xy 132.671576 -247.204971) (xy 132.899902 -247.204971)
			(xy 132.899902 -247.151673) (xy 132.907845 -247.098969) (xy 132.923555 -247.048039) (xy 132.946681 -247.000018)
			(xy 132.976705 -246.955981) (xy 133.012957 -246.91691) (xy 133.054628 -246.883679) (xy 133.100786 -246.85703)
			(xy 133.1504 -246.837558) (xy 133.202362 -246.825698) (xy 133.255512 -246.821715) (xy 133.308662 -246.825698)
			(xy 133.360624 -246.837558) (xy 133.410238 -246.85703) (xy 133.456396 -246.883679) (xy 133.498067 -246.91691)
			(xy 133.534319 -246.955981) (xy 133.564343 -247.000018) (xy 133.587469 -247.048039) (xy 133.603179 -247.098969)
			(xy 133.611122 -247.151673) (xy 133.61162 -247.178322) (xy 133.611122 -247.204971) (xy 133.839956 -247.204971)
			(xy 133.839956 -247.151673) (xy 133.847899 -247.098969) (xy 133.863609 -247.048039) (xy 133.886735 -247.000018)
			(xy 133.916759 -246.955981) (xy 133.953011 -246.91691) (xy 133.994682 -246.883679) (xy 134.04084 -246.85703)
			(xy 134.090454 -246.837558) (xy 134.142416 -246.825698) (xy 134.195566 -246.821715) (xy 134.248716 -246.825698)
			(xy 134.300678 -246.837558) (xy 134.350292 -246.85703) (xy 134.39645 -246.883679) (xy 134.438121 -246.91691)
			(xy 134.474373 -246.955981) (xy 134.504397 -247.000018) (xy 134.527523 -247.048039) (xy 134.543233 -247.098969)
			(xy 134.551176 -247.151673) (xy 134.551674 -247.178322) (xy 134.551176 -247.204971) (xy 134.543233 -247.257675)
			(xy 134.527523 -247.308605) (xy 134.504397 -247.356626) (xy 134.474373 -247.400663) (xy 134.438121 -247.439734)
			(xy 134.39645 -247.472965) (xy 134.350292 -247.499614) (xy 134.300678 -247.519086) (xy 134.248716 -247.530946)
			(xy 134.195566 -247.53493) (xy 134.142416 -247.530946) (xy 134.090454 -247.519086) (xy 134.04084 -247.499614)
			(xy 133.994682 -247.472965) (xy 133.953011 -247.439734) (xy 133.916759 -247.400663) (xy 133.886735 -247.356626)
			(xy 133.863609 -247.308605) (xy 133.847899 -247.257675) (xy 133.839956 -247.204971) (xy 133.611122 -247.204971)
			(xy 133.603179 -247.257675) (xy 133.587469 -247.308605) (xy 133.564343 -247.356626) (xy 133.534319 -247.400663)
			(xy 133.498067 -247.439734) (xy 133.456396 -247.472965) (xy 133.410238 -247.499614) (xy 133.360624 -247.519086)
			(xy 133.308662 -247.530946) (xy 133.255512 -247.53493) (xy 133.202362 -247.530946) (xy 133.1504 -247.519086)
			(xy 133.100786 -247.499614) (xy 133.054628 -247.472965) (xy 133.012957 -247.439734) (xy 132.976705 -247.400663)
			(xy 132.946681 -247.356626) (xy 132.923555 -247.308605) (xy 132.907845 -247.257675) (xy 132.899902 -247.204971)
			(xy 132.671576 -247.204971) (xy 132.663633 -247.257675) (xy 132.647923 -247.308605) (xy 132.624797 -247.356626)
			(xy 132.594773 -247.400663) (xy 132.558521 -247.439734) (xy 132.51685 -247.472965) (xy 132.470692 -247.499614)
			(xy 132.421078 -247.519086) (xy 132.369116 -247.530946) (xy 132.315966 -247.53493) (xy 132.262816 -247.530946)
			(xy 132.210854 -247.519086) (xy 132.16124 -247.499614) (xy 132.115082 -247.472965) (xy 132.073411 -247.439734)
			(xy 132.037159 -247.400663) (xy 132.007135 -247.356626) (xy 131.984009 -247.308605) (xy 131.968299 -247.257675)
			(xy 131.960356 -247.204971) (xy 131.731522 -247.204971) (xy 131.723579 -247.257675) (xy 131.707869 -247.308605)
			(xy 131.684743 -247.356626) (xy 131.654719 -247.400663) (xy 131.618467 -247.439734) (xy 131.576796 -247.472965)
			(xy 131.530638 -247.499614) (xy 131.481024 -247.519086) (xy 131.429062 -247.530946) (xy 131.375912 -247.53493)
			(xy 131.322762 -247.530946) (xy 131.2708 -247.519086) (xy 131.221186 -247.499614) (xy 131.175028 -247.472965)
			(xy 131.133357 -247.439734) (xy 131.097105 -247.400663) (xy 131.067081 -247.356626) (xy 131.043955 -247.308605)
			(xy 131.028245 -247.257675) (xy 131.020302 -247.204971) (xy 130.791976 -247.204971) (xy 130.784033 -247.257675)
			(xy 130.768323 -247.308605) (xy 130.745197 -247.356626) (xy 130.715173 -247.400663) (xy 130.678921 -247.439734)
			(xy 130.63725 -247.472965) (xy 130.591092 -247.499614) (xy 130.541478 -247.519086) (xy 130.489516 -247.530946)
			(xy 130.436366 -247.53493) (xy 130.383216 -247.530946) (xy 130.331254 -247.519086) (xy 130.28164 -247.499614)
			(xy 130.235482 -247.472965) (xy 130.193811 -247.439734) (xy 130.157559 -247.400663) (xy 130.127535 -247.356626)
			(xy 130.104409 -247.308605) (xy 130.088699 -247.257675) (xy 130.080756 -247.204971) (xy 129.852176 -247.204971)
			(xy 129.844233 -247.257675) (xy 129.828523 -247.308605) (xy 129.805397 -247.356626) (xy 129.775373 -247.400663)
			(xy 129.739121 -247.439734) (xy 129.69745 -247.472965) (xy 129.651292 -247.499614) (xy 129.601678 -247.519086)
			(xy 129.549716 -247.530946) (xy 129.496566 -247.53493) (xy 129.443416 -247.530946) (xy 129.391454 -247.519086)
			(xy 129.34184 -247.499614) (xy 129.295682 -247.472965) (xy 129.254011 -247.439734) (xy 129.217759 -247.400663)
			(xy 129.187735 -247.356626) (xy 129.164609 -247.308605) (xy 129.148899 -247.257675) (xy 129.140956 -247.204971)
			(xy 128.912376 -247.204971) (xy 128.904433 -247.257675) (xy 128.888723 -247.308605) (xy 128.865597 -247.356626)
			(xy 128.835573 -247.400663) (xy 128.799321 -247.439734) (xy 128.75765 -247.472965) (xy 128.711492 -247.499614)
			(xy 128.661878 -247.519086) (xy 128.609916 -247.530946) (xy 128.556766 -247.53493) (xy 128.503616 -247.530946)
			(xy 128.451654 -247.519086) (xy 128.40204 -247.499614) (xy 128.355882 -247.472965) (xy 128.314211 -247.439734)
			(xy 128.277959 -247.400663) (xy 128.247935 -247.356626) (xy 128.224809 -247.308605) (xy 128.209099 -247.257675)
			(xy 128.201156 -247.204971) (xy 127.972576 -247.204971) (xy 127.964633 -247.257675) (xy 127.948923 -247.308605)
			(xy 127.925797 -247.356626) (xy 127.895773 -247.400663) (xy 127.859521 -247.439734) (xy 127.81785 -247.472965)
			(xy 127.771692 -247.499614) (xy 127.722078 -247.519086) (xy 127.670116 -247.530946) (xy 127.616966 -247.53493)
			(xy 127.563816 -247.530946) (xy 127.511854 -247.519086) (xy 127.46224 -247.499614) (xy 127.416082 -247.472965)
			(xy 127.374411 -247.439734) (xy 127.338159 -247.400663) (xy 127.308135 -247.356626) (xy 127.285009 -247.308605)
			(xy 127.269299 -247.257675) (xy 127.261356 -247.204971) (xy 127.032522 -247.204971) (xy 127.024579 -247.257675)
			(xy 127.008869 -247.308605) (xy 126.985743 -247.356626) (xy 126.955719 -247.400663) (xy 126.919467 -247.439734)
			(xy 126.877796 -247.472965) (xy 126.831638 -247.499614) (xy 126.782024 -247.519086) (xy 126.730062 -247.530946)
			(xy 126.676912 -247.53493) (xy 126.623762 -247.530946) (xy 126.5718 -247.519086) (xy 126.522186 -247.499614)
			(xy 126.476028 -247.472965) (xy 126.434357 -247.439734) (xy 126.398105 -247.400663) (xy 126.368081 -247.356626)
			(xy 126.344955 -247.308605) (xy 126.329245 -247.257675) (xy 126.321302 -247.204971) (xy 126.092976 -247.204971)
			(xy 126.085033 -247.257675) (xy 126.069323 -247.308605) (xy 126.046197 -247.356626) (xy 126.016173 -247.400663)
			(xy 125.979921 -247.439734) (xy 125.93825 -247.472965) (xy 125.892092 -247.499614) (xy 125.842478 -247.519086)
			(xy 125.790516 -247.530946) (xy 125.737366 -247.53493) (xy 125.684216 -247.530946) (xy 125.632254 -247.519086)
			(xy 125.58264 -247.499614) (xy 125.536482 -247.472965) (xy 125.494811 -247.439734) (xy 125.458559 -247.400663)
			(xy 125.428535 -247.356626) (xy 125.405409 -247.308605) (xy 125.389699 -247.257675) (xy 125.381756 -247.204971)
			(xy 125.153176 -247.204971) (xy 125.145233 -247.257675) (xy 125.129523 -247.308605) (xy 125.106397 -247.356626)
			(xy 125.076373 -247.400663) (xy 125.040121 -247.439734) (xy 124.99845 -247.472965) (xy 124.952292 -247.499614)
			(xy 124.902678 -247.519086) (xy 124.850716 -247.530946) (xy 124.797566 -247.53493) (xy 124.744416 -247.530946)
			(xy 124.692454 -247.519086) (xy 124.64284 -247.499614) (xy 124.596682 -247.472965) (xy 124.555011 -247.439734)
			(xy 124.518759 -247.400663) (xy 124.488735 -247.356626) (xy 124.465609 -247.308605) (xy 124.449899 -247.257675)
			(xy 124.441956 -247.204971) (xy 124.213376 -247.204971) (xy 124.205433 -247.257675) (xy 124.189723 -247.308605)
			(xy 124.166597 -247.356626) (xy 124.136573 -247.400663) (xy 124.100321 -247.439734) (xy 124.05865 -247.472965)
			(xy 124.012492 -247.499614) (xy 123.962878 -247.519086) (xy 123.910916 -247.530946) (xy 123.857766 -247.53493)
			(xy 123.804616 -247.530946) (xy 123.752654 -247.519086) (xy 123.70304 -247.499614) (xy 123.656882 -247.472965)
			(xy 123.615211 -247.439734) (xy 123.578959 -247.400663) (xy 123.548935 -247.356626) (xy 123.525809 -247.308605)
			(xy 123.510099 -247.257675) (xy 123.502156 -247.204971) (xy 123.273576 -247.204971) (xy 123.265633 -247.257675)
			(xy 123.249923 -247.308605) (xy 123.226797 -247.356626) (xy 123.196773 -247.400663) (xy 123.160521 -247.439734)
			(xy 123.11885 -247.472965) (xy 123.072692 -247.499614) (xy 123.023078 -247.519086) (xy 122.971116 -247.530946)
			(xy 122.917966 -247.53493) (xy 122.864816 -247.530946) (xy 122.812854 -247.519086) (xy 122.76324 -247.499614)
			(xy 122.717082 -247.472965) (xy 122.675411 -247.439734) (xy 122.639159 -247.400663) (xy 122.609135 -247.356626)
			(xy 122.586009 -247.308605) (xy 122.570299 -247.257675) (xy 122.562356 -247.204971) (xy 122.333776 -247.204971)
			(xy 122.325833 -247.257675) (xy 122.310123 -247.308605) (xy 122.286997 -247.356626) (xy 122.256973 -247.400663)
			(xy 122.220721 -247.439734) (xy 122.17905 -247.472965) (xy 122.132892 -247.499614) (xy 122.083278 -247.519086)
			(xy 122.031316 -247.530946) (xy 121.978166 -247.53493) (xy 121.925016 -247.530946) (xy 121.873054 -247.519086)
			(xy 121.82344 -247.499614) (xy 121.777282 -247.472965) (xy 121.735611 -247.439734) (xy 121.699359 -247.400663)
			(xy 121.669335 -247.356626) (xy 121.646209 -247.308605) (xy 121.630499 -247.257675) (xy 121.622556 -247.204971)
			(xy 121.300379 -247.204971) (xy 121.311784 -247.23081) (xy 121.325277 -247.278268) (xy 121.332082 -247.327135)
			(xy 121.332498 -247.351804) (xy 121.331963 -247.379982) (xy 121.323088 -247.435634) (xy 121.305561 -247.489195)
			(xy 121.279819 -247.539327) (xy 121.246504 -247.584781) (xy 121.206447 -247.624421) (xy 121.160648 -247.65726)
			(xy 121.11025 -247.682478) (xy 121.056509 -247.699445) (xy 121.028714 -247.704102) (xy 120.98528 -247.710452)
			(xy 120.98528 -247.971056) (xy 121.025666 -247.979692) (xy 121.03862 -247.982486) (xy 121.05169 -247.985327)
			(xy 121.078422 -247.984837) (xy 121.104115 -247.977436) (xy 121.127012 -247.963629) (xy 121.145547 -247.944359)
			(xy 121.158455 -247.920943) (xy 121.162064 -247.908064) (xy 121.168761 -247.882559) (xy 121.188646 -247.833721)
			(xy 121.215514 -247.788347) (xy 121.248776 -247.74743) (xy 121.287706 -247.711864) (xy 121.331454 -247.682424)
			(xy 121.379064 -247.659755) (xy 121.429496 -247.644352) (xy 121.481647 -247.636552) (xy 121.508012 -247.63603)
			(xy 121.534658 -247.636529) (xy 121.587354 -247.644473) (xy 121.638278 -247.660183) (xy 121.686291 -247.683306)
			(xy 121.730323 -247.713327) (xy 121.769387 -247.749576) (xy 121.802614 -247.791241) (xy 121.829259 -247.837394)
			(xy 121.848728 -247.887002) (xy 121.860587 -247.938957) (xy 121.864569 -247.9921) (xy 121.862569 -248.018787)
			(xy 122.092202 -248.018787) (xy 122.092202 -247.965489) (xy 122.100145 -247.912785) (xy 122.115855 -247.861855)
			(xy 122.138981 -247.813834) (xy 122.169005 -247.769797) (xy 122.205257 -247.730726) (xy 122.246928 -247.697495)
			(xy 122.293086 -247.670846) (xy 122.3427 -247.651374) (xy 122.394662 -247.639514) (xy 122.447812 -247.635531)
			(xy 122.500962 -247.639514) (xy 122.552924 -247.651374) (xy 122.602538 -247.670846) (xy 122.648696 -247.697495)
			(xy 122.690367 -247.730726) (xy 122.726619 -247.769797) (xy 122.756643 -247.813834) (xy 122.779769 -247.861855)
			(xy 122.795479 -247.912785) (xy 122.803422 -247.965489) (xy 122.80392 -247.992138) (xy 122.803422 -248.018787)
			(xy 123.032002 -248.018787) (xy 123.032002 -247.965489) (xy 123.039945 -247.912785) (xy 123.055655 -247.861855)
			(xy 123.078781 -247.813834) (xy 123.108805 -247.769797) (xy 123.145057 -247.730726) (xy 123.186728 -247.697495)
			(xy 123.232886 -247.670846) (xy 123.2825 -247.651374) (xy 123.334462 -247.639514) (xy 123.387612 -247.635531)
			(xy 123.440762 -247.639514) (xy 123.492724 -247.651374) (xy 123.542338 -247.670846) (xy 123.588496 -247.697495)
			(xy 123.630167 -247.730726) (xy 123.666419 -247.769797) (xy 123.696443 -247.813834) (xy 123.719569 -247.861855)
			(xy 123.735279 -247.912785) (xy 123.743222 -247.965489) (xy 123.74372 -247.992138) (xy 123.743222 -248.018787)
			(xy 123.971802 -248.018787) (xy 123.971802 -247.965489) (xy 123.979745 -247.912785) (xy 123.995455 -247.861855)
			(xy 124.018581 -247.813834) (xy 124.048605 -247.769797) (xy 124.084857 -247.730726) (xy 124.126528 -247.697495)
			(xy 124.172686 -247.670846) (xy 124.2223 -247.651374) (xy 124.274262 -247.639514) (xy 124.327412 -247.635531)
			(xy 124.380562 -247.639514) (xy 124.432524 -247.651374) (xy 124.482138 -247.670846) (xy 124.528296 -247.697495)
			(xy 124.569967 -247.730726) (xy 124.606219 -247.769797) (xy 124.636243 -247.813834) (xy 124.659369 -247.861855)
			(xy 124.675079 -247.912785) (xy 124.683022 -247.965489) (xy 124.68352 -247.992138) (xy 124.683022 -248.018787)
			(xy 124.911602 -248.018787) (xy 124.911602 -247.965489) (xy 124.919545 -247.912785) (xy 124.935255 -247.861855)
			(xy 124.958381 -247.813834) (xy 124.988405 -247.769797) (xy 125.024657 -247.730726) (xy 125.066328 -247.697495)
			(xy 125.112486 -247.670846) (xy 125.1621 -247.651374) (xy 125.214062 -247.639514) (xy 125.267212 -247.635531)
			(xy 125.320362 -247.639514) (xy 125.372324 -247.651374) (xy 125.421938 -247.670846) (xy 125.468096 -247.697495)
			(xy 125.509767 -247.730726) (xy 125.546019 -247.769797) (xy 125.576043 -247.813834) (xy 125.599169 -247.861855)
			(xy 125.614879 -247.912785) (xy 125.622822 -247.965489) (xy 125.62332 -247.992138) (xy 125.622822 -248.018787)
			(xy 125.851656 -248.018787) (xy 125.851656 -247.965489) (xy 125.859599 -247.912785) (xy 125.875309 -247.861855)
			(xy 125.898435 -247.813834) (xy 125.928459 -247.769797) (xy 125.964711 -247.730726) (xy 126.006382 -247.697495)
			(xy 126.05254 -247.670846) (xy 126.102154 -247.651374) (xy 126.154116 -247.639514) (xy 126.207266 -247.635531)
			(xy 126.260416 -247.639514) (xy 126.312378 -247.651374) (xy 126.361992 -247.670846) (xy 126.40815 -247.697495)
			(xy 126.449821 -247.730726) (xy 126.486073 -247.769797) (xy 126.516097 -247.813834) (xy 126.539223 -247.861855)
			(xy 126.554933 -247.912785) (xy 126.562876 -247.965489) (xy 126.563374 -247.992138) (xy 126.562876 -248.018787)
			(xy 126.791202 -248.018787) (xy 126.791202 -247.965489) (xy 126.799145 -247.912785) (xy 126.814855 -247.861855)
			(xy 126.837981 -247.813834) (xy 126.868005 -247.769797) (xy 126.904257 -247.730726) (xy 126.945928 -247.697495)
			(xy 126.992086 -247.670846) (xy 127.0417 -247.651374) (xy 127.093662 -247.639514) (xy 127.146812 -247.635531)
			(xy 127.199962 -247.639514) (xy 127.251924 -247.651374) (xy 127.301538 -247.670846) (xy 127.347696 -247.697495)
			(xy 127.389367 -247.730726) (xy 127.425619 -247.769797) (xy 127.455643 -247.813834) (xy 127.478769 -247.861855)
			(xy 127.494479 -247.912785) (xy 127.502422 -247.965489) (xy 127.50292 -247.992138) (xy 127.502422 -248.018787)
			(xy 127.731002 -248.018787) (xy 127.731002 -247.965489) (xy 127.738945 -247.912785) (xy 127.754655 -247.861855)
			(xy 127.777781 -247.813834) (xy 127.807805 -247.769797) (xy 127.844057 -247.730726) (xy 127.885728 -247.697495)
			(xy 127.931886 -247.670846) (xy 127.9815 -247.651374) (xy 128.033462 -247.639514) (xy 128.086612 -247.635531)
			(xy 128.139762 -247.639514) (xy 128.191724 -247.651374) (xy 128.241338 -247.670846) (xy 128.287496 -247.697495)
			(xy 128.329167 -247.730726) (xy 128.365419 -247.769797) (xy 128.395443 -247.813834) (xy 128.418569 -247.861855)
			(xy 128.434279 -247.912785) (xy 128.442222 -247.965489) (xy 128.44272 -247.992138) (xy 128.442222 -248.018787)
			(xy 128.670802 -248.018787) (xy 128.670802 -247.965489) (xy 128.678745 -247.912785) (xy 128.694455 -247.861855)
			(xy 128.717581 -247.813834) (xy 128.747605 -247.769797) (xy 128.783857 -247.730726) (xy 128.825528 -247.697495)
			(xy 128.871686 -247.670846) (xy 128.9213 -247.651374) (xy 128.973262 -247.639514) (xy 129.026412 -247.635531)
			(xy 129.079562 -247.639514) (xy 129.131524 -247.651374) (xy 129.181138 -247.670846) (xy 129.227296 -247.697495)
			(xy 129.268967 -247.730726) (xy 129.305219 -247.769797) (xy 129.335243 -247.813834) (xy 129.358369 -247.861855)
			(xy 129.374079 -247.912785) (xy 129.382022 -247.965489) (xy 129.38252 -247.992138) (xy 129.382022 -248.018787)
			(xy 129.610602 -248.018787) (xy 129.610602 -247.965489) (xy 129.618545 -247.912785) (xy 129.634255 -247.861855)
			(xy 129.657381 -247.813834) (xy 129.687405 -247.769797) (xy 129.723657 -247.730726) (xy 129.765328 -247.697495)
			(xy 129.811486 -247.670846) (xy 129.8611 -247.651374) (xy 129.913062 -247.639514) (xy 129.966212 -247.635531)
			(xy 130.019362 -247.639514) (xy 130.071324 -247.651374) (xy 130.120938 -247.670846) (xy 130.167096 -247.697495)
			(xy 130.208767 -247.730726) (xy 130.245019 -247.769797) (xy 130.275043 -247.813834) (xy 130.298169 -247.861855)
			(xy 130.313879 -247.912785) (xy 130.321822 -247.965489) (xy 130.32232 -247.992138) (xy 130.321822 -248.018787)
			(xy 130.550656 -248.018787) (xy 130.550656 -247.965489) (xy 130.558599 -247.912785) (xy 130.574309 -247.861855)
			(xy 130.597435 -247.813834) (xy 130.627459 -247.769797) (xy 130.663711 -247.730726) (xy 130.705382 -247.697495)
			(xy 130.75154 -247.670846) (xy 130.801154 -247.651374) (xy 130.853116 -247.639514) (xy 130.906266 -247.635531)
			(xy 130.959416 -247.639514) (xy 131.011378 -247.651374) (xy 131.060992 -247.670846) (xy 131.10715 -247.697495)
			(xy 131.148821 -247.730726) (xy 131.185073 -247.769797) (xy 131.215097 -247.813834) (xy 131.238223 -247.861855)
			(xy 131.253933 -247.912785) (xy 131.261876 -247.965489) (xy 131.262374 -247.992138) (xy 131.261876 -248.018787)
			(xy 131.490202 -248.018787) (xy 131.490202 -247.965489) (xy 131.498145 -247.912785) (xy 131.513855 -247.861855)
			(xy 131.536981 -247.813834) (xy 131.567005 -247.769797) (xy 131.603257 -247.730726) (xy 131.644928 -247.697495)
			(xy 131.691086 -247.670846) (xy 131.7407 -247.651374) (xy 131.792662 -247.639514) (xy 131.845812 -247.635531)
			(xy 131.898962 -247.639514) (xy 131.950924 -247.651374) (xy 132.000538 -247.670846) (xy 132.046696 -247.697495)
			(xy 132.088367 -247.730726) (xy 132.124619 -247.769797) (xy 132.154643 -247.813834) (xy 132.177769 -247.861855)
			(xy 132.193479 -247.912785) (xy 132.201422 -247.965489) (xy 132.20192 -247.992138) (xy 132.201422 -248.018787)
			(xy 132.430256 -248.018787) (xy 132.430256 -247.965489) (xy 132.438199 -247.912785) (xy 132.453909 -247.861855)
			(xy 132.477035 -247.813834) (xy 132.507059 -247.769797) (xy 132.543311 -247.730726) (xy 132.584982 -247.697495)
			(xy 132.63114 -247.670846) (xy 132.680754 -247.651374) (xy 132.732716 -247.639514) (xy 132.785866 -247.635531)
			(xy 132.839016 -247.639514) (xy 132.890978 -247.651374) (xy 132.940592 -247.670846) (xy 132.98675 -247.697495)
			(xy 133.028421 -247.730726) (xy 133.064673 -247.769797) (xy 133.094697 -247.813834) (xy 133.117823 -247.861855)
			(xy 133.133533 -247.912785) (xy 133.141476 -247.965489) (xy 133.141974 -247.992138) (xy 133.141476 -248.018787)
			(xy 133.133533 -248.071491) (xy 133.117823 -248.122421) (xy 133.094697 -248.170442) (xy 133.064673 -248.214479)
			(xy 133.028421 -248.25355) (xy 132.98675 -248.286781) (xy 132.940592 -248.31343) (xy 132.890978 -248.332902)
			(xy 132.839016 -248.344762) (xy 132.785866 -248.348746) (xy 132.732716 -248.344762) (xy 132.680754 -248.332902)
			(xy 132.63114 -248.31343) (xy 132.584982 -248.286781) (xy 132.543311 -248.25355) (xy 132.507059 -248.214479)
			(xy 132.477035 -248.170442) (xy 132.453909 -248.122421) (xy 132.438199 -248.071491) (xy 132.430256 -248.018787)
			(xy 132.201422 -248.018787) (xy 132.193479 -248.071491) (xy 132.177769 -248.122421) (xy 132.154643 -248.170442)
			(xy 132.124619 -248.214479) (xy 132.088367 -248.25355) (xy 132.046696 -248.286781) (xy 132.000538 -248.31343)
			(xy 131.950924 -248.332902) (xy 131.898962 -248.344762) (xy 131.845812 -248.348746) (xy 131.792662 -248.344762)
			(xy 131.7407 -248.332902) (xy 131.691086 -248.31343) (xy 131.644928 -248.286781) (xy 131.603257 -248.25355)
			(xy 131.567005 -248.214479) (xy 131.536981 -248.170442) (xy 131.513855 -248.122421) (xy 131.498145 -248.071491)
			(xy 131.490202 -248.018787) (xy 131.261876 -248.018787) (xy 131.253933 -248.071491) (xy 131.238223 -248.122421)
			(xy 131.215097 -248.170442) (xy 131.185073 -248.214479) (xy 131.148821 -248.25355) (xy 131.10715 -248.286781)
			(xy 131.060992 -248.31343) (xy 131.011378 -248.332902) (xy 130.959416 -248.344762) (xy 130.906266 -248.348746)
			(xy 130.853116 -248.344762) (xy 130.801154 -248.332902) (xy 130.75154 -248.31343) (xy 130.705382 -248.286781)
			(xy 130.663711 -248.25355) (xy 130.627459 -248.214479) (xy 130.597435 -248.170442) (xy 130.574309 -248.122421)
			(xy 130.558599 -248.071491) (xy 130.550656 -248.018787) (xy 130.321822 -248.018787) (xy 130.313879 -248.071491)
			(xy 130.298169 -248.122421) (xy 130.275043 -248.170442) (xy 130.245019 -248.214479) (xy 130.208767 -248.25355)
			(xy 130.167096 -248.286781) (xy 130.120938 -248.31343) (xy 130.071324 -248.332902) (xy 130.019362 -248.344762)
			(xy 129.966212 -248.348746) (xy 129.913062 -248.344762) (xy 129.8611 -248.332902) (xy 129.811486 -248.31343)
			(xy 129.765328 -248.286781) (xy 129.723657 -248.25355) (xy 129.687405 -248.214479) (xy 129.657381 -248.170442)
			(xy 129.634255 -248.122421) (xy 129.618545 -248.071491) (xy 129.610602 -248.018787) (xy 129.382022 -248.018787)
			(xy 129.374079 -248.071491) (xy 129.358369 -248.122421) (xy 129.335243 -248.170442) (xy 129.305219 -248.214479)
			(xy 129.268967 -248.25355) (xy 129.227296 -248.286781) (xy 129.181138 -248.31343) (xy 129.131524 -248.332902)
			(xy 129.079562 -248.344762) (xy 129.026412 -248.348746) (xy 128.973262 -248.344762) (xy 128.9213 -248.332902)
			(xy 128.871686 -248.31343) (xy 128.825528 -248.286781) (xy 128.783857 -248.25355) (xy 128.747605 -248.214479)
			(xy 128.717581 -248.170442) (xy 128.694455 -248.122421) (xy 128.678745 -248.071491) (xy 128.670802 -248.018787)
			(xy 128.442222 -248.018787) (xy 128.434279 -248.071491) (xy 128.418569 -248.122421) (xy 128.395443 -248.170442)
			(xy 128.365419 -248.214479) (xy 128.329167 -248.25355) (xy 128.287496 -248.286781) (xy 128.241338 -248.31343)
			(xy 128.191724 -248.332902) (xy 128.139762 -248.344762) (xy 128.086612 -248.348746) (xy 128.033462 -248.344762)
			(xy 127.9815 -248.332902) (xy 127.931886 -248.31343) (xy 127.885728 -248.286781) (xy 127.844057 -248.25355)
			(xy 127.807805 -248.214479) (xy 127.777781 -248.170442) (xy 127.754655 -248.122421) (xy 127.738945 -248.071491)
			(xy 127.731002 -248.018787) (xy 127.502422 -248.018787) (xy 127.494479 -248.071491) (xy 127.478769 -248.122421)
			(xy 127.455643 -248.170442) (xy 127.425619 -248.214479) (xy 127.389367 -248.25355) (xy 127.347696 -248.286781)
			(xy 127.301538 -248.31343) (xy 127.251924 -248.332902) (xy 127.199962 -248.344762) (xy 127.146812 -248.348746)
			(xy 127.093662 -248.344762) (xy 127.0417 -248.332902) (xy 126.992086 -248.31343) (xy 126.945928 -248.286781)
			(xy 126.904257 -248.25355) (xy 126.868005 -248.214479) (xy 126.837981 -248.170442) (xy 126.814855 -248.122421)
			(xy 126.799145 -248.071491) (xy 126.791202 -248.018787) (xy 126.562876 -248.018787) (xy 126.554933 -248.071491)
			(xy 126.539223 -248.122421) (xy 126.516097 -248.170442) (xy 126.486073 -248.214479) (xy 126.449821 -248.25355)
			(xy 126.40815 -248.286781) (xy 126.361992 -248.31343) (xy 126.312378 -248.332902) (xy 126.260416 -248.344762)
			(xy 126.207266 -248.348746) (xy 126.154116 -248.344762) (xy 126.102154 -248.332902) (xy 126.05254 -248.31343)
			(xy 126.006382 -248.286781) (xy 125.964711 -248.25355) (xy 125.928459 -248.214479) (xy 125.898435 -248.170442)
			(xy 125.875309 -248.122421) (xy 125.859599 -248.071491) (xy 125.851656 -248.018787) (xy 125.622822 -248.018787)
			(xy 125.614879 -248.071491) (xy 125.599169 -248.122421) (xy 125.576043 -248.170442) (xy 125.546019 -248.214479)
			(xy 125.509767 -248.25355) (xy 125.468096 -248.286781) (xy 125.421938 -248.31343) (xy 125.372324 -248.332902)
			(xy 125.320362 -248.344762) (xy 125.267212 -248.348746) (xy 125.214062 -248.344762) (xy 125.1621 -248.332902)
			(xy 125.112486 -248.31343) (xy 125.066328 -248.286781) (xy 125.024657 -248.25355) (xy 124.988405 -248.214479)
			(xy 124.958381 -248.170442) (xy 124.935255 -248.122421) (xy 124.919545 -248.071491) (xy 124.911602 -248.018787)
			(xy 124.683022 -248.018787) (xy 124.675079 -248.071491) (xy 124.659369 -248.122421) (xy 124.636243 -248.170442)
			(xy 124.606219 -248.214479) (xy 124.569967 -248.25355) (xy 124.528296 -248.286781) (xy 124.482138 -248.31343)
			(xy 124.432524 -248.332902) (xy 124.380562 -248.344762) (xy 124.327412 -248.348746) (xy 124.274262 -248.344762)
			(xy 124.2223 -248.332902) (xy 124.172686 -248.31343) (xy 124.126528 -248.286781) (xy 124.084857 -248.25355)
			(xy 124.048605 -248.214479) (xy 124.018581 -248.170442) (xy 123.995455 -248.122421) (xy 123.979745 -248.071491)
			(xy 123.971802 -248.018787) (xy 123.743222 -248.018787) (xy 123.735279 -248.071491) (xy 123.719569 -248.122421)
			(xy 123.696443 -248.170442) (xy 123.666419 -248.214479) (xy 123.630167 -248.25355) (xy 123.588496 -248.286781)
			(xy 123.542338 -248.31343) (xy 123.492724 -248.332902) (xy 123.440762 -248.344762) (xy 123.387612 -248.348746)
			(xy 123.334462 -248.344762) (xy 123.2825 -248.332902) (xy 123.232886 -248.31343) (xy 123.186728 -248.286781)
			(xy 123.145057 -248.25355) (xy 123.108805 -248.214479) (xy 123.078781 -248.170442) (xy 123.055655 -248.122421)
			(xy 123.039945 -248.071491) (xy 123.032002 -248.018787) (xy 122.803422 -248.018787) (xy 122.795479 -248.071491)
			(xy 122.779769 -248.122421) (xy 122.756643 -248.170442) (xy 122.726619 -248.214479) (xy 122.690367 -248.25355)
			(xy 122.648696 -248.286781) (xy 122.602538 -248.31343) (xy 122.552924 -248.332902) (xy 122.500962 -248.344762)
			(xy 122.447812 -248.348746) (xy 122.394662 -248.344762) (xy 122.3427 -248.332902) (xy 122.293086 -248.31343)
			(xy 122.246928 -248.286781) (xy 122.205257 -248.25355) (xy 122.169005 -248.214479) (xy 122.138981 -248.170442)
			(xy 122.115855 -248.122421) (xy 122.100145 -248.071491) (xy 122.092202 -248.018787) (xy 121.862569 -248.018787)
			(xy 121.860587 -248.045243) (xy 121.848728 -248.097198) (xy 121.829259 -248.146806) (xy 121.802614 -248.192959)
			(xy 121.769387 -248.234624) (xy 121.730323 -248.270873) (xy 121.686291 -248.300894) (xy 121.638278 -248.324017)
			(xy 121.587354 -248.339727) (xy 121.534658 -248.347671) (xy 121.508012 -248.348246) (xy 121.50725 -248.348246)
			(xy 121.485761 -248.347889) (xy 121.443102 -248.342663) (xy 121.42216 -248.337832) (xy 121.409092 -248.334994)
			(xy 121.382364 -248.335487) (xy 121.356677 -248.342892) (xy 121.333787 -248.356701) (xy 121.315259 -248.375971)
			(xy 121.302358 -248.399385) (xy 121.298716 -248.412254) (xy 121.292076 -248.437572) (xy 121.272394 -248.486071)
			(xy 121.245838 -248.531174) (xy 121.212979 -248.571915) (xy 121.17452 -248.607419) (xy 121.153174 -248.622566)
			(xy 121.141175 -248.631327) (xy 121.122438 -248.654367) (xy 121.111121 -248.681824) (xy 121.108182 -248.711375)
			(xy 121.113869 -248.740523) (xy 121.1277 -248.766802) (xy 121.148508 -248.787991) (xy 121.161302 -248.79554)
			(xy 121.184798 -248.809107) (xy 121.215581 -248.832857) (xy 121.622556 -248.832857) (xy 121.622556 -248.779559)
			(xy 121.630499 -248.726855) (xy 121.646209 -248.675925) (xy 121.669335 -248.627904) (xy 121.699359 -248.583867)
			(xy 121.735611 -248.544796) (xy 121.777282 -248.511565) (xy 121.82344 -248.484916) (xy 121.873054 -248.465444)
			(xy 121.925016 -248.453584) (xy 121.978166 -248.449601) (xy 122.031316 -248.453584) (xy 122.083278 -248.465444)
			(xy 122.132892 -248.484916) (xy 122.17905 -248.511565) (xy 122.220721 -248.544796) (xy 122.256973 -248.583867)
			(xy 122.286997 -248.627904) (xy 122.310123 -248.675925) (xy 122.325833 -248.726855) (xy 122.333776 -248.779559)
			(xy 122.334274 -248.806208) (xy 122.333776 -248.832857) (xy 122.562102 -248.832857) (xy 122.562102 -248.779559)
			(xy 122.570045 -248.726855) (xy 122.585755 -248.675925) (xy 122.608881 -248.627904) (xy 122.638905 -248.583867)
			(xy 122.675157 -248.544796) (xy 122.716828 -248.511565) (xy 122.762986 -248.484916) (xy 122.8126 -248.465444)
			(xy 122.864562 -248.453584) (xy 122.917712 -248.449601) (xy 122.970862 -248.453584) (xy 123.022824 -248.465444)
			(xy 123.072438 -248.484916) (xy 123.118596 -248.511565) (xy 123.160267 -248.544796) (xy 123.196519 -248.583867)
			(xy 123.226543 -248.627904) (xy 123.249669 -248.675925) (xy 123.265379 -248.726855) (xy 123.273322 -248.779559)
			(xy 123.27382 -248.806208) (xy 123.273322 -248.832857) (xy 123.502156 -248.832857) (xy 123.502156 -248.779559)
			(xy 123.510099 -248.726855) (xy 123.525809 -248.675925) (xy 123.548935 -248.627904) (xy 123.578959 -248.583867)
			(xy 123.615211 -248.544796) (xy 123.656882 -248.511565) (xy 123.70304 -248.484916) (xy 123.752654 -248.465444)
			(xy 123.804616 -248.453584) (xy 123.857766 -248.449601) (xy 123.910916 -248.453584) (xy 123.962878 -248.465444)
			(xy 124.012492 -248.484916) (xy 124.05865 -248.511565) (xy 124.100321 -248.544796) (xy 124.136573 -248.583867)
			(xy 124.166597 -248.627904) (xy 124.189723 -248.675925) (xy 124.205433 -248.726855) (xy 124.213376 -248.779559)
			(xy 124.213874 -248.806208) (xy 124.213376 -248.832857) (xy 124.441956 -248.832857) (xy 124.441956 -248.779559)
			(xy 124.449899 -248.726855) (xy 124.465609 -248.675925) (xy 124.488735 -248.627904) (xy 124.518759 -248.583867)
			(xy 124.555011 -248.544796) (xy 124.596682 -248.511565) (xy 124.64284 -248.484916) (xy 124.692454 -248.465444)
			(xy 124.744416 -248.453584) (xy 124.797566 -248.449601) (xy 124.850716 -248.453584) (xy 124.902678 -248.465444)
			(xy 124.952292 -248.484916) (xy 124.99845 -248.511565) (xy 125.040121 -248.544796) (xy 125.076373 -248.583867)
			(xy 125.106397 -248.627904) (xy 125.129523 -248.675925) (xy 125.145233 -248.726855) (xy 125.153176 -248.779559)
			(xy 125.153674 -248.806208) (xy 125.153176 -248.832857) (xy 125.381756 -248.832857) (xy 125.381756 -248.779559)
			(xy 125.389699 -248.726855) (xy 125.405409 -248.675925) (xy 125.428535 -248.627904) (xy 125.458559 -248.583867)
			(xy 125.494811 -248.544796) (xy 125.536482 -248.511565) (xy 125.58264 -248.484916) (xy 125.632254 -248.465444)
			(xy 125.684216 -248.453584) (xy 125.737366 -248.449601) (xy 125.790516 -248.453584) (xy 125.842478 -248.465444)
			(xy 125.892092 -248.484916) (xy 125.93825 -248.511565) (xy 125.979921 -248.544796) (xy 126.016173 -248.583867)
			(xy 126.046197 -248.627904) (xy 126.069323 -248.675925) (xy 126.085033 -248.726855) (xy 126.092976 -248.779559)
			(xy 126.093474 -248.806208) (xy 126.092976 -248.832857) (xy 126.321556 -248.832857) (xy 126.321556 -248.779559)
			(xy 126.329499 -248.726855) (xy 126.345209 -248.675925) (xy 126.368335 -248.627904) (xy 126.398359 -248.583867)
			(xy 126.434611 -248.544796) (xy 126.476282 -248.511565) (xy 126.52244 -248.484916) (xy 126.572054 -248.465444)
			(xy 126.624016 -248.453584) (xy 126.677166 -248.449601) (xy 126.730316 -248.453584) (xy 126.782278 -248.465444)
			(xy 126.831892 -248.484916) (xy 126.87805 -248.511565) (xy 126.919721 -248.544796) (xy 126.955973 -248.583867)
			(xy 126.985997 -248.627904) (xy 127.009123 -248.675925) (xy 127.024833 -248.726855) (xy 127.032776 -248.779559)
			(xy 127.033274 -248.806208) (xy 127.032776 -248.832857) (xy 127.261356 -248.832857) (xy 127.261356 -248.779559)
			(xy 127.269299 -248.726855) (xy 127.285009 -248.675925) (xy 127.308135 -248.627904) (xy 127.338159 -248.583867)
			(xy 127.374411 -248.544796) (xy 127.416082 -248.511565) (xy 127.46224 -248.484916) (xy 127.511854 -248.465444)
			(xy 127.563816 -248.453584) (xy 127.616966 -248.449601) (xy 127.670116 -248.453584) (xy 127.722078 -248.465444)
			(xy 127.771692 -248.484916) (xy 127.81785 -248.511565) (xy 127.859521 -248.544796) (xy 127.895773 -248.583867)
			(xy 127.925797 -248.627904) (xy 127.948923 -248.675925) (xy 127.964633 -248.726855) (xy 127.972576 -248.779559)
			(xy 127.973074 -248.806208) (xy 127.972576 -248.832857) (xy 128.201156 -248.832857) (xy 128.201156 -248.779559)
			(xy 128.209099 -248.726855) (xy 128.224809 -248.675925) (xy 128.247935 -248.627904) (xy 128.277959 -248.583867)
			(xy 128.314211 -248.544796) (xy 128.355882 -248.511565) (xy 128.40204 -248.484916) (xy 128.451654 -248.465444)
			(xy 128.503616 -248.453584) (xy 128.556766 -248.449601) (xy 128.609916 -248.453584) (xy 128.661878 -248.465444)
			(xy 128.711492 -248.484916) (xy 128.75765 -248.511565) (xy 128.799321 -248.544796) (xy 128.835573 -248.583867)
			(xy 128.865597 -248.627904) (xy 128.888723 -248.675925) (xy 128.904433 -248.726855) (xy 128.912376 -248.779559)
			(xy 128.912874 -248.806208) (xy 128.912376 -248.832857) (xy 129.140702 -248.832857) (xy 129.140702 -248.779559)
			(xy 129.148645 -248.726855) (xy 129.164355 -248.675925) (xy 129.187481 -248.627904) (xy 129.217505 -248.583867)
			(xy 129.253757 -248.544796) (xy 129.295428 -248.511565) (xy 129.341586 -248.484916) (xy 129.3912 -248.465444)
			(xy 129.443162 -248.453584) (xy 129.496312 -248.449601) (xy 129.549462 -248.453584) (xy 129.601424 -248.465444)
			(xy 129.651038 -248.484916) (xy 129.697196 -248.511565) (xy 129.738867 -248.544796) (xy 129.775119 -248.583867)
			(xy 129.805143 -248.627904) (xy 129.828269 -248.675925) (xy 129.843979 -248.726855) (xy 129.851922 -248.779559)
			(xy 129.85242 -248.806208) (xy 129.851922 -248.832857) (xy 130.080756 -248.832857) (xy 130.080756 -248.779559)
			(xy 130.088699 -248.726855) (xy 130.104409 -248.675925) (xy 130.127535 -248.627904) (xy 130.157559 -248.583867)
			(xy 130.193811 -248.544796) (xy 130.235482 -248.511565) (xy 130.28164 -248.484916) (xy 130.331254 -248.465444)
			(xy 130.383216 -248.453584) (xy 130.436366 -248.449601) (xy 130.489516 -248.453584) (xy 130.541478 -248.465444)
			(xy 130.591092 -248.484916) (xy 130.63725 -248.511565) (xy 130.678921 -248.544796) (xy 130.715173 -248.583867)
			(xy 130.745197 -248.627904) (xy 130.768323 -248.675925) (xy 130.784033 -248.726855) (xy 130.791976 -248.779559)
			(xy 130.792474 -248.806208) (xy 130.791976 -248.832857) (xy 131.020556 -248.832857) (xy 131.020556 -248.779559)
			(xy 131.028499 -248.726855) (xy 131.044209 -248.675925) (xy 131.067335 -248.627904) (xy 131.097359 -248.583867)
			(xy 131.133611 -248.544796) (xy 131.175282 -248.511565) (xy 131.22144 -248.484916) (xy 131.271054 -248.465444)
			(xy 131.323016 -248.453584) (xy 131.376166 -248.449601) (xy 131.429316 -248.453584) (xy 131.481278 -248.465444)
			(xy 131.530892 -248.484916) (xy 131.57705 -248.511565) (xy 131.618721 -248.544796) (xy 131.654973 -248.583867)
			(xy 131.684997 -248.627904) (xy 131.708123 -248.675925) (xy 131.723833 -248.726855) (xy 131.731776 -248.779559)
			(xy 131.732274 -248.806208) (xy 131.731776 -248.832857) (xy 131.960356 -248.832857) (xy 131.960356 -248.779559)
			(xy 131.968299 -248.726855) (xy 131.984009 -248.675925) (xy 132.007135 -248.627904) (xy 132.037159 -248.583867)
			(xy 132.073411 -248.544796) (xy 132.115082 -248.511565) (xy 132.16124 -248.484916) (xy 132.210854 -248.465444)
			(xy 132.262816 -248.453584) (xy 132.315966 -248.449601) (xy 132.369116 -248.453584) (xy 132.421078 -248.465444)
			(xy 132.470692 -248.484916) (xy 132.51685 -248.511565) (xy 132.558521 -248.544796) (xy 132.594773 -248.583867)
			(xy 132.624797 -248.627904) (xy 132.647923 -248.675925) (xy 132.663633 -248.726855) (xy 132.671576 -248.779559)
			(xy 132.672074 -248.806208) (xy 132.671576 -248.832857) (xy 133.839956 -248.832857) (xy 133.839956 -248.779559)
			(xy 133.847899 -248.726855) (xy 133.863609 -248.675925) (xy 133.886735 -248.627904) (xy 133.916759 -248.583867)
			(xy 133.953011 -248.544796) (xy 133.994682 -248.511565) (xy 134.04084 -248.484916) (xy 134.090454 -248.465444)
			(xy 134.142416 -248.453584) (xy 134.195566 -248.449601) (xy 134.248716 -248.453584) (xy 134.300678 -248.465444)
			(xy 134.350292 -248.484916) (xy 134.39645 -248.511565) (xy 134.438121 -248.544796) (xy 134.474373 -248.583867)
			(xy 134.504397 -248.627904) (xy 134.527523 -248.675925) (xy 134.543233 -248.726855) (xy 134.551176 -248.779559)
			(xy 134.551674 -248.806208) (xy 134.551176 -248.832857) (xy 134.543233 -248.885561) (xy 134.527523 -248.936491)
			(xy 134.504397 -248.984512) (xy 134.474373 -249.028549) (xy 134.438121 -249.06762) (xy 134.39645 -249.100851)
			(xy 134.350292 -249.1275) (xy 134.300678 -249.146972) (xy 134.248716 -249.158832) (xy 134.195566 -249.162816)
			(xy 134.142416 -249.158832) (xy 134.090454 -249.146972) (xy 134.04084 -249.1275) (xy 133.994682 -249.100851)
			(xy 133.953011 -249.06762) (xy 133.916759 -249.028549) (xy 133.886735 -248.984512) (xy 133.863609 -248.936491)
			(xy 133.847899 -248.885561) (xy 133.839956 -248.832857) (xy 132.671576 -248.832857) (xy 132.663633 -248.885561)
			(xy 132.647923 -248.936491) (xy 132.624797 -248.984512) (xy 132.594773 -249.028549) (xy 132.558521 -249.06762)
			(xy 132.51685 -249.100851) (xy 132.470692 -249.1275) (xy 132.421078 -249.146972) (xy 132.369116 -249.158832)
			(xy 132.315966 -249.162816) (xy 132.262816 -249.158832) (xy 132.210854 -249.146972) (xy 132.16124 -249.1275)
			(xy 132.115082 -249.100851) (xy 132.073411 -249.06762) (xy 132.037159 -249.028549) (xy 132.007135 -248.984512)
			(xy 131.984009 -248.936491) (xy 131.968299 -248.885561) (xy 131.960356 -248.832857) (xy 131.731776 -248.832857)
			(xy 131.723833 -248.885561) (xy 131.708123 -248.936491) (xy 131.684997 -248.984512) (xy 131.654973 -249.028549)
			(xy 131.618721 -249.06762) (xy 131.57705 -249.100851) (xy 131.530892 -249.1275) (xy 131.481278 -249.146972)
			(xy 131.429316 -249.158832) (xy 131.376166 -249.162816) (xy 131.323016 -249.158832) (xy 131.271054 -249.146972)
			(xy 131.22144 -249.1275) (xy 131.175282 -249.100851) (xy 131.133611 -249.06762) (xy 131.097359 -249.028549)
			(xy 131.067335 -248.984512) (xy 131.044209 -248.936491) (xy 131.028499 -248.885561) (xy 131.020556 -248.832857)
			(xy 130.791976 -248.832857) (xy 130.784033 -248.885561) (xy 130.768323 -248.936491) (xy 130.745197 -248.984512)
			(xy 130.715173 -249.028549) (xy 130.678921 -249.06762) (xy 130.63725 -249.100851) (xy 130.591092 -249.1275)
			(xy 130.541478 -249.146972) (xy 130.489516 -249.158832) (xy 130.436366 -249.162816) (xy 130.383216 -249.158832)
			(xy 130.331254 -249.146972) (xy 130.28164 -249.1275) (xy 130.235482 -249.100851) (xy 130.193811 -249.06762)
			(xy 130.157559 -249.028549) (xy 130.127535 -248.984512) (xy 130.104409 -248.936491) (xy 130.088699 -248.885561)
			(xy 130.080756 -248.832857) (xy 129.851922 -248.832857) (xy 129.843979 -248.885561) (xy 129.828269 -248.936491)
			(xy 129.805143 -248.984512) (xy 129.775119 -249.028549) (xy 129.738867 -249.06762) (xy 129.697196 -249.100851)
			(xy 129.651038 -249.1275) (xy 129.601424 -249.146972) (xy 129.549462 -249.158832) (xy 129.496312 -249.162816)
			(xy 129.443162 -249.158832) (xy 129.3912 -249.146972) (xy 129.341586 -249.1275) (xy 129.295428 -249.100851)
			(xy 129.253757 -249.06762) (xy 129.217505 -249.028549) (xy 129.187481 -248.984512) (xy 129.164355 -248.936491)
			(xy 129.148645 -248.885561) (xy 129.140702 -248.832857) (xy 128.912376 -248.832857) (xy 128.904433 -248.885561)
			(xy 128.888723 -248.936491) (xy 128.865597 -248.984512) (xy 128.835573 -249.028549) (xy 128.799321 -249.06762)
			(xy 128.75765 -249.100851) (xy 128.711492 -249.1275) (xy 128.661878 -249.146972) (xy 128.609916 -249.158832)
			(xy 128.556766 -249.162816) (xy 128.503616 -249.158832) (xy 128.451654 -249.146972) (xy 128.40204 -249.1275)
			(xy 128.355882 -249.100851) (xy 128.314211 -249.06762) (xy 128.277959 -249.028549) (xy 128.247935 -248.984512)
			(xy 128.224809 -248.936491) (xy 128.209099 -248.885561) (xy 128.201156 -248.832857) (xy 127.972576 -248.832857)
			(xy 127.964633 -248.885561) (xy 127.948923 -248.936491) (xy 127.925797 -248.984512) (xy 127.895773 -249.028549)
			(xy 127.859521 -249.06762) (xy 127.81785 -249.100851) (xy 127.771692 -249.1275) (xy 127.722078 -249.146972)
			(xy 127.670116 -249.158832) (xy 127.616966 -249.162816) (xy 127.563816 -249.158832) (xy 127.511854 -249.146972)
			(xy 127.46224 -249.1275) (xy 127.416082 -249.100851) (xy 127.374411 -249.06762) (xy 127.338159 -249.028549)
			(xy 127.308135 -248.984512) (xy 127.285009 -248.936491) (xy 127.269299 -248.885561) (xy 127.261356 -248.832857)
			(xy 127.032776 -248.832857) (xy 127.024833 -248.885561) (xy 127.009123 -248.936491) (xy 126.985997 -248.984512)
			(xy 126.955973 -249.028549) (xy 126.919721 -249.06762) (xy 126.87805 -249.100851) (xy 126.831892 -249.1275)
			(xy 126.782278 -249.146972) (xy 126.730316 -249.158832) (xy 126.677166 -249.162816) (xy 126.624016 -249.158832)
			(xy 126.572054 -249.146972) (xy 126.52244 -249.1275) (xy 126.476282 -249.100851) (xy 126.434611 -249.06762)
			(xy 126.398359 -249.028549) (xy 126.368335 -248.984512) (xy 126.345209 -248.936491) (xy 126.329499 -248.885561)
			(xy 126.321556 -248.832857) (xy 126.092976 -248.832857) (xy 126.085033 -248.885561) (xy 126.069323 -248.936491)
			(xy 126.046197 -248.984512) (xy 126.016173 -249.028549) (xy 125.979921 -249.06762) (xy 125.93825 -249.100851)
			(xy 125.892092 -249.1275) (xy 125.842478 -249.146972) (xy 125.790516 -249.158832) (xy 125.737366 -249.162816)
			(xy 125.684216 -249.158832) (xy 125.632254 -249.146972) (xy 125.58264 -249.1275) (xy 125.536482 -249.100851)
			(xy 125.494811 -249.06762) (xy 125.458559 -249.028549) (xy 125.428535 -248.984512) (xy 125.405409 -248.936491)
			(xy 125.389699 -248.885561) (xy 125.381756 -248.832857) (xy 125.153176 -248.832857) (xy 125.145233 -248.885561)
			(xy 125.129523 -248.936491) (xy 125.106397 -248.984512) (xy 125.076373 -249.028549) (xy 125.040121 -249.06762)
			(xy 124.99845 -249.100851) (xy 124.952292 -249.1275) (xy 124.902678 -249.146972) (xy 124.850716 -249.158832)
			(xy 124.797566 -249.162816) (xy 124.744416 -249.158832) (xy 124.692454 -249.146972) (xy 124.64284 -249.1275)
			(xy 124.596682 -249.100851) (xy 124.555011 -249.06762) (xy 124.518759 -249.028549) (xy 124.488735 -248.984512)
			(xy 124.465609 -248.936491) (xy 124.449899 -248.885561) (xy 124.441956 -248.832857) (xy 124.213376 -248.832857)
			(xy 124.205433 -248.885561) (xy 124.189723 -248.936491) (xy 124.166597 -248.984512) (xy 124.136573 -249.028549)
			(xy 124.100321 -249.06762) (xy 124.05865 -249.100851) (xy 124.012492 -249.1275) (xy 123.962878 -249.146972)
			(xy 123.910916 -249.158832) (xy 123.857766 -249.162816) (xy 123.804616 -249.158832) (xy 123.752654 -249.146972)
			(xy 123.70304 -249.1275) (xy 123.656882 -249.100851) (xy 123.615211 -249.06762) (xy 123.578959 -249.028549)
			(xy 123.548935 -248.984512) (xy 123.525809 -248.936491) (xy 123.510099 -248.885561) (xy 123.502156 -248.832857)
			(xy 123.273322 -248.832857) (xy 123.265379 -248.885561) (xy 123.249669 -248.936491) (xy 123.226543 -248.984512)
			(xy 123.196519 -249.028549) (xy 123.160267 -249.06762) (xy 123.118596 -249.100851) (xy 123.072438 -249.1275)
			(xy 123.022824 -249.146972) (xy 122.970862 -249.158832) (xy 122.917712 -249.162816) (xy 122.864562 -249.158832)
			(xy 122.8126 -249.146972) (xy 122.762986 -249.1275) (xy 122.716828 -249.100851) (xy 122.675157 -249.06762)
			(xy 122.638905 -249.028549) (xy 122.608881 -248.984512) (xy 122.585755 -248.936491) (xy 122.570045 -248.885561)
			(xy 122.562102 -248.832857) (xy 122.333776 -248.832857) (xy 122.325833 -248.885561) (xy 122.310123 -248.936491)
			(xy 122.286997 -248.984512) (xy 122.256973 -249.028549) (xy 122.220721 -249.06762) (xy 122.17905 -249.100851)
			(xy 122.132892 -249.1275) (xy 122.083278 -249.146972) (xy 122.031316 -249.158832) (xy 121.978166 -249.162816)
			(xy 121.925016 -249.158832) (xy 121.873054 -249.146972) (xy 121.82344 -249.1275) (xy 121.777282 -249.100851)
			(xy 121.735611 -249.06762) (xy 121.699359 -249.028549) (xy 121.669335 -248.984512) (xy 121.646209 -248.936491)
			(xy 121.630499 -248.885561) (xy 121.622556 -248.832857) (xy 121.215581 -248.832857) (xy 121.227752 -248.842247)
			(xy 121.265185 -248.881517) (xy 121.296229 -248.92601) (xy 121.320168 -248.974696) (xy 121.336446 -249.026449)
			(xy 121.344689 -249.080072) (xy 121.345198 -249.107198) (xy 121.345105 -249.118853) (xy 121.34358 -249.142113)
			(xy 121.34215 -249.15368) (xy 121.340822 -249.167014) (xy 121.344389 -249.193562) (xy 121.354733 -249.218271)
			(xy 121.371143 -249.239443) (xy 121.392492 -249.255622) (xy 121.417312 -249.265696) (xy 121.443898 -249.268974)
			(xy 121.457212 -249.267472) (xy 121.469844 -249.265783) (xy 121.495268 -249.264005) (xy 121.508012 -249.263916)
			(xy 121.53509 -249.264422) (xy 121.588621 -249.272625) (xy 121.640292 -249.288838) (xy 121.688913 -249.312689)
			(xy 121.733361 -249.343628) (xy 121.772612 -249.38094) (xy 121.80576 -249.423765) (xy 121.832041 -249.471116)
			(xy 121.850849 -249.521901) (xy 121.861751 -249.574948) (xy 121.864494 -249.629034) (xy 121.8627 -249.646673)
			(xy 122.092202 -249.646673) (xy 122.092202 -249.593375) (xy 122.100145 -249.540671) (xy 122.115855 -249.489741)
			(xy 122.138981 -249.44172) (xy 122.169005 -249.397683) (xy 122.205257 -249.358612) (xy 122.246928 -249.325381)
			(xy 122.293086 -249.298732) (xy 122.3427 -249.27926) (xy 122.394662 -249.2674) (xy 122.447812 -249.263417)
			(xy 122.500962 -249.2674) (xy 122.552924 -249.27926) (xy 122.602538 -249.298732) (xy 122.648696 -249.325381)
			(xy 122.690367 -249.358612) (xy 122.726619 -249.397683) (xy 122.756643 -249.44172) (xy 122.779769 -249.489741)
			(xy 122.795479 -249.540671) (xy 122.803422 -249.593375) (xy 122.80392 -249.620024) (xy 122.803422 -249.646673)
			(xy 123.032002 -249.646673) (xy 123.032002 -249.593375) (xy 123.039945 -249.540671) (xy 123.055655 -249.489741)
			(xy 123.078781 -249.44172) (xy 123.108805 -249.397683) (xy 123.145057 -249.358612) (xy 123.186728 -249.325381)
			(xy 123.232886 -249.298732) (xy 123.2825 -249.27926) (xy 123.334462 -249.2674) (xy 123.387612 -249.263417)
			(xy 123.440762 -249.2674) (xy 123.492724 -249.27926) (xy 123.542338 -249.298732) (xy 123.588496 -249.325381)
			(xy 123.630167 -249.358612) (xy 123.666419 -249.397683) (xy 123.696443 -249.44172) (xy 123.719569 -249.489741)
			(xy 123.735279 -249.540671) (xy 123.743222 -249.593375) (xy 123.74372 -249.620024) (xy 123.743222 -249.646673)
			(xy 123.971802 -249.646673) (xy 123.971802 -249.593375) (xy 123.979745 -249.540671) (xy 123.995455 -249.489741)
			(xy 124.018581 -249.44172) (xy 124.048605 -249.397683) (xy 124.084857 -249.358612) (xy 124.126528 -249.325381)
			(xy 124.172686 -249.298732) (xy 124.2223 -249.27926) (xy 124.274262 -249.2674) (xy 124.327412 -249.263417)
			(xy 124.380562 -249.2674) (xy 124.432524 -249.27926) (xy 124.482138 -249.298732) (xy 124.528296 -249.325381)
			(xy 124.569967 -249.358612) (xy 124.606219 -249.397683) (xy 124.636243 -249.44172) (xy 124.659369 -249.489741)
			(xy 124.675079 -249.540671) (xy 124.683022 -249.593375) (xy 124.68352 -249.620024) (xy 124.683022 -249.646673)
			(xy 124.911856 -249.646673) (xy 124.911856 -249.593375) (xy 124.919799 -249.540671) (xy 124.935509 -249.489741)
			(xy 124.958635 -249.44172) (xy 124.988659 -249.397683) (xy 125.024911 -249.358612) (xy 125.066582 -249.325381)
			(xy 125.11274 -249.298732) (xy 125.162354 -249.27926) (xy 125.214316 -249.2674) (xy 125.267466 -249.263417)
			(xy 125.320616 -249.2674) (xy 125.372578 -249.27926) (xy 125.422192 -249.298732) (xy 125.46835 -249.325381)
			(xy 125.510021 -249.358612) (xy 125.546273 -249.397683) (xy 125.576297 -249.44172) (xy 125.599423 -249.489741)
			(xy 125.615133 -249.540671) (xy 125.623076 -249.593375) (xy 125.623574 -249.620024) (xy 125.623076 -249.646673)
			(xy 125.851402 -249.646673) (xy 125.851402 -249.593375) (xy 125.859345 -249.540671) (xy 125.875055 -249.489741)
			(xy 125.898181 -249.44172) (xy 125.928205 -249.397683) (xy 125.964457 -249.358612) (xy 126.006128 -249.325381)
			(xy 126.052286 -249.298732) (xy 126.1019 -249.27926) (xy 126.153862 -249.2674) (xy 126.207012 -249.263417)
			(xy 126.260162 -249.2674) (xy 126.312124 -249.27926) (xy 126.361738 -249.298732) (xy 126.407896 -249.325381)
			(xy 126.449567 -249.358612) (xy 126.485819 -249.397683) (xy 126.515843 -249.44172) (xy 126.538969 -249.489741)
			(xy 126.554679 -249.540671) (xy 126.562622 -249.593375) (xy 126.56312 -249.620024) (xy 126.562622 -249.646673)
			(xy 126.791202 -249.646673) (xy 126.791202 -249.593375) (xy 126.799145 -249.540671) (xy 126.814855 -249.489741)
			(xy 126.837981 -249.44172) (xy 126.868005 -249.397683) (xy 126.904257 -249.358612) (xy 126.945928 -249.325381)
			(xy 126.992086 -249.298732) (xy 127.0417 -249.27926) (xy 127.093662 -249.2674) (xy 127.146812 -249.263417)
			(xy 127.199962 -249.2674) (xy 127.251924 -249.27926) (xy 127.301538 -249.298732) (xy 127.347696 -249.325381)
			(xy 127.389367 -249.358612) (xy 127.425619 -249.397683) (xy 127.455643 -249.44172) (xy 127.478769 -249.489741)
			(xy 127.494479 -249.540671) (xy 127.502422 -249.593375) (xy 127.50292 -249.620024) (xy 127.502422 -249.646673)
			(xy 127.731002 -249.646673) (xy 127.731002 -249.593375) (xy 127.738945 -249.540671) (xy 127.754655 -249.489741)
			(xy 127.777781 -249.44172) (xy 127.807805 -249.397683) (xy 127.844057 -249.358612) (xy 127.885728 -249.325381)
			(xy 127.931886 -249.298732) (xy 127.9815 -249.27926) (xy 128.033462 -249.2674) (xy 128.086612 -249.263417)
			(xy 128.139762 -249.2674) (xy 128.191724 -249.27926) (xy 128.241338 -249.298732) (xy 128.287496 -249.325381)
			(xy 128.329167 -249.358612) (xy 128.365419 -249.397683) (xy 128.395443 -249.44172) (xy 128.418569 -249.489741)
			(xy 128.434279 -249.540671) (xy 128.442222 -249.593375) (xy 128.44272 -249.620024) (xy 128.442222 -249.646673)
			(xy 128.670802 -249.646673) (xy 128.670802 -249.593375) (xy 128.678745 -249.540671) (xy 128.694455 -249.489741)
			(xy 128.717581 -249.44172) (xy 128.747605 -249.397683) (xy 128.783857 -249.358612) (xy 128.825528 -249.325381)
			(xy 128.871686 -249.298732) (xy 128.9213 -249.27926) (xy 128.973262 -249.2674) (xy 129.026412 -249.263417)
			(xy 129.079562 -249.2674) (xy 129.131524 -249.27926) (xy 129.181138 -249.298732) (xy 129.227296 -249.325381)
			(xy 129.268967 -249.358612) (xy 129.305219 -249.397683) (xy 129.335243 -249.44172) (xy 129.358369 -249.489741)
			(xy 129.374079 -249.540671) (xy 129.382022 -249.593375) (xy 129.38252 -249.620024) (xy 129.382022 -249.646673)
			(xy 129.610602 -249.646673) (xy 129.610602 -249.593375) (xy 129.618545 -249.540671) (xy 129.634255 -249.489741)
			(xy 129.657381 -249.44172) (xy 129.687405 -249.397683) (xy 129.723657 -249.358612) (xy 129.765328 -249.325381)
			(xy 129.811486 -249.298732) (xy 129.8611 -249.27926) (xy 129.913062 -249.2674) (xy 129.966212 -249.263417)
			(xy 130.019362 -249.2674) (xy 130.071324 -249.27926) (xy 130.120938 -249.298732) (xy 130.167096 -249.325381)
			(xy 130.208767 -249.358612) (xy 130.245019 -249.397683) (xy 130.275043 -249.44172) (xy 130.298169 -249.489741)
			(xy 130.313879 -249.540671) (xy 130.321822 -249.593375) (xy 130.32232 -249.620024) (xy 130.321822 -249.646673)
			(xy 130.550402 -249.646673) (xy 130.550402 -249.593375) (xy 130.558345 -249.540671) (xy 130.574055 -249.489741)
			(xy 130.597181 -249.44172) (xy 130.627205 -249.397683) (xy 130.663457 -249.358612) (xy 130.705128 -249.325381)
			(xy 130.751286 -249.298732) (xy 130.8009 -249.27926) (xy 130.852862 -249.2674) (xy 130.906012 -249.263417)
			(xy 130.959162 -249.2674) (xy 131.011124 -249.27926) (xy 131.060738 -249.298732) (xy 131.106896 -249.325381)
			(xy 131.148567 -249.358612) (xy 131.184819 -249.397683) (xy 131.214843 -249.44172) (xy 131.237969 -249.489741)
			(xy 131.253679 -249.540671) (xy 131.261622 -249.593375) (xy 131.26212 -249.620024) (xy 131.261622 -249.646673)
			(xy 131.490456 -249.646673) (xy 131.490456 -249.593375) (xy 131.498399 -249.540671) (xy 131.514109 -249.489741)
			(xy 131.537235 -249.44172) (xy 131.567259 -249.397683) (xy 131.603511 -249.358612) (xy 131.645182 -249.325381)
			(xy 131.69134 -249.298732) (xy 131.740954 -249.27926) (xy 131.792916 -249.2674) (xy 131.846066 -249.263417)
			(xy 131.899216 -249.2674) (xy 131.951178 -249.27926) (xy 132.000792 -249.298732) (xy 132.04695 -249.325381)
			(xy 132.088621 -249.358612) (xy 132.124873 -249.397683) (xy 132.154897 -249.44172) (xy 132.178023 -249.489741)
			(xy 132.193733 -249.540671) (xy 132.201676 -249.593375) (xy 132.202174 -249.620024) (xy 132.201676 -249.646673)
			(xy 132.193733 -249.699377) (xy 132.178023 -249.750307) (xy 132.154897 -249.798328) (xy 132.124873 -249.842365)
			(xy 132.088621 -249.881436) (xy 132.04695 -249.914667) (xy 132.000792 -249.941316) (xy 131.951178 -249.960788)
			(xy 131.899216 -249.972648) (xy 131.846066 -249.976632) (xy 131.792916 -249.972648) (xy 131.740954 -249.960788)
			(xy 131.69134 -249.941316) (xy 131.645182 -249.914667) (xy 131.603511 -249.881436) (xy 131.567259 -249.842365)
			(xy 131.537235 -249.798328) (xy 131.514109 -249.750307) (xy 131.498399 -249.699377) (xy 131.490456 -249.646673)
			(xy 131.261622 -249.646673) (xy 131.253679 -249.699377) (xy 131.237969 -249.750307) (xy 131.214843 -249.798328)
			(xy 131.184819 -249.842365) (xy 131.148567 -249.881436) (xy 131.106896 -249.914667) (xy 131.060738 -249.941316)
			(xy 131.011124 -249.960788) (xy 130.959162 -249.972648) (xy 130.906012 -249.976632) (xy 130.852862 -249.972648)
			(xy 130.8009 -249.960788) (xy 130.751286 -249.941316) (xy 130.705128 -249.914667) (xy 130.663457 -249.881436)
			(xy 130.627205 -249.842365) (xy 130.597181 -249.798328) (xy 130.574055 -249.750307) (xy 130.558345 -249.699377)
			(xy 130.550402 -249.646673) (xy 130.321822 -249.646673) (xy 130.313879 -249.699377) (xy 130.298169 -249.750307)
			(xy 130.275043 -249.798328) (xy 130.245019 -249.842365) (xy 130.208767 -249.881436) (xy 130.167096 -249.914667)
			(xy 130.120938 -249.941316) (xy 130.071324 -249.960788) (xy 130.019362 -249.972648) (xy 129.966212 -249.976632)
			(xy 129.913062 -249.972648) (xy 129.8611 -249.960788) (xy 129.811486 -249.941316) (xy 129.765328 -249.914667)
			(xy 129.723657 -249.881436) (xy 129.687405 -249.842365) (xy 129.657381 -249.798328) (xy 129.634255 -249.750307)
			(xy 129.618545 -249.699377) (xy 129.610602 -249.646673) (xy 129.382022 -249.646673) (xy 129.374079 -249.699377)
			(xy 129.358369 -249.750307) (xy 129.335243 -249.798328) (xy 129.305219 -249.842365) (xy 129.268967 -249.881436)
			(xy 129.227296 -249.914667) (xy 129.181138 -249.941316) (xy 129.131524 -249.960788) (xy 129.079562 -249.972648)
			(xy 129.026412 -249.976632) (xy 128.973262 -249.972648) (xy 128.9213 -249.960788) (xy 128.871686 -249.941316)
			(xy 128.825528 -249.914667) (xy 128.783857 -249.881436) (xy 128.747605 -249.842365) (xy 128.717581 -249.798328)
			(xy 128.694455 -249.750307) (xy 128.678745 -249.699377) (xy 128.670802 -249.646673) (xy 128.442222 -249.646673)
			(xy 128.434279 -249.699377) (xy 128.418569 -249.750307) (xy 128.395443 -249.798328) (xy 128.365419 -249.842365)
			(xy 128.329167 -249.881436) (xy 128.287496 -249.914667) (xy 128.241338 -249.941316) (xy 128.191724 -249.960788)
			(xy 128.139762 -249.972648) (xy 128.086612 -249.976632) (xy 128.033462 -249.972648) (xy 127.9815 -249.960788)
			(xy 127.931886 -249.941316) (xy 127.885728 -249.914667) (xy 127.844057 -249.881436) (xy 127.807805 -249.842365)
			(xy 127.777781 -249.798328) (xy 127.754655 -249.750307) (xy 127.738945 -249.699377) (xy 127.731002 -249.646673)
			(xy 127.502422 -249.646673) (xy 127.494479 -249.699377) (xy 127.478769 -249.750307) (xy 127.455643 -249.798328)
			(xy 127.425619 -249.842365) (xy 127.389367 -249.881436) (xy 127.347696 -249.914667) (xy 127.301538 -249.941316)
			(xy 127.251924 -249.960788) (xy 127.199962 -249.972648) (xy 127.146812 -249.976632) (xy 127.093662 -249.972648)
			(xy 127.0417 -249.960788) (xy 126.992086 -249.941316) (xy 126.945928 -249.914667) (xy 126.904257 -249.881436)
			(xy 126.868005 -249.842365) (xy 126.837981 -249.798328) (xy 126.814855 -249.750307) (xy 126.799145 -249.699377)
			(xy 126.791202 -249.646673) (xy 126.562622 -249.646673) (xy 126.554679 -249.699377) (xy 126.538969 -249.750307)
			(xy 126.515843 -249.798328) (xy 126.485819 -249.842365) (xy 126.449567 -249.881436) (xy 126.407896 -249.914667)
			(xy 126.361738 -249.941316) (xy 126.312124 -249.960788) (xy 126.260162 -249.972648) (xy 126.207012 -249.976632)
			(xy 126.153862 -249.972648) (xy 126.1019 -249.960788) (xy 126.052286 -249.941316) (xy 126.006128 -249.914667)
			(xy 125.964457 -249.881436) (xy 125.928205 -249.842365) (xy 125.898181 -249.798328) (xy 125.875055 -249.750307)
			(xy 125.859345 -249.699377) (xy 125.851402 -249.646673) (xy 125.623076 -249.646673) (xy 125.615133 -249.699377)
			(xy 125.599423 -249.750307) (xy 125.576297 -249.798328) (xy 125.546273 -249.842365) (xy 125.510021 -249.881436)
			(xy 125.46835 -249.914667) (xy 125.422192 -249.941316) (xy 125.372578 -249.960788) (xy 125.320616 -249.972648)
			(xy 125.267466 -249.976632) (xy 125.214316 -249.972648) (xy 125.162354 -249.960788) (xy 125.11274 -249.941316)
			(xy 125.066582 -249.914667) (xy 125.024911 -249.881436) (xy 124.988659 -249.842365) (xy 124.958635 -249.798328)
			(xy 124.935509 -249.750307) (xy 124.919799 -249.699377) (xy 124.911856 -249.646673) (xy 124.683022 -249.646673)
			(xy 124.675079 -249.699377) (xy 124.659369 -249.750307) (xy 124.636243 -249.798328) (xy 124.606219 -249.842365)
			(xy 124.569967 -249.881436) (xy 124.528296 -249.914667) (xy 124.482138 -249.941316) (xy 124.432524 -249.960788)
			(xy 124.380562 -249.972648) (xy 124.327412 -249.976632) (xy 124.274262 -249.972648) (xy 124.2223 -249.960788)
			(xy 124.172686 -249.941316) (xy 124.126528 -249.914667) (xy 124.084857 -249.881436) (xy 124.048605 -249.842365)
			(xy 124.018581 -249.798328) (xy 123.995455 -249.750307) (xy 123.979745 -249.699377) (xy 123.971802 -249.646673)
			(xy 123.743222 -249.646673) (xy 123.735279 -249.699377) (xy 123.719569 -249.750307) (xy 123.696443 -249.798328)
			(xy 123.666419 -249.842365) (xy 123.630167 -249.881436) (xy 123.588496 -249.914667) (xy 123.542338 -249.941316)
			(xy 123.492724 -249.960788) (xy 123.440762 -249.972648) (xy 123.387612 -249.976632) (xy 123.334462 -249.972648)
			(xy 123.2825 -249.960788) (xy 123.232886 -249.941316) (xy 123.186728 -249.914667) (xy 123.145057 -249.881436)
			(xy 123.108805 -249.842365) (xy 123.078781 -249.798328) (xy 123.055655 -249.750307) (xy 123.039945 -249.699377)
			(xy 123.032002 -249.646673) (xy 122.803422 -249.646673) (xy 122.795479 -249.699377) (xy 122.779769 -249.750307)
			(xy 122.756643 -249.798328) (xy 122.726619 -249.842365) (xy 122.690367 -249.881436) (xy 122.648696 -249.914667)
			(xy 122.602538 -249.941316) (xy 122.552924 -249.960788) (xy 122.500962 -249.972648) (xy 122.447812 -249.976632)
			(xy 122.394662 -249.972648) (xy 122.3427 -249.960788) (xy 122.293086 -249.941316) (xy 122.246928 -249.914667)
			(xy 122.205257 -249.881436) (xy 122.169005 -249.842365) (xy 122.138981 -249.798328) (xy 122.115855 -249.750307)
			(xy 122.100145 -249.699377) (xy 122.092202 -249.646673) (xy 121.8627 -249.646673) (xy 121.859015 -249.682911)
			(xy 121.845441 -249.735338) (xy 121.824085 -249.785105) (xy 121.795439 -249.831064) (xy 121.760164 -249.872156)
			(xy 121.719074 -249.907432) (xy 121.673116 -249.936079) (xy 121.62335 -249.957437) (xy 121.570923 -249.971013)
			(xy 121.517046 -249.976493) (xy 121.46296 -249.973752) (xy 121.409912 -249.962853) (xy 121.359127 -249.944046)
			(xy 121.311775 -249.917767) (xy 121.268948 -249.88462) (xy 121.231635 -249.84537) (xy 121.200695 -249.800923)
			(xy 121.176843 -249.752303) (xy 121.160627 -249.700632) (xy 121.152423 -249.647102) (xy 121.151904 -249.620024)
			(xy 121.151996 -249.608369) (xy 121.15352 -249.585109) (xy 121.154952 -249.573542) (xy 121.156282 -249.560206)
			(xy 121.15272 -249.533653) (xy 121.142378 -249.508938) (xy 121.125967 -249.487761) (xy 121.104616 -249.471578)
			(xy 121.079793 -249.4615) (xy 121.053203 -249.458221) (xy 121.03989 -249.45975) (xy 121.030238 -249.46102)
			(xy 120.98528 -249.4661) (xy 120.98528 -250.498356) (xy 121.028714 -250.504706) (xy 121.056507 -250.509376)
			(xy 121.110249 -250.526333) (xy 121.16065 -250.551544) (xy 121.20645 -250.58438) (xy 121.246506 -250.62402)
			(xy 121.279817 -250.669475) (xy 121.305553 -250.71961) (xy 121.32307 -250.773173) (xy 121.33193 -250.828827)
			(xy 121.332498 -250.857004) (xy 121.332078 -250.881673) (xy 121.325266 -250.930539) (xy 121.311774 -250.977996)
			(xy 121.291859 -251.023137) (xy 121.265903 -251.065096) (xy 121.250456 -251.084334) (xy 121.241831 -251.095464)
			(xy 121.230486 -251.121224) (xy 121.226607 -251.149103) (xy 121.230488 -251.176982) (xy 121.241834 -251.202741)
			(xy 121.250456 -251.213874) (xy 121.265891 -251.233122) (xy 121.291861 -251.275073) (xy 121.311784 -251.32021)
			(xy 121.325277 -251.367668) (xy 121.332082 -251.416535) (xy 121.332498 -251.441204) (xy 121.331963 -251.469382)
			(xy 121.323088 -251.525034) (xy 121.305561 -251.578595) (xy 121.279819 -251.628727) (xy 121.246504 -251.674181)
			(xy 121.206447 -251.713821) (xy 121.160648 -251.74666) (xy 121.11025 -251.771878) (xy 121.056509 -251.788845)
			(xy 121.028714 -251.793502) (xy 120.98528 -251.799852) (xy 120.98528 -252.250956) (xy 121.028714 -252.257306)
			(xy 121.056507 -252.261976) (xy 121.110249 -252.278933) (xy 121.16065 -252.304144) (xy 121.20645 -252.33698)
			(xy 121.246506 -252.37662) (xy 121.279817 -252.422075) (xy 121.305553 -252.47221) (xy 121.32307 -252.525773)
			(xy 121.33193 -252.581427) (xy 121.332498 -252.609604) (xy 121.332078 -252.634273) (xy 121.325266 -252.683139)
			(xy 121.311774 -252.730596) (xy 121.291859 -252.775737) (xy 121.265903 -252.817696) (xy 121.250456 -252.836934)
			(xy 121.241831 -252.848064) (xy 121.230486 -252.873824) (xy 121.226607 -252.901703) (xy 121.230488 -252.929582)
			(xy 121.241834 -252.955341) (xy 121.250456 -252.966474) (xy 121.265891 -252.985722) (xy 121.291861 -253.027673)
			(xy 121.311784 -253.07281) (xy 121.325277 -253.120268) (xy 121.332082 -253.169135) (xy 121.332498 -253.193804)
			(xy 121.331963 -253.221982) (xy 121.323088 -253.277634) (xy 121.305561 -253.331195) (xy 121.279819 -253.381327)
			(xy 121.246504 -253.426781) (xy 121.206447 -253.466421) (xy 121.160648 -253.49926) (xy 121.11025 -253.524478)
			(xy 121.056509 -253.541445) (xy 121.028714 -253.546102) (xy 120.98528 -253.552452) (xy 120.98528 -253.946385)
			(xy 121.732538 -253.946385) (xy 121.732538 -253.893087) (xy 121.740481 -253.840383) (xy 121.756191 -253.789453)
			(xy 121.779317 -253.741432) (xy 121.809341 -253.697395) (xy 121.845593 -253.658324) (xy 121.887264 -253.625093)
			(xy 121.933422 -253.598444) (xy 121.983036 -253.578972) (xy 122.034998 -253.567112) (xy 122.088148 -253.563129)
			(xy 122.141298 -253.567112) (xy 122.19326 -253.578972) (xy 122.242874 -253.598444) (xy 122.289032 -253.625093)
			(xy 122.330703 -253.658324) (xy 122.366955 -253.697395) (xy 122.396979 -253.741432) (xy 122.420105 -253.789453)
			(xy 122.435815 -253.840383) (xy 122.443758 -253.893087) (xy 122.444256 -253.919736) (xy 122.443758 -253.946385)
			(xy 122.672084 -253.946385) (xy 122.672084 -253.893087) (xy 122.680027 -253.840383) (xy 122.695737 -253.789453)
			(xy 122.718863 -253.741432) (xy 122.748887 -253.697395) (xy 122.785139 -253.658324) (xy 122.82681 -253.625093)
			(xy 122.872968 -253.598444) (xy 122.922582 -253.578972) (xy 122.974544 -253.567112) (xy 123.027694 -253.563129)
			(xy 123.080844 -253.567112) (xy 123.132806 -253.578972) (xy 123.18242 -253.598444) (xy 123.228578 -253.625093)
			(xy 123.270249 -253.658324) (xy 123.306501 -253.697395) (xy 123.336525 -253.741432) (xy 123.359651 -253.789453)
			(xy 123.375361 -253.840383) (xy 123.383304 -253.893087) (xy 123.383802 -253.919736) (xy 123.383304 -253.946385)
			(xy 123.612138 -253.946385) (xy 123.612138 -253.893087) (xy 123.620081 -253.840383) (xy 123.635791 -253.789453)
			(xy 123.658917 -253.741432) (xy 123.688941 -253.697395) (xy 123.725193 -253.658324) (xy 123.766864 -253.625093)
			(xy 123.813022 -253.598444) (xy 123.862636 -253.578972) (xy 123.914598 -253.567112) (xy 123.967748 -253.563129)
			(xy 124.020898 -253.567112) (xy 124.07286 -253.578972) (xy 124.122474 -253.598444) (xy 124.168632 -253.625093)
			(xy 124.210303 -253.658324) (xy 124.246555 -253.697395) (xy 124.276579 -253.741432) (xy 124.299705 -253.789453)
			(xy 124.315415 -253.840383) (xy 124.323358 -253.893087) (xy 124.323856 -253.919736) (xy 124.323358 -253.946385)
			(xy 124.551938 -253.946385) (xy 124.551938 -253.893087) (xy 124.559881 -253.840383) (xy 124.575591 -253.789453)
			(xy 124.598717 -253.741432) (xy 124.628741 -253.697395) (xy 124.664993 -253.658324) (xy 124.706664 -253.625093)
			(xy 124.752822 -253.598444) (xy 124.802436 -253.578972) (xy 124.854398 -253.567112) (xy 124.907548 -253.563129)
			(xy 124.960698 -253.567112) (xy 125.01266 -253.578972) (xy 125.062274 -253.598444) (xy 125.108432 -253.625093)
			(xy 125.150103 -253.658324) (xy 125.186355 -253.697395) (xy 125.216379 -253.741432) (xy 125.239505 -253.789453)
			(xy 125.255215 -253.840383) (xy 125.263158 -253.893087) (xy 125.263656 -253.919736) (xy 125.263158 -253.946385)
			(xy 125.491738 -253.946385) (xy 125.491738 -253.893087) (xy 125.499681 -253.840383) (xy 125.515391 -253.789453)
			(xy 125.538517 -253.741432) (xy 125.568541 -253.697395) (xy 125.604793 -253.658324) (xy 125.646464 -253.625093)
			(xy 125.692622 -253.598444) (xy 125.742236 -253.578972) (xy 125.794198 -253.567112) (xy 125.847348 -253.563129)
			(xy 125.900498 -253.567112) (xy 125.95246 -253.578972) (xy 126.002074 -253.598444) (xy 126.048232 -253.625093)
			(xy 126.089903 -253.658324) (xy 126.126155 -253.697395) (xy 126.156179 -253.741432) (xy 126.179305 -253.789453)
			(xy 126.195015 -253.840383) (xy 126.202958 -253.893087) (xy 126.203456 -253.919736) (xy 126.202958 -253.946385)
			(xy 126.431538 -253.946385) (xy 126.431538 -253.893087) (xy 126.439481 -253.840383) (xy 126.455191 -253.789453)
			(xy 126.478317 -253.741432) (xy 126.508341 -253.697395) (xy 126.544593 -253.658324) (xy 126.586264 -253.625093)
			(xy 126.632422 -253.598444) (xy 126.682036 -253.578972) (xy 126.733998 -253.567112) (xy 126.787148 -253.563129)
			(xy 126.840298 -253.567112) (xy 126.89226 -253.578972) (xy 126.941874 -253.598444) (xy 126.988032 -253.625093)
			(xy 127.029703 -253.658324) (xy 127.065955 -253.697395) (xy 127.095979 -253.741432) (xy 127.119105 -253.789453)
			(xy 127.134815 -253.840383) (xy 127.142758 -253.893087) (xy 127.143256 -253.919736) (xy 127.142758 -253.946385)
			(xy 127.371338 -253.946385) (xy 127.371338 -253.893087) (xy 127.379281 -253.840383) (xy 127.394991 -253.789453)
			(xy 127.418117 -253.741432) (xy 127.448141 -253.697395) (xy 127.484393 -253.658324) (xy 127.526064 -253.625093)
			(xy 127.572222 -253.598444) (xy 127.621836 -253.578972) (xy 127.673798 -253.567112) (xy 127.726948 -253.563129)
			(xy 127.780098 -253.567112) (xy 127.83206 -253.578972) (xy 127.881674 -253.598444) (xy 127.927832 -253.625093)
			(xy 127.969503 -253.658324) (xy 128.005755 -253.697395) (xy 128.035779 -253.741432) (xy 128.058905 -253.789453)
			(xy 128.074615 -253.840383) (xy 128.082558 -253.893087) (xy 128.083056 -253.919736) (xy 128.082558 -253.946385)
			(xy 128.310884 -253.946385) (xy 128.310884 -253.893087) (xy 128.318827 -253.840383) (xy 128.334537 -253.789453)
			(xy 128.357663 -253.741432) (xy 128.387687 -253.697395) (xy 128.423939 -253.658324) (xy 128.46561 -253.625093)
			(xy 128.511768 -253.598444) (xy 128.561382 -253.578972) (xy 128.613344 -253.567112) (xy 128.666494 -253.563129)
			(xy 128.719644 -253.567112) (xy 128.771606 -253.578972) (xy 128.82122 -253.598444) (xy 128.867378 -253.625093)
			(xy 128.909049 -253.658324) (xy 128.945301 -253.697395) (xy 128.975325 -253.741432) (xy 128.998451 -253.789453)
			(xy 129.014161 -253.840383) (xy 129.022104 -253.893087) (xy 129.022602 -253.919736) (xy 129.022104 -253.946385)
			(xy 129.250684 -253.946385) (xy 129.250684 -253.893087) (xy 129.258627 -253.840383) (xy 129.274337 -253.789453)
			(xy 129.297463 -253.741432) (xy 129.327487 -253.697395) (xy 129.363739 -253.658324) (xy 129.40541 -253.625093)
			(xy 129.451568 -253.598444) (xy 129.501182 -253.578972) (xy 129.553144 -253.567112) (xy 129.606294 -253.563129)
			(xy 129.659444 -253.567112) (xy 129.711406 -253.578972) (xy 129.76102 -253.598444) (xy 129.807178 -253.625093)
			(xy 129.848849 -253.658324) (xy 129.885101 -253.697395) (xy 129.915125 -253.741432) (xy 129.938251 -253.789453)
			(xy 129.953961 -253.840383) (xy 129.961904 -253.893087) (xy 129.962402 -253.919736) (xy 129.961904 -253.946385)
			(xy 130.190738 -253.946385) (xy 130.190738 -253.893087) (xy 130.198681 -253.840383) (xy 130.214391 -253.789453)
			(xy 130.237517 -253.741432) (xy 130.267541 -253.697395) (xy 130.303793 -253.658324) (xy 130.345464 -253.625093)
			(xy 130.391622 -253.598444) (xy 130.441236 -253.578972) (xy 130.493198 -253.567112) (xy 130.546348 -253.563129)
			(xy 130.599498 -253.567112) (xy 130.65146 -253.578972) (xy 130.701074 -253.598444) (xy 130.747232 -253.625093)
			(xy 130.788903 -253.658324) (xy 130.825155 -253.697395) (xy 130.855179 -253.741432) (xy 130.878305 -253.789453)
			(xy 130.894015 -253.840383) (xy 130.901958 -253.893087) (xy 130.902456 -253.919736) (xy 130.901958 -253.946385)
			(xy 131.130284 -253.946385) (xy 131.130284 -253.893087) (xy 131.138227 -253.840383) (xy 131.153937 -253.789453)
			(xy 131.177063 -253.741432) (xy 131.207087 -253.697395) (xy 131.243339 -253.658324) (xy 131.28501 -253.625093)
			(xy 131.331168 -253.598444) (xy 131.380782 -253.578972) (xy 131.432744 -253.567112) (xy 131.485894 -253.563129)
			(xy 131.539044 -253.567112) (xy 131.591006 -253.578972) (xy 131.64062 -253.598444) (xy 131.686778 -253.625093)
			(xy 131.728449 -253.658324) (xy 131.764701 -253.697395) (xy 131.794725 -253.741432) (xy 131.817851 -253.789453)
			(xy 131.833561 -253.840383) (xy 131.841504 -253.893087) (xy 131.842002 -253.919736) (xy 131.841504 -253.946385)
			(xy 132.070084 -253.946385) (xy 132.070084 -253.893087) (xy 132.078027 -253.840383) (xy 132.093737 -253.789453)
			(xy 132.116863 -253.741432) (xy 132.146887 -253.697395) (xy 132.183139 -253.658324) (xy 132.22481 -253.625093)
			(xy 132.270968 -253.598444) (xy 132.320582 -253.578972) (xy 132.372544 -253.567112) (xy 132.425694 -253.563129)
			(xy 132.478844 -253.567112) (xy 132.530806 -253.578972) (xy 132.58042 -253.598444) (xy 132.626578 -253.625093)
			(xy 132.668249 -253.658324) (xy 132.704501 -253.697395) (xy 132.734525 -253.741432) (xy 132.757651 -253.789453)
			(xy 132.773361 -253.840383) (xy 132.781304 -253.893087) (xy 132.781802 -253.919736) (xy 132.781304 -253.946385)
			(xy 133.010138 -253.946385) (xy 133.010138 -253.893087) (xy 133.018081 -253.840383) (xy 133.033791 -253.789453)
			(xy 133.056917 -253.741432) (xy 133.086941 -253.697395) (xy 133.123193 -253.658324) (xy 133.164864 -253.625093)
			(xy 133.211022 -253.598444) (xy 133.260636 -253.578972) (xy 133.312598 -253.567112) (xy 133.365748 -253.563129)
			(xy 133.418898 -253.567112) (xy 133.47086 -253.578972) (xy 133.520474 -253.598444) (xy 133.566632 -253.625093)
			(xy 133.608303 -253.658324) (xy 133.644555 -253.697395) (xy 133.674579 -253.741432) (xy 133.697705 -253.789453)
			(xy 133.713415 -253.840383) (xy 133.721358 -253.893087) (xy 133.721856 -253.919736) (xy 133.721358 -253.946385)
			(xy 133.949938 -253.946385) (xy 133.949938 -253.893087) (xy 133.957881 -253.840383) (xy 133.973591 -253.789453)
			(xy 133.996717 -253.741432) (xy 134.026741 -253.697395) (xy 134.062993 -253.658324) (xy 134.104664 -253.625093)
			(xy 134.150822 -253.598444) (xy 134.200436 -253.578972) (xy 134.252398 -253.567112) (xy 134.305548 -253.563129)
			(xy 134.358698 -253.567112) (xy 134.41066 -253.578972) (xy 134.460274 -253.598444) (xy 134.506432 -253.625093)
			(xy 134.548103 -253.658324) (xy 134.584355 -253.697395) (xy 134.614379 -253.741432) (xy 134.637505 -253.789453)
			(xy 134.653215 -253.840383) (xy 134.661158 -253.893087) (xy 134.661656 -253.919736) (xy 134.661158 -253.946385)
			(xy 134.653215 -253.999089) (xy 134.637505 -254.050019) (xy 134.614379 -254.09804) (xy 134.584355 -254.142077)
			(xy 134.548103 -254.181148) (xy 134.506432 -254.214379) (xy 134.460274 -254.241028) (xy 134.41066 -254.2605)
			(xy 134.358698 -254.27236) (xy 134.305548 -254.276344) (xy 134.252398 -254.27236) (xy 134.200436 -254.2605)
			(xy 134.150822 -254.241028) (xy 134.104664 -254.214379) (xy 134.062993 -254.181148) (xy 134.026741 -254.142077)
			(xy 133.996717 -254.09804) (xy 133.973591 -254.050019) (xy 133.957881 -253.999089) (xy 133.949938 -253.946385)
			(xy 133.721358 -253.946385) (xy 133.713415 -253.999089) (xy 133.697705 -254.050019) (xy 133.674579 -254.09804)
			(xy 133.644555 -254.142077) (xy 133.608303 -254.181148) (xy 133.566632 -254.214379) (xy 133.520474 -254.241028)
			(xy 133.47086 -254.2605) (xy 133.418898 -254.27236) (xy 133.365748 -254.276344) (xy 133.312598 -254.27236)
			(xy 133.260636 -254.2605) (xy 133.211022 -254.241028) (xy 133.164864 -254.214379) (xy 133.123193 -254.181148)
			(xy 133.086941 -254.142077) (xy 133.056917 -254.09804) (xy 133.033791 -254.050019) (xy 133.018081 -253.999089)
			(xy 133.010138 -253.946385) (xy 132.781304 -253.946385) (xy 132.773361 -253.999089) (xy 132.757651 -254.050019)
			(xy 132.734525 -254.09804) (xy 132.704501 -254.142077) (xy 132.668249 -254.181148) (xy 132.626578 -254.214379)
			(xy 132.58042 -254.241028) (xy 132.530806 -254.2605) (xy 132.478844 -254.27236) (xy 132.425694 -254.276344)
			(xy 132.372544 -254.27236) (xy 132.320582 -254.2605) (xy 132.270968 -254.241028) (xy 132.22481 -254.214379)
			(xy 132.183139 -254.181148) (xy 132.146887 -254.142077) (xy 132.116863 -254.09804) (xy 132.093737 -254.050019)
			(xy 132.078027 -253.999089) (xy 132.070084 -253.946385) (xy 131.841504 -253.946385) (xy 131.833561 -253.999089)
			(xy 131.817851 -254.050019) (xy 131.794725 -254.09804) (xy 131.764701 -254.142077) (xy 131.728449 -254.181148)
			(xy 131.686778 -254.214379) (xy 131.64062 -254.241028) (xy 131.591006 -254.2605) (xy 131.539044 -254.27236)
			(xy 131.485894 -254.276344) (xy 131.432744 -254.27236) (xy 131.380782 -254.2605) (xy 131.331168 -254.241028)
			(xy 131.28501 -254.214379) (xy 131.243339 -254.181148) (xy 131.207087 -254.142077) (xy 131.177063 -254.09804)
			(xy 131.153937 -254.050019) (xy 131.138227 -253.999089) (xy 131.130284 -253.946385) (xy 130.901958 -253.946385)
			(xy 130.894015 -253.999089) (xy 130.878305 -254.050019) (xy 130.855179 -254.09804) (xy 130.825155 -254.142077)
			(xy 130.788903 -254.181148) (xy 130.747232 -254.214379) (xy 130.701074 -254.241028) (xy 130.65146 -254.2605)
			(xy 130.599498 -254.27236) (xy 130.546348 -254.276344) (xy 130.493198 -254.27236) (xy 130.441236 -254.2605)
			(xy 130.391622 -254.241028) (xy 130.345464 -254.214379) (xy 130.303793 -254.181148) (xy 130.267541 -254.142077)
			(xy 130.237517 -254.09804) (xy 130.214391 -254.050019) (xy 130.198681 -253.999089) (xy 130.190738 -253.946385)
			(xy 129.961904 -253.946385) (xy 129.953961 -253.999089) (xy 129.938251 -254.050019) (xy 129.915125 -254.09804)
			(xy 129.885101 -254.142077) (xy 129.848849 -254.181148) (xy 129.807178 -254.214379) (xy 129.76102 -254.241028)
			(xy 129.711406 -254.2605) (xy 129.659444 -254.27236) (xy 129.606294 -254.276344) (xy 129.553144 -254.27236)
			(xy 129.501182 -254.2605) (xy 129.451568 -254.241028) (xy 129.40541 -254.214379) (xy 129.363739 -254.181148)
			(xy 129.327487 -254.142077) (xy 129.297463 -254.09804) (xy 129.274337 -254.050019) (xy 129.258627 -253.999089)
			(xy 129.250684 -253.946385) (xy 129.022104 -253.946385) (xy 129.014161 -253.999089) (xy 128.998451 -254.050019)
			(xy 128.975325 -254.09804) (xy 128.945301 -254.142077) (xy 128.909049 -254.181148) (xy 128.867378 -254.214379)
			(xy 128.82122 -254.241028) (xy 128.771606 -254.2605) (xy 128.719644 -254.27236) (xy 128.666494 -254.276344)
			(xy 128.613344 -254.27236) (xy 128.561382 -254.2605) (xy 128.511768 -254.241028) (xy 128.46561 -254.214379)
			(xy 128.423939 -254.181148) (xy 128.387687 -254.142077) (xy 128.357663 -254.09804) (xy 128.334537 -254.050019)
			(xy 128.318827 -253.999089) (xy 128.310884 -253.946385) (xy 128.082558 -253.946385) (xy 128.074615 -253.999089)
			(xy 128.058905 -254.050019) (xy 128.035779 -254.09804) (xy 128.005755 -254.142077) (xy 127.969503 -254.181148)
			(xy 127.927832 -254.214379) (xy 127.881674 -254.241028) (xy 127.83206 -254.2605) (xy 127.780098 -254.27236)
			(xy 127.726948 -254.276344) (xy 127.673798 -254.27236) (xy 127.621836 -254.2605) (xy 127.572222 -254.241028)
			(xy 127.526064 -254.214379) (xy 127.484393 -254.181148) (xy 127.448141 -254.142077) (xy 127.418117 -254.09804)
			(xy 127.394991 -254.050019) (xy 127.379281 -253.999089) (xy 127.371338 -253.946385) (xy 127.142758 -253.946385)
			(xy 127.134815 -253.999089) (xy 127.119105 -254.050019) (xy 127.095979 -254.09804) (xy 127.065955 -254.142077)
			(xy 127.029703 -254.181148) (xy 126.988032 -254.214379) (xy 126.941874 -254.241028) (xy 126.89226 -254.2605)
			(xy 126.840298 -254.27236) (xy 126.787148 -254.276344) (xy 126.733998 -254.27236) (xy 126.682036 -254.2605)
			(xy 126.632422 -254.241028) (xy 126.586264 -254.214379) (xy 126.544593 -254.181148) (xy 126.508341 -254.142077)
			(xy 126.478317 -254.09804) (xy 126.455191 -254.050019) (xy 126.439481 -253.999089) (xy 126.431538 -253.946385)
			(xy 126.202958 -253.946385) (xy 126.195015 -253.999089) (xy 126.179305 -254.050019) (xy 126.156179 -254.09804)
			(xy 126.126155 -254.142077) (xy 126.089903 -254.181148) (xy 126.048232 -254.214379) (xy 126.002074 -254.241028)
			(xy 125.95246 -254.2605) (xy 125.900498 -254.27236) (xy 125.847348 -254.276344) (xy 125.794198 -254.27236)
			(xy 125.742236 -254.2605) (xy 125.692622 -254.241028) (xy 125.646464 -254.214379) (xy 125.604793 -254.181148)
			(xy 125.568541 -254.142077) (xy 125.538517 -254.09804) (xy 125.515391 -254.050019) (xy 125.499681 -253.999089)
			(xy 125.491738 -253.946385) (xy 125.263158 -253.946385) (xy 125.255215 -253.999089) (xy 125.239505 -254.050019)
			(xy 125.216379 -254.09804) (xy 125.186355 -254.142077) (xy 125.150103 -254.181148) (xy 125.108432 -254.214379)
			(xy 125.062274 -254.241028) (xy 125.01266 -254.2605) (xy 124.960698 -254.27236) (xy 124.907548 -254.276344)
			(xy 124.854398 -254.27236) (xy 124.802436 -254.2605) (xy 124.752822 -254.241028) (xy 124.706664 -254.214379)
			(xy 124.664993 -254.181148) (xy 124.628741 -254.142077) (xy 124.598717 -254.09804) (xy 124.575591 -254.050019)
			(xy 124.559881 -253.999089) (xy 124.551938 -253.946385) (xy 124.323358 -253.946385) (xy 124.315415 -253.999089)
			(xy 124.299705 -254.050019) (xy 124.276579 -254.09804) (xy 124.246555 -254.142077) (xy 124.210303 -254.181148)
			(xy 124.168632 -254.214379) (xy 124.122474 -254.241028) (xy 124.07286 -254.2605) (xy 124.020898 -254.27236)
			(xy 123.967748 -254.276344) (xy 123.914598 -254.27236) (xy 123.862636 -254.2605) (xy 123.813022 -254.241028)
			(xy 123.766864 -254.214379) (xy 123.725193 -254.181148) (xy 123.688941 -254.142077) (xy 123.658917 -254.09804)
			(xy 123.635791 -254.050019) (xy 123.620081 -253.999089) (xy 123.612138 -253.946385) (xy 123.383304 -253.946385)
			(xy 123.375361 -253.999089) (xy 123.359651 -254.050019) (xy 123.336525 -254.09804) (xy 123.306501 -254.142077)
			(xy 123.270249 -254.181148) (xy 123.228578 -254.214379) (xy 123.18242 -254.241028) (xy 123.132806 -254.2605)
			(xy 123.080844 -254.27236) (xy 123.027694 -254.276344) (xy 122.974544 -254.27236) (xy 122.922582 -254.2605)
			(xy 122.872968 -254.241028) (xy 122.82681 -254.214379) (xy 122.785139 -254.181148) (xy 122.748887 -254.142077)
			(xy 122.718863 -254.09804) (xy 122.695737 -254.050019) (xy 122.680027 -253.999089) (xy 122.672084 -253.946385)
			(xy 122.443758 -253.946385) (xy 122.435815 -253.999089) (xy 122.420105 -254.050019) (xy 122.396979 -254.09804)
			(xy 122.366955 -254.142077) (xy 122.330703 -254.181148) (xy 122.289032 -254.214379) (xy 122.242874 -254.241028)
			(xy 122.19326 -254.2605) (xy 122.141298 -254.27236) (xy 122.088148 -254.276344) (xy 122.034998 -254.27236)
			(xy 121.983036 -254.2605) (xy 121.933422 -254.241028) (xy 121.887264 -254.214379) (xy 121.845593 -254.181148)
			(xy 121.809341 -254.142077) (xy 121.779317 -254.09804) (xy 121.756191 -254.050019) (xy 121.740481 -253.999089)
			(xy 121.732538 -253.946385) (xy 120.98528 -253.946385) (xy 120.98528 -254.587756) (xy 121.028714 -254.594106)
			(xy 121.060607 -254.599581) (xy 121.121821 -254.620545) (xy 121.15038 -254.635762) (xy 121.1629 -254.642274)
			(xy 121.190337 -254.648831) (xy 121.218521 -254.647622) (xy 121.245296 -254.638739) (xy 121.268614 -254.622862)
			(xy 121.286691 -254.601205) (xy 121.292874 -254.588518) (xy 121.303707 -254.565282) (xy 121.331063 -254.521923)
			(xy 121.364358 -254.48294) (xy 121.402904 -254.449139) (xy 121.445903 -254.421221) (xy 121.492464 -254.399764)
			(xy 121.541622 -254.385212) (xy 121.59236 -254.377867) (xy 121.617994 -254.377444) (xy 121.644649 -254.377917)
			(xy 121.697364 -254.385862) (xy 121.748306 -254.401574) (xy 121.796337 -254.424704) (xy 121.840384 -254.454734)
			(xy 121.879463 -254.490994) (xy 121.912702 -254.532673) (xy 121.939357 -254.578841) (xy 121.958833 -254.628466)
			(xy 121.970696 -254.680439) (xy 121.97468 -254.7336) (xy 121.972686 -254.760201) (xy 122.202184 -254.760201)
			(xy 122.202184 -254.706903) (xy 122.210127 -254.654199) (xy 122.225837 -254.603269) (xy 122.248963 -254.555248)
			(xy 122.278987 -254.511211) (xy 122.315239 -254.47214) (xy 122.35691 -254.438909) (xy 122.403068 -254.41226)
			(xy 122.452682 -254.392788) (xy 122.504644 -254.380928) (xy 122.557794 -254.376945) (xy 122.610944 -254.380928)
			(xy 122.662906 -254.392788) (xy 122.71252 -254.41226) (xy 122.758678 -254.438909) (xy 122.800349 -254.47214)
			(xy 122.836601 -254.511211) (xy 122.866625 -254.555248) (xy 122.889751 -254.603269) (xy 122.905461 -254.654199)
			(xy 122.913404 -254.706903) (xy 122.913902 -254.733552) (xy 122.913404 -254.760201) (xy 123.141984 -254.760201)
			(xy 123.141984 -254.706903) (xy 123.149927 -254.654199) (xy 123.165637 -254.603269) (xy 123.188763 -254.555248)
			(xy 123.218787 -254.511211) (xy 123.255039 -254.47214) (xy 123.29671 -254.438909) (xy 123.342868 -254.41226)
			(xy 123.392482 -254.392788) (xy 123.444444 -254.380928) (xy 123.497594 -254.376945) (xy 123.550744 -254.380928)
			(xy 123.602706 -254.392788) (xy 123.65232 -254.41226) (xy 123.698478 -254.438909) (xy 123.740149 -254.47214)
			(xy 123.776401 -254.511211) (xy 123.806425 -254.555248) (xy 123.829551 -254.603269) (xy 123.845261 -254.654199)
			(xy 123.853204 -254.706903) (xy 123.853702 -254.733552) (xy 123.853204 -254.760201) (xy 124.082038 -254.760201)
			(xy 124.082038 -254.706903) (xy 124.089981 -254.654199) (xy 124.105691 -254.603269) (xy 124.128817 -254.555248)
			(xy 124.158841 -254.511211) (xy 124.195093 -254.47214) (xy 124.236764 -254.438909) (xy 124.282922 -254.41226)
			(xy 124.332536 -254.392788) (xy 124.384498 -254.380928) (xy 124.437648 -254.376945) (xy 124.490798 -254.380928)
			(xy 124.54276 -254.392788) (xy 124.592374 -254.41226) (xy 124.638532 -254.438909) (xy 124.680203 -254.47214)
			(xy 124.716455 -254.511211) (xy 124.746479 -254.555248) (xy 124.769605 -254.603269) (xy 124.785315 -254.654199)
			(xy 124.793258 -254.706903) (xy 124.793756 -254.733552) (xy 124.793258 -254.760201) (xy 125.021584 -254.760201)
			(xy 125.021584 -254.706903) (xy 125.029527 -254.654199) (xy 125.045237 -254.603269) (xy 125.068363 -254.555248)
			(xy 125.098387 -254.511211) (xy 125.134639 -254.47214) (xy 125.17631 -254.438909) (xy 125.222468 -254.41226)
			(xy 125.272082 -254.392788) (xy 125.324044 -254.380928) (xy 125.377194 -254.376945) (xy 125.430344 -254.380928)
			(xy 125.482306 -254.392788) (xy 125.53192 -254.41226) (xy 125.578078 -254.438909) (xy 125.619749 -254.47214)
			(xy 125.656001 -254.511211) (xy 125.686025 -254.555248) (xy 125.709151 -254.603269) (xy 125.724861 -254.654199)
			(xy 125.732804 -254.706903) (xy 125.733302 -254.733552) (xy 125.732804 -254.760201) (xy 125.961638 -254.760201)
			(xy 125.961638 -254.706903) (xy 125.969581 -254.654199) (xy 125.985291 -254.603269) (xy 126.008417 -254.555248)
			(xy 126.038441 -254.511211) (xy 126.074693 -254.47214) (xy 126.116364 -254.438909) (xy 126.162522 -254.41226)
			(xy 126.212136 -254.392788) (xy 126.264098 -254.380928) (xy 126.317248 -254.376945) (xy 126.370398 -254.380928)
			(xy 126.42236 -254.392788) (xy 126.471974 -254.41226) (xy 126.518132 -254.438909) (xy 126.559803 -254.47214)
			(xy 126.596055 -254.511211) (xy 126.626079 -254.555248) (xy 126.649205 -254.603269) (xy 126.664915 -254.654199)
			(xy 126.672858 -254.706903) (xy 126.673356 -254.733552) (xy 126.672858 -254.760201) (xy 126.901184 -254.760201)
			(xy 126.901184 -254.706903) (xy 126.909127 -254.654199) (xy 126.924837 -254.603269) (xy 126.947963 -254.555248)
			(xy 126.977987 -254.511211) (xy 127.014239 -254.47214) (xy 127.05591 -254.438909) (xy 127.102068 -254.41226)
			(xy 127.151682 -254.392788) (xy 127.203644 -254.380928) (xy 127.256794 -254.376945) (xy 127.309944 -254.380928)
			(xy 127.361906 -254.392788) (xy 127.41152 -254.41226) (xy 127.457678 -254.438909) (xy 127.499349 -254.47214)
			(xy 127.535601 -254.511211) (xy 127.565625 -254.555248) (xy 127.588751 -254.603269) (xy 127.604461 -254.654199)
			(xy 127.612404 -254.706903) (xy 127.612902 -254.733552) (xy 127.612404 -254.760201) (xy 127.840984 -254.760201)
			(xy 127.840984 -254.706903) (xy 127.848927 -254.654199) (xy 127.864637 -254.603269) (xy 127.887763 -254.555248)
			(xy 127.917787 -254.511211) (xy 127.954039 -254.47214) (xy 127.99571 -254.438909) (xy 128.041868 -254.41226)
			(xy 128.091482 -254.392788) (xy 128.143444 -254.380928) (xy 128.196594 -254.376945) (xy 128.249744 -254.380928)
			(xy 128.301706 -254.392788) (xy 128.35132 -254.41226) (xy 128.397478 -254.438909) (xy 128.439149 -254.47214)
			(xy 128.475401 -254.511211) (xy 128.505425 -254.555248) (xy 128.528551 -254.603269) (xy 128.544261 -254.654199)
			(xy 128.552204 -254.706903) (xy 128.552702 -254.733552) (xy 128.552204 -254.760201) (xy 128.780784 -254.760201)
			(xy 128.780784 -254.706903) (xy 128.788727 -254.654199) (xy 128.804437 -254.603269) (xy 128.827563 -254.555248)
			(xy 128.857587 -254.511211) (xy 128.893839 -254.47214) (xy 128.93551 -254.438909) (xy 128.981668 -254.41226)
			(xy 129.031282 -254.392788) (xy 129.083244 -254.380928) (xy 129.136394 -254.376945) (xy 129.189544 -254.380928)
			(xy 129.241506 -254.392788) (xy 129.29112 -254.41226) (xy 129.337278 -254.438909) (xy 129.378949 -254.47214)
			(xy 129.415201 -254.511211) (xy 129.445225 -254.555248) (xy 129.468351 -254.603269) (xy 129.484061 -254.654199)
			(xy 129.492004 -254.706903) (xy 129.492502 -254.733552) (xy 129.492004 -254.760201) (xy 129.720584 -254.760201)
			(xy 129.720584 -254.706903) (xy 129.728527 -254.654199) (xy 129.744237 -254.603269) (xy 129.767363 -254.555248)
			(xy 129.797387 -254.511211) (xy 129.833639 -254.47214) (xy 129.87531 -254.438909) (xy 129.921468 -254.41226)
			(xy 129.971082 -254.392788) (xy 130.023044 -254.380928) (xy 130.076194 -254.376945) (xy 130.129344 -254.380928)
			(xy 130.181306 -254.392788) (xy 130.23092 -254.41226) (xy 130.277078 -254.438909) (xy 130.318749 -254.47214)
			(xy 130.355001 -254.511211) (xy 130.385025 -254.555248) (xy 130.408151 -254.603269) (xy 130.423861 -254.654199)
			(xy 130.431804 -254.706903) (xy 130.432302 -254.733552) (xy 130.431804 -254.760201) (xy 130.660384 -254.760201)
			(xy 130.660384 -254.706903) (xy 130.668327 -254.654199) (xy 130.684037 -254.603269) (xy 130.707163 -254.555248)
			(xy 130.737187 -254.511211) (xy 130.773439 -254.47214) (xy 130.81511 -254.438909) (xy 130.861268 -254.41226)
			(xy 130.910882 -254.392788) (xy 130.962844 -254.380928) (xy 131.015994 -254.376945) (xy 131.069144 -254.380928)
			(xy 131.121106 -254.392788) (xy 131.17072 -254.41226) (xy 131.216878 -254.438909) (xy 131.258549 -254.47214)
			(xy 131.294801 -254.511211) (xy 131.324825 -254.555248) (xy 131.347951 -254.603269) (xy 131.363661 -254.654199)
			(xy 131.371604 -254.706903) (xy 131.372102 -254.733552) (xy 131.371604 -254.760201) (xy 131.600692 -254.760201)
			(xy 131.600692 -254.706903) (xy 131.608635 -254.654199) (xy 131.624345 -254.603269) (xy 131.647471 -254.555248)
			(xy 131.677495 -254.511211) (xy 131.713747 -254.47214) (xy 131.755418 -254.438909) (xy 131.801576 -254.41226)
			(xy 131.85119 -254.392788) (xy 131.903152 -254.380928) (xy 131.956302 -254.376945) (xy 132.009452 -254.380928)
			(xy 132.061414 -254.392788) (xy 132.111028 -254.41226) (xy 132.157186 -254.438909) (xy 132.198857 -254.47214)
			(xy 132.235109 -254.511211) (xy 132.265133 -254.555248) (xy 132.288259 -254.603269) (xy 132.303969 -254.654199)
			(xy 132.311912 -254.706903) (xy 132.31241 -254.733552) (xy 132.311912 -254.760201) (xy 132.540238 -254.760201)
			(xy 132.540238 -254.706903) (xy 132.548181 -254.654199) (xy 132.563891 -254.603269) (xy 132.587017 -254.555248)
			(xy 132.617041 -254.511211) (xy 132.653293 -254.47214) (xy 132.694964 -254.438909) (xy 132.741122 -254.41226)
			(xy 132.790736 -254.392788) (xy 132.842698 -254.380928) (xy 132.895848 -254.376945) (xy 132.948998 -254.380928)
			(xy 133.00096 -254.392788) (xy 133.050574 -254.41226) (xy 133.096732 -254.438909) (xy 133.138403 -254.47214)
			(xy 133.174655 -254.511211) (xy 133.204679 -254.555248) (xy 133.227805 -254.603269) (xy 133.243515 -254.654199)
			(xy 133.251458 -254.706903) (xy 133.251956 -254.733552) (xy 133.251458 -254.760201) (xy 133.479784 -254.760201)
			(xy 133.479784 -254.706903) (xy 133.487727 -254.654199) (xy 133.503437 -254.603269) (xy 133.526563 -254.555248)
			(xy 133.556587 -254.511211) (xy 133.592839 -254.47214) (xy 133.63451 -254.438909) (xy 133.680668 -254.41226)
			(xy 133.730282 -254.392788) (xy 133.782244 -254.380928) (xy 133.835394 -254.376945) (xy 133.888544 -254.380928)
			(xy 133.940506 -254.392788) (xy 133.99012 -254.41226) (xy 134.036278 -254.438909) (xy 134.077949 -254.47214)
			(xy 134.114201 -254.511211) (xy 134.144225 -254.555248) (xy 134.167351 -254.603269) (xy 134.183061 -254.654199)
			(xy 134.191004 -254.706903) (xy 134.191502 -254.733552) (xy 134.191004 -254.760201) (xy 134.183061 -254.812905)
			(xy 134.167351 -254.863835) (xy 134.144225 -254.911856) (xy 134.114201 -254.955893) (xy 134.077949 -254.994964)
			(xy 134.036278 -255.028195) (xy 133.99012 -255.054844) (xy 133.940506 -255.074316) (xy 133.888544 -255.086176)
			(xy 133.835394 -255.09016) (xy 133.782244 -255.086176) (xy 133.730282 -255.074316) (xy 133.680668 -255.054844)
			(xy 133.63451 -255.028195) (xy 133.592839 -254.994964) (xy 133.556587 -254.955893) (xy 133.526563 -254.911856)
			(xy 133.503437 -254.863835) (xy 133.487727 -254.812905) (xy 133.479784 -254.760201) (xy 133.251458 -254.760201)
			(xy 133.243515 -254.812905) (xy 133.227805 -254.863835) (xy 133.204679 -254.911856) (xy 133.174655 -254.955893)
			(xy 133.138403 -254.994964) (xy 133.096732 -255.028195) (xy 133.050574 -255.054844) (xy 133.00096 -255.074316)
			(xy 132.948998 -255.086176) (xy 132.895848 -255.09016) (xy 132.842698 -255.086176) (xy 132.790736 -255.074316)
			(xy 132.741122 -255.054844) (xy 132.694964 -255.028195) (xy 132.653293 -254.994964) (xy 132.617041 -254.955893)
			(xy 132.587017 -254.911856) (xy 132.563891 -254.863835) (xy 132.548181 -254.812905) (xy 132.540238 -254.760201)
			(xy 132.311912 -254.760201) (xy 132.303969 -254.812905) (xy 132.288259 -254.863835) (xy 132.265133 -254.911856)
			(xy 132.235109 -254.955893) (xy 132.198857 -254.994964) (xy 132.157186 -255.028195) (xy 132.111028 -255.054844)
			(xy 132.061414 -255.074316) (xy 132.009452 -255.086176) (xy 131.956302 -255.09016) (xy 131.903152 -255.086176)
			(xy 131.85119 -255.074316) (xy 131.801576 -255.054844) (xy 131.755418 -255.028195) (xy 131.713747 -254.994964)
			(xy 131.677495 -254.955893) (xy 131.647471 -254.911856) (xy 131.624345 -254.863835) (xy 131.608635 -254.812905)
			(xy 131.600692 -254.760201) (xy 131.371604 -254.760201) (xy 131.363661 -254.812905) (xy 131.347951 -254.863835)
			(xy 131.324825 -254.911856) (xy 131.294801 -254.955893) (xy 131.258549 -254.994964) (xy 131.216878 -255.028195)
			(xy 131.17072 -255.054844) (xy 131.121106 -255.074316) (xy 131.069144 -255.086176) (xy 131.015994 -255.09016)
			(xy 130.962844 -255.086176) (xy 130.910882 -255.074316) (xy 130.861268 -255.054844) (xy 130.81511 -255.028195)
			(xy 130.773439 -254.994964) (xy 130.737187 -254.955893) (xy 130.707163 -254.911856) (xy 130.684037 -254.863835)
			(xy 130.668327 -254.812905) (xy 130.660384 -254.760201) (xy 130.431804 -254.760201) (xy 130.423861 -254.812905)
			(xy 130.408151 -254.863835) (xy 130.385025 -254.911856) (xy 130.355001 -254.955893) (xy 130.318749 -254.994964)
			(xy 130.277078 -255.028195) (xy 130.23092 -255.054844) (xy 130.181306 -255.074316) (xy 130.129344 -255.086176)
			(xy 130.076194 -255.09016) (xy 130.023044 -255.086176) (xy 129.971082 -255.074316) (xy 129.921468 -255.054844)
			(xy 129.87531 -255.028195) (xy 129.833639 -254.994964) (xy 129.797387 -254.955893) (xy 129.767363 -254.911856)
			(xy 129.744237 -254.863835) (xy 129.728527 -254.812905) (xy 129.720584 -254.760201) (xy 129.492004 -254.760201)
			(xy 129.484061 -254.812905) (xy 129.468351 -254.863835) (xy 129.445225 -254.911856) (xy 129.415201 -254.955893)
			(xy 129.378949 -254.994964) (xy 129.337278 -255.028195) (xy 129.29112 -255.054844) (xy 129.241506 -255.074316)
			(xy 129.189544 -255.086176) (xy 129.136394 -255.09016) (xy 129.083244 -255.086176) (xy 129.031282 -255.074316)
			(xy 128.981668 -255.054844) (xy 128.93551 -255.028195) (xy 128.893839 -254.994964) (xy 128.857587 -254.955893)
			(xy 128.827563 -254.911856) (xy 128.804437 -254.863835) (xy 128.788727 -254.812905) (xy 128.780784 -254.760201)
			(xy 128.552204 -254.760201) (xy 128.544261 -254.812905) (xy 128.528551 -254.863835) (xy 128.505425 -254.911856)
			(xy 128.475401 -254.955893) (xy 128.439149 -254.994964) (xy 128.397478 -255.028195) (xy 128.35132 -255.054844)
			(xy 128.301706 -255.074316) (xy 128.249744 -255.086176) (xy 128.196594 -255.09016) (xy 128.143444 -255.086176)
			(xy 128.091482 -255.074316) (xy 128.041868 -255.054844) (xy 127.99571 -255.028195) (xy 127.954039 -254.994964)
			(xy 127.917787 -254.955893) (xy 127.887763 -254.911856) (xy 127.864637 -254.863835) (xy 127.848927 -254.812905)
			(xy 127.840984 -254.760201) (xy 127.612404 -254.760201) (xy 127.604461 -254.812905) (xy 127.588751 -254.863835)
			(xy 127.565625 -254.911856) (xy 127.535601 -254.955893) (xy 127.499349 -254.994964) (xy 127.457678 -255.028195)
			(xy 127.41152 -255.054844) (xy 127.361906 -255.074316) (xy 127.309944 -255.086176) (xy 127.256794 -255.09016)
			(xy 127.203644 -255.086176) (xy 127.151682 -255.074316) (xy 127.102068 -255.054844) (xy 127.05591 -255.028195)
			(xy 127.014239 -254.994964) (xy 126.977987 -254.955893) (xy 126.947963 -254.911856) (xy 126.924837 -254.863835)
			(xy 126.909127 -254.812905) (xy 126.901184 -254.760201) (xy 126.672858 -254.760201) (xy 126.664915 -254.812905)
			(xy 126.649205 -254.863835) (xy 126.626079 -254.911856) (xy 126.596055 -254.955893) (xy 126.559803 -254.994964)
			(xy 126.518132 -255.028195) (xy 126.471974 -255.054844) (xy 126.42236 -255.074316) (xy 126.370398 -255.086176)
			(xy 126.317248 -255.09016) (xy 126.264098 -255.086176) (xy 126.212136 -255.074316) (xy 126.162522 -255.054844)
			(xy 126.116364 -255.028195) (xy 126.074693 -254.994964) (xy 126.038441 -254.955893) (xy 126.008417 -254.911856)
			(xy 125.985291 -254.863835) (xy 125.969581 -254.812905) (xy 125.961638 -254.760201) (xy 125.732804 -254.760201)
			(xy 125.724861 -254.812905) (xy 125.709151 -254.863835) (xy 125.686025 -254.911856) (xy 125.656001 -254.955893)
			(xy 125.619749 -254.994964) (xy 125.578078 -255.028195) (xy 125.53192 -255.054844) (xy 125.482306 -255.074316)
			(xy 125.430344 -255.086176) (xy 125.377194 -255.09016) (xy 125.324044 -255.086176) (xy 125.272082 -255.074316)
			(xy 125.222468 -255.054844) (xy 125.17631 -255.028195) (xy 125.134639 -254.994964) (xy 125.098387 -254.955893)
			(xy 125.068363 -254.911856) (xy 125.045237 -254.863835) (xy 125.029527 -254.812905) (xy 125.021584 -254.760201)
			(xy 124.793258 -254.760201) (xy 124.785315 -254.812905) (xy 124.769605 -254.863835) (xy 124.746479 -254.911856)
			(xy 124.716455 -254.955893) (xy 124.680203 -254.994964) (xy 124.638532 -255.028195) (xy 124.592374 -255.054844)
			(xy 124.54276 -255.074316) (xy 124.490798 -255.086176) (xy 124.437648 -255.09016) (xy 124.384498 -255.086176)
			(xy 124.332536 -255.074316) (xy 124.282922 -255.054844) (xy 124.236764 -255.028195) (xy 124.195093 -254.994964)
			(xy 124.158841 -254.955893) (xy 124.128817 -254.911856) (xy 124.105691 -254.863835) (xy 124.089981 -254.812905)
			(xy 124.082038 -254.760201) (xy 123.853204 -254.760201) (xy 123.845261 -254.812905) (xy 123.829551 -254.863835)
			(xy 123.806425 -254.911856) (xy 123.776401 -254.955893) (xy 123.740149 -254.994964) (xy 123.698478 -255.028195)
			(xy 123.65232 -255.054844) (xy 123.602706 -255.074316) (xy 123.550744 -255.086176) (xy 123.497594 -255.09016)
			(xy 123.444444 -255.086176) (xy 123.392482 -255.074316) (xy 123.342868 -255.054844) (xy 123.29671 -255.028195)
			(xy 123.255039 -254.994964) (xy 123.218787 -254.955893) (xy 123.188763 -254.911856) (xy 123.165637 -254.863835)
			(xy 123.149927 -254.812905) (xy 123.141984 -254.760201) (xy 122.913404 -254.760201) (xy 122.905461 -254.812905)
			(xy 122.889751 -254.863835) (xy 122.866625 -254.911856) (xy 122.836601 -254.955893) (xy 122.800349 -254.994964)
			(xy 122.758678 -255.028195) (xy 122.71252 -255.054844) (xy 122.662906 -255.074316) (xy 122.610944 -255.086176)
			(xy 122.557794 -255.09016) (xy 122.504644 -255.086176) (xy 122.452682 -255.074316) (xy 122.403068 -255.054844)
			(xy 122.35691 -255.028195) (xy 122.315239 -254.994964) (xy 122.278987 -254.955893) (xy 122.248963 -254.911856)
			(xy 122.225837 -254.863835) (xy 122.210127 -254.812905) (xy 122.202184 -254.760201) (xy 121.972686 -254.760201)
			(xy 121.970696 -254.786761) (xy 121.958833 -254.838734) (xy 121.939357 -254.888359) (xy 121.912702 -254.934527)
			(xy 121.879463 -254.976206) (xy 121.840384 -255.012466) (xy 121.796337 -255.042496) (xy 121.748306 -255.065626)
			(xy 121.697364 -255.081338) (xy 121.644649 -255.089283) (xy 121.617994 -255.08966) (xy 121.587672 -255.089052)
			(xy 121.527905 -255.07877) (xy 121.470753 -255.058489) (xy 121.444004 -255.044194) (xy 121.431482 -255.037667)
			(xy 121.404033 -255.031084) (xy 121.375831 -255.032277) (xy 121.349036 -255.041154) (xy 121.325701 -255.057035)
			(xy 121.307612 -255.078705) (xy 121.30151 -255.091438) (xy 121.291275 -255.113479) (xy 121.26566 -255.154776)
			(xy 121.250456 -255.173734) (xy 121.241831 -255.184864) (xy 121.230486 -255.210624) (xy 121.226607 -255.238503)
			(xy 121.230488 -255.266382) (xy 121.241834 -255.292141) (xy 121.250456 -255.303274) (xy 121.265891 -255.322522)
			(xy 121.291861 -255.364473) (xy 121.311784 -255.40961) (xy 121.325277 -255.457068) (xy 121.332082 -255.505935)
			(xy 121.332498 -255.530604) (xy 121.331963 -255.558782) (xy 121.329493 -255.574271) (xy 122.672338 -255.574271)
			(xy 122.672338 -255.520973) (xy 122.680281 -255.468269) (xy 122.695991 -255.417339) (xy 122.719117 -255.369318)
			(xy 122.749141 -255.325281) (xy 122.785393 -255.28621) (xy 122.827064 -255.252979) (xy 122.873222 -255.22633)
			(xy 122.922836 -255.206858) (xy 122.974798 -255.194998) (xy 123.027948 -255.191015) (xy 123.081098 -255.194998)
			(xy 123.13306 -255.206858) (xy 123.182674 -255.22633) (xy 123.228832 -255.252979) (xy 123.270503 -255.28621)
			(xy 123.306755 -255.325281) (xy 123.336779 -255.369318) (xy 123.359905 -255.417339) (xy 123.375615 -255.468269)
			(xy 123.383558 -255.520973) (xy 123.384056 -255.547622) (xy 123.383558 -255.574271) (xy 123.612138 -255.574271)
			(xy 123.612138 -255.520973) (xy 123.620081 -255.468269) (xy 123.635791 -255.417339) (xy 123.658917 -255.369318)
			(xy 123.688941 -255.325281) (xy 123.725193 -255.28621) (xy 123.766864 -255.252979) (xy 123.813022 -255.22633)
			(xy 123.862636 -255.206858) (xy 123.914598 -255.194998) (xy 123.967748 -255.191015) (xy 124.020898 -255.194998)
			(xy 124.07286 -255.206858) (xy 124.122474 -255.22633) (xy 124.168632 -255.252979) (xy 124.210303 -255.28621)
			(xy 124.246555 -255.325281) (xy 124.276579 -255.369318) (xy 124.299705 -255.417339) (xy 124.315415 -255.468269)
			(xy 124.323358 -255.520973) (xy 124.323856 -255.547622) (xy 124.323358 -255.574271) (xy 124.551684 -255.574271)
			(xy 124.551684 -255.520973) (xy 124.559627 -255.468269) (xy 124.575337 -255.417339) (xy 124.598463 -255.369318)
			(xy 124.628487 -255.325281) (xy 124.664739 -255.28621) (xy 124.70641 -255.252979) (xy 124.752568 -255.22633)
			(xy 124.802182 -255.206858) (xy 124.854144 -255.194998) (xy 124.907294 -255.191015) (xy 124.960444 -255.194998)
			(xy 125.012406 -255.206858) (xy 125.06202 -255.22633) (xy 125.108178 -255.252979) (xy 125.149849 -255.28621)
			(xy 125.186101 -255.325281) (xy 125.216125 -255.369318) (xy 125.239251 -255.417339) (xy 125.254961 -255.468269)
			(xy 125.262904 -255.520973) (xy 125.263402 -255.547622) (xy 125.262904 -255.574271) (xy 125.491738 -255.574271)
			(xy 125.491738 -255.520973) (xy 125.499681 -255.468269) (xy 125.515391 -255.417339) (xy 125.538517 -255.369318)
			(xy 125.568541 -255.325281) (xy 125.604793 -255.28621) (xy 125.646464 -255.252979) (xy 125.692622 -255.22633)
			(xy 125.742236 -255.206858) (xy 125.794198 -255.194998) (xy 125.847348 -255.191015) (xy 125.900498 -255.194998)
			(xy 125.95246 -255.206858) (xy 126.002074 -255.22633) (xy 126.048232 -255.252979) (xy 126.089903 -255.28621)
			(xy 126.126155 -255.325281) (xy 126.156179 -255.369318) (xy 126.179305 -255.417339) (xy 126.195015 -255.468269)
			(xy 126.202958 -255.520973) (xy 126.203456 -255.547622) (xy 126.202958 -255.574271) (xy 126.431284 -255.574271)
			(xy 126.431284 -255.520973) (xy 126.439227 -255.468269) (xy 126.454937 -255.417339) (xy 126.478063 -255.369318)
			(xy 126.508087 -255.325281) (xy 126.544339 -255.28621) (xy 126.58601 -255.252979) (xy 126.632168 -255.22633)
			(xy 126.681782 -255.206858) (xy 126.733744 -255.194998) (xy 126.786894 -255.191015) (xy 126.840044 -255.194998)
			(xy 126.892006 -255.206858) (xy 126.94162 -255.22633) (xy 126.987778 -255.252979) (xy 127.029449 -255.28621)
			(xy 127.065701 -255.325281) (xy 127.095725 -255.369318) (xy 127.118851 -255.417339) (xy 127.134561 -255.468269)
			(xy 127.142504 -255.520973) (xy 127.143002 -255.547622) (xy 127.383035 -255.547622) (xy 127.387065 -255.495124)
			(xy 127.399062 -255.443856) (xy 127.418745 -255.395021) (xy 127.445651 -255.349762) (xy 127.479151 -255.309141)
			(xy 127.518459 -255.27411) (xy 127.562654 -255.24549) (xy 127.610699 -255.223951) (xy 127.66147 -255.209999)
			(xy 127.713775 -255.203961) (xy 127.766389 -255.205978) (xy 127.818079 -255.216002) (xy 127.867632 -255.2338)
			(xy 127.913888 -255.258953) (xy 127.955762 -255.290872) (xy 127.992274 -255.32881) (xy 128.022566 -255.371876)
			(xy 128.045929 -255.419061) (xy 128.061815 -255.46926) (xy 128.069852 -255.521296) (xy 128.070356 -255.547622)
			(xy 128.069852 -255.573948) (xy 128.069802 -255.574271) (xy 128.311138 -255.574271) (xy 128.311138 -255.520973)
			(xy 128.319081 -255.468269) (xy 128.334791 -255.417339) (xy 128.357917 -255.369318) (xy 128.387941 -255.325281)
			(xy 128.424193 -255.28621) (xy 128.465864 -255.252979) (xy 128.512022 -255.22633) (xy 128.561636 -255.206858)
			(xy 128.613598 -255.194998) (xy 128.666748 -255.191015) (xy 128.719898 -255.194998) (xy 128.77186 -255.206858)
			(xy 128.821474 -255.22633) (xy 128.867632 -255.252979) (xy 128.909303 -255.28621) (xy 128.945555 -255.325281)
			(xy 128.975579 -255.369318) (xy 128.998705 -255.417339) (xy 129.014415 -255.468269) (xy 129.022358 -255.520973)
			(xy 129.022856 -255.547622) (xy 129.022358 -255.574271) (xy 129.250938 -255.574271) (xy 129.250938 -255.520973)
			(xy 129.258881 -255.468269) (xy 129.274591 -255.417339) (xy 129.297717 -255.369318) (xy 129.327741 -255.325281)
			(xy 129.363993 -255.28621) (xy 129.405664 -255.252979) (xy 129.451822 -255.22633) (xy 129.501436 -255.206858)
			(xy 129.553398 -255.194998) (xy 129.606548 -255.191015) (xy 129.659698 -255.194998) (xy 129.71166 -255.206858)
			(xy 129.761274 -255.22633) (xy 129.807432 -255.252979) (xy 129.849103 -255.28621) (xy 129.885355 -255.325281)
			(xy 129.915379 -255.369318) (xy 129.938505 -255.417339) (xy 129.954215 -255.468269) (xy 129.962158 -255.520973)
			(xy 129.962656 -255.547622) (xy 129.962158 -255.574271) (xy 130.190738 -255.574271) (xy 130.190738 -255.520973)
			(xy 130.198681 -255.468269) (xy 130.214391 -255.417339) (xy 130.237517 -255.369318) (xy 130.267541 -255.325281)
			(xy 130.303793 -255.28621) (xy 130.345464 -255.252979) (xy 130.391622 -255.22633) (xy 130.441236 -255.206858)
			(xy 130.493198 -255.194998) (xy 130.546348 -255.191015) (xy 130.599498 -255.194998) (xy 130.65146 -255.206858)
			(xy 130.701074 -255.22633) (xy 130.747232 -255.252979) (xy 130.788903 -255.28621) (xy 130.825155 -255.325281)
			(xy 130.855179 -255.369318) (xy 130.878305 -255.417339) (xy 130.894015 -255.468269) (xy 130.901958 -255.520973)
			(xy 130.902456 -255.547622) (xy 130.901958 -255.574271) (xy 131.130538 -255.574271) (xy 131.130538 -255.520973)
			(xy 131.138481 -255.468269) (xy 131.154191 -255.417339) (xy 131.177317 -255.369318) (xy 131.207341 -255.325281)
			(xy 131.243593 -255.28621) (xy 131.285264 -255.252979) (xy 131.331422 -255.22633) (xy 131.381036 -255.206858)
			(xy 131.432998 -255.194998) (xy 131.486148 -255.191015) (xy 131.539298 -255.194998) (xy 131.59126 -255.206858)
			(xy 131.640874 -255.22633) (xy 131.687032 -255.252979) (xy 131.728703 -255.28621) (xy 131.764955 -255.325281)
			(xy 131.794979 -255.369318) (xy 131.818105 -255.417339) (xy 131.833815 -255.468269) (xy 131.841758 -255.520973)
			(xy 131.842256 -255.547622) (xy 131.841758 -255.574271) (xy 132.070338 -255.574271) (xy 132.070338 -255.520973)
			(xy 132.078281 -255.468269) (xy 132.093991 -255.417339) (xy 132.117117 -255.369318) (xy 132.147141 -255.325281)
			(xy 132.183393 -255.28621) (xy 132.225064 -255.252979) (xy 132.271222 -255.22633) (xy 132.320836 -255.206858)
			(xy 132.372798 -255.194998) (xy 132.425948 -255.191015) (xy 132.479098 -255.194998) (xy 132.53106 -255.206858)
			(xy 132.580674 -255.22633) (xy 132.626832 -255.252979) (xy 132.668503 -255.28621) (xy 132.704755 -255.325281)
			(xy 132.734779 -255.369318) (xy 132.757905 -255.417339) (xy 132.773615 -255.468269) (xy 132.781558 -255.520973)
			(xy 132.782056 -255.547622) (xy 132.781558 -255.574271) (xy 133.009884 -255.574271) (xy 133.009884 -255.520973)
			(xy 133.017827 -255.468269) (xy 133.033537 -255.417339) (xy 133.056663 -255.369318) (xy 133.086687 -255.325281)
			(xy 133.122939 -255.28621) (xy 133.16461 -255.252979) (xy 133.210768 -255.22633) (xy 133.260382 -255.206858)
			(xy 133.312344 -255.194998) (xy 133.365494 -255.191015) (xy 133.418644 -255.194998) (xy 133.470606 -255.206858)
			(xy 133.52022 -255.22633) (xy 133.566378 -255.252979) (xy 133.608049 -255.28621) (xy 133.644301 -255.325281)
			(xy 133.674325 -255.369318) (xy 133.697451 -255.417339) (xy 133.713161 -255.468269) (xy 133.721104 -255.520973)
			(xy 133.721602 -255.547622) (xy 133.721104 -255.574271) (xy 133.949938 -255.574271) (xy 133.949938 -255.520973)
			(xy 133.957881 -255.468269) (xy 133.973591 -255.417339) (xy 133.996717 -255.369318) (xy 134.026741 -255.325281)
			(xy 134.062993 -255.28621) (xy 134.104664 -255.252979) (xy 134.150822 -255.22633) (xy 134.200436 -255.206858)
			(xy 134.252398 -255.194998) (xy 134.305548 -255.191015) (xy 134.358698 -255.194998) (xy 134.41066 -255.206858)
			(xy 134.460274 -255.22633) (xy 134.506432 -255.252979) (xy 134.548103 -255.28621) (xy 134.584355 -255.325281)
			(xy 134.614379 -255.369318) (xy 134.637505 -255.417339) (xy 134.653215 -255.468269) (xy 134.661158 -255.520973)
			(xy 134.661656 -255.547622) (xy 134.661158 -255.574271) (xy 134.653215 -255.626975) (xy 134.637505 -255.677905)
			(xy 134.614379 -255.725926) (xy 134.584355 -255.769963) (xy 134.548103 -255.809034) (xy 134.506432 -255.842265)
			(xy 134.460274 -255.868914) (xy 134.41066 -255.888386) (xy 134.358698 -255.900246) (xy 134.305548 -255.90423)
			(xy 134.252398 -255.900246) (xy 134.200436 -255.888386) (xy 134.150822 -255.868914) (xy 134.104664 -255.842265)
			(xy 134.062993 -255.809034) (xy 134.026741 -255.769963) (xy 133.996717 -255.725926) (xy 133.973591 -255.677905)
			(xy 133.957881 -255.626975) (xy 133.949938 -255.574271) (xy 133.721104 -255.574271) (xy 133.713161 -255.626975)
			(xy 133.697451 -255.677905) (xy 133.674325 -255.725926) (xy 133.644301 -255.769963) (xy 133.608049 -255.809034)
			(xy 133.566378 -255.842265) (xy 133.52022 -255.868914) (xy 133.470606 -255.888386) (xy 133.418644 -255.900246)
			(xy 133.365494 -255.90423) (xy 133.312344 -255.900246) (xy 133.260382 -255.888386) (xy 133.210768 -255.868914)
			(xy 133.16461 -255.842265) (xy 133.122939 -255.809034) (xy 133.086687 -255.769963) (xy 133.056663 -255.725926)
			(xy 133.033537 -255.677905) (xy 133.017827 -255.626975) (xy 133.009884 -255.574271) (xy 132.781558 -255.574271)
			(xy 132.773615 -255.626975) (xy 132.757905 -255.677905) (xy 132.734779 -255.725926) (xy 132.704755 -255.769963)
			(xy 132.668503 -255.809034) (xy 132.626832 -255.842265) (xy 132.580674 -255.868914) (xy 132.53106 -255.888386)
			(xy 132.479098 -255.900246) (xy 132.425948 -255.90423) (xy 132.372798 -255.900246) (xy 132.320836 -255.888386)
			(xy 132.271222 -255.868914) (xy 132.225064 -255.842265) (xy 132.183393 -255.809034) (xy 132.147141 -255.769963)
			(xy 132.117117 -255.725926) (xy 132.093991 -255.677905) (xy 132.078281 -255.626975) (xy 132.070338 -255.574271)
			(xy 131.841758 -255.574271) (xy 131.833815 -255.626975) (xy 131.818105 -255.677905) (xy 131.794979 -255.725926)
			(xy 131.764955 -255.769963) (xy 131.728703 -255.809034) (xy 131.687032 -255.842265) (xy 131.640874 -255.868914)
			(xy 131.59126 -255.888386) (xy 131.539298 -255.900246) (xy 131.486148 -255.90423) (xy 131.432998 -255.900246)
			(xy 131.381036 -255.888386) (xy 131.331422 -255.868914) (xy 131.285264 -255.842265) (xy 131.243593 -255.809034)
			(xy 131.207341 -255.769963) (xy 131.177317 -255.725926) (xy 131.154191 -255.677905) (xy 131.138481 -255.626975)
			(xy 131.130538 -255.574271) (xy 130.901958 -255.574271) (xy 130.894015 -255.626975) (xy 130.878305 -255.677905)
			(xy 130.855179 -255.725926) (xy 130.825155 -255.769963) (xy 130.788903 -255.809034) (xy 130.747232 -255.842265)
			(xy 130.701074 -255.868914) (xy 130.65146 -255.888386) (xy 130.599498 -255.900246) (xy 130.546348 -255.90423)
			(xy 130.493198 -255.900246) (xy 130.441236 -255.888386) (xy 130.391622 -255.868914) (xy 130.345464 -255.842265)
			(xy 130.303793 -255.809034) (xy 130.267541 -255.769963) (xy 130.237517 -255.725926) (xy 130.214391 -255.677905)
			(xy 130.198681 -255.626975) (xy 130.190738 -255.574271) (xy 129.962158 -255.574271) (xy 129.954215 -255.626975)
			(xy 129.938505 -255.677905) (xy 129.915379 -255.725926) (xy 129.885355 -255.769963) (xy 129.849103 -255.809034)
			(xy 129.807432 -255.842265) (xy 129.761274 -255.868914) (xy 129.71166 -255.888386) (xy 129.659698 -255.900246)
			(xy 129.606548 -255.90423) (xy 129.553398 -255.900246) (xy 129.501436 -255.888386) (xy 129.451822 -255.868914)
			(xy 129.405664 -255.842265) (xy 129.363993 -255.809034) (xy 129.327741 -255.769963) (xy 129.297717 -255.725926)
			(xy 129.274591 -255.677905) (xy 129.258881 -255.626975) (xy 129.250938 -255.574271) (xy 129.022358 -255.574271)
			(xy 129.014415 -255.626975) (xy 128.998705 -255.677905) (xy 128.975579 -255.725926) (xy 128.945555 -255.769963)
			(xy 128.909303 -255.809034) (xy 128.867632 -255.842265) (xy 128.821474 -255.868914) (xy 128.77186 -255.888386)
			(xy 128.719898 -255.900246) (xy 128.666748 -255.90423) (xy 128.613598 -255.900246) (xy 128.561636 -255.888386)
			(xy 128.512022 -255.868914) (xy 128.465864 -255.842265) (xy 128.424193 -255.809034) (xy 128.387941 -255.769963)
			(xy 128.357917 -255.725926) (xy 128.334791 -255.677905) (xy 128.319081 -255.626975) (xy 128.311138 -255.574271)
			(xy 128.069802 -255.574271) (xy 128.061815 -255.625984) (xy 128.045929 -255.676183) (xy 128.022566 -255.723368)
			(xy 127.992274 -255.766434) (xy 127.955762 -255.804372) (xy 127.913888 -255.836291) (xy 127.867632 -255.861444)
			(xy 127.818079 -255.879242) (xy 127.766389 -255.889266) (xy 127.713775 -255.891283) (xy 127.66147 -255.885245)
			(xy 127.610699 -255.871293) (xy 127.562654 -255.849754) (xy 127.518459 -255.821134) (xy 127.479151 -255.786103)
			(xy 127.445651 -255.745482) (xy 127.418745 -255.700223) (xy 127.399062 -255.651388) (xy 127.387065 -255.60012)
			(xy 127.383035 -255.547622) (xy 127.143002 -255.547622) (xy 127.142504 -255.574271) (xy 127.134561 -255.626975)
			(xy 127.118851 -255.677905) (xy 127.095725 -255.725926) (xy 127.065701 -255.769963) (xy 127.029449 -255.809034)
			(xy 126.987778 -255.842265) (xy 126.94162 -255.868914) (xy 126.892006 -255.888386) (xy 126.840044 -255.900246)
			(xy 126.786894 -255.90423) (xy 126.733744 -255.900246) (xy 126.681782 -255.888386) (xy 126.632168 -255.868914)
			(xy 126.58601 -255.842265) (xy 126.544339 -255.809034) (xy 126.508087 -255.769963) (xy 126.478063 -255.725926)
			(xy 126.454937 -255.677905) (xy 126.439227 -255.626975) (xy 126.431284 -255.574271) (xy 126.202958 -255.574271)
			(xy 126.195015 -255.626975) (xy 126.179305 -255.677905) (xy 126.156179 -255.725926) (xy 126.126155 -255.769963)
			(xy 126.089903 -255.809034) (xy 126.048232 -255.842265) (xy 126.002074 -255.868914) (xy 125.95246 -255.888386)
			(xy 125.900498 -255.900246) (xy 125.847348 -255.90423) (xy 125.794198 -255.900246) (xy 125.742236 -255.888386)
			(xy 125.692622 -255.868914) (xy 125.646464 -255.842265) (xy 125.604793 -255.809034) (xy 125.568541 -255.769963)
			(xy 125.538517 -255.725926) (xy 125.515391 -255.677905) (xy 125.499681 -255.626975) (xy 125.491738 -255.574271)
			(xy 125.262904 -255.574271) (xy 125.254961 -255.626975) (xy 125.239251 -255.677905) (xy 125.216125 -255.725926)
			(xy 125.186101 -255.769963) (xy 125.149849 -255.809034) (xy 125.108178 -255.842265) (xy 125.06202 -255.868914)
			(xy 125.012406 -255.888386) (xy 124.960444 -255.900246) (xy 124.907294 -255.90423) (xy 124.854144 -255.900246)
			(xy 124.802182 -255.888386) (xy 124.752568 -255.868914) (xy 124.70641 -255.842265) (xy 124.664739 -255.809034)
			(xy 124.628487 -255.769963) (xy 124.598463 -255.725926) (xy 124.575337 -255.677905) (xy 124.559627 -255.626975)
			(xy 124.551684 -255.574271) (xy 124.323358 -255.574271) (xy 124.315415 -255.626975) (xy 124.299705 -255.677905)
			(xy 124.276579 -255.725926) (xy 124.246555 -255.769963) (xy 124.210303 -255.809034) (xy 124.168632 -255.842265)
			(xy 124.122474 -255.868914) (xy 124.07286 -255.888386) (xy 124.020898 -255.900246) (xy 123.967748 -255.90423)
			(xy 123.914598 -255.900246) (xy 123.862636 -255.888386) (xy 123.813022 -255.868914) (xy 123.766864 -255.842265)
			(xy 123.725193 -255.809034) (xy 123.688941 -255.769963) (xy 123.658917 -255.725926) (xy 123.635791 -255.677905)
			(xy 123.620081 -255.626975) (xy 123.612138 -255.574271) (xy 123.383558 -255.574271) (xy 123.375615 -255.626975)
			(xy 123.359905 -255.677905) (xy 123.336779 -255.725926) (xy 123.306755 -255.769963) (xy 123.270503 -255.809034)
			(xy 123.228832 -255.842265) (xy 123.182674 -255.868914) (xy 123.13306 -255.888386) (xy 123.081098 -255.900246)
			(xy 123.027948 -255.90423) (xy 122.974798 -255.900246) (xy 122.922836 -255.888386) (xy 122.873222 -255.868914)
			(xy 122.827064 -255.842265) (xy 122.785393 -255.809034) (xy 122.749141 -255.769963) (xy 122.719117 -255.725926)
			(xy 122.695991 -255.677905) (xy 122.680281 -255.626975) (xy 122.672338 -255.574271) (xy 121.329493 -255.574271)
			(xy 121.323088 -255.614434) (xy 121.305561 -255.667995) (xy 121.279819 -255.718127) (xy 121.246504 -255.763581)
			(xy 121.206447 -255.803221) (xy 121.160648 -255.83606) (xy 121.11025 -255.861278) (xy 121.056509 -255.878245)
			(xy 121.028714 -255.882902) (xy 120.98528 -255.889252) (xy 120.98528 -256.308352) (xy 121.028968 -256.314448)
			(xy 121.055184 -256.318668) (xy 121.106067 -256.333848) (xy 121.130314 -256.344674) (xy 121.144123 -256.350578)
			(xy 121.173828 -256.3549) (xy 121.203504 -256.350388) (xy 121.230582 -256.337433) (xy 121.252716 -256.317157)
			(xy 121.26799 -256.291316) (xy 121.272046 -256.276856) (xy 121.278764 -256.251376) (xy 121.298684 -256.202595)
			(xy 121.325575 -256.157281) (xy 121.358852 -256.116426) (xy 121.397786 -256.080922) (xy 121.441528 -256.051543)
			(xy 121.489122 -256.028933) (xy 121.539529 -256.013584) (xy 121.591648 -256.005831) (xy 121.617994 -256.00533)
			(xy 121.644643 -256.005803) (xy 121.697345 -256.013745) (xy 121.748274 -256.029454) (xy 121.796294 -256.052579)
			(xy 121.84033 -256.082601) (xy 121.8794 -256.118852) (xy 121.91263 -256.160522) (xy 121.939279 -256.206678)
			(xy 121.958751 -256.256291) (xy 121.970611 -256.308252) (xy 121.974594 -256.3614) (xy 121.972594 -256.388087)
			(xy 122.202438 -256.388087) (xy 122.202438 -256.334789) (xy 122.210381 -256.282085) (xy 122.226091 -256.231155)
			(xy 122.249217 -256.183134) (xy 122.279241 -256.139097) (xy 122.315493 -256.100026) (xy 122.357164 -256.066795)
			(xy 122.403322 -256.040146) (xy 122.452936 -256.020674) (xy 122.504898 -256.008814) (xy 122.558048 -256.004831)
			(xy 122.611198 -256.008814) (xy 122.66316 -256.020674) (xy 122.712774 -256.040146) (xy 122.758932 -256.066795)
			(xy 122.800603 -256.100026) (xy 122.836855 -256.139097) (xy 122.866879 -256.183134) (xy 122.890005 -256.231155)
			(xy 122.905715 -256.282085) (xy 122.913658 -256.334789) (xy 122.914156 -256.361438) (xy 122.913658 -256.388087)
			(xy 123.141984 -256.388087) (xy 123.141984 -256.334789) (xy 123.149927 -256.282085) (xy 123.165637 -256.231155)
			(xy 123.188763 -256.183134) (xy 123.218787 -256.139097) (xy 123.255039 -256.100026) (xy 123.29671 -256.066795)
			(xy 123.342868 -256.040146) (xy 123.392482 -256.020674) (xy 123.444444 -256.008814) (xy 123.497594 -256.004831)
			(xy 123.550744 -256.008814) (xy 123.602706 -256.020674) (xy 123.65232 -256.040146) (xy 123.698478 -256.066795)
			(xy 123.740149 -256.100026) (xy 123.776401 -256.139097) (xy 123.806425 -256.183134) (xy 123.829551 -256.231155)
			(xy 123.845261 -256.282085) (xy 123.853204 -256.334789) (xy 123.853702 -256.361438) (xy 123.853204 -256.388087)
			(xy 124.081784 -256.388087) (xy 124.081784 -256.334789) (xy 124.089727 -256.282085) (xy 124.105437 -256.231155)
			(xy 124.128563 -256.183134) (xy 124.158587 -256.139097) (xy 124.194839 -256.100026) (xy 124.23651 -256.066795)
			(xy 124.282668 -256.040146) (xy 124.332282 -256.020674) (xy 124.384244 -256.008814) (xy 124.437394 -256.004831)
			(xy 124.490544 -256.008814) (xy 124.542506 -256.020674) (xy 124.59212 -256.040146) (xy 124.638278 -256.066795)
			(xy 124.679949 -256.100026) (xy 124.716201 -256.139097) (xy 124.746225 -256.183134) (xy 124.769351 -256.231155)
			(xy 124.785061 -256.282085) (xy 124.793004 -256.334789) (xy 124.793502 -256.361438) (xy 124.793004 -256.388087)
			(xy 125.021584 -256.388087) (xy 125.021584 -256.334789) (xy 125.029527 -256.282085) (xy 125.045237 -256.231155)
			(xy 125.068363 -256.183134) (xy 125.098387 -256.139097) (xy 125.134639 -256.100026) (xy 125.17631 -256.066795)
			(xy 125.222468 -256.040146) (xy 125.272082 -256.020674) (xy 125.324044 -256.008814) (xy 125.377194 -256.004831)
			(xy 125.430344 -256.008814) (xy 125.482306 -256.020674) (xy 125.53192 -256.040146) (xy 125.578078 -256.066795)
			(xy 125.619749 -256.100026) (xy 125.656001 -256.139097) (xy 125.686025 -256.183134) (xy 125.709151 -256.231155)
			(xy 125.724861 -256.282085) (xy 125.732804 -256.334789) (xy 125.733302 -256.361438) (xy 125.732804 -256.388087)
			(xy 125.961384 -256.388087) (xy 125.961384 -256.334789) (xy 125.969327 -256.282085) (xy 125.985037 -256.231155)
			(xy 126.008163 -256.183134) (xy 126.038187 -256.139097) (xy 126.074439 -256.100026) (xy 126.11611 -256.066795)
			(xy 126.162268 -256.040146) (xy 126.211882 -256.020674) (xy 126.263844 -256.008814) (xy 126.316994 -256.004831)
			(xy 126.370144 -256.008814) (xy 126.422106 -256.020674) (xy 126.47172 -256.040146) (xy 126.517878 -256.066795)
			(xy 126.559549 -256.100026) (xy 126.595801 -256.139097) (xy 126.625825 -256.183134) (xy 126.648951 -256.231155)
			(xy 126.664661 -256.282085) (xy 126.672604 -256.334789) (xy 126.673102 -256.361438) (xy 126.672604 -256.388087)
			(xy 126.901184 -256.388087) (xy 126.901184 -256.334789) (xy 126.909127 -256.282085) (xy 126.924837 -256.231155)
			(xy 126.947963 -256.183134) (xy 126.977987 -256.139097) (xy 127.014239 -256.100026) (xy 127.05591 -256.066795)
			(xy 127.102068 -256.040146) (xy 127.151682 -256.020674) (xy 127.203644 -256.008814) (xy 127.256794 -256.004831)
			(xy 127.309944 -256.008814) (xy 127.361906 -256.020674) (xy 127.41152 -256.040146) (xy 127.457678 -256.066795)
			(xy 127.499349 -256.100026) (xy 127.535601 -256.139097) (xy 127.565625 -256.183134) (xy 127.588751 -256.231155)
			(xy 127.604461 -256.282085) (xy 127.612404 -256.334789) (xy 127.612902 -256.361438) (xy 127.612404 -256.388087)
			(xy 127.840984 -256.388087) (xy 127.840984 -256.334789) (xy 127.848927 -256.282085) (xy 127.864637 -256.231155)
			(xy 127.887763 -256.183134) (xy 127.917787 -256.139097) (xy 127.954039 -256.100026) (xy 127.99571 -256.066795)
			(xy 128.041868 -256.040146) (xy 128.091482 -256.020674) (xy 128.143444 -256.008814) (xy 128.196594 -256.004831)
			(xy 128.249744 -256.008814) (xy 128.301706 -256.020674) (xy 128.35132 -256.040146) (xy 128.397478 -256.066795)
			(xy 128.439149 -256.100026) (xy 128.475401 -256.139097) (xy 128.505425 -256.183134) (xy 128.528551 -256.231155)
			(xy 128.544261 -256.282085) (xy 128.552204 -256.334789) (xy 128.552702 -256.361438) (xy 128.552204 -256.388087)
			(xy 128.781038 -256.388087) (xy 128.781038 -256.334789) (xy 128.788981 -256.282085) (xy 128.804691 -256.231155)
			(xy 128.827817 -256.183134) (xy 128.857841 -256.139097) (xy 128.894093 -256.100026) (xy 128.935764 -256.066795)
			(xy 128.981922 -256.040146) (xy 129.031536 -256.020674) (xy 129.083498 -256.008814) (xy 129.136648 -256.004831)
			(xy 129.189798 -256.008814) (xy 129.24176 -256.020674) (xy 129.291374 -256.040146) (xy 129.337532 -256.066795)
			(xy 129.379203 -256.100026) (xy 129.415455 -256.139097) (xy 129.445479 -256.183134) (xy 129.468605 -256.231155)
			(xy 129.484315 -256.282085) (xy 129.492258 -256.334789) (xy 129.492756 -256.361438) (xy 129.492258 -256.388087)
			(xy 129.720584 -256.388087) (xy 129.720584 -256.334789) (xy 129.728527 -256.282085) (xy 129.744237 -256.231155)
			(xy 129.767363 -256.183134) (xy 129.797387 -256.139097) (xy 129.833639 -256.100026) (xy 129.87531 -256.066795)
			(xy 129.921468 -256.040146) (xy 129.971082 -256.020674) (xy 130.023044 -256.008814) (xy 130.076194 -256.004831)
			(xy 130.129344 -256.008814) (xy 130.181306 -256.020674) (xy 130.23092 -256.040146) (xy 130.277078 -256.066795)
			(xy 130.318749 -256.100026) (xy 130.355001 -256.139097) (xy 130.385025 -256.183134) (xy 130.408151 -256.231155)
			(xy 130.423861 -256.282085) (xy 130.431804 -256.334789) (xy 130.432302 -256.361438) (xy 130.431804 -256.388087)
			(xy 130.660384 -256.388087) (xy 130.660384 -256.334789) (xy 130.668327 -256.282085) (xy 130.684037 -256.231155)
			(xy 130.707163 -256.183134) (xy 130.737187 -256.139097) (xy 130.773439 -256.100026) (xy 130.81511 -256.066795)
			(xy 130.861268 -256.040146) (xy 130.910882 -256.020674) (xy 130.962844 -256.008814) (xy 131.015994 -256.004831)
			(xy 131.069144 -256.008814) (xy 131.121106 -256.020674) (xy 131.17072 -256.040146) (xy 131.216878 -256.066795)
			(xy 131.258549 -256.100026) (xy 131.294801 -256.139097) (xy 131.324825 -256.183134) (xy 131.347951 -256.231155)
			(xy 131.363661 -256.282085) (xy 131.371604 -256.334789) (xy 131.372102 -256.361438) (xy 131.371604 -256.388087)
			(xy 131.600184 -256.388087) (xy 131.600184 -256.334789) (xy 131.608127 -256.282085) (xy 131.623837 -256.231155)
			(xy 131.646963 -256.183134) (xy 131.676987 -256.139097) (xy 131.713239 -256.100026) (xy 131.75491 -256.066795)
			(xy 131.801068 -256.040146) (xy 131.850682 -256.020674) (xy 131.902644 -256.008814) (xy 131.955794 -256.004831)
			(xy 132.008944 -256.008814) (xy 132.060906 -256.020674) (xy 132.11052 -256.040146) (xy 132.156678 -256.066795)
			(xy 132.198349 -256.100026) (xy 132.234601 -256.139097) (xy 132.264625 -256.183134) (xy 132.287751 -256.231155)
			(xy 132.303461 -256.282085) (xy 132.311404 -256.334789) (xy 132.311902 -256.361438) (xy 132.311404 -256.388087)
			(xy 132.539984 -256.388087) (xy 132.539984 -256.334789) (xy 132.547927 -256.282085) (xy 132.563637 -256.231155)
			(xy 132.586763 -256.183134) (xy 132.616787 -256.139097) (xy 132.653039 -256.100026) (xy 132.69471 -256.066795)
			(xy 132.740868 -256.040146) (xy 132.790482 -256.020674) (xy 132.842444 -256.008814) (xy 132.895594 -256.004831)
			(xy 132.948744 -256.008814) (xy 133.000706 -256.020674) (xy 133.05032 -256.040146) (xy 133.096478 -256.066795)
			(xy 133.138149 -256.100026) (xy 133.174401 -256.139097) (xy 133.204425 -256.183134) (xy 133.227551 -256.231155)
			(xy 133.243261 -256.282085) (xy 133.251204 -256.334789) (xy 133.251702 -256.361438) (xy 133.251204 -256.388087)
			(xy 133.479784 -256.388087) (xy 133.479784 -256.334789) (xy 133.487727 -256.282085) (xy 133.503437 -256.231155)
			(xy 133.526563 -256.183134) (xy 133.556587 -256.139097) (xy 133.592839 -256.100026) (xy 133.63451 -256.066795)
			(xy 133.680668 -256.040146) (xy 133.730282 -256.020674) (xy 133.782244 -256.008814) (xy 133.835394 -256.004831)
			(xy 133.888544 -256.008814) (xy 133.940506 -256.020674) (xy 133.99012 -256.040146) (xy 134.036278 -256.066795)
			(xy 134.077949 -256.100026) (xy 134.114201 -256.139097) (xy 134.144225 -256.183134) (xy 134.167351 -256.231155)
			(xy 134.183061 -256.282085) (xy 134.191004 -256.334789) (xy 134.191502 -256.361438) (xy 134.191004 -256.388087)
			(xy 134.183061 -256.440791) (xy 134.167351 -256.491721) (xy 134.144225 -256.539742) (xy 134.114201 -256.583779)
			(xy 134.077949 -256.62285) (xy 134.036278 -256.656081) (xy 133.99012 -256.68273) (xy 133.940506 -256.702202)
			(xy 133.888544 -256.714062) (xy 133.835394 -256.718046) (xy 133.782244 -256.714062) (xy 133.730282 -256.702202)
			(xy 133.680668 -256.68273) (xy 133.63451 -256.656081) (xy 133.592839 -256.62285) (xy 133.556587 -256.583779)
			(xy 133.526563 -256.539742) (xy 133.503437 -256.491721) (xy 133.487727 -256.440791) (xy 133.479784 -256.388087)
			(xy 133.251204 -256.388087) (xy 133.243261 -256.440791) (xy 133.227551 -256.491721) (xy 133.204425 -256.539742)
			(xy 133.174401 -256.583779) (xy 133.138149 -256.62285) (xy 133.096478 -256.656081) (xy 133.05032 -256.68273)
			(xy 133.000706 -256.702202) (xy 132.948744 -256.714062) (xy 132.895594 -256.718046) (xy 132.842444 -256.714062)
			(xy 132.790482 -256.702202) (xy 132.740868 -256.68273) (xy 132.69471 -256.656081) (xy 132.653039 -256.62285)
			(xy 132.616787 -256.583779) (xy 132.586763 -256.539742) (xy 132.563637 -256.491721) (xy 132.547927 -256.440791)
			(xy 132.539984 -256.388087) (xy 132.311404 -256.388087) (xy 132.303461 -256.440791) (xy 132.287751 -256.491721)
			(xy 132.264625 -256.539742) (xy 132.234601 -256.583779) (xy 132.198349 -256.62285) (xy 132.156678 -256.656081)
			(xy 132.11052 -256.68273) (xy 132.060906 -256.702202) (xy 132.008944 -256.714062) (xy 131.955794 -256.718046)
			(xy 131.902644 -256.714062) (xy 131.850682 -256.702202) (xy 131.801068 -256.68273) (xy 131.75491 -256.656081)
			(xy 131.713239 -256.62285) (xy 131.676987 -256.583779) (xy 131.646963 -256.539742) (xy 131.623837 -256.491721)
			(xy 131.608127 -256.440791) (xy 131.600184 -256.388087) (xy 131.371604 -256.388087) (xy 131.363661 -256.440791)
			(xy 131.347951 -256.491721) (xy 131.324825 -256.539742) (xy 131.294801 -256.583779) (xy 131.258549 -256.62285)
			(xy 131.216878 -256.656081) (xy 131.17072 -256.68273) (xy 131.121106 -256.702202) (xy 131.069144 -256.714062)
			(xy 131.015994 -256.718046) (xy 130.962844 -256.714062) (xy 130.910882 -256.702202) (xy 130.861268 -256.68273)
			(xy 130.81511 -256.656081) (xy 130.773439 -256.62285) (xy 130.737187 -256.583779) (xy 130.707163 -256.539742)
			(xy 130.684037 -256.491721) (xy 130.668327 -256.440791) (xy 130.660384 -256.388087) (xy 130.431804 -256.388087)
			(xy 130.423861 -256.440791) (xy 130.408151 -256.491721) (xy 130.385025 -256.539742) (xy 130.355001 -256.583779)
			(xy 130.318749 -256.62285) (xy 130.277078 -256.656081) (xy 130.23092 -256.68273) (xy 130.181306 -256.702202)
			(xy 130.129344 -256.714062) (xy 130.076194 -256.718046) (xy 130.023044 -256.714062) (xy 129.971082 -256.702202)
			(xy 129.921468 -256.68273) (xy 129.87531 -256.656081) (xy 129.833639 -256.62285) (xy 129.797387 -256.583779)
			(xy 129.767363 -256.539742) (xy 129.744237 -256.491721) (xy 129.728527 -256.440791) (xy 129.720584 -256.388087)
			(xy 129.492258 -256.388087) (xy 129.484315 -256.440791) (xy 129.468605 -256.491721) (xy 129.445479 -256.539742)
			(xy 129.415455 -256.583779) (xy 129.379203 -256.62285) (xy 129.337532 -256.656081) (xy 129.291374 -256.68273)
			(xy 129.24176 -256.702202) (xy 129.189798 -256.714062) (xy 129.136648 -256.718046) (xy 129.083498 -256.714062)
			(xy 129.031536 -256.702202) (xy 128.981922 -256.68273) (xy 128.935764 -256.656081) (xy 128.894093 -256.62285)
			(xy 128.857841 -256.583779) (xy 128.827817 -256.539742) (xy 128.804691 -256.491721) (xy 128.788981 -256.440791)
			(xy 128.781038 -256.388087) (xy 128.552204 -256.388087) (xy 128.544261 -256.440791) (xy 128.528551 -256.491721)
			(xy 128.505425 -256.539742) (xy 128.475401 -256.583779) (xy 128.439149 -256.62285) (xy 128.397478 -256.656081)
			(xy 128.35132 -256.68273) (xy 128.301706 -256.702202) (xy 128.249744 -256.714062) (xy 128.196594 -256.718046)
			(xy 128.143444 -256.714062) (xy 128.091482 -256.702202) (xy 128.041868 -256.68273) (xy 127.99571 -256.656081)
			(xy 127.954039 -256.62285) (xy 127.917787 -256.583779) (xy 127.887763 -256.539742) (xy 127.864637 -256.491721)
			(xy 127.848927 -256.440791) (xy 127.840984 -256.388087) (xy 127.612404 -256.388087) (xy 127.604461 -256.440791)
			(xy 127.588751 -256.491721) (xy 127.565625 -256.539742) (xy 127.535601 -256.583779) (xy 127.499349 -256.62285)
			(xy 127.457678 -256.656081) (xy 127.41152 -256.68273) (xy 127.361906 -256.702202) (xy 127.309944 -256.714062)
			(xy 127.256794 -256.718046) (xy 127.203644 -256.714062) (xy 127.151682 -256.702202) (xy 127.102068 -256.68273)
			(xy 127.05591 -256.656081) (xy 127.014239 -256.62285) (xy 126.977987 -256.583779) (xy 126.947963 -256.539742)
			(xy 126.924837 -256.491721) (xy 126.909127 -256.440791) (xy 126.901184 -256.388087) (xy 126.672604 -256.388087)
			(xy 126.664661 -256.440791) (xy 126.648951 -256.491721) (xy 126.625825 -256.539742) (xy 126.595801 -256.583779)
			(xy 126.559549 -256.62285) (xy 126.517878 -256.656081) (xy 126.47172 -256.68273) (xy 126.422106 -256.702202)
			(xy 126.370144 -256.714062) (xy 126.316994 -256.718046) (xy 126.263844 -256.714062) (xy 126.211882 -256.702202)
			(xy 126.162268 -256.68273) (xy 126.11611 -256.656081) (xy 126.074439 -256.62285) (xy 126.038187 -256.583779)
			(xy 126.008163 -256.539742) (xy 125.985037 -256.491721) (xy 125.969327 -256.440791) (xy 125.961384 -256.388087)
			(xy 125.732804 -256.388087) (xy 125.724861 -256.440791) (xy 125.709151 -256.491721) (xy 125.686025 -256.539742)
			(xy 125.656001 -256.583779) (xy 125.619749 -256.62285) (xy 125.578078 -256.656081) (xy 125.53192 -256.68273)
			(xy 125.482306 -256.702202) (xy 125.430344 -256.714062) (xy 125.377194 -256.718046) (xy 125.324044 -256.714062)
			(xy 125.272082 -256.702202) (xy 125.222468 -256.68273) (xy 125.17631 -256.656081) (xy 125.134639 -256.62285)
			(xy 125.098387 -256.583779) (xy 125.068363 -256.539742) (xy 125.045237 -256.491721) (xy 125.029527 -256.440791)
			(xy 125.021584 -256.388087) (xy 124.793004 -256.388087) (xy 124.785061 -256.440791) (xy 124.769351 -256.491721)
			(xy 124.746225 -256.539742) (xy 124.716201 -256.583779) (xy 124.679949 -256.62285) (xy 124.638278 -256.656081)
			(xy 124.59212 -256.68273) (xy 124.542506 -256.702202) (xy 124.490544 -256.714062) (xy 124.437394 -256.718046)
			(xy 124.384244 -256.714062) (xy 124.332282 -256.702202) (xy 124.282668 -256.68273) (xy 124.23651 -256.656081)
			(xy 124.194839 -256.62285) (xy 124.158587 -256.583779) (xy 124.128563 -256.539742) (xy 124.105437 -256.491721)
			(xy 124.089727 -256.440791) (xy 124.081784 -256.388087) (xy 123.853204 -256.388087) (xy 123.845261 -256.440791)
			(xy 123.829551 -256.491721) (xy 123.806425 -256.539742) (xy 123.776401 -256.583779) (xy 123.740149 -256.62285)
			(xy 123.698478 -256.656081) (xy 123.65232 -256.68273) (xy 123.602706 -256.702202) (xy 123.550744 -256.714062)
			(xy 123.497594 -256.718046) (xy 123.444444 -256.714062) (xy 123.392482 -256.702202) (xy 123.342868 -256.68273)
			(xy 123.29671 -256.656081) (xy 123.255039 -256.62285) (xy 123.218787 -256.583779) (xy 123.188763 -256.539742)
			(xy 123.165637 -256.491721) (xy 123.149927 -256.440791) (xy 123.141984 -256.388087) (xy 122.913658 -256.388087)
			(xy 122.905715 -256.440791) (xy 122.890005 -256.491721) (xy 122.866879 -256.539742) (xy 122.836855 -256.583779)
			(xy 122.800603 -256.62285) (xy 122.758932 -256.656081) (xy 122.712774 -256.68273) (xy 122.66316 -256.702202)
			(xy 122.611198 -256.714062) (xy 122.558048 -256.718046) (xy 122.504898 -256.714062) (xy 122.452936 -256.702202)
			(xy 122.403322 -256.68273) (xy 122.357164 -256.656081) (xy 122.315493 -256.62285) (xy 122.279241 -256.583779)
			(xy 122.249217 -256.539742) (xy 122.226091 -256.491721) (xy 122.210381 -256.440791) (xy 122.202438 -256.388087)
			(xy 121.972594 -256.388087) (xy 121.970611 -256.414548) (xy 121.958751 -256.466509) (xy 121.939279 -256.516122)
			(xy 121.912631 -256.562278) (xy 121.8794 -256.603948) (xy 121.84033 -256.640199) (xy 121.796294 -256.670221)
			(xy 121.748274 -256.693346) (xy 121.697345 -256.709055) (xy 121.644643 -256.716997) (xy 121.617994 -256.717546)
			(xy 121.591921 -256.71709) (xy 121.540332 -256.709483) (xy 121.490405 -256.694432) (xy 121.46661 -256.683764)
			(xy 121.452801 -256.677855) (xy 121.423093 -256.673525) (xy 121.393412 -256.678033) (xy 121.36633 -256.690989)
			(xy 121.344194 -256.71127) (xy 121.328924 -256.737117) (xy 121.324878 -256.751582) (xy 121.3172 -256.780444)
			(xy 121.293543 -256.835277) (xy 121.261068 -256.885394) (xy 121.241312 -256.907792) (xy 121.23152 -256.919238)
			(xy 121.218489 -256.946378) (xy 121.213943 -256.976138) (xy 121.218278 -257.005931) (xy 121.231117 -257.033162)
			(xy 121.240804 -257.044698) (xy 121.257977 -257.064422) (xy 121.286953 -257.107959) (xy 121.309251 -257.155265)
			(xy 121.323359 -257.201903) (xy 121.732538 -257.201903) (xy 121.732538 -257.148605) (xy 121.740481 -257.095901)
			(xy 121.756191 -257.044971) (xy 121.779317 -256.99695) (xy 121.809341 -256.952913) (xy 121.845593 -256.913842)
			(xy 121.887264 -256.880611) (xy 121.933422 -256.853962) (xy 121.983036 -256.83449) (xy 122.034998 -256.82263)
			(xy 122.088148 -256.818647) (xy 122.141298 -256.82263) (xy 122.19326 -256.83449) (xy 122.242874 -256.853962)
			(xy 122.289032 -256.880611) (xy 122.330703 -256.913842) (xy 122.366955 -256.952913) (xy 122.396979 -256.99695)
			(xy 122.420105 -257.044971) (xy 122.435815 -257.095901) (xy 122.443758 -257.148605) (xy 122.444256 -257.175254)
			(xy 122.443758 -257.201903) (xy 122.672338 -257.201903) (xy 122.672338 -257.148605) (xy 122.680281 -257.095901)
			(xy 122.695991 -257.044971) (xy 122.719117 -256.99695) (xy 122.749141 -256.952913) (xy 122.785393 -256.913842)
			(xy 122.827064 -256.880611) (xy 122.873222 -256.853962) (xy 122.922836 -256.83449) (xy 122.974798 -256.82263)
			(xy 123.027948 -256.818647) (xy 123.081098 -256.82263) (xy 123.13306 -256.83449) (xy 123.182674 -256.853962)
			(xy 123.228832 -256.880611) (xy 123.270503 -256.913842) (xy 123.306755 -256.952913) (xy 123.336779 -256.99695)
			(xy 123.359905 -257.044971) (xy 123.375615 -257.095901) (xy 123.383558 -257.148605) (xy 123.384056 -257.175254)
			(xy 123.383558 -257.201903) (xy 123.612138 -257.201903) (xy 123.612138 -257.148605) (xy 123.620081 -257.095901)
			(xy 123.635791 -257.044971) (xy 123.658917 -256.99695) (xy 123.688941 -256.952913) (xy 123.725193 -256.913842)
			(xy 123.766864 -256.880611) (xy 123.813022 -256.853962) (xy 123.862636 -256.83449) (xy 123.914598 -256.82263)
			(xy 123.967748 -256.818647) (xy 124.020898 -256.82263) (xy 124.07286 -256.83449) (xy 124.122474 -256.853962)
			(xy 124.168632 -256.880611) (xy 124.210303 -256.913842) (xy 124.246555 -256.952913) (xy 124.276579 -256.99695)
			(xy 124.299705 -257.044971) (xy 124.315415 -257.095901) (xy 124.323358 -257.148605) (xy 124.323856 -257.175254)
			(xy 124.323358 -257.201903) (xy 124.551684 -257.201903) (xy 124.551684 -257.148605) (xy 124.559627 -257.095901)
			(xy 124.575337 -257.044971) (xy 124.598463 -256.99695) (xy 124.628487 -256.952913) (xy 124.664739 -256.913842)
			(xy 124.70641 -256.880611) (xy 124.752568 -256.853962) (xy 124.802182 -256.83449) (xy 124.854144 -256.82263)
			(xy 124.907294 -256.818647) (xy 124.960444 -256.82263) (xy 125.012406 -256.83449) (xy 125.06202 -256.853962)
			(xy 125.108178 -256.880611) (xy 125.149849 -256.913842) (xy 125.186101 -256.952913) (xy 125.216125 -256.99695)
			(xy 125.239251 -257.044971) (xy 125.254961 -257.095901) (xy 125.262904 -257.148605) (xy 125.263402 -257.175254)
			(xy 125.262904 -257.201903) (xy 125.491484 -257.201903) (xy 125.491484 -257.148605) (xy 125.499427 -257.095901)
			(xy 125.515137 -257.044971) (xy 125.538263 -256.99695) (xy 125.568287 -256.952913) (xy 125.604539 -256.913842)
			(xy 125.64621 -256.880611) (xy 125.692368 -256.853962) (xy 125.741982 -256.83449) (xy 125.793944 -256.82263)
			(xy 125.847094 -256.818647) (xy 125.900244 -256.82263) (xy 125.952206 -256.83449) (xy 126.00182 -256.853962)
			(xy 126.047978 -256.880611) (xy 126.089649 -256.913842) (xy 126.125901 -256.952913) (xy 126.155925 -256.99695)
			(xy 126.179051 -257.044971) (xy 126.194761 -257.095901) (xy 126.202704 -257.148605) (xy 126.203202 -257.175254)
			(xy 126.202704 -257.201903) (xy 126.431538 -257.201903) (xy 126.431538 -257.148605) (xy 126.439481 -257.095901)
			(xy 126.455191 -257.044971) (xy 126.478317 -256.99695) (xy 126.508341 -256.952913) (xy 126.544593 -256.913842)
			(xy 126.586264 -256.880611) (xy 126.632422 -256.853962) (xy 126.682036 -256.83449) (xy 126.733998 -256.82263)
			(xy 126.787148 -256.818647) (xy 126.840298 -256.82263) (xy 126.89226 -256.83449) (xy 126.941874 -256.853962)
			(xy 126.988032 -256.880611) (xy 127.029703 -256.913842) (xy 127.065955 -256.952913) (xy 127.095979 -256.99695)
			(xy 127.119105 -257.044971) (xy 127.134815 -257.095901) (xy 127.142758 -257.148605) (xy 127.143256 -257.175254)
			(xy 127.142758 -257.201903) (xy 127.371084 -257.201903) (xy 127.371084 -257.148605) (xy 127.379027 -257.095901)
			(xy 127.394737 -257.044971) (xy 127.417863 -256.99695) (xy 127.447887 -256.952913) (xy 127.484139 -256.913842)
			(xy 127.52581 -256.880611) (xy 127.571968 -256.853962) (xy 127.621582 -256.83449) (xy 127.673544 -256.82263)
			(xy 127.726694 -256.818647) (xy 127.779844 -256.82263) (xy 127.831806 -256.83449) (xy 127.88142 -256.853962)
			(xy 127.927578 -256.880611) (xy 127.969249 -256.913842) (xy 128.005501 -256.952913) (xy 128.035525 -256.99695)
			(xy 128.058651 -257.044971) (xy 128.074361 -257.095901) (xy 128.082304 -257.148605) (xy 128.082802 -257.175254)
			(xy 128.082304 -257.201903) (xy 128.311138 -257.201903) (xy 128.311138 -257.148605) (xy 128.319081 -257.095901)
			(xy 128.334791 -257.044971) (xy 128.357917 -256.99695) (xy 128.387941 -256.952913) (xy 128.424193 -256.913842)
			(xy 128.465864 -256.880611) (xy 128.512022 -256.853962) (xy 128.561636 -256.83449) (xy 128.613598 -256.82263)
			(xy 128.666748 -256.818647) (xy 128.719898 -256.82263) (xy 128.77186 -256.83449) (xy 128.821474 -256.853962)
			(xy 128.867632 -256.880611) (xy 128.909303 -256.913842) (xy 128.945555 -256.952913) (xy 128.975579 -256.99695)
			(xy 128.998705 -257.044971) (xy 129.014415 -257.095901) (xy 129.022358 -257.148605) (xy 129.022856 -257.175254)
			(xy 129.022358 -257.201903) (xy 129.250938 -257.201903) (xy 129.250938 -257.148605) (xy 129.258881 -257.095901)
			(xy 129.274591 -257.044971) (xy 129.297717 -256.99695) (xy 129.327741 -256.952913) (xy 129.363993 -256.913842)
			(xy 129.405664 -256.880611) (xy 129.451822 -256.853962) (xy 129.501436 -256.83449) (xy 129.553398 -256.82263)
			(xy 129.606548 -256.818647) (xy 129.659698 -256.82263) (xy 129.71166 -256.83449) (xy 129.761274 -256.853962)
			(xy 129.807432 -256.880611) (xy 129.849103 -256.913842) (xy 129.885355 -256.952913) (xy 129.915379 -256.99695)
			(xy 129.938505 -257.044971) (xy 129.954215 -257.095901) (xy 129.962158 -257.148605) (xy 129.962656 -257.175254)
			(xy 129.962158 -257.201903) (xy 130.190738 -257.201903) (xy 130.190738 -257.148605) (xy 130.198681 -257.095901)
			(xy 130.214391 -257.044971) (xy 130.237517 -256.99695) (xy 130.267541 -256.952913) (xy 130.303793 -256.913842)
			(xy 130.345464 -256.880611) (xy 130.391622 -256.853962) (xy 130.441236 -256.83449) (xy 130.493198 -256.82263)
			(xy 130.546348 -256.818647) (xy 130.599498 -256.82263) (xy 130.65146 -256.83449) (xy 130.701074 -256.853962)
			(xy 130.747232 -256.880611) (xy 130.788903 -256.913842) (xy 130.825155 -256.952913) (xy 130.855179 -256.99695)
			(xy 130.878305 -257.044971) (xy 130.894015 -257.095901) (xy 130.901958 -257.148605) (xy 130.902456 -257.175254)
			(xy 130.901958 -257.201903) (xy 131.130538 -257.201903) (xy 131.130538 -257.148605) (xy 131.138481 -257.095901)
			(xy 131.154191 -257.044971) (xy 131.177317 -256.99695) (xy 131.207341 -256.952913) (xy 131.243593 -256.913842)
			(xy 131.285264 -256.880611) (xy 131.331422 -256.853962) (xy 131.381036 -256.83449) (xy 131.432998 -256.82263)
			(xy 131.486148 -256.818647) (xy 131.539298 -256.82263) (xy 131.59126 -256.83449) (xy 131.640874 -256.853962)
			(xy 131.687032 -256.880611) (xy 131.728703 -256.913842) (xy 131.764955 -256.952913) (xy 131.794979 -256.99695)
			(xy 131.818105 -257.044971) (xy 131.833815 -257.095901) (xy 131.841758 -257.148605) (xy 131.842256 -257.175254)
			(xy 131.841758 -257.201903) (xy 132.070084 -257.201903) (xy 132.070084 -257.148605) (xy 132.078027 -257.095901)
			(xy 132.093737 -257.044971) (xy 132.116863 -256.99695) (xy 132.146887 -256.952913) (xy 132.183139 -256.913842)
			(xy 132.22481 -256.880611) (xy 132.270968 -256.853962) (xy 132.320582 -256.83449) (xy 132.372544 -256.82263)
			(xy 132.425694 -256.818647) (xy 132.478844 -256.82263) (xy 132.530806 -256.83449) (xy 132.58042 -256.853962)
			(xy 132.626578 -256.880611) (xy 132.668249 -256.913842) (xy 132.704501 -256.952913) (xy 132.734525 -256.99695)
			(xy 132.757651 -257.044971) (xy 132.773361 -257.095901) (xy 132.781304 -257.148605) (xy 132.781802 -257.175254)
			(xy 132.781304 -257.201903) (xy 133.010138 -257.201903) (xy 133.010138 -257.148605) (xy 133.018081 -257.095901)
			(xy 133.033791 -257.044971) (xy 133.056917 -256.99695) (xy 133.086941 -256.952913) (xy 133.123193 -256.913842)
			(xy 133.164864 -256.880611) (xy 133.211022 -256.853962) (xy 133.260636 -256.83449) (xy 133.312598 -256.82263)
			(xy 133.365748 -256.818647) (xy 133.418898 -256.82263) (xy 133.47086 -256.83449) (xy 133.520474 -256.853962)
			(xy 133.566632 -256.880611) (xy 133.608303 -256.913842) (xy 133.644555 -256.952913) (xy 133.674579 -256.99695)
			(xy 133.697705 -257.044971) (xy 133.713415 -257.095901) (xy 133.721358 -257.148605) (xy 133.721856 -257.175254)
			(xy 133.721358 -257.201903) (xy 133.949684 -257.201903) (xy 133.949684 -257.148605) (xy 133.957627 -257.095901)
			(xy 133.973337 -257.044971) (xy 133.996463 -256.99695) (xy 134.026487 -256.952913) (xy 134.062739 -256.913842)
			(xy 134.10441 -256.880611) (xy 134.150568 -256.853962) (xy 134.200182 -256.83449) (xy 134.252144 -256.82263)
			(xy 134.305294 -256.818647) (xy 134.358444 -256.82263) (xy 134.410406 -256.83449) (xy 134.46002 -256.853962)
			(xy 134.506178 -256.880611) (xy 134.547849 -256.913842) (xy 134.584101 -256.952913) (xy 134.614125 -256.99695)
			(xy 134.637251 -257.044971) (xy 134.652961 -257.095901) (xy 134.660904 -257.148605) (xy 134.661402 -257.175254)
			(xy 134.660904 -257.201903) (xy 134.652961 -257.254607) (xy 134.637251 -257.305537) (xy 134.614125 -257.353558)
			(xy 134.584101 -257.397595) (xy 134.547849 -257.436666) (xy 134.506178 -257.469897) (xy 134.46002 -257.496546)
			(xy 134.410406 -257.516018) (xy 134.358444 -257.527878) (xy 134.305294 -257.531862) (xy 134.252144 -257.527878)
			(xy 134.200182 -257.516018) (xy 134.150568 -257.496546) (xy 134.10441 -257.469897) (xy 134.062739 -257.436666)
			(xy 134.026487 -257.397595) (xy 133.996463 -257.353558) (xy 133.973337 -257.305537) (xy 133.957627 -257.254607)
			(xy 133.949684 -257.201903) (xy 133.721358 -257.201903) (xy 133.713415 -257.254607) (xy 133.697705 -257.305537)
			(xy 133.674579 -257.353558) (xy 133.644555 -257.397595) (xy 133.608303 -257.436666) (xy 133.566632 -257.469897)
			(xy 133.520474 -257.496546) (xy 133.47086 -257.516018) (xy 133.418898 -257.527878) (xy 133.365748 -257.531862)
			(xy 133.312598 -257.527878) (xy 133.260636 -257.516018) (xy 133.211022 -257.496546) (xy 133.164864 -257.469897)
			(xy 133.123193 -257.436666) (xy 133.086941 -257.397595) (xy 133.056917 -257.353558) (xy 133.033791 -257.305537)
			(xy 133.018081 -257.254607) (xy 133.010138 -257.201903) (xy 132.781304 -257.201903) (xy 132.773361 -257.254607)
			(xy 132.757651 -257.305537) (xy 132.734525 -257.353558) (xy 132.704501 -257.397595) (xy 132.668249 -257.436666)
			(xy 132.626578 -257.469897) (xy 132.58042 -257.496546) (xy 132.530806 -257.516018) (xy 132.478844 -257.527878)
			(xy 132.425694 -257.531862) (xy 132.372544 -257.527878) (xy 132.320582 -257.516018) (xy 132.270968 -257.496546)
			(xy 132.22481 -257.469897) (xy 132.183139 -257.436666) (xy 132.146887 -257.397595) (xy 132.116863 -257.353558)
			(xy 132.093737 -257.305537) (xy 132.078027 -257.254607) (xy 132.070084 -257.201903) (xy 131.841758 -257.201903)
			(xy 131.833815 -257.254607) (xy 131.818105 -257.305537) (xy 131.794979 -257.353558) (xy 131.764955 -257.397595)
			(xy 131.728703 -257.436666) (xy 131.687032 -257.469897) (xy 131.640874 -257.496546) (xy 131.59126 -257.516018)
			(xy 131.539298 -257.527878) (xy 131.486148 -257.531862) (xy 131.432998 -257.527878) (xy 131.381036 -257.516018)
			(xy 131.331422 -257.496546) (xy 131.285264 -257.469897) (xy 131.243593 -257.436666) (xy 131.207341 -257.397595)
			(xy 131.177317 -257.353558) (xy 131.154191 -257.305537) (xy 131.138481 -257.254607) (xy 131.130538 -257.201903)
			(xy 130.901958 -257.201903) (xy 130.894015 -257.254607) (xy 130.878305 -257.305537) (xy 130.855179 -257.353558)
			(xy 130.825155 -257.397595) (xy 130.788903 -257.436666) (xy 130.747232 -257.469897) (xy 130.701074 -257.496546)
			(xy 130.65146 -257.516018) (xy 130.599498 -257.527878) (xy 130.546348 -257.531862) (xy 130.493198 -257.527878)
			(xy 130.441236 -257.516018) (xy 130.391622 -257.496546) (xy 130.345464 -257.469897) (xy 130.303793 -257.436666)
			(xy 130.267541 -257.397595) (xy 130.237517 -257.353558) (xy 130.214391 -257.305537) (xy 130.198681 -257.254607)
			(xy 130.190738 -257.201903) (xy 129.962158 -257.201903) (xy 129.954215 -257.254607) (xy 129.938505 -257.305537)
			(xy 129.915379 -257.353558) (xy 129.885355 -257.397595) (xy 129.849103 -257.436666) (xy 129.807432 -257.469897)
			(xy 129.761274 -257.496546) (xy 129.71166 -257.516018) (xy 129.659698 -257.527878) (xy 129.606548 -257.531862)
			(xy 129.553398 -257.527878) (xy 129.501436 -257.516018) (xy 129.451822 -257.496546) (xy 129.405664 -257.469897)
			(xy 129.363993 -257.436666) (xy 129.327741 -257.397595) (xy 129.297717 -257.353558) (xy 129.274591 -257.305537)
			(xy 129.258881 -257.254607) (xy 129.250938 -257.201903) (xy 129.022358 -257.201903) (xy 129.014415 -257.254607)
			(xy 128.998705 -257.305537) (xy 128.975579 -257.353558) (xy 128.945555 -257.397595) (xy 128.909303 -257.436666)
			(xy 128.867632 -257.469897) (xy 128.821474 -257.496546) (xy 128.77186 -257.516018) (xy 128.719898 -257.527878)
			(xy 128.666748 -257.531862) (xy 128.613598 -257.527878) (xy 128.561636 -257.516018) (xy 128.512022 -257.496546)
			(xy 128.465864 -257.469897) (xy 128.424193 -257.436666) (xy 128.387941 -257.397595) (xy 128.357917 -257.353558)
			(xy 128.334791 -257.305537) (xy 128.319081 -257.254607) (xy 128.311138 -257.201903) (xy 128.082304 -257.201903)
			(xy 128.074361 -257.254607) (xy 128.058651 -257.305537) (xy 128.035525 -257.353558) (xy 128.005501 -257.397595)
			(xy 127.969249 -257.436666) (xy 127.927578 -257.469897) (xy 127.88142 -257.496546) (xy 127.831806 -257.516018)
			(xy 127.779844 -257.527878) (xy 127.726694 -257.531862) (xy 127.673544 -257.527878) (xy 127.621582 -257.516018)
			(xy 127.571968 -257.496546) (xy 127.52581 -257.469897) (xy 127.484139 -257.436666) (xy 127.447887 -257.397595)
			(xy 127.417863 -257.353558) (xy 127.394737 -257.305537) (xy 127.379027 -257.254607) (xy 127.371084 -257.201903)
			(xy 127.142758 -257.201903) (xy 127.134815 -257.254607) (xy 127.119105 -257.305537) (xy 127.095979 -257.353558)
			(xy 127.065955 -257.397595) (xy 127.029703 -257.436666) (xy 126.988032 -257.469897) (xy 126.941874 -257.496546)
			(xy 126.89226 -257.516018) (xy 126.840298 -257.527878) (xy 126.787148 -257.531862) (xy 126.733998 -257.527878)
			(xy 126.682036 -257.516018) (xy 126.632422 -257.496546) (xy 126.586264 -257.469897) (xy 126.544593 -257.436666)
			(xy 126.508341 -257.397595) (xy 126.478317 -257.353558) (xy 126.455191 -257.305537) (xy 126.439481 -257.254607)
			(xy 126.431538 -257.201903) (xy 126.202704 -257.201903) (xy 126.194761 -257.254607) (xy 126.179051 -257.305537)
			(xy 126.155925 -257.353558) (xy 126.125901 -257.397595) (xy 126.089649 -257.436666) (xy 126.047978 -257.469897)
			(xy 126.00182 -257.496546) (xy 125.952206 -257.516018) (xy 125.900244 -257.527878) (xy 125.847094 -257.531862)
			(xy 125.793944 -257.527878) (xy 125.741982 -257.516018) (xy 125.692368 -257.496546) (xy 125.64621 -257.469897)
			(xy 125.604539 -257.436666) (xy 125.568287 -257.397595) (xy 125.538263 -257.353558) (xy 125.515137 -257.305537)
			(xy 125.499427 -257.254607) (xy 125.491484 -257.201903) (xy 125.262904 -257.201903) (xy 125.254961 -257.254607)
			(xy 125.239251 -257.305537) (xy 125.216125 -257.353558) (xy 125.186101 -257.397595) (xy 125.149849 -257.436666)
			(xy 125.108178 -257.469897) (xy 125.06202 -257.496546) (xy 125.012406 -257.516018) (xy 124.960444 -257.527878)
			(xy 124.907294 -257.531862) (xy 124.854144 -257.527878) (xy 124.802182 -257.516018) (xy 124.752568 -257.496546)
			(xy 124.70641 -257.469897) (xy 124.664739 -257.436666) (xy 124.628487 -257.397595) (xy 124.598463 -257.353558)
			(xy 124.575337 -257.305537) (xy 124.559627 -257.254607) (xy 124.551684 -257.201903) (xy 124.323358 -257.201903)
			(xy 124.315415 -257.254607) (xy 124.299705 -257.305537) (xy 124.276579 -257.353558) (xy 124.246555 -257.397595)
			(xy 124.210303 -257.436666) (xy 124.168632 -257.469897) (xy 124.122474 -257.496546) (xy 124.07286 -257.516018)
			(xy 124.020898 -257.527878) (xy 123.967748 -257.531862) (xy 123.914598 -257.527878) (xy 123.862636 -257.516018)
			(xy 123.813022 -257.496546) (xy 123.766864 -257.469897) (xy 123.725193 -257.436666) (xy 123.688941 -257.397595)
			(xy 123.658917 -257.353558) (xy 123.635791 -257.305537) (xy 123.620081 -257.254607) (xy 123.612138 -257.201903)
			(xy 123.383558 -257.201903) (xy 123.375615 -257.254607) (xy 123.359905 -257.305537) (xy 123.336779 -257.353558)
			(xy 123.306755 -257.397595) (xy 123.270503 -257.436666) (xy 123.228832 -257.469897) (xy 123.182674 -257.496546)
			(xy 123.13306 -257.516018) (xy 123.081098 -257.527878) (xy 123.027948 -257.531862) (xy 122.974798 -257.527878)
			(xy 122.922836 -257.516018) (xy 122.873222 -257.496546) (xy 122.827064 -257.469897) (xy 122.785393 -257.436666)
			(xy 122.749141 -257.397595) (xy 122.719117 -257.353558) (xy 122.695991 -257.305537) (xy 122.680281 -257.254607)
			(xy 122.672338 -257.201903) (xy 122.443758 -257.201903) (xy 122.435815 -257.254607) (xy 122.420105 -257.305537)
			(xy 122.396979 -257.353558) (xy 122.366955 -257.397595) (xy 122.330703 -257.436666) (xy 122.289032 -257.469897)
			(xy 122.242874 -257.496546) (xy 122.19326 -257.516018) (xy 122.141298 -257.527878) (xy 122.088148 -257.531862)
			(xy 122.034998 -257.527878) (xy 121.983036 -257.516018) (xy 121.933422 -257.496546) (xy 121.887264 -257.469897)
			(xy 121.845593 -257.436666) (xy 121.809341 -257.397595) (xy 121.779317 -257.353558) (xy 121.756191 -257.305537)
			(xy 121.740481 -257.254607) (xy 121.732538 -257.201903) (xy 121.323359 -257.201903) (xy 121.324393 -257.205322)
			(xy 121.332054 -257.257055) (xy 121.332498 -257.283204) (xy 121.331963 -257.311382) (xy 121.323088 -257.367034)
			(xy 121.305561 -257.420595) (xy 121.279819 -257.470727) (xy 121.246504 -257.516181) (xy 121.206447 -257.555821)
			(xy 121.160648 -257.58866) (xy 121.11025 -257.613878) (xy 121.056509 -257.630845) (xy 121.028714 -257.635502)
			(xy 120.98528 -257.641852) (xy 120.98528 -258.092956) (xy 121.028714 -258.099306) (xy 121.052552 -258.10325)
			(xy 121.098944 -258.116755) (xy 121.12117 -258.12623) (xy 121.135259 -258.13191) (xy 121.165394 -258.1356)
			(xy 121.195282 -258.130268) (xy 121.222283 -258.116386) (xy 121.24401 -258.09518) (xy 121.258545 -258.068525)
			(xy 121.264601 -258.038775) (xy 121.263664 -258.023614) (xy 121.261886 -257.98907) (xy 121.262394 -257.96199)
			(xy 121.2706 -257.908455) (xy 121.286817 -257.856779) (xy 121.310673 -257.808155) (xy 121.341617 -257.763705)
			(xy 121.378934 -257.724452) (xy 121.421766 -257.691304) (xy 121.469122 -257.665023) (xy 121.519913 -257.646216)
			(xy 121.572965 -257.635317) (xy 121.627057 -257.632577) (xy 121.680939 -257.63806) (xy 121.73337 -257.651638)
			(xy 121.78314 -257.672999) (xy 121.829101 -257.701651) (xy 121.870194 -257.736932) (xy 121.905471 -257.778028)
			(xy 121.934117 -257.823992) (xy 121.955474 -257.873765) (xy 121.969047 -257.926197) (xy 121.974524 -257.98008)
			(xy 121.972715 -258.015719) (xy 122.202184 -258.015719) (xy 122.202184 -257.962421) (xy 122.210127 -257.909717)
			(xy 122.225837 -257.858787) (xy 122.248963 -257.810766) (xy 122.278987 -257.766729) (xy 122.315239 -257.727658)
			(xy 122.35691 -257.694427) (xy 122.403068 -257.667778) (xy 122.452682 -257.648306) (xy 122.504644 -257.636446)
			(xy 122.557794 -257.632463) (xy 122.610944 -257.636446) (xy 122.662906 -257.648306) (xy 122.71252 -257.667778)
			(xy 122.758678 -257.694427) (xy 122.800349 -257.727658) (xy 122.836601 -257.766729) (xy 122.866625 -257.810766)
			(xy 122.889751 -257.858787) (xy 122.905461 -257.909717) (xy 122.913404 -257.962421) (xy 122.913902 -257.98907)
			(xy 122.913404 -258.015719) (xy 123.141984 -258.015719) (xy 123.141984 -257.962421) (xy 123.149927 -257.909717)
			(xy 123.165637 -257.858787) (xy 123.188763 -257.810766) (xy 123.218787 -257.766729) (xy 123.255039 -257.727658)
			(xy 123.29671 -257.694427) (xy 123.342868 -257.667778) (xy 123.392482 -257.648306) (xy 123.444444 -257.636446)
			(xy 123.497594 -257.632463) (xy 123.550744 -257.636446) (xy 123.602706 -257.648306) (xy 123.65232 -257.667778)
			(xy 123.698478 -257.694427) (xy 123.740149 -257.727658) (xy 123.776401 -257.766729) (xy 123.806425 -257.810766)
			(xy 123.829551 -257.858787) (xy 123.845261 -257.909717) (xy 123.853204 -257.962421) (xy 123.853702 -257.98907)
			(xy 123.853204 -258.015719) (xy 124.081784 -258.015719) (xy 124.081784 -257.962421) (xy 124.089727 -257.909717)
			(xy 124.105437 -257.858787) (xy 124.128563 -257.810766) (xy 124.158587 -257.766729) (xy 124.194839 -257.727658)
			(xy 124.23651 -257.694427) (xy 124.282668 -257.667778) (xy 124.332282 -257.648306) (xy 124.384244 -257.636446)
			(xy 124.437394 -257.632463) (xy 124.490544 -257.636446) (xy 124.542506 -257.648306) (xy 124.59212 -257.667778)
			(xy 124.638278 -257.694427) (xy 124.679949 -257.727658) (xy 124.716201 -257.766729) (xy 124.746225 -257.810766)
			(xy 124.769351 -257.858787) (xy 124.785061 -257.909717) (xy 124.793004 -257.962421) (xy 124.793502 -257.98907)
			(xy 124.793004 -258.015719) (xy 125.021838 -258.015719) (xy 125.021838 -257.962421) (xy 125.029781 -257.909717)
			(xy 125.045491 -257.858787) (xy 125.068617 -257.810766) (xy 125.098641 -257.766729) (xy 125.134893 -257.727658)
			(xy 125.176564 -257.694427) (xy 125.222722 -257.667778) (xy 125.272336 -257.648306) (xy 125.324298 -257.636446)
			(xy 125.377448 -257.632463) (xy 125.430598 -257.636446) (xy 125.48256 -257.648306) (xy 125.532174 -257.667778)
			(xy 125.578332 -257.694427) (xy 125.620003 -257.727658) (xy 125.656255 -257.766729) (xy 125.686279 -257.810766)
			(xy 125.709405 -257.858787) (xy 125.725115 -257.909717) (xy 125.733058 -257.962421) (xy 125.733556 -257.98907)
			(xy 125.733058 -258.015719) (xy 125.961384 -258.015719) (xy 125.961384 -257.962421) (xy 125.969327 -257.909717)
			(xy 125.985037 -257.858787) (xy 126.008163 -257.810766) (xy 126.038187 -257.766729) (xy 126.074439 -257.727658)
			(xy 126.11611 -257.694427) (xy 126.162268 -257.667778) (xy 126.211882 -257.648306) (xy 126.263844 -257.636446)
			(xy 126.316994 -257.632463) (xy 126.370144 -257.636446) (xy 126.422106 -257.648306) (xy 126.47172 -257.667778)
			(xy 126.517878 -257.694427) (xy 126.559549 -257.727658) (xy 126.595801 -257.766729) (xy 126.625825 -257.810766)
			(xy 126.648951 -257.858787) (xy 126.664661 -257.909717) (xy 126.672604 -257.962421) (xy 126.673102 -257.98907)
			(xy 126.672604 -258.015719) (xy 126.901438 -258.015719) (xy 126.901438 -257.962421) (xy 126.909381 -257.909717)
			(xy 126.925091 -257.858787) (xy 126.948217 -257.810766) (xy 126.978241 -257.766729) (xy 127.014493 -257.727658)
			(xy 127.056164 -257.694427) (xy 127.102322 -257.667778) (xy 127.151936 -257.648306) (xy 127.203898 -257.636446)
			(xy 127.257048 -257.632463) (xy 127.310198 -257.636446) (xy 127.36216 -257.648306) (xy 127.411774 -257.667778)
			(xy 127.457932 -257.694427) (xy 127.499603 -257.727658) (xy 127.535855 -257.766729) (xy 127.565879 -257.810766)
			(xy 127.589005 -257.858787) (xy 127.604715 -257.909717) (xy 127.612658 -257.962421) (xy 127.613156 -257.98907)
			(xy 127.612658 -258.015719) (xy 127.840984 -258.015719) (xy 127.840984 -257.962421) (xy 127.848927 -257.909717)
			(xy 127.864637 -257.858787) (xy 127.887763 -257.810766) (xy 127.917787 -257.766729) (xy 127.954039 -257.727658)
			(xy 127.99571 -257.694427) (xy 128.041868 -257.667778) (xy 128.091482 -257.648306) (xy 128.143444 -257.636446)
			(xy 128.196594 -257.632463) (xy 128.249744 -257.636446) (xy 128.301706 -257.648306) (xy 128.35132 -257.667778)
			(xy 128.397478 -257.694427) (xy 128.439149 -257.727658) (xy 128.475401 -257.766729) (xy 128.505425 -257.810766)
			(xy 128.528551 -257.858787) (xy 128.544261 -257.909717) (xy 128.552204 -257.962421) (xy 128.552702 -257.98907)
			(xy 128.552204 -258.015719) (xy 128.780784 -258.015719) (xy 128.780784 -257.962421) (xy 128.788727 -257.909717)
			(xy 128.804437 -257.858787) (xy 128.827563 -257.810766) (xy 128.857587 -257.766729) (xy 128.893839 -257.727658)
			(xy 128.93551 -257.694427) (xy 128.981668 -257.667778) (xy 129.031282 -257.648306) (xy 129.083244 -257.636446)
			(xy 129.136394 -257.632463) (xy 129.189544 -257.636446) (xy 129.241506 -257.648306) (xy 129.29112 -257.667778)
			(xy 129.337278 -257.694427) (xy 129.378949 -257.727658) (xy 129.415201 -257.766729) (xy 129.445225 -257.810766)
			(xy 129.468351 -257.858787) (xy 129.484061 -257.909717) (xy 129.492004 -257.962421) (xy 129.492502 -257.98907)
			(xy 129.492004 -258.015719) (xy 129.720584 -258.015719) (xy 129.720584 -257.962421) (xy 129.728527 -257.909717)
			(xy 129.744237 -257.858787) (xy 129.767363 -257.810766) (xy 129.797387 -257.766729) (xy 129.833639 -257.727658)
			(xy 129.87531 -257.694427) (xy 129.921468 -257.667778) (xy 129.971082 -257.648306) (xy 130.023044 -257.636446)
			(xy 130.076194 -257.632463) (xy 130.129344 -257.636446) (xy 130.181306 -257.648306) (xy 130.23092 -257.667778)
			(xy 130.277078 -257.694427) (xy 130.318749 -257.727658) (xy 130.355001 -257.766729) (xy 130.385025 -257.810766)
			(xy 130.408151 -257.858787) (xy 130.423861 -257.909717) (xy 130.431804 -257.962421) (xy 130.432302 -257.98907)
			(xy 130.431804 -258.015719) (xy 130.660384 -258.015719) (xy 130.660384 -257.962421) (xy 130.668327 -257.909717)
			(xy 130.684037 -257.858787) (xy 130.707163 -257.810766) (xy 130.737187 -257.766729) (xy 130.773439 -257.727658)
			(xy 130.81511 -257.694427) (xy 130.861268 -257.667778) (xy 130.910882 -257.648306) (xy 130.962844 -257.636446)
			(xy 131.015994 -257.632463) (xy 131.069144 -257.636446) (xy 131.121106 -257.648306) (xy 131.17072 -257.667778)
			(xy 131.216878 -257.694427) (xy 131.258549 -257.727658) (xy 131.294801 -257.766729) (xy 131.324825 -257.810766)
			(xy 131.347951 -257.858787) (xy 131.363661 -257.909717) (xy 131.371604 -257.962421) (xy 131.372102 -257.98907)
			(xy 131.371604 -258.015719) (xy 131.600438 -258.015719) (xy 131.600438 -257.962421) (xy 131.608381 -257.909717)
			(xy 131.624091 -257.858787) (xy 131.647217 -257.810766) (xy 131.677241 -257.766729) (xy 131.713493 -257.727658)
			(xy 131.755164 -257.694427) (xy 131.801322 -257.667778) (xy 131.850936 -257.648306) (xy 131.902898 -257.636446)
			(xy 131.956048 -257.632463) (xy 132.009198 -257.636446) (xy 132.06116 -257.648306) (xy 132.110774 -257.667778)
			(xy 132.156932 -257.694427) (xy 132.198603 -257.727658) (xy 132.234855 -257.766729) (xy 132.264879 -257.810766)
			(xy 132.288005 -257.858787) (xy 132.303715 -257.909717) (xy 132.311658 -257.962421) (xy 132.312156 -257.98907)
			(xy 132.311658 -258.015719) (xy 132.539984 -258.015719) (xy 132.539984 -257.962421) (xy 132.547927 -257.909717)
			(xy 132.563637 -257.858787) (xy 132.586763 -257.810766) (xy 132.616787 -257.766729) (xy 132.653039 -257.727658)
			(xy 132.69471 -257.694427) (xy 132.740868 -257.667778) (xy 132.790482 -257.648306) (xy 132.842444 -257.636446)
			(xy 132.895594 -257.632463) (xy 132.948744 -257.636446) (xy 133.000706 -257.648306) (xy 133.05032 -257.667778)
			(xy 133.096478 -257.694427) (xy 133.138149 -257.727658) (xy 133.174401 -257.766729) (xy 133.204425 -257.810766)
			(xy 133.227551 -257.858787) (xy 133.243261 -257.909717) (xy 133.251204 -257.962421) (xy 133.251702 -257.98907)
			(xy 133.251204 -258.015719) (xy 133.480038 -258.015719) (xy 133.480038 -257.962421) (xy 133.487981 -257.909717)
			(xy 133.503691 -257.858787) (xy 133.526817 -257.810766) (xy 133.556841 -257.766729) (xy 133.593093 -257.727658)
			(xy 133.634764 -257.694427) (xy 133.680922 -257.667778) (xy 133.730536 -257.648306) (xy 133.782498 -257.636446)
			(xy 133.835648 -257.632463) (xy 133.888798 -257.636446) (xy 133.94076 -257.648306) (xy 133.990374 -257.667778)
			(xy 134.036532 -257.694427) (xy 134.078203 -257.727658) (xy 134.114455 -257.766729) (xy 134.144479 -257.810766)
			(xy 134.167605 -257.858787) (xy 134.183315 -257.909717) (xy 134.191258 -257.962421) (xy 134.191756 -257.98907)
			(xy 134.191258 -258.015719) (xy 134.183315 -258.068423) (xy 134.167605 -258.119353) (xy 134.144479 -258.167374)
			(xy 134.114455 -258.211411) (xy 134.078203 -258.250482) (xy 134.036532 -258.283713) (xy 133.990374 -258.310362)
			(xy 133.94076 -258.329834) (xy 133.888798 -258.341694) (xy 133.835648 -258.345678) (xy 133.782498 -258.341694)
			(xy 133.730536 -258.329834) (xy 133.680922 -258.310362) (xy 133.634764 -258.283713) (xy 133.593093 -258.250482)
			(xy 133.556841 -258.211411) (xy 133.526817 -258.167374) (xy 133.503691 -258.119353) (xy 133.487981 -258.068423)
			(xy 133.480038 -258.015719) (xy 133.251204 -258.015719) (xy 133.243261 -258.068423) (xy 133.227551 -258.119353)
			(xy 133.204425 -258.167374) (xy 133.174401 -258.211411) (xy 133.138149 -258.250482) (xy 133.096478 -258.283713)
			(xy 133.05032 -258.310362) (xy 133.000706 -258.329834) (xy 132.948744 -258.341694) (xy 132.895594 -258.345678)
			(xy 132.842444 -258.341694) (xy 132.790482 -258.329834) (xy 132.740868 -258.310362) (xy 132.69471 -258.283713)
			(xy 132.653039 -258.250482) (xy 132.616787 -258.211411) (xy 132.586763 -258.167374) (xy 132.563637 -258.119353)
			(xy 132.547927 -258.068423) (xy 132.539984 -258.015719) (xy 132.311658 -258.015719) (xy 132.303715 -258.068423)
			(xy 132.288005 -258.119353) (xy 132.264879 -258.167374) (xy 132.234855 -258.211411) (xy 132.198603 -258.250482)
			(xy 132.156932 -258.283713) (xy 132.110774 -258.310362) (xy 132.06116 -258.329834) (xy 132.009198 -258.341694)
			(xy 131.956048 -258.345678) (xy 131.902898 -258.341694) (xy 131.850936 -258.329834) (xy 131.801322 -258.310362)
			(xy 131.755164 -258.283713) (xy 131.713493 -258.250482) (xy 131.677241 -258.211411) (xy 131.647217 -258.167374)
			(xy 131.624091 -258.119353) (xy 131.608381 -258.068423) (xy 131.600438 -258.015719) (xy 131.371604 -258.015719)
			(xy 131.363661 -258.068423) (xy 131.347951 -258.119353) (xy 131.324825 -258.167374) (xy 131.294801 -258.211411)
			(xy 131.258549 -258.250482) (xy 131.216878 -258.283713) (xy 131.17072 -258.310362) (xy 131.121106 -258.329834)
			(xy 131.069144 -258.341694) (xy 131.015994 -258.345678) (xy 130.962844 -258.341694) (xy 130.910882 -258.329834)
			(xy 130.861268 -258.310362) (xy 130.81511 -258.283713) (xy 130.773439 -258.250482) (xy 130.737187 -258.211411)
			(xy 130.707163 -258.167374) (xy 130.684037 -258.119353) (xy 130.668327 -258.068423) (xy 130.660384 -258.015719)
			(xy 130.431804 -258.015719) (xy 130.423861 -258.068423) (xy 130.408151 -258.119353) (xy 130.385025 -258.167374)
			(xy 130.355001 -258.211411) (xy 130.318749 -258.250482) (xy 130.277078 -258.283713) (xy 130.23092 -258.310362)
			(xy 130.181306 -258.329834) (xy 130.129344 -258.341694) (xy 130.076194 -258.345678) (xy 130.023044 -258.341694)
			(xy 129.971082 -258.329834) (xy 129.921468 -258.310362) (xy 129.87531 -258.283713) (xy 129.833639 -258.250482)
			(xy 129.797387 -258.211411) (xy 129.767363 -258.167374) (xy 129.744237 -258.119353) (xy 129.728527 -258.068423)
			(xy 129.720584 -258.015719) (xy 129.492004 -258.015719) (xy 129.484061 -258.068423) (xy 129.468351 -258.119353)
			(xy 129.445225 -258.167374) (xy 129.415201 -258.211411) (xy 129.378949 -258.250482) (xy 129.337278 -258.283713)
			(xy 129.29112 -258.310362) (xy 129.241506 -258.329834) (xy 129.189544 -258.341694) (xy 129.136394 -258.345678)
			(xy 129.083244 -258.341694) (xy 129.031282 -258.329834) (xy 128.981668 -258.310362) (xy 128.93551 -258.283713)
			(xy 128.893839 -258.250482) (xy 128.857587 -258.211411) (xy 128.827563 -258.167374) (xy 128.804437 -258.119353)
			(xy 128.788727 -258.068423) (xy 128.780784 -258.015719) (xy 128.552204 -258.015719) (xy 128.544261 -258.068423)
			(xy 128.528551 -258.119353) (xy 128.505425 -258.167374) (xy 128.475401 -258.211411) (xy 128.439149 -258.250482)
			(xy 128.397478 -258.283713) (xy 128.35132 -258.310362) (xy 128.301706 -258.329834) (xy 128.249744 -258.341694)
			(xy 128.196594 -258.345678) (xy 128.143444 -258.341694) (xy 128.091482 -258.329834) (xy 128.041868 -258.310362)
			(xy 127.99571 -258.283713) (xy 127.954039 -258.250482) (xy 127.917787 -258.211411) (xy 127.887763 -258.167374)
			(xy 127.864637 -258.119353) (xy 127.848927 -258.068423) (xy 127.840984 -258.015719) (xy 127.612658 -258.015719)
			(xy 127.604715 -258.068423) (xy 127.589005 -258.119353) (xy 127.565879 -258.167374) (xy 127.535855 -258.211411)
			(xy 127.499603 -258.250482) (xy 127.457932 -258.283713) (xy 127.411774 -258.310362) (xy 127.36216 -258.329834)
			(xy 127.310198 -258.341694) (xy 127.257048 -258.345678) (xy 127.203898 -258.341694) (xy 127.151936 -258.329834)
			(xy 127.102322 -258.310362) (xy 127.056164 -258.283713) (xy 127.014493 -258.250482) (xy 126.978241 -258.211411)
			(xy 126.948217 -258.167374) (xy 126.925091 -258.119353) (xy 126.909381 -258.068423) (xy 126.901438 -258.015719)
			(xy 126.672604 -258.015719) (xy 126.664661 -258.068423) (xy 126.648951 -258.119353) (xy 126.625825 -258.167374)
			(xy 126.595801 -258.211411) (xy 126.559549 -258.250482) (xy 126.517878 -258.283713) (xy 126.47172 -258.310362)
			(xy 126.422106 -258.329834) (xy 126.370144 -258.341694) (xy 126.316994 -258.345678) (xy 126.263844 -258.341694)
			(xy 126.211882 -258.329834) (xy 126.162268 -258.310362) (xy 126.11611 -258.283713) (xy 126.074439 -258.250482)
			(xy 126.038187 -258.211411) (xy 126.008163 -258.167374) (xy 125.985037 -258.119353) (xy 125.969327 -258.068423)
			(xy 125.961384 -258.015719) (xy 125.733058 -258.015719) (xy 125.725115 -258.068423) (xy 125.709405 -258.119353)
			(xy 125.686279 -258.167374) (xy 125.656255 -258.211411) (xy 125.620003 -258.250482) (xy 125.578332 -258.283713)
			(xy 125.532174 -258.310362) (xy 125.48256 -258.329834) (xy 125.430598 -258.341694) (xy 125.377448 -258.345678)
			(xy 125.324298 -258.341694) (xy 125.272336 -258.329834) (xy 125.222722 -258.310362) (xy 125.176564 -258.283713)
			(xy 125.134893 -258.250482) (xy 125.098641 -258.211411) (xy 125.068617 -258.167374) (xy 125.045491 -258.119353)
			(xy 125.029781 -258.068423) (xy 125.021838 -258.015719) (xy 124.793004 -258.015719) (xy 124.785061 -258.068423)
			(xy 124.769351 -258.119353) (xy 124.746225 -258.167374) (xy 124.716201 -258.211411) (xy 124.679949 -258.250482)
			(xy 124.638278 -258.283713) (xy 124.59212 -258.310362) (xy 124.542506 -258.329834) (xy 124.490544 -258.341694)
			(xy 124.437394 -258.345678) (xy 124.384244 -258.341694) (xy 124.332282 -258.329834) (xy 124.282668 -258.310362)
			(xy 124.23651 -258.283713) (xy 124.194839 -258.250482) (xy 124.158587 -258.211411) (xy 124.128563 -258.167374)
			(xy 124.105437 -258.119353) (xy 124.089727 -258.068423) (xy 124.081784 -258.015719) (xy 123.853204 -258.015719)
			(xy 123.845261 -258.068423) (xy 123.829551 -258.119353) (xy 123.806425 -258.167374) (xy 123.776401 -258.211411)
			(xy 123.740149 -258.250482) (xy 123.698478 -258.283713) (xy 123.65232 -258.310362) (xy 123.602706 -258.329834)
			(xy 123.550744 -258.341694) (xy 123.497594 -258.345678) (xy 123.444444 -258.341694) (xy 123.392482 -258.329834)
			(xy 123.342868 -258.310362) (xy 123.29671 -258.283713) (xy 123.255039 -258.250482) (xy 123.218787 -258.211411)
			(xy 123.188763 -258.167374) (xy 123.165637 -258.119353) (xy 123.149927 -258.068423) (xy 123.141984 -258.015719)
			(xy 122.913404 -258.015719) (xy 122.905461 -258.068423) (xy 122.889751 -258.119353) (xy 122.866625 -258.167374)
			(xy 122.836601 -258.211411) (xy 122.800349 -258.250482) (xy 122.758678 -258.283713) (xy 122.71252 -258.310362)
			(xy 122.662906 -258.329834) (xy 122.610944 -258.341694) (xy 122.557794 -258.345678) (xy 122.504644 -258.341694)
			(xy 122.452682 -258.329834) (xy 122.403068 -258.310362) (xy 122.35691 -258.283713) (xy 122.315239 -258.250482)
			(xy 122.278987 -258.211411) (xy 122.248963 -258.167374) (xy 122.225837 -258.119353) (xy 122.210127 -258.068423)
			(xy 122.202184 -258.015719) (xy 121.972715 -258.015719) (xy 121.971779 -258.03417) (xy 121.960874 -258.087222)
			(xy 121.942062 -258.13801) (xy 121.915777 -258.185365) (xy 121.882623 -258.228192) (xy 121.843367 -258.265506)
			(xy 121.798913 -258.296445) (xy 121.750287 -258.320296) (xy 121.69861 -258.336508) (xy 121.645074 -258.344709)
			(xy 121.617994 -258.345178) (xy 121.593135 -258.344746) (xy 121.543901 -258.337834) (xy 121.496105 -258.324146)
			(xy 121.473214 -258.314444) (xy 121.459125 -258.308767) (xy 121.428992 -258.305084) (xy 121.399106 -258.310418)
			(xy 121.372108 -258.3243) (xy 121.350381 -258.345502) (xy 121.335845 -258.372154) (xy 121.329783 -258.4019)
			(xy 121.33072 -258.41706) (xy 121.332498 -258.451604) (xy 121.331963 -258.479782) (xy 121.323088 -258.535434)
			(xy 121.305561 -258.588995) (xy 121.279819 -258.639127) (xy 121.246504 -258.684581) (xy 121.206447 -258.724221)
			(xy 121.160648 -258.75706) (xy 121.11025 -258.782278) (xy 121.056509 -258.799245) (xy 121.028714 -258.803902)
			(xy 120.98528 -258.810252) (xy 120.98528 -258.829789) (xy 121.732284 -258.829789) (xy 121.732284 -258.776491)
			(xy 121.740227 -258.723787) (xy 121.755937 -258.672857) (xy 121.779063 -258.624836) (xy 121.809087 -258.580799)
			(xy 121.845339 -258.541728) (xy 121.88701 -258.508497) (xy 121.933168 -258.481848) (xy 121.982782 -258.462376)
			(xy 122.034744 -258.450516) (xy 122.087894 -258.446533) (xy 122.141044 -258.450516) (xy 122.193006 -258.462376)
			(xy 122.24262 -258.481848) (xy 122.288778 -258.508497) (xy 122.330449 -258.541728) (xy 122.366701 -258.580799)
			(xy 122.396725 -258.624836) (xy 122.419851 -258.672857) (xy 122.435561 -258.723787) (xy 122.443504 -258.776491)
			(xy 122.444002 -258.80314) (xy 122.443504 -258.829789) (xy 122.672084 -258.829789) (xy 122.672084 -258.776491)
			(xy 122.680027 -258.723787) (xy 122.695737 -258.672857) (xy 122.718863 -258.624836) (xy 122.748887 -258.580799)
			(xy 122.785139 -258.541728) (xy 122.82681 -258.508497) (xy 122.872968 -258.481848) (xy 122.922582 -258.462376)
			(xy 122.974544 -258.450516) (xy 123.027694 -258.446533) (xy 123.080844 -258.450516) (xy 123.132806 -258.462376)
			(xy 123.18242 -258.481848) (xy 123.228578 -258.508497) (xy 123.270249 -258.541728) (xy 123.306501 -258.580799)
			(xy 123.336525 -258.624836) (xy 123.359651 -258.672857) (xy 123.375361 -258.723787) (xy 123.383304 -258.776491)
			(xy 123.383802 -258.80314) (xy 123.383304 -258.829789) (xy 123.612138 -258.829789) (xy 123.612138 -258.776491)
			(xy 123.620081 -258.723787) (xy 123.635791 -258.672857) (xy 123.658917 -258.624836) (xy 123.688941 -258.580799)
			(xy 123.725193 -258.541728) (xy 123.766864 -258.508497) (xy 123.813022 -258.481848) (xy 123.862636 -258.462376)
			(xy 123.914598 -258.450516) (xy 123.967748 -258.446533) (xy 124.020898 -258.450516) (xy 124.07286 -258.462376)
			(xy 124.122474 -258.481848) (xy 124.168632 -258.508497) (xy 124.210303 -258.541728) (xy 124.246555 -258.580799)
			(xy 124.276579 -258.624836) (xy 124.299705 -258.672857) (xy 124.315415 -258.723787) (xy 124.323358 -258.776491)
			(xy 124.323856 -258.80314) (xy 124.323358 -258.829789) (xy 124.551938 -258.829789) (xy 124.551938 -258.776491)
			(xy 124.559881 -258.723787) (xy 124.575591 -258.672857) (xy 124.598717 -258.624836) (xy 124.628741 -258.580799)
			(xy 124.664993 -258.541728) (xy 124.706664 -258.508497) (xy 124.752822 -258.481848) (xy 124.802436 -258.462376)
			(xy 124.854398 -258.450516) (xy 124.907548 -258.446533) (xy 124.960698 -258.450516) (xy 125.01266 -258.462376)
			(xy 125.062274 -258.481848) (xy 125.108432 -258.508497) (xy 125.150103 -258.541728) (xy 125.186355 -258.580799)
			(xy 125.216379 -258.624836) (xy 125.239505 -258.672857) (xy 125.255215 -258.723787) (xy 125.263158 -258.776491)
			(xy 125.263656 -258.80314) (xy 125.263158 -258.829789) (xy 125.491738 -258.829789) (xy 125.491738 -258.776491)
			(xy 125.499681 -258.723787) (xy 125.515391 -258.672857) (xy 125.538517 -258.624836) (xy 125.568541 -258.580799)
			(xy 125.604793 -258.541728) (xy 125.646464 -258.508497) (xy 125.692622 -258.481848) (xy 125.742236 -258.462376)
			(xy 125.794198 -258.450516) (xy 125.847348 -258.446533) (xy 125.900498 -258.450516) (xy 125.95246 -258.462376)
			(xy 126.002074 -258.481848) (xy 126.048232 -258.508497) (xy 126.089903 -258.541728) (xy 126.126155 -258.580799)
			(xy 126.156179 -258.624836) (xy 126.179305 -258.672857) (xy 126.195015 -258.723787) (xy 126.202958 -258.776491)
			(xy 126.203456 -258.80314) (xy 126.202958 -258.829789) (xy 126.431538 -258.829789) (xy 126.431538 -258.776491)
			(xy 126.439481 -258.723787) (xy 126.455191 -258.672857) (xy 126.478317 -258.624836) (xy 126.508341 -258.580799)
			(xy 126.544593 -258.541728) (xy 126.586264 -258.508497) (xy 126.632422 -258.481848) (xy 126.682036 -258.462376)
			(xy 126.733998 -258.450516) (xy 126.787148 -258.446533) (xy 126.840298 -258.450516) (xy 126.89226 -258.462376)
			(xy 126.941874 -258.481848) (xy 126.988032 -258.508497) (xy 127.029703 -258.541728) (xy 127.065955 -258.580799)
			(xy 127.095979 -258.624836) (xy 127.119105 -258.672857) (xy 127.134815 -258.723787) (xy 127.142758 -258.776491)
			(xy 127.143256 -258.80314) (xy 127.142758 -258.829789) (xy 127.371338 -258.829789) (xy 127.371338 -258.776491)
			(xy 127.379281 -258.723787) (xy 127.394991 -258.672857) (xy 127.418117 -258.624836) (xy 127.448141 -258.580799)
			(xy 127.484393 -258.541728) (xy 127.526064 -258.508497) (xy 127.572222 -258.481848) (xy 127.621836 -258.462376)
			(xy 127.673798 -258.450516) (xy 127.726948 -258.446533) (xy 127.780098 -258.450516) (xy 127.83206 -258.462376)
			(xy 127.881674 -258.481848) (xy 127.927832 -258.508497) (xy 127.969503 -258.541728) (xy 128.005755 -258.580799)
			(xy 128.035779 -258.624836) (xy 128.058905 -258.672857) (xy 128.074615 -258.723787) (xy 128.082558 -258.776491)
			(xy 128.083056 -258.80314) (xy 128.082558 -258.829789) (xy 128.311138 -258.829789) (xy 128.311138 -258.776491)
			(xy 128.319081 -258.723787) (xy 128.334791 -258.672857) (xy 128.357917 -258.624836) (xy 128.387941 -258.580799)
			(xy 128.424193 -258.541728) (xy 128.465864 -258.508497) (xy 128.512022 -258.481848) (xy 128.561636 -258.462376)
			(xy 128.613598 -258.450516) (xy 128.666748 -258.446533) (xy 128.719898 -258.450516) (xy 128.77186 -258.462376)
			(xy 128.821474 -258.481848) (xy 128.867632 -258.508497) (xy 128.909303 -258.541728) (xy 128.945555 -258.580799)
			(xy 128.975579 -258.624836) (xy 128.998705 -258.672857) (xy 129.014415 -258.723787) (xy 129.022358 -258.776491)
			(xy 129.022856 -258.80314) (xy 129.022358 -258.829789) (xy 129.250684 -258.829789) (xy 129.250684 -258.776491)
			(xy 129.258627 -258.723787) (xy 129.274337 -258.672857) (xy 129.297463 -258.624836) (xy 129.327487 -258.580799)
			(xy 129.363739 -258.541728) (xy 129.40541 -258.508497) (xy 129.451568 -258.481848) (xy 129.501182 -258.462376)
			(xy 129.553144 -258.450516) (xy 129.606294 -258.446533) (xy 129.659444 -258.450516) (xy 129.711406 -258.462376)
			(xy 129.76102 -258.481848) (xy 129.807178 -258.508497) (xy 129.848849 -258.541728) (xy 129.885101 -258.580799)
			(xy 129.915125 -258.624836) (xy 129.938251 -258.672857) (xy 129.953961 -258.723787) (xy 129.961904 -258.776491)
			(xy 129.962402 -258.80314) (xy 129.961904 -258.829789) (xy 130.190738 -258.829789) (xy 130.190738 -258.776491)
			(xy 130.198681 -258.723787) (xy 130.214391 -258.672857) (xy 130.237517 -258.624836) (xy 130.267541 -258.580799)
			(xy 130.303793 -258.541728) (xy 130.345464 -258.508497) (xy 130.391622 -258.481848) (xy 130.441236 -258.462376)
			(xy 130.493198 -258.450516) (xy 130.546348 -258.446533) (xy 130.599498 -258.450516) (xy 130.65146 -258.462376)
			(xy 130.701074 -258.481848) (xy 130.747232 -258.508497) (xy 130.788903 -258.541728) (xy 130.825155 -258.580799)
			(xy 130.855179 -258.624836) (xy 130.878305 -258.672857) (xy 130.894015 -258.723787) (xy 130.901958 -258.776491)
			(xy 130.902456 -258.80314) (xy 130.901958 -258.829789) (xy 131.130538 -258.829789) (xy 131.130538 -258.776491)
			(xy 131.138481 -258.723787) (xy 131.154191 -258.672857) (xy 131.177317 -258.624836) (xy 131.207341 -258.580799)
			(xy 131.243593 -258.541728) (xy 131.285264 -258.508497) (xy 131.331422 -258.481848) (xy 131.381036 -258.462376)
			(xy 131.432998 -258.450516) (xy 131.486148 -258.446533) (xy 131.539298 -258.450516) (xy 131.59126 -258.462376)
			(xy 131.640874 -258.481848) (xy 131.687032 -258.508497) (xy 131.728703 -258.541728) (xy 131.764955 -258.580799)
			(xy 131.794979 -258.624836) (xy 131.818105 -258.672857) (xy 131.833815 -258.723787) (xy 131.841758 -258.776491)
			(xy 131.842256 -258.80314) (xy 131.841758 -258.829789) (xy 132.070338 -258.829789) (xy 132.070338 -258.776491)
			(xy 132.078281 -258.723787) (xy 132.093991 -258.672857) (xy 132.117117 -258.624836) (xy 132.147141 -258.580799)
			(xy 132.183393 -258.541728) (xy 132.225064 -258.508497) (xy 132.271222 -258.481848) (xy 132.320836 -258.462376)
			(xy 132.372798 -258.450516) (xy 132.425948 -258.446533) (xy 132.479098 -258.450516) (xy 132.53106 -258.462376)
			(xy 132.580674 -258.481848) (xy 132.626832 -258.508497) (xy 132.668503 -258.541728) (xy 132.704755 -258.580799)
			(xy 132.734779 -258.624836) (xy 132.757905 -258.672857) (xy 132.773615 -258.723787) (xy 132.781558 -258.776491)
			(xy 132.782056 -258.80314) (xy 132.781558 -258.829789) (xy 133.010138 -258.829789) (xy 133.010138 -258.776491)
			(xy 133.018081 -258.723787) (xy 133.033791 -258.672857) (xy 133.056917 -258.624836) (xy 133.086941 -258.580799)
			(xy 133.123193 -258.541728) (xy 133.164864 -258.508497) (xy 133.211022 -258.481848) (xy 133.260636 -258.462376)
			(xy 133.312598 -258.450516) (xy 133.365748 -258.446533) (xy 133.418898 -258.450516) (xy 133.47086 -258.462376)
			(xy 133.520474 -258.481848) (xy 133.566632 -258.508497) (xy 133.608303 -258.541728) (xy 133.644555 -258.580799)
			(xy 133.674579 -258.624836) (xy 133.697705 -258.672857) (xy 133.713415 -258.723787) (xy 133.721358 -258.776491)
			(xy 133.721856 -258.80314) (xy 133.721358 -258.829789) (xy 133.949938 -258.829789) (xy 133.949938 -258.776491)
			(xy 133.957881 -258.723787) (xy 133.973591 -258.672857) (xy 133.996717 -258.624836) (xy 134.026741 -258.580799)
			(xy 134.062993 -258.541728) (xy 134.104664 -258.508497) (xy 134.150822 -258.481848) (xy 134.200436 -258.462376)
			(xy 134.252398 -258.450516) (xy 134.305548 -258.446533) (xy 134.358698 -258.450516) (xy 134.41066 -258.462376)
			(xy 134.460274 -258.481848) (xy 134.506432 -258.508497) (xy 134.548103 -258.541728) (xy 134.584355 -258.580799)
			(xy 134.614379 -258.624836) (xy 134.637505 -258.672857) (xy 134.653215 -258.723787) (xy 134.661158 -258.776491)
			(xy 134.661656 -258.80314) (xy 134.661158 -258.829789) (xy 134.653215 -258.882493) (xy 134.637505 -258.933423)
			(xy 134.614379 -258.981444) (xy 134.584355 -259.025481) (xy 134.548103 -259.064552) (xy 134.506432 -259.097783)
			(xy 134.460274 -259.124432) (xy 134.41066 -259.143904) (xy 134.358698 -259.155764) (xy 134.305548 -259.159748)
			(xy 134.252398 -259.155764) (xy 134.200436 -259.143904) (xy 134.150822 -259.124432) (xy 134.104664 -259.097783)
			(xy 134.062993 -259.064552) (xy 134.026741 -259.025481) (xy 133.996717 -258.981444) (xy 133.973591 -258.933423)
			(xy 133.957881 -258.882493) (xy 133.949938 -258.829789) (xy 133.721358 -258.829789) (xy 133.713415 -258.882493)
			(xy 133.697705 -258.933423) (xy 133.674579 -258.981444) (xy 133.644555 -259.025481) (xy 133.608303 -259.064552)
			(xy 133.566632 -259.097783) (xy 133.520474 -259.124432) (xy 133.47086 -259.143904) (xy 133.418898 -259.155764)
			(xy 133.365748 -259.159748) (xy 133.312598 -259.155764) (xy 133.260636 -259.143904) (xy 133.211022 -259.124432)
			(xy 133.164864 -259.097783) (xy 133.123193 -259.064552) (xy 133.086941 -259.025481) (xy 133.056917 -258.981444)
			(xy 133.033791 -258.933423) (xy 133.018081 -258.882493) (xy 133.010138 -258.829789) (xy 132.781558 -258.829789)
			(xy 132.773615 -258.882493) (xy 132.757905 -258.933423) (xy 132.734779 -258.981444) (xy 132.704755 -259.025481)
			(xy 132.668503 -259.064552) (xy 132.626832 -259.097783) (xy 132.580674 -259.124432) (xy 132.53106 -259.143904)
			(xy 132.479098 -259.155764) (xy 132.425948 -259.159748) (xy 132.372798 -259.155764) (xy 132.320836 -259.143904)
			(xy 132.271222 -259.124432) (xy 132.225064 -259.097783) (xy 132.183393 -259.064552) (xy 132.147141 -259.025481)
			(xy 132.117117 -258.981444) (xy 132.093991 -258.933423) (xy 132.078281 -258.882493) (xy 132.070338 -258.829789)
			(xy 131.841758 -258.829789) (xy 131.833815 -258.882493) (xy 131.818105 -258.933423) (xy 131.794979 -258.981444)
			(xy 131.764955 -259.025481) (xy 131.728703 -259.064552) (xy 131.687032 -259.097783) (xy 131.640874 -259.124432)
			(xy 131.59126 -259.143904) (xy 131.539298 -259.155764) (xy 131.486148 -259.159748) (xy 131.432998 -259.155764)
			(xy 131.381036 -259.143904) (xy 131.331422 -259.124432) (xy 131.285264 -259.097783) (xy 131.243593 -259.064552)
			(xy 131.207341 -259.025481) (xy 131.177317 -258.981444) (xy 131.154191 -258.933423) (xy 131.138481 -258.882493)
			(xy 131.130538 -258.829789) (xy 130.901958 -258.829789) (xy 130.894015 -258.882493) (xy 130.878305 -258.933423)
			(xy 130.855179 -258.981444) (xy 130.825155 -259.025481) (xy 130.788903 -259.064552) (xy 130.747232 -259.097783)
			(xy 130.701074 -259.124432) (xy 130.65146 -259.143904) (xy 130.599498 -259.155764) (xy 130.546348 -259.159748)
			(xy 130.493198 -259.155764) (xy 130.441236 -259.143904) (xy 130.391622 -259.124432) (xy 130.345464 -259.097783)
			(xy 130.303793 -259.064552) (xy 130.267541 -259.025481) (xy 130.237517 -258.981444) (xy 130.214391 -258.933423)
			(xy 130.198681 -258.882493) (xy 130.190738 -258.829789) (xy 129.961904 -258.829789) (xy 129.953961 -258.882493)
			(xy 129.938251 -258.933423) (xy 129.915125 -258.981444) (xy 129.885101 -259.025481) (xy 129.848849 -259.064552)
			(xy 129.807178 -259.097783) (xy 129.76102 -259.124432) (xy 129.711406 -259.143904) (xy 129.659444 -259.155764)
			(xy 129.606294 -259.159748) (xy 129.553144 -259.155764) (xy 129.501182 -259.143904) (xy 129.451568 -259.124432)
			(xy 129.40541 -259.097783) (xy 129.363739 -259.064552) (xy 129.327487 -259.025481) (xy 129.297463 -258.981444)
			(xy 129.274337 -258.933423) (xy 129.258627 -258.882493) (xy 129.250684 -258.829789) (xy 129.022358 -258.829789)
			(xy 129.014415 -258.882493) (xy 128.998705 -258.933423) (xy 128.975579 -258.981444) (xy 128.945555 -259.025481)
			(xy 128.909303 -259.064552) (xy 128.867632 -259.097783) (xy 128.821474 -259.124432) (xy 128.77186 -259.143904)
			(xy 128.719898 -259.155764) (xy 128.666748 -259.159748) (xy 128.613598 -259.155764) (xy 128.561636 -259.143904)
			(xy 128.512022 -259.124432) (xy 128.465864 -259.097783) (xy 128.424193 -259.064552) (xy 128.387941 -259.025481)
			(xy 128.357917 -258.981444) (xy 128.334791 -258.933423) (xy 128.319081 -258.882493) (xy 128.311138 -258.829789)
			(xy 128.082558 -258.829789) (xy 128.074615 -258.882493) (xy 128.058905 -258.933423) (xy 128.035779 -258.981444)
			(xy 128.005755 -259.025481) (xy 127.969503 -259.064552) (xy 127.927832 -259.097783) (xy 127.881674 -259.124432)
			(xy 127.83206 -259.143904) (xy 127.780098 -259.155764) (xy 127.726948 -259.159748) (xy 127.673798 -259.155764)
			(xy 127.621836 -259.143904) (xy 127.572222 -259.124432) (xy 127.526064 -259.097783) (xy 127.484393 -259.064552)
			(xy 127.448141 -259.025481) (xy 127.418117 -258.981444) (xy 127.394991 -258.933423) (xy 127.379281 -258.882493)
			(xy 127.371338 -258.829789) (xy 127.142758 -258.829789) (xy 127.134815 -258.882493) (xy 127.119105 -258.933423)
			(xy 127.095979 -258.981444) (xy 127.065955 -259.025481) (xy 127.029703 -259.064552) (xy 126.988032 -259.097783)
			(xy 126.941874 -259.124432) (xy 126.89226 -259.143904) (xy 126.840298 -259.155764) (xy 126.787148 -259.159748)
			(xy 126.733998 -259.155764) (xy 126.682036 -259.143904) (xy 126.632422 -259.124432) (xy 126.586264 -259.097783)
			(xy 126.544593 -259.064552) (xy 126.508341 -259.025481) (xy 126.478317 -258.981444) (xy 126.455191 -258.933423)
			(xy 126.439481 -258.882493) (xy 126.431538 -258.829789) (xy 126.202958 -258.829789) (xy 126.195015 -258.882493)
			(xy 126.179305 -258.933423) (xy 126.156179 -258.981444) (xy 126.126155 -259.025481) (xy 126.089903 -259.064552)
			(xy 126.048232 -259.097783) (xy 126.002074 -259.124432) (xy 125.95246 -259.143904) (xy 125.900498 -259.155764)
			(xy 125.847348 -259.159748) (xy 125.794198 -259.155764) (xy 125.742236 -259.143904) (xy 125.692622 -259.124432)
			(xy 125.646464 -259.097783) (xy 125.604793 -259.064552) (xy 125.568541 -259.025481) (xy 125.538517 -258.981444)
			(xy 125.515391 -258.933423) (xy 125.499681 -258.882493) (xy 125.491738 -258.829789) (xy 125.263158 -258.829789)
			(xy 125.255215 -258.882493) (xy 125.239505 -258.933423) (xy 125.216379 -258.981444) (xy 125.186355 -259.025481)
			(xy 125.150103 -259.064552) (xy 125.108432 -259.097783) (xy 125.062274 -259.124432) (xy 125.01266 -259.143904)
			(xy 124.960698 -259.155764) (xy 124.907548 -259.159748) (xy 124.854398 -259.155764) (xy 124.802436 -259.143904)
			(xy 124.752822 -259.124432) (xy 124.706664 -259.097783) (xy 124.664993 -259.064552) (xy 124.628741 -259.025481)
			(xy 124.598717 -258.981444) (xy 124.575591 -258.933423) (xy 124.559881 -258.882493) (xy 124.551938 -258.829789)
			(xy 124.323358 -258.829789) (xy 124.315415 -258.882493) (xy 124.299705 -258.933423) (xy 124.276579 -258.981444)
			(xy 124.246555 -259.025481) (xy 124.210303 -259.064552) (xy 124.168632 -259.097783) (xy 124.122474 -259.124432)
			(xy 124.07286 -259.143904) (xy 124.020898 -259.155764) (xy 123.967748 -259.159748) (xy 123.914598 -259.155764)
			(xy 123.862636 -259.143904) (xy 123.813022 -259.124432) (xy 123.766864 -259.097783) (xy 123.725193 -259.064552)
			(xy 123.688941 -259.025481) (xy 123.658917 -258.981444) (xy 123.635791 -258.933423) (xy 123.620081 -258.882493)
			(xy 123.612138 -258.829789) (xy 123.383304 -258.829789) (xy 123.375361 -258.882493) (xy 123.359651 -258.933423)
			(xy 123.336525 -258.981444) (xy 123.306501 -259.025481) (xy 123.270249 -259.064552) (xy 123.228578 -259.097783)
			(xy 123.18242 -259.124432) (xy 123.132806 -259.143904) (xy 123.080844 -259.155764) (xy 123.027694 -259.159748)
			(xy 122.974544 -259.155764) (xy 122.922582 -259.143904) (xy 122.872968 -259.124432) (xy 122.82681 -259.097783)
			(xy 122.785139 -259.064552) (xy 122.748887 -259.025481) (xy 122.718863 -258.981444) (xy 122.695737 -258.933423)
			(xy 122.680027 -258.882493) (xy 122.672084 -258.829789) (xy 122.443504 -258.829789) (xy 122.435561 -258.882493)
			(xy 122.419851 -258.933423) (xy 122.396725 -258.981444) (xy 122.366701 -259.025481) (xy 122.330449 -259.064552)
			(xy 122.288778 -259.097783) (xy 122.24262 -259.124432) (xy 122.193006 -259.143904) (xy 122.141044 -259.155764)
			(xy 122.087894 -259.159748) (xy 122.034744 -259.155764) (xy 121.982782 -259.143904) (xy 121.933168 -259.124432)
			(xy 121.88701 -259.097783) (xy 121.845339 -259.064552) (xy 121.809087 -259.025481) (xy 121.779063 -258.981444)
			(xy 121.755937 -258.933423) (xy 121.740227 -258.882493) (xy 121.732284 -258.829789) (xy 120.98528 -258.829789)
			(xy 120.98528 -259.390896) (xy 121.028206 -259.3975) (xy 121.054276 -259.402032) (xy 121.104789 -259.417793)
			(xy 121.15241 -259.44086) (xy 121.17451 -259.455412) (xy 121.185995 -259.462693) (xy 121.211712 -259.471502)
			(xy 121.238841 -259.473225) (xy 121.265465 -259.46774) (xy 121.289704 -259.455435) (xy 121.309846 -259.437179)
			(xy 121.317512 -259.425948) (xy 121.331598 -259.404611) (xy 121.364912 -259.365829) (xy 121.403426 -259.332206)
			(xy 121.446352 -259.304434) (xy 121.492805 -259.283082) (xy 121.541834 -259.268588) (xy 121.592431 -259.261252)
			(xy 121.617994 -259.260848) (xy 121.644649 -259.261321) (xy 121.697363 -259.269265) (xy 121.748304 -259.284978)
			(xy 121.796335 -259.308108) (xy 121.840381 -259.338137) (xy 121.87946 -259.374397) (xy 121.912698 -259.416075)
			(xy 121.939353 -259.462243) (xy 121.95883 -259.511867) (xy 121.970692 -259.56384) (xy 121.974676 -259.617)
			(xy 121.972682 -259.643605) (xy 122.202184 -259.643605) (xy 122.202184 -259.590307) (xy 122.210127 -259.537603)
			(xy 122.225837 -259.486673) (xy 122.248963 -259.438652) (xy 122.278987 -259.394615) (xy 122.315239 -259.355544)
			(xy 122.35691 -259.322313) (xy 122.403068 -259.295664) (xy 122.452682 -259.276192) (xy 122.504644 -259.264332)
			(xy 122.557794 -259.260349) (xy 122.610944 -259.264332) (xy 122.662906 -259.276192) (xy 122.71252 -259.295664)
			(xy 122.758678 -259.322313) (xy 122.800349 -259.355544) (xy 122.836601 -259.394615) (xy 122.866625 -259.438652)
			(xy 122.889751 -259.486673) (xy 122.905461 -259.537603) (xy 122.913404 -259.590307) (xy 122.913902 -259.616956)
			(xy 122.913404 -259.643605) (xy 123.141984 -259.643605) (xy 123.141984 -259.590307) (xy 123.149927 -259.537603)
			(xy 123.165637 -259.486673) (xy 123.188763 -259.438652) (xy 123.218787 -259.394615) (xy 123.255039 -259.355544)
			(xy 123.29671 -259.322313) (xy 123.342868 -259.295664) (xy 123.392482 -259.276192) (xy 123.444444 -259.264332)
			(xy 123.497594 -259.260349) (xy 123.550744 -259.264332) (xy 123.602706 -259.276192) (xy 123.65232 -259.295664)
			(xy 123.698478 -259.322313) (xy 123.740149 -259.355544) (xy 123.776401 -259.394615) (xy 123.806425 -259.438652)
			(xy 123.829551 -259.486673) (xy 123.845261 -259.537603) (xy 123.853204 -259.590307) (xy 123.853702 -259.616956)
			(xy 123.853204 -259.643605) (xy 124.081784 -259.643605) (xy 124.081784 -259.590307) (xy 124.089727 -259.537603)
			(xy 124.105437 -259.486673) (xy 124.128563 -259.438652) (xy 124.158587 -259.394615) (xy 124.194839 -259.355544)
			(xy 124.23651 -259.322313) (xy 124.282668 -259.295664) (xy 124.332282 -259.276192) (xy 124.384244 -259.264332)
			(xy 124.437394 -259.260349) (xy 124.490544 -259.264332) (xy 124.542506 -259.276192) (xy 124.59212 -259.295664)
			(xy 124.638278 -259.322313) (xy 124.679949 -259.355544) (xy 124.716201 -259.394615) (xy 124.746225 -259.438652)
			(xy 124.769351 -259.486673) (xy 124.785061 -259.537603) (xy 124.793004 -259.590307) (xy 124.793502 -259.616956)
			(xy 124.793004 -259.643605) (xy 125.021584 -259.643605) (xy 125.021584 -259.590307) (xy 125.029527 -259.537603)
			(xy 125.045237 -259.486673) (xy 125.068363 -259.438652) (xy 125.098387 -259.394615) (xy 125.134639 -259.355544)
			(xy 125.17631 -259.322313) (xy 125.222468 -259.295664) (xy 125.272082 -259.276192) (xy 125.324044 -259.264332)
			(xy 125.377194 -259.260349) (xy 125.430344 -259.264332) (xy 125.482306 -259.276192) (xy 125.53192 -259.295664)
			(xy 125.578078 -259.322313) (xy 125.619749 -259.355544) (xy 125.656001 -259.394615) (xy 125.686025 -259.438652)
			(xy 125.709151 -259.486673) (xy 125.724861 -259.537603) (xy 125.732804 -259.590307) (xy 125.733302 -259.616956)
			(xy 125.732804 -259.643605) (xy 125.961384 -259.643605) (xy 125.961384 -259.590307) (xy 125.969327 -259.537603)
			(xy 125.985037 -259.486673) (xy 126.008163 -259.438652) (xy 126.038187 -259.394615) (xy 126.074439 -259.355544)
			(xy 126.11611 -259.322313) (xy 126.162268 -259.295664) (xy 126.211882 -259.276192) (xy 126.263844 -259.264332)
			(xy 126.316994 -259.260349) (xy 126.370144 -259.264332) (xy 126.422106 -259.276192) (xy 126.47172 -259.295664)
			(xy 126.517878 -259.322313) (xy 126.559549 -259.355544) (xy 126.595801 -259.394615) (xy 126.625825 -259.438652)
			(xy 126.648951 -259.486673) (xy 126.664661 -259.537603) (xy 126.672604 -259.590307) (xy 126.673102 -259.616956)
			(xy 126.672604 -259.643605) (xy 126.901184 -259.643605) (xy 126.901184 -259.590307) (xy 126.909127 -259.537603)
			(xy 126.924837 -259.486673) (xy 126.947963 -259.438652) (xy 126.977987 -259.394615) (xy 127.014239 -259.355544)
			(xy 127.05591 -259.322313) (xy 127.102068 -259.295664) (xy 127.151682 -259.276192) (xy 127.203644 -259.264332)
			(xy 127.256794 -259.260349) (xy 127.309944 -259.264332) (xy 127.361906 -259.276192) (xy 127.41152 -259.295664)
			(xy 127.457678 -259.322313) (xy 127.499349 -259.355544) (xy 127.535601 -259.394615) (xy 127.565625 -259.438652)
			(xy 127.588751 -259.486673) (xy 127.604461 -259.537603) (xy 127.612404 -259.590307) (xy 127.612902 -259.616956)
			(xy 127.612404 -259.643605) (xy 127.840984 -259.643605) (xy 127.840984 -259.590307) (xy 127.848927 -259.537603)
			(xy 127.864637 -259.486673) (xy 127.887763 -259.438652) (xy 127.917787 -259.394615) (xy 127.954039 -259.355544)
			(xy 127.99571 -259.322313) (xy 128.041868 -259.295664) (xy 128.091482 -259.276192) (xy 128.143444 -259.264332)
			(xy 128.196594 -259.260349) (xy 128.249744 -259.264332) (xy 128.301706 -259.276192) (xy 128.35132 -259.295664)
			(xy 128.397478 -259.322313) (xy 128.439149 -259.355544) (xy 128.475401 -259.394615) (xy 128.505425 -259.438652)
			(xy 128.528551 -259.486673) (xy 128.544261 -259.537603) (xy 128.552204 -259.590307) (xy 128.552702 -259.616956)
			(xy 128.552204 -259.643605) (xy 128.780784 -259.643605) (xy 128.780784 -259.590307) (xy 128.788727 -259.537603)
			(xy 128.804437 -259.486673) (xy 128.827563 -259.438652) (xy 128.857587 -259.394615) (xy 128.893839 -259.355544)
			(xy 128.93551 -259.322313) (xy 128.981668 -259.295664) (xy 129.031282 -259.276192) (xy 129.083244 -259.264332)
			(xy 129.136394 -259.260349) (xy 129.189544 -259.264332) (xy 129.241506 -259.276192) (xy 129.29112 -259.295664)
			(xy 129.337278 -259.322313) (xy 129.378949 -259.355544) (xy 129.415201 -259.394615) (xy 129.445225 -259.438652)
			(xy 129.468351 -259.486673) (xy 129.484061 -259.537603) (xy 129.492004 -259.590307) (xy 129.492502 -259.616956)
			(xy 129.492004 -259.643605) (xy 129.720584 -259.643605) (xy 129.720584 -259.590307) (xy 129.728527 -259.537603)
			(xy 129.744237 -259.486673) (xy 129.767363 -259.438652) (xy 129.797387 -259.394615) (xy 129.833639 -259.355544)
			(xy 129.87531 -259.322313) (xy 129.921468 -259.295664) (xy 129.971082 -259.276192) (xy 130.023044 -259.264332)
			(xy 130.076194 -259.260349) (xy 130.129344 -259.264332) (xy 130.181306 -259.276192) (xy 130.23092 -259.295664)
			(xy 130.277078 -259.322313) (xy 130.318749 -259.355544) (xy 130.355001 -259.394615) (xy 130.385025 -259.438652)
			(xy 130.408151 -259.486673) (xy 130.423861 -259.537603) (xy 130.431804 -259.590307) (xy 130.432302 -259.616956)
			(xy 130.431804 -259.643605) (xy 130.660384 -259.643605) (xy 130.660384 -259.590307) (xy 130.668327 -259.537603)
			(xy 130.684037 -259.486673) (xy 130.707163 -259.438652) (xy 130.737187 -259.394615) (xy 130.773439 -259.355544)
			(xy 130.81511 -259.322313) (xy 130.861268 -259.295664) (xy 130.910882 -259.276192) (xy 130.962844 -259.264332)
			(xy 131.015994 -259.260349) (xy 131.069144 -259.264332) (xy 131.121106 -259.276192) (xy 131.17072 -259.295664)
			(xy 131.216878 -259.322313) (xy 131.258549 -259.355544) (xy 131.294801 -259.394615) (xy 131.324825 -259.438652)
			(xy 131.347951 -259.486673) (xy 131.363661 -259.537603) (xy 131.371604 -259.590307) (xy 131.372102 -259.616956)
			(xy 131.371604 -259.643605) (xy 131.600184 -259.643605) (xy 131.600184 -259.590307) (xy 131.608127 -259.537603)
			(xy 131.623837 -259.486673) (xy 131.646963 -259.438652) (xy 131.676987 -259.394615) (xy 131.713239 -259.355544)
			(xy 131.75491 -259.322313) (xy 131.801068 -259.295664) (xy 131.850682 -259.276192) (xy 131.902644 -259.264332)
			(xy 131.955794 -259.260349) (xy 132.008944 -259.264332) (xy 132.060906 -259.276192) (xy 132.11052 -259.295664)
			(xy 132.156678 -259.322313) (xy 132.198349 -259.355544) (xy 132.234601 -259.394615) (xy 132.264625 -259.438652)
			(xy 132.287751 -259.486673) (xy 132.303461 -259.537603) (xy 132.311404 -259.590307) (xy 132.311902 -259.616956)
			(xy 132.311404 -259.643605) (xy 132.539984 -259.643605) (xy 132.539984 -259.590307) (xy 132.547927 -259.537603)
			(xy 132.563637 -259.486673) (xy 132.586763 -259.438652) (xy 132.616787 -259.394615) (xy 132.653039 -259.355544)
			(xy 132.69471 -259.322313) (xy 132.740868 -259.295664) (xy 132.790482 -259.276192) (xy 132.842444 -259.264332)
			(xy 132.895594 -259.260349) (xy 132.948744 -259.264332) (xy 133.000706 -259.276192) (xy 133.05032 -259.295664)
			(xy 133.096478 -259.322313) (xy 133.138149 -259.355544) (xy 133.174401 -259.394615) (xy 133.204425 -259.438652)
			(xy 133.227551 -259.486673) (xy 133.243261 -259.537603) (xy 133.251204 -259.590307) (xy 133.251702 -259.616956)
			(xy 133.251204 -259.643605) (xy 133.479784 -259.643605) (xy 133.479784 -259.590307) (xy 133.487727 -259.537603)
			(xy 133.503437 -259.486673) (xy 133.526563 -259.438652) (xy 133.556587 -259.394615) (xy 133.592839 -259.355544)
			(xy 133.63451 -259.322313) (xy 133.680668 -259.295664) (xy 133.730282 -259.276192) (xy 133.782244 -259.264332)
			(xy 133.835394 -259.260349) (xy 133.888544 -259.264332) (xy 133.940506 -259.276192) (xy 133.99012 -259.295664)
			(xy 134.036278 -259.322313) (xy 134.077949 -259.355544) (xy 134.114201 -259.394615) (xy 134.144225 -259.438652)
			(xy 134.167351 -259.486673) (xy 134.183061 -259.537603) (xy 134.191004 -259.590307) (xy 134.191502 -259.616956)
			(xy 134.191004 -259.643605) (xy 134.183061 -259.696309) (xy 134.167351 -259.747239) (xy 134.144225 -259.79526)
			(xy 134.114201 -259.839297) (xy 134.077949 -259.878368) (xy 134.036278 -259.911599) (xy 133.99012 -259.938248)
			(xy 133.940506 -259.95772) (xy 133.888544 -259.96958) (xy 133.835394 -259.973564) (xy 133.782244 -259.96958)
			(xy 133.730282 -259.95772) (xy 133.680668 -259.938248) (xy 133.63451 -259.911599) (xy 133.592839 -259.878368)
			(xy 133.556587 -259.839297) (xy 133.526563 -259.79526) (xy 133.503437 -259.747239) (xy 133.487727 -259.696309)
			(xy 133.479784 -259.643605) (xy 133.251204 -259.643605) (xy 133.243261 -259.696309) (xy 133.227551 -259.747239)
			(xy 133.204425 -259.79526) (xy 133.174401 -259.839297) (xy 133.138149 -259.878368) (xy 133.096478 -259.911599)
			(xy 133.05032 -259.938248) (xy 133.000706 -259.95772) (xy 132.948744 -259.96958) (xy 132.895594 -259.973564)
			(xy 132.842444 -259.96958) (xy 132.790482 -259.95772) (xy 132.740868 -259.938248) (xy 132.69471 -259.911599)
			(xy 132.653039 -259.878368) (xy 132.616787 -259.839297) (xy 132.586763 -259.79526) (xy 132.563637 -259.747239)
			(xy 132.547927 -259.696309) (xy 132.539984 -259.643605) (xy 132.311404 -259.643605) (xy 132.303461 -259.696309)
			(xy 132.287751 -259.747239) (xy 132.264625 -259.79526) (xy 132.234601 -259.839297) (xy 132.198349 -259.878368)
			(xy 132.156678 -259.911599) (xy 132.11052 -259.938248) (xy 132.060906 -259.95772) (xy 132.008944 -259.96958)
			(xy 131.955794 -259.973564) (xy 131.902644 -259.96958) (xy 131.850682 -259.95772) (xy 131.801068 -259.938248)
			(xy 131.75491 -259.911599) (xy 131.713239 -259.878368) (xy 131.676987 -259.839297) (xy 131.646963 -259.79526)
			(xy 131.623837 -259.747239) (xy 131.608127 -259.696309) (xy 131.600184 -259.643605) (xy 131.371604 -259.643605)
			(xy 131.363661 -259.696309) (xy 131.347951 -259.747239) (xy 131.324825 -259.79526) (xy 131.294801 -259.839297)
			(xy 131.258549 -259.878368) (xy 131.216878 -259.911599) (xy 131.17072 -259.938248) (xy 131.121106 -259.95772)
			(xy 131.069144 -259.96958) (xy 131.015994 -259.973564) (xy 130.962844 -259.96958) (xy 130.910882 -259.95772)
			(xy 130.861268 -259.938248) (xy 130.81511 -259.911599) (xy 130.773439 -259.878368) (xy 130.737187 -259.839297)
			(xy 130.707163 -259.79526) (xy 130.684037 -259.747239) (xy 130.668327 -259.696309) (xy 130.660384 -259.643605)
			(xy 130.431804 -259.643605) (xy 130.423861 -259.696309) (xy 130.408151 -259.747239) (xy 130.385025 -259.79526)
			(xy 130.355001 -259.839297) (xy 130.318749 -259.878368) (xy 130.277078 -259.911599) (xy 130.23092 -259.938248)
			(xy 130.181306 -259.95772) (xy 130.129344 -259.96958) (xy 130.076194 -259.973564) (xy 130.023044 -259.96958)
			(xy 129.971082 -259.95772) (xy 129.921468 -259.938248) (xy 129.87531 -259.911599) (xy 129.833639 -259.878368)
			(xy 129.797387 -259.839297) (xy 129.767363 -259.79526) (xy 129.744237 -259.747239) (xy 129.728527 -259.696309)
			(xy 129.720584 -259.643605) (xy 129.492004 -259.643605) (xy 129.484061 -259.696309) (xy 129.468351 -259.747239)
			(xy 129.445225 -259.79526) (xy 129.415201 -259.839297) (xy 129.378949 -259.878368) (xy 129.337278 -259.911599)
			(xy 129.29112 -259.938248) (xy 129.241506 -259.95772) (xy 129.189544 -259.96958) (xy 129.136394 -259.973564)
			(xy 129.083244 -259.96958) (xy 129.031282 -259.95772) (xy 128.981668 -259.938248) (xy 128.93551 -259.911599)
			(xy 128.893839 -259.878368) (xy 128.857587 -259.839297) (xy 128.827563 -259.79526) (xy 128.804437 -259.747239)
			(xy 128.788727 -259.696309) (xy 128.780784 -259.643605) (xy 128.552204 -259.643605) (xy 128.544261 -259.696309)
			(xy 128.528551 -259.747239) (xy 128.505425 -259.79526) (xy 128.475401 -259.839297) (xy 128.439149 -259.878368)
			(xy 128.397478 -259.911599) (xy 128.35132 -259.938248) (xy 128.301706 -259.95772) (xy 128.249744 -259.96958)
			(xy 128.196594 -259.973564) (xy 128.143444 -259.96958) (xy 128.091482 -259.95772) (xy 128.041868 -259.938248)
			(xy 127.99571 -259.911599) (xy 127.954039 -259.878368) (xy 127.917787 -259.839297) (xy 127.887763 -259.79526)
			(xy 127.864637 -259.747239) (xy 127.848927 -259.696309) (xy 127.840984 -259.643605) (xy 127.612404 -259.643605)
			(xy 127.604461 -259.696309) (xy 127.588751 -259.747239) (xy 127.565625 -259.79526) (xy 127.535601 -259.839297)
			(xy 127.499349 -259.878368) (xy 127.457678 -259.911599) (xy 127.41152 -259.938248) (xy 127.361906 -259.95772)
			(xy 127.309944 -259.96958) (xy 127.256794 -259.973564) (xy 127.203644 -259.96958) (xy 127.151682 -259.95772)
			(xy 127.102068 -259.938248) (xy 127.05591 -259.911599) (xy 127.014239 -259.878368) (xy 126.977987 -259.839297)
			(xy 126.947963 -259.79526) (xy 126.924837 -259.747239) (xy 126.909127 -259.696309) (xy 126.901184 -259.643605)
			(xy 126.672604 -259.643605) (xy 126.664661 -259.696309) (xy 126.648951 -259.747239) (xy 126.625825 -259.79526)
			(xy 126.595801 -259.839297) (xy 126.559549 -259.878368) (xy 126.517878 -259.911599) (xy 126.47172 -259.938248)
			(xy 126.422106 -259.95772) (xy 126.370144 -259.96958) (xy 126.316994 -259.973564) (xy 126.263844 -259.96958)
			(xy 126.211882 -259.95772) (xy 126.162268 -259.938248) (xy 126.11611 -259.911599) (xy 126.074439 -259.878368)
			(xy 126.038187 -259.839297) (xy 126.008163 -259.79526) (xy 125.985037 -259.747239) (xy 125.969327 -259.696309)
			(xy 125.961384 -259.643605) (xy 125.732804 -259.643605) (xy 125.724861 -259.696309) (xy 125.709151 -259.747239)
			(xy 125.686025 -259.79526) (xy 125.656001 -259.839297) (xy 125.619749 -259.878368) (xy 125.578078 -259.911599)
			(xy 125.53192 -259.938248) (xy 125.482306 -259.95772) (xy 125.430344 -259.96958) (xy 125.377194 -259.973564)
			(xy 125.324044 -259.96958) (xy 125.272082 -259.95772) (xy 125.222468 -259.938248) (xy 125.17631 -259.911599)
			(xy 125.134639 -259.878368) (xy 125.098387 -259.839297) (xy 125.068363 -259.79526) (xy 125.045237 -259.747239)
			(xy 125.029527 -259.696309) (xy 125.021584 -259.643605) (xy 124.793004 -259.643605) (xy 124.785061 -259.696309)
			(xy 124.769351 -259.747239) (xy 124.746225 -259.79526) (xy 124.716201 -259.839297) (xy 124.679949 -259.878368)
			(xy 124.638278 -259.911599) (xy 124.59212 -259.938248) (xy 124.542506 -259.95772) (xy 124.490544 -259.96958)
			(xy 124.437394 -259.973564) (xy 124.384244 -259.96958) (xy 124.332282 -259.95772) (xy 124.282668 -259.938248)
			(xy 124.23651 -259.911599) (xy 124.194839 -259.878368) (xy 124.158587 -259.839297) (xy 124.128563 -259.79526)
			(xy 124.105437 -259.747239) (xy 124.089727 -259.696309) (xy 124.081784 -259.643605) (xy 123.853204 -259.643605)
			(xy 123.845261 -259.696309) (xy 123.829551 -259.747239) (xy 123.806425 -259.79526) (xy 123.776401 -259.839297)
			(xy 123.740149 -259.878368) (xy 123.698478 -259.911599) (xy 123.65232 -259.938248) (xy 123.602706 -259.95772)
			(xy 123.550744 -259.96958) (xy 123.497594 -259.973564) (xy 123.444444 -259.96958) (xy 123.392482 -259.95772)
			(xy 123.342868 -259.938248) (xy 123.29671 -259.911599) (xy 123.255039 -259.878368) (xy 123.218787 -259.839297)
			(xy 123.188763 -259.79526) (xy 123.165637 -259.747239) (xy 123.149927 -259.696309) (xy 123.141984 -259.643605)
			(xy 122.913404 -259.643605) (xy 122.905461 -259.696309) (xy 122.889751 -259.747239) (xy 122.866625 -259.79526)
			(xy 122.836601 -259.839297) (xy 122.800349 -259.878368) (xy 122.758678 -259.911599) (xy 122.71252 -259.938248)
			(xy 122.662906 -259.95772) (xy 122.610944 -259.96958) (xy 122.557794 -259.973564) (xy 122.504644 -259.96958)
			(xy 122.452682 -259.95772) (xy 122.403068 -259.938248) (xy 122.35691 -259.911599) (xy 122.315239 -259.878368)
			(xy 122.278987 -259.839297) (xy 122.248963 -259.79526) (xy 122.225837 -259.747239) (xy 122.210127 -259.696309)
			(xy 122.202184 -259.643605) (xy 121.972682 -259.643605) (xy 121.970692 -259.67016) (xy 121.95883 -259.722133)
			(xy 121.939353 -259.771757) (xy 121.912698 -259.817925) (xy 121.87946 -259.859603) (xy 121.840381 -259.895863)
			(xy 121.796335 -259.925892) (xy 121.748304 -259.949022) (xy 121.697363 -259.964735) (xy 121.644649 -259.972679)
			(xy 121.617994 -259.973064) (xy 121.591332 -259.972588) (xy 121.538605 -259.964629) (xy 121.487656 -259.948889)
			(xy 121.439627 -259.925722) (xy 121.417334 -259.911088) (xy 121.405851 -259.903815) (xy 121.380141 -259.895021)
			(xy 121.353022 -259.89331) (xy 121.32641 -259.898802) (xy 121.302185 -259.91111) (xy 121.282058 -259.929365)
			(xy 121.274332 -259.940552) (xy 121.260245 -259.961886) (xy 121.22693 -260.000663) (xy 121.188414 -260.03428)
			(xy 121.145488 -260.062046) (xy 121.099034 -260.083391) (xy 121.050006 -260.097876) (xy 120.999411 -260.105205)
			(xy 120.97385 -260.105652) (xy 120.947163 -260.105172) (xy 120.894386 -260.097198) (xy 120.843392 -260.081434)
			(xy 120.795322 -260.058236) (xy 120.751253 -260.028122) (xy 120.712173 -259.991768) (xy 120.678957 -259.949987)
			(xy 120.66524 -259.92709) (xy 120.658221 -259.915773) (xy 120.639421 -259.896927) (xy 120.616385 -259.883586)
			(xy 120.590683 -259.876656) (xy 120.564063 -259.876611) (xy 120.538337 -259.883452) (xy 120.515256 -259.896715)
			(xy 120.505474 -259.905754) (xy 119.953807 -260.457421) (xy 121.732538 -260.457421) (xy 121.732538 -260.404123)
			(xy 121.740481 -260.351419) (xy 121.756191 -260.300489) (xy 121.779317 -260.252468) (xy 121.809341 -260.208431)
			(xy 121.845593 -260.16936) (xy 121.887264 -260.136129) (xy 121.933422 -260.10948) (xy 121.983036 -260.090008)
			(xy 122.034998 -260.078148) (xy 122.088148 -260.074165) (xy 122.141298 -260.078148) (xy 122.19326 -260.090008)
			(xy 122.242874 -260.10948) (xy 122.289032 -260.136129) (xy 122.330703 -260.16936) (xy 122.366955 -260.208431)
			(xy 122.396979 -260.252468) (xy 122.420105 -260.300489) (xy 122.435815 -260.351419) (xy 122.443758 -260.404123)
			(xy 122.444256 -260.430772) (xy 122.443758 -260.457421) (xy 122.672338 -260.457421) (xy 122.672338 -260.404123)
			(xy 122.680281 -260.351419) (xy 122.695991 -260.300489) (xy 122.719117 -260.252468) (xy 122.749141 -260.208431)
			(xy 122.785393 -260.16936) (xy 122.827064 -260.136129) (xy 122.873222 -260.10948) (xy 122.922836 -260.090008)
			(xy 122.974798 -260.078148) (xy 123.027948 -260.074165) (xy 123.081098 -260.078148) (xy 123.13306 -260.090008)
			(xy 123.182674 -260.10948) (xy 123.228832 -260.136129) (xy 123.270503 -260.16936) (xy 123.306755 -260.208431)
			(xy 123.336779 -260.252468) (xy 123.359905 -260.300489) (xy 123.375615 -260.351419) (xy 123.383558 -260.404123)
			(xy 123.384056 -260.430772) (xy 123.383558 -260.457421) (xy 123.612138 -260.457421) (xy 123.612138 -260.404123)
			(xy 123.620081 -260.351419) (xy 123.635791 -260.300489) (xy 123.658917 -260.252468) (xy 123.688941 -260.208431)
			(xy 123.725193 -260.16936) (xy 123.766864 -260.136129) (xy 123.813022 -260.10948) (xy 123.862636 -260.090008)
			(xy 123.914598 -260.078148) (xy 123.967748 -260.074165) (xy 124.020898 -260.078148) (xy 124.07286 -260.090008)
			(xy 124.122474 -260.10948) (xy 124.168632 -260.136129) (xy 124.210303 -260.16936) (xy 124.246555 -260.208431)
			(xy 124.276579 -260.252468) (xy 124.299705 -260.300489) (xy 124.315415 -260.351419) (xy 124.323358 -260.404123)
			(xy 124.323856 -260.430772) (xy 124.323358 -260.457421) (xy 124.551938 -260.457421) (xy 124.551938 -260.404123)
			(xy 124.559881 -260.351419) (xy 124.575591 -260.300489) (xy 124.598717 -260.252468) (xy 124.628741 -260.208431)
			(xy 124.664993 -260.16936) (xy 124.706664 -260.136129) (xy 124.752822 -260.10948) (xy 124.802436 -260.090008)
			(xy 124.854398 -260.078148) (xy 124.907548 -260.074165) (xy 124.960698 -260.078148) (xy 125.01266 -260.090008)
			(xy 125.062274 -260.10948) (xy 125.108432 -260.136129) (xy 125.150103 -260.16936) (xy 125.186355 -260.208431)
			(xy 125.216379 -260.252468) (xy 125.239505 -260.300489) (xy 125.255215 -260.351419) (xy 125.263158 -260.404123)
			(xy 125.263656 -260.430772) (xy 125.263158 -260.457421) (xy 125.491738 -260.457421) (xy 125.491738 -260.404123)
			(xy 125.499681 -260.351419) (xy 125.515391 -260.300489) (xy 125.538517 -260.252468) (xy 125.568541 -260.208431)
			(xy 125.604793 -260.16936) (xy 125.646464 -260.136129) (xy 125.692622 -260.10948) (xy 125.742236 -260.090008)
			(xy 125.794198 -260.078148) (xy 125.847348 -260.074165) (xy 125.900498 -260.078148) (xy 125.95246 -260.090008)
			(xy 126.002074 -260.10948) (xy 126.048232 -260.136129) (xy 126.089903 -260.16936) (xy 126.126155 -260.208431)
			(xy 126.156179 -260.252468) (xy 126.179305 -260.300489) (xy 126.195015 -260.351419) (xy 126.202958 -260.404123)
			(xy 126.203456 -260.430772) (xy 126.202958 -260.457421) (xy 126.431284 -260.457421) (xy 126.431284 -260.404123)
			(xy 126.439227 -260.351419) (xy 126.454937 -260.300489) (xy 126.478063 -260.252468) (xy 126.508087 -260.208431)
			(xy 126.544339 -260.16936) (xy 126.58601 -260.136129) (xy 126.632168 -260.10948) (xy 126.681782 -260.090008)
			(xy 126.733744 -260.078148) (xy 126.786894 -260.074165) (xy 126.840044 -260.078148) (xy 126.892006 -260.090008)
			(xy 126.94162 -260.10948) (xy 126.987778 -260.136129) (xy 127.029449 -260.16936) (xy 127.065701 -260.208431)
			(xy 127.095725 -260.252468) (xy 127.118851 -260.300489) (xy 127.134561 -260.351419) (xy 127.142504 -260.404123)
			(xy 127.143002 -260.430772) (xy 127.142504 -260.457421) (xy 127.371338 -260.457421) (xy 127.371338 -260.404123)
			(xy 127.379281 -260.351419) (xy 127.394991 -260.300489) (xy 127.418117 -260.252468) (xy 127.448141 -260.208431)
			(xy 127.484393 -260.16936) (xy 127.526064 -260.136129) (xy 127.572222 -260.10948) (xy 127.621836 -260.090008)
			(xy 127.673798 -260.078148) (xy 127.726948 -260.074165) (xy 127.780098 -260.078148) (xy 127.83206 -260.090008)
			(xy 127.881674 -260.10948) (xy 127.927832 -260.136129) (xy 127.969503 -260.16936) (xy 128.005755 -260.208431)
			(xy 128.035779 -260.252468) (xy 128.058905 -260.300489) (xy 128.074615 -260.351419) (xy 128.082558 -260.404123)
			(xy 128.083056 -260.430772) (xy 128.082558 -260.457421) (xy 128.311138 -260.457421) (xy 128.311138 -260.404123)
			(xy 128.319081 -260.351419) (xy 128.334791 -260.300489) (xy 128.357917 -260.252468) (xy 128.387941 -260.208431)
			(xy 128.424193 -260.16936) (xy 128.465864 -260.136129) (xy 128.512022 -260.10948) (xy 128.561636 -260.090008)
			(xy 128.613598 -260.078148) (xy 128.666748 -260.074165) (xy 128.719898 -260.078148) (xy 128.77186 -260.090008)
			(xy 128.821474 -260.10948) (xy 128.867632 -260.136129) (xy 128.909303 -260.16936) (xy 128.945555 -260.208431)
			(xy 128.975579 -260.252468) (xy 128.998705 -260.300489) (xy 129.014415 -260.351419) (xy 129.022358 -260.404123)
			(xy 129.022856 -260.430772) (xy 129.022358 -260.457421) (xy 129.250938 -260.457421) (xy 129.250938 -260.404123)
			(xy 129.258881 -260.351419) (xy 129.274591 -260.300489) (xy 129.297717 -260.252468) (xy 129.327741 -260.208431)
			(xy 129.363993 -260.16936) (xy 129.405664 -260.136129) (xy 129.451822 -260.10948) (xy 129.501436 -260.090008)
			(xy 129.553398 -260.078148) (xy 129.606548 -260.074165) (xy 129.659698 -260.078148) (xy 129.71166 -260.090008)
			(xy 129.761274 -260.10948) (xy 129.807432 -260.136129) (xy 129.849103 -260.16936) (xy 129.885355 -260.208431)
			(xy 129.915379 -260.252468) (xy 129.938505 -260.300489) (xy 129.954215 -260.351419) (xy 129.962158 -260.404123)
			(xy 129.962656 -260.430772) (xy 129.962158 -260.457421) (xy 130.190738 -260.457421) (xy 130.190738 -260.404123)
			(xy 130.198681 -260.351419) (xy 130.214391 -260.300489) (xy 130.237517 -260.252468) (xy 130.267541 -260.208431)
			(xy 130.303793 -260.16936) (xy 130.345464 -260.136129) (xy 130.391622 -260.10948) (xy 130.441236 -260.090008)
			(xy 130.493198 -260.078148) (xy 130.546348 -260.074165) (xy 130.599498 -260.078148) (xy 130.65146 -260.090008)
			(xy 130.701074 -260.10948) (xy 130.747232 -260.136129) (xy 130.788903 -260.16936) (xy 130.825155 -260.208431)
			(xy 130.855179 -260.252468) (xy 130.878305 -260.300489) (xy 130.894015 -260.351419) (xy 130.901958 -260.404123)
			(xy 130.902456 -260.430772) (xy 130.901958 -260.457421) (xy 131.130538 -260.457421) (xy 131.130538 -260.404123)
			(xy 131.138481 -260.351419) (xy 131.154191 -260.300489) (xy 131.177317 -260.252468) (xy 131.207341 -260.208431)
			(xy 131.243593 -260.16936) (xy 131.285264 -260.136129) (xy 131.331422 -260.10948) (xy 131.381036 -260.090008)
			(xy 131.432998 -260.078148) (xy 131.486148 -260.074165) (xy 131.539298 -260.078148) (xy 131.59126 -260.090008)
			(xy 131.640874 -260.10948) (xy 131.687032 -260.136129) (xy 131.728703 -260.16936) (xy 131.764955 -260.208431)
			(xy 131.794979 -260.252468) (xy 131.818105 -260.300489) (xy 131.833815 -260.351419) (xy 131.841758 -260.404123)
			(xy 131.842256 -260.430772) (xy 131.841758 -260.457421) (xy 132.070338 -260.457421) (xy 132.070338 -260.404123)
			(xy 132.078281 -260.351419) (xy 132.093991 -260.300489) (xy 132.117117 -260.252468) (xy 132.147141 -260.208431)
			(xy 132.183393 -260.16936) (xy 132.225064 -260.136129) (xy 132.271222 -260.10948) (xy 132.320836 -260.090008)
			(xy 132.372798 -260.078148) (xy 132.425948 -260.074165) (xy 132.479098 -260.078148) (xy 132.53106 -260.090008)
			(xy 132.580674 -260.10948) (xy 132.626832 -260.136129) (xy 132.668503 -260.16936) (xy 132.704755 -260.208431)
			(xy 132.734779 -260.252468) (xy 132.757905 -260.300489) (xy 132.773615 -260.351419) (xy 132.781558 -260.404123)
			(xy 132.782056 -260.430772) (xy 132.781558 -260.457421) (xy 133.009884 -260.457421) (xy 133.009884 -260.404123)
			(xy 133.017827 -260.351419) (xy 133.033537 -260.300489) (xy 133.056663 -260.252468) (xy 133.086687 -260.208431)
			(xy 133.122939 -260.16936) (xy 133.16461 -260.136129) (xy 133.210768 -260.10948) (xy 133.260382 -260.090008)
			(xy 133.312344 -260.078148) (xy 133.365494 -260.074165) (xy 133.418644 -260.078148) (xy 133.470606 -260.090008)
			(xy 133.52022 -260.10948) (xy 133.566378 -260.136129) (xy 133.608049 -260.16936) (xy 133.644301 -260.208431)
			(xy 133.674325 -260.252468) (xy 133.697451 -260.300489) (xy 133.713161 -260.351419) (xy 133.721104 -260.404123)
			(xy 133.721602 -260.430772) (xy 133.721104 -260.457421) (xy 133.949938 -260.457421) (xy 133.949938 -260.404123)
			(xy 133.957881 -260.351419) (xy 133.973591 -260.300489) (xy 133.996717 -260.252468) (xy 134.026741 -260.208431)
			(xy 134.062993 -260.16936) (xy 134.104664 -260.136129) (xy 134.150822 -260.10948) (xy 134.200436 -260.090008)
			(xy 134.252398 -260.078148) (xy 134.305548 -260.074165) (xy 134.358698 -260.078148) (xy 134.41066 -260.090008)
			(xy 134.460274 -260.10948) (xy 134.506432 -260.136129) (xy 134.548103 -260.16936) (xy 134.584355 -260.208431)
			(xy 134.614379 -260.252468) (xy 134.637505 -260.300489) (xy 134.653215 -260.351419) (xy 134.661158 -260.404123)
			(xy 134.661656 -260.430772) (xy 134.661158 -260.457421) (xy 134.653215 -260.510125) (xy 134.637505 -260.561055)
			(xy 134.614379 -260.609076) (xy 134.584355 -260.653113) (xy 134.548103 -260.692184) (xy 134.506432 -260.725415)
			(xy 134.460274 -260.752064) (xy 134.41066 -260.771536) (xy 134.358698 -260.783396) (xy 134.305548 -260.78738)
			(xy 134.252398 -260.783396) (xy 134.200436 -260.771536) (xy 134.150822 -260.752064) (xy 134.104664 -260.725415)
			(xy 134.062993 -260.692184) (xy 134.026741 -260.653113) (xy 133.996717 -260.609076) (xy 133.973591 -260.561055)
			(xy 133.957881 -260.510125) (xy 133.949938 -260.457421) (xy 133.721104 -260.457421) (xy 133.713161 -260.510125)
			(xy 133.697451 -260.561055) (xy 133.674325 -260.609076) (xy 133.644301 -260.653113) (xy 133.608049 -260.692184)
			(xy 133.566378 -260.725415) (xy 133.52022 -260.752064) (xy 133.470606 -260.771536) (xy 133.418644 -260.783396)
			(xy 133.365494 -260.78738) (xy 133.312344 -260.783396) (xy 133.260382 -260.771536) (xy 133.210768 -260.752064)
			(xy 133.16461 -260.725415) (xy 133.122939 -260.692184) (xy 133.086687 -260.653113) (xy 133.056663 -260.609076)
			(xy 133.033537 -260.561055) (xy 133.017827 -260.510125) (xy 133.009884 -260.457421) (xy 132.781558 -260.457421)
			(xy 132.773615 -260.510125) (xy 132.757905 -260.561055) (xy 132.734779 -260.609076) (xy 132.704755 -260.653113)
			(xy 132.668503 -260.692184) (xy 132.626832 -260.725415) (xy 132.580674 -260.752064) (xy 132.53106 -260.771536)
			(xy 132.479098 -260.783396) (xy 132.425948 -260.78738) (xy 132.372798 -260.783396) (xy 132.320836 -260.771536)
			(xy 132.271222 -260.752064) (xy 132.225064 -260.725415) (xy 132.183393 -260.692184) (xy 132.147141 -260.653113)
			(xy 132.117117 -260.609076) (xy 132.093991 -260.561055) (xy 132.078281 -260.510125) (xy 132.070338 -260.457421)
			(xy 131.841758 -260.457421) (xy 131.833815 -260.510125) (xy 131.818105 -260.561055) (xy 131.794979 -260.609076)
			(xy 131.764955 -260.653113) (xy 131.728703 -260.692184) (xy 131.687032 -260.725415) (xy 131.640874 -260.752064)
			(xy 131.59126 -260.771536) (xy 131.539298 -260.783396) (xy 131.486148 -260.78738) (xy 131.432998 -260.783396)
			(xy 131.381036 -260.771536) (xy 131.331422 -260.752064) (xy 131.285264 -260.725415) (xy 131.243593 -260.692184)
			(xy 131.207341 -260.653113) (xy 131.177317 -260.609076) (xy 131.154191 -260.561055) (xy 131.138481 -260.510125)
			(xy 131.130538 -260.457421) (xy 130.901958 -260.457421) (xy 130.894015 -260.510125) (xy 130.878305 -260.561055)
			(xy 130.855179 -260.609076) (xy 130.825155 -260.653113) (xy 130.788903 -260.692184) (xy 130.747232 -260.725415)
			(xy 130.701074 -260.752064) (xy 130.65146 -260.771536) (xy 130.599498 -260.783396) (xy 130.546348 -260.78738)
			(xy 130.493198 -260.783396) (xy 130.441236 -260.771536) (xy 130.391622 -260.752064) (xy 130.345464 -260.725415)
			(xy 130.303793 -260.692184) (xy 130.267541 -260.653113) (xy 130.237517 -260.609076) (xy 130.214391 -260.561055)
			(xy 130.198681 -260.510125) (xy 130.190738 -260.457421) (xy 129.962158 -260.457421) (xy 129.954215 -260.510125)
			(xy 129.938505 -260.561055) (xy 129.915379 -260.609076) (xy 129.885355 -260.653113) (xy 129.849103 -260.692184)
			(xy 129.807432 -260.725415) (xy 129.761274 -260.752064) (xy 129.71166 -260.771536) (xy 129.659698 -260.783396)
			(xy 129.606548 -260.78738) (xy 129.553398 -260.783396) (xy 129.501436 -260.771536) (xy 129.451822 -260.752064)
			(xy 129.405664 -260.725415) (xy 129.363993 -260.692184) (xy 129.327741 -260.653113) (xy 129.297717 -260.609076)
			(xy 129.274591 -260.561055) (xy 129.258881 -260.510125) (xy 129.250938 -260.457421) (xy 129.022358 -260.457421)
			(xy 129.014415 -260.510125) (xy 128.998705 -260.561055) (xy 128.975579 -260.609076) (xy 128.945555 -260.653113)
			(xy 128.909303 -260.692184) (xy 128.867632 -260.725415) (xy 128.821474 -260.752064) (xy 128.77186 -260.771536)
			(xy 128.719898 -260.783396) (xy 128.666748 -260.78738) (xy 128.613598 -260.783396) (xy 128.561636 -260.771536)
			(xy 128.512022 -260.752064) (xy 128.465864 -260.725415) (xy 128.424193 -260.692184) (xy 128.387941 -260.653113)
			(xy 128.357917 -260.609076) (xy 128.334791 -260.561055) (xy 128.319081 -260.510125) (xy 128.311138 -260.457421)
			(xy 128.082558 -260.457421) (xy 128.074615 -260.510125) (xy 128.058905 -260.561055) (xy 128.035779 -260.609076)
			(xy 128.005755 -260.653113) (xy 127.969503 -260.692184) (xy 127.927832 -260.725415) (xy 127.881674 -260.752064)
			(xy 127.83206 -260.771536) (xy 127.780098 -260.783396) (xy 127.726948 -260.78738) (xy 127.673798 -260.783396)
			(xy 127.621836 -260.771536) (xy 127.572222 -260.752064) (xy 127.526064 -260.725415) (xy 127.484393 -260.692184)
			(xy 127.448141 -260.653113) (xy 127.418117 -260.609076) (xy 127.394991 -260.561055) (xy 127.379281 -260.510125)
			(xy 127.371338 -260.457421) (xy 127.142504 -260.457421) (xy 127.134561 -260.510125) (xy 127.118851 -260.561055)
			(xy 127.095725 -260.609076) (xy 127.065701 -260.653113) (xy 127.029449 -260.692184) (xy 126.987778 -260.725415)
			(xy 126.94162 -260.752064) (xy 126.892006 -260.771536) (xy 126.840044 -260.783396) (xy 126.786894 -260.78738)
			(xy 126.733744 -260.783396) (xy 126.681782 -260.771536) (xy 126.632168 -260.752064) (xy 126.58601 -260.725415)
			(xy 126.544339 -260.692184) (xy 126.508087 -260.653113) (xy 126.478063 -260.609076) (xy 126.454937 -260.561055)
			(xy 126.439227 -260.510125) (xy 126.431284 -260.457421) (xy 126.202958 -260.457421) (xy 126.195015 -260.510125)
			(xy 126.179305 -260.561055) (xy 126.156179 -260.609076) (xy 126.126155 -260.653113) (xy 126.089903 -260.692184)
			(xy 126.048232 -260.725415) (xy 126.002074 -260.752064) (xy 125.95246 -260.771536) (xy 125.900498 -260.783396)
			(xy 125.847348 -260.78738) (xy 125.794198 -260.783396) (xy 125.742236 -260.771536) (xy 125.692622 -260.752064)
			(xy 125.646464 -260.725415) (xy 125.604793 -260.692184) (xy 125.568541 -260.653113) (xy 125.538517 -260.609076)
			(xy 125.515391 -260.561055) (xy 125.499681 -260.510125) (xy 125.491738 -260.457421) (xy 125.263158 -260.457421)
			(xy 125.255215 -260.510125) (xy 125.239505 -260.561055) (xy 125.216379 -260.609076) (xy 125.186355 -260.653113)
			(xy 125.150103 -260.692184) (xy 125.108432 -260.725415) (xy 125.062274 -260.752064) (xy 125.01266 -260.771536)
			(xy 124.960698 -260.783396) (xy 124.907548 -260.78738) (xy 124.854398 -260.783396) (xy 124.802436 -260.771536)
			(xy 124.752822 -260.752064) (xy 124.706664 -260.725415) (xy 124.664993 -260.692184) (xy 124.628741 -260.653113)
			(xy 124.598717 -260.609076) (xy 124.575591 -260.561055) (xy 124.559881 -260.510125) (xy 124.551938 -260.457421)
			(xy 124.323358 -260.457421) (xy 124.315415 -260.510125) (xy 124.299705 -260.561055) (xy 124.276579 -260.609076)
			(xy 124.246555 -260.653113) (xy 124.210303 -260.692184) (xy 124.168632 -260.725415) (xy 124.122474 -260.752064)
			(xy 124.07286 -260.771536) (xy 124.020898 -260.783396) (xy 123.967748 -260.78738) (xy 123.914598 -260.783396)
			(xy 123.862636 -260.771536) (xy 123.813022 -260.752064) (xy 123.766864 -260.725415) (xy 123.725193 -260.692184)
			(xy 123.688941 -260.653113) (xy 123.658917 -260.609076) (xy 123.635791 -260.561055) (xy 123.620081 -260.510125)
			(xy 123.612138 -260.457421) (xy 123.383558 -260.457421) (xy 123.375615 -260.510125) (xy 123.359905 -260.561055)
			(xy 123.336779 -260.609076) (xy 123.306755 -260.653113) (xy 123.270503 -260.692184) (xy 123.228832 -260.725415)
			(xy 123.182674 -260.752064) (xy 123.13306 -260.771536) (xy 123.081098 -260.783396) (xy 123.027948 -260.78738)
			(xy 122.974798 -260.783396) (xy 122.922836 -260.771536) (xy 122.873222 -260.752064) (xy 122.827064 -260.725415)
			(xy 122.785393 -260.692184) (xy 122.749141 -260.653113) (xy 122.719117 -260.609076) (xy 122.695991 -260.561055)
			(xy 122.680281 -260.510125) (xy 122.672338 -260.457421) (xy 122.443758 -260.457421) (xy 122.435815 -260.510125)
			(xy 122.420105 -260.561055) (xy 122.396979 -260.609076) (xy 122.366955 -260.653113) (xy 122.330703 -260.692184)
			(xy 122.289032 -260.725415) (xy 122.242874 -260.752064) (xy 122.19326 -260.771536) (xy 122.141298 -260.783396)
			(xy 122.088148 -260.78738) (xy 122.034998 -260.783396) (xy 121.983036 -260.771536) (xy 121.933422 -260.752064)
			(xy 121.887264 -260.725415) (xy 121.845593 -260.692184) (xy 121.809341 -260.653113) (xy 121.779317 -260.609076)
			(xy 121.756191 -260.561055) (xy 121.740481 -260.510125) (xy 121.732538 -260.457421) (xy 119.953807 -260.457421)
			(xy 119.41048 -261.000748) (xy 119.41048 -261.271491) (xy 121.262384 -261.271491) (xy 121.262384 -261.218193)
			(xy 121.270327 -261.165489) (xy 121.286037 -261.114559) (xy 121.309163 -261.066538) (xy 121.339187 -261.022501)
			(xy 121.375439 -260.98343) (xy 121.41711 -260.950199) (xy 121.463268 -260.92355) (xy 121.512882 -260.904078)
			(xy 121.564844 -260.892218) (xy 121.617994 -260.888235) (xy 121.671144 -260.892218) (xy 121.723106 -260.904078)
			(xy 121.77272 -260.92355) (xy 121.818878 -260.950199) (xy 121.860549 -260.98343) (xy 121.896801 -261.022501)
			(xy 121.926825 -261.066538) (xy 121.949951 -261.114559) (xy 121.965661 -261.165489) (xy 121.973604 -261.218193)
			(xy 121.974102 -261.244842) (xy 121.973604 -261.271491) (xy 122.202184 -261.271491) (xy 122.202184 -261.218193)
			(xy 122.210127 -261.165489) (xy 122.225837 -261.114559) (xy 122.248963 -261.066538) (xy 122.278987 -261.022501)
			(xy 122.315239 -260.98343) (xy 122.35691 -260.950199) (xy 122.403068 -260.92355) (xy 122.452682 -260.904078)
			(xy 122.504644 -260.892218) (xy 122.557794 -260.888235) (xy 122.610944 -260.892218) (xy 122.662906 -260.904078)
			(xy 122.71252 -260.92355) (xy 122.758678 -260.950199) (xy 122.800349 -260.98343) (xy 122.836601 -261.022501)
			(xy 122.866625 -261.066538) (xy 122.889751 -261.114559) (xy 122.905461 -261.165489) (xy 122.913404 -261.218193)
			(xy 122.913902 -261.244842) (xy 122.913404 -261.271491) (xy 123.141984 -261.271491) (xy 123.141984 -261.218193)
			(xy 123.149927 -261.165489) (xy 123.165637 -261.114559) (xy 123.188763 -261.066538) (xy 123.218787 -261.022501)
			(xy 123.255039 -260.98343) (xy 123.29671 -260.950199) (xy 123.342868 -260.92355) (xy 123.392482 -260.904078)
			(xy 123.444444 -260.892218) (xy 123.497594 -260.888235) (xy 123.550744 -260.892218) (xy 123.602706 -260.904078)
			(xy 123.65232 -260.92355) (xy 123.698478 -260.950199) (xy 123.740149 -260.98343) (xy 123.776401 -261.022501)
			(xy 123.806425 -261.066538) (xy 123.829551 -261.114559) (xy 123.845261 -261.165489) (xy 123.853204 -261.218193)
			(xy 123.853702 -261.244842) (xy 123.853204 -261.271491) (xy 124.081784 -261.271491) (xy 124.081784 -261.218193)
			(xy 124.089727 -261.165489) (xy 124.105437 -261.114559) (xy 124.128563 -261.066538) (xy 124.158587 -261.022501)
			(xy 124.194839 -260.98343) (xy 124.23651 -260.950199) (xy 124.282668 -260.92355) (xy 124.332282 -260.904078)
			(xy 124.384244 -260.892218) (xy 124.437394 -260.888235) (xy 124.490544 -260.892218) (xy 124.542506 -260.904078)
			(xy 124.59212 -260.92355) (xy 124.638278 -260.950199) (xy 124.679949 -260.98343) (xy 124.716201 -261.022501)
			(xy 124.746225 -261.066538) (xy 124.769351 -261.114559) (xy 124.785061 -261.165489) (xy 124.793004 -261.218193)
			(xy 124.793502 -261.244842) (xy 124.793004 -261.271491) (xy 125.021584 -261.271491) (xy 125.021584 -261.218193)
			(xy 125.029527 -261.165489) (xy 125.045237 -261.114559) (xy 125.068363 -261.066538) (xy 125.098387 -261.022501)
			(xy 125.134639 -260.98343) (xy 125.17631 -260.950199) (xy 125.222468 -260.92355) (xy 125.272082 -260.904078)
			(xy 125.324044 -260.892218) (xy 125.377194 -260.888235) (xy 125.430344 -260.892218) (xy 125.482306 -260.904078)
			(xy 125.53192 -260.92355) (xy 125.578078 -260.950199) (xy 125.619749 -260.98343) (xy 125.656001 -261.022501)
			(xy 125.686025 -261.066538) (xy 125.709151 -261.114559) (xy 125.724861 -261.165489) (xy 125.732804 -261.218193)
			(xy 125.733302 -261.244842) (xy 125.732804 -261.271491) (xy 125.961384 -261.271491) (xy 125.961384 -261.218193)
			(xy 125.969327 -261.165489) (xy 125.985037 -261.114559) (xy 126.008163 -261.066538) (xy 126.038187 -261.022501)
			(xy 126.074439 -260.98343) (xy 126.11611 -260.950199) (xy 126.162268 -260.92355) (xy 126.211882 -260.904078)
			(xy 126.263844 -260.892218) (xy 126.316994 -260.888235) (xy 126.370144 -260.892218) (xy 126.422106 -260.904078)
			(xy 126.47172 -260.92355) (xy 126.517878 -260.950199) (xy 126.559549 -260.98343) (xy 126.595801 -261.022501)
			(xy 126.625825 -261.066538) (xy 126.648951 -261.114559) (xy 126.664661 -261.165489) (xy 126.672604 -261.218193)
			(xy 126.673102 -261.244842) (xy 126.672604 -261.271491) (xy 126.901184 -261.271491) (xy 126.901184 -261.218193)
			(xy 126.909127 -261.165489) (xy 126.924837 -261.114559) (xy 126.947963 -261.066538) (xy 126.977987 -261.022501)
			(xy 127.014239 -260.98343) (xy 127.05591 -260.950199) (xy 127.102068 -260.92355) (xy 127.151682 -260.904078)
			(xy 127.203644 -260.892218) (xy 127.256794 -260.888235) (xy 127.309944 -260.892218) (xy 127.361906 -260.904078)
			(xy 127.41152 -260.92355) (xy 127.457678 -260.950199) (xy 127.499349 -260.98343) (xy 127.535601 -261.022501)
			(xy 127.565625 -261.066538) (xy 127.588751 -261.114559) (xy 127.604461 -261.165489) (xy 127.612404 -261.218193)
			(xy 127.612902 -261.244842) (xy 127.612404 -261.271491) (xy 127.840984 -261.271491) (xy 127.840984 -261.218193)
			(xy 127.848927 -261.165489) (xy 127.864637 -261.114559) (xy 127.887763 -261.066538) (xy 127.917787 -261.022501)
			(xy 127.954039 -260.98343) (xy 127.99571 -260.950199) (xy 128.041868 -260.92355) (xy 128.091482 -260.904078)
			(xy 128.143444 -260.892218) (xy 128.196594 -260.888235) (xy 128.249744 -260.892218) (xy 128.301706 -260.904078)
			(xy 128.35132 -260.92355) (xy 128.397478 -260.950199) (xy 128.439149 -260.98343) (xy 128.475401 -261.022501)
			(xy 128.505425 -261.066538) (xy 128.528551 -261.114559) (xy 128.544261 -261.165489) (xy 128.552204 -261.218193)
			(xy 128.552702 -261.244842) (xy 128.552204 -261.271491) (xy 128.780784 -261.271491) (xy 128.780784 -261.218193)
			(xy 128.788727 -261.165489) (xy 128.804437 -261.114559) (xy 128.827563 -261.066538) (xy 128.857587 -261.022501)
			(xy 128.893839 -260.98343) (xy 128.93551 -260.950199) (xy 128.981668 -260.92355) (xy 129.031282 -260.904078)
			(xy 129.083244 -260.892218) (xy 129.136394 -260.888235) (xy 129.189544 -260.892218) (xy 129.241506 -260.904078)
			(xy 129.29112 -260.92355) (xy 129.337278 -260.950199) (xy 129.378949 -260.98343) (xy 129.415201 -261.022501)
			(xy 129.445225 -261.066538) (xy 129.468351 -261.114559) (xy 129.484061 -261.165489) (xy 129.492004 -261.218193)
			(xy 129.492502 -261.244842) (xy 129.492004 -261.271491) (xy 129.720584 -261.271491) (xy 129.720584 -261.218193)
			(xy 129.728527 -261.165489) (xy 129.744237 -261.114559) (xy 129.767363 -261.066538) (xy 129.797387 -261.022501)
			(xy 129.833639 -260.98343) (xy 129.87531 -260.950199) (xy 129.921468 -260.92355) (xy 129.971082 -260.904078)
			(xy 130.023044 -260.892218) (xy 130.076194 -260.888235) (xy 130.129344 -260.892218) (xy 130.181306 -260.904078)
			(xy 130.23092 -260.92355) (xy 130.277078 -260.950199) (xy 130.318749 -260.98343) (xy 130.355001 -261.022501)
			(xy 130.385025 -261.066538) (xy 130.408151 -261.114559) (xy 130.423861 -261.165489) (xy 130.431804 -261.218193)
			(xy 130.432302 -261.244842) (xy 130.431804 -261.271491) (xy 130.660384 -261.271491) (xy 130.660384 -261.218193)
			(xy 130.668327 -261.165489) (xy 130.684037 -261.114559) (xy 130.707163 -261.066538) (xy 130.737187 -261.022501)
			(xy 130.773439 -260.98343) (xy 130.81511 -260.950199) (xy 130.861268 -260.92355) (xy 130.910882 -260.904078)
			(xy 130.962844 -260.892218) (xy 131.015994 -260.888235) (xy 131.069144 -260.892218) (xy 131.121106 -260.904078)
			(xy 131.17072 -260.92355) (xy 131.216878 -260.950199) (xy 131.258549 -260.98343) (xy 131.294801 -261.022501)
			(xy 131.324825 -261.066538) (xy 131.347951 -261.114559) (xy 131.363661 -261.165489) (xy 131.371604 -261.218193)
			(xy 131.372102 -261.244842) (xy 131.371604 -261.271491) (xy 131.600184 -261.271491) (xy 131.600184 -261.218193)
			(xy 131.608127 -261.165489) (xy 131.623837 -261.114559) (xy 131.646963 -261.066538) (xy 131.676987 -261.022501)
			(xy 131.713239 -260.98343) (xy 131.75491 -260.950199) (xy 131.801068 -260.92355) (xy 131.850682 -260.904078)
			(xy 131.902644 -260.892218) (xy 131.955794 -260.888235) (xy 132.008944 -260.892218) (xy 132.060906 -260.904078)
			(xy 132.11052 -260.92355) (xy 132.156678 -260.950199) (xy 132.198349 -260.98343) (xy 132.234601 -261.022501)
			(xy 132.264625 -261.066538) (xy 132.287751 -261.114559) (xy 132.303461 -261.165489) (xy 132.311404 -261.218193)
			(xy 132.311902 -261.244842) (xy 132.311404 -261.271491) (xy 132.539984 -261.271491) (xy 132.539984 -261.218193)
			(xy 132.547927 -261.165489) (xy 132.563637 -261.114559) (xy 132.586763 -261.066538) (xy 132.616787 -261.022501)
			(xy 132.653039 -260.98343) (xy 132.69471 -260.950199) (xy 132.740868 -260.92355) (xy 132.790482 -260.904078)
			(xy 132.842444 -260.892218) (xy 132.895594 -260.888235) (xy 132.948744 -260.892218) (xy 133.000706 -260.904078)
			(xy 133.05032 -260.92355) (xy 133.096478 -260.950199) (xy 133.138149 -260.98343) (xy 133.174401 -261.022501)
			(xy 133.204425 -261.066538) (xy 133.227551 -261.114559) (xy 133.243261 -261.165489) (xy 133.251204 -261.218193)
			(xy 133.251702 -261.244842) (xy 133.251204 -261.271491) (xy 133.479784 -261.271491) (xy 133.479784 -261.218193)
			(xy 133.487727 -261.165489) (xy 133.503437 -261.114559) (xy 133.526563 -261.066538) (xy 133.556587 -261.022501)
			(xy 133.592839 -260.98343) (xy 133.63451 -260.950199) (xy 133.680668 -260.92355) (xy 133.730282 -260.904078)
			(xy 133.782244 -260.892218) (xy 133.835394 -260.888235) (xy 133.888544 -260.892218) (xy 133.940506 -260.904078)
			(xy 133.99012 -260.92355) (xy 134.036278 -260.950199) (xy 134.077949 -260.98343) (xy 134.114201 -261.022501)
			(xy 134.144225 -261.066538) (xy 134.167351 -261.114559) (xy 134.183061 -261.165489) (xy 134.191004 -261.218193)
			(xy 134.191502 -261.244842) (xy 134.191004 -261.271491) (xy 134.183061 -261.324195) (xy 134.167351 -261.375125)
			(xy 134.144225 -261.423146) (xy 134.114201 -261.467183) (xy 134.077949 -261.506254) (xy 134.036278 -261.539485)
			(xy 133.99012 -261.566134) (xy 133.940506 -261.585606) (xy 133.888544 -261.597466) (xy 133.835394 -261.60145)
			(xy 133.782244 -261.597466) (xy 133.730282 -261.585606) (xy 133.680668 -261.566134) (xy 133.63451 -261.539485)
			(xy 133.592839 -261.506254) (xy 133.556587 -261.467183) (xy 133.526563 -261.423146) (xy 133.503437 -261.375125)
			(xy 133.487727 -261.324195) (xy 133.479784 -261.271491) (xy 133.251204 -261.271491) (xy 133.243261 -261.324195)
			(xy 133.227551 -261.375125) (xy 133.204425 -261.423146) (xy 133.174401 -261.467183) (xy 133.138149 -261.506254)
			(xy 133.096478 -261.539485) (xy 133.05032 -261.566134) (xy 133.000706 -261.585606) (xy 132.948744 -261.597466)
			(xy 132.895594 -261.60145) (xy 132.842444 -261.597466) (xy 132.790482 -261.585606) (xy 132.740868 -261.566134)
			(xy 132.69471 -261.539485) (xy 132.653039 -261.506254) (xy 132.616787 -261.467183) (xy 132.586763 -261.423146)
			(xy 132.563637 -261.375125) (xy 132.547927 -261.324195) (xy 132.539984 -261.271491) (xy 132.311404 -261.271491)
			(xy 132.303461 -261.324195) (xy 132.287751 -261.375125) (xy 132.264625 -261.423146) (xy 132.234601 -261.467183)
			(xy 132.198349 -261.506254) (xy 132.156678 -261.539485) (xy 132.11052 -261.566134) (xy 132.060906 -261.585606)
			(xy 132.008944 -261.597466) (xy 131.955794 -261.60145) (xy 131.902644 -261.597466) (xy 131.850682 -261.585606)
			(xy 131.801068 -261.566134) (xy 131.75491 -261.539485) (xy 131.713239 -261.506254) (xy 131.676987 -261.467183)
			(xy 131.646963 -261.423146) (xy 131.623837 -261.375125) (xy 131.608127 -261.324195) (xy 131.600184 -261.271491)
			(xy 131.371604 -261.271491) (xy 131.363661 -261.324195) (xy 131.347951 -261.375125) (xy 131.324825 -261.423146)
			(xy 131.294801 -261.467183) (xy 131.258549 -261.506254) (xy 131.216878 -261.539485) (xy 131.17072 -261.566134)
			(xy 131.121106 -261.585606) (xy 131.069144 -261.597466) (xy 131.015994 -261.60145) (xy 130.962844 -261.597466)
			(xy 130.910882 -261.585606) (xy 130.861268 -261.566134) (xy 130.81511 -261.539485) (xy 130.773439 -261.506254)
			(xy 130.737187 -261.467183) (xy 130.707163 -261.423146) (xy 130.684037 -261.375125) (xy 130.668327 -261.324195)
			(xy 130.660384 -261.271491) (xy 130.431804 -261.271491) (xy 130.423861 -261.324195) (xy 130.408151 -261.375125)
			(xy 130.385025 -261.423146) (xy 130.355001 -261.467183) (xy 130.318749 -261.506254) (xy 130.277078 -261.539485)
			(xy 130.23092 -261.566134) (xy 130.181306 -261.585606) (xy 130.129344 -261.597466) (xy 130.076194 -261.60145)
			(xy 130.023044 -261.597466) (xy 129.971082 -261.585606) (xy 129.921468 -261.566134) (xy 129.87531 -261.539485)
			(xy 129.833639 -261.506254) (xy 129.797387 -261.467183) (xy 129.767363 -261.423146) (xy 129.744237 -261.375125)
			(xy 129.728527 -261.324195) (xy 129.720584 -261.271491) (xy 129.492004 -261.271491) (xy 129.484061 -261.324195)
			(xy 129.468351 -261.375125) (xy 129.445225 -261.423146) (xy 129.415201 -261.467183) (xy 129.378949 -261.506254)
			(xy 129.337278 -261.539485) (xy 129.29112 -261.566134) (xy 129.241506 -261.585606) (xy 129.189544 -261.597466)
			(xy 129.136394 -261.60145) (xy 129.083244 -261.597466) (xy 129.031282 -261.585606) (xy 128.981668 -261.566134)
			(xy 128.93551 -261.539485) (xy 128.893839 -261.506254) (xy 128.857587 -261.467183) (xy 128.827563 -261.423146)
			(xy 128.804437 -261.375125) (xy 128.788727 -261.324195) (xy 128.780784 -261.271491) (xy 128.552204 -261.271491)
			(xy 128.544261 -261.324195) (xy 128.528551 -261.375125) (xy 128.505425 -261.423146) (xy 128.475401 -261.467183)
			(xy 128.439149 -261.506254) (xy 128.397478 -261.539485) (xy 128.35132 -261.566134) (xy 128.301706 -261.585606)
			(xy 128.249744 -261.597466) (xy 128.196594 -261.60145) (xy 128.143444 -261.597466) (xy 128.091482 -261.585606)
			(xy 128.041868 -261.566134) (xy 127.99571 -261.539485) (xy 127.954039 -261.506254) (xy 127.917787 -261.467183)
			(xy 127.887763 -261.423146) (xy 127.864637 -261.375125) (xy 127.848927 -261.324195) (xy 127.840984 -261.271491)
			(xy 127.612404 -261.271491) (xy 127.604461 -261.324195) (xy 127.588751 -261.375125) (xy 127.565625 -261.423146)
			(xy 127.535601 -261.467183) (xy 127.499349 -261.506254) (xy 127.457678 -261.539485) (xy 127.41152 -261.566134)
			(xy 127.361906 -261.585606) (xy 127.309944 -261.597466) (xy 127.256794 -261.60145) (xy 127.203644 -261.597466)
			(xy 127.151682 -261.585606) (xy 127.102068 -261.566134) (xy 127.05591 -261.539485) (xy 127.014239 -261.506254)
			(xy 126.977987 -261.467183) (xy 126.947963 -261.423146) (xy 126.924837 -261.375125) (xy 126.909127 -261.324195)
			(xy 126.901184 -261.271491) (xy 126.672604 -261.271491) (xy 126.664661 -261.324195) (xy 126.648951 -261.375125)
			(xy 126.625825 -261.423146) (xy 126.595801 -261.467183) (xy 126.559549 -261.506254) (xy 126.517878 -261.539485)
			(xy 126.47172 -261.566134) (xy 126.422106 -261.585606) (xy 126.370144 -261.597466) (xy 126.316994 -261.60145)
			(xy 126.263844 -261.597466) (xy 126.211882 -261.585606) (xy 126.162268 -261.566134) (xy 126.11611 -261.539485)
			(xy 126.074439 -261.506254) (xy 126.038187 -261.467183) (xy 126.008163 -261.423146) (xy 125.985037 -261.375125)
			(xy 125.969327 -261.324195) (xy 125.961384 -261.271491) (xy 125.732804 -261.271491) (xy 125.724861 -261.324195)
			(xy 125.709151 -261.375125) (xy 125.686025 -261.423146) (xy 125.656001 -261.467183) (xy 125.619749 -261.506254)
			(xy 125.578078 -261.539485) (xy 125.53192 -261.566134) (xy 125.482306 -261.585606) (xy 125.430344 -261.597466)
			(xy 125.377194 -261.60145) (xy 125.324044 -261.597466) (xy 125.272082 -261.585606) (xy 125.222468 -261.566134)
			(xy 125.17631 -261.539485) (xy 125.134639 -261.506254) (xy 125.098387 -261.467183) (xy 125.068363 -261.423146)
			(xy 125.045237 -261.375125) (xy 125.029527 -261.324195) (xy 125.021584 -261.271491) (xy 124.793004 -261.271491)
			(xy 124.785061 -261.324195) (xy 124.769351 -261.375125) (xy 124.746225 -261.423146) (xy 124.716201 -261.467183)
			(xy 124.679949 -261.506254) (xy 124.638278 -261.539485) (xy 124.59212 -261.566134) (xy 124.542506 -261.585606)
			(xy 124.490544 -261.597466) (xy 124.437394 -261.60145) (xy 124.384244 -261.597466) (xy 124.332282 -261.585606)
			(xy 124.282668 -261.566134) (xy 124.23651 -261.539485) (xy 124.194839 -261.506254) (xy 124.158587 -261.467183)
			(xy 124.128563 -261.423146) (xy 124.105437 -261.375125) (xy 124.089727 -261.324195) (xy 124.081784 -261.271491)
			(xy 123.853204 -261.271491) (xy 123.845261 -261.324195) (xy 123.829551 -261.375125) (xy 123.806425 -261.423146)
			(xy 123.776401 -261.467183) (xy 123.740149 -261.506254) (xy 123.698478 -261.539485) (xy 123.65232 -261.566134)
			(xy 123.602706 -261.585606) (xy 123.550744 -261.597466) (xy 123.497594 -261.60145) (xy 123.444444 -261.597466)
			(xy 123.392482 -261.585606) (xy 123.342868 -261.566134) (xy 123.29671 -261.539485) (xy 123.255039 -261.506254)
			(xy 123.218787 -261.467183) (xy 123.188763 -261.423146) (xy 123.165637 -261.375125) (xy 123.149927 -261.324195)
			(xy 123.141984 -261.271491) (xy 122.913404 -261.271491) (xy 122.905461 -261.324195) (xy 122.889751 -261.375125)
			(xy 122.866625 -261.423146) (xy 122.836601 -261.467183) (xy 122.800349 -261.506254) (xy 122.758678 -261.539485)
			(xy 122.71252 -261.566134) (xy 122.662906 -261.585606) (xy 122.610944 -261.597466) (xy 122.557794 -261.60145)
			(xy 122.504644 -261.597466) (xy 122.452682 -261.585606) (xy 122.403068 -261.566134) (xy 122.35691 -261.539485)
			(xy 122.315239 -261.506254) (xy 122.278987 -261.467183) (xy 122.248963 -261.423146) (xy 122.225837 -261.375125)
			(xy 122.210127 -261.324195) (xy 122.202184 -261.271491) (xy 121.973604 -261.271491) (xy 121.965661 -261.324195)
			(xy 121.949951 -261.375125) (xy 121.926825 -261.423146) (xy 121.896801 -261.467183) (xy 121.860549 -261.506254)
			(xy 121.818878 -261.539485) (xy 121.77272 -261.566134) (xy 121.723106 -261.585606) (xy 121.671144 -261.597466)
			(xy 121.617994 -261.60145) (xy 121.564844 -261.597466) (xy 121.512882 -261.585606) (xy 121.463268 -261.566134)
			(xy 121.41711 -261.539485) (xy 121.375439 -261.506254) (xy 121.339187 -261.467183) (xy 121.309163 -261.423146)
			(xy 121.286037 -261.375125) (xy 121.270327 -261.324195) (xy 121.262384 -261.271491) (xy 119.41048 -261.271491)
			(xy 119.41048 -262.085307) (xy 121.732538 -262.085307) (xy 121.732538 -262.032009) (xy 121.740481 -261.979305)
			(xy 121.756191 -261.928375) (xy 121.779317 -261.880354) (xy 121.809341 -261.836317) (xy 121.845593 -261.797246)
			(xy 121.887264 -261.764015) (xy 121.933422 -261.737366) (xy 121.983036 -261.717894) (xy 122.034998 -261.706034)
			(xy 122.088148 -261.702051) (xy 122.141298 -261.706034) (xy 122.19326 -261.717894) (xy 122.242874 -261.737366)
			(xy 122.289032 -261.764015) (xy 122.330703 -261.797246) (xy 122.366955 -261.836317) (xy 122.396979 -261.880354)
			(xy 122.420105 -261.928375) (xy 122.435815 -261.979305) (xy 122.443758 -262.032009) (xy 122.444256 -262.058658)
			(xy 122.443758 -262.085307) (xy 122.672084 -262.085307) (xy 122.672084 -262.032009) (xy 122.680027 -261.979305)
			(xy 122.695737 -261.928375) (xy 122.718863 -261.880354) (xy 122.748887 -261.836317) (xy 122.785139 -261.797246)
			(xy 122.82681 -261.764015) (xy 122.872968 -261.737366) (xy 122.922582 -261.717894) (xy 122.974544 -261.706034)
			(xy 123.027694 -261.702051) (xy 123.080844 -261.706034) (xy 123.132806 -261.717894) (xy 123.18242 -261.737366)
			(xy 123.228578 -261.764015) (xy 123.270249 -261.797246) (xy 123.306501 -261.836317) (xy 123.336525 -261.880354)
			(xy 123.359651 -261.928375) (xy 123.375361 -261.979305) (xy 123.383304 -262.032009) (xy 123.383802 -262.058658)
			(xy 123.383304 -262.085307) (xy 123.612138 -262.085307) (xy 123.612138 -262.032009) (xy 123.620081 -261.979305)
			(xy 123.635791 -261.928375) (xy 123.658917 -261.880354) (xy 123.688941 -261.836317) (xy 123.725193 -261.797246)
			(xy 123.766864 -261.764015) (xy 123.813022 -261.737366) (xy 123.862636 -261.717894) (xy 123.914598 -261.706034)
			(xy 123.967748 -261.702051) (xy 124.020898 -261.706034) (xy 124.07286 -261.717894) (xy 124.122474 -261.737366)
			(xy 124.168632 -261.764015) (xy 124.210303 -261.797246) (xy 124.246555 -261.836317) (xy 124.276579 -261.880354)
			(xy 124.299705 -261.928375) (xy 124.315415 -261.979305) (xy 124.323358 -262.032009) (xy 124.323856 -262.058658)
			(xy 124.323358 -262.085307) (xy 124.551938 -262.085307) (xy 124.551938 -262.032009) (xy 124.559881 -261.979305)
			(xy 124.575591 -261.928375) (xy 124.598717 -261.880354) (xy 124.628741 -261.836317) (xy 124.664993 -261.797246)
			(xy 124.706664 -261.764015) (xy 124.752822 -261.737366) (xy 124.802436 -261.717894) (xy 124.854398 -261.706034)
			(xy 124.907548 -261.702051) (xy 124.960698 -261.706034) (xy 125.01266 -261.717894) (xy 125.062274 -261.737366)
			(xy 125.108432 -261.764015) (xy 125.150103 -261.797246) (xy 125.186355 -261.836317) (xy 125.216379 -261.880354)
			(xy 125.239505 -261.928375) (xy 125.255215 -261.979305) (xy 125.263158 -262.032009) (xy 125.263656 -262.058658)
			(xy 125.263158 -262.085307) (xy 125.491484 -262.085307) (xy 125.491484 -262.032009) (xy 125.499427 -261.979305)
			(xy 125.515137 -261.928375) (xy 125.538263 -261.880354) (xy 125.568287 -261.836317) (xy 125.604539 -261.797246)
			(xy 125.64621 -261.764015) (xy 125.692368 -261.737366) (xy 125.741982 -261.717894) (xy 125.793944 -261.706034)
			(xy 125.847094 -261.702051) (xy 125.900244 -261.706034) (xy 125.952206 -261.717894) (xy 126.00182 -261.737366)
			(xy 126.047978 -261.764015) (xy 126.089649 -261.797246) (xy 126.125901 -261.836317) (xy 126.155925 -261.880354)
			(xy 126.179051 -261.928375) (xy 126.194761 -261.979305) (xy 126.202704 -262.032009) (xy 126.203202 -262.058658)
			(xy 126.202704 -262.085307) (xy 126.431538 -262.085307) (xy 126.431538 -262.032009) (xy 126.439481 -261.979305)
			(xy 126.455191 -261.928375) (xy 126.478317 -261.880354) (xy 126.508341 -261.836317) (xy 126.544593 -261.797246)
			(xy 126.586264 -261.764015) (xy 126.632422 -261.737366) (xy 126.682036 -261.717894) (xy 126.733998 -261.706034)
			(xy 126.787148 -261.702051) (xy 126.840298 -261.706034) (xy 126.89226 -261.717894) (xy 126.941874 -261.737366)
			(xy 126.988032 -261.764015) (xy 127.029703 -261.797246) (xy 127.065955 -261.836317) (xy 127.095979 -261.880354)
			(xy 127.119105 -261.928375) (xy 127.134815 -261.979305) (xy 127.142758 -262.032009) (xy 127.143256 -262.058658)
			(xy 127.142758 -262.085307) (xy 127.371338 -262.085307) (xy 127.371338 -262.032009) (xy 127.379281 -261.979305)
			(xy 127.394991 -261.928375) (xy 127.418117 -261.880354) (xy 127.448141 -261.836317) (xy 127.484393 -261.797246)
			(xy 127.526064 -261.764015) (xy 127.572222 -261.737366) (xy 127.621836 -261.717894) (xy 127.673798 -261.706034)
			(xy 127.726948 -261.702051) (xy 127.780098 -261.706034) (xy 127.83206 -261.717894) (xy 127.881674 -261.737366)
			(xy 127.927832 -261.764015) (xy 127.969503 -261.797246) (xy 128.005755 -261.836317) (xy 128.035779 -261.880354)
			(xy 128.058905 -261.928375) (xy 128.074615 -261.979305) (xy 128.082558 -262.032009) (xy 128.083056 -262.058658)
			(xy 128.082558 -262.085307) (xy 128.311138 -262.085307) (xy 128.311138 -262.032009) (xy 128.319081 -261.979305)
			(xy 128.334791 -261.928375) (xy 128.357917 -261.880354) (xy 128.387941 -261.836317) (xy 128.424193 -261.797246)
			(xy 128.465864 -261.764015) (xy 128.512022 -261.737366) (xy 128.561636 -261.717894) (xy 128.613598 -261.706034)
			(xy 128.666748 -261.702051) (xy 128.719898 -261.706034) (xy 128.77186 -261.717894) (xy 128.821474 -261.737366)
			(xy 128.867632 -261.764015) (xy 128.909303 -261.797246) (xy 128.945555 -261.836317) (xy 128.975579 -261.880354)
			(xy 128.998705 -261.928375) (xy 129.014415 -261.979305) (xy 129.022358 -262.032009) (xy 129.022856 -262.058658)
			(xy 129.022358 -262.085307) (xy 129.250938 -262.085307) (xy 129.250938 -262.032009) (xy 129.258881 -261.979305)
			(xy 129.274591 -261.928375) (xy 129.297717 -261.880354) (xy 129.327741 -261.836317) (xy 129.363993 -261.797246)
			(xy 129.405664 -261.764015) (xy 129.451822 -261.737366) (xy 129.501436 -261.717894) (xy 129.553398 -261.706034)
			(xy 129.606548 -261.702051) (xy 129.659698 -261.706034) (xy 129.71166 -261.717894) (xy 129.761274 -261.737366)
			(xy 129.807432 -261.764015) (xy 129.849103 -261.797246) (xy 129.885355 -261.836317) (xy 129.915379 -261.880354)
			(xy 129.938505 -261.928375) (xy 129.954215 -261.979305) (xy 129.962158 -262.032009) (xy 129.962656 -262.058658)
			(xy 129.962158 -262.085307) (xy 130.190738 -262.085307) (xy 130.190738 -262.032009) (xy 130.198681 -261.979305)
			(xy 130.214391 -261.928375) (xy 130.237517 -261.880354) (xy 130.267541 -261.836317) (xy 130.303793 -261.797246)
			(xy 130.345464 -261.764015) (xy 130.391622 -261.737366) (xy 130.441236 -261.717894) (xy 130.493198 -261.706034)
			(xy 130.546348 -261.702051) (xy 130.599498 -261.706034) (xy 130.65146 -261.717894) (xy 130.701074 -261.737366)
			(xy 130.747232 -261.764015) (xy 130.788903 -261.797246) (xy 130.825155 -261.836317) (xy 130.855179 -261.880354)
			(xy 130.878305 -261.928375) (xy 130.894015 -261.979305) (xy 130.901958 -262.032009) (xy 130.902456 -262.058658)
			(xy 130.901958 -262.085307) (xy 131.130538 -262.085307) (xy 131.130538 -262.032009) (xy 131.138481 -261.979305)
			(xy 131.154191 -261.928375) (xy 131.177317 -261.880354) (xy 131.207341 -261.836317) (xy 131.243593 -261.797246)
			(xy 131.285264 -261.764015) (xy 131.331422 -261.737366) (xy 131.381036 -261.717894) (xy 131.432998 -261.706034)
			(xy 131.486148 -261.702051) (xy 131.539298 -261.706034) (xy 131.59126 -261.717894) (xy 131.640874 -261.737366)
			(xy 131.687032 -261.764015) (xy 131.728703 -261.797246) (xy 131.764955 -261.836317) (xy 131.794979 -261.880354)
			(xy 131.818105 -261.928375) (xy 131.833815 -261.979305) (xy 131.841758 -262.032009) (xy 131.842256 -262.058658)
			(xy 131.841758 -262.085307) (xy 132.070084 -262.085307) (xy 132.070084 -262.032009) (xy 132.078027 -261.979305)
			(xy 132.093737 -261.928375) (xy 132.116863 -261.880354) (xy 132.146887 -261.836317) (xy 132.183139 -261.797246)
			(xy 132.22481 -261.764015) (xy 132.270968 -261.737366) (xy 132.320582 -261.717894) (xy 132.372544 -261.706034)
			(xy 132.425694 -261.702051) (xy 132.478844 -261.706034) (xy 132.530806 -261.717894) (xy 132.58042 -261.737366)
			(xy 132.626578 -261.764015) (xy 132.668249 -261.797246) (xy 132.704501 -261.836317) (xy 132.734525 -261.880354)
			(xy 132.757651 -261.928375) (xy 132.773361 -261.979305) (xy 132.781304 -262.032009) (xy 132.781802 -262.058658)
			(xy 132.781304 -262.085307) (xy 133.010138 -262.085307) (xy 133.010138 -262.032009) (xy 133.018081 -261.979305)
			(xy 133.033791 -261.928375) (xy 133.056917 -261.880354) (xy 133.086941 -261.836317) (xy 133.123193 -261.797246)
			(xy 133.164864 -261.764015) (xy 133.211022 -261.737366) (xy 133.260636 -261.717894) (xy 133.312598 -261.706034)
			(xy 133.365748 -261.702051) (xy 133.418898 -261.706034) (xy 133.47086 -261.717894) (xy 133.520474 -261.737366)
			(xy 133.566632 -261.764015) (xy 133.608303 -261.797246) (xy 133.644555 -261.836317) (xy 133.674579 -261.880354)
			(xy 133.697705 -261.928375) (xy 133.713415 -261.979305) (xy 133.721358 -262.032009) (xy 133.721856 -262.058658)
			(xy 133.721358 -262.085307) (xy 133.949938 -262.085307) (xy 133.949938 -262.032009) (xy 133.957881 -261.979305)
			(xy 133.973591 -261.928375) (xy 133.996717 -261.880354) (xy 134.026741 -261.836317) (xy 134.062993 -261.797246)
			(xy 134.104664 -261.764015) (xy 134.150822 -261.737366) (xy 134.200436 -261.717894) (xy 134.252398 -261.706034)
			(xy 134.305548 -261.702051) (xy 134.358698 -261.706034) (xy 134.41066 -261.717894) (xy 134.460274 -261.737366)
			(xy 134.506432 -261.764015) (xy 134.548103 -261.797246) (xy 134.584355 -261.836317) (xy 134.614379 -261.880354)
			(xy 134.637505 -261.928375) (xy 134.653215 -261.979305) (xy 134.661158 -262.032009) (xy 134.661656 -262.058658)
			(xy 134.661158 -262.085307) (xy 134.653215 -262.138011) (xy 134.637505 -262.188941) (xy 134.614379 -262.236962)
			(xy 134.584355 -262.280999) (xy 134.548103 -262.32007) (xy 134.506432 -262.353301) (xy 134.460274 -262.37995)
			(xy 134.41066 -262.399422) (xy 134.358698 -262.411282) (xy 134.305548 -262.415266) (xy 134.252398 -262.411282)
			(xy 134.200436 -262.399422) (xy 134.150822 -262.37995) (xy 134.104664 -262.353301) (xy 134.062993 -262.32007)
			(xy 134.026741 -262.280999) (xy 133.996717 -262.236962) (xy 133.973591 -262.188941) (xy 133.957881 -262.138011)
			(xy 133.949938 -262.085307) (xy 133.721358 -262.085307) (xy 133.713415 -262.138011) (xy 133.697705 -262.188941)
			(xy 133.674579 -262.236962) (xy 133.644555 -262.280999) (xy 133.608303 -262.32007) (xy 133.566632 -262.353301)
			(xy 133.520474 -262.37995) (xy 133.47086 -262.399422) (xy 133.418898 -262.411282) (xy 133.365748 -262.415266)
			(xy 133.312598 -262.411282) (xy 133.260636 -262.399422) (xy 133.211022 -262.37995) (xy 133.164864 -262.353301)
			(xy 133.123193 -262.32007) (xy 133.086941 -262.280999) (xy 133.056917 -262.236962) (xy 133.033791 -262.188941)
			(xy 133.018081 -262.138011) (xy 133.010138 -262.085307) (xy 132.781304 -262.085307) (xy 132.773361 -262.138011)
			(xy 132.757651 -262.188941) (xy 132.734525 -262.236962) (xy 132.704501 -262.280999) (xy 132.668249 -262.32007)
			(xy 132.626578 -262.353301) (xy 132.58042 -262.37995) (xy 132.530806 -262.399422) (xy 132.478844 -262.411282)
			(xy 132.425694 -262.415266) (xy 132.372544 -262.411282) (xy 132.320582 -262.399422) (xy 132.270968 -262.37995)
			(xy 132.22481 -262.353301) (xy 132.183139 -262.32007) (xy 132.146887 -262.280999) (xy 132.116863 -262.236962)
			(xy 132.093737 -262.188941) (xy 132.078027 -262.138011) (xy 132.070084 -262.085307) (xy 131.841758 -262.085307)
			(xy 131.833815 -262.138011) (xy 131.818105 -262.188941) (xy 131.794979 -262.236962) (xy 131.764955 -262.280999)
			(xy 131.728703 -262.32007) (xy 131.687032 -262.353301) (xy 131.640874 -262.37995) (xy 131.59126 -262.399422)
			(xy 131.539298 -262.411282) (xy 131.486148 -262.415266) (xy 131.432998 -262.411282) (xy 131.381036 -262.399422)
			(xy 131.331422 -262.37995) (xy 131.285264 -262.353301) (xy 131.243593 -262.32007) (xy 131.207341 -262.280999)
			(xy 131.177317 -262.236962) (xy 131.154191 -262.188941) (xy 131.138481 -262.138011) (xy 131.130538 -262.085307)
			(xy 130.901958 -262.085307) (xy 130.894015 -262.138011) (xy 130.878305 -262.188941) (xy 130.855179 -262.236962)
			(xy 130.825155 -262.280999) (xy 130.788903 -262.32007) (xy 130.747232 -262.353301) (xy 130.701074 -262.37995)
			(xy 130.65146 -262.399422) (xy 130.599498 -262.411282) (xy 130.546348 -262.415266) (xy 130.493198 -262.411282)
			(xy 130.441236 -262.399422) (xy 130.391622 -262.37995) (xy 130.345464 -262.353301) (xy 130.303793 -262.32007)
			(xy 130.267541 -262.280999) (xy 130.237517 -262.236962) (xy 130.214391 -262.188941) (xy 130.198681 -262.138011)
			(xy 130.190738 -262.085307) (xy 129.962158 -262.085307) (xy 129.954215 -262.138011) (xy 129.938505 -262.188941)
			(xy 129.915379 -262.236962) (xy 129.885355 -262.280999) (xy 129.849103 -262.32007) (xy 129.807432 -262.353301)
			(xy 129.761274 -262.37995) (xy 129.71166 -262.399422) (xy 129.659698 -262.411282) (xy 129.606548 -262.415266)
			(xy 129.553398 -262.411282) (xy 129.501436 -262.399422) (xy 129.451822 -262.37995) (xy 129.405664 -262.353301)
			(xy 129.363993 -262.32007) (xy 129.327741 -262.280999) (xy 129.297717 -262.236962) (xy 129.274591 -262.188941)
			(xy 129.258881 -262.138011) (xy 129.250938 -262.085307) (xy 129.022358 -262.085307) (xy 129.014415 -262.138011)
			(xy 128.998705 -262.188941) (xy 128.975579 -262.236962) (xy 128.945555 -262.280999) (xy 128.909303 -262.32007)
			(xy 128.867632 -262.353301) (xy 128.821474 -262.37995) (xy 128.77186 -262.399422) (xy 128.719898 -262.411282)
			(xy 128.666748 -262.415266) (xy 128.613598 -262.411282) (xy 128.561636 -262.399422) (xy 128.512022 -262.37995)
			(xy 128.465864 -262.353301) (xy 128.424193 -262.32007) (xy 128.387941 -262.280999) (xy 128.357917 -262.236962)
			(xy 128.334791 -262.188941) (xy 128.319081 -262.138011) (xy 128.311138 -262.085307) (xy 128.082558 -262.085307)
			(xy 128.074615 -262.138011) (xy 128.058905 -262.188941) (xy 128.035779 -262.236962) (xy 128.005755 -262.280999)
			(xy 127.969503 -262.32007) (xy 127.927832 -262.353301) (xy 127.881674 -262.37995) (xy 127.83206 -262.399422)
			(xy 127.780098 -262.411282) (xy 127.726948 -262.415266) (xy 127.673798 -262.411282) (xy 127.621836 -262.399422)
			(xy 127.572222 -262.37995) (xy 127.526064 -262.353301) (xy 127.484393 -262.32007) (xy 127.448141 -262.280999)
			(xy 127.418117 -262.236962) (xy 127.394991 -262.188941) (xy 127.379281 -262.138011) (xy 127.371338 -262.085307)
			(xy 127.142758 -262.085307) (xy 127.134815 -262.138011) (xy 127.119105 -262.188941) (xy 127.095979 -262.236962)
			(xy 127.065955 -262.280999) (xy 127.029703 -262.32007) (xy 126.988032 -262.353301) (xy 126.941874 -262.37995)
			(xy 126.89226 -262.399422) (xy 126.840298 -262.411282) (xy 126.787148 -262.415266) (xy 126.733998 -262.411282)
			(xy 126.682036 -262.399422) (xy 126.632422 -262.37995) (xy 126.586264 -262.353301) (xy 126.544593 -262.32007)
			(xy 126.508341 -262.280999) (xy 126.478317 -262.236962) (xy 126.455191 -262.188941) (xy 126.439481 -262.138011)
			(xy 126.431538 -262.085307) (xy 126.202704 -262.085307) (xy 126.194761 -262.138011) (xy 126.179051 -262.188941)
			(xy 126.155925 -262.236962) (xy 126.125901 -262.280999) (xy 126.089649 -262.32007) (xy 126.047978 -262.353301)
			(xy 126.00182 -262.37995) (xy 125.952206 -262.399422) (xy 125.900244 -262.411282) (xy 125.847094 -262.415266)
			(xy 125.793944 -262.411282) (xy 125.741982 -262.399422) (xy 125.692368 -262.37995) (xy 125.64621 -262.353301)
			(xy 125.604539 -262.32007) (xy 125.568287 -262.280999) (xy 125.538263 -262.236962) (xy 125.515137 -262.188941)
			(xy 125.499427 -262.138011) (xy 125.491484 -262.085307) (xy 125.263158 -262.085307) (xy 125.255215 -262.138011)
			(xy 125.239505 -262.188941) (xy 125.216379 -262.236962) (xy 125.186355 -262.280999) (xy 125.150103 -262.32007)
			(xy 125.108432 -262.353301) (xy 125.062274 -262.37995) (xy 125.01266 -262.399422) (xy 124.960698 -262.411282)
			(xy 124.907548 -262.415266) (xy 124.854398 -262.411282) (xy 124.802436 -262.399422) (xy 124.752822 -262.37995)
			(xy 124.706664 -262.353301) (xy 124.664993 -262.32007) (xy 124.628741 -262.280999) (xy 124.598717 -262.236962)
			(xy 124.575591 -262.188941) (xy 124.559881 -262.138011) (xy 124.551938 -262.085307) (xy 124.323358 -262.085307)
			(xy 124.315415 -262.138011) (xy 124.299705 -262.188941) (xy 124.276579 -262.236962) (xy 124.246555 -262.280999)
			(xy 124.210303 -262.32007) (xy 124.168632 -262.353301) (xy 124.122474 -262.37995) (xy 124.07286 -262.399422)
			(xy 124.020898 -262.411282) (xy 123.967748 -262.415266) (xy 123.914598 -262.411282) (xy 123.862636 -262.399422)
			(xy 123.813022 -262.37995) (xy 123.766864 -262.353301) (xy 123.725193 -262.32007) (xy 123.688941 -262.280999)
			(xy 123.658917 -262.236962) (xy 123.635791 -262.188941) (xy 123.620081 -262.138011) (xy 123.612138 -262.085307)
			(xy 123.383304 -262.085307) (xy 123.375361 -262.138011) (xy 123.359651 -262.188941) (xy 123.336525 -262.236962)
			(xy 123.306501 -262.280999) (xy 123.270249 -262.32007) (xy 123.228578 -262.353301) (xy 123.18242 -262.37995)
			(xy 123.132806 -262.399422) (xy 123.080844 -262.411282) (xy 123.027694 -262.415266) (xy 122.974544 -262.411282)
			(xy 122.922582 -262.399422) (xy 122.872968 -262.37995) (xy 122.82681 -262.353301) (xy 122.785139 -262.32007)
			(xy 122.748887 -262.280999) (xy 122.718863 -262.236962) (xy 122.695737 -262.188941) (xy 122.680027 -262.138011)
			(xy 122.672084 -262.085307) (xy 122.443758 -262.085307) (xy 122.435815 -262.138011) (xy 122.420105 -262.188941)
			(xy 122.396979 -262.236962) (xy 122.366955 -262.280999) (xy 122.330703 -262.32007) (xy 122.289032 -262.353301)
			(xy 122.242874 -262.37995) (xy 122.19326 -262.399422) (xy 122.141298 -262.411282) (xy 122.088148 -262.415266)
			(xy 122.034998 -262.411282) (xy 121.983036 -262.399422) (xy 121.933422 -262.37995) (xy 121.887264 -262.353301)
			(xy 121.845593 -262.32007) (xy 121.809341 -262.280999) (xy 121.779317 -262.236962) (xy 121.756191 -262.188941)
			(xy 121.740481 -262.138011) (xy 121.732538 -262.085307) (xy 119.41048 -262.085307) (xy 119.41048 -262.863076)
			(xy 119.41099 -262.877658) (xy 119.419297 -262.905616) (xy 119.435156 -262.930093) (xy 119.457278 -262.9491)
			(xy 119.483864 -262.961092) (xy 119.512755 -262.965093) (xy 119.5416 -262.960779) (xy 119.555006 -262.955024)
			(xy 119.578697 -262.94446) (xy 119.628375 -262.929536) (xy 119.679693 -262.921981) (xy 119.705628 -262.921496)
			(xy 119.705882 -262.921496) (xy 119.731442 -262.921938) (xy 119.782035 -262.929257) (xy 119.831057 -262.943748)
			(xy 119.854472 -262.954008) (xy 119.867498 -262.95949) (xy 119.895418 -262.963804) (xy 119.923451 -262.960302)
			(xy 119.949452 -262.949254) (xy 119.97143 -262.931504) (xy 119.979948 -262.920226) (xy 119.996772 -262.897367)
			(xy 120.036456 -262.856794) (xy 120.082073 -262.823029) (xy 120.132469 -262.796927) (xy 120.186366 -262.779148)
			(xy 120.242401 -262.770143) (xy 120.270778 -262.769604) (xy 120.297429 -262.770076) (xy 120.350137 -262.778017)
			(xy 120.401072 -262.793726) (xy 120.449097 -262.816851) (xy 120.493139 -262.846875) (xy 120.532214 -262.883129)
			(xy 120.54497 -262.899123) (xy 121.262384 -262.899123) (xy 121.262384 -262.845825) (xy 121.270327 -262.793121)
			(xy 121.286037 -262.742191) (xy 121.309163 -262.69417) (xy 121.339187 -262.650133) (xy 121.375439 -262.611062)
			(xy 121.41711 -262.577831) (xy 121.463268 -262.551182) (xy 121.512882 -262.53171) (xy 121.564844 -262.51985)
			(xy 121.617994 -262.515867) (xy 121.671144 -262.51985) (xy 121.723106 -262.53171) (xy 121.77272 -262.551182)
			(xy 121.818878 -262.577831) (xy 121.860549 -262.611062) (xy 121.896801 -262.650133) (xy 121.926825 -262.69417)
			(xy 121.949951 -262.742191) (xy 121.965661 -262.793121) (xy 121.973604 -262.845825) (xy 121.974102 -262.872474)
			(xy 121.973604 -262.899123) (xy 122.202438 -262.899123) (xy 122.202438 -262.845825) (xy 122.210381 -262.793121)
			(xy 122.226091 -262.742191) (xy 122.249217 -262.69417) (xy 122.279241 -262.650133) (xy 122.315493 -262.611062)
			(xy 122.357164 -262.577831) (xy 122.403322 -262.551182) (xy 122.452936 -262.53171) (xy 122.504898 -262.51985)
			(xy 122.558048 -262.515867) (xy 122.611198 -262.51985) (xy 122.66316 -262.53171) (xy 122.712774 -262.551182)
			(xy 122.758932 -262.577831) (xy 122.800603 -262.611062) (xy 122.836855 -262.650133) (xy 122.866879 -262.69417)
			(xy 122.890005 -262.742191) (xy 122.905715 -262.793121) (xy 122.913658 -262.845825) (xy 122.914156 -262.872474)
			(xy 122.913658 -262.899123) (xy 123.141984 -262.899123) (xy 123.141984 -262.845825) (xy 123.149927 -262.793121)
			(xy 123.165637 -262.742191) (xy 123.188763 -262.69417) (xy 123.218787 -262.650133) (xy 123.255039 -262.611062)
			(xy 123.29671 -262.577831) (xy 123.342868 -262.551182) (xy 123.392482 -262.53171) (xy 123.444444 -262.51985)
			(xy 123.497594 -262.515867) (xy 123.550744 -262.51985) (xy 123.602706 -262.53171) (xy 123.65232 -262.551182)
			(xy 123.698478 -262.577831) (xy 123.740149 -262.611062) (xy 123.776401 -262.650133) (xy 123.806425 -262.69417)
			(xy 123.829551 -262.742191) (xy 123.845261 -262.793121) (xy 123.853204 -262.845825) (xy 123.853702 -262.872474)
			(xy 123.853204 -262.899123) (xy 124.081784 -262.899123) (xy 124.081784 -262.845825) (xy 124.089727 -262.793121)
			(xy 124.105437 -262.742191) (xy 124.128563 -262.69417) (xy 124.158587 -262.650133) (xy 124.194839 -262.611062)
			(xy 124.23651 -262.577831) (xy 124.282668 -262.551182) (xy 124.332282 -262.53171) (xy 124.384244 -262.51985)
			(xy 124.437394 -262.515867) (xy 124.490544 -262.51985) (xy 124.542506 -262.53171) (xy 124.59212 -262.551182)
			(xy 124.638278 -262.577831) (xy 124.679949 -262.611062) (xy 124.716201 -262.650133) (xy 124.746225 -262.69417)
			(xy 124.769351 -262.742191) (xy 124.785061 -262.793121) (xy 124.793004 -262.845825) (xy 124.793502 -262.872474)
			(xy 124.793004 -262.899123) (xy 125.021838 -262.899123) (xy 125.021838 -262.845825) (xy 125.029781 -262.793121)
			(xy 125.045491 -262.742191) (xy 125.068617 -262.69417) (xy 125.098641 -262.650133) (xy 125.134893 -262.611062)
			(xy 125.176564 -262.577831) (xy 125.222722 -262.551182) (xy 125.272336 -262.53171) (xy 125.324298 -262.51985)
			(xy 125.377448 -262.515867) (xy 125.430598 -262.51985) (xy 125.48256 -262.53171) (xy 125.532174 -262.551182)
			(xy 125.578332 -262.577831) (xy 125.620003 -262.611062) (xy 125.656255 -262.650133) (xy 125.686279 -262.69417)
			(xy 125.709405 -262.742191) (xy 125.725115 -262.793121) (xy 125.733058 -262.845825) (xy 125.733556 -262.872474)
			(xy 125.733058 -262.899123) (xy 125.961384 -262.899123) (xy 125.961384 -262.845825) (xy 125.969327 -262.793121)
			(xy 125.985037 -262.742191) (xy 126.008163 -262.69417) (xy 126.038187 -262.650133) (xy 126.074439 -262.611062)
			(xy 126.11611 -262.577831) (xy 126.162268 -262.551182) (xy 126.211882 -262.53171) (xy 126.263844 -262.51985)
			(xy 126.316994 -262.515867) (xy 126.370144 -262.51985) (xy 126.422106 -262.53171) (xy 126.47172 -262.551182)
			(xy 126.517878 -262.577831) (xy 126.559549 -262.611062) (xy 126.595801 -262.650133) (xy 126.625825 -262.69417)
			(xy 126.648951 -262.742191) (xy 126.664661 -262.793121) (xy 126.672604 -262.845825) (xy 126.673102 -262.872474)
			(xy 126.672604 -262.899123) (xy 126.901184 -262.899123) (xy 126.901184 -262.845825) (xy 126.909127 -262.793121)
			(xy 126.924837 -262.742191) (xy 126.947963 -262.69417) (xy 126.977987 -262.650133) (xy 127.014239 -262.611062)
			(xy 127.05591 -262.577831) (xy 127.102068 -262.551182) (xy 127.151682 -262.53171) (xy 127.203644 -262.51985)
			(xy 127.256794 -262.515867) (xy 127.309944 -262.51985) (xy 127.361906 -262.53171) (xy 127.41152 -262.551182)
			(xy 127.457678 -262.577831) (xy 127.499349 -262.611062) (xy 127.535601 -262.650133) (xy 127.565625 -262.69417)
			(xy 127.588751 -262.742191) (xy 127.604461 -262.793121) (xy 127.612404 -262.845825) (xy 127.612902 -262.872474)
			(xy 127.612404 -262.899123) (xy 127.840984 -262.899123) (xy 127.840984 -262.845825) (xy 127.848927 -262.793121)
			(xy 127.864637 -262.742191) (xy 127.887763 -262.69417) (xy 127.917787 -262.650133) (xy 127.954039 -262.611062)
			(xy 127.99571 -262.577831) (xy 128.041868 -262.551182) (xy 128.091482 -262.53171) (xy 128.143444 -262.51985)
			(xy 128.196594 -262.515867) (xy 128.249744 -262.51985) (xy 128.301706 -262.53171) (xy 128.35132 -262.551182)
			(xy 128.397478 -262.577831) (xy 128.439149 -262.611062) (xy 128.475401 -262.650133) (xy 128.505425 -262.69417)
			(xy 128.528551 -262.742191) (xy 128.544261 -262.793121) (xy 128.552204 -262.845825) (xy 128.552702 -262.872474)
			(xy 128.552204 -262.899123) (xy 128.780784 -262.899123) (xy 128.780784 -262.845825) (xy 128.788727 -262.793121)
			(xy 128.804437 -262.742191) (xy 128.827563 -262.69417) (xy 128.857587 -262.650133) (xy 128.893839 -262.611062)
			(xy 128.93551 -262.577831) (xy 128.981668 -262.551182) (xy 129.031282 -262.53171) (xy 129.083244 -262.51985)
			(xy 129.136394 -262.515867) (xy 129.189544 -262.51985) (xy 129.241506 -262.53171) (xy 129.29112 -262.551182)
			(xy 129.337278 -262.577831) (xy 129.378949 -262.611062) (xy 129.415201 -262.650133) (xy 129.445225 -262.69417)
			(xy 129.468351 -262.742191) (xy 129.484061 -262.793121) (xy 129.492004 -262.845825) (xy 129.492502 -262.872474)
			(xy 129.492004 -262.899123) (xy 129.720584 -262.899123) (xy 129.720584 -262.845825) (xy 129.728527 -262.793121)
			(xy 129.744237 -262.742191) (xy 129.767363 -262.69417) (xy 129.797387 -262.650133) (xy 129.833639 -262.611062)
			(xy 129.87531 -262.577831) (xy 129.921468 -262.551182) (xy 129.971082 -262.53171) (xy 130.023044 -262.51985)
			(xy 130.076194 -262.515867) (xy 130.129344 -262.51985) (xy 130.181306 -262.53171) (xy 130.23092 -262.551182)
			(xy 130.277078 -262.577831) (xy 130.318749 -262.611062) (xy 130.355001 -262.650133) (xy 130.385025 -262.69417)
			(xy 130.408151 -262.742191) (xy 130.423861 -262.793121) (xy 130.431804 -262.845825) (xy 130.432302 -262.872474)
			(xy 130.431804 -262.899123) (xy 130.660384 -262.899123) (xy 130.660384 -262.845825) (xy 130.668327 -262.793121)
			(xy 130.684037 -262.742191) (xy 130.707163 -262.69417) (xy 130.737187 -262.650133) (xy 130.773439 -262.611062)
			(xy 130.81511 -262.577831) (xy 130.861268 -262.551182) (xy 130.910882 -262.53171) (xy 130.962844 -262.51985)
			(xy 131.015994 -262.515867) (xy 131.069144 -262.51985) (xy 131.121106 -262.53171) (xy 131.17072 -262.551182)
			(xy 131.216878 -262.577831) (xy 131.258549 -262.611062) (xy 131.294801 -262.650133) (xy 131.324825 -262.69417)
			(xy 131.347951 -262.742191) (xy 131.363661 -262.793121) (xy 131.371604 -262.845825) (xy 131.372102 -262.872474)
			(xy 131.371604 -262.899123) (xy 131.600438 -262.899123) (xy 131.600438 -262.845825) (xy 131.608381 -262.793121)
			(xy 131.624091 -262.742191) (xy 131.647217 -262.69417) (xy 131.677241 -262.650133) (xy 131.713493 -262.611062)
			(xy 131.755164 -262.577831) (xy 131.801322 -262.551182) (xy 131.850936 -262.53171) (xy 131.902898 -262.51985)
			(xy 131.956048 -262.515867) (xy 132.009198 -262.51985) (xy 132.06116 -262.53171) (xy 132.110774 -262.551182)
			(xy 132.156932 -262.577831) (xy 132.198603 -262.611062) (xy 132.234855 -262.650133) (xy 132.264879 -262.69417)
			(xy 132.288005 -262.742191) (xy 132.303715 -262.793121) (xy 132.311658 -262.845825) (xy 132.312156 -262.872474)
			(xy 132.311658 -262.899123) (xy 132.539984 -262.899123) (xy 132.539984 -262.845825) (xy 132.547927 -262.793121)
			(xy 132.563637 -262.742191) (xy 132.586763 -262.69417) (xy 132.616787 -262.650133) (xy 132.653039 -262.611062)
			(xy 132.69471 -262.577831) (xy 132.740868 -262.551182) (xy 132.790482 -262.53171) (xy 132.842444 -262.51985)
			(xy 132.895594 -262.515867) (xy 132.948744 -262.51985) (xy 133.000706 -262.53171) (xy 133.05032 -262.551182)
			(xy 133.096478 -262.577831) (xy 133.138149 -262.611062) (xy 133.174401 -262.650133) (xy 133.204425 -262.69417)
			(xy 133.227551 -262.742191) (xy 133.243261 -262.793121) (xy 133.251204 -262.845825) (xy 133.251702 -262.872474)
			(xy 133.251204 -262.899123) (xy 133.479784 -262.899123) (xy 133.479784 -262.845825) (xy 133.487727 -262.793121)
			(xy 133.503437 -262.742191) (xy 133.526563 -262.69417) (xy 133.556587 -262.650133) (xy 133.592839 -262.611062)
			(xy 133.63451 -262.577831) (xy 133.680668 -262.551182) (xy 133.730282 -262.53171) (xy 133.782244 -262.51985)
			(xy 133.835394 -262.515867) (xy 133.888544 -262.51985) (xy 133.940506 -262.53171) (xy 133.99012 -262.551182)
			(xy 134.036278 -262.577831) (xy 134.077949 -262.611062) (xy 134.114201 -262.650133) (xy 134.144225 -262.69417)
			(xy 134.167351 -262.742191) (xy 134.183061 -262.793121) (xy 134.191004 -262.845825) (xy 134.191502 -262.872474)
			(xy 134.191004 -262.899123) (xy 134.183061 -262.951827) (xy 134.167351 -263.002757) (xy 134.144225 -263.050778)
			(xy 134.114201 -263.094815) (xy 134.077949 -263.133886) (xy 134.036278 -263.167117) (xy 133.99012 -263.193766)
			(xy 133.940506 -263.213238) (xy 133.888544 -263.225098) (xy 133.835394 -263.229082) (xy 133.782244 -263.225098)
			(xy 133.730282 -263.213238) (xy 133.680668 -263.193766) (xy 133.63451 -263.167117) (xy 133.592839 -263.133886)
			(xy 133.556587 -263.094815) (xy 133.526563 -263.050778) (xy 133.503437 -263.002757) (xy 133.487727 -262.951827)
			(xy 133.479784 -262.899123) (xy 133.251204 -262.899123) (xy 133.243261 -262.951827) (xy 133.227551 -263.002757)
			(xy 133.204425 -263.050778) (xy 133.174401 -263.094815) (xy 133.138149 -263.133886) (xy 133.096478 -263.167117)
			(xy 133.05032 -263.193766) (xy 133.000706 -263.213238) (xy 132.948744 -263.225098) (xy 132.895594 -263.229082)
			(xy 132.842444 -263.225098) (xy 132.790482 -263.213238) (xy 132.740868 -263.193766) (xy 132.69471 -263.167117)
			(xy 132.653039 -263.133886) (xy 132.616787 -263.094815) (xy 132.586763 -263.050778) (xy 132.563637 -263.002757)
			(xy 132.547927 -262.951827) (xy 132.539984 -262.899123) (xy 132.311658 -262.899123) (xy 132.303715 -262.951827)
			(xy 132.288005 -263.002757) (xy 132.264879 -263.050778) (xy 132.234855 -263.094815) (xy 132.198603 -263.133886)
			(xy 132.156932 -263.167117) (xy 132.110774 -263.193766) (xy 132.06116 -263.213238) (xy 132.009198 -263.225098)
			(xy 131.956048 -263.229082) (xy 131.902898 -263.225098) (xy 131.850936 -263.213238) (xy 131.801322 -263.193766)
			(xy 131.755164 -263.167117) (xy 131.713493 -263.133886) (xy 131.677241 -263.094815) (xy 131.647217 -263.050778)
			(xy 131.624091 -263.002757) (xy 131.608381 -262.951827) (xy 131.600438 -262.899123) (xy 131.371604 -262.899123)
			(xy 131.363661 -262.951827) (xy 131.347951 -263.002757) (xy 131.324825 -263.050778) (xy 131.294801 -263.094815)
			(xy 131.258549 -263.133886) (xy 131.216878 -263.167117) (xy 131.17072 -263.193766) (xy 131.121106 -263.213238)
			(xy 131.069144 -263.225098) (xy 131.015994 -263.229082) (xy 130.962844 -263.225098) (xy 130.910882 -263.213238)
			(xy 130.861268 -263.193766) (xy 130.81511 -263.167117) (xy 130.773439 -263.133886) (xy 130.737187 -263.094815)
			(xy 130.707163 -263.050778) (xy 130.684037 -263.002757) (xy 130.668327 -262.951827) (xy 130.660384 -262.899123)
			(xy 130.431804 -262.899123) (xy 130.423861 -262.951827) (xy 130.408151 -263.002757) (xy 130.385025 -263.050778)
			(xy 130.355001 -263.094815) (xy 130.318749 -263.133886) (xy 130.277078 -263.167117) (xy 130.23092 -263.193766)
			(xy 130.181306 -263.213238) (xy 130.129344 -263.225098) (xy 130.076194 -263.229082) (xy 130.023044 -263.225098)
			(xy 129.971082 -263.213238) (xy 129.921468 -263.193766) (xy 129.87531 -263.167117) (xy 129.833639 -263.133886)
			(xy 129.797387 -263.094815) (xy 129.767363 -263.050778) (xy 129.744237 -263.002757) (xy 129.728527 -262.951827)
			(xy 129.720584 -262.899123) (xy 129.492004 -262.899123) (xy 129.484061 -262.951827) (xy 129.468351 -263.002757)
			(xy 129.445225 -263.050778) (xy 129.415201 -263.094815) (xy 129.378949 -263.133886) (xy 129.337278 -263.167117)
			(xy 129.29112 -263.193766) (xy 129.241506 -263.213238) (xy 129.189544 -263.225098) (xy 129.136394 -263.229082)
			(xy 129.083244 -263.225098) (xy 129.031282 -263.213238) (xy 128.981668 -263.193766) (xy 128.93551 -263.167117)
			(xy 128.893839 -263.133886) (xy 128.857587 -263.094815) (xy 128.827563 -263.050778) (xy 128.804437 -263.002757)
			(xy 128.788727 -262.951827) (xy 128.780784 -262.899123) (xy 128.552204 -262.899123) (xy 128.544261 -262.951827)
			(xy 128.528551 -263.002757) (xy 128.505425 -263.050778) (xy 128.475401 -263.094815) (xy 128.439149 -263.133886)
			(xy 128.397478 -263.167117) (xy 128.35132 -263.193766) (xy 128.301706 -263.213238) (xy 128.249744 -263.225098)
			(xy 128.196594 -263.229082) (xy 128.143444 -263.225098) (xy 128.091482 -263.213238) (xy 128.041868 -263.193766)
			(xy 127.99571 -263.167117) (xy 127.954039 -263.133886) (xy 127.917787 -263.094815) (xy 127.887763 -263.050778)
			(xy 127.864637 -263.002757) (xy 127.848927 -262.951827) (xy 127.840984 -262.899123) (xy 127.612404 -262.899123)
			(xy 127.604461 -262.951827) (xy 127.588751 -263.002757) (xy 127.565625 -263.050778) (xy 127.535601 -263.094815)
			(xy 127.499349 -263.133886) (xy 127.457678 -263.167117) (xy 127.41152 -263.193766) (xy 127.361906 -263.213238)
			(xy 127.309944 -263.225098) (xy 127.256794 -263.229082) (xy 127.203644 -263.225098) (xy 127.151682 -263.213238)
			(xy 127.102068 -263.193766) (xy 127.05591 -263.167117) (xy 127.014239 -263.133886) (xy 126.977987 -263.094815)
			(xy 126.947963 -263.050778) (xy 126.924837 -263.002757) (xy 126.909127 -262.951827) (xy 126.901184 -262.899123)
			(xy 126.672604 -262.899123) (xy 126.664661 -262.951827) (xy 126.648951 -263.002757) (xy 126.625825 -263.050778)
			(xy 126.595801 -263.094815) (xy 126.559549 -263.133886) (xy 126.517878 -263.167117) (xy 126.47172 -263.193766)
			(xy 126.422106 -263.213238) (xy 126.370144 -263.225098) (xy 126.316994 -263.229082) (xy 126.263844 -263.225098)
			(xy 126.211882 -263.213238) (xy 126.162268 -263.193766) (xy 126.11611 -263.167117) (xy 126.074439 -263.133886)
			(xy 126.038187 -263.094815) (xy 126.008163 -263.050778) (xy 125.985037 -263.002757) (xy 125.969327 -262.951827)
			(xy 125.961384 -262.899123) (xy 125.733058 -262.899123) (xy 125.725115 -262.951827) (xy 125.709405 -263.002757)
			(xy 125.686279 -263.050778) (xy 125.656255 -263.094815) (xy 125.620003 -263.133886) (xy 125.578332 -263.167117)
			(xy 125.532174 -263.193766) (xy 125.48256 -263.213238) (xy 125.430598 -263.225098) (xy 125.377448 -263.229082)
			(xy 125.324298 -263.225098) (xy 125.272336 -263.213238) (xy 125.222722 -263.193766) (xy 125.176564 -263.167117)
			(xy 125.134893 -263.133886) (xy 125.098641 -263.094815) (xy 125.068617 -263.050778) (xy 125.045491 -263.002757)
			(xy 125.029781 -262.951827) (xy 125.021838 -262.899123) (xy 124.793004 -262.899123) (xy 124.785061 -262.951827)
			(xy 124.769351 -263.002757) (xy 124.746225 -263.050778) (xy 124.716201 -263.094815) (xy 124.679949 -263.133886)
			(xy 124.638278 -263.167117) (xy 124.59212 -263.193766) (xy 124.542506 -263.213238) (xy 124.490544 -263.225098)
			(xy 124.437394 -263.229082) (xy 124.384244 -263.225098) (xy 124.332282 -263.213238) (xy 124.282668 -263.193766)
			(xy 124.23651 -263.167117) (xy 124.194839 -263.133886) (xy 124.158587 -263.094815) (xy 124.128563 -263.050778)
			(xy 124.105437 -263.002757) (xy 124.089727 -262.951827) (xy 124.081784 -262.899123) (xy 123.853204 -262.899123)
			(xy 123.845261 -262.951827) (xy 123.829551 -263.002757) (xy 123.806425 -263.050778) (xy 123.776401 -263.094815)
			(xy 123.740149 -263.133886) (xy 123.698478 -263.167117) (xy 123.65232 -263.193766) (xy 123.602706 -263.213238)
			(xy 123.550744 -263.225098) (xy 123.497594 -263.229082) (xy 123.444444 -263.225098) (xy 123.392482 -263.213238)
			(xy 123.342868 -263.193766) (xy 123.29671 -263.167117) (xy 123.255039 -263.133886) (xy 123.218787 -263.094815)
			(xy 123.188763 -263.050778) (xy 123.165637 -263.002757) (xy 123.149927 -262.951827) (xy 123.141984 -262.899123)
			(xy 122.913658 -262.899123) (xy 122.905715 -262.951827) (xy 122.890005 -263.002757) (xy 122.866879 -263.050778)
			(xy 122.836855 -263.094815) (xy 122.800603 -263.133886) (xy 122.758932 -263.167117) (xy 122.712774 -263.193766)
			(xy 122.66316 -263.213238) (xy 122.611198 -263.225098) (xy 122.558048 -263.229082) (xy 122.504898 -263.225098)
			(xy 122.452936 -263.213238) (xy 122.403322 -263.193766) (xy 122.357164 -263.167117) (xy 122.315493 -263.133886)
			(xy 122.279241 -263.094815) (xy 122.249217 -263.050778) (xy 122.226091 -263.002757) (xy 122.210381 -262.951827)
			(xy 122.202438 -262.899123) (xy 121.973604 -262.899123) (xy 121.965661 -262.951827) (xy 121.949951 -263.002757)
			(xy 121.926825 -263.050778) (xy 121.896801 -263.094815) (xy 121.860549 -263.133886) (xy 121.818878 -263.167117)
			(xy 121.77272 -263.193766) (xy 121.723106 -263.213238) (xy 121.671144 -263.225098) (xy 121.617994 -263.229082)
			(xy 121.564844 -263.225098) (xy 121.512882 -263.213238) (xy 121.463268 -263.193766) (xy 121.41711 -263.167117)
			(xy 121.375439 -263.133886) (xy 121.339187 -263.094815) (xy 121.309163 -263.050778) (xy 121.286037 -263.002757)
			(xy 121.270327 -262.951827) (xy 121.262384 -262.899123) (xy 120.54497 -262.899123) (xy 120.565449 -262.924802)
			(xy 120.592101 -262.970963) (xy 120.611575 -263.02058) (xy 120.623437 -263.072546) (xy 120.62742 -263.1257)
			(xy 120.623437 -263.178854) (xy 120.611575 -263.23082) (xy 120.592101 -263.280437) (xy 120.565449 -263.326598)
			(xy 120.532214 -263.368271) (xy 120.493139 -263.404525) (xy 120.449097 -263.434549) (xy 120.401072 -263.457674)
			(xy 120.350137 -263.473383) (xy 120.297429 -263.481324) (xy 120.270778 -263.48182) (xy 120.270524 -263.48182)
			(xy 120.244964 -263.481378) (xy 120.194371 -263.47406) (xy 120.145347 -263.459571) (xy 120.121934 -263.449308)
			(xy 120.108908 -263.443824) (xy 120.080988 -263.439509) (xy 120.052953 -263.443009) (xy 120.026952 -263.454058)
			(xy 120.004973 -263.47181) (xy 119.996458 -263.48309) (xy 119.979634 -263.505948) (xy 119.939949 -263.54652)
			(xy 119.894332 -263.580285) (xy 119.843936 -263.606387) (xy 119.790039 -263.624165) (xy 119.734005 -263.633171)
			(xy 119.705628 -263.633712) (xy 119.679693 -263.633225) (xy 119.628377 -263.625665) (xy 119.578699 -263.610744)
			(xy 119.555006 -263.600184) (xy 119.541585 -263.594454) (xy 119.512739 -263.59011) (xy 119.48384 -263.594093)
			(xy 119.457245 -263.606078) (xy 119.435119 -263.62509) (xy 119.419266 -263.649578) (xy 119.410978 -263.677547)
			(xy 119.41048 -263.692132) (xy 119.41048 -263.713193) (xy 121.732538 -263.713193) (xy 121.732538 -263.659895)
			(xy 121.740481 -263.607191) (xy 121.756191 -263.556261) (xy 121.779317 -263.50824) (xy 121.809341 -263.464203)
			(xy 121.845593 -263.425132) (xy 121.887264 -263.391901) (xy 121.933422 -263.365252) (xy 121.983036 -263.34578)
			(xy 122.034998 -263.33392) (xy 122.088148 -263.329937) (xy 122.141298 -263.33392) (xy 122.19326 -263.34578)
			(xy 122.242874 -263.365252) (xy 122.289032 -263.391901) (xy 122.330703 -263.425132) (xy 122.366955 -263.464203)
			(xy 122.396979 -263.50824) (xy 122.420105 -263.556261) (xy 122.435815 -263.607191) (xy 122.443758 -263.659895)
			(xy 122.444256 -263.686544) (xy 122.443758 -263.713193) (xy 122.672084 -263.713193) (xy 122.672084 -263.659895)
			(xy 122.680027 -263.607191) (xy 122.695737 -263.556261) (xy 122.718863 -263.50824) (xy 122.748887 -263.464203)
			(xy 122.785139 -263.425132) (xy 122.82681 -263.391901) (xy 122.872968 -263.365252) (xy 122.922582 -263.34578)
			(xy 122.974544 -263.33392) (xy 123.027694 -263.329937) (xy 123.080844 -263.33392) (xy 123.132806 -263.34578)
			(xy 123.18242 -263.365252) (xy 123.228578 -263.391901) (xy 123.270249 -263.425132) (xy 123.306501 -263.464203)
			(xy 123.336525 -263.50824) (xy 123.359651 -263.556261) (xy 123.375361 -263.607191) (xy 123.383304 -263.659895)
			(xy 123.383802 -263.686544) (xy 123.383304 -263.713193) (xy 123.612138 -263.713193) (xy 123.612138 -263.659895)
			(xy 123.620081 -263.607191) (xy 123.635791 -263.556261) (xy 123.658917 -263.50824) (xy 123.688941 -263.464203)
			(xy 123.725193 -263.425132) (xy 123.766864 -263.391901) (xy 123.813022 -263.365252) (xy 123.862636 -263.34578)
			(xy 123.914598 -263.33392) (xy 123.967748 -263.329937) (xy 124.020898 -263.33392) (xy 124.07286 -263.34578)
			(xy 124.122474 -263.365252) (xy 124.168632 -263.391901) (xy 124.210303 -263.425132) (xy 124.246555 -263.464203)
			(xy 124.276579 -263.50824) (xy 124.299705 -263.556261) (xy 124.315415 -263.607191) (xy 124.323358 -263.659895)
			(xy 124.323856 -263.686544) (xy 124.323358 -263.713193) (xy 124.551938 -263.713193) (xy 124.551938 -263.659895)
			(xy 124.559881 -263.607191) (xy 124.575591 -263.556261) (xy 124.598717 -263.50824) (xy 124.628741 -263.464203)
			(xy 124.664993 -263.425132) (xy 124.706664 -263.391901) (xy 124.752822 -263.365252) (xy 124.802436 -263.34578)
			(xy 124.854398 -263.33392) (xy 124.907548 -263.329937) (xy 124.960698 -263.33392) (xy 125.01266 -263.34578)
			(xy 125.062274 -263.365252) (xy 125.108432 -263.391901) (xy 125.150103 -263.425132) (xy 125.186355 -263.464203)
			(xy 125.216379 -263.50824) (xy 125.239505 -263.556261) (xy 125.255215 -263.607191) (xy 125.263158 -263.659895)
			(xy 125.263656 -263.686544) (xy 125.263158 -263.713193) (xy 125.491738 -263.713193) (xy 125.491738 -263.659895)
			(xy 125.499681 -263.607191) (xy 125.515391 -263.556261) (xy 125.538517 -263.50824) (xy 125.568541 -263.464203)
			(xy 125.604793 -263.425132) (xy 125.646464 -263.391901) (xy 125.692622 -263.365252) (xy 125.742236 -263.34578)
			(xy 125.794198 -263.33392) (xy 125.847348 -263.329937) (xy 125.900498 -263.33392) (xy 125.95246 -263.34578)
			(xy 126.002074 -263.365252) (xy 126.048232 -263.391901) (xy 126.089903 -263.425132) (xy 126.126155 -263.464203)
			(xy 126.156179 -263.50824) (xy 126.179305 -263.556261) (xy 126.195015 -263.607191) (xy 126.202958 -263.659895)
			(xy 126.203456 -263.686544) (xy 126.202958 -263.713193) (xy 126.431538 -263.713193) (xy 126.431538 -263.659895)
			(xy 126.439481 -263.607191) (xy 126.455191 -263.556261) (xy 126.478317 -263.50824) (xy 126.508341 -263.464203)
			(xy 126.544593 -263.425132) (xy 126.586264 -263.391901) (xy 126.632422 -263.365252) (xy 126.682036 -263.34578)
			(xy 126.733998 -263.33392) (xy 126.787148 -263.329937) (xy 126.840298 -263.33392) (xy 126.89226 -263.34578)
			(xy 126.941874 -263.365252) (xy 126.988032 -263.391901) (xy 127.029703 -263.425132) (xy 127.065955 -263.464203)
			(xy 127.095979 -263.50824) (xy 127.119105 -263.556261) (xy 127.134815 -263.607191) (xy 127.142758 -263.659895)
			(xy 127.143256 -263.686544) (xy 127.142758 -263.713193) (xy 127.371338 -263.713193) (xy 127.371338 -263.659895)
			(xy 127.379281 -263.607191) (xy 127.394991 -263.556261) (xy 127.418117 -263.50824) (xy 127.448141 -263.464203)
			(xy 127.484393 -263.425132) (xy 127.526064 -263.391901) (xy 127.572222 -263.365252) (xy 127.621836 -263.34578)
			(xy 127.673798 -263.33392) (xy 127.726948 -263.329937) (xy 127.780098 -263.33392) (xy 127.83206 -263.34578)
			(xy 127.881674 -263.365252) (xy 127.927832 -263.391901) (xy 127.969503 -263.425132) (xy 128.005755 -263.464203)
			(xy 128.035779 -263.50824) (xy 128.058905 -263.556261) (xy 128.074615 -263.607191) (xy 128.082558 -263.659895)
			(xy 128.083056 -263.686544) (xy 128.082558 -263.713193) (xy 128.311138 -263.713193) (xy 128.311138 -263.659895)
			(xy 128.319081 -263.607191) (xy 128.334791 -263.556261) (xy 128.357917 -263.50824) (xy 128.387941 -263.464203)
			(xy 128.424193 -263.425132) (xy 128.465864 -263.391901) (xy 128.512022 -263.365252) (xy 128.561636 -263.34578)
			(xy 128.613598 -263.33392) (xy 128.666748 -263.329937) (xy 128.719898 -263.33392) (xy 128.77186 -263.34578)
			(xy 128.821474 -263.365252) (xy 128.867632 -263.391901) (xy 128.909303 -263.425132) (xy 128.945555 -263.464203)
			(xy 128.975579 -263.50824) (xy 128.998705 -263.556261) (xy 129.014415 -263.607191) (xy 129.022358 -263.659895)
			(xy 129.022856 -263.686544) (xy 129.022358 -263.713193) (xy 129.250684 -263.713193) (xy 129.250684 -263.659895)
			(xy 129.258627 -263.607191) (xy 129.274337 -263.556261) (xy 129.297463 -263.50824) (xy 129.327487 -263.464203)
			(xy 129.363739 -263.425132) (xy 129.40541 -263.391901) (xy 129.451568 -263.365252) (xy 129.501182 -263.34578)
			(xy 129.553144 -263.33392) (xy 129.606294 -263.329937) (xy 129.659444 -263.33392) (xy 129.711406 -263.34578)
			(xy 129.76102 -263.365252) (xy 129.807178 -263.391901) (xy 129.848849 -263.425132) (xy 129.885101 -263.464203)
			(xy 129.915125 -263.50824) (xy 129.938251 -263.556261) (xy 129.953961 -263.607191) (xy 129.961904 -263.659895)
			(xy 129.962402 -263.686544) (xy 129.961904 -263.713193) (xy 130.190738 -263.713193) (xy 130.190738 -263.659895)
			(xy 130.198681 -263.607191) (xy 130.214391 -263.556261) (xy 130.237517 -263.50824) (xy 130.267541 -263.464203)
			(xy 130.303793 -263.425132) (xy 130.345464 -263.391901) (xy 130.391622 -263.365252) (xy 130.441236 -263.34578)
			(xy 130.493198 -263.33392) (xy 130.546348 -263.329937) (xy 130.599498 -263.33392) (xy 130.65146 -263.34578)
			(xy 130.701074 -263.365252) (xy 130.747232 -263.391901) (xy 130.788903 -263.425132) (xy 130.825155 -263.464203)
			(xy 130.855179 -263.50824) (xy 130.878305 -263.556261) (xy 130.894015 -263.607191) (xy 130.901958 -263.659895)
			(xy 130.902456 -263.686544) (xy 130.901958 -263.713193) (xy 131.130538 -263.713193) (xy 131.130538 -263.659895)
			(xy 131.138481 -263.607191) (xy 131.154191 -263.556261) (xy 131.177317 -263.50824) (xy 131.207341 -263.464203)
			(xy 131.243593 -263.425132) (xy 131.285264 -263.391901) (xy 131.331422 -263.365252) (xy 131.381036 -263.34578)
			(xy 131.432998 -263.33392) (xy 131.486148 -263.329937) (xy 131.539298 -263.33392) (xy 131.59126 -263.34578)
			(xy 131.640874 -263.365252) (xy 131.687032 -263.391901) (xy 131.728703 -263.425132) (xy 131.764955 -263.464203)
			(xy 131.794979 -263.50824) (xy 131.818105 -263.556261) (xy 131.833815 -263.607191) (xy 131.841758 -263.659895)
			(xy 131.842256 -263.686544) (xy 131.841758 -263.713193) (xy 132.070338 -263.713193) (xy 132.070338 -263.659895)
			(xy 132.078281 -263.607191) (xy 132.093991 -263.556261) (xy 132.117117 -263.50824) (xy 132.147141 -263.464203)
			(xy 132.183393 -263.425132) (xy 132.225064 -263.391901) (xy 132.271222 -263.365252) (xy 132.320836 -263.34578)
			(xy 132.372798 -263.33392) (xy 132.425948 -263.329937) (xy 132.479098 -263.33392) (xy 132.53106 -263.34578)
			(xy 132.580674 -263.365252) (xy 132.626832 -263.391901) (xy 132.668503 -263.425132) (xy 132.704755 -263.464203)
			(xy 132.734779 -263.50824) (xy 132.757905 -263.556261) (xy 132.773615 -263.607191) (xy 132.781558 -263.659895)
			(xy 132.782056 -263.686544) (xy 132.781558 -263.713193) (xy 133.010138 -263.713193) (xy 133.010138 -263.659895)
			(xy 133.018081 -263.607191) (xy 133.033791 -263.556261) (xy 133.056917 -263.50824) (xy 133.086941 -263.464203)
			(xy 133.123193 -263.425132) (xy 133.164864 -263.391901) (xy 133.211022 -263.365252) (xy 133.260636 -263.34578)
			(xy 133.312598 -263.33392) (xy 133.365748 -263.329937) (xy 133.418898 -263.33392) (xy 133.47086 -263.34578)
			(xy 133.520474 -263.365252) (xy 133.566632 -263.391901) (xy 133.608303 -263.425132) (xy 133.644555 -263.464203)
			(xy 133.674579 -263.50824) (xy 133.697705 -263.556261) (xy 133.713415 -263.607191) (xy 133.721358 -263.659895)
			(xy 133.721856 -263.686544) (xy 133.721358 -263.713193) (xy 133.949938 -263.713193) (xy 133.949938 -263.659895)
			(xy 133.957881 -263.607191) (xy 133.973591 -263.556261) (xy 133.996717 -263.50824) (xy 134.026741 -263.464203)
			(xy 134.062993 -263.425132) (xy 134.104664 -263.391901) (xy 134.150822 -263.365252) (xy 134.200436 -263.34578)
			(xy 134.252398 -263.33392) (xy 134.305548 -263.329937) (xy 134.358698 -263.33392) (xy 134.41066 -263.34578)
			(xy 134.460274 -263.365252) (xy 134.506432 -263.391901) (xy 134.548103 -263.425132) (xy 134.584355 -263.464203)
			(xy 134.614379 -263.50824) (xy 134.637505 -263.556261) (xy 134.653215 -263.607191) (xy 134.661158 -263.659895)
			(xy 134.661656 -263.686544) (xy 134.661158 -263.713193) (xy 134.653215 -263.765897) (xy 134.637505 -263.816827)
			(xy 134.614379 -263.864848) (xy 134.584355 -263.908885) (xy 134.548103 -263.947956) (xy 134.506432 -263.981187)
			(xy 134.460274 -264.007836) (xy 134.41066 -264.027308) (xy 134.358698 -264.039168) (xy 134.305548 -264.043152)
			(xy 134.252398 -264.039168) (xy 134.200436 -264.027308) (xy 134.150822 -264.007836) (xy 134.104664 -263.981187)
			(xy 134.062993 -263.947956) (xy 134.026741 -263.908885) (xy 133.996717 -263.864848) (xy 133.973591 -263.816827)
			(xy 133.957881 -263.765897) (xy 133.949938 -263.713193) (xy 133.721358 -263.713193) (xy 133.713415 -263.765897)
			(xy 133.697705 -263.816827) (xy 133.674579 -263.864848) (xy 133.644555 -263.908885) (xy 133.608303 -263.947956)
			(xy 133.566632 -263.981187) (xy 133.520474 -264.007836) (xy 133.47086 -264.027308) (xy 133.418898 -264.039168)
			(xy 133.365748 -264.043152) (xy 133.312598 -264.039168) (xy 133.260636 -264.027308) (xy 133.211022 -264.007836)
			(xy 133.164864 -263.981187) (xy 133.123193 -263.947956) (xy 133.086941 -263.908885) (xy 133.056917 -263.864848)
			(xy 133.033791 -263.816827) (xy 133.018081 -263.765897) (xy 133.010138 -263.713193) (xy 132.781558 -263.713193)
			(xy 132.773615 -263.765897) (xy 132.757905 -263.816827) (xy 132.734779 -263.864848) (xy 132.704755 -263.908885)
			(xy 132.668503 -263.947956) (xy 132.626832 -263.981187) (xy 132.580674 -264.007836) (xy 132.53106 -264.027308)
			(xy 132.479098 -264.039168) (xy 132.425948 -264.043152) (xy 132.372798 -264.039168) (xy 132.320836 -264.027308)
			(xy 132.271222 -264.007836) (xy 132.225064 -263.981187) (xy 132.183393 -263.947956) (xy 132.147141 -263.908885)
			(xy 132.117117 -263.864848) (xy 132.093991 -263.816827) (xy 132.078281 -263.765897) (xy 132.070338 -263.713193)
			(xy 131.841758 -263.713193) (xy 131.833815 -263.765897) (xy 131.818105 -263.816827) (xy 131.794979 -263.864848)
			(xy 131.764955 -263.908885) (xy 131.728703 -263.947956) (xy 131.687032 -263.981187) (xy 131.640874 -264.007836)
			(xy 131.59126 -264.027308) (xy 131.539298 -264.039168) (xy 131.486148 -264.043152) (xy 131.432998 -264.039168)
			(xy 131.381036 -264.027308) (xy 131.331422 -264.007836) (xy 131.285264 -263.981187) (xy 131.243593 -263.947956)
			(xy 131.207341 -263.908885) (xy 131.177317 -263.864848) (xy 131.154191 -263.816827) (xy 131.138481 -263.765897)
			(xy 131.130538 -263.713193) (xy 130.901958 -263.713193) (xy 130.894015 -263.765897) (xy 130.878305 -263.816827)
			(xy 130.855179 -263.864848) (xy 130.825155 -263.908885) (xy 130.788903 -263.947956) (xy 130.747232 -263.981187)
			(xy 130.701074 -264.007836) (xy 130.65146 -264.027308) (xy 130.599498 -264.039168) (xy 130.546348 -264.043152)
			(xy 130.493198 -264.039168) (xy 130.441236 -264.027308) (xy 130.391622 -264.007836) (xy 130.345464 -263.981187)
			(xy 130.303793 -263.947956) (xy 130.267541 -263.908885) (xy 130.237517 -263.864848) (xy 130.214391 -263.816827)
			(xy 130.198681 -263.765897) (xy 130.190738 -263.713193) (xy 129.961904 -263.713193) (xy 129.953961 -263.765897)
			(xy 129.938251 -263.816827) (xy 129.915125 -263.864848) (xy 129.885101 -263.908885) (xy 129.848849 -263.947956)
			(xy 129.807178 -263.981187) (xy 129.76102 -264.007836) (xy 129.711406 -264.027308) (xy 129.659444 -264.039168)
			(xy 129.606294 -264.043152) (xy 129.553144 -264.039168) (xy 129.501182 -264.027308) (xy 129.451568 -264.007836)
			(xy 129.40541 -263.981187) (xy 129.363739 -263.947956) (xy 129.327487 -263.908885) (xy 129.297463 -263.864848)
			(xy 129.274337 -263.816827) (xy 129.258627 -263.765897) (xy 129.250684 -263.713193) (xy 129.022358 -263.713193)
			(xy 129.014415 -263.765897) (xy 128.998705 -263.816827) (xy 128.975579 -263.864848) (xy 128.945555 -263.908885)
			(xy 128.909303 -263.947956) (xy 128.867632 -263.981187) (xy 128.821474 -264.007836) (xy 128.77186 -264.027308)
			(xy 128.719898 -264.039168) (xy 128.666748 -264.043152) (xy 128.613598 -264.039168) (xy 128.561636 -264.027308)
			(xy 128.512022 -264.007836) (xy 128.465864 -263.981187) (xy 128.424193 -263.947956) (xy 128.387941 -263.908885)
			(xy 128.357917 -263.864848) (xy 128.334791 -263.816827) (xy 128.319081 -263.765897) (xy 128.311138 -263.713193)
			(xy 128.082558 -263.713193) (xy 128.074615 -263.765897) (xy 128.058905 -263.816827) (xy 128.035779 -263.864848)
			(xy 128.005755 -263.908885) (xy 127.969503 -263.947956) (xy 127.927832 -263.981187) (xy 127.881674 -264.007836)
			(xy 127.83206 -264.027308) (xy 127.780098 -264.039168) (xy 127.726948 -264.043152) (xy 127.673798 -264.039168)
			(xy 127.621836 -264.027308) (xy 127.572222 -264.007836) (xy 127.526064 -263.981187) (xy 127.484393 -263.947956)
			(xy 127.448141 -263.908885) (xy 127.418117 -263.864848) (xy 127.394991 -263.816827) (xy 127.379281 -263.765897)
			(xy 127.371338 -263.713193) (xy 127.142758 -263.713193) (xy 127.134815 -263.765897) (xy 127.119105 -263.816827)
			(xy 127.095979 -263.864848) (xy 127.065955 -263.908885) (xy 127.029703 -263.947956) (xy 126.988032 -263.981187)
			(xy 126.941874 -264.007836) (xy 126.89226 -264.027308) (xy 126.840298 -264.039168) (xy 126.787148 -264.043152)
			(xy 126.733998 -264.039168) (xy 126.682036 -264.027308) (xy 126.632422 -264.007836) (xy 126.586264 -263.981187)
			(xy 126.544593 -263.947956) (xy 126.508341 -263.908885) (xy 126.478317 -263.864848) (xy 126.455191 -263.816827)
			(xy 126.439481 -263.765897) (xy 126.431538 -263.713193) (xy 126.202958 -263.713193) (xy 126.195015 -263.765897)
			(xy 126.179305 -263.816827) (xy 126.156179 -263.864848) (xy 126.126155 -263.908885) (xy 126.089903 -263.947956)
			(xy 126.048232 -263.981187) (xy 126.002074 -264.007836) (xy 125.95246 -264.027308) (xy 125.900498 -264.039168)
			(xy 125.847348 -264.043152) (xy 125.794198 -264.039168) (xy 125.742236 -264.027308) (xy 125.692622 -264.007836)
			(xy 125.646464 -263.981187) (xy 125.604793 -263.947956) (xy 125.568541 -263.908885) (xy 125.538517 -263.864848)
			(xy 125.515391 -263.816827) (xy 125.499681 -263.765897) (xy 125.491738 -263.713193) (xy 125.263158 -263.713193)
			(xy 125.255215 -263.765897) (xy 125.239505 -263.816827) (xy 125.216379 -263.864848) (xy 125.186355 -263.908885)
			(xy 125.150103 -263.947956) (xy 125.108432 -263.981187) (xy 125.062274 -264.007836) (xy 125.01266 -264.027308)
			(xy 124.960698 -264.039168) (xy 124.907548 -264.043152) (xy 124.854398 -264.039168) (xy 124.802436 -264.027308)
			(xy 124.752822 -264.007836) (xy 124.706664 -263.981187) (xy 124.664993 -263.947956) (xy 124.628741 -263.908885)
			(xy 124.598717 -263.864848) (xy 124.575591 -263.816827) (xy 124.559881 -263.765897) (xy 124.551938 -263.713193)
			(xy 124.323358 -263.713193) (xy 124.315415 -263.765897) (xy 124.299705 -263.816827) (xy 124.276579 -263.864848)
			(xy 124.246555 -263.908885) (xy 124.210303 -263.947956) (xy 124.168632 -263.981187) (xy 124.122474 -264.007836)
			(xy 124.07286 -264.027308) (xy 124.020898 -264.039168) (xy 123.967748 -264.043152) (xy 123.914598 -264.039168)
			(xy 123.862636 -264.027308) (xy 123.813022 -264.007836) (xy 123.766864 -263.981187) (xy 123.725193 -263.947956)
			(xy 123.688941 -263.908885) (xy 123.658917 -263.864848) (xy 123.635791 -263.816827) (xy 123.620081 -263.765897)
			(xy 123.612138 -263.713193) (xy 123.383304 -263.713193) (xy 123.375361 -263.765897) (xy 123.359651 -263.816827)
			(xy 123.336525 -263.864848) (xy 123.306501 -263.908885) (xy 123.270249 -263.947956) (xy 123.228578 -263.981187)
			(xy 123.18242 -264.007836) (xy 123.132806 -264.027308) (xy 123.080844 -264.039168) (xy 123.027694 -264.043152)
			(xy 122.974544 -264.039168) (xy 122.922582 -264.027308) (xy 122.872968 -264.007836) (xy 122.82681 -263.981187)
			(xy 122.785139 -263.947956) (xy 122.748887 -263.908885) (xy 122.718863 -263.864848) (xy 122.695737 -263.816827)
			(xy 122.680027 -263.765897) (xy 122.672084 -263.713193) (xy 122.443758 -263.713193) (xy 122.435815 -263.765897)
			(xy 122.420105 -263.816827) (xy 122.396979 -263.864848) (xy 122.366955 -263.908885) (xy 122.330703 -263.947956)
			(xy 122.289032 -263.981187) (xy 122.242874 -264.007836) (xy 122.19326 -264.027308) (xy 122.141298 -264.039168)
			(xy 122.088148 -264.043152) (xy 122.034998 -264.039168) (xy 121.983036 -264.027308) (xy 121.933422 -264.007836)
			(xy 121.887264 -263.981187) (xy 121.845593 -263.947956) (xy 121.809341 -263.908885) (xy 121.779317 -263.864848)
			(xy 121.756191 -263.816827) (xy 121.740481 -263.765897) (xy 121.732538 -263.713193) (xy 119.41048 -263.713193)
			(xy 119.41048 -264.102596) (xy 119.411028 -264.117792) (xy 119.419945 -264.146846) (xy 119.437018 -264.171988)
			(xy 119.460737 -264.19099) (xy 119.488997 -264.202168) (xy 119.519297 -264.204532) (xy 119.548949 -264.197873)
			(xy 119.562372 -264.190734) (xy 119.589342 -264.176131) (xy 119.647059 -264.155401) (xy 119.707477 -264.144884)
			(xy 119.73814 -264.144252) (xy 119.738394 -264.144252) (xy 119.765048 -264.144725) (xy 119.817762 -264.152669)
			(xy 119.868703 -264.168382) (xy 119.916733 -264.191511) (xy 119.960779 -264.22154) (xy 119.999857 -264.257799)
			(xy 120.033095 -264.299478) (xy 120.05975 -264.345644) (xy 120.079226 -264.395268) (xy 120.091088 -264.44724)
			(xy 120.095072 -264.5004) (xy 120.093078 -264.527009) (xy 120.322584 -264.527009) (xy 120.322584 -264.473711)
			(xy 120.330527 -264.421007) (xy 120.346237 -264.370077) (xy 120.369363 -264.322056) (xy 120.399387 -264.278019)
			(xy 120.435639 -264.238948) (xy 120.47731 -264.205717) (xy 120.523468 -264.179068) (xy 120.573082 -264.159596)
			(xy 120.625044 -264.147736) (xy 120.678194 -264.143753) (xy 120.731344 -264.147736) (xy 120.783306 -264.159596)
			(xy 120.83292 -264.179068) (xy 120.879078 -264.205717) (xy 120.920749 -264.238948) (xy 120.957001 -264.278019)
			(xy 120.987025 -264.322056) (xy 121.010151 -264.370077) (xy 121.025861 -264.421007) (xy 121.033804 -264.473711)
			(xy 121.034302 -264.50036) (xy 121.033804 -264.527009) (xy 121.262384 -264.527009) (xy 121.262384 -264.473711)
			(xy 121.270327 -264.421007) (xy 121.286037 -264.370077) (xy 121.309163 -264.322056) (xy 121.339187 -264.278019)
			(xy 121.375439 -264.238948) (xy 121.41711 -264.205717) (xy 121.463268 -264.179068) (xy 121.512882 -264.159596)
			(xy 121.564844 -264.147736) (xy 121.617994 -264.143753) (xy 121.671144 -264.147736) (xy 121.723106 -264.159596)
			(xy 121.77272 -264.179068) (xy 121.818878 -264.205717) (xy 121.860549 -264.238948) (xy 121.896801 -264.278019)
			(xy 121.926825 -264.322056) (xy 121.949951 -264.370077) (xy 121.965661 -264.421007) (xy 121.973604 -264.473711)
			(xy 121.974102 -264.50036) (xy 121.973604 -264.527009) (xy 122.202184 -264.527009) (xy 122.202184 -264.473711)
			(xy 122.210127 -264.421007) (xy 122.225837 -264.370077) (xy 122.248963 -264.322056) (xy 122.278987 -264.278019)
			(xy 122.315239 -264.238948) (xy 122.35691 -264.205717) (xy 122.403068 -264.179068) (xy 122.452682 -264.159596)
			(xy 122.504644 -264.147736) (xy 122.557794 -264.143753) (xy 122.610944 -264.147736) (xy 122.662906 -264.159596)
			(xy 122.71252 -264.179068) (xy 122.758678 -264.205717) (xy 122.800349 -264.238948) (xy 122.836601 -264.278019)
			(xy 122.866625 -264.322056) (xy 122.889751 -264.370077) (xy 122.905461 -264.421007) (xy 122.913404 -264.473711)
			(xy 122.913902 -264.50036) (xy 122.913404 -264.527009) (xy 123.141984 -264.527009) (xy 123.141984 -264.473711)
			(xy 123.149927 -264.421007) (xy 123.165637 -264.370077) (xy 123.188763 -264.322056) (xy 123.218787 -264.278019)
			(xy 123.255039 -264.238948) (xy 123.29671 -264.205717) (xy 123.342868 -264.179068) (xy 123.392482 -264.159596)
			(xy 123.444444 -264.147736) (xy 123.497594 -264.143753) (xy 123.550744 -264.147736) (xy 123.602706 -264.159596)
			(xy 123.65232 -264.179068) (xy 123.698478 -264.205717) (xy 123.740149 -264.238948) (xy 123.776401 -264.278019)
			(xy 123.806425 -264.322056) (xy 123.829551 -264.370077) (xy 123.845261 -264.421007) (xy 123.853204 -264.473711)
			(xy 123.853702 -264.50036) (xy 123.853204 -264.527009) (xy 124.081784 -264.527009) (xy 124.081784 -264.473711)
			(xy 124.089727 -264.421007) (xy 124.105437 -264.370077) (xy 124.128563 -264.322056) (xy 124.158587 -264.278019)
			(xy 124.194839 -264.238948) (xy 124.23651 -264.205717) (xy 124.282668 -264.179068) (xy 124.332282 -264.159596)
			(xy 124.384244 -264.147736) (xy 124.437394 -264.143753) (xy 124.490544 -264.147736) (xy 124.542506 -264.159596)
			(xy 124.59212 -264.179068) (xy 124.638278 -264.205717) (xy 124.679949 -264.238948) (xy 124.716201 -264.278019)
			(xy 124.746225 -264.322056) (xy 124.769351 -264.370077) (xy 124.785061 -264.421007) (xy 124.793004 -264.473711)
			(xy 124.793502 -264.50036) (xy 124.793004 -264.527009) (xy 125.021584 -264.527009) (xy 125.021584 -264.473711)
			(xy 125.029527 -264.421007) (xy 125.045237 -264.370077) (xy 125.068363 -264.322056) (xy 125.098387 -264.278019)
			(xy 125.134639 -264.238948) (xy 125.17631 -264.205717) (xy 125.222468 -264.179068) (xy 125.272082 -264.159596)
			(xy 125.324044 -264.147736) (xy 125.377194 -264.143753) (xy 125.430344 -264.147736) (xy 125.482306 -264.159596)
			(xy 125.53192 -264.179068) (xy 125.578078 -264.205717) (xy 125.619749 -264.238948) (xy 125.656001 -264.278019)
			(xy 125.686025 -264.322056) (xy 125.709151 -264.370077) (xy 125.724861 -264.421007) (xy 125.732804 -264.473711)
			(xy 125.733302 -264.50036) (xy 125.732804 -264.527009) (xy 125.961638 -264.527009) (xy 125.961638 -264.473711)
			(xy 125.969581 -264.421007) (xy 125.985291 -264.370077) (xy 126.008417 -264.322056) (xy 126.038441 -264.278019)
			(xy 126.074693 -264.238948) (xy 126.116364 -264.205717) (xy 126.162522 -264.179068) (xy 126.212136 -264.159596)
			(xy 126.264098 -264.147736) (xy 126.317248 -264.143753) (xy 126.370398 -264.147736) (xy 126.42236 -264.159596)
			(xy 126.471974 -264.179068) (xy 126.518132 -264.205717) (xy 126.559803 -264.238948) (xy 126.596055 -264.278019)
			(xy 126.626079 -264.322056) (xy 126.649205 -264.370077) (xy 126.664915 -264.421007) (xy 126.672858 -264.473711)
			(xy 126.673356 -264.50036) (xy 126.672858 -264.527009) (xy 126.901184 -264.527009) (xy 126.901184 -264.473711)
			(xy 126.909127 -264.421007) (xy 126.924837 -264.370077) (xy 126.947963 -264.322056) (xy 126.977987 -264.278019)
			(xy 127.014239 -264.238948) (xy 127.05591 -264.205717) (xy 127.102068 -264.179068) (xy 127.151682 -264.159596)
			(xy 127.203644 -264.147736) (xy 127.256794 -264.143753) (xy 127.309944 -264.147736) (xy 127.361906 -264.159596)
			(xy 127.41152 -264.179068) (xy 127.457678 -264.205717) (xy 127.499349 -264.238948) (xy 127.535601 -264.278019)
			(xy 127.565625 -264.322056) (xy 127.588751 -264.370077) (xy 127.604461 -264.421007) (xy 127.612404 -264.473711)
			(xy 127.612902 -264.50036) (xy 127.612404 -264.527009) (xy 127.840984 -264.527009) (xy 127.840984 -264.473711)
			(xy 127.848927 -264.421007) (xy 127.864637 -264.370077) (xy 127.887763 -264.322056) (xy 127.917787 -264.278019)
			(xy 127.954039 -264.238948) (xy 127.99571 -264.205717) (xy 128.041868 -264.179068) (xy 128.091482 -264.159596)
			(xy 128.143444 -264.147736) (xy 128.196594 -264.143753) (xy 128.249744 -264.147736) (xy 128.301706 -264.159596)
			(xy 128.35132 -264.179068) (xy 128.397478 -264.205717) (xy 128.439149 -264.238948) (xy 128.475401 -264.278019)
			(xy 128.505425 -264.322056) (xy 128.528551 -264.370077) (xy 128.544261 -264.421007) (xy 128.552204 -264.473711)
			(xy 128.552702 -264.50036) (xy 128.552204 -264.527009) (xy 128.780784 -264.527009) (xy 128.780784 -264.473711)
			(xy 128.788727 -264.421007) (xy 128.804437 -264.370077) (xy 128.827563 -264.322056) (xy 128.857587 -264.278019)
			(xy 128.893839 -264.238948) (xy 128.93551 -264.205717) (xy 128.981668 -264.179068) (xy 129.031282 -264.159596)
			(xy 129.083244 -264.147736) (xy 129.136394 -264.143753) (xy 129.189544 -264.147736) (xy 129.241506 -264.159596)
			(xy 129.29112 -264.179068) (xy 129.337278 -264.205717) (xy 129.378949 -264.238948) (xy 129.415201 -264.278019)
			(xy 129.445225 -264.322056) (xy 129.468351 -264.370077) (xy 129.484061 -264.421007) (xy 129.492004 -264.473711)
			(xy 129.492502 -264.50036) (xy 129.492004 -264.527009) (xy 129.720584 -264.527009) (xy 129.720584 -264.473711)
			(xy 129.728527 -264.421007) (xy 129.744237 -264.370077) (xy 129.767363 -264.322056) (xy 129.797387 -264.278019)
			(xy 129.833639 -264.238948) (xy 129.87531 -264.205717) (xy 129.921468 -264.179068) (xy 129.971082 -264.159596)
			(xy 130.023044 -264.147736) (xy 130.076194 -264.143753) (xy 130.129344 -264.147736) (xy 130.181306 -264.159596)
			(xy 130.23092 -264.179068) (xy 130.277078 -264.205717) (xy 130.318749 -264.238948) (xy 130.355001 -264.278019)
			(xy 130.385025 -264.322056) (xy 130.408151 -264.370077) (xy 130.423861 -264.421007) (xy 130.431804 -264.473711)
			(xy 130.432302 -264.50036) (xy 130.431804 -264.527009) (xy 130.660384 -264.527009) (xy 130.660384 -264.473711)
			(xy 130.668327 -264.421007) (xy 130.684037 -264.370077) (xy 130.707163 -264.322056) (xy 130.737187 -264.278019)
			(xy 130.773439 -264.238948) (xy 130.81511 -264.205717) (xy 130.861268 -264.179068) (xy 130.910882 -264.159596)
			(xy 130.962844 -264.147736) (xy 131.015994 -264.143753) (xy 131.069144 -264.147736) (xy 131.121106 -264.159596)
			(xy 131.17072 -264.179068) (xy 131.216878 -264.205717) (xy 131.258549 -264.238948) (xy 131.294801 -264.278019)
			(xy 131.324825 -264.322056) (xy 131.347951 -264.370077) (xy 131.363661 -264.421007) (xy 131.371604 -264.473711)
			(xy 131.372102 -264.50036) (xy 131.371604 -264.527009) (xy 131.600184 -264.527009) (xy 131.600184 -264.473711)
			(xy 131.608127 -264.421007) (xy 131.623837 -264.370077) (xy 131.646963 -264.322056) (xy 131.676987 -264.278019)
			(xy 131.713239 -264.238948) (xy 131.75491 -264.205717) (xy 131.801068 -264.179068) (xy 131.850682 -264.159596)
			(xy 131.902644 -264.147736) (xy 131.955794 -264.143753) (xy 132.008944 -264.147736) (xy 132.060906 -264.159596)
			(xy 132.11052 -264.179068) (xy 132.156678 -264.205717) (xy 132.198349 -264.238948) (xy 132.234601 -264.278019)
			(xy 132.264625 -264.322056) (xy 132.287751 -264.370077) (xy 132.303461 -264.421007) (xy 132.311404 -264.473711)
			(xy 132.311902 -264.50036) (xy 132.311404 -264.527009) (xy 132.540238 -264.527009) (xy 132.540238 -264.473711)
			(xy 132.548181 -264.421007) (xy 132.563891 -264.370077) (xy 132.587017 -264.322056) (xy 132.617041 -264.278019)
			(xy 132.653293 -264.238948) (xy 132.694964 -264.205717) (xy 132.741122 -264.179068) (xy 132.790736 -264.159596)
			(xy 132.842698 -264.147736) (xy 132.895848 -264.143753) (xy 132.948998 -264.147736) (xy 133.00096 -264.159596)
			(xy 133.050574 -264.179068) (xy 133.096732 -264.205717) (xy 133.138403 -264.238948) (xy 133.174655 -264.278019)
			(xy 133.204679 -264.322056) (xy 133.227805 -264.370077) (xy 133.243515 -264.421007) (xy 133.251458 -264.473711)
			(xy 133.251956 -264.50036) (xy 133.251458 -264.527009) (xy 133.479784 -264.527009) (xy 133.479784 -264.473711)
			(xy 133.487727 -264.421007) (xy 133.503437 -264.370077) (xy 133.526563 -264.322056) (xy 133.556587 -264.278019)
			(xy 133.592839 -264.238948) (xy 133.63451 -264.205717) (xy 133.680668 -264.179068) (xy 133.730282 -264.159596)
			(xy 133.782244 -264.147736) (xy 133.835394 -264.143753) (xy 133.888544 -264.147736) (xy 133.940506 -264.159596)
			(xy 133.99012 -264.179068) (xy 134.036278 -264.205717) (xy 134.077949 -264.238948) (xy 134.114201 -264.278019)
			(xy 134.144225 -264.322056) (xy 134.167351 -264.370077) (xy 134.183061 -264.421007) (xy 134.191004 -264.473711)
			(xy 134.191502 -264.50036) (xy 134.191004 -264.527009) (xy 134.183061 -264.579713) (xy 134.167351 -264.630643)
			(xy 134.144225 -264.678664) (xy 134.114201 -264.722701) (xy 134.077949 -264.761772) (xy 134.036278 -264.795003)
			(xy 133.99012 -264.821652) (xy 133.940506 -264.841124) (xy 133.888544 -264.852984) (xy 133.835394 -264.856968)
			(xy 133.782244 -264.852984) (xy 133.730282 -264.841124) (xy 133.680668 -264.821652) (xy 133.63451 -264.795003)
			(xy 133.592839 -264.761772) (xy 133.556587 -264.722701) (xy 133.526563 -264.678664) (xy 133.503437 -264.630643)
			(xy 133.487727 -264.579713) (xy 133.479784 -264.527009) (xy 133.251458 -264.527009) (xy 133.243515 -264.579713)
			(xy 133.227805 -264.630643) (xy 133.204679 -264.678664) (xy 133.174655 -264.722701) (xy 133.138403 -264.761772)
			(xy 133.096732 -264.795003) (xy 133.050574 -264.821652) (xy 133.00096 -264.841124) (xy 132.948998 -264.852984)
			(xy 132.895848 -264.856968) (xy 132.842698 -264.852984) (xy 132.790736 -264.841124) (xy 132.741122 -264.821652)
			(xy 132.694964 -264.795003) (xy 132.653293 -264.761772) (xy 132.617041 -264.722701) (xy 132.587017 -264.678664)
			(xy 132.563891 -264.630643) (xy 132.548181 -264.579713) (xy 132.540238 -264.527009) (xy 132.311404 -264.527009)
			(xy 132.303461 -264.579713) (xy 132.287751 -264.630643) (xy 132.264625 -264.678664) (xy 132.234601 -264.722701)
			(xy 132.198349 -264.761772) (xy 132.156678 -264.795003) (xy 132.11052 -264.821652) (xy 132.060906 -264.841124)
			(xy 132.008944 -264.852984) (xy 131.955794 -264.856968) (xy 131.902644 -264.852984) (xy 131.850682 -264.841124)
			(xy 131.801068 -264.821652) (xy 131.75491 -264.795003) (xy 131.713239 -264.761772) (xy 131.676987 -264.722701)
			(xy 131.646963 -264.678664) (xy 131.623837 -264.630643) (xy 131.608127 -264.579713) (xy 131.600184 -264.527009)
			(xy 131.371604 -264.527009) (xy 131.363661 -264.579713) (xy 131.347951 -264.630643) (xy 131.324825 -264.678664)
			(xy 131.294801 -264.722701) (xy 131.258549 -264.761772) (xy 131.216878 -264.795003) (xy 131.17072 -264.821652)
			(xy 131.121106 -264.841124) (xy 131.069144 -264.852984) (xy 131.015994 -264.856968) (xy 130.962844 -264.852984)
			(xy 130.910882 -264.841124) (xy 130.861268 -264.821652) (xy 130.81511 -264.795003) (xy 130.773439 -264.761772)
			(xy 130.737187 -264.722701) (xy 130.707163 -264.678664) (xy 130.684037 -264.630643) (xy 130.668327 -264.579713)
			(xy 130.660384 -264.527009) (xy 130.431804 -264.527009) (xy 130.423861 -264.579713) (xy 130.408151 -264.630643)
			(xy 130.385025 -264.678664) (xy 130.355001 -264.722701) (xy 130.318749 -264.761772) (xy 130.277078 -264.795003)
			(xy 130.23092 -264.821652) (xy 130.181306 -264.841124) (xy 130.129344 -264.852984) (xy 130.076194 -264.856968)
			(xy 130.023044 -264.852984) (xy 129.971082 -264.841124) (xy 129.921468 -264.821652) (xy 129.87531 -264.795003)
			(xy 129.833639 -264.761772) (xy 129.797387 -264.722701) (xy 129.767363 -264.678664) (xy 129.744237 -264.630643)
			(xy 129.728527 -264.579713) (xy 129.720584 -264.527009) (xy 129.492004 -264.527009) (xy 129.484061 -264.579713)
			(xy 129.468351 -264.630643) (xy 129.445225 -264.678664) (xy 129.415201 -264.722701) (xy 129.378949 -264.761772)
			(xy 129.337278 -264.795003) (xy 129.29112 -264.821652) (xy 129.241506 -264.841124) (xy 129.189544 -264.852984)
			(xy 129.136394 -264.856968) (xy 129.083244 -264.852984) (xy 129.031282 -264.841124) (xy 128.981668 -264.821652)
			(xy 128.93551 -264.795003) (xy 128.893839 -264.761772) (xy 128.857587 -264.722701) (xy 128.827563 -264.678664)
			(xy 128.804437 -264.630643) (xy 128.788727 -264.579713) (xy 128.780784 -264.527009) (xy 128.552204 -264.527009)
			(xy 128.544261 -264.579713) (xy 128.528551 -264.630643) (xy 128.505425 -264.678664) (xy 128.475401 -264.722701)
			(xy 128.439149 -264.761772) (xy 128.397478 -264.795003) (xy 128.35132 -264.821652) (xy 128.301706 -264.841124)
			(xy 128.249744 -264.852984) (xy 128.196594 -264.856968) (xy 128.143444 -264.852984) (xy 128.091482 -264.841124)
			(xy 128.041868 -264.821652) (xy 127.99571 -264.795003) (xy 127.954039 -264.761772) (xy 127.917787 -264.722701)
			(xy 127.887763 -264.678664) (xy 127.864637 -264.630643) (xy 127.848927 -264.579713) (xy 127.840984 -264.527009)
			(xy 127.612404 -264.527009) (xy 127.604461 -264.579713) (xy 127.588751 -264.630643) (xy 127.565625 -264.678664)
			(xy 127.535601 -264.722701) (xy 127.499349 -264.761772) (xy 127.457678 -264.795003) (xy 127.41152 -264.821652)
			(xy 127.361906 -264.841124) (xy 127.309944 -264.852984) (xy 127.256794 -264.856968) (xy 127.203644 -264.852984)
			(xy 127.151682 -264.841124) (xy 127.102068 -264.821652) (xy 127.05591 -264.795003) (xy 127.014239 -264.761772)
			(xy 126.977987 -264.722701) (xy 126.947963 -264.678664) (xy 126.924837 -264.630643) (xy 126.909127 -264.579713)
			(xy 126.901184 -264.527009) (xy 126.672858 -264.527009) (xy 126.664915 -264.579713) (xy 126.649205 -264.630643)
			(xy 126.626079 -264.678664) (xy 126.596055 -264.722701) (xy 126.559803 -264.761772) (xy 126.518132 -264.795003)
			(xy 126.471974 -264.821652) (xy 126.42236 -264.841124) (xy 126.370398 -264.852984) (xy 126.317248 -264.856968)
			(xy 126.264098 -264.852984) (xy 126.212136 -264.841124) (xy 126.162522 -264.821652) (xy 126.116364 -264.795003)
			(xy 126.074693 -264.761772) (xy 126.038441 -264.722701) (xy 126.008417 -264.678664) (xy 125.985291 -264.630643)
			(xy 125.969581 -264.579713) (xy 125.961638 -264.527009) (xy 125.732804 -264.527009) (xy 125.724861 -264.579713)
			(xy 125.709151 -264.630643) (xy 125.686025 -264.678664) (xy 125.656001 -264.722701) (xy 125.619749 -264.761772)
			(xy 125.578078 -264.795003) (xy 125.53192 -264.821652) (xy 125.482306 -264.841124) (xy 125.430344 -264.852984)
			(xy 125.377194 -264.856968) (xy 125.324044 -264.852984) (xy 125.272082 -264.841124) (xy 125.222468 -264.821652)
			(xy 125.17631 -264.795003) (xy 125.134639 -264.761772) (xy 125.098387 -264.722701) (xy 125.068363 -264.678664)
			(xy 125.045237 -264.630643) (xy 125.029527 -264.579713) (xy 125.021584 -264.527009) (xy 124.793004 -264.527009)
			(xy 124.785061 -264.579713) (xy 124.769351 -264.630643) (xy 124.746225 -264.678664) (xy 124.716201 -264.722701)
			(xy 124.679949 -264.761772) (xy 124.638278 -264.795003) (xy 124.59212 -264.821652) (xy 124.542506 -264.841124)
			(xy 124.490544 -264.852984) (xy 124.437394 -264.856968) (xy 124.384244 -264.852984) (xy 124.332282 -264.841124)
			(xy 124.282668 -264.821652) (xy 124.23651 -264.795003) (xy 124.194839 -264.761772) (xy 124.158587 -264.722701)
			(xy 124.128563 -264.678664) (xy 124.105437 -264.630643) (xy 124.089727 -264.579713) (xy 124.081784 -264.527009)
			(xy 123.853204 -264.527009) (xy 123.845261 -264.579713) (xy 123.829551 -264.630643) (xy 123.806425 -264.678664)
			(xy 123.776401 -264.722701) (xy 123.740149 -264.761772) (xy 123.698478 -264.795003) (xy 123.65232 -264.821652)
			(xy 123.602706 -264.841124) (xy 123.550744 -264.852984) (xy 123.497594 -264.856968) (xy 123.444444 -264.852984)
			(xy 123.392482 -264.841124) (xy 123.342868 -264.821652) (xy 123.29671 -264.795003) (xy 123.255039 -264.761772)
			(xy 123.218787 -264.722701) (xy 123.188763 -264.678664) (xy 123.165637 -264.630643) (xy 123.149927 -264.579713)
			(xy 123.141984 -264.527009) (xy 122.913404 -264.527009) (xy 122.905461 -264.579713) (xy 122.889751 -264.630643)
			(xy 122.866625 -264.678664) (xy 122.836601 -264.722701) (xy 122.800349 -264.761772) (xy 122.758678 -264.795003)
			(xy 122.71252 -264.821652) (xy 122.662906 -264.841124) (xy 122.610944 -264.852984) (xy 122.557794 -264.856968)
			(xy 122.504644 -264.852984) (xy 122.452682 -264.841124) (xy 122.403068 -264.821652) (xy 122.35691 -264.795003)
			(xy 122.315239 -264.761772) (xy 122.278987 -264.722701) (xy 122.248963 -264.678664) (xy 122.225837 -264.630643)
			(xy 122.210127 -264.579713) (xy 122.202184 -264.527009) (xy 121.973604 -264.527009) (xy 121.965661 -264.579713)
			(xy 121.949951 -264.630643) (xy 121.926825 -264.678664) (xy 121.896801 -264.722701) (xy 121.860549 -264.761772)
			(xy 121.818878 -264.795003) (xy 121.77272 -264.821652) (xy 121.723106 -264.841124) (xy 121.671144 -264.852984)
			(xy 121.617994 -264.856968) (xy 121.564844 -264.852984) (xy 121.512882 -264.841124) (xy 121.463268 -264.821652)
			(xy 121.41711 -264.795003) (xy 121.375439 -264.761772) (xy 121.339187 -264.722701) (xy 121.309163 -264.678664)
			(xy 121.286037 -264.630643) (xy 121.270327 -264.579713) (xy 121.262384 -264.527009) (xy 121.033804 -264.527009)
			(xy 121.025861 -264.579713) (xy 121.010151 -264.630643) (xy 120.987025 -264.678664) (xy 120.957001 -264.722701)
			(xy 120.920749 -264.761772) (xy 120.879078 -264.795003) (xy 120.83292 -264.821652) (xy 120.783306 -264.841124)
			(xy 120.731344 -264.852984) (xy 120.678194 -264.856968) (xy 120.625044 -264.852984) (xy 120.573082 -264.841124)
			(xy 120.523468 -264.821652) (xy 120.47731 -264.795003) (xy 120.435639 -264.761772) (xy 120.399387 -264.722701)
			(xy 120.369363 -264.678664) (xy 120.346237 -264.630643) (xy 120.330527 -264.579713) (xy 120.322584 -264.527009)
			(xy 120.093078 -264.527009) (xy 120.091088 -264.55356) (xy 120.079226 -264.605532) (xy 120.05975 -264.655156)
			(xy 120.033095 -264.701322) (xy 119.999857 -264.743001) (xy 119.960779 -264.77926) (xy 119.916733 -264.809289)
			(xy 119.868703 -264.832418) (xy 119.817762 -264.848131) (xy 119.765048 -264.856075) (xy 119.738394 -264.856468)
			(xy 119.73814 -264.856468) (xy 119.70748 -264.855802) (xy 119.647072 -264.845267) (xy 119.589351 -264.824566)
			(xy 119.562372 -264.809986) (xy 119.548908 -264.802965) (xy 119.519286 -264.796359) (xy 119.489031 -264.798744)
			(xy 119.46081 -264.809909) (xy 119.437112 -264.82887) (xy 119.420029 -264.853955) (xy 119.411065 -264.88295)
			(xy 119.41048 -264.898124) (xy 119.41048 -264.986008) (xy 119.43715 -265.000486) (xy 119.461097 -265.013891)
			(xy 119.504917 -265.046929) (xy 119.543143 -265.086305) (xy 119.574867 -265.131085) (xy 119.599335 -265.180207)
			(xy 119.615968 -265.232505) (xy 119.624371 -265.286736) (xy 119.624856 -265.314176) (xy 119.624335 -265.340825)
			(xy 119.852938 -265.340825) (xy 119.852938 -265.287527) (xy 119.860881 -265.234823) (xy 119.876591 -265.183893)
			(xy 119.899717 -265.135872) (xy 119.929741 -265.091835) (xy 119.965993 -265.052764) (xy 120.007664 -265.019533)
			(xy 120.053822 -264.992884) (xy 120.103436 -264.973412) (xy 120.155398 -264.961552) (xy 120.208548 -264.957569)
			(xy 120.261698 -264.961552) (xy 120.31366 -264.973412) (xy 120.363274 -264.992884) (xy 120.409432 -265.019533)
			(xy 120.451103 -265.052764) (xy 120.487355 -265.091835) (xy 120.517379 -265.135872) (xy 120.540505 -265.183893)
			(xy 120.556215 -265.234823) (xy 120.564158 -265.287527) (xy 120.564656 -265.314176) (xy 120.564158 -265.340825)
			(xy 121.732538 -265.340825) (xy 121.732538 -265.287527) (xy 121.740481 -265.234823) (xy 121.756191 -265.183893)
			(xy 121.779317 -265.135872) (xy 121.809341 -265.091835) (xy 121.845593 -265.052764) (xy 121.887264 -265.019533)
			(xy 121.933422 -264.992884) (xy 121.983036 -264.973412) (xy 122.034998 -264.961552) (xy 122.088148 -264.957569)
			(xy 122.141298 -264.961552) (xy 122.19326 -264.973412) (xy 122.242874 -264.992884) (xy 122.289032 -265.019533)
			(xy 122.330703 -265.052764) (xy 122.366955 -265.091835) (xy 122.396979 -265.135872) (xy 122.420105 -265.183893)
			(xy 122.435815 -265.234823) (xy 122.443758 -265.287527) (xy 122.444256 -265.314176) (xy 122.443758 -265.340825)
			(xy 122.672338 -265.340825) (xy 122.672338 -265.287527) (xy 122.680281 -265.234823) (xy 122.695991 -265.183893)
			(xy 122.719117 -265.135872) (xy 122.749141 -265.091835) (xy 122.785393 -265.052764) (xy 122.827064 -265.019533)
			(xy 122.873222 -264.992884) (xy 122.922836 -264.973412) (xy 122.974798 -264.961552) (xy 123.027948 -264.957569)
			(xy 123.081098 -264.961552) (xy 123.13306 -264.973412) (xy 123.182674 -264.992884) (xy 123.228832 -265.019533)
			(xy 123.270503 -265.052764) (xy 123.306755 -265.091835) (xy 123.336779 -265.135872) (xy 123.359905 -265.183893)
			(xy 123.375615 -265.234823) (xy 123.383558 -265.287527) (xy 123.384056 -265.314176) (xy 123.383558 -265.340825)
			(xy 123.612138 -265.340825) (xy 123.612138 -265.287527) (xy 123.620081 -265.234823) (xy 123.635791 -265.183893)
			(xy 123.658917 -265.135872) (xy 123.688941 -265.091835) (xy 123.725193 -265.052764) (xy 123.766864 -265.019533)
			(xy 123.813022 -264.992884) (xy 123.862636 -264.973412) (xy 123.914598 -264.961552) (xy 123.967748 -264.957569)
			(xy 124.020898 -264.961552) (xy 124.07286 -264.973412) (xy 124.122474 -264.992884) (xy 124.168632 -265.019533)
			(xy 124.210303 -265.052764) (xy 124.246555 -265.091835) (xy 124.276579 -265.135872) (xy 124.299705 -265.183893)
			(xy 124.315415 -265.234823) (xy 124.323358 -265.287527) (xy 124.323856 -265.314176) (xy 124.323358 -265.340825)
			(xy 124.551938 -265.340825) (xy 124.551938 -265.287527) (xy 124.559881 -265.234823) (xy 124.575591 -265.183893)
			(xy 124.598717 -265.135872) (xy 124.628741 -265.091835) (xy 124.664993 -265.052764) (xy 124.706664 -265.019533)
			(xy 124.752822 -264.992884) (xy 124.802436 -264.973412) (xy 124.854398 -264.961552) (xy 124.907548 -264.957569)
			(xy 124.960698 -264.961552) (xy 125.01266 -264.973412) (xy 125.062274 -264.992884) (xy 125.108432 -265.019533)
			(xy 125.150103 -265.052764) (xy 125.186355 -265.091835) (xy 125.216379 -265.135872) (xy 125.239505 -265.183893)
			(xy 125.255215 -265.234823) (xy 125.263158 -265.287527) (xy 125.263656 -265.314176) (xy 125.263158 -265.340825)
			(xy 125.491738 -265.340825) (xy 125.491738 -265.287527) (xy 125.499681 -265.234823) (xy 125.515391 -265.183893)
			(xy 125.538517 -265.135872) (xy 125.568541 -265.091835) (xy 125.604793 -265.052764) (xy 125.646464 -265.019533)
			(xy 125.692622 -264.992884) (xy 125.742236 -264.973412) (xy 125.794198 -264.961552) (xy 125.847348 -264.957569)
			(xy 125.900498 -264.961552) (xy 125.95246 -264.973412) (xy 126.002074 -264.992884) (xy 126.048232 -265.019533)
			(xy 126.089903 -265.052764) (xy 126.126155 -265.091835) (xy 126.156179 -265.135872) (xy 126.179305 -265.183893)
			(xy 126.195015 -265.234823) (xy 126.202958 -265.287527) (xy 126.203456 -265.314176) (xy 126.202958 -265.340825)
			(xy 126.431284 -265.340825) (xy 126.431284 -265.287527) (xy 126.439227 -265.234823) (xy 126.454937 -265.183893)
			(xy 126.478063 -265.135872) (xy 126.508087 -265.091835) (xy 126.544339 -265.052764) (xy 126.58601 -265.019533)
			(xy 126.632168 -264.992884) (xy 126.681782 -264.973412) (xy 126.733744 -264.961552) (xy 126.786894 -264.957569)
			(xy 126.840044 -264.961552) (xy 126.892006 -264.973412) (xy 126.94162 -264.992884) (xy 126.987778 -265.019533)
			(xy 127.029449 -265.052764) (xy 127.065701 -265.091835) (xy 127.095725 -265.135872) (xy 127.118851 -265.183893)
			(xy 127.134561 -265.234823) (xy 127.142504 -265.287527) (xy 127.143002 -265.314176) (xy 127.142504 -265.340825)
			(xy 127.371338 -265.340825) (xy 127.371338 -265.287527) (xy 127.379281 -265.234823) (xy 127.394991 -265.183893)
			(xy 127.418117 -265.135872) (xy 127.448141 -265.091835) (xy 127.484393 -265.052764) (xy 127.526064 -265.019533)
			(xy 127.572222 -264.992884) (xy 127.621836 -264.973412) (xy 127.673798 -264.961552) (xy 127.726948 -264.957569)
			(xy 127.780098 -264.961552) (xy 127.83206 -264.973412) (xy 127.881674 -264.992884) (xy 127.927832 -265.019533)
			(xy 127.969503 -265.052764) (xy 128.005755 -265.091835) (xy 128.035779 -265.135872) (xy 128.058905 -265.183893)
			(xy 128.074615 -265.234823) (xy 128.082558 -265.287527) (xy 128.083056 -265.314176) (xy 128.082558 -265.340825)
			(xy 128.311138 -265.340825) (xy 128.311138 -265.287527) (xy 128.319081 -265.234823) (xy 128.334791 -265.183893)
			(xy 128.357917 -265.135872) (xy 128.387941 -265.091835) (xy 128.424193 -265.052764) (xy 128.465864 -265.019533)
			(xy 128.512022 -264.992884) (xy 128.561636 -264.973412) (xy 128.613598 -264.961552) (xy 128.666748 -264.957569)
			(xy 128.719898 -264.961552) (xy 128.77186 -264.973412) (xy 128.821474 -264.992884) (xy 128.867632 -265.019533)
			(xy 128.909303 -265.052764) (xy 128.945555 -265.091835) (xy 128.975579 -265.135872) (xy 128.998705 -265.183893)
			(xy 129.014415 -265.234823) (xy 129.022358 -265.287527) (xy 129.022856 -265.314176) (xy 129.022358 -265.340825)
			(xy 129.250938 -265.340825) (xy 129.250938 -265.287527) (xy 129.258881 -265.234823) (xy 129.274591 -265.183893)
			(xy 129.297717 -265.135872) (xy 129.327741 -265.091835) (xy 129.363993 -265.052764) (xy 129.405664 -265.019533)
			(xy 129.451822 -264.992884) (xy 129.501436 -264.973412) (xy 129.553398 -264.961552) (xy 129.606548 -264.957569)
			(xy 129.659698 -264.961552) (xy 129.71166 -264.973412) (xy 129.761274 -264.992884) (xy 129.807432 -265.019533)
			(xy 129.849103 -265.052764) (xy 129.885355 -265.091835) (xy 129.915379 -265.135872) (xy 129.938505 -265.183893)
			(xy 129.954215 -265.234823) (xy 129.962158 -265.287527) (xy 129.962656 -265.314176) (xy 129.962158 -265.340825)
			(xy 130.190738 -265.340825) (xy 130.190738 -265.287527) (xy 130.198681 -265.234823) (xy 130.214391 -265.183893)
			(xy 130.237517 -265.135872) (xy 130.267541 -265.091835) (xy 130.303793 -265.052764) (xy 130.345464 -265.019533)
			(xy 130.391622 -264.992884) (xy 130.441236 -264.973412) (xy 130.493198 -264.961552) (xy 130.546348 -264.957569)
			(xy 130.599498 -264.961552) (xy 130.65146 -264.973412) (xy 130.701074 -264.992884) (xy 130.747232 -265.019533)
			(xy 130.788903 -265.052764) (xy 130.825155 -265.091835) (xy 130.855179 -265.135872) (xy 130.878305 -265.183893)
			(xy 130.894015 -265.234823) (xy 130.901958 -265.287527) (xy 130.902456 -265.314176) (xy 130.901958 -265.340825)
			(xy 131.130538 -265.340825) (xy 131.130538 -265.287527) (xy 131.138481 -265.234823) (xy 131.154191 -265.183893)
			(xy 131.177317 -265.135872) (xy 131.207341 -265.091835) (xy 131.243593 -265.052764) (xy 131.285264 -265.019533)
			(xy 131.331422 -264.992884) (xy 131.381036 -264.973412) (xy 131.432998 -264.961552) (xy 131.486148 -264.957569)
			(xy 131.539298 -264.961552) (xy 131.59126 -264.973412) (xy 131.640874 -264.992884) (xy 131.687032 -265.019533)
			(xy 131.728703 -265.052764) (xy 131.764955 -265.091835) (xy 131.794979 -265.135872) (xy 131.818105 -265.183893)
			(xy 131.833815 -265.234823) (xy 131.841758 -265.287527) (xy 131.842256 -265.314176) (xy 131.841758 -265.340825)
			(xy 132.070338 -265.340825) (xy 132.070338 -265.287527) (xy 132.078281 -265.234823) (xy 132.093991 -265.183893)
			(xy 132.117117 -265.135872) (xy 132.147141 -265.091835) (xy 132.183393 -265.052764) (xy 132.225064 -265.019533)
			(xy 132.271222 -264.992884) (xy 132.320836 -264.973412) (xy 132.372798 -264.961552) (xy 132.425948 -264.957569)
			(xy 132.479098 -264.961552) (xy 132.53106 -264.973412) (xy 132.580674 -264.992884) (xy 132.626832 -265.019533)
			(xy 132.668503 -265.052764) (xy 132.704755 -265.091835) (xy 132.734779 -265.135872) (xy 132.757905 -265.183893)
			(xy 132.773615 -265.234823) (xy 132.781558 -265.287527) (xy 132.782056 -265.314176) (xy 132.781558 -265.340825)
			(xy 133.009884 -265.340825) (xy 133.009884 -265.287527) (xy 133.017827 -265.234823) (xy 133.033537 -265.183893)
			(xy 133.056663 -265.135872) (xy 133.086687 -265.091835) (xy 133.122939 -265.052764) (xy 133.16461 -265.019533)
			(xy 133.210768 -264.992884) (xy 133.260382 -264.973412) (xy 133.312344 -264.961552) (xy 133.365494 -264.957569)
			(xy 133.418644 -264.961552) (xy 133.470606 -264.973412) (xy 133.52022 -264.992884) (xy 133.566378 -265.019533)
			(xy 133.608049 -265.052764) (xy 133.644301 -265.091835) (xy 133.674325 -265.135872) (xy 133.697451 -265.183893)
			(xy 133.713161 -265.234823) (xy 133.721104 -265.287527) (xy 133.721602 -265.314176) (xy 133.721104 -265.340825)
			(xy 133.949938 -265.340825) (xy 133.949938 -265.287527) (xy 133.957881 -265.234823) (xy 133.973591 -265.183893)
			(xy 133.996717 -265.135872) (xy 134.026741 -265.091835) (xy 134.062993 -265.052764) (xy 134.104664 -265.019533)
			(xy 134.150822 -264.992884) (xy 134.200436 -264.973412) (xy 134.252398 -264.961552) (xy 134.305548 -264.957569)
			(xy 134.358698 -264.961552) (xy 134.41066 -264.973412) (xy 134.460274 -264.992884) (xy 134.506432 -265.019533)
			(xy 134.548103 -265.052764) (xy 134.584355 -265.091835) (xy 134.614379 -265.135872) (xy 134.637505 -265.183893)
			(xy 134.653215 -265.234823) (xy 134.661158 -265.287527) (xy 134.661656 -265.314176) (xy 134.661158 -265.340825)
			(xy 134.653215 -265.393529) (xy 134.637505 -265.444459) (xy 134.614379 -265.49248) (xy 134.584355 -265.536517)
			(xy 134.548103 -265.575588) (xy 134.506432 -265.608819) (xy 134.460274 -265.635468) (xy 134.41066 -265.65494)
			(xy 134.358698 -265.6668) (xy 134.305548 -265.670784) (xy 134.252398 -265.6668) (xy 134.200436 -265.65494)
			(xy 134.150822 -265.635468) (xy 134.104664 -265.608819) (xy 134.062993 -265.575588) (xy 134.026741 -265.536517)
			(xy 133.996717 -265.49248) (xy 133.973591 -265.444459) (xy 133.957881 -265.393529) (xy 133.949938 -265.340825)
			(xy 133.721104 -265.340825) (xy 133.713161 -265.393529) (xy 133.697451 -265.444459) (xy 133.674325 -265.49248)
			(xy 133.644301 -265.536517) (xy 133.608049 -265.575588) (xy 133.566378 -265.608819) (xy 133.52022 -265.635468)
			(xy 133.470606 -265.65494) (xy 133.418644 -265.6668) (xy 133.365494 -265.670784) (xy 133.312344 -265.6668)
			(xy 133.260382 -265.65494) (xy 133.210768 -265.635468) (xy 133.16461 -265.608819) (xy 133.122939 -265.575588)
			(xy 133.086687 -265.536517) (xy 133.056663 -265.49248) (xy 133.033537 -265.444459) (xy 133.017827 -265.393529)
			(xy 133.009884 -265.340825) (xy 132.781558 -265.340825) (xy 132.773615 -265.393529) (xy 132.757905 -265.444459)
			(xy 132.734779 -265.49248) (xy 132.704755 -265.536517) (xy 132.668503 -265.575588) (xy 132.626832 -265.608819)
			(xy 132.580674 -265.635468) (xy 132.53106 -265.65494) (xy 132.479098 -265.6668) (xy 132.425948 -265.670784)
			(xy 132.372798 -265.6668) (xy 132.320836 -265.65494) (xy 132.271222 -265.635468) (xy 132.225064 -265.608819)
			(xy 132.183393 -265.575588) (xy 132.147141 -265.536517) (xy 132.117117 -265.49248) (xy 132.093991 -265.444459)
			(xy 132.078281 -265.393529) (xy 132.070338 -265.340825) (xy 131.841758 -265.340825) (xy 131.833815 -265.393529)
			(xy 131.818105 -265.444459) (xy 131.794979 -265.49248) (xy 131.764955 -265.536517) (xy 131.728703 -265.575588)
			(xy 131.687032 -265.608819) (xy 131.640874 -265.635468) (xy 131.59126 -265.65494) (xy 131.539298 -265.6668)
			(xy 131.486148 -265.670784) (xy 131.432998 -265.6668) (xy 131.381036 -265.65494) (xy 131.331422 -265.635468)
			(xy 131.285264 -265.608819) (xy 131.243593 -265.575588) (xy 131.207341 -265.536517) (xy 131.177317 -265.49248)
			(xy 131.154191 -265.444459) (xy 131.138481 -265.393529) (xy 131.130538 -265.340825) (xy 130.901958 -265.340825)
			(xy 130.894015 -265.393529) (xy 130.878305 -265.444459) (xy 130.855179 -265.49248) (xy 130.825155 -265.536517)
			(xy 130.788903 -265.575588) (xy 130.747232 -265.608819) (xy 130.701074 -265.635468) (xy 130.65146 -265.65494)
			(xy 130.599498 -265.6668) (xy 130.546348 -265.670784) (xy 130.493198 -265.6668) (xy 130.441236 -265.65494)
			(xy 130.391622 -265.635468) (xy 130.345464 -265.608819) (xy 130.303793 -265.575588) (xy 130.267541 -265.536517)
			(xy 130.237517 -265.49248) (xy 130.214391 -265.444459) (xy 130.198681 -265.393529) (xy 130.190738 -265.340825)
			(xy 129.962158 -265.340825) (xy 129.954215 -265.393529) (xy 129.938505 -265.444459) (xy 129.915379 -265.49248)
			(xy 129.885355 -265.536517) (xy 129.849103 -265.575588) (xy 129.807432 -265.608819) (xy 129.761274 -265.635468)
			(xy 129.71166 -265.65494) (xy 129.659698 -265.6668) (xy 129.606548 -265.670784) (xy 129.553398 -265.6668)
			(xy 129.501436 -265.65494) (xy 129.451822 -265.635468) (xy 129.405664 -265.608819) (xy 129.363993 -265.575588)
			(xy 129.327741 -265.536517) (xy 129.297717 -265.49248) (xy 129.274591 -265.444459) (xy 129.258881 -265.393529)
			(xy 129.250938 -265.340825) (xy 129.022358 -265.340825) (xy 129.014415 -265.393529) (xy 128.998705 -265.444459)
			(xy 128.975579 -265.49248) (xy 128.945555 -265.536517) (xy 128.909303 -265.575588) (xy 128.867632 -265.608819)
			(xy 128.821474 -265.635468) (xy 128.77186 -265.65494) (xy 128.719898 -265.6668) (xy 128.666748 -265.670784)
			(xy 128.613598 -265.6668) (xy 128.561636 -265.65494) (xy 128.512022 -265.635468) (xy 128.465864 -265.608819)
			(xy 128.424193 -265.575588) (xy 128.387941 -265.536517) (xy 128.357917 -265.49248) (xy 128.334791 -265.444459)
			(xy 128.319081 -265.393529) (xy 128.311138 -265.340825) (xy 128.082558 -265.340825) (xy 128.074615 -265.393529)
			(xy 128.058905 -265.444459) (xy 128.035779 -265.49248) (xy 128.005755 -265.536517) (xy 127.969503 -265.575588)
			(xy 127.927832 -265.608819) (xy 127.881674 -265.635468) (xy 127.83206 -265.65494) (xy 127.780098 -265.6668)
			(xy 127.726948 -265.670784) (xy 127.673798 -265.6668) (xy 127.621836 -265.65494) (xy 127.572222 -265.635468)
			(xy 127.526064 -265.608819) (xy 127.484393 -265.575588) (xy 127.448141 -265.536517) (xy 127.418117 -265.49248)
			(xy 127.394991 -265.444459) (xy 127.379281 -265.393529) (xy 127.371338 -265.340825) (xy 127.142504 -265.340825)
			(xy 127.134561 -265.393529) (xy 127.118851 -265.444459) (xy 127.095725 -265.49248) (xy 127.065701 -265.536517)
			(xy 127.029449 -265.575588) (xy 126.987778 -265.608819) (xy 126.94162 -265.635468) (xy 126.892006 -265.65494)
			(xy 126.840044 -265.6668) (xy 126.786894 -265.670784) (xy 126.733744 -265.6668) (xy 126.681782 -265.65494)
			(xy 126.632168 -265.635468) (xy 126.58601 -265.608819) (xy 126.544339 -265.575588) (xy 126.508087 -265.536517)
			(xy 126.478063 -265.49248) (xy 126.454937 -265.444459) (xy 126.439227 -265.393529) (xy 126.431284 -265.340825)
			(xy 126.202958 -265.340825) (xy 126.195015 -265.393529) (xy 126.179305 -265.444459) (xy 126.156179 -265.49248)
			(xy 126.126155 -265.536517) (xy 126.089903 -265.575588) (xy 126.048232 -265.608819) (xy 126.002074 -265.635468)
			(xy 125.95246 -265.65494) (xy 125.900498 -265.6668) (xy 125.847348 -265.670784) (xy 125.794198 -265.6668)
			(xy 125.742236 -265.65494) (xy 125.692622 -265.635468) (xy 125.646464 -265.608819) (xy 125.604793 -265.575588)
			(xy 125.568541 -265.536517) (xy 125.538517 -265.49248) (xy 125.515391 -265.444459) (xy 125.499681 -265.393529)
			(xy 125.491738 -265.340825) (xy 125.263158 -265.340825) (xy 125.255215 -265.393529) (xy 125.239505 -265.444459)
			(xy 125.216379 -265.49248) (xy 125.186355 -265.536517) (xy 125.150103 -265.575588) (xy 125.108432 -265.608819)
			(xy 125.062274 -265.635468) (xy 125.01266 -265.65494) (xy 124.960698 -265.6668) (xy 124.907548 -265.670784)
			(xy 124.854398 -265.6668) (xy 124.802436 -265.65494) (xy 124.752822 -265.635468) (xy 124.706664 -265.608819)
			(xy 124.664993 -265.575588) (xy 124.628741 -265.536517) (xy 124.598717 -265.49248) (xy 124.575591 -265.444459)
			(xy 124.559881 -265.393529) (xy 124.551938 -265.340825) (xy 124.323358 -265.340825) (xy 124.315415 -265.393529)
			(xy 124.299705 -265.444459) (xy 124.276579 -265.49248) (xy 124.246555 -265.536517) (xy 124.210303 -265.575588)
			(xy 124.168632 -265.608819) (xy 124.122474 -265.635468) (xy 124.07286 -265.65494) (xy 124.020898 -265.6668)
			(xy 123.967748 -265.670784) (xy 123.914598 -265.6668) (xy 123.862636 -265.65494) (xy 123.813022 -265.635468)
			(xy 123.766864 -265.608819) (xy 123.725193 -265.575588) (xy 123.688941 -265.536517) (xy 123.658917 -265.49248)
			(xy 123.635791 -265.444459) (xy 123.620081 -265.393529) (xy 123.612138 -265.340825) (xy 123.383558 -265.340825)
			(xy 123.375615 -265.393529) (xy 123.359905 -265.444459) (xy 123.336779 -265.49248) (xy 123.306755 -265.536517)
			(xy 123.270503 -265.575588) (xy 123.228832 -265.608819) (xy 123.182674 -265.635468) (xy 123.13306 -265.65494)
			(xy 123.081098 -265.6668) (xy 123.027948 -265.670784) (xy 122.974798 -265.6668) (xy 122.922836 -265.65494)
			(xy 122.873222 -265.635468) (xy 122.827064 -265.608819) (xy 122.785393 -265.575588) (xy 122.749141 -265.536517)
			(xy 122.719117 -265.49248) (xy 122.695991 -265.444459) (xy 122.680281 -265.393529) (xy 122.672338 -265.340825)
			(xy 122.443758 -265.340825) (xy 122.435815 -265.393529) (xy 122.420105 -265.444459) (xy 122.396979 -265.49248)
			(xy 122.366955 -265.536517) (xy 122.330703 -265.575588) (xy 122.289032 -265.608819) (xy 122.242874 -265.635468)
			(xy 122.19326 -265.65494) (xy 122.141298 -265.6668) (xy 122.088148 -265.670784) (xy 122.034998 -265.6668)
			(xy 121.983036 -265.65494) (xy 121.933422 -265.635468) (xy 121.887264 -265.608819) (xy 121.845593 -265.575588)
			(xy 121.809341 -265.536517) (xy 121.779317 -265.49248) (xy 121.756191 -265.444459) (xy 121.740481 -265.393529)
			(xy 121.732538 -265.340825) (xy 120.564158 -265.340825) (xy 120.556215 -265.393529) (xy 120.540505 -265.444459)
			(xy 120.517379 -265.49248) (xy 120.487355 -265.536517) (xy 120.451103 -265.575588) (xy 120.409432 -265.608819)
			(xy 120.363274 -265.635468) (xy 120.31366 -265.65494) (xy 120.261698 -265.6668) (xy 120.208548 -265.670784)
			(xy 120.155398 -265.6668) (xy 120.103436 -265.65494) (xy 120.053822 -265.635468) (xy 120.007664 -265.608819)
			(xy 119.965993 -265.575588) (xy 119.929741 -265.536517) (xy 119.899717 -265.49248) (xy 119.876591 -265.444459)
			(xy 119.860881 -265.393529) (xy 119.852938 -265.340825) (xy 119.624335 -265.340825) (xy 119.624309 -265.342162)
			(xy 119.615557 -265.397445) (xy 119.598265 -265.450678) (xy 119.572859 -265.500551) (xy 119.539964 -265.545836)
			(xy 119.500391 -265.585418) (xy 119.455112 -265.618322) (xy 119.405245 -265.643738) (xy 119.352015 -265.66104)
			(xy 119.296734 -265.669803) (xy 119.268748 -265.670284) (xy 119.244877 -265.669879) (xy 119.197567 -265.663465)
			(xy 119.151535 -265.6508) (xy 119.107603 -265.632108) (xy 119.086884 -265.620246) (xy 119.052848 -265.60018)
			(xy 118.978426 -265.674602) (xy 118.968214 -265.685627) (xy 118.954133 -265.712158) (xy 118.94837 -265.741637)
			(xy 118.951422 -265.771518) (xy 118.963027 -265.799222) (xy 118.982181 -265.822358) (xy 118.994428 -265.831066)
			(xy 119.015201 -265.845262) (xy 119.052911 -265.878568) (xy 119.085558 -265.916851) (xy 119.112491 -265.959348)
			(xy 119.133174 -266.005212) (xy 119.147197 -266.053532) (xy 119.154278 -266.103344) (xy 119.154702 -266.1285)
			(xy 119.154211 -266.154895) (xy 119.382784 -266.154895) (xy 119.382784 -266.101597) (xy 119.390727 -266.048893)
			(xy 119.406437 -265.997963) (xy 119.429563 -265.949942) (xy 119.459587 -265.905905) (xy 119.495839 -265.866834)
			(xy 119.53751 -265.833603) (xy 119.583668 -265.806954) (xy 119.633282 -265.787482) (xy 119.685244 -265.775622)
			(xy 119.738394 -265.771639) (xy 119.791544 -265.775622) (xy 119.843506 -265.787482) (xy 119.89312 -265.806954)
			(xy 119.939278 -265.833603) (xy 119.980949 -265.866834) (xy 120.017201 -265.905905) (xy 120.047225 -265.949942)
			(xy 120.070351 -265.997963) (xy 120.086061 -266.048893) (xy 120.094004 -266.101597) (xy 120.094502 -266.128246)
			(xy 120.094004 -266.154895) (xy 120.322584 -266.154895) (xy 120.322584 -266.101597) (xy 120.330527 -266.048893)
			(xy 120.346237 -265.997963) (xy 120.369363 -265.949942) (xy 120.399387 -265.905905) (xy 120.435639 -265.866834)
			(xy 120.47731 -265.833603) (xy 120.523468 -265.806954) (xy 120.573082 -265.787482) (xy 120.625044 -265.775622)
			(xy 120.678194 -265.771639) (xy 120.731344 -265.775622) (xy 120.783306 -265.787482) (xy 120.83292 -265.806954)
			(xy 120.879078 -265.833603) (xy 120.920749 -265.866834) (xy 120.957001 -265.905905) (xy 120.987025 -265.949942)
			(xy 121.010151 -265.997963) (xy 121.025861 -266.048893) (xy 121.033804 -266.101597) (xy 121.034302 -266.128246)
			(xy 121.033804 -266.154895) (xy 122.202184 -266.154895) (xy 122.202184 -266.101597) (xy 122.210127 -266.048893)
			(xy 122.225837 -265.997963) (xy 122.248963 -265.949942) (xy 122.278987 -265.905905) (xy 122.315239 -265.866834)
			(xy 122.35691 -265.833603) (xy 122.403068 -265.806954) (xy 122.452682 -265.787482) (xy 122.504644 -265.775622)
			(xy 122.557794 -265.771639) (xy 122.610944 -265.775622) (xy 122.662906 -265.787482) (xy 122.71252 -265.806954)
			(xy 122.758678 -265.833603) (xy 122.800349 -265.866834) (xy 122.836601 -265.905905) (xy 122.866625 -265.949942)
			(xy 122.889751 -265.997963) (xy 122.905461 -266.048893) (xy 122.913404 -266.101597) (xy 122.913902 -266.128246)
			(xy 122.913404 -266.154895) (xy 123.141984 -266.154895) (xy 123.141984 -266.101597) (xy 123.149927 -266.048893)
			(xy 123.165637 -265.997963) (xy 123.188763 -265.949942) (xy 123.218787 -265.905905) (xy 123.255039 -265.866834)
			(xy 123.29671 -265.833603) (xy 123.342868 -265.806954) (xy 123.392482 -265.787482) (xy 123.444444 -265.775622)
			(xy 123.497594 -265.771639) (xy 123.550744 -265.775622) (xy 123.602706 -265.787482) (xy 123.65232 -265.806954)
			(xy 123.698478 -265.833603) (xy 123.740149 -265.866834) (xy 123.776401 -265.905905) (xy 123.806425 -265.949942)
			(xy 123.829551 -265.997963) (xy 123.845261 -266.048893) (xy 123.853204 -266.101597) (xy 123.853702 -266.128246)
			(xy 123.853204 -266.154895) (xy 124.081784 -266.154895) (xy 124.081784 -266.101597) (xy 124.089727 -266.048893)
			(xy 124.105437 -265.997963) (xy 124.128563 -265.949942) (xy 124.158587 -265.905905) (xy 124.194839 -265.866834)
			(xy 124.23651 -265.833603) (xy 124.282668 -265.806954) (xy 124.332282 -265.787482) (xy 124.384244 -265.775622)
			(xy 124.437394 -265.771639) (xy 124.490544 -265.775622) (xy 124.542506 -265.787482) (xy 124.59212 -265.806954)
			(xy 124.638278 -265.833603) (xy 124.679949 -265.866834) (xy 124.716201 -265.905905) (xy 124.746225 -265.949942)
			(xy 124.769351 -265.997963) (xy 124.785061 -266.048893) (xy 124.793004 -266.101597) (xy 124.793502 -266.128246)
			(xy 124.793004 -266.154895) (xy 125.021584 -266.154895) (xy 125.021584 -266.101597) (xy 125.029527 -266.048893)
			(xy 125.045237 -265.997963) (xy 125.068363 -265.949942) (xy 125.098387 -265.905905) (xy 125.134639 -265.866834)
			(xy 125.17631 -265.833603) (xy 125.222468 -265.806954) (xy 125.272082 -265.787482) (xy 125.324044 -265.775622)
			(xy 125.377194 -265.771639) (xy 125.430344 -265.775622) (xy 125.482306 -265.787482) (xy 125.53192 -265.806954)
			(xy 125.578078 -265.833603) (xy 125.619749 -265.866834) (xy 125.656001 -265.905905) (xy 125.686025 -265.949942)
			(xy 125.709151 -265.997963) (xy 125.724861 -266.048893) (xy 125.732804 -266.101597) (xy 125.733302 -266.128246)
			(xy 125.732804 -266.154895) (xy 125.961384 -266.154895) (xy 125.961384 -266.101597) (xy 125.969327 -266.048893)
			(xy 125.985037 -265.997963) (xy 126.008163 -265.949942) (xy 126.038187 -265.905905) (xy 126.074439 -265.866834)
			(xy 126.11611 -265.833603) (xy 126.162268 -265.806954) (xy 126.211882 -265.787482) (xy 126.263844 -265.775622)
			(xy 126.316994 -265.771639) (xy 126.370144 -265.775622) (xy 126.422106 -265.787482) (xy 126.47172 -265.806954)
			(xy 126.517878 -265.833603) (xy 126.559549 -265.866834) (xy 126.595801 -265.905905) (xy 126.625825 -265.949942)
			(xy 126.648951 -265.997963) (xy 126.664661 -266.048893) (xy 126.672604 -266.101597) (xy 126.673102 -266.128246)
			(xy 126.672604 -266.154895) (xy 126.901184 -266.154895) (xy 126.901184 -266.101597) (xy 126.909127 -266.048893)
			(xy 126.924837 -265.997963) (xy 126.947963 -265.949942) (xy 126.977987 -265.905905) (xy 127.014239 -265.866834)
			(xy 127.05591 -265.833603) (xy 127.102068 -265.806954) (xy 127.151682 -265.787482) (xy 127.203644 -265.775622)
			(xy 127.256794 -265.771639) (xy 127.309944 -265.775622) (xy 127.361906 -265.787482) (xy 127.41152 -265.806954)
			(xy 127.457678 -265.833603) (xy 127.499349 -265.866834) (xy 127.535601 -265.905905) (xy 127.565625 -265.949942)
			(xy 127.588751 -265.997963) (xy 127.604461 -266.048893) (xy 127.612404 -266.101597) (xy 127.612902 -266.128246)
			(xy 127.612404 -266.154895) (xy 127.840984 -266.154895) (xy 127.840984 -266.101597) (xy 127.848927 -266.048893)
			(xy 127.864637 -265.997963) (xy 127.887763 -265.949942) (xy 127.917787 -265.905905) (xy 127.954039 -265.866834)
			(xy 127.99571 -265.833603) (xy 128.041868 -265.806954) (xy 128.091482 -265.787482) (xy 128.143444 -265.775622)
			(xy 128.196594 -265.771639) (xy 128.249744 -265.775622) (xy 128.301706 -265.787482) (xy 128.35132 -265.806954)
			(xy 128.397478 -265.833603) (xy 128.439149 -265.866834) (xy 128.475401 -265.905905) (xy 128.505425 -265.949942)
			(xy 128.528551 -265.997963) (xy 128.544261 -266.048893) (xy 128.552204 -266.101597) (xy 128.552702 -266.128246)
			(xy 128.552204 -266.154895) (xy 128.780784 -266.154895) (xy 128.780784 -266.101597) (xy 128.788727 -266.048893)
			(xy 128.804437 -265.997963) (xy 128.827563 -265.949942) (xy 128.857587 -265.905905) (xy 128.893839 -265.866834)
			(xy 128.93551 -265.833603) (xy 128.981668 -265.806954) (xy 129.031282 -265.787482) (xy 129.083244 -265.775622)
			(xy 129.136394 -265.771639) (xy 129.189544 -265.775622) (xy 129.241506 -265.787482) (xy 129.29112 -265.806954)
			(xy 129.337278 -265.833603) (xy 129.378949 -265.866834) (xy 129.415201 -265.905905) (xy 129.445225 -265.949942)
			(xy 129.468351 -265.997963) (xy 129.484061 -266.048893) (xy 129.492004 -266.101597) (xy 129.492502 -266.128246)
			(xy 129.492004 -266.154895) (xy 129.720584 -266.154895) (xy 129.720584 -266.101597) (xy 129.728527 -266.048893)
			(xy 129.744237 -265.997963) (xy 129.767363 -265.949942) (xy 129.797387 -265.905905) (xy 129.833639 -265.866834)
			(xy 129.87531 -265.833603) (xy 129.921468 -265.806954) (xy 129.971082 -265.787482) (xy 130.023044 -265.775622)
			(xy 130.076194 -265.771639) (xy 130.129344 -265.775622) (xy 130.181306 -265.787482) (xy 130.23092 -265.806954)
			(xy 130.277078 -265.833603) (xy 130.318749 -265.866834) (xy 130.355001 -265.905905) (xy 130.385025 -265.949942)
			(xy 130.408151 -265.997963) (xy 130.423861 -266.048893) (xy 130.431804 -266.101597) (xy 130.432302 -266.128246)
			(xy 130.431804 -266.154895) (xy 130.660384 -266.154895) (xy 130.660384 -266.101597) (xy 130.668327 -266.048893)
			(xy 130.684037 -265.997963) (xy 130.707163 -265.949942) (xy 130.737187 -265.905905) (xy 130.773439 -265.866834)
			(xy 130.81511 -265.833603) (xy 130.861268 -265.806954) (xy 130.910882 -265.787482) (xy 130.962844 -265.775622)
			(xy 131.015994 -265.771639) (xy 131.069144 -265.775622) (xy 131.121106 -265.787482) (xy 131.17072 -265.806954)
			(xy 131.216878 -265.833603) (xy 131.258549 -265.866834) (xy 131.294801 -265.905905) (xy 131.324825 -265.949942)
			(xy 131.347951 -265.997963) (xy 131.363661 -266.048893) (xy 131.371604 -266.101597) (xy 131.372102 -266.128246)
			(xy 131.371604 -266.154895) (xy 131.600184 -266.154895) (xy 131.600184 -266.101597) (xy 131.608127 -266.048893)
			(xy 131.623837 -265.997963) (xy 131.646963 -265.949942) (xy 131.676987 -265.905905) (xy 131.713239 -265.866834)
			(xy 131.75491 -265.833603) (xy 131.801068 -265.806954) (xy 131.850682 -265.787482) (xy 131.902644 -265.775622)
			(xy 131.955794 -265.771639) (xy 132.008944 -265.775622) (xy 132.060906 -265.787482) (xy 132.11052 -265.806954)
			(xy 132.156678 -265.833603) (xy 132.198349 -265.866834) (xy 132.234601 -265.905905) (xy 132.264625 -265.949942)
			(xy 132.287751 -265.997963) (xy 132.303461 -266.048893) (xy 132.311404 -266.101597) (xy 132.311902 -266.128246)
			(xy 132.311404 -266.154895) (xy 132.539984 -266.154895) (xy 132.539984 -266.101597) (xy 132.547927 -266.048893)
			(xy 132.563637 -265.997963) (xy 132.586763 -265.949942) (xy 132.616787 -265.905905) (xy 132.653039 -265.866834)
			(xy 132.69471 -265.833603) (xy 132.740868 -265.806954) (xy 132.790482 -265.787482) (xy 132.842444 -265.775622)
			(xy 132.895594 -265.771639) (xy 132.948744 -265.775622) (xy 133.000706 -265.787482) (xy 133.05032 -265.806954)
			(xy 133.096478 -265.833603) (xy 133.138149 -265.866834) (xy 133.174401 -265.905905) (xy 133.204425 -265.949942)
			(xy 133.227551 -265.997963) (xy 133.243261 -266.048893) (xy 133.251204 -266.101597) (xy 133.251702 -266.128246)
			(xy 133.251204 -266.154895) (xy 133.479784 -266.154895) (xy 133.479784 -266.101597) (xy 133.487727 -266.048893)
			(xy 133.503437 -265.997963) (xy 133.526563 -265.949942) (xy 133.556587 -265.905905) (xy 133.592839 -265.866834)
			(xy 133.63451 -265.833603) (xy 133.680668 -265.806954) (xy 133.730282 -265.787482) (xy 133.782244 -265.775622)
			(xy 133.835394 -265.771639) (xy 133.888544 -265.775622) (xy 133.940506 -265.787482) (xy 133.99012 -265.806954)
			(xy 134.036278 -265.833603) (xy 134.077949 -265.866834) (xy 134.114201 -265.905905) (xy 134.144225 -265.949942)
			(xy 134.167351 -265.997963) (xy 134.183061 -266.048893) (xy 134.191004 -266.101597) (xy 134.191502 -266.128246)
			(xy 134.191004 -266.154895) (xy 134.183061 -266.207599) (xy 134.167351 -266.258529) (xy 134.144225 -266.30655)
			(xy 134.114201 -266.350587) (xy 134.077949 -266.389658) (xy 134.036278 -266.422889) (xy 133.99012 -266.449538)
			(xy 133.940506 -266.46901) (xy 133.888544 -266.48087) (xy 133.835394 -266.484854) (xy 133.782244 -266.48087)
			(xy 133.730282 -266.46901) (xy 133.680668 -266.449538) (xy 133.63451 -266.422889) (xy 133.592839 -266.389658)
			(xy 133.556587 -266.350587) (xy 133.526563 -266.30655) (xy 133.503437 -266.258529) (xy 133.487727 -266.207599)
			(xy 133.479784 -266.154895) (xy 133.251204 -266.154895) (xy 133.243261 -266.207599) (xy 133.227551 -266.258529)
			(xy 133.204425 -266.30655) (xy 133.174401 -266.350587) (xy 133.138149 -266.389658) (xy 133.096478 -266.422889)
			(xy 133.05032 -266.449538) (xy 133.000706 -266.46901) (xy 132.948744 -266.48087) (xy 132.895594 -266.484854)
			(xy 132.842444 -266.48087) (xy 132.790482 -266.46901) (xy 132.740868 -266.449538) (xy 132.69471 -266.422889)
			(xy 132.653039 -266.389658) (xy 132.616787 -266.350587) (xy 132.586763 -266.30655) (xy 132.563637 -266.258529)
			(xy 132.547927 -266.207599) (xy 132.539984 -266.154895) (xy 132.311404 -266.154895) (xy 132.303461 -266.207599)
			(xy 132.287751 -266.258529) (xy 132.264625 -266.30655) (xy 132.234601 -266.350587) (xy 132.198349 -266.389658)
			(xy 132.156678 -266.422889) (xy 132.11052 -266.449538) (xy 132.060906 -266.46901) (xy 132.008944 -266.48087)
			(xy 131.955794 -266.484854) (xy 131.902644 -266.48087) (xy 131.850682 -266.46901) (xy 131.801068 -266.449538)
			(xy 131.75491 -266.422889) (xy 131.713239 -266.389658) (xy 131.676987 -266.350587) (xy 131.646963 -266.30655)
			(xy 131.623837 -266.258529) (xy 131.608127 -266.207599) (xy 131.600184 -266.154895) (xy 131.371604 -266.154895)
			(xy 131.363661 -266.207599) (xy 131.347951 -266.258529) (xy 131.324825 -266.30655) (xy 131.294801 -266.350587)
			(xy 131.258549 -266.389658) (xy 131.216878 -266.422889) (xy 131.17072 -266.449538) (xy 131.121106 -266.46901)
			(xy 131.069144 -266.48087) (xy 131.015994 -266.484854) (xy 130.962844 -266.48087) (xy 130.910882 -266.46901)
			(xy 130.861268 -266.449538) (xy 130.81511 -266.422889) (xy 130.773439 -266.389658) (xy 130.737187 -266.350587)
			(xy 130.707163 -266.30655) (xy 130.684037 -266.258529) (xy 130.668327 -266.207599) (xy 130.660384 -266.154895)
			(xy 130.431804 -266.154895) (xy 130.423861 -266.207599) (xy 130.408151 -266.258529) (xy 130.385025 -266.30655)
			(xy 130.355001 -266.350587) (xy 130.318749 -266.389658) (xy 130.277078 -266.422889) (xy 130.23092 -266.449538)
			(xy 130.181306 -266.46901) (xy 130.129344 -266.48087) (xy 130.076194 -266.484854) (xy 130.023044 -266.48087)
			(xy 129.971082 -266.46901) (xy 129.921468 -266.449538) (xy 129.87531 -266.422889) (xy 129.833639 -266.389658)
			(xy 129.797387 -266.350587) (xy 129.767363 -266.30655) (xy 129.744237 -266.258529) (xy 129.728527 -266.207599)
			(xy 129.720584 -266.154895) (xy 129.492004 -266.154895) (xy 129.484061 -266.207599) (xy 129.468351 -266.258529)
			(xy 129.445225 -266.30655) (xy 129.415201 -266.350587) (xy 129.378949 -266.389658) (xy 129.337278 -266.422889)
			(xy 129.29112 -266.449538) (xy 129.241506 -266.46901) (xy 129.189544 -266.48087) (xy 129.136394 -266.484854)
			(xy 129.083244 -266.48087) (xy 129.031282 -266.46901) (xy 128.981668 -266.449538) (xy 128.93551 -266.422889)
			(xy 128.893839 -266.389658) (xy 128.857587 -266.350587) (xy 128.827563 -266.30655) (xy 128.804437 -266.258529)
			(xy 128.788727 -266.207599) (xy 128.780784 -266.154895) (xy 128.552204 -266.154895) (xy 128.544261 -266.207599)
			(xy 128.528551 -266.258529) (xy 128.505425 -266.30655) (xy 128.475401 -266.350587) (xy 128.439149 -266.389658)
			(xy 128.397478 -266.422889) (xy 128.35132 -266.449538) (xy 128.301706 -266.46901) (xy 128.249744 -266.48087)
			(xy 128.196594 -266.484854) (xy 128.143444 -266.48087) (xy 128.091482 -266.46901) (xy 128.041868 -266.449538)
			(xy 127.99571 -266.422889) (xy 127.954039 -266.389658) (xy 127.917787 -266.350587) (xy 127.887763 -266.30655)
			(xy 127.864637 -266.258529) (xy 127.848927 -266.207599) (xy 127.840984 -266.154895) (xy 127.612404 -266.154895)
			(xy 127.604461 -266.207599) (xy 127.588751 -266.258529) (xy 127.565625 -266.30655) (xy 127.535601 -266.350587)
			(xy 127.499349 -266.389658) (xy 127.457678 -266.422889) (xy 127.41152 -266.449538) (xy 127.361906 -266.46901)
			(xy 127.309944 -266.48087) (xy 127.256794 -266.484854) (xy 127.203644 -266.48087) (xy 127.151682 -266.46901)
			(xy 127.102068 -266.449538) (xy 127.05591 -266.422889) (xy 127.014239 -266.389658) (xy 126.977987 -266.350587)
			(xy 126.947963 -266.30655) (xy 126.924837 -266.258529) (xy 126.909127 -266.207599) (xy 126.901184 -266.154895)
			(xy 126.672604 -266.154895) (xy 126.664661 -266.207599) (xy 126.648951 -266.258529) (xy 126.625825 -266.30655)
			(xy 126.595801 -266.350587) (xy 126.559549 -266.389658) (xy 126.517878 -266.422889) (xy 126.47172 -266.449538)
			(xy 126.422106 -266.46901) (xy 126.370144 -266.48087) (xy 126.316994 -266.484854) (xy 126.263844 -266.48087)
			(xy 126.211882 -266.46901) (xy 126.162268 -266.449538) (xy 126.11611 -266.422889) (xy 126.074439 -266.389658)
			(xy 126.038187 -266.350587) (xy 126.008163 -266.30655) (xy 125.985037 -266.258529) (xy 125.969327 -266.207599)
			(xy 125.961384 -266.154895) (xy 125.732804 -266.154895) (xy 125.724861 -266.207599) (xy 125.709151 -266.258529)
			(xy 125.686025 -266.30655) (xy 125.656001 -266.350587) (xy 125.619749 -266.389658) (xy 125.578078 -266.422889)
			(xy 125.53192 -266.449538) (xy 125.482306 -266.46901) (xy 125.430344 -266.48087) (xy 125.377194 -266.484854)
			(xy 125.324044 -266.48087) (xy 125.272082 -266.46901) (xy 125.222468 -266.449538) (xy 125.17631 -266.422889)
			(xy 125.134639 -266.389658) (xy 125.098387 -266.350587) (xy 125.068363 -266.30655) (xy 125.045237 -266.258529)
			(xy 125.029527 -266.207599) (xy 125.021584 -266.154895) (xy 124.793004 -266.154895) (xy 124.785061 -266.207599)
			(xy 124.769351 -266.258529) (xy 124.746225 -266.30655) (xy 124.716201 -266.350587) (xy 124.679949 -266.389658)
			(xy 124.638278 -266.422889) (xy 124.59212 -266.449538) (xy 124.542506 -266.46901) (xy 124.490544 -266.48087)
			(xy 124.437394 -266.484854) (xy 124.384244 -266.48087) (xy 124.332282 -266.46901) (xy 124.282668 -266.449538)
			(xy 124.23651 -266.422889) (xy 124.194839 -266.389658) (xy 124.158587 -266.350587) (xy 124.128563 -266.30655)
			(xy 124.105437 -266.258529) (xy 124.089727 -266.207599) (xy 124.081784 -266.154895) (xy 123.853204 -266.154895)
			(xy 123.845261 -266.207599) (xy 123.829551 -266.258529) (xy 123.806425 -266.30655) (xy 123.776401 -266.350587)
			(xy 123.740149 -266.389658) (xy 123.698478 -266.422889) (xy 123.65232 -266.449538) (xy 123.602706 -266.46901)
			(xy 123.550744 -266.48087) (xy 123.497594 -266.484854) (xy 123.444444 -266.48087) (xy 123.392482 -266.46901)
			(xy 123.342868 -266.449538) (xy 123.29671 -266.422889) (xy 123.255039 -266.389658) (xy 123.218787 -266.350587)
			(xy 123.188763 -266.30655) (xy 123.165637 -266.258529) (xy 123.149927 -266.207599) (xy 123.141984 -266.154895)
			(xy 122.913404 -266.154895) (xy 122.905461 -266.207599) (xy 122.889751 -266.258529) (xy 122.866625 -266.30655)
			(xy 122.836601 -266.350587) (xy 122.800349 -266.389658) (xy 122.758678 -266.422889) (xy 122.71252 -266.449538)
			(xy 122.662906 -266.46901) (xy 122.610944 -266.48087) (xy 122.557794 -266.484854) (xy 122.504644 -266.48087)
			(xy 122.452682 -266.46901) (xy 122.403068 -266.449538) (xy 122.35691 -266.422889) (xy 122.315239 -266.389658)
			(xy 122.278987 -266.350587) (xy 122.248963 -266.30655) (xy 122.225837 -266.258529) (xy 122.210127 -266.207599)
			(xy 122.202184 -266.154895) (xy 121.033804 -266.154895) (xy 121.025861 -266.207599) (xy 121.010151 -266.258529)
			(xy 120.987025 -266.30655) (xy 120.957001 -266.350587) (xy 120.920749 -266.389658) (xy 120.879078 -266.422889)
			(xy 120.83292 -266.449538) (xy 120.783306 -266.46901) (xy 120.731344 -266.48087) (xy 120.678194 -266.484854)
			(xy 120.625044 -266.48087) (xy 120.573082 -266.46901) (xy 120.523468 -266.449538) (xy 120.47731 -266.422889)
			(xy 120.435639 -266.389658) (xy 120.399387 -266.350587) (xy 120.369363 -266.30655) (xy 120.346237 -266.258529)
			(xy 120.330527 -266.207599) (xy 120.322584 -266.154895) (xy 120.094004 -266.154895) (xy 120.086061 -266.207599)
			(xy 120.070351 -266.258529) (xy 120.047225 -266.30655) (xy 120.017201 -266.350587) (xy 119.980949 -266.389658)
			(xy 119.939278 -266.422889) (xy 119.89312 -266.449538) (xy 119.843506 -266.46901) (xy 119.791544 -266.48087)
			(xy 119.738394 -266.484854) (xy 119.685244 -266.48087) (xy 119.633282 -266.46901) (xy 119.583668 -266.449538)
			(xy 119.53751 -266.422889) (xy 119.495839 -266.389658) (xy 119.459587 -266.350587) (xy 119.429563 -266.30655)
			(xy 119.406437 -266.258529) (xy 119.390727 -266.207599) (xy 119.382784 -266.154895) (xy 119.154211 -266.154895)
			(xy 119.154181 -266.156485) (xy 119.145426 -266.211766) (xy 119.12813 -266.264997) (xy 119.102719 -266.314867)
			(xy 119.069821 -266.360148) (xy 119.030243 -266.399725) (xy 118.984962 -266.432623) (xy 118.935092 -266.458032)
			(xy 118.881861 -266.475327) (xy 118.826579 -266.484082) (xy 118.798594 -266.484608) (xy 118.78418 -266.484485)
			(xy 118.755442 -266.482197) (xy 118.74119 -266.480036) (xy 118.726604 -266.478118) (xy 118.697427 -266.48178)
			(xy 118.670504 -266.493606) (xy 118.648068 -266.512615) (xy 118.63198 -266.53723) (xy 118.623575 -266.565409)
			(xy 118.62308 -266.580112) (xy 118.62308 -266.74191) (xy 118.637586 -266.764147) (xy 118.660553 -266.812013)
			(xy 118.676153 -266.86276) (xy 118.68404 -266.915261) (xy 118.684039 -266.968352) (xy 118.684023 -266.968457)
			(xy 121.732538 -266.968457) (xy 121.732538 -266.915159) (xy 121.740481 -266.862455) (xy 121.756191 -266.811525)
			(xy 121.779317 -266.763504) (xy 121.809341 -266.719467) (xy 121.845593 -266.680396) (xy 121.887264 -266.647165)
			(xy 121.933422 -266.620516) (xy 121.983036 -266.601044) (xy 122.034998 -266.589184) (xy 122.088148 -266.585201)
			(xy 122.141298 -266.589184) (xy 122.19326 -266.601044) (xy 122.242874 -266.620516) (xy 122.289032 -266.647165)
			(xy 122.330703 -266.680396) (xy 122.366955 -266.719467) (xy 122.396979 -266.763504) (xy 122.420105 -266.811525)
			(xy 122.435815 -266.862455) (xy 122.443758 -266.915159) (xy 122.444256 -266.941808) (xy 122.443758 -266.968457)
			(xy 122.672338 -266.968457) (xy 122.672338 -266.915159) (xy 122.680281 -266.862455) (xy 122.695991 -266.811525)
			(xy 122.719117 -266.763504) (xy 122.749141 -266.719467) (xy 122.785393 -266.680396) (xy 122.827064 -266.647165)
			(xy 122.873222 -266.620516) (xy 122.922836 -266.601044) (xy 122.974798 -266.589184) (xy 123.027948 -266.585201)
			(xy 123.081098 -266.589184) (xy 123.13306 -266.601044) (xy 123.182674 -266.620516) (xy 123.228832 -266.647165)
			(xy 123.270503 -266.680396) (xy 123.306755 -266.719467) (xy 123.336779 -266.763504) (xy 123.359905 -266.811525)
			(xy 123.375615 -266.862455) (xy 123.383558 -266.915159) (xy 123.384056 -266.941808) (xy 123.383558 -266.968457)
			(xy 123.612138 -266.968457) (xy 123.612138 -266.915159) (xy 123.620081 -266.862455) (xy 123.635791 -266.811525)
			(xy 123.658917 -266.763504) (xy 123.688941 -266.719467) (xy 123.725193 -266.680396) (xy 123.766864 -266.647165)
			(xy 123.813022 -266.620516) (xy 123.862636 -266.601044) (xy 123.914598 -266.589184) (xy 123.967748 -266.585201)
			(xy 124.020898 -266.589184) (xy 124.07286 -266.601044) (xy 124.122474 -266.620516) (xy 124.168632 -266.647165)
			(xy 124.210303 -266.680396) (xy 124.246555 -266.719467) (xy 124.276579 -266.763504) (xy 124.299705 -266.811525)
			(xy 124.315415 -266.862455) (xy 124.323358 -266.915159) (xy 124.323856 -266.941808) (xy 124.323358 -266.968457)
			(xy 124.551938 -266.968457) (xy 124.551938 -266.915159) (xy 124.559881 -266.862455) (xy 124.575591 -266.811525)
			(xy 124.598717 -266.763504) (xy 124.628741 -266.719467) (xy 124.664993 -266.680396) (xy 124.706664 -266.647165)
			(xy 124.752822 -266.620516) (xy 124.802436 -266.601044) (xy 124.854398 -266.589184) (xy 124.907548 -266.585201)
			(xy 124.960698 -266.589184) (xy 125.01266 -266.601044) (xy 125.062274 -266.620516) (xy 125.108432 -266.647165)
			(xy 125.150103 -266.680396) (xy 125.186355 -266.719467) (xy 125.216379 -266.763504) (xy 125.239505 -266.811525)
			(xy 125.255215 -266.862455) (xy 125.263158 -266.915159) (xy 125.263656 -266.941808) (xy 125.263158 -266.968457)
			(xy 125.491484 -266.968457) (xy 125.491484 -266.915159) (xy 125.499427 -266.862455) (xy 125.515137 -266.811525)
			(xy 125.538263 -266.763504) (xy 125.568287 -266.719467) (xy 125.604539 -266.680396) (xy 125.64621 -266.647165)
			(xy 125.692368 -266.620516) (xy 125.741982 -266.601044) (xy 125.793944 -266.589184) (xy 125.847094 -266.585201)
			(xy 125.900244 -266.589184) (xy 125.952206 -266.601044) (xy 126.00182 -266.620516) (xy 126.047978 -266.647165)
			(xy 126.089649 -266.680396) (xy 126.125901 -266.719467) (xy 126.155925 -266.763504) (xy 126.179051 -266.811525)
			(xy 126.194761 -266.862455) (xy 126.202704 -266.915159) (xy 126.203202 -266.941808) (xy 126.202704 -266.968457)
			(xy 126.431538 -266.968457) (xy 126.431538 -266.915159) (xy 126.439481 -266.862455) (xy 126.455191 -266.811525)
			(xy 126.478317 -266.763504) (xy 126.508341 -266.719467) (xy 126.544593 -266.680396) (xy 126.586264 -266.647165)
			(xy 126.632422 -266.620516) (xy 126.682036 -266.601044) (xy 126.733998 -266.589184) (xy 126.787148 -266.585201)
			(xy 126.840298 -266.589184) (xy 126.89226 -266.601044) (xy 126.941874 -266.620516) (xy 126.988032 -266.647165)
			(xy 127.029703 -266.680396) (xy 127.065955 -266.719467) (xy 127.095979 -266.763504) (xy 127.119105 -266.811525)
			(xy 127.134815 -266.862455) (xy 127.142758 -266.915159) (xy 127.143256 -266.941808) (xy 127.142758 -266.968457)
			(xy 127.371338 -266.968457) (xy 127.371338 -266.915159) (xy 127.379281 -266.862455) (xy 127.394991 -266.811525)
			(xy 127.418117 -266.763504) (xy 127.448141 -266.719467) (xy 127.484393 -266.680396) (xy 127.526064 -266.647165)
			(xy 127.572222 -266.620516) (xy 127.621836 -266.601044) (xy 127.673798 -266.589184) (xy 127.726948 -266.585201)
			(xy 127.780098 -266.589184) (xy 127.83206 -266.601044) (xy 127.881674 -266.620516) (xy 127.927832 -266.647165)
			(xy 127.969503 -266.680396) (xy 128.005755 -266.719467) (xy 128.035779 -266.763504) (xy 128.058905 -266.811525)
			(xy 128.074615 -266.862455) (xy 128.082558 -266.915159) (xy 128.083056 -266.941808) (xy 128.082558 -266.968457)
			(xy 128.311138 -266.968457) (xy 128.311138 -266.915159) (xy 128.319081 -266.862455) (xy 128.334791 -266.811525)
			(xy 128.357917 -266.763504) (xy 128.387941 -266.719467) (xy 128.424193 -266.680396) (xy 128.465864 -266.647165)
			(xy 128.512022 -266.620516) (xy 128.561636 -266.601044) (xy 128.613598 -266.589184) (xy 128.666748 -266.585201)
			(xy 128.719898 -266.589184) (xy 128.77186 -266.601044) (xy 128.821474 -266.620516) (xy 128.867632 -266.647165)
			(xy 128.909303 -266.680396) (xy 128.945555 -266.719467) (xy 128.975579 -266.763504) (xy 128.998705 -266.811525)
			(xy 129.014415 -266.862455) (xy 129.022358 -266.915159) (xy 129.022856 -266.941808) (xy 129.022358 -266.968457)
			(xy 129.250938 -266.968457) (xy 129.250938 -266.915159) (xy 129.258881 -266.862455) (xy 129.274591 -266.811525)
			(xy 129.297717 -266.763504) (xy 129.327741 -266.719467) (xy 129.363993 -266.680396) (xy 129.405664 -266.647165)
			(xy 129.451822 -266.620516) (xy 129.501436 -266.601044) (xy 129.553398 -266.589184) (xy 129.606548 -266.585201)
			(xy 129.659698 -266.589184) (xy 129.71166 -266.601044) (xy 129.761274 -266.620516) (xy 129.807432 -266.647165)
			(xy 129.849103 -266.680396) (xy 129.885355 -266.719467) (xy 129.915379 -266.763504) (xy 129.938505 -266.811525)
			(xy 129.954215 -266.862455) (xy 129.962158 -266.915159) (xy 129.962656 -266.941808) (xy 129.962158 -266.968457)
			(xy 130.190738 -266.968457) (xy 130.190738 -266.915159) (xy 130.198681 -266.862455) (xy 130.214391 -266.811525)
			(xy 130.237517 -266.763504) (xy 130.267541 -266.719467) (xy 130.303793 -266.680396) (xy 130.345464 -266.647165)
			(xy 130.391622 -266.620516) (xy 130.441236 -266.601044) (xy 130.493198 -266.589184) (xy 130.546348 -266.585201)
			(xy 130.599498 -266.589184) (xy 130.65146 -266.601044) (xy 130.701074 -266.620516) (xy 130.747232 -266.647165)
			(xy 130.788903 -266.680396) (xy 130.825155 -266.719467) (xy 130.855179 -266.763504) (xy 130.878305 -266.811525)
			(xy 130.894015 -266.862455) (xy 130.901958 -266.915159) (xy 130.902456 -266.941808) (xy 130.901958 -266.968457)
			(xy 131.130538 -266.968457) (xy 131.130538 -266.915159) (xy 131.138481 -266.862455) (xy 131.154191 -266.811525)
			(xy 131.177317 -266.763504) (xy 131.207341 -266.719467) (xy 131.243593 -266.680396) (xy 131.285264 -266.647165)
			(xy 131.331422 -266.620516) (xy 131.381036 -266.601044) (xy 131.432998 -266.589184) (xy 131.486148 -266.585201)
			(xy 131.539298 -266.589184) (xy 131.59126 -266.601044) (xy 131.640874 -266.620516) (xy 131.687032 -266.647165)
			(xy 131.728703 -266.680396) (xy 131.764955 -266.719467) (xy 131.794979 -266.763504) (xy 131.818105 -266.811525)
			(xy 131.833815 -266.862455) (xy 131.841758 -266.915159) (xy 131.842256 -266.941808) (xy 131.841758 -266.968457)
			(xy 132.070084 -266.968457) (xy 132.070084 -266.915159) (xy 132.078027 -266.862455) (xy 132.093737 -266.811525)
			(xy 132.116863 -266.763504) (xy 132.146887 -266.719467) (xy 132.183139 -266.680396) (xy 132.22481 -266.647165)
			(xy 132.270968 -266.620516) (xy 132.320582 -266.601044) (xy 132.372544 -266.589184) (xy 132.425694 -266.585201)
			(xy 132.478844 -266.589184) (xy 132.530806 -266.601044) (xy 132.58042 -266.620516) (xy 132.626578 -266.647165)
			(xy 132.668249 -266.680396) (xy 132.704501 -266.719467) (xy 132.734525 -266.763504) (xy 132.757651 -266.811525)
			(xy 132.773361 -266.862455) (xy 132.781304 -266.915159) (xy 132.781802 -266.941808) (xy 132.781304 -266.968457)
			(xy 133.009884 -266.968457) (xy 133.009884 -266.915159) (xy 133.017827 -266.862455) (xy 133.033537 -266.811525)
			(xy 133.056663 -266.763504) (xy 133.086687 -266.719467) (xy 133.122939 -266.680396) (xy 133.16461 -266.647165)
			(xy 133.210768 -266.620516) (xy 133.260382 -266.601044) (xy 133.312344 -266.589184) (xy 133.365494 -266.585201)
			(xy 133.418644 -266.589184) (xy 133.470606 -266.601044) (xy 133.52022 -266.620516) (xy 133.566378 -266.647165)
			(xy 133.608049 -266.680396) (xy 133.644301 -266.719467) (xy 133.674325 -266.763504) (xy 133.697451 -266.811525)
			(xy 133.713161 -266.862455) (xy 133.721104 -266.915159) (xy 133.721602 -266.941808) (xy 133.721104 -266.968457)
			(xy 133.949938 -266.968457) (xy 133.949938 -266.915159) (xy 133.957881 -266.862455) (xy 133.973591 -266.811525)
			(xy 133.996717 -266.763504) (xy 134.026741 -266.719467) (xy 134.062993 -266.680396) (xy 134.104664 -266.647165)
			(xy 134.150822 -266.620516) (xy 134.200436 -266.601044) (xy 134.252398 -266.589184) (xy 134.305548 -266.585201)
			(xy 134.358698 -266.589184) (xy 134.41066 -266.601044) (xy 134.460274 -266.620516) (xy 134.506432 -266.647165)
			(xy 134.548103 -266.680396) (xy 134.584355 -266.719467) (xy 134.614379 -266.763504) (xy 134.637505 -266.811525)
			(xy 134.653215 -266.862455) (xy 134.661158 -266.915159) (xy 134.661656 -266.941808) (xy 134.661158 -266.968457)
			(xy 134.653215 -267.021161) (xy 134.637505 -267.072091) (xy 134.614379 -267.120112) (xy 134.584355 -267.164149)
			(xy 134.548103 -267.20322) (xy 134.506432 -267.236451) (xy 134.460274 -267.2631) (xy 134.41066 -267.282572)
			(xy 134.358698 -267.294432) (xy 134.305548 -267.298416) (xy 134.252398 -267.294432) (xy 134.200436 -267.282572)
			(xy 134.150822 -267.2631) (xy 134.104664 -267.236451) (xy 134.062993 -267.20322) (xy 134.026741 -267.164149)
			(xy 133.996717 -267.120112) (xy 133.973591 -267.072091) (xy 133.957881 -267.021161) (xy 133.949938 -266.968457)
			(xy 133.721104 -266.968457) (xy 133.713161 -267.021161) (xy 133.697451 -267.072091) (xy 133.674325 -267.120112)
			(xy 133.644301 -267.164149) (xy 133.608049 -267.20322) (xy 133.566378 -267.236451) (xy 133.52022 -267.2631)
			(xy 133.470606 -267.282572) (xy 133.418644 -267.294432) (xy 133.365494 -267.298416) (xy 133.312344 -267.294432)
			(xy 133.260382 -267.282572) (xy 133.210768 -267.2631) (xy 133.16461 -267.236451) (xy 133.122939 -267.20322)
			(xy 133.086687 -267.164149) (xy 133.056663 -267.120112) (xy 133.033537 -267.072091) (xy 133.017827 -267.021161)
			(xy 133.009884 -266.968457) (xy 132.781304 -266.968457) (xy 132.773361 -267.021161) (xy 132.757651 -267.072091)
			(xy 132.734525 -267.120112) (xy 132.704501 -267.164149) (xy 132.668249 -267.20322) (xy 132.626578 -267.236451)
			(xy 132.58042 -267.2631) (xy 132.530806 -267.282572) (xy 132.478844 -267.294432) (xy 132.425694 -267.298416)
			(xy 132.372544 -267.294432) (xy 132.320582 -267.282572) (xy 132.270968 -267.2631) (xy 132.22481 -267.236451)
			(xy 132.183139 -267.20322) (xy 132.146887 -267.164149) (xy 132.116863 -267.120112) (xy 132.093737 -267.072091)
			(xy 132.078027 -267.021161) (xy 132.070084 -266.968457) (xy 131.841758 -266.968457) (xy 131.833815 -267.021161)
			(xy 131.818105 -267.072091) (xy 131.794979 -267.120112) (xy 131.764955 -267.164149) (xy 131.728703 -267.20322)
			(xy 131.687032 -267.236451) (xy 131.640874 -267.2631) (xy 131.59126 -267.282572) (xy 131.539298 -267.294432)
			(xy 131.486148 -267.298416) (xy 131.432998 -267.294432) (xy 131.381036 -267.282572) (xy 131.331422 -267.2631)
			(xy 131.285264 -267.236451) (xy 131.243593 -267.20322) (xy 131.207341 -267.164149) (xy 131.177317 -267.120112)
			(xy 131.154191 -267.072091) (xy 131.138481 -267.021161) (xy 131.130538 -266.968457) (xy 130.901958 -266.968457)
			(xy 130.894015 -267.021161) (xy 130.878305 -267.072091) (xy 130.855179 -267.120112) (xy 130.825155 -267.164149)
			(xy 130.788903 -267.20322) (xy 130.747232 -267.236451) (xy 130.701074 -267.2631) (xy 130.65146 -267.282572)
			(xy 130.599498 -267.294432) (xy 130.546348 -267.298416) (xy 130.493198 -267.294432) (xy 130.441236 -267.282572)
			(xy 130.391622 -267.2631) (xy 130.345464 -267.236451) (xy 130.303793 -267.20322) (xy 130.267541 -267.164149)
			(xy 130.237517 -267.120112) (xy 130.214391 -267.072091) (xy 130.198681 -267.021161) (xy 130.190738 -266.968457)
			(xy 129.962158 -266.968457) (xy 129.954215 -267.021161) (xy 129.938505 -267.072091) (xy 129.915379 -267.120112)
			(xy 129.885355 -267.164149) (xy 129.849103 -267.20322) (xy 129.807432 -267.236451) (xy 129.761274 -267.2631)
			(xy 129.71166 -267.282572) (xy 129.659698 -267.294432) (xy 129.606548 -267.298416) (xy 129.553398 -267.294432)
			(xy 129.501436 -267.282572) (xy 129.451822 -267.2631) (xy 129.405664 -267.236451) (xy 129.363993 -267.20322)
			(xy 129.327741 -267.164149) (xy 129.297717 -267.120112) (xy 129.274591 -267.072091) (xy 129.258881 -267.021161)
			(xy 129.250938 -266.968457) (xy 129.022358 -266.968457) (xy 129.014415 -267.021161) (xy 128.998705 -267.072091)
			(xy 128.975579 -267.120112) (xy 128.945555 -267.164149) (xy 128.909303 -267.20322) (xy 128.867632 -267.236451)
			(xy 128.821474 -267.2631) (xy 128.77186 -267.282572) (xy 128.719898 -267.294432) (xy 128.666748 -267.298416)
			(xy 128.613598 -267.294432) (xy 128.561636 -267.282572) (xy 128.512022 -267.2631) (xy 128.465864 -267.236451)
			(xy 128.424193 -267.20322) (xy 128.387941 -267.164149) (xy 128.357917 -267.120112) (xy 128.334791 -267.072091)
			(xy 128.319081 -267.021161) (xy 128.311138 -266.968457) (xy 128.082558 -266.968457) (xy 128.074615 -267.021161)
			(xy 128.058905 -267.072091) (xy 128.035779 -267.120112) (xy 128.005755 -267.164149) (xy 127.969503 -267.20322)
			(xy 127.927832 -267.236451) (xy 127.881674 -267.2631) (xy 127.83206 -267.282572) (xy 127.780098 -267.294432)
			(xy 127.726948 -267.298416) (xy 127.673798 -267.294432) (xy 127.621836 -267.282572) (xy 127.572222 -267.2631)
			(xy 127.526064 -267.236451) (xy 127.484393 -267.20322) (xy 127.448141 -267.164149) (xy 127.418117 -267.120112)
			(xy 127.394991 -267.072091) (xy 127.379281 -267.021161) (xy 127.371338 -266.968457) (xy 127.142758 -266.968457)
			(xy 127.134815 -267.021161) (xy 127.119105 -267.072091) (xy 127.095979 -267.120112) (xy 127.065955 -267.164149)
			(xy 127.029703 -267.20322) (xy 126.988032 -267.236451) (xy 126.941874 -267.2631) (xy 126.89226 -267.282572)
			(xy 126.840298 -267.294432) (xy 126.787148 -267.298416) (xy 126.733998 -267.294432) (xy 126.682036 -267.282572)
			(xy 126.632422 -267.2631) (xy 126.586264 -267.236451) (xy 126.544593 -267.20322) (xy 126.508341 -267.164149)
			(xy 126.478317 -267.120112) (xy 126.455191 -267.072091) (xy 126.439481 -267.021161) (xy 126.431538 -266.968457)
			(xy 126.202704 -266.968457) (xy 126.194761 -267.021161) (xy 126.179051 -267.072091) (xy 126.155925 -267.120112)
			(xy 126.125901 -267.164149) (xy 126.089649 -267.20322) (xy 126.047978 -267.236451) (xy 126.00182 -267.2631)
			(xy 125.952206 -267.282572) (xy 125.900244 -267.294432) (xy 125.847094 -267.298416) (xy 125.793944 -267.294432)
			(xy 125.741982 -267.282572) (xy 125.692368 -267.2631) (xy 125.64621 -267.236451) (xy 125.604539 -267.20322)
			(xy 125.568287 -267.164149) (xy 125.538263 -267.120112) (xy 125.515137 -267.072091) (xy 125.499427 -267.021161)
			(xy 125.491484 -266.968457) (xy 125.263158 -266.968457) (xy 125.255215 -267.021161) (xy 125.239505 -267.072091)
			(xy 125.216379 -267.120112) (xy 125.186355 -267.164149) (xy 125.150103 -267.20322) (xy 125.108432 -267.236451)
			(xy 125.062274 -267.2631) (xy 125.01266 -267.282572) (xy 124.960698 -267.294432) (xy 124.907548 -267.298416)
			(xy 124.854398 -267.294432) (xy 124.802436 -267.282572) (xy 124.752822 -267.2631) (xy 124.706664 -267.236451)
			(xy 124.664993 -267.20322) (xy 124.628741 -267.164149) (xy 124.598717 -267.120112) (xy 124.575591 -267.072091)
			(xy 124.559881 -267.021161) (xy 124.551938 -266.968457) (xy 124.323358 -266.968457) (xy 124.315415 -267.021161)
			(xy 124.299705 -267.072091) (xy 124.276579 -267.120112) (xy 124.246555 -267.164149) (xy 124.210303 -267.20322)
			(xy 124.168632 -267.236451) (xy 124.122474 -267.2631) (xy 124.07286 -267.282572) (xy 124.020898 -267.294432)
			(xy 123.967748 -267.298416) (xy 123.914598 -267.294432) (xy 123.862636 -267.282572) (xy 123.813022 -267.2631)
			(xy 123.766864 -267.236451) (xy 123.725193 -267.20322) (xy 123.688941 -267.164149) (xy 123.658917 -267.120112)
			(xy 123.635791 -267.072091) (xy 123.620081 -267.021161) (xy 123.612138 -266.968457) (xy 123.383558 -266.968457)
			(xy 123.375615 -267.021161) (xy 123.359905 -267.072091) (xy 123.336779 -267.120112) (xy 123.306755 -267.164149)
			(xy 123.270503 -267.20322) (xy 123.228832 -267.236451) (xy 123.182674 -267.2631) (xy 123.13306 -267.282572)
			(xy 123.081098 -267.294432) (xy 123.027948 -267.298416) (xy 122.974798 -267.294432) (xy 122.922836 -267.282572)
			(xy 122.873222 -267.2631) (xy 122.827064 -267.236451) (xy 122.785393 -267.20322) (xy 122.749141 -267.164149)
			(xy 122.719117 -267.120112) (xy 122.695991 -267.072091) (xy 122.680281 -267.021161) (xy 122.672338 -266.968457)
			(xy 122.443758 -266.968457) (xy 122.435815 -267.021161) (xy 122.420105 -267.072091) (xy 122.396979 -267.120112)
			(xy 122.366955 -267.164149) (xy 122.330703 -267.20322) (xy 122.289032 -267.236451) (xy 122.242874 -267.2631)
			(xy 122.19326 -267.282572) (xy 122.141298 -267.294432) (xy 122.088148 -267.298416) (xy 122.034998 -267.294432)
			(xy 121.983036 -267.282572) (xy 121.933422 -267.2631) (xy 121.887264 -267.236451) (xy 121.845593 -267.20322)
			(xy 121.809341 -267.164149) (xy 121.779317 -267.120112) (xy 121.756191 -267.072091) (xy 121.740481 -267.021161)
			(xy 121.732538 -266.968457) (xy 118.684023 -266.968457) (xy 118.67615 -267.020853) (xy 118.660548 -267.0716)
			(xy 118.637579 -267.119465) (xy 118.62308 -267.141706) (xy 118.62308 -267.782527) (xy 119.382784 -267.782527)
			(xy 119.382784 -267.729229) (xy 119.390727 -267.676525) (xy 119.406437 -267.625595) (xy 119.429563 -267.577574)
			(xy 119.459587 -267.533537) (xy 119.495839 -267.494466) (xy 119.53751 -267.461235) (xy 119.583668 -267.434586)
			(xy 119.633282 -267.415114) (xy 119.685244 -267.403254) (xy 119.738394 -267.399271) (xy 119.791544 -267.403254)
			(xy 119.843506 -267.415114) (xy 119.89312 -267.434586) (xy 119.939278 -267.461235) (xy 119.980949 -267.494466)
			(xy 120.017201 -267.533537) (xy 120.047225 -267.577574) (xy 120.070351 -267.625595) (xy 120.086061 -267.676525)
			(xy 120.094004 -267.729229) (xy 120.094502 -267.755878) (xy 120.094004 -267.782527) (xy 123.141984 -267.782527)
			(xy 123.141984 -267.729229) (xy 123.149927 -267.676525) (xy 123.165637 -267.625595) (xy 123.188763 -267.577574)
			(xy 123.218787 -267.533537) (xy 123.255039 -267.494466) (xy 123.29671 -267.461235) (xy 123.342868 -267.434586)
			(xy 123.392482 -267.415114) (xy 123.444444 -267.403254) (xy 123.497594 -267.399271) (xy 123.550744 -267.403254)
			(xy 123.602706 -267.415114) (xy 123.65232 -267.434586) (xy 123.698478 -267.461235) (xy 123.740149 -267.494466)
			(xy 123.776401 -267.533537) (xy 123.806425 -267.577574) (xy 123.829551 -267.625595) (xy 123.845261 -267.676525)
			(xy 123.853204 -267.729229) (xy 123.853702 -267.755878) (xy 123.853204 -267.782527) (xy 124.081784 -267.782527)
			(xy 124.081784 -267.729229) (xy 124.089727 -267.676525) (xy 124.105437 -267.625595) (xy 124.128563 -267.577574)
			(xy 124.158587 -267.533537) (xy 124.194839 -267.494466) (xy 124.23651 -267.461235) (xy 124.282668 -267.434586)
			(xy 124.332282 -267.415114) (xy 124.384244 -267.403254) (xy 124.437394 -267.399271) (xy 124.490544 -267.403254)
			(xy 124.542506 -267.415114) (xy 124.59212 -267.434586) (xy 124.638278 -267.461235) (xy 124.679949 -267.494466)
			(xy 124.716201 -267.533537) (xy 124.746225 -267.577574) (xy 124.769351 -267.625595) (xy 124.785061 -267.676525)
			(xy 124.793004 -267.729229) (xy 124.793502 -267.755878) (xy 124.793004 -267.782527) (xy 125.021584 -267.782527)
			(xy 125.021584 -267.729229) (xy 125.029527 -267.676525) (xy 125.045237 -267.625595) (xy 125.068363 -267.577574)
			(xy 125.098387 -267.533537) (xy 125.134639 -267.494466) (xy 125.17631 -267.461235) (xy 125.222468 -267.434586)
			(xy 125.272082 -267.415114) (xy 125.324044 -267.403254) (xy 125.377194 -267.399271) (xy 125.430344 -267.403254)
			(xy 125.482306 -267.415114) (xy 125.53192 -267.434586) (xy 125.578078 -267.461235) (xy 125.619749 -267.494466)
			(xy 125.656001 -267.533537) (xy 125.686025 -267.577574) (xy 125.709151 -267.625595) (xy 125.724861 -267.676525)
			(xy 125.732804 -267.729229) (xy 125.733302 -267.755878) (xy 125.732804 -267.782527) (xy 125.961384 -267.782527)
			(xy 125.961384 -267.729229) (xy 125.969327 -267.676525) (xy 125.985037 -267.625595) (xy 126.008163 -267.577574)
			(xy 126.038187 -267.533537) (xy 126.074439 -267.494466) (xy 126.11611 -267.461235) (xy 126.162268 -267.434586)
			(xy 126.211882 -267.415114) (xy 126.263844 -267.403254) (xy 126.316994 -267.399271) (xy 126.370144 -267.403254)
			(xy 126.422106 -267.415114) (xy 126.47172 -267.434586) (xy 126.517878 -267.461235) (xy 126.559549 -267.494466)
			(xy 126.595801 -267.533537) (xy 126.625825 -267.577574) (xy 126.648951 -267.625595) (xy 126.664661 -267.676525)
			(xy 126.672604 -267.729229) (xy 126.673102 -267.755878) (xy 126.672604 -267.782527) (xy 126.901184 -267.782527)
			(xy 126.901184 -267.729229) (xy 126.909127 -267.676525) (xy 126.924837 -267.625595) (xy 126.947963 -267.577574)
			(xy 126.977987 -267.533537) (xy 127.014239 -267.494466) (xy 127.05591 -267.461235) (xy 127.102068 -267.434586)
			(xy 127.151682 -267.415114) (xy 127.203644 -267.403254) (xy 127.256794 -267.399271) (xy 127.309944 -267.403254)
			(xy 127.361906 -267.415114) (xy 127.41152 -267.434586) (xy 127.457678 -267.461235) (xy 127.499349 -267.494466)
			(xy 127.535601 -267.533537) (xy 127.565625 -267.577574) (xy 127.588751 -267.625595) (xy 127.604461 -267.676525)
			(xy 127.612404 -267.729229) (xy 127.612902 -267.755878) (xy 127.612404 -267.782527) (xy 127.840984 -267.782527)
			(xy 127.840984 -267.729229) (xy 127.848927 -267.676525) (xy 127.864637 -267.625595) (xy 127.887763 -267.577574)
			(xy 127.917787 -267.533537) (xy 127.954039 -267.494466) (xy 127.99571 -267.461235) (xy 128.041868 -267.434586)
			(xy 128.091482 -267.415114) (xy 128.143444 -267.403254) (xy 128.196594 -267.399271) (xy 128.249744 -267.403254)
			(xy 128.301706 -267.415114) (xy 128.35132 -267.434586) (xy 128.397478 -267.461235) (xy 128.439149 -267.494466)
			(xy 128.475401 -267.533537) (xy 128.505425 -267.577574) (xy 128.528551 -267.625595) (xy 128.544261 -267.676525)
			(xy 128.552204 -267.729229) (xy 128.552702 -267.755878) (xy 128.552204 -267.782527) (xy 128.780784 -267.782527)
			(xy 128.780784 -267.729229) (xy 128.788727 -267.676525) (xy 128.804437 -267.625595) (xy 128.827563 -267.577574)
			(xy 128.857587 -267.533537) (xy 128.893839 -267.494466) (xy 128.93551 -267.461235) (xy 128.981668 -267.434586)
			(xy 129.031282 -267.415114) (xy 129.083244 -267.403254) (xy 129.136394 -267.399271) (xy 129.189544 -267.403254)
			(xy 129.241506 -267.415114) (xy 129.29112 -267.434586) (xy 129.337278 -267.461235) (xy 129.378949 -267.494466)
			(xy 129.415201 -267.533537) (xy 129.445225 -267.577574) (xy 129.468351 -267.625595) (xy 129.484061 -267.676525)
			(xy 129.492004 -267.729229) (xy 129.492502 -267.755878) (xy 129.492004 -267.782527) (xy 129.720584 -267.782527)
			(xy 129.720584 -267.729229) (xy 129.728527 -267.676525) (xy 129.744237 -267.625595) (xy 129.767363 -267.577574)
			(xy 129.797387 -267.533537) (xy 129.833639 -267.494466) (xy 129.87531 -267.461235) (xy 129.921468 -267.434586)
			(xy 129.971082 -267.415114) (xy 130.023044 -267.403254) (xy 130.076194 -267.399271) (xy 130.129344 -267.403254)
			(xy 130.181306 -267.415114) (xy 130.23092 -267.434586) (xy 130.277078 -267.461235) (xy 130.318749 -267.494466)
			(xy 130.355001 -267.533537) (xy 130.385025 -267.577574) (xy 130.408151 -267.625595) (xy 130.423861 -267.676525)
			(xy 130.431804 -267.729229) (xy 130.432302 -267.755878) (xy 130.431804 -267.782527) (xy 130.660384 -267.782527)
			(xy 130.660384 -267.729229) (xy 130.668327 -267.676525) (xy 130.684037 -267.625595) (xy 130.707163 -267.577574)
			(xy 130.737187 -267.533537) (xy 130.773439 -267.494466) (xy 130.81511 -267.461235) (xy 130.861268 -267.434586)
			(xy 130.910882 -267.415114) (xy 130.962844 -267.403254) (xy 131.015994 -267.399271) (xy 131.069144 -267.403254)
			(xy 131.121106 -267.415114) (xy 131.17072 -267.434586) (xy 131.216878 -267.461235) (xy 131.258549 -267.494466)
			(xy 131.294801 -267.533537) (xy 131.324825 -267.577574) (xy 131.347951 -267.625595) (xy 131.363661 -267.676525)
			(xy 131.371604 -267.729229) (xy 131.372102 -267.755878) (xy 131.371604 -267.782527) (xy 131.600438 -267.782527)
			(xy 131.600438 -267.729229) (xy 131.608381 -267.676525) (xy 131.624091 -267.625595) (xy 131.647217 -267.577574)
			(xy 131.677241 -267.533537) (xy 131.713493 -267.494466) (xy 131.755164 -267.461235) (xy 131.801322 -267.434586)
			(xy 131.850936 -267.415114) (xy 131.902898 -267.403254) (xy 131.956048 -267.399271) (xy 132.009198 -267.403254)
			(xy 132.06116 -267.415114) (xy 132.110774 -267.434586) (xy 132.156932 -267.461235) (xy 132.198603 -267.494466)
			(xy 132.234855 -267.533537) (xy 132.264879 -267.577574) (xy 132.288005 -267.625595) (xy 132.303715 -267.676525)
			(xy 132.311658 -267.729229) (xy 132.312156 -267.755878) (xy 132.311658 -267.782527) (xy 132.539984 -267.782527)
			(xy 132.539984 -267.729229) (xy 132.547927 -267.676525) (xy 132.563637 -267.625595) (xy 132.586763 -267.577574)
			(xy 132.616787 -267.533537) (xy 132.653039 -267.494466) (xy 132.69471 -267.461235) (xy 132.740868 -267.434586)
			(xy 132.790482 -267.415114) (xy 132.842444 -267.403254) (xy 132.895594 -267.399271) (xy 132.948744 -267.403254)
			(xy 133.000706 -267.415114) (xy 133.05032 -267.434586) (xy 133.096478 -267.461235) (xy 133.138149 -267.494466)
			(xy 133.174401 -267.533537) (xy 133.204425 -267.577574) (xy 133.227551 -267.625595) (xy 133.243261 -267.676525)
			(xy 133.251204 -267.729229) (xy 133.251702 -267.755878) (xy 133.251204 -267.782527) (xy 133.479784 -267.782527)
			(xy 133.479784 -267.729229) (xy 133.487727 -267.676525) (xy 133.503437 -267.625595) (xy 133.526563 -267.577574)
			(xy 133.556587 -267.533537) (xy 133.592839 -267.494466) (xy 133.63451 -267.461235) (xy 133.680668 -267.434586)
			(xy 133.730282 -267.415114) (xy 133.782244 -267.403254) (xy 133.835394 -267.399271) (xy 133.888544 -267.403254)
			(xy 133.940506 -267.415114) (xy 133.99012 -267.434586) (xy 134.036278 -267.461235) (xy 134.077949 -267.494466)
			(xy 134.114201 -267.533537) (xy 134.144225 -267.577574) (xy 134.167351 -267.625595) (xy 134.183061 -267.676525)
			(xy 134.191004 -267.729229) (xy 134.191502 -267.755878) (xy 134.191004 -267.782527) (xy 134.183061 -267.835231)
			(xy 134.167351 -267.886161) (xy 134.144225 -267.934182) (xy 134.114201 -267.978219) (xy 134.077949 -268.01729)
			(xy 134.036278 -268.050521) (xy 133.99012 -268.07717) (xy 133.940506 -268.096642) (xy 133.888544 -268.108502)
			(xy 133.835394 -268.112486) (xy 133.782244 -268.108502) (xy 133.730282 -268.096642) (xy 133.680668 -268.07717)
			(xy 133.63451 -268.050521) (xy 133.592839 -268.01729) (xy 133.556587 -267.978219) (xy 133.526563 -267.934182)
			(xy 133.503437 -267.886161) (xy 133.487727 -267.835231) (xy 133.479784 -267.782527) (xy 133.251204 -267.782527)
			(xy 133.243261 -267.835231) (xy 133.227551 -267.886161) (xy 133.204425 -267.934182) (xy 133.174401 -267.978219)
			(xy 133.138149 -268.01729) (xy 133.096478 -268.050521) (xy 133.05032 -268.07717) (xy 133.000706 -268.096642)
			(xy 132.948744 -268.108502) (xy 132.895594 -268.112486) (xy 132.842444 -268.108502) (xy 132.790482 -268.096642)
			(xy 132.740868 -268.07717) (xy 132.69471 -268.050521) (xy 132.653039 -268.01729) (xy 132.616787 -267.978219)
			(xy 132.586763 -267.934182) (xy 132.563637 -267.886161) (xy 132.547927 -267.835231) (xy 132.539984 -267.782527)
			(xy 132.311658 -267.782527) (xy 132.303715 -267.835231) (xy 132.288005 -267.886161) (xy 132.264879 -267.934182)
			(xy 132.234855 -267.978219) (xy 132.198603 -268.01729) (xy 132.156932 -268.050521) (xy 132.110774 -268.07717)
			(xy 132.06116 -268.096642) (xy 132.009198 -268.108502) (xy 131.956048 -268.112486) (xy 131.902898 -268.108502)
			(xy 131.850936 -268.096642) (xy 131.801322 -268.07717) (xy 131.755164 -268.050521) (xy 131.713493 -268.01729)
			(xy 131.677241 -267.978219) (xy 131.647217 -267.934182) (xy 131.624091 -267.886161) (xy 131.608381 -267.835231)
			(xy 131.600438 -267.782527) (xy 131.371604 -267.782527) (xy 131.363661 -267.835231) (xy 131.347951 -267.886161)
			(xy 131.324825 -267.934182) (xy 131.294801 -267.978219) (xy 131.258549 -268.01729) (xy 131.216878 -268.050521)
			(xy 131.17072 -268.07717) (xy 131.121106 -268.096642) (xy 131.069144 -268.108502) (xy 131.015994 -268.112486)
			(xy 130.962844 -268.108502) (xy 130.910882 -268.096642) (xy 130.861268 -268.07717) (xy 130.81511 -268.050521)
			(xy 130.773439 -268.01729) (xy 130.737187 -267.978219) (xy 130.707163 -267.934182) (xy 130.684037 -267.886161)
			(xy 130.668327 -267.835231) (xy 130.660384 -267.782527) (xy 130.431804 -267.782527) (xy 130.423861 -267.835231)
			(xy 130.408151 -267.886161) (xy 130.385025 -267.934182) (xy 130.355001 -267.978219) (xy 130.318749 -268.01729)
			(xy 130.277078 -268.050521) (xy 130.23092 -268.07717) (xy 130.181306 -268.096642) (xy 130.129344 -268.108502)
			(xy 130.076194 -268.112486) (xy 130.023044 -268.108502) (xy 129.971082 -268.096642) (xy 129.921468 -268.07717)
			(xy 129.87531 -268.050521) (xy 129.833639 -268.01729) (xy 129.797387 -267.978219) (xy 129.767363 -267.934182)
			(xy 129.744237 -267.886161) (xy 129.728527 -267.835231) (xy 129.720584 -267.782527) (xy 129.492004 -267.782527)
			(xy 129.484061 -267.835231) (xy 129.468351 -267.886161) (xy 129.445225 -267.934182) (xy 129.415201 -267.978219)
			(xy 129.378949 -268.01729) (xy 129.337278 -268.050521) (xy 129.29112 -268.07717) (xy 129.241506 -268.096642)
			(xy 129.189544 -268.108502) (xy 129.136394 -268.112486) (xy 129.083244 -268.108502) (xy 129.031282 -268.096642)
			(xy 128.981668 -268.07717) (xy 128.93551 -268.050521) (xy 128.893839 -268.01729) (xy 128.857587 -267.978219)
			(xy 128.827563 -267.934182) (xy 128.804437 -267.886161) (xy 128.788727 -267.835231) (xy 128.780784 -267.782527)
			(xy 128.552204 -267.782527) (xy 128.544261 -267.835231) (xy 128.528551 -267.886161) (xy 128.505425 -267.934182)
			(xy 128.475401 -267.978219) (xy 128.439149 -268.01729) (xy 128.397478 -268.050521) (xy 128.35132 -268.07717)
			(xy 128.301706 -268.096642) (xy 128.249744 -268.108502) (xy 128.196594 -268.112486) (xy 128.143444 -268.108502)
			(xy 128.091482 -268.096642) (xy 128.041868 -268.07717) (xy 127.99571 -268.050521) (xy 127.954039 -268.01729)
			(xy 127.917787 -267.978219) (xy 127.887763 -267.934182) (xy 127.864637 -267.886161) (xy 127.848927 -267.835231)
			(xy 127.840984 -267.782527) (xy 127.612404 -267.782527) (xy 127.604461 -267.835231) (xy 127.588751 -267.886161)
			(xy 127.565625 -267.934182) (xy 127.535601 -267.978219) (xy 127.499349 -268.01729) (xy 127.457678 -268.050521)
			(xy 127.41152 -268.07717) (xy 127.361906 -268.096642) (xy 127.309944 -268.108502) (xy 127.256794 -268.112486)
			(xy 127.203644 -268.108502) (xy 127.151682 -268.096642) (xy 127.102068 -268.07717) (xy 127.05591 -268.050521)
			(xy 127.014239 -268.01729) (xy 126.977987 -267.978219) (xy 126.947963 -267.934182) (xy 126.924837 -267.886161)
			(xy 126.909127 -267.835231) (xy 126.901184 -267.782527) (xy 126.672604 -267.782527) (xy 126.664661 -267.835231)
			(xy 126.648951 -267.886161) (xy 126.625825 -267.934182) (xy 126.595801 -267.978219) (xy 126.559549 -268.01729)
			(xy 126.517878 -268.050521) (xy 126.47172 -268.07717) (xy 126.422106 -268.096642) (xy 126.370144 -268.108502)
			(xy 126.316994 -268.112486) (xy 126.263844 -268.108502) (xy 126.211882 -268.096642) (xy 126.162268 -268.07717)
			(xy 126.11611 -268.050521) (xy 126.074439 -268.01729) (xy 126.038187 -267.978219) (xy 126.008163 -267.934182)
			(xy 125.985037 -267.886161) (xy 125.969327 -267.835231) (xy 125.961384 -267.782527) (xy 125.732804 -267.782527)
			(xy 125.724861 -267.835231) (xy 125.709151 -267.886161) (xy 125.686025 -267.934182) (xy 125.656001 -267.978219)
			(xy 125.619749 -268.01729) (xy 125.578078 -268.050521) (xy 125.53192 -268.07717) (xy 125.482306 -268.096642)
			(xy 125.430344 -268.108502) (xy 125.377194 -268.112486) (xy 125.324044 -268.108502) (xy 125.272082 -268.096642)
			(xy 125.222468 -268.07717) (xy 125.17631 -268.050521) (xy 125.134639 -268.01729) (xy 125.098387 -267.978219)
			(xy 125.068363 -267.934182) (xy 125.045237 -267.886161) (xy 125.029527 -267.835231) (xy 125.021584 -267.782527)
			(xy 124.793004 -267.782527) (xy 124.785061 -267.835231) (xy 124.769351 -267.886161) (xy 124.746225 -267.934182)
			(xy 124.716201 -267.978219) (xy 124.679949 -268.01729) (xy 124.638278 -268.050521) (xy 124.59212 -268.07717)
			(xy 124.542506 -268.096642) (xy 124.490544 -268.108502) (xy 124.437394 -268.112486) (xy 124.384244 -268.108502)
			(xy 124.332282 -268.096642) (xy 124.282668 -268.07717) (xy 124.23651 -268.050521) (xy 124.194839 -268.01729)
			(xy 124.158587 -267.978219) (xy 124.128563 -267.934182) (xy 124.105437 -267.886161) (xy 124.089727 -267.835231)
			(xy 124.081784 -267.782527) (xy 123.853204 -267.782527) (xy 123.845261 -267.835231) (xy 123.829551 -267.886161)
			(xy 123.806425 -267.934182) (xy 123.776401 -267.978219) (xy 123.740149 -268.01729) (xy 123.698478 -268.050521)
			(xy 123.65232 -268.07717) (xy 123.602706 -268.096642) (xy 123.550744 -268.108502) (xy 123.497594 -268.112486)
			(xy 123.444444 -268.108502) (xy 123.392482 -268.096642) (xy 123.342868 -268.07717) (xy 123.29671 -268.050521)
			(xy 123.255039 -268.01729) (xy 123.218787 -267.978219) (xy 123.188763 -267.934182) (xy 123.165637 -267.886161)
			(xy 123.149927 -267.835231) (xy 123.141984 -267.782527) (xy 120.094004 -267.782527) (xy 120.086061 -267.835231)
			(xy 120.070351 -267.886161) (xy 120.047225 -267.934182) (xy 120.017201 -267.978219) (xy 119.980949 -268.01729)
			(xy 119.939278 -268.050521) (xy 119.89312 -268.07717) (xy 119.843506 -268.096642) (xy 119.791544 -268.108502)
			(xy 119.738394 -268.112486) (xy 119.685244 -268.108502) (xy 119.633282 -268.096642) (xy 119.583668 -268.07717)
			(xy 119.53751 -268.050521) (xy 119.495839 -268.01729) (xy 119.459587 -267.978219) (xy 119.429563 -267.934182)
			(xy 119.406437 -267.886161) (xy 119.390727 -267.835231) (xy 119.382784 -267.782527) (xy 118.62308 -267.782527)
			(xy 118.62308 -268.369034) (xy 118.637723 -268.391321) (xy 118.660885 -268.439353) (xy 118.676621 -268.490304)
			(xy 118.684579 -268.543032) (xy 118.684579 -268.596343) (xy 122.672084 -268.596343) (xy 122.672084 -268.543045)
			(xy 122.680027 -268.490341) (xy 122.695737 -268.439411) (xy 122.718863 -268.39139) (xy 122.748887 -268.347353)
			(xy 122.785139 -268.308282) (xy 122.82681 -268.275051) (xy 122.872968 -268.248402) (xy 122.922582 -268.22893)
			(xy 122.974544 -268.21707) (xy 123.027694 -268.213087) (xy 123.080844 -268.21707) (xy 123.132806 -268.22893)
			(xy 123.18242 -268.248402) (xy 123.228578 -268.275051) (xy 123.270249 -268.308282) (xy 123.306501 -268.347353)
			(xy 123.336525 -268.39139) (xy 123.359651 -268.439411) (xy 123.375361 -268.490341) (xy 123.383304 -268.543045)
			(xy 123.383802 -268.569694) (xy 123.383304 -268.596343) (xy 123.612138 -268.596343) (xy 123.612138 -268.543045)
			(xy 123.620081 -268.490341) (xy 123.635791 -268.439411) (xy 123.658917 -268.39139) (xy 123.688941 -268.347353)
			(xy 123.725193 -268.308282) (xy 123.766864 -268.275051) (xy 123.813022 -268.248402) (xy 123.862636 -268.22893)
			(xy 123.914598 -268.21707) (xy 123.967748 -268.213087) (xy 124.020898 -268.21707) (xy 124.07286 -268.22893)
			(xy 124.122474 -268.248402) (xy 124.168632 -268.275051) (xy 124.210303 -268.308282) (xy 124.246555 -268.347353)
			(xy 124.276579 -268.39139) (xy 124.299705 -268.439411) (xy 124.315415 -268.490341) (xy 124.323358 -268.543045)
			(xy 124.323856 -268.569694) (xy 124.323358 -268.596343) (xy 124.551938 -268.596343) (xy 124.551938 -268.543045)
			(xy 124.559881 -268.490341) (xy 124.575591 -268.439411) (xy 124.598717 -268.39139) (xy 124.628741 -268.347353)
			(xy 124.664993 -268.308282) (xy 124.706664 -268.275051) (xy 124.752822 -268.248402) (xy 124.802436 -268.22893)
			(xy 124.854398 -268.21707) (xy 124.907548 -268.213087) (xy 124.960698 -268.21707) (xy 125.01266 -268.22893)
			(xy 125.062274 -268.248402) (xy 125.108432 -268.275051) (xy 125.150103 -268.308282) (xy 125.186355 -268.347353)
			(xy 125.216379 -268.39139) (xy 125.239505 -268.439411) (xy 125.255215 -268.490341) (xy 125.263158 -268.543045)
			(xy 125.263656 -268.569694) (xy 125.263158 -268.596343) (xy 125.491738 -268.596343) (xy 125.491738 -268.543045)
			(xy 125.499681 -268.490341) (xy 125.515391 -268.439411) (xy 125.538517 -268.39139) (xy 125.568541 -268.347353)
			(xy 125.604793 -268.308282) (xy 125.646464 -268.275051) (xy 125.692622 -268.248402) (xy 125.742236 -268.22893)
			(xy 125.794198 -268.21707) (xy 125.847348 -268.213087) (xy 125.900498 -268.21707) (xy 125.95246 -268.22893)
			(xy 126.002074 -268.248402) (xy 126.048232 -268.275051) (xy 126.089903 -268.308282) (xy 126.126155 -268.347353)
			(xy 126.156179 -268.39139) (xy 126.179305 -268.439411) (xy 126.195015 -268.490341) (xy 126.202958 -268.543045)
			(xy 126.203456 -268.569694) (xy 126.202958 -268.596343) (xy 126.431538 -268.596343) (xy 126.431538 -268.543045)
			(xy 126.439481 -268.490341) (xy 126.455191 -268.439411) (xy 126.478317 -268.39139) (xy 126.508341 -268.347353)
			(xy 126.544593 -268.308282) (xy 126.586264 -268.275051) (xy 126.632422 -268.248402) (xy 126.682036 -268.22893)
			(xy 126.733998 -268.21707) (xy 126.787148 -268.213087) (xy 126.840298 -268.21707) (xy 126.89226 -268.22893)
			(xy 126.941874 -268.248402) (xy 126.988032 -268.275051) (xy 127.029703 -268.308282) (xy 127.065955 -268.347353)
			(xy 127.095979 -268.39139) (xy 127.119105 -268.439411) (xy 127.134815 -268.490341) (xy 127.142758 -268.543045)
			(xy 127.143256 -268.569694) (xy 127.142758 -268.596343) (xy 127.371338 -268.596343) (xy 127.371338 -268.543045)
			(xy 127.379281 -268.490341) (xy 127.394991 -268.439411) (xy 127.418117 -268.39139) (xy 127.448141 -268.347353)
			(xy 127.484393 -268.308282) (xy 127.526064 -268.275051) (xy 127.572222 -268.248402) (xy 127.621836 -268.22893)
			(xy 127.673798 -268.21707) (xy 127.726948 -268.213087) (xy 127.780098 -268.21707) (xy 127.83206 -268.22893)
			(xy 127.881674 -268.248402) (xy 127.927832 -268.275051) (xy 127.969503 -268.308282) (xy 128.005755 -268.347353)
			(xy 128.035779 -268.39139) (xy 128.058905 -268.439411) (xy 128.074615 -268.490341) (xy 128.082558 -268.543045)
			(xy 128.083056 -268.569694) (xy 128.082558 -268.596343) (xy 128.311138 -268.596343) (xy 128.311138 -268.543045)
			(xy 128.319081 -268.490341) (xy 128.334791 -268.439411) (xy 128.357917 -268.39139) (xy 128.387941 -268.347353)
			(xy 128.424193 -268.308282) (xy 128.465864 -268.275051) (xy 128.512022 -268.248402) (xy 128.561636 -268.22893)
			(xy 128.613598 -268.21707) (xy 128.666748 -268.213087) (xy 128.719898 -268.21707) (xy 128.77186 -268.22893)
			(xy 128.821474 -268.248402) (xy 128.867632 -268.275051) (xy 128.909303 -268.308282) (xy 128.945555 -268.347353)
			(xy 128.975579 -268.39139) (xy 128.998705 -268.439411) (xy 129.014415 -268.490341) (xy 129.022358 -268.543045)
			(xy 129.022856 -268.569694) (xy 129.022358 -268.596343) (xy 129.250938 -268.596343) (xy 129.250938 -268.543045)
			(xy 129.258881 -268.490341) (xy 129.274591 -268.439411) (xy 129.297717 -268.39139) (xy 129.327741 -268.347353)
			(xy 129.363993 -268.308282) (xy 129.405664 -268.275051) (xy 129.451822 -268.248402) (xy 129.501436 -268.22893)
			(xy 129.553398 -268.21707) (xy 129.606548 -268.213087) (xy 129.659698 -268.21707) (xy 129.71166 -268.22893)
			(xy 129.761274 -268.248402) (xy 129.807432 -268.275051) (xy 129.849103 -268.308282) (xy 129.885355 -268.347353)
			(xy 129.915379 -268.39139) (xy 129.938505 -268.439411) (xy 129.954215 -268.490341) (xy 129.962158 -268.543045)
			(xy 129.962656 -268.569694) (xy 129.962158 -268.596343) (xy 130.190738 -268.596343) (xy 130.190738 -268.543045)
			(xy 130.198681 -268.490341) (xy 130.214391 -268.439411) (xy 130.237517 -268.39139) (xy 130.267541 -268.347353)
			(xy 130.303793 -268.308282) (xy 130.345464 -268.275051) (xy 130.391622 -268.248402) (xy 130.441236 -268.22893)
			(xy 130.493198 -268.21707) (xy 130.546348 -268.213087) (xy 130.599498 -268.21707) (xy 130.65146 -268.22893)
			(xy 130.701074 -268.248402) (xy 130.747232 -268.275051) (xy 130.788903 -268.308282) (xy 130.825155 -268.347353)
			(xy 130.855179 -268.39139) (xy 130.878305 -268.439411) (xy 130.894015 -268.490341) (xy 130.901958 -268.543045)
			(xy 130.902456 -268.569694) (xy 130.901958 -268.596343) (xy 131.130538 -268.596343) (xy 131.130538 -268.543045)
			(xy 131.138481 -268.490341) (xy 131.154191 -268.439411) (xy 131.177317 -268.39139) (xy 131.207341 -268.347353)
			(xy 131.243593 -268.308282) (xy 131.285264 -268.275051) (xy 131.331422 -268.248402) (xy 131.381036 -268.22893)
			(xy 131.432998 -268.21707) (xy 131.486148 -268.213087) (xy 131.539298 -268.21707) (xy 131.59126 -268.22893)
			(xy 131.640874 -268.248402) (xy 131.687032 -268.275051) (xy 131.728703 -268.308282) (xy 131.764955 -268.347353)
			(xy 131.794979 -268.39139) (xy 131.818105 -268.439411) (xy 131.833815 -268.490341) (xy 131.841758 -268.543045)
			(xy 131.842256 -268.569694) (xy 131.841758 -268.596343) (xy 132.070338 -268.596343) (xy 132.070338 -268.543045)
			(xy 132.078281 -268.490341) (xy 132.093991 -268.439411) (xy 132.117117 -268.39139) (xy 132.147141 -268.347353)
			(xy 132.183393 -268.308282) (xy 132.225064 -268.275051) (xy 132.271222 -268.248402) (xy 132.320836 -268.22893)
			(xy 132.372798 -268.21707) (xy 132.425948 -268.213087) (xy 132.479098 -268.21707) (xy 132.53106 -268.22893)
			(xy 132.580674 -268.248402) (xy 132.626832 -268.275051) (xy 132.668503 -268.308282) (xy 132.704755 -268.347353)
			(xy 132.734779 -268.39139) (xy 132.757905 -268.439411) (xy 132.773615 -268.490341) (xy 132.781558 -268.543045)
			(xy 132.782056 -268.569694) (xy 132.781558 -268.596343) (xy 133.010138 -268.596343) (xy 133.010138 -268.543045)
			(xy 133.018081 -268.490341) (xy 133.033791 -268.439411) (xy 133.056917 -268.39139) (xy 133.086941 -268.347353)
			(xy 133.123193 -268.308282) (xy 133.164864 -268.275051) (xy 133.211022 -268.248402) (xy 133.260636 -268.22893)
			(xy 133.312598 -268.21707) (xy 133.365748 -268.213087) (xy 133.418898 -268.21707) (xy 133.47086 -268.22893)
			(xy 133.520474 -268.248402) (xy 133.566632 -268.275051) (xy 133.608303 -268.308282) (xy 133.644555 -268.347353)
			(xy 133.674579 -268.39139) (xy 133.697705 -268.439411) (xy 133.713415 -268.490341) (xy 133.721358 -268.543045)
			(xy 133.721856 -268.569694) (xy 133.721358 -268.596343) (xy 133.949938 -268.596343) (xy 133.949938 -268.543045)
			(xy 133.957881 -268.490341) (xy 133.973591 -268.439411) (xy 133.996717 -268.39139) (xy 134.026741 -268.347353)
			(xy 134.062993 -268.308282) (xy 134.104664 -268.275051) (xy 134.150822 -268.248402) (xy 134.200436 -268.22893)
			(xy 134.252398 -268.21707) (xy 134.305548 -268.213087) (xy 134.358698 -268.21707) (xy 134.41066 -268.22893)
			(xy 134.460274 -268.248402) (xy 134.506432 -268.275051) (xy 134.548103 -268.308282) (xy 134.584355 -268.347353)
			(xy 134.614379 -268.39139) (xy 134.637505 -268.439411) (xy 134.653215 -268.490341) (xy 134.661158 -268.543045)
			(xy 134.661656 -268.569694) (xy 134.661158 -268.596343) (xy 134.653215 -268.649047) (xy 134.637505 -268.699977)
			(xy 134.614379 -268.747998) (xy 134.584355 -268.792035) (xy 134.548103 -268.831106) (xy 134.506432 -268.864337)
			(xy 134.460274 -268.890986) (xy 134.41066 -268.910458) (xy 134.358698 -268.922318) (xy 134.305548 -268.926302)
			(xy 134.252398 -268.922318) (xy 134.200436 -268.910458) (xy 134.150822 -268.890986) (xy 134.104664 -268.864337)
			(xy 134.062993 -268.831106) (xy 134.026741 -268.792035) (xy 133.996717 -268.747998) (xy 133.973591 -268.699977)
			(xy 133.957881 -268.649047) (xy 133.949938 -268.596343) (xy 133.721358 -268.596343) (xy 133.713415 -268.649047)
			(xy 133.697705 -268.699977) (xy 133.674579 -268.747998) (xy 133.644555 -268.792035) (xy 133.608303 -268.831106)
			(xy 133.566632 -268.864337) (xy 133.520474 -268.890986) (xy 133.47086 -268.910458) (xy 133.418898 -268.922318)
			(xy 133.365748 -268.926302) (xy 133.312598 -268.922318) (xy 133.260636 -268.910458) (xy 133.211022 -268.890986)
			(xy 133.164864 -268.864337) (xy 133.123193 -268.831106) (xy 133.086941 -268.792035) (xy 133.056917 -268.747998)
			(xy 133.033791 -268.699977) (xy 133.018081 -268.649047) (xy 133.010138 -268.596343) (xy 132.781558 -268.596343)
			(xy 132.773615 -268.649047) (xy 132.757905 -268.699977) (xy 132.734779 -268.747998) (xy 132.704755 -268.792035)
			(xy 132.668503 -268.831106) (xy 132.626832 -268.864337) (xy 132.580674 -268.890986) (xy 132.53106 -268.910458)
			(xy 132.479098 -268.922318) (xy 132.425948 -268.926302) (xy 132.372798 -268.922318) (xy 132.320836 -268.910458)
			(xy 132.271222 -268.890986) (xy 132.225064 -268.864337) (xy 132.183393 -268.831106) (xy 132.147141 -268.792035)
			(xy 132.117117 -268.747998) (xy 132.093991 -268.699977) (xy 132.078281 -268.649047) (xy 132.070338 -268.596343)
			(xy 131.841758 -268.596343) (xy 131.833815 -268.649047) (xy 131.818105 -268.699977) (xy 131.794979 -268.747998)
			(xy 131.764955 -268.792035) (xy 131.728703 -268.831106) (xy 131.687032 -268.864337) (xy 131.640874 -268.890986)
			(xy 131.59126 -268.910458) (xy 131.539298 -268.922318) (xy 131.486148 -268.926302) (xy 131.432998 -268.922318)
			(xy 131.381036 -268.910458) (xy 131.331422 -268.890986) (xy 131.285264 -268.864337) (xy 131.243593 -268.831106)
			(xy 131.207341 -268.792035) (xy 131.177317 -268.747998) (xy 131.154191 -268.699977) (xy 131.138481 -268.649047)
			(xy 131.130538 -268.596343) (xy 130.901958 -268.596343) (xy 130.894015 -268.649047) (xy 130.878305 -268.699977)
			(xy 130.855179 -268.747998) (xy 130.825155 -268.792035) (xy 130.788903 -268.831106) (xy 130.747232 -268.864337)
			(xy 130.701074 -268.890986) (xy 130.65146 -268.910458) (xy 130.599498 -268.922318) (xy 130.546348 -268.926302)
			(xy 130.493198 -268.922318) (xy 130.441236 -268.910458) (xy 130.391622 -268.890986) (xy 130.345464 -268.864337)
			(xy 130.303793 -268.831106) (xy 130.267541 -268.792035) (xy 130.237517 -268.747998) (xy 130.214391 -268.699977)
			(xy 130.198681 -268.649047) (xy 130.190738 -268.596343) (xy 129.962158 -268.596343) (xy 129.954215 -268.649047)
			(xy 129.938505 -268.699977) (xy 129.915379 -268.747998) (xy 129.885355 -268.792035) (xy 129.849103 -268.831106)
			(xy 129.807432 -268.864337) (xy 129.761274 -268.890986) (xy 129.71166 -268.910458) (xy 129.659698 -268.922318)
			(xy 129.606548 -268.926302) (xy 129.553398 -268.922318) (xy 129.501436 -268.910458) (xy 129.451822 -268.890986)
			(xy 129.405664 -268.864337) (xy 129.363993 -268.831106) (xy 129.327741 -268.792035) (xy 129.297717 -268.747998)
			(xy 129.274591 -268.699977) (xy 129.258881 -268.649047) (xy 129.250938 -268.596343) (xy 129.022358 -268.596343)
			(xy 129.014415 -268.649047) (xy 128.998705 -268.699977) (xy 128.975579 -268.747998) (xy 128.945555 -268.792035)
			(xy 128.909303 -268.831106) (xy 128.867632 -268.864337) (xy 128.821474 -268.890986) (xy 128.77186 -268.910458)
			(xy 128.719898 -268.922318) (xy 128.666748 -268.926302) (xy 128.613598 -268.922318) (xy 128.561636 -268.910458)
			(xy 128.512022 -268.890986) (xy 128.465864 -268.864337) (xy 128.424193 -268.831106) (xy 128.387941 -268.792035)
			(xy 128.357917 -268.747998) (xy 128.334791 -268.699977) (xy 128.319081 -268.649047) (xy 128.311138 -268.596343)
			(xy 128.082558 -268.596343) (xy 128.074615 -268.649047) (xy 128.058905 -268.699977) (xy 128.035779 -268.747998)
			(xy 128.005755 -268.792035) (xy 127.969503 -268.831106) (xy 127.927832 -268.864337) (xy 127.881674 -268.890986)
			(xy 127.83206 -268.910458) (xy 127.780098 -268.922318) (xy 127.726948 -268.926302) (xy 127.673798 -268.922318)
			(xy 127.621836 -268.910458) (xy 127.572222 -268.890986) (xy 127.526064 -268.864337) (xy 127.484393 -268.831106)
			(xy 127.448141 -268.792035) (xy 127.418117 -268.747998) (xy 127.394991 -268.699977) (xy 127.379281 -268.649047)
			(xy 127.371338 -268.596343) (xy 127.142758 -268.596343) (xy 127.134815 -268.649047) (xy 127.119105 -268.699977)
			(xy 127.095979 -268.747998) (xy 127.065955 -268.792035) (xy 127.029703 -268.831106) (xy 126.988032 -268.864337)
			(xy 126.941874 -268.890986) (xy 126.89226 -268.910458) (xy 126.840298 -268.922318) (xy 126.787148 -268.926302)
			(xy 126.733998 -268.922318) (xy 126.682036 -268.910458) (xy 126.632422 -268.890986) (xy 126.586264 -268.864337)
			(xy 126.544593 -268.831106) (xy 126.508341 -268.792035) (xy 126.478317 -268.747998) (xy 126.455191 -268.699977)
			(xy 126.439481 -268.649047) (xy 126.431538 -268.596343) (xy 126.202958 -268.596343) (xy 126.195015 -268.649047)
			(xy 126.179305 -268.699977) (xy 126.156179 -268.747998) (xy 126.126155 -268.792035) (xy 126.089903 -268.831106)
			(xy 126.048232 -268.864337) (xy 126.002074 -268.890986) (xy 125.95246 -268.910458) (xy 125.900498 -268.922318)
			(xy 125.847348 -268.926302) (xy 125.794198 -268.922318) (xy 125.742236 -268.910458) (xy 125.692622 -268.890986)
			(xy 125.646464 -268.864337) (xy 125.604793 -268.831106) (xy 125.568541 -268.792035) (xy 125.538517 -268.747998)
			(xy 125.515391 -268.699977) (xy 125.499681 -268.649047) (xy 125.491738 -268.596343) (xy 125.263158 -268.596343)
			(xy 125.255215 -268.649047) (xy 125.239505 -268.699977) (xy 125.216379 -268.747998) (xy 125.186355 -268.792035)
			(xy 125.150103 -268.831106) (xy 125.108432 -268.864337) (xy 125.062274 -268.890986) (xy 125.01266 -268.910458)
			(xy 124.960698 -268.922318) (xy 124.907548 -268.926302) (xy 124.854398 -268.922318) (xy 124.802436 -268.910458)
			(xy 124.752822 -268.890986) (xy 124.706664 -268.864337) (xy 124.664993 -268.831106) (xy 124.628741 -268.792035)
			(xy 124.598717 -268.747998) (xy 124.575591 -268.699977) (xy 124.559881 -268.649047) (xy 124.551938 -268.596343)
			(xy 124.323358 -268.596343) (xy 124.315415 -268.649047) (xy 124.299705 -268.699977) (xy 124.276579 -268.747998)
			(xy 124.246555 -268.792035) (xy 124.210303 -268.831106) (xy 124.168632 -268.864337) (xy 124.122474 -268.890986)
			(xy 124.07286 -268.910458) (xy 124.020898 -268.922318) (xy 123.967748 -268.926302) (xy 123.914598 -268.922318)
			(xy 123.862636 -268.910458) (xy 123.813022 -268.890986) (xy 123.766864 -268.864337) (xy 123.725193 -268.831106)
			(xy 123.688941 -268.792035) (xy 123.658917 -268.747998) (xy 123.635791 -268.699977) (xy 123.620081 -268.649047)
			(xy 123.612138 -268.596343) (xy 123.383304 -268.596343) (xy 123.375361 -268.649047) (xy 123.359651 -268.699977)
			(xy 123.336525 -268.747998) (xy 123.306501 -268.792035) (xy 123.270249 -268.831106) (xy 123.228578 -268.864337)
			(xy 123.18242 -268.890986) (xy 123.132806 -268.910458) (xy 123.080844 -268.922318) (xy 123.027694 -268.926302)
			(xy 122.974544 -268.922318) (xy 122.922582 -268.910458) (xy 122.872968 -268.890986) (xy 122.82681 -268.864337)
			(xy 122.785139 -268.831106) (xy 122.748887 -268.792035) (xy 122.718863 -268.747998) (xy 122.695737 -268.699977)
			(xy 122.680027 -268.649047) (xy 122.672084 -268.596343) (xy 118.684579 -268.596343) (xy 118.684579 -268.596358)
			(xy 118.676623 -268.649086) (xy 118.660889 -268.700037) (xy 118.637728 -268.74807) (xy 118.62308 -268.770354)
			(xy 118.62308 -269.410159) (xy 120.322584 -269.410159) (xy 120.322584 -269.356861) (xy 120.330527 -269.304157)
			(xy 120.346237 -269.253227) (xy 120.369363 -269.205206) (xy 120.399387 -269.161169) (xy 120.435639 -269.122098)
			(xy 120.47731 -269.088867) (xy 120.523468 -269.062218) (xy 120.573082 -269.042746) (xy 120.625044 -269.030886)
			(xy 120.678194 -269.026903) (xy 120.731344 -269.030886) (xy 120.783306 -269.042746) (xy 120.83292 -269.062218)
			(xy 120.879078 -269.088867) (xy 120.920749 -269.122098) (xy 120.957001 -269.161169) (xy 120.987025 -269.205206)
			(xy 121.010151 -269.253227) (xy 121.025861 -269.304157) (xy 121.033804 -269.356861) (xy 121.034302 -269.38351)
			(xy 121.033804 -269.410159) (xy 122.202184 -269.410159) (xy 122.202184 -269.356861) (xy 122.210127 -269.304157)
			(xy 122.225837 -269.253227) (xy 122.248963 -269.205206) (xy 122.278987 -269.161169) (xy 122.315239 -269.122098)
			(xy 122.35691 -269.088867) (xy 122.403068 -269.062218) (xy 122.452682 -269.042746) (xy 122.504644 -269.030886)
			(xy 122.557794 -269.026903) (xy 122.610944 -269.030886) (xy 122.662906 -269.042746) (xy 122.71252 -269.062218)
			(xy 122.758678 -269.088867) (xy 122.800349 -269.122098) (xy 122.836601 -269.161169) (xy 122.866625 -269.205206)
			(xy 122.889751 -269.253227) (xy 122.905461 -269.304157) (xy 122.913404 -269.356861) (xy 122.913902 -269.38351)
			(xy 122.913404 -269.410159) (xy 123.141984 -269.410159) (xy 123.141984 -269.356861) (xy 123.149927 -269.304157)
			(xy 123.165637 -269.253227) (xy 123.188763 -269.205206) (xy 123.218787 -269.161169) (xy 123.255039 -269.122098)
			(xy 123.29671 -269.088867) (xy 123.342868 -269.062218) (xy 123.392482 -269.042746) (xy 123.444444 -269.030886)
			(xy 123.497594 -269.026903) (xy 123.550744 -269.030886) (xy 123.602706 -269.042746) (xy 123.65232 -269.062218)
			(xy 123.698478 -269.088867) (xy 123.740149 -269.122098) (xy 123.776401 -269.161169) (xy 123.806425 -269.205206)
			(xy 123.829551 -269.253227) (xy 123.845261 -269.304157) (xy 123.853204 -269.356861) (xy 123.853702 -269.38351)
			(xy 123.853204 -269.410159) (xy 124.081784 -269.410159) (xy 124.081784 -269.356861) (xy 124.089727 -269.304157)
			(xy 124.105437 -269.253227) (xy 124.128563 -269.205206) (xy 124.158587 -269.161169) (xy 124.194839 -269.122098)
			(xy 124.23651 -269.088867) (xy 124.282668 -269.062218) (xy 124.332282 -269.042746) (xy 124.384244 -269.030886)
			(xy 124.437394 -269.026903) (xy 124.490544 -269.030886) (xy 124.542506 -269.042746) (xy 124.59212 -269.062218)
			(xy 124.638278 -269.088867) (xy 124.679949 -269.122098) (xy 124.716201 -269.161169) (xy 124.746225 -269.205206)
			(xy 124.769351 -269.253227) (xy 124.785061 -269.304157) (xy 124.793004 -269.356861) (xy 124.793502 -269.38351)
			(xy 124.793004 -269.410159) (xy 125.021584 -269.410159) (xy 125.021584 -269.356861) (xy 125.029527 -269.304157)
			(xy 125.045237 -269.253227) (xy 125.068363 -269.205206) (xy 125.098387 -269.161169) (xy 125.134639 -269.122098)
			(xy 125.17631 -269.088867) (xy 125.222468 -269.062218) (xy 125.272082 -269.042746) (xy 125.324044 -269.030886)
			(xy 125.377194 -269.026903) (xy 125.430344 -269.030886) (xy 125.482306 -269.042746) (xy 125.53192 -269.062218)
			(xy 125.578078 -269.088867) (xy 125.619749 -269.122098) (xy 125.656001 -269.161169) (xy 125.686025 -269.205206)
			(xy 125.709151 -269.253227) (xy 125.724861 -269.304157) (xy 125.732804 -269.356861) (xy 125.733302 -269.38351)
			(xy 125.732804 -269.410159) (xy 125.961384 -269.410159) (xy 125.961384 -269.356861) (xy 125.969327 -269.304157)
			(xy 125.985037 -269.253227) (xy 126.008163 -269.205206) (xy 126.038187 -269.161169) (xy 126.074439 -269.122098)
			(xy 126.11611 -269.088867) (xy 126.162268 -269.062218) (xy 126.211882 -269.042746) (xy 126.263844 -269.030886)
			(xy 126.316994 -269.026903) (xy 126.370144 -269.030886) (xy 126.422106 -269.042746) (xy 126.47172 -269.062218)
			(xy 126.517878 -269.088867) (xy 126.559549 -269.122098) (xy 126.595801 -269.161169) (xy 126.625825 -269.205206)
			(xy 126.648951 -269.253227) (xy 126.664661 -269.304157) (xy 126.672604 -269.356861) (xy 126.673102 -269.38351)
			(xy 126.672604 -269.410159) (xy 126.901184 -269.410159) (xy 126.901184 -269.356861) (xy 126.909127 -269.304157)
			(xy 126.924837 -269.253227) (xy 126.947963 -269.205206) (xy 126.977987 -269.161169) (xy 127.014239 -269.122098)
			(xy 127.05591 -269.088867) (xy 127.102068 -269.062218) (xy 127.151682 -269.042746) (xy 127.203644 -269.030886)
			(xy 127.256794 -269.026903) (xy 127.309944 -269.030886) (xy 127.361906 -269.042746) (xy 127.41152 -269.062218)
			(xy 127.457678 -269.088867) (xy 127.499349 -269.122098) (xy 127.535601 -269.161169) (xy 127.565625 -269.205206)
			(xy 127.588751 -269.253227) (xy 127.604461 -269.304157) (xy 127.612404 -269.356861) (xy 127.612902 -269.38351)
			(xy 127.612404 -269.410159) (xy 127.840984 -269.410159) (xy 127.840984 -269.356861) (xy 127.848927 -269.304157)
			(xy 127.864637 -269.253227) (xy 127.887763 -269.205206) (xy 127.917787 -269.161169) (xy 127.954039 -269.122098)
			(xy 127.99571 -269.088867) (xy 128.041868 -269.062218) (xy 128.091482 -269.042746) (xy 128.143444 -269.030886)
			(xy 128.196594 -269.026903) (xy 128.249744 -269.030886) (xy 128.301706 -269.042746) (xy 128.35132 -269.062218)
			(xy 128.397478 -269.088867) (xy 128.439149 -269.122098) (xy 128.475401 -269.161169) (xy 128.505425 -269.205206)
			(xy 128.528551 -269.253227) (xy 128.544261 -269.304157) (xy 128.552204 -269.356861) (xy 128.552702 -269.38351)
			(xy 128.552204 -269.410159) (xy 128.780784 -269.410159) (xy 128.780784 -269.356861) (xy 128.788727 -269.304157)
			(xy 128.804437 -269.253227) (xy 128.827563 -269.205206) (xy 128.857587 -269.161169) (xy 128.893839 -269.122098)
			(xy 128.93551 -269.088867) (xy 128.981668 -269.062218) (xy 129.031282 -269.042746) (xy 129.083244 -269.030886)
			(xy 129.136394 -269.026903) (xy 129.189544 -269.030886) (xy 129.241506 -269.042746) (xy 129.29112 -269.062218)
			(xy 129.337278 -269.088867) (xy 129.378949 -269.122098) (xy 129.415201 -269.161169) (xy 129.445225 -269.205206)
			(xy 129.468351 -269.253227) (xy 129.484061 -269.304157) (xy 129.492004 -269.356861) (xy 129.492502 -269.38351)
			(xy 129.492004 -269.410159) (xy 129.720584 -269.410159) (xy 129.720584 -269.356861) (xy 129.728527 -269.304157)
			(xy 129.744237 -269.253227) (xy 129.767363 -269.205206) (xy 129.797387 -269.161169) (xy 129.833639 -269.122098)
			(xy 129.87531 -269.088867) (xy 129.921468 -269.062218) (xy 129.971082 -269.042746) (xy 130.023044 -269.030886)
			(xy 130.076194 -269.026903) (xy 130.129344 -269.030886) (xy 130.181306 -269.042746) (xy 130.23092 -269.062218)
			(xy 130.277078 -269.088867) (xy 130.318749 -269.122098) (xy 130.355001 -269.161169) (xy 130.385025 -269.205206)
			(xy 130.408151 -269.253227) (xy 130.423861 -269.304157) (xy 130.431804 -269.356861) (xy 130.432302 -269.38351)
			(xy 130.431804 -269.410159) (xy 130.660384 -269.410159) (xy 130.660384 -269.356861) (xy 130.668327 -269.304157)
			(xy 130.684037 -269.253227) (xy 130.707163 -269.205206) (xy 130.737187 -269.161169) (xy 130.773439 -269.122098)
			(xy 130.81511 -269.088867) (xy 130.861268 -269.062218) (xy 130.910882 -269.042746) (xy 130.962844 -269.030886)
			(xy 131.015994 -269.026903) (xy 131.069144 -269.030886) (xy 131.121106 -269.042746) (xy 131.17072 -269.062218)
			(xy 131.216878 -269.088867) (xy 131.258549 -269.122098) (xy 131.294801 -269.161169) (xy 131.324825 -269.205206)
			(xy 131.347951 -269.253227) (xy 131.363661 -269.304157) (xy 131.371604 -269.356861) (xy 131.372102 -269.38351)
			(xy 131.371604 -269.410159) (xy 131.600184 -269.410159) (xy 131.600184 -269.356861) (xy 131.608127 -269.304157)
			(xy 131.623837 -269.253227) (xy 131.646963 -269.205206) (xy 131.676987 -269.161169) (xy 131.713239 -269.122098)
			(xy 131.75491 -269.088867) (xy 131.801068 -269.062218) (xy 131.850682 -269.042746) (xy 131.902644 -269.030886)
			(xy 131.955794 -269.026903) (xy 132.008944 -269.030886) (xy 132.060906 -269.042746) (xy 132.11052 -269.062218)
			(xy 132.156678 -269.088867) (xy 132.198349 -269.122098) (xy 132.234601 -269.161169) (xy 132.264625 -269.205206)
			(xy 132.287751 -269.253227) (xy 132.303461 -269.304157) (xy 132.311404 -269.356861) (xy 132.311902 -269.38351)
			(xy 132.311404 -269.410159) (xy 132.540238 -269.410159) (xy 132.540238 -269.356861) (xy 132.548181 -269.304157)
			(xy 132.563891 -269.253227) (xy 132.587017 -269.205206) (xy 132.617041 -269.161169) (xy 132.653293 -269.122098)
			(xy 132.694964 -269.088867) (xy 132.741122 -269.062218) (xy 132.790736 -269.042746) (xy 132.842698 -269.030886)
			(xy 132.895848 -269.026903) (xy 132.948998 -269.030886) (xy 133.00096 -269.042746) (xy 133.050574 -269.062218)
			(xy 133.096732 -269.088867) (xy 133.138403 -269.122098) (xy 133.174655 -269.161169) (xy 133.204679 -269.205206)
			(xy 133.227805 -269.253227) (xy 133.243515 -269.304157) (xy 133.251458 -269.356861) (xy 133.251956 -269.38351)
			(xy 133.251458 -269.410159) (xy 133.479784 -269.410159) (xy 133.479784 -269.356861) (xy 133.487727 -269.304157)
			(xy 133.503437 -269.253227) (xy 133.526563 -269.205206) (xy 133.556587 -269.161169) (xy 133.592839 -269.122098)
			(xy 133.63451 -269.088867) (xy 133.680668 -269.062218) (xy 133.730282 -269.042746) (xy 133.782244 -269.030886)
			(xy 133.835394 -269.026903) (xy 133.888544 -269.030886) (xy 133.940506 -269.042746) (xy 133.99012 -269.062218)
			(xy 134.036278 -269.088867) (xy 134.077949 -269.122098) (xy 134.114201 -269.161169) (xy 134.144225 -269.205206)
			(xy 134.167351 -269.253227) (xy 134.183061 -269.304157) (xy 134.191004 -269.356861) (xy 134.191502 -269.38351)
			(xy 134.191004 -269.410159) (xy 134.183061 -269.462863) (xy 134.167351 -269.513793) (xy 134.144225 -269.561814)
			(xy 134.114201 -269.605851) (xy 134.077949 -269.644922) (xy 134.036278 -269.678153) (xy 133.99012 -269.704802)
			(xy 133.940506 -269.724274) (xy 133.888544 -269.736134) (xy 133.835394 -269.740118) (xy 133.782244 -269.736134)
			(xy 133.730282 -269.724274) (xy 133.680668 -269.704802) (xy 133.63451 -269.678153) (xy 133.592839 -269.644922)
			(xy 133.556587 -269.605851) (xy 133.526563 -269.561814) (xy 133.503437 -269.513793) (xy 133.487727 -269.462863)
			(xy 133.479784 -269.410159) (xy 133.251458 -269.410159) (xy 133.243515 -269.462863) (xy 133.227805 -269.513793)
			(xy 133.204679 -269.561814) (xy 133.174655 -269.605851) (xy 133.138403 -269.644922) (xy 133.096732 -269.678153)
			(xy 133.050574 -269.704802) (xy 133.00096 -269.724274) (xy 132.948998 -269.736134) (xy 132.895848 -269.740118)
			(xy 132.842698 -269.736134) (xy 132.790736 -269.724274) (xy 132.741122 -269.704802) (xy 132.694964 -269.678153)
			(xy 132.653293 -269.644922) (xy 132.617041 -269.605851) (xy 132.587017 -269.561814) (xy 132.563891 -269.513793)
			(xy 132.548181 -269.462863) (xy 132.540238 -269.410159) (xy 132.311404 -269.410159) (xy 132.303461 -269.462863)
			(xy 132.287751 -269.513793) (xy 132.264625 -269.561814) (xy 132.234601 -269.605851) (xy 132.198349 -269.644922)
			(xy 132.156678 -269.678153) (xy 132.11052 -269.704802) (xy 132.060906 -269.724274) (xy 132.008944 -269.736134)
			(xy 131.955794 -269.740118) (xy 131.902644 -269.736134) (xy 131.850682 -269.724274) (xy 131.801068 -269.704802)
			(xy 131.75491 -269.678153) (xy 131.713239 -269.644922) (xy 131.676987 -269.605851) (xy 131.646963 -269.561814)
			(xy 131.623837 -269.513793) (xy 131.608127 -269.462863) (xy 131.600184 -269.410159) (xy 131.371604 -269.410159)
			(xy 131.363661 -269.462863) (xy 131.347951 -269.513793) (xy 131.324825 -269.561814) (xy 131.294801 -269.605851)
			(xy 131.258549 -269.644922) (xy 131.216878 -269.678153) (xy 131.17072 -269.704802) (xy 131.121106 -269.724274)
			(xy 131.069144 -269.736134) (xy 131.015994 -269.740118) (xy 130.962844 -269.736134) (xy 130.910882 -269.724274)
			(xy 130.861268 -269.704802) (xy 130.81511 -269.678153) (xy 130.773439 -269.644922) (xy 130.737187 -269.605851)
			(xy 130.707163 -269.561814) (xy 130.684037 -269.513793) (xy 130.668327 -269.462863) (xy 130.660384 -269.410159)
			(xy 130.431804 -269.410159) (xy 130.423861 -269.462863) (xy 130.408151 -269.513793) (xy 130.385025 -269.561814)
			(xy 130.355001 -269.605851) (xy 130.318749 -269.644922) (xy 130.277078 -269.678153) (xy 130.23092 -269.704802)
			(xy 130.181306 -269.724274) (xy 130.129344 -269.736134) (xy 130.076194 -269.740118) (xy 130.023044 -269.736134)
			(xy 129.971082 -269.724274) (xy 129.921468 -269.704802) (xy 129.87531 -269.678153) (xy 129.833639 -269.644922)
			(xy 129.797387 -269.605851) (xy 129.767363 -269.561814) (xy 129.744237 -269.513793) (xy 129.728527 -269.462863)
			(xy 129.720584 -269.410159) (xy 129.492004 -269.410159) (xy 129.484061 -269.462863) (xy 129.468351 -269.513793)
			(xy 129.445225 -269.561814) (xy 129.415201 -269.605851) (xy 129.378949 -269.644922) (xy 129.337278 -269.678153)
			(xy 129.29112 -269.704802) (xy 129.241506 -269.724274) (xy 129.189544 -269.736134) (xy 129.136394 -269.740118)
			(xy 129.083244 -269.736134) (xy 129.031282 -269.724274) (xy 128.981668 -269.704802) (xy 128.93551 -269.678153)
			(xy 128.893839 -269.644922) (xy 128.857587 -269.605851) (xy 128.827563 -269.561814) (xy 128.804437 -269.513793)
			(xy 128.788727 -269.462863) (xy 128.780784 -269.410159) (xy 128.552204 -269.410159) (xy 128.544261 -269.462863)
			(xy 128.528551 -269.513793) (xy 128.505425 -269.561814) (xy 128.475401 -269.605851) (xy 128.439149 -269.644922)
			(xy 128.397478 -269.678153) (xy 128.35132 -269.704802) (xy 128.301706 -269.724274) (xy 128.249744 -269.736134)
			(xy 128.196594 -269.740118) (xy 128.143444 -269.736134) (xy 128.091482 -269.724274) (xy 128.041868 -269.704802)
			(xy 127.99571 -269.678153) (xy 127.954039 -269.644922) (xy 127.917787 -269.605851) (xy 127.887763 -269.561814)
			(xy 127.864637 -269.513793) (xy 127.848927 -269.462863) (xy 127.840984 -269.410159) (xy 127.612404 -269.410159)
			(xy 127.604461 -269.462863) (xy 127.588751 -269.513793) (xy 127.565625 -269.561814) (xy 127.535601 -269.605851)
			(xy 127.499349 -269.644922) (xy 127.457678 -269.678153) (xy 127.41152 -269.704802) (xy 127.361906 -269.724274)
			(xy 127.309944 -269.736134) (xy 127.256794 -269.740118) (xy 127.203644 -269.736134) (xy 127.151682 -269.724274)
			(xy 127.102068 -269.704802) (xy 127.05591 -269.678153) (xy 127.014239 -269.644922) (xy 126.977987 -269.605851)
			(xy 126.947963 -269.561814) (xy 126.924837 -269.513793) (xy 126.909127 -269.462863) (xy 126.901184 -269.410159)
			(xy 126.672604 -269.410159) (xy 126.664661 -269.462863) (xy 126.648951 -269.513793) (xy 126.625825 -269.561814)
			(xy 126.595801 -269.605851) (xy 126.559549 -269.644922) (xy 126.517878 -269.678153) (xy 126.47172 -269.704802)
			(xy 126.422106 -269.724274) (xy 126.370144 -269.736134) (xy 126.316994 -269.740118) (xy 126.263844 -269.736134)
			(xy 126.211882 -269.724274) (xy 126.162268 -269.704802) (xy 126.11611 -269.678153) (xy 126.074439 -269.644922)
			(xy 126.038187 -269.605851) (xy 126.008163 -269.561814) (xy 125.985037 -269.513793) (xy 125.969327 -269.462863)
			(xy 125.961384 -269.410159) (xy 125.732804 -269.410159) (xy 125.724861 -269.462863) (xy 125.709151 -269.513793)
			(xy 125.686025 -269.561814) (xy 125.656001 -269.605851) (xy 125.619749 -269.644922) (xy 125.578078 -269.678153)
			(xy 125.53192 -269.704802) (xy 125.482306 -269.724274) (xy 125.430344 -269.736134) (xy 125.377194 -269.740118)
			(xy 125.324044 -269.736134) (xy 125.272082 -269.724274) (xy 125.222468 -269.704802) (xy 125.17631 -269.678153)
			(xy 125.134639 -269.644922) (xy 125.098387 -269.605851) (xy 125.068363 -269.561814) (xy 125.045237 -269.513793)
			(xy 125.029527 -269.462863) (xy 125.021584 -269.410159) (xy 124.793004 -269.410159) (xy 124.785061 -269.462863)
			(xy 124.769351 -269.513793) (xy 124.746225 -269.561814) (xy 124.716201 -269.605851) (xy 124.679949 -269.644922)
			(xy 124.638278 -269.678153) (xy 124.59212 -269.704802) (xy 124.542506 -269.724274) (xy 124.490544 -269.736134)
			(xy 124.437394 -269.740118) (xy 124.384244 -269.736134) (xy 124.332282 -269.724274) (xy 124.282668 -269.704802)
			(xy 124.23651 -269.678153) (xy 124.194839 -269.644922) (xy 124.158587 -269.605851) (xy 124.128563 -269.561814)
			(xy 124.105437 -269.513793) (xy 124.089727 -269.462863) (xy 124.081784 -269.410159) (xy 123.853204 -269.410159)
			(xy 123.845261 -269.462863) (xy 123.829551 -269.513793) (xy 123.806425 -269.561814) (xy 123.776401 -269.605851)
			(xy 123.740149 -269.644922) (xy 123.698478 -269.678153) (xy 123.65232 -269.704802) (xy 123.602706 -269.724274)
			(xy 123.550744 -269.736134) (xy 123.497594 -269.740118) (xy 123.444444 -269.736134) (xy 123.392482 -269.724274)
			(xy 123.342868 -269.704802) (xy 123.29671 -269.678153) (xy 123.255039 -269.644922) (xy 123.218787 -269.605851)
			(xy 123.188763 -269.561814) (xy 123.165637 -269.513793) (xy 123.149927 -269.462863) (xy 123.141984 -269.410159)
			(xy 122.913404 -269.410159) (xy 122.905461 -269.462863) (xy 122.889751 -269.513793) (xy 122.866625 -269.561814)
			(xy 122.836601 -269.605851) (xy 122.800349 -269.644922) (xy 122.758678 -269.678153) (xy 122.71252 -269.704802)
			(xy 122.662906 -269.724274) (xy 122.610944 -269.736134) (xy 122.557794 -269.740118) (xy 122.504644 -269.736134)
			(xy 122.452682 -269.724274) (xy 122.403068 -269.704802) (xy 122.35691 -269.678153) (xy 122.315239 -269.644922)
			(xy 122.278987 -269.605851) (xy 122.248963 -269.561814) (xy 122.225837 -269.513793) (xy 122.210127 -269.462863)
			(xy 122.202184 -269.410159) (xy 121.033804 -269.410159) (xy 121.025861 -269.462863) (xy 121.010151 -269.513793)
			(xy 120.987025 -269.561814) (xy 120.957001 -269.605851) (xy 120.920749 -269.644922) (xy 120.879078 -269.678153)
			(xy 120.83292 -269.704802) (xy 120.783306 -269.724274) (xy 120.731344 -269.736134) (xy 120.678194 -269.740118)
			(xy 120.625044 -269.736134) (xy 120.573082 -269.724274) (xy 120.523468 -269.704802) (xy 120.47731 -269.678153)
			(xy 120.435639 -269.644922) (xy 120.399387 -269.605851) (xy 120.369363 -269.561814) (xy 120.346237 -269.513793)
			(xy 120.330527 -269.462863) (xy 120.322584 -269.410159) (xy 118.62308 -269.410159) (xy 118.62308 -269.99692)
			(xy 118.637723 -270.019207) (xy 118.660888 -270.067239) (xy 118.676626 -270.118189) (xy 118.684585 -270.170917)
			(xy 118.685056 -270.19758) (xy 118.684802 -270.209264) (xy 118.68428 -270.224229) (xy 122.672338 -270.224229)
			(xy 122.672338 -270.170931) (xy 122.680281 -270.118227) (xy 122.695991 -270.067297) (xy 122.719117 -270.019276)
			(xy 122.749141 -269.975239) (xy 122.785393 -269.936168) (xy 122.827064 -269.902937) (xy 122.873222 -269.876288)
			(xy 122.922836 -269.856816) (xy 122.974798 -269.844956) (xy 123.027948 -269.840973) (xy 123.081098 -269.844956)
			(xy 123.13306 -269.856816) (xy 123.182674 -269.876288) (xy 123.228832 -269.902937) (xy 123.270503 -269.936168)
			(xy 123.306755 -269.975239) (xy 123.336779 -270.019276) (xy 123.359905 -270.067297) (xy 123.375615 -270.118227)
			(xy 123.383558 -270.170931) (xy 123.384056 -270.19758) (xy 123.383558 -270.224229) (xy 123.612138 -270.224229)
			(xy 123.612138 -270.170931) (xy 123.620081 -270.118227) (xy 123.635791 -270.067297) (xy 123.658917 -270.019276)
			(xy 123.688941 -269.975239) (xy 123.725193 -269.936168) (xy 123.766864 -269.902937) (xy 123.813022 -269.876288)
			(xy 123.862636 -269.856816) (xy 123.914598 -269.844956) (xy 123.967748 -269.840973) (xy 124.020898 -269.844956)
			(xy 124.07286 -269.856816) (xy 124.122474 -269.876288) (xy 124.168632 -269.902937) (xy 124.210303 -269.936168)
			(xy 124.246555 -269.975239) (xy 124.276579 -270.019276) (xy 124.299705 -270.067297) (xy 124.315415 -270.118227)
			(xy 124.323358 -270.170931) (xy 124.323856 -270.19758) (xy 124.323358 -270.224229) (xy 124.551938 -270.224229)
			(xy 124.551938 -270.170931) (xy 124.559881 -270.118227) (xy 124.575591 -270.067297) (xy 124.598717 -270.019276)
			(xy 124.628741 -269.975239) (xy 124.664993 -269.936168) (xy 124.706664 -269.902937) (xy 124.752822 -269.876288)
			(xy 124.802436 -269.856816) (xy 124.854398 -269.844956) (xy 124.907548 -269.840973) (xy 124.960698 -269.844956)
			(xy 125.01266 -269.856816) (xy 125.062274 -269.876288) (xy 125.108432 -269.902937) (xy 125.150103 -269.936168)
			(xy 125.186355 -269.975239) (xy 125.216379 -270.019276) (xy 125.239505 -270.067297) (xy 125.255215 -270.118227)
			(xy 125.263158 -270.170931) (xy 125.263656 -270.19758) (xy 125.263158 -270.224229) (xy 125.491738 -270.224229)
			(xy 125.491738 -270.170931) (xy 125.499681 -270.118227) (xy 125.515391 -270.067297) (xy 125.538517 -270.019276)
			(xy 125.568541 -269.975239) (xy 125.604793 -269.936168) (xy 125.646464 -269.902937) (xy 125.692622 -269.876288)
			(xy 125.742236 -269.856816) (xy 125.794198 -269.844956) (xy 125.847348 -269.840973) (xy 125.900498 -269.844956)
			(xy 125.95246 -269.856816) (xy 126.002074 -269.876288) (xy 126.048232 -269.902937) (xy 126.089903 -269.936168)
			(xy 126.126155 -269.975239) (xy 126.156179 -270.019276) (xy 126.179305 -270.067297) (xy 126.195015 -270.118227)
			(xy 126.202958 -270.170931) (xy 126.203456 -270.19758) (xy 126.202958 -270.224229) (xy 126.431538 -270.224229)
			(xy 126.431538 -270.170931) (xy 126.439481 -270.118227) (xy 126.455191 -270.067297) (xy 126.478317 -270.019276)
			(xy 126.508341 -269.975239) (xy 126.544593 -269.936168) (xy 126.586264 -269.902937) (xy 126.632422 -269.876288)
			(xy 126.682036 -269.856816) (xy 126.733998 -269.844956) (xy 126.787148 -269.840973) (xy 126.840298 -269.844956)
			(xy 126.89226 -269.856816) (xy 126.941874 -269.876288) (xy 126.988032 -269.902937) (xy 127.029703 -269.936168)
			(xy 127.065955 -269.975239) (xy 127.095979 -270.019276) (xy 127.119105 -270.067297) (xy 127.134815 -270.118227)
			(xy 127.142758 -270.170931) (xy 127.143256 -270.19758) (xy 127.142758 -270.224229) (xy 127.371338 -270.224229)
			(xy 127.371338 -270.170931) (xy 127.379281 -270.118227) (xy 127.394991 -270.067297) (xy 127.418117 -270.019276)
			(xy 127.448141 -269.975239) (xy 127.484393 -269.936168) (xy 127.526064 -269.902937) (xy 127.572222 -269.876288)
			(xy 127.621836 -269.856816) (xy 127.673798 -269.844956) (xy 127.726948 -269.840973) (xy 127.780098 -269.844956)
			(xy 127.83206 -269.856816) (xy 127.881674 -269.876288) (xy 127.927832 -269.902937) (xy 127.969503 -269.936168)
			(xy 128.005755 -269.975239) (xy 128.035779 -270.019276) (xy 128.058905 -270.067297) (xy 128.074615 -270.118227)
			(xy 128.082558 -270.170931) (xy 128.083056 -270.19758) (xy 128.082558 -270.224229) (xy 128.311138 -270.224229)
			(xy 128.311138 -270.170931) (xy 128.319081 -270.118227) (xy 128.334791 -270.067297) (xy 128.357917 -270.019276)
			(xy 128.387941 -269.975239) (xy 128.424193 -269.936168) (xy 128.465864 -269.902937) (xy 128.512022 -269.876288)
			(xy 128.561636 -269.856816) (xy 128.613598 -269.844956) (xy 128.666748 -269.840973) (xy 128.719898 -269.844956)
			(xy 128.77186 -269.856816) (xy 128.821474 -269.876288) (xy 128.867632 -269.902937) (xy 128.909303 -269.936168)
			(xy 128.945555 -269.975239) (xy 128.975579 -270.019276) (xy 128.998705 -270.067297) (xy 129.014415 -270.118227)
			(xy 129.022358 -270.170931) (xy 129.022856 -270.19758) (xy 129.022358 -270.224229) (xy 129.250938 -270.224229)
			(xy 129.250938 -270.170931) (xy 129.258881 -270.118227) (xy 129.274591 -270.067297) (xy 129.297717 -270.019276)
			(xy 129.327741 -269.975239) (xy 129.363993 -269.936168) (xy 129.405664 -269.902937) (xy 129.451822 -269.876288)
			(xy 129.501436 -269.856816) (xy 129.553398 -269.844956) (xy 129.606548 -269.840973) (xy 129.659698 -269.844956)
			(xy 129.71166 -269.856816) (xy 129.761274 -269.876288) (xy 129.807432 -269.902937) (xy 129.849103 -269.936168)
			(xy 129.885355 -269.975239) (xy 129.915379 -270.019276) (xy 129.938505 -270.067297) (xy 129.954215 -270.118227)
			(xy 129.962158 -270.170931) (xy 129.962656 -270.19758) (xy 129.962158 -270.224229) (xy 130.190738 -270.224229)
			(xy 130.190738 -270.170931) (xy 130.198681 -270.118227) (xy 130.214391 -270.067297) (xy 130.237517 -270.019276)
			(xy 130.267541 -269.975239) (xy 130.303793 -269.936168) (xy 130.345464 -269.902937) (xy 130.391622 -269.876288)
			(xy 130.441236 -269.856816) (xy 130.493198 -269.844956) (xy 130.546348 -269.840973) (xy 130.599498 -269.844956)
			(xy 130.65146 -269.856816) (xy 130.701074 -269.876288) (xy 130.747232 -269.902937) (xy 130.788903 -269.936168)
			(xy 130.825155 -269.975239) (xy 130.855179 -270.019276) (xy 130.878305 -270.067297) (xy 130.894015 -270.118227)
			(xy 130.901958 -270.170931) (xy 130.902456 -270.19758) (xy 130.901958 -270.224229) (xy 131.130538 -270.224229)
			(xy 131.130538 -270.170931) (xy 131.138481 -270.118227) (xy 131.154191 -270.067297) (xy 131.177317 -270.019276)
			(xy 131.207341 -269.975239) (xy 131.243593 -269.936168) (xy 131.285264 -269.902937) (xy 131.331422 -269.876288)
			(xy 131.381036 -269.856816) (xy 131.432998 -269.844956) (xy 131.486148 -269.840973) (xy 131.539298 -269.844956)
			(xy 131.59126 -269.856816) (xy 131.640874 -269.876288) (xy 131.687032 -269.902937) (xy 131.728703 -269.936168)
			(xy 131.764955 -269.975239) (xy 131.794979 -270.019276) (xy 131.818105 -270.067297) (xy 131.833815 -270.118227)
			(xy 131.841758 -270.170931) (xy 131.842256 -270.19758) (xy 131.841758 -270.224229) (xy 132.070338 -270.224229)
			(xy 132.070338 -270.170931) (xy 132.078281 -270.118227) (xy 132.093991 -270.067297) (xy 132.117117 -270.019276)
			(xy 132.147141 -269.975239) (xy 132.183393 -269.936168) (xy 132.225064 -269.902937) (xy 132.271222 -269.876288)
			(xy 132.320836 -269.856816) (xy 132.372798 -269.844956) (xy 132.425948 -269.840973) (xy 132.479098 -269.844956)
			(xy 132.53106 -269.856816) (xy 132.580674 -269.876288) (xy 132.626832 -269.902937) (xy 132.668503 -269.936168)
			(xy 132.704755 -269.975239) (xy 132.734779 -270.019276) (xy 132.757905 -270.067297) (xy 132.773615 -270.118227)
			(xy 132.781558 -270.170931) (xy 132.782056 -270.19758) (xy 132.781558 -270.224229) (xy 133.009884 -270.224229)
			(xy 133.009884 -270.170931) (xy 133.017827 -270.118227) (xy 133.033537 -270.067297) (xy 133.056663 -270.019276)
			(xy 133.086687 -269.975239) (xy 133.122939 -269.936168) (xy 133.16461 -269.902937) (xy 133.210768 -269.876288)
			(xy 133.260382 -269.856816) (xy 133.312344 -269.844956) (xy 133.365494 -269.840973) (xy 133.418644 -269.844956)
			(xy 133.470606 -269.856816) (xy 133.52022 -269.876288) (xy 133.566378 -269.902937) (xy 133.608049 -269.936168)
			(xy 133.644301 -269.975239) (xy 133.674325 -270.019276) (xy 133.697451 -270.067297) (xy 133.713161 -270.118227)
			(xy 133.721104 -270.170931) (xy 133.721602 -270.19758) (xy 133.721104 -270.224229) (xy 133.713161 -270.276933)
			(xy 133.697451 -270.327863) (xy 133.674325 -270.375884) (xy 133.644301 -270.419921) (xy 133.608049 -270.458992)
			(xy 133.566378 -270.492223) (xy 133.52022 -270.518872) (xy 133.470606 -270.538344) (xy 133.418644 -270.550204)
			(xy 133.365494 -270.554188) (xy 133.312344 -270.550204) (xy 133.260382 -270.538344) (xy 133.210768 -270.518872)
			(xy 133.16461 -270.492223) (xy 133.122939 -270.458992) (xy 133.086687 -270.419921) (xy 133.056663 -270.375884)
			(xy 133.033537 -270.327863) (xy 133.017827 -270.276933) (xy 133.009884 -270.224229) (xy 132.781558 -270.224229)
			(xy 132.773615 -270.276933) (xy 132.757905 -270.327863) (xy 132.734779 -270.375884) (xy 132.704755 -270.419921)
			(xy 132.668503 -270.458992) (xy 132.626832 -270.492223) (xy 132.580674 -270.518872) (xy 132.53106 -270.538344)
			(xy 132.479098 -270.550204) (xy 132.425948 -270.554188) (xy 132.372798 -270.550204) (xy 132.320836 -270.538344)
			(xy 132.271222 -270.518872) (xy 132.225064 -270.492223) (xy 132.183393 -270.458992) (xy 132.147141 -270.419921)
			(xy 132.117117 -270.375884) (xy 132.093991 -270.327863) (xy 132.078281 -270.276933) (xy 132.070338 -270.224229)
			(xy 131.841758 -270.224229) (xy 131.833815 -270.276933) (xy 131.818105 -270.327863) (xy 131.794979 -270.375884)
			(xy 131.764955 -270.419921) (xy 131.728703 -270.458992) (xy 131.687032 -270.492223) (xy 131.640874 -270.518872)
			(xy 131.59126 -270.538344) (xy 131.539298 -270.550204) (xy 131.486148 -270.554188) (xy 131.432998 -270.550204)
			(xy 131.381036 -270.538344) (xy 131.331422 -270.518872) (xy 131.285264 -270.492223) (xy 131.243593 -270.458992)
			(xy 131.207341 -270.419921) (xy 131.177317 -270.375884) (xy 131.154191 -270.327863) (xy 131.138481 -270.276933)
			(xy 131.130538 -270.224229) (xy 130.901958 -270.224229) (xy 130.894015 -270.276933) (xy 130.878305 -270.327863)
			(xy 130.855179 -270.375884) (xy 130.825155 -270.419921) (xy 130.788903 -270.458992) (xy 130.747232 -270.492223)
			(xy 130.701074 -270.518872) (xy 130.65146 -270.538344) (xy 130.599498 -270.550204) (xy 130.546348 -270.554188)
			(xy 130.493198 -270.550204) (xy 130.441236 -270.538344) (xy 130.391622 -270.518872) (xy 130.345464 -270.492223)
			(xy 130.303793 -270.458992) (xy 130.267541 -270.419921) (xy 130.237517 -270.375884) (xy 130.214391 -270.327863)
			(xy 130.198681 -270.276933) (xy 130.190738 -270.224229) (xy 129.962158 -270.224229) (xy 129.954215 -270.276933)
			(xy 129.938505 -270.327863) (xy 129.915379 -270.375884) (xy 129.885355 -270.419921) (xy 129.849103 -270.458992)
			(xy 129.807432 -270.492223) (xy 129.761274 -270.518872) (xy 129.71166 -270.538344) (xy 129.659698 -270.550204)
			(xy 129.606548 -270.554188) (xy 129.553398 -270.550204) (xy 129.501436 -270.538344) (xy 129.451822 -270.518872)
			(xy 129.405664 -270.492223) (xy 129.363993 -270.458992) (xy 129.327741 -270.419921) (xy 129.297717 -270.375884)
			(xy 129.274591 -270.327863) (xy 129.258881 -270.276933) (xy 129.250938 -270.224229) (xy 129.022358 -270.224229)
			(xy 129.014415 -270.276933) (xy 128.998705 -270.327863) (xy 128.975579 -270.375884) (xy 128.945555 -270.419921)
			(xy 128.909303 -270.458992) (xy 128.867632 -270.492223) (xy 128.821474 -270.518872) (xy 128.77186 -270.538344)
			(xy 128.719898 -270.550204) (xy 128.666748 -270.554188) (xy 128.613598 -270.550204) (xy 128.561636 -270.538344)
			(xy 128.512022 -270.518872) (xy 128.465864 -270.492223) (xy 128.424193 -270.458992) (xy 128.387941 -270.419921)
			(xy 128.357917 -270.375884) (xy 128.334791 -270.327863) (xy 128.319081 -270.276933) (xy 128.311138 -270.224229)
			(xy 128.082558 -270.224229) (xy 128.074615 -270.276933) (xy 128.058905 -270.327863) (xy 128.035779 -270.375884)
			(xy 128.005755 -270.419921) (xy 127.969503 -270.458992) (xy 127.927832 -270.492223) (xy 127.881674 -270.518872)
			(xy 127.83206 -270.538344) (xy 127.780098 -270.550204) (xy 127.726948 -270.554188) (xy 127.673798 -270.550204)
			(xy 127.621836 -270.538344) (xy 127.572222 -270.518872) (xy 127.526064 -270.492223) (xy 127.484393 -270.458992)
			(xy 127.448141 -270.419921) (xy 127.418117 -270.375884) (xy 127.394991 -270.327863) (xy 127.379281 -270.276933)
			(xy 127.371338 -270.224229) (xy 127.142758 -270.224229) (xy 127.134815 -270.276933) (xy 127.119105 -270.327863)
			(xy 127.095979 -270.375884) (xy 127.065955 -270.419921) (xy 127.029703 -270.458992) (xy 126.988032 -270.492223)
			(xy 126.941874 -270.518872) (xy 126.89226 -270.538344) (xy 126.840298 -270.550204) (xy 126.787148 -270.554188)
			(xy 126.733998 -270.550204) (xy 126.682036 -270.538344) (xy 126.632422 -270.518872) (xy 126.586264 -270.492223)
			(xy 126.544593 -270.458992) (xy 126.508341 -270.419921) (xy 126.478317 -270.375884) (xy 126.455191 -270.327863)
			(xy 126.439481 -270.276933) (xy 126.431538 -270.224229) (xy 126.202958 -270.224229) (xy 126.195015 -270.276933)
			(xy 126.179305 -270.327863) (xy 126.156179 -270.375884) (xy 126.126155 -270.419921) (xy 126.089903 -270.458992)
			(xy 126.048232 -270.492223) (xy 126.002074 -270.518872) (xy 125.95246 -270.538344) (xy 125.900498 -270.550204)
			(xy 125.847348 -270.554188) (xy 125.794198 -270.550204) (xy 125.742236 -270.538344) (xy 125.692622 -270.518872)
			(xy 125.646464 -270.492223) (xy 125.604793 -270.458992) (xy 125.568541 -270.419921) (xy 125.538517 -270.375884)
			(xy 125.515391 -270.327863) (xy 125.499681 -270.276933) (xy 125.491738 -270.224229) (xy 125.263158 -270.224229)
			(xy 125.255215 -270.276933) (xy 125.239505 -270.327863) (xy 125.216379 -270.375884) (xy 125.186355 -270.419921)
			(xy 125.150103 -270.458992) (xy 125.108432 -270.492223) (xy 125.062274 -270.518872) (xy 125.01266 -270.538344)
			(xy 124.960698 -270.550204) (xy 124.907548 -270.554188) (xy 124.854398 -270.550204) (xy 124.802436 -270.538344)
			(xy 124.752822 -270.518872) (xy 124.706664 -270.492223) (xy 124.664993 -270.458992) (xy 124.628741 -270.419921)
			(xy 124.598717 -270.375884) (xy 124.575591 -270.327863) (xy 124.559881 -270.276933) (xy 124.551938 -270.224229)
			(xy 124.323358 -270.224229) (xy 124.315415 -270.276933) (xy 124.299705 -270.327863) (xy 124.276579 -270.375884)
			(xy 124.246555 -270.419921) (xy 124.210303 -270.458992) (xy 124.168632 -270.492223) (xy 124.122474 -270.518872)
			(xy 124.07286 -270.538344) (xy 124.020898 -270.550204) (xy 123.967748 -270.554188) (xy 123.914598 -270.550204)
			(xy 123.862636 -270.538344) (xy 123.813022 -270.518872) (xy 123.766864 -270.492223) (xy 123.725193 -270.458992)
			(xy 123.688941 -270.419921) (xy 123.658917 -270.375884) (xy 123.635791 -270.327863) (xy 123.620081 -270.276933)
			(xy 123.612138 -270.224229) (xy 123.383558 -270.224229) (xy 123.375615 -270.276933) (xy 123.359905 -270.327863)
			(xy 123.336779 -270.375884) (xy 123.306755 -270.419921) (xy 123.270503 -270.458992) (xy 123.228832 -270.492223)
			(xy 123.182674 -270.518872) (xy 123.13306 -270.538344) (xy 123.081098 -270.550204) (xy 123.027948 -270.554188)
			(xy 122.974798 -270.550204) (xy 122.922836 -270.538344) (xy 122.873222 -270.518872) (xy 122.827064 -270.492223)
			(xy 122.785393 -270.458992) (xy 122.749141 -270.419921) (xy 122.719117 -270.375884) (xy 122.695991 -270.327863)
			(xy 122.680281 -270.276933) (xy 122.672338 -270.224229) (xy 118.68428 -270.224229) (xy 118.68404 -270.231108)
			(xy 119.25808 -270.805148) (xy 119.448072 -270.805148) (xy 119.463575 -270.784117) (xy 119.499731 -270.746403)
			(xy 119.54101 -270.714376) (xy 119.586526 -270.688724) (xy 119.635301 -270.669998) (xy 119.686288 -270.658598)
			(xy 119.738394 -270.654771) (xy 119.7905 -270.658598) (xy 119.841487 -270.669998) (xy 119.890262 -270.688724)
			(xy 119.935778 -270.714376) (xy 119.977057 -270.746403) (xy 120.013213 -270.784117) (xy 120.028716 -270.805148)
			(xy 120.387872 -270.805148) (xy 120.403375 -270.784117) (xy 120.439531 -270.746403) (xy 120.48081 -270.714376)
			(xy 120.526326 -270.688724) (xy 120.575101 -270.669998) (xy 120.626088 -270.658598) (xy 120.678194 -270.654771)
			(xy 120.7303 -270.658598) (xy 120.781287 -270.669998) (xy 120.830062 -270.688724) (xy 120.875578 -270.714376)
			(xy 120.916857 -270.746403) (xy 120.953013 -270.784117) (xy 120.968516 -270.805148) (xy 121.327672 -270.805148)
			(xy 121.343175 -270.784117) (xy 121.379331 -270.746403) (xy 121.42061 -270.714376) (xy 121.466126 -270.688724)
			(xy 121.514901 -270.669998) (xy 121.565888 -270.658598) (xy 121.617994 -270.654771) (xy 121.6701 -270.658598)
			(xy 121.721087 -270.669998) (xy 121.769862 -270.688724) (xy 121.815378 -270.714376) (xy 121.856657 -270.746403)
			(xy 121.892813 -270.784117) (xy 121.908316 -270.805148) (xy 122.267726 -270.805148) (xy 122.283229 -270.784117)
			(xy 122.319385 -270.746403) (xy 122.360664 -270.714376) (xy 122.40618 -270.688724) (xy 122.454955 -270.669998)
			(xy 122.505942 -270.658598) (xy 122.558048 -270.654771) (xy 122.610154 -270.658598) (xy 122.661141 -270.669998)
			(xy 122.709916 -270.688724) (xy 122.755432 -270.714376) (xy 122.796711 -270.746403) (xy 122.832867 -270.784117)
			(xy 122.84837 -270.805148) (xy 123.207272 -270.805148) (xy 123.222775 -270.784117) (xy 123.258931 -270.746403)
			(xy 123.30021 -270.714376) (xy 123.345726 -270.688724) (xy 123.394501 -270.669998) (xy 123.445488 -270.658598)
			(xy 123.497594 -270.654771) (xy 123.5497 -270.658598) (xy 123.600687 -270.669998) (xy 123.649462 -270.688724)
			(xy 123.694978 -270.714376) (xy 123.736257 -270.746403) (xy 123.772413 -270.784117) (xy 123.787916 -270.805148)
			(xy 124.147072 -270.805148) (xy 124.162575 -270.784117) (xy 124.198731 -270.746403) (xy 124.24001 -270.714376)
			(xy 124.285526 -270.688724) (xy 124.334301 -270.669998) (xy 124.385288 -270.658598) (xy 124.437394 -270.654771)
			(xy 124.4895 -270.658598) (xy 124.540487 -270.669998) (xy 124.589262 -270.688724) (xy 124.634778 -270.714376)
			(xy 124.676057 -270.746403) (xy 124.712213 -270.784117) (xy 124.727716 -270.805148) (xy 125.086872 -270.805148)
			(xy 125.102375 -270.784117) (xy 125.138531 -270.746403) (xy 125.17981 -270.714376) (xy 125.225326 -270.688724)
			(xy 125.274101 -270.669998) (xy 125.325088 -270.658598) (xy 125.377194 -270.654771) (xy 125.4293 -270.658598)
			(xy 125.480287 -270.669998) (xy 125.529062 -270.688724) (xy 125.574578 -270.714376) (xy 125.615857 -270.746403)
			(xy 125.652013 -270.784117) (xy 125.667516 -270.805148) (xy 126.026672 -270.805148) (xy 126.042175 -270.784117)
			(xy 126.078331 -270.746403) (xy 126.11961 -270.714376) (xy 126.165126 -270.688724) (xy 126.213901 -270.669998)
			(xy 126.264888 -270.658598) (xy 126.316994 -270.654771) (xy 126.3691 -270.658598) (xy 126.420087 -270.669998)
			(xy 126.468862 -270.688724) (xy 126.514378 -270.714376) (xy 126.555657 -270.746403) (xy 126.591813 -270.784117)
			(xy 126.607316 -270.805148) (xy 126.966472 -270.805148) (xy 126.981975 -270.784117) (xy 127.018131 -270.746403)
			(xy 127.05941 -270.714376) (xy 127.104926 -270.688724) (xy 127.153701 -270.669998) (xy 127.204688 -270.658598)
			(xy 127.256794 -270.654771) (xy 127.3089 -270.658598) (xy 127.359887 -270.669998) (xy 127.408662 -270.688724)
			(xy 127.454178 -270.714376) (xy 127.495457 -270.746403) (xy 127.531613 -270.784117) (xy 127.547116 -270.805148)
			(xy 127.906272 -270.805148) (xy 127.921775 -270.784117) (xy 127.957931 -270.746403) (xy 127.99921 -270.714376)
			(xy 128.044726 -270.688724) (xy 128.093501 -270.669998) (xy 128.144488 -270.658598) (xy 128.196594 -270.654771)
			(xy 128.2487 -270.658598) (xy 128.299687 -270.669998) (xy 128.348462 -270.688724) (xy 128.393978 -270.714376)
			(xy 128.435257 -270.746403) (xy 128.471413 -270.784117) (xy 128.486916 -270.805148) (xy 128.846072 -270.805148)
			(xy 128.861575 -270.784117) (xy 128.897731 -270.746403) (xy 128.93901 -270.714376) (xy 128.984526 -270.688724)
			(xy 129.033301 -270.669998) (xy 129.084288 -270.658598) (xy 129.136394 -270.654771) (xy 129.1885 -270.658598)
			(xy 129.239487 -270.669998) (xy 129.288262 -270.688724) (xy 129.333778 -270.714376) (xy 129.375057 -270.746403)
			(xy 129.411213 -270.784117) (xy 129.426716 -270.805148) (xy 129.785872 -270.805148) (xy 129.801375 -270.784117)
			(xy 129.837531 -270.746403) (xy 129.87881 -270.714376) (xy 129.924326 -270.688724) (xy 129.973101 -270.669998)
			(xy 130.024088 -270.658598) (xy 130.076194 -270.654771) (xy 130.1283 -270.658598) (xy 130.179287 -270.669998)
			(xy 130.228062 -270.688724) (xy 130.273578 -270.714376) (xy 130.314857 -270.746403) (xy 130.351013 -270.784117)
			(xy 130.366516 -270.805148) (xy 130.725672 -270.805148) (xy 130.741175 -270.784117) (xy 130.777331 -270.746403)
			(xy 130.81861 -270.714376) (xy 130.864126 -270.688724) (xy 130.912901 -270.669998) (xy 130.963888 -270.658598)
			(xy 131.015994 -270.654771) (xy 131.0681 -270.658598) (xy 131.119087 -270.669998) (xy 131.167862 -270.688724)
			(xy 131.213378 -270.714376) (xy 131.254657 -270.746403) (xy 131.290813 -270.784117) (xy 131.306316 -270.805148)
			(xy 131.665472 -270.805148) (xy 131.680975 -270.784117) (xy 131.717131 -270.746403) (xy 131.75841 -270.714376)
			(xy 131.803926 -270.688724) (xy 131.852701 -270.669998) (xy 131.903688 -270.658598) (xy 131.955794 -270.654771)
			(xy 132.0079 -270.658598) (xy 132.058887 -270.669998) (xy 132.107662 -270.688724) (xy 132.153178 -270.714376)
			(xy 132.194457 -270.746403) (xy 132.230613 -270.784117) (xy 132.246116 -270.805148) (xy 132.605272 -270.805148)
			(xy 132.620775 -270.784117) (xy 132.656931 -270.746403) (xy 132.69821 -270.714376) (xy 132.743726 -270.688724)
			(xy 132.792501 -270.669998) (xy 132.843488 -270.658598) (xy 132.895594 -270.654771) (xy 132.9477 -270.658598)
			(xy 132.998687 -270.669998) (xy 133.047462 -270.688724) (xy 133.092978 -270.714376) (xy 133.134257 -270.746403)
			(xy 133.170413 -270.784117) (xy 133.185916 -270.805148) (xy 133.43128 -270.805148) (xy 133.957822 -270.278606)
			(xy 133.953758 -270.252952) (xy 133.951734 -270.239262) (xy 133.949569 -270.211672) (xy 133.94944 -270.197834)
			(xy 133.94944 -270.19758) (xy 133.949962 -270.169597) (xy 133.958721 -270.114321) (xy 133.976019 -270.061095)
			(xy 134.001431 -270.011231) (xy 134.034331 -269.965957) (xy 134.073908 -269.926387) (xy 134.119189 -269.893495)
			(xy 134.169058 -269.868093) (xy 134.222287 -269.850805) (xy 134.277565 -269.842057) (xy 134.305548 -269.841472)
			(xy 134.305802 -269.841472) (xy 134.319639 -269.841616) (xy 134.34723 -269.843775) (xy 134.36092 -269.84579)
			(xy 134.386574 -269.849854) (xy 134.562342 -269.674086) (xy 134.52602 -269.637764) (xy 134.506147 -269.61755)
			(xy 134.472431 -269.571984) (xy 134.446367 -269.521649) (xy 134.428615 -269.467817) (xy 134.419624 -269.411852)
			(xy 134.419086 -269.38351) (xy 134.419605 -269.355524) (xy 134.42836 -269.300241) (xy 134.445655 -269.247008)
			(xy 134.471064 -269.197136) (xy 134.503963 -269.151852) (xy 134.54354 -269.112273) (xy 134.588822 -269.079373)
			(xy 134.638693 -269.053961) (xy 134.691925 -269.036664) (xy 134.747208 -269.027907) (xy 134.775194 -269.027402)
			(xy 134.803532 -269.027972) (xy 134.859488 -269.036986) (xy 134.913313 -269.054739) (xy 134.96365 -269.080786)
			(xy 135.009233 -269.114469) (xy 135.029448 -269.134336) (xy 135.06577 -269.170658) (xy 135.18388 -269.052548)
			(xy 135.18388 -268.9225) (xy 135.14705 -268.912086) (xy 135.121184 -268.904117) (xy 135.072036 -268.881452)
			(xy 135.026881 -268.851615) (xy 134.986759 -268.815292) (xy 134.952592 -268.773318) (xy 134.925166 -268.726659)
			(xy 134.905113 -268.676389) (xy 134.892894 -268.623665) (xy 134.888789 -268.569698) (xy 134.892894 -268.515732)
			(xy 134.905114 -268.463008) (xy 134.925168 -268.412738) (xy 134.952594 -268.366079) (xy 134.986761 -268.324106)
			(xy 135.026884 -268.287783) (xy 135.072039 -268.257946) (xy 135.121187 -268.235282) (xy 135.14705 -268.227302)
			(xy 135.18388 -268.216888) (xy 135.18388 -268.095222) (xy 135.183409 -268.080542) (xy 135.175085 -268.052388)
			(xy 135.15909 -268.027769) (xy 135.136748 -268.008722) (xy 135.109908 -267.996824) (xy 135.080791 -267.99306)
			(xy 135.051808 -267.99774) (xy 135.025356 -268.010478) (xy 135.014208 -268.020038) (xy 134.994471 -268.037247)
			(xy 134.950897 -268.066287) (xy 134.903542 -268.088638) (xy 134.853427 -268.10382) (xy 134.80163 -268.111504)
			(xy 134.775448 -268.111986) (xy 134.775194 -268.111986) (xy 134.748547 -268.111487) (xy 134.695847 -268.103544)
			(xy 134.644921 -268.087834) (xy 134.596904 -268.06471) (xy 134.55287 -268.034687) (xy 134.513803 -267.998437)
			(xy 134.480574 -267.95677) (xy 134.453927 -267.910615) (xy 134.434457 -267.861004) (xy 134.422598 -267.809046)
			(xy 134.418615 -267.7559) (xy 134.422598 -267.702754) (xy 134.434457 -267.650796) (xy 134.453927 -267.601185)
			(xy 134.480574 -267.55503) (xy 134.513803 -267.513363) (xy 134.55287 -267.477113) (xy 134.596904 -267.44709)
			(xy 134.644921 -267.423966) (xy 134.695847 -267.408256) (xy 134.748547 -267.400313) (xy 134.775194 -267.39977)
			(xy 134.775448 -267.39977) (xy 134.801632 -267.400231) (xy 134.853436 -267.407899) (xy 134.903557 -267.423077)
			(xy 134.950912 -267.445437) (xy 134.994478 -267.474497) (xy 135.014208 -267.491718) (xy 135.025404 -267.501188)
			(xy 135.051837 -267.513858) (xy 135.08078 -267.518497) (xy 135.109848 -267.514722) (xy 135.136646 -267.502844)
			(xy 135.158966 -267.483843) (xy 135.174967 -267.459283) (xy 135.183332 -267.431189) (xy 135.18388 -267.416534)
			(xy 135.18388 -267.294868) (xy 135.14705 -267.284454) (xy 135.121186 -267.276485) (xy 135.072043 -267.253821)
			(xy 135.026893 -267.223985) (xy 134.986775 -267.187664) (xy 134.952612 -267.145693) (xy 134.92519 -267.099038)
			(xy 134.90514 -267.048772) (xy 134.892923 -266.996051) (xy 134.88882 -266.942089) (xy 134.892926 -266.888128)
			(xy 134.905146 -266.835408) (xy 134.925199 -266.785143) (xy 134.952624 -266.73849) (xy 134.98679 -266.696521)
			(xy 135.02691 -266.660202) (xy 135.072062 -266.630369) (xy 135.121206 -266.607708) (xy 135.14705 -266.59967)
			(xy 135.18388 -266.589256) (xy 135.18388 -266.46759) (xy 135.183405 -266.452913) (xy 135.175076 -266.424768)
			(xy 135.15908 -266.400157) (xy 135.13674 -266.381117) (xy 135.109906 -266.369224) (xy 135.080796 -266.36546)
			(xy 135.051819 -266.370137) (xy 135.025371 -266.382868) (xy 135.014208 -266.392406) (xy 134.994471 -266.409616)
			(xy 134.950898 -266.438659) (xy 134.903544 -266.461012) (xy 134.853428 -266.476195) (xy 134.80163 -266.48388)
			(xy 134.775448 -266.484354) (xy 134.775194 -266.484354) (xy 134.748542 -266.483856) (xy 134.695832 -266.47591)
			(xy 134.644896 -266.460198) (xy 134.59687 -266.437069) (xy 134.552827 -266.407041) (xy 134.513753 -266.370784)
			(xy 134.480518 -266.329108) (xy 134.453866 -266.282945) (xy 134.434391 -266.233324) (xy 134.42253 -266.181356)
			(xy 134.418546 -266.1282) (xy 134.42253 -266.075044) (xy 134.434391 -266.023076) (xy 134.453866 -265.973455)
			(xy 134.480518 -265.927292) (xy 134.513753 -265.885616) (xy 134.552827 -265.849359) (xy 134.59687 -265.819331)
			(xy 134.644896 -265.796202) (xy 134.695832 -265.78049) (xy 134.748542 -265.772544) (xy 134.775194 -265.772138)
			(xy 134.775448 -265.772138) (xy 134.801633 -265.772598) (xy 134.853437 -265.780266) (xy 134.903559 -265.795443)
			(xy 134.950915 -265.817802) (xy 134.994483 -265.84686) (xy 135.014208 -265.864086) (xy 135.025408 -265.873551)
			(xy 135.051845 -265.886214) (xy 135.080789 -265.890848) (xy 135.109858 -265.887072) (xy 135.136657 -265.875197)
			(xy 135.158982 -265.8562) (xy 135.174993 -265.831647) (xy 135.183373 -265.803557) (xy 135.18388 -265.788902)
			(xy 135.18388 -265.666982) (xy 135.14705 -265.656568) (xy 135.121185 -265.648599) (xy 135.07204 -265.625935)
			(xy 135.026888 -265.596098) (xy 134.986768 -265.559776) (xy 134.952603 -265.517804) (xy 134.92518 -265.471147)
			(xy 134.905128 -265.420879) (xy 134.89291 -265.368157) (xy 134.888807 -265.314193) (xy 134.892912 -265.26023)
			(xy 134.905132 -265.207508) (xy 134.925185 -265.157241) (xy 134.952611 -265.110585) (xy 134.986777 -265.068614)
			(xy 135.026899 -265.032293) (xy 135.072052 -265.002459) (xy 135.121198 -264.979796) (xy 135.14705 -264.971784)
			(xy 135.18388 -264.96137) (xy 135.18388 -264.839704) (xy 135.183407 -264.825026) (xy 135.17508 -264.796877)
			(xy 135.159084 -264.772262) (xy 135.136744 -264.753219) (xy 135.109907 -264.741324) (xy 135.080794 -264.73756)
			(xy 135.051814 -264.742238) (xy 135.025365 -264.754973) (xy 135.014208 -264.76452) (xy 134.994471 -264.78173)
			(xy 134.950898 -264.810771) (xy 134.903543 -264.833124) (xy 134.853428 -264.848306) (xy 134.80163 -264.85599)
			(xy 134.775448 -264.856468) (xy 134.775194 -264.856468) (xy 134.748548 -264.85597) (xy 134.695851 -264.848026)
			(xy 134.644927 -264.832317) (xy 134.596913 -264.809194) (xy 134.552881 -264.779173) (xy 134.513816 -264.742925)
			(xy 134.480589 -264.701259) (xy 134.453943 -264.655107) (xy 134.434474 -264.605499) (xy 134.422615 -264.553543)
			(xy 134.418633 -264.5004) (xy 134.422615 -264.447257) (xy 134.434474 -264.395301) (xy 134.453943 -264.345693)
			(xy 134.480589 -264.299541) (xy 134.513816 -264.257875) (xy 134.552881 -264.221627) (xy 134.596913 -264.191606)
			(xy 134.644927 -264.168483) (xy 134.695851 -264.152774) (xy 134.748548 -264.14483) (xy 134.775194 -264.144252)
			(xy 134.775448 -264.144252) (xy 134.801632 -264.144712) (xy 134.853437 -264.15238) (xy 134.903558 -264.167558)
			(xy 134.950914 -264.189917) (xy 134.994481 -264.218976) (xy 135.014208 -264.2362) (xy 135.025409 -264.245665)
			(xy 135.051847 -264.258326) (xy 135.080791 -264.262959) (xy 135.10986 -264.259182) (xy 135.13666 -264.247308)
			(xy 135.158986 -264.228313) (xy 135.174999 -264.20376) (xy 135.183382 -264.175671) (xy 135.18388 -264.161016)
			(xy 135.18388 -264.03935) (xy 135.14705 -264.028936) (xy 135.121153 -264.020995) (xy 135.071938 -263.998373)
			(xy 135.026716 -263.968561) (xy 134.986529 -263.932245) (xy 134.952303 -263.890264) (xy 134.924828 -263.843584)
			(xy 134.904737 -263.793284) (xy 134.892493 -263.740521) (xy 134.888379 -263.686512) (xy 134.89249 -263.632503)
			(xy 134.90473 -263.57974) (xy 134.924817 -263.529437) (xy 134.952289 -263.482756) (xy 134.986512 -263.440772)
			(xy 135.026697 -263.404454) (xy 135.071917 -263.374639) (xy 135.12113 -263.352013) (xy 135.14705 -263.344152)
			(xy 135.18388 -263.333738) (xy 135.18388 -263.211818) (xy 135.183409 -263.197138) (xy 135.175084 -263.168985)
			(xy 135.159089 -263.144367) (xy 135.136747 -263.125321) (xy 135.109907 -263.113424) (xy 135.080792 -263.10966)
			(xy 135.051809 -263.11434) (xy 135.025358 -263.127077) (xy 135.014208 -263.136634) (xy 134.994471 -263.153843)
			(xy 134.950897 -263.182884) (xy 134.903543 -263.205235) (xy 134.853427 -263.220417) (xy 134.80163 -263.228101)
			(xy 134.775448 -263.228582) (xy 134.775194 -263.228582) (xy 134.748547 -263.228083) (xy 134.695848 -263.22014)
			(xy 134.644922 -263.20443) (xy 134.596906 -263.181306) (xy 134.552873 -263.151284) (xy 134.513806 -263.115035)
			(xy 134.480578 -263.073367) (xy 134.453931 -263.027213) (xy 134.434461 -262.977603) (xy 134.422602 -262.925645)
			(xy 134.418619 -262.8725) (xy 134.422602 -262.819355) (xy 134.434461 -262.767397) (xy 134.453931 -262.717787)
			(xy 134.480578 -262.671633) (xy 134.513806 -262.629965) (xy 134.552873 -262.593716) (xy 134.596906 -262.563694)
			(xy 134.644922 -262.54057) (xy 134.695848 -262.52486) (xy 134.748547 -262.516917) (xy 134.775194 -262.516366)
			(xy 134.775448 -262.516366) (xy 134.801632 -262.516827) (xy 134.853437 -262.524495) (xy 134.903557 -262.539673)
			(xy 134.950912 -262.562033) (xy 134.994479 -262.591092) (xy 135.014208 -262.608314) (xy 135.025404 -262.617784)
			(xy 135.051836 -262.630455) (xy 135.080779 -262.635094) (xy 135.109848 -262.631319) (xy 135.136646 -262.619441)
			(xy 135.158965 -262.600439) (xy 135.174965 -262.575879) (xy 135.183329 -262.547785) (xy 135.18388 -262.53313)
			(xy 135.18388 -262.411464) (xy 135.14705 -262.40105) (xy 135.121159 -262.393109) (xy 135.071958 -262.370489)
			(xy 135.026748 -262.340681) (xy 134.986572 -262.304371) (xy 134.952357 -262.262397) (xy 134.924892 -262.215727)
			(xy 134.904809 -262.165436) (xy 134.892571 -262.112685) (xy 134.888462 -262.058688) (xy 134.892575 -262.004692)
			(xy 134.904816 -261.951942) (xy 134.924902 -261.901652) (xy 134.952371 -261.854984) (xy 134.986588 -261.813012)
			(xy 135.026766 -261.776705) (xy 135.071978 -261.746899) (xy 135.121181 -261.724283) (xy 135.14705 -261.716266)
			(xy 135.18388 -261.705852) (xy 135.18388 -261.584186) (xy 135.183405 -261.56951) (xy 135.175075 -261.541365)
			(xy 135.159078 -261.516756) (xy 135.136739 -261.497717) (xy 135.109906 -261.485824) (xy 135.080796 -261.48206)
			(xy 135.05182 -261.486736) (xy 135.025373 -261.499467) (xy 135.014208 -261.509002) (xy 134.994471 -261.526213)
			(xy 134.950898 -261.555256) (xy 134.903544 -261.577609) (xy 134.853428 -261.592792) (xy 134.80163 -261.600477)
			(xy 134.775448 -261.60095) (xy 134.775194 -261.60095) (xy 134.748542 -261.600452) (xy 134.695833 -261.592506)
			(xy 134.644897 -261.576794) (xy 134.596872 -261.553666) (xy 134.55283 -261.523638) (xy 134.513755 -261.487381)
			(xy 134.480521 -261.445706) (xy 134.453869 -261.399543) (xy 134.434395 -261.349923) (xy 134.422534 -261.297955)
			(xy 134.41855 -261.2448) (xy 134.422534 -261.191645) (xy 134.434395 -261.139677) (xy 134.453869 -261.090057)
			(xy 134.480521 -261.043894) (xy 134.513755 -261.002219) (xy 134.55283 -260.965962) (xy 134.596872 -260.935934)
			(xy 134.644897 -260.912806) (xy 134.695833 -260.897094) (xy 134.748542 -260.889148) (xy 134.775194 -260.888734)
			(xy 134.775448 -260.888734) (xy 134.801633 -260.889194) (xy 134.853437 -260.896862) (xy 134.903559 -260.912039)
			(xy 134.950915 -260.934398) (xy 134.994483 -260.963455) (xy 135.014208 -260.980682) (xy 135.025408 -260.990148)
			(xy 135.051845 -261.00281) (xy 135.080789 -261.007445) (xy 135.109857 -261.003669) (xy 135.136657 -260.991794)
			(xy 135.158981 -260.972797) (xy 135.174991 -260.948243) (xy 135.18337 -260.920153) (xy 135.18388 -260.905498)
			(xy 135.18388 -260.783578) (xy 135.14705 -260.773164) (xy 135.121158 -260.765223) (xy 135.071955 -260.742603)
			(xy 135.026743 -260.712794) (xy 134.986565 -260.676483) (xy 134.952348 -260.634508) (xy 134.924881 -260.587836)
			(xy 134.904797 -260.537544) (xy 134.892559 -260.48479) (xy 134.888448 -260.430792) (xy 134.892561 -260.376794)
			(xy 134.904802 -260.324041) (xy 134.924888 -260.27375) (xy 134.952357 -260.227079) (xy 134.986576 -260.185106)
			(xy 135.026755 -260.148797) (xy 135.071968 -260.11899) (xy 135.121173 -260.096371) (xy 135.14705 -260.08838)
			(xy 135.18388 -260.077966) (xy 135.18388 -259.9563) (xy 135.183407 -259.941622) (xy 135.175079 -259.913474)
			(xy 135.159083 -259.888861) (xy 135.136743 -259.869819) (xy 135.109906 -259.857924) (xy 135.080794 -259.85416)
			(xy 135.051815 -259.858838) (xy 135.025366 -259.871571) (xy 135.014208 -259.881116) (xy 134.994471 -259.898326)
			(xy 134.950898 -259.927368) (xy 134.903544 -259.949721) (xy 134.853428 -259.964903) (xy 134.80163 -259.972587)
			(xy 134.775448 -259.973064) (xy 134.775194 -259.973064) (xy 134.748548 -259.972566) (xy 134.695852 -259.964622)
			(xy 134.644929 -259.948913) (xy 134.596915 -259.925791) (xy 134.552884 -259.89577) (xy 134.513819 -259.859522)
			(xy 134.480593 -259.817857) (xy 134.453947 -259.771705) (xy 134.434478 -259.722098) (xy 134.422619 -259.670142)
			(xy 134.418637 -259.617) (xy 134.422619 -259.563858) (xy 134.434478 -259.511902) (xy 134.453947 -259.462295)
			(xy 134.480593 -259.416143) (xy 134.513819 -259.374478) (xy 134.552884 -259.33823) (xy 134.596915 -259.308209)
			(xy 134.644929 -259.285087) (xy 134.695852 -259.269378) (xy 134.748548 -259.261434) (xy 134.775194 -259.260848)
			(xy 134.775448 -259.260848) (xy 134.801632 -259.261308) (xy 134.853437 -259.268976) (xy 134.903558 -259.284154)
			(xy 134.950914 -259.306513) (xy 134.994481 -259.335571) (xy 135.014208 -259.352796) (xy 135.025409 -259.362261)
			(xy 135.051846 -259.374922) (xy 135.080791 -259.379556) (xy 135.109859 -259.375779) (xy 135.136659 -259.363905)
			(xy 135.158985 -259.344909) (xy 135.174997 -259.320356) (xy 135.183379 -259.292267) (xy 135.18388 -259.277612)
			(xy 135.18388 -259.155946) (xy 135.14705 -259.145532) (xy 135.121153 -259.137591) (xy 135.071939 -259.114969)
			(xy 135.026717 -259.085157) (xy 134.986531 -259.048842) (xy 134.952305 -259.006861) (xy 134.924831 -258.960182)
			(xy 134.90474 -258.909881) (xy 134.892497 -258.857119) (xy 134.888383 -258.803111) (xy 134.892493 -258.749103)
			(xy 134.904734 -258.69634) (xy 134.924821 -258.646038) (xy 134.952293 -258.599357) (xy 134.986516 -258.557374)
			(xy 135.0267 -258.521057) (xy 135.07192 -258.491242) (xy 135.121133 -258.468617) (xy 135.14705 -258.460748)
			(xy 135.18388 -258.450334) (xy 135.18388 -258.328414) (xy 135.183408 -258.313735) (xy 135.175083 -258.285583)
			(xy 135.159087 -258.260966) (xy 135.136746 -258.241921) (xy 135.109907 -258.230024) (xy 135.080792 -258.22626)
			(xy 135.05181 -258.230939) (xy 135.02536 -258.243676) (xy 135.014208 -258.25323) (xy 134.994471 -258.270439)
			(xy 134.950897 -258.29948) (xy 134.903543 -258.321832) (xy 134.853427 -258.337013) (xy 134.80163 -258.344698)
			(xy 134.775448 -258.345178) (xy 134.775194 -258.345178) (xy 134.748547 -258.34468) (xy 134.695849 -258.336736)
			(xy 134.644924 -258.321026) (xy 134.596908 -258.297903) (xy 134.552875 -258.267881) (xy 134.513809 -258.231632)
			(xy 134.480581 -258.189965) (xy 134.453934 -258.143811) (xy 134.434464 -258.094202) (xy 134.422606 -258.042244)
			(xy 134.418623 -257.9891) (xy 134.422606 -257.935956) (xy 134.434464 -257.883998) (xy 134.453934 -257.834389)
			(xy 134.480581 -257.788235) (xy 134.513809 -257.746568) (xy 134.552875 -257.710319) (xy 134.596908 -257.680297)
			(xy 134.644924 -257.657174) (xy 134.695849 -257.641464) (xy 134.748547 -257.63352) (xy 134.775194 -257.632962)
			(xy 134.775448 -257.632962) (xy 134.801632 -257.633423) (xy 134.853437 -257.64109) (xy 134.903558 -257.656268)
			(xy 134.950913 -257.678628) (xy 134.994479 -257.707688) (xy 135.014208 -257.72491) (xy 135.02541 -257.734374)
			(xy 135.051848 -257.747034) (xy 135.080793 -257.751666) (xy 135.109861 -257.74789) (xy 135.136662 -257.736016)
			(xy 135.158988 -257.717021) (xy 135.175003 -257.69247) (xy 135.183388 -257.664381) (xy 135.18388 -257.649726)
			(xy 135.18388 -257.52806) (xy 135.14705 -257.517646) (xy 135.12116 -257.509705) (xy 135.071959 -257.487085)
			(xy 135.026749 -257.457277) (xy 134.986574 -257.420968) (xy 134.95236 -257.378994) (xy 134.924895 -257.332324)
			(xy 134.904812 -257.282034) (xy 134.892575 -257.229283) (xy 134.888466 -257.175287) (xy 134.892579 -257.121292)
			(xy 134.90482 -257.068542) (xy 134.924906 -257.018253) (xy 134.952374 -256.971585) (xy 134.986592 -256.929614)
			(xy 135.026769 -256.893307) (xy 135.071981 -256.863502) (xy 135.121184 -256.840886) (xy 135.14705 -256.832862)
			(xy 135.18388 -256.822448) (xy 135.18388 -256.700782) (xy 135.183404 -256.686106) (xy 135.175073 -256.657963)
			(xy 135.159077 -256.633354) (xy 135.136739 -256.614316) (xy 135.109905 -256.602423) (xy 135.080797 -256.59866)
			(xy 135.051821 -256.603336) (xy 135.025375 -256.616066) (xy 135.014208 -256.625598) (xy 134.994471 -256.642809)
			(xy 134.950899 -256.671852) (xy 134.903544 -256.694206) (xy 134.853429 -256.709389) (xy 134.80163 -256.717074)
			(xy 134.775448 -256.717546) (xy 134.775194 -256.717546) (xy 134.748542 -256.717048) (xy 134.695834 -256.709103)
			(xy 134.644899 -256.69339) (xy 134.596874 -256.670262) (xy 134.552832 -256.640235) (xy 134.513758 -256.603978)
			(xy 134.480524 -256.562304) (xy 134.453873 -256.516141) (xy 134.434399 -256.466522) (xy 134.422538 -256.414555)
			(xy 134.418554 -256.3614) (xy 134.422538 -256.308245) (xy 134.434399 -256.256278) (xy 134.453873 -256.206659)
			(xy 134.480524 -256.160496) (xy 134.513758 -256.118822) (xy 134.552832 -256.082565) (xy 134.596874 -256.052538)
			(xy 134.644899 -256.02941) (xy 134.695834 -256.013697) (xy 134.748542 -256.005752) (xy 134.775194 -256.00533)
			(xy 134.775448 -256.00533) (xy 134.801633 -256.00579) (xy 134.853437 -256.013458) (xy 134.903559 -256.028635)
			(xy 134.950915 -256.050993) (xy 134.994484 -256.080051) (xy 135.014208 -256.097278) (xy 135.025408 -256.106744)
			(xy 135.051844 -256.119407) (xy 135.080788 -256.124042) (xy 135.109857 -256.120266) (xy 135.136656 -256.108391)
			(xy 135.15898 -256.089394) (xy 135.17499 -256.064839) (xy 135.183368 -256.036749) (xy 135.18388 -256.022094)
			(xy 135.18388 -255.900428) (xy 135.14705 -255.890014) (xy 135.121155 -255.882073) (xy 135.071943 -255.859452)
			(xy 135.026724 -255.82964) (xy 134.98654 -255.793326) (xy 134.952317 -255.751347) (xy 134.924844 -255.70467)
			(xy 134.904755 -255.654371) (xy 134.892513 -255.601611) (xy 134.8884 -255.547606) (xy 134.892511 -255.493601)
			(xy 134.904752 -255.44084) (xy 134.924839 -255.390541) (xy 134.95231 -255.343863) (xy 134.986532 -255.301883)
			(xy 135.026715 -255.265567) (xy 135.071933 -255.235754) (xy 135.121143 -255.213131) (xy 135.14705 -255.20523)
			(xy 135.18388 -255.194816) (xy 135.18388 -255.072896) (xy 135.183406 -255.058219) (xy 135.175077 -255.030072)
			(xy 135.159082 -255.005459) (xy 135.136742 -254.986418) (xy 135.109906 -254.974524) (xy 135.080795 -254.97076)
			(xy 135.051817 -254.975437) (xy 135.025368 -254.98817) (xy 135.014208 -254.997712) (xy 134.994471 -255.014922)
			(xy 134.950898 -255.043964) (xy 134.903544 -255.066317) (xy 134.853428 -255.0815) (xy 134.80163 -255.089184)
			(xy 134.775448 -255.08966) (xy 134.775194 -255.08966) (xy 134.748549 -255.089162) (xy 134.695853 -255.081218)
			(xy 134.64493 -255.06551) (xy 134.596917 -255.042387) (xy 134.552886 -255.012367) (xy 134.513822 -254.97612)
			(xy 134.480596 -254.934455) (xy 134.453951 -254.888304) (xy 134.434482 -254.838697) (xy 134.422623 -254.786742)
			(xy 134.418641 -254.7336) (xy 134.422623 -254.680458) (xy 134.434482 -254.628503) (xy 134.453951 -254.578896)
			(xy 134.480596 -254.532745) (xy 134.513822 -254.49108) (xy 134.552886 -254.454833) (xy 134.596917 -254.424813)
			(xy 134.64493 -254.40169) (xy 134.695853 -254.385982) (xy 134.748549 -254.378038) (xy 134.775194 -254.377444)
			(xy 134.775448 -254.377444) (xy 134.801633 -254.377904) (xy 134.853437 -254.385572) (xy 134.903558 -254.400749)
			(xy 134.950914 -254.423109) (xy 134.994482 -254.452167) (xy 135.014208 -254.469392) (xy 135.025409 -254.478857)
			(xy 135.051846 -254.491519) (xy 135.08079 -254.496152) (xy 135.109859 -254.492376) (xy 135.136658 -254.480501)
			(xy 135.158983 -254.461506) (xy 135.174995 -254.436952) (xy 135.183376 -254.408863) (xy 135.18388 -254.394208)
			(xy 135.18388 -254.272542) (xy 135.14705 -254.262128) (xy 135.121154 -254.254187) (xy 135.07194 -254.231565)
			(xy 135.026719 -254.201753) (xy 134.986533 -254.165438) (xy 134.952308 -254.123458) (xy 134.924834 -254.076779)
			(xy 134.904744 -254.026479) (xy 134.8925 -253.973717) (xy 134.888387 -253.91971) (xy 134.892497 -253.865702)
			(xy 134.904738 -253.81294) (xy 134.924825 -253.762639) (xy 134.952297 -253.715959) (xy 134.986519 -253.673976)
			(xy 135.026703 -253.637659) (xy 135.071923 -253.607844) (xy 135.121135 -253.58522) (xy 135.14705 -253.577344)
			(xy 135.18388 -253.56693) (xy 135.18388 -247.58523) (xy 135.133334 -247.53443) (xy 135.106784 -247.533786)
			(xy 135.054313 -247.525595) (xy 135.00364 -247.509703) (xy 134.955889 -247.486463) (xy 134.912118 -247.45639)
			(xy 134.873299 -247.420151) (xy 134.840291 -247.378548) (xy 134.813827 -247.332506) (xy 134.794493 -247.283044)
			(xy 134.782719 -247.231259) (xy 134.778765 -247.1783) (xy 134.782718 -247.125341) (xy 134.794493 -247.073557)
			(xy 134.813826 -247.024095) (xy 134.840291 -246.978052) (xy 134.873298 -246.93645) (xy 134.912118 -246.90021)
			(xy 134.955889 -246.870137) (xy 135.00364 -246.846897) (xy 135.054313 -246.831005) (xy 135.106784 -246.822814)
			(xy 135.133334 -246.822214) (xy 135.18388 -246.771414) (xy 135.18388 -245.957598) (xy 135.133334 -245.906798)
			(xy 135.106787 -245.906154) (xy 135.05432 -245.897964) (xy 135.003652 -245.882074) (xy 134.955905 -245.858836)
			(xy 134.912138 -245.828765) (xy 134.873322 -245.792529) (xy 134.840317 -245.75093) (xy 134.813855 -245.704892)
			(xy 134.794523 -245.655434) (xy 134.78275 -245.603654) (xy 134.778797 -245.5507) (xy 134.78275 -245.497746)
			(xy 134.794523 -245.445966) (xy 134.813855 -245.396508) (xy 134.840317 -245.35047) (xy 134.873322 -245.308871)
			(xy 134.912138 -245.272635) (xy 134.955905 -245.242564) (xy 135.003652 -245.219326) (xy 135.05432 -245.203436)
			(xy 135.106787 -245.195246) (xy 135.133334 -245.194582) (xy 135.18388 -245.143782) (xy 135.18388 -244.329712)
			(xy 135.133334 -244.278912) (xy 135.106785 -244.278268) (xy 135.054317 -244.270077) (xy 135.003647 -244.254187)
			(xy 134.955898 -244.230948) (xy 134.91213 -244.200876) (xy 134.873312 -244.164638) (xy 134.840306 -244.123038)
			(xy 134.813843 -244.076998) (xy 134.79451 -244.027538) (xy 134.782736 -243.975756) (xy 134.778783 -243.9228)
			(xy 134.782736 -243.869844) (xy 134.79451 -243.818062) (xy 134.813843 -243.768602) (xy 134.840306 -243.722562)
			(xy 134.873312 -243.680962) (xy 134.91213 -243.644724) (xy 134.955898 -243.614652) (xy 135.003647 -243.591413)
			(xy 135.054317 -243.575523) (xy 135.106785 -243.567332) (xy 135.133334 -243.566696) (xy 135.18388 -243.515896)
			(xy 135.18388 -242.701826) (xy 135.133334 -242.651026) (xy 135.106784 -242.650382) (xy 135.054314 -242.642191)
			(xy 135.003642 -242.6263) (xy 134.955891 -242.60306) (xy 134.912121 -242.572987) (xy 134.873302 -242.536748)
			(xy 134.840294 -242.495146) (xy 134.81383 -242.449104) (xy 134.794497 -242.399642) (xy 134.782722 -242.347858)
			(xy 134.778769 -242.2949) (xy 134.782722 -242.241942) (xy 134.794497 -242.190158) (xy 134.81383 -242.140696)
			(xy 134.840294 -242.094654) (xy 134.873301 -242.053052) (xy 134.912121 -242.016813) (xy 134.955891 -241.98674)
			(xy 135.003642 -241.9635) (xy 135.054314 -241.947609) (xy 135.106784 -241.939418) (xy 135.133334 -241.93881)
			(xy 135.18388 -241.88801) (xy 135.18388 -241.074194) (xy 135.133334 -241.023394) (xy 135.106787 -241.02275)
			(xy 135.054321 -241.01456) (xy 135.003653 -240.99867) (xy 134.955907 -240.975432) (xy 134.912141 -240.945362)
			(xy 134.873325 -240.909126) (xy 134.84032 -240.867528) (xy 134.813859 -240.82149) (xy 134.794527 -240.772033)
			(xy 134.782754 -240.720253) (xy 134.778801 -240.6673) (xy 134.782754 -240.614346) (xy 134.794527 -240.562567)
			(xy 134.813859 -240.51311) (xy 134.84032 -240.467072) (xy 134.873325 -240.425474) (xy 134.912141 -240.389238)
			(xy 134.955907 -240.359168) (xy 135.003654 -240.33593) (xy 135.054321 -240.32004) (xy 135.106787 -240.31185)
			(xy 135.133334 -240.311178) (xy 135.18388 -240.260378) (xy 135.18388 -239.446308) (xy 135.133334 -239.395508)
			(xy 135.106786 -239.394864) (xy 135.054318 -239.386674) (xy 135.003648 -239.370783) (xy 134.9559 -239.347544)
			(xy 134.912132 -239.317473) (xy 134.873315 -239.281236) (xy 134.840309 -239.239636) (xy 134.813846 -239.193596)
			(xy 134.794514 -239.144137) (xy 134.78274 -239.092356) (xy 134.778787 -239.0394) (xy 134.78274 -238.986444)
			(xy 134.794514 -238.934663) (xy 134.813846 -238.885204) (xy 134.840309 -238.839164) (xy 134.873315 -238.797564)
			(xy 134.912132 -238.761327) (xy 134.9559 -238.731256) (xy 135.003648 -238.708017) (xy 135.054318 -238.692126)
			(xy 135.106786 -238.683936) (xy 135.133334 -238.683292) (xy 135.18388 -238.632492) (xy 135.18388 -237.818422)
			(xy 135.133334 -237.767622) (xy 135.106785 -237.766978) (xy 135.054315 -237.758787) (xy 135.003643 -237.742896)
			(xy 134.955893 -237.719657) (xy 134.912123 -237.689584) (xy 134.873304 -237.653345) (xy 134.840297 -237.611744)
			(xy 134.813834 -237.565702) (xy 134.794501 -237.516241) (xy 134.782726 -237.464458) (xy 134.778773 -237.4115)
			(xy 134.782726 -237.358542) (xy 134.7945 -237.306759) (xy 134.813834 -237.257298) (xy 134.840297 -237.211256)
			(xy 134.873304 -237.169655) (xy 134.912123 -237.133416) (xy 134.955893 -237.103344) (xy 135.003643 -237.080104)
			(xy 135.054315 -237.064213) (xy 135.106785 -237.056022) (xy 135.133334 -237.055406) (xy 135.18388 -237.004606)
			(xy 135.18388 -236.19079) (xy 135.133334 -236.13999) (xy 135.106787 -236.139346) (xy 135.054322 -236.131156)
			(xy 135.003655 -236.115266) (xy 134.955909 -236.092029) (xy 134.912143 -236.061959) (xy 134.873328 -236.025723)
			(xy 134.840324 -235.984126) (xy 134.813862 -235.938088) (xy 134.794531 -235.888632) (xy 134.782758 -235.836853)
			(xy 134.778805 -235.7839) (xy 134.782758 -235.730947) (xy 134.794531 -235.679168) (xy 134.813863 -235.629712)
			(xy 134.840324 -235.583674) (xy 134.873328 -235.542076) (xy 134.912143 -235.505841) (xy 134.955909 -235.475771)
			(xy 135.003655 -235.452534) (xy 135.054322 -235.436644) (xy 135.106787 -235.428454) (xy 135.133334 -235.427774)
			(xy 135.18388 -235.376974) (xy 135.18388 -234.563158) (xy 135.133334 -234.512358) (xy 135.106782 -234.511714)
			(xy 135.054307 -234.503522) (xy 135.00363 -234.48763) (xy 134.955875 -234.464388) (xy 134.912101 -234.434312)
			(xy 134.873278 -234.39807) (xy 134.840268 -234.356464) (xy 134.813801 -234.310418) (xy 134.794466 -234.260952)
			(xy 134.782691 -234.209163) (xy 134.778737 -234.1562) (xy 134.782691 -234.103237) (xy 134.794466 -234.051449)
			(xy 134.813801 -234.001983) (xy 134.840267 -233.955936) (xy 134.873278 -233.914331) (xy 134.912101 -233.878088)
			(xy 134.955875 -233.848013) (xy 135.00363 -233.824771) (xy 135.054306 -233.808878) (xy 135.106781 -233.800687)
			(xy 135.133334 -233.800142) (xy 135.18388 -233.749342) (xy 135.18388 -232.935272) (xy 135.133334 -232.884472)
			(xy 135.106788 -232.883827) (xy 135.054326 -232.875638) (xy 135.003662 -232.859749) (xy 134.955918 -232.836513)
			(xy 134.912155 -232.806444) (xy 134.873341 -232.770211) (xy 134.840339 -232.728615) (xy 134.813879 -232.68258)
			(xy 134.794549 -232.633126) (xy 134.782776 -232.58135) (xy 134.778823 -232.5284) (xy 134.782776 -232.47545)
			(xy 134.794549 -232.423673) (xy 134.813879 -232.37422) (xy 134.840339 -232.328184) (xy 134.873342 -232.286589)
			(xy 134.912155 -232.250355) (xy 134.955919 -232.220287) (xy 135.003662 -232.197051) (xy 135.054327 -232.181162)
			(xy 135.106789 -232.172973) (xy 135.133334 -232.172256) (xy 135.18388 -232.121456) (xy 135.18388 -231.307386)
			(xy 135.133334 -231.256586) (xy 135.106787 -231.255941) (xy 135.054323 -231.247752) (xy 135.003657 -231.231862)
			(xy 134.955911 -231.208625) (xy 134.912146 -231.178555) (xy 134.873331 -231.14232) (xy 134.840327 -231.100723)
			(xy 134.813867 -231.054686) (xy 134.794535 -231.00523) (xy 134.782763 -230.953452) (xy 134.778809 -230.9005)
			(xy 134.782763 -230.847548) (xy 134.794535 -230.795769) (xy 134.813867 -230.746314) (xy 134.840328 -230.700277)
			(xy 134.873331 -230.65868) (xy 134.912146 -230.622444) (xy 134.955912 -230.592375) (xy 135.003657 -230.569138)
			(xy 135.054323 -230.553248) (xy 135.106788 -230.545059) (xy 135.133334 -230.54437) (xy 135.18388 -230.49357)
			(xy 135.18388 -229.679754) (xy 135.133334 -229.628954) (xy 135.106782 -229.62831) (xy 135.054308 -229.620118)
			(xy 135.003632 -229.604226) (xy 134.955877 -229.580984) (xy 134.912103 -229.550909) (xy 134.873281 -229.514667)
			(xy 134.840271 -229.473062) (xy 134.813805 -229.427016) (xy 134.79447 -229.377551) (xy 134.782695 -229.325763)
			(xy 134.778741 -229.2728) (xy 134.782695 -229.219838) (xy 134.79447 -229.16805) (xy 134.813805 -229.118584)
			(xy 134.840271 -229.072539) (xy 134.873281 -229.030933) (xy 134.912103 -228.994691) (xy 134.955877 -228.964616)
			(xy 135.003631 -228.941374) (xy 135.054307 -228.925482) (xy 135.106782 -228.917291) (xy 135.133334 -228.916738)
			(xy 135.18388 -228.865938) (xy 135.18388 -228.051868) (xy 135.133334 -228.001068) (xy 135.105458 -228.000365)
			(xy 135.050433 -227.991355) (xy 134.997484 -227.973877) (xy 134.947907 -227.94836) (xy 134.902913 -227.915427)
			(xy 134.863603 -227.875883) (xy 134.830936 -227.830696) (xy 134.805713 -227.780968) (xy 134.788549 -227.727917)
			(xy 134.779864 -227.672839) (xy 134.779258 -227.64496) (xy 134.779769 -227.617861) (xy 134.787994 -227.564292)
			(xy 134.804247 -227.512589) (xy 134.828152 -227.463949) (xy 134.859157 -227.419496) (xy 134.896544 -227.38026)
			(xy 134.939449 -227.347146) (xy 134.9629 -227.333556) (xy 134.974473 -227.326671) (xy 134.993794 -227.307925)
			(xy 135.007549 -227.284783) (xy 135.014783 -227.258853) (xy 135.014994 -227.231933) (xy 135.008167 -227.205893)
			(xy 134.994776 -227.182539) (xy 134.985506 -227.172774) (xy 134.908036 -227.095304) (xy 134.872984 -227.12045)
			(xy 134.850171 -227.136192) (xy 134.80069 -227.161158) (xy 134.747932 -227.178139) (xy 134.693178 -227.186723)
			(xy 134.665466 -227.187252) (xy 134.665212 -227.187252) (xy 134.637227 -227.186704) (xy 134.581946 -227.177951)
			(xy 134.528714 -227.160658) (xy 134.478843 -227.135251) (xy 134.43356 -227.102356) (xy 134.393981 -227.062782)
			(xy 134.361078 -227.017505) (xy 134.335664 -226.967637) (xy 134.318362 -226.914409) (xy 134.3096 -226.859129)
			(xy 134.309104 -226.831144) (xy 134.309104 -226.83089) (xy 134.309659 -226.803183) (xy 134.318287 -226.748444)
			(xy 134.335272 -226.695697) (xy 134.360206 -226.646208) (xy 134.375906 -226.623372) (xy 134.401052 -226.58832)
			(xy 134.186422 -226.37369) (xy 134.16788 -226.37242) (xy 134.139987 -226.369719) (xy 134.085493 -226.356664)
			(xy 134.033714 -226.335238) (xy 133.985929 -226.305969) (xy 133.943316 -226.269579) (xy 133.906927 -226.226966)
			(xy 133.877659 -226.17918) (xy 133.856234 -226.127401) (xy 133.84318 -226.072906) (xy 133.840474 -226.045014)
			(xy 133.839204 -226.026472) (xy 133.784594 -225.971862) (xy 133.773914 -225.961839) (xy 133.748204 -225.947833)
			(xy 133.719578 -225.941695) (xy 133.690386 -225.943931) (xy 133.663027 -225.954356) (xy 133.639751 -225.972114)
			(xy 133.622468 -225.995746) (xy 133.612599 -226.02331) (xy 133.611366 -226.037902) (xy 133.609318 -226.064788)
			(xy 133.598132 -226.117534) (xy 133.579122 -226.167991) (xy 133.55272 -226.215004) (xy 133.519533 -226.257499)
			(xy 133.480317 -226.294505) (xy 133.435969 -226.325174) (xy 133.387505 -226.348806) (xy 133.336032 -226.36486)
			(xy 133.282726 -226.37297) (xy 133.255766 -226.373436) (xy 133.22943 -226.372967) (xy 133.177332 -226.365221)
			(xy 133.126941 -226.349888) (xy 133.079358 -226.327303) (xy 133.035619 -226.297957) (xy 132.996678 -226.262491)
			(xy 132.963383 -226.221678) (xy 132.936461 -226.176407) (xy 132.926074 -226.152202) (xy 132.891162 -226.157065)
			(xy 132.82086 -226.162277) (xy 132.785612 -226.162616) (xy 132.750492 -226.162265) (xy 132.680443 -226.157054)
			(xy 132.645658 -226.152202) (xy 132.635233 -226.176389) (xy 132.608306 -226.221653) (xy 132.575012 -226.262463)
			(xy 132.536075 -226.297929) (xy 132.492345 -226.327281) (xy 132.444771 -226.34988) (xy 132.394391 -226.365233)
			(xy 132.3423 -226.373006) (xy 132.315966 -226.373436) (xy 132.287984 -226.372885) (xy 132.232709 -226.364125)
			(xy 132.179485 -226.346828) (xy 132.129621 -226.321419) (xy 132.084346 -226.288523) (xy 132.044774 -226.248949)
			(xy 132.011878 -226.203674) (xy 131.986469 -226.15381) (xy 131.969173 -226.100585) (xy 131.960415 -226.04531)
			(xy 131.959858 -226.017328) (xy 131.960473 -225.98803) (xy 131.970101 -225.93023) (xy 131.989053 -225.874784)
			(xy 132.016819 -225.823183) (xy 132.03428 -225.79965) (xy 132.010188 -225.76868) (xy 131.966574 -225.703445)
			(xy 131.947158 -225.669348) (xy 131.744466 -225.669348) (xy 131.725092 -225.703306) (xy 131.681605 -225.768285)
			(xy 131.657598 -225.799142) (xy 131.675122 -225.822723) (xy 131.703012 -225.874427) (xy 131.722041 -225.930006)
			(xy 131.731692 -225.987955) (xy 131.732274 -226.017328) (xy 131.731751 -226.045311) (xy 131.722992 -226.100587)
			(xy 131.705693 -226.153812) (xy 131.680281 -226.203676) (xy 131.647381 -226.248951) (xy 131.607804 -226.288521)
			(xy 131.562523 -226.321413) (xy 131.512655 -226.346817) (xy 131.459427 -226.364106) (xy 131.404149 -226.372856)
			(xy 131.376166 -226.373436) (xy 131.34983 -226.372967) (xy 131.297732 -226.365221) (xy 131.247341 -226.349888)
			(xy 131.199758 -226.327303) (xy 131.156019 -226.297957) (xy 131.117078 -226.262491) (xy 131.083783 -226.221678)
			(xy 131.056861 -226.176407) (xy 131.046474 -226.152202) (xy 131.011562 -226.157065) (xy 130.94126 -226.162277)
			(xy 130.906012 -226.162616) (xy 130.870892 -226.162265) (xy 130.800843 -226.157054) (xy 130.766058 -226.152202)
			(xy 130.755633 -226.176389) (xy 130.728706 -226.221653) (xy 130.695412 -226.262463) (xy 130.656475 -226.297929)
			(xy 130.612745 -226.327281) (xy 130.565171 -226.34988) (xy 130.514791 -226.365233) (xy 130.4627 -226.373006)
			(xy 130.436366 -226.373436) (xy 130.408384 -226.372885) (xy 130.353109 -226.364125) (xy 130.299885 -226.346828)
			(xy 130.250021 -226.321419) (xy 130.204746 -226.288523) (xy 130.165174 -226.248949) (xy 130.132278 -226.203674)
			(xy 130.106869 -226.15381) (xy 130.089573 -226.100585) (xy 130.080815 -226.04531) (xy 130.080258 -226.017328)
			(xy 130.080873 -225.98803) (xy 130.090501 -225.93023) (xy 130.109453 -225.874784) (xy 130.137219 -225.823183)
			(xy 130.15468 -225.79965) (xy 130.130588 -225.76868) (xy 130.086974 -225.703445) (xy 130.067558 -225.669348)
			(xy 129.864866 -225.669348) (xy 129.845492 -225.703306) (xy 129.802005 -225.768285) (xy 129.777998 -225.799142)
			(xy 129.795522 -225.822723) (xy 129.823412 -225.874427) (xy 129.842441 -225.930006) (xy 129.852092 -225.987955)
			(xy 129.852674 -226.017328) (xy 129.852151 -226.045311) (xy 129.843392 -226.100587) (xy 129.826093 -226.153812)
			(xy 129.800681 -226.203676) (xy 129.767781 -226.248951) (xy 129.728204 -226.288521) (xy 129.682923 -226.321413)
			(xy 129.633055 -226.346817) (xy 129.579827 -226.364106) (xy 129.524549 -226.372856) (xy 129.496566 -226.373436)
			(xy 129.47023 -226.372967) (xy 129.418132 -226.365221) (xy 129.367741 -226.349888) (xy 129.320158 -226.327303)
			(xy 129.276419 -226.297957) (xy 129.237478 -226.262491) (xy 129.204183 -226.221678) (xy 129.177261 -226.176407)
			(xy 129.166874 -226.152202) (xy 129.131962 -226.157065) (xy 129.06166 -226.162277) (xy 129.026412 -226.162616)
			(xy 128.991292 -226.162265) (xy 128.921243 -226.157054) (xy 128.886458 -226.152202) (xy 128.876033 -226.176389)
			(xy 128.849106 -226.221653) (xy 128.815812 -226.262463) (xy 128.776875 -226.297929) (xy 128.733145 -226.327281)
			(xy 128.685571 -226.34988) (xy 128.635191 -226.365233) (xy 128.5831 -226.373006) (xy 128.556766 -226.373436)
			(xy 128.528784 -226.372885) (xy 128.473509 -226.364125) (xy 128.420285 -226.346828) (xy 128.370421 -226.321419)
			(xy 128.325146 -226.288523) (xy 128.285574 -226.248949) (xy 128.252678 -226.203674) (xy 128.227269 -226.15381)
			(xy 128.209973 -226.100585) (xy 128.201215 -226.04531) (xy 128.200658 -226.017328) (xy 128.201273 -225.98803)
			(xy 128.210901 -225.93023) (xy 128.229853 -225.874784) (xy 128.257619 -225.823183) (xy 128.27508 -225.79965)
			(xy 128.250988 -225.76868) (xy 128.207374 -225.703445) (xy 128.187958 -225.669348) (xy 127.985266 -225.669348)
			(xy 127.965892 -225.703306) (xy 127.922405 -225.768285) (xy 127.898398 -225.799142) (xy 127.915922 -225.822723)
			(xy 127.943812 -225.874427) (xy 127.962841 -225.930006) (xy 127.972492 -225.987955) (xy 127.973074 -226.017328)
			(xy 127.972551 -226.045311) (xy 127.963792 -226.100587) (xy 127.946493 -226.153812) (xy 127.921081 -226.203676)
			(xy 127.888181 -226.248951) (xy 127.848604 -226.288521) (xy 127.803323 -226.321413) (xy 127.753455 -226.346817)
			(xy 127.700227 -226.364106) (xy 127.644949 -226.372856) (xy 127.616966 -226.373436) (xy 127.59063 -226.372967)
			(xy 127.538532 -226.365221) (xy 127.488141 -226.349888) (xy 127.440558 -226.327303) (xy 127.396819 -226.297957)
			(xy 127.357878 -226.262491) (xy 127.324583 -226.221678) (xy 127.297661 -226.176407) (xy 127.287274 -226.152202)
			(xy 127.252362 -226.157065) (xy 127.18206 -226.162277) (xy 127.146812 -226.162616) (xy 127.111692 -226.162265)
			(xy 127.041643 -226.157054) (xy 127.006858 -226.152202) (xy 126.996433 -226.176389) (xy 126.969506 -226.221653)
			(xy 126.936212 -226.262463) (xy 126.897275 -226.297929) (xy 126.853545 -226.327281) (xy 126.805971 -226.34988)
			(xy 126.755591 -226.365233) (xy 126.7035 -226.373006) (xy 126.677166 -226.373436) (xy 126.649184 -226.372885)
			(xy 126.593909 -226.364125) (xy 126.540685 -226.346828) (xy 126.490821 -226.321419) (xy 126.445546 -226.288523)
			(xy 126.405974 -226.248949) (xy 126.373078 -226.203674) (xy 126.347669 -226.15381) (xy 126.330373 -226.100585)
			(xy 126.321615 -226.04531) (xy 126.321058 -226.017328) (xy 126.321673 -225.98803) (xy 126.331301 -225.93023)
			(xy 126.350253 -225.874784) (xy 126.378019 -225.823183) (xy 126.39548 -225.79965) (xy 126.371388 -225.76868)
			(xy 126.327774 -225.703445) (xy 126.308358 -225.669348) (xy 126.105666 -225.669348) (xy 126.086292 -225.703306)
			(xy 126.042805 -225.768285) (xy 126.018798 -225.799142) (xy 126.036322 -225.822723) (xy 126.064212 -225.874427)
			(xy 126.083241 -225.930006) (xy 126.092892 -225.987955) (xy 126.093474 -226.017328) (xy 126.092951 -226.045311)
			(xy 126.084192 -226.100587) (xy 126.066893 -226.153812) (xy 126.041481 -226.203676) (xy 126.008581 -226.248951)
			(xy 125.969004 -226.288521) (xy 125.923723 -226.321413) (xy 125.873855 -226.346817) (xy 125.820627 -226.364106)
			(xy 125.765349 -226.372856) (xy 125.737366 -226.373436) (xy 125.71103 -226.372967) (xy 125.658932 -226.365221)
			(xy 125.608541 -226.349888) (xy 125.560958 -226.327303) (xy 125.517219 -226.297957) (xy 125.478278 -226.262491)
			(xy 125.444983 -226.221678) (xy 125.418061 -226.176407) (xy 125.407674 -226.152202) (xy 125.372762 -226.157065)
			(xy 125.30246 -226.162277) (xy 125.267212 -226.162616) (xy 125.232092 -226.162265) (xy 125.162043 -226.157054)
			(xy 125.127258 -226.152202) (xy 125.116833 -226.176389) (xy 125.089906 -226.221653) (xy 125.056612 -226.262463)
			(xy 125.017675 -226.297929) (xy 124.973945 -226.327281) (xy 124.926371 -226.34988) (xy 124.875991 -226.365233)
			(xy 124.8239 -226.373006) (xy 124.797566 -226.373436) (xy 124.769584 -226.372885) (xy 124.714309 -226.364125)
			(xy 124.661085 -226.346828) (xy 124.611221 -226.321419) (xy 124.565946 -226.288523) (xy 124.526374 -226.248949)
			(xy 124.493478 -226.203674) (xy 124.468069 -226.15381) (xy 124.450773 -226.100585) (xy 124.442015 -226.04531)
			(xy 124.441458 -226.017328) (xy 124.442073 -225.98803) (xy 124.451701 -225.93023) (xy 124.470653 -225.874784)
			(xy 124.498419 -225.823183) (xy 124.51588 -225.79965) (xy 124.491788 -225.76868) (xy 124.448174 -225.703445)
			(xy 124.428758 -225.669348) (xy 124.226066 -225.669348) (xy 124.206692 -225.703306) (xy 124.163205 -225.768285)
			(xy 124.139198 -225.799142) (xy 124.156722 -225.822723) (xy 124.184612 -225.874427) (xy 124.203641 -225.930006)
			(xy 124.213292 -225.987955) (xy 124.213874 -226.017328) (xy 124.213351 -226.045311) (xy 124.204592 -226.100587)
			(xy 124.187293 -226.153812) (xy 124.161881 -226.203676) (xy 124.128981 -226.248951) (xy 124.089404 -226.288521)
			(xy 124.044123 -226.321413) (xy 123.994255 -226.346817) (xy 123.941027 -226.364106) (xy 123.885749 -226.372856)
			(xy 123.857766 -226.373436) (xy 123.83143 -226.372967) (xy 123.779332 -226.365221) (xy 123.728941 -226.349888)
			(xy 123.681358 -226.327303) (xy 123.637619 -226.297957) (xy 123.598678 -226.262491) (xy 123.565383 -226.221678)
			(xy 123.538461 -226.176407) (xy 123.528074 -226.152202) (xy 123.493162 -226.157065) (xy 123.42286 -226.162277)
			(xy 123.387612 -226.162616) (xy 123.352492 -226.162265) (xy 123.282443 -226.157054) (xy 123.247658 -226.152202)
			(xy 123.237233 -226.176389) (xy 123.210306 -226.221653) (xy 123.177012 -226.262463) (xy 123.138075 -226.297929)
			(xy 123.094345 -226.327281) (xy 123.046771 -226.34988) (xy 122.996391 -226.365233) (xy 122.9443 -226.373006)
			(xy 122.917966 -226.373436) (xy 122.889984 -226.372885) (xy 122.834709 -226.364125) (xy 122.781485 -226.346828)
			(xy 122.731621 -226.321419) (xy 122.686346 -226.288523) (xy 122.646774 -226.248949) (xy 122.613878 -226.203674)
			(xy 122.588469 -226.15381) (xy 122.571173 -226.100585) (xy 122.562415 -226.04531) (xy 122.561858 -226.017328)
			(xy 122.562473 -225.98803) (xy 122.572101 -225.93023) (xy 122.591053 -225.874784) (xy 122.618819 -225.823183)
			(xy 122.63628 -225.79965) (xy 122.612188 -225.76868) (xy 122.568574 -225.703445) (xy 122.549158 -225.669348)
			(xy 122.346466 -225.669348) (xy 122.327092 -225.703306) (xy 122.283605 -225.768285) (xy 122.259598 -225.799142)
			(xy 122.277122 -225.822723) (xy 122.305012 -225.874427) (xy 122.324041 -225.930006) (xy 122.333692 -225.987955)
			(xy 122.334274 -226.017328) (xy 122.333751 -226.045311) (xy 122.324992 -226.100587) (xy 122.307693 -226.153812)
			(xy 122.282281 -226.203676) (xy 122.249381 -226.248951) (xy 122.209804 -226.288521) (xy 122.164523 -226.321413)
			(xy 122.114655 -226.346817) (xy 122.061427 -226.364106) (xy 122.006149 -226.372856) (xy 121.978166 -226.373436)
			(xy 121.95183 -226.372967) (xy 121.899732 -226.365221) (xy 121.849341 -226.349888) (xy 121.801758 -226.327303)
			(xy 121.758019 -226.297957) (xy 121.719078 -226.262491) (xy 121.685783 -226.221678) (xy 121.658861 -226.176407)
			(xy 121.648474 -226.152202) (xy 121.613562 -226.157065) (xy 121.54326 -226.162277) (xy 121.508012 -226.162616)
			(xy 121.472892 -226.162265) (xy 121.402843 -226.157054) (xy 121.368058 -226.152202) (xy 121.357633 -226.176389)
			(xy 121.330706 -226.221653) (xy 121.297412 -226.262463) (xy 121.258475 -226.297929) (xy 121.214745 -226.327281)
			(xy 121.167171 -226.34988) (xy 121.116791 -226.365233) (xy 121.0647 -226.373006) (xy 121.038366 -226.373436)
			(xy 121.010384 -226.372885) (xy 120.955109 -226.364125) (xy 120.901885 -226.346828) (xy 120.852021 -226.321419)
			(xy 120.806746 -226.288523) (xy 120.767174 -226.248949) (xy 120.734278 -226.203674) (xy 120.708869 -226.15381)
			(xy 120.691573 -226.100585) (xy 120.682815 -226.04531) (xy 120.682258 -226.017328) (xy 120.682873 -225.98803)
			(xy 120.692501 -225.93023) (xy 120.711453 -225.874784) (xy 120.739219 -225.823183) (xy 120.75668 -225.79965)
			(xy 120.732588 -225.76868) (xy 120.688974 -225.703445) (xy 120.669558 -225.669348) (xy 120.484392 -225.669348)
			(xy 120.470793 -225.669782) (xy 120.444561 -225.67697) (xy 120.421161 -225.690832) (xy 120.402254 -225.710385)
			(xy 120.389185 -225.734237) (xy 120.382882 -225.760695) (xy 120.383793 -225.787878) (xy 120.391853 -225.813855)
			(xy 120.398794 -225.825558) (xy 120.412008 -225.847086) (xy 120.432888 -225.893081) (xy 120.447059 -225.941565)
			(xy 120.454236 -225.991564) (xy 120.454674 -226.01682) (xy 120.454674 -226.017328) (xy 120.454176 -226.043977)
			(xy 120.446233 -226.096681) (xy 120.430523 -226.147611) (xy 120.407397 -226.195632) (xy 120.377373 -226.239669)
			(xy 120.341121 -226.27874) (xy 120.29945 -226.311971) (xy 120.253292 -226.33862) (xy 120.203678 -226.358092)
			(xy 120.151716 -226.369952) (xy 120.098566 -226.373936) (xy 120.045416 -226.369952) (xy 119.993454 -226.358092)
			(xy 119.94384 -226.33862) (xy 119.897682 -226.311971) (xy 119.856011 -226.27874) (xy 119.819759 -226.239669)
			(xy 119.789735 -226.195632) (xy 119.766609 -226.147611) (xy 119.750899 -226.096681) (xy 119.742956 -226.043977)
			(xy 119.742458 -226.017328) (xy 119.74304 -225.988154) (xy 119.752543 -225.930587) (xy 119.771301 -225.875337)
			(xy 119.798811 -225.823883) (xy 119.834338 -225.777599) (xy 119.855234 -225.757232) (xy 119.871236 -225.720148)
			(xy 119.870763 -225.710163) (xy 119.86316 -225.691697) (xy 119.849087 -225.67753) (xy 119.830672 -225.669804)
			(xy 119.82069 -225.669348) (xy 119.74068 -225.669348) (xy 119.631206 -225.559874) (xy 119.611648 -225.558858)
			(xy 119.585404 -225.557149) (xy 119.533808 -225.546971) (xy 119.484271 -225.529313) (xy 119.437871 -225.504558)
			(xy 119.395619 -225.473246) (xy 119.358434 -225.436057) (xy 119.327125 -225.393802) (xy 119.302374 -225.3474)
			(xy 119.28472 -225.297862) (xy 119.274547 -225.246265) (xy 119.272812 -225.220022) (xy 119.271796 -225.200464)
			(xy 119.13108 -225.059748) (xy 119.13108 -224.74682) (xy 119.090186 -224.738946) (xy 119.063534 -224.733185)
			(xy 119.012254 -224.714651) (xy 118.964399 -224.688519) (xy 118.921084 -224.655399) (xy 118.883324 -224.616064)
			(xy 118.851998 -224.571435) (xy 118.82784 -224.522553) (xy 118.811414 -224.47056) (xy 118.803103 -224.416671)
			(xy 118.803102 -224.362145) (xy 118.81141 -224.308256) (xy 118.827834 -224.256262) (xy 118.85199 -224.207379)
			(xy 118.883313 -224.162748) (xy 118.921072 -224.123412) (xy 118.964385 -224.09029) (xy 119.01224 -224.064156)
			(xy 119.063518 -224.045619) (xy 119.090186 -224.039938) (xy 119.13108 -224.032064) (xy 119.13108 -223.880934)
			(xy 119.13061 -223.86732) (xy 119.123341 -223.841079) (xy 119.109392 -223.817693) (xy 119.089756 -223.798829)
			(xy 119.06583 -223.785828) (xy 119.039319 -223.779616) (xy 119.012108 -223.780635) (xy 118.986136 -223.788813)
			(xy 118.96325 -223.803568) (xy 118.953788 -223.81337) (xy 118.936632 -223.831849) (xy 118.898013 -223.864271)
			(xy 118.85521 -223.890924) (xy 118.809077 -223.911276) (xy 118.760535 -223.924921) (xy 118.735602 -223.928686)
			(xy 118.71071 -223.931988) (xy 118.538498 -224.230438) (xy 118.54815 -224.253552) (xy 118.556666 -224.275184)
			(xy 118.568652 -224.320102) (xy 118.574693 -224.366197) (xy 118.575074 -224.389442) (xy 118.574576 -224.416091)
			(xy 118.566633 -224.468795) (xy 118.550923 -224.519725) (xy 118.527797 -224.567746) (xy 118.497773 -224.611783)
			(xy 118.461521 -224.650854) (xy 118.41985 -224.684085) (xy 118.373692 -224.710734) (xy 118.324078 -224.730206)
			(xy 118.272116 -224.742066) (xy 118.218966 -224.74605) (xy 118.165816 -224.742066) (xy 118.113854 -224.730206)
			(xy 118.06424 -224.710734) (xy 118.018082 -224.684085) (xy 117.976411 -224.650854) (xy 117.940159 -224.611783)
			(xy 117.910135 -224.567746) (xy 117.887009 -224.519725) (xy 117.871299 -224.468795) (xy 117.863356 -224.416091)
			(xy 117.862858 -224.389442) (xy 117.863307 -224.363817) (xy 117.87066 -224.313096) (xy 117.885205 -224.263953)
			(xy 117.906642 -224.217401) (xy 117.934529 -224.174401) (xy 117.96829 -224.135842) (xy 118.007228 -224.102518)
			(xy 118.05054 -224.075119) (xy 118.097331 -224.054208) (xy 118.146636 -224.040219) (xy 118.171976 -224.036382)
			(xy 118.196614 -224.03308) (xy 118.368826 -223.734376) (xy 118.359428 -223.711516) (xy 118.350908 -223.689885)
			(xy 118.338914 -223.644967) (xy 118.332864 -223.598872) (xy 118.332504 -223.575626) (xy 118.333023 -223.54764)
			(xy 118.341775 -223.492356) (xy 118.359069 -223.439122) (xy 118.384478 -223.389249) (xy 118.417376 -223.343965)
			(xy 118.456954 -223.304386) (xy 118.502237 -223.271485) (xy 118.552109 -223.246074) (xy 118.605342 -223.228778)
			(xy 118.660626 -223.220024) (xy 118.688612 -223.219518) (xy 118.71355 -223.219936) (xy 118.762937 -223.226892)
			(xy 118.810873 -223.240666) (xy 118.85642 -223.260989) (xy 118.898688 -223.287464) (xy 118.936852 -223.319573)
			(xy 118.953788 -223.337882) (xy 118.9632 -223.347743) (xy 118.986099 -223.362514) (xy 119.012089 -223.370702)
			(xy 119.03932 -223.371725) (xy 119.065851 -223.365508) (xy 119.089792 -223.352494) (xy 119.109439 -223.333612)
			(xy 119.123391 -223.310205) (xy 119.130655 -223.283942) (xy 119.13108 -223.270318) (xy 119.13108 -223.118934)
			(xy 119.090186 -223.11106) (xy 119.06354 -223.105299) (xy 119.012274 -223.086767) (xy 118.964431 -223.060639)
			(xy 118.921128 -223.027525) (xy 118.883378 -222.988198) (xy 118.852062 -222.943577) (xy 118.827912 -222.894706)
			(xy 118.811492 -222.842724) (xy 118.803186 -222.788848) (xy 118.803187 -222.734335) (xy 118.811496 -222.680459)
			(xy 118.827919 -222.628479) (xy 118.852071 -222.579608) (xy 118.883389 -222.534989) (xy 118.921141 -222.495664)
			(xy 118.964445 -222.462552) (xy 119.012289 -222.436426) (xy 119.063557 -222.417896) (xy 119.090186 -222.412052)
			(xy 119.13108 -222.404178) (xy 119.13108 -221.491302) (xy 119.090186 -221.483428) (xy 119.063534 -221.477673)
			(xy 119.012254 -221.459148) (xy 118.964398 -221.433022) (xy 118.921084 -221.399907) (xy 118.883325 -221.360575)
			(xy 118.852003 -221.315947) (xy 118.827851 -221.267065) (xy 118.811432 -221.215073) (xy 118.803132 -221.161186)
			(xy 118.802658 -221.133924) (xy 118.803032 -221.110679) (xy 118.809073 -221.064582) (xy 118.821056 -221.019662)
			(xy 118.829582 -220.998034) (xy 118.839234 -220.97492) (xy 118.666768 -220.676216) (xy 118.641876 -220.672914)
			(xy 118.616517 -220.669107) (xy 118.567174 -220.655156) (xy 118.520341 -220.634273) (xy 118.476988 -220.606887)
			(xy 118.438012 -220.573567) (xy 118.404218 -220.535) (xy 118.376305 -220.491985) (xy 118.354851 -220.445411)
			(xy 118.3403 -220.396242) (xy 118.332951 -220.345493) (xy 118.332504 -220.319854) (xy 118.333056 -220.291874)
			(xy 118.341817 -220.236603) (xy 118.359116 -220.183383) (xy 118.384527 -220.133524) (xy 118.417424 -220.088253)
			(xy 118.456997 -220.048686) (xy 118.502273 -220.015796) (xy 118.552136 -219.990394) (xy 118.605359 -219.973104)
			(xy 118.660632 -219.964352) (xy 118.688612 -219.963746) (xy 118.713549 -219.964164) (xy 118.762937 -219.97112)
			(xy 118.810872 -219.984895) (xy 118.856417 -220.005219) (xy 118.898684 -220.031695) (xy 118.936847 -220.063807)
			(xy 118.953788 -220.08211) (xy 118.963202 -220.091969) (xy 118.986102 -220.106737) (xy 119.012093 -220.114923)
			(xy 119.039323 -220.115944) (xy 119.065854 -220.109727) (xy 119.089796 -220.096715) (xy 119.109445 -220.077835)
			(xy 119.123401 -220.054431) (xy 119.130671 -220.02817) (xy 119.13108 -220.014546) (xy 119.13108 -219.863416)
			(xy 119.090186 -219.855542) (xy 119.063534 -219.849781) (xy 119.012255 -219.831247) (xy 118.9644 -219.805115)
			(xy 118.921087 -219.771995) (xy 118.883326 -219.732661) (xy 118.852001 -219.688032) (xy 118.827844 -219.63915)
			(xy 118.811418 -219.587158) (xy 118.803107 -219.53327) (xy 118.803106 -219.478745) (xy 118.811414 -219.424856)
			(xy 118.827838 -219.372863) (xy 118.851994 -219.323981) (xy 118.883317 -219.27935) (xy 118.921076 -219.240015)
			(xy 118.964388 -219.206893) (xy 119.012242 -219.180759) (xy 119.06352 -219.162223) (xy 119.090186 -219.156534)
			(xy 119.13108 -219.14866) (xy 119.13108 -218.235784) (xy 119.090186 -218.22791) (xy 119.063534 -218.222155)
			(xy 119.012256 -218.20363) (xy 118.964402 -218.177504) (xy 118.921089 -218.144387) (xy 118.883332 -218.105055)
			(xy 118.852012 -218.060427) (xy 118.827862 -218.011546) (xy 118.811446 -217.959554) (xy 118.803148 -217.905667)
			(xy 118.802658 -217.878406) (xy 118.803033 -217.855161) (xy 118.809077 -217.809065) (xy 118.821062 -217.764146)
			(xy 118.829582 -217.742516) (xy 118.839234 -217.719402) (xy 118.666768 -217.420698) (xy 118.641876 -217.417396)
			(xy 118.616518 -217.413589) (xy 118.567175 -217.399638) (xy 118.520344 -217.378754) (xy 118.476993 -217.351368)
			(xy 118.438018 -217.318048) (xy 118.404226 -217.279481) (xy 118.376315 -217.236466) (xy 118.354863 -217.189892)
			(xy 118.340314 -217.140722) (xy 118.332968 -217.089974) (xy 118.332504 -217.064336) (xy 118.333022 -217.036349)
			(xy 118.341773 -216.981064) (xy 118.359066 -216.927829) (xy 118.384475 -216.877954) (xy 118.417373 -216.832669)
			(xy 118.456951 -216.793088) (xy 118.502234 -216.760187) (xy 118.552106 -216.734775) (xy 118.605341 -216.717479)
			(xy 118.660625 -216.708724) (xy 118.688612 -216.708228) (xy 118.71355 -216.708646) (xy 118.762937 -216.715602)
			(xy 118.810872 -216.729376) (xy 118.856419 -216.7497) (xy 118.898687 -216.776175) (xy 118.93685 -216.808285)
			(xy 118.953788 -216.826592) (xy 118.963201 -216.836452) (xy 118.9861 -216.851222) (xy 119.012091 -216.859409)
			(xy 119.039321 -216.860431) (xy 119.065852 -216.854214) (xy 119.089793 -216.841202) (xy 119.109441 -216.82232)
			(xy 119.123394 -216.798915) (xy 119.130661 -216.772652) (xy 119.13108 -216.759028) (xy 119.13108 -216.607898)
			(xy 119.090186 -216.600024) (xy 119.063535 -216.594263) (xy 119.012259 -216.57573) (xy 118.964407 -216.549598)
			(xy 118.921096 -216.51648) (xy 118.883338 -216.477147) (xy 118.852015 -216.43252) (xy 118.827859 -216.383641)
			(xy 118.811434 -216.331651) (xy 118.803124 -216.277765) (xy 118.803124 -216.223243) (xy 118.811432 -216.169357)
			(xy 118.827856 -216.117367) (xy 118.852011 -216.068487) (xy 118.883333 -216.023859) (xy 118.92109 -215.984526)
			(xy 118.9644 -215.951406) (xy 119.012252 -215.925274) (xy 119.063528 -215.906739) (xy 119.090186 -215.901016)
			(xy 119.13108 -215.893142) (xy 119.13108 -214.980266) (xy 119.089932 -214.972138) (xy 119.063266 -214.966398)
			(xy 119.011957 -214.947898) (xy 118.964069 -214.921788) (xy 118.920723 -214.888681) (xy 118.882935 -214.849349)
			(xy 118.851587 -214.804714) (xy 118.827413 -214.755821) (xy 118.81098 -214.703812) (xy 118.802671 -214.649906)
			(xy 118.80215 -214.622634) (xy 118.80269 -214.594818) (xy 118.811348 -214.539864) (xy 118.828443 -214.486923)
			(xy 118.840504 -214.461852) (xy 118.852442 -214.438484) (xy 118.668038 -214.08898) (xy 118.64213 -214.085678)
			(xy 118.61677 -214.081874) (xy 118.567422 -214.067929) (xy 118.520586 -214.047048) (xy 118.477229 -214.019664)
			(xy 118.43825 -213.986344) (xy 118.404453 -213.947776) (xy 118.37654 -213.904759) (xy 118.355086 -213.858182)
			(xy 118.340536 -213.80901) (xy 118.333191 -213.758258) (xy 118.332758 -213.732618) (xy 118.333306 -213.704633)
			(xy 118.342058 -213.649352) (xy 118.359351 -213.59612) (xy 118.384757 -213.546249) (xy 118.417653 -213.500966)
			(xy 118.457226 -213.461386) (xy 118.502504 -213.428485) (xy 118.552372 -213.403071) (xy 118.605601 -213.38577)
			(xy 118.660881 -213.37701) (xy 118.688866 -213.37651) (xy 118.713781 -213.376945) (xy 118.763122 -213.383925)
			(xy 118.811008 -213.397713) (xy 118.856505 -213.418038) (xy 118.898727 -213.444506) (xy 118.936849 -213.476598)
			(xy 118.953788 -213.494874) (xy 118.963211 -213.504744) (xy 118.986137 -213.519526) (xy 119.012158 -213.527709)
			(xy 119.039417 -213.52871) (xy 119.065969 -213.522457) (xy 119.089917 -213.509396) (xy 119.109552 -213.490461)
			(xy 119.123472 -213.467002) (xy 119.130683 -213.440695) (xy 119.13108 -213.427056) (xy 119.13108 -208.747868)
			(xy 129.5654 -198.313548) (xy 129.5654 -176.469548) (xy 129.4511 -176.355248) (xy 129.4511 -166.068248)
			(xy 112.9157 -149.532848) (xy 102.6287 -149.532848) (xy 87.6046 -134.508748) (xy 61.7728 -134.508748)
			(xy 61.53658 -134.744968) (xy 61.53658 -140.274548) (xy 75.950062 -140.274548) (xy 75.954133 -140.218926)
			(xy 75.966259 -140.164489) (xy 75.986182 -140.112398) (xy 76.013478 -140.063763) (xy 76.047564 -140.01962)
			(xy 76.087713 -139.980911) (xy 76.133071 -139.94846) (xy 76.182671 -139.922959) (xy 76.235455 -139.904952)
			(xy 76.290298 -139.894822) (xy 76.346032 -139.892785) (xy 76.401469 -139.898885) (xy 76.455426 -139.912991)
			(xy 76.506755 -139.934803) (xy 76.554361 -139.963857) (xy 76.597229 -139.999532) (xy 76.634446 -140.041069)
			(xy 76.665219 -140.087582) (xy 76.688891 -140.138079) (xy 76.704959 -140.191486) (xy 76.713079 -140.246662)
			(xy 76.713588 -140.274548) (xy 76.713079 -140.302434) (xy 76.704959 -140.35761) (xy 76.688891 -140.411017)
			(xy 76.665219 -140.461514) (xy 76.634446 -140.508027) (xy 76.597229 -140.549564) (xy 76.554361 -140.585239)
			(xy 76.506755 -140.614293) (xy 76.455426 -140.636105) (xy 76.401469 -140.650211) (xy 76.346032 -140.656311)
			(xy 76.290298 -140.654274) (xy 76.235455 -140.644144) (xy 76.182671 -140.626137) (xy 76.133071 -140.600636)
			(xy 76.087713 -140.568185) (xy 76.047564 -140.529476) (xy 76.013478 -140.485333) (xy 75.986182 -140.436698)
			(xy 75.966259 -140.384607) (xy 75.954133 -140.33017) (xy 75.950062 -140.274548) (xy 61.53658 -140.274548)
			(xy 61.53658 -142.01775) (xy 79.994758 -142.01775) (xy 79.998829 -141.962128) (xy 80.010955 -141.907691)
			(xy 80.030878 -141.8556) (xy 80.058174 -141.806965) (xy 80.09226 -141.762822) (xy 80.132409 -141.724113)
			(xy 80.177767 -141.691662) (xy 80.227367 -141.666161) (xy 80.280151 -141.648154) (xy 80.334994 -141.638024)
			(xy 80.390728 -141.635987) (xy 80.446165 -141.642087) (xy 80.500122 -141.656193) (xy 80.551451 -141.678005)
			(xy 80.599057 -141.707059) (xy 80.641925 -141.742734) (xy 80.679142 -141.784271) (xy 80.709915 -141.830784)
			(xy 80.733587 -141.881281) (xy 80.749655 -141.934688) (xy 80.757775 -141.989864) (xy 80.758284 -142.01775)
			(xy 80.757775 -142.045636) (xy 80.749655 -142.100812) (xy 80.733587 -142.154219) (xy 80.709915 -142.204716)
			(xy 80.679142 -142.251229) (xy 80.641925 -142.292766) (xy 80.599057 -142.328441) (xy 80.551451 -142.357495)
			(xy 80.500122 -142.379307) (xy 80.446165 -142.393413) (xy 80.390728 -142.399513) (xy 80.334994 -142.397476)
			(xy 80.280151 -142.387346) (xy 80.227367 -142.369339) (xy 80.177767 -142.343838) (xy 80.132409 -142.311387)
			(xy 80.09226 -142.272678) (xy 80.058174 -142.228535) (xy 80.030878 -142.1799) (xy 80.010955 -142.127809)
			(xy 79.998829 -142.073372) (xy 79.994758 -142.01775) (xy 61.53658 -142.01775) (xy 61.53658 -143.043148)
			(xy 62.203582 -143.043148) (xy 62.207653 -142.987526) (xy 62.219779 -142.933089) (xy 62.239702 -142.880998)
			(xy 62.266998 -142.832363) (xy 62.301084 -142.78822) (xy 62.341233 -142.749511) (xy 62.386591 -142.71706)
			(xy 62.436191 -142.691559) (xy 62.488975 -142.673552) (xy 62.543818 -142.663422) (xy 62.599552 -142.661385)
			(xy 62.654989 -142.667485) (xy 62.708946 -142.681591) (xy 62.760275 -142.703403) (xy 62.807881 -142.732457)
			(xy 62.850749 -142.768132) (xy 62.887966 -142.809669) (xy 62.918739 -142.856182) (xy 62.942411 -142.906679)
			(xy 62.958479 -142.960086) (xy 62.966599 -143.015262) (xy 62.967108 -143.043148) (xy 62.966599 -143.071034)
			(xy 62.958479 -143.12621) (xy 62.942411 -143.179617) (xy 62.918739 -143.230114) (xy 62.887966 -143.276627)
			(xy 62.850749 -143.318164) (xy 62.807881 -143.353839) (xy 62.760275 -143.382893) (xy 62.708946 -143.404705)
			(xy 62.654989 -143.418811) (xy 62.599552 -143.424911) (xy 62.543818 -143.422874) (xy 62.488975 -143.412744)
			(xy 62.436191 -143.394737) (xy 62.386591 -143.369236) (xy 62.341233 -143.336785) (xy 62.301084 -143.298076)
			(xy 62.266998 -143.253933) (xy 62.239702 -143.205298) (xy 62.219779 -143.153207) (xy 62.207653 -143.09877)
			(xy 62.203582 -143.043148) (xy 61.53658 -143.043148) (xy 61.53658 -144.665192) (xy 71.87641 -144.665192)
			(xy 71.880481 -144.60957) (xy 71.892607 -144.555133) (xy 71.91253 -144.503042) (xy 71.939826 -144.454407)
			(xy 71.973912 -144.410264) (xy 72.014061 -144.371555) (xy 72.059419 -144.339104) (xy 72.109019 -144.313603)
			(xy 72.161803 -144.295596) (xy 72.216646 -144.285466) (xy 72.27238 -144.283429) (xy 72.327817 -144.289529)
			(xy 72.381774 -144.303635) (xy 72.433103 -144.325447) (xy 72.480709 -144.354501) (xy 72.523577 -144.390176)
			(xy 72.560794 -144.431713) (xy 72.591567 -144.478226) (xy 72.615239 -144.528723) (xy 72.631307 -144.58213)
			(xy 72.637886 -144.626838) (xy 73.863962 -144.626838) (xy 73.86452 -144.586697) (xy 73.872942 -144.506858)
			(xy 73.889707 -144.428346) (xy 73.914629 -144.35203) (xy 73.947433 -144.278756) (xy 73.987755 -144.209335)
			(xy 74.035149 -144.144535) (xy 74.089089 -144.085074) (xy 74.14898 -144.031611) (xy 74.214157 -143.984737)
			(xy 74.248772 -143.964406) (xy 74.25648 -143.959614) (xy 74.268154 -143.945732) (xy 74.274263 -143.928654)
			(xy 74.274042 -143.910517) (xy 74.271124 -143.901922) (xy 74.262848 -143.879748) (xy 74.251218 -143.833868)
			(xy 74.245337 -143.786903) (xy 74.244962 -143.763238) (xy 74.245448 -143.735987) (xy 74.253204 -143.682039)
			(xy 74.268559 -143.629744) (xy 74.291201 -143.580167) (xy 74.320667 -143.534317) (xy 74.356358 -143.493126)
			(xy 74.397549 -143.457435) (xy 74.443399 -143.427969) (xy 74.492976 -143.405327) (xy 74.545271 -143.389972)
			(xy 74.599219 -143.382216) (xy 74.653721 -143.382216) (xy 74.707669 -143.389972) (xy 74.759964 -143.405327)
			(xy 74.809541 -143.427969) (xy 74.855391 -143.457435) (xy 74.896582 -143.493126) (xy 74.932273 -143.534317)
			(xy 74.961739 -143.580167) (xy 74.984381 -143.629744) (xy 74.999736 -143.682039) (xy 75.007492 -143.735987)
			(xy 75.007978 -143.763238) (xy 75.007605 -143.786904) (xy 75.001743 -143.833872) (xy 74.990101 -143.879751)
			(xy 74.981816 -143.901922) (xy 74.978874 -143.910506) (xy 74.978686 -143.928641) (xy 74.984804 -143.945714)
			(xy 74.996468 -143.959602) (xy 75.004168 -143.964406) (xy 75.038779 -143.984744) (xy 75.103951 -144.031624)
			(xy 75.163837 -144.085091) (xy 75.217776 -144.144553) (xy 75.265171 -144.209351) (xy 75.305497 -144.27877)
			(xy 75.338308 -144.35204) (xy 75.363241 -144.428352) (xy 75.38002 -144.506861) (xy 75.388459 -144.586697)
			(xy 75.388978 -144.626838) (xy 75.388489 -144.665483) (xy 75.384127 -144.708372) (xy 77.36408 -144.708372)
			(xy 77.368151 -144.65275) (xy 77.380277 -144.598313) (xy 77.4002 -144.546222) (xy 77.427496 -144.497587)
			(xy 77.461582 -144.453444) (xy 77.501731 -144.414735) (xy 77.547089 -144.382284) (xy 77.596689 -144.356783)
			(xy 77.649473 -144.338776) (xy 77.704316 -144.328646) (xy 77.76005 -144.326609) (xy 77.815487 -144.332709)
			(xy 77.869444 -144.346815) (xy 77.920773 -144.368627) (xy 77.968379 -144.397681) (xy 78.011247 -144.433356)
			(xy 78.048464 -144.474893) (xy 78.079237 -144.521406) (xy 78.102909 -144.571903) (xy 78.118977 -144.62531)
			(xy 78.127097 -144.680486) (xy 78.127606 -144.708372) (xy 78.127097 -144.736258) (xy 78.118977 -144.791434)
			(xy 78.102909 -144.844841) (xy 78.079237 -144.895338) (xy 78.048464 -144.941851) (xy 78.011247 -144.983388)
			(xy 77.968379 -145.019063) (xy 77.920773 -145.048117) (xy 77.869444 -145.069929) (xy 77.815487 -145.084035)
			(xy 77.76005 -145.090135) (xy 77.704316 -145.088098) (xy 77.649473 -145.077968) (xy 77.596689 -145.059961)
			(xy 77.547089 -145.03446) (xy 77.501731 -145.002009) (xy 77.461582 -144.9633) (xy 77.427496 -144.919157)
			(xy 77.4002 -144.870522) (xy 77.380277 -144.818431) (xy 77.368151 -144.763994) (xy 77.36408 -144.708372)
			(xy 75.384127 -144.708372) (xy 75.380669 -144.742377) (xy 75.365111 -144.818085) (xy 75.341973 -144.891831)
			(xy 75.311493 -144.962858) (xy 75.273984 -145.030436) (xy 75.22983 -145.093874) (xy 75.179485 -145.152518)
			(xy 75.123466 -145.205769) (xy 75.062347 -145.253079) (xy 74.996754 -145.293963) (xy 74.927363 -145.328001)
			(xy 74.854883 -145.354844) (xy 74.797166 -145.369788) (xy 80.354422 -145.369788) (xy 80.358493 -145.314166)
			(xy 80.370619 -145.259729) (xy 80.390542 -145.207638) (xy 80.417838 -145.159003) (xy 80.451924 -145.11486)
			(xy 80.492073 -145.076151) (xy 80.537431 -145.0437) (xy 80.587031 -145.018199) (xy 80.639815 -145.000192)
			(xy 80.694658 -144.990062) (xy 80.750392 -144.988025) (xy 80.805829 -144.994125) (xy 80.859786 -145.008231)
			(xy 80.911115 -145.030043) (xy 80.958721 -145.059097) (xy 81.001589 -145.094772) (xy 81.038806 -145.136309)
			(xy 81.069579 -145.182822) (xy 81.093251 -145.233319) (xy 81.109319 -145.286726) (xy 81.117439 -145.341902)
			(xy 81.117948 -145.369788) (xy 81.117439 -145.397674) (xy 81.109319 -145.45285) (xy 81.093251 -145.506257)
			(xy 81.069579 -145.556754) (xy 81.038806 -145.603267) (xy 81.001589 -145.644804) (xy 80.958721 -145.680479)
			(xy 80.911115 -145.709533) (xy 80.859786 -145.731345) (xy 80.805829 -145.745451) (xy 80.750392 -145.751551)
			(xy 80.694658 -145.749514) (xy 80.639815 -145.739384) (xy 80.587031 -145.721377) (xy 80.537431 -145.695876)
			(xy 80.492073 -145.663425) (xy 80.451924 -145.624716) (xy 80.417838 -145.580573) (xy 80.390542 -145.531938)
			(xy 80.370619 -145.479847) (xy 80.358493 -145.42541) (xy 80.354422 -145.369788) (xy 74.797166 -145.369788)
			(xy 74.78006 -145.374217) (xy 74.703661 -145.385921) (xy 74.62647 -145.389836) (xy 74.549279 -145.385921)
			(xy 74.47288 -145.374217) (xy 74.398057 -145.354844) (xy 74.325577 -145.328001) (xy 74.256186 -145.293963)
			(xy 74.190593 -145.253079) (xy 74.129474 -145.205769) (xy 74.073455 -145.152518) (xy 74.02311 -145.093874)
			(xy 73.978956 -145.030436) (xy 73.941447 -144.962858) (xy 73.910967 -144.891831) (xy 73.887829 -144.818085)
			(xy 73.872271 -144.742377) (xy 73.864451 -144.665483) (xy 73.863962 -144.626838) (xy 72.637886 -144.626838)
			(xy 72.639427 -144.637306) (xy 72.639936 -144.665192) (xy 72.639427 -144.693078) (xy 72.631307 -144.748254)
			(xy 72.615239 -144.801661) (xy 72.591567 -144.852158) (xy 72.560794 -144.898671) (xy 72.523577 -144.940208)
			(xy 72.480709 -144.975883) (xy 72.433103 -145.004937) (xy 72.381774 -145.026749) (xy 72.327817 -145.040855)
			(xy 72.27238 -145.046955) (xy 72.216646 -145.044918) (xy 72.161803 -145.034788) (xy 72.109019 -145.016781)
			(xy 72.059419 -144.99128) (xy 72.014061 -144.958829) (xy 71.973912 -144.92012) (xy 71.939826 -144.875977)
			(xy 71.91253 -144.827342) (xy 71.892607 -144.775251) (xy 71.880481 -144.720814) (xy 71.87641 -144.665192)
			(xy 61.53658 -144.665192) (xy 61.53658 -144.703546) (xy 61.550125 -144.726281) (xy 61.571501 -144.774693)
			(xy 61.585984 -144.825593) (xy 61.593299 -144.878006) (xy 61.593303 -144.930926) (xy 61.585998 -144.983341)
			(xy 61.571524 -145.034243) (xy 61.550157 -145.082659) (xy 61.53658 -145.105374) (xy 61.53658 -146.228308)
			(xy 69.007995 -146.228308) (xy 69.012017 -146.142588) (xy 69.024048 -146.05762) (xy 69.043984 -145.974153)
			(xy 69.071647 -145.892919) (xy 69.106796 -145.814633) (xy 69.149122 -145.739982) (xy 69.198251 -145.669623)
			(xy 69.253754 -145.604173) (xy 69.315141 -145.544209) (xy 69.381874 -145.490256) (xy 69.453366 -145.442789)
			(xy 69.528988 -145.402225) (xy 69.608077 -145.368921) (xy 69.689937 -145.343169) (xy 69.773848 -145.325196)
			(xy 69.859074 -145.31516) (xy 69.944866 -145.313148) (xy 70.030468 -145.319179) (xy 70.11513 -145.333199)
			(xy 70.198107 -145.355085) (xy 70.27867 -145.384646) (xy 70.35611 -145.42162) (xy 70.429749 -145.465684)
			(xy 70.498937 -145.51645) (xy 70.563068 -145.573471) (xy 70.621577 -145.636247) (xy 70.67395 -145.704227)
			(xy 70.719728 -145.776812) (xy 70.758508 -145.853364) (xy 70.789949 -145.933212) (xy 70.813775 -146.015653)
			(xy 70.829776 -146.099963) (xy 70.837811 -146.185401) (xy 70.838314 -146.228308) (xy 70.837811 -146.271215)
			(xy 70.829776 -146.356653) (xy 70.813775 -146.440963) (xy 70.789949 -146.523404) (xy 70.758508 -146.603252)
			(xy 70.719728 -146.679804) (xy 70.69114 -146.725132) (xy 77.84668 -146.725132) (xy 77.850751 -146.66951)
			(xy 77.862877 -146.615073) (xy 77.8828 -146.562982) (xy 77.910096 -146.514347) (xy 77.944182 -146.470204)
			(xy 77.984331 -146.431495) (xy 78.029689 -146.399044) (xy 78.079289 -146.373543) (xy 78.132073 -146.355536)
			(xy 78.186916 -146.345406) (xy 78.24265 -146.343369) (xy 78.298087 -146.349469) (xy 78.352044 -146.363575)
			(xy 78.403373 -146.385387) (xy 78.450979 -146.414441) (xy 78.493847 -146.450116) (xy 78.531064 -146.491653)
			(xy 78.561837 -146.538166) (xy 78.585509 -146.588663) (xy 78.601577 -146.64207) (xy 78.609697 -146.697246)
			(xy 78.610206 -146.725132) (xy 78.609697 -146.753018) (xy 78.601577 -146.808194) (xy 78.585509 -146.861601)
			(xy 78.577565 -146.878548) (xy 79.902302 -146.878548) (xy 79.906373 -146.822926) (xy 79.918499 -146.768489)
			(xy 79.938422 -146.716398) (xy 79.965718 -146.667763) (xy 79.999804 -146.62362) (xy 80.039953 -146.584911)
			(xy 80.085311 -146.55246) (xy 80.134911 -146.526959) (xy 80.187695 -146.508952) (xy 80.242538 -146.498822)
			(xy 80.298272 -146.496785) (xy 80.353709 -146.502885) (xy 80.407666 -146.516991) (xy 80.458995 -146.538803)
			(xy 80.506601 -146.567857) (xy 80.549469 -146.603532) (xy 80.586686 -146.645069) (xy 80.617459 -146.691582)
			(xy 80.633187 -146.725132) (xy 80.776062 -146.725132) (xy 80.780133 -146.66951) (xy 80.792259 -146.615073)
			(xy 80.812182 -146.562982) (xy 80.839478 -146.514347) (xy 80.873564 -146.470204) (xy 80.913713 -146.431495)
			(xy 80.959071 -146.399044) (xy 81.008671 -146.373543) (xy 81.061455 -146.355536) (xy 81.116298 -146.345406)
			(xy 81.172032 -146.343369) (xy 81.227469 -146.349469) (xy 81.281426 -146.363575) (xy 81.332755 -146.385387)
			(xy 81.380361 -146.414441) (xy 81.423229 -146.450116) (xy 81.460446 -146.491653) (xy 81.491219 -146.538166)
			(xy 81.514891 -146.588663) (xy 81.530959 -146.64207) (xy 81.539079 -146.697246) (xy 81.539588 -146.725132)
			(xy 81.539079 -146.753018) (xy 81.530959 -146.808194) (xy 81.514891 -146.861601) (xy 81.491219 -146.912098)
			(xy 81.460446 -146.958611) (xy 81.423229 -147.000148) (xy 81.380361 -147.035823) (xy 81.332755 -147.064877)
			(xy 81.281426 -147.086689) (xy 81.227469 -147.100795) (xy 81.172032 -147.106895) (xy 81.116298 -147.104858)
			(xy 81.061455 -147.094728) (xy 81.008671 -147.076721) (xy 80.959071 -147.05122) (xy 80.913713 -147.018769)
			(xy 80.873564 -146.98006) (xy 80.839478 -146.935917) (xy 80.812182 -146.887282) (xy 80.792259 -146.835191)
			(xy 80.780133 -146.780754) (xy 80.776062 -146.725132) (xy 80.633187 -146.725132) (xy 80.641131 -146.742079)
			(xy 80.657199 -146.795486) (xy 80.665319 -146.850662) (xy 80.665828 -146.878548) (xy 80.665319 -146.906434)
			(xy 80.657199 -146.96161) (xy 80.641131 -147.015017) (xy 80.617459 -147.065514) (xy 80.586686 -147.112027)
			(xy 80.549469 -147.153564) (xy 80.506601 -147.189239) (xy 80.458995 -147.218293) (xy 80.407666 -147.240105)
			(xy 80.353709 -147.254211) (xy 80.298272 -147.260311) (xy 80.242538 -147.258274) (xy 80.187695 -147.248144)
			(xy 80.134911 -147.230137) (xy 80.085311 -147.204636) (xy 80.039953 -147.172185) (xy 79.999804 -147.133476)
			(xy 79.965718 -147.089333) (xy 79.938422 -147.040698) (xy 79.918499 -146.988607) (xy 79.906373 -146.93417)
			(xy 79.902302 -146.878548) (xy 78.577565 -146.878548) (xy 78.561837 -146.912098) (xy 78.531064 -146.958611)
			(xy 78.493847 -147.000148) (xy 78.450979 -147.035823) (xy 78.403373 -147.064877) (xy 78.352044 -147.086689)
			(xy 78.298087 -147.100795) (xy 78.24265 -147.106895) (xy 78.186916 -147.104858) (xy 78.132073 -147.094728)
			(xy 78.079289 -147.076721) (xy 78.029689 -147.05122) (xy 77.984331 -147.018769) (xy 77.944182 -146.98006)
			(xy 77.910096 -146.935917) (xy 77.8828 -146.887282) (xy 77.862877 -146.835191) (xy 77.850751 -146.780754)
			(xy 77.84668 -146.725132) (xy 70.69114 -146.725132) (xy 70.67395 -146.752389) (xy 70.621577 -146.820369)
			(xy 70.563068 -146.883145) (xy 70.498937 -146.940166) (xy 70.429749 -146.990932) (xy 70.35611 -147.034996)
			(xy 70.27867 -147.07197) (xy 70.198107 -147.101531) (xy 70.11513 -147.123417) (xy 70.030468 -147.137437)
			(xy 69.944866 -147.143468) (xy 69.859074 -147.141456) (xy 69.773848 -147.13142) (xy 69.689937 -147.113447)
			(xy 69.608077 -147.087695) (xy 69.528988 -147.054391) (xy 69.453366 -147.013827) (xy 69.381874 -146.96636)
			(xy 69.315141 -146.912407) (xy 69.253754 -146.852443) (xy 69.198251 -146.786993) (xy 69.149122 -146.716634)
			(xy 69.106796 -146.641983) (xy 69.071647 -146.563697) (xy 69.043984 -146.482463) (xy 69.024048 -146.398996)
			(xy 69.012017 -146.314028) (xy 69.007995 -146.228308) (xy 61.53658 -146.228308) (xy 61.53658 -148.270652)
			(xy 69.034402 -148.270652) (xy 69.034402 -148.185956) (xy 69.042453 -148.101642) (xy 69.058482 -148.018476)
			(xy 69.082343 -147.937209) (xy 69.113822 -147.858579) (xy 69.152633 -147.783298) (xy 69.198423 -147.712046)
			(xy 69.250779 -147.64547) (xy 69.309227 -147.584172) (xy 69.373237 -147.528707) (xy 69.442229 -147.479578)
			(xy 69.515579 -147.437229) (xy 69.592622 -147.402045) (xy 69.672661 -147.374343) (xy 69.75497 -147.354375)
			(xy 69.838805 -147.342322) (xy 69.923406 -147.338292) (xy 70.008007 -147.342322) (xy 70.091842 -147.354375)
			(xy 70.174151 -147.374343) (xy 70.25419 -147.402045) (xy 70.331233 -147.437229) (xy 70.404583 -147.479578)
			(xy 70.473575 -147.528707) (xy 70.537585 -147.584172) (xy 70.596033 -147.64547) (xy 70.648389 -147.712046)
			(xy 70.694179 -147.783298) (xy 70.73299 -147.858579) (xy 70.764469 -147.937209) (xy 70.781476 -147.995132)
			(xy 80.776062 -147.995132) (xy 80.780133 -147.93951) (xy 80.792259 -147.885073) (xy 80.812182 -147.832982)
			(xy 80.839478 -147.784347) (xy 80.873564 -147.740204) (xy 80.913713 -147.701495) (xy 80.959071 -147.669044)
			(xy 81.008671 -147.643543) (xy 81.061455 -147.625536) (xy 81.116298 -147.615406) (xy 81.172032 -147.613369)
			(xy 81.227469 -147.619469) (xy 81.281426 -147.633575) (xy 81.332755 -147.655387) (xy 81.380361 -147.684441)
			(xy 81.423229 -147.720116) (xy 81.460446 -147.761653) (xy 81.491219 -147.808166) (xy 81.514891 -147.858663)
			(xy 81.530959 -147.91207) (xy 81.539079 -147.967246) (xy 81.539588 -147.995132) (xy 81.539079 -148.023018)
			(xy 81.530959 -148.078194) (xy 81.514891 -148.131601) (xy 81.491219 -148.182098) (xy 81.460446 -148.228611)
			(xy 81.423229 -148.270148) (xy 81.380361 -148.305823) (xy 81.332755 -148.334877) (xy 81.281426 -148.356689)
			(xy 81.227469 -148.370795) (xy 81.172032 -148.376895) (xy 81.116298 -148.374858) (xy 81.061455 -148.364728)
			(xy 81.008671 -148.346721) (xy 80.959071 -148.32122) (xy 80.913713 -148.288769) (xy 80.873564 -148.25006)
			(xy 80.839478 -148.205917) (xy 80.812182 -148.157282) (xy 80.792259 -148.105191) (xy 80.780133 -148.050754)
			(xy 80.776062 -147.995132) (xy 70.781476 -147.995132) (xy 70.78833 -148.018476) (xy 70.804359 -148.101642)
			(xy 70.81241 -148.185956) (xy 70.812914 -148.228304) (xy 70.81241 -148.270652) (xy 70.804359 -148.354966)
			(xy 70.78833 -148.438132) (xy 70.764469 -148.519399) (xy 70.73299 -148.598029) (xy 70.716439 -148.630132)
			(xy 77.9559 -148.630132) (xy 77.959971 -148.57451) (xy 77.972097 -148.520073) (xy 77.99202 -148.467982)
			(xy 78.019316 -148.419347) (xy 78.053402 -148.375204) (xy 78.093551 -148.336495) (xy 78.138909 -148.304044)
			(xy 78.188509 -148.278543) (xy 78.241293 -148.260536) (xy 78.296136 -148.250406) (xy 78.35187 -148.248369)
			(xy 78.407307 -148.254469) (xy 78.461264 -148.268575) (xy 78.512593 -148.290387) (xy 78.560199 -148.319441)
			(xy 78.603067 -148.355116) (xy 78.640284 -148.396653) (xy 78.671057 -148.443166) (xy 78.694729 -148.493663)
			(xy 78.710797 -148.54707) (xy 78.718917 -148.602246) (xy 78.719426 -148.630132) (xy 78.718917 -148.658018)
			(xy 78.718386 -148.661628) (xy 79.424782 -148.661628) (xy 79.428853 -148.606006) (xy 79.440979 -148.551569)
			(xy 79.460902 -148.499478) (xy 79.488198 -148.450843) (xy 79.522284 -148.4067) (xy 79.562433 -148.367991)
			(xy 79.607791 -148.33554) (xy 79.657391 -148.310039) (xy 79.710175 -148.292032) (xy 79.765018 -148.281902)
			(xy 79.820752 -148.279865) (xy 79.876189 -148.285965) (xy 79.930146 -148.300071) (xy 79.981475 -148.321883)
			(xy 80.029081 -148.350937) (xy 80.071949 -148.386612) (xy 80.109166 -148.428149) (xy 80.139939 -148.474662)
			(xy 80.163611 -148.525159) (xy 80.179679 -148.578566) (xy 80.187799 -148.633742) (xy 80.188308 -148.661628)
			(xy 80.187799 -148.689514) (xy 80.179679 -148.74469) (xy 80.163611 -148.798097) (xy 80.139939 -148.848594)
			(xy 80.109166 -148.895107) (xy 80.071949 -148.936644) (xy 80.029081 -148.972319) (xy 79.981475 -149.001373)
			(xy 79.930146 -149.023185) (xy 79.876189 -149.037291) (xy 79.820752 -149.043391) (xy 79.765018 -149.041354)
			(xy 79.710175 -149.031224) (xy 79.657391 -149.013217) (xy 79.607791 -148.987716) (xy 79.562433 -148.955265)
			(xy 79.522284 -148.916556) (xy 79.488198 -148.872413) (xy 79.460902 -148.823778) (xy 79.440979 -148.771687)
			(xy 79.428853 -148.71725) (xy 79.424782 -148.661628) (xy 78.718386 -148.661628) (xy 78.710797 -148.713194)
			(xy 78.694729 -148.766601) (xy 78.671057 -148.817098) (xy 78.640284 -148.863611) (xy 78.603067 -148.905148)
			(xy 78.560199 -148.940823) (xy 78.512593 -148.969877) (xy 78.461264 -148.991689) (xy 78.407307 -149.005795)
			(xy 78.35187 -149.011895) (xy 78.296136 -149.009858) (xy 78.241293 -148.999728) (xy 78.188509 -148.981721)
			(xy 78.138909 -148.95622) (xy 78.093551 -148.923769) (xy 78.053402 -148.88506) (xy 78.019316 -148.840917)
			(xy 77.99202 -148.792282) (xy 77.972097 -148.740191) (xy 77.959971 -148.685754) (xy 77.9559 -148.630132)
			(xy 70.716439 -148.630132) (xy 70.694179 -148.67331) (xy 70.648389 -148.744562) (xy 70.596033 -148.811138)
			(xy 70.537585 -148.872436) (xy 70.473575 -148.927901) (xy 70.404583 -148.97703) (xy 70.331233 -149.019379)
			(xy 70.25419 -149.054563) (xy 70.174151 -149.082265) (xy 70.091842 -149.102233) (xy 70.008007 -149.114286)
			(xy 69.923406 -149.118317) (xy 69.838805 -149.114286) (xy 69.75497 -149.102233) (xy 69.672661 -149.082265)
			(xy 69.592622 -149.054563) (xy 69.515579 -149.019379) (xy 69.442229 -148.97703) (xy 69.373237 -148.927901)
			(xy 69.309227 -148.872436) (xy 69.250779 -148.811138) (xy 69.198423 -148.744562) (xy 69.152633 -148.67331)
			(xy 69.113822 -148.598029) (xy 69.082343 -148.519399) (xy 69.058482 -148.438132) (xy 69.042453 -148.354966)
			(xy 69.034402 -148.270652) (xy 61.53658 -148.270652) (xy 61.53658 -149.32406) (xy 75.309982 -149.32406)
			(xy 75.314053 -149.268438) (xy 75.326179 -149.214001) (xy 75.346102 -149.16191) (xy 75.373398 -149.113275)
			(xy 75.407484 -149.069132) (xy 75.447633 -149.030423) (xy 75.492991 -148.997972) (xy 75.542591 -148.972471)
			(xy 75.595375 -148.954464) (xy 75.650218 -148.944334) (xy 75.705952 -148.942297) (xy 75.761389 -148.948397)
			(xy 75.815346 -148.962503) (xy 75.866675 -148.984315) (xy 75.914281 -149.013369) (xy 75.957149 -149.049044)
			(xy 75.994366 -149.090581) (xy 76.025139 -149.137094) (xy 76.048811 -149.187591) (xy 76.064879 -149.240998)
			(xy 76.072999 -149.296174) (xy 76.073508 -149.32406) (xy 76.072999 -149.351946) (xy 76.064879 -149.407122)
			(xy 76.048811 -149.460529) (xy 76.025139 -149.511026) (xy 76.016919 -149.52345) (xy 78.86776 -149.52345)
			(xy 78.871831 -149.467828) (xy 78.883957 -149.413391) (xy 78.90388 -149.3613) (xy 78.931176 -149.312665)
			(xy 78.965262 -149.268522) (xy 79.005411 -149.229813) (xy 79.050769 -149.197362) (xy 79.100369 -149.171861)
			(xy 79.153153 -149.153854) (xy 79.207996 -149.143724) (xy 79.26373 -149.141687) (xy 79.319167 -149.147787)
			(xy 79.373124 -149.161893) (xy 79.424453 -149.183705) (xy 79.472059 -149.212759) (xy 79.514927 -149.248434)
			(xy 79.523971 -149.258528) (xy 80.532222 -149.258528) (xy 80.536293 -149.202906) (xy 80.548419 -149.148469)
			(xy 80.568342 -149.096378) (xy 80.595638 -149.047743) (xy 80.629724 -149.0036) (xy 80.669873 -148.964891)
			(xy 80.715231 -148.93244) (xy 80.764831 -148.906939) (xy 80.817615 -148.888932) (xy 80.872458 -148.878802)
			(xy 80.928192 -148.876765) (xy 80.983629 -148.882865) (xy 81.037586 -148.896971) (xy 81.088915 -148.918783)
			(xy 81.136521 -148.947837) (xy 81.179389 -148.983512) (xy 81.216606 -149.025049) (xy 81.247379 -149.071562)
			(xy 81.271051 -149.122059) (xy 81.287119 -149.175466) (xy 81.295239 -149.230642) (xy 81.295748 -149.258528)
			(xy 81.295239 -149.286414) (xy 81.287119 -149.34159) (xy 81.271051 -149.394997) (xy 81.247379 -149.445494)
			(xy 81.216606 -149.492007) (xy 81.179389 -149.533544) (xy 81.136521 -149.569219) (xy 81.088915 -149.598273)
			(xy 81.037586 -149.620085) (xy 80.983629 -149.634191) (xy 80.928192 -149.640291) (xy 80.872458 -149.638254)
			(xy 80.817615 -149.628124) (xy 80.764831 -149.610117) (xy 80.715231 -149.584616) (xy 80.669873 -149.552165)
			(xy 80.629724 -149.513456) (xy 80.595638 -149.469313) (xy 80.568342 -149.420678) (xy 80.548419 -149.368587)
			(xy 80.536293 -149.31415) (xy 80.532222 -149.258528) (xy 79.523971 -149.258528) (xy 79.552144 -149.289971)
			(xy 79.582917 -149.336484) (xy 79.606589 -149.386981) (xy 79.622657 -149.440388) (xy 79.630777 -149.495564)
			(xy 79.631286 -149.52345) (xy 79.630777 -149.551336) (xy 79.622657 -149.606512) (xy 79.606589 -149.659919)
			(xy 79.582917 -149.710416) (xy 79.552144 -149.756929) (xy 79.514927 -149.798466) (xy 79.472059 -149.834141)
			(xy 79.424453 -149.863195) (xy 79.373124 -149.885007) (xy 79.319167 -149.899113) (xy 79.26373 -149.905213)
			(xy 79.207996 -149.903176) (xy 79.153153 -149.893046) (xy 79.100369 -149.875039) (xy 79.050769 -149.849538)
			(xy 79.005411 -149.817087) (xy 78.965262 -149.778378) (xy 78.931176 -149.734235) (xy 78.90388 -149.6856)
			(xy 78.883957 -149.633509) (xy 78.871831 -149.579072) (xy 78.86776 -149.52345) (xy 76.016919 -149.52345)
			(xy 75.994366 -149.557539) (xy 75.957149 -149.599076) (xy 75.914281 -149.634751) (xy 75.866675 -149.663805)
			(xy 75.815346 -149.685617) (xy 75.761389 -149.699723) (xy 75.705952 -149.705823) (xy 75.650218 -149.703786)
			(xy 75.595375 -149.693656) (xy 75.542591 -149.675649) (xy 75.492991 -149.650148) (xy 75.447633 -149.617697)
			(xy 75.407484 -149.578988) (xy 75.373398 -149.534845) (xy 75.346102 -149.48621) (xy 75.326179 -149.434119)
			(xy 75.314053 -149.379682) (xy 75.309982 -149.32406) (xy 61.53658 -149.32406) (xy 61.53658 -150.43277)
			(xy 77.96352 -150.43277) (xy 77.967591 -150.377148) (xy 77.979717 -150.322711) (xy 77.99964 -150.27062)
			(xy 78.026936 -150.221985) (xy 78.061022 -150.177842) (xy 78.101171 -150.139133) (xy 78.146529 -150.106682)
			(xy 78.196129 -150.081181) (xy 78.248913 -150.063174) (xy 78.303756 -150.053044) (xy 78.35949 -150.051007)
			(xy 78.414927 -150.057107) (xy 78.468884 -150.071213) (xy 78.520213 -150.093025) (xy 78.567819 -150.122079)
			(xy 78.610687 -150.157754) (xy 78.647904 -150.199291) (xy 78.678677 -150.245804) (xy 78.702349 -150.296301)
			(xy 78.718417 -150.349708) (xy 78.726537 -150.404884) (xy 78.727046 -150.43277) (xy 78.726537 -150.460656)
			(xy 78.718417 -150.515832) (xy 78.702905 -150.56739) (xy 79.91424 -150.56739) (xy 79.918311 -150.511768)
			(xy 79.930437 -150.457331) (xy 79.95036 -150.40524) (xy 79.977656 -150.356605) (xy 80.011742 -150.312462)
			(xy 80.051891 -150.273753) (xy 80.097249 -150.241302) (xy 80.146849 -150.215801) (xy 80.199633 -150.197794)
			(xy 80.254476 -150.187664) (xy 80.31021 -150.185627) (xy 80.365647 -150.191727) (xy 80.419604 -150.205833)
			(xy 80.470933 -150.227645) (xy 80.518539 -150.256699) (xy 80.561407 -150.292374) (xy 80.598624 -150.333911)
			(xy 80.629397 -150.380424) (xy 80.653069 -150.430921) (xy 80.669137 -150.484328) (xy 80.677257 -150.539504)
			(xy 80.677766 -150.56739) (xy 80.677257 -150.595276) (xy 80.669137 -150.650452) (xy 80.653069 -150.703859)
			(xy 80.629397 -150.754356) (xy 80.598624 -150.800869) (xy 80.561407 -150.842406) (xy 80.518539 -150.878081)
			(xy 80.470933 -150.907135) (xy 80.419604 -150.928947) (xy 80.365647 -150.943053) (xy 80.31021 -150.949153)
			(xy 80.254476 -150.947116) (xy 80.199633 -150.936986) (xy 80.146849 -150.918979) (xy 80.097249 -150.893478)
			(xy 80.051891 -150.861027) (xy 80.011742 -150.822318) (xy 79.977656 -150.778175) (xy 79.95036 -150.72954)
			(xy 79.930437 -150.677449) (xy 79.918311 -150.623012) (xy 79.91424 -150.56739) (xy 78.702905 -150.56739)
			(xy 78.702349 -150.569239) (xy 78.678677 -150.619736) (xy 78.647904 -150.666249) (xy 78.610687 -150.707786)
			(xy 78.567819 -150.743461) (xy 78.520213 -150.772515) (xy 78.468884 -150.794327) (xy 78.414927 -150.808433)
			(xy 78.35949 -150.814533) (xy 78.303756 -150.812496) (xy 78.248913 -150.802366) (xy 78.196129 -150.784359)
			(xy 78.146529 -150.758858) (xy 78.101171 -150.726407) (xy 78.061022 -150.687698) (xy 78.026936 -150.643555)
			(xy 77.99964 -150.59492) (xy 77.979717 -150.542829) (xy 77.967591 -150.488392) (xy 77.96352 -150.43277)
			(xy 61.53658 -150.43277) (xy 61.53658 -150.730966) (xy 61.550124 -150.753701) (xy 61.571497 -150.802112)
			(xy 61.585978 -150.853012) (xy 61.593289 -150.905423) (xy 61.593292 -150.958343) (xy 61.585985 -151.010755)
			(xy 61.571508 -151.061656) (xy 61.55014 -151.110069) (xy 61.53658 -151.132794) (xy 61.53658 -151.391366)
			(xy 61.550124 -151.414101) (xy 61.571497 -151.462512) (xy 61.585978 -151.513412) (xy 61.593289 -151.565823)
			(xy 61.593292 -151.618743) (xy 61.585985 -151.671155) (xy 61.571508 -151.722056) (xy 61.55014 -151.770469)
			(xy 61.53658 -151.793194) (xy 61.53658 -152.364694) (xy 69.007995 -152.364694) (xy 69.012017 -152.278974)
			(xy 69.024048 -152.194006) (xy 69.043984 -152.110539) (xy 69.071647 -152.029305) (xy 69.106796 -151.951019)
			(xy 69.149122 -151.876368) (xy 69.198251 -151.806009) (xy 69.253754 -151.740559) (xy 69.315141 -151.680595)
			(xy 69.381874 -151.626642) (xy 69.453366 -151.579175) (xy 69.528988 -151.538611) (xy 69.608077 -151.505307)
			(xy 69.689937 -151.479555) (xy 69.773848 -151.461582) (xy 69.859074 -151.451546) (xy 69.944866 -151.449534)
			(xy 70.030468 -151.455565) (xy 70.11513 -151.469585) (xy 70.198107 -151.491471) (xy 70.27867 -151.521032)
			(xy 70.35611 -151.558006) (xy 70.429749 -151.60207) (xy 70.498937 -151.652836) (xy 70.563068 -151.709857)
			(xy 70.621577 -151.772633) (xy 70.67395 -151.840613) (xy 70.719728 -151.913198) (xy 70.758508 -151.98975)
			(xy 70.789949 -152.069598) (xy 70.794559 -152.085548) (xy 78.820262 -152.085548) (xy 78.824333 -152.029926)
			(xy 78.836459 -151.975489) (xy 78.856382 -151.923398) (xy 78.883678 -151.874763) (xy 78.917764 -151.83062)
			(xy 78.957913 -151.791911) (xy 79.003271 -151.75946) (xy 79.052871 -151.733959) (xy 79.105655 -151.715952)
			(xy 79.160498 -151.705822) (xy 79.216232 -151.703785) (xy 79.271669 -151.709885) (xy 79.325626 -151.723991)
			(xy 79.376955 -151.745803) (xy 79.424561 -151.774857) (xy 79.467429 -151.810532) (xy 79.504646 -151.852069)
			(xy 79.535419 -151.898582) (xy 79.559091 -151.949079) (xy 79.575159 -152.002486) (xy 79.583279 -152.057662)
			(xy 79.583788 -152.085548) (xy 79.583279 -152.113434) (xy 79.575159 -152.16861) (xy 79.559091 -152.222017)
			(xy 79.535419 -152.272514) (xy 79.504646 -152.319027) (xy 79.467429 -152.360564) (xy 79.424561 -152.396239)
			(xy 79.376955 -152.425293) (xy 79.325626 -152.447105) (xy 79.271669 -152.461211) (xy 79.216232 -152.467311)
			(xy 79.160498 -152.465274) (xy 79.105655 -152.455144) (xy 79.052871 -152.437137) (xy 79.003271 -152.411636)
			(xy 78.957913 -152.379185) (xy 78.917764 -152.340476) (xy 78.883678 -152.296333) (xy 78.856382 -152.247698)
			(xy 78.836459 -152.195607) (xy 78.824333 -152.14117) (xy 78.820262 -152.085548) (xy 70.794559 -152.085548)
			(xy 70.813775 -152.152039) (xy 70.829776 -152.236349) (xy 70.837811 -152.321787) (xy 70.838314 -152.364694)
			(xy 70.837811 -152.407601) (xy 70.829776 -152.493039) (xy 70.813775 -152.577349) (xy 70.789949 -152.65979)
			(xy 70.758508 -152.739638) (xy 70.719728 -152.81619) (xy 70.67395 -152.888775) (xy 70.621577 -152.956755)
			(xy 70.613753 -152.96515) (xy 77.378558 -152.96515) (xy 77.382629 -152.909528) (xy 77.394755 -152.855091)
			(xy 77.414678 -152.803) (xy 77.441974 -152.754365) (xy 77.47606 -152.710222) (xy 77.516209 -152.671513)
			(xy 77.561567 -152.639062) (xy 77.611167 -152.613561) (xy 77.663951 -152.595554) (xy 77.718794 -152.585424)
			(xy 77.774528 -152.583387) (xy 77.829965 -152.589487) (xy 77.883922 -152.603593) (xy 77.935251 -152.625405)
			(xy 77.982857 -152.654459) (xy 78.025725 -152.690134) (xy 78.062942 -152.731671) (xy 78.093715 -152.778184)
			(xy 78.117387 -152.828681) (xy 78.133455 -152.882088) (xy 78.141575 -152.937264) (xy 78.142084 -152.96515)
			(xy 78.141575 -152.993036) (xy 78.137343 -153.021792) (xy 81.074006 -153.021792) (xy 81.074538 -152.993514)
			(xy 81.082862 -152.937575) (xy 81.099356 -152.883478) (xy 81.123659 -152.83241) (xy 81.155237 -152.785492)
			(xy 81.193398 -152.743751) (xy 81.237305 -152.708105) (xy 81.285995 -152.679333) (xy 81.312004 -152.668224)
			(xy 81.325346 -152.662366) (xy 81.348154 -152.644245) (xy 81.364915 -152.62042) (xy 81.374264 -152.59283)
			(xy 81.375439 -152.563724) (xy 81.368346 -152.53547) (xy 81.353561 -152.510371) (xy 81.343246 -152.500076)
			(xy 81.32456 -152.481974) (xy 81.291783 -152.441571) (xy 81.264801 -152.397089) (xy 81.244114 -152.349353)
			(xy 81.230106 -152.299248) (xy 81.223037 -152.247705) (xy 81.222596 -152.221692) (xy 81.223082 -152.194441)
			(xy 81.230838 -152.140493) (xy 81.246193 -152.088198) (xy 81.268835 -152.038621) (xy 81.298301 -151.992771)
			(xy 81.333992 -151.95158) (xy 81.375183 -151.915889) (xy 81.421033 -151.886423) (xy 81.47061 -151.863781)
			(xy 81.522905 -151.848426) (xy 81.576853 -151.84067) (xy 81.631355 -151.84067) (xy 81.685303 -151.848426)
			(xy 81.737598 -151.863781) (xy 81.787175 -151.886423) (xy 81.833025 -151.915889) (xy 81.874216 -151.95158)
			(xy 81.909907 -151.992771) (xy 81.939373 -152.038621) (xy 81.962015 -152.088198) (xy 81.97737 -152.140493)
			(xy 81.985126 -152.194441) (xy 81.985612 -152.221692) (xy 81.985056 -152.249969) (xy 81.976734 -152.305907)
			(xy 81.960243 -152.360002) (xy 81.935944 -152.411069) (xy 81.904369 -152.457988) (xy 81.866212 -152.499729)
			(xy 81.822308 -152.535377) (xy 81.773622 -152.56415) (xy 81.747614 -152.57526) (xy 81.734285 -152.581144)
			(xy 81.711476 -152.599259) (xy 81.694713 -152.623079) (xy 81.685362 -152.650664) (xy 81.684184 -152.679767)
			(xy 81.691276 -152.708018) (xy 81.706059 -152.733114) (xy 81.716372 -152.743408) (xy 81.735054 -152.761514)
			(xy 81.767831 -152.801916) (xy 81.794813 -152.846398) (xy 81.8155 -152.894133) (xy 81.82951 -152.944237)
			(xy 81.83658 -152.995779) (xy 81.837022 -153.021792) (xy 81.836536 -153.049043) (xy 81.82878 -153.102991)
			(xy 81.813425 -153.155286) (xy 81.790783 -153.204863) (xy 81.761317 -153.250713) (xy 81.725626 -153.291904)
			(xy 81.684435 -153.327595) (xy 81.638585 -153.357061) (xy 81.589008 -153.379703) (xy 81.536713 -153.395058)
			(xy 81.482765 -153.402814) (xy 81.428263 -153.402814) (xy 81.374315 -153.395058) (xy 81.32202 -153.379703)
			(xy 81.272443 -153.357061) (xy 81.226593 -153.327595) (xy 81.185402 -153.291904) (xy 81.149711 -153.250713)
			(xy 81.120245 -153.204863) (xy 81.097603 -153.155286) (xy 81.082248 -153.102991) (xy 81.074492 -153.049043)
			(xy 81.074006 -153.021792) (xy 78.137343 -153.021792) (xy 78.133455 -153.048212) (xy 78.117387 -153.101619)
			(xy 78.093715 -153.152116) (xy 78.062942 -153.198629) (xy 78.025725 -153.240166) (xy 77.982857 -153.275841)
			(xy 77.935251 -153.304895) (xy 77.883922 -153.326707) (xy 77.829965 -153.340813) (xy 77.774528 -153.346913)
			(xy 77.718794 -153.344876) (xy 77.663951 -153.334746) (xy 77.611167 -153.316739) (xy 77.561567 -153.291238)
			(xy 77.516209 -153.258787) (xy 77.47606 -153.220078) (xy 77.441974 -153.175935) (xy 77.414678 -153.1273)
			(xy 77.394755 -153.075209) (xy 77.382629 -153.020772) (xy 77.378558 -152.96515) (xy 70.613753 -152.96515)
			(xy 70.563068 -153.019531) (xy 70.498937 -153.076552) (xy 70.429749 -153.127318) (xy 70.35611 -153.171382)
			(xy 70.27867 -153.208356) (xy 70.198107 -153.237917) (xy 70.11513 -153.259803) (xy 70.030468 -153.273823)
			(xy 69.944866 -153.279854) (xy 69.859074 -153.277842) (xy 69.773848 -153.267806) (xy 69.689937 -153.249833)
			(xy 69.608077 -153.224081) (xy 69.528988 -153.190777) (xy 69.453366 -153.150213) (xy 69.381874 -153.102746)
			(xy 69.315141 -153.048793) (xy 69.253754 -152.988829) (xy 69.198251 -152.923379) (xy 69.149122 -152.85302)
			(xy 69.106796 -152.778369) (xy 69.071647 -152.700083) (xy 69.043984 -152.618849) (xy 69.024048 -152.535382)
			(xy 69.012017 -152.450414) (xy 69.007995 -152.364694) (xy 61.53658 -152.364694) (xy 61.53658 -153.339546)
			(xy 61.550125 -153.362281) (xy 61.571501 -153.410693) (xy 61.585984 -153.461593) (xy 61.593299 -153.514006)
			(xy 61.593303 -153.566926) (xy 61.585998 -153.619341) (xy 61.571524 -153.670243) (xy 61.550157 -153.718659)
			(xy 61.53658 -153.741374) (xy 61.53658 -154.407038) (xy 69.034402 -154.407038) (xy 69.034402 -154.322342)
			(xy 69.042453 -154.238028) (xy 69.058482 -154.154862) (xy 69.082343 -154.073595) (xy 69.113822 -153.994965)
			(xy 69.152633 -153.919684) (xy 69.198423 -153.848432) (xy 69.250779 -153.781856) (xy 69.309227 -153.720558)
			(xy 69.373237 -153.665093) (xy 69.442229 -153.615964) (xy 69.515579 -153.573615) (xy 69.592622 -153.538431)
			(xy 69.672661 -153.510729) (xy 69.75497 -153.490761) (xy 69.838805 -153.478708) (xy 69.923406 -153.474678)
			(xy 70.008007 -153.478708) (xy 70.091842 -153.490761) (xy 70.174151 -153.510729) (xy 70.25419 -153.538431)
			(xy 70.331233 -153.573615) (xy 70.404583 -153.615964) (xy 70.473575 -153.665093) (xy 70.537585 -153.720558)
			(xy 70.596033 -153.781856) (xy 70.648389 -153.848432) (xy 70.694179 -153.919684) (xy 70.73299 -153.994965)
			(xy 70.764469 -154.073595) (xy 70.78833 -154.154862) (xy 70.804359 -154.238028) (xy 70.808377 -154.280108)
			(xy 83.196682 -154.280108) (xy 83.200753 -154.224486) (xy 83.212879 -154.170049) (xy 83.232802 -154.117958)
			(xy 83.260098 -154.069323) (xy 83.294184 -154.02518) (xy 83.334333 -153.986471) (xy 83.379691 -153.95402)
			(xy 83.429291 -153.928519) (xy 83.482075 -153.910512) (xy 83.536918 -153.900382) (xy 83.592652 -153.898345)
			(xy 83.648089 -153.904445) (xy 83.702046 -153.918551) (xy 83.753375 -153.940363) (xy 83.800981 -153.969417)
			(xy 83.843849 -154.005092) (xy 83.881066 -154.046629) (xy 83.911839 -154.093142) (xy 83.935511 -154.143639)
			(xy 83.951579 -154.197046) (xy 83.959699 -154.252222) (xy 83.960208 -154.280108) (xy 83.959699 -154.307994)
			(xy 83.951579 -154.36317) (xy 83.935511 -154.416577) (xy 83.911839 -154.467074) (xy 83.881066 -154.513587)
			(xy 83.843849 -154.555124) (xy 83.800981 -154.590799) (xy 83.753375 -154.619853) (xy 83.702046 -154.641665)
			(xy 83.648089 -154.655771) (xy 83.592652 -154.661871) (xy 83.536918 -154.659834) (xy 83.482075 -154.649704)
			(xy 83.429291 -154.631697) (xy 83.379691 -154.606196) (xy 83.334333 -154.573745) (xy 83.294184 -154.535036)
			(xy 83.260098 -154.490893) (xy 83.232802 -154.442258) (xy 83.212879 -154.390167) (xy 83.200753 -154.33573)
			(xy 83.196682 -154.280108) (xy 70.808377 -154.280108) (xy 70.81241 -154.322342) (xy 70.812914 -154.36469)
			(xy 70.81241 -154.407038) (xy 70.804359 -154.491352) (xy 70.78833 -154.574518) (xy 70.764469 -154.655785)
			(xy 70.73299 -154.734415) (xy 70.694179 -154.809696) (xy 70.648389 -154.880948) (xy 70.596033 -154.947524)
			(xy 70.537585 -155.008822) (xy 70.473575 -155.064287) (xy 70.404583 -155.113416) (xy 70.331233 -155.155765)
			(xy 70.25419 -155.190949) (xy 70.174151 -155.218651) (xy 70.091842 -155.238619) (xy 70.008007 -155.250672)
			(xy 69.923406 -155.254703) (xy 69.838805 -155.250672) (xy 69.75497 -155.238619) (xy 69.672661 -155.218651)
			(xy 69.592622 -155.190949) (xy 69.515579 -155.155765) (xy 69.442229 -155.113416) (xy 69.373237 -155.064287)
			(xy 69.309227 -155.008822) (xy 69.250779 -154.947524) (xy 69.198423 -154.880948) (xy 69.152633 -154.809696)
			(xy 69.113822 -154.734415) (xy 69.082343 -154.655785) (xy 69.058482 -154.574518) (xy 69.042453 -154.491352)
			(xy 69.034402 -154.407038) (xy 61.53658 -154.407038) (xy 61.53658 -158.49981) (xy 69.007995 -158.49981)
			(xy 69.012017 -158.41409) (xy 69.024048 -158.329122) (xy 69.043984 -158.245655) (xy 69.071647 -158.164421)
			(xy 69.106796 -158.086135) (xy 69.149122 -158.011484) (xy 69.198251 -157.941125) (xy 69.253754 -157.875675)
			(xy 69.315141 -157.815711) (xy 69.381874 -157.761758) (xy 69.453366 -157.714291) (xy 69.528988 -157.673727)
			(xy 69.608077 -157.640423) (xy 69.689937 -157.614671) (xy 69.773848 -157.596698) (xy 69.859074 -157.586662)
			(xy 69.944866 -157.58465) (xy 70.030468 -157.590681) (xy 70.11513 -157.604701) (xy 70.198107 -157.626587)
			(xy 70.27867 -157.656148) (xy 70.35611 -157.693122) (xy 70.429749 -157.737186) (xy 70.498937 -157.787952)
			(xy 70.563068 -157.844973) (xy 70.621577 -157.907749) (xy 70.67395 -157.975729) (xy 70.719728 -158.048314)
			(xy 70.758508 -158.124866) (xy 70.789949 -158.204714) (xy 70.813775 -158.287155) (xy 70.829776 -158.371465)
			(xy 70.837811 -158.456903) (xy 70.838314 -158.49981) (xy 70.837811 -158.542717) (xy 70.829776 -158.628155)
			(xy 70.813775 -158.712465) (xy 70.789949 -158.794906) (xy 70.758508 -158.874754) (xy 70.719728 -158.951306)
			(xy 70.67395 -159.023891) (xy 70.621577 -159.091871) (xy 70.563068 -159.154647) (xy 70.498937 -159.211668)
			(xy 70.429749 -159.262434) (xy 70.35611 -159.306498) (xy 70.27867 -159.343472) (xy 70.198107 -159.373033)
			(xy 70.123846 -159.39262) (xy 77.24394 -159.39262) (xy 77.244408 -159.36525) (xy 77.252224 -159.31107)
			(xy 77.267712 -159.258567) (xy 77.290554 -159.20882) (xy 77.320278 -159.162853) (xy 77.33792 -159.141922)
			(xy 77.347136 -159.13058) (xy 77.359313 -159.104027) (xy 77.363489 -159.075115) (xy 77.359322 -159.046202)
			(xy 77.347152 -159.019646) (xy 77.33792 -159.008318) (xy 77.320299 -158.987369) (xy 77.290574 -158.941404)
			(xy 77.267728 -158.89166) (xy 77.252231 -158.839161) (xy 77.2444 -158.784985) (xy 77.244398 -158.730245)
			(xy 77.252224 -158.676069) (xy 77.267717 -158.623568) (xy 77.29056 -158.573822) (xy 77.320281 -158.527855)
			(xy 77.33792 -158.506922) (xy 77.347136 -158.49558) (xy 77.359313 -158.469027) (xy 77.363489 -158.440115)
			(xy 77.359322 -158.411202) (xy 77.347152 -158.384646) (xy 77.33792 -158.373318) (xy 77.320279 -158.352387)
			(xy 77.290567 -158.306415) (xy 77.267731 -158.256667) (xy 77.25224 -158.204166) (xy 77.244413 -158.149989)
			(xy 77.24394 -158.12262) (xy 77.244426 -158.095369) (xy 77.252182 -158.041421) (xy 77.267537 -157.989126)
			(xy 77.290179 -157.939549) (xy 77.319645 -157.893699) (xy 77.355336 -157.852508) (xy 77.396527 -157.816817)
			(xy 77.442377 -157.787351) (xy 77.491954 -157.764709) (xy 77.544249 -157.749354) (xy 77.598197 -157.741598)
			(xy 77.652699 -157.741598) (xy 77.706647 -157.749354) (xy 77.758942 -157.764709) (xy 77.808519 -157.787351)
			(xy 77.854369 -157.816817) (xy 77.89556 -157.852508) (xy 77.931251 -157.893699) (xy 77.960717 -157.939549)
			(xy 77.983359 -157.989126) (xy 77.998714 -158.041421) (xy 78.00647 -158.095369) (xy 78.006956 -158.12262)
			(xy 78.006512 -158.149991) (xy 77.998691 -158.204172) (xy 77.983197 -158.256675) (xy 77.96579 -158.294578)
			(xy 80.234026 -158.294578) (xy 80.238097 -158.238956) (xy 80.250223 -158.184519) (xy 80.270146 -158.132428)
			(xy 80.297442 -158.083793) (xy 80.331528 -158.03965) (xy 80.371677 -158.000941) (xy 80.417035 -157.96849)
			(xy 80.466635 -157.942989) (xy 80.519419 -157.924982) (xy 80.574262 -157.914852) (xy 80.629996 -157.912815)
			(xy 80.685433 -157.918915) (xy 80.73939 -157.933021) (xy 80.790719 -157.954833) (xy 80.838325 -157.983887)
			(xy 80.881193 -158.019562) (xy 80.91841 -158.061099) (xy 80.949183 -158.107612) (xy 80.972855 -158.158109)
			(xy 80.988923 -158.211516) (xy 80.997043 -158.266692) (xy 80.997552 -158.294578) (xy 80.997043 -158.322464)
			(xy 80.988923 -158.37764) (xy 80.972855 -158.431047) (xy 80.949183 -158.481544) (xy 80.91841 -158.528057)
			(xy 80.881193 -158.569594) (xy 80.838325 -158.605269) (xy 80.790719 -158.634323) (xy 80.73939 -158.656135)
			(xy 80.685433 -158.670241) (xy 80.629996 -158.676341) (xy 80.574262 -158.674304) (xy 80.519419 -158.664174)
			(xy 80.466635 -158.646167) (xy 80.417035 -158.620666) (xy 80.371677 -158.588215) (xy 80.331528 -158.549506)
			(xy 80.297442 -158.505363) (xy 80.270146 -158.456728) (xy 80.250223 -158.404637) (xy 80.238097 -158.3502)
			(xy 80.234026 -158.294578) (xy 77.96579 -158.294578) (xy 77.96035 -158.306422) (xy 77.93062 -158.352387)
			(xy 77.912976 -158.373318) (xy 77.903722 -158.384632) (xy 77.89155 -158.411195) (xy 77.887382 -158.440115)
			(xy 77.891558 -158.469034) (xy 77.903738 -158.495594) (xy 77.912976 -158.506922) (xy 77.930636 -158.527839)
			(xy 77.96036 -158.57381) (xy 77.983204 -158.623558) (xy 77.998699 -158.676063) (xy 78.006525 -158.730244)
			(xy 78.006523 -158.784987) (xy 77.998692 -158.839167) (xy 77.983193 -158.89167) (xy 77.960345 -158.941417)
			(xy 77.930618 -158.987385) (xy 77.912976 -159.008318) (xy 77.903722 -159.019632) (xy 77.89155 -159.046195)
			(xy 77.887382 -159.075115) (xy 77.891558 -159.104034) (xy 77.903738 -159.130594) (xy 77.912976 -159.141922)
			(xy 77.93228 -159.165798) (xy 77.938156 -159.173078) (xy 77.953931 -159.183109) (xy 77.972258 -159.186795)
			(xy 77.990685 -159.183643) (xy 78.006744 -159.174074) (xy 78.018288 -159.15937) (xy 78.021434 -159.150558)
			(xy 78.029884 -159.125026) (xy 78.05298 -159.076456) (xy 78.082668 -159.031611) (xy 78.118358 -158.991379)
			(xy 78.159344 -158.956557) (xy 78.204814 -158.927836) (xy 78.253867 -158.905785) (xy 78.30553 -158.890839)
			(xy 78.358779 -158.883297) (xy 78.38567 -158.882842) (xy 78.412924 -158.883283) (xy 78.466879 -158.891038)
			(xy 78.51918 -158.906392) (xy 78.568763 -158.929035) (xy 78.614619 -158.958504) (xy 78.655813 -158.994201)
			(xy 78.691508 -159.035397) (xy 78.720975 -159.081254) (xy 78.743615 -159.130839) (xy 78.758967 -159.183141)
			(xy 78.766718 -159.237096) (xy 78.767178 -159.26435) (xy 78.766688 -159.291719) (xy 78.758877 -159.345898)
			(xy 78.743394 -159.398401) (xy 78.720557 -159.448148) (xy 78.690837 -159.494116) (xy 78.673198 -159.515048)
			(xy 78.663913 -159.526339) (xy 78.651742 -159.55291) (xy 78.647579 -159.581838) (xy 78.651763 -159.610763)
			(xy 78.663954 -159.637324) (xy 78.673198 -159.648652) (xy 78.690828 -159.669592) (xy 78.720541 -159.715562)
			(xy 78.743379 -159.765308) (xy 78.758872 -159.817807) (xy 78.766703 -159.871981) (xy 78.767178 -159.89935)
			(xy 78.766692 -159.926601) (xy 78.758936 -159.980549) (xy 78.743581 -160.032844) (xy 78.720939 -160.082421)
			(xy 78.691473 -160.128271) (xy 78.655782 -160.169462) (xy 78.614591 -160.205153) (xy 78.568741 -160.234619)
			(xy 78.519164 -160.257261) (xy 78.466869 -160.272616) (xy 78.412921 -160.280372) (xy 78.358419 -160.280372)
			(xy 78.304471 -160.272616) (xy 78.252176 -160.257261) (xy 78.202599 -160.234619) (xy 78.156749 -160.205153)
			(xy 78.115558 -160.169462) (xy 78.079867 -160.128271) (xy 78.050401 -160.082421) (xy 78.027759 -160.032844)
			(xy 78.012404 -159.980549) (xy 78.004648 -159.926601) (xy 78.004162 -159.89935) (xy 78.004642 -159.87198)
			(xy 78.012454 -159.817801) (xy 78.027939 -159.765297) (xy 78.050778 -159.71555) (xy 78.080501 -159.669583)
			(xy 78.098142 -159.648652) (xy 78.107327 -159.637287) (xy 78.119506 -159.610742) (xy 78.123686 -159.581838)
			(xy 78.119527 -159.55293) (xy 78.107368 -159.526376) (xy 78.098142 -159.515048) (xy 78.078838 -159.491172)
			(xy 78.072931 -159.483922) (xy 78.057164 -159.473898) (xy 78.038848 -159.470214) (xy 78.020432 -159.47336)
			(xy 78.004378 -159.482918) (xy 77.992834 -159.497607) (xy 77.989684 -159.506412) (xy 77.9812 -159.531932)
			(xy 77.958109 -159.580502) (xy 77.928427 -159.625347) (xy 77.892741 -159.66558) (xy 77.851759 -159.700403)
			(xy 77.806293 -159.729126) (xy 77.757244 -159.75118) (xy 77.705584 -159.766127) (xy 77.652337 -159.773672)
			(xy 77.625448 -159.774128) (xy 77.598197 -159.7736) (xy 77.54425 -159.76585) (xy 77.491954 -159.750501)
			(xy 77.442376 -159.727866) (xy 77.396523 -159.698405) (xy 77.35533 -159.662718) (xy 77.319636 -159.621531)
			(xy 77.290167 -159.575684) (xy 77.267523 -159.52611) (xy 77.252164 -159.473817) (xy 77.244405 -159.419871)
			(xy 77.24394 -159.39262) (xy 70.123846 -159.39262) (xy 70.11513 -159.394919) (xy 70.030468 -159.408939)
			(xy 69.944866 -159.41497) (xy 69.859074 -159.412958) (xy 69.773848 -159.402922) (xy 69.689937 -159.384949)
			(xy 69.608077 -159.359197) (xy 69.528988 -159.325893) (xy 69.453366 -159.285329) (xy 69.381874 -159.237862)
			(xy 69.315141 -159.183909) (xy 69.253754 -159.123945) (xy 69.198251 -159.058495) (xy 69.149122 -158.988136)
			(xy 69.106796 -158.913485) (xy 69.071647 -158.835199) (xy 69.043984 -158.753965) (xy 69.024048 -158.670498)
			(xy 69.012017 -158.58553) (xy 69.007995 -158.49981) (xy 61.53658 -158.49981) (xy 61.53658 -159.319468)
			(xy 62.74816 -160.531048) (xy 68.326 -160.531048) (xy 69.27596 -161.481008) (xy 69.466714 -161.481008)
			(xy 69.481777 -161.480464) (xy 69.510592 -161.471675) (xy 69.535592 -161.454866) (xy 69.554604 -161.431497)
			(xy 69.565975 -161.4036) (xy 69.568717 -161.3736) (xy 69.562592 -161.344103) (xy 69.548132 -161.317675)
			(xy 69.526594 -161.296612) (xy 69.51345 -161.289238) (xy 69.477741 -161.270179) (xy 69.409587 -161.226503)
			(xy 69.345683 -161.176813) (xy 69.28656 -161.121523) (xy 69.232705 -161.061088) (xy 69.184566 -160.996009)
			(xy 69.142539 -160.926825) (xy 69.106974 -160.854109) (xy 69.078163 -160.778461) (xy 69.056346 -160.700508)
			(xy 69.041703 -160.620895) (xy 69.034356 -160.54028) (xy 69.033898 -160.499806) (xy 69.034402 -160.457458)
			(xy 69.042453 -160.373144) (xy 69.058482 -160.289978) (xy 69.082343 -160.208711) (xy 69.113822 -160.130081)
			(xy 69.152633 -160.0548) (xy 69.198423 -159.983548) (xy 69.250779 -159.916972) (xy 69.309227 -159.855674)
			(xy 69.373237 -159.800209) (xy 69.442229 -159.75108) (xy 69.515579 -159.708731) (xy 69.592622 -159.673547)
			(xy 69.672661 -159.645845) (xy 69.75497 -159.625877) (xy 69.838805 -159.613824) (xy 69.923406 -159.609794)
			(xy 70.008007 -159.613824) (xy 70.091842 -159.625877) (xy 70.174151 -159.645845) (xy 70.25419 -159.673547)
			(xy 70.331233 -159.708731) (xy 70.404583 -159.75108) (xy 70.473575 -159.800209) (xy 70.537585 -159.855674)
			(xy 70.596033 -159.916972) (xy 70.648389 -159.983548) (xy 70.694179 -160.0548) (xy 70.73299 -160.130081)
			(xy 70.764469 -160.208711) (xy 70.78833 -160.289978) (xy 70.804359 -160.373144) (xy 70.81241 -160.457458)
			(xy 70.812914 -160.499806) (xy 70.812455 -160.54028) (xy 70.8051 -160.620893) (xy 70.790452 -160.700504)
			(xy 70.768632 -160.778456) (xy 70.73982 -160.854102) (xy 70.704254 -160.926819) (xy 70.66223 -160.996003)
			(xy 70.614093 -161.061083) (xy 70.560244 -161.121521) (xy 70.501126 -161.176817) (xy 70.437228 -161.226513)
			(xy 70.369081 -161.270199) (xy 70.333362 -161.289238) (xy 70.320245 -161.296649) (xy 70.298714 -161.317701)
			(xy 70.284259 -161.344117) (xy 70.278135 -161.373601) (xy 70.280876 -161.403588) (xy 70.292243 -161.431473)
			(xy 70.311248 -161.454831) (xy 70.336238 -161.471631) (xy 70.365042 -161.480413) (xy 70.380098 -161.481008)
			(xy 70.65518 -161.481008) (xy 72.00138 -160.134808) (xy 72.416416 -160.134808) (xy 72.427592 -160.098994)
			(xy 72.436025 -160.073436) (xy 72.459073 -160.024802) (xy 72.488729 -159.97989) (xy 72.524403 -159.939593)
			(xy 72.565387 -159.904711) (xy 72.610868 -159.875935) (xy 72.659941 -159.853839) (xy 72.711634 -159.838859)
			(xy 72.764918 -159.831294) (xy 72.818738 -159.831294) (xy 72.872022 -159.838859) (xy 72.923715 -159.853839)
			(xy 72.972788 -159.875935) (xy 73.018269 -159.904711) (xy 73.059253 -159.939593) (xy 73.094927 -159.97989)
			(xy 73.124583 -160.024802) (xy 73.147631 -160.073436) (xy 73.156064 -160.098994) (xy 73.16724 -160.134808)
			(xy 74.4093 -160.134808) (xy 74.776076 -160.501584) (xy 74.811636 -160.47339) (xy 74.834872 -160.455186)
			(xy 74.883694 -160.422002) (xy 74.909172 -160.407096) (xy 74.916865 -160.402288) (xy 74.928517 -160.3884)
			(xy 74.934627 -160.371331) (xy 74.934436 -160.353203) (xy 74.931524 -160.344612) (xy 74.923232 -160.322442)
			(xy 74.911579 -160.276564) (xy 74.905705 -160.229595) (xy 74.905362 -160.205928) (xy 74.905848 -160.178677)
			(xy 74.913604 -160.124729) (xy 74.928959 -160.072434) (xy 74.951601 -160.022857) (xy 74.981067 -159.977007)
			(xy 75.016758 -159.935816) (xy 75.057949 -159.900125) (xy 75.103799 -159.870659) (xy 75.153376 -159.848017)
			(xy 75.205671 -159.832662) (xy 75.259619 -159.824906) (xy 75.314121 -159.824906) (xy 75.368069 -159.832662)
			(xy 75.420364 -159.848017) (xy 75.469941 -159.870659) (xy 75.515791 -159.900125) (xy 75.556982 -159.935816)
			(xy 75.592673 -159.977007) (xy 75.622139 -160.022857) (xy 75.644781 -160.072434) (xy 75.660136 -160.124729)
			(xy 75.667892 -160.178677) (xy 75.668378 -160.205928) (xy 75.668004 -160.229593) (xy 75.662123 -160.276558)
			(xy 75.650493 -160.322438) (xy 75.642216 -160.344612) (xy 75.639295 -160.353206) (xy 75.63907 -160.371344)
			(xy 75.64518 -160.388424) (xy 75.656859 -160.402303) (xy 75.664568 -160.407096) (xy 75.699186 -160.427425)
			(xy 75.764368 -160.474296) (xy 75.824264 -160.527757) (xy 75.878209 -160.587217) (xy 75.925608 -160.652016)
			(xy 75.965934 -160.721438) (xy 75.998742 -160.794713) (xy 76.023667 -160.87103) (xy 76.040435 -160.949544)
			(xy 76.048858 -161.029386) (xy 76.049378 -161.069528) (xy 76.048927 -161.106187) (xy 76.041861 -161.179164)
			(xy 76.027824 -161.251127) (xy 76.006948 -161.321411) (xy 75.979423 -161.389367) (xy 75.945505 -161.454368)
			(xy 75.905507 -161.515815) (xy 75.883008 -161.544762) (xy 75.854814 -161.580322) (xy 76.74102 -162.466528)
			(xy 76.74102 -167.36568) (xy 78.901544 -169.526204) (xy 78.901544 -173.708568) (xy 94.098362 -173.708568)
			(xy 94.102433 -173.652946) (xy 94.114559 -173.598509) (xy 94.134482 -173.546418) (xy 94.161778 -173.497783)
			(xy 94.195864 -173.45364) (xy 94.236013 -173.414931) (xy 94.281371 -173.38248) (xy 94.330971 -173.356979)
			(xy 94.383755 -173.338972) (xy 94.438598 -173.328842) (xy 94.494332 -173.326805) (xy 94.549769 -173.332905)
			(xy 94.603726 -173.347011) (xy 94.655055 -173.368823) (xy 94.702661 -173.397877) (xy 94.745529 -173.433552)
			(xy 94.782746 -173.475089) (xy 94.813519 -173.521602) (xy 94.837191 -173.572099) (xy 94.853259 -173.625506)
			(xy 94.861379 -173.680682) (xy 94.861888 -173.708568) (xy 94.861379 -173.736454) (xy 94.853259 -173.79163)
			(xy 94.837191 -173.845037) (xy 94.813519 -173.895534) (xy 94.782746 -173.942047) (xy 94.745529 -173.983584)
			(xy 94.702661 -174.019259) (xy 94.655055 -174.048313) (xy 94.603726 -174.070125) (xy 94.549769 -174.084231)
			(xy 94.494332 -174.090331) (xy 94.438598 -174.088294) (xy 94.383755 -174.078164) (xy 94.330971 -174.060157)
			(xy 94.281371 -174.034656) (xy 94.236013 -174.002205) (xy 94.195864 -173.963496) (xy 94.161778 -173.919353)
			(xy 94.134482 -173.870718) (xy 94.114559 -173.818627) (xy 94.102433 -173.76419) (xy 94.098362 -173.708568)
			(xy 78.901544 -173.708568) (xy 78.901544 -175.288956) (xy 90.966798 -175.288956) (xy 90.967181 -175.262774)
			(xy 90.974324 -175.2109) (xy 90.988497 -175.160492) (xy 91.009435 -175.112497) (xy 91.036742 -175.067817)
			(xy 91.069906 -175.027295) (xy 91.108302 -174.991691) (xy 91.151208 -174.961675) (xy 91.174316 -174.949358)
			(xy 91.186494 -174.942722) (xy 91.206898 -174.923945) (xy 91.221497 -174.900372) (xy 91.229215 -174.873739)
			(xy 91.229483 -174.846013) (xy 91.22228 -174.819236) (xy 91.208139 -174.795385) (xy 91.188101 -174.776219)
			(xy 91.176094 -174.769272) (xy 91.150385 -174.754926) (xy 91.103329 -174.719546) (xy 91.062272 -174.677353)
			(xy 91.028191 -174.629349) (xy 91.001895 -174.576675) (xy 90.984011 -174.520585) (xy 90.974963 -174.462412)
			(xy 90.974418 -174.432976) (xy 90.974904 -174.405725) (xy 90.98266 -174.351777) (xy 90.998015 -174.299482)
			(xy 91.020657 -174.249905) (xy 91.050123 -174.204055) (xy 91.085814 -174.162864) (xy 91.127005 -174.127173)
			(xy 91.172855 -174.097707) (xy 91.222432 -174.075065) (xy 91.274727 -174.05971) (xy 91.328675 -174.051954)
			(xy 91.383177 -174.051954) (xy 91.437125 -174.05971) (xy 91.48942 -174.075065) (xy 91.538997 -174.097707)
			(xy 91.584847 -174.127173) (xy 91.626038 -174.162864) (xy 91.661729 -174.204055) (xy 91.691195 -174.249905)
			(xy 91.713837 -174.299482) (xy 91.729192 -174.351777) (xy 91.736948 -174.405725) (xy 91.737434 -174.432976)
			(xy 91.73706 -174.459158) (xy 91.729914 -174.511031) (xy 91.715737 -174.561439) (xy 91.694798 -174.609434)
			(xy 91.667489 -174.654112) (xy 91.634325 -174.694635) (xy 91.595929 -174.730239) (xy 91.553023 -174.760256)
			(xy 91.529916 -174.772574) (xy 91.517795 -174.779308) (xy 91.497391 -174.798065) (xy 91.482788 -174.82162)
			(xy 91.475064 -174.848237) (xy 91.474788 -174.87595) (xy 91.481981 -174.902715) (xy 91.496111 -174.926557)
			(xy 91.516137 -174.945716) (xy 91.528138 -174.95266) (xy 91.553868 -174.96697) (xy 91.600923 -175.002357)
			(xy 91.641978 -175.044557) (xy 91.676056 -175.092567) (xy 91.702348 -175.145246) (xy 91.720228 -175.201341)
			(xy 91.729271 -175.259518) (xy 91.729814 -175.288956) (xy 91.729328 -175.316207) (xy 91.721572 -175.370155)
			(xy 91.706217 -175.42245) (xy 91.683575 -175.472027) (xy 91.654109 -175.517877) (xy 91.618418 -175.559068)
			(xy 91.577227 -175.594759) (xy 91.531377 -175.624225) (xy 91.4818 -175.646867) (xy 91.429505 -175.662222)
			(xy 91.375557 -175.669978) (xy 91.321055 -175.669978) (xy 91.267107 -175.662222) (xy 91.214812 -175.646867)
			(xy 91.165235 -175.624225) (xy 91.119385 -175.594759) (xy 91.078194 -175.559068) (xy 91.042503 -175.517877)
			(xy 91.013037 -175.472027) (xy 90.990395 -175.42245) (xy 90.97504 -175.370155) (xy 90.967284 -175.316207)
			(xy 90.966798 -175.288956) (xy 78.901544 -175.288956) (xy 78.901544 -177.126392) (xy 91.846146 -177.126392)
			(xy 91.84664 -177.100014) (xy 91.853893 -177.04776) (xy 91.868272 -176.997003) (xy 91.889505 -176.94871)
			(xy 91.917185 -176.9038) (xy 91.950787 -176.863131) (xy 91.989669 -176.827476) (xy 92.033091 -176.797516)
			(xy 92.056458 -176.78527) (xy 92.068824 -176.778581) (xy 92.089556 -176.759604) (xy 92.104318 -176.735687)
			(xy 92.11199 -176.708649) (xy 92.111989 -176.680544) (xy 92.104315 -176.653506) (xy 92.089551 -176.629591)
			(xy 92.068818 -176.610615) (xy 92.056458 -176.603914) (xy 92.033075 -176.591696) (xy 91.989652 -176.561729)
			(xy 91.950768 -176.52607) (xy 91.917164 -176.485397) (xy 91.889479 -176.440485) (xy 91.86824 -176.392189)
			(xy 91.853853 -176.341429) (xy 91.846591 -176.289172) (xy 91.846146 -176.262792) (xy 91.846632 -176.235541)
			(xy 91.854388 -176.181593) (xy 91.869743 -176.129298) (xy 91.892385 -176.079721) (xy 91.921851 -176.033871)
			(xy 91.957542 -175.99268) (xy 91.998733 -175.956989) (xy 92.044583 -175.927523) (xy 92.09416 -175.904881)
			(xy 92.146455 -175.889526) (xy 92.200403 -175.88177) (xy 92.254905 -175.88177) (xy 92.308853 -175.889526)
			(xy 92.361148 -175.904881) (xy 92.410725 -175.927523) (xy 92.456575 -175.956989) (xy 92.497766 -175.99268)
			(xy 92.533457 -176.033871) (xy 92.562923 -176.079721) (xy 92.585565 -176.129298) (xy 92.60092 -176.181593)
			(xy 92.608676 -176.235541) (xy 92.609162 -176.262792) (xy 92.608705 -176.289171) (xy 92.601452 -176.341429)
			(xy 92.587071 -176.39219) (xy 92.565835 -176.440486) (xy 92.538149 -176.485396) (xy 92.504541 -176.526065)
			(xy 92.465651 -176.561717) (xy 92.422221 -176.591672) (xy 92.39885 -176.603914) (xy 92.386497 -176.610626)
			(xy 92.365766 -176.629599) (xy 92.351002 -176.653511) (xy 92.343328 -176.680545) (xy 92.343327 -176.708648)
			(xy 92.350999 -176.735683) (xy 92.365761 -176.759596) (xy 92.386491 -176.77857) (xy 92.39885 -176.78527)
			(xy 92.422229 -176.797496) (xy 92.465651 -176.827463) (xy 92.504534 -176.863121) (xy 92.538139 -176.903793)
			(xy 92.565824 -176.948704) (xy 92.587064 -176.996998) (xy 92.601452 -177.047757) (xy 92.608716 -177.100013)
			(xy 92.609162 -177.126392) (xy 92.608676 -177.153643) (xy 92.60092 -177.207591) (xy 92.585565 -177.259886)
			(xy 92.562923 -177.309463) (xy 92.533457 -177.355313) (xy 92.497766 -177.396504) (xy 92.456575 -177.432195)
			(xy 92.410725 -177.461661) (xy 92.361148 -177.484303) (xy 92.308853 -177.499658) (xy 92.254905 -177.507414)
			(xy 92.200403 -177.507414) (xy 92.146455 -177.499658) (xy 92.09416 -177.484303) (xy 92.044583 -177.461661)
			(xy 91.998733 -177.432195) (xy 91.957542 -177.396504) (xy 91.921851 -177.355313) (xy 91.892385 -177.309463)
			(xy 91.869743 -177.259886) (xy 91.854388 -177.207591) (xy 91.846632 -177.153643) (xy 91.846146 -177.126392)
			(xy 78.901544 -177.126392) (xy 78.901544 -178.674268) (xy 88.233502 -178.674268) (xy 88.237573 -178.618646)
			(xy 88.249699 -178.564209) (xy 88.269622 -178.512118) (xy 88.296918 -178.463483) (xy 88.331004 -178.41934)
			(xy 88.371153 -178.380631) (xy 88.416511 -178.34818) (xy 88.466111 -178.322679) (xy 88.518895 -178.304672)
			(xy 88.573738 -178.294542) (xy 88.629472 -178.292505) (xy 88.684909 -178.298605) (xy 88.738866 -178.312711)
			(xy 88.790195 -178.334523) (xy 88.837801 -178.363577) (xy 88.880669 -178.399252) (xy 88.917886 -178.440789)
			(xy 88.948659 -178.487302) (xy 88.972331 -178.537799) (xy 88.988399 -178.591206) (xy 88.996519 -178.646382)
			(xy 88.997028 -178.674268) (xy 88.996519 -178.702154) (xy 88.988399 -178.75733) (xy 88.972331 -178.810737)
			(xy 88.948659 -178.861234) (xy 88.917886 -178.907747) (xy 88.880669 -178.949284) (xy 88.837801 -178.984959)
			(xy 88.790195 -179.014013) (xy 88.738866 -179.035825) (xy 88.684909 -179.049931) (xy 88.629472 -179.056031)
			(xy 88.573738 -179.053994) (xy 88.518895 -179.043864) (xy 88.466111 -179.025857) (xy 88.416511 -179.000356)
			(xy 88.371153 -178.967905) (xy 88.331004 -178.929196) (xy 88.296918 -178.885053) (xy 88.269622 -178.836418)
			(xy 88.249699 -178.784327) (xy 88.237573 -178.72989) (xy 88.233502 -178.674268) (xy 78.901544 -178.674268)
			(xy 78.901544 -179.294028) (xy 83.885022 -179.294028) (xy 83.889093 -179.238406) (xy 83.901219 -179.183969)
			(xy 83.921142 -179.131878) (xy 83.948438 -179.083243) (xy 83.982524 -179.0391) (xy 84.022673 -179.000391)
			(xy 84.068031 -178.96794) (xy 84.117631 -178.942439) (xy 84.170415 -178.924432) (xy 84.225258 -178.914302)
			(xy 84.280992 -178.912265) (xy 84.336429 -178.918365) (xy 84.390386 -178.932471) (xy 84.441715 -178.954283)
			(xy 84.489321 -178.983337) (xy 84.532189 -179.019012) (xy 84.569406 -179.060549) (xy 84.600179 -179.107062)
			(xy 84.623851 -179.157559) (xy 84.639919 -179.210966) (xy 84.648039 -179.266142) (xy 84.648548 -179.294028)
			(xy 84.648163 -179.31511) (xy 91.177362 -179.31511) (xy 91.181433 -179.259488) (xy 91.193559 -179.205051)
			(xy 91.213482 -179.15296) (xy 91.240778 -179.104325) (xy 91.274864 -179.060182) (xy 91.315013 -179.021473)
			(xy 91.360371 -178.989022) (xy 91.409971 -178.963521) (xy 91.462755 -178.945514) (xy 91.517598 -178.935384)
			(xy 91.573332 -178.933347) (xy 91.628769 -178.939447) (xy 91.682726 -178.953553) (xy 91.734055 -178.975365)
			(xy 91.781661 -179.004419) (xy 91.824529 -179.040094) (xy 91.861746 -179.081631) (xy 91.892519 -179.128144)
			(xy 91.916191 -179.178641) (xy 91.932259 -179.232048) (xy 91.940379 -179.287224) (xy 91.940888 -179.31511)
			(xy 91.940379 -179.342996) (xy 91.932259 -179.398172) (xy 91.916191 -179.451579) (xy 91.892519 -179.502076)
			(xy 91.861746 -179.548589) (xy 91.824529 -179.590126) (xy 91.781661 -179.625801) (xy 91.734055 -179.654855)
			(xy 91.682726 -179.676667) (xy 91.628769 -179.690773) (xy 91.573332 -179.696873) (xy 91.517598 -179.694836)
			(xy 91.462755 -179.684706) (xy 91.409971 -179.666699) (xy 91.360371 -179.641198) (xy 91.315013 -179.608747)
			(xy 91.274864 -179.570038) (xy 91.240778 -179.525895) (xy 91.213482 -179.47726) (xy 91.193559 -179.425169)
			(xy 91.181433 -179.370732) (xy 91.177362 -179.31511) (xy 84.648163 -179.31511) (xy 84.648039 -179.321914)
			(xy 84.639919 -179.37709) (xy 84.623851 -179.430497) (xy 84.600179 -179.480994) (xy 84.569406 -179.527507)
			(xy 84.532189 -179.569044) (xy 84.489321 -179.604719) (xy 84.441715 -179.633773) (xy 84.390386 -179.655585)
			(xy 84.336429 -179.669691) (xy 84.280992 -179.675791) (xy 84.225258 -179.673754) (xy 84.170415 -179.663624)
			(xy 84.117631 -179.645617) (xy 84.068031 -179.620116) (xy 84.022673 -179.587665) (xy 83.982524 -179.548956)
			(xy 83.948438 -179.504813) (xy 83.921142 -179.456178) (xy 83.901219 -179.404087) (xy 83.889093 -179.34965)
			(xy 83.885022 -179.294028) (xy 78.901544 -179.294028) (xy 78.901544 -180.165502) (xy 83.778088 -180.165502)
			(xy 83.782159 -180.10988) (xy 83.794285 -180.055443) (xy 83.814208 -180.003352) (xy 83.841504 -179.954717)
			(xy 83.87559 -179.910574) (xy 83.915739 -179.871865) (xy 83.961097 -179.839414) (xy 84.010697 -179.813913)
			(xy 84.063481 -179.795906) (xy 84.118324 -179.785776) (xy 84.174058 -179.783739) (xy 84.229495 -179.789839)
			(xy 84.283452 -179.803945) (xy 84.334781 -179.825757) (xy 84.382387 -179.854811) (xy 84.425255 -179.890486)
			(xy 84.462472 -179.932023) (xy 84.493245 -179.978536) (xy 84.516917 -180.029033) (xy 84.532985 -180.08244)
			(xy 84.541105 -180.137616) (xy 84.541614 -180.165502) (xy 84.541105 -180.193388) (xy 84.532985 -180.248564)
			(xy 84.516917 -180.301971) (xy 84.493245 -180.352468) (xy 84.462472 -180.398981) (xy 84.425255 -180.440518)
			(xy 84.382387 -180.476193) (xy 84.334781 -180.505247) (xy 84.283452 -180.527059) (xy 84.229495 -180.541165)
			(xy 84.174058 -180.547265) (xy 84.118324 -180.545228) (xy 84.063481 -180.535098) (xy 84.010697 -180.517091)
			(xy 83.961097 -180.49159) (xy 83.915739 -180.459139) (xy 83.87559 -180.42043) (xy 83.841504 -180.376287)
			(xy 83.814208 -180.327652) (xy 83.794285 -180.275561) (xy 83.782159 -180.221124) (xy 83.778088 -180.165502)
			(xy 78.901544 -180.165502) (xy 78.901544 -180.558948) (xy 82.960462 -180.558948) (xy 82.964533 -180.503326)
			(xy 82.976659 -180.448889) (xy 82.996582 -180.396798) (xy 83.023878 -180.348163) (xy 83.057964 -180.30402)
			(xy 83.098113 -180.265311) (xy 83.143471 -180.23286) (xy 83.193071 -180.207359) (xy 83.245855 -180.189352)
			(xy 83.300698 -180.179222) (xy 83.356432 -180.177185) (xy 83.411869 -180.183285) (xy 83.465826 -180.197391)
			(xy 83.517155 -180.219203) (xy 83.564761 -180.248257) (xy 83.607629 -180.283932) (xy 83.644846 -180.325469)
			(xy 83.675619 -180.371982) (xy 83.699291 -180.422479) (xy 83.715359 -180.475886) (xy 83.723479 -180.531062)
			(xy 83.723988 -180.558948) (xy 83.723479 -180.586834) (xy 83.715359 -180.64201) (xy 83.699291 -180.695417)
			(xy 83.675619 -180.745914) (xy 83.644846 -180.792427) (xy 83.607629 -180.833964) (xy 83.564761 -180.869639)
			(xy 83.517155 -180.898693) (xy 83.465826 -180.920505) (xy 83.411869 -180.934611) (xy 83.356432 -180.940711)
			(xy 83.300698 -180.938674) (xy 83.245855 -180.928544) (xy 83.193071 -180.910537) (xy 83.143471 -180.885036)
			(xy 83.098113 -180.852585) (xy 83.057964 -180.813876) (xy 83.023878 -180.769733) (xy 82.996582 -180.721098)
			(xy 82.976659 -180.669007) (xy 82.964533 -180.61457) (xy 82.960462 -180.558948) (xy 78.901544 -180.558948)
			(xy 78.901544 -181.66461) (xy 84.87994 -181.66461) (xy 84.884011 -181.608988) (xy 84.896137 -181.554551)
			(xy 84.91606 -181.50246) (xy 84.943356 -181.453825) (xy 84.977442 -181.409682) (xy 85.017591 -181.370973)
			(xy 85.062949 -181.338522) (xy 85.112549 -181.313021) (xy 85.165333 -181.295014) (xy 85.220176 -181.284884)
			(xy 85.27591 -181.282847) (xy 85.331347 -181.288947) (xy 85.385304 -181.303053) (xy 85.436633 -181.324865)
			(xy 85.484239 -181.353919) (xy 85.527107 -181.389594) (xy 85.564324 -181.431131) (xy 85.595097 -181.477644)
			(xy 85.618769 -181.528141) (xy 85.634837 -181.581548) (xy 85.642957 -181.636724) (xy 85.643466 -181.66461)
			(xy 85.642957 -181.692496) (xy 85.636968 -181.73319) (xy 88.31148 -181.73319) (xy 88.315551 -181.677568)
			(xy 88.327677 -181.623131) (xy 88.3476 -181.57104) (xy 88.374896 -181.522405) (xy 88.408982 -181.478262)
			(xy 88.449131 -181.439553) (xy 88.494489 -181.407102) (xy 88.544089 -181.381601) (xy 88.596873 -181.363594)
			(xy 88.651716 -181.353464) (xy 88.70745 -181.351427) (xy 88.762887 -181.357527) (xy 88.816844 -181.371633)
			(xy 88.868173 -181.393445) (xy 88.915779 -181.422499) (xy 88.958647 -181.458174) (xy 88.995864 -181.499711)
			(xy 89.026637 -181.546224) (xy 89.050309 -181.596721) (xy 89.066377 -181.650128) (xy 89.074497 -181.705304)
			(xy 89.075006 -181.73319) (xy 89.074497 -181.761076) (xy 89.066377 -181.816252) (xy 89.050309 -181.869659)
			(xy 89.026637 -181.920156) (xy 88.995864 -181.966669) (xy 88.958647 -182.008206) (xy 88.915779 -182.043881)
			(xy 88.868173 -182.072935) (xy 88.816844 -182.094747) (xy 88.762887 -182.108853) (xy 88.70745 -182.114953)
			(xy 88.651716 -182.112916) (xy 88.596873 -182.102786) (xy 88.544089 -182.084779) (xy 88.494489 -182.059278)
			(xy 88.449131 -182.026827) (xy 88.408982 -181.988118) (xy 88.374896 -181.943975) (xy 88.3476 -181.89534)
			(xy 88.327677 -181.843249) (xy 88.315551 -181.788812) (xy 88.31148 -181.73319) (xy 85.636968 -181.73319)
			(xy 85.634837 -181.747672) (xy 85.618769 -181.801079) (xy 85.595097 -181.851576) (xy 85.564324 -181.898089)
			(xy 85.527107 -181.939626) (xy 85.484239 -181.975301) (xy 85.436633 -182.004355) (xy 85.385304 -182.026167)
			(xy 85.331347 -182.040273) (xy 85.27591 -182.046373) (xy 85.220176 -182.044336) (xy 85.165333 -182.034206)
			(xy 85.112549 -182.016199) (xy 85.062949 -181.990698) (xy 85.017591 -181.958247) (xy 84.977442 -181.919538)
			(xy 84.943356 -181.875395) (xy 84.91606 -181.82676) (xy 84.896137 -181.774669) (xy 84.884011 -181.720232)
			(xy 84.87994 -181.66461) (xy 78.901544 -181.66461) (xy 78.901544 -183.068722) (xy 89.559382 -183.068722)
			(xy 89.563453 -183.0131) (xy 89.575579 -182.958663) (xy 89.595502 -182.906572) (xy 89.622798 -182.857937)
			(xy 89.656884 -182.813794) (xy 89.697033 -182.775085) (xy 89.742391 -182.742634) (xy 89.791991 -182.717133)
			(xy 89.844775 -182.699126) (xy 89.899618 -182.688996) (xy 89.955352 -182.686959) (xy 90.010789 -182.693059)
			(xy 90.064746 -182.707165) (xy 90.116075 -182.728977) (xy 90.163681 -182.758031) (xy 90.206549 -182.793706)
			(xy 90.243766 -182.835243) (xy 90.274539 -182.881756) (xy 90.298211 -182.932253) (xy 90.314279 -182.98566)
			(xy 90.322399 -183.040836) (xy 90.322908 -183.068722) (xy 90.322399 -183.096608) (xy 90.314279 -183.151784)
			(xy 90.298211 -183.205191) (xy 90.274539 -183.255688) (xy 90.243766 -183.302201) (xy 90.206549 -183.343738)
			(xy 90.163681 -183.379413) (xy 90.116075 -183.408467) (xy 90.064746 -183.430279) (xy 90.010789 -183.444385)
			(xy 89.955352 -183.450485) (xy 89.899618 -183.448448) (xy 89.844775 -183.438318) (xy 89.791991 -183.420311)
			(xy 89.742391 -183.39481) (xy 89.697033 -183.362359) (xy 89.656884 -183.32365) (xy 89.622798 -183.279507)
			(xy 89.595502 -183.230872) (xy 89.575579 -183.178781) (xy 89.563453 -183.124344) (xy 89.559382 -183.068722)
			(xy 78.901544 -183.068722) (xy 78.901544 -184.994042) (xy 84.740496 -184.994042) (xy 84.740951 -184.966084)
			(xy 84.749132 -184.910771) (xy 84.765297 -184.857243) (xy 84.7891 -184.806646) (xy 84.820031 -184.760064)
			(xy 84.857427 -184.718494) (xy 84.900489 -184.682826) (xy 84.924138 -184.667906) (xy 84.937026 -184.659357)
			(xy 84.957433 -184.636144) (xy 84.969973 -184.607895) (xy 84.973502 -184.577189) (xy 84.967696 -184.546832)
			(xy 84.953087 -184.519595) (xy 84.942426 -184.508394) (xy 84.924508 -184.490388) (xy 84.893149 -184.450424)
			(xy 84.86737 -184.406653) (xy 84.847626 -184.359849) (xy 84.834266 -184.310839) (xy 84.827528 -184.260489)
			(xy 84.82711 -184.23509) (xy 84.827596 -184.207839) (xy 84.835352 -184.153891) (xy 84.850707 -184.101596)
			(xy 84.873349 -184.052019) (xy 84.902815 -184.006169) (xy 84.938506 -183.964978) (xy 84.979697 -183.929287)
			(xy 85.025547 -183.899821) (xy 85.075124 -183.877179) (xy 85.127419 -183.861824) (xy 85.181367 -183.854068)
			(xy 85.235869 -183.854068) (xy 85.289817 -183.861824) (xy 85.342112 -183.877179) (xy 85.391689 -183.899821)
			(xy 85.437539 -183.929287) (xy 85.47873 -183.964978) (xy 85.514421 -184.006169) (xy 85.543887 -184.052019)
			(xy 85.566529 -184.101596) (xy 85.581884 -184.153891) (xy 85.58964 -184.207839) (xy 85.590126 -184.23509)
			(xy 85.589608 -184.263045) (xy 85.581436 -184.318356) (xy 85.565281 -184.371882) (xy 85.541489 -184.422478)
			(xy 85.510569 -184.46906) (xy 85.473182 -184.510632) (xy 85.430129 -184.546304) (xy 85.406484 -184.561226)
			(xy 85.393568 -184.569738) (xy 85.373157 -184.592959) (xy 85.360616 -184.621218) (xy 85.357092 -184.651933)
			(xy 85.362906 -184.682297) (xy 85.377528 -184.709538) (xy 85.388196 -184.720738) (xy 85.406115 -184.738743)
			(xy 85.437477 -184.778705) (xy 85.463258 -184.822476) (xy 85.483002 -184.869281) (xy 85.49636 -184.918292)
			(xy 85.503096 -184.968642) (xy 85.503512 -184.994042) (xy 85.503026 -185.021293) (xy 85.49527 -185.075241)
			(xy 85.488385 -185.09869) (xy 88.01989 -185.09869) (xy 88.020376 -185.071439) (xy 88.028132 -185.017491)
			(xy 88.043487 -184.965196) (xy 88.066129 -184.915619) (xy 88.095595 -184.869769) (xy 88.131286 -184.828578)
			(xy 88.172477 -184.792887) (xy 88.218327 -184.763421) (xy 88.267904 -184.740779) (xy 88.320199 -184.725424)
			(xy 88.374147 -184.717668) (xy 88.428649 -184.717668) (xy 88.482597 -184.725424) (xy 88.534892 -184.740779)
			(xy 88.584469 -184.763421) (xy 88.630319 -184.792887) (xy 88.67151 -184.828578) (xy 88.707201 -184.869769)
			(xy 88.736667 -184.915619) (xy 88.759309 -184.965196) (xy 88.774664 -185.017491) (xy 88.78242 -185.071439)
			(xy 88.782906 -185.09869) (xy 88.782775 -185.106151) (xy 89.250256 -185.106151) (xy 89.250256 -185.051649)
			(xy 89.258012 -184.997701) (xy 89.273366 -184.945406) (xy 89.296006 -184.895828) (xy 89.325471 -184.849977)
			(xy 89.361161 -184.808785) (xy 89.402349 -184.773091) (xy 89.448198 -184.743622) (xy 89.497774 -184.720978)
			(xy 89.550068 -184.705619) (xy 89.604015 -184.697858) (xy 89.631266 -184.69737) (xy 89.658143 -184.697838)
			(xy 89.711364 -184.705384) (xy 89.762997 -184.720332) (xy 89.812018 -184.742384) (xy 89.857456 -184.771105)
			(xy 89.898409 -184.805923) (xy 89.934064 -184.846148) (xy 89.949274 -184.868312) (xy 89.957211 -184.879439)
			(xy 89.977773 -184.897425) (xy 90.002373 -184.909305) (xy 90.029244 -184.914224) (xy 90.056457 -184.911831)
			(xy 90.082057 -184.902296) (xy 90.104206 -184.886305) (xy 90.113104 -184.875932) (xy 90.131324 -184.854138)
			(xy 90.173121 -184.815668) (xy 90.220158 -184.78382) (xy 90.271396 -184.759296) (xy 90.325704 -184.742638)
			(xy 90.381881 -184.734215) (xy 90.410284 -184.733692) (xy 90.437538 -184.734154) (xy 90.49149 -184.741909)
			(xy 90.54379 -184.757264) (xy 90.593372 -184.779906) (xy 90.639227 -184.809373) (xy 90.680422 -184.845067)
			(xy 90.716117 -184.88626) (xy 90.745587 -184.932114) (xy 90.76823 -184.981695) (xy 90.783587 -185.033994)
			(xy 90.791345 -185.087946) (xy 90.791345 -185.142454) (xy 90.783587 -185.196406) (xy 90.76823 -185.248705)
			(xy 90.745587 -185.298286) (xy 90.716117 -185.34414) (xy 90.680422 -185.385333) (xy 90.639227 -185.421027)
			(xy 90.593372 -185.450494) (xy 90.54379 -185.473136) (xy 90.49149 -185.488491) (xy 90.437538 -185.496246)
			(xy 90.410284 -185.496708) (xy 90.383406 -185.496288) (xy 90.330182 -185.488734) (xy 90.278547 -185.473779)
			(xy 90.229525 -185.451719) (xy 90.184088 -185.422991) (xy 90.143137 -185.388166) (xy 90.107484 -185.347933)
			(xy 90.092276 -185.325766) (xy 90.0844 -185.314593) (xy 90.063823 -185.296609) (xy 90.03921 -185.284734)
			(xy 90.012328 -185.279822) (xy 89.985106 -185.282224) (xy 89.959499 -185.291768) (xy 89.937346 -185.307769)
			(xy 89.928446 -185.318146) (xy 89.910193 -185.339912) (xy 89.868404 -185.378384) (xy 89.821374 -185.410237)
			(xy 89.770142 -185.434766) (xy 89.715839 -185.451429) (xy 89.659667 -185.459859) (xy 89.631266 -185.460386)
			(xy 89.604015 -185.459942) (xy 89.550068 -185.452181) (xy 89.497774 -185.436822) (xy 89.448198 -185.414178)
			(xy 89.402349 -185.384709) (xy 89.361161 -185.349015) (xy 89.325471 -185.307823) (xy 89.296006 -185.261972)
			(xy 89.273366 -185.212394) (xy 89.258012 -185.160099) (xy 89.250256 -185.106151) (xy 88.782775 -185.106151)
			(xy 88.782439 -185.125319) (xy 88.775033 -185.178061) (xy 88.760362 -185.229259) (xy 88.738713 -185.27792)
			(xy 88.710505 -185.323096) (xy 88.693752 -185.3438) (xy 88.685499 -185.354452) (xy 88.674248 -185.378923)
			(xy 88.669782 -185.405482) (xy 88.67241 -185.432287) (xy 88.681951 -185.457473) (xy 88.697741 -185.479292)
			(xy 88.718683 -185.496227) (xy 88.730836 -185.502042) (xy 88.755922 -185.513559) (xy 88.80274 -185.542797)
			(xy 88.844853 -185.57848) (xy 88.881381 -185.619862) (xy 88.911561 -185.666078) (xy 88.934763 -185.716163)
			(xy 88.950501 -185.76907) (xy 88.958446 -185.823693) (xy 88.958928 -185.851292) (xy 88.958435 -185.87767)
			(xy 88.951184 -185.929924) (xy 88.936805 -185.980683) (xy 88.915573 -186.028977) (xy 88.887892 -186.073886)
			(xy 88.85429 -186.114556) (xy 88.815407 -186.15021) (xy 88.771984 -186.180169) (xy 88.748616 -186.192414)
			(xy 88.736266 -186.199129) (xy 88.715542 -186.218104) (xy 88.700784 -186.242015) (xy 88.693113 -186.269047)
			(xy 88.693112 -186.297146) (xy 88.700781 -186.324178) (xy 88.715537 -186.348091) (xy 88.73626 -186.367067)
			(xy 88.748616 -186.37377) (xy 88.771987 -186.386011) (xy 88.81541 -186.415974) (xy 88.854295 -186.451629)
			(xy 88.887901 -186.492299) (xy 88.915588 -186.537208) (xy 88.936828 -186.585501) (xy 88.951218 -186.636258)
			(xy 88.958482 -186.688513) (xy 88.958928 -186.714892) (xy 88.958442 -186.742143) (xy 88.950686 -186.796091)
			(xy 88.935331 -186.848386) (xy 88.912689 -186.897963) (xy 88.883223 -186.943813) (xy 88.847532 -186.985004)
			(xy 88.828898 -187.00115) (xy 90.7796 -187.00115) (xy 90.780142 -186.974203) (xy 90.787733 -186.920846)
			(xy 90.802758 -186.869088) (xy 90.824918 -186.819959) (xy 90.85377 -186.774438) (xy 90.888741 -186.733431)
			(xy 90.929136 -186.697753) (xy 90.974149 -186.668114) (xy 91.022885 -186.645106) (xy 91.074375 -186.629185)
			(xy 91.10091 -186.624468) (xy 91.114738 -186.621771) (xy 91.140288 -186.609933) (xy 91.161632 -186.591565)
			(xy 91.177147 -186.568065) (xy 91.185652 -186.541221) (xy 91.186501 -186.513075) (xy 91.179628 -186.485767)
			(xy 91.165558 -186.461375) (xy 91.155774 -186.45124) (xy 91.137909 -186.433224) (xy 91.106612 -186.393289)
			(xy 91.080886 -186.349558) (xy 91.061183 -186.302803) (xy 91.047852 -186.253848) (xy 91.041128 -186.203559)
			(xy 91.040712 -186.17819) (xy 91.041313 -186.148537) (xy 91.050504 -186.089946) (xy 91.068647 -186.033482)
			(xy 91.095307 -185.980504) (xy 91.12984 -185.932288) (xy 91.171416 -185.889994) (xy 91.19489 -185.871866)
			(xy 91.206077 -185.863075) (xy 91.22337 -185.840491) (xy 91.233775 -185.814019) (xy 91.236488 -185.785704)
			(xy 91.231299 -185.757738) (xy 91.218609 -185.732281) (xy 91.1994 -185.711303) (xy 91.187524 -185.703464)
			(xy 91.164048 -185.688472) (xy 91.121263 -185.652809) (xy 91.084121 -185.611301) (xy 91.053413 -185.564831)
			(xy 91.029792 -185.514389) (xy 91.01376 -185.461047) (xy 91.005658 -185.40594) (xy 91.005152 -185.37809)
			(xy 91.00559 -185.351641) (xy 91.012878 -185.299247) (xy 91.027342 -185.248365) (xy 91.048703 -185.199972)
			(xy 91.076551 -185.154997) (xy 91.110351 -185.114306) (xy 91.149452 -185.078679) (xy 91.193105 -185.048802)
			(xy 91.24047 -185.025248) (xy 91.290636 -185.00847) (xy 91.316556 -185.003186) (xy 91.33081 -185.000008)
			(xy 91.356817 -184.986752) (xy 91.378026 -184.966696) (xy 91.392713 -184.941469) (xy 91.399684 -184.913123)
			(xy 91.398371 -184.883962) (xy 91.388881 -184.856357) (xy 91.380818 -184.844182) (xy 91.364117 -184.819831)
			(xy 91.337663 -184.767041) (xy 91.319655 -184.710807) (xy 91.310523 -184.652471) (xy 91.309952 -184.622948)
			(xy 91.310438 -184.595697) (xy 91.318194 -184.541749) (xy 91.333549 -184.489454) (xy 91.356191 -184.439877)
			(xy 91.385657 -184.394027) (xy 91.421348 -184.352836) (xy 91.462539 -184.317145) (xy 91.508389 -184.287679)
			(xy 91.557966 -184.265037) (xy 91.610261 -184.249682) (xy 91.664209 -184.241926) (xy 91.718711 -184.241926)
			(xy 91.772659 -184.249682) (xy 91.824954 -184.265037) (xy 91.874531 -184.287679) (xy 91.920381 -184.317145)
			(xy 91.961572 -184.352836) (xy 91.997263 -184.394027) (xy 92.026729 -184.439877) (xy 92.049371 -184.489454)
			(xy 92.064726 -184.541749) (xy 92.072482 -184.595697) (xy 92.072968 -184.622948) (xy 92.072549 -184.649397)
			(xy 92.065255 -184.701791) (xy 92.050788 -184.752673) (xy 92.029423 -184.801065) (xy 92.001573 -184.846039)
			(xy 91.967772 -184.88673) (xy 91.928669 -184.922356) (xy 91.885016 -184.952233) (xy 91.837651 -184.975788)
			(xy 91.787484 -184.992567) (xy 91.761564 -184.997852) (xy 91.747297 -185.000984) (xy 91.72128 -185.014243)
			(xy 91.700065 -185.034306) (xy 91.685376 -185.059543) (xy 91.678409 -185.087899) (xy 91.67973 -185.117069)
			(xy 91.689231 -185.14468) (xy 91.697302 -185.156856) (xy 91.713967 -185.181231) (xy 91.740431 -185.234011)
			(xy 91.75845 -185.290238) (xy 91.767592 -185.348569) (xy 91.768168 -185.37809) (xy 91.767633 -185.407746)
			(xy 91.75843 -185.46634) (xy 91.740273 -185.522806) (xy 91.713602 -185.575783) (xy 91.679056 -185.623998)
			(xy 91.637469 -185.666288) (xy 91.61399 -185.684414) (xy 91.602827 -185.693231) (xy 91.585537 -185.71581)
			(xy 91.575133 -185.742276) (xy 91.572418 -185.770584) (xy 91.577602 -185.798545) (xy 91.590284 -185.823998)
			(xy 91.609485 -185.844975) (xy 91.621356 -185.852816) (xy 91.644841 -185.867794) (xy 91.687622 -185.903462)
			(xy 91.724761 -185.944974) (xy 91.755466 -185.991446) (xy 91.779086 -186.04189) (xy 91.795118 -186.095233)
			(xy 91.803221 -186.15034) (xy 91.803728 -186.17819) (xy 91.803283 -186.205141) (xy 91.795684 -186.258505)
			(xy 91.780651 -186.310268) (xy 91.758482 -186.359401) (xy 91.729619 -186.404924) (xy 91.694636 -186.445932)
			(xy 91.65423 -186.481609) (xy 91.609205 -186.511244) (xy 91.560458 -186.534247) (xy 91.508958 -186.55016)
			(xy 91.482418 -186.554872) (xy 91.468576 -186.557515) (xy 91.443014 -186.569355) (xy 91.421661 -186.587729)
			(xy 91.406141 -186.611239) (xy 91.402756 -186.621928) (xy 96.394522 -186.621928) (xy 96.398593 -186.566306)
			(xy 96.410719 -186.511869) (xy 96.430642 -186.459778) (xy 96.457938 -186.411143) (xy 96.492024 -186.367)
			(xy 96.532173 -186.328291) (xy 96.577531 -186.29584) (xy 96.627131 -186.270339) (xy 96.679915 -186.252332)
			(xy 96.734758 -186.242202) (xy 96.790492 -186.240165) (xy 96.845929 -186.246265) (xy 96.899886 -186.260371)
			(xy 96.951215 -186.282183) (xy 96.998821 -186.311237) (xy 97.041689 -186.346912) (xy 97.078906 -186.388449)
			(xy 97.109679 -186.434962) (xy 97.133351 -186.485459) (xy 97.149419 -186.538866) (xy 97.157539 -186.594042)
			(xy 97.158048 -186.621928) (xy 97.157539 -186.649814) (xy 97.149419 -186.70499) (xy 97.133351 -186.758397)
			(xy 97.109679 -186.808894) (xy 97.078906 -186.855407) (xy 97.041689 -186.896944) (xy 96.998821 -186.932619)
			(xy 96.951215 -186.961673) (xy 96.899886 -186.983485) (xy 96.845929 -186.997591) (xy 96.790492 -187.003691)
			(xy 96.734758 -187.001654) (xy 96.679915 -186.991524) (xy 96.627131 -186.973517) (xy 96.577531 -186.948016)
			(xy 96.532173 -186.915565) (xy 96.492024 -186.876856) (xy 96.457938 -186.832713) (xy 96.430642 -186.784078)
			(xy 96.410719 -186.731987) (xy 96.398593 -186.67755) (xy 96.394522 -186.621928) (xy 91.402756 -186.621928)
			(xy 91.397636 -186.638095) (xy 91.396793 -186.666253) (xy 91.403676 -186.693569) (xy 91.417762 -186.717965)
			(xy 91.427554 -186.7281) (xy 91.445396 -186.746138) (xy 91.476693 -186.786069) (xy 91.502422 -186.829795)
			(xy 91.522129 -186.876546) (xy 91.535465 -186.925497) (xy 91.542196 -186.975783) (xy 91.542616 -187.00115)
			(xy 91.54213 -187.028401) (xy 91.534374 -187.082349) (xy 91.519019 -187.134644) (xy 91.496377 -187.184221)
			(xy 91.466911 -187.230071) (xy 91.43122 -187.271262) (xy 91.390029 -187.306953) (xy 91.344179 -187.336419)
			(xy 91.294602 -187.359061) (xy 91.242307 -187.374416) (xy 91.188359 -187.382172) (xy 91.133857 -187.382172)
			(xy 91.079909 -187.374416) (xy 91.027614 -187.359061) (xy 90.978037 -187.336419) (xy 90.932187 -187.306953)
			(xy 90.890996 -187.271262) (xy 90.855305 -187.230071) (xy 90.825839 -187.184221) (xy 90.803197 -187.134644)
			(xy 90.787842 -187.082349) (xy 90.780086 -187.028401) (xy 90.7796 -187.00115) (xy 88.828898 -187.00115)
			(xy 88.806341 -187.020695) (xy 88.760491 -187.050161) (xy 88.710914 -187.072803) (xy 88.658619 -187.088158)
			(xy 88.604671 -187.095914) (xy 88.550169 -187.095914) (xy 88.496221 -187.088158) (xy 88.443926 -187.072803)
			(xy 88.394349 -187.050161) (xy 88.348499 -187.020695) (xy 88.307308 -186.985004) (xy 88.271617 -186.943813)
			(xy 88.242151 -186.897963) (xy 88.219509 -186.848386) (xy 88.204154 -186.796091) (xy 88.196398 -186.742143)
			(xy 88.195912 -186.714892) (xy 88.19637 -186.688513) (xy 88.203624 -186.636256) (xy 88.218006 -186.585496)
			(xy 88.239243 -186.5372) (xy 88.266929 -186.49229) (xy 88.300536 -186.451622) (xy 88.339425 -186.415969)
			(xy 88.382854 -186.386013) (xy 88.406224 -186.37377) (xy 88.418594 -186.367084) (xy 88.439332 -186.348109)
			(xy 88.4541 -186.324192) (xy 88.461775 -186.297151) (xy 88.461774 -186.269042) (xy 88.454097 -186.242002)
			(xy 88.439327 -186.218086) (xy 88.418588 -186.199112) (xy 88.406224 -186.192414) (xy 88.382856 -186.180168)
			(xy 88.33943 -186.150208) (xy 88.300544 -186.114554) (xy 88.266937 -186.073885) (xy 88.239249 -186.028977)
			(xy 88.218009 -185.980684) (xy 88.20362 -185.929926) (xy 88.196357 -185.877671) (xy 88.195912 -185.851292)
			(xy 88.196364 -185.824662) (xy 88.203774 -185.77192) (xy 88.218448 -185.720721) (xy 88.2401 -185.672061)
			(xy 88.268311 -185.626886) (xy 88.285066 -185.606182) (xy 88.293333 -185.595541) (xy 88.30458 -185.571067)
			(xy 88.309042 -185.544505) (xy 88.306411 -185.5177) (xy 88.296869 -185.492513) (xy 88.281078 -185.470693)
			(xy 88.260135 -185.453757) (xy 88.247982 -185.44794) (xy 88.22291 -185.436398) (xy 88.176097 -185.407158)
			(xy 88.133987 -185.371476) (xy 88.097461 -185.330097) (xy 88.06728 -185.283886) (xy 88.044076 -185.233806)
			(xy 88.028332 -185.180905) (xy 88.020378 -185.126287) (xy 88.01989 -185.09869) (xy 85.488385 -185.09869)
			(xy 85.479915 -185.127536) (xy 85.457273 -185.177113) (xy 85.427807 -185.222963) (xy 85.392116 -185.264154)
			(xy 85.350925 -185.299845) (xy 85.305075 -185.329311) (xy 85.255498 -185.351953) (xy 85.203203 -185.367308)
			(xy 85.149255 -185.375064) (xy 85.094753 -185.375064) (xy 85.040805 -185.367308) (xy 84.98851 -185.351953)
			(xy 84.938933 -185.329311) (xy 84.893083 -185.299845) (xy 84.851892 -185.264154) (xy 84.816201 -185.222963)
			(xy 84.786735 -185.177113) (xy 84.764093 -185.127536) (xy 84.748738 -185.075241) (xy 84.740982 -185.021293)
			(xy 84.740496 -184.994042) (xy 78.901544 -184.994042) (xy 78.901544 -187.00115) (xy 80.78546 -187.00115)
			(xy 80.789531 -186.945528) (xy 80.801657 -186.891091) (xy 80.82158 -186.839) (xy 80.848876 -186.790365)
			(xy 80.882962 -186.746222) (xy 80.923111 -186.707513) (xy 80.968469 -186.675062) (xy 81.018069 -186.649561)
			(xy 81.070853 -186.631554) (xy 81.125696 -186.621424) (xy 81.18143 -186.619387) (xy 81.236867 -186.625487)
			(xy 81.290824 -186.639593) (xy 81.342153 -186.661405) (xy 81.389759 -186.690459) (xy 81.432627 -186.726134)
			(xy 81.469844 -186.767671) (xy 81.500617 -186.814184) (xy 81.524289 -186.864681) (xy 81.540357 -186.918088)
			(xy 81.544357 -186.94527) (xy 82.700876 -186.94527) (xy 82.701367 -186.915951) (xy 82.710337 -186.858004)
			(xy 82.728075 -186.802114) (xy 82.754163 -186.749599) (xy 82.787986 -186.7017) (xy 82.828745 -186.659545)
			(xy 82.87548 -186.62413) (xy 82.901028 -186.609736) (xy 82.912821 -186.602843) (xy 82.932557 -186.583976)
			(xy 82.946585 -186.560552) (xy 82.953901 -186.534247) (xy 82.953981 -186.506944) (xy 82.946819 -186.480597)
			(xy 82.932928 -186.457091) (xy 82.913303 -186.438109) (xy 82.901536 -186.431174) (xy 82.876258 -186.416693)
			(xy 82.830048 -186.381224) (xy 82.78977 -186.339139) (xy 82.756361 -186.291418) (xy 82.730599 -186.23917)
			(xy 82.713084 -186.183612) (xy 82.704222 -186.126037) (xy 82.70367 -186.09691) (xy 82.704156 -186.069659)
			(xy 82.711912 -186.015711) (xy 82.727267 -185.963416) (xy 82.749909 -185.913839) (xy 82.779375 -185.867989)
			(xy 82.815066 -185.826798) (xy 82.856257 -185.791107) (xy 82.902107 -185.761641) (xy 82.951684 -185.738999)
			(xy 83.003979 -185.723644) (xy 83.057927 -185.715888) (xy 83.112429 -185.715888) (xy 83.166377 -185.723644)
			(xy 83.218672 -185.738999) (xy 83.268249 -185.761641) (xy 83.314099 -185.791107) (xy 83.35529 -185.826798)
			(xy 83.390981 -185.867989) (xy 83.420447 -185.913839) (xy 83.443089 -185.963416) (xy 83.458444 -186.015711)
			(xy 83.4662 -186.069659) (xy 83.466686 -186.09691) (xy 83.466146 -186.126227) (xy 83.457181 -186.18417)
			(xy 83.439449 -186.240058) (xy 83.413369 -186.292571) (xy 83.379554 -186.340471) (xy 83.338803 -186.382628)
			(xy 83.292078 -186.418047) (xy 83.266534 -186.432444) (xy 83.254763 -186.439368) (xy 83.235035 -186.458232)
			(xy 83.221013 -186.48165) (xy 83.213699 -186.507947) (xy 83.213617 -186.535242) (xy 83.220772 -186.561583)
			(xy 83.234652 -186.585085) (xy 83.254265 -186.604068) (xy 83.266026 -186.611006) (xy 83.291286 -186.625516)
			(xy 83.337498 -186.660979) (xy 83.377779 -186.703058) (xy 83.41119 -186.750775) (xy 83.436955 -186.803018)
			(xy 83.454474 -186.858572) (xy 83.463338 -186.916145) (xy 83.463892 -186.94527) (xy 83.463406 -186.972521)
			(xy 83.458925 -187.00369) (xy 85.49462 -187.00369) (xy 85.498691 -186.948068) (xy 85.510817 -186.893631)
			(xy 85.53074 -186.84154) (xy 85.558036 -186.792905) (xy 85.592122 -186.748762) (xy 85.632271 -186.710053)
			(xy 85.677629 -186.677602) (xy 85.727229 -186.652101) (xy 85.780013 -186.634094) (xy 85.834856 -186.623964)
			(xy 85.89059 -186.621927) (xy 85.946027 -186.628027) (xy 85.999984 -186.642133) (xy 86.051313 -186.663945)
			(xy 86.098919 -186.692999) (xy 86.141787 -186.728674) (xy 86.179004 -186.770211) (xy 86.209777 -186.816724)
			(xy 86.233449 -186.867221) (xy 86.249517 -186.920628) (xy 86.257637 -186.975804) (xy 86.258146 -187.00369)
			(xy 86.257637 -187.031576) (xy 86.249517 -187.086752) (xy 86.233449 -187.140159) (xy 86.209777 -187.190656)
			(xy 86.179004 -187.237169) (xy 86.141787 -187.278706) (xy 86.098919 -187.314381) (xy 86.051313 -187.343435)
			(xy 85.999984 -187.365247) (xy 85.946027 -187.379353) (xy 85.89059 -187.385453) (xy 85.834856 -187.383416)
			(xy 85.780013 -187.373286) (xy 85.727229 -187.355279) (xy 85.677629 -187.329778) (xy 85.632271 -187.297327)
			(xy 85.592122 -187.258618) (xy 85.558036 -187.214475) (xy 85.53074 -187.16584) (xy 85.510817 -187.113749)
			(xy 85.498691 -187.059312) (xy 85.49462 -187.00369) (xy 83.458925 -187.00369) (xy 83.45565 -187.026469)
			(xy 83.440295 -187.078764) (xy 83.417653 -187.128341) (xy 83.388187 -187.174191) (xy 83.352496 -187.215382)
			(xy 83.311305 -187.251073) (xy 83.265455 -187.280539) (xy 83.215878 -187.303181) (xy 83.163583 -187.318536)
			(xy 83.109635 -187.326292) (xy 83.055133 -187.326292) (xy 83.001185 -187.318536) (xy 82.94889 -187.303181)
			(xy 82.899313 -187.280539) (xy 82.853463 -187.251073) (xy 82.812272 -187.215382) (xy 82.776581 -187.174191)
			(xy 82.747115 -187.128341) (xy 82.724473 -187.078764) (xy 82.709118 -187.026469) (xy 82.701362 -186.972521)
			(xy 82.700876 -186.94527) (xy 81.544357 -186.94527) (xy 81.548477 -186.973264) (xy 81.548986 -187.00115)
			(xy 81.548477 -187.029036) (xy 81.540357 -187.084212) (xy 81.524289 -187.137619) (xy 81.500617 -187.188116)
			(xy 81.469844 -187.234629) (xy 81.432627 -187.276166) (xy 81.389759 -187.311841) (xy 81.342153 -187.340895)
			(xy 81.290824 -187.362707) (xy 81.236867 -187.376813) (xy 81.18143 -187.382913) (xy 81.125696 -187.380876)
			(xy 81.070853 -187.370746) (xy 81.018069 -187.352739) (xy 80.968469 -187.327238) (xy 80.923111 -187.294787)
			(xy 80.882962 -187.256078) (xy 80.848876 -187.211935) (xy 80.82158 -187.1633) (xy 80.801657 -187.111209)
			(xy 80.789531 -187.056772) (xy 80.78546 -187.00115) (xy 78.901544 -187.00115) (xy 78.901544 -187.816236)
			(xy 87.107266 -187.816236) (xy 87.111337 -187.760614) (xy 87.123463 -187.706177) (xy 87.143386 -187.654086)
			(xy 87.170682 -187.605451) (xy 87.204768 -187.561308) (xy 87.244917 -187.522599) (xy 87.290275 -187.490148)
			(xy 87.339875 -187.464647) (xy 87.392659 -187.44664) (xy 87.447502 -187.43651) (xy 87.503236 -187.434473)
			(xy 87.558673 -187.440573) (xy 87.61263 -187.454679) (xy 87.663959 -187.476491) (xy 87.711565 -187.505545)
			(xy 87.754433 -187.54122) (xy 87.79165 -187.582757) (xy 87.822423 -187.62927) (xy 87.846095 -187.679767)
			(xy 87.862163 -187.733174) (xy 87.870283 -187.78835) (xy 87.870792 -187.816236) (xy 87.870283 -187.844122)
			(xy 87.862163 -187.899298) (xy 87.846095 -187.952705) (xy 87.822423 -188.003202) (xy 87.79165 -188.049715)
			(xy 87.754433 -188.091252) (xy 87.711565 -188.126927) (xy 87.663959 -188.155981) (xy 87.61263 -188.177793)
			(xy 87.558673 -188.191899) (xy 87.503236 -188.197999) (xy 87.447502 -188.195962) (xy 87.392659 -188.185832)
			(xy 87.339875 -188.167825) (xy 87.290275 -188.142324) (xy 87.244917 -188.109873) (xy 87.204768 -188.071164)
			(xy 87.170682 -188.027021) (xy 87.143386 -187.978386) (xy 87.123463 -187.926295) (xy 87.111337 -187.871858)
			(xy 87.107266 -187.816236) (xy 78.901544 -187.816236) (xy 78.901544 -189.73419) (xy 80.3816 -189.73419)
			(xy 80.385671 -189.678568) (xy 80.397797 -189.624131) (xy 80.41772 -189.57204) (xy 80.445016 -189.523405)
			(xy 80.479102 -189.479262) (xy 80.519251 -189.440553) (xy 80.564609 -189.408102) (xy 80.614209 -189.382601)
			(xy 80.666993 -189.364594) (xy 80.721836 -189.354464) (xy 80.77757 -189.352427) (xy 80.833007 -189.358527)
			(xy 80.886964 -189.372633) (xy 80.938293 -189.394445) (xy 80.985899 -189.423499) (xy 81.028767 -189.459174)
			(xy 81.065984 -189.500711) (xy 81.096757 -189.547224) (xy 81.120429 -189.597721) (xy 81.123354 -189.607444)
			(xy 85.075266 -189.607444) (xy 85.079337 -189.551822) (xy 85.091463 -189.497385) (xy 85.111386 -189.445294)
			(xy 85.138682 -189.396659) (xy 85.172768 -189.352516) (xy 85.212917 -189.313807) (xy 85.258275 -189.281356)
			(xy 85.307875 -189.255855) (xy 85.360659 -189.237848) (xy 85.415502 -189.227718) (xy 85.471236 -189.225681)
			(xy 85.526673 -189.231781) (xy 85.58063 -189.245887) (xy 85.631959 -189.267699) (xy 85.679565 -189.296753)
			(xy 85.722433 -189.332428) (xy 85.75965 -189.373965) (xy 85.790423 -189.420478) (xy 85.814095 -189.470975)
			(xy 85.830163 -189.524382) (xy 85.838283 -189.579558) (xy 85.838416 -189.58687) (xy 90.7796 -189.58687)
			(xy 90.780053 -189.560906) (xy 90.787096 -189.509458) (xy 90.801046 -189.459439) (xy 90.821648 -189.411772)
			(xy 90.84852 -189.367338) (xy 90.881167 -189.326956) (xy 90.918986 -189.291372) (xy 90.96128 -189.261243)
			(xy 90.98407 -189.248796) (xy 90.996136 -189.242005) (xy 91.016315 -189.223061) (xy 91.030654 -189.199388)
			(xy 91.038097 -189.17273) (xy 91.038095 -189.145052) (xy 91.030647 -189.118395) (xy 91.016303 -189.094724)
			(xy 90.996121 -189.075784) (xy 90.98407 -189.068964) (xy 90.961278 -189.056518) (xy 90.918979 -189.026393)
			(xy 90.881154 -188.990811) (xy 90.848503 -188.95043) (xy 90.821628 -188.905996) (xy 90.801025 -188.858327)
			(xy 90.787076 -188.808306) (xy 90.780036 -188.756855) (xy 90.7796 -188.73089) (xy 90.780094 -188.702548)
			(xy 90.788482 -188.646487) (xy 90.805073 -188.592285) (xy 90.8295 -188.541134) (xy 90.861227 -188.49416)
			(xy 90.899555 -188.452397) (xy 90.94364 -188.416765) (xy 90.967814 -188.40196) (xy 90.980564 -188.393795)
			(xy 91.001049 -188.371529) (xy 91.014109 -188.344237) (xy 91.018596 -188.314315) (xy 91.014118 -188.284393)
			(xy 91.001066 -188.257096) (xy 90.980588 -188.234824) (xy 90.967814 -188.2267) (xy 90.943614 -188.211939)
			(xy 90.899536 -188.176295) (xy 90.861217 -188.134522) (xy 90.829499 -188.08754) (xy 90.805079 -188.036383)
			(xy 90.788497 -187.982176) (xy 90.780115 -187.926113) (xy 90.7796 -187.89777) (xy 90.780086 -187.870519)
			(xy 90.787842 -187.816571) (xy 90.803197 -187.764276) (xy 90.825839 -187.714699) (xy 90.855305 -187.668849)
			(xy 90.890996 -187.627658) (xy 90.932187 -187.591967) (xy 90.978037 -187.562501) (xy 91.027614 -187.539859)
			(xy 91.079909 -187.524504) (xy 91.133857 -187.516748) (xy 91.188359 -187.516748) (xy 91.242307 -187.524504)
			(xy 91.294602 -187.539859) (xy 91.344179 -187.562501) (xy 91.390029 -187.591967) (xy 91.43122 -187.627658)
			(xy 91.466911 -187.668849) (xy 91.496377 -187.714699) (xy 91.519019 -187.764276) (xy 91.534374 -187.816571)
			(xy 91.54213 -187.870519) (xy 91.542616 -187.89777) (xy 91.542083 -187.926111) (xy 91.533701 -187.982169)
			(xy 91.517116 -188.03637) (xy 91.492695 -188.087521) (xy 91.460974 -188.134495) (xy 91.422653 -188.176259)
			(xy 91.378573 -188.211894) (xy 91.354402 -188.2267) (xy 91.341594 -188.234782) (xy 91.321102 -188.257065)
			(xy 91.308042 -188.284376) (xy 91.30356 -188.314315) (xy 91.308051 -188.344253) (xy 91.321119 -188.37156)
			(xy 91.341618 -188.393837) (xy 91.354402 -188.40196) (xy 91.378565 -188.416779) (xy 91.422647 -188.452411)
			(xy 91.460971 -188.494172) (xy 91.492696 -188.541144) (xy 91.517121 -188.592293) (xy 91.53371 -188.646492)
			(xy 91.542098 -188.702549) (xy 91.542616 -188.73089) (xy 91.542203 -188.756855) (xy 91.535153 -188.808305)
			(xy 91.521195 -188.858324) (xy 91.500587 -188.905991) (xy 91.47371 -188.950424) (xy 91.441058 -188.990805)
			(xy 91.403235 -189.026389) (xy 91.360938 -189.056518) (xy 91.338146 -189.068964) (xy 91.326114 -189.075812)
			(xy 91.305936 -189.094744) (xy 91.291594 -189.118407) (xy 91.284148 -189.145056) (xy 91.284146 -189.172726)
			(xy 91.291587 -189.199376) (xy 91.305924 -189.223041) (xy 91.326099 -189.241977) (xy 91.338146 -189.248796)
			(xy 91.360925 -189.261265) (xy 91.403223 -189.291388) (xy 91.441047 -189.326966) (xy 91.473699 -189.367344)
			(xy 91.500575 -189.411775) (xy 91.52118 -189.45944) (xy 91.535133 -189.509458) (xy 91.542177 -189.560906)
			(xy 91.542616 -189.58687) (xy 91.54213 -189.614121) (xy 91.534374 -189.668069) (xy 91.519019 -189.720364)
			(xy 91.496377 -189.769941) (xy 91.466911 -189.815791) (xy 91.43122 -189.856982) (xy 91.390029 -189.892673)
			(xy 91.344179 -189.922139) (xy 91.294602 -189.944781) (xy 91.242307 -189.960136) (xy 91.188359 -189.967892)
			(xy 91.133857 -189.967892) (xy 91.079909 -189.960136) (xy 91.027614 -189.944781) (xy 90.978037 -189.922139)
			(xy 90.932187 -189.892673) (xy 90.890996 -189.856982) (xy 90.855305 -189.815791) (xy 90.825839 -189.769941)
			(xy 90.803197 -189.720364) (xy 90.787842 -189.668069) (xy 90.780086 -189.614121) (xy 90.7796 -189.58687)
			(xy 85.838416 -189.58687) (xy 85.838792 -189.607444) (xy 85.838283 -189.63533) (xy 85.830163 -189.690506)
			(xy 85.814095 -189.743913) (xy 85.790423 -189.79441) (xy 85.75965 -189.840923) (xy 85.722433 -189.88246)
			(xy 85.679565 -189.918135) (xy 85.631959 -189.947189) (xy 85.58063 -189.969001) (xy 85.526673 -189.983107)
			(xy 85.471236 -189.989207) (xy 85.415502 -189.98717) (xy 85.360659 -189.97704) (xy 85.307875 -189.959033)
			(xy 85.258275 -189.933532) (xy 85.212917 -189.901081) (xy 85.172768 -189.862372) (xy 85.138682 -189.818229)
			(xy 85.111386 -189.769594) (xy 85.091463 -189.717503) (xy 85.079337 -189.663066) (xy 85.075266 -189.607444)
			(xy 81.123354 -189.607444) (xy 81.136497 -189.651128) (xy 81.144617 -189.706304) (xy 81.145126 -189.73419)
			(xy 81.144617 -189.762076) (xy 81.136497 -189.817252) (xy 81.120429 -189.870659) (xy 81.096757 -189.921156)
			(xy 81.065984 -189.967669) (xy 81.028767 -190.009206) (xy 80.985899 -190.044881) (xy 80.938293 -190.073935)
			(xy 80.886964 -190.095747) (xy 80.833007 -190.109853) (xy 80.77757 -190.115953) (xy 80.721836 -190.113916)
			(xy 80.666993 -190.103786) (xy 80.614209 -190.085779) (xy 80.564609 -190.060278) (xy 80.519251 -190.027827)
			(xy 80.479102 -189.989118) (xy 80.445016 -189.944975) (xy 80.41772 -189.89634) (xy 80.397797 -189.844249)
			(xy 80.385671 -189.789812) (xy 80.3816 -189.73419) (xy 78.901544 -189.73419) (xy 78.901544 -191.861948)
			(xy 88.009982 -191.861948) (xy 88.014053 -191.806326) (xy 88.026179 -191.751889) (xy 88.046102 -191.699798)
			(xy 88.073398 -191.651163) (xy 88.107484 -191.60702) (xy 88.147633 -191.568311) (xy 88.192991 -191.53586)
			(xy 88.242591 -191.510359) (xy 88.295375 -191.492352) (xy 88.350218 -191.482222) (xy 88.405952 -191.480185)
			(xy 88.461389 -191.486285) (xy 88.515346 -191.500391) (xy 88.566675 -191.522203) (xy 88.614281 -191.551257)
			(xy 88.657149 -191.586932) (xy 88.694366 -191.628469) (xy 88.725139 -191.674982) (xy 88.748811 -191.725479)
			(xy 88.764879 -191.778886) (xy 88.765521 -191.783249) (xy 90.780047 -191.783249) (xy 90.780048 -191.728741)
			(xy 90.787806 -191.674788) (xy 90.803163 -191.622489) (xy 90.825808 -191.572907) (xy 90.855278 -191.527052)
			(xy 90.890975 -191.485859) (xy 90.93217 -191.450165) (xy 90.978026 -191.420697) (xy 91.027609 -191.398056)
			(xy 91.07991 -191.382701) (xy 91.133863 -191.374946) (xy 91.188371 -191.374949) (xy 91.242324 -191.382709)
			(xy 91.294623 -191.398068) (xy 91.344204 -191.420714) (xy 91.390058 -191.450186) (xy 91.43125 -191.485884)
			(xy 91.466942 -191.52708) (xy 91.496409 -191.572937) (xy 91.519049 -191.622521) (xy 91.534402 -191.674822)
			(xy 91.542155 -191.728776) (xy 91.542616 -191.75603) (xy 91.542078 -191.785356) (xy 91.533092 -191.843314)
			(xy 91.515321 -191.899208) (xy 91.502738 -191.925702) (xy 91.496862 -191.938409) (xy 91.491773 -191.965935)
			(xy 91.494334 -191.993809) (xy 91.504351 -192.019947) (xy 91.521077 -192.042393) (xy 91.543259 -192.059467)
			(xy 91.569237 -192.069892) (xy 91.597068 -192.072887) (xy 91.610942 -192.07099) (xy 91.626944 -192.068384)
			(xy 91.659246 -192.065589) (xy 91.675458 -192.065402) (xy 91.702714 -192.06581) (xy 91.756673 -192.073562)
			(xy 91.808979 -192.088915) (xy 91.858568 -192.111555) (xy 91.90443 -192.141022) (xy 91.945632 -192.176716)
			(xy 91.981334 -192.217911) (xy 92.01081 -192.263767) (xy 92.03346 -192.313352) (xy 92.048822 -192.365655)
			(xy 92.056585 -192.419612) (xy 92.056589 -192.474125) (xy 92.048836 -192.528084) (xy 92.033482 -192.580389)
			(xy 92.01084 -192.629978) (xy 91.981371 -192.675839) (xy 91.945676 -192.717039) (xy 91.90448 -192.75274)
			(xy 91.858623 -192.782215) (xy 91.809038 -192.804863) (xy 91.756734 -192.820225) (xy 91.702777 -192.827986)
			(xy 91.648264 -192.827988) (xy 91.594306 -192.820233) (xy 91.542001 -192.804878) (xy 91.492413 -192.782235)
			(xy 91.446553 -192.752765) (xy 91.405353 -192.717068) (xy 91.369653 -192.675872) (xy 91.34018 -192.630014)
			(xy 91.317533 -192.580428) (xy 91.302173 -192.528124) (xy 91.294414 -192.474166) (xy 91.29395 -192.44691)
			(xy 91.294506 -192.417585) (xy 91.303485 -192.359628) (xy 91.321249 -192.303733) (xy 91.333828 -192.277238)
			(xy 91.339587 -192.264484) (xy 91.344675 -192.236979) (xy 91.342122 -192.209125) (xy 91.332118 -192.183003)
			(xy 91.315412 -192.160568) (xy 91.293253 -192.143498) (xy 91.267298 -192.13307) (xy 91.239489 -192.130062)
			(xy 91.225624 -192.13195) (xy 91.209621 -192.134547) (xy 91.177319 -192.137348) (xy 91.161108 -192.137538)
			(xy 91.133854 -192.137053) (xy 91.079901 -192.129297) (xy 91.0276 -192.113941) (xy 90.978018 -192.091298)
			(xy 90.932163 -192.061829) (xy 90.890968 -192.026134) (xy 90.855273 -191.98494) (xy 90.825803 -191.939085)
			(xy 90.80316 -191.889503) (xy 90.787804 -191.837203) (xy 90.780047 -191.783249) (xy 88.765521 -191.783249)
			(xy 88.772999 -191.834062) (xy 88.773508 -191.861948) (xy 88.772999 -191.889834) (xy 88.764879 -191.94501)
			(xy 88.748811 -191.998417) (xy 88.725139 -192.048914) (xy 88.694366 -192.095427) (xy 88.657149 -192.136964)
			(xy 88.614281 -192.172639) (xy 88.566675 -192.201693) (xy 88.515346 -192.223505) (xy 88.461389 -192.237611)
			(xy 88.405952 -192.243711) (xy 88.350218 -192.241674) (xy 88.295375 -192.231544) (xy 88.242591 -192.213537)
			(xy 88.192991 -192.188036) (xy 88.147633 -192.155585) (xy 88.107484 -192.116876) (xy 88.073398 -192.072733)
			(xy 88.046102 -192.024098) (xy 88.026179 -191.972007) (xy 88.014053 -191.91757) (xy 88.009982 -191.861948)
			(xy 78.901544 -191.861948) (xy 78.901544 -192.861692) (xy 82.24266 -196.202808) (xy 85.6394 -196.202808)
			(xy 85.643471 -196.147186) (xy 85.655597 -196.092749) (xy 85.67552 -196.040658) (xy 85.702816 -195.992023)
			(xy 85.736902 -195.94788) (xy 85.777051 -195.909171) (xy 85.822409 -195.87672) (xy 85.872009 -195.851219)
			(xy 85.924793 -195.833212) (xy 85.979636 -195.823082) (xy 86.03537 -195.821045) (xy 86.090807 -195.827145)
			(xy 86.144764 -195.841251) (xy 86.196093 -195.863063) (xy 86.243699 -195.892117) (xy 86.286567 -195.927792)
			(xy 86.323784 -195.969329) (xy 86.354557 -196.015842) (xy 86.378229 -196.066339) (xy 86.394297 -196.119746)
			(xy 86.402417 -196.174922) (xy 86.402926 -196.202808) (xy 86.402417 -196.230694) (xy 86.394297 -196.28587)
			(xy 86.378229 -196.339277) (xy 86.354557 -196.389774) (xy 86.327012 -196.431408) (xy 90.77909 -196.431408)
			(xy 90.783161 -196.375786) (xy 90.795287 -196.321349) (xy 90.81521 -196.269258) (xy 90.842506 -196.220623)
			(xy 90.876592 -196.17648) (xy 90.916741 -196.137771) (xy 90.962099 -196.10532) (xy 91.011699 -196.079819)
			(xy 91.064483 -196.061812) (xy 91.119326 -196.051682) (xy 91.17506 -196.049645) (xy 91.230497 -196.055745)
			(xy 91.284454 -196.069851) (xy 91.335783 -196.091663) (xy 91.383389 -196.120717) (xy 91.426257 -196.156392)
			(xy 91.463474 -196.197929) (xy 91.494247 -196.244442) (xy 91.517919 -196.294939) (xy 91.533987 -196.348346)
			(xy 91.542107 -196.403522) (xy 91.542616 -196.431408) (xy 91.542107 -196.459294) (xy 91.533987 -196.51447)
			(xy 91.517919 -196.567877) (xy 91.494247 -196.618374) (xy 91.463474 -196.664887) (xy 91.426257 -196.706424)
			(xy 91.383389 -196.742099) (xy 91.335783 -196.771153) (xy 91.284454 -196.792965) (xy 91.230497 -196.807071)
			(xy 91.17506 -196.813171) (xy 91.119326 -196.811134) (xy 91.064483 -196.801004) (xy 91.011699 -196.782997)
			(xy 90.962099 -196.757496) (xy 90.916741 -196.725045) (xy 90.876592 -196.686336) (xy 90.842506 -196.642193)
			(xy 90.81521 -196.593558) (xy 90.795287 -196.541467) (xy 90.783161 -196.48703) (xy 90.77909 -196.431408)
			(xy 86.327012 -196.431408) (xy 86.323784 -196.436287) (xy 86.286567 -196.477824) (xy 86.243699 -196.513499)
			(xy 86.196093 -196.542553) (xy 86.144764 -196.564365) (xy 86.090807 -196.578471) (xy 86.03537 -196.584571)
			(xy 85.979636 -196.582534) (xy 85.924793 -196.572404) (xy 85.872009 -196.554397) (xy 85.822409 -196.528896)
			(xy 85.777051 -196.496445) (xy 85.736902 -196.457736) (xy 85.702816 -196.413593) (xy 85.67552 -196.364958)
			(xy 85.655597 -196.312867) (xy 85.643471 -196.25843) (xy 85.6394 -196.202808) (xy 82.24266 -196.202808)
			(xy 83.689444 -197.649592) (xy 86.368128 -197.649592) (xy 86.37778 -197.611238) (xy 86.385095 -197.584097)
			(xy 86.406606 -197.532167) (xy 86.435505 -197.483955) (xy 86.471164 -197.440505) (xy 86.512813 -197.402758)
			(xy 86.55955 -197.37153) (xy 86.610363 -197.347498) (xy 86.664152 -197.331182) (xy 86.719753 -197.322934)
			(xy 86.775963 -197.322934) (xy 86.831564 -197.331182) (xy 86.885353 -197.347498) (xy 86.936166 -197.37153)
			(xy 86.982903 -197.402758) (xy 87.024552 -197.440505) (xy 87.060211 -197.483955) (xy 87.08911 -197.532167)
			(xy 87.110621 -197.584097) (xy 87.117936 -197.611238) (xy 87.127588 -197.649592) (xy 93.798644 -197.649592)
			(xy 105.534968 -209.385916) (xy 105.534968 -213.373716) (xy 105.57891 -213.379558) (xy 105.604244 -213.38339)
			(xy 105.653534 -213.397382) (xy 105.700309 -213.418297) (xy 105.743601 -213.445701) (xy 105.782518 -213.47903)
			(xy 105.816254 -213.517593) (xy 105.844112 -213.560595) (xy 105.865518 -213.607147) (xy 105.880028 -213.656287)
			(xy 105.887343 -213.706999) (xy 105.887774 -213.732618) (xy 105.887261 -213.759267) (xy 106.115856 -213.759267)
			(xy 106.115856 -213.705969) (xy 106.123799 -213.653265) (xy 106.139509 -213.602335) (xy 106.162635 -213.554314)
			(xy 106.192659 -213.510277) (xy 106.228911 -213.471206) (xy 106.270582 -213.437975) (xy 106.31674 -213.411326)
			(xy 106.366354 -213.391854) (xy 106.418316 -213.379994) (xy 106.471466 -213.376011) (xy 106.524616 -213.379994)
			(xy 106.576578 -213.391854) (xy 106.626192 -213.411326) (xy 106.67235 -213.437975) (xy 106.714021 -213.471206)
			(xy 106.750273 -213.510277) (xy 106.780297 -213.554314) (xy 106.803423 -213.602335) (xy 106.819133 -213.653265)
			(xy 106.827076 -213.705969) (xy 106.827574 -213.732618) (xy 107.055158 -213.732618) (xy 107.055656 -213.705969)
			(xy 107.063599 -213.653265) (xy 107.079309 -213.602335) (xy 107.102435 -213.554314) (xy 107.132459 -213.510277)
			(xy 107.168711 -213.471206) (xy 107.210382 -213.437975) (xy 107.25654 -213.411326) (xy 107.306154 -213.391854)
			(xy 107.358116 -213.379994) (xy 107.411266 -213.376011) (xy 107.464416 -213.379994) (xy 107.516378 -213.391854)
			(xy 107.565992 -213.411326) (xy 107.61215 -213.437975) (xy 107.653821 -213.471206) (xy 107.690073 -213.510277)
			(xy 107.720097 -213.554314) (xy 107.743223 -213.602335) (xy 107.758933 -213.653265) (xy 107.766876 -213.705969)
			(xy 107.767374 -213.732618) (xy 107.766852 -213.759267) (xy 107.995456 -213.759267) (xy 107.995456 -213.705969)
			(xy 108.003399 -213.653265) (xy 108.019109 -213.602335) (xy 108.042235 -213.554314) (xy 108.072259 -213.510277)
			(xy 108.108511 -213.471206) (xy 108.150182 -213.437975) (xy 108.19634 -213.411326) (xy 108.245954 -213.391854)
			(xy 108.297916 -213.379994) (xy 108.351066 -213.376011) (xy 108.404216 -213.379994) (xy 108.456178 -213.391854)
			(xy 108.505792 -213.411326) (xy 108.55195 -213.437975) (xy 108.593621 -213.471206) (xy 108.629873 -213.510277)
			(xy 108.659897 -213.554314) (xy 108.683023 -213.602335) (xy 108.698733 -213.653265) (xy 108.706676 -213.705969)
			(xy 108.707174 -213.732618) (xy 114.573558 -213.732618) (xy 114.574056 -213.705969) (xy 114.581999 -213.653265)
			(xy 114.597709 -213.602335) (xy 114.620835 -213.554314) (xy 114.650859 -213.510277) (xy 114.687111 -213.471206)
			(xy 114.728782 -213.437975) (xy 114.77494 -213.411326) (xy 114.824554 -213.391854) (xy 114.876516 -213.379994)
			(xy 114.929666 -213.376011) (xy 114.982816 -213.379994) (xy 115.034778 -213.391854) (xy 115.084392 -213.411326)
			(xy 115.13055 -213.437975) (xy 115.172221 -213.471206) (xy 115.208473 -213.510277) (xy 115.238497 -213.554314)
			(xy 115.261623 -213.602335) (xy 115.277333 -213.653265) (xy 115.285276 -213.705969) (xy 115.285774 -213.732618)
			(xy 115.285252 -213.759267) (xy 115.513856 -213.759267) (xy 115.513856 -213.705969) (xy 115.521799 -213.653265)
			(xy 115.537509 -213.602335) (xy 115.560635 -213.554314) (xy 115.590659 -213.510277) (xy 115.626911 -213.471206)
			(xy 115.668582 -213.437975) (xy 115.71474 -213.411326) (xy 115.764354 -213.391854) (xy 115.816316 -213.379994)
			(xy 115.869466 -213.376011) (xy 115.922616 -213.379994) (xy 115.974578 -213.391854) (xy 116.024192 -213.411326)
			(xy 116.07035 -213.437975) (xy 116.112021 -213.471206) (xy 116.148273 -213.510277) (xy 116.178297 -213.554314)
			(xy 116.201423 -213.602335) (xy 116.217133 -213.653265) (xy 116.225076 -213.705969) (xy 116.225574 -213.732618)
			(xy 116.453158 -213.732618) (xy 116.453656 -213.705969) (xy 116.461599 -213.653265) (xy 116.477309 -213.602335)
			(xy 116.500435 -213.554314) (xy 116.530459 -213.510277) (xy 116.566711 -213.471206) (xy 116.608382 -213.437975)
			(xy 116.65454 -213.411326) (xy 116.704154 -213.391854) (xy 116.756116 -213.379994) (xy 116.809266 -213.376011)
			(xy 116.862416 -213.379994) (xy 116.914378 -213.391854) (xy 116.963992 -213.411326) (xy 117.01015 -213.437975)
			(xy 117.051821 -213.471206) (xy 117.088073 -213.510277) (xy 117.118097 -213.554314) (xy 117.141223 -213.602335)
			(xy 117.156933 -213.653265) (xy 117.164876 -213.705969) (xy 117.165374 -213.732618) (xy 117.164852 -213.759267)
			(xy 117.393456 -213.759267) (xy 117.393456 -213.705969) (xy 117.401399 -213.653265) (xy 117.417109 -213.602335)
			(xy 117.440235 -213.554314) (xy 117.470259 -213.510277) (xy 117.506511 -213.471206) (xy 117.548182 -213.437975)
			(xy 117.59434 -213.411326) (xy 117.643954 -213.391854) (xy 117.695916 -213.379994) (xy 117.749066 -213.376011)
			(xy 117.802216 -213.379994) (xy 117.854178 -213.391854) (xy 117.903792 -213.411326) (xy 117.94995 -213.437975)
			(xy 117.991621 -213.471206) (xy 118.027873 -213.510277) (xy 118.057897 -213.554314) (xy 118.081023 -213.602335)
			(xy 118.096733 -213.653265) (xy 118.104676 -213.705969) (xy 118.105174 -213.732618) (xy 118.104676 -213.759267)
			(xy 118.096733 -213.811971) (xy 118.081023 -213.862901) (xy 118.057897 -213.910922) (xy 118.027873 -213.954959)
			(xy 117.991621 -213.99403) (xy 117.94995 -214.027261) (xy 117.903792 -214.05391) (xy 117.854178 -214.073382)
			(xy 117.802216 -214.085242) (xy 117.749066 -214.089226) (xy 117.695916 -214.085242) (xy 117.643954 -214.073382)
			(xy 117.59434 -214.05391) (xy 117.548182 -214.027261) (xy 117.506511 -213.99403) (xy 117.470259 -213.954959)
			(xy 117.440235 -213.910922) (xy 117.417109 -213.862901) (xy 117.401399 -213.811971) (xy 117.393456 -213.759267)
			(xy 117.164852 -213.759267) (xy 117.164829 -213.760435) (xy 117.156187 -213.815393) (xy 117.139099 -213.868337)
			(xy 117.12702 -213.8934) (xy 117.115082 -213.916768) (xy 117.299486 -214.266272) (xy 117.325394 -214.269574)
			(xy 117.350743 -214.27343) (xy 117.400079 -214.287384) (xy 117.446905 -214.308268) (xy 117.490252 -214.335651)
			(xy 117.529225 -214.368966) (xy 117.563018 -214.407526) (xy 117.590933 -214.450532) (xy 117.612393 -214.497097)
			(xy 117.626954 -214.546258) (xy 117.634315 -214.596998) (xy 117.634766 -214.622634) (xy 117.634268 -214.649283)
			(xy 117.626325 -214.701987) (xy 117.610615 -214.752917) (xy 117.587489 -214.800938) (xy 117.557465 -214.844975)
			(xy 117.521213 -214.884046) (xy 117.479542 -214.917277) (xy 117.433384 -214.943926) (xy 117.38377 -214.963398)
			(xy 117.331808 -214.975258) (xy 117.278658 -214.979242) (xy 117.225508 -214.975258) (xy 117.173546 -214.963398)
			(xy 117.123932 -214.943926) (xy 117.077774 -214.917277) (xy 117.036103 -214.884046) (xy 116.999851 -214.844975)
			(xy 116.969827 -214.800938) (xy 116.946701 -214.752917) (xy 116.930991 -214.701987) (xy 116.923048 -214.649283)
			(xy 116.92255 -214.622634) (xy 116.923074 -214.594816) (xy 116.931725 -214.539858) (xy 116.94882 -214.486914)
			(xy 116.960904 -214.461852) (xy 116.972842 -214.438484) (xy 116.788438 -214.08898) (xy 116.76253 -214.085678)
			(xy 116.737176 -214.081849) (xy 116.687836 -214.067896) (xy 116.641007 -214.047011) (xy 116.597657 -214.019626)
			(xy 116.558683 -213.986308) (xy 116.524889 -213.947745) (xy 116.496976 -213.904734) (xy 116.475518 -213.858165)
			(xy 116.460961 -213.809) (xy 116.453606 -213.758255) (xy 116.453158 -213.732618) (xy 116.225574 -213.732618)
			(xy 116.225076 -213.759267) (xy 116.217133 -213.811971) (xy 116.201423 -213.862901) (xy 116.178297 -213.910922)
			(xy 116.148273 -213.954959) (xy 116.112021 -213.99403) (xy 116.07035 -214.027261) (xy 116.024192 -214.05391)
			(xy 115.974578 -214.073382) (xy 115.922616 -214.085242) (xy 115.869466 -214.089226) (xy 115.816316 -214.085242)
			(xy 115.764354 -214.073382) (xy 115.71474 -214.05391) (xy 115.668582 -214.027261) (xy 115.626911 -213.99403)
			(xy 115.590659 -213.954959) (xy 115.560635 -213.910922) (xy 115.537509 -213.862901) (xy 115.521799 -213.811971)
			(xy 115.513856 -213.759267) (xy 115.285252 -213.759267) (xy 115.285229 -213.760435) (xy 115.276587 -213.815393)
			(xy 115.259499 -213.868337) (xy 115.24742 -213.8934) (xy 115.235482 -213.916768) (xy 115.419886 -214.266272)
			(xy 115.445794 -214.269574) (xy 115.471143 -214.27343) (xy 115.520479 -214.287384) (xy 115.567305 -214.308268)
			(xy 115.610652 -214.335651) (xy 115.649625 -214.368966) (xy 115.683418 -214.407526) (xy 115.711333 -214.450532)
			(xy 115.732793 -214.497097) (xy 115.747354 -214.546258) (xy 115.754715 -214.596998) (xy 115.755166 -214.622634)
			(xy 115.754668 -214.649283) (xy 115.746725 -214.701987) (xy 115.731015 -214.752917) (xy 115.707889 -214.800938)
			(xy 115.677865 -214.844975) (xy 115.641613 -214.884046) (xy 115.599942 -214.917277) (xy 115.553784 -214.943926)
			(xy 115.50417 -214.963398) (xy 115.452208 -214.975258) (xy 115.399058 -214.979242) (xy 115.345908 -214.975258)
			(xy 115.293946 -214.963398) (xy 115.244332 -214.943926) (xy 115.198174 -214.917277) (xy 115.156503 -214.884046)
			(xy 115.120251 -214.844975) (xy 115.090227 -214.800938) (xy 115.067101 -214.752917) (xy 115.051391 -214.701987)
			(xy 115.043448 -214.649283) (xy 115.04295 -214.622634) (xy 115.043474 -214.594816) (xy 115.052125 -214.539858)
			(xy 115.06922 -214.486914) (xy 115.081304 -214.461852) (xy 115.093242 -214.438484) (xy 114.908838 -214.08898)
			(xy 114.88293 -214.085678) (xy 114.857576 -214.081849) (xy 114.808236 -214.067896) (xy 114.761407 -214.047011)
			(xy 114.718057 -214.019626) (xy 114.679083 -213.986308) (xy 114.645289 -213.947745) (xy 114.617376 -213.904734)
			(xy 114.595918 -213.858165) (xy 114.581361 -213.809) (xy 114.574006 -213.758255) (xy 114.573558 -213.732618)
			(xy 108.707174 -213.732618) (xy 108.706676 -213.759267) (xy 108.698733 -213.811971) (xy 108.683023 -213.862901)
			(xy 108.659897 -213.910922) (xy 108.629873 -213.954959) (xy 108.593621 -213.99403) (xy 108.55195 -214.027261)
			(xy 108.505792 -214.05391) (xy 108.456178 -214.073382) (xy 108.404216 -214.085242) (xy 108.351066 -214.089226)
			(xy 108.297916 -214.085242) (xy 108.245954 -214.073382) (xy 108.19634 -214.05391) (xy 108.150182 -214.027261)
			(xy 108.108511 -213.99403) (xy 108.072259 -213.954959) (xy 108.042235 -213.910922) (xy 108.019109 -213.862901)
			(xy 108.003399 -213.811971) (xy 107.995456 -213.759267) (xy 107.766852 -213.759267) (xy 107.766829 -213.760435)
			(xy 107.758187 -213.815393) (xy 107.741099 -213.868337) (xy 107.72902 -213.8934) (xy 107.717082 -213.916768)
			(xy 107.901486 -214.266272) (xy 107.927394 -214.269574) (xy 107.952743 -214.27343) (xy 108.002079 -214.287384)
			(xy 108.048905 -214.308268) (xy 108.092252 -214.335651) (xy 108.131225 -214.368966) (xy 108.165018 -214.407526)
			(xy 108.192933 -214.450532) (xy 108.214393 -214.497097) (xy 108.228954 -214.546258) (xy 108.236315 -214.596998)
			(xy 108.236766 -214.622634) (xy 108.236268 -214.649283) (xy 108.228325 -214.701987) (xy 108.212615 -214.752917)
			(xy 108.189489 -214.800938) (xy 108.159465 -214.844975) (xy 108.123213 -214.884046) (xy 108.081542 -214.917277)
			(xy 108.035384 -214.943926) (xy 107.98577 -214.963398) (xy 107.933808 -214.975258) (xy 107.880658 -214.979242)
			(xy 107.827508 -214.975258) (xy 107.775546 -214.963398) (xy 107.725932 -214.943926) (xy 107.679774 -214.917277)
			(xy 107.638103 -214.884046) (xy 107.601851 -214.844975) (xy 107.571827 -214.800938) (xy 107.548701 -214.752917)
			(xy 107.532991 -214.701987) (xy 107.525048 -214.649283) (xy 107.52455 -214.622634) (xy 107.525074 -214.594816)
			(xy 107.533725 -214.539858) (xy 107.55082 -214.486914) (xy 107.562904 -214.461852) (xy 107.574842 -214.438484)
			(xy 107.390438 -214.08898) (xy 107.36453 -214.085678) (xy 107.339176 -214.081849) (xy 107.289836 -214.067896)
			(xy 107.243007 -214.047011) (xy 107.199657 -214.019626) (xy 107.160683 -213.986308) (xy 107.126889 -213.947745)
			(xy 107.098976 -213.904734) (xy 107.077518 -213.858165) (xy 107.062961 -213.809) (xy 107.055606 -213.758255)
			(xy 107.055158 -213.732618) (xy 106.827574 -213.732618) (xy 106.827076 -213.759267) (xy 106.819133 -213.811971)
			(xy 106.803423 -213.862901) (xy 106.780297 -213.910922) (xy 106.750273 -213.954959) (xy 106.714021 -213.99403)
			(xy 106.67235 -214.027261) (xy 106.626192 -214.05391) (xy 106.576578 -214.073382) (xy 106.524616 -214.085242)
			(xy 106.471466 -214.089226) (xy 106.418316 -214.085242) (xy 106.366354 -214.073382) (xy 106.31674 -214.05391)
			(xy 106.270582 -214.027261) (xy 106.228911 -213.99403) (xy 106.192659 -213.954959) (xy 106.162635 -213.910922)
			(xy 106.139509 -213.862901) (xy 106.123799 -213.811971) (xy 106.115856 -213.759267) (xy 105.887261 -213.759267)
			(xy 105.887238 -213.760435) (xy 105.878587 -213.815392) (xy 105.861499 -213.868337) (xy 105.84942 -213.8934)
			(xy 105.837482 -213.916768) (xy 106.021886 -214.266272) (xy 106.047794 -214.269574) (xy 106.073155 -214.273379)
			(xy 106.122502 -214.287326) (xy 106.169339 -214.308207) (xy 106.212697 -214.335591) (xy 106.251678 -214.368911)
			(xy 106.285476 -214.407478) (xy 106.313393 -214.450494) (xy 106.334851 -214.49707) (xy 106.349406 -214.546242)
			(xy 106.356757 -214.596993) (xy 106.357166 -214.622634) (xy 106.356668 -214.649283) (xy 106.348725 -214.701987)
			(xy 106.333015 -214.752917) (xy 106.309889 -214.800938) (xy 106.279865 -214.844975) (xy 106.243613 -214.884046)
			(xy 106.201942 -214.917277) (xy 106.155784 -214.943926) (xy 106.10617 -214.963398) (xy 106.054208 -214.975258)
			(xy 106.001058 -214.979242) (xy 105.947908 -214.975258) (xy 105.895946 -214.963398) (xy 105.846332 -214.943926)
			(xy 105.800174 -214.917277) (xy 105.758503 -214.884046) (xy 105.722251 -214.844975) (xy 105.692227 -214.800938)
			(xy 105.669101 -214.752917) (xy 105.653391 -214.701987) (xy 105.645448 -214.649283) (xy 105.64495 -214.622634)
			(xy 105.64549 -214.594818) (xy 105.654148 -214.539864) (xy 105.671243 -214.486923) (xy 105.683304 -214.461852)
			(xy 105.695242 -214.438484) (xy 105.630726 -214.31631) (xy 105.625854 -214.307944) (xy 105.611151 -214.295371)
			(xy 105.592836 -214.289146) (xy 105.573517 -214.290154) (xy 105.555949 -214.298253) (xy 105.542636 -214.312288)
			(xy 105.535475 -214.330259) (xy 105.534968 -214.339932) (xy 105.534968 -215.077802) (xy 105.57891 -215.083898)
			(xy 105.605555 -215.087965) (xy 105.657289 -215.103086) (xy 105.706152 -215.125834) (xy 105.751026 -215.155689)
			(xy 105.790886 -215.191968) (xy 105.824821 -215.233843) (xy 105.852055 -215.280355) (xy 105.871965 -215.330441)
			(xy 105.884096 -215.382956) (xy 105.88817 -215.436701) (xy 105.88817 -215.436704) (xy 106.115104 -215.436704)
			(xy 106.115484 -215.411073) (xy 106.12282 -215.360338) (xy 106.137357 -215.31118) (xy 106.158793 -215.264615)
			(xy 106.186685 -215.221605) (xy 106.220457 -215.18304) (xy 106.25941 -215.149717) (xy 106.30274 -215.122324)
			(xy 106.34955 -215.101428) (xy 106.398873 -215.087461) (xy 106.424222 -215.083644) (xy 106.44886 -215.080342)
			(xy 106.621326 -214.781638) (xy 106.611674 -214.758524) (xy 106.603165 -214.736889) (xy 106.591176 -214.691973)
			(xy 106.585128 -214.645879) (xy 106.58475 -214.622634) (xy 106.585248 -214.595985) (xy 106.593191 -214.543281)
			(xy 106.608901 -214.492351) (xy 106.632027 -214.44433) (xy 106.662051 -214.400293) (xy 106.698303 -214.361222)
			(xy 106.739974 -214.327991) (xy 106.786132 -214.301342) (xy 106.835746 -214.28187) (xy 106.887708 -214.27001)
			(xy 106.940858 -214.266027) (xy 106.994008 -214.27001) (xy 107.04597 -214.28187) (xy 107.095584 -214.301342)
			(xy 107.141742 -214.327991) (xy 107.183413 -214.361222) (xy 107.219665 -214.400293) (xy 107.249689 -214.44433)
			(xy 107.272815 -214.492351) (xy 107.288525 -214.543281) (xy 107.296468 -214.595985) (xy 107.296966 -214.622634)
			(xy 107.296469 -214.648261) (xy 107.289143 -214.698988) (xy 107.274618 -214.74814) (xy 107.253194 -214.794701)
			(xy 107.225315 -214.837708) (xy 107.191557 -214.876273) (xy 107.152617 -214.909599) (xy 107.109301 -214.936995)
			(xy 107.062503 -214.957897) (xy 107.013192 -214.971872) (xy 106.987848 -214.975694) (xy 106.96321 -214.978996)
			(xy 106.790744 -215.2777) (xy 106.800396 -215.300814) (xy 106.808915 -215.322445) (xy 106.820901 -215.367363)
			(xy 106.826945 -215.413459) (xy 106.82732 -215.436704) (xy 106.826822 -215.463353) (xy 107.055402 -215.463353)
			(xy 107.055402 -215.410055) (xy 107.063345 -215.357351) (xy 107.079055 -215.306421) (xy 107.102181 -215.2584)
			(xy 107.132205 -215.214363) (xy 107.168457 -215.175292) (xy 107.210128 -215.142061) (xy 107.256286 -215.115412)
			(xy 107.3059 -215.09594) (xy 107.357862 -215.08408) (xy 107.411012 -215.080097) (xy 107.464162 -215.08408)
			(xy 107.516124 -215.09594) (xy 107.565738 -215.115412) (xy 107.611896 -215.142061) (xy 107.653567 -215.175292)
			(xy 107.689819 -215.214363) (xy 107.719843 -215.2584) (xy 107.742969 -215.306421) (xy 107.758679 -215.357351)
			(xy 107.766622 -215.410055) (xy 107.76712 -215.436704) (xy 107.994704 -215.436704) (xy 107.995084 -215.411073)
			(xy 108.00242 -215.360338) (xy 108.016957 -215.31118) (xy 108.038393 -215.264615) (xy 108.066285 -215.221605)
			(xy 108.100057 -215.18304) (xy 108.13901 -215.149717) (xy 108.18234 -215.122324) (xy 108.22915 -215.101428)
			(xy 108.278473 -215.087461) (xy 108.303822 -215.083644) (xy 108.32846 -215.080342) (xy 108.500926 -214.781638)
			(xy 108.491274 -214.758524) (xy 108.482765 -214.736889) (xy 108.470776 -214.691973) (xy 108.464728 -214.645879)
			(xy 108.46435 -214.622634) (xy 108.464848 -214.595985) (xy 108.472791 -214.543281) (xy 108.488501 -214.492351)
			(xy 108.511627 -214.44433) (xy 108.541651 -214.400293) (xy 108.577903 -214.361222) (xy 108.619574 -214.327991)
			(xy 108.665732 -214.301342) (xy 108.715346 -214.28187) (xy 108.767308 -214.27001) (xy 108.820458 -214.266027)
			(xy 108.873608 -214.27001) (xy 108.92557 -214.28187) (xy 108.975184 -214.301342) (xy 109.021342 -214.327991)
			(xy 109.063013 -214.361222) (xy 109.099265 -214.400293) (xy 109.129289 -214.44433) (xy 109.152415 -214.492351)
			(xy 109.168125 -214.543281) (xy 109.172616 -214.573083) (xy 109.404902 -214.573083) (xy 109.404902 -214.519785)
			(xy 109.412845 -214.467081) (xy 109.428555 -214.416151) (xy 109.451681 -214.36813) (xy 109.481705 -214.324093)
			(xy 109.517957 -214.285022) (xy 109.559628 -214.251791) (xy 109.605786 -214.225142) (xy 109.6554 -214.20567)
			(xy 109.707362 -214.19381) (xy 109.760512 -214.189827) (xy 109.813662 -214.19381) (xy 109.865624 -214.20567)
			(xy 109.915238 -214.225142) (xy 109.961396 -214.251791) (xy 110.003067 -214.285022) (xy 110.039319 -214.324093)
			(xy 110.069343 -214.36813) (xy 110.092469 -214.416151) (xy 110.108179 -214.467081) (xy 110.116122 -214.519785)
			(xy 110.11662 -214.546434) (xy 110.344458 -214.546434) (xy 110.344956 -214.519785) (xy 110.352899 -214.467081)
			(xy 110.368609 -214.416151) (xy 110.391735 -214.36813) (xy 110.421759 -214.324093) (xy 110.458011 -214.285022)
			(xy 110.499682 -214.251791) (xy 110.54584 -214.225142) (xy 110.595454 -214.20567) (xy 110.647416 -214.19381)
			(xy 110.700566 -214.189827) (xy 110.753716 -214.19381) (xy 110.805678 -214.20567) (xy 110.855292 -214.225142)
			(xy 110.90145 -214.251791) (xy 110.943121 -214.285022) (xy 110.979373 -214.324093) (xy 111.009397 -214.36813)
			(xy 111.032523 -214.416151) (xy 111.048233 -214.467081) (xy 111.056176 -214.519785) (xy 111.056674 -214.546434)
			(xy 111.056158 -214.573083) (xy 111.284756 -214.573083) (xy 111.284756 -214.519785) (xy 111.292699 -214.467081)
			(xy 111.308409 -214.416151) (xy 111.331535 -214.36813) (xy 111.361559 -214.324093) (xy 111.397811 -214.285022)
			(xy 111.439482 -214.251791) (xy 111.48564 -214.225142) (xy 111.535254 -214.20567) (xy 111.587216 -214.19381)
			(xy 111.640366 -214.189827) (xy 111.693516 -214.19381) (xy 111.745478 -214.20567) (xy 111.795092 -214.225142)
			(xy 111.84125 -214.251791) (xy 111.882921 -214.285022) (xy 111.919173 -214.324093) (xy 111.949197 -214.36813)
			(xy 111.972323 -214.416151) (xy 111.988033 -214.467081) (xy 111.995976 -214.519785) (xy 111.996473 -214.5464)
			(xy 112.223127 -214.5464) (xy 112.227109 -214.49326) (xy 112.238966 -214.441306) (xy 112.258434 -214.3917)
			(xy 112.285077 -214.345549) (xy 112.3183 -214.303883) (xy 112.357362 -214.267635) (xy 112.401389 -214.237613)
			(xy 112.449399 -214.214487) (xy 112.50032 -214.198775) (xy 112.553013 -214.190827) (xy 112.579658 -214.190326)
			(xy 112.604683 -214.190766) (xy 112.65424 -214.197769) (xy 112.702328 -214.211643) (xy 112.747999 -214.232115)
			(xy 112.790354 -214.258781) (xy 112.828556 -214.291115) (xy 112.861854 -214.328481) (xy 112.876076 -214.349076)
			(xy 113.22304 -214.349076) (xy 113.237301 -214.328509) (xy 113.270592 -214.29114) (xy 113.308787 -214.258801)
			(xy 113.351134 -214.232129) (xy 113.396799 -214.21165) (xy 113.444882 -214.197767) (xy 113.494435 -214.190753)
			(xy 113.519458 -214.190326) (xy 113.546114 -214.190728) (xy 113.59883 -214.198668) (xy 113.649775 -214.214377)
			(xy 113.697809 -214.237504) (xy 113.741859 -214.267532) (xy 113.780941 -214.303791) (xy 113.814182 -214.34547)
			(xy 113.84084 -214.391638) (xy 113.860318 -214.441263) (xy 113.872182 -214.493238) (xy 113.876166 -214.5464)
			(xy 113.872182 -214.599562) (xy 113.860318 -214.651537) (xy 113.84084 -214.701162) (xy 113.814182 -214.74733)
			(xy 113.780941 -214.789009) (xy 113.741859 -214.825268) (xy 113.697809 -214.855296) (xy 113.649775 -214.878423)
			(xy 113.598831 -214.894132) (xy 113.546114 -214.902072) (xy 113.519458 -214.902542) (xy 113.494432 -214.902136)
			(xy 113.444875 -214.895123) (xy 113.396788 -214.88124) (xy 113.351117 -214.860762) (xy 113.308764 -214.834092)
			(xy 113.270561 -214.801755) (xy 113.237263 -214.764388) (xy 113.22304 -214.743792) (xy 112.876076 -214.743792)
			(xy 112.86189 -214.764414) (xy 112.828585 -214.801778) (xy 112.790375 -214.834111) (xy 112.748015 -214.860775)
			(xy 112.702339 -214.881245) (xy 112.654246 -214.895118) (xy 112.604685 -214.902121) (xy 112.579658 -214.902542)
			(xy 112.553013 -214.901973) (xy 112.50032 -214.894025) (xy 112.449399 -214.878313) (xy 112.401389 -214.855187)
			(xy 112.357362 -214.825165) (xy 112.3183 -214.788917) (xy 112.285077 -214.747251) (xy 112.258434 -214.7011)
			(xy 112.238966 -214.651494) (xy 112.227109 -214.59954) (xy 112.223127 -214.5464) (xy 111.996473 -214.5464)
			(xy 111.996474 -214.546434) (xy 111.995976 -214.573083) (xy 111.988033 -214.625787) (xy 111.972323 -214.676717)
			(xy 111.949197 -214.724738) (xy 111.919173 -214.768775) (xy 111.882921 -214.807846) (xy 111.84125 -214.841077)
			(xy 111.795092 -214.867726) (xy 111.745478 -214.887198) (xy 111.693516 -214.899058) (xy 111.640366 -214.903042)
			(xy 111.587216 -214.899058) (xy 111.535254 -214.887198) (xy 111.48564 -214.867726) (xy 111.439482 -214.841077)
			(xy 111.397811 -214.807846) (xy 111.361559 -214.768775) (xy 111.331535 -214.724738) (xy 111.308409 -214.676717)
			(xy 111.292699 -214.625787) (xy 111.284756 -214.573083) (xy 111.056158 -214.573083) (xy 111.056135 -214.574251)
			(xy 111.04749 -214.629209) (xy 111.030401 -214.682153) (xy 111.01832 -214.707216) (xy 111.006636 -214.730584)
			(xy 111.19104 -215.080342) (xy 111.216948 -215.083644) (xy 111.242316 -215.08739) (xy 111.291658 -215.101355)
			(xy 111.338488 -215.122251) (xy 111.381837 -215.149646) (xy 111.42081 -215.182974) (xy 111.454602 -215.221546)
			(xy 111.482513 -215.264565) (xy 111.503968 -215.311142) (xy 111.518521 -215.360313) (xy 111.525874 -215.411064)
			(xy 111.52632 -215.436704) (xy 111.525822 -215.463353) (xy 111.754402 -215.463353) (xy 111.754402 -215.410055)
			(xy 111.762345 -215.357351) (xy 111.778055 -215.306421) (xy 111.801181 -215.2584) (xy 111.831205 -215.214363)
			(xy 111.867457 -215.175292) (xy 111.909128 -215.142061) (xy 111.955286 -215.115412) (xy 112.0049 -215.09594)
			(xy 112.056862 -215.08408) (xy 112.110012 -215.080097) (xy 112.163162 -215.08408) (xy 112.215124 -215.09594)
			(xy 112.264738 -215.115412) (xy 112.310896 -215.142061) (xy 112.352567 -215.175292) (xy 112.388819 -215.214363)
			(xy 112.418843 -215.2584) (xy 112.441969 -215.306421) (xy 112.457679 -215.357351) (xy 112.465622 -215.410055)
			(xy 112.46612 -215.436704) (xy 112.465622 -215.463353) (xy 112.694202 -215.463353) (xy 112.694202 -215.410055)
			(xy 112.702145 -215.357351) (xy 112.717855 -215.306421) (xy 112.740981 -215.2584) (xy 112.771005 -215.214363)
			(xy 112.807257 -215.175292) (xy 112.848928 -215.142061) (xy 112.895086 -215.115412) (xy 112.9447 -215.09594)
			(xy 112.996662 -215.08408) (xy 113.049812 -215.080097) (xy 113.102962 -215.08408) (xy 113.154924 -215.09594)
			(xy 113.204538 -215.115412) (xy 113.250696 -215.142061) (xy 113.292367 -215.175292) (xy 113.328619 -215.214363)
			(xy 113.358643 -215.2584) (xy 113.381769 -215.306421) (xy 113.397479 -215.357351) (xy 113.405422 -215.410055)
			(xy 113.40592 -215.436704) (xy 113.633504 -215.436704) (xy 113.633884 -215.411073) (xy 113.64122 -215.360338)
			(xy 113.655757 -215.31118) (xy 113.677193 -215.264615) (xy 113.705085 -215.221605) (xy 113.738857 -215.18304)
			(xy 113.77781 -215.149717) (xy 113.82114 -215.122324) (xy 113.86795 -215.101428) (xy 113.917273 -215.087461)
			(xy 113.942622 -215.083644) (xy 113.96726 -215.080342) (xy 114.13998 -214.781638) (xy 114.130328 -214.758524)
			(xy 114.121822 -214.736888) (xy 114.109831 -214.691972) (xy 114.103782 -214.645878) (xy 114.103404 -214.622634)
			(xy 114.103902 -214.595985) (xy 114.111845 -214.543281) (xy 114.127555 -214.492351) (xy 114.150681 -214.44433)
			(xy 114.180705 -214.400293) (xy 114.216957 -214.361222) (xy 114.258628 -214.327991) (xy 114.304786 -214.301342)
			(xy 114.3544 -214.28187) (xy 114.406362 -214.27001) (xy 114.459512 -214.266027) (xy 114.512662 -214.27001)
			(xy 114.564624 -214.28187) (xy 114.614238 -214.301342) (xy 114.660396 -214.327991) (xy 114.702067 -214.361222)
			(xy 114.738319 -214.400293) (xy 114.768343 -214.44433) (xy 114.791469 -214.492351) (xy 114.807179 -214.543281)
			(xy 114.815122 -214.595985) (xy 114.81562 -214.622634) (xy 114.815163 -214.648263) (xy 114.807835 -214.698993)
			(xy 114.793308 -214.748148) (xy 114.771881 -214.794712) (xy 114.743998 -214.837721) (xy 114.710235 -214.876287)
			(xy 114.671289 -214.909611) (xy 114.627967 -214.937006) (xy 114.581165 -214.957905) (xy 114.531848 -214.971875)
			(xy 114.506502 -214.975694) (xy 114.481864 -214.978996) (xy 114.309144 -215.2777) (xy 114.318796 -215.300814)
			(xy 114.327315 -215.322445) (xy 114.339301 -215.367363) (xy 114.345345 -215.413459) (xy 114.34572 -215.436704)
			(xy 114.345222 -215.463353) (xy 114.573802 -215.463353) (xy 114.573802 -215.410055) (xy 114.581745 -215.357351)
			(xy 114.597455 -215.306421) (xy 114.620581 -215.2584) (xy 114.650605 -215.214363) (xy 114.686857 -215.175292)
			(xy 114.728528 -215.142061) (xy 114.774686 -215.115412) (xy 114.8243 -215.09594) (xy 114.876262 -215.08408)
			(xy 114.929412 -215.080097) (xy 114.982562 -215.08408) (xy 115.034524 -215.09594) (xy 115.084138 -215.115412)
			(xy 115.130296 -215.142061) (xy 115.171967 -215.175292) (xy 115.208219 -215.214363) (xy 115.238243 -215.2584)
			(xy 115.261369 -215.306421) (xy 115.277079 -215.357351) (xy 115.285022 -215.410055) (xy 115.28552 -215.436704)
			(xy 115.513104 -215.436704) (xy 115.513484 -215.411073) (xy 115.52082 -215.360338) (xy 115.535357 -215.31118)
			(xy 115.556793 -215.264615) (xy 115.584685 -215.221605) (xy 115.618457 -215.18304) (xy 115.65741 -215.149717)
			(xy 115.70074 -215.122324) (xy 115.74755 -215.101428) (xy 115.796873 -215.087461) (xy 115.822222 -215.083644)
			(xy 115.84686 -215.080342) (xy 116.019326 -214.781638) (xy 116.009674 -214.758524) (xy 116.001165 -214.736889)
			(xy 115.989176 -214.691973) (xy 115.983128 -214.645879) (xy 115.98275 -214.622634) (xy 115.983248 -214.595985)
			(xy 115.991191 -214.543281) (xy 116.006901 -214.492351) (xy 116.030027 -214.44433) (xy 116.060051 -214.400293)
			(xy 116.096303 -214.361222) (xy 116.137974 -214.327991) (xy 116.184132 -214.301342) (xy 116.233746 -214.28187)
			(xy 116.285708 -214.27001) (xy 116.338858 -214.266027) (xy 116.392008 -214.27001) (xy 116.44397 -214.28187)
			(xy 116.493584 -214.301342) (xy 116.539742 -214.327991) (xy 116.581413 -214.361222) (xy 116.617665 -214.400293)
			(xy 116.647689 -214.44433) (xy 116.670815 -214.492351) (xy 116.686525 -214.543281) (xy 116.694468 -214.595985)
			(xy 116.694966 -214.622634) (xy 116.694469 -214.648261) (xy 116.687143 -214.698988) (xy 116.672618 -214.74814)
			(xy 116.651194 -214.794701) (xy 116.623315 -214.837708) (xy 116.589557 -214.876273) (xy 116.550617 -214.909599)
			(xy 116.507301 -214.936995) (xy 116.460503 -214.957897) (xy 116.411192 -214.971872) (xy 116.385848 -214.975694)
			(xy 116.36121 -214.978996) (xy 116.188744 -215.2777) (xy 116.198396 -215.300814) (xy 116.206915 -215.322445)
			(xy 116.218901 -215.367363) (xy 116.224945 -215.413459) (xy 116.22532 -215.436704) (xy 117.392704 -215.436704)
			(xy 117.393084 -215.411073) (xy 117.40042 -215.360338) (xy 117.414957 -215.31118) (xy 117.436393 -215.264615)
			(xy 117.464285 -215.221605) (xy 117.498057 -215.18304) (xy 117.53701 -215.149717) (xy 117.58034 -215.122324)
			(xy 117.62715 -215.101428) (xy 117.676473 -215.087461) (xy 117.701822 -215.083644) (xy 117.72646 -215.080342)
			(xy 117.898926 -214.781638) (xy 117.889274 -214.758524) (xy 117.880765 -214.736889) (xy 117.868776 -214.691973)
			(xy 117.862728 -214.645879) (xy 117.86235 -214.622634) (xy 117.862848 -214.595985) (xy 117.870791 -214.543281)
			(xy 117.886501 -214.492351) (xy 117.909627 -214.44433) (xy 117.939651 -214.400293) (xy 117.975903 -214.361222)
			(xy 118.017574 -214.327991) (xy 118.063732 -214.301342) (xy 118.113346 -214.28187) (xy 118.165308 -214.27001)
			(xy 118.218458 -214.266027) (xy 118.271608 -214.27001) (xy 118.32357 -214.28187) (xy 118.373184 -214.301342)
			(xy 118.419342 -214.327991) (xy 118.461013 -214.361222) (xy 118.497265 -214.400293) (xy 118.527289 -214.44433)
			(xy 118.550415 -214.492351) (xy 118.566125 -214.543281) (xy 118.574068 -214.595985) (xy 118.574566 -214.622634)
			(xy 118.574069 -214.648261) (xy 118.566743 -214.698988) (xy 118.552218 -214.74814) (xy 118.530794 -214.794701)
			(xy 118.502915 -214.837708) (xy 118.469157 -214.876273) (xy 118.430217 -214.909599) (xy 118.386901 -214.936995)
			(xy 118.340103 -214.957897) (xy 118.290792 -214.971872) (xy 118.265448 -214.975694) (xy 118.24081 -214.978996)
			(xy 118.068344 -215.2777) (xy 118.077996 -215.300814) (xy 118.086515 -215.322445) (xy 118.098501 -215.367363)
			(xy 118.104545 -215.413459) (xy 118.10492 -215.436704) (xy 118.104422 -215.463353) (xy 118.096479 -215.516057)
			(xy 118.080769 -215.566987) (xy 118.057643 -215.615008) (xy 118.027619 -215.659045) (xy 117.991367 -215.698116)
			(xy 117.949696 -215.731347) (xy 117.903538 -215.757996) (xy 117.853924 -215.777468) (xy 117.801962 -215.789328)
			(xy 117.748812 -215.793312) (xy 117.695662 -215.789328) (xy 117.6437 -215.777468) (xy 117.594086 -215.757996)
			(xy 117.547928 -215.731347) (xy 117.506257 -215.698116) (xy 117.470005 -215.659045) (xy 117.439981 -215.615008)
			(xy 117.416855 -215.566987) (xy 117.401145 -215.516057) (xy 117.393202 -215.463353) (xy 117.392704 -215.436704)
			(xy 116.22532 -215.436704) (xy 116.224822 -215.463353) (xy 116.216879 -215.516057) (xy 116.201169 -215.566987)
			(xy 116.178043 -215.615008) (xy 116.148019 -215.659045) (xy 116.111767 -215.698116) (xy 116.070096 -215.731347)
			(xy 116.023938 -215.757996) (xy 115.974324 -215.777468) (xy 115.922362 -215.789328) (xy 115.869212 -215.793312)
			(xy 115.816062 -215.789328) (xy 115.7641 -215.777468) (xy 115.714486 -215.757996) (xy 115.668328 -215.731347)
			(xy 115.626657 -215.698116) (xy 115.590405 -215.659045) (xy 115.560381 -215.615008) (xy 115.537255 -215.566987)
			(xy 115.521545 -215.516057) (xy 115.513602 -215.463353) (xy 115.513104 -215.436704) (xy 115.28552 -215.436704)
			(xy 115.285022 -215.463353) (xy 115.277079 -215.516057) (xy 115.261369 -215.566987) (xy 115.238243 -215.615008)
			(xy 115.208219 -215.659045) (xy 115.171967 -215.698116) (xy 115.130296 -215.731347) (xy 115.084138 -215.757996)
			(xy 115.034524 -215.777468) (xy 114.982562 -215.789328) (xy 114.929412 -215.793312) (xy 114.876262 -215.789328)
			(xy 114.8243 -215.777468) (xy 114.774686 -215.757996) (xy 114.728528 -215.731347) (xy 114.686857 -215.698116)
			(xy 114.650605 -215.659045) (xy 114.620581 -215.615008) (xy 114.597455 -215.566987) (xy 114.581745 -215.516057)
			(xy 114.573802 -215.463353) (xy 114.345222 -215.463353) (xy 114.337279 -215.516057) (xy 114.321569 -215.566987)
			(xy 114.298443 -215.615008) (xy 114.268419 -215.659045) (xy 114.232167 -215.698116) (xy 114.190496 -215.731347)
			(xy 114.144338 -215.757996) (xy 114.094724 -215.777468) (xy 114.042762 -215.789328) (xy 113.989612 -215.793312)
			(xy 113.936462 -215.789328) (xy 113.8845 -215.777468) (xy 113.834886 -215.757996) (xy 113.788728 -215.731347)
			(xy 113.747057 -215.698116) (xy 113.710805 -215.659045) (xy 113.680781 -215.615008) (xy 113.657655 -215.566987)
			(xy 113.641945 -215.516057) (xy 113.634002 -215.463353) (xy 113.633504 -215.436704) (xy 113.40592 -215.436704)
			(xy 113.405422 -215.463353) (xy 113.397479 -215.516057) (xy 113.381769 -215.566987) (xy 113.358643 -215.615008)
			(xy 113.328619 -215.659045) (xy 113.292367 -215.698116) (xy 113.250696 -215.731347) (xy 113.204538 -215.757996)
			(xy 113.154924 -215.777468) (xy 113.102962 -215.789328) (xy 113.049812 -215.793312) (xy 112.996662 -215.789328)
			(xy 112.9447 -215.777468) (xy 112.895086 -215.757996) (xy 112.848928 -215.731347) (xy 112.807257 -215.698116)
			(xy 112.771005 -215.659045) (xy 112.740981 -215.615008) (xy 112.717855 -215.566987) (xy 112.702145 -215.516057)
			(xy 112.694202 -215.463353) (xy 112.465622 -215.463353) (xy 112.457679 -215.516057) (xy 112.441969 -215.566987)
			(xy 112.418843 -215.615008) (xy 112.388819 -215.659045) (xy 112.352567 -215.698116) (xy 112.310896 -215.731347)
			(xy 112.264738 -215.757996) (xy 112.215124 -215.777468) (xy 112.163162 -215.789328) (xy 112.110012 -215.793312)
			(xy 112.056862 -215.789328) (xy 112.0049 -215.777468) (xy 111.955286 -215.757996) (xy 111.909128 -215.731347)
			(xy 111.867457 -215.698116) (xy 111.831205 -215.659045) (xy 111.801181 -215.615008) (xy 111.778055 -215.566987)
			(xy 111.762345 -215.516057) (xy 111.754402 -215.463353) (xy 111.525822 -215.463353) (xy 111.517879 -215.516057)
			(xy 111.502169 -215.566987) (xy 111.479043 -215.615008) (xy 111.449019 -215.659045) (xy 111.412767 -215.698116)
			(xy 111.371096 -215.731347) (xy 111.324938 -215.757996) (xy 111.275324 -215.777468) (xy 111.223362 -215.789328)
			(xy 111.170212 -215.793312) (xy 111.117062 -215.789328) (xy 111.0651 -215.777468) (xy 111.015486 -215.757996)
			(xy 110.969328 -215.731347) (xy 110.927657 -215.698116) (xy 110.891405 -215.659045) (xy 110.861381 -215.615008)
			(xy 110.838255 -215.566987) (xy 110.822545 -215.516057) (xy 110.814602 -215.463353) (xy 110.814104 -215.436704)
			(xy 110.814622 -215.408886) (xy 110.823276 -215.353927) (xy 110.840374 -215.300984) (xy 110.852458 -215.275922)
			(xy 110.864142 -215.252554) (xy 110.679738 -214.902796) (xy 110.65383 -214.899494) (xy 110.628479 -214.89565)
			(xy 110.57914 -214.881697) (xy 110.532312 -214.860814) (xy 110.488963 -214.833431) (xy 110.449989 -214.800114)
			(xy 110.416195 -214.761553) (xy 110.388281 -214.718544) (xy 110.366823 -214.671977) (xy 110.352264 -214.622814)
			(xy 110.344907 -214.572071) (xy 110.344458 -214.546434) (xy 110.11662 -214.546434) (xy 110.116122 -214.573083)
			(xy 110.108179 -214.625787) (xy 110.092469 -214.676717) (xy 110.069343 -214.724738) (xy 110.039319 -214.768775)
			(xy 110.003067 -214.807846) (xy 109.961396 -214.841077) (xy 109.915238 -214.867726) (xy 109.865624 -214.887198)
			(xy 109.813662 -214.899058) (xy 109.760512 -214.903042) (xy 109.707362 -214.899058) (xy 109.6554 -214.887198)
			(xy 109.605786 -214.867726) (xy 109.559628 -214.841077) (xy 109.517957 -214.807846) (xy 109.481705 -214.768775)
			(xy 109.451681 -214.724738) (xy 109.428555 -214.676717) (xy 109.412845 -214.625787) (xy 109.404902 -214.573083)
			(xy 109.172616 -214.573083) (xy 109.176068 -214.595985) (xy 109.176566 -214.622634) (xy 109.176069 -214.648261)
			(xy 109.168743 -214.698988) (xy 109.154218 -214.74814) (xy 109.132794 -214.794701) (xy 109.104915 -214.837708)
			(xy 109.071157 -214.876273) (xy 109.032217 -214.909599) (xy 108.988901 -214.936995) (xy 108.942103 -214.957897)
			(xy 108.892792 -214.971872) (xy 108.867448 -214.975694) (xy 108.84281 -214.978996) (xy 108.670344 -215.2777)
			(xy 108.679996 -215.300814) (xy 108.688515 -215.322445) (xy 108.700501 -215.367363) (xy 108.706545 -215.413459)
			(xy 108.70692 -215.4367) (xy 108.933972 -215.4367) (xy 108.937955 -215.383546) (xy 108.949817 -215.33158)
			(xy 108.969291 -215.281962) (xy 108.995943 -215.235801) (xy 109.029177 -215.194127) (xy 109.068251 -215.157873)
			(xy 109.112293 -215.127847) (xy 109.160318 -215.104721) (xy 109.211253 -215.089011) (xy 109.263961 -215.081068)
			(xy 109.290612 -215.080596) (xy 109.315626 -215.081031) (xy 109.365163 -215.088017) (xy 109.413236 -215.101864)
			(xy 109.458899 -215.1223) (xy 109.501254 -215.148923) (xy 109.539468 -215.181208) (xy 109.572791 -215.218523)
			(xy 109.58703 -215.239092) (xy 109.933994 -215.239092) (xy 109.948204 -215.218502) (xy 109.981537 -215.181195)
			(xy 110.01976 -215.148915) (xy 110.06212 -215.122296) (xy 110.107785 -215.10186) (xy 110.155859 -215.08801)
			(xy 110.205397 -215.081017) (xy 110.230412 -215.080596) (xy 110.257061 -215.081087) (xy 110.309764 -215.089032)
			(xy 110.360693 -215.104743) (xy 110.408713 -215.127869) (xy 110.452749 -215.157894) (xy 110.491819 -215.194147)
			(xy 110.525049 -215.235817) (xy 110.551697 -215.281975) (xy 110.571169 -215.331589) (xy 110.583029 -215.383551)
			(xy 110.587012 -215.4367) (xy 110.583029 -215.489849) (xy 110.571169 -215.541811) (xy 110.551697 -215.591425)
			(xy 110.525049 -215.637583) (xy 110.491819 -215.679253) (xy 110.452749 -215.715506) (xy 110.408713 -215.745531)
			(xy 110.360693 -215.768657) (xy 110.309764 -215.784368) (xy 110.257061 -215.792313) (xy 110.230412 -215.792812)
			(xy 110.205399 -215.792355) (xy 110.155863 -215.785372) (xy 110.107791 -215.771529) (xy 110.062128 -215.751097)
			(xy 110.019773 -215.724478) (xy 109.981557 -215.692195) (xy 109.948234 -215.654884) (xy 109.933994 -215.634316)
			(xy 109.58703 -215.634316) (xy 109.572808 -215.654897) (xy 109.539476 -215.692204) (xy 109.501255 -215.724484)
			(xy 109.458898 -215.751104) (xy 109.413234 -215.771541) (xy 109.365162 -215.785393) (xy 109.315626 -215.792389)
			(xy 109.290612 -215.792812) (xy 109.263961 -215.792332) (xy 109.211253 -215.784389) (xy 109.160318 -215.768679)
			(xy 109.112293 -215.745553) (xy 109.068251 -215.715527) (xy 109.029177 -215.679273) (xy 108.995943 -215.637599)
			(xy 108.969291 -215.591438) (xy 108.949817 -215.54182) (xy 108.937955 -215.489854) (xy 108.933972 -215.4367)
			(xy 108.70692 -215.4367) (xy 108.70692 -215.436704) (xy 108.706422 -215.463353) (xy 108.698479 -215.516057)
			(xy 108.682769 -215.566987) (xy 108.659643 -215.615008) (xy 108.629619 -215.659045) (xy 108.593367 -215.698116)
			(xy 108.551696 -215.731347) (xy 108.505538 -215.757996) (xy 108.455924 -215.777468) (xy 108.403962 -215.789328)
			(xy 108.350812 -215.793312) (xy 108.297662 -215.789328) (xy 108.2457 -215.777468) (xy 108.196086 -215.757996)
			(xy 108.149928 -215.731347) (xy 108.108257 -215.698116) (xy 108.072005 -215.659045) (xy 108.041981 -215.615008)
			(xy 108.018855 -215.566987) (xy 108.003145 -215.516057) (xy 107.995202 -215.463353) (xy 107.994704 -215.436704)
			(xy 107.76712 -215.436704) (xy 107.766622 -215.463353) (xy 107.758679 -215.516057) (xy 107.742969 -215.566987)
			(xy 107.719843 -215.615008) (xy 107.689819 -215.659045) (xy 107.653567 -215.698116) (xy 107.611896 -215.731347)
			(xy 107.565738 -215.757996) (xy 107.516124 -215.777468) (xy 107.464162 -215.789328) (xy 107.411012 -215.793312)
			(xy 107.357862 -215.789328) (xy 107.3059 -215.777468) (xy 107.256286 -215.757996) (xy 107.210128 -215.731347)
			(xy 107.168457 -215.698116) (xy 107.132205 -215.659045) (xy 107.102181 -215.615008) (xy 107.079055 -215.566987)
			(xy 107.063345 -215.516057) (xy 107.055402 -215.463353) (xy 106.826822 -215.463353) (xy 106.818879 -215.516057)
			(xy 106.803169 -215.566987) (xy 106.780043 -215.615008) (xy 106.750019 -215.659045) (xy 106.713767 -215.698116)
			(xy 106.672096 -215.731347) (xy 106.625938 -215.757996) (xy 106.576324 -215.777468) (xy 106.524362 -215.789328)
			(xy 106.471212 -215.793312) (xy 106.418062 -215.789328) (xy 106.3661 -215.777468) (xy 106.316486 -215.757996)
			(xy 106.270328 -215.731347) (xy 106.228657 -215.698116) (xy 106.192405 -215.659045) (xy 106.162381 -215.615008)
			(xy 106.139255 -215.566987) (xy 106.123545 -215.516057) (xy 106.115602 -215.463353) (xy 106.115104 -215.436704)
			(xy 105.88817 -215.436704) (xy 105.884095 -215.490445) (xy 105.871964 -215.54296) (xy 105.852054 -215.593046)
			(xy 105.82482 -215.639558) (xy 105.790885 -215.681432) (xy 105.751025 -215.717712) (xy 105.706151 -215.747566)
			(xy 105.657288 -215.770315) (xy 105.605554 -215.785436) (xy 105.57891 -215.78951) (xy 105.534968 -215.795606)
			(xy 105.534968 -216.277169) (xy 105.645956 -216.277169) (xy 105.645956 -216.223871) (xy 105.653899 -216.171167)
			(xy 105.669609 -216.120237) (xy 105.692735 -216.072216) (xy 105.722759 -216.028179) (xy 105.759011 -215.989108)
			(xy 105.800682 -215.955877) (xy 105.84684 -215.929228) (xy 105.896454 -215.909756) (xy 105.948416 -215.897896)
			(xy 106.001566 -215.893913) (xy 106.054716 -215.897896) (xy 106.106678 -215.909756) (xy 106.156292 -215.929228)
			(xy 106.20245 -215.955877) (xy 106.244121 -215.989108) (xy 106.280373 -216.028179) (xy 106.310397 -216.072216)
			(xy 106.333523 -216.120237) (xy 106.349233 -216.171167) (xy 106.357176 -216.223871) (xy 106.357674 -216.25052)
			(xy 106.357176 -216.277169) (xy 106.585756 -216.277169) (xy 106.585756 -216.223871) (xy 106.593699 -216.171167)
			(xy 106.609409 -216.120237) (xy 106.632535 -216.072216) (xy 106.662559 -216.028179) (xy 106.698811 -215.989108)
			(xy 106.740482 -215.955877) (xy 106.78664 -215.929228) (xy 106.836254 -215.909756) (xy 106.888216 -215.897896)
			(xy 106.941366 -215.893913) (xy 106.994516 -215.897896) (xy 107.046478 -215.909756) (xy 107.096092 -215.929228)
			(xy 107.14225 -215.955877) (xy 107.183921 -215.989108) (xy 107.220173 -216.028179) (xy 107.250197 -216.072216)
			(xy 107.273323 -216.120237) (xy 107.289033 -216.171167) (xy 107.296976 -216.223871) (xy 107.297474 -216.25052)
			(xy 107.296976 -216.277169) (xy 107.525556 -216.277169) (xy 107.525556 -216.223871) (xy 107.533499 -216.171167)
			(xy 107.549209 -216.120237) (xy 107.572335 -216.072216) (xy 107.602359 -216.028179) (xy 107.638611 -215.989108)
			(xy 107.680282 -215.955877) (xy 107.72644 -215.929228) (xy 107.776054 -215.909756) (xy 107.828016 -215.897896)
			(xy 107.881166 -215.893913) (xy 107.934316 -215.897896) (xy 107.986278 -215.909756) (xy 108.035892 -215.929228)
			(xy 108.08205 -215.955877) (xy 108.123721 -215.989108) (xy 108.159973 -216.028179) (xy 108.189997 -216.072216)
			(xy 108.213123 -216.120237) (xy 108.228833 -216.171167) (xy 108.236776 -216.223871) (xy 108.237274 -216.25052)
			(xy 108.236776 -216.277169) (xy 108.465356 -216.277169) (xy 108.465356 -216.223871) (xy 108.473299 -216.171167)
			(xy 108.489009 -216.120237) (xy 108.512135 -216.072216) (xy 108.542159 -216.028179) (xy 108.578411 -215.989108)
			(xy 108.620082 -215.955877) (xy 108.66624 -215.929228) (xy 108.715854 -215.909756) (xy 108.767816 -215.897896)
			(xy 108.820966 -215.893913) (xy 108.874116 -215.897896) (xy 108.926078 -215.909756) (xy 108.975692 -215.929228)
			(xy 109.02185 -215.955877) (xy 109.063521 -215.989108) (xy 109.099773 -216.028179) (xy 109.129797 -216.072216)
			(xy 109.152923 -216.120237) (xy 109.168633 -216.171167) (xy 109.176576 -216.223871) (xy 109.177074 -216.25052)
			(xy 109.176576 -216.277169) (xy 109.405156 -216.277169) (xy 109.405156 -216.223871) (xy 109.413099 -216.171167)
			(xy 109.428809 -216.120237) (xy 109.451935 -216.072216) (xy 109.481959 -216.028179) (xy 109.518211 -215.989108)
			(xy 109.559882 -215.955877) (xy 109.60604 -215.929228) (xy 109.655654 -215.909756) (xy 109.707616 -215.897896)
			(xy 109.760766 -215.893913) (xy 109.813916 -215.897896) (xy 109.865878 -215.909756) (xy 109.915492 -215.929228)
			(xy 109.96165 -215.955877) (xy 110.003321 -215.989108) (xy 110.039573 -216.028179) (xy 110.069597 -216.072216)
			(xy 110.092723 -216.120237) (xy 110.108433 -216.171167) (xy 110.116376 -216.223871) (xy 110.116874 -216.25052)
			(xy 110.116376 -216.277169) (xy 110.344956 -216.277169) (xy 110.344956 -216.223871) (xy 110.352899 -216.171167)
			(xy 110.368609 -216.120237) (xy 110.391735 -216.072216) (xy 110.421759 -216.028179) (xy 110.458011 -215.989108)
			(xy 110.499682 -215.955877) (xy 110.54584 -215.929228) (xy 110.595454 -215.909756) (xy 110.647416 -215.897896)
			(xy 110.700566 -215.893913) (xy 110.753716 -215.897896) (xy 110.805678 -215.909756) (xy 110.855292 -215.929228)
			(xy 110.90145 -215.955877) (xy 110.943121 -215.989108) (xy 110.979373 -216.028179) (xy 111.009397 -216.072216)
			(xy 111.032523 -216.120237) (xy 111.048233 -216.171167) (xy 111.056176 -216.223871) (xy 111.056674 -216.25052)
			(xy 111.056176 -216.277169) (xy 111.284756 -216.277169) (xy 111.284756 -216.223871) (xy 111.292699 -216.171167)
			(xy 111.308409 -216.120237) (xy 111.331535 -216.072216) (xy 111.361559 -216.028179) (xy 111.397811 -215.989108)
			(xy 111.439482 -215.955877) (xy 111.48564 -215.929228) (xy 111.535254 -215.909756) (xy 111.587216 -215.897896)
			(xy 111.640366 -215.893913) (xy 111.693516 -215.897896) (xy 111.745478 -215.909756) (xy 111.795092 -215.929228)
			(xy 111.84125 -215.955877) (xy 111.882921 -215.989108) (xy 111.919173 -216.028179) (xy 111.949197 -216.072216)
			(xy 111.972323 -216.120237) (xy 111.988033 -216.171167) (xy 111.995976 -216.223871) (xy 111.996474 -216.25052)
			(xy 111.995976 -216.277169) (xy 112.224302 -216.277169) (xy 112.224302 -216.223871) (xy 112.232245 -216.171167)
			(xy 112.247955 -216.120237) (xy 112.271081 -216.072216) (xy 112.301105 -216.028179) (xy 112.337357 -215.989108)
			(xy 112.379028 -215.955877) (xy 112.425186 -215.929228) (xy 112.4748 -215.909756) (xy 112.526762 -215.897896)
			(xy 112.579912 -215.893913) (xy 112.633062 -215.897896) (xy 112.685024 -215.909756) (xy 112.734638 -215.929228)
			(xy 112.780796 -215.955877) (xy 112.822467 -215.989108) (xy 112.858719 -216.028179) (xy 112.888743 -216.072216)
			(xy 112.911869 -216.120237) (xy 112.927579 -216.171167) (xy 112.935522 -216.223871) (xy 112.93602 -216.25052)
			(xy 112.935522 -216.277169) (xy 113.164356 -216.277169) (xy 113.164356 -216.223871) (xy 113.172299 -216.171167)
			(xy 113.188009 -216.120237) (xy 113.211135 -216.072216) (xy 113.241159 -216.028179) (xy 113.277411 -215.989108)
			(xy 113.319082 -215.955877) (xy 113.36524 -215.929228) (xy 113.414854 -215.909756) (xy 113.466816 -215.897896)
			(xy 113.519966 -215.893913) (xy 113.573116 -215.897896) (xy 113.625078 -215.909756) (xy 113.674692 -215.929228)
			(xy 113.72085 -215.955877) (xy 113.762521 -215.989108) (xy 113.798773 -216.028179) (xy 113.828797 -216.072216)
			(xy 113.851923 -216.120237) (xy 113.867633 -216.171167) (xy 113.875576 -216.223871) (xy 113.876074 -216.25052)
			(xy 113.875576 -216.277169) (xy 114.104156 -216.277169) (xy 114.104156 -216.223871) (xy 114.112099 -216.171167)
			(xy 114.127809 -216.120237) (xy 114.150935 -216.072216) (xy 114.180959 -216.028179) (xy 114.217211 -215.989108)
			(xy 114.258882 -215.955877) (xy 114.30504 -215.929228) (xy 114.354654 -215.909756) (xy 114.406616 -215.897896)
			(xy 114.459766 -215.893913) (xy 114.512916 -215.897896) (xy 114.564878 -215.909756) (xy 114.614492 -215.929228)
			(xy 114.66065 -215.955877) (xy 114.702321 -215.989108) (xy 114.738573 -216.028179) (xy 114.768597 -216.072216)
			(xy 114.791723 -216.120237) (xy 114.807433 -216.171167) (xy 114.815376 -216.223871) (xy 114.815874 -216.25052)
			(xy 114.815376 -216.277169) (xy 115.043702 -216.277169) (xy 115.043702 -216.223871) (xy 115.051645 -216.171167)
			(xy 115.067355 -216.120237) (xy 115.090481 -216.072216) (xy 115.120505 -216.028179) (xy 115.156757 -215.989108)
			(xy 115.198428 -215.955877) (xy 115.244586 -215.929228) (xy 115.2942 -215.909756) (xy 115.346162 -215.897896)
			(xy 115.399312 -215.893913) (xy 115.452462 -215.897896) (xy 115.504424 -215.909756) (xy 115.554038 -215.929228)
			(xy 115.600196 -215.955877) (xy 115.641867 -215.989108) (xy 115.678119 -216.028179) (xy 115.708143 -216.072216)
			(xy 115.731269 -216.120237) (xy 115.746979 -216.171167) (xy 115.754922 -216.223871) (xy 115.75542 -216.25052)
			(xy 115.754922 -216.277169) (xy 115.983756 -216.277169) (xy 115.983756 -216.223871) (xy 115.991699 -216.171167)
			(xy 116.007409 -216.120237) (xy 116.030535 -216.072216) (xy 116.060559 -216.028179) (xy 116.096811 -215.989108)
			(xy 116.138482 -215.955877) (xy 116.18464 -215.929228) (xy 116.234254 -215.909756) (xy 116.286216 -215.897896)
			(xy 116.339366 -215.893913) (xy 116.392516 -215.897896) (xy 116.444478 -215.909756) (xy 116.494092 -215.929228)
			(xy 116.54025 -215.955877) (xy 116.581921 -215.989108) (xy 116.618173 -216.028179) (xy 116.648197 -216.072216)
			(xy 116.671323 -216.120237) (xy 116.687033 -216.171167) (xy 116.694976 -216.223871) (xy 116.695474 -216.25052)
			(xy 116.694976 -216.277169) (xy 116.923556 -216.277169) (xy 116.923556 -216.223871) (xy 116.931499 -216.171167)
			(xy 116.947209 -216.120237) (xy 116.970335 -216.072216) (xy 117.000359 -216.028179) (xy 117.036611 -215.989108)
			(xy 117.078282 -215.955877) (xy 117.12444 -215.929228) (xy 117.174054 -215.909756) (xy 117.226016 -215.897896)
			(xy 117.279166 -215.893913) (xy 117.332316 -215.897896) (xy 117.384278 -215.909756) (xy 117.433892 -215.929228)
			(xy 117.48005 -215.955877) (xy 117.521721 -215.989108) (xy 117.557973 -216.028179) (xy 117.587997 -216.072216)
			(xy 117.611123 -216.120237) (xy 117.626833 -216.171167) (xy 117.634776 -216.223871) (xy 117.635274 -216.25052)
			(xy 117.634776 -216.277169) (xy 117.863356 -216.277169) (xy 117.863356 -216.223871) (xy 117.871299 -216.171167)
			(xy 117.887009 -216.120237) (xy 117.910135 -216.072216) (xy 117.940159 -216.028179) (xy 117.976411 -215.989108)
			(xy 118.018082 -215.955877) (xy 118.06424 -215.929228) (xy 118.113854 -215.909756) (xy 118.165816 -215.897896)
			(xy 118.218966 -215.893913) (xy 118.272116 -215.897896) (xy 118.324078 -215.909756) (xy 118.373692 -215.929228)
			(xy 118.41985 -215.955877) (xy 118.461521 -215.989108) (xy 118.497773 -216.028179) (xy 118.527797 -216.072216)
			(xy 118.550923 -216.120237) (xy 118.566633 -216.171167) (xy 118.574576 -216.223871) (xy 118.575074 -216.25052)
			(xy 118.574576 -216.277169) (xy 118.566633 -216.329873) (xy 118.550923 -216.380803) (xy 118.527797 -216.428824)
			(xy 118.497773 -216.472861) (xy 118.461521 -216.511932) (xy 118.41985 -216.545163) (xy 118.373692 -216.571812)
			(xy 118.324078 -216.591284) (xy 118.272116 -216.603144) (xy 118.218966 -216.607128) (xy 118.165816 -216.603144)
			(xy 118.113854 -216.591284) (xy 118.06424 -216.571812) (xy 118.018082 -216.545163) (xy 117.976411 -216.511932)
			(xy 117.940159 -216.472861) (xy 117.910135 -216.428824) (xy 117.887009 -216.380803) (xy 117.871299 -216.329873)
			(xy 117.863356 -216.277169) (xy 117.634776 -216.277169) (xy 117.626833 -216.329873) (xy 117.611123 -216.380803)
			(xy 117.587997 -216.428824) (xy 117.557973 -216.472861) (xy 117.521721 -216.511932) (xy 117.48005 -216.545163)
			(xy 117.433892 -216.571812) (xy 117.384278 -216.591284) (xy 117.332316 -216.603144) (xy 117.279166 -216.607128)
			(xy 117.226016 -216.603144) (xy 117.174054 -216.591284) (xy 117.12444 -216.571812) (xy 117.078282 -216.545163)
			(xy 117.036611 -216.511932) (xy 117.000359 -216.472861) (xy 116.970335 -216.428824) (xy 116.947209 -216.380803)
			(xy 116.931499 -216.329873) (xy 116.923556 -216.277169) (xy 116.694976 -216.277169) (xy 116.687033 -216.329873)
			(xy 116.671323 -216.380803) (xy 116.648197 -216.428824) (xy 116.618173 -216.472861) (xy 116.581921 -216.511932)
			(xy 116.54025 -216.545163) (xy 116.494092 -216.571812) (xy 116.444478 -216.591284) (xy 116.392516 -216.603144)
			(xy 116.339366 -216.607128) (xy 116.286216 -216.603144) (xy 116.234254 -216.591284) (xy 116.18464 -216.571812)
			(xy 116.138482 -216.545163) (xy 116.096811 -216.511932) (xy 116.060559 -216.472861) (xy 116.030535 -216.428824)
			(xy 116.007409 -216.380803) (xy 115.991699 -216.329873) (xy 115.983756 -216.277169) (xy 115.754922 -216.277169)
			(xy 115.746979 -216.329873) (xy 115.731269 -216.380803) (xy 115.708143 -216.428824) (xy 115.678119 -216.472861)
			(xy 115.641867 -216.511932) (xy 115.600196 -216.545163) (xy 115.554038 -216.571812) (xy 115.504424 -216.591284)
			(xy 115.452462 -216.603144) (xy 115.399312 -216.607128) (xy 115.346162 -216.603144) (xy 115.2942 -216.591284)
			(xy 115.244586 -216.571812) (xy 115.198428 -216.545163) (xy 115.156757 -216.511932) (xy 115.120505 -216.472861)
			(xy 115.090481 -216.428824) (xy 115.067355 -216.380803) (xy 115.051645 -216.329873) (xy 115.043702 -216.277169)
			(xy 114.815376 -216.277169) (xy 114.807433 -216.329873) (xy 114.791723 -216.380803) (xy 114.768597 -216.428824)
			(xy 114.738573 -216.472861) (xy 114.702321 -216.511932) (xy 114.66065 -216.545163) (xy 114.614492 -216.571812)
			(xy 114.564878 -216.591284) (xy 114.512916 -216.603144) (xy 114.459766 -216.607128) (xy 114.406616 -216.603144)
			(xy 114.354654 -216.591284) (xy 114.30504 -216.571812) (xy 114.258882 -216.545163) (xy 114.217211 -216.511932)
			(xy 114.180959 -216.472861) (xy 114.150935 -216.428824) (xy 114.127809 -216.380803) (xy 114.112099 -216.329873)
			(xy 114.104156 -216.277169) (xy 113.875576 -216.277169) (xy 113.867633 -216.329873) (xy 113.851923 -216.380803)
			(xy 113.828797 -216.428824) (xy 113.798773 -216.472861) (xy 113.762521 -216.511932) (xy 113.72085 -216.545163)
			(xy 113.674692 -216.571812) (xy 113.625078 -216.591284) (xy 113.573116 -216.603144) (xy 113.519966 -216.607128)
			(xy 113.466816 -216.603144) (xy 113.414854 -216.591284) (xy 113.36524 -216.571812) (xy 113.319082 -216.545163)
			(xy 113.277411 -216.511932) (xy 113.241159 -216.472861) (xy 113.211135 -216.428824) (xy 113.188009 -216.380803)
			(xy 113.172299 -216.329873) (xy 113.164356 -216.277169) (xy 112.935522 -216.277169) (xy 112.927579 -216.329873)
			(xy 112.911869 -216.380803) (xy 112.888743 -216.428824) (xy 112.858719 -216.472861) (xy 112.822467 -216.511932)
			(xy 112.780796 -216.545163) (xy 112.734638 -216.571812) (xy 112.685024 -216.591284) (xy 112.633062 -216.603144)
			(xy 112.579912 -216.607128) (xy 112.526762 -216.603144) (xy 112.4748 -216.591284) (xy 112.425186 -216.571812)
			(xy 112.379028 -216.545163) (xy 112.337357 -216.511932) (xy 112.301105 -216.472861) (xy 112.271081 -216.428824)
			(xy 112.247955 -216.380803) (xy 112.232245 -216.329873) (xy 112.224302 -216.277169) (xy 111.995976 -216.277169)
			(xy 111.988033 -216.329873) (xy 111.972323 -216.380803) (xy 111.949197 -216.428824) (xy 111.919173 -216.472861)
			(xy 111.882921 -216.511932) (xy 111.84125 -216.545163) (xy 111.795092 -216.571812) (xy 111.745478 -216.591284)
			(xy 111.693516 -216.603144) (xy 111.640366 -216.607128) (xy 111.587216 -216.603144) (xy 111.535254 -216.591284)
			(xy 111.48564 -216.571812) (xy 111.439482 -216.545163) (xy 111.397811 -216.511932) (xy 111.361559 -216.472861)
			(xy 111.331535 -216.428824) (xy 111.308409 -216.380803) (xy 111.292699 -216.329873) (xy 111.284756 -216.277169)
			(xy 111.056176 -216.277169) (xy 111.048233 -216.329873) (xy 111.032523 -216.380803) (xy 111.009397 -216.428824)
			(xy 110.979373 -216.472861) (xy 110.943121 -216.511932) (xy 110.90145 -216.545163) (xy 110.855292 -216.571812)
			(xy 110.805678 -216.591284) (xy 110.753716 -216.603144) (xy 110.700566 -216.607128) (xy 110.647416 -216.603144)
			(xy 110.595454 -216.591284) (xy 110.54584 -216.571812) (xy 110.499682 -216.545163) (xy 110.458011 -216.511932)
			(xy 110.421759 -216.472861) (xy 110.391735 -216.428824) (xy 110.368609 -216.380803) (xy 110.352899 -216.329873)
			(xy 110.344956 -216.277169) (xy 110.116376 -216.277169) (xy 110.108433 -216.329873) (xy 110.092723 -216.380803)
			(xy 110.069597 -216.428824) (xy 110.039573 -216.472861) (xy 110.003321 -216.511932) (xy 109.96165 -216.545163)
			(xy 109.915492 -216.571812) (xy 109.865878 -216.591284) (xy 109.813916 -216.603144) (xy 109.760766 -216.607128)
			(xy 109.707616 -216.603144) (xy 109.655654 -216.591284) (xy 109.60604 -216.571812) (xy 109.559882 -216.545163)
			(xy 109.518211 -216.511932) (xy 109.481959 -216.472861) (xy 109.451935 -216.428824) (xy 109.428809 -216.380803)
			(xy 109.413099 -216.329873) (xy 109.405156 -216.277169) (xy 109.176576 -216.277169) (xy 109.168633 -216.329873)
			(xy 109.152923 -216.380803) (xy 109.129797 -216.428824) (xy 109.099773 -216.472861) (xy 109.063521 -216.511932)
			(xy 109.02185 -216.545163) (xy 108.975692 -216.571812) (xy 108.926078 -216.591284) (xy 108.874116 -216.603144)
			(xy 108.820966 -216.607128) (xy 108.767816 -216.603144) (xy 108.715854 -216.591284) (xy 108.66624 -216.571812)
			(xy 108.620082 -216.545163) (xy 108.578411 -216.511932) (xy 108.542159 -216.472861) (xy 108.512135 -216.428824)
			(xy 108.489009 -216.380803) (xy 108.473299 -216.329873) (xy 108.465356 -216.277169) (xy 108.236776 -216.277169)
			(xy 108.228833 -216.329873) (xy 108.213123 -216.380803) (xy 108.189997 -216.428824) (xy 108.159973 -216.472861)
			(xy 108.123721 -216.511932) (xy 108.08205 -216.545163) (xy 108.035892 -216.571812) (xy 107.986278 -216.591284)
			(xy 107.934316 -216.603144) (xy 107.881166 -216.607128) (xy 107.828016 -216.603144) (xy 107.776054 -216.591284)
			(xy 107.72644 -216.571812) (xy 107.680282 -216.545163) (xy 107.638611 -216.511932) (xy 107.602359 -216.472861)
			(xy 107.572335 -216.428824) (xy 107.549209 -216.380803) (xy 107.533499 -216.329873) (xy 107.525556 -216.277169)
			(xy 107.296976 -216.277169) (xy 107.289033 -216.329873) (xy 107.273323 -216.380803) (xy 107.250197 -216.428824)
			(xy 107.220173 -216.472861) (xy 107.183921 -216.511932) (xy 107.14225 -216.545163) (xy 107.096092 -216.571812)
			(xy 107.046478 -216.591284) (xy 106.994516 -216.603144) (xy 106.941366 -216.607128) (xy 106.888216 -216.603144)
			(xy 106.836254 -216.591284) (xy 106.78664 -216.571812) (xy 106.740482 -216.545163) (xy 106.698811 -216.511932)
			(xy 106.662559 -216.472861) (xy 106.632535 -216.428824) (xy 106.609409 -216.380803) (xy 106.593699 -216.329873)
			(xy 106.585756 -216.277169) (xy 106.357176 -216.277169) (xy 106.349233 -216.329873) (xy 106.333523 -216.380803)
			(xy 106.310397 -216.428824) (xy 106.280373 -216.472861) (xy 106.244121 -216.511932) (xy 106.20245 -216.545163)
			(xy 106.156292 -216.571812) (xy 106.106678 -216.591284) (xy 106.054716 -216.603144) (xy 106.001566 -216.607128)
			(xy 105.948416 -216.603144) (xy 105.896454 -216.591284) (xy 105.84684 -216.571812) (xy 105.800682 -216.545163)
			(xy 105.759011 -216.511932) (xy 105.722759 -216.472861) (xy 105.692735 -216.428824) (xy 105.669609 -216.380803)
			(xy 105.653899 -216.329873) (xy 105.645956 -216.277169) (xy 105.534968 -216.277169) (xy 105.534968 -216.705434)
			(xy 105.57891 -216.71153) (xy 105.605553 -216.715596) (xy 105.657282 -216.730717) (xy 105.70614 -216.753464)
			(xy 105.75101 -216.783317) (xy 105.790866 -216.819593) (xy 105.824797 -216.861464) (xy 105.852028 -216.907972)
			(xy 105.871936 -216.958054) (xy 105.884065 -217.010565) (xy 105.888138 -217.064305) (xy 105.886115 -217.090985)
			(xy 106.115856 -217.090985) (xy 106.115856 -217.037687) (xy 106.123799 -216.984983) (xy 106.139509 -216.934053)
			(xy 106.162635 -216.886032) (xy 106.192659 -216.841995) (xy 106.228911 -216.802924) (xy 106.270582 -216.769693)
			(xy 106.31674 -216.743044) (xy 106.366354 -216.723572) (xy 106.418316 -216.711712) (xy 106.471466 -216.707729)
			(xy 106.524616 -216.711712) (xy 106.576578 -216.723572) (xy 106.626192 -216.743044) (xy 106.67235 -216.769693)
			(xy 106.714021 -216.802924) (xy 106.750273 -216.841995) (xy 106.780297 -216.886032) (xy 106.803423 -216.934053)
			(xy 106.819133 -216.984983) (xy 106.827076 -217.037687) (xy 106.827574 -217.064336) (xy 106.827076 -217.090985)
			(xy 106.819133 -217.143689) (xy 106.803423 -217.194619) (xy 106.780297 -217.24264) (xy 106.750273 -217.286677)
			(xy 106.714021 -217.325748) (xy 106.67235 -217.358979) (xy 106.626192 -217.385628) (xy 106.576578 -217.4051)
			(xy 106.524616 -217.41696) (xy 106.471466 -217.420944) (xy 106.418316 -217.41696) (xy 106.366354 -217.4051)
			(xy 106.31674 -217.385628) (xy 106.270582 -217.358979) (xy 106.228911 -217.325748) (xy 106.192659 -217.286677)
			(xy 106.162635 -217.24264) (xy 106.139509 -217.194619) (xy 106.123799 -217.143689) (xy 106.115856 -217.090985)
			(xy 105.886115 -217.090985) (xy 105.884063 -217.118044) (xy 105.871933 -217.170555) (xy 105.852024 -217.220636)
			(xy 105.824792 -217.267144) (xy 105.790859 -217.309014) (xy 105.751002 -217.345289) (xy 105.706131 -217.375141)
			(xy 105.657273 -217.397886) (xy 105.605543 -217.413005) (xy 105.57891 -217.417142) (xy 105.553764 -217.420698)
			(xy 105.534968 -217.45321) (xy 105.534968 -217.878406) (xy 105.645458 -217.878406) (xy 105.645956 -217.851757)
			(xy 105.653899 -217.799053) (xy 105.669609 -217.748123) (xy 105.692735 -217.700102) (xy 105.722759 -217.656065)
			(xy 105.759011 -217.616994) (xy 105.800682 -217.583763) (xy 105.84684 -217.557114) (xy 105.896454 -217.537642)
			(xy 105.948416 -217.525782) (xy 106.001566 -217.521799) (xy 106.054716 -217.525782) (xy 106.106678 -217.537642)
			(xy 106.156292 -217.557114) (xy 106.20245 -217.583763) (xy 106.244121 -217.616994) (xy 106.280373 -217.656065)
			(xy 106.310397 -217.700102) (xy 106.333523 -217.748123) (xy 106.349233 -217.799053) (xy 106.357176 -217.851757)
			(xy 106.357674 -217.878406) (xy 106.585258 -217.878406) (xy 106.585679 -217.852777) (xy 106.593014 -217.802046)
			(xy 106.607548 -217.752891) (xy 106.628981 -217.706328) (xy 106.656869 -217.66332) (xy 106.690635 -217.624755)
			(xy 106.729583 -217.591431) (xy 106.772907 -217.564037) (xy 106.819712 -217.543138) (xy 106.869029 -217.529166)
			(xy 106.894376 -217.525346) (xy 106.919014 -217.522044) (xy 107.09148 -217.22334) (xy 107.081828 -217.200226)
			(xy 107.073323 -217.17859) (xy 107.061331 -217.133674) (xy 107.055282 -217.08758) (xy 107.054904 -217.064336)
			(xy 107.055402 -217.037687) (xy 107.063345 -216.984983) (xy 107.079055 -216.934053) (xy 107.102181 -216.886032)
			(xy 107.132205 -216.841995) (xy 107.168457 -216.802924) (xy 107.210128 -216.769693) (xy 107.256286 -216.743044)
			(xy 107.3059 -216.723572) (xy 107.357862 -216.711712) (xy 107.411012 -216.707729) (xy 107.464162 -216.711712)
			(xy 107.516124 -216.723572) (xy 107.565738 -216.743044) (xy 107.611896 -216.769693) (xy 107.653567 -216.802924)
			(xy 107.689819 -216.841995) (xy 107.719843 -216.886032) (xy 107.742969 -216.934053) (xy 107.758679 -216.984983)
			(xy 107.766622 -217.037687) (xy 107.76712 -217.064336) (xy 107.766664 -217.089965) (xy 107.766517 -217.090985)
			(xy 107.995456 -217.090985) (xy 107.995456 -217.037687) (xy 108.003399 -216.984983) (xy 108.019109 -216.934053)
			(xy 108.042235 -216.886032) (xy 108.072259 -216.841995) (xy 108.108511 -216.802924) (xy 108.150182 -216.769693)
			(xy 108.19634 -216.743044) (xy 108.245954 -216.723572) (xy 108.297916 -216.711712) (xy 108.351066 -216.707729)
			(xy 108.404216 -216.711712) (xy 108.456178 -216.723572) (xy 108.505792 -216.743044) (xy 108.55195 -216.769693)
			(xy 108.593621 -216.802924) (xy 108.629873 -216.841995) (xy 108.659897 -216.886032) (xy 108.683023 -216.934053)
			(xy 108.698733 -216.984983) (xy 108.706676 -217.037687) (xy 108.707174 -217.064336) (xy 108.706676 -217.090985)
			(xy 108.698733 -217.143689) (xy 108.683023 -217.194619) (xy 108.659897 -217.24264) (xy 108.629873 -217.286677)
			(xy 108.593621 -217.325748) (xy 108.55195 -217.358979) (xy 108.505792 -217.385628) (xy 108.456178 -217.4051)
			(xy 108.404216 -217.41696) (xy 108.351066 -217.420944) (xy 108.297916 -217.41696) (xy 108.245954 -217.4051)
			(xy 108.19634 -217.385628) (xy 108.150182 -217.358979) (xy 108.108511 -217.325748) (xy 108.072259 -217.286677)
			(xy 108.042235 -217.24264) (xy 108.019109 -217.194619) (xy 108.003399 -217.143689) (xy 107.995456 -217.090985)
			(xy 107.766517 -217.090985) (xy 107.759337 -217.140695) (xy 107.744809 -217.18985) (xy 107.723382 -217.236414)
			(xy 107.695499 -217.279423) (xy 107.661735 -217.317989) (xy 107.62279 -217.351313) (xy 107.579468 -217.378708)
			(xy 107.532665 -217.399607) (xy 107.483348 -217.413577) (xy 107.458002 -217.417396) (xy 107.433364 -217.420698)
			(xy 107.260898 -217.719402) (xy 107.27055 -217.742516) (xy 107.279067 -217.764148) (xy 107.291054 -217.809066)
			(xy 107.297099 -217.855161) (xy 107.297474 -217.878406) (xy 107.525058 -217.878406) (xy 107.525556 -217.851757)
			(xy 107.533499 -217.799053) (xy 107.549209 -217.748123) (xy 107.572335 -217.700102) (xy 107.602359 -217.656065)
			(xy 107.638611 -217.616994) (xy 107.680282 -217.583763) (xy 107.72644 -217.557114) (xy 107.776054 -217.537642)
			(xy 107.828016 -217.525782) (xy 107.881166 -217.521799) (xy 107.934316 -217.525782) (xy 107.986278 -217.537642)
			(xy 108.035892 -217.557114) (xy 108.08205 -217.583763) (xy 108.123721 -217.616994) (xy 108.159973 -217.656065)
			(xy 108.189997 -217.700102) (xy 108.213123 -217.748123) (xy 108.228833 -217.799053) (xy 108.236776 -217.851757)
			(xy 108.237274 -217.878406) (xy 108.464858 -217.878406) (xy 108.465279 -217.852777) (xy 108.472614 -217.802046)
			(xy 108.487148 -217.752891) (xy 108.508581 -217.706328) (xy 108.536469 -217.66332) (xy 108.570235 -217.624755)
			(xy 108.609183 -217.591431) (xy 108.652507 -217.564037) (xy 108.699312 -217.543138) (xy 108.748629 -217.529166)
			(xy 108.773976 -217.525346) (xy 108.798614 -217.522044) (xy 108.97108 -217.22334) (xy 108.961428 -217.200226)
			(xy 108.952923 -217.17859) (xy 108.940931 -217.133674) (xy 108.934882 -217.08758) (xy 108.934504 -217.064336)
			(xy 108.935002 -217.037687) (xy 108.942945 -216.984983) (xy 108.958655 -216.934053) (xy 108.981781 -216.886032)
			(xy 109.011805 -216.841995) (xy 109.048057 -216.802924) (xy 109.089728 -216.769693) (xy 109.135886 -216.743044)
			(xy 109.1855 -216.723572) (xy 109.237462 -216.711712) (xy 109.290612 -216.707729) (xy 109.343762 -216.711712)
			(xy 109.395724 -216.723572) (xy 109.445338 -216.743044) (xy 109.491496 -216.769693) (xy 109.533167 -216.802924)
			(xy 109.569419 -216.841995) (xy 109.599443 -216.886032) (xy 109.622569 -216.934053) (xy 109.638279 -216.984983)
			(xy 109.646222 -217.037687) (xy 109.64672 -217.064336) (xy 109.646264 -217.089965) (xy 109.646117 -217.090985)
			(xy 109.875056 -217.090985) (xy 109.875056 -217.037687) (xy 109.882999 -216.984983) (xy 109.898709 -216.934053)
			(xy 109.921835 -216.886032) (xy 109.951859 -216.841995) (xy 109.988111 -216.802924) (xy 110.029782 -216.769693)
			(xy 110.07594 -216.743044) (xy 110.125554 -216.723572) (xy 110.177516 -216.711712) (xy 110.230666 -216.707729)
			(xy 110.283816 -216.711712) (xy 110.335778 -216.723572) (xy 110.385392 -216.743044) (xy 110.43155 -216.769693)
			(xy 110.473221 -216.802924) (xy 110.509473 -216.841995) (xy 110.539497 -216.886032) (xy 110.562623 -216.934053)
			(xy 110.578333 -216.984983) (xy 110.586276 -217.037687) (xy 110.586774 -217.064336) (xy 110.586276 -217.090985)
			(xy 110.578333 -217.143689) (xy 110.562623 -217.194619) (xy 110.539497 -217.24264) (xy 110.509473 -217.286677)
			(xy 110.473221 -217.325748) (xy 110.43155 -217.358979) (xy 110.385392 -217.385628) (xy 110.335778 -217.4051)
			(xy 110.283816 -217.41696) (xy 110.230666 -217.420944) (xy 110.177516 -217.41696) (xy 110.125554 -217.4051)
			(xy 110.07594 -217.385628) (xy 110.029782 -217.358979) (xy 109.988111 -217.325748) (xy 109.951859 -217.286677)
			(xy 109.921835 -217.24264) (xy 109.898709 -217.194619) (xy 109.882999 -217.143689) (xy 109.875056 -217.090985)
			(xy 109.646117 -217.090985) (xy 109.638937 -217.140695) (xy 109.624409 -217.18985) (xy 109.602982 -217.236414)
			(xy 109.575099 -217.279423) (xy 109.541335 -217.317989) (xy 109.50239 -217.351313) (xy 109.459068 -217.378708)
			(xy 109.412265 -217.399607) (xy 109.362948 -217.413577) (xy 109.337602 -217.417396) (xy 109.312964 -217.420698)
			(xy 109.140498 -217.719402) (xy 109.15015 -217.742516) (xy 109.158667 -217.764148) (xy 109.170654 -217.809066)
			(xy 109.176699 -217.855161) (xy 109.177074 -217.878406) (xy 109.404658 -217.878406) (xy 109.405156 -217.851757)
			(xy 109.413099 -217.799053) (xy 109.428809 -217.748123) (xy 109.451935 -217.700102) (xy 109.481959 -217.656065)
			(xy 109.518211 -217.616994) (xy 109.559882 -217.583763) (xy 109.60604 -217.557114) (xy 109.655654 -217.537642)
			(xy 109.707616 -217.525782) (xy 109.760766 -217.521799) (xy 109.813916 -217.525782) (xy 109.865878 -217.537642)
			(xy 109.915492 -217.557114) (xy 109.96165 -217.583763) (xy 110.003321 -217.616994) (xy 110.039573 -217.656065)
			(xy 110.069597 -217.700102) (xy 110.092723 -217.748123) (xy 110.108433 -217.799053) (xy 110.116376 -217.851757)
			(xy 110.116874 -217.878406) (xy 110.344458 -217.878406) (xy 110.344879 -217.852777) (xy 110.352214 -217.802046)
			(xy 110.366748 -217.752891) (xy 110.388181 -217.706328) (xy 110.416069 -217.66332) (xy 110.449835 -217.624755)
			(xy 110.488783 -217.591431) (xy 110.532107 -217.564037) (xy 110.578912 -217.543138) (xy 110.628229 -217.529166)
			(xy 110.653576 -217.525346) (xy 110.678214 -217.522044) (xy 110.85068 -217.223086) (xy 110.841282 -217.199972)
			(xy 110.832787 -217.178378) (xy 110.820812 -217.133545) (xy 110.814752 -217.087538) (xy 110.814358 -217.064336)
			(xy 110.814856 -217.037687) (xy 110.822799 -216.984983) (xy 110.838509 -216.934053) (xy 110.861635 -216.886032)
			(xy 110.891659 -216.841995) (xy 110.927911 -216.802924) (xy 110.969582 -216.769693) (xy 111.01574 -216.743044)
			(xy 111.065354 -216.723572) (xy 111.117316 -216.711712) (xy 111.170466 -216.707729) (xy 111.223616 -216.711712)
			(xy 111.275578 -216.723572) (xy 111.325192 -216.743044) (xy 111.37135 -216.769693) (xy 111.413021 -216.802924)
			(xy 111.449273 -216.841995) (xy 111.479297 -216.886032) (xy 111.502423 -216.934053) (xy 111.518133 -216.984983)
			(xy 111.526076 -217.037687) (xy 111.526574 -217.064336) (xy 111.526072 -217.089963) (xy 111.525924 -217.090985)
			(xy 111.754656 -217.090985) (xy 111.754656 -217.037687) (xy 111.762599 -216.984983) (xy 111.778309 -216.934053)
			(xy 111.801435 -216.886032) (xy 111.831459 -216.841995) (xy 111.867711 -216.802924) (xy 111.909382 -216.769693)
			(xy 111.95554 -216.743044) (xy 112.005154 -216.723572) (xy 112.057116 -216.711712) (xy 112.110266 -216.707729)
			(xy 112.163416 -216.711712) (xy 112.215378 -216.723572) (xy 112.264992 -216.743044) (xy 112.31115 -216.769693)
			(xy 112.352821 -216.802924) (xy 112.389073 -216.841995) (xy 112.419097 -216.886032) (xy 112.442223 -216.934053)
			(xy 112.457933 -216.984983) (xy 112.465876 -217.037687) (xy 112.466374 -217.064336) (xy 112.693704 -217.064336)
			(xy 112.694202 -217.037687) (xy 112.702145 -216.984983) (xy 112.717855 -216.934053) (xy 112.740981 -216.886032)
			(xy 112.771005 -216.841995) (xy 112.807257 -216.802924) (xy 112.848928 -216.769693) (xy 112.895086 -216.743044)
			(xy 112.9447 -216.723572) (xy 112.996662 -216.711712) (xy 113.049812 -216.707729) (xy 113.102962 -216.711712)
			(xy 113.154924 -216.723572) (xy 113.204538 -216.743044) (xy 113.250696 -216.769693) (xy 113.292367 -216.802924)
			(xy 113.328619 -216.841995) (xy 113.358643 -216.886032) (xy 113.381769 -216.934053) (xy 113.397479 -216.984983)
			(xy 113.405422 -217.037687) (xy 113.40592 -217.064336) (xy 113.405549 -217.08754) (xy 113.405096 -217.090985)
			(xy 113.634256 -217.090985) (xy 113.634256 -217.037687) (xy 113.642199 -216.984983) (xy 113.657909 -216.934053)
			(xy 113.681035 -216.886032) (xy 113.711059 -216.841995) (xy 113.747311 -216.802924) (xy 113.788982 -216.769693)
			(xy 113.83514 -216.743044) (xy 113.884754 -216.723572) (xy 113.936716 -216.711712) (xy 113.989866 -216.707729)
			(xy 114.043016 -216.711712) (xy 114.094978 -216.723572) (xy 114.144592 -216.743044) (xy 114.19075 -216.769693)
			(xy 114.232421 -216.802924) (xy 114.268673 -216.841995) (xy 114.298697 -216.886032) (xy 114.321823 -216.934053)
			(xy 114.337533 -216.984983) (xy 114.345476 -217.037687) (xy 114.345974 -217.064336) (xy 114.573304 -217.064336)
			(xy 114.573802 -217.037687) (xy 114.581745 -216.984983) (xy 114.597455 -216.934053) (xy 114.620581 -216.886032)
			(xy 114.650605 -216.841995) (xy 114.686857 -216.802924) (xy 114.728528 -216.769693) (xy 114.774686 -216.743044)
			(xy 114.8243 -216.723572) (xy 114.876262 -216.711712) (xy 114.929412 -216.707729) (xy 114.982562 -216.711712)
			(xy 115.034524 -216.723572) (xy 115.084138 -216.743044) (xy 115.130296 -216.769693) (xy 115.171967 -216.802924)
			(xy 115.208219 -216.841995) (xy 115.238243 -216.886032) (xy 115.261369 -216.934053) (xy 115.277079 -216.984983)
			(xy 115.285022 -217.037687) (xy 115.28552 -217.064336) (xy 115.285149 -217.08754) (xy 115.284696 -217.090985)
			(xy 115.513856 -217.090985) (xy 115.513856 -217.037687) (xy 115.521799 -216.984983) (xy 115.537509 -216.934053)
			(xy 115.560635 -216.886032) (xy 115.590659 -216.841995) (xy 115.626911 -216.802924) (xy 115.668582 -216.769693)
			(xy 115.71474 -216.743044) (xy 115.764354 -216.723572) (xy 115.816316 -216.711712) (xy 115.869466 -216.707729)
			(xy 115.922616 -216.711712) (xy 115.974578 -216.723572) (xy 116.024192 -216.743044) (xy 116.07035 -216.769693)
			(xy 116.112021 -216.802924) (xy 116.148273 -216.841995) (xy 116.178297 -216.886032) (xy 116.201423 -216.934053)
			(xy 116.217133 -216.984983) (xy 116.225076 -217.037687) (xy 116.225574 -217.064336) (xy 116.452904 -217.064336)
			(xy 116.453402 -217.037687) (xy 116.461345 -216.984983) (xy 116.477055 -216.934053) (xy 116.500181 -216.886032)
			(xy 116.530205 -216.841995) (xy 116.566457 -216.802924) (xy 116.608128 -216.769693) (xy 116.654286 -216.743044)
			(xy 116.7039 -216.723572) (xy 116.755862 -216.711712) (xy 116.809012 -216.707729) (xy 116.862162 -216.711712)
			(xy 116.914124 -216.723572) (xy 116.963738 -216.743044) (xy 117.009896 -216.769693) (xy 117.051567 -216.802924)
			(xy 117.087819 -216.841995) (xy 117.117843 -216.886032) (xy 117.140969 -216.934053) (xy 117.156679 -216.984983)
			(xy 117.164622 -217.037687) (xy 117.16512 -217.064336) (xy 117.164749 -217.08754) (xy 117.164296 -217.090985)
			(xy 117.393456 -217.090985) (xy 117.393456 -217.037687) (xy 117.401399 -216.984983) (xy 117.417109 -216.934053)
			(xy 117.440235 -216.886032) (xy 117.470259 -216.841995) (xy 117.506511 -216.802924) (xy 117.548182 -216.769693)
			(xy 117.59434 -216.743044) (xy 117.643954 -216.723572) (xy 117.695916 -216.711712) (xy 117.749066 -216.707729)
			(xy 117.802216 -216.711712) (xy 117.854178 -216.723572) (xy 117.903792 -216.743044) (xy 117.94995 -216.769693)
			(xy 117.991621 -216.802924) (xy 118.027873 -216.841995) (xy 118.057897 -216.886032) (xy 118.081023 -216.934053)
			(xy 118.096733 -216.984983) (xy 118.104676 -217.037687) (xy 118.105174 -217.064336) (xy 118.104676 -217.090985)
			(xy 118.096733 -217.143689) (xy 118.081023 -217.194619) (xy 118.057897 -217.24264) (xy 118.027873 -217.286677)
			(xy 117.991621 -217.325748) (xy 117.94995 -217.358979) (xy 117.903792 -217.385628) (xy 117.854178 -217.4051)
			(xy 117.802216 -217.41696) (xy 117.749066 -217.420944) (xy 117.695916 -217.41696) (xy 117.643954 -217.4051)
			(xy 117.59434 -217.385628) (xy 117.548182 -217.358979) (xy 117.506511 -217.325748) (xy 117.470259 -217.286677)
			(xy 117.440235 -217.24264) (xy 117.417109 -217.194619) (xy 117.401399 -217.143689) (xy 117.393456 -217.090985)
			(xy 117.164296 -217.090985) (xy 117.158695 -217.13355) (xy 117.146708 -217.178383) (xy 117.138196 -217.199972)
			(xy 117.128798 -217.223086) (xy 117.301518 -217.522044) (xy 117.326156 -217.525346) (xy 117.351494 -217.529193)
			(xy 117.400796 -217.543184) (xy 117.447585 -217.564096) (xy 117.490895 -217.591496) (xy 117.529831 -217.624818)
			(xy 117.563592 -217.663376) (xy 117.591479 -217.706373) (xy 117.612918 -217.752922) (xy 117.627466 -217.802063)
			(xy 117.634822 -217.852782) (xy 117.635274 -217.878406) (xy 117.634776 -217.905055) (xy 117.626833 -217.957759)
			(xy 117.611123 -218.008689) (xy 117.587997 -218.05671) (xy 117.557973 -218.100747) (xy 117.521721 -218.139818)
			(xy 117.48005 -218.173049) (xy 117.433892 -218.199698) (xy 117.384278 -218.21917) (xy 117.332316 -218.23103)
			(xy 117.279166 -218.235014) (xy 117.226016 -218.23103) (xy 117.174054 -218.21917) (xy 117.12444 -218.199698)
			(xy 117.078282 -218.173049) (xy 117.036611 -218.139818) (xy 117.000359 -218.100747) (xy 116.970335 -218.05671)
			(xy 116.947209 -218.008689) (xy 116.931499 -217.957759) (xy 116.923556 -217.905055) (xy 116.923058 -217.878406)
			(xy 116.923432 -217.855161) (xy 116.929477 -217.809066) (xy 116.941465 -217.764148) (xy 116.949982 -217.742516)
			(xy 116.959634 -217.719402) (xy 116.787168 -217.420698) (xy 116.762276 -217.417396) (xy 116.736918 -217.413592)
			(xy 116.687579 -217.399633) (xy 116.640752 -217.378743) (xy 116.597404 -217.351354) (xy 116.558431 -217.318033)
			(xy 116.524638 -217.279467) (xy 116.496725 -217.236455) (xy 116.475268 -217.189885) (xy 116.46071 -217.140719)
			(xy 116.453353 -217.089974) (xy 116.452904 -217.064336) (xy 116.225574 -217.064336) (xy 116.225076 -217.090985)
			(xy 116.217133 -217.143689) (xy 116.201423 -217.194619) (xy 116.178297 -217.24264) (xy 116.148273 -217.286677)
			(xy 116.112021 -217.325748) (xy 116.07035 -217.358979) (xy 116.024192 -217.385628) (xy 115.974578 -217.4051)
			(xy 115.922616 -217.41696) (xy 115.869466 -217.420944) (xy 115.816316 -217.41696) (xy 115.764354 -217.4051)
			(xy 115.71474 -217.385628) (xy 115.668582 -217.358979) (xy 115.626911 -217.325748) (xy 115.590659 -217.286677)
			(xy 115.560635 -217.24264) (xy 115.537509 -217.194619) (xy 115.521799 -217.143689) (xy 115.513856 -217.090985)
			(xy 115.284696 -217.090985) (xy 115.279095 -217.13355) (xy 115.267108 -217.178383) (xy 115.258596 -217.199972)
			(xy 115.249198 -217.223086) (xy 115.421918 -217.522044) (xy 115.446556 -217.525346) (xy 115.471894 -217.529193)
			(xy 115.521196 -217.543184) (xy 115.567985 -217.564096) (xy 115.611295 -217.591496) (xy 115.650231 -217.624818)
			(xy 115.683992 -217.663376) (xy 115.711879 -217.706373) (xy 115.733318 -217.752922) (xy 115.747866 -217.802063)
			(xy 115.755222 -217.852782) (xy 115.755674 -217.878406) (xy 115.755176 -217.905055) (xy 115.747233 -217.957759)
			(xy 115.731523 -218.008689) (xy 115.708397 -218.05671) (xy 115.678373 -218.100747) (xy 115.642121 -218.139818)
			(xy 115.60045 -218.173049) (xy 115.554292 -218.199698) (xy 115.504678 -218.21917) (xy 115.452716 -218.23103)
			(xy 115.399566 -218.235014) (xy 115.346416 -218.23103) (xy 115.294454 -218.21917) (xy 115.24484 -218.199698)
			(xy 115.198682 -218.173049) (xy 115.157011 -218.139818) (xy 115.120759 -218.100747) (xy 115.090735 -218.05671)
			(xy 115.067609 -218.008689) (xy 115.051899 -217.957759) (xy 115.043956 -217.905055) (xy 115.043458 -217.878406)
			(xy 115.043832 -217.855161) (xy 115.049877 -217.809066) (xy 115.061865 -217.764148) (xy 115.070382 -217.742516)
			(xy 115.080034 -217.719402) (xy 114.907568 -217.420698) (xy 114.882676 -217.417396) (xy 114.857318 -217.413592)
			(xy 114.807979 -217.399633) (xy 114.761152 -217.378743) (xy 114.717804 -217.351354) (xy 114.678831 -217.318033)
			(xy 114.645038 -217.279467) (xy 114.617125 -217.236455) (xy 114.595668 -217.189885) (xy 114.58111 -217.140719)
			(xy 114.573753 -217.089974) (xy 114.573304 -217.064336) (xy 114.345974 -217.064336) (xy 114.345476 -217.090985)
			(xy 114.337533 -217.143689) (xy 114.321823 -217.194619) (xy 114.298697 -217.24264) (xy 114.268673 -217.286677)
			(xy 114.232421 -217.325748) (xy 114.19075 -217.358979) (xy 114.144592 -217.385628) (xy 114.094978 -217.4051)
			(xy 114.043016 -217.41696) (xy 113.989866 -217.420944) (xy 113.936716 -217.41696) (xy 113.884754 -217.4051)
			(xy 113.83514 -217.385628) (xy 113.788982 -217.358979) (xy 113.747311 -217.325748) (xy 113.711059 -217.286677)
			(xy 113.681035 -217.24264) (xy 113.657909 -217.194619) (xy 113.642199 -217.143689) (xy 113.634256 -217.090985)
			(xy 113.405096 -217.090985) (xy 113.399495 -217.13355) (xy 113.387508 -217.178383) (xy 113.378996 -217.199972)
			(xy 113.369598 -217.223086) (xy 113.542318 -217.522044) (xy 113.566956 -217.525346) (xy 113.592294 -217.529193)
			(xy 113.641596 -217.543184) (xy 113.688385 -217.564096) (xy 113.731695 -217.591496) (xy 113.770631 -217.624818)
			(xy 113.804392 -217.663376) (xy 113.832279 -217.706373) (xy 113.853718 -217.752922) (xy 113.868266 -217.802063)
			(xy 113.875622 -217.852782) (xy 113.876074 -217.878406) (xy 113.875576 -217.905055) (xy 113.867633 -217.957759)
			(xy 113.851923 -218.008689) (xy 113.828797 -218.05671) (xy 113.798773 -218.100747) (xy 113.762521 -218.139818)
			(xy 113.72085 -218.173049) (xy 113.674692 -218.199698) (xy 113.625078 -218.21917) (xy 113.573116 -218.23103)
			(xy 113.519966 -218.235014) (xy 113.466816 -218.23103) (xy 113.414854 -218.21917) (xy 113.36524 -218.199698)
			(xy 113.319082 -218.173049) (xy 113.277411 -218.139818) (xy 113.241159 -218.100747) (xy 113.211135 -218.05671)
			(xy 113.188009 -218.008689) (xy 113.172299 -217.957759) (xy 113.164356 -217.905055) (xy 113.163858 -217.878406)
			(xy 113.164232 -217.855161) (xy 113.170277 -217.809066) (xy 113.182265 -217.764148) (xy 113.190782 -217.742516)
			(xy 113.200434 -217.719402) (xy 113.027968 -217.420698) (xy 113.003076 -217.417396) (xy 112.977718 -217.413592)
			(xy 112.928379 -217.399633) (xy 112.881552 -217.378743) (xy 112.838204 -217.351354) (xy 112.799231 -217.318033)
			(xy 112.765438 -217.279467) (xy 112.737525 -217.236455) (xy 112.716068 -217.189885) (xy 112.70151 -217.140719)
			(xy 112.694153 -217.089974) (xy 112.693704 -217.064336) (xy 112.466374 -217.064336) (xy 112.465876 -217.090985)
			(xy 112.457933 -217.143689) (xy 112.442223 -217.194619) (xy 112.419097 -217.24264) (xy 112.389073 -217.286677)
			(xy 112.352821 -217.325748) (xy 112.31115 -217.358979) (xy 112.264992 -217.385628) (xy 112.215378 -217.4051)
			(xy 112.163416 -217.41696) (xy 112.110266 -217.420944) (xy 112.057116 -217.41696) (xy 112.005154 -217.4051)
			(xy 111.95554 -217.385628) (xy 111.909382 -217.358979) (xy 111.867711 -217.325748) (xy 111.831459 -217.286677)
			(xy 111.801435 -217.24264) (xy 111.778309 -217.194619) (xy 111.762599 -217.143689) (xy 111.754656 -217.090985)
			(xy 111.525924 -217.090985) (xy 111.518745 -217.140689) (xy 111.504221 -217.18984) (xy 111.482797 -217.236401)
			(xy 111.454919 -217.279408) (xy 111.421161 -217.317973) (xy 111.382222 -217.351298) (xy 111.338907 -217.378696)
			(xy 111.29211 -217.399598) (xy 111.2428 -217.413574) (xy 111.217456 -217.417396) (xy 111.192564 -217.420698)
			(xy 111.020098 -217.719402) (xy 111.02975 -217.742516) (xy 111.038267 -217.764148) (xy 111.050254 -217.809066)
			(xy 111.056299 -217.855161) (xy 111.056674 -217.878406) (xy 111.056176 -217.905055) (xy 111.284502 -217.905055)
			(xy 111.284502 -217.851757) (xy 111.292445 -217.799053) (xy 111.308155 -217.748123) (xy 111.331281 -217.700102)
			(xy 111.361305 -217.656065) (xy 111.397557 -217.616994) (xy 111.439228 -217.583763) (xy 111.485386 -217.557114)
			(xy 111.535 -217.537642) (xy 111.586962 -217.525782) (xy 111.640112 -217.521799) (xy 111.693262 -217.525782)
			(xy 111.745224 -217.537642) (xy 111.794838 -217.557114) (xy 111.840996 -217.583763) (xy 111.882667 -217.616994)
			(xy 111.918919 -217.656065) (xy 111.948943 -217.700102) (xy 111.972069 -217.748123) (xy 111.987779 -217.799053)
			(xy 111.995722 -217.851757) (xy 111.99622 -217.878406) (xy 111.995722 -217.905055) (xy 111.987779 -217.957759)
			(xy 111.972069 -218.008689) (xy 111.948943 -218.05671) (xy 111.918919 -218.100747) (xy 111.882667 -218.139818)
			(xy 111.840996 -218.173049) (xy 111.794838 -218.199698) (xy 111.745224 -218.21917) (xy 111.693262 -218.23103)
			(xy 111.640112 -218.235014) (xy 111.586962 -218.23103) (xy 111.535 -218.21917) (xy 111.485386 -218.199698)
			(xy 111.439228 -218.173049) (xy 111.397557 -218.139818) (xy 111.361305 -218.100747) (xy 111.331281 -218.05671)
			(xy 111.308155 -218.008689) (xy 111.292445 -217.957759) (xy 111.284502 -217.905055) (xy 111.056176 -217.905055)
			(xy 111.048233 -217.957759) (xy 111.032523 -218.008689) (xy 111.009397 -218.05671) (xy 110.979373 -218.100747)
			(xy 110.943121 -218.139818) (xy 110.90145 -218.173049) (xy 110.855292 -218.199698) (xy 110.805678 -218.21917)
			(xy 110.753716 -218.23103) (xy 110.700566 -218.235014) (xy 110.647416 -218.23103) (xy 110.595454 -218.21917)
			(xy 110.54584 -218.199698) (xy 110.499682 -218.173049) (xy 110.458011 -218.139818) (xy 110.421759 -218.100747)
			(xy 110.391735 -218.05671) (xy 110.368609 -218.008689) (xy 110.352899 -217.957759) (xy 110.344956 -217.905055)
			(xy 110.344458 -217.878406) (xy 110.116874 -217.878406) (xy 110.116497 -217.901609) (xy 110.110446 -217.94762)
			(xy 110.098461 -217.992452) (xy 110.08995 -218.014042) (xy 110.080552 -218.037156) (xy 110.253018 -218.33586)
			(xy 110.277656 -218.339162) (xy 110.302997 -218.342993) (xy 110.3523 -218.356986) (xy 110.39909 -218.377898)
			(xy 110.4424 -218.4053) (xy 110.481337 -218.438624) (xy 110.515098 -218.477184) (xy 110.542985 -218.520183)
			(xy 110.564422 -218.566734) (xy 110.578969 -218.615877) (xy 110.586323 -218.666597) (xy 110.586774 -218.692222)
			(xy 110.586281 -218.718617) (xy 110.81511 -218.718617) (xy 110.81511 -218.665319) (xy 110.823053 -218.612615)
			(xy 110.838763 -218.561685) (xy 110.861889 -218.513664) (xy 110.891913 -218.469627) (xy 110.928165 -218.430556)
			(xy 110.969836 -218.397325) (xy 111.015994 -218.370676) (xy 111.065608 -218.351204) (xy 111.11757 -218.339344)
			(xy 111.17072 -218.335361) (xy 111.22387 -218.339344) (xy 111.275832 -218.351204) (xy 111.325446 -218.370676)
			(xy 111.371604 -218.397325) (xy 111.413275 -218.430556) (xy 111.449527 -218.469627) (xy 111.479551 -218.513664)
			(xy 111.502677 -218.561685) (xy 111.518387 -218.612615) (xy 111.52633 -218.665319) (xy 111.526828 -218.691968)
			(xy 111.526823 -218.692222) (xy 111.753904 -218.692222) (xy 111.7543 -218.666591) (xy 111.761634 -218.615857)
			(xy 111.776168 -218.5667) (xy 111.797602 -218.520135) (xy 111.825493 -218.477125) (xy 111.859263 -218.438559)
			(xy 111.898214 -218.405236) (xy 111.941543 -218.377843) (xy 111.988352 -218.356946) (xy 112.037673 -218.342979)
			(xy 112.063022 -218.339162) (xy 112.08766 -218.33586) (xy 112.260126 -218.036902) (xy 112.250728 -218.013788)
			(xy 112.242298 -217.992267) (xy 112.230415 -217.9476) (xy 112.224426 -217.90177) (xy 112.224058 -217.87866)
			(xy 112.224058 -217.878406) (xy 112.224556 -217.851757) (xy 112.232499 -217.799053) (xy 112.248209 -217.748123)
			(xy 112.271335 -217.700102) (xy 112.301359 -217.656065) (xy 112.337611 -217.616994) (xy 112.379282 -217.583763)
			(xy 112.42544 -217.557114) (xy 112.475054 -217.537642) (xy 112.527016 -217.525782) (xy 112.580166 -217.521799)
			(xy 112.633316 -217.525782) (xy 112.685278 -217.537642) (xy 112.734892 -217.557114) (xy 112.78105 -217.583763)
			(xy 112.822721 -217.616994) (xy 112.858973 -217.656065) (xy 112.888997 -217.700102) (xy 112.912123 -217.748123)
			(xy 112.927833 -217.799053) (xy 112.935776 -217.851757) (xy 112.936274 -217.878406) (xy 112.93586 -217.904057)
			(xy 112.928498 -217.954829) (xy 112.913925 -218.004019) (xy 112.892445 -218.050609) (xy 112.864501 -218.093634)
			(xy 112.830673 -218.132203) (xy 112.791659 -218.165519) (xy 112.748269 -218.192892) (xy 112.7014 -218.213755)
			(xy 112.652022 -218.227677) (xy 112.626648 -218.231466) (xy 112.601756 -218.234768) (xy 112.429544 -218.533218)
			(xy 112.439196 -218.556332) (xy 112.44772 -218.577961) (xy 112.459704 -218.62288) (xy 112.465746 -218.668977)
			(xy 112.46612 -218.692222) (xy 112.465622 -218.718871) (xy 112.694202 -218.718871) (xy 112.694202 -218.665573)
			(xy 112.702145 -218.612869) (xy 112.717855 -218.561939) (xy 112.740981 -218.513918) (xy 112.771005 -218.469881)
			(xy 112.807257 -218.43081) (xy 112.848928 -218.397579) (xy 112.895086 -218.37093) (xy 112.9447 -218.351458)
			(xy 112.996662 -218.339598) (xy 113.049812 -218.335615) (xy 113.102962 -218.339598) (xy 113.154924 -218.351458)
			(xy 113.204538 -218.37093) (xy 113.250696 -218.397579) (xy 113.292367 -218.43081) (xy 113.328619 -218.469881)
			(xy 113.358643 -218.513918) (xy 113.381769 -218.561939) (xy 113.397479 -218.612869) (xy 113.405422 -218.665573)
			(xy 113.40592 -218.692222) (xy 113.633758 -218.692222) (xy 113.634194 -218.666593) (xy 113.641527 -218.615863)
			(xy 113.656059 -218.566708) (xy 113.677489 -218.520146) (xy 113.705375 -218.477138) (xy 113.739141 -218.438573)
			(xy 113.778087 -218.405248) (xy 113.82141 -218.377853) (xy 113.868213 -218.356954) (xy 113.91753 -218.342982)
			(xy 113.942876 -218.339162) (xy 113.967514 -218.33586) (xy 114.13998 -218.037156) (xy 114.130582 -218.014042)
			(xy 114.122078 -217.992451) (xy 114.110107 -217.947616) (xy 114.10405 -217.901608) (xy 114.103658 -217.878406)
			(xy 114.104156 -217.851757) (xy 114.112099 -217.799053) (xy 114.127809 -217.748123) (xy 114.150935 -217.700102)
			(xy 114.180959 -217.656065) (xy 114.217211 -217.616994) (xy 114.258882 -217.583763) (xy 114.30504 -217.557114)
			(xy 114.354654 -217.537642) (xy 114.406616 -217.525782) (xy 114.459766 -217.521799) (xy 114.512916 -217.525782)
			(xy 114.564878 -217.537642) (xy 114.614492 -217.557114) (xy 114.66065 -217.583763) (xy 114.702321 -217.616994)
			(xy 114.738573 -217.656065) (xy 114.768597 -217.700102) (xy 114.791723 -217.748123) (xy 114.807433 -217.799053)
			(xy 114.815376 -217.851757) (xy 114.815874 -217.878406) (xy 114.815402 -217.904045) (xy 114.808059 -217.954793)
			(xy 114.793513 -218.003963) (xy 114.772063 -218.050538) (xy 114.744153 -218.093554) (xy 114.710362 -218.132122)
			(xy 114.671387 -218.165443) (xy 114.628035 -218.192828) (xy 114.581204 -218.213711) (xy 114.53186 -218.22766)
			(xy 114.506502 -218.231466) (xy 114.48161 -218.234768) (xy 114.309398 -218.533218) (xy 114.31905 -218.556332)
			(xy 114.327572 -218.577962) (xy 114.339557 -218.622881) (xy 114.3456 -218.668977) (xy 114.345974 -218.692222)
			(xy 114.345476 -218.718871) (xy 114.574056 -218.718871) (xy 114.574056 -218.665573) (xy 114.581999 -218.612869)
			(xy 114.597709 -218.561939) (xy 114.620835 -218.513918) (xy 114.650859 -218.469881) (xy 114.687111 -218.43081)
			(xy 114.728782 -218.397579) (xy 114.77494 -218.37093) (xy 114.824554 -218.351458) (xy 114.876516 -218.339598)
			(xy 114.929666 -218.335615) (xy 114.982816 -218.339598) (xy 115.034778 -218.351458) (xy 115.084392 -218.37093)
			(xy 115.13055 -218.397579) (xy 115.172221 -218.43081) (xy 115.208473 -218.469881) (xy 115.238497 -218.513918)
			(xy 115.261623 -218.561939) (xy 115.277333 -218.612869) (xy 115.285276 -218.665573) (xy 115.285774 -218.692222)
			(xy 115.513104 -218.692222) (xy 115.5135 -218.666591) (xy 115.520834 -218.615857) (xy 115.535368 -218.5667)
			(xy 115.556802 -218.520135) (xy 115.584693 -218.477125) (xy 115.618463 -218.438559) (xy 115.657414 -218.405236)
			(xy 115.700743 -218.377843) (xy 115.747552 -218.356946) (xy 115.796873 -218.342979) (xy 115.822222 -218.339162)
			(xy 115.84686 -218.33586) (xy 116.019326 -218.036902) (xy 116.009928 -218.013788) (xy 116.001498 -217.992267)
			(xy 115.989615 -217.9476) (xy 115.983626 -217.90177) (xy 115.983258 -217.87866) (xy 115.983258 -217.878406)
			(xy 115.983756 -217.851757) (xy 115.991699 -217.799053) (xy 116.007409 -217.748123) (xy 116.030535 -217.700102)
			(xy 116.060559 -217.656065) (xy 116.096811 -217.616994) (xy 116.138482 -217.583763) (xy 116.18464 -217.557114)
			(xy 116.234254 -217.537642) (xy 116.286216 -217.525782) (xy 116.339366 -217.521799) (xy 116.392516 -217.525782)
			(xy 116.444478 -217.537642) (xy 116.494092 -217.557114) (xy 116.54025 -217.583763) (xy 116.581921 -217.616994)
			(xy 116.618173 -217.656065) (xy 116.648197 -217.700102) (xy 116.671323 -217.748123) (xy 116.687033 -217.799053)
			(xy 116.694976 -217.851757) (xy 116.695474 -217.878406) (xy 116.69506 -217.904057) (xy 116.687698 -217.954829)
			(xy 116.673125 -218.004019) (xy 116.651645 -218.050609) (xy 116.623701 -218.093634) (xy 116.589873 -218.132203)
			(xy 116.550859 -218.165519) (xy 116.507469 -218.192892) (xy 116.4606 -218.213755) (xy 116.411222 -218.227677)
			(xy 116.385848 -218.231466) (xy 116.360956 -218.234768) (xy 116.188744 -218.533218) (xy 116.198396 -218.556332)
			(xy 116.20692 -218.577961) (xy 116.218904 -218.62288) (xy 116.224946 -218.668977) (xy 116.22532 -218.692222)
			(xy 117.392704 -218.692222) (xy 117.3931 -218.666591) (xy 117.400434 -218.615857) (xy 117.414968 -218.5667)
			(xy 117.436402 -218.520135) (xy 117.464293 -218.477125) (xy 117.498063 -218.438559) (xy 117.537014 -218.405236)
			(xy 117.580343 -218.377843) (xy 117.627152 -218.356946) (xy 117.676473 -218.342979) (xy 117.701822 -218.339162)
			(xy 117.72646 -218.33586) (xy 117.898926 -218.036902) (xy 117.889528 -218.013788) (xy 117.881098 -217.992267)
			(xy 117.869215 -217.9476) (xy 117.863226 -217.90177) (xy 117.862858 -217.87866) (xy 117.862858 -217.878406)
			(xy 117.863356 -217.851757) (xy 117.871299 -217.799053) (xy 117.887009 -217.748123) (xy 117.910135 -217.700102)
			(xy 117.940159 -217.656065) (xy 117.976411 -217.616994) (xy 118.018082 -217.583763) (xy 118.06424 -217.557114)
			(xy 118.113854 -217.537642) (xy 118.165816 -217.525782) (xy 118.218966 -217.521799) (xy 118.272116 -217.525782)
			(xy 118.324078 -217.537642) (xy 118.373692 -217.557114) (xy 118.41985 -217.583763) (xy 118.461521 -217.616994)
			(xy 118.497773 -217.656065) (xy 118.527797 -217.700102) (xy 118.550923 -217.748123) (xy 118.566633 -217.799053)
			(xy 118.574576 -217.851757) (xy 118.575074 -217.878406) (xy 118.57466 -217.904057) (xy 118.567298 -217.954829)
			(xy 118.552725 -218.004019) (xy 118.531245 -218.050609) (xy 118.503301 -218.093634) (xy 118.469473 -218.132203)
			(xy 118.430459 -218.165519) (xy 118.387069 -218.192892) (xy 118.3402 -218.213755) (xy 118.290822 -218.227677)
			(xy 118.265448 -218.231466) (xy 118.240556 -218.234768) (xy 118.068344 -218.533218) (xy 118.077996 -218.556332)
			(xy 118.08652 -218.577961) (xy 118.098504 -218.62288) (xy 118.104546 -218.668977) (xy 118.10492 -218.692222)
			(xy 118.104422 -218.718871) (xy 118.096479 -218.771575) (xy 118.080769 -218.822505) (xy 118.057643 -218.870526)
			(xy 118.027619 -218.914563) (xy 117.991367 -218.953634) (xy 117.949696 -218.986865) (xy 117.903538 -219.013514)
			(xy 117.853924 -219.032986) (xy 117.801962 -219.044846) (xy 117.748812 -219.04883) (xy 117.695662 -219.044846)
			(xy 117.6437 -219.032986) (xy 117.594086 -219.013514) (xy 117.547928 -218.986865) (xy 117.506257 -218.953634)
			(xy 117.470005 -218.914563) (xy 117.439981 -218.870526) (xy 117.416855 -218.822505) (xy 117.401145 -218.771575)
			(xy 117.393202 -218.718871) (xy 117.392704 -218.692222) (xy 116.22532 -218.692222) (xy 116.224822 -218.718871)
			(xy 116.216879 -218.771575) (xy 116.201169 -218.822505) (xy 116.178043 -218.870526) (xy 116.148019 -218.914563)
			(xy 116.111767 -218.953634) (xy 116.070096 -218.986865) (xy 116.023938 -219.013514) (xy 115.974324 -219.032986)
			(xy 115.922362 -219.044846) (xy 115.869212 -219.04883) (xy 115.816062 -219.044846) (xy 115.7641 -219.032986)
			(xy 115.714486 -219.013514) (xy 115.668328 -218.986865) (xy 115.626657 -218.953634) (xy 115.590405 -218.914563)
			(xy 115.560381 -218.870526) (xy 115.537255 -218.822505) (xy 115.521545 -218.771575) (xy 115.513602 -218.718871)
			(xy 115.513104 -218.692222) (xy 115.285774 -218.692222) (xy 115.285276 -218.718871) (xy 115.277333 -218.771575)
			(xy 115.261623 -218.822505) (xy 115.238497 -218.870526) (xy 115.208473 -218.914563) (xy 115.172221 -218.953634)
			(xy 115.13055 -218.986865) (xy 115.084392 -219.013514) (xy 115.034778 -219.032986) (xy 114.982816 -219.044846)
			(xy 114.929666 -219.04883) (xy 114.876516 -219.044846) (xy 114.824554 -219.032986) (xy 114.77494 -219.013514)
			(xy 114.728782 -218.986865) (xy 114.687111 -218.953634) (xy 114.650859 -218.914563) (xy 114.620835 -218.870526)
			(xy 114.597709 -218.822505) (xy 114.581999 -218.771575) (xy 114.574056 -218.718871) (xy 114.345476 -218.718871)
			(xy 114.337533 -218.771575) (xy 114.321823 -218.822505) (xy 114.298697 -218.870526) (xy 114.268673 -218.914563)
			(xy 114.232421 -218.953634) (xy 114.19075 -218.986865) (xy 114.144592 -219.013514) (xy 114.094978 -219.032986)
			(xy 114.043016 -219.044846) (xy 113.989866 -219.04883) (xy 113.936716 -219.044846) (xy 113.884754 -219.032986)
			(xy 113.83514 -219.013514) (xy 113.788982 -218.986865) (xy 113.747311 -218.953634) (xy 113.711059 -218.914563)
			(xy 113.681035 -218.870526) (xy 113.657909 -218.822505) (xy 113.642199 -218.771575) (xy 113.634256 -218.718871)
			(xy 113.633758 -218.692222) (xy 113.40592 -218.692222) (xy 113.405422 -218.718871) (xy 113.397479 -218.771575)
			(xy 113.381769 -218.822505) (xy 113.358643 -218.870526) (xy 113.328619 -218.914563) (xy 113.292367 -218.953634)
			(xy 113.250696 -218.986865) (xy 113.204538 -219.013514) (xy 113.154924 -219.032986) (xy 113.102962 -219.044846)
			(xy 113.049812 -219.04883) (xy 112.996662 -219.044846) (xy 112.9447 -219.032986) (xy 112.895086 -219.013514)
			(xy 112.848928 -218.986865) (xy 112.807257 -218.953634) (xy 112.771005 -218.914563) (xy 112.740981 -218.870526)
			(xy 112.717855 -218.822505) (xy 112.702145 -218.771575) (xy 112.694202 -218.718871) (xy 112.465622 -218.718871)
			(xy 112.457679 -218.771575) (xy 112.441969 -218.822505) (xy 112.418843 -218.870526) (xy 112.388819 -218.914563)
			(xy 112.352567 -218.953634) (xy 112.310896 -218.986865) (xy 112.264738 -219.013514) (xy 112.215124 -219.032986)
			(xy 112.163162 -219.044846) (xy 112.110012 -219.04883) (xy 112.056862 -219.044846) (xy 112.0049 -219.032986)
			(xy 111.955286 -219.013514) (xy 111.909128 -218.986865) (xy 111.867457 -218.953634) (xy 111.831205 -218.914563)
			(xy 111.801181 -218.870526) (xy 111.778055 -218.822505) (xy 111.762345 -218.771575) (xy 111.754402 -218.718871)
			(xy 111.753904 -218.692222) (xy 111.526823 -218.692222) (xy 111.52633 -218.718617) (xy 111.518387 -218.771321)
			(xy 111.502677 -218.822251) (xy 111.479551 -218.870272) (xy 111.449527 -218.914309) (xy 111.413275 -218.95338)
			(xy 111.371604 -218.986611) (xy 111.325446 -219.01326) (xy 111.275832 -219.032732) (xy 111.22387 -219.044592)
			(xy 111.17072 -219.048576) (xy 111.11757 -219.044592) (xy 111.065608 -219.032732) (xy 111.015994 -219.01326)
			(xy 110.969836 -218.986611) (xy 110.928165 -218.95338) (xy 110.891913 -218.914309) (xy 110.861889 -218.870272)
			(xy 110.838763 -218.822251) (xy 110.823053 -218.771321) (xy 110.81511 -218.718617) (xy 110.586281 -218.718617)
			(xy 110.586276 -218.718871) (xy 110.578333 -218.771575) (xy 110.562623 -218.822505) (xy 110.539497 -218.870526)
			(xy 110.509473 -218.914563) (xy 110.473221 -218.953634) (xy 110.43155 -218.986865) (xy 110.385392 -219.013514)
			(xy 110.335778 -219.032986) (xy 110.283816 -219.044846) (xy 110.230666 -219.04883) (xy 110.177516 -219.044846)
			(xy 110.125554 -219.032986) (xy 110.07594 -219.013514) (xy 110.029782 -218.986865) (xy 109.988111 -218.953634)
			(xy 109.951859 -218.914563) (xy 109.921835 -218.870526) (xy 109.898709 -218.822505) (xy 109.882999 -218.771575)
			(xy 109.875056 -218.718871) (xy 109.874558 -218.692222) (xy 109.874937 -218.668977) (xy 109.88098 -218.622882)
			(xy 109.892966 -218.577964) (xy 109.901482 -218.556332) (xy 109.911134 -218.533218) (xy 109.738668 -218.234768)
			(xy 109.71403 -218.231466) (xy 109.688674 -218.227649) (xy 109.639333 -218.213695) (xy 109.592503 -218.192809)
			(xy 109.549153 -218.165423) (xy 109.510178 -218.132104) (xy 109.476385 -218.093539) (xy 109.448472 -218.050527)
			(xy 109.427015 -218.003956) (xy 109.412459 -217.95479) (xy 109.405105 -217.904044) (xy 109.404658 -217.878406)
			(xy 109.177074 -217.878406) (xy 109.176576 -217.905055) (xy 109.168633 -217.957759) (xy 109.152923 -218.008689)
			(xy 109.129797 -218.05671) (xy 109.099773 -218.100747) (xy 109.063521 -218.139818) (xy 109.02185 -218.173049)
			(xy 108.975692 -218.199698) (xy 108.926078 -218.21917) (xy 108.874116 -218.23103) (xy 108.820966 -218.235014)
			(xy 108.767816 -218.23103) (xy 108.715854 -218.21917) (xy 108.66624 -218.199698) (xy 108.620082 -218.173049)
			(xy 108.578411 -218.139818) (xy 108.542159 -218.100747) (xy 108.512135 -218.05671) (xy 108.489009 -218.008689)
			(xy 108.473299 -217.957759) (xy 108.465356 -217.905055) (xy 108.464858 -217.878406) (xy 108.237274 -217.878406)
			(xy 108.236909 -217.901651) (xy 108.230861 -217.947747) (xy 108.218869 -217.992664) (xy 108.21035 -218.014296)
			(xy 108.200698 -218.03741) (xy 108.373164 -218.33586) (xy 108.397802 -218.339162) (xy 108.423136 -218.343036)
			(xy 108.472439 -218.357021) (xy 108.519229 -218.377927) (xy 108.56254 -218.405322) (xy 108.601478 -218.438642)
			(xy 108.63524 -218.477197) (xy 108.663128 -218.520192) (xy 108.684567 -218.566741) (xy 108.699114 -218.615881)
			(xy 108.706469 -218.666598) (xy 108.70692 -218.692222) (xy 108.706422 -218.718871) (xy 108.935002 -218.718871)
			(xy 108.935002 -218.665573) (xy 108.942945 -218.612869) (xy 108.958655 -218.561939) (xy 108.981781 -218.513918)
			(xy 109.011805 -218.469881) (xy 109.048057 -218.43081) (xy 109.089728 -218.397579) (xy 109.135886 -218.37093)
			(xy 109.1855 -218.351458) (xy 109.237462 -218.339598) (xy 109.290612 -218.335615) (xy 109.343762 -218.339598)
			(xy 109.395724 -218.351458) (xy 109.445338 -218.37093) (xy 109.491496 -218.397579) (xy 109.533167 -218.43081)
			(xy 109.569419 -218.469881) (xy 109.599443 -218.513918) (xy 109.622569 -218.561939) (xy 109.638279 -218.612869)
			(xy 109.646222 -218.665573) (xy 109.64672 -218.692222) (xy 109.646222 -218.718871) (xy 109.638279 -218.771575)
			(xy 109.622569 -218.822505) (xy 109.599443 -218.870526) (xy 109.569419 -218.914563) (xy 109.533167 -218.953634)
			(xy 109.491496 -218.986865) (xy 109.445338 -219.013514) (xy 109.395724 -219.032986) (xy 109.343762 -219.044846)
			(xy 109.290612 -219.04883) (xy 109.237462 -219.044846) (xy 109.1855 -219.032986) (xy 109.135886 -219.013514)
			(xy 109.089728 -218.986865) (xy 109.048057 -218.953634) (xy 109.011805 -218.914563) (xy 108.981781 -218.870526)
			(xy 108.958655 -218.822505) (xy 108.942945 -218.771575) (xy 108.935002 -218.718871) (xy 108.706422 -218.718871)
			(xy 108.698479 -218.771575) (xy 108.682769 -218.822505) (xy 108.659643 -218.870526) (xy 108.629619 -218.914563)
			(xy 108.593367 -218.953634) (xy 108.551696 -218.986865) (xy 108.505538 -219.013514) (xy 108.455924 -219.032986)
			(xy 108.403962 -219.044846) (xy 108.350812 -219.04883) (xy 108.297662 -219.044846) (xy 108.2457 -219.032986)
			(xy 108.196086 -219.013514) (xy 108.149928 -218.986865) (xy 108.108257 -218.953634) (xy 108.072005 -218.914563)
			(xy 108.041981 -218.870526) (xy 108.018855 -218.822505) (xy 108.003145 -218.771575) (xy 107.995202 -218.718871)
			(xy 107.994704 -218.692222) (xy 107.99508 -218.668977) (xy 108.001124 -218.622882) (xy 108.013112 -218.577964)
			(xy 108.021628 -218.556332) (xy 108.03128 -218.533218) (xy 107.858814 -218.234768) (xy 107.834176 -218.231466)
			(xy 107.808827 -218.227679) (xy 107.759518 -218.213687) (xy 107.712724 -218.192773) (xy 107.66941 -218.165368)
			(xy 107.630471 -218.132039) (xy 107.59671 -218.093473) (xy 107.568825 -218.050468) (xy 107.547391 -218.003909)
			(xy 107.53285 -217.95476) (xy 107.525504 -217.904034) (xy 107.525058 -217.878406) (xy 107.297474 -217.878406)
			(xy 107.296976 -217.905055) (xy 107.289033 -217.957759) (xy 107.273323 -218.008689) (xy 107.250197 -218.05671)
			(xy 107.220173 -218.100747) (xy 107.183921 -218.139818) (xy 107.14225 -218.173049) (xy 107.096092 -218.199698)
			(xy 107.046478 -218.21917) (xy 106.994516 -218.23103) (xy 106.941366 -218.235014) (xy 106.888216 -218.23103)
			(xy 106.836254 -218.21917) (xy 106.78664 -218.199698) (xy 106.740482 -218.173049) (xy 106.698811 -218.139818)
			(xy 106.662559 -218.100747) (xy 106.632535 -218.05671) (xy 106.609409 -218.008689) (xy 106.593699 -217.957759)
			(xy 106.585756 -217.905055) (xy 106.585258 -217.878406) (xy 106.357674 -217.878406) (xy 106.357309 -217.901651)
			(xy 106.351261 -217.947747) (xy 106.339269 -217.992664) (xy 106.33075 -218.014296) (xy 106.321098 -218.03741)
			(xy 106.493564 -218.33586) (xy 106.518202 -218.339162) (xy 106.543536 -218.343036) (xy 106.592839 -218.357021)
			(xy 106.639629 -218.377927) (xy 106.68294 -218.405322) (xy 106.721878 -218.438642) (xy 106.75564 -218.477197)
			(xy 106.783528 -218.520192) (xy 106.804967 -218.566741) (xy 106.819514 -218.615881) (xy 106.826869 -218.666598)
			(xy 106.82732 -218.692222) (xy 106.826822 -218.718871) (xy 107.055402 -218.718871) (xy 107.055402 -218.665573)
			(xy 107.063345 -218.612869) (xy 107.079055 -218.561939) (xy 107.102181 -218.513918) (xy 107.132205 -218.469881)
			(xy 107.168457 -218.43081) (xy 107.210128 -218.397579) (xy 107.256286 -218.37093) (xy 107.3059 -218.351458)
			(xy 107.357862 -218.339598) (xy 107.411012 -218.335615) (xy 107.464162 -218.339598) (xy 107.516124 -218.351458)
			(xy 107.565738 -218.37093) (xy 107.611896 -218.397579) (xy 107.653567 -218.43081) (xy 107.689819 -218.469881)
			(xy 107.719843 -218.513918) (xy 107.742969 -218.561939) (xy 107.758679 -218.612869) (xy 107.766622 -218.665573)
			(xy 107.76712 -218.692222) (xy 107.766622 -218.718871) (xy 107.758679 -218.771575) (xy 107.742969 -218.822505)
			(xy 107.719843 -218.870526) (xy 107.689819 -218.914563) (xy 107.653567 -218.953634) (xy 107.611896 -218.986865)
			(xy 107.565738 -219.013514) (xy 107.516124 -219.032986) (xy 107.464162 -219.044846) (xy 107.411012 -219.04883)
			(xy 107.357862 -219.044846) (xy 107.3059 -219.032986) (xy 107.256286 -219.013514) (xy 107.210128 -218.986865)
			(xy 107.168457 -218.953634) (xy 107.132205 -218.914563) (xy 107.102181 -218.870526) (xy 107.079055 -218.822505)
			(xy 107.063345 -218.771575) (xy 107.055402 -218.718871) (xy 106.826822 -218.718871) (xy 106.818879 -218.771575)
			(xy 106.803169 -218.822505) (xy 106.780043 -218.870526) (xy 106.750019 -218.914563) (xy 106.713767 -218.953634)
			(xy 106.672096 -218.986865) (xy 106.625938 -219.013514) (xy 106.576324 -219.032986) (xy 106.524362 -219.044846)
			(xy 106.471212 -219.04883) (xy 106.418062 -219.044846) (xy 106.3661 -219.032986) (xy 106.316486 -219.013514)
			(xy 106.270328 -218.986865) (xy 106.228657 -218.953634) (xy 106.192405 -218.914563) (xy 106.162381 -218.870526)
			(xy 106.139255 -218.822505) (xy 106.123545 -218.771575) (xy 106.115602 -218.718871) (xy 106.115104 -218.692222)
			(xy 106.11548 -218.668977) (xy 106.121524 -218.622882) (xy 106.133512 -218.577964) (xy 106.142028 -218.556332)
			(xy 106.15168 -218.533218) (xy 105.979214 -218.234768) (xy 105.954576 -218.231466) (xy 105.929227 -218.227679)
			(xy 105.879918 -218.213687) (xy 105.833124 -218.192773) (xy 105.78981 -218.165368) (xy 105.750871 -218.132039)
			(xy 105.71711 -218.093473) (xy 105.689225 -218.050468) (xy 105.667791 -218.003909) (xy 105.65325 -217.95476)
			(xy 105.645904 -217.904034) (xy 105.645458 -217.878406) (xy 105.534968 -217.878406) (xy 105.534968 -218.33332)
			(xy 105.57891 -218.339416) (xy 105.605554 -218.343483) (xy 105.657285 -218.358603) (xy 105.706145 -218.381351)
			(xy 105.751017 -218.411205) (xy 105.790875 -218.447482) (xy 105.824808 -218.489355) (xy 105.85204 -218.535865)
			(xy 105.871948 -218.585949) (xy 105.884078 -218.638461) (xy 105.888152 -218.692203) (xy 105.884077 -218.745944)
			(xy 105.871947 -218.798457) (xy 105.852037 -218.848541) (xy 105.824804 -218.89505) (xy 105.790871 -218.936922)
			(xy 105.751012 -218.973199) (xy 105.70614 -219.003052) (xy 105.657279 -219.025799) (xy 105.605548 -219.040919)
			(xy 105.57891 -219.045028) (xy 105.534968 -219.051124) (xy 105.534968 -219.532687) (xy 105.645956 -219.532687)
			(xy 105.645956 -219.479389) (xy 105.653899 -219.426685) (xy 105.669609 -219.375755) (xy 105.692735 -219.327734)
			(xy 105.722759 -219.283697) (xy 105.759011 -219.244626) (xy 105.800682 -219.211395) (xy 105.84684 -219.184746)
			(xy 105.896454 -219.165274) (xy 105.948416 -219.153414) (xy 106.001566 -219.149431) (xy 106.054716 -219.153414)
			(xy 106.106678 -219.165274) (xy 106.156292 -219.184746) (xy 106.20245 -219.211395) (xy 106.244121 -219.244626)
			(xy 106.280373 -219.283697) (xy 106.310397 -219.327734) (xy 106.333523 -219.375755) (xy 106.349233 -219.426685)
			(xy 106.357176 -219.479389) (xy 106.357674 -219.506038) (xy 106.357176 -219.532687) (xy 106.585756 -219.532687)
			(xy 106.585756 -219.479389) (xy 106.593699 -219.426685) (xy 106.609409 -219.375755) (xy 106.632535 -219.327734)
			(xy 106.662559 -219.283697) (xy 106.698811 -219.244626) (xy 106.740482 -219.211395) (xy 106.78664 -219.184746)
			(xy 106.836254 -219.165274) (xy 106.888216 -219.153414) (xy 106.941366 -219.149431) (xy 106.994516 -219.153414)
			(xy 107.046478 -219.165274) (xy 107.096092 -219.184746) (xy 107.14225 -219.211395) (xy 107.183921 -219.244626)
			(xy 107.220173 -219.283697) (xy 107.250197 -219.327734) (xy 107.273323 -219.375755) (xy 107.289033 -219.426685)
			(xy 107.296976 -219.479389) (xy 107.297474 -219.506038) (xy 107.296976 -219.532687) (xy 107.525556 -219.532687)
			(xy 107.525556 -219.479389) (xy 107.533499 -219.426685) (xy 107.549209 -219.375755) (xy 107.572335 -219.327734)
			(xy 107.602359 -219.283697) (xy 107.638611 -219.244626) (xy 107.680282 -219.211395) (xy 107.72644 -219.184746)
			(xy 107.776054 -219.165274) (xy 107.828016 -219.153414) (xy 107.881166 -219.149431) (xy 107.934316 -219.153414)
			(xy 107.986278 -219.165274) (xy 108.035892 -219.184746) (xy 108.08205 -219.211395) (xy 108.123721 -219.244626)
			(xy 108.159973 -219.283697) (xy 108.189997 -219.327734) (xy 108.213123 -219.375755) (xy 108.228833 -219.426685)
			(xy 108.236776 -219.479389) (xy 108.237274 -219.506038) (xy 108.236776 -219.532687) (xy 108.465356 -219.532687)
			(xy 108.465356 -219.479389) (xy 108.473299 -219.426685) (xy 108.489009 -219.375755) (xy 108.512135 -219.327734)
			(xy 108.542159 -219.283697) (xy 108.578411 -219.244626) (xy 108.620082 -219.211395) (xy 108.66624 -219.184746)
			(xy 108.715854 -219.165274) (xy 108.767816 -219.153414) (xy 108.820966 -219.149431) (xy 108.874116 -219.153414)
			(xy 108.926078 -219.165274) (xy 108.975692 -219.184746) (xy 109.02185 -219.211395) (xy 109.063521 -219.244626)
			(xy 109.099773 -219.283697) (xy 109.129797 -219.327734) (xy 109.152923 -219.375755) (xy 109.168633 -219.426685)
			(xy 109.176576 -219.479389) (xy 109.177074 -219.506038) (xy 109.176576 -219.532687) (xy 109.405156 -219.532687)
			(xy 109.405156 -219.479389) (xy 109.413099 -219.426685) (xy 109.428809 -219.375755) (xy 109.451935 -219.327734)
			(xy 109.481959 -219.283697) (xy 109.518211 -219.244626) (xy 109.559882 -219.211395) (xy 109.60604 -219.184746)
			(xy 109.655654 -219.165274) (xy 109.707616 -219.153414) (xy 109.760766 -219.149431) (xy 109.813916 -219.153414)
			(xy 109.865878 -219.165274) (xy 109.915492 -219.184746) (xy 109.96165 -219.211395) (xy 110.003321 -219.244626)
			(xy 110.039573 -219.283697) (xy 110.069597 -219.327734) (xy 110.092723 -219.375755) (xy 110.108433 -219.426685)
			(xy 110.116376 -219.479389) (xy 110.116874 -219.506038) (xy 110.116376 -219.532687) (xy 110.344956 -219.532687)
			(xy 110.344956 -219.479389) (xy 110.352899 -219.426685) (xy 110.368609 -219.375755) (xy 110.391735 -219.327734)
			(xy 110.421759 -219.283697) (xy 110.458011 -219.244626) (xy 110.499682 -219.211395) (xy 110.54584 -219.184746)
			(xy 110.595454 -219.165274) (xy 110.647416 -219.153414) (xy 110.700566 -219.149431) (xy 110.753716 -219.153414)
			(xy 110.805678 -219.165274) (xy 110.855292 -219.184746) (xy 110.90145 -219.211395) (xy 110.943121 -219.244626)
			(xy 110.979373 -219.283697) (xy 111.009397 -219.327734) (xy 111.032523 -219.375755) (xy 111.048233 -219.426685)
			(xy 111.056176 -219.479389) (xy 111.056674 -219.506038) (xy 111.056176 -219.532687) (xy 111.284756 -219.532687)
			(xy 111.284756 -219.479389) (xy 111.292699 -219.426685) (xy 111.308409 -219.375755) (xy 111.331535 -219.327734)
			(xy 111.361559 -219.283697) (xy 111.397811 -219.244626) (xy 111.439482 -219.211395) (xy 111.48564 -219.184746)
			(xy 111.535254 -219.165274) (xy 111.587216 -219.153414) (xy 111.640366 -219.149431) (xy 111.693516 -219.153414)
			(xy 111.745478 -219.165274) (xy 111.795092 -219.184746) (xy 111.84125 -219.211395) (xy 111.882921 -219.244626)
			(xy 111.919173 -219.283697) (xy 111.949197 -219.327734) (xy 111.972323 -219.375755) (xy 111.988033 -219.426685)
			(xy 111.995976 -219.479389) (xy 111.996474 -219.506038) (xy 111.995976 -219.532687) (xy 112.224556 -219.532687)
			(xy 112.224556 -219.479389) (xy 112.232499 -219.426685) (xy 112.248209 -219.375755) (xy 112.271335 -219.327734)
			(xy 112.301359 -219.283697) (xy 112.337611 -219.244626) (xy 112.379282 -219.211395) (xy 112.42544 -219.184746)
			(xy 112.475054 -219.165274) (xy 112.527016 -219.153414) (xy 112.580166 -219.149431) (xy 112.633316 -219.153414)
			(xy 112.685278 -219.165274) (xy 112.734892 -219.184746) (xy 112.78105 -219.211395) (xy 112.822721 -219.244626)
			(xy 112.858973 -219.283697) (xy 112.888997 -219.327734) (xy 112.912123 -219.375755) (xy 112.927833 -219.426685)
			(xy 112.935776 -219.479389) (xy 112.936274 -219.506038) (xy 112.935776 -219.532687) (xy 113.164356 -219.532687)
			(xy 113.164356 -219.479389) (xy 113.172299 -219.426685) (xy 113.188009 -219.375755) (xy 113.211135 -219.327734)
			(xy 113.241159 -219.283697) (xy 113.277411 -219.244626) (xy 113.319082 -219.211395) (xy 113.36524 -219.184746)
			(xy 113.414854 -219.165274) (xy 113.466816 -219.153414) (xy 113.519966 -219.149431) (xy 113.573116 -219.153414)
			(xy 113.625078 -219.165274) (xy 113.674692 -219.184746) (xy 113.72085 -219.211395) (xy 113.762521 -219.244626)
			(xy 113.798773 -219.283697) (xy 113.828797 -219.327734) (xy 113.851923 -219.375755) (xy 113.867633 -219.426685)
			(xy 113.875576 -219.479389) (xy 113.876074 -219.506038) (xy 113.875576 -219.532687) (xy 114.104156 -219.532687)
			(xy 114.104156 -219.479389) (xy 114.112099 -219.426685) (xy 114.127809 -219.375755) (xy 114.150935 -219.327734)
			(xy 114.180959 -219.283697) (xy 114.217211 -219.244626) (xy 114.258882 -219.211395) (xy 114.30504 -219.184746)
			(xy 114.354654 -219.165274) (xy 114.406616 -219.153414) (xy 114.459766 -219.149431) (xy 114.512916 -219.153414)
			(xy 114.564878 -219.165274) (xy 114.614492 -219.184746) (xy 114.66065 -219.211395) (xy 114.702321 -219.244626)
			(xy 114.738573 -219.283697) (xy 114.768597 -219.327734) (xy 114.791723 -219.375755) (xy 114.807433 -219.426685)
			(xy 114.815376 -219.479389) (xy 114.815874 -219.506038) (xy 114.815376 -219.532687) (xy 115.043956 -219.532687)
			(xy 115.043956 -219.479389) (xy 115.051899 -219.426685) (xy 115.067609 -219.375755) (xy 115.090735 -219.327734)
			(xy 115.120759 -219.283697) (xy 115.157011 -219.244626) (xy 115.198682 -219.211395) (xy 115.24484 -219.184746)
			(xy 115.294454 -219.165274) (xy 115.346416 -219.153414) (xy 115.399566 -219.149431) (xy 115.452716 -219.153414)
			(xy 115.504678 -219.165274) (xy 115.554292 -219.184746) (xy 115.60045 -219.211395) (xy 115.642121 -219.244626)
			(xy 115.678373 -219.283697) (xy 115.708397 -219.327734) (xy 115.731523 -219.375755) (xy 115.747233 -219.426685)
			(xy 115.755176 -219.479389) (xy 115.755674 -219.506038) (xy 115.755176 -219.532687) (xy 115.983756 -219.532687)
			(xy 115.983756 -219.479389) (xy 115.991699 -219.426685) (xy 116.007409 -219.375755) (xy 116.030535 -219.327734)
			(xy 116.060559 -219.283697) (xy 116.096811 -219.244626) (xy 116.138482 -219.211395) (xy 116.18464 -219.184746)
			(xy 116.234254 -219.165274) (xy 116.286216 -219.153414) (xy 116.339366 -219.149431) (xy 116.392516 -219.153414)
			(xy 116.444478 -219.165274) (xy 116.494092 -219.184746) (xy 116.54025 -219.211395) (xy 116.581921 -219.244626)
			(xy 116.618173 -219.283697) (xy 116.648197 -219.327734) (xy 116.671323 -219.375755) (xy 116.687033 -219.426685)
			(xy 116.694976 -219.479389) (xy 116.695474 -219.506038) (xy 116.694976 -219.532687) (xy 116.923556 -219.532687)
			(xy 116.923556 -219.479389) (xy 116.931499 -219.426685) (xy 116.947209 -219.375755) (xy 116.970335 -219.327734)
			(xy 117.000359 -219.283697) (xy 117.036611 -219.244626) (xy 117.078282 -219.211395) (xy 117.12444 -219.184746)
			(xy 117.174054 -219.165274) (xy 117.226016 -219.153414) (xy 117.279166 -219.149431) (xy 117.332316 -219.153414)
			(xy 117.384278 -219.165274) (xy 117.433892 -219.184746) (xy 117.48005 -219.211395) (xy 117.521721 -219.244626)
			(xy 117.557973 -219.283697) (xy 117.587997 -219.327734) (xy 117.611123 -219.375755) (xy 117.626833 -219.426685)
			(xy 117.634776 -219.479389) (xy 117.635274 -219.506038) (xy 117.634776 -219.532687) (xy 117.863356 -219.532687)
			(xy 117.863356 -219.479389) (xy 117.871299 -219.426685) (xy 117.887009 -219.375755) (xy 117.910135 -219.327734)
			(xy 117.940159 -219.283697) (xy 117.976411 -219.244626) (xy 118.018082 -219.211395) (xy 118.06424 -219.184746)
			(xy 118.113854 -219.165274) (xy 118.165816 -219.153414) (xy 118.218966 -219.149431) (xy 118.272116 -219.153414)
			(xy 118.324078 -219.165274) (xy 118.373692 -219.184746) (xy 118.41985 -219.211395) (xy 118.461521 -219.244626)
			(xy 118.497773 -219.283697) (xy 118.527797 -219.327734) (xy 118.550923 -219.375755) (xy 118.566633 -219.426685)
			(xy 118.574576 -219.479389) (xy 118.575074 -219.506038) (xy 118.574576 -219.532687) (xy 118.566633 -219.585391)
			(xy 118.550923 -219.636321) (xy 118.527797 -219.684342) (xy 118.497773 -219.728379) (xy 118.461521 -219.76745)
			(xy 118.41985 -219.800681) (xy 118.373692 -219.82733) (xy 118.324078 -219.846802) (xy 118.272116 -219.858662)
			(xy 118.218966 -219.862646) (xy 118.165816 -219.858662) (xy 118.113854 -219.846802) (xy 118.06424 -219.82733)
			(xy 118.018082 -219.800681) (xy 117.976411 -219.76745) (xy 117.940159 -219.728379) (xy 117.910135 -219.684342)
			(xy 117.887009 -219.636321) (xy 117.871299 -219.585391) (xy 117.863356 -219.532687) (xy 117.634776 -219.532687)
			(xy 117.626833 -219.585391) (xy 117.611123 -219.636321) (xy 117.587997 -219.684342) (xy 117.557973 -219.728379)
			(xy 117.521721 -219.76745) (xy 117.48005 -219.800681) (xy 117.433892 -219.82733) (xy 117.384278 -219.846802)
			(xy 117.332316 -219.858662) (xy 117.279166 -219.862646) (xy 117.226016 -219.858662) (xy 117.174054 -219.846802)
			(xy 117.12444 -219.82733) (xy 117.078282 -219.800681) (xy 117.036611 -219.76745) (xy 117.000359 -219.728379)
			(xy 116.970335 -219.684342) (xy 116.947209 -219.636321) (xy 116.931499 -219.585391) (xy 116.923556 -219.532687)
			(xy 116.694976 -219.532687) (xy 116.687033 -219.585391) (xy 116.671323 -219.636321) (xy 116.648197 -219.684342)
			(xy 116.618173 -219.728379) (xy 116.581921 -219.76745) (xy 116.54025 -219.800681) (xy 116.494092 -219.82733)
			(xy 116.444478 -219.846802) (xy 116.392516 -219.858662) (xy 116.339366 -219.862646) (xy 116.286216 -219.858662)
			(xy 116.234254 -219.846802) (xy 116.18464 -219.82733) (xy 116.138482 -219.800681) (xy 116.096811 -219.76745)
			(xy 116.060559 -219.728379) (xy 116.030535 -219.684342) (xy 116.007409 -219.636321) (xy 115.991699 -219.585391)
			(xy 115.983756 -219.532687) (xy 115.755176 -219.532687) (xy 115.747233 -219.585391) (xy 115.731523 -219.636321)
			(xy 115.708397 -219.684342) (xy 115.678373 -219.728379) (xy 115.642121 -219.76745) (xy 115.60045 -219.800681)
			(xy 115.554292 -219.82733) (xy 115.504678 -219.846802) (xy 115.452716 -219.858662) (xy 115.399566 -219.862646)
			(xy 115.346416 -219.858662) (xy 115.294454 -219.846802) (xy 115.24484 -219.82733) (xy 115.198682 -219.800681)
			(xy 115.157011 -219.76745) (xy 115.120759 -219.728379) (xy 115.090735 -219.684342) (xy 115.067609 -219.636321)
			(xy 115.051899 -219.585391) (xy 115.043956 -219.532687) (xy 114.815376 -219.532687) (xy 114.807433 -219.585391)
			(xy 114.791723 -219.636321) (xy 114.768597 -219.684342) (xy 114.738573 -219.728379) (xy 114.702321 -219.76745)
			(xy 114.66065 -219.800681) (xy 114.614492 -219.82733) (xy 114.564878 -219.846802) (xy 114.512916 -219.858662)
			(xy 114.459766 -219.862646) (xy 114.406616 -219.858662) (xy 114.354654 -219.846802) (xy 114.30504 -219.82733)
			(xy 114.258882 -219.800681) (xy 114.217211 -219.76745) (xy 114.180959 -219.728379) (xy 114.150935 -219.684342)
			(xy 114.127809 -219.636321) (xy 114.112099 -219.585391) (xy 114.104156 -219.532687) (xy 113.875576 -219.532687)
			(xy 113.867633 -219.585391) (xy 113.851923 -219.636321) (xy 113.828797 -219.684342) (xy 113.798773 -219.728379)
			(xy 113.762521 -219.76745) (xy 113.72085 -219.800681) (xy 113.674692 -219.82733) (xy 113.625078 -219.846802)
			(xy 113.573116 -219.858662) (xy 113.519966 -219.862646) (xy 113.466816 -219.858662) (xy 113.414854 -219.846802)
			(xy 113.36524 -219.82733) (xy 113.319082 -219.800681) (xy 113.277411 -219.76745) (xy 113.241159 -219.728379)
			(xy 113.211135 -219.684342) (xy 113.188009 -219.636321) (xy 113.172299 -219.585391) (xy 113.164356 -219.532687)
			(xy 112.935776 -219.532687) (xy 112.927833 -219.585391) (xy 112.912123 -219.636321) (xy 112.888997 -219.684342)
			(xy 112.858973 -219.728379) (xy 112.822721 -219.76745) (xy 112.78105 -219.800681) (xy 112.734892 -219.82733)
			(xy 112.685278 -219.846802) (xy 112.633316 -219.858662) (xy 112.580166 -219.862646) (xy 112.527016 -219.858662)
			(xy 112.475054 -219.846802) (xy 112.42544 -219.82733) (xy 112.379282 -219.800681) (xy 112.337611 -219.76745)
			(xy 112.301359 -219.728379) (xy 112.271335 -219.684342) (xy 112.248209 -219.636321) (xy 112.232499 -219.585391)
			(xy 112.224556 -219.532687) (xy 111.995976 -219.532687) (xy 111.988033 -219.585391) (xy 111.972323 -219.636321)
			(xy 111.949197 -219.684342) (xy 111.919173 -219.728379) (xy 111.882921 -219.76745) (xy 111.84125 -219.800681)
			(xy 111.795092 -219.82733) (xy 111.745478 -219.846802) (xy 111.693516 -219.858662) (xy 111.640366 -219.862646)
			(xy 111.587216 -219.858662) (xy 111.535254 -219.846802) (xy 111.48564 -219.82733) (xy 111.439482 -219.800681)
			(xy 111.397811 -219.76745) (xy 111.361559 -219.728379) (xy 111.331535 -219.684342) (xy 111.308409 -219.636321)
			(xy 111.292699 -219.585391) (xy 111.284756 -219.532687) (xy 111.056176 -219.532687) (xy 111.048233 -219.585391)
			(xy 111.032523 -219.636321) (xy 111.009397 -219.684342) (xy 110.979373 -219.728379) (xy 110.943121 -219.76745)
			(xy 110.90145 -219.800681) (xy 110.855292 -219.82733) (xy 110.805678 -219.846802) (xy 110.753716 -219.858662)
			(xy 110.700566 -219.862646) (xy 110.647416 -219.858662) (xy 110.595454 -219.846802) (xy 110.54584 -219.82733)
			(xy 110.499682 -219.800681) (xy 110.458011 -219.76745) (xy 110.421759 -219.728379) (xy 110.391735 -219.684342)
			(xy 110.368609 -219.636321) (xy 110.352899 -219.585391) (xy 110.344956 -219.532687) (xy 110.116376 -219.532687)
			(xy 110.108433 -219.585391) (xy 110.092723 -219.636321) (xy 110.069597 -219.684342) (xy 110.039573 -219.728379)
			(xy 110.003321 -219.76745) (xy 109.96165 -219.800681) (xy 109.915492 -219.82733) (xy 109.865878 -219.846802)
			(xy 109.813916 -219.858662) (xy 109.760766 -219.862646) (xy 109.707616 -219.858662) (xy 109.655654 -219.846802)
			(xy 109.60604 -219.82733) (xy 109.559882 -219.800681) (xy 109.518211 -219.76745) (xy 109.481959 -219.728379)
			(xy 109.451935 -219.684342) (xy 109.428809 -219.636321) (xy 109.413099 -219.585391) (xy 109.405156 -219.532687)
			(xy 109.176576 -219.532687) (xy 109.168633 -219.585391) (xy 109.152923 -219.636321) (xy 109.129797 -219.684342)
			(xy 109.099773 -219.728379) (xy 109.063521 -219.76745) (xy 109.02185 -219.800681) (xy 108.975692 -219.82733)
			(xy 108.926078 -219.846802) (xy 108.874116 -219.858662) (xy 108.820966 -219.862646) (xy 108.767816 -219.858662)
			(xy 108.715854 -219.846802) (xy 108.66624 -219.82733) (xy 108.620082 -219.800681) (xy 108.578411 -219.76745)
			(xy 108.542159 -219.728379) (xy 108.512135 -219.684342) (xy 108.489009 -219.636321) (xy 108.473299 -219.585391)
			(xy 108.465356 -219.532687) (xy 108.236776 -219.532687) (xy 108.228833 -219.585391) (xy 108.213123 -219.636321)
			(xy 108.189997 -219.684342) (xy 108.159973 -219.728379) (xy 108.123721 -219.76745) (xy 108.08205 -219.800681)
			(xy 108.035892 -219.82733) (xy 107.986278 -219.846802) (xy 107.934316 -219.858662) (xy 107.881166 -219.862646)
			(xy 107.828016 -219.858662) (xy 107.776054 -219.846802) (xy 107.72644 -219.82733) (xy 107.680282 -219.800681)
			(xy 107.638611 -219.76745) (xy 107.602359 -219.728379) (xy 107.572335 -219.684342) (xy 107.549209 -219.636321)
			(xy 107.533499 -219.585391) (xy 107.525556 -219.532687) (xy 107.296976 -219.532687) (xy 107.289033 -219.585391)
			(xy 107.273323 -219.636321) (xy 107.250197 -219.684342) (xy 107.220173 -219.728379) (xy 107.183921 -219.76745)
			(xy 107.14225 -219.800681) (xy 107.096092 -219.82733) (xy 107.046478 -219.846802) (xy 106.994516 -219.858662)
			(xy 106.941366 -219.862646) (xy 106.888216 -219.858662) (xy 106.836254 -219.846802) (xy 106.78664 -219.82733)
			(xy 106.740482 -219.800681) (xy 106.698811 -219.76745) (xy 106.662559 -219.728379) (xy 106.632535 -219.684342)
			(xy 106.609409 -219.636321) (xy 106.593699 -219.585391) (xy 106.585756 -219.532687) (xy 106.357176 -219.532687)
			(xy 106.349233 -219.585391) (xy 106.333523 -219.636321) (xy 106.310397 -219.684342) (xy 106.280373 -219.728379)
			(xy 106.244121 -219.76745) (xy 106.20245 -219.800681) (xy 106.156292 -219.82733) (xy 106.106678 -219.846802)
			(xy 106.054716 -219.858662) (xy 106.001566 -219.862646) (xy 105.948416 -219.858662) (xy 105.896454 -219.846802)
			(xy 105.84684 -219.82733) (xy 105.800682 -219.800681) (xy 105.759011 -219.76745) (xy 105.722759 -219.728379)
			(xy 105.692735 -219.684342) (xy 105.669609 -219.636321) (xy 105.653899 -219.585391) (xy 105.645956 -219.532687)
			(xy 105.534968 -219.532687) (xy 105.534968 -219.960952) (xy 105.57891 -219.967048) (xy 105.604226 -219.970879)
			(xy 105.653481 -219.984864) (xy 105.700222 -220.005764) (xy 105.743485 -220.033149) (xy 105.782375 -220.066453)
			(xy 105.816089 -220.104988) (xy 105.843932 -220.147957) (xy 105.865327 -220.194474) (xy 105.879833 -220.243577)
			(xy 105.887151 -220.294253) (xy 105.88752 -220.319854) (xy 105.887125 -220.343056) (xy 105.886671 -220.346503)
			(xy 106.115856 -220.346503) (xy 106.115856 -220.293205) (xy 106.123799 -220.240501) (xy 106.139509 -220.189571)
			(xy 106.162635 -220.14155) (xy 106.192659 -220.097513) (xy 106.228911 -220.058442) (xy 106.270582 -220.025211)
			(xy 106.31674 -219.998562) (xy 106.366354 -219.97909) (xy 106.418316 -219.96723) (xy 106.471466 -219.963247)
			(xy 106.524616 -219.96723) (xy 106.576578 -219.97909) (xy 106.626192 -219.998562) (xy 106.67235 -220.025211)
			(xy 106.714021 -220.058442) (xy 106.750273 -220.097513) (xy 106.780297 -220.14155) (xy 106.803423 -220.189571)
			(xy 106.819133 -220.240501) (xy 106.827076 -220.293205) (xy 106.827574 -220.319854) (xy 107.054904 -220.319854)
			(xy 107.055402 -220.293205) (xy 107.063345 -220.240501) (xy 107.079055 -220.189571) (xy 107.102181 -220.14155)
			(xy 107.132205 -220.097513) (xy 107.168457 -220.058442) (xy 107.210128 -220.025211) (xy 107.256286 -219.998562)
			(xy 107.3059 -219.97909) (xy 107.357862 -219.96723) (xy 107.411012 -219.963247) (xy 107.464162 -219.96723)
			(xy 107.516124 -219.97909) (xy 107.565738 -219.998562) (xy 107.611896 -220.025211) (xy 107.653567 -220.058442)
			(xy 107.689819 -220.097513) (xy 107.719843 -220.14155) (xy 107.742969 -220.189571) (xy 107.758679 -220.240501)
			(xy 107.766622 -220.293205) (xy 107.76712 -220.319854) (xy 107.766723 -220.343057) (xy 107.76627 -220.346503)
			(xy 107.995456 -220.346503) (xy 107.995456 -220.293205) (xy 108.003399 -220.240501) (xy 108.019109 -220.189571)
			(xy 108.042235 -220.14155) (xy 108.072259 -220.097513) (xy 108.108511 -220.058442) (xy 108.150182 -220.025211)
			(xy 108.19634 -219.998562) (xy 108.245954 -219.97909) (xy 108.297916 -219.96723) (xy 108.351066 -219.963247)
			(xy 108.404216 -219.96723) (xy 108.456178 -219.97909) (xy 108.505792 -219.998562) (xy 108.55195 -220.025211)
			(xy 108.593621 -220.058442) (xy 108.629873 -220.097513) (xy 108.659897 -220.14155) (xy 108.683023 -220.189571)
			(xy 108.698733 -220.240501) (xy 108.706676 -220.293205) (xy 108.707174 -220.319854) (xy 108.934504 -220.319854)
			(xy 108.935002 -220.293205) (xy 108.942945 -220.240501) (xy 108.958655 -220.189571) (xy 108.981781 -220.14155)
			(xy 109.011805 -220.097513) (xy 109.048057 -220.058442) (xy 109.089728 -220.025211) (xy 109.135886 -219.998562)
			(xy 109.1855 -219.97909) (xy 109.237462 -219.96723) (xy 109.290612 -219.963247) (xy 109.343762 -219.96723)
			(xy 109.395724 -219.97909) (xy 109.445338 -219.998562) (xy 109.491496 -220.025211) (xy 109.533167 -220.058442)
			(xy 109.569419 -220.097513) (xy 109.599443 -220.14155) (xy 109.622569 -220.189571) (xy 109.638279 -220.240501)
			(xy 109.646222 -220.293205) (xy 109.64672 -220.319854) (xy 109.646323 -220.343057) (xy 109.64587 -220.346503)
			(xy 109.875056 -220.346503) (xy 109.875056 -220.293205) (xy 109.882999 -220.240501) (xy 109.898709 -220.189571)
			(xy 109.921835 -220.14155) (xy 109.951859 -220.097513) (xy 109.988111 -220.058442) (xy 110.029782 -220.025211)
			(xy 110.07594 -219.998562) (xy 110.125554 -219.97909) (xy 110.177516 -219.96723) (xy 110.230666 -219.963247)
			(xy 110.283816 -219.96723) (xy 110.335778 -219.97909) (xy 110.385392 -219.998562) (xy 110.43155 -220.025211)
			(xy 110.473221 -220.058442) (xy 110.509473 -220.097513) (xy 110.539497 -220.14155) (xy 110.562623 -220.189571)
			(xy 110.578333 -220.240501) (xy 110.586276 -220.293205) (xy 110.586774 -220.319854) (xy 110.814104 -220.319854)
			(xy 110.814602 -220.293205) (xy 110.822545 -220.240501) (xy 110.838255 -220.189571) (xy 110.861381 -220.14155)
			(xy 110.891405 -220.097513) (xy 110.927657 -220.058442) (xy 110.969328 -220.025211) (xy 111.015486 -219.998562)
			(xy 111.0651 -219.97909) (xy 111.117062 -219.96723) (xy 111.170212 -219.963247) (xy 111.223362 -219.96723)
			(xy 111.275324 -219.97909) (xy 111.324938 -219.998562) (xy 111.371096 -220.025211) (xy 111.412767 -220.058442)
			(xy 111.449019 -220.097513) (xy 111.479043 -220.14155) (xy 111.502169 -220.189571) (xy 111.517879 -220.240501)
			(xy 111.525822 -220.293205) (xy 111.52632 -220.319854) (xy 111.525923 -220.343057) (xy 111.52547 -220.346503)
			(xy 111.754656 -220.346503) (xy 111.754656 -220.293205) (xy 111.762599 -220.240501) (xy 111.778309 -220.189571)
			(xy 111.801435 -220.14155) (xy 111.831459 -220.097513) (xy 111.867711 -220.058442) (xy 111.909382 -220.025211)
			(xy 111.95554 -219.998562) (xy 112.005154 -219.97909) (xy 112.057116 -219.96723) (xy 112.110266 -219.963247)
			(xy 112.163416 -219.96723) (xy 112.215378 -219.97909) (xy 112.264992 -219.998562) (xy 112.31115 -220.025211)
			(xy 112.352821 -220.058442) (xy 112.389073 -220.097513) (xy 112.419097 -220.14155) (xy 112.442223 -220.189571)
			(xy 112.457933 -220.240501) (xy 112.465876 -220.293205) (xy 112.466374 -220.319854) (xy 112.693704 -220.319854)
			(xy 112.694202 -220.293205) (xy 112.702145 -220.240501) (xy 112.717855 -220.189571) (xy 112.740981 -220.14155)
			(xy 112.771005 -220.097513) (xy 112.807257 -220.058442) (xy 112.848928 -220.025211) (xy 112.895086 -219.998562)
			(xy 112.9447 -219.97909) (xy 112.996662 -219.96723) (xy 113.049812 -219.963247) (xy 113.102962 -219.96723)
			(xy 113.154924 -219.97909) (xy 113.204538 -219.998562) (xy 113.250696 -220.025211) (xy 113.292367 -220.058442)
			(xy 113.328619 -220.097513) (xy 113.358643 -220.14155) (xy 113.381769 -220.189571) (xy 113.397479 -220.240501)
			(xy 113.405422 -220.293205) (xy 113.40592 -220.319854) (xy 113.405523 -220.343057) (xy 113.40507 -220.346503)
			(xy 113.634256 -220.346503) (xy 113.634256 -220.293205) (xy 113.642199 -220.240501) (xy 113.657909 -220.189571)
			(xy 113.681035 -220.14155) (xy 113.711059 -220.097513) (xy 113.747311 -220.058442) (xy 113.788982 -220.025211)
			(xy 113.83514 -219.998562) (xy 113.884754 -219.97909) (xy 113.936716 -219.96723) (xy 113.989866 -219.963247)
			(xy 114.043016 -219.96723) (xy 114.094978 -219.97909) (xy 114.144592 -219.998562) (xy 114.19075 -220.025211)
			(xy 114.232421 -220.058442) (xy 114.268673 -220.097513) (xy 114.298697 -220.14155) (xy 114.321823 -220.189571)
			(xy 114.337533 -220.240501) (xy 114.345476 -220.293205) (xy 114.345974 -220.319854) (xy 114.573304 -220.319854)
			(xy 114.573802 -220.293205) (xy 114.581745 -220.240501) (xy 114.597455 -220.189571) (xy 114.620581 -220.14155)
			(xy 114.650605 -220.097513) (xy 114.686857 -220.058442) (xy 114.728528 -220.025211) (xy 114.774686 -219.998562)
			(xy 114.8243 -219.97909) (xy 114.876262 -219.96723) (xy 114.929412 -219.963247) (xy 114.982562 -219.96723)
			(xy 115.034524 -219.97909) (xy 115.084138 -219.998562) (xy 115.130296 -220.025211) (xy 115.171967 -220.058442)
			(xy 115.208219 -220.097513) (xy 115.238243 -220.14155) (xy 115.261369 -220.189571) (xy 115.277079 -220.240501)
			(xy 115.285022 -220.293205) (xy 115.28552 -220.319854) (xy 115.285123 -220.343057) (xy 115.28467 -220.346503)
			(xy 115.513856 -220.346503) (xy 115.513856 -220.293205) (xy 115.521799 -220.240501) (xy 115.537509 -220.189571)
			(xy 115.560635 -220.14155) (xy 115.590659 -220.097513) (xy 115.626911 -220.058442) (xy 115.668582 -220.025211)
			(xy 115.71474 -219.998562) (xy 115.764354 -219.97909) (xy 115.816316 -219.96723) (xy 115.869466 -219.963247)
			(xy 115.922616 -219.96723) (xy 115.974578 -219.97909) (xy 116.024192 -219.998562) (xy 116.07035 -220.025211)
			(xy 116.112021 -220.058442) (xy 116.148273 -220.097513) (xy 116.178297 -220.14155) (xy 116.201423 -220.189571)
			(xy 116.217133 -220.240501) (xy 116.225076 -220.293205) (xy 116.225574 -220.319854) (xy 116.452904 -220.319854)
			(xy 116.453402 -220.293205) (xy 116.461345 -220.240501) (xy 116.477055 -220.189571) (xy 116.500181 -220.14155)
			(xy 116.530205 -220.097513) (xy 116.566457 -220.058442) (xy 116.608128 -220.025211) (xy 116.654286 -219.998562)
			(xy 116.7039 -219.97909) (xy 116.755862 -219.96723) (xy 116.809012 -219.963247) (xy 116.862162 -219.96723)
			(xy 116.914124 -219.97909) (xy 116.963738 -219.998562) (xy 117.009896 -220.025211) (xy 117.051567 -220.058442)
			(xy 117.087819 -220.097513) (xy 117.117843 -220.14155) (xy 117.140969 -220.189571) (xy 117.156679 -220.240501)
			(xy 117.164622 -220.293205) (xy 117.16512 -220.319854) (xy 117.164723 -220.343057) (xy 117.16427 -220.346503)
			(xy 117.393456 -220.346503) (xy 117.393456 -220.293205) (xy 117.401399 -220.240501) (xy 117.417109 -220.189571)
			(xy 117.440235 -220.14155) (xy 117.470259 -220.097513) (xy 117.506511 -220.058442) (xy 117.548182 -220.025211)
			(xy 117.59434 -219.998562) (xy 117.643954 -219.97909) (xy 117.695916 -219.96723) (xy 117.749066 -219.963247)
			(xy 117.802216 -219.96723) (xy 117.854178 -219.97909) (xy 117.903792 -219.998562) (xy 117.94995 -220.025211)
			(xy 117.991621 -220.058442) (xy 118.027873 -220.097513) (xy 118.057897 -220.14155) (xy 118.081023 -220.189571)
			(xy 118.096733 -220.240501) (xy 118.104676 -220.293205) (xy 118.105174 -220.319854) (xy 118.104676 -220.346503)
			(xy 118.096733 -220.399207) (xy 118.081023 -220.450137) (xy 118.057897 -220.498158) (xy 118.027873 -220.542195)
			(xy 117.991621 -220.581266) (xy 117.94995 -220.614497) (xy 117.903792 -220.641146) (xy 117.854178 -220.660618)
			(xy 117.802216 -220.672478) (xy 117.749066 -220.676462) (xy 117.695916 -220.672478) (xy 117.643954 -220.660618)
			(xy 117.59434 -220.641146) (xy 117.548182 -220.614497) (xy 117.506511 -220.581266) (xy 117.470259 -220.542195)
			(xy 117.440235 -220.498158) (xy 117.417109 -220.450137) (xy 117.401399 -220.399207) (xy 117.393456 -220.346503)
			(xy 117.16427 -220.346503) (xy 117.15868 -220.389067) (xy 117.146703 -220.4339) (xy 117.138196 -220.45549)
			(xy 117.128798 -220.478604) (xy 117.301518 -220.777562) (xy 117.326156 -220.780864) (xy 117.351497 -220.784693)
			(xy 117.400801 -220.798686) (xy 117.447591 -220.819599) (xy 117.490901 -220.847) (xy 117.529838 -220.880325)
			(xy 117.563598 -220.918885) (xy 117.591485 -220.961884) (xy 117.612923 -221.008436) (xy 117.627469 -221.057579)
			(xy 117.634824 -221.108299) (xy 117.635274 -221.133924) (xy 117.634776 -221.160573) (xy 117.626833 -221.213277)
			(xy 117.611123 -221.264207) (xy 117.587997 -221.312228) (xy 117.557973 -221.356265) (xy 117.521721 -221.395336)
			(xy 117.48005 -221.428567) (xy 117.433892 -221.455216) (xy 117.384278 -221.474688) (xy 117.332316 -221.486548)
			(xy 117.279166 -221.490532) (xy 117.226016 -221.486548) (xy 117.174054 -221.474688) (xy 117.12444 -221.455216)
			(xy 117.078282 -221.428567) (xy 117.036611 -221.395336) (xy 117.000359 -221.356265) (xy 116.970335 -221.312228)
			(xy 116.947209 -221.264207) (xy 116.931499 -221.213277) (xy 116.923556 -221.160573) (xy 116.923058 -221.133924)
			(xy 116.923437 -221.110679) (xy 116.92948 -221.064584) (xy 116.941466 -221.019666) (xy 116.949982 -220.998034)
			(xy 116.959634 -220.97492) (xy 116.787168 -220.676216) (xy 116.762276 -220.672914) (xy 116.736921 -220.669093)
			(xy 116.687584 -220.655134) (xy 116.640757 -220.634246) (xy 116.59741 -220.606859) (xy 116.558437 -220.573539)
			(xy 116.524645 -220.534976) (xy 116.496731 -220.491966) (xy 116.475273 -220.445398) (xy 116.460714 -220.396234)
			(xy 116.453354 -220.345491) (xy 116.452904 -220.319854) (xy 116.225574 -220.319854) (xy 116.225076 -220.346503)
			(xy 116.217133 -220.399207) (xy 116.201423 -220.450137) (xy 116.178297 -220.498158) (xy 116.148273 -220.542195)
			(xy 116.112021 -220.581266) (xy 116.07035 -220.614497) (xy 116.024192 -220.641146) (xy 115.974578 -220.660618)
			(xy 115.922616 -220.672478) (xy 115.869466 -220.676462) (xy 115.816316 -220.672478) (xy 115.764354 -220.660618)
			(xy 115.71474 -220.641146) (xy 115.668582 -220.614497) (xy 115.626911 -220.581266) (xy 115.590659 -220.542195)
			(xy 115.560635 -220.498158) (xy 115.537509 -220.450137) (xy 115.521799 -220.399207) (xy 115.513856 -220.346503)
			(xy 115.28467 -220.346503) (xy 115.27908 -220.389067) (xy 115.267103 -220.4339) (xy 115.258596 -220.45549)
			(xy 115.249198 -220.478604) (xy 115.421918 -220.777562) (xy 115.446556 -220.780864) (xy 115.471897 -220.784693)
			(xy 115.521201 -220.798686) (xy 115.567991 -220.819599) (xy 115.611301 -220.847) (xy 115.650238 -220.880325)
			(xy 115.683998 -220.918885) (xy 115.711885 -220.961884) (xy 115.733323 -221.008436) (xy 115.747869 -221.057579)
			(xy 115.755224 -221.108299) (xy 115.755674 -221.133924) (xy 115.755176 -221.160573) (xy 115.747233 -221.213277)
			(xy 115.731523 -221.264207) (xy 115.708397 -221.312228) (xy 115.678373 -221.356265) (xy 115.642121 -221.395336)
			(xy 115.60045 -221.428567) (xy 115.554292 -221.455216) (xy 115.504678 -221.474688) (xy 115.452716 -221.486548)
			(xy 115.399566 -221.490532) (xy 115.346416 -221.486548) (xy 115.294454 -221.474688) (xy 115.24484 -221.455216)
			(xy 115.198682 -221.428567) (xy 115.157011 -221.395336) (xy 115.120759 -221.356265) (xy 115.090735 -221.312228)
			(xy 115.067609 -221.264207) (xy 115.051899 -221.213277) (xy 115.043956 -221.160573) (xy 115.043458 -221.133924)
			(xy 115.043837 -221.110679) (xy 115.04988 -221.064584) (xy 115.061866 -221.019666) (xy 115.070382 -220.998034)
			(xy 115.080034 -220.97492) (xy 114.907568 -220.676216) (xy 114.882676 -220.672914) (xy 114.857321 -220.669093)
			(xy 114.807984 -220.655134) (xy 114.761157 -220.634246) (xy 114.71781 -220.606859) (xy 114.678837 -220.573539)
			(xy 114.645045 -220.534976) (xy 114.617131 -220.491966) (xy 114.595673 -220.445398) (xy 114.581114 -220.396234)
			(xy 114.573754 -220.345491) (xy 114.573304 -220.319854) (xy 114.345974 -220.319854) (xy 114.345476 -220.346503)
			(xy 114.337533 -220.399207) (xy 114.321823 -220.450137) (xy 114.298697 -220.498158) (xy 114.268673 -220.542195)
			(xy 114.232421 -220.581266) (xy 114.19075 -220.614497) (xy 114.144592 -220.641146) (xy 114.094978 -220.660618)
			(xy 114.043016 -220.672478) (xy 113.989866 -220.676462) (xy 113.936716 -220.672478) (xy 113.884754 -220.660618)
			(xy 113.83514 -220.641146) (xy 113.788982 -220.614497) (xy 113.747311 -220.581266) (xy 113.711059 -220.542195)
			(xy 113.681035 -220.498158) (xy 113.657909 -220.450137) (xy 113.642199 -220.399207) (xy 113.634256 -220.346503)
			(xy 113.40507 -220.346503) (xy 113.39948 -220.389067) (xy 113.387503 -220.4339) (xy 113.378996 -220.45549)
			(xy 113.369598 -220.478604) (xy 113.542318 -220.777562) (xy 113.566956 -220.780864) (xy 113.592297 -220.784693)
			(xy 113.641601 -220.798686) (xy 113.688391 -220.819599) (xy 113.731701 -220.847) (xy 113.770638 -220.880325)
			(xy 113.804398 -220.918885) (xy 113.832285 -220.961884) (xy 113.853723 -221.008436) (xy 113.868269 -221.057579)
			(xy 113.875624 -221.108299) (xy 113.876074 -221.133924) (xy 113.875576 -221.160573) (xy 113.867633 -221.213277)
			(xy 113.851923 -221.264207) (xy 113.828797 -221.312228) (xy 113.798773 -221.356265) (xy 113.762521 -221.395336)
			(xy 113.72085 -221.428567) (xy 113.674692 -221.455216) (xy 113.625078 -221.474688) (xy 113.573116 -221.486548)
			(xy 113.519966 -221.490532) (xy 113.466816 -221.486548) (xy 113.414854 -221.474688) (xy 113.36524 -221.455216)
			(xy 113.319082 -221.428567) (xy 113.277411 -221.395336) (xy 113.241159 -221.356265) (xy 113.211135 -221.312228)
			(xy 113.188009 -221.264207) (xy 113.172299 -221.213277) (xy 113.164356 -221.160573) (xy 113.163858 -221.133924)
			(xy 113.164237 -221.110679) (xy 113.17028 -221.064584) (xy 113.182266 -221.019666) (xy 113.190782 -220.998034)
			(xy 113.200434 -220.97492) (xy 113.027968 -220.676216) (xy 113.003076 -220.672914) (xy 112.977721 -220.669093)
			(xy 112.928384 -220.655134) (xy 112.881557 -220.634246) (xy 112.83821 -220.606859) (xy 112.799237 -220.573539)
			(xy 112.765445 -220.534976) (xy 112.737531 -220.491966) (xy 112.716073 -220.445398) (xy 112.701514 -220.396234)
			(xy 112.694154 -220.345491) (xy 112.693704 -220.319854) (xy 112.466374 -220.319854) (xy 112.465876 -220.346503)
			(xy 112.457933 -220.399207) (xy 112.442223 -220.450137) (xy 112.419097 -220.498158) (xy 112.389073 -220.542195)
			(xy 112.352821 -220.581266) (xy 112.31115 -220.614497) (xy 112.264992 -220.641146) (xy 112.215378 -220.660618)
			(xy 112.163416 -220.672478) (xy 112.110266 -220.676462) (xy 112.057116 -220.672478) (xy 112.005154 -220.660618)
			(xy 111.95554 -220.641146) (xy 111.909382 -220.614497) (xy 111.867711 -220.581266) (xy 111.831459 -220.542195)
			(xy 111.801435 -220.498158) (xy 111.778309 -220.450137) (xy 111.762599 -220.399207) (xy 111.754656 -220.346503)
			(xy 111.52547 -220.346503) (xy 111.51988 -220.389067) (xy 111.507903 -220.4339) (xy 111.499396 -220.45549)
			(xy 111.489998 -220.478604) (xy 111.662718 -220.777562) (xy 111.687356 -220.780864) (xy 111.712697 -220.784693)
			(xy 111.762001 -220.798686) (xy 111.808791 -220.819599) (xy 111.852101 -220.847) (xy 111.891038 -220.880325)
			(xy 111.924798 -220.918885) (xy 111.952685 -220.961884) (xy 111.974123 -221.008436) (xy 111.988669 -221.057579)
			(xy 111.996024 -221.108299) (xy 111.996474 -221.133924) (xy 111.995976 -221.160573) (xy 111.988033 -221.213277)
			(xy 111.972323 -221.264207) (xy 111.949197 -221.312228) (xy 111.919173 -221.356265) (xy 111.882921 -221.395336)
			(xy 111.84125 -221.428567) (xy 111.795092 -221.455216) (xy 111.745478 -221.474688) (xy 111.693516 -221.486548)
			(xy 111.640366 -221.490532) (xy 111.587216 -221.486548) (xy 111.535254 -221.474688) (xy 111.48564 -221.455216)
			(xy 111.439482 -221.428567) (xy 111.397811 -221.395336) (xy 111.361559 -221.356265) (xy 111.331535 -221.312228)
			(xy 111.308409 -221.264207) (xy 111.292699 -221.213277) (xy 111.284756 -221.160573) (xy 111.284258 -221.133924)
			(xy 111.284637 -221.110679) (xy 111.29068 -221.064584) (xy 111.302666 -221.019666) (xy 111.311182 -220.998034)
			(xy 111.320834 -220.97492) (xy 111.148368 -220.676216) (xy 111.123476 -220.672914) (xy 111.098121 -220.669093)
			(xy 111.048784 -220.655134) (xy 111.001957 -220.634246) (xy 110.95861 -220.606859) (xy 110.919637 -220.573539)
			(xy 110.885845 -220.534976) (xy 110.857931 -220.491966) (xy 110.836473 -220.445398) (xy 110.821914 -220.396234)
			(xy 110.814554 -220.345491) (xy 110.814104 -220.319854) (xy 110.586774 -220.319854) (xy 110.586276 -220.346503)
			(xy 110.578333 -220.399207) (xy 110.562623 -220.450137) (xy 110.539497 -220.498158) (xy 110.509473 -220.542195)
			(xy 110.473221 -220.581266) (xy 110.43155 -220.614497) (xy 110.385392 -220.641146) (xy 110.335778 -220.660618)
			(xy 110.283816 -220.672478) (xy 110.230666 -220.676462) (xy 110.177516 -220.672478) (xy 110.125554 -220.660618)
			(xy 110.07594 -220.641146) (xy 110.029782 -220.614497) (xy 109.988111 -220.581266) (xy 109.951859 -220.542195)
			(xy 109.921835 -220.498158) (xy 109.898709 -220.450137) (xy 109.882999 -220.399207) (xy 109.875056 -220.346503)
			(xy 109.64587 -220.346503) (xy 109.64028 -220.389067) (xy 109.628303 -220.4339) (xy 109.619796 -220.45549)
			(xy 109.610398 -220.478604) (xy 109.783118 -220.777562) (xy 109.807756 -220.780864) (xy 109.833097 -220.784693)
			(xy 109.882401 -220.798686) (xy 109.929191 -220.819599) (xy 109.972501 -220.847) (xy 110.011438 -220.880325)
			(xy 110.045198 -220.918885) (xy 110.073085 -220.961884) (xy 110.094523 -221.008436) (xy 110.109069 -221.057579)
			(xy 110.116424 -221.108299) (xy 110.116874 -221.133924) (xy 110.116376 -221.160573) (xy 110.108433 -221.213277)
			(xy 110.092723 -221.264207) (xy 110.069597 -221.312228) (xy 110.039573 -221.356265) (xy 110.003321 -221.395336)
			(xy 109.96165 -221.428567) (xy 109.915492 -221.455216) (xy 109.865878 -221.474688) (xy 109.813916 -221.486548)
			(xy 109.760766 -221.490532) (xy 109.707616 -221.486548) (xy 109.655654 -221.474688) (xy 109.60604 -221.455216)
			(xy 109.559882 -221.428567) (xy 109.518211 -221.395336) (xy 109.481959 -221.356265) (xy 109.451935 -221.312228)
			(xy 109.428809 -221.264207) (xy 109.413099 -221.213277) (xy 109.405156 -221.160573) (xy 109.404658 -221.133924)
			(xy 109.405037 -221.110679) (xy 109.41108 -221.064584) (xy 109.423066 -221.019666) (xy 109.431582 -220.998034)
			(xy 109.441234 -220.97492) (xy 109.268768 -220.676216) (xy 109.243876 -220.672914) (xy 109.218521 -220.669093)
			(xy 109.169184 -220.655134) (xy 109.122357 -220.634246) (xy 109.07901 -220.606859) (xy 109.040037 -220.573539)
			(xy 109.006245 -220.534976) (xy 108.978331 -220.491966) (xy 108.956873 -220.445398) (xy 108.942314 -220.396234)
			(xy 108.934954 -220.345491) (xy 108.934504 -220.319854) (xy 108.707174 -220.319854) (xy 108.706676 -220.346503)
			(xy 108.698733 -220.399207) (xy 108.683023 -220.450137) (xy 108.659897 -220.498158) (xy 108.629873 -220.542195)
			(xy 108.593621 -220.581266) (xy 108.55195 -220.614497) (xy 108.505792 -220.641146) (xy 108.456178 -220.660618)
			(xy 108.404216 -220.672478) (xy 108.351066 -220.676462) (xy 108.297916 -220.672478) (xy 108.245954 -220.660618)
			(xy 108.19634 -220.641146) (xy 108.150182 -220.614497) (xy 108.108511 -220.581266) (xy 108.072259 -220.542195)
			(xy 108.042235 -220.498158) (xy 108.019109 -220.450137) (xy 108.003399 -220.399207) (xy 107.995456 -220.346503)
			(xy 107.76627 -220.346503) (xy 107.76068 -220.389067) (xy 107.748703 -220.4339) (xy 107.740196 -220.45549)
			(xy 107.730798 -220.478604) (xy 107.903518 -220.777562) (xy 107.928156 -220.780864) (xy 107.953497 -220.784693)
			(xy 108.002801 -220.798686) (xy 108.049591 -220.819599) (xy 108.092901 -220.847) (xy 108.131838 -220.880325)
			(xy 108.165598 -220.918885) (xy 108.193485 -220.961884) (xy 108.214923 -221.008436) (xy 108.229469 -221.057579)
			(xy 108.236824 -221.108299) (xy 108.237274 -221.133924) (xy 108.236776 -221.160573) (xy 108.228833 -221.213277)
			(xy 108.213123 -221.264207) (xy 108.189997 -221.312228) (xy 108.159973 -221.356265) (xy 108.123721 -221.395336)
			(xy 108.08205 -221.428567) (xy 108.035892 -221.455216) (xy 107.986278 -221.474688) (xy 107.934316 -221.486548)
			(xy 107.881166 -221.490532) (xy 107.828016 -221.486548) (xy 107.776054 -221.474688) (xy 107.72644 -221.455216)
			(xy 107.680282 -221.428567) (xy 107.638611 -221.395336) (xy 107.602359 -221.356265) (xy 107.572335 -221.312228)
			(xy 107.549209 -221.264207) (xy 107.533499 -221.213277) (xy 107.525556 -221.160573) (xy 107.525058 -221.133924)
			(xy 107.525437 -221.110679) (xy 107.53148 -221.064584) (xy 107.543466 -221.019666) (xy 107.551982 -220.998034)
			(xy 107.561634 -220.97492) (xy 107.389168 -220.676216) (xy 107.364276 -220.672914) (xy 107.338921 -220.669093)
			(xy 107.289584 -220.655134) (xy 107.242757 -220.634246) (xy 107.19941 -220.606859) (xy 107.160437 -220.573539)
			(xy 107.126645 -220.534976) (xy 107.098731 -220.491966) (xy 107.077273 -220.445398) (xy 107.062714 -220.396234)
			(xy 107.055354 -220.345491) (xy 107.054904 -220.319854) (xy 106.827574 -220.319854) (xy 106.827076 -220.346503)
			(xy 106.819133 -220.399207) (xy 106.803423 -220.450137) (xy 106.780297 -220.498158) (xy 106.750273 -220.542195)
			(xy 106.714021 -220.581266) (xy 106.67235 -220.614497) (xy 106.626192 -220.641146) (xy 106.576578 -220.660618)
			(xy 106.524616 -220.672478) (xy 106.471466 -220.676462) (xy 106.418316 -220.672478) (xy 106.366354 -220.660618)
			(xy 106.31674 -220.641146) (xy 106.270582 -220.614497) (xy 106.228911 -220.581266) (xy 106.192659 -220.542195)
			(xy 106.162635 -220.498158) (xy 106.139509 -220.450137) (xy 106.123799 -220.399207) (xy 106.115856 -220.346503)
			(xy 105.886671 -220.346503) (xy 105.881062 -220.389062) (xy 105.869085 -220.433893) (xy 105.860596 -220.45549)
			(xy 105.851198 -220.478604) (xy 106.023918 -220.777562) (xy 106.048556 -220.780864) (xy 106.073901 -220.784686)
			(xy 106.123214 -220.798661) (xy 106.170013 -220.819563) (xy 106.213332 -220.846959) (xy 106.252274 -220.880284)
			(xy 106.286036 -220.918849) (xy 106.313919 -220.961856) (xy 106.335347 -221.008416) (xy 106.349877 -221.057569)
			(xy 106.357209 -221.108296) (xy 106.357674 -221.133924) (xy 106.357176 -221.160573) (xy 106.349233 -221.213277)
			(xy 106.333523 -221.264207) (xy 106.310397 -221.312228) (xy 106.280373 -221.356265) (xy 106.244121 -221.395336)
			(xy 106.20245 -221.428567) (xy 106.156292 -221.455216) (xy 106.106678 -221.474688) (xy 106.054716 -221.486548)
			(xy 106.001566 -221.490532) (xy 105.948416 -221.486548) (xy 105.896454 -221.474688) (xy 105.84684 -221.455216)
			(xy 105.800682 -221.428567) (xy 105.759011 -221.395336) (xy 105.722759 -221.356265) (xy 105.692735 -221.312228)
			(xy 105.669609 -221.264207) (xy 105.653899 -221.213277) (xy 105.645956 -221.160573) (xy 105.645458 -221.133924)
			(xy 105.645832 -221.110679) (xy 105.651873 -221.064582) (xy 105.663856 -221.019662) (xy 105.672382 -220.998034)
			(xy 105.682034 -220.97492) (xy 105.62971 -220.884496) (xy 105.6246 -220.876454) (xy 105.609705 -220.864594)
			(xy 105.591508 -220.858993) (xy 105.572521 -220.860425) (xy 105.55537 -220.868692) (xy 105.542422 -220.882652)
			(xy 105.535467 -220.900376) (xy 105.534968 -220.909896) (xy 105.534968 -221.588838) (xy 105.57891 -221.594934)
			(xy 105.605553 -221.599) (xy 105.657281 -221.614121) (xy 105.706138 -221.636868) (xy 105.751008 -221.66672)
			(xy 105.790864 -221.702996) (xy 105.824794 -221.744867) (xy 105.852025 -221.791375) (xy 105.871932 -221.841456)
			(xy 105.884061 -221.893967) (xy 105.888134 -221.947705) (xy 105.888131 -221.94774) (xy 106.115104 -221.94774)
			(xy 106.115517 -221.92211) (xy 106.122848 -221.871376) (xy 106.13738 -221.822219) (xy 106.158812 -221.775654)
			(xy 106.1867 -221.732644) (xy 106.220469 -221.694079) (xy 106.259419 -221.660755) (xy 106.302746 -221.633361)
			(xy 106.349553 -221.612465) (xy 106.398874 -221.598497) (xy 106.424222 -221.59468) (xy 106.44886 -221.591378)
			(xy 106.621326 -221.29242) (xy 106.611928 -221.269306) (xy 106.603474 -221.247794) (xy 106.5916 -221.203123)
			(xy 106.585621 -221.157289) (xy 106.585258 -221.134178) (xy 106.585258 -221.133924) (xy 106.585756 -221.107275)
			(xy 106.593699 -221.054571) (xy 106.609409 -221.003641) (xy 106.632535 -220.95562) (xy 106.662559 -220.911583)
			(xy 106.698811 -220.872512) (xy 106.740482 -220.839281) (xy 106.78664 -220.812632) (xy 106.836254 -220.79316)
			(xy 106.888216 -220.7813) (xy 106.941366 -220.777317) (xy 106.994516 -220.7813) (xy 107.046478 -220.79316)
			(xy 107.096092 -220.812632) (xy 107.14225 -220.839281) (xy 107.183921 -220.872512) (xy 107.220173 -220.911583)
			(xy 107.250197 -220.95562) (xy 107.273323 -221.003641) (xy 107.289033 -221.054571) (xy 107.296976 -221.107275)
			(xy 107.297474 -221.133924) (xy 107.297077 -221.159576) (xy 107.289712 -221.210348) (xy 107.275137 -221.259539)
			(xy 107.253654 -221.306128) (xy 107.225709 -221.349153) (xy 107.191878 -221.387723) (xy 107.152864 -221.421038)
			(xy 107.109472 -221.448411) (xy 107.062602 -221.469274) (xy 107.013223 -221.483195) (xy 106.987848 -221.486984)
			(xy 106.962956 -221.490286) (xy 106.790744 -221.788736) (xy 106.800396 -221.81185) (xy 106.808925 -221.833477)
			(xy 106.820907 -221.878397) (xy 106.826947 -221.924494) (xy 106.82732 -221.94774) (xy 106.826822 -221.974389)
			(xy 107.055402 -221.974389) (xy 107.055402 -221.921091) (xy 107.063345 -221.868387) (xy 107.079055 -221.817457)
			(xy 107.102181 -221.769436) (xy 107.132205 -221.725399) (xy 107.168457 -221.686328) (xy 107.210128 -221.653097)
			(xy 107.256286 -221.626448) (xy 107.3059 -221.606976) (xy 107.357862 -221.595116) (xy 107.411012 -221.591133)
			(xy 107.464162 -221.595116) (xy 107.516124 -221.606976) (xy 107.565738 -221.626448) (xy 107.611896 -221.653097)
			(xy 107.653567 -221.686328) (xy 107.689819 -221.725399) (xy 107.719843 -221.769436) (xy 107.742969 -221.817457)
			(xy 107.758679 -221.868387) (xy 107.766622 -221.921091) (xy 107.76712 -221.94774) (xy 107.994704 -221.94774)
			(xy 107.995117 -221.92211) (xy 108.002448 -221.871376) (xy 108.01698 -221.822219) (xy 108.038412 -221.775654)
			(xy 108.0663 -221.732644) (xy 108.100069 -221.694079) (xy 108.139019 -221.660755) (xy 108.182346 -221.633361)
			(xy 108.229153 -221.612465) (xy 108.278474 -221.598497) (xy 108.303822 -221.59468) (xy 108.32846 -221.591378)
			(xy 108.500926 -221.29242) (xy 108.491528 -221.269306) (xy 108.483074 -221.247794) (xy 108.4712 -221.203123)
			(xy 108.465221 -221.157289) (xy 108.464858 -221.134178) (xy 108.464858 -221.133924) (xy 108.465356 -221.107275)
			(xy 108.473299 -221.054571) (xy 108.489009 -221.003641) (xy 108.512135 -220.95562) (xy 108.542159 -220.911583)
			(xy 108.578411 -220.872512) (xy 108.620082 -220.839281) (xy 108.66624 -220.812632) (xy 108.715854 -220.79316)
			(xy 108.767816 -220.7813) (xy 108.820966 -220.777317) (xy 108.874116 -220.7813) (xy 108.926078 -220.79316)
			(xy 108.975692 -220.812632) (xy 109.02185 -220.839281) (xy 109.063521 -220.872512) (xy 109.099773 -220.911583)
			(xy 109.129797 -220.95562) (xy 109.152923 -221.003641) (xy 109.168633 -221.054571) (xy 109.176576 -221.107275)
			(xy 109.177074 -221.133924) (xy 109.176677 -221.159576) (xy 109.169312 -221.210348) (xy 109.154737 -221.259539)
			(xy 109.133254 -221.306128) (xy 109.105309 -221.349153) (xy 109.071478 -221.387723) (xy 109.032464 -221.421038)
			(xy 108.989072 -221.448411) (xy 108.942202 -221.469274) (xy 108.892823 -221.483195) (xy 108.867448 -221.486984)
			(xy 108.842556 -221.490286) (xy 108.670344 -221.788736) (xy 108.679996 -221.81185) (xy 108.688525 -221.833477)
			(xy 108.700507 -221.878397) (xy 108.706547 -221.924494) (xy 108.70692 -221.94774) (xy 108.706422 -221.974389)
			(xy 108.935002 -221.974389) (xy 108.935002 -221.921091) (xy 108.942945 -221.868387) (xy 108.958655 -221.817457)
			(xy 108.981781 -221.769436) (xy 109.011805 -221.725399) (xy 109.048057 -221.686328) (xy 109.089728 -221.653097)
			(xy 109.135886 -221.626448) (xy 109.1855 -221.606976) (xy 109.237462 -221.595116) (xy 109.290612 -221.591133)
			(xy 109.343762 -221.595116) (xy 109.395724 -221.606976) (xy 109.445338 -221.626448) (xy 109.491496 -221.653097)
			(xy 109.533167 -221.686328) (xy 109.569419 -221.725399) (xy 109.599443 -221.769436) (xy 109.622569 -221.817457)
			(xy 109.638279 -221.868387) (xy 109.646222 -221.921091) (xy 109.64672 -221.94774) (xy 109.874558 -221.94774)
			(xy 109.875011 -221.922112) (xy 109.882341 -221.871382) (xy 109.896871 -221.822228) (xy 109.918299 -221.775665)
			(xy 109.946183 -221.732657) (xy 109.979946 -221.694092) (xy 110.018891 -221.660767) (xy 110.062213 -221.633372)
			(xy 110.109015 -221.612472) (xy 110.15833 -221.5985) (xy 110.183676 -221.59468) (xy 110.208314 -221.591378)
			(xy 110.38078 -221.292674) (xy 110.371382 -221.26956) (xy 110.362883 -221.247967) (xy 110.35091 -221.203133)
			(xy 110.344851 -221.157126) (xy 110.344458 -221.133924) (xy 110.344956 -221.107275) (xy 110.352899 -221.054571)
			(xy 110.368609 -221.003641) (xy 110.391735 -220.95562) (xy 110.421759 -220.911583) (xy 110.458011 -220.872512)
			(xy 110.499682 -220.839281) (xy 110.54584 -220.812632) (xy 110.595454 -220.79316) (xy 110.647416 -220.7813)
			(xy 110.700566 -220.777317) (xy 110.753716 -220.7813) (xy 110.805678 -220.79316) (xy 110.855292 -220.812632)
			(xy 110.90145 -220.839281) (xy 110.943121 -220.872512) (xy 110.979373 -220.911583) (xy 111.009397 -220.95562)
			(xy 111.032523 -221.003641) (xy 111.048233 -221.054571) (xy 111.056176 -221.107275) (xy 111.056674 -221.133924)
			(xy 111.056218 -221.159563) (xy 111.048873 -221.210312) (xy 111.034324 -221.259483) (xy 111.012872 -221.306058)
			(xy 110.984961 -221.349074) (xy 110.951168 -221.387641) (xy 110.912191 -221.420962) (xy 110.868838 -221.448347)
			(xy 110.822005 -221.469229) (xy 110.772661 -221.483178) (xy 110.747302 -221.486984) (xy 110.72241 -221.490286)
			(xy 110.550198 -221.788736) (xy 110.55985 -221.81185) (xy 110.568377 -221.833478) (xy 110.580361 -221.878398)
			(xy 110.586401 -221.924495) (xy 110.586774 -221.94774) (xy 110.586276 -221.974389) (xy 110.814856 -221.974389)
			(xy 110.814856 -221.921091) (xy 110.822799 -221.868387) (xy 110.838509 -221.817457) (xy 110.861635 -221.769436)
			(xy 110.891659 -221.725399) (xy 110.927911 -221.686328) (xy 110.969582 -221.653097) (xy 111.01574 -221.626448)
			(xy 111.065354 -221.606976) (xy 111.117316 -221.595116) (xy 111.170466 -221.591133) (xy 111.223616 -221.595116)
			(xy 111.275578 -221.606976) (xy 111.325192 -221.626448) (xy 111.37135 -221.653097) (xy 111.413021 -221.686328)
			(xy 111.449273 -221.725399) (xy 111.479297 -221.769436) (xy 111.502423 -221.817457) (xy 111.518133 -221.868387)
			(xy 111.526076 -221.921091) (xy 111.526574 -221.94774) (xy 111.753904 -221.94774) (xy 111.754317 -221.92211)
			(xy 111.761648 -221.871376) (xy 111.77618 -221.822219) (xy 111.797612 -221.775654) (xy 111.8255 -221.732644)
			(xy 111.859269 -221.694079) (xy 111.898219 -221.660755) (xy 111.941546 -221.633361) (xy 111.988353 -221.612465)
			(xy 112.037674 -221.598497) (xy 112.063022 -221.59468) (xy 112.08766 -221.591378) (xy 112.260126 -221.29242)
			(xy 112.250728 -221.269306) (xy 112.242274 -221.247794) (xy 112.2304 -221.203123) (xy 112.224421 -221.157289)
			(xy 112.224058 -221.134178) (xy 112.224058 -221.133924) (xy 112.224556 -221.107275) (xy 112.232499 -221.054571)
			(xy 112.248209 -221.003641) (xy 112.271335 -220.95562) (xy 112.301359 -220.911583) (xy 112.337611 -220.872512)
			(xy 112.379282 -220.839281) (xy 112.42544 -220.812632) (xy 112.475054 -220.79316) (xy 112.527016 -220.7813)
			(xy 112.580166 -220.777317) (xy 112.633316 -220.7813) (xy 112.685278 -220.79316) (xy 112.734892 -220.812632)
			(xy 112.78105 -220.839281) (xy 112.822721 -220.872512) (xy 112.858973 -220.911583) (xy 112.888997 -220.95562)
			(xy 112.912123 -221.003641) (xy 112.927833 -221.054571) (xy 112.935776 -221.107275) (xy 112.936274 -221.133924)
			(xy 112.935877 -221.159576) (xy 112.928512 -221.210348) (xy 112.913937 -221.259539) (xy 112.892454 -221.306128)
			(xy 112.864509 -221.349153) (xy 112.830678 -221.387723) (xy 112.791664 -221.421038) (xy 112.748272 -221.448411)
			(xy 112.701402 -221.469274) (xy 112.652023 -221.483195) (xy 112.626648 -221.486984) (xy 112.601756 -221.490286)
			(xy 112.429544 -221.788736) (xy 112.439196 -221.81185) (xy 112.447725 -221.833477) (xy 112.459707 -221.878397)
			(xy 112.465747 -221.924494) (xy 112.46612 -221.94774) (xy 112.465622 -221.974389) (xy 112.694202 -221.974389)
			(xy 112.694202 -221.921091) (xy 112.702145 -221.868387) (xy 112.717855 -221.817457) (xy 112.740981 -221.769436)
			(xy 112.771005 -221.725399) (xy 112.807257 -221.686328) (xy 112.848928 -221.653097) (xy 112.895086 -221.626448)
			(xy 112.9447 -221.606976) (xy 112.996662 -221.595116) (xy 113.049812 -221.591133) (xy 113.102962 -221.595116)
			(xy 113.154924 -221.606976) (xy 113.204538 -221.626448) (xy 113.250696 -221.653097) (xy 113.292367 -221.686328)
			(xy 113.328619 -221.725399) (xy 113.358643 -221.769436) (xy 113.381769 -221.817457) (xy 113.397479 -221.868387)
			(xy 113.405422 -221.921091) (xy 113.40592 -221.94774) (xy 113.633758 -221.94774) (xy 113.634211 -221.922112)
			(xy 113.641541 -221.871382) (xy 113.656071 -221.822228) (xy 113.677499 -221.775665) (xy 113.705383 -221.732657)
			(xy 113.739146 -221.694092) (xy 113.778091 -221.660767) (xy 113.821413 -221.633372) (xy 113.868215 -221.612472)
			(xy 113.91753 -221.5985) (xy 113.942876 -221.59468) (xy 113.967514 -221.591378) (xy 114.13998 -221.292674)
			(xy 114.130582 -221.26956) (xy 114.122083 -221.247967) (xy 114.11011 -221.203133) (xy 114.104051 -221.157126)
			(xy 114.103658 -221.133924) (xy 114.104156 -221.107275) (xy 114.112099 -221.054571) (xy 114.127809 -221.003641)
			(xy 114.150935 -220.95562) (xy 114.180959 -220.911583) (xy 114.217211 -220.872512) (xy 114.258882 -220.839281)
			(xy 114.30504 -220.812632) (xy 114.354654 -220.79316) (xy 114.406616 -220.7813) (xy 114.459766 -220.777317)
			(xy 114.512916 -220.7813) (xy 114.564878 -220.79316) (xy 114.614492 -220.812632) (xy 114.66065 -220.839281)
			(xy 114.702321 -220.872512) (xy 114.738573 -220.911583) (xy 114.768597 -220.95562) (xy 114.791723 -221.003641)
			(xy 114.807433 -221.054571) (xy 114.815376 -221.107275) (xy 114.815874 -221.133924) (xy 114.815418 -221.159563)
			(xy 114.808073 -221.210312) (xy 114.793524 -221.259483) (xy 114.772072 -221.306058) (xy 114.744161 -221.349074)
			(xy 114.710368 -221.387641) (xy 114.671391 -221.420962) (xy 114.628038 -221.448347) (xy 114.581205 -221.469229)
			(xy 114.531861 -221.483178) (xy 114.506502 -221.486984) (xy 114.48161 -221.490286) (xy 114.309398 -221.788736)
			(xy 114.31905 -221.81185) (xy 114.327577 -221.833478) (xy 114.339561 -221.878398) (xy 114.345601 -221.924495)
			(xy 114.345974 -221.94774) (xy 114.345476 -221.974389) (xy 114.574056 -221.974389) (xy 114.574056 -221.921091)
			(xy 114.581999 -221.868387) (xy 114.597709 -221.817457) (xy 114.620835 -221.769436) (xy 114.650859 -221.725399)
			(xy 114.687111 -221.686328) (xy 114.728782 -221.653097) (xy 114.77494 -221.626448) (xy 114.824554 -221.606976)
			(xy 114.876516 -221.595116) (xy 114.929666 -221.591133) (xy 114.982816 -221.595116) (xy 115.034778 -221.606976)
			(xy 115.084392 -221.626448) (xy 115.13055 -221.653097) (xy 115.172221 -221.686328) (xy 115.208473 -221.725399)
			(xy 115.238497 -221.769436) (xy 115.261623 -221.817457) (xy 115.277333 -221.868387) (xy 115.285276 -221.921091)
			(xy 115.285774 -221.94774) (xy 115.513104 -221.94774) (xy 115.513517 -221.92211) (xy 115.520848 -221.871376)
			(xy 115.53538 -221.822219) (xy 115.556812 -221.775654) (xy 115.5847 -221.732644) (xy 115.618469 -221.694079)
			(xy 115.657419 -221.660755) (xy 115.700746 -221.633361) (xy 115.747553 -221.612465) (xy 115.796874 -221.598497)
			(xy 115.822222 -221.59468) (xy 115.84686 -221.591378) (xy 116.019326 -221.29242) (xy 116.009928 -221.269306)
			(xy 116.001474 -221.247794) (xy 115.9896 -221.203123) (xy 115.983621 -221.157289) (xy 115.983258 -221.134178)
			(xy 115.983258 -221.133924) (xy 115.983756 -221.107275) (xy 115.991699 -221.054571) (xy 116.007409 -221.003641)
			(xy 116.030535 -220.95562) (xy 116.060559 -220.911583) (xy 116.096811 -220.872512) (xy 116.138482 -220.839281)
			(xy 116.18464 -220.812632) (xy 116.234254 -220.79316) (xy 116.286216 -220.7813) (xy 116.339366 -220.777317)
			(xy 116.392516 -220.7813) (xy 116.444478 -220.79316) (xy 116.494092 -220.812632) (xy 116.54025 -220.839281)
			(xy 116.581921 -220.872512) (xy 116.618173 -220.911583) (xy 116.648197 -220.95562) (xy 116.671323 -221.003641)
			(xy 116.687033 -221.054571) (xy 116.694976 -221.107275) (xy 116.695474 -221.133924) (xy 116.695077 -221.159576)
			(xy 116.687712 -221.210348) (xy 116.673137 -221.259539) (xy 116.651654 -221.306128) (xy 116.623709 -221.349153)
			(xy 116.589878 -221.387723) (xy 116.550864 -221.421038) (xy 116.507472 -221.448411) (xy 116.460602 -221.469274)
			(xy 116.411223 -221.483195) (xy 116.385848 -221.486984) (xy 116.360956 -221.490286) (xy 116.188744 -221.788736)
			(xy 116.198396 -221.81185) (xy 116.206925 -221.833477) (xy 116.218907 -221.878397) (xy 116.224947 -221.924494)
			(xy 116.22532 -221.94774) (xy 117.392704 -221.94774) (xy 117.393117 -221.92211) (xy 117.400448 -221.871376)
			(xy 117.41498 -221.822219) (xy 117.436412 -221.775654) (xy 117.4643 -221.732644) (xy 117.498069 -221.694079)
			(xy 117.537019 -221.660755) (xy 117.580346 -221.633361) (xy 117.627153 -221.612465) (xy 117.676474 -221.598497)
			(xy 117.701822 -221.59468) (xy 117.72646 -221.591378) (xy 117.898926 -221.29242) (xy 117.889528 -221.269306)
			(xy 117.881074 -221.247794) (xy 117.8692 -221.203123) (xy 117.863221 -221.157289) (xy 117.862858 -221.134178)
			(xy 117.862858 -221.133924) (xy 117.863356 -221.107275) (xy 117.871299 -221.054571) (xy 117.887009 -221.003641)
			(xy 117.910135 -220.95562) (xy 117.940159 -220.911583) (xy 117.976411 -220.872512) (xy 118.018082 -220.839281)
			(xy 118.06424 -220.812632) (xy 118.113854 -220.79316) (xy 118.165816 -220.7813) (xy 118.218966 -220.777317)
			(xy 118.272116 -220.7813) (xy 118.324078 -220.79316) (xy 118.373692 -220.812632) (xy 118.41985 -220.839281)
			(xy 118.461521 -220.872512) (xy 118.497773 -220.911583) (xy 118.527797 -220.95562) (xy 118.550923 -221.003641)
			(xy 118.566633 -221.054571) (xy 118.574576 -221.107275) (xy 118.575074 -221.133924) (xy 118.574677 -221.159576)
			(xy 118.567312 -221.210348) (xy 118.552737 -221.259539) (xy 118.531254 -221.306128) (xy 118.503309 -221.349153)
			(xy 118.469478 -221.387723) (xy 118.430464 -221.421038) (xy 118.387072 -221.448411) (xy 118.340202 -221.469274)
			(xy 118.290823 -221.483195) (xy 118.265448 -221.486984) (xy 118.240556 -221.490286) (xy 118.068344 -221.788736)
			(xy 118.077996 -221.81185) (xy 118.086525 -221.833477) (xy 118.098507 -221.878397) (xy 118.104547 -221.924494)
			(xy 118.10492 -221.94774) (xy 118.104422 -221.974389) (xy 118.096479 -222.027093) (xy 118.080769 -222.078023)
			(xy 118.057643 -222.126044) (xy 118.027619 -222.170081) (xy 117.991367 -222.209152) (xy 117.949696 -222.242383)
			(xy 117.903538 -222.269032) (xy 117.853924 -222.288504) (xy 117.801962 -222.300364) (xy 117.748812 -222.304348)
			(xy 117.695662 -222.300364) (xy 117.6437 -222.288504) (xy 117.594086 -222.269032) (xy 117.547928 -222.242383)
			(xy 117.506257 -222.209152) (xy 117.470005 -222.170081) (xy 117.439981 -222.126044) (xy 117.416855 -222.078023)
			(xy 117.401145 -222.027093) (xy 117.393202 -221.974389) (xy 117.392704 -221.94774) (xy 116.22532 -221.94774)
			(xy 116.224822 -221.974389) (xy 116.216879 -222.027093) (xy 116.201169 -222.078023) (xy 116.178043 -222.126044)
			(xy 116.148019 -222.170081) (xy 116.111767 -222.209152) (xy 116.070096 -222.242383) (xy 116.023938 -222.269032)
			(xy 115.974324 -222.288504) (xy 115.922362 -222.300364) (xy 115.869212 -222.304348) (xy 115.816062 -222.300364)
			(xy 115.7641 -222.288504) (xy 115.714486 -222.269032) (xy 115.668328 -222.242383) (xy 115.626657 -222.209152)
			(xy 115.590405 -222.170081) (xy 115.560381 -222.126044) (xy 115.537255 -222.078023) (xy 115.521545 -222.027093)
			(xy 115.513602 -221.974389) (xy 115.513104 -221.94774) (xy 115.285774 -221.94774) (xy 115.285276 -221.974389)
			(xy 115.277333 -222.027093) (xy 115.261623 -222.078023) (xy 115.238497 -222.126044) (xy 115.208473 -222.170081)
			(xy 115.172221 -222.209152) (xy 115.13055 -222.242383) (xy 115.084392 -222.269032) (xy 115.034778 -222.288504)
			(xy 114.982816 -222.300364) (xy 114.929666 -222.304348) (xy 114.876516 -222.300364) (xy 114.824554 -222.288504)
			(xy 114.77494 -222.269032) (xy 114.728782 -222.242383) (xy 114.687111 -222.209152) (xy 114.650859 -222.170081)
			(xy 114.620835 -222.126044) (xy 114.597709 -222.078023) (xy 114.581999 -222.027093) (xy 114.574056 -221.974389)
			(xy 114.345476 -221.974389) (xy 114.337533 -222.027093) (xy 114.321823 -222.078023) (xy 114.298697 -222.126044)
			(xy 114.268673 -222.170081) (xy 114.232421 -222.209152) (xy 114.19075 -222.242383) (xy 114.144592 -222.269032)
			(xy 114.094978 -222.288504) (xy 114.043016 -222.300364) (xy 113.989866 -222.304348) (xy 113.936716 -222.300364)
			(xy 113.884754 -222.288504) (xy 113.83514 -222.269032) (xy 113.788982 -222.242383) (xy 113.747311 -222.209152)
			(xy 113.711059 -222.170081) (xy 113.681035 -222.126044) (xy 113.657909 -222.078023) (xy 113.642199 -222.027093)
			(xy 113.634256 -221.974389) (xy 113.633758 -221.94774) (xy 113.40592 -221.94774) (xy 113.405422 -221.974389)
			(xy 113.397479 -222.027093) (xy 113.381769 -222.078023) (xy 113.358643 -222.126044) (xy 113.328619 -222.170081)
			(xy 113.292367 -222.209152) (xy 113.250696 -222.242383) (xy 113.204538 -222.269032) (xy 113.154924 -222.288504)
			(xy 113.102962 -222.300364) (xy 113.049812 -222.304348) (xy 112.996662 -222.300364) (xy 112.9447 -222.288504)
			(xy 112.895086 -222.269032) (xy 112.848928 -222.242383) (xy 112.807257 -222.209152) (xy 112.771005 -222.170081)
			(xy 112.740981 -222.126044) (xy 112.717855 -222.078023) (xy 112.702145 -222.027093) (xy 112.694202 -221.974389)
			(xy 112.465622 -221.974389) (xy 112.457679 -222.027093) (xy 112.441969 -222.078023) (xy 112.418843 -222.126044)
			(xy 112.388819 -222.170081) (xy 112.352567 -222.209152) (xy 112.310896 -222.242383) (xy 112.264738 -222.269032)
			(xy 112.215124 -222.288504) (xy 112.163162 -222.300364) (xy 112.110012 -222.304348) (xy 112.056862 -222.300364)
			(xy 112.0049 -222.288504) (xy 111.955286 -222.269032) (xy 111.909128 -222.242383) (xy 111.867457 -222.209152)
			(xy 111.831205 -222.170081) (xy 111.801181 -222.126044) (xy 111.778055 -222.078023) (xy 111.762345 -222.027093)
			(xy 111.754402 -221.974389) (xy 111.753904 -221.94774) (xy 111.526574 -221.94774) (xy 111.526076 -221.974389)
			(xy 111.518133 -222.027093) (xy 111.502423 -222.078023) (xy 111.479297 -222.126044) (xy 111.449273 -222.170081)
			(xy 111.413021 -222.209152) (xy 111.37135 -222.242383) (xy 111.325192 -222.269032) (xy 111.275578 -222.288504)
			(xy 111.223616 -222.300364) (xy 111.170466 -222.304348) (xy 111.117316 -222.300364) (xy 111.065354 -222.288504)
			(xy 111.01574 -222.269032) (xy 110.969582 -222.242383) (xy 110.927911 -222.209152) (xy 110.891659 -222.170081)
			(xy 110.861635 -222.126044) (xy 110.838509 -222.078023) (xy 110.822799 -222.027093) (xy 110.814856 -221.974389)
			(xy 110.586276 -221.974389) (xy 110.578333 -222.027093) (xy 110.562623 -222.078023) (xy 110.539497 -222.126044)
			(xy 110.509473 -222.170081) (xy 110.473221 -222.209152) (xy 110.43155 -222.242383) (xy 110.385392 -222.269032)
			(xy 110.335778 -222.288504) (xy 110.283816 -222.300364) (xy 110.230666 -222.304348) (xy 110.177516 -222.300364)
			(xy 110.125554 -222.288504) (xy 110.07594 -222.269032) (xy 110.029782 -222.242383) (xy 109.988111 -222.209152)
			(xy 109.951859 -222.170081) (xy 109.921835 -222.126044) (xy 109.898709 -222.078023) (xy 109.882999 -222.027093)
			(xy 109.875056 -221.974389) (xy 109.874558 -221.94774) (xy 109.64672 -221.94774) (xy 109.646222 -221.974389)
			(xy 109.638279 -222.027093) (xy 109.622569 -222.078023) (xy 109.599443 -222.126044) (xy 109.569419 -222.170081)
			(xy 109.533167 -222.209152) (xy 109.491496 -222.242383) (xy 109.445338 -222.269032) (xy 109.395724 -222.288504)
			(xy 109.343762 -222.300364) (xy 109.290612 -222.304348) (xy 109.237462 -222.300364) (xy 109.1855 -222.288504)
			(xy 109.135886 -222.269032) (xy 109.089728 -222.242383) (xy 109.048057 -222.209152) (xy 109.011805 -222.170081)
			(xy 108.981781 -222.126044) (xy 108.958655 -222.078023) (xy 108.942945 -222.027093) (xy 108.935002 -221.974389)
			(xy 108.706422 -221.974389) (xy 108.698479 -222.027093) (xy 108.682769 -222.078023) (xy 108.659643 -222.126044)
			(xy 108.629619 -222.170081) (xy 108.593367 -222.209152) (xy 108.551696 -222.242383) (xy 108.505538 -222.269032)
			(xy 108.455924 -222.288504) (xy 108.403962 -222.300364) (xy 108.350812 -222.304348) (xy 108.297662 -222.300364)
			(xy 108.2457 -222.288504) (xy 108.196086 -222.269032) (xy 108.149928 -222.242383) (xy 108.108257 -222.209152)
			(xy 108.072005 -222.170081) (xy 108.041981 -222.126044) (xy 108.018855 -222.078023) (xy 108.003145 -222.027093)
			(xy 107.995202 -221.974389) (xy 107.994704 -221.94774) (xy 107.76712 -221.94774) (xy 107.766622 -221.974389)
			(xy 107.758679 -222.027093) (xy 107.742969 -222.078023) (xy 107.719843 -222.126044) (xy 107.689819 -222.170081)
			(xy 107.653567 -222.209152) (xy 107.611896 -222.242383) (xy 107.565738 -222.269032) (xy 107.516124 -222.288504)
			(xy 107.464162 -222.300364) (xy 107.411012 -222.304348) (xy 107.357862 -222.300364) (xy 107.3059 -222.288504)
			(xy 107.256286 -222.269032) (xy 107.210128 -222.242383) (xy 107.168457 -222.209152) (xy 107.132205 -222.170081)
			(xy 107.102181 -222.126044) (xy 107.079055 -222.078023) (xy 107.063345 -222.027093) (xy 107.055402 -221.974389)
			(xy 106.826822 -221.974389) (xy 106.818879 -222.027093) (xy 106.803169 -222.078023) (xy 106.780043 -222.126044)
			(xy 106.750019 -222.170081) (xy 106.713767 -222.209152) (xy 106.672096 -222.242383) (xy 106.625938 -222.269032)
			(xy 106.576324 -222.288504) (xy 106.524362 -222.300364) (xy 106.471212 -222.304348) (xy 106.418062 -222.300364)
			(xy 106.3661 -222.288504) (xy 106.316486 -222.269032) (xy 106.270328 -222.242383) (xy 106.228657 -222.209152)
			(xy 106.192405 -222.170081) (xy 106.162381 -222.126044) (xy 106.139255 -222.078023) (xy 106.123545 -222.027093)
			(xy 106.115602 -221.974389) (xy 106.115104 -221.94774) (xy 105.888131 -221.94774) (xy 105.884059 -222.001444)
			(xy 105.871929 -222.053954) (xy 105.85202 -222.104035) (xy 105.824788 -222.150542) (xy 105.790856 -222.192411)
			(xy 105.750999 -222.228686) (xy 105.706129 -222.258538) (xy 105.657271 -222.281283) (xy 105.605542 -222.296402)
			(xy 105.57891 -222.300546) (xy 105.534968 -222.306642) (xy 105.534968 -222.788205) (xy 105.645956 -222.788205)
			(xy 105.645956 -222.734907) (xy 105.653899 -222.682203) (xy 105.669609 -222.631273) (xy 105.692735 -222.583252)
			(xy 105.722759 -222.539215) (xy 105.759011 -222.500144) (xy 105.800682 -222.466913) (xy 105.84684 -222.440264)
			(xy 105.896454 -222.420792) (xy 105.948416 -222.408932) (xy 106.001566 -222.404949) (xy 106.054716 -222.408932)
			(xy 106.106678 -222.420792) (xy 106.156292 -222.440264) (xy 106.20245 -222.466913) (xy 106.244121 -222.500144)
			(xy 106.280373 -222.539215) (xy 106.310397 -222.583252) (xy 106.333523 -222.631273) (xy 106.349233 -222.682203)
			(xy 106.357176 -222.734907) (xy 106.357674 -222.761556) (xy 106.357176 -222.788205) (xy 106.585756 -222.788205)
			(xy 106.585756 -222.734907) (xy 106.593699 -222.682203) (xy 106.609409 -222.631273) (xy 106.632535 -222.583252)
			(xy 106.662559 -222.539215) (xy 106.698811 -222.500144) (xy 106.740482 -222.466913) (xy 106.78664 -222.440264)
			(xy 106.836254 -222.420792) (xy 106.888216 -222.408932) (xy 106.941366 -222.404949) (xy 106.994516 -222.408932)
			(xy 107.046478 -222.420792) (xy 107.096092 -222.440264) (xy 107.14225 -222.466913) (xy 107.183921 -222.500144)
			(xy 107.220173 -222.539215) (xy 107.250197 -222.583252) (xy 107.273323 -222.631273) (xy 107.289033 -222.682203)
			(xy 107.296976 -222.734907) (xy 107.297474 -222.761556) (xy 107.296976 -222.788205) (xy 107.525556 -222.788205)
			(xy 107.525556 -222.734907) (xy 107.533499 -222.682203) (xy 107.549209 -222.631273) (xy 107.572335 -222.583252)
			(xy 107.602359 -222.539215) (xy 107.638611 -222.500144) (xy 107.680282 -222.466913) (xy 107.72644 -222.440264)
			(xy 107.776054 -222.420792) (xy 107.828016 -222.408932) (xy 107.881166 -222.404949) (xy 107.934316 -222.408932)
			(xy 107.986278 -222.420792) (xy 108.035892 -222.440264) (xy 108.08205 -222.466913) (xy 108.123721 -222.500144)
			(xy 108.159973 -222.539215) (xy 108.189997 -222.583252) (xy 108.213123 -222.631273) (xy 108.228833 -222.682203)
			(xy 108.236776 -222.734907) (xy 108.237274 -222.761556) (xy 108.236776 -222.788205) (xy 108.465356 -222.788205)
			(xy 108.465356 -222.734907) (xy 108.473299 -222.682203) (xy 108.489009 -222.631273) (xy 108.512135 -222.583252)
			(xy 108.542159 -222.539215) (xy 108.578411 -222.500144) (xy 108.620082 -222.466913) (xy 108.66624 -222.440264)
			(xy 108.715854 -222.420792) (xy 108.767816 -222.408932) (xy 108.820966 -222.404949) (xy 108.874116 -222.408932)
			(xy 108.926078 -222.420792) (xy 108.975692 -222.440264) (xy 109.02185 -222.466913) (xy 109.063521 -222.500144)
			(xy 109.099773 -222.539215) (xy 109.129797 -222.583252) (xy 109.152923 -222.631273) (xy 109.168633 -222.682203)
			(xy 109.176576 -222.734907) (xy 109.177074 -222.761556) (xy 109.176576 -222.788205) (xy 109.405156 -222.788205)
			(xy 109.405156 -222.734907) (xy 109.413099 -222.682203) (xy 109.428809 -222.631273) (xy 109.451935 -222.583252)
			(xy 109.481959 -222.539215) (xy 109.518211 -222.500144) (xy 109.559882 -222.466913) (xy 109.60604 -222.440264)
			(xy 109.655654 -222.420792) (xy 109.707616 -222.408932) (xy 109.760766 -222.404949) (xy 109.813916 -222.408932)
			(xy 109.865878 -222.420792) (xy 109.915492 -222.440264) (xy 109.96165 -222.466913) (xy 110.003321 -222.500144)
			(xy 110.039573 -222.539215) (xy 110.069597 -222.583252) (xy 110.092723 -222.631273) (xy 110.108433 -222.682203)
			(xy 110.116376 -222.734907) (xy 110.116874 -222.761556) (xy 110.116376 -222.788205) (xy 110.344956 -222.788205)
			(xy 110.344956 -222.734907) (xy 110.352899 -222.682203) (xy 110.368609 -222.631273) (xy 110.391735 -222.583252)
			(xy 110.421759 -222.539215) (xy 110.458011 -222.500144) (xy 110.499682 -222.466913) (xy 110.54584 -222.440264)
			(xy 110.595454 -222.420792) (xy 110.647416 -222.408932) (xy 110.700566 -222.404949) (xy 110.753716 -222.408932)
			(xy 110.805678 -222.420792) (xy 110.855292 -222.440264) (xy 110.90145 -222.466913) (xy 110.943121 -222.500144)
			(xy 110.979373 -222.539215) (xy 111.009397 -222.583252) (xy 111.032523 -222.631273) (xy 111.048233 -222.682203)
			(xy 111.056176 -222.734907) (xy 111.056674 -222.761556) (xy 111.056176 -222.788205) (xy 111.284756 -222.788205)
			(xy 111.284756 -222.734907) (xy 111.292699 -222.682203) (xy 111.308409 -222.631273) (xy 111.331535 -222.583252)
			(xy 111.361559 -222.539215) (xy 111.397811 -222.500144) (xy 111.439482 -222.466913) (xy 111.48564 -222.440264)
			(xy 111.535254 -222.420792) (xy 111.587216 -222.408932) (xy 111.640366 -222.404949) (xy 111.693516 -222.408932)
			(xy 111.745478 -222.420792) (xy 111.795092 -222.440264) (xy 111.84125 -222.466913) (xy 111.882921 -222.500144)
			(xy 111.919173 -222.539215) (xy 111.949197 -222.583252) (xy 111.972323 -222.631273) (xy 111.988033 -222.682203)
			(xy 111.995976 -222.734907) (xy 111.996474 -222.761556) (xy 111.995976 -222.788205) (xy 112.224556 -222.788205)
			(xy 112.224556 -222.734907) (xy 112.232499 -222.682203) (xy 112.248209 -222.631273) (xy 112.271335 -222.583252)
			(xy 112.301359 -222.539215) (xy 112.337611 -222.500144) (xy 112.379282 -222.466913) (xy 112.42544 -222.440264)
			(xy 112.475054 -222.420792) (xy 112.527016 -222.408932) (xy 112.580166 -222.404949) (xy 112.633316 -222.408932)
			(xy 112.685278 -222.420792) (xy 112.734892 -222.440264) (xy 112.78105 -222.466913) (xy 112.822721 -222.500144)
			(xy 112.858973 -222.539215) (xy 112.888997 -222.583252) (xy 112.912123 -222.631273) (xy 112.927833 -222.682203)
			(xy 112.935776 -222.734907) (xy 112.936274 -222.761556) (xy 112.935776 -222.788205) (xy 113.164356 -222.788205)
			(xy 113.164356 -222.734907) (xy 113.172299 -222.682203) (xy 113.188009 -222.631273) (xy 113.211135 -222.583252)
			(xy 113.241159 -222.539215) (xy 113.277411 -222.500144) (xy 113.319082 -222.466913) (xy 113.36524 -222.440264)
			(xy 113.414854 -222.420792) (xy 113.466816 -222.408932) (xy 113.519966 -222.404949) (xy 113.573116 -222.408932)
			(xy 113.625078 -222.420792) (xy 113.674692 -222.440264) (xy 113.72085 -222.466913) (xy 113.762521 -222.500144)
			(xy 113.798773 -222.539215) (xy 113.828797 -222.583252) (xy 113.851923 -222.631273) (xy 113.867633 -222.682203)
			(xy 113.875576 -222.734907) (xy 113.876074 -222.761556) (xy 113.875576 -222.788205) (xy 114.104156 -222.788205)
			(xy 114.104156 -222.734907) (xy 114.112099 -222.682203) (xy 114.127809 -222.631273) (xy 114.150935 -222.583252)
			(xy 114.180959 -222.539215) (xy 114.217211 -222.500144) (xy 114.258882 -222.466913) (xy 114.30504 -222.440264)
			(xy 114.354654 -222.420792) (xy 114.406616 -222.408932) (xy 114.459766 -222.404949) (xy 114.512916 -222.408932)
			(xy 114.564878 -222.420792) (xy 114.614492 -222.440264) (xy 114.66065 -222.466913) (xy 114.702321 -222.500144)
			(xy 114.738573 -222.539215) (xy 114.768597 -222.583252) (xy 114.791723 -222.631273) (xy 114.807433 -222.682203)
			(xy 114.815376 -222.734907) (xy 114.815874 -222.761556) (xy 114.815376 -222.788205) (xy 115.043956 -222.788205)
			(xy 115.043956 -222.734907) (xy 115.051899 -222.682203) (xy 115.067609 -222.631273) (xy 115.090735 -222.583252)
			(xy 115.120759 -222.539215) (xy 115.157011 -222.500144) (xy 115.198682 -222.466913) (xy 115.24484 -222.440264)
			(xy 115.294454 -222.420792) (xy 115.346416 -222.408932) (xy 115.399566 -222.404949) (xy 115.452716 -222.408932)
			(xy 115.504678 -222.420792) (xy 115.554292 -222.440264) (xy 115.60045 -222.466913) (xy 115.642121 -222.500144)
			(xy 115.678373 -222.539215) (xy 115.708397 -222.583252) (xy 115.731523 -222.631273) (xy 115.747233 -222.682203)
			(xy 115.755176 -222.734907) (xy 115.755674 -222.761556) (xy 115.755176 -222.788205) (xy 115.983756 -222.788205)
			(xy 115.983756 -222.734907) (xy 115.991699 -222.682203) (xy 116.007409 -222.631273) (xy 116.030535 -222.583252)
			(xy 116.060559 -222.539215) (xy 116.096811 -222.500144) (xy 116.138482 -222.466913) (xy 116.18464 -222.440264)
			(xy 116.234254 -222.420792) (xy 116.286216 -222.408932) (xy 116.339366 -222.404949) (xy 116.392516 -222.408932)
			(xy 116.444478 -222.420792) (xy 116.494092 -222.440264) (xy 116.54025 -222.466913) (xy 116.581921 -222.500144)
			(xy 116.618173 -222.539215) (xy 116.648197 -222.583252) (xy 116.671323 -222.631273) (xy 116.687033 -222.682203)
			(xy 116.694976 -222.734907) (xy 116.695474 -222.761556) (xy 116.694976 -222.788205) (xy 116.923556 -222.788205)
			(xy 116.923556 -222.734907) (xy 116.931499 -222.682203) (xy 116.947209 -222.631273) (xy 116.970335 -222.583252)
			(xy 117.000359 -222.539215) (xy 117.036611 -222.500144) (xy 117.078282 -222.466913) (xy 117.12444 -222.440264)
			(xy 117.174054 -222.420792) (xy 117.226016 -222.408932) (xy 117.279166 -222.404949) (xy 117.332316 -222.408932)
			(xy 117.384278 -222.420792) (xy 117.433892 -222.440264) (xy 117.48005 -222.466913) (xy 117.521721 -222.500144)
			(xy 117.557973 -222.539215) (xy 117.587997 -222.583252) (xy 117.611123 -222.631273) (xy 117.626833 -222.682203)
			(xy 117.634776 -222.734907) (xy 117.635274 -222.761556) (xy 117.634776 -222.788205) (xy 117.863356 -222.788205)
			(xy 117.863356 -222.734907) (xy 117.871299 -222.682203) (xy 117.887009 -222.631273) (xy 117.910135 -222.583252)
			(xy 117.940159 -222.539215) (xy 117.976411 -222.500144) (xy 118.018082 -222.466913) (xy 118.06424 -222.440264)
			(xy 118.113854 -222.420792) (xy 118.165816 -222.408932) (xy 118.218966 -222.404949) (xy 118.272116 -222.408932)
			(xy 118.324078 -222.420792) (xy 118.373692 -222.440264) (xy 118.41985 -222.466913) (xy 118.461521 -222.500144)
			(xy 118.497773 -222.539215) (xy 118.527797 -222.583252) (xy 118.550923 -222.631273) (xy 118.566633 -222.682203)
			(xy 118.574576 -222.734907) (xy 118.575074 -222.761556) (xy 118.574576 -222.788205) (xy 118.566633 -222.840909)
			(xy 118.550923 -222.891839) (xy 118.527797 -222.93986) (xy 118.497773 -222.983897) (xy 118.461521 -223.022968)
			(xy 118.41985 -223.056199) (xy 118.373692 -223.082848) (xy 118.324078 -223.10232) (xy 118.272116 -223.11418)
			(xy 118.218966 -223.118164) (xy 118.165816 -223.11418) (xy 118.113854 -223.10232) (xy 118.06424 -223.082848)
			(xy 118.018082 -223.056199) (xy 117.976411 -223.022968) (xy 117.940159 -222.983897) (xy 117.910135 -222.93986)
			(xy 117.887009 -222.891839) (xy 117.871299 -222.840909) (xy 117.863356 -222.788205) (xy 117.634776 -222.788205)
			(xy 117.626833 -222.840909) (xy 117.611123 -222.891839) (xy 117.587997 -222.93986) (xy 117.557973 -222.983897)
			(xy 117.521721 -223.022968) (xy 117.48005 -223.056199) (xy 117.433892 -223.082848) (xy 117.384278 -223.10232)
			(xy 117.332316 -223.11418) (xy 117.279166 -223.118164) (xy 117.226016 -223.11418) (xy 117.174054 -223.10232)
			(xy 117.12444 -223.082848) (xy 117.078282 -223.056199) (xy 117.036611 -223.022968) (xy 117.000359 -222.983897)
			(xy 116.970335 -222.93986) (xy 116.947209 -222.891839) (xy 116.931499 -222.840909) (xy 116.923556 -222.788205)
			(xy 116.694976 -222.788205) (xy 116.687033 -222.840909) (xy 116.671323 -222.891839) (xy 116.648197 -222.93986)
			(xy 116.618173 -222.983897) (xy 116.581921 -223.022968) (xy 116.54025 -223.056199) (xy 116.494092 -223.082848)
			(xy 116.444478 -223.10232) (xy 116.392516 -223.11418) (xy 116.339366 -223.118164) (xy 116.286216 -223.11418)
			(xy 116.234254 -223.10232) (xy 116.18464 -223.082848) (xy 116.138482 -223.056199) (xy 116.096811 -223.022968)
			(xy 116.060559 -222.983897) (xy 116.030535 -222.93986) (xy 116.007409 -222.891839) (xy 115.991699 -222.840909)
			(xy 115.983756 -222.788205) (xy 115.755176 -222.788205) (xy 115.747233 -222.840909) (xy 115.731523 -222.891839)
			(xy 115.708397 -222.93986) (xy 115.678373 -222.983897) (xy 115.642121 -223.022968) (xy 115.60045 -223.056199)
			(xy 115.554292 -223.082848) (xy 115.504678 -223.10232) (xy 115.452716 -223.11418) (xy 115.399566 -223.118164)
			(xy 115.346416 -223.11418) (xy 115.294454 -223.10232) (xy 115.24484 -223.082848) (xy 115.198682 -223.056199)
			(xy 115.157011 -223.022968) (xy 115.120759 -222.983897) (xy 115.090735 -222.93986) (xy 115.067609 -222.891839)
			(xy 115.051899 -222.840909) (xy 115.043956 -222.788205) (xy 114.815376 -222.788205) (xy 114.807433 -222.840909)
			(xy 114.791723 -222.891839) (xy 114.768597 -222.93986) (xy 114.738573 -222.983897) (xy 114.702321 -223.022968)
			(xy 114.66065 -223.056199) (xy 114.614492 -223.082848) (xy 114.564878 -223.10232) (xy 114.512916 -223.11418)
			(xy 114.459766 -223.118164) (xy 114.406616 -223.11418) (xy 114.354654 -223.10232) (xy 114.30504 -223.082848)
			(xy 114.258882 -223.056199) (xy 114.217211 -223.022968) (xy 114.180959 -222.983897) (xy 114.150935 -222.93986)
			(xy 114.127809 -222.891839) (xy 114.112099 -222.840909) (xy 114.104156 -222.788205) (xy 113.875576 -222.788205)
			(xy 113.867633 -222.840909) (xy 113.851923 -222.891839) (xy 113.828797 -222.93986) (xy 113.798773 -222.983897)
			(xy 113.762521 -223.022968) (xy 113.72085 -223.056199) (xy 113.674692 -223.082848) (xy 113.625078 -223.10232)
			(xy 113.573116 -223.11418) (xy 113.519966 -223.118164) (xy 113.466816 -223.11418) (xy 113.414854 -223.10232)
			(xy 113.36524 -223.082848) (xy 113.319082 -223.056199) (xy 113.277411 -223.022968) (xy 113.241159 -222.983897)
			(xy 113.211135 -222.93986) (xy 113.188009 -222.891839) (xy 113.172299 -222.840909) (xy 113.164356 -222.788205)
			(xy 112.935776 -222.788205) (xy 112.927833 -222.840909) (xy 112.912123 -222.891839) (xy 112.888997 -222.93986)
			(xy 112.858973 -222.983897) (xy 112.822721 -223.022968) (xy 112.78105 -223.056199) (xy 112.734892 -223.082848)
			(xy 112.685278 -223.10232) (xy 112.633316 -223.11418) (xy 112.580166 -223.118164) (xy 112.527016 -223.11418)
			(xy 112.475054 -223.10232) (xy 112.42544 -223.082848) (xy 112.379282 -223.056199) (xy 112.337611 -223.022968)
			(xy 112.301359 -222.983897) (xy 112.271335 -222.93986) (xy 112.248209 -222.891839) (xy 112.232499 -222.840909)
			(xy 112.224556 -222.788205) (xy 111.995976 -222.788205) (xy 111.988033 -222.840909) (xy 111.972323 -222.891839)
			(xy 111.949197 -222.93986) (xy 111.919173 -222.983897) (xy 111.882921 -223.022968) (xy 111.84125 -223.056199)
			(xy 111.795092 -223.082848) (xy 111.745478 -223.10232) (xy 111.693516 -223.11418) (xy 111.640366 -223.118164)
			(xy 111.587216 -223.11418) (xy 111.535254 -223.10232) (xy 111.48564 -223.082848) (xy 111.439482 -223.056199)
			(xy 111.397811 -223.022968) (xy 111.361559 -222.983897) (xy 111.331535 -222.93986) (xy 111.308409 -222.891839)
			(xy 111.292699 -222.840909) (xy 111.284756 -222.788205) (xy 111.056176 -222.788205) (xy 111.048233 -222.840909)
			(xy 111.032523 -222.891839) (xy 111.009397 -222.93986) (xy 110.979373 -222.983897) (xy 110.943121 -223.022968)
			(xy 110.90145 -223.056199) (xy 110.855292 -223.082848) (xy 110.805678 -223.10232) (xy 110.753716 -223.11418)
			(xy 110.700566 -223.118164) (xy 110.647416 -223.11418) (xy 110.595454 -223.10232) (xy 110.54584 -223.082848)
			(xy 110.499682 -223.056199) (xy 110.458011 -223.022968) (xy 110.421759 -222.983897) (xy 110.391735 -222.93986)
			(xy 110.368609 -222.891839) (xy 110.352899 -222.840909) (xy 110.344956 -222.788205) (xy 110.116376 -222.788205)
			(xy 110.108433 -222.840909) (xy 110.092723 -222.891839) (xy 110.069597 -222.93986) (xy 110.039573 -222.983897)
			(xy 110.003321 -223.022968) (xy 109.96165 -223.056199) (xy 109.915492 -223.082848) (xy 109.865878 -223.10232)
			(xy 109.813916 -223.11418) (xy 109.760766 -223.118164) (xy 109.707616 -223.11418) (xy 109.655654 -223.10232)
			(xy 109.60604 -223.082848) (xy 109.559882 -223.056199) (xy 109.518211 -223.022968) (xy 109.481959 -222.983897)
			(xy 109.451935 -222.93986) (xy 109.428809 -222.891839) (xy 109.413099 -222.840909) (xy 109.405156 -222.788205)
			(xy 109.176576 -222.788205) (xy 109.168633 -222.840909) (xy 109.152923 -222.891839) (xy 109.129797 -222.93986)
			(xy 109.099773 -222.983897) (xy 109.063521 -223.022968) (xy 109.02185 -223.056199) (xy 108.975692 -223.082848)
			(xy 108.926078 -223.10232) (xy 108.874116 -223.11418) (xy 108.820966 -223.118164) (xy 108.767816 -223.11418)
			(xy 108.715854 -223.10232) (xy 108.66624 -223.082848) (xy 108.620082 -223.056199) (xy 108.578411 -223.022968)
			(xy 108.542159 -222.983897) (xy 108.512135 -222.93986) (xy 108.489009 -222.891839) (xy 108.473299 -222.840909)
			(xy 108.465356 -222.788205) (xy 108.236776 -222.788205) (xy 108.228833 -222.840909) (xy 108.213123 -222.891839)
			(xy 108.189997 -222.93986) (xy 108.159973 -222.983897) (xy 108.123721 -223.022968) (xy 108.08205 -223.056199)
			(xy 108.035892 -223.082848) (xy 107.986278 -223.10232) (xy 107.934316 -223.11418) (xy 107.881166 -223.118164)
			(xy 107.828016 -223.11418) (xy 107.776054 -223.10232) (xy 107.72644 -223.082848) (xy 107.680282 -223.056199)
			(xy 107.638611 -223.022968) (xy 107.602359 -222.983897) (xy 107.572335 -222.93986) (xy 107.549209 -222.891839)
			(xy 107.533499 -222.840909) (xy 107.525556 -222.788205) (xy 107.296976 -222.788205) (xy 107.289033 -222.840909)
			(xy 107.273323 -222.891839) (xy 107.250197 -222.93986) (xy 107.220173 -222.983897) (xy 107.183921 -223.022968)
			(xy 107.14225 -223.056199) (xy 107.096092 -223.082848) (xy 107.046478 -223.10232) (xy 106.994516 -223.11418)
			(xy 106.941366 -223.118164) (xy 106.888216 -223.11418) (xy 106.836254 -223.10232) (xy 106.78664 -223.082848)
			(xy 106.740482 -223.056199) (xy 106.698811 -223.022968) (xy 106.662559 -222.983897) (xy 106.632535 -222.93986)
			(xy 106.609409 -222.891839) (xy 106.593699 -222.840909) (xy 106.585756 -222.788205) (xy 106.357176 -222.788205)
			(xy 106.349233 -222.840909) (xy 106.333523 -222.891839) (xy 106.310397 -222.93986) (xy 106.280373 -222.983897)
			(xy 106.244121 -223.022968) (xy 106.20245 -223.056199) (xy 106.156292 -223.082848) (xy 106.106678 -223.10232)
			(xy 106.054716 -223.11418) (xy 106.001566 -223.118164) (xy 105.948416 -223.11418) (xy 105.896454 -223.10232)
			(xy 105.84684 -223.082848) (xy 105.800682 -223.056199) (xy 105.759011 -223.022968) (xy 105.722759 -222.983897)
			(xy 105.692735 -222.93986) (xy 105.669609 -222.891839) (xy 105.653899 -222.840909) (xy 105.645956 -222.788205)
			(xy 105.534968 -222.788205) (xy 105.534968 -223.216724) (xy 105.57891 -223.22282) (xy 105.605554 -223.226887)
			(xy 105.657284 -223.242007) (xy 105.706143 -223.264754) (xy 105.751015 -223.294608) (xy 105.790872 -223.330886)
			(xy 105.824805 -223.372758) (xy 105.852036 -223.419267) (xy 105.871945 -223.46935) (xy 105.884074 -223.521863)
			(xy 105.888148 -223.575603) (xy 105.886126 -223.602275) (xy 106.115856 -223.602275) (xy 106.115856 -223.548977)
			(xy 106.123799 -223.496273) (xy 106.139509 -223.445343) (xy 106.162635 -223.397322) (xy 106.192659 -223.353285)
			(xy 106.228911 -223.314214) (xy 106.270582 -223.280983) (xy 106.31674 -223.254334) (xy 106.366354 -223.234862)
			(xy 106.418316 -223.223002) (xy 106.471466 -223.219019) (xy 106.524616 -223.223002) (xy 106.576578 -223.234862)
			(xy 106.626192 -223.254334) (xy 106.67235 -223.280983) (xy 106.714021 -223.314214) (xy 106.750273 -223.353285)
			(xy 106.780297 -223.397322) (xy 106.803423 -223.445343) (xy 106.819133 -223.496273) (xy 106.827076 -223.548977)
			(xy 106.827574 -223.575626) (xy 106.827076 -223.602275) (xy 106.819133 -223.654979) (xy 106.803423 -223.705909)
			(xy 106.780297 -223.75393) (xy 106.750273 -223.797967) (xy 106.714021 -223.837038) (xy 106.67235 -223.870269)
			(xy 106.626192 -223.896918) (xy 106.576578 -223.91639) (xy 106.524616 -223.92825) (xy 106.471466 -223.932234)
			(xy 106.418316 -223.92825) (xy 106.366354 -223.91639) (xy 106.31674 -223.896918) (xy 106.270582 -223.870269)
			(xy 106.228911 -223.837038) (xy 106.192659 -223.797967) (xy 106.162635 -223.75393) (xy 106.139509 -223.705909)
			(xy 106.123799 -223.654979) (xy 106.115856 -223.602275) (xy 105.886126 -223.602275) (xy 105.884073 -223.629344)
			(xy 105.871943 -223.681856) (xy 105.852033 -223.731939) (xy 105.824801 -223.778448) (xy 105.790868 -223.820319)
			(xy 105.751009 -223.856596) (xy 105.706137 -223.886449) (xy 105.657278 -223.909195) (xy 105.605547 -223.924315)
			(xy 105.57891 -223.928432) (xy 105.55351 -223.931988) (xy 105.534968 -223.964246) (xy 105.534968 -224.389442)
			(xy 105.645458 -224.389442) (xy 105.645956 -224.362793) (xy 105.653899 -224.310089) (xy 105.669609 -224.259159)
			(xy 105.692735 -224.211138) (xy 105.722759 -224.167101) (xy 105.759011 -224.12803) (xy 105.800682 -224.094799)
			(xy 105.84684 -224.06815) (xy 105.896454 -224.048678) (xy 105.948416 -224.036818) (xy 106.001566 -224.032835)
			(xy 106.054716 -224.036818) (xy 106.106678 -224.048678) (xy 106.156292 -224.06815) (xy 106.20245 -224.094799)
			(xy 106.244121 -224.12803) (xy 106.280373 -224.167101) (xy 106.310397 -224.211138) (xy 106.333523 -224.259159)
			(xy 106.349233 -224.310089) (xy 106.357176 -224.362793) (xy 106.357674 -224.389442) (xy 106.585258 -224.389442)
			(xy 106.585712 -224.363814) (xy 106.593043 -224.313084) (xy 106.607572 -224.26393) (xy 106.629 -224.217367)
			(xy 106.656884 -224.174359) (xy 106.690647 -224.135794) (xy 106.729592 -224.102469) (xy 106.772913 -224.075074)
			(xy 106.819715 -224.054174) (xy 106.86903 -224.040202) (xy 106.894376 -224.036382) (xy 106.919014 -224.03308)
			(xy 107.091226 -223.734376) (xy 107.081828 -223.711516) (xy 107.07332 -223.689881) (xy 107.061329 -223.644965)
			(xy 107.055281 -223.598871) (xy 107.054904 -223.575626) (xy 107.055402 -223.548977) (xy 107.063345 -223.496273)
			(xy 107.079055 -223.445343) (xy 107.102181 -223.397322) (xy 107.132205 -223.353285) (xy 107.168457 -223.314214)
			(xy 107.210128 -223.280983) (xy 107.256286 -223.254334) (xy 107.3059 -223.234862) (xy 107.357862 -223.223002)
			(xy 107.411012 -223.219019) (xy 107.464162 -223.223002) (xy 107.516124 -223.234862) (xy 107.565738 -223.254334)
			(xy 107.611896 -223.280983) (xy 107.653567 -223.314214) (xy 107.689819 -223.353285) (xy 107.719843 -223.397322)
			(xy 107.742969 -223.445343) (xy 107.758679 -223.496273) (xy 107.766622 -223.548977) (xy 107.76712 -223.575626)
			(xy 107.766747 -223.601257) (xy 107.7666 -223.602275) (xy 107.995456 -223.602275) (xy 107.995456 -223.548977)
			(xy 108.003399 -223.496273) (xy 108.019109 -223.445343) (xy 108.042235 -223.397322) (xy 108.072259 -223.353285)
			(xy 108.108511 -223.314214) (xy 108.150182 -223.280983) (xy 108.19634 -223.254334) (xy 108.245954 -223.234862)
			(xy 108.297916 -223.223002) (xy 108.351066 -223.219019) (xy 108.404216 -223.223002) (xy 108.456178 -223.234862)
			(xy 108.505792 -223.254334) (xy 108.55195 -223.280983) (xy 108.593621 -223.314214) (xy 108.629873 -223.353285)
			(xy 108.659897 -223.397322) (xy 108.683023 -223.445343) (xy 108.698733 -223.496273) (xy 108.706676 -223.548977)
			(xy 108.707174 -223.575626) (xy 108.706676 -223.602275) (xy 108.698733 -223.654979) (xy 108.683023 -223.705909)
			(xy 108.659897 -223.75393) (xy 108.629873 -223.797967) (xy 108.593621 -223.837038) (xy 108.55195 -223.870269)
			(xy 108.505792 -223.896918) (xy 108.456178 -223.91639) (xy 108.404216 -223.92825) (xy 108.351066 -223.932234)
			(xy 108.297916 -223.92825) (xy 108.245954 -223.91639) (xy 108.19634 -223.896918) (xy 108.150182 -223.870269)
			(xy 108.108511 -223.837038) (xy 108.072259 -223.797967) (xy 108.042235 -223.75393) (xy 108.019109 -223.705909)
			(xy 108.003399 -223.654979) (xy 107.995456 -223.602275) (xy 107.7666 -223.602275) (xy 107.759407 -223.651991)
			(xy 107.744868 -223.701148) (xy 107.72343 -223.747712) (xy 107.695537 -223.790721) (xy 107.661764 -223.829285)
			(xy 107.622811 -223.862608) (xy 107.579482 -223.890002) (xy 107.532673 -223.910899) (xy 107.483351 -223.924868)
			(xy 107.458002 -223.928686) (xy 107.43311 -223.931988) (xy 107.260898 -224.230438) (xy 107.27055 -224.253552)
			(xy 107.279078 -224.27518) (xy 107.291061 -224.3201) (xy 107.297101 -224.366197) (xy 107.297474 -224.389442)
			(xy 107.525058 -224.389442) (xy 107.525556 -224.362793) (xy 107.533499 -224.310089) (xy 107.549209 -224.259159)
			(xy 107.572335 -224.211138) (xy 107.602359 -224.167101) (xy 107.638611 -224.12803) (xy 107.680282 -224.094799)
			(xy 107.72644 -224.06815) (xy 107.776054 -224.048678) (xy 107.828016 -224.036818) (xy 107.881166 -224.032835)
			(xy 107.934316 -224.036818) (xy 107.986278 -224.048678) (xy 108.035892 -224.06815) (xy 108.08205 -224.094799)
			(xy 108.123721 -224.12803) (xy 108.159973 -224.167101) (xy 108.189997 -224.211138) (xy 108.213123 -224.259159)
			(xy 108.228833 -224.310089) (xy 108.236776 -224.362793) (xy 108.237274 -224.389442) (xy 108.464858 -224.389442)
			(xy 108.465312 -224.363814) (xy 108.472643 -224.313084) (xy 108.487172 -224.26393) (xy 108.5086 -224.217367)
			(xy 108.536484 -224.174359) (xy 108.570247 -224.135794) (xy 108.609192 -224.102469) (xy 108.652513 -224.075074)
			(xy 108.699315 -224.054174) (xy 108.74863 -224.040202) (xy 108.773976 -224.036382) (xy 108.798614 -224.03308)
			(xy 108.970826 -223.734376) (xy 108.961428 -223.711516) (xy 108.95292 -223.689881) (xy 108.940929 -223.644965)
			(xy 108.934881 -223.598871) (xy 108.934504 -223.575626) (xy 108.935002 -223.548977) (xy 108.942945 -223.496273)
			(xy 108.958655 -223.445343) (xy 108.981781 -223.397322) (xy 109.011805 -223.353285) (xy 109.048057 -223.314214)
			(xy 109.089728 -223.280983) (xy 109.135886 -223.254334) (xy 109.1855 -223.234862) (xy 109.237462 -223.223002)
			(xy 109.290612 -223.219019) (xy 109.343762 -223.223002) (xy 109.395724 -223.234862) (xy 109.445338 -223.254334)
			(xy 109.491496 -223.280983) (xy 109.533167 -223.314214) (xy 109.569419 -223.353285) (xy 109.599443 -223.397322)
			(xy 109.622569 -223.445343) (xy 109.638279 -223.496273) (xy 109.646222 -223.548977) (xy 109.64672 -223.575626)
			(xy 109.646347 -223.601257) (xy 109.6462 -223.602275) (xy 109.875056 -223.602275) (xy 109.875056 -223.548977)
			(xy 109.882999 -223.496273) (xy 109.898709 -223.445343) (xy 109.921835 -223.397322) (xy 109.951859 -223.353285)
			(xy 109.988111 -223.314214) (xy 110.029782 -223.280983) (xy 110.07594 -223.254334) (xy 110.125554 -223.234862)
			(xy 110.177516 -223.223002) (xy 110.230666 -223.219019) (xy 110.283816 -223.223002) (xy 110.335778 -223.234862)
			(xy 110.385392 -223.254334) (xy 110.43155 -223.280983) (xy 110.473221 -223.314214) (xy 110.509473 -223.353285)
			(xy 110.539497 -223.397322) (xy 110.562623 -223.445343) (xy 110.578333 -223.496273) (xy 110.586276 -223.548977)
			(xy 110.586774 -223.575626) (xy 110.586276 -223.602275) (xy 110.578333 -223.654979) (xy 110.562623 -223.705909)
			(xy 110.539497 -223.75393) (xy 110.509473 -223.797967) (xy 110.473221 -223.837038) (xy 110.43155 -223.870269)
			(xy 110.385392 -223.896918) (xy 110.335778 -223.91639) (xy 110.283816 -223.92825) (xy 110.230666 -223.932234)
			(xy 110.177516 -223.92825) (xy 110.125554 -223.91639) (xy 110.07594 -223.896918) (xy 110.029782 -223.870269)
			(xy 109.988111 -223.837038) (xy 109.951859 -223.797967) (xy 109.921835 -223.75393) (xy 109.898709 -223.705909)
			(xy 109.882999 -223.654979) (xy 109.875056 -223.602275) (xy 109.6462 -223.602275) (xy 109.639007 -223.651991)
			(xy 109.624468 -223.701148) (xy 109.60303 -223.747712) (xy 109.575137 -223.790721) (xy 109.541364 -223.829285)
			(xy 109.502411 -223.862608) (xy 109.459082 -223.890002) (xy 109.412273 -223.910899) (xy 109.362951 -223.924868)
			(xy 109.337602 -223.928686) (xy 109.31271 -223.931988) (xy 109.140498 -224.230438) (xy 109.15015 -224.253552)
			(xy 109.158678 -224.27518) (xy 109.170661 -224.3201) (xy 109.176701 -224.366197) (xy 109.177074 -224.389442)
			(xy 109.404658 -224.389442) (xy 109.405156 -224.362793) (xy 109.413099 -224.310089) (xy 109.428809 -224.259159)
			(xy 109.451935 -224.211138) (xy 109.481959 -224.167101) (xy 109.518211 -224.12803) (xy 109.559882 -224.094799)
			(xy 109.60604 -224.06815) (xy 109.655654 -224.048678) (xy 109.707616 -224.036818) (xy 109.760766 -224.032835)
			(xy 109.813916 -224.036818) (xy 109.865878 -224.048678) (xy 109.915492 -224.06815) (xy 109.96165 -224.094799)
			(xy 110.003321 -224.12803) (xy 110.039573 -224.167101) (xy 110.069597 -224.211138) (xy 110.092723 -224.259159)
			(xy 110.108433 -224.310089) (xy 110.116376 -224.362793) (xy 110.116874 -224.389442) (xy 110.344458 -224.389442)
			(xy 110.344912 -224.363814) (xy 110.352243 -224.313084) (xy 110.366772 -224.26393) (xy 110.3882 -224.217367)
			(xy 110.416084 -224.174359) (xy 110.449847 -224.135794) (xy 110.488792 -224.102469) (xy 110.532113 -224.075074)
			(xy 110.578915 -224.054174) (xy 110.62823 -224.040202) (xy 110.653576 -224.036382) (xy 110.678214 -224.03308)
			(xy 110.850426 -223.734376) (xy 110.841028 -223.711516) (xy 110.83252 -223.689881) (xy 110.820529 -223.644965)
			(xy 110.814481 -223.598871) (xy 110.814104 -223.575626) (xy 110.814602 -223.548977) (xy 110.822545 -223.496273)
			(xy 110.838255 -223.445343) (xy 110.861381 -223.397322) (xy 110.891405 -223.353285) (xy 110.927657 -223.314214)
			(xy 110.969328 -223.280983) (xy 111.015486 -223.254334) (xy 111.0651 -223.234862) (xy 111.117062 -223.223002)
			(xy 111.170212 -223.219019) (xy 111.223362 -223.223002) (xy 111.275324 -223.234862) (xy 111.324938 -223.254334)
			(xy 111.371096 -223.280983) (xy 111.412767 -223.314214) (xy 111.449019 -223.353285) (xy 111.479043 -223.397322)
			(xy 111.502169 -223.445343) (xy 111.517879 -223.496273) (xy 111.525822 -223.548977) (xy 111.52632 -223.575626)
			(xy 111.525947 -223.601257) (xy 111.5258 -223.602275) (xy 111.754656 -223.602275) (xy 111.754656 -223.548977)
			(xy 111.762599 -223.496273) (xy 111.778309 -223.445343) (xy 111.801435 -223.397322) (xy 111.831459 -223.353285)
			(xy 111.867711 -223.314214) (xy 111.909382 -223.280983) (xy 111.95554 -223.254334) (xy 112.005154 -223.234862)
			(xy 112.057116 -223.223002) (xy 112.110266 -223.219019) (xy 112.163416 -223.223002) (xy 112.215378 -223.234862)
			(xy 112.264992 -223.254334) (xy 112.31115 -223.280983) (xy 112.352821 -223.314214) (xy 112.389073 -223.353285)
			(xy 112.419097 -223.397322) (xy 112.442223 -223.445343) (xy 112.457933 -223.496273) (xy 112.465876 -223.548977)
			(xy 112.466374 -223.575626) (xy 112.465876 -223.602275) (xy 112.457933 -223.654979) (xy 112.442223 -223.705909)
			(xy 112.419097 -223.75393) (xy 112.389073 -223.797967) (xy 112.352821 -223.837038) (xy 112.31115 -223.870269)
			(xy 112.264992 -223.896918) (xy 112.215378 -223.91639) (xy 112.163416 -223.92825) (xy 112.110266 -223.932234)
			(xy 112.057116 -223.92825) (xy 112.005154 -223.91639) (xy 111.95554 -223.896918) (xy 111.909382 -223.870269)
			(xy 111.867711 -223.837038) (xy 111.831459 -223.797967) (xy 111.801435 -223.75393) (xy 111.778309 -223.705909)
			(xy 111.762599 -223.654979) (xy 111.754656 -223.602275) (xy 111.5258 -223.602275) (xy 111.518607 -223.651991)
			(xy 111.504068 -223.701148) (xy 111.48263 -223.747712) (xy 111.454737 -223.790721) (xy 111.420964 -223.829285)
			(xy 111.382011 -223.862608) (xy 111.338682 -223.890002) (xy 111.291873 -223.910899) (xy 111.242551 -223.924868)
			(xy 111.217202 -223.928686) (xy 111.19231 -223.931988) (xy 111.020098 -224.230438) (xy 111.02975 -224.253552)
			(xy 111.038278 -224.27518) (xy 111.050261 -224.3201) (xy 111.056301 -224.366197) (xy 111.056674 -224.389442)
			(xy 111.284258 -224.389442) (xy 111.284756 -224.362793) (xy 111.292699 -224.310089) (xy 111.308409 -224.259159)
			(xy 111.331535 -224.211138) (xy 111.361559 -224.167101) (xy 111.397811 -224.12803) (xy 111.439482 -224.094799)
			(xy 111.48564 -224.06815) (xy 111.535254 -224.048678) (xy 111.587216 -224.036818) (xy 111.640366 -224.032835)
			(xy 111.693516 -224.036818) (xy 111.745478 -224.048678) (xy 111.795092 -224.06815) (xy 111.84125 -224.094799)
			(xy 111.882921 -224.12803) (xy 111.919173 -224.167101) (xy 111.949197 -224.211138) (xy 111.972323 -224.259159)
			(xy 111.988033 -224.310089) (xy 111.995976 -224.362793) (xy 111.996474 -224.389442) (xy 112.224058 -224.389442)
			(xy 112.224512 -224.363814) (xy 112.231843 -224.313084) (xy 112.246372 -224.26393) (xy 112.2678 -224.217367)
			(xy 112.295684 -224.174359) (xy 112.329447 -224.135794) (xy 112.368392 -224.102469) (xy 112.411713 -224.075074)
			(xy 112.458515 -224.054174) (xy 112.50783 -224.040202) (xy 112.533176 -224.036382) (xy 112.557814 -224.03308)
			(xy 112.730026 -223.734376) (xy 112.720628 -223.711516) (xy 112.71212 -223.689881) (xy 112.700129 -223.644965)
			(xy 112.694081 -223.598871) (xy 112.693704 -223.575626) (xy 112.694202 -223.548977) (xy 112.702145 -223.496273)
			(xy 112.717855 -223.445343) (xy 112.740981 -223.397322) (xy 112.771005 -223.353285) (xy 112.807257 -223.314214)
			(xy 112.848928 -223.280983) (xy 112.895086 -223.254334) (xy 112.9447 -223.234862) (xy 112.996662 -223.223002)
			(xy 113.049812 -223.219019) (xy 113.102962 -223.223002) (xy 113.154924 -223.234862) (xy 113.204538 -223.254334)
			(xy 113.250696 -223.280983) (xy 113.292367 -223.314214) (xy 113.328619 -223.353285) (xy 113.358643 -223.397322)
			(xy 113.381769 -223.445343) (xy 113.397479 -223.496273) (xy 113.405422 -223.548977) (xy 113.40592 -223.575626)
			(xy 113.405547 -223.601257) (xy 113.4054 -223.602275) (xy 113.634256 -223.602275) (xy 113.634256 -223.548977)
			(xy 113.642199 -223.496273) (xy 113.657909 -223.445343) (xy 113.681035 -223.397322) (xy 113.711059 -223.353285)
			(xy 113.747311 -223.314214) (xy 113.788982 -223.280983) (xy 113.83514 -223.254334) (xy 113.884754 -223.234862)
			(xy 113.936716 -223.223002) (xy 113.989866 -223.219019) (xy 114.043016 -223.223002) (xy 114.094978 -223.234862)
			(xy 114.144592 -223.254334) (xy 114.19075 -223.280983) (xy 114.232421 -223.314214) (xy 114.268673 -223.353285)
			(xy 114.298697 -223.397322) (xy 114.321823 -223.445343) (xy 114.337533 -223.496273) (xy 114.345476 -223.548977)
			(xy 114.345974 -223.575626) (xy 114.345476 -223.602275) (xy 114.337533 -223.654979) (xy 114.321823 -223.705909)
			(xy 114.298697 -223.75393) (xy 114.268673 -223.797967) (xy 114.232421 -223.837038) (xy 114.19075 -223.870269)
			(xy 114.144592 -223.896918) (xy 114.094978 -223.91639) (xy 114.043016 -223.92825) (xy 113.989866 -223.932234)
			(xy 113.936716 -223.92825) (xy 113.884754 -223.91639) (xy 113.83514 -223.896918) (xy 113.788982 -223.870269)
			(xy 113.747311 -223.837038) (xy 113.711059 -223.797967) (xy 113.681035 -223.75393) (xy 113.657909 -223.705909)
			(xy 113.642199 -223.654979) (xy 113.634256 -223.602275) (xy 113.4054 -223.602275) (xy 113.398207 -223.651991)
			(xy 113.383668 -223.701148) (xy 113.36223 -223.747712) (xy 113.334337 -223.790721) (xy 113.300564 -223.829285)
			(xy 113.261611 -223.862608) (xy 113.218282 -223.890002) (xy 113.171473 -223.910899) (xy 113.122151 -223.924868)
			(xy 113.096802 -223.928686) (xy 113.07191 -223.931988) (xy 112.899698 -224.230438) (xy 112.90935 -224.253552)
			(xy 112.917878 -224.27518) (xy 112.929861 -224.3201) (xy 112.935901 -224.366197) (xy 112.936274 -224.389442)
			(xy 113.163858 -224.389442) (xy 113.164356 -224.362793) (xy 113.172299 -224.310089) (xy 113.188009 -224.259159)
			(xy 113.211135 -224.211138) (xy 113.241159 -224.167101) (xy 113.277411 -224.12803) (xy 113.319082 -224.094799)
			(xy 113.36524 -224.06815) (xy 113.414854 -224.048678) (xy 113.466816 -224.036818) (xy 113.519966 -224.032835)
			(xy 113.573116 -224.036818) (xy 113.625078 -224.048678) (xy 113.674692 -224.06815) (xy 113.72085 -224.094799)
			(xy 113.762521 -224.12803) (xy 113.798773 -224.167101) (xy 113.828797 -224.211138) (xy 113.851923 -224.259159)
			(xy 113.867633 -224.310089) (xy 113.875576 -224.362793) (xy 113.876074 -224.389442) (xy 114.103658 -224.389442)
			(xy 114.104112 -224.363814) (xy 114.111443 -224.313084) (xy 114.125972 -224.26393) (xy 114.1474 -224.217367)
			(xy 114.175284 -224.174359) (xy 114.209047 -224.135794) (xy 114.247992 -224.102469) (xy 114.291313 -224.075074)
			(xy 114.338115 -224.054174) (xy 114.38743 -224.040202) (xy 114.412776 -224.036382) (xy 114.437414 -224.03308)
			(xy 114.60988 -223.734376) (xy 114.600482 -223.711262) (xy 114.591984 -223.689669) (xy 114.58001 -223.644835)
			(xy 114.573951 -223.598828) (xy 114.573558 -223.575626) (xy 114.574056 -223.548977) (xy 114.581999 -223.496273)
			(xy 114.597709 -223.445343) (xy 114.620835 -223.397322) (xy 114.650859 -223.353285) (xy 114.687111 -223.314214)
			(xy 114.728782 -223.280983) (xy 114.77494 -223.254334) (xy 114.824554 -223.234862) (xy 114.876516 -223.223002)
			(xy 114.929666 -223.219019) (xy 114.982816 -223.223002) (xy 115.034778 -223.234862) (xy 115.084392 -223.254334)
			(xy 115.13055 -223.280983) (xy 115.172221 -223.314214) (xy 115.208473 -223.353285) (xy 115.238497 -223.397322)
			(xy 115.261623 -223.445343) (xy 115.277333 -223.496273) (xy 115.285276 -223.548977) (xy 115.285774 -223.575626)
			(xy 115.28532 -223.601265) (xy 115.285174 -223.602275) (xy 115.513856 -223.602275) (xy 115.513856 -223.548977)
			(xy 115.521799 -223.496273) (xy 115.537509 -223.445343) (xy 115.560635 -223.397322) (xy 115.590659 -223.353285)
			(xy 115.626911 -223.314214) (xy 115.668582 -223.280983) (xy 115.71474 -223.254334) (xy 115.764354 -223.234862)
			(xy 115.816316 -223.223002) (xy 115.869466 -223.219019) (xy 115.922616 -223.223002) (xy 115.974578 -223.234862)
			(xy 116.024192 -223.254334) (xy 116.07035 -223.280983) (xy 116.112021 -223.314214) (xy 116.148273 -223.353285)
			(xy 116.178297 -223.397322) (xy 116.201423 -223.445343) (xy 116.217133 -223.496273) (xy 116.225076 -223.548977)
			(xy 116.225574 -223.575626) (xy 116.225076 -223.602275) (xy 116.217133 -223.654979) (xy 116.201423 -223.705909)
			(xy 116.178297 -223.75393) (xy 116.148273 -223.797967) (xy 116.112021 -223.837038) (xy 116.07035 -223.870269)
			(xy 116.024192 -223.896918) (xy 115.974578 -223.91639) (xy 115.922616 -223.92825) (xy 115.869466 -223.932234)
			(xy 115.816316 -223.92825) (xy 115.764354 -223.91639) (xy 115.71474 -223.896918) (xy 115.668582 -223.870269)
			(xy 115.626911 -223.837038) (xy 115.590659 -223.797967) (xy 115.560635 -223.75393) (xy 115.537509 -223.705909)
			(xy 115.521799 -223.654979) (xy 115.513856 -223.602275) (xy 115.285174 -223.602275) (xy 115.277975 -223.652014)
			(xy 115.263426 -223.701185) (xy 115.241973 -223.74776) (xy 115.214062 -223.790776) (xy 115.180268 -223.829343)
			(xy 115.141292 -223.862664) (xy 115.097939 -223.890049) (xy 115.051105 -223.910931) (xy 115.001761 -223.92488)
			(xy 114.976402 -223.928686) (xy 114.95151 -223.931988) (xy 114.779298 -224.230438) (xy 114.78895 -224.253552)
			(xy 114.797478 -224.27518) (xy 114.809461 -224.3201) (xy 114.815501 -224.366197) (xy 114.815874 -224.389442)
			(xy 115.043458 -224.389442) (xy 115.043956 -224.362793) (xy 115.051899 -224.310089) (xy 115.067609 -224.259159)
			(xy 115.090735 -224.211138) (xy 115.120759 -224.167101) (xy 115.157011 -224.12803) (xy 115.198682 -224.094799)
			(xy 115.24484 -224.06815) (xy 115.294454 -224.048678) (xy 115.346416 -224.036818) (xy 115.399566 -224.032835)
			(xy 115.452716 -224.036818) (xy 115.504678 -224.048678) (xy 115.554292 -224.06815) (xy 115.60045 -224.094799)
			(xy 115.642121 -224.12803) (xy 115.678373 -224.167101) (xy 115.708397 -224.211138) (xy 115.731523 -224.259159)
			(xy 115.747233 -224.310089) (xy 115.755176 -224.362793) (xy 115.755674 -224.389442) (xy 115.983258 -224.389442)
			(xy 115.983712 -224.363814) (xy 115.991043 -224.313084) (xy 116.005572 -224.26393) (xy 116.027 -224.217367)
			(xy 116.054884 -224.174359) (xy 116.088647 -224.135794) (xy 116.127592 -224.102469) (xy 116.170913 -224.075074)
			(xy 116.217715 -224.054174) (xy 116.26703 -224.040202) (xy 116.292376 -224.036382) (xy 116.317014 -224.03308)
			(xy 116.489226 -223.734376) (xy 116.479828 -223.711516) (xy 116.47132 -223.689881) (xy 116.459329 -223.644965)
			(xy 116.453281 -223.598871) (xy 116.452904 -223.575626) (xy 116.453402 -223.548977) (xy 116.461345 -223.496273)
			(xy 116.477055 -223.445343) (xy 116.500181 -223.397322) (xy 116.530205 -223.353285) (xy 116.566457 -223.314214)
			(xy 116.608128 -223.280983) (xy 116.654286 -223.254334) (xy 116.7039 -223.234862) (xy 116.755862 -223.223002)
			(xy 116.809012 -223.219019) (xy 116.862162 -223.223002) (xy 116.914124 -223.234862) (xy 116.963738 -223.254334)
			(xy 117.009896 -223.280983) (xy 117.051567 -223.314214) (xy 117.087819 -223.353285) (xy 117.117843 -223.397322)
			(xy 117.140969 -223.445343) (xy 117.156679 -223.496273) (xy 117.164622 -223.548977) (xy 117.16512 -223.575626)
			(xy 117.164747 -223.601257) (xy 117.1646 -223.602275) (xy 117.393456 -223.602275) (xy 117.393456 -223.548977)
			(xy 117.401399 -223.496273) (xy 117.417109 -223.445343) (xy 117.440235 -223.397322) (xy 117.470259 -223.353285)
			(xy 117.506511 -223.314214) (xy 117.548182 -223.280983) (xy 117.59434 -223.254334) (xy 117.643954 -223.234862)
			(xy 117.695916 -223.223002) (xy 117.749066 -223.219019) (xy 117.802216 -223.223002) (xy 117.854178 -223.234862)
			(xy 117.903792 -223.254334) (xy 117.94995 -223.280983) (xy 117.991621 -223.314214) (xy 118.027873 -223.353285)
			(xy 118.057897 -223.397322) (xy 118.081023 -223.445343) (xy 118.096733 -223.496273) (xy 118.104676 -223.548977)
			(xy 118.105174 -223.575626) (xy 118.104676 -223.602275) (xy 118.096733 -223.654979) (xy 118.081023 -223.705909)
			(xy 118.057897 -223.75393) (xy 118.027873 -223.797967) (xy 117.991621 -223.837038) (xy 117.94995 -223.870269)
			(xy 117.903792 -223.896918) (xy 117.854178 -223.91639) (xy 117.802216 -223.92825) (xy 117.749066 -223.932234)
			(xy 117.695916 -223.92825) (xy 117.643954 -223.91639) (xy 117.59434 -223.896918) (xy 117.548182 -223.870269)
			(xy 117.506511 -223.837038) (xy 117.470259 -223.797967) (xy 117.440235 -223.75393) (xy 117.417109 -223.705909)
			(xy 117.401399 -223.654979) (xy 117.393456 -223.602275) (xy 117.1646 -223.602275) (xy 117.157407 -223.651991)
			(xy 117.142868 -223.701148) (xy 117.12143 -223.747712) (xy 117.093537 -223.790721) (xy 117.059764 -223.829285)
			(xy 117.020811 -223.862608) (xy 116.977482 -223.890002) (xy 116.930673 -223.910899) (xy 116.881351 -223.924868)
			(xy 116.856002 -223.928686) (xy 116.83111 -223.931988) (xy 116.658898 -224.230438) (xy 116.66855 -224.253552)
			(xy 116.677078 -224.27518) (xy 116.689061 -224.3201) (xy 116.695101 -224.366197) (xy 116.695474 -224.389442)
			(xy 116.923058 -224.389442) (xy 116.923556 -224.362793) (xy 116.931499 -224.310089) (xy 116.947209 -224.259159)
			(xy 116.970335 -224.211138) (xy 117.000359 -224.167101) (xy 117.036611 -224.12803) (xy 117.078282 -224.094799)
			(xy 117.12444 -224.06815) (xy 117.174054 -224.048678) (xy 117.226016 -224.036818) (xy 117.279166 -224.032835)
			(xy 117.332316 -224.036818) (xy 117.384278 -224.048678) (xy 117.433892 -224.06815) (xy 117.48005 -224.094799)
			(xy 117.521721 -224.12803) (xy 117.557973 -224.167101) (xy 117.587997 -224.211138) (xy 117.611123 -224.259159)
			(xy 117.626833 -224.310089) (xy 117.634776 -224.362793) (xy 117.635274 -224.389442) (xy 117.634888 -224.412687)
			(xy 117.628849 -224.458782) (xy 117.616865 -224.5037) (xy 117.60835 -224.525332) (xy 117.598698 -224.548446)
			(xy 117.771164 -224.846896) (xy 117.795802 -224.850198) (xy 117.821142 -224.854037) (xy 117.870448 -224.868024)
			(xy 117.91724 -224.888933) (xy 117.960553 -224.916332) (xy 117.999492 -224.949655) (xy 118.033253 -224.988214)
			(xy 118.06114 -225.031214) (xy 118.082577 -225.077767) (xy 118.097121 -225.126911) (xy 118.104472 -225.177632)
			(xy 118.10492 -225.203258) (xy 118.104422 -225.229907) (xy 118.096479 -225.282611) (xy 118.080769 -225.333541)
			(xy 118.057643 -225.381562) (xy 118.027619 -225.425599) (xy 117.991367 -225.46467) (xy 117.949696 -225.497901)
			(xy 117.903538 -225.52455) (xy 117.853924 -225.544022) (xy 117.801962 -225.555882) (xy 117.748812 -225.559866)
			(xy 117.695662 -225.555882) (xy 117.6437 -225.544022) (xy 117.594086 -225.52455) (xy 117.547928 -225.497901)
			(xy 117.506257 -225.46467) (xy 117.470005 -225.425599) (xy 117.439981 -225.381562) (xy 117.416855 -225.333541)
			(xy 117.401145 -225.282611) (xy 117.393202 -225.229907) (xy 117.392704 -225.203258) (xy 117.393091 -225.180013)
			(xy 117.399131 -225.133918) (xy 117.411114 -225.089) (xy 117.419628 -225.067368) (xy 117.42928 -225.044254)
			(xy 117.256814 -224.745804) (xy 117.232176 -224.742502) (xy 117.206833 -224.73868) (xy 117.157527 -224.72469)
			(xy 117.110735 -224.703779) (xy 117.067423 -224.676378) (xy 117.028484 -224.643052) (xy 116.994723 -224.604491)
			(xy 116.966837 -224.56149) (xy 116.9454 -224.514936) (xy 116.930857 -224.46579) (xy 116.923506 -224.415068)
			(xy 116.923058 -224.389442) (xy 116.695474 -224.389442) (xy 116.694976 -224.416091) (xy 116.687033 -224.468795)
			(xy 116.671323 -224.519725) (xy 116.648197 -224.567746) (xy 116.618173 -224.611783) (xy 116.581921 -224.650854)
			(xy 116.54025 -224.684085) (xy 116.494092 -224.710734) (xy 116.444478 -224.730206) (xy 116.392516 -224.742066)
			(xy 116.339366 -224.74605) (xy 116.286216 -224.742066) (xy 116.234254 -224.730206) (xy 116.18464 -224.710734)
			(xy 116.138482 -224.684085) (xy 116.096811 -224.650854) (xy 116.060559 -224.611783) (xy 116.030535 -224.567746)
			(xy 116.007409 -224.519725) (xy 115.991699 -224.468795) (xy 115.983756 -224.416091) (xy 115.983258 -224.389442)
			(xy 115.755674 -224.389442) (xy 115.755288 -224.412687) (xy 115.749249 -224.458782) (xy 115.737265 -224.5037)
			(xy 115.72875 -224.525332) (xy 115.719098 -224.548446) (xy 115.891564 -224.846896) (xy 115.916202 -224.850198)
			(xy 115.941542 -224.854037) (xy 115.990848 -224.868024) (xy 116.03764 -224.888933) (xy 116.080953 -224.916332)
			(xy 116.119892 -224.949655) (xy 116.153653 -224.988214) (xy 116.18154 -225.031214) (xy 116.202977 -225.077767)
			(xy 116.217521 -225.126911) (xy 116.224872 -225.177632) (xy 116.22532 -225.203258) (xy 116.224822 -225.229907)
			(xy 116.216879 -225.282611) (xy 116.201169 -225.333541) (xy 116.178043 -225.381562) (xy 116.148019 -225.425599)
			(xy 116.111767 -225.46467) (xy 116.070096 -225.497901) (xy 116.023938 -225.52455) (xy 115.974324 -225.544022)
			(xy 115.922362 -225.555882) (xy 115.869212 -225.559866) (xy 115.816062 -225.555882) (xy 115.7641 -225.544022)
			(xy 115.714486 -225.52455) (xy 115.668328 -225.497901) (xy 115.626657 -225.46467) (xy 115.590405 -225.425599)
			(xy 115.560381 -225.381562) (xy 115.537255 -225.333541) (xy 115.521545 -225.282611) (xy 115.513602 -225.229907)
			(xy 115.513104 -225.203258) (xy 115.513491 -225.180013) (xy 115.519531 -225.133918) (xy 115.531514 -225.089)
			(xy 115.540028 -225.067368) (xy 115.54968 -225.044254) (xy 115.377214 -224.745804) (xy 115.352576 -224.742502)
			(xy 115.327233 -224.73868) (xy 115.277927 -224.72469) (xy 115.231135 -224.703779) (xy 115.187823 -224.676378)
			(xy 115.148884 -224.643052) (xy 115.115123 -224.604491) (xy 115.087237 -224.56149) (xy 115.0658 -224.514936)
			(xy 115.051257 -224.46579) (xy 115.043906 -224.415068) (xy 115.043458 -224.389442) (xy 114.815874 -224.389442)
			(xy 114.815376 -224.416091) (xy 114.807433 -224.468795) (xy 114.791723 -224.519725) (xy 114.768597 -224.567746)
			(xy 114.738573 -224.611783) (xy 114.702321 -224.650854) (xy 114.66065 -224.684085) (xy 114.614492 -224.710734)
			(xy 114.564878 -224.730206) (xy 114.512916 -224.742066) (xy 114.459766 -224.74605) (xy 114.406616 -224.742066)
			(xy 114.354654 -224.730206) (xy 114.30504 -224.710734) (xy 114.258882 -224.684085) (xy 114.217211 -224.650854)
			(xy 114.180959 -224.611783) (xy 114.150935 -224.567746) (xy 114.127809 -224.519725) (xy 114.112099 -224.468795)
			(xy 114.104156 -224.416091) (xy 114.103658 -224.389442) (xy 113.876074 -224.389442) (xy 113.875688 -224.412687)
			(xy 113.869649 -224.458782) (xy 113.857665 -224.5037) (xy 113.84915 -224.525332) (xy 113.839498 -224.548446)
			(xy 114.011964 -224.846896) (xy 114.036602 -224.850198) (xy 114.061942 -224.854037) (xy 114.111248 -224.868024)
			(xy 114.15804 -224.888933) (xy 114.201353 -224.916332) (xy 114.240292 -224.949655) (xy 114.274053 -224.988214)
			(xy 114.30194 -225.031214) (xy 114.323377 -225.077767) (xy 114.337921 -225.126911) (xy 114.345272 -225.177632)
			(xy 114.34572 -225.203258) (xy 114.345222 -225.229907) (xy 114.337279 -225.282611) (xy 114.321569 -225.333541)
			(xy 114.298443 -225.381562) (xy 114.268419 -225.425599) (xy 114.232167 -225.46467) (xy 114.190496 -225.497901)
			(xy 114.144338 -225.52455) (xy 114.094724 -225.544022) (xy 114.042762 -225.555882) (xy 113.989612 -225.559866)
			(xy 113.936462 -225.555882) (xy 113.8845 -225.544022) (xy 113.834886 -225.52455) (xy 113.788728 -225.497901)
			(xy 113.747057 -225.46467) (xy 113.710805 -225.425599) (xy 113.680781 -225.381562) (xy 113.657655 -225.333541)
			(xy 113.641945 -225.282611) (xy 113.634002 -225.229907) (xy 113.633504 -225.203258) (xy 113.633891 -225.180013)
			(xy 113.639931 -225.133918) (xy 113.651914 -225.089) (xy 113.660428 -225.067368) (xy 113.67008 -225.044254)
			(xy 113.497614 -224.745804) (xy 113.472976 -224.742502) (xy 113.447633 -224.73868) (xy 113.398327 -224.72469)
			(xy 113.351535 -224.703779) (xy 113.308223 -224.676378) (xy 113.269284 -224.643052) (xy 113.235523 -224.604491)
			(xy 113.207637 -224.56149) (xy 113.1862 -224.514936) (xy 113.171657 -224.46579) (xy 113.164306 -224.415068)
			(xy 113.163858 -224.389442) (xy 112.936274 -224.389442) (xy 112.935776 -224.416091) (xy 112.927833 -224.468795)
			(xy 112.912123 -224.519725) (xy 112.888997 -224.567746) (xy 112.858973 -224.611783) (xy 112.822721 -224.650854)
			(xy 112.78105 -224.684085) (xy 112.734892 -224.710734) (xy 112.685278 -224.730206) (xy 112.633316 -224.742066)
			(xy 112.580166 -224.74605) (xy 112.527016 -224.742066) (xy 112.475054 -224.730206) (xy 112.42544 -224.710734)
			(xy 112.379282 -224.684085) (xy 112.337611 -224.650854) (xy 112.301359 -224.611783) (xy 112.271335 -224.567746)
			(xy 112.248209 -224.519725) (xy 112.232499 -224.468795) (xy 112.224556 -224.416091) (xy 112.224058 -224.389442)
			(xy 111.996474 -224.389442) (xy 111.996088 -224.412687) (xy 111.990049 -224.458782) (xy 111.978065 -224.5037)
			(xy 111.96955 -224.525332) (xy 111.959898 -224.548446) (xy 112.132364 -224.846896) (xy 112.157002 -224.850198)
			(xy 112.182342 -224.854037) (xy 112.231648 -224.868024) (xy 112.27844 -224.888933) (xy 112.321753 -224.916332)
			(xy 112.360692 -224.949655) (xy 112.394453 -224.988214) (xy 112.42234 -225.031214) (xy 112.443777 -225.077767)
			(xy 112.458321 -225.126911) (xy 112.465672 -225.177632) (xy 112.46612 -225.203258) (xy 112.465622 -225.229907)
			(xy 112.457679 -225.282611) (xy 112.441969 -225.333541) (xy 112.418843 -225.381562) (xy 112.388819 -225.425599)
			(xy 112.352567 -225.46467) (xy 112.310896 -225.497901) (xy 112.264738 -225.52455) (xy 112.215124 -225.544022)
			(xy 112.163162 -225.555882) (xy 112.110012 -225.559866) (xy 112.056862 -225.555882) (xy 112.0049 -225.544022)
			(xy 111.955286 -225.52455) (xy 111.909128 -225.497901) (xy 111.867457 -225.46467) (xy 111.831205 -225.425599)
			(xy 111.801181 -225.381562) (xy 111.778055 -225.333541) (xy 111.762345 -225.282611) (xy 111.754402 -225.229907)
			(xy 111.753904 -225.203258) (xy 111.754291 -225.180013) (xy 111.760331 -225.133918) (xy 111.772314 -225.089)
			(xy 111.780828 -225.067368) (xy 111.79048 -225.044254) (xy 111.618014 -224.745804) (xy 111.593376 -224.742502)
			(xy 111.568033 -224.73868) (xy 111.518727 -224.72469) (xy 111.471935 -224.703779) (xy 111.428623 -224.676378)
			(xy 111.389684 -224.643052) (xy 111.355923 -224.604491) (xy 111.328037 -224.56149) (xy 111.3066 -224.514936)
			(xy 111.292057 -224.46579) (xy 111.284706 -224.415068) (xy 111.284258 -224.389442) (xy 111.056674 -224.389442)
			(xy 111.056176 -224.416091) (xy 111.048233 -224.468795) (xy 111.032523 -224.519725) (xy 111.009397 -224.567746)
			(xy 110.979373 -224.611783) (xy 110.943121 -224.650854) (xy 110.90145 -224.684085) (xy 110.855292 -224.710734)
			(xy 110.805678 -224.730206) (xy 110.753716 -224.742066) (xy 110.700566 -224.74605) (xy 110.647416 -224.742066)
			(xy 110.595454 -224.730206) (xy 110.54584 -224.710734) (xy 110.499682 -224.684085) (xy 110.458011 -224.650854)
			(xy 110.421759 -224.611783) (xy 110.391735 -224.567746) (xy 110.368609 -224.519725) (xy 110.352899 -224.468795)
			(xy 110.344956 -224.416091) (xy 110.344458 -224.389442) (xy 110.116874 -224.389442) (xy 110.116488 -224.412687)
			(xy 110.110449 -224.458782) (xy 110.098465 -224.5037) (xy 110.08995 -224.525332) (xy 110.080298 -224.548446)
			(xy 110.252764 -224.846896) (xy 110.277402 -224.850198) (xy 110.302742 -224.854037) (xy 110.352048 -224.868024)
			(xy 110.39884 -224.888933) (xy 110.442153 -224.916332) (xy 110.481092 -224.949655) (xy 110.514853 -224.988214)
			(xy 110.54274 -225.031214) (xy 110.564177 -225.077767) (xy 110.578721 -225.126911) (xy 110.586072 -225.177632)
			(xy 110.58652 -225.203258) (xy 110.586022 -225.229907) (xy 110.814602 -225.229907) (xy 110.814602 -225.176609)
			(xy 110.822545 -225.123905) (xy 110.838255 -225.072975) (xy 110.861381 -225.024954) (xy 110.891405 -224.980917)
			(xy 110.927657 -224.941846) (xy 110.969328 -224.908615) (xy 111.015486 -224.881966) (xy 111.0651 -224.862494)
			(xy 111.117062 -224.850634) (xy 111.170212 -224.846651) (xy 111.223362 -224.850634) (xy 111.275324 -224.862494)
			(xy 111.324938 -224.881966) (xy 111.371096 -224.908615) (xy 111.412767 -224.941846) (xy 111.449019 -224.980917)
			(xy 111.479043 -225.024954) (xy 111.502169 -225.072975) (xy 111.517879 -225.123905) (xy 111.525822 -225.176609)
			(xy 111.52632 -225.203258) (xy 111.525822 -225.229907) (xy 111.517879 -225.282611) (xy 111.502169 -225.333541)
			(xy 111.479043 -225.381562) (xy 111.449019 -225.425599) (xy 111.412767 -225.46467) (xy 111.371096 -225.497901)
			(xy 111.324938 -225.52455) (xy 111.275324 -225.544022) (xy 111.223362 -225.555882) (xy 111.170212 -225.559866)
			(xy 111.117062 -225.555882) (xy 111.0651 -225.544022) (xy 111.015486 -225.52455) (xy 110.969328 -225.497901)
			(xy 110.927657 -225.46467) (xy 110.891405 -225.425599) (xy 110.861381 -225.381562) (xy 110.838255 -225.333541)
			(xy 110.822545 -225.282611) (xy 110.814602 -225.229907) (xy 110.586022 -225.229907) (xy 110.578079 -225.282611)
			(xy 110.562369 -225.333541) (xy 110.539243 -225.381562) (xy 110.509219 -225.425599) (xy 110.472967 -225.46467)
			(xy 110.431296 -225.497901) (xy 110.385138 -225.52455) (xy 110.335524 -225.544022) (xy 110.283562 -225.555882)
			(xy 110.230412 -225.559866) (xy 110.177262 -225.555882) (xy 110.1253 -225.544022) (xy 110.075686 -225.52455)
			(xy 110.029528 -225.497901) (xy 109.987857 -225.46467) (xy 109.951605 -225.425599) (xy 109.921581 -225.381562)
			(xy 109.898455 -225.333541) (xy 109.882745 -225.282611) (xy 109.874802 -225.229907) (xy 109.874304 -225.203258)
			(xy 109.874691 -225.180013) (xy 109.880731 -225.133918) (xy 109.892714 -225.089) (xy 109.901228 -225.067368)
			(xy 109.91088 -225.044254) (xy 109.738414 -224.745804) (xy 109.713776 -224.742502) (xy 109.688433 -224.73868)
			(xy 109.639127 -224.72469) (xy 109.592335 -224.703779) (xy 109.549023 -224.676378) (xy 109.510084 -224.643052)
			(xy 109.476323 -224.604491) (xy 109.448437 -224.56149) (xy 109.427 -224.514936) (xy 109.412457 -224.46579)
			(xy 109.405106 -224.415068) (xy 109.404658 -224.389442) (xy 109.177074 -224.389442) (xy 109.176576 -224.416091)
			(xy 109.168633 -224.468795) (xy 109.152923 -224.519725) (xy 109.129797 -224.567746) (xy 109.099773 -224.611783)
			(xy 109.063521 -224.650854) (xy 109.02185 -224.684085) (xy 108.975692 -224.710734) (xy 108.926078 -224.730206)
			(xy 108.874116 -224.742066) (xy 108.820966 -224.74605) (xy 108.767816 -224.742066) (xy 108.715854 -224.730206)
			(xy 108.66624 -224.710734) (xy 108.620082 -224.684085) (xy 108.578411 -224.650854) (xy 108.542159 -224.611783)
			(xy 108.512135 -224.567746) (xy 108.489009 -224.519725) (xy 108.473299 -224.468795) (xy 108.465356 -224.416091)
			(xy 108.464858 -224.389442) (xy 108.237274 -224.389442) (xy 108.236888 -224.412687) (xy 108.230849 -224.458782)
			(xy 108.218865 -224.5037) (xy 108.21035 -224.525332) (xy 108.200698 -224.548446) (xy 108.373164 -224.846896)
			(xy 108.397802 -224.850198) (xy 108.423142 -224.854037) (xy 108.472448 -224.868024) (xy 108.51924 -224.888933)
			(xy 108.562553 -224.916332) (xy 108.601492 -224.949655) (xy 108.635253 -224.988214) (xy 108.66314 -225.031214)
			(xy 108.684577 -225.077767) (xy 108.699121 -225.126911) (xy 108.706472 -225.177632) (xy 108.70692 -225.203258)
			(xy 108.706422 -225.229907) (xy 108.698479 -225.282611) (xy 108.682769 -225.333541) (xy 108.659643 -225.381562)
			(xy 108.629619 -225.425599) (xy 108.593367 -225.46467) (xy 108.551696 -225.497901) (xy 108.505538 -225.52455)
			(xy 108.455924 -225.544022) (xy 108.403962 -225.555882) (xy 108.350812 -225.559866) (xy 108.297662 -225.555882)
			(xy 108.2457 -225.544022) (xy 108.196086 -225.52455) (xy 108.149928 -225.497901) (xy 108.108257 -225.46467)
			(xy 108.072005 -225.425599) (xy 108.041981 -225.381562) (xy 108.018855 -225.333541) (xy 108.003145 -225.282611)
			(xy 107.995202 -225.229907) (xy 107.994704 -225.203258) (xy 107.995091 -225.180013) (xy 108.001131 -225.133918)
			(xy 108.013114 -225.089) (xy 108.021628 -225.067368) (xy 108.03128 -225.044254) (xy 107.858814 -224.745804)
			(xy 107.834176 -224.742502) (xy 107.808833 -224.73868) (xy 107.759527 -224.72469) (xy 107.712735 -224.703779)
			(xy 107.669423 -224.676378) (xy 107.630484 -224.643052) (xy 107.596723 -224.604491) (xy 107.568837 -224.56149)
			(xy 107.5474 -224.514936) (xy 107.532857 -224.46579) (xy 107.525506 -224.415068) (xy 107.525058 -224.389442)
			(xy 107.297474 -224.389442) (xy 107.296976 -224.416091) (xy 107.289033 -224.468795) (xy 107.273323 -224.519725)
			(xy 107.250197 -224.567746) (xy 107.220173 -224.611783) (xy 107.183921 -224.650854) (xy 107.14225 -224.684085)
			(xy 107.096092 -224.710734) (xy 107.046478 -224.730206) (xy 106.994516 -224.742066) (xy 106.941366 -224.74605)
			(xy 106.888216 -224.742066) (xy 106.836254 -224.730206) (xy 106.78664 -224.710734) (xy 106.740482 -224.684085)
			(xy 106.698811 -224.650854) (xy 106.662559 -224.611783) (xy 106.632535 -224.567746) (xy 106.609409 -224.519725)
			(xy 106.593699 -224.468795) (xy 106.585756 -224.416091) (xy 106.585258 -224.389442) (xy 106.357674 -224.389442)
			(xy 106.357288 -224.412687) (xy 106.351249 -224.458782) (xy 106.339265 -224.5037) (xy 106.33075 -224.525332)
			(xy 106.321098 -224.548446) (xy 106.493564 -224.846896) (xy 106.518202 -224.850198) (xy 106.543542 -224.854037)
			(xy 106.592848 -224.868024) (xy 106.63964 -224.888933) (xy 106.682953 -224.916332) (xy 106.721892 -224.949655)
			(xy 106.755653 -224.988214) (xy 106.78354 -225.031214) (xy 106.804977 -225.077767) (xy 106.819521 -225.126911)
			(xy 106.826872 -225.177632) (xy 106.82732 -225.203258) (xy 106.826822 -225.229907) (xy 106.818879 -225.282611)
			(xy 106.803169 -225.333541) (xy 106.780043 -225.381562) (xy 106.750019 -225.425599) (xy 106.713767 -225.46467)
			(xy 106.672096 -225.497901) (xy 106.625938 -225.52455) (xy 106.576324 -225.544022) (xy 106.524362 -225.555882)
			(xy 106.471212 -225.559866) (xy 106.418062 -225.555882) (xy 106.3661 -225.544022) (xy 106.316486 -225.52455)
			(xy 106.270328 -225.497901) (xy 106.228657 -225.46467) (xy 106.192405 -225.425599) (xy 106.162381 -225.381562)
			(xy 106.139255 -225.333541) (xy 106.123545 -225.282611) (xy 106.115602 -225.229907) (xy 106.115104 -225.203258)
			(xy 106.115491 -225.180013) (xy 106.121531 -225.133918) (xy 106.133514 -225.089) (xy 106.142028 -225.067368)
			(xy 106.15168 -225.044254) (xy 105.979214 -224.745804) (xy 105.954576 -224.742502) (xy 105.929233 -224.73868)
			(xy 105.879927 -224.72469) (xy 105.833135 -224.703779) (xy 105.789823 -224.676378) (xy 105.750884 -224.643052)
			(xy 105.717123 -224.604491) (xy 105.689237 -224.56149) (xy 105.6678 -224.514936) (xy 105.653257 -224.46579)
			(xy 105.645906 -224.415068) (xy 105.645458 -224.389442) (xy 105.534968 -224.389442) (xy 105.534968 -224.637092)
			(xy 105.432352 -224.739708) (xy 105.448608 -224.772474) (xy 105.460958 -224.797483) (xy 105.483072 -224.848696)
			(xy 105.492804 -224.874836) (xy 105.50242 -224.873769) (xy 105.521737 -224.872628) (xy 105.531412 -224.87255)
			(xy 105.557402 -224.873061) (xy 105.608741 -224.881194) (xy 105.658177 -224.897258) (xy 105.70449 -224.920857)
			(xy 105.746542 -224.951411) (xy 105.783297 -224.988167) (xy 105.813849 -225.03022) (xy 105.837447 -225.076534)
			(xy 105.853509 -225.12597) (xy 105.86164 -225.17731) (xy 105.86164 -225.22929) (xy 105.853509 -225.28063)
			(xy 105.837447 -225.330066) (xy 105.813849 -225.37638) (xy 105.783297 -225.418433) (xy 105.746542 -225.455189)
			(xy 105.70449 -225.485743) (xy 105.658177 -225.509342) (xy 105.608741 -225.525406) (xy 105.557402 -225.533539)
			(xy 105.531412 -225.533966) (xy 105.521737 -225.533888) (xy 105.50242 -225.532746) (xy 105.492804 -225.53168)
			(xy 105.479259 -225.567696) (xy 105.447186 -225.637649) (xy 105.409621 -225.704812) (xy 105.366804 -225.768755)
			(xy 105.343198 -225.799142) (xy 105.360722 -225.822723) (xy 105.388612 -225.874427) (xy 105.407641 -225.930006)
			(xy 105.417292 -225.987955) (xy 105.417874 -226.017328) (xy 105.417376 -226.043977) (xy 105.645956 -226.043977)
			(xy 105.645956 -225.990679) (xy 105.653899 -225.937975) (xy 105.669609 -225.887045) (xy 105.692735 -225.839024)
			(xy 105.722759 -225.794987) (xy 105.759011 -225.755916) (xy 105.800682 -225.722685) (xy 105.84684 -225.696036)
			(xy 105.896454 -225.676564) (xy 105.948416 -225.664704) (xy 106.001566 -225.660721) (xy 106.054716 -225.664704)
			(xy 106.106678 -225.676564) (xy 106.156292 -225.696036) (xy 106.20245 -225.722685) (xy 106.244121 -225.755916)
			(xy 106.280373 -225.794987) (xy 106.310397 -225.839024) (xy 106.333523 -225.887045) (xy 106.349233 -225.937975)
			(xy 106.357176 -225.990679) (xy 106.357674 -226.017328) (xy 106.357176 -226.043977) (xy 106.585756 -226.043977)
			(xy 106.585756 -225.990679) (xy 106.593699 -225.937975) (xy 106.609409 -225.887045) (xy 106.632535 -225.839024)
			(xy 106.662559 -225.794987) (xy 106.698811 -225.755916) (xy 106.740482 -225.722685) (xy 106.78664 -225.696036)
			(xy 106.836254 -225.676564) (xy 106.888216 -225.664704) (xy 106.941366 -225.660721) (xy 106.994516 -225.664704)
			(xy 107.046478 -225.676564) (xy 107.096092 -225.696036) (xy 107.14225 -225.722685) (xy 107.183921 -225.755916)
			(xy 107.220173 -225.794987) (xy 107.250197 -225.839024) (xy 107.273323 -225.887045) (xy 107.289033 -225.937975)
			(xy 107.296976 -225.990679) (xy 107.297474 -226.017328) (xy 107.296976 -226.043977) (xy 107.525556 -226.043977)
			(xy 107.525556 -225.990679) (xy 107.533499 -225.937975) (xy 107.549209 -225.887045) (xy 107.572335 -225.839024)
			(xy 107.602359 -225.794987) (xy 107.638611 -225.755916) (xy 107.680282 -225.722685) (xy 107.72644 -225.696036)
			(xy 107.776054 -225.676564) (xy 107.828016 -225.664704) (xy 107.881166 -225.660721) (xy 107.934316 -225.664704)
			(xy 107.986278 -225.676564) (xy 108.035892 -225.696036) (xy 108.08205 -225.722685) (xy 108.123721 -225.755916)
			(xy 108.159973 -225.794987) (xy 108.189997 -225.839024) (xy 108.213123 -225.887045) (xy 108.228833 -225.937975)
			(xy 108.236776 -225.990679) (xy 108.237274 -226.017328) (xy 108.236776 -226.043977) (xy 108.465356 -226.043977)
			(xy 108.465356 -225.990679) (xy 108.473299 -225.937975) (xy 108.489009 -225.887045) (xy 108.512135 -225.839024)
			(xy 108.542159 -225.794987) (xy 108.578411 -225.755916) (xy 108.620082 -225.722685) (xy 108.66624 -225.696036)
			(xy 108.715854 -225.676564) (xy 108.767816 -225.664704) (xy 108.820966 -225.660721) (xy 108.874116 -225.664704)
			(xy 108.926078 -225.676564) (xy 108.975692 -225.696036) (xy 109.02185 -225.722685) (xy 109.063521 -225.755916)
			(xy 109.099773 -225.794987) (xy 109.129797 -225.839024) (xy 109.152923 -225.887045) (xy 109.168633 -225.937975)
			(xy 109.176576 -225.990679) (xy 109.177074 -226.017328) (xy 109.176576 -226.043977) (xy 109.405156 -226.043977)
			(xy 109.405156 -225.990679) (xy 109.413099 -225.937975) (xy 109.428809 -225.887045) (xy 109.451935 -225.839024)
			(xy 109.481959 -225.794987) (xy 109.518211 -225.755916) (xy 109.559882 -225.722685) (xy 109.60604 -225.696036)
			(xy 109.655654 -225.676564) (xy 109.707616 -225.664704) (xy 109.760766 -225.660721) (xy 109.813916 -225.664704)
			(xy 109.865878 -225.676564) (xy 109.915492 -225.696036) (xy 109.96165 -225.722685) (xy 110.003321 -225.755916)
			(xy 110.039573 -225.794987) (xy 110.069597 -225.839024) (xy 110.092723 -225.887045) (xy 110.108433 -225.937975)
			(xy 110.116376 -225.990679) (xy 110.116874 -226.017328) (xy 110.116376 -226.043977) (xy 110.344956 -226.043977)
			(xy 110.344956 -225.990679) (xy 110.352899 -225.937975) (xy 110.368609 -225.887045) (xy 110.391735 -225.839024)
			(xy 110.421759 -225.794987) (xy 110.458011 -225.755916) (xy 110.499682 -225.722685) (xy 110.54584 -225.696036)
			(xy 110.595454 -225.676564) (xy 110.647416 -225.664704) (xy 110.700566 -225.660721) (xy 110.753716 -225.664704)
			(xy 110.805678 -225.676564) (xy 110.855292 -225.696036) (xy 110.90145 -225.722685) (xy 110.943121 -225.755916)
			(xy 110.979373 -225.794987) (xy 111.009397 -225.839024) (xy 111.032523 -225.887045) (xy 111.048233 -225.937975)
			(xy 111.056176 -225.990679) (xy 111.056674 -226.017328) (xy 111.056176 -226.043977) (xy 111.284756 -226.043977)
			(xy 111.284756 -225.990679) (xy 111.292699 -225.937975) (xy 111.308409 -225.887045) (xy 111.331535 -225.839024)
			(xy 111.361559 -225.794987) (xy 111.397811 -225.755916) (xy 111.439482 -225.722685) (xy 111.48564 -225.696036)
			(xy 111.535254 -225.676564) (xy 111.587216 -225.664704) (xy 111.640366 -225.660721) (xy 111.693516 -225.664704)
			(xy 111.745478 -225.676564) (xy 111.795092 -225.696036) (xy 111.84125 -225.722685) (xy 111.882921 -225.755916)
			(xy 111.919173 -225.794987) (xy 111.949197 -225.839024) (xy 111.972323 -225.887045) (xy 111.988033 -225.937975)
			(xy 111.995976 -225.990679) (xy 111.996474 -226.017328) (xy 111.995976 -226.043977) (xy 112.224556 -226.043977)
			(xy 112.224556 -225.990679) (xy 112.232499 -225.937975) (xy 112.248209 -225.887045) (xy 112.271335 -225.839024)
			(xy 112.301359 -225.794987) (xy 112.337611 -225.755916) (xy 112.379282 -225.722685) (xy 112.42544 -225.696036)
			(xy 112.475054 -225.676564) (xy 112.527016 -225.664704) (xy 112.580166 -225.660721) (xy 112.633316 -225.664704)
			(xy 112.685278 -225.676564) (xy 112.734892 -225.696036) (xy 112.78105 -225.722685) (xy 112.822721 -225.755916)
			(xy 112.858973 -225.794987) (xy 112.888997 -225.839024) (xy 112.912123 -225.887045) (xy 112.927833 -225.937975)
			(xy 112.935776 -225.990679) (xy 112.936274 -226.017328) (xy 112.935776 -226.043977) (xy 113.164356 -226.043977)
			(xy 113.164356 -225.990679) (xy 113.172299 -225.937975) (xy 113.188009 -225.887045) (xy 113.211135 -225.839024)
			(xy 113.241159 -225.794987) (xy 113.277411 -225.755916) (xy 113.319082 -225.722685) (xy 113.36524 -225.696036)
			(xy 113.414854 -225.676564) (xy 113.466816 -225.664704) (xy 113.519966 -225.660721) (xy 113.573116 -225.664704)
			(xy 113.625078 -225.676564) (xy 113.674692 -225.696036) (xy 113.72085 -225.722685) (xy 113.762521 -225.755916)
			(xy 113.798773 -225.794987) (xy 113.828797 -225.839024) (xy 113.851923 -225.887045) (xy 113.867633 -225.937975)
			(xy 113.875576 -225.990679) (xy 113.876074 -226.017328) (xy 113.875576 -226.043977) (xy 114.104156 -226.043977)
			(xy 114.104156 -225.990679) (xy 114.112099 -225.937975) (xy 114.127809 -225.887045) (xy 114.150935 -225.839024)
			(xy 114.180959 -225.794987) (xy 114.217211 -225.755916) (xy 114.258882 -225.722685) (xy 114.30504 -225.696036)
			(xy 114.354654 -225.676564) (xy 114.406616 -225.664704) (xy 114.459766 -225.660721) (xy 114.512916 -225.664704)
			(xy 114.564878 -225.676564) (xy 114.614492 -225.696036) (xy 114.66065 -225.722685) (xy 114.702321 -225.755916)
			(xy 114.738573 -225.794987) (xy 114.768597 -225.839024) (xy 114.791723 -225.887045) (xy 114.807433 -225.937975)
			(xy 114.815376 -225.990679) (xy 114.815874 -226.017328) (xy 114.815376 -226.043977) (xy 115.043956 -226.043977)
			(xy 115.043956 -225.990679) (xy 115.051899 -225.937975) (xy 115.067609 -225.887045) (xy 115.090735 -225.839024)
			(xy 115.120759 -225.794987) (xy 115.157011 -225.755916) (xy 115.198682 -225.722685) (xy 115.24484 -225.696036)
			(xy 115.294454 -225.676564) (xy 115.346416 -225.664704) (xy 115.399566 -225.660721) (xy 115.452716 -225.664704)
			(xy 115.504678 -225.676564) (xy 115.554292 -225.696036) (xy 115.60045 -225.722685) (xy 115.642121 -225.755916)
			(xy 115.678373 -225.794987) (xy 115.708397 -225.839024) (xy 115.731523 -225.887045) (xy 115.747233 -225.937975)
			(xy 115.755176 -225.990679) (xy 115.755674 -226.017328) (xy 115.755176 -226.043977) (xy 115.983756 -226.043977)
			(xy 115.983756 -225.990679) (xy 115.991699 -225.937975) (xy 116.007409 -225.887045) (xy 116.030535 -225.839024)
			(xy 116.060559 -225.794987) (xy 116.096811 -225.755916) (xy 116.138482 -225.722685) (xy 116.18464 -225.696036)
			(xy 116.234254 -225.676564) (xy 116.286216 -225.664704) (xy 116.339366 -225.660721) (xy 116.392516 -225.664704)
			(xy 116.444478 -225.676564) (xy 116.494092 -225.696036) (xy 116.54025 -225.722685) (xy 116.581921 -225.755916)
			(xy 116.618173 -225.794987) (xy 116.648197 -225.839024) (xy 116.671323 -225.887045) (xy 116.687033 -225.937975)
			(xy 116.694976 -225.990679) (xy 116.695474 -226.017328) (xy 116.694976 -226.043977) (xy 116.923556 -226.043977)
			(xy 116.923556 -225.990679) (xy 116.931499 -225.937975) (xy 116.947209 -225.887045) (xy 116.970335 -225.839024)
			(xy 117.000359 -225.794987) (xy 117.036611 -225.755916) (xy 117.078282 -225.722685) (xy 117.12444 -225.696036)
			(xy 117.174054 -225.676564) (xy 117.226016 -225.664704) (xy 117.279166 -225.660721) (xy 117.332316 -225.664704)
			(xy 117.384278 -225.676564) (xy 117.433892 -225.696036) (xy 117.48005 -225.722685) (xy 117.521721 -225.755916)
			(xy 117.557973 -225.794987) (xy 117.587997 -225.839024) (xy 117.611123 -225.887045) (xy 117.626833 -225.937975)
			(xy 117.634776 -225.990679) (xy 117.635274 -226.017328) (xy 117.634776 -226.043977) (xy 117.863356 -226.043977)
			(xy 117.863356 -225.990679) (xy 117.871299 -225.937975) (xy 117.887009 -225.887045) (xy 117.910135 -225.839024)
			(xy 117.940159 -225.794987) (xy 117.976411 -225.755916) (xy 118.018082 -225.722685) (xy 118.06424 -225.696036)
			(xy 118.113854 -225.676564) (xy 118.165816 -225.664704) (xy 118.218966 -225.660721) (xy 118.272116 -225.664704)
			(xy 118.324078 -225.676564) (xy 118.373692 -225.696036) (xy 118.41985 -225.722685) (xy 118.461521 -225.755916)
			(xy 118.497773 -225.794987) (xy 118.527797 -225.839024) (xy 118.550923 -225.887045) (xy 118.566633 -225.937975)
			(xy 118.574576 -225.990679) (xy 118.575074 -226.017328) (xy 118.574576 -226.043977) (xy 118.803156 -226.043977)
			(xy 118.803156 -225.990679) (xy 118.811099 -225.937975) (xy 118.826809 -225.887045) (xy 118.849935 -225.839024)
			(xy 118.879959 -225.794987) (xy 118.916211 -225.755916) (xy 118.957882 -225.722685) (xy 119.00404 -225.696036)
			(xy 119.053654 -225.676564) (xy 119.105616 -225.664704) (xy 119.158766 -225.660721) (xy 119.211916 -225.664704)
			(xy 119.263878 -225.676564) (xy 119.313492 -225.696036) (xy 119.35965 -225.722685) (xy 119.401321 -225.755916)
			(xy 119.437573 -225.794987) (xy 119.467597 -225.839024) (xy 119.490723 -225.887045) (xy 119.506433 -225.937975)
			(xy 119.514376 -225.990679) (xy 119.514874 -226.017328) (xy 119.514376 -226.043977) (xy 119.506433 -226.096681)
			(xy 119.490723 -226.147611) (xy 119.467597 -226.195632) (xy 119.437573 -226.239669) (xy 119.401321 -226.27874)
			(xy 119.35965 -226.311971) (xy 119.313492 -226.33862) (xy 119.263878 -226.358092) (xy 119.211916 -226.369952)
			(xy 119.158766 -226.373936) (xy 119.105616 -226.369952) (xy 119.053654 -226.358092) (xy 119.00404 -226.33862)
			(xy 118.957882 -226.311971) (xy 118.916211 -226.27874) (xy 118.879959 -226.239669) (xy 118.849935 -226.195632)
			(xy 118.826809 -226.147611) (xy 118.811099 -226.096681) (xy 118.803156 -226.043977) (xy 118.574576 -226.043977)
			(xy 118.566633 -226.096681) (xy 118.550923 -226.147611) (xy 118.527797 -226.195632) (xy 118.497773 -226.239669)
			(xy 118.461521 -226.27874) (xy 118.41985 -226.311971) (xy 118.373692 -226.33862) (xy 118.324078 -226.358092)
			(xy 118.272116 -226.369952) (xy 118.218966 -226.373936) (xy 118.165816 -226.369952) (xy 118.113854 -226.358092)
			(xy 118.06424 -226.33862) (xy 118.018082 -226.311971) (xy 117.976411 -226.27874) (xy 117.940159 -226.239669)
			(xy 117.910135 -226.195632) (xy 117.887009 -226.147611) (xy 117.871299 -226.096681) (xy 117.863356 -226.043977)
			(xy 117.634776 -226.043977) (xy 117.626833 -226.096681) (xy 117.611123 -226.147611) (xy 117.587997 -226.195632)
			(xy 117.557973 -226.239669) (xy 117.521721 -226.27874) (xy 117.48005 -226.311971) (xy 117.433892 -226.33862)
			(xy 117.384278 -226.358092) (xy 117.332316 -226.369952) (xy 117.279166 -226.373936) (xy 117.226016 -226.369952)
			(xy 117.174054 -226.358092) (xy 117.12444 -226.33862) (xy 117.078282 -226.311971) (xy 117.036611 -226.27874)
			(xy 117.000359 -226.239669) (xy 116.970335 -226.195632) (xy 116.947209 -226.147611) (xy 116.931499 -226.096681)
			(xy 116.923556 -226.043977) (xy 116.694976 -226.043977) (xy 116.687033 -226.096681) (xy 116.671323 -226.147611)
			(xy 116.648197 -226.195632) (xy 116.618173 -226.239669) (xy 116.581921 -226.27874) (xy 116.54025 -226.311971)
			(xy 116.494092 -226.33862) (xy 116.444478 -226.358092) (xy 116.392516 -226.369952) (xy 116.339366 -226.373936)
			(xy 116.286216 -226.369952) (xy 116.234254 -226.358092) (xy 116.18464 -226.33862) (xy 116.138482 -226.311971)
			(xy 116.096811 -226.27874) (xy 116.060559 -226.239669) (xy 116.030535 -226.195632) (xy 116.007409 -226.147611)
			(xy 115.991699 -226.096681) (xy 115.983756 -226.043977) (xy 115.755176 -226.043977) (xy 115.747233 -226.096681)
			(xy 115.731523 -226.147611) (xy 115.708397 -226.195632) (xy 115.678373 -226.239669) (xy 115.642121 -226.27874)
			(xy 115.60045 -226.311971) (xy 115.554292 -226.33862) (xy 115.504678 -226.358092) (xy 115.452716 -226.369952)
			(xy 115.399566 -226.373936) (xy 115.346416 -226.369952) (xy 115.294454 -226.358092) (xy 115.24484 -226.33862)
			(xy 115.198682 -226.311971) (xy 115.157011 -226.27874) (xy 115.120759 -226.239669) (xy 115.090735 -226.195632)
			(xy 115.067609 -226.147611) (xy 115.051899 -226.096681) (xy 115.043956 -226.043977) (xy 114.815376 -226.043977)
			(xy 114.807433 -226.096681) (xy 114.791723 -226.147611) (xy 114.768597 -226.195632) (xy 114.738573 -226.239669)
			(xy 114.702321 -226.27874) (xy 114.66065 -226.311971) (xy 114.614492 -226.33862) (xy 114.564878 -226.358092)
			(xy 114.512916 -226.369952) (xy 114.459766 -226.373936) (xy 114.406616 -226.369952) (xy 114.354654 -226.358092)
			(xy 114.30504 -226.33862) (xy 114.258882 -226.311971) (xy 114.217211 -226.27874) (xy 114.180959 -226.239669)
			(xy 114.150935 -226.195632) (xy 114.127809 -226.147611) (xy 114.112099 -226.096681) (xy 114.104156 -226.043977)
			(xy 113.875576 -226.043977) (xy 113.867633 -226.096681) (xy 113.851923 -226.147611) (xy 113.828797 -226.195632)
			(xy 113.798773 -226.239669) (xy 113.762521 -226.27874) (xy 113.72085 -226.311971) (xy 113.674692 -226.33862)
			(xy 113.625078 -226.358092) (xy 113.573116 -226.369952) (xy 113.519966 -226.373936) (xy 113.466816 -226.369952)
			(xy 113.414854 -226.358092) (xy 113.36524 -226.33862) (xy 113.319082 -226.311971) (xy 113.277411 -226.27874)
			(xy 113.241159 -226.239669) (xy 113.211135 -226.195632) (xy 113.188009 -226.147611) (xy 113.172299 -226.096681)
			(xy 113.164356 -226.043977) (xy 112.935776 -226.043977) (xy 112.927833 -226.096681) (xy 112.912123 -226.147611)
			(xy 112.888997 -226.195632) (xy 112.858973 -226.239669) (xy 112.822721 -226.27874) (xy 112.78105 -226.311971)
			(xy 112.734892 -226.33862) (xy 112.685278 -226.358092) (xy 112.633316 -226.369952) (xy 112.580166 -226.373936)
			(xy 112.527016 -226.369952) (xy 112.475054 -226.358092) (xy 112.42544 -226.33862) (xy 112.379282 -226.311971)
			(xy 112.337611 -226.27874) (xy 112.301359 -226.239669) (xy 112.271335 -226.195632) (xy 112.248209 -226.147611)
			(xy 112.232499 -226.096681) (xy 112.224556 -226.043977) (xy 111.995976 -226.043977) (xy 111.988033 -226.096681)
			(xy 111.972323 -226.147611) (xy 111.949197 -226.195632) (xy 111.919173 -226.239669) (xy 111.882921 -226.27874)
			(xy 111.84125 -226.311971) (xy 111.795092 -226.33862) (xy 111.745478 -226.358092) (xy 111.693516 -226.369952)
			(xy 111.640366 -226.373936) (xy 111.587216 -226.369952) (xy 111.535254 -226.358092) (xy 111.48564 -226.33862)
			(xy 111.439482 -226.311971) (xy 111.397811 -226.27874) (xy 111.361559 -226.239669) (xy 111.331535 -226.195632)
			(xy 111.308409 -226.147611) (xy 111.292699 -226.096681) (xy 111.284756 -226.043977) (xy 111.056176 -226.043977)
			(xy 111.048233 -226.096681) (xy 111.032523 -226.147611) (xy 111.009397 -226.195632) (xy 110.979373 -226.239669)
			(xy 110.943121 -226.27874) (xy 110.90145 -226.311971) (xy 110.855292 -226.33862) (xy 110.805678 -226.358092)
			(xy 110.753716 -226.369952) (xy 110.700566 -226.373936) (xy 110.647416 -226.369952) (xy 110.595454 -226.358092)
			(xy 110.54584 -226.33862) (xy 110.499682 -226.311971) (xy 110.458011 -226.27874) (xy 110.421759 -226.239669)
			(xy 110.391735 -226.195632) (xy 110.368609 -226.147611) (xy 110.352899 -226.096681) (xy 110.344956 -226.043977)
			(xy 110.116376 -226.043977) (xy 110.108433 -226.096681) (xy 110.092723 -226.147611) (xy 110.069597 -226.195632)
			(xy 110.039573 -226.239669) (xy 110.003321 -226.27874) (xy 109.96165 -226.311971) (xy 109.915492 -226.33862)
			(xy 109.865878 -226.358092) (xy 109.813916 -226.369952) (xy 109.760766 -226.373936) (xy 109.707616 -226.369952)
			(xy 109.655654 -226.358092) (xy 109.60604 -226.33862) (xy 109.559882 -226.311971) (xy 109.518211 -226.27874)
			(xy 109.481959 -226.239669) (xy 109.451935 -226.195632) (xy 109.428809 -226.147611) (xy 109.413099 -226.096681)
			(xy 109.405156 -226.043977) (xy 109.176576 -226.043977) (xy 109.168633 -226.096681) (xy 109.152923 -226.147611)
			(xy 109.129797 -226.195632) (xy 109.099773 -226.239669) (xy 109.063521 -226.27874) (xy 109.02185 -226.311971)
			(xy 108.975692 -226.33862) (xy 108.926078 -226.358092) (xy 108.874116 -226.369952) (xy 108.820966 -226.373936)
			(xy 108.767816 -226.369952) (xy 108.715854 -226.358092) (xy 108.66624 -226.33862) (xy 108.620082 -226.311971)
			(xy 108.578411 -226.27874) (xy 108.542159 -226.239669) (xy 108.512135 -226.195632) (xy 108.489009 -226.147611)
			(xy 108.473299 -226.096681) (xy 108.465356 -226.043977) (xy 108.236776 -226.043977) (xy 108.228833 -226.096681)
			(xy 108.213123 -226.147611) (xy 108.189997 -226.195632) (xy 108.159973 -226.239669) (xy 108.123721 -226.27874)
			(xy 108.08205 -226.311971) (xy 108.035892 -226.33862) (xy 107.986278 -226.358092) (xy 107.934316 -226.369952)
			(xy 107.881166 -226.373936) (xy 107.828016 -226.369952) (xy 107.776054 -226.358092) (xy 107.72644 -226.33862)
			(xy 107.680282 -226.311971) (xy 107.638611 -226.27874) (xy 107.602359 -226.239669) (xy 107.572335 -226.195632)
			(xy 107.549209 -226.147611) (xy 107.533499 -226.096681) (xy 107.525556 -226.043977) (xy 107.296976 -226.043977)
			(xy 107.289033 -226.096681) (xy 107.273323 -226.147611) (xy 107.250197 -226.195632) (xy 107.220173 -226.239669)
			(xy 107.183921 -226.27874) (xy 107.14225 -226.311971) (xy 107.096092 -226.33862) (xy 107.046478 -226.358092)
			(xy 106.994516 -226.369952) (xy 106.941366 -226.373936) (xy 106.888216 -226.369952) (xy 106.836254 -226.358092)
			(xy 106.78664 -226.33862) (xy 106.740482 -226.311971) (xy 106.698811 -226.27874) (xy 106.662559 -226.239669)
			(xy 106.632535 -226.195632) (xy 106.609409 -226.147611) (xy 106.593699 -226.096681) (xy 106.585756 -226.043977)
			(xy 106.357176 -226.043977) (xy 106.349233 -226.096681) (xy 106.333523 -226.147611) (xy 106.310397 -226.195632)
			(xy 106.280373 -226.239669) (xy 106.244121 -226.27874) (xy 106.20245 -226.311971) (xy 106.156292 -226.33862)
			(xy 106.106678 -226.358092) (xy 106.054716 -226.369952) (xy 106.001566 -226.373936) (xy 105.948416 -226.369952)
			(xy 105.896454 -226.358092) (xy 105.84684 -226.33862) (xy 105.800682 -226.311971) (xy 105.759011 -226.27874)
			(xy 105.722759 -226.239669) (xy 105.692735 -226.195632) (xy 105.669609 -226.147611) (xy 105.653899 -226.096681)
			(xy 105.645956 -226.043977) (xy 105.417376 -226.043977) (xy 105.417351 -226.045311) (xy 105.408592 -226.100587)
			(xy 105.391293 -226.153812) (xy 105.365881 -226.203676) (xy 105.332981 -226.248951) (xy 105.293404 -226.288521)
			(xy 105.248123 -226.321413) (xy 105.198255 -226.346817) (xy 105.145027 -226.364106) (xy 105.089749 -226.372856)
			(xy 105.061766 -226.373436) (xy 105.03543 -226.372967) (xy 104.983332 -226.365221) (xy 104.932941 -226.349888)
			(xy 104.885358 -226.327303) (xy 104.841619 -226.297957) (xy 104.802678 -226.262491) (xy 104.769383 -226.221678)
			(xy 104.742461 -226.176407) (xy 104.732074 -226.152202) (xy 104.697162 -226.157065) (xy 104.62686 -226.162277)
			(xy 104.591612 -226.162616) (xy 104.556492 -226.162265) (xy 104.486443 -226.157054) (xy 104.451658 -226.152202)
			(xy 104.441233 -226.176389) (xy 104.414306 -226.221653) (xy 104.381012 -226.262463) (xy 104.342075 -226.297929)
			(xy 104.298345 -226.327281) (xy 104.250771 -226.34988) (xy 104.200391 -226.365233) (xy 104.1483 -226.373006)
			(xy 104.121966 -226.373436) (xy 104.093984 -226.372885) (xy 104.038709 -226.364125) (xy 103.985485 -226.346828)
			(xy 103.935621 -226.321419) (xy 103.890346 -226.288523) (xy 103.850774 -226.248949) (xy 103.817878 -226.203674)
			(xy 103.792469 -226.15381) (xy 103.775173 -226.100585) (xy 103.766415 -226.04531) (xy 103.765858 -226.017328)
			(xy 103.765858 -226.017074) (xy 103.766208 -225.994471) (xy 103.771942 -225.94963) (xy 103.777288 -225.927666)
			(xy 103.779306 -225.917866) (xy 103.776524 -225.898073) (xy 103.766413 -225.88083) (xy 103.750497 -225.868738)
			(xy 103.740966 -225.86569) (xy 103.721602 -225.860674) (xy 103.683116 -225.849751) (xy 103.664004 -225.843846)
			(xy 103.649674 -225.839839) (xy 103.619937 -225.839396) (xy 103.591334 -225.847543) (xy 103.566292 -225.863588)
			(xy 103.546939 -225.88617) (xy 103.534916 -225.913373) (xy 103.531243 -225.942886) (xy 103.533194 -225.957638)
			(xy 103.535567 -225.972447) (xy 103.538113 -226.002331) (xy 103.538274 -226.017328) (xy 103.537751 -226.045311)
			(xy 103.528992 -226.100587) (xy 103.511693 -226.153812) (xy 103.486281 -226.203676) (xy 103.453381 -226.248951)
			(xy 103.413804 -226.288521) (xy 103.368523 -226.321413) (xy 103.318655 -226.346817) (xy 103.265427 -226.364106)
			(xy 103.210149 -226.372856) (xy 103.182166 -226.373436) (xy 103.15583 -226.372967) (xy 103.103732 -226.365221)
			(xy 103.053341 -226.349888) (xy 103.005758 -226.327303) (xy 102.962019 -226.297957) (xy 102.923078 -226.262491)
			(xy 102.889783 -226.221678) (xy 102.862861 -226.176407) (xy 102.852474 -226.152202) (xy 102.817562 -226.157065)
			(xy 102.74726 -226.162277) (xy 102.712012 -226.162616) (xy 102.676892 -226.162265) (xy 102.606843 -226.157054)
			(xy 102.572058 -226.152202) (xy 102.561633 -226.176389) (xy 102.534706 -226.221653) (xy 102.501412 -226.262463)
			(xy 102.462475 -226.297929) (xy 102.418745 -226.327281) (xy 102.371171 -226.34988) (xy 102.320791 -226.365233)
			(xy 102.2687 -226.373006) (xy 102.242366 -226.373436) (xy 102.214384 -226.372885) (xy 102.159109 -226.364125)
			(xy 102.105885 -226.346828) (xy 102.056021 -226.321419) (xy 102.010746 -226.288523) (xy 101.971174 -226.248949)
			(xy 101.938278 -226.203674) (xy 101.912869 -226.15381) (xy 101.895573 -226.100585) (xy 101.886815 -226.04531)
			(xy 101.886258 -226.017328) (xy 101.886605 -225.994725) (xy 101.892332 -225.949882) (xy 101.897688 -225.92792)
			(xy 101.89972 -225.918088) (xy 101.896919 -225.898229) (xy 101.886731 -225.880953) (xy 101.870708 -225.868892)
			(xy 101.861112 -225.865944) (xy 101.841811 -225.86086) (xy 101.803452 -225.849809) (xy 101.784404 -225.843846)
			(xy 101.770057 -225.839874) (xy 101.740304 -225.839498) (xy 101.7117 -225.847699) (xy 101.686667 -225.863784)
			(xy 101.66732 -225.886392) (xy 101.655297 -225.91361) (xy 101.651615 -225.943137) (xy 101.653594 -225.957892)
			(xy 101.655957 -225.972638) (xy 101.658498 -226.002395) (xy 101.658674 -226.017328) (xy 101.658151 -226.045311)
			(xy 101.649392 -226.100587) (xy 101.632093 -226.153812) (xy 101.606681 -226.203676) (xy 101.573781 -226.248951)
			(xy 101.534204 -226.288521) (xy 101.488923 -226.321413) (xy 101.439055 -226.346817) (xy 101.385827 -226.364106)
			(xy 101.330549 -226.372856) (xy 101.302566 -226.373436) (xy 101.27623 -226.372967) (xy 101.224132 -226.365221)
			(xy 101.173741 -226.349888) (xy 101.126158 -226.327303) (xy 101.082419 -226.297957) (xy 101.043478 -226.262491)
			(xy 101.010183 -226.221678) (xy 100.983261 -226.176407) (xy 100.972874 -226.152202) (xy 100.937962 -226.157065)
			(xy 100.86766 -226.162277) (xy 100.832412 -226.162616) (xy 100.797292 -226.162265) (xy 100.727243 -226.157054)
			(xy 100.692458 -226.152202) (xy 100.682033 -226.176389) (xy 100.655106 -226.221653) (xy 100.621812 -226.262463)
			(xy 100.582875 -226.297929) (xy 100.539145 -226.327281) (xy 100.491571 -226.34988) (xy 100.441191 -226.365233)
			(xy 100.3891 -226.373006) (xy 100.362766 -226.373436) (xy 100.334784 -226.372885) (xy 100.279509 -226.364125)
			(xy 100.226285 -226.346828) (xy 100.176421 -226.321419) (xy 100.131146 -226.288523) (xy 100.091574 -226.248949)
			(xy 100.058678 -226.203674) (xy 100.033269 -226.15381) (xy 100.015973 -226.100585) (xy 100.007215 -226.04531)
			(xy 100.006658 -226.017328) (xy 100.006658 -226.017074) (xy 100.007008 -225.994471) (xy 100.012742 -225.94963)
			(xy 100.018088 -225.927666) (xy 100.020106 -225.917866) (xy 100.017324 -225.898073) (xy 100.007213 -225.88083)
			(xy 99.991297 -225.868738) (xy 99.981766 -225.86569) (xy 99.962402 -225.860674) (xy 99.923916 -225.849751)
			(xy 99.904804 -225.843846) (xy 99.890474 -225.839839) (xy 99.860737 -225.839396) (xy 99.832134 -225.847543)
			(xy 99.807092 -225.863588) (xy 99.787739 -225.88617) (xy 99.775716 -225.913373) (xy 99.772043 -225.942886)
			(xy 99.773994 -225.957638) (xy 99.776367 -225.972447) (xy 99.778913 -226.002331) (xy 99.779074 -226.017328)
			(xy 99.778551 -226.045311) (xy 99.769792 -226.100587) (xy 99.752493 -226.153812) (xy 99.727081 -226.203676)
			(xy 99.694181 -226.248951) (xy 99.654604 -226.288521) (xy 99.609323 -226.321413) (xy 99.559455 -226.346817)
			(xy 99.506227 -226.364106) (xy 99.450949 -226.372856) (xy 99.422966 -226.373436) (xy 99.39663 -226.372967)
			(xy 99.344532 -226.365221) (xy 99.294141 -226.349888) (xy 99.246558 -226.327303) (xy 99.202819 -226.297957)
			(xy 99.163878 -226.262491) (xy 99.130583 -226.221678) (xy 99.103661 -226.176407) (xy 99.093274 -226.152202)
			(xy 99.058362 -226.157065) (xy 98.98806 -226.162277) (xy 98.952812 -226.162616) (xy 98.917692 -226.162265)
			(xy 98.847643 -226.157054) (xy 98.812858 -226.152202) (xy 98.802433 -226.176389) (xy 98.775506 -226.221653)
			(xy 98.742212 -226.262463) (xy 98.703275 -226.297929) (xy 98.659545 -226.327281) (xy 98.611971 -226.34988)
			(xy 98.561591 -226.365233) (xy 98.5095 -226.373006) (xy 98.483166 -226.373436) (xy 98.455184 -226.372885)
			(xy 98.399909 -226.364125) (xy 98.346685 -226.346828) (xy 98.296821 -226.321419) (xy 98.251546 -226.288523)
			(xy 98.211974 -226.248949) (xy 98.179078 -226.203674) (xy 98.153669 -226.15381) (xy 98.136373 -226.100585)
			(xy 98.127615 -226.04531) (xy 98.127058 -226.017328) (xy 98.127058 -226.017074) (xy 98.127408 -225.994471)
			(xy 98.133142 -225.94963) (xy 98.138488 -225.927666) (xy 98.140506 -225.917866) (xy 98.137724 -225.898073)
			(xy 98.127613 -225.88083) (xy 98.111697 -225.868738) (xy 98.102166 -225.86569) (xy 98.082802 -225.860674)
			(xy 98.044316 -225.849751) (xy 98.025204 -225.843846) (xy 98.010874 -225.839839) (xy 97.981137 -225.839396)
			(xy 97.952534 -225.847543) (xy 97.927492 -225.863588) (xy 97.908139 -225.88617) (xy 97.896116 -225.913373)
			(xy 97.892443 -225.942886) (xy 97.894394 -225.957638) (xy 97.896767 -225.972447) (xy 97.899313 -226.002331)
			(xy 97.899474 -226.017328) (xy 97.898951 -226.045311) (xy 97.890192 -226.100587) (xy 97.872893 -226.153812)
			(xy 97.847481 -226.203676) (xy 97.814581 -226.248951) (xy 97.775004 -226.288521) (xy 97.729723 -226.321413)
			(xy 97.679855 -226.346817) (xy 97.626627 -226.364106) (xy 97.571349 -226.372856) (xy 97.543366 -226.373436)
			(xy 97.51703 -226.372967) (xy 97.464932 -226.365221) (xy 97.414541 -226.349888) (xy 97.366958 -226.327303)
			(xy 97.323219 -226.297957) (xy 97.284278 -226.262491) (xy 97.250983 -226.221678) (xy 97.224061 -226.176407)
			(xy 97.213674 -226.152202) (xy 97.178762 -226.157065) (xy 97.10846 -226.162277) (xy 97.073212 -226.162616)
			(xy 97.038092 -226.162265) (xy 96.968043 -226.157054) (xy 96.933258 -226.152202) (xy 96.922833 -226.176389)
			(xy 96.895906 -226.221653) (xy 96.862612 -226.262463) (xy 96.823675 -226.297929) (xy 96.779945 -226.327281)
			(xy 96.732371 -226.34988) (xy 96.681991 -226.365233) (xy 96.6299 -226.373006) (xy 96.603566 -226.373436)
			(xy 96.575584 -226.372885) (xy 96.520309 -226.364125) (xy 96.467085 -226.346828) (xy 96.417221 -226.321419)
			(xy 96.371946 -226.288523) (xy 96.332374 -226.248949) (xy 96.299478 -226.203674) (xy 96.274069 -226.15381)
			(xy 96.256773 -226.100585) (xy 96.248015 -226.04531) (xy 96.247458 -226.017328) (xy 96.247805 -225.994725)
			(xy 96.253532 -225.949882) (xy 96.258888 -225.92792) (xy 96.26092 -225.918088) (xy 96.258119 -225.898229)
			(xy 96.247931 -225.880953) (xy 96.231908 -225.868892) (xy 96.222312 -225.865944) (xy 96.203011 -225.86086)
			(xy 96.164652 -225.849809) (xy 96.145604 -225.843846) (xy 96.131257 -225.839874) (xy 96.101504 -225.839498)
			(xy 96.0729 -225.847699) (xy 96.047867 -225.863784) (xy 96.02852 -225.886392) (xy 96.016497 -225.91361)
			(xy 96.012815 -225.943137) (xy 96.014794 -225.957892) (xy 96.017157 -225.972638) (xy 96.019698 -226.002395)
			(xy 96.019874 -226.017328) (xy 96.019351 -226.045311) (xy 96.010592 -226.100587) (xy 95.993293 -226.153812)
			(xy 95.967881 -226.203676) (xy 95.934981 -226.248951) (xy 95.895404 -226.288521) (xy 95.850123 -226.321413)
			(xy 95.800255 -226.346817) (xy 95.747027 -226.364106) (xy 95.691749 -226.372856) (xy 95.663766 -226.373436)
			(xy 95.63743 -226.372967) (xy 95.585332 -226.365221) (xy 95.534941 -226.349888) (xy 95.487358 -226.327303)
			(xy 95.443619 -226.297957) (xy 95.404678 -226.262491) (xy 95.371383 -226.221678) (xy 95.344461 -226.176407)
			(xy 95.334074 -226.152202) (xy 95.299162 -226.157065) (xy 95.22886 -226.162277) (xy 95.193612 -226.162616)
			(xy 95.158492 -226.162265) (xy 95.088443 -226.157054) (xy 95.053658 -226.152202) (xy 95.043233 -226.176389)
			(xy 95.016306 -226.221653) (xy 94.983012 -226.262463) (xy 94.944075 -226.297929) (xy 94.900345 -226.327281)
			(xy 94.852771 -226.34988) (xy 94.802391 -226.365233) (xy 94.7503 -226.373006) (xy 94.723966 -226.373436)
			(xy 94.695984 -226.372885) (xy 94.640709 -226.364125) (xy 94.587485 -226.346828) (xy 94.537621 -226.321419)
			(xy 94.492346 -226.288523) (xy 94.452774 -226.248949) (xy 94.419878 -226.203674) (xy 94.394469 -226.15381)
			(xy 94.377173 -226.100585) (xy 94.368415 -226.04531) (xy 94.367858 -226.017328) (xy 94.367858 -226.017074)
			(xy 94.368208 -225.994471) (xy 94.373942 -225.94963) (xy 94.379288 -225.927666) (xy 94.381306 -225.917866)
			(xy 94.378524 -225.898073) (xy 94.368413 -225.88083) (xy 94.352497 -225.868738) (xy 94.342966 -225.86569)
			(xy 94.323602 -225.860674) (xy 94.285116 -225.849751) (xy 94.266004 -225.843846) (xy 94.251674 -225.839839)
			(xy 94.221937 -225.839396) (xy 94.193334 -225.847543) (xy 94.168292 -225.863588) (xy 94.148939 -225.88617)
			(xy 94.136916 -225.913373) (xy 94.133243 -225.942886) (xy 94.135194 -225.957638) (xy 94.137567 -225.972447)
			(xy 94.140113 -226.002331) (xy 94.140274 -226.017328) (xy 94.139751 -226.045311) (xy 94.130992 -226.100587)
			(xy 94.113693 -226.153812) (xy 94.088281 -226.203676) (xy 94.055381 -226.248951) (xy 94.015804 -226.288521)
			(xy 93.970523 -226.321413) (xy 93.920655 -226.346817) (xy 93.867427 -226.364106) (xy 93.812149 -226.372856)
			(xy 93.784166 -226.373436) (xy 93.75783 -226.372967) (xy 93.705732 -226.365221) (xy 93.655341 -226.349888)
			(xy 93.607758 -226.327303) (xy 93.564019 -226.297957) (xy 93.525078 -226.262491) (xy 93.491783 -226.221678)
			(xy 93.464861 -226.176407) (xy 93.454474 -226.152202) (xy 93.419562 -226.157065) (xy 93.34926 -226.162277)
			(xy 93.314012 -226.162616) (xy 93.278892 -226.162265) (xy 93.208843 -226.157054) (xy 93.174058 -226.152202)
			(xy 93.163633 -226.176389) (xy 93.136706 -226.221653) (xy 93.103412 -226.262463) (xy 93.064475 -226.297929)
			(xy 93.020745 -226.327281) (xy 92.973171 -226.34988) (xy 92.922791 -226.365233) (xy 92.8707 -226.373006)
			(xy 92.844366 -226.373436) (xy 92.816384 -226.372885) (xy 92.761109 -226.364125) (xy 92.707885 -226.346828)
			(xy 92.658021 -226.321419) (xy 92.612746 -226.288523) (xy 92.573174 -226.248949) (xy 92.540278 -226.203674)
			(xy 92.514869 -226.15381) (xy 92.497573 -226.100585) (xy 92.488815 -226.04531) (xy 92.488258 -226.017328)
			(xy 92.488258 -226.017074) (xy 92.488608 -225.994471) (xy 92.494342 -225.94963) (xy 92.499688 -225.927666)
			(xy 92.501706 -225.917866) (xy 92.498924 -225.898073) (xy 92.488813 -225.88083) (xy 92.472897 -225.868738)
			(xy 92.463366 -225.86569) (xy 92.444002 -225.860674) (xy 92.405516 -225.849751) (xy 92.386404 -225.843846)
			(xy 92.372074 -225.839839) (xy 92.342337 -225.839396) (xy 92.313734 -225.847543) (xy 92.288692 -225.863588)
			(xy 92.269339 -225.88617) (xy 92.257316 -225.913373) (xy 92.253643 -225.942886) (xy 92.255594 -225.957638)
			(xy 92.257967 -225.972447) (xy 92.260513 -226.002331) (xy 92.260674 -226.017328) (xy 92.260151 -226.045311)
			(xy 92.251392 -226.100587) (xy 92.234093 -226.153812) (xy 92.208681 -226.203676) (xy 92.175781 -226.248951)
			(xy 92.136204 -226.288521) (xy 92.090923 -226.321413) (xy 92.041055 -226.346817) (xy 91.987827 -226.364106)
			(xy 91.932549 -226.372856) (xy 91.904566 -226.373436) (xy 91.87823 -226.372967) (xy 91.826132 -226.365221)
			(xy 91.775741 -226.349888) (xy 91.728158 -226.327303) (xy 91.684419 -226.297957) (xy 91.645478 -226.262491)
			(xy 91.612183 -226.221678) (xy 91.585261 -226.176407) (xy 91.574874 -226.152202) (xy 91.539962 -226.157065)
			(xy 91.46966 -226.162277) (xy 91.434412 -226.162616) (xy 91.399228 -226.16227) (xy 91.329053 -226.157056)
			(xy 91.294204 -226.152202) (xy 91.283778 -226.176387) (xy 91.256849 -226.221646) (xy 91.223554 -226.262451)
			(xy 91.184617 -226.297911) (xy 91.140886 -226.327257) (xy 91.093313 -226.349849) (xy 91.042933 -226.365194)
			(xy 90.990844 -226.37296) (xy 90.964512 -226.373436) (xy 90.936527 -226.372888) (xy 90.881247 -226.364135)
			(xy 90.828017 -226.346841) (xy 90.778147 -226.321434) (xy 90.732865 -226.288539) (xy 90.693287 -226.248965)
			(xy 90.660386 -226.203687) (xy 90.634974 -226.15382) (xy 90.617675 -226.100592) (xy 90.608915 -226.045312)
			(xy 90.608404 -226.017328) (xy 90.608404 -226.017074) (xy 90.608754 -225.994471) (xy 90.614487 -225.94963)
			(xy 90.619834 -225.927666) (xy 90.621851 -225.917864) (xy 90.619069 -225.898067) (xy 90.608962 -225.880818)
			(xy 90.593051 -225.868714) (xy 90.583512 -225.86569) (xy 90.564213 -225.860668) (xy 90.525854 -225.849744)
			(xy 90.506804 -225.843846) (xy 90.492474 -225.839839) (xy 90.462737 -225.839396) (xy 90.434134 -225.847543)
			(xy 90.409092 -225.863588) (xy 90.389739 -225.88617) (xy 90.377716 -225.913373) (xy 90.374043 -225.942886)
			(xy 90.375994 -225.957638) (xy 90.378367 -225.972447) (xy 90.380913 -226.002331) (xy 90.381074 -226.017328)
			(xy 90.380551 -226.045311) (xy 90.371792 -226.100587) (xy 90.354493 -226.153812) (xy 90.329081 -226.203676)
			(xy 90.296181 -226.248951) (xy 90.256604 -226.288521) (xy 90.211323 -226.321413) (xy 90.161455 -226.346817)
			(xy 90.108227 -226.364106) (xy 90.052949 -226.372856) (xy 90.024966 -226.373436) (xy 89.997249 -226.372914)
			(xy 89.942482 -226.364337) (xy 89.889705 -226.347381) (xy 89.840192 -226.322454) (xy 89.795137 -226.290158)
			(xy 89.77503 -226.271074) (xy 89.739216 -226.256342) (xy 89.703148 -226.271582) (xy 89.686816 -226.288092)
			(xy 89.653283 -226.32023) (xy 89.636092 -226.335844) (xy 89.63122 -226.358336) (xy 89.620295 -226.403047)
			(xy 89.614248 -226.425252) (xy 89.612011 -226.435046) (xy 89.614401 -226.45497) (xy 89.624232 -226.472465)
			(xy 89.640009 -226.484866) (xy 89.649554 -226.48799) (xy 89.67427 -226.495262) (xy 89.721454 -226.515949)
			(xy 89.76516 -226.543225) (xy 89.804475 -226.576521) (xy 89.838576 -226.615139) (xy 89.866749 -226.658273)
			(xy 89.888406 -226.705019) (xy 89.903094 -226.754401) (xy 89.910504 -226.805384) (xy 89.91092 -226.831144)
			(xy 89.910394 -226.857793) (xy 90.139002 -226.857793) (xy 90.139002 -226.804495) (xy 90.146945 -226.751791)
			(xy 90.162655 -226.700861) (xy 90.185781 -226.65284) (xy 90.215805 -226.608803) (xy 90.252057 -226.569732)
			(xy 90.293728 -226.536501) (xy 90.339886 -226.509852) (xy 90.3895 -226.49038) (xy 90.441462 -226.47852)
			(xy 90.494612 -226.474537) (xy 90.547762 -226.47852) (xy 90.599724 -226.49038) (xy 90.649338 -226.509852)
			(xy 90.695496 -226.536501) (xy 90.737167 -226.569732) (xy 90.773419 -226.608803) (xy 90.803443 -226.65284)
			(xy 90.826569 -226.700861) (xy 90.842279 -226.751791) (xy 90.850222 -226.804495) (xy 90.85072 -226.831144)
			(xy 90.850222 -226.857793) (xy 91.079056 -226.857793) (xy 91.079056 -226.804495) (xy 91.086999 -226.751791)
			(xy 91.102709 -226.700861) (xy 91.125835 -226.65284) (xy 91.155859 -226.608803) (xy 91.192111 -226.569732)
			(xy 91.233782 -226.536501) (xy 91.27994 -226.509852) (xy 91.329554 -226.49038) (xy 91.381516 -226.47852)
			(xy 91.434666 -226.474537) (xy 91.487816 -226.47852) (xy 91.539778 -226.49038) (xy 91.589392 -226.509852)
			(xy 91.63555 -226.536501) (xy 91.677221 -226.569732) (xy 91.713473 -226.608803) (xy 91.743497 -226.65284)
			(xy 91.766623 -226.700861) (xy 91.782333 -226.751791) (xy 91.790276 -226.804495) (xy 91.790774 -226.831144)
			(xy 91.790276 -226.857793) (xy 92.018856 -226.857793) (xy 92.018856 -226.804495) (xy 92.026799 -226.751791)
			(xy 92.042509 -226.700861) (xy 92.065635 -226.65284) (xy 92.095659 -226.608803) (xy 92.131911 -226.569732)
			(xy 92.173582 -226.536501) (xy 92.21974 -226.509852) (xy 92.269354 -226.49038) (xy 92.321316 -226.47852)
			(xy 92.374466 -226.474537) (xy 92.427616 -226.47852) (xy 92.479578 -226.49038) (xy 92.529192 -226.509852)
			(xy 92.57535 -226.536501) (xy 92.617021 -226.569732) (xy 92.653273 -226.608803) (xy 92.683297 -226.65284)
			(xy 92.706423 -226.700861) (xy 92.722133 -226.751791) (xy 92.730076 -226.804495) (xy 92.730574 -226.831144)
			(xy 92.730076 -226.857793) (xy 92.958656 -226.857793) (xy 92.958656 -226.804495) (xy 92.966599 -226.751791)
			(xy 92.982309 -226.700861) (xy 93.005435 -226.65284) (xy 93.035459 -226.608803) (xy 93.071711 -226.569732)
			(xy 93.113382 -226.536501) (xy 93.15954 -226.509852) (xy 93.209154 -226.49038) (xy 93.261116 -226.47852)
			(xy 93.314266 -226.474537) (xy 93.367416 -226.47852) (xy 93.419378 -226.49038) (xy 93.468992 -226.509852)
			(xy 93.51515 -226.536501) (xy 93.556821 -226.569732) (xy 93.593073 -226.608803) (xy 93.623097 -226.65284)
			(xy 93.646223 -226.700861) (xy 93.661933 -226.751791) (xy 93.669876 -226.804495) (xy 93.670374 -226.831144)
			(xy 93.669876 -226.857793) (xy 93.898202 -226.857793) (xy 93.898202 -226.804495) (xy 93.906145 -226.751791)
			(xy 93.921855 -226.700861) (xy 93.944981 -226.65284) (xy 93.975005 -226.608803) (xy 94.011257 -226.569732)
			(xy 94.052928 -226.536501) (xy 94.099086 -226.509852) (xy 94.1487 -226.49038) (xy 94.200662 -226.47852)
			(xy 94.253812 -226.474537) (xy 94.306962 -226.47852) (xy 94.358924 -226.49038) (xy 94.408538 -226.509852)
			(xy 94.454696 -226.536501) (xy 94.496367 -226.569732) (xy 94.532619 -226.608803) (xy 94.562643 -226.65284)
			(xy 94.585769 -226.700861) (xy 94.601479 -226.751791) (xy 94.609422 -226.804495) (xy 94.60992 -226.831144)
			(xy 94.609422 -226.857793) (xy 94.838002 -226.857793) (xy 94.838002 -226.804495) (xy 94.845945 -226.751791)
			(xy 94.861655 -226.700861) (xy 94.884781 -226.65284) (xy 94.914805 -226.608803) (xy 94.951057 -226.569732)
			(xy 94.992728 -226.536501) (xy 95.038886 -226.509852) (xy 95.0885 -226.49038) (xy 95.140462 -226.47852)
			(xy 95.193612 -226.474537) (xy 95.246762 -226.47852) (xy 95.298724 -226.49038) (xy 95.348338 -226.509852)
			(xy 95.394496 -226.536501) (xy 95.436167 -226.569732) (xy 95.472419 -226.608803) (xy 95.502443 -226.65284)
			(xy 95.525569 -226.700861) (xy 95.541279 -226.751791) (xy 95.549222 -226.804495) (xy 95.54972 -226.831144)
			(xy 95.549222 -226.857793) (xy 95.778056 -226.857793) (xy 95.778056 -226.804495) (xy 95.785999 -226.751791)
			(xy 95.801709 -226.700861) (xy 95.824835 -226.65284) (xy 95.854859 -226.608803) (xy 95.891111 -226.569732)
			(xy 95.932782 -226.536501) (xy 95.97894 -226.509852) (xy 96.028554 -226.49038) (xy 96.080516 -226.47852)
			(xy 96.133666 -226.474537) (xy 96.186816 -226.47852) (xy 96.238778 -226.49038) (xy 96.288392 -226.509852)
			(xy 96.33455 -226.536501) (xy 96.376221 -226.569732) (xy 96.412473 -226.608803) (xy 96.442497 -226.65284)
			(xy 96.465623 -226.700861) (xy 96.481333 -226.751791) (xy 96.489276 -226.804495) (xy 96.489774 -226.831144)
			(xy 96.489276 -226.857793) (xy 96.717602 -226.857793) (xy 96.717602 -226.804495) (xy 96.725545 -226.751791)
			(xy 96.741255 -226.700861) (xy 96.764381 -226.65284) (xy 96.794405 -226.608803) (xy 96.830657 -226.569732)
			(xy 96.872328 -226.536501) (xy 96.918486 -226.509852) (xy 96.9681 -226.49038) (xy 97.020062 -226.47852)
			(xy 97.073212 -226.474537) (xy 97.126362 -226.47852) (xy 97.178324 -226.49038) (xy 97.227938 -226.509852)
			(xy 97.274096 -226.536501) (xy 97.315767 -226.569732) (xy 97.352019 -226.608803) (xy 97.382043 -226.65284)
			(xy 97.405169 -226.700861) (xy 97.420879 -226.751791) (xy 97.428822 -226.804495) (xy 97.42932 -226.831144)
			(xy 97.428822 -226.857793) (xy 97.657402 -226.857793) (xy 97.657402 -226.804495) (xy 97.665345 -226.751791)
			(xy 97.681055 -226.700861) (xy 97.704181 -226.65284) (xy 97.734205 -226.608803) (xy 97.770457 -226.569732)
			(xy 97.812128 -226.536501) (xy 97.858286 -226.509852) (xy 97.9079 -226.49038) (xy 97.959862 -226.47852)
			(xy 98.013012 -226.474537) (xy 98.066162 -226.47852) (xy 98.118124 -226.49038) (xy 98.167738 -226.509852)
			(xy 98.213896 -226.536501) (xy 98.255567 -226.569732) (xy 98.291819 -226.608803) (xy 98.321843 -226.65284)
			(xy 98.344969 -226.700861) (xy 98.360679 -226.751791) (xy 98.368622 -226.804495) (xy 98.36912 -226.831144)
			(xy 98.368622 -226.857793) (xy 98.597456 -226.857793) (xy 98.597456 -226.804495) (xy 98.605399 -226.751791)
			(xy 98.621109 -226.700861) (xy 98.644235 -226.65284) (xy 98.674259 -226.608803) (xy 98.710511 -226.569732)
			(xy 98.752182 -226.536501) (xy 98.79834 -226.509852) (xy 98.847954 -226.49038) (xy 98.899916 -226.47852)
			(xy 98.953066 -226.474537) (xy 99.006216 -226.47852) (xy 99.058178 -226.49038) (xy 99.107792 -226.509852)
			(xy 99.15395 -226.536501) (xy 99.195621 -226.569732) (xy 99.231873 -226.608803) (xy 99.261897 -226.65284)
			(xy 99.285023 -226.700861) (xy 99.300733 -226.751791) (xy 99.308676 -226.804495) (xy 99.309174 -226.831144)
			(xy 99.308676 -226.857793) (xy 99.537256 -226.857793) (xy 99.537256 -226.804495) (xy 99.545199 -226.751791)
			(xy 99.560909 -226.700861) (xy 99.584035 -226.65284) (xy 99.614059 -226.608803) (xy 99.650311 -226.569732)
			(xy 99.691982 -226.536501) (xy 99.73814 -226.509852) (xy 99.787754 -226.49038) (xy 99.839716 -226.47852)
			(xy 99.892866 -226.474537) (xy 99.946016 -226.47852) (xy 99.997978 -226.49038) (xy 100.047592 -226.509852)
			(xy 100.09375 -226.536501) (xy 100.135421 -226.569732) (xy 100.171673 -226.608803) (xy 100.201697 -226.65284)
			(xy 100.224823 -226.700861) (xy 100.240533 -226.751791) (xy 100.248476 -226.804495) (xy 100.248974 -226.831144)
			(xy 100.248476 -226.857793) (xy 100.477056 -226.857793) (xy 100.477056 -226.804495) (xy 100.484999 -226.751791)
			(xy 100.500709 -226.700861) (xy 100.523835 -226.65284) (xy 100.553859 -226.608803) (xy 100.590111 -226.569732)
			(xy 100.631782 -226.536501) (xy 100.67794 -226.509852) (xy 100.727554 -226.49038) (xy 100.779516 -226.47852)
			(xy 100.832666 -226.474537) (xy 100.885816 -226.47852) (xy 100.937778 -226.49038) (xy 100.987392 -226.509852)
			(xy 101.03355 -226.536501) (xy 101.075221 -226.569732) (xy 101.111473 -226.608803) (xy 101.141497 -226.65284)
			(xy 101.164623 -226.700861) (xy 101.180333 -226.751791) (xy 101.188276 -226.804495) (xy 101.188774 -226.831144)
			(xy 101.188276 -226.857793) (xy 101.416602 -226.857793) (xy 101.416602 -226.804495) (xy 101.424545 -226.751791)
			(xy 101.440255 -226.700861) (xy 101.463381 -226.65284) (xy 101.493405 -226.608803) (xy 101.529657 -226.569732)
			(xy 101.571328 -226.536501) (xy 101.617486 -226.509852) (xy 101.6671 -226.49038) (xy 101.719062 -226.47852)
			(xy 101.772212 -226.474537) (xy 101.825362 -226.47852) (xy 101.877324 -226.49038) (xy 101.926938 -226.509852)
			(xy 101.973096 -226.536501) (xy 102.014767 -226.569732) (xy 102.051019 -226.608803) (xy 102.081043 -226.65284)
			(xy 102.104169 -226.700861) (xy 102.119879 -226.751791) (xy 102.127822 -226.804495) (xy 102.12832 -226.831144)
			(xy 102.127822 -226.857793) (xy 102.356402 -226.857793) (xy 102.356402 -226.804495) (xy 102.364345 -226.751791)
			(xy 102.380055 -226.700861) (xy 102.403181 -226.65284) (xy 102.433205 -226.608803) (xy 102.469457 -226.569732)
			(xy 102.511128 -226.536501) (xy 102.557286 -226.509852) (xy 102.6069 -226.49038) (xy 102.658862 -226.47852)
			(xy 102.712012 -226.474537) (xy 102.765162 -226.47852) (xy 102.817124 -226.49038) (xy 102.866738 -226.509852)
			(xy 102.912896 -226.536501) (xy 102.954567 -226.569732) (xy 102.990819 -226.608803) (xy 103.020843 -226.65284)
			(xy 103.043969 -226.700861) (xy 103.059679 -226.751791) (xy 103.067622 -226.804495) (xy 103.06812 -226.831144)
			(xy 103.067622 -226.857793) (xy 103.296456 -226.857793) (xy 103.296456 -226.804495) (xy 103.304399 -226.751791)
			(xy 103.320109 -226.700861) (xy 103.343235 -226.65284) (xy 103.373259 -226.608803) (xy 103.409511 -226.569732)
			(xy 103.451182 -226.536501) (xy 103.49734 -226.509852) (xy 103.546954 -226.49038) (xy 103.598916 -226.47852)
			(xy 103.652066 -226.474537) (xy 103.705216 -226.47852) (xy 103.757178 -226.49038) (xy 103.806792 -226.509852)
			(xy 103.85295 -226.536501) (xy 103.894621 -226.569732) (xy 103.930873 -226.608803) (xy 103.960897 -226.65284)
			(xy 103.984023 -226.700861) (xy 103.999733 -226.751791) (xy 104.007676 -226.804495) (xy 104.008174 -226.831144)
			(xy 104.007676 -226.857793) (xy 104.236256 -226.857793) (xy 104.236256 -226.804495) (xy 104.244199 -226.751791)
			(xy 104.259909 -226.700861) (xy 104.283035 -226.65284) (xy 104.313059 -226.608803) (xy 104.349311 -226.569732)
			(xy 104.390982 -226.536501) (xy 104.43714 -226.509852) (xy 104.486754 -226.49038) (xy 104.538716 -226.47852)
			(xy 104.591866 -226.474537) (xy 104.645016 -226.47852) (xy 104.696978 -226.49038) (xy 104.746592 -226.509852)
			(xy 104.79275 -226.536501) (xy 104.834421 -226.569732) (xy 104.870673 -226.608803) (xy 104.900697 -226.65284)
			(xy 104.923823 -226.700861) (xy 104.939533 -226.751791) (xy 104.947476 -226.804495) (xy 104.947974 -226.831144)
			(xy 104.947476 -226.857793) (xy 105.175802 -226.857793) (xy 105.175802 -226.804495) (xy 105.183745 -226.751791)
			(xy 105.199455 -226.700861) (xy 105.222581 -226.65284) (xy 105.252605 -226.608803) (xy 105.288857 -226.569732)
			(xy 105.330528 -226.536501) (xy 105.376686 -226.509852) (xy 105.4263 -226.49038) (xy 105.478262 -226.47852)
			(xy 105.531412 -226.474537) (xy 105.584562 -226.47852) (xy 105.636524 -226.49038) (xy 105.686138 -226.509852)
			(xy 105.732296 -226.536501) (xy 105.773967 -226.569732) (xy 105.810219 -226.608803) (xy 105.840243 -226.65284)
			(xy 105.863369 -226.700861) (xy 105.879079 -226.751791) (xy 105.887022 -226.804495) (xy 105.88752 -226.831144)
			(xy 105.887022 -226.857793) (xy 106.115856 -226.857793) (xy 106.115856 -226.804495) (xy 106.123799 -226.751791)
			(xy 106.139509 -226.700861) (xy 106.162635 -226.65284) (xy 106.192659 -226.608803) (xy 106.228911 -226.569732)
			(xy 106.270582 -226.536501) (xy 106.31674 -226.509852) (xy 106.366354 -226.49038) (xy 106.418316 -226.47852)
			(xy 106.471466 -226.474537) (xy 106.524616 -226.47852) (xy 106.576578 -226.49038) (xy 106.626192 -226.509852)
			(xy 106.67235 -226.536501) (xy 106.714021 -226.569732) (xy 106.750273 -226.608803) (xy 106.780297 -226.65284)
			(xy 106.803423 -226.700861) (xy 106.819133 -226.751791) (xy 106.827076 -226.804495) (xy 106.827574 -226.831144)
			(xy 106.827076 -226.857793) (xy 107.055402 -226.857793) (xy 107.055402 -226.804495) (xy 107.063345 -226.751791)
			(xy 107.079055 -226.700861) (xy 107.102181 -226.65284) (xy 107.132205 -226.608803) (xy 107.168457 -226.569732)
			(xy 107.210128 -226.536501) (xy 107.256286 -226.509852) (xy 107.3059 -226.49038) (xy 107.357862 -226.47852)
			(xy 107.411012 -226.474537) (xy 107.464162 -226.47852) (xy 107.516124 -226.49038) (xy 107.565738 -226.509852)
			(xy 107.611896 -226.536501) (xy 107.653567 -226.569732) (xy 107.689819 -226.608803) (xy 107.719843 -226.65284)
			(xy 107.742969 -226.700861) (xy 107.758679 -226.751791) (xy 107.766622 -226.804495) (xy 107.76712 -226.831144)
			(xy 107.766622 -226.857793) (xy 107.995456 -226.857793) (xy 107.995456 -226.804495) (xy 108.003399 -226.751791)
			(xy 108.019109 -226.700861) (xy 108.042235 -226.65284) (xy 108.072259 -226.608803) (xy 108.108511 -226.569732)
			(xy 108.150182 -226.536501) (xy 108.19634 -226.509852) (xy 108.245954 -226.49038) (xy 108.297916 -226.47852)
			(xy 108.351066 -226.474537) (xy 108.404216 -226.47852) (xy 108.456178 -226.49038) (xy 108.505792 -226.509852)
			(xy 108.55195 -226.536501) (xy 108.593621 -226.569732) (xy 108.629873 -226.608803) (xy 108.659897 -226.65284)
			(xy 108.683023 -226.700861) (xy 108.698733 -226.751791) (xy 108.706676 -226.804495) (xy 108.707174 -226.831144)
			(xy 108.706676 -226.857793) (xy 108.935002 -226.857793) (xy 108.935002 -226.804495) (xy 108.942945 -226.751791)
			(xy 108.958655 -226.700861) (xy 108.981781 -226.65284) (xy 109.011805 -226.608803) (xy 109.048057 -226.569732)
			(xy 109.089728 -226.536501) (xy 109.135886 -226.509852) (xy 109.1855 -226.49038) (xy 109.237462 -226.47852)
			(xy 109.290612 -226.474537) (xy 109.343762 -226.47852) (xy 109.395724 -226.49038) (xy 109.445338 -226.509852)
			(xy 109.491496 -226.536501) (xy 109.533167 -226.569732) (xy 109.569419 -226.608803) (xy 109.599443 -226.65284)
			(xy 109.622569 -226.700861) (xy 109.638279 -226.751791) (xy 109.646222 -226.804495) (xy 109.64672 -226.831144)
			(xy 109.646222 -226.857793) (xy 109.875056 -226.857793) (xy 109.875056 -226.804495) (xy 109.882999 -226.751791)
			(xy 109.898709 -226.700861) (xy 109.921835 -226.65284) (xy 109.951859 -226.608803) (xy 109.988111 -226.569732)
			(xy 110.029782 -226.536501) (xy 110.07594 -226.509852) (xy 110.125554 -226.49038) (xy 110.177516 -226.47852)
			(xy 110.230666 -226.474537) (xy 110.283816 -226.47852) (xy 110.335778 -226.49038) (xy 110.385392 -226.509852)
			(xy 110.43155 -226.536501) (xy 110.473221 -226.569732) (xy 110.509473 -226.608803) (xy 110.539497 -226.65284)
			(xy 110.562623 -226.700861) (xy 110.578333 -226.751791) (xy 110.586276 -226.804495) (xy 110.586774 -226.831144)
			(xy 110.586276 -226.857793) (xy 110.814602 -226.857793) (xy 110.814602 -226.804495) (xy 110.822545 -226.751791)
			(xy 110.838255 -226.700861) (xy 110.861381 -226.65284) (xy 110.891405 -226.608803) (xy 110.927657 -226.569732)
			(xy 110.969328 -226.536501) (xy 111.015486 -226.509852) (xy 111.0651 -226.49038) (xy 111.117062 -226.47852)
			(xy 111.170212 -226.474537) (xy 111.223362 -226.47852) (xy 111.275324 -226.49038) (xy 111.324938 -226.509852)
			(xy 111.371096 -226.536501) (xy 111.412767 -226.569732) (xy 111.449019 -226.608803) (xy 111.479043 -226.65284)
			(xy 111.502169 -226.700861) (xy 111.517879 -226.751791) (xy 111.525822 -226.804495) (xy 111.52632 -226.831144)
			(xy 111.525822 -226.857793) (xy 111.754656 -226.857793) (xy 111.754656 -226.804495) (xy 111.762599 -226.751791)
			(xy 111.778309 -226.700861) (xy 111.801435 -226.65284) (xy 111.831459 -226.608803) (xy 111.867711 -226.569732)
			(xy 111.909382 -226.536501) (xy 111.95554 -226.509852) (xy 112.005154 -226.49038) (xy 112.057116 -226.47852)
			(xy 112.110266 -226.474537) (xy 112.163416 -226.47852) (xy 112.215378 -226.49038) (xy 112.264992 -226.509852)
			(xy 112.31115 -226.536501) (xy 112.352821 -226.569732) (xy 112.389073 -226.608803) (xy 112.419097 -226.65284)
			(xy 112.442223 -226.700861) (xy 112.457933 -226.751791) (xy 112.465876 -226.804495) (xy 112.466374 -226.831144)
			(xy 112.465876 -226.857793) (xy 112.694202 -226.857793) (xy 112.694202 -226.804495) (xy 112.702145 -226.751791)
			(xy 112.717855 -226.700861) (xy 112.740981 -226.65284) (xy 112.771005 -226.608803) (xy 112.807257 -226.569732)
			(xy 112.848928 -226.536501) (xy 112.895086 -226.509852) (xy 112.9447 -226.49038) (xy 112.996662 -226.47852)
			(xy 113.049812 -226.474537) (xy 113.102962 -226.47852) (xy 113.154924 -226.49038) (xy 113.204538 -226.509852)
			(xy 113.250696 -226.536501) (xy 113.292367 -226.569732) (xy 113.328619 -226.608803) (xy 113.358643 -226.65284)
			(xy 113.381769 -226.700861) (xy 113.397479 -226.751791) (xy 113.405422 -226.804495) (xy 113.40592 -226.831144)
			(xy 113.405422 -226.857793) (xy 113.634256 -226.857793) (xy 113.634256 -226.804495) (xy 113.642199 -226.751791)
			(xy 113.657909 -226.700861) (xy 113.681035 -226.65284) (xy 113.711059 -226.608803) (xy 113.747311 -226.569732)
			(xy 113.788982 -226.536501) (xy 113.83514 -226.509852) (xy 113.884754 -226.49038) (xy 113.936716 -226.47852)
			(xy 113.989866 -226.474537) (xy 114.043016 -226.47852) (xy 114.094978 -226.49038) (xy 114.144592 -226.509852)
			(xy 114.19075 -226.536501) (xy 114.232421 -226.569732) (xy 114.268673 -226.608803) (xy 114.298697 -226.65284)
			(xy 114.321823 -226.700861) (xy 114.337533 -226.751791) (xy 114.345476 -226.804495) (xy 114.345974 -226.831144)
			(xy 114.345476 -226.857793) (xy 114.574056 -226.857793) (xy 114.574056 -226.804495) (xy 114.581999 -226.751791)
			(xy 114.597709 -226.700861) (xy 114.620835 -226.65284) (xy 114.650859 -226.608803) (xy 114.687111 -226.569732)
			(xy 114.728782 -226.536501) (xy 114.77494 -226.509852) (xy 114.824554 -226.49038) (xy 114.876516 -226.47852)
			(xy 114.929666 -226.474537) (xy 114.982816 -226.47852) (xy 115.034778 -226.49038) (xy 115.084392 -226.509852)
			(xy 115.13055 -226.536501) (xy 115.172221 -226.569732) (xy 115.208473 -226.608803) (xy 115.238497 -226.65284)
			(xy 115.261623 -226.700861) (xy 115.277333 -226.751791) (xy 115.285276 -226.804495) (xy 115.285774 -226.831144)
			(xy 115.285276 -226.857793) (xy 115.513856 -226.857793) (xy 115.513856 -226.804495) (xy 115.521799 -226.751791)
			(xy 115.537509 -226.700861) (xy 115.560635 -226.65284) (xy 115.590659 -226.608803) (xy 115.626911 -226.569732)
			(xy 115.668582 -226.536501) (xy 115.71474 -226.509852) (xy 115.764354 -226.49038) (xy 115.816316 -226.47852)
			(xy 115.869466 -226.474537) (xy 115.922616 -226.47852) (xy 115.974578 -226.49038) (xy 116.024192 -226.509852)
			(xy 116.07035 -226.536501) (xy 116.112021 -226.569732) (xy 116.148273 -226.608803) (xy 116.178297 -226.65284)
			(xy 116.201423 -226.700861) (xy 116.217133 -226.751791) (xy 116.225076 -226.804495) (xy 116.225574 -226.831144)
			(xy 116.225076 -226.857793) (xy 116.453402 -226.857793) (xy 116.453402 -226.804495) (xy 116.461345 -226.751791)
			(xy 116.477055 -226.700861) (xy 116.500181 -226.65284) (xy 116.530205 -226.608803) (xy 116.566457 -226.569732)
			(xy 116.608128 -226.536501) (xy 116.654286 -226.509852) (xy 116.7039 -226.49038) (xy 116.755862 -226.47852)
			(xy 116.809012 -226.474537) (xy 116.862162 -226.47852) (xy 116.914124 -226.49038) (xy 116.963738 -226.509852)
			(xy 117.009896 -226.536501) (xy 117.051567 -226.569732) (xy 117.087819 -226.608803) (xy 117.117843 -226.65284)
			(xy 117.140969 -226.700861) (xy 117.156679 -226.751791) (xy 117.164622 -226.804495) (xy 117.16512 -226.831144)
			(xy 117.164622 -226.857793) (xy 117.393456 -226.857793) (xy 117.393456 -226.804495) (xy 117.401399 -226.751791)
			(xy 117.417109 -226.700861) (xy 117.440235 -226.65284) (xy 117.470259 -226.608803) (xy 117.506511 -226.569732)
			(xy 117.548182 -226.536501) (xy 117.59434 -226.509852) (xy 117.643954 -226.49038) (xy 117.695916 -226.47852)
			(xy 117.749066 -226.474537) (xy 117.802216 -226.47852) (xy 117.854178 -226.49038) (xy 117.903792 -226.509852)
			(xy 117.94995 -226.536501) (xy 117.991621 -226.569732) (xy 118.027873 -226.608803) (xy 118.057897 -226.65284)
			(xy 118.081023 -226.700861) (xy 118.096733 -226.751791) (xy 118.104676 -226.804495) (xy 118.105174 -226.831144)
			(xy 118.104676 -226.857793) (xy 118.333002 -226.857793) (xy 118.333002 -226.804495) (xy 118.340945 -226.751791)
			(xy 118.356655 -226.700861) (xy 118.379781 -226.65284) (xy 118.409805 -226.608803) (xy 118.446057 -226.569732)
			(xy 118.487728 -226.536501) (xy 118.533886 -226.509852) (xy 118.5835 -226.49038) (xy 118.635462 -226.47852)
			(xy 118.688612 -226.474537) (xy 118.741762 -226.47852) (xy 118.793724 -226.49038) (xy 118.843338 -226.509852)
			(xy 118.889496 -226.536501) (xy 118.931167 -226.569732) (xy 118.967419 -226.608803) (xy 118.997443 -226.65284)
			(xy 119.020569 -226.700861) (xy 119.036279 -226.751791) (xy 119.044222 -226.804495) (xy 119.04472 -226.831144)
			(xy 119.044222 -226.857793) (xy 119.273056 -226.857793) (xy 119.273056 -226.804495) (xy 119.280999 -226.751791)
			(xy 119.296709 -226.700861) (xy 119.319835 -226.65284) (xy 119.349859 -226.608803) (xy 119.386111 -226.569732)
			(xy 119.427782 -226.536501) (xy 119.47394 -226.509852) (xy 119.523554 -226.49038) (xy 119.575516 -226.47852)
			(xy 119.628666 -226.474537) (xy 119.681816 -226.47852) (xy 119.733778 -226.49038) (xy 119.783392 -226.509852)
			(xy 119.82955 -226.536501) (xy 119.871221 -226.569732) (xy 119.907473 -226.608803) (xy 119.937497 -226.65284)
			(xy 119.960623 -226.700861) (xy 119.976333 -226.751791) (xy 119.984276 -226.804495) (xy 119.984774 -226.831144)
			(xy 119.984276 -226.857793) (xy 120.212602 -226.857793) (xy 120.212602 -226.804495) (xy 120.220545 -226.751791)
			(xy 120.236255 -226.700861) (xy 120.259381 -226.65284) (xy 120.289405 -226.608803) (xy 120.325657 -226.569732)
			(xy 120.367328 -226.536501) (xy 120.413486 -226.509852) (xy 120.4631 -226.49038) (xy 120.515062 -226.47852)
			(xy 120.568212 -226.474537) (xy 120.621362 -226.47852) (xy 120.673324 -226.49038) (xy 120.722938 -226.509852)
			(xy 120.769096 -226.536501) (xy 120.810767 -226.569732) (xy 120.847019 -226.608803) (xy 120.877043 -226.65284)
			(xy 120.900169 -226.700861) (xy 120.915879 -226.751791) (xy 120.923822 -226.804495) (xy 120.92432 -226.831144)
			(xy 120.923822 -226.857793) (xy 121.152656 -226.857793) (xy 121.152656 -226.804495) (xy 121.160599 -226.751791)
			(xy 121.176309 -226.700861) (xy 121.199435 -226.65284) (xy 121.229459 -226.608803) (xy 121.265711 -226.569732)
			(xy 121.307382 -226.536501) (xy 121.35354 -226.509852) (xy 121.403154 -226.49038) (xy 121.455116 -226.47852)
			(xy 121.508266 -226.474537) (xy 121.561416 -226.47852) (xy 121.613378 -226.49038) (xy 121.662992 -226.509852)
			(xy 121.70915 -226.536501) (xy 121.750821 -226.569732) (xy 121.787073 -226.608803) (xy 121.817097 -226.65284)
			(xy 121.840223 -226.700861) (xy 121.855933 -226.751791) (xy 121.863876 -226.804495) (xy 121.864374 -226.831144)
			(xy 121.863876 -226.857793) (xy 122.092202 -226.857793) (xy 122.092202 -226.804495) (xy 122.100145 -226.751791)
			(xy 122.115855 -226.700861) (xy 122.138981 -226.65284) (xy 122.169005 -226.608803) (xy 122.205257 -226.569732)
			(xy 122.246928 -226.536501) (xy 122.293086 -226.509852) (xy 122.3427 -226.49038) (xy 122.394662 -226.47852)
			(xy 122.447812 -226.474537) (xy 122.500962 -226.47852) (xy 122.552924 -226.49038) (xy 122.602538 -226.509852)
			(xy 122.648696 -226.536501) (xy 122.690367 -226.569732) (xy 122.726619 -226.608803) (xy 122.756643 -226.65284)
			(xy 122.779769 -226.700861) (xy 122.795479 -226.751791) (xy 122.803422 -226.804495) (xy 122.80392 -226.831144)
			(xy 122.803422 -226.857793) (xy 123.032002 -226.857793) (xy 123.032002 -226.804495) (xy 123.039945 -226.751791)
			(xy 123.055655 -226.700861) (xy 123.078781 -226.65284) (xy 123.108805 -226.608803) (xy 123.145057 -226.569732)
			(xy 123.186728 -226.536501) (xy 123.232886 -226.509852) (xy 123.2825 -226.49038) (xy 123.334462 -226.47852)
			(xy 123.387612 -226.474537) (xy 123.440762 -226.47852) (xy 123.492724 -226.49038) (xy 123.542338 -226.509852)
			(xy 123.588496 -226.536501) (xy 123.630167 -226.569732) (xy 123.666419 -226.608803) (xy 123.696443 -226.65284)
			(xy 123.719569 -226.700861) (xy 123.735279 -226.751791) (xy 123.743222 -226.804495) (xy 123.74372 -226.831144)
			(xy 123.743222 -226.857793) (xy 123.972056 -226.857793) (xy 123.972056 -226.804495) (xy 123.979999 -226.751791)
			(xy 123.995709 -226.700861) (xy 124.018835 -226.65284) (xy 124.048859 -226.608803) (xy 124.085111 -226.569732)
			(xy 124.126782 -226.536501) (xy 124.17294 -226.509852) (xy 124.222554 -226.49038) (xy 124.274516 -226.47852)
			(xy 124.327666 -226.474537) (xy 124.380816 -226.47852) (xy 124.432778 -226.49038) (xy 124.482392 -226.509852)
			(xy 124.52855 -226.536501) (xy 124.570221 -226.569732) (xy 124.606473 -226.608803) (xy 124.636497 -226.65284)
			(xy 124.659623 -226.700861) (xy 124.675333 -226.751791) (xy 124.683276 -226.804495) (xy 124.683774 -226.831144)
			(xy 124.683276 -226.857793) (xy 124.911602 -226.857793) (xy 124.911602 -226.804495) (xy 124.919545 -226.751791)
			(xy 124.935255 -226.700861) (xy 124.958381 -226.65284) (xy 124.988405 -226.608803) (xy 125.024657 -226.569732)
			(xy 125.066328 -226.536501) (xy 125.112486 -226.509852) (xy 125.1621 -226.49038) (xy 125.214062 -226.47852)
			(xy 125.267212 -226.474537) (xy 125.320362 -226.47852) (xy 125.372324 -226.49038) (xy 125.421938 -226.509852)
			(xy 125.468096 -226.536501) (xy 125.509767 -226.569732) (xy 125.546019 -226.608803) (xy 125.576043 -226.65284)
			(xy 125.599169 -226.700861) (xy 125.614879 -226.751791) (xy 125.622822 -226.804495) (xy 125.62332 -226.831144)
			(xy 125.622822 -226.857793) (xy 125.851402 -226.857793) (xy 125.851402 -226.804495) (xy 125.859345 -226.751791)
			(xy 125.875055 -226.700861) (xy 125.898181 -226.65284) (xy 125.928205 -226.608803) (xy 125.964457 -226.569732)
			(xy 126.006128 -226.536501) (xy 126.052286 -226.509852) (xy 126.1019 -226.49038) (xy 126.153862 -226.47852)
			(xy 126.207012 -226.474537) (xy 126.260162 -226.47852) (xy 126.312124 -226.49038) (xy 126.361738 -226.509852)
			(xy 126.407896 -226.536501) (xy 126.449567 -226.569732) (xy 126.485819 -226.608803) (xy 126.515843 -226.65284)
			(xy 126.538969 -226.700861) (xy 126.554679 -226.751791) (xy 126.562622 -226.804495) (xy 126.56312 -226.831144)
			(xy 126.562622 -226.857793) (xy 126.791456 -226.857793) (xy 126.791456 -226.804495) (xy 126.799399 -226.751791)
			(xy 126.815109 -226.700861) (xy 126.838235 -226.65284) (xy 126.868259 -226.608803) (xy 126.904511 -226.569732)
			(xy 126.946182 -226.536501) (xy 126.99234 -226.509852) (xy 127.041954 -226.49038) (xy 127.093916 -226.47852)
			(xy 127.147066 -226.474537) (xy 127.200216 -226.47852) (xy 127.252178 -226.49038) (xy 127.301792 -226.509852)
			(xy 127.34795 -226.536501) (xy 127.389621 -226.569732) (xy 127.425873 -226.608803) (xy 127.455897 -226.65284)
			(xy 127.479023 -226.700861) (xy 127.494733 -226.751791) (xy 127.502676 -226.804495) (xy 127.503174 -226.831144)
			(xy 127.502676 -226.857793) (xy 127.731256 -226.857793) (xy 127.731256 -226.804495) (xy 127.739199 -226.751791)
			(xy 127.754909 -226.700861) (xy 127.778035 -226.65284) (xy 127.808059 -226.608803) (xy 127.844311 -226.569732)
			(xy 127.885982 -226.536501) (xy 127.93214 -226.509852) (xy 127.981754 -226.49038) (xy 128.033716 -226.47852)
			(xy 128.086866 -226.474537) (xy 128.140016 -226.47852) (xy 128.191978 -226.49038) (xy 128.241592 -226.509852)
			(xy 128.28775 -226.536501) (xy 128.329421 -226.569732) (xy 128.365673 -226.608803) (xy 128.395697 -226.65284)
			(xy 128.418823 -226.700861) (xy 128.434533 -226.751791) (xy 128.442476 -226.804495) (xy 128.442974 -226.831144)
			(xy 128.442476 -226.857793) (xy 128.670802 -226.857793) (xy 128.670802 -226.804495) (xy 128.678745 -226.751791)
			(xy 128.694455 -226.700861) (xy 128.717581 -226.65284) (xy 128.747605 -226.608803) (xy 128.783857 -226.569732)
			(xy 128.825528 -226.536501) (xy 128.871686 -226.509852) (xy 128.9213 -226.49038) (xy 128.973262 -226.47852)
			(xy 129.026412 -226.474537) (xy 129.079562 -226.47852) (xy 129.131524 -226.49038) (xy 129.181138 -226.509852)
			(xy 129.227296 -226.536501) (xy 129.268967 -226.569732) (xy 129.305219 -226.608803) (xy 129.335243 -226.65284)
			(xy 129.358369 -226.700861) (xy 129.374079 -226.751791) (xy 129.382022 -226.804495) (xy 129.38252 -226.831144)
			(xy 129.382022 -226.857793) (xy 129.610602 -226.857793) (xy 129.610602 -226.804495) (xy 129.618545 -226.751791)
			(xy 129.634255 -226.700861) (xy 129.657381 -226.65284) (xy 129.687405 -226.608803) (xy 129.723657 -226.569732)
			(xy 129.765328 -226.536501) (xy 129.811486 -226.509852) (xy 129.8611 -226.49038) (xy 129.913062 -226.47852)
			(xy 129.966212 -226.474537) (xy 130.019362 -226.47852) (xy 130.071324 -226.49038) (xy 130.120938 -226.509852)
			(xy 130.167096 -226.536501) (xy 130.208767 -226.569732) (xy 130.245019 -226.608803) (xy 130.275043 -226.65284)
			(xy 130.298169 -226.700861) (xy 130.313879 -226.751791) (xy 130.321822 -226.804495) (xy 130.32232 -226.831144)
			(xy 130.321822 -226.857793) (xy 130.550656 -226.857793) (xy 130.550656 -226.804495) (xy 130.558599 -226.751791)
			(xy 130.574309 -226.700861) (xy 130.597435 -226.65284) (xy 130.627459 -226.608803) (xy 130.663711 -226.569732)
			(xy 130.705382 -226.536501) (xy 130.75154 -226.509852) (xy 130.801154 -226.49038) (xy 130.853116 -226.47852)
			(xy 130.906266 -226.474537) (xy 130.959416 -226.47852) (xy 131.011378 -226.49038) (xy 131.060992 -226.509852)
			(xy 131.10715 -226.536501) (xy 131.148821 -226.569732) (xy 131.185073 -226.608803) (xy 131.215097 -226.65284)
			(xy 131.238223 -226.700861) (xy 131.253933 -226.751791) (xy 131.261876 -226.804495) (xy 131.262374 -226.831144)
			(xy 131.261876 -226.857793) (xy 131.490202 -226.857793) (xy 131.490202 -226.804495) (xy 131.498145 -226.751791)
			(xy 131.513855 -226.700861) (xy 131.536981 -226.65284) (xy 131.567005 -226.608803) (xy 131.603257 -226.569732)
			(xy 131.644928 -226.536501) (xy 131.691086 -226.509852) (xy 131.7407 -226.49038) (xy 131.792662 -226.47852)
			(xy 131.845812 -226.474537) (xy 131.898962 -226.47852) (xy 131.950924 -226.49038) (xy 132.000538 -226.509852)
			(xy 132.046696 -226.536501) (xy 132.088367 -226.569732) (xy 132.124619 -226.608803) (xy 132.154643 -226.65284)
			(xy 132.177769 -226.700861) (xy 132.193479 -226.751791) (xy 132.201422 -226.804495) (xy 132.20192 -226.831144)
			(xy 132.201422 -226.857793) (xy 132.430002 -226.857793) (xy 132.430002 -226.804495) (xy 132.437945 -226.751791)
			(xy 132.453655 -226.700861) (xy 132.476781 -226.65284) (xy 132.506805 -226.608803) (xy 132.543057 -226.569732)
			(xy 132.584728 -226.536501) (xy 132.630886 -226.509852) (xy 132.6805 -226.49038) (xy 132.732462 -226.47852)
			(xy 132.785612 -226.474537) (xy 132.838762 -226.47852) (xy 132.890724 -226.49038) (xy 132.940338 -226.509852)
			(xy 132.986496 -226.536501) (xy 133.028167 -226.569732) (xy 133.064419 -226.608803) (xy 133.094443 -226.65284)
			(xy 133.117569 -226.700861) (xy 133.133279 -226.751791) (xy 133.141222 -226.804495) (xy 133.14172 -226.831144)
			(xy 133.141222 -226.857793) (xy 133.370056 -226.857793) (xy 133.370056 -226.804495) (xy 133.377999 -226.751791)
			(xy 133.393709 -226.700861) (xy 133.416835 -226.65284) (xy 133.446859 -226.608803) (xy 133.483111 -226.569732)
			(xy 133.524782 -226.536501) (xy 133.57094 -226.509852) (xy 133.620554 -226.49038) (xy 133.672516 -226.47852)
			(xy 133.725666 -226.474537) (xy 133.778816 -226.47852) (xy 133.830778 -226.49038) (xy 133.880392 -226.509852)
			(xy 133.92655 -226.536501) (xy 133.968221 -226.569732) (xy 134.004473 -226.608803) (xy 134.034497 -226.65284)
			(xy 134.057623 -226.700861) (xy 134.073333 -226.751791) (xy 134.081276 -226.804495) (xy 134.081774 -226.831144)
			(xy 134.081276 -226.857793) (xy 134.073333 -226.910497) (xy 134.057623 -226.961427) (xy 134.034497 -227.009448)
			(xy 134.004473 -227.053485) (xy 133.968221 -227.092556) (xy 133.92655 -227.125787) (xy 133.880392 -227.152436)
			(xy 133.830778 -227.171908) (xy 133.778816 -227.183768) (xy 133.725666 -227.187752) (xy 133.672516 -227.183768)
			(xy 133.620554 -227.171908) (xy 133.57094 -227.152436) (xy 133.524782 -227.125787) (xy 133.483111 -227.092556)
			(xy 133.446859 -227.053485) (xy 133.416835 -227.009448) (xy 133.393709 -226.961427) (xy 133.377999 -226.910497)
			(xy 133.370056 -226.857793) (xy 133.141222 -226.857793) (xy 133.133279 -226.910497) (xy 133.117569 -226.961427)
			(xy 133.094443 -227.009448) (xy 133.064419 -227.053485) (xy 133.028167 -227.092556) (xy 132.986496 -227.125787)
			(xy 132.940338 -227.152436) (xy 132.890724 -227.171908) (xy 132.838762 -227.183768) (xy 132.785612 -227.187752)
			(xy 132.732462 -227.183768) (xy 132.6805 -227.171908) (xy 132.630886 -227.152436) (xy 132.584728 -227.125787)
			(xy 132.543057 -227.092556) (xy 132.506805 -227.053485) (xy 132.476781 -227.009448) (xy 132.453655 -226.961427)
			(xy 132.437945 -226.910497) (xy 132.430002 -226.857793) (xy 132.201422 -226.857793) (xy 132.193479 -226.910497)
			(xy 132.177769 -226.961427) (xy 132.154643 -227.009448) (xy 132.124619 -227.053485) (xy 132.088367 -227.092556)
			(xy 132.046696 -227.125787) (xy 132.000538 -227.152436) (xy 131.950924 -227.171908) (xy 131.898962 -227.183768)
			(xy 131.845812 -227.187752) (xy 131.792662 -227.183768) (xy 131.7407 -227.171908) (xy 131.691086 -227.152436)
			(xy 131.644928 -227.125787) (xy 131.603257 -227.092556) (xy 131.567005 -227.053485) (xy 131.536981 -227.009448)
			(xy 131.513855 -226.961427) (xy 131.498145 -226.910497) (xy 131.490202 -226.857793) (xy 131.261876 -226.857793)
			(xy 131.253933 -226.910497) (xy 131.238223 -226.961427) (xy 131.215097 -227.009448) (xy 131.185073 -227.053485)
			(xy 131.148821 -227.092556) (xy 131.10715 -227.125787) (xy 131.060992 -227.152436) (xy 131.011378 -227.171908)
			(xy 130.959416 -227.183768) (xy 130.906266 -227.187752) (xy 130.853116 -227.183768) (xy 130.801154 -227.171908)
			(xy 130.75154 -227.152436) (xy 130.705382 -227.125787) (xy 130.663711 -227.092556) (xy 130.627459 -227.053485)
			(xy 130.597435 -227.009448) (xy 130.574309 -226.961427) (xy 130.558599 -226.910497) (xy 130.550656 -226.857793)
			(xy 130.321822 -226.857793) (xy 130.313879 -226.910497) (xy 130.298169 -226.961427) (xy 130.275043 -227.009448)
			(xy 130.245019 -227.053485) (xy 130.208767 -227.092556) (xy 130.167096 -227.125787) (xy 130.120938 -227.152436)
			(xy 130.071324 -227.171908) (xy 130.019362 -227.183768) (xy 129.966212 -227.187752) (xy 129.913062 -227.183768)
			(xy 129.8611 -227.171908) (xy 129.811486 -227.152436) (xy 129.765328 -227.125787) (xy 129.723657 -227.092556)
			(xy 129.687405 -227.053485) (xy 129.657381 -227.009448) (xy 129.634255 -226.961427) (xy 129.618545 -226.910497)
			(xy 129.610602 -226.857793) (xy 129.382022 -226.857793) (xy 129.374079 -226.910497) (xy 129.358369 -226.961427)
			(xy 129.335243 -227.009448) (xy 129.305219 -227.053485) (xy 129.268967 -227.092556) (xy 129.227296 -227.125787)
			(xy 129.181138 -227.152436) (xy 129.131524 -227.171908) (xy 129.079562 -227.183768) (xy 129.026412 -227.187752)
			(xy 128.973262 -227.183768) (xy 128.9213 -227.171908) (xy 128.871686 -227.152436) (xy 128.825528 -227.125787)
			(xy 128.783857 -227.092556) (xy 128.747605 -227.053485) (xy 128.717581 -227.009448) (xy 128.694455 -226.961427)
			(xy 128.678745 -226.910497) (xy 128.670802 -226.857793) (xy 128.442476 -226.857793) (xy 128.434533 -226.910497)
			(xy 128.418823 -226.961427) (xy 128.395697 -227.009448) (xy 128.365673 -227.053485) (xy 128.329421 -227.092556)
			(xy 128.28775 -227.125787) (xy 128.241592 -227.152436) (xy 128.191978 -227.171908) (xy 128.140016 -227.183768)
			(xy 128.086866 -227.187752) (xy 128.033716 -227.183768) (xy 127.981754 -227.171908) (xy 127.93214 -227.152436)
			(xy 127.885982 -227.125787) (xy 127.844311 -227.092556) (xy 127.808059 -227.053485) (xy 127.778035 -227.009448)
			(xy 127.754909 -226.961427) (xy 127.739199 -226.910497) (xy 127.731256 -226.857793) (xy 127.502676 -226.857793)
			(xy 127.494733 -226.910497) (xy 127.479023 -226.961427) (xy 127.455897 -227.009448) (xy 127.425873 -227.053485)
			(xy 127.389621 -227.092556) (xy 127.34795 -227.125787) (xy 127.301792 -227.152436) (xy 127.252178 -227.171908)
			(xy 127.200216 -227.183768) (xy 127.147066 -227.187752) (xy 127.093916 -227.183768) (xy 127.041954 -227.171908)
			(xy 126.99234 -227.152436) (xy 126.946182 -227.125787) (xy 126.904511 -227.092556) (xy 126.868259 -227.053485)
			(xy 126.838235 -227.009448) (xy 126.815109 -226.961427) (xy 126.799399 -226.910497) (xy 126.791456 -226.857793)
			(xy 126.562622 -226.857793) (xy 126.554679 -226.910497) (xy 126.538969 -226.961427) (xy 126.515843 -227.009448)
			(xy 126.485819 -227.053485) (xy 126.449567 -227.092556) (xy 126.407896 -227.125787) (xy 126.361738 -227.152436)
			(xy 126.312124 -227.171908) (xy 126.260162 -227.183768) (xy 126.207012 -227.187752) (xy 126.153862 -227.183768)
			(xy 126.1019 -227.171908) (xy 126.052286 -227.152436) (xy 126.006128 -227.125787) (xy 125.964457 -227.092556)
			(xy 125.928205 -227.053485) (xy 125.898181 -227.009448) (xy 125.875055 -226.961427) (xy 125.859345 -226.910497)
			(xy 125.851402 -226.857793) (xy 125.622822 -226.857793) (xy 125.614879 -226.910497) (xy 125.599169 -226.961427)
			(xy 125.576043 -227.009448) (xy 125.546019 -227.053485) (xy 125.509767 -227.092556) (xy 125.468096 -227.125787)
			(xy 125.421938 -227.152436) (xy 125.372324 -227.171908) (xy 125.320362 -227.183768) (xy 125.267212 -227.187752)
			(xy 125.214062 -227.183768) (xy 125.1621 -227.171908) (xy 125.112486 -227.152436) (xy 125.066328 -227.125787)
			(xy 125.024657 -227.092556) (xy 124.988405 -227.053485) (xy 124.958381 -227.009448) (xy 124.935255 -226.961427)
			(xy 124.919545 -226.910497) (xy 124.911602 -226.857793) (xy 124.683276 -226.857793) (xy 124.675333 -226.910497)
			(xy 124.659623 -226.961427) (xy 124.636497 -227.009448) (xy 124.606473 -227.053485) (xy 124.570221 -227.092556)
			(xy 124.52855 -227.125787) (xy 124.482392 -227.152436) (xy 124.432778 -227.171908) (xy 124.380816 -227.183768)
			(xy 124.327666 -227.187752) (xy 124.274516 -227.183768) (xy 124.222554 -227.171908) (xy 124.17294 -227.152436)
			(xy 124.126782 -227.125787) (xy 124.085111 -227.092556) (xy 124.048859 -227.053485) (xy 124.018835 -227.009448)
			(xy 123.995709 -226.961427) (xy 123.979999 -226.910497) (xy 123.972056 -226.857793) (xy 123.743222 -226.857793)
			(xy 123.735279 -226.910497) (xy 123.719569 -226.961427) (xy 123.696443 -227.009448) (xy 123.666419 -227.053485)
			(xy 123.630167 -227.092556) (xy 123.588496 -227.125787) (xy 123.542338 -227.152436) (xy 123.492724 -227.171908)
			(xy 123.440762 -227.183768) (xy 123.387612 -227.187752) (xy 123.334462 -227.183768) (xy 123.2825 -227.171908)
			(xy 123.232886 -227.152436) (xy 123.186728 -227.125787) (xy 123.145057 -227.092556) (xy 123.108805 -227.053485)
			(xy 123.078781 -227.009448) (xy 123.055655 -226.961427) (xy 123.039945 -226.910497) (xy 123.032002 -226.857793)
			(xy 122.803422 -226.857793) (xy 122.795479 -226.910497) (xy 122.779769 -226.961427) (xy 122.756643 -227.009448)
			(xy 122.726619 -227.053485) (xy 122.690367 -227.092556) (xy 122.648696 -227.125787) (xy 122.602538 -227.152436)
			(xy 122.552924 -227.171908) (xy 122.500962 -227.183768) (xy 122.447812 -227.187752) (xy 122.394662 -227.183768)
			(xy 122.3427 -227.171908) (xy 122.293086 -227.152436) (xy 122.246928 -227.125787) (xy 122.205257 -227.092556)
			(xy 122.169005 -227.053485) (xy 122.138981 -227.009448) (xy 122.115855 -226.961427) (xy 122.100145 -226.910497)
			(xy 122.092202 -226.857793) (xy 121.863876 -226.857793) (xy 121.855933 -226.910497) (xy 121.840223 -226.961427)
			(xy 121.817097 -227.009448) (xy 121.787073 -227.053485) (xy 121.750821 -227.092556) (xy 121.70915 -227.125787)
			(xy 121.662992 -227.152436) (xy 121.613378 -227.171908) (xy 121.561416 -227.183768) (xy 121.508266 -227.187752)
			(xy 121.455116 -227.183768) (xy 121.403154 -227.171908) (xy 121.35354 -227.152436) (xy 121.307382 -227.125787)
			(xy 121.265711 -227.092556) (xy 121.229459 -227.053485) (xy 121.199435 -227.009448) (xy 121.176309 -226.961427)
			(xy 121.160599 -226.910497) (xy 121.152656 -226.857793) (xy 120.923822 -226.857793) (xy 120.915879 -226.910497)
			(xy 120.900169 -226.961427) (xy 120.877043 -227.009448) (xy 120.847019 -227.053485) (xy 120.810767 -227.092556)
			(xy 120.769096 -227.125787) (xy 120.722938 -227.152436) (xy 120.673324 -227.171908) (xy 120.621362 -227.183768)
			(xy 120.568212 -227.187752) (xy 120.515062 -227.183768) (xy 120.4631 -227.171908) (xy 120.413486 -227.152436)
			(xy 120.367328 -227.125787) (xy 120.325657 -227.092556) (xy 120.289405 -227.053485) (xy 120.259381 -227.009448)
			(xy 120.236255 -226.961427) (xy 120.220545 -226.910497) (xy 120.212602 -226.857793) (xy 119.984276 -226.857793)
			(xy 119.976333 -226.910497) (xy 119.960623 -226.961427) (xy 119.937497 -227.009448) (xy 119.907473 -227.053485)
			(xy 119.871221 -227.092556) (xy 119.82955 -227.125787) (xy 119.783392 -227.152436) (xy 119.733778 -227.171908)
			(xy 119.681816 -227.183768) (xy 119.628666 -227.187752) (xy 119.575516 -227.183768) (xy 119.523554 -227.171908)
			(xy 119.47394 -227.152436) (xy 119.427782 -227.125787) (xy 119.386111 -227.092556) (xy 119.349859 -227.053485)
			(xy 119.319835 -227.009448) (xy 119.296709 -226.961427) (xy 119.280999 -226.910497) (xy 119.273056 -226.857793)
			(xy 119.044222 -226.857793) (xy 119.036279 -226.910497) (xy 119.020569 -226.961427) (xy 118.997443 -227.009448)
			(xy 118.967419 -227.053485) (xy 118.931167 -227.092556) (xy 118.889496 -227.125787) (xy 118.843338 -227.152436)
			(xy 118.793724 -227.171908) (xy 118.741762 -227.183768) (xy 118.688612 -227.187752) (xy 118.635462 -227.183768)
			(xy 118.5835 -227.171908) (xy 118.533886 -227.152436) (xy 118.487728 -227.125787) (xy 118.446057 -227.092556)
			(xy 118.409805 -227.053485) (xy 118.379781 -227.009448) (xy 118.356655 -226.961427) (xy 118.340945 -226.910497)
			(xy 118.333002 -226.857793) (xy 118.104676 -226.857793) (xy 118.096733 -226.910497) (xy 118.081023 -226.961427)
			(xy 118.057897 -227.009448) (xy 118.027873 -227.053485) (xy 117.991621 -227.092556) (xy 117.94995 -227.125787)
			(xy 117.903792 -227.152436) (xy 117.854178 -227.171908) (xy 117.802216 -227.183768) (xy 117.749066 -227.187752)
			(xy 117.695916 -227.183768) (xy 117.643954 -227.171908) (xy 117.59434 -227.152436) (xy 117.548182 -227.125787)
			(xy 117.506511 -227.092556) (xy 117.470259 -227.053485) (xy 117.440235 -227.009448) (xy 117.417109 -226.961427)
			(xy 117.401399 -226.910497) (xy 117.393456 -226.857793) (xy 117.164622 -226.857793) (xy 117.156679 -226.910497)
			(xy 117.140969 -226.961427) (xy 117.117843 -227.009448) (xy 117.087819 -227.053485) (xy 117.051567 -227.092556)
			(xy 117.009896 -227.125787) (xy 116.963738 -227.152436) (xy 116.914124 -227.171908) (xy 116.862162 -227.183768)
			(xy 116.809012 -227.187752) (xy 116.755862 -227.183768) (xy 116.7039 -227.171908) (xy 116.654286 -227.152436)
			(xy 116.608128 -227.125787) (xy 116.566457 -227.092556) (xy 116.530205 -227.053485) (xy 116.500181 -227.009448)
			(xy 116.477055 -226.961427) (xy 116.461345 -226.910497) (xy 116.453402 -226.857793) (xy 116.225076 -226.857793)
			(xy 116.217133 -226.910497) (xy 116.201423 -226.961427) (xy 116.178297 -227.009448) (xy 116.148273 -227.053485)
			(xy 116.112021 -227.092556) (xy 116.07035 -227.125787) (xy 116.024192 -227.152436) (xy 115.974578 -227.171908)
			(xy 115.922616 -227.183768) (xy 115.869466 -227.187752) (xy 115.816316 -227.183768) (xy 115.764354 -227.171908)
			(xy 115.71474 -227.152436) (xy 115.668582 -227.125787) (xy 115.626911 -227.092556) (xy 115.590659 -227.053485)
			(xy 115.560635 -227.009448) (xy 115.537509 -226.961427) (xy 115.521799 -226.910497) (xy 115.513856 -226.857793)
			(xy 115.285276 -226.857793) (xy 115.277333 -226.910497) (xy 115.261623 -226.961427) (xy 115.238497 -227.009448)
			(xy 115.208473 -227.053485) (xy 115.172221 -227.092556) (xy 115.13055 -227.125787) (xy 115.084392 -227.152436)
			(xy 115.034778 -227.171908) (xy 114.982816 -227.183768) (xy 114.929666 -227.187752) (xy 114.876516 -227.183768)
			(xy 114.824554 -227.171908) (xy 114.77494 -227.152436) (xy 114.728782 -227.125787) (xy 114.687111 -227.092556)
			(xy 114.650859 -227.053485) (xy 114.620835 -227.009448) (xy 114.597709 -226.961427) (xy 114.581999 -226.910497)
			(xy 114.574056 -226.857793) (xy 114.345476 -226.857793) (xy 114.337533 -226.910497) (xy 114.321823 -226.961427)
			(xy 114.298697 -227.009448) (xy 114.268673 -227.053485) (xy 114.232421 -227.092556) (xy 114.19075 -227.125787)
			(xy 114.144592 -227.152436) (xy 114.094978 -227.171908) (xy 114.043016 -227.183768) (xy 113.989866 -227.187752)
			(xy 113.936716 -227.183768) (xy 113.884754 -227.171908) (xy 113.83514 -227.152436) (xy 113.788982 -227.125787)
			(xy 113.747311 -227.092556) (xy 113.711059 -227.053485) (xy 113.681035 -227.009448) (xy 113.657909 -226.961427)
			(xy 113.642199 -226.910497) (xy 113.634256 -226.857793) (xy 113.405422 -226.857793) (xy 113.397479 -226.910497)
			(xy 113.381769 -226.961427) (xy 113.358643 -227.009448) (xy 113.328619 -227.053485) (xy 113.292367 -227.092556)
			(xy 113.250696 -227.125787) (xy 113.204538 -227.152436) (xy 113.154924 -227.171908) (xy 113.102962 -227.183768)
			(xy 113.049812 -227.187752) (xy 112.996662 -227.183768) (xy 112.9447 -227.171908) (xy 112.895086 -227.152436)
			(xy 112.848928 -227.125787) (xy 112.807257 -227.092556) (xy 112.771005 -227.053485) (xy 112.740981 -227.009448)
			(xy 112.717855 -226.961427) (xy 112.702145 -226.910497) (xy 112.694202 -226.857793) (xy 112.465876 -226.857793)
			(xy 112.457933 -226.910497) (xy 112.442223 -226.961427) (xy 112.419097 -227.009448) (xy 112.389073 -227.053485)
			(xy 112.352821 -227.092556) (xy 112.31115 -227.125787) (xy 112.264992 -227.152436) (xy 112.215378 -227.171908)
			(xy 112.163416 -227.183768) (xy 112.110266 -227.187752) (xy 112.057116 -227.183768) (xy 112.005154 -227.171908)
			(xy 111.95554 -227.152436) (xy 111.909382 -227.125787) (xy 111.867711 -227.092556) (xy 111.831459 -227.053485)
			(xy 111.801435 -227.009448) (xy 111.778309 -226.961427) (xy 111.762599 -226.910497) (xy 111.754656 -226.857793)
			(xy 111.525822 -226.857793) (xy 111.517879 -226.910497) (xy 111.502169 -226.961427) (xy 111.479043 -227.009448)
			(xy 111.449019 -227.053485) (xy 111.412767 -227.092556) (xy 111.371096 -227.125787) (xy 111.324938 -227.152436)
			(xy 111.275324 -227.171908) (xy 111.223362 -227.183768) (xy 111.170212 -227.187752) (xy 111.117062 -227.183768)
			(xy 111.0651 -227.171908) (xy 111.015486 -227.152436) (xy 110.969328 -227.125787) (xy 110.927657 -227.092556)
			(xy 110.891405 -227.053485) (xy 110.861381 -227.009448) (xy 110.838255 -226.961427) (xy 110.822545 -226.910497)
			(xy 110.814602 -226.857793) (xy 110.586276 -226.857793) (xy 110.578333 -226.910497) (xy 110.562623 -226.961427)
			(xy 110.539497 -227.009448) (xy 110.509473 -227.053485) (xy 110.473221 -227.092556) (xy 110.43155 -227.125787)
			(xy 110.385392 -227.152436) (xy 110.335778 -227.171908) (xy 110.283816 -227.183768) (xy 110.230666 -227.187752)
			(xy 110.177516 -227.183768) (xy 110.125554 -227.171908) (xy 110.07594 -227.152436) (xy 110.029782 -227.125787)
			(xy 109.988111 -227.092556) (xy 109.951859 -227.053485) (xy 109.921835 -227.009448) (xy 109.898709 -226.961427)
			(xy 109.882999 -226.910497) (xy 109.875056 -226.857793) (xy 109.646222 -226.857793) (xy 109.638279 -226.910497)
			(xy 109.622569 -226.961427) (xy 109.599443 -227.009448) (xy 109.569419 -227.053485) (xy 109.533167 -227.092556)
			(xy 109.491496 -227.125787) (xy 109.445338 -227.152436) (xy 109.395724 -227.171908) (xy 109.343762 -227.183768)
			(xy 109.290612 -227.187752) (xy 109.237462 -227.183768) (xy 109.1855 -227.171908) (xy 109.135886 -227.152436)
			(xy 109.089728 -227.125787) (xy 109.048057 -227.092556) (xy 109.011805 -227.053485) (xy 108.981781 -227.009448)
			(xy 108.958655 -226.961427) (xy 108.942945 -226.910497) (xy 108.935002 -226.857793) (xy 108.706676 -226.857793)
			(xy 108.698733 -226.910497) (xy 108.683023 -226.961427) (xy 108.659897 -227.009448) (xy 108.629873 -227.053485)
			(xy 108.593621 -227.092556) (xy 108.55195 -227.125787) (xy 108.505792 -227.152436) (xy 108.456178 -227.171908)
			(xy 108.404216 -227.183768) (xy 108.351066 -227.187752) (xy 108.297916 -227.183768) (xy 108.245954 -227.171908)
			(xy 108.19634 -227.152436) (xy 108.150182 -227.125787) (xy 108.108511 -227.092556) (xy 108.072259 -227.053485)
			(xy 108.042235 -227.009448) (xy 108.019109 -226.961427) (xy 108.003399 -226.910497) (xy 107.995456 -226.857793)
			(xy 107.766622 -226.857793) (xy 107.758679 -226.910497) (xy 107.742969 -226.961427) (xy 107.719843 -227.009448)
			(xy 107.689819 -227.053485) (xy 107.653567 -227.092556) (xy 107.611896 -227.125787) (xy 107.565738 -227.152436)
			(xy 107.516124 -227.171908) (xy 107.464162 -227.183768) (xy 107.411012 -227.187752) (xy 107.357862 -227.183768)
			(xy 107.3059 -227.171908) (xy 107.256286 -227.152436) (xy 107.210128 -227.125787) (xy 107.168457 -227.092556)
			(xy 107.132205 -227.053485) (xy 107.102181 -227.009448) (xy 107.079055 -226.961427) (xy 107.063345 -226.910497)
			(xy 107.055402 -226.857793) (xy 106.827076 -226.857793) (xy 106.819133 -226.910497) (xy 106.803423 -226.961427)
			(xy 106.780297 -227.009448) (xy 106.750273 -227.053485) (xy 106.714021 -227.092556) (xy 106.67235 -227.125787)
			(xy 106.626192 -227.152436) (xy 106.576578 -227.171908) (xy 106.524616 -227.183768) (xy 106.471466 -227.187752)
			(xy 106.418316 -227.183768) (xy 106.366354 -227.171908) (xy 106.31674 -227.152436) (xy 106.270582 -227.125787)
			(xy 106.228911 -227.092556) (xy 106.192659 -227.053485) (xy 106.162635 -227.009448) (xy 106.139509 -226.961427)
			(xy 106.123799 -226.910497) (xy 106.115856 -226.857793) (xy 105.887022 -226.857793) (xy 105.879079 -226.910497)
			(xy 105.863369 -226.961427) (xy 105.840243 -227.009448) (xy 105.810219 -227.053485) (xy 105.773967 -227.092556)
			(xy 105.732296 -227.125787) (xy 105.686138 -227.152436) (xy 105.636524 -227.171908) (xy 105.584562 -227.183768)
			(xy 105.531412 -227.187752) (xy 105.478262 -227.183768) (xy 105.4263 -227.171908) (xy 105.376686 -227.152436)
			(xy 105.330528 -227.125787) (xy 105.288857 -227.092556) (xy 105.252605 -227.053485) (xy 105.222581 -227.009448)
			(xy 105.199455 -226.961427) (xy 105.183745 -226.910497) (xy 105.175802 -226.857793) (xy 104.947476 -226.857793)
			(xy 104.939533 -226.910497) (xy 104.923823 -226.961427) (xy 104.900697 -227.009448) (xy 104.870673 -227.053485)
			(xy 104.834421 -227.092556) (xy 104.79275 -227.125787) (xy 104.746592 -227.152436) (xy 104.696978 -227.171908)
			(xy 104.645016 -227.183768) (xy 104.591866 -227.187752) (xy 104.538716 -227.183768) (xy 104.486754 -227.171908)
			(xy 104.43714 -227.152436) (xy 104.390982 -227.125787) (xy 104.349311 -227.092556) (xy 104.313059 -227.053485)
			(xy 104.283035 -227.009448) (xy 104.259909 -226.961427) (xy 104.244199 -226.910497) (xy 104.236256 -226.857793)
			(xy 104.007676 -226.857793) (xy 103.999733 -226.910497) (xy 103.984023 -226.961427) (xy 103.960897 -227.009448)
			(xy 103.930873 -227.053485) (xy 103.894621 -227.092556) (xy 103.85295 -227.125787) (xy 103.806792 -227.152436)
			(xy 103.757178 -227.171908) (xy 103.705216 -227.183768) (xy 103.652066 -227.187752) (xy 103.598916 -227.183768)
			(xy 103.546954 -227.171908) (xy 103.49734 -227.152436) (xy 103.451182 -227.125787) (xy 103.409511 -227.092556)
			(xy 103.373259 -227.053485) (xy 103.343235 -227.009448) (xy 103.320109 -226.961427) (xy 103.304399 -226.910497)
			(xy 103.296456 -226.857793) (xy 103.067622 -226.857793) (xy 103.059679 -226.910497) (xy 103.043969 -226.961427)
			(xy 103.020843 -227.009448) (xy 102.990819 -227.053485) (xy 102.954567 -227.092556) (xy 102.912896 -227.125787)
			(xy 102.866738 -227.152436) (xy 102.817124 -227.171908) (xy 102.765162 -227.183768) (xy 102.712012 -227.187752)
			(xy 102.658862 -227.183768) (xy 102.6069 -227.171908) (xy 102.557286 -227.152436) (xy 102.511128 -227.125787)
			(xy 102.469457 -227.092556) (xy 102.433205 -227.053485) (xy 102.403181 -227.009448) (xy 102.380055 -226.961427)
			(xy 102.364345 -226.910497) (xy 102.356402 -226.857793) (xy 102.127822 -226.857793) (xy 102.119879 -226.910497)
			(xy 102.104169 -226.961427) (xy 102.081043 -227.009448) (xy 102.051019 -227.053485) (xy 102.014767 -227.092556)
			(xy 101.973096 -227.125787) (xy 101.926938 -227.152436) (xy 101.877324 -227.171908) (xy 101.825362 -227.183768)
			(xy 101.772212 -227.187752) (xy 101.719062 -227.183768) (xy 101.6671 -227.171908) (xy 101.617486 -227.152436)
			(xy 101.571328 -227.125787) (xy 101.529657 -227.092556) (xy 101.493405 -227.053485) (xy 101.463381 -227.009448)
			(xy 101.440255 -226.961427) (xy 101.424545 -226.910497) (xy 101.416602 -226.857793) (xy 101.188276 -226.857793)
			(xy 101.180333 -226.910497) (xy 101.164623 -226.961427) (xy 101.141497 -227.009448) (xy 101.111473 -227.053485)
			(xy 101.075221 -227.092556) (xy 101.03355 -227.125787) (xy 100.987392 -227.152436) (xy 100.937778 -227.171908)
			(xy 100.885816 -227.183768) (xy 100.832666 -227.187752) (xy 100.779516 -227.183768) (xy 100.727554 -227.171908)
			(xy 100.67794 -227.152436) (xy 100.631782 -227.125787) (xy 100.590111 -227.092556) (xy 100.553859 -227.053485)
			(xy 100.523835 -227.009448) (xy 100.500709 -226.961427) (xy 100.484999 -226.910497) (xy 100.477056 -226.857793)
			(xy 100.248476 -226.857793) (xy 100.240533 -226.910497) (xy 100.224823 -226.961427) (xy 100.201697 -227.009448)
			(xy 100.171673 -227.053485) (xy 100.135421 -227.092556) (xy 100.09375 -227.125787) (xy 100.047592 -227.152436)
			(xy 99.997978 -227.171908) (xy 99.946016 -227.183768) (xy 99.892866 -227.187752) (xy 99.839716 -227.183768)
			(xy 99.787754 -227.171908) (xy 99.73814 -227.152436) (xy 99.691982 -227.125787) (xy 99.650311 -227.092556)
			(xy 99.614059 -227.053485) (xy 99.584035 -227.009448) (xy 99.560909 -226.961427) (xy 99.545199 -226.910497)
			(xy 99.537256 -226.857793) (xy 99.308676 -226.857793) (xy 99.300733 -226.910497) (xy 99.285023 -226.961427)
			(xy 99.261897 -227.009448) (xy 99.231873 -227.053485) (xy 99.195621 -227.092556) (xy 99.15395 -227.125787)
			(xy 99.107792 -227.152436) (xy 99.058178 -227.171908) (xy 99.006216 -227.183768) (xy 98.953066 -227.187752)
			(xy 98.899916 -227.183768) (xy 98.847954 -227.171908) (xy 98.79834 -227.152436) (xy 98.752182 -227.125787)
			(xy 98.710511 -227.092556) (xy 98.674259 -227.053485) (xy 98.644235 -227.009448) (xy 98.621109 -226.961427)
			(xy 98.605399 -226.910497) (xy 98.597456 -226.857793) (xy 98.368622 -226.857793) (xy 98.360679 -226.910497)
			(xy 98.344969 -226.961427) (xy 98.321843 -227.009448) (xy 98.291819 -227.053485) (xy 98.255567 -227.092556)
			(xy 98.213896 -227.125787) (xy 98.167738 -227.152436) (xy 98.118124 -227.171908) (xy 98.066162 -227.183768)
			(xy 98.013012 -227.187752) (xy 97.959862 -227.183768) (xy 97.9079 -227.171908) (xy 97.858286 -227.152436)
			(xy 97.812128 -227.125787) (xy 97.770457 -227.092556) (xy 97.734205 -227.053485) (xy 97.704181 -227.009448)
			(xy 97.681055 -226.961427) (xy 97.665345 -226.910497) (xy 97.657402 -226.857793) (xy 97.428822 -226.857793)
			(xy 97.420879 -226.910497) (xy 97.405169 -226.961427) (xy 97.382043 -227.009448) (xy 97.352019 -227.053485)
			(xy 97.315767 -227.092556) (xy 97.274096 -227.125787) (xy 97.227938 -227.152436) (xy 97.178324 -227.171908)
			(xy 97.126362 -227.183768) (xy 97.073212 -227.187752) (xy 97.020062 -227.183768) (xy 96.9681 -227.171908)
			(xy 96.918486 -227.152436) (xy 96.872328 -227.125787) (xy 96.830657 -227.092556) (xy 96.794405 -227.053485)
			(xy 96.764381 -227.009448) (xy 96.741255 -226.961427) (xy 96.725545 -226.910497) (xy 96.717602 -226.857793)
			(xy 96.489276 -226.857793) (xy 96.481333 -226.910497) (xy 96.465623 -226.961427) (xy 96.442497 -227.009448)
			(xy 96.412473 -227.053485) (xy 96.376221 -227.092556) (xy 96.33455 -227.125787) (xy 96.288392 -227.152436)
			(xy 96.238778 -227.171908) (xy 96.186816 -227.183768) (xy 96.133666 -227.187752) (xy 96.080516 -227.183768)
			(xy 96.028554 -227.171908) (xy 95.97894 -227.152436) (xy 95.932782 -227.125787) (xy 95.891111 -227.092556)
			(xy 95.854859 -227.053485) (xy 95.824835 -227.009448) (xy 95.801709 -226.961427) (xy 95.785999 -226.910497)
			(xy 95.778056 -226.857793) (xy 95.549222 -226.857793) (xy 95.541279 -226.910497) (xy 95.525569 -226.961427)
			(xy 95.502443 -227.009448) (xy 95.472419 -227.053485) (xy 95.436167 -227.092556) (xy 95.394496 -227.125787)
			(xy 95.348338 -227.152436) (xy 95.298724 -227.171908) (xy 95.246762 -227.183768) (xy 95.193612 -227.187752)
			(xy 95.140462 -227.183768) (xy 95.0885 -227.171908) (xy 95.038886 -227.152436) (xy 94.992728 -227.125787)
			(xy 94.951057 -227.092556) (xy 94.914805 -227.053485) (xy 94.884781 -227.009448) (xy 94.861655 -226.961427)
			(xy 94.845945 -226.910497) (xy 94.838002 -226.857793) (xy 94.609422 -226.857793) (xy 94.601479 -226.910497)
			(xy 94.585769 -226.961427) (xy 94.562643 -227.009448) (xy 94.532619 -227.053485) (xy 94.496367 -227.092556)
			(xy 94.454696 -227.125787) (xy 94.408538 -227.152436) (xy 94.358924 -227.171908) (xy 94.306962 -227.183768)
			(xy 94.253812 -227.187752) (xy 94.200662 -227.183768) (xy 94.1487 -227.171908) (xy 94.099086 -227.152436)
			(xy 94.052928 -227.125787) (xy 94.011257 -227.092556) (xy 93.975005 -227.053485) (xy 93.944981 -227.009448)
			(xy 93.921855 -226.961427) (xy 93.906145 -226.910497) (xy 93.898202 -226.857793) (xy 93.669876 -226.857793)
			(xy 93.661933 -226.910497) (xy 93.646223 -226.961427) (xy 93.623097 -227.009448) (xy 93.593073 -227.053485)
			(xy 93.556821 -227.092556) (xy 93.51515 -227.125787) (xy 93.468992 -227.152436) (xy 93.419378 -227.171908)
			(xy 93.367416 -227.183768) (xy 93.314266 -227.187752) (xy 93.261116 -227.183768) (xy 93.209154 -227.171908)
			(xy 93.15954 -227.152436) (xy 93.113382 -227.125787) (xy 93.071711 -227.092556) (xy 93.035459 -227.053485)
			(xy 93.005435 -227.009448) (xy 92.982309 -226.961427) (xy 92.966599 -226.910497) (xy 92.958656 -226.857793)
			(xy 92.730076 -226.857793) (xy 92.722133 -226.910497) (xy 92.706423 -226.961427) (xy 92.683297 -227.009448)
			(xy 92.653273 -227.053485) (xy 92.617021 -227.092556) (xy 92.57535 -227.125787) (xy 92.529192 -227.152436)
			(xy 92.479578 -227.171908) (xy 92.427616 -227.183768) (xy 92.374466 -227.187752) (xy 92.321316 -227.183768)
			(xy 92.269354 -227.171908) (xy 92.21974 -227.152436) (xy 92.173582 -227.125787) (xy 92.131911 -227.092556)
			(xy 92.095659 -227.053485) (xy 92.065635 -227.009448) (xy 92.042509 -226.961427) (xy 92.026799 -226.910497)
			(xy 92.018856 -226.857793) (xy 91.790276 -226.857793) (xy 91.782333 -226.910497) (xy 91.766623 -226.961427)
			(xy 91.743497 -227.009448) (xy 91.713473 -227.053485) (xy 91.677221 -227.092556) (xy 91.63555 -227.125787)
			(xy 91.589392 -227.152436) (xy 91.539778 -227.171908) (xy 91.487816 -227.183768) (xy 91.434666 -227.187752)
			(xy 91.381516 -227.183768) (xy 91.329554 -227.171908) (xy 91.27994 -227.152436) (xy 91.233782 -227.125787)
			(xy 91.192111 -227.092556) (xy 91.155859 -227.053485) (xy 91.125835 -227.009448) (xy 91.102709 -226.961427)
			(xy 91.086999 -226.910497) (xy 91.079056 -226.857793) (xy 90.850222 -226.857793) (xy 90.842279 -226.910497)
			(xy 90.826569 -226.961427) (xy 90.803443 -227.009448) (xy 90.773419 -227.053485) (xy 90.737167 -227.092556)
			(xy 90.695496 -227.125787) (xy 90.649338 -227.152436) (xy 90.599724 -227.171908) (xy 90.547762 -227.183768)
			(xy 90.494612 -227.187752) (xy 90.441462 -227.183768) (xy 90.3895 -227.171908) (xy 90.339886 -227.152436)
			(xy 90.293728 -227.125787) (xy 90.252057 -227.092556) (xy 90.215805 -227.053485) (xy 90.185781 -227.009448)
			(xy 90.162655 -226.961427) (xy 90.146945 -226.910497) (xy 90.139002 -226.857793) (xy 89.910394 -226.857793)
			(xy 89.910368 -226.859125) (xy 89.901607 -226.914398) (xy 89.884309 -226.96762) (xy 89.858899 -227.017481)
			(xy 89.826002 -227.062753) (xy 89.786429 -227.102323) (xy 89.741153 -227.135216) (xy 89.69129 -227.160621)
			(xy 89.638067 -227.177915) (xy 89.582793 -227.18667) (xy 89.554812 -227.187252) (xy 89.527096 -227.186726)
			(xy 89.472334 -227.178142) (xy 89.419561 -227.16118) (xy 89.370053 -227.136249) (xy 89.325004 -227.103951)
			(xy 89.304876 -227.08489) (xy 89.269062 -227.070158) (xy 89.232994 -227.085398) (xy 89.216782 -227.101775)
			(xy 89.183502 -227.133656) (xy 89.166446 -227.149152) (xy 89.161518 -227.171774) (xy 89.150467 -227.216739)
			(xy 89.144348 -227.239068) (xy 89.14257 -227.25253) (xy 89.179908 -227.301552) (xy 89.204617 -227.308863)
			(xy 89.251779 -227.329618) (xy 89.295462 -227.356946) (xy 89.334755 -227.390279) (xy 89.368839 -227.428923)
			(xy 89.397005 -227.472071) (xy 89.418664 -227.518824) (xy 89.433367 -227.568209) (xy 89.440806 -227.619197)
			(xy 89.441274 -227.64496) (xy 89.440781 -227.671609) (xy 89.669356 -227.671609) (xy 89.669356 -227.618311)
			(xy 89.677299 -227.565607) (xy 89.693009 -227.514677) (xy 89.716135 -227.466656) (xy 89.746159 -227.422619)
			(xy 89.782411 -227.383548) (xy 89.824082 -227.350317) (xy 89.87024 -227.323668) (xy 89.919854 -227.304196)
			(xy 89.971816 -227.292336) (xy 90.024966 -227.288353) (xy 90.078116 -227.292336) (xy 90.130078 -227.304196)
			(xy 90.179692 -227.323668) (xy 90.22585 -227.350317) (xy 90.267521 -227.383548) (xy 90.303773 -227.422619)
			(xy 90.333797 -227.466656) (xy 90.356923 -227.514677) (xy 90.372633 -227.565607) (xy 90.380576 -227.618311)
			(xy 90.381074 -227.64496) (xy 90.380576 -227.671609) (xy 90.609156 -227.671609) (xy 90.609156 -227.618311)
			(xy 90.617099 -227.565607) (xy 90.632809 -227.514677) (xy 90.655935 -227.466656) (xy 90.685959 -227.422619)
			(xy 90.722211 -227.383548) (xy 90.763882 -227.350317) (xy 90.81004 -227.323668) (xy 90.859654 -227.304196)
			(xy 90.911616 -227.292336) (xy 90.964766 -227.288353) (xy 91.017916 -227.292336) (xy 91.069878 -227.304196)
			(xy 91.119492 -227.323668) (xy 91.16565 -227.350317) (xy 91.207321 -227.383548) (xy 91.243573 -227.422619)
			(xy 91.273597 -227.466656) (xy 91.296723 -227.514677) (xy 91.312433 -227.565607) (xy 91.320376 -227.618311)
			(xy 91.320874 -227.64496) (xy 91.320376 -227.671609) (xy 91.548702 -227.671609) (xy 91.548702 -227.618311)
			(xy 91.556645 -227.565607) (xy 91.572355 -227.514677) (xy 91.595481 -227.466656) (xy 91.625505 -227.422619)
			(xy 91.661757 -227.383548) (xy 91.703428 -227.350317) (xy 91.749586 -227.323668) (xy 91.7992 -227.304196)
			(xy 91.851162 -227.292336) (xy 91.904312 -227.288353) (xy 91.957462 -227.292336) (xy 92.009424 -227.304196)
			(xy 92.059038 -227.323668) (xy 92.105196 -227.350317) (xy 92.146867 -227.383548) (xy 92.183119 -227.422619)
			(xy 92.213143 -227.466656) (xy 92.236269 -227.514677) (xy 92.251979 -227.565607) (xy 92.259922 -227.618311)
			(xy 92.26042 -227.64496) (xy 92.259922 -227.671609) (xy 92.488756 -227.671609) (xy 92.488756 -227.618311)
			(xy 92.496699 -227.565607) (xy 92.512409 -227.514677) (xy 92.535535 -227.466656) (xy 92.565559 -227.422619)
			(xy 92.601811 -227.383548) (xy 92.643482 -227.350317) (xy 92.68964 -227.323668) (xy 92.739254 -227.304196)
			(xy 92.791216 -227.292336) (xy 92.844366 -227.288353) (xy 92.897516 -227.292336) (xy 92.949478 -227.304196)
			(xy 92.999092 -227.323668) (xy 93.04525 -227.350317) (xy 93.086921 -227.383548) (xy 93.123173 -227.422619)
			(xy 93.153197 -227.466656) (xy 93.176323 -227.514677) (xy 93.192033 -227.565607) (xy 93.199976 -227.618311)
			(xy 93.200474 -227.64496) (xy 93.199976 -227.671609) (xy 93.428556 -227.671609) (xy 93.428556 -227.618311)
			(xy 93.436499 -227.565607) (xy 93.452209 -227.514677) (xy 93.475335 -227.466656) (xy 93.505359 -227.422619)
			(xy 93.541611 -227.383548) (xy 93.583282 -227.350317) (xy 93.62944 -227.323668) (xy 93.679054 -227.304196)
			(xy 93.731016 -227.292336) (xy 93.784166 -227.288353) (xy 93.837316 -227.292336) (xy 93.889278 -227.304196)
			(xy 93.938892 -227.323668) (xy 93.98505 -227.350317) (xy 94.026721 -227.383548) (xy 94.062973 -227.422619)
			(xy 94.092997 -227.466656) (xy 94.116123 -227.514677) (xy 94.131833 -227.565607) (xy 94.139776 -227.618311)
			(xy 94.140274 -227.64496) (xy 94.139776 -227.671609) (xy 94.368356 -227.671609) (xy 94.368356 -227.618311)
			(xy 94.376299 -227.565607) (xy 94.392009 -227.514677) (xy 94.415135 -227.466656) (xy 94.445159 -227.422619)
			(xy 94.481411 -227.383548) (xy 94.523082 -227.350317) (xy 94.56924 -227.323668) (xy 94.618854 -227.304196)
			(xy 94.670816 -227.292336) (xy 94.723966 -227.288353) (xy 94.777116 -227.292336) (xy 94.829078 -227.304196)
			(xy 94.878692 -227.323668) (xy 94.92485 -227.350317) (xy 94.966521 -227.383548) (xy 95.002773 -227.422619)
			(xy 95.032797 -227.466656) (xy 95.055923 -227.514677) (xy 95.071633 -227.565607) (xy 95.079576 -227.618311)
			(xy 95.080074 -227.64496) (xy 95.079576 -227.671609) (xy 95.308156 -227.671609) (xy 95.308156 -227.618311)
			(xy 95.316099 -227.565607) (xy 95.331809 -227.514677) (xy 95.354935 -227.466656) (xy 95.384959 -227.422619)
			(xy 95.421211 -227.383548) (xy 95.462882 -227.350317) (xy 95.50904 -227.323668) (xy 95.558654 -227.304196)
			(xy 95.610616 -227.292336) (xy 95.663766 -227.288353) (xy 95.716916 -227.292336) (xy 95.768878 -227.304196)
			(xy 95.818492 -227.323668) (xy 95.86465 -227.350317) (xy 95.906321 -227.383548) (xy 95.942573 -227.422619)
			(xy 95.972597 -227.466656) (xy 95.995723 -227.514677) (xy 96.011433 -227.565607) (xy 96.019376 -227.618311)
			(xy 96.019874 -227.64496) (xy 96.019376 -227.671609) (xy 96.247956 -227.671609) (xy 96.247956 -227.618311)
			(xy 96.255899 -227.565607) (xy 96.271609 -227.514677) (xy 96.294735 -227.466656) (xy 96.324759 -227.422619)
			(xy 96.361011 -227.383548) (xy 96.402682 -227.350317) (xy 96.44884 -227.323668) (xy 96.498454 -227.304196)
			(xy 96.550416 -227.292336) (xy 96.603566 -227.288353) (xy 96.656716 -227.292336) (xy 96.708678 -227.304196)
			(xy 96.758292 -227.323668) (xy 96.80445 -227.350317) (xy 96.846121 -227.383548) (xy 96.882373 -227.422619)
			(xy 96.912397 -227.466656) (xy 96.935523 -227.514677) (xy 96.951233 -227.565607) (xy 96.959176 -227.618311)
			(xy 96.959674 -227.64496) (xy 96.959176 -227.671609) (xy 97.187756 -227.671609) (xy 97.187756 -227.618311)
			(xy 97.195699 -227.565607) (xy 97.211409 -227.514677) (xy 97.234535 -227.466656) (xy 97.264559 -227.422619)
			(xy 97.300811 -227.383548) (xy 97.342482 -227.350317) (xy 97.38864 -227.323668) (xy 97.438254 -227.304196)
			(xy 97.490216 -227.292336) (xy 97.543366 -227.288353) (xy 97.596516 -227.292336) (xy 97.648478 -227.304196)
			(xy 97.698092 -227.323668) (xy 97.74425 -227.350317) (xy 97.785921 -227.383548) (xy 97.822173 -227.422619)
			(xy 97.852197 -227.466656) (xy 97.875323 -227.514677) (xy 97.891033 -227.565607) (xy 97.898976 -227.618311)
			(xy 97.899474 -227.64496) (xy 97.898976 -227.671609) (xy 98.127556 -227.671609) (xy 98.127556 -227.618311)
			(xy 98.135499 -227.565607) (xy 98.151209 -227.514677) (xy 98.174335 -227.466656) (xy 98.204359 -227.422619)
			(xy 98.240611 -227.383548) (xy 98.282282 -227.350317) (xy 98.32844 -227.323668) (xy 98.378054 -227.304196)
			(xy 98.430016 -227.292336) (xy 98.483166 -227.288353) (xy 98.536316 -227.292336) (xy 98.588278 -227.304196)
			(xy 98.637892 -227.323668) (xy 98.68405 -227.350317) (xy 98.725721 -227.383548) (xy 98.761973 -227.422619)
			(xy 98.791997 -227.466656) (xy 98.815123 -227.514677) (xy 98.830833 -227.565607) (xy 98.838776 -227.618311)
			(xy 98.839274 -227.64496) (xy 98.838776 -227.671609) (xy 99.067102 -227.671609) (xy 99.067102 -227.618311)
			(xy 99.075045 -227.565607) (xy 99.090755 -227.514677) (xy 99.113881 -227.466656) (xy 99.143905 -227.422619)
			(xy 99.180157 -227.383548) (xy 99.221828 -227.350317) (xy 99.267986 -227.323668) (xy 99.3176 -227.304196)
			(xy 99.369562 -227.292336) (xy 99.422712 -227.288353) (xy 99.475862 -227.292336) (xy 99.527824 -227.304196)
			(xy 99.577438 -227.323668) (xy 99.623596 -227.350317) (xy 99.665267 -227.383548) (xy 99.701519 -227.422619)
			(xy 99.731543 -227.466656) (xy 99.754669 -227.514677) (xy 99.770379 -227.565607) (xy 99.778322 -227.618311)
			(xy 99.77882 -227.64496) (xy 99.778322 -227.671609) (xy 100.007156 -227.671609) (xy 100.007156 -227.618311)
			(xy 100.015099 -227.565607) (xy 100.030809 -227.514677) (xy 100.053935 -227.466656) (xy 100.083959 -227.422619)
			(xy 100.120211 -227.383548) (xy 100.161882 -227.350317) (xy 100.20804 -227.323668) (xy 100.257654 -227.304196)
			(xy 100.309616 -227.292336) (xy 100.362766 -227.288353) (xy 100.415916 -227.292336) (xy 100.467878 -227.304196)
			(xy 100.517492 -227.323668) (xy 100.56365 -227.350317) (xy 100.605321 -227.383548) (xy 100.641573 -227.422619)
			(xy 100.671597 -227.466656) (xy 100.694723 -227.514677) (xy 100.710433 -227.565607) (xy 100.718376 -227.618311)
			(xy 100.718874 -227.64496) (xy 100.718376 -227.671609) (xy 100.946956 -227.671609) (xy 100.946956 -227.618311)
			(xy 100.954899 -227.565607) (xy 100.970609 -227.514677) (xy 100.993735 -227.466656) (xy 101.023759 -227.422619)
			(xy 101.060011 -227.383548) (xy 101.101682 -227.350317) (xy 101.14784 -227.323668) (xy 101.197454 -227.304196)
			(xy 101.249416 -227.292336) (xy 101.302566 -227.288353) (xy 101.355716 -227.292336) (xy 101.407678 -227.304196)
			(xy 101.457292 -227.323668) (xy 101.50345 -227.350317) (xy 101.545121 -227.383548) (xy 101.581373 -227.422619)
			(xy 101.611397 -227.466656) (xy 101.634523 -227.514677) (xy 101.650233 -227.565607) (xy 101.658176 -227.618311)
			(xy 101.658674 -227.64496) (xy 101.658176 -227.671609) (xy 101.886756 -227.671609) (xy 101.886756 -227.618311)
			(xy 101.894699 -227.565607) (xy 101.910409 -227.514677) (xy 101.933535 -227.466656) (xy 101.963559 -227.422619)
			(xy 101.999811 -227.383548) (xy 102.041482 -227.350317) (xy 102.08764 -227.323668) (xy 102.137254 -227.304196)
			(xy 102.189216 -227.292336) (xy 102.242366 -227.288353) (xy 102.295516 -227.292336) (xy 102.347478 -227.304196)
			(xy 102.397092 -227.323668) (xy 102.44325 -227.350317) (xy 102.484921 -227.383548) (xy 102.521173 -227.422619)
			(xy 102.551197 -227.466656) (xy 102.574323 -227.514677) (xy 102.590033 -227.565607) (xy 102.597976 -227.618311)
			(xy 102.598474 -227.64496) (xy 102.597976 -227.671609) (xy 103.766356 -227.671609) (xy 103.766356 -227.618311)
			(xy 103.774299 -227.565607) (xy 103.790009 -227.514677) (xy 103.813135 -227.466656) (xy 103.843159 -227.422619)
			(xy 103.879411 -227.383548) (xy 103.921082 -227.350317) (xy 103.96724 -227.323668) (xy 104.016854 -227.304196)
			(xy 104.068816 -227.292336) (xy 104.121966 -227.288353) (xy 104.175116 -227.292336) (xy 104.227078 -227.304196)
			(xy 104.276692 -227.323668) (xy 104.32285 -227.350317) (xy 104.364521 -227.383548) (xy 104.400773 -227.422619)
			(xy 104.430797 -227.466656) (xy 104.453923 -227.514677) (xy 104.469633 -227.565607) (xy 104.477576 -227.618311)
			(xy 104.478074 -227.64496) (xy 104.477576 -227.671609) (xy 104.706156 -227.671609) (xy 104.706156 -227.618311)
			(xy 104.714099 -227.565607) (xy 104.729809 -227.514677) (xy 104.752935 -227.466656) (xy 104.782959 -227.422619)
			(xy 104.819211 -227.383548) (xy 104.860882 -227.350317) (xy 104.90704 -227.323668) (xy 104.956654 -227.304196)
			(xy 105.008616 -227.292336) (xy 105.061766 -227.288353) (xy 105.114916 -227.292336) (xy 105.166878 -227.304196)
			(xy 105.216492 -227.323668) (xy 105.26265 -227.350317) (xy 105.304321 -227.383548) (xy 105.340573 -227.422619)
			(xy 105.370597 -227.466656) (xy 105.393723 -227.514677) (xy 105.409433 -227.565607) (xy 105.417376 -227.618311)
			(xy 105.417874 -227.64496) (xy 105.417376 -227.671609) (xy 105.645956 -227.671609) (xy 105.645956 -227.618311)
			(xy 105.653899 -227.565607) (xy 105.669609 -227.514677) (xy 105.692735 -227.466656) (xy 105.722759 -227.422619)
			(xy 105.759011 -227.383548) (xy 105.800682 -227.350317) (xy 105.84684 -227.323668) (xy 105.896454 -227.304196)
			(xy 105.948416 -227.292336) (xy 106.001566 -227.288353) (xy 106.054716 -227.292336) (xy 106.106678 -227.304196)
			(xy 106.156292 -227.323668) (xy 106.20245 -227.350317) (xy 106.244121 -227.383548) (xy 106.280373 -227.422619)
			(xy 106.310397 -227.466656) (xy 106.333523 -227.514677) (xy 106.349233 -227.565607) (xy 106.357176 -227.618311)
			(xy 106.357674 -227.64496) (xy 106.357176 -227.671609) (xy 106.585756 -227.671609) (xy 106.585756 -227.618311)
			(xy 106.593699 -227.565607) (xy 106.609409 -227.514677) (xy 106.632535 -227.466656) (xy 106.662559 -227.422619)
			(xy 106.698811 -227.383548) (xy 106.740482 -227.350317) (xy 106.78664 -227.323668) (xy 106.836254 -227.304196)
			(xy 106.888216 -227.292336) (xy 106.941366 -227.288353) (xy 106.994516 -227.292336) (xy 107.046478 -227.304196)
			(xy 107.096092 -227.323668) (xy 107.14225 -227.350317) (xy 107.183921 -227.383548) (xy 107.220173 -227.422619)
			(xy 107.250197 -227.466656) (xy 107.273323 -227.514677) (xy 107.289033 -227.565607) (xy 107.296976 -227.618311)
			(xy 107.297474 -227.64496) (xy 107.296976 -227.671609) (xy 107.525556 -227.671609) (xy 107.525556 -227.618311)
			(xy 107.533499 -227.565607) (xy 107.549209 -227.514677) (xy 107.572335 -227.466656) (xy 107.602359 -227.422619)
			(xy 107.638611 -227.383548) (xy 107.680282 -227.350317) (xy 107.72644 -227.323668) (xy 107.776054 -227.304196)
			(xy 107.828016 -227.292336) (xy 107.881166 -227.288353) (xy 107.934316 -227.292336) (xy 107.986278 -227.304196)
			(xy 108.035892 -227.323668) (xy 108.08205 -227.350317) (xy 108.123721 -227.383548) (xy 108.159973 -227.422619)
			(xy 108.189997 -227.466656) (xy 108.213123 -227.514677) (xy 108.228833 -227.565607) (xy 108.236776 -227.618311)
			(xy 108.237274 -227.64496) (xy 108.236776 -227.671609) (xy 108.465356 -227.671609) (xy 108.465356 -227.618311)
			(xy 108.473299 -227.565607) (xy 108.489009 -227.514677) (xy 108.512135 -227.466656) (xy 108.542159 -227.422619)
			(xy 108.578411 -227.383548) (xy 108.620082 -227.350317) (xy 108.66624 -227.323668) (xy 108.715854 -227.304196)
			(xy 108.767816 -227.292336) (xy 108.820966 -227.288353) (xy 108.874116 -227.292336) (xy 108.926078 -227.304196)
			(xy 108.975692 -227.323668) (xy 109.02185 -227.350317) (xy 109.063521 -227.383548) (xy 109.099773 -227.422619)
			(xy 109.129797 -227.466656) (xy 109.152923 -227.514677) (xy 109.168633 -227.565607) (xy 109.176576 -227.618311)
			(xy 109.177074 -227.64496) (xy 109.176576 -227.671609) (xy 109.405156 -227.671609) (xy 109.405156 -227.618311)
			(xy 109.413099 -227.565607) (xy 109.428809 -227.514677) (xy 109.451935 -227.466656) (xy 109.481959 -227.422619)
			(xy 109.518211 -227.383548) (xy 109.559882 -227.350317) (xy 109.60604 -227.323668) (xy 109.655654 -227.304196)
			(xy 109.707616 -227.292336) (xy 109.760766 -227.288353) (xy 109.813916 -227.292336) (xy 109.865878 -227.304196)
			(xy 109.915492 -227.323668) (xy 109.96165 -227.350317) (xy 110.003321 -227.383548) (xy 110.039573 -227.422619)
			(xy 110.069597 -227.466656) (xy 110.092723 -227.514677) (xy 110.108433 -227.565607) (xy 110.116376 -227.618311)
			(xy 110.116874 -227.64496) (xy 110.116376 -227.671609) (xy 110.344956 -227.671609) (xy 110.344956 -227.618311)
			(xy 110.352899 -227.565607) (xy 110.368609 -227.514677) (xy 110.391735 -227.466656) (xy 110.421759 -227.422619)
			(xy 110.458011 -227.383548) (xy 110.499682 -227.350317) (xy 110.54584 -227.323668) (xy 110.595454 -227.304196)
			(xy 110.647416 -227.292336) (xy 110.700566 -227.288353) (xy 110.753716 -227.292336) (xy 110.805678 -227.304196)
			(xy 110.855292 -227.323668) (xy 110.90145 -227.350317) (xy 110.943121 -227.383548) (xy 110.979373 -227.422619)
			(xy 111.009397 -227.466656) (xy 111.032523 -227.514677) (xy 111.048233 -227.565607) (xy 111.056176 -227.618311)
			(xy 111.056674 -227.64496) (xy 111.056176 -227.671609) (xy 111.284756 -227.671609) (xy 111.284756 -227.618311)
			(xy 111.292699 -227.565607) (xy 111.308409 -227.514677) (xy 111.331535 -227.466656) (xy 111.361559 -227.422619)
			(xy 111.397811 -227.383548) (xy 111.439482 -227.350317) (xy 111.48564 -227.323668) (xy 111.535254 -227.304196)
			(xy 111.587216 -227.292336) (xy 111.640366 -227.288353) (xy 111.693516 -227.292336) (xy 111.745478 -227.304196)
			(xy 111.795092 -227.323668) (xy 111.84125 -227.350317) (xy 111.882921 -227.383548) (xy 111.919173 -227.422619)
			(xy 111.949197 -227.466656) (xy 111.972323 -227.514677) (xy 111.988033 -227.565607) (xy 111.995976 -227.618311)
			(xy 111.996474 -227.64496) (xy 111.995976 -227.671609) (xy 112.224556 -227.671609) (xy 112.224556 -227.618311)
			(xy 112.232499 -227.565607) (xy 112.248209 -227.514677) (xy 112.271335 -227.466656) (xy 112.301359 -227.422619)
			(xy 112.337611 -227.383548) (xy 112.379282 -227.350317) (xy 112.42544 -227.323668) (xy 112.475054 -227.304196)
			(xy 112.527016 -227.292336) (xy 112.580166 -227.288353) (xy 112.633316 -227.292336) (xy 112.685278 -227.304196)
			(xy 112.734892 -227.323668) (xy 112.78105 -227.350317) (xy 112.822721 -227.383548) (xy 112.858973 -227.422619)
			(xy 112.888997 -227.466656) (xy 112.912123 -227.514677) (xy 112.927833 -227.565607) (xy 112.935776 -227.618311)
			(xy 112.936274 -227.64496) (xy 112.935776 -227.671609) (xy 113.164356 -227.671609) (xy 113.164356 -227.618311)
			(xy 113.172299 -227.565607) (xy 113.188009 -227.514677) (xy 113.211135 -227.466656) (xy 113.241159 -227.422619)
			(xy 113.277411 -227.383548) (xy 113.319082 -227.350317) (xy 113.36524 -227.323668) (xy 113.414854 -227.304196)
			(xy 113.466816 -227.292336) (xy 113.519966 -227.288353) (xy 113.573116 -227.292336) (xy 113.625078 -227.304196)
			(xy 113.674692 -227.323668) (xy 113.72085 -227.350317) (xy 113.762521 -227.383548) (xy 113.798773 -227.422619)
			(xy 113.828797 -227.466656) (xy 113.851923 -227.514677) (xy 113.867633 -227.565607) (xy 113.875576 -227.618311)
			(xy 113.876074 -227.64496) (xy 113.875576 -227.671609) (xy 114.10441 -227.671609) (xy 114.10441 -227.618311)
			(xy 114.112353 -227.565607) (xy 114.128063 -227.514677) (xy 114.151189 -227.466656) (xy 114.181213 -227.422619)
			(xy 114.217465 -227.383548) (xy 114.259136 -227.350317) (xy 114.305294 -227.323668) (xy 114.354908 -227.304196)
			(xy 114.40687 -227.292336) (xy 114.46002 -227.288353) (xy 114.51317 -227.292336) (xy 114.565132 -227.304196)
			(xy 114.614746 -227.323668) (xy 114.660904 -227.350317) (xy 114.702575 -227.383548) (xy 114.738827 -227.422619)
			(xy 114.768851 -227.466656) (xy 114.791977 -227.514677) (xy 114.807687 -227.565607) (xy 114.81563 -227.618311)
			(xy 114.816128 -227.64496) (xy 114.81563 -227.671609) (xy 115.043956 -227.671609) (xy 115.043956 -227.618311)
			(xy 115.051899 -227.565607) (xy 115.067609 -227.514677) (xy 115.090735 -227.466656) (xy 115.120759 -227.422619)
			(xy 115.157011 -227.383548) (xy 115.198682 -227.350317) (xy 115.24484 -227.323668) (xy 115.294454 -227.304196)
			(xy 115.346416 -227.292336) (xy 115.399566 -227.288353) (xy 115.452716 -227.292336) (xy 115.504678 -227.304196)
			(xy 115.554292 -227.323668) (xy 115.60045 -227.350317) (xy 115.642121 -227.383548) (xy 115.678373 -227.422619)
			(xy 115.708397 -227.466656) (xy 115.731523 -227.514677) (xy 115.747233 -227.565607) (xy 115.755176 -227.618311)
			(xy 115.755674 -227.64496) (xy 115.755176 -227.671609) (xy 115.983756 -227.671609) (xy 115.983756 -227.618311)
			(xy 115.991699 -227.565607) (xy 116.007409 -227.514677) (xy 116.030535 -227.466656) (xy 116.060559 -227.422619)
			(xy 116.096811 -227.383548) (xy 116.138482 -227.350317) (xy 116.18464 -227.323668) (xy 116.234254 -227.304196)
			(xy 116.286216 -227.292336) (xy 116.339366 -227.288353) (xy 116.392516 -227.292336) (xy 116.444478 -227.304196)
			(xy 116.494092 -227.323668) (xy 116.54025 -227.350317) (xy 116.581921 -227.383548) (xy 116.618173 -227.422619)
			(xy 116.648197 -227.466656) (xy 116.671323 -227.514677) (xy 116.687033 -227.565607) (xy 116.694976 -227.618311)
			(xy 116.695474 -227.64496) (xy 116.694976 -227.671609) (xy 116.923556 -227.671609) (xy 116.923556 -227.618311)
			(xy 116.931499 -227.565607) (xy 116.947209 -227.514677) (xy 116.970335 -227.466656) (xy 117.000359 -227.422619)
			(xy 117.036611 -227.383548) (xy 117.078282 -227.350317) (xy 117.12444 -227.323668) (xy 117.174054 -227.304196)
			(xy 117.226016 -227.292336) (xy 117.279166 -227.288353) (xy 117.332316 -227.292336) (xy 117.384278 -227.304196)
			(xy 117.433892 -227.323668) (xy 117.48005 -227.350317) (xy 117.521721 -227.383548) (xy 117.557973 -227.422619)
			(xy 117.587997 -227.466656) (xy 117.611123 -227.514677) (xy 117.626833 -227.565607) (xy 117.634776 -227.618311)
			(xy 117.635274 -227.64496) (xy 117.634776 -227.671609) (xy 117.863356 -227.671609) (xy 117.863356 -227.618311)
			(xy 117.871299 -227.565607) (xy 117.887009 -227.514677) (xy 117.910135 -227.466656) (xy 117.940159 -227.422619)
			(xy 117.976411 -227.383548) (xy 118.018082 -227.350317) (xy 118.06424 -227.323668) (xy 118.113854 -227.304196)
			(xy 118.165816 -227.292336) (xy 118.218966 -227.288353) (xy 118.272116 -227.292336) (xy 118.324078 -227.304196)
			(xy 118.373692 -227.323668) (xy 118.41985 -227.350317) (xy 118.461521 -227.383548) (xy 118.497773 -227.422619)
			(xy 118.527797 -227.466656) (xy 118.550923 -227.514677) (xy 118.566633 -227.565607) (xy 118.574576 -227.618311)
			(xy 118.575074 -227.64496) (xy 118.574576 -227.671609) (xy 118.803156 -227.671609) (xy 118.803156 -227.618311)
			(xy 118.811099 -227.565607) (xy 118.826809 -227.514677) (xy 118.849935 -227.466656) (xy 118.879959 -227.422619)
			(xy 118.916211 -227.383548) (xy 118.957882 -227.350317) (xy 119.00404 -227.323668) (xy 119.053654 -227.304196)
			(xy 119.105616 -227.292336) (xy 119.158766 -227.288353) (xy 119.211916 -227.292336) (xy 119.263878 -227.304196)
			(xy 119.313492 -227.323668) (xy 119.35965 -227.350317) (xy 119.401321 -227.383548) (xy 119.437573 -227.422619)
			(xy 119.467597 -227.466656) (xy 119.490723 -227.514677) (xy 119.506433 -227.565607) (xy 119.514376 -227.618311)
			(xy 119.514874 -227.64496) (xy 119.514376 -227.671609) (xy 119.742956 -227.671609) (xy 119.742956 -227.618311)
			(xy 119.750899 -227.565607) (xy 119.766609 -227.514677) (xy 119.789735 -227.466656) (xy 119.819759 -227.422619)
			(xy 119.856011 -227.383548) (xy 119.897682 -227.350317) (xy 119.94384 -227.323668) (xy 119.993454 -227.304196)
			(xy 120.045416 -227.292336) (xy 120.098566 -227.288353) (xy 120.151716 -227.292336) (xy 120.203678 -227.304196)
			(xy 120.253292 -227.323668) (xy 120.29945 -227.350317) (xy 120.341121 -227.383548) (xy 120.377373 -227.422619)
			(xy 120.407397 -227.466656) (xy 120.430523 -227.514677) (xy 120.446233 -227.565607) (xy 120.454176 -227.618311)
			(xy 120.454674 -227.64496) (xy 120.454176 -227.671609) (xy 120.682756 -227.671609) (xy 120.682756 -227.618311)
			(xy 120.690699 -227.565607) (xy 120.706409 -227.514677) (xy 120.729535 -227.466656) (xy 120.759559 -227.422619)
			(xy 120.795811 -227.383548) (xy 120.837482 -227.350317) (xy 120.88364 -227.323668) (xy 120.933254 -227.304196)
			(xy 120.985216 -227.292336) (xy 121.038366 -227.288353) (xy 121.091516 -227.292336) (xy 121.143478 -227.304196)
			(xy 121.193092 -227.323668) (xy 121.23925 -227.350317) (xy 121.280921 -227.383548) (xy 121.317173 -227.422619)
			(xy 121.347197 -227.466656) (xy 121.370323 -227.514677) (xy 121.386033 -227.565607) (xy 121.393976 -227.618311)
			(xy 121.394474 -227.64496) (xy 121.393976 -227.671609) (xy 121.622302 -227.671609) (xy 121.622302 -227.618311)
			(xy 121.630245 -227.565607) (xy 121.645955 -227.514677) (xy 121.669081 -227.466656) (xy 121.699105 -227.422619)
			(xy 121.735357 -227.383548) (xy 121.777028 -227.350317) (xy 121.823186 -227.323668) (xy 121.8728 -227.304196)
			(xy 121.924762 -227.292336) (xy 121.977912 -227.288353) (xy 122.031062 -227.292336) (xy 122.083024 -227.304196)
			(xy 122.132638 -227.323668) (xy 122.178796 -227.350317) (xy 122.220467 -227.383548) (xy 122.256719 -227.422619)
			(xy 122.286743 -227.466656) (xy 122.309869 -227.514677) (xy 122.325579 -227.565607) (xy 122.333522 -227.618311)
			(xy 122.33402 -227.64496) (xy 122.333522 -227.671609) (xy 122.562356 -227.671609) (xy 122.562356 -227.618311)
			(xy 122.570299 -227.565607) (xy 122.586009 -227.514677) (xy 122.609135 -227.466656) (xy 122.639159 -227.422619)
			(xy 122.675411 -227.383548) (xy 122.717082 -227.350317) (xy 122.76324 -227.323668) (xy 122.812854 -227.304196)
			(xy 122.864816 -227.292336) (xy 122.917966 -227.288353) (xy 122.971116 -227.292336) (xy 123.023078 -227.304196)
			(xy 123.072692 -227.323668) (xy 123.11885 -227.350317) (xy 123.160521 -227.383548) (xy 123.196773 -227.422619)
			(xy 123.226797 -227.466656) (xy 123.249923 -227.514677) (xy 123.265633 -227.565607) (xy 123.273576 -227.618311)
			(xy 123.274074 -227.64496) (xy 123.273576 -227.671609) (xy 123.502156 -227.671609) (xy 123.502156 -227.618311)
			(xy 123.510099 -227.565607) (xy 123.525809 -227.514677) (xy 123.548935 -227.466656) (xy 123.578959 -227.422619)
			(xy 123.615211 -227.383548) (xy 123.656882 -227.350317) (xy 123.70304 -227.323668) (xy 123.752654 -227.304196)
			(xy 123.804616 -227.292336) (xy 123.857766 -227.288353) (xy 123.910916 -227.292336) (xy 123.962878 -227.304196)
			(xy 124.012492 -227.323668) (xy 124.05865 -227.350317) (xy 124.100321 -227.383548) (xy 124.136573 -227.422619)
			(xy 124.166597 -227.466656) (xy 124.189723 -227.514677) (xy 124.205433 -227.565607) (xy 124.213376 -227.618311)
			(xy 124.213874 -227.64496) (xy 124.213376 -227.671609) (xy 124.441956 -227.671609) (xy 124.441956 -227.618311)
			(xy 124.449899 -227.565607) (xy 124.465609 -227.514677) (xy 124.488735 -227.466656) (xy 124.518759 -227.422619)
			(xy 124.555011 -227.383548) (xy 124.596682 -227.350317) (xy 124.64284 -227.323668) (xy 124.692454 -227.304196)
			(xy 124.744416 -227.292336) (xy 124.797566 -227.288353) (xy 124.850716 -227.292336) (xy 124.902678 -227.304196)
			(xy 124.952292 -227.323668) (xy 124.99845 -227.350317) (xy 125.040121 -227.383548) (xy 125.076373 -227.422619)
			(xy 125.106397 -227.466656) (xy 125.129523 -227.514677) (xy 125.145233 -227.565607) (xy 125.153176 -227.618311)
			(xy 125.153674 -227.64496) (xy 125.153176 -227.671609) (xy 125.381756 -227.671609) (xy 125.381756 -227.618311)
			(xy 125.389699 -227.565607) (xy 125.405409 -227.514677) (xy 125.428535 -227.466656) (xy 125.458559 -227.422619)
			(xy 125.494811 -227.383548) (xy 125.536482 -227.350317) (xy 125.58264 -227.323668) (xy 125.632254 -227.304196)
			(xy 125.684216 -227.292336) (xy 125.737366 -227.288353) (xy 125.790516 -227.292336) (xy 125.842478 -227.304196)
			(xy 125.892092 -227.323668) (xy 125.93825 -227.350317) (xy 125.979921 -227.383548) (xy 126.016173 -227.422619)
			(xy 126.046197 -227.466656) (xy 126.069323 -227.514677) (xy 126.085033 -227.565607) (xy 126.092976 -227.618311)
			(xy 126.093474 -227.64496) (xy 126.092976 -227.671609) (xy 126.321556 -227.671609) (xy 126.321556 -227.618311)
			(xy 126.329499 -227.565607) (xy 126.345209 -227.514677) (xy 126.368335 -227.466656) (xy 126.398359 -227.422619)
			(xy 126.434611 -227.383548) (xy 126.476282 -227.350317) (xy 126.52244 -227.323668) (xy 126.572054 -227.304196)
			(xy 126.624016 -227.292336) (xy 126.677166 -227.288353) (xy 126.730316 -227.292336) (xy 126.782278 -227.304196)
			(xy 126.831892 -227.323668) (xy 126.87805 -227.350317) (xy 126.919721 -227.383548) (xy 126.955973 -227.422619)
			(xy 126.985997 -227.466656) (xy 127.009123 -227.514677) (xy 127.024833 -227.565607) (xy 127.032776 -227.618311)
			(xy 127.033274 -227.64496) (xy 127.032776 -227.671609) (xy 127.261102 -227.671609) (xy 127.261102 -227.618311)
			(xy 127.269045 -227.565607) (xy 127.284755 -227.514677) (xy 127.307881 -227.466656) (xy 127.337905 -227.422619)
			(xy 127.374157 -227.383548) (xy 127.415828 -227.350317) (xy 127.461986 -227.323668) (xy 127.5116 -227.304196)
			(xy 127.563562 -227.292336) (xy 127.616712 -227.288353) (xy 127.669862 -227.292336) (xy 127.721824 -227.304196)
			(xy 127.771438 -227.323668) (xy 127.817596 -227.350317) (xy 127.859267 -227.383548) (xy 127.895519 -227.422619)
			(xy 127.925543 -227.466656) (xy 127.948669 -227.514677) (xy 127.964379 -227.565607) (xy 127.972322 -227.618311)
			(xy 127.97282 -227.64496) (xy 127.972322 -227.671609) (xy 128.200902 -227.671609) (xy 128.200902 -227.618311)
			(xy 128.208845 -227.565607) (xy 128.224555 -227.514677) (xy 128.247681 -227.466656) (xy 128.277705 -227.422619)
			(xy 128.313957 -227.383548) (xy 128.355628 -227.350317) (xy 128.401786 -227.323668) (xy 128.4514 -227.304196)
			(xy 128.503362 -227.292336) (xy 128.556512 -227.288353) (xy 128.609662 -227.292336) (xy 128.661624 -227.304196)
			(xy 128.711238 -227.323668) (xy 128.757396 -227.350317) (xy 128.799067 -227.383548) (xy 128.835319 -227.422619)
			(xy 128.865343 -227.466656) (xy 128.888469 -227.514677) (xy 128.904179 -227.565607) (xy 128.912122 -227.618311)
			(xy 128.91262 -227.64496) (xy 128.912122 -227.671609) (xy 129.140956 -227.671609) (xy 129.140956 -227.618311)
			(xy 129.148899 -227.565607) (xy 129.164609 -227.514677) (xy 129.187735 -227.466656) (xy 129.217759 -227.422619)
			(xy 129.254011 -227.383548) (xy 129.295682 -227.350317) (xy 129.34184 -227.323668) (xy 129.391454 -227.304196)
			(xy 129.443416 -227.292336) (xy 129.496566 -227.288353) (xy 129.549716 -227.292336) (xy 129.601678 -227.304196)
			(xy 129.651292 -227.323668) (xy 129.69745 -227.350317) (xy 129.739121 -227.383548) (xy 129.775373 -227.422619)
			(xy 129.805397 -227.466656) (xy 129.828523 -227.514677) (xy 129.844233 -227.565607) (xy 129.852176 -227.618311)
			(xy 129.852674 -227.64496) (xy 129.852176 -227.671609) (xy 130.080756 -227.671609) (xy 130.080756 -227.618311)
			(xy 130.088699 -227.565607) (xy 130.104409 -227.514677) (xy 130.127535 -227.466656) (xy 130.157559 -227.422619)
			(xy 130.193811 -227.383548) (xy 130.235482 -227.350317) (xy 130.28164 -227.323668) (xy 130.331254 -227.304196)
			(xy 130.383216 -227.292336) (xy 130.436366 -227.288353) (xy 130.489516 -227.292336) (xy 130.541478 -227.304196)
			(xy 130.591092 -227.323668) (xy 130.63725 -227.350317) (xy 130.678921 -227.383548) (xy 130.715173 -227.422619)
			(xy 130.745197 -227.466656) (xy 130.768323 -227.514677) (xy 130.784033 -227.565607) (xy 130.791976 -227.618311)
			(xy 130.792474 -227.64496) (xy 130.791976 -227.671609) (xy 131.020556 -227.671609) (xy 131.020556 -227.618311)
			(xy 131.028499 -227.565607) (xy 131.044209 -227.514677) (xy 131.067335 -227.466656) (xy 131.097359 -227.422619)
			(xy 131.133611 -227.383548) (xy 131.175282 -227.350317) (xy 131.22144 -227.323668) (xy 131.271054 -227.304196)
			(xy 131.323016 -227.292336) (xy 131.376166 -227.288353) (xy 131.429316 -227.292336) (xy 131.481278 -227.304196)
			(xy 131.530892 -227.323668) (xy 131.57705 -227.350317) (xy 131.618721 -227.383548) (xy 131.654973 -227.422619)
			(xy 131.684997 -227.466656) (xy 131.708123 -227.514677) (xy 131.723833 -227.565607) (xy 131.731776 -227.618311)
			(xy 131.732274 -227.64496) (xy 131.731776 -227.671609) (xy 131.960356 -227.671609) (xy 131.960356 -227.618311)
			(xy 131.968299 -227.565607) (xy 131.984009 -227.514677) (xy 132.007135 -227.466656) (xy 132.037159 -227.422619)
			(xy 132.073411 -227.383548) (xy 132.115082 -227.350317) (xy 132.16124 -227.323668) (xy 132.210854 -227.304196)
			(xy 132.262816 -227.292336) (xy 132.315966 -227.288353) (xy 132.369116 -227.292336) (xy 132.421078 -227.304196)
			(xy 132.470692 -227.323668) (xy 132.51685 -227.350317) (xy 132.558521 -227.383548) (xy 132.594773 -227.422619)
			(xy 132.624797 -227.466656) (xy 132.647923 -227.514677) (xy 132.663633 -227.565607) (xy 132.671576 -227.618311)
			(xy 132.672074 -227.64496) (xy 132.671576 -227.671609) (xy 132.900156 -227.671609) (xy 132.900156 -227.618311)
			(xy 132.908099 -227.565607) (xy 132.923809 -227.514677) (xy 132.946935 -227.466656) (xy 132.976959 -227.422619)
			(xy 133.013211 -227.383548) (xy 133.054882 -227.350317) (xy 133.10104 -227.323668) (xy 133.150654 -227.304196)
			(xy 133.202616 -227.292336) (xy 133.255766 -227.288353) (xy 133.308916 -227.292336) (xy 133.360878 -227.304196)
			(xy 133.410492 -227.323668) (xy 133.45665 -227.350317) (xy 133.498321 -227.383548) (xy 133.534573 -227.422619)
			(xy 133.564597 -227.466656) (xy 133.587723 -227.514677) (xy 133.603433 -227.565607) (xy 133.611376 -227.618311)
			(xy 133.611874 -227.64496) (xy 133.611376 -227.671609) (xy 133.839956 -227.671609) (xy 133.839956 -227.618311)
			(xy 133.847899 -227.565607) (xy 133.863609 -227.514677) (xy 133.886735 -227.466656) (xy 133.916759 -227.422619)
			(xy 133.953011 -227.383548) (xy 133.994682 -227.350317) (xy 134.04084 -227.323668) (xy 134.090454 -227.304196)
			(xy 134.142416 -227.292336) (xy 134.195566 -227.288353) (xy 134.248716 -227.292336) (xy 134.300678 -227.304196)
			(xy 134.350292 -227.323668) (xy 134.39645 -227.350317) (xy 134.438121 -227.383548) (xy 134.474373 -227.422619)
			(xy 134.504397 -227.466656) (xy 134.527523 -227.514677) (xy 134.543233 -227.565607) (xy 134.551176 -227.618311)
			(xy 134.551674 -227.64496) (xy 134.551176 -227.671609) (xy 134.543233 -227.724313) (xy 134.527523 -227.775243)
			(xy 134.504397 -227.823264) (xy 134.474373 -227.867301) (xy 134.438121 -227.906372) (xy 134.39645 -227.939603)
			(xy 134.350292 -227.966252) (xy 134.300678 -227.985724) (xy 134.248716 -227.997584) (xy 134.195566 -228.001568)
			(xy 134.142416 -227.997584) (xy 134.090454 -227.985724) (xy 134.04084 -227.966252) (xy 133.994682 -227.939603)
			(xy 133.953011 -227.906372) (xy 133.916759 -227.867301) (xy 133.886735 -227.823264) (xy 133.863609 -227.775243)
			(xy 133.847899 -227.724313) (xy 133.839956 -227.671609) (xy 133.611376 -227.671609) (xy 133.603433 -227.724313)
			(xy 133.587723 -227.775243) (xy 133.564597 -227.823264) (xy 133.534573 -227.867301) (xy 133.498321 -227.906372)
			(xy 133.45665 -227.939603) (xy 133.410492 -227.966252) (xy 133.360878 -227.985724) (xy 133.308916 -227.997584)
			(xy 133.255766 -228.001568) (xy 133.202616 -227.997584) (xy 133.150654 -227.985724) (xy 133.10104 -227.966252)
			(xy 133.054882 -227.939603) (xy 133.013211 -227.906372) (xy 132.976959 -227.867301) (xy 132.946935 -227.823264)
			(xy 132.923809 -227.775243) (xy 132.908099 -227.724313) (xy 132.900156 -227.671609) (xy 132.671576 -227.671609)
			(xy 132.663633 -227.724313) (xy 132.647923 -227.775243) (xy 132.624797 -227.823264) (xy 132.594773 -227.867301)
			(xy 132.558521 -227.906372) (xy 132.51685 -227.939603) (xy 132.470692 -227.966252) (xy 132.421078 -227.985724)
			(xy 132.369116 -227.997584) (xy 132.315966 -228.001568) (xy 132.262816 -227.997584) (xy 132.210854 -227.985724)
			(xy 132.16124 -227.966252) (xy 132.115082 -227.939603) (xy 132.073411 -227.906372) (xy 132.037159 -227.867301)
			(xy 132.007135 -227.823264) (xy 131.984009 -227.775243) (xy 131.968299 -227.724313) (xy 131.960356 -227.671609)
			(xy 131.731776 -227.671609) (xy 131.723833 -227.724313) (xy 131.708123 -227.775243) (xy 131.684997 -227.823264)
			(xy 131.654973 -227.867301) (xy 131.618721 -227.906372) (xy 131.57705 -227.939603) (xy 131.530892 -227.966252)
			(xy 131.481278 -227.985724) (xy 131.429316 -227.997584) (xy 131.376166 -228.001568) (xy 131.323016 -227.997584)
			(xy 131.271054 -227.985724) (xy 131.22144 -227.966252) (xy 131.175282 -227.939603) (xy 131.133611 -227.906372)
			(xy 131.097359 -227.867301) (xy 131.067335 -227.823264) (xy 131.044209 -227.775243) (xy 131.028499 -227.724313)
			(xy 131.020556 -227.671609) (xy 130.791976 -227.671609) (xy 130.784033 -227.724313) (xy 130.768323 -227.775243)
			(xy 130.745197 -227.823264) (xy 130.715173 -227.867301) (xy 130.678921 -227.906372) (xy 130.63725 -227.939603)
			(xy 130.591092 -227.966252) (xy 130.541478 -227.985724) (xy 130.489516 -227.997584) (xy 130.436366 -228.001568)
			(xy 130.383216 -227.997584) (xy 130.331254 -227.985724) (xy 130.28164 -227.966252) (xy 130.235482 -227.939603)
			(xy 130.193811 -227.906372) (xy 130.157559 -227.867301) (xy 130.127535 -227.823264) (xy 130.104409 -227.775243)
			(xy 130.088699 -227.724313) (xy 130.080756 -227.671609) (xy 129.852176 -227.671609) (xy 129.844233 -227.724313)
			(xy 129.828523 -227.775243) (xy 129.805397 -227.823264) (xy 129.775373 -227.867301) (xy 129.739121 -227.906372)
			(xy 129.69745 -227.939603) (xy 129.651292 -227.966252) (xy 129.601678 -227.985724) (xy 129.549716 -227.997584)
			(xy 129.496566 -228.001568) (xy 129.443416 -227.997584) (xy 129.391454 -227.985724) (xy 129.34184 -227.966252)
			(xy 129.295682 -227.939603) (xy 129.254011 -227.906372) (xy 129.217759 -227.867301) (xy 129.187735 -227.823264)
			(xy 129.164609 -227.775243) (xy 129.148899 -227.724313) (xy 129.140956 -227.671609) (xy 128.912122 -227.671609)
			(xy 128.904179 -227.724313) (xy 128.888469 -227.775243) (xy 128.865343 -227.823264) (xy 128.835319 -227.867301)
			(xy 128.799067 -227.906372) (xy 128.757396 -227.939603) (xy 128.711238 -227.966252) (xy 128.661624 -227.985724)
			(xy 128.609662 -227.997584) (xy 128.556512 -228.001568) (xy 128.503362 -227.997584) (xy 128.4514 -227.985724)
			(xy 128.401786 -227.966252) (xy 128.355628 -227.939603) (xy 128.313957 -227.906372) (xy 128.277705 -227.867301)
			(xy 128.247681 -227.823264) (xy 128.224555 -227.775243) (xy 128.208845 -227.724313) (xy 128.200902 -227.671609)
			(xy 127.972322 -227.671609) (xy 127.964379 -227.724313) (xy 127.948669 -227.775243) (xy 127.925543 -227.823264)
			(xy 127.895519 -227.867301) (xy 127.859267 -227.906372) (xy 127.817596 -227.939603) (xy 127.771438 -227.966252)
			(xy 127.721824 -227.985724) (xy 127.669862 -227.997584) (xy 127.616712 -228.001568) (xy 127.563562 -227.997584)
			(xy 127.5116 -227.985724) (xy 127.461986 -227.966252) (xy 127.415828 -227.939603) (xy 127.374157 -227.906372)
			(xy 127.337905 -227.867301) (xy 127.307881 -227.823264) (xy 127.284755 -227.775243) (xy 127.269045 -227.724313)
			(xy 127.261102 -227.671609) (xy 127.032776 -227.671609) (xy 127.024833 -227.724313) (xy 127.009123 -227.775243)
			(xy 126.985997 -227.823264) (xy 126.955973 -227.867301) (xy 126.919721 -227.906372) (xy 126.87805 -227.939603)
			(xy 126.831892 -227.966252) (xy 126.782278 -227.985724) (xy 126.730316 -227.997584) (xy 126.677166 -228.001568)
			(xy 126.624016 -227.997584) (xy 126.572054 -227.985724) (xy 126.52244 -227.966252) (xy 126.476282 -227.939603)
			(xy 126.434611 -227.906372) (xy 126.398359 -227.867301) (xy 126.368335 -227.823264) (xy 126.345209 -227.775243)
			(xy 126.329499 -227.724313) (xy 126.321556 -227.671609) (xy 126.092976 -227.671609) (xy 126.085033 -227.724313)
			(xy 126.069323 -227.775243) (xy 126.046197 -227.823264) (xy 126.016173 -227.867301) (xy 125.979921 -227.906372)
			(xy 125.93825 -227.939603) (xy 125.892092 -227.966252) (xy 125.842478 -227.985724) (xy 125.790516 -227.997584)
			(xy 125.737366 -228.001568) (xy 125.684216 -227.997584) (xy 125.632254 -227.985724) (xy 125.58264 -227.966252)
			(xy 125.536482 -227.939603) (xy 125.494811 -227.906372) (xy 125.458559 -227.867301) (xy 125.428535 -227.823264)
			(xy 125.405409 -227.775243) (xy 125.389699 -227.724313) (xy 125.381756 -227.671609) (xy 125.153176 -227.671609)
			(xy 125.145233 -227.724313) (xy 125.129523 -227.775243) (xy 125.106397 -227.823264) (xy 125.076373 -227.867301)
			(xy 125.040121 -227.906372) (xy 124.99845 -227.939603) (xy 124.952292 -227.966252) (xy 124.902678 -227.985724)
			(xy 124.850716 -227.997584) (xy 124.797566 -228.001568) (xy 124.744416 -227.997584) (xy 124.692454 -227.985724)
			(xy 124.64284 -227.966252) (xy 124.596682 -227.939603) (xy 124.555011 -227.906372) (xy 124.518759 -227.867301)
			(xy 124.488735 -227.823264) (xy 124.465609 -227.775243) (xy 124.449899 -227.724313) (xy 124.441956 -227.671609)
			(xy 124.213376 -227.671609) (xy 124.205433 -227.724313) (xy 124.189723 -227.775243) (xy 124.166597 -227.823264)
			(xy 124.136573 -227.867301) (xy 124.100321 -227.906372) (xy 124.05865 -227.939603) (xy 124.012492 -227.966252)
			(xy 123.962878 -227.985724) (xy 123.910916 -227.997584) (xy 123.857766 -228.001568) (xy 123.804616 -227.997584)
			(xy 123.752654 -227.985724) (xy 123.70304 -227.966252) (xy 123.656882 -227.939603) (xy 123.615211 -227.906372)
			(xy 123.578959 -227.867301) (xy 123.548935 -227.823264) (xy 123.525809 -227.775243) (xy 123.510099 -227.724313)
			(xy 123.502156 -227.671609) (xy 123.273576 -227.671609) (xy 123.265633 -227.724313) (xy 123.249923 -227.775243)
			(xy 123.226797 -227.823264) (xy 123.196773 -227.867301) (xy 123.160521 -227.906372) (xy 123.11885 -227.939603)
			(xy 123.072692 -227.966252) (xy 123.023078 -227.985724) (xy 122.971116 -227.997584) (xy 122.917966 -228.001568)
			(xy 122.864816 -227.997584) (xy 122.812854 -227.985724) (xy 122.76324 -227.966252) (xy 122.717082 -227.939603)
			(xy 122.675411 -227.906372) (xy 122.639159 -227.867301) (xy 122.609135 -227.823264) (xy 122.586009 -227.775243)
			(xy 122.570299 -227.724313) (xy 122.562356 -227.671609) (xy 122.333522 -227.671609) (xy 122.325579 -227.724313)
			(xy 122.309869 -227.775243) (xy 122.286743 -227.823264) (xy 122.256719 -227.867301) (xy 122.220467 -227.906372)
			(xy 122.178796 -227.939603) (xy 122.132638 -227.966252) (xy 122.083024 -227.985724) (xy 122.031062 -227.997584)
			(xy 121.977912 -228.001568) (xy 121.924762 -227.997584) (xy 121.8728 -227.985724) (xy 121.823186 -227.966252)
			(xy 121.777028 -227.939603) (xy 121.735357 -227.906372) (xy 121.699105 -227.867301) (xy 121.669081 -227.823264)
			(xy 121.645955 -227.775243) (xy 121.630245 -227.724313) (xy 121.622302 -227.671609) (xy 121.393976 -227.671609)
			(xy 121.386033 -227.724313) (xy 121.370323 -227.775243) (xy 121.347197 -227.823264) (xy 121.317173 -227.867301)
			(xy 121.280921 -227.906372) (xy 121.23925 -227.939603) (xy 121.193092 -227.966252) (xy 121.143478 -227.985724)
			(xy 121.091516 -227.997584) (xy 121.038366 -228.001568) (xy 120.985216 -227.997584) (xy 120.933254 -227.985724)
			(xy 120.88364 -227.966252) (xy 120.837482 -227.939603) (xy 120.795811 -227.906372) (xy 120.759559 -227.867301)
			(xy 120.729535 -227.823264) (xy 120.706409 -227.775243) (xy 120.690699 -227.724313) (xy 120.682756 -227.671609)
			(xy 120.454176 -227.671609) (xy 120.446233 -227.724313) (xy 120.430523 -227.775243) (xy 120.407397 -227.823264)
			(xy 120.377373 -227.867301) (xy 120.341121 -227.906372) (xy 120.29945 -227.939603) (xy 120.253292 -227.966252)
			(xy 120.203678 -227.985724) (xy 120.151716 -227.997584) (xy 120.098566 -228.001568) (xy 120.045416 -227.997584)
			(xy 119.993454 -227.985724) (xy 119.94384 -227.966252) (xy 119.897682 -227.939603) (xy 119.856011 -227.906372)
			(xy 119.819759 -227.867301) (xy 119.789735 -227.823264) (xy 119.766609 -227.775243) (xy 119.750899 -227.724313)
			(xy 119.742956 -227.671609) (xy 119.514376 -227.671609) (xy 119.506433 -227.724313) (xy 119.490723 -227.775243)
			(xy 119.467597 -227.823264) (xy 119.437573 -227.867301) (xy 119.401321 -227.906372) (xy 119.35965 -227.939603)
			(xy 119.313492 -227.966252) (xy 119.263878 -227.985724) (xy 119.211916 -227.997584) (xy 119.158766 -228.001568)
			(xy 119.105616 -227.997584) (xy 119.053654 -227.985724) (xy 119.00404 -227.966252) (xy 118.957882 -227.939603)
			(xy 118.916211 -227.906372) (xy 118.879959 -227.867301) (xy 118.849935 -227.823264) (xy 118.826809 -227.775243)
			(xy 118.811099 -227.724313) (xy 118.803156 -227.671609) (xy 118.574576 -227.671609) (xy 118.566633 -227.724313)
			(xy 118.550923 -227.775243) (xy 118.527797 -227.823264) (xy 118.497773 -227.867301) (xy 118.461521 -227.906372)
			(xy 118.41985 -227.939603) (xy 118.373692 -227.966252) (xy 118.324078 -227.985724) (xy 118.272116 -227.997584)
			(xy 118.218966 -228.001568) (xy 118.165816 -227.997584) (xy 118.113854 -227.985724) (xy 118.06424 -227.966252)
			(xy 118.018082 -227.939603) (xy 117.976411 -227.906372) (xy 117.940159 -227.867301) (xy 117.910135 -227.823264)
			(xy 117.887009 -227.775243) (xy 117.871299 -227.724313) (xy 117.863356 -227.671609) (xy 117.634776 -227.671609)
			(xy 117.626833 -227.724313) (xy 117.611123 -227.775243) (xy 117.587997 -227.823264) (xy 117.557973 -227.867301)
			(xy 117.521721 -227.906372) (xy 117.48005 -227.939603) (xy 117.433892 -227.966252) (xy 117.384278 -227.985724)
			(xy 117.332316 -227.997584) (xy 117.279166 -228.001568) (xy 117.226016 -227.997584) (xy 117.174054 -227.985724)
			(xy 117.12444 -227.966252) (xy 117.078282 -227.939603) (xy 117.036611 -227.906372) (xy 117.000359 -227.867301)
			(xy 116.970335 -227.823264) (xy 116.947209 -227.775243) (xy 116.931499 -227.724313) (xy 116.923556 -227.671609)
			(xy 116.694976 -227.671609) (xy 116.687033 -227.724313) (xy 116.671323 -227.775243) (xy 116.648197 -227.823264)
			(xy 116.618173 -227.867301) (xy 116.581921 -227.906372) (xy 116.54025 -227.939603) (xy 116.494092 -227.966252)
			(xy 116.444478 -227.985724) (xy 116.392516 -227.997584) (xy 116.339366 -228.001568) (xy 116.286216 -227.997584)
			(xy 116.234254 -227.985724) (xy 116.18464 -227.966252) (xy 116.138482 -227.939603) (xy 116.096811 -227.906372)
			(xy 116.060559 -227.867301) (xy 116.030535 -227.823264) (xy 116.007409 -227.775243) (xy 115.991699 -227.724313)
			(xy 115.983756 -227.671609) (xy 115.755176 -227.671609) (xy 115.747233 -227.724313) (xy 115.731523 -227.775243)
			(xy 115.708397 -227.823264) (xy 115.678373 -227.867301) (xy 115.642121 -227.906372) (xy 115.60045 -227.939603)
			(xy 115.554292 -227.966252) (xy 115.504678 -227.985724) (xy 115.452716 -227.997584) (xy 115.399566 -228.001568)
			(xy 115.346416 -227.997584) (xy 115.294454 -227.985724) (xy 115.24484 -227.966252) (xy 115.198682 -227.939603)
			(xy 115.157011 -227.906372) (xy 115.120759 -227.867301) (xy 115.090735 -227.823264) (xy 115.067609 -227.775243)
			(xy 115.051899 -227.724313) (xy 115.043956 -227.671609) (xy 114.81563 -227.671609) (xy 114.807687 -227.724313)
			(xy 114.791977 -227.775243) (xy 114.768851 -227.823264) (xy 114.738827 -227.867301) (xy 114.702575 -227.906372)
			(xy 114.660904 -227.939603) (xy 114.614746 -227.966252) (xy 114.565132 -227.985724) (xy 114.51317 -227.997584)
			(xy 114.46002 -228.001568) (xy 114.40687 -227.997584) (xy 114.354908 -227.985724) (xy 114.305294 -227.966252)
			(xy 114.259136 -227.939603) (xy 114.217465 -227.906372) (xy 114.181213 -227.867301) (xy 114.151189 -227.823264)
			(xy 114.128063 -227.775243) (xy 114.112353 -227.724313) (xy 114.10441 -227.671609) (xy 113.875576 -227.671609)
			(xy 113.867633 -227.724313) (xy 113.851923 -227.775243) (xy 113.828797 -227.823264) (xy 113.798773 -227.867301)
			(xy 113.762521 -227.906372) (xy 113.72085 -227.939603) (xy 113.674692 -227.966252) (xy 113.625078 -227.985724)
			(xy 113.573116 -227.997584) (xy 113.519966 -228.001568) (xy 113.466816 -227.997584) (xy 113.414854 -227.985724)
			(xy 113.36524 -227.966252) (xy 113.319082 -227.939603) (xy 113.277411 -227.906372) (xy 113.241159 -227.867301)
			(xy 113.211135 -227.823264) (xy 113.188009 -227.775243) (xy 113.172299 -227.724313) (xy 113.164356 -227.671609)
			(xy 112.935776 -227.671609) (xy 112.927833 -227.724313) (xy 112.912123 -227.775243) (xy 112.888997 -227.823264)
			(xy 112.858973 -227.867301) (xy 112.822721 -227.906372) (xy 112.78105 -227.939603) (xy 112.734892 -227.966252)
			(xy 112.685278 -227.985724) (xy 112.633316 -227.997584) (xy 112.580166 -228.001568) (xy 112.527016 -227.997584)
			(xy 112.475054 -227.985724) (xy 112.42544 -227.966252) (xy 112.379282 -227.939603) (xy 112.337611 -227.906372)
			(xy 112.301359 -227.867301) (xy 112.271335 -227.823264) (xy 112.248209 -227.775243) (xy 112.232499 -227.724313)
			(xy 112.224556 -227.671609) (xy 111.995976 -227.671609) (xy 111.988033 -227.724313) (xy 111.972323 -227.775243)
			(xy 111.949197 -227.823264) (xy 111.919173 -227.867301) (xy 111.882921 -227.906372) (xy 111.84125 -227.939603)
			(xy 111.795092 -227.966252) (xy 111.745478 -227.985724) (xy 111.693516 -227.997584) (xy 111.640366 -228.001568)
			(xy 111.587216 -227.997584) (xy 111.535254 -227.985724) (xy 111.48564 -227.966252) (xy 111.439482 -227.939603)
			(xy 111.397811 -227.906372) (xy 111.361559 -227.867301) (xy 111.331535 -227.823264) (xy 111.308409 -227.775243)
			(xy 111.292699 -227.724313) (xy 111.284756 -227.671609) (xy 111.056176 -227.671609) (xy 111.048233 -227.724313)
			(xy 111.032523 -227.775243) (xy 111.009397 -227.823264) (xy 110.979373 -227.867301) (xy 110.943121 -227.906372)
			(xy 110.90145 -227.939603) (xy 110.855292 -227.966252) (xy 110.805678 -227.985724) (xy 110.753716 -227.997584)
			(xy 110.700566 -228.001568) (xy 110.647416 -227.997584) (xy 110.595454 -227.985724) (xy 110.54584 -227.966252)
			(xy 110.499682 -227.939603) (xy 110.458011 -227.906372) (xy 110.421759 -227.867301) (xy 110.391735 -227.823264)
			(xy 110.368609 -227.775243) (xy 110.352899 -227.724313) (xy 110.344956 -227.671609) (xy 110.116376 -227.671609)
			(xy 110.108433 -227.724313) (xy 110.092723 -227.775243) (xy 110.069597 -227.823264) (xy 110.039573 -227.867301)
			(xy 110.003321 -227.906372) (xy 109.96165 -227.939603) (xy 109.915492 -227.966252) (xy 109.865878 -227.985724)
			(xy 109.813916 -227.997584) (xy 109.760766 -228.001568) (xy 109.707616 -227.997584) (xy 109.655654 -227.985724)
			(xy 109.60604 -227.966252) (xy 109.559882 -227.939603) (xy 109.518211 -227.906372) (xy 109.481959 -227.867301)
			(xy 109.451935 -227.823264) (xy 109.428809 -227.775243) (xy 109.413099 -227.724313) (xy 109.405156 -227.671609)
			(xy 109.176576 -227.671609) (xy 109.168633 -227.724313) (xy 109.152923 -227.775243) (xy 109.129797 -227.823264)
			(xy 109.099773 -227.867301) (xy 109.063521 -227.906372) (xy 109.02185 -227.939603) (xy 108.975692 -227.966252)
			(xy 108.926078 -227.985724) (xy 108.874116 -227.997584) (xy 108.820966 -228.001568) (xy 108.767816 -227.997584)
			(xy 108.715854 -227.985724) (xy 108.66624 -227.966252) (xy 108.620082 -227.939603) (xy 108.578411 -227.906372)
			(xy 108.542159 -227.867301) (xy 108.512135 -227.823264) (xy 108.489009 -227.775243) (xy 108.473299 -227.724313)
			(xy 108.465356 -227.671609) (xy 108.236776 -227.671609) (xy 108.228833 -227.724313) (xy 108.213123 -227.775243)
			(xy 108.189997 -227.823264) (xy 108.159973 -227.867301) (xy 108.123721 -227.906372) (xy 108.08205 -227.939603)
			(xy 108.035892 -227.966252) (xy 107.986278 -227.985724) (xy 107.934316 -227.997584) (xy 107.881166 -228.001568)
			(xy 107.828016 -227.997584) (xy 107.776054 -227.985724) (xy 107.72644 -227.966252) (xy 107.680282 -227.939603)
			(xy 107.638611 -227.906372) (xy 107.602359 -227.867301) (xy 107.572335 -227.823264) (xy 107.549209 -227.775243)
			(xy 107.533499 -227.724313) (xy 107.525556 -227.671609) (xy 107.296976 -227.671609) (xy 107.289033 -227.724313)
			(xy 107.273323 -227.775243) (xy 107.250197 -227.823264) (xy 107.220173 -227.867301) (xy 107.183921 -227.906372)
			(xy 107.14225 -227.939603) (xy 107.096092 -227.966252) (xy 107.046478 -227.985724) (xy 106.994516 -227.997584)
			(xy 106.941366 -228.001568) (xy 106.888216 -227.997584) (xy 106.836254 -227.985724) (xy 106.78664 -227.966252)
			(xy 106.740482 -227.939603) (xy 106.698811 -227.906372) (xy 106.662559 -227.867301) (xy 106.632535 -227.823264)
			(xy 106.609409 -227.775243) (xy 106.593699 -227.724313) (xy 106.585756 -227.671609) (xy 106.357176 -227.671609)
			(xy 106.349233 -227.724313) (xy 106.333523 -227.775243) (xy 106.310397 -227.823264) (xy 106.280373 -227.867301)
			(xy 106.244121 -227.906372) (xy 106.20245 -227.939603) (xy 106.156292 -227.966252) (xy 106.106678 -227.985724)
			(xy 106.054716 -227.997584) (xy 106.001566 -228.001568) (xy 105.948416 -227.997584) (xy 105.896454 -227.985724)
			(xy 105.84684 -227.966252) (xy 105.800682 -227.939603) (xy 105.759011 -227.906372) (xy 105.722759 -227.867301)
			(xy 105.692735 -227.823264) (xy 105.669609 -227.775243) (xy 105.653899 -227.724313) (xy 105.645956 -227.671609)
			(xy 105.417376 -227.671609) (xy 105.409433 -227.724313) (xy 105.393723 -227.775243) (xy 105.370597 -227.823264)
			(xy 105.340573 -227.867301) (xy 105.304321 -227.906372) (xy 105.26265 -227.939603) (xy 105.216492 -227.966252)
			(xy 105.166878 -227.985724) (xy 105.114916 -227.997584) (xy 105.061766 -228.001568) (xy 105.008616 -227.997584)
			(xy 104.956654 -227.985724) (xy 104.90704 -227.966252) (xy 104.860882 -227.939603) (xy 104.819211 -227.906372)
			(xy 104.782959 -227.867301) (xy 104.752935 -227.823264) (xy 104.729809 -227.775243) (xy 104.714099 -227.724313)
			(xy 104.706156 -227.671609) (xy 104.477576 -227.671609) (xy 104.469633 -227.724313) (xy 104.453923 -227.775243)
			(xy 104.430797 -227.823264) (xy 104.400773 -227.867301) (xy 104.364521 -227.906372) (xy 104.32285 -227.939603)
			(xy 104.276692 -227.966252) (xy 104.227078 -227.985724) (xy 104.175116 -227.997584) (xy 104.121966 -228.001568)
			(xy 104.068816 -227.997584) (xy 104.016854 -227.985724) (xy 103.96724 -227.966252) (xy 103.921082 -227.939603)
			(xy 103.879411 -227.906372) (xy 103.843159 -227.867301) (xy 103.813135 -227.823264) (xy 103.790009 -227.775243)
			(xy 103.774299 -227.724313) (xy 103.766356 -227.671609) (xy 102.597976 -227.671609) (xy 102.590033 -227.724313)
			(xy 102.574323 -227.775243) (xy 102.551197 -227.823264) (xy 102.521173 -227.867301) (xy 102.484921 -227.906372)
			(xy 102.44325 -227.939603) (xy 102.397092 -227.966252) (xy 102.347478 -227.985724) (xy 102.295516 -227.997584)
			(xy 102.242366 -228.001568) (xy 102.189216 -227.997584) (xy 102.137254 -227.985724) (xy 102.08764 -227.966252)
			(xy 102.041482 -227.939603) (xy 101.999811 -227.906372) (xy 101.963559 -227.867301) (xy 101.933535 -227.823264)
			(xy 101.910409 -227.775243) (xy 101.894699 -227.724313) (xy 101.886756 -227.671609) (xy 101.658176 -227.671609)
			(xy 101.650233 -227.724313) (xy 101.634523 -227.775243) (xy 101.611397 -227.823264) (xy 101.581373 -227.867301)
			(xy 101.545121 -227.906372) (xy 101.50345 -227.939603) (xy 101.457292 -227.966252) (xy 101.407678 -227.985724)
			(xy 101.355716 -227.997584) (xy 101.302566 -228.001568) (xy 101.249416 -227.997584) (xy 101.197454 -227.985724)
			(xy 101.14784 -227.966252) (xy 101.101682 -227.939603) (xy 101.060011 -227.906372) (xy 101.023759 -227.867301)
			(xy 100.993735 -227.823264) (xy 100.970609 -227.775243) (xy 100.954899 -227.724313) (xy 100.946956 -227.671609)
			(xy 100.718376 -227.671609) (xy 100.710433 -227.724313) (xy 100.694723 -227.775243) (xy 100.671597 -227.823264)
			(xy 100.641573 -227.867301) (xy 100.605321 -227.906372) (xy 100.56365 -227.939603) (xy 100.517492 -227.966252)
			(xy 100.467878 -227.985724) (xy 100.415916 -227.997584) (xy 100.362766 -228.001568) (xy 100.309616 -227.997584)
			(xy 100.257654 -227.985724) (xy 100.20804 -227.966252) (xy 100.161882 -227.939603) (xy 100.120211 -227.906372)
			(xy 100.083959 -227.867301) (xy 100.053935 -227.823264) (xy 100.030809 -227.775243) (xy 100.015099 -227.724313)
			(xy 100.007156 -227.671609) (xy 99.778322 -227.671609) (xy 99.770379 -227.724313) (xy 99.754669 -227.775243)
			(xy 99.731543 -227.823264) (xy 99.701519 -227.867301) (xy 99.665267 -227.906372) (xy 99.623596 -227.939603)
			(xy 99.577438 -227.966252) (xy 99.527824 -227.985724) (xy 99.475862 -227.997584) (xy 99.422712 -228.001568)
			(xy 99.369562 -227.997584) (xy 99.3176 -227.985724) (xy 99.267986 -227.966252) (xy 99.221828 -227.939603)
			(xy 99.180157 -227.906372) (xy 99.143905 -227.867301) (xy 99.113881 -227.823264) (xy 99.090755 -227.775243)
			(xy 99.075045 -227.724313) (xy 99.067102 -227.671609) (xy 98.838776 -227.671609) (xy 98.830833 -227.724313)
			(xy 98.815123 -227.775243) (xy 98.791997 -227.823264) (xy 98.761973 -227.867301) (xy 98.725721 -227.906372)
			(xy 98.68405 -227.939603) (xy 98.637892 -227.966252) (xy 98.588278 -227.985724) (xy 98.536316 -227.997584)
			(xy 98.483166 -228.001568) (xy 98.430016 -227.997584) (xy 98.378054 -227.985724) (xy 98.32844 -227.966252)
			(xy 98.282282 -227.939603) (xy 98.240611 -227.906372) (xy 98.204359 -227.867301) (xy 98.174335 -227.823264)
			(xy 98.151209 -227.775243) (xy 98.135499 -227.724313) (xy 98.127556 -227.671609) (xy 97.898976 -227.671609)
			(xy 97.891033 -227.724313) (xy 97.875323 -227.775243) (xy 97.852197 -227.823264) (xy 97.822173 -227.867301)
			(xy 97.785921 -227.906372) (xy 97.74425 -227.939603) (xy 97.698092 -227.966252) (xy 97.648478 -227.985724)
			(xy 97.596516 -227.997584) (xy 97.543366 -228.001568) (xy 97.490216 -227.997584) (xy 97.438254 -227.985724)
			(xy 97.38864 -227.966252) (xy 97.342482 -227.939603) (xy 97.300811 -227.906372) (xy 97.264559 -227.867301)
			(xy 97.234535 -227.823264) (xy 97.211409 -227.775243) (xy 97.195699 -227.724313) (xy 97.187756 -227.671609)
			(xy 96.959176 -227.671609) (xy 96.951233 -227.724313) (xy 96.935523 -227.775243) (xy 96.912397 -227.823264)
			(xy 96.882373 -227.867301) (xy 96.846121 -227.906372) (xy 96.80445 -227.939603) (xy 96.758292 -227.966252)
			(xy 96.708678 -227.985724) (xy 96.656716 -227.997584) (xy 96.603566 -228.001568) (xy 96.550416 -227.997584)
			(xy 96.498454 -227.985724) (xy 96.44884 -227.966252) (xy 96.402682 -227.939603) (xy 96.361011 -227.906372)
			(xy 96.324759 -227.867301) (xy 96.294735 -227.823264) (xy 96.271609 -227.775243) (xy 96.255899 -227.724313)
			(xy 96.247956 -227.671609) (xy 96.019376 -227.671609) (xy 96.011433 -227.724313) (xy 95.995723 -227.775243)
			(xy 95.972597 -227.823264) (xy 95.942573 -227.867301) (xy 95.906321 -227.906372) (xy 95.86465 -227.939603)
			(xy 95.818492 -227.966252) (xy 95.768878 -227.985724) (xy 95.716916 -227.997584) (xy 95.663766 -228.001568)
			(xy 95.610616 -227.997584) (xy 95.558654 -227.985724) (xy 95.50904 -227.966252) (xy 95.462882 -227.939603)
			(xy 95.421211 -227.906372) (xy 95.384959 -227.867301) (xy 95.354935 -227.823264) (xy 95.331809 -227.775243)
			(xy 95.316099 -227.724313) (xy 95.308156 -227.671609) (xy 95.079576 -227.671609) (xy 95.071633 -227.724313)
			(xy 95.055923 -227.775243) (xy 95.032797 -227.823264) (xy 95.002773 -227.867301) (xy 94.966521 -227.906372)
			(xy 94.92485 -227.939603) (xy 94.878692 -227.966252) (xy 94.829078 -227.985724) (xy 94.777116 -227.997584)
			(xy 94.723966 -228.001568) (xy 94.670816 -227.997584) (xy 94.618854 -227.985724) (xy 94.56924 -227.966252)
			(xy 94.523082 -227.939603) (xy 94.481411 -227.906372) (xy 94.445159 -227.867301) (xy 94.415135 -227.823264)
			(xy 94.392009 -227.775243) (xy 94.376299 -227.724313) (xy 94.368356 -227.671609) (xy 94.139776 -227.671609)
			(xy 94.131833 -227.724313) (xy 94.116123 -227.775243) (xy 94.092997 -227.823264) (xy 94.062973 -227.867301)
			(xy 94.026721 -227.906372) (xy 93.98505 -227.939603) (xy 93.938892 -227.966252) (xy 93.889278 -227.985724)
			(xy 93.837316 -227.997584) (xy 93.784166 -228.001568) (xy 93.731016 -227.997584) (xy 93.679054 -227.985724)
			(xy 93.62944 -227.966252) (xy 93.583282 -227.939603) (xy 93.541611 -227.906372) (xy 93.505359 -227.867301)
			(xy 93.475335 -227.823264) (xy 93.452209 -227.775243) (xy 93.436499 -227.724313) (xy 93.428556 -227.671609)
			(xy 93.199976 -227.671609) (xy 93.192033 -227.724313) (xy 93.176323 -227.775243) (xy 93.153197 -227.823264)
			(xy 93.123173 -227.867301) (xy 93.086921 -227.906372) (xy 93.04525 -227.939603) (xy 92.999092 -227.966252)
			(xy 92.949478 -227.985724) (xy 92.897516 -227.997584) (xy 92.844366 -228.001568) (xy 92.791216 -227.997584)
			(xy 92.739254 -227.985724) (xy 92.68964 -227.966252) (xy 92.643482 -227.939603) (xy 92.601811 -227.906372)
			(xy 92.565559 -227.867301) (xy 92.535535 -227.823264) (xy 92.512409 -227.775243) (xy 92.496699 -227.724313)
			(xy 92.488756 -227.671609) (xy 92.259922 -227.671609) (xy 92.251979 -227.724313) (xy 92.236269 -227.775243)
			(xy 92.213143 -227.823264) (xy 92.183119 -227.867301) (xy 92.146867 -227.906372) (xy 92.105196 -227.939603)
			(xy 92.059038 -227.966252) (xy 92.009424 -227.985724) (xy 91.957462 -227.997584) (xy 91.904312 -228.001568)
			(xy 91.851162 -227.997584) (xy 91.7992 -227.985724) (xy 91.749586 -227.966252) (xy 91.703428 -227.939603)
			(xy 91.661757 -227.906372) (xy 91.625505 -227.867301) (xy 91.595481 -227.823264) (xy 91.572355 -227.775243)
			(xy 91.556645 -227.724313) (xy 91.548702 -227.671609) (xy 91.320376 -227.671609) (xy 91.312433 -227.724313)
			(xy 91.296723 -227.775243) (xy 91.273597 -227.823264) (xy 91.243573 -227.867301) (xy 91.207321 -227.906372)
			(xy 91.16565 -227.939603) (xy 91.119492 -227.966252) (xy 91.069878 -227.985724) (xy 91.017916 -227.997584)
			(xy 90.964766 -228.001568) (xy 90.911616 -227.997584) (xy 90.859654 -227.985724) (xy 90.81004 -227.966252)
			(xy 90.763882 -227.939603) (xy 90.722211 -227.906372) (xy 90.685959 -227.867301) (xy 90.655935 -227.823264)
			(xy 90.632809 -227.775243) (xy 90.617099 -227.724313) (xy 90.609156 -227.671609) (xy 90.380576 -227.671609)
			(xy 90.372633 -227.724313) (xy 90.356923 -227.775243) (xy 90.333797 -227.823264) (xy 90.303773 -227.867301)
			(xy 90.267521 -227.906372) (xy 90.22585 -227.939603) (xy 90.179692 -227.966252) (xy 90.130078 -227.985724)
			(xy 90.078116 -227.997584) (xy 90.024966 -228.001568) (xy 89.971816 -227.997584) (xy 89.919854 -227.985724)
			(xy 89.87024 -227.966252) (xy 89.824082 -227.939603) (xy 89.782411 -227.906372) (xy 89.746159 -227.867301)
			(xy 89.716135 -227.823264) (xy 89.693009 -227.775243) (xy 89.677299 -227.724313) (xy 89.669356 -227.671609)
			(xy 89.440781 -227.671609) (xy 89.440756 -227.672946) (xy 89.432005 -227.728231) (xy 89.414713 -227.781465)
			(xy 89.389304 -227.831339) (xy 89.356405 -227.876622) (xy 89.316827 -227.916202) (xy 89.271544 -227.949101)
			(xy 89.221671 -227.97451) (xy 89.168437 -227.991804) (xy 89.113152 -228.000556) (xy 89.085166 -228.001068)
			(xy 89.057441 -228.000515) (xy 89.002668 -227.991877) (xy 88.949893 -227.974862) (xy 88.900389 -227.949881)
			(xy 88.85535 -227.917535) (xy 88.83523 -227.898452) (xy 88.827732 -227.891804) (xy 88.809154 -227.884351)
			(xy 88.789137 -227.884572) (xy 88.770728 -227.892432) (xy 88.763348 -227.899214) (xy 88.747075 -227.915656)
			(xy 88.713669 -227.947667) (xy 88.696546 -227.963222) (xy 88.689688 -227.993448) (xy 88.688418 -227.99929)
			(xy 88.688418 -228.10851) (xy 88.723724 -228.11994) (xy 88.74873 -228.128463) (xy 88.7961 -228.15185)
			(xy 88.839495 -228.18198) (xy 88.877961 -228.21819) (xy 88.910656 -228.259686) (xy 88.93686 -228.305558)
			(xy 88.955999 -228.354798) (xy 88.967652 -228.406326) (xy 88.971564 -228.459009) (xy 88.969583 -228.485679)
			(xy 89.199202 -228.485679) (xy 89.199202 -228.432381) (xy 89.207145 -228.379677) (xy 89.222855 -228.328747)
			(xy 89.245981 -228.280726) (xy 89.276005 -228.236689) (xy 89.312257 -228.197618) (xy 89.353928 -228.164387)
			(xy 89.400086 -228.137738) (xy 89.4497 -228.118266) (xy 89.501662 -228.106406) (xy 89.554812 -228.102423)
			(xy 89.607962 -228.106406) (xy 89.659924 -228.118266) (xy 89.709538 -228.137738) (xy 89.755696 -228.164387)
			(xy 89.797367 -228.197618) (xy 89.833619 -228.236689) (xy 89.863643 -228.280726) (xy 89.886769 -228.328747)
			(xy 89.902479 -228.379677) (xy 89.910422 -228.432381) (xy 89.91092 -228.45903) (xy 89.910422 -228.485679)
			(xy 90.139002 -228.485679) (xy 90.139002 -228.432381) (xy 90.146945 -228.379677) (xy 90.162655 -228.328747)
			(xy 90.185781 -228.280726) (xy 90.215805 -228.236689) (xy 90.252057 -228.197618) (xy 90.293728 -228.164387)
			(xy 90.339886 -228.137738) (xy 90.3895 -228.118266) (xy 90.441462 -228.106406) (xy 90.494612 -228.102423)
			(xy 90.547762 -228.106406) (xy 90.599724 -228.118266) (xy 90.649338 -228.137738) (xy 90.695496 -228.164387)
			(xy 90.737167 -228.197618) (xy 90.773419 -228.236689) (xy 90.803443 -228.280726) (xy 90.826569 -228.328747)
			(xy 90.842279 -228.379677) (xy 90.850222 -228.432381) (xy 90.85072 -228.45903) (xy 90.850222 -228.485679)
			(xy 91.079056 -228.485679) (xy 91.079056 -228.432381) (xy 91.086999 -228.379677) (xy 91.102709 -228.328747)
			(xy 91.125835 -228.280726) (xy 91.155859 -228.236689) (xy 91.192111 -228.197618) (xy 91.233782 -228.164387)
			(xy 91.27994 -228.137738) (xy 91.329554 -228.118266) (xy 91.381516 -228.106406) (xy 91.434666 -228.102423)
			(xy 91.487816 -228.106406) (xy 91.539778 -228.118266) (xy 91.589392 -228.137738) (xy 91.63555 -228.164387)
			(xy 91.677221 -228.197618) (xy 91.713473 -228.236689) (xy 91.743497 -228.280726) (xy 91.766623 -228.328747)
			(xy 91.782333 -228.379677) (xy 91.790276 -228.432381) (xy 91.790774 -228.45903) (xy 91.790276 -228.485679)
			(xy 92.018602 -228.485679) (xy 92.018602 -228.432381) (xy 92.026545 -228.379677) (xy 92.042255 -228.328747)
			(xy 92.065381 -228.280726) (xy 92.095405 -228.236689) (xy 92.131657 -228.197618) (xy 92.173328 -228.164387)
			(xy 92.219486 -228.137738) (xy 92.2691 -228.118266) (xy 92.321062 -228.106406) (xy 92.374212 -228.102423)
			(xy 92.427362 -228.106406) (xy 92.479324 -228.118266) (xy 92.528938 -228.137738) (xy 92.575096 -228.164387)
			(xy 92.616767 -228.197618) (xy 92.653019 -228.236689) (xy 92.683043 -228.280726) (xy 92.706169 -228.328747)
			(xy 92.721879 -228.379677) (xy 92.729822 -228.432381) (xy 92.73032 -228.45903) (xy 92.729822 -228.485679)
			(xy 92.958402 -228.485679) (xy 92.958402 -228.432381) (xy 92.966345 -228.379677) (xy 92.982055 -228.328747)
			(xy 93.005181 -228.280726) (xy 93.035205 -228.236689) (xy 93.071457 -228.197618) (xy 93.113128 -228.164387)
			(xy 93.159286 -228.137738) (xy 93.2089 -228.118266) (xy 93.260862 -228.106406) (xy 93.314012 -228.102423)
			(xy 93.367162 -228.106406) (xy 93.419124 -228.118266) (xy 93.468738 -228.137738) (xy 93.514896 -228.164387)
			(xy 93.556567 -228.197618) (xy 93.592819 -228.236689) (xy 93.622843 -228.280726) (xy 93.645969 -228.328747)
			(xy 93.661679 -228.379677) (xy 93.669622 -228.432381) (xy 93.67012 -228.45903) (xy 93.669622 -228.485679)
			(xy 93.898202 -228.485679) (xy 93.898202 -228.432381) (xy 93.906145 -228.379677) (xy 93.921855 -228.328747)
			(xy 93.944981 -228.280726) (xy 93.975005 -228.236689) (xy 94.011257 -228.197618) (xy 94.052928 -228.164387)
			(xy 94.099086 -228.137738) (xy 94.1487 -228.118266) (xy 94.200662 -228.106406) (xy 94.253812 -228.102423)
			(xy 94.306962 -228.106406) (xy 94.358924 -228.118266) (xy 94.408538 -228.137738) (xy 94.454696 -228.164387)
			(xy 94.496367 -228.197618) (xy 94.532619 -228.236689) (xy 94.562643 -228.280726) (xy 94.585769 -228.328747)
			(xy 94.601479 -228.379677) (xy 94.609422 -228.432381) (xy 94.60992 -228.45903) (xy 94.609422 -228.485679)
			(xy 94.838002 -228.485679) (xy 94.838002 -228.432381) (xy 94.845945 -228.379677) (xy 94.861655 -228.328747)
			(xy 94.884781 -228.280726) (xy 94.914805 -228.236689) (xy 94.951057 -228.197618) (xy 94.992728 -228.164387)
			(xy 95.038886 -228.137738) (xy 95.0885 -228.118266) (xy 95.140462 -228.106406) (xy 95.193612 -228.102423)
			(xy 95.246762 -228.106406) (xy 95.298724 -228.118266) (xy 95.348338 -228.137738) (xy 95.394496 -228.164387)
			(xy 95.436167 -228.197618) (xy 95.472419 -228.236689) (xy 95.502443 -228.280726) (xy 95.525569 -228.328747)
			(xy 95.541279 -228.379677) (xy 95.549222 -228.432381) (xy 95.54972 -228.45903) (xy 95.549222 -228.485679)
			(xy 95.777802 -228.485679) (xy 95.777802 -228.432381) (xy 95.785745 -228.379677) (xy 95.801455 -228.328747)
			(xy 95.824581 -228.280726) (xy 95.854605 -228.236689) (xy 95.890857 -228.197618) (xy 95.932528 -228.164387)
			(xy 95.978686 -228.137738) (xy 96.0283 -228.118266) (xy 96.080262 -228.106406) (xy 96.133412 -228.102423)
			(xy 96.186562 -228.106406) (xy 96.238524 -228.118266) (xy 96.288138 -228.137738) (xy 96.334296 -228.164387)
			(xy 96.375967 -228.197618) (xy 96.412219 -228.236689) (xy 96.442243 -228.280726) (xy 96.465369 -228.328747)
			(xy 96.481079 -228.379677) (xy 96.489022 -228.432381) (xy 96.48952 -228.45903) (xy 96.489022 -228.485679)
			(xy 96.717602 -228.485679) (xy 96.717602 -228.432381) (xy 96.725545 -228.379677) (xy 96.741255 -228.328747)
			(xy 96.764381 -228.280726) (xy 96.794405 -228.236689) (xy 96.830657 -228.197618) (xy 96.872328 -228.164387)
			(xy 96.918486 -228.137738) (xy 96.9681 -228.118266) (xy 97.020062 -228.106406) (xy 97.073212 -228.102423)
			(xy 97.126362 -228.106406) (xy 97.178324 -228.118266) (xy 97.227938 -228.137738) (xy 97.274096 -228.164387)
			(xy 97.315767 -228.197618) (xy 97.352019 -228.236689) (xy 97.382043 -228.280726) (xy 97.405169 -228.328747)
			(xy 97.420879 -228.379677) (xy 97.428822 -228.432381) (xy 97.42932 -228.45903) (xy 97.428822 -228.485679)
			(xy 97.657656 -228.485679) (xy 97.657656 -228.432381) (xy 97.665599 -228.379677) (xy 97.681309 -228.328747)
			(xy 97.704435 -228.280726) (xy 97.734459 -228.236689) (xy 97.770711 -228.197618) (xy 97.812382 -228.164387)
			(xy 97.85854 -228.137738) (xy 97.908154 -228.118266) (xy 97.960116 -228.106406) (xy 98.013266 -228.102423)
			(xy 98.066416 -228.106406) (xy 98.118378 -228.118266) (xy 98.167992 -228.137738) (xy 98.21415 -228.164387)
			(xy 98.255821 -228.197618) (xy 98.292073 -228.236689) (xy 98.322097 -228.280726) (xy 98.345223 -228.328747)
			(xy 98.360933 -228.379677) (xy 98.368876 -228.432381) (xy 98.369374 -228.45903) (xy 98.368876 -228.485679)
			(xy 98.597202 -228.485679) (xy 98.597202 -228.432381) (xy 98.605145 -228.379677) (xy 98.620855 -228.328747)
			(xy 98.643981 -228.280726) (xy 98.674005 -228.236689) (xy 98.710257 -228.197618) (xy 98.751928 -228.164387)
			(xy 98.798086 -228.137738) (xy 98.8477 -228.118266) (xy 98.899662 -228.106406) (xy 98.952812 -228.102423)
			(xy 99.005962 -228.106406) (xy 99.057924 -228.118266) (xy 99.107538 -228.137738) (xy 99.153696 -228.164387)
			(xy 99.195367 -228.197618) (xy 99.231619 -228.236689) (xy 99.261643 -228.280726) (xy 99.284769 -228.328747)
			(xy 99.300479 -228.379677) (xy 99.308422 -228.432381) (xy 99.30892 -228.45903) (xy 99.308422 -228.485679)
			(xy 99.537002 -228.485679) (xy 99.537002 -228.432381) (xy 99.544945 -228.379677) (xy 99.560655 -228.328747)
			(xy 99.583781 -228.280726) (xy 99.613805 -228.236689) (xy 99.650057 -228.197618) (xy 99.691728 -228.164387)
			(xy 99.737886 -228.137738) (xy 99.7875 -228.118266) (xy 99.839462 -228.106406) (xy 99.892612 -228.102423)
			(xy 99.945762 -228.106406) (xy 99.997724 -228.118266) (xy 100.047338 -228.137738) (xy 100.093496 -228.164387)
			(xy 100.135167 -228.197618) (xy 100.171419 -228.236689) (xy 100.201443 -228.280726) (xy 100.224569 -228.328747)
			(xy 100.240279 -228.379677) (xy 100.248222 -228.432381) (xy 100.24872 -228.45903) (xy 100.248222 -228.485679)
			(xy 100.476802 -228.485679) (xy 100.476802 -228.432381) (xy 100.484745 -228.379677) (xy 100.500455 -228.328747)
			(xy 100.523581 -228.280726) (xy 100.553605 -228.236689) (xy 100.589857 -228.197618) (xy 100.631528 -228.164387)
			(xy 100.677686 -228.137738) (xy 100.7273 -228.118266) (xy 100.779262 -228.106406) (xy 100.832412 -228.102423)
			(xy 100.885562 -228.106406) (xy 100.937524 -228.118266) (xy 100.987138 -228.137738) (xy 101.033296 -228.164387)
			(xy 101.074967 -228.197618) (xy 101.111219 -228.236689) (xy 101.141243 -228.280726) (xy 101.164369 -228.328747)
			(xy 101.180079 -228.379677) (xy 101.188022 -228.432381) (xy 101.18852 -228.45903) (xy 101.188022 -228.485679)
			(xy 101.416602 -228.485679) (xy 101.416602 -228.432381) (xy 101.424545 -228.379677) (xy 101.440255 -228.328747)
			(xy 101.463381 -228.280726) (xy 101.493405 -228.236689) (xy 101.529657 -228.197618) (xy 101.571328 -228.164387)
			(xy 101.617486 -228.137738) (xy 101.6671 -228.118266) (xy 101.719062 -228.106406) (xy 101.772212 -228.102423)
			(xy 101.825362 -228.106406) (xy 101.877324 -228.118266) (xy 101.926938 -228.137738) (xy 101.973096 -228.164387)
			(xy 102.014767 -228.197618) (xy 102.051019 -228.236689) (xy 102.081043 -228.280726) (xy 102.104169 -228.328747)
			(xy 102.119879 -228.379677) (xy 102.127822 -228.432381) (xy 102.12832 -228.45903) (xy 102.127822 -228.485679)
			(xy 102.356402 -228.485679) (xy 102.356402 -228.432381) (xy 102.364345 -228.379677) (xy 102.380055 -228.328747)
			(xy 102.403181 -228.280726) (xy 102.433205 -228.236689) (xy 102.469457 -228.197618) (xy 102.511128 -228.164387)
			(xy 102.557286 -228.137738) (xy 102.6069 -228.118266) (xy 102.658862 -228.106406) (xy 102.712012 -228.102423)
			(xy 102.765162 -228.106406) (xy 102.817124 -228.118266) (xy 102.866738 -228.137738) (xy 102.912896 -228.164387)
			(xy 102.954567 -228.197618) (xy 102.990819 -228.236689) (xy 103.020843 -228.280726) (xy 103.043969 -228.328747)
			(xy 103.059679 -228.379677) (xy 103.067622 -228.432381) (xy 103.06812 -228.45903) (xy 103.067622 -228.485679)
			(xy 103.296202 -228.485679) (xy 103.296202 -228.432381) (xy 103.304145 -228.379677) (xy 103.319855 -228.328747)
			(xy 103.342981 -228.280726) (xy 103.373005 -228.236689) (xy 103.409257 -228.197618) (xy 103.450928 -228.164387)
			(xy 103.497086 -228.137738) (xy 103.5467 -228.118266) (xy 103.598662 -228.106406) (xy 103.651812 -228.102423)
			(xy 103.704962 -228.106406) (xy 103.756924 -228.118266) (xy 103.806538 -228.137738) (xy 103.852696 -228.164387)
			(xy 103.894367 -228.197618) (xy 103.930619 -228.236689) (xy 103.960643 -228.280726) (xy 103.983769 -228.328747)
			(xy 103.999479 -228.379677) (xy 104.007422 -228.432381) (xy 104.00792 -228.45903) (xy 104.007422 -228.485679)
			(xy 104.236002 -228.485679) (xy 104.236002 -228.432381) (xy 104.243945 -228.379677) (xy 104.259655 -228.328747)
			(xy 104.282781 -228.280726) (xy 104.312805 -228.236689) (xy 104.349057 -228.197618) (xy 104.390728 -228.164387)
			(xy 104.436886 -228.137738) (xy 104.4865 -228.118266) (xy 104.538462 -228.106406) (xy 104.591612 -228.102423)
			(xy 104.644762 -228.106406) (xy 104.696724 -228.118266) (xy 104.746338 -228.137738) (xy 104.792496 -228.164387)
			(xy 104.834167 -228.197618) (xy 104.870419 -228.236689) (xy 104.900443 -228.280726) (xy 104.923569 -228.328747)
			(xy 104.939279 -228.379677) (xy 104.947222 -228.432381) (xy 104.94772 -228.45903) (xy 104.947222 -228.485679)
			(xy 105.175802 -228.485679) (xy 105.175802 -228.432381) (xy 105.183745 -228.379677) (xy 105.199455 -228.328747)
			(xy 105.222581 -228.280726) (xy 105.252605 -228.236689) (xy 105.288857 -228.197618) (xy 105.330528 -228.164387)
			(xy 105.376686 -228.137738) (xy 105.4263 -228.118266) (xy 105.478262 -228.106406) (xy 105.531412 -228.102423)
			(xy 105.584562 -228.106406) (xy 105.636524 -228.118266) (xy 105.686138 -228.137738) (xy 105.732296 -228.164387)
			(xy 105.773967 -228.197618) (xy 105.810219 -228.236689) (xy 105.840243 -228.280726) (xy 105.863369 -228.328747)
			(xy 105.879079 -228.379677) (xy 105.887022 -228.432381) (xy 105.88752 -228.45903) (xy 105.887022 -228.485679)
			(xy 106.115602 -228.485679) (xy 106.115602 -228.432381) (xy 106.123545 -228.379677) (xy 106.139255 -228.328747)
			(xy 106.162381 -228.280726) (xy 106.192405 -228.236689) (xy 106.228657 -228.197618) (xy 106.270328 -228.164387)
			(xy 106.316486 -228.137738) (xy 106.3661 -228.118266) (xy 106.418062 -228.106406) (xy 106.471212 -228.102423)
			(xy 106.524362 -228.106406) (xy 106.576324 -228.118266) (xy 106.625938 -228.137738) (xy 106.672096 -228.164387)
			(xy 106.713767 -228.197618) (xy 106.750019 -228.236689) (xy 106.780043 -228.280726) (xy 106.803169 -228.328747)
			(xy 106.818879 -228.379677) (xy 106.826822 -228.432381) (xy 106.82732 -228.45903) (xy 106.826822 -228.485679)
			(xy 107.055402 -228.485679) (xy 107.055402 -228.432381) (xy 107.063345 -228.379677) (xy 107.079055 -228.328747)
			(xy 107.102181 -228.280726) (xy 107.132205 -228.236689) (xy 107.168457 -228.197618) (xy 107.210128 -228.164387)
			(xy 107.256286 -228.137738) (xy 107.3059 -228.118266) (xy 107.357862 -228.106406) (xy 107.411012 -228.102423)
			(xy 107.464162 -228.106406) (xy 107.516124 -228.118266) (xy 107.565738 -228.137738) (xy 107.611896 -228.164387)
			(xy 107.653567 -228.197618) (xy 107.689819 -228.236689) (xy 107.719843 -228.280726) (xy 107.742969 -228.328747)
			(xy 107.758679 -228.379677) (xy 107.766622 -228.432381) (xy 107.76712 -228.45903) (xy 107.766622 -228.485679)
			(xy 107.995202 -228.485679) (xy 107.995202 -228.432381) (xy 108.003145 -228.379677) (xy 108.018855 -228.328747)
			(xy 108.041981 -228.280726) (xy 108.072005 -228.236689) (xy 108.108257 -228.197618) (xy 108.149928 -228.164387)
			(xy 108.196086 -228.137738) (xy 108.2457 -228.118266) (xy 108.297662 -228.106406) (xy 108.350812 -228.102423)
			(xy 108.403962 -228.106406) (xy 108.455924 -228.118266) (xy 108.505538 -228.137738) (xy 108.551696 -228.164387)
			(xy 108.593367 -228.197618) (xy 108.629619 -228.236689) (xy 108.659643 -228.280726) (xy 108.682769 -228.328747)
			(xy 108.698479 -228.379677) (xy 108.706422 -228.432381) (xy 108.70692 -228.45903) (xy 108.706422 -228.485679)
			(xy 108.935002 -228.485679) (xy 108.935002 -228.432381) (xy 108.942945 -228.379677) (xy 108.958655 -228.328747)
			(xy 108.981781 -228.280726) (xy 109.011805 -228.236689) (xy 109.048057 -228.197618) (xy 109.089728 -228.164387)
			(xy 109.135886 -228.137738) (xy 109.1855 -228.118266) (xy 109.237462 -228.106406) (xy 109.290612 -228.102423)
			(xy 109.343762 -228.106406) (xy 109.395724 -228.118266) (xy 109.445338 -228.137738) (xy 109.491496 -228.164387)
			(xy 109.533167 -228.197618) (xy 109.569419 -228.236689) (xy 109.599443 -228.280726) (xy 109.622569 -228.328747)
			(xy 109.638279 -228.379677) (xy 109.646222 -228.432381) (xy 109.64672 -228.45903) (xy 109.646222 -228.485679)
			(xy 109.874802 -228.485679) (xy 109.874802 -228.432381) (xy 109.882745 -228.379677) (xy 109.898455 -228.328747)
			(xy 109.921581 -228.280726) (xy 109.951605 -228.236689) (xy 109.987857 -228.197618) (xy 110.029528 -228.164387)
			(xy 110.075686 -228.137738) (xy 110.1253 -228.118266) (xy 110.177262 -228.106406) (xy 110.230412 -228.102423)
			(xy 110.283562 -228.106406) (xy 110.335524 -228.118266) (xy 110.385138 -228.137738) (xy 110.431296 -228.164387)
			(xy 110.472967 -228.197618) (xy 110.509219 -228.236689) (xy 110.539243 -228.280726) (xy 110.562369 -228.328747)
			(xy 110.578079 -228.379677) (xy 110.586022 -228.432381) (xy 110.58652 -228.45903) (xy 110.586022 -228.485679)
			(xy 110.814856 -228.485679) (xy 110.814856 -228.432381) (xy 110.822799 -228.379677) (xy 110.838509 -228.328747)
			(xy 110.861635 -228.280726) (xy 110.891659 -228.236689) (xy 110.927911 -228.197618) (xy 110.969582 -228.164387)
			(xy 111.01574 -228.137738) (xy 111.065354 -228.118266) (xy 111.117316 -228.106406) (xy 111.170466 -228.102423)
			(xy 111.223616 -228.106406) (xy 111.275578 -228.118266) (xy 111.325192 -228.137738) (xy 111.37135 -228.164387)
			(xy 111.413021 -228.197618) (xy 111.449273 -228.236689) (xy 111.479297 -228.280726) (xy 111.502423 -228.328747)
			(xy 111.518133 -228.379677) (xy 111.526076 -228.432381) (xy 111.526574 -228.45903) (xy 111.526076 -228.485679)
			(xy 111.754402 -228.485679) (xy 111.754402 -228.432381) (xy 111.762345 -228.379677) (xy 111.778055 -228.328747)
			(xy 111.801181 -228.280726) (xy 111.831205 -228.236689) (xy 111.867457 -228.197618) (xy 111.909128 -228.164387)
			(xy 111.955286 -228.137738) (xy 112.0049 -228.118266) (xy 112.056862 -228.106406) (xy 112.110012 -228.102423)
			(xy 112.163162 -228.106406) (xy 112.215124 -228.118266) (xy 112.264738 -228.137738) (xy 112.310896 -228.164387)
			(xy 112.352567 -228.197618) (xy 112.388819 -228.236689) (xy 112.418843 -228.280726) (xy 112.441969 -228.328747)
			(xy 112.457679 -228.379677) (xy 112.465622 -228.432381) (xy 112.46612 -228.45903) (xy 112.465622 -228.485679)
			(xy 112.694202 -228.485679) (xy 112.694202 -228.432381) (xy 112.702145 -228.379677) (xy 112.717855 -228.328747)
			(xy 112.740981 -228.280726) (xy 112.771005 -228.236689) (xy 112.807257 -228.197618) (xy 112.848928 -228.164387)
			(xy 112.895086 -228.137738) (xy 112.9447 -228.118266) (xy 112.996662 -228.106406) (xy 113.049812 -228.102423)
			(xy 113.102962 -228.106406) (xy 113.154924 -228.118266) (xy 113.204538 -228.137738) (xy 113.250696 -228.164387)
			(xy 113.292367 -228.197618) (xy 113.328619 -228.236689) (xy 113.358643 -228.280726) (xy 113.381769 -228.328747)
			(xy 113.397479 -228.379677) (xy 113.405422 -228.432381) (xy 113.40592 -228.45903) (xy 113.405422 -228.485679)
			(xy 113.634002 -228.485679) (xy 113.634002 -228.432381) (xy 113.641945 -228.379677) (xy 113.657655 -228.328747)
			(xy 113.680781 -228.280726) (xy 113.710805 -228.236689) (xy 113.747057 -228.197618) (xy 113.788728 -228.164387)
			(xy 113.834886 -228.137738) (xy 113.8845 -228.118266) (xy 113.936462 -228.106406) (xy 113.989612 -228.102423)
			(xy 114.042762 -228.106406) (xy 114.094724 -228.118266) (xy 114.144338 -228.137738) (xy 114.190496 -228.164387)
			(xy 114.232167 -228.197618) (xy 114.268419 -228.236689) (xy 114.298443 -228.280726) (xy 114.321569 -228.328747)
			(xy 114.337279 -228.379677) (xy 114.345222 -228.432381) (xy 114.34572 -228.45903) (xy 114.345222 -228.485679)
			(xy 115.513602 -228.485679) (xy 115.513602 -228.432381) (xy 115.521545 -228.379677) (xy 115.537255 -228.328747)
			(xy 115.560381 -228.280726) (xy 115.590405 -228.236689) (xy 115.626657 -228.197618) (xy 115.668328 -228.164387)
			(xy 115.714486 -228.137738) (xy 115.7641 -228.118266) (xy 115.816062 -228.106406) (xy 115.869212 -228.102423)
			(xy 115.922362 -228.106406) (xy 115.974324 -228.118266) (xy 116.023938 -228.137738) (xy 116.070096 -228.164387)
			(xy 116.111767 -228.197618) (xy 116.148019 -228.236689) (xy 116.178043 -228.280726) (xy 116.201169 -228.328747)
			(xy 116.216879 -228.379677) (xy 116.224822 -228.432381) (xy 116.22532 -228.45903) (xy 116.224822 -228.485679)
			(xy 117.393202 -228.485679) (xy 117.393202 -228.432381) (xy 117.401145 -228.379677) (xy 117.416855 -228.328747)
			(xy 117.439981 -228.280726) (xy 117.470005 -228.236689) (xy 117.506257 -228.197618) (xy 117.547928 -228.164387)
			(xy 117.594086 -228.137738) (xy 117.6437 -228.118266) (xy 117.695662 -228.106406) (xy 117.748812 -228.102423)
			(xy 117.801962 -228.106406) (xy 117.853924 -228.118266) (xy 117.903538 -228.137738) (xy 117.949696 -228.164387)
			(xy 117.991367 -228.197618) (xy 118.027619 -228.236689) (xy 118.057643 -228.280726) (xy 118.080769 -228.328747)
			(xy 118.096479 -228.379677) (xy 118.104422 -228.432381) (xy 118.10492 -228.45903) (xy 118.104422 -228.485679)
			(xy 119.272802 -228.485679) (xy 119.272802 -228.432381) (xy 119.280745 -228.379677) (xy 119.296455 -228.328747)
			(xy 119.319581 -228.280726) (xy 119.349605 -228.236689) (xy 119.385857 -228.197618) (xy 119.427528 -228.164387)
			(xy 119.473686 -228.137738) (xy 119.5233 -228.118266) (xy 119.575262 -228.106406) (xy 119.628412 -228.102423)
			(xy 119.681562 -228.106406) (xy 119.733524 -228.118266) (xy 119.783138 -228.137738) (xy 119.829296 -228.164387)
			(xy 119.870967 -228.197618) (xy 119.907219 -228.236689) (xy 119.937243 -228.280726) (xy 119.960369 -228.328747)
			(xy 119.976079 -228.379677) (xy 119.984022 -228.432381) (xy 119.98452 -228.45903) (xy 119.984022 -228.485679)
			(xy 120.212602 -228.485679) (xy 120.212602 -228.432381) (xy 120.220545 -228.379677) (xy 120.236255 -228.328747)
			(xy 120.259381 -228.280726) (xy 120.289405 -228.236689) (xy 120.325657 -228.197618) (xy 120.367328 -228.164387)
			(xy 120.413486 -228.137738) (xy 120.4631 -228.118266) (xy 120.515062 -228.106406) (xy 120.568212 -228.102423)
			(xy 120.621362 -228.106406) (xy 120.673324 -228.118266) (xy 120.722938 -228.137738) (xy 120.769096 -228.164387)
			(xy 120.810767 -228.197618) (xy 120.847019 -228.236689) (xy 120.877043 -228.280726) (xy 120.900169 -228.328747)
			(xy 120.915879 -228.379677) (xy 120.923822 -228.432381) (xy 120.92432 -228.45903) (xy 120.923822 -228.485679)
			(xy 121.152402 -228.485679) (xy 121.152402 -228.432381) (xy 121.160345 -228.379677) (xy 121.176055 -228.328747)
			(xy 121.199181 -228.280726) (xy 121.229205 -228.236689) (xy 121.265457 -228.197618) (xy 121.307128 -228.164387)
			(xy 121.353286 -228.137738) (xy 121.4029 -228.118266) (xy 121.454862 -228.106406) (xy 121.508012 -228.102423)
			(xy 121.561162 -228.106406) (xy 121.613124 -228.118266) (xy 121.662738 -228.137738) (xy 121.708896 -228.164387)
			(xy 121.750567 -228.197618) (xy 121.786819 -228.236689) (xy 121.816843 -228.280726) (xy 121.839969 -228.328747)
			(xy 121.855679 -228.379677) (xy 121.863622 -228.432381) (xy 121.86412 -228.45903) (xy 121.863622 -228.485679)
			(xy 122.092202 -228.485679) (xy 122.092202 -228.432381) (xy 122.100145 -228.379677) (xy 122.115855 -228.328747)
			(xy 122.138981 -228.280726) (xy 122.169005 -228.236689) (xy 122.205257 -228.197618) (xy 122.246928 -228.164387)
			(xy 122.293086 -228.137738) (xy 122.3427 -228.118266) (xy 122.394662 -228.106406) (xy 122.447812 -228.102423)
			(xy 122.500962 -228.106406) (xy 122.552924 -228.118266) (xy 122.602538 -228.137738) (xy 122.648696 -228.164387)
			(xy 122.690367 -228.197618) (xy 122.726619 -228.236689) (xy 122.756643 -228.280726) (xy 122.779769 -228.328747)
			(xy 122.795479 -228.379677) (xy 122.803422 -228.432381) (xy 122.80392 -228.45903) (xy 122.803422 -228.485679)
			(xy 123.032002 -228.485679) (xy 123.032002 -228.432381) (xy 123.039945 -228.379677) (xy 123.055655 -228.328747)
			(xy 123.078781 -228.280726) (xy 123.108805 -228.236689) (xy 123.145057 -228.197618) (xy 123.186728 -228.164387)
			(xy 123.232886 -228.137738) (xy 123.2825 -228.118266) (xy 123.334462 -228.106406) (xy 123.387612 -228.102423)
			(xy 123.440762 -228.106406) (xy 123.492724 -228.118266) (xy 123.542338 -228.137738) (xy 123.588496 -228.164387)
			(xy 123.630167 -228.197618) (xy 123.666419 -228.236689) (xy 123.696443 -228.280726) (xy 123.719569 -228.328747)
			(xy 123.735279 -228.379677) (xy 123.743222 -228.432381) (xy 123.74372 -228.45903) (xy 123.743222 -228.485679)
			(xy 123.971802 -228.485679) (xy 123.971802 -228.432381) (xy 123.979745 -228.379677) (xy 123.995455 -228.328747)
			(xy 124.018581 -228.280726) (xy 124.048605 -228.236689) (xy 124.084857 -228.197618) (xy 124.126528 -228.164387)
			(xy 124.172686 -228.137738) (xy 124.2223 -228.118266) (xy 124.274262 -228.106406) (xy 124.327412 -228.102423)
			(xy 124.380562 -228.106406) (xy 124.432524 -228.118266) (xy 124.482138 -228.137738) (xy 124.528296 -228.164387)
			(xy 124.569967 -228.197618) (xy 124.606219 -228.236689) (xy 124.636243 -228.280726) (xy 124.659369 -228.328747)
			(xy 124.675079 -228.379677) (xy 124.683022 -228.432381) (xy 124.68352 -228.45903) (xy 124.683022 -228.485679)
			(xy 124.911602 -228.485679) (xy 124.911602 -228.432381) (xy 124.919545 -228.379677) (xy 124.935255 -228.328747)
			(xy 124.958381 -228.280726) (xy 124.988405 -228.236689) (xy 125.024657 -228.197618) (xy 125.066328 -228.164387)
			(xy 125.112486 -228.137738) (xy 125.1621 -228.118266) (xy 125.214062 -228.106406) (xy 125.267212 -228.102423)
			(xy 125.320362 -228.106406) (xy 125.372324 -228.118266) (xy 125.421938 -228.137738) (xy 125.468096 -228.164387)
			(xy 125.509767 -228.197618) (xy 125.546019 -228.236689) (xy 125.576043 -228.280726) (xy 125.599169 -228.328747)
			(xy 125.614879 -228.379677) (xy 125.622822 -228.432381) (xy 125.62332 -228.45903) (xy 125.622822 -228.485679)
			(xy 125.851656 -228.485679) (xy 125.851656 -228.432381) (xy 125.859599 -228.379677) (xy 125.875309 -228.328747)
			(xy 125.898435 -228.280726) (xy 125.928459 -228.236689) (xy 125.964711 -228.197618) (xy 126.006382 -228.164387)
			(xy 126.05254 -228.137738) (xy 126.102154 -228.118266) (xy 126.154116 -228.106406) (xy 126.207266 -228.102423)
			(xy 126.260416 -228.106406) (xy 126.312378 -228.118266) (xy 126.361992 -228.137738) (xy 126.40815 -228.164387)
			(xy 126.449821 -228.197618) (xy 126.486073 -228.236689) (xy 126.516097 -228.280726) (xy 126.539223 -228.328747)
			(xy 126.554933 -228.379677) (xy 126.562876 -228.432381) (xy 126.563374 -228.45903) (xy 126.562876 -228.485679)
			(xy 126.791202 -228.485679) (xy 126.791202 -228.432381) (xy 126.799145 -228.379677) (xy 126.814855 -228.328747)
			(xy 126.837981 -228.280726) (xy 126.868005 -228.236689) (xy 126.904257 -228.197618) (xy 126.945928 -228.164387)
			(xy 126.992086 -228.137738) (xy 127.0417 -228.118266) (xy 127.093662 -228.106406) (xy 127.146812 -228.102423)
			(xy 127.199962 -228.106406) (xy 127.251924 -228.118266) (xy 127.301538 -228.137738) (xy 127.347696 -228.164387)
			(xy 127.389367 -228.197618) (xy 127.425619 -228.236689) (xy 127.455643 -228.280726) (xy 127.478769 -228.328747)
			(xy 127.494479 -228.379677) (xy 127.502422 -228.432381) (xy 127.50292 -228.45903) (xy 127.502422 -228.485679)
			(xy 127.731002 -228.485679) (xy 127.731002 -228.432381) (xy 127.738945 -228.379677) (xy 127.754655 -228.328747)
			(xy 127.777781 -228.280726) (xy 127.807805 -228.236689) (xy 127.844057 -228.197618) (xy 127.885728 -228.164387)
			(xy 127.931886 -228.137738) (xy 127.9815 -228.118266) (xy 128.033462 -228.106406) (xy 128.086612 -228.102423)
			(xy 128.139762 -228.106406) (xy 128.191724 -228.118266) (xy 128.241338 -228.137738) (xy 128.287496 -228.164387)
			(xy 128.329167 -228.197618) (xy 128.365419 -228.236689) (xy 128.395443 -228.280726) (xy 128.418569 -228.328747)
			(xy 128.434279 -228.379677) (xy 128.442222 -228.432381) (xy 128.44272 -228.45903) (xy 128.442222 -228.485679)
			(xy 128.670802 -228.485679) (xy 128.670802 -228.432381) (xy 128.678745 -228.379677) (xy 128.694455 -228.328747)
			(xy 128.717581 -228.280726) (xy 128.747605 -228.236689) (xy 128.783857 -228.197618) (xy 128.825528 -228.164387)
			(xy 128.871686 -228.137738) (xy 128.9213 -228.118266) (xy 128.973262 -228.106406) (xy 129.026412 -228.102423)
			(xy 129.079562 -228.106406) (xy 129.131524 -228.118266) (xy 129.181138 -228.137738) (xy 129.227296 -228.164387)
			(xy 129.268967 -228.197618) (xy 129.305219 -228.236689) (xy 129.335243 -228.280726) (xy 129.358369 -228.328747)
			(xy 129.374079 -228.379677) (xy 129.382022 -228.432381) (xy 129.38252 -228.45903) (xy 129.382022 -228.485679)
			(xy 129.610602 -228.485679) (xy 129.610602 -228.432381) (xy 129.618545 -228.379677) (xy 129.634255 -228.328747)
			(xy 129.657381 -228.280726) (xy 129.687405 -228.236689) (xy 129.723657 -228.197618) (xy 129.765328 -228.164387)
			(xy 129.811486 -228.137738) (xy 129.8611 -228.118266) (xy 129.913062 -228.106406) (xy 129.966212 -228.102423)
			(xy 130.019362 -228.106406) (xy 130.071324 -228.118266) (xy 130.120938 -228.137738) (xy 130.167096 -228.164387)
			(xy 130.208767 -228.197618) (xy 130.245019 -228.236689) (xy 130.275043 -228.280726) (xy 130.298169 -228.328747)
			(xy 130.313879 -228.379677) (xy 130.321822 -228.432381) (xy 130.32232 -228.45903) (xy 130.321822 -228.485679)
			(xy 130.550402 -228.485679) (xy 130.550402 -228.432381) (xy 130.558345 -228.379677) (xy 130.574055 -228.328747)
			(xy 130.597181 -228.280726) (xy 130.627205 -228.236689) (xy 130.663457 -228.197618) (xy 130.705128 -228.164387)
			(xy 130.751286 -228.137738) (xy 130.8009 -228.118266) (xy 130.852862 -228.106406) (xy 130.906012 -228.102423)
			(xy 130.959162 -228.106406) (xy 131.011124 -228.118266) (xy 131.060738 -228.137738) (xy 131.106896 -228.164387)
			(xy 131.148567 -228.197618) (xy 131.184819 -228.236689) (xy 131.214843 -228.280726) (xy 131.237969 -228.328747)
			(xy 131.253679 -228.379677) (xy 131.261622 -228.432381) (xy 131.26212 -228.45903) (xy 131.261622 -228.485679)
			(xy 131.490202 -228.485679) (xy 131.490202 -228.432381) (xy 131.498145 -228.379677) (xy 131.513855 -228.328747)
			(xy 131.536981 -228.280726) (xy 131.567005 -228.236689) (xy 131.603257 -228.197618) (xy 131.644928 -228.164387)
			(xy 131.691086 -228.137738) (xy 131.7407 -228.118266) (xy 131.792662 -228.106406) (xy 131.845812 -228.102423)
			(xy 131.898962 -228.106406) (xy 131.950924 -228.118266) (xy 132.000538 -228.137738) (xy 132.046696 -228.164387)
			(xy 132.088367 -228.197618) (xy 132.124619 -228.236689) (xy 132.154643 -228.280726) (xy 132.177769 -228.328747)
			(xy 132.193479 -228.379677) (xy 132.201422 -228.432381) (xy 132.20192 -228.45903) (xy 132.201422 -228.485679)
			(xy 132.430256 -228.485679) (xy 132.430256 -228.432381) (xy 132.438199 -228.379677) (xy 132.453909 -228.328747)
			(xy 132.477035 -228.280726) (xy 132.507059 -228.236689) (xy 132.543311 -228.197618) (xy 132.584982 -228.164387)
			(xy 132.63114 -228.137738) (xy 132.680754 -228.118266) (xy 132.732716 -228.106406) (xy 132.785866 -228.102423)
			(xy 132.839016 -228.106406) (xy 132.890978 -228.118266) (xy 132.940592 -228.137738) (xy 132.98675 -228.164387)
			(xy 133.028421 -228.197618) (xy 133.064673 -228.236689) (xy 133.094697 -228.280726) (xy 133.117823 -228.328747)
			(xy 133.133533 -228.379677) (xy 133.141476 -228.432381) (xy 133.141974 -228.45903) (xy 133.141476 -228.485679)
			(xy 133.370056 -228.485679) (xy 133.370056 -228.432381) (xy 133.377999 -228.379677) (xy 133.393709 -228.328747)
			(xy 133.416835 -228.280726) (xy 133.446859 -228.236689) (xy 133.483111 -228.197618) (xy 133.524782 -228.164387)
			(xy 133.57094 -228.137738) (xy 133.620554 -228.118266) (xy 133.672516 -228.106406) (xy 133.725666 -228.102423)
			(xy 133.778816 -228.106406) (xy 133.830778 -228.118266) (xy 133.880392 -228.137738) (xy 133.92655 -228.164387)
			(xy 133.968221 -228.197618) (xy 134.004473 -228.236689) (xy 134.034497 -228.280726) (xy 134.057623 -228.328747)
			(xy 134.073333 -228.379677) (xy 134.081276 -228.432381) (xy 134.081774 -228.45903) (xy 134.081276 -228.485679)
			(xy 134.309602 -228.485679) (xy 134.309602 -228.432381) (xy 134.317545 -228.379677) (xy 134.333255 -228.328747)
			(xy 134.356381 -228.280726) (xy 134.386405 -228.236689) (xy 134.422657 -228.197618) (xy 134.464328 -228.164387)
			(xy 134.510486 -228.137738) (xy 134.5601 -228.118266) (xy 134.612062 -228.106406) (xy 134.665212 -228.102423)
			(xy 134.718362 -228.106406) (xy 134.770324 -228.118266) (xy 134.819938 -228.137738) (xy 134.866096 -228.164387)
			(xy 134.907767 -228.197618) (xy 134.944019 -228.236689) (xy 134.974043 -228.280726) (xy 134.997169 -228.328747)
			(xy 135.012879 -228.379677) (xy 135.020822 -228.432381) (xy 135.02132 -228.45903) (xy 135.020822 -228.485679)
			(xy 135.012879 -228.538383) (xy 134.997169 -228.589313) (xy 134.974043 -228.637334) (xy 134.944019 -228.681371)
			(xy 134.907767 -228.720442) (xy 134.866096 -228.753673) (xy 134.819938 -228.780322) (xy 134.770324 -228.799794)
			(xy 134.718362 -228.811654) (xy 134.665212 -228.815638) (xy 134.612062 -228.811654) (xy 134.5601 -228.799794)
			(xy 134.510486 -228.780322) (xy 134.464328 -228.753673) (xy 134.422657 -228.720442) (xy 134.386405 -228.681371)
			(xy 134.356381 -228.637334) (xy 134.333255 -228.589313) (xy 134.317545 -228.538383) (xy 134.309602 -228.485679)
			(xy 134.081276 -228.485679) (xy 134.073333 -228.538383) (xy 134.057623 -228.589313) (xy 134.034497 -228.637334)
			(xy 134.004473 -228.681371) (xy 133.968221 -228.720442) (xy 133.92655 -228.753673) (xy 133.880392 -228.780322)
			(xy 133.830778 -228.799794) (xy 133.778816 -228.811654) (xy 133.725666 -228.815638) (xy 133.672516 -228.811654)
			(xy 133.620554 -228.799794) (xy 133.57094 -228.780322) (xy 133.524782 -228.753673) (xy 133.483111 -228.720442)
			(xy 133.446859 -228.681371) (xy 133.416835 -228.637334) (xy 133.393709 -228.589313) (xy 133.377999 -228.538383)
			(xy 133.370056 -228.485679) (xy 133.141476 -228.485679) (xy 133.133533 -228.538383) (xy 133.117823 -228.589313)
			(xy 133.094697 -228.637334) (xy 133.064673 -228.681371) (xy 133.028421 -228.720442) (xy 132.98675 -228.753673)
			(xy 132.940592 -228.780322) (xy 132.890978 -228.799794) (xy 132.839016 -228.811654) (xy 132.785866 -228.815638)
			(xy 132.732716 -228.811654) (xy 132.680754 -228.799794) (xy 132.63114 -228.780322) (xy 132.584982 -228.753673)
			(xy 132.543311 -228.720442) (xy 132.507059 -228.681371) (xy 132.477035 -228.637334) (xy 132.453909 -228.589313)
			(xy 132.438199 -228.538383) (xy 132.430256 -228.485679) (xy 132.201422 -228.485679) (xy 132.193479 -228.538383)
			(xy 132.177769 -228.589313) (xy 132.154643 -228.637334) (xy 132.124619 -228.681371) (xy 132.088367 -228.720442)
			(xy 132.046696 -228.753673) (xy 132.000538 -228.780322) (xy 131.950924 -228.799794) (xy 131.898962 -228.811654)
			(xy 131.845812 -228.815638) (xy 131.792662 -228.811654) (xy 131.7407 -228.799794) (xy 131.691086 -228.780322)
			(xy 131.644928 -228.753673) (xy 131.603257 -228.720442) (xy 131.567005 -228.681371) (xy 131.536981 -228.637334)
			(xy 131.513855 -228.589313) (xy 131.498145 -228.538383) (xy 131.490202 -228.485679) (xy 131.261622 -228.485679)
			(xy 131.253679 -228.538383) (xy 131.237969 -228.589313) (xy 131.214843 -228.637334) (xy 131.184819 -228.681371)
			(xy 131.148567 -228.720442) (xy 131.106896 -228.753673) (xy 131.060738 -228.780322) (xy 131.011124 -228.799794)
			(xy 130.959162 -228.811654) (xy 130.906012 -228.815638) (xy 130.852862 -228.811654) (xy 130.8009 -228.799794)
			(xy 130.751286 -228.780322) (xy 130.705128 -228.753673) (xy 130.663457 -228.720442) (xy 130.627205 -228.681371)
			(xy 130.597181 -228.637334) (xy 130.574055 -228.589313) (xy 130.558345 -228.538383) (xy 130.550402 -228.485679)
			(xy 130.321822 -228.485679) (xy 130.313879 -228.538383) (xy 130.298169 -228.589313) (xy 130.275043 -228.637334)
			(xy 130.245019 -228.681371) (xy 130.208767 -228.720442) (xy 130.167096 -228.753673) (xy 130.120938 -228.780322)
			(xy 130.071324 -228.799794) (xy 130.019362 -228.811654) (xy 129.966212 -228.815638) (xy 129.913062 -228.811654)
			(xy 129.8611 -228.799794) (xy 129.811486 -228.780322) (xy 129.765328 -228.753673) (xy 129.723657 -228.720442)
			(xy 129.687405 -228.681371) (xy 129.657381 -228.637334) (xy 129.634255 -228.589313) (xy 129.618545 -228.538383)
			(xy 129.610602 -228.485679) (xy 129.382022 -228.485679) (xy 129.374079 -228.538383) (xy 129.358369 -228.589313)
			(xy 129.335243 -228.637334) (xy 129.305219 -228.681371) (xy 129.268967 -228.720442) (xy 129.227296 -228.753673)
			(xy 129.181138 -228.780322) (xy 129.131524 -228.799794) (xy 129.079562 -228.811654) (xy 129.026412 -228.815638)
			(xy 128.973262 -228.811654) (xy 128.9213 -228.799794) (xy 128.871686 -228.780322) (xy 128.825528 -228.753673)
			(xy 128.783857 -228.720442) (xy 128.747605 -228.681371) (xy 128.717581 -228.637334) (xy 128.694455 -228.589313)
			(xy 128.678745 -228.538383) (xy 128.670802 -228.485679) (xy 128.442222 -228.485679) (xy 128.434279 -228.538383)
			(xy 128.418569 -228.589313) (xy 128.395443 -228.637334) (xy 128.365419 -228.681371) (xy 128.329167 -228.720442)
			(xy 128.287496 -228.753673) (xy 128.241338 -228.780322) (xy 128.191724 -228.799794) (xy 128.139762 -228.811654)
			(xy 128.086612 -228.815638) (xy 128.033462 -228.811654) (xy 127.9815 -228.799794) (xy 127.931886 -228.780322)
			(xy 127.885728 -228.753673) (xy 127.844057 -228.720442) (xy 127.807805 -228.681371) (xy 127.777781 -228.637334)
			(xy 127.754655 -228.589313) (xy 127.738945 -228.538383) (xy 127.731002 -228.485679) (xy 127.502422 -228.485679)
			(xy 127.494479 -228.538383) (xy 127.478769 -228.589313) (xy 127.455643 -228.637334) (xy 127.425619 -228.681371)
			(xy 127.389367 -228.720442) (xy 127.347696 -228.753673) (xy 127.301538 -228.780322) (xy 127.251924 -228.799794)
			(xy 127.199962 -228.811654) (xy 127.146812 -228.815638) (xy 127.093662 -228.811654) (xy 127.0417 -228.799794)
			(xy 126.992086 -228.780322) (xy 126.945928 -228.753673) (xy 126.904257 -228.720442) (xy 126.868005 -228.681371)
			(xy 126.837981 -228.637334) (xy 126.814855 -228.589313) (xy 126.799145 -228.538383) (xy 126.791202 -228.485679)
			(xy 126.562876 -228.485679) (xy 126.554933 -228.538383) (xy 126.539223 -228.589313) (xy 126.516097 -228.637334)
			(xy 126.486073 -228.681371) (xy 126.449821 -228.720442) (xy 126.40815 -228.753673) (xy 126.361992 -228.780322)
			(xy 126.312378 -228.799794) (xy 126.260416 -228.811654) (xy 126.207266 -228.815638) (xy 126.154116 -228.811654)
			(xy 126.102154 -228.799794) (xy 126.05254 -228.780322) (xy 126.006382 -228.753673) (xy 125.964711 -228.720442)
			(xy 125.928459 -228.681371) (xy 125.898435 -228.637334) (xy 125.875309 -228.589313) (xy 125.859599 -228.538383)
			(xy 125.851656 -228.485679) (xy 125.622822 -228.485679) (xy 125.614879 -228.538383) (xy 125.599169 -228.589313)
			(xy 125.576043 -228.637334) (xy 125.546019 -228.681371) (xy 125.509767 -228.720442) (xy 125.468096 -228.753673)
			(xy 125.421938 -228.780322) (xy 125.372324 -228.799794) (xy 125.320362 -228.811654) (xy 125.267212 -228.815638)
			(xy 125.214062 -228.811654) (xy 125.1621 -228.799794) (xy 125.112486 -228.780322) (xy 125.066328 -228.753673)
			(xy 125.024657 -228.720442) (xy 124.988405 -228.681371) (xy 124.958381 -228.637334) (xy 124.935255 -228.589313)
			(xy 124.919545 -228.538383) (xy 124.911602 -228.485679) (xy 124.683022 -228.485679) (xy 124.675079 -228.538383)
			(xy 124.659369 -228.589313) (xy 124.636243 -228.637334) (xy 124.606219 -228.681371) (xy 124.569967 -228.720442)
			(xy 124.528296 -228.753673) (xy 124.482138 -228.780322) (xy 124.432524 -228.799794) (xy 124.380562 -228.811654)
			(xy 124.327412 -228.815638) (xy 124.274262 -228.811654) (xy 124.2223 -228.799794) (xy 124.172686 -228.780322)
			(xy 124.126528 -228.753673) (xy 124.084857 -228.720442) (xy 124.048605 -228.681371) (xy 124.018581 -228.637334)
			(xy 123.995455 -228.589313) (xy 123.979745 -228.538383) (xy 123.971802 -228.485679) (xy 123.743222 -228.485679)
			(xy 123.735279 -228.538383) (xy 123.719569 -228.589313) (xy 123.696443 -228.637334) (xy 123.666419 -228.681371)
			(xy 123.630167 -228.720442) (xy 123.588496 -228.753673) (xy 123.542338 -228.780322) (xy 123.492724 -228.799794)
			(xy 123.440762 -228.811654) (xy 123.387612 -228.815638) (xy 123.334462 -228.811654) (xy 123.2825 -228.799794)
			(xy 123.232886 -228.780322) (xy 123.186728 -228.753673) (xy 123.145057 -228.720442) (xy 123.108805 -228.681371)
			(xy 123.078781 -228.637334) (xy 123.055655 -228.589313) (xy 123.039945 -228.538383) (xy 123.032002 -228.485679)
			(xy 122.803422 -228.485679) (xy 122.795479 -228.538383) (xy 122.779769 -228.589313) (xy 122.756643 -228.637334)
			(xy 122.726619 -228.681371) (xy 122.690367 -228.720442) (xy 122.648696 -228.753673) (xy 122.602538 -228.780322)
			(xy 122.552924 -228.799794) (xy 122.500962 -228.811654) (xy 122.447812 -228.815638) (xy 122.394662 -228.811654)
			(xy 122.3427 -228.799794) (xy 122.293086 -228.780322) (xy 122.246928 -228.753673) (xy 122.205257 -228.720442)
			(xy 122.169005 -228.681371) (xy 122.138981 -228.637334) (xy 122.115855 -228.589313) (xy 122.100145 -228.538383)
			(xy 122.092202 -228.485679) (xy 121.863622 -228.485679) (xy 121.855679 -228.538383) (xy 121.839969 -228.589313)
			(xy 121.816843 -228.637334) (xy 121.786819 -228.681371) (xy 121.750567 -228.720442) (xy 121.708896 -228.753673)
			(xy 121.662738 -228.780322) (xy 121.613124 -228.799794) (xy 121.561162 -228.811654) (xy 121.508012 -228.815638)
			(xy 121.454862 -228.811654) (xy 121.4029 -228.799794) (xy 121.353286 -228.780322) (xy 121.307128 -228.753673)
			(xy 121.265457 -228.720442) (xy 121.229205 -228.681371) (xy 121.199181 -228.637334) (xy 121.176055 -228.589313)
			(xy 121.160345 -228.538383) (xy 121.152402 -228.485679) (xy 120.923822 -228.485679) (xy 120.915879 -228.538383)
			(xy 120.900169 -228.589313) (xy 120.877043 -228.637334) (xy 120.847019 -228.681371) (xy 120.810767 -228.720442)
			(xy 120.769096 -228.753673) (xy 120.722938 -228.780322) (xy 120.673324 -228.799794) (xy 120.621362 -228.811654)
			(xy 120.568212 -228.815638) (xy 120.515062 -228.811654) (xy 120.4631 -228.799794) (xy 120.413486 -228.780322)
			(xy 120.367328 -228.753673) (xy 120.325657 -228.720442) (xy 120.289405 -228.681371) (xy 120.259381 -228.637334)
			(xy 120.236255 -228.589313) (xy 120.220545 -228.538383) (xy 120.212602 -228.485679) (xy 119.984022 -228.485679)
			(xy 119.976079 -228.538383) (xy 119.960369 -228.589313) (xy 119.937243 -228.637334) (xy 119.907219 -228.681371)
			(xy 119.870967 -228.720442) (xy 119.829296 -228.753673) (xy 119.783138 -228.780322) (xy 119.733524 -228.799794)
			(xy 119.681562 -228.811654) (xy 119.628412 -228.815638) (xy 119.575262 -228.811654) (xy 119.5233 -228.799794)
			(xy 119.473686 -228.780322) (xy 119.427528 -228.753673) (xy 119.385857 -228.720442) (xy 119.349605 -228.681371)
			(xy 119.319581 -228.637334) (xy 119.296455 -228.589313) (xy 119.280745 -228.538383) (xy 119.272802 -228.485679)
			(xy 118.104422 -228.485679) (xy 118.096479 -228.538383) (xy 118.080769 -228.589313) (xy 118.057643 -228.637334)
			(xy 118.027619 -228.681371) (xy 117.991367 -228.720442) (xy 117.949696 -228.753673) (xy 117.903538 -228.780322)
			(xy 117.853924 -228.799794) (xy 117.801962 -228.811654) (xy 117.748812 -228.815638) (xy 117.695662 -228.811654)
			(xy 117.6437 -228.799794) (xy 117.594086 -228.780322) (xy 117.547928 -228.753673) (xy 117.506257 -228.720442)
			(xy 117.470005 -228.681371) (xy 117.439981 -228.637334) (xy 117.416855 -228.589313) (xy 117.401145 -228.538383)
			(xy 117.393202 -228.485679) (xy 116.224822 -228.485679) (xy 116.216879 -228.538383) (xy 116.201169 -228.589313)
			(xy 116.178043 -228.637334) (xy 116.148019 -228.681371) (xy 116.111767 -228.720442) (xy 116.070096 -228.753673)
			(xy 116.023938 -228.780322) (xy 115.974324 -228.799794) (xy 115.922362 -228.811654) (xy 115.869212 -228.815638)
			(xy 115.816062 -228.811654) (xy 115.7641 -228.799794) (xy 115.714486 -228.780322) (xy 115.668328 -228.753673)
			(xy 115.626657 -228.720442) (xy 115.590405 -228.681371) (xy 115.560381 -228.637334) (xy 115.537255 -228.589313)
			(xy 115.521545 -228.538383) (xy 115.513602 -228.485679) (xy 114.345222 -228.485679) (xy 114.337279 -228.538383)
			(xy 114.321569 -228.589313) (xy 114.298443 -228.637334) (xy 114.268419 -228.681371) (xy 114.232167 -228.720442)
			(xy 114.190496 -228.753673) (xy 114.144338 -228.780322) (xy 114.094724 -228.799794) (xy 114.042762 -228.811654)
			(xy 113.989612 -228.815638) (xy 113.936462 -228.811654) (xy 113.8845 -228.799794) (xy 113.834886 -228.780322)
			(xy 113.788728 -228.753673) (xy 113.747057 -228.720442) (xy 113.710805 -228.681371) (xy 113.680781 -228.637334)
			(xy 113.657655 -228.589313) (xy 113.641945 -228.538383) (xy 113.634002 -228.485679) (xy 113.405422 -228.485679)
			(xy 113.397479 -228.538383) (xy 113.381769 -228.589313) (xy 113.358643 -228.637334) (xy 113.328619 -228.681371)
			(xy 113.292367 -228.720442) (xy 113.250696 -228.753673) (xy 113.204538 -228.780322) (xy 113.154924 -228.799794)
			(xy 113.102962 -228.811654) (xy 113.049812 -228.815638) (xy 112.996662 -228.811654) (xy 112.9447 -228.799794)
			(xy 112.895086 -228.780322) (xy 112.848928 -228.753673) (xy 112.807257 -228.720442) (xy 112.771005 -228.681371)
			(xy 112.740981 -228.637334) (xy 112.717855 -228.589313) (xy 112.702145 -228.538383) (xy 112.694202 -228.485679)
			(xy 112.465622 -228.485679) (xy 112.457679 -228.538383) (xy 112.441969 -228.589313) (xy 112.418843 -228.637334)
			(xy 112.388819 -228.681371) (xy 112.352567 -228.720442) (xy 112.310896 -228.753673) (xy 112.264738 -228.780322)
			(xy 112.215124 -228.799794) (xy 112.163162 -228.811654) (xy 112.110012 -228.815638) (xy 112.056862 -228.811654)
			(xy 112.0049 -228.799794) (xy 111.955286 -228.780322) (xy 111.909128 -228.753673) (xy 111.867457 -228.720442)
			(xy 111.831205 -228.681371) (xy 111.801181 -228.637334) (xy 111.778055 -228.589313) (xy 111.762345 -228.538383)
			(xy 111.754402 -228.485679) (xy 111.526076 -228.485679) (xy 111.518133 -228.538383) (xy 111.502423 -228.589313)
			(xy 111.479297 -228.637334) (xy 111.449273 -228.681371) (xy 111.413021 -228.720442) (xy 111.37135 -228.753673)
			(xy 111.325192 -228.780322) (xy 111.275578 -228.799794) (xy 111.223616 -228.811654) (xy 111.170466 -228.815638)
			(xy 111.117316 -228.811654) (xy 111.065354 -228.799794) (xy 111.01574 -228.780322) (xy 110.969582 -228.753673)
			(xy 110.927911 -228.720442) (xy 110.891659 -228.681371) (xy 110.861635 -228.637334) (xy 110.838509 -228.589313)
			(xy 110.822799 -228.538383) (xy 110.814856 -228.485679) (xy 110.586022 -228.485679) (xy 110.578079 -228.538383)
			(xy 110.562369 -228.589313) (xy 110.539243 -228.637334) (xy 110.509219 -228.681371) (xy 110.472967 -228.720442)
			(xy 110.431296 -228.753673) (xy 110.385138 -228.780322) (xy 110.335524 -228.799794) (xy 110.283562 -228.811654)
			(xy 110.230412 -228.815638) (xy 110.177262 -228.811654) (xy 110.1253 -228.799794) (xy 110.075686 -228.780322)
			(xy 110.029528 -228.753673) (xy 109.987857 -228.720442) (xy 109.951605 -228.681371) (xy 109.921581 -228.637334)
			(xy 109.898455 -228.589313) (xy 109.882745 -228.538383) (xy 109.874802 -228.485679) (xy 109.646222 -228.485679)
			(xy 109.638279 -228.538383) (xy 109.622569 -228.589313) (xy 109.599443 -228.637334) (xy 109.569419 -228.681371)
			(xy 109.533167 -228.720442) (xy 109.491496 -228.753673) (xy 109.445338 -228.780322) (xy 109.395724 -228.799794)
			(xy 109.343762 -228.811654) (xy 109.290612 -228.815638) (xy 109.237462 -228.811654) (xy 109.1855 -228.799794)
			(xy 109.135886 -228.780322) (xy 109.089728 -228.753673) (xy 109.048057 -228.720442) (xy 109.011805 -228.681371)
			(xy 108.981781 -228.637334) (xy 108.958655 -228.589313) (xy 108.942945 -228.538383) (xy 108.935002 -228.485679)
			(xy 108.706422 -228.485679) (xy 108.698479 -228.538383) (xy 108.682769 -228.589313) (xy 108.659643 -228.637334)
			(xy 108.629619 -228.681371) (xy 108.593367 -228.720442) (xy 108.551696 -228.753673) (xy 108.505538 -228.780322)
			(xy 108.455924 -228.799794) (xy 108.403962 -228.811654) (xy 108.350812 -228.815638) (xy 108.297662 -228.811654)
			(xy 108.2457 -228.799794) (xy 108.196086 -228.780322) (xy 108.149928 -228.753673) (xy 108.108257 -228.720442)
			(xy 108.072005 -228.681371) (xy 108.041981 -228.637334) (xy 108.018855 -228.589313) (xy 108.003145 -228.538383)
			(xy 107.995202 -228.485679) (xy 107.766622 -228.485679) (xy 107.758679 -228.538383) (xy 107.742969 -228.589313)
			(xy 107.719843 -228.637334) (xy 107.689819 -228.681371) (xy 107.653567 -228.720442) (xy 107.611896 -228.753673)
			(xy 107.565738 -228.780322) (xy 107.516124 -228.799794) (xy 107.464162 -228.811654) (xy 107.411012 -228.815638)
			(xy 107.357862 -228.811654) (xy 107.3059 -228.799794) (xy 107.256286 -228.780322) (xy 107.210128 -228.753673)
			(xy 107.168457 -228.720442) (xy 107.132205 -228.681371) (xy 107.102181 -228.637334) (xy 107.079055 -228.589313)
			(xy 107.063345 -228.538383) (xy 107.055402 -228.485679) (xy 106.826822 -228.485679) (xy 106.818879 -228.538383)
			(xy 106.803169 -228.589313) (xy 106.780043 -228.637334) (xy 106.750019 -228.681371) (xy 106.713767 -228.720442)
			(xy 106.672096 -228.753673) (xy 106.625938 -228.780322) (xy 106.576324 -228.799794) (xy 106.524362 -228.811654)
			(xy 106.471212 -228.815638) (xy 106.418062 -228.811654) (xy 106.3661 -228.799794) (xy 106.316486 -228.780322)
			(xy 106.270328 -228.753673) (xy 106.228657 -228.720442) (xy 106.192405 -228.681371) (xy 106.162381 -228.637334)
			(xy 106.139255 -228.589313) (xy 106.123545 -228.538383) (xy 106.115602 -228.485679) (xy 105.887022 -228.485679)
			(xy 105.879079 -228.538383) (xy 105.863369 -228.589313) (xy 105.840243 -228.637334) (xy 105.810219 -228.681371)
			(xy 105.773967 -228.720442) (xy 105.732296 -228.753673) (xy 105.686138 -228.780322) (xy 105.636524 -228.799794)
			(xy 105.584562 -228.811654) (xy 105.531412 -228.815638) (xy 105.478262 -228.811654) (xy 105.4263 -228.799794)
			(xy 105.376686 -228.780322) (xy 105.330528 -228.753673) (xy 105.288857 -228.720442) (xy 105.252605 -228.681371)
			(xy 105.222581 -228.637334) (xy 105.199455 -228.589313) (xy 105.183745 -228.538383) (xy 105.175802 -228.485679)
			(xy 104.947222 -228.485679) (xy 104.939279 -228.538383) (xy 104.923569 -228.589313) (xy 104.900443 -228.637334)
			(xy 104.870419 -228.681371) (xy 104.834167 -228.720442) (xy 104.792496 -228.753673) (xy 104.746338 -228.780322)
			(xy 104.696724 -228.799794) (xy 104.644762 -228.811654) (xy 104.591612 -228.815638) (xy 104.538462 -228.811654)
			(xy 104.4865 -228.799794) (xy 104.436886 -228.780322) (xy 104.390728 -228.753673) (xy 104.349057 -228.720442)
			(xy 104.312805 -228.681371) (xy 104.282781 -228.637334) (xy 104.259655 -228.589313) (xy 104.243945 -228.538383)
			(xy 104.236002 -228.485679) (xy 104.007422 -228.485679) (xy 103.999479 -228.538383) (xy 103.983769 -228.589313)
			(xy 103.960643 -228.637334) (xy 103.930619 -228.681371) (xy 103.894367 -228.720442) (xy 103.852696 -228.753673)
			(xy 103.806538 -228.780322) (xy 103.756924 -228.799794) (xy 103.704962 -228.811654) (xy 103.651812 -228.815638)
			(xy 103.598662 -228.811654) (xy 103.5467 -228.799794) (xy 103.497086 -228.780322) (xy 103.450928 -228.753673)
			(xy 103.409257 -228.720442) (xy 103.373005 -228.681371) (xy 103.342981 -228.637334) (xy 103.319855 -228.589313)
			(xy 103.304145 -228.538383) (xy 103.296202 -228.485679) (xy 103.067622 -228.485679) (xy 103.059679 -228.538383)
			(xy 103.043969 -228.589313) (xy 103.020843 -228.637334) (xy 102.990819 -228.681371) (xy 102.954567 -228.720442)
			(xy 102.912896 -228.753673) (xy 102.866738 -228.780322) (xy 102.817124 -228.799794) (xy 102.765162 -228.811654)
			(xy 102.712012 -228.815638) (xy 102.658862 -228.811654) (xy 102.6069 -228.799794) (xy 102.557286 -228.780322)
			(xy 102.511128 -228.753673) (xy 102.469457 -228.720442) (xy 102.433205 -228.681371) (xy 102.403181 -228.637334)
			(xy 102.380055 -228.589313) (xy 102.364345 -228.538383) (xy 102.356402 -228.485679) (xy 102.127822 -228.485679)
			(xy 102.119879 -228.538383) (xy 102.104169 -228.589313) (xy 102.081043 -228.637334) (xy 102.051019 -228.681371)
			(xy 102.014767 -228.720442) (xy 101.973096 -228.753673) (xy 101.926938 -228.780322) (xy 101.877324 -228.799794)
			(xy 101.825362 -228.811654) (xy 101.772212 -228.815638) (xy 101.719062 -228.811654) (xy 101.6671 -228.799794)
			(xy 101.617486 -228.780322) (xy 101.571328 -228.753673) (xy 101.529657 -228.720442) (xy 101.493405 -228.681371)
			(xy 101.463381 -228.637334) (xy 101.440255 -228.589313) (xy 101.424545 -228.538383) (xy 101.416602 -228.485679)
			(xy 101.188022 -228.485679) (xy 101.180079 -228.538383) (xy 101.164369 -228.589313) (xy 101.141243 -228.637334)
			(xy 101.111219 -228.681371) (xy 101.074967 -228.720442) (xy 101.033296 -228.753673) (xy 100.987138 -228.780322)
			(xy 100.937524 -228.799794) (xy 100.885562 -228.811654) (xy 100.832412 -228.815638) (xy 100.779262 -228.811654)
			(xy 100.7273 -228.799794) (xy 100.677686 -228.780322) (xy 100.631528 -228.753673) (xy 100.589857 -228.720442)
			(xy 100.553605 -228.681371) (xy 100.523581 -228.637334) (xy 100.500455 -228.589313) (xy 100.484745 -228.538383)
			(xy 100.476802 -228.485679) (xy 100.248222 -228.485679) (xy 100.240279 -228.538383) (xy 100.224569 -228.589313)
			(xy 100.201443 -228.637334) (xy 100.171419 -228.681371) (xy 100.135167 -228.720442) (xy 100.093496 -228.753673)
			(xy 100.047338 -228.780322) (xy 99.997724 -228.799794) (xy 99.945762 -228.811654) (xy 99.892612 -228.815638)
			(xy 99.839462 -228.811654) (xy 99.7875 -228.799794) (xy 99.737886 -228.780322) (xy 99.691728 -228.753673)
			(xy 99.650057 -228.720442) (xy 99.613805 -228.681371) (xy 99.583781 -228.637334) (xy 99.560655 -228.589313)
			(xy 99.544945 -228.538383) (xy 99.537002 -228.485679) (xy 99.308422 -228.485679) (xy 99.300479 -228.538383)
			(xy 99.284769 -228.589313) (xy 99.261643 -228.637334) (xy 99.231619 -228.681371) (xy 99.195367 -228.720442)
			(xy 99.153696 -228.753673) (xy 99.107538 -228.780322) (xy 99.057924 -228.799794) (xy 99.005962 -228.811654)
			(xy 98.952812 -228.815638) (xy 98.899662 -228.811654) (xy 98.8477 -228.799794) (xy 98.798086 -228.780322)
			(xy 98.751928 -228.753673) (xy 98.710257 -228.720442) (xy 98.674005 -228.681371) (xy 98.643981 -228.637334)
			(xy 98.620855 -228.589313) (xy 98.605145 -228.538383) (xy 98.597202 -228.485679) (xy 98.368876 -228.485679)
			(xy 98.360933 -228.538383) (xy 98.345223 -228.589313) (xy 98.322097 -228.637334) (xy 98.292073 -228.681371)
			(xy 98.255821 -228.720442) (xy 98.21415 -228.753673) (xy 98.167992 -228.780322) (xy 98.118378 -228.799794)
			(xy 98.066416 -228.811654) (xy 98.013266 -228.815638) (xy 97.960116 -228.811654) (xy 97.908154 -228.799794)
			(xy 97.85854 -228.780322) (xy 97.812382 -228.753673) (xy 97.770711 -228.720442) (xy 97.734459 -228.681371)
			(xy 97.704435 -228.637334) (xy 97.681309 -228.589313) (xy 97.665599 -228.538383) (xy 97.657656 -228.485679)
			(xy 97.428822 -228.485679) (xy 97.420879 -228.538383) (xy 97.405169 -228.589313) (xy 97.382043 -228.637334)
			(xy 97.352019 -228.681371) (xy 97.315767 -228.720442) (xy 97.274096 -228.753673) (xy 97.227938 -228.780322)
			(xy 97.178324 -228.799794) (xy 97.126362 -228.811654) (xy 97.073212 -228.815638) (xy 97.020062 -228.811654)
			(xy 96.9681 -228.799794) (xy 96.918486 -228.780322) (xy 96.872328 -228.753673) (xy 96.830657 -228.720442)
			(xy 96.794405 -228.681371) (xy 96.764381 -228.637334) (xy 96.741255 -228.589313) (xy 96.725545 -228.538383)
			(xy 96.717602 -228.485679) (xy 96.489022 -228.485679) (xy 96.481079 -228.538383) (xy 96.465369 -228.589313)
			(xy 96.442243 -228.637334) (xy 96.412219 -228.681371) (xy 96.375967 -228.720442) (xy 96.334296 -228.753673)
			(xy 96.288138 -228.780322) (xy 96.238524 -228.799794) (xy 96.186562 -228.811654) (xy 96.133412 -228.815638)
			(xy 96.080262 -228.811654) (xy 96.0283 -228.799794) (xy 95.978686 -228.780322) (xy 95.932528 -228.753673)
			(xy 95.890857 -228.720442) (xy 95.854605 -228.681371) (xy 95.824581 -228.637334) (xy 95.801455 -228.589313)
			(xy 95.785745 -228.538383) (xy 95.777802 -228.485679) (xy 95.549222 -228.485679) (xy 95.541279 -228.538383)
			(xy 95.525569 -228.589313) (xy 95.502443 -228.637334) (xy 95.472419 -228.681371) (xy 95.436167 -228.720442)
			(xy 95.394496 -228.753673) (xy 95.348338 -228.780322) (xy 95.298724 -228.799794) (xy 95.246762 -228.811654)
			(xy 95.193612 -228.815638) (xy 95.140462 -228.811654) (xy 95.0885 -228.799794) (xy 95.038886 -228.780322)
			(xy 94.992728 -228.753673) (xy 94.951057 -228.720442) (xy 94.914805 -228.681371) (xy 94.884781 -228.637334)
			(xy 94.861655 -228.589313) (xy 94.845945 -228.538383) (xy 94.838002 -228.485679) (xy 94.609422 -228.485679)
			(xy 94.601479 -228.538383) (xy 94.585769 -228.589313) (xy 94.562643 -228.637334) (xy 94.532619 -228.681371)
			(xy 94.496367 -228.720442) (xy 94.454696 -228.753673) (xy 94.408538 -228.780322) (xy 94.358924 -228.799794)
			(xy 94.306962 -228.811654) (xy 94.253812 -228.815638) (xy 94.200662 -228.811654) (xy 94.1487 -228.799794)
			(xy 94.099086 -228.780322) (xy 94.052928 -228.753673) (xy 94.011257 -228.720442) (xy 93.975005 -228.681371)
			(xy 93.944981 -228.637334) (xy 93.921855 -228.589313) (xy 93.906145 -228.538383) (xy 93.898202 -228.485679)
			(xy 93.669622 -228.485679) (xy 93.661679 -228.538383) (xy 93.645969 -228.589313) (xy 93.622843 -228.637334)
			(xy 93.592819 -228.681371) (xy 93.556567 -228.720442) (xy 93.514896 -228.753673) (xy 93.468738 -228.780322)
			(xy 93.419124 -228.799794) (xy 93.367162 -228.811654) (xy 93.314012 -228.815638) (xy 93.260862 -228.811654)
			(xy 93.2089 -228.799794) (xy 93.159286 -228.780322) (xy 93.113128 -228.753673) (xy 93.071457 -228.720442)
			(xy 93.035205 -228.681371) (xy 93.005181 -228.637334) (xy 92.982055 -228.589313) (xy 92.966345 -228.538383)
			(xy 92.958402 -228.485679) (xy 92.729822 -228.485679) (xy 92.721879 -228.538383) (xy 92.706169 -228.589313)
			(xy 92.683043 -228.637334) (xy 92.653019 -228.681371) (xy 92.616767 -228.720442) (xy 92.575096 -228.753673)
			(xy 92.528938 -228.780322) (xy 92.479324 -228.799794) (xy 92.427362 -228.811654) (xy 92.374212 -228.815638)
			(xy 92.321062 -228.811654) (xy 92.2691 -228.799794) (xy 92.219486 -228.780322) (xy 92.173328 -228.753673)
			(xy 92.131657 -228.720442) (xy 92.095405 -228.681371) (xy 92.065381 -228.637334) (xy 92.042255 -228.589313)
			(xy 92.026545 -228.538383) (xy 92.018602 -228.485679) (xy 91.790276 -228.485679) (xy 91.782333 -228.538383)
			(xy 91.766623 -228.589313) (xy 91.743497 -228.637334) (xy 91.713473 -228.681371) (xy 91.677221 -228.720442)
			(xy 91.63555 -228.753673) (xy 91.589392 -228.780322) (xy 91.539778 -228.799794) (xy 91.487816 -228.811654)
			(xy 91.434666 -228.815638) (xy 91.381516 -228.811654) (xy 91.329554 -228.799794) (xy 91.27994 -228.780322)
			(xy 91.233782 -228.753673) (xy 91.192111 -228.720442) (xy 91.155859 -228.681371) (xy 91.125835 -228.637334)
			(xy 91.102709 -228.589313) (xy 91.086999 -228.538383) (xy 91.079056 -228.485679) (xy 90.850222 -228.485679)
			(xy 90.842279 -228.538383) (xy 90.826569 -228.589313) (xy 90.803443 -228.637334) (xy 90.773419 -228.681371)
			(xy 90.737167 -228.720442) (xy 90.695496 -228.753673) (xy 90.649338 -228.780322) (xy 90.599724 -228.799794)
			(xy 90.547762 -228.811654) (xy 90.494612 -228.815638) (xy 90.441462 -228.811654) (xy 90.3895 -228.799794)
			(xy 90.339886 -228.780322) (xy 90.293728 -228.753673) (xy 90.252057 -228.720442) (xy 90.215805 -228.681371)
			(xy 90.185781 -228.637334) (xy 90.162655 -228.589313) (xy 90.146945 -228.538383) (xy 90.139002 -228.485679)
			(xy 89.910422 -228.485679) (xy 89.902479 -228.538383) (xy 89.886769 -228.589313) (xy 89.863643 -228.637334)
			(xy 89.833619 -228.681371) (xy 89.797367 -228.720442) (xy 89.755696 -228.753673) (xy 89.709538 -228.780322)
			(xy 89.659924 -228.799794) (xy 89.607962 -228.811654) (xy 89.554812 -228.815638) (xy 89.501662 -228.811654)
			(xy 89.4497 -228.799794) (xy 89.400086 -228.780322) (xy 89.353928 -228.753673) (xy 89.312257 -228.720442)
			(xy 89.276005 -228.681371) (xy 89.245981 -228.637334) (xy 89.222855 -228.589313) (xy 89.207145 -228.538383)
			(xy 89.199202 -228.485679) (xy 88.969583 -228.485679) (xy 88.96765 -228.511693) (xy 88.955993 -228.563219)
			(xy 88.936852 -228.612458) (xy 88.910645 -228.658329) (xy 88.877949 -228.699824) (xy 88.839481 -228.736032)
			(xy 88.796084 -228.766159) (xy 88.748713 -228.789544) (xy 88.723724 -228.79812) (xy 88.688418 -228.80955)
			(xy 88.688418 -228.923088) (xy 88.68891 -228.937547) (xy 88.696994 -228.965312) (xy 88.712546 -228.989692)
			(xy 88.734314 -229.008728) (xy 88.760549 -229.02089) (xy 88.789143 -229.025201) (xy 88.817798 -229.021315)
			(xy 88.844211 -229.009543) (xy 88.85555 -229.000558) (xy 88.874909 -228.984795) (xy 88.917205 -228.958272)
			(xy 88.962789 -228.937915) (xy 89.010769 -228.92412) (xy 89.060204 -228.91716) (xy 89.085166 -228.916738)
			(xy 89.111815 -228.917209) (xy 89.164519 -228.925148) (xy 89.215451 -228.940854) (xy 89.263473 -228.963976)
			(xy 89.307513 -228.993998) (xy 89.346585 -229.030248) (xy 89.379818 -229.071917) (xy 89.406469 -229.118074)
			(xy 89.425942 -229.167688) (xy 89.437803 -229.21965) (xy 89.441786 -229.2728) (xy 89.439786 -229.299495)
			(xy 89.669356 -229.299495) (xy 89.669356 -229.246197) (xy 89.677299 -229.193493) (xy 89.693009 -229.142563)
			(xy 89.716135 -229.094542) (xy 89.746159 -229.050505) (xy 89.782411 -229.011434) (xy 89.824082 -228.978203)
			(xy 89.87024 -228.951554) (xy 89.919854 -228.932082) (xy 89.971816 -228.920222) (xy 90.024966 -228.916239)
			(xy 90.078116 -228.920222) (xy 90.130078 -228.932082) (xy 90.179692 -228.951554) (xy 90.22585 -228.978203)
			(xy 90.267521 -229.011434) (xy 90.303773 -229.050505) (xy 90.333797 -229.094542) (xy 90.356923 -229.142563)
			(xy 90.372633 -229.193493) (xy 90.380576 -229.246197) (xy 90.381074 -229.272846) (xy 90.380576 -229.299495)
			(xy 90.609156 -229.299495) (xy 90.609156 -229.246197) (xy 90.617099 -229.193493) (xy 90.632809 -229.142563)
			(xy 90.655935 -229.094542) (xy 90.685959 -229.050505) (xy 90.722211 -229.011434) (xy 90.763882 -228.978203)
			(xy 90.81004 -228.951554) (xy 90.859654 -228.932082) (xy 90.911616 -228.920222) (xy 90.964766 -228.916239)
			(xy 91.017916 -228.920222) (xy 91.069878 -228.932082) (xy 91.119492 -228.951554) (xy 91.16565 -228.978203)
			(xy 91.207321 -229.011434) (xy 91.243573 -229.050505) (xy 91.273597 -229.094542) (xy 91.296723 -229.142563)
			(xy 91.312433 -229.193493) (xy 91.320376 -229.246197) (xy 91.320874 -229.272846) (xy 91.320376 -229.299495)
			(xy 91.548956 -229.299495) (xy 91.548956 -229.246197) (xy 91.556899 -229.193493) (xy 91.572609 -229.142563)
			(xy 91.595735 -229.094542) (xy 91.625759 -229.050505) (xy 91.662011 -229.011434) (xy 91.703682 -228.978203)
			(xy 91.74984 -228.951554) (xy 91.799454 -228.932082) (xy 91.851416 -228.920222) (xy 91.904566 -228.916239)
			(xy 91.957716 -228.920222) (xy 92.009678 -228.932082) (xy 92.059292 -228.951554) (xy 92.10545 -228.978203)
			(xy 92.147121 -229.011434) (xy 92.183373 -229.050505) (xy 92.213397 -229.094542) (xy 92.236523 -229.142563)
			(xy 92.252233 -229.193493) (xy 92.260176 -229.246197) (xy 92.260674 -229.272846) (xy 92.260176 -229.299495)
			(xy 92.488756 -229.299495) (xy 92.488756 -229.246197) (xy 92.496699 -229.193493) (xy 92.512409 -229.142563)
			(xy 92.535535 -229.094542) (xy 92.565559 -229.050505) (xy 92.601811 -229.011434) (xy 92.643482 -228.978203)
			(xy 92.68964 -228.951554) (xy 92.739254 -228.932082) (xy 92.791216 -228.920222) (xy 92.844366 -228.916239)
			(xy 92.897516 -228.920222) (xy 92.949478 -228.932082) (xy 92.999092 -228.951554) (xy 93.04525 -228.978203)
			(xy 93.086921 -229.011434) (xy 93.123173 -229.050505) (xy 93.153197 -229.094542) (xy 93.176323 -229.142563)
			(xy 93.192033 -229.193493) (xy 93.199976 -229.246197) (xy 93.200474 -229.272846) (xy 93.199976 -229.299495)
			(xy 93.428556 -229.299495) (xy 93.428556 -229.246197) (xy 93.436499 -229.193493) (xy 93.452209 -229.142563)
			(xy 93.475335 -229.094542) (xy 93.505359 -229.050505) (xy 93.541611 -229.011434) (xy 93.583282 -228.978203)
			(xy 93.62944 -228.951554) (xy 93.679054 -228.932082) (xy 93.731016 -228.920222) (xy 93.784166 -228.916239)
			(xy 93.837316 -228.920222) (xy 93.889278 -228.932082) (xy 93.938892 -228.951554) (xy 93.98505 -228.978203)
			(xy 94.026721 -229.011434) (xy 94.062973 -229.050505) (xy 94.092997 -229.094542) (xy 94.116123 -229.142563)
			(xy 94.131833 -229.193493) (xy 94.139776 -229.246197) (xy 94.140274 -229.272846) (xy 94.139776 -229.299495)
			(xy 94.368102 -229.299495) (xy 94.368102 -229.246197) (xy 94.376045 -229.193493) (xy 94.391755 -229.142563)
			(xy 94.414881 -229.094542) (xy 94.444905 -229.050505) (xy 94.481157 -229.011434) (xy 94.522828 -228.978203)
			(xy 94.568986 -228.951554) (xy 94.6186 -228.932082) (xy 94.670562 -228.920222) (xy 94.723712 -228.916239)
			(xy 94.776862 -228.920222) (xy 94.828824 -228.932082) (xy 94.878438 -228.951554) (xy 94.924596 -228.978203)
			(xy 94.966267 -229.011434) (xy 95.002519 -229.050505) (xy 95.032543 -229.094542) (xy 95.055669 -229.142563)
			(xy 95.071379 -229.193493) (xy 95.079322 -229.246197) (xy 95.07982 -229.272846) (xy 95.079322 -229.299495)
			(xy 95.308156 -229.299495) (xy 95.308156 -229.246197) (xy 95.316099 -229.193493) (xy 95.331809 -229.142563)
			(xy 95.354935 -229.094542) (xy 95.384959 -229.050505) (xy 95.421211 -229.011434) (xy 95.462882 -228.978203)
			(xy 95.50904 -228.951554) (xy 95.558654 -228.932082) (xy 95.610616 -228.920222) (xy 95.663766 -228.916239)
			(xy 95.716916 -228.920222) (xy 95.768878 -228.932082) (xy 95.818492 -228.951554) (xy 95.86465 -228.978203)
			(xy 95.906321 -229.011434) (xy 95.942573 -229.050505) (xy 95.972597 -229.094542) (xy 95.995723 -229.142563)
			(xy 96.011433 -229.193493) (xy 96.019376 -229.246197) (xy 96.019874 -229.272846) (xy 96.019376 -229.299495)
			(xy 96.247956 -229.299495) (xy 96.247956 -229.246197) (xy 96.255899 -229.193493) (xy 96.271609 -229.142563)
			(xy 96.294735 -229.094542) (xy 96.324759 -229.050505) (xy 96.361011 -229.011434) (xy 96.402682 -228.978203)
			(xy 96.44884 -228.951554) (xy 96.498454 -228.932082) (xy 96.550416 -228.920222) (xy 96.603566 -228.916239)
			(xy 96.656716 -228.920222) (xy 96.708678 -228.932082) (xy 96.758292 -228.951554) (xy 96.80445 -228.978203)
			(xy 96.846121 -229.011434) (xy 96.882373 -229.050505) (xy 96.912397 -229.094542) (xy 96.935523 -229.142563)
			(xy 96.951233 -229.193493) (xy 96.959176 -229.246197) (xy 96.959674 -229.272846) (xy 96.959176 -229.299495)
			(xy 97.187756 -229.299495) (xy 97.187756 -229.246197) (xy 97.195699 -229.193493) (xy 97.211409 -229.142563)
			(xy 97.234535 -229.094542) (xy 97.264559 -229.050505) (xy 97.300811 -229.011434) (xy 97.342482 -228.978203)
			(xy 97.38864 -228.951554) (xy 97.438254 -228.932082) (xy 97.490216 -228.920222) (xy 97.543366 -228.916239)
			(xy 97.596516 -228.920222) (xy 97.648478 -228.932082) (xy 97.698092 -228.951554) (xy 97.74425 -228.978203)
			(xy 97.785921 -229.011434) (xy 97.822173 -229.050505) (xy 97.852197 -229.094542) (xy 97.875323 -229.142563)
			(xy 97.891033 -229.193493) (xy 97.898976 -229.246197) (xy 97.899474 -229.272846) (xy 97.898976 -229.299495)
			(xy 98.127556 -229.299495) (xy 98.127556 -229.246197) (xy 98.135499 -229.193493) (xy 98.151209 -229.142563)
			(xy 98.174335 -229.094542) (xy 98.204359 -229.050505) (xy 98.240611 -229.011434) (xy 98.282282 -228.978203)
			(xy 98.32844 -228.951554) (xy 98.378054 -228.932082) (xy 98.430016 -228.920222) (xy 98.483166 -228.916239)
			(xy 98.536316 -228.920222) (xy 98.588278 -228.932082) (xy 98.637892 -228.951554) (xy 98.68405 -228.978203)
			(xy 98.725721 -229.011434) (xy 98.761973 -229.050505) (xy 98.791997 -229.094542) (xy 98.815123 -229.142563)
			(xy 98.830833 -229.193493) (xy 98.838776 -229.246197) (xy 98.839274 -229.272846) (xy 98.838776 -229.299495)
			(xy 99.067356 -229.299495) (xy 99.067356 -229.246197) (xy 99.075299 -229.193493) (xy 99.091009 -229.142563)
			(xy 99.114135 -229.094542) (xy 99.144159 -229.050505) (xy 99.180411 -229.011434) (xy 99.222082 -228.978203)
			(xy 99.26824 -228.951554) (xy 99.317854 -228.932082) (xy 99.369816 -228.920222) (xy 99.422966 -228.916239)
			(xy 99.476116 -228.920222) (xy 99.528078 -228.932082) (xy 99.577692 -228.951554) (xy 99.62385 -228.978203)
			(xy 99.665521 -229.011434) (xy 99.701773 -229.050505) (xy 99.731797 -229.094542) (xy 99.754923 -229.142563)
			(xy 99.770633 -229.193493) (xy 99.778576 -229.246197) (xy 99.779074 -229.272846) (xy 99.778576 -229.299495)
			(xy 100.007156 -229.299495) (xy 100.007156 -229.246197) (xy 100.015099 -229.193493) (xy 100.030809 -229.142563)
			(xy 100.053935 -229.094542) (xy 100.083959 -229.050505) (xy 100.120211 -229.011434) (xy 100.161882 -228.978203)
			(xy 100.20804 -228.951554) (xy 100.257654 -228.932082) (xy 100.309616 -228.920222) (xy 100.362766 -228.916239)
			(xy 100.415916 -228.920222) (xy 100.467878 -228.932082) (xy 100.517492 -228.951554) (xy 100.56365 -228.978203)
			(xy 100.605321 -229.011434) (xy 100.641573 -229.050505) (xy 100.671597 -229.094542) (xy 100.694723 -229.142563)
			(xy 100.710433 -229.193493) (xy 100.718376 -229.246197) (xy 100.718874 -229.272846) (xy 100.718376 -229.299495)
			(xy 100.946702 -229.299495) (xy 100.946702 -229.246197) (xy 100.954645 -229.193493) (xy 100.970355 -229.142563)
			(xy 100.993481 -229.094542) (xy 101.023505 -229.050505) (xy 101.059757 -229.011434) (xy 101.101428 -228.978203)
			(xy 101.147586 -228.951554) (xy 101.1972 -228.932082) (xy 101.249162 -228.920222) (xy 101.302312 -228.916239)
			(xy 101.355462 -228.920222) (xy 101.407424 -228.932082) (xy 101.457038 -228.951554) (xy 101.503196 -228.978203)
			(xy 101.544867 -229.011434) (xy 101.581119 -229.050505) (xy 101.611143 -229.094542) (xy 101.634269 -229.142563)
			(xy 101.649979 -229.193493) (xy 101.657922 -229.246197) (xy 101.65842 -229.272846) (xy 101.657922 -229.299495)
			(xy 101.886756 -229.299495) (xy 101.886756 -229.246197) (xy 101.894699 -229.193493) (xy 101.910409 -229.142563)
			(xy 101.933535 -229.094542) (xy 101.963559 -229.050505) (xy 101.999811 -229.011434) (xy 102.041482 -228.978203)
			(xy 102.08764 -228.951554) (xy 102.137254 -228.932082) (xy 102.189216 -228.920222) (xy 102.242366 -228.916239)
			(xy 102.295516 -228.920222) (xy 102.347478 -228.932082) (xy 102.397092 -228.951554) (xy 102.44325 -228.978203)
			(xy 102.484921 -229.011434) (xy 102.521173 -229.050505) (xy 102.551197 -229.094542) (xy 102.574323 -229.142563)
			(xy 102.590033 -229.193493) (xy 102.597976 -229.246197) (xy 102.598474 -229.272846) (xy 102.597976 -229.299495)
			(xy 102.826556 -229.299495) (xy 102.826556 -229.246197) (xy 102.834499 -229.193493) (xy 102.850209 -229.142563)
			(xy 102.873335 -229.094542) (xy 102.903359 -229.050505) (xy 102.939611 -229.011434) (xy 102.981282 -228.978203)
			(xy 103.02744 -228.951554) (xy 103.077054 -228.932082) (xy 103.129016 -228.920222) (xy 103.182166 -228.916239)
			(xy 103.235316 -228.920222) (xy 103.287278 -228.932082) (xy 103.336892 -228.951554) (xy 103.38305 -228.978203)
			(xy 103.424721 -229.011434) (xy 103.460973 -229.050505) (xy 103.490997 -229.094542) (xy 103.514123 -229.142563)
			(xy 103.529833 -229.193493) (xy 103.537776 -229.246197) (xy 103.538274 -229.272846) (xy 103.537776 -229.299495)
			(xy 103.766356 -229.299495) (xy 103.766356 -229.246197) (xy 103.774299 -229.193493) (xy 103.790009 -229.142563)
			(xy 103.813135 -229.094542) (xy 103.843159 -229.050505) (xy 103.879411 -229.011434) (xy 103.921082 -228.978203)
			(xy 103.96724 -228.951554) (xy 104.016854 -228.932082) (xy 104.068816 -228.920222) (xy 104.121966 -228.916239)
			(xy 104.175116 -228.920222) (xy 104.227078 -228.932082) (xy 104.276692 -228.951554) (xy 104.32285 -228.978203)
			(xy 104.364521 -229.011434) (xy 104.400773 -229.050505) (xy 104.430797 -229.094542) (xy 104.453923 -229.142563)
			(xy 104.469633 -229.193493) (xy 104.477576 -229.246197) (xy 104.478074 -229.272846) (xy 104.477576 -229.299495)
			(xy 104.706156 -229.299495) (xy 104.706156 -229.246197) (xy 104.714099 -229.193493) (xy 104.729809 -229.142563)
			(xy 104.752935 -229.094542) (xy 104.782959 -229.050505) (xy 104.819211 -229.011434) (xy 104.860882 -228.978203)
			(xy 104.90704 -228.951554) (xy 104.956654 -228.932082) (xy 105.008616 -228.920222) (xy 105.061766 -228.916239)
			(xy 105.114916 -228.920222) (xy 105.166878 -228.932082) (xy 105.216492 -228.951554) (xy 105.26265 -228.978203)
			(xy 105.304321 -229.011434) (xy 105.340573 -229.050505) (xy 105.370597 -229.094542) (xy 105.393723 -229.142563)
			(xy 105.409433 -229.193493) (xy 105.417376 -229.246197) (xy 105.417874 -229.272846) (xy 105.417376 -229.299495)
			(xy 105.645956 -229.299495) (xy 105.645956 -229.246197) (xy 105.653899 -229.193493) (xy 105.669609 -229.142563)
			(xy 105.692735 -229.094542) (xy 105.722759 -229.050505) (xy 105.759011 -229.011434) (xy 105.800682 -228.978203)
			(xy 105.84684 -228.951554) (xy 105.896454 -228.932082) (xy 105.948416 -228.920222) (xy 106.001566 -228.916239)
			(xy 106.054716 -228.920222) (xy 106.106678 -228.932082) (xy 106.156292 -228.951554) (xy 106.20245 -228.978203)
			(xy 106.244121 -229.011434) (xy 106.280373 -229.050505) (xy 106.310397 -229.094542) (xy 106.333523 -229.142563)
			(xy 106.349233 -229.193493) (xy 106.357176 -229.246197) (xy 106.357674 -229.272846) (xy 106.357176 -229.299495)
			(xy 106.585756 -229.299495) (xy 106.585756 -229.246197) (xy 106.593699 -229.193493) (xy 106.609409 -229.142563)
			(xy 106.632535 -229.094542) (xy 106.662559 -229.050505) (xy 106.698811 -229.011434) (xy 106.740482 -228.978203)
			(xy 106.78664 -228.951554) (xy 106.836254 -228.932082) (xy 106.888216 -228.920222) (xy 106.941366 -228.916239)
			(xy 106.994516 -228.920222) (xy 107.046478 -228.932082) (xy 107.096092 -228.951554) (xy 107.14225 -228.978203)
			(xy 107.183921 -229.011434) (xy 107.220173 -229.050505) (xy 107.250197 -229.094542) (xy 107.273323 -229.142563)
			(xy 107.289033 -229.193493) (xy 107.296976 -229.246197) (xy 107.297474 -229.272846) (xy 107.296976 -229.299495)
			(xy 107.525556 -229.299495) (xy 107.525556 -229.246197) (xy 107.533499 -229.193493) (xy 107.549209 -229.142563)
			(xy 107.572335 -229.094542) (xy 107.602359 -229.050505) (xy 107.638611 -229.011434) (xy 107.680282 -228.978203)
			(xy 107.72644 -228.951554) (xy 107.776054 -228.932082) (xy 107.828016 -228.920222) (xy 107.881166 -228.916239)
			(xy 107.934316 -228.920222) (xy 107.986278 -228.932082) (xy 108.035892 -228.951554) (xy 108.08205 -228.978203)
			(xy 108.123721 -229.011434) (xy 108.159973 -229.050505) (xy 108.189997 -229.094542) (xy 108.213123 -229.142563)
			(xy 108.228833 -229.193493) (xy 108.236776 -229.246197) (xy 108.237274 -229.272846) (xy 108.236776 -229.299495)
			(xy 108.465356 -229.299495) (xy 108.465356 -229.246197) (xy 108.473299 -229.193493) (xy 108.489009 -229.142563)
			(xy 108.512135 -229.094542) (xy 108.542159 -229.050505) (xy 108.578411 -229.011434) (xy 108.620082 -228.978203)
			(xy 108.66624 -228.951554) (xy 108.715854 -228.932082) (xy 108.767816 -228.920222) (xy 108.820966 -228.916239)
			(xy 108.874116 -228.920222) (xy 108.926078 -228.932082) (xy 108.975692 -228.951554) (xy 109.02185 -228.978203)
			(xy 109.063521 -229.011434) (xy 109.099773 -229.050505) (xy 109.129797 -229.094542) (xy 109.152923 -229.142563)
			(xy 109.168633 -229.193493) (xy 109.176576 -229.246197) (xy 109.177074 -229.272846) (xy 109.176576 -229.299495)
			(xy 109.405156 -229.299495) (xy 109.405156 -229.246197) (xy 109.413099 -229.193493) (xy 109.428809 -229.142563)
			(xy 109.451935 -229.094542) (xy 109.481959 -229.050505) (xy 109.518211 -229.011434) (xy 109.559882 -228.978203)
			(xy 109.60604 -228.951554) (xy 109.655654 -228.932082) (xy 109.707616 -228.920222) (xy 109.760766 -228.916239)
			(xy 109.813916 -228.920222) (xy 109.865878 -228.932082) (xy 109.915492 -228.951554) (xy 109.96165 -228.978203)
			(xy 110.003321 -229.011434) (xy 110.039573 -229.050505) (xy 110.069597 -229.094542) (xy 110.092723 -229.142563)
			(xy 110.108433 -229.193493) (xy 110.116376 -229.246197) (xy 110.116874 -229.272846) (xy 110.116376 -229.299495)
			(xy 110.344956 -229.299495) (xy 110.344956 -229.246197) (xy 110.352899 -229.193493) (xy 110.368609 -229.142563)
			(xy 110.391735 -229.094542) (xy 110.421759 -229.050505) (xy 110.458011 -229.011434) (xy 110.499682 -228.978203)
			(xy 110.54584 -228.951554) (xy 110.595454 -228.932082) (xy 110.647416 -228.920222) (xy 110.700566 -228.916239)
			(xy 110.753716 -228.920222) (xy 110.805678 -228.932082) (xy 110.855292 -228.951554) (xy 110.90145 -228.978203)
			(xy 110.943121 -229.011434) (xy 110.979373 -229.050505) (xy 111.009397 -229.094542) (xy 111.032523 -229.142563)
			(xy 111.048233 -229.193493) (xy 111.056176 -229.246197) (xy 111.056674 -229.272846) (xy 111.056176 -229.299495)
			(xy 111.284502 -229.299495) (xy 111.284502 -229.246197) (xy 111.292445 -229.193493) (xy 111.308155 -229.142563)
			(xy 111.331281 -229.094542) (xy 111.361305 -229.050505) (xy 111.397557 -229.011434) (xy 111.439228 -228.978203)
			(xy 111.485386 -228.951554) (xy 111.535 -228.932082) (xy 111.586962 -228.920222) (xy 111.640112 -228.916239)
			(xy 111.693262 -228.920222) (xy 111.745224 -228.932082) (xy 111.794838 -228.951554) (xy 111.840996 -228.978203)
			(xy 111.882667 -229.011434) (xy 111.918919 -229.050505) (xy 111.948943 -229.094542) (xy 111.972069 -229.142563)
			(xy 111.987779 -229.193493) (xy 111.995722 -229.246197) (xy 111.99622 -229.272846) (xy 111.995722 -229.299495)
			(xy 112.224556 -229.299495) (xy 112.224556 -229.246197) (xy 112.232499 -229.193493) (xy 112.248209 -229.142563)
			(xy 112.271335 -229.094542) (xy 112.301359 -229.050505) (xy 112.337611 -229.011434) (xy 112.379282 -228.978203)
			(xy 112.42544 -228.951554) (xy 112.475054 -228.932082) (xy 112.527016 -228.920222) (xy 112.580166 -228.916239)
			(xy 112.633316 -228.920222) (xy 112.685278 -228.932082) (xy 112.734892 -228.951554) (xy 112.78105 -228.978203)
			(xy 112.822721 -229.011434) (xy 112.858973 -229.050505) (xy 112.888997 -229.094542) (xy 112.912123 -229.142563)
			(xy 112.927833 -229.193493) (xy 112.935776 -229.246197) (xy 112.936274 -229.272846) (xy 112.935776 -229.299495)
			(xy 113.164356 -229.299495) (xy 113.164356 -229.246197) (xy 113.172299 -229.193493) (xy 113.188009 -229.142563)
			(xy 113.211135 -229.094542) (xy 113.241159 -229.050505) (xy 113.277411 -229.011434) (xy 113.319082 -228.978203)
			(xy 113.36524 -228.951554) (xy 113.414854 -228.932082) (xy 113.466816 -228.920222) (xy 113.519966 -228.916239)
			(xy 113.573116 -228.920222) (xy 113.625078 -228.932082) (xy 113.674692 -228.951554) (xy 113.72085 -228.978203)
			(xy 113.762521 -229.011434) (xy 113.798773 -229.050505) (xy 113.828797 -229.094542) (xy 113.851923 -229.142563)
			(xy 113.867633 -229.193493) (xy 113.875576 -229.246197) (xy 113.876074 -229.272846) (xy 113.875576 -229.299495)
			(xy 114.104156 -229.299495) (xy 114.104156 -229.246197) (xy 114.112099 -229.193493) (xy 114.127809 -229.142563)
			(xy 114.150935 -229.094542) (xy 114.180959 -229.050505) (xy 114.217211 -229.011434) (xy 114.258882 -228.978203)
			(xy 114.30504 -228.951554) (xy 114.354654 -228.932082) (xy 114.406616 -228.920222) (xy 114.459766 -228.916239)
			(xy 114.512916 -228.920222) (xy 114.564878 -228.932082) (xy 114.614492 -228.951554) (xy 114.66065 -228.978203)
			(xy 114.702321 -229.011434) (xy 114.738573 -229.050505) (xy 114.768597 -229.094542) (xy 114.791723 -229.142563)
			(xy 114.807433 -229.193493) (xy 114.815376 -229.246197) (xy 114.815874 -229.272846) (xy 114.815376 -229.299495)
			(xy 115.043956 -229.299495) (xy 115.043956 -229.246197) (xy 115.051899 -229.193493) (xy 115.067609 -229.142563)
			(xy 115.090735 -229.094542) (xy 115.120759 -229.050505) (xy 115.157011 -229.011434) (xy 115.198682 -228.978203)
			(xy 115.24484 -228.951554) (xy 115.294454 -228.932082) (xy 115.346416 -228.920222) (xy 115.399566 -228.916239)
			(xy 115.452716 -228.920222) (xy 115.504678 -228.932082) (xy 115.554292 -228.951554) (xy 115.60045 -228.978203)
			(xy 115.642121 -229.011434) (xy 115.678373 -229.050505) (xy 115.708397 -229.094542) (xy 115.731523 -229.142563)
			(xy 115.747233 -229.193493) (xy 115.755176 -229.246197) (xy 115.755674 -229.272846) (xy 115.755176 -229.299495)
			(xy 115.983756 -229.299495) (xy 115.983756 -229.246197) (xy 115.991699 -229.193493) (xy 116.007409 -229.142563)
			(xy 116.030535 -229.094542) (xy 116.060559 -229.050505) (xy 116.096811 -229.011434) (xy 116.138482 -228.978203)
			(xy 116.18464 -228.951554) (xy 116.234254 -228.932082) (xy 116.286216 -228.920222) (xy 116.339366 -228.916239)
			(xy 116.392516 -228.920222) (xy 116.444478 -228.932082) (xy 116.494092 -228.951554) (xy 116.54025 -228.978203)
			(xy 116.581921 -229.011434) (xy 116.618173 -229.050505) (xy 116.648197 -229.094542) (xy 116.671323 -229.142563)
			(xy 116.687033 -229.193493) (xy 116.694976 -229.246197) (xy 116.695474 -229.272846) (xy 116.694976 -229.299495)
			(xy 116.923556 -229.299495) (xy 116.923556 -229.246197) (xy 116.931499 -229.193493) (xy 116.947209 -229.142563)
			(xy 116.970335 -229.094542) (xy 117.000359 -229.050505) (xy 117.036611 -229.011434) (xy 117.078282 -228.978203)
			(xy 117.12444 -228.951554) (xy 117.174054 -228.932082) (xy 117.226016 -228.920222) (xy 117.279166 -228.916239)
			(xy 117.332316 -228.920222) (xy 117.384278 -228.932082) (xy 117.433892 -228.951554) (xy 117.48005 -228.978203)
			(xy 117.521721 -229.011434) (xy 117.557973 -229.050505) (xy 117.587997 -229.094542) (xy 117.611123 -229.142563)
			(xy 117.626833 -229.193493) (xy 117.634776 -229.246197) (xy 117.635274 -229.272846) (xy 117.634776 -229.299495)
			(xy 117.863356 -229.299495) (xy 117.863356 -229.246197) (xy 117.871299 -229.193493) (xy 117.887009 -229.142563)
			(xy 117.910135 -229.094542) (xy 117.940159 -229.050505) (xy 117.976411 -229.011434) (xy 118.018082 -228.978203)
			(xy 118.06424 -228.951554) (xy 118.113854 -228.932082) (xy 118.165816 -228.920222) (xy 118.218966 -228.916239)
			(xy 118.272116 -228.920222) (xy 118.324078 -228.932082) (xy 118.373692 -228.951554) (xy 118.41985 -228.978203)
			(xy 118.461521 -229.011434) (xy 118.497773 -229.050505) (xy 118.527797 -229.094542) (xy 118.550923 -229.142563)
			(xy 118.566633 -229.193493) (xy 118.574576 -229.246197) (xy 118.575074 -229.272846) (xy 118.574576 -229.299495)
			(xy 118.803156 -229.299495) (xy 118.803156 -229.246197) (xy 118.811099 -229.193493) (xy 118.826809 -229.142563)
			(xy 118.849935 -229.094542) (xy 118.879959 -229.050505) (xy 118.916211 -229.011434) (xy 118.957882 -228.978203)
			(xy 119.00404 -228.951554) (xy 119.053654 -228.932082) (xy 119.105616 -228.920222) (xy 119.158766 -228.916239)
			(xy 119.211916 -228.920222) (xy 119.263878 -228.932082) (xy 119.313492 -228.951554) (xy 119.35965 -228.978203)
			(xy 119.401321 -229.011434) (xy 119.437573 -229.050505) (xy 119.467597 -229.094542) (xy 119.490723 -229.142563)
			(xy 119.506433 -229.193493) (xy 119.514376 -229.246197) (xy 119.514874 -229.272846) (xy 119.514376 -229.299495)
			(xy 119.742956 -229.299495) (xy 119.742956 -229.246197) (xy 119.750899 -229.193493) (xy 119.766609 -229.142563)
			(xy 119.789735 -229.094542) (xy 119.819759 -229.050505) (xy 119.856011 -229.011434) (xy 119.897682 -228.978203)
			(xy 119.94384 -228.951554) (xy 119.993454 -228.932082) (xy 120.045416 -228.920222) (xy 120.098566 -228.916239)
			(xy 120.151716 -228.920222) (xy 120.203678 -228.932082) (xy 120.253292 -228.951554) (xy 120.29945 -228.978203)
			(xy 120.341121 -229.011434) (xy 120.377373 -229.050505) (xy 120.407397 -229.094542) (xy 120.430523 -229.142563)
			(xy 120.446233 -229.193493) (xy 120.454176 -229.246197) (xy 120.454674 -229.272846) (xy 120.454176 -229.299495)
			(xy 120.682756 -229.299495) (xy 120.682756 -229.246197) (xy 120.690699 -229.193493) (xy 120.706409 -229.142563)
			(xy 120.729535 -229.094542) (xy 120.759559 -229.050505) (xy 120.795811 -229.011434) (xy 120.837482 -228.978203)
			(xy 120.88364 -228.951554) (xy 120.933254 -228.932082) (xy 120.985216 -228.920222) (xy 121.038366 -228.916239)
			(xy 121.091516 -228.920222) (xy 121.143478 -228.932082) (xy 121.193092 -228.951554) (xy 121.23925 -228.978203)
			(xy 121.280921 -229.011434) (xy 121.317173 -229.050505) (xy 121.347197 -229.094542) (xy 121.370323 -229.142563)
			(xy 121.386033 -229.193493) (xy 121.393976 -229.246197) (xy 121.394474 -229.272846) (xy 121.393976 -229.299495)
			(xy 121.622556 -229.299495) (xy 121.622556 -229.246197) (xy 121.630499 -229.193493) (xy 121.646209 -229.142563)
			(xy 121.669335 -229.094542) (xy 121.699359 -229.050505) (xy 121.735611 -229.011434) (xy 121.777282 -228.978203)
			(xy 121.82344 -228.951554) (xy 121.873054 -228.932082) (xy 121.925016 -228.920222) (xy 121.978166 -228.916239)
			(xy 122.031316 -228.920222) (xy 122.083278 -228.932082) (xy 122.132892 -228.951554) (xy 122.17905 -228.978203)
			(xy 122.220721 -229.011434) (xy 122.256973 -229.050505) (xy 122.286997 -229.094542) (xy 122.310123 -229.142563)
			(xy 122.325833 -229.193493) (xy 122.333776 -229.246197) (xy 122.334274 -229.272846) (xy 122.333776 -229.299495)
			(xy 122.562102 -229.299495) (xy 122.562102 -229.246197) (xy 122.570045 -229.193493) (xy 122.585755 -229.142563)
			(xy 122.608881 -229.094542) (xy 122.638905 -229.050505) (xy 122.675157 -229.011434) (xy 122.716828 -228.978203)
			(xy 122.762986 -228.951554) (xy 122.8126 -228.932082) (xy 122.864562 -228.920222) (xy 122.917712 -228.916239)
			(xy 122.970862 -228.920222) (xy 123.022824 -228.932082) (xy 123.072438 -228.951554) (xy 123.118596 -228.978203)
			(xy 123.160267 -229.011434) (xy 123.196519 -229.050505) (xy 123.226543 -229.094542) (xy 123.249669 -229.142563)
			(xy 123.265379 -229.193493) (xy 123.273322 -229.246197) (xy 123.27382 -229.272846) (xy 123.273322 -229.299495)
			(xy 123.502156 -229.299495) (xy 123.502156 -229.246197) (xy 123.510099 -229.193493) (xy 123.525809 -229.142563)
			(xy 123.548935 -229.094542) (xy 123.578959 -229.050505) (xy 123.615211 -229.011434) (xy 123.656882 -228.978203)
			(xy 123.70304 -228.951554) (xy 123.752654 -228.932082) (xy 123.804616 -228.920222) (xy 123.857766 -228.916239)
			(xy 123.910916 -228.920222) (xy 123.962878 -228.932082) (xy 124.012492 -228.951554) (xy 124.05865 -228.978203)
			(xy 124.100321 -229.011434) (xy 124.136573 -229.050505) (xy 124.166597 -229.094542) (xy 124.189723 -229.142563)
			(xy 124.205433 -229.193493) (xy 124.213376 -229.246197) (xy 124.213874 -229.272846) (xy 124.213376 -229.299495)
			(xy 124.441956 -229.299495) (xy 124.441956 -229.246197) (xy 124.449899 -229.193493) (xy 124.465609 -229.142563)
			(xy 124.488735 -229.094542) (xy 124.518759 -229.050505) (xy 124.555011 -229.011434) (xy 124.596682 -228.978203)
			(xy 124.64284 -228.951554) (xy 124.692454 -228.932082) (xy 124.744416 -228.920222) (xy 124.797566 -228.916239)
			(xy 124.850716 -228.920222) (xy 124.902678 -228.932082) (xy 124.952292 -228.951554) (xy 124.99845 -228.978203)
			(xy 125.040121 -229.011434) (xy 125.076373 -229.050505) (xy 125.106397 -229.094542) (xy 125.129523 -229.142563)
			(xy 125.145233 -229.193493) (xy 125.153176 -229.246197) (xy 125.153674 -229.272846) (xy 125.153176 -229.299495)
			(xy 125.381756 -229.299495) (xy 125.381756 -229.246197) (xy 125.389699 -229.193493) (xy 125.405409 -229.142563)
			(xy 125.428535 -229.094542) (xy 125.458559 -229.050505) (xy 125.494811 -229.011434) (xy 125.536482 -228.978203)
			(xy 125.58264 -228.951554) (xy 125.632254 -228.932082) (xy 125.684216 -228.920222) (xy 125.737366 -228.916239)
			(xy 125.790516 -228.920222) (xy 125.842478 -228.932082) (xy 125.892092 -228.951554) (xy 125.93825 -228.978203)
			(xy 125.979921 -229.011434) (xy 126.016173 -229.050505) (xy 126.046197 -229.094542) (xy 126.069323 -229.142563)
			(xy 126.085033 -229.193493) (xy 126.092976 -229.246197) (xy 126.093474 -229.272846) (xy 126.092976 -229.299495)
			(xy 126.321556 -229.299495) (xy 126.321556 -229.246197) (xy 126.329499 -229.193493) (xy 126.345209 -229.142563)
			(xy 126.368335 -229.094542) (xy 126.398359 -229.050505) (xy 126.434611 -229.011434) (xy 126.476282 -228.978203)
			(xy 126.52244 -228.951554) (xy 126.572054 -228.932082) (xy 126.624016 -228.920222) (xy 126.677166 -228.916239)
			(xy 126.730316 -228.920222) (xy 126.782278 -228.932082) (xy 126.831892 -228.951554) (xy 126.87805 -228.978203)
			(xy 126.919721 -229.011434) (xy 126.955973 -229.050505) (xy 126.985997 -229.094542) (xy 127.009123 -229.142563)
			(xy 127.024833 -229.193493) (xy 127.032776 -229.246197) (xy 127.033274 -229.272846) (xy 127.032776 -229.299495)
			(xy 127.261356 -229.299495) (xy 127.261356 -229.246197) (xy 127.269299 -229.193493) (xy 127.285009 -229.142563)
			(xy 127.308135 -229.094542) (xy 127.338159 -229.050505) (xy 127.374411 -229.011434) (xy 127.416082 -228.978203)
			(xy 127.46224 -228.951554) (xy 127.511854 -228.932082) (xy 127.563816 -228.920222) (xy 127.616966 -228.916239)
			(xy 127.670116 -228.920222) (xy 127.722078 -228.932082) (xy 127.771692 -228.951554) (xy 127.81785 -228.978203)
			(xy 127.859521 -229.011434) (xy 127.895773 -229.050505) (xy 127.925797 -229.094542) (xy 127.948923 -229.142563)
			(xy 127.964633 -229.193493) (xy 127.972576 -229.246197) (xy 127.973074 -229.272846) (xy 127.972576 -229.299495)
			(xy 128.201156 -229.299495) (xy 128.201156 -229.246197) (xy 128.209099 -229.193493) (xy 128.224809 -229.142563)
			(xy 128.247935 -229.094542) (xy 128.277959 -229.050505) (xy 128.314211 -229.011434) (xy 128.355882 -228.978203)
			(xy 128.40204 -228.951554) (xy 128.451654 -228.932082) (xy 128.503616 -228.920222) (xy 128.556766 -228.916239)
			(xy 128.609916 -228.920222) (xy 128.661878 -228.932082) (xy 128.711492 -228.951554) (xy 128.75765 -228.978203)
			(xy 128.799321 -229.011434) (xy 128.835573 -229.050505) (xy 128.865597 -229.094542) (xy 128.888723 -229.142563)
			(xy 128.904433 -229.193493) (xy 128.912376 -229.246197) (xy 128.912874 -229.272846) (xy 128.912376 -229.299495)
			(xy 129.140702 -229.299495) (xy 129.140702 -229.246197) (xy 129.148645 -229.193493) (xy 129.164355 -229.142563)
			(xy 129.187481 -229.094542) (xy 129.217505 -229.050505) (xy 129.253757 -229.011434) (xy 129.295428 -228.978203)
			(xy 129.341586 -228.951554) (xy 129.3912 -228.932082) (xy 129.443162 -228.920222) (xy 129.496312 -228.916239)
			(xy 129.549462 -228.920222) (xy 129.601424 -228.932082) (xy 129.651038 -228.951554) (xy 129.697196 -228.978203)
			(xy 129.738867 -229.011434) (xy 129.775119 -229.050505) (xy 129.805143 -229.094542) (xy 129.828269 -229.142563)
			(xy 129.843979 -229.193493) (xy 129.851922 -229.246197) (xy 129.85242 -229.272846) (xy 129.851922 -229.299495)
			(xy 130.080756 -229.299495) (xy 130.080756 -229.246197) (xy 130.088699 -229.193493) (xy 130.104409 -229.142563)
			(xy 130.127535 -229.094542) (xy 130.157559 -229.050505) (xy 130.193811 -229.011434) (xy 130.235482 -228.978203)
			(xy 130.28164 -228.951554) (xy 130.331254 -228.932082) (xy 130.383216 -228.920222) (xy 130.436366 -228.916239)
			(xy 130.489516 -228.920222) (xy 130.541478 -228.932082) (xy 130.591092 -228.951554) (xy 130.63725 -228.978203)
			(xy 130.678921 -229.011434) (xy 130.715173 -229.050505) (xy 130.745197 -229.094542) (xy 130.768323 -229.142563)
			(xy 130.784033 -229.193493) (xy 130.791976 -229.246197) (xy 130.792474 -229.272846) (xy 130.791976 -229.299495)
			(xy 131.020556 -229.299495) (xy 131.020556 -229.246197) (xy 131.028499 -229.193493) (xy 131.044209 -229.142563)
			(xy 131.067335 -229.094542) (xy 131.097359 -229.050505) (xy 131.133611 -229.011434) (xy 131.175282 -228.978203)
			(xy 131.22144 -228.951554) (xy 131.271054 -228.932082) (xy 131.323016 -228.920222) (xy 131.376166 -228.916239)
			(xy 131.429316 -228.920222) (xy 131.481278 -228.932082) (xy 131.530892 -228.951554) (xy 131.57705 -228.978203)
			(xy 131.618721 -229.011434) (xy 131.654973 -229.050505) (xy 131.684997 -229.094542) (xy 131.708123 -229.142563)
			(xy 131.723833 -229.193493) (xy 131.731776 -229.246197) (xy 131.732274 -229.272846) (xy 131.731776 -229.299495)
			(xy 131.960356 -229.299495) (xy 131.960356 -229.246197) (xy 131.968299 -229.193493) (xy 131.984009 -229.142563)
			(xy 132.007135 -229.094542) (xy 132.037159 -229.050505) (xy 132.073411 -229.011434) (xy 132.115082 -228.978203)
			(xy 132.16124 -228.951554) (xy 132.210854 -228.932082) (xy 132.262816 -228.920222) (xy 132.315966 -228.916239)
			(xy 132.369116 -228.920222) (xy 132.421078 -228.932082) (xy 132.470692 -228.951554) (xy 132.51685 -228.978203)
			(xy 132.558521 -229.011434) (xy 132.594773 -229.050505) (xy 132.624797 -229.094542) (xy 132.647923 -229.142563)
			(xy 132.663633 -229.193493) (xy 132.671576 -229.246197) (xy 132.672074 -229.272846) (xy 132.671576 -229.299495)
			(xy 132.900156 -229.299495) (xy 132.900156 -229.246197) (xy 132.908099 -229.193493) (xy 132.923809 -229.142563)
			(xy 132.946935 -229.094542) (xy 132.976959 -229.050505) (xy 133.013211 -229.011434) (xy 133.054882 -228.978203)
			(xy 133.10104 -228.951554) (xy 133.150654 -228.932082) (xy 133.202616 -228.920222) (xy 133.255766 -228.916239)
			(xy 133.308916 -228.920222) (xy 133.360878 -228.932082) (xy 133.410492 -228.951554) (xy 133.45665 -228.978203)
			(xy 133.498321 -229.011434) (xy 133.534573 -229.050505) (xy 133.564597 -229.094542) (xy 133.587723 -229.142563)
			(xy 133.603433 -229.193493) (xy 133.611376 -229.246197) (xy 133.611874 -229.272846) (xy 133.611376 -229.299495)
			(xy 133.839956 -229.299495) (xy 133.839956 -229.246197) (xy 133.847899 -229.193493) (xy 133.863609 -229.142563)
			(xy 133.886735 -229.094542) (xy 133.916759 -229.050505) (xy 133.953011 -229.011434) (xy 133.994682 -228.978203)
			(xy 134.04084 -228.951554) (xy 134.090454 -228.932082) (xy 134.142416 -228.920222) (xy 134.195566 -228.916239)
			(xy 134.248716 -228.920222) (xy 134.300678 -228.932082) (xy 134.350292 -228.951554) (xy 134.39645 -228.978203)
			(xy 134.438121 -229.011434) (xy 134.474373 -229.050505) (xy 134.504397 -229.094542) (xy 134.527523 -229.142563)
			(xy 134.543233 -229.193493) (xy 134.551176 -229.246197) (xy 134.551674 -229.272846) (xy 134.551176 -229.299495)
			(xy 134.543233 -229.352199) (xy 134.527523 -229.403129) (xy 134.504397 -229.45115) (xy 134.474373 -229.495187)
			(xy 134.438121 -229.534258) (xy 134.39645 -229.567489) (xy 134.350292 -229.594138) (xy 134.300678 -229.61361)
			(xy 134.248716 -229.62547) (xy 134.195566 -229.629454) (xy 134.142416 -229.62547) (xy 134.090454 -229.61361)
			(xy 134.04084 -229.594138) (xy 133.994682 -229.567489) (xy 133.953011 -229.534258) (xy 133.916759 -229.495187)
			(xy 133.886735 -229.45115) (xy 133.863609 -229.403129) (xy 133.847899 -229.352199) (xy 133.839956 -229.299495)
			(xy 133.611376 -229.299495) (xy 133.603433 -229.352199) (xy 133.587723 -229.403129) (xy 133.564597 -229.45115)
			(xy 133.534573 -229.495187) (xy 133.498321 -229.534258) (xy 133.45665 -229.567489) (xy 133.410492 -229.594138)
			(xy 133.360878 -229.61361) (xy 133.308916 -229.62547) (xy 133.255766 -229.629454) (xy 133.202616 -229.62547)
			(xy 133.150654 -229.61361) (xy 133.10104 -229.594138) (xy 133.054882 -229.567489) (xy 133.013211 -229.534258)
			(xy 132.976959 -229.495187) (xy 132.946935 -229.45115) (xy 132.923809 -229.403129) (xy 132.908099 -229.352199)
			(xy 132.900156 -229.299495) (xy 132.671576 -229.299495) (xy 132.663633 -229.352199) (xy 132.647923 -229.403129)
			(xy 132.624797 -229.45115) (xy 132.594773 -229.495187) (xy 132.558521 -229.534258) (xy 132.51685 -229.567489)
			(xy 132.470692 -229.594138) (xy 132.421078 -229.61361) (xy 132.369116 -229.62547) (xy 132.315966 -229.629454)
			(xy 132.262816 -229.62547) (xy 132.210854 -229.61361) (xy 132.16124 -229.594138) (xy 132.115082 -229.567489)
			(xy 132.073411 -229.534258) (xy 132.037159 -229.495187) (xy 132.007135 -229.45115) (xy 131.984009 -229.403129)
			(xy 131.968299 -229.352199) (xy 131.960356 -229.299495) (xy 131.731776 -229.299495) (xy 131.723833 -229.352199)
			(xy 131.708123 -229.403129) (xy 131.684997 -229.45115) (xy 131.654973 -229.495187) (xy 131.618721 -229.534258)
			(xy 131.57705 -229.567489) (xy 131.530892 -229.594138) (xy 131.481278 -229.61361) (xy 131.429316 -229.62547)
			(xy 131.376166 -229.629454) (xy 131.323016 -229.62547) (xy 131.271054 -229.61361) (xy 131.22144 -229.594138)
			(xy 131.175282 -229.567489) (xy 131.133611 -229.534258) (xy 131.097359 -229.495187) (xy 131.067335 -229.45115)
			(xy 131.044209 -229.403129) (xy 131.028499 -229.352199) (xy 131.020556 -229.299495) (xy 130.791976 -229.299495)
			(xy 130.784033 -229.352199) (xy 130.768323 -229.403129) (xy 130.745197 -229.45115) (xy 130.715173 -229.495187)
			(xy 130.678921 -229.534258) (xy 130.63725 -229.567489) (xy 130.591092 -229.594138) (xy 130.541478 -229.61361)
			(xy 130.489516 -229.62547) (xy 130.436366 -229.629454) (xy 130.383216 -229.62547) (xy 130.331254 -229.61361)
			(xy 130.28164 -229.594138) (xy 130.235482 -229.567489) (xy 130.193811 -229.534258) (xy 130.157559 -229.495187)
			(xy 130.127535 -229.45115) (xy 130.104409 -229.403129) (xy 130.088699 -229.352199) (xy 130.080756 -229.299495)
			(xy 129.851922 -229.299495) (xy 129.843979 -229.352199) (xy 129.828269 -229.403129) (xy 129.805143 -229.45115)
			(xy 129.775119 -229.495187) (xy 129.738867 -229.534258) (xy 129.697196 -229.567489) (xy 129.651038 -229.594138)
			(xy 129.601424 -229.61361) (xy 129.549462 -229.62547) (xy 129.496312 -229.629454) (xy 129.443162 -229.62547)
			(xy 129.3912 -229.61361) (xy 129.341586 -229.594138) (xy 129.295428 -229.567489) (xy 129.253757 -229.534258)
			(xy 129.217505 -229.495187) (xy 129.187481 -229.45115) (xy 129.164355 -229.403129) (xy 129.148645 -229.352199)
			(xy 129.140702 -229.299495) (xy 128.912376 -229.299495) (xy 128.904433 -229.352199) (xy 128.888723 -229.403129)
			(xy 128.865597 -229.45115) (xy 128.835573 -229.495187) (xy 128.799321 -229.534258) (xy 128.75765 -229.567489)
			(xy 128.711492 -229.594138) (xy 128.661878 -229.61361) (xy 128.609916 -229.62547) (xy 128.556766 -229.629454)
			(xy 128.503616 -229.62547) (xy 128.451654 -229.61361) (xy 128.40204 -229.594138) (xy 128.355882 -229.567489)
			(xy 128.314211 -229.534258) (xy 128.277959 -229.495187) (xy 128.247935 -229.45115) (xy 128.224809 -229.403129)
			(xy 128.209099 -229.352199) (xy 128.201156 -229.299495) (xy 127.972576 -229.299495) (xy 127.964633 -229.352199)
			(xy 127.948923 -229.403129) (xy 127.925797 -229.45115) (xy 127.895773 -229.495187) (xy 127.859521 -229.534258)
			(xy 127.81785 -229.567489) (xy 127.771692 -229.594138) (xy 127.722078 -229.61361) (xy 127.670116 -229.62547)
			(xy 127.616966 -229.629454) (xy 127.563816 -229.62547) (xy 127.511854 -229.61361) (xy 127.46224 -229.594138)
			(xy 127.416082 -229.567489) (xy 127.374411 -229.534258) (xy 127.338159 -229.495187) (xy 127.308135 -229.45115)
			(xy 127.285009 -229.403129) (xy 127.269299 -229.352199) (xy 127.261356 -229.299495) (xy 127.032776 -229.299495)
			(xy 127.024833 -229.352199) (xy 127.009123 -229.403129) (xy 126.985997 -229.45115) (xy 126.955973 -229.495187)
			(xy 126.919721 -229.534258) (xy 126.87805 -229.567489) (xy 126.831892 -229.594138) (xy 126.782278 -229.61361)
			(xy 126.730316 -229.62547) (xy 126.677166 -229.629454) (xy 126.624016 -229.62547) (xy 126.572054 -229.61361)
			(xy 126.52244 -229.594138) (xy 126.476282 -229.567489) (xy 126.434611 -229.534258) (xy 126.398359 -229.495187)
			(xy 126.368335 -229.45115) (xy 126.345209 -229.403129) (xy 126.329499 -229.352199) (xy 126.321556 -229.299495)
			(xy 126.092976 -229.299495) (xy 126.085033 -229.352199) (xy 126.069323 -229.403129) (xy 126.046197 -229.45115)
			(xy 126.016173 -229.495187) (xy 125.979921 -229.534258) (xy 125.93825 -229.567489) (xy 125.892092 -229.594138)
			(xy 125.842478 -229.61361) (xy 125.790516 -229.62547) (xy 125.737366 -229.629454) (xy 125.684216 -229.62547)
			(xy 125.632254 -229.61361) (xy 125.58264 -229.594138) (xy 125.536482 -229.567489) (xy 125.494811 -229.534258)
			(xy 125.458559 -229.495187) (xy 125.428535 -229.45115) (xy 125.405409 -229.403129) (xy 125.389699 -229.352199)
			(xy 125.381756 -229.299495) (xy 125.153176 -229.299495) (xy 125.145233 -229.352199) (xy 125.129523 -229.403129)
			(xy 125.106397 -229.45115) (xy 125.076373 -229.495187) (xy 125.040121 -229.534258) (xy 124.99845 -229.567489)
			(xy 124.952292 -229.594138) (xy 124.902678 -229.61361) (xy 124.850716 -229.62547) (xy 124.797566 -229.629454)
			(xy 124.744416 -229.62547) (xy 124.692454 -229.61361) (xy 124.64284 -229.594138) (xy 124.596682 -229.567489)
			(xy 124.555011 -229.534258) (xy 124.518759 -229.495187) (xy 124.488735 -229.45115) (xy 124.465609 -229.403129)
			(xy 124.449899 -229.352199) (xy 124.441956 -229.299495) (xy 124.213376 -229.299495) (xy 124.205433 -229.352199)
			(xy 124.189723 -229.403129) (xy 124.166597 -229.45115) (xy 124.136573 -229.495187) (xy 124.100321 -229.534258)
			(xy 124.05865 -229.567489) (xy 124.012492 -229.594138) (xy 123.962878 -229.61361) (xy 123.910916 -229.62547)
			(xy 123.857766 -229.629454) (xy 123.804616 -229.62547) (xy 123.752654 -229.61361) (xy 123.70304 -229.594138)
			(xy 123.656882 -229.567489) (xy 123.615211 -229.534258) (xy 123.578959 -229.495187) (xy 123.548935 -229.45115)
			(xy 123.525809 -229.403129) (xy 123.510099 -229.352199) (xy 123.502156 -229.299495) (xy 123.273322 -229.299495)
			(xy 123.265379 -229.352199) (xy 123.249669 -229.403129) (xy 123.226543 -229.45115) (xy 123.196519 -229.495187)
			(xy 123.160267 -229.534258) (xy 123.118596 -229.567489) (xy 123.072438 -229.594138) (xy 123.022824 -229.61361)
			(xy 122.970862 -229.62547) (xy 122.917712 -229.629454) (xy 122.864562 -229.62547) (xy 122.8126 -229.61361)
			(xy 122.762986 -229.594138) (xy 122.716828 -229.567489) (xy 122.675157 -229.534258) (xy 122.638905 -229.495187)
			(xy 122.608881 -229.45115) (xy 122.585755 -229.403129) (xy 122.570045 -229.352199) (xy 122.562102 -229.299495)
			(xy 122.333776 -229.299495) (xy 122.325833 -229.352199) (xy 122.310123 -229.403129) (xy 122.286997 -229.45115)
			(xy 122.256973 -229.495187) (xy 122.220721 -229.534258) (xy 122.17905 -229.567489) (xy 122.132892 -229.594138)
			(xy 122.083278 -229.61361) (xy 122.031316 -229.62547) (xy 121.978166 -229.629454) (xy 121.925016 -229.62547)
			(xy 121.873054 -229.61361) (xy 121.82344 -229.594138) (xy 121.777282 -229.567489) (xy 121.735611 -229.534258)
			(xy 121.699359 -229.495187) (xy 121.669335 -229.45115) (xy 121.646209 -229.403129) (xy 121.630499 -229.352199)
			(xy 121.622556 -229.299495) (xy 121.393976 -229.299495) (xy 121.386033 -229.352199) (xy 121.370323 -229.403129)
			(xy 121.347197 -229.45115) (xy 121.317173 -229.495187) (xy 121.280921 -229.534258) (xy 121.23925 -229.567489)
			(xy 121.193092 -229.594138) (xy 121.143478 -229.61361) (xy 121.091516 -229.62547) (xy 121.038366 -229.629454)
			(xy 120.985216 -229.62547) (xy 120.933254 -229.61361) (xy 120.88364 -229.594138) (xy 120.837482 -229.567489)
			(xy 120.795811 -229.534258) (xy 120.759559 -229.495187) (xy 120.729535 -229.45115) (xy 120.706409 -229.403129)
			(xy 120.690699 -229.352199) (xy 120.682756 -229.299495) (xy 120.454176 -229.299495) (xy 120.446233 -229.352199)
			(xy 120.430523 -229.403129) (xy 120.407397 -229.45115) (xy 120.377373 -229.495187) (xy 120.341121 -229.534258)
			(xy 120.29945 -229.567489) (xy 120.253292 -229.594138) (xy 120.203678 -229.61361) (xy 120.151716 -229.62547)
			(xy 120.098566 -229.629454) (xy 120.045416 -229.62547) (xy 119.993454 -229.61361) (xy 119.94384 -229.594138)
			(xy 119.897682 -229.567489) (xy 119.856011 -229.534258) (xy 119.819759 -229.495187) (xy 119.789735 -229.45115)
			(xy 119.766609 -229.403129) (xy 119.750899 -229.352199) (xy 119.742956 -229.299495) (xy 119.514376 -229.299495)
			(xy 119.506433 -229.352199) (xy 119.490723 -229.403129) (xy 119.467597 -229.45115) (xy 119.437573 -229.495187)
			(xy 119.401321 -229.534258) (xy 119.35965 -229.567489) (xy 119.313492 -229.594138) (xy 119.263878 -229.61361)
			(xy 119.211916 -229.62547) (xy 119.158766 -229.629454) (xy 119.105616 -229.62547) (xy 119.053654 -229.61361)
			(xy 119.00404 -229.594138) (xy 118.957882 -229.567489) (xy 118.916211 -229.534258) (xy 118.879959 -229.495187)
			(xy 118.849935 -229.45115) (xy 118.826809 -229.403129) (xy 118.811099 -229.352199) (xy 118.803156 -229.299495)
			(xy 118.574576 -229.299495) (xy 118.566633 -229.352199) (xy 118.550923 -229.403129) (xy 118.527797 -229.45115)
			(xy 118.497773 -229.495187) (xy 118.461521 -229.534258) (xy 118.41985 -229.567489) (xy 118.373692 -229.594138)
			(xy 118.324078 -229.61361) (xy 118.272116 -229.62547) (xy 118.218966 -229.629454) (xy 118.165816 -229.62547)
			(xy 118.113854 -229.61361) (xy 118.06424 -229.594138) (xy 118.018082 -229.567489) (xy 117.976411 -229.534258)
			(xy 117.940159 -229.495187) (xy 117.910135 -229.45115) (xy 117.887009 -229.403129) (xy 117.871299 -229.352199)
			(xy 117.863356 -229.299495) (xy 117.634776 -229.299495) (xy 117.626833 -229.352199) (xy 117.611123 -229.403129)
			(xy 117.587997 -229.45115) (xy 117.557973 -229.495187) (xy 117.521721 -229.534258) (xy 117.48005 -229.567489)
			(xy 117.433892 -229.594138) (xy 117.384278 -229.61361) (xy 117.332316 -229.62547) (xy 117.279166 -229.629454)
			(xy 117.226016 -229.62547) (xy 117.174054 -229.61361) (xy 117.12444 -229.594138) (xy 117.078282 -229.567489)
			(xy 117.036611 -229.534258) (xy 117.000359 -229.495187) (xy 116.970335 -229.45115) (xy 116.947209 -229.403129)
			(xy 116.931499 -229.352199) (xy 116.923556 -229.299495) (xy 116.694976 -229.299495) (xy 116.687033 -229.352199)
			(xy 116.671323 -229.403129) (xy 116.648197 -229.45115) (xy 116.618173 -229.495187) (xy 116.581921 -229.534258)
			(xy 116.54025 -229.567489) (xy 116.494092 -229.594138) (xy 116.444478 -229.61361) (xy 116.392516 -229.62547)
			(xy 116.339366 -229.629454) (xy 116.286216 -229.62547) (xy 116.234254 -229.61361) (xy 116.18464 -229.594138)
			(xy 116.138482 -229.567489) (xy 116.096811 -229.534258) (xy 116.060559 -229.495187) (xy 116.030535 -229.45115)
			(xy 116.007409 -229.403129) (xy 115.991699 -229.352199) (xy 115.983756 -229.299495) (xy 115.755176 -229.299495)
			(xy 115.747233 -229.352199) (xy 115.731523 -229.403129) (xy 115.708397 -229.45115) (xy 115.678373 -229.495187)
			(xy 115.642121 -229.534258) (xy 115.60045 -229.567489) (xy 115.554292 -229.594138) (xy 115.504678 -229.61361)
			(xy 115.452716 -229.62547) (xy 115.399566 -229.629454) (xy 115.346416 -229.62547) (xy 115.294454 -229.61361)
			(xy 115.24484 -229.594138) (xy 115.198682 -229.567489) (xy 115.157011 -229.534258) (xy 115.120759 -229.495187)
			(xy 115.090735 -229.45115) (xy 115.067609 -229.403129) (xy 115.051899 -229.352199) (xy 115.043956 -229.299495)
			(xy 114.815376 -229.299495) (xy 114.807433 -229.352199) (xy 114.791723 -229.403129) (xy 114.768597 -229.45115)
			(xy 114.738573 -229.495187) (xy 114.702321 -229.534258) (xy 114.66065 -229.567489) (xy 114.614492 -229.594138)
			(xy 114.564878 -229.61361) (xy 114.512916 -229.62547) (xy 114.459766 -229.629454) (xy 114.406616 -229.62547)
			(xy 114.354654 -229.61361) (xy 114.30504 -229.594138) (xy 114.258882 -229.567489) (xy 114.217211 -229.534258)
			(xy 114.180959 -229.495187) (xy 114.150935 -229.45115) (xy 114.127809 -229.403129) (xy 114.112099 -229.352199)
			(xy 114.104156 -229.299495) (xy 113.875576 -229.299495) (xy 113.867633 -229.352199) (xy 113.851923 -229.403129)
			(xy 113.828797 -229.45115) (xy 113.798773 -229.495187) (xy 113.762521 -229.534258) (xy 113.72085 -229.567489)
			(xy 113.674692 -229.594138) (xy 113.625078 -229.61361) (xy 113.573116 -229.62547) (xy 113.519966 -229.629454)
			(xy 113.466816 -229.62547) (xy 113.414854 -229.61361) (xy 113.36524 -229.594138) (xy 113.319082 -229.567489)
			(xy 113.277411 -229.534258) (xy 113.241159 -229.495187) (xy 113.211135 -229.45115) (xy 113.188009 -229.403129)
			(xy 113.172299 -229.352199) (xy 113.164356 -229.299495) (xy 112.935776 -229.299495) (xy 112.927833 -229.352199)
			(xy 112.912123 -229.403129) (xy 112.888997 -229.45115) (xy 112.858973 -229.495187) (xy 112.822721 -229.534258)
			(xy 112.78105 -229.567489) (xy 112.734892 -229.594138) (xy 112.685278 -229.61361) (xy 112.633316 -229.62547)
			(xy 112.580166 -229.629454) (xy 112.527016 -229.62547) (xy 112.475054 -229.61361) (xy 112.42544 -229.594138)
			(xy 112.379282 -229.567489) (xy 112.337611 -229.534258) (xy 112.301359 -229.495187) (xy 112.271335 -229.45115)
			(xy 112.248209 -229.403129) (xy 112.232499 -229.352199) (xy 112.224556 -229.299495) (xy 111.995722 -229.299495)
			(xy 111.987779 -229.352199) (xy 111.972069 -229.403129) (xy 111.948943 -229.45115) (xy 111.918919 -229.495187)
			(xy 111.882667 -229.534258) (xy 111.840996 -229.567489) (xy 111.794838 -229.594138) (xy 111.745224 -229.61361)
			(xy 111.693262 -229.62547) (xy 111.640112 -229.629454) (xy 111.586962 -229.62547) (xy 111.535 -229.61361)
			(xy 111.485386 -229.594138) (xy 111.439228 -229.567489) (xy 111.397557 -229.534258) (xy 111.361305 -229.495187)
			(xy 111.331281 -229.45115) (xy 111.308155 -229.403129) (xy 111.292445 -229.352199) (xy 111.284502 -229.299495)
			(xy 111.056176 -229.299495) (xy 111.048233 -229.352199) (xy 111.032523 -229.403129) (xy 111.009397 -229.45115)
			(xy 110.979373 -229.495187) (xy 110.943121 -229.534258) (xy 110.90145 -229.567489) (xy 110.855292 -229.594138)
			(xy 110.805678 -229.61361) (xy 110.753716 -229.62547) (xy 110.700566 -229.629454) (xy 110.647416 -229.62547)
			(xy 110.595454 -229.61361) (xy 110.54584 -229.594138) (xy 110.499682 -229.567489) (xy 110.458011 -229.534258)
			(xy 110.421759 -229.495187) (xy 110.391735 -229.45115) (xy 110.368609 -229.403129) (xy 110.352899 -229.352199)
			(xy 110.344956 -229.299495) (xy 110.116376 -229.299495) (xy 110.108433 -229.352199) (xy 110.092723 -229.403129)
			(xy 110.069597 -229.45115) (xy 110.039573 -229.495187) (xy 110.003321 -229.534258) (xy 109.96165 -229.567489)
			(xy 109.915492 -229.594138) (xy 109.865878 -229.61361) (xy 109.813916 -229.62547) (xy 109.760766 -229.629454)
			(xy 109.707616 -229.62547) (xy 109.655654 -229.61361) (xy 109.60604 -229.594138) (xy 109.559882 -229.567489)
			(xy 109.518211 -229.534258) (xy 109.481959 -229.495187) (xy 109.451935 -229.45115) (xy 109.428809 -229.403129)
			(xy 109.413099 -229.352199) (xy 109.405156 -229.299495) (xy 109.176576 -229.299495) (xy 109.168633 -229.352199)
			(xy 109.152923 -229.403129) (xy 109.129797 -229.45115) (xy 109.099773 -229.495187) (xy 109.063521 -229.534258)
			(xy 109.02185 -229.567489) (xy 108.975692 -229.594138) (xy 108.926078 -229.61361) (xy 108.874116 -229.62547)
			(xy 108.820966 -229.629454) (xy 108.767816 -229.62547) (xy 108.715854 -229.61361) (xy 108.66624 -229.594138)
			(xy 108.620082 -229.567489) (xy 108.578411 -229.534258) (xy 108.542159 -229.495187) (xy 108.512135 -229.45115)
			(xy 108.489009 -229.403129) (xy 108.473299 -229.352199) (xy 108.465356 -229.299495) (xy 108.236776 -229.299495)
			(xy 108.228833 -229.352199) (xy 108.213123 -229.403129) (xy 108.189997 -229.45115) (xy 108.159973 -229.495187)
			(xy 108.123721 -229.534258) (xy 108.08205 -229.567489) (xy 108.035892 -229.594138) (xy 107.986278 -229.61361)
			(xy 107.934316 -229.62547) (xy 107.881166 -229.629454) (xy 107.828016 -229.62547) (xy 107.776054 -229.61361)
			(xy 107.72644 -229.594138) (xy 107.680282 -229.567489) (xy 107.638611 -229.534258) (xy 107.602359 -229.495187)
			(xy 107.572335 -229.45115) (xy 107.549209 -229.403129) (xy 107.533499 -229.352199) (xy 107.525556 -229.299495)
			(xy 107.296976 -229.299495) (xy 107.289033 -229.352199) (xy 107.273323 -229.403129) (xy 107.250197 -229.45115)
			(xy 107.220173 -229.495187) (xy 107.183921 -229.534258) (xy 107.14225 -229.567489) (xy 107.096092 -229.594138)
			(xy 107.046478 -229.61361) (xy 106.994516 -229.62547) (xy 106.941366 -229.629454) (xy 106.888216 -229.62547)
			(xy 106.836254 -229.61361) (xy 106.78664 -229.594138) (xy 106.740482 -229.567489) (xy 106.698811 -229.534258)
			(xy 106.662559 -229.495187) (xy 106.632535 -229.45115) (xy 106.609409 -229.403129) (xy 106.593699 -229.352199)
			(xy 106.585756 -229.299495) (xy 106.357176 -229.299495) (xy 106.349233 -229.352199) (xy 106.333523 -229.403129)
			(xy 106.310397 -229.45115) (xy 106.280373 -229.495187) (xy 106.244121 -229.534258) (xy 106.20245 -229.567489)
			(xy 106.156292 -229.594138) (xy 106.106678 -229.61361) (xy 106.054716 -229.62547) (xy 106.001566 -229.629454)
			(xy 105.948416 -229.62547) (xy 105.896454 -229.61361) (xy 105.84684 -229.594138) (xy 105.800682 -229.567489)
			(xy 105.759011 -229.534258) (xy 105.722759 -229.495187) (xy 105.692735 -229.45115) (xy 105.669609 -229.403129)
			(xy 105.653899 -229.352199) (xy 105.645956 -229.299495) (xy 105.417376 -229.299495) (xy 105.409433 -229.352199)
			(xy 105.393723 -229.403129) (xy 105.370597 -229.45115) (xy 105.340573 -229.495187) (xy 105.304321 -229.534258)
			(xy 105.26265 -229.567489) (xy 105.216492 -229.594138) (xy 105.166878 -229.61361) (xy 105.114916 -229.62547)
			(xy 105.061766 -229.629454) (xy 105.008616 -229.62547) (xy 104.956654 -229.61361) (xy 104.90704 -229.594138)
			(xy 104.860882 -229.567489) (xy 104.819211 -229.534258) (xy 104.782959 -229.495187) (xy 104.752935 -229.45115)
			(xy 104.729809 -229.403129) (xy 104.714099 -229.352199) (xy 104.706156 -229.299495) (xy 104.477576 -229.299495)
			(xy 104.469633 -229.352199) (xy 104.453923 -229.403129) (xy 104.430797 -229.45115) (xy 104.400773 -229.495187)
			(xy 104.364521 -229.534258) (xy 104.32285 -229.567489) (xy 104.276692 -229.594138) (xy 104.227078 -229.61361)
			(xy 104.175116 -229.62547) (xy 104.121966 -229.629454) (xy 104.068816 -229.62547) (xy 104.016854 -229.61361)
			(xy 103.96724 -229.594138) (xy 103.921082 -229.567489) (xy 103.879411 -229.534258) (xy 103.843159 -229.495187)
			(xy 103.813135 -229.45115) (xy 103.790009 -229.403129) (xy 103.774299 -229.352199) (xy 103.766356 -229.299495)
			(xy 103.537776 -229.299495) (xy 103.529833 -229.352199) (xy 103.514123 -229.403129) (xy 103.490997 -229.45115)
			(xy 103.460973 -229.495187) (xy 103.424721 -229.534258) (xy 103.38305 -229.567489) (xy 103.336892 -229.594138)
			(xy 103.287278 -229.61361) (xy 103.235316 -229.62547) (xy 103.182166 -229.629454) (xy 103.129016 -229.62547)
			(xy 103.077054 -229.61361) (xy 103.02744 -229.594138) (xy 102.981282 -229.567489) (xy 102.939611 -229.534258)
			(xy 102.903359 -229.495187) (xy 102.873335 -229.45115) (xy 102.850209 -229.403129) (xy 102.834499 -229.352199)
			(xy 102.826556 -229.299495) (xy 102.597976 -229.299495) (xy 102.590033 -229.352199) (xy 102.574323 -229.403129)
			(xy 102.551197 -229.45115) (xy 102.521173 -229.495187) (xy 102.484921 -229.534258) (xy 102.44325 -229.567489)
			(xy 102.397092 -229.594138) (xy 102.347478 -229.61361) (xy 102.295516 -229.62547) (xy 102.242366 -229.629454)
			(xy 102.189216 -229.62547) (xy 102.137254 -229.61361) (xy 102.08764 -229.594138) (xy 102.041482 -229.567489)
			(xy 101.999811 -229.534258) (xy 101.963559 -229.495187) (xy 101.933535 -229.45115) (xy 101.910409 -229.403129)
			(xy 101.894699 -229.352199) (xy 101.886756 -229.299495) (xy 101.657922 -229.299495) (xy 101.649979 -229.352199)
			(xy 101.634269 -229.403129) (xy 101.611143 -229.45115) (xy 101.581119 -229.495187) (xy 101.544867 -229.534258)
			(xy 101.503196 -229.567489) (xy 101.457038 -229.594138) (xy 101.407424 -229.61361) (xy 101.355462 -229.62547)
			(xy 101.302312 -229.629454) (xy 101.249162 -229.62547) (xy 101.1972 -229.61361) (xy 101.147586 -229.594138)
			(xy 101.101428 -229.567489) (xy 101.059757 -229.534258) (xy 101.023505 -229.495187) (xy 100.993481 -229.45115)
			(xy 100.970355 -229.403129) (xy 100.954645 -229.352199) (xy 100.946702 -229.299495) (xy 100.718376 -229.299495)
			(xy 100.710433 -229.352199) (xy 100.694723 -229.403129) (xy 100.671597 -229.45115) (xy 100.641573 -229.495187)
			(xy 100.605321 -229.534258) (xy 100.56365 -229.567489) (xy 100.517492 -229.594138) (xy 100.467878 -229.61361)
			(xy 100.415916 -229.62547) (xy 100.362766 -229.629454) (xy 100.309616 -229.62547) (xy 100.257654 -229.61361)
			(xy 100.20804 -229.594138) (xy 100.161882 -229.567489) (xy 100.120211 -229.534258) (xy 100.083959 -229.495187)
			(xy 100.053935 -229.45115) (xy 100.030809 -229.403129) (xy 100.015099 -229.352199) (xy 100.007156 -229.299495)
			(xy 99.778576 -229.299495) (xy 99.770633 -229.352199) (xy 99.754923 -229.403129) (xy 99.731797 -229.45115)
			(xy 99.701773 -229.495187) (xy 99.665521 -229.534258) (xy 99.62385 -229.567489) (xy 99.577692 -229.594138)
			(xy 99.528078 -229.61361) (xy 99.476116 -229.62547) (xy 99.422966 -229.629454) (xy 99.369816 -229.62547)
			(xy 99.317854 -229.61361) (xy 99.26824 -229.594138) (xy 99.222082 -229.567489) (xy 99.180411 -229.534258)
			(xy 99.144159 -229.495187) (xy 99.114135 -229.45115) (xy 99.091009 -229.403129) (xy 99.075299 -229.352199)
			(xy 99.067356 -229.299495) (xy 98.838776 -229.299495) (xy 98.830833 -229.352199) (xy 98.815123 -229.403129)
			(xy 98.791997 -229.45115) (xy 98.761973 -229.495187) (xy 98.725721 -229.534258) (xy 98.68405 -229.567489)
			(xy 98.637892 -229.594138) (xy 98.588278 -229.61361) (xy 98.536316 -229.62547) (xy 98.483166 -229.629454)
			(xy 98.430016 -229.62547) (xy 98.378054 -229.61361) (xy 98.32844 -229.594138) (xy 98.282282 -229.567489)
			(xy 98.240611 -229.534258) (xy 98.204359 -229.495187) (xy 98.174335 -229.45115) (xy 98.151209 -229.403129)
			(xy 98.135499 -229.352199) (xy 98.127556 -229.299495) (xy 97.898976 -229.299495) (xy 97.891033 -229.352199)
			(xy 97.875323 -229.403129) (xy 97.852197 -229.45115) (xy 97.822173 -229.495187) (xy 97.785921 -229.534258)
			(xy 97.74425 -229.567489) (xy 97.698092 -229.594138) (xy 97.648478 -229.61361) (xy 97.596516 -229.62547)
			(xy 97.543366 -229.629454) (xy 97.490216 -229.62547) (xy 97.438254 -229.61361) (xy 97.38864 -229.594138)
			(xy 97.342482 -229.567489) (xy 97.300811 -229.534258) (xy 97.264559 -229.495187) (xy 97.234535 -229.45115)
			(xy 97.211409 -229.403129) (xy 97.195699 -229.352199) (xy 97.187756 -229.299495) (xy 96.959176 -229.299495)
			(xy 96.951233 -229.352199) (xy 96.935523 -229.403129) (xy 96.912397 -229.45115) (xy 96.882373 -229.495187)
			(xy 96.846121 -229.534258) (xy 96.80445 -229.567489) (xy 96.758292 -229.594138) (xy 96.708678 -229.61361)
			(xy 96.656716 -229.62547) (xy 96.603566 -229.629454) (xy 96.550416 -229.62547) (xy 96.498454 -229.61361)
			(xy 96.44884 -229.594138) (xy 96.402682 -229.567489) (xy 96.361011 -229.534258) (xy 96.324759 -229.495187)
			(xy 96.294735 -229.45115) (xy 96.271609 -229.403129) (xy 96.255899 -229.352199) (xy 96.247956 -229.299495)
			(xy 96.019376 -229.299495) (xy 96.011433 -229.352199) (xy 95.995723 -229.403129) (xy 95.972597 -229.45115)
			(xy 95.942573 -229.495187) (xy 95.906321 -229.534258) (xy 95.86465 -229.567489) (xy 95.818492 -229.594138)
			(xy 95.768878 -229.61361) (xy 95.716916 -229.62547) (xy 95.663766 -229.629454) (xy 95.610616 -229.62547)
			(xy 95.558654 -229.61361) (xy 95.50904 -229.594138) (xy 95.462882 -229.567489) (xy 95.421211 -229.534258)
			(xy 95.384959 -229.495187) (xy 95.354935 -229.45115) (xy 95.331809 -229.403129) (xy 95.316099 -229.352199)
			(xy 95.308156 -229.299495) (xy 95.079322 -229.299495) (xy 95.071379 -229.352199) (xy 95.055669 -229.403129)
			(xy 95.032543 -229.45115) (xy 95.002519 -229.495187) (xy 94.966267 -229.534258) (xy 94.924596 -229.567489)
			(xy 94.878438 -229.594138) (xy 94.828824 -229.61361) (xy 94.776862 -229.62547) (xy 94.723712 -229.629454)
			(xy 94.670562 -229.62547) (xy 94.6186 -229.61361) (xy 94.568986 -229.594138) (xy 94.522828 -229.567489)
			(xy 94.481157 -229.534258) (xy 94.444905 -229.495187) (xy 94.414881 -229.45115) (xy 94.391755 -229.403129)
			(xy 94.376045 -229.352199) (xy 94.368102 -229.299495) (xy 94.139776 -229.299495) (xy 94.131833 -229.352199)
			(xy 94.116123 -229.403129) (xy 94.092997 -229.45115) (xy 94.062973 -229.495187) (xy 94.026721 -229.534258)
			(xy 93.98505 -229.567489) (xy 93.938892 -229.594138) (xy 93.889278 -229.61361) (xy 93.837316 -229.62547)
			(xy 93.784166 -229.629454) (xy 93.731016 -229.62547) (xy 93.679054 -229.61361) (xy 93.62944 -229.594138)
			(xy 93.583282 -229.567489) (xy 93.541611 -229.534258) (xy 93.505359 -229.495187) (xy 93.475335 -229.45115)
			(xy 93.452209 -229.403129) (xy 93.436499 -229.352199) (xy 93.428556 -229.299495) (xy 93.199976 -229.299495)
			(xy 93.192033 -229.352199) (xy 93.176323 -229.403129) (xy 93.153197 -229.45115) (xy 93.123173 -229.495187)
			(xy 93.086921 -229.534258) (xy 93.04525 -229.567489) (xy 92.999092 -229.594138) (xy 92.949478 -229.61361)
			(xy 92.897516 -229.62547) (xy 92.844366 -229.629454) (xy 92.791216 -229.62547) (xy 92.739254 -229.61361)
			(xy 92.68964 -229.594138) (xy 92.643482 -229.567489) (xy 92.601811 -229.534258) (xy 92.565559 -229.495187)
			(xy 92.535535 -229.45115) (xy 92.512409 -229.403129) (xy 92.496699 -229.352199) (xy 92.488756 -229.299495)
			(xy 92.260176 -229.299495) (xy 92.252233 -229.352199) (xy 92.236523 -229.403129) (xy 92.213397 -229.45115)
			(xy 92.183373 -229.495187) (xy 92.147121 -229.534258) (xy 92.10545 -229.567489) (xy 92.059292 -229.594138)
			(xy 92.009678 -229.61361) (xy 91.957716 -229.62547) (xy 91.904566 -229.629454) (xy 91.851416 -229.62547)
			(xy 91.799454 -229.61361) (xy 91.74984 -229.594138) (xy 91.703682 -229.567489) (xy 91.662011 -229.534258)
			(xy 91.625759 -229.495187) (xy 91.595735 -229.45115) (xy 91.572609 -229.403129) (xy 91.556899 -229.352199)
			(xy 91.548956 -229.299495) (xy 91.320376 -229.299495) (xy 91.312433 -229.352199) (xy 91.296723 -229.403129)
			(xy 91.273597 -229.45115) (xy 91.243573 -229.495187) (xy 91.207321 -229.534258) (xy 91.16565 -229.567489)
			(xy 91.119492 -229.594138) (xy 91.069878 -229.61361) (xy 91.017916 -229.62547) (xy 90.964766 -229.629454)
			(xy 90.911616 -229.62547) (xy 90.859654 -229.61361) (xy 90.81004 -229.594138) (xy 90.763882 -229.567489)
			(xy 90.722211 -229.534258) (xy 90.685959 -229.495187) (xy 90.655935 -229.45115) (xy 90.632809 -229.403129)
			(xy 90.617099 -229.352199) (xy 90.609156 -229.299495) (xy 90.380576 -229.299495) (xy 90.372633 -229.352199)
			(xy 90.356923 -229.403129) (xy 90.333797 -229.45115) (xy 90.303773 -229.495187) (xy 90.267521 -229.534258)
			(xy 90.22585 -229.567489) (xy 90.179692 -229.594138) (xy 90.130078 -229.61361) (xy 90.078116 -229.62547)
			(xy 90.024966 -229.629454) (xy 89.971816 -229.62547) (xy 89.919854 -229.61361) (xy 89.87024 -229.594138)
			(xy 89.824082 -229.567489) (xy 89.782411 -229.534258) (xy 89.746159 -229.495187) (xy 89.716135 -229.45115)
			(xy 89.693009 -229.403129) (xy 89.677299 -229.352199) (xy 89.669356 -229.299495) (xy 89.439786 -229.299495)
			(xy 89.437803 -229.32595) (xy 89.425942 -229.377912) (xy 89.406469 -229.427526) (xy 89.379818 -229.473683)
			(xy 89.346585 -229.515352) (xy 89.307513 -229.551602) (xy 89.263473 -229.581624) (xy 89.215451 -229.604746)
			(xy 89.164519 -229.620452) (xy 89.111815 -229.628391) (xy 89.085166 -229.628954) (xy 89.060205 -229.628533)
			(xy 89.010772 -229.621563) (xy 88.962796 -229.607763) (xy 88.917214 -229.587405) (xy 88.874918 -229.560885)
			(xy 88.85555 -229.545134) (xy 88.844193 -229.536197) (xy 88.81779 -229.524479) (xy 88.789163 -229.520627)
			(xy 88.760602 -229.524949) (xy 88.734395 -229.537098) (xy 88.712641 -229.556102) (xy 88.697082 -229.58044)
			(xy 88.688964 -229.608162) (xy 88.688418 -229.622604) (xy 88.688418 -229.736142) (xy 88.723724 -229.747572)
			(xy 88.748735 -229.756095) (xy 88.796115 -229.779484) (xy 88.83952 -229.809616) (xy 88.877996 -229.845831)
			(xy 88.910698 -229.887333) (xy 88.93691 -229.933211) (xy 88.956055 -229.982459) (xy 88.967714 -230.033995)
			(xy 88.97163 -230.086688) (xy 88.969653 -230.113311) (xy 89.199202 -230.113311) (xy 89.199202 -230.060013)
			(xy 89.207145 -230.007309) (xy 89.222855 -229.956379) (xy 89.245981 -229.908358) (xy 89.276005 -229.864321)
			(xy 89.312257 -229.82525) (xy 89.353928 -229.792019) (xy 89.400086 -229.76537) (xy 89.4497 -229.745898)
			(xy 89.501662 -229.734038) (xy 89.554812 -229.730055) (xy 89.607962 -229.734038) (xy 89.659924 -229.745898)
			(xy 89.709538 -229.76537) (xy 89.755696 -229.792019) (xy 89.797367 -229.82525) (xy 89.833619 -229.864321)
			(xy 89.863643 -229.908358) (xy 89.886769 -229.956379) (xy 89.902479 -230.007309) (xy 89.910422 -230.060013)
			(xy 89.91092 -230.086662) (xy 89.910422 -230.113311) (xy 90.139002 -230.113311) (xy 90.139002 -230.060013)
			(xy 90.146945 -230.007309) (xy 90.162655 -229.956379) (xy 90.185781 -229.908358) (xy 90.215805 -229.864321)
			(xy 90.252057 -229.82525) (xy 90.293728 -229.792019) (xy 90.339886 -229.76537) (xy 90.3895 -229.745898)
			(xy 90.441462 -229.734038) (xy 90.494612 -229.730055) (xy 90.547762 -229.734038) (xy 90.599724 -229.745898)
			(xy 90.649338 -229.76537) (xy 90.695496 -229.792019) (xy 90.737167 -229.82525) (xy 90.773419 -229.864321)
			(xy 90.803443 -229.908358) (xy 90.826569 -229.956379) (xy 90.842279 -230.007309) (xy 90.850222 -230.060013)
			(xy 90.85072 -230.086662) (xy 90.850222 -230.113311) (xy 91.078802 -230.113311) (xy 91.078802 -230.060013)
			(xy 91.086745 -230.007309) (xy 91.102455 -229.956379) (xy 91.125581 -229.908358) (xy 91.155605 -229.864321)
			(xy 91.191857 -229.82525) (xy 91.233528 -229.792019) (xy 91.279686 -229.76537) (xy 91.3293 -229.745898)
			(xy 91.381262 -229.734038) (xy 91.434412 -229.730055) (xy 91.487562 -229.734038) (xy 91.539524 -229.745898)
			(xy 91.589138 -229.76537) (xy 91.635296 -229.792019) (xy 91.676967 -229.82525) (xy 91.713219 -229.864321)
			(xy 91.743243 -229.908358) (xy 91.766369 -229.956379) (xy 91.782079 -230.007309) (xy 91.790022 -230.060013)
			(xy 91.79052 -230.086662) (xy 91.790022 -230.113311) (xy 92.018602 -230.113311) (xy 92.018602 -230.060013)
			(xy 92.026545 -230.007309) (xy 92.042255 -229.956379) (xy 92.065381 -229.908358) (xy 92.095405 -229.864321)
			(xy 92.131657 -229.82525) (xy 92.173328 -229.792019) (xy 92.219486 -229.76537) (xy 92.2691 -229.745898)
			(xy 92.321062 -229.734038) (xy 92.374212 -229.730055) (xy 92.427362 -229.734038) (xy 92.479324 -229.745898)
			(xy 92.528938 -229.76537) (xy 92.575096 -229.792019) (xy 92.616767 -229.82525) (xy 92.653019 -229.864321)
			(xy 92.683043 -229.908358) (xy 92.706169 -229.956379) (xy 92.721879 -230.007309) (xy 92.729822 -230.060013)
			(xy 92.73032 -230.086662) (xy 92.729822 -230.113311) (xy 92.958402 -230.113311) (xy 92.958402 -230.060013)
			(xy 92.966345 -230.007309) (xy 92.982055 -229.956379) (xy 93.005181 -229.908358) (xy 93.035205 -229.864321)
			(xy 93.071457 -229.82525) (xy 93.113128 -229.792019) (xy 93.159286 -229.76537) (xy 93.2089 -229.745898)
			(xy 93.260862 -229.734038) (xy 93.314012 -229.730055) (xy 93.367162 -229.734038) (xy 93.419124 -229.745898)
			(xy 93.468738 -229.76537) (xy 93.514896 -229.792019) (xy 93.556567 -229.82525) (xy 93.592819 -229.864321)
			(xy 93.622843 -229.908358) (xy 93.645969 -229.956379) (xy 93.661679 -230.007309) (xy 93.669622 -230.060013)
			(xy 93.67012 -230.086662) (xy 93.669622 -230.113311) (xy 93.898202 -230.113311) (xy 93.898202 -230.060013)
			(xy 93.906145 -230.007309) (xy 93.921855 -229.956379) (xy 93.944981 -229.908358) (xy 93.975005 -229.864321)
			(xy 94.011257 -229.82525) (xy 94.052928 -229.792019) (xy 94.099086 -229.76537) (xy 94.1487 -229.745898)
			(xy 94.200662 -229.734038) (xy 94.253812 -229.730055) (xy 94.306962 -229.734038) (xy 94.358924 -229.745898)
			(xy 94.408538 -229.76537) (xy 94.454696 -229.792019) (xy 94.496367 -229.82525) (xy 94.532619 -229.864321)
			(xy 94.562643 -229.908358) (xy 94.585769 -229.956379) (xy 94.601479 -230.007309) (xy 94.609422 -230.060013)
			(xy 94.60992 -230.086662) (xy 94.609422 -230.113311) (xy 94.838002 -230.113311) (xy 94.838002 -230.060013)
			(xy 94.845945 -230.007309) (xy 94.861655 -229.956379) (xy 94.884781 -229.908358) (xy 94.914805 -229.864321)
			(xy 94.951057 -229.82525) (xy 94.992728 -229.792019) (xy 95.038886 -229.76537) (xy 95.0885 -229.745898)
			(xy 95.140462 -229.734038) (xy 95.193612 -229.730055) (xy 95.246762 -229.734038) (xy 95.298724 -229.745898)
			(xy 95.348338 -229.76537) (xy 95.394496 -229.792019) (xy 95.436167 -229.82525) (xy 95.472419 -229.864321)
			(xy 95.502443 -229.908358) (xy 95.525569 -229.956379) (xy 95.541279 -230.007309) (xy 95.549222 -230.060013)
			(xy 95.54972 -230.086662) (xy 95.549222 -230.113311) (xy 95.777802 -230.113311) (xy 95.777802 -230.060013)
			(xy 95.785745 -230.007309) (xy 95.801455 -229.956379) (xy 95.824581 -229.908358) (xy 95.854605 -229.864321)
			(xy 95.890857 -229.82525) (xy 95.932528 -229.792019) (xy 95.978686 -229.76537) (xy 96.0283 -229.745898)
			(xy 96.080262 -229.734038) (xy 96.133412 -229.730055) (xy 96.186562 -229.734038) (xy 96.238524 -229.745898)
			(xy 96.288138 -229.76537) (xy 96.334296 -229.792019) (xy 96.375967 -229.82525) (xy 96.412219 -229.864321)
			(xy 96.442243 -229.908358) (xy 96.465369 -229.956379) (xy 96.481079 -230.007309) (xy 96.489022 -230.060013)
			(xy 96.48952 -230.086662) (xy 96.489022 -230.113311) (xy 96.717856 -230.113311) (xy 96.717856 -230.060013)
			(xy 96.725799 -230.007309) (xy 96.741509 -229.956379) (xy 96.764635 -229.908358) (xy 96.794659 -229.864321)
			(xy 96.830911 -229.82525) (xy 96.872582 -229.792019) (xy 96.91874 -229.76537) (xy 96.968354 -229.745898)
			(xy 97.020316 -229.734038) (xy 97.073466 -229.730055) (xy 97.126616 -229.734038) (xy 97.178578 -229.745898)
			(xy 97.228192 -229.76537) (xy 97.27435 -229.792019) (xy 97.316021 -229.82525) (xy 97.352273 -229.864321)
			(xy 97.382297 -229.908358) (xy 97.405423 -229.956379) (xy 97.421133 -230.007309) (xy 97.429076 -230.060013)
			(xy 97.429574 -230.086662) (xy 97.429076 -230.113311) (xy 97.657402 -230.113311) (xy 97.657402 -230.060013)
			(xy 97.665345 -230.007309) (xy 97.681055 -229.956379) (xy 97.704181 -229.908358) (xy 97.734205 -229.864321)
			(xy 97.770457 -229.82525) (xy 97.812128 -229.792019) (xy 97.858286 -229.76537) (xy 97.9079 -229.745898)
			(xy 97.959862 -229.734038) (xy 98.013012 -229.730055) (xy 98.066162 -229.734038) (xy 98.118124 -229.745898)
			(xy 98.167738 -229.76537) (xy 98.213896 -229.792019) (xy 98.255567 -229.82525) (xy 98.291819 -229.864321)
			(xy 98.321843 -229.908358) (xy 98.344969 -229.956379) (xy 98.360679 -230.007309) (xy 98.368622 -230.060013)
			(xy 98.36912 -230.086662) (xy 98.368622 -230.113311) (xy 98.597202 -230.113311) (xy 98.597202 -230.060013)
			(xy 98.605145 -230.007309) (xy 98.620855 -229.956379) (xy 98.643981 -229.908358) (xy 98.674005 -229.864321)
			(xy 98.710257 -229.82525) (xy 98.751928 -229.792019) (xy 98.798086 -229.76537) (xy 98.8477 -229.745898)
			(xy 98.899662 -229.734038) (xy 98.952812 -229.730055) (xy 99.005962 -229.734038) (xy 99.057924 -229.745898)
			(xy 99.107538 -229.76537) (xy 99.153696 -229.792019) (xy 99.195367 -229.82525) (xy 99.231619 -229.864321)
			(xy 99.261643 -229.908358) (xy 99.284769 -229.956379) (xy 99.300479 -230.007309) (xy 99.308422 -230.060013)
			(xy 99.30892 -230.086662) (xy 99.308422 -230.113311) (xy 99.537002 -230.113311) (xy 99.537002 -230.060013)
			(xy 99.544945 -230.007309) (xy 99.560655 -229.956379) (xy 99.583781 -229.908358) (xy 99.613805 -229.864321)
			(xy 99.650057 -229.82525) (xy 99.691728 -229.792019) (xy 99.737886 -229.76537) (xy 99.7875 -229.745898)
			(xy 99.839462 -229.734038) (xy 99.892612 -229.730055) (xy 99.945762 -229.734038) (xy 99.997724 -229.745898)
			(xy 100.047338 -229.76537) (xy 100.093496 -229.792019) (xy 100.135167 -229.82525) (xy 100.171419 -229.864321)
			(xy 100.201443 -229.908358) (xy 100.224569 -229.956379) (xy 100.240279 -230.007309) (xy 100.248222 -230.060013)
			(xy 100.24872 -230.086662) (xy 100.248222 -230.113311) (xy 100.476802 -230.113311) (xy 100.476802 -230.060013)
			(xy 100.484745 -230.007309) (xy 100.500455 -229.956379) (xy 100.523581 -229.908358) (xy 100.553605 -229.864321)
			(xy 100.589857 -229.82525) (xy 100.631528 -229.792019) (xy 100.677686 -229.76537) (xy 100.7273 -229.745898)
			(xy 100.779262 -229.734038) (xy 100.832412 -229.730055) (xy 100.885562 -229.734038) (xy 100.937524 -229.745898)
			(xy 100.987138 -229.76537) (xy 101.033296 -229.792019) (xy 101.074967 -229.82525) (xy 101.111219 -229.864321)
			(xy 101.141243 -229.908358) (xy 101.164369 -229.956379) (xy 101.180079 -230.007309) (xy 101.188022 -230.060013)
			(xy 101.18852 -230.086662) (xy 101.188022 -230.113311) (xy 101.416602 -230.113311) (xy 101.416602 -230.060013)
			(xy 101.424545 -230.007309) (xy 101.440255 -229.956379) (xy 101.463381 -229.908358) (xy 101.493405 -229.864321)
			(xy 101.529657 -229.82525) (xy 101.571328 -229.792019) (xy 101.617486 -229.76537) (xy 101.6671 -229.745898)
			(xy 101.719062 -229.734038) (xy 101.772212 -229.730055) (xy 101.825362 -229.734038) (xy 101.877324 -229.745898)
			(xy 101.926938 -229.76537) (xy 101.973096 -229.792019) (xy 102.014767 -229.82525) (xy 102.051019 -229.864321)
			(xy 102.081043 -229.908358) (xy 102.104169 -229.956379) (xy 102.119879 -230.007309) (xy 102.127822 -230.060013)
			(xy 102.12832 -230.086662) (xy 102.127822 -230.113311) (xy 102.356402 -230.113311) (xy 102.356402 -230.060013)
			(xy 102.364345 -230.007309) (xy 102.380055 -229.956379) (xy 102.403181 -229.908358) (xy 102.433205 -229.864321)
			(xy 102.469457 -229.82525) (xy 102.511128 -229.792019) (xy 102.557286 -229.76537) (xy 102.6069 -229.745898)
			(xy 102.658862 -229.734038) (xy 102.712012 -229.730055) (xy 102.765162 -229.734038) (xy 102.817124 -229.745898)
			(xy 102.866738 -229.76537) (xy 102.912896 -229.792019) (xy 102.954567 -229.82525) (xy 102.990819 -229.864321)
			(xy 103.020843 -229.908358) (xy 103.043969 -229.956379) (xy 103.059679 -230.007309) (xy 103.067622 -230.060013)
			(xy 103.06812 -230.086662) (xy 103.067622 -230.113311) (xy 103.296202 -230.113311) (xy 103.296202 -230.060013)
			(xy 103.304145 -230.007309) (xy 103.319855 -229.956379) (xy 103.342981 -229.908358) (xy 103.373005 -229.864321)
			(xy 103.409257 -229.82525) (xy 103.450928 -229.792019) (xy 103.497086 -229.76537) (xy 103.5467 -229.745898)
			(xy 103.598662 -229.734038) (xy 103.651812 -229.730055) (xy 103.704962 -229.734038) (xy 103.756924 -229.745898)
			(xy 103.806538 -229.76537) (xy 103.852696 -229.792019) (xy 103.894367 -229.82525) (xy 103.930619 -229.864321)
			(xy 103.960643 -229.908358) (xy 103.983769 -229.956379) (xy 103.999479 -230.007309) (xy 104.007422 -230.060013)
			(xy 104.00792 -230.086662) (xy 104.007422 -230.113311) (xy 104.236002 -230.113311) (xy 104.236002 -230.060013)
			(xy 104.243945 -230.007309) (xy 104.259655 -229.956379) (xy 104.282781 -229.908358) (xy 104.312805 -229.864321)
			(xy 104.349057 -229.82525) (xy 104.390728 -229.792019) (xy 104.436886 -229.76537) (xy 104.4865 -229.745898)
			(xy 104.538462 -229.734038) (xy 104.591612 -229.730055) (xy 104.644762 -229.734038) (xy 104.696724 -229.745898)
			(xy 104.746338 -229.76537) (xy 104.792496 -229.792019) (xy 104.834167 -229.82525) (xy 104.870419 -229.864321)
			(xy 104.900443 -229.908358) (xy 104.923569 -229.956379) (xy 104.939279 -230.007309) (xy 104.947222 -230.060013)
			(xy 104.94772 -230.086662) (xy 104.947222 -230.113311) (xy 105.175802 -230.113311) (xy 105.175802 -230.060013)
			(xy 105.183745 -230.007309) (xy 105.199455 -229.956379) (xy 105.222581 -229.908358) (xy 105.252605 -229.864321)
			(xy 105.288857 -229.82525) (xy 105.330528 -229.792019) (xy 105.376686 -229.76537) (xy 105.4263 -229.745898)
			(xy 105.478262 -229.734038) (xy 105.531412 -229.730055) (xy 105.584562 -229.734038) (xy 105.636524 -229.745898)
			(xy 105.686138 -229.76537) (xy 105.732296 -229.792019) (xy 105.773967 -229.82525) (xy 105.810219 -229.864321)
			(xy 105.840243 -229.908358) (xy 105.863369 -229.956379) (xy 105.879079 -230.007309) (xy 105.887022 -230.060013)
			(xy 105.88752 -230.086662) (xy 105.887022 -230.113311) (xy 106.115856 -230.113311) (xy 106.115856 -230.060013)
			(xy 106.123799 -230.007309) (xy 106.139509 -229.956379) (xy 106.162635 -229.908358) (xy 106.192659 -229.864321)
			(xy 106.228911 -229.82525) (xy 106.270582 -229.792019) (xy 106.31674 -229.76537) (xy 106.366354 -229.745898)
			(xy 106.418316 -229.734038) (xy 106.471466 -229.730055) (xy 106.524616 -229.734038) (xy 106.576578 -229.745898)
			(xy 106.626192 -229.76537) (xy 106.67235 -229.792019) (xy 106.714021 -229.82525) (xy 106.750273 -229.864321)
			(xy 106.780297 -229.908358) (xy 106.803423 -229.956379) (xy 106.819133 -230.007309) (xy 106.827076 -230.060013)
			(xy 106.827574 -230.086662) (xy 106.827076 -230.113311) (xy 107.055402 -230.113311) (xy 107.055402 -230.060013)
			(xy 107.063345 -230.007309) (xy 107.079055 -229.956379) (xy 107.102181 -229.908358) (xy 107.132205 -229.864321)
			(xy 107.168457 -229.82525) (xy 107.210128 -229.792019) (xy 107.256286 -229.76537) (xy 107.3059 -229.745898)
			(xy 107.357862 -229.734038) (xy 107.411012 -229.730055) (xy 107.464162 -229.734038) (xy 107.516124 -229.745898)
			(xy 107.565738 -229.76537) (xy 107.611896 -229.792019) (xy 107.653567 -229.82525) (xy 107.689819 -229.864321)
			(xy 107.719843 -229.908358) (xy 107.742969 -229.956379) (xy 107.758679 -230.007309) (xy 107.766622 -230.060013)
			(xy 107.76712 -230.086662) (xy 107.766622 -230.113311) (xy 107.995202 -230.113311) (xy 107.995202 -230.060013)
			(xy 108.003145 -230.007309) (xy 108.018855 -229.956379) (xy 108.041981 -229.908358) (xy 108.072005 -229.864321)
			(xy 108.108257 -229.82525) (xy 108.149928 -229.792019) (xy 108.196086 -229.76537) (xy 108.2457 -229.745898)
			(xy 108.297662 -229.734038) (xy 108.350812 -229.730055) (xy 108.403962 -229.734038) (xy 108.455924 -229.745898)
			(xy 108.505538 -229.76537) (xy 108.551696 -229.792019) (xy 108.593367 -229.82525) (xy 108.629619 -229.864321)
			(xy 108.659643 -229.908358) (xy 108.682769 -229.956379) (xy 108.698479 -230.007309) (xy 108.706422 -230.060013)
			(xy 108.70692 -230.086662) (xy 108.706422 -230.113311) (xy 108.935002 -230.113311) (xy 108.935002 -230.060013)
			(xy 108.942945 -230.007309) (xy 108.958655 -229.956379) (xy 108.981781 -229.908358) (xy 109.011805 -229.864321)
			(xy 109.048057 -229.82525) (xy 109.089728 -229.792019) (xy 109.135886 -229.76537) (xy 109.1855 -229.745898)
			(xy 109.237462 -229.734038) (xy 109.290612 -229.730055) (xy 109.343762 -229.734038) (xy 109.395724 -229.745898)
			(xy 109.445338 -229.76537) (xy 109.491496 -229.792019) (xy 109.533167 -229.82525) (xy 109.569419 -229.864321)
			(xy 109.599443 -229.908358) (xy 109.622569 -229.956379) (xy 109.638279 -230.007309) (xy 109.646222 -230.060013)
			(xy 109.64672 -230.086662) (xy 109.646222 -230.113311) (xy 109.874802 -230.113311) (xy 109.874802 -230.060013)
			(xy 109.882745 -230.007309) (xy 109.898455 -229.956379) (xy 109.921581 -229.908358) (xy 109.951605 -229.864321)
			(xy 109.987857 -229.82525) (xy 110.029528 -229.792019) (xy 110.075686 -229.76537) (xy 110.1253 -229.745898)
			(xy 110.177262 -229.734038) (xy 110.230412 -229.730055) (xy 110.283562 -229.734038) (xy 110.335524 -229.745898)
			(xy 110.385138 -229.76537) (xy 110.431296 -229.792019) (xy 110.472967 -229.82525) (xy 110.509219 -229.864321)
			(xy 110.539243 -229.908358) (xy 110.562369 -229.956379) (xy 110.578079 -230.007309) (xy 110.586022 -230.060013)
			(xy 110.58652 -230.086662) (xy 110.586022 -230.113311) (xy 110.814856 -230.113311) (xy 110.814856 -230.060013)
			(xy 110.822799 -230.007309) (xy 110.838509 -229.956379) (xy 110.861635 -229.908358) (xy 110.891659 -229.864321)
			(xy 110.927911 -229.82525) (xy 110.969582 -229.792019) (xy 111.01574 -229.76537) (xy 111.065354 -229.745898)
			(xy 111.117316 -229.734038) (xy 111.170466 -229.730055) (xy 111.223616 -229.734038) (xy 111.275578 -229.745898)
			(xy 111.325192 -229.76537) (xy 111.37135 -229.792019) (xy 111.413021 -229.82525) (xy 111.449273 -229.864321)
			(xy 111.479297 -229.908358) (xy 111.502423 -229.956379) (xy 111.518133 -230.007309) (xy 111.526076 -230.060013)
			(xy 111.526574 -230.086662) (xy 111.526076 -230.113311) (xy 111.754656 -230.113311) (xy 111.754656 -230.060013)
			(xy 111.762599 -230.007309) (xy 111.778309 -229.956379) (xy 111.801435 -229.908358) (xy 111.831459 -229.864321)
			(xy 111.867711 -229.82525) (xy 111.909382 -229.792019) (xy 111.95554 -229.76537) (xy 112.005154 -229.745898)
			(xy 112.057116 -229.734038) (xy 112.110266 -229.730055) (xy 112.163416 -229.734038) (xy 112.215378 -229.745898)
			(xy 112.264992 -229.76537) (xy 112.31115 -229.792019) (xy 112.352821 -229.82525) (xy 112.389073 -229.864321)
			(xy 112.419097 -229.908358) (xy 112.442223 -229.956379) (xy 112.457933 -230.007309) (xy 112.465876 -230.060013)
			(xy 112.466374 -230.086662) (xy 112.465876 -230.113311) (xy 112.694456 -230.113311) (xy 112.694456 -230.060013)
			(xy 112.702399 -230.007309) (xy 112.718109 -229.956379) (xy 112.741235 -229.908358) (xy 112.771259 -229.864321)
			(xy 112.807511 -229.82525) (xy 112.849182 -229.792019) (xy 112.89534 -229.76537) (xy 112.944954 -229.745898)
			(xy 112.996916 -229.734038) (xy 113.050066 -229.730055) (xy 113.103216 -229.734038) (xy 113.155178 -229.745898)
			(xy 113.204792 -229.76537) (xy 113.25095 -229.792019) (xy 113.292621 -229.82525) (xy 113.328873 -229.864321)
			(xy 113.358897 -229.908358) (xy 113.382023 -229.956379) (xy 113.397733 -230.007309) (xy 113.405676 -230.060013)
			(xy 113.406174 -230.086662) (xy 113.405676 -230.113311) (xy 113.634256 -230.113311) (xy 113.634256 -230.060013)
			(xy 113.642199 -230.007309) (xy 113.657909 -229.956379) (xy 113.681035 -229.908358) (xy 113.711059 -229.864321)
			(xy 113.747311 -229.82525) (xy 113.788982 -229.792019) (xy 113.83514 -229.76537) (xy 113.884754 -229.745898)
			(xy 113.936716 -229.734038) (xy 113.989866 -229.730055) (xy 114.043016 -229.734038) (xy 114.094978 -229.745898)
			(xy 114.144592 -229.76537) (xy 114.19075 -229.792019) (xy 114.232421 -229.82525) (xy 114.268673 -229.864321)
			(xy 114.298697 -229.908358) (xy 114.321823 -229.956379) (xy 114.337533 -230.007309) (xy 114.345476 -230.060013)
			(xy 114.345974 -230.086662) (xy 114.345476 -230.113311) (xy 114.574056 -230.113311) (xy 114.574056 -230.060013)
			(xy 114.581999 -230.007309) (xy 114.597709 -229.956379) (xy 114.620835 -229.908358) (xy 114.650859 -229.864321)
			(xy 114.687111 -229.82525) (xy 114.728782 -229.792019) (xy 114.77494 -229.76537) (xy 114.824554 -229.745898)
			(xy 114.876516 -229.734038) (xy 114.929666 -229.730055) (xy 114.982816 -229.734038) (xy 115.034778 -229.745898)
			(xy 115.084392 -229.76537) (xy 115.13055 -229.792019) (xy 115.172221 -229.82525) (xy 115.208473 -229.864321)
			(xy 115.238497 -229.908358) (xy 115.261623 -229.956379) (xy 115.277333 -230.007309) (xy 115.285276 -230.060013)
			(xy 115.285774 -230.086662) (xy 115.285276 -230.113311) (xy 115.513602 -230.113311) (xy 115.513602 -230.060013)
			(xy 115.521545 -230.007309) (xy 115.537255 -229.956379) (xy 115.560381 -229.908358) (xy 115.590405 -229.864321)
			(xy 115.626657 -229.82525) (xy 115.668328 -229.792019) (xy 115.714486 -229.76537) (xy 115.7641 -229.745898)
			(xy 115.816062 -229.734038) (xy 115.869212 -229.730055) (xy 115.922362 -229.734038) (xy 115.974324 -229.745898)
			(xy 116.023938 -229.76537) (xy 116.070096 -229.792019) (xy 116.111767 -229.82525) (xy 116.148019 -229.864321)
			(xy 116.178043 -229.908358) (xy 116.201169 -229.956379) (xy 116.216879 -230.007309) (xy 116.224822 -230.060013)
			(xy 116.22532 -230.086662) (xy 116.224822 -230.113311) (xy 116.453402 -230.113311) (xy 116.453402 -230.060013)
			(xy 116.461345 -230.007309) (xy 116.477055 -229.956379) (xy 116.500181 -229.908358) (xy 116.530205 -229.864321)
			(xy 116.566457 -229.82525) (xy 116.608128 -229.792019) (xy 116.654286 -229.76537) (xy 116.7039 -229.745898)
			(xy 116.755862 -229.734038) (xy 116.809012 -229.730055) (xy 116.862162 -229.734038) (xy 116.914124 -229.745898)
			(xy 116.963738 -229.76537) (xy 117.009896 -229.792019) (xy 117.051567 -229.82525) (xy 117.087819 -229.864321)
			(xy 117.117843 -229.908358) (xy 117.140969 -229.956379) (xy 117.156679 -230.007309) (xy 117.164622 -230.060013)
			(xy 117.16512 -230.086662) (xy 117.164622 -230.113311) (xy 117.393202 -230.113311) (xy 117.393202 -230.060013)
			(xy 117.401145 -230.007309) (xy 117.416855 -229.956379) (xy 117.439981 -229.908358) (xy 117.470005 -229.864321)
			(xy 117.506257 -229.82525) (xy 117.547928 -229.792019) (xy 117.594086 -229.76537) (xy 117.6437 -229.745898)
			(xy 117.695662 -229.734038) (xy 117.748812 -229.730055) (xy 117.801962 -229.734038) (xy 117.853924 -229.745898)
			(xy 117.903538 -229.76537) (xy 117.949696 -229.792019) (xy 117.991367 -229.82525) (xy 118.027619 -229.864321)
			(xy 118.057643 -229.908358) (xy 118.080769 -229.956379) (xy 118.096479 -230.007309) (xy 118.104422 -230.060013)
			(xy 118.10492 -230.086662) (xy 118.104422 -230.113311) (xy 118.333002 -230.113311) (xy 118.333002 -230.060013)
			(xy 118.340945 -230.007309) (xy 118.356655 -229.956379) (xy 118.379781 -229.908358) (xy 118.409805 -229.864321)
			(xy 118.446057 -229.82525) (xy 118.487728 -229.792019) (xy 118.533886 -229.76537) (xy 118.5835 -229.745898)
			(xy 118.635462 -229.734038) (xy 118.688612 -229.730055) (xy 118.741762 -229.734038) (xy 118.793724 -229.745898)
			(xy 118.843338 -229.76537) (xy 118.889496 -229.792019) (xy 118.931167 -229.82525) (xy 118.967419 -229.864321)
			(xy 118.997443 -229.908358) (xy 119.020569 -229.956379) (xy 119.036279 -230.007309) (xy 119.044222 -230.060013)
			(xy 119.04472 -230.086662) (xy 119.044222 -230.113311) (xy 119.272802 -230.113311) (xy 119.272802 -230.060013)
			(xy 119.280745 -230.007309) (xy 119.296455 -229.956379) (xy 119.319581 -229.908358) (xy 119.349605 -229.864321)
			(xy 119.385857 -229.82525) (xy 119.427528 -229.792019) (xy 119.473686 -229.76537) (xy 119.5233 -229.745898)
			(xy 119.575262 -229.734038) (xy 119.628412 -229.730055) (xy 119.681562 -229.734038) (xy 119.733524 -229.745898)
			(xy 119.783138 -229.76537) (xy 119.829296 -229.792019) (xy 119.870967 -229.82525) (xy 119.907219 -229.864321)
			(xy 119.937243 -229.908358) (xy 119.960369 -229.956379) (xy 119.976079 -230.007309) (xy 119.984022 -230.060013)
			(xy 119.98452 -230.086662) (xy 119.984022 -230.113311) (xy 120.212602 -230.113311) (xy 120.212602 -230.060013)
			(xy 120.220545 -230.007309) (xy 120.236255 -229.956379) (xy 120.259381 -229.908358) (xy 120.289405 -229.864321)
			(xy 120.325657 -229.82525) (xy 120.367328 -229.792019) (xy 120.413486 -229.76537) (xy 120.4631 -229.745898)
			(xy 120.515062 -229.734038) (xy 120.568212 -229.730055) (xy 120.621362 -229.734038) (xy 120.673324 -229.745898)
			(xy 120.722938 -229.76537) (xy 120.769096 -229.792019) (xy 120.810767 -229.82525) (xy 120.847019 -229.864321)
			(xy 120.877043 -229.908358) (xy 120.900169 -229.956379) (xy 120.915879 -230.007309) (xy 120.923822 -230.060013)
			(xy 120.92432 -230.086662) (xy 120.923822 -230.113311) (xy 121.152402 -230.113311) (xy 121.152402 -230.060013)
			(xy 121.160345 -230.007309) (xy 121.176055 -229.956379) (xy 121.199181 -229.908358) (xy 121.229205 -229.864321)
			(xy 121.265457 -229.82525) (xy 121.307128 -229.792019) (xy 121.353286 -229.76537) (xy 121.4029 -229.745898)
			(xy 121.454862 -229.734038) (xy 121.508012 -229.730055) (xy 121.561162 -229.734038) (xy 121.613124 -229.745898)
			(xy 121.662738 -229.76537) (xy 121.708896 -229.792019) (xy 121.750567 -229.82525) (xy 121.786819 -229.864321)
			(xy 121.816843 -229.908358) (xy 121.839969 -229.956379) (xy 121.855679 -230.007309) (xy 121.863622 -230.060013)
			(xy 121.86412 -230.086662) (xy 121.863622 -230.113311) (xy 123.032002 -230.113311) (xy 123.032002 -230.060013)
			(xy 123.039945 -230.007309) (xy 123.055655 -229.956379) (xy 123.078781 -229.908358) (xy 123.108805 -229.864321)
			(xy 123.145057 -229.82525) (xy 123.186728 -229.792019) (xy 123.232886 -229.76537) (xy 123.2825 -229.745898)
			(xy 123.334462 -229.734038) (xy 123.387612 -229.730055) (xy 123.440762 -229.734038) (xy 123.492724 -229.745898)
			(xy 123.542338 -229.76537) (xy 123.588496 -229.792019) (xy 123.630167 -229.82525) (xy 123.666419 -229.864321)
			(xy 123.696443 -229.908358) (xy 123.719569 -229.956379) (xy 123.735279 -230.007309) (xy 123.743222 -230.060013)
			(xy 123.74372 -230.086662) (xy 123.743222 -230.113311) (xy 123.971802 -230.113311) (xy 123.971802 -230.060013)
			(xy 123.979745 -230.007309) (xy 123.995455 -229.956379) (xy 124.018581 -229.908358) (xy 124.048605 -229.864321)
			(xy 124.084857 -229.82525) (xy 124.126528 -229.792019) (xy 124.172686 -229.76537) (xy 124.2223 -229.745898)
			(xy 124.274262 -229.734038) (xy 124.327412 -229.730055) (xy 124.380562 -229.734038) (xy 124.432524 -229.745898)
			(xy 124.482138 -229.76537) (xy 124.528296 -229.792019) (xy 124.569967 -229.82525) (xy 124.606219 -229.864321)
			(xy 124.636243 -229.908358) (xy 124.659369 -229.956379) (xy 124.675079 -230.007309) (xy 124.683022 -230.060013)
			(xy 124.68352 -230.086662) (xy 124.683022 -230.113311) (xy 124.911856 -230.113311) (xy 124.911856 -230.060013)
			(xy 124.919799 -230.007309) (xy 124.935509 -229.956379) (xy 124.958635 -229.908358) (xy 124.988659 -229.864321)
			(xy 125.024911 -229.82525) (xy 125.066582 -229.792019) (xy 125.11274 -229.76537) (xy 125.162354 -229.745898)
			(xy 125.214316 -229.734038) (xy 125.267466 -229.730055) (xy 125.320616 -229.734038) (xy 125.372578 -229.745898)
			(xy 125.422192 -229.76537) (xy 125.46835 -229.792019) (xy 125.510021 -229.82525) (xy 125.546273 -229.864321)
			(xy 125.576297 -229.908358) (xy 125.599423 -229.956379) (xy 125.615133 -230.007309) (xy 125.623076 -230.060013)
			(xy 125.623574 -230.086662) (xy 125.623076 -230.113311) (xy 125.851402 -230.113311) (xy 125.851402 -230.060013)
			(xy 125.859345 -230.007309) (xy 125.875055 -229.956379) (xy 125.898181 -229.908358) (xy 125.928205 -229.864321)
			(xy 125.964457 -229.82525) (xy 126.006128 -229.792019) (xy 126.052286 -229.76537) (xy 126.1019 -229.745898)
			(xy 126.153862 -229.734038) (xy 126.207012 -229.730055) (xy 126.260162 -229.734038) (xy 126.312124 -229.745898)
			(xy 126.361738 -229.76537) (xy 126.407896 -229.792019) (xy 126.449567 -229.82525) (xy 126.485819 -229.864321)
			(xy 126.515843 -229.908358) (xy 126.538969 -229.956379) (xy 126.554679 -230.007309) (xy 126.562622 -230.060013)
			(xy 126.56312 -230.086662) (xy 126.562622 -230.113311) (xy 126.791202 -230.113311) (xy 126.791202 -230.060013)
			(xy 126.799145 -230.007309) (xy 126.814855 -229.956379) (xy 126.837981 -229.908358) (xy 126.868005 -229.864321)
			(xy 126.904257 -229.82525) (xy 126.945928 -229.792019) (xy 126.992086 -229.76537) (xy 127.0417 -229.745898)
			(xy 127.093662 -229.734038) (xy 127.146812 -229.730055) (xy 127.199962 -229.734038) (xy 127.251924 -229.745898)
			(xy 127.301538 -229.76537) (xy 127.347696 -229.792019) (xy 127.389367 -229.82525) (xy 127.425619 -229.864321)
			(xy 127.455643 -229.908358) (xy 127.478769 -229.956379) (xy 127.494479 -230.007309) (xy 127.502422 -230.060013)
			(xy 127.50292 -230.086662) (xy 127.502422 -230.113311) (xy 127.731002 -230.113311) (xy 127.731002 -230.060013)
			(xy 127.738945 -230.007309) (xy 127.754655 -229.956379) (xy 127.777781 -229.908358) (xy 127.807805 -229.864321)
			(xy 127.844057 -229.82525) (xy 127.885728 -229.792019) (xy 127.931886 -229.76537) (xy 127.9815 -229.745898)
			(xy 128.033462 -229.734038) (xy 128.086612 -229.730055) (xy 128.139762 -229.734038) (xy 128.191724 -229.745898)
			(xy 128.241338 -229.76537) (xy 128.287496 -229.792019) (xy 128.329167 -229.82525) (xy 128.365419 -229.864321)
			(xy 128.395443 -229.908358) (xy 128.418569 -229.956379) (xy 128.434279 -230.007309) (xy 128.442222 -230.060013)
			(xy 128.44272 -230.086662) (xy 128.442222 -230.113311) (xy 128.670802 -230.113311) (xy 128.670802 -230.060013)
			(xy 128.678745 -230.007309) (xy 128.694455 -229.956379) (xy 128.717581 -229.908358) (xy 128.747605 -229.864321)
			(xy 128.783857 -229.82525) (xy 128.825528 -229.792019) (xy 128.871686 -229.76537) (xy 128.9213 -229.745898)
			(xy 128.973262 -229.734038) (xy 129.026412 -229.730055) (xy 129.079562 -229.734038) (xy 129.131524 -229.745898)
			(xy 129.181138 -229.76537) (xy 129.227296 -229.792019) (xy 129.268967 -229.82525) (xy 129.305219 -229.864321)
			(xy 129.335243 -229.908358) (xy 129.358369 -229.956379) (xy 129.374079 -230.007309) (xy 129.382022 -230.060013)
			(xy 129.38252 -230.086662) (xy 129.382022 -230.113311) (xy 129.610602 -230.113311) (xy 129.610602 -230.060013)
			(xy 129.618545 -230.007309) (xy 129.634255 -229.956379) (xy 129.657381 -229.908358) (xy 129.687405 -229.864321)
			(xy 129.723657 -229.82525) (xy 129.765328 -229.792019) (xy 129.811486 -229.76537) (xy 129.8611 -229.745898)
			(xy 129.913062 -229.734038) (xy 129.966212 -229.730055) (xy 130.019362 -229.734038) (xy 130.071324 -229.745898)
			(xy 130.120938 -229.76537) (xy 130.167096 -229.792019) (xy 130.208767 -229.82525) (xy 130.245019 -229.864321)
			(xy 130.275043 -229.908358) (xy 130.298169 -229.956379) (xy 130.313879 -230.007309) (xy 130.321822 -230.060013)
			(xy 130.32232 -230.086662) (xy 130.321822 -230.113311) (xy 130.550402 -230.113311) (xy 130.550402 -230.060013)
			(xy 130.558345 -230.007309) (xy 130.574055 -229.956379) (xy 130.597181 -229.908358) (xy 130.627205 -229.864321)
			(xy 130.663457 -229.82525) (xy 130.705128 -229.792019) (xy 130.751286 -229.76537) (xy 130.8009 -229.745898)
			(xy 130.852862 -229.734038) (xy 130.906012 -229.730055) (xy 130.959162 -229.734038) (xy 131.011124 -229.745898)
			(xy 131.060738 -229.76537) (xy 131.106896 -229.792019) (xy 131.148567 -229.82525) (xy 131.184819 -229.864321)
			(xy 131.214843 -229.908358) (xy 131.237969 -229.956379) (xy 131.253679 -230.007309) (xy 131.261622 -230.060013)
			(xy 131.26212 -230.086662) (xy 131.261622 -230.113311) (xy 131.490456 -230.113311) (xy 131.490456 -230.060013)
			(xy 131.498399 -230.007309) (xy 131.514109 -229.956379) (xy 131.537235 -229.908358) (xy 131.567259 -229.864321)
			(xy 131.603511 -229.82525) (xy 131.645182 -229.792019) (xy 131.69134 -229.76537) (xy 131.740954 -229.745898)
			(xy 131.792916 -229.734038) (xy 131.846066 -229.730055) (xy 131.899216 -229.734038) (xy 131.951178 -229.745898)
			(xy 132.000792 -229.76537) (xy 132.04695 -229.792019) (xy 132.088621 -229.82525) (xy 132.124873 -229.864321)
			(xy 132.154897 -229.908358) (xy 132.178023 -229.956379) (xy 132.193733 -230.007309) (xy 132.201676 -230.060013)
			(xy 132.202174 -230.086662) (xy 132.201676 -230.113311) (xy 132.430002 -230.113311) (xy 132.430002 -230.060013)
			(xy 132.437945 -230.007309) (xy 132.453655 -229.956379) (xy 132.476781 -229.908358) (xy 132.506805 -229.864321)
			(xy 132.543057 -229.82525) (xy 132.584728 -229.792019) (xy 132.630886 -229.76537) (xy 132.6805 -229.745898)
			(xy 132.732462 -229.734038) (xy 132.785612 -229.730055) (xy 132.838762 -229.734038) (xy 132.890724 -229.745898)
			(xy 132.940338 -229.76537) (xy 132.986496 -229.792019) (xy 133.028167 -229.82525) (xy 133.064419 -229.864321)
			(xy 133.094443 -229.908358) (xy 133.117569 -229.956379) (xy 133.133279 -230.007309) (xy 133.141222 -230.060013)
			(xy 133.14172 -230.086662) (xy 133.141222 -230.113311) (xy 133.370056 -230.113311) (xy 133.370056 -230.060013)
			(xy 133.377999 -230.007309) (xy 133.393709 -229.956379) (xy 133.416835 -229.908358) (xy 133.446859 -229.864321)
			(xy 133.483111 -229.82525) (xy 133.524782 -229.792019) (xy 133.57094 -229.76537) (xy 133.620554 -229.745898)
			(xy 133.672516 -229.734038) (xy 133.725666 -229.730055) (xy 133.778816 -229.734038) (xy 133.830778 -229.745898)
			(xy 133.880392 -229.76537) (xy 133.92655 -229.792019) (xy 133.968221 -229.82525) (xy 134.004473 -229.864321)
			(xy 134.034497 -229.908358) (xy 134.057623 -229.956379) (xy 134.073333 -230.007309) (xy 134.081276 -230.060013)
			(xy 134.081774 -230.086662) (xy 134.081276 -230.113311) (xy 134.309856 -230.113311) (xy 134.309856 -230.060013)
			(xy 134.317799 -230.007309) (xy 134.333509 -229.956379) (xy 134.356635 -229.908358) (xy 134.386659 -229.864321)
			(xy 134.422911 -229.82525) (xy 134.464582 -229.792019) (xy 134.51074 -229.76537) (xy 134.560354 -229.745898)
			(xy 134.612316 -229.734038) (xy 134.665466 -229.730055) (xy 134.718616 -229.734038) (xy 134.770578 -229.745898)
			(xy 134.820192 -229.76537) (xy 134.86635 -229.792019) (xy 134.908021 -229.82525) (xy 134.944273 -229.864321)
			(xy 134.974297 -229.908358) (xy 134.997423 -229.956379) (xy 135.013133 -230.007309) (xy 135.021076 -230.060013)
			(xy 135.021574 -230.086662) (xy 135.021076 -230.113311) (xy 135.013133 -230.166015) (xy 134.997423 -230.216945)
			(xy 134.974297 -230.264966) (xy 134.944273 -230.309003) (xy 134.908021 -230.348074) (xy 134.86635 -230.381305)
			(xy 134.820192 -230.407954) (xy 134.770578 -230.427426) (xy 134.718616 -230.439286) (xy 134.665466 -230.44327)
			(xy 134.612316 -230.439286) (xy 134.560354 -230.427426) (xy 134.51074 -230.407954) (xy 134.464582 -230.381305)
			(xy 134.422911 -230.348074) (xy 134.386659 -230.309003) (xy 134.356635 -230.264966) (xy 134.333509 -230.216945)
			(xy 134.317799 -230.166015) (xy 134.309856 -230.113311) (xy 134.081276 -230.113311) (xy 134.073333 -230.166015)
			(xy 134.057623 -230.216945) (xy 134.034497 -230.264966) (xy 134.004473 -230.309003) (xy 133.968221 -230.348074)
			(xy 133.92655 -230.381305) (xy 133.880392 -230.407954) (xy 133.830778 -230.427426) (xy 133.778816 -230.439286)
			(xy 133.725666 -230.44327) (xy 133.672516 -230.439286) (xy 133.620554 -230.427426) (xy 133.57094 -230.407954)
			(xy 133.524782 -230.381305) (xy 133.483111 -230.348074) (xy 133.446859 -230.309003) (xy 133.416835 -230.264966)
			(xy 133.393709 -230.216945) (xy 133.377999 -230.166015) (xy 133.370056 -230.113311) (xy 133.141222 -230.113311)
			(xy 133.133279 -230.166015) (xy 133.117569 -230.216945) (xy 133.094443 -230.264966) (xy 133.064419 -230.309003)
			(xy 133.028167 -230.348074) (xy 132.986496 -230.381305) (xy 132.940338 -230.407954) (xy 132.890724 -230.427426)
			(xy 132.838762 -230.439286) (xy 132.785612 -230.44327) (xy 132.732462 -230.439286) (xy 132.6805 -230.427426)
			(xy 132.630886 -230.407954) (xy 132.584728 -230.381305) (xy 132.543057 -230.348074) (xy 132.506805 -230.309003)
			(xy 132.476781 -230.264966) (xy 132.453655 -230.216945) (xy 132.437945 -230.166015) (xy 132.430002 -230.113311)
			(xy 132.201676 -230.113311) (xy 132.193733 -230.166015) (xy 132.178023 -230.216945) (xy 132.154897 -230.264966)
			(xy 132.124873 -230.309003) (xy 132.088621 -230.348074) (xy 132.04695 -230.381305) (xy 132.000792 -230.407954)
			(xy 131.951178 -230.427426) (xy 131.899216 -230.439286) (xy 131.846066 -230.44327) (xy 131.792916 -230.439286)
			(xy 131.740954 -230.427426) (xy 131.69134 -230.407954) (xy 131.645182 -230.381305) (xy 131.603511 -230.348074)
			(xy 131.567259 -230.309003) (xy 131.537235 -230.264966) (xy 131.514109 -230.216945) (xy 131.498399 -230.166015)
			(xy 131.490456 -230.113311) (xy 131.261622 -230.113311) (xy 131.253679 -230.166015) (xy 131.237969 -230.216945)
			(xy 131.214843 -230.264966) (xy 131.184819 -230.309003) (xy 131.148567 -230.348074) (xy 131.106896 -230.381305)
			(xy 131.060738 -230.407954) (xy 131.011124 -230.427426) (xy 130.959162 -230.439286) (xy 130.906012 -230.44327)
			(xy 130.852862 -230.439286) (xy 130.8009 -230.427426) (xy 130.751286 -230.407954) (xy 130.705128 -230.381305)
			(xy 130.663457 -230.348074) (xy 130.627205 -230.309003) (xy 130.597181 -230.264966) (xy 130.574055 -230.216945)
			(xy 130.558345 -230.166015) (xy 130.550402 -230.113311) (xy 130.321822 -230.113311) (xy 130.313879 -230.166015)
			(xy 130.298169 -230.216945) (xy 130.275043 -230.264966) (xy 130.245019 -230.309003) (xy 130.208767 -230.348074)
			(xy 130.167096 -230.381305) (xy 130.120938 -230.407954) (xy 130.071324 -230.427426) (xy 130.019362 -230.439286)
			(xy 129.966212 -230.44327) (xy 129.913062 -230.439286) (xy 129.8611 -230.427426) (xy 129.811486 -230.407954)
			(xy 129.765328 -230.381305) (xy 129.723657 -230.348074) (xy 129.687405 -230.309003) (xy 129.657381 -230.264966)
			(xy 129.634255 -230.216945) (xy 129.618545 -230.166015) (xy 129.610602 -230.113311) (xy 129.382022 -230.113311)
			(xy 129.374079 -230.166015) (xy 129.358369 -230.216945) (xy 129.335243 -230.264966) (xy 129.305219 -230.309003)
			(xy 129.268967 -230.348074) (xy 129.227296 -230.381305) (xy 129.181138 -230.407954) (xy 129.131524 -230.427426)
			(xy 129.079562 -230.439286) (xy 129.026412 -230.44327) (xy 128.973262 -230.439286) (xy 128.9213 -230.427426)
			(xy 128.871686 -230.407954) (xy 128.825528 -230.381305) (xy 128.783857 -230.348074) (xy 128.747605 -230.309003)
			(xy 128.717581 -230.264966) (xy 128.694455 -230.216945) (xy 128.678745 -230.166015) (xy 128.670802 -230.113311)
			(xy 128.442222 -230.113311) (xy 128.434279 -230.166015) (xy 128.418569 -230.216945) (xy 128.395443 -230.264966)
			(xy 128.365419 -230.309003) (xy 128.329167 -230.348074) (xy 128.287496 -230.381305) (xy 128.241338 -230.407954)
			(xy 128.191724 -230.427426) (xy 128.139762 -230.439286) (xy 128.086612 -230.44327) (xy 128.033462 -230.439286)
			(xy 127.9815 -230.427426) (xy 127.931886 -230.407954) (xy 127.885728 -230.381305) (xy 127.844057 -230.348074)
			(xy 127.807805 -230.309003) (xy 127.777781 -230.264966) (xy 127.754655 -230.216945) (xy 127.738945 -230.166015)
			(xy 127.731002 -230.113311) (xy 127.502422 -230.113311) (xy 127.494479 -230.166015) (xy 127.478769 -230.216945)
			(xy 127.455643 -230.264966) (xy 127.425619 -230.309003) (xy 127.389367 -230.348074) (xy 127.347696 -230.381305)
			(xy 127.301538 -230.407954) (xy 127.251924 -230.427426) (xy 127.199962 -230.439286) (xy 127.146812 -230.44327)
			(xy 127.093662 -230.439286) (xy 127.0417 -230.427426) (xy 126.992086 -230.407954) (xy 126.945928 -230.381305)
			(xy 126.904257 -230.348074) (xy 126.868005 -230.309003) (xy 126.837981 -230.264966) (xy 126.814855 -230.216945)
			(xy 126.799145 -230.166015) (xy 126.791202 -230.113311) (xy 126.562622 -230.113311) (xy 126.554679 -230.166015)
			(xy 126.538969 -230.216945) (xy 126.515843 -230.264966) (xy 126.485819 -230.309003) (xy 126.449567 -230.348074)
			(xy 126.407896 -230.381305) (xy 126.361738 -230.407954) (xy 126.312124 -230.427426) (xy 126.260162 -230.439286)
			(xy 126.207012 -230.44327) (xy 126.153862 -230.439286) (xy 126.1019 -230.427426) (xy 126.052286 -230.407954)
			(xy 126.006128 -230.381305) (xy 125.964457 -230.348074) (xy 125.928205 -230.309003) (xy 125.898181 -230.264966)
			(xy 125.875055 -230.216945) (xy 125.859345 -230.166015) (xy 125.851402 -230.113311) (xy 125.623076 -230.113311)
			(xy 125.615133 -230.166015) (xy 125.599423 -230.216945) (xy 125.576297 -230.264966) (xy 125.546273 -230.309003)
			(xy 125.510021 -230.348074) (xy 125.46835 -230.381305) (xy 125.422192 -230.407954) (xy 125.372578 -230.427426)
			(xy 125.320616 -230.439286) (xy 125.267466 -230.44327) (xy 125.214316 -230.439286) (xy 125.162354 -230.427426)
			(xy 125.11274 -230.407954) (xy 125.066582 -230.381305) (xy 125.024911 -230.348074) (xy 124.988659 -230.309003)
			(xy 124.958635 -230.264966) (xy 124.935509 -230.216945) (xy 124.919799 -230.166015) (xy 124.911856 -230.113311)
			(xy 124.683022 -230.113311) (xy 124.675079 -230.166015) (xy 124.659369 -230.216945) (xy 124.636243 -230.264966)
			(xy 124.606219 -230.309003) (xy 124.569967 -230.348074) (xy 124.528296 -230.381305) (xy 124.482138 -230.407954)
			(xy 124.432524 -230.427426) (xy 124.380562 -230.439286) (xy 124.327412 -230.44327) (xy 124.274262 -230.439286)
			(xy 124.2223 -230.427426) (xy 124.172686 -230.407954) (xy 124.126528 -230.381305) (xy 124.084857 -230.348074)
			(xy 124.048605 -230.309003) (xy 124.018581 -230.264966) (xy 123.995455 -230.216945) (xy 123.979745 -230.166015)
			(xy 123.971802 -230.113311) (xy 123.743222 -230.113311) (xy 123.735279 -230.166015) (xy 123.719569 -230.216945)
			(xy 123.696443 -230.264966) (xy 123.666419 -230.309003) (xy 123.630167 -230.348074) (xy 123.588496 -230.381305)
			(xy 123.542338 -230.407954) (xy 123.492724 -230.427426) (xy 123.440762 -230.439286) (xy 123.387612 -230.44327)
			(xy 123.334462 -230.439286) (xy 123.2825 -230.427426) (xy 123.232886 -230.407954) (xy 123.186728 -230.381305)
			(xy 123.145057 -230.348074) (xy 123.108805 -230.309003) (xy 123.078781 -230.264966) (xy 123.055655 -230.216945)
			(xy 123.039945 -230.166015) (xy 123.032002 -230.113311) (xy 121.863622 -230.113311) (xy 121.855679 -230.166015)
			(xy 121.839969 -230.216945) (xy 121.816843 -230.264966) (xy 121.786819 -230.309003) (xy 121.750567 -230.348074)
			(xy 121.708896 -230.381305) (xy 121.662738 -230.407954) (xy 121.613124 -230.427426) (xy 121.561162 -230.439286)
			(xy 121.508012 -230.44327) (xy 121.454862 -230.439286) (xy 121.4029 -230.427426) (xy 121.353286 -230.407954)
			(xy 121.307128 -230.381305) (xy 121.265457 -230.348074) (xy 121.229205 -230.309003) (xy 121.199181 -230.264966)
			(xy 121.176055 -230.216945) (xy 121.160345 -230.166015) (xy 121.152402 -230.113311) (xy 120.923822 -230.113311)
			(xy 120.915879 -230.166015) (xy 120.900169 -230.216945) (xy 120.877043 -230.264966) (xy 120.847019 -230.309003)
			(xy 120.810767 -230.348074) (xy 120.769096 -230.381305) (xy 120.722938 -230.407954) (xy 120.673324 -230.427426)
			(xy 120.621362 -230.439286) (xy 120.568212 -230.44327) (xy 120.515062 -230.439286) (xy 120.4631 -230.427426)
			(xy 120.413486 -230.407954) (xy 120.367328 -230.381305) (xy 120.325657 -230.348074) (xy 120.289405 -230.309003)
			(xy 120.259381 -230.264966) (xy 120.236255 -230.216945) (xy 120.220545 -230.166015) (xy 120.212602 -230.113311)
			(xy 119.984022 -230.113311) (xy 119.976079 -230.166015) (xy 119.960369 -230.216945) (xy 119.937243 -230.264966)
			(xy 119.907219 -230.309003) (xy 119.870967 -230.348074) (xy 119.829296 -230.381305) (xy 119.783138 -230.407954)
			(xy 119.733524 -230.427426) (xy 119.681562 -230.439286) (xy 119.628412 -230.44327) (xy 119.575262 -230.439286)
			(xy 119.5233 -230.427426) (xy 119.473686 -230.407954) (xy 119.427528 -230.381305) (xy 119.385857 -230.348074)
			(xy 119.349605 -230.309003) (xy 119.319581 -230.264966) (xy 119.296455 -230.216945) (xy 119.280745 -230.166015)
			(xy 119.272802 -230.113311) (xy 119.044222 -230.113311) (xy 119.036279 -230.166015) (xy 119.020569 -230.216945)
			(xy 118.997443 -230.264966) (xy 118.967419 -230.309003) (xy 118.931167 -230.348074) (xy 118.889496 -230.381305)
			(xy 118.843338 -230.407954) (xy 118.793724 -230.427426) (xy 118.741762 -230.439286) (xy 118.688612 -230.44327)
			(xy 118.635462 -230.439286) (xy 118.5835 -230.427426) (xy 118.533886 -230.407954) (xy 118.487728 -230.381305)
			(xy 118.446057 -230.348074) (xy 118.409805 -230.309003) (xy 118.379781 -230.264966) (xy 118.356655 -230.216945)
			(xy 118.340945 -230.166015) (xy 118.333002 -230.113311) (xy 118.104422 -230.113311) (xy 118.096479 -230.166015)
			(xy 118.080769 -230.216945) (xy 118.057643 -230.264966) (xy 118.027619 -230.309003) (xy 117.991367 -230.348074)
			(xy 117.949696 -230.381305) (xy 117.903538 -230.407954) (xy 117.853924 -230.427426) (xy 117.801962 -230.439286)
			(xy 117.748812 -230.44327) (xy 117.695662 -230.439286) (xy 117.6437 -230.427426) (xy 117.594086 -230.407954)
			(xy 117.547928 -230.381305) (xy 117.506257 -230.348074) (xy 117.470005 -230.309003) (xy 117.439981 -230.264966)
			(xy 117.416855 -230.216945) (xy 117.401145 -230.166015) (xy 117.393202 -230.113311) (xy 117.164622 -230.113311)
			(xy 117.156679 -230.166015) (xy 117.140969 -230.216945) (xy 117.117843 -230.264966) (xy 117.087819 -230.309003)
			(xy 117.051567 -230.348074) (xy 117.009896 -230.381305) (xy 116.963738 -230.407954) (xy 116.914124 -230.427426)
			(xy 116.862162 -230.439286) (xy 116.809012 -230.44327) (xy 116.755862 -230.439286) (xy 116.7039 -230.427426)
			(xy 116.654286 -230.407954) (xy 116.608128 -230.381305) (xy 116.566457 -230.348074) (xy 116.530205 -230.309003)
			(xy 116.500181 -230.264966) (xy 116.477055 -230.216945) (xy 116.461345 -230.166015) (xy 116.453402 -230.113311)
			(xy 116.224822 -230.113311) (xy 116.216879 -230.166015) (xy 116.201169 -230.216945) (xy 116.178043 -230.264966)
			(xy 116.148019 -230.309003) (xy 116.111767 -230.348074) (xy 116.070096 -230.381305) (xy 116.023938 -230.407954)
			(xy 115.974324 -230.427426) (xy 115.922362 -230.439286) (xy 115.869212 -230.44327) (xy 115.816062 -230.439286)
			(xy 115.7641 -230.427426) (xy 115.714486 -230.407954) (xy 115.668328 -230.381305) (xy 115.626657 -230.348074)
			(xy 115.590405 -230.309003) (xy 115.560381 -230.264966) (xy 115.537255 -230.216945) (xy 115.521545 -230.166015)
			(xy 115.513602 -230.113311) (xy 115.285276 -230.113311) (xy 115.277333 -230.166015) (xy 115.261623 -230.216945)
			(xy 115.238497 -230.264966) (xy 115.208473 -230.309003) (xy 115.172221 -230.348074) (xy 115.13055 -230.381305)
			(xy 115.084392 -230.407954) (xy 115.034778 -230.427426) (xy 114.982816 -230.439286) (xy 114.929666 -230.44327)
			(xy 114.876516 -230.439286) (xy 114.824554 -230.427426) (xy 114.77494 -230.407954) (xy 114.728782 -230.381305)
			(xy 114.687111 -230.348074) (xy 114.650859 -230.309003) (xy 114.620835 -230.264966) (xy 114.597709 -230.216945)
			(xy 114.581999 -230.166015) (xy 114.574056 -230.113311) (xy 114.345476 -230.113311) (xy 114.337533 -230.166015)
			(xy 114.321823 -230.216945) (xy 114.298697 -230.264966) (xy 114.268673 -230.309003) (xy 114.232421 -230.348074)
			(xy 114.19075 -230.381305) (xy 114.144592 -230.407954) (xy 114.094978 -230.427426) (xy 114.043016 -230.439286)
			(xy 113.989866 -230.44327) (xy 113.936716 -230.439286) (xy 113.884754 -230.427426) (xy 113.83514 -230.407954)
			(xy 113.788982 -230.381305) (xy 113.747311 -230.348074) (xy 113.711059 -230.309003) (xy 113.681035 -230.264966)
			(xy 113.657909 -230.216945) (xy 113.642199 -230.166015) (xy 113.634256 -230.113311) (xy 113.405676 -230.113311)
			(xy 113.397733 -230.166015) (xy 113.382023 -230.216945) (xy 113.358897 -230.264966) (xy 113.328873 -230.309003)
			(xy 113.292621 -230.348074) (xy 113.25095 -230.381305) (xy 113.204792 -230.407954) (xy 113.155178 -230.427426)
			(xy 113.103216 -230.439286) (xy 113.050066 -230.44327) (xy 112.996916 -230.439286) (xy 112.944954 -230.427426)
			(xy 112.89534 -230.407954) (xy 112.849182 -230.381305) (xy 112.807511 -230.348074) (xy 112.771259 -230.309003)
			(xy 112.741235 -230.264966) (xy 112.718109 -230.216945) (xy 112.702399 -230.166015) (xy 112.694456 -230.113311)
			(xy 112.465876 -230.113311) (xy 112.457933 -230.166015) (xy 112.442223 -230.216945) (xy 112.419097 -230.264966)
			(xy 112.389073 -230.309003) (xy 112.352821 -230.348074) (xy 112.31115 -230.381305) (xy 112.264992 -230.407954)
			(xy 112.215378 -230.427426) (xy 112.163416 -230.439286) (xy 112.110266 -230.44327) (xy 112.057116 -230.439286)
			(xy 112.005154 -230.427426) (xy 111.95554 -230.407954) (xy 111.909382 -230.381305) (xy 111.867711 -230.348074)
			(xy 111.831459 -230.309003) (xy 111.801435 -230.264966) (xy 111.778309 -230.216945) (xy 111.762599 -230.166015)
			(xy 111.754656 -230.113311) (xy 111.526076 -230.113311) (xy 111.518133 -230.166015) (xy 111.502423 -230.216945)
			(xy 111.479297 -230.264966) (xy 111.449273 -230.309003) (xy 111.413021 -230.348074) (xy 111.37135 -230.381305)
			(xy 111.325192 -230.407954) (xy 111.275578 -230.427426) (xy 111.223616 -230.439286) (xy 111.170466 -230.44327)
			(xy 111.117316 -230.439286) (xy 111.065354 -230.427426) (xy 111.01574 -230.407954) (xy 110.969582 -230.381305)
			(xy 110.927911 -230.348074) (xy 110.891659 -230.309003) (xy 110.861635 -230.264966) (xy 110.838509 -230.216945)
			(xy 110.822799 -230.166015) (xy 110.814856 -230.113311) (xy 110.586022 -230.113311) (xy 110.578079 -230.166015)
			(xy 110.562369 -230.216945) (xy 110.539243 -230.264966) (xy 110.509219 -230.309003) (xy 110.472967 -230.348074)
			(xy 110.431296 -230.381305) (xy 110.385138 -230.407954) (xy 110.335524 -230.427426) (xy 110.283562 -230.439286)
			(xy 110.230412 -230.44327) (xy 110.177262 -230.439286) (xy 110.1253 -230.427426) (xy 110.075686 -230.407954)
			(xy 110.029528 -230.381305) (xy 109.987857 -230.348074) (xy 109.951605 -230.309003) (xy 109.921581 -230.264966)
			(xy 109.898455 -230.216945) (xy 109.882745 -230.166015) (xy 109.874802 -230.113311) (xy 109.646222 -230.113311)
			(xy 109.638279 -230.166015) (xy 109.622569 -230.216945) (xy 109.599443 -230.264966) (xy 109.569419 -230.309003)
			(xy 109.533167 -230.348074) (xy 109.491496 -230.381305) (xy 109.445338 -230.407954) (xy 109.395724 -230.427426)
			(xy 109.343762 -230.439286) (xy 109.290612 -230.44327) (xy 109.237462 -230.439286) (xy 109.1855 -230.427426)
			(xy 109.135886 -230.407954) (xy 109.089728 -230.381305) (xy 109.048057 -230.348074) (xy 109.011805 -230.309003)
			(xy 108.981781 -230.264966) (xy 108.958655 -230.216945) (xy 108.942945 -230.166015) (xy 108.935002 -230.113311)
			(xy 108.706422 -230.113311) (xy 108.698479 -230.166015) (xy 108.682769 -230.216945) (xy 108.659643 -230.264966)
			(xy 108.629619 -230.309003) (xy 108.593367 -230.348074) (xy 108.551696 -230.381305) (xy 108.505538 -230.407954)
			(xy 108.455924 -230.427426) (xy 108.403962 -230.439286) (xy 108.350812 -230.44327) (xy 108.297662 -230.439286)
			(xy 108.2457 -230.427426) (xy 108.196086 -230.407954) (xy 108.149928 -230.381305) (xy 108.108257 -230.348074)
			(xy 108.072005 -230.309003) (xy 108.041981 -230.264966) (xy 108.018855 -230.216945) (xy 108.003145 -230.166015)
			(xy 107.995202 -230.113311) (xy 107.766622 -230.113311) (xy 107.758679 -230.166015) (xy 107.742969 -230.216945)
			(xy 107.719843 -230.264966) (xy 107.689819 -230.309003) (xy 107.653567 -230.348074) (xy 107.611896 -230.381305)
			(xy 107.565738 -230.407954) (xy 107.516124 -230.427426) (xy 107.464162 -230.439286) (xy 107.411012 -230.44327)
			(xy 107.357862 -230.439286) (xy 107.3059 -230.427426) (xy 107.256286 -230.407954) (xy 107.210128 -230.381305)
			(xy 107.168457 -230.348074) (xy 107.132205 -230.309003) (xy 107.102181 -230.264966) (xy 107.079055 -230.216945)
			(xy 107.063345 -230.166015) (xy 107.055402 -230.113311) (xy 106.827076 -230.113311) (xy 106.819133 -230.166015)
			(xy 106.803423 -230.216945) (xy 106.780297 -230.264966) (xy 106.750273 -230.309003) (xy 106.714021 -230.348074)
			(xy 106.67235 -230.381305) (xy 106.626192 -230.407954) (xy 106.576578 -230.427426) (xy 106.524616 -230.439286)
			(xy 106.471466 -230.44327) (xy 106.418316 -230.439286) (xy 106.366354 -230.427426) (xy 106.31674 -230.407954)
			(xy 106.270582 -230.381305) (xy 106.228911 -230.348074) (xy 106.192659 -230.309003) (xy 106.162635 -230.264966)
			(xy 106.139509 -230.216945) (xy 106.123799 -230.166015) (xy 106.115856 -230.113311) (xy 105.887022 -230.113311)
			(xy 105.879079 -230.166015) (xy 105.863369 -230.216945) (xy 105.840243 -230.264966) (xy 105.810219 -230.309003)
			(xy 105.773967 -230.348074) (xy 105.732296 -230.381305) (xy 105.686138 -230.407954) (xy 105.636524 -230.427426)
			(xy 105.584562 -230.439286) (xy 105.531412 -230.44327) (xy 105.478262 -230.439286) (xy 105.4263 -230.427426)
			(xy 105.376686 -230.407954) (xy 105.330528 -230.381305) (xy 105.288857 -230.348074) (xy 105.252605 -230.309003)
			(xy 105.222581 -230.264966) (xy 105.199455 -230.216945) (xy 105.183745 -230.166015) (xy 105.175802 -230.113311)
			(xy 104.947222 -230.113311) (xy 104.939279 -230.166015) (xy 104.923569 -230.216945) (xy 104.900443 -230.264966)
			(xy 104.870419 -230.309003) (xy 104.834167 -230.348074) (xy 104.792496 -230.381305) (xy 104.746338 -230.407954)
			(xy 104.696724 -230.427426) (xy 104.644762 -230.439286) (xy 104.591612 -230.44327) (xy 104.538462 -230.439286)
			(xy 104.4865 -230.427426) (xy 104.436886 -230.407954) (xy 104.390728 -230.381305) (xy 104.349057 -230.348074)
			(xy 104.312805 -230.309003) (xy 104.282781 -230.264966) (xy 104.259655 -230.216945) (xy 104.243945 -230.166015)
			(xy 104.236002 -230.113311) (xy 104.007422 -230.113311) (xy 103.999479 -230.166015) (xy 103.983769 -230.216945)
			(xy 103.960643 -230.264966) (xy 103.930619 -230.309003) (xy 103.894367 -230.348074) (xy 103.852696 -230.381305)
			(xy 103.806538 -230.407954) (xy 103.756924 -230.427426) (xy 103.704962 -230.439286) (xy 103.651812 -230.44327)
			(xy 103.598662 -230.439286) (xy 103.5467 -230.427426) (xy 103.497086 -230.407954) (xy 103.450928 -230.381305)
			(xy 103.409257 -230.348074) (xy 103.373005 -230.309003) (xy 103.342981 -230.264966) (xy 103.319855 -230.216945)
			(xy 103.304145 -230.166015) (xy 103.296202 -230.113311) (xy 103.067622 -230.113311) (xy 103.059679 -230.166015)
			(xy 103.043969 -230.216945) (xy 103.020843 -230.264966) (xy 102.990819 -230.309003) (xy 102.954567 -230.348074)
			(xy 102.912896 -230.381305) (xy 102.866738 -230.407954) (xy 102.817124 -230.427426) (xy 102.765162 -230.439286)
			(xy 102.712012 -230.44327) (xy 102.658862 -230.439286) (xy 102.6069 -230.427426) (xy 102.557286 -230.407954)
			(xy 102.511128 -230.381305) (xy 102.469457 -230.348074) (xy 102.433205 -230.309003) (xy 102.403181 -230.264966)
			(xy 102.380055 -230.216945) (xy 102.364345 -230.166015) (xy 102.356402 -230.113311) (xy 102.127822 -230.113311)
			(xy 102.119879 -230.166015) (xy 102.104169 -230.216945) (xy 102.081043 -230.264966) (xy 102.051019 -230.309003)
			(xy 102.014767 -230.348074) (xy 101.973096 -230.381305) (xy 101.926938 -230.407954) (xy 101.877324 -230.427426)
			(xy 101.825362 -230.439286) (xy 101.772212 -230.44327) (xy 101.719062 -230.439286) (xy 101.6671 -230.427426)
			(xy 101.617486 -230.407954) (xy 101.571328 -230.381305) (xy 101.529657 -230.348074) (xy 101.493405 -230.309003)
			(xy 101.463381 -230.264966) (xy 101.440255 -230.216945) (xy 101.424545 -230.166015) (xy 101.416602 -230.113311)
			(xy 101.188022 -230.113311) (xy 101.180079 -230.166015) (xy 101.164369 -230.216945) (xy 101.141243 -230.264966)
			(xy 101.111219 -230.309003) (xy 101.074967 -230.348074) (xy 101.033296 -230.381305) (xy 100.987138 -230.407954)
			(xy 100.937524 -230.427426) (xy 100.885562 -230.439286) (xy 100.832412 -230.44327) (xy 100.779262 -230.439286)
			(xy 100.7273 -230.427426) (xy 100.677686 -230.407954) (xy 100.631528 -230.381305) (xy 100.589857 -230.348074)
			(xy 100.553605 -230.309003) (xy 100.523581 -230.264966) (xy 100.500455 -230.216945) (xy 100.484745 -230.166015)
			(xy 100.476802 -230.113311) (xy 100.248222 -230.113311) (xy 100.240279 -230.166015) (xy 100.224569 -230.216945)
			(xy 100.201443 -230.264966) (xy 100.171419 -230.309003) (xy 100.135167 -230.348074) (xy 100.093496 -230.381305)
			(xy 100.047338 -230.407954) (xy 99.997724 -230.427426) (xy 99.945762 -230.439286) (xy 99.892612 -230.44327)
			(xy 99.839462 -230.439286) (xy 99.7875 -230.427426) (xy 99.737886 -230.407954) (xy 99.691728 -230.381305)
			(xy 99.650057 -230.348074) (xy 99.613805 -230.309003) (xy 99.583781 -230.264966) (xy 99.560655 -230.216945)
			(xy 99.544945 -230.166015) (xy 99.537002 -230.113311) (xy 99.308422 -230.113311) (xy 99.300479 -230.166015)
			(xy 99.284769 -230.216945) (xy 99.261643 -230.264966) (xy 99.231619 -230.309003) (xy 99.195367 -230.348074)
			(xy 99.153696 -230.381305) (xy 99.107538 -230.407954) (xy 99.057924 -230.427426) (xy 99.005962 -230.439286)
			(xy 98.952812 -230.44327) (xy 98.899662 -230.439286) (xy 98.8477 -230.427426) (xy 98.798086 -230.407954)
			(xy 98.751928 -230.381305) (xy 98.710257 -230.348074) (xy 98.674005 -230.309003) (xy 98.643981 -230.264966)
			(xy 98.620855 -230.216945) (xy 98.605145 -230.166015) (xy 98.597202 -230.113311) (xy 98.368622 -230.113311)
			(xy 98.360679 -230.166015) (xy 98.344969 -230.216945) (xy 98.321843 -230.264966) (xy 98.291819 -230.309003)
			(xy 98.255567 -230.348074) (xy 98.213896 -230.381305) (xy 98.167738 -230.407954) (xy 98.118124 -230.427426)
			(xy 98.066162 -230.439286) (xy 98.013012 -230.44327) (xy 97.959862 -230.439286) (xy 97.9079 -230.427426)
			(xy 97.858286 -230.407954) (xy 97.812128 -230.381305) (xy 97.770457 -230.348074) (xy 97.734205 -230.309003)
			(xy 97.704181 -230.264966) (xy 97.681055 -230.216945) (xy 97.665345 -230.166015) (xy 97.657402 -230.113311)
			(xy 97.429076 -230.113311) (xy 97.421133 -230.166015) (xy 97.405423 -230.216945) (xy 97.382297 -230.264966)
			(xy 97.352273 -230.309003) (xy 97.316021 -230.348074) (xy 97.27435 -230.381305) (xy 97.228192 -230.407954)
			(xy 97.178578 -230.427426) (xy 97.126616 -230.439286) (xy 97.073466 -230.44327) (xy 97.020316 -230.439286)
			(xy 96.968354 -230.427426) (xy 96.91874 -230.407954) (xy 96.872582 -230.381305) (xy 96.830911 -230.348074)
			(xy 96.794659 -230.309003) (xy 96.764635 -230.264966) (xy 96.741509 -230.216945) (xy 96.725799 -230.166015)
			(xy 96.717856 -230.113311) (xy 96.489022 -230.113311) (xy 96.481079 -230.166015) (xy 96.465369 -230.216945)
			(xy 96.442243 -230.264966) (xy 96.412219 -230.309003) (xy 96.375967 -230.348074) (xy 96.334296 -230.381305)
			(xy 96.288138 -230.407954) (xy 96.238524 -230.427426) (xy 96.186562 -230.439286) (xy 96.133412 -230.44327)
			(xy 96.080262 -230.439286) (xy 96.0283 -230.427426) (xy 95.978686 -230.407954) (xy 95.932528 -230.381305)
			(xy 95.890857 -230.348074) (xy 95.854605 -230.309003) (xy 95.824581 -230.264966) (xy 95.801455 -230.216945)
			(xy 95.785745 -230.166015) (xy 95.777802 -230.113311) (xy 95.549222 -230.113311) (xy 95.541279 -230.166015)
			(xy 95.525569 -230.216945) (xy 95.502443 -230.264966) (xy 95.472419 -230.309003) (xy 95.436167 -230.348074)
			(xy 95.394496 -230.381305) (xy 95.348338 -230.407954) (xy 95.298724 -230.427426) (xy 95.246762 -230.439286)
			(xy 95.193612 -230.44327) (xy 95.140462 -230.439286) (xy 95.0885 -230.427426) (xy 95.038886 -230.407954)
			(xy 94.992728 -230.381305) (xy 94.951057 -230.348074) (xy 94.914805 -230.309003) (xy 94.884781 -230.264966)
			(xy 94.861655 -230.216945) (xy 94.845945 -230.166015) (xy 94.838002 -230.113311) (xy 94.609422 -230.113311)
			(xy 94.601479 -230.166015) (xy 94.585769 -230.216945) (xy 94.562643 -230.264966) (xy 94.532619 -230.309003)
			(xy 94.496367 -230.348074) (xy 94.454696 -230.381305) (xy 94.408538 -230.407954) (xy 94.358924 -230.427426)
			(xy 94.306962 -230.439286) (xy 94.253812 -230.44327) (xy 94.200662 -230.439286) (xy 94.1487 -230.427426)
			(xy 94.099086 -230.407954) (xy 94.052928 -230.381305) (xy 94.011257 -230.348074) (xy 93.975005 -230.309003)
			(xy 93.944981 -230.264966) (xy 93.921855 -230.216945) (xy 93.906145 -230.166015) (xy 93.898202 -230.113311)
			(xy 93.669622 -230.113311) (xy 93.661679 -230.166015) (xy 93.645969 -230.216945) (xy 93.622843 -230.264966)
			(xy 93.592819 -230.309003) (xy 93.556567 -230.348074) (xy 93.514896 -230.381305) (xy 93.468738 -230.407954)
			(xy 93.419124 -230.427426) (xy 93.367162 -230.439286) (xy 93.314012 -230.44327) (xy 93.260862 -230.439286)
			(xy 93.2089 -230.427426) (xy 93.159286 -230.407954) (xy 93.113128 -230.381305) (xy 93.071457 -230.348074)
			(xy 93.035205 -230.309003) (xy 93.005181 -230.264966) (xy 92.982055 -230.216945) (xy 92.966345 -230.166015)
			(xy 92.958402 -230.113311) (xy 92.729822 -230.113311) (xy 92.721879 -230.166015) (xy 92.706169 -230.216945)
			(xy 92.683043 -230.264966) (xy 92.653019 -230.309003) (xy 92.616767 -230.348074) (xy 92.575096 -230.381305)
			(xy 92.528938 -230.407954) (xy 92.479324 -230.427426) (xy 92.427362 -230.439286) (xy 92.374212 -230.44327)
			(xy 92.321062 -230.439286) (xy 92.2691 -230.427426) (xy 92.219486 -230.407954) (xy 92.173328 -230.381305)
			(xy 92.131657 -230.348074) (xy 92.095405 -230.309003) (xy 92.065381 -230.264966) (xy 92.042255 -230.216945)
			(xy 92.026545 -230.166015) (xy 92.018602 -230.113311) (xy 91.790022 -230.113311) (xy 91.782079 -230.166015)
			(xy 91.766369 -230.216945) (xy 91.743243 -230.264966) (xy 91.713219 -230.309003) (xy 91.676967 -230.348074)
			(xy 91.635296 -230.381305) (xy 91.589138 -230.407954) (xy 91.539524 -230.427426) (xy 91.487562 -230.439286)
			(xy 91.434412 -230.44327) (xy 91.381262 -230.439286) (xy 91.3293 -230.427426) (xy 91.279686 -230.407954)
			(xy 91.233528 -230.381305) (xy 91.191857 -230.348074) (xy 91.155605 -230.309003) (xy 91.125581 -230.264966)
			(xy 91.102455 -230.216945) (xy 91.086745 -230.166015) (xy 91.078802 -230.113311) (xy 90.850222 -230.113311)
			(xy 90.842279 -230.166015) (xy 90.826569 -230.216945) (xy 90.803443 -230.264966) (xy 90.773419 -230.309003)
			(xy 90.737167 -230.348074) (xy 90.695496 -230.381305) (xy 90.649338 -230.407954) (xy 90.599724 -230.427426)
			(xy 90.547762 -230.439286) (xy 90.494612 -230.44327) (xy 90.441462 -230.439286) (xy 90.3895 -230.427426)
			(xy 90.339886 -230.407954) (xy 90.293728 -230.381305) (xy 90.252057 -230.348074) (xy 90.215805 -230.309003)
			(xy 90.185781 -230.264966) (xy 90.162655 -230.216945) (xy 90.146945 -230.166015) (xy 90.139002 -230.113311)
			(xy 89.910422 -230.113311) (xy 89.902479 -230.166015) (xy 89.886769 -230.216945) (xy 89.863643 -230.264966)
			(xy 89.833619 -230.309003) (xy 89.797367 -230.348074) (xy 89.755696 -230.381305) (xy 89.709538 -230.407954)
			(xy 89.659924 -230.427426) (xy 89.607962 -230.439286) (xy 89.554812 -230.44327) (xy 89.501662 -230.439286)
			(xy 89.4497 -230.427426) (xy 89.400086 -230.407954) (xy 89.353928 -230.381305) (xy 89.312257 -230.348074)
			(xy 89.276005 -230.309003) (xy 89.245981 -230.264966) (xy 89.222855 -230.216945) (xy 89.207145 -230.166015)
			(xy 89.199202 -230.113311) (xy 88.969653 -230.113311) (xy 88.967717 -230.139382) (xy 88.956062 -230.190919)
			(xy 88.93692 -230.240168) (xy 88.910711 -230.286048) (xy 88.878011 -230.327552) (xy 88.839538 -230.36377)
			(xy 88.796135 -230.393905) (xy 88.748757 -230.417296) (xy 88.723724 -230.425752) (xy 88.688418 -230.437182)
			(xy 88.688418 -230.55072) (xy 88.688914 -230.565176) (xy 88.697004 -230.592932) (xy 88.712556 -230.617303)
			(xy 88.734321 -230.636333) (xy 88.760551 -230.648491) (xy 88.789139 -230.652801) (xy 88.817788 -230.648918)
			(xy 88.844197 -230.637152) (xy 88.85555 -230.62819) (xy 88.874909 -230.612426) (xy 88.917204 -230.585901)
			(xy 88.962787 -230.565541) (xy 89.010768 -230.551745) (xy 89.060204 -230.544784) (xy 89.085166 -230.54437)
			(xy 89.11182 -230.544841) (xy 89.164535 -230.552782) (xy 89.215476 -230.568491) (xy 89.263507 -230.591617)
			(xy 89.307555 -230.621645) (xy 89.346635 -230.657902) (xy 89.379874 -230.699579) (xy 89.40653 -230.745745)
			(xy 89.426007 -230.795368) (xy 89.43787 -230.84734) (xy 89.441854 -230.9005) (xy 89.439858 -230.927127)
			(xy 89.669356 -230.927127) (xy 89.669356 -230.873829) (xy 89.677299 -230.821125) (xy 89.693009 -230.770195)
			(xy 89.716135 -230.722174) (xy 89.746159 -230.678137) (xy 89.782411 -230.639066) (xy 89.824082 -230.605835)
			(xy 89.87024 -230.579186) (xy 89.919854 -230.559714) (xy 89.971816 -230.547854) (xy 90.024966 -230.543871)
			(xy 90.078116 -230.547854) (xy 90.130078 -230.559714) (xy 90.179692 -230.579186) (xy 90.22585 -230.605835)
			(xy 90.267521 -230.639066) (xy 90.303773 -230.678137) (xy 90.333797 -230.722174) (xy 90.356923 -230.770195)
			(xy 90.372633 -230.821125) (xy 90.380576 -230.873829) (xy 90.381074 -230.900478) (xy 90.380576 -230.927127)
			(xy 90.608902 -230.927127) (xy 90.608902 -230.873829) (xy 90.616845 -230.821125) (xy 90.632555 -230.770195)
			(xy 90.655681 -230.722174) (xy 90.685705 -230.678137) (xy 90.721957 -230.639066) (xy 90.763628 -230.605835)
			(xy 90.809786 -230.579186) (xy 90.8594 -230.559714) (xy 90.911362 -230.547854) (xy 90.964512 -230.543871)
			(xy 91.017662 -230.547854) (xy 91.069624 -230.559714) (xy 91.119238 -230.579186) (xy 91.165396 -230.605835)
			(xy 91.207067 -230.639066) (xy 91.243319 -230.678137) (xy 91.273343 -230.722174) (xy 91.296469 -230.770195)
			(xy 91.312179 -230.821125) (xy 91.320122 -230.873829) (xy 91.32062 -230.900478) (xy 91.320122 -230.927127)
			(xy 91.548956 -230.927127) (xy 91.548956 -230.873829) (xy 91.556899 -230.821125) (xy 91.572609 -230.770195)
			(xy 91.595735 -230.722174) (xy 91.625759 -230.678137) (xy 91.662011 -230.639066) (xy 91.703682 -230.605835)
			(xy 91.74984 -230.579186) (xy 91.799454 -230.559714) (xy 91.851416 -230.547854) (xy 91.904566 -230.543871)
			(xy 91.957716 -230.547854) (xy 92.009678 -230.559714) (xy 92.059292 -230.579186) (xy 92.10545 -230.605835)
			(xy 92.147121 -230.639066) (xy 92.183373 -230.678137) (xy 92.213397 -230.722174) (xy 92.236523 -230.770195)
			(xy 92.252233 -230.821125) (xy 92.260176 -230.873829) (xy 92.260674 -230.900478) (xy 92.260176 -230.927127)
			(xy 92.488756 -230.927127) (xy 92.488756 -230.873829) (xy 92.496699 -230.821125) (xy 92.512409 -230.770195)
			(xy 92.535535 -230.722174) (xy 92.565559 -230.678137) (xy 92.601811 -230.639066) (xy 92.643482 -230.605835)
			(xy 92.68964 -230.579186) (xy 92.739254 -230.559714) (xy 92.791216 -230.547854) (xy 92.844366 -230.543871)
			(xy 92.897516 -230.547854) (xy 92.949478 -230.559714) (xy 92.999092 -230.579186) (xy 93.04525 -230.605835)
			(xy 93.086921 -230.639066) (xy 93.123173 -230.678137) (xy 93.153197 -230.722174) (xy 93.176323 -230.770195)
			(xy 93.192033 -230.821125) (xy 93.199976 -230.873829) (xy 93.200474 -230.900478) (xy 93.199976 -230.927127)
			(xy 93.428556 -230.927127) (xy 93.428556 -230.873829) (xy 93.436499 -230.821125) (xy 93.452209 -230.770195)
			(xy 93.475335 -230.722174) (xy 93.505359 -230.678137) (xy 93.541611 -230.639066) (xy 93.583282 -230.605835)
			(xy 93.62944 -230.579186) (xy 93.679054 -230.559714) (xy 93.731016 -230.547854) (xy 93.784166 -230.543871)
			(xy 93.837316 -230.547854) (xy 93.889278 -230.559714) (xy 93.938892 -230.579186) (xy 93.98505 -230.605835)
			(xy 94.026721 -230.639066) (xy 94.062973 -230.678137) (xy 94.092997 -230.722174) (xy 94.116123 -230.770195)
			(xy 94.131833 -230.821125) (xy 94.139776 -230.873829) (xy 94.140274 -230.900478) (xy 94.139776 -230.927127)
			(xy 94.368356 -230.927127) (xy 94.368356 -230.873829) (xy 94.376299 -230.821125) (xy 94.392009 -230.770195)
			(xy 94.415135 -230.722174) (xy 94.445159 -230.678137) (xy 94.481411 -230.639066) (xy 94.523082 -230.605835)
			(xy 94.56924 -230.579186) (xy 94.618854 -230.559714) (xy 94.670816 -230.547854) (xy 94.723966 -230.543871)
			(xy 94.777116 -230.547854) (xy 94.829078 -230.559714) (xy 94.878692 -230.579186) (xy 94.92485 -230.605835)
			(xy 94.966521 -230.639066) (xy 95.002773 -230.678137) (xy 95.032797 -230.722174) (xy 95.055923 -230.770195)
			(xy 95.071633 -230.821125) (xy 95.079576 -230.873829) (xy 95.080074 -230.900478) (xy 95.079576 -230.927127)
			(xy 95.308156 -230.927127) (xy 95.308156 -230.873829) (xy 95.316099 -230.821125) (xy 95.331809 -230.770195)
			(xy 95.354935 -230.722174) (xy 95.384959 -230.678137) (xy 95.421211 -230.639066) (xy 95.462882 -230.605835)
			(xy 95.50904 -230.579186) (xy 95.558654 -230.559714) (xy 95.610616 -230.547854) (xy 95.663766 -230.543871)
			(xy 95.716916 -230.547854) (xy 95.768878 -230.559714) (xy 95.818492 -230.579186) (xy 95.86465 -230.605835)
			(xy 95.906321 -230.639066) (xy 95.942573 -230.678137) (xy 95.972597 -230.722174) (xy 95.995723 -230.770195)
			(xy 96.011433 -230.821125) (xy 96.019376 -230.873829) (xy 96.019874 -230.900478) (xy 96.019376 -230.927127)
			(xy 96.247956 -230.927127) (xy 96.247956 -230.873829) (xy 96.255899 -230.821125) (xy 96.271609 -230.770195)
			(xy 96.294735 -230.722174) (xy 96.324759 -230.678137) (xy 96.361011 -230.639066) (xy 96.402682 -230.605835)
			(xy 96.44884 -230.579186) (xy 96.498454 -230.559714) (xy 96.550416 -230.547854) (xy 96.603566 -230.543871)
			(xy 96.656716 -230.547854) (xy 96.708678 -230.559714) (xy 96.758292 -230.579186) (xy 96.80445 -230.605835)
			(xy 96.846121 -230.639066) (xy 96.882373 -230.678137) (xy 96.912397 -230.722174) (xy 96.935523 -230.770195)
			(xy 96.951233 -230.821125) (xy 96.959176 -230.873829) (xy 96.959674 -230.900478) (xy 96.959176 -230.927127)
			(xy 97.187502 -230.927127) (xy 97.187502 -230.873829) (xy 97.195445 -230.821125) (xy 97.211155 -230.770195)
			(xy 97.234281 -230.722174) (xy 97.264305 -230.678137) (xy 97.300557 -230.639066) (xy 97.342228 -230.605835)
			(xy 97.388386 -230.579186) (xy 97.438 -230.559714) (xy 97.489962 -230.547854) (xy 97.543112 -230.543871)
			(xy 97.596262 -230.547854) (xy 97.648224 -230.559714) (xy 97.697838 -230.579186) (xy 97.743996 -230.605835)
			(xy 97.785667 -230.639066) (xy 97.821919 -230.678137) (xy 97.851943 -230.722174) (xy 97.875069 -230.770195)
			(xy 97.890779 -230.821125) (xy 97.898722 -230.873829) (xy 97.89922 -230.900478) (xy 97.898722 -230.927127)
			(xy 98.127556 -230.927127) (xy 98.127556 -230.873829) (xy 98.135499 -230.821125) (xy 98.151209 -230.770195)
			(xy 98.174335 -230.722174) (xy 98.204359 -230.678137) (xy 98.240611 -230.639066) (xy 98.282282 -230.605835)
			(xy 98.32844 -230.579186) (xy 98.378054 -230.559714) (xy 98.430016 -230.547854) (xy 98.483166 -230.543871)
			(xy 98.536316 -230.547854) (xy 98.588278 -230.559714) (xy 98.637892 -230.579186) (xy 98.68405 -230.605835)
			(xy 98.725721 -230.639066) (xy 98.761973 -230.678137) (xy 98.791997 -230.722174) (xy 98.815123 -230.770195)
			(xy 98.830833 -230.821125) (xy 98.838776 -230.873829) (xy 98.839274 -230.900478) (xy 98.838776 -230.927127)
			(xy 99.067356 -230.927127) (xy 99.067356 -230.873829) (xy 99.075299 -230.821125) (xy 99.091009 -230.770195)
			(xy 99.114135 -230.722174) (xy 99.144159 -230.678137) (xy 99.180411 -230.639066) (xy 99.222082 -230.605835)
			(xy 99.26824 -230.579186) (xy 99.317854 -230.559714) (xy 99.369816 -230.547854) (xy 99.422966 -230.543871)
			(xy 99.476116 -230.547854) (xy 99.528078 -230.559714) (xy 99.577692 -230.579186) (xy 99.62385 -230.605835)
			(xy 99.665521 -230.639066) (xy 99.701773 -230.678137) (xy 99.731797 -230.722174) (xy 99.754923 -230.770195)
			(xy 99.770633 -230.821125) (xy 99.778576 -230.873829) (xy 99.779074 -230.900478) (xy 99.778576 -230.927127)
			(xy 100.007156 -230.927127) (xy 100.007156 -230.873829) (xy 100.015099 -230.821125) (xy 100.030809 -230.770195)
			(xy 100.053935 -230.722174) (xy 100.083959 -230.678137) (xy 100.120211 -230.639066) (xy 100.161882 -230.605835)
			(xy 100.20804 -230.579186) (xy 100.257654 -230.559714) (xy 100.309616 -230.547854) (xy 100.362766 -230.543871)
			(xy 100.415916 -230.547854) (xy 100.467878 -230.559714) (xy 100.517492 -230.579186) (xy 100.56365 -230.605835)
			(xy 100.605321 -230.639066) (xy 100.641573 -230.678137) (xy 100.671597 -230.722174) (xy 100.694723 -230.770195)
			(xy 100.710433 -230.821125) (xy 100.718376 -230.873829) (xy 100.718874 -230.900478) (xy 100.718376 -230.927127)
			(xy 100.946956 -230.927127) (xy 100.946956 -230.873829) (xy 100.954899 -230.821125) (xy 100.970609 -230.770195)
			(xy 100.993735 -230.722174) (xy 101.023759 -230.678137) (xy 101.060011 -230.639066) (xy 101.101682 -230.605835)
			(xy 101.14784 -230.579186) (xy 101.197454 -230.559714) (xy 101.249416 -230.547854) (xy 101.302566 -230.543871)
			(xy 101.355716 -230.547854) (xy 101.407678 -230.559714) (xy 101.457292 -230.579186) (xy 101.50345 -230.605835)
			(xy 101.545121 -230.639066) (xy 101.581373 -230.678137) (xy 101.611397 -230.722174) (xy 101.634523 -230.770195)
			(xy 101.650233 -230.821125) (xy 101.658176 -230.873829) (xy 101.658674 -230.900478) (xy 101.658176 -230.927127)
			(xy 101.886756 -230.927127) (xy 101.886756 -230.873829) (xy 101.894699 -230.821125) (xy 101.910409 -230.770195)
			(xy 101.933535 -230.722174) (xy 101.963559 -230.678137) (xy 101.999811 -230.639066) (xy 102.041482 -230.605835)
			(xy 102.08764 -230.579186) (xy 102.137254 -230.559714) (xy 102.189216 -230.547854) (xy 102.242366 -230.543871)
			(xy 102.295516 -230.547854) (xy 102.347478 -230.559714) (xy 102.397092 -230.579186) (xy 102.44325 -230.605835)
			(xy 102.484921 -230.639066) (xy 102.521173 -230.678137) (xy 102.551197 -230.722174) (xy 102.574323 -230.770195)
			(xy 102.590033 -230.821125) (xy 102.597976 -230.873829) (xy 102.598474 -230.900478) (xy 102.597976 -230.927127)
			(xy 102.826556 -230.927127) (xy 102.826556 -230.873829) (xy 102.834499 -230.821125) (xy 102.850209 -230.770195)
			(xy 102.873335 -230.722174) (xy 102.903359 -230.678137) (xy 102.939611 -230.639066) (xy 102.981282 -230.605835)
			(xy 103.02744 -230.579186) (xy 103.077054 -230.559714) (xy 103.129016 -230.547854) (xy 103.182166 -230.543871)
			(xy 103.235316 -230.547854) (xy 103.287278 -230.559714) (xy 103.336892 -230.579186) (xy 103.38305 -230.605835)
			(xy 103.424721 -230.639066) (xy 103.460973 -230.678137) (xy 103.490997 -230.722174) (xy 103.514123 -230.770195)
			(xy 103.529833 -230.821125) (xy 103.537776 -230.873829) (xy 103.538274 -230.900478) (xy 103.537776 -230.927127)
			(xy 103.766356 -230.927127) (xy 103.766356 -230.873829) (xy 103.774299 -230.821125) (xy 103.790009 -230.770195)
			(xy 103.813135 -230.722174) (xy 103.843159 -230.678137) (xy 103.879411 -230.639066) (xy 103.921082 -230.605835)
			(xy 103.96724 -230.579186) (xy 104.016854 -230.559714) (xy 104.068816 -230.547854) (xy 104.121966 -230.543871)
			(xy 104.175116 -230.547854) (xy 104.227078 -230.559714) (xy 104.276692 -230.579186) (xy 104.32285 -230.605835)
			(xy 104.364521 -230.639066) (xy 104.400773 -230.678137) (xy 104.430797 -230.722174) (xy 104.453923 -230.770195)
			(xy 104.469633 -230.821125) (xy 104.477576 -230.873829) (xy 104.478074 -230.900478) (xy 104.477576 -230.927127)
			(xy 104.706156 -230.927127) (xy 104.706156 -230.873829) (xy 104.714099 -230.821125) (xy 104.729809 -230.770195)
			(xy 104.752935 -230.722174) (xy 104.782959 -230.678137) (xy 104.819211 -230.639066) (xy 104.860882 -230.605835)
			(xy 104.90704 -230.579186) (xy 104.956654 -230.559714) (xy 105.008616 -230.547854) (xy 105.061766 -230.543871)
			(xy 105.114916 -230.547854) (xy 105.166878 -230.559714) (xy 105.216492 -230.579186) (xy 105.26265 -230.605835)
			(xy 105.304321 -230.639066) (xy 105.340573 -230.678137) (xy 105.370597 -230.722174) (xy 105.393723 -230.770195)
			(xy 105.409433 -230.821125) (xy 105.417376 -230.873829) (xy 105.417874 -230.900478) (xy 105.417376 -230.927127)
			(xy 105.645956 -230.927127) (xy 105.645956 -230.873829) (xy 105.653899 -230.821125) (xy 105.669609 -230.770195)
			(xy 105.692735 -230.722174) (xy 105.722759 -230.678137) (xy 105.759011 -230.639066) (xy 105.800682 -230.605835)
			(xy 105.84684 -230.579186) (xy 105.896454 -230.559714) (xy 105.948416 -230.547854) (xy 106.001566 -230.543871)
			(xy 106.054716 -230.547854) (xy 106.106678 -230.559714) (xy 106.156292 -230.579186) (xy 106.20245 -230.605835)
			(xy 106.244121 -230.639066) (xy 106.280373 -230.678137) (xy 106.310397 -230.722174) (xy 106.333523 -230.770195)
			(xy 106.349233 -230.821125) (xy 106.357176 -230.873829) (xy 106.357674 -230.900478) (xy 106.357176 -230.927127)
			(xy 106.585756 -230.927127) (xy 106.585756 -230.873829) (xy 106.593699 -230.821125) (xy 106.609409 -230.770195)
			(xy 106.632535 -230.722174) (xy 106.662559 -230.678137) (xy 106.698811 -230.639066) (xy 106.740482 -230.605835)
			(xy 106.78664 -230.579186) (xy 106.836254 -230.559714) (xy 106.888216 -230.547854) (xy 106.941366 -230.543871)
			(xy 106.994516 -230.547854) (xy 107.046478 -230.559714) (xy 107.096092 -230.579186) (xy 107.14225 -230.605835)
			(xy 107.183921 -230.639066) (xy 107.220173 -230.678137) (xy 107.250197 -230.722174) (xy 107.273323 -230.770195)
			(xy 107.289033 -230.821125) (xy 107.296976 -230.873829) (xy 107.297474 -230.900478) (xy 107.296976 -230.927127)
			(xy 107.525302 -230.927127) (xy 107.525302 -230.873829) (xy 107.533245 -230.821125) (xy 107.548955 -230.770195)
			(xy 107.572081 -230.722174) (xy 107.602105 -230.678137) (xy 107.638357 -230.639066) (xy 107.680028 -230.605835)
			(xy 107.726186 -230.579186) (xy 107.7758 -230.559714) (xy 107.827762 -230.547854) (xy 107.880912 -230.543871)
			(xy 107.934062 -230.547854) (xy 107.986024 -230.559714) (xy 108.035638 -230.579186) (xy 108.081796 -230.605835)
			(xy 108.123467 -230.639066) (xy 108.159719 -230.678137) (xy 108.189743 -230.722174) (xy 108.212869 -230.770195)
			(xy 108.228579 -230.821125) (xy 108.236522 -230.873829) (xy 108.23702 -230.900478) (xy 108.236522 -230.927127)
			(xy 108.465356 -230.927127) (xy 108.465356 -230.873829) (xy 108.473299 -230.821125) (xy 108.489009 -230.770195)
			(xy 108.512135 -230.722174) (xy 108.542159 -230.678137) (xy 108.578411 -230.639066) (xy 108.620082 -230.605835)
			(xy 108.66624 -230.579186) (xy 108.715854 -230.559714) (xy 108.767816 -230.547854) (xy 108.820966 -230.543871)
			(xy 108.874116 -230.547854) (xy 108.926078 -230.559714) (xy 108.975692 -230.579186) (xy 109.02185 -230.605835)
			(xy 109.063521 -230.639066) (xy 109.099773 -230.678137) (xy 109.129797 -230.722174) (xy 109.152923 -230.770195)
			(xy 109.168633 -230.821125) (xy 109.176576 -230.873829) (xy 109.177074 -230.900478) (xy 109.176576 -230.927127)
			(xy 109.404902 -230.927127) (xy 109.404902 -230.873829) (xy 109.412845 -230.821125) (xy 109.428555 -230.770195)
			(xy 109.451681 -230.722174) (xy 109.481705 -230.678137) (xy 109.517957 -230.639066) (xy 109.559628 -230.605835)
			(xy 109.605786 -230.579186) (xy 109.6554 -230.559714) (xy 109.707362 -230.547854) (xy 109.760512 -230.543871)
			(xy 109.813662 -230.547854) (xy 109.865624 -230.559714) (xy 109.915238 -230.579186) (xy 109.961396 -230.605835)
			(xy 110.003067 -230.639066) (xy 110.039319 -230.678137) (xy 110.069343 -230.722174) (xy 110.092469 -230.770195)
			(xy 110.108179 -230.821125) (xy 110.116122 -230.873829) (xy 110.11662 -230.900478) (xy 110.116122 -230.927127)
			(xy 110.344956 -230.927127) (xy 110.344956 -230.873829) (xy 110.352899 -230.821125) (xy 110.368609 -230.770195)
			(xy 110.391735 -230.722174) (xy 110.421759 -230.678137) (xy 110.458011 -230.639066) (xy 110.499682 -230.605835)
			(xy 110.54584 -230.579186) (xy 110.595454 -230.559714) (xy 110.647416 -230.547854) (xy 110.700566 -230.543871)
			(xy 110.753716 -230.547854) (xy 110.805678 -230.559714) (xy 110.855292 -230.579186) (xy 110.90145 -230.605835)
			(xy 110.943121 -230.639066) (xy 110.979373 -230.678137) (xy 111.009397 -230.722174) (xy 111.032523 -230.770195)
			(xy 111.048233 -230.821125) (xy 111.056176 -230.873829) (xy 111.056674 -230.900478) (xy 111.056176 -230.927127)
			(xy 111.284756 -230.927127) (xy 111.284756 -230.873829) (xy 111.292699 -230.821125) (xy 111.308409 -230.770195)
			(xy 111.331535 -230.722174) (xy 111.361559 -230.678137) (xy 111.397811 -230.639066) (xy 111.439482 -230.605835)
			(xy 111.48564 -230.579186) (xy 111.535254 -230.559714) (xy 111.587216 -230.547854) (xy 111.640366 -230.543871)
			(xy 111.693516 -230.547854) (xy 111.745478 -230.559714) (xy 111.795092 -230.579186) (xy 111.84125 -230.605835)
			(xy 111.882921 -230.639066) (xy 111.919173 -230.678137) (xy 111.949197 -230.722174) (xy 111.972323 -230.770195)
			(xy 111.988033 -230.821125) (xy 111.995976 -230.873829) (xy 111.996474 -230.900478) (xy 111.995976 -230.927127)
			(xy 112.224556 -230.927127) (xy 112.224556 -230.873829) (xy 112.232499 -230.821125) (xy 112.248209 -230.770195)
			(xy 112.271335 -230.722174) (xy 112.301359 -230.678137) (xy 112.337611 -230.639066) (xy 112.379282 -230.605835)
			(xy 112.42544 -230.579186) (xy 112.475054 -230.559714) (xy 112.527016 -230.547854) (xy 112.580166 -230.543871)
			(xy 112.633316 -230.547854) (xy 112.685278 -230.559714) (xy 112.734892 -230.579186) (xy 112.78105 -230.605835)
			(xy 112.822721 -230.639066) (xy 112.858973 -230.678137) (xy 112.888997 -230.722174) (xy 112.912123 -230.770195)
			(xy 112.927833 -230.821125) (xy 112.935776 -230.873829) (xy 112.936274 -230.900478) (xy 112.935776 -230.927127)
			(xy 113.164356 -230.927127) (xy 113.164356 -230.873829) (xy 113.172299 -230.821125) (xy 113.188009 -230.770195)
			(xy 113.211135 -230.722174) (xy 113.241159 -230.678137) (xy 113.277411 -230.639066) (xy 113.319082 -230.605835)
			(xy 113.36524 -230.579186) (xy 113.414854 -230.559714) (xy 113.466816 -230.547854) (xy 113.519966 -230.543871)
			(xy 113.573116 -230.547854) (xy 113.625078 -230.559714) (xy 113.674692 -230.579186) (xy 113.72085 -230.605835)
			(xy 113.762521 -230.639066) (xy 113.798773 -230.678137) (xy 113.828797 -230.722174) (xy 113.851923 -230.770195)
			(xy 113.867633 -230.821125) (xy 113.875576 -230.873829) (xy 113.876074 -230.900478) (xy 113.875576 -230.927127)
			(xy 114.10441 -230.927127) (xy 114.10441 -230.873829) (xy 114.112353 -230.821125) (xy 114.128063 -230.770195)
			(xy 114.151189 -230.722174) (xy 114.181213 -230.678137) (xy 114.217465 -230.639066) (xy 114.259136 -230.605835)
			(xy 114.305294 -230.579186) (xy 114.354908 -230.559714) (xy 114.40687 -230.547854) (xy 114.46002 -230.543871)
			(xy 114.51317 -230.547854) (xy 114.565132 -230.559714) (xy 114.614746 -230.579186) (xy 114.660904 -230.605835)
			(xy 114.702575 -230.639066) (xy 114.738827 -230.678137) (xy 114.768851 -230.722174) (xy 114.791977 -230.770195)
			(xy 114.807687 -230.821125) (xy 114.81563 -230.873829) (xy 114.816128 -230.900478) (xy 114.81563 -230.927127)
			(xy 115.043956 -230.927127) (xy 115.043956 -230.873829) (xy 115.051899 -230.821125) (xy 115.067609 -230.770195)
			(xy 115.090735 -230.722174) (xy 115.120759 -230.678137) (xy 115.157011 -230.639066) (xy 115.198682 -230.605835)
			(xy 115.24484 -230.579186) (xy 115.294454 -230.559714) (xy 115.346416 -230.547854) (xy 115.399566 -230.543871)
			(xy 115.452716 -230.547854) (xy 115.504678 -230.559714) (xy 115.554292 -230.579186) (xy 115.60045 -230.605835)
			(xy 115.642121 -230.639066) (xy 115.678373 -230.678137) (xy 115.708397 -230.722174) (xy 115.731523 -230.770195)
			(xy 115.747233 -230.821125) (xy 115.755176 -230.873829) (xy 115.755674 -230.900478) (xy 115.755176 -230.927127)
			(xy 115.983756 -230.927127) (xy 115.983756 -230.873829) (xy 115.991699 -230.821125) (xy 116.007409 -230.770195)
			(xy 116.030535 -230.722174) (xy 116.060559 -230.678137) (xy 116.096811 -230.639066) (xy 116.138482 -230.605835)
			(xy 116.18464 -230.579186) (xy 116.234254 -230.559714) (xy 116.286216 -230.547854) (xy 116.339366 -230.543871)
			(xy 116.392516 -230.547854) (xy 116.444478 -230.559714) (xy 116.494092 -230.579186) (xy 116.54025 -230.605835)
			(xy 116.581921 -230.639066) (xy 116.618173 -230.678137) (xy 116.648197 -230.722174) (xy 116.671323 -230.770195)
			(xy 116.687033 -230.821125) (xy 116.694976 -230.873829) (xy 116.695474 -230.900478) (xy 116.694976 -230.927127)
			(xy 116.923556 -230.927127) (xy 116.923556 -230.873829) (xy 116.931499 -230.821125) (xy 116.947209 -230.770195)
			(xy 116.970335 -230.722174) (xy 117.000359 -230.678137) (xy 117.036611 -230.639066) (xy 117.078282 -230.605835)
			(xy 117.12444 -230.579186) (xy 117.174054 -230.559714) (xy 117.226016 -230.547854) (xy 117.279166 -230.543871)
			(xy 117.332316 -230.547854) (xy 117.384278 -230.559714) (xy 117.433892 -230.579186) (xy 117.48005 -230.605835)
			(xy 117.521721 -230.639066) (xy 117.557973 -230.678137) (xy 117.587997 -230.722174) (xy 117.611123 -230.770195)
			(xy 117.626833 -230.821125) (xy 117.634776 -230.873829) (xy 117.635274 -230.900478) (xy 117.634776 -230.927127)
			(xy 117.863356 -230.927127) (xy 117.863356 -230.873829) (xy 117.871299 -230.821125) (xy 117.887009 -230.770195)
			(xy 117.910135 -230.722174) (xy 117.940159 -230.678137) (xy 117.976411 -230.639066) (xy 118.018082 -230.605835)
			(xy 118.06424 -230.579186) (xy 118.113854 -230.559714) (xy 118.165816 -230.547854) (xy 118.218966 -230.543871)
			(xy 118.272116 -230.547854) (xy 118.324078 -230.559714) (xy 118.373692 -230.579186) (xy 118.41985 -230.605835)
			(xy 118.461521 -230.639066) (xy 118.497773 -230.678137) (xy 118.527797 -230.722174) (xy 118.550923 -230.770195)
			(xy 118.566633 -230.821125) (xy 118.574576 -230.873829) (xy 118.575074 -230.900478) (xy 118.574576 -230.927127)
			(xy 118.803156 -230.927127) (xy 118.803156 -230.873829) (xy 118.811099 -230.821125) (xy 118.826809 -230.770195)
			(xy 118.849935 -230.722174) (xy 118.879959 -230.678137) (xy 118.916211 -230.639066) (xy 118.957882 -230.605835)
			(xy 119.00404 -230.579186) (xy 119.053654 -230.559714) (xy 119.105616 -230.547854) (xy 119.158766 -230.543871)
			(xy 119.211916 -230.547854) (xy 119.263878 -230.559714) (xy 119.313492 -230.579186) (xy 119.35965 -230.605835)
			(xy 119.401321 -230.639066) (xy 119.437573 -230.678137) (xy 119.467597 -230.722174) (xy 119.490723 -230.770195)
			(xy 119.506433 -230.821125) (xy 119.514376 -230.873829) (xy 119.514874 -230.900478) (xy 119.514376 -230.927127)
			(xy 119.742956 -230.927127) (xy 119.742956 -230.873829) (xy 119.750899 -230.821125) (xy 119.766609 -230.770195)
			(xy 119.789735 -230.722174) (xy 119.819759 -230.678137) (xy 119.856011 -230.639066) (xy 119.897682 -230.605835)
			(xy 119.94384 -230.579186) (xy 119.993454 -230.559714) (xy 120.045416 -230.547854) (xy 120.098566 -230.543871)
			(xy 120.151716 -230.547854) (xy 120.203678 -230.559714) (xy 120.253292 -230.579186) (xy 120.29945 -230.605835)
			(xy 120.341121 -230.639066) (xy 120.377373 -230.678137) (xy 120.407397 -230.722174) (xy 120.430523 -230.770195)
			(xy 120.446233 -230.821125) (xy 120.454176 -230.873829) (xy 120.454674 -230.900478) (xy 120.454176 -230.927127)
			(xy 120.682756 -230.927127) (xy 120.682756 -230.873829) (xy 120.690699 -230.821125) (xy 120.706409 -230.770195)
			(xy 120.729535 -230.722174) (xy 120.759559 -230.678137) (xy 120.795811 -230.639066) (xy 120.837482 -230.605835)
			(xy 120.88364 -230.579186) (xy 120.933254 -230.559714) (xy 120.985216 -230.547854) (xy 121.038366 -230.543871)
			(xy 121.091516 -230.547854) (xy 121.143478 -230.559714) (xy 121.193092 -230.579186) (xy 121.23925 -230.605835)
			(xy 121.280921 -230.639066) (xy 121.317173 -230.678137) (xy 121.347197 -230.722174) (xy 121.370323 -230.770195)
			(xy 121.386033 -230.821125) (xy 121.393976 -230.873829) (xy 121.394474 -230.900478) (xy 121.393976 -230.927127)
			(xy 121.622302 -230.927127) (xy 121.622302 -230.873829) (xy 121.630245 -230.821125) (xy 121.645955 -230.770195)
			(xy 121.669081 -230.722174) (xy 121.699105 -230.678137) (xy 121.735357 -230.639066) (xy 121.777028 -230.605835)
			(xy 121.823186 -230.579186) (xy 121.8728 -230.559714) (xy 121.924762 -230.547854) (xy 121.977912 -230.543871)
			(xy 122.031062 -230.547854) (xy 122.083024 -230.559714) (xy 122.132638 -230.579186) (xy 122.178796 -230.605835)
			(xy 122.220467 -230.639066) (xy 122.256719 -230.678137) (xy 122.286743 -230.722174) (xy 122.309869 -230.770195)
			(xy 122.325579 -230.821125) (xy 122.333522 -230.873829) (xy 122.33402 -230.900478) (xy 122.333522 -230.927127)
			(xy 122.562356 -230.927127) (xy 122.562356 -230.873829) (xy 122.570299 -230.821125) (xy 122.586009 -230.770195)
			(xy 122.609135 -230.722174) (xy 122.639159 -230.678137) (xy 122.675411 -230.639066) (xy 122.717082 -230.605835)
			(xy 122.76324 -230.579186) (xy 122.812854 -230.559714) (xy 122.864816 -230.547854) (xy 122.917966 -230.543871)
			(xy 122.971116 -230.547854) (xy 123.023078 -230.559714) (xy 123.072692 -230.579186) (xy 123.11885 -230.605835)
			(xy 123.160521 -230.639066) (xy 123.196773 -230.678137) (xy 123.226797 -230.722174) (xy 123.249923 -230.770195)
			(xy 123.265633 -230.821125) (xy 123.273576 -230.873829) (xy 123.274074 -230.900478) (xy 123.273576 -230.927127)
			(xy 123.502156 -230.927127) (xy 123.502156 -230.873829) (xy 123.510099 -230.821125) (xy 123.525809 -230.770195)
			(xy 123.548935 -230.722174) (xy 123.578959 -230.678137) (xy 123.615211 -230.639066) (xy 123.656882 -230.605835)
			(xy 123.70304 -230.579186) (xy 123.752654 -230.559714) (xy 123.804616 -230.547854) (xy 123.857766 -230.543871)
			(xy 123.910916 -230.547854) (xy 123.962878 -230.559714) (xy 124.012492 -230.579186) (xy 124.05865 -230.605835)
			(xy 124.100321 -230.639066) (xy 124.136573 -230.678137) (xy 124.166597 -230.722174) (xy 124.189723 -230.770195)
			(xy 124.205433 -230.821125) (xy 124.213376 -230.873829) (xy 124.213874 -230.900478) (xy 124.213376 -230.927127)
			(xy 124.441956 -230.927127) (xy 124.441956 -230.873829) (xy 124.449899 -230.821125) (xy 124.465609 -230.770195)
			(xy 124.488735 -230.722174) (xy 124.518759 -230.678137) (xy 124.555011 -230.639066) (xy 124.596682 -230.605835)
			(xy 124.64284 -230.579186) (xy 124.692454 -230.559714) (xy 124.744416 -230.547854) (xy 124.797566 -230.543871)
			(xy 124.850716 -230.547854) (xy 124.902678 -230.559714) (xy 124.952292 -230.579186) (xy 124.99845 -230.605835)
			(xy 125.040121 -230.639066) (xy 125.076373 -230.678137) (xy 125.106397 -230.722174) (xy 125.129523 -230.770195)
			(xy 125.145233 -230.821125) (xy 125.153176 -230.873829) (xy 125.153674 -230.900478) (xy 125.153176 -230.927127)
			(xy 125.381756 -230.927127) (xy 125.381756 -230.873829) (xy 125.389699 -230.821125) (xy 125.405409 -230.770195)
			(xy 125.428535 -230.722174) (xy 125.458559 -230.678137) (xy 125.494811 -230.639066) (xy 125.536482 -230.605835)
			(xy 125.58264 -230.579186) (xy 125.632254 -230.559714) (xy 125.684216 -230.547854) (xy 125.737366 -230.543871)
			(xy 125.790516 -230.547854) (xy 125.842478 -230.559714) (xy 125.892092 -230.579186) (xy 125.93825 -230.605835)
			(xy 125.979921 -230.639066) (xy 126.016173 -230.678137) (xy 126.046197 -230.722174) (xy 126.069323 -230.770195)
			(xy 126.085033 -230.821125) (xy 126.092976 -230.873829) (xy 126.093474 -230.900478) (xy 126.092976 -230.927127)
			(xy 126.321556 -230.927127) (xy 126.321556 -230.873829) (xy 126.329499 -230.821125) (xy 126.345209 -230.770195)
			(xy 126.368335 -230.722174) (xy 126.398359 -230.678137) (xy 126.434611 -230.639066) (xy 126.476282 -230.605835)
			(xy 126.52244 -230.579186) (xy 126.572054 -230.559714) (xy 126.624016 -230.547854) (xy 126.677166 -230.543871)
			(xy 126.730316 -230.547854) (xy 126.782278 -230.559714) (xy 126.831892 -230.579186) (xy 126.87805 -230.605835)
			(xy 126.919721 -230.639066) (xy 126.955973 -230.678137) (xy 126.985997 -230.722174) (xy 127.009123 -230.770195)
			(xy 127.024833 -230.821125) (xy 127.032776 -230.873829) (xy 127.033274 -230.900478) (xy 127.032776 -230.927127)
			(xy 127.261356 -230.927127) (xy 127.261356 -230.873829) (xy 127.269299 -230.821125) (xy 127.285009 -230.770195)
			(xy 127.308135 -230.722174) (xy 127.338159 -230.678137) (xy 127.374411 -230.639066) (xy 127.416082 -230.605835)
			(xy 127.46224 -230.579186) (xy 127.511854 -230.559714) (xy 127.563816 -230.547854) (xy 127.616966 -230.543871)
			(xy 127.670116 -230.547854) (xy 127.722078 -230.559714) (xy 127.771692 -230.579186) (xy 127.81785 -230.605835)
			(xy 127.859521 -230.639066) (xy 127.895773 -230.678137) (xy 127.925797 -230.722174) (xy 127.948923 -230.770195)
			(xy 127.964633 -230.821125) (xy 127.972576 -230.873829) (xy 127.973074 -230.900478) (xy 127.972576 -230.927127)
			(xy 128.201156 -230.927127) (xy 128.201156 -230.873829) (xy 128.209099 -230.821125) (xy 128.224809 -230.770195)
			(xy 128.247935 -230.722174) (xy 128.277959 -230.678137) (xy 128.314211 -230.639066) (xy 128.355882 -230.605835)
			(xy 128.40204 -230.579186) (xy 128.451654 -230.559714) (xy 128.503616 -230.547854) (xy 128.556766 -230.543871)
			(xy 128.609916 -230.547854) (xy 128.661878 -230.559714) (xy 128.711492 -230.579186) (xy 128.75765 -230.605835)
			(xy 128.799321 -230.639066) (xy 128.835573 -230.678137) (xy 128.865597 -230.722174) (xy 128.888723 -230.770195)
			(xy 128.904433 -230.821125) (xy 128.912376 -230.873829) (xy 128.912874 -230.900478) (xy 128.912376 -230.927127)
			(xy 129.140956 -230.927127) (xy 129.140956 -230.873829) (xy 129.148899 -230.821125) (xy 129.164609 -230.770195)
			(xy 129.187735 -230.722174) (xy 129.217759 -230.678137) (xy 129.254011 -230.639066) (xy 129.295682 -230.605835)
			(xy 129.34184 -230.579186) (xy 129.391454 -230.559714) (xy 129.443416 -230.547854) (xy 129.496566 -230.543871)
			(xy 129.549716 -230.547854) (xy 129.601678 -230.559714) (xy 129.651292 -230.579186) (xy 129.69745 -230.605835)
			(xy 129.739121 -230.639066) (xy 129.775373 -230.678137) (xy 129.805397 -230.722174) (xy 129.828523 -230.770195)
			(xy 129.844233 -230.821125) (xy 129.852176 -230.873829) (xy 129.852674 -230.900478) (xy 129.852176 -230.927127)
			(xy 130.080756 -230.927127) (xy 130.080756 -230.873829) (xy 130.088699 -230.821125) (xy 130.104409 -230.770195)
			(xy 130.127535 -230.722174) (xy 130.157559 -230.678137) (xy 130.193811 -230.639066) (xy 130.235482 -230.605835)
			(xy 130.28164 -230.579186) (xy 130.331254 -230.559714) (xy 130.383216 -230.547854) (xy 130.436366 -230.543871)
			(xy 130.489516 -230.547854) (xy 130.541478 -230.559714) (xy 130.591092 -230.579186) (xy 130.63725 -230.605835)
			(xy 130.678921 -230.639066) (xy 130.715173 -230.678137) (xy 130.745197 -230.722174) (xy 130.768323 -230.770195)
			(xy 130.784033 -230.821125) (xy 130.791976 -230.873829) (xy 130.792474 -230.900478) (xy 130.791976 -230.927127)
			(xy 131.020556 -230.927127) (xy 131.020556 -230.873829) (xy 131.028499 -230.821125) (xy 131.044209 -230.770195)
			(xy 131.067335 -230.722174) (xy 131.097359 -230.678137) (xy 131.133611 -230.639066) (xy 131.175282 -230.605835)
			(xy 131.22144 -230.579186) (xy 131.271054 -230.559714) (xy 131.323016 -230.547854) (xy 131.376166 -230.543871)
			(xy 131.429316 -230.547854) (xy 131.481278 -230.559714) (xy 131.530892 -230.579186) (xy 131.57705 -230.605835)
			(xy 131.618721 -230.639066) (xy 131.654973 -230.678137) (xy 131.684997 -230.722174) (xy 131.708123 -230.770195)
			(xy 131.723833 -230.821125) (xy 131.731776 -230.873829) (xy 131.732274 -230.900478) (xy 131.731776 -230.927127)
			(xy 131.960102 -230.927127) (xy 131.960102 -230.873829) (xy 131.968045 -230.821125) (xy 131.983755 -230.770195)
			(xy 132.006881 -230.722174) (xy 132.036905 -230.678137) (xy 132.073157 -230.639066) (xy 132.114828 -230.605835)
			(xy 132.160986 -230.579186) (xy 132.2106 -230.559714) (xy 132.262562 -230.547854) (xy 132.315712 -230.543871)
			(xy 132.368862 -230.547854) (xy 132.420824 -230.559714) (xy 132.470438 -230.579186) (xy 132.516596 -230.605835)
			(xy 132.558267 -230.639066) (xy 132.594519 -230.678137) (xy 132.624543 -230.722174) (xy 132.647669 -230.770195)
			(xy 132.663379 -230.821125) (xy 132.671322 -230.873829) (xy 132.67182 -230.900478) (xy 132.671322 -230.927127)
			(xy 132.900156 -230.927127) (xy 132.900156 -230.873829) (xy 132.908099 -230.821125) (xy 132.923809 -230.770195)
			(xy 132.946935 -230.722174) (xy 132.976959 -230.678137) (xy 133.013211 -230.639066) (xy 133.054882 -230.605835)
			(xy 133.10104 -230.579186) (xy 133.150654 -230.559714) (xy 133.202616 -230.547854) (xy 133.255766 -230.543871)
			(xy 133.308916 -230.547854) (xy 133.360878 -230.559714) (xy 133.410492 -230.579186) (xy 133.45665 -230.605835)
			(xy 133.498321 -230.639066) (xy 133.534573 -230.678137) (xy 133.564597 -230.722174) (xy 133.587723 -230.770195)
			(xy 133.603433 -230.821125) (xy 133.611376 -230.873829) (xy 133.611874 -230.900478) (xy 133.611376 -230.927127)
			(xy 133.839956 -230.927127) (xy 133.839956 -230.873829) (xy 133.847899 -230.821125) (xy 133.863609 -230.770195)
			(xy 133.886735 -230.722174) (xy 133.916759 -230.678137) (xy 133.953011 -230.639066) (xy 133.994682 -230.605835)
			(xy 134.04084 -230.579186) (xy 134.090454 -230.559714) (xy 134.142416 -230.547854) (xy 134.195566 -230.543871)
			(xy 134.248716 -230.547854) (xy 134.300678 -230.559714) (xy 134.350292 -230.579186) (xy 134.39645 -230.605835)
			(xy 134.438121 -230.639066) (xy 134.474373 -230.678137) (xy 134.504397 -230.722174) (xy 134.527523 -230.770195)
			(xy 134.543233 -230.821125) (xy 134.551176 -230.873829) (xy 134.551674 -230.900478) (xy 134.551176 -230.927127)
			(xy 134.543233 -230.979831) (xy 134.527523 -231.030761) (xy 134.504397 -231.078782) (xy 134.474373 -231.122819)
			(xy 134.438121 -231.16189) (xy 134.39645 -231.195121) (xy 134.350292 -231.22177) (xy 134.300678 -231.241242)
			(xy 134.248716 -231.253102) (xy 134.195566 -231.257086) (xy 134.142416 -231.253102) (xy 134.090454 -231.241242)
			(xy 134.04084 -231.22177) (xy 133.994682 -231.195121) (xy 133.953011 -231.16189) (xy 133.916759 -231.122819)
			(xy 133.886735 -231.078782) (xy 133.863609 -231.030761) (xy 133.847899 -230.979831) (xy 133.839956 -230.927127)
			(xy 133.611376 -230.927127) (xy 133.603433 -230.979831) (xy 133.587723 -231.030761) (xy 133.564597 -231.078782)
			(xy 133.534573 -231.122819) (xy 133.498321 -231.16189) (xy 133.45665 -231.195121) (xy 133.410492 -231.22177)
			(xy 133.360878 -231.241242) (xy 133.308916 -231.253102) (xy 133.255766 -231.257086) (xy 133.202616 -231.253102)
			(xy 133.150654 -231.241242) (xy 133.10104 -231.22177) (xy 133.054882 -231.195121) (xy 133.013211 -231.16189)
			(xy 132.976959 -231.122819) (xy 132.946935 -231.078782) (xy 132.923809 -231.030761) (xy 132.908099 -230.979831)
			(xy 132.900156 -230.927127) (xy 132.671322 -230.927127) (xy 132.663379 -230.979831) (xy 132.647669 -231.030761)
			(xy 132.624543 -231.078782) (xy 132.594519 -231.122819) (xy 132.558267 -231.16189) (xy 132.516596 -231.195121)
			(xy 132.470438 -231.22177) (xy 132.420824 -231.241242) (xy 132.368862 -231.253102) (xy 132.315712 -231.257086)
			(xy 132.262562 -231.253102) (xy 132.2106 -231.241242) (xy 132.160986 -231.22177) (xy 132.114828 -231.195121)
			(xy 132.073157 -231.16189) (xy 132.036905 -231.122819) (xy 132.006881 -231.078782) (xy 131.983755 -231.030761)
			(xy 131.968045 -230.979831) (xy 131.960102 -230.927127) (xy 131.731776 -230.927127) (xy 131.723833 -230.979831)
			(xy 131.708123 -231.030761) (xy 131.684997 -231.078782) (xy 131.654973 -231.122819) (xy 131.618721 -231.16189)
			(xy 131.57705 -231.195121) (xy 131.530892 -231.22177) (xy 131.481278 -231.241242) (xy 131.429316 -231.253102)
			(xy 131.376166 -231.257086) (xy 131.323016 -231.253102) (xy 131.271054 -231.241242) (xy 131.22144 -231.22177)
			(xy 131.175282 -231.195121) (xy 131.133611 -231.16189) (xy 131.097359 -231.122819) (xy 131.067335 -231.078782)
			(xy 131.044209 -231.030761) (xy 131.028499 -230.979831) (xy 131.020556 -230.927127) (xy 130.791976 -230.927127)
			(xy 130.784033 -230.979831) (xy 130.768323 -231.030761) (xy 130.745197 -231.078782) (xy 130.715173 -231.122819)
			(xy 130.678921 -231.16189) (xy 130.63725 -231.195121) (xy 130.591092 -231.22177) (xy 130.541478 -231.241242)
			(xy 130.489516 -231.253102) (xy 130.436366 -231.257086) (xy 130.383216 -231.253102) (xy 130.331254 -231.241242)
			(xy 130.28164 -231.22177) (xy 130.235482 -231.195121) (xy 130.193811 -231.16189) (xy 130.157559 -231.122819)
			(xy 130.127535 -231.078782) (xy 130.104409 -231.030761) (xy 130.088699 -230.979831) (xy 130.080756 -230.927127)
			(xy 129.852176 -230.927127) (xy 129.844233 -230.979831) (xy 129.828523 -231.030761) (xy 129.805397 -231.078782)
			(xy 129.775373 -231.122819) (xy 129.739121 -231.16189) (xy 129.69745 -231.195121) (xy 129.651292 -231.22177)
			(xy 129.601678 -231.241242) (xy 129.549716 -231.253102) (xy 129.496566 -231.257086) (xy 129.443416 -231.253102)
			(xy 129.391454 -231.241242) (xy 129.34184 -231.22177) (xy 129.295682 -231.195121) (xy 129.254011 -231.16189)
			(xy 129.217759 -231.122819) (xy 129.187735 -231.078782) (xy 129.164609 -231.030761) (xy 129.148899 -230.979831)
			(xy 129.140956 -230.927127) (xy 128.912376 -230.927127) (xy 128.904433 -230.979831) (xy 128.888723 -231.030761)
			(xy 128.865597 -231.078782) (xy 128.835573 -231.122819) (xy 128.799321 -231.16189) (xy 128.75765 -231.195121)
			(xy 128.711492 -231.22177) (xy 128.661878 -231.241242) (xy 128.609916 -231.253102) (xy 128.556766 -231.257086)
			(xy 128.503616 -231.253102) (xy 128.451654 -231.241242) (xy 128.40204 -231.22177) (xy 128.355882 -231.195121)
			(xy 128.314211 -231.16189) (xy 128.277959 -231.122819) (xy 128.247935 -231.078782) (xy 128.224809 -231.030761)
			(xy 128.209099 -230.979831) (xy 128.201156 -230.927127) (xy 127.972576 -230.927127) (xy 127.964633 -230.979831)
			(xy 127.948923 -231.030761) (xy 127.925797 -231.078782) (xy 127.895773 -231.122819) (xy 127.859521 -231.16189)
			(xy 127.81785 -231.195121) (xy 127.771692 -231.22177) (xy 127.722078 -231.241242) (xy 127.670116 -231.253102)
			(xy 127.616966 -231.257086) (xy 127.563816 -231.253102) (xy 127.511854 -231.241242) (xy 127.46224 -231.22177)
			(xy 127.416082 -231.195121) (xy 127.374411 -231.16189) (xy 127.338159 -231.122819) (xy 127.308135 -231.078782)
			(xy 127.285009 -231.030761) (xy 127.269299 -230.979831) (xy 127.261356 -230.927127) (xy 127.032776 -230.927127)
			(xy 127.024833 -230.979831) (xy 127.009123 -231.030761) (xy 126.985997 -231.078782) (xy 126.955973 -231.122819)
			(xy 126.919721 -231.16189) (xy 126.87805 -231.195121) (xy 126.831892 -231.22177) (xy 126.782278 -231.241242)
			(xy 126.730316 -231.253102) (xy 126.677166 -231.257086) (xy 126.624016 -231.253102) (xy 126.572054 -231.241242)
			(xy 126.52244 -231.22177) (xy 126.476282 -231.195121) (xy 126.434611 -231.16189) (xy 126.398359 -231.122819)
			(xy 126.368335 -231.078782) (xy 126.345209 -231.030761) (xy 126.329499 -230.979831) (xy 126.321556 -230.927127)
			(xy 126.092976 -230.927127) (xy 126.085033 -230.979831) (xy 126.069323 -231.030761) (xy 126.046197 -231.078782)
			(xy 126.016173 -231.122819) (xy 125.979921 -231.16189) (xy 125.93825 -231.195121) (xy 125.892092 -231.22177)
			(xy 125.842478 -231.241242) (xy 125.790516 -231.253102) (xy 125.737366 -231.257086) (xy 125.684216 -231.253102)
			(xy 125.632254 -231.241242) (xy 125.58264 -231.22177) (xy 125.536482 -231.195121) (xy 125.494811 -231.16189)
			(xy 125.458559 -231.122819) (xy 125.428535 -231.078782) (xy 125.405409 -231.030761) (xy 125.389699 -230.979831)
			(xy 125.381756 -230.927127) (xy 125.153176 -230.927127) (xy 125.145233 -230.979831) (xy 125.129523 -231.030761)
			(xy 125.106397 -231.078782) (xy 125.076373 -231.122819) (xy 125.040121 -231.16189) (xy 124.99845 -231.195121)
			(xy 124.952292 -231.22177) (xy 124.902678 -231.241242) (xy 124.850716 -231.253102) (xy 124.797566 -231.257086)
			(xy 124.744416 -231.253102) (xy 124.692454 -231.241242) (xy 124.64284 -231.22177) (xy 124.596682 -231.195121)
			(xy 124.555011 -231.16189) (xy 124.518759 -231.122819) (xy 124.488735 -231.078782) (xy 124.465609 -231.030761)
			(xy 124.449899 -230.979831) (xy 124.441956 -230.927127) (xy 124.213376 -230.927127) (xy 124.205433 -230.979831)
			(xy 124.189723 -231.030761) (xy 124.166597 -231.078782) (xy 124.136573 -231.122819) (xy 124.100321 -231.16189)
			(xy 124.05865 -231.195121) (xy 124.012492 -231.22177) (xy 123.962878 -231.241242) (xy 123.910916 -231.253102)
			(xy 123.857766 -231.257086) (xy 123.804616 -231.253102) (xy 123.752654 -231.241242) (xy 123.70304 -231.22177)
			(xy 123.656882 -231.195121) (xy 123.615211 -231.16189) (xy 123.578959 -231.122819) (xy 123.548935 -231.078782)
			(xy 123.525809 -231.030761) (xy 123.510099 -230.979831) (xy 123.502156 -230.927127) (xy 123.273576 -230.927127)
			(xy 123.265633 -230.979831) (xy 123.249923 -231.030761) (xy 123.226797 -231.078782) (xy 123.196773 -231.122819)
			(xy 123.160521 -231.16189) (xy 123.11885 -231.195121) (xy 123.072692 -231.22177) (xy 123.023078 -231.241242)
			(xy 122.971116 -231.253102) (xy 122.917966 -231.257086) (xy 122.864816 -231.253102) (xy 122.812854 -231.241242)
			(xy 122.76324 -231.22177) (xy 122.717082 -231.195121) (xy 122.675411 -231.16189) (xy 122.639159 -231.122819)
			(xy 122.609135 -231.078782) (xy 122.586009 -231.030761) (xy 122.570299 -230.979831) (xy 122.562356 -230.927127)
			(xy 122.333522 -230.927127) (xy 122.325579 -230.979831) (xy 122.309869 -231.030761) (xy 122.286743 -231.078782)
			(xy 122.256719 -231.122819) (xy 122.220467 -231.16189) (xy 122.178796 -231.195121) (xy 122.132638 -231.22177)
			(xy 122.083024 -231.241242) (xy 122.031062 -231.253102) (xy 121.977912 -231.257086) (xy 121.924762 -231.253102)
			(xy 121.8728 -231.241242) (xy 121.823186 -231.22177) (xy 121.777028 -231.195121) (xy 121.735357 -231.16189)
			(xy 121.699105 -231.122819) (xy 121.669081 -231.078782) (xy 121.645955 -231.030761) (xy 121.630245 -230.979831)
			(xy 121.622302 -230.927127) (xy 121.393976 -230.927127) (xy 121.386033 -230.979831) (xy 121.370323 -231.030761)
			(xy 121.347197 -231.078782) (xy 121.317173 -231.122819) (xy 121.280921 -231.16189) (xy 121.23925 -231.195121)
			(xy 121.193092 -231.22177) (xy 121.143478 -231.241242) (xy 121.091516 -231.253102) (xy 121.038366 -231.257086)
			(xy 120.985216 -231.253102) (xy 120.933254 -231.241242) (xy 120.88364 -231.22177) (xy 120.837482 -231.195121)
			(xy 120.795811 -231.16189) (xy 120.759559 -231.122819) (xy 120.729535 -231.078782) (xy 120.706409 -231.030761)
			(xy 120.690699 -230.979831) (xy 120.682756 -230.927127) (xy 120.454176 -230.927127) (xy 120.446233 -230.979831)
			(xy 120.430523 -231.030761) (xy 120.407397 -231.078782) (xy 120.377373 -231.122819) (xy 120.341121 -231.16189)
			(xy 120.29945 -231.195121) (xy 120.253292 -231.22177) (xy 120.203678 -231.241242) (xy 120.151716 -231.253102)
			(xy 120.098566 -231.257086) (xy 120.045416 -231.253102) (xy 119.993454 -231.241242) (xy 119.94384 -231.22177)
			(xy 119.897682 -231.195121) (xy 119.856011 -231.16189) (xy 119.819759 -231.122819) (xy 119.789735 -231.078782)
			(xy 119.766609 -231.030761) (xy 119.750899 -230.979831) (xy 119.742956 -230.927127) (xy 119.514376 -230.927127)
			(xy 119.506433 -230.979831) (xy 119.490723 -231.030761) (xy 119.467597 -231.078782) (xy 119.437573 -231.122819)
			(xy 119.401321 -231.16189) (xy 119.35965 -231.195121) (xy 119.313492 -231.22177) (xy 119.263878 -231.241242)
			(xy 119.211916 -231.253102) (xy 119.158766 -231.257086) (xy 119.105616 -231.253102) (xy 119.053654 -231.241242)
			(xy 119.00404 -231.22177) (xy 118.957882 -231.195121) (xy 118.916211 -231.16189) (xy 118.879959 -231.122819)
			(xy 118.849935 -231.078782) (xy 118.826809 -231.030761) (xy 118.811099 -230.979831) (xy 118.803156 -230.927127)
			(xy 118.574576 -230.927127) (xy 118.566633 -230.979831) (xy 118.550923 -231.030761) (xy 118.527797 -231.078782)
			(xy 118.497773 -231.122819) (xy 118.461521 -231.16189) (xy 118.41985 -231.195121) (xy 118.373692 -231.22177)
			(xy 118.324078 -231.241242) (xy 118.272116 -231.253102) (xy 118.218966 -231.257086) (xy 118.165816 -231.253102)
			(xy 118.113854 -231.241242) (xy 118.06424 -231.22177) (xy 118.018082 -231.195121) (xy 117.976411 -231.16189)
			(xy 117.940159 -231.122819) (xy 117.910135 -231.078782) (xy 117.887009 -231.030761) (xy 117.871299 -230.979831)
			(xy 117.863356 -230.927127) (xy 117.634776 -230.927127) (xy 117.626833 -230.979831) (xy 117.611123 -231.030761)
			(xy 117.587997 -231.078782) (xy 117.557973 -231.122819) (xy 117.521721 -231.16189) (xy 117.48005 -231.195121)
			(xy 117.433892 -231.22177) (xy 117.384278 -231.241242) (xy 117.332316 -231.253102) (xy 117.279166 -231.257086)
			(xy 117.226016 -231.253102) (xy 117.174054 -231.241242) (xy 117.12444 -231.22177) (xy 117.078282 -231.195121)
			(xy 117.036611 -231.16189) (xy 117.000359 -231.122819) (xy 116.970335 -231.078782) (xy 116.947209 -231.030761)
			(xy 116.931499 -230.979831) (xy 116.923556 -230.927127) (xy 116.694976 -230.927127) (xy 116.687033 -230.979831)
			(xy 116.671323 -231.030761) (xy 116.648197 -231.078782) (xy 116.618173 -231.122819) (xy 116.581921 -231.16189)
			(xy 116.54025 -231.195121) (xy 116.494092 -231.22177) (xy 116.444478 -231.241242) (xy 116.392516 -231.253102)
			(xy 116.339366 -231.257086) (xy 116.286216 -231.253102) (xy 116.234254 -231.241242) (xy 116.18464 -231.22177)
			(xy 116.138482 -231.195121) (xy 116.096811 -231.16189) (xy 116.060559 -231.122819) (xy 116.030535 -231.078782)
			(xy 116.007409 -231.030761) (xy 115.991699 -230.979831) (xy 115.983756 -230.927127) (xy 115.755176 -230.927127)
			(xy 115.747233 -230.979831) (xy 115.731523 -231.030761) (xy 115.708397 -231.078782) (xy 115.678373 -231.122819)
			(xy 115.642121 -231.16189) (xy 115.60045 -231.195121) (xy 115.554292 -231.22177) (xy 115.504678 -231.241242)
			(xy 115.452716 -231.253102) (xy 115.399566 -231.257086) (xy 115.346416 -231.253102) (xy 115.294454 -231.241242)
			(xy 115.24484 -231.22177) (xy 115.198682 -231.195121) (xy 115.157011 -231.16189) (xy 115.120759 -231.122819)
			(xy 115.090735 -231.078782) (xy 115.067609 -231.030761) (xy 115.051899 -230.979831) (xy 115.043956 -230.927127)
			(xy 114.81563 -230.927127) (xy 114.807687 -230.979831) (xy 114.791977 -231.030761) (xy 114.768851 -231.078782)
			(xy 114.738827 -231.122819) (xy 114.702575 -231.16189) (xy 114.660904 -231.195121) (xy 114.614746 -231.22177)
			(xy 114.565132 -231.241242) (xy 114.51317 -231.253102) (xy 114.46002 -231.257086) (xy 114.40687 -231.253102)
			(xy 114.354908 -231.241242) (xy 114.305294 -231.22177) (xy 114.259136 -231.195121) (xy 114.217465 -231.16189)
			(xy 114.181213 -231.122819) (xy 114.151189 -231.078782) (xy 114.128063 -231.030761) (xy 114.112353 -230.979831)
			(xy 114.10441 -230.927127) (xy 113.875576 -230.927127) (xy 113.867633 -230.979831) (xy 113.851923 -231.030761)
			(xy 113.828797 -231.078782) (xy 113.798773 -231.122819) (xy 113.762521 -231.16189) (xy 113.72085 -231.195121)
			(xy 113.674692 -231.22177) (xy 113.625078 -231.241242) (xy 113.573116 -231.253102) (xy 113.519966 -231.257086)
			(xy 113.466816 -231.253102) (xy 113.414854 -231.241242) (xy 113.36524 -231.22177) (xy 113.319082 -231.195121)
			(xy 113.277411 -231.16189) (xy 113.241159 -231.122819) (xy 113.211135 -231.078782) (xy 113.188009 -231.030761)
			(xy 113.172299 -230.979831) (xy 113.164356 -230.927127) (xy 112.935776 -230.927127) (xy 112.927833 -230.979831)
			(xy 112.912123 -231.030761) (xy 112.888997 -231.078782) (xy 112.858973 -231.122819) (xy 112.822721 -231.16189)
			(xy 112.78105 -231.195121) (xy 112.734892 -231.22177) (xy 112.685278 -231.241242) (xy 112.633316 -231.253102)
			(xy 112.580166 -231.257086) (xy 112.527016 -231.253102) (xy 112.475054 -231.241242) (xy 112.42544 -231.22177)
			(xy 112.379282 -231.195121) (xy 112.337611 -231.16189) (xy 112.301359 -231.122819) (xy 112.271335 -231.078782)
			(xy 112.248209 -231.030761) (xy 112.232499 -230.979831) (xy 112.224556 -230.927127) (xy 111.995976 -230.927127)
			(xy 111.988033 -230.979831) (xy 111.972323 -231.030761) (xy 111.949197 -231.078782) (xy 111.919173 -231.122819)
			(xy 111.882921 -231.16189) (xy 111.84125 -231.195121) (xy 111.795092 -231.22177) (xy 111.745478 -231.241242)
			(xy 111.693516 -231.253102) (xy 111.640366 -231.257086) (xy 111.587216 -231.253102) (xy 111.535254 -231.241242)
			(xy 111.48564 -231.22177) (xy 111.439482 -231.195121) (xy 111.397811 -231.16189) (xy 111.361559 -231.122819)
			(xy 111.331535 -231.078782) (xy 111.308409 -231.030761) (xy 111.292699 -230.979831) (xy 111.284756 -230.927127)
			(xy 111.056176 -230.927127) (xy 111.048233 -230.979831) (xy 111.032523 -231.030761) (xy 111.009397 -231.078782)
			(xy 110.979373 -231.122819) (xy 110.943121 -231.16189) (xy 110.90145 -231.195121) (xy 110.855292 -231.22177)
			(xy 110.805678 -231.241242) (xy 110.753716 -231.253102) (xy 110.700566 -231.257086) (xy 110.647416 -231.253102)
			(xy 110.595454 -231.241242) (xy 110.54584 -231.22177) (xy 110.499682 -231.195121) (xy 110.458011 -231.16189)
			(xy 110.421759 -231.122819) (xy 110.391735 -231.078782) (xy 110.368609 -231.030761) (xy 110.352899 -230.979831)
			(xy 110.344956 -230.927127) (xy 110.116122 -230.927127) (xy 110.108179 -230.979831) (xy 110.092469 -231.030761)
			(xy 110.069343 -231.078782) (xy 110.039319 -231.122819) (xy 110.003067 -231.16189) (xy 109.961396 -231.195121)
			(xy 109.915238 -231.22177) (xy 109.865624 -231.241242) (xy 109.813662 -231.253102) (xy 109.760512 -231.257086)
			(xy 109.707362 -231.253102) (xy 109.6554 -231.241242) (xy 109.605786 -231.22177) (xy 109.559628 -231.195121)
			(xy 109.517957 -231.16189) (xy 109.481705 -231.122819) (xy 109.451681 -231.078782) (xy 109.428555 -231.030761)
			(xy 109.412845 -230.979831) (xy 109.404902 -230.927127) (xy 109.176576 -230.927127) (xy 109.168633 -230.979831)
			(xy 109.152923 -231.030761) (xy 109.129797 -231.078782) (xy 109.099773 -231.122819) (xy 109.063521 -231.16189)
			(xy 109.02185 -231.195121) (xy 108.975692 -231.22177) (xy 108.926078 -231.241242) (xy 108.874116 -231.253102)
			(xy 108.820966 -231.257086) (xy 108.767816 -231.253102) (xy 108.715854 -231.241242) (xy 108.66624 -231.22177)
			(xy 108.620082 -231.195121) (xy 108.578411 -231.16189) (xy 108.542159 -231.122819) (xy 108.512135 -231.078782)
			(xy 108.489009 -231.030761) (xy 108.473299 -230.979831) (xy 108.465356 -230.927127) (xy 108.236522 -230.927127)
			(xy 108.228579 -230.979831) (xy 108.212869 -231.030761) (xy 108.189743 -231.078782) (xy 108.159719 -231.122819)
			(xy 108.123467 -231.16189) (xy 108.081796 -231.195121) (xy 108.035638 -231.22177) (xy 107.986024 -231.241242)
			(xy 107.934062 -231.253102) (xy 107.880912 -231.257086) (xy 107.827762 -231.253102) (xy 107.7758 -231.241242)
			(xy 107.726186 -231.22177) (xy 107.680028 -231.195121) (xy 107.638357 -231.16189) (xy 107.602105 -231.122819)
			(xy 107.572081 -231.078782) (xy 107.548955 -231.030761) (xy 107.533245 -230.979831) (xy 107.525302 -230.927127)
			(xy 107.296976 -230.927127) (xy 107.289033 -230.979831) (xy 107.273323 -231.030761) (xy 107.250197 -231.078782)
			(xy 107.220173 -231.122819) (xy 107.183921 -231.16189) (xy 107.14225 -231.195121) (xy 107.096092 -231.22177)
			(xy 107.046478 -231.241242) (xy 106.994516 -231.253102) (xy 106.941366 -231.257086) (xy 106.888216 -231.253102)
			(xy 106.836254 -231.241242) (xy 106.78664 -231.22177) (xy 106.740482 -231.195121) (xy 106.698811 -231.16189)
			(xy 106.662559 -231.122819) (xy 106.632535 -231.078782) (xy 106.609409 -231.030761) (xy 106.593699 -230.979831)
			(xy 106.585756 -230.927127) (xy 106.357176 -230.927127) (xy 106.349233 -230.979831) (xy 106.333523 -231.030761)
			(xy 106.310397 -231.078782) (xy 106.280373 -231.122819) (xy 106.244121 -231.16189) (xy 106.20245 -231.195121)
			(xy 106.156292 -231.22177) (xy 106.106678 -231.241242) (xy 106.054716 -231.253102) (xy 106.001566 -231.257086)
			(xy 105.948416 -231.253102) (xy 105.896454 -231.241242) (xy 105.84684 -231.22177) (xy 105.800682 -231.195121)
			(xy 105.759011 -231.16189) (xy 105.722759 -231.122819) (xy 105.692735 -231.078782) (xy 105.669609 -231.030761)
			(xy 105.653899 -230.979831) (xy 105.645956 -230.927127) (xy 105.417376 -230.927127) (xy 105.409433 -230.979831)
			(xy 105.393723 -231.030761) (xy 105.370597 -231.078782) (xy 105.340573 -231.122819) (xy 105.304321 -231.16189)
			(xy 105.26265 -231.195121) (xy 105.216492 -231.22177) (xy 105.166878 -231.241242) (xy 105.114916 -231.253102)
			(xy 105.061766 -231.257086) (xy 105.008616 -231.253102) (xy 104.956654 -231.241242) (xy 104.90704 -231.22177)
			(xy 104.860882 -231.195121) (xy 104.819211 -231.16189) (xy 104.782959 -231.122819) (xy 104.752935 -231.078782)
			(xy 104.729809 -231.030761) (xy 104.714099 -230.979831) (xy 104.706156 -230.927127) (xy 104.477576 -230.927127)
			(xy 104.469633 -230.979831) (xy 104.453923 -231.030761) (xy 104.430797 -231.078782) (xy 104.400773 -231.122819)
			(xy 104.364521 -231.16189) (xy 104.32285 -231.195121) (xy 104.276692 -231.22177) (xy 104.227078 -231.241242)
			(xy 104.175116 -231.253102) (xy 104.121966 -231.257086) (xy 104.068816 -231.253102) (xy 104.016854 -231.241242)
			(xy 103.96724 -231.22177) (xy 103.921082 -231.195121) (xy 103.879411 -231.16189) (xy 103.843159 -231.122819)
			(xy 103.813135 -231.078782) (xy 103.790009 -231.030761) (xy 103.774299 -230.979831) (xy 103.766356 -230.927127)
			(xy 103.537776 -230.927127) (xy 103.529833 -230.979831) (xy 103.514123 -231.030761) (xy 103.490997 -231.078782)
			(xy 103.460973 -231.122819) (xy 103.424721 -231.16189) (xy 103.38305 -231.195121) (xy 103.336892 -231.22177)
			(xy 103.287278 -231.241242) (xy 103.235316 -231.253102) (xy 103.182166 -231.257086) (xy 103.129016 -231.253102)
			(xy 103.077054 -231.241242) (xy 103.02744 -231.22177) (xy 102.981282 -231.195121) (xy 102.939611 -231.16189)
			(xy 102.903359 -231.122819) (xy 102.873335 -231.078782) (xy 102.850209 -231.030761) (xy 102.834499 -230.979831)
			(xy 102.826556 -230.927127) (xy 102.597976 -230.927127) (xy 102.590033 -230.979831) (xy 102.574323 -231.030761)
			(xy 102.551197 -231.078782) (xy 102.521173 -231.122819) (xy 102.484921 -231.16189) (xy 102.44325 -231.195121)
			(xy 102.397092 -231.22177) (xy 102.347478 -231.241242) (xy 102.295516 -231.253102) (xy 102.242366 -231.257086)
			(xy 102.189216 -231.253102) (xy 102.137254 -231.241242) (xy 102.08764 -231.22177) (xy 102.041482 -231.195121)
			(xy 101.999811 -231.16189) (xy 101.963559 -231.122819) (xy 101.933535 -231.078782) (xy 101.910409 -231.030761)
			(xy 101.894699 -230.979831) (xy 101.886756 -230.927127) (xy 101.658176 -230.927127) (xy 101.650233 -230.979831)
			(xy 101.634523 -231.030761) (xy 101.611397 -231.078782) (xy 101.581373 -231.122819) (xy 101.545121 -231.16189)
			(xy 101.50345 -231.195121) (xy 101.457292 -231.22177) (xy 101.407678 -231.241242) (xy 101.355716 -231.253102)
			(xy 101.302566 -231.257086) (xy 101.249416 -231.253102) (xy 101.197454 -231.241242) (xy 101.14784 -231.22177)
			(xy 101.101682 -231.195121) (xy 101.060011 -231.16189) (xy 101.023759 -231.122819) (xy 100.993735 -231.078782)
			(xy 100.970609 -231.030761) (xy 100.954899 -230.979831) (xy 100.946956 -230.927127) (xy 100.718376 -230.927127)
			(xy 100.710433 -230.979831) (xy 100.694723 -231.030761) (xy 100.671597 -231.078782) (xy 100.641573 -231.122819)
			(xy 100.605321 -231.16189) (xy 100.56365 -231.195121) (xy 100.517492 -231.22177) (xy 100.467878 -231.241242)
			(xy 100.415916 -231.253102) (xy 100.362766 -231.257086) (xy 100.309616 -231.253102) (xy 100.257654 -231.241242)
			(xy 100.20804 -231.22177) (xy 100.161882 -231.195121) (xy 100.120211 -231.16189) (xy 100.083959 -231.122819)
			(xy 100.053935 -231.078782) (xy 100.030809 -231.030761) (xy 100.015099 -230.979831) (xy 100.007156 -230.927127)
			(xy 99.778576 -230.927127) (xy 99.770633 -230.979831) (xy 99.754923 -231.030761) (xy 99.731797 -231.078782)
			(xy 99.701773 -231.122819) (xy 99.665521 -231.16189) (xy 99.62385 -231.195121) (xy 99.577692 -231.22177)
			(xy 99.528078 -231.241242) (xy 99.476116 -231.253102) (xy 99.422966 -231.257086) (xy 99.369816 -231.253102)
			(xy 99.317854 -231.241242) (xy 99.26824 -231.22177) (xy 99.222082 -231.195121) (xy 99.180411 -231.16189)
			(xy 99.144159 -231.122819) (xy 99.114135 -231.078782) (xy 99.091009 -231.030761) (xy 99.075299 -230.979831)
			(xy 99.067356 -230.927127) (xy 98.838776 -230.927127) (xy 98.830833 -230.979831) (xy 98.815123 -231.030761)
			(xy 98.791997 -231.078782) (xy 98.761973 -231.122819) (xy 98.725721 -231.16189) (xy 98.68405 -231.195121)
			(xy 98.637892 -231.22177) (xy 98.588278 -231.241242) (xy 98.536316 -231.253102) (xy 98.483166 -231.257086)
			(xy 98.430016 -231.253102) (xy 98.378054 -231.241242) (xy 98.32844 -231.22177) (xy 98.282282 -231.195121)
			(xy 98.240611 -231.16189) (xy 98.204359 -231.122819) (xy 98.174335 -231.078782) (xy 98.151209 -231.030761)
			(xy 98.135499 -230.979831) (xy 98.127556 -230.927127) (xy 97.898722 -230.927127) (xy 97.890779 -230.979831)
			(xy 97.875069 -231.030761) (xy 97.851943 -231.078782) (xy 97.821919 -231.122819) (xy 97.785667 -231.16189)
			(xy 97.743996 -231.195121) (xy 97.697838 -231.22177) (xy 97.648224 -231.241242) (xy 97.596262 -231.253102)
			(xy 97.543112 -231.257086) (xy 97.489962 -231.253102) (xy 97.438 -231.241242) (xy 97.388386 -231.22177)
			(xy 97.342228 -231.195121) (xy 97.300557 -231.16189) (xy 97.264305 -231.122819) (xy 97.234281 -231.078782)
			(xy 97.211155 -231.030761) (xy 97.195445 -230.979831) (xy 97.187502 -230.927127) (xy 96.959176 -230.927127)
			(xy 96.951233 -230.979831) (xy 96.935523 -231.030761) (xy 96.912397 -231.078782) (xy 96.882373 -231.122819)
			(xy 96.846121 -231.16189) (xy 96.80445 -231.195121) (xy 96.758292 -231.22177) (xy 96.708678 -231.241242)
			(xy 96.656716 -231.253102) (xy 96.603566 -231.257086) (xy 96.550416 -231.253102) (xy 96.498454 -231.241242)
			(xy 96.44884 -231.22177) (xy 96.402682 -231.195121) (xy 96.361011 -231.16189) (xy 96.324759 -231.122819)
			(xy 96.294735 -231.078782) (xy 96.271609 -231.030761) (xy 96.255899 -230.979831) (xy 96.247956 -230.927127)
			(xy 96.019376 -230.927127) (xy 96.011433 -230.979831) (xy 95.995723 -231.030761) (xy 95.972597 -231.078782)
			(xy 95.942573 -231.122819) (xy 95.906321 -231.16189) (xy 95.86465 -231.195121) (xy 95.818492 -231.22177)
			(xy 95.768878 -231.241242) (xy 95.716916 -231.253102) (xy 95.663766 -231.257086) (xy 95.610616 -231.253102)
			(xy 95.558654 -231.241242) (xy 95.50904 -231.22177) (xy 95.462882 -231.195121) (xy 95.421211 -231.16189)
			(xy 95.384959 -231.122819) (xy 95.354935 -231.078782) (xy 95.331809 -231.030761) (xy 95.316099 -230.979831)
			(xy 95.308156 -230.927127) (xy 95.079576 -230.927127) (xy 95.071633 -230.979831) (xy 95.055923 -231.030761)
			(xy 95.032797 -231.078782) (xy 95.002773 -231.122819) (xy 94.966521 -231.16189) (xy 94.92485 -231.195121)
			(xy 94.878692 -231.22177) (xy 94.829078 -231.241242) (xy 94.777116 -231.253102) (xy 94.723966 -231.257086)
			(xy 94.670816 -231.253102) (xy 94.618854 -231.241242) (xy 94.56924 -231.22177) (xy 94.523082 -231.195121)
			(xy 94.481411 -231.16189) (xy 94.445159 -231.122819) (xy 94.415135 -231.078782) (xy 94.392009 -231.030761)
			(xy 94.376299 -230.979831) (xy 94.368356 -230.927127) (xy 94.139776 -230.927127) (xy 94.131833 -230.979831)
			(xy 94.116123 -231.030761) (xy 94.092997 -231.078782) (xy 94.062973 -231.122819) (xy 94.026721 -231.16189)
			(xy 93.98505 -231.195121) (xy 93.938892 -231.22177) (xy 93.889278 -231.241242) (xy 93.837316 -231.253102)
			(xy 93.784166 -231.257086) (xy 93.731016 -231.253102) (xy 93.679054 -231.241242) (xy 93.62944 -231.22177)
			(xy 93.583282 -231.195121) (xy 93.541611 -231.16189) (xy 93.505359 -231.122819) (xy 93.475335 -231.078782)
			(xy 93.452209 -231.030761) (xy 93.436499 -230.979831) (xy 93.428556 -230.927127) (xy 93.199976 -230.927127)
			(xy 93.192033 -230.979831) (xy 93.176323 -231.030761) (xy 93.153197 -231.078782) (xy 93.123173 -231.122819)
			(xy 93.086921 -231.16189) (xy 93.04525 -231.195121) (xy 92.999092 -231.22177) (xy 92.949478 -231.241242)
			(xy 92.897516 -231.253102) (xy 92.844366 -231.257086) (xy 92.791216 -231.253102) (xy 92.739254 -231.241242)
			(xy 92.68964 -231.22177) (xy 92.643482 -231.195121) (xy 92.601811 -231.16189) (xy 92.565559 -231.122819)
			(xy 92.535535 -231.078782) (xy 92.512409 -231.030761) (xy 92.496699 -230.979831) (xy 92.488756 -230.927127)
			(xy 92.260176 -230.927127) (xy 92.252233 -230.979831) (xy 92.236523 -231.030761) (xy 92.213397 -231.078782)
			(xy 92.183373 -231.122819) (xy 92.147121 -231.16189) (xy 92.10545 -231.195121) (xy 92.059292 -231.22177)
			(xy 92.009678 -231.241242) (xy 91.957716 -231.253102) (xy 91.904566 -231.257086) (xy 91.851416 -231.253102)
			(xy 91.799454 -231.241242) (xy 91.74984 -231.22177) (xy 91.703682 -231.195121) (xy 91.662011 -231.16189)
			(xy 91.625759 -231.122819) (xy 91.595735 -231.078782) (xy 91.572609 -231.030761) (xy 91.556899 -230.979831)
			(xy 91.548956 -230.927127) (xy 91.320122 -230.927127) (xy 91.312179 -230.979831) (xy 91.296469 -231.030761)
			(xy 91.273343 -231.078782) (xy 91.243319 -231.122819) (xy 91.207067 -231.16189) (xy 91.165396 -231.195121)
			(xy 91.119238 -231.22177) (xy 91.069624 -231.241242) (xy 91.017662 -231.253102) (xy 90.964512 -231.257086)
			(xy 90.911362 -231.253102) (xy 90.8594 -231.241242) (xy 90.809786 -231.22177) (xy 90.763628 -231.195121)
			(xy 90.721957 -231.16189) (xy 90.685705 -231.122819) (xy 90.655681 -231.078782) (xy 90.632555 -231.030761)
			(xy 90.616845 -230.979831) (xy 90.608902 -230.927127) (xy 90.380576 -230.927127) (xy 90.372633 -230.979831)
			(xy 90.356923 -231.030761) (xy 90.333797 -231.078782) (xy 90.303773 -231.122819) (xy 90.267521 -231.16189)
			(xy 90.22585 -231.195121) (xy 90.179692 -231.22177) (xy 90.130078 -231.241242) (xy 90.078116 -231.253102)
			(xy 90.024966 -231.257086) (xy 89.971816 -231.253102) (xy 89.919854 -231.241242) (xy 89.87024 -231.22177)
			(xy 89.824082 -231.195121) (xy 89.782411 -231.16189) (xy 89.746159 -231.122819) (xy 89.716135 -231.078782)
			(xy 89.693009 -231.030761) (xy 89.677299 -230.979831) (xy 89.669356 -230.927127) (xy 89.439858 -230.927127)
			(xy 89.43787 -230.95366) (xy 89.426007 -231.005632) (xy 89.40653 -231.055255) (xy 89.379874 -231.101421)
			(xy 89.346635 -231.143098) (xy 89.307555 -231.179355) (xy 89.263507 -231.209383) (xy 89.215476 -231.232509)
			(xy 89.164535 -231.248218) (xy 89.11182 -231.256159) (xy 89.085166 -231.256586) (xy 89.060205 -231.256165)
			(xy 89.010772 -231.249195) (xy 88.962794 -231.235397) (xy 88.917211 -231.21504) (xy 88.874914 -231.188522)
			(xy 88.85555 -231.172766) (xy 88.844189 -231.163833) (xy 88.817782 -231.152123) (xy 88.789153 -231.148275)
			(xy 88.760592 -231.152597) (xy 88.734383 -231.164744) (xy 88.712623 -231.183743) (xy 88.697054 -231.208075)
			(xy 88.688921 -231.235793) (xy 88.688418 -231.250236) (xy 88.688418 -231.364028) (xy 88.723724 -231.375458)
			(xy 88.748729 -231.383981) (xy 88.796096 -231.407368) (xy 88.839488 -231.437496) (xy 88.877953 -231.473706)
			(xy 88.910645 -231.515201) (xy 88.936847 -231.56107) (xy 88.955984 -231.610308) (xy 88.967636 -231.661833)
			(xy 88.971547 -231.714515) (xy 88.969564 -231.741197) (xy 89.199202 -231.741197) (xy 89.199202 -231.687899)
			(xy 89.207145 -231.635195) (xy 89.222855 -231.584265) (xy 89.245981 -231.536244) (xy 89.276005 -231.492207)
			(xy 89.312257 -231.453136) (xy 89.353928 -231.419905) (xy 89.400086 -231.393256) (xy 89.4497 -231.373784)
			(xy 89.501662 -231.361924) (xy 89.554812 -231.357941) (xy 89.607962 -231.361924) (xy 89.659924 -231.373784)
			(xy 89.709538 -231.393256) (xy 89.755696 -231.419905) (xy 89.797367 -231.453136) (xy 89.833619 -231.492207)
			(xy 89.863643 -231.536244) (xy 89.886769 -231.584265) (xy 89.902479 -231.635195) (xy 89.910422 -231.687899)
			(xy 89.91092 -231.714548) (xy 89.910422 -231.741197) (xy 90.139002 -231.741197) (xy 90.139002 -231.687899)
			(xy 90.146945 -231.635195) (xy 90.162655 -231.584265) (xy 90.185781 -231.536244) (xy 90.215805 -231.492207)
			(xy 90.252057 -231.453136) (xy 90.293728 -231.419905) (xy 90.339886 -231.393256) (xy 90.3895 -231.373784)
			(xy 90.441462 -231.361924) (xy 90.494612 -231.357941) (xy 90.547762 -231.361924) (xy 90.599724 -231.373784)
			(xy 90.649338 -231.393256) (xy 90.695496 -231.419905) (xy 90.737167 -231.453136) (xy 90.773419 -231.492207)
			(xy 90.803443 -231.536244) (xy 90.826569 -231.584265) (xy 90.842279 -231.635195) (xy 90.850222 -231.687899)
			(xy 90.85072 -231.714548) (xy 90.850222 -231.741197) (xy 91.078802 -231.741197) (xy 91.078802 -231.687899)
			(xy 91.086745 -231.635195) (xy 91.102455 -231.584265) (xy 91.125581 -231.536244) (xy 91.155605 -231.492207)
			(xy 91.191857 -231.453136) (xy 91.233528 -231.419905) (xy 91.279686 -231.393256) (xy 91.3293 -231.373784)
			(xy 91.381262 -231.361924) (xy 91.434412 -231.357941) (xy 91.487562 -231.361924) (xy 91.539524 -231.373784)
			(xy 91.589138 -231.393256) (xy 91.635296 -231.419905) (xy 91.676967 -231.453136) (xy 91.713219 -231.492207)
			(xy 91.743243 -231.536244) (xy 91.766369 -231.584265) (xy 91.782079 -231.635195) (xy 91.790022 -231.687899)
			(xy 91.79052 -231.714548) (xy 91.790022 -231.741197) (xy 92.018602 -231.741197) (xy 92.018602 -231.687899)
			(xy 92.026545 -231.635195) (xy 92.042255 -231.584265) (xy 92.065381 -231.536244) (xy 92.095405 -231.492207)
			(xy 92.131657 -231.453136) (xy 92.173328 -231.419905) (xy 92.219486 -231.393256) (xy 92.2691 -231.373784)
			(xy 92.321062 -231.361924) (xy 92.374212 -231.357941) (xy 92.427362 -231.361924) (xy 92.479324 -231.373784)
			(xy 92.528938 -231.393256) (xy 92.575096 -231.419905) (xy 92.616767 -231.453136) (xy 92.653019 -231.492207)
			(xy 92.683043 -231.536244) (xy 92.706169 -231.584265) (xy 92.721879 -231.635195) (xy 92.729822 -231.687899)
			(xy 92.73032 -231.714548) (xy 92.729822 -231.741197) (xy 92.958402 -231.741197) (xy 92.958402 -231.687899)
			(xy 92.966345 -231.635195) (xy 92.982055 -231.584265) (xy 93.005181 -231.536244) (xy 93.035205 -231.492207)
			(xy 93.071457 -231.453136) (xy 93.113128 -231.419905) (xy 93.159286 -231.393256) (xy 93.2089 -231.373784)
			(xy 93.260862 -231.361924) (xy 93.314012 -231.357941) (xy 93.367162 -231.361924) (xy 93.419124 -231.373784)
			(xy 93.468738 -231.393256) (xy 93.514896 -231.419905) (xy 93.556567 -231.453136) (xy 93.592819 -231.492207)
			(xy 93.622843 -231.536244) (xy 93.645969 -231.584265) (xy 93.661679 -231.635195) (xy 93.669622 -231.687899)
			(xy 93.67012 -231.714548) (xy 93.669622 -231.741197) (xy 93.898456 -231.741197) (xy 93.898456 -231.687899)
			(xy 93.906399 -231.635195) (xy 93.922109 -231.584265) (xy 93.945235 -231.536244) (xy 93.975259 -231.492207)
			(xy 94.011511 -231.453136) (xy 94.053182 -231.419905) (xy 94.09934 -231.393256) (xy 94.148954 -231.373784)
			(xy 94.200916 -231.361924) (xy 94.254066 -231.357941) (xy 94.307216 -231.361924) (xy 94.359178 -231.373784)
			(xy 94.408792 -231.393256) (xy 94.45495 -231.419905) (xy 94.496621 -231.453136) (xy 94.532873 -231.492207)
			(xy 94.562897 -231.536244) (xy 94.586023 -231.584265) (xy 94.601733 -231.635195) (xy 94.609676 -231.687899)
			(xy 94.610174 -231.714548) (xy 94.609676 -231.741197) (xy 94.838002 -231.741197) (xy 94.838002 -231.687899)
			(xy 94.845945 -231.635195) (xy 94.861655 -231.584265) (xy 94.884781 -231.536244) (xy 94.914805 -231.492207)
			(xy 94.951057 -231.453136) (xy 94.992728 -231.419905) (xy 95.038886 -231.393256) (xy 95.0885 -231.373784)
			(xy 95.140462 -231.361924) (xy 95.193612 -231.357941) (xy 95.246762 -231.361924) (xy 95.298724 -231.373784)
			(xy 95.348338 -231.393256) (xy 95.394496 -231.419905) (xy 95.436167 -231.453136) (xy 95.472419 -231.492207)
			(xy 95.502443 -231.536244) (xy 95.525569 -231.584265) (xy 95.541279 -231.635195) (xy 95.549222 -231.687899)
			(xy 95.54972 -231.714548) (xy 95.549222 -231.741197) (xy 95.777802 -231.741197) (xy 95.777802 -231.687899)
			(xy 95.785745 -231.635195) (xy 95.801455 -231.584265) (xy 95.824581 -231.536244) (xy 95.854605 -231.492207)
			(xy 95.890857 -231.453136) (xy 95.932528 -231.419905) (xy 95.978686 -231.393256) (xy 96.0283 -231.373784)
			(xy 96.080262 -231.361924) (xy 96.133412 -231.357941) (xy 96.186562 -231.361924) (xy 96.238524 -231.373784)
			(xy 96.288138 -231.393256) (xy 96.334296 -231.419905) (xy 96.375967 -231.453136) (xy 96.412219 -231.492207)
			(xy 96.442243 -231.536244) (xy 96.465369 -231.584265) (xy 96.481079 -231.635195) (xy 96.489022 -231.687899)
			(xy 96.48952 -231.714548) (xy 96.489022 -231.741197) (xy 96.717602 -231.741197) (xy 96.717602 -231.687899)
			(xy 96.725545 -231.635195) (xy 96.741255 -231.584265) (xy 96.764381 -231.536244) (xy 96.794405 -231.492207)
			(xy 96.830657 -231.453136) (xy 96.872328 -231.419905) (xy 96.918486 -231.393256) (xy 96.9681 -231.373784)
			(xy 97.020062 -231.361924) (xy 97.073212 -231.357941) (xy 97.126362 -231.361924) (xy 97.178324 -231.373784)
			(xy 97.227938 -231.393256) (xy 97.274096 -231.419905) (xy 97.315767 -231.453136) (xy 97.352019 -231.492207)
			(xy 97.382043 -231.536244) (xy 97.405169 -231.584265) (xy 97.420879 -231.635195) (xy 97.428822 -231.687899)
			(xy 97.42932 -231.714548) (xy 97.428822 -231.741197) (xy 97.657402 -231.741197) (xy 97.657402 -231.687899)
			(xy 97.665345 -231.635195) (xy 97.681055 -231.584265) (xy 97.704181 -231.536244) (xy 97.734205 -231.492207)
			(xy 97.770457 -231.453136) (xy 97.812128 -231.419905) (xy 97.858286 -231.393256) (xy 97.9079 -231.373784)
			(xy 97.959862 -231.361924) (xy 98.013012 -231.357941) (xy 98.066162 -231.361924) (xy 98.118124 -231.373784)
			(xy 98.167738 -231.393256) (xy 98.213896 -231.419905) (xy 98.255567 -231.453136) (xy 98.291819 -231.492207)
			(xy 98.321843 -231.536244) (xy 98.344969 -231.584265) (xy 98.360679 -231.635195) (xy 98.368622 -231.687899)
			(xy 98.36912 -231.714548) (xy 98.368622 -231.741197) (xy 98.597202 -231.741197) (xy 98.597202 -231.687899)
			(xy 98.605145 -231.635195) (xy 98.620855 -231.584265) (xy 98.643981 -231.536244) (xy 98.674005 -231.492207)
			(xy 98.710257 -231.453136) (xy 98.751928 -231.419905) (xy 98.798086 -231.393256) (xy 98.8477 -231.373784)
			(xy 98.899662 -231.361924) (xy 98.952812 -231.357941) (xy 99.005962 -231.361924) (xy 99.057924 -231.373784)
			(xy 99.107538 -231.393256) (xy 99.153696 -231.419905) (xy 99.195367 -231.453136) (xy 99.231619 -231.492207)
			(xy 99.261643 -231.536244) (xy 99.284769 -231.584265) (xy 99.300479 -231.635195) (xy 99.308422 -231.687899)
			(xy 99.30892 -231.714548) (xy 99.308422 -231.741197) (xy 99.537002 -231.741197) (xy 99.537002 -231.687899)
			(xy 99.544945 -231.635195) (xy 99.560655 -231.584265) (xy 99.583781 -231.536244) (xy 99.613805 -231.492207)
			(xy 99.650057 -231.453136) (xy 99.691728 -231.419905) (xy 99.737886 -231.393256) (xy 99.7875 -231.373784)
			(xy 99.839462 -231.361924) (xy 99.892612 -231.357941) (xy 99.945762 -231.361924) (xy 99.997724 -231.373784)
			(xy 100.047338 -231.393256) (xy 100.093496 -231.419905) (xy 100.135167 -231.453136) (xy 100.171419 -231.492207)
			(xy 100.201443 -231.536244) (xy 100.224569 -231.584265) (xy 100.240279 -231.635195) (xy 100.248222 -231.687899)
			(xy 100.24872 -231.714548) (xy 100.248222 -231.741197) (xy 100.477056 -231.741197) (xy 100.477056 -231.687899)
			(xy 100.484999 -231.635195) (xy 100.500709 -231.584265) (xy 100.523835 -231.536244) (xy 100.553859 -231.492207)
			(xy 100.590111 -231.453136) (xy 100.631782 -231.419905) (xy 100.67794 -231.393256) (xy 100.727554 -231.373784)
			(xy 100.779516 -231.361924) (xy 100.832666 -231.357941) (xy 100.885816 -231.361924) (xy 100.937778 -231.373784)
			(xy 100.987392 -231.393256) (xy 101.03355 -231.419905) (xy 101.075221 -231.453136) (xy 101.111473 -231.492207)
			(xy 101.141497 -231.536244) (xy 101.164623 -231.584265) (xy 101.180333 -231.635195) (xy 101.188276 -231.687899)
			(xy 101.188774 -231.714548) (xy 101.188276 -231.741197) (xy 101.416602 -231.741197) (xy 101.416602 -231.687899)
			(xy 101.424545 -231.635195) (xy 101.440255 -231.584265) (xy 101.463381 -231.536244) (xy 101.493405 -231.492207)
			(xy 101.529657 -231.453136) (xy 101.571328 -231.419905) (xy 101.617486 -231.393256) (xy 101.6671 -231.373784)
			(xy 101.719062 -231.361924) (xy 101.772212 -231.357941) (xy 101.825362 -231.361924) (xy 101.877324 -231.373784)
			(xy 101.926938 -231.393256) (xy 101.973096 -231.419905) (xy 102.014767 -231.453136) (xy 102.051019 -231.492207)
			(xy 102.081043 -231.536244) (xy 102.104169 -231.584265) (xy 102.119879 -231.635195) (xy 102.127822 -231.687899)
			(xy 102.12832 -231.714548) (xy 102.127822 -231.741197) (xy 102.356402 -231.741197) (xy 102.356402 -231.687899)
			(xy 102.364345 -231.635195) (xy 102.380055 -231.584265) (xy 102.403181 -231.536244) (xy 102.433205 -231.492207)
			(xy 102.469457 -231.453136) (xy 102.511128 -231.419905) (xy 102.557286 -231.393256) (xy 102.6069 -231.373784)
			(xy 102.658862 -231.361924) (xy 102.712012 -231.357941) (xy 102.765162 -231.361924) (xy 102.817124 -231.373784)
			(xy 102.866738 -231.393256) (xy 102.912896 -231.419905) (xy 102.954567 -231.453136) (xy 102.990819 -231.492207)
			(xy 103.020843 -231.536244) (xy 103.043969 -231.584265) (xy 103.059679 -231.635195) (xy 103.067622 -231.687899)
			(xy 103.06812 -231.714548) (xy 103.067622 -231.741197) (xy 103.296202 -231.741197) (xy 103.296202 -231.687899)
			(xy 103.304145 -231.635195) (xy 103.319855 -231.584265) (xy 103.342981 -231.536244) (xy 103.373005 -231.492207)
			(xy 103.409257 -231.453136) (xy 103.450928 -231.419905) (xy 103.497086 -231.393256) (xy 103.5467 -231.373784)
			(xy 103.598662 -231.361924) (xy 103.651812 -231.357941) (xy 103.704962 -231.361924) (xy 103.756924 -231.373784)
			(xy 103.806538 -231.393256) (xy 103.852696 -231.419905) (xy 103.894367 -231.453136) (xy 103.930619 -231.492207)
			(xy 103.960643 -231.536244) (xy 103.983769 -231.584265) (xy 103.999479 -231.635195) (xy 104.007422 -231.687899)
			(xy 104.00792 -231.714548) (xy 104.007422 -231.741197) (xy 104.236002 -231.741197) (xy 104.236002 -231.687899)
			(xy 104.243945 -231.635195) (xy 104.259655 -231.584265) (xy 104.282781 -231.536244) (xy 104.312805 -231.492207)
			(xy 104.349057 -231.453136) (xy 104.390728 -231.419905) (xy 104.436886 -231.393256) (xy 104.4865 -231.373784)
			(xy 104.538462 -231.361924) (xy 104.591612 -231.357941) (xy 104.644762 -231.361924) (xy 104.696724 -231.373784)
			(xy 104.746338 -231.393256) (xy 104.792496 -231.419905) (xy 104.834167 -231.453136) (xy 104.870419 -231.492207)
			(xy 104.900443 -231.536244) (xy 104.923569 -231.584265) (xy 104.939279 -231.635195) (xy 104.947222 -231.687899)
			(xy 104.94772 -231.714548) (xy 104.947222 -231.741197) (xy 105.175802 -231.741197) (xy 105.175802 -231.687899)
			(xy 105.183745 -231.635195) (xy 105.199455 -231.584265) (xy 105.222581 -231.536244) (xy 105.252605 -231.492207)
			(xy 105.288857 -231.453136) (xy 105.330528 -231.419905) (xy 105.376686 -231.393256) (xy 105.4263 -231.373784)
			(xy 105.478262 -231.361924) (xy 105.531412 -231.357941) (xy 105.584562 -231.361924) (xy 105.636524 -231.373784)
			(xy 105.686138 -231.393256) (xy 105.732296 -231.419905) (xy 105.773967 -231.453136) (xy 105.810219 -231.492207)
			(xy 105.840243 -231.536244) (xy 105.863369 -231.584265) (xy 105.879079 -231.635195) (xy 105.887022 -231.687899)
			(xy 105.88752 -231.714548) (xy 105.887022 -231.741197) (xy 106.115602 -231.741197) (xy 106.115602 -231.687899)
			(xy 106.123545 -231.635195) (xy 106.139255 -231.584265) (xy 106.162381 -231.536244) (xy 106.192405 -231.492207)
			(xy 106.228657 -231.453136) (xy 106.270328 -231.419905) (xy 106.316486 -231.393256) (xy 106.3661 -231.373784)
			(xy 106.418062 -231.361924) (xy 106.471212 -231.357941) (xy 106.524362 -231.361924) (xy 106.576324 -231.373784)
			(xy 106.625938 -231.393256) (xy 106.672096 -231.419905) (xy 106.713767 -231.453136) (xy 106.750019 -231.492207)
			(xy 106.780043 -231.536244) (xy 106.803169 -231.584265) (xy 106.818879 -231.635195) (xy 106.826822 -231.687899)
			(xy 106.82732 -231.714548) (xy 106.826822 -231.741197) (xy 107.055402 -231.741197) (xy 107.055402 -231.687899)
			(xy 107.063345 -231.635195) (xy 107.079055 -231.584265) (xy 107.102181 -231.536244) (xy 107.132205 -231.492207)
			(xy 107.168457 -231.453136) (xy 107.210128 -231.419905) (xy 107.256286 -231.393256) (xy 107.3059 -231.373784)
			(xy 107.357862 -231.361924) (xy 107.411012 -231.357941) (xy 107.464162 -231.361924) (xy 107.516124 -231.373784)
			(xy 107.565738 -231.393256) (xy 107.611896 -231.419905) (xy 107.653567 -231.453136) (xy 107.689819 -231.492207)
			(xy 107.719843 -231.536244) (xy 107.742969 -231.584265) (xy 107.758679 -231.635195) (xy 107.766622 -231.687899)
			(xy 107.76712 -231.714548) (xy 107.766622 -231.741197) (xy 107.995202 -231.741197) (xy 107.995202 -231.687899)
			(xy 108.003145 -231.635195) (xy 108.018855 -231.584265) (xy 108.041981 -231.536244) (xy 108.072005 -231.492207)
			(xy 108.108257 -231.453136) (xy 108.149928 -231.419905) (xy 108.196086 -231.393256) (xy 108.2457 -231.373784)
			(xy 108.297662 -231.361924) (xy 108.350812 -231.357941) (xy 108.403962 -231.361924) (xy 108.455924 -231.373784)
			(xy 108.505538 -231.393256) (xy 108.551696 -231.419905) (xy 108.593367 -231.453136) (xy 108.629619 -231.492207)
			(xy 108.659643 -231.536244) (xy 108.682769 -231.584265) (xy 108.698479 -231.635195) (xy 108.706422 -231.687899)
			(xy 108.70692 -231.714548) (xy 108.706422 -231.741197) (xy 108.935002 -231.741197) (xy 108.935002 -231.687899)
			(xy 108.942945 -231.635195) (xy 108.958655 -231.584265) (xy 108.981781 -231.536244) (xy 109.011805 -231.492207)
			(xy 109.048057 -231.453136) (xy 109.089728 -231.419905) (xy 109.135886 -231.393256) (xy 109.1855 -231.373784)
			(xy 109.237462 -231.361924) (xy 109.290612 -231.357941) (xy 109.343762 -231.361924) (xy 109.395724 -231.373784)
			(xy 109.445338 -231.393256) (xy 109.491496 -231.419905) (xy 109.533167 -231.453136) (xy 109.569419 -231.492207)
			(xy 109.599443 -231.536244) (xy 109.622569 -231.584265) (xy 109.638279 -231.635195) (xy 109.646222 -231.687899)
			(xy 109.64672 -231.714548) (xy 109.646222 -231.741197) (xy 109.875056 -231.741197) (xy 109.875056 -231.687899)
			(xy 109.882999 -231.635195) (xy 109.898709 -231.584265) (xy 109.921835 -231.536244) (xy 109.951859 -231.492207)
			(xy 109.988111 -231.453136) (xy 110.029782 -231.419905) (xy 110.07594 -231.393256) (xy 110.125554 -231.373784)
			(xy 110.177516 -231.361924) (xy 110.230666 -231.357941) (xy 110.283816 -231.361924) (xy 110.335778 -231.373784)
			(xy 110.385392 -231.393256) (xy 110.43155 -231.419905) (xy 110.473221 -231.453136) (xy 110.509473 -231.492207)
			(xy 110.539497 -231.536244) (xy 110.562623 -231.584265) (xy 110.578333 -231.635195) (xy 110.586276 -231.687899)
			(xy 110.586774 -231.714548) (xy 110.586276 -231.741197) (xy 110.814602 -231.741197) (xy 110.814602 -231.687899)
			(xy 110.822545 -231.635195) (xy 110.838255 -231.584265) (xy 110.861381 -231.536244) (xy 110.891405 -231.492207)
			(xy 110.927657 -231.453136) (xy 110.969328 -231.419905) (xy 111.015486 -231.393256) (xy 111.0651 -231.373784)
			(xy 111.117062 -231.361924) (xy 111.170212 -231.357941) (xy 111.223362 -231.361924) (xy 111.275324 -231.373784)
			(xy 111.324938 -231.393256) (xy 111.371096 -231.419905) (xy 111.412767 -231.453136) (xy 111.449019 -231.492207)
			(xy 111.479043 -231.536244) (xy 111.502169 -231.584265) (xy 111.517879 -231.635195) (xy 111.525822 -231.687899)
			(xy 111.52632 -231.714548) (xy 111.525822 -231.741197) (xy 111.75491 -231.741197) (xy 111.75491 -231.687899)
			(xy 111.762853 -231.635195) (xy 111.778563 -231.584265) (xy 111.801689 -231.536244) (xy 111.831713 -231.492207)
			(xy 111.867965 -231.453136) (xy 111.909636 -231.419905) (xy 111.955794 -231.393256) (xy 112.005408 -231.373784)
			(xy 112.05737 -231.361924) (xy 112.11052 -231.357941) (xy 112.16367 -231.361924) (xy 112.215632 -231.373784)
			(xy 112.265246 -231.393256) (xy 112.311404 -231.419905) (xy 112.353075 -231.453136) (xy 112.389327 -231.492207)
			(xy 112.419351 -231.536244) (xy 112.442477 -231.584265) (xy 112.458187 -231.635195) (xy 112.46613 -231.687899)
			(xy 112.466628 -231.714548) (xy 112.46613 -231.741197) (xy 112.69471 -231.741197) (xy 112.69471 -231.687899)
			(xy 112.702653 -231.635195) (xy 112.718363 -231.584265) (xy 112.741489 -231.536244) (xy 112.771513 -231.492207)
			(xy 112.807765 -231.453136) (xy 112.849436 -231.419905) (xy 112.895594 -231.393256) (xy 112.945208 -231.373784)
			(xy 112.99717 -231.361924) (xy 113.05032 -231.357941) (xy 113.10347 -231.361924) (xy 113.155432 -231.373784)
			(xy 113.205046 -231.393256) (xy 113.251204 -231.419905) (xy 113.292875 -231.453136) (xy 113.329127 -231.492207)
			(xy 113.359151 -231.536244) (xy 113.382277 -231.584265) (xy 113.397987 -231.635195) (xy 113.40593 -231.687899)
			(xy 113.406428 -231.714548) (xy 113.40593 -231.741197) (xy 113.63451 -231.741197) (xy 113.63451 -231.687899)
			(xy 113.642453 -231.635195) (xy 113.658163 -231.584265) (xy 113.681289 -231.536244) (xy 113.711313 -231.492207)
			(xy 113.747565 -231.453136) (xy 113.789236 -231.419905) (xy 113.835394 -231.393256) (xy 113.885008 -231.373784)
			(xy 113.93697 -231.361924) (xy 113.99012 -231.357941) (xy 114.04327 -231.361924) (xy 114.095232 -231.373784)
			(xy 114.144846 -231.393256) (xy 114.191004 -231.419905) (xy 114.232675 -231.453136) (xy 114.268927 -231.492207)
			(xy 114.298951 -231.536244) (xy 114.322077 -231.584265) (xy 114.337787 -231.635195) (xy 114.34573 -231.687899)
			(xy 114.346228 -231.714548) (xy 114.34573 -231.741197) (xy 114.573802 -231.741197) (xy 114.573802 -231.687899)
			(xy 114.581745 -231.635195) (xy 114.597455 -231.584265) (xy 114.620581 -231.536244) (xy 114.650605 -231.492207)
			(xy 114.686857 -231.453136) (xy 114.728528 -231.419905) (xy 114.774686 -231.393256) (xy 114.8243 -231.373784)
			(xy 114.876262 -231.361924) (xy 114.929412 -231.357941) (xy 114.982562 -231.361924) (xy 115.034524 -231.373784)
			(xy 115.084138 -231.393256) (xy 115.130296 -231.419905) (xy 115.171967 -231.453136) (xy 115.208219 -231.492207)
			(xy 115.238243 -231.536244) (xy 115.261369 -231.584265) (xy 115.277079 -231.635195) (xy 115.285022 -231.687899)
			(xy 115.28552 -231.714548) (xy 115.285022 -231.741197) (xy 115.513602 -231.741197) (xy 115.513602 -231.687899)
			(xy 115.521545 -231.635195) (xy 115.537255 -231.584265) (xy 115.560381 -231.536244) (xy 115.590405 -231.492207)
			(xy 115.626657 -231.453136) (xy 115.668328 -231.419905) (xy 115.714486 -231.393256) (xy 115.7641 -231.373784)
			(xy 115.816062 -231.361924) (xy 115.869212 -231.357941) (xy 115.922362 -231.361924) (xy 115.974324 -231.373784)
			(xy 116.023938 -231.393256) (xy 116.070096 -231.419905) (xy 116.111767 -231.453136) (xy 116.148019 -231.492207)
			(xy 116.178043 -231.536244) (xy 116.201169 -231.584265) (xy 116.216879 -231.635195) (xy 116.224822 -231.687899)
			(xy 116.22532 -231.714548) (xy 116.224822 -231.741197) (xy 116.453402 -231.741197) (xy 116.453402 -231.687899)
			(xy 116.461345 -231.635195) (xy 116.477055 -231.584265) (xy 116.500181 -231.536244) (xy 116.530205 -231.492207)
			(xy 116.566457 -231.453136) (xy 116.608128 -231.419905) (xy 116.654286 -231.393256) (xy 116.7039 -231.373784)
			(xy 116.755862 -231.361924) (xy 116.809012 -231.357941) (xy 116.862162 -231.361924) (xy 116.914124 -231.373784)
			(xy 116.963738 -231.393256) (xy 117.009896 -231.419905) (xy 117.051567 -231.453136) (xy 117.087819 -231.492207)
			(xy 117.117843 -231.536244) (xy 117.140969 -231.584265) (xy 117.156679 -231.635195) (xy 117.164622 -231.687899)
			(xy 117.16512 -231.714548) (xy 117.164622 -231.741197) (xy 117.393202 -231.741197) (xy 117.393202 -231.687899)
			(xy 117.401145 -231.635195) (xy 117.416855 -231.584265) (xy 117.439981 -231.536244) (xy 117.470005 -231.492207)
			(xy 117.506257 -231.453136) (xy 117.547928 -231.419905) (xy 117.594086 -231.393256) (xy 117.6437 -231.373784)
			(xy 117.695662 -231.361924) (xy 117.748812 -231.357941) (xy 117.801962 -231.361924) (xy 117.853924 -231.373784)
			(xy 117.903538 -231.393256) (xy 117.949696 -231.419905) (xy 117.991367 -231.453136) (xy 118.027619 -231.492207)
			(xy 118.057643 -231.536244) (xy 118.080769 -231.584265) (xy 118.096479 -231.635195) (xy 118.104422 -231.687899)
			(xy 118.10492 -231.714548) (xy 118.104422 -231.741197) (xy 118.333002 -231.741197) (xy 118.333002 -231.687899)
			(xy 118.340945 -231.635195) (xy 118.356655 -231.584265) (xy 118.379781 -231.536244) (xy 118.409805 -231.492207)
			(xy 118.446057 -231.453136) (xy 118.487728 -231.419905) (xy 118.533886 -231.393256) (xy 118.5835 -231.373784)
			(xy 118.635462 -231.361924) (xy 118.688612 -231.357941) (xy 118.741762 -231.361924) (xy 118.793724 -231.373784)
			(xy 118.843338 -231.393256) (xy 118.889496 -231.419905) (xy 118.931167 -231.453136) (xy 118.967419 -231.492207)
			(xy 118.997443 -231.536244) (xy 119.020569 -231.584265) (xy 119.036279 -231.635195) (xy 119.044222 -231.687899)
			(xy 119.04472 -231.714548) (xy 119.044222 -231.741197) (xy 119.27331 -231.741197) (xy 119.27331 -231.687899)
			(xy 119.281253 -231.635195) (xy 119.296963 -231.584265) (xy 119.320089 -231.536244) (xy 119.350113 -231.492207)
			(xy 119.386365 -231.453136) (xy 119.428036 -231.419905) (xy 119.474194 -231.393256) (xy 119.523808 -231.373784)
			(xy 119.57577 -231.361924) (xy 119.62892 -231.357941) (xy 119.68207 -231.361924) (xy 119.734032 -231.373784)
			(xy 119.783646 -231.393256) (xy 119.829804 -231.419905) (xy 119.871475 -231.453136) (xy 119.907727 -231.492207)
			(xy 119.937751 -231.536244) (xy 119.960877 -231.584265) (xy 119.976587 -231.635195) (xy 119.98453 -231.687899)
			(xy 119.985028 -231.714548) (xy 119.98453 -231.741197) (xy 120.212602 -231.741197) (xy 120.212602 -231.687899)
			(xy 120.220545 -231.635195) (xy 120.236255 -231.584265) (xy 120.259381 -231.536244) (xy 120.289405 -231.492207)
			(xy 120.325657 -231.453136) (xy 120.367328 -231.419905) (xy 120.413486 -231.393256) (xy 120.4631 -231.373784)
			(xy 120.515062 -231.361924) (xy 120.568212 -231.357941) (xy 120.621362 -231.361924) (xy 120.673324 -231.373784)
			(xy 120.722938 -231.393256) (xy 120.769096 -231.419905) (xy 120.810767 -231.453136) (xy 120.847019 -231.492207)
			(xy 120.877043 -231.536244) (xy 120.900169 -231.584265) (xy 120.915879 -231.635195) (xy 120.923822 -231.687899)
			(xy 120.92432 -231.714548) (xy 120.923822 -231.741197) (xy 121.15291 -231.741197) (xy 121.15291 -231.687899)
			(xy 121.160853 -231.635195) (xy 121.176563 -231.584265) (xy 121.199689 -231.536244) (xy 121.229713 -231.492207)
			(xy 121.265965 -231.453136) (xy 121.307636 -231.419905) (xy 121.353794 -231.393256) (xy 121.403408 -231.373784)
			(xy 121.45537 -231.361924) (xy 121.50852 -231.357941) (xy 121.56167 -231.361924) (xy 121.613632 -231.373784)
			(xy 121.663246 -231.393256) (xy 121.709404 -231.419905) (xy 121.751075 -231.453136) (xy 121.787327 -231.492207)
			(xy 121.817351 -231.536244) (xy 121.840477 -231.584265) (xy 121.856187 -231.635195) (xy 121.86413 -231.687899)
			(xy 121.864628 -231.714548) (xy 121.86413 -231.741197) (xy 122.092456 -231.741197) (xy 122.092456 -231.687899)
			(xy 122.100399 -231.635195) (xy 122.116109 -231.584265) (xy 122.139235 -231.536244) (xy 122.169259 -231.492207)
			(xy 122.205511 -231.453136) (xy 122.247182 -231.419905) (xy 122.29334 -231.393256) (xy 122.342954 -231.373784)
			(xy 122.394916 -231.361924) (xy 122.448066 -231.357941) (xy 122.501216 -231.361924) (xy 122.553178 -231.373784)
			(xy 122.602792 -231.393256) (xy 122.64895 -231.419905) (xy 122.690621 -231.453136) (xy 122.726873 -231.492207)
			(xy 122.756897 -231.536244) (xy 122.780023 -231.584265) (xy 122.795733 -231.635195) (xy 122.803676 -231.687899)
			(xy 122.804174 -231.714548) (xy 122.803676 -231.741197) (xy 123.032002 -231.741197) (xy 123.032002 -231.687899)
			(xy 123.039945 -231.635195) (xy 123.055655 -231.584265) (xy 123.078781 -231.536244) (xy 123.108805 -231.492207)
			(xy 123.145057 -231.453136) (xy 123.186728 -231.419905) (xy 123.232886 -231.393256) (xy 123.2825 -231.373784)
			(xy 123.334462 -231.361924) (xy 123.387612 -231.357941) (xy 123.440762 -231.361924) (xy 123.492724 -231.373784)
			(xy 123.542338 -231.393256) (xy 123.588496 -231.419905) (xy 123.630167 -231.453136) (xy 123.666419 -231.492207)
			(xy 123.696443 -231.536244) (xy 123.719569 -231.584265) (xy 123.735279 -231.635195) (xy 123.743222 -231.687899)
			(xy 123.74372 -231.714548) (xy 123.743222 -231.741197) (xy 123.971802 -231.741197) (xy 123.971802 -231.687899)
			(xy 123.979745 -231.635195) (xy 123.995455 -231.584265) (xy 124.018581 -231.536244) (xy 124.048605 -231.492207)
			(xy 124.084857 -231.453136) (xy 124.126528 -231.419905) (xy 124.172686 -231.393256) (xy 124.2223 -231.373784)
			(xy 124.274262 -231.361924) (xy 124.327412 -231.357941) (xy 124.380562 -231.361924) (xy 124.432524 -231.373784)
			(xy 124.482138 -231.393256) (xy 124.528296 -231.419905) (xy 124.569967 -231.453136) (xy 124.606219 -231.492207)
			(xy 124.636243 -231.536244) (xy 124.659369 -231.584265) (xy 124.675079 -231.635195) (xy 124.683022 -231.687899)
			(xy 124.68352 -231.714548) (xy 124.683022 -231.741197) (xy 124.911602 -231.741197) (xy 124.911602 -231.687899)
			(xy 124.919545 -231.635195) (xy 124.935255 -231.584265) (xy 124.958381 -231.536244) (xy 124.988405 -231.492207)
			(xy 125.024657 -231.453136) (xy 125.066328 -231.419905) (xy 125.112486 -231.393256) (xy 125.1621 -231.373784)
			(xy 125.214062 -231.361924) (xy 125.267212 -231.357941) (xy 125.320362 -231.361924) (xy 125.372324 -231.373784)
			(xy 125.421938 -231.393256) (xy 125.468096 -231.419905) (xy 125.509767 -231.453136) (xy 125.546019 -231.492207)
			(xy 125.576043 -231.536244) (xy 125.599169 -231.584265) (xy 125.614879 -231.635195) (xy 125.622822 -231.687899)
			(xy 125.62332 -231.714548) (xy 125.622822 -231.741197) (xy 125.851402 -231.741197) (xy 125.851402 -231.687899)
			(xy 125.859345 -231.635195) (xy 125.875055 -231.584265) (xy 125.898181 -231.536244) (xy 125.928205 -231.492207)
			(xy 125.964457 -231.453136) (xy 126.006128 -231.419905) (xy 126.052286 -231.393256) (xy 126.1019 -231.373784)
			(xy 126.153862 -231.361924) (xy 126.207012 -231.357941) (xy 126.260162 -231.361924) (xy 126.312124 -231.373784)
			(xy 126.361738 -231.393256) (xy 126.407896 -231.419905) (xy 126.449567 -231.453136) (xy 126.485819 -231.492207)
			(xy 126.515843 -231.536244) (xy 126.538969 -231.584265) (xy 126.554679 -231.635195) (xy 126.562622 -231.687899)
			(xy 126.56312 -231.714548) (xy 126.562622 -231.741197) (xy 126.791202 -231.741197) (xy 126.791202 -231.687899)
			(xy 126.799145 -231.635195) (xy 126.814855 -231.584265) (xy 126.837981 -231.536244) (xy 126.868005 -231.492207)
			(xy 126.904257 -231.453136) (xy 126.945928 -231.419905) (xy 126.992086 -231.393256) (xy 127.0417 -231.373784)
			(xy 127.093662 -231.361924) (xy 127.146812 -231.357941) (xy 127.199962 -231.361924) (xy 127.251924 -231.373784)
			(xy 127.301538 -231.393256) (xy 127.347696 -231.419905) (xy 127.389367 -231.453136) (xy 127.425619 -231.492207)
			(xy 127.455643 -231.536244) (xy 127.478769 -231.584265) (xy 127.494479 -231.635195) (xy 127.502422 -231.687899)
			(xy 127.50292 -231.714548) (xy 127.502422 -231.741197) (xy 127.731002 -231.741197) (xy 127.731002 -231.687899)
			(xy 127.738945 -231.635195) (xy 127.754655 -231.584265) (xy 127.777781 -231.536244) (xy 127.807805 -231.492207)
			(xy 127.844057 -231.453136) (xy 127.885728 -231.419905) (xy 127.931886 -231.393256) (xy 127.9815 -231.373784)
			(xy 128.033462 -231.361924) (xy 128.086612 -231.357941) (xy 128.139762 -231.361924) (xy 128.191724 -231.373784)
			(xy 128.241338 -231.393256) (xy 128.287496 -231.419905) (xy 128.329167 -231.453136) (xy 128.365419 -231.492207)
			(xy 128.395443 -231.536244) (xy 128.418569 -231.584265) (xy 128.434279 -231.635195) (xy 128.442222 -231.687899)
			(xy 128.44272 -231.714548) (xy 128.442222 -231.741197) (xy 128.671056 -231.741197) (xy 128.671056 -231.687899)
			(xy 128.678999 -231.635195) (xy 128.694709 -231.584265) (xy 128.717835 -231.536244) (xy 128.747859 -231.492207)
			(xy 128.784111 -231.453136) (xy 128.825782 -231.419905) (xy 128.87194 -231.393256) (xy 128.921554 -231.373784)
			(xy 128.973516 -231.361924) (xy 129.026666 -231.357941) (xy 129.079816 -231.361924) (xy 129.131778 -231.373784)
			(xy 129.181392 -231.393256) (xy 129.22755 -231.419905) (xy 129.269221 -231.453136) (xy 129.305473 -231.492207)
			(xy 129.335497 -231.536244) (xy 129.358623 -231.584265) (xy 129.374333 -231.635195) (xy 129.382276 -231.687899)
			(xy 129.382774 -231.714548) (xy 129.382276 -231.741197) (xy 129.610602 -231.741197) (xy 129.610602 -231.687899)
			(xy 129.618545 -231.635195) (xy 129.634255 -231.584265) (xy 129.657381 -231.536244) (xy 129.687405 -231.492207)
			(xy 129.723657 -231.453136) (xy 129.765328 -231.419905) (xy 129.811486 -231.393256) (xy 129.8611 -231.373784)
			(xy 129.913062 -231.361924) (xy 129.966212 -231.357941) (xy 130.019362 -231.361924) (xy 130.071324 -231.373784)
			(xy 130.120938 -231.393256) (xy 130.167096 -231.419905) (xy 130.208767 -231.453136) (xy 130.245019 -231.492207)
			(xy 130.275043 -231.536244) (xy 130.298169 -231.584265) (xy 130.313879 -231.635195) (xy 130.321822 -231.687899)
			(xy 130.32232 -231.714548) (xy 130.321822 -231.741197) (xy 130.550402 -231.741197) (xy 130.550402 -231.687899)
			(xy 130.558345 -231.635195) (xy 130.574055 -231.584265) (xy 130.597181 -231.536244) (xy 130.627205 -231.492207)
			(xy 130.663457 -231.453136) (xy 130.705128 -231.419905) (xy 130.751286 -231.393256) (xy 130.8009 -231.373784)
			(xy 130.852862 -231.361924) (xy 130.906012 -231.357941) (xy 130.959162 -231.361924) (xy 131.011124 -231.373784)
			(xy 131.060738 -231.393256) (xy 131.106896 -231.419905) (xy 131.148567 -231.453136) (xy 131.184819 -231.492207)
			(xy 131.214843 -231.536244) (xy 131.237969 -231.584265) (xy 131.253679 -231.635195) (xy 131.261622 -231.687899)
			(xy 131.26212 -231.714548) (xy 131.261622 -231.741197) (xy 131.490202 -231.741197) (xy 131.490202 -231.687899)
			(xy 131.498145 -231.635195) (xy 131.513855 -231.584265) (xy 131.536981 -231.536244) (xy 131.567005 -231.492207)
			(xy 131.603257 -231.453136) (xy 131.644928 -231.419905) (xy 131.691086 -231.393256) (xy 131.7407 -231.373784)
			(xy 131.792662 -231.361924) (xy 131.845812 -231.357941) (xy 131.898962 -231.361924) (xy 131.950924 -231.373784)
			(xy 132.000538 -231.393256) (xy 132.046696 -231.419905) (xy 132.088367 -231.453136) (xy 132.124619 -231.492207)
			(xy 132.154643 -231.536244) (xy 132.177769 -231.584265) (xy 132.193479 -231.635195) (xy 132.201422 -231.687899)
			(xy 132.20192 -231.714548) (xy 132.201422 -231.741197) (xy 132.430002 -231.741197) (xy 132.430002 -231.687899)
			(xy 132.437945 -231.635195) (xy 132.453655 -231.584265) (xy 132.476781 -231.536244) (xy 132.506805 -231.492207)
			(xy 132.543057 -231.453136) (xy 132.584728 -231.419905) (xy 132.630886 -231.393256) (xy 132.6805 -231.373784)
			(xy 132.732462 -231.361924) (xy 132.785612 -231.357941) (xy 132.838762 -231.361924) (xy 132.890724 -231.373784)
			(xy 132.940338 -231.393256) (xy 132.986496 -231.419905) (xy 133.028167 -231.453136) (xy 133.064419 -231.492207)
			(xy 133.094443 -231.536244) (xy 133.117569 -231.584265) (xy 133.133279 -231.635195) (xy 133.141222 -231.687899)
			(xy 133.14172 -231.714548) (xy 133.141222 -231.741197) (xy 133.370056 -231.741197) (xy 133.370056 -231.687899)
			(xy 133.377999 -231.635195) (xy 133.393709 -231.584265) (xy 133.416835 -231.536244) (xy 133.446859 -231.492207)
			(xy 133.483111 -231.453136) (xy 133.524782 -231.419905) (xy 133.57094 -231.393256) (xy 133.620554 -231.373784)
			(xy 133.672516 -231.361924) (xy 133.725666 -231.357941) (xy 133.778816 -231.361924) (xy 133.830778 -231.373784)
			(xy 133.880392 -231.393256) (xy 133.92655 -231.419905) (xy 133.968221 -231.453136) (xy 134.004473 -231.492207)
			(xy 134.034497 -231.536244) (xy 134.057623 -231.584265) (xy 134.073333 -231.635195) (xy 134.081276 -231.687899)
			(xy 134.081774 -231.714548) (xy 134.081276 -231.741197) (xy 134.309856 -231.741197) (xy 134.309856 -231.687899)
			(xy 134.317799 -231.635195) (xy 134.333509 -231.584265) (xy 134.356635 -231.536244) (xy 134.386659 -231.492207)
			(xy 134.422911 -231.453136) (xy 134.464582 -231.419905) (xy 134.51074 -231.393256) (xy 134.560354 -231.373784)
			(xy 134.612316 -231.361924) (xy 134.665466 -231.357941) (xy 134.718616 -231.361924) (xy 134.770578 -231.373784)
			(xy 134.820192 -231.393256) (xy 134.86635 -231.419905) (xy 134.908021 -231.453136) (xy 134.944273 -231.492207)
			(xy 134.974297 -231.536244) (xy 134.997423 -231.584265) (xy 135.013133 -231.635195) (xy 135.021076 -231.687899)
			(xy 135.021574 -231.714548) (xy 135.021076 -231.741197) (xy 135.013133 -231.793901) (xy 134.997423 -231.844831)
			(xy 134.974297 -231.892852) (xy 134.944273 -231.936889) (xy 134.908021 -231.97596) (xy 134.86635 -232.009191)
			(xy 134.820192 -232.03584) (xy 134.770578 -232.055312) (xy 134.718616 -232.067172) (xy 134.665466 -232.071156)
			(xy 134.612316 -232.067172) (xy 134.560354 -232.055312) (xy 134.51074 -232.03584) (xy 134.464582 -232.009191)
			(xy 134.422911 -231.97596) (xy 134.386659 -231.936889) (xy 134.356635 -231.892852) (xy 134.333509 -231.844831)
			(xy 134.317799 -231.793901) (xy 134.309856 -231.741197) (xy 134.081276 -231.741197) (xy 134.073333 -231.793901)
			(xy 134.057623 -231.844831) (xy 134.034497 -231.892852) (xy 134.004473 -231.936889) (xy 133.968221 -231.97596)
			(xy 133.92655 -232.009191) (xy 133.880392 -232.03584) (xy 133.830778 -232.055312) (xy 133.778816 -232.067172)
			(xy 133.725666 -232.071156) (xy 133.672516 -232.067172) (xy 133.620554 -232.055312) (xy 133.57094 -232.03584)
			(xy 133.524782 -232.009191) (xy 133.483111 -231.97596) (xy 133.446859 -231.936889) (xy 133.416835 -231.892852)
			(xy 133.393709 -231.844831) (xy 133.377999 -231.793901) (xy 133.370056 -231.741197) (xy 133.141222 -231.741197)
			(xy 133.133279 -231.793901) (xy 133.117569 -231.844831) (xy 133.094443 -231.892852) (xy 133.064419 -231.936889)
			(xy 133.028167 -231.97596) (xy 132.986496 -232.009191) (xy 132.940338 -232.03584) (xy 132.890724 -232.055312)
			(xy 132.838762 -232.067172) (xy 132.785612 -232.071156) (xy 132.732462 -232.067172) (xy 132.6805 -232.055312)
			(xy 132.630886 -232.03584) (xy 132.584728 -232.009191) (xy 132.543057 -231.97596) (xy 132.506805 -231.936889)
			(xy 132.476781 -231.892852) (xy 132.453655 -231.844831) (xy 132.437945 -231.793901) (xy 132.430002 -231.741197)
			(xy 132.201422 -231.741197) (xy 132.193479 -231.793901) (xy 132.177769 -231.844831) (xy 132.154643 -231.892852)
			(xy 132.124619 -231.936889) (xy 132.088367 -231.97596) (xy 132.046696 -232.009191) (xy 132.000538 -232.03584)
			(xy 131.950924 -232.055312) (xy 131.898962 -232.067172) (xy 131.845812 -232.071156) (xy 131.792662 -232.067172)
			(xy 131.7407 -232.055312) (xy 131.691086 -232.03584) (xy 131.644928 -232.009191) (xy 131.603257 -231.97596)
			(xy 131.567005 -231.936889) (xy 131.536981 -231.892852) (xy 131.513855 -231.844831) (xy 131.498145 -231.793901)
			(xy 131.490202 -231.741197) (xy 131.261622 -231.741197) (xy 131.253679 -231.793901) (xy 131.237969 -231.844831)
			(xy 131.214843 -231.892852) (xy 131.184819 -231.936889) (xy 131.148567 -231.97596) (xy 131.106896 -232.009191)
			(xy 131.060738 -232.03584) (xy 131.011124 -232.055312) (xy 130.959162 -232.067172) (xy 130.906012 -232.071156)
			(xy 130.852862 -232.067172) (xy 130.8009 -232.055312) (xy 130.751286 -232.03584) (xy 130.705128 -232.009191)
			(xy 130.663457 -231.97596) (xy 130.627205 -231.936889) (xy 130.597181 -231.892852) (xy 130.574055 -231.844831)
			(xy 130.558345 -231.793901) (xy 130.550402 -231.741197) (xy 130.321822 -231.741197) (xy 130.313879 -231.793901)
			(xy 130.298169 -231.844831) (xy 130.275043 -231.892852) (xy 130.245019 -231.936889) (xy 130.208767 -231.97596)
			(xy 130.167096 -232.009191) (xy 130.120938 -232.03584) (xy 130.071324 -232.055312) (xy 130.019362 -232.067172)
			(xy 129.966212 -232.071156) (xy 129.913062 -232.067172) (xy 129.8611 -232.055312) (xy 129.811486 -232.03584)
			(xy 129.765328 -232.009191) (xy 129.723657 -231.97596) (xy 129.687405 -231.936889) (xy 129.657381 -231.892852)
			(xy 129.634255 -231.844831) (xy 129.618545 -231.793901) (xy 129.610602 -231.741197) (xy 129.382276 -231.741197)
			(xy 129.374333 -231.793901) (xy 129.358623 -231.844831) (xy 129.335497 -231.892852) (xy 129.305473 -231.936889)
			(xy 129.269221 -231.97596) (xy 129.22755 -232.009191) (xy 129.181392 -232.03584) (xy 129.131778 -232.055312)
			(xy 129.079816 -232.067172) (xy 129.026666 -232.071156) (xy 128.973516 -232.067172) (xy 128.921554 -232.055312)
			(xy 128.87194 -232.03584) (xy 128.825782 -232.009191) (xy 128.784111 -231.97596) (xy 128.747859 -231.936889)
			(xy 128.717835 -231.892852) (xy 128.694709 -231.844831) (xy 128.678999 -231.793901) (xy 128.671056 -231.741197)
			(xy 128.442222 -231.741197) (xy 128.434279 -231.793901) (xy 128.418569 -231.844831) (xy 128.395443 -231.892852)
			(xy 128.365419 -231.936889) (xy 128.329167 -231.97596) (xy 128.287496 -232.009191) (xy 128.241338 -232.03584)
			(xy 128.191724 -232.055312) (xy 128.139762 -232.067172) (xy 128.086612 -232.071156) (xy 128.033462 -232.067172)
			(xy 127.9815 -232.055312) (xy 127.931886 -232.03584) (xy 127.885728 -232.009191) (xy 127.844057 -231.97596)
			(xy 127.807805 -231.936889) (xy 127.777781 -231.892852) (xy 127.754655 -231.844831) (xy 127.738945 -231.793901)
			(xy 127.731002 -231.741197) (xy 127.502422 -231.741197) (xy 127.494479 -231.793901) (xy 127.478769 -231.844831)
			(xy 127.455643 -231.892852) (xy 127.425619 -231.936889) (xy 127.389367 -231.97596) (xy 127.347696 -232.009191)
			(xy 127.301538 -232.03584) (xy 127.251924 -232.055312) (xy 127.199962 -232.067172) (xy 127.146812 -232.071156)
			(xy 127.093662 -232.067172) (xy 127.0417 -232.055312) (xy 126.992086 -232.03584) (xy 126.945928 -232.009191)
			(xy 126.904257 -231.97596) (xy 126.868005 -231.936889) (xy 126.837981 -231.892852) (xy 126.814855 -231.844831)
			(xy 126.799145 -231.793901) (xy 126.791202 -231.741197) (xy 126.562622 -231.741197) (xy 126.554679 -231.793901)
			(xy 126.538969 -231.844831) (xy 126.515843 -231.892852) (xy 126.485819 -231.936889) (xy 126.449567 -231.97596)
			(xy 126.407896 -232.009191) (xy 126.361738 -232.03584) (xy 126.312124 -232.055312) (xy 126.260162 -232.067172)
			(xy 126.207012 -232.071156) (xy 126.153862 -232.067172) (xy 126.1019 -232.055312) (xy 126.052286 -232.03584)
			(xy 126.006128 -232.009191) (xy 125.964457 -231.97596) (xy 125.928205 -231.936889) (xy 125.898181 -231.892852)
			(xy 125.875055 -231.844831) (xy 125.859345 -231.793901) (xy 125.851402 -231.741197) (xy 125.622822 -231.741197)
			(xy 125.614879 -231.793901) (xy 125.599169 -231.844831) (xy 125.576043 -231.892852) (xy 125.546019 -231.936889)
			(xy 125.509767 -231.97596) (xy 125.468096 -232.009191) (xy 125.421938 -232.03584) (xy 125.372324 -232.055312)
			(xy 125.320362 -232.067172) (xy 125.267212 -232.071156) (xy 125.214062 -232.067172) (xy 125.1621 -232.055312)
			(xy 125.112486 -232.03584) (xy 125.066328 -232.009191) (xy 125.024657 -231.97596) (xy 124.988405 -231.936889)
			(xy 124.958381 -231.892852) (xy 124.935255 -231.844831) (xy 124.919545 -231.793901) (xy 124.911602 -231.741197)
			(xy 124.683022 -231.741197) (xy 124.675079 -231.793901) (xy 124.659369 -231.844831) (xy 124.636243 -231.892852)
			(xy 124.606219 -231.936889) (xy 124.569967 -231.97596) (xy 124.528296 -232.009191) (xy 124.482138 -232.03584)
			(xy 124.432524 -232.055312) (xy 124.380562 -232.067172) (xy 124.327412 -232.071156) (xy 124.274262 -232.067172)
			(xy 124.2223 -232.055312) (xy 124.172686 -232.03584) (xy 124.126528 -232.009191) (xy 124.084857 -231.97596)
			(xy 124.048605 -231.936889) (xy 124.018581 -231.892852) (xy 123.995455 -231.844831) (xy 123.979745 -231.793901)
			(xy 123.971802 -231.741197) (xy 123.743222 -231.741197) (xy 123.735279 -231.793901) (xy 123.719569 -231.844831)
			(xy 123.696443 -231.892852) (xy 123.666419 -231.936889) (xy 123.630167 -231.97596) (xy 123.588496 -232.009191)
			(xy 123.542338 -232.03584) (xy 123.492724 -232.055312) (xy 123.440762 -232.067172) (xy 123.387612 -232.071156)
			(xy 123.334462 -232.067172) (xy 123.2825 -232.055312) (xy 123.232886 -232.03584) (xy 123.186728 -232.009191)
			(xy 123.145057 -231.97596) (xy 123.108805 -231.936889) (xy 123.078781 -231.892852) (xy 123.055655 -231.844831)
			(xy 123.039945 -231.793901) (xy 123.032002 -231.741197) (xy 122.803676 -231.741197) (xy 122.795733 -231.793901)
			(xy 122.780023 -231.844831) (xy 122.756897 -231.892852) (xy 122.726873 -231.936889) (xy 122.690621 -231.97596)
			(xy 122.64895 -232.009191) (xy 122.602792 -232.03584) (xy 122.553178 -232.055312) (xy 122.501216 -232.067172)
			(xy 122.448066 -232.071156) (xy 122.394916 -232.067172) (xy 122.342954 -232.055312) (xy 122.29334 -232.03584)
			(xy 122.247182 -232.009191) (xy 122.205511 -231.97596) (xy 122.169259 -231.936889) (xy 122.139235 -231.892852)
			(xy 122.116109 -231.844831) (xy 122.100399 -231.793901) (xy 122.092456 -231.741197) (xy 121.86413 -231.741197)
			(xy 121.856187 -231.793901) (xy 121.840477 -231.844831) (xy 121.817351 -231.892852) (xy 121.787327 -231.936889)
			(xy 121.751075 -231.97596) (xy 121.709404 -232.009191) (xy 121.663246 -232.03584) (xy 121.613632 -232.055312)
			(xy 121.56167 -232.067172) (xy 121.50852 -232.071156) (xy 121.45537 -232.067172) (xy 121.403408 -232.055312)
			(xy 121.353794 -232.03584) (xy 121.307636 -232.009191) (xy 121.265965 -231.97596) (xy 121.229713 -231.936889)
			(xy 121.199689 -231.892852) (xy 121.176563 -231.844831) (xy 121.160853 -231.793901) (xy 121.15291 -231.741197)
			(xy 120.923822 -231.741197) (xy 120.915879 -231.793901) (xy 120.900169 -231.844831) (xy 120.877043 -231.892852)
			(xy 120.847019 -231.936889) (xy 120.810767 -231.97596) (xy 120.769096 -232.009191) (xy 120.722938 -232.03584)
			(xy 120.673324 -232.055312) (xy 120.621362 -232.067172) (xy 120.568212 -232.071156) (xy 120.515062 -232.067172)
			(xy 120.4631 -232.055312) (xy 120.413486 -232.03584) (xy 120.367328 -232.009191) (xy 120.325657 -231.97596)
			(xy 120.289405 -231.936889) (xy 120.259381 -231.892852) (xy 120.236255 -231.844831) (xy 120.220545 -231.793901)
			(xy 120.212602 -231.741197) (xy 119.98453 -231.741197) (xy 119.976587 -231.793901) (xy 119.960877 -231.844831)
			(xy 119.937751 -231.892852) (xy 119.907727 -231.936889) (xy 119.871475 -231.97596) (xy 119.829804 -232.009191)
			(xy 119.783646 -232.03584) (xy 119.734032 -232.055312) (xy 119.68207 -232.067172) (xy 119.62892 -232.071156)
			(xy 119.57577 -232.067172) (xy 119.523808 -232.055312) (xy 119.474194 -232.03584) (xy 119.428036 -232.009191)
			(xy 119.386365 -231.97596) (xy 119.350113 -231.936889) (xy 119.320089 -231.892852) (xy 119.296963 -231.844831)
			(xy 119.281253 -231.793901) (xy 119.27331 -231.741197) (xy 119.044222 -231.741197) (xy 119.036279 -231.793901)
			(xy 119.020569 -231.844831) (xy 118.997443 -231.892852) (xy 118.967419 -231.936889) (xy 118.931167 -231.97596)
			(xy 118.889496 -232.009191) (xy 118.843338 -232.03584) (xy 118.793724 -232.055312) (xy 118.741762 -232.067172)
			(xy 118.688612 -232.071156) (xy 118.635462 -232.067172) (xy 118.5835 -232.055312) (xy 118.533886 -232.03584)
			(xy 118.487728 -232.009191) (xy 118.446057 -231.97596) (xy 118.409805 -231.936889) (xy 118.379781 -231.892852)
			(xy 118.356655 -231.844831) (xy 118.340945 -231.793901) (xy 118.333002 -231.741197) (xy 118.104422 -231.741197)
			(xy 118.096479 -231.793901) (xy 118.080769 -231.844831) (xy 118.057643 -231.892852) (xy 118.027619 -231.936889)
			(xy 117.991367 -231.97596) (xy 117.949696 -232.009191) (xy 117.903538 -232.03584) (xy 117.853924 -232.055312)
			(xy 117.801962 -232.067172) (xy 117.748812 -232.071156) (xy 117.695662 -232.067172) (xy 117.6437 -232.055312)
			(xy 117.594086 -232.03584) (xy 117.547928 -232.009191) (xy 117.506257 -231.97596) (xy 117.470005 -231.936889)
			(xy 117.439981 -231.892852) (xy 117.416855 -231.844831) (xy 117.401145 -231.793901) (xy 117.393202 -231.741197)
			(xy 117.164622 -231.741197) (xy 117.156679 -231.793901) (xy 117.140969 -231.844831) (xy 117.117843 -231.892852)
			(xy 117.087819 -231.936889) (xy 117.051567 -231.97596) (xy 117.009896 -232.009191) (xy 116.963738 -232.03584)
			(xy 116.914124 -232.055312) (xy 116.862162 -232.067172) (xy 116.809012 -232.071156) (xy 116.755862 -232.067172)
			(xy 116.7039 -232.055312) (xy 116.654286 -232.03584) (xy 116.608128 -232.009191) (xy 116.566457 -231.97596)
			(xy 116.530205 -231.936889) (xy 116.500181 -231.892852) (xy 116.477055 -231.844831) (xy 116.461345 -231.793901)
			(xy 116.453402 -231.741197) (xy 116.224822 -231.741197) (xy 116.216879 -231.793901) (xy 116.201169 -231.844831)
			(xy 116.178043 -231.892852) (xy 116.148019 -231.936889) (xy 116.111767 -231.97596) (xy 116.070096 -232.009191)
			(xy 116.023938 -232.03584) (xy 115.974324 -232.055312) (xy 115.922362 -232.067172) (xy 115.869212 -232.071156)
			(xy 115.816062 -232.067172) (xy 115.7641 -232.055312) (xy 115.714486 -232.03584) (xy 115.668328 -232.009191)
			(xy 115.626657 -231.97596) (xy 115.590405 -231.936889) (xy 115.560381 -231.892852) (xy 115.537255 -231.844831)
			(xy 115.521545 -231.793901) (xy 115.513602 -231.741197) (xy 115.285022 -231.741197) (xy 115.277079 -231.793901)
			(xy 115.261369 -231.844831) (xy 115.238243 -231.892852) (xy 115.208219 -231.936889) (xy 115.171967 -231.97596)
			(xy 115.130296 -232.009191) (xy 115.084138 -232.03584) (xy 115.034524 -232.055312) (xy 114.982562 -232.067172)
			(xy 114.929412 -232.071156) (xy 114.876262 -232.067172) (xy 114.8243 -232.055312) (xy 114.774686 -232.03584)
			(xy 114.728528 -232.009191) (xy 114.686857 -231.97596) (xy 114.650605 -231.936889) (xy 114.620581 -231.892852)
			(xy 114.597455 -231.844831) (xy 114.581745 -231.793901) (xy 114.573802 -231.741197) (xy 114.34573 -231.741197)
			(xy 114.337787 -231.793901) (xy 114.322077 -231.844831) (xy 114.298951 -231.892852) (xy 114.268927 -231.936889)
			(xy 114.232675 -231.97596) (xy 114.191004 -232.009191) (xy 114.144846 -232.03584) (xy 114.095232 -232.055312)
			(xy 114.04327 -232.067172) (xy 113.99012 -232.071156) (xy 113.93697 -232.067172) (xy 113.885008 -232.055312)
			(xy 113.835394 -232.03584) (xy 113.789236 -232.009191) (xy 113.747565 -231.97596) (xy 113.711313 -231.936889)
			(xy 113.681289 -231.892852) (xy 113.658163 -231.844831) (xy 113.642453 -231.793901) (xy 113.63451 -231.741197)
			(xy 113.40593 -231.741197) (xy 113.397987 -231.793901) (xy 113.382277 -231.844831) (xy 113.359151 -231.892852)
			(xy 113.329127 -231.936889) (xy 113.292875 -231.97596) (xy 113.251204 -232.009191) (xy 113.205046 -232.03584)
			(xy 113.155432 -232.055312) (xy 113.10347 -232.067172) (xy 113.05032 -232.071156) (xy 112.99717 -232.067172)
			(xy 112.945208 -232.055312) (xy 112.895594 -232.03584) (xy 112.849436 -232.009191) (xy 112.807765 -231.97596)
			(xy 112.771513 -231.936889) (xy 112.741489 -231.892852) (xy 112.718363 -231.844831) (xy 112.702653 -231.793901)
			(xy 112.69471 -231.741197) (xy 112.46613 -231.741197) (xy 112.458187 -231.793901) (xy 112.442477 -231.844831)
			(xy 112.419351 -231.892852) (xy 112.389327 -231.936889) (xy 112.353075 -231.97596) (xy 112.311404 -232.009191)
			(xy 112.265246 -232.03584) (xy 112.215632 -232.055312) (xy 112.16367 -232.067172) (xy 112.11052 -232.071156)
			(xy 112.05737 -232.067172) (xy 112.005408 -232.055312) (xy 111.955794 -232.03584) (xy 111.909636 -232.009191)
			(xy 111.867965 -231.97596) (xy 111.831713 -231.936889) (xy 111.801689 -231.892852) (xy 111.778563 -231.844831)
			(xy 111.762853 -231.793901) (xy 111.75491 -231.741197) (xy 111.525822 -231.741197) (xy 111.517879 -231.793901)
			(xy 111.502169 -231.844831) (xy 111.479043 -231.892852) (xy 111.449019 -231.936889) (xy 111.412767 -231.97596)
			(xy 111.371096 -232.009191) (xy 111.324938 -232.03584) (xy 111.275324 -232.055312) (xy 111.223362 -232.067172)
			(xy 111.170212 -232.071156) (xy 111.117062 -232.067172) (xy 111.0651 -232.055312) (xy 111.015486 -232.03584)
			(xy 110.969328 -232.009191) (xy 110.927657 -231.97596) (xy 110.891405 -231.936889) (xy 110.861381 -231.892852)
			(xy 110.838255 -231.844831) (xy 110.822545 -231.793901) (xy 110.814602 -231.741197) (xy 110.586276 -231.741197)
			(xy 110.578333 -231.793901) (xy 110.562623 -231.844831) (xy 110.539497 -231.892852) (xy 110.509473 -231.936889)
			(xy 110.473221 -231.97596) (xy 110.43155 -232.009191) (xy 110.385392 -232.03584) (xy 110.335778 -232.055312)
			(xy 110.283816 -232.067172) (xy 110.230666 -232.071156) (xy 110.177516 -232.067172) (xy 110.125554 -232.055312)
			(xy 110.07594 -232.03584) (xy 110.029782 -232.009191) (xy 109.988111 -231.97596) (xy 109.951859 -231.936889)
			(xy 109.921835 -231.892852) (xy 109.898709 -231.844831) (xy 109.882999 -231.793901) (xy 109.875056 -231.741197)
			(xy 109.646222 -231.741197) (xy 109.638279 -231.793901) (xy 109.622569 -231.844831) (xy 109.599443 -231.892852)
			(xy 109.569419 -231.936889) (xy 109.533167 -231.97596) (xy 109.491496 -232.009191) (xy 109.445338 -232.03584)
			(xy 109.395724 -232.055312) (xy 109.343762 -232.067172) (xy 109.290612 -232.071156) (xy 109.237462 -232.067172)
			(xy 109.1855 -232.055312) (xy 109.135886 -232.03584) (xy 109.089728 -232.009191) (xy 109.048057 -231.97596)
			(xy 109.011805 -231.936889) (xy 108.981781 -231.892852) (xy 108.958655 -231.844831) (xy 108.942945 -231.793901)
			(xy 108.935002 -231.741197) (xy 108.706422 -231.741197) (xy 108.698479 -231.793901) (xy 108.682769 -231.844831)
			(xy 108.659643 -231.892852) (xy 108.629619 -231.936889) (xy 108.593367 -231.97596) (xy 108.551696 -232.009191)
			(xy 108.505538 -232.03584) (xy 108.455924 -232.055312) (xy 108.403962 -232.067172) (xy 108.350812 -232.071156)
			(xy 108.297662 -232.067172) (xy 108.2457 -232.055312) (xy 108.196086 -232.03584) (xy 108.149928 -232.009191)
			(xy 108.108257 -231.97596) (xy 108.072005 -231.936889) (xy 108.041981 -231.892852) (xy 108.018855 -231.844831)
			(xy 108.003145 -231.793901) (xy 107.995202 -231.741197) (xy 107.766622 -231.741197) (xy 107.758679 -231.793901)
			(xy 107.742969 -231.844831) (xy 107.719843 -231.892852) (xy 107.689819 -231.936889) (xy 107.653567 -231.97596)
			(xy 107.611896 -232.009191) (xy 107.565738 -232.03584) (xy 107.516124 -232.055312) (xy 107.464162 -232.067172)
			(xy 107.411012 -232.071156) (xy 107.357862 -232.067172) (xy 107.3059 -232.055312) (xy 107.256286 -232.03584)
			(xy 107.210128 -232.009191) (xy 107.168457 -231.97596) (xy 107.132205 -231.936889) (xy 107.102181 -231.892852)
			(xy 107.079055 -231.844831) (xy 107.063345 -231.793901) (xy 107.055402 -231.741197) (xy 106.826822 -231.741197)
			(xy 106.818879 -231.793901) (xy 106.803169 -231.844831) (xy 106.780043 -231.892852) (xy 106.750019 -231.936889)
			(xy 106.713767 -231.97596) (xy 106.672096 -232.009191) (xy 106.625938 -232.03584) (xy 106.576324 -232.055312)
			(xy 106.524362 -232.067172) (xy 106.471212 -232.071156) (xy 106.418062 -232.067172) (xy 106.3661 -232.055312)
			(xy 106.316486 -232.03584) (xy 106.270328 -232.009191) (xy 106.228657 -231.97596) (xy 106.192405 -231.936889)
			(xy 106.162381 -231.892852) (xy 106.139255 -231.844831) (xy 106.123545 -231.793901) (xy 106.115602 -231.741197)
			(xy 105.887022 -231.741197) (xy 105.879079 -231.793901) (xy 105.863369 -231.844831) (xy 105.840243 -231.892852)
			(xy 105.810219 -231.936889) (xy 105.773967 -231.97596) (xy 105.732296 -232.009191) (xy 105.686138 -232.03584)
			(xy 105.636524 -232.055312) (xy 105.584562 -232.067172) (xy 105.531412 -232.071156) (xy 105.478262 -232.067172)
			(xy 105.4263 -232.055312) (xy 105.376686 -232.03584) (xy 105.330528 -232.009191) (xy 105.288857 -231.97596)
			(xy 105.252605 -231.936889) (xy 105.222581 -231.892852) (xy 105.199455 -231.844831) (xy 105.183745 -231.793901)
			(xy 105.175802 -231.741197) (xy 104.947222 -231.741197) (xy 104.939279 -231.793901) (xy 104.923569 -231.844831)
			(xy 104.900443 -231.892852) (xy 104.870419 -231.936889) (xy 104.834167 -231.97596) (xy 104.792496 -232.009191)
			(xy 104.746338 -232.03584) (xy 104.696724 -232.055312) (xy 104.644762 -232.067172) (xy 104.591612 -232.071156)
			(xy 104.538462 -232.067172) (xy 104.4865 -232.055312) (xy 104.436886 -232.03584) (xy 104.390728 -232.009191)
			(xy 104.349057 -231.97596) (xy 104.312805 -231.936889) (xy 104.282781 -231.892852) (xy 104.259655 -231.844831)
			(xy 104.243945 -231.793901) (xy 104.236002 -231.741197) (xy 104.007422 -231.741197) (xy 103.999479 -231.793901)
			(xy 103.983769 -231.844831) (xy 103.960643 -231.892852) (xy 103.930619 -231.936889) (xy 103.894367 -231.97596)
			(xy 103.852696 -232.009191) (xy 103.806538 -232.03584) (xy 103.756924 -232.055312) (xy 103.704962 -232.067172)
			(xy 103.651812 -232.071156) (xy 103.598662 -232.067172) (xy 103.5467 -232.055312) (xy 103.497086 -232.03584)
			(xy 103.450928 -232.009191) (xy 103.409257 -231.97596) (xy 103.373005 -231.936889) (xy 103.342981 -231.892852)
			(xy 103.319855 -231.844831) (xy 103.304145 -231.793901) (xy 103.296202 -231.741197) (xy 103.067622 -231.741197)
			(xy 103.059679 -231.793901) (xy 103.043969 -231.844831) (xy 103.020843 -231.892852) (xy 102.990819 -231.936889)
			(xy 102.954567 -231.97596) (xy 102.912896 -232.009191) (xy 102.866738 -232.03584) (xy 102.817124 -232.055312)
			(xy 102.765162 -232.067172) (xy 102.712012 -232.071156) (xy 102.658862 -232.067172) (xy 102.6069 -232.055312)
			(xy 102.557286 -232.03584) (xy 102.511128 -232.009191) (xy 102.469457 -231.97596) (xy 102.433205 -231.936889)
			(xy 102.403181 -231.892852) (xy 102.380055 -231.844831) (xy 102.364345 -231.793901) (xy 102.356402 -231.741197)
			(xy 102.127822 -231.741197) (xy 102.119879 -231.793901) (xy 102.104169 -231.844831) (xy 102.081043 -231.892852)
			(xy 102.051019 -231.936889) (xy 102.014767 -231.97596) (xy 101.973096 -232.009191) (xy 101.926938 -232.03584)
			(xy 101.877324 -232.055312) (xy 101.825362 -232.067172) (xy 101.772212 -232.071156) (xy 101.719062 -232.067172)
			(xy 101.6671 -232.055312) (xy 101.617486 -232.03584) (xy 101.571328 -232.009191) (xy 101.529657 -231.97596)
			(xy 101.493405 -231.936889) (xy 101.463381 -231.892852) (xy 101.440255 -231.844831) (xy 101.424545 -231.793901)
			(xy 101.416602 -231.741197) (xy 101.188276 -231.741197) (xy 101.180333 -231.793901) (xy 101.164623 -231.844831)
			(xy 101.141497 -231.892852) (xy 101.111473 -231.936889) (xy 101.075221 -231.97596) (xy 101.03355 -232.009191)
			(xy 100.987392 -232.03584) (xy 100.937778 -232.055312) (xy 100.885816 -232.067172) (xy 100.832666 -232.071156)
			(xy 100.779516 -232.067172) (xy 100.727554 -232.055312) (xy 100.67794 -232.03584) (xy 100.631782 -232.009191)
			(xy 100.590111 -231.97596) (xy 100.553859 -231.936889) (xy 100.523835 -231.892852) (xy 100.500709 -231.844831)
			(xy 100.484999 -231.793901) (xy 100.477056 -231.741197) (xy 100.248222 -231.741197) (xy 100.240279 -231.793901)
			(xy 100.224569 -231.844831) (xy 100.201443 -231.892852) (xy 100.171419 -231.936889) (xy 100.135167 -231.97596)
			(xy 100.093496 -232.009191) (xy 100.047338 -232.03584) (xy 99.997724 -232.055312) (xy 99.945762 -232.067172)
			(xy 99.892612 -232.071156) (xy 99.839462 -232.067172) (xy 99.7875 -232.055312) (xy 99.737886 -232.03584)
			(xy 99.691728 -232.009191) (xy 99.650057 -231.97596) (xy 99.613805 -231.936889) (xy 99.583781 -231.892852)
			(xy 99.560655 -231.844831) (xy 99.544945 -231.793901) (xy 99.537002 -231.741197) (xy 99.308422 -231.741197)
			(xy 99.300479 -231.793901) (xy 99.284769 -231.844831) (xy 99.261643 -231.892852) (xy 99.231619 -231.936889)
			(xy 99.195367 -231.97596) (xy 99.153696 -232.009191) (xy 99.107538 -232.03584) (xy 99.057924 -232.055312)
			(xy 99.005962 -232.067172) (xy 98.952812 -232.071156) (xy 98.899662 -232.067172) (xy 98.8477 -232.055312)
			(xy 98.798086 -232.03584) (xy 98.751928 -232.009191) (xy 98.710257 -231.97596) (xy 98.674005 -231.936889)
			(xy 98.643981 -231.892852) (xy 98.620855 -231.844831) (xy 98.605145 -231.793901) (xy 98.597202 -231.741197)
			(xy 98.368622 -231.741197) (xy 98.360679 -231.793901) (xy 98.344969 -231.844831) (xy 98.321843 -231.892852)
			(xy 98.291819 -231.936889) (xy 98.255567 -231.97596) (xy 98.213896 -232.009191) (xy 98.167738 -232.03584)
			(xy 98.118124 -232.055312) (xy 98.066162 -232.067172) (xy 98.013012 -232.071156) (xy 97.959862 -232.067172)
			(xy 97.9079 -232.055312) (xy 97.858286 -232.03584) (xy 97.812128 -232.009191) (xy 97.770457 -231.97596)
			(xy 97.734205 -231.936889) (xy 97.704181 -231.892852) (xy 97.681055 -231.844831) (xy 97.665345 -231.793901)
			(xy 97.657402 -231.741197) (xy 97.428822 -231.741197) (xy 97.420879 -231.793901) (xy 97.405169 -231.844831)
			(xy 97.382043 -231.892852) (xy 97.352019 -231.936889) (xy 97.315767 -231.97596) (xy 97.274096 -232.009191)
			(xy 97.227938 -232.03584) (xy 97.178324 -232.055312) (xy 97.126362 -232.067172) (xy 97.073212 -232.071156)
			(xy 97.020062 -232.067172) (xy 96.9681 -232.055312) (xy 96.918486 -232.03584) (xy 96.872328 -232.009191)
			(xy 96.830657 -231.97596) (xy 96.794405 -231.936889) (xy 96.764381 -231.892852) (xy 96.741255 -231.844831)
			(xy 96.725545 -231.793901) (xy 96.717602 -231.741197) (xy 96.489022 -231.741197) (xy 96.481079 -231.793901)
			(xy 96.465369 -231.844831) (xy 96.442243 -231.892852) (xy 96.412219 -231.936889) (xy 96.375967 -231.97596)
			(xy 96.334296 -232.009191) (xy 96.288138 -232.03584) (xy 96.238524 -232.055312) (xy 96.186562 -232.067172)
			(xy 96.133412 -232.071156) (xy 96.080262 -232.067172) (xy 96.0283 -232.055312) (xy 95.978686 -232.03584)
			(xy 95.932528 -232.009191) (xy 95.890857 -231.97596) (xy 95.854605 -231.936889) (xy 95.824581 -231.892852)
			(xy 95.801455 -231.844831) (xy 95.785745 -231.793901) (xy 95.777802 -231.741197) (xy 95.549222 -231.741197)
			(xy 95.541279 -231.793901) (xy 95.525569 -231.844831) (xy 95.502443 -231.892852) (xy 95.472419 -231.936889)
			(xy 95.436167 -231.97596) (xy 95.394496 -232.009191) (xy 95.348338 -232.03584) (xy 95.298724 -232.055312)
			(xy 95.246762 -232.067172) (xy 95.193612 -232.071156) (xy 95.140462 -232.067172) (xy 95.0885 -232.055312)
			(xy 95.038886 -232.03584) (xy 94.992728 -232.009191) (xy 94.951057 -231.97596) (xy 94.914805 -231.936889)
			(xy 94.884781 -231.892852) (xy 94.861655 -231.844831) (xy 94.845945 -231.793901) (xy 94.838002 -231.741197)
			(xy 94.609676 -231.741197) (xy 94.601733 -231.793901) (xy 94.586023 -231.844831) (xy 94.562897 -231.892852)
			(xy 94.532873 -231.936889) (xy 94.496621 -231.97596) (xy 94.45495 -232.009191) (xy 94.408792 -232.03584)
			(xy 94.359178 -232.055312) (xy 94.307216 -232.067172) (xy 94.254066 -232.071156) (xy 94.200916 -232.067172)
			(xy 94.148954 -232.055312) (xy 94.09934 -232.03584) (xy 94.053182 -232.009191) (xy 94.011511 -231.97596)
			(xy 93.975259 -231.936889) (xy 93.945235 -231.892852) (xy 93.922109 -231.844831) (xy 93.906399 -231.793901)
			(xy 93.898456 -231.741197) (xy 93.669622 -231.741197) (xy 93.661679 -231.793901) (xy 93.645969 -231.844831)
			(xy 93.622843 -231.892852) (xy 93.592819 -231.936889) (xy 93.556567 -231.97596) (xy 93.514896 -232.009191)
			(xy 93.468738 -232.03584) (xy 93.419124 -232.055312) (xy 93.367162 -232.067172) (xy 93.314012 -232.071156)
			(xy 93.260862 -232.067172) (xy 93.2089 -232.055312) (xy 93.159286 -232.03584) (xy 93.113128 -232.009191)
			(xy 93.071457 -231.97596) (xy 93.035205 -231.936889) (xy 93.005181 -231.892852) (xy 92.982055 -231.844831)
			(xy 92.966345 -231.793901) (xy 92.958402 -231.741197) (xy 92.729822 -231.741197) (xy 92.721879 -231.793901)
			(xy 92.706169 -231.844831) (xy 92.683043 -231.892852) (xy 92.653019 -231.936889) (xy 92.616767 -231.97596)
			(xy 92.575096 -232.009191) (xy 92.528938 -232.03584) (xy 92.479324 -232.055312) (xy 92.427362 -232.067172)
			(xy 92.374212 -232.071156) (xy 92.321062 -232.067172) (xy 92.2691 -232.055312) (xy 92.219486 -232.03584)
			(xy 92.173328 -232.009191) (xy 92.131657 -231.97596) (xy 92.095405 -231.936889) (xy 92.065381 -231.892852)
			(xy 92.042255 -231.844831) (xy 92.026545 -231.793901) (xy 92.018602 -231.741197) (xy 91.790022 -231.741197)
			(xy 91.782079 -231.793901) (xy 91.766369 -231.844831) (xy 91.743243 -231.892852) (xy 91.713219 -231.936889)
			(xy 91.676967 -231.97596) (xy 91.635296 -232.009191) (xy 91.589138 -232.03584) (xy 91.539524 -232.055312)
			(xy 91.487562 -232.067172) (xy 91.434412 -232.071156) (xy 91.381262 -232.067172) (xy 91.3293 -232.055312)
			(xy 91.279686 -232.03584) (xy 91.233528 -232.009191) (xy 91.191857 -231.97596) (xy 91.155605 -231.936889)
			(xy 91.125581 -231.892852) (xy 91.102455 -231.844831) (xy 91.086745 -231.793901) (xy 91.078802 -231.741197)
			(xy 90.850222 -231.741197) (xy 90.842279 -231.793901) (xy 90.826569 -231.844831) (xy 90.803443 -231.892852)
			(xy 90.773419 -231.936889) (xy 90.737167 -231.97596) (xy 90.695496 -232.009191) (xy 90.649338 -232.03584)
			(xy 90.599724 -232.055312) (xy 90.547762 -232.067172) (xy 90.494612 -232.071156) (xy 90.441462 -232.067172)
			(xy 90.3895 -232.055312) (xy 90.339886 -232.03584) (xy 90.293728 -232.009191) (xy 90.252057 -231.97596)
			(xy 90.215805 -231.936889) (xy 90.185781 -231.892852) (xy 90.162655 -231.844831) (xy 90.146945 -231.793901)
			(xy 90.139002 -231.741197) (xy 89.910422 -231.741197) (xy 89.902479 -231.793901) (xy 89.886769 -231.844831)
			(xy 89.863643 -231.892852) (xy 89.833619 -231.936889) (xy 89.797367 -231.97596) (xy 89.755696 -232.009191)
			(xy 89.709538 -232.03584) (xy 89.659924 -232.055312) (xy 89.607962 -232.067172) (xy 89.554812 -232.071156)
			(xy 89.501662 -232.067172) (xy 89.4497 -232.055312) (xy 89.400086 -232.03584) (xy 89.353928 -232.009191)
			(xy 89.312257 -231.97596) (xy 89.276005 -231.936889) (xy 89.245981 -231.892852) (xy 89.222855 -231.844831)
			(xy 89.207145 -231.793901) (xy 89.199202 -231.741197) (xy 88.969564 -231.741197) (xy 88.967632 -231.767196)
			(xy 88.955975 -231.81872) (xy 88.936834 -231.867956) (xy 88.910628 -231.913824) (xy 88.877933 -231.955316)
			(xy 88.839465 -231.991522) (xy 88.796071 -232.021647) (xy 88.748702 -232.04503) (xy 88.723724 -232.053638)
			(xy 88.688418 -232.065068) (xy 88.688418 -232.178606) (xy 88.688912 -232.193063) (xy 88.697 -232.220823)
			(xy 88.712551 -232.245198) (xy 88.734318 -232.26423) (xy 88.76055 -232.27639) (xy 88.789141 -232.280701)
			(xy 88.817793 -232.276816) (xy 88.844203 -232.265048) (xy 88.85555 -232.256076) (xy 88.874909 -232.240312)
			(xy 88.917204 -232.213788) (xy 88.962788 -232.19343) (xy 89.010768 -232.179634) (xy 89.060204 -232.172673)
			(xy 89.085166 -232.172256) (xy 89.111821 -232.172727) (xy 89.164538 -232.180668) (xy 89.215481 -232.196378)
			(xy 89.263514 -232.219505) (xy 89.307564 -232.249534) (xy 89.346645 -232.285792) (xy 89.379886 -232.327471)
			(xy 89.406543 -232.373639) (xy 89.42602 -232.423264) (xy 89.437884 -232.475238) (xy 89.441868 -232.5284)
			(xy 89.439874 -232.555013) (xy 89.669356 -232.555013) (xy 89.669356 -232.501715) (xy 89.677299 -232.449011)
			(xy 89.693009 -232.398081) (xy 89.716135 -232.35006) (xy 89.746159 -232.306023) (xy 89.782411 -232.266952)
			(xy 89.824082 -232.233721) (xy 89.87024 -232.207072) (xy 89.919854 -232.1876) (xy 89.971816 -232.17574)
			(xy 90.024966 -232.171757) (xy 90.078116 -232.17574) (xy 90.130078 -232.1876) (xy 90.179692 -232.207072)
			(xy 90.22585 -232.233721) (xy 90.267521 -232.266952) (xy 90.303773 -232.306023) (xy 90.333797 -232.35006)
			(xy 90.356923 -232.398081) (xy 90.372633 -232.449011) (xy 90.380576 -232.501715) (xy 90.381074 -232.528364)
			(xy 90.380576 -232.555013) (xy 90.609156 -232.555013) (xy 90.609156 -232.501715) (xy 90.617099 -232.449011)
			(xy 90.632809 -232.398081) (xy 90.655935 -232.35006) (xy 90.685959 -232.306023) (xy 90.722211 -232.266952)
			(xy 90.763882 -232.233721) (xy 90.81004 -232.207072) (xy 90.859654 -232.1876) (xy 90.911616 -232.17574)
			(xy 90.964766 -232.171757) (xy 91.017916 -232.17574) (xy 91.069878 -232.1876) (xy 91.119492 -232.207072)
			(xy 91.16565 -232.233721) (xy 91.207321 -232.266952) (xy 91.243573 -232.306023) (xy 91.273597 -232.35006)
			(xy 91.296723 -232.398081) (xy 91.312433 -232.449011) (xy 91.320376 -232.501715) (xy 91.320874 -232.528364)
			(xy 91.320376 -232.555013) (xy 91.548702 -232.555013) (xy 91.548702 -232.501715) (xy 91.556645 -232.449011)
			(xy 91.572355 -232.398081) (xy 91.595481 -232.35006) (xy 91.625505 -232.306023) (xy 91.661757 -232.266952)
			(xy 91.703428 -232.233721) (xy 91.749586 -232.207072) (xy 91.7992 -232.1876) (xy 91.851162 -232.17574)
			(xy 91.904312 -232.171757) (xy 91.957462 -232.17574) (xy 92.009424 -232.1876) (xy 92.059038 -232.207072)
			(xy 92.105196 -232.233721) (xy 92.146867 -232.266952) (xy 92.183119 -232.306023) (xy 92.213143 -232.35006)
			(xy 92.236269 -232.398081) (xy 92.251979 -232.449011) (xy 92.259922 -232.501715) (xy 92.26042 -232.528364)
			(xy 92.259922 -232.555013) (xy 92.488756 -232.555013) (xy 92.488756 -232.501715) (xy 92.496699 -232.449011)
			(xy 92.512409 -232.398081) (xy 92.535535 -232.35006) (xy 92.565559 -232.306023) (xy 92.601811 -232.266952)
			(xy 92.643482 -232.233721) (xy 92.68964 -232.207072) (xy 92.739254 -232.1876) (xy 92.791216 -232.17574)
			(xy 92.844366 -232.171757) (xy 92.897516 -232.17574) (xy 92.949478 -232.1876) (xy 92.999092 -232.207072)
			(xy 93.04525 -232.233721) (xy 93.086921 -232.266952) (xy 93.123173 -232.306023) (xy 93.153197 -232.35006)
			(xy 93.176323 -232.398081) (xy 93.192033 -232.449011) (xy 93.199976 -232.501715) (xy 93.200474 -232.528364)
			(xy 93.199976 -232.555013) (xy 93.428556 -232.555013) (xy 93.428556 -232.501715) (xy 93.436499 -232.449011)
			(xy 93.452209 -232.398081) (xy 93.475335 -232.35006) (xy 93.505359 -232.306023) (xy 93.541611 -232.266952)
			(xy 93.583282 -232.233721) (xy 93.62944 -232.207072) (xy 93.679054 -232.1876) (xy 93.731016 -232.17574)
			(xy 93.784166 -232.171757) (xy 93.837316 -232.17574) (xy 93.889278 -232.1876) (xy 93.938892 -232.207072)
			(xy 93.98505 -232.233721) (xy 94.026721 -232.266952) (xy 94.062973 -232.306023) (xy 94.092997 -232.35006)
			(xy 94.116123 -232.398081) (xy 94.131833 -232.449011) (xy 94.139776 -232.501715) (xy 94.140274 -232.528364)
			(xy 94.139776 -232.555013) (xy 94.368356 -232.555013) (xy 94.368356 -232.501715) (xy 94.376299 -232.449011)
			(xy 94.392009 -232.398081) (xy 94.415135 -232.35006) (xy 94.445159 -232.306023) (xy 94.481411 -232.266952)
			(xy 94.523082 -232.233721) (xy 94.56924 -232.207072) (xy 94.618854 -232.1876) (xy 94.670816 -232.17574)
			(xy 94.723966 -232.171757) (xy 94.777116 -232.17574) (xy 94.829078 -232.1876) (xy 94.878692 -232.207072)
			(xy 94.92485 -232.233721) (xy 94.966521 -232.266952) (xy 95.002773 -232.306023) (xy 95.032797 -232.35006)
			(xy 95.055923 -232.398081) (xy 95.071633 -232.449011) (xy 95.079576 -232.501715) (xy 95.080074 -232.528364)
			(xy 95.079576 -232.555013) (xy 95.308156 -232.555013) (xy 95.308156 -232.501715) (xy 95.316099 -232.449011)
			(xy 95.331809 -232.398081) (xy 95.354935 -232.35006) (xy 95.384959 -232.306023) (xy 95.421211 -232.266952)
			(xy 95.462882 -232.233721) (xy 95.50904 -232.207072) (xy 95.558654 -232.1876) (xy 95.610616 -232.17574)
			(xy 95.663766 -232.171757) (xy 95.716916 -232.17574) (xy 95.768878 -232.1876) (xy 95.818492 -232.207072)
			(xy 95.86465 -232.233721) (xy 95.906321 -232.266952) (xy 95.942573 -232.306023) (xy 95.972597 -232.35006)
			(xy 95.995723 -232.398081) (xy 96.011433 -232.449011) (xy 96.019376 -232.501715) (xy 96.019874 -232.528364)
			(xy 96.019376 -232.555013) (xy 96.247956 -232.555013) (xy 96.247956 -232.501715) (xy 96.255899 -232.449011)
			(xy 96.271609 -232.398081) (xy 96.294735 -232.35006) (xy 96.324759 -232.306023) (xy 96.361011 -232.266952)
			(xy 96.402682 -232.233721) (xy 96.44884 -232.207072) (xy 96.498454 -232.1876) (xy 96.550416 -232.17574)
			(xy 96.603566 -232.171757) (xy 96.656716 -232.17574) (xy 96.708678 -232.1876) (xy 96.758292 -232.207072)
			(xy 96.80445 -232.233721) (xy 96.846121 -232.266952) (xy 96.882373 -232.306023) (xy 96.912397 -232.35006)
			(xy 96.935523 -232.398081) (xy 96.951233 -232.449011) (xy 96.959176 -232.501715) (xy 96.959674 -232.528364)
			(xy 96.959176 -232.555013) (xy 97.187756 -232.555013) (xy 97.187756 -232.501715) (xy 97.195699 -232.449011)
			(xy 97.211409 -232.398081) (xy 97.234535 -232.35006) (xy 97.264559 -232.306023) (xy 97.300811 -232.266952)
			(xy 97.342482 -232.233721) (xy 97.38864 -232.207072) (xy 97.438254 -232.1876) (xy 97.490216 -232.17574)
			(xy 97.543366 -232.171757) (xy 97.596516 -232.17574) (xy 97.648478 -232.1876) (xy 97.698092 -232.207072)
			(xy 97.74425 -232.233721) (xy 97.785921 -232.266952) (xy 97.822173 -232.306023) (xy 97.852197 -232.35006)
			(xy 97.875323 -232.398081) (xy 97.891033 -232.449011) (xy 97.898976 -232.501715) (xy 97.899474 -232.528364)
			(xy 97.898976 -232.555013) (xy 98.127302 -232.555013) (xy 98.127302 -232.501715) (xy 98.135245 -232.449011)
			(xy 98.150955 -232.398081) (xy 98.174081 -232.35006) (xy 98.204105 -232.306023) (xy 98.240357 -232.266952)
			(xy 98.282028 -232.233721) (xy 98.328186 -232.207072) (xy 98.3778 -232.1876) (xy 98.429762 -232.17574)
			(xy 98.482912 -232.171757) (xy 98.536062 -232.17574) (xy 98.588024 -232.1876) (xy 98.637638 -232.207072)
			(xy 98.683796 -232.233721) (xy 98.725467 -232.266952) (xy 98.761719 -232.306023) (xy 98.791743 -232.35006)
			(xy 98.814869 -232.398081) (xy 98.830579 -232.449011) (xy 98.838522 -232.501715) (xy 98.83902 -232.528364)
			(xy 98.838522 -232.555013) (xy 99.067356 -232.555013) (xy 99.067356 -232.501715) (xy 99.075299 -232.449011)
			(xy 99.091009 -232.398081) (xy 99.114135 -232.35006) (xy 99.144159 -232.306023) (xy 99.180411 -232.266952)
			(xy 99.222082 -232.233721) (xy 99.26824 -232.207072) (xy 99.317854 -232.1876) (xy 99.369816 -232.17574)
			(xy 99.422966 -232.171757) (xy 99.476116 -232.17574) (xy 99.528078 -232.1876) (xy 99.577692 -232.207072)
			(xy 99.62385 -232.233721) (xy 99.665521 -232.266952) (xy 99.701773 -232.306023) (xy 99.731797 -232.35006)
			(xy 99.754923 -232.398081) (xy 99.770633 -232.449011) (xy 99.778576 -232.501715) (xy 99.779074 -232.528364)
			(xy 99.778576 -232.555013) (xy 100.007156 -232.555013) (xy 100.007156 -232.501715) (xy 100.015099 -232.449011)
			(xy 100.030809 -232.398081) (xy 100.053935 -232.35006) (xy 100.083959 -232.306023) (xy 100.120211 -232.266952)
			(xy 100.161882 -232.233721) (xy 100.20804 -232.207072) (xy 100.257654 -232.1876) (xy 100.309616 -232.17574)
			(xy 100.362766 -232.171757) (xy 100.415916 -232.17574) (xy 100.467878 -232.1876) (xy 100.517492 -232.207072)
			(xy 100.56365 -232.233721) (xy 100.605321 -232.266952) (xy 100.641573 -232.306023) (xy 100.671597 -232.35006)
			(xy 100.694723 -232.398081) (xy 100.710433 -232.449011) (xy 100.718376 -232.501715) (xy 100.718874 -232.528364)
			(xy 100.718376 -232.555013) (xy 101.886756 -232.555013) (xy 101.886756 -232.501715) (xy 101.894699 -232.449011)
			(xy 101.910409 -232.398081) (xy 101.933535 -232.35006) (xy 101.963559 -232.306023) (xy 101.999811 -232.266952)
			(xy 102.041482 -232.233721) (xy 102.08764 -232.207072) (xy 102.137254 -232.1876) (xy 102.189216 -232.17574)
			(xy 102.242366 -232.171757) (xy 102.295516 -232.17574) (xy 102.347478 -232.1876) (xy 102.397092 -232.207072)
			(xy 102.44325 -232.233721) (xy 102.484921 -232.266952) (xy 102.521173 -232.306023) (xy 102.551197 -232.35006)
			(xy 102.574323 -232.398081) (xy 102.590033 -232.449011) (xy 102.597976 -232.501715) (xy 102.598474 -232.528364)
			(xy 102.597976 -232.555013) (xy 102.826556 -232.555013) (xy 102.826556 -232.501715) (xy 102.834499 -232.449011)
			(xy 102.850209 -232.398081) (xy 102.873335 -232.35006) (xy 102.903359 -232.306023) (xy 102.939611 -232.266952)
			(xy 102.981282 -232.233721) (xy 103.02744 -232.207072) (xy 103.077054 -232.1876) (xy 103.129016 -232.17574)
			(xy 103.182166 -232.171757) (xy 103.235316 -232.17574) (xy 103.287278 -232.1876) (xy 103.336892 -232.207072)
			(xy 103.38305 -232.233721) (xy 103.424721 -232.266952) (xy 103.460973 -232.306023) (xy 103.490997 -232.35006)
			(xy 103.514123 -232.398081) (xy 103.529833 -232.449011) (xy 103.537776 -232.501715) (xy 103.538274 -232.528364)
			(xy 103.537776 -232.555013) (xy 103.766356 -232.555013) (xy 103.766356 -232.501715) (xy 103.774299 -232.449011)
			(xy 103.790009 -232.398081) (xy 103.813135 -232.35006) (xy 103.843159 -232.306023) (xy 103.879411 -232.266952)
			(xy 103.921082 -232.233721) (xy 103.96724 -232.207072) (xy 104.016854 -232.1876) (xy 104.068816 -232.17574)
			(xy 104.121966 -232.171757) (xy 104.175116 -232.17574) (xy 104.227078 -232.1876) (xy 104.276692 -232.207072)
			(xy 104.32285 -232.233721) (xy 104.364521 -232.266952) (xy 104.400773 -232.306023) (xy 104.430797 -232.35006)
			(xy 104.453923 -232.398081) (xy 104.469633 -232.449011) (xy 104.477576 -232.501715) (xy 104.478074 -232.528364)
			(xy 104.477576 -232.555013) (xy 104.706156 -232.555013) (xy 104.706156 -232.501715) (xy 104.714099 -232.449011)
			(xy 104.729809 -232.398081) (xy 104.752935 -232.35006) (xy 104.782959 -232.306023) (xy 104.819211 -232.266952)
			(xy 104.860882 -232.233721) (xy 104.90704 -232.207072) (xy 104.956654 -232.1876) (xy 105.008616 -232.17574)
			(xy 105.061766 -232.171757) (xy 105.114916 -232.17574) (xy 105.166878 -232.1876) (xy 105.216492 -232.207072)
			(xy 105.26265 -232.233721) (xy 105.304321 -232.266952) (xy 105.340573 -232.306023) (xy 105.370597 -232.35006)
			(xy 105.393723 -232.398081) (xy 105.409433 -232.449011) (xy 105.417376 -232.501715) (xy 105.417874 -232.528364)
			(xy 105.417376 -232.555013) (xy 105.645956 -232.555013) (xy 105.645956 -232.501715) (xy 105.653899 -232.449011)
			(xy 105.669609 -232.398081) (xy 105.692735 -232.35006) (xy 105.722759 -232.306023) (xy 105.759011 -232.266952)
			(xy 105.800682 -232.233721) (xy 105.84684 -232.207072) (xy 105.896454 -232.1876) (xy 105.948416 -232.17574)
			(xy 106.001566 -232.171757) (xy 106.054716 -232.17574) (xy 106.106678 -232.1876) (xy 106.156292 -232.207072)
			(xy 106.20245 -232.233721) (xy 106.244121 -232.266952) (xy 106.280373 -232.306023) (xy 106.310397 -232.35006)
			(xy 106.333523 -232.398081) (xy 106.349233 -232.449011) (xy 106.357176 -232.501715) (xy 106.357674 -232.528364)
			(xy 106.357176 -232.555013) (xy 106.585756 -232.555013) (xy 106.585756 -232.501715) (xy 106.593699 -232.449011)
			(xy 106.609409 -232.398081) (xy 106.632535 -232.35006) (xy 106.662559 -232.306023) (xy 106.698811 -232.266952)
			(xy 106.740482 -232.233721) (xy 106.78664 -232.207072) (xy 106.836254 -232.1876) (xy 106.888216 -232.17574)
			(xy 106.941366 -232.171757) (xy 106.994516 -232.17574) (xy 107.046478 -232.1876) (xy 107.096092 -232.207072)
			(xy 107.14225 -232.233721) (xy 107.183921 -232.266952) (xy 107.220173 -232.306023) (xy 107.250197 -232.35006)
			(xy 107.273323 -232.398081) (xy 107.289033 -232.449011) (xy 107.296976 -232.501715) (xy 107.297474 -232.528364)
			(xy 107.296976 -232.555013) (xy 107.525556 -232.555013) (xy 107.525556 -232.501715) (xy 107.533499 -232.449011)
			(xy 107.549209 -232.398081) (xy 107.572335 -232.35006) (xy 107.602359 -232.306023) (xy 107.638611 -232.266952)
			(xy 107.680282 -232.233721) (xy 107.72644 -232.207072) (xy 107.776054 -232.1876) (xy 107.828016 -232.17574)
			(xy 107.881166 -232.171757) (xy 107.934316 -232.17574) (xy 107.986278 -232.1876) (xy 108.035892 -232.207072)
			(xy 108.08205 -232.233721) (xy 108.123721 -232.266952) (xy 108.159973 -232.306023) (xy 108.189997 -232.35006)
			(xy 108.213123 -232.398081) (xy 108.228833 -232.449011) (xy 108.236776 -232.501715) (xy 108.237274 -232.528364)
			(xy 108.236776 -232.555013) (xy 108.465356 -232.555013) (xy 108.465356 -232.501715) (xy 108.473299 -232.449011)
			(xy 108.489009 -232.398081) (xy 108.512135 -232.35006) (xy 108.542159 -232.306023) (xy 108.578411 -232.266952)
			(xy 108.620082 -232.233721) (xy 108.66624 -232.207072) (xy 108.715854 -232.1876) (xy 108.767816 -232.17574)
			(xy 108.820966 -232.171757) (xy 108.874116 -232.17574) (xy 108.926078 -232.1876) (xy 108.975692 -232.207072)
			(xy 109.02185 -232.233721) (xy 109.063521 -232.266952) (xy 109.099773 -232.306023) (xy 109.129797 -232.35006)
			(xy 109.152923 -232.398081) (xy 109.168633 -232.449011) (xy 109.176576 -232.501715) (xy 109.177074 -232.528364)
			(xy 109.176576 -232.555013) (xy 109.405156 -232.555013) (xy 109.405156 -232.501715) (xy 109.413099 -232.449011)
			(xy 109.428809 -232.398081) (xy 109.451935 -232.35006) (xy 109.481959 -232.306023) (xy 109.518211 -232.266952)
			(xy 109.559882 -232.233721) (xy 109.60604 -232.207072) (xy 109.655654 -232.1876) (xy 109.707616 -232.17574)
			(xy 109.760766 -232.171757) (xy 109.813916 -232.17574) (xy 109.865878 -232.1876) (xy 109.915492 -232.207072)
			(xy 109.96165 -232.233721) (xy 110.003321 -232.266952) (xy 110.039573 -232.306023) (xy 110.069597 -232.35006)
			(xy 110.092723 -232.398081) (xy 110.108433 -232.449011) (xy 110.116376 -232.501715) (xy 110.116874 -232.528364)
			(xy 110.116376 -232.555013) (xy 110.344956 -232.555013) (xy 110.344956 -232.501715) (xy 110.352899 -232.449011)
			(xy 110.368609 -232.398081) (xy 110.391735 -232.35006) (xy 110.421759 -232.306023) (xy 110.458011 -232.266952)
			(xy 110.499682 -232.233721) (xy 110.54584 -232.207072) (xy 110.595454 -232.1876) (xy 110.647416 -232.17574)
			(xy 110.700566 -232.171757) (xy 110.753716 -232.17574) (xy 110.805678 -232.1876) (xy 110.855292 -232.207072)
			(xy 110.90145 -232.233721) (xy 110.943121 -232.266952) (xy 110.979373 -232.306023) (xy 111.009397 -232.35006)
			(xy 111.032523 -232.398081) (xy 111.048233 -232.449011) (xy 111.056176 -232.501715) (xy 111.056674 -232.528364)
			(xy 111.056176 -232.555013) (xy 111.284756 -232.555013) (xy 111.284756 -232.501715) (xy 111.292699 -232.449011)
			(xy 111.308409 -232.398081) (xy 111.331535 -232.35006) (xy 111.361559 -232.306023) (xy 111.397811 -232.266952)
			(xy 111.439482 -232.233721) (xy 111.48564 -232.207072) (xy 111.535254 -232.1876) (xy 111.587216 -232.17574)
			(xy 111.640366 -232.171757) (xy 111.693516 -232.17574) (xy 111.745478 -232.1876) (xy 111.795092 -232.207072)
			(xy 111.84125 -232.233721) (xy 111.882921 -232.266952) (xy 111.919173 -232.306023) (xy 111.949197 -232.35006)
			(xy 111.972323 -232.398081) (xy 111.988033 -232.449011) (xy 111.995976 -232.501715) (xy 111.996474 -232.528364)
			(xy 111.995976 -232.555013) (xy 112.224556 -232.555013) (xy 112.224556 -232.501715) (xy 112.232499 -232.449011)
			(xy 112.248209 -232.398081) (xy 112.271335 -232.35006) (xy 112.301359 -232.306023) (xy 112.337611 -232.266952)
			(xy 112.379282 -232.233721) (xy 112.42544 -232.207072) (xy 112.475054 -232.1876) (xy 112.527016 -232.17574)
			(xy 112.580166 -232.171757) (xy 112.633316 -232.17574) (xy 112.685278 -232.1876) (xy 112.734892 -232.207072)
			(xy 112.78105 -232.233721) (xy 112.822721 -232.266952) (xy 112.858973 -232.306023) (xy 112.888997 -232.35006)
			(xy 112.912123 -232.398081) (xy 112.927833 -232.449011) (xy 112.935776 -232.501715) (xy 112.936274 -232.528364)
			(xy 112.935776 -232.555013) (xy 113.164356 -232.555013) (xy 113.164356 -232.501715) (xy 113.172299 -232.449011)
			(xy 113.188009 -232.398081) (xy 113.211135 -232.35006) (xy 113.241159 -232.306023) (xy 113.277411 -232.266952)
			(xy 113.319082 -232.233721) (xy 113.36524 -232.207072) (xy 113.414854 -232.1876) (xy 113.466816 -232.17574)
			(xy 113.519966 -232.171757) (xy 113.573116 -232.17574) (xy 113.625078 -232.1876) (xy 113.674692 -232.207072)
			(xy 113.72085 -232.233721) (xy 113.762521 -232.266952) (xy 113.798773 -232.306023) (xy 113.828797 -232.35006)
			(xy 113.851923 -232.398081) (xy 113.867633 -232.449011) (xy 113.875576 -232.501715) (xy 113.876074 -232.528364)
			(xy 113.875576 -232.555013) (xy 114.104156 -232.555013) (xy 114.104156 -232.501715) (xy 114.112099 -232.449011)
			(xy 114.127809 -232.398081) (xy 114.150935 -232.35006) (xy 114.180959 -232.306023) (xy 114.217211 -232.266952)
			(xy 114.258882 -232.233721) (xy 114.30504 -232.207072) (xy 114.354654 -232.1876) (xy 114.406616 -232.17574)
			(xy 114.459766 -232.171757) (xy 114.512916 -232.17574) (xy 114.564878 -232.1876) (xy 114.614492 -232.207072)
			(xy 114.66065 -232.233721) (xy 114.702321 -232.266952) (xy 114.738573 -232.306023) (xy 114.768597 -232.35006)
			(xy 114.791723 -232.398081) (xy 114.807433 -232.449011) (xy 114.815376 -232.501715) (xy 114.815874 -232.528364)
			(xy 114.815376 -232.555013) (xy 115.043956 -232.555013) (xy 115.043956 -232.501715) (xy 115.051899 -232.449011)
			(xy 115.067609 -232.398081) (xy 115.090735 -232.35006) (xy 115.120759 -232.306023) (xy 115.157011 -232.266952)
			(xy 115.198682 -232.233721) (xy 115.24484 -232.207072) (xy 115.294454 -232.1876) (xy 115.346416 -232.17574)
			(xy 115.399566 -232.171757) (xy 115.452716 -232.17574) (xy 115.504678 -232.1876) (xy 115.554292 -232.207072)
			(xy 115.60045 -232.233721) (xy 115.642121 -232.266952) (xy 115.678373 -232.306023) (xy 115.708397 -232.35006)
			(xy 115.731523 -232.398081) (xy 115.747233 -232.449011) (xy 115.755176 -232.501715) (xy 115.755674 -232.528364)
			(xy 115.755176 -232.555013) (xy 115.983756 -232.555013) (xy 115.983756 -232.501715) (xy 115.991699 -232.449011)
			(xy 116.007409 -232.398081) (xy 116.030535 -232.35006) (xy 116.060559 -232.306023) (xy 116.096811 -232.266952)
			(xy 116.138482 -232.233721) (xy 116.18464 -232.207072) (xy 116.234254 -232.1876) (xy 116.286216 -232.17574)
			(xy 116.339366 -232.171757) (xy 116.392516 -232.17574) (xy 116.444478 -232.1876) (xy 116.494092 -232.207072)
			(xy 116.54025 -232.233721) (xy 116.581921 -232.266952) (xy 116.618173 -232.306023) (xy 116.648197 -232.35006)
			(xy 116.671323 -232.398081) (xy 116.687033 -232.449011) (xy 116.694976 -232.501715) (xy 116.695474 -232.528364)
			(xy 116.694976 -232.555013) (xy 116.923556 -232.555013) (xy 116.923556 -232.501715) (xy 116.931499 -232.449011)
			(xy 116.947209 -232.398081) (xy 116.970335 -232.35006) (xy 117.000359 -232.306023) (xy 117.036611 -232.266952)
			(xy 117.078282 -232.233721) (xy 117.12444 -232.207072) (xy 117.174054 -232.1876) (xy 117.226016 -232.17574)
			(xy 117.279166 -232.171757) (xy 117.332316 -232.17574) (xy 117.384278 -232.1876) (xy 117.433892 -232.207072)
			(xy 117.48005 -232.233721) (xy 117.521721 -232.266952) (xy 117.557973 -232.306023) (xy 117.587997 -232.35006)
			(xy 117.611123 -232.398081) (xy 117.626833 -232.449011) (xy 117.634776 -232.501715) (xy 117.635274 -232.528364)
			(xy 117.634776 -232.555013) (xy 117.863356 -232.555013) (xy 117.863356 -232.501715) (xy 117.871299 -232.449011)
			(xy 117.887009 -232.398081) (xy 117.910135 -232.35006) (xy 117.940159 -232.306023) (xy 117.976411 -232.266952)
			(xy 118.018082 -232.233721) (xy 118.06424 -232.207072) (xy 118.113854 -232.1876) (xy 118.165816 -232.17574)
			(xy 118.218966 -232.171757) (xy 118.272116 -232.17574) (xy 118.324078 -232.1876) (xy 118.373692 -232.207072)
			(xy 118.41985 -232.233721) (xy 118.461521 -232.266952) (xy 118.497773 -232.306023) (xy 118.527797 -232.35006)
			(xy 118.550923 -232.398081) (xy 118.566633 -232.449011) (xy 118.574576 -232.501715) (xy 118.575074 -232.528364)
			(xy 118.574576 -232.555013) (xy 118.803156 -232.555013) (xy 118.803156 -232.501715) (xy 118.811099 -232.449011)
			(xy 118.826809 -232.398081) (xy 118.849935 -232.35006) (xy 118.879959 -232.306023) (xy 118.916211 -232.266952)
			(xy 118.957882 -232.233721) (xy 119.00404 -232.207072) (xy 119.053654 -232.1876) (xy 119.105616 -232.17574)
			(xy 119.158766 -232.171757) (xy 119.211916 -232.17574) (xy 119.263878 -232.1876) (xy 119.313492 -232.207072)
			(xy 119.35965 -232.233721) (xy 119.401321 -232.266952) (xy 119.437573 -232.306023) (xy 119.467597 -232.35006)
			(xy 119.490723 -232.398081) (xy 119.506433 -232.449011) (xy 119.514376 -232.501715) (xy 119.514874 -232.528364)
			(xy 119.514376 -232.555013) (xy 119.742702 -232.555013) (xy 119.742702 -232.501715) (xy 119.750645 -232.449011)
			(xy 119.766355 -232.398081) (xy 119.789481 -232.35006) (xy 119.819505 -232.306023) (xy 119.855757 -232.266952)
			(xy 119.897428 -232.233721) (xy 119.943586 -232.207072) (xy 119.9932 -232.1876) (xy 120.045162 -232.17574)
			(xy 120.098312 -232.171757) (xy 120.151462 -232.17574) (xy 120.203424 -232.1876) (xy 120.253038 -232.207072)
			(xy 120.299196 -232.233721) (xy 120.340867 -232.266952) (xy 120.377119 -232.306023) (xy 120.407143 -232.35006)
			(xy 120.430269 -232.398081) (xy 120.445979 -232.449011) (xy 120.453922 -232.501715) (xy 120.45442 -232.528364)
			(xy 120.453922 -232.555013) (xy 120.682756 -232.555013) (xy 120.682756 -232.501715) (xy 120.690699 -232.449011)
			(xy 120.706409 -232.398081) (xy 120.729535 -232.35006) (xy 120.759559 -232.306023) (xy 120.795811 -232.266952)
			(xy 120.837482 -232.233721) (xy 120.88364 -232.207072) (xy 120.933254 -232.1876) (xy 120.985216 -232.17574)
			(xy 121.038366 -232.171757) (xy 121.091516 -232.17574) (xy 121.143478 -232.1876) (xy 121.193092 -232.207072)
			(xy 121.23925 -232.233721) (xy 121.280921 -232.266952) (xy 121.317173 -232.306023) (xy 121.347197 -232.35006)
			(xy 121.370323 -232.398081) (xy 121.386033 -232.449011) (xy 121.393976 -232.501715) (xy 121.394474 -232.528364)
			(xy 121.393976 -232.555013) (xy 121.622556 -232.555013) (xy 121.622556 -232.501715) (xy 121.630499 -232.449011)
			(xy 121.646209 -232.398081) (xy 121.669335 -232.35006) (xy 121.699359 -232.306023) (xy 121.735611 -232.266952)
			(xy 121.777282 -232.233721) (xy 121.82344 -232.207072) (xy 121.873054 -232.1876) (xy 121.925016 -232.17574)
			(xy 121.978166 -232.171757) (xy 122.031316 -232.17574) (xy 122.083278 -232.1876) (xy 122.132892 -232.207072)
			(xy 122.17905 -232.233721) (xy 122.220721 -232.266952) (xy 122.256973 -232.306023) (xy 122.286997 -232.35006)
			(xy 122.310123 -232.398081) (xy 122.325833 -232.449011) (xy 122.333776 -232.501715) (xy 122.334274 -232.528364)
			(xy 122.333776 -232.555013) (xy 122.562356 -232.555013) (xy 122.562356 -232.501715) (xy 122.570299 -232.449011)
			(xy 122.586009 -232.398081) (xy 122.609135 -232.35006) (xy 122.639159 -232.306023) (xy 122.675411 -232.266952)
			(xy 122.717082 -232.233721) (xy 122.76324 -232.207072) (xy 122.812854 -232.1876) (xy 122.864816 -232.17574)
			(xy 122.917966 -232.171757) (xy 122.971116 -232.17574) (xy 123.023078 -232.1876) (xy 123.072692 -232.207072)
			(xy 123.11885 -232.233721) (xy 123.160521 -232.266952) (xy 123.196773 -232.306023) (xy 123.226797 -232.35006)
			(xy 123.249923 -232.398081) (xy 123.265633 -232.449011) (xy 123.273576 -232.501715) (xy 123.274074 -232.528364)
			(xy 123.273576 -232.555013) (xy 123.502156 -232.555013) (xy 123.502156 -232.501715) (xy 123.510099 -232.449011)
			(xy 123.525809 -232.398081) (xy 123.548935 -232.35006) (xy 123.578959 -232.306023) (xy 123.615211 -232.266952)
			(xy 123.656882 -232.233721) (xy 123.70304 -232.207072) (xy 123.752654 -232.1876) (xy 123.804616 -232.17574)
			(xy 123.857766 -232.171757) (xy 123.910916 -232.17574) (xy 123.962878 -232.1876) (xy 124.012492 -232.207072)
			(xy 124.05865 -232.233721) (xy 124.100321 -232.266952) (xy 124.136573 -232.306023) (xy 124.166597 -232.35006)
			(xy 124.189723 -232.398081) (xy 124.205433 -232.449011) (xy 124.213376 -232.501715) (xy 124.213874 -232.528364)
			(xy 124.213376 -232.555013) (xy 124.441956 -232.555013) (xy 124.441956 -232.501715) (xy 124.449899 -232.449011)
			(xy 124.465609 -232.398081) (xy 124.488735 -232.35006) (xy 124.518759 -232.306023) (xy 124.555011 -232.266952)
			(xy 124.596682 -232.233721) (xy 124.64284 -232.207072) (xy 124.692454 -232.1876) (xy 124.744416 -232.17574)
			(xy 124.797566 -232.171757) (xy 124.850716 -232.17574) (xy 124.902678 -232.1876) (xy 124.952292 -232.207072)
			(xy 124.99845 -232.233721) (xy 125.040121 -232.266952) (xy 125.076373 -232.306023) (xy 125.106397 -232.35006)
			(xy 125.129523 -232.398081) (xy 125.145233 -232.449011) (xy 125.153176 -232.501715) (xy 125.153674 -232.528364)
			(xy 125.153176 -232.555013) (xy 125.381756 -232.555013) (xy 125.381756 -232.501715) (xy 125.389699 -232.449011)
			(xy 125.405409 -232.398081) (xy 125.428535 -232.35006) (xy 125.458559 -232.306023) (xy 125.494811 -232.266952)
			(xy 125.536482 -232.233721) (xy 125.58264 -232.207072) (xy 125.632254 -232.1876) (xy 125.684216 -232.17574)
			(xy 125.737366 -232.171757) (xy 125.790516 -232.17574) (xy 125.842478 -232.1876) (xy 125.892092 -232.207072)
			(xy 125.93825 -232.233721) (xy 125.979921 -232.266952) (xy 126.016173 -232.306023) (xy 126.046197 -232.35006)
			(xy 126.069323 -232.398081) (xy 126.085033 -232.449011) (xy 126.092976 -232.501715) (xy 126.093474 -232.528364)
			(xy 126.092976 -232.555013) (xy 126.321302 -232.555013) (xy 126.321302 -232.501715) (xy 126.329245 -232.449011)
			(xy 126.344955 -232.398081) (xy 126.368081 -232.35006) (xy 126.398105 -232.306023) (xy 126.434357 -232.266952)
			(xy 126.476028 -232.233721) (xy 126.522186 -232.207072) (xy 126.5718 -232.1876) (xy 126.623762 -232.17574)
			(xy 126.676912 -232.171757) (xy 126.730062 -232.17574) (xy 126.782024 -232.1876) (xy 126.831638 -232.207072)
			(xy 126.877796 -232.233721) (xy 126.919467 -232.266952) (xy 126.955719 -232.306023) (xy 126.985743 -232.35006)
			(xy 127.008869 -232.398081) (xy 127.024579 -232.449011) (xy 127.032522 -232.501715) (xy 127.03302 -232.528364)
			(xy 127.032522 -232.555013) (xy 127.261356 -232.555013) (xy 127.261356 -232.501715) (xy 127.269299 -232.449011)
			(xy 127.285009 -232.398081) (xy 127.308135 -232.35006) (xy 127.338159 -232.306023) (xy 127.374411 -232.266952)
			(xy 127.416082 -232.233721) (xy 127.46224 -232.207072) (xy 127.511854 -232.1876) (xy 127.563816 -232.17574)
			(xy 127.616966 -232.171757) (xy 127.670116 -232.17574) (xy 127.722078 -232.1876) (xy 127.771692 -232.207072)
			(xy 127.81785 -232.233721) (xy 127.859521 -232.266952) (xy 127.895773 -232.306023) (xy 127.925797 -232.35006)
			(xy 127.948923 -232.398081) (xy 127.964633 -232.449011) (xy 127.972576 -232.501715) (xy 127.973074 -232.528364)
			(xy 127.972576 -232.555013) (xy 128.201156 -232.555013) (xy 128.201156 -232.501715) (xy 128.209099 -232.449011)
			(xy 128.224809 -232.398081) (xy 128.247935 -232.35006) (xy 128.277959 -232.306023) (xy 128.314211 -232.266952)
			(xy 128.355882 -232.233721) (xy 128.40204 -232.207072) (xy 128.451654 -232.1876) (xy 128.503616 -232.17574)
			(xy 128.556766 -232.171757) (xy 128.609916 -232.17574) (xy 128.661878 -232.1876) (xy 128.711492 -232.207072)
			(xy 128.75765 -232.233721) (xy 128.799321 -232.266952) (xy 128.835573 -232.306023) (xy 128.865597 -232.35006)
			(xy 128.888723 -232.398081) (xy 128.904433 -232.449011) (xy 128.912376 -232.501715) (xy 128.912874 -232.528364)
			(xy 128.912376 -232.555013) (xy 129.140956 -232.555013) (xy 129.140956 -232.501715) (xy 129.148899 -232.449011)
			(xy 129.164609 -232.398081) (xy 129.187735 -232.35006) (xy 129.217759 -232.306023) (xy 129.254011 -232.266952)
			(xy 129.295682 -232.233721) (xy 129.34184 -232.207072) (xy 129.391454 -232.1876) (xy 129.443416 -232.17574)
			(xy 129.496566 -232.171757) (xy 129.549716 -232.17574) (xy 129.601678 -232.1876) (xy 129.651292 -232.207072)
			(xy 129.69745 -232.233721) (xy 129.739121 -232.266952) (xy 129.775373 -232.306023) (xy 129.805397 -232.35006)
			(xy 129.828523 -232.398081) (xy 129.844233 -232.449011) (xy 129.852176 -232.501715) (xy 129.852674 -232.528364)
			(xy 129.852176 -232.555013) (xy 130.080756 -232.555013) (xy 130.080756 -232.501715) (xy 130.088699 -232.449011)
			(xy 130.104409 -232.398081) (xy 130.127535 -232.35006) (xy 130.157559 -232.306023) (xy 130.193811 -232.266952)
			(xy 130.235482 -232.233721) (xy 130.28164 -232.207072) (xy 130.331254 -232.1876) (xy 130.383216 -232.17574)
			(xy 130.436366 -232.171757) (xy 130.489516 -232.17574) (xy 130.541478 -232.1876) (xy 130.591092 -232.207072)
			(xy 130.63725 -232.233721) (xy 130.678921 -232.266952) (xy 130.715173 -232.306023) (xy 130.745197 -232.35006)
			(xy 130.768323 -232.398081) (xy 130.784033 -232.449011) (xy 130.791976 -232.501715) (xy 130.792474 -232.528364)
			(xy 130.791976 -232.555013) (xy 131.020556 -232.555013) (xy 131.020556 -232.501715) (xy 131.028499 -232.449011)
			(xy 131.044209 -232.398081) (xy 131.067335 -232.35006) (xy 131.097359 -232.306023) (xy 131.133611 -232.266952)
			(xy 131.175282 -232.233721) (xy 131.22144 -232.207072) (xy 131.271054 -232.1876) (xy 131.323016 -232.17574)
			(xy 131.376166 -232.171757) (xy 131.429316 -232.17574) (xy 131.481278 -232.1876) (xy 131.530892 -232.207072)
			(xy 131.57705 -232.233721) (xy 131.618721 -232.266952) (xy 131.654973 -232.306023) (xy 131.684997 -232.35006)
			(xy 131.708123 -232.398081) (xy 131.723833 -232.449011) (xy 131.731776 -232.501715) (xy 131.732274 -232.528364)
			(xy 131.731776 -232.555013) (xy 131.960356 -232.555013) (xy 131.960356 -232.501715) (xy 131.968299 -232.449011)
			(xy 131.984009 -232.398081) (xy 132.007135 -232.35006) (xy 132.037159 -232.306023) (xy 132.073411 -232.266952)
			(xy 132.115082 -232.233721) (xy 132.16124 -232.207072) (xy 132.210854 -232.1876) (xy 132.262816 -232.17574)
			(xy 132.315966 -232.171757) (xy 132.369116 -232.17574) (xy 132.421078 -232.1876) (xy 132.470692 -232.207072)
			(xy 132.51685 -232.233721) (xy 132.558521 -232.266952) (xy 132.594773 -232.306023) (xy 132.624797 -232.35006)
			(xy 132.647923 -232.398081) (xy 132.663633 -232.449011) (xy 132.671576 -232.501715) (xy 132.672074 -232.528364)
			(xy 132.671576 -232.555013) (xy 132.899902 -232.555013) (xy 132.899902 -232.501715) (xy 132.907845 -232.449011)
			(xy 132.923555 -232.398081) (xy 132.946681 -232.35006) (xy 132.976705 -232.306023) (xy 133.012957 -232.266952)
			(xy 133.054628 -232.233721) (xy 133.100786 -232.207072) (xy 133.1504 -232.1876) (xy 133.202362 -232.17574)
			(xy 133.255512 -232.171757) (xy 133.308662 -232.17574) (xy 133.360624 -232.1876) (xy 133.410238 -232.207072)
			(xy 133.456396 -232.233721) (xy 133.498067 -232.266952) (xy 133.534319 -232.306023) (xy 133.564343 -232.35006)
			(xy 133.587469 -232.398081) (xy 133.603179 -232.449011) (xy 133.611122 -232.501715) (xy 133.61162 -232.528364)
			(xy 133.611122 -232.555013) (xy 133.839956 -232.555013) (xy 133.839956 -232.501715) (xy 133.847899 -232.449011)
			(xy 133.863609 -232.398081) (xy 133.886735 -232.35006) (xy 133.916759 -232.306023) (xy 133.953011 -232.266952)
			(xy 133.994682 -232.233721) (xy 134.04084 -232.207072) (xy 134.090454 -232.1876) (xy 134.142416 -232.17574)
			(xy 134.195566 -232.171757) (xy 134.248716 -232.17574) (xy 134.300678 -232.1876) (xy 134.350292 -232.207072)
			(xy 134.39645 -232.233721) (xy 134.438121 -232.266952) (xy 134.474373 -232.306023) (xy 134.504397 -232.35006)
			(xy 134.527523 -232.398081) (xy 134.543233 -232.449011) (xy 134.551176 -232.501715) (xy 134.551674 -232.528364)
			(xy 134.551176 -232.555013) (xy 134.543233 -232.607717) (xy 134.527523 -232.658647) (xy 134.504397 -232.706668)
			(xy 134.474373 -232.750705) (xy 134.438121 -232.789776) (xy 134.39645 -232.823007) (xy 134.350292 -232.849656)
			(xy 134.300678 -232.869128) (xy 134.248716 -232.880988) (xy 134.195566 -232.884972) (xy 134.142416 -232.880988)
			(xy 134.090454 -232.869128) (xy 134.04084 -232.849656) (xy 133.994682 -232.823007) (xy 133.953011 -232.789776)
			(xy 133.916759 -232.750705) (xy 133.886735 -232.706668) (xy 133.863609 -232.658647) (xy 133.847899 -232.607717)
			(xy 133.839956 -232.555013) (xy 133.611122 -232.555013) (xy 133.603179 -232.607717) (xy 133.587469 -232.658647)
			(xy 133.564343 -232.706668) (xy 133.534319 -232.750705) (xy 133.498067 -232.789776) (xy 133.456396 -232.823007)
			(xy 133.410238 -232.849656) (xy 133.360624 -232.869128) (xy 133.308662 -232.880988) (xy 133.255512 -232.884972)
			(xy 133.202362 -232.880988) (xy 133.1504 -232.869128) (xy 133.100786 -232.849656) (xy 133.054628 -232.823007)
			(xy 133.012957 -232.789776) (xy 132.976705 -232.750705) (xy 132.946681 -232.706668) (xy 132.923555 -232.658647)
			(xy 132.907845 -232.607717) (xy 132.899902 -232.555013) (xy 132.671576 -232.555013) (xy 132.663633 -232.607717)
			(xy 132.647923 -232.658647) (xy 132.624797 -232.706668) (xy 132.594773 -232.750705) (xy 132.558521 -232.789776)
			(xy 132.51685 -232.823007) (xy 132.470692 -232.849656) (xy 132.421078 -232.869128) (xy 132.369116 -232.880988)
			(xy 132.315966 -232.884972) (xy 132.262816 -232.880988) (xy 132.210854 -232.869128) (xy 132.16124 -232.849656)
			(xy 132.115082 -232.823007) (xy 132.073411 -232.789776) (xy 132.037159 -232.750705) (xy 132.007135 -232.706668)
			(xy 131.984009 -232.658647) (xy 131.968299 -232.607717) (xy 131.960356 -232.555013) (xy 131.731776 -232.555013)
			(xy 131.723833 -232.607717) (xy 131.708123 -232.658647) (xy 131.684997 -232.706668) (xy 131.654973 -232.750705)
			(xy 131.618721 -232.789776) (xy 131.57705 -232.823007) (xy 131.530892 -232.849656) (xy 131.481278 -232.869128)
			(xy 131.429316 -232.880988) (xy 131.376166 -232.884972) (xy 131.323016 -232.880988) (xy 131.271054 -232.869128)
			(xy 131.22144 -232.849656) (xy 131.175282 -232.823007) (xy 131.133611 -232.789776) (xy 131.097359 -232.750705)
			(xy 131.067335 -232.706668) (xy 131.044209 -232.658647) (xy 131.028499 -232.607717) (xy 131.020556 -232.555013)
			(xy 130.791976 -232.555013) (xy 130.784033 -232.607717) (xy 130.768323 -232.658647) (xy 130.745197 -232.706668)
			(xy 130.715173 -232.750705) (xy 130.678921 -232.789776) (xy 130.63725 -232.823007) (xy 130.591092 -232.849656)
			(xy 130.541478 -232.869128) (xy 130.489516 -232.880988) (xy 130.436366 -232.884972) (xy 130.383216 -232.880988)
			(xy 130.331254 -232.869128) (xy 130.28164 -232.849656) (xy 130.235482 -232.823007) (xy 130.193811 -232.789776)
			(xy 130.157559 -232.750705) (xy 130.127535 -232.706668) (xy 130.104409 -232.658647) (xy 130.088699 -232.607717)
			(xy 130.080756 -232.555013) (xy 129.852176 -232.555013) (xy 129.844233 -232.607717) (xy 129.828523 -232.658647)
			(xy 129.805397 -232.706668) (xy 129.775373 -232.750705) (xy 129.739121 -232.789776) (xy 129.69745 -232.823007)
			(xy 129.651292 -232.849656) (xy 129.601678 -232.869128) (xy 129.549716 -232.880988) (xy 129.496566 -232.884972)
			(xy 129.443416 -232.880988) (xy 129.391454 -232.869128) (xy 129.34184 -232.849656) (xy 129.295682 -232.823007)
			(xy 129.254011 -232.789776) (xy 129.217759 -232.750705) (xy 129.187735 -232.706668) (xy 129.164609 -232.658647)
			(xy 129.148899 -232.607717) (xy 129.140956 -232.555013) (xy 128.912376 -232.555013) (xy 128.904433 -232.607717)
			(xy 128.888723 -232.658647) (xy 128.865597 -232.706668) (xy 128.835573 -232.750705) (xy 128.799321 -232.789776)
			(xy 128.75765 -232.823007) (xy 128.711492 -232.849656) (xy 128.661878 -232.869128) (xy 128.609916 -232.880988)
			(xy 128.556766 -232.884972) (xy 128.503616 -232.880988) (xy 128.451654 -232.869128) (xy 128.40204 -232.849656)
			(xy 128.355882 -232.823007) (xy 128.314211 -232.789776) (xy 128.277959 -232.750705) (xy 128.247935 -232.706668)
			(xy 128.224809 -232.658647) (xy 128.209099 -232.607717) (xy 128.201156 -232.555013) (xy 127.972576 -232.555013)
			(xy 127.964633 -232.607717) (xy 127.948923 -232.658647) (xy 127.925797 -232.706668) (xy 127.895773 -232.750705)
			(xy 127.859521 -232.789776) (xy 127.81785 -232.823007) (xy 127.771692 -232.849656) (xy 127.722078 -232.869128)
			(xy 127.670116 -232.880988) (xy 127.616966 -232.884972) (xy 127.563816 -232.880988) (xy 127.511854 -232.869128)
			(xy 127.46224 -232.849656) (xy 127.416082 -232.823007) (xy 127.374411 -232.789776) (xy 127.338159 -232.750705)
			(xy 127.308135 -232.706668) (xy 127.285009 -232.658647) (xy 127.269299 -232.607717) (xy 127.261356 -232.555013)
			(xy 127.032522 -232.555013) (xy 127.024579 -232.607717) (xy 127.008869 -232.658647) (xy 126.985743 -232.706668)
			(xy 126.955719 -232.750705) (xy 126.919467 -232.789776) (xy 126.877796 -232.823007) (xy 126.831638 -232.849656)
			(xy 126.782024 -232.869128) (xy 126.730062 -232.880988) (xy 126.676912 -232.884972) (xy 126.623762 -232.880988)
			(xy 126.5718 -232.869128) (xy 126.522186 -232.849656) (xy 126.476028 -232.823007) (xy 126.434357 -232.789776)
			(xy 126.398105 -232.750705) (xy 126.368081 -232.706668) (xy 126.344955 -232.658647) (xy 126.329245 -232.607717)
			(xy 126.321302 -232.555013) (xy 126.092976 -232.555013) (xy 126.085033 -232.607717) (xy 126.069323 -232.658647)
			(xy 126.046197 -232.706668) (xy 126.016173 -232.750705) (xy 125.979921 -232.789776) (xy 125.93825 -232.823007)
			(xy 125.892092 -232.849656) (xy 125.842478 -232.869128) (xy 125.790516 -232.880988) (xy 125.737366 -232.884972)
			(xy 125.684216 -232.880988) (xy 125.632254 -232.869128) (xy 125.58264 -232.849656) (xy 125.536482 -232.823007)
			(xy 125.494811 -232.789776) (xy 125.458559 -232.750705) (xy 125.428535 -232.706668) (xy 125.405409 -232.658647)
			(xy 125.389699 -232.607717) (xy 125.381756 -232.555013) (xy 125.153176 -232.555013) (xy 125.145233 -232.607717)
			(xy 125.129523 -232.658647) (xy 125.106397 -232.706668) (xy 125.076373 -232.750705) (xy 125.040121 -232.789776)
			(xy 124.99845 -232.823007) (xy 124.952292 -232.849656) (xy 124.902678 -232.869128) (xy 124.850716 -232.880988)
			(xy 124.797566 -232.884972) (xy 124.744416 -232.880988) (xy 124.692454 -232.869128) (xy 124.64284 -232.849656)
			(xy 124.596682 -232.823007) (xy 124.555011 -232.789776) (xy 124.518759 -232.750705) (xy 124.488735 -232.706668)
			(xy 124.465609 -232.658647) (xy 124.449899 -232.607717) (xy 124.441956 -232.555013) (xy 124.213376 -232.555013)
			(xy 124.205433 -232.607717) (xy 124.189723 -232.658647) (xy 124.166597 -232.706668) (xy 124.136573 -232.750705)
			(xy 124.100321 -232.789776) (xy 124.05865 -232.823007) (xy 124.012492 -232.849656) (xy 123.962878 -232.869128)
			(xy 123.910916 -232.880988) (xy 123.857766 -232.884972) (xy 123.804616 -232.880988) (xy 123.752654 -232.869128)
			(xy 123.70304 -232.849656) (xy 123.656882 -232.823007) (xy 123.615211 -232.789776) (xy 123.578959 -232.750705)
			(xy 123.548935 -232.706668) (xy 123.525809 -232.658647) (xy 123.510099 -232.607717) (xy 123.502156 -232.555013)
			(xy 123.273576 -232.555013) (xy 123.265633 -232.607717) (xy 123.249923 -232.658647) (xy 123.226797 -232.706668)
			(xy 123.196773 -232.750705) (xy 123.160521 -232.789776) (xy 123.11885 -232.823007) (xy 123.072692 -232.849656)
			(xy 123.023078 -232.869128) (xy 122.971116 -232.880988) (xy 122.917966 -232.884972) (xy 122.864816 -232.880988)
			(xy 122.812854 -232.869128) (xy 122.76324 -232.849656) (xy 122.717082 -232.823007) (xy 122.675411 -232.789776)
			(xy 122.639159 -232.750705) (xy 122.609135 -232.706668) (xy 122.586009 -232.658647) (xy 122.570299 -232.607717)
			(xy 122.562356 -232.555013) (xy 122.333776 -232.555013) (xy 122.325833 -232.607717) (xy 122.310123 -232.658647)
			(xy 122.286997 -232.706668) (xy 122.256973 -232.750705) (xy 122.220721 -232.789776) (xy 122.17905 -232.823007)
			(xy 122.132892 -232.849656) (xy 122.083278 -232.869128) (xy 122.031316 -232.880988) (xy 121.978166 -232.884972)
			(xy 121.925016 -232.880988) (xy 121.873054 -232.869128) (xy 121.82344 -232.849656) (xy 121.777282 -232.823007)
			(xy 121.735611 -232.789776) (xy 121.699359 -232.750705) (xy 121.669335 -232.706668) (xy 121.646209 -232.658647)
			(xy 121.630499 -232.607717) (xy 121.622556 -232.555013) (xy 121.393976 -232.555013) (xy 121.386033 -232.607717)
			(xy 121.370323 -232.658647) (xy 121.347197 -232.706668) (xy 121.317173 -232.750705) (xy 121.280921 -232.789776)
			(xy 121.23925 -232.823007) (xy 121.193092 -232.849656) (xy 121.143478 -232.869128) (xy 121.091516 -232.880988)
			(xy 121.038366 -232.884972) (xy 120.985216 -232.880988) (xy 120.933254 -232.869128) (xy 120.88364 -232.849656)
			(xy 120.837482 -232.823007) (xy 120.795811 -232.789776) (xy 120.759559 -232.750705) (xy 120.729535 -232.706668)
			(xy 120.706409 -232.658647) (xy 120.690699 -232.607717) (xy 120.682756 -232.555013) (xy 120.453922 -232.555013)
			(xy 120.445979 -232.607717) (xy 120.430269 -232.658647) (xy 120.407143 -232.706668) (xy 120.377119 -232.750705)
			(xy 120.340867 -232.789776) (xy 120.299196 -232.823007) (xy 120.253038 -232.849656) (xy 120.203424 -232.869128)
			(xy 120.151462 -232.880988) (xy 120.098312 -232.884972) (xy 120.045162 -232.880988) (xy 119.9932 -232.869128)
			(xy 119.943586 -232.849656) (xy 119.897428 -232.823007) (xy 119.855757 -232.789776) (xy 119.819505 -232.750705)
			(xy 119.789481 -232.706668) (xy 119.766355 -232.658647) (xy 119.750645 -232.607717) (xy 119.742702 -232.555013)
			(xy 119.514376 -232.555013) (xy 119.506433 -232.607717) (xy 119.490723 -232.658647) (xy 119.467597 -232.706668)
			(xy 119.437573 -232.750705) (xy 119.401321 -232.789776) (xy 119.35965 -232.823007) (xy 119.313492 -232.849656)
			(xy 119.263878 -232.869128) (xy 119.211916 -232.880988) (xy 119.158766 -232.884972) (xy 119.105616 -232.880988)
			(xy 119.053654 -232.869128) (xy 119.00404 -232.849656) (xy 118.957882 -232.823007) (xy 118.916211 -232.789776)
			(xy 118.879959 -232.750705) (xy 118.849935 -232.706668) (xy 118.826809 -232.658647) (xy 118.811099 -232.607717)
			(xy 118.803156 -232.555013) (xy 118.574576 -232.555013) (xy 118.566633 -232.607717) (xy 118.550923 -232.658647)
			(xy 118.527797 -232.706668) (xy 118.497773 -232.750705) (xy 118.461521 -232.789776) (xy 118.41985 -232.823007)
			(xy 118.373692 -232.849656) (xy 118.324078 -232.869128) (xy 118.272116 -232.880988) (xy 118.218966 -232.884972)
			(xy 118.165816 -232.880988) (xy 118.113854 -232.869128) (xy 118.06424 -232.849656) (xy 118.018082 -232.823007)
			(xy 117.976411 -232.789776) (xy 117.940159 -232.750705) (xy 117.910135 -232.706668) (xy 117.887009 -232.658647)
			(xy 117.871299 -232.607717) (xy 117.863356 -232.555013) (xy 117.634776 -232.555013) (xy 117.626833 -232.607717)
			(xy 117.611123 -232.658647) (xy 117.587997 -232.706668) (xy 117.557973 -232.750705) (xy 117.521721 -232.789776)
			(xy 117.48005 -232.823007) (xy 117.433892 -232.849656) (xy 117.384278 -232.869128) (xy 117.332316 -232.880988)
			(xy 117.279166 -232.884972) (xy 117.226016 -232.880988) (xy 117.174054 -232.869128) (xy 117.12444 -232.849656)
			(xy 117.078282 -232.823007) (xy 117.036611 -232.789776) (xy 117.000359 -232.750705) (xy 116.970335 -232.706668)
			(xy 116.947209 -232.658647) (xy 116.931499 -232.607717) (xy 116.923556 -232.555013) (xy 116.694976 -232.555013)
			(xy 116.687033 -232.607717) (xy 116.671323 -232.658647) (xy 116.648197 -232.706668) (xy 116.618173 -232.750705)
			(xy 116.581921 -232.789776) (xy 116.54025 -232.823007) (xy 116.494092 -232.849656) (xy 116.444478 -232.869128)
			(xy 116.392516 -232.880988) (xy 116.339366 -232.884972) (xy 116.286216 -232.880988) (xy 116.234254 -232.869128)
			(xy 116.18464 -232.849656) (xy 116.138482 -232.823007) (xy 116.096811 -232.789776) (xy 116.060559 -232.750705)
			(xy 116.030535 -232.706668) (xy 116.007409 -232.658647) (xy 115.991699 -232.607717) (xy 115.983756 -232.555013)
			(xy 115.755176 -232.555013) (xy 115.747233 -232.607717) (xy 115.731523 -232.658647) (xy 115.708397 -232.706668)
			(xy 115.678373 -232.750705) (xy 115.642121 -232.789776) (xy 115.60045 -232.823007) (xy 115.554292 -232.849656)
			(xy 115.504678 -232.869128) (xy 115.452716 -232.880988) (xy 115.399566 -232.884972) (xy 115.346416 -232.880988)
			(xy 115.294454 -232.869128) (xy 115.24484 -232.849656) (xy 115.198682 -232.823007) (xy 115.157011 -232.789776)
			(xy 115.120759 -232.750705) (xy 115.090735 -232.706668) (xy 115.067609 -232.658647) (xy 115.051899 -232.607717)
			(xy 115.043956 -232.555013) (xy 114.815376 -232.555013) (xy 114.807433 -232.607717) (xy 114.791723 -232.658647)
			(xy 114.768597 -232.706668) (xy 114.738573 -232.750705) (xy 114.702321 -232.789776) (xy 114.66065 -232.823007)
			(xy 114.614492 -232.849656) (xy 114.564878 -232.869128) (xy 114.512916 -232.880988) (xy 114.459766 -232.884972)
			(xy 114.406616 -232.880988) (xy 114.354654 -232.869128) (xy 114.30504 -232.849656) (xy 114.258882 -232.823007)
			(xy 114.217211 -232.789776) (xy 114.180959 -232.750705) (xy 114.150935 -232.706668) (xy 114.127809 -232.658647)
			(xy 114.112099 -232.607717) (xy 114.104156 -232.555013) (xy 113.875576 -232.555013) (xy 113.867633 -232.607717)
			(xy 113.851923 -232.658647) (xy 113.828797 -232.706668) (xy 113.798773 -232.750705) (xy 113.762521 -232.789776)
			(xy 113.72085 -232.823007) (xy 113.674692 -232.849656) (xy 113.625078 -232.869128) (xy 113.573116 -232.880988)
			(xy 113.519966 -232.884972) (xy 113.466816 -232.880988) (xy 113.414854 -232.869128) (xy 113.36524 -232.849656)
			(xy 113.319082 -232.823007) (xy 113.277411 -232.789776) (xy 113.241159 -232.750705) (xy 113.211135 -232.706668)
			(xy 113.188009 -232.658647) (xy 113.172299 -232.607717) (xy 113.164356 -232.555013) (xy 112.935776 -232.555013)
			(xy 112.927833 -232.607717) (xy 112.912123 -232.658647) (xy 112.888997 -232.706668) (xy 112.858973 -232.750705)
			(xy 112.822721 -232.789776) (xy 112.78105 -232.823007) (xy 112.734892 -232.849656) (xy 112.685278 -232.869128)
			(xy 112.633316 -232.880988) (xy 112.580166 -232.884972) (xy 112.527016 -232.880988) (xy 112.475054 -232.869128)
			(xy 112.42544 -232.849656) (xy 112.379282 -232.823007) (xy 112.337611 -232.789776) (xy 112.301359 -232.750705)
			(xy 112.271335 -232.706668) (xy 112.248209 -232.658647) (xy 112.232499 -232.607717) (xy 112.224556 -232.555013)
			(xy 111.995976 -232.555013) (xy 111.988033 -232.607717) (xy 111.972323 -232.658647) (xy 111.949197 -232.706668)
			(xy 111.919173 -232.750705) (xy 111.882921 -232.789776) (xy 111.84125 -232.823007) (xy 111.795092 -232.849656)
			(xy 111.745478 -232.869128) (xy 111.693516 -232.880988) (xy 111.640366 -232.884972) (xy 111.587216 -232.880988)
			(xy 111.535254 -232.869128) (xy 111.48564 -232.849656) (xy 111.439482 -232.823007) (xy 111.397811 -232.789776)
			(xy 111.361559 -232.750705) (xy 111.331535 -232.706668) (xy 111.308409 -232.658647) (xy 111.292699 -232.607717)
			(xy 111.284756 -232.555013) (xy 111.056176 -232.555013) (xy 111.048233 -232.607717) (xy 111.032523 -232.658647)
			(xy 111.009397 -232.706668) (xy 110.979373 -232.750705) (xy 110.943121 -232.789776) (xy 110.90145 -232.823007)
			(xy 110.855292 -232.849656) (xy 110.805678 -232.869128) (xy 110.753716 -232.880988) (xy 110.700566 -232.884972)
			(xy 110.647416 -232.880988) (xy 110.595454 -232.869128) (xy 110.54584 -232.849656) (xy 110.499682 -232.823007)
			(xy 110.458011 -232.789776) (xy 110.421759 -232.750705) (xy 110.391735 -232.706668) (xy 110.368609 -232.658647)
			(xy 110.352899 -232.607717) (xy 110.344956 -232.555013) (xy 110.116376 -232.555013) (xy 110.108433 -232.607717)
			(xy 110.092723 -232.658647) (xy 110.069597 -232.706668) (xy 110.039573 -232.750705) (xy 110.003321 -232.789776)
			(xy 109.96165 -232.823007) (xy 109.915492 -232.849656) (xy 109.865878 -232.869128) (xy 109.813916 -232.880988)
			(xy 109.760766 -232.884972) (xy 109.707616 -232.880988) (xy 109.655654 -232.869128) (xy 109.60604 -232.849656)
			(xy 109.559882 -232.823007) (xy 109.518211 -232.789776) (xy 109.481959 -232.750705) (xy 109.451935 -232.706668)
			(xy 109.428809 -232.658647) (xy 109.413099 -232.607717) (xy 109.405156 -232.555013) (xy 109.176576 -232.555013)
			(xy 109.168633 -232.607717) (xy 109.152923 -232.658647) (xy 109.129797 -232.706668) (xy 109.099773 -232.750705)
			(xy 109.063521 -232.789776) (xy 109.02185 -232.823007) (xy 108.975692 -232.849656) (xy 108.926078 -232.869128)
			(xy 108.874116 -232.880988) (xy 108.820966 -232.884972) (xy 108.767816 -232.880988) (xy 108.715854 -232.869128)
			(xy 108.66624 -232.849656) (xy 108.620082 -232.823007) (xy 108.578411 -232.789776) (xy 108.542159 -232.750705)
			(xy 108.512135 -232.706668) (xy 108.489009 -232.658647) (xy 108.473299 -232.607717) (xy 108.465356 -232.555013)
			(xy 108.236776 -232.555013) (xy 108.228833 -232.607717) (xy 108.213123 -232.658647) (xy 108.189997 -232.706668)
			(xy 108.159973 -232.750705) (xy 108.123721 -232.789776) (xy 108.08205 -232.823007) (xy 108.035892 -232.849656)
			(xy 107.986278 -232.869128) (xy 107.934316 -232.880988) (xy 107.881166 -232.884972) (xy 107.828016 -232.880988)
			(xy 107.776054 -232.869128) (xy 107.72644 -232.849656) (xy 107.680282 -232.823007) (xy 107.638611 -232.789776)
			(xy 107.602359 -232.750705) (xy 107.572335 -232.706668) (xy 107.549209 -232.658647) (xy 107.533499 -232.607717)
			(xy 107.525556 -232.555013) (xy 107.296976 -232.555013) (xy 107.289033 -232.607717) (xy 107.273323 -232.658647)
			(xy 107.250197 -232.706668) (xy 107.220173 -232.750705) (xy 107.183921 -232.789776) (xy 107.14225 -232.823007)
			(xy 107.096092 -232.849656) (xy 107.046478 -232.869128) (xy 106.994516 -232.880988) (xy 106.941366 -232.884972)
			(xy 106.888216 -232.880988) (xy 106.836254 -232.869128) (xy 106.78664 -232.849656) (xy 106.740482 -232.823007)
			(xy 106.698811 -232.789776) (xy 106.662559 -232.750705) (xy 106.632535 -232.706668) (xy 106.609409 -232.658647)
			(xy 106.593699 -232.607717) (xy 106.585756 -232.555013) (xy 106.357176 -232.555013) (xy 106.349233 -232.607717)
			(xy 106.333523 -232.658647) (xy 106.310397 -232.706668) (xy 106.280373 -232.750705) (xy 106.244121 -232.789776)
			(xy 106.20245 -232.823007) (xy 106.156292 -232.849656) (xy 106.106678 -232.869128) (xy 106.054716 -232.880988)
			(xy 106.001566 -232.884972) (xy 105.948416 -232.880988) (xy 105.896454 -232.869128) (xy 105.84684 -232.849656)
			(xy 105.800682 -232.823007) (xy 105.759011 -232.789776) (xy 105.722759 -232.750705) (xy 105.692735 -232.706668)
			(xy 105.669609 -232.658647) (xy 105.653899 -232.607717) (xy 105.645956 -232.555013) (xy 105.417376 -232.555013)
			(xy 105.409433 -232.607717) (xy 105.393723 -232.658647) (xy 105.370597 -232.706668) (xy 105.340573 -232.750705)
			(xy 105.304321 -232.789776) (xy 105.26265 -232.823007) (xy 105.216492 -232.849656) (xy 105.166878 -232.869128)
			(xy 105.114916 -232.880988) (xy 105.061766 -232.884972) (xy 105.008616 -232.880988) (xy 104.956654 -232.869128)
			(xy 104.90704 -232.849656) (xy 104.860882 -232.823007) (xy 104.819211 -232.789776) (xy 104.782959 -232.750705)
			(xy 104.752935 -232.706668) (xy 104.729809 -232.658647) (xy 104.714099 -232.607717) (xy 104.706156 -232.555013)
			(xy 104.477576 -232.555013) (xy 104.469633 -232.607717) (xy 104.453923 -232.658647) (xy 104.430797 -232.706668)
			(xy 104.400773 -232.750705) (xy 104.364521 -232.789776) (xy 104.32285 -232.823007) (xy 104.276692 -232.849656)
			(xy 104.227078 -232.869128) (xy 104.175116 -232.880988) (xy 104.121966 -232.884972) (xy 104.068816 -232.880988)
			(xy 104.016854 -232.869128) (xy 103.96724 -232.849656) (xy 103.921082 -232.823007) (xy 103.879411 -232.789776)
			(xy 103.843159 -232.750705) (xy 103.813135 -232.706668) (xy 103.790009 -232.658647) (xy 103.774299 -232.607717)
			(xy 103.766356 -232.555013) (xy 103.537776 -232.555013) (xy 103.529833 -232.607717) (xy 103.514123 -232.658647)
			(xy 103.490997 -232.706668) (xy 103.460973 -232.750705) (xy 103.424721 -232.789776) (xy 103.38305 -232.823007)
			(xy 103.336892 -232.849656) (xy 103.287278 -232.869128) (xy 103.235316 -232.880988) (xy 103.182166 -232.884972)
			(xy 103.129016 -232.880988) (xy 103.077054 -232.869128) (xy 103.02744 -232.849656) (xy 102.981282 -232.823007)
			(xy 102.939611 -232.789776) (xy 102.903359 -232.750705) (xy 102.873335 -232.706668) (xy 102.850209 -232.658647)
			(xy 102.834499 -232.607717) (xy 102.826556 -232.555013) (xy 102.597976 -232.555013) (xy 102.590033 -232.607717)
			(xy 102.574323 -232.658647) (xy 102.551197 -232.706668) (xy 102.521173 -232.750705) (xy 102.484921 -232.789776)
			(xy 102.44325 -232.823007) (xy 102.397092 -232.849656) (xy 102.347478 -232.869128) (xy 102.295516 -232.880988)
			(xy 102.242366 -232.884972) (xy 102.189216 -232.880988) (xy 102.137254 -232.869128) (xy 102.08764 -232.849656)
			(xy 102.041482 -232.823007) (xy 101.999811 -232.789776) (xy 101.963559 -232.750705) (xy 101.933535 -232.706668)
			(xy 101.910409 -232.658647) (xy 101.894699 -232.607717) (xy 101.886756 -232.555013) (xy 100.718376 -232.555013)
			(xy 100.710433 -232.607717) (xy 100.694723 -232.658647) (xy 100.671597 -232.706668) (xy 100.641573 -232.750705)
			(xy 100.605321 -232.789776) (xy 100.56365 -232.823007) (xy 100.517492 -232.849656) (xy 100.467878 -232.869128)
			(xy 100.415916 -232.880988) (xy 100.362766 -232.884972) (xy 100.309616 -232.880988) (xy 100.257654 -232.869128)
			(xy 100.20804 -232.849656) (xy 100.161882 -232.823007) (xy 100.120211 -232.789776) (xy 100.083959 -232.750705)
			(xy 100.053935 -232.706668) (xy 100.030809 -232.658647) (xy 100.015099 -232.607717) (xy 100.007156 -232.555013)
			(xy 99.778576 -232.555013) (xy 99.770633 -232.607717) (xy 99.754923 -232.658647) (xy 99.731797 -232.706668)
			(xy 99.701773 -232.750705) (xy 99.665521 -232.789776) (xy 99.62385 -232.823007) (xy 99.577692 -232.849656)
			(xy 99.528078 -232.869128) (xy 99.476116 -232.880988) (xy 99.422966 -232.884972) (xy 99.369816 -232.880988)
			(xy 99.317854 -232.869128) (xy 99.26824 -232.849656) (xy 99.222082 -232.823007) (xy 99.180411 -232.789776)
			(xy 99.144159 -232.750705) (xy 99.114135 -232.706668) (xy 99.091009 -232.658647) (xy 99.075299 -232.607717)
			(xy 99.067356 -232.555013) (xy 98.838522 -232.555013) (xy 98.830579 -232.607717) (xy 98.814869 -232.658647)
			(xy 98.791743 -232.706668) (xy 98.761719 -232.750705) (xy 98.725467 -232.789776) (xy 98.683796 -232.823007)
			(xy 98.637638 -232.849656) (xy 98.588024 -232.869128) (xy 98.536062 -232.880988) (xy 98.482912 -232.884972)
			(xy 98.429762 -232.880988) (xy 98.3778 -232.869128) (xy 98.328186 -232.849656) (xy 98.282028 -232.823007)
			(xy 98.240357 -232.789776) (xy 98.204105 -232.750705) (xy 98.174081 -232.706668) (xy 98.150955 -232.658647)
			(xy 98.135245 -232.607717) (xy 98.127302 -232.555013) (xy 97.898976 -232.555013) (xy 97.891033 -232.607717)
			(xy 97.875323 -232.658647) (xy 97.852197 -232.706668) (xy 97.822173 -232.750705) (xy 97.785921 -232.789776)
			(xy 97.74425 -232.823007) (xy 97.698092 -232.849656) (xy 97.648478 -232.869128) (xy 97.596516 -232.880988)
			(xy 97.543366 -232.884972) (xy 97.490216 -232.880988) (xy 97.438254 -232.869128) (xy 97.38864 -232.849656)
			(xy 97.342482 -232.823007) (xy 97.300811 -232.789776) (xy 97.264559 -232.750705) (xy 97.234535 -232.706668)
			(xy 97.211409 -232.658647) (xy 97.195699 -232.607717) (xy 97.187756 -232.555013) (xy 96.959176 -232.555013)
			(xy 96.951233 -232.607717) (xy 96.935523 -232.658647) (xy 96.912397 -232.706668) (xy 96.882373 -232.750705)
			(xy 96.846121 -232.789776) (xy 96.80445 -232.823007) (xy 96.758292 -232.849656) (xy 96.708678 -232.869128)
			(xy 96.656716 -232.880988) (xy 96.603566 -232.884972) (xy 96.550416 -232.880988) (xy 96.498454 -232.869128)
			(xy 96.44884 -232.849656) (xy 96.402682 -232.823007) (xy 96.361011 -232.789776) (xy 96.324759 -232.750705)
			(xy 96.294735 -232.706668) (xy 96.271609 -232.658647) (xy 96.255899 -232.607717) (xy 96.247956 -232.555013)
			(xy 96.019376 -232.555013) (xy 96.011433 -232.607717) (xy 95.995723 -232.658647) (xy 95.972597 -232.706668)
			(xy 95.942573 -232.750705) (xy 95.906321 -232.789776) (xy 95.86465 -232.823007) (xy 95.818492 -232.849656)
			(xy 95.768878 -232.869128) (xy 95.716916 -232.880988) (xy 95.663766 -232.884972) (xy 95.610616 -232.880988)
			(xy 95.558654 -232.869128) (xy 95.50904 -232.849656) (xy 95.462882 -232.823007) (xy 95.421211 -232.789776)
			(xy 95.384959 -232.750705) (xy 95.354935 -232.706668) (xy 95.331809 -232.658647) (xy 95.316099 -232.607717)
			(xy 95.308156 -232.555013) (xy 95.079576 -232.555013) (xy 95.071633 -232.607717) (xy 95.055923 -232.658647)
			(xy 95.032797 -232.706668) (xy 95.002773 -232.750705) (xy 94.966521 -232.789776) (xy 94.92485 -232.823007)
			(xy 94.878692 -232.849656) (xy 94.829078 -232.869128) (xy 94.777116 -232.880988) (xy 94.723966 -232.884972)
			(xy 94.670816 -232.880988) (xy 94.618854 -232.869128) (xy 94.56924 -232.849656) (xy 94.523082 -232.823007)
			(xy 94.481411 -232.789776) (xy 94.445159 -232.750705) (xy 94.415135 -232.706668) (xy 94.392009 -232.658647)
			(xy 94.376299 -232.607717) (xy 94.368356 -232.555013) (xy 94.139776 -232.555013) (xy 94.131833 -232.607717)
			(xy 94.116123 -232.658647) (xy 94.092997 -232.706668) (xy 94.062973 -232.750705) (xy 94.026721 -232.789776)
			(xy 93.98505 -232.823007) (xy 93.938892 -232.849656) (xy 93.889278 -232.869128) (xy 93.837316 -232.880988)
			(xy 93.784166 -232.884972) (xy 93.731016 -232.880988) (xy 93.679054 -232.869128) (xy 93.62944 -232.849656)
			(xy 93.583282 -232.823007) (xy 93.541611 -232.789776) (xy 93.505359 -232.750705) (xy 93.475335 -232.706668)
			(xy 93.452209 -232.658647) (xy 93.436499 -232.607717) (xy 93.428556 -232.555013) (xy 93.199976 -232.555013)
			(xy 93.192033 -232.607717) (xy 93.176323 -232.658647) (xy 93.153197 -232.706668) (xy 93.123173 -232.750705)
			(xy 93.086921 -232.789776) (xy 93.04525 -232.823007) (xy 92.999092 -232.849656) (xy 92.949478 -232.869128)
			(xy 92.897516 -232.880988) (xy 92.844366 -232.884972) (xy 92.791216 -232.880988) (xy 92.739254 -232.869128)
			(xy 92.68964 -232.849656) (xy 92.643482 -232.823007) (xy 92.601811 -232.789776) (xy 92.565559 -232.750705)
			(xy 92.535535 -232.706668) (xy 92.512409 -232.658647) (xy 92.496699 -232.607717) (xy 92.488756 -232.555013)
			(xy 92.259922 -232.555013) (xy 92.251979 -232.607717) (xy 92.236269 -232.658647) (xy 92.213143 -232.706668)
			(xy 92.183119 -232.750705) (xy 92.146867 -232.789776) (xy 92.105196 -232.823007) (xy 92.059038 -232.849656)
			(xy 92.009424 -232.869128) (xy 91.957462 -232.880988) (xy 91.904312 -232.884972) (xy 91.851162 -232.880988)
			(xy 91.7992 -232.869128) (xy 91.749586 -232.849656) (xy 91.703428 -232.823007) (xy 91.661757 -232.789776)
			(xy 91.625505 -232.750705) (xy 91.595481 -232.706668) (xy 91.572355 -232.658647) (xy 91.556645 -232.607717)
			(xy 91.548702 -232.555013) (xy 91.320376 -232.555013) (xy 91.312433 -232.607717) (xy 91.296723 -232.658647)
			(xy 91.273597 -232.706668) (xy 91.243573 -232.750705) (xy 91.207321 -232.789776) (xy 91.16565 -232.823007)
			(xy 91.119492 -232.849656) (xy 91.069878 -232.869128) (xy 91.017916 -232.880988) (xy 90.964766 -232.884972)
			(xy 90.911616 -232.880988) (xy 90.859654 -232.869128) (xy 90.81004 -232.849656) (xy 90.763882 -232.823007)
			(xy 90.722211 -232.789776) (xy 90.685959 -232.750705) (xy 90.655935 -232.706668) (xy 90.632809 -232.658647)
			(xy 90.617099 -232.607717) (xy 90.609156 -232.555013) (xy 90.380576 -232.555013) (xy 90.372633 -232.607717)
			(xy 90.356923 -232.658647) (xy 90.333797 -232.706668) (xy 90.303773 -232.750705) (xy 90.267521 -232.789776)
			(xy 90.22585 -232.823007) (xy 90.179692 -232.849656) (xy 90.130078 -232.869128) (xy 90.078116 -232.880988)
			(xy 90.024966 -232.884972) (xy 89.971816 -232.880988) (xy 89.919854 -232.869128) (xy 89.87024 -232.849656)
			(xy 89.824082 -232.823007) (xy 89.782411 -232.789776) (xy 89.746159 -232.750705) (xy 89.716135 -232.706668)
			(xy 89.693009 -232.658647) (xy 89.677299 -232.607717) (xy 89.669356 -232.555013) (xy 89.439874 -232.555013)
			(xy 89.437884 -232.581562) (xy 89.42602 -232.633536) (xy 89.406543 -232.683161) (xy 89.379886 -232.729329)
			(xy 89.346645 -232.771008) (xy 89.307564 -232.807266) (xy 89.263514 -232.837295) (xy 89.215481 -232.860422)
			(xy 89.164538 -232.876132) (xy 89.111821 -232.884073) (xy 89.085166 -232.884472) (xy 89.060205 -232.884051)
			(xy 89.010772 -232.877081) (xy 88.962795 -232.863282) (xy 88.917212 -232.842924) (xy 88.874916 -232.816406)
			(xy 88.85555 -232.800652) (xy 88.844188 -232.79172) (xy 88.817781 -232.780011) (xy 88.789151 -232.776164)
			(xy 88.760589 -232.780486) (xy 88.73438 -232.792633) (xy 88.71262 -232.811631) (xy 88.697049 -232.835962)
			(xy 88.688912 -232.863679) (xy 88.688418 -232.878122) (xy 88.688418 -232.99166) (xy 88.723724 -233.00309)
			(xy 88.748734 -233.011613) (xy 88.796111 -233.035001) (xy 88.839513 -233.065133) (xy 88.877987 -233.101346)
			(xy 88.910687 -233.142847) (xy 88.936897 -233.188724) (xy 88.95604 -233.237969) (xy 88.967698 -233.289503)
			(xy 88.971613 -233.342194) (xy 88.969634 -233.368829) (xy 89.199202 -233.368829) (xy 89.199202 -233.315531)
			(xy 89.207145 -233.262827) (xy 89.222855 -233.211897) (xy 89.245981 -233.163876) (xy 89.276005 -233.119839)
			(xy 89.312257 -233.080768) (xy 89.353928 -233.047537) (xy 89.400086 -233.020888) (xy 89.4497 -233.001416)
			(xy 89.501662 -232.989556) (xy 89.554812 -232.985573) (xy 89.607962 -232.989556) (xy 89.659924 -233.001416)
			(xy 89.709538 -233.020888) (xy 89.755696 -233.047537) (xy 89.797367 -233.080768) (xy 89.833619 -233.119839)
			(xy 89.863643 -233.163876) (xy 89.886769 -233.211897) (xy 89.902479 -233.262827) (xy 89.910422 -233.315531)
			(xy 89.91092 -233.34218) (xy 89.910422 -233.368829) (xy 90.139002 -233.368829) (xy 90.139002 -233.315531)
			(xy 90.146945 -233.262827) (xy 90.162655 -233.211897) (xy 90.185781 -233.163876) (xy 90.215805 -233.119839)
			(xy 90.252057 -233.080768) (xy 90.293728 -233.047537) (xy 90.339886 -233.020888) (xy 90.3895 -233.001416)
			(xy 90.441462 -232.989556) (xy 90.494612 -232.985573) (xy 90.547762 -232.989556) (xy 90.599724 -233.001416)
			(xy 90.649338 -233.020888) (xy 90.695496 -233.047537) (xy 90.737167 -233.080768) (xy 90.773419 -233.119839)
			(xy 90.803443 -233.163876) (xy 90.826569 -233.211897) (xy 90.842279 -233.262827) (xy 90.850222 -233.315531)
			(xy 90.85072 -233.34218) (xy 90.850222 -233.368829) (xy 91.079056 -233.368829) (xy 91.079056 -233.315531)
			(xy 91.086999 -233.262827) (xy 91.102709 -233.211897) (xy 91.125835 -233.163876) (xy 91.155859 -233.119839)
			(xy 91.192111 -233.080768) (xy 91.233782 -233.047537) (xy 91.27994 -233.020888) (xy 91.329554 -233.001416)
			(xy 91.381516 -232.989556) (xy 91.434666 -232.985573) (xy 91.487816 -232.989556) (xy 91.539778 -233.001416)
			(xy 91.589392 -233.020888) (xy 91.63555 -233.047537) (xy 91.677221 -233.080768) (xy 91.713473 -233.119839)
			(xy 91.743497 -233.163876) (xy 91.766623 -233.211897) (xy 91.782333 -233.262827) (xy 91.790276 -233.315531)
			(xy 91.790774 -233.34218) (xy 91.790276 -233.368829) (xy 92.018602 -233.368829) (xy 92.018602 -233.315531)
			(xy 92.026545 -233.262827) (xy 92.042255 -233.211897) (xy 92.065381 -233.163876) (xy 92.095405 -233.119839)
			(xy 92.131657 -233.080768) (xy 92.173328 -233.047537) (xy 92.219486 -233.020888) (xy 92.2691 -233.001416)
			(xy 92.321062 -232.989556) (xy 92.374212 -232.985573) (xy 92.427362 -232.989556) (xy 92.479324 -233.001416)
			(xy 92.528938 -233.020888) (xy 92.575096 -233.047537) (xy 92.616767 -233.080768) (xy 92.653019 -233.119839)
			(xy 92.683043 -233.163876) (xy 92.706169 -233.211897) (xy 92.721879 -233.262827) (xy 92.729822 -233.315531)
			(xy 92.73032 -233.34218) (xy 92.729822 -233.368829) (xy 92.958402 -233.368829) (xy 92.958402 -233.315531)
			(xy 92.966345 -233.262827) (xy 92.982055 -233.211897) (xy 93.005181 -233.163876) (xy 93.035205 -233.119839)
			(xy 93.071457 -233.080768) (xy 93.113128 -233.047537) (xy 93.159286 -233.020888) (xy 93.2089 -233.001416)
			(xy 93.260862 -232.989556) (xy 93.314012 -232.985573) (xy 93.367162 -232.989556) (xy 93.419124 -233.001416)
			(xy 93.468738 -233.020888) (xy 93.514896 -233.047537) (xy 93.556567 -233.080768) (xy 93.592819 -233.119839)
			(xy 93.622843 -233.163876) (xy 93.645969 -233.211897) (xy 93.661679 -233.262827) (xy 93.669622 -233.315531)
			(xy 93.67012 -233.34218) (xy 93.669622 -233.368829) (xy 93.898202 -233.368829) (xy 93.898202 -233.315531)
			(xy 93.906145 -233.262827) (xy 93.921855 -233.211897) (xy 93.944981 -233.163876) (xy 93.975005 -233.119839)
			(xy 94.011257 -233.080768) (xy 94.052928 -233.047537) (xy 94.099086 -233.020888) (xy 94.1487 -233.001416)
			(xy 94.200662 -232.989556) (xy 94.253812 -232.985573) (xy 94.306962 -232.989556) (xy 94.358924 -233.001416)
			(xy 94.408538 -233.020888) (xy 94.454696 -233.047537) (xy 94.496367 -233.080768) (xy 94.532619 -233.119839)
			(xy 94.562643 -233.163876) (xy 94.585769 -233.211897) (xy 94.601479 -233.262827) (xy 94.609422 -233.315531)
			(xy 94.60992 -233.34218) (xy 94.609422 -233.368829) (xy 94.838002 -233.368829) (xy 94.838002 -233.315531)
			(xy 94.845945 -233.262827) (xy 94.861655 -233.211897) (xy 94.884781 -233.163876) (xy 94.914805 -233.119839)
			(xy 94.951057 -233.080768) (xy 94.992728 -233.047537) (xy 95.038886 -233.020888) (xy 95.0885 -233.001416)
			(xy 95.140462 -232.989556) (xy 95.193612 -232.985573) (xy 95.246762 -232.989556) (xy 95.298724 -233.001416)
			(xy 95.348338 -233.020888) (xy 95.394496 -233.047537) (xy 95.436167 -233.080768) (xy 95.472419 -233.119839)
			(xy 95.502443 -233.163876) (xy 95.525569 -233.211897) (xy 95.541279 -233.262827) (xy 95.549222 -233.315531)
			(xy 95.54972 -233.34218) (xy 95.549222 -233.368829) (xy 95.777802 -233.368829) (xy 95.777802 -233.315531)
			(xy 95.785745 -233.262827) (xy 95.801455 -233.211897) (xy 95.824581 -233.163876) (xy 95.854605 -233.119839)
			(xy 95.890857 -233.080768) (xy 95.932528 -233.047537) (xy 95.978686 -233.020888) (xy 96.0283 -233.001416)
			(xy 96.080262 -232.989556) (xy 96.133412 -232.985573) (xy 96.186562 -232.989556) (xy 96.238524 -233.001416)
			(xy 96.288138 -233.020888) (xy 96.334296 -233.047537) (xy 96.375967 -233.080768) (xy 96.412219 -233.119839)
			(xy 96.442243 -233.163876) (xy 96.465369 -233.211897) (xy 96.481079 -233.262827) (xy 96.489022 -233.315531)
			(xy 96.48952 -233.34218) (xy 96.489022 -233.368829) (xy 96.717602 -233.368829) (xy 96.717602 -233.315531)
			(xy 96.725545 -233.262827) (xy 96.741255 -233.211897) (xy 96.764381 -233.163876) (xy 96.794405 -233.119839)
			(xy 96.830657 -233.080768) (xy 96.872328 -233.047537) (xy 96.918486 -233.020888) (xy 96.9681 -233.001416)
			(xy 97.020062 -232.989556) (xy 97.073212 -232.985573) (xy 97.126362 -232.989556) (xy 97.178324 -233.001416)
			(xy 97.227938 -233.020888) (xy 97.274096 -233.047537) (xy 97.315767 -233.080768) (xy 97.352019 -233.119839)
			(xy 97.382043 -233.163876) (xy 97.405169 -233.211897) (xy 97.420879 -233.262827) (xy 97.428822 -233.315531)
			(xy 97.42932 -233.34218) (xy 97.428822 -233.368829) (xy 97.657656 -233.368829) (xy 97.657656 -233.315531)
			(xy 97.665599 -233.262827) (xy 97.681309 -233.211897) (xy 97.704435 -233.163876) (xy 97.734459 -233.119839)
			(xy 97.770711 -233.080768) (xy 97.812382 -233.047537) (xy 97.85854 -233.020888) (xy 97.908154 -233.001416)
			(xy 97.960116 -232.989556) (xy 98.013266 -232.985573) (xy 98.066416 -232.989556) (xy 98.118378 -233.001416)
			(xy 98.167992 -233.020888) (xy 98.21415 -233.047537) (xy 98.255821 -233.080768) (xy 98.292073 -233.119839)
			(xy 98.322097 -233.163876) (xy 98.345223 -233.211897) (xy 98.360933 -233.262827) (xy 98.368876 -233.315531)
			(xy 98.369374 -233.34218) (xy 98.368876 -233.368829) (xy 98.597202 -233.368829) (xy 98.597202 -233.315531)
			(xy 98.605145 -233.262827) (xy 98.620855 -233.211897) (xy 98.643981 -233.163876) (xy 98.674005 -233.119839)
			(xy 98.710257 -233.080768) (xy 98.751928 -233.047537) (xy 98.798086 -233.020888) (xy 98.8477 -233.001416)
			(xy 98.899662 -232.989556) (xy 98.952812 -232.985573) (xy 99.005962 -232.989556) (xy 99.057924 -233.001416)
			(xy 99.107538 -233.020888) (xy 99.153696 -233.047537) (xy 99.195367 -233.080768) (xy 99.231619 -233.119839)
			(xy 99.261643 -233.163876) (xy 99.284769 -233.211897) (xy 99.300479 -233.262827) (xy 99.308422 -233.315531)
			(xy 99.30892 -233.34218) (xy 99.308422 -233.368829) (xy 99.537002 -233.368829) (xy 99.537002 -233.315531)
			(xy 99.544945 -233.262827) (xy 99.560655 -233.211897) (xy 99.583781 -233.163876) (xy 99.613805 -233.119839)
			(xy 99.650057 -233.080768) (xy 99.691728 -233.047537) (xy 99.737886 -233.020888) (xy 99.7875 -233.001416)
			(xy 99.839462 -232.989556) (xy 99.892612 -232.985573) (xy 99.945762 -232.989556) (xy 99.997724 -233.001416)
			(xy 100.047338 -233.020888) (xy 100.093496 -233.047537) (xy 100.135167 -233.080768) (xy 100.171419 -233.119839)
			(xy 100.201443 -233.163876) (xy 100.224569 -233.211897) (xy 100.240279 -233.262827) (xy 100.248222 -233.315531)
			(xy 100.24872 -233.34218) (xy 100.248222 -233.368829) (xy 100.476802 -233.368829) (xy 100.476802 -233.315531)
			(xy 100.484745 -233.262827) (xy 100.500455 -233.211897) (xy 100.523581 -233.163876) (xy 100.553605 -233.119839)
			(xy 100.589857 -233.080768) (xy 100.631528 -233.047537) (xy 100.677686 -233.020888) (xy 100.7273 -233.001416)
			(xy 100.779262 -232.989556) (xy 100.832412 -232.985573) (xy 100.885562 -232.989556) (xy 100.937524 -233.001416)
			(xy 100.987138 -233.020888) (xy 101.033296 -233.047537) (xy 101.074967 -233.080768) (xy 101.111219 -233.119839)
			(xy 101.141243 -233.163876) (xy 101.164369 -233.211897) (xy 101.180079 -233.262827) (xy 101.188022 -233.315531)
			(xy 101.18852 -233.34218) (xy 101.188022 -233.368829) (xy 102.356402 -233.368829) (xy 102.356402 -233.315531)
			(xy 102.364345 -233.262827) (xy 102.380055 -233.211897) (xy 102.403181 -233.163876) (xy 102.433205 -233.119839)
			(xy 102.469457 -233.080768) (xy 102.511128 -233.047537) (xy 102.557286 -233.020888) (xy 102.6069 -233.001416)
			(xy 102.658862 -232.989556) (xy 102.712012 -232.985573) (xy 102.765162 -232.989556) (xy 102.817124 -233.001416)
			(xy 102.866738 -233.020888) (xy 102.912896 -233.047537) (xy 102.954567 -233.080768) (xy 102.990819 -233.119839)
			(xy 103.020843 -233.163876) (xy 103.043969 -233.211897) (xy 103.059679 -233.262827) (xy 103.067622 -233.315531)
			(xy 103.06812 -233.34218) (xy 103.067622 -233.368829) (xy 103.296202 -233.368829) (xy 103.296202 -233.315531)
			(xy 103.304145 -233.262827) (xy 103.319855 -233.211897) (xy 103.342981 -233.163876) (xy 103.373005 -233.119839)
			(xy 103.409257 -233.080768) (xy 103.450928 -233.047537) (xy 103.497086 -233.020888) (xy 103.5467 -233.001416)
			(xy 103.598662 -232.989556) (xy 103.651812 -232.985573) (xy 103.704962 -232.989556) (xy 103.756924 -233.001416)
			(xy 103.806538 -233.020888) (xy 103.852696 -233.047537) (xy 103.894367 -233.080768) (xy 103.930619 -233.119839)
			(xy 103.960643 -233.163876) (xy 103.983769 -233.211897) (xy 103.999479 -233.262827) (xy 104.007422 -233.315531)
			(xy 104.00792 -233.34218) (xy 104.007422 -233.368829) (xy 104.236256 -233.368829) (xy 104.236256 -233.315531)
			(xy 104.244199 -233.262827) (xy 104.259909 -233.211897) (xy 104.283035 -233.163876) (xy 104.313059 -233.119839)
			(xy 104.349311 -233.080768) (xy 104.390982 -233.047537) (xy 104.43714 -233.020888) (xy 104.486754 -233.001416)
			(xy 104.538716 -232.989556) (xy 104.591866 -232.985573) (xy 104.645016 -232.989556) (xy 104.696978 -233.001416)
			(xy 104.746592 -233.020888) (xy 104.79275 -233.047537) (xy 104.834421 -233.080768) (xy 104.870673 -233.119839)
			(xy 104.900697 -233.163876) (xy 104.923823 -233.211897) (xy 104.939533 -233.262827) (xy 104.947476 -233.315531)
			(xy 104.947974 -233.34218) (xy 104.947476 -233.368829) (xy 105.176056 -233.368829) (xy 105.176056 -233.315531)
			(xy 105.183999 -233.262827) (xy 105.199709 -233.211897) (xy 105.222835 -233.163876) (xy 105.252859 -233.119839)
			(xy 105.289111 -233.080768) (xy 105.330782 -233.047537) (xy 105.37694 -233.020888) (xy 105.426554 -233.001416)
			(xy 105.478516 -232.989556) (xy 105.531666 -232.985573) (xy 105.584816 -232.989556) (xy 105.636778 -233.001416)
			(xy 105.686392 -233.020888) (xy 105.73255 -233.047537) (xy 105.774221 -233.080768) (xy 105.810473 -233.119839)
			(xy 105.840497 -233.163876) (xy 105.863623 -233.211897) (xy 105.879333 -233.262827) (xy 105.887276 -233.315531)
			(xy 105.887774 -233.34218) (xy 105.887276 -233.368829) (xy 106.115602 -233.368829) (xy 106.115602 -233.315531)
			(xy 106.123545 -233.262827) (xy 106.139255 -233.211897) (xy 106.162381 -233.163876) (xy 106.192405 -233.119839)
			(xy 106.228657 -233.080768) (xy 106.270328 -233.047537) (xy 106.316486 -233.020888) (xy 106.3661 -233.001416)
			(xy 106.418062 -232.989556) (xy 106.471212 -232.985573) (xy 106.524362 -232.989556) (xy 106.576324 -233.001416)
			(xy 106.625938 -233.020888) (xy 106.672096 -233.047537) (xy 106.713767 -233.080768) (xy 106.750019 -233.119839)
			(xy 106.780043 -233.163876) (xy 106.803169 -233.211897) (xy 106.818879 -233.262827) (xy 106.826822 -233.315531)
			(xy 106.82732 -233.34218) (xy 106.826822 -233.368829) (xy 107.055402 -233.368829) (xy 107.055402 -233.315531)
			(xy 107.063345 -233.262827) (xy 107.079055 -233.211897) (xy 107.102181 -233.163876) (xy 107.132205 -233.119839)
			(xy 107.168457 -233.080768) (xy 107.210128 -233.047537) (xy 107.256286 -233.020888) (xy 107.3059 -233.001416)
			(xy 107.357862 -232.989556) (xy 107.411012 -232.985573) (xy 107.464162 -232.989556) (xy 107.516124 -233.001416)
			(xy 107.565738 -233.020888) (xy 107.611896 -233.047537) (xy 107.653567 -233.080768) (xy 107.689819 -233.119839)
			(xy 107.719843 -233.163876) (xy 107.742969 -233.211897) (xy 107.758679 -233.262827) (xy 107.766622 -233.315531)
			(xy 107.76712 -233.34218) (xy 107.766622 -233.368829) (xy 107.995202 -233.368829) (xy 107.995202 -233.315531)
			(xy 108.003145 -233.262827) (xy 108.018855 -233.211897) (xy 108.041981 -233.163876) (xy 108.072005 -233.119839)
			(xy 108.108257 -233.080768) (xy 108.149928 -233.047537) (xy 108.196086 -233.020888) (xy 108.2457 -233.001416)
			(xy 108.297662 -232.989556) (xy 108.350812 -232.985573) (xy 108.403962 -232.989556) (xy 108.455924 -233.001416)
			(xy 108.505538 -233.020888) (xy 108.551696 -233.047537) (xy 108.593367 -233.080768) (xy 108.629619 -233.119839)
			(xy 108.659643 -233.163876) (xy 108.682769 -233.211897) (xy 108.698479 -233.262827) (xy 108.706422 -233.315531)
			(xy 108.70692 -233.34218) (xy 108.706422 -233.368829) (xy 108.935002 -233.368829) (xy 108.935002 -233.315531)
			(xy 108.942945 -233.262827) (xy 108.958655 -233.211897) (xy 108.981781 -233.163876) (xy 109.011805 -233.119839)
			(xy 109.048057 -233.080768) (xy 109.089728 -233.047537) (xy 109.135886 -233.020888) (xy 109.1855 -233.001416)
			(xy 109.237462 -232.989556) (xy 109.290612 -232.985573) (xy 109.343762 -232.989556) (xy 109.395724 -233.001416)
			(xy 109.445338 -233.020888) (xy 109.491496 -233.047537) (xy 109.533167 -233.080768) (xy 109.569419 -233.119839)
			(xy 109.599443 -233.163876) (xy 109.622569 -233.211897) (xy 109.638279 -233.262827) (xy 109.646222 -233.315531)
			(xy 109.64672 -233.34218) (xy 109.646222 -233.368829) (xy 109.875056 -233.368829) (xy 109.875056 -233.315531)
			(xy 109.882999 -233.262827) (xy 109.898709 -233.211897) (xy 109.921835 -233.163876) (xy 109.951859 -233.119839)
			(xy 109.988111 -233.080768) (xy 110.029782 -233.047537) (xy 110.07594 -233.020888) (xy 110.125554 -233.001416)
			(xy 110.177516 -232.989556) (xy 110.230666 -232.985573) (xy 110.283816 -232.989556) (xy 110.335778 -233.001416)
			(xy 110.385392 -233.020888) (xy 110.43155 -233.047537) (xy 110.473221 -233.080768) (xy 110.509473 -233.119839)
			(xy 110.539497 -233.163876) (xy 110.562623 -233.211897) (xy 110.578333 -233.262827) (xy 110.586276 -233.315531)
			(xy 110.586774 -233.34218) (xy 110.586276 -233.368829) (xy 110.814602 -233.368829) (xy 110.814602 -233.315531)
			(xy 110.822545 -233.262827) (xy 110.838255 -233.211897) (xy 110.861381 -233.163876) (xy 110.891405 -233.119839)
			(xy 110.927657 -233.080768) (xy 110.969328 -233.047537) (xy 111.015486 -233.020888) (xy 111.0651 -233.001416)
			(xy 111.117062 -232.989556) (xy 111.170212 -232.985573) (xy 111.223362 -232.989556) (xy 111.275324 -233.001416)
			(xy 111.324938 -233.020888) (xy 111.371096 -233.047537) (xy 111.412767 -233.080768) (xy 111.449019 -233.119839)
			(xy 111.479043 -233.163876) (xy 111.502169 -233.211897) (xy 111.517879 -233.262827) (xy 111.525822 -233.315531)
			(xy 111.52632 -233.34218) (xy 111.525822 -233.368829) (xy 111.754402 -233.368829) (xy 111.754402 -233.315531)
			(xy 111.762345 -233.262827) (xy 111.778055 -233.211897) (xy 111.801181 -233.163876) (xy 111.831205 -233.119839)
			(xy 111.867457 -233.080768) (xy 111.909128 -233.047537) (xy 111.955286 -233.020888) (xy 112.0049 -233.001416)
			(xy 112.056862 -232.989556) (xy 112.110012 -232.985573) (xy 112.163162 -232.989556) (xy 112.215124 -233.001416)
			(xy 112.264738 -233.020888) (xy 112.310896 -233.047537) (xy 112.352567 -233.080768) (xy 112.388819 -233.119839)
			(xy 112.418843 -233.163876) (xy 112.441969 -233.211897) (xy 112.457679 -233.262827) (xy 112.465622 -233.315531)
			(xy 112.46612 -233.34218) (xy 112.465622 -233.368829) (xy 112.694202 -233.368829) (xy 112.694202 -233.315531)
			(xy 112.702145 -233.262827) (xy 112.717855 -233.211897) (xy 112.740981 -233.163876) (xy 112.771005 -233.119839)
			(xy 112.807257 -233.080768) (xy 112.848928 -233.047537) (xy 112.895086 -233.020888) (xy 112.9447 -233.001416)
			(xy 112.996662 -232.989556) (xy 113.049812 -232.985573) (xy 113.102962 -232.989556) (xy 113.154924 -233.001416)
			(xy 113.204538 -233.020888) (xy 113.250696 -233.047537) (xy 113.292367 -233.080768) (xy 113.328619 -233.119839)
			(xy 113.358643 -233.163876) (xy 113.381769 -233.211897) (xy 113.397479 -233.262827) (xy 113.405422 -233.315531)
			(xy 113.40592 -233.34218) (xy 113.405422 -233.368829) (xy 113.634256 -233.368829) (xy 113.634256 -233.315531)
			(xy 113.642199 -233.262827) (xy 113.657909 -233.211897) (xy 113.681035 -233.163876) (xy 113.711059 -233.119839)
			(xy 113.747311 -233.080768) (xy 113.788982 -233.047537) (xy 113.83514 -233.020888) (xy 113.884754 -233.001416)
			(xy 113.936716 -232.989556) (xy 113.989866 -232.985573) (xy 114.043016 -232.989556) (xy 114.094978 -233.001416)
			(xy 114.144592 -233.020888) (xy 114.19075 -233.047537) (xy 114.232421 -233.080768) (xy 114.268673 -233.119839)
			(xy 114.298697 -233.163876) (xy 114.321823 -233.211897) (xy 114.337533 -233.262827) (xy 114.345476 -233.315531)
			(xy 114.345974 -233.34218) (xy 114.345476 -233.368829) (xy 114.573802 -233.368829) (xy 114.573802 -233.315531)
			(xy 114.581745 -233.262827) (xy 114.597455 -233.211897) (xy 114.620581 -233.163876) (xy 114.650605 -233.119839)
			(xy 114.686857 -233.080768) (xy 114.728528 -233.047537) (xy 114.774686 -233.020888) (xy 114.8243 -233.001416)
			(xy 114.876262 -232.989556) (xy 114.929412 -232.985573) (xy 114.982562 -232.989556) (xy 115.034524 -233.001416)
			(xy 115.084138 -233.020888) (xy 115.130296 -233.047537) (xy 115.171967 -233.080768) (xy 115.208219 -233.119839)
			(xy 115.238243 -233.163876) (xy 115.261369 -233.211897) (xy 115.277079 -233.262827) (xy 115.285022 -233.315531)
			(xy 115.28552 -233.34218) (xy 115.285022 -233.368829) (xy 115.513602 -233.368829) (xy 115.513602 -233.315531)
			(xy 115.521545 -233.262827) (xy 115.537255 -233.211897) (xy 115.560381 -233.163876) (xy 115.590405 -233.119839)
			(xy 115.626657 -233.080768) (xy 115.668328 -233.047537) (xy 115.714486 -233.020888) (xy 115.7641 -233.001416)
			(xy 115.816062 -232.989556) (xy 115.869212 -232.985573) (xy 115.922362 -232.989556) (xy 115.974324 -233.001416)
			(xy 116.023938 -233.020888) (xy 116.070096 -233.047537) (xy 116.111767 -233.080768) (xy 116.148019 -233.119839)
			(xy 116.178043 -233.163876) (xy 116.201169 -233.211897) (xy 116.216879 -233.262827) (xy 116.224822 -233.315531)
			(xy 116.22532 -233.34218) (xy 116.224822 -233.368829) (xy 116.453402 -233.368829) (xy 116.453402 -233.315531)
			(xy 116.461345 -233.262827) (xy 116.477055 -233.211897) (xy 116.500181 -233.163876) (xy 116.530205 -233.119839)
			(xy 116.566457 -233.080768) (xy 116.608128 -233.047537) (xy 116.654286 -233.020888) (xy 116.7039 -233.001416)
			(xy 116.755862 -232.989556) (xy 116.809012 -232.985573) (xy 116.862162 -232.989556) (xy 116.914124 -233.001416)
			(xy 116.963738 -233.020888) (xy 117.009896 -233.047537) (xy 117.051567 -233.080768) (xy 117.087819 -233.119839)
			(xy 117.117843 -233.163876) (xy 117.140969 -233.211897) (xy 117.156679 -233.262827) (xy 117.164622 -233.315531)
			(xy 117.16512 -233.34218) (xy 117.164622 -233.368829) (xy 117.393202 -233.368829) (xy 117.393202 -233.315531)
			(xy 117.401145 -233.262827) (xy 117.416855 -233.211897) (xy 117.439981 -233.163876) (xy 117.470005 -233.119839)
			(xy 117.506257 -233.080768) (xy 117.547928 -233.047537) (xy 117.594086 -233.020888) (xy 117.6437 -233.001416)
			(xy 117.695662 -232.989556) (xy 117.748812 -232.985573) (xy 117.801962 -232.989556) (xy 117.853924 -233.001416)
			(xy 117.903538 -233.020888) (xy 117.949696 -233.047537) (xy 117.991367 -233.080768) (xy 118.027619 -233.119839)
			(xy 118.057643 -233.163876) (xy 118.080769 -233.211897) (xy 118.096479 -233.262827) (xy 118.104422 -233.315531)
			(xy 118.10492 -233.34218) (xy 118.104422 -233.368829) (xy 118.333002 -233.368829) (xy 118.333002 -233.315531)
			(xy 118.340945 -233.262827) (xy 118.356655 -233.211897) (xy 118.379781 -233.163876) (xy 118.409805 -233.119839)
			(xy 118.446057 -233.080768) (xy 118.487728 -233.047537) (xy 118.533886 -233.020888) (xy 118.5835 -233.001416)
			(xy 118.635462 -232.989556) (xy 118.688612 -232.985573) (xy 118.741762 -232.989556) (xy 118.793724 -233.001416)
			(xy 118.843338 -233.020888) (xy 118.889496 -233.047537) (xy 118.931167 -233.080768) (xy 118.967419 -233.119839)
			(xy 118.997443 -233.163876) (xy 119.020569 -233.211897) (xy 119.036279 -233.262827) (xy 119.044222 -233.315531)
			(xy 119.04472 -233.34218) (xy 119.044222 -233.368829) (xy 119.272802 -233.368829) (xy 119.272802 -233.315531)
			(xy 119.280745 -233.262827) (xy 119.296455 -233.211897) (xy 119.319581 -233.163876) (xy 119.349605 -233.119839)
			(xy 119.385857 -233.080768) (xy 119.427528 -233.047537) (xy 119.473686 -233.020888) (xy 119.5233 -233.001416)
			(xy 119.575262 -232.989556) (xy 119.628412 -232.985573) (xy 119.681562 -232.989556) (xy 119.733524 -233.001416)
			(xy 119.783138 -233.020888) (xy 119.829296 -233.047537) (xy 119.870967 -233.080768) (xy 119.907219 -233.119839)
			(xy 119.937243 -233.163876) (xy 119.960369 -233.211897) (xy 119.976079 -233.262827) (xy 119.984022 -233.315531)
			(xy 119.98452 -233.34218) (xy 119.984022 -233.368829) (xy 120.212602 -233.368829) (xy 120.212602 -233.315531)
			(xy 120.220545 -233.262827) (xy 120.236255 -233.211897) (xy 120.259381 -233.163876) (xy 120.289405 -233.119839)
			(xy 120.325657 -233.080768) (xy 120.367328 -233.047537) (xy 120.413486 -233.020888) (xy 120.4631 -233.001416)
			(xy 120.515062 -232.989556) (xy 120.568212 -232.985573) (xy 120.621362 -232.989556) (xy 120.673324 -233.001416)
			(xy 120.722938 -233.020888) (xy 120.769096 -233.047537) (xy 120.810767 -233.080768) (xy 120.847019 -233.119839)
			(xy 120.877043 -233.163876) (xy 120.900169 -233.211897) (xy 120.915879 -233.262827) (xy 120.923822 -233.315531)
			(xy 120.92432 -233.34218) (xy 120.923822 -233.368829) (xy 121.152656 -233.368829) (xy 121.152656 -233.315531)
			(xy 121.160599 -233.262827) (xy 121.176309 -233.211897) (xy 121.199435 -233.163876) (xy 121.229459 -233.119839)
			(xy 121.265711 -233.080768) (xy 121.307382 -233.047537) (xy 121.35354 -233.020888) (xy 121.403154 -233.001416)
			(xy 121.455116 -232.989556) (xy 121.508266 -232.985573) (xy 121.561416 -232.989556) (xy 121.613378 -233.001416)
			(xy 121.662992 -233.020888) (xy 121.70915 -233.047537) (xy 121.750821 -233.080768) (xy 121.787073 -233.119839)
			(xy 121.817097 -233.163876) (xy 121.840223 -233.211897) (xy 121.855933 -233.262827) (xy 121.863876 -233.315531)
			(xy 121.864374 -233.34218) (xy 121.863876 -233.368829) (xy 122.092202 -233.368829) (xy 122.092202 -233.315531)
			(xy 122.100145 -233.262827) (xy 122.115855 -233.211897) (xy 122.138981 -233.163876) (xy 122.169005 -233.119839)
			(xy 122.205257 -233.080768) (xy 122.246928 -233.047537) (xy 122.293086 -233.020888) (xy 122.3427 -233.001416)
			(xy 122.394662 -232.989556) (xy 122.447812 -232.985573) (xy 122.500962 -232.989556) (xy 122.552924 -233.001416)
			(xy 122.602538 -233.020888) (xy 122.648696 -233.047537) (xy 122.690367 -233.080768) (xy 122.726619 -233.119839)
			(xy 122.756643 -233.163876) (xy 122.779769 -233.211897) (xy 122.795479 -233.262827) (xy 122.803422 -233.315531)
			(xy 122.80392 -233.34218) (xy 122.803422 -233.368829) (xy 123.032002 -233.368829) (xy 123.032002 -233.315531)
			(xy 123.039945 -233.262827) (xy 123.055655 -233.211897) (xy 123.078781 -233.163876) (xy 123.108805 -233.119839)
			(xy 123.145057 -233.080768) (xy 123.186728 -233.047537) (xy 123.232886 -233.020888) (xy 123.2825 -233.001416)
			(xy 123.334462 -232.989556) (xy 123.387612 -232.985573) (xy 123.440762 -232.989556) (xy 123.492724 -233.001416)
			(xy 123.542338 -233.020888) (xy 123.588496 -233.047537) (xy 123.630167 -233.080768) (xy 123.666419 -233.119839)
			(xy 123.696443 -233.163876) (xy 123.719569 -233.211897) (xy 123.735279 -233.262827) (xy 123.743222 -233.315531)
			(xy 123.74372 -233.34218) (xy 123.743222 -233.368829) (xy 123.971802 -233.368829) (xy 123.971802 -233.315531)
			(xy 123.979745 -233.262827) (xy 123.995455 -233.211897) (xy 124.018581 -233.163876) (xy 124.048605 -233.119839)
			(xy 124.084857 -233.080768) (xy 124.126528 -233.047537) (xy 124.172686 -233.020888) (xy 124.2223 -233.001416)
			(xy 124.274262 -232.989556) (xy 124.327412 -232.985573) (xy 124.380562 -232.989556) (xy 124.432524 -233.001416)
			(xy 124.482138 -233.020888) (xy 124.528296 -233.047537) (xy 124.569967 -233.080768) (xy 124.606219 -233.119839)
			(xy 124.636243 -233.163876) (xy 124.659369 -233.211897) (xy 124.675079 -233.262827) (xy 124.683022 -233.315531)
			(xy 124.68352 -233.34218) (xy 124.683022 -233.368829) (xy 124.911602 -233.368829) (xy 124.911602 -233.315531)
			(xy 124.919545 -233.262827) (xy 124.935255 -233.211897) (xy 124.958381 -233.163876) (xy 124.988405 -233.119839)
			(xy 125.024657 -233.080768) (xy 125.066328 -233.047537) (xy 125.112486 -233.020888) (xy 125.1621 -233.001416)
			(xy 125.214062 -232.989556) (xy 125.267212 -232.985573) (xy 125.320362 -232.989556) (xy 125.372324 -233.001416)
			(xy 125.421938 -233.020888) (xy 125.468096 -233.047537) (xy 125.509767 -233.080768) (xy 125.546019 -233.119839)
			(xy 125.576043 -233.163876) (xy 125.599169 -233.211897) (xy 125.614879 -233.262827) (xy 125.622822 -233.315531)
			(xy 125.62332 -233.34218) (xy 125.622822 -233.368829) (xy 125.851656 -233.368829) (xy 125.851656 -233.315531)
			(xy 125.859599 -233.262827) (xy 125.875309 -233.211897) (xy 125.898435 -233.163876) (xy 125.928459 -233.119839)
			(xy 125.964711 -233.080768) (xy 126.006382 -233.047537) (xy 126.05254 -233.020888) (xy 126.102154 -233.001416)
			(xy 126.154116 -232.989556) (xy 126.207266 -232.985573) (xy 126.260416 -232.989556) (xy 126.312378 -233.001416)
			(xy 126.361992 -233.020888) (xy 126.40815 -233.047537) (xy 126.449821 -233.080768) (xy 126.486073 -233.119839)
			(xy 126.516097 -233.163876) (xy 126.539223 -233.211897) (xy 126.554933 -233.262827) (xy 126.562876 -233.315531)
			(xy 126.563374 -233.34218) (xy 126.562876 -233.368829) (xy 126.791202 -233.368829) (xy 126.791202 -233.315531)
			(xy 126.799145 -233.262827) (xy 126.814855 -233.211897) (xy 126.837981 -233.163876) (xy 126.868005 -233.119839)
			(xy 126.904257 -233.080768) (xy 126.945928 -233.047537) (xy 126.992086 -233.020888) (xy 127.0417 -233.001416)
			(xy 127.093662 -232.989556) (xy 127.146812 -232.985573) (xy 127.199962 -232.989556) (xy 127.251924 -233.001416)
			(xy 127.301538 -233.020888) (xy 127.347696 -233.047537) (xy 127.389367 -233.080768) (xy 127.425619 -233.119839)
			(xy 127.455643 -233.163876) (xy 127.478769 -233.211897) (xy 127.494479 -233.262827) (xy 127.502422 -233.315531)
			(xy 127.50292 -233.34218) (xy 127.502422 -233.368829) (xy 127.731002 -233.368829) (xy 127.731002 -233.315531)
			(xy 127.738945 -233.262827) (xy 127.754655 -233.211897) (xy 127.777781 -233.163876) (xy 127.807805 -233.119839)
			(xy 127.844057 -233.080768) (xy 127.885728 -233.047537) (xy 127.931886 -233.020888) (xy 127.9815 -233.001416)
			(xy 128.033462 -232.989556) (xy 128.086612 -232.985573) (xy 128.139762 -232.989556) (xy 128.191724 -233.001416)
			(xy 128.241338 -233.020888) (xy 128.287496 -233.047537) (xy 128.329167 -233.080768) (xy 128.365419 -233.119839)
			(xy 128.395443 -233.163876) (xy 128.418569 -233.211897) (xy 128.434279 -233.262827) (xy 128.442222 -233.315531)
			(xy 128.44272 -233.34218) (xy 128.442222 -233.368829) (xy 128.670802 -233.368829) (xy 128.670802 -233.315531)
			(xy 128.678745 -233.262827) (xy 128.694455 -233.211897) (xy 128.717581 -233.163876) (xy 128.747605 -233.119839)
			(xy 128.783857 -233.080768) (xy 128.825528 -233.047537) (xy 128.871686 -233.020888) (xy 128.9213 -233.001416)
			(xy 128.973262 -232.989556) (xy 129.026412 -232.985573) (xy 129.079562 -232.989556) (xy 129.131524 -233.001416)
			(xy 129.181138 -233.020888) (xy 129.227296 -233.047537) (xy 129.268967 -233.080768) (xy 129.305219 -233.119839)
			(xy 129.335243 -233.163876) (xy 129.358369 -233.211897) (xy 129.374079 -233.262827) (xy 129.382022 -233.315531)
			(xy 129.38252 -233.34218) (xy 129.382022 -233.368829) (xy 129.610602 -233.368829) (xy 129.610602 -233.315531)
			(xy 129.618545 -233.262827) (xy 129.634255 -233.211897) (xy 129.657381 -233.163876) (xy 129.687405 -233.119839)
			(xy 129.723657 -233.080768) (xy 129.765328 -233.047537) (xy 129.811486 -233.020888) (xy 129.8611 -233.001416)
			(xy 129.913062 -232.989556) (xy 129.966212 -232.985573) (xy 130.019362 -232.989556) (xy 130.071324 -233.001416)
			(xy 130.120938 -233.020888) (xy 130.167096 -233.047537) (xy 130.208767 -233.080768) (xy 130.245019 -233.119839)
			(xy 130.275043 -233.163876) (xy 130.298169 -233.211897) (xy 130.313879 -233.262827) (xy 130.321822 -233.315531)
			(xy 130.32232 -233.34218) (xy 130.321822 -233.368829) (xy 130.550402 -233.368829) (xy 130.550402 -233.315531)
			(xy 130.558345 -233.262827) (xy 130.574055 -233.211897) (xy 130.597181 -233.163876) (xy 130.627205 -233.119839)
			(xy 130.663457 -233.080768) (xy 130.705128 -233.047537) (xy 130.751286 -233.020888) (xy 130.8009 -233.001416)
			(xy 130.852862 -232.989556) (xy 130.906012 -232.985573) (xy 130.959162 -232.989556) (xy 131.011124 -233.001416)
			(xy 131.060738 -233.020888) (xy 131.106896 -233.047537) (xy 131.148567 -233.080768) (xy 131.184819 -233.119839)
			(xy 131.214843 -233.163876) (xy 131.237969 -233.211897) (xy 131.253679 -233.262827) (xy 131.261622 -233.315531)
			(xy 131.26212 -233.34218) (xy 131.261622 -233.368829) (xy 131.490202 -233.368829) (xy 131.490202 -233.315531)
			(xy 131.498145 -233.262827) (xy 131.513855 -233.211897) (xy 131.536981 -233.163876) (xy 131.567005 -233.119839)
			(xy 131.603257 -233.080768) (xy 131.644928 -233.047537) (xy 131.691086 -233.020888) (xy 131.7407 -233.001416)
			(xy 131.792662 -232.989556) (xy 131.845812 -232.985573) (xy 131.898962 -232.989556) (xy 131.950924 -233.001416)
			(xy 132.000538 -233.020888) (xy 132.046696 -233.047537) (xy 132.088367 -233.080768) (xy 132.124619 -233.119839)
			(xy 132.154643 -233.163876) (xy 132.177769 -233.211897) (xy 132.193479 -233.262827) (xy 132.201422 -233.315531)
			(xy 132.20192 -233.34218) (xy 132.201422 -233.368829) (xy 132.430256 -233.368829) (xy 132.430256 -233.315531)
			(xy 132.438199 -233.262827) (xy 132.453909 -233.211897) (xy 132.477035 -233.163876) (xy 132.507059 -233.119839)
			(xy 132.543311 -233.080768) (xy 132.584982 -233.047537) (xy 132.63114 -233.020888) (xy 132.680754 -233.001416)
			(xy 132.732716 -232.989556) (xy 132.785866 -232.985573) (xy 132.839016 -232.989556) (xy 132.890978 -233.001416)
			(xy 132.940592 -233.020888) (xy 132.98675 -233.047537) (xy 133.028421 -233.080768) (xy 133.064673 -233.119839)
			(xy 133.094697 -233.163876) (xy 133.117823 -233.211897) (xy 133.133533 -233.262827) (xy 133.141476 -233.315531)
			(xy 133.141974 -233.34218) (xy 133.141476 -233.368829) (xy 133.370056 -233.368829) (xy 133.370056 -233.315531)
			(xy 133.377999 -233.262827) (xy 133.393709 -233.211897) (xy 133.416835 -233.163876) (xy 133.446859 -233.119839)
			(xy 133.483111 -233.080768) (xy 133.524782 -233.047537) (xy 133.57094 -233.020888) (xy 133.620554 -233.001416)
			(xy 133.672516 -232.989556) (xy 133.725666 -232.985573) (xy 133.778816 -232.989556) (xy 133.830778 -233.001416)
			(xy 133.880392 -233.020888) (xy 133.92655 -233.047537) (xy 133.968221 -233.080768) (xy 134.004473 -233.119839)
			(xy 134.034497 -233.163876) (xy 134.057623 -233.211897) (xy 134.073333 -233.262827) (xy 134.081276 -233.315531)
			(xy 134.081774 -233.34218) (xy 134.081276 -233.368829) (xy 134.309856 -233.368829) (xy 134.309856 -233.315531)
			(xy 134.317799 -233.262827) (xy 134.333509 -233.211897) (xy 134.356635 -233.163876) (xy 134.386659 -233.119839)
			(xy 134.422911 -233.080768) (xy 134.464582 -233.047537) (xy 134.51074 -233.020888) (xy 134.560354 -233.001416)
			(xy 134.612316 -232.989556) (xy 134.665466 -232.985573) (xy 134.718616 -232.989556) (xy 134.770578 -233.001416)
			(xy 134.820192 -233.020888) (xy 134.86635 -233.047537) (xy 134.908021 -233.080768) (xy 134.944273 -233.119839)
			(xy 134.974297 -233.163876) (xy 134.997423 -233.211897) (xy 135.013133 -233.262827) (xy 135.021076 -233.315531)
			(xy 135.021574 -233.34218) (xy 135.021076 -233.368829) (xy 135.013133 -233.421533) (xy 134.997423 -233.472463)
			(xy 134.974297 -233.520484) (xy 134.944273 -233.564521) (xy 134.908021 -233.603592) (xy 134.86635 -233.636823)
			(xy 134.820192 -233.663472) (xy 134.770578 -233.682944) (xy 134.718616 -233.694804) (xy 134.665466 -233.698788)
			(xy 134.612316 -233.694804) (xy 134.560354 -233.682944) (xy 134.51074 -233.663472) (xy 134.464582 -233.636823)
			(xy 134.422911 -233.603592) (xy 134.386659 -233.564521) (xy 134.356635 -233.520484) (xy 134.333509 -233.472463)
			(xy 134.317799 -233.421533) (xy 134.309856 -233.368829) (xy 134.081276 -233.368829) (xy 134.073333 -233.421533)
			(xy 134.057623 -233.472463) (xy 134.034497 -233.520484) (xy 134.004473 -233.564521) (xy 133.968221 -233.603592)
			(xy 133.92655 -233.636823) (xy 133.880392 -233.663472) (xy 133.830778 -233.682944) (xy 133.778816 -233.694804)
			(xy 133.725666 -233.698788) (xy 133.672516 -233.694804) (xy 133.620554 -233.682944) (xy 133.57094 -233.663472)
			(xy 133.524782 -233.636823) (xy 133.483111 -233.603592) (xy 133.446859 -233.564521) (xy 133.416835 -233.520484)
			(xy 133.393709 -233.472463) (xy 133.377999 -233.421533) (xy 133.370056 -233.368829) (xy 133.141476 -233.368829)
			(xy 133.133533 -233.421533) (xy 133.117823 -233.472463) (xy 133.094697 -233.520484) (xy 133.064673 -233.564521)
			(xy 133.028421 -233.603592) (xy 132.98675 -233.636823) (xy 132.940592 -233.663472) (xy 132.890978 -233.682944)
			(xy 132.839016 -233.694804) (xy 132.785866 -233.698788) (xy 132.732716 -233.694804) (xy 132.680754 -233.682944)
			(xy 132.63114 -233.663472) (xy 132.584982 -233.636823) (xy 132.543311 -233.603592) (xy 132.507059 -233.564521)
			(xy 132.477035 -233.520484) (xy 132.453909 -233.472463) (xy 132.438199 -233.421533) (xy 132.430256 -233.368829)
			(xy 132.201422 -233.368829) (xy 132.193479 -233.421533) (xy 132.177769 -233.472463) (xy 132.154643 -233.520484)
			(xy 132.124619 -233.564521) (xy 132.088367 -233.603592) (xy 132.046696 -233.636823) (xy 132.000538 -233.663472)
			(xy 131.950924 -233.682944) (xy 131.898962 -233.694804) (xy 131.845812 -233.698788) (xy 131.792662 -233.694804)
			(xy 131.7407 -233.682944) (xy 131.691086 -233.663472) (xy 131.644928 -233.636823) (xy 131.603257 -233.603592)
			(xy 131.567005 -233.564521) (xy 131.536981 -233.520484) (xy 131.513855 -233.472463) (xy 131.498145 -233.421533)
			(xy 131.490202 -233.368829) (xy 131.261622 -233.368829) (xy 131.253679 -233.421533) (xy 131.237969 -233.472463)
			(xy 131.214843 -233.520484) (xy 131.184819 -233.564521) (xy 131.148567 -233.603592) (xy 131.106896 -233.636823)
			(xy 131.060738 -233.663472) (xy 131.011124 -233.682944) (xy 130.959162 -233.694804) (xy 130.906012 -233.698788)
			(xy 130.852862 -233.694804) (xy 130.8009 -233.682944) (xy 130.751286 -233.663472) (xy 130.705128 -233.636823)
			(xy 130.663457 -233.603592) (xy 130.627205 -233.564521) (xy 130.597181 -233.520484) (xy 130.574055 -233.472463)
			(xy 130.558345 -233.421533) (xy 130.550402 -233.368829) (xy 130.321822 -233.368829) (xy 130.313879 -233.421533)
			(xy 130.298169 -233.472463) (xy 130.275043 -233.520484) (xy 130.245019 -233.564521) (xy 130.208767 -233.603592)
			(xy 130.167096 -233.636823) (xy 130.120938 -233.663472) (xy 130.071324 -233.682944) (xy 130.019362 -233.694804)
			(xy 129.966212 -233.698788) (xy 129.913062 -233.694804) (xy 129.8611 -233.682944) (xy 129.811486 -233.663472)
			(xy 129.765328 -233.636823) (xy 129.723657 -233.603592) (xy 129.687405 -233.564521) (xy 129.657381 -233.520484)
			(xy 129.634255 -233.472463) (xy 129.618545 -233.421533) (xy 129.610602 -233.368829) (xy 129.382022 -233.368829)
			(xy 129.374079 -233.421533) (xy 129.358369 -233.472463) (xy 129.335243 -233.520484) (xy 129.305219 -233.564521)
			(xy 129.268967 -233.603592) (xy 129.227296 -233.636823) (xy 129.181138 -233.663472) (xy 129.131524 -233.682944)
			(xy 129.079562 -233.694804) (xy 129.026412 -233.698788) (xy 128.973262 -233.694804) (xy 128.9213 -233.682944)
			(xy 128.871686 -233.663472) (xy 128.825528 -233.636823) (xy 128.783857 -233.603592) (xy 128.747605 -233.564521)
			(xy 128.717581 -233.520484) (xy 128.694455 -233.472463) (xy 128.678745 -233.421533) (xy 128.670802 -233.368829)
			(xy 128.442222 -233.368829) (xy 128.434279 -233.421533) (xy 128.418569 -233.472463) (xy 128.395443 -233.520484)
			(xy 128.365419 -233.564521) (xy 128.329167 -233.603592) (xy 128.287496 -233.636823) (xy 128.241338 -233.663472)
			(xy 128.191724 -233.682944) (xy 128.139762 -233.694804) (xy 128.086612 -233.698788) (xy 128.033462 -233.694804)
			(xy 127.9815 -233.682944) (xy 127.931886 -233.663472) (xy 127.885728 -233.636823) (xy 127.844057 -233.603592)
			(xy 127.807805 -233.564521) (xy 127.777781 -233.520484) (xy 127.754655 -233.472463) (xy 127.738945 -233.421533)
			(xy 127.731002 -233.368829) (xy 127.502422 -233.368829) (xy 127.494479 -233.421533) (xy 127.478769 -233.472463)
			(xy 127.455643 -233.520484) (xy 127.425619 -233.564521) (xy 127.389367 -233.603592) (xy 127.347696 -233.636823)
			(xy 127.301538 -233.663472) (xy 127.251924 -233.682944) (xy 127.199962 -233.694804) (xy 127.146812 -233.698788)
			(xy 127.093662 -233.694804) (xy 127.0417 -233.682944) (xy 126.992086 -233.663472) (xy 126.945928 -233.636823)
			(xy 126.904257 -233.603592) (xy 126.868005 -233.564521) (xy 126.837981 -233.520484) (xy 126.814855 -233.472463)
			(xy 126.799145 -233.421533) (xy 126.791202 -233.368829) (xy 126.562876 -233.368829) (xy 126.554933 -233.421533)
			(xy 126.539223 -233.472463) (xy 126.516097 -233.520484) (xy 126.486073 -233.564521) (xy 126.449821 -233.603592)
			(xy 126.40815 -233.636823) (xy 126.361992 -233.663472) (xy 126.312378 -233.682944) (xy 126.260416 -233.694804)
			(xy 126.207266 -233.698788) (xy 126.154116 -233.694804) (xy 126.102154 -233.682944) (xy 126.05254 -233.663472)
			(xy 126.006382 -233.636823) (xy 125.964711 -233.603592) (xy 125.928459 -233.564521) (xy 125.898435 -233.520484)
			(xy 125.875309 -233.472463) (xy 125.859599 -233.421533) (xy 125.851656 -233.368829) (xy 125.622822 -233.368829)
			(xy 125.614879 -233.421533) (xy 125.599169 -233.472463) (xy 125.576043 -233.520484) (xy 125.546019 -233.564521)
			(xy 125.509767 -233.603592) (xy 125.468096 -233.636823) (xy 125.421938 -233.663472) (xy 125.372324 -233.682944)
			(xy 125.320362 -233.694804) (xy 125.267212 -233.698788) (xy 125.214062 -233.694804) (xy 125.1621 -233.682944)
			(xy 125.112486 -233.663472) (xy 125.066328 -233.636823) (xy 125.024657 -233.603592) (xy 124.988405 -233.564521)
			(xy 124.958381 -233.520484) (xy 124.935255 -233.472463) (xy 124.919545 -233.421533) (xy 124.911602 -233.368829)
			(xy 124.683022 -233.368829) (xy 124.675079 -233.421533) (xy 124.659369 -233.472463) (xy 124.636243 -233.520484)
			(xy 124.606219 -233.564521) (xy 124.569967 -233.603592) (xy 124.528296 -233.636823) (xy 124.482138 -233.663472)
			(xy 124.432524 -233.682944) (xy 124.380562 -233.694804) (xy 124.327412 -233.698788) (xy 124.274262 -233.694804)
			(xy 124.2223 -233.682944) (xy 124.172686 -233.663472) (xy 124.126528 -233.636823) (xy 124.084857 -233.603592)
			(xy 124.048605 -233.564521) (xy 124.018581 -233.520484) (xy 123.995455 -233.472463) (xy 123.979745 -233.421533)
			(xy 123.971802 -233.368829) (xy 123.743222 -233.368829) (xy 123.735279 -233.421533) (xy 123.719569 -233.472463)
			(xy 123.696443 -233.520484) (xy 123.666419 -233.564521) (xy 123.630167 -233.603592) (xy 123.588496 -233.636823)
			(xy 123.542338 -233.663472) (xy 123.492724 -233.682944) (xy 123.440762 -233.694804) (xy 123.387612 -233.698788)
			(xy 123.334462 -233.694804) (xy 123.2825 -233.682944) (xy 123.232886 -233.663472) (xy 123.186728 -233.636823)
			(xy 123.145057 -233.603592) (xy 123.108805 -233.564521) (xy 123.078781 -233.520484) (xy 123.055655 -233.472463)
			(xy 123.039945 -233.421533) (xy 123.032002 -233.368829) (xy 122.803422 -233.368829) (xy 122.795479 -233.421533)
			(xy 122.779769 -233.472463) (xy 122.756643 -233.520484) (xy 122.726619 -233.564521) (xy 122.690367 -233.603592)
			(xy 122.648696 -233.636823) (xy 122.602538 -233.663472) (xy 122.552924 -233.682944) (xy 122.500962 -233.694804)
			(xy 122.447812 -233.698788) (xy 122.394662 -233.694804) (xy 122.3427 -233.682944) (xy 122.293086 -233.663472)
			(xy 122.246928 -233.636823) (xy 122.205257 -233.603592) (xy 122.169005 -233.564521) (xy 122.138981 -233.520484)
			(xy 122.115855 -233.472463) (xy 122.100145 -233.421533) (xy 122.092202 -233.368829) (xy 121.863876 -233.368829)
			(xy 121.855933 -233.421533) (xy 121.840223 -233.472463) (xy 121.817097 -233.520484) (xy 121.787073 -233.564521)
			(xy 121.750821 -233.603592) (xy 121.70915 -233.636823) (xy 121.662992 -233.663472) (xy 121.613378 -233.682944)
			(xy 121.561416 -233.694804) (xy 121.508266 -233.698788) (xy 121.455116 -233.694804) (xy 121.403154 -233.682944)
			(xy 121.35354 -233.663472) (xy 121.307382 -233.636823) (xy 121.265711 -233.603592) (xy 121.229459 -233.564521)
			(xy 121.199435 -233.520484) (xy 121.176309 -233.472463) (xy 121.160599 -233.421533) (xy 121.152656 -233.368829)
			(xy 120.923822 -233.368829) (xy 120.915879 -233.421533) (xy 120.900169 -233.472463) (xy 120.877043 -233.520484)
			(xy 120.847019 -233.564521) (xy 120.810767 -233.603592) (xy 120.769096 -233.636823) (xy 120.722938 -233.663472)
			(xy 120.673324 -233.682944) (xy 120.621362 -233.694804) (xy 120.568212 -233.698788) (xy 120.515062 -233.694804)
			(xy 120.4631 -233.682944) (xy 120.413486 -233.663472) (xy 120.367328 -233.636823) (xy 120.325657 -233.603592)
			(xy 120.289405 -233.564521) (xy 120.259381 -233.520484) (xy 120.236255 -233.472463) (xy 120.220545 -233.421533)
			(xy 120.212602 -233.368829) (xy 119.984022 -233.368829) (xy 119.976079 -233.421533) (xy 119.960369 -233.472463)
			(xy 119.937243 -233.520484) (xy 119.907219 -233.564521) (xy 119.870967 -233.603592) (xy 119.829296 -233.636823)
			(xy 119.783138 -233.663472) (xy 119.733524 -233.682944) (xy 119.681562 -233.694804) (xy 119.628412 -233.698788)
			(xy 119.575262 -233.694804) (xy 119.5233 -233.682944) (xy 119.473686 -233.663472) (xy 119.427528 -233.636823)
			(xy 119.385857 -233.603592) (xy 119.349605 -233.564521) (xy 119.319581 -233.520484) (xy 119.296455 -233.472463)
			(xy 119.280745 -233.421533) (xy 119.272802 -233.368829) (xy 119.044222 -233.368829) (xy 119.036279 -233.421533)
			(xy 119.020569 -233.472463) (xy 118.997443 -233.520484) (xy 118.967419 -233.564521) (xy 118.931167 -233.603592)
			(xy 118.889496 -233.636823) (xy 118.843338 -233.663472) (xy 118.793724 -233.682944) (xy 118.741762 -233.694804)
			(xy 118.688612 -233.698788) (xy 118.635462 -233.694804) (xy 118.5835 -233.682944) (xy 118.533886 -233.663472)
			(xy 118.487728 -233.636823) (xy 118.446057 -233.603592) (xy 118.409805 -233.564521) (xy 118.379781 -233.520484)
			(xy 118.356655 -233.472463) (xy 118.340945 -233.421533) (xy 118.333002 -233.368829) (xy 118.104422 -233.368829)
			(xy 118.096479 -233.421533) (xy 118.080769 -233.472463) (xy 118.057643 -233.520484) (xy 118.027619 -233.564521)
			(xy 117.991367 -233.603592) (xy 117.949696 -233.636823) (xy 117.903538 -233.663472) (xy 117.853924 -233.682944)
			(xy 117.801962 -233.694804) (xy 117.748812 -233.698788) (xy 117.695662 -233.694804) (xy 117.6437 -233.682944)
			(xy 117.594086 -233.663472) (xy 117.547928 -233.636823) (xy 117.506257 -233.603592) (xy 117.470005 -233.564521)
			(xy 117.439981 -233.520484) (xy 117.416855 -233.472463) (xy 117.401145 -233.421533) (xy 117.393202 -233.368829)
			(xy 117.164622 -233.368829) (xy 117.156679 -233.421533) (xy 117.140969 -233.472463) (xy 117.117843 -233.520484)
			(xy 117.087819 -233.564521) (xy 117.051567 -233.603592) (xy 117.009896 -233.636823) (xy 116.963738 -233.663472)
			(xy 116.914124 -233.682944) (xy 116.862162 -233.694804) (xy 116.809012 -233.698788) (xy 116.755862 -233.694804)
			(xy 116.7039 -233.682944) (xy 116.654286 -233.663472) (xy 116.608128 -233.636823) (xy 116.566457 -233.603592)
			(xy 116.530205 -233.564521) (xy 116.500181 -233.520484) (xy 116.477055 -233.472463) (xy 116.461345 -233.421533)
			(xy 116.453402 -233.368829) (xy 116.224822 -233.368829) (xy 116.216879 -233.421533) (xy 116.201169 -233.472463)
			(xy 116.178043 -233.520484) (xy 116.148019 -233.564521) (xy 116.111767 -233.603592) (xy 116.070096 -233.636823)
			(xy 116.023938 -233.663472) (xy 115.974324 -233.682944) (xy 115.922362 -233.694804) (xy 115.869212 -233.698788)
			(xy 115.816062 -233.694804) (xy 115.7641 -233.682944) (xy 115.714486 -233.663472) (xy 115.668328 -233.636823)
			(xy 115.626657 -233.603592) (xy 115.590405 -233.564521) (xy 115.560381 -233.520484) (xy 115.537255 -233.472463)
			(xy 115.521545 -233.421533) (xy 115.513602 -233.368829) (xy 115.285022 -233.368829) (xy 115.277079 -233.421533)
			(xy 115.261369 -233.472463) (xy 115.238243 -233.520484) (xy 115.208219 -233.564521) (xy 115.171967 -233.603592)
			(xy 115.130296 -233.636823) (xy 115.084138 -233.663472) (xy 115.034524 -233.682944) (xy 114.982562 -233.694804)
			(xy 114.929412 -233.698788) (xy 114.876262 -233.694804) (xy 114.8243 -233.682944) (xy 114.774686 -233.663472)
			(xy 114.728528 -233.636823) (xy 114.686857 -233.603592) (xy 114.650605 -233.564521) (xy 114.620581 -233.520484)
			(xy 114.597455 -233.472463) (xy 114.581745 -233.421533) (xy 114.573802 -233.368829) (xy 114.345476 -233.368829)
			(xy 114.337533 -233.421533) (xy 114.321823 -233.472463) (xy 114.298697 -233.520484) (xy 114.268673 -233.564521)
			(xy 114.232421 -233.603592) (xy 114.19075 -233.636823) (xy 114.144592 -233.663472) (xy 114.094978 -233.682944)
			(xy 114.043016 -233.694804) (xy 113.989866 -233.698788) (xy 113.936716 -233.694804) (xy 113.884754 -233.682944)
			(xy 113.83514 -233.663472) (xy 113.788982 -233.636823) (xy 113.747311 -233.603592) (xy 113.711059 -233.564521)
			(xy 113.681035 -233.520484) (xy 113.657909 -233.472463) (xy 113.642199 -233.421533) (xy 113.634256 -233.368829)
			(xy 113.405422 -233.368829) (xy 113.397479 -233.421533) (xy 113.381769 -233.472463) (xy 113.358643 -233.520484)
			(xy 113.328619 -233.564521) (xy 113.292367 -233.603592) (xy 113.250696 -233.636823) (xy 113.204538 -233.663472)
			(xy 113.154924 -233.682944) (xy 113.102962 -233.694804) (xy 113.049812 -233.698788) (xy 112.996662 -233.694804)
			(xy 112.9447 -233.682944) (xy 112.895086 -233.663472) (xy 112.848928 -233.636823) (xy 112.807257 -233.603592)
			(xy 112.771005 -233.564521) (xy 112.740981 -233.520484) (xy 112.717855 -233.472463) (xy 112.702145 -233.421533)
			(xy 112.694202 -233.368829) (xy 112.465622 -233.368829) (xy 112.457679 -233.421533) (xy 112.441969 -233.472463)
			(xy 112.418843 -233.520484) (xy 112.388819 -233.564521) (xy 112.352567 -233.603592) (xy 112.310896 -233.636823)
			(xy 112.264738 -233.663472) (xy 112.215124 -233.682944) (xy 112.163162 -233.694804) (xy 112.110012 -233.698788)
			(xy 112.056862 -233.694804) (xy 112.0049 -233.682944) (xy 111.955286 -233.663472) (xy 111.909128 -233.636823)
			(xy 111.867457 -233.603592) (xy 111.831205 -233.564521) (xy 111.801181 -233.520484) (xy 111.778055 -233.472463)
			(xy 111.762345 -233.421533) (xy 111.754402 -233.368829) (xy 111.525822 -233.368829) (xy 111.517879 -233.421533)
			(xy 111.502169 -233.472463) (xy 111.479043 -233.520484) (xy 111.449019 -233.564521) (xy 111.412767 -233.603592)
			(xy 111.371096 -233.636823) (xy 111.324938 -233.663472) (xy 111.275324 -233.682944) (xy 111.223362 -233.694804)
			(xy 111.170212 -233.698788) (xy 111.117062 -233.694804) (xy 111.0651 -233.682944) (xy 111.015486 -233.663472)
			(xy 110.969328 -233.636823) (xy 110.927657 -233.603592) (xy 110.891405 -233.564521) (xy 110.861381 -233.520484)
			(xy 110.838255 -233.472463) (xy 110.822545 -233.421533) (xy 110.814602 -233.368829) (xy 110.586276 -233.368829)
			(xy 110.578333 -233.421533) (xy 110.562623 -233.472463) (xy 110.539497 -233.520484) (xy 110.509473 -233.564521)
			(xy 110.473221 -233.603592) (xy 110.43155 -233.636823) (xy 110.385392 -233.663472) (xy 110.335778 -233.682944)
			(xy 110.283816 -233.694804) (xy 110.230666 -233.698788) (xy 110.177516 -233.694804) (xy 110.125554 -233.682944)
			(xy 110.07594 -233.663472) (xy 110.029782 -233.636823) (xy 109.988111 -233.603592) (xy 109.951859 -233.564521)
			(xy 109.921835 -233.520484) (xy 109.898709 -233.472463) (xy 109.882999 -233.421533) (xy 109.875056 -233.368829)
			(xy 109.646222 -233.368829) (xy 109.638279 -233.421533) (xy 109.622569 -233.472463) (xy 109.599443 -233.520484)
			(xy 109.569419 -233.564521) (xy 109.533167 -233.603592) (xy 109.491496 -233.636823) (xy 109.445338 -233.663472)
			(xy 109.395724 -233.682944) (xy 109.343762 -233.694804) (xy 109.290612 -233.698788) (xy 109.237462 -233.694804)
			(xy 109.1855 -233.682944) (xy 109.135886 -233.663472) (xy 109.089728 -233.636823) (xy 109.048057 -233.603592)
			(xy 109.011805 -233.564521) (xy 108.981781 -233.520484) (xy 108.958655 -233.472463) (xy 108.942945 -233.421533)
			(xy 108.935002 -233.368829) (xy 108.706422 -233.368829) (xy 108.698479 -233.421533) (xy 108.682769 -233.472463)
			(xy 108.659643 -233.520484) (xy 108.629619 -233.564521) (xy 108.593367 -233.603592) (xy 108.551696 -233.636823)
			(xy 108.505538 -233.663472) (xy 108.455924 -233.682944) (xy 108.403962 -233.694804) (xy 108.350812 -233.698788)
			(xy 108.297662 -233.694804) (xy 108.2457 -233.682944) (xy 108.196086 -233.663472) (xy 108.149928 -233.636823)
			(xy 108.108257 -233.603592) (xy 108.072005 -233.564521) (xy 108.041981 -233.520484) (xy 108.018855 -233.472463)
			(xy 108.003145 -233.421533) (xy 107.995202 -233.368829) (xy 107.766622 -233.368829) (xy 107.758679 -233.421533)
			(xy 107.742969 -233.472463) (xy 107.719843 -233.520484) (xy 107.689819 -233.564521) (xy 107.653567 -233.603592)
			(xy 107.611896 -233.636823) (xy 107.565738 -233.663472) (xy 107.516124 -233.682944) (xy 107.464162 -233.694804)
			(xy 107.411012 -233.698788) (xy 107.357862 -233.694804) (xy 107.3059 -233.682944) (xy 107.256286 -233.663472)
			(xy 107.210128 -233.636823) (xy 107.168457 -233.603592) (xy 107.132205 -233.564521) (xy 107.102181 -233.520484)
			(xy 107.079055 -233.472463) (xy 107.063345 -233.421533) (xy 107.055402 -233.368829) (xy 106.826822 -233.368829)
			(xy 106.818879 -233.421533) (xy 106.803169 -233.472463) (xy 106.780043 -233.520484) (xy 106.750019 -233.564521)
			(xy 106.713767 -233.603592) (xy 106.672096 -233.636823) (xy 106.625938 -233.663472) (xy 106.576324 -233.682944)
			(xy 106.524362 -233.694804) (xy 106.471212 -233.698788) (xy 106.418062 -233.694804) (xy 106.3661 -233.682944)
			(xy 106.316486 -233.663472) (xy 106.270328 -233.636823) (xy 106.228657 -233.603592) (xy 106.192405 -233.564521)
			(xy 106.162381 -233.520484) (xy 106.139255 -233.472463) (xy 106.123545 -233.421533) (xy 106.115602 -233.368829)
			(xy 105.887276 -233.368829) (xy 105.879333 -233.421533) (xy 105.863623 -233.472463) (xy 105.840497 -233.520484)
			(xy 105.810473 -233.564521) (xy 105.774221 -233.603592) (xy 105.73255 -233.636823) (xy 105.686392 -233.663472)
			(xy 105.636778 -233.682944) (xy 105.584816 -233.694804) (xy 105.531666 -233.698788) (xy 105.478516 -233.694804)
			(xy 105.426554 -233.682944) (xy 105.37694 -233.663472) (xy 105.330782 -233.636823) (xy 105.289111 -233.603592)
			(xy 105.252859 -233.564521) (xy 105.222835 -233.520484) (xy 105.199709 -233.472463) (xy 105.183999 -233.421533)
			(xy 105.176056 -233.368829) (xy 104.947476 -233.368829) (xy 104.939533 -233.421533) (xy 104.923823 -233.472463)
			(xy 104.900697 -233.520484) (xy 104.870673 -233.564521) (xy 104.834421 -233.603592) (xy 104.79275 -233.636823)
			(xy 104.746592 -233.663472) (xy 104.696978 -233.682944) (xy 104.645016 -233.694804) (xy 104.591866 -233.698788)
			(xy 104.538716 -233.694804) (xy 104.486754 -233.682944) (xy 104.43714 -233.663472) (xy 104.390982 -233.636823)
			(xy 104.349311 -233.603592) (xy 104.313059 -233.564521) (xy 104.283035 -233.520484) (xy 104.259909 -233.472463)
			(xy 104.244199 -233.421533) (xy 104.236256 -233.368829) (xy 104.007422 -233.368829) (xy 103.999479 -233.421533)
			(xy 103.983769 -233.472463) (xy 103.960643 -233.520484) (xy 103.930619 -233.564521) (xy 103.894367 -233.603592)
			(xy 103.852696 -233.636823) (xy 103.806538 -233.663472) (xy 103.756924 -233.682944) (xy 103.704962 -233.694804)
			(xy 103.651812 -233.698788) (xy 103.598662 -233.694804) (xy 103.5467 -233.682944) (xy 103.497086 -233.663472)
			(xy 103.450928 -233.636823) (xy 103.409257 -233.603592) (xy 103.373005 -233.564521) (xy 103.342981 -233.520484)
			(xy 103.319855 -233.472463) (xy 103.304145 -233.421533) (xy 103.296202 -233.368829) (xy 103.067622 -233.368829)
			(xy 103.059679 -233.421533) (xy 103.043969 -233.472463) (xy 103.020843 -233.520484) (xy 102.990819 -233.564521)
			(xy 102.954567 -233.603592) (xy 102.912896 -233.636823) (xy 102.866738 -233.663472) (xy 102.817124 -233.682944)
			(xy 102.765162 -233.694804) (xy 102.712012 -233.698788) (xy 102.658862 -233.694804) (xy 102.6069 -233.682944)
			(xy 102.557286 -233.663472) (xy 102.511128 -233.636823) (xy 102.469457 -233.603592) (xy 102.433205 -233.564521)
			(xy 102.403181 -233.520484) (xy 102.380055 -233.472463) (xy 102.364345 -233.421533) (xy 102.356402 -233.368829)
			(xy 101.188022 -233.368829) (xy 101.180079 -233.421533) (xy 101.164369 -233.472463) (xy 101.141243 -233.520484)
			(xy 101.111219 -233.564521) (xy 101.074967 -233.603592) (xy 101.033296 -233.636823) (xy 100.987138 -233.663472)
			(xy 100.937524 -233.682944) (xy 100.885562 -233.694804) (xy 100.832412 -233.698788) (xy 100.779262 -233.694804)
			(xy 100.7273 -233.682944) (xy 100.677686 -233.663472) (xy 100.631528 -233.636823) (xy 100.589857 -233.603592)
			(xy 100.553605 -233.564521) (xy 100.523581 -233.520484) (xy 100.500455 -233.472463) (xy 100.484745 -233.421533)
			(xy 100.476802 -233.368829) (xy 100.248222 -233.368829) (xy 100.240279 -233.421533) (xy 100.224569 -233.472463)
			(xy 100.201443 -233.520484) (xy 100.171419 -233.564521) (xy 100.135167 -233.603592) (xy 100.093496 -233.636823)
			(xy 100.047338 -233.663472) (xy 99.997724 -233.682944) (xy 99.945762 -233.694804) (xy 99.892612 -233.698788)
			(xy 99.839462 -233.694804) (xy 99.7875 -233.682944) (xy 99.737886 -233.663472) (xy 99.691728 -233.636823)
			(xy 99.650057 -233.603592) (xy 99.613805 -233.564521) (xy 99.583781 -233.520484) (xy 99.560655 -233.472463)
			(xy 99.544945 -233.421533) (xy 99.537002 -233.368829) (xy 99.308422 -233.368829) (xy 99.300479 -233.421533)
			(xy 99.284769 -233.472463) (xy 99.261643 -233.520484) (xy 99.231619 -233.564521) (xy 99.195367 -233.603592)
			(xy 99.153696 -233.636823) (xy 99.107538 -233.663472) (xy 99.057924 -233.682944) (xy 99.005962 -233.694804)
			(xy 98.952812 -233.698788) (xy 98.899662 -233.694804) (xy 98.8477 -233.682944) (xy 98.798086 -233.663472)
			(xy 98.751928 -233.636823) (xy 98.710257 -233.603592) (xy 98.674005 -233.564521) (xy 98.643981 -233.520484)
			(xy 98.620855 -233.472463) (xy 98.605145 -233.421533) (xy 98.597202 -233.368829) (xy 98.368876 -233.368829)
			(xy 98.360933 -233.421533) (xy 98.345223 -233.472463) (xy 98.322097 -233.520484) (xy 98.292073 -233.564521)
			(xy 98.255821 -233.603592) (xy 98.21415 -233.636823) (xy 98.167992 -233.663472) (xy 98.118378 -233.682944)
			(xy 98.066416 -233.694804) (xy 98.013266 -233.698788) (xy 97.960116 -233.694804) (xy 97.908154 -233.682944)
			(xy 97.85854 -233.663472) (xy 97.812382 -233.636823) (xy 97.770711 -233.603592) (xy 97.734459 -233.564521)
			(xy 97.704435 -233.520484) (xy 97.681309 -233.472463) (xy 97.665599 -233.421533) (xy 97.657656 -233.368829)
			(xy 97.428822 -233.368829) (xy 97.420879 -233.421533) (xy 97.405169 -233.472463) (xy 97.382043 -233.520484)
			(xy 97.352019 -233.564521) (xy 97.315767 -233.603592) (xy 97.274096 -233.636823) (xy 97.227938 -233.663472)
			(xy 97.178324 -233.682944) (xy 97.126362 -233.694804) (xy 97.073212 -233.698788) (xy 97.020062 -233.694804)
			(xy 96.9681 -233.682944) (xy 96.918486 -233.663472) (xy 96.872328 -233.636823) (xy 96.830657 -233.603592)
			(xy 96.794405 -233.564521) (xy 96.764381 -233.520484) (xy 96.741255 -233.472463) (xy 96.725545 -233.421533)
			(xy 96.717602 -233.368829) (xy 96.489022 -233.368829) (xy 96.481079 -233.421533) (xy 96.465369 -233.472463)
			(xy 96.442243 -233.520484) (xy 96.412219 -233.564521) (xy 96.375967 -233.603592) (xy 96.334296 -233.636823)
			(xy 96.288138 -233.663472) (xy 96.238524 -233.682944) (xy 96.186562 -233.694804) (xy 96.133412 -233.698788)
			(xy 96.080262 -233.694804) (xy 96.0283 -233.682944) (xy 95.978686 -233.663472) (xy 95.932528 -233.636823)
			(xy 95.890857 -233.603592) (xy 95.854605 -233.564521) (xy 95.824581 -233.520484) (xy 95.801455 -233.472463)
			(xy 95.785745 -233.421533) (xy 95.777802 -233.368829) (xy 95.549222 -233.368829) (xy 95.541279 -233.421533)
			(xy 95.525569 -233.472463) (xy 95.502443 -233.520484) (xy 95.472419 -233.564521) (xy 95.436167 -233.603592)
			(xy 95.394496 -233.636823) (xy 95.348338 -233.663472) (xy 95.298724 -233.682944) (xy 95.246762 -233.694804)
			(xy 95.193612 -233.698788) (xy 95.140462 -233.694804) (xy 95.0885 -233.682944) (xy 95.038886 -233.663472)
			(xy 94.992728 -233.636823) (xy 94.951057 -233.603592) (xy 94.914805 -233.564521) (xy 94.884781 -233.520484)
			(xy 94.861655 -233.472463) (xy 94.845945 -233.421533) (xy 94.838002 -233.368829) (xy 94.609422 -233.368829)
			(xy 94.601479 -233.421533) (xy 94.585769 -233.472463) (xy 94.562643 -233.520484) (xy 94.532619 -233.564521)
			(xy 94.496367 -233.603592) (xy 94.454696 -233.636823) (xy 94.408538 -233.663472) (xy 94.358924 -233.682944)
			(xy 94.306962 -233.694804) (xy 94.253812 -233.698788) (xy 94.200662 -233.694804) (xy 94.1487 -233.682944)
			(xy 94.099086 -233.663472) (xy 94.052928 -233.636823) (xy 94.011257 -233.603592) (xy 93.975005 -233.564521)
			(xy 93.944981 -233.520484) (xy 93.921855 -233.472463) (xy 93.906145 -233.421533) (xy 93.898202 -233.368829)
			(xy 93.669622 -233.368829) (xy 93.661679 -233.421533) (xy 93.645969 -233.472463) (xy 93.622843 -233.520484)
			(xy 93.592819 -233.564521) (xy 93.556567 -233.603592) (xy 93.514896 -233.636823) (xy 93.468738 -233.663472)
			(xy 93.419124 -233.682944) (xy 93.367162 -233.694804) (xy 93.314012 -233.698788) (xy 93.260862 -233.694804)
			(xy 93.2089 -233.682944) (xy 93.159286 -233.663472) (xy 93.113128 -233.636823) (xy 93.071457 -233.603592)
			(xy 93.035205 -233.564521) (xy 93.005181 -233.520484) (xy 92.982055 -233.472463) (xy 92.966345 -233.421533)
			(xy 92.958402 -233.368829) (xy 92.729822 -233.368829) (xy 92.721879 -233.421533) (xy 92.706169 -233.472463)
			(xy 92.683043 -233.520484) (xy 92.653019 -233.564521) (xy 92.616767 -233.603592) (xy 92.575096 -233.636823)
			(xy 92.528938 -233.663472) (xy 92.479324 -233.682944) (xy 92.427362 -233.694804) (xy 92.374212 -233.698788)
			(xy 92.321062 -233.694804) (xy 92.2691 -233.682944) (xy 92.219486 -233.663472) (xy 92.173328 -233.636823)
			(xy 92.131657 -233.603592) (xy 92.095405 -233.564521) (xy 92.065381 -233.520484) (xy 92.042255 -233.472463)
			(xy 92.026545 -233.421533) (xy 92.018602 -233.368829) (xy 91.790276 -233.368829) (xy 91.782333 -233.421533)
			(xy 91.766623 -233.472463) (xy 91.743497 -233.520484) (xy 91.713473 -233.564521) (xy 91.677221 -233.603592)
			(xy 91.63555 -233.636823) (xy 91.589392 -233.663472) (xy 91.539778 -233.682944) (xy 91.487816 -233.694804)
			(xy 91.434666 -233.698788) (xy 91.381516 -233.694804) (xy 91.329554 -233.682944) (xy 91.27994 -233.663472)
			(xy 91.233782 -233.636823) (xy 91.192111 -233.603592) (xy 91.155859 -233.564521) (xy 91.125835 -233.520484)
			(xy 91.102709 -233.472463) (xy 91.086999 -233.421533) (xy 91.079056 -233.368829) (xy 90.850222 -233.368829)
			(xy 90.842279 -233.421533) (xy 90.826569 -233.472463) (xy 90.803443 -233.520484) (xy 90.773419 -233.564521)
			(xy 90.737167 -233.603592) (xy 90.695496 -233.636823) (xy 90.649338 -233.663472) (xy 90.599724 -233.682944)
			(xy 90.547762 -233.694804) (xy 90.494612 -233.698788) (xy 90.441462 -233.694804) (xy 90.3895 -233.682944)
			(xy 90.339886 -233.663472) (xy 90.293728 -233.636823) (xy 90.252057 -233.603592) (xy 90.215805 -233.564521)
			(xy 90.185781 -233.520484) (xy 90.162655 -233.472463) (xy 90.146945 -233.421533) (xy 90.139002 -233.368829)
			(xy 89.910422 -233.368829) (xy 89.902479 -233.421533) (xy 89.886769 -233.472463) (xy 89.863643 -233.520484)
			(xy 89.833619 -233.564521) (xy 89.797367 -233.603592) (xy 89.755696 -233.636823) (xy 89.709538 -233.663472)
			(xy 89.659924 -233.682944) (xy 89.607962 -233.694804) (xy 89.554812 -233.698788) (xy 89.501662 -233.694804)
			(xy 89.4497 -233.682944) (xy 89.400086 -233.663472) (xy 89.353928 -233.636823) (xy 89.312257 -233.603592)
			(xy 89.276005 -233.564521) (xy 89.245981 -233.520484) (xy 89.222855 -233.472463) (xy 89.207145 -233.421533)
			(xy 89.199202 -233.368829) (xy 88.969634 -233.368829) (xy 88.967699 -233.394885) (xy 88.956044 -233.446419)
			(xy 88.936902 -233.495665) (xy 88.910694 -233.541543) (xy 88.877995 -233.583045) (xy 88.839523 -233.61926)
			(xy 88.796122 -233.649393) (xy 88.748745 -233.672782) (xy 88.723724 -233.68127) (xy 88.688418 -233.6927)
			(xy 88.688418 -233.806492) (xy 88.68891 -233.820951) (xy 88.696996 -233.848714) (xy 88.712547 -233.873093)
			(xy 88.734315 -233.892128) (xy 88.760549 -233.90429) (xy 88.789143 -233.908601) (xy 88.817797 -233.904715)
			(xy 88.84421 -233.892944) (xy 88.85555 -233.883962) (xy 88.874909 -233.868199) (xy 88.917205 -233.841676)
			(xy 88.962789 -233.821318) (xy 89.010768 -233.807523) (xy 89.060204 -233.800563) (xy 89.085166 -233.800142)
			(xy 89.111815 -233.800613) (xy 89.164519 -233.808552) (xy 89.21545 -233.824258) (xy 89.263471 -233.84738)
			(xy 89.30751 -233.877401) (xy 89.346582 -233.913651) (xy 89.379815 -233.955319) (xy 89.406465 -234.001476)
			(xy 89.425938 -234.051089) (xy 89.437799 -234.103051) (xy 89.441782 -234.1562) (xy 89.439781 -234.182899)
			(xy 89.669356 -234.182899) (xy 89.669356 -234.129601) (xy 89.677299 -234.076897) (xy 89.693009 -234.025967)
			(xy 89.716135 -233.977946) (xy 89.746159 -233.933909) (xy 89.782411 -233.894838) (xy 89.824082 -233.861607)
			(xy 89.87024 -233.834958) (xy 89.919854 -233.815486) (xy 89.971816 -233.803626) (xy 90.024966 -233.799643)
			(xy 90.078116 -233.803626) (xy 90.130078 -233.815486) (xy 90.179692 -233.834958) (xy 90.22585 -233.861607)
			(xy 90.267521 -233.894838) (xy 90.303773 -233.933909) (xy 90.333797 -233.977946) (xy 90.356923 -234.025967)
			(xy 90.372633 -234.076897) (xy 90.380576 -234.129601) (xy 90.381074 -234.15625) (xy 90.380576 -234.182899)
			(xy 90.609156 -234.182899) (xy 90.609156 -234.129601) (xy 90.617099 -234.076897) (xy 90.632809 -234.025967)
			(xy 90.655935 -233.977946) (xy 90.685959 -233.933909) (xy 90.722211 -233.894838) (xy 90.763882 -233.861607)
			(xy 90.81004 -233.834958) (xy 90.859654 -233.815486) (xy 90.911616 -233.803626) (xy 90.964766 -233.799643)
			(xy 91.017916 -233.803626) (xy 91.069878 -233.815486) (xy 91.119492 -233.834958) (xy 91.16565 -233.861607)
			(xy 91.207321 -233.894838) (xy 91.243573 -233.933909) (xy 91.273597 -233.977946) (xy 91.296723 -234.025967)
			(xy 91.312433 -234.076897) (xy 91.320376 -234.129601) (xy 91.320874 -234.15625) (xy 91.320376 -234.182899)
			(xy 91.548956 -234.182899) (xy 91.548956 -234.129601) (xy 91.556899 -234.076897) (xy 91.572609 -234.025967)
			(xy 91.595735 -233.977946) (xy 91.625759 -233.933909) (xy 91.662011 -233.894838) (xy 91.703682 -233.861607)
			(xy 91.74984 -233.834958) (xy 91.799454 -233.815486) (xy 91.851416 -233.803626) (xy 91.904566 -233.799643)
			(xy 91.957716 -233.803626) (xy 92.009678 -233.815486) (xy 92.059292 -233.834958) (xy 92.10545 -233.861607)
			(xy 92.147121 -233.894838) (xy 92.183373 -233.933909) (xy 92.213397 -233.977946) (xy 92.236523 -234.025967)
			(xy 92.252233 -234.076897) (xy 92.260176 -234.129601) (xy 92.260674 -234.15625) (xy 92.260176 -234.182899)
			(xy 92.488756 -234.182899) (xy 92.488756 -234.129601) (xy 92.496699 -234.076897) (xy 92.512409 -234.025967)
			(xy 92.535535 -233.977946) (xy 92.565559 -233.933909) (xy 92.601811 -233.894838) (xy 92.643482 -233.861607)
			(xy 92.68964 -233.834958) (xy 92.739254 -233.815486) (xy 92.791216 -233.803626) (xy 92.844366 -233.799643)
			(xy 92.897516 -233.803626) (xy 92.949478 -233.815486) (xy 92.999092 -233.834958) (xy 93.04525 -233.861607)
			(xy 93.086921 -233.894838) (xy 93.123173 -233.933909) (xy 93.153197 -233.977946) (xy 93.176323 -234.025967)
			(xy 93.192033 -234.076897) (xy 93.199976 -234.129601) (xy 93.200474 -234.15625) (xy 93.199976 -234.182899)
			(xy 93.428556 -234.182899) (xy 93.428556 -234.129601) (xy 93.436499 -234.076897) (xy 93.452209 -234.025967)
			(xy 93.475335 -233.977946) (xy 93.505359 -233.933909) (xy 93.541611 -233.894838) (xy 93.583282 -233.861607)
			(xy 93.62944 -233.834958) (xy 93.679054 -233.815486) (xy 93.731016 -233.803626) (xy 93.784166 -233.799643)
			(xy 93.837316 -233.803626) (xy 93.889278 -233.815486) (xy 93.938892 -233.834958) (xy 93.98505 -233.861607)
			(xy 94.026721 -233.894838) (xy 94.062973 -233.933909) (xy 94.092997 -233.977946) (xy 94.116123 -234.025967)
			(xy 94.131833 -234.076897) (xy 94.139776 -234.129601) (xy 94.140274 -234.15625) (xy 94.139776 -234.182899)
			(xy 94.368102 -234.182899) (xy 94.368102 -234.129601) (xy 94.376045 -234.076897) (xy 94.391755 -234.025967)
			(xy 94.414881 -233.977946) (xy 94.444905 -233.933909) (xy 94.481157 -233.894838) (xy 94.522828 -233.861607)
			(xy 94.568986 -233.834958) (xy 94.6186 -233.815486) (xy 94.670562 -233.803626) (xy 94.723712 -233.799643)
			(xy 94.776862 -233.803626) (xy 94.828824 -233.815486) (xy 94.878438 -233.834958) (xy 94.924596 -233.861607)
			(xy 94.966267 -233.894838) (xy 95.002519 -233.933909) (xy 95.032543 -233.977946) (xy 95.055669 -234.025967)
			(xy 95.071379 -234.076897) (xy 95.079322 -234.129601) (xy 95.07982 -234.15625) (xy 95.079322 -234.182899)
			(xy 95.308156 -234.182899) (xy 95.308156 -234.129601) (xy 95.316099 -234.076897) (xy 95.331809 -234.025967)
			(xy 95.354935 -233.977946) (xy 95.384959 -233.933909) (xy 95.421211 -233.894838) (xy 95.462882 -233.861607)
			(xy 95.50904 -233.834958) (xy 95.558654 -233.815486) (xy 95.610616 -233.803626) (xy 95.663766 -233.799643)
			(xy 95.716916 -233.803626) (xy 95.768878 -233.815486) (xy 95.818492 -233.834958) (xy 95.86465 -233.861607)
			(xy 95.906321 -233.894838) (xy 95.942573 -233.933909) (xy 95.972597 -233.977946) (xy 95.995723 -234.025967)
			(xy 96.011433 -234.076897) (xy 96.019376 -234.129601) (xy 96.019874 -234.15625) (xy 96.019376 -234.182899)
			(xy 96.247956 -234.182899) (xy 96.247956 -234.129601) (xy 96.255899 -234.076897) (xy 96.271609 -234.025967)
			(xy 96.294735 -233.977946) (xy 96.324759 -233.933909) (xy 96.361011 -233.894838) (xy 96.402682 -233.861607)
			(xy 96.44884 -233.834958) (xy 96.498454 -233.815486) (xy 96.550416 -233.803626) (xy 96.603566 -233.799643)
			(xy 96.656716 -233.803626) (xy 96.708678 -233.815486) (xy 96.758292 -233.834958) (xy 96.80445 -233.861607)
			(xy 96.846121 -233.894838) (xy 96.882373 -233.933909) (xy 96.912397 -233.977946) (xy 96.935523 -234.025967)
			(xy 96.951233 -234.076897) (xy 96.959176 -234.129601) (xy 96.959674 -234.15625) (xy 96.959176 -234.182899)
			(xy 97.187756 -234.182899) (xy 97.187756 -234.129601) (xy 97.195699 -234.076897) (xy 97.211409 -234.025967)
			(xy 97.234535 -233.977946) (xy 97.264559 -233.933909) (xy 97.300811 -233.894838) (xy 97.342482 -233.861607)
			(xy 97.38864 -233.834958) (xy 97.438254 -233.815486) (xy 97.490216 -233.803626) (xy 97.543366 -233.799643)
			(xy 97.596516 -233.803626) (xy 97.648478 -233.815486) (xy 97.698092 -233.834958) (xy 97.74425 -233.861607)
			(xy 97.785921 -233.894838) (xy 97.822173 -233.933909) (xy 97.852197 -233.977946) (xy 97.875323 -234.025967)
			(xy 97.891033 -234.076897) (xy 97.898976 -234.129601) (xy 97.899474 -234.15625) (xy 97.898976 -234.182899)
			(xy 98.127556 -234.182899) (xy 98.127556 -234.129601) (xy 98.135499 -234.076897) (xy 98.151209 -234.025967)
			(xy 98.174335 -233.977946) (xy 98.204359 -233.933909) (xy 98.240611 -233.894838) (xy 98.282282 -233.861607)
			(xy 98.32844 -233.834958) (xy 98.378054 -233.815486) (xy 98.430016 -233.803626) (xy 98.483166 -233.799643)
			(xy 98.536316 -233.803626) (xy 98.588278 -233.815486) (xy 98.637892 -233.834958) (xy 98.68405 -233.861607)
			(xy 98.725721 -233.894838) (xy 98.761973 -233.933909) (xy 98.791997 -233.977946) (xy 98.815123 -234.025967)
			(xy 98.830833 -234.076897) (xy 98.838776 -234.129601) (xy 98.839274 -234.15625) (xy 98.838776 -234.182899)
			(xy 99.067356 -234.182899) (xy 99.067356 -234.129601) (xy 99.075299 -234.076897) (xy 99.091009 -234.025967)
			(xy 99.114135 -233.977946) (xy 99.144159 -233.933909) (xy 99.180411 -233.894838) (xy 99.222082 -233.861607)
			(xy 99.26824 -233.834958) (xy 99.317854 -233.815486) (xy 99.369816 -233.803626) (xy 99.422966 -233.799643)
			(xy 99.476116 -233.803626) (xy 99.528078 -233.815486) (xy 99.577692 -233.834958) (xy 99.62385 -233.861607)
			(xy 99.665521 -233.894838) (xy 99.701773 -233.933909) (xy 99.731797 -233.977946) (xy 99.754923 -234.025967)
			(xy 99.770633 -234.076897) (xy 99.778576 -234.129601) (xy 99.779074 -234.15625) (xy 99.778576 -234.182899)
			(xy 100.007156 -234.182899) (xy 100.007156 -234.129601) (xy 100.015099 -234.076897) (xy 100.030809 -234.025967)
			(xy 100.053935 -233.977946) (xy 100.083959 -233.933909) (xy 100.120211 -233.894838) (xy 100.161882 -233.861607)
			(xy 100.20804 -233.834958) (xy 100.257654 -233.815486) (xy 100.309616 -233.803626) (xy 100.362766 -233.799643)
			(xy 100.415916 -233.803626) (xy 100.467878 -233.815486) (xy 100.517492 -233.834958) (xy 100.56365 -233.861607)
			(xy 100.605321 -233.894838) (xy 100.641573 -233.933909) (xy 100.671597 -233.977946) (xy 100.694723 -234.025967)
			(xy 100.710433 -234.076897) (xy 100.718376 -234.129601) (xy 100.718874 -234.15625) (xy 100.718376 -234.182899)
			(xy 100.946702 -234.182899) (xy 100.946702 -234.129601) (xy 100.954645 -234.076897) (xy 100.970355 -234.025967)
			(xy 100.993481 -233.977946) (xy 101.023505 -233.933909) (xy 101.059757 -233.894838) (xy 101.101428 -233.861607)
			(xy 101.147586 -233.834958) (xy 101.1972 -233.815486) (xy 101.249162 -233.803626) (xy 101.302312 -233.799643)
			(xy 101.355462 -233.803626) (xy 101.407424 -233.815486) (xy 101.457038 -233.834958) (xy 101.503196 -233.861607)
			(xy 101.544867 -233.894838) (xy 101.581119 -233.933909) (xy 101.611143 -233.977946) (xy 101.634269 -234.025967)
			(xy 101.649979 -234.076897) (xy 101.657922 -234.129601) (xy 101.65842 -234.15625) (xy 101.657922 -234.182899)
			(xy 101.886756 -234.182899) (xy 101.886756 -234.129601) (xy 101.894699 -234.076897) (xy 101.910409 -234.025967)
			(xy 101.933535 -233.977946) (xy 101.963559 -233.933909) (xy 101.999811 -233.894838) (xy 102.041482 -233.861607)
			(xy 102.08764 -233.834958) (xy 102.137254 -233.815486) (xy 102.189216 -233.803626) (xy 102.242366 -233.799643)
			(xy 102.295516 -233.803626) (xy 102.347478 -233.815486) (xy 102.397092 -233.834958) (xy 102.44325 -233.861607)
			(xy 102.484921 -233.894838) (xy 102.521173 -233.933909) (xy 102.551197 -233.977946) (xy 102.574323 -234.025967)
			(xy 102.590033 -234.076897) (xy 102.597976 -234.129601) (xy 102.598474 -234.15625) (xy 102.597976 -234.182899)
			(xy 102.826556 -234.182899) (xy 102.826556 -234.129601) (xy 102.834499 -234.076897) (xy 102.850209 -234.025967)
			(xy 102.873335 -233.977946) (xy 102.903359 -233.933909) (xy 102.939611 -233.894838) (xy 102.981282 -233.861607)
			(xy 103.02744 -233.834958) (xy 103.077054 -233.815486) (xy 103.129016 -233.803626) (xy 103.182166 -233.799643)
			(xy 103.235316 -233.803626) (xy 103.287278 -233.815486) (xy 103.336892 -233.834958) (xy 103.38305 -233.861607)
			(xy 103.424721 -233.894838) (xy 103.460973 -233.933909) (xy 103.490997 -233.977946) (xy 103.514123 -234.025967)
			(xy 103.529833 -234.076897) (xy 103.537776 -234.129601) (xy 103.538274 -234.15625) (xy 103.537776 -234.182899)
			(xy 103.766356 -234.182899) (xy 103.766356 -234.129601) (xy 103.774299 -234.076897) (xy 103.790009 -234.025967)
			(xy 103.813135 -233.977946) (xy 103.843159 -233.933909) (xy 103.879411 -233.894838) (xy 103.921082 -233.861607)
			(xy 103.96724 -233.834958) (xy 104.016854 -233.815486) (xy 104.068816 -233.803626) (xy 104.121966 -233.799643)
			(xy 104.175116 -233.803626) (xy 104.227078 -233.815486) (xy 104.276692 -233.834958) (xy 104.32285 -233.861607)
			(xy 104.364521 -233.894838) (xy 104.400773 -233.933909) (xy 104.430797 -233.977946) (xy 104.453923 -234.025967)
			(xy 104.469633 -234.076897) (xy 104.477576 -234.129601) (xy 104.478074 -234.15625) (xy 104.477576 -234.182899)
			(xy 105.645956 -234.182899) (xy 105.645956 -234.129601) (xy 105.653899 -234.076897) (xy 105.669609 -234.025967)
			(xy 105.692735 -233.977946) (xy 105.722759 -233.933909) (xy 105.759011 -233.894838) (xy 105.800682 -233.861607)
			(xy 105.84684 -233.834958) (xy 105.896454 -233.815486) (xy 105.948416 -233.803626) (xy 106.001566 -233.799643)
			(xy 106.054716 -233.803626) (xy 106.106678 -233.815486) (xy 106.156292 -233.834958) (xy 106.20245 -233.861607)
			(xy 106.244121 -233.894838) (xy 106.280373 -233.933909) (xy 106.310397 -233.977946) (xy 106.333523 -234.025967)
			(xy 106.349233 -234.076897) (xy 106.357176 -234.129601) (xy 106.357674 -234.15625) (xy 106.357176 -234.182899)
			(xy 106.585756 -234.182899) (xy 106.585756 -234.129601) (xy 106.593699 -234.076897) (xy 106.609409 -234.025967)
			(xy 106.632535 -233.977946) (xy 106.662559 -233.933909) (xy 106.698811 -233.894838) (xy 106.740482 -233.861607)
			(xy 106.78664 -233.834958) (xy 106.836254 -233.815486) (xy 106.888216 -233.803626) (xy 106.941366 -233.799643)
			(xy 106.994516 -233.803626) (xy 107.046478 -233.815486) (xy 107.096092 -233.834958) (xy 107.14225 -233.861607)
			(xy 107.183921 -233.894838) (xy 107.220173 -233.933909) (xy 107.250197 -233.977946) (xy 107.273323 -234.025967)
			(xy 107.289033 -234.076897) (xy 107.296976 -234.129601) (xy 107.297474 -234.15625) (xy 107.296976 -234.182899)
			(xy 107.525556 -234.182899) (xy 107.525556 -234.129601) (xy 107.533499 -234.076897) (xy 107.549209 -234.025967)
			(xy 107.572335 -233.977946) (xy 107.602359 -233.933909) (xy 107.638611 -233.894838) (xy 107.680282 -233.861607)
			(xy 107.72644 -233.834958) (xy 107.776054 -233.815486) (xy 107.828016 -233.803626) (xy 107.881166 -233.799643)
			(xy 107.934316 -233.803626) (xy 107.986278 -233.815486) (xy 108.035892 -233.834958) (xy 108.08205 -233.861607)
			(xy 108.123721 -233.894838) (xy 108.159973 -233.933909) (xy 108.189997 -233.977946) (xy 108.213123 -234.025967)
			(xy 108.228833 -234.076897) (xy 108.236776 -234.129601) (xy 108.237274 -234.15625) (xy 108.236776 -234.182899)
			(xy 108.465356 -234.182899) (xy 108.465356 -234.129601) (xy 108.473299 -234.076897) (xy 108.489009 -234.025967)
			(xy 108.512135 -233.977946) (xy 108.542159 -233.933909) (xy 108.578411 -233.894838) (xy 108.620082 -233.861607)
			(xy 108.66624 -233.834958) (xy 108.715854 -233.815486) (xy 108.767816 -233.803626) (xy 108.820966 -233.799643)
			(xy 108.874116 -233.803626) (xy 108.926078 -233.815486) (xy 108.975692 -233.834958) (xy 109.02185 -233.861607)
			(xy 109.063521 -233.894838) (xy 109.099773 -233.933909) (xy 109.129797 -233.977946) (xy 109.152923 -234.025967)
			(xy 109.168633 -234.076897) (xy 109.176576 -234.129601) (xy 109.177074 -234.15625) (xy 109.176576 -234.182899)
			(xy 109.405156 -234.182899) (xy 109.405156 -234.129601) (xy 109.413099 -234.076897) (xy 109.428809 -234.025967)
			(xy 109.451935 -233.977946) (xy 109.481959 -233.933909) (xy 109.518211 -233.894838) (xy 109.559882 -233.861607)
			(xy 109.60604 -233.834958) (xy 109.655654 -233.815486) (xy 109.707616 -233.803626) (xy 109.760766 -233.799643)
			(xy 109.813916 -233.803626) (xy 109.865878 -233.815486) (xy 109.915492 -233.834958) (xy 109.96165 -233.861607)
			(xy 110.003321 -233.894838) (xy 110.039573 -233.933909) (xy 110.069597 -233.977946) (xy 110.092723 -234.025967)
			(xy 110.108433 -234.076897) (xy 110.116376 -234.129601) (xy 110.116874 -234.15625) (xy 110.116376 -234.182899)
			(xy 110.344956 -234.182899) (xy 110.344956 -234.129601) (xy 110.352899 -234.076897) (xy 110.368609 -234.025967)
			(xy 110.391735 -233.977946) (xy 110.421759 -233.933909) (xy 110.458011 -233.894838) (xy 110.499682 -233.861607)
			(xy 110.54584 -233.834958) (xy 110.595454 -233.815486) (xy 110.647416 -233.803626) (xy 110.700566 -233.799643)
			(xy 110.753716 -233.803626) (xy 110.805678 -233.815486) (xy 110.855292 -233.834958) (xy 110.90145 -233.861607)
			(xy 110.943121 -233.894838) (xy 110.979373 -233.933909) (xy 111.009397 -233.977946) (xy 111.032523 -234.025967)
			(xy 111.048233 -234.076897) (xy 111.056176 -234.129601) (xy 111.056674 -234.15625) (xy 111.056176 -234.182899)
			(xy 111.284756 -234.182899) (xy 111.284756 -234.129601) (xy 111.292699 -234.076897) (xy 111.308409 -234.025967)
			(xy 111.331535 -233.977946) (xy 111.361559 -233.933909) (xy 111.397811 -233.894838) (xy 111.439482 -233.861607)
			(xy 111.48564 -233.834958) (xy 111.535254 -233.815486) (xy 111.587216 -233.803626) (xy 111.640366 -233.799643)
			(xy 111.693516 -233.803626) (xy 111.745478 -233.815486) (xy 111.795092 -233.834958) (xy 111.84125 -233.861607)
			(xy 111.882921 -233.894838) (xy 111.919173 -233.933909) (xy 111.949197 -233.977946) (xy 111.972323 -234.025967)
			(xy 111.988033 -234.076897) (xy 111.995976 -234.129601) (xy 111.996474 -234.15625) (xy 111.995976 -234.182899)
			(xy 112.224556 -234.182899) (xy 112.224556 -234.129601) (xy 112.232499 -234.076897) (xy 112.248209 -234.025967)
			(xy 112.271335 -233.977946) (xy 112.301359 -233.933909) (xy 112.337611 -233.894838) (xy 112.379282 -233.861607)
			(xy 112.42544 -233.834958) (xy 112.475054 -233.815486) (xy 112.527016 -233.803626) (xy 112.580166 -233.799643)
			(xy 112.633316 -233.803626) (xy 112.685278 -233.815486) (xy 112.734892 -233.834958) (xy 112.78105 -233.861607)
			(xy 112.822721 -233.894838) (xy 112.858973 -233.933909) (xy 112.888997 -233.977946) (xy 112.912123 -234.025967)
			(xy 112.927833 -234.076897) (xy 112.935776 -234.129601) (xy 112.936274 -234.15625) (xy 112.935776 -234.182899)
			(xy 113.164356 -234.182899) (xy 113.164356 -234.129601) (xy 113.172299 -234.076897) (xy 113.188009 -234.025967)
			(xy 113.211135 -233.977946) (xy 113.241159 -233.933909) (xy 113.277411 -233.894838) (xy 113.319082 -233.861607)
			(xy 113.36524 -233.834958) (xy 113.414854 -233.815486) (xy 113.466816 -233.803626) (xy 113.519966 -233.799643)
			(xy 113.573116 -233.803626) (xy 113.625078 -233.815486) (xy 113.674692 -233.834958) (xy 113.72085 -233.861607)
			(xy 113.762521 -233.894838) (xy 113.798773 -233.933909) (xy 113.828797 -233.977946) (xy 113.851923 -234.025967)
			(xy 113.867633 -234.076897) (xy 113.875576 -234.129601) (xy 113.876074 -234.15625) (xy 113.875576 -234.182899)
			(xy 114.104156 -234.182899) (xy 114.104156 -234.129601) (xy 114.112099 -234.076897) (xy 114.127809 -234.025967)
			(xy 114.150935 -233.977946) (xy 114.180959 -233.933909) (xy 114.217211 -233.894838) (xy 114.258882 -233.861607)
			(xy 114.30504 -233.834958) (xy 114.354654 -233.815486) (xy 114.406616 -233.803626) (xy 114.459766 -233.799643)
			(xy 114.512916 -233.803626) (xy 114.564878 -233.815486) (xy 114.614492 -233.834958) (xy 114.66065 -233.861607)
			(xy 114.702321 -233.894838) (xy 114.738573 -233.933909) (xy 114.768597 -233.977946) (xy 114.791723 -234.025967)
			(xy 114.807433 -234.076897) (xy 114.815376 -234.129601) (xy 114.815874 -234.15625) (xy 114.815376 -234.182899)
			(xy 115.043956 -234.182899) (xy 115.043956 -234.129601) (xy 115.051899 -234.076897) (xy 115.067609 -234.025967)
			(xy 115.090735 -233.977946) (xy 115.120759 -233.933909) (xy 115.157011 -233.894838) (xy 115.198682 -233.861607)
			(xy 115.24484 -233.834958) (xy 115.294454 -233.815486) (xy 115.346416 -233.803626) (xy 115.399566 -233.799643)
			(xy 115.452716 -233.803626) (xy 115.504678 -233.815486) (xy 115.554292 -233.834958) (xy 115.60045 -233.861607)
			(xy 115.642121 -233.894838) (xy 115.678373 -233.933909) (xy 115.708397 -233.977946) (xy 115.731523 -234.025967)
			(xy 115.747233 -234.076897) (xy 115.755176 -234.129601) (xy 115.755674 -234.15625) (xy 115.755176 -234.182899)
			(xy 115.983756 -234.182899) (xy 115.983756 -234.129601) (xy 115.991699 -234.076897) (xy 116.007409 -234.025967)
			(xy 116.030535 -233.977946) (xy 116.060559 -233.933909) (xy 116.096811 -233.894838) (xy 116.138482 -233.861607)
			(xy 116.18464 -233.834958) (xy 116.234254 -233.815486) (xy 116.286216 -233.803626) (xy 116.339366 -233.799643)
			(xy 116.392516 -233.803626) (xy 116.444478 -233.815486) (xy 116.494092 -233.834958) (xy 116.54025 -233.861607)
			(xy 116.581921 -233.894838) (xy 116.618173 -233.933909) (xy 116.648197 -233.977946) (xy 116.671323 -234.025967)
			(xy 116.687033 -234.076897) (xy 116.694976 -234.129601) (xy 116.695474 -234.15625) (xy 116.694976 -234.182899)
			(xy 116.923556 -234.182899) (xy 116.923556 -234.129601) (xy 116.931499 -234.076897) (xy 116.947209 -234.025967)
			(xy 116.970335 -233.977946) (xy 117.000359 -233.933909) (xy 117.036611 -233.894838) (xy 117.078282 -233.861607)
			(xy 117.12444 -233.834958) (xy 117.174054 -233.815486) (xy 117.226016 -233.803626) (xy 117.279166 -233.799643)
			(xy 117.332316 -233.803626) (xy 117.384278 -233.815486) (xy 117.433892 -233.834958) (xy 117.48005 -233.861607)
			(xy 117.521721 -233.894838) (xy 117.557973 -233.933909) (xy 117.587997 -233.977946) (xy 117.611123 -234.025967)
			(xy 117.626833 -234.076897) (xy 117.634776 -234.129601) (xy 117.635274 -234.15625) (xy 117.634776 -234.182899)
			(xy 117.863356 -234.182899) (xy 117.863356 -234.129601) (xy 117.871299 -234.076897) (xy 117.887009 -234.025967)
			(xy 117.910135 -233.977946) (xy 117.940159 -233.933909) (xy 117.976411 -233.894838) (xy 118.018082 -233.861607)
			(xy 118.06424 -233.834958) (xy 118.113854 -233.815486) (xy 118.165816 -233.803626) (xy 118.218966 -233.799643)
			(xy 118.272116 -233.803626) (xy 118.324078 -233.815486) (xy 118.373692 -233.834958) (xy 118.41985 -233.861607)
			(xy 118.461521 -233.894838) (xy 118.497773 -233.933909) (xy 118.527797 -233.977946) (xy 118.550923 -234.025967)
			(xy 118.566633 -234.076897) (xy 118.574576 -234.129601) (xy 118.575074 -234.15625) (xy 118.574576 -234.182899)
			(xy 118.803156 -234.182899) (xy 118.803156 -234.129601) (xy 118.811099 -234.076897) (xy 118.826809 -234.025967)
			(xy 118.849935 -233.977946) (xy 118.879959 -233.933909) (xy 118.916211 -233.894838) (xy 118.957882 -233.861607)
			(xy 119.00404 -233.834958) (xy 119.053654 -233.815486) (xy 119.105616 -233.803626) (xy 119.158766 -233.799643)
			(xy 119.211916 -233.803626) (xy 119.263878 -233.815486) (xy 119.313492 -233.834958) (xy 119.35965 -233.861607)
			(xy 119.401321 -233.894838) (xy 119.437573 -233.933909) (xy 119.467597 -233.977946) (xy 119.490723 -234.025967)
			(xy 119.506433 -234.076897) (xy 119.514376 -234.129601) (xy 119.514874 -234.15625) (xy 119.514376 -234.182899)
			(xy 119.742956 -234.182899) (xy 119.742956 -234.129601) (xy 119.750899 -234.076897) (xy 119.766609 -234.025967)
			(xy 119.789735 -233.977946) (xy 119.819759 -233.933909) (xy 119.856011 -233.894838) (xy 119.897682 -233.861607)
			(xy 119.94384 -233.834958) (xy 119.993454 -233.815486) (xy 120.045416 -233.803626) (xy 120.098566 -233.799643)
			(xy 120.151716 -233.803626) (xy 120.203678 -233.815486) (xy 120.253292 -233.834958) (xy 120.29945 -233.861607)
			(xy 120.341121 -233.894838) (xy 120.377373 -233.933909) (xy 120.407397 -233.977946) (xy 120.430523 -234.025967)
			(xy 120.446233 -234.076897) (xy 120.454176 -234.129601) (xy 120.454674 -234.15625) (xy 120.454176 -234.182899)
			(xy 120.682502 -234.182899) (xy 120.682502 -234.129601) (xy 120.690445 -234.076897) (xy 120.706155 -234.025967)
			(xy 120.729281 -233.977946) (xy 120.759305 -233.933909) (xy 120.795557 -233.894838) (xy 120.837228 -233.861607)
			(xy 120.883386 -233.834958) (xy 120.933 -233.815486) (xy 120.984962 -233.803626) (xy 121.038112 -233.799643)
			(xy 121.091262 -233.803626) (xy 121.143224 -233.815486) (xy 121.192838 -233.834958) (xy 121.238996 -233.861607)
			(xy 121.280667 -233.894838) (xy 121.316919 -233.933909) (xy 121.346943 -233.977946) (xy 121.370069 -234.025967)
			(xy 121.385779 -234.076897) (xy 121.393722 -234.129601) (xy 121.39422 -234.15625) (xy 121.393722 -234.182899)
			(xy 121.622556 -234.182899) (xy 121.622556 -234.129601) (xy 121.630499 -234.076897) (xy 121.646209 -234.025967)
			(xy 121.669335 -233.977946) (xy 121.699359 -233.933909) (xy 121.735611 -233.894838) (xy 121.777282 -233.861607)
			(xy 121.82344 -233.834958) (xy 121.873054 -233.815486) (xy 121.925016 -233.803626) (xy 121.978166 -233.799643)
			(xy 122.031316 -233.803626) (xy 122.083278 -233.815486) (xy 122.132892 -233.834958) (xy 122.17905 -233.861607)
			(xy 122.220721 -233.894838) (xy 122.256973 -233.933909) (xy 122.286997 -233.977946) (xy 122.310123 -234.025967)
			(xy 122.325833 -234.076897) (xy 122.333776 -234.129601) (xy 122.334274 -234.15625) (xy 122.333776 -234.182899)
			(xy 122.562102 -234.182899) (xy 122.562102 -234.129601) (xy 122.570045 -234.076897) (xy 122.585755 -234.025967)
			(xy 122.608881 -233.977946) (xy 122.638905 -233.933909) (xy 122.675157 -233.894838) (xy 122.716828 -233.861607)
			(xy 122.762986 -233.834958) (xy 122.8126 -233.815486) (xy 122.864562 -233.803626) (xy 122.917712 -233.799643)
			(xy 122.970862 -233.803626) (xy 123.022824 -233.815486) (xy 123.072438 -233.834958) (xy 123.118596 -233.861607)
			(xy 123.160267 -233.894838) (xy 123.196519 -233.933909) (xy 123.226543 -233.977946) (xy 123.249669 -234.025967)
			(xy 123.265379 -234.076897) (xy 123.273322 -234.129601) (xy 123.27382 -234.15625) (xy 123.273322 -234.182899)
			(xy 123.502156 -234.182899) (xy 123.502156 -234.129601) (xy 123.510099 -234.076897) (xy 123.525809 -234.025967)
			(xy 123.548935 -233.977946) (xy 123.578959 -233.933909) (xy 123.615211 -233.894838) (xy 123.656882 -233.861607)
			(xy 123.70304 -233.834958) (xy 123.752654 -233.815486) (xy 123.804616 -233.803626) (xy 123.857766 -233.799643)
			(xy 123.910916 -233.803626) (xy 123.962878 -233.815486) (xy 124.012492 -233.834958) (xy 124.05865 -233.861607)
			(xy 124.100321 -233.894838) (xy 124.136573 -233.933909) (xy 124.166597 -233.977946) (xy 124.189723 -234.025967)
			(xy 124.205433 -234.076897) (xy 124.213376 -234.129601) (xy 124.213874 -234.15625) (xy 124.213376 -234.182899)
			(xy 124.441956 -234.182899) (xy 124.441956 -234.129601) (xy 124.449899 -234.076897) (xy 124.465609 -234.025967)
			(xy 124.488735 -233.977946) (xy 124.518759 -233.933909) (xy 124.555011 -233.894838) (xy 124.596682 -233.861607)
			(xy 124.64284 -233.834958) (xy 124.692454 -233.815486) (xy 124.744416 -233.803626) (xy 124.797566 -233.799643)
			(xy 124.850716 -233.803626) (xy 124.902678 -233.815486) (xy 124.952292 -233.834958) (xy 124.99845 -233.861607)
			(xy 125.040121 -233.894838) (xy 125.076373 -233.933909) (xy 125.106397 -233.977946) (xy 125.129523 -234.025967)
			(xy 125.145233 -234.076897) (xy 125.153176 -234.129601) (xy 125.153674 -234.15625) (xy 125.153176 -234.182899)
			(xy 125.381756 -234.182899) (xy 125.381756 -234.129601) (xy 125.389699 -234.076897) (xy 125.405409 -234.025967)
			(xy 125.428535 -233.977946) (xy 125.458559 -233.933909) (xy 125.494811 -233.894838) (xy 125.536482 -233.861607)
			(xy 125.58264 -233.834958) (xy 125.632254 -233.815486) (xy 125.684216 -233.803626) (xy 125.737366 -233.799643)
			(xy 125.790516 -233.803626) (xy 125.842478 -233.815486) (xy 125.892092 -233.834958) (xy 125.93825 -233.861607)
			(xy 125.979921 -233.894838) (xy 126.016173 -233.933909) (xy 126.046197 -233.977946) (xy 126.069323 -234.025967)
			(xy 126.085033 -234.076897) (xy 126.092976 -234.129601) (xy 126.093474 -234.15625) (xy 126.092976 -234.182899)
			(xy 126.321556 -234.182899) (xy 126.321556 -234.129601) (xy 126.329499 -234.076897) (xy 126.345209 -234.025967)
			(xy 126.368335 -233.977946) (xy 126.398359 -233.933909) (xy 126.434611 -233.894838) (xy 126.476282 -233.861607)
			(xy 126.52244 -233.834958) (xy 126.572054 -233.815486) (xy 126.624016 -233.803626) (xy 126.677166 -233.799643)
			(xy 126.730316 -233.803626) (xy 126.782278 -233.815486) (xy 126.831892 -233.834958) (xy 126.87805 -233.861607)
			(xy 126.919721 -233.894838) (xy 126.955973 -233.933909) (xy 126.985997 -233.977946) (xy 127.009123 -234.025967)
			(xy 127.024833 -234.076897) (xy 127.032776 -234.129601) (xy 127.033274 -234.15625) (xy 127.032776 -234.182899)
			(xy 127.261356 -234.182899) (xy 127.261356 -234.129601) (xy 127.269299 -234.076897) (xy 127.285009 -234.025967)
			(xy 127.308135 -233.977946) (xy 127.338159 -233.933909) (xy 127.374411 -233.894838) (xy 127.416082 -233.861607)
			(xy 127.46224 -233.834958) (xy 127.511854 -233.815486) (xy 127.563816 -233.803626) (xy 127.616966 -233.799643)
			(xy 127.670116 -233.803626) (xy 127.722078 -233.815486) (xy 127.771692 -233.834958) (xy 127.81785 -233.861607)
			(xy 127.859521 -233.894838) (xy 127.895773 -233.933909) (xy 127.925797 -233.977946) (xy 127.948923 -234.025967)
			(xy 127.964633 -234.076897) (xy 127.972576 -234.129601) (xy 127.973074 -234.15625) (xy 127.972576 -234.182899)
			(xy 128.201156 -234.182899) (xy 128.201156 -234.129601) (xy 128.209099 -234.076897) (xy 128.224809 -234.025967)
			(xy 128.247935 -233.977946) (xy 128.277959 -233.933909) (xy 128.314211 -233.894838) (xy 128.355882 -233.861607)
			(xy 128.40204 -233.834958) (xy 128.451654 -233.815486) (xy 128.503616 -233.803626) (xy 128.556766 -233.799643)
			(xy 128.609916 -233.803626) (xy 128.661878 -233.815486) (xy 128.711492 -233.834958) (xy 128.75765 -233.861607)
			(xy 128.799321 -233.894838) (xy 128.835573 -233.933909) (xy 128.865597 -233.977946) (xy 128.888723 -234.025967)
			(xy 128.904433 -234.076897) (xy 128.912376 -234.129601) (xy 128.912874 -234.15625) (xy 128.912376 -234.182899)
			(xy 129.140702 -234.182899) (xy 129.140702 -234.129601) (xy 129.148645 -234.076897) (xy 129.164355 -234.025967)
			(xy 129.187481 -233.977946) (xy 129.217505 -233.933909) (xy 129.253757 -233.894838) (xy 129.295428 -233.861607)
			(xy 129.341586 -233.834958) (xy 129.3912 -233.815486) (xy 129.443162 -233.803626) (xy 129.496312 -233.799643)
			(xy 129.549462 -233.803626) (xy 129.601424 -233.815486) (xy 129.651038 -233.834958) (xy 129.697196 -233.861607)
			(xy 129.738867 -233.894838) (xy 129.775119 -233.933909) (xy 129.805143 -233.977946) (xy 129.828269 -234.025967)
			(xy 129.843979 -234.076897) (xy 129.851922 -234.129601) (xy 129.85242 -234.15625) (xy 129.851922 -234.182899)
			(xy 130.080756 -234.182899) (xy 130.080756 -234.129601) (xy 130.088699 -234.076897) (xy 130.104409 -234.025967)
			(xy 130.127535 -233.977946) (xy 130.157559 -233.933909) (xy 130.193811 -233.894838) (xy 130.235482 -233.861607)
			(xy 130.28164 -233.834958) (xy 130.331254 -233.815486) (xy 130.383216 -233.803626) (xy 130.436366 -233.799643)
			(xy 130.489516 -233.803626) (xy 130.541478 -233.815486) (xy 130.591092 -233.834958) (xy 130.63725 -233.861607)
			(xy 130.678921 -233.894838) (xy 130.715173 -233.933909) (xy 130.745197 -233.977946) (xy 130.768323 -234.025967)
			(xy 130.784033 -234.076897) (xy 130.791976 -234.129601) (xy 130.792474 -234.15625) (xy 130.791976 -234.182899)
			(xy 131.020556 -234.182899) (xy 131.020556 -234.129601) (xy 131.028499 -234.076897) (xy 131.044209 -234.025967)
			(xy 131.067335 -233.977946) (xy 131.097359 -233.933909) (xy 131.133611 -233.894838) (xy 131.175282 -233.861607)
			(xy 131.22144 -233.834958) (xy 131.271054 -233.815486) (xy 131.323016 -233.803626) (xy 131.376166 -233.799643)
			(xy 131.429316 -233.803626) (xy 131.481278 -233.815486) (xy 131.530892 -233.834958) (xy 131.57705 -233.861607)
			(xy 131.618721 -233.894838) (xy 131.654973 -233.933909) (xy 131.684997 -233.977946) (xy 131.708123 -234.025967)
			(xy 131.723833 -234.076897) (xy 131.731776 -234.129601) (xy 131.732274 -234.15625) (xy 131.731776 -234.182899)
			(xy 131.960356 -234.182899) (xy 131.960356 -234.129601) (xy 131.968299 -234.076897) (xy 131.984009 -234.025967)
			(xy 132.007135 -233.977946) (xy 132.037159 -233.933909) (xy 132.073411 -233.894838) (xy 132.115082 -233.861607)
			(xy 132.16124 -233.834958) (xy 132.210854 -233.815486) (xy 132.262816 -233.803626) (xy 132.315966 -233.799643)
			(xy 132.369116 -233.803626) (xy 132.421078 -233.815486) (xy 132.470692 -233.834958) (xy 132.51685 -233.861607)
			(xy 132.558521 -233.894838) (xy 132.594773 -233.933909) (xy 132.624797 -233.977946) (xy 132.647923 -234.025967)
			(xy 132.663633 -234.076897) (xy 132.671576 -234.129601) (xy 132.672074 -234.15625) (xy 132.671576 -234.182899)
			(xy 132.900156 -234.182899) (xy 132.900156 -234.129601) (xy 132.908099 -234.076897) (xy 132.923809 -234.025967)
			(xy 132.946935 -233.977946) (xy 132.976959 -233.933909) (xy 133.013211 -233.894838) (xy 133.054882 -233.861607)
			(xy 133.10104 -233.834958) (xy 133.150654 -233.815486) (xy 133.202616 -233.803626) (xy 133.255766 -233.799643)
			(xy 133.308916 -233.803626) (xy 133.360878 -233.815486) (xy 133.410492 -233.834958) (xy 133.45665 -233.861607)
			(xy 133.498321 -233.894838) (xy 133.534573 -233.933909) (xy 133.564597 -233.977946) (xy 133.587723 -234.025967)
			(xy 133.603433 -234.076897) (xy 133.611376 -234.129601) (xy 133.611874 -234.15625) (xy 133.611376 -234.182899)
			(xy 133.839956 -234.182899) (xy 133.839956 -234.129601) (xy 133.847899 -234.076897) (xy 133.863609 -234.025967)
			(xy 133.886735 -233.977946) (xy 133.916759 -233.933909) (xy 133.953011 -233.894838) (xy 133.994682 -233.861607)
			(xy 134.04084 -233.834958) (xy 134.090454 -233.815486) (xy 134.142416 -233.803626) (xy 134.195566 -233.799643)
			(xy 134.248716 -233.803626) (xy 134.300678 -233.815486) (xy 134.350292 -233.834958) (xy 134.39645 -233.861607)
			(xy 134.438121 -233.894838) (xy 134.474373 -233.933909) (xy 134.504397 -233.977946) (xy 134.527523 -234.025967)
			(xy 134.543233 -234.076897) (xy 134.551176 -234.129601) (xy 134.551674 -234.15625) (xy 134.551176 -234.182899)
			(xy 134.543233 -234.235603) (xy 134.527523 -234.286533) (xy 134.504397 -234.334554) (xy 134.474373 -234.378591)
			(xy 134.438121 -234.417662) (xy 134.39645 -234.450893) (xy 134.350292 -234.477542) (xy 134.300678 -234.497014)
			(xy 134.248716 -234.508874) (xy 134.195566 -234.512858) (xy 134.142416 -234.508874) (xy 134.090454 -234.497014)
			(xy 134.04084 -234.477542) (xy 133.994682 -234.450893) (xy 133.953011 -234.417662) (xy 133.916759 -234.378591)
			(xy 133.886735 -234.334554) (xy 133.863609 -234.286533) (xy 133.847899 -234.235603) (xy 133.839956 -234.182899)
			(xy 133.611376 -234.182899) (xy 133.603433 -234.235603) (xy 133.587723 -234.286533) (xy 133.564597 -234.334554)
			(xy 133.534573 -234.378591) (xy 133.498321 -234.417662) (xy 133.45665 -234.450893) (xy 133.410492 -234.477542)
			(xy 133.360878 -234.497014) (xy 133.308916 -234.508874) (xy 133.255766 -234.512858) (xy 133.202616 -234.508874)
			(xy 133.150654 -234.497014) (xy 133.10104 -234.477542) (xy 133.054882 -234.450893) (xy 133.013211 -234.417662)
			(xy 132.976959 -234.378591) (xy 132.946935 -234.334554) (xy 132.923809 -234.286533) (xy 132.908099 -234.235603)
			(xy 132.900156 -234.182899) (xy 132.671576 -234.182899) (xy 132.663633 -234.235603) (xy 132.647923 -234.286533)
			(xy 132.624797 -234.334554) (xy 132.594773 -234.378591) (xy 132.558521 -234.417662) (xy 132.51685 -234.450893)
			(xy 132.470692 -234.477542) (xy 132.421078 -234.497014) (xy 132.369116 -234.508874) (xy 132.315966 -234.512858)
			(xy 132.262816 -234.508874) (xy 132.210854 -234.497014) (xy 132.16124 -234.477542) (xy 132.115082 -234.450893)
			(xy 132.073411 -234.417662) (xy 132.037159 -234.378591) (xy 132.007135 -234.334554) (xy 131.984009 -234.286533)
			(xy 131.968299 -234.235603) (xy 131.960356 -234.182899) (xy 131.731776 -234.182899) (xy 131.723833 -234.235603)
			(xy 131.708123 -234.286533) (xy 131.684997 -234.334554) (xy 131.654973 -234.378591) (xy 131.618721 -234.417662)
			(xy 131.57705 -234.450893) (xy 131.530892 -234.477542) (xy 131.481278 -234.497014) (xy 131.429316 -234.508874)
			(xy 131.376166 -234.512858) (xy 131.323016 -234.508874) (xy 131.271054 -234.497014) (xy 131.22144 -234.477542)
			(xy 131.175282 -234.450893) (xy 131.133611 -234.417662) (xy 131.097359 -234.378591) (xy 131.067335 -234.334554)
			(xy 131.044209 -234.286533) (xy 131.028499 -234.235603) (xy 131.020556 -234.182899) (xy 130.791976 -234.182899)
			(xy 130.784033 -234.235603) (xy 130.768323 -234.286533) (xy 130.745197 -234.334554) (xy 130.715173 -234.378591)
			(xy 130.678921 -234.417662) (xy 130.63725 -234.450893) (xy 130.591092 -234.477542) (xy 130.541478 -234.497014)
			(xy 130.489516 -234.508874) (xy 130.436366 -234.512858) (xy 130.383216 -234.508874) (xy 130.331254 -234.497014)
			(xy 130.28164 -234.477542) (xy 130.235482 -234.450893) (xy 130.193811 -234.417662) (xy 130.157559 -234.378591)
			(xy 130.127535 -234.334554) (xy 130.104409 -234.286533) (xy 130.088699 -234.235603) (xy 130.080756 -234.182899)
			(xy 129.851922 -234.182899) (xy 129.843979 -234.235603) (xy 129.828269 -234.286533) (xy 129.805143 -234.334554)
			(xy 129.775119 -234.378591) (xy 129.738867 -234.417662) (xy 129.697196 -234.450893) (xy 129.651038 -234.477542)
			(xy 129.601424 -234.497014) (xy 129.549462 -234.508874) (xy 129.496312 -234.512858) (xy 129.443162 -234.508874)
			(xy 129.3912 -234.497014) (xy 129.341586 -234.477542) (xy 129.295428 -234.450893) (xy 129.253757 -234.417662)
			(xy 129.217505 -234.378591) (xy 129.187481 -234.334554) (xy 129.164355 -234.286533) (xy 129.148645 -234.235603)
			(xy 129.140702 -234.182899) (xy 128.912376 -234.182899) (xy 128.904433 -234.235603) (xy 128.888723 -234.286533)
			(xy 128.865597 -234.334554) (xy 128.835573 -234.378591) (xy 128.799321 -234.417662) (xy 128.75765 -234.450893)
			(xy 128.711492 -234.477542) (xy 128.661878 -234.497014) (xy 128.609916 -234.508874) (xy 128.556766 -234.512858)
			(xy 128.503616 -234.508874) (xy 128.451654 -234.497014) (xy 128.40204 -234.477542) (xy 128.355882 -234.450893)
			(xy 128.314211 -234.417662) (xy 128.277959 -234.378591) (xy 128.247935 -234.334554) (xy 128.224809 -234.286533)
			(xy 128.209099 -234.235603) (xy 128.201156 -234.182899) (xy 127.972576 -234.182899) (xy 127.964633 -234.235603)
			(xy 127.948923 -234.286533) (xy 127.925797 -234.334554) (xy 127.895773 -234.378591) (xy 127.859521 -234.417662)
			(xy 127.81785 -234.450893) (xy 127.771692 -234.477542) (xy 127.722078 -234.497014) (xy 127.670116 -234.508874)
			(xy 127.616966 -234.512858) (xy 127.563816 -234.508874) (xy 127.511854 -234.497014) (xy 127.46224 -234.477542)
			(xy 127.416082 -234.450893) (xy 127.374411 -234.417662) (xy 127.338159 -234.378591) (xy 127.308135 -234.334554)
			(xy 127.285009 -234.286533) (xy 127.269299 -234.235603) (xy 127.261356 -234.182899) (xy 127.032776 -234.182899)
			(xy 127.024833 -234.235603) (xy 127.009123 -234.286533) (xy 126.985997 -234.334554) (xy 126.955973 -234.378591)
			(xy 126.919721 -234.417662) (xy 126.87805 -234.450893) (xy 126.831892 -234.477542) (xy 126.782278 -234.497014)
			(xy 126.730316 -234.508874) (xy 126.677166 -234.512858) (xy 126.624016 -234.508874) (xy 126.572054 -234.497014)
			(xy 126.52244 -234.477542) (xy 126.476282 -234.450893) (xy 126.434611 -234.417662) (xy 126.398359 -234.378591)
			(xy 126.368335 -234.334554) (xy 126.345209 -234.286533) (xy 126.329499 -234.235603) (xy 126.321556 -234.182899)
			(xy 126.092976 -234.182899) (xy 126.085033 -234.235603) (xy 126.069323 -234.286533) (xy 126.046197 -234.334554)
			(xy 126.016173 -234.378591) (xy 125.979921 -234.417662) (xy 125.93825 -234.450893) (xy 125.892092 -234.477542)
			(xy 125.842478 -234.497014) (xy 125.790516 -234.508874) (xy 125.737366 -234.512858) (xy 125.684216 -234.508874)
			(xy 125.632254 -234.497014) (xy 125.58264 -234.477542) (xy 125.536482 -234.450893) (xy 125.494811 -234.417662)
			(xy 125.458559 -234.378591) (xy 125.428535 -234.334554) (xy 125.405409 -234.286533) (xy 125.389699 -234.235603)
			(xy 125.381756 -234.182899) (xy 125.153176 -234.182899) (xy 125.145233 -234.235603) (xy 125.129523 -234.286533)
			(xy 125.106397 -234.334554) (xy 125.076373 -234.378591) (xy 125.040121 -234.417662) (xy 124.99845 -234.450893)
			(xy 124.952292 -234.477542) (xy 124.902678 -234.497014) (xy 124.850716 -234.508874) (xy 124.797566 -234.512858)
			(xy 124.744416 -234.508874) (xy 124.692454 -234.497014) (xy 124.64284 -234.477542) (xy 124.596682 -234.450893)
			(xy 124.555011 -234.417662) (xy 124.518759 -234.378591) (xy 124.488735 -234.334554) (xy 124.465609 -234.286533)
			(xy 124.449899 -234.235603) (xy 124.441956 -234.182899) (xy 124.213376 -234.182899) (xy 124.205433 -234.235603)
			(xy 124.189723 -234.286533) (xy 124.166597 -234.334554) (xy 124.136573 -234.378591) (xy 124.100321 -234.417662)
			(xy 124.05865 -234.450893) (xy 124.012492 -234.477542) (xy 123.962878 -234.497014) (xy 123.910916 -234.508874)
			(xy 123.857766 -234.512858) (xy 123.804616 -234.508874) (xy 123.752654 -234.497014) (xy 123.70304 -234.477542)
			(xy 123.656882 -234.450893) (xy 123.615211 -234.417662) (xy 123.578959 -234.378591) (xy 123.548935 -234.334554)
			(xy 123.525809 -234.286533) (xy 123.510099 -234.235603) (xy 123.502156 -234.182899) (xy 123.273322 -234.182899)
			(xy 123.265379 -234.235603) (xy 123.249669 -234.286533) (xy 123.226543 -234.334554) (xy 123.196519 -234.378591)
			(xy 123.160267 -234.417662) (xy 123.118596 -234.450893) (xy 123.072438 -234.477542) (xy 123.022824 -234.497014)
			(xy 122.970862 -234.508874) (xy 122.917712 -234.512858) (xy 122.864562 -234.508874) (xy 122.8126 -234.497014)
			(xy 122.762986 -234.477542) (xy 122.716828 -234.450893) (xy 122.675157 -234.417662) (xy 122.638905 -234.378591)
			(xy 122.608881 -234.334554) (xy 122.585755 -234.286533) (xy 122.570045 -234.235603) (xy 122.562102 -234.182899)
			(xy 122.333776 -234.182899) (xy 122.325833 -234.235603) (xy 122.310123 -234.286533) (xy 122.286997 -234.334554)
			(xy 122.256973 -234.378591) (xy 122.220721 -234.417662) (xy 122.17905 -234.450893) (xy 122.132892 -234.477542)
			(xy 122.083278 -234.497014) (xy 122.031316 -234.508874) (xy 121.978166 -234.512858) (xy 121.925016 -234.508874)
			(xy 121.873054 -234.497014) (xy 121.82344 -234.477542) (xy 121.777282 -234.450893) (xy 121.735611 -234.417662)
			(xy 121.699359 -234.378591) (xy 121.669335 -234.334554) (xy 121.646209 -234.286533) (xy 121.630499 -234.235603)
			(xy 121.622556 -234.182899) (xy 121.393722 -234.182899) (xy 121.385779 -234.235603) (xy 121.370069 -234.286533)
			(xy 121.346943 -234.334554) (xy 121.316919 -234.378591) (xy 121.280667 -234.417662) (xy 121.238996 -234.450893)
			(xy 121.192838 -234.477542) (xy 121.143224 -234.497014) (xy 121.091262 -234.508874) (xy 121.038112 -234.512858)
			(xy 120.984962 -234.508874) (xy 120.933 -234.497014) (xy 120.883386 -234.477542) (xy 120.837228 -234.450893)
			(xy 120.795557 -234.417662) (xy 120.759305 -234.378591) (xy 120.729281 -234.334554) (xy 120.706155 -234.286533)
			(xy 120.690445 -234.235603) (xy 120.682502 -234.182899) (xy 120.454176 -234.182899) (xy 120.446233 -234.235603)
			(xy 120.430523 -234.286533) (xy 120.407397 -234.334554) (xy 120.377373 -234.378591) (xy 120.341121 -234.417662)
			(xy 120.29945 -234.450893) (xy 120.253292 -234.477542) (xy 120.203678 -234.497014) (xy 120.151716 -234.508874)
			(xy 120.098566 -234.512858) (xy 120.045416 -234.508874) (xy 119.993454 -234.497014) (xy 119.94384 -234.477542)
			(xy 119.897682 -234.450893) (xy 119.856011 -234.417662) (xy 119.819759 -234.378591) (xy 119.789735 -234.334554)
			(xy 119.766609 -234.286533) (xy 119.750899 -234.235603) (xy 119.742956 -234.182899) (xy 119.514376 -234.182899)
			(xy 119.506433 -234.235603) (xy 119.490723 -234.286533) (xy 119.467597 -234.334554) (xy 119.437573 -234.378591)
			(xy 119.401321 -234.417662) (xy 119.35965 -234.450893) (xy 119.313492 -234.477542) (xy 119.263878 -234.497014)
			(xy 119.211916 -234.508874) (xy 119.158766 -234.512858) (xy 119.105616 -234.508874) (xy 119.053654 -234.497014)
			(xy 119.00404 -234.477542) (xy 118.957882 -234.450893) (xy 118.916211 -234.417662) (xy 118.879959 -234.378591)
			(xy 118.849935 -234.334554) (xy 118.826809 -234.286533) (xy 118.811099 -234.235603) (xy 118.803156 -234.182899)
			(xy 118.574576 -234.182899) (xy 118.566633 -234.235603) (xy 118.550923 -234.286533) (xy 118.527797 -234.334554)
			(xy 118.497773 -234.378591) (xy 118.461521 -234.417662) (xy 118.41985 -234.450893) (xy 118.373692 -234.477542)
			(xy 118.324078 -234.497014) (xy 118.272116 -234.508874) (xy 118.218966 -234.512858) (xy 118.165816 -234.508874)
			(xy 118.113854 -234.497014) (xy 118.06424 -234.477542) (xy 118.018082 -234.450893) (xy 117.976411 -234.417662)
			(xy 117.940159 -234.378591) (xy 117.910135 -234.334554) (xy 117.887009 -234.286533) (xy 117.871299 -234.235603)
			(xy 117.863356 -234.182899) (xy 117.634776 -234.182899) (xy 117.626833 -234.235603) (xy 117.611123 -234.286533)
			(xy 117.587997 -234.334554) (xy 117.557973 -234.378591) (xy 117.521721 -234.417662) (xy 117.48005 -234.450893)
			(xy 117.433892 -234.477542) (xy 117.384278 -234.497014) (xy 117.332316 -234.508874) (xy 117.279166 -234.512858)
			(xy 117.226016 -234.508874) (xy 117.174054 -234.497014) (xy 117.12444 -234.477542) (xy 117.078282 -234.450893)
			(xy 117.036611 -234.417662) (xy 117.000359 -234.378591) (xy 116.970335 -234.334554) (xy 116.947209 -234.286533)
			(xy 116.931499 -234.235603) (xy 116.923556 -234.182899) (xy 116.694976 -234.182899) (xy 116.687033 -234.235603)
			(xy 116.671323 -234.286533) (xy 116.648197 -234.334554) (xy 116.618173 -234.378591) (xy 116.581921 -234.417662)
			(xy 116.54025 -234.450893) (xy 116.494092 -234.477542) (xy 116.444478 -234.497014) (xy 116.392516 -234.508874)
			(xy 116.339366 -234.512858) (xy 116.286216 -234.508874) (xy 116.234254 -234.497014) (xy 116.18464 -234.477542)
			(xy 116.138482 -234.450893) (xy 116.096811 -234.417662) (xy 116.060559 -234.378591) (xy 116.030535 -234.334554)
			(xy 116.007409 -234.286533) (xy 115.991699 -234.235603) (xy 115.983756 -234.182899) (xy 115.755176 -234.182899)
			(xy 115.747233 -234.235603) (xy 115.731523 -234.286533) (xy 115.708397 -234.334554) (xy 115.678373 -234.378591)
			(xy 115.642121 -234.417662) (xy 115.60045 -234.450893) (xy 115.554292 -234.477542) (xy 115.504678 -234.497014)
			(xy 115.452716 -234.508874) (xy 115.399566 -234.512858) (xy 115.346416 -234.508874) (xy 115.294454 -234.497014)
			(xy 115.24484 -234.477542) (xy 115.198682 -234.450893) (xy 115.157011 -234.417662) (xy 115.120759 -234.378591)
			(xy 115.090735 -234.334554) (xy 115.067609 -234.286533) (xy 115.051899 -234.235603) (xy 115.043956 -234.182899)
			(xy 114.815376 -234.182899) (xy 114.807433 -234.235603) (xy 114.791723 -234.286533) (xy 114.768597 -234.334554)
			(xy 114.738573 -234.378591) (xy 114.702321 -234.417662) (xy 114.66065 -234.450893) (xy 114.614492 -234.477542)
			(xy 114.564878 -234.497014) (xy 114.512916 -234.508874) (xy 114.459766 -234.512858) (xy 114.406616 -234.508874)
			(xy 114.354654 -234.497014) (xy 114.30504 -234.477542) (xy 114.258882 -234.450893) (xy 114.217211 -234.417662)
			(xy 114.180959 -234.378591) (xy 114.150935 -234.334554) (xy 114.127809 -234.286533) (xy 114.112099 -234.235603)
			(xy 114.104156 -234.182899) (xy 113.875576 -234.182899) (xy 113.867633 -234.235603) (xy 113.851923 -234.286533)
			(xy 113.828797 -234.334554) (xy 113.798773 -234.378591) (xy 113.762521 -234.417662) (xy 113.72085 -234.450893)
			(xy 113.674692 -234.477542) (xy 113.625078 -234.497014) (xy 113.573116 -234.508874) (xy 113.519966 -234.512858)
			(xy 113.466816 -234.508874) (xy 113.414854 -234.497014) (xy 113.36524 -234.477542) (xy 113.319082 -234.450893)
			(xy 113.277411 -234.417662) (xy 113.241159 -234.378591) (xy 113.211135 -234.334554) (xy 113.188009 -234.286533)
			(xy 113.172299 -234.235603) (xy 113.164356 -234.182899) (xy 112.935776 -234.182899) (xy 112.927833 -234.235603)
			(xy 112.912123 -234.286533) (xy 112.888997 -234.334554) (xy 112.858973 -234.378591) (xy 112.822721 -234.417662)
			(xy 112.78105 -234.450893) (xy 112.734892 -234.477542) (xy 112.685278 -234.497014) (xy 112.633316 -234.508874)
			(xy 112.580166 -234.512858) (xy 112.527016 -234.508874) (xy 112.475054 -234.497014) (xy 112.42544 -234.477542)
			(xy 112.379282 -234.450893) (xy 112.337611 -234.417662) (xy 112.301359 -234.378591) (xy 112.271335 -234.334554)
			(xy 112.248209 -234.286533) (xy 112.232499 -234.235603) (xy 112.224556 -234.182899) (xy 111.995976 -234.182899)
			(xy 111.988033 -234.235603) (xy 111.972323 -234.286533) (xy 111.949197 -234.334554) (xy 111.919173 -234.378591)
			(xy 111.882921 -234.417662) (xy 111.84125 -234.450893) (xy 111.795092 -234.477542) (xy 111.745478 -234.497014)
			(xy 111.693516 -234.508874) (xy 111.640366 -234.512858) (xy 111.587216 -234.508874) (xy 111.535254 -234.497014)
			(xy 111.48564 -234.477542) (xy 111.439482 -234.450893) (xy 111.397811 -234.417662) (xy 111.361559 -234.378591)
			(xy 111.331535 -234.334554) (xy 111.308409 -234.286533) (xy 111.292699 -234.235603) (xy 111.284756 -234.182899)
			(xy 111.056176 -234.182899) (xy 111.048233 -234.235603) (xy 111.032523 -234.286533) (xy 111.009397 -234.334554)
			(xy 110.979373 -234.378591) (xy 110.943121 -234.417662) (xy 110.90145 -234.450893) (xy 110.855292 -234.477542)
			(xy 110.805678 -234.497014) (xy 110.753716 -234.508874) (xy 110.700566 -234.512858) (xy 110.647416 -234.508874)
			(xy 110.595454 -234.497014) (xy 110.54584 -234.477542) (xy 110.499682 -234.450893) (xy 110.458011 -234.417662)
			(xy 110.421759 -234.378591) (xy 110.391735 -234.334554) (xy 110.368609 -234.286533) (xy 110.352899 -234.235603)
			(xy 110.344956 -234.182899) (xy 110.116376 -234.182899) (xy 110.108433 -234.235603) (xy 110.092723 -234.286533)
			(xy 110.069597 -234.334554) (xy 110.039573 -234.378591) (xy 110.003321 -234.417662) (xy 109.96165 -234.450893)
			(xy 109.915492 -234.477542) (xy 109.865878 -234.497014) (xy 109.813916 -234.508874) (xy 109.760766 -234.512858)
			(xy 109.707616 -234.508874) (xy 109.655654 -234.497014) (xy 109.60604 -234.477542) (xy 109.559882 -234.450893)
			(xy 109.518211 -234.417662) (xy 109.481959 -234.378591) (xy 109.451935 -234.334554) (xy 109.428809 -234.286533)
			(xy 109.413099 -234.235603) (xy 109.405156 -234.182899) (xy 109.176576 -234.182899) (xy 109.168633 -234.235603)
			(xy 109.152923 -234.286533) (xy 109.129797 -234.334554) (xy 109.099773 -234.378591) (xy 109.063521 -234.417662)
			(xy 109.02185 -234.450893) (xy 108.975692 -234.477542) (xy 108.926078 -234.497014) (xy 108.874116 -234.508874)
			(xy 108.820966 -234.512858) (xy 108.767816 -234.508874) (xy 108.715854 -234.497014) (xy 108.66624 -234.477542)
			(xy 108.620082 -234.450893) (xy 108.578411 -234.417662) (xy 108.542159 -234.378591) (xy 108.512135 -234.334554)
			(xy 108.489009 -234.286533) (xy 108.473299 -234.235603) (xy 108.465356 -234.182899) (xy 108.236776 -234.182899)
			(xy 108.228833 -234.235603) (xy 108.213123 -234.286533) (xy 108.189997 -234.334554) (xy 108.159973 -234.378591)
			(xy 108.123721 -234.417662) (xy 108.08205 -234.450893) (xy 108.035892 -234.477542) (xy 107.986278 -234.497014)
			(xy 107.934316 -234.508874) (xy 107.881166 -234.512858) (xy 107.828016 -234.508874) (xy 107.776054 -234.497014)
			(xy 107.72644 -234.477542) (xy 107.680282 -234.450893) (xy 107.638611 -234.417662) (xy 107.602359 -234.378591)
			(xy 107.572335 -234.334554) (xy 107.549209 -234.286533) (xy 107.533499 -234.235603) (xy 107.525556 -234.182899)
			(xy 107.296976 -234.182899) (xy 107.289033 -234.235603) (xy 107.273323 -234.286533) (xy 107.250197 -234.334554)
			(xy 107.220173 -234.378591) (xy 107.183921 -234.417662) (xy 107.14225 -234.450893) (xy 107.096092 -234.477542)
			(xy 107.046478 -234.497014) (xy 106.994516 -234.508874) (xy 106.941366 -234.512858) (xy 106.888216 -234.508874)
			(xy 106.836254 -234.497014) (xy 106.78664 -234.477542) (xy 106.740482 -234.450893) (xy 106.698811 -234.417662)
			(xy 106.662559 -234.378591) (xy 106.632535 -234.334554) (xy 106.609409 -234.286533) (xy 106.593699 -234.235603)
			(xy 106.585756 -234.182899) (xy 106.357176 -234.182899) (xy 106.349233 -234.235603) (xy 106.333523 -234.286533)
			(xy 106.310397 -234.334554) (xy 106.280373 -234.378591) (xy 106.244121 -234.417662) (xy 106.20245 -234.450893)
			(xy 106.156292 -234.477542) (xy 106.106678 -234.497014) (xy 106.054716 -234.508874) (xy 106.001566 -234.512858)
			(xy 105.948416 -234.508874) (xy 105.896454 -234.497014) (xy 105.84684 -234.477542) (xy 105.800682 -234.450893)
			(xy 105.759011 -234.417662) (xy 105.722759 -234.378591) (xy 105.692735 -234.334554) (xy 105.669609 -234.286533)
			(xy 105.653899 -234.235603) (xy 105.645956 -234.182899) (xy 104.477576 -234.182899) (xy 104.469633 -234.235603)
			(xy 104.453923 -234.286533) (xy 104.430797 -234.334554) (xy 104.400773 -234.378591) (xy 104.364521 -234.417662)
			(xy 104.32285 -234.450893) (xy 104.276692 -234.477542) (xy 104.227078 -234.497014) (xy 104.175116 -234.508874)
			(xy 104.121966 -234.512858) (xy 104.068816 -234.508874) (xy 104.016854 -234.497014) (xy 103.96724 -234.477542)
			(xy 103.921082 -234.450893) (xy 103.879411 -234.417662) (xy 103.843159 -234.378591) (xy 103.813135 -234.334554)
			(xy 103.790009 -234.286533) (xy 103.774299 -234.235603) (xy 103.766356 -234.182899) (xy 103.537776 -234.182899)
			(xy 103.529833 -234.235603) (xy 103.514123 -234.286533) (xy 103.490997 -234.334554) (xy 103.460973 -234.378591)
			(xy 103.424721 -234.417662) (xy 103.38305 -234.450893) (xy 103.336892 -234.477542) (xy 103.287278 -234.497014)
			(xy 103.235316 -234.508874) (xy 103.182166 -234.512858) (xy 103.129016 -234.508874) (xy 103.077054 -234.497014)
			(xy 103.02744 -234.477542) (xy 102.981282 -234.450893) (xy 102.939611 -234.417662) (xy 102.903359 -234.378591)
			(xy 102.873335 -234.334554) (xy 102.850209 -234.286533) (xy 102.834499 -234.235603) (xy 102.826556 -234.182899)
			(xy 102.597976 -234.182899) (xy 102.590033 -234.235603) (xy 102.574323 -234.286533) (xy 102.551197 -234.334554)
			(xy 102.521173 -234.378591) (xy 102.484921 -234.417662) (xy 102.44325 -234.450893) (xy 102.397092 -234.477542)
			(xy 102.347478 -234.497014) (xy 102.295516 -234.508874) (xy 102.242366 -234.512858) (xy 102.189216 -234.508874)
			(xy 102.137254 -234.497014) (xy 102.08764 -234.477542) (xy 102.041482 -234.450893) (xy 101.999811 -234.417662)
			(xy 101.963559 -234.378591) (xy 101.933535 -234.334554) (xy 101.910409 -234.286533) (xy 101.894699 -234.235603)
			(xy 101.886756 -234.182899) (xy 101.657922 -234.182899) (xy 101.649979 -234.235603) (xy 101.634269 -234.286533)
			(xy 101.611143 -234.334554) (xy 101.581119 -234.378591) (xy 101.544867 -234.417662) (xy 101.503196 -234.450893)
			(xy 101.457038 -234.477542) (xy 101.407424 -234.497014) (xy 101.355462 -234.508874) (xy 101.302312 -234.512858)
			(xy 101.249162 -234.508874) (xy 101.1972 -234.497014) (xy 101.147586 -234.477542) (xy 101.101428 -234.450893)
			(xy 101.059757 -234.417662) (xy 101.023505 -234.378591) (xy 100.993481 -234.334554) (xy 100.970355 -234.286533)
			(xy 100.954645 -234.235603) (xy 100.946702 -234.182899) (xy 100.718376 -234.182899) (xy 100.710433 -234.235603)
			(xy 100.694723 -234.286533) (xy 100.671597 -234.334554) (xy 100.641573 -234.378591) (xy 100.605321 -234.417662)
			(xy 100.56365 -234.450893) (xy 100.517492 -234.477542) (xy 100.467878 -234.497014) (xy 100.415916 -234.508874)
			(xy 100.362766 -234.512858) (xy 100.309616 -234.508874) (xy 100.257654 -234.497014) (xy 100.20804 -234.477542)
			(xy 100.161882 -234.450893) (xy 100.120211 -234.417662) (xy 100.083959 -234.378591) (xy 100.053935 -234.334554)
			(xy 100.030809 -234.286533) (xy 100.015099 -234.235603) (xy 100.007156 -234.182899) (xy 99.778576 -234.182899)
			(xy 99.770633 -234.235603) (xy 99.754923 -234.286533) (xy 99.731797 -234.334554) (xy 99.701773 -234.378591)
			(xy 99.665521 -234.417662) (xy 99.62385 -234.450893) (xy 99.577692 -234.477542) (xy 99.528078 -234.497014)
			(xy 99.476116 -234.508874) (xy 99.422966 -234.512858) (xy 99.369816 -234.508874) (xy 99.317854 -234.497014)
			(xy 99.26824 -234.477542) (xy 99.222082 -234.450893) (xy 99.180411 -234.417662) (xy 99.144159 -234.378591)
			(xy 99.114135 -234.334554) (xy 99.091009 -234.286533) (xy 99.075299 -234.235603) (xy 99.067356 -234.182899)
			(xy 98.838776 -234.182899) (xy 98.830833 -234.235603) (xy 98.815123 -234.286533) (xy 98.791997 -234.334554)
			(xy 98.761973 -234.378591) (xy 98.725721 -234.417662) (xy 98.68405 -234.450893) (xy 98.637892 -234.477542)
			(xy 98.588278 -234.497014) (xy 98.536316 -234.508874) (xy 98.483166 -234.512858) (xy 98.430016 -234.508874)
			(xy 98.378054 -234.497014) (xy 98.32844 -234.477542) (xy 98.282282 -234.450893) (xy 98.240611 -234.417662)
			(xy 98.204359 -234.378591) (xy 98.174335 -234.334554) (xy 98.151209 -234.286533) (xy 98.135499 -234.235603)
			(xy 98.127556 -234.182899) (xy 97.898976 -234.182899) (xy 97.891033 -234.235603) (xy 97.875323 -234.286533)
			(xy 97.852197 -234.334554) (xy 97.822173 -234.378591) (xy 97.785921 -234.417662) (xy 97.74425 -234.450893)
			(xy 97.698092 -234.477542) (xy 97.648478 -234.497014) (xy 97.596516 -234.508874) (xy 97.543366 -234.512858)
			(xy 97.490216 -234.508874) (xy 97.438254 -234.497014) (xy 97.38864 -234.477542) (xy 97.342482 -234.450893)
			(xy 97.300811 -234.417662) (xy 97.264559 -234.378591) (xy 97.234535 -234.334554) (xy 97.211409 -234.286533)
			(xy 97.195699 -234.235603) (xy 97.187756 -234.182899) (xy 96.959176 -234.182899) (xy 96.951233 -234.235603)
			(xy 96.935523 -234.286533) (xy 96.912397 -234.334554) (xy 96.882373 -234.378591) (xy 96.846121 -234.417662)
			(xy 96.80445 -234.450893) (xy 96.758292 -234.477542) (xy 96.708678 -234.497014) (xy 96.656716 -234.508874)
			(xy 96.603566 -234.512858) (xy 96.550416 -234.508874) (xy 96.498454 -234.497014) (xy 96.44884 -234.477542)
			(xy 96.402682 -234.450893) (xy 96.361011 -234.417662) (xy 96.324759 -234.378591) (xy 96.294735 -234.334554)
			(xy 96.271609 -234.286533) (xy 96.255899 -234.235603) (xy 96.247956 -234.182899) (xy 96.019376 -234.182899)
			(xy 96.011433 -234.235603) (xy 95.995723 -234.286533) (xy 95.972597 -234.334554) (xy 95.942573 -234.378591)
			(xy 95.906321 -234.417662) (xy 95.86465 -234.450893) (xy 95.818492 -234.477542) (xy 95.768878 -234.497014)
			(xy 95.716916 -234.508874) (xy 95.663766 -234.512858) (xy 95.610616 -234.508874) (xy 95.558654 -234.497014)
			(xy 95.50904 -234.477542) (xy 95.462882 -234.450893) (xy 95.421211 -234.417662) (xy 95.384959 -234.378591)
			(xy 95.354935 -234.334554) (xy 95.331809 -234.286533) (xy 95.316099 -234.235603) (xy 95.308156 -234.182899)
			(xy 95.079322 -234.182899) (xy 95.071379 -234.235603) (xy 95.055669 -234.286533) (xy 95.032543 -234.334554)
			(xy 95.002519 -234.378591) (xy 94.966267 -234.417662) (xy 94.924596 -234.450893) (xy 94.878438 -234.477542)
			(xy 94.828824 -234.497014) (xy 94.776862 -234.508874) (xy 94.723712 -234.512858) (xy 94.670562 -234.508874)
			(xy 94.6186 -234.497014) (xy 94.568986 -234.477542) (xy 94.522828 -234.450893) (xy 94.481157 -234.417662)
			(xy 94.444905 -234.378591) (xy 94.414881 -234.334554) (xy 94.391755 -234.286533) (xy 94.376045 -234.235603)
			(xy 94.368102 -234.182899) (xy 94.139776 -234.182899) (xy 94.131833 -234.235603) (xy 94.116123 -234.286533)
			(xy 94.092997 -234.334554) (xy 94.062973 -234.378591) (xy 94.026721 -234.417662) (xy 93.98505 -234.450893)
			(xy 93.938892 -234.477542) (xy 93.889278 -234.497014) (xy 93.837316 -234.508874) (xy 93.784166 -234.512858)
			(xy 93.731016 -234.508874) (xy 93.679054 -234.497014) (xy 93.62944 -234.477542) (xy 93.583282 -234.450893)
			(xy 93.541611 -234.417662) (xy 93.505359 -234.378591) (xy 93.475335 -234.334554) (xy 93.452209 -234.286533)
			(xy 93.436499 -234.235603) (xy 93.428556 -234.182899) (xy 93.199976 -234.182899) (xy 93.192033 -234.235603)
			(xy 93.176323 -234.286533) (xy 93.153197 -234.334554) (xy 93.123173 -234.378591) (xy 93.086921 -234.417662)
			(xy 93.04525 -234.450893) (xy 92.999092 -234.477542) (xy 92.949478 -234.497014) (xy 92.897516 -234.508874)
			(xy 92.844366 -234.512858) (xy 92.791216 -234.508874) (xy 92.739254 -234.497014) (xy 92.68964 -234.477542)
			(xy 92.643482 -234.450893) (xy 92.601811 -234.417662) (xy 92.565559 -234.378591) (xy 92.535535 -234.334554)
			(xy 92.512409 -234.286533) (xy 92.496699 -234.235603) (xy 92.488756 -234.182899) (xy 92.260176 -234.182899)
			(xy 92.252233 -234.235603) (xy 92.236523 -234.286533) (xy 92.213397 -234.334554) (xy 92.183373 -234.378591)
			(xy 92.147121 -234.417662) (xy 92.10545 -234.450893) (xy 92.059292 -234.477542) (xy 92.009678 -234.497014)
			(xy 91.957716 -234.508874) (xy 91.904566 -234.512858) (xy 91.851416 -234.508874) (xy 91.799454 -234.497014)
			(xy 91.74984 -234.477542) (xy 91.703682 -234.450893) (xy 91.662011 -234.417662) (xy 91.625759 -234.378591)
			(xy 91.595735 -234.334554) (xy 91.572609 -234.286533) (xy 91.556899 -234.235603) (xy 91.548956 -234.182899)
			(xy 91.320376 -234.182899) (xy 91.312433 -234.235603) (xy 91.296723 -234.286533) (xy 91.273597 -234.334554)
			(xy 91.243573 -234.378591) (xy 91.207321 -234.417662) (xy 91.16565 -234.450893) (xy 91.119492 -234.477542)
			(xy 91.069878 -234.497014) (xy 91.017916 -234.508874) (xy 90.964766 -234.512858) (xy 90.911616 -234.508874)
			(xy 90.859654 -234.497014) (xy 90.81004 -234.477542) (xy 90.763882 -234.450893) (xy 90.722211 -234.417662)
			(xy 90.685959 -234.378591) (xy 90.655935 -234.334554) (xy 90.632809 -234.286533) (xy 90.617099 -234.235603)
			(xy 90.609156 -234.182899) (xy 90.380576 -234.182899) (xy 90.372633 -234.235603) (xy 90.356923 -234.286533)
			(xy 90.333797 -234.334554) (xy 90.303773 -234.378591) (xy 90.267521 -234.417662) (xy 90.22585 -234.450893)
			(xy 90.179692 -234.477542) (xy 90.130078 -234.497014) (xy 90.078116 -234.508874) (xy 90.024966 -234.512858)
			(xy 89.971816 -234.508874) (xy 89.919854 -234.497014) (xy 89.87024 -234.477542) (xy 89.824082 -234.450893)
			(xy 89.782411 -234.417662) (xy 89.746159 -234.378591) (xy 89.716135 -234.334554) (xy 89.693009 -234.286533)
			(xy 89.677299 -234.235603) (xy 89.669356 -234.182899) (xy 89.439781 -234.182899) (xy 89.437799 -234.209349)
			(xy 89.425938 -234.261311) (xy 89.406465 -234.310924) (xy 89.379815 -234.357081) (xy 89.346582 -234.398749)
			(xy 89.30751 -234.434999) (xy 89.263471 -234.46502) (xy 89.21545 -234.488142) (xy 89.164519 -234.503848)
			(xy 89.111815 -234.511787) (xy 89.085166 -234.512358) (xy 89.060205 -234.511937) (xy 89.010772 -234.504967)
			(xy 88.962795 -234.491168) (xy 88.917213 -234.470809) (xy 88.874918 -234.44429) (xy 88.85555 -234.428538)
			(xy 88.844193 -234.419601) (xy 88.817791 -234.407883) (xy 88.789163 -234.40403) (xy 88.760602 -234.408352)
			(xy 88.734396 -234.420501) (xy 88.712642 -234.439506) (xy 88.697084 -234.463844) (xy 88.688967 -234.491566)
			(xy 88.688418 -234.506008) (xy 88.688418 -234.619546) (xy 88.723724 -234.630976) (xy 88.748735 -234.639499)
			(xy 88.796114 -234.662887) (xy 88.839518 -234.69302) (xy 88.877994 -234.729234) (xy 88.910696 -234.770736)
			(xy 88.936907 -234.816614) (xy 88.956052 -234.865861) (xy 88.96771 -234.917397) (xy 88.971626 -234.97009)
			(xy 88.969649 -234.996715) (xy 89.199202 -234.996715) (xy 89.199202 -234.943417) (xy 89.207145 -234.890713)
			(xy 89.222855 -234.839783) (xy 89.245981 -234.791762) (xy 89.276005 -234.747725) (xy 89.312257 -234.708654)
			(xy 89.353928 -234.675423) (xy 89.400086 -234.648774) (xy 89.4497 -234.629302) (xy 89.501662 -234.617442)
			(xy 89.554812 -234.613459) (xy 89.607962 -234.617442) (xy 89.659924 -234.629302) (xy 89.709538 -234.648774)
			(xy 89.755696 -234.675423) (xy 89.797367 -234.708654) (xy 89.833619 -234.747725) (xy 89.863643 -234.791762)
			(xy 89.886769 -234.839783) (xy 89.902479 -234.890713) (xy 89.910422 -234.943417) (xy 89.91092 -234.970066)
			(xy 89.910422 -234.996715) (xy 90.139256 -234.996715) (xy 90.139256 -234.943417) (xy 90.147199 -234.890713)
			(xy 90.162909 -234.839783) (xy 90.186035 -234.791762) (xy 90.216059 -234.747725) (xy 90.252311 -234.708654)
			(xy 90.293982 -234.675423) (xy 90.34014 -234.648774) (xy 90.389754 -234.629302) (xy 90.441716 -234.617442)
			(xy 90.494866 -234.613459) (xy 90.548016 -234.617442) (xy 90.599978 -234.629302) (xy 90.649592 -234.648774)
			(xy 90.69575 -234.675423) (xy 90.737421 -234.708654) (xy 90.773673 -234.747725) (xy 90.803697 -234.791762)
			(xy 90.826823 -234.839783) (xy 90.842533 -234.890713) (xy 90.850476 -234.943417) (xy 90.850974 -234.970066)
			(xy 90.850476 -234.996715) (xy 91.078802 -234.996715) (xy 91.078802 -234.943417) (xy 91.086745 -234.890713)
			(xy 91.102455 -234.839783) (xy 91.125581 -234.791762) (xy 91.155605 -234.747725) (xy 91.191857 -234.708654)
			(xy 91.233528 -234.675423) (xy 91.279686 -234.648774) (xy 91.3293 -234.629302) (xy 91.381262 -234.617442)
			(xy 91.434412 -234.613459) (xy 91.487562 -234.617442) (xy 91.539524 -234.629302) (xy 91.589138 -234.648774)
			(xy 91.635296 -234.675423) (xy 91.676967 -234.708654) (xy 91.713219 -234.747725) (xy 91.743243 -234.791762)
			(xy 91.766369 -234.839783) (xy 91.782079 -234.890713) (xy 91.790022 -234.943417) (xy 91.79052 -234.970066)
			(xy 91.790022 -234.996715) (xy 92.018602 -234.996715) (xy 92.018602 -234.943417) (xy 92.026545 -234.890713)
			(xy 92.042255 -234.839783) (xy 92.065381 -234.791762) (xy 92.095405 -234.747725) (xy 92.131657 -234.708654)
			(xy 92.173328 -234.675423) (xy 92.219486 -234.648774) (xy 92.2691 -234.629302) (xy 92.321062 -234.617442)
			(xy 92.374212 -234.613459) (xy 92.427362 -234.617442) (xy 92.479324 -234.629302) (xy 92.528938 -234.648774)
			(xy 92.575096 -234.675423) (xy 92.616767 -234.708654) (xy 92.653019 -234.747725) (xy 92.683043 -234.791762)
			(xy 92.706169 -234.839783) (xy 92.721879 -234.890713) (xy 92.729822 -234.943417) (xy 92.73032 -234.970066)
			(xy 92.729822 -234.996715) (xy 92.958402 -234.996715) (xy 92.958402 -234.943417) (xy 92.966345 -234.890713)
			(xy 92.982055 -234.839783) (xy 93.005181 -234.791762) (xy 93.035205 -234.747725) (xy 93.071457 -234.708654)
			(xy 93.113128 -234.675423) (xy 93.159286 -234.648774) (xy 93.2089 -234.629302) (xy 93.260862 -234.617442)
			(xy 93.314012 -234.613459) (xy 93.367162 -234.617442) (xy 93.419124 -234.629302) (xy 93.468738 -234.648774)
			(xy 93.514896 -234.675423) (xy 93.556567 -234.708654) (xy 93.592819 -234.747725) (xy 93.622843 -234.791762)
			(xy 93.645969 -234.839783) (xy 93.661679 -234.890713) (xy 93.669622 -234.943417) (xy 93.67012 -234.970066)
			(xy 93.669622 -234.996715) (xy 93.898202 -234.996715) (xy 93.898202 -234.943417) (xy 93.906145 -234.890713)
			(xy 93.921855 -234.839783) (xy 93.944981 -234.791762) (xy 93.975005 -234.747725) (xy 94.011257 -234.708654)
			(xy 94.052928 -234.675423) (xy 94.099086 -234.648774) (xy 94.1487 -234.629302) (xy 94.200662 -234.617442)
			(xy 94.253812 -234.613459) (xy 94.306962 -234.617442) (xy 94.358924 -234.629302) (xy 94.408538 -234.648774)
			(xy 94.454696 -234.675423) (xy 94.496367 -234.708654) (xy 94.532619 -234.747725) (xy 94.562643 -234.791762)
			(xy 94.585769 -234.839783) (xy 94.601479 -234.890713) (xy 94.609422 -234.943417) (xy 94.60992 -234.970066)
			(xy 94.609422 -234.996715) (xy 94.838002 -234.996715) (xy 94.838002 -234.943417) (xy 94.845945 -234.890713)
			(xy 94.861655 -234.839783) (xy 94.884781 -234.791762) (xy 94.914805 -234.747725) (xy 94.951057 -234.708654)
			(xy 94.992728 -234.675423) (xy 95.038886 -234.648774) (xy 95.0885 -234.629302) (xy 95.140462 -234.617442)
			(xy 95.193612 -234.613459) (xy 95.246762 -234.617442) (xy 95.298724 -234.629302) (xy 95.348338 -234.648774)
			(xy 95.394496 -234.675423) (xy 95.436167 -234.708654) (xy 95.472419 -234.747725) (xy 95.502443 -234.791762)
			(xy 95.525569 -234.839783) (xy 95.541279 -234.890713) (xy 95.549222 -234.943417) (xy 95.54972 -234.970066)
			(xy 95.549222 -234.996715) (xy 95.777802 -234.996715) (xy 95.777802 -234.943417) (xy 95.785745 -234.890713)
			(xy 95.801455 -234.839783) (xy 95.824581 -234.791762) (xy 95.854605 -234.747725) (xy 95.890857 -234.708654)
			(xy 95.932528 -234.675423) (xy 95.978686 -234.648774) (xy 96.0283 -234.629302) (xy 96.080262 -234.617442)
			(xy 96.133412 -234.613459) (xy 96.186562 -234.617442) (xy 96.238524 -234.629302) (xy 96.288138 -234.648774)
			(xy 96.334296 -234.675423) (xy 96.375967 -234.708654) (xy 96.412219 -234.747725) (xy 96.442243 -234.791762)
			(xy 96.465369 -234.839783) (xy 96.481079 -234.890713) (xy 96.489022 -234.943417) (xy 96.48952 -234.970066)
			(xy 96.489022 -234.996715) (xy 96.717856 -234.996715) (xy 96.717856 -234.943417) (xy 96.725799 -234.890713)
			(xy 96.741509 -234.839783) (xy 96.764635 -234.791762) (xy 96.794659 -234.747725) (xy 96.830911 -234.708654)
			(xy 96.872582 -234.675423) (xy 96.91874 -234.648774) (xy 96.968354 -234.629302) (xy 97.020316 -234.617442)
			(xy 97.073466 -234.613459) (xy 97.126616 -234.617442) (xy 97.178578 -234.629302) (xy 97.228192 -234.648774)
			(xy 97.27435 -234.675423) (xy 97.316021 -234.708654) (xy 97.352273 -234.747725) (xy 97.382297 -234.791762)
			(xy 97.405423 -234.839783) (xy 97.421133 -234.890713) (xy 97.429076 -234.943417) (xy 97.429574 -234.970066)
			(xy 97.429076 -234.996715) (xy 97.657402 -234.996715) (xy 97.657402 -234.943417) (xy 97.665345 -234.890713)
			(xy 97.681055 -234.839783) (xy 97.704181 -234.791762) (xy 97.734205 -234.747725) (xy 97.770457 -234.708654)
			(xy 97.812128 -234.675423) (xy 97.858286 -234.648774) (xy 97.9079 -234.629302) (xy 97.959862 -234.617442)
			(xy 98.013012 -234.613459) (xy 98.066162 -234.617442) (xy 98.118124 -234.629302) (xy 98.167738 -234.648774)
			(xy 98.213896 -234.675423) (xy 98.255567 -234.708654) (xy 98.291819 -234.747725) (xy 98.321843 -234.791762)
			(xy 98.344969 -234.839783) (xy 98.360679 -234.890713) (xy 98.368622 -234.943417) (xy 98.36912 -234.970066)
			(xy 98.368622 -234.996715) (xy 98.597202 -234.996715) (xy 98.597202 -234.943417) (xy 98.605145 -234.890713)
			(xy 98.620855 -234.839783) (xy 98.643981 -234.791762) (xy 98.674005 -234.747725) (xy 98.710257 -234.708654)
			(xy 98.751928 -234.675423) (xy 98.798086 -234.648774) (xy 98.8477 -234.629302) (xy 98.899662 -234.617442)
			(xy 98.952812 -234.613459) (xy 99.005962 -234.617442) (xy 99.057924 -234.629302) (xy 99.107538 -234.648774)
			(xy 99.153696 -234.675423) (xy 99.195367 -234.708654) (xy 99.231619 -234.747725) (xy 99.261643 -234.791762)
			(xy 99.284769 -234.839783) (xy 99.300479 -234.890713) (xy 99.308422 -234.943417) (xy 99.30892 -234.970066)
			(xy 99.308422 -234.996715) (xy 99.537002 -234.996715) (xy 99.537002 -234.943417) (xy 99.544945 -234.890713)
			(xy 99.560655 -234.839783) (xy 99.583781 -234.791762) (xy 99.613805 -234.747725) (xy 99.650057 -234.708654)
			(xy 99.691728 -234.675423) (xy 99.737886 -234.648774) (xy 99.7875 -234.629302) (xy 99.839462 -234.617442)
			(xy 99.892612 -234.613459) (xy 99.945762 -234.617442) (xy 99.997724 -234.629302) (xy 100.047338 -234.648774)
			(xy 100.093496 -234.675423) (xy 100.135167 -234.708654) (xy 100.171419 -234.747725) (xy 100.201443 -234.791762)
			(xy 100.224569 -234.839783) (xy 100.240279 -234.890713) (xy 100.248222 -234.943417) (xy 100.24872 -234.970066)
			(xy 100.248222 -234.996715) (xy 100.476802 -234.996715) (xy 100.476802 -234.943417) (xy 100.484745 -234.890713)
			(xy 100.500455 -234.839783) (xy 100.523581 -234.791762) (xy 100.553605 -234.747725) (xy 100.589857 -234.708654)
			(xy 100.631528 -234.675423) (xy 100.677686 -234.648774) (xy 100.7273 -234.629302) (xy 100.779262 -234.617442)
			(xy 100.832412 -234.613459) (xy 100.885562 -234.617442) (xy 100.937524 -234.629302) (xy 100.987138 -234.648774)
			(xy 101.033296 -234.675423) (xy 101.074967 -234.708654) (xy 101.111219 -234.747725) (xy 101.141243 -234.791762)
			(xy 101.164369 -234.839783) (xy 101.180079 -234.890713) (xy 101.188022 -234.943417) (xy 101.18852 -234.970066)
			(xy 101.188022 -234.996715) (xy 101.416602 -234.996715) (xy 101.416602 -234.943417) (xy 101.424545 -234.890713)
			(xy 101.440255 -234.839783) (xy 101.463381 -234.791762) (xy 101.493405 -234.747725) (xy 101.529657 -234.708654)
			(xy 101.571328 -234.675423) (xy 101.617486 -234.648774) (xy 101.6671 -234.629302) (xy 101.719062 -234.617442)
			(xy 101.772212 -234.613459) (xy 101.825362 -234.617442) (xy 101.877324 -234.629302) (xy 101.926938 -234.648774)
			(xy 101.973096 -234.675423) (xy 102.014767 -234.708654) (xy 102.051019 -234.747725) (xy 102.081043 -234.791762)
			(xy 102.104169 -234.839783) (xy 102.119879 -234.890713) (xy 102.127822 -234.943417) (xy 102.12832 -234.970066)
			(xy 102.127822 -234.996715) (xy 102.12074 -235.043705) (xy 104.259878 -235.043705) (xy 104.259878 -234.990407)
			(xy 104.267821 -234.937703) (xy 104.283531 -234.886773) (xy 104.306657 -234.838752) (xy 104.336681 -234.794715)
			(xy 104.372933 -234.755644) (xy 104.414604 -234.722413) (xy 104.460762 -234.695764) (xy 104.510376 -234.676292)
			(xy 104.562338 -234.664432) (xy 104.615488 -234.660449) (xy 104.668638 -234.664432) (xy 104.7206 -234.676292)
			(xy 104.770214 -234.695764) (xy 104.816372 -234.722413) (xy 104.858043 -234.755644) (xy 104.894295 -234.794715)
			(xy 104.924319 -234.838752) (xy 104.947445 -234.886773) (xy 104.963155 -234.937703) (xy 104.971098 -234.990407)
			(xy 104.971216 -234.996715) (xy 108.935256 -234.996715) (xy 108.935256 -234.943417) (xy 108.943199 -234.890713)
			(xy 108.958909 -234.839783) (xy 108.982035 -234.791762) (xy 109.012059 -234.747725) (xy 109.048311 -234.708654)
			(xy 109.089982 -234.675423) (xy 109.13614 -234.648774) (xy 109.185754 -234.629302) (xy 109.237716 -234.617442)
			(xy 109.290866 -234.613459) (xy 109.344016 -234.617442) (xy 109.395978 -234.629302) (xy 109.445592 -234.648774)
			(xy 109.49175 -234.675423) (xy 109.533421 -234.708654) (xy 109.569673 -234.747725) (xy 109.599697 -234.791762)
			(xy 109.622823 -234.839783) (xy 109.638533 -234.890713) (xy 109.646476 -234.943417) (xy 109.646974 -234.970066)
			(xy 109.646476 -234.996715) (xy 109.87531 -234.996715) (xy 109.87531 -234.943417) (xy 109.883253 -234.890713)
			(xy 109.898963 -234.839783) (xy 109.922089 -234.791762) (xy 109.952113 -234.747725) (xy 109.988365 -234.708654)
			(xy 110.030036 -234.675423) (xy 110.076194 -234.648774) (xy 110.125808 -234.629302) (xy 110.17777 -234.617442)
			(xy 110.23092 -234.613459) (xy 110.28407 -234.617442) (xy 110.336032 -234.629302) (xy 110.385646 -234.648774)
			(xy 110.431804 -234.675423) (xy 110.473475 -234.708654) (xy 110.509727 -234.747725) (xy 110.539751 -234.791762)
			(xy 110.562877 -234.839783) (xy 110.578587 -234.890713) (xy 110.58653 -234.943417) (xy 110.587028 -234.970066)
			(xy 110.58653 -234.996715) (xy 110.814856 -234.996715) (xy 110.814856 -234.943417) (xy 110.822799 -234.890713)
			(xy 110.838509 -234.839783) (xy 110.861635 -234.791762) (xy 110.891659 -234.747725) (xy 110.927911 -234.708654)
			(xy 110.969582 -234.675423) (xy 111.01574 -234.648774) (xy 111.065354 -234.629302) (xy 111.117316 -234.617442)
			(xy 111.170466 -234.613459) (xy 111.223616 -234.617442) (xy 111.275578 -234.629302) (xy 111.325192 -234.648774)
			(xy 111.37135 -234.675423) (xy 111.413021 -234.708654) (xy 111.449273 -234.747725) (xy 111.479297 -234.791762)
			(xy 111.502423 -234.839783) (xy 111.518133 -234.890713) (xy 111.526076 -234.943417) (xy 111.526574 -234.970066)
			(xy 111.526076 -234.996715) (xy 111.754656 -234.996715) (xy 111.754656 -234.943417) (xy 111.762599 -234.890713)
			(xy 111.778309 -234.839783) (xy 111.801435 -234.791762) (xy 111.831459 -234.747725) (xy 111.867711 -234.708654)
			(xy 111.909382 -234.675423) (xy 111.95554 -234.648774) (xy 112.005154 -234.629302) (xy 112.057116 -234.617442)
			(xy 112.110266 -234.613459) (xy 112.163416 -234.617442) (xy 112.215378 -234.629302) (xy 112.264992 -234.648774)
			(xy 112.31115 -234.675423) (xy 112.352821 -234.708654) (xy 112.389073 -234.747725) (xy 112.419097 -234.791762)
			(xy 112.442223 -234.839783) (xy 112.457933 -234.890713) (xy 112.465876 -234.943417) (xy 112.466374 -234.970066)
			(xy 112.465876 -234.996715) (xy 112.694456 -234.996715) (xy 112.694456 -234.943417) (xy 112.702399 -234.890713)
			(xy 112.718109 -234.839783) (xy 112.741235 -234.791762) (xy 112.771259 -234.747725) (xy 112.807511 -234.708654)
			(xy 112.849182 -234.675423) (xy 112.89534 -234.648774) (xy 112.944954 -234.629302) (xy 112.996916 -234.617442)
			(xy 113.050066 -234.613459) (xy 113.103216 -234.617442) (xy 113.155178 -234.629302) (xy 113.204792 -234.648774)
			(xy 113.25095 -234.675423) (xy 113.292621 -234.708654) (xy 113.328873 -234.747725) (xy 113.358897 -234.791762)
			(xy 113.382023 -234.839783) (xy 113.397733 -234.890713) (xy 113.405676 -234.943417) (xy 113.406174 -234.970066)
			(xy 113.405676 -234.996715) (xy 113.63451 -234.996715) (xy 113.63451 -234.943417) (xy 113.642453 -234.890713)
			(xy 113.658163 -234.839783) (xy 113.681289 -234.791762) (xy 113.711313 -234.747725) (xy 113.747565 -234.708654)
			(xy 113.789236 -234.675423) (xy 113.835394 -234.648774) (xy 113.885008 -234.629302) (xy 113.93697 -234.617442)
			(xy 113.99012 -234.613459) (xy 114.04327 -234.617442) (xy 114.095232 -234.629302) (xy 114.144846 -234.648774)
			(xy 114.191004 -234.675423) (xy 114.232675 -234.708654) (xy 114.268927 -234.747725) (xy 114.298951 -234.791762)
			(xy 114.322077 -234.839783) (xy 114.337787 -234.890713) (xy 114.34573 -234.943417) (xy 114.346228 -234.970066)
			(xy 114.34573 -234.996715) (xy 121.152402 -234.996715) (xy 121.152402 -234.943417) (xy 121.160345 -234.890713)
			(xy 121.176055 -234.839783) (xy 121.199181 -234.791762) (xy 121.229205 -234.747725) (xy 121.265457 -234.708654)
			(xy 121.307128 -234.675423) (xy 121.353286 -234.648774) (xy 121.4029 -234.629302) (xy 121.454862 -234.617442)
			(xy 121.508012 -234.613459) (xy 121.561162 -234.617442) (xy 121.613124 -234.629302) (xy 121.662738 -234.648774)
			(xy 121.708896 -234.675423) (xy 121.750567 -234.708654) (xy 121.786819 -234.747725) (xy 121.816843 -234.791762)
			(xy 121.839969 -234.839783) (xy 121.855679 -234.890713) (xy 121.863622 -234.943417) (xy 121.86412 -234.970066)
			(xy 121.863622 -234.996715) (xy 122.092202 -234.996715) (xy 122.092202 -234.943417) (xy 122.100145 -234.890713)
			(xy 122.115855 -234.839783) (xy 122.138981 -234.791762) (xy 122.169005 -234.747725) (xy 122.205257 -234.708654)
			(xy 122.246928 -234.675423) (xy 122.293086 -234.648774) (xy 122.3427 -234.629302) (xy 122.394662 -234.617442)
			(xy 122.447812 -234.613459) (xy 122.500962 -234.617442) (xy 122.552924 -234.629302) (xy 122.602538 -234.648774)
			(xy 122.648696 -234.675423) (xy 122.690367 -234.708654) (xy 122.726619 -234.747725) (xy 122.756643 -234.791762)
			(xy 122.779769 -234.839783) (xy 122.795479 -234.890713) (xy 122.803422 -234.943417) (xy 122.80392 -234.970066)
			(xy 122.803422 -234.996715) (xy 123.032002 -234.996715) (xy 123.032002 -234.943417) (xy 123.039945 -234.890713)
			(xy 123.055655 -234.839783) (xy 123.078781 -234.791762) (xy 123.108805 -234.747725) (xy 123.145057 -234.708654)
			(xy 123.186728 -234.675423) (xy 123.232886 -234.648774) (xy 123.2825 -234.629302) (xy 123.334462 -234.617442)
			(xy 123.387612 -234.613459) (xy 123.440762 -234.617442) (xy 123.492724 -234.629302) (xy 123.542338 -234.648774)
			(xy 123.588496 -234.675423) (xy 123.630167 -234.708654) (xy 123.666419 -234.747725) (xy 123.696443 -234.791762)
			(xy 123.719569 -234.839783) (xy 123.735279 -234.890713) (xy 123.743222 -234.943417) (xy 123.74372 -234.970066)
			(xy 123.743222 -234.996715) (xy 123.971802 -234.996715) (xy 123.971802 -234.943417) (xy 123.979745 -234.890713)
			(xy 123.995455 -234.839783) (xy 124.018581 -234.791762) (xy 124.048605 -234.747725) (xy 124.084857 -234.708654)
			(xy 124.126528 -234.675423) (xy 124.172686 -234.648774) (xy 124.2223 -234.629302) (xy 124.274262 -234.617442)
			(xy 124.327412 -234.613459) (xy 124.380562 -234.617442) (xy 124.432524 -234.629302) (xy 124.482138 -234.648774)
			(xy 124.528296 -234.675423) (xy 124.569967 -234.708654) (xy 124.606219 -234.747725) (xy 124.636243 -234.791762)
			(xy 124.659369 -234.839783) (xy 124.675079 -234.890713) (xy 124.683022 -234.943417) (xy 124.68352 -234.970066)
			(xy 124.683022 -234.996715) (xy 124.911856 -234.996715) (xy 124.911856 -234.943417) (xy 124.919799 -234.890713)
			(xy 124.935509 -234.839783) (xy 124.958635 -234.791762) (xy 124.988659 -234.747725) (xy 125.024911 -234.708654)
			(xy 125.066582 -234.675423) (xy 125.11274 -234.648774) (xy 125.162354 -234.629302) (xy 125.214316 -234.617442)
			(xy 125.267466 -234.613459) (xy 125.320616 -234.617442) (xy 125.372578 -234.629302) (xy 125.422192 -234.648774)
			(xy 125.46835 -234.675423) (xy 125.510021 -234.708654) (xy 125.546273 -234.747725) (xy 125.576297 -234.791762)
			(xy 125.599423 -234.839783) (xy 125.615133 -234.890713) (xy 125.623076 -234.943417) (xy 125.623574 -234.970066)
			(xy 125.623076 -234.996715) (xy 125.851402 -234.996715) (xy 125.851402 -234.943417) (xy 125.859345 -234.890713)
			(xy 125.875055 -234.839783) (xy 125.898181 -234.791762) (xy 125.928205 -234.747725) (xy 125.964457 -234.708654)
			(xy 126.006128 -234.675423) (xy 126.052286 -234.648774) (xy 126.1019 -234.629302) (xy 126.153862 -234.617442)
			(xy 126.207012 -234.613459) (xy 126.260162 -234.617442) (xy 126.312124 -234.629302) (xy 126.361738 -234.648774)
			(xy 126.407896 -234.675423) (xy 126.449567 -234.708654) (xy 126.485819 -234.747725) (xy 126.515843 -234.791762)
			(xy 126.538969 -234.839783) (xy 126.554679 -234.890713) (xy 126.562622 -234.943417) (xy 126.56312 -234.970066)
			(xy 126.562622 -234.996715) (xy 126.791202 -234.996715) (xy 126.791202 -234.943417) (xy 126.799145 -234.890713)
			(xy 126.814855 -234.839783) (xy 126.837981 -234.791762) (xy 126.868005 -234.747725) (xy 126.904257 -234.708654)
			(xy 126.945928 -234.675423) (xy 126.992086 -234.648774) (xy 127.0417 -234.629302) (xy 127.093662 -234.617442)
			(xy 127.146812 -234.613459) (xy 127.199962 -234.617442) (xy 127.251924 -234.629302) (xy 127.301538 -234.648774)
			(xy 127.347696 -234.675423) (xy 127.389367 -234.708654) (xy 127.425619 -234.747725) (xy 127.455643 -234.791762)
			(xy 127.478769 -234.839783) (xy 127.494479 -234.890713) (xy 127.502422 -234.943417) (xy 127.50292 -234.970066)
			(xy 127.502422 -234.996715) (xy 127.731002 -234.996715) (xy 127.731002 -234.943417) (xy 127.738945 -234.890713)
			(xy 127.754655 -234.839783) (xy 127.777781 -234.791762) (xy 127.807805 -234.747725) (xy 127.844057 -234.708654)
			(xy 127.885728 -234.675423) (xy 127.931886 -234.648774) (xy 127.9815 -234.629302) (xy 128.033462 -234.617442)
			(xy 128.086612 -234.613459) (xy 128.139762 -234.617442) (xy 128.191724 -234.629302) (xy 128.241338 -234.648774)
			(xy 128.287496 -234.675423) (xy 128.329167 -234.708654) (xy 128.365419 -234.747725) (xy 128.395443 -234.791762)
			(xy 128.418569 -234.839783) (xy 128.434279 -234.890713) (xy 128.442222 -234.943417) (xy 128.44272 -234.970066)
			(xy 128.442222 -234.996715) (xy 128.670802 -234.996715) (xy 128.670802 -234.943417) (xy 128.678745 -234.890713)
			(xy 128.694455 -234.839783) (xy 128.717581 -234.791762) (xy 128.747605 -234.747725) (xy 128.783857 -234.708654)
			(xy 128.825528 -234.675423) (xy 128.871686 -234.648774) (xy 128.9213 -234.629302) (xy 128.973262 -234.617442)
			(xy 129.026412 -234.613459) (xy 129.079562 -234.617442) (xy 129.131524 -234.629302) (xy 129.181138 -234.648774)
			(xy 129.227296 -234.675423) (xy 129.268967 -234.708654) (xy 129.305219 -234.747725) (xy 129.335243 -234.791762)
			(xy 129.358369 -234.839783) (xy 129.374079 -234.890713) (xy 129.382022 -234.943417) (xy 129.38252 -234.970066)
			(xy 129.382022 -234.996715) (xy 129.610602 -234.996715) (xy 129.610602 -234.943417) (xy 129.618545 -234.890713)
			(xy 129.634255 -234.839783) (xy 129.657381 -234.791762) (xy 129.687405 -234.747725) (xy 129.723657 -234.708654)
			(xy 129.765328 -234.675423) (xy 129.811486 -234.648774) (xy 129.8611 -234.629302) (xy 129.913062 -234.617442)
			(xy 129.966212 -234.613459) (xy 130.019362 -234.617442) (xy 130.071324 -234.629302) (xy 130.120938 -234.648774)
			(xy 130.167096 -234.675423) (xy 130.208767 -234.708654) (xy 130.245019 -234.747725) (xy 130.275043 -234.791762)
			(xy 130.298169 -234.839783) (xy 130.313879 -234.890713) (xy 130.321822 -234.943417) (xy 130.32232 -234.970066)
			(xy 130.321822 -234.996715) (xy 130.550402 -234.996715) (xy 130.550402 -234.943417) (xy 130.558345 -234.890713)
			(xy 130.574055 -234.839783) (xy 130.597181 -234.791762) (xy 130.627205 -234.747725) (xy 130.663457 -234.708654)
			(xy 130.705128 -234.675423) (xy 130.751286 -234.648774) (xy 130.8009 -234.629302) (xy 130.852862 -234.617442)
			(xy 130.906012 -234.613459) (xy 130.959162 -234.617442) (xy 131.011124 -234.629302) (xy 131.060738 -234.648774)
			(xy 131.106896 -234.675423) (xy 131.148567 -234.708654) (xy 131.184819 -234.747725) (xy 131.214843 -234.791762)
			(xy 131.237969 -234.839783) (xy 131.253679 -234.890713) (xy 131.261622 -234.943417) (xy 131.26212 -234.970066)
			(xy 131.261622 -234.996715) (xy 131.490456 -234.996715) (xy 131.490456 -234.943417) (xy 131.498399 -234.890713)
			(xy 131.514109 -234.839783) (xy 131.537235 -234.791762) (xy 131.567259 -234.747725) (xy 131.603511 -234.708654)
			(xy 131.645182 -234.675423) (xy 131.69134 -234.648774) (xy 131.740954 -234.629302) (xy 131.792916 -234.617442)
			(xy 131.846066 -234.613459) (xy 131.899216 -234.617442) (xy 131.951178 -234.629302) (xy 132.000792 -234.648774)
			(xy 132.04695 -234.675423) (xy 132.088621 -234.708654) (xy 132.124873 -234.747725) (xy 132.154897 -234.791762)
			(xy 132.178023 -234.839783) (xy 132.193733 -234.890713) (xy 132.201676 -234.943417) (xy 132.202174 -234.970066)
			(xy 132.201676 -234.996715) (xy 132.430002 -234.996715) (xy 132.430002 -234.943417) (xy 132.437945 -234.890713)
			(xy 132.453655 -234.839783) (xy 132.476781 -234.791762) (xy 132.506805 -234.747725) (xy 132.543057 -234.708654)
			(xy 132.584728 -234.675423) (xy 132.630886 -234.648774) (xy 132.6805 -234.629302) (xy 132.732462 -234.617442)
			(xy 132.785612 -234.613459) (xy 132.838762 -234.617442) (xy 132.890724 -234.629302) (xy 132.940338 -234.648774)
			(xy 132.986496 -234.675423) (xy 133.028167 -234.708654) (xy 133.064419 -234.747725) (xy 133.094443 -234.791762)
			(xy 133.117569 -234.839783) (xy 133.133279 -234.890713) (xy 133.141222 -234.943417) (xy 133.14172 -234.970066)
			(xy 133.141222 -234.996715) (xy 133.370056 -234.996715) (xy 133.370056 -234.943417) (xy 133.377999 -234.890713)
			(xy 133.393709 -234.839783) (xy 133.416835 -234.791762) (xy 133.446859 -234.747725) (xy 133.483111 -234.708654)
			(xy 133.524782 -234.675423) (xy 133.57094 -234.648774) (xy 133.620554 -234.629302) (xy 133.672516 -234.617442)
			(xy 133.725666 -234.613459) (xy 133.778816 -234.617442) (xy 133.830778 -234.629302) (xy 133.880392 -234.648774)
			(xy 133.92655 -234.675423) (xy 133.968221 -234.708654) (xy 134.004473 -234.747725) (xy 134.034497 -234.791762)
			(xy 134.057623 -234.839783) (xy 134.073333 -234.890713) (xy 134.081276 -234.943417) (xy 134.081774 -234.970066)
			(xy 134.081276 -234.996715) (xy 134.309856 -234.996715) (xy 134.309856 -234.943417) (xy 134.317799 -234.890713)
			(xy 134.333509 -234.839783) (xy 134.356635 -234.791762) (xy 134.386659 -234.747725) (xy 134.422911 -234.708654)
			(xy 134.464582 -234.675423) (xy 134.51074 -234.648774) (xy 134.560354 -234.629302) (xy 134.612316 -234.617442)
			(xy 134.665466 -234.613459) (xy 134.718616 -234.617442) (xy 134.770578 -234.629302) (xy 134.820192 -234.648774)
			(xy 134.86635 -234.675423) (xy 134.908021 -234.708654) (xy 134.944273 -234.747725) (xy 134.974297 -234.791762)
			(xy 134.997423 -234.839783) (xy 135.013133 -234.890713) (xy 135.021076 -234.943417) (xy 135.021574 -234.970066)
			(xy 135.021076 -234.996715) (xy 135.013133 -235.049419) (xy 134.997423 -235.100349) (xy 134.974297 -235.14837)
			(xy 134.944273 -235.192407) (xy 134.908021 -235.231478) (xy 134.86635 -235.264709) (xy 134.820192 -235.291358)
			(xy 134.770578 -235.31083) (xy 134.718616 -235.32269) (xy 134.665466 -235.326674) (xy 134.612316 -235.32269)
			(xy 134.560354 -235.31083) (xy 134.51074 -235.291358) (xy 134.464582 -235.264709) (xy 134.422911 -235.231478)
			(xy 134.386659 -235.192407) (xy 134.356635 -235.14837) (xy 134.333509 -235.100349) (xy 134.317799 -235.049419)
			(xy 134.309856 -234.996715) (xy 134.081276 -234.996715) (xy 134.073333 -235.049419) (xy 134.057623 -235.100349)
			(xy 134.034497 -235.14837) (xy 134.004473 -235.192407) (xy 133.968221 -235.231478) (xy 133.92655 -235.264709)
			(xy 133.880392 -235.291358) (xy 133.830778 -235.31083) (xy 133.778816 -235.32269) (xy 133.725666 -235.326674)
			(xy 133.672516 -235.32269) (xy 133.620554 -235.31083) (xy 133.57094 -235.291358) (xy 133.524782 -235.264709)
			(xy 133.483111 -235.231478) (xy 133.446859 -235.192407) (xy 133.416835 -235.14837) (xy 133.393709 -235.100349)
			(xy 133.377999 -235.049419) (xy 133.370056 -234.996715) (xy 133.141222 -234.996715) (xy 133.133279 -235.049419)
			(xy 133.117569 -235.100349) (xy 133.094443 -235.14837) (xy 133.064419 -235.192407) (xy 133.028167 -235.231478)
			(xy 132.986496 -235.264709) (xy 132.940338 -235.291358) (xy 132.890724 -235.31083) (xy 132.838762 -235.32269)
			(xy 132.785612 -235.326674) (xy 132.732462 -235.32269) (xy 132.6805 -235.31083) (xy 132.630886 -235.291358)
			(xy 132.584728 -235.264709) (xy 132.543057 -235.231478) (xy 132.506805 -235.192407) (xy 132.476781 -235.14837)
			(xy 132.453655 -235.100349) (xy 132.437945 -235.049419) (xy 132.430002 -234.996715) (xy 132.201676 -234.996715)
			(xy 132.193733 -235.049419) (xy 132.178023 -235.100349) (xy 132.154897 -235.14837) (xy 132.124873 -235.192407)
			(xy 132.088621 -235.231478) (xy 132.04695 -235.264709) (xy 132.000792 -235.291358) (xy 131.951178 -235.31083)
			(xy 131.899216 -235.32269) (xy 131.846066 -235.326674) (xy 131.792916 -235.32269) (xy 131.740954 -235.31083)
			(xy 131.69134 -235.291358) (xy 131.645182 -235.264709) (xy 131.603511 -235.231478) (xy 131.567259 -235.192407)
			(xy 131.537235 -235.14837) (xy 131.514109 -235.100349) (xy 131.498399 -235.049419) (xy 131.490456 -234.996715)
			(xy 131.261622 -234.996715) (xy 131.253679 -235.049419) (xy 131.237969 -235.100349) (xy 131.214843 -235.14837)
			(xy 131.184819 -235.192407) (xy 131.148567 -235.231478) (xy 131.106896 -235.264709) (xy 131.060738 -235.291358)
			(xy 131.011124 -235.31083) (xy 130.959162 -235.32269) (xy 130.906012 -235.326674) (xy 130.852862 -235.32269)
			(xy 130.8009 -235.31083) (xy 130.751286 -235.291358) (xy 130.705128 -235.264709) (xy 130.663457 -235.231478)
			(xy 130.627205 -235.192407) (xy 130.597181 -235.14837) (xy 130.574055 -235.100349) (xy 130.558345 -235.049419)
			(xy 130.550402 -234.996715) (xy 130.321822 -234.996715) (xy 130.313879 -235.049419) (xy 130.298169 -235.100349)
			(xy 130.275043 -235.14837) (xy 130.245019 -235.192407) (xy 130.208767 -235.231478) (xy 130.167096 -235.264709)
			(xy 130.120938 -235.291358) (xy 130.071324 -235.31083) (xy 130.019362 -235.32269) (xy 129.966212 -235.326674)
			(xy 129.913062 -235.32269) (xy 129.8611 -235.31083) (xy 129.811486 -235.291358) (xy 129.765328 -235.264709)
			(xy 129.723657 -235.231478) (xy 129.687405 -235.192407) (xy 129.657381 -235.14837) (xy 129.634255 -235.100349)
			(xy 129.618545 -235.049419) (xy 129.610602 -234.996715) (xy 129.382022 -234.996715) (xy 129.374079 -235.049419)
			(xy 129.358369 -235.100349) (xy 129.335243 -235.14837) (xy 129.305219 -235.192407) (xy 129.268967 -235.231478)
			(xy 129.227296 -235.264709) (xy 129.181138 -235.291358) (xy 129.131524 -235.31083) (xy 129.079562 -235.32269)
			(xy 129.026412 -235.326674) (xy 128.973262 -235.32269) (xy 128.9213 -235.31083) (xy 128.871686 -235.291358)
			(xy 128.825528 -235.264709) (xy 128.783857 -235.231478) (xy 128.747605 -235.192407) (xy 128.717581 -235.14837)
			(xy 128.694455 -235.100349) (xy 128.678745 -235.049419) (xy 128.670802 -234.996715) (xy 128.442222 -234.996715)
			(xy 128.434279 -235.049419) (xy 128.418569 -235.100349) (xy 128.395443 -235.14837) (xy 128.365419 -235.192407)
			(xy 128.329167 -235.231478) (xy 128.287496 -235.264709) (xy 128.241338 -235.291358) (xy 128.191724 -235.31083)
			(xy 128.139762 -235.32269) (xy 128.086612 -235.326674) (xy 128.033462 -235.32269) (xy 127.9815 -235.31083)
			(xy 127.931886 -235.291358) (xy 127.885728 -235.264709) (xy 127.844057 -235.231478) (xy 127.807805 -235.192407)
			(xy 127.777781 -235.14837) (xy 127.754655 -235.100349) (xy 127.738945 -235.049419) (xy 127.731002 -234.996715)
			(xy 127.502422 -234.996715) (xy 127.494479 -235.049419) (xy 127.478769 -235.100349) (xy 127.455643 -235.14837)
			(xy 127.425619 -235.192407) (xy 127.389367 -235.231478) (xy 127.347696 -235.264709) (xy 127.301538 -235.291358)
			(xy 127.251924 -235.31083) (xy 127.199962 -235.32269) (xy 127.146812 -235.326674) (xy 127.093662 -235.32269)
			(xy 127.0417 -235.31083) (xy 126.992086 -235.291358) (xy 126.945928 -235.264709) (xy 126.904257 -235.231478)
			(xy 126.868005 -235.192407) (xy 126.837981 -235.14837) (xy 126.814855 -235.100349) (xy 126.799145 -235.049419)
			(xy 126.791202 -234.996715) (xy 126.562622 -234.996715) (xy 126.554679 -235.049419) (xy 126.538969 -235.100349)
			(xy 126.515843 -235.14837) (xy 126.485819 -235.192407) (xy 126.449567 -235.231478) (xy 126.407896 -235.264709)
			(xy 126.361738 -235.291358) (xy 126.312124 -235.31083) (xy 126.260162 -235.32269) (xy 126.207012 -235.326674)
			(xy 126.153862 -235.32269) (xy 126.1019 -235.31083) (xy 126.052286 -235.291358) (xy 126.006128 -235.264709)
			(xy 125.964457 -235.231478) (xy 125.928205 -235.192407) (xy 125.898181 -235.14837) (xy 125.875055 -235.100349)
			(xy 125.859345 -235.049419) (xy 125.851402 -234.996715) (xy 125.623076 -234.996715) (xy 125.615133 -235.049419)
			(xy 125.599423 -235.100349) (xy 125.576297 -235.14837) (xy 125.546273 -235.192407) (xy 125.510021 -235.231478)
			(xy 125.46835 -235.264709) (xy 125.422192 -235.291358) (xy 125.372578 -235.31083) (xy 125.320616 -235.32269)
			(xy 125.267466 -235.326674) (xy 125.214316 -235.32269) (xy 125.162354 -235.31083) (xy 125.11274 -235.291358)
			(xy 125.066582 -235.264709) (xy 125.024911 -235.231478) (xy 124.988659 -235.192407) (xy 124.958635 -235.14837)
			(xy 124.935509 -235.100349) (xy 124.919799 -235.049419) (xy 124.911856 -234.996715) (xy 124.683022 -234.996715)
			(xy 124.675079 -235.049419) (xy 124.659369 -235.100349) (xy 124.636243 -235.14837) (xy 124.606219 -235.192407)
			(xy 124.569967 -235.231478) (xy 124.528296 -235.264709) (xy 124.482138 -235.291358) (xy 124.432524 -235.31083)
			(xy 124.380562 -235.32269) (xy 124.327412 -235.326674) (xy 124.274262 -235.32269) (xy 124.2223 -235.31083)
			(xy 124.172686 -235.291358) (xy 124.126528 -235.264709) (xy 124.084857 -235.231478) (xy 124.048605 -235.192407)
			(xy 124.018581 -235.14837) (xy 123.995455 -235.100349) (xy 123.979745 -235.049419) (xy 123.971802 -234.996715)
			(xy 123.743222 -234.996715) (xy 123.735279 -235.049419) (xy 123.719569 -235.100349) (xy 123.696443 -235.14837)
			(xy 123.666419 -235.192407) (xy 123.630167 -235.231478) (xy 123.588496 -235.264709) (xy 123.542338 -235.291358)
			(xy 123.492724 -235.31083) (xy 123.440762 -235.32269) (xy 123.387612 -235.326674) (xy 123.334462 -235.32269)
			(xy 123.2825 -235.31083) (xy 123.232886 -235.291358) (xy 123.186728 -235.264709) (xy 123.145057 -235.231478)
			(xy 123.108805 -235.192407) (xy 123.078781 -235.14837) (xy 123.055655 -235.100349) (xy 123.039945 -235.049419)
			(xy 123.032002 -234.996715) (xy 122.803422 -234.996715) (xy 122.795479 -235.049419) (xy 122.779769 -235.100349)
			(xy 122.756643 -235.14837) (xy 122.726619 -235.192407) (xy 122.690367 -235.231478) (xy 122.648696 -235.264709)
			(xy 122.602538 -235.291358) (xy 122.552924 -235.31083) (xy 122.500962 -235.32269) (xy 122.447812 -235.326674)
			(xy 122.394662 -235.32269) (xy 122.3427 -235.31083) (xy 122.293086 -235.291358) (xy 122.246928 -235.264709)
			(xy 122.205257 -235.231478) (xy 122.169005 -235.192407) (xy 122.138981 -235.14837) (xy 122.115855 -235.100349)
			(xy 122.100145 -235.049419) (xy 122.092202 -234.996715) (xy 121.863622 -234.996715) (xy 121.855679 -235.049419)
			(xy 121.839969 -235.100349) (xy 121.816843 -235.14837) (xy 121.786819 -235.192407) (xy 121.750567 -235.231478)
			(xy 121.708896 -235.264709) (xy 121.662738 -235.291358) (xy 121.613124 -235.31083) (xy 121.561162 -235.32269)
			(xy 121.508012 -235.326674) (xy 121.454862 -235.32269) (xy 121.4029 -235.31083) (xy 121.353286 -235.291358)
			(xy 121.307128 -235.264709) (xy 121.265457 -235.231478) (xy 121.229205 -235.192407) (xy 121.199181 -235.14837)
			(xy 121.176055 -235.100349) (xy 121.160345 -235.049419) (xy 121.152402 -234.996715) (xy 114.34573 -234.996715)
			(xy 114.337787 -235.049419) (xy 114.322077 -235.100349) (xy 114.298951 -235.14837) (xy 114.268927 -235.192407)
			(xy 114.232675 -235.231478) (xy 114.191004 -235.264709) (xy 114.144846 -235.291358) (xy 114.095232 -235.31083)
			(xy 114.04327 -235.32269) (xy 113.99012 -235.326674) (xy 113.93697 -235.32269) (xy 113.885008 -235.31083)
			(xy 113.835394 -235.291358) (xy 113.789236 -235.264709) (xy 113.747565 -235.231478) (xy 113.711313 -235.192407)
			(xy 113.681289 -235.14837) (xy 113.658163 -235.100349) (xy 113.642453 -235.049419) (xy 113.63451 -234.996715)
			(xy 113.405676 -234.996715) (xy 113.397733 -235.049419) (xy 113.382023 -235.100349) (xy 113.358897 -235.14837)
			(xy 113.328873 -235.192407) (xy 113.292621 -235.231478) (xy 113.25095 -235.264709) (xy 113.204792 -235.291358)
			(xy 113.155178 -235.31083) (xy 113.103216 -235.32269) (xy 113.050066 -235.326674) (xy 112.996916 -235.32269)
			(xy 112.944954 -235.31083) (xy 112.89534 -235.291358) (xy 112.849182 -235.264709) (xy 112.807511 -235.231478)
			(xy 112.771259 -235.192407) (xy 112.741235 -235.14837) (xy 112.718109 -235.100349) (xy 112.702399 -235.049419)
			(xy 112.694456 -234.996715) (xy 112.465876 -234.996715) (xy 112.457933 -235.049419) (xy 112.442223 -235.100349)
			(xy 112.419097 -235.14837) (xy 112.389073 -235.192407) (xy 112.352821 -235.231478) (xy 112.31115 -235.264709)
			(xy 112.264992 -235.291358) (xy 112.215378 -235.31083) (xy 112.163416 -235.32269) (xy 112.110266 -235.326674)
			(xy 112.057116 -235.32269) (xy 112.005154 -235.31083) (xy 111.95554 -235.291358) (xy 111.909382 -235.264709)
			(xy 111.867711 -235.231478) (xy 111.831459 -235.192407) (xy 111.801435 -235.14837) (xy 111.778309 -235.100349)
			(xy 111.762599 -235.049419) (xy 111.754656 -234.996715) (xy 111.526076 -234.996715) (xy 111.518133 -235.049419)
			(xy 111.502423 -235.100349) (xy 111.479297 -235.14837) (xy 111.449273 -235.192407) (xy 111.413021 -235.231478)
			(xy 111.37135 -235.264709) (xy 111.325192 -235.291358) (xy 111.275578 -235.31083) (xy 111.223616 -235.32269)
			(xy 111.170466 -235.326674) (xy 111.117316 -235.32269) (xy 111.065354 -235.31083) (xy 111.01574 -235.291358)
			(xy 110.969582 -235.264709) (xy 110.927911 -235.231478) (xy 110.891659 -235.192407) (xy 110.861635 -235.14837)
			(xy 110.838509 -235.100349) (xy 110.822799 -235.049419) (xy 110.814856 -234.996715) (xy 110.58653 -234.996715)
			(xy 110.578587 -235.049419) (xy 110.562877 -235.100349) (xy 110.539751 -235.14837) (xy 110.509727 -235.192407)
			(xy 110.473475 -235.231478) (xy 110.431804 -235.264709) (xy 110.385646 -235.291358) (xy 110.336032 -235.31083)
			(xy 110.28407 -235.32269) (xy 110.23092 -235.326674) (xy 110.17777 -235.32269) (xy 110.125808 -235.31083)
			(xy 110.076194 -235.291358) (xy 110.030036 -235.264709) (xy 109.988365 -235.231478) (xy 109.952113 -235.192407)
			(xy 109.922089 -235.14837) (xy 109.898963 -235.100349) (xy 109.883253 -235.049419) (xy 109.87531 -234.996715)
			(xy 109.646476 -234.996715) (xy 109.638533 -235.049419) (xy 109.622823 -235.100349) (xy 109.599697 -235.14837)
			(xy 109.569673 -235.192407) (xy 109.533421 -235.231478) (xy 109.49175 -235.264709) (xy 109.445592 -235.291358)
			(xy 109.395978 -235.31083) (xy 109.344016 -235.32269) (xy 109.290866 -235.326674) (xy 109.237716 -235.32269)
			(xy 109.185754 -235.31083) (xy 109.13614 -235.291358) (xy 109.089982 -235.264709) (xy 109.048311 -235.231478)
			(xy 109.012059 -235.192407) (xy 108.982035 -235.14837) (xy 108.958909 -235.100349) (xy 108.943199 -235.049419)
			(xy 108.935256 -234.996715) (xy 104.971216 -234.996715) (xy 104.971596 -235.017056) (xy 104.971098 -235.043705)
			(xy 104.963155 -235.096409) (xy 104.947445 -235.147339) (xy 104.924319 -235.19536) (xy 104.894295 -235.239397)
			(xy 104.858043 -235.278468) (xy 104.816372 -235.311699) (xy 104.770214 -235.338348) (xy 104.7206 -235.35782)
			(xy 104.668638 -235.36968) (xy 104.615488 -235.373664) (xy 104.562338 -235.36968) (xy 104.510376 -235.35782)
			(xy 104.460762 -235.338348) (xy 104.414604 -235.311699) (xy 104.372933 -235.278468) (xy 104.336681 -235.239397)
			(xy 104.306657 -235.19536) (xy 104.283531 -235.147339) (xy 104.267821 -235.096409) (xy 104.259878 -235.043705)
			(xy 102.12074 -235.043705) (xy 102.119879 -235.049419) (xy 102.104169 -235.100349) (xy 102.081043 -235.14837)
			(xy 102.051019 -235.192407) (xy 102.014767 -235.231478) (xy 101.973096 -235.264709) (xy 101.926938 -235.291358)
			(xy 101.877324 -235.31083) (xy 101.825362 -235.32269) (xy 101.772212 -235.326674) (xy 101.719062 -235.32269)
			(xy 101.6671 -235.31083) (xy 101.617486 -235.291358) (xy 101.571328 -235.264709) (xy 101.529657 -235.231478)
			(xy 101.493405 -235.192407) (xy 101.463381 -235.14837) (xy 101.440255 -235.100349) (xy 101.424545 -235.049419)
			(xy 101.416602 -234.996715) (xy 101.188022 -234.996715) (xy 101.180079 -235.049419) (xy 101.164369 -235.100349)
			(xy 101.141243 -235.14837) (xy 101.111219 -235.192407) (xy 101.074967 -235.231478) (xy 101.033296 -235.264709)
			(xy 100.987138 -235.291358) (xy 100.937524 -235.31083) (xy 100.885562 -235.32269) (xy 100.832412 -235.326674)
			(xy 100.779262 -235.32269) (xy 100.7273 -235.31083) (xy 100.677686 -235.291358) (xy 100.631528 -235.264709)
			(xy 100.589857 -235.231478) (xy 100.553605 -235.192407) (xy 100.523581 -235.14837) (xy 100.500455 -235.100349)
			(xy 100.484745 -235.049419) (xy 100.476802 -234.996715) (xy 100.248222 -234.996715) (xy 100.240279 -235.049419)
			(xy 100.224569 -235.100349) (xy 100.201443 -235.14837) (xy 100.171419 -235.192407) (xy 100.135167 -235.231478)
			(xy 100.093496 -235.264709) (xy 100.047338 -235.291358) (xy 99.997724 -235.31083) (xy 99.945762 -235.32269)
			(xy 99.892612 -235.326674) (xy 99.839462 -235.32269) (xy 99.7875 -235.31083) (xy 99.737886 -235.291358)
			(xy 99.691728 -235.264709) (xy 99.650057 -235.231478) (xy 99.613805 -235.192407) (xy 99.583781 -235.14837)
			(xy 99.560655 -235.100349) (xy 99.544945 -235.049419) (xy 99.537002 -234.996715) (xy 99.308422 -234.996715)
			(xy 99.300479 -235.049419) (xy 99.284769 -235.100349) (xy 99.261643 -235.14837) (xy 99.231619 -235.192407)
			(xy 99.195367 -235.231478) (xy 99.153696 -235.264709) (xy 99.107538 -235.291358) (xy 99.057924 -235.31083)
			(xy 99.005962 -235.32269) (xy 98.952812 -235.326674) (xy 98.899662 -235.32269) (xy 98.8477 -235.31083)
			(xy 98.798086 -235.291358) (xy 98.751928 -235.264709) (xy 98.710257 -235.231478) (xy 98.674005 -235.192407)
			(xy 98.643981 -235.14837) (xy 98.620855 -235.100349) (xy 98.605145 -235.049419) (xy 98.597202 -234.996715)
			(xy 98.368622 -234.996715) (xy 98.360679 -235.049419) (xy 98.344969 -235.100349) (xy 98.321843 -235.14837)
			(xy 98.291819 -235.192407) (xy 98.255567 -235.231478) (xy 98.213896 -235.264709) (xy 98.167738 -235.291358)
			(xy 98.118124 -235.31083) (xy 98.066162 -235.32269) (xy 98.013012 -235.326674) (xy 97.959862 -235.32269)
			(xy 97.9079 -235.31083) (xy 97.858286 -235.291358) (xy 97.812128 -235.264709) (xy 97.770457 -235.231478)
			(xy 97.734205 -235.192407) (xy 97.704181 -235.14837) (xy 97.681055 -235.100349) (xy 97.665345 -235.049419)
			(xy 97.657402 -234.996715) (xy 97.429076 -234.996715) (xy 97.421133 -235.049419) (xy 97.405423 -235.100349)
			(xy 97.382297 -235.14837) (xy 97.352273 -235.192407) (xy 97.316021 -235.231478) (xy 97.27435 -235.264709)
			(xy 97.228192 -235.291358) (xy 97.178578 -235.31083) (xy 97.126616 -235.32269) (xy 97.073466 -235.326674)
			(xy 97.020316 -235.32269) (xy 96.968354 -235.31083) (xy 96.91874 -235.291358) (xy 96.872582 -235.264709)
			(xy 96.830911 -235.231478) (xy 96.794659 -235.192407) (xy 96.764635 -235.14837) (xy 96.741509 -235.100349)
			(xy 96.725799 -235.049419) (xy 96.717856 -234.996715) (xy 96.489022 -234.996715) (xy 96.481079 -235.049419)
			(xy 96.465369 -235.100349) (xy 96.442243 -235.14837) (xy 96.412219 -235.192407) (xy 96.375967 -235.231478)
			(xy 96.334296 -235.264709) (xy 96.288138 -235.291358) (xy 96.238524 -235.31083) (xy 96.186562 -235.32269)
			(xy 96.133412 -235.326674) (xy 96.080262 -235.32269) (xy 96.0283 -235.31083) (xy 95.978686 -235.291358)
			(xy 95.932528 -235.264709) (xy 95.890857 -235.231478) (xy 95.854605 -235.192407) (xy 95.824581 -235.14837)
			(xy 95.801455 -235.100349) (xy 95.785745 -235.049419) (xy 95.777802 -234.996715) (xy 95.549222 -234.996715)
			(xy 95.541279 -235.049419) (xy 95.525569 -235.100349) (xy 95.502443 -235.14837) (xy 95.472419 -235.192407)
			(xy 95.436167 -235.231478) (xy 95.394496 -235.264709) (xy 95.348338 -235.291358) (xy 95.298724 -235.31083)
			(xy 95.246762 -235.32269) (xy 95.193612 -235.326674) (xy 95.140462 -235.32269) (xy 95.0885 -235.31083)
			(xy 95.038886 -235.291358) (xy 94.992728 -235.264709) (xy 94.951057 -235.231478) (xy 94.914805 -235.192407)
			(xy 94.884781 -235.14837) (xy 94.861655 -235.100349) (xy 94.845945 -235.049419) (xy 94.838002 -234.996715)
			(xy 94.609422 -234.996715) (xy 94.601479 -235.049419) (xy 94.585769 -235.100349) (xy 94.562643 -235.14837)
			(xy 94.532619 -235.192407) (xy 94.496367 -235.231478) (xy 94.454696 -235.264709) (xy 94.408538 -235.291358)
			(xy 94.358924 -235.31083) (xy 94.306962 -235.32269) (xy 94.253812 -235.326674) (xy 94.200662 -235.32269)
			(xy 94.1487 -235.31083) (xy 94.099086 -235.291358) (xy 94.052928 -235.264709) (xy 94.011257 -235.231478)
			(xy 93.975005 -235.192407) (xy 93.944981 -235.14837) (xy 93.921855 -235.100349) (xy 93.906145 -235.049419)
			(xy 93.898202 -234.996715) (xy 93.669622 -234.996715) (xy 93.661679 -235.049419) (xy 93.645969 -235.100349)
			(xy 93.622843 -235.14837) (xy 93.592819 -235.192407) (xy 93.556567 -235.231478) (xy 93.514896 -235.264709)
			(xy 93.468738 -235.291358) (xy 93.419124 -235.31083) (xy 93.367162 -235.32269) (xy 93.314012 -235.326674)
			(xy 93.260862 -235.32269) (xy 93.2089 -235.31083) (xy 93.159286 -235.291358) (xy 93.113128 -235.264709)
			(xy 93.071457 -235.231478) (xy 93.035205 -235.192407) (xy 93.005181 -235.14837) (xy 92.982055 -235.100349)
			(xy 92.966345 -235.049419) (xy 92.958402 -234.996715) (xy 92.729822 -234.996715) (xy 92.721879 -235.049419)
			(xy 92.706169 -235.100349) (xy 92.683043 -235.14837) (xy 92.653019 -235.192407) (xy 92.616767 -235.231478)
			(xy 92.575096 -235.264709) (xy 92.528938 -235.291358) (xy 92.479324 -235.31083) (xy 92.427362 -235.32269)
			(xy 92.374212 -235.326674) (xy 92.321062 -235.32269) (xy 92.2691 -235.31083) (xy 92.219486 -235.291358)
			(xy 92.173328 -235.264709) (xy 92.131657 -235.231478) (xy 92.095405 -235.192407) (xy 92.065381 -235.14837)
			(xy 92.042255 -235.100349) (xy 92.026545 -235.049419) (xy 92.018602 -234.996715) (xy 91.790022 -234.996715)
			(xy 91.782079 -235.049419) (xy 91.766369 -235.100349) (xy 91.743243 -235.14837) (xy 91.713219 -235.192407)
			(xy 91.676967 -235.231478) (xy 91.635296 -235.264709) (xy 91.589138 -235.291358) (xy 91.539524 -235.31083)
			(xy 91.487562 -235.32269) (xy 91.434412 -235.326674) (xy 91.381262 -235.32269) (xy 91.3293 -235.31083)
			(xy 91.279686 -235.291358) (xy 91.233528 -235.264709) (xy 91.191857 -235.231478) (xy 91.155605 -235.192407)
			(xy 91.125581 -235.14837) (xy 91.102455 -235.100349) (xy 91.086745 -235.049419) (xy 91.078802 -234.996715)
			(xy 90.850476 -234.996715) (xy 90.842533 -235.049419) (xy 90.826823 -235.100349) (xy 90.803697 -235.14837)
			(xy 90.773673 -235.192407) (xy 90.737421 -235.231478) (xy 90.69575 -235.264709) (xy 90.649592 -235.291358)
			(xy 90.599978 -235.31083) (xy 90.548016 -235.32269) (xy 90.494866 -235.326674) (xy 90.441716 -235.32269)
			(xy 90.389754 -235.31083) (xy 90.34014 -235.291358) (xy 90.293982 -235.264709) (xy 90.252311 -235.231478)
			(xy 90.216059 -235.192407) (xy 90.186035 -235.14837) (xy 90.162909 -235.100349) (xy 90.147199 -235.049419)
			(xy 90.139256 -234.996715) (xy 89.910422 -234.996715) (xy 89.902479 -235.049419) (xy 89.886769 -235.100349)
			(xy 89.863643 -235.14837) (xy 89.833619 -235.192407) (xy 89.797367 -235.231478) (xy 89.755696 -235.264709)
			(xy 89.709538 -235.291358) (xy 89.659924 -235.31083) (xy 89.607962 -235.32269) (xy 89.554812 -235.326674)
			(xy 89.501662 -235.32269) (xy 89.4497 -235.31083) (xy 89.400086 -235.291358) (xy 89.353928 -235.264709)
			(xy 89.312257 -235.231478) (xy 89.276005 -235.192407) (xy 89.245981 -235.14837) (xy 89.222855 -235.100349)
			(xy 89.207145 -235.049419) (xy 89.199202 -234.996715) (xy 88.969649 -234.996715) (xy 88.967713 -235.022782)
			(xy 88.956058 -235.074319) (xy 88.936916 -235.123567) (xy 88.910707 -235.169447) (xy 88.878008 -235.210951)
			(xy 88.839534 -235.247167) (xy 88.796132 -235.277302) (xy 88.748754 -235.300693) (xy 88.723724 -235.309156)
			(xy 88.688418 -235.320586) (xy 88.688418 -235.434124) (xy 88.688915 -235.448579) (xy 88.697005 -235.476334)
			(xy 88.712557 -235.500705) (xy 88.734322 -235.519733) (xy 88.760552 -235.531891) (xy 88.789139 -235.536201)
			(xy 88.817787 -235.532318) (xy 88.844195 -235.520553) (xy 88.85555 -235.511594) (xy 88.874909 -235.495829)
			(xy 88.917203 -235.469304) (xy 88.962787 -235.448944) (xy 89.010767 -235.435149) (xy 89.060204 -235.428187)
			(xy 89.085166 -235.427774) (xy 89.11182 -235.428245) (xy 89.164534 -235.436185) (xy 89.215475 -235.451894)
			(xy 89.263505 -235.475021) (xy 89.307552 -235.505048) (xy 89.346632 -235.541305) (xy 89.379871 -235.582981)
			(xy 89.406526 -235.629147) (xy 89.426003 -235.678769) (xy 89.437866 -235.730741) (xy 89.44185 -235.7839)
			(xy 89.439854 -235.810531) (xy 89.669356 -235.810531) (xy 89.669356 -235.757233) (xy 89.677299 -235.704529)
			(xy 89.693009 -235.653599) (xy 89.716135 -235.605578) (xy 89.746159 -235.561541) (xy 89.782411 -235.52247)
			(xy 89.824082 -235.489239) (xy 89.87024 -235.46259) (xy 89.919854 -235.443118) (xy 89.971816 -235.431258)
			(xy 90.024966 -235.427275) (xy 90.078116 -235.431258) (xy 90.130078 -235.443118) (xy 90.179692 -235.46259)
			(xy 90.22585 -235.489239) (xy 90.267521 -235.52247) (xy 90.303773 -235.561541) (xy 90.333797 -235.605578)
			(xy 90.356923 -235.653599) (xy 90.372633 -235.704529) (xy 90.380576 -235.757233) (xy 90.381074 -235.783882)
			(xy 90.380576 -235.810531) (xy 90.608902 -235.810531) (xy 90.608902 -235.757233) (xy 90.616845 -235.704529)
			(xy 90.632555 -235.653599) (xy 90.655681 -235.605578) (xy 90.685705 -235.561541) (xy 90.721957 -235.52247)
			(xy 90.763628 -235.489239) (xy 90.809786 -235.46259) (xy 90.8594 -235.443118) (xy 90.911362 -235.431258)
			(xy 90.964512 -235.427275) (xy 91.017662 -235.431258) (xy 91.069624 -235.443118) (xy 91.119238 -235.46259)
			(xy 91.165396 -235.489239) (xy 91.207067 -235.52247) (xy 91.243319 -235.561541) (xy 91.273343 -235.605578)
			(xy 91.296469 -235.653599) (xy 91.312179 -235.704529) (xy 91.320122 -235.757233) (xy 91.32062 -235.783882)
			(xy 91.320122 -235.810531) (xy 91.548956 -235.810531) (xy 91.548956 -235.757233) (xy 91.556899 -235.704529)
			(xy 91.572609 -235.653599) (xy 91.595735 -235.605578) (xy 91.625759 -235.561541) (xy 91.662011 -235.52247)
			(xy 91.703682 -235.489239) (xy 91.74984 -235.46259) (xy 91.799454 -235.443118) (xy 91.851416 -235.431258)
			(xy 91.904566 -235.427275) (xy 91.957716 -235.431258) (xy 92.009678 -235.443118) (xy 92.059292 -235.46259)
			(xy 92.10545 -235.489239) (xy 92.147121 -235.52247) (xy 92.183373 -235.561541) (xy 92.213397 -235.605578)
			(xy 92.236523 -235.653599) (xy 92.252233 -235.704529) (xy 92.260176 -235.757233) (xy 92.260674 -235.783882)
			(xy 92.260176 -235.810531) (xy 92.488756 -235.810531) (xy 92.488756 -235.757233) (xy 92.496699 -235.704529)
			(xy 92.512409 -235.653599) (xy 92.535535 -235.605578) (xy 92.565559 -235.561541) (xy 92.601811 -235.52247)
			(xy 92.643482 -235.489239) (xy 92.68964 -235.46259) (xy 92.739254 -235.443118) (xy 92.791216 -235.431258)
			(xy 92.844366 -235.427275) (xy 92.897516 -235.431258) (xy 92.949478 -235.443118) (xy 92.999092 -235.46259)
			(xy 93.04525 -235.489239) (xy 93.086921 -235.52247) (xy 93.123173 -235.561541) (xy 93.153197 -235.605578)
			(xy 93.176323 -235.653599) (xy 93.192033 -235.704529) (xy 93.199976 -235.757233) (xy 93.200474 -235.783882)
			(xy 93.199976 -235.810531) (xy 93.428556 -235.810531) (xy 93.428556 -235.757233) (xy 93.436499 -235.704529)
			(xy 93.452209 -235.653599) (xy 93.475335 -235.605578) (xy 93.505359 -235.561541) (xy 93.541611 -235.52247)
			(xy 93.583282 -235.489239) (xy 93.62944 -235.46259) (xy 93.679054 -235.443118) (xy 93.731016 -235.431258)
			(xy 93.784166 -235.427275) (xy 93.837316 -235.431258) (xy 93.889278 -235.443118) (xy 93.938892 -235.46259)
			(xy 93.98505 -235.489239) (xy 94.026721 -235.52247) (xy 94.062973 -235.561541) (xy 94.092997 -235.605578)
			(xy 94.116123 -235.653599) (xy 94.131833 -235.704529) (xy 94.139776 -235.757233) (xy 94.140274 -235.783882)
			(xy 94.139776 -235.810531) (xy 94.368356 -235.810531) (xy 94.368356 -235.757233) (xy 94.376299 -235.704529)
			(xy 94.392009 -235.653599) (xy 94.415135 -235.605578) (xy 94.445159 -235.561541) (xy 94.481411 -235.52247)
			(xy 94.523082 -235.489239) (xy 94.56924 -235.46259) (xy 94.618854 -235.443118) (xy 94.670816 -235.431258)
			(xy 94.723966 -235.427275) (xy 94.777116 -235.431258) (xy 94.829078 -235.443118) (xy 94.878692 -235.46259)
			(xy 94.92485 -235.489239) (xy 94.966521 -235.52247) (xy 95.002773 -235.561541) (xy 95.032797 -235.605578)
			(xy 95.055923 -235.653599) (xy 95.071633 -235.704529) (xy 95.079576 -235.757233) (xy 95.080074 -235.783882)
			(xy 95.079576 -235.810531) (xy 95.308156 -235.810531) (xy 95.308156 -235.757233) (xy 95.316099 -235.704529)
			(xy 95.331809 -235.653599) (xy 95.354935 -235.605578) (xy 95.384959 -235.561541) (xy 95.421211 -235.52247)
			(xy 95.462882 -235.489239) (xy 95.50904 -235.46259) (xy 95.558654 -235.443118) (xy 95.610616 -235.431258)
			(xy 95.663766 -235.427275) (xy 95.716916 -235.431258) (xy 95.768878 -235.443118) (xy 95.818492 -235.46259)
			(xy 95.86465 -235.489239) (xy 95.906321 -235.52247) (xy 95.942573 -235.561541) (xy 95.972597 -235.605578)
			(xy 95.995723 -235.653599) (xy 96.011433 -235.704529) (xy 96.019376 -235.757233) (xy 96.019874 -235.783882)
			(xy 96.019376 -235.810531) (xy 96.247956 -235.810531) (xy 96.247956 -235.757233) (xy 96.255899 -235.704529)
			(xy 96.271609 -235.653599) (xy 96.294735 -235.605578) (xy 96.324759 -235.561541) (xy 96.361011 -235.52247)
			(xy 96.402682 -235.489239) (xy 96.44884 -235.46259) (xy 96.498454 -235.443118) (xy 96.550416 -235.431258)
			(xy 96.603566 -235.427275) (xy 96.656716 -235.431258) (xy 96.708678 -235.443118) (xy 96.758292 -235.46259)
			(xy 96.80445 -235.489239) (xy 96.846121 -235.52247) (xy 96.882373 -235.561541) (xy 96.912397 -235.605578)
			(xy 96.935523 -235.653599) (xy 96.951233 -235.704529) (xy 96.959176 -235.757233) (xy 96.959674 -235.783882)
			(xy 96.959176 -235.810531) (xy 97.187502 -235.810531) (xy 97.187502 -235.757233) (xy 97.195445 -235.704529)
			(xy 97.211155 -235.653599) (xy 97.234281 -235.605578) (xy 97.264305 -235.561541) (xy 97.300557 -235.52247)
			(xy 97.342228 -235.489239) (xy 97.388386 -235.46259) (xy 97.438 -235.443118) (xy 97.489962 -235.431258)
			(xy 97.543112 -235.427275) (xy 97.596262 -235.431258) (xy 97.648224 -235.443118) (xy 97.697838 -235.46259)
			(xy 97.743996 -235.489239) (xy 97.785667 -235.52247) (xy 97.821919 -235.561541) (xy 97.851943 -235.605578)
			(xy 97.875069 -235.653599) (xy 97.890779 -235.704529) (xy 97.898722 -235.757233) (xy 97.89922 -235.783882)
			(xy 97.898722 -235.810531) (xy 98.127556 -235.810531) (xy 98.127556 -235.757233) (xy 98.135499 -235.704529)
			(xy 98.151209 -235.653599) (xy 98.174335 -235.605578) (xy 98.204359 -235.561541) (xy 98.240611 -235.52247)
			(xy 98.282282 -235.489239) (xy 98.32844 -235.46259) (xy 98.378054 -235.443118) (xy 98.430016 -235.431258)
			(xy 98.483166 -235.427275) (xy 98.536316 -235.431258) (xy 98.588278 -235.443118) (xy 98.637892 -235.46259)
			(xy 98.68405 -235.489239) (xy 98.725721 -235.52247) (xy 98.761973 -235.561541) (xy 98.791997 -235.605578)
			(xy 98.815123 -235.653599) (xy 98.830833 -235.704529) (xy 98.838776 -235.757233) (xy 98.839274 -235.783882)
			(xy 98.838776 -235.810531) (xy 99.067356 -235.810531) (xy 99.067356 -235.757233) (xy 99.075299 -235.704529)
			(xy 99.091009 -235.653599) (xy 99.114135 -235.605578) (xy 99.144159 -235.561541) (xy 99.180411 -235.52247)
			(xy 99.222082 -235.489239) (xy 99.26824 -235.46259) (xy 99.317854 -235.443118) (xy 99.369816 -235.431258)
			(xy 99.422966 -235.427275) (xy 99.476116 -235.431258) (xy 99.528078 -235.443118) (xy 99.577692 -235.46259)
			(xy 99.62385 -235.489239) (xy 99.665521 -235.52247) (xy 99.701773 -235.561541) (xy 99.731797 -235.605578)
			(xy 99.754923 -235.653599) (xy 99.770633 -235.704529) (xy 99.778576 -235.757233) (xy 99.779074 -235.783882)
			(xy 99.778576 -235.810531) (xy 100.007156 -235.810531) (xy 100.007156 -235.757233) (xy 100.015099 -235.704529)
			(xy 100.030809 -235.653599) (xy 100.053935 -235.605578) (xy 100.083959 -235.561541) (xy 100.120211 -235.52247)
			(xy 100.161882 -235.489239) (xy 100.20804 -235.46259) (xy 100.257654 -235.443118) (xy 100.309616 -235.431258)
			(xy 100.362766 -235.427275) (xy 100.415916 -235.431258) (xy 100.467878 -235.443118) (xy 100.517492 -235.46259)
			(xy 100.56365 -235.489239) (xy 100.605321 -235.52247) (xy 100.641573 -235.561541) (xy 100.671597 -235.605578)
			(xy 100.694723 -235.653599) (xy 100.710433 -235.704529) (xy 100.718376 -235.757233) (xy 100.718874 -235.783882)
			(xy 100.718376 -235.810531) (xy 100.946956 -235.810531) (xy 100.946956 -235.757233) (xy 100.954899 -235.704529)
			(xy 100.970609 -235.653599) (xy 100.993735 -235.605578) (xy 101.023759 -235.561541) (xy 101.060011 -235.52247)
			(xy 101.101682 -235.489239) (xy 101.14784 -235.46259) (xy 101.197454 -235.443118) (xy 101.249416 -235.431258)
			(xy 101.302566 -235.427275) (xy 101.355716 -235.431258) (xy 101.407678 -235.443118) (xy 101.457292 -235.46259)
			(xy 101.50345 -235.489239) (xy 101.545121 -235.52247) (xy 101.581373 -235.561541) (xy 101.611397 -235.605578)
			(xy 101.634523 -235.653599) (xy 101.650233 -235.704529) (xy 101.658176 -235.757233) (xy 101.658674 -235.783882)
			(xy 101.658176 -235.810531) (xy 101.886756 -235.810531) (xy 101.886756 -235.757233) (xy 101.894699 -235.704529)
			(xy 101.910409 -235.653599) (xy 101.933535 -235.605578) (xy 101.963559 -235.561541) (xy 101.999811 -235.52247)
			(xy 102.041482 -235.489239) (xy 102.08764 -235.46259) (xy 102.137254 -235.443118) (xy 102.189216 -235.431258)
			(xy 102.242366 -235.427275) (xy 102.295516 -235.431258) (xy 102.347478 -235.443118) (xy 102.385991 -235.458233)
			(xy 105.874556 -235.458233) (xy 105.874556 -235.404935) (xy 105.882499 -235.352231) (xy 105.898209 -235.301301)
			(xy 105.921335 -235.25328) (xy 105.951359 -235.209243) (xy 105.987611 -235.170172) (xy 106.029282 -235.136941)
			(xy 106.07544 -235.110292) (xy 106.125054 -235.09082) (xy 106.177016 -235.07896) (xy 106.230166 -235.074977)
			(xy 106.283316 -235.07896) (xy 106.335278 -235.09082) (xy 106.384892 -235.110292) (xy 106.43105 -235.136941)
			(xy 106.472721 -235.170172) (xy 106.508973 -235.209243) (xy 106.538997 -235.25328) (xy 106.562123 -235.301301)
			(xy 106.577833 -235.352231) (xy 106.585776 -235.404935) (xy 106.586274 -235.431584) (xy 106.585776 -235.458233)
			(xy 106.577833 -235.510937) (xy 106.562123 -235.561867) (xy 106.538997 -235.609888) (xy 106.508973 -235.653925)
			(xy 106.472721 -235.692996) (xy 106.43105 -235.726227) (xy 106.384892 -235.752876) (xy 106.335278 -235.772348)
			(xy 106.283316 -235.784208) (xy 106.230166 -235.788192) (xy 106.177016 -235.784208) (xy 106.125054 -235.772348)
			(xy 106.07544 -235.752876) (xy 106.029282 -235.726227) (xy 105.987611 -235.692996) (xy 105.951359 -235.653925)
			(xy 105.921335 -235.609888) (xy 105.898209 -235.561867) (xy 105.882499 -235.510937) (xy 105.874556 -235.458233)
			(xy 102.385991 -235.458233) (xy 102.397092 -235.46259) (xy 102.44325 -235.489239) (xy 102.484921 -235.52247)
			(xy 102.521173 -235.561541) (xy 102.551197 -235.605578) (xy 102.574323 -235.653599) (xy 102.590033 -235.704529)
			(xy 102.597976 -235.757233) (xy 102.598474 -235.783882) (xy 102.597976 -235.810531) (xy 102.590033 -235.863235)
			(xy 102.574323 -235.914165) (xy 102.551197 -235.962186) (xy 102.521173 -236.006223) (xy 102.484921 -236.045294)
			(xy 102.44325 -236.078525) (xy 102.397092 -236.105174) (xy 102.347478 -236.124646) (xy 102.295516 -236.136506)
			(xy 102.242366 -236.14049) (xy 102.189216 -236.136506) (xy 102.137254 -236.124646) (xy 102.08764 -236.105174)
			(xy 102.041482 -236.078525) (xy 101.999811 -236.045294) (xy 101.963559 -236.006223) (xy 101.933535 -235.962186)
			(xy 101.910409 -235.914165) (xy 101.894699 -235.863235) (xy 101.886756 -235.810531) (xy 101.658176 -235.810531)
			(xy 101.650233 -235.863235) (xy 101.634523 -235.914165) (xy 101.611397 -235.962186) (xy 101.581373 -236.006223)
			(xy 101.545121 -236.045294) (xy 101.50345 -236.078525) (xy 101.457292 -236.105174) (xy 101.407678 -236.124646)
			(xy 101.355716 -236.136506) (xy 101.302566 -236.14049) (xy 101.249416 -236.136506) (xy 101.197454 -236.124646)
			(xy 101.14784 -236.105174) (xy 101.101682 -236.078525) (xy 101.060011 -236.045294) (xy 101.023759 -236.006223)
			(xy 100.993735 -235.962186) (xy 100.970609 -235.914165) (xy 100.954899 -235.863235) (xy 100.946956 -235.810531)
			(xy 100.718376 -235.810531) (xy 100.710433 -235.863235) (xy 100.694723 -235.914165) (xy 100.671597 -235.962186)
			(xy 100.641573 -236.006223) (xy 100.605321 -236.045294) (xy 100.56365 -236.078525) (xy 100.517492 -236.105174)
			(xy 100.467878 -236.124646) (xy 100.415916 -236.136506) (xy 100.362766 -236.14049) (xy 100.309616 -236.136506)
			(xy 100.257654 -236.124646) (xy 100.20804 -236.105174) (xy 100.161882 -236.078525) (xy 100.120211 -236.045294)
			(xy 100.083959 -236.006223) (xy 100.053935 -235.962186) (xy 100.030809 -235.914165) (xy 100.015099 -235.863235)
			(xy 100.007156 -235.810531) (xy 99.778576 -235.810531) (xy 99.770633 -235.863235) (xy 99.754923 -235.914165)
			(xy 99.731797 -235.962186) (xy 99.701773 -236.006223) (xy 99.665521 -236.045294) (xy 99.62385 -236.078525)
			(xy 99.577692 -236.105174) (xy 99.528078 -236.124646) (xy 99.476116 -236.136506) (xy 99.422966 -236.14049)
			(xy 99.369816 -236.136506) (xy 99.317854 -236.124646) (xy 99.26824 -236.105174) (xy 99.222082 -236.078525)
			(xy 99.180411 -236.045294) (xy 99.144159 -236.006223) (xy 99.114135 -235.962186) (xy 99.091009 -235.914165)
			(xy 99.075299 -235.863235) (xy 99.067356 -235.810531) (xy 98.838776 -235.810531) (xy 98.830833 -235.863235)
			(xy 98.815123 -235.914165) (xy 98.791997 -235.962186) (xy 98.761973 -236.006223) (xy 98.725721 -236.045294)
			(xy 98.68405 -236.078525) (xy 98.637892 -236.105174) (xy 98.588278 -236.124646) (xy 98.536316 -236.136506)
			(xy 98.483166 -236.14049) (xy 98.430016 -236.136506) (xy 98.378054 -236.124646) (xy 98.32844 -236.105174)
			(xy 98.282282 -236.078525) (xy 98.240611 -236.045294) (xy 98.204359 -236.006223) (xy 98.174335 -235.962186)
			(xy 98.151209 -235.914165) (xy 98.135499 -235.863235) (xy 98.127556 -235.810531) (xy 97.898722 -235.810531)
			(xy 97.890779 -235.863235) (xy 97.875069 -235.914165) (xy 97.851943 -235.962186) (xy 97.821919 -236.006223)
			(xy 97.785667 -236.045294) (xy 97.743996 -236.078525) (xy 97.697838 -236.105174) (xy 97.648224 -236.124646)
			(xy 97.596262 -236.136506) (xy 97.543112 -236.14049) (xy 97.489962 -236.136506) (xy 97.438 -236.124646)
			(xy 97.388386 -236.105174) (xy 97.342228 -236.078525) (xy 97.300557 -236.045294) (xy 97.264305 -236.006223)
			(xy 97.234281 -235.962186) (xy 97.211155 -235.914165) (xy 97.195445 -235.863235) (xy 97.187502 -235.810531)
			(xy 96.959176 -235.810531) (xy 96.951233 -235.863235) (xy 96.935523 -235.914165) (xy 96.912397 -235.962186)
			(xy 96.882373 -236.006223) (xy 96.846121 -236.045294) (xy 96.80445 -236.078525) (xy 96.758292 -236.105174)
			(xy 96.708678 -236.124646) (xy 96.656716 -236.136506) (xy 96.603566 -236.14049) (xy 96.550416 -236.136506)
			(xy 96.498454 -236.124646) (xy 96.44884 -236.105174) (xy 96.402682 -236.078525) (xy 96.361011 -236.045294)
			(xy 96.324759 -236.006223) (xy 96.294735 -235.962186) (xy 96.271609 -235.914165) (xy 96.255899 -235.863235)
			(xy 96.247956 -235.810531) (xy 96.019376 -235.810531) (xy 96.011433 -235.863235) (xy 95.995723 -235.914165)
			(xy 95.972597 -235.962186) (xy 95.942573 -236.006223) (xy 95.906321 -236.045294) (xy 95.86465 -236.078525)
			(xy 95.818492 -236.105174) (xy 95.768878 -236.124646) (xy 95.716916 -236.136506) (xy 95.663766 -236.14049)
			(xy 95.610616 -236.136506) (xy 95.558654 -236.124646) (xy 95.50904 -236.105174) (xy 95.462882 -236.078525)
			(xy 95.421211 -236.045294) (xy 95.384959 -236.006223) (xy 95.354935 -235.962186) (xy 95.331809 -235.914165)
			(xy 95.316099 -235.863235) (xy 95.308156 -235.810531) (xy 95.079576 -235.810531) (xy 95.071633 -235.863235)
			(xy 95.055923 -235.914165) (xy 95.032797 -235.962186) (xy 95.002773 -236.006223) (xy 94.966521 -236.045294)
			(xy 94.92485 -236.078525) (xy 94.878692 -236.105174) (xy 94.829078 -236.124646) (xy 94.777116 -236.136506)
			(xy 94.723966 -236.14049) (xy 94.670816 -236.136506) (xy 94.618854 -236.124646) (xy 94.56924 -236.105174)
			(xy 94.523082 -236.078525) (xy 94.481411 -236.045294) (xy 94.445159 -236.006223) (xy 94.415135 -235.962186)
			(xy 94.392009 -235.914165) (xy 94.376299 -235.863235) (xy 94.368356 -235.810531) (xy 94.139776 -235.810531)
			(xy 94.131833 -235.863235) (xy 94.116123 -235.914165) (xy 94.092997 -235.962186) (xy 94.062973 -236.006223)
			(xy 94.026721 -236.045294) (xy 93.98505 -236.078525) (xy 93.938892 -236.105174) (xy 93.889278 -236.124646)
			(xy 93.837316 -236.136506) (xy 93.784166 -236.14049) (xy 93.731016 -236.136506) (xy 93.679054 -236.124646)
			(xy 93.62944 -236.105174) (xy 93.583282 -236.078525) (xy 93.541611 -236.045294) (xy 93.505359 -236.006223)
			(xy 93.475335 -235.962186) (xy 93.452209 -235.914165) (xy 93.436499 -235.863235) (xy 93.428556 -235.810531)
			(xy 93.199976 -235.810531) (xy 93.192033 -235.863235) (xy 93.176323 -235.914165) (xy 93.153197 -235.962186)
			(xy 93.123173 -236.006223) (xy 93.086921 -236.045294) (xy 93.04525 -236.078525) (xy 92.999092 -236.105174)
			(xy 92.949478 -236.124646) (xy 92.897516 -236.136506) (xy 92.844366 -236.14049) (xy 92.791216 -236.136506)
			(xy 92.739254 -236.124646) (xy 92.68964 -236.105174) (xy 92.643482 -236.078525) (xy 92.601811 -236.045294)
			(xy 92.565559 -236.006223) (xy 92.535535 -235.962186) (xy 92.512409 -235.914165) (xy 92.496699 -235.863235)
			(xy 92.488756 -235.810531) (xy 92.260176 -235.810531) (xy 92.252233 -235.863235) (xy 92.236523 -235.914165)
			(xy 92.213397 -235.962186) (xy 92.183373 -236.006223) (xy 92.147121 -236.045294) (xy 92.10545 -236.078525)
			(xy 92.059292 -236.105174) (xy 92.009678 -236.124646) (xy 91.957716 -236.136506) (xy 91.904566 -236.14049)
			(xy 91.851416 -236.136506) (xy 91.799454 -236.124646) (xy 91.74984 -236.105174) (xy 91.703682 -236.078525)
			(xy 91.662011 -236.045294) (xy 91.625759 -236.006223) (xy 91.595735 -235.962186) (xy 91.572609 -235.914165)
			(xy 91.556899 -235.863235) (xy 91.548956 -235.810531) (xy 91.320122 -235.810531) (xy 91.312179 -235.863235)
			(xy 91.296469 -235.914165) (xy 91.273343 -235.962186) (xy 91.243319 -236.006223) (xy 91.207067 -236.045294)
			(xy 91.165396 -236.078525) (xy 91.119238 -236.105174) (xy 91.069624 -236.124646) (xy 91.017662 -236.136506)
			(xy 90.964512 -236.14049) (xy 90.911362 -236.136506) (xy 90.8594 -236.124646) (xy 90.809786 -236.105174)
			(xy 90.763628 -236.078525) (xy 90.721957 -236.045294) (xy 90.685705 -236.006223) (xy 90.655681 -235.962186)
			(xy 90.632555 -235.914165) (xy 90.616845 -235.863235) (xy 90.608902 -235.810531) (xy 90.380576 -235.810531)
			(xy 90.372633 -235.863235) (xy 90.356923 -235.914165) (xy 90.333797 -235.962186) (xy 90.303773 -236.006223)
			(xy 90.267521 -236.045294) (xy 90.22585 -236.078525) (xy 90.179692 -236.105174) (xy 90.130078 -236.124646)
			(xy 90.078116 -236.136506) (xy 90.024966 -236.14049) (xy 89.971816 -236.136506) (xy 89.919854 -236.124646)
			(xy 89.87024 -236.105174) (xy 89.824082 -236.078525) (xy 89.782411 -236.045294) (xy 89.746159 -236.006223)
			(xy 89.716135 -235.962186) (xy 89.693009 -235.914165) (xy 89.677299 -235.863235) (xy 89.669356 -235.810531)
			(xy 89.439854 -235.810531) (xy 89.437866 -235.837059) (xy 89.426003 -235.889031) (xy 89.406526 -235.938653)
			(xy 89.379871 -235.984819) (xy 89.346632 -236.026495) (xy 89.307552 -236.062752) (xy 89.263505 -236.092779)
			(xy 89.215475 -236.115906) (xy 89.164534 -236.131615) (xy 89.11182 -236.139555) (xy 89.085166 -236.13999)
			(xy 89.060205 -236.139569) (xy 89.010772 -236.1326) (xy 88.962794 -236.118801) (xy 88.917211 -236.098444)
			(xy 88.874914 -236.071927) (xy 88.85555 -236.05617) (xy 88.844189 -236.047237) (xy 88.817783 -236.035526)
			(xy 88.789154 -236.031678) (xy 88.760592 -236.036) (xy 88.734383 -236.048147) (xy 88.712624 -236.067147)
			(xy 88.697056 -236.091479) (xy 88.688924 -236.119197) (xy 88.688418 -236.13364) (xy 88.688418 -236.247432)
			(xy 88.723724 -236.258862) (xy 88.748763 -236.267359) (xy 88.796202 -236.290706) (xy 88.839666 -236.320813)
			(xy 88.878198 -236.357018) (xy 88.910952 -236.398524) (xy 88.937207 -236.444418) (xy 88.956384 -236.493691)
			(xy 88.968063 -236.545258) (xy 88.971986 -236.597985) (xy 88.970008 -236.624601) (xy 89.199202 -236.624601)
			(xy 89.199202 -236.571303) (xy 89.207145 -236.518599) (xy 89.222855 -236.467669) (xy 89.245981 -236.419648)
			(xy 89.276005 -236.375611) (xy 89.312257 -236.33654) (xy 89.353928 -236.303309) (xy 89.400086 -236.27666)
			(xy 89.4497 -236.257188) (xy 89.501662 -236.245328) (xy 89.554812 -236.241345) (xy 89.607962 -236.245328)
			(xy 89.659924 -236.257188) (xy 89.709538 -236.27666) (xy 89.755696 -236.303309) (xy 89.797367 -236.33654)
			(xy 89.833619 -236.375611) (xy 89.863643 -236.419648) (xy 89.886769 -236.467669) (xy 89.902479 -236.518599)
			(xy 89.910422 -236.571303) (xy 89.91092 -236.597952) (xy 89.910422 -236.624601) (xy 90.139002 -236.624601)
			(xy 90.139002 -236.571303) (xy 90.146945 -236.518599) (xy 90.162655 -236.467669) (xy 90.185781 -236.419648)
			(xy 90.215805 -236.375611) (xy 90.252057 -236.33654) (xy 90.293728 -236.303309) (xy 90.339886 -236.27666)
			(xy 90.3895 -236.257188) (xy 90.441462 -236.245328) (xy 90.494612 -236.241345) (xy 90.547762 -236.245328)
			(xy 90.599724 -236.257188) (xy 90.649338 -236.27666) (xy 90.695496 -236.303309) (xy 90.737167 -236.33654)
			(xy 90.773419 -236.375611) (xy 90.803443 -236.419648) (xy 90.826569 -236.467669) (xy 90.842279 -236.518599)
			(xy 90.850222 -236.571303) (xy 90.85072 -236.597952) (xy 90.850222 -236.624601) (xy 91.078802 -236.624601)
			(xy 91.078802 -236.571303) (xy 91.086745 -236.518599) (xy 91.102455 -236.467669) (xy 91.125581 -236.419648)
			(xy 91.155605 -236.375611) (xy 91.191857 -236.33654) (xy 91.233528 -236.303309) (xy 91.279686 -236.27666)
			(xy 91.3293 -236.257188) (xy 91.381262 -236.245328) (xy 91.434412 -236.241345) (xy 91.487562 -236.245328)
			(xy 91.539524 -236.257188) (xy 91.589138 -236.27666) (xy 91.635296 -236.303309) (xy 91.676967 -236.33654)
			(xy 91.713219 -236.375611) (xy 91.743243 -236.419648) (xy 91.766369 -236.467669) (xy 91.782079 -236.518599)
			(xy 91.790022 -236.571303) (xy 91.79052 -236.597952) (xy 91.790022 -236.624601) (xy 92.018602 -236.624601)
			(xy 92.018602 -236.571303) (xy 92.026545 -236.518599) (xy 92.042255 -236.467669) (xy 92.065381 -236.419648)
			(xy 92.095405 -236.375611) (xy 92.131657 -236.33654) (xy 92.173328 -236.303309) (xy 92.219486 -236.27666)
			(xy 92.2691 -236.257188) (xy 92.321062 -236.245328) (xy 92.374212 -236.241345) (xy 92.427362 -236.245328)
			(xy 92.479324 -236.257188) (xy 92.528938 -236.27666) (xy 92.575096 -236.303309) (xy 92.616767 -236.33654)
			(xy 92.653019 -236.375611) (xy 92.683043 -236.419648) (xy 92.706169 -236.467669) (xy 92.721879 -236.518599)
			(xy 92.729822 -236.571303) (xy 92.73032 -236.597952) (xy 92.729822 -236.624601) (xy 92.958402 -236.624601)
			(xy 92.958402 -236.571303) (xy 92.966345 -236.518599) (xy 92.982055 -236.467669) (xy 93.005181 -236.419648)
			(xy 93.035205 -236.375611) (xy 93.071457 -236.33654) (xy 93.113128 -236.303309) (xy 93.159286 -236.27666)
			(xy 93.2089 -236.257188) (xy 93.260862 -236.245328) (xy 93.314012 -236.241345) (xy 93.367162 -236.245328)
			(xy 93.419124 -236.257188) (xy 93.468738 -236.27666) (xy 93.514896 -236.303309) (xy 93.556567 -236.33654)
			(xy 93.592819 -236.375611) (xy 93.622843 -236.419648) (xy 93.645969 -236.467669) (xy 93.661679 -236.518599)
			(xy 93.669622 -236.571303) (xy 93.67012 -236.597952) (xy 93.669622 -236.624601) (xy 93.898456 -236.624601)
			(xy 93.898456 -236.571303) (xy 93.906399 -236.518599) (xy 93.922109 -236.467669) (xy 93.945235 -236.419648)
			(xy 93.975259 -236.375611) (xy 94.011511 -236.33654) (xy 94.053182 -236.303309) (xy 94.09934 -236.27666)
			(xy 94.148954 -236.257188) (xy 94.200916 -236.245328) (xy 94.254066 -236.241345) (xy 94.307216 -236.245328)
			(xy 94.359178 -236.257188) (xy 94.408792 -236.27666) (xy 94.45495 -236.303309) (xy 94.496621 -236.33654)
			(xy 94.532873 -236.375611) (xy 94.562897 -236.419648) (xy 94.586023 -236.467669) (xy 94.601733 -236.518599)
			(xy 94.609676 -236.571303) (xy 94.610174 -236.597952) (xy 94.609676 -236.624601) (xy 94.838002 -236.624601)
			(xy 94.838002 -236.571303) (xy 94.845945 -236.518599) (xy 94.861655 -236.467669) (xy 94.884781 -236.419648)
			(xy 94.914805 -236.375611) (xy 94.951057 -236.33654) (xy 94.992728 -236.303309) (xy 95.038886 -236.27666)
			(xy 95.0885 -236.257188) (xy 95.140462 -236.245328) (xy 95.193612 -236.241345) (xy 95.246762 -236.245328)
			(xy 95.298724 -236.257188) (xy 95.348338 -236.27666) (xy 95.394496 -236.303309) (xy 95.436167 -236.33654)
			(xy 95.472419 -236.375611) (xy 95.502443 -236.419648) (xy 95.525569 -236.467669) (xy 95.541279 -236.518599)
			(xy 95.549222 -236.571303) (xy 95.54972 -236.597952) (xy 95.549222 -236.624601) (xy 95.777802 -236.624601)
			(xy 95.777802 -236.571303) (xy 95.785745 -236.518599) (xy 95.801455 -236.467669) (xy 95.824581 -236.419648)
			(xy 95.854605 -236.375611) (xy 95.890857 -236.33654) (xy 95.932528 -236.303309) (xy 95.978686 -236.27666)
			(xy 96.0283 -236.257188) (xy 96.080262 -236.245328) (xy 96.133412 -236.241345) (xy 96.186562 -236.245328)
			(xy 96.238524 -236.257188) (xy 96.288138 -236.27666) (xy 96.334296 -236.303309) (xy 96.375967 -236.33654)
			(xy 96.412219 -236.375611) (xy 96.442243 -236.419648) (xy 96.465369 -236.467669) (xy 96.481079 -236.518599)
			(xy 96.489022 -236.571303) (xy 96.48952 -236.597952) (xy 96.489022 -236.624601) (xy 96.717602 -236.624601)
			(xy 96.717602 -236.571303) (xy 96.725545 -236.518599) (xy 96.741255 -236.467669) (xy 96.764381 -236.419648)
			(xy 96.794405 -236.375611) (xy 96.830657 -236.33654) (xy 96.872328 -236.303309) (xy 96.918486 -236.27666)
			(xy 96.9681 -236.257188) (xy 97.020062 -236.245328) (xy 97.073212 -236.241345) (xy 97.126362 -236.245328)
			(xy 97.178324 -236.257188) (xy 97.227938 -236.27666) (xy 97.274096 -236.303309) (xy 97.315767 -236.33654)
			(xy 97.352019 -236.375611) (xy 97.382043 -236.419648) (xy 97.405169 -236.467669) (xy 97.420879 -236.518599)
			(xy 97.428822 -236.571303) (xy 97.42932 -236.597952) (xy 97.428822 -236.624601) (xy 97.657402 -236.624601)
			(xy 97.657402 -236.571303) (xy 97.665345 -236.518599) (xy 97.681055 -236.467669) (xy 97.704181 -236.419648)
			(xy 97.734205 -236.375611) (xy 97.770457 -236.33654) (xy 97.812128 -236.303309) (xy 97.858286 -236.27666)
			(xy 97.9079 -236.257188) (xy 97.959862 -236.245328) (xy 98.013012 -236.241345) (xy 98.066162 -236.245328)
			(xy 98.118124 -236.257188) (xy 98.167738 -236.27666) (xy 98.213896 -236.303309) (xy 98.255567 -236.33654)
			(xy 98.291819 -236.375611) (xy 98.321843 -236.419648) (xy 98.344969 -236.467669) (xy 98.360679 -236.518599)
			(xy 98.368622 -236.571303) (xy 98.36912 -236.597952) (xy 98.368622 -236.624601) (xy 98.597202 -236.624601)
			(xy 98.597202 -236.571303) (xy 98.605145 -236.518599) (xy 98.620855 -236.467669) (xy 98.643981 -236.419648)
			(xy 98.674005 -236.375611) (xy 98.710257 -236.33654) (xy 98.751928 -236.303309) (xy 98.798086 -236.27666)
			(xy 98.8477 -236.257188) (xy 98.899662 -236.245328) (xy 98.952812 -236.241345) (xy 99.005962 -236.245328)
			(xy 99.057924 -236.257188) (xy 99.107538 -236.27666) (xy 99.153696 -236.303309) (xy 99.195367 -236.33654)
			(xy 99.231619 -236.375611) (xy 99.261643 -236.419648) (xy 99.284769 -236.467669) (xy 99.300479 -236.518599)
			(xy 99.308422 -236.571303) (xy 99.30892 -236.597952) (xy 99.308422 -236.624601) (xy 99.537002 -236.624601)
			(xy 99.537002 -236.571303) (xy 99.544945 -236.518599) (xy 99.560655 -236.467669) (xy 99.583781 -236.419648)
			(xy 99.613805 -236.375611) (xy 99.650057 -236.33654) (xy 99.691728 -236.303309) (xy 99.737886 -236.27666)
			(xy 99.7875 -236.257188) (xy 99.839462 -236.245328) (xy 99.892612 -236.241345) (xy 99.945762 -236.245328)
			(xy 99.997724 -236.257188) (xy 100.047338 -236.27666) (xy 100.093496 -236.303309) (xy 100.135167 -236.33654)
			(xy 100.171419 -236.375611) (xy 100.201443 -236.419648) (xy 100.224569 -236.467669) (xy 100.240279 -236.518599)
			(xy 100.248222 -236.571303) (xy 100.24872 -236.597952) (xy 100.248222 -236.624601) (xy 100.477056 -236.624601)
			(xy 100.477056 -236.571303) (xy 100.484999 -236.518599) (xy 100.500709 -236.467669) (xy 100.523835 -236.419648)
			(xy 100.553859 -236.375611) (xy 100.590111 -236.33654) (xy 100.631782 -236.303309) (xy 100.67794 -236.27666)
			(xy 100.727554 -236.257188) (xy 100.779516 -236.245328) (xy 100.832666 -236.241345) (xy 100.885816 -236.245328)
			(xy 100.937778 -236.257188) (xy 100.987392 -236.27666) (xy 101.03355 -236.303309) (xy 101.075221 -236.33654)
			(xy 101.111473 -236.375611) (xy 101.141497 -236.419648) (xy 101.164623 -236.467669) (xy 101.180333 -236.518599)
			(xy 101.188276 -236.571303) (xy 101.188774 -236.597952) (xy 101.188276 -236.624601) (xy 101.416602 -236.624601)
			(xy 101.416602 -236.571303) (xy 101.424545 -236.518599) (xy 101.440255 -236.467669) (xy 101.463381 -236.419648)
			(xy 101.493405 -236.375611) (xy 101.529657 -236.33654) (xy 101.571328 -236.303309) (xy 101.617486 -236.27666)
			(xy 101.6671 -236.257188) (xy 101.719062 -236.245328) (xy 101.772212 -236.241345) (xy 101.825362 -236.245328)
			(xy 101.877324 -236.257188) (xy 101.926938 -236.27666) (xy 101.973096 -236.303309) (xy 102.014767 -236.33654)
			(xy 102.051019 -236.375611) (xy 102.081043 -236.419648) (xy 102.104169 -236.467669) (xy 102.119879 -236.518599)
			(xy 102.127822 -236.571303) (xy 102.12832 -236.597952) (xy 102.127822 -236.624601) (xy 102.119879 -236.677305)
			(xy 102.104169 -236.728235) (xy 102.081043 -236.776256) (xy 102.051019 -236.820293) (xy 102.014767 -236.859364)
			(xy 101.973096 -236.892595) (xy 101.926938 -236.919244) (xy 101.877324 -236.938716) (xy 101.825362 -236.950576)
			(xy 101.772212 -236.95456) (xy 101.719062 -236.950576) (xy 101.6671 -236.938716) (xy 101.617486 -236.919244)
			(xy 101.571328 -236.892595) (xy 101.529657 -236.859364) (xy 101.493405 -236.820293) (xy 101.463381 -236.776256)
			(xy 101.440255 -236.728235) (xy 101.424545 -236.677305) (xy 101.416602 -236.624601) (xy 101.188276 -236.624601)
			(xy 101.180333 -236.677305) (xy 101.164623 -236.728235) (xy 101.141497 -236.776256) (xy 101.111473 -236.820293)
			(xy 101.075221 -236.859364) (xy 101.03355 -236.892595) (xy 100.987392 -236.919244) (xy 100.937778 -236.938716)
			(xy 100.885816 -236.950576) (xy 100.832666 -236.95456) (xy 100.779516 -236.950576) (xy 100.727554 -236.938716)
			(xy 100.67794 -236.919244) (xy 100.631782 -236.892595) (xy 100.590111 -236.859364) (xy 100.553859 -236.820293)
			(xy 100.523835 -236.776256) (xy 100.500709 -236.728235) (xy 100.484999 -236.677305) (xy 100.477056 -236.624601)
			(xy 100.248222 -236.624601) (xy 100.240279 -236.677305) (xy 100.224569 -236.728235) (xy 100.201443 -236.776256)
			(xy 100.171419 -236.820293) (xy 100.135167 -236.859364) (xy 100.093496 -236.892595) (xy 100.047338 -236.919244)
			(xy 99.997724 -236.938716) (xy 99.945762 -236.950576) (xy 99.892612 -236.95456) (xy 99.839462 -236.950576)
			(xy 99.7875 -236.938716) (xy 99.737886 -236.919244) (xy 99.691728 -236.892595) (xy 99.650057 -236.859364)
			(xy 99.613805 -236.820293) (xy 99.583781 -236.776256) (xy 99.560655 -236.728235) (xy 99.544945 -236.677305)
			(xy 99.537002 -236.624601) (xy 99.308422 -236.624601) (xy 99.300479 -236.677305) (xy 99.284769 -236.728235)
			(xy 99.261643 -236.776256) (xy 99.231619 -236.820293) (xy 99.195367 -236.859364) (xy 99.153696 -236.892595)
			(xy 99.107538 -236.919244) (xy 99.057924 -236.938716) (xy 99.005962 -236.950576) (xy 98.952812 -236.95456)
			(xy 98.899662 -236.950576) (xy 98.8477 -236.938716) (xy 98.798086 -236.919244) (xy 98.751928 -236.892595)
			(xy 98.710257 -236.859364) (xy 98.674005 -236.820293) (xy 98.643981 -236.776256) (xy 98.620855 -236.728235)
			(xy 98.605145 -236.677305) (xy 98.597202 -236.624601) (xy 98.368622 -236.624601) (xy 98.360679 -236.677305)
			(xy 98.344969 -236.728235) (xy 98.321843 -236.776256) (xy 98.291819 -236.820293) (xy 98.255567 -236.859364)
			(xy 98.213896 -236.892595) (xy 98.167738 -236.919244) (xy 98.118124 -236.938716) (xy 98.066162 -236.950576)
			(xy 98.013012 -236.95456) (xy 97.959862 -236.950576) (xy 97.9079 -236.938716) (xy 97.858286 -236.919244)
			(xy 97.812128 -236.892595) (xy 97.770457 -236.859364) (xy 97.734205 -236.820293) (xy 97.704181 -236.776256)
			(xy 97.681055 -236.728235) (xy 97.665345 -236.677305) (xy 97.657402 -236.624601) (xy 97.428822 -236.624601)
			(xy 97.420879 -236.677305) (xy 97.405169 -236.728235) (xy 97.382043 -236.776256) (xy 97.352019 -236.820293)
			(xy 97.315767 -236.859364) (xy 97.274096 -236.892595) (xy 97.227938 -236.919244) (xy 97.178324 -236.938716)
			(xy 97.126362 -236.950576) (xy 97.073212 -236.95456) (xy 97.020062 -236.950576) (xy 96.9681 -236.938716)
			(xy 96.918486 -236.919244) (xy 96.872328 -236.892595) (xy 96.830657 -236.859364) (xy 96.794405 -236.820293)
			(xy 96.764381 -236.776256) (xy 96.741255 -236.728235) (xy 96.725545 -236.677305) (xy 96.717602 -236.624601)
			(xy 96.489022 -236.624601) (xy 96.481079 -236.677305) (xy 96.465369 -236.728235) (xy 96.442243 -236.776256)
			(xy 96.412219 -236.820293) (xy 96.375967 -236.859364) (xy 96.334296 -236.892595) (xy 96.288138 -236.919244)
			(xy 96.238524 -236.938716) (xy 96.186562 -236.950576) (xy 96.133412 -236.95456) (xy 96.080262 -236.950576)
			(xy 96.0283 -236.938716) (xy 95.978686 -236.919244) (xy 95.932528 -236.892595) (xy 95.890857 -236.859364)
			(xy 95.854605 -236.820293) (xy 95.824581 -236.776256) (xy 95.801455 -236.728235) (xy 95.785745 -236.677305)
			(xy 95.777802 -236.624601) (xy 95.549222 -236.624601) (xy 95.541279 -236.677305) (xy 95.525569 -236.728235)
			(xy 95.502443 -236.776256) (xy 95.472419 -236.820293) (xy 95.436167 -236.859364) (xy 95.394496 -236.892595)
			(xy 95.348338 -236.919244) (xy 95.298724 -236.938716) (xy 95.246762 -236.950576) (xy 95.193612 -236.95456)
			(xy 95.140462 -236.950576) (xy 95.0885 -236.938716) (xy 95.038886 -236.919244) (xy 94.992728 -236.892595)
			(xy 94.951057 -236.859364) (xy 94.914805 -236.820293) (xy 94.884781 -236.776256) (xy 94.861655 -236.728235)
			(xy 94.845945 -236.677305) (xy 94.838002 -236.624601) (xy 94.609676 -236.624601) (xy 94.601733 -236.677305)
			(xy 94.586023 -236.728235) (xy 94.562897 -236.776256) (xy 94.532873 -236.820293) (xy 94.496621 -236.859364)
			(xy 94.45495 -236.892595) (xy 94.408792 -236.919244) (xy 94.359178 -236.938716) (xy 94.307216 -236.950576)
			(xy 94.254066 -236.95456) (xy 94.200916 -236.950576) (xy 94.148954 -236.938716) (xy 94.09934 -236.919244)
			(xy 94.053182 -236.892595) (xy 94.011511 -236.859364) (xy 93.975259 -236.820293) (xy 93.945235 -236.776256)
			(xy 93.922109 -236.728235) (xy 93.906399 -236.677305) (xy 93.898456 -236.624601) (xy 93.669622 -236.624601)
			(xy 93.661679 -236.677305) (xy 93.645969 -236.728235) (xy 93.622843 -236.776256) (xy 93.592819 -236.820293)
			(xy 93.556567 -236.859364) (xy 93.514896 -236.892595) (xy 93.468738 -236.919244) (xy 93.419124 -236.938716)
			(xy 93.367162 -236.950576) (xy 93.314012 -236.95456) (xy 93.260862 -236.950576) (xy 93.2089 -236.938716)
			(xy 93.159286 -236.919244) (xy 93.113128 -236.892595) (xy 93.071457 -236.859364) (xy 93.035205 -236.820293)
			(xy 93.005181 -236.776256) (xy 92.982055 -236.728235) (xy 92.966345 -236.677305) (xy 92.958402 -236.624601)
			(xy 92.729822 -236.624601) (xy 92.721879 -236.677305) (xy 92.706169 -236.728235) (xy 92.683043 -236.776256)
			(xy 92.653019 -236.820293) (xy 92.616767 -236.859364) (xy 92.575096 -236.892595) (xy 92.528938 -236.919244)
			(xy 92.479324 -236.938716) (xy 92.427362 -236.950576) (xy 92.374212 -236.95456) (xy 92.321062 -236.950576)
			(xy 92.2691 -236.938716) (xy 92.219486 -236.919244) (xy 92.173328 -236.892595) (xy 92.131657 -236.859364)
			(xy 92.095405 -236.820293) (xy 92.065381 -236.776256) (xy 92.042255 -236.728235) (xy 92.026545 -236.677305)
			(xy 92.018602 -236.624601) (xy 91.790022 -236.624601) (xy 91.782079 -236.677305) (xy 91.766369 -236.728235)
			(xy 91.743243 -236.776256) (xy 91.713219 -236.820293) (xy 91.676967 -236.859364) (xy 91.635296 -236.892595)
			(xy 91.589138 -236.919244) (xy 91.539524 -236.938716) (xy 91.487562 -236.950576) (xy 91.434412 -236.95456)
			(xy 91.381262 -236.950576) (xy 91.3293 -236.938716) (xy 91.279686 -236.919244) (xy 91.233528 -236.892595)
			(xy 91.191857 -236.859364) (xy 91.155605 -236.820293) (xy 91.125581 -236.776256) (xy 91.102455 -236.728235)
			(xy 91.086745 -236.677305) (xy 91.078802 -236.624601) (xy 90.850222 -236.624601) (xy 90.842279 -236.677305)
			(xy 90.826569 -236.728235) (xy 90.803443 -236.776256) (xy 90.773419 -236.820293) (xy 90.737167 -236.859364)
			(xy 90.695496 -236.892595) (xy 90.649338 -236.919244) (xy 90.599724 -236.938716) (xy 90.547762 -236.950576)
			(xy 90.494612 -236.95456) (xy 90.441462 -236.950576) (xy 90.3895 -236.938716) (xy 90.339886 -236.919244)
			(xy 90.293728 -236.892595) (xy 90.252057 -236.859364) (xy 90.215805 -236.820293) (xy 90.185781 -236.776256)
			(xy 90.162655 -236.728235) (xy 90.146945 -236.677305) (xy 90.139002 -236.624601) (xy 89.910422 -236.624601)
			(xy 89.902479 -236.677305) (xy 89.886769 -236.728235) (xy 89.863643 -236.776256) (xy 89.833619 -236.820293)
			(xy 89.797367 -236.859364) (xy 89.755696 -236.892595) (xy 89.709538 -236.919244) (xy 89.659924 -236.938716)
			(xy 89.607962 -236.950576) (xy 89.554812 -236.95456) (xy 89.501662 -236.950576) (xy 89.4497 -236.938716)
			(xy 89.400086 -236.919244) (xy 89.353928 -236.892595) (xy 89.312257 -236.859364) (xy 89.276005 -236.820293)
			(xy 89.245981 -236.776256) (xy 89.222855 -236.728235) (xy 89.207145 -236.677305) (xy 89.199202 -236.624601)
			(xy 88.970008 -236.624601) (xy 88.968068 -236.650713) (xy 88.956393 -236.702281) (xy 88.937219 -236.751555)
			(xy 88.910969 -236.797451) (xy 88.878218 -236.83896) (xy 88.839688 -236.875168) (xy 88.796227 -236.905279)
			(xy 88.74879 -236.92863) (xy 88.723724 -236.937042) (xy 88.688418 -236.948472) (xy 88.688418 -237.061756)
			(xy 88.688919 -237.076208) (xy 88.697014 -237.103955) (xy 88.712567 -237.128317) (xy 88.73433 -237.147338)
			(xy 88.760554 -237.159491) (xy 88.789134 -237.163801) (xy 88.817776 -237.159921) (xy 88.84418 -237.148163)
			(xy 88.85555 -237.139226) (xy 88.87491 -237.123464) (xy 88.917206 -237.096944) (xy 88.96279 -237.076588)
			(xy 89.010769 -237.062795) (xy 89.060205 -237.055835) (xy 89.085166 -237.055406) (xy 89.111818 -237.055877)
			(xy 89.164527 -237.063817) (xy 89.215463 -237.079524) (xy 89.263489 -237.102648) (xy 89.307532 -237.132673)
			(xy 89.346608 -237.168926) (xy 89.379844 -237.210599) (xy 89.406497 -237.25676) (xy 89.425973 -237.306379)
			(xy 89.437834 -237.358346) (xy 89.441818 -237.4115) (xy 89.43982 -237.438163) (xy 89.669356 -237.438163)
			(xy 89.669356 -237.384865) (xy 89.677299 -237.332161) (xy 89.693009 -237.281231) (xy 89.716135 -237.23321)
			(xy 89.746159 -237.189173) (xy 89.782411 -237.150102) (xy 89.824082 -237.116871) (xy 89.87024 -237.090222)
			(xy 89.919854 -237.07075) (xy 89.971816 -237.05889) (xy 90.024966 -237.054907) (xy 90.078116 -237.05889)
			(xy 90.130078 -237.07075) (xy 90.179692 -237.090222) (xy 90.22585 -237.116871) (xy 90.267521 -237.150102)
			(xy 90.303773 -237.189173) (xy 90.333797 -237.23321) (xy 90.356923 -237.281231) (xy 90.372633 -237.332161)
			(xy 90.380576 -237.384865) (xy 90.381074 -237.411514) (xy 90.380576 -237.438163) (xy 90.609156 -237.438163)
			(xy 90.609156 -237.384865) (xy 90.617099 -237.332161) (xy 90.632809 -237.281231) (xy 90.655935 -237.23321)
			(xy 90.685959 -237.189173) (xy 90.722211 -237.150102) (xy 90.763882 -237.116871) (xy 90.81004 -237.090222)
			(xy 90.859654 -237.07075) (xy 90.911616 -237.05889) (xy 90.964766 -237.054907) (xy 91.017916 -237.05889)
			(xy 91.069878 -237.07075) (xy 91.119492 -237.090222) (xy 91.16565 -237.116871) (xy 91.207321 -237.150102)
			(xy 91.243573 -237.189173) (xy 91.273597 -237.23321) (xy 91.296723 -237.281231) (xy 91.312433 -237.332161)
			(xy 91.320376 -237.384865) (xy 91.320874 -237.411514) (xy 91.320376 -237.438163) (xy 91.548702 -237.438163)
			(xy 91.548702 -237.384865) (xy 91.556645 -237.332161) (xy 91.572355 -237.281231) (xy 91.595481 -237.23321)
			(xy 91.625505 -237.189173) (xy 91.661757 -237.150102) (xy 91.703428 -237.116871) (xy 91.749586 -237.090222)
			(xy 91.7992 -237.07075) (xy 91.851162 -237.05889) (xy 91.904312 -237.054907) (xy 91.957462 -237.05889)
			(xy 92.009424 -237.07075) (xy 92.059038 -237.090222) (xy 92.105196 -237.116871) (xy 92.146867 -237.150102)
			(xy 92.183119 -237.189173) (xy 92.213143 -237.23321) (xy 92.236269 -237.281231) (xy 92.251979 -237.332161)
			(xy 92.259922 -237.384865) (xy 92.26042 -237.411514) (xy 92.259922 -237.438163) (xy 92.488756 -237.438163)
			(xy 92.488756 -237.384865) (xy 92.496699 -237.332161) (xy 92.512409 -237.281231) (xy 92.535535 -237.23321)
			(xy 92.565559 -237.189173) (xy 92.601811 -237.150102) (xy 92.643482 -237.116871) (xy 92.68964 -237.090222)
			(xy 92.739254 -237.07075) (xy 92.791216 -237.05889) (xy 92.844366 -237.054907) (xy 92.897516 -237.05889)
			(xy 92.949478 -237.07075) (xy 92.999092 -237.090222) (xy 93.04525 -237.116871) (xy 93.086921 -237.150102)
			(xy 93.123173 -237.189173) (xy 93.153197 -237.23321) (xy 93.176323 -237.281231) (xy 93.192033 -237.332161)
			(xy 93.199976 -237.384865) (xy 93.200474 -237.411514) (xy 93.199976 -237.438163) (xy 93.428556 -237.438163)
			(xy 93.428556 -237.384865) (xy 93.436499 -237.332161) (xy 93.452209 -237.281231) (xy 93.475335 -237.23321)
			(xy 93.505359 -237.189173) (xy 93.541611 -237.150102) (xy 93.583282 -237.116871) (xy 93.62944 -237.090222)
			(xy 93.679054 -237.07075) (xy 93.731016 -237.05889) (xy 93.784166 -237.054907) (xy 93.837316 -237.05889)
			(xy 93.889278 -237.07075) (xy 93.938892 -237.090222) (xy 93.98505 -237.116871) (xy 94.026721 -237.150102)
			(xy 94.062973 -237.189173) (xy 94.092997 -237.23321) (xy 94.116123 -237.281231) (xy 94.131833 -237.332161)
			(xy 94.139776 -237.384865) (xy 94.140274 -237.411514) (xy 94.139776 -237.438163) (xy 94.368356 -237.438163)
			(xy 94.368356 -237.384865) (xy 94.376299 -237.332161) (xy 94.392009 -237.281231) (xy 94.415135 -237.23321)
			(xy 94.445159 -237.189173) (xy 94.481411 -237.150102) (xy 94.523082 -237.116871) (xy 94.56924 -237.090222)
			(xy 94.618854 -237.07075) (xy 94.670816 -237.05889) (xy 94.723966 -237.054907) (xy 94.777116 -237.05889)
			(xy 94.829078 -237.07075) (xy 94.878692 -237.090222) (xy 94.92485 -237.116871) (xy 94.966521 -237.150102)
			(xy 95.002773 -237.189173) (xy 95.032797 -237.23321) (xy 95.055923 -237.281231) (xy 95.071633 -237.332161)
			(xy 95.079576 -237.384865) (xy 95.080074 -237.411514) (xy 95.079576 -237.438163) (xy 95.308156 -237.438163)
			(xy 95.308156 -237.384865) (xy 95.316099 -237.332161) (xy 95.331809 -237.281231) (xy 95.354935 -237.23321)
			(xy 95.384959 -237.189173) (xy 95.421211 -237.150102) (xy 95.462882 -237.116871) (xy 95.50904 -237.090222)
			(xy 95.558654 -237.07075) (xy 95.610616 -237.05889) (xy 95.663766 -237.054907) (xy 95.716916 -237.05889)
			(xy 95.768878 -237.07075) (xy 95.818492 -237.090222) (xy 95.86465 -237.116871) (xy 95.906321 -237.150102)
			(xy 95.942573 -237.189173) (xy 95.972597 -237.23321) (xy 95.995723 -237.281231) (xy 96.011433 -237.332161)
			(xy 96.019376 -237.384865) (xy 96.019874 -237.411514) (xy 96.019376 -237.438163) (xy 96.247956 -237.438163)
			(xy 96.247956 -237.384865) (xy 96.255899 -237.332161) (xy 96.271609 -237.281231) (xy 96.294735 -237.23321)
			(xy 96.324759 -237.189173) (xy 96.361011 -237.150102) (xy 96.402682 -237.116871) (xy 96.44884 -237.090222)
			(xy 96.498454 -237.07075) (xy 96.550416 -237.05889) (xy 96.603566 -237.054907) (xy 96.656716 -237.05889)
			(xy 96.708678 -237.07075) (xy 96.758292 -237.090222) (xy 96.80445 -237.116871) (xy 96.846121 -237.150102)
			(xy 96.882373 -237.189173) (xy 96.912397 -237.23321) (xy 96.935523 -237.281231) (xy 96.951233 -237.332161)
			(xy 96.959176 -237.384865) (xy 96.959674 -237.411514) (xy 96.959176 -237.438163) (xy 97.187756 -237.438163)
			(xy 97.187756 -237.384865) (xy 97.195699 -237.332161) (xy 97.211409 -237.281231) (xy 97.234535 -237.23321)
			(xy 97.264559 -237.189173) (xy 97.300811 -237.150102) (xy 97.342482 -237.116871) (xy 97.38864 -237.090222)
			(xy 97.438254 -237.07075) (xy 97.490216 -237.05889) (xy 97.543366 -237.054907) (xy 97.596516 -237.05889)
			(xy 97.648478 -237.07075) (xy 97.698092 -237.090222) (xy 97.74425 -237.116871) (xy 97.785921 -237.150102)
			(xy 97.822173 -237.189173) (xy 97.852197 -237.23321) (xy 97.875323 -237.281231) (xy 97.891033 -237.332161)
			(xy 97.898976 -237.384865) (xy 97.899474 -237.411514) (xy 97.898976 -237.438163) (xy 98.127302 -237.438163)
			(xy 98.127302 -237.384865) (xy 98.135245 -237.332161) (xy 98.150955 -237.281231) (xy 98.174081 -237.23321)
			(xy 98.204105 -237.189173) (xy 98.240357 -237.150102) (xy 98.282028 -237.116871) (xy 98.328186 -237.090222)
			(xy 98.3778 -237.07075) (xy 98.429762 -237.05889) (xy 98.482912 -237.054907) (xy 98.536062 -237.05889)
			(xy 98.588024 -237.07075) (xy 98.637638 -237.090222) (xy 98.683796 -237.116871) (xy 98.725467 -237.150102)
			(xy 98.761719 -237.189173) (xy 98.791743 -237.23321) (xy 98.814869 -237.281231) (xy 98.830579 -237.332161)
			(xy 98.838522 -237.384865) (xy 98.83902 -237.411514) (xy 98.838522 -237.438163) (xy 99.067356 -237.438163)
			(xy 99.067356 -237.384865) (xy 99.075299 -237.332161) (xy 99.091009 -237.281231) (xy 99.114135 -237.23321)
			(xy 99.144159 -237.189173) (xy 99.180411 -237.150102) (xy 99.222082 -237.116871) (xy 99.26824 -237.090222)
			(xy 99.317854 -237.07075) (xy 99.369816 -237.05889) (xy 99.422966 -237.054907) (xy 99.476116 -237.05889)
			(xy 99.528078 -237.07075) (xy 99.577692 -237.090222) (xy 99.62385 -237.116871) (xy 99.665521 -237.150102)
			(xy 99.701773 -237.189173) (xy 99.731797 -237.23321) (xy 99.754923 -237.281231) (xy 99.770633 -237.332161)
			(xy 99.778576 -237.384865) (xy 99.779074 -237.411514) (xy 99.778576 -237.438163) (xy 100.007156 -237.438163)
			(xy 100.007156 -237.384865) (xy 100.015099 -237.332161) (xy 100.030809 -237.281231) (xy 100.053935 -237.23321)
			(xy 100.083959 -237.189173) (xy 100.120211 -237.150102) (xy 100.161882 -237.116871) (xy 100.20804 -237.090222)
			(xy 100.257654 -237.07075) (xy 100.309616 -237.05889) (xy 100.362766 -237.054907) (xy 100.415916 -237.05889)
			(xy 100.467878 -237.07075) (xy 100.517492 -237.090222) (xy 100.56365 -237.116871) (xy 100.605321 -237.150102)
			(xy 100.641573 -237.189173) (xy 100.671597 -237.23321) (xy 100.694723 -237.281231) (xy 100.710433 -237.332161)
			(xy 100.718376 -237.384865) (xy 100.718874 -237.411514) (xy 100.718376 -237.438163) (xy 100.946956 -237.438163)
			(xy 100.946956 -237.384865) (xy 100.954899 -237.332161) (xy 100.970609 -237.281231) (xy 100.993735 -237.23321)
			(xy 101.023759 -237.189173) (xy 101.060011 -237.150102) (xy 101.101682 -237.116871) (xy 101.14784 -237.090222)
			(xy 101.197454 -237.07075) (xy 101.249416 -237.05889) (xy 101.302566 -237.054907) (xy 101.355716 -237.05889)
			(xy 101.407678 -237.07075) (xy 101.457292 -237.090222) (xy 101.50345 -237.116871) (xy 101.545121 -237.150102)
			(xy 101.581373 -237.189173) (xy 101.611397 -237.23321) (xy 101.634523 -237.281231) (xy 101.650233 -237.332161)
			(xy 101.658176 -237.384865) (xy 101.658674 -237.411514) (xy 101.658176 -237.438163) (xy 101.650233 -237.490867)
			(xy 101.634523 -237.541797) (xy 101.611397 -237.589818) (xy 101.581373 -237.633855) (xy 101.545121 -237.672926)
			(xy 101.50345 -237.706157) (xy 101.457292 -237.732806) (xy 101.407678 -237.752278) (xy 101.355716 -237.764138)
			(xy 101.302566 -237.768122) (xy 101.249416 -237.764138) (xy 101.197454 -237.752278) (xy 101.14784 -237.732806)
			(xy 101.101682 -237.706157) (xy 101.060011 -237.672926) (xy 101.023759 -237.633855) (xy 100.993735 -237.589818)
			(xy 100.970609 -237.541797) (xy 100.954899 -237.490867) (xy 100.946956 -237.438163) (xy 100.718376 -237.438163)
			(xy 100.710433 -237.490867) (xy 100.694723 -237.541797) (xy 100.671597 -237.589818) (xy 100.641573 -237.633855)
			(xy 100.605321 -237.672926) (xy 100.56365 -237.706157) (xy 100.517492 -237.732806) (xy 100.467878 -237.752278)
			(xy 100.415916 -237.764138) (xy 100.362766 -237.768122) (xy 100.309616 -237.764138) (xy 100.257654 -237.752278)
			(xy 100.20804 -237.732806) (xy 100.161882 -237.706157) (xy 100.120211 -237.672926) (xy 100.083959 -237.633855)
			(xy 100.053935 -237.589818) (xy 100.030809 -237.541797) (xy 100.015099 -237.490867) (xy 100.007156 -237.438163)
			(xy 99.778576 -237.438163) (xy 99.770633 -237.490867) (xy 99.754923 -237.541797) (xy 99.731797 -237.589818)
			(xy 99.701773 -237.633855) (xy 99.665521 -237.672926) (xy 99.62385 -237.706157) (xy 99.577692 -237.732806)
			(xy 99.528078 -237.752278) (xy 99.476116 -237.764138) (xy 99.422966 -237.768122) (xy 99.369816 -237.764138)
			(xy 99.317854 -237.752278) (xy 99.26824 -237.732806) (xy 99.222082 -237.706157) (xy 99.180411 -237.672926)
			(xy 99.144159 -237.633855) (xy 99.114135 -237.589818) (xy 99.091009 -237.541797) (xy 99.075299 -237.490867)
			(xy 99.067356 -237.438163) (xy 98.838522 -237.438163) (xy 98.830579 -237.490867) (xy 98.814869 -237.541797)
			(xy 98.791743 -237.589818) (xy 98.761719 -237.633855) (xy 98.725467 -237.672926) (xy 98.683796 -237.706157)
			(xy 98.637638 -237.732806) (xy 98.588024 -237.752278) (xy 98.536062 -237.764138) (xy 98.482912 -237.768122)
			(xy 98.429762 -237.764138) (xy 98.3778 -237.752278) (xy 98.328186 -237.732806) (xy 98.282028 -237.706157)
			(xy 98.240357 -237.672926) (xy 98.204105 -237.633855) (xy 98.174081 -237.589818) (xy 98.150955 -237.541797)
			(xy 98.135245 -237.490867) (xy 98.127302 -237.438163) (xy 97.898976 -237.438163) (xy 97.891033 -237.490867)
			(xy 97.875323 -237.541797) (xy 97.852197 -237.589818) (xy 97.822173 -237.633855) (xy 97.785921 -237.672926)
			(xy 97.74425 -237.706157) (xy 97.698092 -237.732806) (xy 97.648478 -237.752278) (xy 97.596516 -237.764138)
			(xy 97.543366 -237.768122) (xy 97.490216 -237.764138) (xy 97.438254 -237.752278) (xy 97.38864 -237.732806)
			(xy 97.342482 -237.706157) (xy 97.300811 -237.672926) (xy 97.264559 -237.633855) (xy 97.234535 -237.589818)
			(xy 97.211409 -237.541797) (xy 97.195699 -237.490867) (xy 97.187756 -237.438163) (xy 96.959176 -237.438163)
			(xy 96.951233 -237.490867) (xy 96.935523 -237.541797) (xy 96.912397 -237.589818) (xy 96.882373 -237.633855)
			(xy 96.846121 -237.672926) (xy 96.80445 -237.706157) (xy 96.758292 -237.732806) (xy 96.708678 -237.752278)
			(xy 96.656716 -237.764138) (xy 96.603566 -237.768122) (xy 96.550416 -237.764138) (xy 96.498454 -237.752278)
			(xy 96.44884 -237.732806) (xy 96.402682 -237.706157) (xy 96.361011 -237.672926) (xy 96.324759 -237.633855)
			(xy 96.294735 -237.589818) (xy 96.271609 -237.541797) (xy 96.255899 -237.490867) (xy 96.247956 -237.438163)
			(xy 96.019376 -237.438163) (xy 96.011433 -237.490867) (xy 95.995723 -237.541797) (xy 95.972597 -237.589818)
			(xy 95.942573 -237.633855) (xy 95.906321 -237.672926) (xy 95.86465 -237.706157) (xy 95.818492 -237.732806)
			(xy 95.768878 -237.752278) (xy 95.716916 -237.764138) (xy 95.663766 -237.768122) (xy 95.610616 -237.764138)
			(xy 95.558654 -237.752278) (xy 95.50904 -237.732806) (xy 95.462882 -237.706157) (xy 95.421211 -237.672926)
			(xy 95.384959 -237.633855) (xy 95.354935 -237.589818) (xy 95.331809 -237.541797) (xy 95.316099 -237.490867)
			(xy 95.308156 -237.438163) (xy 95.079576 -237.438163) (xy 95.071633 -237.490867) (xy 95.055923 -237.541797)
			(xy 95.032797 -237.589818) (xy 95.002773 -237.633855) (xy 94.966521 -237.672926) (xy 94.92485 -237.706157)
			(xy 94.878692 -237.732806) (xy 94.829078 -237.752278) (xy 94.777116 -237.764138) (xy 94.723966 -237.768122)
			(xy 94.670816 -237.764138) (xy 94.618854 -237.752278) (xy 94.56924 -237.732806) (xy 94.523082 -237.706157)
			(xy 94.481411 -237.672926) (xy 94.445159 -237.633855) (xy 94.415135 -237.589818) (xy 94.392009 -237.541797)
			(xy 94.376299 -237.490867) (xy 94.368356 -237.438163) (xy 94.139776 -237.438163) (xy 94.131833 -237.490867)
			(xy 94.116123 -237.541797) (xy 94.092997 -237.589818) (xy 94.062973 -237.633855) (xy 94.026721 -237.672926)
			(xy 93.98505 -237.706157) (xy 93.938892 -237.732806) (xy 93.889278 -237.752278) (xy 93.837316 -237.764138)
			(xy 93.784166 -237.768122) (xy 93.731016 -237.764138) (xy 93.679054 -237.752278) (xy 93.62944 -237.732806)
			(xy 93.583282 -237.706157) (xy 93.541611 -237.672926) (xy 93.505359 -237.633855) (xy 93.475335 -237.589818)
			(xy 93.452209 -237.541797) (xy 93.436499 -237.490867) (xy 93.428556 -237.438163) (xy 93.199976 -237.438163)
			(xy 93.192033 -237.490867) (xy 93.176323 -237.541797) (xy 93.153197 -237.589818) (xy 93.123173 -237.633855)
			(xy 93.086921 -237.672926) (xy 93.04525 -237.706157) (xy 92.999092 -237.732806) (xy 92.949478 -237.752278)
			(xy 92.897516 -237.764138) (xy 92.844366 -237.768122) (xy 92.791216 -237.764138) (xy 92.739254 -237.752278)
			(xy 92.68964 -237.732806) (xy 92.643482 -237.706157) (xy 92.601811 -237.672926) (xy 92.565559 -237.633855)
			(xy 92.535535 -237.589818) (xy 92.512409 -237.541797) (xy 92.496699 -237.490867) (xy 92.488756 -237.438163)
			(xy 92.259922 -237.438163) (xy 92.251979 -237.490867) (xy 92.236269 -237.541797) (xy 92.213143 -237.589818)
			(xy 92.183119 -237.633855) (xy 92.146867 -237.672926) (xy 92.105196 -237.706157) (xy 92.059038 -237.732806)
			(xy 92.009424 -237.752278) (xy 91.957462 -237.764138) (xy 91.904312 -237.768122) (xy 91.851162 -237.764138)
			(xy 91.7992 -237.752278) (xy 91.749586 -237.732806) (xy 91.703428 -237.706157) (xy 91.661757 -237.672926)
			(xy 91.625505 -237.633855) (xy 91.595481 -237.589818) (xy 91.572355 -237.541797) (xy 91.556645 -237.490867)
			(xy 91.548702 -237.438163) (xy 91.320376 -237.438163) (xy 91.312433 -237.490867) (xy 91.296723 -237.541797)
			(xy 91.273597 -237.589818) (xy 91.243573 -237.633855) (xy 91.207321 -237.672926) (xy 91.16565 -237.706157)
			(xy 91.119492 -237.732806) (xy 91.069878 -237.752278) (xy 91.017916 -237.764138) (xy 90.964766 -237.768122)
			(xy 90.911616 -237.764138) (xy 90.859654 -237.752278) (xy 90.81004 -237.732806) (xy 90.763882 -237.706157)
			(xy 90.722211 -237.672926) (xy 90.685959 -237.633855) (xy 90.655935 -237.589818) (xy 90.632809 -237.541797)
			(xy 90.617099 -237.490867) (xy 90.609156 -237.438163) (xy 90.380576 -237.438163) (xy 90.372633 -237.490867)
			(xy 90.356923 -237.541797) (xy 90.333797 -237.589818) (xy 90.303773 -237.633855) (xy 90.267521 -237.672926)
			(xy 90.22585 -237.706157) (xy 90.179692 -237.732806) (xy 90.130078 -237.752278) (xy 90.078116 -237.764138)
			(xy 90.024966 -237.768122) (xy 89.971816 -237.764138) (xy 89.919854 -237.752278) (xy 89.87024 -237.732806)
			(xy 89.824082 -237.706157) (xy 89.782411 -237.672926) (xy 89.746159 -237.633855) (xy 89.716135 -237.589818)
			(xy 89.693009 -237.541797) (xy 89.677299 -237.490867) (xy 89.669356 -237.438163) (xy 89.43982 -237.438163)
			(xy 89.437834 -237.464654) (xy 89.425973 -237.516621) (xy 89.406497 -237.56624) (xy 89.379844 -237.612401)
			(xy 89.346608 -237.654074) (xy 89.307532 -237.690327) (xy 89.263489 -237.720352) (xy 89.215463 -237.743476)
			(xy 89.164527 -237.759183) (xy 89.111818 -237.767123) (xy 89.085166 -237.767622) (xy 89.060205 -237.767201)
			(xy 89.010773 -237.76023) (xy 88.962797 -237.746429) (xy 88.917216 -237.726069) (xy 88.874922 -237.699548)
			(xy 88.85555 -237.683802) (xy 88.844191 -237.674867) (xy 88.817787 -237.663152) (xy 88.789158 -237.659302)
			(xy 88.760597 -237.663624) (xy 88.734389 -237.675772) (xy 88.712633 -237.694774) (xy 88.697069 -237.719109)
			(xy 88.688944 -237.746829) (xy 88.688418 -237.761272) (xy 88.688418 -237.875064) (xy 88.723724 -237.886494)
			(xy 88.748734 -237.895017) (xy 88.79611 -237.918405) (xy 88.839512 -237.948536) (xy 88.877985 -237.98475)
			(xy 88.910685 -238.02625) (xy 88.936894 -238.072126) (xy 88.956037 -238.121372) (xy 88.967694 -238.172905)
			(xy 88.971609 -238.225595) (xy 88.96963 -238.252233) (xy 89.199202 -238.252233) (xy 89.199202 -238.198935)
			(xy 89.207145 -238.146231) (xy 89.222855 -238.095301) (xy 89.245981 -238.04728) (xy 89.276005 -238.003243)
			(xy 89.312257 -237.964172) (xy 89.353928 -237.930941) (xy 89.400086 -237.904292) (xy 89.4497 -237.88482)
			(xy 89.501662 -237.87296) (xy 89.554812 -237.868977) (xy 89.607962 -237.87296) (xy 89.659924 -237.88482)
			(xy 89.709538 -237.904292) (xy 89.755696 -237.930941) (xy 89.797367 -237.964172) (xy 89.833619 -238.003243)
			(xy 89.863643 -238.04728) (xy 89.886769 -238.095301) (xy 89.902479 -238.146231) (xy 89.910422 -238.198935)
			(xy 89.91092 -238.225584) (xy 89.910422 -238.252233) (xy 90.139002 -238.252233) (xy 90.139002 -238.198935)
			(xy 90.146945 -238.146231) (xy 90.162655 -238.095301) (xy 90.185781 -238.04728) (xy 90.215805 -238.003243)
			(xy 90.252057 -237.964172) (xy 90.293728 -237.930941) (xy 90.339886 -237.904292) (xy 90.3895 -237.88482)
			(xy 90.441462 -237.87296) (xy 90.494612 -237.868977) (xy 90.547762 -237.87296) (xy 90.599724 -237.88482)
			(xy 90.649338 -237.904292) (xy 90.695496 -237.930941) (xy 90.737167 -237.964172) (xy 90.773419 -238.003243)
			(xy 90.803443 -238.04728) (xy 90.826569 -238.095301) (xy 90.842279 -238.146231) (xy 90.850222 -238.198935)
			(xy 90.85072 -238.225584) (xy 90.850222 -238.252233) (xy 91.079056 -238.252233) (xy 91.079056 -238.198935)
			(xy 91.086999 -238.146231) (xy 91.102709 -238.095301) (xy 91.125835 -238.04728) (xy 91.155859 -238.003243)
			(xy 91.192111 -237.964172) (xy 91.233782 -237.930941) (xy 91.27994 -237.904292) (xy 91.329554 -237.88482)
			(xy 91.381516 -237.87296) (xy 91.434666 -237.868977) (xy 91.487816 -237.87296) (xy 91.539778 -237.88482)
			(xy 91.589392 -237.904292) (xy 91.63555 -237.930941) (xy 91.677221 -237.964172) (xy 91.713473 -238.003243)
			(xy 91.743497 -238.04728) (xy 91.766623 -238.095301) (xy 91.782333 -238.146231) (xy 91.790276 -238.198935)
			(xy 91.790774 -238.225584) (xy 91.790276 -238.252233) (xy 92.018602 -238.252233) (xy 92.018602 -238.198935)
			(xy 92.026545 -238.146231) (xy 92.042255 -238.095301) (xy 92.065381 -238.04728) (xy 92.095405 -238.003243)
			(xy 92.131657 -237.964172) (xy 92.173328 -237.930941) (xy 92.219486 -237.904292) (xy 92.2691 -237.88482)
			(xy 92.321062 -237.87296) (xy 92.374212 -237.868977) (xy 92.427362 -237.87296) (xy 92.479324 -237.88482)
			(xy 92.528938 -237.904292) (xy 92.575096 -237.930941) (xy 92.616767 -237.964172) (xy 92.653019 -238.003243)
			(xy 92.683043 -238.04728) (xy 92.706169 -238.095301) (xy 92.721879 -238.146231) (xy 92.729822 -238.198935)
			(xy 92.73032 -238.225584) (xy 92.729822 -238.252233) (xy 92.958402 -238.252233) (xy 92.958402 -238.198935)
			(xy 92.966345 -238.146231) (xy 92.982055 -238.095301) (xy 93.005181 -238.04728) (xy 93.035205 -238.003243)
			(xy 93.071457 -237.964172) (xy 93.113128 -237.930941) (xy 93.159286 -237.904292) (xy 93.2089 -237.88482)
			(xy 93.260862 -237.87296) (xy 93.314012 -237.868977) (xy 93.367162 -237.87296) (xy 93.419124 -237.88482)
			(xy 93.468738 -237.904292) (xy 93.514896 -237.930941) (xy 93.556567 -237.964172) (xy 93.592819 -238.003243)
			(xy 93.622843 -238.04728) (xy 93.645969 -238.095301) (xy 93.661679 -238.146231) (xy 93.669622 -238.198935)
			(xy 93.67012 -238.225584) (xy 93.669622 -238.252233) (xy 93.898202 -238.252233) (xy 93.898202 -238.198935)
			(xy 93.906145 -238.146231) (xy 93.921855 -238.095301) (xy 93.944981 -238.04728) (xy 93.975005 -238.003243)
			(xy 94.011257 -237.964172) (xy 94.052928 -237.930941) (xy 94.099086 -237.904292) (xy 94.1487 -237.88482)
			(xy 94.200662 -237.87296) (xy 94.253812 -237.868977) (xy 94.306962 -237.87296) (xy 94.358924 -237.88482)
			(xy 94.408538 -237.904292) (xy 94.454696 -237.930941) (xy 94.496367 -237.964172) (xy 94.532619 -238.003243)
			(xy 94.562643 -238.04728) (xy 94.585769 -238.095301) (xy 94.601479 -238.146231) (xy 94.609422 -238.198935)
			(xy 94.60992 -238.225584) (xy 94.609422 -238.252233) (xy 94.838002 -238.252233) (xy 94.838002 -238.198935)
			(xy 94.845945 -238.146231) (xy 94.861655 -238.095301) (xy 94.884781 -238.04728) (xy 94.914805 -238.003243)
			(xy 94.951057 -237.964172) (xy 94.992728 -237.930941) (xy 95.038886 -237.904292) (xy 95.0885 -237.88482)
			(xy 95.140462 -237.87296) (xy 95.193612 -237.868977) (xy 95.246762 -237.87296) (xy 95.298724 -237.88482)
			(xy 95.348338 -237.904292) (xy 95.394496 -237.930941) (xy 95.436167 -237.964172) (xy 95.472419 -238.003243)
			(xy 95.502443 -238.04728) (xy 95.525569 -238.095301) (xy 95.541279 -238.146231) (xy 95.549222 -238.198935)
			(xy 95.54972 -238.225584) (xy 95.549222 -238.252233) (xy 95.777802 -238.252233) (xy 95.777802 -238.198935)
			(xy 95.785745 -238.146231) (xy 95.801455 -238.095301) (xy 95.824581 -238.04728) (xy 95.854605 -238.003243)
			(xy 95.890857 -237.964172) (xy 95.932528 -237.930941) (xy 95.978686 -237.904292) (xy 96.0283 -237.88482)
			(xy 96.080262 -237.87296) (xy 96.133412 -237.868977) (xy 96.186562 -237.87296) (xy 96.238524 -237.88482)
			(xy 96.288138 -237.904292) (xy 96.334296 -237.930941) (xy 96.375967 -237.964172) (xy 96.412219 -238.003243)
			(xy 96.442243 -238.04728) (xy 96.465369 -238.095301) (xy 96.481079 -238.146231) (xy 96.489022 -238.198935)
			(xy 96.48952 -238.225584) (xy 96.489022 -238.252233) (xy 96.717602 -238.252233) (xy 96.717602 -238.198935)
			(xy 96.725545 -238.146231) (xy 96.741255 -238.095301) (xy 96.764381 -238.04728) (xy 96.794405 -238.003243)
			(xy 96.830657 -237.964172) (xy 96.872328 -237.930941) (xy 96.918486 -237.904292) (xy 96.9681 -237.88482)
			(xy 97.020062 -237.87296) (xy 97.073212 -237.868977) (xy 97.126362 -237.87296) (xy 97.178324 -237.88482)
			(xy 97.227938 -237.904292) (xy 97.274096 -237.930941) (xy 97.315767 -237.964172) (xy 97.352019 -238.003243)
			(xy 97.382043 -238.04728) (xy 97.405169 -238.095301) (xy 97.420879 -238.146231) (xy 97.428822 -238.198935)
			(xy 97.42932 -238.225584) (xy 97.428822 -238.252233) (xy 97.657656 -238.252233) (xy 97.657656 -238.198935)
			(xy 97.665599 -238.146231) (xy 97.681309 -238.095301) (xy 97.704435 -238.04728) (xy 97.734459 -238.003243)
			(xy 97.770711 -237.964172) (xy 97.812382 -237.930941) (xy 97.85854 -237.904292) (xy 97.908154 -237.88482)
			(xy 97.960116 -237.87296) (xy 98.013266 -237.868977) (xy 98.066416 -237.87296) (xy 98.118378 -237.88482)
			(xy 98.167992 -237.904292) (xy 98.21415 -237.930941) (xy 98.255821 -237.964172) (xy 98.292073 -238.003243)
			(xy 98.322097 -238.04728) (xy 98.345223 -238.095301) (xy 98.360933 -238.146231) (xy 98.368876 -238.198935)
			(xy 98.369374 -238.225584) (xy 98.368876 -238.252233) (xy 98.597202 -238.252233) (xy 98.597202 -238.198935)
			(xy 98.605145 -238.146231) (xy 98.620855 -238.095301) (xy 98.643981 -238.04728) (xy 98.674005 -238.003243)
			(xy 98.710257 -237.964172) (xy 98.751928 -237.930941) (xy 98.798086 -237.904292) (xy 98.8477 -237.88482)
			(xy 98.899662 -237.87296) (xy 98.952812 -237.868977) (xy 99.005962 -237.87296) (xy 99.057924 -237.88482)
			(xy 99.107538 -237.904292) (xy 99.153696 -237.930941) (xy 99.195367 -237.964172) (xy 99.231619 -238.003243)
			(xy 99.261643 -238.04728) (xy 99.284769 -238.095301) (xy 99.300479 -238.146231) (xy 99.308422 -238.198935)
			(xy 99.30892 -238.225584) (xy 99.308422 -238.252233) (xy 99.537002 -238.252233) (xy 99.537002 -238.198935)
			(xy 99.544945 -238.146231) (xy 99.560655 -238.095301) (xy 99.583781 -238.04728) (xy 99.613805 -238.003243)
			(xy 99.650057 -237.964172) (xy 99.691728 -237.930941) (xy 99.737886 -237.904292) (xy 99.7875 -237.88482)
			(xy 99.839462 -237.87296) (xy 99.892612 -237.868977) (xy 99.945762 -237.87296) (xy 99.997724 -237.88482)
			(xy 100.047338 -237.904292) (xy 100.093496 -237.930941) (xy 100.135167 -237.964172) (xy 100.171419 -238.003243)
			(xy 100.201443 -238.04728) (xy 100.224569 -238.095301) (xy 100.240279 -238.146231) (xy 100.248222 -238.198935)
			(xy 100.24872 -238.225584) (xy 100.248222 -238.252233) (xy 100.240279 -238.304937) (xy 100.224569 -238.355867)
			(xy 100.201443 -238.403888) (xy 100.171419 -238.447925) (xy 100.135167 -238.486996) (xy 100.093496 -238.520227)
			(xy 100.047338 -238.546876) (xy 99.997724 -238.566348) (xy 99.945762 -238.578208) (xy 99.892612 -238.582192)
			(xy 99.839462 -238.578208) (xy 99.7875 -238.566348) (xy 99.737886 -238.546876) (xy 99.691728 -238.520227)
			(xy 99.650057 -238.486996) (xy 99.613805 -238.447925) (xy 99.583781 -238.403888) (xy 99.560655 -238.355867)
			(xy 99.544945 -238.304937) (xy 99.537002 -238.252233) (xy 99.308422 -238.252233) (xy 99.300479 -238.304937)
			(xy 99.284769 -238.355867) (xy 99.261643 -238.403888) (xy 99.231619 -238.447925) (xy 99.195367 -238.486996)
			(xy 99.153696 -238.520227) (xy 99.107538 -238.546876) (xy 99.057924 -238.566348) (xy 99.005962 -238.578208)
			(xy 98.952812 -238.582192) (xy 98.899662 -238.578208) (xy 98.8477 -238.566348) (xy 98.798086 -238.546876)
			(xy 98.751928 -238.520227) (xy 98.710257 -238.486996) (xy 98.674005 -238.447925) (xy 98.643981 -238.403888)
			(xy 98.620855 -238.355867) (xy 98.605145 -238.304937) (xy 98.597202 -238.252233) (xy 98.368876 -238.252233)
			(xy 98.360933 -238.304937) (xy 98.345223 -238.355867) (xy 98.322097 -238.403888) (xy 98.292073 -238.447925)
			(xy 98.255821 -238.486996) (xy 98.21415 -238.520227) (xy 98.167992 -238.546876) (xy 98.118378 -238.566348)
			(xy 98.066416 -238.578208) (xy 98.013266 -238.582192) (xy 97.960116 -238.578208) (xy 97.908154 -238.566348)
			(xy 97.85854 -238.546876) (xy 97.812382 -238.520227) (xy 97.770711 -238.486996) (xy 97.734459 -238.447925)
			(xy 97.704435 -238.403888) (xy 97.681309 -238.355867) (xy 97.665599 -238.304937) (xy 97.657656 -238.252233)
			(xy 97.428822 -238.252233) (xy 97.420879 -238.304937) (xy 97.405169 -238.355867) (xy 97.382043 -238.403888)
			(xy 97.352019 -238.447925) (xy 97.315767 -238.486996) (xy 97.274096 -238.520227) (xy 97.227938 -238.546876)
			(xy 97.178324 -238.566348) (xy 97.126362 -238.578208) (xy 97.073212 -238.582192) (xy 97.020062 -238.578208)
			(xy 96.9681 -238.566348) (xy 96.918486 -238.546876) (xy 96.872328 -238.520227) (xy 96.830657 -238.486996)
			(xy 96.794405 -238.447925) (xy 96.764381 -238.403888) (xy 96.741255 -238.355867) (xy 96.725545 -238.304937)
			(xy 96.717602 -238.252233) (xy 96.489022 -238.252233) (xy 96.481079 -238.304937) (xy 96.465369 -238.355867)
			(xy 96.442243 -238.403888) (xy 96.412219 -238.447925) (xy 96.375967 -238.486996) (xy 96.334296 -238.520227)
			(xy 96.288138 -238.546876) (xy 96.238524 -238.566348) (xy 96.186562 -238.578208) (xy 96.133412 -238.582192)
			(xy 96.080262 -238.578208) (xy 96.0283 -238.566348) (xy 95.978686 -238.546876) (xy 95.932528 -238.520227)
			(xy 95.890857 -238.486996) (xy 95.854605 -238.447925) (xy 95.824581 -238.403888) (xy 95.801455 -238.355867)
			(xy 95.785745 -238.304937) (xy 95.777802 -238.252233) (xy 95.549222 -238.252233) (xy 95.541279 -238.304937)
			(xy 95.525569 -238.355867) (xy 95.502443 -238.403888) (xy 95.472419 -238.447925) (xy 95.436167 -238.486996)
			(xy 95.394496 -238.520227) (xy 95.348338 -238.546876) (xy 95.298724 -238.566348) (xy 95.246762 -238.578208)
			(xy 95.193612 -238.582192) (xy 95.140462 -238.578208) (xy 95.0885 -238.566348) (xy 95.038886 -238.546876)
			(xy 94.992728 -238.520227) (xy 94.951057 -238.486996) (xy 94.914805 -238.447925) (xy 94.884781 -238.403888)
			(xy 94.861655 -238.355867) (xy 94.845945 -238.304937) (xy 94.838002 -238.252233) (xy 94.609422 -238.252233)
			(xy 94.601479 -238.304937) (xy 94.585769 -238.355867) (xy 94.562643 -238.403888) (xy 94.532619 -238.447925)
			(xy 94.496367 -238.486996) (xy 94.454696 -238.520227) (xy 94.408538 -238.546876) (xy 94.358924 -238.566348)
			(xy 94.306962 -238.578208) (xy 94.253812 -238.582192) (xy 94.200662 -238.578208) (xy 94.1487 -238.566348)
			(xy 94.099086 -238.546876) (xy 94.052928 -238.520227) (xy 94.011257 -238.486996) (xy 93.975005 -238.447925)
			(xy 93.944981 -238.403888) (xy 93.921855 -238.355867) (xy 93.906145 -238.304937) (xy 93.898202 -238.252233)
			(xy 93.669622 -238.252233) (xy 93.661679 -238.304937) (xy 93.645969 -238.355867) (xy 93.622843 -238.403888)
			(xy 93.592819 -238.447925) (xy 93.556567 -238.486996) (xy 93.514896 -238.520227) (xy 93.468738 -238.546876)
			(xy 93.419124 -238.566348) (xy 93.367162 -238.578208) (xy 93.314012 -238.582192) (xy 93.260862 -238.578208)
			(xy 93.2089 -238.566348) (xy 93.159286 -238.546876) (xy 93.113128 -238.520227) (xy 93.071457 -238.486996)
			(xy 93.035205 -238.447925) (xy 93.005181 -238.403888) (xy 92.982055 -238.355867) (xy 92.966345 -238.304937)
			(xy 92.958402 -238.252233) (xy 92.729822 -238.252233) (xy 92.721879 -238.304937) (xy 92.706169 -238.355867)
			(xy 92.683043 -238.403888) (xy 92.653019 -238.447925) (xy 92.616767 -238.486996) (xy 92.575096 -238.520227)
			(xy 92.528938 -238.546876) (xy 92.479324 -238.566348) (xy 92.427362 -238.578208) (xy 92.374212 -238.582192)
			(xy 92.321062 -238.578208) (xy 92.2691 -238.566348) (xy 92.219486 -238.546876) (xy 92.173328 -238.520227)
			(xy 92.131657 -238.486996) (xy 92.095405 -238.447925) (xy 92.065381 -238.403888) (xy 92.042255 -238.355867)
			(xy 92.026545 -238.304937) (xy 92.018602 -238.252233) (xy 91.790276 -238.252233) (xy 91.782333 -238.304937)
			(xy 91.766623 -238.355867) (xy 91.743497 -238.403888) (xy 91.713473 -238.447925) (xy 91.677221 -238.486996)
			(xy 91.63555 -238.520227) (xy 91.589392 -238.546876) (xy 91.539778 -238.566348) (xy 91.487816 -238.578208)
			(xy 91.434666 -238.582192) (xy 91.381516 -238.578208) (xy 91.329554 -238.566348) (xy 91.27994 -238.546876)
			(xy 91.233782 -238.520227) (xy 91.192111 -238.486996) (xy 91.155859 -238.447925) (xy 91.125835 -238.403888)
			(xy 91.102709 -238.355867) (xy 91.086999 -238.304937) (xy 91.079056 -238.252233) (xy 90.850222 -238.252233)
			(xy 90.842279 -238.304937) (xy 90.826569 -238.355867) (xy 90.803443 -238.403888) (xy 90.773419 -238.447925)
			(xy 90.737167 -238.486996) (xy 90.695496 -238.520227) (xy 90.649338 -238.546876) (xy 90.599724 -238.566348)
			(xy 90.547762 -238.578208) (xy 90.494612 -238.582192) (xy 90.441462 -238.578208) (xy 90.3895 -238.566348)
			(xy 90.339886 -238.546876) (xy 90.293728 -238.520227) (xy 90.252057 -238.486996) (xy 90.215805 -238.447925)
			(xy 90.185781 -238.403888) (xy 90.162655 -238.355867) (xy 90.146945 -238.304937) (xy 90.139002 -238.252233)
			(xy 89.910422 -238.252233) (xy 89.902479 -238.304937) (xy 89.886769 -238.355867) (xy 89.863643 -238.403888)
			(xy 89.833619 -238.447925) (xy 89.797367 -238.486996) (xy 89.755696 -238.520227) (xy 89.709538 -238.546876)
			(xy 89.659924 -238.566348) (xy 89.607962 -238.578208) (xy 89.554812 -238.582192) (xy 89.501662 -238.578208)
			(xy 89.4497 -238.566348) (xy 89.400086 -238.546876) (xy 89.353928 -238.520227) (xy 89.312257 -238.486996)
			(xy 89.276005 -238.447925) (xy 89.245981 -238.403888) (xy 89.222855 -238.355867) (xy 89.207145 -238.304937)
			(xy 89.199202 -238.252233) (xy 88.96963 -238.252233) (xy 88.967695 -238.278285) (xy 88.95604 -238.329819)
			(xy 88.936898 -238.379065) (xy 88.91069 -238.424942) (xy 88.877991 -238.466443) (xy 88.839519 -238.502657)
			(xy 88.796119 -238.53279) (xy 88.748743 -238.556179) (xy 88.723724 -238.564674) (xy 88.688418 -238.576104)
			(xy 88.688418 -238.689642) (xy 88.688917 -238.704095) (xy 88.69701 -238.731846) (xy 88.712563 -238.756212)
			(xy 88.734326 -238.775236) (xy 88.760553 -238.787391) (xy 88.789136 -238.791701) (xy 88.817781 -238.78782)
			(xy 88.844186 -238.776059) (xy 88.85555 -238.767112) (xy 88.87491 -238.751351) (xy 88.917207 -238.724832)
			(xy 88.962791 -238.704476) (xy 89.01077 -238.690684) (xy 89.060205 -238.683724) (xy 89.085166 -238.683292)
			(xy 89.111819 -238.683763) (xy 89.16453 -238.691703) (xy 89.215468 -238.707411) (xy 89.263496 -238.730536)
			(xy 89.307541 -238.760562) (xy 89.346619 -238.796817) (xy 89.379856 -238.838491) (xy 89.40651 -238.884654)
			(xy 89.425986 -238.934275) (xy 89.437848 -238.986244) (xy 89.441832 -239.0394) (xy 89.439835 -239.066049)
			(xy 89.669356 -239.066049) (xy 89.669356 -239.012751) (xy 89.677299 -238.960047) (xy 89.693009 -238.909117)
			(xy 89.716135 -238.861096) (xy 89.746159 -238.817059) (xy 89.782411 -238.777988) (xy 89.824082 -238.744757)
			(xy 89.87024 -238.718108) (xy 89.919854 -238.698636) (xy 89.971816 -238.686776) (xy 90.024966 -238.682793)
			(xy 90.078116 -238.686776) (xy 90.130078 -238.698636) (xy 90.179692 -238.718108) (xy 90.22585 -238.744757)
			(xy 90.267521 -238.777988) (xy 90.303773 -238.817059) (xy 90.333797 -238.861096) (xy 90.356923 -238.909117)
			(xy 90.372633 -238.960047) (xy 90.380576 -239.012751) (xy 90.381074 -239.0394) (xy 90.380576 -239.066049)
			(xy 90.609156 -239.066049) (xy 90.609156 -239.012751) (xy 90.617099 -238.960047) (xy 90.632809 -238.909117)
			(xy 90.655935 -238.861096) (xy 90.685959 -238.817059) (xy 90.722211 -238.777988) (xy 90.763882 -238.744757)
			(xy 90.81004 -238.718108) (xy 90.859654 -238.698636) (xy 90.911616 -238.686776) (xy 90.964766 -238.682793)
			(xy 91.017916 -238.686776) (xy 91.069878 -238.698636) (xy 91.119492 -238.718108) (xy 91.16565 -238.744757)
			(xy 91.207321 -238.777988) (xy 91.243573 -238.817059) (xy 91.273597 -238.861096) (xy 91.296723 -238.909117)
			(xy 91.312433 -238.960047) (xy 91.320376 -239.012751) (xy 91.320874 -239.0394) (xy 91.320376 -239.066049)
			(xy 91.548956 -239.066049) (xy 91.548956 -239.012751) (xy 91.556899 -238.960047) (xy 91.572609 -238.909117)
			(xy 91.595735 -238.861096) (xy 91.625759 -238.817059) (xy 91.662011 -238.777988) (xy 91.703682 -238.744757)
			(xy 91.74984 -238.718108) (xy 91.799454 -238.698636) (xy 91.851416 -238.686776) (xy 91.904566 -238.682793)
			(xy 91.957716 -238.686776) (xy 92.009678 -238.698636) (xy 92.059292 -238.718108) (xy 92.10545 -238.744757)
			(xy 92.147121 -238.777988) (xy 92.183373 -238.817059) (xy 92.213397 -238.861096) (xy 92.236523 -238.909117)
			(xy 92.252233 -238.960047) (xy 92.260176 -239.012751) (xy 92.260674 -239.0394) (xy 92.260176 -239.066049)
			(xy 92.488756 -239.066049) (xy 92.488756 -239.012751) (xy 92.496699 -238.960047) (xy 92.512409 -238.909117)
			(xy 92.535535 -238.861096) (xy 92.565559 -238.817059) (xy 92.601811 -238.777988) (xy 92.643482 -238.744757)
			(xy 92.68964 -238.718108) (xy 92.739254 -238.698636) (xy 92.791216 -238.686776) (xy 92.844366 -238.682793)
			(xy 92.897516 -238.686776) (xy 92.949478 -238.698636) (xy 92.999092 -238.718108) (xy 93.04525 -238.744757)
			(xy 93.086921 -238.777988) (xy 93.123173 -238.817059) (xy 93.153197 -238.861096) (xy 93.176323 -238.909117)
			(xy 93.192033 -238.960047) (xy 93.199976 -239.012751) (xy 93.200474 -239.0394) (xy 93.199976 -239.066049)
			(xy 93.428556 -239.066049) (xy 93.428556 -239.012751) (xy 93.436499 -238.960047) (xy 93.452209 -238.909117)
			(xy 93.475335 -238.861096) (xy 93.505359 -238.817059) (xy 93.541611 -238.777988) (xy 93.583282 -238.744757)
			(xy 93.62944 -238.718108) (xy 93.679054 -238.698636) (xy 93.731016 -238.686776) (xy 93.784166 -238.682793)
			(xy 93.837316 -238.686776) (xy 93.889278 -238.698636) (xy 93.938892 -238.718108) (xy 93.98505 -238.744757)
			(xy 94.026721 -238.777988) (xy 94.062973 -238.817059) (xy 94.092997 -238.861096) (xy 94.116123 -238.909117)
			(xy 94.131833 -238.960047) (xy 94.139776 -239.012751) (xy 94.140274 -239.0394) (xy 94.139776 -239.066049)
			(xy 94.368102 -239.066049) (xy 94.368102 -239.012751) (xy 94.376045 -238.960047) (xy 94.391755 -238.909117)
			(xy 94.414881 -238.861096) (xy 94.444905 -238.817059) (xy 94.481157 -238.777988) (xy 94.522828 -238.744757)
			(xy 94.568986 -238.718108) (xy 94.6186 -238.698636) (xy 94.670562 -238.686776) (xy 94.723712 -238.682793)
			(xy 94.776862 -238.686776) (xy 94.828824 -238.698636) (xy 94.878438 -238.718108) (xy 94.924596 -238.744757)
			(xy 94.966267 -238.777988) (xy 95.002519 -238.817059) (xy 95.032543 -238.861096) (xy 95.055669 -238.909117)
			(xy 95.071379 -238.960047) (xy 95.079322 -239.012751) (xy 95.07982 -239.0394) (xy 95.079322 -239.066049)
			(xy 95.308156 -239.066049) (xy 95.308156 -239.012751) (xy 95.316099 -238.960047) (xy 95.331809 -238.909117)
			(xy 95.354935 -238.861096) (xy 95.384959 -238.817059) (xy 95.421211 -238.777988) (xy 95.462882 -238.744757)
			(xy 95.50904 -238.718108) (xy 95.558654 -238.698636) (xy 95.610616 -238.686776) (xy 95.663766 -238.682793)
			(xy 95.716916 -238.686776) (xy 95.768878 -238.698636) (xy 95.818492 -238.718108) (xy 95.86465 -238.744757)
			(xy 95.906321 -238.777988) (xy 95.942573 -238.817059) (xy 95.972597 -238.861096) (xy 95.995723 -238.909117)
			(xy 96.011433 -238.960047) (xy 96.019376 -239.012751) (xy 96.019874 -239.0394) (xy 96.019376 -239.066049)
			(xy 96.247956 -239.066049) (xy 96.247956 -239.012751) (xy 96.255899 -238.960047) (xy 96.271609 -238.909117)
			(xy 96.294735 -238.861096) (xy 96.324759 -238.817059) (xy 96.361011 -238.777988) (xy 96.402682 -238.744757)
			(xy 96.44884 -238.718108) (xy 96.498454 -238.698636) (xy 96.550416 -238.686776) (xy 96.603566 -238.682793)
			(xy 96.656716 -238.686776) (xy 96.708678 -238.698636) (xy 96.758292 -238.718108) (xy 96.80445 -238.744757)
			(xy 96.846121 -238.777988) (xy 96.882373 -238.817059) (xy 96.912397 -238.861096) (xy 96.935523 -238.909117)
			(xy 96.951233 -238.960047) (xy 96.959176 -239.012751) (xy 96.959674 -239.0394) (xy 96.959176 -239.066049)
			(xy 97.187756 -239.066049) (xy 97.187756 -239.012751) (xy 97.195699 -238.960047) (xy 97.211409 -238.909117)
			(xy 97.234535 -238.861096) (xy 97.264559 -238.817059) (xy 97.300811 -238.777988) (xy 97.342482 -238.744757)
			(xy 97.38864 -238.718108) (xy 97.438254 -238.698636) (xy 97.490216 -238.686776) (xy 97.543366 -238.682793)
			(xy 97.596516 -238.686776) (xy 97.648478 -238.698636) (xy 97.698092 -238.718108) (xy 97.74425 -238.744757)
			(xy 97.785921 -238.777988) (xy 97.822173 -238.817059) (xy 97.852197 -238.861096) (xy 97.875323 -238.909117)
			(xy 97.891033 -238.960047) (xy 97.898976 -239.012751) (xy 97.899474 -239.0394) (xy 97.898976 -239.066049)
			(xy 98.127556 -239.066049) (xy 98.127556 -239.012751) (xy 98.135499 -238.960047) (xy 98.151209 -238.909117)
			(xy 98.174335 -238.861096) (xy 98.204359 -238.817059) (xy 98.240611 -238.777988) (xy 98.282282 -238.744757)
			(xy 98.32844 -238.718108) (xy 98.378054 -238.698636) (xy 98.430016 -238.686776) (xy 98.483166 -238.682793)
			(xy 98.536316 -238.686776) (xy 98.588278 -238.698636) (xy 98.637892 -238.718108) (xy 98.68405 -238.744757)
			(xy 98.725721 -238.777988) (xy 98.761973 -238.817059) (xy 98.791997 -238.861096) (xy 98.815123 -238.909117)
			(xy 98.830833 -238.960047) (xy 98.838776 -239.012751) (xy 98.839274 -239.0394) (xy 98.838776 -239.066049)
			(xy 99.067356 -239.066049) (xy 99.067356 -239.012751) (xy 99.075299 -238.960047) (xy 99.091009 -238.909117)
			(xy 99.114135 -238.861096) (xy 99.144159 -238.817059) (xy 99.180411 -238.777988) (xy 99.222082 -238.744757)
			(xy 99.26824 -238.718108) (xy 99.317854 -238.698636) (xy 99.369816 -238.686776) (xy 99.422966 -238.682793)
			(xy 99.476116 -238.686776) (xy 99.528078 -238.698636) (xy 99.577692 -238.718108) (xy 99.62385 -238.744757)
			(xy 99.665521 -238.777988) (xy 99.701773 -238.817059) (xy 99.731797 -238.861096) (xy 99.754923 -238.909117)
			(xy 99.770633 -238.960047) (xy 99.778576 -239.012751) (xy 99.779074 -239.0394) (xy 99.778576 -239.066049)
			(xy 99.770633 -239.118753) (xy 99.754923 -239.169683) (xy 99.731797 -239.217704) (xy 99.701773 -239.261741)
			(xy 99.665521 -239.300812) (xy 99.62385 -239.334043) (xy 99.577692 -239.360692) (xy 99.528078 -239.380164)
			(xy 99.476116 -239.392024) (xy 99.422966 -239.396008) (xy 99.369816 -239.392024) (xy 99.317854 -239.380164)
			(xy 99.26824 -239.360692) (xy 99.222082 -239.334043) (xy 99.180411 -239.300812) (xy 99.144159 -239.261741)
			(xy 99.114135 -239.217704) (xy 99.091009 -239.169683) (xy 99.075299 -239.118753) (xy 99.067356 -239.066049)
			(xy 98.838776 -239.066049) (xy 98.830833 -239.118753) (xy 98.815123 -239.169683) (xy 98.791997 -239.217704)
			(xy 98.761973 -239.261741) (xy 98.725721 -239.300812) (xy 98.68405 -239.334043) (xy 98.637892 -239.360692)
			(xy 98.588278 -239.380164) (xy 98.536316 -239.392024) (xy 98.483166 -239.396008) (xy 98.430016 -239.392024)
			(xy 98.378054 -239.380164) (xy 98.32844 -239.360692) (xy 98.282282 -239.334043) (xy 98.240611 -239.300812)
			(xy 98.204359 -239.261741) (xy 98.174335 -239.217704) (xy 98.151209 -239.169683) (xy 98.135499 -239.118753)
			(xy 98.127556 -239.066049) (xy 97.898976 -239.066049) (xy 97.891033 -239.118753) (xy 97.875323 -239.169683)
			(xy 97.852197 -239.217704) (xy 97.822173 -239.261741) (xy 97.785921 -239.300812) (xy 97.74425 -239.334043)
			(xy 97.698092 -239.360692) (xy 97.648478 -239.380164) (xy 97.596516 -239.392024) (xy 97.543366 -239.396008)
			(xy 97.490216 -239.392024) (xy 97.438254 -239.380164) (xy 97.38864 -239.360692) (xy 97.342482 -239.334043)
			(xy 97.300811 -239.300812) (xy 97.264559 -239.261741) (xy 97.234535 -239.217704) (xy 97.211409 -239.169683)
			(xy 97.195699 -239.118753) (xy 97.187756 -239.066049) (xy 96.959176 -239.066049) (xy 96.951233 -239.118753)
			(xy 96.935523 -239.169683) (xy 96.912397 -239.217704) (xy 96.882373 -239.261741) (xy 96.846121 -239.300812)
			(xy 96.80445 -239.334043) (xy 96.758292 -239.360692) (xy 96.708678 -239.380164) (xy 96.656716 -239.392024)
			(xy 96.603566 -239.396008) (xy 96.550416 -239.392024) (xy 96.498454 -239.380164) (xy 96.44884 -239.360692)
			(xy 96.402682 -239.334043) (xy 96.361011 -239.300812) (xy 96.324759 -239.261741) (xy 96.294735 -239.217704)
			(xy 96.271609 -239.169683) (xy 96.255899 -239.118753) (xy 96.247956 -239.066049) (xy 96.019376 -239.066049)
			(xy 96.011433 -239.118753) (xy 95.995723 -239.169683) (xy 95.972597 -239.217704) (xy 95.942573 -239.261741)
			(xy 95.906321 -239.300812) (xy 95.86465 -239.334043) (xy 95.818492 -239.360692) (xy 95.768878 -239.380164)
			(xy 95.716916 -239.392024) (xy 95.663766 -239.396008) (xy 95.610616 -239.392024) (xy 95.558654 -239.380164)
			(xy 95.50904 -239.360692) (xy 95.462882 -239.334043) (xy 95.421211 -239.300812) (xy 95.384959 -239.261741)
			(xy 95.354935 -239.217704) (xy 95.331809 -239.169683) (xy 95.316099 -239.118753) (xy 95.308156 -239.066049)
			(xy 95.079322 -239.066049) (xy 95.071379 -239.118753) (xy 95.055669 -239.169683) (xy 95.032543 -239.217704)
			(xy 95.002519 -239.261741) (xy 94.966267 -239.300812) (xy 94.924596 -239.334043) (xy 94.878438 -239.360692)
			(xy 94.828824 -239.380164) (xy 94.776862 -239.392024) (xy 94.723712 -239.396008) (xy 94.670562 -239.392024)
			(xy 94.6186 -239.380164) (xy 94.568986 -239.360692) (xy 94.522828 -239.334043) (xy 94.481157 -239.300812)
			(xy 94.444905 -239.261741) (xy 94.414881 -239.217704) (xy 94.391755 -239.169683) (xy 94.376045 -239.118753)
			(xy 94.368102 -239.066049) (xy 94.139776 -239.066049) (xy 94.131833 -239.118753) (xy 94.116123 -239.169683)
			(xy 94.092997 -239.217704) (xy 94.062973 -239.261741) (xy 94.026721 -239.300812) (xy 93.98505 -239.334043)
			(xy 93.938892 -239.360692) (xy 93.889278 -239.380164) (xy 93.837316 -239.392024) (xy 93.784166 -239.396008)
			(xy 93.731016 -239.392024) (xy 93.679054 -239.380164) (xy 93.62944 -239.360692) (xy 93.583282 -239.334043)
			(xy 93.541611 -239.300812) (xy 93.505359 -239.261741) (xy 93.475335 -239.217704) (xy 93.452209 -239.169683)
			(xy 93.436499 -239.118753) (xy 93.428556 -239.066049) (xy 93.199976 -239.066049) (xy 93.192033 -239.118753)
			(xy 93.176323 -239.169683) (xy 93.153197 -239.217704) (xy 93.123173 -239.261741) (xy 93.086921 -239.300812)
			(xy 93.04525 -239.334043) (xy 92.999092 -239.360692) (xy 92.949478 -239.380164) (xy 92.897516 -239.392024)
			(xy 92.844366 -239.396008) (xy 92.791216 -239.392024) (xy 92.739254 -239.380164) (xy 92.68964 -239.360692)
			(xy 92.643482 -239.334043) (xy 92.601811 -239.300812) (xy 92.565559 -239.261741) (xy 92.535535 -239.217704)
			(xy 92.512409 -239.169683) (xy 92.496699 -239.118753) (xy 92.488756 -239.066049) (xy 92.260176 -239.066049)
			(xy 92.252233 -239.118753) (xy 92.236523 -239.169683) (xy 92.213397 -239.217704) (xy 92.183373 -239.261741)
			(xy 92.147121 -239.300812) (xy 92.10545 -239.334043) (xy 92.059292 -239.360692) (xy 92.009678 -239.380164)
			(xy 91.957716 -239.392024) (xy 91.904566 -239.396008) (xy 91.851416 -239.392024) (xy 91.799454 -239.380164)
			(xy 91.74984 -239.360692) (xy 91.703682 -239.334043) (xy 91.662011 -239.300812) (xy 91.625759 -239.261741)
			(xy 91.595735 -239.217704) (xy 91.572609 -239.169683) (xy 91.556899 -239.118753) (xy 91.548956 -239.066049)
			(xy 91.320376 -239.066049) (xy 91.312433 -239.118753) (xy 91.296723 -239.169683) (xy 91.273597 -239.217704)
			(xy 91.243573 -239.261741) (xy 91.207321 -239.300812) (xy 91.16565 -239.334043) (xy 91.119492 -239.360692)
			(xy 91.069878 -239.380164) (xy 91.017916 -239.392024) (xy 90.964766 -239.396008) (xy 90.911616 -239.392024)
			(xy 90.859654 -239.380164) (xy 90.81004 -239.360692) (xy 90.763882 -239.334043) (xy 90.722211 -239.300812)
			(xy 90.685959 -239.261741) (xy 90.655935 -239.217704) (xy 90.632809 -239.169683) (xy 90.617099 -239.118753)
			(xy 90.609156 -239.066049) (xy 90.380576 -239.066049) (xy 90.372633 -239.118753) (xy 90.356923 -239.169683)
			(xy 90.333797 -239.217704) (xy 90.303773 -239.261741) (xy 90.267521 -239.300812) (xy 90.22585 -239.334043)
			(xy 90.179692 -239.360692) (xy 90.130078 -239.380164) (xy 90.078116 -239.392024) (xy 90.024966 -239.396008)
			(xy 89.971816 -239.392024) (xy 89.919854 -239.380164) (xy 89.87024 -239.360692) (xy 89.824082 -239.334043)
			(xy 89.782411 -239.300812) (xy 89.746159 -239.261741) (xy 89.716135 -239.217704) (xy 89.693009 -239.169683)
			(xy 89.677299 -239.118753) (xy 89.669356 -239.066049) (xy 89.439835 -239.066049) (xy 89.437848 -239.092556)
			(xy 89.425986 -239.144525) (xy 89.40651 -239.194146) (xy 89.379856 -239.240309) (xy 89.346619 -239.281983)
			(xy 89.307541 -239.318238) (xy 89.263496 -239.348264) (xy 89.215468 -239.371389) (xy 89.16453 -239.387097)
			(xy 89.111819 -239.395037) (xy 89.085166 -239.395508) (xy 89.060205 -239.395087) (xy 89.010771 -239.388118)
			(xy 88.962793 -239.37432) (xy 88.91721 -239.353964) (xy 88.874912 -239.327447) (xy 88.85555 -239.311688)
			(xy 88.84419 -239.302754) (xy 88.817785 -239.291041) (xy 88.789156 -239.287191) (xy 88.760595 -239.291514)
			(xy 88.734387 -239.303661) (xy 88.712629 -239.322662) (xy 88.697063 -239.346996) (xy 88.688935 -239.374715)
			(xy 88.688418 -239.389158) (xy 88.688418 -239.502696) (xy 88.723724 -239.514126) (xy 88.748731 -239.522649)
			(xy 88.796103 -239.546037) (xy 88.8395 -239.576167) (xy 88.877968 -239.612378) (xy 88.910664 -239.653875)
			(xy 88.93687 -239.699749) (xy 88.95601 -239.74899) (xy 88.967665 -239.800519) (xy 88.971578 -239.853205)
			(xy 88.969597 -239.879865) (xy 89.199202 -239.879865) (xy 89.199202 -239.826567) (xy 89.207145 -239.773863)
			(xy 89.222855 -239.722933) (xy 89.245981 -239.674912) (xy 89.276005 -239.630875) (xy 89.312257 -239.591804)
			(xy 89.353928 -239.558573) (xy 89.400086 -239.531924) (xy 89.4497 -239.512452) (xy 89.501662 -239.500592)
			(xy 89.554812 -239.496609) (xy 89.607962 -239.500592) (xy 89.659924 -239.512452) (xy 89.709538 -239.531924)
			(xy 89.755696 -239.558573) (xy 89.797367 -239.591804) (xy 89.833619 -239.630875) (xy 89.863643 -239.674912)
			(xy 89.886769 -239.722933) (xy 89.902479 -239.773863) (xy 89.910422 -239.826567) (xy 89.91092 -239.853216)
			(xy 89.910422 -239.879865) (xy 90.139256 -239.879865) (xy 90.139256 -239.826567) (xy 90.147199 -239.773863)
			(xy 90.162909 -239.722933) (xy 90.186035 -239.674912) (xy 90.216059 -239.630875) (xy 90.252311 -239.591804)
			(xy 90.293982 -239.558573) (xy 90.34014 -239.531924) (xy 90.389754 -239.512452) (xy 90.441716 -239.500592)
			(xy 90.494866 -239.496609) (xy 90.548016 -239.500592) (xy 90.599978 -239.512452) (xy 90.649592 -239.531924)
			(xy 90.69575 -239.558573) (xy 90.737421 -239.591804) (xy 90.773673 -239.630875) (xy 90.803697 -239.674912)
			(xy 90.826823 -239.722933) (xy 90.842533 -239.773863) (xy 90.850476 -239.826567) (xy 90.850974 -239.853216)
			(xy 90.850476 -239.879865) (xy 91.078802 -239.879865) (xy 91.078802 -239.826567) (xy 91.086745 -239.773863)
			(xy 91.102455 -239.722933) (xy 91.125581 -239.674912) (xy 91.155605 -239.630875) (xy 91.191857 -239.591804)
			(xy 91.233528 -239.558573) (xy 91.279686 -239.531924) (xy 91.3293 -239.512452) (xy 91.381262 -239.500592)
			(xy 91.434412 -239.496609) (xy 91.487562 -239.500592) (xy 91.539524 -239.512452) (xy 91.589138 -239.531924)
			(xy 91.635296 -239.558573) (xy 91.676967 -239.591804) (xy 91.713219 -239.630875) (xy 91.743243 -239.674912)
			(xy 91.766369 -239.722933) (xy 91.782079 -239.773863) (xy 91.790022 -239.826567) (xy 91.79052 -239.853216)
			(xy 91.790022 -239.879865) (xy 92.018602 -239.879865) (xy 92.018602 -239.826567) (xy 92.026545 -239.773863)
			(xy 92.042255 -239.722933) (xy 92.065381 -239.674912) (xy 92.095405 -239.630875) (xy 92.131657 -239.591804)
			(xy 92.173328 -239.558573) (xy 92.219486 -239.531924) (xy 92.2691 -239.512452) (xy 92.321062 -239.500592)
			(xy 92.374212 -239.496609) (xy 92.427362 -239.500592) (xy 92.479324 -239.512452) (xy 92.528938 -239.531924)
			(xy 92.575096 -239.558573) (xy 92.616767 -239.591804) (xy 92.653019 -239.630875) (xy 92.683043 -239.674912)
			(xy 92.706169 -239.722933) (xy 92.721879 -239.773863) (xy 92.729822 -239.826567) (xy 92.73032 -239.853216)
			(xy 92.729822 -239.879865) (xy 92.958402 -239.879865) (xy 92.958402 -239.826567) (xy 92.966345 -239.773863)
			(xy 92.982055 -239.722933) (xy 93.005181 -239.674912) (xy 93.035205 -239.630875) (xy 93.071457 -239.591804)
			(xy 93.113128 -239.558573) (xy 93.159286 -239.531924) (xy 93.2089 -239.512452) (xy 93.260862 -239.500592)
			(xy 93.314012 -239.496609) (xy 93.367162 -239.500592) (xy 93.419124 -239.512452) (xy 93.468738 -239.531924)
			(xy 93.514896 -239.558573) (xy 93.556567 -239.591804) (xy 93.592819 -239.630875) (xy 93.622843 -239.674912)
			(xy 93.645969 -239.722933) (xy 93.661679 -239.773863) (xy 93.669622 -239.826567) (xy 93.67012 -239.853216)
			(xy 93.669622 -239.879865) (xy 93.898202 -239.879865) (xy 93.898202 -239.826567) (xy 93.906145 -239.773863)
			(xy 93.921855 -239.722933) (xy 93.944981 -239.674912) (xy 93.975005 -239.630875) (xy 94.011257 -239.591804)
			(xy 94.052928 -239.558573) (xy 94.099086 -239.531924) (xy 94.1487 -239.512452) (xy 94.200662 -239.500592)
			(xy 94.253812 -239.496609) (xy 94.306962 -239.500592) (xy 94.358924 -239.512452) (xy 94.408538 -239.531924)
			(xy 94.454696 -239.558573) (xy 94.496367 -239.591804) (xy 94.532619 -239.630875) (xy 94.562643 -239.674912)
			(xy 94.585769 -239.722933) (xy 94.601479 -239.773863) (xy 94.609422 -239.826567) (xy 94.60992 -239.853216)
			(xy 94.609422 -239.879865) (xy 94.838002 -239.879865) (xy 94.838002 -239.826567) (xy 94.845945 -239.773863)
			(xy 94.861655 -239.722933) (xy 94.884781 -239.674912) (xy 94.914805 -239.630875) (xy 94.951057 -239.591804)
			(xy 94.992728 -239.558573) (xy 95.038886 -239.531924) (xy 95.0885 -239.512452) (xy 95.140462 -239.500592)
			(xy 95.193612 -239.496609) (xy 95.246762 -239.500592) (xy 95.298724 -239.512452) (xy 95.348338 -239.531924)
			(xy 95.394496 -239.558573) (xy 95.436167 -239.591804) (xy 95.472419 -239.630875) (xy 95.502443 -239.674912)
			(xy 95.525569 -239.722933) (xy 95.541279 -239.773863) (xy 95.549222 -239.826567) (xy 95.54972 -239.853216)
			(xy 95.549222 -239.879865) (xy 95.777802 -239.879865) (xy 95.777802 -239.826567) (xy 95.785745 -239.773863)
			(xy 95.801455 -239.722933) (xy 95.824581 -239.674912) (xy 95.854605 -239.630875) (xy 95.890857 -239.591804)
			(xy 95.932528 -239.558573) (xy 95.978686 -239.531924) (xy 96.0283 -239.512452) (xy 96.080262 -239.500592)
			(xy 96.133412 -239.496609) (xy 96.186562 -239.500592) (xy 96.238524 -239.512452) (xy 96.288138 -239.531924)
			(xy 96.334296 -239.558573) (xy 96.375967 -239.591804) (xy 96.412219 -239.630875) (xy 96.442243 -239.674912)
			(xy 96.465369 -239.722933) (xy 96.481079 -239.773863) (xy 96.489022 -239.826567) (xy 96.48952 -239.853216)
			(xy 96.489022 -239.879865) (xy 96.717856 -239.879865) (xy 96.717856 -239.826567) (xy 96.725799 -239.773863)
			(xy 96.741509 -239.722933) (xy 96.764635 -239.674912) (xy 96.794659 -239.630875) (xy 96.830911 -239.591804)
			(xy 96.872582 -239.558573) (xy 96.91874 -239.531924) (xy 96.968354 -239.512452) (xy 97.020316 -239.500592)
			(xy 97.073466 -239.496609) (xy 97.126616 -239.500592) (xy 97.178578 -239.512452) (xy 97.228192 -239.531924)
			(xy 97.27435 -239.558573) (xy 97.316021 -239.591804) (xy 97.352273 -239.630875) (xy 97.382297 -239.674912)
			(xy 97.405423 -239.722933) (xy 97.421133 -239.773863) (xy 97.429076 -239.826567) (xy 97.429574 -239.853216)
			(xy 97.429076 -239.879865) (xy 97.657402 -239.879865) (xy 97.657402 -239.826567) (xy 97.665345 -239.773863)
			(xy 97.681055 -239.722933) (xy 97.704181 -239.674912) (xy 97.734205 -239.630875) (xy 97.770457 -239.591804)
			(xy 97.812128 -239.558573) (xy 97.858286 -239.531924) (xy 97.9079 -239.512452) (xy 97.959862 -239.500592)
			(xy 98.013012 -239.496609) (xy 98.066162 -239.500592) (xy 98.118124 -239.512452) (xy 98.167738 -239.531924)
			(xy 98.213896 -239.558573) (xy 98.255567 -239.591804) (xy 98.291819 -239.630875) (xy 98.321843 -239.674912)
			(xy 98.344969 -239.722933) (xy 98.360679 -239.773863) (xy 98.368622 -239.826567) (xy 98.36912 -239.853216)
			(xy 98.368622 -239.879865) (xy 98.597202 -239.879865) (xy 98.597202 -239.826567) (xy 98.605145 -239.773863)
			(xy 98.620855 -239.722933) (xy 98.643981 -239.674912) (xy 98.674005 -239.630875) (xy 98.710257 -239.591804)
			(xy 98.751928 -239.558573) (xy 98.798086 -239.531924) (xy 98.8477 -239.512452) (xy 98.899662 -239.500592)
			(xy 98.952812 -239.496609) (xy 99.005962 -239.500592) (xy 99.057924 -239.512452) (xy 99.107538 -239.531924)
			(xy 99.153696 -239.558573) (xy 99.195367 -239.591804) (xy 99.231619 -239.630875) (xy 99.261643 -239.674912)
			(xy 99.284769 -239.722933) (xy 99.300479 -239.773863) (xy 99.308422 -239.826567) (xy 99.30892 -239.853216)
			(xy 99.308422 -239.879865) (xy 99.300479 -239.932569) (xy 99.284769 -239.983499) (xy 99.261643 -240.03152)
			(xy 99.231619 -240.075557) (xy 99.195367 -240.114628) (xy 99.153696 -240.147859) (xy 99.107538 -240.174508)
			(xy 99.057924 -240.19398) (xy 99.005962 -240.20584) (xy 98.952812 -240.209824) (xy 98.899662 -240.20584)
			(xy 98.8477 -240.19398) (xy 98.798086 -240.174508) (xy 98.751928 -240.147859) (xy 98.710257 -240.114628)
			(xy 98.674005 -240.075557) (xy 98.643981 -240.03152) (xy 98.620855 -239.983499) (xy 98.605145 -239.932569)
			(xy 98.597202 -239.879865) (xy 98.368622 -239.879865) (xy 98.360679 -239.932569) (xy 98.344969 -239.983499)
			(xy 98.321843 -240.03152) (xy 98.291819 -240.075557) (xy 98.255567 -240.114628) (xy 98.213896 -240.147859)
			(xy 98.167738 -240.174508) (xy 98.118124 -240.19398) (xy 98.066162 -240.20584) (xy 98.013012 -240.209824)
			(xy 97.959862 -240.20584) (xy 97.9079 -240.19398) (xy 97.858286 -240.174508) (xy 97.812128 -240.147859)
			(xy 97.770457 -240.114628) (xy 97.734205 -240.075557) (xy 97.704181 -240.03152) (xy 97.681055 -239.983499)
			(xy 97.665345 -239.932569) (xy 97.657402 -239.879865) (xy 97.429076 -239.879865) (xy 97.421133 -239.932569)
			(xy 97.405423 -239.983499) (xy 97.382297 -240.03152) (xy 97.352273 -240.075557) (xy 97.316021 -240.114628)
			(xy 97.27435 -240.147859) (xy 97.228192 -240.174508) (xy 97.178578 -240.19398) (xy 97.126616 -240.20584)
			(xy 97.073466 -240.209824) (xy 97.020316 -240.20584) (xy 96.968354 -240.19398) (xy 96.91874 -240.174508)
			(xy 96.872582 -240.147859) (xy 96.830911 -240.114628) (xy 96.794659 -240.075557) (xy 96.764635 -240.03152)
			(xy 96.741509 -239.983499) (xy 96.725799 -239.932569) (xy 96.717856 -239.879865) (xy 96.489022 -239.879865)
			(xy 96.481079 -239.932569) (xy 96.465369 -239.983499) (xy 96.442243 -240.03152) (xy 96.412219 -240.075557)
			(xy 96.375967 -240.114628) (xy 96.334296 -240.147859) (xy 96.288138 -240.174508) (xy 96.238524 -240.19398)
			(xy 96.186562 -240.20584) (xy 96.133412 -240.209824) (xy 96.080262 -240.20584) (xy 96.0283 -240.19398)
			(xy 95.978686 -240.174508) (xy 95.932528 -240.147859) (xy 95.890857 -240.114628) (xy 95.854605 -240.075557)
			(xy 95.824581 -240.03152) (xy 95.801455 -239.983499) (xy 95.785745 -239.932569) (xy 95.777802 -239.879865)
			(xy 95.549222 -239.879865) (xy 95.541279 -239.932569) (xy 95.525569 -239.983499) (xy 95.502443 -240.03152)
			(xy 95.472419 -240.075557) (xy 95.436167 -240.114628) (xy 95.394496 -240.147859) (xy 95.348338 -240.174508)
			(xy 95.298724 -240.19398) (xy 95.246762 -240.20584) (xy 95.193612 -240.209824) (xy 95.140462 -240.20584)
			(xy 95.0885 -240.19398) (xy 95.038886 -240.174508) (xy 94.992728 -240.147859) (xy 94.951057 -240.114628)
			(xy 94.914805 -240.075557) (xy 94.884781 -240.03152) (xy 94.861655 -239.983499) (xy 94.845945 -239.932569)
			(xy 94.838002 -239.879865) (xy 94.609422 -239.879865) (xy 94.601479 -239.932569) (xy 94.585769 -239.983499)
			(xy 94.562643 -240.03152) (xy 94.532619 -240.075557) (xy 94.496367 -240.114628) (xy 94.454696 -240.147859)
			(xy 94.408538 -240.174508) (xy 94.358924 -240.19398) (xy 94.306962 -240.20584) (xy 94.253812 -240.209824)
			(xy 94.200662 -240.20584) (xy 94.1487 -240.19398) (xy 94.099086 -240.174508) (xy 94.052928 -240.147859)
			(xy 94.011257 -240.114628) (xy 93.975005 -240.075557) (xy 93.944981 -240.03152) (xy 93.921855 -239.983499)
			(xy 93.906145 -239.932569) (xy 93.898202 -239.879865) (xy 93.669622 -239.879865) (xy 93.661679 -239.932569)
			(xy 93.645969 -239.983499) (xy 93.622843 -240.03152) (xy 93.592819 -240.075557) (xy 93.556567 -240.114628)
			(xy 93.514896 -240.147859) (xy 93.468738 -240.174508) (xy 93.419124 -240.19398) (xy 93.367162 -240.20584)
			(xy 93.314012 -240.209824) (xy 93.260862 -240.20584) (xy 93.2089 -240.19398) (xy 93.159286 -240.174508)
			(xy 93.113128 -240.147859) (xy 93.071457 -240.114628) (xy 93.035205 -240.075557) (xy 93.005181 -240.03152)
			(xy 92.982055 -239.983499) (xy 92.966345 -239.932569) (xy 92.958402 -239.879865) (xy 92.729822 -239.879865)
			(xy 92.721879 -239.932569) (xy 92.706169 -239.983499) (xy 92.683043 -240.03152) (xy 92.653019 -240.075557)
			(xy 92.616767 -240.114628) (xy 92.575096 -240.147859) (xy 92.528938 -240.174508) (xy 92.479324 -240.19398)
			(xy 92.427362 -240.20584) (xy 92.374212 -240.209824) (xy 92.321062 -240.20584) (xy 92.2691 -240.19398)
			(xy 92.219486 -240.174508) (xy 92.173328 -240.147859) (xy 92.131657 -240.114628) (xy 92.095405 -240.075557)
			(xy 92.065381 -240.03152) (xy 92.042255 -239.983499) (xy 92.026545 -239.932569) (xy 92.018602 -239.879865)
			(xy 91.790022 -239.879865) (xy 91.782079 -239.932569) (xy 91.766369 -239.983499) (xy 91.743243 -240.03152)
			(xy 91.713219 -240.075557) (xy 91.676967 -240.114628) (xy 91.635296 -240.147859) (xy 91.589138 -240.174508)
			(xy 91.539524 -240.19398) (xy 91.487562 -240.20584) (xy 91.434412 -240.209824) (xy 91.381262 -240.20584)
			(xy 91.3293 -240.19398) (xy 91.279686 -240.174508) (xy 91.233528 -240.147859) (xy 91.191857 -240.114628)
			(xy 91.155605 -240.075557) (xy 91.125581 -240.03152) (xy 91.102455 -239.983499) (xy 91.086745 -239.932569)
			(xy 91.078802 -239.879865) (xy 90.850476 -239.879865) (xy 90.842533 -239.932569) (xy 90.826823 -239.983499)
			(xy 90.803697 -240.03152) (xy 90.773673 -240.075557) (xy 90.737421 -240.114628) (xy 90.69575 -240.147859)
			(xy 90.649592 -240.174508) (xy 90.599978 -240.19398) (xy 90.548016 -240.20584) (xy 90.494866 -240.209824)
			(xy 90.441716 -240.20584) (xy 90.389754 -240.19398) (xy 90.34014 -240.174508) (xy 90.293982 -240.147859)
			(xy 90.252311 -240.114628) (xy 90.216059 -240.075557) (xy 90.186035 -240.03152) (xy 90.162909 -239.983499)
			(xy 90.147199 -239.932569) (xy 90.139256 -239.879865) (xy 89.910422 -239.879865) (xy 89.902479 -239.932569)
			(xy 89.886769 -239.983499) (xy 89.863643 -240.03152) (xy 89.833619 -240.075557) (xy 89.797367 -240.114628)
			(xy 89.755696 -240.147859) (xy 89.709538 -240.174508) (xy 89.659924 -240.19398) (xy 89.607962 -240.20584)
			(xy 89.554812 -240.209824) (xy 89.501662 -240.20584) (xy 89.4497 -240.19398) (xy 89.400086 -240.174508)
			(xy 89.353928 -240.147859) (xy 89.312257 -240.114628) (xy 89.276005 -240.075557) (xy 89.245981 -240.03152)
			(xy 89.222855 -239.983499) (xy 89.207145 -239.932569) (xy 89.199202 -239.879865) (xy 88.969597 -239.879865)
			(xy 88.967663 -239.90589) (xy 88.956007 -239.957419) (xy 88.936866 -240.00666) (xy 88.910659 -240.052533)
			(xy 88.877962 -240.094029) (xy 88.839492 -240.13024) (xy 88.796095 -240.160368) (xy 88.748722 -240.183754)
			(xy 88.723724 -240.192306) (xy 88.688418 -240.203736) (xy 88.688418 -240.317528) (xy 88.688915 -240.331983)
			(xy 88.697006 -240.359737) (xy 88.712558 -240.384106) (xy 88.734323 -240.403134) (xy 88.760552 -240.415291)
			(xy 88.789138 -240.419601) (xy 88.817785 -240.415718) (xy 88.844193 -240.403955) (xy 88.85555 -240.394998)
			(xy 88.874911 -240.379237) (xy 88.917207 -240.352719) (xy 88.962791 -240.332365) (xy 89.01077 -240.318573)
			(xy 89.060205 -240.311613) (xy 89.085166 -240.311178) (xy 89.11182 -240.311649) (xy 89.164533 -240.319589)
			(xy 89.215473 -240.335298) (xy 89.263503 -240.358424) (xy 89.30755 -240.388451) (xy 89.346629 -240.424707)
			(xy 89.379867 -240.466383) (xy 89.406523 -240.512548) (xy 89.425999 -240.562171) (xy 89.437862 -240.614141)
			(xy 89.441846 -240.6673) (xy 89.43985 -240.693935) (xy 89.669356 -240.693935) (xy 89.669356 -240.640637)
			(xy 89.677299 -240.587933) (xy 89.693009 -240.537003) (xy 89.716135 -240.488982) (xy 89.746159 -240.444945)
			(xy 89.782411 -240.405874) (xy 89.824082 -240.372643) (xy 89.87024 -240.345994) (xy 89.919854 -240.326522)
			(xy 89.971816 -240.314662) (xy 90.024966 -240.310679) (xy 90.078116 -240.314662) (xy 90.130078 -240.326522)
			(xy 90.179692 -240.345994) (xy 90.22585 -240.372643) (xy 90.267521 -240.405874) (xy 90.303773 -240.444945)
			(xy 90.333797 -240.488982) (xy 90.356923 -240.537003) (xy 90.372633 -240.587933) (xy 90.380576 -240.640637)
			(xy 90.381074 -240.667286) (xy 90.380576 -240.693935) (xy 90.608902 -240.693935) (xy 90.608902 -240.640637)
			(xy 90.616845 -240.587933) (xy 90.632555 -240.537003) (xy 90.655681 -240.488982) (xy 90.685705 -240.444945)
			(xy 90.721957 -240.405874) (xy 90.763628 -240.372643) (xy 90.809786 -240.345994) (xy 90.8594 -240.326522)
			(xy 90.911362 -240.314662) (xy 90.964512 -240.310679) (xy 91.017662 -240.314662) (xy 91.069624 -240.326522)
			(xy 91.119238 -240.345994) (xy 91.165396 -240.372643) (xy 91.207067 -240.405874) (xy 91.243319 -240.444945)
			(xy 91.273343 -240.488982) (xy 91.296469 -240.537003) (xy 91.312179 -240.587933) (xy 91.320122 -240.640637)
			(xy 91.32062 -240.667286) (xy 91.320122 -240.693935) (xy 91.548956 -240.693935) (xy 91.548956 -240.640637)
			(xy 91.556899 -240.587933) (xy 91.572609 -240.537003) (xy 91.595735 -240.488982) (xy 91.625759 -240.444945)
			(xy 91.662011 -240.405874) (xy 91.703682 -240.372643) (xy 91.74984 -240.345994) (xy 91.799454 -240.326522)
			(xy 91.851416 -240.314662) (xy 91.904566 -240.310679) (xy 91.957716 -240.314662) (xy 92.009678 -240.326522)
			(xy 92.059292 -240.345994) (xy 92.10545 -240.372643) (xy 92.147121 -240.405874) (xy 92.183373 -240.444945)
			(xy 92.213397 -240.488982) (xy 92.236523 -240.537003) (xy 92.252233 -240.587933) (xy 92.260176 -240.640637)
			(xy 92.260674 -240.667286) (xy 92.260176 -240.693935) (xy 92.488756 -240.693935) (xy 92.488756 -240.640637)
			(xy 92.496699 -240.587933) (xy 92.512409 -240.537003) (xy 92.535535 -240.488982) (xy 92.565559 -240.444945)
			(xy 92.601811 -240.405874) (xy 92.643482 -240.372643) (xy 92.68964 -240.345994) (xy 92.739254 -240.326522)
			(xy 92.791216 -240.314662) (xy 92.844366 -240.310679) (xy 92.897516 -240.314662) (xy 92.949478 -240.326522)
			(xy 92.999092 -240.345994) (xy 93.04525 -240.372643) (xy 93.086921 -240.405874) (xy 93.123173 -240.444945)
			(xy 93.153197 -240.488982) (xy 93.176323 -240.537003) (xy 93.192033 -240.587933) (xy 93.199976 -240.640637)
			(xy 93.200474 -240.667286) (xy 93.199976 -240.693935) (xy 93.428556 -240.693935) (xy 93.428556 -240.640637)
			(xy 93.436499 -240.587933) (xy 93.452209 -240.537003) (xy 93.475335 -240.488982) (xy 93.505359 -240.444945)
			(xy 93.541611 -240.405874) (xy 93.583282 -240.372643) (xy 93.62944 -240.345994) (xy 93.679054 -240.326522)
			(xy 93.731016 -240.314662) (xy 93.784166 -240.310679) (xy 93.837316 -240.314662) (xy 93.889278 -240.326522)
			(xy 93.938892 -240.345994) (xy 93.98505 -240.372643) (xy 94.026721 -240.405874) (xy 94.062973 -240.444945)
			(xy 94.092997 -240.488982) (xy 94.116123 -240.537003) (xy 94.131833 -240.587933) (xy 94.139776 -240.640637)
			(xy 94.140274 -240.667286) (xy 94.139776 -240.693935) (xy 94.368356 -240.693935) (xy 94.368356 -240.640637)
			(xy 94.376299 -240.587933) (xy 94.392009 -240.537003) (xy 94.415135 -240.488982) (xy 94.445159 -240.444945)
			(xy 94.481411 -240.405874) (xy 94.523082 -240.372643) (xy 94.56924 -240.345994) (xy 94.618854 -240.326522)
			(xy 94.670816 -240.314662) (xy 94.723966 -240.310679) (xy 94.777116 -240.314662) (xy 94.829078 -240.326522)
			(xy 94.878692 -240.345994) (xy 94.92485 -240.372643) (xy 94.966521 -240.405874) (xy 95.002773 -240.444945)
			(xy 95.032797 -240.488982) (xy 95.055923 -240.537003) (xy 95.071633 -240.587933) (xy 95.079576 -240.640637)
			(xy 95.080074 -240.667286) (xy 95.079576 -240.693935) (xy 95.308156 -240.693935) (xy 95.308156 -240.640637)
			(xy 95.316099 -240.587933) (xy 95.331809 -240.537003) (xy 95.354935 -240.488982) (xy 95.384959 -240.444945)
			(xy 95.421211 -240.405874) (xy 95.462882 -240.372643) (xy 95.50904 -240.345994) (xy 95.558654 -240.326522)
			(xy 95.610616 -240.314662) (xy 95.663766 -240.310679) (xy 95.716916 -240.314662) (xy 95.768878 -240.326522)
			(xy 95.818492 -240.345994) (xy 95.86465 -240.372643) (xy 95.906321 -240.405874) (xy 95.942573 -240.444945)
			(xy 95.972597 -240.488982) (xy 95.995723 -240.537003) (xy 96.011433 -240.587933) (xy 96.019376 -240.640637)
			(xy 96.019874 -240.667286) (xy 96.019376 -240.693935) (xy 96.247956 -240.693935) (xy 96.247956 -240.640637)
			(xy 96.255899 -240.587933) (xy 96.271609 -240.537003) (xy 96.294735 -240.488982) (xy 96.324759 -240.444945)
			(xy 96.361011 -240.405874) (xy 96.402682 -240.372643) (xy 96.44884 -240.345994) (xy 96.498454 -240.326522)
			(xy 96.550416 -240.314662) (xy 96.603566 -240.310679) (xy 96.656716 -240.314662) (xy 96.708678 -240.326522)
			(xy 96.758292 -240.345994) (xy 96.80445 -240.372643) (xy 96.846121 -240.405874) (xy 96.882373 -240.444945)
			(xy 96.912397 -240.488982) (xy 96.935523 -240.537003) (xy 96.951233 -240.587933) (xy 96.959176 -240.640637)
			(xy 96.959674 -240.667286) (xy 96.959176 -240.693935) (xy 97.187502 -240.693935) (xy 97.187502 -240.640637)
			(xy 97.195445 -240.587933) (xy 97.211155 -240.537003) (xy 97.234281 -240.488982) (xy 97.264305 -240.444945)
			(xy 97.300557 -240.405874) (xy 97.342228 -240.372643) (xy 97.388386 -240.345994) (xy 97.438 -240.326522)
			(xy 97.489962 -240.314662) (xy 97.543112 -240.310679) (xy 97.596262 -240.314662) (xy 97.648224 -240.326522)
			(xy 97.697838 -240.345994) (xy 97.743996 -240.372643) (xy 97.785667 -240.405874) (xy 97.821919 -240.444945)
			(xy 97.851943 -240.488982) (xy 97.875069 -240.537003) (xy 97.890779 -240.587933) (xy 97.898722 -240.640637)
			(xy 97.89922 -240.667286) (xy 97.898722 -240.693935) (xy 98.127556 -240.693935) (xy 98.127556 -240.640637)
			(xy 98.135499 -240.587933) (xy 98.151209 -240.537003) (xy 98.174335 -240.488982) (xy 98.204359 -240.444945)
			(xy 98.240611 -240.405874) (xy 98.282282 -240.372643) (xy 98.32844 -240.345994) (xy 98.378054 -240.326522)
			(xy 98.430016 -240.314662) (xy 98.483166 -240.310679) (xy 98.536316 -240.314662) (xy 98.588278 -240.326522)
			(xy 98.637892 -240.345994) (xy 98.68405 -240.372643) (xy 98.725721 -240.405874) (xy 98.761973 -240.444945)
			(xy 98.791997 -240.488982) (xy 98.815123 -240.537003) (xy 98.830833 -240.587933) (xy 98.838776 -240.640637)
			(xy 98.839274 -240.667286) (xy 98.838776 -240.693935) (xy 98.830833 -240.746639) (xy 98.815123 -240.797569)
			(xy 98.791997 -240.84559) (xy 98.761973 -240.889627) (xy 98.725721 -240.928698) (xy 98.68405 -240.961929)
			(xy 98.637892 -240.988578) (xy 98.588278 -241.00805) (xy 98.536316 -241.01991) (xy 98.483166 -241.023894)
			(xy 98.430016 -241.01991) (xy 98.378054 -241.00805) (xy 98.32844 -240.988578) (xy 98.282282 -240.961929)
			(xy 98.240611 -240.928698) (xy 98.204359 -240.889627) (xy 98.174335 -240.84559) (xy 98.151209 -240.797569)
			(xy 98.135499 -240.746639) (xy 98.127556 -240.693935) (xy 97.898722 -240.693935) (xy 97.890779 -240.746639)
			(xy 97.875069 -240.797569) (xy 97.851943 -240.84559) (xy 97.821919 -240.889627) (xy 97.785667 -240.928698)
			(xy 97.743996 -240.961929) (xy 97.697838 -240.988578) (xy 97.648224 -241.00805) (xy 97.596262 -241.01991)
			(xy 97.543112 -241.023894) (xy 97.489962 -241.01991) (xy 97.438 -241.00805) (xy 97.388386 -240.988578)
			(xy 97.342228 -240.961929) (xy 97.300557 -240.928698) (xy 97.264305 -240.889627) (xy 97.234281 -240.84559)
			(xy 97.211155 -240.797569) (xy 97.195445 -240.746639) (xy 97.187502 -240.693935) (xy 96.959176 -240.693935)
			(xy 96.951233 -240.746639) (xy 96.935523 -240.797569) (xy 96.912397 -240.84559) (xy 96.882373 -240.889627)
			(xy 96.846121 -240.928698) (xy 96.80445 -240.961929) (xy 96.758292 -240.988578) (xy 96.708678 -241.00805)
			(xy 96.656716 -241.01991) (xy 96.603566 -241.023894) (xy 96.550416 -241.01991) (xy 96.498454 -241.00805)
			(xy 96.44884 -240.988578) (xy 96.402682 -240.961929) (xy 96.361011 -240.928698) (xy 96.324759 -240.889627)
			(xy 96.294735 -240.84559) (xy 96.271609 -240.797569) (xy 96.255899 -240.746639) (xy 96.247956 -240.693935)
			(xy 96.019376 -240.693935) (xy 96.011433 -240.746639) (xy 95.995723 -240.797569) (xy 95.972597 -240.84559)
			(xy 95.942573 -240.889627) (xy 95.906321 -240.928698) (xy 95.86465 -240.961929) (xy 95.818492 -240.988578)
			(xy 95.768878 -241.00805) (xy 95.716916 -241.01991) (xy 95.663766 -241.023894) (xy 95.610616 -241.01991)
			(xy 95.558654 -241.00805) (xy 95.50904 -240.988578) (xy 95.462882 -240.961929) (xy 95.421211 -240.928698)
			(xy 95.384959 -240.889627) (xy 95.354935 -240.84559) (xy 95.331809 -240.797569) (xy 95.316099 -240.746639)
			(xy 95.308156 -240.693935) (xy 95.079576 -240.693935) (xy 95.071633 -240.746639) (xy 95.055923 -240.797569)
			(xy 95.032797 -240.84559) (xy 95.002773 -240.889627) (xy 94.966521 -240.928698) (xy 94.92485 -240.961929)
			(xy 94.878692 -240.988578) (xy 94.829078 -241.00805) (xy 94.777116 -241.01991) (xy 94.723966 -241.023894)
			(xy 94.670816 -241.01991) (xy 94.618854 -241.00805) (xy 94.56924 -240.988578) (xy 94.523082 -240.961929)
			(xy 94.481411 -240.928698) (xy 94.445159 -240.889627) (xy 94.415135 -240.84559) (xy 94.392009 -240.797569)
			(xy 94.376299 -240.746639) (xy 94.368356 -240.693935) (xy 94.139776 -240.693935) (xy 94.131833 -240.746639)
			(xy 94.116123 -240.797569) (xy 94.092997 -240.84559) (xy 94.062973 -240.889627) (xy 94.026721 -240.928698)
			(xy 93.98505 -240.961929) (xy 93.938892 -240.988578) (xy 93.889278 -241.00805) (xy 93.837316 -241.01991)
			(xy 93.784166 -241.023894) (xy 93.731016 -241.01991) (xy 93.679054 -241.00805) (xy 93.62944 -240.988578)
			(xy 93.583282 -240.961929) (xy 93.541611 -240.928698) (xy 93.505359 -240.889627) (xy 93.475335 -240.84559)
			(xy 93.452209 -240.797569) (xy 93.436499 -240.746639) (xy 93.428556 -240.693935) (xy 93.199976 -240.693935)
			(xy 93.192033 -240.746639) (xy 93.176323 -240.797569) (xy 93.153197 -240.84559) (xy 93.123173 -240.889627)
			(xy 93.086921 -240.928698) (xy 93.04525 -240.961929) (xy 92.999092 -240.988578) (xy 92.949478 -241.00805)
			(xy 92.897516 -241.01991) (xy 92.844366 -241.023894) (xy 92.791216 -241.01991) (xy 92.739254 -241.00805)
			(xy 92.68964 -240.988578) (xy 92.643482 -240.961929) (xy 92.601811 -240.928698) (xy 92.565559 -240.889627)
			(xy 92.535535 -240.84559) (xy 92.512409 -240.797569) (xy 92.496699 -240.746639) (xy 92.488756 -240.693935)
			(xy 92.260176 -240.693935) (xy 92.252233 -240.746639) (xy 92.236523 -240.797569) (xy 92.213397 -240.84559)
			(xy 92.183373 -240.889627) (xy 92.147121 -240.928698) (xy 92.10545 -240.961929) (xy 92.059292 -240.988578)
			(xy 92.009678 -241.00805) (xy 91.957716 -241.01991) (xy 91.904566 -241.023894) (xy 91.851416 -241.01991)
			(xy 91.799454 -241.00805) (xy 91.74984 -240.988578) (xy 91.703682 -240.961929) (xy 91.662011 -240.928698)
			(xy 91.625759 -240.889627) (xy 91.595735 -240.84559) (xy 91.572609 -240.797569) (xy 91.556899 -240.746639)
			(xy 91.548956 -240.693935) (xy 91.320122 -240.693935) (xy 91.312179 -240.746639) (xy 91.296469 -240.797569)
			(xy 91.273343 -240.84559) (xy 91.243319 -240.889627) (xy 91.207067 -240.928698) (xy 91.165396 -240.961929)
			(xy 91.119238 -240.988578) (xy 91.069624 -241.00805) (xy 91.017662 -241.01991) (xy 90.964512 -241.023894)
			(xy 90.911362 -241.01991) (xy 90.8594 -241.00805) (xy 90.809786 -240.988578) (xy 90.763628 -240.961929)
			(xy 90.721957 -240.928698) (xy 90.685705 -240.889627) (xy 90.655681 -240.84559) (xy 90.632555 -240.797569)
			(xy 90.616845 -240.746639) (xy 90.608902 -240.693935) (xy 90.380576 -240.693935) (xy 90.372633 -240.746639)
			(xy 90.356923 -240.797569) (xy 90.333797 -240.84559) (xy 90.303773 -240.889627) (xy 90.267521 -240.928698)
			(xy 90.22585 -240.961929) (xy 90.179692 -240.988578) (xy 90.130078 -241.00805) (xy 90.078116 -241.01991)
			(xy 90.024966 -241.023894) (xy 89.971816 -241.01991) (xy 89.919854 -241.00805) (xy 89.87024 -240.988578)
			(xy 89.824082 -240.961929) (xy 89.782411 -240.928698) (xy 89.746159 -240.889627) (xy 89.716135 -240.84559)
			(xy 89.693009 -240.797569) (xy 89.677299 -240.746639) (xy 89.669356 -240.693935) (xy 89.43985 -240.693935)
			(xy 89.437862 -240.720459) (xy 89.425999 -240.772429) (xy 89.406523 -240.822052) (xy 89.379867 -240.868217)
			(xy 89.346629 -240.909893) (xy 89.30755 -240.946149) (xy 89.263503 -240.976176) (xy 89.215473 -240.999302)
			(xy 89.164533 -241.015011) (xy 89.11182 -241.022951) (xy 89.085166 -241.023394) (xy 89.060205 -241.022973)
			(xy 89.010772 -241.016004) (xy 88.962794 -241.002205) (xy 88.917211 -240.981849) (xy 88.874914 -240.955331)
			(xy 88.85555 -240.939574) (xy 88.84419 -240.930641) (xy 88.817783 -240.918929) (xy 88.789154 -240.915081)
			(xy 88.760593 -240.919403) (xy 88.734384 -240.93155) (xy 88.712625 -240.95055) (xy 88.697058 -240.974883)
			(xy 88.688926 -241.002601) (xy 88.688418 -241.017044) (xy 88.688418 -241.130582) (xy 88.723724 -241.142012)
			(xy 88.748732 -241.150535) (xy 88.796106 -241.173923) (xy 88.839505 -241.204054) (xy 88.877975 -241.240266)
			(xy 88.910673 -241.281764) (xy 88.93688 -241.327639) (xy 88.956022 -241.376882) (xy 88.967677 -241.428413)
			(xy 88.971591 -241.481101) (xy 88.969611 -241.507751) (xy 89.199202 -241.507751) (xy 89.199202 -241.454453)
			(xy 89.207145 -241.401749) (xy 89.222855 -241.350819) (xy 89.245981 -241.302798) (xy 89.276005 -241.258761)
			(xy 89.312257 -241.21969) (xy 89.353928 -241.186459) (xy 89.400086 -241.15981) (xy 89.4497 -241.140338)
			(xy 89.501662 -241.128478) (xy 89.554812 -241.124495) (xy 89.607962 -241.128478) (xy 89.659924 -241.140338)
			(xy 89.709538 -241.15981) (xy 89.755696 -241.186459) (xy 89.797367 -241.21969) (xy 89.833619 -241.258761)
			(xy 89.863643 -241.302798) (xy 89.886769 -241.350819) (xy 89.902479 -241.401749) (xy 89.910422 -241.454453)
			(xy 89.91092 -241.481102) (xy 89.910422 -241.507751) (xy 90.139002 -241.507751) (xy 90.139002 -241.454453)
			(xy 90.146945 -241.401749) (xy 90.162655 -241.350819) (xy 90.185781 -241.302798) (xy 90.215805 -241.258761)
			(xy 90.252057 -241.21969) (xy 90.293728 -241.186459) (xy 90.339886 -241.15981) (xy 90.3895 -241.140338)
			(xy 90.441462 -241.128478) (xy 90.494612 -241.124495) (xy 90.547762 -241.128478) (xy 90.599724 -241.140338)
			(xy 90.649338 -241.15981) (xy 90.695496 -241.186459) (xy 90.737167 -241.21969) (xy 90.773419 -241.258761)
			(xy 90.803443 -241.302798) (xy 90.826569 -241.350819) (xy 90.842279 -241.401749) (xy 90.850222 -241.454453)
			(xy 90.85072 -241.481102) (xy 90.850222 -241.507751) (xy 91.078802 -241.507751) (xy 91.078802 -241.454453)
			(xy 91.086745 -241.401749) (xy 91.102455 -241.350819) (xy 91.125581 -241.302798) (xy 91.155605 -241.258761)
			(xy 91.191857 -241.21969) (xy 91.233528 -241.186459) (xy 91.279686 -241.15981) (xy 91.3293 -241.140338)
			(xy 91.381262 -241.128478) (xy 91.434412 -241.124495) (xy 91.487562 -241.128478) (xy 91.539524 -241.140338)
			(xy 91.589138 -241.15981) (xy 91.635296 -241.186459) (xy 91.676967 -241.21969) (xy 91.713219 -241.258761)
			(xy 91.743243 -241.302798) (xy 91.766369 -241.350819) (xy 91.782079 -241.401749) (xy 91.790022 -241.454453)
			(xy 91.79052 -241.481102) (xy 91.790022 -241.507751) (xy 92.018602 -241.507751) (xy 92.018602 -241.454453)
			(xy 92.026545 -241.401749) (xy 92.042255 -241.350819) (xy 92.065381 -241.302798) (xy 92.095405 -241.258761)
			(xy 92.131657 -241.21969) (xy 92.173328 -241.186459) (xy 92.219486 -241.15981) (xy 92.2691 -241.140338)
			(xy 92.321062 -241.128478) (xy 92.374212 -241.124495) (xy 92.427362 -241.128478) (xy 92.479324 -241.140338)
			(xy 92.528938 -241.15981) (xy 92.575096 -241.186459) (xy 92.616767 -241.21969) (xy 92.653019 -241.258761)
			(xy 92.683043 -241.302798) (xy 92.706169 -241.350819) (xy 92.721879 -241.401749) (xy 92.729822 -241.454453)
			(xy 92.73032 -241.481102) (xy 92.729822 -241.507751) (xy 92.958402 -241.507751) (xy 92.958402 -241.454453)
			(xy 92.966345 -241.401749) (xy 92.982055 -241.350819) (xy 93.005181 -241.302798) (xy 93.035205 -241.258761)
			(xy 93.071457 -241.21969) (xy 93.113128 -241.186459) (xy 93.159286 -241.15981) (xy 93.2089 -241.140338)
			(xy 93.260862 -241.128478) (xy 93.314012 -241.124495) (xy 93.367162 -241.128478) (xy 93.419124 -241.140338)
			(xy 93.468738 -241.15981) (xy 93.514896 -241.186459) (xy 93.556567 -241.21969) (xy 93.592819 -241.258761)
			(xy 93.622843 -241.302798) (xy 93.645969 -241.350819) (xy 93.661679 -241.401749) (xy 93.669622 -241.454453)
			(xy 93.67012 -241.481102) (xy 93.669622 -241.507751) (xy 93.898456 -241.507751) (xy 93.898456 -241.454453)
			(xy 93.906399 -241.401749) (xy 93.922109 -241.350819) (xy 93.945235 -241.302798) (xy 93.975259 -241.258761)
			(xy 94.011511 -241.21969) (xy 94.053182 -241.186459) (xy 94.09934 -241.15981) (xy 94.148954 -241.140338)
			(xy 94.200916 -241.128478) (xy 94.254066 -241.124495) (xy 94.307216 -241.128478) (xy 94.359178 -241.140338)
			(xy 94.408792 -241.15981) (xy 94.45495 -241.186459) (xy 94.496621 -241.21969) (xy 94.532873 -241.258761)
			(xy 94.562897 -241.302798) (xy 94.586023 -241.350819) (xy 94.601733 -241.401749) (xy 94.609676 -241.454453)
			(xy 94.610174 -241.481102) (xy 94.609676 -241.507751) (xy 94.838002 -241.507751) (xy 94.838002 -241.454453)
			(xy 94.845945 -241.401749) (xy 94.861655 -241.350819) (xy 94.884781 -241.302798) (xy 94.914805 -241.258761)
			(xy 94.951057 -241.21969) (xy 94.992728 -241.186459) (xy 95.038886 -241.15981) (xy 95.0885 -241.140338)
			(xy 95.140462 -241.128478) (xy 95.193612 -241.124495) (xy 95.246762 -241.128478) (xy 95.298724 -241.140338)
			(xy 95.348338 -241.15981) (xy 95.394496 -241.186459) (xy 95.436167 -241.21969) (xy 95.472419 -241.258761)
			(xy 95.502443 -241.302798) (xy 95.525569 -241.350819) (xy 95.541279 -241.401749) (xy 95.549222 -241.454453)
			(xy 95.54972 -241.481102) (xy 95.549222 -241.507751) (xy 95.777802 -241.507751) (xy 95.777802 -241.454453)
			(xy 95.785745 -241.401749) (xy 95.801455 -241.350819) (xy 95.824581 -241.302798) (xy 95.854605 -241.258761)
			(xy 95.890857 -241.21969) (xy 95.932528 -241.186459) (xy 95.978686 -241.15981) (xy 96.0283 -241.140338)
			(xy 96.080262 -241.128478) (xy 96.133412 -241.124495) (xy 96.186562 -241.128478) (xy 96.238524 -241.140338)
			(xy 96.288138 -241.15981) (xy 96.334296 -241.186459) (xy 96.375967 -241.21969) (xy 96.412219 -241.258761)
			(xy 96.442243 -241.302798) (xy 96.465369 -241.350819) (xy 96.481079 -241.401749) (xy 96.489022 -241.454453)
			(xy 96.48952 -241.481102) (xy 96.489022 -241.507751) (xy 96.717602 -241.507751) (xy 96.717602 -241.454453)
			(xy 96.725545 -241.401749) (xy 96.741255 -241.350819) (xy 96.764381 -241.302798) (xy 96.794405 -241.258761)
			(xy 96.830657 -241.21969) (xy 96.872328 -241.186459) (xy 96.918486 -241.15981) (xy 96.9681 -241.140338)
			(xy 97.020062 -241.128478) (xy 97.073212 -241.124495) (xy 97.126362 -241.128478) (xy 97.178324 -241.140338)
			(xy 97.227938 -241.15981) (xy 97.274096 -241.186459) (xy 97.315767 -241.21969) (xy 97.352019 -241.258761)
			(xy 97.382043 -241.302798) (xy 97.405169 -241.350819) (xy 97.420879 -241.401749) (xy 97.428822 -241.454453)
			(xy 97.42932 -241.481102) (xy 97.428822 -241.507751) (xy 97.657402 -241.507751) (xy 97.657402 -241.454453)
			(xy 97.665345 -241.401749) (xy 97.681055 -241.350819) (xy 97.704181 -241.302798) (xy 97.734205 -241.258761)
			(xy 97.770457 -241.21969) (xy 97.812128 -241.186459) (xy 97.858286 -241.15981) (xy 97.9079 -241.140338)
			(xy 97.959862 -241.128478) (xy 98.013012 -241.124495) (xy 98.066162 -241.128478) (xy 98.118124 -241.140338)
			(xy 98.167738 -241.15981) (xy 98.213896 -241.186459) (xy 98.255567 -241.21969) (xy 98.291819 -241.258761)
			(xy 98.321843 -241.302798) (xy 98.344969 -241.350819) (xy 98.360679 -241.401749) (xy 98.368622 -241.454453)
			(xy 98.36912 -241.481102) (xy 98.368622 -241.507751) (xy 98.597202 -241.507751) (xy 98.597202 -241.454453)
			(xy 98.605145 -241.401749) (xy 98.620855 -241.350819) (xy 98.643981 -241.302798) (xy 98.674005 -241.258761)
			(xy 98.710257 -241.21969) (xy 98.751928 -241.186459) (xy 98.798086 -241.15981) (xy 98.8477 -241.140338)
			(xy 98.899662 -241.128478) (xy 98.952812 -241.124495) (xy 99.005962 -241.128478) (xy 99.057924 -241.140338)
			(xy 99.107538 -241.15981) (xy 99.153696 -241.186459) (xy 99.195367 -241.21969) (xy 99.231619 -241.258761)
			(xy 99.261643 -241.302798) (xy 99.284769 -241.350819) (xy 99.300479 -241.401749) (xy 99.308422 -241.454453)
			(xy 99.30892 -241.481102) (xy 99.308422 -241.507751) (xy 99.300479 -241.560455) (xy 99.284769 -241.611385)
			(xy 99.261643 -241.659406) (xy 99.231619 -241.703443) (xy 99.195367 -241.742514) (xy 99.153696 -241.775745)
			(xy 99.107538 -241.802394) (xy 99.057924 -241.821866) (xy 99.005962 -241.833726) (xy 98.952812 -241.83771)
			(xy 98.899662 -241.833726) (xy 98.8477 -241.821866) (xy 98.798086 -241.802394) (xy 98.751928 -241.775745)
			(xy 98.710257 -241.742514) (xy 98.674005 -241.703443) (xy 98.643981 -241.659406) (xy 98.620855 -241.611385)
			(xy 98.605145 -241.560455) (xy 98.597202 -241.507751) (xy 98.368622 -241.507751) (xy 98.360679 -241.560455)
			(xy 98.344969 -241.611385) (xy 98.321843 -241.659406) (xy 98.291819 -241.703443) (xy 98.255567 -241.742514)
			(xy 98.213896 -241.775745) (xy 98.167738 -241.802394) (xy 98.118124 -241.821866) (xy 98.066162 -241.833726)
			(xy 98.013012 -241.83771) (xy 97.959862 -241.833726) (xy 97.9079 -241.821866) (xy 97.858286 -241.802394)
			(xy 97.812128 -241.775745) (xy 97.770457 -241.742514) (xy 97.734205 -241.703443) (xy 97.704181 -241.659406)
			(xy 97.681055 -241.611385) (xy 97.665345 -241.560455) (xy 97.657402 -241.507751) (xy 97.428822 -241.507751)
			(xy 97.420879 -241.560455) (xy 97.405169 -241.611385) (xy 97.382043 -241.659406) (xy 97.352019 -241.703443)
			(xy 97.315767 -241.742514) (xy 97.274096 -241.775745) (xy 97.227938 -241.802394) (xy 97.178324 -241.821866)
			(xy 97.126362 -241.833726) (xy 97.073212 -241.83771) (xy 97.020062 -241.833726) (xy 96.9681 -241.821866)
			(xy 96.918486 -241.802394) (xy 96.872328 -241.775745) (xy 96.830657 -241.742514) (xy 96.794405 -241.703443)
			(xy 96.764381 -241.659406) (xy 96.741255 -241.611385) (xy 96.725545 -241.560455) (xy 96.717602 -241.507751)
			(xy 96.489022 -241.507751) (xy 96.481079 -241.560455) (xy 96.465369 -241.611385) (xy 96.442243 -241.659406)
			(xy 96.412219 -241.703443) (xy 96.375967 -241.742514) (xy 96.334296 -241.775745) (xy 96.288138 -241.802394)
			(xy 96.238524 -241.821866) (xy 96.186562 -241.833726) (xy 96.133412 -241.83771) (xy 96.080262 -241.833726)
			(xy 96.0283 -241.821866) (xy 95.978686 -241.802394) (xy 95.932528 -241.775745) (xy 95.890857 -241.742514)
			(xy 95.854605 -241.703443) (xy 95.824581 -241.659406) (xy 95.801455 -241.611385) (xy 95.785745 -241.560455)
			(xy 95.777802 -241.507751) (xy 95.549222 -241.507751) (xy 95.541279 -241.560455) (xy 95.525569 -241.611385)
			(xy 95.502443 -241.659406) (xy 95.472419 -241.703443) (xy 95.436167 -241.742514) (xy 95.394496 -241.775745)
			(xy 95.348338 -241.802394) (xy 95.298724 -241.821866) (xy 95.246762 -241.833726) (xy 95.193612 -241.83771)
			(xy 95.140462 -241.833726) (xy 95.0885 -241.821866) (xy 95.038886 -241.802394) (xy 94.992728 -241.775745)
			(xy 94.951057 -241.742514) (xy 94.914805 -241.703443) (xy 94.884781 -241.659406) (xy 94.861655 -241.611385)
			(xy 94.845945 -241.560455) (xy 94.838002 -241.507751) (xy 94.609676 -241.507751) (xy 94.601733 -241.560455)
			(xy 94.586023 -241.611385) (xy 94.562897 -241.659406) (xy 94.532873 -241.703443) (xy 94.496621 -241.742514)
			(xy 94.45495 -241.775745) (xy 94.408792 -241.802394) (xy 94.359178 -241.821866) (xy 94.307216 -241.833726)
			(xy 94.254066 -241.83771) (xy 94.200916 -241.833726) (xy 94.148954 -241.821866) (xy 94.09934 -241.802394)
			(xy 94.053182 -241.775745) (xy 94.011511 -241.742514) (xy 93.975259 -241.703443) (xy 93.945235 -241.659406)
			(xy 93.922109 -241.611385) (xy 93.906399 -241.560455) (xy 93.898456 -241.507751) (xy 93.669622 -241.507751)
			(xy 93.661679 -241.560455) (xy 93.645969 -241.611385) (xy 93.622843 -241.659406) (xy 93.592819 -241.703443)
			(xy 93.556567 -241.742514) (xy 93.514896 -241.775745) (xy 93.468738 -241.802394) (xy 93.419124 -241.821866)
			(xy 93.367162 -241.833726) (xy 93.314012 -241.83771) (xy 93.260862 -241.833726) (xy 93.2089 -241.821866)
			(xy 93.159286 -241.802394) (xy 93.113128 -241.775745) (xy 93.071457 -241.742514) (xy 93.035205 -241.703443)
			(xy 93.005181 -241.659406) (xy 92.982055 -241.611385) (xy 92.966345 -241.560455) (xy 92.958402 -241.507751)
			(xy 92.729822 -241.507751) (xy 92.721879 -241.560455) (xy 92.706169 -241.611385) (xy 92.683043 -241.659406)
			(xy 92.653019 -241.703443) (xy 92.616767 -241.742514) (xy 92.575096 -241.775745) (xy 92.528938 -241.802394)
			(xy 92.479324 -241.821866) (xy 92.427362 -241.833726) (xy 92.374212 -241.83771) (xy 92.321062 -241.833726)
			(xy 92.2691 -241.821866) (xy 92.219486 -241.802394) (xy 92.173328 -241.775745) (xy 92.131657 -241.742514)
			(xy 92.095405 -241.703443) (xy 92.065381 -241.659406) (xy 92.042255 -241.611385) (xy 92.026545 -241.560455)
			(xy 92.018602 -241.507751) (xy 91.790022 -241.507751) (xy 91.782079 -241.560455) (xy 91.766369 -241.611385)
			(xy 91.743243 -241.659406) (xy 91.713219 -241.703443) (xy 91.676967 -241.742514) (xy 91.635296 -241.775745)
			(xy 91.589138 -241.802394) (xy 91.539524 -241.821866) (xy 91.487562 -241.833726) (xy 91.434412 -241.83771)
			(xy 91.381262 -241.833726) (xy 91.3293 -241.821866) (xy 91.279686 -241.802394) (xy 91.233528 -241.775745)
			(xy 91.191857 -241.742514) (xy 91.155605 -241.703443) (xy 91.125581 -241.659406) (xy 91.102455 -241.611385)
			(xy 91.086745 -241.560455) (xy 91.078802 -241.507751) (xy 90.850222 -241.507751) (xy 90.842279 -241.560455)
			(xy 90.826569 -241.611385) (xy 90.803443 -241.659406) (xy 90.773419 -241.703443) (xy 90.737167 -241.742514)
			(xy 90.695496 -241.775745) (xy 90.649338 -241.802394) (xy 90.599724 -241.821866) (xy 90.547762 -241.833726)
			(xy 90.494612 -241.83771) (xy 90.441462 -241.833726) (xy 90.3895 -241.821866) (xy 90.339886 -241.802394)
			(xy 90.293728 -241.775745) (xy 90.252057 -241.742514) (xy 90.215805 -241.703443) (xy 90.185781 -241.659406)
			(xy 90.162655 -241.611385) (xy 90.146945 -241.560455) (xy 90.139002 -241.507751) (xy 89.910422 -241.507751)
			(xy 89.902479 -241.560455) (xy 89.886769 -241.611385) (xy 89.863643 -241.659406) (xy 89.833619 -241.703443)
			(xy 89.797367 -241.742514) (xy 89.755696 -241.775745) (xy 89.709538 -241.802394) (xy 89.659924 -241.821866)
			(xy 89.607962 -241.833726) (xy 89.554812 -241.83771) (xy 89.501662 -241.833726) (xy 89.4497 -241.821866)
			(xy 89.400086 -241.802394) (xy 89.353928 -241.775745) (xy 89.312257 -241.742514) (xy 89.276005 -241.703443)
			(xy 89.245981 -241.659406) (xy 89.222855 -241.611385) (xy 89.207145 -241.560455) (xy 89.199202 -241.507751)
			(xy 88.969611 -241.507751) (xy 88.967677 -241.533788) (xy 88.956021 -241.585319) (xy 88.93688 -241.634562)
			(xy 88.910672 -241.680437) (xy 88.877974 -241.721935) (xy 88.839504 -241.758147) (xy 88.796105 -241.788278)
			(xy 88.748731 -241.811665) (xy 88.723724 -241.820192) (xy 88.688418 -241.831622) (xy 88.688418 -241.94516)
			(xy 88.688919 -241.959612) (xy 88.697015 -241.987357) (xy 88.712569 -242.011718) (xy 88.734331 -242.030739)
			(xy 88.760554 -242.042892) (xy 88.789134 -242.047201) (xy 88.817775 -242.043321) (xy 88.844178 -242.031564)
			(xy 88.85555 -242.02263) (xy 88.87491 -242.006868) (xy 88.917206 -241.980348) (xy 88.96279 -241.959991)
			(xy 89.010769 -241.946198) (xy 89.060205 -241.939238) (xy 89.085166 -241.93881) (xy 89.111817 -241.939281)
			(xy 89.164526 -241.947221) (xy 89.215462 -241.962928) (xy 89.263487 -241.986052) (xy 89.30753 -242.016076)
			(xy 89.346606 -242.052329) (xy 89.379841 -242.094001) (xy 89.406494 -242.140162) (xy 89.425969 -242.18978)
			(xy 89.43783 -242.241746) (xy 89.441814 -242.2949) (xy 89.439815 -242.321567) (xy 89.669356 -242.321567)
			(xy 89.669356 -242.268269) (xy 89.677299 -242.215565) (xy 89.693009 -242.164635) (xy 89.716135 -242.116614)
			(xy 89.746159 -242.072577) (xy 89.782411 -242.033506) (xy 89.824082 -242.000275) (xy 89.87024 -241.973626)
			(xy 89.919854 -241.954154) (xy 89.971816 -241.942294) (xy 90.024966 -241.938311) (xy 90.078116 -241.942294)
			(xy 90.130078 -241.954154) (xy 90.179692 -241.973626) (xy 90.22585 -242.000275) (xy 90.267521 -242.033506)
			(xy 90.303773 -242.072577) (xy 90.333797 -242.116614) (xy 90.356923 -242.164635) (xy 90.372633 -242.215565)
			(xy 90.380576 -242.268269) (xy 90.381074 -242.294918) (xy 90.380576 -242.321567) (xy 90.609156 -242.321567)
			(xy 90.609156 -242.268269) (xy 90.617099 -242.215565) (xy 90.632809 -242.164635) (xy 90.655935 -242.116614)
			(xy 90.685959 -242.072577) (xy 90.722211 -242.033506) (xy 90.763882 -242.000275) (xy 90.81004 -241.973626)
			(xy 90.859654 -241.954154) (xy 90.911616 -241.942294) (xy 90.964766 -241.938311) (xy 91.017916 -241.942294)
			(xy 91.069878 -241.954154) (xy 91.119492 -241.973626) (xy 91.16565 -242.000275) (xy 91.207321 -242.033506)
			(xy 91.243573 -242.072577) (xy 91.273597 -242.116614) (xy 91.296723 -242.164635) (xy 91.312433 -242.215565)
			(xy 91.320376 -242.268269) (xy 91.320874 -242.294918) (xy 91.320376 -242.321567) (xy 91.548956 -242.321567)
			(xy 91.548956 -242.268269) (xy 91.556899 -242.215565) (xy 91.572609 -242.164635) (xy 91.595735 -242.116614)
			(xy 91.625759 -242.072577) (xy 91.662011 -242.033506) (xy 91.703682 -242.000275) (xy 91.74984 -241.973626)
			(xy 91.799454 -241.954154) (xy 91.851416 -241.942294) (xy 91.904566 -241.938311) (xy 91.957716 -241.942294)
			(xy 92.009678 -241.954154) (xy 92.059292 -241.973626) (xy 92.10545 -242.000275) (xy 92.147121 -242.033506)
			(xy 92.183373 -242.072577) (xy 92.213397 -242.116614) (xy 92.236523 -242.164635) (xy 92.252233 -242.215565)
			(xy 92.260176 -242.268269) (xy 92.260674 -242.294918) (xy 92.260176 -242.321567) (xy 92.488756 -242.321567)
			(xy 92.488756 -242.268269) (xy 92.496699 -242.215565) (xy 92.512409 -242.164635) (xy 92.535535 -242.116614)
			(xy 92.565559 -242.072577) (xy 92.601811 -242.033506) (xy 92.643482 -242.000275) (xy 92.68964 -241.973626)
			(xy 92.739254 -241.954154) (xy 92.791216 -241.942294) (xy 92.844366 -241.938311) (xy 92.897516 -241.942294)
			(xy 92.949478 -241.954154) (xy 92.999092 -241.973626) (xy 93.04525 -242.000275) (xy 93.086921 -242.033506)
			(xy 93.123173 -242.072577) (xy 93.153197 -242.116614) (xy 93.176323 -242.164635) (xy 93.192033 -242.215565)
			(xy 93.199976 -242.268269) (xy 93.200474 -242.294918) (xy 93.199976 -242.321567) (xy 93.428556 -242.321567)
			(xy 93.428556 -242.268269) (xy 93.436499 -242.215565) (xy 93.452209 -242.164635) (xy 93.475335 -242.116614)
			(xy 93.505359 -242.072577) (xy 93.541611 -242.033506) (xy 93.583282 -242.000275) (xy 93.62944 -241.973626)
			(xy 93.679054 -241.954154) (xy 93.731016 -241.942294) (xy 93.784166 -241.938311) (xy 93.837316 -241.942294)
			(xy 93.889278 -241.954154) (xy 93.938892 -241.973626) (xy 93.98505 -242.000275) (xy 94.026721 -242.033506)
			(xy 94.062973 -242.072577) (xy 94.092997 -242.116614) (xy 94.116123 -242.164635) (xy 94.131833 -242.215565)
			(xy 94.139776 -242.268269) (xy 94.140274 -242.294918) (xy 94.139776 -242.321567) (xy 94.368356 -242.321567)
			(xy 94.368356 -242.268269) (xy 94.376299 -242.215565) (xy 94.392009 -242.164635) (xy 94.415135 -242.116614)
			(xy 94.445159 -242.072577) (xy 94.481411 -242.033506) (xy 94.523082 -242.000275) (xy 94.56924 -241.973626)
			(xy 94.618854 -241.954154) (xy 94.670816 -241.942294) (xy 94.723966 -241.938311) (xy 94.777116 -241.942294)
			(xy 94.829078 -241.954154) (xy 94.878692 -241.973626) (xy 94.92485 -242.000275) (xy 94.966521 -242.033506)
			(xy 95.002773 -242.072577) (xy 95.032797 -242.116614) (xy 95.055923 -242.164635) (xy 95.071633 -242.215565)
			(xy 95.079576 -242.268269) (xy 95.080074 -242.294918) (xy 95.079576 -242.321567) (xy 95.308156 -242.321567)
			(xy 95.308156 -242.268269) (xy 95.316099 -242.215565) (xy 95.331809 -242.164635) (xy 95.354935 -242.116614)
			(xy 95.384959 -242.072577) (xy 95.421211 -242.033506) (xy 95.462882 -242.000275) (xy 95.50904 -241.973626)
			(xy 95.558654 -241.954154) (xy 95.610616 -241.942294) (xy 95.663766 -241.938311) (xy 95.716916 -241.942294)
			(xy 95.768878 -241.954154) (xy 95.818492 -241.973626) (xy 95.86465 -242.000275) (xy 95.906321 -242.033506)
			(xy 95.942573 -242.072577) (xy 95.972597 -242.116614) (xy 95.995723 -242.164635) (xy 96.011433 -242.215565)
			(xy 96.019376 -242.268269) (xy 96.019874 -242.294918) (xy 96.019376 -242.321567) (xy 96.247956 -242.321567)
			(xy 96.247956 -242.268269) (xy 96.255899 -242.215565) (xy 96.271609 -242.164635) (xy 96.294735 -242.116614)
			(xy 96.324759 -242.072577) (xy 96.361011 -242.033506) (xy 96.402682 -242.000275) (xy 96.44884 -241.973626)
			(xy 96.498454 -241.954154) (xy 96.550416 -241.942294) (xy 96.603566 -241.938311) (xy 96.656716 -241.942294)
			(xy 96.708678 -241.954154) (xy 96.758292 -241.973626) (xy 96.80445 -242.000275) (xy 96.846121 -242.033506)
			(xy 96.882373 -242.072577) (xy 96.912397 -242.116614) (xy 96.935523 -242.164635) (xy 96.951233 -242.215565)
			(xy 96.959176 -242.268269) (xy 96.959674 -242.294918) (xy 96.959176 -242.321567) (xy 97.187756 -242.321567)
			(xy 97.187756 -242.268269) (xy 97.195699 -242.215565) (xy 97.211409 -242.164635) (xy 97.234535 -242.116614)
			(xy 97.264559 -242.072577) (xy 97.300811 -242.033506) (xy 97.342482 -242.000275) (xy 97.38864 -241.973626)
			(xy 97.438254 -241.954154) (xy 97.490216 -241.942294) (xy 97.543366 -241.938311) (xy 97.596516 -241.942294)
			(xy 97.648478 -241.954154) (xy 97.698092 -241.973626) (xy 97.74425 -242.000275) (xy 97.785921 -242.033506)
			(xy 97.822173 -242.072577) (xy 97.852197 -242.116614) (xy 97.875323 -242.164635) (xy 97.891033 -242.215565)
			(xy 97.898976 -242.268269) (xy 97.899474 -242.294918) (xy 97.898976 -242.321567) (xy 98.127556 -242.321567)
			(xy 98.127556 -242.268269) (xy 98.135499 -242.215565) (xy 98.151209 -242.164635) (xy 98.174335 -242.116614)
			(xy 98.204359 -242.072577) (xy 98.240611 -242.033506) (xy 98.282282 -242.000275) (xy 98.32844 -241.973626)
			(xy 98.378054 -241.954154) (xy 98.430016 -241.942294) (xy 98.483166 -241.938311) (xy 98.536316 -241.942294)
			(xy 98.588278 -241.954154) (xy 98.637892 -241.973626) (xy 98.68405 -242.000275) (xy 98.725721 -242.033506)
			(xy 98.761973 -242.072577) (xy 98.791997 -242.116614) (xy 98.815123 -242.164635) (xy 98.830833 -242.215565)
			(xy 98.838776 -242.268269) (xy 98.839274 -242.294918) (xy 98.838776 -242.321567) (xy 98.830833 -242.374271)
			(xy 98.815123 -242.425201) (xy 98.791997 -242.473222) (xy 98.761973 -242.517259) (xy 98.725721 -242.55633)
			(xy 98.68405 -242.589561) (xy 98.637892 -242.61621) (xy 98.588278 -242.635682) (xy 98.536316 -242.647542)
			(xy 98.483166 -242.651526) (xy 98.430016 -242.647542) (xy 98.378054 -242.635682) (xy 98.32844 -242.61621)
			(xy 98.282282 -242.589561) (xy 98.240611 -242.55633) (xy 98.204359 -242.517259) (xy 98.174335 -242.473222)
			(xy 98.151209 -242.425201) (xy 98.135499 -242.374271) (xy 98.127556 -242.321567) (xy 97.898976 -242.321567)
			(xy 97.891033 -242.374271) (xy 97.875323 -242.425201) (xy 97.852197 -242.473222) (xy 97.822173 -242.517259)
			(xy 97.785921 -242.55633) (xy 97.74425 -242.589561) (xy 97.698092 -242.61621) (xy 97.648478 -242.635682)
			(xy 97.596516 -242.647542) (xy 97.543366 -242.651526) (xy 97.490216 -242.647542) (xy 97.438254 -242.635682)
			(xy 97.38864 -242.61621) (xy 97.342482 -242.589561) (xy 97.300811 -242.55633) (xy 97.264559 -242.517259)
			(xy 97.234535 -242.473222) (xy 97.211409 -242.425201) (xy 97.195699 -242.374271) (xy 97.187756 -242.321567)
			(xy 96.959176 -242.321567) (xy 96.951233 -242.374271) (xy 96.935523 -242.425201) (xy 96.912397 -242.473222)
			(xy 96.882373 -242.517259) (xy 96.846121 -242.55633) (xy 96.80445 -242.589561) (xy 96.758292 -242.61621)
			(xy 96.708678 -242.635682) (xy 96.656716 -242.647542) (xy 96.603566 -242.651526) (xy 96.550416 -242.647542)
			(xy 96.498454 -242.635682) (xy 96.44884 -242.61621) (xy 96.402682 -242.589561) (xy 96.361011 -242.55633)
			(xy 96.324759 -242.517259) (xy 96.294735 -242.473222) (xy 96.271609 -242.425201) (xy 96.255899 -242.374271)
			(xy 96.247956 -242.321567) (xy 96.019376 -242.321567) (xy 96.011433 -242.374271) (xy 95.995723 -242.425201)
			(xy 95.972597 -242.473222) (xy 95.942573 -242.517259) (xy 95.906321 -242.55633) (xy 95.86465 -242.589561)
			(xy 95.818492 -242.61621) (xy 95.768878 -242.635682) (xy 95.716916 -242.647542) (xy 95.663766 -242.651526)
			(xy 95.610616 -242.647542) (xy 95.558654 -242.635682) (xy 95.50904 -242.61621) (xy 95.462882 -242.589561)
			(xy 95.421211 -242.55633) (xy 95.384959 -242.517259) (xy 95.354935 -242.473222) (xy 95.331809 -242.425201)
			(xy 95.316099 -242.374271) (xy 95.308156 -242.321567) (xy 95.079576 -242.321567) (xy 95.071633 -242.374271)
			(xy 95.055923 -242.425201) (xy 95.032797 -242.473222) (xy 95.002773 -242.517259) (xy 94.966521 -242.55633)
			(xy 94.92485 -242.589561) (xy 94.878692 -242.61621) (xy 94.829078 -242.635682) (xy 94.777116 -242.647542)
			(xy 94.723966 -242.651526) (xy 94.670816 -242.647542) (xy 94.618854 -242.635682) (xy 94.56924 -242.61621)
			(xy 94.523082 -242.589561) (xy 94.481411 -242.55633) (xy 94.445159 -242.517259) (xy 94.415135 -242.473222)
			(xy 94.392009 -242.425201) (xy 94.376299 -242.374271) (xy 94.368356 -242.321567) (xy 94.139776 -242.321567)
			(xy 94.131833 -242.374271) (xy 94.116123 -242.425201) (xy 94.092997 -242.473222) (xy 94.062973 -242.517259)
			(xy 94.026721 -242.55633) (xy 93.98505 -242.589561) (xy 93.938892 -242.61621) (xy 93.889278 -242.635682)
			(xy 93.837316 -242.647542) (xy 93.784166 -242.651526) (xy 93.731016 -242.647542) (xy 93.679054 -242.635682)
			(xy 93.62944 -242.61621) (xy 93.583282 -242.589561) (xy 93.541611 -242.55633) (xy 93.505359 -242.517259)
			(xy 93.475335 -242.473222) (xy 93.452209 -242.425201) (xy 93.436499 -242.374271) (xy 93.428556 -242.321567)
			(xy 93.199976 -242.321567) (xy 93.192033 -242.374271) (xy 93.176323 -242.425201) (xy 93.153197 -242.473222)
			(xy 93.123173 -242.517259) (xy 93.086921 -242.55633) (xy 93.04525 -242.589561) (xy 92.999092 -242.61621)
			(xy 92.949478 -242.635682) (xy 92.897516 -242.647542) (xy 92.844366 -242.651526) (xy 92.791216 -242.647542)
			(xy 92.739254 -242.635682) (xy 92.68964 -242.61621) (xy 92.643482 -242.589561) (xy 92.601811 -242.55633)
			(xy 92.565559 -242.517259) (xy 92.535535 -242.473222) (xy 92.512409 -242.425201) (xy 92.496699 -242.374271)
			(xy 92.488756 -242.321567) (xy 92.260176 -242.321567) (xy 92.252233 -242.374271) (xy 92.236523 -242.425201)
			(xy 92.213397 -242.473222) (xy 92.183373 -242.517259) (xy 92.147121 -242.55633) (xy 92.10545 -242.589561)
			(xy 92.059292 -242.61621) (xy 92.009678 -242.635682) (xy 91.957716 -242.647542) (xy 91.904566 -242.651526)
			(xy 91.851416 -242.647542) (xy 91.799454 -242.635682) (xy 91.74984 -242.61621) (xy 91.703682 -242.589561)
			(xy 91.662011 -242.55633) (xy 91.625759 -242.517259) (xy 91.595735 -242.473222) (xy 91.572609 -242.425201)
			(xy 91.556899 -242.374271) (xy 91.548956 -242.321567) (xy 91.320376 -242.321567) (xy 91.312433 -242.374271)
			(xy 91.296723 -242.425201) (xy 91.273597 -242.473222) (xy 91.243573 -242.517259) (xy 91.207321 -242.55633)
			(xy 91.16565 -242.589561) (xy 91.119492 -242.61621) (xy 91.069878 -242.635682) (xy 91.017916 -242.647542)
			(xy 90.964766 -242.651526) (xy 90.911616 -242.647542) (xy 90.859654 -242.635682) (xy 90.81004 -242.61621)
			(xy 90.763882 -242.589561) (xy 90.722211 -242.55633) (xy 90.685959 -242.517259) (xy 90.655935 -242.473222)
			(xy 90.632809 -242.425201) (xy 90.617099 -242.374271) (xy 90.609156 -242.321567) (xy 90.380576 -242.321567)
			(xy 90.372633 -242.374271) (xy 90.356923 -242.425201) (xy 90.333797 -242.473222) (xy 90.303773 -242.517259)
			(xy 90.267521 -242.55633) (xy 90.22585 -242.589561) (xy 90.179692 -242.61621) (xy 90.130078 -242.635682)
			(xy 90.078116 -242.647542) (xy 90.024966 -242.651526) (xy 89.971816 -242.647542) (xy 89.919854 -242.635682)
			(xy 89.87024 -242.61621) (xy 89.824082 -242.589561) (xy 89.782411 -242.55633) (xy 89.746159 -242.517259)
			(xy 89.716135 -242.473222) (xy 89.693009 -242.425201) (xy 89.677299 -242.374271) (xy 89.669356 -242.321567)
			(xy 89.439815 -242.321567) (xy 89.43783 -242.348054) (xy 89.425969 -242.40002) (xy 89.406494 -242.449638)
			(xy 89.379841 -242.495799) (xy 89.346606 -242.537471) (xy 89.30753 -242.573724) (xy 89.263487 -242.603748)
			(xy 89.215462 -242.626872) (xy 89.164526 -242.642579) (xy 89.111817 -242.650519) (xy 89.085166 -242.651026)
			(xy 89.060205 -242.650605) (xy 89.010773 -242.643634) (xy 88.962797 -242.629834) (xy 88.917216 -242.609474)
			(xy 88.874922 -242.582953) (xy 88.85555 -242.567206) (xy 88.844191 -242.558271) (xy 88.817787 -242.546556)
			(xy 88.789159 -242.542705) (xy 88.760597 -242.547027) (xy 88.73439 -242.559175) (xy 88.712634 -242.578178)
			(xy 88.697071 -242.602513) (xy 88.688946 -242.630233) (xy 88.688418 -242.644676) (xy 88.688418 -242.758468)
			(xy 88.723724 -242.769898) (xy 88.748733 -242.778421) (xy 88.79611 -242.801809) (xy 88.83951 -242.83194)
			(xy 88.877983 -242.868153) (xy 88.910682 -242.909653) (xy 88.936891 -242.955529) (xy 88.956034 -243.004774)
			(xy 88.96769 -243.056307) (xy 88.971605 -243.108996) (xy 88.969626 -243.135637) (xy 89.199202 -243.135637)
			(xy 89.199202 -243.082339) (xy 89.207145 -243.029635) (xy 89.222855 -242.978705) (xy 89.245981 -242.930684)
			(xy 89.276005 -242.886647) (xy 89.312257 -242.847576) (xy 89.353928 -242.814345) (xy 89.400086 -242.787696)
			(xy 89.4497 -242.768224) (xy 89.501662 -242.756364) (xy 89.554812 -242.752381) (xy 89.607962 -242.756364)
			(xy 89.659924 -242.768224) (xy 89.709538 -242.787696) (xy 89.755696 -242.814345) (xy 89.797367 -242.847576)
			(xy 89.833619 -242.886647) (xy 89.863643 -242.930684) (xy 89.886769 -242.978705) (xy 89.902479 -243.029635)
			(xy 89.910422 -243.082339) (xy 89.91092 -243.108988) (xy 89.910422 -243.135637) (xy 90.139002 -243.135637)
			(xy 90.139002 -243.082339) (xy 90.146945 -243.029635) (xy 90.162655 -242.978705) (xy 90.185781 -242.930684)
			(xy 90.215805 -242.886647) (xy 90.252057 -242.847576) (xy 90.293728 -242.814345) (xy 90.339886 -242.787696)
			(xy 90.3895 -242.768224) (xy 90.441462 -242.756364) (xy 90.494612 -242.752381) (xy 90.547762 -242.756364)
			(xy 90.599724 -242.768224) (xy 90.649338 -242.787696) (xy 90.695496 -242.814345) (xy 90.737167 -242.847576)
			(xy 90.773419 -242.886647) (xy 90.803443 -242.930684) (xy 90.826569 -242.978705) (xy 90.842279 -243.029635)
			(xy 90.850222 -243.082339) (xy 90.85072 -243.108988) (xy 90.850222 -243.135637) (xy 91.079056 -243.135637)
			(xy 91.079056 -243.082339) (xy 91.086999 -243.029635) (xy 91.102709 -242.978705) (xy 91.125835 -242.930684)
			(xy 91.155859 -242.886647) (xy 91.192111 -242.847576) (xy 91.233782 -242.814345) (xy 91.27994 -242.787696)
			(xy 91.329554 -242.768224) (xy 91.381516 -242.756364) (xy 91.434666 -242.752381) (xy 91.487816 -242.756364)
			(xy 91.539778 -242.768224) (xy 91.589392 -242.787696) (xy 91.63555 -242.814345) (xy 91.677221 -242.847576)
			(xy 91.713473 -242.886647) (xy 91.743497 -242.930684) (xy 91.766623 -242.978705) (xy 91.782333 -243.029635)
			(xy 91.790276 -243.082339) (xy 91.790774 -243.108988) (xy 91.790276 -243.135637) (xy 92.018602 -243.135637)
			(xy 92.018602 -243.082339) (xy 92.026545 -243.029635) (xy 92.042255 -242.978705) (xy 92.065381 -242.930684)
			(xy 92.095405 -242.886647) (xy 92.131657 -242.847576) (xy 92.173328 -242.814345) (xy 92.219486 -242.787696)
			(xy 92.2691 -242.768224) (xy 92.321062 -242.756364) (xy 92.374212 -242.752381) (xy 92.427362 -242.756364)
			(xy 92.479324 -242.768224) (xy 92.528938 -242.787696) (xy 92.575096 -242.814345) (xy 92.616767 -242.847576)
			(xy 92.653019 -242.886647) (xy 92.683043 -242.930684) (xy 92.706169 -242.978705) (xy 92.721879 -243.029635)
			(xy 92.729822 -243.082339) (xy 92.73032 -243.108988) (xy 92.729822 -243.135637) (xy 92.958402 -243.135637)
			(xy 92.958402 -243.082339) (xy 92.966345 -243.029635) (xy 92.982055 -242.978705) (xy 93.005181 -242.930684)
			(xy 93.035205 -242.886647) (xy 93.071457 -242.847576) (xy 93.113128 -242.814345) (xy 93.159286 -242.787696)
			(xy 93.2089 -242.768224) (xy 93.260862 -242.756364) (xy 93.314012 -242.752381) (xy 93.367162 -242.756364)
			(xy 93.419124 -242.768224) (xy 93.468738 -242.787696) (xy 93.514896 -242.814345) (xy 93.556567 -242.847576)
			(xy 93.592819 -242.886647) (xy 93.622843 -242.930684) (xy 93.645969 -242.978705) (xy 93.661679 -243.029635)
			(xy 93.669622 -243.082339) (xy 93.67012 -243.108988) (xy 93.669622 -243.135637) (xy 93.898202 -243.135637)
			(xy 93.898202 -243.082339) (xy 93.906145 -243.029635) (xy 93.921855 -242.978705) (xy 93.944981 -242.930684)
			(xy 93.975005 -242.886647) (xy 94.011257 -242.847576) (xy 94.052928 -242.814345) (xy 94.099086 -242.787696)
			(xy 94.1487 -242.768224) (xy 94.200662 -242.756364) (xy 94.253812 -242.752381) (xy 94.306962 -242.756364)
			(xy 94.358924 -242.768224) (xy 94.408538 -242.787696) (xy 94.454696 -242.814345) (xy 94.496367 -242.847576)
			(xy 94.532619 -242.886647) (xy 94.562643 -242.930684) (xy 94.585769 -242.978705) (xy 94.601479 -243.029635)
			(xy 94.609422 -243.082339) (xy 94.60992 -243.108988) (xy 94.609422 -243.135637) (xy 94.838002 -243.135637)
			(xy 94.838002 -243.082339) (xy 94.845945 -243.029635) (xy 94.861655 -242.978705) (xy 94.884781 -242.930684)
			(xy 94.914805 -242.886647) (xy 94.951057 -242.847576) (xy 94.992728 -242.814345) (xy 95.038886 -242.787696)
			(xy 95.0885 -242.768224) (xy 95.140462 -242.756364) (xy 95.193612 -242.752381) (xy 95.246762 -242.756364)
			(xy 95.298724 -242.768224) (xy 95.348338 -242.787696) (xy 95.394496 -242.814345) (xy 95.436167 -242.847576)
			(xy 95.472419 -242.886647) (xy 95.502443 -242.930684) (xy 95.525569 -242.978705) (xy 95.541279 -243.029635)
			(xy 95.549222 -243.082339) (xy 95.54972 -243.108988) (xy 95.549222 -243.135637) (xy 95.777802 -243.135637)
			(xy 95.777802 -243.082339) (xy 95.785745 -243.029635) (xy 95.801455 -242.978705) (xy 95.824581 -242.930684)
			(xy 95.854605 -242.886647) (xy 95.890857 -242.847576) (xy 95.932528 -242.814345) (xy 95.978686 -242.787696)
			(xy 96.0283 -242.768224) (xy 96.080262 -242.756364) (xy 96.133412 -242.752381) (xy 96.186562 -242.756364)
			(xy 96.238524 -242.768224) (xy 96.288138 -242.787696) (xy 96.334296 -242.814345) (xy 96.375967 -242.847576)
			(xy 96.412219 -242.886647) (xy 96.442243 -242.930684) (xy 96.465369 -242.978705) (xy 96.481079 -243.029635)
			(xy 96.489022 -243.082339) (xy 96.48952 -243.108988) (xy 96.489022 -243.135637) (xy 96.717602 -243.135637)
			(xy 96.717602 -243.082339) (xy 96.725545 -243.029635) (xy 96.741255 -242.978705) (xy 96.764381 -242.930684)
			(xy 96.794405 -242.886647) (xy 96.830657 -242.847576) (xy 96.872328 -242.814345) (xy 96.918486 -242.787696)
			(xy 96.9681 -242.768224) (xy 97.020062 -242.756364) (xy 97.073212 -242.752381) (xy 97.126362 -242.756364)
			(xy 97.178324 -242.768224) (xy 97.227938 -242.787696) (xy 97.274096 -242.814345) (xy 97.315767 -242.847576)
			(xy 97.352019 -242.886647) (xy 97.382043 -242.930684) (xy 97.405169 -242.978705) (xy 97.420879 -243.029635)
			(xy 97.428822 -243.082339) (xy 97.42932 -243.108988) (xy 97.428822 -243.135637) (xy 97.657656 -243.135637)
			(xy 97.657656 -243.082339) (xy 97.665599 -243.029635) (xy 97.681309 -242.978705) (xy 97.704435 -242.930684)
			(xy 97.734459 -242.886647) (xy 97.770711 -242.847576) (xy 97.812382 -242.814345) (xy 97.85854 -242.787696)
			(xy 97.908154 -242.768224) (xy 97.960116 -242.756364) (xy 98.013266 -242.752381) (xy 98.066416 -242.756364)
			(xy 98.118378 -242.768224) (xy 98.167992 -242.787696) (xy 98.21415 -242.814345) (xy 98.255821 -242.847576)
			(xy 98.292073 -242.886647) (xy 98.322097 -242.930684) (xy 98.345223 -242.978705) (xy 98.360933 -243.029635)
			(xy 98.368876 -243.082339) (xy 98.369374 -243.108988) (xy 98.368876 -243.135637) (xy 98.597202 -243.135637)
			(xy 98.597202 -243.082339) (xy 98.605145 -243.029635) (xy 98.620855 -242.978705) (xy 98.643981 -242.930684)
			(xy 98.674005 -242.886647) (xy 98.710257 -242.847576) (xy 98.751928 -242.814345) (xy 98.798086 -242.787696)
			(xy 98.8477 -242.768224) (xy 98.899662 -242.756364) (xy 98.952812 -242.752381) (xy 99.005962 -242.756364)
			(xy 99.057924 -242.768224) (xy 99.107538 -242.787696) (xy 99.153696 -242.814345) (xy 99.195367 -242.847576)
			(xy 99.231619 -242.886647) (xy 99.261643 -242.930684) (xy 99.284769 -242.978705) (xy 99.300479 -243.029635)
			(xy 99.308422 -243.082339) (xy 99.30892 -243.108988) (xy 99.308422 -243.135637) (xy 99.300479 -243.188341)
			(xy 99.284769 -243.239271) (xy 99.261643 -243.287292) (xy 99.231619 -243.331329) (xy 99.195367 -243.3704)
			(xy 99.153696 -243.403631) (xy 99.107538 -243.43028) (xy 99.057924 -243.449752) (xy 99.005962 -243.461612)
			(xy 98.952812 -243.465596) (xy 98.899662 -243.461612) (xy 98.8477 -243.449752) (xy 98.798086 -243.43028)
			(xy 98.751928 -243.403631) (xy 98.710257 -243.3704) (xy 98.674005 -243.331329) (xy 98.643981 -243.287292)
			(xy 98.620855 -243.239271) (xy 98.605145 -243.188341) (xy 98.597202 -243.135637) (xy 98.368876 -243.135637)
			(xy 98.360933 -243.188341) (xy 98.345223 -243.239271) (xy 98.322097 -243.287292) (xy 98.292073 -243.331329)
			(xy 98.255821 -243.3704) (xy 98.21415 -243.403631) (xy 98.167992 -243.43028) (xy 98.118378 -243.449752)
			(xy 98.066416 -243.461612) (xy 98.013266 -243.465596) (xy 97.960116 -243.461612) (xy 97.908154 -243.449752)
			(xy 97.85854 -243.43028) (xy 97.812382 -243.403631) (xy 97.770711 -243.3704) (xy 97.734459 -243.331329)
			(xy 97.704435 -243.287292) (xy 97.681309 -243.239271) (xy 97.665599 -243.188341) (xy 97.657656 -243.135637)
			(xy 97.428822 -243.135637) (xy 97.420879 -243.188341) (xy 97.405169 -243.239271) (xy 97.382043 -243.287292)
			(xy 97.352019 -243.331329) (xy 97.315767 -243.3704) (xy 97.274096 -243.403631) (xy 97.227938 -243.43028)
			(xy 97.178324 -243.449752) (xy 97.126362 -243.461612) (xy 97.073212 -243.465596) (xy 97.020062 -243.461612)
			(xy 96.9681 -243.449752) (xy 96.918486 -243.43028) (xy 96.872328 -243.403631) (xy 96.830657 -243.3704)
			(xy 96.794405 -243.331329) (xy 96.764381 -243.287292) (xy 96.741255 -243.239271) (xy 96.725545 -243.188341)
			(xy 96.717602 -243.135637) (xy 96.489022 -243.135637) (xy 96.481079 -243.188341) (xy 96.465369 -243.239271)
			(xy 96.442243 -243.287292) (xy 96.412219 -243.331329) (xy 96.375967 -243.3704) (xy 96.334296 -243.403631)
			(xy 96.288138 -243.43028) (xy 96.238524 -243.449752) (xy 96.186562 -243.461612) (xy 96.133412 -243.465596)
			(xy 96.080262 -243.461612) (xy 96.0283 -243.449752) (xy 95.978686 -243.43028) (xy 95.932528 -243.403631)
			(xy 95.890857 -243.3704) (xy 95.854605 -243.331329) (xy 95.824581 -243.287292) (xy 95.801455 -243.239271)
			(xy 95.785745 -243.188341) (xy 95.777802 -243.135637) (xy 95.549222 -243.135637) (xy 95.541279 -243.188341)
			(xy 95.525569 -243.239271) (xy 95.502443 -243.287292) (xy 95.472419 -243.331329) (xy 95.436167 -243.3704)
			(xy 95.394496 -243.403631) (xy 95.348338 -243.43028) (xy 95.298724 -243.449752) (xy 95.246762 -243.461612)
			(xy 95.193612 -243.465596) (xy 95.140462 -243.461612) (xy 95.0885 -243.449752) (xy 95.038886 -243.43028)
			(xy 94.992728 -243.403631) (xy 94.951057 -243.3704) (xy 94.914805 -243.331329) (xy 94.884781 -243.287292)
			(xy 94.861655 -243.239271) (xy 94.845945 -243.188341) (xy 94.838002 -243.135637) (xy 94.609422 -243.135637)
			(xy 94.601479 -243.188341) (xy 94.585769 -243.239271) (xy 94.562643 -243.287292) (xy 94.532619 -243.331329)
			(xy 94.496367 -243.3704) (xy 94.454696 -243.403631) (xy 94.408538 -243.43028) (xy 94.358924 -243.449752)
			(xy 94.306962 -243.461612) (xy 94.253812 -243.465596) (xy 94.200662 -243.461612) (xy 94.1487 -243.449752)
			(xy 94.099086 -243.43028) (xy 94.052928 -243.403631) (xy 94.011257 -243.3704) (xy 93.975005 -243.331329)
			(xy 93.944981 -243.287292) (xy 93.921855 -243.239271) (xy 93.906145 -243.188341) (xy 93.898202 -243.135637)
			(xy 93.669622 -243.135637) (xy 93.661679 -243.188341) (xy 93.645969 -243.239271) (xy 93.622843 -243.287292)
			(xy 93.592819 -243.331329) (xy 93.556567 -243.3704) (xy 93.514896 -243.403631) (xy 93.468738 -243.43028)
			(xy 93.419124 -243.449752) (xy 93.367162 -243.461612) (xy 93.314012 -243.465596) (xy 93.260862 -243.461612)
			(xy 93.2089 -243.449752) (xy 93.159286 -243.43028) (xy 93.113128 -243.403631) (xy 93.071457 -243.3704)
			(xy 93.035205 -243.331329) (xy 93.005181 -243.287292) (xy 92.982055 -243.239271) (xy 92.966345 -243.188341)
			(xy 92.958402 -243.135637) (xy 92.729822 -243.135637) (xy 92.721879 -243.188341) (xy 92.706169 -243.239271)
			(xy 92.683043 -243.287292) (xy 92.653019 -243.331329) (xy 92.616767 -243.3704) (xy 92.575096 -243.403631)
			(xy 92.528938 -243.43028) (xy 92.479324 -243.449752) (xy 92.427362 -243.461612) (xy 92.374212 -243.465596)
			(xy 92.321062 -243.461612) (xy 92.2691 -243.449752) (xy 92.219486 -243.43028) (xy 92.173328 -243.403631)
			(xy 92.131657 -243.3704) (xy 92.095405 -243.331329) (xy 92.065381 -243.287292) (xy 92.042255 -243.239271)
			(xy 92.026545 -243.188341) (xy 92.018602 -243.135637) (xy 91.790276 -243.135637) (xy 91.782333 -243.188341)
			(xy 91.766623 -243.239271) (xy 91.743497 -243.287292) (xy 91.713473 -243.331329) (xy 91.677221 -243.3704)
			(xy 91.63555 -243.403631) (xy 91.589392 -243.43028) (xy 91.539778 -243.449752) (xy 91.487816 -243.461612)
			(xy 91.434666 -243.465596) (xy 91.381516 -243.461612) (xy 91.329554 -243.449752) (xy 91.27994 -243.43028)
			(xy 91.233782 -243.403631) (xy 91.192111 -243.3704) (xy 91.155859 -243.331329) (xy 91.125835 -243.287292)
			(xy 91.102709 -243.239271) (xy 91.086999 -243.188341) (xy 91.079056 -243.135637) (xy 90.850222 -243.135637)
			(xy 90.842279 -243.188341) (xy 90.826569 -243.239271) (xy 90.803443 -243.287292) (xy 90.773419 -243.331329)
			(xy 90.737167 -243.3704) (xy 90.695496 -243.403631) (xy 90.649338 -243.43028) (xy 90.599724 -243.449752)
			(xy 90.547762 -243.461612) (xy 90.494612 -243.465596) (xy 90.441462 -243.461612) (xy 90.3895 -243.449752)
			(xy 90.339886 -243.43028) (xy 90.293728 -243.403631) (xy 90.252057 -243.3704) (xy 90.215805 -243.331329)
			(xy 90.185781 -243.287292) (xy 90.162655 -243.239271) (xy 90.146945 -243.188341) (xy 90.139002 -243.135637)
			(xy 89.910422 -243.135637) (xy 89.902479 -243.188341) (xy 89.886769 -243.239271) (xy 89.863643 -243.287292)
			(xy 89.833619 -243.331329) (xy 89.797367 -243.3704) (xy 89.755696 -243.403631) (xy 89.709538 -243.43028)
			(xy 89.659924 -243.449752) (xy 89.607962 -243.461612) (xy 89.554812 -243.465596) (xy 89.501662 -243.461612)
			(xy 89.4497 -243.449752) (xy 89.400086 -243.43028) (xy 89.353928 -243.403631) (xy 89.312257 -243.3704)
			(xy 89.276005 -243.331329) (xy 89.245981 -243.287292) (xy 89.222855 -243.239271) (xy 89.207145 -243.188341)
			(xy 89.199202 -243.135637) (xy 88.969626 -243.135637) (xy 88.967691 -243.161686) (xy 88.956036 -243.213219)
			(xy 88.936894 -243.262464) (xy 88.910686 -243.308341) (xy 88.877988 -243.349841) (xy 88.839516 -243.386055)
			(xy 88.796116 -243.416187) (xy 88.74874 -243.439576) (xy 88.723724 -243.448078) (xy 88.688418 -243.459508)
			(xy 88.688418 -243.573046) (xy 88.688917 -243.587499) (xy 88.697011 -243.615248) (xy 88.712564 -243.639613)
			(xy 88.734327 -243.658637) (xy 88.760553 -243.670791) (xy 88.789136 -243.675101) (xy 88.81778 -243.67122)
			(xy 88.844185 -243.65946) (xy 88.85555 -243.650516) (xy 88.87491 -243.634755) (xy 88.917206 -243.608235)
			(xy 88.96279 -243.58788) (xy 89.01077 -243.574087) (xy 89.060205 -243.567127) (xy 89.085166 -243.566696)
			(xy 89.111819 -243.567167) (xy 89.164529 -243.575107) (xy 89.215467 -243.590815) (xy 89.263494 -243.61394)
			(xy 89.307539 -243.643965) (xy 89.346616 -243.680219) (xy 89.379853 -243.721894) (xy 89.406507 -243.768056)
			(xy 89.425982 -243.817676) (xy 89.437844 -243.869644) (xy 89.441828 -243.9228) (xy 89.43983 -243.949453)
			(xy 89.669356 -243.949453) (xy 89.669356 -243.896155) (xy 89.677299 -243.843451) (xy 89.693009 -243.792521)
			(xy 89.716135 -243.7445) (xy 89.746159 -243.700463) (xy 89.782411 -243.661392) (xy 89.824082 -243.628161)
			(xy 89.87024 -243.601512) (xy 89.919854 -243.58204) (xy 89.971816 -243.57018) (xy 90.024966 -243.566197)
			(xy 90.078116 -243.57018) (xy 90.130078 -243.58204) (xy 90.179692 -243.601512) (xy 90.22585 -243.628161)
			(xy 90.267521 -243.661392) (xy 90.303773 -243.700463) (xy 90.333797 -243.7445) (xy 90.356923 -243.792521)
			(xy 90.372633 -243.843451) (xy 90.380576 -243.896155) (xy 90.381074 -243.922804) (xy 90.380576 -243.949453)
			(xy 90.609156 -243.949453) (xy 90.609156 -243.896155) (xy 90.617099 -243.843451) (xy 90.632809 -243.792521)
			(xy 90.655935 -243.7445) (xy 90.685959 -243.700463) (xy 90.722211 -243.661392) (xy 90.763882 -243.628161)
			(xy 90.81004 -243.601512) (xy 90.859654 -243.58204) (xy 90.911616 -243.57018) (xy 90.964766 -243.566197)
			(xy 91.017916 -243.57018) (xy 91.069878 -243.58204) (xy 91.119492 -243.601512) (xy 91.16565 -243.628161)
			(xy 91.207321 -243.661392) (xy 91.243573 -243.700463) (xy 91.273597 -243.7445) (xy 91.296723 -243.792521)
			(xy 91.312433 -243.843451) (xy 91.320376 -243.896155) (xy 91.320874 -243.922804) (xy 91.320376 -243.949453)
			(xy 91.548956 -243.949453) (xy 91.548956 -243.896155) (xy 91.556899 -243.843451) (xy 91.572609 -243.792521)
			(xy 91.595735 -243.7445) (xy 91.625759 -243.700463) (xy 91.662011 -243.661392) (xy 91.703682 -243.628161)
			(xy 91.74984 -243.601512) (xy 91.799454 -243.58204) (xy 91.851416 -243.57018) (xy 91.904566 -243.566197)
			(xy 91.957716 -243.57018) (xy 92.009678 -243.58204) (xy 92.059292 -243.601512) (xy 92.10545 -243.628161)
			(xy 92.147121 -243.661392) (xy 92.183373 -243.700463) (xy 92.213397 -243.7445) (xy 92.236523 -243.792521)
			(xy 92.252233 -243.843451) (xy 92.260176 -243.896155) (xy 92.260674 -243.922804) (xy 92.260176 -243.949453)
			(xy 92.488756 -243.949453) (xy 92.488756 -243.896155) (xy 92.496699 -243.843451) (xy 92.512409 -243.792521)
			(xy 92.535535 -243.7445) (xy 92.565559 -243.700463) (xy 92.601811 -243.661392) (xy 92.643482 -243.628161)
			(xy 92.68964 -243.601512) (xy 92.739254 -243.58204) (xy 92.791216 -243.57018) (xy 92.844366 -243.566197)
			(xy 92.897516 -243.57018) (xy 92.949478 -243.58204) (xy 92.999092 -243.601512) (xy 93.04525 -243.628161)
			(xy 93.086921 -243.661392) (xy 93.123173 -243.700463) (xy 93.153197 -243.7445) (xy 93.176323 -243.792521)
			(xy 93.192033 -243.843451) (xy 93.199976 -243.896155) (xy 93.200474 -243.922804) (xy 93.199976 -243.949453)
			(xy 93.428556 -243.949453) (xy 93.428556 -243.896155) (xy 93.436499 -243.843451) (xy 93.452209 -243.792521)
			(xy 93.475335 -243.7445) (xy 93.505359 -243.700463) (xy 93.541611 -243.661392) (xy 93.583282 -243.628161)
			(xy 93.62944 -243.601512) (xy 93.679054 -243.58204) (xy 93.731016 -243.57018) (xy 93.784166 -243.566197)
			(xy 93.837316 -243.57018) (xy 93.889278 -243.58204) (xy 93.938892 -243.601512) (xy 93.98505 -243.628161)
			(xy 94.026721 -243.661392) (xy 94.062973 -243.700463) (xy 94.092997 -243.7445) (xy 94.116123 -243.792521)
			(xy 94.131833 -243.843451) (xy 94.139776 -243.896155) (xy 94.140274 -243.922804) (xy 94.139776 -243.949453)
			(xy 94.368102 -243.949453) (xy 94.368102 -243.896155) (xy 94.376045 -243.843451) (xy 94.391755 -243.792521)
			(xy 94.414881 -243.7445) (xy 94.444905 -243.700463) (xy 94.481157 -243.661392) (xy 94.522828 -243.628161)
			(xy 94.568986 -243.601512) (xy 94.6186 -243.58204) (xy 94.670562 -243.57018) (xy 94.723712 -243.566197)
			(xy 94.776862 -243.57018) (xy 94.828824 -243.58204) (xy 94.878438 -243.601512) (xy 94.924596 -243.628161)
			(xy 94.966267 -243.661392) (xy 95.002519 -243.700463) (xy 95.032543 -243.7445) (xy 95.055669 -243.792521)
			(xy 95.071379 -243.843451) (xy 95.079322 -243.896155) (xy 95.07982 -243.922804) (xy 95.079322 -243.949453)
			(xy 95.308156 -243.949453) (xy 95.308156 -243.896155) (xy 95.316099 -243.843451) (xy 95.331809 -243.792521)
			(xy 95.354935 -243.7445) (xy 95.384959 -243.700463) (xy 95.421211 -243.661392) (xy 95.462882 -243.628161)
			(xy 95.50904 -243.601512) (xy 95.558654 -243.58204) (xy 95.610616 -243.57018) (xy 95.663766 -243.566197)
			(xy 95.716916 -243.57018) (xy 95.768878 -243.58204) (xy 95.818492 -243.601512) (xy 95.86465 -243.628161)
			(xy 95.906321 -243.661392) (xy 95.942573 -243.700463) (xy 95.972597 -243.7445) (xy 95.995723 -243.792521)
			(xy 96.011433 -243.843451) (xy 96.019376 -243.896155) (xy 96.019874 -243.922804) (xy 96.019376 -243.949453)
			(xy 96.247956 -243.949453) (xy 96.247956 -243.896155) (xy 96.255899 -243.843451) (xy 96.271609 -243.792521)
			(xy 96.294735 -243.7445) (xy 96.324759 -243.700463) (xy 96.361011 -243.661392) (xy 96.402682 -243.628161)
			(xy 96.44884 -243.601512) (xy 96.498454 -243.58204) (xy 96.550416 -243.57018) (xy 96.603566 -243.566197)
			(xy 96.656716 -243.57018) (xy 96.708678 -243.58204) (xy 96.758292 -243.601512) (xy 96.80445 -243.628161)
			(xy 96.846121 -243.661392) (xy 96.882373 -243.700463) (xy 96.912397 -243.7445) (xy 96.935523 -243.792521)
			(xy 96.951233 -243.843451) (xy 96.959176 -243.896155) (xy 96.959674 -243.922804) (xy 96.959176 -243.949453)
			(xy 97.187756 -243.949453) (xy 97.187756 -243.896155) (xy 97.195699 -243.843451) (xy 97.211409 -243.792521)
			(xy 97.234535 -243.7445) (xy 97.264559 -243.700463) (xy 97.300811 -243.661392) (xy 97.342482 -243.628161)
			(xy 97.38864 -243.601512) (xy 97.438254 -243.58204) (xy 97.490216 -243.57018) (xy 97.543366 -243.566197)
			(xy 97.596516 -243.57018) (xy 97.648478 -243.58204) (xy 97.698092 -243.601512) (xy 97.74425 -243.628161)
			(xy 97.785921 -243.661392) (xy 97.822173 -243.700463) (xy 97.852197 -243.7445) (xy 97.875323 -243.792521)
			(xy 97.891033 -243.843451) (xy 97.898976 -243.896155) (xy 97.899474 -243.922804) (xy 97.898976 -243.949453)
			(xy 98.127556 -243.949453) (xy 98.127556 -243.896155) (xy 98.135499 -243.843451) (xy 98.151209 -243.792521)
			(xy 98.174335 -243.7445) (xy 98.204359 -243.700463) (xy 98.240611 -243.661392) (xy 98.282282 -243.628161)
			(xy 98.32844 -243.601512) (xy 98.378054 -243.58204) (xy 98.430016 -243.57018) (xy 98.483166 -243.566197)
			(xy 98.536316 -243.57018) (xy 98.588278 -243.58204) (xy 98.637892 -243.601512) (xy 98.68405 -243.628161)
			(xy 98.725721 -243.661392) (xy 98.761973 -243.700463) (xy 98.791997 -243.7445) (xy 98.815123 -243.792521)
			(xy 98.830833 -243.843451) (xy 98.838776 -243.896155) (xy 98.839274 -243.922804) (xy 98.838776 -243.949453)
			(xy 98.830833 -244.002157) (xy 98.815123 -244.053087) (xy 98.791997 -244.101108) (xy 98.761973 -244.145145)
			(xy 98.725721 -244.184216) (xy 98.68405 -244.217447) (xy 98.637892 -244.244096) (xy 98.588278 -244.263568)
			(xy 98.536316 -244.275428) (xy 98.483166 -244.279412) (xy 98.430016 -244.275428) (xy 98.378054 -244.263568)
			(xy 98.32844 -244.244096) (xy 98.282282 -244.217447) (xy 98.240611 -244.184216) (xy 98.204359 -244.145145)
			(xy 98.174335 -244.101108) (xy 98.151209 -244.053087) (xy 98.135499 -244.002157) (xy 98.127556 -243.949453)
			(xy 97.898976 -243.949453) (xy 97.891033 -244.002157) (xy 97.875323 -244.053087) (xy 97.852197 -244.101108)
			(xy 97.822173 -244.145145) (xy 97.785921 -244.184216) (xy 97.74425 -244.217447) (xy 97.698092 -244.244096)
			(xy 97.648478 -244.263568) (xy 97.596516 -244.275428) (xy 97.543366 -244.279412) (xy 97.490216 -244.275428)
			(xy 97.438254 -244.263568) (xy 97.38864 -244.244096) (xy 97.342482 -244.217447) (xy 97.300811 -244.184216)
			(xy 97.264559 -244.145145) (xy 97.234535 -244.101108) (xy 97.211409 -244.053087) (xy 97.195699 -244.002157)
			(xy 97.187756 -243.949453) (xy 96.959176 -243.949453) (xy 96.951233 -244.002157) (xy 96.935523 -244.053087)
			(xy 96.912397 -244.101108) (xy 96.882373 -244.145145) (xy 96.846121 -244.184216) (xy 96.80445 -244.217447)
			(xy 96.758292 -244.244096) (xy 96.708678 -244.263568) (xy 96.656716 -244.275428) (xy 96.603566 -244.279412)
			(xy 96.550416 -244.275428) (xy 96.498454 -244.263568) (xy 96.44884 -244.244096) (xy 96.402682 -244.217447)
			(xy 96.361011 -244.184216) (xy 96.324759 -244.145145) (xy 96.294735 -244.101108) (xy 96.271609 -244.053087)
			(xy 96.255899 -244.002157) (xy 96.247956 -243.949453) (xy 96.019376 -243.949453) (xy 96.011433 -244.002157)
			(xy 95.995723 -244.053087) (xy 95.972597 -244.101108) (xy 95.942573 -244.145145) (xy 95.906321 -244.184216)
			(xy 95.86465 -244.217447) (xy 95.818492 -244.244096) (xy 95.768878 -244.263568) (xy 95.716916 -244.275428)
			(xy 95.663766 -244.279412) (xy 95.610616 -244.275428) (xy 95.558654 -244.263568) (xy 95.50904 -244.244096)
			(xy 95.462882 -244.217447) (xy 95.421211 -244.184216) (xy 95.384959 -244.145145) (xy 95.354935 -244.101108)
			(xy 95.331809 -244.053087) (xy 95.316099 -244.002157) (xy 95.308156 -243.949453) (xy 95.079322 -243.949453)
			(xy 95.071379 -244.002157) (xy 95.055669 -244.053087) (xy 95.032543 -244.101108) (xy 95.002519 -244.145145)
			(xy 94.966267 -244.184216) (xy 94.924596 -244.217447) (xy 94.878438 -244.244096) (xy 94.828824 -244.263568)
			(xy 94.776862 -244.275428) (xy 94.723712 -244.279412) (xy 94.670562 -244.275428) (xy 94.6186 -244.263568)
			(xy 94.568986 -244.244096) (xy 94.522828 -244.217447) (xy 94.481157 -244.184216) (xy 94.444905 -244.145145)
			(xy 94.414881 -244.101108) (xy 94.391755 -244.053087) (xy 94.376045 -244.002157) (xy 94.368102 -243.949453)
			(xy 94.139776 -243.949453) (xy 94.131833 -244.002157) (xy 94.116123 -244.053087) (xy 94.092997 -244.101108)
			(xy 94.062973 -244.145145) (xy 94.026721 -244.184216) (xy 93.98505 -244.217447) (xy 93.938892 -244.244096)
			(xy 93.889278 -244.263568) (xy 93.837316 -244.275428) (xy 93.784166 -244.279412) (xy 93.731016 -244.275428)
			(xy 93.679054 -244.263568) (xy 93.62944 -244.244096) (xy 93.583282 -244.217447) (xy 93.541611 -244.184216)
			(xy 93.505359 -244.145145) (xy 93.475335 -244.101108) (xy 93.452209 -244.053087) (xy 93.436499 -244.002157)
			(xy 93.428556 -243.949453) (xy 93.199976 -243.949453) (xy 93.192033 -244.002157) (xy 93.176323 -244.053087)
			(xy 93.153197 -244.101108) (xy 93.123173 -244.145145) (xy 93.086921 -244.184216) (xy 93.04525 -244.217447)
			(xy 92.999092 -244.244096) (xy 92.949478 -244.263568) (xy 92.897516 -244.275428) (xy 92.844366 -244.279412)
			(xy 92.791216 -244.275428) (xy 92.739254 -244.263568) (xy 92.68964 -244.244096) (xy 92.643482 -244.217447)
			(xy 92.601811 -244.184216) (xy 92.565559 -244.145145) (xy 92.535535 -244.101108) (xy 92.512409 -244.053087)
			(xy 92.496699 -244.002157) (xy 92.488756 -243.949453) (xy 92.260176 -243.949453) (xy 92.252233 -244.002157)
			(xy 92.236523 -244.053087) (xy 92.213397 -244.101108) (xy 92.183373 -244.145145) (xy 92.147121 -244.184216)
			(xy 92.10545 -244.217447) (xy 92.059292 -244.244096) (xy 92.009678 -244.263568) (xy 91.957716 -244.275428)
			(xy 91.904566 -244.279412) (xy 91.851416 -244.275428) (xy 91.799454 -244.263568) (xy 91.74984 -244.244096)
			(xy 91.703682 -244.217447) (xy 91.662011 -244.184216) (xy 91.625759 -244.145145) (xy 91.595735 -244.101108)
			(xy 91.572609 -244.053087) (xy 91.556899 -244.002157) (xy 91.548956 -243.949453) (xy 91.320376 -243.949453)
			(xy 91.312433 -244.002157) (xy 91.296723 -244.053087) (xy 91.273597 -244.101108) (xy 91.243573 -244.145145)
			(xy 91.207321 -244.184216) (xy 91.16565 -244.217447) (xy 91.119492 -244.244096) (xy 91.069878 -244.263568)
			(xy 91.017916 -244.275428) (xy 90.964766 -244.279412) (xy 90.911616 -244.275428) (xy 90.859654 -244.263568)
			(xy 90.81004 -244.244096) (xy 90.763882 -244.217447) (xy 90.722211 -244.184216) (xy 90.685959 -244.145145)
			(xy 90.655935 -244.101108) (xy 90.632809 -244.053087) (xy 90.617099 -244.002157) (xy 90.609156 -243.949453)
			(xy 90.380576 -243.949453) (xy 90.372633 -244.002157) (xy 90.356923 -244.053087) (xy 90.333797 -244.101108)
			(xy 90.303773 -244.145145) (xy 90.267521 -244.184216) (xy 90.22585 -244.217447) (xy 90.179692 -244.244096)
			(xy 90.130078 -244.263568) (xy 90.078116 -244.275428) (xy 90.024966 -244.279412) (xy 89.971816 -244.275428)
			(xy 89.919854 -244.263568) (xy 89.87024 -244.244096) (xy 89.824082 -244.217447) (xy 89.782411 -244.184216)
			(xy 89.746159 -244.145145) (xy 89.716135 -244.101108) (xy 89.693009 -244.053087) (xy 89.677299 -244.002157)
			(xy 89.669356 -243.949453) (xy 89.43983 -243.949453) (xy 89.437844 -243.975956) (xy 89.425982 -244.027924)
			(xy 89.406507 -244.077544) (xy 89.379853 -244.123706) (xy 89.346616 -244.165381) (xy 89.307539 -244.201635)
			(xy 89.263494 -244.23166) (xy 89.215467 -244.254785) (xy 89.164529 -244.270493) (xy 89.111819 -244.278433)
			(xy 89.085166 -244.278912) (xy 89.060205 -244.278491) (xy 89.010771 -244.271522) (xy 88.962793 -244.257724)
			(xy 88.91721 -244.237368) (xy 88.874911 -244.210852) (xy 88.85555 -244.195092) (xy 88.844191 -244.186157)
			(xy 88.817786 -244.174444) (xy 88.789157 -244.170595) (xy 88.760595 -244.174917) (xy 88.734387 -244.187064)
			(xy 88.71263 -244.206066) (xy 88.697065 -244.2304) (xy 88.688937 -244.258119) (xy 88.688418 -244.272562)
			(xy 88.688418 -244.3861) (xy 88.723724 -244.39753) (xy 88.748731 -244.406053) (xy 88.796102 -244.429441)
			(xy 88.839498 -244.45957) (xy 88.877966 -244.495781) (xy 88.910662 -244.537279) (xy 88.936867 -244.583151)
			(xy 88.956007 -244.632392) (xy 88.967661 -244.683921) (xy 88.971574 -244.736606) (xy 88.969593 -244.763269)
			(xy 89.199202 -244.763269) (xy 89.199202 -244.709971) (xy 89.207145 -244.657267) (xy 89.222855 -244.606337)
			(xy 89.245981 -244.558316) (xy 89.276005 -244.514279) (xy 89.312257 -244.475208) (xy 89.353928 -244.441977)
			(xy 89.400086 -244.415328) (xy 89.4497 -244.395856) (xy 89.501662 -244.383996) (xy 89.554812 -244.380013)
			(xy 89.607962 -244.383996) (xy 89.659924 -244.395856) (xy 89.709538 -244.415328) (xy 89.755696 -244.441977)
			(xy 89.797367 -244.475208) (xy 89.833619 -244.514279) (xy 89.863643 -244.558316) (xy 89.886769 -244.606337)
			(xy 89.902479 -244.657267) (xy 89.910422 -244.709971) (xy 89.91092 -244.73662) (xy 89.910422 -244.763269)
			(xy 90.139256 -244.763269) (xy 90.139256 -244.709971) (xy 90.147199 -244.657267) (xy 90.162909 -244.606337)
			(xy 90.186035 -244.558316) (xy 90.216059 -244.514279) (xy 90.252311 -244.475208) (xy 90.293982 -244.441977)
			(xy 90.34014 -244.415328) (xy 90.389754 -244.395856) (xy 90.441716 -244.383996) (xy 90.494866 -244.380013)
			(xy 90.548016 -244.383996) (xy 90.599978 -244.395856) (xy 90.649592 -244.415328) (xy 90.69575 -244.441977)
			(xy 90.737421 -244.475208) (xy 90.773673 -244.514279) (xy 90.803697 -244.558316) (xy 90.826823 -244.606337)
			(xy 90.842533 -244.657267) (xy 90.850476 -244.709971) (xy 90.850974 -244.73662) (xy 90.850476 -244.763269)
			(xy 91.078802 -244.763269) (xy 91.078802 -244.709971) (xy 91.086745 -244.657267) (xy 91.102455 -244.606337)
			(xy 91.125581 -244.558316) (xy 91.155605 -244.514279) (xy 91.191857 -244.475208) (xy 91.233528 -244.441977)
			(xy 91.279686 -244.415328) (xy 91.3293 -244.395856) (xy 91.381262 -244.383996) (xy 91.434412 -244.380013)
			(xy 91.487562 -244.383996) (xy 91.539524 -244.395856) (xy 91.589138 -244.415328) (xy 91.635296 -244.441977)
			(xy 91.676967 -244.475208) (xy 91.713219 -244.514279) (xy 91.743243 -244.558316) (xy 91.766369 -244.606337)
			(xy 91.782079 -244.657267) (xy 91.790022 -244.709971) (xy 91.79052 -244.73662) (xy 91.790022 -244.763269)
			(xy 92.018856 -244.763269) (xy 92.018856 -244.709971) (xy 92.026799 -244.657267) (xy 92.042509 -244.606337)
			(xy 92.065635 -244.558316) (xy 92.095659 -244.514279) (xy 92.131911 -244.475208) (xy 92.173582 -244.441977)
			(xy 92.21974 -244.415328) (xy 92.269354 -244.395856) (xy 92.321316 -244.383996) (xy 92.374466 -244.380013)
			(xy 92.427616 -244.383996) (xy 92.479578 -244.395856) (xy 92.529192 -244.415328) (xy 92.57535 -244.441977)
			(xy 92.617021 -244.475208) (xy 92.653273 -244.514279) (xy 92.683297 -244.558316) (xy 92.706423 -244.606337)
			(xy 92.722133 -244.657267) (xy 92.730076 -244.709971) (xy 92.730574 -244.73662) (xy 92.730076 -244.763269)
			(xy 92.958402 -244.763269) (xy 92.958402 -244.709971) (xy 92.966345 -244.657267) (xy 92.982055 -244.606337)
			(xy 93.005181 -244.558316) (xy 93.035205 -244.514279) (xy 93.071457 -244.475208) (xy 93.113128 -244.441977)
			(xy 93.159286 -244.415328) (xy 93.2089 -244.395856) (xy 93.260862 -244.383996) (xy 93.314012 -244.380013)
			(xy 93.367162 -244.383996) (xy 93.419124 -244.395856) (xy 93.468738 -244.415328) (xy 93.514896 -244.441977)
			(xy 93.556567 -244.475208) (xy 93.592819 -244.514279) (xy 93.622843 -244.558316) (xy 93.645969 -244.606337)
			(xy 93.661679 -244.657267) (xy 93.669622 -244.709971) (xy 93.67012 -244.73662) (xy 93.669622 -244.763269)
			(xy 93.898202 -244.763269) (xy 93.898202 -244.709971) (xy 93.906145 -244.657267) (xy 93.921855 -244.606337)
			(xy 93.944981 -244.558316) (xy 93.975005 -244.514279) (xy 94.011257 -244.475208) (xy 94.052928 -244.441977)
			(xy 94.099086 -244.415328) (xy 94.1487 -244.395856) (xy 94.200662 -244.383996) (xy 94.253812 -244.380013)
			(xy 94.306962 -244.383996) (xy 94.358924 -244.395856) (xy 94.408538 -244.415328) (xy 94.454696 -244.441977)
			(xy 94.496367 -244.475208) (xy 94.532619 -244.514279) (xy 94.562643 -244.558316) (xy 94.585769 -244.606337)
			(xy 94.601479 -244.657267) (xy 94.609422 -244.709971) (xy 94.60992 -244.73662) (xy 94.609422 -244.763269)
			(xy 94.838002 -244.763269) (xy 94.838002 -244.709971) (xy 94.845945 -244.657267) (xy 94.861655 -244.606337)
			(xy 94.884781 -244.558316) (xy 94.914805 -244.514279) (xy 94.951057 -244.475208) (xy 94.992728 -244.441977)
			(xy 95.038886 -244.415328) (xy 95.0885 -244.395856) (xy 95.140462 -244.383996) (xy 95.193612 -244.380013)
			(xy 95.246762 -244.383996) (xy 95.298724 -244.395856) (xy 95.348338 -244.415328) (xy 95.394496 -244.441977)
			(xy 95.436167 -244.475208) (xy 95.472419 -244.514279) (xy 95.502443 -244.558316) (xy 95.525569 -244.606337)
			(xy 95.541279 -244.657267) (xy 95.549222 -244.709971) (xy 95.54972 -244.73662) (xy 95.549222 -244.763269)
			(xy 95.777802 -244.763269) (xy 95.777802 -244.709971) (xy 95.785745 -244.657267) (xy 95.801455 -244.606337)
			(xy 95.824581 -244.558316) (xy 95.854605 -244.514279) (xy 95.890857 -244.475208) (xy 95.932528 -244.441977)
			(xy 95.978686 -244.415328) (xy 96.0283 -244.395856) (xy 96.080262 -244.383996) (xy 96.133412 -244.380013)
			(xy 96.186562 -244.383996) (xy 96.238524 -244.395856) (xy 96.288138 -244.415328) (xy 96.334296 -244.441977)
			(xy 96.375967 -244.475208) (xy 96.412219 -244.514279) (xy 96.442243 -244.558316) (xy 96.465369 -244.606337)
			(xy 96.481079 -244.657267) (xy 96.489022 -244.709971) (xy 96.48952 -244.73662) (xy 96.489022 -244.763269)
			(xy 96.717856 -244.763269) (xy 96.717856 -244.709971) (xy 96.725799 -244.657267) (xy 96.741509 -244.606337)
			(xy 96.764635 -244.558316) (xy 96.794659 -244.514279) (xy 96.830911 -244.475208) (xy 96.872582 -244.441977)
			(xy 96.91874 -244.415328) (xy 96.968354 -244.395856) (xy 97.020316 -244.383996) (xy 97.073466 -244.380013)
			(xy 97.126616 -244.383996) (xy 97.178578 -244.395856) (xy 97.228192 -244.415328) (xy 97.27435 -244.441977)
			(xy 97.316021 -244.475208) (xy 97.352273 -244.514279) (xy 97.382297 -244.558316) (xy 97.405423 -244.606337)
			(xy 97.421133 -244.657267) (xy 97.429076 -244.709971) (xy 97.429574 -244.73662) (xy 97.429076 -244.763269)
			(xy 97.657402 -244.763269) (xy 97.657402 -244.709971) (xy 97.665345 -244.657267) (xy 97.681055 -244.606337)
			(xy 97.704181 -244.558316) (xy 97.734205 -244.514279) (xy 97.770457 -244.475208) (xy 97.812128 -244.441977)
			(xy 97.858286 -244.415328) (xy 97.9079 -244.395856) (xy 97.959862 -244.383996) (xy 98.013012 -244.380013)
			(xy 98.066162 -244.383996) (xy 98.118124 -244.395856) (xy 98.167738 -244.415328) (xy 98.213896 -244.441977)
			(xy 98.255567 -244.475208) (xy 98.291819 -244.514279) (xy 98.321843 -244.558316) (xy 98.344969 -244.606337)
			(xy 98.360679 -244.657267) (xy 98.368622 -244.709971) (xy 98.36912 -244.73662) (xy 98.368622 -244.763269)
			(xy 98.597202 -244.763269) (xy 98.597202 -244.709971) (xy 98.605145 -244.657267) (xy 98.620855 -244.606337)
			(xy 98.643981 -244.558316) (xy 98.674005 -244.514279) (xy 98.710257 -244.475208) (xy 98.751928 -244.441977)
			(xy 98.798086 -244.415328) (xy 98.8477 -244.395856) (xy 98.899662 -244.383996) (xy 98.952812 -244.380013)
			(xy 99.005962 -244.383996) (xy 99.057924 -244.395856) (xy 99.107538 -244.415328) (xy 99.153696 -244.441977)
			(xy 99.195367 -244.475208) (xy 99.231619 -244.514279) (xy 99.261643 -244.558316) (xy 99.284769 -244.606337)
			(xy 99.300479 -244.657267) (xy 99.308422 -244.709971) (xy 99.30892 -244.73662) (xy 99.308422 -244.763269)
			(xy 99.300479 -244.815973) (xy 99.284769 -244.866903) (xy 99.261643 -244.914924) (xy 99.231619 -244.958961)
			(xy 99.195367 -244.998032) (xy 99.153696 -245.031263) (xy 99.107538 -245.057912) (xy 99.057924 -245.077384)
			(xy 99.005962 -245.089244) (xy 98.952812 -245.093228) (xy 98.899662 -245.089244) (xy 98.8477 -245.077384)
			(xy 98.798086 -245.057912) (xy 98.751928 -245.031263) (xy 98.710257 -244.998032) (xy 98.674005 -244.958961)
			(xy 98.643981 -244.914924) (xy 98.620855 -244.866903) (xy 98.605145 -244.815973) (xy 98.597202 -244.763269)
			(xy 98.368622 -244.763269) (xy 98.360679 -244.815973) (xy 98.344969 -244.866903) (xy 98.321843 -244.914924)
			(xy 98.291819 -244.958961) (xy 98.255567 -244.998032) (xy 98.213896 -245.031263) (xy 98.167738 -245.057912)
			(xy 98.118124 -245.077384) (xy 98.066162 -245.089244) (xy 98.013012 -245.093228) (xy 97.959862 -245.089244)
			(xy 97.9079 -245.077384) (xy 97.858286 -245.057912) (xy 97.812128 -245.031263) (xy 97.770457 -244.998032)
			(xy 97.734205 -244.958961) (xy 97.704181 -244.914924) (xy 97.681055 -244.866903) (xy 97.665345 -244.815973)
			(xy 97.657402 -244.763269) (xy 97.429076 -244.763269) (xy 97.421133 -244.815973) (xy 97.405423 -244.866903)
			(xy 97.382297 -244.914924) (xy 97.352273 -244.958961) (xy 97.316021 -244.998032) (xy 97.27435 -245.031263)
			(xy 97.228192 -245.057912) (xy 97.178578 -245.077384) (xy 97.126616 -245.089244) (xy 97.073466 -245.093228)
			(xy 97.020316 -245.089244) (xy 96.968354 -245.077384) (xy 96.91874 -245.057912) (xy 96.872582 -245.031263)
			(xy 96.830911 -244.998032) (xy 96.794659 -244.958961) (xy 96.764635 -244.914924) (xy 96.741509 -244.866903)
			(xy 96.725799 -244.815973) (xy 96.717856 -244.763269) (xy 96.489022 -244.763269) (xy 96.481079 -244.815973)
			(xy 96.465369 -244.866903) (xy 96.442243 -244.914924) (xy 96.412219 -244.958961) (xy 96.375967 -244.998032)
			(xy 96.334296 -245.031263) (xy 96.288138 -245.057912) (xy 96.238524 -245.077384) (xy 96.186562 -245.089244)
			(xy 96.133412 -245.093228) (xy 96.080262 -245.089244) (xy 96.0283 -245.077384) (xy 95.978686 -245.057912)
			(xy 95.932528 -245.031263) (xy 95.890857 -244.998032) (xy 95.854605 -244.958961) (xy 95.824581 -244.914924)
			(xy 95.801455 -244.866903) (xy 95.785745 -244.815973) (xy 95.777802 -244.763269) (xy 95.549222 -244.763269)
			(xy 95.541279 -244.815973) (xy 95.525569 -244.866903) (xy 95.502443 -244.914924) (xy 95.472419 -244.958961)
			(xy 95.436167 -244.998032) (xy 95.394496 -245.031263) (xy 95.348338 -245.057912) (xy 95.298724 -245.077384)
			(xy 95.246762 -245.089244) (xy 95.193612 -245.093228) (xy 95.140462 -245.089244) (xy 95.0885 -245.077384)
			(xy 95.038886 -245.057912) (xy 94.992728 -245.031263) (xy 94.951057 -244.998032) (xy 94.914805 -244.958961)
			(xy 94.884781 -244.914924) (xy 94.861655 -244.866903) (xy 94.845945 -244.815973) (xy 94.838002 -244.763269)
			(xy 94.609422 -244.763269) (xy 94.601479 -244.815973) (xy 94.585769 -244.866903) (xy 94.562643 -244.914924)
			(xy 94.532619 -244.958961) (xy 94.496367 -244.998032) (xy 94.454696 -245.031263) (xy 94.408538 -245.057912)
			(xy 94.358924 -245.077384) (xy 94.306962 -245.089244) (xy 94.253812 -245.093228) (xy 94.200662 -245.089244)
			(xy 94.1487 -245.077384) (xy 94.099086 -245.057912) (xy 94.052928 -245.031263) (xy 94.011257 -244.998032)
			(xy 93.975005 -244.958961) (xy 93.944981 -244.914924) (xy 93.921855 -244.866903) (xy 93.906145 -244.815973)
			(xy 93.898202 -244.763269) (xy 93.669622 -244.763269) (xy 93.661679 -244.815973) (xy 93.645969 -244.866903)
			(xy 93.622843 -244.914924) (xy 93.592819 -244.958961) (xy 93.556567 -244.998032) (xy 93.514896 -245.031263)
			(xy 93.468738 -245.057912) (xy 93.419124 -245.077384) (xy 93.367162 -245.089244) (xy 93.314012 -245.093228)
			(xy 93.260862 -245.089244) (xy 93.2089 -245.077384) (xy 93.159286 -245.057912) (xy 93.113128 -245.031263)
			(xy 93.071457 -244.998032) (xy 93.035205 -244.958961) (xy 93.005181 -244.914924) (xy 92.982055 -244.866903)
			(xy 92.966345 -244.815973) (xy 92.958402 -244.763269) (xy 92.730076 -244.763269) (xy 92.722133 -244.815973)
			(xy 92.706423 -244.866903) (xy 92.683297 -244.914924) (xy 92.653273 -244.958961) (xy 92.617021 -244.998032)
			(xy 92.57535 -245.031263) (xy 92.529192 -245.057912) (xy 92.479578 -245.077384) (xy 92.427616 -245.089244)
			(xy 92.374466 -245.093228) (xy 92.321316 -245.089244) (xy 92.269354 -245.077384) (xy 92.21974 -245.057912)
			(xy 92.173582 -245.031263) (xy 92.131911 -244.998032) (xy 92.095659 -244.958961) (xy 92.065635 -244.914924)
			(xy 92.042509 -244.866903) (xy 92.026799 -244.815973) (xy 92.018856 -244.763269) (xy 91.790022 -244.763269)
			(xy 91.782079 -244.815973) (xy 91.766369 -244.866903) (xy 91.743243 -244.914924) (xy 91.713219 -244.958961)
			(xy 91.676967 -244.998032) (xy 91.635296 -245.031263) (xy 91.589138 -245.057912) (xy 91.539524 -245.077384)
			(xy 91.487562 -245.089244) (xy 91.434412 -245.093228) (xy 91.381262 -245.089244) (xy 91.3293 -245.077384)
			(xy 91.279686 -245.057912) (xy 91.233528 -245.031263) (xy 91.191857 -244.998032) (xy 91.155605 -244.958961)
			(xy 91.125581 -244.914924) (xy 91.102455 -244.866903) (xy 91.086745 -244.815973) (xy 91.078802 -244.763269)
			(xy 90.850476 -244.763269) (xy 90.842533 -244.815973) (xy 90.826823 -244.866903) (xy 90.803697 -244.914924)
			(xy 90.773673 -244.958961) (xy 90.737421 -244.998032) (xy 90.69575 -245.031263) (xy 90.649592 -245.057912)
			(xy 90.599978 -245.077384) (xy 90.548016 -245.089244) (xy 90.494866 -245.093228) (xy 90.441716 -245.089244)
			(xy 90.389754 -245.077384) (xy 90.34014 -245.057912) (xy 90.293982 -245.031263) (xy 90.252311 -244.998032)
			(xy 90.216059 -244.958961) (xy 90.186035 -244.914924) (xy 90.162909 -244.866903) (xy 90.147199 -244.815973)
			(xy 90.139256 -244.763269) (xy 89.910422 -244.763269) (xy 89.902479 -244.815973) (xy 89.886769 -244.866903)
			(xy 89.863643 -244.914924) (xy 89.833619 -244.958961) (xy 89.797367 -244.998032) (xy 89.755696 -245.031263)
			(xy 89.709538 -245.057912) (xy 89.659924 -245.077384) (xy 89.607962 -245.089244) (xy 89.554812 -245.093228)
			(xy 89.501662 -245.089244) (xy 89.4497 -245.077384) (xy 89.400086 -245.057912) (xy 89.353928 -245.031263)
			(xy 89.312257 -244.998032) (xy 89.276005 -244.958961) (xy 89.245981 -244.914924) (xy 89.222855 -244.866903)
			(xy 89.207145 -244.815973) (xy 89.199202 -244.763269) (xy 88.969593 -244.763269) (xy 88.967659 -244.789291)
			(xy 88.956003 -244.840819) (xy 88.936862 -244.89006) (xy 88.910655 -244.935932) (xy 88.877958 -244.977428)
			(xy 88.839489 -245.013637) (xy 88.796092 -245.043766) (xy 88.748719 -245.067151) (xy 88.723724 -245.07571)
			(xy 88.688418 -245.08714) (xy 88.688418 -245.200932) (xy 88.688916 -245.215387) (xy 88.697007 -245.243139)
			(xy 88.71256 -245.267508) (xy 88.734324 -245.286534) (xy 88.760552 -245.298691) (xy 88.789138 -245.303001)
			(xy 88.817784 -245.299119) (xy 88.844191 -245.287356) (xy 88.85555 -245.278402) (xy 88.87491 -245.262641)
			(xy 88.917207 -245.236123) (xy 88.962791 -245.215768) (xy 89.01077 -245.201976) (xy 89.060205 -245.195017)
			(xy 89.085166 -245.194582) (xy 89.11182 -245.195053) (xy 89.164532 -245.202993) (xy 89.215472 -245.218702)
			(xy 89.263501 -245.241828) (xy 89.307547 -245.271854) (xy 89.346626 -245.30811) (xy 89.379864 -245.349786)
			(xy 89.406519 -245.39595) (xy 89.425995 -245.445572) (xy 89.437858 -245.497542) (xy 89.441842 -245.5507)
			(xy 89.439846 -245.577339) (xy 89.669356 -245.577339) (xy 89.669356 -245.524041) (xy 89.677299 -245.471337)
			(xy 89.693009 -245.420407) (xy 89.716135 -245.372386) (xy 89.746159 -245.328349) (xy 89.782411 -245.289278)
			(xy 89.824082 -245.256047) (xy 89.87024 -245.229398) (xy 89.919854 -245.209926) (xy 89.971816 -245.198066)
			(xy 90.024966 -245.194083) (xy 90.078116 -245.198066) (xy 90.130078 -245.209926) (xy 90.179692 -245.229398)
			(xy 90.22585 -245.256047) (xy 90.267521 -245.289278) (xy 90.303773 -245.328349) (xy 90.333797 -245.372386)
			(xy 90.356923 -245.420407) (xy 90.372633 -245.471337) (xy 90.380576 -245.524041) (xy 90.381074 -245.55069)
			(xy 90.380576 -245.577339) (xy 90.608902 -245.577339) (xy 90.608902 -245.524041) (xy 90.616845 -245.471337)
			(xy 90.632555 -245.420407) (xy 90.655681 -245.372386) (xy 90.685705 -245.328349) (xy 90.721957 -245.289278)
			(xy 90.763628 -245.256047) (xy 90.809786 -245.229398) (xy 90.8594 -245.209926) (xy 90.911362 -245.198066)
			(xy 90.964512 -245.194083) (xy 91.017662 -245.198066) (xy 91.069624 -245.209926) (xy 91.119238 -245.229398)
			(xy 91.165396 -245.256047) (xy 91.207067 -245.289278) (xy 91.243319 -245.328349) (xy 91.273343 -245.372386)
			(xy 91.296469 -245.420407) (xy 91.312179 -245.471337) (xy 91.320122 -245.524041) (xy 91.32062 -245.55069)
			(xy 91.320122 -245.577339) (xy 91.548956 -245.577339) (xy 91.548956 -245.524041) (xy 91.556899 -245.471337)
			(xy 91.572609 -245.420407) (xy 91.595735 -245.372386) (xy 91.625759 -245.328349) (xy 91.662011 -245.289278)
			(xy 91.703682 -245.256047) (xy 91.74984 -245.229398) (xy 91.799454 -245.209926) (xy 91.851416 -245.198066)
			(xy 91.904566 -245.194083) (xy 91.957716 -245.198066) (xy 92.009678 -245.209926) (xy 92.059292 -245.229398)
			(xy 92.10545 -245.256047) (xy 92.147121 -245.289278) (xy 92.183373 -245.328349) (xy 92.213397 -245.372386)
			(xy 92.236523 -245.420407) (xy 92.252233 -245.471337) (xy 92.260176 -245.524041) (xy 92.260674 -245.55069)
			(xy 92.260176 -245.577339) (xy 92.488502 -245.577339) (xy 92.488502 -245.524041) (xy 92.496445 -245.471337)
			(xy 92.512155 -245.420407) (xy 92.535281 -245.372386) (xy 92.565305 -245.328349) (xy 92.601557 -245.289278)
			(xy 92.643228 -245.256047) (xy 92.689386 -245.229398) (xy 92.739 -245.209926) (xy 92.790962 -245.198066)
			(xy 92.844112 -245.194083) (xy 92.897262 -245.198066) (xy 92.949224 -245.209926) (xy 92.998838 -245.229398)
			(xy 93.044996 -245.256047) (xy 93.086667 -245.289278) (xy 93.122919 -245.328349) (xy 93.152943 -245.372386)
			(xy 93.176069 -245.420407) (xy 93.191779 -245.471337) (xy 93.199722 -245.524041) (xy 93.20022 -245.55069)
			(xy 93.199722 -245.577339) (xy 93.428556 -245.577339) (xy 93.428556 -245.524041) (xy 93.436499 -245.471337)
			(xy 93.452209 -245.420407) (xy 93.475335 -245.372386) (xy 93.505359 -245.328349) (xy 93.541611 -245.289278)
			(xy 93.583282 -245.256047) (xy 93.62944 -245.229398) (xy 93.679054 -245.209926) (xy 93.731016 -245.198066)
			(xy 93.784166 -245.194083) (xy 93.837316 -245.198066) (xy 93.889278 -245.209926) (xy 93.938892 -245.229398)
			(xy 93.98505 -245.256047) (xy 94.026721 -245.289278) (xy 94.062973 -245.328349) (xy 94.092997 -245.372386)
			(xy 94.116123 -245.420407) (xy 94.131833 -245.471337) (xy 94.139776 -245.524041) (xy 94.140274 -245.55069)
			(xy 94.139776 -245.577339) (xy 94.368356 -245.577339) (xy 94.368356 -245.524041) (xy 94.376299 -245.471337)
			(xy 94.392009 -245.420407) (xy 94.415135 -245.372386) (xy 94.445159 -245.328349) (xy 94.481411 -245.289278)
			(xy 94.523082 -245.256047) (xy 94.56924 -245.229398) (xy 94.618854 -245.209926) (xy 94.670816 -245.198066)
			(xy 94.723966 -245.194083) (xy 94.777116 -245.198066) (xy 94.829078 -245.209926) (xy 94.878692 -245.229398)
			(xy 94.92485 -245.256047) (xy 94.966521 -245.289278) (xy 95.002773 -245.328349) (xy 95.032797 -245.372386)
			(xy 95.055923 -245.420407) (xy 95.071633 -245.471337) (xy 95.079576 -245.524041) (xy 95.080074 -245.55069)
			(xy 95.079576 -245.577339) (xy 95.308156 -245.577339) (xy 95.308156 -245.524041) (xy 95.316099 -245.471337)
			(xy 95.331809 -245.420407) (xy 95.354935 -245.372386) (xy 95.384959 -245.328349) (xy 95.421211 -245.289278)
			(xy 95.462882 -245.256047) (xy 95.50904 -245.229398) (xy 95.558654 -245.209926) (xy 95.610616 -245.198066)
			(xy 95.663766 -245.194083) (xy 95.716916 -245.198066) (xy 95.768878 -245.209926) (xy 95.818492 -245.229398)
			(xy 95.86465 -245.256047) (xy 95.906321 -245.289278) (xy 95.942573 -245.328349) (xy 95.972597 -245.372386)
			(xy 95.995723 -245.420407) (xy 96.011433 -245.471337) (xy 96.019376 -245.524041) (xy 96.019874 -245.55069)
			(xy 96.019376 -245.577339) (xy 96.247956 -245.577339) (xy 96.247956 -245.524041) (xy 96.255899 -245.471337)
			(xy 96.271609 -245.420407) (xy 96.294735 -245.372386) (xy 96.324759 -245.328349) (xy 96.361011 -245.289278)
			(xy 96.402682 -245.256047) (xy 96.44884 -245.229398) (xy 96.498454 -245.209926) (xy 96.550416 -245.198066)
			(xy 96.603566 -245.194083) (xy 96.656716 -245.198066) (xy 96.708678 -245.209926) (xy 96.758292 -245.229398)
			(xy 96.80445 -245.256047) (xy 96.846121 -245.289278) (xy 96.882373 -245.328349) (xy 96.912397 -245.372386)
			(xy 96.935523 -245.420407) (xy 96.951233 -245.471337) (xy 96.959176 -245.524041) (xy 96.959674 -245.55069)
			(xy 96.959176 -245.577339) (xy 97.187502 -245.577339) (xy 97.187502 -245.524041) (xy 97.195445 -245.471337)
			(xy 97.211155 -245.420407) (xy 97.234281 -245.372386) (xy 97.264305 -245.328349) (xy 97.300557 -245.289278)
			(xy 97.342228 -245.256047) (xy 97.388386 -245.229398) (xy 97.438 -245.209926) (xy 97.489962 -245.198066)
			(xy 97.543112 -245.194083) (xy 97.596262 -245.198066) (xy 97.648224 -245.209926) (xy 97.697838 -245.229398)
			(xy 97.743996 -245.256047) (xy 97.785667 -245.289278) (xy 97.821919 -245.328349) (xy 97.851943 -245.372386)
			(xy 97.875069 -245.420407) (xy 97.890779 -245.471337) (xy 97.898722 -245.524041) (xy 97.89922 -245.55069)
			(xy 97.898722 -245.577339) (xy 98.127556 -245.577339) (xy 98.127556 -245.524041) (xy 98.135499 -245.471337)
			(xy 98.151209 -245.420407) (xy 98.174335 -245.372386) (xy 98.204359 -245.328349) (xy 98.240611 -245.289278)
			(xy 98.282282 -245.256047) (xy 98.32844 -245.229398) (xy 98.378054 -245.209926) (xy 98.430016 -245.198066)
			(xy 98.483166 -245.194083) (xy 98.536316 -245.198066) (xy 98.588278 -245.209926) (xy 98.637892 -245.229398)
			(xy 98.68405 -245.256047) (xy 98.725721 -245.289278) (xy 98.761973 -245.328349) (xy 98.791997 -245.372386)
			(xy 98.815123 -245.420407) (xy 98.830833 -245.471337) (xy 98.838776 -245.524041) (xy 98.839274 -245.55069)
			(xy 98.838776 -245.577339) (xy 98.830833 -245.630043) (xy 98.815123 -245.680973) (xy 98.791997 -245.728994)
			(xy 98.761973 -245.773031) (xy 98.725721 -245.812102) (xy 98.68405 -245.845333) (xy 98.637892 -245.871982)
			(xy 98.588278 -245.891454) (xy 98.536316 -245.903314) (xy 98.483166 -245.907298) (xy 98.430016 -245.903314)
			(xy 98.378054 -245.891454) (xy 98.32844 -245.871982) (xy 98.282282 -245.845333) (xy 98.240611 -245.812102)
			(xy 98.204359 -245.773031) (xy 98.174335 -245.728994) (xy 98.151209 -245.680973) (xy 98.135499 -245.630043)
			(xy 98.127556 -245.577339) (xy 97.898722 -245.577339) (xy 97.890779 -245.630043) (xy 97.875069 -245.680973)
			(xy 97.851943 -245.728994) (xy 97.821919 -245.773031) (xy 97.785667 -245.812102) (xy 97.743996 -245.845333)
			(xy 97.697838 -245.871982) (xy 97.648224 -245.891454) (xy 97.596262 -245.903314) (xy 97.543112 -245.907298)
			(xy 97.489962 -245.903314) (xy 97.438 -245.891454) (xy 97.388386 -245.871982) (xy 97.342228 -245.845333)
			(xy 97.300557 -245.812102) (xy 97.264305 -245.773031) (xy 97.234281 -245.728994) (xy 97.211155 -245.680973)
			(xy 97.195445 -245.630043) (xy 97.187502 -245.577339) (xy 96.959176 -245.577339) (xy 96.951233 -245.630043)
			(xy 96.935523 -245.680973) (xy 96.912397 -245.728994) (xy 96.882373 -245.773031) (xy 96.846121 -245.812102)
			(xy 96.80445 -245.845333) (xy 96.758292 -245.871982) (xy 96.708678 -245.891454) (xy 96.656716 -245.903314)
			(xy 96.603566 -245.907298) (xy 96.550416 -245.903314) (xy 96.498454 -245.891454) (xy 96.44884 -245.871982)
			(xy 96.402682 -245.845333) (xy 96.361011 -245.812102) (xy 96.324759 -245.773031) (xy 96.294735 -245.728994)
			(xy 96.271609 -245.680973) (xy 96.255899 -245.630043) (xy 96.247956 -245.577339) (xy 96.019376 -245.577339)
			(xy 96.011433 -245.630043) (xy 95.995723 -245.680973) (xy 95.972597 -245.728994) (xy 95.942573 -245.773031)
			(xy 95.906321 -245.812102) (xy 95.86465 -245.845333) (xy 95.818492 -245.871982) (xy 95.768878 -245.891454)
			(xy 95.716916 -245.903314) (xy 95.663766 -245.907298) (xy 95.610616 -245.903314) (xy 95.558654 -245.891454)
			(xy 95.50904 -245.871982) (xy 95.462882 -245.845333) (xy 95.421211 -245.812102) (xy 95.384959 -245.773031)
			(xy 95.354935 -245.728994) (xy 95.331809 -245.680973) (xy 95.316099 -245.630043) (xy 95.308156 -245.577339)
			(xy 95.079576 -245.577339) (xy 95.071633 -245.630043) (xy 95.055923 -245.680973) (xy 95.032797 -245.728994)
			(xy 95.002773 -245.773031) (xy 94.966521 -245.812102) (xy 94.92485 -245.845333) (xy 94.878692 -245.871982)
			(xy 94.829078 -245.891454) (xy 94.777116 -245.903314) (xy 94.723966 -245.907298) (xy 94.670816 -245.903314)
			(xy 94.618854 -245.891454) (xy 94.56924 -245.871982) (xy 94.523082 -245.845333) (xy 94.481411 -245.812102)
			(xy 94.445159 -245.773031) (xy 94.415135 -245.728994) (xy 94.392009 -245.680973) (xy 94.376299 -245.630043)
			(xy 94.368356 -245.577339) (xy 94.139776 -245.577339) (xy 94.131833 -245.630043) (xy 94.116123 -245.680973)
			(xy 94.092997 -245.728994) (xy 94.062973 -245.773031) (xy 94.026721 -245.812102) (xy 93.98505 -245.845333)
			(xy 93.938892 -245.871982) (xy 93.889278 -245.891454) (xy 93.837316 -245.903314) (xy 93.784166 -245.907298)
			(xy 93.731016 -245.903314) (xy 93.679054 -245.891454) (xy 93.62944 -245.871982) (xy 93.583282 -245.845333)
			(xy 93.541611 -245.812102) (xy 93.505359 -245.773031) (xy 93.475335 -245.728994) (xy 93.452209 -245.680973)
			(xy 93.436499 -245.630043) (xy 93.428556 -245.577339) (xy 93.199722 -245.577339) (xy 93.191779 -245.630043)
			(xy 93.176069 -245.680973) (xy 93.152943 -245.728994) (xy 93.122919 -245.773031) (xy 93.086667 -245.812102)
			(xy 93.044996 -245.845333) (xy 92.998838 -245.871982) (xy 92.949224 -245.891454) (xy 92.897262 -245.903314)
			(xy 92.844112 -245.907298) (xy 92.790962 -245.903314) (xy 92.739 -245.891454) (xy 92.689386 -245.871982)
			(xy 92.643228 -245.845333) (xy 92.601557 -245.812102) (xy 92.565305 -245.773031) (xy 92.535281 -245.728994)
			(xy 92.512155 -245.680973) (xy 92.496445 -245.630043) (xy 92.488502 -245.577339) (xy 92.260176 -245.577339)
			(xy 92.252233 -245.630043) (xy 92.236523 -245.680973) (xy 92.213397 -245.728994) (xy 92.183373 -245.773031)
			(xy 92.147121 -245.812102) (xy 92.10545 -245.845333) (xy 92.059292 -245.871982) (xy 92.009678 -245.891454)
			(xy 91.957716 -245.903314) (xy 91.904566 -245.907298) (xy 91.851416 -245.903314) (xy 91.799454 -245.891454)
			(xy 91.74984 -245.871982) (xy 91.703682 -245.845333) (xy 91.662011 -245.812102) (xy 91.625759 -245.773031)
			(xy 91.595735 -245.728994) (xy 91.572609 -245.680973) (xy 91.556899 -245.630043) (xy 91.548956 -245.577339)
			(xy 91.320122 -245.577339) (xy 91.312179 -245.630043) (xy 91.296469 -245.680973) (xy 91.273343 -245.728994)
			(xy 91.243319 -245.773031) (xy 91.207067 -245.812102) (xy 91.165396 -245.845333) (xy 91.119238 -245.871982)
			(xy 91.069624 -245.891454) (xy 91.017662 -245.903314) (xy 90.964512 -245.907298) (xy 90.911362 -245.903314)
			(xy 90.8594 -245.891454) (xy 90.809786 -245.871982) (xy 90.763628 -245.845333) (xy 90.721957 -245.812102)
			(xy 90.685705 -245.773031) (xy 90.655681 -245.728994) (xy 90.632555 -245.680973) (xy 90.616845 -245.630043)
			(xy 90.608902 -245.577339) (xy 90.380576 -245.577339) (xy 90.372633 -245.630043) (xy 90.356923 -245.680973)
			(xy 90.333797 -245.728994) (xy 90.303773 -245.773031) (xy 90.267521 -245.812102) (xy 90.22585 -245.845333)
			(xy 90.179692 -245.871982) (xy 90.130078 -245.891454) (xy 90.078116 -245.903314) (xy 90.024966 -245.907298)
			(xy 89.971816 -245.903314) (xy 89.919854 -245.891454) (xy 89.87024 -245.871982) (xy 89.824082 -245.845333)
			(xy 89.782411 -245.812102) (xy 89.746159 -245.773031) (xy 89.716135 -245.728994) (xy 89.693009 -245.680973)
			(xy 89.677299 -245.630043) (xy 89.669356 -245.577339) (xy 89.439846 -245.577339) (xy 89.437858 -245.603858)
			(xy 89.425995 -245.655828) (xy 89.406519 -245.70545) (xy 89.379864 -245.751614) (xy 89.346626 -245.79329)
			(xy 89.307547 -245.829546) (xy 89.263501 -245.859572) (xy 89.215472 -245.882698) (xy 89.164532 -245.898407)
			(xy 89.11182 -245.906347) (xy 89.085166 -245.906798) (xy 89.060205 -245.906377) (xy 89.010771 -245.899408)
			(xy 88.962794 -245.88561) (xy 88.917211 -245.865253) (xy 88.874913 -245.838736) (xy 88.85555 -245.822978)
			(xy 88.84419 -245.814044) (xy 88.817784 -245.802333) (xy 88.789155 -245.798484) (xy 88.760593 -245.802806)
			(xy 88.734385 -245.814953) (xy 88.712626 -245.833954) (xy 88.697059 -245.858287) (xy 88.688929 -245.886005)
			(xy 88.688418 -245.900448) (xy 88.688418 -246.013986) (xy 88.723724 -246.025416) (xy 88.748732 -246.033939)
			(xy 88.796105 -246.057327) (xy 88.839503 -246.087457) (xy 88.877973 -246.123669) (xy 88.910671 -246.165168)
			(xy 88.936877 -246.211042) (xy 88.956018 -246.260284) (xy 88.967674 -246.311815) (xy 88.971587 -246.364502)
			(xy 88.969607 -246.391155) (xy 89.199202 -246.391155) (xy 89.199202 -246.337857) (xy 89.207145 -246.285153)
			(xy 89.222855 -246.234223) (xy 89.245981 -246.186202) (xy 89.276005 -246.142165) (xy 89.312257 -246.103094)
			(xy 89.353928 -246.069863) (xy 89.400086 -246.043214) (xy 89.4497 -246.023742) (xy 89.501662 -246.011882)
			(xy 89.554812 -246.007899) (xy 89.607962 -246.011882) (xy 89.659924 -246.023742) (xy 89.709538 -246.043214)
			(xy 89.755696 -246.069863) (xy 89.797367 -246.103094) (xy 89.833619 -246.142165) (xy 89.863643 -246.186202)
			(xy 89.886769 -246.234223) (xy 89.902479 -246.285153) (xy 89.910422 -246.337857) (xy 89.91092 -246.364506)
			(xy 89.910422 -246.391155) (xy 90.139002 -246.391155) (xy 90.139002 -246.337857) (xy 90.146945 -246.285153)
			(xy 90.162655 -246.234223) (xy 90.185781 -246.186202) (xy 90.215805 -246.142165) (xy 90.252057 -246.103094)
			(xy 90.293728 -246.069863) (xy 90.339886 -246.043214) (xy 90.3895 -246.023742) (xy 90.441462 -246.011882)
			(xy 90.494612 -246.007899) (xy 90.547762 -246.011882) (xy 90.599724 -246.023742) (xy 90.649338 -246.043214)
			(xy 90.695496 -246.069863) (xy 90.737167 -246.103094) (xy 90.773419 -246.142165) (xy 90.803443 -246.186202)
			(xy 90.826569 -246.234223) (xy 90.842279 -246.285153) (xy 90.850222 -246.337857) (xy 90.85072 -246.364506)
			(xy 90.850222 -246.391155) (xy 91.078802 -246.391155) (xy 91.078802 -246.337857) (xy 91.086745 -246.285153)
			(xy 91.102455 -246.234223) (xy 91.125581 -246.186202) (xy 91.155605 -246.142165) (xy 91.191857 -246.103094)
			(xy 91.233528 -246.069863) (xy 91.279686 -246.043214) (xy 91.3293 -246.023742) (xy 91.381262 -246.011882)
			(xy 91.434412 -246.007899) (xy 91.487562 -246.011882) (xy 91.539524 -246.023742) (xy 91.589138 -246.043214)
			(xy 91.635296 -246.069863) (xy 91.676967 -246.103094) (xy 91.713219 -246.142165) (xy 91.743243 -246.186202)
			(xy 91.766369 -246.234223) (xy 91.782079 -246.285153) (xy 91.790022 -246.337857) (xy 91.79052 -246.364506)
			(xy 91.790022 -246.391155) (xy 92.018602 -246.391155) (xy 92.018602 -246.337857) (xy 92.026545 -246.285153)
			(xy 92.042255 -246.234223) (xy 92.065381 -246.186202) (xy 92.095405 -246.142165) (xy 92.131657 -246.103094)
			(xy 92.173328 -246.069863) (xy 92.219486 -246.043214) (xy 92.2691 -246.023742) (xy 92.321062 -246.011882)
			(xy 92.374212 -246.007899) (xy 92.427362 -246.011882) (xy 92.479324 -246.023742) (xy 92.528938 -246.043214)
			(xy 92.575096 -246.069863) (xy 92.616767 -246.103094) (xy 92.653019 -246.142165) (xy 92.683043 -246.186202)
			(xy 92.706169 -246.234223) (xy 92.721879 -246.285153) (xy 92.729822 -246.337857) (xy 92.73032 -246.364506)
			(xy 92.729822 -246.391155) (xy 92.958402 -246.391155) (xy 92.958402 -246.337857) (xy 92.966345 -246.285153)
			(xy 92.982055 -246.234223) (xy 93.005181 -246.186202) (xy 93.035205 -246.142165) (xy 93.071457 -246.103094)
			(xy 93.113128 -246.069863) (xy 93.159286 -246.043214) (xy 93.2089 -246.023742) (xy 93.260862 -246.011882)
			(xy 93.314012 -246.007899) (xy 93.367162 -246.011882) (xy 93.419124 -246.023742) (xy 93.468738 -246.043214)
			(xy 93.514896 -246.069863) (xy 93.556567 -246.103094) (xy 93.592819 -246.142165) (xy 93.622843 -246.186202)
			(xy 93.645969 -246.234223) (xy 93.661679 -246.285153) (xy 93.669622 -246.337857) (xy 93.67012 -246.364506)
			(xy 93.669622 -246.391155) (xy 93.898456 -246.391155) (xy 93.898456 -246.337857) (xy 93.906399 -246.285153)
			(xy 93.922109 -246.234223) (xy 93.945235 -246.186202) (xy 93.975259 -246.142165) (xy 94.011511 -246.103094)
			(xy 94.053182 -246.069863) (xy 94.09934 -246.043214) (xy 94.148954 -246.023742) (xy 94.200916 -246.011882)
			(xy 94.254066 -246.007899) (xy 94.307216 -246.011882) (xy 94.359178 -246.023742) (xy 94.408792 -246.043214)
			(xy 94.45495 -246.069863) (xy 94.496621 -246.103094) (xy 94.532873 -246.142165) (xy 94.562897 -246.186202)
			(xy 94.586023 -246.234223) (xy 94.601733 -246.285153) (xy 94.609676 -246.337857) (xy 94.610174 -246.364506)
			(xy 94.609676 -246.391155) (xy 94.838002 -246.391155) (xy 94.838002 -246.337857) (xy 94.845945 -246.285153)
			(xy 94.861655 -246.234223) (xy 94.884781 -246.186202) (xy 94.914805 -246.142165) (xy 94.951057 -246.103094)
			(xy 94.992728 -246.069863) (xy 95.038886 -246.043214) (xy 95.0885 -246.023742) (xy 95.140462 -246.011882)
			(xy 95.193612 -246.007899) (xy 95.246762 -246.011882) (xy 95.298724 -246.023742) (xy 95.348338 -246.043214)
			(xy 95.394496 -246.069863) (xy 95.436167 -246.103094) (xy 95.472419 -246.142165) (xy 95.502443 -246.186202)
			(xy 95.525569 -246.234223) (xy 95.541279 -246.285153) (xy 95.549222 -246.337857) (xy 95.54972 -246.364506)
			(xy 95.549222 -246.391155) (xy 95.777802 -246.391155) (xy 95.777802 -246.337857) (xy 95.785745 -246.285153)
			(xy 95.801455 -246.234223) (xy 95.824581 -246.186202) (xy 95.854605 -246.142165) (xy 95.890857 -246.103094)
			(xy 95.932528 -246.069863) (xy 95.978686 -246.043214) (xy 96.0283 -246.023742) (xy 96.080262 -246.011882)
			(xy 96.133412 -246.007899) (xy 96.186562 -246.011882) (xy 96.238524 -246.023742) (xy 96.288138 -246.043214)
			(xy 96.334296 -246.069863) (xy 96.375967 -246.103094) (xy 96.412219 -246.142165) (xy 96.442243 -246.186202)
			(xy 96.465369 -246.234223) (xy 96.481079 -246.285153) (xy 96.489022 -246.337857) (xy 96.48952 -246.364506)
			(xy 96.489022 -246.391155) (xy 96.717602 -246.391155) (xy 96.717602 -246.337857) (xy 96.725545 -246.285153)
			(xy 96.741255 -246.234223) (xy 96.764381 -246.186202) (xy 96.794405 -246.142165) (xy 96.830657 -246.103094)
			(xy 96.872328 -246.069863) (xy 96.918486 -246.043214) (xy 96.9681 -246.023742) (xy 97.020062 -246.011882)
			(xy 97.073212 -246.007899) (xy 97.126362 -246.011882) (xy 97.178324 -246.023742) (xy 97.227938 -246.043214)
			(xy 97.274096 -246.069863) (xy 97.315767 -246.103094) (xy 97.352019 -246.142165) (xy 97.382043 -246.186202)
			(xy 97.405169 -246.234223) (xy 97.420879 -246.285153) (xy 97.428822 -246.337857) (xy 97.42932 -246.364506)
			(xy 97.428822 -246.391155) (xy 97.657402 -246.391155) (xy 97.657402 -246.337857) (xy 97.665345 -246.285153)
			(xy 97.681055 -246.234223) (xy 97.704181 -246.186202) (xy 97.734205 -246.142165) (xy 97.770457 -246.103094)
			(xy 97.812128 -246.069863) (xy 97.858286 -246.043214) (xy 97.9079 -246.023742) (xy 97.959862 -246.011882)
			(xy 98.013012 -246.007899) (xy 98.066162 -246.011882) (xy 98.118124 -246.023742) (xy 98.167738 -246.043214)
			(xy 98.213896 -246.069863) (xy 98.255567 -246.103094) (xy 98.291819 -246.142165) (xy 98.321843 -246.186202)
			(xy 98.344969 -246.234223) (xy 98.360679 -246.285153) (xy 98.368622 -246.337857) (xy 98.36912 -246.364506)
			(xy 98.368622 -246.391155) (xy 98.597202 -246.391155) (xy 98.597202 -246.337857) (xy 98.605145 -246.285153)
			(xy 98.620855 -246.234223) (xy 98.643981 -246.186202) (xy 98.674005 -246.142165) (xy 98.710257 -246.103094)
			(xy 98.751928 -246.069863) (xy 98.798086 -246.043214) (xy 98.8477 -246.023742) (xy 98.899662 -246.011882)
			(xy 98.952812 -246.007899) (xy 99.005962 -246.011882) (xy 99.057924 -246.023742) (xy 99.107538 -246.043214)
			(xy 99.153696 -246.069863) (xy 99.195367 -246.103094) (xy 99.231619 -246.142165) (xy 99.261643 -246.186202)
			(xy 99.284769 -246.234223) (xy 99.300479 -246.285153) (xy 99.308422 -246.337857) (xy 99.30892 -246.364506)
			(xy 99.308422 -246.391155) (xy 99.300479 -246.443859) (xy 99.284769 -246.494789) (xy 99.261643 -246.54281)
			(xy 99.231619 -246.586847) (xy 99.195367 -246.625918) (xy 99.153696 -246.659149) (xy 99.107538 -246.685798)
			(xy 99.057924 -246.70527) (xy 99.005962 -246.71713) (xy 98.952812 -246.721114) (xy 98.899662 -246.71713)
			(xy 98.8477 -246.70527) (xy 98.798086 -246.685798) (xy 98.751928 -246.659149) (xy 98.710257 -246.625918)
			(xy 98.674005 -246.586847) (xy 98.643981 -246.54281) (xy 98.620855 -246.494789) (xy 98.605145 -246.443859)
			(xy 98.597202 -246.391155) (xy 98.368622 -246.391155) (xy 98.360679 -246.443859) (xy 98.344969 -246.494789)
			(xy 98.321843 -246.54281) (xy 98.291819 -246.586847) (xy 98.255567 -246.625918) (xy 98.213896 -246.659149)
			(xy 98.167738 -246.685798) (xy 98.118124 -246.70527) (xy 98.066162 -246.71713) (xy 98.013012 -246.721114)
			(xy 97.959862 -246.71713) (xy 97.9079 -246.70527) (xy 97.858286 -246.685798) (xy 97.812128 -246.659149)
			(xy 97.770457 -246.625918) (xy 97.734205 -246.586847) (xy 97.704181 -246.54281) (xy 97.681055 -246.494789)
			(xy 97.665345 -246.443859) (xy 97.657402 -246.391155) (xy 97.428822 -246.391155) (xy 97.420879 -246.443859)
			(xy 97.405169 -246.494789) (xy 97.382043 -246.54281) (xy 97.352019 -246.586847) (xy 97.315767 -246.625918)
			(xy 97.274096 -246.659149) (xy 97.227938 -246.685798) (xy 97.178324 -246.70527) (xy 97.126362 -246.71713)
			(xy 97.073212 -246.721114) (xy 97.020062 -246.71713) (xy 96.9681 -246.70527) (xy 96.918486 -246.685798)
			(xy 96.872328 -246.659149) (xy 96.830657 -246.625918) (xy 96.794405 -246.586847) (xy 96.764381 -246.54281)
			(xy 96.741255 -246.494789) (xy 96.725545 -246.443859) (xy 96.717602 -246.391155) (xy 96.489022 -246.391155)
			(xy 96.481079 -246.443859) (xy 96.465369 -246.494789) (xy 96.442243 -246.54281) (xy 96.412219 -246.586847)
			(xy 96.375967 -246.625918) (xy 96.334296 -246.659149) (xy 96.288138 -246.685798) (xy 96.238524 -246.70527)
			(xy 96.186562 -246.71713) (xy 96.133412 -246.721114) (xy 96.080262 -246.71713) (xy 96.0283 -246.70527)
			(xy 95.978686 -246.685798) (xy 95.932528 -246.659149) (xy 95.890857 -246.625918) (xy 95.854605 -246.586847)
			(xy 95.824581 -246.54281) (xy 95.801455 -246.494789) (xy 95.785745 -246.443859) (xy 95.777802 -246.391155)
			(xy 95.549222 -246.391155) (xy 95.541279 -246.443859) (xy 95.525569 -246.494789) (xy 95.502443 -246.54281)
			(xy 95.472419 -246.586847) (xy 95.436167 -246.625918) (xy 95.394496 -246.659149) (xy 95.348338 -246.685798)
			(xy 95.298724 -246.70527) (xy 95.246762 -246.71713) (xy 95.193612 -246.721114) (xy 95.140462 -246.71713)
			(xy 95.0885 -246.70527) (xy 95.038886 -246.685798) (xy 94.992728 -246.659149) (xy 94.951057 -246.625918)
			(xy 94.914805 -246.586847) (xy 94.884781 -246.54281) (xy 94.861655 -246.494789) (xy 94.845945 -246.443859)
			(xy 94.838002 -246.391155) (xy 94.609676 -246.391155) (xy 94.601733 -246.443859) (xy 94.586023 -246.494789)
			(xy 94.562897 -246.54281) (xy 94.532873 -246.586847) (xy 94.496621 -246.625918) (xy 94.45495 -246.659149)
			(xy 94.408792 -246.685798) (xy 94.359178 -246.70527) (xy 94.307216 -246.71713) (xy 94.254066 -246.721114)
			(xy 94.200916 -246.71713) (xy 94.148954 -246.70527) (xy 94.09934 -246.685798) (xy 94.053182 -246.659149)
			(xy 94.011511 -246.625918) (xy 93.975259 -246.586847) (xy 93.945235 -246.54281) (xy 93.922109 -246.494789)
			(xy 93.906399 -246.443859) (xy 93.898456 -246.391155) (xy 93.669622 -246.391155) (xy 93.661679 -246.443859)
			(xy 93.645969 -246.494789) (xy 93.622843 -246.54281) (xy 93.592819 -246.586847) (xy 93.556567 -246.625918)
			(xy 93.514896 -246.659149) (xy 93.468738 -246.685798) (xy 93.419124 -246.70527) (xy 93.367162 -246.71713)
			(xy 93.314012 -246.721114) (xy 93.260862 -246.71713) (xy 93.2089 -246.70527) (xy 93.159286 -246.685798)
			(xy 93.113128 -246.659149) (xy 93.071457 -246.625918) (xy 93.035205 -246.586847) (xy 93.005181 -246.54281)
			(xy 92.982055 -246.494789) (xy 92.966345 -246.443859) (xy 92.958402 -246.391155) (xy 92.729822 -246.391155)
			(xy 92.721879 -246.443859) (xy 92.706169 -246.494789) (xy 92.683043 -246.54281) (xy 92.653019 -246.586847)
			(xy 92.616767 -246.625918) (xy 92.575096 -246.659149) (xy 92.528938 -246.685798) (xy 92.479324 -246.70527)
			(xy 92.427362 -246.71713) (xy 92.374212 -246.721114) (xy 92.321062 -246.71713) (xy 92.2691 -246.70527)
			(xy 92.219486 -246.685798) (xy 92.173328 -246.659149) (xy 92.131657 -246.625918) (xy 92.095405 -246.586847)
			(xy 92.065381 -246.54281) (xy 92.042255 -246.494789) (xy 92.026545 -246.443859) (xy 92.018602 -246.391155)
			(xy 91.790022 -246.391155) (xy 91.782079 -246.443859) (xy 91.766369 -246.494789) (xy 91.743243 -246.54281)
			(xy 91.713219 -246.586847) (xy 91.676967 -246.625918) (xy 91.635296 -246.659149) (xy 91.589138 -246.685798)
			(xy 91.539524 -246.70527) (xy 91.487562 -246.71713) (xy 91.434412 -246.721114) (xy 91.381262 -246.71713)
			(xy 91.3293 -246.70527) (xy 91.279686 -246.685798) (xy 91.233528 -246.659149) (xy 91.191857 -246.625918)
			(xy 91.155605 -246.586847) (xy 91.125581 -246.54281) (xy 91.102455 -246.494789) (xy 91.086745 -246.443859)
			(xy 91.078802 -246.391155) (xy 90.850222 -246.391155) (xy 90.842279 -246.443859) (xy 90.826569 -246.494789)
			(xy 90.803443 -246.54281) (xy 90.773419 -246.586847) (xy 90.737167 -246.625918) (xy 90.695496 -246.659149)
			(xy 90.649338 -246.685798) (xy 90.599724 -246.70527) (xy 90.547762 -246.71713) (xy 90.494612 -246.721114)
			(xy 90.441462 -246.71713) (xy 90.3895 -246.70527) (xy 90.339886 -246.685798) (xy 90.293728 -246.659149)
			(xy 90.252057 -246.625918) (xy 90.215805 -246.586847) (xy 90.185781 -246.54281) (xy 90.162655 -246.494789)
			(xy 90.146945 -246.443859) (xy 90.139002 -246.391155) (xy 89.910422 -246.391155) (xy 89.902479 -246.443859)
			(xy 89.886769 -246.494789) (xy 89.863643 -246.54281) (xy 89.833619 -246.586847) (xy 89.797367 -246.625918)
			(xy 89.755696 -246.659149) (xy 89.709538 -246.685798) (xy 89.659924 -246.70527) (xy 89.607962 -246.71713)
			(xy 89.554812 -246.721114) (xy 89.501662 -246.71713) (xy 89.4497 -246.70527) (xy 89.400086 -246.685798)
			(xy 89.353928 -246.659149) (xy 89.312257 -246.625918) (xy 89.276005 -246.586847) (xy 89.245981 -246.54281)
			(xy 89.222855 -246.494789) (xy 89.207145 -246.443859) (xy 89.199202 -246.391155) (xy 88.969607 -246.391155)
			(xy 88.967673 -246.417189) (xy 88.956017 -246.468719) (xy 88.936876 -246.517962) (xy 88.910669 -246.563835)
			(xy 88.877971 -246.605334) (xy 88.839501 -246.641545) (xy 88.796102 -246.671675) (xy 88.748728 -246.695062)
			(xy 88.723724 -246.703596) (xy 88.688418 -246.715026) (xy 88.688418 -246.828564) (xy 88.68892 -246.843015)
			(xy 88.697016 -246.87076) (xy 88.71257 -246.89512) (xy 88.734332 -246.914139) (xy 88.760554 -246.926292)
			(xy 88.789133 -246.930601) (xy 88.817774 -246.926722) (xy 88.844176 -246.914965) (xy 88.85555 -246.906034)
			(xy 88.87491 -246.890272) (xy 88.917206 -246.863751) (xy 88.96279 -246.843395) (xy 89.010769 -246.829601)
			(xy 89.060205 -246.822641) (xy 89.085166 -246.822214) (xy 89.111817 -246.822685) (xy 89.164525 -246.830624)
			(xy 89.21546 -246.846332) (xy 89.263485 -246.869455) (xy 89.307527 -246.899479) (xy 89.346603 -246.935732)
			(xy 89.379838 -246.977404) (xy 89.40649 -247.023564) (xy 89.425965 -247.073181) (xy 89.437826 -247.125147)
			(xy 89.44181 -247.1783) (xy 89.439811 -247.204971) (xy 89.669102 -247.204971) (xy 89.669102 -247.151673)
			(xy 89.677045 -247.098969) (xy 89.692755 -247.048039) (xy 89.715881 -247.000018) (xy 89.745905 -246.955981)
			(xy 89.782157 -246.91691) (xy 89.823828 -246.883679) (xy 89.869986 -246.85703) (xy 89.9196 -246.837558)
			(xy 89.971562 -246.825698) (xy 90.024712 -246.821715) (xy 90.077862 -246.825698) (xy 90.129824 -246.837558)
			(xy 90.179438 -246.85703) (xy 90.225596 -246.883679) (xy 90.267267 -246.91691) (xy 90.303519 -246.955981)
			(xy 90.333543 -247.000018) (xy 90.356669 -247.048039) (xy 90.372379 -247.098969) (xy 90.380322 -247.151673)
			(xy 90.38082 -247.178322) (xy 90.380322 -247.204971) (xy 90.609156 -247.204971) (xy 90.609156 -247.151673)
			(xy 90.617099 -247.098969) (xy 90.632809 -247.048039) (xy 90.655935 -247.000018) (xy 90.685959 -246.955981)
			(xy 90.722211 -246.91691) (xy 90.763882 -246.883679) (xy 90.81004 -246.85703) (xy 90.859654 -246.837558)
			(xy 90.911616 -246.825698) (xy 90.964766 -246.821715) (xy 91.017916 -246.825698) (xy 91.069878 -246.837558)
			(xy 91.119492 -246.85703) (xy 91.16565 -246.883679) (xy 91.207321 -246.91691) (xy 91.243573 -246.955981)
			(xy 91.273597 -247.000018) (xy 91.296723 -247.048039) (xy 91.312433 -247.098969) (xy 91.320376 -247.151673)
			(xy 91.320874 -247.178322) (xy 91.320376 -247.204971) (xy 91.548702 -247.204971) (xy 91.548702 -247.151673)
			(xy 91.556645 -247.098969) (xy 91.572355 -247.048039) (xy 91.595481 -247.000018) (xy 91.625505 -246.955981)
			(xy 91.661757 -246.91691) (xy 91.703428 -246.883679) (xy 91.749586 -246.85703) (xy 91.7992 -246.837558)
			(xy 91.851162 -246.825698) (xy 91.904312 -246.821715) (xy 91.957462 -246.825698) (xy 92.009424 -246.837558)
			(xy 92.059038 -246.85703) (xy 92.105196 -246.883679) (xy 92.146867 -246.91691) (xy 92.183119 -246.955981)
			(xy 92.213143 -247.000018) (xy 92.236269 -247.048039) (xy 92.251979 -247.098969) (xy 92.259922 -247.151673)
			(xy 92.26042 -247.178322) (xy 92.259922 -247.204971) (xy 92.488756 -247.204971) (xy 92.488756 -247.151673)
			(xy 92.496699 -247.098969) (xy 92.512409 -247.048039) (xy 92.535535 -247.000018) (xy 92.565559 -246.955981)
			(xy 92.601811 -246.91691) (xy 92.643482 -246.883679) (xy 92.68964 -246.85703) (xy 92.739254 -246.837558)
			(xy 92.791216 -246.825698) (xy 92.844366 -246.821715) (xy 92.897516 -246.825698) (xy 92.949478 -246.837558)
			(xy 92.999092 -246.85703) (xy 93.04525 -246.883679) (xy 93.086921 -246.91691) (xy 93.123173 -246.955981)
			(xy 93.153197 -247.000018) (xy 93.176323 -247.048039) (xy 93.192033 -247.098969) (xy 93.199976 -247.151673)
			(xy 93.200474 -247.178322) (xy 93.199976 -247.204971) (xy 93.428556 -247.204971) (xy 93.428556 -247.151673)
			(xy 93.436499 -247.098969) (xy 93.452209 -247.048039) (xy 93.475335 -247.000018) (xy 93.505359 -246.955981)
			(xy 93.541611 -246.91691) (xy 93.583282 -246.883679) (xy 93.62944 -246.85703) (xy 93.679054 -246.837558)
			(xy 93.731016 -246.825698) (xy 93.784166 -246.821715) (xy 93.837316 -246.825698) (xy 93.889278 -246.837558)
			(xy 93.938892 -246.85703) (xy 93.98505 -246.883679) (xy 94.026721 -246.91691) (xy 94.062973 -246.955981)
			(xy 94.092997 -247.000018) (xy 94.116123 -247.048039) (xy 94.131833 -247.098969) (xy 94.139776 -247.151673)
			(xy 94.140274 -247.178322) (xy 94.139776 -247.204971) (xy 94.368356 -247.204971) (xy 94.368356 -247.151673)
			(xy 94.376299 -247.098969) (xy 94.392009 -247.048039) (xy 94.415135 -247.000018) (xy 94.445159 -246.955981)
			(xy 94.481411 -246.91691) (xy 94.523082 -246.883679) (xy 94.56924 -246.85703) (xy 94.618854 -246.837558)
			(xy 94.670816 -246.825698) (xy 94.723966 -246.821715) (xy 94.777116 -246.825698) (xy 94.829078 -246.837558)
			(xy 94.878692 -246.85703) (xy 94.92485 -246.883679) (xy 94.966521 -246.91691) (xy 95.002773 -246.955981)
			(xy 95.032797 -247.000018) (xy 95.055923 -247.048039) (xy 95.071633 -247.098969) (xy 95.079576 -247.151673)
			(xy 95.080074 -247.178322) (xy 95.079576 -247.204971) (xy 95.308156 -247.204971) (xy 95.308156 -247.151673)
			(xy 95.316099 -247.098969) (xy 95.331809 -247.048039) (xy 95.354935 -247.000018) (xy 95.384959 -246.955981)
			(xy 95.421211 -246.91691) (xy 95.462882 -246.883679) (xy 95.50904 -246.85703) (xy 95.558654 -246.837558)
			(xy 95.610616 -246.825698) (xy 95.663766 -246.821715) (xy 95.716916 -246.825698) (xy 95.768878 -246.837558)
			(xy 95.818492 -246.85703) (xy 95.86465 -246.883679) (xy 95.906321 -246.91691) (xy 95.942573 -246.955981)
			(xy 95.972597 -247.000018) (xy 95.995723 -247.048039) (xy 96.011433 -247.098969) (xy 96.019376 -247.151673)
			(xy 96.019874 -247.178322) (xy 96.019376 -247.204971) (xy 96.247702 -247.204971) (xy 96.247702 -247.151673)
			(xy 96.255645 -247.098969) (xy 96.271355 -247.048039) (xy 96.294481 -247.000018) (xy 96.324505 -246.955981)
			(xy 96.360757 -246.91691) (xy 96.402428 -246.883679) (xy 96.448586 -246.85703) (xy 96.4982 -246.837558)
			(xy 96.550162 -246.825698) (xy 96.603312 -246.821715) (xy 96.656462 -246.825698) (xy 96.708424 -246.837558)
			(xy 96.758038 -246.85703) (xy 96.804196 -246.883679) (xy 96.845867 -246.91691) (xy 96.882119 -246.955981)
			(xy 96.912143 -247.000018) (xy 96.935269 -247.048039) (xy 96.950979 -247.098969) (xy 96.958922 -247.151673)
			(xy 96.95942 -247.178322) (xy 96.958922 -247.204971) (xy 97.187756 -247.204971) (xy 97.187756 -247.151673)
			(xy 97.195699 -247.098969) (xy 97.211409 -247.048039) (xy 97.234535 -247.000018) (xy 97.264559 -246.955981)
			(xy 97.300811 -246.91691) (xy 97.342482 -246.883679) (xy 97.38864 -246.85703) (xy 97.438254 -246.837558)
			(xy 97.490216 -246.825698) (xy 97.543366 -246.821715) (xy 97.596516 -246.825698) (xy 97.648478 -246.837558)
			(xy 97.698092 -246.85703) (xy 97.74425 -246.883679) (xy 97.785921 -246.91691) (xy 97.822173 -246.955981)
			(xy 97.852197 -247.000018) (xy 97.875323 -247.048039) (xy 97.891033 -247.098969) (xy 97.898976 -247.151673)
			(xy 97.899474 -247.178322) (xy 97.898976 -247.204971) (xy 98.127302 -247.204971) (xy 98.127302 -247.151673)
			(xy 98.135245 -247.098969) (xy 98.150955 -247.048039) (xy 98.174081 -247.000018) (xy 98.204105 -246.955981)
			(xy 98.240357 -246.91691) (xy 98.282028 -246.883679) (xy 98.328186 -246.85703) (xy 98.3778 -246.837558)
			(xy 98.429762 -246.825698) (xy 98.482912 -246.821715) (xy 98.536062 -246.825698) (xy 98.588024 -246.837558)
			(xy 98.637638 -246.85703) (xy 98.683796 -246.883679) (xy 98.725467 -246.91691) (xy 98.761719 -246.955981)
			(xy 98.791743 -247.000018) (xy 98.814869 -247.048039) (xy 98.830579 -247.098969) (xy 98.838522 -247.151673)
			(xy 98.83902 -247.178322) (xy 98.838522 -247.204971) (xy 98.830579 -247.257675) (xy 98.814869 -247.308605)
			(xy 98.791743 -247.356626) (xy 98.761719 -247.400663) (xy 98.725467 -247.439734) (xy 98.683796 -247.472965)
			(xy 98.637638 -247.499614) (xy 98.588024 -247.519086) (xy 98.536062 -247.530946) (xy 98.482912 -247.53493)
			(xy 98.429762 -247.530946) (xy 98.3778 -247.519086) (xy 98.328186 -247.499614) (xy 98.282028 -247.472965)
			(xy 98.240357 -247.439734) (xy 98.204105 -247.400663) (xy 98.174081 -247.356626) (xy 98.150955 -247.308605)
			(xy 98.135245 -247.257675) (xy 98.127302 -247.204971) (xy 97.898976 -247.204971) (xy 97.891033 -247.257675)
			(xy 97.875323 -247.308605) (xy 97.852197 -247.356626) (xy 97.822173 -247.400663) (xy 97.785921 -247.439734)
			(xy 97.74425 -247.472965) (xy 97.698092 -247.499614) (xy 97.648478 -247.519086) (xy 97.596516 -247.530946)
			(xy 97.543366 -247.53493) (xy 97.490216 -247.530946) (xy 97.438254 -247.519086) (xy 97.38864 -247.499614)
			(xy 97.342482 -247.472965) (xy 97.300811 -247.439734) (xy 97.264559 -247.400663) (xy 97.234535 -247.356626)
			(xy 97.211409 -247.308605) (xy 97.195699 -247.257675) (xy 97.187756 -247.204971) (xy 96.958922 -247.204971)
			(xy 96.950979 -247.257675) (xy 96.935269 -247.308605) (xy 96.912143 -247.356626) (xy 96.882119 -247.400663)
			(xy 96.845867 -247.439734) (xy 96.804196 -247.472965) (xy 96.758038 -247.499614) (xy 96.708424 -247.519086)
			(xy 96.656462 -247.530946) (xy 96.603312 -247.53493) (xy 96.550162 -247.530946) (xy 96.4982 -247.519086)
			(xy 96.448586 -247.499614) (xy 96.402428 -247.472965) (xy 96.360757 -247.439734) (xy 96.324505 -247.400663)
			(xy 96.294481 -247.356626) (xy 96.271355 -247.308605) (xy 96.255645 -247.257675) (xy 96.247702 -247.204971)
			(xy 96.019376 -247.204971) (xy 96.011433 -247.257675) (xy 95.995723 -247.308605) (xy 95.972597 -247.356626)
			(xy 95.942573 -247.400663) (xy 95.906321 -247.439734) (xy 95.86465 -247.472965) (xy 95.818492 -247.499614)
			(xy 95.768878 -247.519086) (xy 95.716916 -247.530946) (xy 95.663766 -247.53493) (xy 95.610616 -247.530946)
			(xy 95.558654 -247.519086) (xy 95.50904 -247.499614) (xy 95.462882 -247.472965) (xy 95.421211 -247.439734)
			(xy 95.384959 -247.400663) (xy 95.354935 -247.356626) (xy 95.331809 -247.308605) (xy 95.316099 -247.257675)
			(xy 95.308156 -247.204971) (xy 95.079576 -247.204971) (xy 95.071633 -247.257675) (xy 95.055923 -247.308605)
			(xy 95.032797 -247.356626) (xy 95.002773 -247.400663) (xy 94.966521 -247.439734) (xy 94.92485 -247.472965)
			(xy 94.878692 -247.499614) (xy 94.829078 -247.519086) (xy 94.777116 -247.530946) (xy 94.723966 -247.53493)
			(xy 94.670816 -247.530946) (xy 94.618854 -247.519086) (xy 94.56924 -247.499614) (xy 94.523082 -247.472965)
			(xy 94.481411 -247.439734) (xy 94.445159 -247.400663) (xy 94.415135 -247.356626) (xy 94.392009 -247.308605)
			(xy 94.376299 -247.257675) (xy 94.368356 -247.204971) (xy 94.139776 -247.204971) (xy 94.131833 -247.257675)
			(xy 94.116123 -247.308605) (xy 94.092997 -247.356626) (xy 94.062973 -247.400663) (xy 94.026721 -247.439734)
			(xy 93.98505 -247.472965) (xy 93.938892 -247.499614) (xy 93.889278 -247.519086) (xy 93.837316 -247.530946)
			(xy 93.784166 -247.53493) (xy 93.731016 -247.530946) (xy 93.679054 -247.519086) (xy 93.62944 -247.499614)
			(xy 93.583282 -247.472965) (xy 93.541611 -247.439734) (xy 93.505359 -247.400663) (xy 93.475335 -247.356626)
			(xy 93.452209 -247.308605) (xy 93.436499 -247.257675) (xy 93.428556 -247.204971) (xy 93.199976 -247.204971)
			(xy 93.192033 -247.257675) (xy 93.176323 -247.308605) (xy 93.153197 -247.356626) (xy 93.123173 -247.400663)
			(xy 93.086921 -247.439734) (xy 93.04525 -247.472965) (xy 92.999092 -247.499614) (xy 92.949478 -247.519086)
			(xy 92.897516 -247.530946) (xy 92.844366 -247.53493) (xy 92.791216 -247.530946) (xy 92.739254 -247.519086)
			(xy 92.68964 -247.499614) (xy 92.643482 -247.472965) (xy 92.601811 -247.439734) (xy 92.565559 -247.400663)
			(xy 92.535535 -247.356626) (xy 92.512409 -247.308605) (xy 92.496699 -247.257675) (xy 92.488756 -247.204971)
			(xy 92.259922 -247.204971) (xy 92.251979 -247.257675) (xy 92.236269 -247.308605) (xy 92.213143 -247.356626)
			(xy 92.183119 -247.400663) (xy 92.146867 -247.439734) (xy 92.105196 -247.472965) (xy 92.059038 -247.499614)
			(xy 92.009424 -247.519086) (xy 91.957462 -247.530946) (xy 91.904312 -247.53493) (xy 91.851162 -247.530946)
			(xy 91.7992 -247.519086) (xy 91.749586 -247.499614) (xy 91.703428 -247.472965) (xy 91.661757 -247.439734)
			(xy 91.625505 -247.400663) (xy 91.595481 -247.356626) (xy 91.572355 -247.308605) (xy 91.556645 -247.257675)
			(xy 91.548702 -247.204971) (xy 91.320376 -247.204971) (xy 91.312433 -247.257675) (xy 91.296723 -247.308605)
			(xy 91.273597 -247.356626) (xy 91.243573 -247.400663) (xy 91.207321 -247.439734) (xy 91.16565 -247.472965)
			(xy 91.119492 -247.499614) (xy 91.069878 -247.519086) (xy 91.017916 -247.530946) (xy 90.964766 -247.53493)
			(xy 90.911616 -247.530946) (xy 90.859654 -247.519086) (xy 90.81004 -247.499614) (xy 90.763882 -247.472965)
			(xy 90.722211 -247.439734) (xy 90.685959 -247.400663) (xy 90.655935 -247.356626) (xy 90.632809 -247.308605)
			(xy 90.617099 -247.257675) (xy 90.609156 -247.204971) (xy 90.380322 -247.204971) (xy 90.372379 -247.257675)
			(xy 90.356669 -247.308605) (xy 90.333543 -247.356626) (xy 90.303519 -247.400663) (xy 90.267267 -247.439734)
			(xy 90.225596 -247.472965) (xy 90.179438 -247.499614) (xy 90.129824 -247.519086) (xy 90.077862 -247.530946)
			(xy 90.024712 -247.53493) (xy 89.971562 -247.530946) (xy 89.9196 -247.519086) (xy 89.869986 -247.499614)
			(xy 89.823828 -247.472965) (xy 89.782157 -247.439734) (xy 89.745905 -247.400663) (xy 89.715881 -247.356626)
			(xy 89.692755 -247.308605) (xy 89.677045 -247.257675) (xy 89.669102 -247.204971) (xy 89.439811 -247.204971)
			(xy 89.437826 -247.231453) (xy 89.425965 -247.283419) (xy 89.40649 -247.333036) (xy 89.379838 -247.379196)
			(xy 89.346603 -247.420868) (xy 89.307527 -247.457121) (xy 89.263485 -247.487145) (xy 89.21546 -247.510268)
			(xy 89.164525 -247.525976) (xy 89.111817 -247.533915) (xy 89.085166 -247.53443) (xy 89.060205 -247.534009)
			(xy 89.010773 -247.527038) (xy 88.962797 -247.513238) (xy 88.917216 -247.492878) (xy 88.874922 -247.466357)
			(xy 88.85555 -247.45061) (xy 88.844191 -247.441675) (xy 88.817788 -247.42996) (xy 88.789159 -247.426109)
			(xy 88.760598 -247.430431) (xy 88.734391 -247.442579) (xy 88.712635 -247.461582) (xy 88.697073 -247.485917)
			(xy 88.688949 -247.513638) (xy 88.688418 -247.52808) (xy 88.688418 -247.641618) (xy 88.723724 -247.653048)
			(xy 88.748729 -247.661571) (xy 88.796098 -247.684958) (xy 88.839492 -247.715087) (xy 88.877957 -247.751297)
			(xy 88.910651 -247.792793) (xy 88.936854 -247.838664) (xy 88.955992 -247.887903) (xy 88.967645 -247.939429)
			(xy 88.971557 -247.992112) (xy 88.969575 -248.018787) (xy 89.199456 -248.018787) (xy 89.199456 -247.965489)
			(xy 89.207399 -247.912785) (xy 89.223109 -247.861855) (xy 89.246235 -247.813834) (xy 89.276259 -247.769797)
			(xy 89.312511 -247.730726) (xy 89.354182 -247.697495) (xy 89.40034 -247.670846) (xy 89.449954 -247.651374)
			(xy 89.501916 -247.639514) (xy 89.555066 -247.635531) (xy 89.608216 -247.639514) (xy 89.660178 -247.651374)
			(xy 89.709792 -247.670846) (xy 89.75595 -247.697495) (xy 89.797621 -247.730726) (xy 89.833873 -247.769797)
			(xy 89.863897 -247.813834) (xy 89.887023 -247.861855) (xy 89.902733 -247.912785) (xy 89.910676 -247.965489)
			(xy 89.911174 -247.992138) (xy 89.910676 -248.018787) (xy 90.139002 -248.018787) (xy 90.139002 -247.965489)
			(xy 90.146945 -247.912785) (xy 90.162655 -247.861855) (xy 90.185781 -247.813834) (xy 90.215805 -247.769797)
			(xy 90.252057 -247.730726) (xy 90.293728 -247.697495) (xy 90.339886 -247.670846) (xy 90.3895 -247.651374)
			(xy 90.441462 -247.639514) (xy 90.494612 -247.635531) (xy 90.547762 -247.639514) (xy 90.599724 -247.651374)
			(xy 90.649338 -247.670846) (xy 90.695496 -247.697495) (xy 90.737167 -247.730726) (xy 90.773419 -247.769797)
			(xy 90.803443 -247.813834) (xy 90.826569 -247.861855) (xy 90.842279 -247.912785) (xy 90.850222 -247.965489)
			(xy 90.85072 -247.992138) (xy 90.850222 -248.018787) (xy 91.079056 -248.018787) (xy 91.079056 -247.965489)
			(xy 91.086999 -247.912785) (xy 91.102709 -247.861855) (xy 91.125835 -247.813834) (xy 91.155859 -247.769797)
			(xy 91.192111 -247.730726) (xy 91.233782 -247.697495) (xy 91.27994 -247.670846) (xy 91.329554 -247.651374)
			(xy 91.381516 -247.639514) (xy 91.434666 -247.635531) (xy 91.487816 -247.639514) (xy 91.539778 -247.651374)
			(xy 91.589392 -247.670846) (xy 91.63555 -247.697495) (xy 91.677221 -247.730726) (xy 91.713473 -247.769797)
			(xy 91.743497 -247.813834) (xy 91.766623 -247.861855) (xy 91.782333 -247.912785) (xy 91.790276 -247.965489)
			(xy 91.790774 -247.992138) (xy 91.790276 -248.018787) (xy 92.018602 -248.018787) (xy 92.018602 -247.965489)
			(xy 92.026545 -247.912785) (xy 92.042255 -247.861855) (xy 92.065381 -247.813834) (xy 92.095405 -247.769797)
			(xy 92.131657 -247.730726) (xy 92.173328 -247.697495) (xy 92.219486 -247.670846) (xy 92.2691 -247.651374)
			(xy 92.321062 -247.639514) (xy 92.374212 -247.635531) (xy 92.427362 -247.639514) (xy 92.479324 -247.651374)
			(xy 92.528938 -247.670846) (xy 92.575096 -247.697495) (xy 92.616767 -247.730726) (xy 92.653019 -247.769797)
			(xy 92.683043 -247.813834) (xy 92.706169 -247.861855) (xy 92.721879 -247.912785) (xy 92.729822 -247.965489)
			(xy 92.73032 -247.992138) (xy 92.729822 -248.018787) (xy 92.958402 -248.018787) (xy 92.958402 -247.965489)
			(xy 92.966345 -247.912785) (xy 92.982055 -247.861855) (xy 93.005181 -247.813834) (xy 93.035205 -247.769797)
			(xy 93.071457 -247.730726) (xy 93.113128 -247.697495) (xy 93.159286 -247.670846) (xy 93.2089 -247.651374)
			(xy 93.260862 -247.639514) (xy 93.314012 -247.635531) (xy 93.367162 -247.639514) (xy 93.419124 -247.651374)
			(xy 93.468738 -247.670846) (xy 93.514896 -247.697495) (xy 93.556567 -247.730726) (xy 93.592819 -247.769797)
			(xy 93.622843 -247.813834) (xy 93.645969 -247.861855) (xy 93.661679 -247.912785) (xy 93.669622 -247.965489)
			(xy 93.67012 -247.992138) (xy 93.669622 -248.018787) (xy 93.898202 -248.018787) (xy 93.898202 -247.965489)
			(xy 93.906145 -247.912785) (xy 93.921855 -247.861855) (xy 93.944981 -247.813834) (xy 93.975005 -247.769797)
			(xy 94.011257 -247.730726) (xy 94.052928 -247.697495) (xy 94.099086 -247.670846) (xy 94.1487 -247.651374)
			(xy 94.200662 -247.639514) (xy 94.253812 -247.635531) (xy 94.306962 -247.639514) (xy 94.358924 -247.651374)
			(xy 94.408538 -247.670846) (xy 94.454696 -247.697495) (xy 94.496367 -247.730726) (xy 94.532619 -247.769797)
			(xy 94.562643 -247.813834) (xy 94.585769 -247.861855) (xy 94.601479 -247.912785) (xy 94.609422 -247.965489)
			(xy 94.60992 -247.992138) (xy 94.609422 -248.018787) (xy 94.838002 -248.018787) (xy 94.838002 -247.965489)
			(xy 94.845945 -247.912785) (xy 94.861655 -247.861855) (xy 94.884781 -247.813834) (xy 94.914805 -247.769797)
			(xy 94.951057 -247.730726) (xy 94.992728 -247.697495) (xy 95.038886 -247.670846) (xy 95.0885 -247.651374)
			(xy 95.140462 -247.639514) (xy 95.193612 -247.635531) (xy 95.246762 -247.639514) (xy 95.298724 -247.651374)
			(xy 95.348338 -247.670846) (xy 95.394496 -247.697495) (xy 95.436167 -247.730726) (xy 95.472419 -247.769797)
			(xy 95.502443 -247.813834) (xy 95.525569 -247.861855) (xy 95.541279 -247.912785) (xy 95.549222 -247.965489)
			(xy 95.54972 -247.992138) (xy 95.549222 -248.018787) (xy 95.778056 -248.018787) (xy 95.778056 -247.965489)
			(xy 95.785999 -247.912785) (xy 95.801709 -247.861855) (xy 95.824835 -247.813834) (xy 95.854859 -247.769797)
			(xy 95.891111 -247.730726) (xy 95.932782 -247.697495) (xy 95.97894 -247.670846) (xy 96.028554 -247.651374)
			(xy 96.080516 -247.639514) (xy 96.133666 -247.635531) (xy 96.186816 -247.639514) (xy 96.238778 -247.651374)
			(xy 96.288392 -247.670846) (xy 96.33455 -247.697495) (xy 96.376221 -247.730726) (xy 96.412473 -247.769797)
			(xy 96.442497 -247.813834) (xy 96.465623 -247.861855) (xy 96.481333 -247.912785) (xy 96.489276 -247.965489)
			(xy 96.489774 -247.992138) (xy 96.489276 -248.018787) (xy 96.717602 -248.018787) (xy 96.717602 -247.965489)
			(xy 96.725545 -247.912785) (xy 96.741255 -247.861855) (xy 96.764381 -247.813834) (xy 96.794405 -247.769797)
			(xy 96.830657 -247.730726) (xy 96.872328 -247.697495) (xy 96.918486 -247.670846) (xy 96.9681 -247.651374)
			(xy 97.020062 -247.639514) (xy 97.073212 -247.635531) (xy 97.126362 -247.639514) (xy 97.178324 -247.651374)
			(xy 97.227938 -247.670846) (xy 97.274096 -247.697495) (xy 97.315767 -247.730726) (xy 97.352019 -247.769797)
			(xy 97.382043 -247.813834) (xy 97.405169 -247.861855) (xy 97.420879 -247.912785) (xy 97.428822 -247.965489)
			(xy 97.42932 -247.992138) (xy 97.428822 -248.018787) (xy 97.657656 -248.018787) (xy 97.657656 -247.965489)
			(xy 97.665599 -247.912785) (xy 97.681309 -247.861855) (xy 97.704435 -247.813834) (xy 97.734459 -247.769797)
			(xy 97.770711 -247.730726) (xy 97.812382 -247.697495) (xy 97.85854 -247.670846) (xy 97.908154 -247.651374)
			(xy 97.960116 -247.639514) (xy 98.013266 -247.635531) (xy 98.066416 -247.639514) (xy 98.118378 -247.651374)
			(xy 98.167992 -247.670846) (xy 98.21415 -247.697495) (xy 98.255821 -247.730726) (xy 98.292073 -247.769797)
			(xy 98.322097 -247.813834) (xy 98.345223 -247.861855) (xy 98.360933 -247.912785) (xy 98.368876 -247.965489)
			(xy 98.369374 -247.992138) (xy 98.368876 -248.018787) (xy 98.597456 -248.018787) (xy 98.597456 -247.965489)
			(xy 98.605399 -247.912785) (xy 98.621109 -247.861855) (xy 98.644235 -247.813834) (xy 98.674259 -247.769797)
			(xy 98.710511 -247.730726) (xy 98.752182 -247.697495) (xy 98.79834 -247.670846) (xy 98.847954 -247.651374)
			(xy 98.899916 -247.639514) (xy 98.953066 -247.635531) (xy 99.006216 -247.639514) (xy 99.058178 -247.651374)
			(xy 99.107792 -247.670846) (xy 99.15395 -247.697495) (xy 99.195621 -247.730726) (xy 99.231873 -247.769797)
			(xy 99.261897 -247.813834) (xy 99.285023 -247.861855) (xy 99.300733 -247.912785) (xy 99.308676 -247.965489)
			(xy 99.309174 -247.992138) (xy 99.308676 -248.018787) (xy 99.300733 -248.071491) (xy 99.285023 -248.122421)
			(xy 99.261897 -248.170442) (xy 99.231873 -248.214479) (xy 99.195621 -248.25355) (xy 99.15395 -248.286781)
			(xy 99.107792 -248.31343) (xy 99.058178 -248.332902) (xy 99.006216 -248.344762) (xy 98.953066 -248.348746)
			(xy 98.899916 -248.344762) (xy 98.847954 -248.332902) (xy 98.79834 -248.31343) (xy 98.752182 -248.286781)
			(xy 98.710511 -248.25355) (xy 98.674259 -248.214479) (xy 98.644235 -248.170442) (xy 98.621109 -248.122421)
			(xy 98.605399 -248.071491) (xy 98.597456 -248.018787) (xy 98.368876 -248.018787) (xy 98.360933 -248.071491)
			(xy 98.345223 -248.122421) (xy 98.322097 -248.170442) (xy 98.292073 -248.214479) (xy 98.255821 -248.25355)
			(xy 98.21415 -248.286781) (xy 98.167992 -248.31343) (xy 98.118378 -248.332902) (xy 98.066416 -248.344762)
			(xy 98.013266 -248.348746) (xy 97.960116 -248.344762) (xy 97.908154 -248.332902) (xy 97.85854 -248.31343)
			(xy 97.812382 -248.286781) (xy 97.770711 -248.25355) (xy 97.734459 -248.214479) (xy 97.704435 -248.170442)
			(xy 97.681309 -248.122421) (xy 97.665599 -248.071491) (xy 97.657656 -248.018787) (xy 97.428822 -248.018787)
			(xy 97.420879 -248.071491) (xy 97.405169 -248.122421) (xy 97.382043 -248.170442) (xy 97.352019 -248.214479)
			(xy 97.315767 -248.25355) (xy 97.274096 -248.286781) (xy 97.227938 -248.31343) (xy 97.178324 -248.332902)
			(xy 97.126362 -248.344762) (xy 97.073212 -248.348746) (xy 97.020062 -248.344762) (xy 96.9681 -248.332902)
			(xy 96.918486 -248.31343) (xy 96.872328 -248.286781) (xy 96.830657 -248.25355) (xy 96.794405 -248.214479)
			(xy 96.764381 -248.170442) (xy 96.741255 -248.122421) (xy 96.725545 -248.071491) (xy 96.717602 -248.018787)
			(xy 96.489276 -248.018787) (xy 96.481333 -248.071491) (xy 96.465623 -248.122421) (xy 96.442497 -248.170442)
			(xy 96.412473 -248.214479) (xy 96.376221 -248.25355) (xy 96.33455 -248.286781) (xy 96.288392 -248.31343)
			(xy 96.238778 -248.332902) (xy 96.186816 -248.344762) (xy 96.133666 -248.348746) (xy 96.080516 -248.344762)
			(xy 96.028554 -248.332902) (xy 95.97894 -248.31343) (xy 95.932782 -248.286781) (xy 95.891111 -248.25355)
			(xy 95.854859 -248.214479) (xy 95.824835 -248.170442) (xy 95.801709 -248.122421) (xy 95.785999 -248.071491)
			(xy 95.778056 -248.018787) (xy 95.549222 -248.018787) (xy 95.541279 -248.071491) (xy 95.525569 -248.122421)
			(xy 95.502443 -248.170442) (xy 95.472419 -248.214479) (xy 95.436167 -248.25355) (xy 95.394496 -248.286781)
			(xy 95.348338 -248.31343) (xy 95.298724 -248.332902) (xy 95.246762 -248.344762) (xy 95.193612 -248.348746)
			(xy 95.140462 -248.344762) (xy 95.0885 -248.332902) (xy 95.038886 -248.31343) (xy 94.992728 -248.286781)
			(xy 94.951057 -248.25355) (xy 94.914805 -248.214479) (xy 94.884781 -248.170442) (xy 94.861655 -248.122421)
			(xy 94.845945 -248.071491) (xy 94.838002 -248.018787) (xy 94.609422 -248.018787) (xy 94.601479 -248.071491)
			(xy 94.585769 -248.122421) (xy 94.562643 -248.170442) (xy 94.532619 -248.214479) (xy 94.496367 -248.25355)
			(xy 94.454696 -248.286781) (xy 94.408538 -248.31343) (xy 94.358924 -248.332902) (xy 94.306962 -248.344762)
			(xy 94.253812 -248.348746) (xy 94.200662 -248.344762) (xy 94.1487 -248.332902) (xy 94.099086 -248.31343)
			(xy 94.052928 -248.286781) (xy 94.011257 -248.25355) (xy 93.975005 -248.214479) (xy 93.944981 -248.170442)
			(xy 93.921855 -248.122421) (xy 93.906145 -248.071491) (xy 93.898202 -248.018787) (xy 93.669622 -248.018787)
			(xy 93.661679 -248.071491) (xy 93.645969 -248.122421) (xy 93.622843 -248.170442) (xy 93.592819 -248.214479)
			(xy 93.556567 -248.25355) (xy 93.514896 -248.286781) (xy 93.468738 -248.31343) (xy 93.419124 -248.332902)
			(xy 93.367162 -248.344762) (xy 93.314012 -248.348746) (xy 93.260862 -248.344762) (xy 93.2089 -248.332902)
			(xy 93.159286 -248.31343) (xy 93.113128 -248.286781) (xy 93.071457 -248.25355) (xy 93.035205 -248.214479)
			(xy 93.005181 -248.170442) (xy 92.982055 -248.122421) (xy 92.966345 -248.071491) (xy 92.958402 -248.018787)
			(xy 92.729822 -248.018787) (xy 92.721879 -248.071491) (xy 92.706169 -248.122421) (xy 92.683043 -248.170442)
			(xy 92.653019 -248.214479) (xy 92.616767 -248.25355) (xy 92.575096 -248.286781) (xy 92.528938 -248.31343)
			(xy 92.479324 -248.332902) (xy 92.427362 -248.344762) (xy 92.374212 -248.348746) (xy 92.321062 -248.344762)
			(xy 92.2691 -248.332902) (xy 92.219486 -248.31343) (xy 92.173328 -248.286781) (xy 92.131657 -248.25355)
			(xy 92.095405 -248.214479) (xy 92.065381 -248.170442) (xy 92.042255 -248.122421) (xy 92.026545 -248.071491)
			(xy 92.018602 -248.018787) (xy 91.790276 -248.018787) (xy 91.782333 -248.071491) (xy 91.766623 -248.122421)
			(xy 91.743497 -248.170442) (xy 91.713473 -248.214479) (xy 91.677221 -248.25355) (xy 91.63555 -248.286781)
			(xy 91.589392 -248.31343) (xy 91.539778 -248.332902) (xy 91.487816 -248.344762) (xy 91.434666 -248.348746)
			(xy 91.381516 -248.344762) (xy 91.329554 -248.332902) (xy 91.27994 -248.31343) (xy 91.233782 -248.286781)
			(xy 91.192111 -248.25355) (xy 91.155859 -248.214479) (xy 91.125835 -248.170442) (xy 91.102709 -248.122421)
			(xy 91.086999 -248.071491) (xy 91.079056 -248.018787) (xy 90.850222 -248.018787) (xy 90.842279 -248.071491)
			(xy 90.826569 -248.122421) (xy 90.803443 -248.170442) (xy 90.773419 -248.214479) (xy 90.737167 -248.25355)
			(xy 90.695496 -248.286781) (xy 90.649338 -248.31343) (xy 90.599724 -248.332902) (xy 90.547762 -248.344762)
			(xy 90.494612 -248.348746) (xy 90.441462 -248.344762) (xy 90.3895 -248.332902) (xy 90.339886 -248.31343)
			(xy 90.293728 -248.286781) (xy 90.252057 -248.25355) (xy 90.215805 -248.214479) (xy 90.185781 -248.170442)
			(xy 90.162655 -248.122421) (xy 90.146945 -248.071491) (xy 90.139002 -248.018787) (xy 89.910676 -248.018787)
			(xy 89.902733 -248.071491) (xy 89.887023 -248.122421) (xy 89.863897 -248.170442) (xy 89.833873 -248.214479)
			(xy 89.797621 -248.25355) (xy 89.75595 -248.286781) (xy 89.709792 -248.31343) (xy 89.660178 -248.332902)
			(xy 89.608216 -248.344762) (xy 89.555066 -248.348746) (xy 89.501916 -248.344762) (xy 89.449954 -248.332902)
			(xy 89.40034 -248.31343) (xy 89.354182 -248.286781) (xy 89.312511 -248.25355) (xy 89.276259 -248.214479)
			(xy 89.246235 -248.170442) (xy 89.223109 -248.122421) (xy 89.207399 -248.071491) (xy 89.199456 -248.018787)
			(xy 88.969575 -248.018787) (xy 88.967642 -248.044794) (xy 88.955985 -248.09632) (xy 88.936844 -248.145557)
			(xy 88.910638 -248.191427) (xy 88.877942 -248.23292) (xy 88.839474 -248.269128) (xy 88.796078 -248.299254)
			(xy 88.748708 -248.322637) (xy 88.723724 -248.331228) (xy 88.688418 -248.342658) (xy 88.688418 -248.45645)
			(xy 88.688918 -248.470903) (xy 88.697012 -248.498651) (xy 88.712565 -248.523015) (xy 88.734328 -248.542037)
			(xy 88.760553 -248.554191) (xy 88.789135 -248.558501) (xy 88.817778 -248.55462) (xy 88.844183 -248.542861)
			(xy 88.85555 -248.53392) (xy 88.87491 -248.518158) (xy 88.917206 -248.491639) (xy 88.96279 -248.471283)
			(xy 89.01077 -248.45749) (xy 89.060205 -248.45053) (xy 89.085166 -248.4501) (xy 89.111818 -248.450571)
			(xy 89.164528 -248.458511) (xy 89.215465 -248.474219) (xy 89.263492 -248.497343) (xy 89.307536 -248.527368)
			(xy 89.346613 -248.563622) (xy 89.379849 -248.605296) (xy 89.406503 -248.651458) (xy 89.425978 -248.701077)
			(xy 89.43784 -248.753045) (xy 89.441824 -248.8062) (xy 89.439826 -248.832857) (xy 89.669356 -248.832857)
			(xy 89.669356 -248.779559) (xy 89.677299 -248.726855) (xy 89.693009 -248.675925) (xy 89.716135 -248.627904)
			(xy 89.746159 -248.583867) (xy 89.782411 -248.544796) (xy 89.824082 -248.511565) (xy 89.87024 -248.484916)
			(xy 89.919854 -248.465444) (xy 89.971816 -248.453584) (xy 90.024966 -248.449601) (xy 90.078116 -248.453584)
			(xy 90.130078 -248.465444) (xy 90.179692 -248.484916) (xy 90.22585 -248.511565) (xy 90.267521 -248.544796)
			(xy 90.303773 -248.583867) (xy 90.333797 -248.627904) (xy 90.356923 -248.675925) (xy 90.372633 -248.726855)
			(xy 90.380576 -248.779559) (xy 90.381074 -248.806208) (xy 90.380576 -248.832857) (xy 90.609156 -248.832857)
			(xy 90.609156 -248.779559) (xy 90.617099 -248.726855) (xy 90.632809 -248.675925) (xy 90.655935 -248.627904)
			(xy 90.685959 -248.583867) (xy 90.722211 -248.544796) (xy 90.763882 -248.511565) (xy 90.81004 -248.484916)
			(xy 90.859654 -248.465444) (xy 90.911616 -248.453584) (xy 90.964766 -248.449601) (xy 91.017916 -248.453584)
			(xy 91.069878 -248.465444) (xy 91.119492 -248.484916) (xy 91.16565 -248.511565) (xy 91.207321 -248.544796)
			(xy 91.243573 -248.583867) (xy 91.273597 -248.627904) (xy 91.296723 -248.675925) (xy 91.312433 -248.726855)
			(xy 91.320376 -248.779559) (xy 91.320874 -248.806208) (xy 91.320376 -248.832857) (xy 91.548956 -248.832857)
			(xy 91.548956 -248.779559) (xy 91.556899 -248.726855) (xy 91.572609 -248.675925) (xy 91.595735 -248.627904)
			(xy 91.625759 -248.583867) (xy 91.662011 -248.544796) (xy 91.703682 -248.511565) (xy 91.74984 -248.484916)
			(xy 91.799454 -248.465444) (xy 91.851416 -248.453584) (xy 91.904566 -248.449601) (xy 91.957716 -248.453584)
			(xy 92.009678 -248.465444) (xy 92.059292 -248.484916) (xy 92.10545 -248.511565) (xy 92.147121 -248.544796)
			(xy 92.183373 -248.583867) (xy 92.213397 -248.627904) (xy 92.236523 -248.675925) (xy 92.252233 -248.726855)
			(xy 92.260176 -248.779559) (xy 92.260674 -248.806208) (xy 92.260176 -248.832857) (xy 92.488756 -248.832857)
			(xy 92.488756 -248.779559) (xy 92.496699 -248.726855) (xy 92.512409 -248.675925) (xy 92.535535 -248.627904)
			(xy 92.565559 -248.583867) (xy 92.601811 -248.544796) (xy 92.643482 -248.511565) (xy 92.68964 -248.484916)
			(xy 92.739254 -248.465444) (xy 92.791216 -248.453584) (xy 92.844366 -248.449601) (xy 92.897516 -248.453584)
			(xy 92.949478 -248.465444) (xy 92.999092 -248.484916) (xy 93.04525 -248.511565) (xy 93.086921 -248.544796)
			(xy 93.123173 -248.583867) (xy 93.153197 -248.627904) (xy 93.176323 -248.675925) (xy 93.192033 -248.726855)
			(xy 93.199976 -248.779559) (xy 93.200474 -248.806208) (xy 93.199976 -248.832857) (xy 93.428556 -248.832857)
			(xy 93.428556 -248.779559) (xy 93.436499 -248.726855) (xy 93.452209 -248.675925) (xy 93.475335 -248.627904)
			(xy 93.505359 -248.583867) (xy 93.541611 -248.544796) (xy 93.583282 -248.511565) (xy 93.62944 -248.484916)
			(xy 93.679054 -248.465444) (xy 93.731016 -248.453584) (xy 93.784166 -248.449601) (xy 93.837316 -248.453584)
			(xy 93.889278 -248.465444) (xy 93.938892 -248.484916) (xy 93.98505 -248.511565) (xy 94.026721 -248.544796)
			(xy 94.062973 -248.583867) (xy 94.092997 -248.627904) (xy 94.116123 -248.675925) (xy 94.131833 -248.726855)
			(xy 94.139776 -248.779559) (xy 94.140274 -248.806208) (xy 94.139776 -248.832857) (xy 94.368102 -248.832857)
			(xy 94.368102 -248.779559) (xy 94.376045 -248.726855) (xy 94.391755 -248.675925) (xy 94.414881 -248.627904)
			(xy 94.444905 -248.583867) (xy 94.481157 -248.544796) (xy 94.522828 -248.511565) (xy 94.568986 -248.484916)
			(xy 94.6186 -248.465444) (xy 94.670562 -248.453584) (xy 94.723712 -248.449601) (xy 94.776862 -248.453584)
			(xy 94.828824 -248.465444) (xy 94.878438 -248.484916) (xy 94.924596 -248.511565) (xy 94.966267 -248.544796)
			(xy 95.002519 -248.583867) (xy 95.032543 -248.627904) (xy 95.055669 -248.675925) (xy 95.071379 -248.726855)
			(xy 95.079322 -248.779559) (xy 95.07982 -248.806208) (xy 95.079322 -248.832857) (xy 95.308156 -248.832857)
			(xy 95.308156 -248.779559) (xy 95.316099 -248.726855) (xy 95.331809 -248.675925) (xy 95.354935 -248.627904)
			(xy 95.384959 -248.583867) (xy 95.421211 -248.544796) (xy 95.462882 -248.511565) (xy 95.50904 -248.484916)
			(xy 95.558654 -248.465444) (xy 95.610616 -248.453584) (xy 95.663766 -248.449601) (xy 95.716916 -248.453584)
			(xy 95.768878 -248.465444) (xy 95.818492 -248.484916) (xy 95.86465 -248.511565) (xy 95.906321 -248.544796)
			(xy 95.942573 -248.583867) (xy 95.972597 -248.627904) (xy 95.995723 -248.675925) (xy 96.011433 -248.726855)
			(xy 96.019376 -248.779559) (xy 96.019874 -248.806208) (xy 96.019376 -248.832857) (xy 96.247956 -248.832857)
			(xy 96.247956 -248.779559) (xy 96.255899 -248.726855) (xy 96.271609 -248.675925) (xy 96.294735 -248.627904)
			(xy 96.324759 -248.583867) (xy 96.361011 -248.544796) (xy 96.402682 -248.511565) (xy 96.44884 -248.484916)
			(xy 96.498454 -248.465444) (xy 96.550416 -248.453584) (xy 96.603566 -248.449601) (xy 96.656716 -248.453584)
			(xy 96.708678 -248.465444) (xy 96.758292 -248.484916) (xy 96.80445 -248.511565) (xy 96.846121 -248.544796)
			(xy 96.882373 -248.583867) (xy 96.912397 -248.627904) (xy 96.935523 -248.675925) (xy 96.951233 -248.726855)
			(xy 96.959176 -248.779559) (xy 96.959674 -248.806208) (xy 96.959176 -248.832857) (xy 97.187756 -248.832857)
			(xy 97.187756 -248.779559) (xy 97.195699 -248.726855) (xy 97.211409 -248.675925) (xy 97.234535 -248.627904)
			(xy 97.264559 -248.583867) (xy 97.300811 -248.544796) (xy 97.342482 -248.511565) (xy 97.38864 -248.484916)
			(xy 97.438254 -248.465444) (xy 97.490216 -248.453584) (xy 97.543366 -248.449601) (xy 97.596516 -248.453584)
			(xy 97.648478 -248.465444) (xy 97.698092 -248.484916) (xy 97.74425 -248.511565) (xy 97.785921 -248.544796)
			(xy 97.822173 -248.583867) (xy 97.852197 -248.627904) (xy 97.875323 -248.675925) (xy 97.891033 -248.726855)
			(xy 97.898976 -248.779559) (xy 97.899474 -248.806208) (xy 97.898976 -248.832857) (xy 98.127556 -248.832857)
			(xy 98.127556 -248.779559) (xy 98.135499 -248.726855) (xy 98.151209 -248.675925) (xy 98.174335 -248.627904)
			(xy 98.204359 -248.583867) (xy 98.240611 -248.544796) (xy 98.282282 -248.511565) (xy 98.32844 -248.484916)
			(xy 98.378054 -248.465444) (xy 98.430016 -248.453584) (xy 98.483166 -248.449601) (xy 98.536316 -248.453584)
			(xy 98.588278 -248.465444) (xy 98.637892 -248.484916) (xy 98.68405 -248.511565) (xy 98.725721 -248.544796)
			(xy 98.761973 -248.583867) (xy 98.791997 -248.627904) (xy 98.815123 -248.675925) (xy 98.830833 -248.726855)
			(xy 98.838776 -248.779559) (xy 98.839274 -248.806208) (xy 98.838776 -248.832857) (xy 98.830833 -248.885561)
			(xy 98.815123 -248.936491) (xy 98.791997 -248.984512) (xy 98.761973 -249.028549) (xy 98.725721 -249.06762)
			(xy 98.68405 -249.100851) (xy 98.637892 -249.1275) (xy 98.588278 -249.146972) (xy 98.536316 -249.158832)
			(xy 98.483166 -249.162816) (xy 98.430016 -249.158832) (xy 98.378054 -249.146972) (xy 98.32844 -249.1275)
			(xy 98.282282 -249.100851) (xy 98.240611 -249.06762) (xy 98.204359 -249.028549) (xy 98.174335 -248.984512)
			(xy 98.151209 -248.936491) (xy 98.135499 -248.885561) (xy 98.127556 -248.832857) (xy 97.898976 -248.832857)
			(xy 97.891033 -248.885561) (xy 97.875323 -248.936491) (xy 97.852197 -248.984512) (xy 97.822173 -249.028549)
			(xy 97.785921 -249.06762) (xy 97.74425 -249.100851) (xy 97.698092 -249.1275) (xy 97.648478 -249.146972)
			(xy 97.596516 -249.158832) (xy 97.543366 -249.162816) (xy 97.490216 -249.158832) (xy 97.438254 -249.146972)
			(xy 97.38864 -249.1275) (xy 97.342482 -249.100851) (xy 97.300811 -249.06762) (xy 97.264559 -249.028549)
			(xy 97.234535 -248.984512) (xy 97.211409 -248.936491) (xy 97.195699 -248.885561) (xy 97.187756 -248.832857)
			(xy 96.959176 -248.832857) (xy 96.951233 -248.885561) (xy 96.935523 -248.936491) (xy 96.912397 -248.984512)
			(xy 96.882373 -249.028549) (xy 96.846121 -249.06762) (xy 96.80445 -249.100851) (xy 96.758292 -249.1275)
			(xy 96.708678 -249.146972) (xy 96.656716 -249.158832) (xy 96.603566 -249.162816) (xy 96.550416 -249.158832)
			(xy 96.498454 -249.146972) (xy 96.44884 -249.1275) (xy 96.402682 -249.100851) (xy 96.361011 -249.06762)
			(xy 96.324759 -249.028549) (xy 96.294735 -248.984512) (xy 96.271609 -248.936491) (xy 96.255899 -248.885561)
			(xy 96.247956 -248.832857) (xy 96.019376 -248.832857) (xy 96.011433 -248.885561) (xy 95.995723 -248.936491)
			(xy 95.972597 -248.984512) (xy 95.942573 -249.028549) (xy 95.906321 -249.06762) (xy 95.86465 -249.100851)
			(xy 95.818492 -249.1275) (xy 95.768878 -249.146972) (xy 95.716916 -249.158832) (xy 95.663766 -249.162816)
			(xy 95.610616 -249.158832) (xy 95.558654 -249.146972) (xy 95.50904 -249.1275) (xy 95.462882 -249.100851)
			(xy 95.421211 -249.06762) (xy 95.384959 -249.028549) (xy 95.354935 -248.984512) (xy 95.331809 -248.936491)
			(xy 95.316099 -248.885561) (xy 95.308156 -248.832857) (xy 95.079322 -248.832857) (xy 95.071379 -248.885561)
			(xy 95.055669 -248.936491) (xy 95.032543 -248.984512) (xy 95.002519 -249.028549) (xy 94.966267 -249.06762)
			(xy 94.924596 -249.100851) (xy 94.878438 -249.1275) (xy 94.828824 -249.146972) (xy 94.776862 -249.158832)
			(xy 94.723712 -249.162816) (xy 94.670562 -249.158832) (xy 94.6186 -249.146972) (xy 94.568986 -249.1275)
			(xy 94.522828 -249.100851) (xy 94.481157 -249.06762) (xy 94.444905 -249.028549) (xy 94.414881 -248.984512)
			(xy 94.391755 -248.936491) (xy 94.376045 -248.885561) (xy 94.368102 -248.832857) (xy 94.139776 -248.832857)
			(xy 94.131833 -248.885561) (xy 94.116123 -248.936491) (xy 94.092997 -248.984512) (xy 94.062973 -249.028549)
			(xy 94.026721 -249.06762) (xy 93.98505 -249.100851) (xy 93.938892 -249.1275) (xy 93.889278 -249.146972)
			(xy 93.837316 -249.158832) (xy 93.784166 -249.162816) (xy 93.731016 -249.158832) (xy 93.679054 -249.146972)
			(xy 93.62944 -249.1275) (xy 93.583282 -249.100851) (xy 93.541611 -249.06762) (xy 93.505359 -249.028549)
			(xy 93.475335 -248.984512) (xy 93.452209 -248.936491) (xy 93.436499 -248.885561) (xy 93.428556 -248.832857)
			(xy 93.199976 -248.832857) (xy 93.192033 -248.885561) (xy 93.176323 -248.936491) (xy 93.153197 -248.984512)
			(xy 93.123173 -249.028549) (xy 93.086921 -249.06762) (xy 93.04525 -249.100851) (xy 92.999092 -249.1275)
			(xy 92.949478 -249.146972) (xy 92.897516 -249.158832) (xy 92.844366 -249.162816) (xy 92.791216 -249.158832)
			(xy 92.739254 -249.146972) (xy 92.68964 -249.1275) (xy 92.643482 -249.100851) (xy 92.601811 -249.06762)
			(xy 92.565559 -249.028549) (xy 92.535535 -248.984512) (xy 92.512409 -248.936491) (xy 92.496699 -248.885561)
			(xy 92.488756 -248.832857) (xy 92.260176 -248.832857) (xy 92.252233 -248.885561) (xy 92.236523 -248.936491)
			(xy 92.213397 -248.984512) (xy 92.183373 -249.028549) (xy 92.147121 -249.06762) (xy 92.10545 -249.100851)
			(xy 92.059292 -249.1275) (xy 92.009678 -249.146972) (xy 91.957716 -249.158832) (xy 91.904566 -249.162816)
			(xy 91.851416 -249.158832) (xy 91.799454 -249.146972) (xy 91.74984 -249.1275) (xy 91.703682 -249.100851)
			(xy 91.662011 -249.06762) (xy 91.625759 -249.028549) (xy 91.595735 -248.984512) (xy 91.572609 -248.936491)
			(xy 91.556899 -248.885561) (xy 91.548956 -248.832857) (xy 91.320376 -248.832857) (xy 91.312433 -248.885561)
			(xy 91.296723 -248.936491) (xy 91.273597 -248.984512) (xy 91.243573 -249.028549) (xy 91.207321 -249.06762)
			(xy 91.16565 -249.100851) (xy 91.119492 -249.1275) (xy 91.069878 -249.146972) (xy 91.017916 -249.158832)
			(xy 90.964766 -249.162816) (xy 90.911616 -249.158832) (xy 90.859654 -249.146972) (xy 90.81004 -249.1275)
			(xy 90.763882 -249.100851) (xy 90.722211 -249.06762) (xy 90.685959 -249.028549) (xy 90.655935 -248.984512)
			(xy 90.632809 -248.936491) (xy 90.617099 -248.885561) (xy 90.609156 -248.832857) (xy 90.380576 -248.832857)
			(xy 90.372633 -248.885561) (xy 90.356923 -248.936491) (xy 90.333797 -248.984512) (xy 90.303773 -249.028549)
			(xy 90.267521 -249.06762) (xy 90.22585 -249.100851) (xy 90.179692 -249.1275) (xy 90.130078 -249.146972)
			(xy 90.078116 -249.158832) (xy 90.024966 -249.162816) (xy 89.971816 -249.158832) (xy 89.919854 -249.146972)
			(xy 89.87024 -249.1275) (xy 89.824082 -249.100851) (xy 89.782411 -249.06762) (xy 89.746159 -249.028549)
			(xy 89.716135 -248.984512) (xy 89.693009 -248.936491) (xy 89.677299 -248.885561) (xy 89.669356 -248.832857)
			(xy 89.439826 -248.832857) (xy 89.43784 -248.859355) (xy 89.425978 -248.911323) (xy 89.406503 -248.960942)
			(xy 89.379849 -249.007104) (xy 89.346613 -249.048778) (xy 89.307536 -249.085032) (xy 89.263492 -249.115057)
			(xy 89.215465 -249.138181) (xy 89.164528 -249.153889) (xy 89.111818 -249.161829) (xy 89.085166 -249.162316)
			(xy 89.060205 -249.161895) (xy 89.010771 -249.154926) (xy 88.962793 -249.141129) (xy 88.917209 -249.120773)
			(xy 88.874911 -249.094256) (xy 88.85555 -249.078496) (xy 88.844191 -249.069561) (xy 88.817786 -249.057848)
			(xy 88.789157 -249.053998) (xy 88.760596 -249.05832) (xy 88.734388 -249.070468) (xy 88.712631 -249.089469)
			(xy 88.697067 -249.113804) (xy 88.68894 -249.141523) (xy 88.688418 -249.155966) (xy 88.688418 -249.269504)
			(xy 88.723724 -249.280934) (xy 88.74873 -249.289457) (xy 88.796101 -249.312844) (xy 88.839497 -249.342974)
			(xy 88.877964 -249.379185) (xy 88.910659 -249.420682) (xy 88.936864 -249.466554) (xy 88.956004 -249.515795)
			(xy 88.967658 -249.567323) (xy 88.97157 -249.620007) (xy 88.969588 -249.646673) (xy 89.199202 -249.646673)
			(xy 89.199202 -249.593375) (xy 89.207145 -249.540671) (xy 89.222855 -249.489741) (xy 89.245981 -249.44172)
			(xy 89.276005 -249.397683) (xy 89.312257 -249.358612) (xy 89.353928 -249.325381) (xy 89.400086 -249.298732)
			(xy 89.4497 -249.27926) (xy 89.501662 -249.2674) (xy 89.554812 -249.263417) (xy 89.607962 -249.2674)
			(xy 89.659924 -249.27926) (xy 89.709538 -249.298732) (xy 89.755696 -249.325381) (xy 89.797367 -249.358612)
			(xy 89.833619 -249.397683) (xy 89.863643 -249.44172) (xy 89.886769 -249.489741) (xy 89.902479 -249.540671)
			(xy 89.910422 -249.593375) (xy 89.91092 -249.620024) (xy 89.910422 -249.646673) (xy 90.139256 -249.646673)
			(xy 90.139256 -249.593375) (xy 90.147199 -249.540671) (xy 90.162909 -249.489741) (xy 90.186035 -249.44172)
			(xy 90.216059 -249.397683) (xy 90.252311 -249.358612) (xy 90.293982 -249.325381) (xy 90.34014 -249.298732)
			(xy 90.389754 -249.27926) (xy 90.441716 -249.2674) (xy 90.494866 -249.263417) (xy 90.548016 -249.2674)
			(xy 90.599978 -249.27926) (xy 90.649592 -249.298732) (xy 90.69575 -249.325381) (xy 90.737421 -249.358612)
			(xy 90.773673 -249.397683) (xy 90.803697 -249.44172) (xy 90.826823 -249.489741) (xy 90.842533 -249.540671)
			(xy 90.850476 -249.593375) (xy 90.850974 -249.620024) (xy 90.850476 -249.646673) (xy 91.078802 -249.646673)
			(xy 91.078802 -249.593375) (xy 91.086745 -249.540671) (xy 91.102455 -249.489741) (xy 91.125581 -249.44172)
			(xy 91.155605 -249.397683) (xy 91.191857 -249.358612) (xy 91.233528 -249.325381) (xy 91.279686 -249.298732)
			(xy 91.3293 -249.27926) (xy 91.381262 -249.2674) (xy 91.434412 -249.263417) (xy 91.487562 -249.2674)
			(xy 91.539524 -249.27926) (xy 91.589138 -249.298732) (xy 91.635296 -249.325381) (xy 91.676967 -249.358612)
			(xy 91.713219 -249.397683) (xy 91.743243 -249.44172) (xy 91.766369 -249.489741) (xy 91.782079 -249.540671)
			(xy 91.790022 -249.593375) (xy 91.79052 -249.620024) (xy 91.790022 -249.646673) (xy 92.018602 -249.646673)
			(xy 92.018602 -249.593375) (xy 92.026545 -249.540671) (xy 92.042255 -249.489741) (xy 92.065381 -249.44172)
			(xy 92.095405 -249.397683) (xy 92.131657 -249.358612) (xy 92.173328 -249.325381) (xy 92.219486 -249.298732)
			(xy 92.2691 -249.27926) (xy 92.321062 -249.2674) (xy 92.374212 -249.263417) (xy 92.427362 -249.2674)
			(xy 92.479324 -249.27926) (xy 92.528938 -249.298732) (xy 92.575096 -249.325381) (xy 92.616767 -249.358612)
			(xy 92.653019 -249.397683) (xy 92.683043 -249.44172) (xy 92.706169 -249.489741) (xy 92.721879 -249.540671)
			(xy 92.729822 -249.593375) (xy 92.73032 -249.620024) (xy 92.729822 -249.646673) (xy 92.958402 -249.646673)
			(xy 92.958402 -249.593375) (xy 92.966345 -249.540671) (xy 92.982055 -249.489741) (xy 93.005181 -249.44172)
			(xy 93.035205 -249.397683) (xy 93.071457 -249.358612) (xy 93.113128 -249.325381) (xy 93.159286 -249.298732)
			(xy 93.2089 -249.27926) (xy 93.260862 -249.2674) (xy 93.314012 -249.263417) (xy 93.367162 -249.2674)
			(xy 93.419124 -249.27926) (xy 93.468738 -249.298732) (xy 93.514896 -249.325381) (xy 93.556567 -249.358612)
			(xy 93.592819 -249.397683) (xy 93.622843 -249.44172) (xy 93.645969 -249.489741) (xy 93.661679 -249.540671)
			(xy 93.669622 -249.593375) (xy 93.67012 -249.620024) (xy 93.669622 -249.646673) (xy 93.898202 -249.646673)
			(xy 93.898202 -249.593375) (xy 93.906145 -249.540671) (xy 93.921855 -249.489741) (xy 93.944981 -249.44172)
			(xy 93.975005 -249.397683) (xy 94.011257 -249.358612) (xy 94.052928 -249.325381) (xy 94.099086 -249.298732)
			(xy 94.1487 -249.27926) (xy 94.200662 -249.2674) (xy 94.253812 -249.263417) (xy 94.306962 -249.2674)
			(xy 94.358924 -249.27926) (xy 94.408538 -249.298732) (xy 94.454696 -249.325381) (xy 94.496367 -249.358612)
			(xy 94.532619 -249.397683) (xy 94.562643 -249.44172) (xy 94.585769 -249.489741) (xy 94.601479 -249.540671)
			(xy 94.609422 -249.593375) (xy 94.60992 -249.620024) (xy 94.609422 -249.646673) (xy 94.838002 -249.646673)
			(xy 94.838002 -249.593375) (xy 94.845945 -249.540671) (xy 94.861655 -249.489741) (xy 94.884781 -249.44172)
			(xy 94.914805 -249.397683) (xy 94.951057 -249.358612) (xy 94.992728 -249.325381) (xy 95.038886 -249.298732)
			(xy 95.0885 -249.27926) (xy 95.140462 -249.2674) (xy 95.193612 -249.263417) (xy 95.246762 -249.2674)
			(xy 95.298724 -249.27926) (xy 95.348338 -249.298732) (xy 95.394496 -249.325381) (xy 95.436167 -249.358612)
			(xy 95.472419 -249.397683) (xy 95.502443 -249.44172) (xy 95.525569 -249.489741) (xy 95.541279 -249.540671)
			(xy 95.549222 -249.593375) (xy 95.54972 -249.620024) (xy 95.549222 -249.646673) (xy 95.777802 -249.646673)
			(xy 95.777802 -249.593375) (xy 95.785745 -249.540671) (xy 95.801455 -249.489741) (xy 95.824581 -249.44172)
			(xy 95.854605 -249.397683) (xy 95.890857 -249.358612) (xy 95.932528 -249.325381) (xy 95.978686 -249.298732)
			(xy 96.0283 -249.27926) (xy 96.080262 -249.2674) (xy 96.133412 -249.263417) (xy 96.186562 -249.2674)
			(xy 96.238524 -249.27926) (xy 96.288138 -249.298732) (xy 96.334296 -249.325381) (xy 96.375967 -249.358612)
			(xy 96.412219 -249.397683) (xy 96.442243 -249.44172) (xy 96.465369 -249.489741) (xy 96.481079 -249.540671)
			(xy 96.489022 -249.593375) (xy 96.48952 -249.620024) (xy 96.489022 -249.646673) (xy 96.717856 -249.646673)
			(xy 96.717856 -249.593375) (xy 96.725799 -249.540671) (xy 96.741509 -249.489741) (xy 96.764635 -249.44172)
			(xy 96.794659 -249.397683) (xy 96.830911 -249.358612) (xy 96.872582 -249.325381) (xy 96.91874 -249.298732)
			(xy 96.968354 -249.27926) (xy 97.020316 -249.2674) (xy 97.073466 -249.263417) (xy 97.126616 -249.2674)
			(xy 97.178578 -249.27926) (xy 97.228192 -249.298732) (xy 97.27435 -249.325381) (xy 97.316021 -249.358612)
			(xy 97.352273 -249.397683) (xy 97.382297 -249.44172) (xy 97.405423 -249.489741) (xy 97.421133 -249.540671)
			(xy 97.429076 -249.593375) (xy 97.429574 -249.620024) (xy 97.429076 -249.646673) (xy 97.657402 -249.646673)
			(xy 97.657402 -249.593375) (xy 97.665345 -249.540671) (xy 97.681055 -249.489741) (xy 97.704181 -249.44172)
			(xy 97.734205 -249.397683) (xy 97.770457 -249.358612) (xy 97.812128 -249.325381) (xy 97.858286 -249.298732)
			(xy 97.9079 -249.27926) (xy 97.959862 -249.2674) (xy 98.013012 -249.263417) (xy 98.066162 -249.2674)
			(xy 98.118124 -249.27926) (xy 98.167738 -249.298732) (xy 98.213896 -249.325381) (xy 98.255567 -249.358612)
			(xy 98.291819 -249.397683) (xy 98.321843 -249.44172) (xy 98.344969 -249.489741) (xy 98.360679 -249.540671)
			(xy 98.368622 -249.593375) (xy 98.36912 -249.620024) (xy 98.368622 -249.646673) (xy 98.597202 -249.646673)
			(xy 98.597202 -249.593375) (xy 98.605145 -249.540671) (xy 98.620855 -249.489741) (xy 98.643981 -249.44172)
			(xy 98.674005 -249.397683) (xy 98.710257 -249.358612) (xy 98.751928 -249.325381) (xy 98.798086 -249.298732)
			(xy 98.8477 -249.27926) (xy 98.899662 -249.2674) (xy 98.952812 -249.263417) (xy 99.005962 -249.2674)
			(xy 99.057924 -249.27926) (xy 99.107538 -249.298732) (xy 99.153696 -249.325381) (xy 99.195367 -249.358612)
			(xy 99.231619 -249.397683) (xy 99.261643 -249.44172) (xy 99.284769 -249.489741) (xy 99.300479 -249.540671)
			(xy 99.308422 -249.593375) (xy 99.30892 -249.620024) (xy 99.308422 -249.646673) (xy 99.300479 -249.699377)
			(xy 99.284769 -249.750307) (xy 99.261643 -249.798328) (xy 99.231619 -249.842365) (xy 99.195367 -249.881436)
			(xy 99.153696 -249.914667) (xy 99.107538 -249.941316) (xy 99.057924 -249.960788) (xy 99.005962 -249.972648)
			(xy 98.952812 -249.976632) (xy 98.899662 -249.972648) (xy 98.8477 -249.960788) (xy 98.798086 -249.941316)
			(xy 98.751928 -249.914667) (xy 98.710257 -249.881436) (xy 98.674005 -249.842365) (xy 98.643981 -249.798328)
			(xy 98.620855 -249.750307) (xy 98.605145 -249.699377) (xy 98.597202 -249.646673) (xy 98.368622 -249.646673)
			(xy 98.360679 -249.699377) (xy 98.344969 -249.750307) (xy 98.321843 -249.798328) (xy 98.291819 -249.842365)
			(xy 98.255567 -249.881436) (xy 98.213896 -249.914667) (xy 98.167738 -249.941316) (xy 98.118124 -249.960788)
			(xy 98.066162 -249.972648) (xy 98.013012 -249.976632) (xy 97.959862 -249.972648) (xy 97.9079 -249.960788)
			(xy 97.858286 -249.941316) (xy 97.812128 -249.914667) (xy 97.770457 -249.881436) (xy 97.734205 -249.842365)
			(xy 97.704181 -249.798328) (xy 97.681055 -249.750307) (xy 97.665345 -249.699377) (xy 97.657402 -249.646673)
			(xy 97.429076 -249.646673) (xy 97.421133 -249.699377) (xy 97.405423 -249.750307) (xy 97.382297 -249.798328)
			(xy 97.352273 -249.842365) (xy 97.316021 -249.881436) (xy 97.27435 -249.914667) (xy 97.228192 -249.941316)
			(xy 97.178578 -249.960788) (xy 97.126616 -249.972648) (xy 97.073466 -249.976632) (xy 97.020316 -249.972648)
			(xy 96.968354 -249.960788) (xy 96.91874 -249.941316) (xy 96.872582 -249.914667) (xy 96.830911 -249.881436)
			(xy 96.794659 -249.842365) (xy 96.764635 -249.798328) (xy 96.741509 -249.750307) (xy 96.725799 -249.699377)
			(xy 96.717856 -249.646673) (xy 96.489022 -249.646673) (xy 96.481079 -249.699377) (xy 96.465369 -249.750307)
			(xy 96.442243 -249.798328) (xy 96.412219 -249.842365) (xy 96.375967 -249.881436) (xy 96.334296 -249.914667)
			(xy 96.288138 -249.941316) (xy 96.238524 -249.960788) (xy 96.186562 -249.972648) (xy 96.133412 -249.976632)
			(xy 96.080262 -249.972648) (xy 96.0283 -249.960788) (xy 95.978686 -249.941316) (xy 95.932528 -249.914667)
			(xy 95.890857 -249.881436) (xy 95.854605 -249.842365) (xy 95.824581 -249.798328) (xy 95.801455 -249.750307)
			(xy 95.785745 -249.699377) (xy 95.777802 -249.646673) (xy 95.549222 -249.646673) (xy 95.541279 -249.699377)
			(xy 95.525569 -249.750307) (xy 95.502443 -249.798328) (xy 95.472419 -249.842365) (xy 95.436167 -249.881436)
			(xy 95.394496 -249.914667) (xy 95.348338 -249.941316) (xy 95.298724 -249.960788) (xy 95.246762 -249.972648)
			(xy 95.193612 -249.976632) (xy 95.140462 -249.972648) (xy 95.0885 -249.960788) (xy 95.038886 -249.941316)
			(xy 94.992728 -249.914667) (xy 94.951057 -249.881436) (xy 94.914805 -249.842365) (xy 94.884781 -249.798328)
			(xy 94.861655 -249.750307) (xy 94.845945 -249.699377) (xy 94.838002 -249.646673) (xy 94.609422 -249.646673)
			(xy 94.601479 -249.699377) (xy 94.585769 -249.750307) (xy 94.562643 -249.798328) (xy 94.532619 -249.842365)
			(xy 94.496367 -249.881436) (xy 94.454696 -249.914667) (xy 94.408538 -249.941316) (xy 94.358924 -249.960788)
			(xy 94.306962 -249.972648) (xy 94.253812 -249.976632) (xy 94.200662 -249.972648) (xy 94.1487 -249.960788)
			(xy 94.099086 -249.941316) (xy 94.052928 -249.914667) (xy 94.011257 -249.881436) (xy 93.975005 -249.842365)
			(xy 93.944981 -249.798328) (xy 93.921855 -249.750307) (xy 93.906145 -249.699377) (xy 93.898202 -249.646673)
			(xy 93.669622 -249.646673) (xy 93.661679 -249.699377) (xy 93.645969 -249.750307) (xy 93.622843 -249.798328)
			(xy 93.592819 -249.842365) (xy 93.556567 -249.881436) (xy 93.514896 -249.914667) (xy 93.468738 -249.941316)
			(xy 93.419124 -249.960788) (xy 93.367162 -249.972648) (xy 93.314012 -249.976632) (xy 93.260862 -249.972648)
			(xy 93.2089 -249.960788) (xy 93.159286 -249.941316) (xy 93.113128 -249.914667) (xy 93.071457 -249.881436)
			(xy 93.035205 -249.842365) (xy 93.005181 -249.798328) (xy 92.982055 -249.750307) (xy 92.966345 -249.699377)
			(xy 92.958402 -249.646673) (xy 92.729822 -249.646673) (xy 92.721879 -249.699377) (xy 92.706169 -249.750307)
			(xy 92.683043 -249.798328) (xy 92.653019 -249.842365) (xy 92.616767 -249.881436) (xy 92.575096 -249.914667)
			(xy 92.528938 -249.941316) (xy 92.479324 -249.960788) (xy 92.427362 -249.972648) (xy 92.374212 -249.976632)
			(xy 92.321062 -249.972648) (xy 92.2691 -249.960788) (xy 92.219486 -249.941316) (xy 92.173328 -249.914667)
			(xy 92.131657 -249.881436) (xy 92.095405 -249.842365) (xy 92.065381 -249.798328) (xy 92.042255 -249.750307)
			(xy 92.026545 -249.699377) (xy 92.018602 -249.646673) (xy 91.790022 -249.646673) (xy 91.782079 -249.699377)
			(xy 91.766369 -249.750307) (xy 91.743243 -249.798328) (xy 91.713219 -249.842365) (xy 91.676967 -249.881436)
			(xy 91.635296 -249.914667) (xy 91.589138 -249.941316) (xy 91.539524 -249.960788) (xy 91.487562 -249.972648)
			(xy 91.434412 -249.976632) (xy 91.381262 -249.972648) (xy 91.3293 -249.960788) (xy 91.279686 -249.941316)
			(xy 91.233528 -249.914667) (xy 91.191857 -249.881436) (xy 91.155605 -249.842365) (xy 91.125581 -249.798328)
			(xy 91.102455 -249.750307) (xy 91.086745 -249.699377) (xy 91.078802 -249.646673) (xy 90.850476 -249.646673)
			(xy 90.842533 -249.699377) (xy 90.826823 -249.750307) (xy 90.803697 -249.798328) (xy 90.773673 -249.842365)
			(xy 90.737421 -249.881436) (xy 90.69575 -249.914667) (xy 90.649592 -249.941316) (xy 90.599978 -249.960788)
			(xy 90.548016 -249.972648) (xy 90.494866 -249.976632) (xy 90.441716 -249.972648) (xy 90.389754 -249.960788)
			(xy 90.34014 -249.941316) (xy 90.293982 -249.914667) (xy 90.252311 -249.881436) (xy 90.216059 -249.842365)
			(xy 90.186035 -249.798328) (xy 90.162909 -249.750307) (xy 90.147199 -249.699377) (xy 90.139256 -249.646673)
			(xy 89.910422 -249.646673) (xy 89.902479 -249.699377) (xy 89.886769 -249.750307) (xy 89.863643 -249.798328)
			(xy 89.833619 -249.842365) (xy 89.797367 -249.881436) (xy 89.755696 -249.914667) (xy 89.709538 -249.941316)
			(xy 89.659924 -249.960788) (xy 89.607962 -249.972648) (xy 89.554812 -249.976632) (xy 89.501662 -249.972648)
			(xy 89.4497 -249.960788) (xy 89.400086 -249.941316) (xy 89.353928 -249.914667) (xy 89.312257 -249.881436)
			(xy 89.276005 -249.842365) (xy 89.245981 -249.798328) (xy 89.222855 -249.750307) (xy 89.207145 -249.699377)
			(xy 89.199202 -249.646673) (xy 88.969588 -249.646673) (xy 88.967655 -249.672692) (xy 88.955999 -249.724219)
			(xy 88.936858 -249.773459) (xy 88.910651 -249.81933) (xy 88.877955 -249.860826) (xy 88.839486 -249.897035)
			(xy 88.796089 -249.927163) (xy 88.748717 -249.950548) (xy 88.723724 -249.959114) (xy 88.688418 -249.970544)
			(xy 88.688418 -253.132569) (xy 94.94773 -253.132569) (xy 94.94773 -253.079271) (xy 94.955673 -253.026567)
			(xy 94.971383 -252.975637) (xy 94.994509 -252.927616) (xy 95.024533 -252.883579) (xy 95.060785 -252.844508)
			(xy 95.102456 -252.811277) (xy 95.148614 -252.784628) (xy 95.198228 -252.765156) (xy 95.25019 -252.753296)
			(xy 95.30334 -252.749313) (xy 95.35649 -252.753296) (xy 95.408452 -252.765156) (xy 95.458066 -252.784628)
			(xy 95.504224 -252.811277) (xy 95.545895 -252.844508) (xy 95.582147 -252.883579) (xy 95.612171 -252.927616)
			(xy 95.635297 -252.975637) (xy 95.651007 -253.026567) (xy 95.65895 -253.079271) (xy 95.659448 -253.10592)
			(xy 95.65895 -253.132569) (xy 95.651007 -253.185273) (xy 95.635297 -253.236203) (xy 95.612171 -253.284224)
			(xy 95.582147 -253.328261) (xy 95.545895 -253.367332) (xy 95.504224 -253.400563) (xy 95.458066 -253.427212)
			(xy 95.408452 -253.446684) (xy 95.35649 -253.458544) (xy 95.30334 -253.462528) (xy 95.25019 -253.458544)
			(xy 95.198228 -253.446684) (xy 95.148614 -253.427212) (xy 95.102456 -253.400563) (xy 95.060785 -253.367332)
			(xy 95.024533 -253.328261) (xy 94.994509 -253.284224) (xy 94.971383 -253.236203) (xy 94.955673 -253.185273)
			(xy 94.94773 -253.132569) (xy 88.688418 -253.132569) (xy 88.688418 -253.946385) (xy 88.839284 -253.946385)
			(xy 88.839284 -253.893087) (xy 88.847227 -253.840383) (xy 88.862937 -253.789453) (xy 88.886063 -253.741432)
			(xy 88.916087 -253.697395) (xy 88.952339 -253.658324) (xy 88.99401 -253.625093) (xy 89.040168 -253.598444)
			(xy 89.089782 -253.578972) (xy 89.141744 -253.567112) (xy 89.194894 -253.563129) (xy 89.248044 -253.567112)
			(xy 89.300006 -253.578972) (xy 89.34962 -253.598444) (xy 89.395778 -253.625093) (xy 89.437449 -253.658324)
			(xy 89.473701 -253.697395) (xy 89.503725 -253.741432) (xy 89.526851 -253.789453) (xy 89.542561 -253.840383)
			(xy 89.550504 -253.893087) (xy 89.551002 -253.919736) (xy 89.550504 -253.946385) (xy 89.779084 -253.946385)
			(xy 89.779084 -253.893087) (xy 89.787027 -253.840383) (xy 89.802737 -253.789453) (xy 89.825863 -253.741432)
			(xy 89.855887 -253.697395) (xy 89.892139 -253.658324) (xy 89.93381 -253.625093) (xy 89.979968 -253.598444)
			(xy 90.029582 -253.578972) (xy 90.081544 -253.567112) (xy 90.134694 -253.563129) (xy 90.187844 -253.567112)
			(xy 90.239806 -253.578972) (xy 90.28942 -253.598444) (xy 90.335578 -253.625093) (xy 90.377249 -253.658324)
			(xy 90.413501 -253.697395) (xy 90.443525 -253.741432) (xy 90.466651 -253.789453) (xy 90.482361 -253.840383)
			(xy 90.490304 -253.893087) (xy 90.490802 -253.919736) (xy 90.490304 -253.946385) (xy 90.719138 -253.946385)
			(xy 90.719138 -253.893087) (xy 90.727081 -253.840383) (xy 90.742791 -253.789453) (xy 90.765917 -253.741432)
			(xy 90.795941 -253.697395) (xy 90.832193 -253.658324) (xy 90.873864 -253.625093) (xy 90.920022 -253.598444)
			(xy 90.969636 -253.578972) (xy 91.021598 -253.567112) (xy 91.074748 -253.563129) (xy 91.127898 -253.567112)
			(xy 91.17986 -253.578972) (xy 91.229474 -253.598444) (xy 91.275632 -253.625093) (xy 91.317303 -253.658324)
			(xy 91.353555 -253.697395) (xy 91.383579 -253.741432) (xy 91.406705 -253.789453) (xy 91.422415 -253.840383)
			(xy 91.430358 -253.893087) (xy 91.430856 -253.919736) (xy 91.430358 -253.946385) (xy 91.658938 -253.946385)
			(xy 91.658938 -253.893087) (xy 91.666881 -253.840383) (xy 91.682591 -253.789453) (xy 91.705717 -253.741432)
			(xy 91.735741 -253.697395) (xy 91.771993 -253.658324) (xy 91.813664 -253.625093) (xy 91.859822 -253.598444)
			(xy 91.909436 -253.578972) (xy 91.961398 -253.567112) (xy 92.014548 -253.563129) (xy 92.067698 -253.567112)
			(xy 92.11966 -253.578972) (xy 92.169274 -253.598444) (xy 92.215432 -253.625093) (xy 92.257103 -253.658324)
			(xy 92.293355 -253.697395) (xy 92.323379 -253.741432) (xy 92.346505 -253.789453) (xy 92.362215 -253.840383)
			(xy 92.370158 -253.893087) (xy 92.370656 -253.919736) (xy 92.370158 -253.946385) (xy 92.598738 -253.946385)
			(xy 92.598738 -253.893087) (xy 92.606681 -253.840383) (xy 92.622391 -253.789453) (xy 92.645517 -253.741432)
			(xy 92.675541 -253.697395) (xy 92.711793 -253.658324) (xy 92.753464 -253.625093) (xy 92.799622 -253.598444)
			(xy 92.849236 -253.578972) (xy 92.901198 -253.567112) (xy 92.954348 -253.563129) (xy 93.007498 -253.567112)
			(xy 93.05946 -253.578972) (xy 93.109074 -253.598444) (xy 93.155232 -253.625093) (xy 93.196903 -253.658324)
			(xy 93.233155 -253.697395) (xy 93.263179 -253.741432) (xy 93.286305 -253.789453) (xy 93.302015 -253.840383)
			(xy 93.309958 -253.893087) (xy 93.310456 -253.919736) (xy 93.309958 -253.946385) (xy 93.538538 -253.946385)
			(xy 93.538538 -253.893087) (xy 93.546481 -253.840383) (xy 93.562191 -253.789453) (xy 93.585317 -253.741432)
			(xy 93.615341 -253.697395) (xy 93.651593 -253.658324) (xy 93.693264 -253.625093) (xy 93.739422 -253.598444)
			(xy 93.789036 -253.578972) (xy 93.840998 -253.567112) (xy 93.894148 -253.563129) (xy 93.947298 -253.567112)
			(xy 93.99926 -253.578972) (xy 94.048874 -253.598444) (xy 94.095032 -253.625093) (xy 94.136703 -253.658324)
			(xy 94.172955 -253.697395) (xy 94.202979 -253.741432) (xy 94.226105 -253.789453) (xy 94.241815 -253.840383)
			(xy 94.249758 -253.893087) (xy 94.250256 -253.919736) (xy 94.249758 -253.946385) (xy 94.478084 -253.946385)
			(xy 94.478084 -253.893087) (xy 94.486027 -253.840383) (xy 94.501737 -253.789453) (xy 94.524863 -253.741432)
			(xy 94.554887 -253.697395) (xy 94.591139 -253.658324) (xy 94.63281 -253.625093) (xy 94.678968 -253.598444)
			(xy 94.728582 -253.578972) (xy 94.780544 -253.567112) (xy 94.833694 -253.563129) (xy 94.886844 -253.567112)
			(xy 94.938806 -253.578972) (xy 94.98842 -253.598444) (xy 95.034578 -253.625093) (xy 95.076249 -253.658324)
			(xy 95.112501 -253.697395) (xy 95.142525 -253.741432) (xy 95.165651 -253.789453) (xy 95.181361 -253.840383)
			(xy 95.189304 -253.893087) (xy 95.189802 -253.919736) (xy 95.189304 -253.946385) (xy 95.418138 -253.946385)
			(xy 95.418138 -253.893087) (xy 95.426081 -253.840383) (xy 95.441791 -253.789453) (xy 95.464917 -253.741432)
			(xy 95.494941 -253.697395) (xy 95.531193 -253.658324) (xy 95.572864 -253.625093) (xy 95.619022 -253.598444)
			(xy 95.668636 -253.578972) (xy 95.720598 -253.567112) (xy 95.773748 -253.563129) (xy 95.826898 -253.567112)
			(xy 95.87886 -253.578972) (xy 95.928474 -253.598444) (xy 95.974632 -253.625093) (xy 96.016303 -253.658324)
			(xy 96.052555 -253.697395) (xy 96.082579 -253.741432) (xy 96.105705 -253.789453) (xy 96.121415 -253.840383)
			(xy 96.129358 -253.893087) (xy 96.129856 -253.919736) (xy 96.129358 -253.946385) (xy 96.357938 -253.946385)
			(xy 96.357938 -253.893087) (xy 96.365881 -253.840383) (xy 96.381591 -253.789453) (xy 96.404717 -253.741432)
			(xy 96.434741 -253.697395) (xy 96.470993 -253.658324) (xy 96.512664 -253.625093) (xy 96.558822 -253.598444)
			(xy 96.608436 -253.578972) (xy 96.660398 -253.567112) (xy 96.713548 -253.563129) (xy 96.766698 -253.567112)
			(xy 96.81866 -253.578972) (xy 96.868274 -253.598444) (xy 96.914432 -253.625093) (xy 96.956103 -253.658324)
			(xy 96.992355 -253.697395) (xy 97.022379 -253.741432) (xy 97.045505 -253.789453) (xy 97.061215 -253.840383)
			(xy 97.069158 -253.893087) (xy 97.069656 -253.919736) (xy 97.069158 -253.946385) (xy 97.297738 -253.946385)
			(xy 97.297738 -253.893087) (xy 97.305681 -253.840383) (xy 97.321391 -253.789453) (xy 97.344517 -253.741432)
			(xy 97.374541 -253.697395) (xy 97.410793 -253.658324) (xy 97.452464 -253.625093) (xy 97.498622 -253.598444)
			(xy 97.548236 -253.578972) (xy 97.600198 -253.567112) (xy 97.653348 -253.563129) (xy 97.706498 -253.567112)
			(xy 97.75846 -253.578972) (xy 97.808074 -253.598444) (xy 97.854232 -253.625093) (xy 97.895903 -253.658324)
			(xy 97.932155 -253.697395) (xy 97.962179 -253.741432) (xy 97.985305 -253.789453) (xy 98.001015 -253.840383)
			(xy 98.008958 -253.893087) (xy 98.009456 -253.919736) (xy 98.008958 -253.946385) (xy 98.237538 -253.946385)
			(xy 98.237538 -253.893087) (xy 98.245481 -253.840383) (xy 98.261191 -253.789453) (xy 98.284317 -253.741432)
			(xy 98.314341 -253.697395) (xy 98.350593 -253.658324) (xy 98.392264 -253.625093) (xy 98.438422 -253.598444)
			(xy 98.488036 -253.578972) (xy 98.539998 -253.567112) (xy 98.593148 -253.563129) (xy 98.646298 -253.567112)
			(xy 98.69826 -253.578972) (xy 98.747874 -253.598444) (xy 98.794032 -253.625093) (xy 98.835703 -253.658324)
			(xy 98.871955 -253.697395) (xy 98.901979 -253.741432) (xy 98.925105 -253.789453) (xy 98.940815 -253.840383)
			(xy 98.948758 -253.893087) (xy 98.949256 -253.919736) (xy 98.948758 -253.946385) (xy 98.940815 -253.999089)
			(xy 98.925105 -254.050019) (xy 98.901979 -254.09804) (xy 98.871955 -254.142077) (xy 98.835703 -254.181148)
			(xy 98.794032 -254.214379) (xy 98.747874 -254.241028) (xy 98.69826 -254.2605) (xy 98.646298 -254.27236)
			(xy 98.593148 -254.276344) (xy 98.539998 -254.27236) (xy 98.488036 -254.2605) (xy 98.438422 -254.241028)
			(xy 98.392264 -254.214379) (xy 98.350593 -254.181148) (xy 98.314341 -254.142077) (xy 98.284317 -254.09804)
			(xy 98.261191 -254.050019) (xy 98.245481 -253.999089) (xy 98.237538 -253.946385) (xy 98.008958 -253.946385)
			(xy 98.001015 -253.999089) (xy 97.985305 -254.050019) (xy 97.962179 -254.09804) (xy 97.932155 -254.142077)
			(xy 97.895903 -254.181148) (xy 97.854232 -254.214379) (xy 97.808074 -254.241028) (xy 97.75846 -254.2605)
			(xy 97.706498 -254.27236) (xy 97.653348 -254.276344) (xy 97.600198 -254.27236) (xy 97.548236 -254.2605)
			(xy 97.498622 -254.241028) (xy 97.452464 -254.214379) (xy 97.410793 -254.181148) (xy 97.374541 -254.142077)
			(xy 97.344517 -254.09804) (xy 97.321391 -254.050019) (xy 97.305681 -253.999089) (xy 97.297738 -253.946385)
			(xy 97.069158 -253.946385) (xy 97.061215 -253.999089) (xy 97.045505 -254.050019) (xy 97.022379 -254.09804)
			(xy 96.992355 -254.142077) (xy 96.956103 -254.181148) (xy 96.914432 -254.214379) (xy 96.868274 -254.241028)
			(xy 96.81866 -254.2605) (xy 96.766698 -254.27236) (xy 96.713548 -254.276344) (xy 96.660398 -254.27236)
			(xy 96.608436 -254.2605) (xy 96.558822 -254.241028) (xy 96.512664 -254.214379) (xy 96.470993 -254.181148)
			(xy 96.434741 -254.142077) (xy 96.404717 -254.09804) (xy 96.381591 -254.050019) (xy 96.365881 -253.999089)
			(xy 96.357938 -253.946385) (xy 96.129358 -253.946385) (xy 96.121415 -253.999089) (xy 96.105705 -254.050019)
			(xy 96.082579 -254.09804) (xy 96.052555 -254.142077) (xy 96.016303 -254.181148) (xy 95.974632 -254.214379)
			(xy 95.928474 -254.241028) (xy 95.87886 -254.2605) (xy 95.826898 -254.27236) (xy 95.773748 -254.276344)
			(xy 95.720598 -254.27236) (xy 95.668636 -254.2605) (xy 95.619022 -254.241028) (xy 95.572864 -254.214379)
			(xy 95.531193 -254.181148) (xy 95.494941 -254.142077) (xy 95.464917 -254.09804) (xy 95.441791 -254.050019)
			(xy 95.426081 -253.999089) (xy 95.418138 -253.946385) (xy 95.189304 -253.946385) (xy 95.181361 -253.999089)
			(xy 95.165651 -254.050019) (xy 95.142525 -254.09804) (xy 95.112501 -254.142077) (xy 95.076249 -254.181148)
			(xy 95.034578 -254.214379) (xy 94.98842 -254.241028) (xy 94.938806 -254.2605) (xy 94.886844 -254.27236)
			(xy 94.833694 -254.276344) (xy 94.780544 -254.27236) (xy 94.728582 -254.2605) (xy 94.678968 -254.241028)
			(xy 94.63281 -254.214379) (xy 94.591139 -254.181148) (xy 94.554887 -254.142077) (xy 94.524863 -254.09804)
			(xy 94.501737 -254.050019) (xy 94.486027 -253.999089) (xy 94.478084 -253.946385) (xy 94.249758 -253.946385)
			(xy 94.241815 -253.999089) (xy 94.226105 -254.050019) (xy 94.202979 -254.09804) (xy 94.172955 -254.142077)
			(xy 94.136703 -254.181148) (xy 94.095032 -254.214379) (xy 94.048874 -254.241028) (xy 93.99926 -254.2605)
			(xy 93.947298 -254.27236) (xy 93.894148 -254.276344) (xy 93.840998 -254.27236) (xy 93.789036 -254.2605)
			(xy 93.739422 -254.241028) (xy 93.693264 -254.214379) (xy 93.651593 -254.181148) (xy 93.615341 -254.142077)
			(xy 93.585317 -254.09804) (xy 93.562191 -254.050019) (xy 93.546481 -253.999089) (xy 93.538538 -253.946385)
			(xy 93.309958 -253.946385) (xy 93.302015 -253.999089) (xy 93.286305 -254.050019) (xy 93.263179 -254.09804)
			(xy 93.233155 -254.142077) (xy 93.196903 -254.181148) (xy 93.155232 -254.214379) (xy 93.109074 -254.241028)
			(xy 93.05946 -254.2605) (xy 93.007498 -254.27236) (xy 92.954348 -254.276344) (xy 92.901198 -254.27236)
			(xy 92.849236 -254.2605) (xy 92.799622 -254.241028) (xy 92.753464 -254.214379) (xy 92.711793 -254.181148)
			(xy 92.675541 -254.142077) (xy 92.645517 -254.09804) (xy 92.622391 -254.050019) (xy 92.606681 -253.999089)
			(xy 92.598738 -253.946385) (xy 92.370158 -253.946385) (xy 92.362215 -253.999089) (xy 92.346505 -254.050019)
			(xy 92.323379 -254.09804) (xy 92.293355 -254.142077) (xy 92.257103 -254.181148) (xy 92.215432 -254.214379)
			(xy 92.169274 -254.241028) (xy 92.11966 -254.2605) (xy 92.067698 -254.27236) (xy 92.014548 -254.276344)
			(xy 91.961398 -254.27236) (xy 91.909436 -254.2605) (xy 91.859822 -254.241028) (xy 91.813664 -254.214379)
			(xy 91.771993 -254.181148) (xy 91.735741 -254.142077) (xy 91.705717 -254.09804) (xy 91.682591 -254.050019)
			(xy 91.666881 -253.999089) (xy 91.658938 -253.946385) (xy 91.430358 -253.946385) (xy 91.422415 -253.999089)
			(xy 91.406705 -254.050019) (xy 91.383579 -254.09804) (xy 91.353555 -254.142077) (xy 91.317303 -254.181148)
			(xy 91.275632 -254.214379) (xy 91.229474 -254.241028) (xy 91.17986 -254.2605) (xy 91.127898 -254.27236)
			(xy 91.074748 -254.276344) (xy 91.021598 -254.27236) (xy 90.969636 -254.2605) (xy 90.920022 -254.241028)
			(xy 90.873864 -254.214379) (xy 90.832193 -254.181148) (xy 90.795941 -254.142077) (xy 90.765917 -254.09804)
			(xy 90.742791 -254.050019) (xy 90.727081 -253.999089) (xy 90.719138 -253.946385) (xy 90.490304 -253.946385)
			(xy 90.482361 -253.999089) (xy 90.466651 -254.050019) (xy 90.443525 -254.09804) (xy 90.413501 -254.142077)
			(xy 90.377249 -254.181148) (xy 90.335578 -254.214379) (xy 90.28942 -254.241028) (xy 90.239806 -254.2605)
			(xy 90.187844 -254.27236) (xy 90.134694 -254.276344) (xy 90.081544 -254.27236) (xy 90.029582 -254.2605)
			(xy 89.979968 -254.241028) (xy 89.93381 -254.214379) (xy 89.892139 -254.181148) (xy 89.855887 -254.142077)
			(xy 89.825863 -254.09804) (xy 89.802737 -254.050019) (xy 89.787027 -253.999089) (xy 89.779084 -253.946385)
			(xy 89.550504 -253.946385) (xy 89.542561 -253.999089) (xy 89.526851 -254.050019) (xy 89.503725 -254.09804)
			(xy 89.473701 -254.142077) (xy 89.437449 -254.181148) (xy 89.395778 -254.214379) (xy 89.34962 -254.241028)
			(xy 89.300006 -254.2605) (xy 89.248044 -254.27236) (xy 89.194894 -254.276344) (xy 89.141744 -254.27236)
			(xy 89.089782 -254.2605) (xy 89.040168 -254.241028) (xy 88.99401 -254.214379) (xy 88.952339 -254.181148)
			(xy 88.916087 -254.142077) (xy 88.886063 -254.09804) (xy 88.862937 -254.050019) (xy 88.847227 -253.999089)
			(xy 88.839284 -253.946385) (xy 88.688418 -253.946385) (xy 88.688418 -254.326898) (xy 88.688861 -254.336691)
			(xy 88.69619 -254.354855) (xy 88.709784 -254.368957) (xy 88.727668 -254.376946) (xy 88.73744 -254.377698)
			(xy 88.764769 -254.379154) (xy 88.818524 -254.38941) (xy 88.870078 -254.407769) (xy 88.918217 -254.433799)
			(xy 88.961807 -254.466887) (xy 88.999822 -254.506253) (xy 89.031367 -254.550972) (xy 89.055699 -254.599991)
			(xy 89.072246 -254.652154) (xy 89.080619 -254.706236) (xy 89.080619 -254.760201) (xy 89.309184 -254.760201)
			(xy 89.309184 -254.706903) (xy 89.317127 -254.654199) (xy 89.332837 -254.603269) (xy 89.355963 -254.555248)
			(xy 89.385987 -254.511211) (xy 89.422239 -254.47214) (xy 89.46391 -254.438909) (xy 89.510068 -254.41226)
			(xy 89.559682 -254.392788) (xy 89.611644 -254.380928) (xy 89.664794 -254.376945) (xy 89.717944 -254.380928)
			(xy 89.769906 -254.392788) (xy 89.81952 -254.41226) (xy 89.865678 -254.438909) (xy 89.907349 -254.47214)
			(xy 89.943601 -254.511211) (xy 89.973625 -254.555248) (xy 89.996751 -254.603269) (xy 90.012461 -254.654199)
			(xy 90.020404 -254.706903) (xy 90.020902 -254.733552) (xy 90.020404 -254.760201) (xy 90.248984 -254.760201)
			(xy 90.248984 -254.706903) (xy 90.256927 -254.654199) (xy 90.272637 -254.603269) (xy 90.295763 -254.555248)
			(xy 90.325787 -254.511211) (xy 90.362039 -254.47214) (xy 90.40371 -254.438909) (xy 90.449868 -254.41226)
			(xy 90.499482 -254.392788) (xy 90.551444 -254.380928) (xy 90.604594 -254.376945) (xy 90.657744 -254.380928)
			(xy 90.709706 -254.392788) (xy 90.75932 -254.41226) (xy 90.805478 -254.438909) (xy 90.847149 -254.47214)
			(xy 90.883401 -254.511211) (xy 90.913425 -254.555248) (xy 90.936551 -254.603269) (xy 90.952261 -254.654199)
			(xy 90.960204 -254.706903) (xy 90.960702 -254.733552) (xy 90.960204 -254.760201) (xy 91.189038 -254.760201)
			(xy 91.189038 -254.706903) (xy 91.196981 -254.654199) (xy 91.212691 -254.603269) (xy 91.235817 -254.555248)
			(xy 91.265841 -254.511211) (xy 91.302093 -254.47214) (xy 91.343764 -254.438909) (xy 91.389922 -254.41226)
			(xy 91.439536 -254.392788) (xy 91.491498 -254.380928) (xy 91.544648 -254.376945) (xy 91.597798 -254.380928)
			(xy 91.64976 -254.392788) (xy 91.699374 -254.41226) (xy 91.745532 -254.438909) (xy 91.787203 -254.47214)
			(xy 91.823455 -254.511211) (xy 91.853479 -254.555248) (xy 91.876605 -254.603269) (xy 91.892315 -254.654199)
			(xy 91.900258 -254.706903) (xy 91.900756 -254.733552) (xy 91.900258 -254.760201) (xy 92.128584 -254.760201)
			(xy 92.128584 -254.706903) (xy 92.136527 -254.654199) (xy 92.152237 -254.603269) (xy 92.175363 -254.555248)
			(xy 92.205387 -254.511211) (xy 92.241639 -254.47214) (xy 92.28331 -254.438909) (xy 92.329468 -254.41226)
			(xy 92.379082 -254.392788) (xy 92.431044 -254.380928) (xy 92.484194 -254.376945) (xy 92.537344 -254.380928)
			(xy 92.589306 -254.392788) (xy 92.63892 -254.41226) (xy 92.685078 -254.438909) (xy 92.726749 -254.47214)
			(xy 92.763001 -254.511211) (xy 92.793025 -254.555248) (xy 92.816151 -254.603269) (xy 92.831861 -254.654199)
			(xy 92.839804 -254.706903) (xy 92.840302 -254.733552) (xy 93.080081 -254.733552) (xy 93.084111 -254.681054)
			(xy 93.096108 -254.629786) (xy 93.115791 -254.580951) (xy 93.142697 -254.535692) (xy 93.176197 -254.495071)
			(xy 93.215505 -254.46004) (xy 93.2597 -254.43142) (xy 93.307745 -254.409881) (xy 93.358516 -254.395929)
			(xy 93.410821 -254.389891) (xy 93.463435 -254.391908) (xy 93.515125 -254.401932) (xy 93.564678 -254.41973)
			(xy 93.610934 -254.444883) (xy 93.652808 -254.476802) (xy 93.68932 -254.51474) (xy 93.719612 -254.557806)
			(xy 93.742975 -254.604991) (xy 93.758861 -254.65519) (xy 93.766898 -254.707226) (xy 93.767402 -254.733552)
			(xy 94.019881 -254.733552) (xy 94.023911 -254.681054) (xy 94.035908 -254.629786) (xy 94.055591 -254.580951)
			(xy 94.082497 -254.535692) (xy 94.115997 -254.495071) (xy 94.155305 -254.46004) (xy 94.1995 -254.43142)
			(xy 94.247545 -254.409881) (xy 94.298316 -254.395929) (xy 94.350621 -254.389891) (xy 94.403235 -254.391908)
			(xy 94.454925 -254.401932) (xy 94.504478 -254.41973) (xy 94.550734 -254.444883) (xy 94.592608 -254.476802)
			(xy 94.62912 -254.51474) (xy 94.659412 -254.557806) (xy 94.682775 -254.604991) (xy 94.698661 -254.65519)
			(xy 94.706698 -254.707226) (xy 94.707202 -254.733552) (xy 94.706698 -254.759878) (xy 94.706648 -254.760201)
			(xy 94.947984 -254.760201) (xy 94.947984 -254.706903) (xy 94.955927 -254.654199) (xy 94.971637 -254.603269)
			(xy 94.994763 -254.555248) (xy 95.024787 -254.511211) (xy 95.061039 -254.47214) (xy 95.10271 -254.438909)
			(xy 95.148868 -254.41226) (xy 95.198482 -254.392788) (xy 95.250444 -254.380928) (xy 95.303594 -254.376945)
			(xy 95.356744 -254.380928) (xy 95.408706 -254.392788) (xy 95.45832 -254.41226) (xy 95.504478 -254.438909)
			(xy 95.546149 -254.47214) (xy 95.582401 -254.511211) (xy 95.612425 -254.555248) (xy 95.635551 -254.603269)
			(xy 95.651261 -254.654199) (xy 95.659204 -254.706903) (xy 95.659702 -254.733552) (xy 95.659204 -254.760201)
			(xy 95.887784 -254.760201) (xy 95.887784 -254.706903) (xy 95.895727 -254.654199) (xy 95.911437 -254.603269)
			(xy 95.934563 -254.555248) (xy 95.964587 -254.511211) (xy 96.000839 -254.47214) (xy 96.04251 -254.438909)
			(xy 96.088668 -254.41226) (xy 96.138282 -254.392788) (xy 96.190244 -254.380928) (xy 96.243394 -254.376945)
			(xy 96.296544 -254.380928) (xy 96.348506 -254.392788) (xy 96.39812 -254.41226) (xy 96.444278 -254.438909)
			(xy 96.485949 -254.47214) (xy 96.522201 -254.511211) (xy 96.552225 -254.555248) (xy 96.575351 -254.603269)
			(xy 96.591061 -254.654199) (xy 96.599004 -254.706903) (xy 96.599502 -254.733552) (xy 96.599004 -254.760201)
			(xy 96.827584 -254.760201) (xy 96.827584 -254.706903) (xy 96.835527 -254.654199) (xy 96.851237 -254.603269)
			(xy 96.874363 -254.555248) (xy 96.904387 -254.511211) (xy 96.940639 -254.47214) (xy 96.98231 -254.438909)
			(xy 97.028468 -254.41226) (xy 97.078082 -254.392788) (xy 97.130044 -254.380928) (xy 97.183194 -254.376945)
			(xy 97.236344 -254.380928) (xy 97.288306 -254.392788) (xy 97.33792 -254.41226) (xy 97.384078 -254.438909)
			(xy 97.425749 -254.47214) (xy 97.462001 -254.511211) (xy 97.492025 -254.555248) (xy 97.515151 -254.603269)
			(xy 97.530861 -254.654199) (xy 97.538804 -254.706903) (xy 97.539302 -254.733552) (xy 97.538804 -254.760201)
			(xy 97.767638 -254.760201) (xy 97.767638 -254.706903) (xy 97.775581 -254.654199) (xy 97.791291 -254.603269)
			(xy 97.814417 -254.555248) (xy 97.844441 -254.511211) (xy 97.880693 -254.47214) (xy 97.922364 -254.438909)
			(xy 97.968522 -254.41226) (xy 98.018136 -254.392788) (xy 98.070098 -254.380928) (xy 98.123248 -254.376945)
			(xy 98.176398 -254.380928) (xy 98.22836 -254.392788) (xy 98.277974 -254.41226) (xy 98.324132 -254.438909)
			(xy 98.365803 -254.47214) (xy 98.402055 -254.511211) (xy 98.432079 -254.555248) (xy 98.455205 -254.603269)
			(xy 98.470915 -254.654199) (xy 98.478858 -254.706903) (xy 98.479356 -254.733552) (xy 98.478858 -254.760201)
			(xy 98.707184 -254.760201) (xy 98.707184 -254.706903) (xy 98.715127 -254.654199) (xy 98.730837 -254.603269)
			(xy 98.753963 -254.555248) (xy 98.783987 -254.511211) (xy 98.820239 -254.47214) (xy 98.86191 -254.438909)
			(xy 98.908068 -254.41226) (xy 98.957682 -254.392788) (xy 99.009644 -254.380928) (xy 99.062794 -254.376945)
			(xy 99.115944 -254.380928) (xy 99.167906 -254.392788) (xy 99.21752 -254.41226) (xy 99.263678 -254.438909)
			(xy 99.305349 -254.47214) (xy 99.341601 -254.511211) (xy 99.371625 -254.555248) (xy 99.394751 -254.603269)
			(xy 99.410461 -254.654199) (xy 99.418404 -254.706903) (xy 99.418902 -254.733552) (xy 99.418404 -254.760201)
			(xy 99.410461 -254.812905) (xy 99.394751 -254.863835) (xy 99.371625 -254.911856) (xy 99.341601 -254.955893)
			(xy 99.305349 -254.994964) (xy 99.263678 -255.028195) (xy 99.21752 -255.054844) (xy 99.167906 -255.074316)
			(xy 99.115944 -255.086176) (xy 99.062794 -255.09016) (xy 99.009644 -255.086176) (xy 98.957682 -255.074316)
			(xy 98.908068 -255.054844) (xy 98.86191 -255.028195) (xy 98.820239 -254.994964) (xy 98.783987 -254.955893)
			(xy 98.753963 -254.911856) (xy 98.730837 -254.863835) (xy 98.715127 -254.812905) (xy 98.707184 -254.760201)
			(xy 98.478858 -254.760201) (xy 98.470915 -254.812905) (xy 98.455205 -254.863835) (xy 98.432079 -254.911856)
			(xy 98.402055 -254.955893) (xy 98.365803 -254.994964) (xy 98.324132 -255.028195) (xy 98.277974 -255.054844)
			(xy 98.22836 -255.074316) (xy 98.176398 -255.086176) (xy 98.123248 -255.09016) (xy 98.070098 -255.086176)
			(xy 98.018136 -255.074316) (xy 97.968522 -255.054844) (xy 97.922364 -255.028195) (xy 97.880693 -254.994964)
			(xy 97.844441 -254.955893) (xy 97.814417 -254.911856) (xy 97.791291 -254.863835) (xy 97.775581 -254.812905)
			(xy 97.767638 -254.760201) (xy 97.538804 -254.760201) (xy 97.530861 -254.812905) (xy 97.515151 -254.863835)
			(xy 97.492025 -254.911856) (xy 97.462001 -254.955893) (xy 97.425749 -254.994964) (xy 97.384078 -255.028195)
			(xy 97.33792 -255.054844) (xy 97.288306 -255.074316) (xy 97.236344 -255.086176) (xy 97.183194 -255.09016)
			(xy 97.130044 -255.086176) (xy 97.078082 -255.074316) (xy 97.028468 -255.054844) (xy 96.98231 -255.028195)
			(xy 96.940639 -254.994964) (xy 96.904387 -254.955893) (xy 96.874363 -254.911856) (xy 96.851237 -254.863835)
			(xy 96.835527 -254.812905) (xy 96.827584 -254.760201) (xy 96.599004 -254.760201) (xy 96.591061 -254.812905)
			(xy 96.575351 -254.863835) (xy 96.552225 -254.911856) (xy 96.522201 -254.955893) (xy 96.485949 -254.994964)
			(xy 96.444278 -255.028195) (xy 96.39812 -255.054844) (xy 96.348506 -255.074316) (xy 96.296544 -255.086176)
			(xy 96.243394 -255.09016) (xy 96.190244 -255.086176) (xy 96.138282 -255.074316) (xy 96.088668 -255.054844)
			(xy 96.04251 -255.028195) (xy 96.000839 -254.994964) (xy 95.964587 -254.955893) (xy 95.934563 -254.911856)
			(xy 95.911437 -254.863835) (xy 95.895727 -254.812905) (xy 95.887784 -254.760201) (xy 95.659204 -254.760201)
			(xy 95.651261 -254.812905) (xy 95.635551 -254.863835) (xy 95.612425 -254.911856) (xy 95.582401 -254.955893)
			(xy 95.546149 -254.994964) (xy 95.504478 -255.028195) (xy 95.45832 -255.054844) (xy 95.408706 -255.074316)
			(xy 95.356744 -255.086176) (xy 95.303594 -255.09016) (xy 95.250444 -255.086176) (xy 95.198482 -255.074316)
			(xy 95.148868 -255.054844) (xy 95.10271 -255.028195) (xy 95.061039 -254.994964) (xy 95.024787 -254.955893)
			(xy 94.994763 -254.911856) (xy 94.971637 -254.863835) (xy 94.955927 -254.812905) (xy 94.947984 -254.760201)
			(xy 94.706648 -254.760201) (xy 94.698661 -254.811914) (xy 94.682775 -254.862113) (xy 94.659412 -254.909298)
			(xy 94.62912 -254.952364) (xy 94.592608 -254.990302) (xy 94.550734 -255.022221) (xy 94.504478 -255.047374)
			(xy 94.454925 -255.065172) (xy 94.403235 -255.075196) (xy 94.350621 -255.077213) (xy 94.298316 -255.071175)
			(xy 94.247545 -255.057223) (xy 94.1995 -255.035684) (xy 94.155305 -255.007064) (xy 94.115997 -254.972033)
			(xy 94.082497 -254.931412) (xy 94.055591 -254.886153) (xy 94.035908 -254.837318) (xy 94.023911 -254.78605)
			(xy 94.019881 -254.733552) (xy 93.767402 -254.733552) (xy 93.766898 -254.759878) (xy 93.758861 -254.811914)
			(xy 93.742975 -254.862113) (xy 93.719612 -254.909298) (xy 93.68932 -254.952364) (xy 93.652808 -254.990302)
			(xy 93.610934 -255.022221) (xy 93.564678 -255.047374) (xy 93.515125 -255.065172) (xy 93.463435 -255.075196)
			(xy 93.410821 -255.077213) (xy 93.358516 -255.071175) (xy 93.307745 -255.057223) (xy 93.2597 -255.035684)
			(xy 93.215505 -255.007064) (xy 93.176197 -254.972033) (xy 93.142697 -254.931412) (xy 93.115791 -254.886153)
			(xy 93.096108 -254.837318) (xy 93.084111 -254.78605) (xy 93.080081 -254.733552) (xy 92.840302 -254.733552)
			(xy 92.839804 -254.760201) (xy 92.831861 -254.812905) (xy 92.816151 -254.863835) (xy 92.793025 -254.911856)
			(xy 92.763001 -254.955893) (xy 92.726749 -254.994964) (xy 92.685078 -255.028195) (xy 92.63892 -255.054844)
			(xy 92.589306 -255.074316) (xy 92.537344 -255.086176) (xy 92.484194 -255.09016) (xy 92.431044 -255.086176)
			(xy 92.379082 -255.074316) (xy 92.329468 -255.054844) (xy 92.28331 -255.028195) (xy 92.241639 -254.994964)
			(xy 92.205387 -254.955893) (xy 92.175363 -254.911856) (xy 92.152237 -254.863835) (xy 92.136527 -254.812905)
			(xy 92.128584 -254.760201) (xy 91.900258 -254.760201) (xy 91.892315 -254.812905) (xy 91.876605 -254.863835)
			(xy 91.853479 -254.911856) (xy 91.823455 -254.955893) (xy 91.787203 -254.994964) (xy 91.745532 -255.028195)
			(xy 91.699374 -255.054844) (xy 91.64976 -255.074316) (xy 91.597798 -255.086176) (xy 91.544648 -255.09016)
			(xy 91.491498 -255.086176) (xy 91.439536 -255.074316) (xy 91.389922 -255.054844) (xy 91.343764 -255.028195)
			(xy 91.302093 -254.994964) (xy 91.265841 -254.955893) (xy 91.235817 -254.911856) (xy 91.212691 -254.863835)
			(xy 91.196981 -254.812905) (xy 91.189038 -254.760201) (xy 90.960204 -254.760201) (xy 90.952261 -254.812905)
			(xy 90.936551 -254.863835) (xy 90.913425 -254.911856) (xy 90.883401 -254.955893) (xy 90.847149 -254.994964)
			(xy 90.805478 -255.028195) (xy 90.75932 -255.054844) (xy 90.709706 -255.074316) (xy 90.657744 -255.086176)
			(xy 90.604594 -255.09016) (xy 90.551444 -255.086176) (xy 90.499482 -255.074316) (xy 90.449868 -255.054844)
			(xy 90.40371 -255.028195) (xy 90.362039 -254.994964) (xy 90.325787 -254.955893) (xy 90.295763 -254.911856)
			(xy 90.272637 -254.863835) (xy 90.256927 -254.812905) (xy 90.248984 -254.760201) (xy 90.020404 -254.760201)
			(xy 90.012461 -254.812905) (xy 89.996751 -254.863835) (xy 89.973625 -254.911856) (xy 89.943601 -254.955893)
			(xy 89.907349 -254.994964) (xy 89.865678 -255.028195) (xy 89.81952 -255.054844) (xy 89.769906 -255.074316)
			(xy 89.717944 -255.086176) (xy 89.664794 -255.09016) (xy 89.611644 -255.086176) (xy 89.559682 -255.074316)
			(xy 89.510068 -255.054844) (xy 89.46391 -255.028195) (xy 89.422239 -254.994964) (xy 89.385987 -254.955893)
			(xy 89.355963 -254.911856) (xy 89.332837 -254.863835) (xy 89.317127 -254.812905) (xy 89.309184 -254.760201)
			(xy 89.080619 -254.760201) (xy 89.080619 -254.760961) (xy 89.072247 -254.815042) (xy 89.0557 -254.867206)
			(xy 89.031368 -254.916225) (xy 88.999824 -254.960944) (xy 88.961809 -255.000311) (xy 88.91822 -255.033399)
			(xy 88.870081 -255.059429) (xy 88.818528 -255.077789) (xy 88.764772 -255.088045) (xy 88.73744 -255.089406)
			(xy 88.727666 -255.09019) (xy 88.709768 -255.098155) (xy 88.696158 -255.112247) (xy 88.68882 -255.130411)
			(xy 88.688418 -255.140206) (xy 88.688418 -255.574271) (xy 88.839538 -255.574271) (xy 88.839538 -255.520973)
			(xy 88.847481 -255.468269) (xy 88.863191 -255.417339) (xy 88.886317 -255.369318) (xy 88.916341 -255.325281)
			(xy 88.952593 -255.28621) (xy 88.994264 -255.252979) (xy 89.040422 -255.22633) (xy 89.090036 -255.206858)
			(xy 89.141998 -255.194998) (xy 89.195148 -255.191015) (xy 89.248298 -255.194998) (xy 89.30026 -255.206858)
			(xy 89.349874 -255.22633) (xy 89.396032 -255.252979) (xy 89.437703 -255.28621) (xy 89.473955 -255.325281)
			(xy 89.503979 -255.369318) (xy 89.527105 -255.417339) (xy 89.542815 -255.468269) (xy 89.550758 -255.520973)
			(xy 89.551256 -255.547622) (xy 89.550758 -255.574271) (xy 89.779084 -255.574271) (xy 89.779084 -255.520973)
			(xy 89.787027 -255.468269) (xy 89.802737 -255.417339) (xy 89.825863 -255.369318) (xy 89.855887 -255.325281)
			(xy 89.892139 -255.28621) (xy 89.93381 -255.252979) (xy 89.979968 -255.22633) (xy 90.029582 -255.206858)
			(xy 90.081544 -255.194998) (xy 90.134694 -255.191015) (xy 90.187844 -255.194998) (xy 90.239806 -255.206858)
			(xy 90.28942 -255.22633) (xy 90.335578 -255.252979) (xy 90.377249 -255.28621) (xy 90.413501 -255.325281)
			(xy 90.443525 -255.369318) (xy 90.466651 -255.417339) (xy 90.482361 -255.468269) (xy 90.490304 -255.520973)
			(xy 90.490802 -255.547622) (xy 90.490304 -255.574271) (xy 90.719138 -255.574271) (xy 90.719138 -255.520973)
			(xy 90.727081 -255.468269) (xy 90.742791 -255.417339) (xy 90.765917 -255.369318) (xy 90.795941 -255.325281)
			(xy 90.832193 -255.28621) (xy 90.873864 -255.252979) (xy 90.920022 -255.22633) (xy 90.969636 -255.206858)
			(xy 91.021598 -255.194998) (xy 91.074748 -255.191015) (xy 91.127898 -255.194998) (xy 91.17986 -255.206858)
			(xy 91.229474 -255.22633) (xy 91.275632 -255.252979) (xy 91.317303 -255.28621) (xy 91.353555 -255.325281)
			(xy 91.383579 -255.369318) (xy 91.406705 -255.417339) (xy 91.422415 -255.468269) (xy 91.430358 -255.520973)
			(xy 91.430856 -255.547622) (xy 91.430358 -255.574271) (xy 91.658684 -255.574271) (xy 91.658684 -255.520973)
			(xy 91.666627 -255.468269) (xy 91.682337 -255.417339) (xy 91.705463 -255.369318) (xy 91.735487 -255.325281)
			(xy 91.771739 -255.28621) (xy 91.81341 -255.252979) (xy 91.859568 -255.22633) (xy 91.909182 -255.206858)
			(xy 91.961144 -255.194998) (xy 92.014294 -255.191015) (xy 92.067444 -255.194998) (xy 92.119406 -255.206858)
			(xy 92.16902 -255.22633) (xy 92.215178 -255.252979) (xy 92.256849 -255.28621) (xy 92.293101 -255.325281)
			(xy 92.323125 -255.369318) (xy 92.346251 -255.417339) (xy 92.361961 -255.468269) (xy 92.369904 -255.520973)
			(xy 92.370402 -255.547622) (xy 92.369904 -255.574271) (xy 92.598738 -255.574271) (xy 92.598738 -255.520973)
			(xy 92.606681 -255.468269) (xy 92.622391 -255.417339) (xy 92.645517 -255.369318) (xy 92.675541 -255.325281)
			(xy 92.711793 -255.28621) (xy 92.753464 -255.252979) (xy 92.799622 -255.22633) (xy 92.849236 -255.206858)
			(xy 92.901198 -255.194998) (xy 92.954348 -255.191015) (xy 93.007498 -255.194998) (xy 93.05946 -255.206858)
			(xy 93.109074 -255.22633) (xy 93.155232 -255.252979) (xy 93.196903 -255.28621) (xy 93.233155 -255.325281)
			(xy 93.263179 -255.369318) (xy 93.286305 -255.417339) (xy 93.302015 -255.468269) (xy 93.309958 -255.520973)
			(xy 93.310456 -255.547622) (xy 93.309958 -255.574271) (xy 93.538538 -255.574271) (xy 93.538538 -255.520973)
			(xy 93.546481 -255.468269) (xy 93.562191 -255.417339) (xy 93.585317 -255.369318) (xy 93.615341 -255.325281)
			(xy 93.651593 -255.28621) (xy 93.693264 -255.252979) (xy 93.739422 -255.22633) (xy 93.789036 -255.206858)
			(xy 93.840998 -255.194998) (xy 93.894148 -255.191015) (xy 93.947298 -255.194998) (xy 93.99926 -255.206858)
			(xy 94.048874 -255.22633) (xy 94.095032 -255.252979) (xy 94.136703 -255.28621) (xy 94.172955 -255.325281)
			(xy 94.202979 -255.369318) (xy 94.226105 -255.417339) (xy 94.241815 -255.468269) (xy 94.249758 -255.520973)
			(xy 94.250256 -255.547622) (xy 94.249758 -255.574271) (xy 94.478338 -255.574271) (xy 94.478338 -255.520973)
			(xy 94.486281 -255.468269) (xy 94.501991 -255.417339) (xy 94.525117 -255.369318) (xy 94.555141 -255.325281)
			(xy 94.591393 -255.28621) (xy 94.633064 -255.252979) (xy 94.679222 -255.22633) (xy 94.728836 -255.206858)
			(xy 94.780798 -255.194998) (xy 94.833948 -255.191015) (xy 94.887098 -255.194998) (xy 94.93906 -255.206858)
			(xy 94.988674 -255.22633) (xy 95.034832 -255.252979) (xy 95.076503 -255.28621) (xy 95.112755 -255.325281)
			(xy 95.142779 -255.369318) (xy 95.165905 -255.417339) (xy 95.181615 -255.468269) (xy 95.189558 -255.520973)
			(xy 95.190056 -255.547622) (xy 95.189558 -255.574271) (xy 95.418138 -255.574271) (xy 95.418138 -255.520973)
			(xy 95.426081 -255.468269) (xy 95.441791 -255.417339) (xy 95.464917 -255.369318) (xy 95.494941 -255.325281)
			(xy 95.531193 -255.28621) (xy 95.572864 -255.252979) (xy 95.619022 -255.22633) (xy 95.668636 -255.206858)
			(xy 95.720598 -255.194998) (xy 95.773748 -255.191015) (xy 95.826898 -255.194998) (xy 95.87886 -255.206858)
			(xy 95.928474 -255.22633) (xy 95.974632 -255.252979) (xy 96.016303 -255.28621) (xy 96.052555 -255.325281)
			(xy 96.082579 -255.369318) (xy 96.105705 -255.417339) (xy 96.121415 -255.468269) (xy 96.129358 -255.520973)
			(xy 96.129856 -255.547622) (xy 96.129358 -255.574271) (xy 96.357938 -255.574271) (xy 96.357938 -255.520973)
			(xy 96.365881 -255.468269) (xy 96.381591 -255.417339) (xy 96.404717 -255.369318) (xy 96.434741 -255.325281)
			(xy 96.470993 -255.28621) (xy 96.512664 -255.252979) (xy 96.558822 -255.22633) (xy 96.608436 -255.206858)
			(xy 96.660398 -255.194998) (xy 96.713548 -255.191015) (xy 96.766698 -255.194998) (xy 96.81866 -255.206858)
			(xy 96.868274 -255.22633) (xy 96.914432 -255.252979) (xy 96.956103 -255.28621) (xy 96.992355 -255.325281)
			(xy 97.022379 -255.369318) (xy 97.045505 -255.417339) (xy 97.061215 -255.468269) (xy 97.069158 -255.520973)
			(xy 97.069656 -255.547622) (xy 97.069158 -255.574271) (xy 97.297738 -255.574271) (xy 97.297738 -255.520973)
			(xy 97.305681 -255.468269) (xy 97.321391 -255.417339) (xy 97.344517 -255.369318) (xy 97.374541 -255.325281)
			(xy 97.410793 -255.28621) (xy 97.452464 -255.252979) (xy 97.498622 -255.22633) (xy 97.548236 -255.206858)
			(xy 97.600198 -255.194998) (xy 97.653348 -255.191015) (xy 97.706498 -255.194998) (xy 97.75846 -255.206858)
			(xy 97.808074 -255.22633) (xy 97.854232 -255.252979) (xy 97.895903 -255.28621) (xy 97.932155 -255.325281)
			(xy 97.962179 -255.369318) (xy 97.985305 -255.417339) (xy 98.001015 -255.468269) (xy 98.008958 -255.520973)
			(xy 98.009456 -255.547622) (xy 98.008958 -255.574271) (xy 98.237284 -255.574271) (xy 98.237284 -255.520973)
			(xy 98.245227 -255.468269) (xy 98.260937 -255.417339) (xy 98.284063 -255.369318) (xy 98.314087 -255.325281)
			(xy 98.350339 -255.28621) (xy 98.39201 -255.252979) (xy 98.438168 -255.22633) (xy 98.487782 -255.206858)
			(xy 98.539744 -255.194998) (xy 98.592894 -255.191015) (xy 98.646044 -255.194998) (xy 98.698006 -255.206858)
			(xy 98.74762 -255.22633) (xy 98.793778 -255.252979) (xy 98.835449 -255.28621) (xy 98.871701 -255.325281)
			(xy 98.901725 -255.369318) (xy 98.924851 -255.417339) (xy 98.940561 -255.468269) (xy 98.948504 -255.520973)
			(xy 98.949002 -255.547622) (xy 98.948504 -255.574271) (xy 98.940561 -255.626975) (xy 98.924851 -255.677905)
			(xy 98.901725 -255.725926) (xy 98.871701 -255.769963) (xy 98.835449 -255.809034) (xy 98.793778 -255.842265)
			(xy 98.74762 -255.868914) (xy 98.698006 -255.888386) (xy 98.646044 -255.900246) (xy 98.592894 -255.90423)
			(xy 98.539744 -255.900246) (xy 98.487782 -255.888386) (xy 98.438168 -255.868914) (xy 98.39201 -255.842265)
			(xy 98.350339 -255.809034) (xy 98.314087 -255.769963) (xy 98.284063 -255.725926) (xy 98.260937 -255.677905)
			(xy 98.245227 -255.626975) (xy 98.237284 -255.574271) (xy 98.008958 -255.574271) (xy 98.001015 -255.626975)
			(xy 97.985305 -255.677905) (xy 97.962179 -255.725926) (xy 97.932155 -255.769963) (xy 97.895903 -255.809034)
			(xy 97.854232 -255.842265) (xy 97.808074 -255.868914) (xy 97.75846 -255.888386) (xy 97.706498 -255.900246)
			(xy 97.653348 -255.90423) (xy 97.600198 -255.900246) (xy 97.548236 -255.888386) (xy 97.498622 -255.868914)
			(xy 97.452464 -255.842265) (xy 97.410793 -255.809034) (xy 97.374541 -255.769963) (xy 97.344517 -255.725926)
			(xy 97.321391 -255.677905) (xy 97.305681 -255.626975) (xy 97.297738 -255.574271) (xy 97.069158 -255.574271)
			(xy 97.061215 -255.626975) (xy 97.045505 -255.677905) (xy 97.022379 -255.725926) (xy 96.992355 -255.769963)
			(xy 96.956103 -255.809034) (xy 96.914432 -255.842265) (xy 96.868274 -255.868914) (xy 96.81866 -255.888386)
			(xy 96.766698 -255.900246) (xy 96.713548 -255.90423) (xy 96.660398 -255.900246) (xy 96.608436 -255.888386)
			(xy 96.558822 -255.868914) (xy 96.512664 -255.842265) (xy 96.470993 -255.809034) (xy 96.434741 -255.769963)
			(xy 96.404717 -255.725926) (xy 96.381591 -255.677905) (xy 96.365881 -255.626975) (xy 96.357938 -255.574271)
			(xy 96.129358 -255.574271) (xy 96.121415 -255.626975) (xy 96.105705 -255.677905) (xy 96.082579 -255.725926)
			(xy 96.052555 -255.769963) (xy 96.016303 -255.809034) (xy 95.974632 -255.842265) (xy 95.928474 -255.868914)
			(xy 95.87886 -255.888386) (xy 95.826898 -255.900246) (xy 95.773748 -255.90423) (xy 95.720598 -255.900246)
			(xy 95.668636 -255.888386) (xy 95.619022 -255.868914) (xy 95.572864 -255.842265) (xy 95.531193 -255.809034)
			(xy 95.494941 -255.769963) (xy 95.464917 -255.725926) (xy 95.441791 -255.677905) (xy 95.426081 -255.626975)
			(xy 95.418138 -255.574271) (xy 95.189558 -255.574271) (xy 95.181615 -255.626975) (xy 95.165905 -255.677905)
			(xy 95.142779 -255.725926) (xy 95.112755 -255.769963) (xy 95.076503 -255.809034) (xy 95.034832 -255.842265)
			(xy 94.988674 -255.868914) (xy 94.93906 -255.888386) (xy 94.887098 -255.900246) (xy 94.833948 -255.90423)
			(xy 94.780798 -255.900246) (xy 94.728836 -255.888386) (xy 94.679222 -255.868914) (xy 94.633064 -255.842265)
			(xy 94.591393 -255.809034) (xy 94.555141 -255.769963) (xy 94.525117 -255.725926) (xy 94.501991 -255.677905)
			(xy 94.486281 -255.626975) (xy 94.478338 -255.574271) (xy 94.249758 -255.574271) (xy 94.241815 -255.626975)
			(xy 94.226105 -255.677905) (xy 94.202979 -255.725926) (xy 94.172955 -255.769963) (xy 94.136703 -255.809034)
			(xy 94.095032 -255.842265) (xy 94.048874 -255.868914) (xy 93.99926 -255.888386) (xy 93.947298 -255.900246)
			(xy 93.894148 -255.90423) (xy 93.840998 -255.900246) (xy 93.789036 -255.888386) (xy 93.739422 -255.868914)
			(xy 93.693264 -255.842265) (xy 93.651593 -255.809034) (xy 93.615341 -255.769963) (xy 93.585317 -255.725926)
			(xy 93.562191 -255.677905) (xy 93.546481 -255.626975) (xy 93.538538 -255.574271) (xy 93.309958 -255.574271)
			(xy 93.302015 -255.626975) (xy 93.286305 -255.677905) (xy 93.263179 -255.725926) (xy 93.233155 -255.769963)
			(xy 93.196903 -255.809034) (xy 93.155232 -255.842265) (xy 93.109074 -255.868914) (xy 93.05946 -255.888386)
			(xy 93.007498 -255.900246) (xy 92.954348 -255.90423) (xy 92.901198 -255.900246) (xy 92.849236 -255.888386)
			(xy 92.799622 -255.868914) (xy 92.753464 -255.842265) (xy 92.711793 -255.809034) (xy 92.675541 -255.769963)
			(xy 92.645517 -255.725926) (xy 92.622391 -255.677905) (xy 92.606681 -255.626975) (xy 92.598738 -255.574271)
			(xy 92.369904 -255.574271) (xy 92.361961 -255.626975) (xy 92.346251 -255.677905) (xy 92.323125 -255.725926)
			(xy 92.293101 -255.769963) (xy 92.256849 -255.809034) (xy 92.215178 -255.842265) (xy 92.16902 -255.868914)
			(xy 92.119406 -255.888386) (xy 92.067444 -255.900246) (xy 92.014294 -255.90423) (xy 91.961144 -255.900246)
			(xy 91.909182 -255.888386) (xy 91.859568 -255.868914) (xy 91.81341 -255.842265) (xy 91.771739 -255.809034)
			(xy 91.735487 -255.769963) (xy 91.705463 -255.725926) (xy 91.682337 -255.677905) (xy 91.666627 -255.626975)
			(xy 91.658684 -255.574271) (xy 91.430358 -255.574271) (xy 91.422415 -255.626975) (xy 91.406705 -255.677905)
			(xy 91.383579 -255.725926) (xy 91.353555 -255.769963) (xy 91.317303 -255.809034) (xy 91.275632 -255.842265)
			(xy 91.229474 -255.868914) (xy 91.17986 -255.888386) (xy 91.127898 -255.900246) (xy 91.074748 -255.90423)
			(xy 91.021598 -255.900246) (xy 90.969636 -255.888386) (xy 90.920022 -255.868914) (xy 90.873864 -255.842265)
			(xy 90.832193 -255.809034) (xy 90.795941 -255.769963) (xy 90.765917 -255.725926) (xy 90.742791 -255.677905)
			(xy 90.727081 -255.626975) (xy 90.719138 -255.574271) (xy 90.490304 -255.574271) (xy 90.482361 -255.626975)
			(xy 90.466651 -255.677905) (xy 90.443525 -255.725926) (xy 90.413501 -255.769963) (xy 90.377249 -255.809034)
			(xy 90.335578 -255.842265) (xy 90.28942 -255.868914) (xy 90.239806 -255.888386) (xy 90.187844 -255.900246)
			(xy 90.134694 -255.90423) (xy 90.081544 -255.900246) (xy 90.029582 -255.888386) (xy 89.979968 -255.868914)
			(xy 89.93381 -255.842265) (xy 89.892139 -255.809034) (xy 89.855887 -255.769963) (xy 89.825863 -255.725926)
			(xy 89.802737 -255.677905) (xy 89.787027 -255.626975) (xy 89.779084 -255.574271) (xy 89.550758 -255.574271)
			(xy 89.542815 -255.626975) (xy 89.527105 -255.677905) (xy 89.503979 -255.725926) (xy 89.473955 -255.769963)
			(xy 89.437703 -255.809034) (xy 89.396032 -255.842265) (xy 89.349874 -255.868914) (xy 89.30026 -255.888386)
			(xy 89.248298 -255.900246) (xy 89.195148 -255.90423) (xy 89.141998 -255.900246) (xy 89.090036 -255.888386)
			(xy 89.040422 -255.868914) (xy 88.994264 -255.842265) (xy 88.952593 -255.809034) (xy 88.916341 -255.769963)
			(xy 88.886317 -255.725926) (xy 88.863191 -255.677905) (xy 88.847481 -255.626975) (xy 88.839538 -255.574271)
			(xy 88.688418 -255.574271) (xy 88.688418 -255.954784) (xy 88.688859 -255.964579) (xy 88.696185 -255.982748)
			(xy 88.70978 -255.996854) (xy 88.727665 -256.004846) (xy 88.73744 -256.005584) (xy 88.764762 -256.00704)
			(xy 88.818505 -256.017294) (xy 88.870046 -256.035649) (xy 88.918173 -256.061673) (xy 88.961752 -256.094753)
			(xy 88.999757 -256.134111) (xy 89.031294 -256.178819) (xy 89.055621 -256.227826) (xy 89.072163 -256.279977)
			(xy 89.080533 -256.334045) (xy 89.080533 -256.388087) (xy 89.309184 -256.388087) (xy 89.309184 -256.334789)
			(xy 89.317127 -256.282085) (xy 89.332837 -256.231155) (xy 89.355963 -256.183134) (xy 89.385987 -256.139097)
			(xy 89.422239 -256.100026) (xy 89.46391 -256.066795) (xy 89.510068 -256.040146) (xy 89.559682 -256.020674)
			(xy 89.611644 -256.008814) (xy 89.664794 -256.004831) (xy 89.717944 -256.008814) (xy 89.769906 -256.020674)
			(xy 89.81952 -256.040146) (xy 89.865678 -256.066795) (xy 89.907349 -256.100026) (xy 89.943601 -256.139097)
			(xy 89.973625 -256.183134) (xy 89.996751 -256.231155) (xy 90.012461 -256.282085) (xy 90.020404 -256.334789)
			(xy 90.020902 -256.361438) (xy 90.020404 -256.388087) (xy 90.248984 -256.388087) (xy 90.248984 -256.334789)
			(xy 90.256927 -256.282085) (xy 90.272637 -256.231155) (xy 90.295763 -256.183134) (xy 90.325787 -256.139097)
			(xy 90.362039 -256.100026) (xy 90.40371 -256.066795) (xy 90.449868 -256.040146) (xy 90.499482 -256.020674)
			(xy 90.551444 -256.008814) (xy 90.604594 -256.004831) (xy 90.657744 -256.008814) (xy 90.709706 -256.020674)
			(xy 90.75932 -256.040146) (xy 90.805478 -256.066795) (xy 90.847149 -256.100026) (xy 90.883401 -256.139097)
			(xy 90.913425 -256.183134) (xy 90.936551 -256.231155) (xy 90.952261 -256.282085) (xy 90.960204 -256.334789)
			(xy 90.960702 -256.361438) (xy 90.960204 -256.388087) (xy 91.188784 -256.388087) (xy 91.188784 -256.334789)
			(xy 91.196727 -256.282085) (xy 91.212437 -256.231155) (xy 91.235563 -256.183134) (xy 91.265587 -256.139097)
			(xy 91.301839 -256.100026) (xy 91.34351 -256.066795) (xy 91.389668 -256.040146) (xy 91.439282 -256.020674)
			(xy 91.491244 -256.008814) (xy 91.544394 -256.004831) (xy 91.597544 -256.008814) (xy 91.649506 -256.020674)
			(xy 91.69912 -256.040146) (xy 91.745278 -256.066795) (xy 91.786949 -256.100026) (xy 91.823201 -256.139097)
			(xy 91.853225 -256.183134) (xy 91.876351 -256.231155) (xy 91.892061 -256.282085) (xy 91.900004 -256.334789)
			(xy 91.900502 -256.361438) (xy 91.900004 -256.388087) (xy 92.128584 -256.388087) (xy 92.128584 -256.334789)
			(xy 92.136527 -256.282085) (xy 92.152237 -256.231155) (xy 92.175363 -256.183134) (xy 92.205387 -256.139097)
			(xy 92.241639 -256.100026) (xy 92.28331 -256.066795) (xy 92.329468 -256.040146) (xy 92.379082 -256.020674)
			(xy 92.431044 -256.008814) (xy 92.484194 -256.004831) (xy 92.537344 -256.008814) (xy 92.589306 -256.020674)
			(xy 92.63892 -256.040146) (xy 92.685078 -256.066795) (xy 92.726749 -256.100026) (xy 92.763001 -256.139097)
			(xy 92.793025 -256.183134) (xy 92.816151 -256.231155) (xy 92.831861 -256.282085) (xy 92.839804 -256.334789)
			(xy 92.840302 -256.361438) (xy 92.839804 -256.388087) (xy 93.068384 -256.388087) (xy 93.068384 -256.334789)
			(xy 93.076327 -256.282085) (xy 93.092037 -256.231155) (xy 93.115163 -256.183134) (xy 93.145187 -256.139097)
			(xy 93.181439 -256.100026) (xy 93.22311 -256.066795) (xy 93.269268 -256.040146) (xy 93.318882 -256.020674)
			(xy 93.370844 -256.008814) (xy 93.423994 -256.004831) (xy 93.477144 -256.008814) (xy 93.529106 -256.020674)
			(xy 93.57872 -256.040146) (xy 93.624878 -256.066795) (xy 93.666549 -256.100026) (xy 93.702801 -256.139097)
			(xy 93.732825 -256.183134) (xy 93.755951 -256.231155) (xy 93.771661 -256.282085) (xy 93.779604 -256.334789)
			(xy 93.780102 -256.361438) (xy 93.779604 -256.388087) (xy 94.008438 -256.388087) (xy 94.008438 -256.334789)
			(xy 94.016381 -256.282085) (xy 94.032091 -256.231155) (xy 94.055217 -256.183134) (xy 94.085241 -256.139097)
			(xy 94.121493 -256.100026) (xy 94.163164 -256.066795) (xy 94.209322 -256.040146) (xy 94.258936 -256.020674)
			(xy 94.310898 -256.008814) (xy 94.364048 -256.004831) (xy 94.417198 -256.008814) (xy 94.46916 -256.020674)
			(xy 94.518774 -256.040146) (xy 94.564932 -256.066795) (xy 94.606603 -256.100026) (xy 94.642855 -256.139097)
			(xy 94.672879 -256.183134) (xy 94.696005 -256.231155) (xy 94.711715 -256.282085) (xy 94.719658 -256.334789)
			(xy 94.720156 -256.361438) (xy 94.719658 -256.388087) (xy 94.947984 -256.388087) (xy 94.947984 -256.334789)
			(xy 94.955927 -256.282085) (xy 94.971637 -256.231155) (xy 94.994763 -256.183134) (xy 95.024787 -256.139097)
			(xy 95.061039 -256.100026) (xy 95.10271 -256.066795) (xy 95.148868 -256.040146) (xy 95.198482 -256.020674)
			(xy 95.250444 -256.008814) (xy 95.303594 -256.004831) (xy 95.356744 -256.008814) (xy 95.408706 -256.020674)
			(xy 95.45832 -256.040146) (xy 95.504478 -256.066795) (xy 95.546149 -256.100026) (xy 95.582401 -256.139097)
			(xy 95.612425 -256.183134) (xy 95.635551 -256.231155) (xy 95.651261 -256.282085) (xy 95.659204 -256.334789)
			(xy 95.659702 -256.361438) (xy 95.659204 -256.388087) (xy 95.887784 -256.388087) (xy 95.887784 -256.334789)
			(xy 95.895727 -256.282085) (xy 95.911437 -256.231155) (xy 95.934563 -256.183134) (xy 95.964587 -256.139097)
			(xy 96.000839 -256.100026) (xy 96.04251 -256.066795) (xy 96.088668 -256.040146) (xy 96.138282 -256.020674)
			(xy 96.190244 -256.008814) (xy 96.243394 -256.004831) (xy 96.296544 -256.008814) (xy 96.348506 -256.020674)
			(xy 96.39812 -256.040146) (xy 96.444278 -256.066795) (xy 96.485949 -256.100026) (xy 96.522201 -256.139097)
			(xy 96.552225 -256.183134) (xy 96.575351 -256.231155) (xy 96.591061 -256.282085) (xy 96.599004 -256.334789)
			(xy 96.599502 -256.361438) (xy 96.599004 -256.388087) (xy 96.827584 -256.388087) (xy 96.827584 -256.334789)
			(xy 96.835527 -256.282085) (xy 96.851237 -256.231155) (xy 96.874363 -256.183134) (xy 96.904387 -256.139097)
			(xy 96.940639 -256.100026) (xy 96.98231 -256.066795) (xy 97.028468 -256.040146) (xy 97.078082 -256.020674)
			(xy 97.130044 -256.008814) (xy 97.183194 -256.004831) (xy 97.236344 -256.008814) (xy 97.288306 -256.020674)
			(xy 97.33792 -256.040146) (xy 97.384078 -256.066795) (xy 97.425749 -256.100026) (xy 97.462001 -256.139097)
			(xy 97.492025 -256.183134) (xy 97.515151 -256.231155) (xy 97.530861 -256.282085) (xy 97.538804 -256.334789)
			(xy 97.539302 -256.361438) (xy 97.538804 -256.388087) (xy 97.767384 -256.388087) (xy 97.767384 -256.334789)
			(xy 97.775327 -256.282085) (xy 97.791037 -256.231155) (xy 97.814163 -256.183134) (xy 97.844187 -256.139097)
			(xy 97.880439 -256.100026) (xy 97.92211 -256.066795) (xy 97.968268 -256.040146) (xy 98.017882 -256.020674)
			(xy 98.069844 -256.008814) (xy 98.122994 -256.004831) (xy 98.176144 -256.008814) (xy 98.228106 -256.020674)
			(xy 98.27772 -256.040146) (xy 98.323878 -256.066795) (xy 98.365549 -256.100026) (xy 98.401801 -256.139097)
			(xy 98.431825 -256.183134) (xy 98.454951 -256.231155) (xy 98.470661 -256.282085) (xy 98.478604 -256.334789)
			(xy 98.479102 -256.361438) (xy 98.478604 -256.388087) (xy 98.707184 -256.388087) (xy 98.707184 -256.334789)
			(xy 98.715127 -256.282085) (xy 98.730837 -256.231155) (xy 98.753963 -256.183134) (xy 98.783987 -256.139097)
			(xy 98.820239 -256.100026) (xy 98.86191 -256.066795) (xy 98.908068 -256.040146) (xy 98.957682 -256.020674)
			(xy 99.009644 -256.008814) (xy 99.062794 -256.004831) (xy 99.115944 -256.008814) (xy 99.167906 -256.020674)
			(xy 99.21752 -256.040146) (xy 99.263678 -256.066795) (xy 99.305349 -256.100026) (xy 99.341601 -256.139097)
			(xy 99.371625 -256.183134) (xy 99.394751 -256.231155) (xy 99.410461 -256.282085) (xy 99.418404 -256.334789)
			(xy 99.418902 -256.361438) (xy 99.418404 -256.388087) (xy 99.410461 -256.440791) (xy 99.394751 -256.491721)
			(xy 99.371625 -256.539742) (xy 99.341601 -256.583779) (xy 99.305349 -256.62285) (xy 99.263678 -256.656081)
			(xy 99.21752 -256.68273) (xy 99.167906 -256.702202) (xy 99.115944 -256.714062) (xy 99.062794 -256.718046)
			(xy 99.009644 -256.714062) (xy 98.957682 -256.702202) (xy 98.908068 -256.68273) (xy 98.86191 -256.656081)
			(xy 98.820239 -256.62285) (xy 98.783987 -256.583779) (xy 98.753963 -256.539742) (xy 98.730837 -256.491721)
			(xy 98.715127 -256.440791) (xy 98.707184 -256.388087) (xy 98.478604 -256.388087) (xy 98.470661 -256.440791)
			(xy 98.454951 -256.491721) (xy 98.431825 -256.539742) (xy 98.401801 -256.583779) (xy 98.365549 -256.62285)
			(xy 98.323878 -256.656081) (xy 98.27772 -256.68273) (xy 98.228106 -256.702202) (xy 98.176144 -256.714062)
			(xy 98.122994 -256.718046) (xy 98.069844 -256.714062) (xy 98.017882 -256.702202) (xy 97.968268 -256.68273)
			(xy 97.92211 -256.656081) (xy 97.880439 -256.62285) (xy 97.844187 -256.583779) (xy 97.814163 -256.539742)
			(xy 97.791037 -256.491721) (xy 97.775327 -256.440791) (xy 97.767384 -256.388087) (xy 97.538804 -256.388087)
			(xy 97.530861 -256.440791) (xy 97.515151 -256.491721) (xy 97.492025 -256.539742) (xy 97.462001 -256.583779)
			(xy 97.425749 -256.62285) (xy 97.384078 -256.656081) (xy 97.33792 -256.68273) (xy 97.288306 -256.702202)
			(xy 97.236344 -256.714062) (xy 97.183194 -256.718046) (xy 97.130044 -256.714062) (xy 97.078082 -256.702202)
			(xy 97.028468 -256.68273) (xy 96.98231 -256.656081) (xy 96.940639 -256.62285) (xy 96.904387 -256.583779)
			(xy 96.874363 -256.539742) (xy 96.851237 -256.491721) (xy 96.835527 -256.440791) (xy 96.827584 -256.388087)
			(xy 96.599004 -256.388087) (xy 96.591061 -256.440791) (xy 96.575351 -256.491721) (xy 96.552225 -256.539742)
			(xy 96.522201 -256.583779) (xy 96.485949 -256.62285) (xy 96.444278 -256.656081) (xy 96.39812 -256.68273)
			(xy 96.348506 -256.702202) (xy 96.296544 -256.714062) (xy 96.243394 -256.718046) (xy 96.190244 -256.714062)
			(xy 96.138282 -256.702202) (xy 96.088668 -256.68273) (xy 96.04251 -256.656081) (xy 96.000839 -256.62285)
			(xy 95.964587 -256.583779) (xy 95.934563 -256.539742) (xy 95.911437 -256.491721) (xy 95.895727 -256.440791)
			(xy 95.887784 -256.388087) (xy 95.659204 -256.388087) (xy 95.651261 -256.440791) (xy 95.635551 -256.491721)
			(xy 95.612425 -256.539742) (xy 95.582401 -256.583779) (xy 95.546149 -256.62285) (xy 95.504478 -256.656081)
			(xy 95.45832 -256.68273) (xy 95.408706 -256.702202) (xy 95.356744 -256.714062) (xy 95.303594 -256.718046)
			(xy 95.250444 -256.714062) (xy 95.198482 -256.702202) (xy 95.148868 -256.68273) (xy 95.10271 -256.656081)
			(xy 95.061039 -256.62285) (xy 95.024787 -256.583779) (xy 94.994763 -256.539742) (xy 94.971637 -256.491721)
			(xy 94.955927 -256.440791) (xy 94.947984 -256.388087) (xy 94.719658 -256.388087) (xy 94.711715 -256.440791)
			(xy 94.696005 -256.491721) (xy 94.672879 -256.539742) (xy 94.642855 -256.583779) (xy 94.606603 -256.62285)
			(xy 94.564932 -256.656081) (xy 94.518774 -256.68273) (xy 94.46916 -256.702202) (xy 94.417198 -256.714062)
			(xy 94.364048 -256.718046) (xy 94.310898 -256.714062) (xy 94.258936 -256.702202) (xy 94.209322 -256.68273)
			(xy 94.163164 -256.656081) (xy 94.121493 -256.62285) (xy 94.085241 -256.583779) (xy 94.055217 -256.539742)
			(xy 94.032091 -256.491721) (xy 94.016381 -256.440791) (xy 94.008438 -256.388087) (xy 93.779604 -256.388087)
			(xy 93.771661 -256.440791) (xy 93.755951 -256.491721) (xy 93.732825 -256.539742) (xy 93.702801 -256.583779)
			(xy 93.666549 -256.62285) (xy 93.624878 -256.656081) (xy 93.57872 -256.68273) (xy 93.529106 -256.702202)
			(xy 93.477144 -256.714062) (xy 93.423994 -256.718046) (xy 93.370844 -256.714062) (xy 93.318882 -256.702202)
			(xy 93.269268 -256.68273) (xy 93.22311 -256.656081) (xy 93.181439 -256.62285) (xy 93.145187 -256.583779)
			(xy 93.115163 -256.539742) (xy 93.092037 -256.491721) (xy 93.076327 -256.440791) (xy 93.068384 -256.388087)
			(xy 92.839804 -256.388087) (xy 92.831861 -256.440791) (xy 92.816151 -256.491721) (xy 92.793025 -256.539742)
			(xy 92.763001 -256.583779) (xy 92.726749 -256.62285) (xy 92.685078 -256.656081) (xy 92.63892 -256.68273)
			(xy 92.589306 -256.702202) (xy 92.537344 -256.714062) (xy 92.484194 -256.718046) (xy 92.431044 -256.714062)
			(xy 92.379082 -256.702202) (xy 92.329468 -256.68273) (xy 92.28331 -256.656081) (xy 92.241639 -256.62285)
			(xy 92.205387 -256.583779) (xy 92.175363 -256.539742) (xy 92.152237 -256.491721) (xy 92.136527 -256.440791)
			(xy 92.128584 -256.388087) (xy 91.900004 -256.388087) (xy 91.892061 -256.440791) (xy 91.876351 -256.491721)
			(xy 91.853225 -256.539742) (xy 91.823201 -256.583779) (xy 91.786949 -256.62285) (xy 91.745278 -256.656081)
			(xy 91.69912 -256.68273) (xy 91.649506 -256.702202) (xy 91.597544 -256.714062) (xy 91.544394 -256.718046)
			(xy 91.491244 -256.714062) (xy 91.439282 -256.702202) (xy 91.389668 -256.68273) (xy 91.34351 -256.656081)
			(xy 91.301839 -256.62285) (xy 91.265587 -256.583779) (xy 91.235563 -256.539742) (xy 91.212437 -256.491721)
			(xy 91.196727 -256.440791) (xy 91.188784 -256.388087) (xy 90.960204 -256.388087) (xy 90.952261 -256.440791)
			(xy 90.936551 -256.491721) (xy 90.913425 -256.539742) (xy 90.883401 -256.583779) (xy 90.847149 -256.62285)
			(xy 90.805478 -256.656081) (xy 90.75932 -256.68273) (xy 90.709706 -256.702202) (xy 90.657744 -256.714062)
			(xy 90.604594 -256.718046) (xy 90.551444 -256.714062) (xy 90.499482 -256.702202) (xy 90.449868 -256.68273)
			(xy 90.40371 -256.656081) (xy 90.362039 -256.62285) (xy 90.325787 -256.583779) (xy 90.295763 -256.539742)
			(xy 90.272637 -256.491721) (xy 90.256927 -256.440791) (xy 90.248984 -256.388087) (xy 90.020404 -256.388087)
			(xy 90.012461 -256.440791) (xy 89.996751 -256.491721) (xy 89.973625 -256.539742) (xy 89.943601 -256.583779)
			(xy 89.907349 -256.62285) (xy 89.865678 -256.656081) (xy 89.81952 -256.68273) (xy 89.769906 -256.702202)
			(xy 89.717944 -256.714062) (xy 89.664794 -256.718046) (xy 89.611644 -256.714062) (xy 89.559682 -256.702202)
			(xy 89.510068 -256.68273) (xy 89.46391 -256.656081) (xy 89.422239 -256.62285) (xy 89.385987 -256.583779)
			(xy 89.355963 -256.539742) (xy 89.332837 -256.491721) (xy 89.317127 -256.440791) (xy 89.309184 -256.388087)
			(xy 89.080533 -256.388087) (xy 89.080533 -256.388757) (xy 89.072163 -256.442826) (xy 89.05562 -256.494977)
			(xy 89.031293 -256.543983) (xy 88.999756 -256.588692) (xy 88.96175 -256.628049) (xy 88.918171 -256.661129)
			(xy 88.870044 -256.687152) (xy 88.818502 -256.705507) (xy 88.764759 -256.71576) (xy 88.73744 -256.717292)
			(xy 88.727672 -256.718078) (xy 88.70979 -256.726046) (xy 88.696201 -256.74014) (xy 88.688891 -256.758302)
			(xy 88.688418 -256.768092) (xy 88.688418 -257.201903) (xy 88.839284 -257.201903) (xy 88.839284 -257.148605)
			(xy 88.847227 -257.095901) (xy 88.862937 -257.044971) (xy 88.886063 -256.99695) (xy 88.916087 -256.952913)
			(xy 88.952339 -256.913842) (xy 88.99401 -256.880611) (xy 89.040168 -256.853962) (xy 89.089782 -256.83449)
			(xy 89.141744 -256.82263) (xy 89.194894 -256.818647) (xy 89.248044 -256.82263) (xy 89.300006 -256.83449)
			(xy 89.34962 -256.853962) (xy 89.395778 -256.880611) (xy 89.437449 -256.913842) (xy 89.473701 -256.952913)
			(xy 89.503725 -256.99695) (xy 89.526851 -257.044971) (xy 89.542561 -257.095901) (xy 89.550504 -257.148605)
			(xy 89.551002 -257.175254) (xy 89.550504 -257.201903) (xy 89.779084 -257.201903) (xy 89.779084 -257.148605)
			(xy 89.787027 -257.095901) (xy 89.802737 -257.044971) (xy 89.825863 -256.99695) (xy 89.855887 -256.952913)
			(xy 89.892139 -256.913842) (xy 89.93381 -256.880611) (xy 89.979968 -256.853962) (xy 90.029582 -256.83449)
			(xy 90.081544 -256.82263) (xy 90.134694 -256.818647) (xy 90.187844 -256.82263) (xy 90.239806 -256.83449)
			(xy 90.28942 -256.853962) (xy 90.335578 -256.880611) (xy 90.377249 -256.913842) (xy 90.413501 -256.952913)
			(xy 90.443525 -256.99695) (xy 90.466651 -257.044971) (xy 90.482361 -257.095901) (xy 90.490304 -257.148605)
			(xy 90.490802 -257.175254) (xy 90.490304 -257.201903) (xy 90.718884 -257.201903) (xy 90.718884 -257.148605)
			(xy 90.726827 -257.095901) (xy 90.742537 -257.044971) (xy 90.765663 -256.99695) (xy 90.795687 -256.952913)
			(xy 90.831939 -256.913842) (xy 90.87361 -256.880611) (xy 90.919768 -256.853962) (xy 90.969382 -256.83449)
			(xy 91.021344 -256.82263) (xy 91.074494 -256.818647) (xy 91.127644 -256.82263) (xy 91.179606 -256.83449)
			(xy 91.22922 -256.853962) (xy 91.275378 -256.880611) (xy 91.317049 -256.913842) (xy 91.353301 -256.952913)
			(xy 91.383325 -256.99695) (xy 91.406451 -257.044971) (xy 91.422161 -257.095901) (xy 91.430104 -257.148605)
			(xy 91.430602 -257.175254) (xy 91.430104 -257.201903) (xy 91.658938 -257.201903) (xy 91.658938 -257.148605)
			(xy 91.666881 -257.095901) (xy 91.682591 -257.044971) (xy 91.705717 -256.99695) (xy 91.735741 -256.952913)
			(xy 91.771993 -256.913842) (xy 91.813664 -256.880611) (xy 91.859822 -256.853962) (xy 91.909436 -256.83449)
			(xy 91.961398 -256.82263) (xy 92.014548 -256.818647) (xy 92.067698 -256.82263) (xy 92.11966 -256.83449)
			(xy 92.169274 -256.853962) (xy 92.215432 -256.880611) (xy 92.257103 -256.913842) (xy 92.293355 -256.952913)
			(xy 92.323379 -256.99695) (xy 92.346505 -257.044971) (xy 92.362215 -257.095901) (xy 92.370158 -257.148605)
			(xy 92.370656 -257.175254) (xy 92.370158 -257.201903) (xy 92.598484 -257.201903) (xy 92.598484 -257.148605)
			(xy 92.606427 -257.095901) (xy 92.622137 -257.044971) (xy 92.645263 -256.99695) (xy 92.675287 -256.952913)
			(xy 92.711539 -256.913842) (xy 92.75321 -256.880611) (xy 92.799368 -256.853962) (xy 92.848982 -256.83449)
			(xy 92.900944 -256.82263) (xy 92.954094 -256.818647) (xy 93.007244 -256.82263) (xy 93.059206 -256.83449)
			(xy 93.10882 -256.853962) (xy 93.154978 -256.880611) (xy 93.196649 -256.913842) (xy 93.232901 -256.952913)
			(xy 93.262925 -256.99695) (xy 93.286051 -257.044971) (xy 93.301761 -257.095901) (xy 93.309704 -257.148605)
			(xy 93.310202 -257.175254) (xy 93.309704 -257.201903) (xy 93.538538 -257.201903) (xy 93.538538 -257.148605)
			(xy 93.546481 -257.095901) (xy 93.562191 -257.044971) (xy 93.585317 -256.99695) (xy 93.615341 -256.952913)
			(xy 93.651593 -256.913842) (xy 93.693264 -256.880611) (xy 93.739422 -256.853962) (xy 93.789036 -256.83449)
			(xy 93.840998 -256.82263) (xy 93.894148 -256.818647) (xy 93.947298 -256.82263) (xy 93.99926 -256.83449)
			(xy 94.048874 -256.853962) (xy 94.095032 -256.880611) (xy 94.136703 -256.913842) (xy 94.172955 -256.952913)
			(xy 94.202979 -256.99695) (xy 94.226105 -257.044971) (xy 94.241815 -257.095901) (xy 94.249758 -257.148605)
			(xy 94.250256 -257.175254) (xy 94.249758 -257.201903) (xy 94.478338 -257.201903) (xy 94.478338 -257.148605)
			(xy 94.486281 -257.095901) (xy 94.501991 -257.044971) (xy 94.525117 -256.99695) (xy 94.555141 -256.952913)
			(xy 94.591393 -256.913842) (xy 94.633064 -256.880611) (xy 94.679222 -256.853962) (xy 94.728836 -256.83449)
			(xy 94.780798 -256.82263) (xy 94.833948 -256.818647) (xy 94.887098 -256.82263) (xy 94.93906 -256.83449)
			(xy 94.988674 -256.853962) (xy 95.034832 -256.880611) (xy 95.076503 -256.913842) (xy 95.112755 -256.952913)
			(xy 95.142779 -256.99695) (xy 95.165905 -257.044971) (xy 95.181615 -257.095901) (xy 95.189558 -257.148605)
			(xy 95.190056 -257.175254) (xy 95.189558 -257.201903) (xy 95.418138 -257.201903) (xy 95.418138 -257.148605)
			(xy 95.426081 -257.095901) (xy 95.441791 -257.044971) (xy 95.464917 -256.99695) (xy 95.494941 -256.952913)
			(xy 95.531193 -256.913842) (xy 95.572864 -256.880611) (xy 95.619022 -256.853962) (xy 95.668636 -256.83449)
			(xy 95.720598 -256.82263) (xy 95.773748 -256.818647) (xy 95.826898 -256.82263) (xy 95.87886 -256.83449)
			(xy 95.928474 -256.853962) (xy 95.974632 -256.880611) (xy 96.016303 -256.913842) (xy 96.052555 -256.952913)
			(xy 96.082579 -256.99695) (xy 96.105705 -257.044971) (xy 96.121415 -257.095901) (xy 96.129358 -257.148605)
			(xy 96.129856 -257.175254) (xy 96.129358 -257.201903) (xy 96.357938 -257.201903) (xy 96.357938 -257.148605)
			(xy 96.365881 -257.095901) (xy 96.381591 -257.044971) (xy 96.404717 -256.99695) (xy 96.434741 -256.952913)
			(xy 96.470993 -256.913842) (xy 96.512664 -256.880611) (xy 96.558822 -256.853962) (xy 96.608436 -256.83449)
			(xy 96.660398 -256.82263) (xy 96.713548 -256.818647) (xy 96.766698 -256.82263) (xy 96.81866 -256.83449)
			(xy 96.868274 -256.853962) (xy 96.914432 -256.880611) (xy 96.956103 -256.913842) (xy 96.992355 -256.952913)
			(xy 97.022379 -256.99695) (xy 97.045505 -257.044971) (xy 97.061215 -257.095901) (xy 97.069158 -257.148605)
			(xy 97.069656 -257.175254) (xy 97.069158 -257.201903) (xy 97.297484 -257.201903) (xy 97.297484 -257.148605)
			(xy 97.305427 -257.095901) (xy 97.321137 -257.044971) (xy 97.344263 -256.99695) (xy 97.374287 -256.952913)
			(xy 97.410539 -256.913842) (xy 97.45221 -256.880611) (xy 97.498368 -256.853962) (xy 97.547982 -256.83449)
			(xy 97.599944 -256.82263) (xy 97.653094 -256.818647) (xy 97.706244 -256.82263) (xy 97.758206 -256.83449)
			(xy 97.80782 -256.853962) (xy 97.853978 -256.880611) (xy 97.895649 -256.913842) (xy 97.931901 -256.952913)
			(xy 97.961925 -256.99695) (xy 97.985051 -257.044971) (xy 98.000761 -257.095901) (xy 98.008704 -257.148605)
			(xy 98.009202 -257.175254) (xy 98.008704 -257.201903) (xy 98.237538 -257.201903) (xy 98.237538 -257.148605)
			(xy 98.245481 -257.095901) (xy 98.261191 -257.044971) (xy 98.284317 -256.99695) (xy 98.314341 -256.952913)
			(xy 98.350593 -256.913842) (xy 98.392264 -256.880611) (xy 98.438422 -256.853962) (xy 98.488036 -256.83449)
			(xy 98.539998 -256.82263) (xy 98.593148 -256.818647) (xy 98.646298 -256.82263) (xy 98.69826 -256.83449)
			(xy 98.747874 -256.853962) (xy 98.794032 -256.880611) (xy 98.835703 -256.913842) (xy 98.871955 -256.952913)
			(xy 98.901979 -256.99695) (xy 98.925105 -257.044971) (xy 98.940815 -257.095901) (xy 98.948758 -257.148605)
			(xy 98.949256 -257.175254) (xy 98.948758 -257.201903) (xy 98.940815 -257.254607) (xy 98.925105 -257.305537)
			(xy 98.901979 -257.353558) (xy 98.871955 -257.397595) (xy 98.835703 -257.436666) (xy 98.794032 -257.469897)
			(xy 98.747874 -257.496546) (xy 98.69826 -257.516018) (xy 98.646298 -257.527878) (xy 98.593148 -257.531862)
			(xy 98.539998 -257.527878) (xy 98.488036 -257.516018) (xy 98.438422 -257.496546) (xy 98.392264 -257.469897)
			(xy 98.350593 -257.436666) (xy 98.314341 -257.397595) (xy 98.284317 -257.353558) (xy 98.261191 -257.305537)
			(xy 98.245481 -257.254607) (xy 98.237538 -257.201903) (xy 98.008704 -257.201903) (xy 98.000761 -257.254607)
			(xy 97.985051 -257.305537) (xy 97.961925 -257.353558) (xy 97.931901 -257.397595) (xy 97.895649 -257.436666)
			(xy 97.853978 -257.469897) (xy 97.80782 -257.496546) (xy 97.758206 -257.516018) (xy 97.706244 -257.527878)
			(xy 97.653094 -257.531862) (xy 97.599944 -257.527878) (xy 97.547982 -257.516018) (xy 97.498368 -257.496546)
			(xy 97.45221 -257.469897) (xy 97.410539 -257.436666) (xy 97.374287 -257.397595) (xy 97.344263 -257.353558)
			(xy 97.321137 -257.305537) (xy 97.305427 -257.254607) (xy 97.297484 -257.201903) (xy 97.069158 -257.201903)
			(xy 97.061215 -257.254607) (xy 97.045505 -257.305537) (xy 97.022379 -257.353558) (xy 96.992355 -257.397595)
			(xy 96.956103 -257.436666) (xy 96.914432 -257.469897) (xy 96.868274 -257.496546) (xy 96.81866 -257.516018)
			(xy 96.766698 -257.527878) (xy 96.713548 -257.531862) (xy 96.660398 -257.527878) (xy 96.608436 -257.516018)
			(xy 96.558822 -257.496546) (xy 96.512664 -257.469897) (xy 96.470993 -257.436666) (xy 96.434741 -257.397595)
			(xy 96.404717 -257.353558) (xy 96.381591 -257.305537) (xy 96.365881 -257.254607) (xy 96.357938 -257.201903)
			(xy 96.129358 -257.201903) (xy 96.121415 -257.254607) (xy 96.105705 -257.305537) (xy 96.082579 -257.353558)
			(xy 96.052555 -257.397595) (xy 96.016303 -257.436666) (xy 95.974632 -257.469897) (xy 95.928474 -257.496546)
			(xy 95.87886 -257.516018) (xy 95.826898 -257.527878) (xy 95.773748 -257.531862) (xy 95.720598 -257.527878)
			(xy 95.668636 -257.516018) (xy 95.619022 -257.496546) (xy 95.572864 -257.469897) (xy 95.531193 -257.436666)
			(xy 95.494941 -257.397595) (xy 95.464917 -257.353558) (xy 95.441791 -257.305537) (xy 95.426081 -257.254607)
			(xy 95.418138 -257.201903) (xy 95.189558 -257.201903) (xy 95.181615 -257.254607) (xy 95.165905 -257.305537)
			(xy 95.142779 -257.353558) (xy 95.112755 -257.397595) (xy 95.076503 -257.436666) (xy 95.034832 -257.469897)
			(xy 94.988674 -257.496546) (xy 94.93906 -257.516018) (xy 94.887098 -257.527878) (xy 94.833948 -257.531862)
			(xy 94.780798 -257.527878) (xy 94.728836 -257.516018) (xy 94.679222 -257.496546) (xy 94.633064 -257.469897)
			(xy 94.591393 -257.436666) (xy 94.555141 -257.397595) (xy 94.525117 -257.353558) (xy 94.501991 -257.305537)
			(xy 94.486281 -257.254607) (xy 94.478338 -257.201903) (xy 94.249758 -257.201903) (xy 94.241815 -257.254607)
			(xy 94.226105 -257.305537) (xy 94.202979 -257.353558) (xy 94.172955 -257.397595) (xy 94.136703 -257.436666)
			(xy 94.095032 -257.469897) (xy 94.048874 -257.496546) (xy 93.99926 -257.516018) (xy 93.947298 -257.527878)
			(xy 93.894148 -257.531862) (xy 93.840998 -257.527878) (xy 93.789036 -257.516018) (xy 93.739422 -257.496546)
			(xy 93.693264 -257.469897) (xy 93.651593 -257.436666) (xy 93.615341 -257.397595) (xy 93.585317 -257.353558)
			(xy 93.562191 -257.305537) (xy 93.546481 -257.254607) (xy 93.538538 -257.201903) (xy 93.309704 -257.201903)
			(xy 93.301761 -257.254607) (xy 93.286051 -257.305537) (xy 93.262925 -257.353558) (xy 93.232901 -257.397595)
			(xy 93.196649 -257.436666) (xy 93.154978 -257.469897) (xy 93.10882 -257.496546) (xy 93.059206 -257.516018)
			(xy 93.007244 -257.527878) (xy 92.954094 -257.531862) (xy 92.900944 -257.527878) (xy 92.848982 -257.516018)
			(xy 92.799368 -257.496546) (xy 92.75321 -257.469897) (xy 92.711539 -257.436666) (xy 92.675287 -257.397595)
			(xy 92.645263 -257.353558) (xy 92.622137 -257.305537) (xy 92.606427 -257.254607) (xy 92.598484 -257.201903)
			(xy 92.370158 -257.201903) (xy 92.362215 -257.254607) (xy 92.346505 -257.305537) (xy 92.323379 -257.353558)
			(xy 92.293355 -257.397595) (xy 92.257103 -257.436666) (xy 92.215432 -257.469897) (xy 92.169274 -257.496546)
			(xy 92.11966 -257.516018) (xy 92.067698 -257.527878) (xy 92.014548 -257.531862) (xy 91.961398 -257.527878)
			(xy 91.909436 -257.516018) (xy 91.859822 -257.496546) (xy 91.813664 -257.469897) (xy 91.771993 -257.436666)
			(xy 91.735741 -257.397595) (xy 91.705717 -257.353558) (xy 91.682591 -257.305537) (xy 91.666881 -257.254607)
			(xy 91.658938 -257.201903) (xy 91.430104 -257.201903) (xy 91.422161 -257.254607) (xy 91.406451 -257.305537)
			(xy 91.383325 -257.353558) (xy 91.353301 -257.397595) (xy 91.317049 -257.436666) (xy 91.275378 -257.469897)
			(xy 91.22922 -257.496546) (xy 91.179606 -257.516018) (xy 91.127644 -257.527878) (xy 91.074494 -257.531862)
			(xy 91.021344 -257.527878) (xy 90.969382 -257.516018) (xy 90.919768 -257.496546) (xy 90.87361 -257.469897)
			(xy 90.831939 -257.436666) (xy 90.795687 -257.397595) (xy 90.765663 -257.353558) (xy 90.742537 -257.305537)
			(xy 90.726827 -257.254607) (xy 90.718884 -257.201903) (xy 90.490304 -257.201903) (xy 90.482361 -257.254607)
			(xy 90.466651 -257.305537) (xy 90.443525 -257.353558) (xy 90.413501 -257.397595) (xy 90.377249 -257.436666)
			(xy 90.335578 -257.469897) (xy 90.28942 -257.496546) (xy 90.239806 -257.516018) (xy 90.187844 -257.527878)
			(xy 90.134694 -257.531862) (xy 90.081544 -257.527878) (xy 90.029582 -257.516018) (xy 89.979968 -257.496546)
			(xy 89.93381 -257.469897) (xy 89.892139 -257.436666) (xy 89.855887 -257.397595) (xy 89.825863 -257.353558)
			(xy 89.802737 -257.305537) (xy 89.787027 -257.254607) (xy 89.779084 -257.201903) (xy 89.550504 -257.201903)
			(xy 89.542561 -257.254607) (xy 89.526851 -257.305537) (xy 89.503725 -257.353558) (xy 89.473701 -257.397595)
			(xy 89.437449 -257.436666) (xy 89.395778 -257.469897) (xy 89.34962 -257.496546) (xy 89.300006 -257.516018)
			(xy 89.248044 -257.527878) (xy 89.194894 -257.531862) (xy 89.141744 -257.527878) (xy 89.089782 -257.516018)
			(xy 89.040168 -257.496546) (xy 88.99401 -257.469897) (xy 88.952339 -257.436666) (xy 88.916087 -257.397595)
			(xy 88.886063 -257.353558) (xy 88.862937 -257.305537) (xy 88.847227 -257.254607) (xy 88.839284 -257.201903)
			(xy 88.688418 -257.201903) (xy 88.688418 -257.582416) (xy 88.688864 -257.592207) (xy 88.696197 -257.610365)
			(xy 88.70979 -257.624461) (xy 88.72767 -257.632447) (xy 88.73744 -257.633216) (xy 88.764767 -257.634672)
			(xy 88.81852 -257.644928) (xy 88.870072 -257.663286) (xy 88.918208 -257.689314) (xy 88.961795 -257.722401)
			(xy 88.999808 -257.761765) (xy 89.031351 -257.806482) (xy 89.055683 -257.855498) (xy 89.072229 -257.907659)
			(xy 89.080601 -257.961738) (xy 89.080601 -258.015719) (xy 89.309184 -258.015719) (xy 89.309184 -257.962421)
			(xy 89.317127 -257.909717) (xy 89.332837 -257.858787) (xy 89.355963 -257.810766) (xy 89.385987 -257.766729)
			(xy 89.422239 -257.727658) (xy 89.46391 -257.694427) (xy 89.510068 -257.667778) (xy 89.559682 -257.648306)
			(xy 89.611644 -257.636446) (xy 89.664794 -257.632463) (xy 89.717944 -257.636446) (xy 89.769906 -257.648306)
			(xy 89.81952 -257.667778) (xy 89.865678 -257.694427) (xy 89.907349 -257.727658) (xy 89.943601 -257.766729)
			(xy 89.973625 -257.810766) (xy 89.996751 -257.858787) (xy 90.012461 -257.909717) (xy 90.020404 -257.962421)
			(xy 90.020902 -257.98907) (xy 90.020404 -258.015719) (xy 90.249238 -258.015719) (xy 90.249238 -257.962421)
			(xy 90.257181 -257.909717) (xy 90.272891 -257.858787) (xy 90.296017 -257.810766) (xy 90.326041 -257.766729)
			(xy 90.362293 -257.727658) (xy 90.403964 -257.694427) (xy 90.450122 -257.667778) (xy 90.499736 -257.648306)
			(xy 90.551698 -257.636446) (xy 90.604848 -257.632463) (xy 90.657998 -257.636446) (xy 90.70996 -257.648306)
			(xy 90.759574 -257.667778) (xy 90.805732 -257.694427) (xy 90.847403 -257.727658) (xy 90.883655 -257.766729)
			(xy 90.913679 -257.810766) (xy 90.936805 -257.858787) (xy 90.952515 -257.909717) (xy 90.960458 -257.962421)
			(xy 90.960956 -257.98907) (xy 90.960458 -258.015719) (xy 91.188784 -258.015719) (xy 91.188784 -257.962421)
			(xy 91.196727 -257.909717) (xy 91.212437 -257.858787) (xy 91.235563 -257.810766) (xy 91.265587 -257.766729)
			(xy 91.301839 -257.727658) (xy 91.34351 -257.694427) (xy 91.389668 -257.667778) (xy 91.439282 -257.648306)
			(xy 91.491244 -257.636446) (xy 91.544394 -257.632463) (xy 91.597544 -257.636446) (xy 91.649506 -257.648306)
			(xy 91.69912 -257.667778) (xy 91.745278 -257.694427) (xy 91.786949 -257.727658) (xy 91.823201 -257.766729)
			(xy 91.853225 -257.810766) (xy 91.876351 -257.858787) (xy 91.892061 -257.909717) (xy 91.900004 -257.962421)
			(xy 91.900502 -257.98907) (xy 91.900004 -258.015719) (xy 92.128838 -258.015719) (xy 92.128838 -257.962421)
			(xy 92.136781 -257.909717) (xy 92.152491 -257.858787) (xy 92.175617 -257.810766) (xy 92.205641 -257.766729)
			(xy 92.241893 -257.727658) (xy 92.283564 -257.694427) (xy 92.329722 -257.667778) (xy 92.379336 -257.648306)
			(xy 92.431298 -257.636446) (xy 92.484448 -257.632463) (xy 92.537598 -257.636446) (xy 92.58956 -257.648306)
			(xy 92.639174 -257.667778) (xy 92.685332 -257.694427) (xy 92.727003 -257.727658) (xy 92.763255 -257.766729)
			(xy 92.793279 -257.810766) (xy 92.816405 -257.858787) (xy 92.832115 -257.909717) (xy 92.840058 -257.962421)
			(xy 92.840556 -257.98907) (xy 92.840058 -258.015719) (xy 93.068384 -258.015719) (xy 93.068384 -257.962421)
			(xy 93.076327 -257.909717) (xy 93.092037 -257.858787) (xy 93.115163 -257.810766) (xy 93.145187 -257.766729)
			(xy 93.181439 -257.727658) (xy 93.22311 -257.694427) (xy 93.269268 -257.667778) (xy 93.318882 -257.648306)
			(xy 93.370844 -257.636446) (xy 93.423994 -257.632463) (xy 93.477144 -257.636446) (xy 93.529106 -257.648306)
			(xy 93.57872 -257.667778) (xy 93.624878 -257.694427) (xy 93.666549 -257.727658) (xy 93.702801 -257.766729)
			(xy 93.732825 -257.810766) (xy 93.755951 -257.858787) (xy 93.771661 -257.909717) (xy 93.779604 -257.962421)
			(xy 93.780102 -257.98907) (xy 93.779604 -258.015719) (xy 94.008184 -258.015719) (xy 94.008184 -257.962421)
			(xy 94.016127 -257.909717) (xy 94.031837 -257.858787) (xy 94.054963 -257.810766) (xy 94.084987 -257.766729)
			(xy 94.121239 -257.727658) (xy 94.16291 -257.694427) (xy 94.209068 -257.667778) (xy 94.258682 -257.648306)
			(xy 94.310644 -257.636446) (xy 94.363794 -257.632463) (xy 94.416944 -257.636446) (xy 94.468906 -257.648306)
			(xy 94.51852 -257.667778) (xy 94.564678 -257.694427) (xy 94.606349 -257.727658) (xy 94.642601 -257.766729)
			(xy 94.672625 -257.810766) (xy 94.695751 -257.858787) (xy 94.711461 -257.909717) (xy 94.719404 -257.962421)
			(xy 94.719902 -257.98907) (xy 94.719404 -258.015719) (xy 94.947984 -258.015719) (xy 94.947984 -257.962421)
			(xy 94.955927 -257.909717) (xy 94.971637 -257.858787) (xy 94.994763 -257.810766) (xy 95.024787 -257.766729)
			(xy 95.061039 -257.727658) (xy 95.10271 -257.694427) (xy 95.148868 -257.667778) (xy 95.198482 -257.648306)
			(xy 95.250444 -257.636446) (xy 95.303594 -257.632463) (xy 95.356744 -257.636446) (xy 95.408706 -257.648306)
			(xy 95.45832 -257.667778) (xy 95.504478 -257.694427) (xy 95.546149 -257.727658) (xy 95.582401 -257.766729)
			(xy 95.612425 -257.810766) (xy 95.635551 -257.858787) (xy 95.651261 -257.909717) (xy 95.659204 -257.962421)
			(xy 95.659702 -257.98907) (xy 95.659204 -258.015719) (xy 95.887784 -258.015719) (xy 95.887784 -257.962421)
			(xy 95.895727 -257.909717) (xy 95.911437 -257.858787) (xy 95.934563 -257.810766) (xy 95.964587 -257.766729)
			(xy 96.000839 -257.727658) (xy 96.04251 -257.694427) (xy 96.088668 -257.667778) (xy 96.138282 -257.648306)
			(xy 96.190244 -257.636446) (xy 96.243394 -257.632463) (xy 96.296544 -257.636446) (xy 96.348506 -257.648306)
			(xy 96.39812 -257.667778) (xy 96.444278 -257.694427) (xy 96.485949 -257.727658) (xy 96.522201 -257.766729)
			(xy 96.552225 -257.810766) (xy 96.575351 -257.858787) (xy 96.591061 -257.909717) (xy 96.599004 -257.962421)
			(xy 96.599502 -257.98907) (xy 96.599004 -258.015719) (xy 96.827838 -258.015719) (xy 96.827838 -257.962421)
			(xy 96.835781 -257.909717) (xy 96.851491 -257.858787) (xy 96.874617 -257.810766) (xy 96.904641 -257.766729)
			(xy 96.940893 -257.727658) (xy 96.982564 -257.694427) (xy 97.028722 -257.667778) (xy 97.078336 -257.648306)
			(xy 97.130298 -257.636446) (xy 97.183448 -257.632463) (xy 97.236598 -257.636446) (xy 97.28856 -257.648306)
			(xy 97.338174 -257.667778) (xy 97.384332 -257.694427) (xy 97.426003 -257.727658) (xy 97.462255 -257.766729)
			(xy 97.492279 -257.810766) (xy 97.515405 -257.858787) (xy 97.531115 -257.909717) (xy 97.539058 -257.962421)
			(xy 97.539556 -257.98907) (xy 97.539058 -258.015719) (xy 97.767384 -258.015719) (xy 97.767384 -257.962421)
			(xy 97.775327 -257.909717) (xy 97.791037 -257.858787) (xy 97.814163 -257.810766) (xy 97.844187 -257.766729)
			(xy 97.880439 -257.727658) (xy 97.92211 -257.694427) (xy 97.968268 -257.667778) (xy 98.017882 -257.648306)
			(xy 98.069844 -257.636446) (xy 98.122994 -257.632463) (xy 98.176144 -257.636446) (xy 98.228106 -257.648306)
			(xy 98.27772 -257.667778) (xy 98.323878 -257.694427) (xy 98.365549 -257.727658) (xy 98.401801 -257.766729)
			(xy 98.431825 -257.810766) (xy 98.454951 -257.858787) (xy 98.470661 -257.909717) (xy 98.478604 -257.962421)
			(xy 98.479102 -257.98907) (xy 98.478604 -258.015719) (xy 98.707438 -258.015719) (xy 98.707438 -257.962421)
			(xy 98.715381 -257.909717) (xy 98.731091 -257.858787) (xy 98.754217 -257.810766) (xy 98.784241 -257.766729)
			(xy 98.820493 -257.727658) (xy 98.862164 -257.694427) (xy 98.908322 -257.667778) (xy 98.957936 -257.648306)
			(xy 99.009898 -257.636446) (xy 99.063048 -257.632463) (xy 99.116198 -257.636446) (xy 99.16816 -257.648306)
			(xy 99.217774 -257.667778) (xy 99.263932 -257.694427) (xy 99.305603 -257.727658) (xy 99.341855 -257.766729)
			(xy 99.371879 -257.810766) (xy 99.395005 -257.858787) (xy 99.410715 -257.909717) (xy 99.418658 -257.962421)
			(xy 99.419156 -257.98907) (xy 99.418658 -258.015719) (xy 99.410715 -258.068423) (xy 99.395005 -258.119353)
			(xy 99.371879 -258.167374) (xy 99.341855 -258.211411) (xy 99.305603 -258.250482) (xy 99.263932 -258.283713)
			(xy 99.217774 -258.310362) (xy 99.16816 -258.329834) (xy 99.116198 -258.341694) (xy 99.063048 -258.345678)
			(xy 99.009898 -258.341694) (xy 98.957936 -258.329834) (xy 98.908322 -258.310362) (xy 98.862164 -258.283713)
			(xy 98.820493 -258.250482) (xy 98.784241 -258.211411) (xy 98.754217 -258.167374) (xy 98.731091 -258.119353)
			(xy 98.715381 -258.068423) (xy 98.707438 -258.015719) (xy 98.478604 -258.015719) (xy 98.470661 -258.068423)
			(xy 98.454951 -258.119353) (xy 98.431825 -258.167374) (xy 98.401801 -258.211411) (xy 98.365549 -258.250482)
			(xy 98.323878 -258.283713) (xy 98.27772 -258.310362) (xy 98.228106 -258.329834) (xy 98.176144 -258.341694)
			(xy 98.122994 -258.345678) (xy 98.069844 -258.341694) (xy 98.017882 -258.329834) (xy 97.968268 -258.310362)
			(xy 97.92211 -258.283713) (xy 97.880439 -258.250482) (xy 97.844187 -258.211411) (xy 97.814163 -258.167374)
			(xy 97.791037 -258.119353) (xy 97.775327 -258.068423) (xy 97.767384 -258.015719) (xy 97.539058 -258.015719)
			(xy 97.531115 -258.068423) (xy 97.515405 -258.119353) (xy 97.492279 -258.167374) (xy 97.462255 -258.211411)
			(xy 97.426003 -258.250482) (xy 97.384332 -258.283713) (xy 97.338174 -258.310362) (xy 97.28856 -258.329834)
			(xy 97.236598 -258.341694) (xy 97.183448 -258.345678) (xy 97.130298 -258.341694) (xy 97.078336 -258.329834)
			(xy 97.028722 -258.310362) (xy 96.982564 -258.283713) (xy 96.940893 -258.250482) (xy 96.904641 -258.211411)
			(xy 96.874617 -258.167374) (xy 96.851491 -258.119353) (xy 96.835781 -258.068423) (xy 96.827838 -258.015719)
			(xy 96.599004 -258.015719) (xy 96.591061 -258.068423) (xy 96.575351 -258.119353) (xy 96.552225 -258.167374)
			(xy 96.522201 -258.211411) (xy 96.485949 -258.250482) (xy 96.444278 -258.283713) (xy 96.39812 -258.310362)
			(xy 96.348506 -258.329834) (xy 96.296544 -258.341694) (xy 96.243394 -258.345678) (xy 96.190244 -258.341694)
			(xy 96.138282 -258.329834) (xy 96.088668 -258.310362) (xy 96.04251 -258.283713) (xy 96.000839 -258.250482)
			(xy 95.964587 -258.211411) (xy 95.934563 -258.167374) (xy 95.911437 -258.119353) (xy 95.895727 -258.068423)
			(xy 95.887784 -258.015719) (xy 95.659204 -258.015719) (xy 95.651261 -258.068423) (xy 95.635551 -258.119353)
			(xy 95.612425 -258.167374) (xy 95.582401 -258.211411) (xy 95.546149 -258.250482) (xy 95.504478 -258.283713)
			(xy 95.45832 -258.310362) (xy 95.408706 -258.329834) (xy 95.356744 -258.341694) (xy 95.303594 -258.345678)
			(xy 95.250444 -258.341694) (xy 95.198482 -258.329834) (xy 95.148868 -258.310362) (xy 95.10271 -258.283713)
			(xy 95.061039 -258.250482) (xy 95.024787 -258.211411) (xy 94.994763 -258.167374) (xy 94.971637 -258.119353)
			(xy 94.955927 -258.068423) (xy 94.947984 -258.015719) (xy 94.719404 -258.015719) (xy 94.711461 -258.068423)
			(xy 94.695751 -258.119353) (xy 94.672625 -258.167374) (xy 94.642601 -258.211411) (xy 94.606349 -258.250482)
			(xy 94.564678 -258.283713) (xy 94.51852 -258.310362) (xy 94.468906 -258.329834) (xy 94.416944 -258.341694)
			(xy 94.363794 -258.345678) (xy 94.310644 -258.341694) (xy 94.258682 -258.329834) (xy 94.209068 -258.310362)
			(xy 94.16291 -258.283713) (xy 94.121239 -258.250482) (xy 94.084987 -258.211411) (xy 94.054963 -258.167374)
			(xy 94.031837 -258.119353) (xy 94.016127 -258.068423) (xy 94.008184 -258.015719) (xy 93.779604 -258.015719)
			(xy 93.771661 -258.068423) (xy 93.755951 -258.119353) (xy 93.732825 -258.167374) (xy 93.702801 -258.211411)
			(xy 93.666549 -258.250482) (xy 93.624878 -258.283713) (xy 93.57872 -258.310362) (xy 93.529106 -258.329834)
			(xy 93.477144 -258.341694) (xy 93.423994 -258.345678) (xy 93.370844 -258.341694) (xy 93.318882 -258.329834)
			(xy 93.269268 -258.310362) (xy 93.22311 -258.283713) (xy 93.181439 -258.250482) (xy 93.145187 -258.211411)
			(xy 93.115163 -258.167374) (xy 93.092037 -258.119353) (xy 93.076327 -258.068423) (xy 93.068384 -258.015719)
			(xy 92.840058 -258.015719) (xy 92.832115 -258.068423) (xy 92.816405 -258.119353) (xy 92.793279 -258.167374)
			(xy 92.763255 -258.211411) (xy 92.727003 -258.250482) (xy 92.685332 -258.283713) (xy 92.639174 -258.310362)
			(xy 92.58956 -258.329834) (xy 92.537598 -258.341694) (xy 92.484448 -258.345678) (xy 92.431298 -258.341694)
			(xy 92.379336 -258.329834) (xy 92.329722 -258.310362) (xy 92.283564 -258.283713) (xy 92.241893 -258.250482)
			(xy 92.205641 -258.211411) (xy 92.175617 -258.167374) (xy 92.152491 -258.119353) (xy 92.136781 -258.068423)
			(xy 92.128838 -258.015719) (xy 91.900004 -258.015719) (xy 91.892061 -258.068423) (xy 91.876351 -258.119353)
			(xy 91.853225 -258.167374) (xy 91.823201 -258.211411) (xy 91.786949 -258.250482) (xy 91.745278 -258.283713)
			(xy 91.69912 -258.310362) (xy 91.649506 -258.329834) (xy 91.597544 -258.341694) (xy 91.544394 -258.345678)
			(xy 91.491244 -258.341694) (xy 91.439282 -258.329834) (xy 91.389668 -258.310362) (xy 91.34351 -258.283713)
			(xy 91.301839 -258.250482) (xy 91.265587 -258.211411) (xy 91.235563 -258.167374) (xy 91.212437 -258.119353)
			(xy 91.196727 -258.068423) (xy 91.188784 -258.015719) (xy 90.960458 -258.015719) (xy 90.952515 -258.068423)
			(xy 90.936805 -258.119353) (xy 90.913679 -258.167374) (xy 90.883655 -258.211411) (xy 90.847403 -258.250482)
			(xy 90.805732 -258.283713) (xy 90.759574 -258.310362) (xy 90.70996 -258.329834) (xy 90.657998 -258.341694)
			(xy 90.604848 -258.345678) (xy 90.551698 -258.341694) (xy 90.499736 -258.329834) (xy 90.450122 -258.310362)
			(xy 90.403964 -258.283713) (xy 90.362293 -258.250482) (xy 90.326041 -258.211411) (xy 90.296017 -258.167374)
			(xy 90.272891 -258.119353) (xy 90.257181 -258.068423) (xy 90.249238 -258.015719) (xy 90.020404 -258.015719)
			(xy 90.012461 -258.068423) (xy 89.996751 -258.119353) (xy 89.973625 -258.167374) (xy 89.943601 -258.211411)
			(xy 89.907349 -258.250482) (xy 89.865678 -258.283713) (xy 89.81952 -258.310362) (xy 89.769906 -258.329834)
			(xy 89.717944 -258.341694) (xy 89.664794 -258.345678) (xy 89.611644 -258.341694) (xy 89.559682 -258.329834)
			(xy 89.510068 -258.310362) (xy 89.46391 -258.283713) (xy 89.422239 -258.250482) (xy 89.385987 -258.211411)
			(xy 89.355963 -258.167374) (xy 89.332837 -258.119353) (xy 89.317127 -258.068423) (xy 89.309184 -258.015719)
			(xy 89.080601 -258.015719) (xy 89.080601 -258.01646) (xy 89.072229 -258.070539) (xy 89.055683 -258.1227)
			(xy 89.031353 -258.171716) (xy 88.999809 -258.216433) (xy 88.961797 -258.255798) (xy 88.918209 -258.288884)
			(xy 88.870073 -258.314913) (xy 88.818522 -258.333272) (xy 88.764769 -258.343528) (xy 88.73744 -258.344924)
			(xy 88.727667 -258.345709) (xy 88.709773 -258.353675) (xy 88.696167 -258.367766) (xy 88.688835 -258.38593)
			(xy 88.688418 -258.395724) (xy 88.688418 -258.829789) (xy 88.839284 -258.829789) (xy 88.839284 -258.776491)
			(xy 88.847227 -258.723787) (xy 88.862937 -258.672857) (xy 88.886063 -258.624836) (xy 88.916087 -258.580799)
			(xy 88.952339 -258.541728) (xy 88.99401 -258.508497) (xy 89.040168 -258.481848) (xy 89.089782 -258.462376)
			(xy 89.141744 -258.450516) (xy 89.194894 -258.446533) (xy 89.248044 -258.450516) (xy 89.300006 -258.462376)
			(xy 89.34962 -258.481848) (xy 89.395778 -258.508497) (xy 89.437449 -258.541728) (xy 89.473701 -258.580799)
			(xy 89.503725 -258.624836) (xy 89.526851 -258.672857) (xy 89.542561 -258.723787) (xy 89.550504 -258.776491)
			(xy 89.551002 -258.80314) (xy 89.550504 -258.829789) (xy 89.779084 -258.829789) (xy 89.779084 -258.776491)
			(xy 89.787027 -258.723787) (xy 89.802737 -258.672857) (xy 89.825863 -258.624836) (xy 89.855887 -258.580799)
			(xy 89.892139 -258.541728) (xy 89.93381 -258.508497) (xy 89.979968 -258.481848) (xy 90.029582 -258.462376)
			(xy 90.081544 -258.450516) (xy 90.134694 -258.446533) (xy 90.187844 -258.450516) (xy 90.239806 -258.462376)
			(xy 90.28942 -258.481848) (xy 90.335578 -258.508497) (xy 90.377249 -258.541728) (xy 90.413501 -258.580799)
			(xy 90.443525 -258.624836) (xy 90.466651 -258.672857) (xy 90.482361 -258.723787) (xy 90.490304 -258.776491)
			(xy 90.490802 -258.80314) (xy 90.490304 -258.829789) (xy 90.719138 -258.829789) (xy 90.719138 -258.776491)
			(xy 90.727081 -258.723787) (xy 90.742791 -258.672857) (xy 90.765917 -258.624836) (xy 90.795941 -258.580799)
			(xy 90.832193 -258.541728) (xy 90.873864 -258.508497) (xy 90.920022 -258.481848) (xy 90.969636 -258.462376)
			(xy 91.021598 -258.450516) (xy 91.074748 -258.446533) (xy 91.127898 -258.450516) (xy 91.17986 -258.462376)
			(xy 91.229474 -258.481848) (xy 91.275632 -258.508497) (xy 91.317303 -258.541728) (xy 91.353555 -258.580799)
			(xy 91.383579 -258.624836) (xy 91.406705 -258.672857) (xy 91.422415 -258.723787) (xy 91.430358 -258.776491)
			(xy 91.430856 -258.80314) (xy 91.430358 -258.829789) (xy 91.658938 -258.829789) (xy 91.658938 -258.776491)
			(xy 91.666881 -258.723787) (xy 91.682591 -258.672857) (xy 91.705717 -258.624836) (xy 91.735741 -258.580799)
			(xy 91.771993 -258.541728) (xy 91.813664 -258.508497) (xy 91.859822 -258.481848) (xy 91.909436 -258.462376)
			(xy 91.961398 -258.450516) (xy 92.014548 -258.446533) (xy 92.067698 -258.450516) (xy 92.11966 -258.462376)
			(xy 92.169274 -258.481848) (xy 92.215432 -258.508497) (xy 92.257103 -258.541728) (xy 92.293355 -258.580799)
			(xy 92.323379 -258.624836) (xy 92.346505 -258.672857) (xy 92.362215 -258.723787) (xy 92.370158 -258.776491)
			(xy 92.370656 -258.80314) (xy 92.370158 -258.829789) (xy 92.598738 -258.829789) (xy 92.598738 -258.776491)
			(xy 92.606681 -258.723787) (xy 92.622391 -258.672857) (xy 92.645517 -258.624836) (xy 92.675541 -258.580799)
			(xy 92.711793 -258.541728) (xy 92.753464 -258.508497) (xy 92.799622 -258.481848) (xy 92.849236 -258.462376)
			(xy 92.901198 -258.450516) (xy 92.954348 -258.446533) (xy 93.007498 -258.450516) (xy 93.05946 -258.462376)
			(xy 93.109074 -258.481848) (xy 93.155232 -258.508497) (xy 93.196903 -258.541728) (xy 93.233155 -258.580799)
			(xy 93.263179 -258.624836) (xy 93.286305 -258.672857) (xy 93.302015 -258.723787) (xy 93.309958 -258.776491)
			(xy 93.310456 -258.80314) (xy 93.309958 -258.829789) (xy 93.538538 -258.829789) (xy 93.538538 -258.776491)
			(xy 93.546481 -258.723787) (xy 93.562191 -258.672857) (xy 93.585317 -258.624836) (xy 93.615341 -258.580799)
			(xy 93.651593 -258.541728) (xy 93.693264 -258.508497) (xy 93.739422 -258.481848) (xy 93.789036 -258.462376)
			(xy 93.840998 -258.450516) (xy 93.894148 -258.446533) (xy 93.947298 -258.450516) (xy 93.99926 -258.462376)
			(xy 94.048874 -258.481848) (xy 94.095032 -258.508497) (xy 94.136703 -258.541728) (xy 94.172955 -258.580799)
			(xy 94.202979 -258.624836) (xy 94.226105 -258.672857) (xy 94.241815 -258.723787) (xy 94.249758 -258.776491)
			(xy 94.250256 -258.80314) (xy 94.249758 -258.829789) (xy 94.478084 -258.829789) (xy 94.478084 -258.776491)
			(xy 94.486027 -258.723787) (xy 94.501737 -258.672857) (xy 94.524863 -258.624836) (xy 94.554887 -258.580799)
			(xy 94.591139 -258.541728) (xy 94.63281 -258.508497) (xy 94.678968 -258.481848) (xy 94.728582 -258.462376)
			(xy 94.780544 -258.450516) (xy 94.833694 -258.446533) (xy 94.886844 -258.450516) (xy 94.938806 -258.462376)
			(xy 94.98842 -258.481848) (xy 95.034578 -258.508497) (xy 95.076249 -258.541728) (xy 95.112501 -258.580799)
			(xy 95.142525 -258.624836) (xy 95.165651 -258.672857) (xy 95.181361 -258.723787) (xy 95.189304 -258.776491)
			(xy 95.189802 -258.80314) (xy 95.189304 -258.829789) (xy 95.418138 -258.829789) (xy 95.418138 -258.776491)
			(xy 95.426081 -258.723787) (xy 95.441791 -258.672857) (xy 95.464917 -258.624836) (xy 95.494941 -258.580799)
			(xy 95.531193 -258.541728) (xy 95.572864 -258.508497) (xy 95.619022 -258.481848) (xy 95.668636 -258.462376)
			(xy 95.720598 -258.450516) (xy 95.773748 -258.446533) (xy 95.826898 -258.450516) (xy 95.87886 -258.462376)
			(xy 95.928474 -258.481848) (xy 95.974632 -258.508497) (xy 96.016303 -258.541728) (xy 96.052555 -258.580799)
			(xy 96.082579 -258.624836) (xy 96.105705 -258.672857) (xy 96.121415 -258.723787) (xy 96.129358 -258.776491)
			(xy 96.129856 -258.80314) (xy 96.129358 -258.829789) (xy 96.357938 -258.829789) (xy 96.357938 -258.776491)
			(xy 96.365881 -258.723787) (xy 96.381591 -258.672857) (xy 96.404717 -258.624836) (xy 96.434741 -258.580799)
			(xy 96.470993 -258.541728) (xy 96.512664 -258.508497) (xy 96.558822 -258.481848) (xy 96.608436 -258.462376)
			(xy 96.660398 -258.450516) (xy 96.713548 -258.446533) (xy 96.766698 -258.450516) (xy 96.81866 -258.462376)
			(xy 96.868274 -258.481848) (xy 96.914432 -258.508497) (xy 96.956103 -258.541728) (xy 96.992355 -258.580799)
			(xy 97.022379 -258.624836) (xy 97.045505 -258.672857) (xy 97.061215 -258.723787) (xy 97.069158 -258.776491)
			(xy 97.069656 -258.80314) (xy 97.069158 -258.829789) (xy 97.297738 -258.829789) (xy 97.297738 -258.776491)
			(xy 97.305681 -258.723787) (xy 97.321391 -258.672857) (xy 97.344517 -258.624836) (xy 97.374541 -258.580799)
			(xy 97.410793 -258.541728) (xy 97.452464 -258.508497) (xy 97.498622 -258.481848) (xy 97.548236 -258.462376)
			(xy 97.600198 -258.450516) (xy 97.653348 -258.446533) (xy 97.706498 -258.450516) (xy 97.75846 -258.462376)
			(xy 97.808074 -258.481848) (xy 97.854232 -258.508497) (xy 97.895903 -258.541728) (xy 97.932155 -258.580799)
			(xy 97.962179 -258.624836) (xy 97.985305 -258.672857) (xy 98.001015 -258.723787) (xy 98.008958 -258.776491)
			(xy 98.009456 -258.80314) (xy 98.008958 -258.829789) (xy 98.237538 -258.829789) (xy 98.237538 -258.776491)
			(xy 98.245481 -258.723787) (xy 98.261191 -258.672857) (xy 98.284317 -258.624836) (xy 98.314341 -258.580799)
			(xy 98.350593 -258.541728) (xy 98.392264 -258.508497) (xy 98.438422 -258.481848) (xy 98.488036 -258.462376)
			(xy 98.539998 -258.450516) (xy 98.593148 -258.446533) (xy 98.646298 -258.450516) (xy 98.69826 -258.462376)
			(xy 98.747874 -258.481848) (xy 98.794032 -258.508497) (xy 98.835703 -258.541728) (xy 98.871955 -258.580799)
			(xy 98.901979 -258.624836) (xy 98.925105 -258.672857) (xy 98.940815 -258.723787) (xy 98.948758 -258.776491)
			(xy 98.949256 -258.80314) (xy 98.948758 -258.829789) (xy 98.940815 -258.882493) (xy 98.925105 -258.933423)
			(xy 98.901979 -258.981444) (xy 98.871955 -259.025481) (xy 98.835703 -259.064552) (xy 98.794032 -259.097783)
			(xy 98.747874 -259.124432) (xy 98.69826 -259.143904) (xy 98.646298 -259.155764) (xy 98.593148 -259.159748)
			(xy 98.539998 -259.155764) (xy 98.488036 -259.143904) (xy 98.438422 -259.124432) (xy 98.392264 -259.097783)
			(xy 98.350593 -259.064552) (xy 98.314341 -259.025481) (xy 98.284317 -258.981444) (xy 98.261191 -258.933423)
			(xy 98.245481 -258.882493) (xy 98.237538 -258.829789) (xy 98.008958 -258.829789) (xy 98.001015 -258.882493)
			(xy 97.985305 -258.933423) (xy 97.962179 -258.981444) (xy 97.932155 -259.025481) (xy 97.895903 -259.064552)
			(xy 97.854232 -259.097783) (xy 97.808074 -259.124432) (xy 97.75846 -259.143904) (xy 97.706498 -259.155764)
			(xy 97.653348 -259.159748) (xy 97.600198 -259.155764) (xy 97.548236 -259.143904) (xy 97.498622 -259.124432)
			(xy 97.452464 -259.097783) (xy 97.410793 -259.064552) (xy 97.374541 -259.025481) (xy 97.344517 -258.981444)
			(xy 97.321391 -258.933423) (xy 97.305681 -258.882493) (xy 97.297738 -258.829789) (xy 97.069158 -258.829789)
			(xy 97.061215 -258.882493) (xy 97.045505 -258.933423) (xy 97.022379 -258.981444) (xy 96.992355 -259.025481)
			(xy 96.956103 -259.064552) (xy 96.914432 -259.097783) (xy 96.868274 -259.124432) (xy 96.81866 -259.143904)
			(xy 96.766698 -259.155764) (xy 96.713548 -259.159748) (xy 96.660398 -259.155764) (xy 96.608436 -259.143904)
			(xy 96.558822 -259.124432) (xy 96.512664 -259.097783) (xy 96.470993 -259.064552) (xy 96.434741 -259.025481)
			(xy 96.404717 -258.981444) (xy 96.381591 -258.933423) (xy 96.365881 -258.882493) (xy 96.357938 -258.829789)
			(xy 96.129358 -258.829789) (xy 96.121415 -258.882493) (xy 96.105705 -258.933423) (xy 96.082579 -258.981444)
			(xy 96.052555 -259.025481) (xy 96.016303 -259.064552) (xy 95.974632 -259.097783) (xy 95.928474 -259.124432)
			(xy 95.87886 -259.143904) (xy 95.826898 -259.155764) (xy 95.773748 -259.159748) (xy 95.720598 -259.155764)
			(xy 95.668636 -259.143904) (xy 95.619022 -259.124432) (xy 95.572864 -259.097783) (xy 95.531193 -259.064552)
			(xy 95.494941 -259.025481) (xy 95.464917 -258.981444) (xy 95.441791 -258.933423) (xy 95.426081 -258.882493)
			(xy 95.418138 -258.829789) (xy 95.189304 -258.829789) (xy 95.181361 -258.882493) (xy 95.165651 -258.933423)
			(xy 95.142525 -258.981444) (xy 95.112501 -259.025481) (xy 95.076249 -259.064552) (xy 95.034578 -259.097783)
			(xy 94.98842 -259.124432) (xy 94.938806 -259.143904) (xy 94.886844 -259.155764) (xy 94.833694 -259.159748)
			(xy 94.780544 -259.155764) (xy 94.728582 -259.143904) (xy 94.678968 -259.124432) (xy 94.63281 -259.097783)
			(xy 94.591139 -259.064552) (xy 94.554887 -259.025481) (xy 94.524863 -258.981444) (xy 94.501737 -258.933423)
			(xy 94.486027 -258.882493) (xy 94.478084 -258.829789) (xy 94.249758 -258.829789) (xy 94.241815 -258.882493)
			(xy 94.226105 -258.933423) (xy 94.202979 -258.981444) (xy 94.172955 -259.025481) (xy 94.136703 -259.064552)
			(xy 94.095032 -259.097783) (xy 94.048874 -259.124432) (xy 93.99926 -259.143904) (xy 93.947298 -259.155764)
			(xy 93.894148 -259.159748) (xy 93.840998 -259.155764) (xy 93.789036 -259.143904) (xy 93.739422 -259.124432)
			(xy 93.693264 -259.097783) (xy 93.651593 -259.064552) (xy 93.615341 -259.025481) (xy 93.585317 -258.981444)
			(xy 93.562191 -258.933423) (xy 93.546481 -258.882493) (xy 93.538538 -258.829789) (xy 93.309958 -258.829789)
			(xy 93.302015 -258.882493) (xy 93.286305 -258.933423) (xy 93.263179 -258.981444) (xy 93.233155 -259.025481)
			(xy 93.196903 -259.064552) (xy 93.155232 -259.097783) (xy 93.109074 -259.124432) (xy 93.05946 -259.143904)
			(xy 93.007498 -259.155764) (xy 92.954348 -259.159748) (xy 92.901198 -259.155764) (xy 92.849236 -259.143904)
			(xy 92.799622 -259.124432) (xy 92.753464 -259.097783) (xy 92.711793 -259.064552) (xy 92.675541 -259.025481)
			(xy 92.645517 -258.981444) (xy 92.622391 -258.933423) (xy 92.606681 -258.882493) (xy 92.598738 -258.829789)
			(xy 92.370158 -258.829789) (xy 92.362215 -258.882493) (xy 92.346505 -258.933423) (xy 92.323379 -258.981444)
			(xy 92.293355 -259.025481) (xy 92.257103 -259.064552) (xy 92.215432 -259.097783) (xy 92.169274 -259.124432)
			(xy 92.11966 -259.143904) (xy 92.067698 -259.155764) (xy 92.014548 -259.159748) (xy 91.961398 -259.155764)
			(xy 91.909436 -259.143904) (xy 91.859822 -259.124432) (xy 91.813664 -259.097783) (xy 91.771993 -259.064552)
			(xy 91.735741 -259.025481) (xy 91.705717 -258.981444) (xy 91.682591 -258.933423) (xy 91.666881 -258.882493)
			(xy 91.658938 -258.829789) (xy 91.430358 -258.829789) (xy 91.422415 -258.882493) (xy 91.406705 -258.933423)
			(xy 91.383579 -258.981444) (xy 91.353555 -259.025481) (xy 91.317303 -259.064552) (xy 91.275632 -259.097783)
			(xy 91.229474 -259.124432) (xy 91.17986 -259.143904) (xy 91.127898 -259.155764) (xy 91.074748 -259.159748)
			(xy 91.021598 -259.155764) (xy 90.969636 -259.143904) (xy 90.920022 -259.124432) (xy 90.873864 -259.097783)
			(xy 90.832193 -259.064552) (xy 90.795941 -259.025481) (xy 90.765917 -258.981444) (xy 90.742791 -258.933423)
			(xy 90.727081 -258.882493) (xy 90.719138 -258.829789) (xy 90.490304 -258.829789) (xy 90.482361 -258.882493)
			(xy 90.466651 -258.933423) (xy 90.443525 -258.981444) (xy 90.413501 -259.025481) (xy 90.377249 -259.064552)
			(xy 90.335578 -259.097783) (xy 90.28942 -259.124432) (xy 90.239806 -259.143904) (xy 90.187844 -259.155764)
			(xy 90.134694 -259.159748) (xy 90.081544 -259.155764) (xy 90.029582 -259.143904) (xy 89.979968 -259.124432)
			(xy 89.93381 -259.097783) (xy 89.892139 -259.064552) (xy 89.855887 -259.025481) (xy 89.825863 -258.981444)
			(xy 89.802737 -258.933423) (xy 89.787027 -258.882493) (xy 89.779084 -258.829789) (xy 89.550504 -258.829789)
			(xy 89.542561 -258.882493) (xy 89.526851 -258.933423) (xy 89.503725 -258.981444) (xy 89.473701 -259.025481)
			(xy 89.437449 -259.064552) (xy 89.395778 -259.097783) (xy 89.34962 -259.124432) (xy 89.300006 -259.143904)
			(xy 89.248044 -259.155764) (xy 89.194894 -259.159748) (xy 89.141744 -259.155764) (xy 89.089782 -259.143904)
			(xy 89.040168 -259.124432) (xy 88.99401 -259.097783) (xy 88.952339 -259.064552) (xy 88.916087 -259.025481)
			(xy 88.886063 -258.981444) (xy 88.862937 -258.933423) (xy 88.847227 -258.882493) (xy 88.839284 -258.829789)
			(xy 88.688418 -258.829789) (xy 88.688418 -259.210302) (xy 88.688862 -259.220095) (xy 88.696192 -259.238258)
			(xy 88.709786 -259.252358) (xy 88.727668 -259.260347) (xy 88.73744 -259.261102) (xy 88.764768 -259.262558)
			(xy 88.818523 -259.272814) (xy 88.870077 -259.291173) (xy 88.918215 -259.317202) (xy 88.961804 -259.35029)
			(xy 88.999819 -259.389656) (xy 89.031363 -259.434374) (xy 89.055695 -259.483392) (xy 89.072242 -259.535555)
			(xy 89.080615 -259.589636) (xy 89.080615 -259.643605) (xy 89.309184 -259.643605) (xy 89.309184 -259.590307)
			(xy 89.317127 -259.537603) (xy 89.332837 -259.486673) (xy 89.355963 -259.438652) (xy 89.385987 -259.394615)
			(xy 89.422239 -259.355544) (xy 89.46391 -259.322313) (xy 89.510068 -259.295664) (xy 89.559682 -259.276192)
			(xy 89.611644 -259.264332) (xy 89.664794 -259.260349) (xy 89.717944 -259.264332) (xy 89.769906 -259.276192)
			(xy 89.81952 -259.295664) (xy 89.865678 -259.322313) (xy 89.907349 -259.355544) (xy 89.943601 -259.394615)
			(xy 89.973625 -259.438652) (xy 89.996751 -259.486673) (xy 90.012461 -259.537603) (xy 90.020404 -259.590307)
			(xy 90.020902 -259.616956) (xy 90.020404 -259.643605) (xy 90.248984 -259.643605) (xy 90.248984 -259.590307)
			(xy 90.256927 -259.537603) (xy 90.272637 -259.486673) (xy 90.295763 -259.438652) (xy 90.325787 -259.394615)
			(xy 90.362039 -259.355544) (xy 90.40371 -259.322313) (xy 90.449868 -259.295664) (xy 90.499482 -259.276192)
			(xy 90.551444 -259.264332) (xy 90.604594 -259.260349) (xy 90.657744 -259.264332) (xy 90.709706 -259.276192)
			(xy 90.75932 -259.295664) (xy 90.805478 -259.322313) (xy 90.847149 -259.355544) (xy 90.883401 -259.394615)
			(xy 90.913425 -259.438652) (xy 90.936551 -259.486673) (xy 90.952261 -259.537603) (xy 90.960204 -259.590307)
			(xy 90.960702 -259.616956) (xy 90.960204 -259.643605) (xy 91.189038 -259.643605) (xy 91.189038 -259.590307)
			(xy 91.196981 -259.537603) (xy 91.212691 -259.486673) (xy 91.235817 -259.438652) (xy 91.265841 -259.394615)
			(xy 91.302093 -259.355544) (xy 91.343764 -259.322313) (xy 91.389922 -259.295664) (xy 91.439536 -259.276192)
			(xy 91.491498 -259.264332) (xy 91.544648 -259.260349) (xy 91.597798 -259.264332) (xy 91.64976 -259.276192)
			(xy 91.699374 -259.295664) (xy 91.745532 -259.322313) (xy 91.787203 -259.355544) (xy 91.823455 -259.394615)
			(xy 91.853479 -259.438652) (xy 91.876605 -259.486673) (xy 91.892315 -259.537603) (xy 91.900258 -259.590307)
			(xy 91.900756 -259.616956) (xy 91.900258 -259.643605) (xy 92.128584 -259.643605) (xy 92.128584 -259.590307)
			(xy 92.136527 -259.537603) (xy 92.152237 -259.486673) (xy 92.175363 -259.438652) (xy 92.205387 -259.394615)
			(xy 92.241639 -259.355544) (xy 92.28331 -259.322313) (xy 92.329468 -259.295664) (xy 92.379082 -259.276192)
			(xy 92.431044 -259.264332) (xy 92.484194 -259.260349) (xy 92.537344 -259.264332) (xy 92.589306 -259.276192)
			(xy 92.63892 -259.295664) (xy 92.685078 -259.322313) (xy 92.726749 -259.355544) (xy 92.763001 -259.394615)
			(xy 92.793025 -259.438652) (xy 92.816151 -259.486673) (xy 92.831861 -259.537603) (xy 92.839804 -259.590307)
			(xy 92.840302 -259.616956) (xy 92.839804 -259.643605) (xy 93.068384 -259.643605) (xy 93.068384 -259.590307)
			(xy 93.076327 -259.537603) (xy 93.092037 -259.486673) (xy 93.115163 -259.438652) (xy 93.145187 -259.394615)
			(xy 93.181439 -259.355544) (xy 93.22311 -259.322313) (xy 93.269268 -259.295664) (xy 93.318882 -259.276192)
			(xy 93.370844 -259.264332) (xy 93.423994 -259.260349) (xy 93.477144 -259.264332) (xy 93.529106 -259.276192)
			(xy 93.57872 -259.295664) (xy 93.624878 -259.322313) (xy 93.666549 -259.355544) (xy 93.702801 -259.394615)
			(xy 93.732825 -259.438652) (xy 93.755951 -259.486673) (xy 93.771661 -259.537603) (xy 93.779604 -259.590307)
			(xy 93.780102 -259.616956) (xy 93.779604 -259.643605) (xy 94.008184 -259.643605) (xy 94.008184 -259.590307)
			(xy 94.016127 -259.537603) (xy 94.031837 -259.486673) (xy 94.054963 -259.438652) (xy 94.084987 -259.394615)
			(xy 94.121239 -259.355544) (xy 94.16291 -259.322313) (xy 94.209068 -259.295664) (xy 94.258682 -259.276192)
			(xy 94.310644 -259.264332) (xy 94.363794 -259.260349) (xy 94.416944 -259.264332) (xy 94.468906 -259.276192)
			(xy 94.51852 -259.295664) (xy 94.564678 -259.322313) (xy 94.606349 -259.355544) (xy 94.642601 -259.394615)
			(xy 94.672625 -259.438652) (xy 94.695751 -259.486673) (xy 94.711461 -259.537603) (xy 94.719404 -259.590307)
			(xy 94.719902 -259.616956) (xy 94.719404 -259.643605) (xy 94.947984 -259.643605) (xy 94.947984 -259.590307)
			(xy 94.955927 -259.537603) (xy 94.971637 -259.486673) (xy 94.994763 -259.438652) (xy 95.024787 -259.394615)
			(xy 95.061039 -259.355544) (xy 95.10271 -259.322313) (xy 95.148868 -259.295664) (xy 95.198482 -259.276192)
			(xy 95.250444 -259.264332) (xy 95.303594 -259.260349) (xy 95.356744 -259.264332) (xy 95.408706 -259.276192)
			(xy 95.45832 -259.295664) (xy 95.504478 -259.322313) (xy 95.546149 -259.355544) (xy 95.582401 -259.394615)
			(xy 95.612425 -259.438652) (xy 95.635551 -259.486673) (xy 95.651261 -259.537603) (xy 95.659204 -259.590307)
			(xy 95.659702 -259.616956) (xy 95.659204 -259.643605) (xy 95.887784 -259.643605) (xy 95.887784 -259.590307)
			(xy 95.895727 -259.537603) (xy 95.911437 -259.486673) (xy 95.934563 -259.438652) (xy 95.964587 -259.394615)
			(xy 96.000839 -259.355544) (xy 96.04251 -259.322313) (xy 96.088668 -259.295664) (xy 96.138282 -259.276192)
			(xy 96.190244 -259.264332) (xy 96.243394 -259.260349) (xy 96.296544 -259.264332) (xy 96.348506 -259.276192)
			(xy 96.39812 -259.295664) (xy 96.444278 -259.322313) (xy 96.485949 -259.355544) (xy 96.522201 -259.394615)
			(xy 96.552225 -259.438652) (xy 96.575351 -259.486673) (xy 96.591061 -259.537603) (xy 96.599004 -259.590307)
			(xy 96.599502 -259.616956) (xy 96.599004 -259.643605) (xy 96.827584 -259.643605) (xy 96.827584 -259.590307)
			(xy 96.835527 -259.537603) (xy 96.851237 -259.486673) (xy 96.874363 -259.438652) (xy 96.904387 -259.394615)
			(xy 96.940639 -259.355544) (xy 96.98231 -259.322313) (xy 97.028468 -259.295664) (xy 97.078082 -259.276192)
			(xy 97.130044 -259.264332) (xy 97.183194 -259.260349) (xy 97.236344 -259.264332) (xy 97.288306 -259.276192)
			(xy 97.33792 -259.295664) (xy 97.384078 -259.322313) (xy 97.425749 -259.355544) (xy 97.462001 -259.394615)
			(xy 97.492025 -259.438652) (xy 97.515151 -259.486673) (xy 97.530861 -259.537603) (xy 97.538804 -259.590307)
			(xy 97.539302 -259.616956) (xy 97.538804 -259.643605) (xy 97.767638 -259.643605) (xy 97.767638 -259.590307)
			(xy 97.775581 -259.537603) (xy 97.791291 -259.486673) (xy 97.814417 -259.438652) (xy 97.844441 -259.394615)
			(xy 97.880693 -259.355544) (xy 97.922364 -259.322313) (xy 97.968522 -259.295664) (xy 98.018136 -259.276192)
			(xy 98.070098 -259.264332) (xy 98.123248 -259.260349) (xy 98.176398 -259.264332) (xy 98.22836 -259.276192)
			(xy 98.277974 -259.295664) (xy 98.324132 -259.322313) (xy 98.365803 -259.355544) (xy 98.402055 -259.394615)
			(xy 98.432079 -259.438652) (xy 98.455205 -259.486673) (xy 98.470915 -259.537603) (xy 98.478858 -259.590307)
			(xy 98.479356 -259.616956) (xy 98.478858 -259.643605) (xy 98.707184 -259.643605) (xy 98.707184 -259.590307)
			(xy 98.715127 -259.537603) (xy 98.730837 -259.486673) (xy 98.753963 -259.438652) (xy 98.783987 -259.394615)
			(xy 98.820239 -259.355544) (xy 98.86191 -259.322313) (xy 98.908068 -259.295664) (xy 98.957682 -259.276192)
			(xy 99.009644 -259.264332) (xy 99.062794 -259.260349) (xy 99.115944 -259.264332) (xy 99.167906 -259.276192)
			(xy 99.21752 -259.295664) (xy 99.263678 -259.322313) (xy 99.305349 -259.355544) (xy 99.341601 -259.394615)
			(xy 99.371625 -259.438652) (xy 99.394751 -259.486673) (xy 99.410461 -259.537603) (xy 99.418404 -259.590307)
			(xy 99.418902 -259.616956) (xy 99.418404 -259.643605) (xy 99.410461 -259.696309) (xy 99.394751 -259.747239)
			(xy 99.371625 -259.79526) (xy 99.341601 -259.839297) (xy 99.305349 -259.878368) (xy 99.263678 -259.911599)
			(xy 99.21752 -259.938248) (xy 99.167906 -259.95772) (xy 99.115944 -259.96958) (xy 99.062794 -259.973564)
			(xy 99.009644 -259.96958) (xy 98.957682 -259.95772) (xy 98.908068 -259.938248) (xy 98.86191 -259.911599)
			(xy 98.820239 -259.878368) (xy 98.783987 -259.839297) (xy 98.753963 -259.79526) (xy 98.730837 -259.747239)
			(xy 98.715127 -259.696309) (xy 98.707184 -259.643605) (xy 98.478858 -259.643605) (xy 98.470915 -259.696309)
			(xy 98.455205 -259.747239) (xy 98.432079 -259.79526) (xy 98.402055 -259.839297) (xy 98.365803 -259.878368)
			(xy 98.324132 -259.911599) (xy 98.277974 -259.938248) (xy 98.22836 -259.95772) (xy 98.176398 -259.96958)
			(xy 98.123248 -259.973564) (xy 98.070098 -259.96958) (xy 98.018136 -259.95772) (xy 97.968522 -259.938248)
			(xy 97.922364 -259.911599) (xy 97.880693 -259.878368) (xy 97.844441 -259.839297) (xy 97.814417 -259.79526)
			(xy 97.791291 -259.747239) (xy 97.775581 -259.696309) (xy 97.767638 -259.643605) (xy 97.538804 -259.643605)
			(xy 97.530861 -259.696309) (xy 97.515151 -259.747239) (xy 97.492025 -259.79526) (xy 97.462001 -259.839297)
			(xy 97.425749 -259.878368) (xy 97.384078 -259.911599) (xy 97.33792 -259.938248) (xy 97.288306 -259.95772)
			(xy 97.236344 -259.96958) (xy 97.183194 -259.973564) (xy 97.130044 -259.96958) (xy 97.078082 -259.95772)
			(xy 97.028468 -259.938248) (xy 96.98231 -259.911599) (xy 96.940639 -259.878368) (xy 96.904387 -259.839297)
			(xy 96.874363 -259.79526) (xy 96.851237 -259.747239) (xy 96.835527 -259.696309) (xy 96.827584 -259.643605)
			(xy 96.599004 -259.643605) (xy 96.591061 -259.696309) (xy 96.575351 -259.747239) (xy 96.552225 -259.79526)
			(xy 96.522201 -259.839297) (xy 96.485949 -259.878368) (xy 96.444278 -259.911599) (xy 96.39812 -259.938248)
			(xy 96.348506 -259.95772) (xy 96.296544 -259.96958) (xy 96.243394 -259.973564) (xy 96.190244 -259.96958)
			(xy 96.138282 -259.95772) (xy 96.088668 -259.938248) (xy 96.04251 -259.911599) (xy 96.000839 -259.878368)
			(xy 95.964587 -259.839297) (xy 95.934563 -259.79526) (xy 95.911437 -259.747239) (xy 95.895727 -259.696309)
			(xy 95.887784 -259.643605) (xy 95.659204 -259.643605) (xy 95.651261 -259.696309) (xy 95.635551 -259.747239)
			(xy 95.612425 -259.79526) (xy 95.582401 -259.839297) (xy 95.546149 -259.878368) (xy 95.504478 -259.911599)
			(xy 95.45832 -259.938248) (xy 95.408706 -259.95772) (xy 95.356744 -259.96958) (xy 95.303594 -259.973564)
			(xy 95.250444 -259.96958) (xy 95.198482 -259.95772) (xy 95.148868 -259.938248) (xy 95.10271 -259.911599)
			(xy 95.061039 -259.878368) (xy 95.024787 -259.839297) (xy 94.994763 -259.79526) (xy 94.971637 -259.747239)
			(xy 94.955927 -259.696309) (xy 94.947984 -259.643605) (xy 94.719404 -259.643605) (xy 94.711461 -259.696309)
			(xy 94.695751 -259.747239) (xy 94.672625 -259.79526) (xy 94.642601 -259.839297) (xy 94.606349 -259.878368)
			(xy 94.564678 -259.911599) (xy 94.51852 -259.938248) (xy 94.468906 -259.95772) (xy 94.416944 -259.96958)
			(xy 94.363794 -259.973564) (xy 94.310644 -259.96958) (xy 94.258682 -259.95772) (xy 94.209068 -259.938248)
			(xy 94.16291 -259.911599) (xy 94.121239 -259.878368) (xy 94.084987 -259.839297) (xy 94.054963 -259.79526)
			(xy 94.031837 -259.747239) (xy 94.016127 -259.696309) (xy 94.008184 -259.643605) (xy 93.779604 -259.643605)
			(xy 93.771661 -259.696309) (xy 93.755951 -259.747239) (xy 93.732825 -259.79526) (xy 93.702801 -259.839297)
			(xy 93.666549 -259.878368) (xy 93.624878 -259.911599) (xy 93.57872 -259.938248) (xy 93.529106 -259.95772)
			(xy 93.477144 -259.96958) (xy 93.423994 -259.973564) (xy 93.370844 -259.96958) (xy 93.318882 -259.95772)
			(xy 93.269268 -259.938248) (xy 93.22311 -259.911599) (xy 93.181439 -259.878368) (xy 93.145187 -259.839297)
			(xy 93.115163 -259.79526) (xy 93.092037 -259.747239) (xy 93.076327 -259.696309) (xy 93.068384 -259.643605)
			(xy 92.839804 -259.643605) (xy 92.831861 -259.696309) (xy 92.816151 -259.747239) (xy 92.793025 -259.79526)
			(xy 92.763001 -259.839297) (xy 92.726749 -259.878368) (xy 92.685078 -259.911599) (xy 92.63892 -259.938248)
			(xy 92.589306 -259.95772) (xy 92.537344 -259.96958) (xy 92.484194 -259.973564) (xy 92.431044 -259.96958)
			(xy 92.379082 -259.95772) (xy 92.329468 -259.938248) (xy 92.28331 -259.911599) (xy 92.241639 -259.878368)
			(xy 92.205387 -259.839297) (xy 92.175363 -259.79526) (xy 92.152237 -259.747239) (xy 92.136527 -259.696309)
			(xy 92.128584 -259.643605) (xy 91.900258 -259.643605) (xy 91.892315 -259.696309) (xy 91.876605 -259.747239)
			(xy 91.853479 -259.79526) (xy 91.823455 -259.839297) (xy 91.787203 -259.878368) (xy 91.745532 -259.911599)
			(xy 91.699374 -259.938248) (xy 91.64976 -259.95772) (xy 91.597798 -259.96958) (xy 91.544648 -259.973564)
			(xy 91.491498 -259.96958) (xy 91.439536 -259.95772) (xy 91.389922 -259.938248) (xy 91.343764 -259.911599)
			(xy 91.302093 -259.878368) (xy 91.265841 -259.839297) (xy 91.235817 -259.79526) (xy 91.212691 -259.747239)
			(xy 91.196981 -259.696309) (xy 91.189038 -259.643605) (xy 90.960204 -259.643605) (xy 90.952261 -259.696309)
			(xy 90.936551 -259.747239) (xy 90.913425 -259.79526) (xy 90.883401 -259.839297) (xy 90.847149 -259.878368)
			(xy 90.805478 -259.911599) (xy 90.75932 -259.938248) (xy 90.709706 -259.95772) (xy 90.657744 -259.96958)
			(xy 90.604594 -259.973564) (xy 90.551444 -259.96958) (xy 90.499482 -259.95772) (xy 90.449868 -259.938248)
			(xy 90.40371 -259.911599) (xy 90.362039 -259.878368) (xy 90.325787 -259.839297) (xy 90.295763 -259.79526)
			(xy 90.272637 -259.747239) (xy 90.256927 -259.696309) (xy 90.248984 -259.643605) (xy 90.020404 -259.643605)
			(xy 90.012461 -259.696309) (xy 89.996751 -259.747239) (xy 89.973625 -259.79526) (xy 89.943601 -259.839297)
			(xy 89.907349 -259.878368) (xy 89.865678 -259.911599) (xy 89.81952 -259.938248) (xy 89.769906 -259.95772)
			(xy 89.717944 -259.96958) (xy 89.664794 -259.973564) (xy 89.611644 -259.96958) (xy 89.559682 -259.95772)
			(xy 89.510068 -259.938248) (xy 89.46391 -259.911599) (xy 89.422239 -259.878368) (xy 89.385987 -259.839297)
			(xy 89.355963 -259.79526) (xy 89.332837 -259.747239) (xy 89.317127 -259.696309) (xy 89.309184 -259.643605)
			(xy 89.080615 -259.643605) (xy 89.080615 -259.644361) (xy 89.072243 -259.698442) (xy 89.055697 -259.750605)
			(xy 89.031365 -259.799623) (xy 88.999821 -259.844342) (xy 88.961806 -259.883708) (xy 88.918217 -259.916796)
			(xy 88.87008 -259.942826) (xy 88.818526 -259.961185) (xy 88.764771 -259.971441) (xy 88.73744 -259.97281)
			(xy 88.727666 -259.973594) (xy 88.709769 -259.98156) (xy 88.69616 -259.995651) (xy 88.688823 -260.013815)
			(xy 88.688418 -260.02361) (xy 88.688418 -260.457421) (xy 88.839538 -260.457421) (xy 88.839538 -260.404123)
			(xy 88.847481 -260.351419) (xy 88.863191 -260.300489) (xy 88.886317 -260.252468) (xy 88.916341 -260.208431)
			(xy 88.952593 -260.16936) (xy 88.994264 -260.136129) (xy 89.040422 -260.10948) (xy 89.090036 -260.090008)
			(xy 89.141998 -260.078148) (xy 89.195148 -260.074165) (xy 89.248298 -260.078148) (xy 89.30026 -260.090008)
			(xy 89.349874 -260.10948) (xy 89.396032 -260.136129) (xy 89.437703 -260.16936) (xy 89.473955 -260.208431)
			(xy 89.503979 -260.252468) (xy 89.527105 -260.300489) (xy 89.542815 -260.351419) (xy 89.550758 -260.404123)
			(xy 89.551256 -260.430772) (xy 89.550758 -260.457421) (xy 89.779338 -260.457421) (xy 89.779338 -260.404123)
			(xy 89.787281 -260.351419) (xy 89.802991 -260.300489) (xy 89.826117 -260.252468) (xy 89.856141 -260.208431)
			(xy 89.892393 -260.16936) (xy 89.934064 -260.136129) (xy 89.980222 -260.10948) (xy 90.029836 -260.090008)
			(xy 90.081798 -260.078148) (xy 90.134948 -260.074165) (xy 90.188098 -260.078148) (xy 90.24006 -260.090008)
			(xy 90.289674 -260.10948) (xy 90.335832 -260.136129) (xy 90.377503 -260.16936) (xy 90.413755 -260.208431)
			(xy 90.443779 -260.252468) (xy 90.466905 -260.300489) (xy 90.482615 -260.351419) (xy 90.490558 -260.404123)
			(xy 90.491056 -260.430772) (xy 90.490558 -260.457421) (xy 90.719138 -260.457421) (xy 90.719138 -260.404123)
			(xy 90.727081 -260.351419) (xy 90.742791 -260.300489) (xy 90.765917 -260.252468) (xy 90.795941 -260.208431)
			(xy 90.832193 -260.16936) (xy 90.873864 -260.136129) (xy 90.920022 -260.10948) (xy 90.969636 -260.090008)
			(xy 91.021598 -260.078148) (xy 91.074748 -260.074165) (xy 91.127898 -260.078148) (xy 91.17986 -260.090008)
			(xy 91.229474 -260.10948) (xy 91.275632 -260.136129) (xy 91.317303 -260.16936) (xy 91.353555 -260.208431)
			(xy 91.383579 -260.252468) (xy 91.406705 -260.300489) (xy 91.422415 -260.351419) (xy 91.430358 -260.404123)
			(xy 91.430856 -260.430772) (xy 91.430358 -260.457421) (xy 91.658684 -260.457421) (xy 91.658684 -260.404123)
			(xy 91.666627 -260.351419) (xy 91.682337 -260.300489) (xy 91.705463 -260.252468) (xy 91.735487 -260.208431)
			(xy 91.771739 -260.16936) (xy 91.81341 -260.136129) (xy 91.859568 -260.10948) (xy 91.909182 -260.090008)
			(xy 91.961144 -260.078148) (xy 92.014294 -260.074165) (xy 92.067444 -260.078148) (xy 92.119406 -260.090008)
			(xy 92.16902 -260.10948) (xy 92.215178 -260.136129) (xy 92.256849 -260.16936) (xy 92.293101 -260.208431)
			(xy 92.323125 -260.252468) (xy 92.346251 -260.300489) (xy 92.361961 -260.351419) (xy 92.369904 -260.404123)
			(xy 92.370402 -260.430772) (xy 92.369904 -260.457421) (xy 92.598738 -260.457421) (xy 92.598738 -260.404123)
			(xy 92.606681 -260.351419) (xy 92.622391 -260.300489) (xy 92.645517 -260.252468) (xy 92.675541 -260.208431)
			(xy 92.711793 -260.16936) (xy 92.753464 -260.136129) (xy 92.799622 -260.10948) (xy 92.849236 -260.090008)
			(xy 92.901198 -260.078148) (xy 92.954348 -260.074165) (xy 93.007498 -260.078148) (xy 93.05946 -260.090008)
			(xy 93.109074 -260.10948) (xy 93.155232 -260.136129) (xy 93.196903 -260.16936) (xy 93.233155 -260.208431)
			(xy 93.263179 -260.252468) (xy 93.286305 -260.300489) (xy 93.302015 -260.351419) (xy 93.309958 -260.404123)
			(xy 93.310456 -260.430772) (xy 93.309958 -260.457421) (xy 93.538538 -260.457421) (xy 93.538538 -260.404123)
			(xy 93.546481 -260.351419) (xy 93.562191 -260.300489) (xy 93.585317 -260.252468) (xy 93.615341 -260.208431)
			(xy 93.651593 -260.16936) (xy 93.693264 -260.136129) (xy 93.739422 -260.10948) (xy 93.789036 -260.090008)
			(xy 93.840998 -260.078148) (xy 93.894148 -260.074165) (xy 93.947298 -260.078148) (xy 93.99926 -260.090008)
			(xy 94.048874 -260.10948) (xy 94.095032 -260.136129) (xy 94.136703 -260.16936) (xy 94.172955 -260.208431)
			(xy 94.202979 -260.252468) (xy 94.226105 -260.300489) (xy 94.241815 -260.351419) (xy 94.249758 -260.404123)
			(xy 94.250256 -260.430772) (xy 94.249758 -260.457421) (xy 94.47783 -260.457421) (xy 94.47783 -260.404123)
			(xy 94.485773 -260.351419) (xy 94.501483 -260.300489) (xy 94.524609 -260.252468) (xy 94.554633 -260.208431)
			(xy 94.590885 -260.16936) (xy 94.632556 -260.136129) (xy 94.678714 -260.10948) (xy 94.728328 -260.090008)
			(xy 94.78029 -260.078148) (xy 94.83344 -260.074165) (xy 94.88659 -260.078148) (xy 94.938552 -260.090008)
			(xy 94.988166 -260.10948) (xy 95.034324 -260.136129) (xy 95.075995 -260.16936) (xy 95.112247 -260.208431)
			(xy 95.142271 -260.252468) (xy 95.165397 -260.300489) (xy 95.181107 -260.351419) (xy 95.18905 -260.404123)
			(xy 95.189548 -260.430772) (xy 95.18905 -260.457421) (xy 95.418138 -260.457421) (xy 95.418138 -260.404123)
			(xy 95.426081 -260.351419) (xy 95.441791 -260.300489) (xy 95.464917 -260.252468) (xy 95.494941 -260.208431)
			(xy 95.531193 -260.16936) (xy 95.572864 -260.136129) (xy 95.619022 -260.10948) (xy 95.668636 -260.090008)
			(xy 95.720598 -260.078148) (xy 95.773748 -260.074165) (xy 95.826898 -260.078148) (xy 95.87886 -260.090008)
			(xy 95.928474 -260.10948) (xy 95.974632 -260.136129) (xy 96.016303 -260.16936) (xy 96.052555 -260.208431)
			(xy 96.082579 -260.252468) (xy 96.105705 -260.300489) (xy 96.121415 -260.351419) (xy 96.129358 -260.404123)
			(xy 96.129856 -260.430772) (xy 96.129358 -260.457421) (xy 96.35743 -260.457421) (xy 96.35743 -260.404123)
			(xy 96.365373 -260.351419) (xy 96.381083 -260.300489) (xy 96.404209 -260.252468) (xy 96.434233 -260.208431)
			(xy 96.470485 -260.16936) (xy 96.512156 -260.136129) (xy 96.558314 -260.10948) (xy 96.607928 -260.090008)
			(xy 96.65989 -260.078148) (xy 96.71304 -260.074165) (xy 96.76619 -260.078148) (xy 96.818152 -260.090008)
			(xy 96.867766 -260.10948) (xy 96.913924 -260.136129) (xy 96.955595 -260.16936) (xy 96.991847 -260.208431)
			(xy 97.021871 -260.252468) (xy 97.044997 -260.300489) (xy 97.060707 -260.351419) (xy 97.06865 -260.404123)
			(xy 97.069148 -260.430772) (xy 97.06865 -260.457421) (xy 97.297738 -260.457421) (xy 97.297738 -260.404123)
			(xy 97.305681 -260.351419) (xy 97.321391 -260.300489) (xy 97.344517 -260.252468) (xy 97.374541 -260.208431)
			(xy 97.410793 -260.16936) (xy 97.452464 -260.136129) (xy 97.498622 -260.10948) (xy 97.548236 -260.090008)
			(xy 97.600198 -260.078148) (xy 97.653348 -260.074165) (xy 97.706498 -260.078148) (xy 97.75846 -260.090008)
			(xy 97.808074 -260.10948) (xy 97.854232 -260.136129) (xy 97.895903 -260.16936) (xy 97.932155 -260.208431)
			(xy 97.962179 -260.252468) (xy 97.985305 -260.300489) (xy 98.001015 -260.351419) (xy 98.008958 -260.404123)
			(xy 98.009456 -260.430772) (xy 98.008958 -260.457421) (xy 98.237284 -260.457421) (xy 98.237284 -260.404123)
			(xy 98.245227 -260.351419) (xy 98.260937 -260.300489) (xy 98.284063 -260.252468) (xy 98.314087 -260.208431)
			(xy 98.350339 -260.16936) (xy 98.39201 -260.136129) (xy 98.438168 -260.10948) (xy 98.487782 -260.090008)
			(xy 98.539744 -260.078148) (xy 98.592894 -260.074165) (xy 98.646044 -260.078148) (xy 98.698006 -260.090008)
			(xy 98.74762 -260.10948) (xy 98.793778 -260.136129) (xy 98.835449 -260.16936) (xy 98.871701 -260.208431)
			(xy 98.901725 -260.252468) (xy 98.924851 -260.300489) (xy 98.940561 -260.351419) (xy 98.948504 -260.404123)
			(xy 98.949002 -260.430772) (xy 98.948504 -260.457421) (xy 98.940561 -260.510125) (xy 98.924851 -260.561055)
			(xy 98.901725 -260.609076) (xy 98.871701 -260.653113) (xy 98.835449 -260.692184) (xy 98.793778 -260.725415)
			(xy 98.74762 -260.752064) (xy 98.698006 -260.771536) (xy 98.646044 -260.783396) (xy 98.592894 -260.78738)
			(xy 98.539744 -260.783396) (xy 98.487782 -260.771536) (xy 98.438168 -260.752064) (xy 98.39201 -260.725415)
			(xy 98.350339 -260.692184) (xy 98.314087 -260.653113) (xy 98.284063 -260.609076) (xy 98.260937 -260.561055)
			(xy 98.245227 -260.510125) (xy 98.237284 -260.457421) (xy 98.008958 -260.457421) (xy 98.001015 -260.510125)
			(xy 97.985305 -260.561055) (xy 97.962179 -260.609076) (xy 97.932155 -260.653113) (xy 97.895903 -260.692184)
			(xy 97.854232 -260.725415) (xy 97.808074 -260.752064) (xy 97.75846 -260.771536) (xy 97.706498 -260.783396)
			(xy 97.653348 -260.78738) (xy 97.600198 -260.783396) (xy 97.548236 -260.771536) (xy 97.498622 -260.752064)
			(xy 97.452464 -260.725415) (xy 97.410793 -260.692184) (xy 97.374541 -260.653113) (xy 97.344517 -260.609076)
			(xy 97.321391 -260.561055) (xy 97.305681 -260.510125) (xy 97.297738 -260.457421) (xy 97.06865 -260.457421)
			(xy 97.060707 -260.510125) (xy 97.044997 -260.561055) (xy 97.021871 -260.609076) (xy 96.991847 -260.653113)
			(xy 96.955595 -260.692184) (xy 96.913924 -260.725415) (xy 96.867766 -260.752064) (xy 96.818152 -260.771536)
			(xy 96.76619 -260.783396) (xy 96.71304 -260.78738) (xy 96.65989 -260.783396) (xy 96.607928 -260.771536)
			(xy 96.558314 -260.752064) (xy 96.512156 -260.725415) (xy 96.470485 -260.692184) (xy 96.434233 -260.653113)
			(xy 96.404209 -260.609076) (xy 96.381083 -260.561055) (xy 96.365373 -260.510125) (xy 96.35743 -260.457421)
			(xy 96.129358 -260.457421) (xy 96.121415 -260.510125) (xy 96.105705 -260.561055) (xy 96.082579 -260.609076)
			(xy 96.052555 -260.653113) (xy 96.016303 -260.692184) (xy 95.974632 -260.725415) (xy 95.928474 -260.752064)
			(xy 95.87886 -260.771536) (xy 95.826898 -260.783396) (xy 95.773748 -260.78738) (xy 95.720598 -260.783396)
			(xy 95.668636 -260.771536) (xy 95.619022 -260.752064) (xy 95.572864 -260.725415) (xy 95.531193 -260.692184)
			(xy 95.494941 -260.653113) (xy 95.464917 -260.609076) (xy 95.441791 -260.561055) (xy 95.426081 -260.510125)
			(xy 95.418138 -260.457421) (xy 95.18905 -260.457421) (xy 95.181107 -260.510125) (xy 95.165397 -260.561055)
			(xy 95.142271 -260.609076) (xy 95.112247 -260.653113) (xy 95.075995 -260.692184) (xy 95.034324 -260.725415)
			(xy 94.988166 -260.752064) (xy 94.938552 -260.771536) (xy 94.88659 -260.783396) (xy 94.83344 -260.78738)
			(xy 94.78029 -260.783396) (xy 94.728328 -260.771536) (xy 94.678714 -260.752064) (xy 94.632556 -260.725415)
			(xy 94.590885 -260.692184) (xy 94.554633 -260.653113) (xy 94.524609 -260.609076) (xy 94.501483 -260.561055)
			(xy 94.485773 -260.510125) (xy 94.47783 -260.457421) (xy 94.249758 -260.457421) (xy 94.241815 -260.510125)
			(xy 94.226105 -260.561055) (xy 94.202979 -260.609076) (xy 94.172955 -260.653113) (xy 94.136703 -260.692184)
			(xy 94.095032 -260.725415) (xy 94.048874 -260.752064) (xy 93.99926 -260.771536) (xy 93.947298 -260.783396)
			(xy 93.894148 -260.78738) (xy 93.840998 -260.783396) (xy 93.789036 -260.771536) (xy 93.739422 -260.752064)
			(xy 93.693264 -260.725415) (xy 93.651593 -260.692184) (xy 93.615341 -260.653113) (xy 93.585317 -260.609076)
			(xy 93.562191 -260.561055) (xy 93.546481 -260.510125) (xy 93.538538 -260.457421) (xy 93.309958 -260.457421)
			(xy 93.302015 -260.510125) (xy 93.286305 -260.561055) (xy 93.263179 -260.609076) (xy 93.233155 -260.653113)
			(xy 93.196903 -260.692184) (xy 93.155232 -260.725415) (xy 93.109074 -260.752064) (xy 93.05946 -260.771536)
			(xy 93.007498 -260.783396) (xy 92.954348 -260.78738) (xy 92.901198 -260.783396) (xy 92.849236 -260.771536)
			(xy 92.799622 -260.752064) (xy 92.753464 -260.725415) (xy 92.711793 -260.692184) (xy 92.675541 -260.653113)
			(xy 92.645517 -260.609076) (xy 92.622391 -260.561055) (xy 92.606681 -260.510125) (xy 92.598738 -260.457421)
			(xy 92.369904 -260.457421) (xy 92.361961 -260.510125) (xy 92.346251 -260.561055) (xy 92.323125 -260.609076)
			(xy 92.293101 -260.653113) (xy 92.256849 -260.692184) (xy 92.215178 -260.725415) (xy 92.16902 -260.752064)
			(xy 92.119406 -260.771536) (xy 92.067444 -260.783396) (xy 92.014294 -260.78738) (xy 91.961144 -260.783396)
			(xy 91.909182 -260.771536) (xy 91.859568 -260.752064) (xy 91.81341 -260.725415) (xy 91.771739 -260.692184)
			(xy 91.735487 -260.653113) (xy 91.705463 -260.609076) (xy 91.682337 -260.561055) (xy 91.666627 -260.510125)
			(xy 91.658684 -260.457421) (xy 91.430358 -260.457421) (xy 91.422415 -260.510125) (xy 91.406705 -260.561055)
			(xy 91.383579 -260.609076) (xy 91.353555 -260.653113) (xy 91.317303 -260.692184) (xy 91.275632 -260.725415)
			(xy 91.229474 -260.752064) (xy 91.17986 -260.771536) (xy 91.127898 -260.783396) (xy 91.074748 -260.78738)
			(xy 91.021598 -260.783396) (xy 90.969636 -260.771536) (xy 90.920022 -260.752064) (xy 90.873864 -260.725415)
			(xy 90.832193 -260.692184) (xy 90.795941 -260.653113) (xy 90.765917 -260.609076) (xy 90.742791 -260.561055)
			(xy 90.727081 -260.510125) (xy 90.719138 -260.457421) (xy 90.490558 -260.457421) (xy 90.482615 -260.510125)
			(xy 90.466905 -260.561055) (xy 90.443779 -260.609076) (xy 90.413755 -260.653113) (xy 90.377503 -260.692184)
			(xy 90.335832 -260.725415) (xy 90.289674 -260.752064) (xy 90.24006 -260.771536) (xy 90.188098 -260.783396)
			(xy 90.134948 -260.78738) (xy 90.081798 -260.783396) (xy 90.029836 -260.771536) (xy 89.980222 -260.752064)
			(xy 89.934064 -260.725415) (xy 89.892393 -260.692184) (xy 89.856141 -260.653113) (xy 89.826117 -260.609076)
			(xy 89.802991 -260.561055) (xy 89.787281 -260.510125) (xy 89.779338 -260.457421) (xy 89.550758 -260.457421)
			(xy 89.542815 -260.510125) (xy 89.527105 -260.561055) (xy 89.503979 -260.609076) (xy 89.473955 -260.653113)
			(xy 89.437703 -260.692184) (xy 89.396032 -260.725415) (xy 89.349874 -260.752064) (xy 89.30026 -260.771536)
			(xy 89.248298 -260.783396) (xy 89.195148 -260.78738) (xy 89.141998 -260.783396) (xy 89.090036 -260.771536)
			(xy 89.040422 -260.752064) (xy 88.994264 -260.725415) (xy 88.952593 -260.692184) (xy 88.916341 -260.653113)
			(xy 88.886317 -260.609076) (xy 88.863191 -260.561055) (xy 88.847481 -260.510125) (xy 88.839538 -260.457421)
			(xy 88.688418 -260.457421) (xy 88.688418 -260.838188) (xy 88.688859 -260.847983) (xy 88.696187 -260.86615)
			(xy 88.709781 -260.880254) (xy 88.727666 -260.888246) (xy 88.73744 -260.888988) (xy 88.764762 -260.890444)
			(xy 88.818504 -260.900698) (xy 88.870045 -260.919053) (xy 88.918171 -260.945076) (xy 88.961749 -260.978156)
			(xy 88.999754 -261.017513) (xy 89.031291 -261.062221) (xy 89.055617 -261.111227) (xy 89.072159 -261.163378)
			(xy 89.080529 -261.217446) (xy 89.080529 -261.271491) (xy 89.309184 -261.271491) (xy 89.309184 -261.218193)
			(xy 89.317127 -261.165489) (xy 89.332837 -261.114559) (xy 89.355963 -261.066538) (xy 89.385987 -261.022501)
			(xy 89.422239 -260.98343) (xy 89.46391 -260.950199) (xy 89.510068 -260.92355) (xy 89.559682 -260.904078)
			(xy 89.611644 -260.892218) (xy 89.664794 -260.888235) (xy 89.717944 -260.892218) (xy 89.769906 -260.904078)
			(xy 89.81952 -260.92355) (xy 89.865678 -260.950199) (xy 89.907349 -260.98343) (xy 89.943601 -261.022501)
			(xy 89.973625 -261.066538) (xy 89.996751 -261.114559) (xy 90.012461 -261.165489) (xy 90.020404 -261.218193)
			(xy 90.020902 -261.244842) (xy 90.020404 -261.271491) (xy 90.248984 -261.271491) (xy 90.248984 -261.218193)
			(xy 90.256927 -261.165489) (xy 90.272637 -261.114559) (xy 90.295763 -261.066538) (xy 90.325787 -261.022501)
			(xy 90.362039 -260.98343) (xy 90.40371 -260.950199) (xy 90.449868 -260.92355) (xy 90.499482 -260.904078)
			(xy 90.551444 -260.892218) (xy 90.604594 -260.888235) (xy 90.657744 -260.892218) (xy 90.709706 -260.904078)
			(xy 90.75932 -260.92355) (xy 90.805478 -260.950199) (xy 90.847149 -260.98343) (xy 90.883401 -261.022501)
			(xy 90.913425 -261.066538) (xy 90.936551 -261.114559) (xy 90.952261 -261.165489) (xy 90.960204 -261.218193)
			(xy 90.960702 -261.244842) (xy 90.960204 -261.271491) (xy 91.188784 -261.271491) (xy 91.188784 -261.218193)
			(xy 91.196727 -261.165489) (xy 91.212437 -261.114559) (xy 91.235563 -261.066538) (xy 91.265587 -261.022501)
			(xy 91.301839 -260.98343) (xy 91.34351 -260.950199) (xy 91.389668 -260.92355) (xy 91.439282 -260.904078)
			(xy 91.491244 -260.892218) (xy 91.544394 -260.888235) (xy 91.597544 -260.892218) (xy 91.649506 -260.904078)
			(xy 91.69912 -260.92355) (xy 91.745278 -260.950199) (xy 91.786949 -260.98343) (xy 91.823201 -261.022501)
			(xy 91.853225 -261.066538) (xy 91.876351 -261.114559) (xy 91.892061 -261.165489) (xy 91.900004 -261.218193)
			(xy 91.900502 -261.244842) (xy 91.900004 -261.271491) (xy 92.128584 -261.271491) (xy 92.128584 -261.218193)
			(xy 92.136527 -261.165489) (xy 92.152237 -261.114559) (xy 92.175363 -261.066538) (xy 92.205387 -261.022501)
			(xy 92.241639 -260.98343) (xy 92.28331 -260.950199) (xy 92.329468 -260.92355) (xy 92.379082 -260.904078)
			(xy 92.431044 -260.892218) (xy 92.484194 -260.888235) (xy 92.537344 -260.892218) (xy 92.589306 -260.904078)
			(xy 92.63892 -260.92355) (xy 92.685078 -260.950199) (xy 92.726749 -260.98343) (xy 92.763001 -261.022501)
			(xy 92.793025 -261.066538) (xy 92.816151 -261.114559) (xy 92.831861 -261.165489) (xy 92.839804 -261.218193)
			(xy 92.840302 -261.244842) (xy 92.839804 -261.271491) (xy 93.068384 -261.271491) (xy 93.068384 -261.218193)
			(xy 93.076327 -261.165489) (xy 93.092037 -261.114559) (xy 93.115163 -261.066538) (xy 93.145187 -261.022501)
			(xy 93.181439 -260.98343) (xy 93.22311 -260.950199) (xy 93.269268 -260.92355) (xy 93.318882 -260.904078)
			(xy 93.370844 -260.892218) (xy 93.423994 -260.888235) (xy 93.477144 -260.892218) (xy 93.529106 -260.904078)
			(xy 93.57872 -260.92355) (xy 93.624878 -260.950199) (xy 93.666549 -260.98343) (xy 93.702801 -261.022501)
			(xy 93.732825 -261.066538) (xy 93.755951 -261.114559) (xy 93.771661 -261.165489) (xy 93.779604 -261.218193)
			(xy 93.780102 -261.244842) (xy 93.779604 -261.271491) (xy 94.008184 -261.271491) (xy 94.008184 -261.218193)
			(xy 94.016127 -261.165489) (xy 94.031837 -261.114559) (xy 94.054963 -261.066538) (xy 94.084987 -261.022501)
			(xy 94.121239 -260.98343) (xy 94.16291 -260.950199) (xy 94.209068 -260.92355) (xy 94.258682 -260.904078)
			(xy 94.310644 -260.892218) (xy 94.363794 -260.888235) (xy 94.416944 -260.892218) (xy 94.468906 -260.904078)
			(xy 94.51852 -260.92355) (xy 94.564678 -260.950199) (xy 94.606349 -260.98343) (xy 94.642601 -261.022501)
			(xy 94.672625 -261.066538) (xy 94.695751 -261.114559) (xy 94.711461 -261.165489) (xy 94.719404 -261.218193)
			(xy 94.719902 -261.244842) (xy 94.719404 -261.271491) (xy 94.947984 -261.271491) (xy 94.947984 -261.218193)
			(xy 94.955927 -261.165489) (xy 94.971637 -261.114559) (xy 94.994763 -261.066538) (xy 95.024787 -261.022501)
			(xy 95.061039 -260.98343) (xy 95.10271 -260.950199) (xy 95.148868 -260.92355) (xy 95.198482 -260.904078)
			(xy 95.250444 -260.892218) (xy 95.303594 -260.888235) (xy 95.356744 -260.892218) (xy 95.408706 -260.904078)
			(xy 95.45832 -260.92355) (xy 95.504478 -260.950199) (xy 95.546149 -260.98343) (xy 95.582401 -261.022501)
			(xy 95.612425 -261.066538) (xy 95.635551 -261.114559) (xy 95.651261 -261.165489) (xy 95.659204 -261.218193)
			(xy 95.659702 -261.244842) (xy 95.659204 -261.271491) (xy 95.887784 -261.271491) (xy 95.887784 -261.218193)
			(xy 95.895727 -261.165489) (xy 95.911437 -261.114559) (xy 95.934563 -261.066538) (xy 95.964587 -261.022501)
			(xy 96.000839 -260.98343) (xy 96.04251 -260.950199) (xy 96.088668 -260.92355) (xy 96.138282 -260.904078)
			(xy 96.190244 -260.892218) (xy 96.243394 -260.888235) (xy 96.296544 -260.892218) (xy 96.348506 -260.904078)
			(xy 96.39812 -260.92355) (xy 96.444278 -260.950199) (xy 96.485949 -260.98343) (xy 96.522201 -261.022501)
			(xy 96.552225 -261.066538) (xy 96.575351 -261.114559) (xy 96.591061 -261.165489) (xy 96.599004 -261.218193)
			(xy 96.599502 -261.244842) (xy 96.599004 -261.271491) (xy 96.827584 -261.271491) (xy 96.827584 -261.218193)
			(xy 96.835527 -261.165489) (xy 96.851237 -261.114559) (xy 96.874363 -261.066538) (xy 96.904387 -261.022501)
			(xy 96.940639 -260.98343) (xy 96.98231 -260.950199) (xy 97.028468 -260.92355) (xy 97.078082 -260.904078)
			(xy 97.130044 -260.892218) (xy 97.183194 -260.888235) (xy 97.236344 -260.892218) (xy 97.288306 -260.904078)
			(xy 97.33792 -260.92355) (xy 97.384078 -260.950199) (xy 97.425749 -260.98343) (xy 97.462001 -261.022501)
			(xy 97.492025 -261.066538) (xy 97.515151 -261.114559) (xy 97.530861 -261.165489) (xy 97.538804 -261.218193)
			(xy 97.539302 -261.244842) (xy 97.538804 -261.271491) (xy 97.767384 -261.271491) (xy 97.767384 -261.218193)
			(xy 97.775327 -261.165489) (xy 97.791037 -261.114559) (xy 97.814163 -261.066538) (xy 97.844187 -261.022501)
			(xy 97.880439 -260.98343) (xy 97.92211 -260.950199) (xy 97.968268 -260.92355) (xy 98.017882 -260.904078)
			(xy 98.069844 -260.892218) (xy 98.122994 -260.888235) (xy 98.176144 -260.892218) (xy 98.228106 -260.904078)
			(xy 98.27772 -260.92355) (xy 98.323878 -260.950199) (xy 98.365549 -260.98343) (xy 98.401801 -261.022501)
			(xy 98.431825 -261.066538) (xy 98.454951 -261.114559) (xy 98.470661 -261.165489) (xy 98.478604 -261.218193)
			(xy 98.479102 -261.244842) (xy 98.478604 -261.271491) (xy 98.707184 -261.271491) (xy 98.707184 -261.218193)
			(xy 98.715127 -261.165489) (xy 98.730837 -261.114559) (xy 98.753963 -261.066538) (xy 98.783987 -261.022501)
			(xy 98.820239 -260.98343) (xy 98.86191 -260.950199) (xy 98.908068 -260.92355) (xy 98.957682 -260.904078)
			(xy 99.009644 -260.892218) (xy 99.062794 -260.888235) (xy 99.115944 -260.892218) (xy 99.167906 -260.904078)
			(xy 99.21752 -260.92355) (xy 99.263678 -260.950199) (xy 99.305349 -260.98343) (xy 99.341601 -261.022501)
			(xy 99.371625 -261.066538) (xy 99.394751 -261.114559) (xy 99.410461 -261.165489) (xy 99.418404 -261.218193)
			(xy 99.418902 -261.244842) (xy 99.418404 -261.271491) (xy 99.410461 -261.324195) (xy 99.394751 -261.375125)
			(xy 99.371625 -261.423146) (xy 99.341601 -261.467183) (xy 99.305349 -261.506254) (xy 99.263678 -261.539485)
			(xy 99.21752 -261.566134) (xy 99.167906 -261.585606) (xy 99.115944 -261.597466) (xy 99.062794 -261.60145)
			(xy 99.009644 -261.597466) (xy 98.957682 -261.585606) (xy 98.908068 -261.566134) (xy 98.86191 -261.539485)
			(xy 98.820239 -261.506254) (xy 98.783987 -261.467183) (xy 98.753963 -261.423146) (xy 98.730837 -261.375125)
			(xy 98.715127 -261.324195) (xy 98.707184 -261.271491) (xy 98.478604 -261.271491) (xy 98.470661 -261.324195)
			(xy 98.454951 -261.375125) (xy 98.431825 -261.423146) (xy 98.401801 -261.467183) (xy 98.365549 -261.506254)
			(xy 98.323878 -261.539485) (xy 98.27772 -261.566134) (xy 98.228106 -261.585606) (xy 98.176144 -261.597466)
			(xy 98.122994 -261.60145) (xy 98.069844 -261.597466) (xy 98.017882 -261.585606) (xy 97.968268 -261.566134)
			(xy 97.92211 -261.539485) (xy 97.880439 -261.506254) (xy 97.844187 -261.467183) (xy 97.814163 -261.423146)
			(xy 97.791037 -261.375125) (xy 97.775327 -261.324195) (xy 97.767384 -261.271491) (xy 97.538804 -261.271491)
			(xy 97.530861 -261.324195) (xy 97.515151 -261.375125) (xy 97.492025 -261.423146) (xy 97.462001 -261.467183)
			(xy 97.425749 -261.506254) (xy 97.384078 -261.539485) (xy 97.33792 -261.566134) (xy 97.288306 -261.585606)
			(xy 97.236344 -261.597466) (xy 97.183194 -261.60145) (xy 97.130044 -261.597466) (xy 97.078082 -261.585606)
			(xy 97.028468 -261.566134) (xy 96.98231 -261.539485) (xy 96.940639 -261.506254) (xy 96.904387 -261.467183)
			(xy 96.874363 -261.423146) (xy 96.851237 -261.375125) (xy 96.835527 -261.324195) (xy 96.827584 -261.271491)
			(xy 96.599004 -261.271491) (xy 96.591061 -261.324195) (xy 96.575351 -261.375125) (xy 96.552225 -261.423146)
			(xy 96.522201 -261.467183) (xy 96.485949 -261.506254) (xy 96.444278 -261.539485) (xy 96.39812 -261.566134)
			(xy 96.348506 -261.585606) (xy 96.296544 -261.597466) (xy 96.243394 -261.60145) (xy 96.190244 -261.597466)
			(xy 96.138282 -261.585606) (xy 96.088668 -261.566134) (xy 96.04251 -261.539485) (xy 96.000839 -261.506254)
			(xy 95.964587 -261.467183) (xy 95.934563 -261.423146) (xy 95.911437 -261.375125) (xy 95.895727 -261.324195)
			(xy 95.887784 -261.271491) (xy 95.659204 -261.271491) (xy 95.651261 -261.324195) (xy 95.635551 -261.375125)
			(xy 95.612425 -261.423146) (xy 95.582401 -261.467183) (xy 95.546149 -261.506254) (xy 95.504478 -261.539485)
			(xy 95.45832 -261.566134) (xy 95.408706 -261.585606) (xy 95.356744 -261.597466) (xy 95.303594 -261.60145)
			(xy 95.250444 -261.597466) (xy 95.198482 -261.585606) (xy 95.148868 -261.566134) (xy 95.10271 -261.539485)
			(xy 95.061039 -261.506254) (xy 95.024787 -261.467183) (xy 94.994763 -261.423146) (xy 94.971637 -261.375125)
			(xy 94.955927 -261.324195) (xy 94.947984 -261.271491) (xy 94.719404 -261.271491) (xy 94.711461 -261.324195)
			(xy 94.695751 -261.375125) (xy 94.672625 -261.423146) (xy 94.642601 -261.467183) (xy 94.606349 -261.506254)
			(xy 94.564678 -261.539485) (xy 94.51852 -261.566134) (xy 94.468906 -261.585606) (xy 94.416944 -261.597466)
			(xy 94.363794 -261.60145) (xy 94.310644 -261.597466) (xy 94.258682 -261.585606) (xy 94.209068 -261.566134)
			(xy 94.16291 -261.539485) (xy 94.121239 -261.506254) (xy 94.084987 -261.467183) (xy 94.054963 -261.423146)
			(xy 94.031837 -261.375125) (xy 94.016127 -261.324195) (xy 94.008184 -261.271491) (xy 93.779604 -261.271491)
			(xy 93.771661 -261.324195) (xy 93.755951 -261.375125) (xy 93.732825 -261.423146) (xy 93.702801 -261.467183)
			(xy 93.666549 -261.506254) (xy 93.624878 -261.539485) (xy 93.57872 -261.566134) (xy 93.529106 -261.585606)
			(xy 93.477144 -261.597466) (xy 93.423994 -261.60145) (xy 93.370844 -261.597466) (xy 93.318882 -261.585606)
			(xy 93.269268 -261.566134) (xy 93.22311 -261.539485) (xy 93.181439 -261.506254) (xy 93.145187 -261.467183)
			(xy 93.115163 -261.423146) (xy 93.092037 -261.375125) (xy 93.076327 -261.324195) (xy 93.068384 -261.271491)
			(xy 92.839804 -261.271491) (xy 92.831861 -261.324195) (xy 92.816151 -261.375125) (xy 92.793025 -261.423146)
			(xy 92.763001 -261.467183) (xy 92.726749 -261.506254) (xy 92.685078 -261.539485) (xy 92.63892 -261.566134)
			(xy 92.589306 -261.585606) (xy 92.537344 -261.597466) (xy 92.484194 -261.60145) (xy 92.431044 -261.597466)
			(xy 92.379082 -261.585606) (xy 92.329468 -261.566134) (xy 92.28331 -261.539485) (xy 92.241639 -261.506254)
			(xy 92.205387 -261.467183) (xy 92.175363 -261.423146) (xy 92.152237 -261.375125) (xy 92.136527 -261.324195)
			(xy 92.128584 -261.271491) (xy 91.900004 -261.271491) (xy 91.892061 -261.324195) (xy 91.876351 -261.375125)
			(xy 91.853225 -261.423146) (xy 91.823201 -261.467183) (xy 91.786949 -261.506254) (xy 91.745278 -261.539485)
			(xy 91.69912 -261.566134) (xy 91.649506 -261.585606) (xy 91.597544 -261.597466) (xy 91.544394 -261.60145)
			(xy 91.491244 -261.597466) (xy 91.439282 -261.585606) (xy 91.389668 -261.566134) (xy 91.34351 -261.539485)
			(xy 91.301839 -261.506254) (xy 91.265587 -261.467183) (xy 91.235563 -261.423146) (xy 91.212437 -261.375125)
			(xy 91.196727 -261.324195) (xy 91.188784 -261.271491) (xy 90.960204 -261.271491) (xy 90.952261 -261.324195)
			(xy 90.936551 -261.375125) (xy 90.913425 -261.423146) (xy 90.883401 -261.467183) (xy 90.847149 -261.506254)
			(xy 90.805478 -261.539485) (xy 90.75932 -261.566134) (xy 90.709706 -261.585606) (xy 90.657744 -261.597466)
			(xy 90.604594 -261.60145) (xy 90.551444 -261.597466) (xy 90.499482 -261.585606) (xy 90.449868 -261.566134)
			(xy 90.40371 -261.539485) (xy 90.362039 -261.506254) (xy 90.325787 -261.467183) (xy 90.295763 -261.423146)
			(xy 90.272637 -261.375125) (xy 90.256927 -261.324195) (xy 90.248984 -261.271491) (xy 90.020404 -261.271491)
			(xy 90.012461 -261.324195) (xy 89.996751 -261.375125) (xy 89.973625 -261.423146) (xy 89.943601 -261.467183)
			(xy 89.907349 -261.506254) (xy 89.865678 -261.539485) (xy 89.81952 -261.566134) (xy 89.769906 -261.585606)
			(xy 89.717944 -261.597466) (xy 89.664794 -261.60145) (xy 89.611644 -261.597466) (xy 89.559682 -261.585606)
			(xy 89.510068 -261.566134) (xy 89.46391 -261.539485) (xy 89.422239 -261.506254) (xy 89.385987 -261.467183)
			(xy 89.355963 -261.423146) (xy 89.332837 -261.375125) (xy 89.317127 -261.324195) (xy 89.309184 -261.271491)
			(xy 89.080529 -261.271491) (xy 89.080529 -261.272157) (xy 89.072159 -261.326225) (xy 89.055616 -261.378375)
			(xy 89.031289 -261.427381) (xy 88.999752 -261.472089) (xy 88.961747 -261.511446) (xy 88.918168 -261.544525)
			(xy 88.870042 -261.570548) (xy 88.818501 -261.588903) (xy 88.764759 -261.599156) (xy 88.73744 -261.600696)
			(xy 88.727673 -261.601482) (xy 88.709791 -261.609451) (xy 88.696203 -261.623545) (xy 88.688894 -261.641706)
			(xy 88.688418 -261.651496) (xy 88.688418 -262.085307) (xy 88.839538 -262.085307) (xy 88.839538 -262.032009)
			(xy 88.847481 -261.979305) (xy 88.863191 -261.928375) (xy 88.886317 -261.880354) (xy 88.916341 -261.836317)
			(xy 88.952593 -261.797246) (xy 88.994264 -261.764015) (xy 89.040422 -261.737366) (xy 89.090036 -261.717894)
			(xy 89.141998 -261.706034) (xy 89.195148 -261.702051) (xy 89.248298 -261.706034) (xy 89.30026 -261.717894)
			(xy 89.349874 -261.737366) (xy 89.396032 -261.764015) (xy 89.437703 -261.797246) (xy 89.473955 -261.836317)
			(xy 89.503979 -261.880354) (xy 89.527105 -261.928375) (xy 89.542815 -261.979305) (xy 89.550758 -262.032009)
			(xy 89.551256 -262.058658) (xy 89.550758 -262.085307) (xy 89.779084 -262.085307) (xy 89.779084 -262.032009)
			(xy 89.787027 -261.979305) (xy 89.802737 -261.928375) (xy 89.825863 -261.880354) (xy 89.855887 -261.836317)
			(xy 89.892139 -261.797246) (xy 89.93381 -261.764015) (xy 89.979968 -261.737366) (xy 90.029582 -261.717894)
			(xy 90.081544 -261.706034) (xy 90.134694 -261.702051) (xy 90.187844 -261.706034) (xy 90.239806 -261.717894)
			(xy 90.28942 -261.737366) (xy 90.335578 -261.764015) (xy 90.377249 -261.797246) (xy 90.413501 -261.836317)
			(xy 90.443525 -261.880354) (xy 90.466651 -261.928375) (xy 90.482361 -261.979305) (xy 90.490304 -262.032009)
			(xy 90.490802 -262.058658) (xy 90.490304 -262.085307) (xy 90.718884 -262.085307) (xy 90.718884 -262.032009)
			(xy 90.726827 -261.979305) (xy 90.742537 -261.928375) (xy 90.765663 -261.880354) (xy 90.795687 -261.836317)
			(xy 90.831939 -261.797246) (xy 90.87361 -261.764015) (xy 90.919768 -261.737366) (xy 90.969382 -261.717894)
			(xy 91.021344 -261.706034) (xy 91.074494 -261.702051) (xy 91.127644 -261.706034) (xy 91.179606 -261.717894)
			(xy 91.22922 -261.737366) (xy 91.275378 -261.764015) (xy 91.317049 -261.797246) (xy 91.353301 -261.836317)
			(xy 91.383325 -261.880354) (xy 91.406451 -261.928375) (xy 91.422161 -261.979305) (xy 91.430104 -262.032009)
			(xy 91.430602 -262.058658) (xy 91.430104 -262.085307) (xy 91.658938 -262.085307) (xy 91.658938 -262.032009)
			(xy 91.666881 -261.979305) (xy 91.682591 -261.928375) (xy 91.705717 -261.880354) (xy 91.735741 -261.836317)
			(xy 91.771993 -261.797246) (xy 91.813664 -261.764015) (xy 91.859822 -261.737366) (xy 91.909436 -261.717894)
			(xy 91.961398 -261.706034) (xy 92.014548 -261.702051) (xy 92.067698 -261.706034) (xy 92.11966 -261.717894)
			(xy 92.169274 -261.737366) (xy 92.215432 -261.764015) (xy 92.257103 -261.797246) (xy 92.293355 -261.836317)
			(xy 92.323379 -261.880354) (xy 92.346505 -261.928375) (xy 92.362215 -261.979305) (xy 92.370158 -262.032009)
			(xy 92.370656 -262.058658) (xy 92.370158 -262.085307) (xy 92.598738 -262.085307) (xy 92.598738 -262.032009)
			(xy 92.606681 -261.979305) (xy 92.622391 -261.928375) (xy 92.645517 -261.880354) (xy 92.675541 -261.836317)
			(xy 92.711793 -261.797246) (xy 92.753464 -261.764015) (xy 92.799622 -261.737366) (xy 92.849236 -261.717894)
			(xy 92.901198 -261.706034) (xy 92.954348 -261.702051) (xy 93.007498 -261.706034) (xy 93.05946 -261.717894)
			(xy 93.109074 -261.737366) (xy 93.155232 -261.764015) (xy 93.196903 -261.797246) (xy 93.233155 -261.836317)
			(xy 93.263179 -261.880354) (xy 93.286305 -261.928375) (xy 93.302015 -261.979305) (xy 93.309958 -262.032009)
			(xy 93.310456 -262.058658) (xy 93.309958 -262.085307) (xy 93.538538 -262.085307) (xy 93.538538 -262.032009)
			(xy 93.546481 -261.979305) (xy 93.562191 -261.928375) (xy 93.585317 -261.880354) (xy 93.615341 -261.836317)
			(xy 93.651593 -261.797246) (xy 93.693264 -261.764015) (xy 93.739422 -261.737366) (xy 93.789036 -261.717894)
			(xy 93.840998 -261.706034) (xy 93.894148 -261.702051) (xy 93.947298 -261.706034) (xy 93.99926 -261.717894)
			(xy 94.048874 -261.737366) (xy 94.095032 -261.764015) (xy 94.136703 -261.797246) (xy 94.172955 -261.836317)
			(xy 94.202979 -261.880354) (xy 94.226105 -261.928375) (xy 94.241815 -261.979305) (xy 94.249758 -262.032009)
			(xy 94.250256 -262.058658) (xy 94.249758 -262.085307) (xy 94.478338 -262.085307) (xy 94.478338 -262.032009)
			(xy 94.486281 -261.979305) (xy 94.501991 -261.928375) (xy 94.525117 -261.880354) (xy 94.555141 -261.836317)
			(xy 94.591393 -261.797246) (xy 94.633064 -261.764015) (xy 94.679222 -261.737366) (xy 94.728836 -261.717894)
			(xy 94.780798 -261.706034) (xy 94.833948 -261.702051) (xy 94.887098 -261.706034) (xy 94.93906 -261.717894)
			(xy 94.988674 -261.737366) (xy 95.034832 -261.764015) (xy 95.076503 -261.797246) (xy 95.112755 -261.836317)
			(xy 95.142779 -261.880354) (xy 95.165905 -261.928375) (xy 95.181615 -261.979305) (xy 95.189558 -262.032009)
			(xy 95.190056 -262.058658) (xy 95.189558 -262.085307) (xy 95.418138 -262.085307) (xy 95.418138 -262.032009)
			(xy 95.426081 -261.979305) (xy 95.441791 -261.928375) (xy 95.464917 -261.880354) (xy 95.494941 -261.836317)
			(xy 95.531193 -261.797246) (xy 95.572864 -261.764015) (xy 95.619022 -261.737366) (xy 95.668636 -261.717894)
			(xy 95.720598 -261.706034) (xy 95.773748 -261.702051) (xy 95.826898 -261.706034) (xy 95.87886 -261.717894)
			(xy 95.928474 -261.737366) (xy 95.974632 -261.764015) (xy 96.016303 -261.797246) (xy 96.052555 -261.836317)
			(xy 96.082579 -261.880354) (xy 96.105705 -261.928375) (xy 96.121415 -261.979305) (xy 96.129358 -262.032009)
			(xy 96.129856 -262.058658) (xy 96.129358 -262.085307) (xy 96.357938 -262.085307) (xy 96.357938 -262.032009)
			(xy 96.365881 -261.979305) (xy 96.381591 -261.928375) (xy 96.404717 -261.880354) (xy 96.434741 -261.836317)
			(xy 96.470993 -261.797246) (xy 96.512664 -261.764015) (xy 96.558822 -261.737366) (xy 96.608436 -261.717894)
			(xy 96.660398 -261.706034) (xy 96.713548 -261.702051) (xy 96.766698 -261.706034) (xy 96.81866 -261.717894)
			(xy 96.868274 -261.737366) (xy 96.914432 -261.764015) (xy 96.956103 -261.797246) (xy 96.992355 -261.836317)
			(xy 97.022379 -261.880354) (xy 97.045505 -261.928375) (xy 97.061215 -261.979305) (xy 97.069158 -262.032009)
			(xy 97.069656 -262.058658) (xy 97.069158 -262.085307) (xy 97.297484 -262.085307) (xy 97.297484 -262.032009)
			(xy 97.305427 -261.979305) (xy 97.321137 -261.928375) (xy 97.344263 -261.880354) (xy 97.374287 -261.836317)
			(xy 97.410539 -261.797246) (xy 97.45221 -261.764015) (xy 97.498368 -261.737366) (xy 97.547982 -261.717894)
			(xy 97.599944 -261.706034) (xy 97.653094 -261.702051) (xy 97.706244 -261.706034) (xy 97.758206 -261.717894)
			(xy 97.80782 -261.737366) (xy 97.853978 -261.764015) (xy 97.895649 -261.797246) (xy 97.931901 -261.836317)
			(xy 97.961925 -261.880354) (xy 97.985051 -261.928375) (xy 98.000761 -261.979305) (xy 98.008704 -262.032009)
			(xy 98.009202 -262.058658) (xy 98.008704 -262.085307) (xy 98.237538 -262.085307) (xy 98.237538 -262.032009)
			(xy 98.245481 -261.979305) (xy 98.261191 -261.928375) (xy 98.284317 -261.880354) (xy 98.314341 -261.836317)
			(xy 98.350593 -261.797246) (xy 98.392264 -261.764015) (xy 98.438422 -261.737366) (xy 98.488036 -261.717894)
			(xy 98.539998 -261.706034) (xy 98.593148 -261.702051) (xy 98.646298 -261.706034) (xy 98.69826 -261.717894)
			(xy 98.747874 -261.737366) (xy 98.794032 -261.764015) (xy 98.835703 -261.797246) (xy 98.871955 -261.836317)
			(xy 98.901979 -261.880354) (xy 98.925105 -261.928375) (xy 98.940815 -261.979305) (xy 98.948758 -262.032009)
			(xy 98.949256 -262.058658) (xy 98.948758 -262.085307) (xy 99.177338 -262.085307) (xy 99.177338 -262.032009)
			(xy 99.185281 -261.979305) (xy 99.200991 -261.928375) (xy 99.224117 -261.880354) (xy 99.254141 -261.836317)
			(xy 99.290393 -261.797246) (xy 99.332064 -261.764015) (xy 99.378222 -261.737366) (xy 99.427836 -261.717894)
			(xy 99.479798 -261.706034) (xy 99.532948 -261.702051) (xy 99.586098 -261.706034) (xy 99.63806 -261.717894)
			(xy 99.687674 -261.737366) (xy 99.733832 -261.764015) (xy 99.775503 -261.797246) (xy 99.811755 -261.836317)
			(xy 99.841779 -261.880354) (xy 99.864905 -261.928375) (xy 99.880615 -261.979305) (xy 99.888558 -262.032009)
			(xy 99.889056 -262.058658) (xy 99.888558 -262.085307) (xy 99.880615 -262.138011) (xy 99.864905 -262.188941)
			(xy 99.841779 -262.236962) (xy 99.811755 -262.280999) (xy 99.775503 -262.32007) (xy 99.733832 -262.353301)
			(xy 99.687674 -262.37995) (xy 99.63806 -262.399422) (xy 99.586098 -262.411282) (xy 99.532948 -262.415266)
			(xy 99.479798 -262.411282) (xy 99.427836 -262.399422) (xy 99.378222 -262.37995) (xy 99.332064 -262.353301)
			(xy 99.290393 -262.32007) (xy 99.254141 -262.280999) (xy 99.224117 -262.236962) (xy 99.200991 -262.188941)
			(xy 99.185281 -262.138011) (xy 99.177338 -262.085307) (xy 98.948758 -262.085307) (xy 98.940815 -262.138011)
			(xy 98.925105 -262.188941) (xy 98.901979 -262.236962) (xy 98.871955 -262.280999) (xy 98.835703 -262.32007)
			(xy 98.794032 -262.353301) (xy 98.747874 -262.37995) (xy 98.69826 -262.399422) (xy 98.646298 -262.411282)
			(xy 98.593148 -262.415266) (xy 98.539998 -262.411282) (xy 98.488036 -262.399422) (xy 98.438422 -262.37995)
			(xy 98.392264 -262.353301) (xy 98.350593 -262.32007) (xy 98.314341 -262.280999) (xy 98.284317 -262.236962)
			(xy 98.261191 -262.188941) (xy 98.245481 -262.138011) (xy 98.237538 -262.085307) (xy 98.008704 -262.085307)
			(xy 98.000761 -262.138011) (xy 97.985051 -262.188941) (xy 97.961925 -262.236962) (xy 97.931901 -262.280999)
			(xy 97.895649 -262.32007) (xy 97.853978 -262.353301) (xy 97.80782 -262.37995) (xy 97.758206 -262.399422)
			(xy 97.706244 -262.411282) (xy 97.653094 -262.415266) (xy 97.599944 -262.411282) (xy 97.547982 -262.399422)
			(xy 97.498368 -262.37995) (xy 97.45221 -262.353301) (xy 97.410539 -262.32007) (xy 97.374287 -262.280999)
			(xy 97.344263 -262.236962) (xy 97.321137 -262.188941) (xy 97.305427 -262.138011) (xy 97.297484 -262.085307)
			(xy 97.069158 -262.085307) (xy 97.061215 -262.138011) (xy 97.045505 -262.188941) (xy 97.022379 -262.236962)
			(xy 96.992355 -262.280999) (xy 96.956103 -262.32007) (xy 96.914432 -262.353301) (xy 96.868274 -262.37995)
			(xy 96.81866 -262.399422) (xy 96.766698 -262.411282) (xy 96.713548 -262.415266) (xy 96.660398 -262.411282)
			(xy 96.608436 -262.399422) (xy 96.558822 -262.37995) (xy 96.512664 -262.353301) (xy 96.470993 -262.32007)
			(xy 96.434741 -262.280999) (xy 96.404717 -262.236962) (xy 96.381591 -262.188941) (xy 96.365881 -262.138011)
			(xy 96.357938 -262.085307) (xy 96.129358 -262.085307) (xy 96.121415 -262.138011) (xy 96.105705 -262.188941)
			(xy 96.082579 -262.236962) (xy 96.052555 -262.280999) (xy 96.016303 -262.32007) (xy 95.974632 -262.353301)
			(xy 95.928474 -262.37995) (xy 95.87886 -262.399422) (xy 95.826898 -262.411282) (xy 95.773748 -262.415266)
			(xy 95.720598 -262.411282) (xy 95.668636 -262.399422) (xy 95.619022 -262.37995) (xy 95.572864 -262.353301)
			(xy 95.531193 -262.32007) (xy 95.494941 -262.280999) (xy 95.464917 -262.236962) (xy 95.441791 -262.188941)
			(xy 95.426081 -262.138011) (xy 95.418138 -262.085307) (xy 95.189558 -262.085307) (xy 95.181615 -262.138011)
			(xy 95.165905 -262.188941) (xy 95.142779 -262.236962) (xy 95.112755 -262.280999) (xy 95.076503 -262.32007)
			(xy 95.034832 -262.353301) (xy 94.988674 -262.37995) (xy 94.93906 -262.399422) (xy 94.887098 -262.411282)
			(xy 94.833948 -262.415266) (xy 94.780798 -262.411282) (xy 94.728836 -262.399422) (xy 94.679222 -262.37995)
			(xy 94.633064 -262.353301) (xy 94.591393 -262.32007) (xy 94.555141 -262.280999) (xy 94.525117 -262.236962)
			(xy 94.501991 -262.188941) (xy 94.486281 -262.138011) (xy 94.478338 -262.085307) (xy 94.249758 -262.085307)
			(xy 94.241815 -262.138011) (xy 94.226105 -262.188941) (xy 94.202979 -262.236962) (xy 94.172955 -262.280999)
			(xy 94.136703 -262.32007) (xy 94.095032 -262.353301) (xy 94.048874 -262.37995) (xy 93.99926 -262.399422)
			(xy 93.947298 -262.411282) (xy 93.894148 -262.415266) (xy 93.840998 -262.411282) (xy 93.789036 -262.399422)
			(xy 93.739422 -262.37995) (xy 93.693264 -262.353301) (xy 93.651593 -262.32007) (xy 93.615341 -262.280999)
			(xy 93.585317 -262.236962) (xy 93.562191 -262.188941) (xy 93.546481 -262.138011) (xy 93.538538 -262.085307)
			(xy 93.309958 -262.085307) (xy 93.302015 -262.138011) (xy 93.286305 -262.188941) (xy 93.263179 -262.236962)
			(xy 93.233155 -262.280999) (xy 93.196903 -262.32007) (xy 93.155232 -262.353301) (xy 93.109074 -262.37995)
			(xy 93.05946 -262.399422) (xy 93.007498 -262.411282) (xy 92.954348 -262.415266) (xy 92.901198 -262.411282)
			(xy 92.849236 -262.399422) (xy 92.799622 -262.37995) (xy 92.753464 -262.353301) (xy 92.711793 -262.32007)
			(xy 92.675541 -262.280999) (xy 92.645517 -262.236962) (xy 92.622391 -262.188941) (xy 92.606681 -262.138011)
			(xy 92.598738 -262.085307) (xy 92.370158 -262.085307) (xy 92.362215 -262.138011) (xy 92.346505 -262.188941)
			(xy 92.323379 -262.236962) (xy 92.293355 -262.280999) (xy 92.257103 -262.32007) (xy 92.215432 -262.353301)
			(xy 92.169274 -262.37995) (xy 92.11966 -262.399422) (xy 92.067698 -262.411282) (xy 92.014548 -262.415266)
			(xy 91.961398 -262.411282) (xy 91.909436 -262.399422) (xy 91.859822 -262.37995) (xy 91.813664 -262.353301)
			(xy 91.771993 -262.32007) (xy 91.735741 -262.280999) (xy 91.705717 -262.236962) (xy 91.682591 -262.188941)
			(xy 91.666881 -262.138011) (xy 91.658938 -262.085307) (xy 91.430104 -262.085307) (xy 91.422161 -262.138011)
			(xy 91.406451 -262.188941) (xy 91.383325 -262.236962) (xy 91.353301 -262.280999) (xy 91.317049 -262.32007)
			(xy 91.275378 -262.353301) (xy 91.22922 -262.37995) (xy 91.179606 -262.399422) (xy 91.127644 -262.411282)
			(xy 91.074494 -262.415266) (xy 91.021344 -262.411282) (xy 90.969382 -262.399422) (xy 90.919768 -262.37995)
			(xy 90.87361 -262.353301) (xy 90.831939 -262.32007) (xy 90.795687 -262.280999) (xy 90.765663 -262.236962)
			(xy 90.742537 -262.188941) (xy 90.726827 -262.138011) (xy 90.718884 -262.085307) (xy 90.490304 -262.085307)
			(xy 90.482361 -262.138011) (xy 90.466651 -262.188941) (xy 90.443525 -262.236962) (xy 90.413501 -262.280999)
			(xy 90.377249 -262.32007) (xy 90.335578 -262.353301) (xy 90.28942 -262.37995) (xy 90.239806 -262.399422)
			(xy 90.187844 -262.411282) (xy 90.134694 -262.415266) (xy 90.081544 -262.411282) (xy 90.029582 -262.399422)
			(xy 89.979968 -262.37995) (xy 89.93381 -262.353301) (xy 89.892139 -262.32007) (xy 89.855887 -262.280999)
			(xy 89.825863 -262.236962) (xy 89.802737 -262.188941) (xy 89.787027 -262.138011) (xy 89.779084 -262.085307)
			(xy 89.550758 -262.085307) (xy 89.542815 -262.138011) (xy 89.527105 -262.188941) (xy 89.503979 -262.236962)
			(xy 89.473955 -262.280999) (xy 89.437703 -262.32007) (xy 89.396032 -262.353301) (xy 89.349874 -262.37995)
			(xy 89.30026 -262.399422) (xy 89.248298 -262.411282) (xy 89.195148 -262.415266) (xy 89.141998 -262.411282)
			(xy 89.090036 -262.399422) (xy 89.040422 -262.37995) (xy 88.994264 -262.353301) (xy 88.952593 -262.32007)
			(xy 88.916341 -262.280999) (xy 88.886317 -262.236962) (xy 88.863191 -262.188941) (xy 88.847481 -262.138011)
			(xy 88.839538 -262.085307) (xy 88.688418 -262.085307) (xy 88.688418 -262.46582) (xy 88.688865 -262.475611)
			(xy 88.696198 -262.493767) (xy 88.709791 -262.507862) (xy 88.727671 -262.515847) (xy 88.73744 -262.51662)
			(xy 88.764767 -262.518076) (xy 88.818519 -262.528332) (xy 88.87007 -262.54669) (xy 88.918206 -262.572718)
			(xy 88.961793 -262.605804) (xy 88.999805 -262.645168) (xy 89.031348 -262.689884) (xy 89.055679 -262.7389)
			(xy 89.072225 -262.79106) (xy 89.080597 -262.845138) (xy 89.080597 -262.899123) (xy 89.309184 -262.899123)
			(xy 89.309184 -262.845825) (xy 89.317127 -262.793121) (xy 89.332837 -262.742191) (xy 89.355963 -262.69417)
			(xy 89.385987 -262.650133) (xy 89.422239 -262.611062) (xy 89.46391 -262.577831) (xy 89.510068 -262.551182)
			(xy 89.559682 -262.53171) (xy 89.611644 -262.51985) (xy 89.664794 -262.515867) (xy 89.717944 -262.51985)
			(xy 89.769906 -262.53171) (xy 89.81952 -262.551182) (xy 89.865678 -262.577831) (xy 89.907349 -262.611062)
			(xy 89.943601 -262.650133) (xy 89.973625 -262.69417) (xy 89.996751 -262.742191) (xy 90.012461 -262.793121)
			(xy 90.020404 -262.845825) (xy 90.020902 -262.872474) (xy 90.020404 -262.899123) (xy 90.249238 -262.899123)
			(xy 90.249238 -262.845825) (xy 90.257181 -262.793121) (xy 90.272891 -262.742191) (xy 90.296017 -262.69417)
			(xy 90.326041 -262.650133) (xy 90.362293 -262.611062) (xy 90.403964 -262.577831) (xy 90.450122 -262.551182)
			(xy 90.499736 -262.53171) (xy 90.551698 -262.51985) (xy 90.604848 -262.515867) (xy 90.657998 -262.51985)
			(xy 90.70996 -262.53171) (xy 90.759574 -262.551182) (xy 90.805732 -262.577831) (xy 90.847403 -262.611062)
			(xy 90.883655 -262.650133) (xy 90.913679 -262.69417) (xy 90.936805 -262.742191) (xy 90.952515 -262.793121)
			(xy 90.960458 -262.845825) (xy 90.960956 -262.872474) (xy 90.960458 -262.899123) (xy 91.188784 -262.899123)
			(xy 91.188784 -262.845825) (xy 91.196727 -262.793121) (xy 91.212437 -262.742191) (xy 91.235563 -262.69417)
			(xy 91.265587 -262.650133) (xy 91.301839 -262.611062) (xy 91.34351 -262.577831) (xy 91.389668 -262.551182)
			(xy 91.439282 -262.53171) (xy 91.491244 -262.51985) (xy 91.544394 -262.515867) (xy 91.597544 -262.51985)
			(xy 91.649506 -262.53171) (xy 91.69912 -262.551182) (xy 91.745278 -262.577831) (xy 91.786949 -262.611062)
			(xy 91.823201 -262.650133) (xy 91.853225 -262.69417) (xy 91.876351 -262.742191) (xy 91.892061 -262.793121)
			(xy 91.900004 -262.845825) (xy 91.900502 -262.872474) (xy 91.900004 -262.899123) (xy 92.128584 -262.899123)
			(xy 92.128584 -262.845825) (xy 92.136527 -262.793121) (xy 92.152237 -262.742191) (xy 92.175363 -262.69417)
			(xy 92.205387 -262.650133) (xy 92.241639 -262.611062) (xy 92.28331 -262.577831) (xy 92.329468 -262.551182)
			(xy 92.379082 -262.53171) (xy 92.431044 -262.51985) (xy 92.484194 -262.515867) (xy 92.537344 -262.51985)
			(xy 92.589306 -262.53171) (xy 92.63892 -262.551182) (xy 92.685078 -262.577831) (xy 92.726749 -262.611062)
			(xy 92.763001 -262.650133) (xy 92.793025 -262.69417) (xy 92.816151 -262.742191) (xy 92.831861 -262.793121)
			(xy 92.839804 -262.845825) (xy 92.840302 -262.872474) (xy 92.839804 -262.899123) (xy 93.068384 -262.899123)
			(xy 93.068384 -262.845825) (xy 93.076327 -262.793121) (xy 93.092037 -262.742191) (xy 93.115163 -262.69417)
			(xy 93.145187 -262.650133) (xy 93.181439 -262.611062) (xy 93.22311 -262.577831) (xy 93.269268 -262.551182)
			(xy 93.318882 -262.53171) (xy 93.370844 -262.51985) (xy 93.423994 -262.515867) (xy 93.477144 -262.51985)
			(xy 93.529106 -262.53171) (xy 93.57872 -262.551182) (xy 93.624878 -262.577831) (xy 93.666549 -262.611062)
			(xy 93.702801 -262.650133) (xy 93.732825 -262.69417) (xy 93.755951 -262.742191) (xy 93.771661 -262.793121)
			(xy 93.779604 -262.845825) (xy 93.780102 -262.872474) (xy 93.779604 -262.899123) (xy 94.008184 -262.899123)
			(xy 94.008184 -262.845825) (xy 94.016127 -262.793121) (xy 94.031837 -262.742191) (xy 94.054963 -262.69417)
			(xy 94.084987 -262.650133) (xy 94.121239 -262.611062) (xy 94.16291 -262.577831) (xy 94.209068 -262.551182)
			(xy 94.258682 -262.53171) (xy 94.310644 -262.51985) (xy 94.363794 -262.515867) (xy 94.416944 -262.51985)
			(xy 94.468906 -262.53171) (xy 94.51852 -262.551182) (xy 94.564678 -262.577831) (xy 94.606349 -262.611062)
			(xy 94.642601 -262.650133) (xy 94.672625 -262.69417) (xy 94.695751 -262.742191) (xy 94.711461 -262.793121)
			(xy 94.719404 -262.845825) (xy 94.719902 -262.872474) (xy 94.719404 -262.899123) (xy 94.947984 -262.899123)
			(xy 94.947984 -262.845825) (xy 94.955927 -262.793121) (xy 94.971637 -262.742191) (xy 94.994763 -262.69417)
			(xy 95.024787 -262.650133) (xy 95.061039 -262.611062) (xy 95.10271 -262.577831) (xy 95.148868 -262.551182)
			(xy 95.198482 -262.53171) (xy 95.250444 -262.51985) (xy 95.303594 -262.515867) (xy 95.356744 -262.51985)
			(xy 95.408706 -262.53171) (xy 95.45832 -262.551182) (xy 95.504478 -262.577831) (xy 95.546149 -262.611062)
			(xy 95.582401 -262.650133) (xy 95.612425 -262.69417) (xy 95.635551 -262.742191) (xy 95.651261 -262.793121)
			(xy 95.659204 -262.845825) (xy 95.659702 -262.872474) (xy 95.659204 -262.899123) (xy 95.887784 -262.899123)
			(xy 95.887784 -262.845825) (xy 95.895727 -262.793121) (xy 95.911437 -262.742191) (xy 95.934563 -262.69417)
			(xy 95.964587 -262.650133) (xy 96.000839 -262.611062) (xy 96.04251 -262.577831) (xy 96.088668 -262.551182)
			(xy 96.138282 -262.53171) (xy 96.190244 -262.51985) (xy 96.243394 -262.515867) (xy 96.296544 -262.51985)
			(xy 96.348506 -262.53171) (xy 96.39812 -262.551182) (xy 96.444278 -262.577831) (xy 96.485949 -262.611062)
			(xy 96.522201 -262.650133) (xy 96.552225 -262.69417) (xy 96.575351 -262.742191) (xy 96.591061 -262.793121)
			(xy 96.599004 -262.845825) (xy 96.599502 -262.872474) (xy 96.599004 -262.899123) (xy 96.827838 -262.899123)
			(xy 96.827838 -262.845825) (xy 96.835781 -262.793121) (xy 96.851491 -262.742191) (xy 96.874617 -262.69417)
			(xy 96.904641 -262.650133) (xy 96.940893 -262.611062) (xy 96.982564 -262.577831) (xy 97.028722 -262.551182)
			(xy 97.078336 -262.53171) (xy 97.130298 -262.51985) (xy 97.183448 -262.515867) (xy 97.236598 -262.51985)
			(xy 97.28856 -262.53171) (xy 97.338174 -262.551182) (xy 97.384332 -262.577831) (xy 97.426003 -262.611062)
			(xy 97.462255 -262.650133) (xy 97.492279 -262.69417) (xy 97.515405 -262.742191) (xy 97.531115 -262.793121)
			(xy 97.539058 -262.845825) (xy 97.539556 -262.872474) (xy 97.539058 -262.899123) (xy 97.767384 -262.899123)
			(xy 97.767384 -262.845825) (xy 97.775327 -262.793121) (xy 97.791037 -262.742191) (xy 97.814163 -262.69417)
			(xy 97.844187 -262.650133) (xy 97.880439 -262.611062) (xy 97.92211 -262.577831) (xy 97.968268 -262.551182)
			(xy 98.017882 -262.53171) (xy 98.069844 -262.51985) (xy 98.122994 -262.515867) (xy 98.176144 -262.51985)
			(xy 98.228106 -262.53171) (xy 98.27772 -262.551182) (xy 98.323878 -262.577831) (xy 98.365549 -262.611062)
			(xy 98.401801 -262.650133) (xy 98.431825 -262.69417) (xy 98.454951 -262.742191) (xy 98.470661 -262.793121)
			(xy 98.478604 -262.845825) (xy 98.479102 -262.872474) (xy 98.478604 -262.899123) (xy 98.707184 -262.899123)
			(xy 98.707184 -262.845825) (xy 98.715127 -262.793121) (xy 98.730837 -262.742191) (xy 98.753963 -262.69417)
			(xy 98.783987 -262.650133) (xy 98.820239 -262.611062) (xy 98.86191 -262.577831) (xy 98.908068 -262.551182)
			(xy 98.957682 -262.53171) (xy 99.009644 -262.51985) (xy 99.062794 -262.515867) (xy 99.115944 -262.51985)
			(xy 99.167906 -262.53171) (xy 99.21752 -262.551182) (xy 99.263678 -262.577831) (xy 99.305349 -262.611062)
			(xy 99.341601 -262.650133) (xy 99.371625 -262.69417) (xy 99.394751 -262.742191) (xy 99.410461 -262.793121)
			(xy 99.418404 -262.845825) (xy 99.418902 -262.872474) (xy 99.418404 -262.899123) (xy 99.646984 -262.899123)
			(xy 99.646984 -262.845825) (xy 99.654927 -262.793121) (xy 99.670637 -262.742191) (xy 99.693763 -262.69417)
			(xy 99.723787 -262.650133) (xy 99.760039 -262.611062) (xy 99.80171 -262.577831) (xy 99.847868 -262.551182)
			(xy 99.897482 -262.53171) (xy 99.949444 -262.51985) (xy 100.002594 -262.515867) (xy 100.055744 -262.51985)
			(xy 100.107706 -262.53171) (xy 100.15732 -262.551182) (xy 100.203478 -262.577831) (xy 100.245149 -262.611062)
			(xy 100.281401 -262.650133) (xy 100.311425 -262.69417) (xy 100.334551 -262.742191) (xy 100.350261 -262.793121)
			(xy 100.358204 -262.845825) (xy 100.358702 -262.872474) (xy 100.358204 -262.899123) (xy 100.586784 -262.899123)
			(xy 100.586784 -262.845825) (xy 100.594727 -262.793121) (xy 100.610437 -262.742191) (xy 100.633563 -262.69417)
			(xy 100.663587 -262.650133) (xy 100.699839 -262.611062) (xy 100.74151 -262.577831) (xy 100.787668 -262.551182)
			(xy 100.837282 -262.53171) (xy 100.889244 -262.51985) (xy 100.942394 -262.515867) (xy 100.995544 -262.51985)
			(xy 101.047506 -262.53171) (xy 101.09712 -262.551182) (xy 101.143278 -262.577831) (xy 101.184949 -262.611062)
			(xy 101.221201 -262.650133) (xy 101.251225 -262.69417) (xy 101.274351 -262.742191) (xy 101.290061 -262.793121)
			(xy 101.298004 -262.845825) (xy 101.298502 -262.872474) (xy 101.298004 -262.899123) (xy 101.290061 -262.951827)
			(xy 101.274351 -263.002757) (xy 101.251225 -263.050778) (xy 101.221201 -263.094815) (xy 101.184949 -263.133886)
			(xy 101.143278 -263.167117) (xy 101.09712 -263.193766) (xy 101.047506 -263.213238) (xy 100.995544 -263.225098)
			(xy 100.942394 -263.229082) (xy 100.889244 -263.225098) (xy 100.837282 -263.213238) (xy 100.787668 -263.193766)
			(xy 100.74151 -263.167117) (xy 100.699839 -263.133886) (xy 100.663587 -263.094815) (xy 100.633563 -263.050778)
			(xy 100.610437 -263.002757) (xy 100.594727 -262.951827) (xy 100.586784 -262.899123) (xy 100.358204 -262.899123)
			(xy 100.350261 -262.951827) (xy 100.334551 -263.002757) (xy 100.311425 -263.050778) (xy 100.281401 -263.094815)
			(xy 100.245149 -263.133886) (xy 100.203478 -263.167117) (xy 100.15732 -263.193766) (xy 100.107706 -263.213238)
			(xy 100.055744 -263.225098) (xy 100.002594 -263.229082) (xy 99.949444 -263.225098) (xy 99.897482 -263.213238)
			(xy 99.847868 -263.193766) (xy 99.80171 -263.167117) (xy 99.760039 -263.133886) (xy 99.723787 -263.094815)
			(xy 99.693763 -263.050778) (xy 99.670637 -263.002757) (xy 99.654927 -262.951827) (xy 99.646984 -262.899123)
			(xy 99.418404 -262.899123) (xy 99.410461 -262.951827) (xy 99.394751 -263.002757) (xy 99.371625 -263.050778)
			(xy 99.341601 -263.094815) (xy 99.305349 -263.133886) (xy 99.263678 -263.167117) (xy 99.21752 -263.193766)
			(xy 99.167906 -263.213238) (xy 99.115944 -263.225098) (xy 99.062794 -263.229082) (xy 99.009644 -263.225098)
			(xy 98.957682 -263.213238) (xy 98.908068 -263.193766) (xy 98.86191 -263.167117) (xy 98.820239 -263.133886)
			(xy 98.783987 -263.094815) (xy 98.753963 -263.050778) (xy 98.730837 -263.002757) (xy 98.715127 -262.951827)
			(xy 98.707184 -262.899123) (xy 98.478604 -262.899123) (xy 98.470661 -262.951827) (xy 98.454951 -263.002757)
			(xy 98.431825 -263.050778) (xy 98.401801 -263.094815) (xy 98.365549 -263.133886) (xy 98.323878 -263.167117)
			(xy 98.27772 -263.193766) (xy 98.228106 -263.213238) (xy 98.176144 -263.225098) (xy 98.122994 -263.229082)
			(xy 98.069844 -263.225098) (xy 98.017882 -263.213238) (xy 97.968268 -263.193766) (xy 97.92211 -263.167117)
			(xy 97.880439 -263.133886) (xy 97.844187 -263.094815) (xy 97.814163 -263.050778) (xy 97.791037 -263.002757)
			(xy 97.775327 -262.951827) (xy 97.767384 -262.899123) (xy 97.539058 -262.899123) (xy 97.531115 -262.951827)
			(xy 97.515405 -263.002757) (xy 97.492279 -263.050778) (xy 97.462255 -263.094815) (xy 97.426003 -263.133886)
			(xy 97.384332 -263.167117) (xy 97.338174 -263.193766) (xy 97.28856 -263.213238) (xy 97.236598 -263.225098)
			(xy 97.183448 -263.229082) (xy 97.130298 -263.225098) (xy 97.078336 -263.213238) (xy 97.028722 -263.193766)
			(xy 96.982564 -263.167117) (xy 96.940893 -263.133886) (xy 96.904641 -263.094815) (xy 96.874617 -263.050778)
			(xy 96.851491 -263.002757) (xy 96.835781 -262.951827) (xy 96.827838 -262.899123) (xy 96.599004 -262.899123)
			(xy 96.591061 -262.951827) (xy 96.575351 -263.002757) (xy 96.552225 -263.050778) (xy 96.522201 -263.094815)
			(xy 96.485949 -263.133886) (xy 96.444278 -263.167117) (xy 96.39812 -263.193766) (xy 96.348506 -263.213238)
			(xy 96.296544 -263.225098) (xy 96.243394 -263.229082) (xy 96.190244 -263.225098) (xy 96.138282 -263.213238)
			(xy 96.088668 -263.193766) (xy 96.04251 -263.167117) (xy 96.000839 -263.133886) (xy 95.964587 -263.094815)
			(xy 95.934563 -263.050778) (xy 95.911437 -263.002757) (xy 95.895727 -262.951827) (xy 95.887784 -262.899123)
			(xy 95.659204 -262.899123) (xy 95.651261 -262.951827) (xy 95.635551 -263.002757) (xy 95.612425 -263.050778)
			(xy 95.582401 -263.094815) (xy 95.546149 -263.133886) (xy 95.504478 -263.167117) (xy 95.45832 -263.193766)
			(xy 95.408706 -263.213238) (xy 95.356744 -263.225098) (xy 95.303594 -263.229082) (xy 95.250444 -263.225098)
			(xy 95.198482 -263.213238) (xy 95.148868 -263.193766) (xy 95.10271 -263.167117) (xy 95.061039 -263.133886)
			(xy 95.024787 -263.094815) (xy 94.994763 -263.050778) (xy 94.971637 -263.002757) (xy 94.955927 -262.951827)
			(xy 94.947984 -262.899123) (xy 94.719404 -262.899123) (xy 94.711461 -262.951827) (xy 94.695751 -263.002757)
			(xy 94.672625 -263.050778) (xy 94.642601 -263.094815) (xy 94.606349 -263.133886) (xy 94.564678 -263.167117)
			(xy 94.51852 -263.193766) (xy 94.468906 -263.213238) (xy 94.416944 -263.225098) (xy 94.363794 -263.229082)
			(xy 94.310644 -263.225098) (xy 94.258682 -263.213238) (xy 94.209068 -263.193766) (xy 94.16291 -263.167117)
			(xy 94.121239 -263.133886) (xy 94.084987 -263.094815) (xy 94.054963 -263.050778) (xy 94.031837 -263.002757)
			(xy 94.016127 -262.951827) (xy 94.008184 -262.899123) (xy 93.779604 -262.899123) (xy 93.771661 -262.951827)
			(xy 93.755951 -263.002757) (xy 93.732825 -263.050778) (xy 93.702801 -263.094815) (xy 93.666549 -263.133886)
			(xy 93.624878 -263.167117) (xy 93.57872 -263.193766) (xy 93.529106 -263.213238) (xy 93.477144 -263.225098)
			(xy 93.423994 -263.229082) (xy 93.370844 -263.225098) (xy 93.318882 -263.213238) (xy 93.269268 -263.193766)
			(xy 93.22311 -263.167117) (xy 93.181439 -263.133886) (xy 93.145187 -263.094815) (xy 93.115163 -263.050778)
			(xy 93.092037 -263.002757) (xy 93.076327 -262.951827) (xy 93.068384 -262.899123) (xy 92.839804 -262.899123)
			(xy 92.831861 -262.951827) (xy 92.816151 -263.002757) (xy 92.793025 -263.050778) (xy 92.763001 -263.094815)
			(xy 92.726749 -263.133886) (xy 92.685078 -263.167117) (xy 92.63892 -263.193766) (xy 92.589306 -263.213238)
			(xy 92.537344 -263.225098) (xy 92.484194 -263.229082) (xy 92.431044 -263.225098) (xy 92.379082 -263.213238)
			(xy 92.329468 -263.193766) (xy 92.28331 -263.167117) (xy 92.241639 -263.133886) (xy 92.205387 -263.094815)
			(xy 92.175363 -263.050778) (xy 92.152237 -263.002757) (xy 92.136527 -262.951827) (xy 92.128584 -262.899123)
			(xy 91.900004 -262.899123) (xy 91.892061 -262.951827) (xy 91.876351 -263.002757) (xy 91.853225 -263.050778)
			(xy 91.823201 -263.094815) (xy 91.786949 -263.133886) (xy 91.745278 -263.167117) (xy 91.69912 -263.193766)
			(xy 91.649506 -263.213238) (xy 91.597544 -263.225098) (xy 91.544394 -263.229082) (xy 91.491244 -263.225098)
			(xy 91.439282 -263.213238) (xy 91.389668 -263.193766) (xy 91.34351 -263.167117) (xy 91.301839 -263.133886)
			(xy 91.265587 -263.094815) (xy 91.235563 -263.050778) (xy 91.212437 -263.002757) (xy 91.196727 -262.951827)
			(xy 91.188784 -262.899123) (xy 90.960458 -262.899123) (xy 90.952515 -262.951827) (xy 90.936805 -263.002757)
			(xy 90.913679 -263.050778) (xy 90.883655 -263.094815) (xy 90.847403 -263.133886) (xy 90.805732 -263.167117)
			(xy 90.759574 -263.193766) (xy 90.70996 -263.213238) (xy 90.657998 -263.225098) (xy 90.604848 -263.229082)
			(xy 90.551698 -263.225098) (xy 90.499736 -263.213238) (xy 90.450122 -263.193766) (xy 90.403964 -263.167117)
			(xy 90.362293 -263.133886) (xy 90.326041 -263.094815) (xy 90.296017 -263.050778) (xy 90.272891 -263.002757)
			(xy 90.257181 -262.951827) (xy 90.249238 -262.899123) (xy 90.020404 -262.899123) (xy 90.012461 -262.951827)
			(xy 89.996751 -263.002757) (xy 89.973625 -263.050778) (xy 89.943601 -263.094815) (xy 89.907349 -263.133886)
			(xy 89.865678 -263.167117) (xy 89.81952 -263.193766) (xy 89.769906 -263.213238) (xy 89.717944 -263.225098)
			(xy 89.664794 -263.229082) (xy 89.611644 -263.225098) (xy 89.559682 -263.213238) (xy 89.510068 -263.193766)
			(xy 89.46391 -263.167117) (xy 89.422239 -263.133886) (xy 89.385987 -263.094815) (xy 89.355963 -263.050778)
			(xy 89.332837 -263.002757) (xy 89.317127 -262.951827) (xy 89.309184 -262.899123) (xy 89.080597 -262.899123)
			(xy 89.080597 -262.89986) (xy 89.072225 -262.953938) (xy 89.05568 -263.006099) (xy 89.031349 -263.055114)
			(xy 88.999806 -263.099831) (xy 88.961794 -263.139195) (xy 88.918207 -263.172281) (xy 88.870072 -263.19831)
			(xy 88.818521 -263.216668) (xy 88.764769 -263.226924) (xy 88.73744 -263.228328) (xy 88.727668 -263.229113)
			(xy 88.709774 -263.237079) (xy 88.696169 -263.251171) (xy 88.688838 -263.269334) (xy 88.688418 -263.279128)
			(xy 88.688418 -263.713193) (xy 88.839284 -263.713193) (xy 88.839284 -263.659895) (xy 88.847227 -263.607191)
			(xy 88.862937 -263.556261) (xy 88.886063 -263.50824) (xy 88.916087 -263.464203) (xy 88.952339 -263.425132)
			(xy 88.99401 -263.391901) (xy 89.040168 -263.365252) (xy 89.089782 -263.34578) (xy 89.141744 -263.33392)
			(xy 89.194894 -263.329937) (xy 89.248044 -263.33392) (xy 89.300006 -263.34578) (xy 89.34962 -263.365252)
			(xy 89.395778 -263.391901) (xy 89.437449 -263.425132) (xy 89.473701 -263.464203) (xy 89.503725 -263.50824)
			(xy 89.526851 -263.556261) (xy 89.542561 -263.607191) (xy 89.550504 -263.659895) (xy 89.551002 -263.686544)
			(xy 89.550504 -263.713193) (xy 89.779084 -263.713193) (xy 89.779084 -263.659895) (xy 89.787027 -263.607191)
			(xy 89.802737 -263.556261) (xy 89.825863 -263.50824) (xy 89.855887 -263.464203) (xy 89.892139 -263.425132)
			(xy 89.93381 -263.391901) (xy 89.979968 -263.365252) (xy 90.029582 -263.34578) (xy 90.081544 -263.33392)
			(xy 90.134694 -263.329937) (xy 90.187844 -263.33392) (xy 90.239806 -263.34578) (xy 90.28942 -263.365252)
			(xy 90.335578 -263.391901) (xy 90.377249 -263.425132) (xy 90.413501 -263.464203) (xy 90.443525 -263.50824)
			(xy 90.466651 -263.556261) (xy 90.482361 -263.607191) (xy 90.490304 -263.659895) (xy 90.490802 -263.686544)
			(xy 90.490304 -263.713193) (xy 90.719138 -263.713193) (xy 90.719138 -263.659895) (xy 90.727081 -263.607191)
			(xy 90.742791 -263.556261) (xy 90.765917 -263.50824) (xy 90.795941 -263.464203) (xy 90.832193 -263.425132)
			(xy 90.873864 -263.391901) (xy 90.920022 -263.365252) (xy 90.969636 -263.34578) (xy 91.021598 -263.33392)
			(xy 91.074748 -263.329937) (xy 91.127898 -263.33392) (xy 91.17986 -263.34578) (xy 91.229474 -263.365252)
			(xy 91.275632 -263.391901) (xy 91.317303 -263.425132) (xy 91.353555 -263.464203) (xy 91.383579 -263.50824)
			(xy 91.406705 -263.556261) (xy 91.422415 -263.607191) (xy 91.430358 -263.659895) (xy 91.430856 -263.686544)
			(xy 91.430358 -263.713193) (xy 91.658938 -263.713193) (xy 91.658938 -263.659895) (xy 91.666881 -263.607191)
			(xy 91.682591 -263.556261) (xy 91.705717 -263.50824) (xy 91.735741 -263.464203) (xy 91.771993 -263.425132)
			(xy 91.813664 -263.391901) (xy 91.859822 -263.365252) (xy 91.909436 -263.34578) (xy 91.961398 -263.33392)
			(xy 92.014548 -263.329937) (xy 92.067698 -263.33392) (xy 92.11966 -263.34578) (xy 92.169274 -263.365252)
			(xy 92.215432 -263.391901) (xy 92.257103 -263.425132) (xy 92.293355 -263.464203) (xy 92.323379 -263.50824)
			(xy 92.346505 -263.556261) (xy 92.362215 -263.607191) (xy 92.370158 -263.659895) (xy 92.370656 -263.686544)
			(xy 92.370158 -263.713193) (xy 92.598738 -263.713193) (xy 92.598738 -263.659895) (xy 92.606681 -263.607191)
			(xy 92.622391 -263.556261) (xy 92.645517 -263.50824) (xy 92.675541 -263.464203) (xy 92.711793 -263.425132)
			(xy 92.753464 -263.391901) (xy 92.799622 -263.365252) (xy 92.849236 -263.34578) (xy 92.901198 -263.33392)
			(xy 92.954348 -263.329937) (xy 93.007498 -263.33392) (xy 93.05946 -263.34578) (xy 93.109074 -263.365252)
			(xy 93.155232 -263.391901) (xy 93.196903 -263.425132) (xy 93.233155 -263.464203) (xy 93.263179 -263.50824)
			(xy 93.286305 -263.556261) (xy 93.302015 -263.607191) (xy 93.309958 -263.659895) (xy 93.310456 -263.686544)
			(xy 93.309958 -263.713193) (xy 93.538538 -263.713193) (xy 93.538538 -263.659895) (xy 93.546481 -263.607191)
			(xy 93.562191 -263.556261) (xy 93.585317 -263.50824) (xy 93.615341 -263.464203) (xy 93.651593 -263.425132)
			(xy 93.693264 -263.391901) (xy 93.739422 -263.365252) (xy 93.789036 -263.34578) (xy 93.840998 -263.33392)
			(xy 93.894148 -263.329937) (xy 93.947298 -263.33392) (xy 93.99926 -263.34578) (xy 94.048874 -263.365252)
			(xy 94.095032 -263.391901) (xy 94.136703 -263.425132) (xy 94.172955 -263.464203) (xy 94.202979 -263.50824)
			(xy 94.226105 -263.556261) (xy 94.241815 -263.607191) (xy 94.249758 -263.659895) (xy 94.250256 -263.686544)
			(xy 94.249758 -263.713193) (xy 94.478084 -263.713193) (xy 94.478084 -263.659895) (xy 94.486027 -263.607191)
			(xy 94.501737 -263.556261) (xy 94.524863 -263.50824) (xy 94.554887 -263.464203) (xy 94.591139 -263.425132)
			(xy 94.63281 -263.391901) (xy 94.678968 -263.365252) (xy 94.728582 -263.34578) (xy 94.780544 -263.33392)
			(xy 94.833694 -263.329937) (xy 94.886844 -263.33392) (xy 94.938806 -263.34578) (xy 94.98842 -263.365252)
			(xy 95.034578 -263.391901) (xy 95.076249 -263.425132) (xy 95.112501 -263.464203) (xy 95.142525 -263.50824)
			(xy 95.165651 -263.556261) (xy 95.181361 -263.607191) (xy 95.189304 -263.659895) (xy 95.189802 -263.686544)
			(xy 95.189304 -263.713193) (xy 95.418138 -263.713193) (xy 95.418138 -263.659895) (xy 95.426081 -263.607191)
			(xy 95.441791 -263.556261) (xy 95.464917 -263.50824) (xy 95.494941 -263.464203) (xy 95.531193 -263.425132)
			(xy 95.572864 -263.391901) (xy 95.619022 -263.365252) (xy 95.668636 -263.34578) (xy 95.720598 -263.33392)
			(xy 95.773748 -263.329937) (xy 95.826898 -263.33392) (xy 95.87886 -263.34578) (xy 95.928474 -263.365252)
			(xy 95.974632 -263.391901) (xy 96.016303 -263.425132) (xy 96.052555 -263.464203) (xy 96.082579 -263.50824)
			(xy 96.105705 -263.556261) (xy 96.121415 -263.607191) (xy 96.129358 -263.659895) (xy 96.129856 -263.686544)
			(xy 96.129358 -263.713193) (xy 96.357938 -263.713193) (xy 96.357938 -263.659895) (xy 96.365881 -263.607191)
			(xy 96.381591 -263.556261) (xy 96.404717 -263.50824) (xy 96.434741 -263.464203) (xy 96.470993 -263.425132)
			(xy 96.512664 -263.391901) (xy 96.558822 -263.365252) (xy 96.608436 -263.34578) (xy 96.660398 -263.33392)
			(xy 96.713548 -263.329937) (xy 96.766698 -263.33392) (xy 96.81866 -263.34578) (xy 96.868274 -263.365252)
			(xy 96.914432 -263.391901) (xy 96.956103 -263.425132) (xy 96.992355 -263.464203) (xy 97.022379 -263.50824)
			(xy 97.045505 -263.556261) (xy 97.061215 -263.607191) (xy 97.069158 -263.659895) (xy 97.069656 -263.686544)
			(xy 97.069158 -263.713193) (xy 97.297738 -263.713193) (xy 97.297738 -263.659895) (xy 97.305681 -263.607191)
			(xy 97.321391 -263.556261) (xy 97.344517 -263.50824) (xy 97.374541 -263.464203) (xy 97.410793 -263.425132)
			(xy 97.452464 -263.391901) (xy 97.498622 -263.365252) (xy 97.548236 -263.34578) (xy 97.600198 -263.33392)
			(xy 97.653348 -263.329937) (xy 97.706498 -263.33392) (xy 97.75846 -263.34578) (xy 97.808074 -263.365252)
			(xy 97.854232 -263.391901) (xy 97.895903 -263.425132) (xy 97.932155 -263.464203) (xy 97.962179 -263.50824)
			(xy 97.985305 -263.556261) (xy 98.001015 -263.607191) (xy 98.008958 -263.659895) (xy 98.009456 -263.686544)
			(xy 98.008958 -263.713193) (xy 98.237538 -263.713193) (xy 98.237538 -263.659895) (xy 98.245481 -263.607191)
			(xy 98.261191 -263.556261) (xy 98.284317 -263.50824) (xy 98.314341 -263.464203) (xy 98.350593 -263.425132)
			(xy 98.392264 -263.391901) (xy 98.438422 -263.365252) (xy 98.488036 -263.34578) (xy 98.539998 -263.33392)
			(xy 98.593148 -263.329937) (xy 98.646298 -263.33392) (xy 98.69826 -263.34578) (xy 98.747874 -263.365252)
			(xy 98.794032 -263.391901) (xy 98.835703 -263.425132) (xy 98.871955 -263.464203) (xy 98.901979 -263.50824)
			(xy 98.925105 -263.556261) (xy 98.940815 -263.607191) (xy 98.948758 -263.659895) (xy 98.949256 -263.686544)
			(xy 98.948758 -263.713193) (xy 99.177338 -263.713193) (xy 99.177338 -263.659895) (xy 99.185281 -263.607191)
			(xy 99.200991 -263.556261) (xy 99.224117 -263.50824) (xy 99.254141 -263.464203) (xy 99.290393 -263.425132)
			(xy 99.332064 -263.391901) (xy 99.378222 -263.365252) (xy 99.427836 -263.34578) (xy 99.479798 -263.33392)
			(xy 99.532948 -263.329937) (xy 99.586098 -263.33392) (xy 99.63806 -263.34578) (xy 99.687674 -263.365252)
			(xy 99.733832 -263.391901) (xy 99.775503 -263.425132) (xy 99.811755 -263.464203) (xy 99.841779 -263.50824)
			(xy 99.864905 -263.556261) (xy 99.880615 -263.607191) (xy 99.888558 -263.659895) (xy 99.889056 -263.686544)
			(xy 99.888558 -263.713193) (xy 100.117138 -263.713193) (xy 100.117138 -263.659895) (xy 100.125081 -263.607191)
			(xy 100.140791 -263.556261) (xy 100.163917 -263.50824) (xy 100.193941 -263.464203) (xy 100.230193 -263.425132)
			(xy 100.271864 -263.391901) (xy 100.318022 -263.365252) (xy 100.367636 -263.34578) (xy 100.419598 -263.33392)
			(xy 100.472748 -263.329937) (xy 100.525898 -263.33392) (xy 100.57786 -263.34578) (xy 100.627474 -263.365252)
			(xy 100.673632 -263.391901) (xy 100.715303 -263.425132) (xy 100.751555 -263.464203) (xy 100.781579 -263.50824)
			(xy 100.804705 -263.556261) (xy 100.820415 -263.607191) (xy 100.828358 -263.659895) (xy 100.828856 -263.686544)
			(xy 100.828358 -263.713193) (xy 101.056684 -263.713193) (xy 101.056684 -263.659895) (xy 101.064627 -263.607191)
			(xy 101.080337 -263.556261) (xy 101.103463 -263.50824) (xy 101.133487 -263.464203) (xy 101.169739 -263.425132)
			(xy 101.21141 -263.391901) (xy 101.257568 -263.365252) (xy 101.307182 -263.34578) (xy 101.359144 -263.33392)
			(xy 101.412294 -263.329937) (xy 101.465444 -263.33392) (xy 101.517406 -263.34578) (xy 101.56702 -263.365252)
			(xy 101.613178 -263.391901) (xy 101.654849 -263.425132) (xy 101.691101 -263.464203) (xy 101.721125 -263.50824)
			(xy 101.744251 -263.556261) (xy 101.759961 -263.607191) (xy 101.767904 -263.659895) (xy 101.768402 -263.686544)
			(xy 101.767904 -263.713193) (xy 101.759961 -263.765897) (xy 101.744251 -263.816827) (xy 101.721125 -263.864848)
			(xy 101.691101 -263.908885) (xy 101.654849 -263.947956) (xy 101.613178 -263.981187) (xy 101.56702 -264.007836)
			(xy 101.517406 -264.027308) (xy 101.465444 -264.039168) (xy 101.412294 -264.043152) (xy 101.359144 -264.039168)
			(xy 101.307182 -264.027308) (xy 101.257568 -264.007836) (xy 101.21141 -263.981187) (xy 101.169739 -263.947956)
			(xy 101.133487 -263.908885) (xy 101.103463 -263.864848) (xy 101.080337 -263.816827) (xy 101.064627 -263.765897)
			(xy 101.056684 -263.713193) (xy 100.828358 -263.713193) (xy 100.820415 -263.765897) (xy 100.804705 -263.816827)
			(xy 100.781579 -263.864848) (xy 100.751555 -263.908885) (xy 100.715303 -263.947956) (xy 100.673632 -263.981187)
			(xy 100.627474 -264.007836) (xy 100.57786 -264.027308) (xy 100.525898 -264.039168) (xy 100.472748 -264.043152)
			(xy 100.419598 -264.039168) (xy 100.367636 -264.027308) (xy 100.318022 -264.007836) (xy 100.271864 -263.981187)
			(xy 100.230193 -263.947956) (xy 100.193941 -263.908885) (xy 100.163917 -263.864848) (xy 100.140791 -263.816827)
			(xy 100.125081 -263.765897) (xy 100.117138 -263.713193) (xy 99.888558 -263.713193) (xy 99.880615 -263.765897)
			(xy 99.864905 -263.816827) (xy 99.841779 -263.864848) (xy 99.811755 -263.908885) (xy 99.775503 -263.947956)
			(xy 99.733832 -263.981187) (xy 99.687674 -264.007836) (xy 99.63806 -264.027308) (xy 99.586098 -264.039168)
			(xy 99.532948 -264.043152) (xy 99.479798 -264.039168) (xy 99.427836 -264.027308) (xy 99.378222 -264.007836)
			(xy 99.332064 -263.981187) (xy 99.290393 -263.947956) (xy 99.254141 -263.908885) (xy 99.224117 -263.864848)
			(xy 99.200991 -263.816827) (xy 99.185281 -263.765897) (xy 99.177338 -263.713193) (xy 98.948758 -263.713193)
			(xy 98.940815 -263.765897) (xy 98.925105 -263.816827) (xy 98.901979 -263.864848) (xy 98.871955 -263.908885)
			(xy 98.835703 -263.947956) (xy 98.794032 -263.981187) (xy 98.747874 -264.007836) (xy 98.69826 -264.027308)
			(xy 98.646298 -264.039168) (xy 98.593148 -264.043152) (xy 98.539998 -264.039168) (xy 98.488036 -264.027308)
			(xy 98.438422 -264.007836) (xy 98.392264 -263.981187) (xy 98.350593 -263.947956) (xy 98.314341 -263.908885)
			(xy 98.284317 -263.864848) (xy 98.261191 -263.816827) (xy 98.245481 -263.765897) (xy 98.237538 -263.713193)
			(xy 98.008958 -263.713193) (xy 98.001015 -263.765897) (xy 97.985305 -263.816827) (xy 97.962179 -263.864848)
			(xy 97.932155 -263.908885) (xy 97.895903 -263.947956) (xy 97.854232 -263.981187) (xy 97.808074 -264.007836)
			(xy 97.75846 -264.027308) (xy 97.706498 -264.039168) (xy 97.653348 -264.043152) (xy 97.600198 -264.039168)
			(xy 97.548236 -264.027308) (xy 97.498622 -264.007836) (xy 97.452464 -263.981187) (xy 97.410793 -263.947956)
			(xy 97.374541 -263.908885) (xy 97.344517 -263.864848) (xy 97.321391 -263.816827) (xy 97.305681 -263.765897)
			(xy 97.297738 -263.713193) (xy 97.069158 -263.713193) (xy 97.061215 -263.765897) (xy 97.045505 -263.816827)
			(xy 97.022379 -263.864848) (xy 96.992355 -263.908885) (xy 96.956103 -263.947956) (xy 96.914432 -263.981187)
			(xy 96.868274 -264.007836) (xy 96.81866 -264.027308) (xy 96.766698 -264.039168) (xy 96.713548 -264.043152)
			(xy 96.660398 -264.039168) (xy 96.608436 -264.027308) (xy 96.558822 -264.007836) (xy 96.512664 -263.981187)
			(xy 96.470993 -263.947956) (xy 96.434741 -263.908885) (xy 96.404717 -263.864848) (xy 96.381591 -263.816827)
			(xy 96.365881 -263.765897) (xy 96.357938 -263.713193) (xy 96.129358 -263.713193) (xy 96.121415 -263.765897)
			(xy 96.105705 -263.816827) (xy 96.082579 -263.864848) (xy 96.052555 -263.908885) (xy 96.016303 -263.947956)
			(xy 95.974632 -263.981187) (xy 95.928474 -264.007836) (xy 95.87886 -264.027308) (xy 95.826898 -264.039168)
			(xy 95.773748 -264.043152) (xy 95.720598 -264.039168) (xy 95.668636 -264.027308) (xy 95.619022 -264.007836)
			(xy 95.572864 -263.981187) (xy 95.531193 -263.947956) (xy 95.494941 -263.908885) (xy 95.464917 -263.864848)
			(xy 95.441791 -263.816827) (xy 95.426081 -263.765897) (xy 95.418138 -263.713193) (xy 95.189304 -263.713193)
			(xy 95.181361 -263.765897) (xy 95.165651 -263.816827) (xy 95.142525 -263.864848) (xy 95.112501 -263.908885)
			(xy 95.076249 -263.947956) (xy 95.034578 -263.981187) (xy 94.98842 -264.007836) (xy 94.938806 -264.027308)
			(xy 94.886844 -264.039168) (xy 94.833694 -264.043152) (xy 94.780544 -264.039168) (xy 94.728582 -264.027308)
			(xy 94.678968 -264.007836) (xy 94.63281 -263.981187) (xy 94.591139 -263.947956) (xy 94.554887 -263.908885)
			(xy 94.524863 -263.864848) (xy 94.501737 -263.816827) (xy 94.486027 -263.765897) (xy 94.478084 -263.713193)
			(xy 94.249758 -263.713193) (xy 94.241815 -263.765897) (xy 94.226105 -263.816827) (xy 94.202979 -263.864848)
			(xy 94.172955 -263.908885) (xy 94.136703 -263.947956) (xy 94.095032 -263.981187) (xy 94.048874 -264.007836)
			(xy 93.99926 -264.027308) (xy 93.947298 -264.039168) (xy 93.894148 -264.043152) (xy 93.840998 -264.039168)
			(xy 93.789036 -264.027308) (xy 93.739422 -264.007836) (xy 93.693264 -263.981187) (xy 93.651593 -263.947956)
			(xy 93.615341 -263.908885) (xy 93.585317 -263.864848) (xy 93.562191 -263.816827) (xy 93.546481 -263.765897)
			(xy 93.538538 -263.713193) (xy 93.309958 -263.713193) (xy 93.302015 -263.765897) (xy 93.286305 -263.816827)
			(xy 93.263179 -263.864848) (xy 93.233155 -263.908885) (xy 93.196903 -263.947956) (xy 93.155232 -263.981187)
			(xy 93.109074 -264.007836) (xy 93.05946 -264.027308) (xy 93.007498 -264.039168) (xy 92.954348 -264.043152)
			(xy 92.901198 -264.039168) (xy 92.849236 -264.027308) (xy 92.799622 -264.007836) (xy 92.753464 -263.981187)
			(xy 92.711793 -263.947956) (xy 92.675541 -263.908885) (xy 92.645517 -263.864848) (xy 92.622391 -263.816827)
			(xy 92.606681 -263.765897) (xy 92.598738 -263.713193) (xy 92.370158 -263.713193) (xy 92.362215 -263.765897)
			(xy 92.346505 -263.816827) (xy 92.323379 -263.864848) (xy 92.293355 -263.908885) (xy 92.257103 -263.947956)
			(xy 92.215432 -263.981187) (xy 92.169274 -264.007836) (xy 92.11966 -264.027308) (xy 92.067698 -264.039168)
			(xy 92.014548 -264.043152) (xy 91.961398 -264.039168) (xy 91.909436 -264.027308) (xy 91.859822 -264.007836)
			(xy 91.813664 -263.981187) (xy 91.771993 -263.947956) (xy 91.735741 -263.908885) (xy 91.705717 -263.864848)
			(xy 91.682591 -263.816827) (xy 91.666881 -263.765897) (xy 91.658938 -263.713193) (xy 91.430358 -263.713193)
			(xy 91.422415 -263.765897) (xy 91.406705 -263.816827) (xy 91.383579 -263.864848) (xy 91.353555 -263.908885)
			(xy 91.317303 -263.947956) (xy 91.275632 -263.981187) (xy 91.229474 -264.007836) (xy 91.17986 -264.027308)
			(xy 91.127898 -264.039168) (xy 91.074748 -264.043152) (xy 91.021598 -264.039168) (xy 90.969636 -264.027308)
			(xy 90.920022 -264.007836) (xy 90.873864 -263.981187) (xy 90.832193 -263.947956) (xy 90.795941 -263.908885)
			(xy 90.765917 -263.864848) (xy 90.742791 -263.816827) (xy 90.727081 -263.765897) (xy 90.719138 -263.713193)
			(xy 90.490304 -263.713193) (xy 90.482361 -263.765897) (xy 90.466651 -263.816827) (xy 90.443525 -263.864848)
			(xy 90.413501 -263.908885) (xy 90.377249 -263.947956) (xy 90.335578 -263.981187) (xy 90.28942 -264.007836)
			(xy 90.239806 -264.027308) (xy 90.187844 -264.039168) (xy 90.134694 -264.043152) (xy 90.081544 -264.039168)
			(xy 90.029582 -264.027308) (xy 89.979968 -264.007836) (xy 89.93381 -263.981187) (xy 89.892139 -263.947956)
			(xy 89.855887 -263.908885) (xy 89.825863 -263.864848) (xy 89.802737 -263.816827) (xy 89.787027 -263.765897)
			(xy 89.779084 -263.713193) (xy 89.550504 -263.713193) (xy 89.542561 -263.765897) (xy 89.526851 -263.816827)
			(xy 89.503725 -263.864848) (xy 89.473701 -263.908885) (xy 89.437449 -263.947956) (xy 89.395778 -263.981187)
			(xy 89.34962 -264.007836) (xy 89.300006 -264.027308) (xy 89.248044 -264.039168) (xy 89.194894 -264.043152)
			(xy 89.141744 -264.039168) (xy 89.089782 -264.027308) (xy 89.040168 -264.007836) (xy 88.99401 -263.981187)
			(xy 88.952339 -263.947956) (xy 88.916087 -263.908885) (xy 88.886063 -263.864848) (xy 88.862937 -263.816827)
			(xy 88.847227 -263.765897) (xy 88.839284 -263.713193) (xy 88.688418 -263.713193) (xy 88.688418 -264.093706)
			(xy 88.688862 -264.103498) (xy 88.696193 -264.12166) (xy 88.709787 -264.135759) (xy 88.727669 -264.143747)
			(xy 88.73744 -264.144506) (xy 88.764768 -264.145962) (xy 88.818522 -264.156218) (xy 88.870075 -264.174577)
			(xy 88.918213 -264.200606) (xy 88.961802 -264.233693) (xy 88.999816 -264.273059) (xy 89.03136 -264.317777)
			(xy 89.055692 -264.366794) (xy 89.072239 -264.418957) (xy 89.080611 -264.473037) (xy 89.080611 -264.527009)
			(xy 89.309184 -264.527009) (xy 89.309184 -264.473711) (xy 89.317127 -264.421007) (xy 89.332837 -264.370077)
			(xy 89.355963 -264.322056) (xy 89.385987 -264.278019) (xy 89.422239 -264.238948) (xy 89.46391 -264.205717)
			(xy 89.510068 -264.179068) (xy 89.559682 -264.159596) (xy 89.611644 -264.147736) (xy 89.664794 -264.143753)
			(xy 89.717944 -264.147736) (xy 89.769906 -264.159596) (xy 89.81952 -264.179068) (xy 89.865678 -264.205717)
			(xy 89.907349 -264.238948) (xy 89.943601 -264.278019) (xy 89.973625 -264.322056) (xy 89.996751 -264.370077)
			(xy 90.012461 -264.421007) (xy 90.020404 -264.473711) (xy 90.020902 -264.50036) (xy 90.020404 -264.527009)
			(xy 90.248984 -264.527009) (xy 90.248984 -264.473711) (xy 90.256927 -264.421007) (xy 90.272637 -264.370077)
			(xy 90.295763 -264.322056) (xy 90.325787 -264.278019) (xy 90.362039 -264.238948) (xy 90.40371 -264.205717)
			(xy 90.449868 -264.179068) (xy 90.499482 -264.159596) (xy 90.551444 -264.147736) (xy 90.604594 -264.143753)
			(xy 90.657744 -264.147736) (xy 90.709706 -264.159596) (xy 90.75932 -264.179068) (xy 90.805478 -264.205717)
			(xy 90.847149 -264.238948) (xy 90.883401 -264.278019) (xy 90.913425 -264.322056) (xy 90.936551 -264.370077)
			(xy 90.952261 -264.421007) (xy 90.960204 -264.473711) (xy 90.960702 -264.50036) (xy 90.960204 -264.527009)
			(xy 91.189038 -264.527009) (xy 91.189038 -264.473711) (xy 91.196981 -264.421007) (xy 91.212691 -264.370077)
			(xy 91.235817 -264.322056) (xy 91.265841 -264.278019) (xy 91.302093 -264.238948) (xy 91.343764 -264.205717)
			(xy 91.389922 -264.179068) (xy 91.439536 -264.159596) (xy 91.491498 -264.147736) (xy 91.544648 -264.143753)
			(xy 91.597798 -264.147736) (xy 91.64976 -264.159596) (xy 91.699374 -264.179068) (xy 91.745532 -264.205717)
			(xy 91.787203 -264.238948) (xy 91.823455 -264.278019) (xy 91.853479 -264.322056) (xy 91.876605 -264.370077)
			(xy 91.892315 -264.421007) (xy 91.900258 -264.473711) (xy 91.900756 -264.50036) (xy 91.900258 -264.527009)
			(xy 92.128584 -264.527009) (xy 92.128584 -264.473711) (xy 92.136527 -264.421007) (xy 92.152237 -264.370077)
			(xy 92.175363 -264.322056) (xy 92.205387 -264.278019) (xy 92.241639 -264.238948) (xy 92.28331 -264.205717)
			(xy 92.329468 -264.179068) (xy 92.379082 -264.159596) (xy 92.431044 -264.147736) (xy 92.484194 -264.143753)
			(xy 92.537344 -264.147736) (xy 92.589306 -264.159596) (xy 92.63892 -264.179068) (xy 92.685078 -264.205717)
			(xy 92.726749 -264.238948) (xy 92.763001 -264.278019) (xy 92.793025 -264.322056) (xy 92.816151 -264.370077)
			(xy 92.831861 -264.421007) (xy 92.839804 -264.473711) (xy 92.840302 -264.50036) (xy 92.839804 -264.527009)
			(xy 93.068384 -264.527009) (xy 93.068384 -264.473711) (xy 93.076327 -264.421007) (xy 93.092037 -264.370077)
			(xy 93.115163 -264.322056) (xy 93.145187 -264.278019) (xy 93.181439 -264.238948) (xy 93.22311 -264.205717)
			(xy 93.269268 -264.179068) (xy 93.318882 -264.159596) (xy 93.370844 -264.147736) (xy 93.423994 -264.143753)
			(xy 93.477144 -264.147736) (xy 93.529106 -264.159596) (xy 93.57872 -264.179068) (xy 93.624878 -264.205717)
			(xy 93.666549 -264.238948) (xy 93.702801 -264.278019) (xy 93.732825 -264.322056) (xy 93.755951 -264.370077)
			(xy 93.771661 -264.421007) (xy 93.779604 -264.473711) (xy 93.780102 -264.50036) (xy 93.779604 -264.527009)
			(xy 94.008184 -264.527009) (xy 94.008184 -264.473711) (xy 94.016127 -264.421007) (xy 94.031837 -264.370077)
			(xy 94.054963 -264.322056) (xy 94.084987 -264.278019) (xy 94.121239 -264.238948) (xy 94.16291 -264.205717)
			(xy 94.209068 -264.179068) (xy 94.258682 -264.159596) (xy 94.310644 -264.147736) (xy 94.363794 -264.143753)
			(xy 94.416944 -264.147736) (xy 94.468906 -264.159596) (xy 94.51852 -264.179068) (xy 94.564678 -264.205717)
			(xy 94.606349 -264.238948) (xy 94.642601 -264.278019) (xy 94.672625 -264.322056) (xy 94.695751 -264.370077)
			(xy 94.711461 -264.421007) (xy 94.719404 -264.473711) (xy 94.719902 -264.50036) (xy 94.719404 -264.527009)
			(xy 94.947984 -264.527009) (xy 94.947984 -264.473711) (xy 94.955927 -264.421007) (xy 94.971637 -264.370077)
			(xy 94.994763 -264.322056) (xy 95.024787 -264.278019) (xy 95.061039 -264.238948) (xy 95.10271 -264.205717)
			(xy 95.148868 -264.179068) (xy 95.198482 -264.159596) (xy 95.250444 -264.147736) (xy 95.303594 -264.143753)
			(xy 95.356744 -264.147736) (xy 95.408706 -264.159596) (xy 95.45832 -264.179068) (xy 95.504478 -264.205717)
			(xy 95.546149 -264.238948) (xy 95.582401 -264.278019) (xy 95.612425 -264.322056) (xy 95.635551 -264.370077)
			(xy 95.651261 -264.421007) (xy 95.659204 -264.473711) (xy 95.659702 -264.50036) (xy 95.659204 -264.527009)
			(xy 95.887784 -264.527009) (xy 95.887784 -264.473711) (xy 95.895727 -264.421007) (xy 95.911437 -264.370077)
			(xy 95.934563 -264.322056) (xy 95.964587 -264.278019) (xy 96.000839 -264.238948) (xy 96.04251 -264.205717)
			(xy 96.088668 -264.179068) (xy 96.138282 -264.159596) (xy 96.190244 -264.147736) (xy 96.243394 -264.143753)
			(xy 96.296544 -264.147736) (xy 96.348506 -264.159596) (xy 96.39812 -264.179068) (xy 96.444278 -264.205717)
			(xy 96.485949 -264.238948) (xy 96.522201 -264.278019) (xy 96.552225 -264.322056) (xy 96.575351 -264.370077)
			(xy 96.591061 -264.421007) (xy 96.599004 -264.473711) (xy 96.599502 -264.50036) (xy 96.599004 -264.527009)
			(xy 96.827584 -264.527009) (xy 96.827584 -264.473711) (xy 96.835527 -264.421007) (xy 96.851237 -264.370077)
			(xy 96.874363 -264.322056) (xy 96.904387 -264.278019) (xy 96.940639 -264.238948) (xy 96.98231 -264.205717)
			(xy 97.028468 -264.179068) (xy 97.078082 -264.159596) (xy 97.130044 -264.147736) (xy 97.183194 -264.143753)
			(xy 97.236344 -264.147736) (xy 97.288306 -264.159596) (xy 97.33792 -264.179068) (xy 97.384078 -264.205717)
			(xy 97.425749 -264.238948) (xy 97.462001 -264.278019) (xy 97.492025 -264.322056) (xy 97.515151 -264.370077)
			(xy 97.530861 -264.421007) (xy 97.538804 -264.473711) (xy 97.539302 -264.50036) (xy 97.538804 -264.527009)
			(xy 97.767638 -264.527009) (xy 97.767638 -264.473711) (xy 97.775581 -264.421007) (xy 97.791291 -264.370077)
			(xy 97.814417 -264.322056) (xy 97.844441 -264.278019) (xy 97.880693 -264.238948) (xy 97.922364 -264.205717)
			(xy 97.968522 -264.179068) (xy 98.018136 -264.159596) (xy 98.070098 -264.147736) (xy 98.123248 -264.143753)
			(xy 98.176398 -264.147736) (xy 98.22836 -264.159596) (xy 98.277974 -264.179068) (xy 98.324132 -264.205717)
			(xy 98.365803 -264.238948) (xy 98.402055 -264.278019) (xy 98.432079 -264.322056) (xy 98.455205 -264.370077)
			(xy 98.470915 -264.421007) (xy 98.478858 -264.473711) (xy 98.479356 -264.50036) (xy 98.478858 -264.527009)
			(xy 98.707184 -264.527009) (xy 98.707184 -264.473711) (xy 98.715127 -264.421007) (xy 98.730837 -264.370077)
			(xy 98.753963 -264.322056) (xy 98.783987 -264.278019) (xy 98.820239 -264.238948) (xy 98.86191 -264.205717)
			(xy 98.908068 -264.179068) (xy 98.957682 -264.159596) (xy 99.009644 -264.147736) (xy 99.062794 -264.143753)
			(xy 99.115944 -264.147736) (xy 99.167906 -264.159596) (xy 99.21752 -264.179068) (xy 99.263678 -264.205717)
			(xy 99.305349 -264.238948) (xy 99.341601 -264.278019) (xy 99.371625 -264.322056) (xy 99.394751 -264.370077)
			(xy 99.410461 -264.421007) (xy 99.418404 -264.473711) (xy 99.418902 -264.50036) (xy 99.418404 -264.527009)
			(xy 99.646984 -264.527009) (xy 99.646984 -264.473711) (xy 99.654927 -264.421007) (xy 99.670637 -264.370077)
			(xy 99.693763 -264.322056) (xy 99.723787 -264.278019) (xy 99.760039 -264.238948) (xy 99.80171 -264.205717)
			(xy 99.847868 -264.179068) (xy 99.897482 -264.159596) (xy 99.949444 -264.147736) (xy 100.002594 -264.143753)
			(xy 100.055744 -264.147736) (xy 100.107706 -264.159596) (xy 100.15732 -264.179068) (xy 100.203478 -264.205717)
			(xy 100.245149 -264.238948) (xy 100.281401 -264.278019) (xy 100.311425 -264.322056) (xy 100.334551 -264.370077)
			(xy 100.350261 -264.421007) (xy 100.358204 -264.473711) (xy 100.358702 -264.50036) (xy 100.358204 -264.527009)
			(xy 100.586784 -264.527009) (xy 100.586784 -264.473711) (xy 100.594727 -264.421007) (xy 100.610437 -264.370077)
			(xy 100.633563 -264.322056) (xy 100.663587 -264.278019) (xy 100.699839 -264.238948) (xy 100.74151 -264.205717)
			(xy 100.787668 -264.179068) (xy 100.837282 -264.159596) (xy 100.889244 -264.147736) (xy 100.942394 -264.143753)
			(xy 100.995544 -264.147736) (xy 101.047506 -264.159596) (xy 101.09712 -264.179068) (xy 101.143278 -264.205717)
			(xy 101.184949 -264.238948) (xy 101.221201 -264.278019) (xy 101.251225 -264.322056) (xy 101.274351 -264.370077)
			(xy 101.290061 -264.421007) (xy 101.298004 -264.473711) (xy 101.298502 -264.50036) (xy 101.298004 -264.527009)
			(xy 101.526584 -264.527009) (xy 101.526584 -264.473711) (xy 101.534527 -264.421007) (xy 101.550237 -264.370077)
			(xy 101.573363 -264.322056) (xy 101.603387 -264.278019) (xy 101.639639 -264.238948) (xy 101.68131 -264.205717)
			(xy 101.727468 -264.179068) (xy 101.777082 -264.159596) (xy 101.829044 -264.147736) (xy 101.882194 -264.143753)
			(xy 101.935344 -264.147736) (xy 101.987306 -264.159596) (xy 102.03692 -264.179068) (xy 102.083078 -264.205717)
			(xy 102.124749 -264.238948) (xy 102.161001 -264.278019) (xy 102.191025 -264.322056) (xy 102.214151 -264.370077)
			(xy 102.229861 -264.421007) (xy 102.237804 -264.473711) (xy 102.238302 -264.50036) (xy 102.237804 -264.527009)
			(xy 102.229861 -264.579713) (xy 102.214151 -264.630643) (xy 102.191025 -264.678664) (xy 102.161001 -264.722701)
			(xy 102.124749 -264.761772) (xy 102.083078 -264.795003) (xy 102.03692 -264.821652) (xy 101.987306 -264.841124)
			(xy 101.935344 -264.852984) (xy 101.882194 -264.856968) (xy 101.829044 -264.852984) (xy 101.777082 -264.841124)
			(xy 101.727468 -264.821652) (xy 101.68131 -264.795003) (xy 101.639639 -264.761772) (xy 101.603387 -264.722701)
			(xy 101.573363 -264.678664) (xy 101.550237 -264.630643) (xy 101.534527 -264.579713) (xy 101.526584 -264.527009)
			(xy 101.298004 -264.527009) (xy 101.290061 -264.579713) (xy 101.274351 -264.630643) (xy 101.251225 -264.678664)
			(xy 101.221201 -264.722701) (xy 101.184949 -264.761772) (xy 101.143278 -264.795003) (xy 101.09712 -264.821652)
			(xy 101.047506 -264.841124) (xy 100.995544 -264.852984) (xy 100.942394 -264.856968) (xy 100.889244 -264.852984)
			(xy 100.837282 -264.841124) (xy 100.787668 -264.821652) (xy 100.74151 -264.795003) (xy 100.699839 -264.761772)
			(xy 100.663587 -264.722701) (xy 100.633563 -264.678664) (xy 100.610437 -264.630643) (xy 100.594727 -264.579713)
			(xy 100.586784 -264.527009) (xy 100.358204 -264.527009) (xy 100.350261 -264.579713) (xy 100.334551 -264.630643)
			(xy 100.311425 -264.678664) (xy 100.281401 -264.722701) (xy 100.245149 -264.761772) (xy 100.203478 -264.795003)
			(xy 100.15732 -264.821652) (xy 100.107706 -264.841124) (xy 100.055744 -264.852984) (xy 100.002594 -264.856968)
			(xy 99.949444 -264.852984) (xy 99.897482 -264.841124) (xy 99.847868 -264.821652) (xy 99.80171 -264.795003)
			(xy 99.760039 -264.761772) (xy 99.723787 -264.722701) (xy 99.693763 -264.678664) (xy 99.670637 -264.630643)
			(xy 99.654927 -264.579713) (xy 99.646984 -264.527009) (xy 99.418404 -264.527009) (xy 99.410461 -264.579713)
			(xy 99.394751 -264.630643) (xy 99.371625 -264.678664) (xy 99.341601 -264.722701) (xy 99.305349 -264.761772)
			(xy 99.263678 -264.795003) (xy 99.21752 -264.821652) (xy 99.167906 -264.841124) (xy 99.115944 -264.852984)
			(xy 99.062794 -264.856968) (xy 99.009644 -264.852984) (xy 98.957682 -264.841124) (xy 98.908068 -264.821652)
			(xy 98.86191 -264.795003) (xy 98.820239 -264.761772) (xy 98.783987 -264.722701) (xy 98.753963 -264.678664)
			(xy 98.730837 -264.630643) (xy 98.715127 -264.579713) (xy 98.707184 -264.527009) (xy 98.478858 -264.527009)
			(xy 98.470915 -264.579713) (xy 98.455205 -264.630643) (xy 98.432079 -264.678664) (xy 98.402055 -264.722701)
			(xy 98.365803 -264.761772) (xy 98.324132 -264.795003) (xy 98.277974 -264.821652) (xy 98.22836 -264.841124)
			(xy 98.176398 -264.852984) (xy 98.123248 -264.856968) (xy 98.070098 -264.852984) (xy 98.018136 -264.841124)
			(xy 97.968522 -264.821652) (xy 97.922364 -264.795003) (xy 97.880693 -264.761772) (xy 97.844441 -264.722701)
			(xy 97.814417 -264.678664) (xy 97.791291 -264.630643) (xy 97.775581 -264.579713) (xy 97.767638 -264.527009)
			(xy 97.538804 -264.527009) (xy 97.530861 -264.579713) (xy 97.515151 -264.630643) (xy 97.492025 -264.678664)
			(xy 97.462001 -264.722701) (xy 97.425749 -264.761772) (xy 97.384078 -264.795003) (xy 97.33792 -264.821652)
			(xy 97.288306 -264.841124) (xy 97.236344 -264.852984) (xy 97.183194 -264.856968) (xy 97.130044 -264.852984)
			(xy 97.078082 -264.841124) (xy 97.028468 -264.821652) (xy 96.98231 -264.795003) (xy 96.940639 -264.761772)
			(xy 96.904387 -264.722701) (xy 96.874363 -264.678664) (xy 96.851237 -264.630643) (xy 96.835527 -264.579713)
			(xy 96.827584 -264.527009) (xy 96.599004 -264.527009) (xy 96.591061 -264.579713) (xy 96.575351 -264.630643)
			(xy 96.552225 -264.678664) (xy 96.522201 -264.722701) (xy 96.485949 -264.761772) (xy 96.444278 -264.795003)
			(xy 96.39812 -264.821652) (xy 96.348506 -264.841124) (xy 96.296544 -264.852984) (xy 96.243394 -264.856968)
			(xy 96.190244 -264.852984) (xy 96.138282 -264.841124) (xy 96.088668 -264.821652) (xy 96.04251 -264.795003)
			(xy 96.000839 -264.761772) (xy 95.964587 -264.722701) (xy 95.934563 -264.678664) (xy 95.911437 -264.630643)
			(xy 95.895727 -264.579713) (xy 95.887784 -264.527009) (xy 95.659204 -264.527009) (xy 95.651261 -264.579713)
			(xy 95.635551 -264.630643) (xy 95.612425 -264.678664) (xy 95.582401 -264.722701) (xy 95.546149 -264.761772)
			(xy 95.504478 -264.795003) (xy 95.45832 -264.821652) (xy 95.408706 -264.841124) (xy 95.356744 -264.852984)
			(xy 95.303594 -264.856968) (xy 95.250444 -264.852984) (xy 95.198482 -264.841124) (xy 95.148868 -264.821652)
			(xy 95.10271 -264.795003) (xy 95.061039 -264.761772) (xy 95.024787 -264.722701) (xy 94.994763 -264.678664)
			(xy 94.971637 -264.630643) (xy 94.955927 -264.579713) (xy 94.947984 -264.527009) (xy 94.719404 -264.527009)
			(xy 94.711461 -264.579713) (xy 94.695751 -264.630643) (xy 94.672625 -264.678664) (xy 94.642601 -264.722701)
			(xy 94.606349 -264.761772) (xy 94.564678 -264.795003) (xy 94.51852 -264.821652) (xy 94.468906 -264.841124)
			(xy 94.416944 -264.852984) (xy 94.363794 -264.856968) (xy 94.310644 -264.852984) (xy 94.258682 -264.841124)
			(xy 94.209068 -264.821652) (xy 94.16291 -264.795003) (xy 94.121239 -264.761772) (xy 94.084987 -264.722701)
			(xy 94.054963 -264.678664) (xy 94.031837 -264.630643) (xy 94.016127 -264.579713) (xy 94.008184 -264.527009)
			(xy 93.779604 -264.527009) (xy 93.771661 -264.579713) (xy 93.755951 -264.630643) (xy 93.732825 -264.678664)
			(xy 93.702801 -264.722701) (xy 93.666549 -264.761772) (xy 93.624878 -264.795003) (xy 93.57872 -264.821652)
			(xy 93.529106 -264.841124) (xy 93.477144 -264.852984) (xy 93.423994 -264.856968) (xy 93.370844 -264.852984)
			(xy 93.318882 -264.841124) (xy 93.269268 -264.821652) (xy 93.22311 -264.795003) (xy 93.181439 -264.761772)
			(xy 93.145187 -264.722701) (xy 93.115163 -264.678664) (xy 93.092037 -264.630643) (xy 93.076327 -264.579713)
			(xy 93.068384 -264.527009) (xy 92.839804 -264.527009) (xy 92.831861 -264.579713) (xy 92.816151 -264.630643)
			(xy 92.793025 -264.678664) (xy 92.763001 -264.722701) (xy 92.726749 -264.761772) (xy 92.685078 -264.795003)
			(xy 92.63892 -264.821652) (xy 92.589306 -264.841124) (xy 92.537344 -264.852984) (xy 92.484194 -264.856968)
			(xy 92.431044 -264.852984) (xy 92.379082 -264.841124) (xy 92.329468 -264.821652) (xy 92.28331 -264.795003)
			(xy 92.241639 -264.761772) (xy 92.205387 -264.722701) (xy 92.175363 -264.678664) (xy 92.152237 -264.630643)
			(xy 92.136527 -264.579713) (xy 92.128584 -264.527009) (xy 91.900258 -264.527009) (xy 91.892315 -264.579713)
			(xy 91.876605 -264.630643) (xy 91.853479 -264.678664) (xy 91.823455 -264.722701) (xy 91.787203 -264.761772)
			(xy 91.745532 -264.795003) (xy 91.699374 -264.821652) (xy 91.64976 -264.841124) (xy 91.597798 -264.852984)
			(xy 91.544648 -264.856968) (xy 91.491498 -264.852984) (xy 91.439536 -264.841124) (xy 91.389922 -264.821652)
			(xy 91.343764 -264.795003) (xy 91.302093 -264.761772) (xy 91.265841 -264.722701) (xy 91.235817 -264.678664)
			(xy 91.212691 -264.630643) (xy 91.196981 -264.579713) (xy 91.189038 -264.527009) (xy 90.960204 -264.527009)
			(xy 90.952261 -264.579713) (xy 90.936551 -264.630643) (xy 90.913425 -264.678664) (xy 90.883401 -264.722701)
			(xy 90.847149 -264.761772) (xy 90.805478 -264.795003) (xy 90.75932 -264.821652) (xy 90.709706 -264.841124)
			(xy 90.657744 -264.852984) (xy 90.604594 -264.856968) (xy 90.551444 -264.852984) (xy 90.499482 -264.841124)
			(xy 90.449868 -264.821652) (xy 90.40371 -264.795003) (xy 90.362039 -264.761772) (xy 90.325787 -264.722701)
			(xy 90.295763 -264.678664) (xy 90.272637 -264.630643) (xy 90.256927 -264.579713) (xy 90.248984 -264.527009)
			(xy 90.020404 -264.527009) (xy 90.012461 -264.579713) (xy 89.996751 -264.630643) (xy 89.973625 -264.678664)
			(xy 89.943601 -264.722701) (xy 89.907349 -264.761772) (xy 89.865678 -264.795003) (xy 89.81952 -264.821652)
			(xy 89.769906 -264.841124) (xy 89.717944 -264.852984) (xy 89.664794 -264.856968) (xy 89.611644 -264.852984)
			(xy 89.559682 -264.841124) (xy 89.510068 -264.821652) (xy 89.46391 -264.795003) (xy 89.422239 -264.761772)
			(xy 89.385987 -264.722701) (xy 89.355963 -264.678664) (xy 89.332837 -264.630643) (xy 89.317127 -264.579713)
			(xy 89.309184 -264.527009) (xy 89.080611 -264.527009) (xy 89.080611 -264.527761) (xy 89.072239 -264.581841)
			(xy 89.055693 -264.634003) (xy 89.031361 -264.683021) (xy 88.999817 -264.727739) (xy 88.961804 -264.767105)
			(xy 88.918215 -264.800193) (xy 88.870078 -264.826222) (xy 88.818525 -264.844581) (xy 88.764771 -264.854838)
			(xy 88.73744 -264.856214) (xy 88.727667 -264.856998) (xy 88.70977 -264.864964) (xy 88.696162 -264.879055)
			(xy 88.688826 -264.897219) (xy 88.688418 -264.907014) (xy 88.688418 -265.340825) (xy 88.839284 -265.340825)
			(xy 88.839284 -265.287527) (xy 88.847227 -265.234823) (xy 88.862937 -265.183893) (xy 88.886063 -265.135872)
			(xy 88.916087 -265.091835) (xy 88.952339 -265.052764) (xy 88.99401 -265.019533) (xy 89.040168 -264.992884)
			(xy 89.089782 -264.973412) (xy 89.141744 -264.961552) (xy 89.194894 -264.957569) (xy 89.248044 -264.961552)
			(xy 89.300006 -264.973412) (xy 89.34962 -264.992884) (xy 89.395778 -265.019533) (xy 89.437449 -265.052764)
			(xy 89.473701 -265.091835) (xy 89.503725 -265.135872) (xy 89.526851 -265.183893) (xy 89.542561 -265.234823)
			(xy 89.550504 -265.287527) (xy 89.551002 -265.314176) (xy 89.550504 -265.340825) (xy 89.779084 -265.340825)
			(xy 89.779084 -265.287527) (xy 89.787027 -265.234823) (xy 89.802737 -265.183893) (xy 89.825863 -265.135872)
			(xy 89.855887 -265.091835) (xy 89.892139 -265.052764) (xy 89.93381 -265.019533) (xy 89.979968 -264.992884)
			(xy 90.029582 -264.973412) (xy 90.081544 -264.961552) (xy 90.134694 -264.957569) (xy 90.187844 -264.961552)
			(xy 90.239806 -264.973412) (xy 90.28942 -264.992884) (xy 90.335578 -265.019533) (xy 90.377249 -265.052764)
			(xy 90.413501 -265.091835) (xy 90.443525 -265.135872) (xy 90.466651 -265.183893) (xy 90.482361 -265.234823)
			(xy 90.490304 -265.287527) (xy 90.490802 -265.314176) (xy 90.490304 -265.340825) (xy 90.719138 -265.340825)
			(xy 90.719138 -265.287527) (xy 90.727081 -265.234823) (xy 90.742791 -265.183893) (xy 90.765917 -265.135872)
			(xy 90.795941 -265.091835) (xy 90.832193 -265.052764) (xy 90.873864 -265.019533) (xy 90.920022 -264.992884)
			(xy 90.969636 -264.973412) (xy 91.021598 -264.961552) (xy 91.074748 -264.957569) (xy 91.127898 -264.961552)
			(xy 91.17986 -264.973412) (xy 91.229474 -264.992884) (xy 91.275632 -265.019533) (xy 91.317303 -265.052764)
			(xy 91.353555 -265.091835) (xy 91.383579 -265.135872) (xy 91.406705 -265.183893) (xy 91.422415 -265.234823)
			(xy 91.430358 -265.287527) (xy 91.430856 -265.314176) (xy 91.430358 -265.340825) (xy 91.658684 -265.340825)
			(xy 91.658684 -265.287527) (xy 91.666627 -265.234823) (xy 91.682337 -265.183893) (xy 91.705463 -265.135872)
			(xy 91.735487 -265.091835) (xy 91.771739 -265.052764) (xy 91.81341 -265.019533) (xy 91.859568 -264.992884)
			(xy 91.909182 -264.973412) (xy 91.961144 -264.961552) (xy 92.014294 -264.957569) (xy 92.067444 -264.961552)
			(xy 92.119406 -264.973412) (xy 92.16902 -264.992884) (xy 92.215178 -265.019533) (xy 92.256849 -265.052764)
			(xy 92.293101 -265.091835) (xy 92.323125 -265.135872) (xy 92.346251 -265.183893) (xy 92.361961 -265.234823)
			(xy 92.369904 -265.287527) (xy 92.370402 -265.314176) (xy 92.369904 -265.340825) (xy 92.598738 -265.340825)
			(xy 92.598738 -265.287527) (xy 92.606681 -265.234823) (xy 92.622391 -265.183893) (xy 92.645517 -265.135872)
			(xy 92.675541 -265.091835) (xy 92.711793 -265.052764) (xy 92.753464 -265.019533) (xy 92.799622 -264.992884)
			(xy 92.849236 -264.973412) (xy 92.901198 -264.961552) (xy 92.954348 -264.957569) (xy 93.007498 -264.961552)
			(xy 93.05946 -264.973412) (xy 93.109074 -264.992884) (xy 93.155232 -265.019533) (xy 93.196903 -265.052764)
			(xy 93.233155 -265.091835) (xy 93.263179 -265.135872) (xy 93.286305 -265.183893) (xy 93.302015 -265.234823)
			(xy 93.309958 -265.287527) (xy 93.310456 -265.314176) (xy 93.309958 -265.340825) (xy 93.538538 -265.340825)
			(xy 93.538538 -265.287527) (xy 93.546481 -265.234823) (xy 93.562191 -265.183893) (xy 93.585317 -265.135872)
			(xy 93.615341 -265.091835) (xy 93.651593 -265.052764) (xy 93.693264 -265.019533) (xy 93.739422 -264.992884)
			(xy 93.789036 -264.973412) (xy 93.840998 -264.961552) (xy 93.894148 -264.957569) (xy 93.947298 -264.961552)
			(xy 93.99926 -264.973412) (xy 94.048874 -264.992884) (xy 94.095032 -265.019533) (xy 94.136703 -265.052764)
			(xy 94.172955 -265.091835) (xy 94.202979 -265.135872) (xy 94.226105 -265.183893) (xy 94.241815 -265.234823)
			(xy 94.249758 -265.287527) (xy 94.250256 -265.314176) (xy 94.249758 -265.340825) (xy 94.478338 -265.340825)
			(xy 94.478338 -265.287527) (xy 94.486281 -265.234823) (xy 94.501991 -265.183893) (xy 94.525117 -265.135872)
			(xy 94.555141 -265.091835) (xy 94.591393 -265.052764) (xy 94.633064 -265.019533) (xy 94.679222 -264.992884)
			(xy 94.728836 -264.973412) (xy 94.780798 -264.961552) (xy 94.833948 -264.957569) (xy 94.887098 -264.961552)
			(xy 94.93906 -264.973412) (xy 94.988674 -264.992884) (xy 95.034832 -265.019533) (xy 95.076503 -265.052764)
			(xy 95.112755 -265.091835) (xy 95.142779 -265.135872) (xy 95.165905 -265.183893) (xy 95.181615 -265.234823)
			(xy 95.189558 -265.287527) (xy 95.190056 -265.314176) (xy 95.189558 -265.340825) (xy 95.418138 -265.340825)
			(xy 95.418138 -265.287527) (xy 95.426081 -265.234823) (xy 95.441791 -265.183893) (xy 95.464917 -265.135872)
			(xy 95.494941 -265.091835) (xy 95.531193 -265.052764) (xy 95.572864 -265.019533) (xy 95.619022 -264.992884)
			(xy 95.668636 -264.973412) (xy 95.720598 -264.961552) (xy 95.773748 -264.957569) (xy 95.826898 -264.961552)
			(xy 95.87886 -264.973412) (xy 95.928474 -264.992884) (xy 95.974632 -265.019533) (xy 96.016303 -265.052764)
			(xy 96.052555 -265.091835) (xy 96.082579 -265.135872) (xy 96.105705 -265.183893) (xy 96.121415 -265.234823)
			(xy 96.129358 -265.287527) (xy 96.129856 -265.314176) (xy 96.129358 -265.340825) (xy 96.357938 -265.340825)
			(xy 96.357938 -265.287527) (xy 96.365881 -265.234823) (xy 96.381591 -265.183893) (xy 96.404717 -265.135872)
			(xy 96.434741 -265.091835) (xy 96.470993 -265.052764) (xy 96.512664 -265.019533) (xy 96.558822 -264.992884)
			(xy 96.608436 -264.973412) (xy 96.660398 -264.961552) (xy 96.713548 -264.957569) (xy 96.766698 -264.961552)
			(xy 96.81866 -264.973412) (xy 96.868274 -264.992884) (xy 96.914432 -265.019533) (xy 96.956103 -265.052764)
			(xy 96.992355 -265.091835) (xy 97.022379 -265.135872) (xy 97.045505 -265.183893) (xy 97.061215 -265.234823)
			(xy 97.069158 -265.287527) (xy 97.069656 -265.314176) (xy 97.069158 -265.340825) (xy 97.297738 -265.340825)
			(xy 97.297738 -265.287527) (xy 97.305681 -265.234823) (xy 97.321391 -265.183893) (xy 97.344517 -265.135872)
			(xy 97.374541 -265.091835) (xy 97.410793 -265.052764) (xy 97.452464 -265.019533) (xy 97.498622 -264.992884)
			(xy 97.548236 -264.973412) (xy 97.600198 -264.961552) (xy 97.653348 -264.957569) (xy 97.706498 -264.961552)
			(xy 97.75846 -264.973412) (xy 97.808074 -264.992884) (xy 97.854232 -265.019533) (xy 97.895903 -265.052764)
			(xy 97.932155 -265.091835) (xy 97.962179 -265.135872) (xy 97.985305 -265.183893) (xy 98.001015 -265.234823)
			(xy 98.008958 -265.287527) (xy 98.009456 -265.314176) (xy 98.008958 -265.340825) (xy 98.237284 -265.340825)
			(xy 98.237284 -265.287527) (xy 98.245227 -265.234823) (xy 98.260937 -265.183893) (xy 98.284063 -265.135872)
			(xy 98.314087 -265.091835) (xy 98.350339 -265.052764) (xy 98.39201 -265.019533) (xy 98.438168 -264.992884)
			(xy 98.487782 -264.973412) (xy 98.539744 -264.961552) (xy 98.592894 -264.957569) (xy 98.646044 -264.961552)
			(xy 98.698006 -264.973412) (xy 98.74762 -264.992884) (xy 98.793778 -265.019533) (xy 98.835449 -265.052764)
			(xy 98.871701 -265.091835) (xy 98.901725 -265.135872) (xy 98.924851 -265.183893) (xy 98.940561 -265.234823)
			(xy 98.948504 -265.287527) (xy 98.949002 -265.314176) (xy 98.948504 -265.340825) (xy 99.177338 -265.340825)
			(xy 99.177338 -265.287527) (xy 99.185281 -265.234823) (xy 99.200991 -265.183893) (xy 99.224117 -265.135872)
			(xy 99.254141 -265.091835) (xy 99.290393 -265.052764) (xy 99.332064 -265.019533) (xy 99.378222 -264.992884)
			(xy 99.427836 -264.973412) (xy 99.479798 -264.961552) (xy 99.532948 -264.957569) (xy 99.586098 -264.961552)
			(xy 99.63806 -264.973412) (xy 99.687674 -264.992884) (xy 99.733832 -265.019533) (xy 99.775503 -265.052764)
			(xy 99.811755 -265.091835) (xy 99.841779 -265.135872) (xy 99.864905 -265.183893) (xy 99.880615 -265.234823)
			(xy 99.888558 -265.287527) (xy 99.889056 -265.314176) (xy 99.888558 -265.340825) (xy 100.117138 -265.340825)
			(xy 100.117138 -265.287527) (xy 100.125081 -265.234823) (xy 100.140791 -265.183893) (xy 100.163917 -265.135872)
			(xy 100.193941 -265.091835) (xy 100.230193 -265.052764) (xy 100.271864 -265.019533) (xy 100.318022 -264.992884)
			(xy 100.367636 -264.973412) (xy 100.419598 -264.961552) (xy 100.472748 -264.957569) (xy 100.525898 -264.961552)
			(xy 100.57786 -264.973412) (xy 100.627474 -264.992884) (xy 100.673632 -265.019533) (xy 100.715303 -265.052764)
			(xy 100.751555 -265.091835) (xy 100.781579 -265.135872) (xy 100.804705 -265.183893) (xy 100.820415 -265.234823)
			(xy 100.828358 -265.287527) (xy 100.828856 -265.314176) (xy 100.828358 -265.340825) (xy 101.056938 -265.340825)
			(xy 101.056938 -265.287527) (xy 101.064881 -265.234823) (xy 101.080591 -265.183893) (xy 101.103717 -265.135872)
			(xy 101.133741 -265.091835) (xy 101.169993 -265.052764) (xy 101.211664 -265.019533) (xy 101.257822 -264.992884)
			(xy 101.307436 -264.973412) (xy 101.359398 -264.961552) (xy 101.412548 -264.957569) (xy 101.465698 -264.961552)
			(xy 101.51766 -264.973412) (xy 101.567274 -264.992884) (xy 101.613432 -265.019533) (xy 101.655103 -265.052764)
			(xy 101.691355 -265.091835) (xy 101.721379 -265.135872) (xy 101.744505 -265.183893) (xy 101.760215 -265.234823)
			(xy 101.768158 -265.287527) (xy 101.768656 -265.314176) (xy 101.768158 -265.340825) (xy 101.996738 -265.340825)
			(xy 101.996738 -265.287527) (xy 102.004681 -265.234823) (xy 102.020391 -265.183893) (xy 102.043517 -265.135872)
			(xy 102.073541 -265.091835) (xy 102.109793 -265.052764) (xy 102.151464 -265.019533) (xy 102.197622 -264.992884)
			(xy 102.247236 -264.973412) (xy 102.299198 -264.961552) (xy 102.352348 -264.957569) (xy 102.405498 -264.961552)
			(xy 102.45746 -264.973412) (xy 102.507074 -264.992884) (xy 102.553232 -265.019533) (xy 102.594903 -265.052764)
			(xy 102.631155 -265.091835) (xy 102.661179 -265.135872) (xy 102.684305 -265.183893) (xy 102.700015 -265.234823)
			(xy 102.707958 -265.287527) (xy 102.708456 -265.314176) (xy 102.707958 -265.340825) (xy 102.936538 -265.340825)
			(xy 102.936538 -265.287527) (xy 102.944481 -265.234823) (xy 102.960191 -265.183893) (xy 102.983317 -265.135872)
			(xy 103.013341 -265.091835) (xy 103.049593 -265.052764) (xy 103.091264 -265.019533) (xy 103.137422 -264.992884)
			(xy 103.187036 -264.973412) (xy 103.238998 -264.961552) (xy 103.292148 -264.957569) (xy 103.345298 -264.961552)
			(xy 103.39726 -264.973412) (xy 103.446874 -264.992884) (xy 103.493032 -265.019533) (xy 103.534703 -265.052764)
			(xy 103.570955 -265.091835) (xy 103.600979 -265.135872) (xy 103.624105 -265.183893) (xy 103.639815 -265.234823)
			(xy 103.647758 -265.287527) (xy 103.648256 -265.314176) (xy 103.647758 -265.340825) (xy 103.876338 -265.340825)
			(xy 103.876338 -265.287527) (xy 103.884281 -265.234823) (xy 103.899991 -265.183893) (xy 103.923117 -265.135872)
			(xy 103.953141 -265.091835) (xy 103.989393 -265.052764) (xy 104.031064 -265.019533) (xy 104.077222 -264.992884)
			(xy 104.126836 -264.973412) (xy 104.178798 -264.961552) (xy 104.231948 -264.957569) (xy 104.285098 -264.961552)
			(xy 104.33706 -264.973412) (xy 104.386674 -264.992884) (xy 104.432832 -265.019533) (xy 104.474503 -265.052764)
			(xy 104.510755 -265.091835) (xy 104.540779 -265.135872) (xy 104.563905 -265.183893) (xy 104.579615 -265.234823)
			(xy 104.587558 -265.287527) (xy 104.588056 -265.314176) (xy 104.587558 -265.340825) (xy 104.816138 -265.340825)
			(xy 104.816138 -265.287527) (xy 104.824081 -265.234823) (xy 104.839791 -265.183893) (xy 104.862917 -265.135872)
			(xy 104.892941 -265.091835) (xy 104.929193 -265.052764) (xy 104.970864 -265.019533) (xy 105.017022 -264.992884)
			(xy 105.066636 -264.973412) (xy 105.118598 -264.961552) (xy 105.171748 -264.957569) (xy 105.224898 -264.961552)
			(xy 105.27686 -264.973412) (xy 105.326474 -264.992884) (xy 105.372632 -265.019533) (xy 105.414303 -265.052764)
			(xy 105.450555 -265.091835) (xy 105.480579 -265.135872) (xy 105.503705 -265.183893) (xy 105.519415 -265.234823)
			(xy 105.527358 -265.287527) (xy 105.527856 -265.314176) (xy 105.527358 -265.340825) (xy 105.755938 -265.340825)
			(xy 105.755938 -265.287527) (xy 105.763881 -265.234823) (xy 105.779591 -265.183893) (xy 105.802717 -265.135872)
			(xy 105.832741 -265.091835) (xy 105.868993 -265.052764) (xy 105.910664 -265.019533) (xy 105.956822 -264.992884)
			(xy 106.006436 -264.973412) (xy 106.058398 -264.961552) (xy 106.111548 -264.957569) (xy 106.164698 -264.961552)
			(xy 106.21666 -264.973412) (xy 106.266274 -264.992884) (xy 106.312432 -265.019533) (xy 106.354103 -265.052764)
			(xy 106.390355 -265.091835) (xy 106.420379 -265.135872) (xy 106.443505 -265.183893) (xy 106.459215 -265.234823)
			(xy 106.467158 -265.287527) (xy 106.467656 -265.314176) (xy 106.467158 -265.340825) (xy 106.695738 -265.340825)
			(xy 106.695738 -265.287527) (xy 106.703681 -265.234823) (xy 106.719391 -265.183893) (xy 106.742517 -265.135872)
			(xy 106.772541 -265.091835) (xy 106.808793 -265.052764) (xy 106.850464 -265.019533) (xy 106.896622 -264.992884)
			(xy 106.946236 -264.973412) (xy 106.998198 -264.961552) (xy 107.051348 -264.957569) (xy 107.104498 -264.961552)
			(xy 107.15646 -264.973412) (xy 107.206074 -264.992884) (xy 107.252232 -265.019533) (xy 107.293903 -265.052764)
			(xy 107.330155 -265.091835) (xy 107.360179 -265.135872) (xy 107.383305 -265.183893) (xy 107.399015 -265.234823)
			(xy 107.406958 -265.287527) (xy 107.407456 -265.314176) (xy 107.406958 -265.340825) (xy 107.399015 -265.393529)
			(xy 107.383305 -265.444459) (xy 107.360179 -265.49248) (xy 107.330155 -265.536517) (xy 107.293903 -265.575588)
			(xy 107.252232 -265.608819) (xy 107.206074 -265.635468) (xy 107.15646 -265.65494) (xy 107.104498 -265.6668)
			(xy 107.051348 -265.670784) (xy 106.998198 -265.6668) (xy 106.946236 -265.65494) (xy 106.896622 -265.635468)
			(xy 106.850464 -265.608819) (xy 106.808793 -265.575588) (xy 106.772541 -265.536517) (xy 106.742517 -265.49248)
			(xy 106.719391 -265.444459) (xy 106.703681 -265.393529) (xy 106.695738 -265.340825) (xy 106.467158 -265.340825)
			(xy 106.459215 -265.393529) (xy 106.443505 -265.444459) (xy 106.420379 -265.49248) (xy 106.390355 -265.536517)
			(xy 106.354103 -265.575588) (xy 106.312432 -265.608819) (xy 106.266274 -265.635468) (xy 106.21666 -265.65494)
			(xy 106.164698 -265.6668) (xy 106.111548 -265.670784) (xy 106.058398 -265.6668) (xy 106.006436 -265.65494)
			(xy 105.956822 -265.635468) (xy 105.910664 -265.608819) (xy 105.868993 -265.575588) (xy 105.832741 -265.536517)
			(xy 105.802717 -265.49248) (xy 105.779591 -265.444459) (xy 105.763881 -265.393529) (xy 105.755938 -265.340825)
			(xy 105.527358 -265.340825) (xy 105.519415 -265.393529) (xy 105.503705 -265.444459) (xy 105.480579 -265.49248)
			(xy 105.450555 -265.536517) (xy 105.414303 -265.575588) (xy 105.372632 -265.608819) (xy 105.326474 -265.635468)
			(xy 105.27686 -265.65494) (xy 105.224898 -265.6668) (xy 105.171748 -265.670784) (xy 105.118598 -265.6668)
			(xy 105.066636 -265.65494) (xy 105.017022 -265.635468) (xy 104.970864 -265.608819) (xy 104.929193 -265.575588)
			(xy 104.892941 -265.536517) (xy 104.862917 -265.49248) (xy 104.839791 -265.444459) (xy 104.824081 -265.393529)
			(xy 104.816138 -265.340825) (xy 104.587558 -265.340825) (xy 104.579615 -265.393529) (xy 104.563905 -265.444459)
			(xy 104.540779 -265.49248) (xy 104.510755 -265.536517) (xy 104.474503 -265.575588) (xy 104.432832 -265.608819)
			(xy 104.386674 -265.635468) (xy 104.33706 -265.65494) (xy 104.285098 -265.6668) (xy 104.231948 -265.670784)
			(xy 104.178798 -265.6668) (xy 104.126836 -265.65494) (xy 104.077222 -265.635468) (xy 104.031064 -265.608819)
			(xy 103.989393 -265.575588) (xy 103.953141 -265.536517) (xy 103.923117 -265.49248) (xy 103.899991 -265.444459)
			(xy 103.884281 -265.393529) (xy 103.876338 -265.340825) (xy 103.647758 -265.340825) (xy 103.639815 -265.393529)
			(xy 103.624105 -265.444459) (xy 103.600979 -265.49248) (xy 103.570955 -265.536517) (xy 103.534703 -265.575588)
			(xy 103.493032 -265.608819) (xy 103.446874 -265.635468) (xy 103.39726 -265.65494) (xy 103.345298 -265.6668)
			(xy 103.292148 -265.670784) (xy 103.238998 -265.6668) (xy 103.187036 -265.65494) (xy 103.137422 -265.635468)
			(xy 103.091264 -265.608819) (xy 103.049593 -265.575588) (xy 103.013341 -265.536517) (xy 102.983317 -265.49248)
			(xy 102.960191 -265.444459) (xy 102.944481 -265.393529) (xy 102.936538 -265.340825) (xy 102.707958 -265.340825)
			(xy 102.700015 -265.393529) (xy 102.684305 -265.444459) (xy 102.661179 -265.49248) (xy 102.631155 -265.536517)
			(xy 102.594903 -265.575588) (xy 102.553232 -265.608819) (xy 102.507074 -265.635468) (xy 102.45746 -265.65494)
			(xy 102.405498 -265.6668) (xy 102.352348 -265.670784) (xy 102.299198 -265.6668) (xy 102.247236 -265.65494)
			(xy 102.197622 -265.635468) (xy 102.151464 -265.608819) (xy 102.109793 -265.575588) (xy 102.073541 -265.536517)
			(xy 102.043517 -265.49248) (xy 102.020391 -265.444459) (xy 102.004681 -265.393529) (xy 101.996738 -265.340825)
			(xy 101.768158 -265.340825) (xy 101.760215 -265.393529) (xy 101.744505 -265.444459) (xy 101.721379 -265.49248)
			(xy 101.691355 -265.536517) (xy 101.655103 -265.575588) (xy 101.613432 -265.608819) (xy 101.567274 -265.635468)
			(xy 101.51766 -265.65494) (xy 101.465698 -265.6668) (xy 101.412548 -265.670784) (xy 101.359398 -265.6668)
			(xy 101.307436 -265.65494) (xy 101.257822 -265.635468) (xy 101.211664 -265.608819) (xy 101.169993 -265.575588)
			(xy 101.133741 -265.536517) (xy 101.103717 -265.49248) (xy 101.080591 -265.444459) (xy 101.064881 -265.393529)
			(xy 101.056938 -265.340825) (xy 100.828358 -265.340825) (xy 100.820415 -265.393529) (xy 100.804705 -265.444459)
			(xy 100.781579 -265.49248) (xy 100.751555 -265.536517) (xy 100.715303 -265.575588) (xy 100.673632 -265.608819)
			(xy 100.627474 -265.635468) (xy 100.57786 -265.65494) (xy 100.525898 -265.6668) (xy 100.472748 -265.670784)
			(xy 100.419598 -265.6668) (xy 100.367636 -265.65494) (xy 100.318022 -265.635468) (xy 100.271864 -265.608819)
			(xy 100.230193 -265.575588) (xy 100.193941 -265.536517) (xy 100.163917 -265.49248) (xy 100.140791 -265.444459)
			(xy 100.125081 -265.393529) (xy 100.117138 -265.340825) (xy 99.888558 -265.340825) (xy 99.880615 -265.393529)
			(xy 99.864905 -265.444459) (xy 99.841779 -265.49248) (xy 99.811755 -265.536517) (xy 99.775503 -265.575588)
			(xy 99.733832 -265.608819) (xy 99.687674 -265.635468) (xy 99.63806 -265.65494) (xy 99.586098 -265.6668)
			(xy 99.532948 -265.670784) (xy 99.479798 -265.6668) (xy 99.427836 -265.65494) (xy 99.378222 -265.635468)
			(xy 99.332064 -265.608819) (xy 99.290393 -265.575588) (xy 99.254141 -265.536517) (xy 99.224117 -265.49248)
			(xy 99.200991 -265.444459) (xy 99.185281 -265.393529) (xy 99.177338 -265.340825) (xy 98.948504 -265.340825)
			(xy 98.940561 -265.393529) (xy 98.924851 -265.444459) (xy 98.901725 -265.49248) (xy 98.871701 -265.536517)
			(xy 98.835449 -265.575588) (xy 98.793778 -265.608819) (xy 98.74762 -265.635468) (xy 98.698006 -265.65494)
			(xy 98.646044 -265.6668) (xy 98.592894 -265.670784) (xy 98.539744 -265.6668) (xy 98.487782 -265.65494)
			(xy 98.438168 -265.635468) (xy 98.39201 -265.608819) (xy 98.350339 -265.575588) (xy 98.314087 -265.536517)
			(xy 98.284063 -265.49248) (xy 98.260937 -265.444459) (xy 98.245227 -265.393529) (xy 98.237284 -265.340825)
			(xy 98.008958 -265.340825) (xy 98.001015 -265.393529) (xy 97.985305 -265.444459) (xy 97.962179 -265.49248)
			(xy 97.932155 -265.536517) (xy 97.895903 -265.575588) (xy 97.854232 -265.608819) (xy 97.808074 -265.635468)
			(xy 97.75846 -265.65494) (xy 97.706498 -265.6668) (xy 97.653348 -265.670784) (xy 97.600198 -265.6668)
			(xy 97.548236 -265.65494) (xy 97.498622 -265.635468) (xy 97.452464 -265.608819) (xy 97.410793 -265.575588)
			(xy 97.374541 -265.536517) (xy 97.344517 -265.49248) (xy 97.321391 -265.444459) (xy 97.305681 -265.393529)
			(xy 97.297738 -265.340825) (xy 97.069158 -265.340825) (xy 97.061215 -265.393529) (xy 97.045505 -265.444459)
			(xy 97.022379 -265.49248) (xy 96.992355 -265.536517) (xy 96.956103 -265.575588) (xy 96.914432 -265.608819)
			(xy 96.868274 -265.635468) (xy 96.81866 -265.65494) (xy 96.766698 -265.6668) (xy 96.713548 -265.670784)
			(xy 96.660398 -265.6668) (xy 96.608436 -265.65494) (xy 96.558822 -265.635468) (xy 96.512664 -265.608819)
			(xy 96.470993 -265.575588) (xy 96.434741 -265.536517) (xy 96.404717 -265.49248) (xy 96.381591 -265.444459)
			(xy 96.365881 -265.393529) (xy 96.357938 -265.340825) (xy 96.129358 -265.340825) (xy 96.121415 -265.393529)
			(xy 96.105705 -265.444459) (xy 96.082579 -265.49248) (xy 96.052555 -265.536517) (xy 96.016303 -265.575588)
			(xy 95.974632 -265.608819) (xy 95.928474 -265.635468) (xy 95.87886 -265.65494) (xy 95.826898 -265.6668)
			(xy 95.773748 -265.670784) (xy 95.720598 -265.6668) (xy 95.668636 -265.65494) (xy 95.619022 -265.635468)
			(xy 95.572864 -265.608819) (xy 95.531193 -265.575588) (xy 95.494941 -265.536517) (xy 95.464917 -265.49248)
			(xy 95.441791 -265.444459) (xy 95.426081 -265.393529) (xy 95.418138 -265.340825) (xy 95.189558 -265.340825)
			(xy 95.181615 -265.393529) (xy 95.165905 -265.444459) (xy 95.142779 -265.49248) (xy 95.112755 -265.536517)
			(xy 95.076503 -265.575588) (xy 95.034832 -265.608819) (xy 94.988674 -265.635468) (xy 94.93906 -265.65494)
			(xy 94.887098 -265.6668) (xy 94.833948 -265.670784) (xy 94.780798 -265.6668) (xy 94.728836 -265.65494)
			(xy 94.679222 -265.635468) (xy 94.633064 -265.608819) (xy 94.591393 -265.575588) (xy 94.555141 -265.536517)
			(xy 94.525117 -265.49248) (xy 94.501991 -265.444459) (xy 94.486281 -265.393529) (xy 94.478338 -265.340825)
			(xy 94.249758 -265.340825) (xy 94.241815 -265.393529) (xy 94.226105 -265.444459) (xy 94.202979 -265.49248)
			(xy 94.172955 -265.536517) (xy 94.136703 -265.575588) (xy 94.095032 -265.608819) (xy 94.048874 -265.635468)
			(xy 93.99926 -265.65494) (xy 93.947298 -265.6668) (xy 93.894148 -265.670784) (xy 93.840998 -265.6668)
			(xy 93.789036 -265.65494) (xy 93.739422 -265.635468) (xy 93.693264 -265.608819) (xy 93.651593 -265.575588)
			(xy 93.615341 -265.536517) (xy 93.585317 -265.49248) (xy 93.562191 -265.444459) (xy 93.546481 -265.393529)
			(xy 93.538538 -265.340825) (xy 93.309958 -265.340825) (xy 93.302015 -265.393529) (xy 93.286305 -265.444459)
			(xy 93.263179 -265.49248) (xy 93.233155 -265.536517) (xy 93.196903 -265.575588) (xy 93.155232 -265.608819)
			(xy 93.109074 -265.635468) (xy 93.05946 -265.65494) (xy 93.007498 -265.6668) (xy 92.954348 -265.670784)
			(xy 92.901198 -265.6668) (xy 92.849236 -265.65494) (xy 92.799622 -265.635468) (xy 92.753464 -265.608819)
			(xy 92.711793 -265.575588) (xy 92.675541 -265.536517) (xy 92.645517 -265.49248) (xy 92.622391 -265.444459)
			(xy 92.606681 -265.393529) (xy 92.598738 -265.340825) (xy 92.369904 -265.340825) (xy 92.361961 -265.393529)
			(xy 92.346251 -265.444459) (xy 92.323125 -265.49248) (xy 92.293101 -265.536517) (xy 92.256849 -265.575588)
			(xy 92.215178 -265.608819) (xy 92.16902 -265.635468) (xy 92.119406 -265.65494) (xy 92.067444 -265.6668)
			(xy 92.014294 -265.670784) (xy 91.961144 -265.6668) (xy 91.909182 -265.65494) (xy 91.859568 -265.635468)
			(xy 91.81341 -265.608819) (xy 91.771739 -265.575588) (xy 91.735487 -265.536517) (xy 91.705463 -265.49248)
			(xy 91.682337 -265.444459) (xy 91.666627 -265.393529) (xy 91.658684 -265.340825) (xy 91.430358 -265.340825)
			(xy 91.422415 -265.393529) (xy 91.406705 -265.444459) (xy 91.383579 -265.49248) (xy 91.353555 -265.536517)
			(xy 91.317303 -265.575588) (xy 91.275632 -265.608819) (xy 91.229474 -265.635468) (xy 91.17986 -265.65494)
			(xy 91.127898 -265.6668) (xy 91.074748 -265.670784) (xy 91.021598 -265.6668) (xy 90.969636 -265.65494)
			(xy 90.920022 -265.635468) (xy 90.873864 -265.608819) (xy 90.832193 -265.575588) (xy 90.795941 -265.536517)
			(xy 90.765917 -265.49248) (xy 90.742791 -265.444459) (xy 90.727081 -265.393529) (xy 90.719138 -265.340825)
			(xy 90.490304 -265.340825) (xy 90.482361 -265.393529) (xy 90.466651 -265.444459) (xy 90.443525 -265.49248)
			(xy 90.413501 -265.536517) (xy 90.377249 -265.575588) (xy 90.335578 -265.608819) (xy 90.28942 -265.635468)
			(xy 90.239806 -265.65494) (xy 90.187844 -265.6668) (xy 90.134694 -265.670784) (xy 90.081544 -265.6668)
			(xy 90.029582 -265.65494) (xy 89.979968 -265.635468) (xy 89.93381 -265.608819) (xy 89.892139 -265.575588)
			(xy 89.855887 -265.536517) (xy 89.825863 -265.49248) (xy 89.802737 -265.444459) (xy 89.787027 -265.393529)
			(xy 89.779084 -265.340825) (xy 89.550504 -265.340825) (xy 89.542561 -265.393529) (xy 89.526851 -265.444459)
			(xy 89.503725 -265.49248) (xy 89.473701 -265.536517) (xy 89.437449 -265.575588) (xy 89.395778 -265.608819)
			(xy 89.34962 -265.635468) (xy 89.300006 -265.65494) (xy 89.248044 -265.6668) (xy 89.194894 -265.670784)
			(xy 89.141744 -265.6668) (xy 89.089782 -265.65494) (xy 89.040168 -265.635468) (xy 88.99401 -265.608819)
			(xy 88.952339 -265.575588) (xy 88.916087 -265.536517) (xy 88.886063 -265.49248) (xy 88.862937 -265.444459)
			(xy 88.847227 -265.393529) (xy 88.839284 -265.340825) (xy 88.688418 -265.340825) (xy 88.688418 -265.721592)
			(xy 88.68886 -265.731386) (xy 88.696188 -265.749552) (xy 88.709782 -265.763655) (xy 88.727667 -265.771646)
			(xy 88.73744 -265.772392) (xy 88.764761 -265.773848) (xy 88.818503 -265.784102) (xy 88.870043 -265.802456)
			(xy 88.918169 -265.82848) (xy 88.961747 -265.861559) (xy 88.999751 -265.900916) (xy 89.031288 -265.945623)
			(xy 89.055613 -265.994629) (xy 89.072156 -266.046779) (xy 89.080525 -266.100846) (xy 89.080525 -266.154895)
			(xy 89.309184 -266.154895) (xy 89.309184 -266.101597) (xy 89.317127 -266.048893) (xy 89.332837 -265.997963)
			(xy 89.355963 -265.949942) (xy 89.385987 -265.905905) (xy 89.422239 -265.866834) (xy 89.46391 -265.833603)
			(xy 89.510068 -265.806954) (xy 89.559682 -265.787482) (xy 89.611644 -265.775622) (xy 89.664794 -265.771639)
			(xy 89.717944 -265.775622) (xy 89.769906 -265.787482) (xy 89.81952 -265.806954) (xy 89.865678 -265.833603)
			(xy 89.907349 -265.866834) (xy 89.943601 -265.905905) (xy 89.973625 -265.949942) (xy 89.996751 -265.997963)
			(xy 90.012461 -266.048893) (xy 90.020404 -266.101597) (xy 90.020902 -266.128246) (xy 90.020404 -266.154895)
			(xy 90.248984 -266.154895) (xy 90.248984 -266.101597) (xy 90.256927 -266.048893) (xy 90.272637 -265.997963)
			(xy 90.295763 -265.949942) (xy 90.325787 -265.905905) (xy 90.362039 -265.866834) (xy 90.40371 -265.833603)
			(xy 90.449868 -265.806954) (xy 90.499482 -265.787482) (xy 90.551444 -265.775622) (xy 90.604594 -265.771639)
			(xy 90.657744 -265.775622) (xy 90.709706 -265.787482) (xy 90.75932 -265.806954) (xy 90.805478 -265.833603)
			(xy 90.847149 -265.866834) (xy 90.883401 -265.905905) (xy 90.913425 -265.949942) (xy 90.936551 -265.997963)
			(xy 90.952261 -266.048893) (xy 90.960204 -266.101597) (xy 90.960702 -266.128246) (xy 90.960204 -266.154895)
			(xy 91.188784 -266.154895) (xy 91.188784 -266.101597) (xy 91.196727 -266.048893) (xy 91.212437 -265.997963)
			(xy 91.235563 -265.949942) (xy 91.265587 -265.905905) (xy 91.301839 -265.866834) (xy 91.34351 -265.833603)
			(xy 91.389668 -265.806954) (xy 91.439282 -265.787482) (xy 91.491244 -265.775622) (xy 91.544394 -265.771639)
			(xy 91.597544 -265.775622) (xy 91.649506 -265.787482) (xy 91.69912 -265.806954) (xy 91.745278 -265.833603)
			(xy 91.786949 -265.866834) (xy 91.823201 -265.905905) (xy 91.853225 -265.949942) (xy 91.876351 -265.997963)
			(xy 91.892061 -266.048893) (xy 91.900004 -266.101597) (xy 91.900502 -266.128246) (xy 91.900004 -266.154895)
			(xy 92.128584 -266.154895) (xy 92.128584 -266.101597) (xy 92.136527 -266.048893) (xy 92.152237 -265.997963)
			(xy 92.175363 -265.949942) (xy 92.205387 -265.905905) (xy 92.241639 -265.866834) (xy 92.28331 -265.833603)
			(xy 92.329468 -265.806954) (xy 92.379082 -265.787482) (xy 92.431044 -265.775622) (xy 92.484194 -265.771639)
			(xy 92.537344 -265.775622) (xy 92.589306 -265.787482) (xy 92.63892 -265.806954) (xy 92.685078 -265.833603)
			(xy 92.726749 -265.866834) (xy 92.763001 -265.905905) (xy 92.793025 -265.949942) (xy 92.816151 -265.997963)
			(xy 92.831861 -266.048893) (xy 92.839804 -266.101597) (xy 92.840302 -266.128246) (xy 92.839804 -266.154895)
			(xy 93.068384 -266.154895) (xy 93.068384 -266.101597) (xy 93.076327 -266.048893) (xy 93.092037 -265.997963)
			(xy 93.115163 -265.949942) (xy 93.145187 -265.905905) (xy 93.181439 -265.866834) (xy 93.22311 -265.833603)
			(xy 93.269268 -265.806954) (xy 93.318882 -265.787482) (xy 93.370844 -265.775622) (xy 93.423994 -265.771639)
			(xy 93.477144 -265.775622) (xy 93.529106 -265.787482) (xy 93.57872 -265.806954) (xy 93.624878 -265.833603)
			(xy 93.666549 -265.866834) (xy 93.702801 -265.905905) (xy 93.732825 -265.949942) (xy 93.755951 -265.997963)
			(xy 93.771661 -266.048893) (xy 93.779604 -266.101597) (xy 93.780102 -266.128246) (xy 93.779604 -266.154895)
			(xy 94.008184 -266.154895) (xy 94.008184 -266.101597) (xy 94.016127 -266.048893) (xy 94.031837 -265.997963)
			(xy 94.054963 -265.949942) (xy 94.084987 -265.905905) (xy 94.121239 -265.866834) (xy 94.16291 -265.833603)
			(xy 94.209068 -265.806954) (xy 94.258682 -265.787482) (xy 94.310644 -265.775622) (xy 94.363794 -265.771639)
			(xy 94.416944 -265.775622) (xy 94.468906 -265.787482) (xy 94.51852 -265.806954) (xy 94.564678 -265.833603)
			(xy 94.606349 -265.866834) (xy 94.642601 -265.905905) (xy 94.672625 -265.949942) (xy 94.695751 -265.997963)
			(xy 94.711461 -266.048893) (xy 94.719404 -266.101597) (xy 94.719902 -266.128246) (xy 94.719404 -266.154895)
			(xy 94.947984 -266.154895) (xy 94.947984 -266.101597) (xy 94.955927 -266.048893) (xy 94.971637 -265.997963)
			(xy 94.994763 -265.949942) (xy 95.024787 -265.905905) (xy 95.061039 -265.866834) (xy 95.10271 -265.833603)
			(xy 95.148868 -265.806954) (xy 95.198482 -265.787482) (xy 95.250444 -265.775622) (xy 95.303594 -265.771639)
			(xy 95.356744 -265.775622) (xy 95.408706 -265.787482) (xy 95.45832 -265.806954) (xy 95.504478 -265.833603)
			(xy 95.546149 -265.866834) (xy 95.582401 -265.905905) (xy 95.612425 -265.949942) (xy 95.635551 -265.997963)
			(xy 95.651261 -266.048893) (xy 95.659204 -266.101597) (xy 95.659702 -266.128246) (xy 95.659204 -266.154895)
			(xy 95.887784 -266.154895) (xy 95.887784 -266.101597) (xy 95.895727 -266.048893) (xy 95.911437 -265.997963)
			(xy 95.934563 -265.949942) (xy 95.964587 -265.905905) (xy 96.000839 -265.866834) (xy 96.04251 -265.833603)
			(xy 96.088668 -265.806954) (xy 96.138282 -265.787482) (xy 96.190244 -265.775622) (xy 96.243394 -265.771639)
			(xy 96.296544 -265.775622) (xy 96.348506 -265.787482) (xy 96.39812 -265.806954) (xy 96.444278 -265.833603)
			(xy 96.485949 -265.866834) (xy 96.522201 -265.905905) (xy 96.552225 -265.949942) (xy 96.575351 -265.997963)
			(xy 96.591061 -266.048893) (xy 96.599004 -266.101597) (xy 96.599502 -266.128246) (xy 96.599004 -266.154895)
			(xy 96.827584 -266.154895) (xy 96.827584 -266.101597) (xy 96.835527 -266.048893) (xy 96.851237 -265.997963)
			(xy 96.874363 -265.949942) (xy 96.904387 -265.905905) (xy 96.940639 -265.866834) (xy 96.98231 -265.833603)
			(xy 97.028468 -265.806954) (xy 97.078082 -265.787482) (xy 97.130044 -265.775622) (xy 97.183194 -265.771639)
			(xy 97.236344 -265.775622) (xy 97.288306 -265.787482) (xy 97.33792 -265.806954) (xy 97.384078 -265.833603)
			(xy 97.425749 -265.866834) (xy 97.462001 -265.905905) (xy 97.492025 -265.949942) (xy 97.515151 -265.997963)
			(xy 97.530861 -266.048893) (xy 97.538804 -266.101597) (xy 97.539302 -266.128246) (xy 97.538804 -266.154895)
			(xy 97.767384 -266.154895) (xy 97.767384 -266.101597) (xy 97.775327 -266.048893) (xy 97.791037 -265.997963)
			(xy 97.814163 -265.949942) (xy 97.844187 -265.905905) (xy 97.880439 -265.866834) (xy 97.92211 -265.833603)
			(xy 97.968268 -265.806954) (xy 98.017882 -265.787482) (xy 98.069844 -265.775622) (xy 98.122994 -265.771639)
			(xy 98.176144 -265.775622) (xy 98.228106 -265.787482) (xy 98.27772 -265.806954) (xy 98.323878 -265.833603)
			(xy 98.365549 -265.866834) (xy 98.401801 -265.905905) (xy 98.431825 -265.949942) (xy 98.454951 -265.997963)
			(xy 98.470661 -266.048893) (xy 98.478604 -266.101597) (xy 98.479102 -266.128246) (xy 98.478604 -266.154895)
			(xy 98.707184 -266.154895) (xy 98.707184 -266.101597) (xy 98.715127 -266.048893) (xy 98.730837 -265.997963)
			(xy 98.753963 -265.949942) (xy 98.783987 -265.905905) (xy 98.820239 -265.866834) (xy 98.86191 -265.833603)
			(xy 98.908068 -265.806954) (xy 98.957682 -265.787482) (xy 99.009644 -265.775622) (xy 99.062794 -265.771639)
			(xy 99.115944 -265.775622) (xy 99.167906 -265.787482) (xy 99.21752 -265.806954) (xy 99.263678 -265.833603)
			(xy 99.305349 -265.866834) (xy 99.341601 -265.905905) (xy 99.371625 -265.949942) (xy 99.394751 -265.997963)
			(xy 99.410461 -266.048893) (xy 99.418404 -266.101597) (xy 99.418902 -266.128246) (xy 99.418404 -266.154895)
			(xy 99.646984 -266.154895) (xy 99.646984 -266.101597) (xy 99.654927 -266.048893) (xy 99.670637 -265.997963)
			(xy 99.693763 -265.949942) (xy 99.723787 -265.905905) (xy 99.760039 -265.866834) (xy 99.80171 -265.833603)
			(xy 99.847868 -265.806954) (xy 99.897482 -265.787482) (xy 99.949444 -265.775622) (xy 100.002594 -265.771639)
			(xy 100.055744 -265.775622) (xy 100.107706 -265.787482) (xy 100.15732 -265.806954) (xy 100.203478 -265.833603)
			(xy 100.245149 -265.866834) (xy 100.281401 -265.905905) (xy 100.311425 -265.949942) (xy 100.334551 -265.997963)
			(xy 100.350261 -266.048893) (xy 100.358204 -266.101597) (xy 100.358702 -266.128246) (xy 100.358204 -266.154895)
			(xy 100.586784 -266.154895) (xy 100.586784 -266.101597) (xy 100.594727 -266.048893) (xy 100.610437 -265.997963)
			(xy 100.633563 -265.949942) (xy 100.663587 -265.905905) (xy 100.699839 -265.866834) (xy 100.74151 -265.833603)
			(xy 100.787668 -265.806954) (xy 100.837282 -265.787482) (xy 100.889244 -265.775622) (xy 100.942394 -265.771639)
			(xy 100.995544 -265.775622) (xy 101.047506 -265.787482) (xy 101.09712 -265.806954) (xy 101.143278 -265.833603)
			(xy 101.184949 -265.866834) (xy 101.221201 -265.905905) (xy 101.251225 -265.949942) (xy 101.274351 -265.997963)
			(xy 101.290061 -266.048893) (xy 101.298004 -266.101597) (xy 101.298502 -266.128246) (xy 101.298004 -266.154895)
			(xy 101.526584 -266.154895) (xy 101.526584 -266.101597) (xy 101.534527 -266.048893) (xy 101.550237 -265.997963)
			(xy 101.573363 -265.949942) (xy 101.603387 -265.905905) (xy 101.639639 -265.866834) (xy 101.68131 -265.833603)
			(xy 101.727468 -265.806954) (xy 101.777082 -265.787482) (xy 101.829044 -265.775622) (xy 101.882194 -265.771639)
			(xy 101.935344 -265.775622) (xy 101.987306 -265.787482) (xy 102.03692 -265.806954) (xy 102.083078 -265.833603)
			(xy 102.124749 -265.866834) (xy 102.161001 -265.905905) (xy 102.191025 -265.949942) (xy 102.214151 -265.997963)
			(xy 102.229861 -266.048893) (xy 102.237804 -266.101597) (xy 102.238302 -266.128246) (xy 102.237804 -266.154895)
			(xy 102.466384 -266.154895) (xy 102.466384 -266.101597) (xy 102.474327 -266.048893) (xy 102.490037 -265.997963)
			(xy 102.513163 -265.949942) (xy 102.543187 -265.905905) (xy 102.579439 -265.866834) (xy 102.62111 -265.833603)
			(xy 102.667268 -265.806954) (xy 102.716882 -265.787482) (xy 102.768844 -265.775622) (xy 102.821994 -265.771639)
			(xy 102.875144 -265.775622) (xy 102.927106 -265.787482) (xy 102.97672 -265.806954) (xy 103.022878 -265.833603)
			(xy 103.064549 -265.866834) (xy 103.100801 -265.905905) (xy 103.130825 -265.949942) (xy 103.153951 -265.997963)
			(xy 103.169661 -266.048893) (xy 103.177604 -266.101597) (xy 103.178102 -266.128246) (xy 103.177604 -266.154895)
			(xy 103.406184 -266.154895) (xy 103.406184 -266.101597) (xy 103.414127 -266.048893) (xy 103.429837 -265.997963)
			(xy 103.452963 -265.949942) (xy 103.482987 -265.905905) (xy 103.519239 -265.866834) (xy 103.56091 -265.833603)
			(xy 103.607068 -265.806954) (xy 103.656682 -265.787482) (xy 103.708644 -265.775622) (xy 103.761794 -265.771639)
			(xy 103.814944 -265.775622) (xy 103.866906 -265.787482) (xy 103.91652 -265.806954) (xy 103.962678 -265.833603)
			(xy 104.004349 -265.866834) (xy 104.040601 -265.905905) (xy 104.070625 -265.949942) (xy 104.093751 -265.997963)
			(xy 104.109461 -266.048893) (xy 104.117404 -266.101597) (xy 104.117902 -266.128246) (xy 104.117404 -266.154895)
			(xy 104.345984 -266.154895) (xy 104.345984 -266.101597) (xy 104.353927 -266.048893) (xy 104.369637 -265.997963)
			(xy 104.392763 -265.949942) (xy 104.422787 -265.905905) (xy 104.459039 -265.866834) (xy 104.50071 -265.833603)
			(xy 104.546868 -265.806954) (xy 104.596482 -265.787482) (xy 104.648444 -265.775622) (xy 104.701594 -265.771639)
			(xy 104.754744 -265.775622) (xy 104.806706 -265.787482) (xy 104.85632 -265.806954) (xy 104.902478 -265.833603)
			(xy 104.944149 -265.866834) (xy 104.980401 -265.905905) (xy 105.010425 -265.949942) (xy 105.033551 -265.997963)
			(xy 105.049261 -266.048893) (xy 105.057204 -266.101597) (xy 105.057702 -266.128246) (xy 105.057204 -266.154895)
			(xy 105.285784 -266.154895) (xy 105.285784 -266.101597) (xy 105.293727 -266.048893) (xy 105.309437 -265.997963)
			(xy 105.332563 -265.949942) (xy 105.362587 -265.905905) (xy 105.398839 -265.866834) (xy 105.44051 -265.833603)
			(xy 105.486668 -265.806954) (xy 105.536282 -265.787482) (xy 105.588244 -265.775622) (xy 105.641394 -265.771639)
			(xy 105.694544 -265.775622) (xy 105.746506 -265.787482) (xy 105.79612 -265.806954) (xy 105.842278 -265.833603)
			(xy 105.883949 -265.866834) (xy 105.920201 -265.905905) (xy 105.950225 -265.949942) (xy 105.973351 -265.997963)
			(xy 105.989061 -266.048893) (xy 105.997004 -266.101597) (xy 105.997502 -266.128246) (xy 105.997004 -266.154895)
			(xy 106.225584 -266.154895) (xy 106.225584 -266.101597) (xy 106.233527 -266.048893) (xy 106.249237 -265.997963)
			(xy 106.272363 -265.949942) (xy 106.302387 -265.905905) (xy 106.338639 -265.866834) (xy 106.38031 -265.833603)
			(xy 106.426468 -265.806954) (xy 106.476082 -265.787482) (xy 106.528044 -265.775622) (xy 106.581194 -265.771639)
			(xy 106.634344 -265.775622) (xy 106.686306 -265.787482) (xy 106.73592 -265.806954) (xy 106.782078 -265.833603)
			(xy 106.823749 -265.866834) (xy 106.860001 -265.905905) (xy 106.890025 -265.949942) (xy 106.913151 -265.997963)
			(xy 106.928861 -266.048893) (xy 106.936804 -266.101597) (xy 106.937302 -266.128246) (xy 106.936804 -266.154895)
			(xy 107.165384 -266.154895) (xy 107.165384 -266.101597) (xy 107.173327 -266.048893) (xy 107.189037 -265.997963)
			(xy 107.212163 -265.949942) (xy 107.242187 -265.905905) (xy 107.278439 -265.866834) (xy 107.32011 -265.833603)
			(xy 107.366268 -265.806954) (xy 107.415882 -265.787482) (xy 107.467844 -265.775622) (xy 107.520994 -265.771639)
			(xy 107.574144 -265.775622) (xy 107.626106 -265.787482) (xy 107.67572 -265.806954) (xy 107.721878 -265.833603)
			(xy 107.763549 -265.866834) (xy 107.799801 -265.905905) (xy 107.829825 -265.949942) (xy 107.852951 -265.997963)
			(xy 107.868661 -266.048893) (xy 107.876604 -266.101597) (xy 107.877102 -266.128246) (xy 107.876604 -266.154895)
			(xy 107.868661 -266.207599) (xy 107.852951 -266.258529) (xy 107.829825 -266.30655) (xy 107.799801 -266.350587)
			(xy 107.763549 -266.389658) (xy 107.721878 -266.422889) (xy 107.67572 -266.449538) (xy 107.626106 -266.46901)
			(xy 107.574144 -266.48087) (xy 107.520994 -266.484854) (xy 107.467844 -266.48087) (xy 107.415882 -266.46901)
			(xy 107.366268 -266.449538) (xy 107.32011 -266.422889) (xy 107.278439 -266.389658) (xy 107.242187 -266.350587)
			(xy 107.212163 -266.30655) (xy 107.189037 -266.258529) (xy 107.173327 -266.207599) (xy 107.165384 -266.154895)
			(xy 106.936804 -266.154895) (xy 106.928861 -266.207599) (xy 106.913151 -266.258529) (xy 106.890025 -266.30655)
			(xy 106.860001 -266.350587) (xy 106.823749 -266.389658) (xy 106.782078 -266.422889) (xy 106.73592 -266.449538)
			(xy 106.686306 -266.46901) (xy 106.634344 -266.48087) (xy 106.581194 -266.484854) (xy 106.528044 -266.48087)
			(xy 106.476082 -266.46901) (xy 106.426468 -266.449538) (xy 106.38031 -266.422889) (xy 106.338639 -266.389658)
			(xy 106.302387 -266.350587) (xy 106.272363 -266.30655) (xy 106.249237 -266.258529) (xy 106.233527 -266.207599)
			(xy 106.225584 -266.154895) (xy 105.997004 -266.154895) (xy 105.989061 -266.207599) (xy 105.973351 -266.258529)
			(xy 105.950225 -266.30655) (xy 105.920201 -266.350587) (xy 105.883949 -266.389658) (xy 105.842278 -266.422889)
			(xy 105.79612 -266.449538) (xy 105.746506 -266.46901) (xy 105.694544 -266.48087) (xy 105.641394 -266.484854)
			(xy 105.588244 -266.48087) (xy 105.536282 -266.46901) (xy 105.486668 -266.449538) (xy 105.44051 -266.422889)
			(xy 105.398839 -266.389658) (xy 105.362587 -266.350587) (xy 105.332563 -266.30655) (xy 105.309437 -266.258529)
			(xy 105.293727 -266.207599) (xy 105.285784 -266.154895) (xy 105.057204 -266.154895) (xy 105.049261 -266.207599)
			(xy 105.033551 -266.258529) (xy 105.010425 -266.30655) (xy 104.980401 -266.350587) (xy 104.944149 -266.389658)
			(xy 104.902478 -266.422889) (xy 104.85632 -266.449538) (xy 104.806706 -266.46901) (xy 104.754744 -266.48087)
			(xy 104.701594 -266.484854) (xy 104.648444 -266.48087) (xy 104.596482 -266.46901) (xy 104.546868 -266.449538)
			(xy 104.50071 -266.422889) (xy 104.459039 -266.389658) (xy 104.422787 -266.350587) (xy 104.392763 -266.30655)
			(xy 104.369637 -266.258529) (xy 104.353927 -266.207599) (xy 104.345984 -266.154895) (xy 104.117404 -266.154895)
			(xy 104.109461 -266.207599) (xy 104.093751 -266.258529) (xy 104.070625 -266.30655) (xy 104.040601 -266.350587)
			(xy 104.004349 -266.389658) (xy 103.962678 -266.422889) (xy 103.91652 -266.449538) (xy 103.866906 -266.46901)
			(xy 103.814944 -266.48087) (xy 103.761794 -266.484854) (xy 103.708644 -266.48087) (xy 103.656682 -266.46901)
			(xy 103.607068 -266.449538) (xy 103.56091 -266.422889) (xy 103.519239 -266.389658) (xy 103.482987 -266.350587)
			(xy 103.452963 -266.30655) (xy 103.429837 -266.258529) (xy 103.414127 -266.207599) (xy 103.406184 -266.154895)
			(xy 103.177604 -266.154895) (xy 103.169661 -266.207599) (xy 103.153951 -266.258529) (xy 103.130825 -266.30655)
			(xy 103.100801 -266.350587) (xy 103.064549 -266.389658) (xy 103.022878 -266.422889) (xy 102.97672 -266.449538)
			(xy 102.927106 -266.46901) (xy 102.875144 -266.48087) (xy 102.821994 -266.484854) (xy 102.768844 -266.48087)
			(xy 102.716882 -266.46901) (xy 102.667268 -266.449538) (xy 102.62111 -266.422889) (xy 102.579439 -266.389658)
			(xy 102.543187 -266.350587) (xy 102.513163 -266.30655) (xy 102.490037 -266.258529) (xy 102.474327 -266.207599)
			(xy 102.466384 -266.154895) (xy 102.237804 -266.154895) (xy 102.229861 -266.207599) (xy 102.214151 -266.258529)
			(xy 102.191025 -266.30655) (xy 102.161001 -266.350587) (xy 102.124749 -266.389658) (xy 102.083078 -266.422889)
			(xy 102.03692 -266.449538) (xy 101.987306 -266.46901) (xy 101.935344 -266.48087) (xy 101.882194 -266.484854)
			(xy 101.829044 -266.48087) (xy 101.777082 -266.46901) (xy 101.727468 -266.449538) (xy 101.68131 -266.422889)
			(xy 101.639639 -266.389658) (xy 101.603387 -266.350587) (xy 101.573363 -266.30655) (xy 101.550237 -266.258529)
			(xy 101.534527 -266.207599) (xy 101.526584 -266.154895) (xy 101.298004 -266.154895) (xy 101.290061 -266.207599)
			(xy 101.274351 -266.258529) (xy 101.251225 -266.30655) (xy 101.221201 -266.350587) (xy 101.184949 -266.389658)
			(xy 101.143278 -266.422889) (xy 101.09712 -266.449538) (xy 101.047506 -266.46901) (xy 100.995544 -266.48087)
			(xy 100.942394 -266.484854) (xy 100.889244 -266.48087) (xy 100.837282 -266.46901) (xy 100.787668 -266.449538)
			(xy 100.74151 -266.422889) (xy 100.699839 -266.389658) (xy 100.663587 -266.350587) (xy 100.633563 -266.30655)
			(xy 100.610437 -266.258529) (xy 100.594727 -266.207599) (xy 100.586784 -266.154895) (xy 100.358204 -266.154895)
			(xy 100.350261 -266.207599) (xy 100.334551 -266.258529) (xy 100.311425 -266.30655) (xy 100.281401 -266.350587)
			(xy 100.245149 -266.389658) (xy 100.203478 -266.422889) (xy 100.15732 -266.449538) (xy 100.107706 -266.46901)
			(xy 100.055744 -266.48087) (xy 100.002594 -266.484854) (xy 99.949444 -266.48087) (xy 99.897482 -266.46901)
			(xy 99.847868 -266.449538) (xy 99.80171 -266.422889) (xy 99.760039 -266.389658) (xy 99.723787 -266.350587)
			(xy 99.693763 -266.30655) (xy 99.670637 -266.258529) (xy 99.654927 -266.207599) (xy 99.646984 -266.154895)
			(xy 99.418404 -266.154895) (xy 99.410461 -266.207599) (xy 99.394751 -266.258529) (xy 99.371625 -266.30655)
			(xy 99.341601 -266.350587) (xy 99.305349 -266.389658) (xy 99.263678 -266.422889) (xy 99.21752 -266.449538)
			(xy 99.167906 -266.46901) (xy 99.115944 -266.48087) (xy 99.062794 -266.484854) (xy 99.009644 -266.48087)
			(xy 98.957682 -266.46901) (xy 98.908068 -266.449538) (xy 98.86191 -266.422889) (xy 98.820239 -266.389658)
			(xy 98.783987 -266.350587) (xy 98.753963 -266.30655) (xy 98.730837 -266.258529) (xy 98.715127 -266.207599)
			(xy 98.707184 -266.154895) (xy 98.478604 -266.154895) (xy 98.470661 -266.207599) (xy 98.454951 -266.258529)
			(xy 98.431825 -266.30655) (xy 98.401801 -266.350587) (xy 98.365549 -266.389658) (xy 98.323878 -266.422889)
			(xy 98.27772 -266.449538) (xy 98.228106 -266.46901) (xy 98.176144 -266.48087) (xy 98.122994 -266.484854)
			(xy 98.069844 -266.48087) (xy 98.017882 -266.46901) (xy 97.968268 -266.449538) (xy 97.92211 -266.422889)
			(xy 97.880439 -266.389658) (xy 97.844187 -266.350587) (xy 97.814163 -266.30655) (xy 97.791037 -266.258529)
			(xy 97.775327 -266.207599) (xy 97.767384 -266.154895) (xy 97.538804 -266.154895) (xy 97.530861 -266.207599)
			(xy 97.515151 -266.258529) (xy 97.492025 -266.30655) (xy 97.462001 -266.350587) (xy 97.425749 -266.389658)
			(xy 97.384078 -266.422889) (xy 97.33792 -266.449538) (xy 97.288306 -266.46901) (xy 97.236344 -266.48087)
			(xy 97.183194 -266.484854) (xy 97.130044 -266.48087) (xy 97.078082 -266.46901) (xy 97.028468 -266.449538)
			(xy 96.98231 -266.422889) (xy 96.940639 -266.389658) (xy 96.904387 -266.350587) (xy 96.874363 -266.30655)
			(xy 96.851237 -266.258529) (xy 96.835527 -266.207599) (xy 96.827584 -266.154895) (xy 96.599004 -266.154895)
			(xy 96.591061 -266.207599) (xy 96.575351 -266.258529) (xy 96.552225 -266.30655) (xy 96.522201 -266.350587)
			(xy 96.485949 -266.389658) (xy 96.444278 -266.422889) (xy 96.39812 -266.449538) (xy 96.348506 -266.46901)
			(xy 96.296544 -266.48087) (xy 96.243394 -266.484854) (xy 96.190244 -266.48087) (xy 96.138282 -266.46901)
			(xy 96.088668 -266.449538) (xy 96.04251 -266.422889) (xy 96.000839 -266.389658) (xy 95.964587 -266.350587)
			(xy 95.934563 -266.30655) (xy 95.911437 -266.258529) (xy 95.895727 -266.207599) (xy 95.887784 -266.154895)
			(xy 95.659204 -266.154895) (xy 95.651261 -266.207599) (xy 95.635551 -266.258529) (xy 95.612425 -266.30655)
			(xy 95.582401 -266.350587) (xy 95.546149 -266.389658) (xy 95.504478 -266.422889) (xy 95.45832 -266.449538)
			(xy 95.408706 -266.46901) (xy 95.356744 -266.48087) (xy 95.303594 -266.484854) (xy 95.250444 -266.48087)
			(xy 95.198482 -266.46901) (xy 95.148868 -266.449538) (xy 95.10271 -266.422889) (xy 95.061039 -266.389658)
			(xy 95.024787 -266.350587) (xy 94.994763 -266.30655) (xy 94.971637 -266.258529) (xy 94.955927 -266.207599)
			(xy 94.947984 -266.154895) (xy 94.719404 -266.154895) (xy 94.711461 -266.207599) (xy 94.695751 -266.258529)
			(xy 94.672625 -266.30655) (xy 94.642601 -266.350587) (xy 94.606349 -266.389658) (xy 94.564678 -266.422889)
			(xy 94.51852 -266.449538) (xy 94.468906 -266.46901) (xy 94.416944 -266.48087) (xy 94.363794 -266.484854)
			(xy 94.310644 -266.48087) (xy 94.258682 -266.46901) (xy 94.209068 -266.449538) (xy 94.16291 -266.422889)
			(xy 94.121239 -266.389658) (xy 94.084987 -266.350587) (xy 94.054963 -266.30655) (xy 94.031837 -266.258529)
			(xy 94.016127 -266.207599) (xy 94.008184 -266.154895) (xy 93.779604 -266.154895) (xy 93.771661 -266.207599)
			(xy 93.755951 -266.258529) (xy 93.732825 -266.30655) (xy 93.702801 -266.350587) (xy 93.666549 -266.389658)
			(xy 93.624878 -266.422889) (xy 93.57872 -266.449538) (xy 93.529106 -266.46901) (xy 93.477144 -266.48087)
			(xy 93.423994 -266.484854) (xy 93.370844 -266.48087) (xy 93.318882 -266.46901) (xy 93.269268 -266.449538)
			(xy 93.22311 -266.422889) (xy 93.181439 -266.389658) (xy 93.145187 -266.350587) (xy 93.115163 -266.30655)
			(xy 93.092037 -266.258529) (xy 93.076327 -266.207599) (xy 93.068384 -266.154895) (xy 92.839804 -266.154895)
			(xy 92.831861 -266.207599) (xy 92.816151 -266.258529) (xy 92.793025 -266.30655) (xy 92.763001 -266.350587)
			(xy 92.726749 -266.389658) (xy 92.685078 -266.422889) (xy 92.63892 -266.449538) (xy 92.589306 -266.46901)
			(xy 92.537344 -266.48087) (xy 92.484194 -266.484854) (xy 92.431044 -266.48087) (xy 92.379082 -266.46901)
			(xy 92.329468 -266.449538) (xy 92.28331 -266.422889) (xy 92.241639 -266.389658) (xy 92.205387 -266.350587)
			(xy 92.175363 -266.30655) (xy 92.152237 -266.258529) (xy 92.136527 -266.207599) (xy 92.128584 -266.154895)
			(xy 91.900004 -266.154895) (xy 91.892061 -266.207599) (xy 91.876351 -266.258529) (xy 91.853225 -266.30655)
			(xy 91.823201 -266.350587) (xy 91.786949 -266.389658) (xy 91.745278 -266.422889) (xy 91.69912 -266.449538)
			(xy 91.649506 -266.46901) (xy 91.597544 -266.48087) (xy 91.544394 -266.484854) (xy 91.491244 -266.48087)
			(xy 91.439282 -266.46901) (xy 91.389668 -266.449538) (xy 91.34351 -266.422889) (xy 91.301839 -266.389658)
			(xy 91.265587 -266.350587) (xy 91.235563 -266.30655) (xy 91.212437 -266.258529) (xy 91.196727 -266.207599)
			(xy 91.188784 -266.154895) (xy 90.960204 -266.154895) (xy 90.952261 -266.207599) (xy 90.936551 -266.258529)
			(xy 90.913425 -266.30655) (xy 90.883401 -266.350587) (xy 90.847149 -266.389658) (xy 90.805478 -266.422889)
			(xy 90.75932 -266.449538) (xy 90.709706 -266.46901) (xy 90.657744 -266.48087) (xy 90.604594 -266.484854)
			(xy 90.551444 -266.48087) (xy 90.499482 -266.46901) (xy 90.449868 -266.449538) (xy 90.40371 -266.422889)
			(xy 90.362039 -266.389658) (xy 90.325787 -266.350587) (xy 90.295763 -266.30655) (xy 90.272637 -266.258529)
			(xy 90.256927 -266.207599) (xy 90.248984 -266.154895) (xy 90.020404 -266.154895) (xy 90.012461 -266.207599)
			(xy 89.996751 -266.258529) (xy 89.973625 -266.30655) (xy 89.943601 -266.350587) (xy 89.907349 -266.389658)
			(xy 89.865678 -266.422889) (xy 89.81952 -266.449538) (xy 89.769906 -266.46901) (xy 89.717944 -266.48087)
			(xy 89.664794 -266.484854) (xy 89.611644 -266.48087) (xy 89.559682 -266.46901) (xy 89.510068 -266.449538)
			(xy 89.46391 -266.422889) (xy 89.422239 -266.389658) (xy 89.385987 -266.350587) (xy 89.355963 -266.30655)
			(xy 89.332837 -266.258529) (xy 89.317127 -266.207599) (xy 89.309184 -266.154895) (xy 89.080525 -266.154895)
			(xy 89.080525 -266.155557) (xy 89.072155 -266.209624) (xy 89.055612 -266.261774) (xy 89.031286 -266.31078)
			(xy 88.999749 -266.355487) (xy 88.961744 -266.394843) (xy 88.918166 -266.427922) (xy 88.87004 -266.453945)
			(xy 88.8185 -266.472299) (xy 88.764758 -266.482552) (xy 88.73744 -266.4841) (xy 88.727673 -266.484886)
			(xy 88.709792 -266.492855) (xy 88.696205 -266.506949) (xy 88.688897 -266.525111) (xy 88.688418 -266.5349)
			(xy 88.688418 -266.968457) (xy 88.839284 -266.968457) (xy 88.839284 -266.915159) (xy 88.847227 -266.862455)
			(xy 88.862937 -266.811525) (xy 88.886063 -266.763504) (xy 88.916087 -266.719467) (xy 88.952339 -266.680396)
			(xy 88.99401 -266.647165) (xy 89.040168 -266.620516) (xy 89.089782 -266.601044) (xy 89.141744 -266.589184)
			(xy 89.194894 -266.585201) (xy 89.248044 -266.589184) (xy 89.300006 -266.601044) (xy 89.34962 -266.620516)
			(xy 89.395778 -266.647165) (xy 89.437449 -266.680396) (xy 89.473701 -266.719467) (xy 89.503725 -266.763504)
			(xy 89.526851 -266.811525) (xy 89.542561 -266.862455) (xy 89.550504 -266.915159) (xy 89.551002 -266.941808)
			(xy 89.550504 -266.968457) (xy 89.779084 -266.968457) (xy 89.779084 -266.915159) (xy 89.787027 -266.862455)
			(xy 89.802737 -266.811525) (xy 89.825863 -266.763504) (xy 89.855887 -266.719467) (xy 89.892139 -266.680396)
			(xy 89.93381 -266.647165) (xy 89.979968 -266.620516) (xy 90.029582 -266.601044) (xy 90.081544 -266.589184)
			(xy 90.134694 -266.585201) (xy 90.187844 -266.589184) (xy 90.239806 -266.601044) (xy 90.28942 -266.620516)
			(xy 90.335578 -266.647165) (xy 90.377249 -266.680396) (xy 90.413501 -266.719467) (xy 90.443525 -266.763504)
			(xy 90.466651 -266.811525) (xy 90.482361 -266.862455) (xy 90.490304 -266.915159) (xy 90.490802 -266.941808)
			(xy 90.490304 -266.968457) (xy 90.718884 -266.968457) (xy 90.718884 -266.915159) (xy 90.726827 -266.862455)
			(xy 90.742537 -266.811525) (xy 90.765663 -266.763504) (xy 90.795687 -266.719467) (xy 90.831939 -266.680396)
			(xy 90.87361 -266.647165) (xy 90.919768 -266.620516) (xy 90.969382 -266.601044) (xy 91.021344 -266.589184)
			(xy 91.074494 -266.585201) (xy 91.127644 -266.589184) (xy 91.179606 -266.601044) (xy 91.22922 -266.620516)
			(xy 91.275378 -266.647165) (xy 91.317049 -266.680396) (xy 91.353301 -266.719467) (xy 91.383325 -266.763504)
			(xy 91.406451 -266.811525) (xy 91.422161 -266.862455) (xy 91.430104 -266.915159) (xy 91.430602 -266.941808)
			(xy 91.430104 -266.968457) (xy 91.658938 -266.968457) (xy 91.658938 -266.915159) (xy 91.666881 -266.862455)
			(xy 91.682591 -266.811525) (xy 91.705717 -266.763504) (xy 91.735741 -266.719467) (xy 91.771993 -266.680396)
			(xy 91.813664 -266.647165) (xy 91.859822 -266.620516) (xy 91.909436 -266.601044) (xy 91.961398 -266.589184)
			(xy 92.014548 -266.585201) (xy 92.067698 -266.589184) (xy 92.11966 -266.601044) (xy 92.169274 -266.620516)
			(xy 92.215432 -266.647165) (xy 92.257103 -266.680396) (xy 92.293355 -266.719467) (xy 92.323379 -266.763504)
			(xy 92.346505 -266.811525) (xy 92.362215 -266.862455) (xy 92.370158 -266.915159) (xy 92.370656 -266.941808)
			(xy 92.370158 -266.968457) (xy 92.598738 -266.968457) (xy 92.598738 -266.915159) (xy 92.606681 -266.862455)
			(xy 92.622391 -266.811525) (xy 92.645517 -266.763504) (xy 92.675541 -266.719467) (xy 92.711793 -266.680396)
			(xy 92.753464 -266.647165) (xy 92.799622 -266.620516) (xy 92.849236 -266.601044) (xy 92.901198 -266.589184)
			(xy 92.954348 -266.585201) (xy 93.007498 -266.589184) (xy 93.05946 -266.601044) (xy 93.109074 -266.620516)
			(xy 93.155232 -266.647165) (xy 93.196903 -266.680396) (xy 93.233155 -266.719467) (xy 93.263179 -266.763504)
			(xy 93.286305 -266.811525) (xy 93.302015 -266.862455) (xy 93.309958 -266.915159) (xy 93.310456 -266.941808)
			(xy 93.309958 -266.968457) (xy 93.538538 -266.968457) (xy 93.538538 -266.915159) (xy 93.546481 -266.862455)
			(xy 93.562191 -266.811525) (xy 93.585317 -266.763504) (xy 93.615341 -266.719467) (xy 93.651593 -266.680396)
			(xy 93.693264 -266.647165) (xy 93.739422 -266.620516) (xy 93.789036 -266.601044) (xy 93.840998 -266.589184)
			(xy 93.894148 -266.585201) (xy 93.947298 -266.589184) (xy 93.99926 -266.601044) (xy 94.048874 -266.620516)
			(xy 94.095032 -266.647165) (xy 94.136703 -266.680396) (xy 94.172955 -266.719467) (xy 94.202979 -266.763504)
			(xy 94.226105 -266.811525) (xy 94.241815 -266.862455) (xy 94.249758 -266.915159) (xy 94.250256 -266.941808)
			(xy 94.249758 -266.968457) (xy 94.478338 -266.968457) (xy 94.478338 -266.915159) (xy 94.486281 -266.862455)
			(xy 94.501991 -266.811525) (xy 94.525117 -266.763504) (xy 94.555141 -266.719467) (xy 94.591393 -266.680396)
			(xy 94.633064 -266.647165) (xy 94.679222 -266.620516) (xy 94.728836 -266.601044) (xy 94.780798 -266.589184)
			(xy 94.833948 -266.585201) (xy 94.887098 -266.589184) (xy 94.93906 -266.601044) (xy 94.988674 -266.620516)
			(xy 95.034832 -266.647165) (xy 95.076503 -266.680396) (xy 95.112755 -266.719467) (xy 95.142779 -266.763504)
			(xy 95.165905 -266.811525) (xy 95.181615 -266.862455) (xy 95.189558 -266.915159) (xy 95.190056 -266.941808)
			(xy 95.189558 -266.968457) (xy 95.418138 -266.968457) (xy 95.418138 -266.915159) (xy 95.426081 -266.862455)
			(xy 95.441791 -266.811525) (xy 95.464917 -266.763504) (xy 95.494941 -266.719467) (xy 95.531193 -266.680396)
			(xy 95.572864 -266.647165) (xy 95.619022 -266.620516) (xy 95.668636 -266.601044) (xy 95.720598 -266.589184)
			(xy 95.773748 -266.585201) (xy 95.826898 -266.589184) (xy 95.87886 -266.601044) (xy 95.928474 -266.620516)
			(xy 95.974632 -266.647165) (xy 96.016303 -266.680396) (xy 96.052555 -266.719467) (xy 96.082579 -266.763504)
			(xy 96.105705 -266.811525) (xy 96.121415 -266.862455) (xy 96.129358 -266.915159) (xy 96.129856 -266.941808)
			(xy 96.129358 -266.968457) (xy 96.357938 -266.968457) (xy 96.357938 -266.915159) (xy 96.365881 -266.862455)
			(xy 96.381591 -266.811525) (xy 96.404717 -266.763504) (xy 96.434741 -266.719467) (xy 96.470993 -266.680396)
			(xy 96.512664 -266.647165) (xy 96.558822 -266.620516) (xy 96.608436 -266.601044) (xy 96.660398 -266.589184)
			(xy 96.713548 -266.585201) (xy 96.766698 -266.589184) (xy 96.81866 -266.601044) (xy 96.868274 -266.620516)
			(xy 96.914432 -266.647165) (xy 96.956103 -266.680396) (xy 96.992355 -266.719467) (xy 97.022379 -266.763504)
			(xy 97.045505 -266.811525) (xy 97.061215 -266.862455) (xy 97.069158 -266.915159) (xy 97.069656 -266.941808)
			(xy 97.069158 -266.968457) (xy 97.297484 -266.968457) (xy 97.297484 -266.915159) (xy 97.305427 -266.862455)
			(xy 97.321137 -266.811525) (xy 97.344263 -266.763504) (xy 97.374287 -266.719467) (xy 97.410539 -266.680396)
			(xy 97.45221 -266.647165) (xy 97.498368 -266.620516) (xy 97.547982 -266.601044) (xy 97.599944 -266.589184)
			(xy 97.653094 -266.585201) (xy 97.706244 -266.589184) (xy 97.758206 -266.601044) (xy 97.80782 -266.620516)
			(xy 97.853978 -266.647165) (xy 97.895649 -266.680396) (xy 97.931901 -266.719467) (xy 97.961925 -266.763504)
			(xy 97.985051 -266.811525) (xy 98.000761 -266.862455) (xy 98.008704 -266.915159) (xy 98.009202 -266.941808)
			(xy 98.008704 -266.968457) (xy 98.237538 -266.968457) (xy 98.237538 -266.915159) (xy 98.245481 -266.862455)
			(xy 98.261191 -266.811525) (xy 98.284317 -266.763504) (xy 98.314341 -266.719467) (xy 98.350593 -266.680396)
			(xy 98.392264 -266.647165) (xy 98.438422 -266.620516) (xy 98.488036 -266.601044) (xy 98.539998 -266.589184)
			(xy 98.593148 -266.585201) (xy 98.646298 -266.589184) (xy 98.69826 -266.601044) (xy 98.747874 -266.620516)
			(xy 98.794032 -266.647165) (xy 98.835703 -266.680396) (xy 98.871955 -266.719467) (xy 98.901979 -266.763504)
			(xy 98.925105 -266.811525) (xy 98.940815 -266.862455) (xy 98.948758 -266.915159) (xy 98.949256 -266.941808)
			(xy 98.948758 -266.968457) (xy 99.177338 -266.968457) (xy 99.177338 -266.915159) (xy 99.185281 -266.862455)
			(xy 99.200991 -266.811525) (xy 99.224117 -266.763504) (xy 99.254141 -266.719467) (xy 99.290393 -266.680396)
			(xy 99.332064 -266.647165) (xy 99.378222 -266.620516) (xy 99.427836 -266.601044) (xy 99.479798 -266.589184)
			(xy 99.532948 -266.585201) (xy 99.586098 -266.589184) (xy 99.63806 -266.601044) (xy 99.687674 -266.620516)
			(xy 99.733832 -266.647165) (xy 99.775503 -266.680396) (xy 99.811755 -266.719467) (xy 99.841779 -266.763504)
			(xy 99.864905 -266.811525) (xy 99.880615 -266.862455) (xy 99.888558 -266.915159) (xy 99.889056 -266.941808)
			(xy 99.888558 -266.968457) (xy 100.117138 -266.968457) (xy 100.117138 -266.915159) (xy 100.125081 -266.862455)
			(xy 100.140791 -266.811525) (xy 100.163917 -266.763504) (xy 100.193941 -266.719467) (xy 100.230193 -266.680396)
			(xy 100.271864 -266.647165) (xy 100.318022 -266.620516) (xy 100.367636 -266.601044) (xy 100.419598 -266.589184)
			(xy 100.472748 -266.585201) (xy 100.525898 -266.589184) (xy 100.57786 -266.601044) (xy 100.627474 -266.620516)
			(xy 100.673632 -266.647165) (xy 100.715303 -266.680396) (xy 100.751555 -266.719467) (xy 100.781579 -266.763504)
			(xy 100.804705 -266.811525) (xy 100.820415 -266.862455) (xy 100.828358 -266.915159) (xy 100.828856 -266.941808)
			(xy 100.828358 -266.968457) (xy 101.056938 -266.968457) (xy 101.056938 -266.915159) (xy 101.064881 -266.862455)
			(xy 101.080591 -266.811525) (xy 101.103717 -266.763504) (xy 101.133741 -266.719467) (xy 101.169993 -266.680396)
			(xy 101.211664 -266.647165) (xy 101.257822 -266.620516) (xy 101.307436 -266.601044) (xy 101.359398 -266.589184)
			(xy 101.412548 -266.585201) (xy 101.465698 -266.589184) (xy 101.51766 -266.601044) (xy 101.567274 -266.620516)
			(xy 101.613432 -266.647165) (xy 101.655103 -266.680396) (xy 101.691355 -266.719467) (xy 101.721379 -266.763504)
			(xy 101.744505 -266.811525) (xy 101.760215 -266.862455) (xy 101.768158 -266.915159) (xy 101.768656 -266.941808)
			(xy 101.768158 -266.968457) (xy 101.996738 -266.968457) (xy 101.996738 -266.915159) (xy 102.004681 -266.862455)
			(xy 102.020391 -266.811525) (xy 102.043517 -266.763504) (xy 102.073541 -266.719467) (xy 102.109793 -266.680396)
			(xy 102.151464 -266.647165) (xy 102.197622 -266.620516) (xy 102.247236 -266.601044) (xy 102.299198 -266.589184)
			(xy 102.352348 -266.585201) (xy 102.405498 -266.589184) (xy 102.45746 -266.601044) (xy 102.507074 -266.620516)
			(xy 102.553232 -266.647165) (xy 102.594903 -266.680396) (xy 102.631155 -266.719467) (xy 102.661179 -266.763504)
			(xy 102.684305 -266.811525) (xy 102.700015 -266.862455) (xy 102.707958 -266.915159) (xy 102.708456 -266.941808)
			(xy 102.707958 -266.968457) (xy 102.936538 -266.968457) (xy 102.936538 -266.915159) (xy 102.944481 -266.862455)
			(xy 102.960191 -266.811525) (xy 102.983317 -266.763504) (xy 103.013341 -266.719467) (xy 103.049593 -266.680396)
			(xy 103.091264 -266.647165) (xy 103.137422 -266.620516) (xy 103.187036 -266.601044) (xy 103.238998 -266.589184)
			(xy 103.292148 -266.585201) (xy 103.345298 -266.589184) (xy 103.39726 -266.601044) (xy 103.446874 -266.620516)
			(xy 103.493032 -266.647165) (xy 103.534703 -266.680396) (xy 103.570955 -266.719467) (xy 103.600979 -266.763504)
			(xy 103.624105 -266.811525) (xy 103.639815 -266.862455) (xy 103.647758 -266.915159) (xy 103.648256 -266.941808)
			(xy 103.647758 -266.968457) (xy 103.876084 -266.968457) (xy 103.876084 -266.915159) (xy 103.884027 -266.862455)
			(xy 103.899737 -266.811525) (xy 103.922863 -266.763504) (xy 103.952887 -266.719467) (xy 103.989139 -266.680396)
			(xy 104.03081 -266.647165) (xy 104.076968 -266.620516) (xy 104.126582 -266.601044) (xy 104.178544 -266.589184)
			(xy 104.231694 -266.585201) (xy 104.284844 -266.589184) (xy 104.336806 -266.601044) (xy 104.38642 -266.620516)
			(xy 104.432578 -266.647165) (xy 104.474249 -266.680396) (xy 104.510501 -266.719467) (xy 104.540525 -266.763504)
			(xy 104.563651 -266.811525) (xy 104.579361 -266.862455) (xy 104.587304 -266.915159) (xy 104.587802 -266.941808)
			(xy 104.587304 -266.968457) (xy 104.81563 -266.968457) (xy 104.81563 -266.915159) (xy 104.823573 -266.862455)
			(xy 104.839283 -266.811525) (xy 104.862409 -266.763504) (xy 104.892433 -266.719467) (xy 104.928685 -266.680396)
			(xy 104.970356 -266.647165) (xy 105.016514 -266.620516) (xy 105.066128 -266.601044) (xy 105.11809 -266.589184)
			(xy 105.17124 -266.585201) (xy 105.22439 -266.589184) (xy 105.276352 -266.601044) (xy 105.325966 -266.620516)
			(xy 105.372124 -266.647165) (xy 105.413795 -266.680396) (xy 105.450047 -266.719467) (xy 105.480071 -266.763504)
			(xy 105.503197 -266.811525) (xy 105.518907 -266.862455) (xy 105.52685 -266.915159) (xy 105.527348 -266.941808)
			(xy 105.52685 -266.968457) (xy 105.755684 -266.968457) (xy 105.755684 -266.915159) (xy 105.763627 -266.862455)
			(xy 105.779337 -266.811525) (xy 105.802463 -266.763504) (xy 105.832487 -266.719467) (xy 105.868739 -266.680396)
			(xy 105.91041 -266.647165) (xy 105.956568 -266.620516) (xy 106.006182 -266.601044) (xy 106.058144 -266.589184)
			(xy 106.111294 -266.585201) (xy 106.164444 -266.589184) (xy 106.216406 -266.601044) (xy 106.26602 -266.620516)
			(xy 106.312178 -266.647165) (xy 106.353849 -266.680396) (xy 106.390101 -266.719467) (xy 106.420125 -266.763504)
			(xy 106.443251 -266.811525) (xy 106.458961 -266.862455) (xy 106.466904 -266.915159) (xy 106.467402 -266.941808)
			(xy 106.466904 -266.968457) (xy 106.695738 -266.968457) (xy 106.695738 -266.915159) (xy 106.703681 -266.862455)
			(xy 106.719391 -266.811525) (xy 106.742517 -266.763504) (xy 106.772541 -266.719467) (xy 106.808793 -266.680396)
			(xy 106.850464 -266.647165) (xy 106.896622 -266.620516) (xy 106.946236 -266.601044) (xy 106.998198 -266.589184)
			(xy 107.051348 -266.585201) (xy 107.104498 -266.589184) (xy 107.15646 -266.601044) (xy 107.206074 -266.620516)
			(xy 107.252232 -266.647165) (xy 107.293903 -266.680396) (xy 107.330155 -266.719467) (xy 107.360179 -266.763504)
			(xy 107.383305 -266.811525) (xy 107.399015 -266.862455) (xy 107.406958 -266.915159) (xy 107.407456 -266.941808)
			(xy 107.406958 -266.968457) (xy 107.635538 -266.968457) (xy 107.635538 -266.915159) (xy 107.643481 -266.862455)
			(xy 107.659191 -266.811525) (xy 107.682317 -266.763504) (xy 107.712341 -266.719467) (xy 107.748593 -266.680396)
			(xy 107.790264 -266.647165) (xy 107.836422 -266.620516) (xy 107.886036 -266.601044) (xy 107.937998 -266.589184)
			(xy 107.991148 -266.585201) (xy 108.044298 -266.589184) (xy 108.09626 -266.601044) (xy 108.145874 -266.620516)
			(xy 108.192032 -266.647165) (xy 108.233703 -266.680396) (xy 108.269955 -266.719467) (xy 108.299979 -266.763504)
			(xy 108.323105 -266.811525) (xy 108.338815 -266.862455) (xy 108.346758 -266.915159) (xy 108.347256 -266.941808)
			(xy 108.346758 -266.968457) (xy 108.338815 -267.021161) (xy 108.323105 -267.072091) (xy 108.299979 -267.120112)
			(xy 108.269955 -267.164149) (xy 108.233703 -267.20322) (xy 108.192032 -267.236451) (xy 108.145874 -267.2631)
			(xy 108.09626 -267.282572) (xy 108.044298 -267.294432) (xy 107.991148 -267.298416) (xy 107.937998 -267.294432)
			(xy 107.886036 -267.282572) (xy 107.836422 -267.2631) (xy 107.790264 -267.236451) (xy 107.748593 -267.20322)
			(xy 107.712341 -267.164149) (xy 107.682317 -267.120112) (xy 107.659191 -267.072091) (xy 107.643481 -267.021161)
			(xy 107.635538 -266.968457) (xy 107.406958 -266.968457) (xy 107.399015 -267.021161) (xy 107.383305 -267.072091)
			(xy 107.360179 -267.120112) (xy 107.330155 -267.164149) (xy 107.293903 -267.20322) (xy 107.252232 -267.236451)
			(xy 107.206074 -267.2631) (xy 107.15646 -267.282572) (xy 107.104498 -267.294432) (xy 107.051348 -267.298416)
			(xy 106.998198 -267.294432) (xy 106.946236 -267.282572) (xy 106.896622 -267.2631) (xy 106.850464 -267.236451)
			(xy 106.808793 -267.20322) (xy 106.772541 -267.164149) (xy 106.742517 -267.120112) (xy 106.719391 -267.072091)
			(xy 106.703681 -267.021161) (xy 106.695738 -266.968457) (xy 106.466904 -266.968457) (xy 106.458961 -267.021161)
			(xy 106.443251 -267.072091) (xy 106.420125 -267.120112) (xy 106.390101 -267.164149) (xy 106.353849 -267.20322)
			(xy 106.312178 -267.236451) (xy 106.26602 -267.2631) (xy 106.216406 -267.282572) (xy 106.164444 -267.294432)
			(xy 106.111294 -267.298416) (xy 106.058144 -267.294432) (xy 106.006182 -267.282572) (xy 105.956568 -267.2631)
			(xy 105.91041 -267.236451) (xy 105.868739 -267.20322) (xy 105.832487 -267.164149) (xy 105.802463 -267.120112)
			(xy 105.779337 -267.072091) (xy 105.763627 -267.021161) (xy 105.755684 -266.968457) (xy 105.52685 -266.968457)
			(xy 105.518907 -267.021161) (xy 105.503197 -267.072091) (xy 105.480071 -267.120112) (xy 105.450047 -267.164149)
			(xy 105.413795 -267.20322) (xy 105.372124 -267.236451) (xy 105.325966 -267.2631) (xy 105.276352 -267.282572)
			(xy 105.22439 -267.294432) (xy 105.17124 -267.298416) (xy 105.11809 -267.294432) (xy 105.066128 -267.282572)
			(xy 105.016514 -267.2631) (xy 104.970356 -267.236451) (xy 104.928685 -267.20322) (xy 104.892433 -267.164149)
			(xy 104.862409 -267.120112) (xy 104.839283 -267.072091) (xy 104.823573 -267.021161) (xy 104.81563 -266.968457)
			(xy 104.587304 -266.968457) (xy 104.579361 -267.021161) (xy 104.563651 -267.072091) (xy 104.540525 -267.120112)
			(xy 104.510501 -267.164149) (xy 104.474249 -267.20322) (xy 104.432578 -267.236451) (xy 104.38642 -267.2631)
			(xy 104.336806 -267.282572) (xy 104.284844 -267.294432) (xy 104.231694 -267.298416) (xy 104.178544 -267.294432)
			(xy 104.126582 -267.282572) (xy 104.076968 -267.2631) (xy 104.03081 -267.236451) (xy 103.989139 -267.20322)
			(xy 103.952887 -267.164149) (xy 103.922863 -267.120112) (xy 103.899737 -267.072091) (xy 103.884027 -267.021161)
			(xy 103.876084 -266.968457) (xy 103.647758 -266.968457) (xy 103.639815 -267.021161) (xy 103.624105 -267.072091)
			(xy 103.600979 -267.120112) (xy 103.570955 -267.164149) (xy 103.534703 -267.20322) (xy 103.493032 -267.236451)
			(xy 103.446874 -267.2631) (xy 103.39726 -267.282572) (xy 103.345298 -267.294432) (xy 103.292148 -267.298416)
			(xy 103.238998 -267.294432) (xy 103.187036 -267.282572) (xy 103.137422 -267.2631) (xy 103.091264 -267.236451)
			(xy 103.049593 -267.20322) (xy 103.013341 -267.164149) (xy 102.983317 -267.120112) (xy 102.960191 -267.072091)
			(xy 102.944481 -267.021161) (xy 102.936538 -266.968457) (xy 102.707958 -266.968457) (xy 102.700015 -267.021161)
			(xy 102.684305 -267.072091) (xy 102.661179 -267.120112) (xy 102.631155 -267.164149) (xy 102.594903 -267.20322)
			(xy 102.553232 -267.236451) (xy 102.507074 -267.2631) (xy 102.45746 -267.282572) (xy 102.405498 -267.294432)
			(xy 102.352348 -267.298416) (xy 102.299198 -267.294432) (xy 102.247236 -267.282572) (xy 102.197622 -267.2631)
			(xy 102.151464 -267.236451) (xy 102.109793 -267.20322) (xy 102.073541 -267.164149) (xy 102.043517 -267.120112)
			(xy 102.020391 -267.072091) (xy 102.004681 -267.021161) (xy 101.996738 -266.968457) (xy 101.768158 -266.968457)
			(xy 101.760215 -267.021161) (xy 101.744505 -267.072091) (xy 101.721379 -267.120112) (xy 101.691355 -267.164149)
			(xy 101.655103 -267.20322) (xy 101.613432 -267.236451) (xy 101.567274 -267.2631) (xy 101.51766 -267.282572)
			(xy 101.465698 -267.294432) (xy 101.412548 -267.298416) (xy 101.359398 -267.294432) (xy 101.307436 -267.282572)
			(xy 101.257822 -267.2631) (xy 101.211664 -267.236451) (xy 101.169993 -267.20322) (xy 101.133741 -267.164149)
			(xy 101.103717 -267.120112) (xy 101.080591 -267.072091) (xy 101.064881 -267.021161) (xy 101.056938 -266.968457)
			(xy 100.828358 -266.968457) (xy 100.820415 -267.021161) (xy 100.804705 -267.072091) (xy 100.781579 -267.120112)
			(xy 100.751555 -267.164149) (xy 100.715303 -267.20322) (xy 100.673632 -267.236451) (xy 100.627474 -267.2631)
			(xy 100.57786 -267.282572) (xy 100.525898 -267.294432) (xy 100.472748 -267.298416) (xy 100.419598 -267.294432)
			(xy 100.367636 -267.282572) (xy 100.318022 -267.2631) (xy 100.271864 -267.236451) (xy 100.230193 -267.20322)
			(xy 100.193941 -267.164149) (xy 100.163917 -267.120112) (xy 100.140791 -267.072091) (xy 100.125081 -267.021161)
			(xy 100.117138 -266.968457) (xy 99.888558 -266.968457) (xy 99.880615 -267.021161) (xy 99.864905 -267.072091)
			(xy 99.841779 -267.120112) (xy 99.811755 -267.164149) (xy 99.775503 -267.20322) (xy 99.733832 -267.236451)
			(xy 99.687674 -267.2631) (xy 99.63806 -267.282572) (xy 99.586098 -267.294432) (xy 99.532948 -267.298416)
			(xy 99.479798 -267.294432) (xy 99.427836 -267.282572) (xy 99.378222 -267.2631) (xy 99.332064 -267.236451)
			(xy 99.290393 -267.20322) (xy 99.254141 -267.164149) (xy 99.224117 -267.120112) (xy 99.200991 -267.072091)
			(xy 99.185281 -267.021161) (xy 99.177338 -266.968457) (xy 98.948758 -266.968457) (xy 98.940815 -267.021161)
			(xy 98.925105 -267.072091) (xy 98.901979 -267.120112) (xy 98.871955 -267.164149) (xy 98.835703 -267.20322)
			(xy 98.794032 -267.236451) (xy 98.747874 -267.2631) (xy 98.69826 -267.282572) (xy 98.646298 -267.294432)
			(xy 98.593148 -267.298416) (xy 98.539998 -267.294432) (xy 98.488036 -267.282572) (xy 98.438422 -267.2631)
			(xy 98.392264 -267.236451) (xy 98.350593 -267.20322) (xy 98.314341 -267.164149) (xy 98.284317 -267.120112)
			(xy 98.261191 -267.072091) (xy 98.245481 -267.021161) (xy 98.237538 -266.968457) (xy 98.008704 -266.968457)
			(xy 98.000761 -267.021161) (xy 97.985051 -267.072091) (xy 97.961925 -267.120112) (xy 97.931901 -267.164149)
			(xy 97.895649 -267.20322) (xy 97.853978 -267.236451) (xy 97.80782 -267.2631) (xy 97.758206 -267.282572)
			(xy 97.706244 -267.294432) (xy 97.653094 -267.298416) (xy 97.599944 -267.294432) (xy 97.547982 -267.282572)
			(xy 97.498368 -267.2631) (xy 97.45221 -267.236451) (xy 97.410539 -267.20322) (xy 97.374287 -267.164149)
			(xy 97.344263 -267.120112) (xy 97.321137 -267.072091) (xy 97.305427 -267.021161) (xy 97.297484 -266.968457)
			(xy 97.069158 -266.968457) (xy 97.061215 -267.021161) (xy 97.045505 -267.072091) (xy 97.022379 -267.120112)
			(xy 96.992355 -267.164149) (xy 96.956103 -267.20322) (xy 96.914432 -267.236451) (xy 96.868274 -267.2631)
			(xy 96.81866 -267.282572) (xy 96.766698 -267.294432) (xy 96.713548 -267.298416) (xy 96.660398 -267.294432)
			(xy 96.608436 -267.282572) (xy 96.558822 -267.2631) (xy 96.512664 -267.236451) (xy 96.470993 -267.20322)
			(xy 96.434741 -267.164149) (xy 96.404717 -267.120112) (xy 96.381591 -267.072091) (xy 96.365881 -267.021161)
			(xy 96.357938 -266.968457) (xy 96.129358 -266.968457) (xy 96.121415 -267.021161) (xy 96.105705 -267.072091)
			(xy 96.082579 -267.120112) (xy 96.052555 -267.164149) (xy 96.016303 -267.20322) (xy 95.974632 -267.236451)
			(xy 95.928474 -267.2631) (xy 95.87886 -267.282572) (xy 95.826898 -267.294432) (xy 95.773748 -267.298416)
			(xy 95.720598 -267.294432) (xy 95.668636 -267.282572) (xy 95.619022 -267.2631) (xy 95.572864 -267.236451)
			(xy 95.531193 -267.20322) (xy 95.494941 -267.164149) (xy 95.464917 -267.120112) (xy 95.441791 -267.072091)
			(xy 95.426081 -267.021161) (xy 95.418138 -266.968457) (xy 95.189558 -266.968457) (xy 95.181615 -267.021161)
			(xy 95.165905 -267.072091) (xy 95.142779 -267.120112) (xy 95.112755 -267.164149) (xy 95.076503 -267.20322)
			(xy 95.034832 -267.236451) (xy 94.988674 -267.2631) (xy 94.93906 -267.282572) (xy 94.887098 -267.294432)
			(xy 94.833948 -267.298416) (xy 94.780798 -267.294432) (xy 94.728836 -267.282572) (xy 94.679222 -267.2631)
			(xy 94.633064 -267.236451) (xy 94.591393 -267.20322) (xy 94.555141 -267.164149) (xy 94.525117 -267.120112)
			(xy 94.501991 -267.072091) (xy 94.486281 -267.021161) (xy 94.478338 -266.968457) (xy 94.249758 -266.968457)
			(xy 94.241815 -267.021161) (xy 94.226105 -267.072091) (xy 94.202979 -267.120112) (xy 94.172955 -267.164149)
			(xy 94.136703 -267.20322) (xy 94.095032 -267.236451) (xy 94.048874 -267.2631) (xy 93.99926 -267.282572)
			(xy 93.947298 -267.294432) (xy 93.894148 -267.298416) (xy 93.840998 -267.294432) (xy 93.789036 -267.282572)
			(xy 93.739422 -267.2631) (xy 93.693264 -267.236451) (xy 93.651593 -267.20322) (xy 93.615341 -267.164149)
			(xy 93.585317 -267.120112) (xy 93.562191 -267.072091) (xy 93.546481 -267.021161) (xy 93.538538 -266.968457)
			(xy 93.309958 -266.968457) (xy 93.302015 -267.021161) (xy 93.286305 -267.072091) (xy 93.263179 -267.120112)
			(xy 93.233155 -267.164149) (xy 93.196903 -267.20322) (xy 93.155232 -267.236451) (xy 93.109074 -267.2631)
			(xy 93.05946 -267.282572) (xy 93.007498 -267.294432) (xy 92.954348 -267.298416) (xy 92.901198 -267.294432)
			(xy 92.849236 -267.282572) (xy 92.799622 -267.2631) (xy 92.753464 -267.236451) (xy 92.711793 -267.20322)
			(xy 92.675541 -267.164149) (xy 92.645517 -267.120112) (xy 92.622391 -267.072091) (xy 92.606681 -267.021161)
			(xy 92.598738 -266.968457) (xy 92.370158 -266.968457) (xy 92.362215 -267.021161) (xy 92.346505 -267.072091)
			(xy 92.323379 -267.120112) (xy 92.293355 -267.164149) (xy 92.257103 -267.20322) (xy 92.215432 -267.236451)
			(xy 92.169274 -267.2631) (xy 92.11966 -267.282572) (xy 92.067698 -267.294432) (xy 92.014548 -267.298416)
			(xy 91.961398 -267.294432) (xy 91.909436 -267.282572) (xy 91.859822 -267.2631) (xy 91.813664 -267.236451)
			(xy 91.771993 -267.20322) (xy 91.735741 -267.164149) (xy 91.705717 -267.120112) (xy 91.682591 -267.072091)
			(xy 91.666881 -267.021161) (xy 91.658938 -266.968457) (xy 91.430104 -266.968457) (xy 91.422161 -267.021161)
			(xy 91.406451 -267.072091) (xy 91.383325 -267.120112) (xy 91.353301 -267.164149) (xy 91.317049 -267.20322)
			(xy 91.275378 -267.236451) (xy 91.22922 -267.2631) (xy 91.179606 -267.282572) (xy 91.127644 -267.294432)
			(xy 91.074494 -267.298416) (xy 91.021344 -267.294432) (xy 90.969382 -267.282572) (xy 90.919768 -267.2631)
			(xy 90.87361 -267.236451) (xy 90.831939 -267.20322) (xy 90.795687 -267.164149) (xy 90.765663 -267.120112)
			(xy 90.742537 -267.072091) (xy 90.726827 -267.021161) (xy 90.718884 -266.968457) (xy 90.490304 -266.968457)
			(xy 90.482361 -267.021161) (xy 90.466651 -267.072091) (xy 90.443525 -267.120112) (xy 90.413501 -267.164149)
			(xy 90.377249 -267.20322) (xy 90.335578 -267.236451) (xy 90.28942 -267.2631) (xy 90.239806 -267.282572)
			(xy 90.187844 -267.294432) (xy 90.134694 -267.298416) (xy 90.081544 -267.294432) (xy 90.029582 -267.282572)
			(xy 89.979968 -267.2631) (xy 89.93381 -267.236451) (xy 89.892139 -267.20322) (xy 89.855887 -267.164149)
			(xy 89.825863 -267.120112) (xy 89.802737 -267.072091) (xy 89.787027 -267.021161) (xy 89.779084 -266.968457)
			(xy 89.550504 -266.968457) (xy 89.542561 -267.021161) (xy 89.526851 -267.072091) (xy 89.503725 -267.120112)
			(xy 89.473701 -267.164149) (xy 89.437449 -267.20322) (xy 89.395778 -267.236451) (xy 89.34962 -267.2631)
			(xy 89.300006 -267.282572) (xy 89.248044 -267.294432) (xy 89.194894 -267.298416) (xy 89.141744 -267.294432)
			(xy 89.089782 -267.282572) (xy 89.040168 -267.2631) (xy 88.99401 -267.236451) (xy 88.952339 -267.20322)
			(xy 88.916087 -267.164149) (xy 88.886063 -267.120112) (xy 88.862937 -267.072091) (xy 88.847227 -267.021161)
			(xy 88.839284 -266.968457) (xy 88.688418 -266.968457) (xy 88.688418 -267.349224) (xy 88.688865 -267.359014)
			(xy 88.696199 -267.377169) (xy 88.709793 -267.391263) (xy 88.727672 -267.399247) (xy 88.73744 -267.400024)
			(xy 88.764767 -267.40148) (xy 88.818518 -267.411736) (xy 88.870069 -267.430093) (xy 88.918204 -267.456121)
			(xy 88.96179 -267.489207) (xy 88.999802 -267.528571) (xy 89.031345 -267.573286) (xy 89.055675 -267.622301)
			(xy 89.072221 -267.674461) (xy 89.080593 -267.728539) (xy 89.080593 -267.782527) (xy 89.309184 -267.782527)
			(xy 89.309184 -267.729229) (xy 89.317127 -267.676525) (xy 89.332837 -267.625595) (xy 89.355963 -267.577574)
			(xy 89.385987 -267.533537) (xy 89.422239 -267.494466) (xy 89.46391 -267.461235) (xy 89.510068 -267.434586)
			(xy 89.559682 -267.415114) (xy 89.611644 -267.403254) (xy 89.664794 -267.399271) (xy 89.717944 -267.403254)
			(xy 89.769906 -267.415114) (xy 89.81952 -267.434586) (xy 89.865678 -267.461235) (xy 89.907349 -267.494466)
			(xy 89.943601 -267.533537) (xy 89.973625 -267.577574) (xy 89.996751 -267.625595) (xy 90.012461 -267.676525)
			(xy 90.020404 -267.729229) (xy 90.020902 -267.755878) (xy 90.020404 -267.782527) (xy 90.249238 -267.782527)
			(xy 90.249238 -267.729229) (xy 90.257181 -267.676525) (xy 90.272891 -267.625595) (xy 90.296017 -267.577574)
			(xy 90.326041 -267.533537) (xy 90.362293 -267.494466) (xy 90.403964 -267.461235) (xy 90.450122 -267.434586)
			(xy 90.499736 -267.415114) (xy 90.551698 -267.403254) (xy 90.604848 -267.399271) (xy 90.657998 -267.403254)
			(xy 90.70996 -267.415114) (xy 90.759574 -267.434586) (xy 90.805732 -267.461235) (xy 90.847403 -267.494466)
			(xy 90.883655 -267.533537) (xy 90.913679 -267.577574) (xy 90.936805 -267.625595) (xy 90.952515 -267.676525)
			(xy 90.960458 -267.729229) (xy 90.960956 -267.755878) (xy 90.960458 -267.782527) (xy 91.188784 -267.782527)
			(xy 91.188784 -267.729229) (xy 91.196727 -267.676525) (xy 91.212437 -267.625595) (xy 91.235563 -267.577574)
			(xy 91.265587 -267.533537) (xy 91.301839 -267.494466) (xy 91.34351 -267.461235) (xy 91.389668 -267.434586)
			(xy 91.439282 -267.415114) (xy 91.491244 -267.403254) (xy 91.544394 -267.399271) (xy 91.597544 -267.403254)
			(xy 91.649506 -267.415114) (xy 91.69912 -267.434586) (xy 91.745278 -267.461235) (xy 91.786949 -267.494466)
			(xy 91.823201 -267.533537) (xy 91.853225 -267.577574) (xy 91.876351 -267.625595) (xy 91.892061 -267.676525)
			(xy 91.900004 -267.729229) (xy 91.900502 -267.755878) (xy 91.900004 -267.782527) (xy 92.128584 -267.782527)
			(xy 92.128584 -267.729229) (xy 92.136527 -267.676525) (xy 92.152237 -267.625595) (xy 92.175363 -267.577574)
			(xy 92.205387 -267.533537) (xy 92.241639 -267.494466) (xy 92.28331 -267.461235) (xy 92.329468 -267.434586)
			(xy 92.379082 -267.415114) (xy 92.431044 -267.403254) (xy 92.484194 -267.399271) (xy 92.537344 -267.403254)
			(xy 92.589306 -267.415114) (xy 92.63892 -267.434586) (xy 92.685078 -267.461235) (xy 92.726749 -267.494466)
			(xy 92.763001 -267.533537) (xy 92.793025 -267.577574) (xy 92.816151 -267.625595) (xy 92.831861 -267.676525)
			(xy 92.839804 -267.729229) (xy 92.840302 -267.755878) (xy 92.839804 -267.782527) (xy 93.068384 -267.782527)
			(xy 93.068384 -267.729229) (xy 93.076327 -267.676525) (xy 93.092037 -267.625595) (xy 93.115163 -267.577574)
			(xy 93.145187 -267.533537) (xy 93.181439 -267.494466) (xy 93.22311 -267.461235) (xy 93.269268 -267.434586)
			(xy 93.318882 -267.415114) (xy 93.370844 -267.403254) (xy 93.423994 -267.399271) (xy 93.477144 -267.403254)
			(xy 93.529106 -267.415114) (xy 93.57872 -267.434586) (xy 93.624878 -267.461235) (xy 93.666549 -267.494466)
			(xy 93.702801 -267.533537) (xy 93.732825 -267.577574) (xy 93.755951 -267.625595) (xy 93.771661 -267.676525)
			(xy 93.779604 -267.729229) (xy 93.780102 -267.755878) (xy 93.779604 -267.782527) (xy 94.008184 -267.782527)
			(xy 94.008184 -267.729229) (xy 94.016127 -267.676525) (xy 94.031837 -267.625595) (xy 94.054963 -267.577574)
			(xy 94.084987 -267.533537) (xy 94.121239 -267.494466) (xy 94.16291 -267.461235) (xy 94.209068 -267.434586)
			(xy 94.258682 -267.415114) (xy 94.310644 -267.403254) (xy 94.363794 -267.399271) (xy 94.416944 -267.403254)
			(xy 94.468906 -267.415114) (xy 94.51852 -267.434586) (xy 94.564678 -267.461235) (xy 94.606349 -267.494466)
			(xy 94.642601 -267.533537) (xy 94.672625 -267.577574) (xy 94.695751 -267.625595) (xy 94.711461 -267.676525)
			(xy 94.719404 -267.729229) (xy 94.719902 -267.755878) (xy 94.719404 -267.782527) (xy 94.947984 -267.782527)
			(xy 94.947984 -267.729229) (xy 94.955927 -267.676525) (xy 94.971637 -267.625595) (xy 94.994763 -267.577574)
			(xy 95.024787 -267.533537) (xy 95.061039 -267.494466) (xy 95.10271 -267.461235) (xy 95.148868 -267.434586)
			(xy 95.198482 -267.415114) (xy 95.250444 -267.403254) (xy 95.303594 -267.399271) (xy 95.356744 -267.403254)
			(xy 95.408706 -267.415114) (xy 95.45832 -267.434586) (xy 95.504478 -267.461235) (xy 95.546149 -267.494466)
			(xy 95.582401 -267.533537) (xy 95.612425 -267.577574) (xy 95.635551 -267.625595) (xy 95.651261 -267.676525)
			(xy 95.659204 -267.729229) (xy 95.659702 -267.755878) (xy 95.659204 -267.782527) (xy 95.887784 -267.782527)
			(xy 95.887784 -267.729229) (xy 95.895727 -267.676525) (xy 95.911437 -267.625595) (xy 95.934563 -267.577574)
			(xy 95.964587 -267.533537) (xy 96.000839 -267.494466) (xy 96.04251 -267.461235) (xy 96.088668 -267.434586)
			(xy 96.138282 -267.415114) (xy 96.190244 -267.403254) (xy 96.243394 -267.399271) (xy 96.296544 -267.403254)
			(xy 96.348506 -267.415114) (xy 96.39812 -267.434586) (xy 96.444278 -267.461235) (xy 96.485949 -267.494466)
			(xy 96.522201 -267.533537) (xy 96.552225 -267.577574) (xy 96.575351 -267.625595) (xy 96.591061 -267.676525)
			(xy 96.599004 -267.729229) (xy 96.599502 -267.755878) (xy 96.599004 -267.782527) (xy 96.827838 -267.782527)
			(xy 96.827838 -267.729229) (xy 96.835781 -267.676525) (xy 96.851491 -267.625595) (xy 96.874617 -267.577574)
			(xy 96.904641 -267.533537) (xy 96.940893 -267.494466) (xy 96.982564 -267.461235) (xy 97.028722 -267.434586)
			(xy 97.078336 -267.415114) (xy 97.130298 -267.403254) (xy 97.183448 -267.399271) (xy 97.236598 -267.403254)
			(xy 97.28856 -267.415114) (xy 97.338174 -267.434586) (xy 97.384332 -267.461235) (xy 97.426003 -267.494466)
			(xy 97.462255 -267.533537) (xy 97.492279 -267.577574) (xy 97.515405 -267.625595) (xy 97.531115 -267.676525)
			(xy 97.539058 -267.729229) (xy 97.539556 -267.755878) (xy 97.539058 -267.782527) (xy 97.767384 -267.782527)
			(xy 97.767384 -267.729229) (xy 97.775327 -267.676525) (xy 97.791037 -267.625595) (xy 97.814163 -267.577574)
			(xy 97.844187 -267.533537) (xy 97.880439 -267.494466) (xy 97.92211 -267.461235) (xy 97.968268 -267.434586)
			(xy 98.017882 -267.415114) (xy 98.069844 -267.403254) (xy 98.122994 -267.399271) (xy 98.176144 -267.403254)
			(xy 98.228106 -267.415114) (xy 98.27772 -267.434586) (xy 98.323878 -267.461235) (xy 98.365549 -267.494466)
			(xy 98.401801 -267.533537) (xy 98.431825 -267.577574) (xy 98.454951 -267.625595) (xy 98.470661 -267.676525)
			(xy 98.478604 -267.729229) (xy 98.479102 -267.755878) (xy 98.478604 -267.782527) (xy 98.707184 -267.782527)
			(xy 98.707184 -267.729229) (xy 98.715127 -267.676525) (xy 98.730837 -267.625595) (xy 98.753963 -267.577574)
			(xy 98.783987 -267.533537) (xy 98.820239 -267.494466) (xy 98.86191 -267.461235) (xy 98.908068 -267.434586)
			(xy 98.957682 -267.415114) (xy 99.009644 -267.403254) (xy 99.062794 -267.399271) (xy 99.115944 -267.403254)
			(xy 99.167906 -267.415114) (xy 99.21752 -267.434586) (xy 99.263678 -267.461235) (xy 99.305349 -267.494466)
			(xy 99.341601 -267.533537) (xy 99.371625 -267.577574) (xy 99.394751 -267.625595) (xy 99.410461 -267.676525)
			(xy 99.418404 -267.729229) (xy 99.418902 -267.755878) (xy 99.418404 -267.782527) (xy 99.646984 -267.782527)
			(xy 99.646984 -267.729229) (xy 99.654927 -267.676525) (xy 99.670637 -267.625595) (xy 99.693763 -267.577574)
			(xy 99.723787 -267.533537) (xy 99.760039 -267.494466) (xy 99.80171 -267.461235) (xy 99.847868 -267.434586)
			(xy 99.897482 -267.415114) (xy 99.949444 -267.403254) (xy 100.002594 -267.399271) (xy 100.055744 -267.403254)
			(xy 100.107706 -267.415114) (xy 100.15732 -267.434586) (xy 100.203478 -267.461235) (xy 100.245149 -267.494466)
			(xy 100.281401 -267.533537) (xy 100.311425 -267.577574) (xy 100.334551 -267.625595) (xy 100.350261 -267.676525)
			(xy 100.358204 -267.729229) (xy 100.358702 -267.755878) (xy 100.358204 -267.782527) (xy 100.586784 -267.782527)
			(xy 100.586784 -267.729229) (xy 100.594727 -267.676525) (xy 100.610437 -267.625595) (xy 100.633563 -267.577574)
			(xy 100.663587 -267.533537) (xy 100.699839 -267.494466) (xy 100.74151 -267.461235) (xy 100.787668 -267.434586)
			(xy 100.837282 -267.415114) (xy 100.889244 -267.403254) (xy 100.942394 -267.399271) (xy 100.995544 -267.403254)
			(xy 101.047506 -267.415114) (xy 101.09712 -267.434586) (xy 101.143278 -267.461235) (xy 101.184949 -267.494466)
			(xy 101.221201 -267.533537) (xy 101.251225 -267.577574) (xy 101.274351 -267.625595) (xy 101.290061 -267.676525)
			(xy 101.298004 -267.729229) (xy 101.298502 -267.755878) (xy 101.298004 -267.782527) (xy 101.526584 -267.782527)
			(xy 101.526584 -267.729229) (xy 101.534527 -267.676525) (xy 101.550237 -267.625595) (xy 101.573363 -267.577574)
			(xy 101.603387 -267.533537) (xy 101.639639 -267.494466) (xy 101.68131 -267.461235) (xy 101.727468 -267.434586)
			(xy 101.777082 -267.415114) (xy 101.829044 -267.403254) (xy 101.882194 -267.399271) (xy 101.935344 -267.403254)
			(xy 101.987306 -267.415114) (xy 102.03692 -267.434586) (xy 102.083078 -267.461235) (xy 102.124749 -267.494466)
			(xy 102.161001 -267.533537) (xy 102.191025 -267.577574) (xy 102.214151 -267.625595) (xy 102.229861 -267.676525)
			(xy 102.237804 -267.729229) (xy 102.238302 -267.755878) (xy 102.237804 -267.782527) (xy 102.466384 -267.782527)
			(xy 102.466384 -267.729229) (xy 102.474327 -267.676525) (xy 102.490037 -267.625595) (xy 102.513163 -267.577574)
			(xy 102.543187 -267.533537) (xy 102.579439 -267.494466) (xy 102.62111 -267.461235) (xy 102.667268 -267.434586)
			(xy 102.716882 -267.415114) (xy 102.768844 -267.403254) (xy 102.821994 -267.399271) (xy 102.875144 -267.403254)
			(xy 102.927106 -267.415114) (xy 102.97672 -267.434586) (xy 103.022878 -267.461235) (xy 103.064549 -267.494466)
			(xy 103.100801 -267.533537) (xy 103.130825 -267.577574) (xy 103.153951 -267.625595) (xy 103.169661 -267.676525)
			(xy 103.177604 -267.729229) (xy 103.178102 -267.755878) (xy 103.177604 -267.782527) (xy 103.406184 -267.782527)
			(xy 103.406184 -267.729229) (xy 103.414127 -267.676525) (xy 103.429837 -267.625595) (xy 103.452963 -267.577574)
			(xy 103.482987 -267.533537) (xy 103.519239 -267.494466) (xy 103.56091 -267.461235) (xy 103.607068 -267.434586)
			(xy 103.656682 -267.415114) (xy 103.708644 -267.403254) (xy 103.761794 -267.399271) (xy 103.814944 -267.403254)
			(xy 103.866906 -267.415114) (xy 103.91652 -267.434586) (xy 103.962678 -267.461235) (xy 104.004349 -267.494466)
			(xy 104.040601 -267.533537) (xy 104.070625 -267.577574) (xy 104.093751 -267.625595) (xy 104.109461 -267.676525)
			(xy 104.117404 -267.729229) (xy 104.117902 -267.755878) (xy 104.117404 -267.782527) (xy 104.345984 -267.782527)
			(xy 104.345984 -267.729229) (xy 104.353927 -267.676525) (xy 104.369637 -267.625595) (xy 104.392763 -267.577574)
			(xy 104.422787 -267.533537) (xy 104.459039 -267.494466) (xy 104.50071 -267.461235) (xy 104.546868 -267.434586)
			(xy 104.596482 -267.415114) (xy 104.648444 -267.403254) (xy 104.701594 -267.399271) (xy 104.754744 -267.403254)
			(xy 104.806706 -267.415114) (xy 104.85632 -267.434586) (xy 104.902478 -267.461235) (xy 104.944149 -267.494466)
			(xy 104.980401 -267.533537) (xy 105.010425 -267.577574) (xy 105.033551 -267.625595) (xy 105.049261 -267.676525)
			(xy 105.057204 -267.729229) (xy 105.057702 -267.755878) (xy 105.057204 -267.782527) (xy 105.285784 -267.782527)
			(xy 105.285784 -267.729229) (xy 105.293727 -267.676525) (xy 105.309437 -267.625595) (xy 105.332563 -267.577574)
			(xy 105.362587 -267.533537) (xy 105.398839 -267.494466) (xy 105.44051 -267.461235) (xy 105.486668 -267.434586)
			(xy 105.536282 -267.415114) (xy 105.588244 -267.403254) (xy 105.641394 -267.399271) (xy 105.694544 -267.403254)
			(xy 105.746506 -267.415114) (xy 105.79612 -267.434586) (xy 105.842278 -267.461235) (xy 105.883949 -267.494466)
			(xy 105.920201 -267.533537) (xy 105.950225 -267.577574) (xy 105.973351 -267.625595) (xy 105.989061 -267.676525)
			(xy 105.997004 -267.729229) (xy 105.997502 -267.755878) (xy 105.997004 -267.782527) (xy 106.225584 -267.782527)
			(xy 106.225584 -267.729229) (xy 106.233527 -267.676525) (xy 106.249237 -267.625595) (xy 106.272363 -267.577574)
			(xy 106.302387 -267.533537) (xy 106.338639 -267.494466) (xy 106.38031 -267.461235) (xy 106.426468 -267.434586)
			(xy 106.476082 -267.415114) (xy 106.528044 -267.403254) (xy 106.581194 -267.399271) (xy 106.634344 -267.403254)
			(xy 106.686306 -267.415114) (xy 106.73592 -267.434586) (xy 106.782078 -267.461235) (xy 106.823749 -267.494466)
			(xy 106.860001 -267.533537) (xy 106.890025 -267.577574) (xy 106.913151 -267.625595) (xy 106.928861 -267.676525)
			(xy 106.936804 -267.729229) (xy 106.937302 -267.755878) (xy 106.936804 -267.782527) (xy 107.165384 -267.782527)
			(xy 107.165384 -267.729229) (xy 107.173327 -267.676525) (xy 107.189037 -267.625595) (xy 107.212163 -267.577574)
			(xy 107.242187 -267.533537) (xy 107.278439 -267.494466) (xy 107.32011 -267.461235) (xy 107.366268 -267.434586)
			(xy 107.415882 -267.415114) (xy 107.467844 -267.403254) (xy 107.520994 -267.399271) (xy 107.574144 -267.403254)
			(xy 107.626106 -267.415114) (xy 107.67572 -267.434586) (xy 107.721878 -267.461235) (xy 107.763549 -267.494466)
			(xy 107.799801 -267.533537) (xy 107.829825 -267.577574) (xy 107.852951 -267.625595) (xy 107.868661 -267.676525)
			(xy 107.876604 -267.729229) (xy 107.877102 -267.755878) (xy 107.876604 -267.782527) (xy 107.868661 -267.835231)
			(xy 107.852951 -267.886161) (xy 107.829825 -267.934182) (xy 107.799801 -267.978219) (xy 107.763549 -268.01729)
			(xy 107.721878 -268.050521) (xy 107.67572 -268.07717) (xy 107.626106 -268.096642) (xy 107.574144 -268.108502)
			(xy 107.520994 -268.112486) (xy 107.467844 -268.108502) (xy 107.415882 -268.096642) (xy 107.366268 -268.07717)
			(xy 107.32011 -268.050521) (xy 107.278439 -268.01729) (xy 107.242187 -267.978219) (xy 107.212163 -267.934182)
			(xy 107.189037 -267.886161) (xy 107.173327 -267.835231) (xy 107.165384 -267.782527) (xy 106.936804 -267.782527)
			(xy 106.928861 -267.835231) (xy 106.913151 -267.886161) (xy 106.890025 -267.934182) (xy 106.860001 -267.978219)
			(xy 106.823749 -268.01729) (xy 106.782078 -268.050521) (xy 106.73592 -268.07717) (xy 106.686306 -268.096642)
			(xy 106.634344 -268.108502) (xy 106.581194 -268.112486) (xy 106.528044 -268.108502) (xy 106.476082 -268.096642)
			(xy 106.426468 -268.07717) (xy 106.38031 -268.050521) (xy 106.338639 -268.01729) (xy 106.302387 -267.978219)
			(xy 106.272363 -267.934182) (xy 106.249237 -267.886161) (xy 106.233527 -267.835231) (xy 106.225584 -267.782527)
			(xy 105.997004 -267.782527) (xy 105.989061 -267.835231) (xy 105.973351 -267.886161) (xy 105.950225 -267.934182)
			(xy 105.920201 -267.978219) (xy 105.883949 -268.01729) (xy 105.842278 -268.050521) (xy 105.79612 -268.07717)
			(xy 105.746506 -268.096642) (xy 105.694544 -268.108502) (xy 105.641394 -268.112486) (xy 105.588244 -268.108502)
			(xy 105.536282 -268.096642) (xy 105.486668 -268.07717) (xy 105.44051 -268.050521) (xy 105.398839 -268.01729)
			(xy 105.362587 -267.978219) (xy 105.332563 -267.934182) (xy 105.309437 -267.886161) (xy 105.293727 -267.835231)
			(xy 105.285784 -267.782527) (xy 105.057204 -267.782527) (xy 105.049261 -267.835231) (xy 105.033551 -267.886161)
			(xy 105.010425 -267.934182) (xy 104.980401 -267.978219) (xy 104.944149 -268.01729) (xy 104.902478 -268.050521)
			(xy 104.85632 -268.07717) (xy 104.806706 -268.096642) (xy 104.754744 -268.108502) (xy 104.701594 -268.112486)
			(xy 104.648444 -268.108502) (xy 104.596482 -268.096642) (xy 104.546868 -268.07717) (xy 104.50071 -268.050521)
			(xy 104.459039 -268.01729) (xy 104.422787 -267.978219) (xy 104.392763 -267.934182) (xy 104.369637 -267.886161)
			(xy 104.353927 -267.835231) (xy 104.345984 -267.782527) (xy 104.117404 -267.782527) (xy 104.109461 -267.835231)
			(xy 104.093751 -267.886161) (xy 104.070625 -267.934182) (xy 104.040601 -267.978219) (xy 104.004349 -268.01729)
			(xy 103.962678 -268.050521) (xy 103.91652 -268.07717) (xy 103.866906 -268.096642) (xy 103.814944 -268.108502)
			(xy 103.761794 -268.112486) (xy 103.708644 -268.108502) (xy 103.656682 -268.096642) (xy 103.607068 -268.07717)
			(xy 103.56091 -268.050521) (xy 103.519239 -268.01729) (xy 103.482987 -267.978219) (xy 103.452963 -267.934182)
			(xy 103.429837 -267.886161) (xy 103.414127 -267.835231) (xy 103.406184 -267.782527) (xy 103.177604 -267.782527)
			(xy 103.169661 -267.835231) (xy 103.153951 -267.886161) (xy 103.130825 -267.934182) (xy 103.100801 -267.978219)
			(xy 103.064549 -268.01729) (xy 103.022878 -268.050521) (xy 102.97672 -268.07717) (xy 102.927106 -268.096642)
			(xy 102.875144 -268.108502) (xy 102.821994 -268.112486) (xy 102.768844 -268.108502) (xy 102.716882 -268.096642)
			(xy 102.667268 -268.07717) (xy 102.62111 -268.050521) (xy 102.579439 -268.01729) (xy 102.543187 -267.978219)
			(xy 102.513163 -267.934182) (xy 102.490037 -267.886161) (xy 102.474327 -267.835231) (xy 102.466384 -267.782527)
			(xy 102.237804 -267.782527) (xy 102.229861 -267.835231) (xy 102.214151 -267.886161) (xy 102.191025 -267.934182)
			(xy 102.161001 -267.978219) (xy 102.124749 -268.01729) (xy 102.083078 -268.050521) (xy 102.03692 -268.07717)
			(xy 101.987306 -268.096642) (xy 101.935344 -268.108502) (xy 101.882194 -268.112486) (xy 101.829044 -268.108502)
			(xy 101.777082 -268.096642) (xy 101.727468 -268.07717) (xy 101.68131 -268.050521) (xy 101.639639 -268.01729)
			(xy 101.603387 -267.978219) (xy 101.573363 -267.934182) (xy 101.550237 -267.886161) (xy 101.534527 -267.835231)
			(xy 101.526584 -267.782527) (xy 101.298004 -267.782527) (xy 101.290061 -267.835231) (xy 101.274351 -267.886161)
			(xy 101.251225 -267.934182) (xy 101.221201 -267.978219) (xy 101.184949 -268.01729) (xy 101.143278 -268.050521)
			(xy 101.09712 -268.07717) (xy 101.047506 -268.096642) (xy 100.995544 -268.108502) (xy 100.942394 -268.112486)
			(xy 100.889244 -268.108502) (xy 100.837282 -268.096642) (xy 100.787668 -268.07717) (xy 100.74151 -268.050521)
			(xy 100.699839 -268.01729) (xy 100.663587 -267.978219) (xy 100.633563 -267.934182) (xy 100.610437 -267.886161)
			(xy 100.594727 -267.835231) (xy 100.586784 -267.782527) (xy 100.358204 -267.782527) (xy 100.350261 -267.835231)
			(xy 100.334551 -267.886161) (xy 100.311425 -267.934182) (xy 100.281401 -267.978219) (xy 100.245149 -268.01729)
			(xy 100.203478 -268.050521) (xy 100.15732 -268.07717) (xy 100.107706 -268.096642) (xy 100.055744 -268.108502)
			(xy 100.002594 -268.112486) (xy 99.949444 -268.108502) (xy 99.897482 -268.096642) (xy 99.847868 -268.07717)
			(xy 99.80171 -268.050521) (xy 99.760039 -268.01729) (xy 99.723787 -267.978219) (xy 99.693763 -267.934182)
			(xy 99.670637 -267.886161) (xy 99.654927 -267.835231) (xy 99.646984 -267.782527) (xy 99.418404 -267.782527)
			(xy 99.410461 -267.835231) (xy 99.394751 -267.886161) (xy 99.371625 -267.934182) (xy 99.341601 -267.978219)
			(xy 99.305349 -268.01729) (xy 99.263678 -268.050521) (xy 99.21752 -268.07717) (xy 99.167906 -268.096642)
			(xy 99.115944 -268.108502) (xy 99.062794 -268.112486) (xy 99.009644 -268.108502) (xy 98.957682 -268.096642)
			(xy 98.908068 -268.07717) (xy 98.86191 -268.050521) (xy 98.820239 -268.01729) (xy 98.783987 -267.978219)
			(xy 98.753963 -267.934182) (xy 98.730837 -267.886161) (xy 98.715127 -267.835231) (xy 98.707184 -267.782527)
			(xy 98.478604 -267.782527) (xy 98.470661 -267.835231) (xy 98.454951 -267.886161) (xy 98.431825 -267.934182)
			(xy 98.401801 -267.978219) (xy 98.365549 -268.01729) (xy 98.323878 -268.050521) (xy 98.27772 -268.07717)
			(xy 98.228106 -268.096642) (xy 98.176144 -268.108502) (xy 98.122994 -268.112486) (xy 98.069844 -268.108502)
			(xy 98.017882 -268.096642) (xy 97.968268 -268.07717) (xy 97.92211 -268.050521) (xy 97.880439 -268.01729)
			(xy 97.844187 -267.978219) (xy 97.814163 -267.934182) (xy 97.791037 -267.886161) (xy 97.775327 -267.835231)
			(xy 97.767384 -267.782527) (xy 97.539058 -267.782527) (xy 97.531115 -267.835231) (xy 97.515405 -267.886161)
			(xy 97.492279 -267.934182) (xy 97.462255 -267.978219) (xy 97.426003 -268.01729) (xy 97.384332 -268.050521)
			(xy 97.338174 -268.07717) (xy 97.28856 -268.096642) (xy 97.236598 -268.108502) (xy 97.183448 -268.112486)
			(xy 97.130298 -268.108502) (xy 97.078336 -268.096642) (xy 97.028722 -268.07717) (xy 96.982564 -268.050521)
			(xy 96.940893 -268.01729) (xy 96.904641 -267.978219) (xy 96.874617 -267.934182) (xy 96.851491 -267.886161)
			(xy 96.835781 -267.835231) (xy 96.827838 -267.782527) (xy 96.599004 -267.782527) (xy 96.591061 -267.835231)
			(xy 96.575351 -267.886161) (xy 96.552225 -267.934182) (xy 96.522201 -267.978219) (xy 96.485949 -268.01729)
			(xy 96.444278 -268.050521) (xy 96.39812 -268.07717) (xy 96.348506 -268.096642) (xy 96.296544 -268.108502)
			(xy 96.243394 -268.112486) (xy 96.190244 -268.108502) (xy 96.138282 -268.096642) (xy 96.088668 -268.07717)
			(xy 96.04251 -268.050521) (xy 96.000839 -268.01729) (xy 95.964587 -267.978219) (xy 95.934563 -267.934182)
			(xy 95.911437 -267.886161) (xy 95.895727 -267.835231) (xy 95.887784 -267.782527) (xy 95.659204 -267.782527)
			(xy 95.651261 -267.835231) (xy 95.635551 -267.886161) (xy 95.612425 -267.934182) (xy 95.582401 -267.978219)
			(xy 95.546149 -268.01729) (xy 95.504478 -268.050521) (xy 95.45832 -268.07717) (xy 95.408706 -268.096642)
			(xy 95.356744 -268.108502) (xy 95.303594 -268.112486) (xy 95.250444 -268.108502) (xy 95.198482 -268.096642)
			(xy 95.148868 -268.07717) (xy 95.10271 -268.050521) (xy 95.061039 -268.01729) (xy 95.024787 -267.978219)
			(xy 94.994763 -267.934182) (xy 94.971637 -267.886161) (xy 94.955927 -267.835231) (xy 94.947984 -267.782527)
			(xy 94.719404 -267.782527) (xy 94.711461 -267.835231) (xy 94.695751 -267.886161) (xy 94.672625 -267.934182)
			(xy 94.642601 -267.978219) (xy 94.606349 -268.01729) (xy 94.564678 -268.050521) (xy 94.51852 -268.07717)
			(xy 94.468906 -268.096642) (xy 94.416944 -268.108502) (xy 94.363794 -268.112486) (xy 94.310644 -268.108502)
			(xy 94.258682 -268.096642) (xy 94.209068 -268.07717) (xy 94.16291 -268.050521) (xy 94.121239 -268.01729)
			(xy 94.084987 -267.978219) (xy 94.054963 -267.934182) (xy 94.031837 -267.886161) (xy 94.016127 -267.835231)
			(xy 94.008184 -267.782527) (xy 93.779604 -267.782527) (xy 93.771661 -267.835231) (xy 93.755951 -267.886161)
			(xy 93.732825 -267.934182) (xy 93.702801 -267.978219) (xy 93.666549 -268.01729) (xy 93.624878 -268.050521)
			(xy 93.57872 -268.07717) (xy 93.529106 -268.096642) (xy 93.477144 -268.108502) (xy 93.423994 -268.112486)
			(xy 93.370844 -268.108502) (xy 93.318882 -268.096642) (xy 93.269268 -268.07717) (xy 93.22311 -268.050521)
			(xy 93.181439 -268.01729) (xy 93.145187 -267.978219) (xy 93.115163 -267.934182) (xy 93.092037 -267.886161)
			(xy 93.076327 -267.835231) (xy 93.068384 -267.782527) (xy 92.839804 -267.782527) (xy 92.831861 -267.835231)
			(xy 92.816151 -267.886161) (xy 92.793025 -267.934182) (xy 92.763001 -267.978219) (xy 92.726749 -268.01729)
			(xy 92.685078 -268.050521) (xy 92.63892 -268.07717) (xy 92.589306 -268.096642) (xy 92.537344 -268.108502)
			(xy 92.484194 -268.112486) (xy 92.431044 -268.108502) (xy 92.379082 -268.096642) (xy 92.329468 -268.07717)
			(xy 92.28331 -268.050521) (xy 92.241639 -268.01729) (xy 92.205387 -267.978219) (xy 92.175363 -267.934182)
			(xy 92.152237 -267.886161) (xy 92.136527 -267.835231) (xy 92.128584 -267.782527) (xy 91.900004 -267.782527)
			(xy 91.892061 -267.835231) (xy 91.876351 -267.886161) (xy 91.853225 -267.934182) (xy 91.823201 -267.978219)
			(xy 91.786949 -268.01729) (xy 91.745278 -268.050521) (xy 91.69912 -268.07717) (xy 91.649506 -268.096642)
			(xy 91.597544 -268.108502) (xy 91.544394 -268.112486) (xy 91.491244 -268.108502) (xy 91.439282 -268.096642)
			(xy 91.389668 -268.07717) (xy 91.34351 -268.050521) (xy 91.301839 -268.01729) (xy 91.265587 -267.978219)
			(xy 91.235563 -267.934182) (xy 91.212437 -267.886161) (xy 91.196727 -267.835231) (xy 91.188784 -267.782527)
			(xy 90.960458 -267.782527) (xy 90.952515 -267.835231) (xy 90.936805 -267.886161) (xy 90.913679 -267.934182)
			(xy 90.883655 -267.978219) (xy 90.847403 -268.01729) (xy 90.805732 -268.050521) (xy 90.759574 -268.07717)
			(xy 90.70996 -268.096642) (xy 90.657998 -268.108502) (xy 90.604848 -268.112486) (xy 90.551698 -268.108502)
			(xy 90.499736 -268.096642) (xy 90.450122 -268.07717) (xy 90.403964 -268.050521) (xy 90.362293 -268.01729)
			(xy 90.326041 -267.978219) (xy 90.296017 -267.934182) (xy 90.272891 -267.886161) (xy 90.257181 -267.835231)
			(xy 90.249238 -267.782527) (xy 90.020404 -267.782527) (xy 90.012461 -267.835231) (xy 89.996751 -267.886161)
			(xy 89.973625 -267.934182) (xy 89.943601 -267.978219) (xy 89.907349 -268.01729) (xy 89.865678 -268.050521)
			(xy 89.81952 -268.07717) (xy 89.769906 -268.096642) (xy 89.717944 -268.108502) (xy 89.664794 -268.112486)
			(xy 89.611644 -268.108502) (xy 89.559682 -268.096642) (xy 89.510068 -268.07717) (xy 89.46391 -268.050521)
			(xy 89.422239 -268.01729) (xy 89.385987 -267.978219) (xy 89.355963 -267.934182) (xy 89.332837 -267.886161)
			(xy 89.317127 -267.835231) (xy 89.309184 -267.782527) (xy 89.080593 -267.782527) (xy 89.080593 -267.78326)
			(xy 89.072222 -267.837337) (xy 89.055676 -267.889497) (xy 89.031346 -267.938512) (xy 88.999803 -267.983228)
			(xy 88.961791 -268.022592) (xy 88.918205 -268.055678) (xy 88.87007 -268.081706) (xy 88.81852 -268.100064)
			(xy 88.764768 -268.11032) (xy 88.73744 -268.111732) (xy 88.727668 -268.112517) (xy 88.709775 -268.120483)
			(xy 88.696171 -268.134575) (xy 88.688841 -268.152738) (xy 88.688418 -268.162532) (xy 88.688418 -268.596343)
			(xy 88.839284 -268.596343) (xy 88.839284 -268.543045) (xy 88.847227 -268.490341) (xy 88.862937 -268.439411)
			(xy 88.886063 -268.39139) (xy 88.916087 -268.347353) (xy 88.952339 -268.308282) (xy 88.99401 -268.275051)
			(xy 89.040168 -268.248402) (xy 89.089782 -268.22893) (xy 89.141744 -268.21707) (xy 89.194894 -268.213087)
			(xy 89.248044 -268.21707) (xy 89.300006 -268.22893) (xy 89.34962 -268.248402) (xy 89.395778 -268.275051)
			(xy 89.437449 -268.308282) (xy 89.473701 -268.347353) (xy 89.503725 -268.39139) (xy 89.526851 -268.439411)
			(xy 89.542561 -268.490341) (xy 89.550504 -268.543045) (xy 89.551002 -268.569694) (xy 89.550504 -268.596343)
			(xy 89.779084 -268.596343) (xy 89.779084 -268.543045) (xy 89.787027 -268.490341) (xy 89.802737 -268.439411)
			(xy 89.825863 -268.39139) (xy 89.855887 -268.347353) (xy 89.892139 -268.308282) (xy 89.93381 -268.275051)
			(xy 89.979968 -268.248402) (xy 90.029582 -268.22893) (xy 90.081544 -268.21707) (xy 90.134694 -268.213087)
			(xy 90.187844 -268.21707) (xy 90.239806 -268.22893) (xy 90.28942 -268.248402) (xy 90.335578 -268.275051)
			(xy 90.377249 -268.308282) (xy 90.413501 -268.347353) (xy 90.443525 -268.39139) (xy 90.466651 -268.439411)
			(xy 90.482361 -268.490341) (xy 90.490304 -268.543045) (xy 90.490802 -268.569694) (xy 90.490304 -268.596343)
			(xy 90.719138 -268.596343) (xy 90.719138 -268.543045) (xy 90.727081 -268.490341) (xy 90.742791 -268.439411)
			(xy 90.765917 -268.39139) (xy 90.795941 -268.347353) (xy 90.832193 -268.308282) (xy 90.873864 -268.275051)
			(xy 90.920022 -268.248402) (xy 90.969636 -268.22893) (xy 91.021598 -268.21707) (xy 91.074748 -268.213087)
			(xy 91.127898 -268.21707) (xy 91.17986 -268.22893) (xy 91.229474 -268.248402) (xy 91.275632 -268.275051)
			(xy 91.317303 -268.308282) (xy 91.353555 -268.347353) (xy 91.383579 -268.39139) (xy 91.406705 -268.439411)
			(xy 91.422415 -268.490341) (xy 91.430358 -268.543045) (xy 91.430856 -268.569694) (xy 91.430358 -268.596343)
			(xy 91.658938 -268.596343) (xy 91.658938 -268.543045) (xy 91.666881 -268.490341) (xy 91.682591 -268.439411)
			(xy 91.705717 -268.39139) (xy 91.735741 -268.347353) (xy 91.771993 -268.308282) (xy 91.813664 -268.275051)
			(xy 91.859822 -268.248402) (xy 91.909436 -268.22893) (xy 91.961398 -268.21707) (xy 92.014548 -268.213087)
			(xy 92.067698 -268.21707) (xy 92.11966 -268.22893) (xy 92.169274 -268.248402) (xy 92.215432 -268.275051)
			(xy 92.257103 -268.308282) (xy 92.293355 -268.347353) (xy 92.323379 -268.39139) (xy 92.346505 -268.439411)
			(xy 92.362215 -268.490341) (xy 92.370158 -268.543045) (xy 92.370656 -268.569694) (xy 92.370158 -268.596343)
			(xy 92.598738 -268.596343) (xy 92.598738 -268.543045) (xy 92.606681 -268.490341) (xy 92.622391 -268.439411)
			(xy 92.645517 -268.39139) (xy 92.675541 -268.347353) (xy 92.711793 -268.308282) (xy 92.753464 -268.275051)
			(xy 92.799622 -268.248402) (xy 92.849236 -268.22893) (xy 92.901198 -268.21707) (xy 92.954348 -268.213087)
			(xy 93.007498 -268.21707) (xy 93.05946 -268.22893) (xy 93.109074 -268.248402) (xy 93.155232 -268.275051)
			(xy 93.196903 -268.308282) (xy 93.233155 -268.347353) (xy 93.263179 -268.39139) (xy 93.286305 -268.439411)
			(xy 93.302015 -268.490341) (xy 93.309958 -268.543045) (xy 93.310456 -268.569694) (xy 93.309958 -268.596343)
			(xy 93.538538 -268.596343) (xy 93.538538 -268.543045) (xy 93.546481 -268.490341) (xy 93.562191 -268.439411)
			(xy 93.585317 -268.39139) (xy 93.615341 -268.347353) (xy 93.651593 -268.308282) (xy 93.693264 -268.275051)
			(xy 93.739422 -268.248402) (xy 93.789036 -268.22893) (xy 93.840998 -268.21707) (xy 93.894148 -268.213087)
			(xy 93.947298 -268.21707) (xy 93.99926 -268.22893) (xy 94.048874 -268.248402) (xy 94.095032 -268.275051)
			(xy 94.136703 -268.308282) (xy 94.172955 -268.347353) (xy 94.202979 -268.39139) (xy 94.226105 -268.439411)
			(xy 94.241815 -268.490341) (xy 94.249758 -268.543045) (xy 94.250256 -268.569694) (xy 94.249758 -268.596343)
			(xy 94.478084 -268.596343) (xy 94.478084 -268.543045) (xy 94.486027 -268.490341) (xy 94.501737 -268.439411)
			(xy 94.524863 -268.39139) (xy 94.554887 -268.347353) (xy 94.591139 -268.308282) (xy 94.63281 -268.275051)
			(xy 94.678968 -268.248402) (xy 94.728582 -268.22893) (xy 94.780544 -268.21707) (xy 94.833694 -268.213087)
			(xy 94.886844 -268.21707) (xy 94.938806 -268.22893) (xy 94.98842 -268.248402) (xy 95.034578 -268.275051)
			(xy 95.076249 -268.308282) (xy 95.112501 -268.347353) (xy 95.142525 -268.39139) (xy 95.165651 -268.439411)
			(xy 95.181361 -268.490341) (xy 95.189304 -268.543045) (xy 95.189802 -268.569694) (xy 95.189304 -268.596343)
			(xy 95.418138 -268.596343) (xy 95.418138 -268.543045) (xy 95.426081 -268.490341) (xy 95.441791 -268.439411)
			(xy 95.464917 -268.39139) (xy 95.494941 -268.347353) (xy 95.531193 -268.308282) (xy 95.572864 -268.275051)
			(xy 95.619022 -268.248402) (xy 95.668636 -268.22893) (xy 95.720598 -268.21707) (xy 95.773748 -268.213087)
			(xy 95.826898 -268.21707) (xy 95.87886 -268.22893) (xy 95.928474 -268.248402) (xy 95.974632 -268.275051)
			(xy 96.016303 -268.308282) (xy 96.052555 -268.347353) (xy 96.082579 -268.39139) (xy 96.105705 -268.439411)
			(xy 96.121415 -268.490341) (xy 96.129358 -268.543045) (xy 96.129856 -268.569694) (xy 96.129358 -268.596343)
			(xy 96.357938 -268.596343) (xy 96.357938 -268.543045) (xy 96.365881 -268.490341) (xy 96.381591 -268.439411)
			(xy 96.404717 -268.39139) (xy 96.434741 -268.347353) (xy 96.470993 -268.308282) (xy 96.512664 -268.275051)
			(xy 96.558822 -268.248402) (xy 96.608436 -268.22893) (xy 96.660398 -268.21707) (xy 96.713548 -268.213087)
			(xy 96.766698 -268.21707) (xy 96.81866 -268.22893) (xy 96.868274 -268.248402) (xy 96.914432 -268.275051)
			(xy 96.956103 -268.308282) (xy 96.992355 -268.347353) (xy 97.022379 -268.39139) (xy 97.045505 -268.439411)
			(xy 97.061215 -268.490341) (xy 97.069158 -268.543045) (xy 97.069656 -268.569694) (xy 97.069158 -268.596343)
			(xy 97.297738 -268.596343) (xy 97.297738 -268.543045) (xy 97.305681 -268.490341) (xy 97.321391 -268.439411)
			(xy 97.344517 -268.39139) (xy 97.374541 -268.347353) (xy 97.410793 -268.308282) (xy 97.452464 -268.275051)
			(xy 97.498622 -268.248402) (xy 97.548236 -268.22893) (xy 97.600198 -268.21707) (xy 97.653348 -268.213087)
			(xy 97.706498 -268.21707) (xy 97.75846 -268.22893) (xy 97.808074 -268.248402) (xy 97.854232 -268.275051)
			(xy 97.895903 -268.308282) (xy 97.932155 -268.347353) (xy 97.962179 -268.39139) (xy 97.985305 -268.439411)
			(xy 98.001015 -268.490341) (xy 98.008958 -268.543045) (xy 98.009456 -268.569694) (xy 98.008958 -268.596343)
			(xy 98.237538 -268.596343) (xy 98.237538 -268.543045) (xy 98.245481 -268.490341) (xy 98.261191 -268.439411)
			(xy 98.284317 -268.39139) (xy 98.314341 -268.347353) (xy 98.350593 -268.308282) (xy 98.392264 -268.275051)
			(xy 98.438422 -268.248402) (xy 98.488036 -268.22893) (xy 98.539998 -268.21707) (xy 98.593148 -268.213087)
			(xy 98.646298 -268.21707) (xy 98.69826 -268.22893) (xy 98.747874 -268.248402) (xy 98.794032 -268.275051)
			(xy 98.835703 -268.308282) (xy 98.871955 -268.347353) (xy 98.901979 -268.39139) (xy 98.925105 -268.439411)
			(xy 98.940815 -268.490341) (xy 98.948758 -268.543045) (xy 98.949256 -268.569694) (xy 98.948758 -268.596343)
			(xy 99.177338 -268.596343) (xy 99.177338 -268.543045) (xy 99.185281 -268.490341) (xy 99.200991 -268.439411)
			(xy 99.224117 -268.39139) (xy 99.254141 -268.347353) (xy 99.290393 -268.308282) (xy 99.332064 -268.275051)
			(xy 99.378222 -268.248402) (xy 99.427836 -268.22893) (xy 99.479798 -268.21707) (xy 99.532948 -268.213087)
			(xy 99.586098 -268.21707) (xy 99.63806 -268.22893) (xy 99.687674 -268.248402) (xy 99.733832 -268.275051)
			(xy 99.775503 -268.308282) (xy 99.811755 -268.347353) (xy 99.841779 -268.39139) (xy 99.864905 -268.439411)
			(xy 99.880615 -268.490341) (xy 99.888558 -268.543045) (xy 99.889056 -268.569694) (xy 99.888558 -268.596343)
			(xy 100.117138 -268.596343) (xy 100.117138 -268.543045) (xy 100.125081 -268.490341) (xy 100.140791 -268.439411)
			(xy 100.163917 -268.39139) (xy 100.193941 -268.347353) (xy 100.230193 -268.308282) (xy 100.271864 -268.275051)
			(xy 100.318022 -268.248402) (xy 100.367636 -268.22893) (xy 100.419598 -268.21707) (xy 100.472748 -268.213087)
			(xy 100.525898 -268.21707) (xy 100.57786 -268.22893) (xy 100.627474 -268.248402) (xy 100.673632 -268.275051)
			(xy 100.715303 -268.308282) (xy 100.751555 -268.347353) (xy 100.781579 -268.39139) (xy 100.804705 -268.439411)
			(xy 100.820415 -268.490341) (xy 100.828358 -268.543045) (xy 100.828856 -268.569694) (xy 100.828358 -268.596343)
			(xy 101.056684 -268.596343) (xy 101.056684 -268.543045) (xy 101.064627 -268.490341) (xy 101.080337 -268.439411)
			(xy 101.103463 -268.39139) (xy 101.133487 -268.347353) (xy 101.169739 -268.308282) (xy 101.21141 -268.275051)
			(xy 101.257568 -268.248402) (xy 101.307182 -268.22893) (xy 101.359144 -268.21707) (xy 101.412294 -268.213087)
			(xy 101.465444 -268.21707) (xy 101.517406 -268.22893) (xy 101.56702 -268.248402) (xy 101.613178 -268.275051)
			(xy 101.654849 -268.308282) (xy 101.691101 -268.347353) (xy 101.721125 -268.39139) (xy 101.744251 -268.439411)
			(xy 101.759961 -268.490341) (xy 101.767904 -268.543045) (xy 101.768402 -268.569694) (xy 101.767904 -268.596343)
			(xy 101.996738 -268.596343) (xy 101.996738 -268.543045) (xy 102.004681 -268.490341) (xy 102.020391 -268.439411)
			(xy 102.043517 -268.39139) (xy 102.073541 -268.347353) (xy 102.109793 -268.308282) (xy 102.151464 -268.275051)
			(xy 102.197622 -268.248402) (xy 102.247236 -268.22893) (xy 102.299198 -268.21707) (xy 102.352348 -268.213087)
			(xy 102.405498 -268.21707) (xy 102.45746 -268.22893) (xy 102.507074 -268.248402) (xy 102.553232 -268.275051)
			(xy 102.594903 -268.308282) (xy 102.631155 -268.347353) (xy 102.661179 -268.39139) (xy 102.684305 -268.439411)
			(xy 102.700015 -268.490341) (xy 102.707958 -268.543045) (xy 102.708456 -268.569694) (xy 102.707958 -268.596343)
			(xy 102.936538 -268.596343) (xy 102.936538 -268.543045) (xy 102.944481 -268.490341) (xy 102.960191 -268.439411)
			(xy 102.983317 -268.39139) (xy 103.013341 -268.347353) (xy 103.049593 -268.308282) (xy 103.091264 -268.275051)
			(xy 103.137422 -268.248402) (xy 103.187036 -268.22893) (xy 103.238998 -268.21707) (xy 103.292148 -268.213087)
			(xy 103.345298 -268.21707) (xy 103.39726 -268.22893) (xy 103.446874 -268.248402) (xy 103.493032 -268.275051)
			(xy 103.534703 -268.308282) (xy 103.570955 -268.347353) (xy 103.600979 -268.39139) (xy 103.624105 -268.439411)
			(xy 103.639815 -268.490341) (xy 103.647758 -268.543045) (xy 103.648256 -268.569694) (xy 103.647758 -268.596343)
			(xy 103.876338 -268.596343) (xy 103.876338 -268.543045) (xy 103.884281 -268.490341) (xy 103.899991 -268.439411)
			(xy 103.923117 -268.39139) (xy 103.953141 -268.347353) (xy 103.989393 -268.308282) (xy 104.031064 -268.275051)
			(xy 104.077222 -268.248402) (xy 104.126836 -268.22893) (xy 104.178798 -268.21707) (xy 104.231948 -268.213087)
			(xy 104.285098 -268.21707) (xy 104.33706 -268.22893) (xy 104.386674 -268.248402) (xy 104.432832 -268.275051)
			(xy 104.474503 -268.308282) (xy 104.510755 -268.347353) (xy 104.540779 -268.39139) (xy 104.563905 -268.439411)
			(xy 104.579615 -268.490341) (xy 104.587558 -268.543045) (xy 104.588056 -268.569694) (xy 104.587558 -268.596343)
			(xy 104.816138 -268.596343) (xy 104.816138 -268.543045) (xy 104.824081 -268.490341) (xy 104.839791 -268.439411)
			(xy 104.862917 -268.39139) (xy 104.892941 -268.347353) (xy 104.929193 -268.308282) (xy 104.970864 -268.275051)
			(xy 105.017022 -268.248402) (xy 105.066636 -268.22893) (xy 105.118598 -268.21707) (xy 105.171748 -268.213087)
			(xy 105.224898 -268.21707) (xy 105.27686 -268.22893) (xy 105.326474 -268.248402) (xy 105.372632 -268.275051)
			(xy 105.414303 -268.308282) (xy 105.450555 -268.347353) (xy 105.480579 -268.39139) (xy 105.503705 -268.439411)
			(xy 105.519415 -268.490341) (xy 105.527358 -268.543045) (xy 105.527856 -268.569694) (xy 105.527358 -268.596343)
			(xy 105.755938 -268.596343) (xy 105.755938 -268.543045) (xy 105.763881 -268.490341) (xy 105.779591 -268.439411)
			(xy 105.802717 -268.39139) (xy 105.832741 -268.347353) (xy 105.868993 -268.308282) (xy 105.910664 -268.275051)
			(xy 105.956822 -268.248402) (xy 106.006436 -268.22893) (xy 106.058398 -268.21707) (xy 106.111548 -268.213087)
			(xy 106.164698 -268.21707) (xy 106.21666 -268.22893) (xy 106.266274 -268.248402) (xy 106.312432 -268.275051)
			(xy 106.354103 -268.308282) (xy 106.390355 -268.347353) (xy 106.420379 -268.39139) (xy 106.443505 -268.439411)
			(xy 106.459215 -268.490341) (xy 106.467158 -268.543045) (xy 106.467656 -268.569694) (xy 106.467158 -268.596343)
			(xy 106.695738 -268.596343) (xy 106.695738 -268.543045) (xy 106.703681 -268.490341) (xy 106.719391 -268.439411)
			(xy 106.742517 -268.39139) (xy 106.772541 -268.347353) (xy 106.808793 -268.308282) (xy 106.850464 -268.275051)
			(xy 106.896622 -268.248402) (xy 106.946236 -268.22893) (xy 106.998198 -268.21707) (xy 107.051348 -268.213087)
			(xy 107.104498 -268.21707) (xy 107.15646 -268.22893) (xy 107.206074 -268.248402) (xy 107.252232 -268.275051)
			(xy 107.293903 -268.308282) (xy 107.330155 -268.347353) (xy 107.360179 -268.39139) (xy 107.383305 -268.439411)
			(xy 107.399015 -268.490341) (xy 107.406958 -268.543045) (xy 107.407456 -268.569694) (xy 107.406958 -268.596343)
			(xy 107.635538 -268.596343) (xy 107.635538 -268.543045) (xy 107.643481 -268.490341) (xy 107.659191 -268.439411)
			(xy 107.682317 -268.39139) (xy 107.712341 -268.347353) (xy 107.748593 -268.308282) (xy 107.790264 -268.275051)
			(xy 107.836422 -268.248402) (xy 107.886036 -268.22893) (xy 107.937998 -268.21707) (xy 107.991148 -268.213087)
			(xy 108.044298 -268.21707) (xy 108.09626 -268.22893) (xy 108.145874 -268.248402) (xy 108.192032 -268.275051)
			(xy 108.233703 -268.308282) (xy 108.269955 -268.347353) (xy 108.299979 -268.39139) (xy 108.323105 -268.439411)
			(xy 108.338815 -268.490341) (xy 108.346758 -268.543045) (xy 108.347256 -268.569694) (xy 108.346758 -268.596343)
			(xy 108.338815 -268.649047) (xy 108.323105 -268.699977) (xy 108.299979 -268.747998) (xy 108.269955 -268.792035)
			(xy 108.233703 -268.831106) (xy 108.192032 -268.864337) (xy 108.145874 -268.890986) (xy 108.09626 -268.910458)
			(xy 108.044298 -268.922318) (xy 107.991148 -268.926302) (xy 107.937998 -268.922318) (xy 107.886036 -268.910458)
			(xy 107.836422 -268.890986) (xy 107.790264 -268.864337) (xy 107.748593 -268.831106) (xy 107.712341 -268.792035)
			(xy 107.682317 -268.747998) (xy 107.659191 -268.699977) (xy 107.643481 -268.649047) (xy 107.635538 -268.596343)
			(xy 107.406958 -268.596343) (xy 107.399015 -268.649047) (xy 107.383305 -268.699977) (xy 107.360179 -268.747998)
			(xy 107.330155 -268.792035) (xy 107.293903 -268.831106) (xy 107.252232 -268.864337) (xy 107.206074 -268.890986)
			(xy 107.15646 -268.910458) (xy 107.104498 -268.922318) (xy 107.051348 -268.926302) (xy 106.998198 -268.922318)
			(xy 106.946236 -268.910458) (xy 106.896622 -268.890986) (xy 106.850464 -268.864337) (xy 106.808793 -268.831106)
			(xy 106.772541 -268.792035) (xy 106.742517 -268.747998) (xy 106.719391 -268.699977) (xy 106.703681 -268.649047)
			(xy 106.695738 -268.596343) (xy 106.467158 -268.596343) (xy 106.459215 -268.649047) (xy 106.443505 -268.699977)
			(xy 106.420379 -268.747998) (xy 106.390355 -268.792035) (xy 106.354103 -268.831106) (xy 106.312432 -268.864337)
			(xy 106.266274 -268.890986) (xy 106.21666 -268.910458) (xy 106.164698 -268.922318) (xy 106.111548 -268.926302)
			(xy 106.058398 -268.922318) (xy 106.006436 -268.910458) (xy 105.956822 -268.890986) (xy 105.910664 -268.864337)
			(xy 105.868993 -268.831106) (xy 105.832741 -268.792035) (xy 105.802717 -268.747998) (xy 105.779591 -268.699977)
			(xy 105.763881 -268.649047) (xy 105.755938 -268.596343) (xy 105.527358 -268.596343) (xy 105.519415 -268.649047)
			(xy 105.503705 -268.699977) (xy 105.480579 -268.747998) (xy 105.450555 -268.792035) (xy 105.414303 -268.831106)
			(xy 105.372632 -268.864337) (xy 105.326474 -268.890986) (xy 105.27686 -268.910458) (xy 105.224898 -268.922318)
			(xy 105.171748 -268.926302) (xy 105.118598 -268.922318) (xy 105.066636 -268.910458) (xy 105.017022 -268.890986)
			(xy 104.970864 -268.864337) (xy 104.929193 -268.831106) (xy 104.892941 -268.792035) (xy 104.862917 -268.747998)
			(xy 104.839791 -268.699977) (xy 104.824081 -268.649047) (xy 104.816138 -268.596343) (xy 104.587558 -268.596343)
			(xy 104.579615 -268.649047) (xy 104.563905 -268.699977) (xy 104.540779 -268.747998) (xy 104.510755 -268.792035)
			(xy 104.474503 -268.831106) (xy 104.432832 -268.864337) (xy 104.386674 -268.890986) (xy 104.33706 -268.910458)
			(xy 104.285098 -268.922318) (xy 104.231948 -268.926302) (xy 104.178798 -268.922318) (xy 104.126836 -268.910458)
			(xy 104.077222 -268.890986) (xy 104.031064 -268.864337) (xy 103.989393 -268.831106) (xy 103.953141 -268.792035)
			(xy 103.923117 -268.747998) (xy 103.899991 -268.699977) (xy 103.884281 -268.649047) (xy 103.876338 -268.596343)
			(xy 103.647758 -268.596343) (xy 103.639815 -268.649047) (xy 103.624105 -268.699977) (xy 103.600979 -268.747998)
			(xy 103.570955 -268.792035) (xy 103.534703 -268.831106) (xy 103.493032 -268.864337) (xy 103.446874 -268.890986)
			(xy 103.39726 -268.910458) (xy 103.345298 -268.922318) (xy 103.292148 -268.926302) (xy 103.238998 -268.922318)
			(xy 103.187036 -268.910458) (xy 103.137422 -268.890986) (xy 103.091264 -268.864337) (xy 103.049593 -268.831106)
			(xy 103.013341 -268.792035) (xy 102.983317 -268.747998) (xy 102.960191 -268.699977) (xy 102.944481 -268.649047)
			(xy 102.936538 -268.596343) (xy 102.707958 -268.596343) (xy 102.700015 -268.649047) (xy 102.684305 -268.699977)
			(xy 102.661179 -268.747998) (xy 102.631155 -268.792035) (xy 102.594903 -268.831106) (xy 102.553232 -268.864337)
			(xy 102.507074 -268.890986) (xy 102.45746 -268.910458) (xy 102.405498 -268.922318) (xy 102.352348 -268.926302)
			(xy 102.299198 -268.922318) (xy 102.247236 -268.910458) (xy 102.197622 -268.890986) (xy 102.151464 -268.864337)
			(xy 102.109793 -268.831106) (xy 102.073541 -268.792035) (xy 102.043517 -268.747998) (xy 102.020391 -268.699977)
			(xy 102.004681 -268.649047) (xy 101.996738 -268.596343) (xy 101.767904 -268.596343) (xy 101.759961 -268.649047)
			(xy 101.744251 -268.699977) (xy 101.721125 -268.747998) (xy 101.691101 -268.792035) (xy 101.654849 -268.831106)
			(xy 101.613178 -268.864337) (xy 101.56702 -268.890986) (xy 101.517406 -268.910458) (xy 101.465444 -268.922318)
			(xy 101.412294 -268.926302) (xy 101.359144 -268.922318) (xy 101.307182 -268.910458) (xy 101.257568 -268.890986)
			(xy 101.21141 -268.864337) (xy 101.169739 -268.831106) (xy 101.133487 -268.792035) (xy 101.103463 -268.747998)
			(xy 101.080337 -268.699977) (xy 101.064627 -268.649047) (xy 101.056684 -268.596343) (xy 100.828358 -268.596343)
			(xy 100.820415 -268.649047) (xy 100.804705 -268.699977) (xy 100.781579 -268.747998) (xy 100.751555 -268.792035)
			(xy 100.715303 -268.831106) (xy 100.673632 -268.864337) (xy 100.627474 -268.890986) (xy 100.57786 -268.910458)
			(xy 100.525898 -268.922318) (xy 100.472748 -268.926302) (xy 100.419598 -268.922318) (xy 100.367636 -268.910458)
			(xy 100.318022 -268.890986) (xy 100.271864 -268.864337) (xy 100.230193 -268.831106) (xy 100.193941 -268.792035)
			(xy 100.163917 -268.747998) (xy 100.140791 -268.699977) (xy 100.125081 -268.649047) (xy 100.117138 -268.596343)
			(xy 99.888558 -268.596343) (xy 99.880615 -268.649047) (xy 99.864905 -268.699977) (xy 99.841779 -268.747998)
			(xy 99.811755 -268.792035) (xy 99.775503 -268.831106) (xy 99.733832 -268.864337) (xy 99.687674 -268.890986)
			(xy 99.63806 -268.910458) (xy 99.586098 -268.922318) (xy 99.532948 -268.926302) (xy 99.479798 -268.922318)
			(xy 99.427836 -268.910458) (xy 99.378222 -268.890986) (xy 99.332064 -268.864337) (xy 99.290393 -268.831106)
			(xy 99.254141 -268.792035) (xy 99.224117 -268.747998) (xy 99.200991 -268.699977) (xy 99.185281 -268.649047)
			(xy 99.177338 -268.596343) (xy 98.948758 -268.596343) (xy 98.940815 -268.649047) (xy 98.925105 -268.699977)
			(xy 98.901979 -268.747998) (xy 98.871955 -268.792035) (xy 98.835703 -268.831106) (xy 98.794032 -268.864337)
			(xy 98.747874 -268.890986) (xy 98.69826 -268.910458) (xy 98.646298 -268.922318) (xy 98.593148 -268.926302)
			(xy 98.539998 -268.922318) (xy 98.488036 -268.910458) (xy 98.438422 -268.890986) (xy 98.392264 -268.864337)
			(xy 98.350593 -268.831106) (xy 98.314341 -268.792035) (xy 98.284317 -268.747998) (xy 98.261191 -268.699977)
			(xy 98.245481 -268.649047) (xy 98.237538 -268.596343) (xy 98.008958 -268.596343) (xy 98.001015 -268.649047)
			(xy 97.985305 -268.699977) (xy 97.962179 -268.747998) (xy 97.932155 -268.792035) (xy 97.895903 -268.831106)
			(xy 97.854232 -268.864337) (xy 97.808074 -268.890986) (xy 97.75846 -268.910458) (xy 97.706498 -268.922318)
			(xy 97.653348 -268.926302) (xy 97.600198 -268.922318) (xy 97.548236 -268.910458) (xy 97.498622 -268.890986)
			(xy 97.452464 -268.864337) (xy 97.410793 -268.831106) (xy 97.374541 -268.792035) (xy 97.344517 -268.747998)
			(xy 97.321391 -268.699977) (xy 97.305681 -268.649047) (xy 97.297738 -268.596343) (xy 97.069158 -268.596343)
			(xy 97.061215 -268.649047) (xy 97.045505 -268.699977) (xy 97.022379 -268.747998) (xy 96.992355 -268.792035)
			(xy 96.956103 -268.831106) (xy 96.914432 -268.864337) (xy 96.868274 -268.890986) (xy 96.81866 -268.910458)
			(xy 96.766698 -268.922318) (xy 96.713548 -268.926302) (xy 96.660398 -268.922318) (xy 96.608436 -268.910458)
			(xy 96.558822 -268.890986) (xy 96.512664 -268.864337) (xy 96.470993 -268.831106) (xy 96.434741 -268.792035)
			(xy 96.404717 -268.747998) (xy 96.381591 -268.699977) (xy 96.365881 -268.649047) (xy 96.357938 -268.596343)
			(xy 96.129358 -268.596343) (xy 96.121415 -268.649047) (xy 96.105705 -268.699977) (xy 96.082579 -268.747998)
			(xy 96.052555 -268.792035) (xy 96.016303 -268.831106) (xy 95.974632 -268.864337) (xy 95.928474 -268.890986)
			(xy 95.87886 -268.910458) (xy 95.826898 -268.922318) (xy 95.773748 -268.926302) (xy 95.720598 -268.922318)
			(xy 95.668636 -268.910458) (xy 95.619022 -268.890986) (xy 95.572864 -268.864337) (xy 95.531193 -268.831106)
			(xy 95.494941 -268.792035) (xy 95.464917 -268.747998) (xy 95.441791 -268.699977) (xy 95.426081 -268.649047)
			(xy 95.418138 -268.596343) (xy 95.189304 -268.596343) (xy 95.181361 -268.649047) (xy 95.165651 -268.699977)
			(xy 95.142525 -268.747998) (xy 95.112501 -268.792035) (xy 95.076249 -268.831106) (xy 95.034578 -268.864337)
			(xy 94.98842 -268.890986) (xy 94.938806 -268.910458) (xy 94.886844 -268.922318) (xy 94.833694 -268.926302)
			(xy 94.780544 -268.922318) (xy 94.728582 -268.910458) (xy 94.678968 -268.890986) (xy 94.63281 -268.864337)
			(xy 94.591139 -268.831106) (xy 94.554887 -268.792035) (xy 94.524863 -268.747998) (xy 94.501737 -268.699977)
			(xy 94.486027 -268.649047) (xy 94.478084 -268.596343) (xy 94.249758 -268.596343) (xy 94.241815 -268.649047)
			(xy 94.226105 -268.699977) (xy 94.202979 -268.747998) (xy 94.172955 -268.792035) (xy 94.136703 -268.831106)
			(xy 94.095032 -268.864337) (xy 94.048874 -268.890986) (xy 93.99926 -268.910458) (xy 93.947298 -268.922318)
			(xy 93.894148 -268.926302) (xy 93.840998 -268.922318) (xy 93.789036 -268.910458) (xy 93.739422 -268.890986)
			(xy 93.693264 -268.864337) (xy 93.651593 -268.831106) (xy 93.615341 -268.792035) (xy 93.585317 -268.747998)
			(xy 93.562191 -268.699977) (xy 93.546481 -268.649047) (xy 93.538538 -268.596343) (xy 93.309958 -268.596343)
			(xy 93.302015 -268.649047) (xy 93.286305 -268.699977) (xy 93.263179 -268.747998) (xy 93.233155 -268.792035)
			(xy 93.196903 -268.831106) (xy 93.155232 -268.864337) (xy 93.109074 -268.890986) (xy 93.05946 -268.910458)
			(xy 93.007498 -268.922318) (xy 92.954348 -268.926302) (xy 92.901198 -268.922318) (xy 92.849236 -268.910458)
			(xy 92.799622 -268.890986) (xy 92.753464 -268.864337) (xy 92.711793 -268.831106) (xy 92.675541 -268.792035)
			(xy 92.645517 -268.747998) (xy 92.622391 -268.699977) (xy 92.606681 -268.649047) (xy 92.598738 -268.596343)
			(xy 92.370158 -268.596343) (xy 92.362215 -268.649047) (xy 92.346505 -268.699977) (xy 92.323379 -268.747998)
			(xy 92.293355 -268.792035) (xy 92.257103 -268.831106) (xy 92.215432 -268.864337) (xy 92.169274 -268.890986)
			(xy 92.11966 -268.910458) (xy 92.067698 -268.922318) (xy 92.014548 -268.926302) (xy 91.961398 -268.922318)
			(xy 91.909436 -268.910458) (xy 91.859822 -268.890986) (xy 91.813664 -268.864337) (xy 91.771993 -268.831106)
			(xy 91.735741 -268.792035) (xy 91.705717 -268.747998) (xy 91.682591 -268.699977) (xy 91.666881 -268.649047)
			(xy 91.658938 -268.596343) (xy 91.430358 -268.596343) (xy 91.422415 -268.649047) (xy 91.406705 -268.699977)
			(xy 91.383579 -268.747998) (xy 91.353555 -268.792035) (xy 91.317303 -268.831106) (xy 91.275632 -268.864337)
			(xy 91.229474 -268.890986) (xy 91.17986 -268.910458) (xy 91.127898 -268.922318) (xy 91.074748 -268.926302)
			(xy 91.021598 -268.922318) (xy 90.969636 -268.910458) (xy 90.920022 -268.890986) (xy 90.873864 -268.864337)
			(xy 90.832193 -268.831106) (xy 90.795941 -268.792035) (xy 90.765917 -268.747998) (xy 90.742791 -268.699977)
			(xy 90.727081 -268.649047) (xy 90.719138 -268.596343) (xy 90.490304 -268.596343) (xy 90.482361 -268.649047)
			(xy 90.466651 -268.699977) (xy 90.443525 -268.747998) (xy 90.413501 -268.792035) (xy 90.377249 -268.831106)
			(xy 90.335578 -268.864337) (xy 90.28942 -268.890986) (xy 90.239806 -268.910458) (xy 90.187844 -268.922318)
			(xy 90.134694 -268.926302) (xy 90.081544 -268.922318) (xy 90.029582 -268.910458) (xy 89.979968 -268.890986)
			(xy 89.93381 -268.864337) (xy 89.892139 -268.831106) (xy 89.855887 -268.792035) (xy 89.825863 -268.747998)
			(xy 89.802737 -268.699977) (xy 89.787027 -268.649047) (xy 89.779084 -268.596343) (xy 89.550504 -268.596343)
			(xy 89.542561 -268.649047) (xy 89.526851 -268.699977) (xy 89.503725 -268.747998) (xy 89.473701 -268.792035)
			(xy 89.437449 -268.831106) (xy 89.395778 -268.864337) (xy 89.34962 -268.890986) (xy 89.300006 -268.910458)
			(xy 89.248044 -268.922318) (xy 89.194894 -268.926302) (xy 89.141744 -268.922318) (xy 89.089782 -268.910458)
			(xy 89.040168 -268.890986) (xy 88.99401 -268.864337) (xy 88.952339 -268.831106) (xy 88.916087 -268.792035)
			(xy 88.886063 -268.747998) (xy 88.862937 -268.699977) (xy 88.847227 -268.649047) (xy 88.839284 -268.596343)
			(xy 88.688418 -268.596343) (xy 88.688418 -268.976856) (xy 88.688871 -268.986642) (xy 88.696211 -269.004787)
			(xy 88.709803 -269.01887) (xy 88.727676 -269.026849) (xy 88.73744 -269.027656) (xy 88.764764 -269.029112)
			(xy 88.818511 -269.039367) (xy 88.870057 -269.057723) (xy 88.918187 -269.083749) (xy 88.96177 -269.116831)
			(xy 88.999778 -269.156192) (xy 89.031318 -269.200904) (xy 89.055646 -269.249914) (xy 89.07219 -269.30207)
			(xy 89.080561 -269.356142) (xy 89.080561 -269.410159) (xy 89.309184 -269.410159) (xy 89.309184 -269.356861)
			(xy 89.317127 -269.304157) (xy 89.332837 -269.253227) (xy 89.355963 -269.205206) (xy 89.385987 -269.161169)
			(xy 89.422239 -269.122098) (xy 89.46391 -269.088867) (xy 89.510068 -269.062218) (xy 89.559682 -269.042746)
			(xy 89.611644 -269.030886) (xy 89.664794 -269.026903) (xy 89.717944 -269.030886) (xy 89.769906 -269.042746)
			(xy 89.81952 -269.062218) (xy 89.865678 -269.088867) (xy 89.907349 -269.122098) (xy 89.943601 -269.161169)
			(xy 89.973625 -269.205206) (xy 89.996751 -269.253227) (xy 90.012461 -269.304157) (xy 90.020404 -269.356861)
			(xy 90.020902 -269.38351) (xy 90.020404 -269.410159) (xy 90.248984 -269.410159) (xy 90.248984 -269.356861)
			(xy 90.256927 -269.304157) (xy 90.272637 -269.253227) (xy 90.295763 -269.205206) (xy 90.325787 -269.161169)
			(xy 90.362039 -269.122098) (xy 90.40371 -269.088867) (xy 90.449868 -269.062218) (xy 90.499482 -269.042746)
			(xy 90.551444 -269.030886) (xy 90.604594 -269.026903) (xy 90.657744 -269.030886) (xy 90.709706 -269.042746)
			(xy 90.75932 -269.062218) (xy 90.805478 -269.088867) (xy 90.847149 -269.122098) (xy 90.883401 -269.161169)
			(xy 90.913425 -269.205206) (xy 90.936551 -269.253227) (xy 90.952261 -269.304157) (xy 90.960204 -269.356861)
			(xy 90.960702 -269.38351) (xy 90.960204 -269.410159) (xy 91.189038 -269.410159) (xy 91.189038 -269.356861)
			(xy 91.196981 -269.304157) (xy 91.212691 -269.253227) (xy 91.235817 -269.205206) (xy 91.265841 -269.161169)
			(xy 91.302093 -269.122098) (xy 91.343764 -269.088867) (xy 91.389922 -269.062218) (xy 91.439536 -269.042746)
			(xy 91.491498 -269.030886) (xy 91.544648 -269.026903) (xy 91.597798 -269.030886) (xy 91.64976 -269.042746)
			(xy 91.699374 -269.062218) (xy 91.745532 -269.088867) (xy 91.787203 -269.122098) (xy 91.823455 -269.161169)
			(xy 91.853479 -269.205206) (xy 91.876605 -269.253227) (xy 91.892315 -269.304157) (xy 91.900258 -269.356861)
			(xy 91.900756 -269.38351) (xy 91.900258 -269.410159) (xy 92.128584 -269.410159) (xy 92.128584 -269.356861)
			(xy 92.136527 -269.304157) (xy 92.152237 -269.253227) (xy 92.175363 -269.205206) (xy 92.205387 -269.161169)
			(xy 92.241639 -269.122098) (xy 92.28331 -269.088867) (xy 92.329468 -269.062218) (xy 92.379082 -269.042746)
			(xy 92.431044 -269.030886) (xy 92.484194 -269.026903) (xy 92.537344 -269.030886) (xy 92.589306 -269.042746)
			(xy 92.63892 -269.062218) (xy 92.685078 -269.088867) (xy 92.726749 -269.122098) (xy 92.763001 -269.161169)
			(xy 92.793025 -269.205206) (xy 92.816151 -269.253227) (xy 92.831861 -269.304157) (xy 92.839804 -269.356861)
			(xy 92.840302 -269.38351) (xy 92.839804 -269.410159) (xy 93.068384 -269.410159) (xy 93.068384 -269.356861)
			(xy 93.076327 -269.304157) (xy 93.092037 -269.253227) (xy 93.115163 -269.205206) (xy 93.145187 -269.161169)
			(xy 93.181439 -269.122098) (xy 93.22311 -269.088867) (xy 93.269268 -269.062218) (xy 93.318882 -269.042746)
			(xy 93.370844 -269.030886) (xy 93.423994 -269.026903) (xy 93.477144 -269.030886) (xy 93.529106 -269.042746)
			(xy 93.57872 -269.062218) (xy 93.624878 -269.088867) (xy 93.666549 -269.122098) (xy 93.702801 -269.161169)
			(xy 93.732825 -269.205206) (xy 93.755951 -269.253227) (xy 93.771661 -269.304157) (xy 93.779604 -269.356861)
			(xy 93.780102 -269.38351) (xy 93.779604 -269.410159) (xy 94.008184 -269.410159) (xy 94.008184 -269.356861)
			(xy 94.016127 -269.304157) (xy 94.031837 -269.253227) (xy 94.054963 -269.205206) (xy 94.084987 -269.161169)
			(xy 94.121239 -269.122098) (xy 94.16291 -269.088867) (xy 94.209068 -269.062218) (xy 94.258682 -269.042746)
			(xy 94.310644 -269.030886) (xy 94.363794 -269.026903) (xy 94.416944 -269.030886) (xy 94.468906 -269.042746)
			(xy 94.51852 -269.062218) (xy 94.564678 -269.088867) (xy 94.606349 -269.122098) (xy 94.642601 -269.161169)
			(xy 94.672625 -269.205206) (xy 94.695751 -269.253227) (xy 94.711461 -269.304157) (xy 94.719404 -269.356861)
			(xy 94.719902 -269.38351) (xy 94.719404 -269.410159) (xy 94.947984 -269.410159) (xy 94.947984 -269.356861)
			(xy 94.955927 -269.304157) (xy 94.971637 -269.253227) (xy 94.994763 -269.205206) (xy 95.024787 -269.161169)
			(xy 95.061039 -269.122098) (xy 95.10271 -269.088867) (xy 95.148868 -269.062218) (xy 95.198482 -269.042746)
			(xy 95.250444 -269.030886) (xy 95.303594 -269.026903) (xy 95.356744 -269.030886) (xy 95.408706 -269.042746)
			(xy 95.45832 -269.062218) (xy 95.504478 -269.088867) (xy 95.546149 -269.122098) (xy 95.582401 -269.161169)
			(xy 95.612425 -269.205206) (xy 95.635551 -269.253227) (xy 95.651261 -269.304157) (xy 95.659204 -269.356861)
			(xy 95.659702 -269.38351) (xy 95.659204 -269.410159) (xy 95.887784 -269.410159) (xy 95.887784 -269.356861)
			(xy 95.895727 -269.304157) (xy 95.911437 -269.253227) (xy 95.934563 -269.205206) (xy 95.964587 -269.161169)
			(xy 96.000839 -269.122098) (xy 96.04251 -269.088867) (xy 96.088668 -269.062218) (xy 96.138282 -269.042746)
			(xy 96.190244 -269.030886) (xy 96.243394 -269.026903) (xy 96.296544 -269.030886) (xy 96.348506 -269.042746)
			(xy 96.39812 -269.062218) (xy 96.444278 -269.088867) (xy 96.485949 -269.122098) (xy 96.522201 -269.161169)
			(xy 96.552225 -269.205206) (xy 96.575351 -269.253227) (xy 96.591061 -269.304157) (xy 96.599004 -269.356861)
			(xy 96.599502 -269.38351) (xy 96.599004 -269.410159) (xy 96.827584 -269.410159) (xy 96.827584 -269.356861)
			(xy 96.835527 -269.304157) (xy 96.851237 -269.253227) (xy 96.874363 -269.205206) (xy 96.904387 -269.161169)
			(xy 96.940639 -269.122098) (xy 96.98231 -269.088867) (xy 97.028468 -269.062218) (xy 97.078082 -269.042746)
			(xy 97.130044 -269.030886) (xy 97.183194 -269.026903) (xy 97.236344 -269.030886) (xy 97.288306 -269.042746)
			(xy 97.33792 -269.062218) (xy 97.384078 -269.088867) (xy 97.425749 -269.122098) (xy 97.462001 -269.161169)
			(xy 97.492025 -269.205206) (xy 97.515151 -269.253227) (xy 97.530861 -269.304157) (xy 97.538804 -269.356861)
			(xy 97.539302 -269.38351) (xy 97.538804 -269.410159) (xy 97.767638 -269.410159) (xy 97.767638 -269.356861)
			(xy 97.775581 -269.304157) (xy 97.791291 -269.253227) (xy 97.814417 -269.205206) (xy 97.844441 -269.161169)
			(xy 97.880693 -269.122098) (xy 97.922364 -269.088867) (xy 97.968522 -269.062218) (xy 98.018136 -269.042746)
			(xy 98.070098 -269.030886) (xy 98.123248 -269.026903) (xy 98.176398 -269.030886) (xy 98.22836 -269.042746)
			(xy 98.277974 -269.062218) (xy 98.324132 -269.088867) (xy 98.365803 -269.122098) (xy 98.402055 -269.161169)
			(xy 98.432079 -269.205206) (xy 98.455205 -269.253227) (xy 98.470915 -269.304157) (xy 98.478858 -269.356861)
			(xy 98.479356 -269.38351) (xy 98.478858 -269.410159) (xy 98.707184 -269.410159) (xy 98.707184 -269.356861)
			(xy 98.715127 -269.304157) (xy 98.730837 -269.253227) (xy 98.753963 -269.205206) (xy 98.783987 -269.161169)
			(xy 98.820239 -269.122098) (xy 98.86191 -269.088867) (xy 98.908068 -269.062218) (xy 98.957682 -269.042746)
			(xy 99.009644 -269.030886) (xy 99.062794 -269.026903) (xy 99.115944 -269.030886) (xy 99.167906 -269.042746)
			(xy 99.21752 -269.062218) (xy 99.263678 -269.088867) (xy 99.305349 -269.122098) (xy 99.341601 -269.161169)
			(xy 99.371625 -269.205206) (xy 99.394751 -269.253227) (xy 99.410461 -269.304157) (xy 99.418404 -269.356861)
			(xy 99.418902 -269.38351) (xy 99.418404 -269.410159) (xy 99.646984 -269.410159) (xy 99.646984 -269.356861)
			(xy 99.654927 -269.304157) (xy 99.670637 -269.253227) (xy 99.693763 -269.205206) (xy 99.723787 -269.161169)
			(xy 99.760039 -269.122098) (xy 99.80171 -269.088867) (xy 99.847868 -269.062218) (xy 99.897482 -269.042746)
			(xy 99.949444 -269.030886) (xy 100.002594 -269.026903) (xy 100.055744 -269.030886) (xy 100.107706 -269.042746)
			(xy 100.15732 -269.062218) (xy 100.203478 -269.088867) (xy 100.245149 -269.122098) (xy 100.281401 -269.161169)
			(xy 100.311425 -269.205206) (xy 100.334551 -269.253227) (xy 100.350261 -269.304157) (xy 100.358204 -269.356861)
			(xy 100.358702 -269.38351) (xy 100.358204 -269.410159) (xy 100.586784 -269.410159) (xy 100.586784 -269.356861)
			(xy 100.594727 -269.304157) (xy 100.610437 -269.253227) (xy 100.633563 -269.205206) (xy 100.663587 -269.161169)
			(xy 100.699839 -269.122098) (xy 100.74151 -269.088867) (xy 100.787668 -269.062218) (xy 100.837282 -269.042746)
			(xy 100.889244 -269.030886) (xy 100.942394 -269.026903) (xy 100.995544 -269.030886) (xy 101.047506 -269.042746)
			(xy 101.09712 -269.062218) (xy 101.143278 -269.088867) (xy 101.184949 -269.122098) (xy 101.221201 -269.161169)
			(xy 101.251225 -269.205206) (xy 101.274351 -269.253227) (xy 101.290061 -269.304157) (xy 101.298004 -269.356861)
			(xy 101.298502 -269.38351) (xy 101.298004 -269.410159) (xy 101.527092 -269.410159) (xy 101.527092 -269.356861)
			(xy 101.535035 -269.304157) (xy 101.550745 -269.253227) (xy 101.573871 -269.205206) (xy 101.603895 -269.161169)
			(xy 101.640147 -269.122098) (xy 101.681818 -269.088867) (xy 101.727976 -269.062218) (xy 101.77759 -269.042746)
			(xy 101.829552 -269.030886) (xy 101.882702 -269.026903) (xy 101.935852 -269.030886) (xy 101.987814 -269.042746)
			(xy 102.037428 -269.062218) (xy 102.083586 -269.088867) (xy 102.125257 -269.122098) (xy 102.161509 -269.161169)
			(xy 102.191533 -269.205206) (xy 102.214659 -269.253227) (xy 102.230369 -269.304157) (xy 102.238312 -269.356861)
			(xy 102.23881 -269.38351) (xy 102.238312 -269.410159) (xy 102.466384 -269.410159) (xy 102.466384 -269.356861)
			(xy 102.474327 -269.304157) (xy 102.490037 -269.253227) (xy 102.513163 -269.205206) (xy 102.543187 -269.161169)
			(xy 102.579439 -269.122098) (xy 102.62111 -269.088867) (xy 102.667268 -269.062218) (xy 102.716882 -269.042746)
			(xy 102.768844 -269.030886) (xy 102.821994 -269.026903) (xy 102.875144 -269.030886) (xy 102.927106 -269.042746)
			(xy 102.97672 -269.062218) (xy 103.022878 -269.088867) (xy 103.064549 -269.122098) (xy 103.100801 -269.161169)
			(xy 103.130825 -269.205206) (xy 103.153951 -269.253227) (xy 103.169661 -269.304157) (xy 103.177604 -269.356861)
			(xy 103.178102 -269.38351) (xy 103.177604 -269.410159) (xy 103.406184 -269.410159) (xy 103.406184 -269.356861)
			(xy 103.414127 -269.304157) (xy 103.429837 -269.253227) (xy 103.452963 -269.205206) (xy 103.482987 -269.161169)
			(xy 103.519239 -269.122098) (xy 103.56091 -269.088867) (xy 103.607068 -269.062218) (xy 103.656682 -269.042746)
			(xy 103.708644 -269.030886) (xy 103.761794 -269.026903) (xy 103.814944 -269.030886) (xy 103.866906 -269.042746)
			(xy 103.91652 -269.062218) (xy 103.962678 -269.088867) (xy 104.004349 -269.122098) (xy 104.040601 -269.161169)
			(xy 104.070625 -269.205206) (xy 104.093751 -269.253227) (xy 104.109461 -269.304157) (xy 104.117404 -269.356861)
			(xy 104.117902 -269.38351) (xy 104.117404 -269.410159) (xy 104.345984 -269.410159) (xy 104.345984 -269.356861)
			(xy 104.353927 -269.304157) (xy 104.369637 -269.253227) (xy 104.392763 -269.205206) (xy 104.422787 -269.161169)
			(xy 104.459039 -269.122098) (xy 104.50071 -269.088867) (xy 104.546868 -269.062218) (xy 104.596482 -269.042746)
			(xy 104.648444 -269.030886) (xy 104.701594 -269.026903) (xy 104.754744 -269.030886) (xy 104.806706 -269.042746)
			(xy 104.85632 -269.062218) (xy 104.902478 -269.088867) (xy 104.944149 -269.122098) (xy 104.980401 -269.161169)
			(xy 105.010425 -269.205206) (xy 105.033551 -269.253227) (xy 105.049261 -269.304157) (xy 105.057204 -269.356861)
			(xy 105.057702 -269.38351) (xy 105.057204 -269.410159) (xy 105.285784 -269.410159) (xy 105.285784 -269.356861)
			(xy 105.293727 -269.304157) (xy 105.309437 -269.253227) (xy 105.332563 -269.205206) (xy 105.362587 -269.161169)
			(xy 105.398839 -269.122098) (xy 105.44051 -269.088867) (xy 105.486668 -269.062218) (xy 105.536282 -269.042746)
			(xy 105.588244 -269.030886) (xy 105.641394 -269.026903) (xy 105.694544 -269.030886) (xy 105.746506 -269.042746)
			(xy 105.79612 -269.062218) (xy 105.842278 -269.088867) (xy 105.883949 -269.122098) (xy 105.920201 -269.161169)
			(xy 105.950225 -269.205206) (xy 105.973351 -269.253227) (xy 105.989061 -269.304157) (xy 105.997004 -269.356861)
			(xy 105.997502 -269.38351) (xy 105.997004 -269.410159) (xy 106.225584 -269.410159) (xy 106.225584 -269.356861)
			(xy 106.233527 -269.304157) (xy 106.249237 -269.253227) (xy 106.272363 -269.205206) (xy 106.302387 -269.161169)
			(xy 106.338639 -269.122098) (xy 106.38031 -269.088867) (xy 106.426468 -269.062218) (xy 106.476082 -269.042746)
			(xy 106.528044 -269.030886) (xy 106.581194 -269.026903) (xy 106.634344 -269.030886) (xy 106.686306 -269.042746)
			(xy 106.73592 -269.062218) (xy 106.782078 -269.088867) (xy 106.823749 -269.122098) (xy 106.860001 -269.161169)
			(xy 106.890025 -269.205206) (xy 106.913151 -269.253227) (xy 106.928861 -269.304157) (xy 106.936804 -269.356861)
			(xy 106.937302 -269.38351) (xy 106.936804 -269.410159) (xy 107.165384 -269.410159) (xy 107.165384 -269.356861)
			(xy 107.173327 -269.304157) (xy 107.189037 -269.253227) (xy 107.212163 -269.205206) (xy 107.242187 -269.161169)
			(xy 107.278439 -269.122098) (xy 107.32011 -269.088867) (xy 107.366268 -269.062218) (xy 107.415882 -269.042746)
			(xy 107.467844 -269.030886) (xy 107.520994 -269.026903) (xy 107.574144 -269.030886) (xy 107.626106 -269.042746)
			(xy 107.67572 -269.062218) (xy 107.721878 -269.088867) (xy 107.763549 -269.122098) (xy 107.799801 -269.161169)
			(xy 107.829825 -269.205206) (xy 107.852951 -269.253227) (xy 107.868661 -269.304157) (xy 107.876604 -269.356861)
			(xy 107.877102 -269.38351) (xy 107.876604 -269.410159) (xy 107.868661 -269.462863) (xy 107.852951 -269.513793)
			(xy 107.829825 -269.561814) (xy 107.799801 -269.605851) (xy 107.763549 -269.644922) (xy 107.721878 -269.678153)
			(xy 107.67572 -269.704802) (xy 107.626106 -269.724274) (xy 107.574144 -269.736134) (xy 107.520994 -269.740118)
			(xy 107.467844 -269.736134) (xy 107.415882 -269.724274) (xy 107.366268 -269.704802) (xy 107.32011 -269.678153)
			(xy 107.278439 -269.644922) (xy 107.242187 -269.605851) (xy 107.212163 -269.561814) (xy 107.189037 -269.513793)
			(xy 107.173327 -269.462863) (xy 107.165384 -269.410159) (xy 106.936804 -269.410159) (xy 106.928861 -269.462863)
			(xy 106.913151 -269.513793) (xy 106.890025 -269.561814) (xy 106.860001 -269.605851) (xy 106.823749 -269.644922)
			(xy 106.782078 -269.678153) (xy 106.73592 -269.704802) (xy 106.686306 -269.724274) (xy 106.634344 -269.736134)
			(xy 106.581194 -269.740118) (xy 106.528044 -269.736134) (xy 106.476082 -269.724274) (xy 106.426468 -269.704802)
			(xy 106.38031 -269.678153) (xy 106.338639 -269.644922) (xy 106.302387 -269.605851) (xy 106.272363 -269.561814)
			(xy 106.249237 -269.513793) (xy 106.233527 -269.462863) (xy 106.225584 -269.410159) (xy 105.997004 -269.410159)
			(xy 105.989061 -269.462863) (xy 105.973351 -269.513793) (xy 105.950225 -269.561814) (xy 105.920201 -269.605851)
			(xy 105.883949 -269.644922) (xy 105.842278 -269.678153) (xy 105.79612 -269.704802) (xy 105.746506 -269.724274)
			(xy 105.694544 -269.736134) (xy 105.641394 -269.740118) (xy 105.588244 -269.736134) (xy 105.536282 -269.724274)
			(xy 105.486668 -269.704802) (xy 105.44051 -269.678153) (xy 105.398839 -269.644922) (xy 105.362587 -269.605851)
			(xy 105.332563 -269.561814) (xy 105.309437 -269.513793) (xy 105.293727 -269.462863) (xy 105.285784 -269.410159)
			(xy 105.057204 -269.410159) (xy 105.049261 -269.462863) (xy 105.033551 -269.513793) (xy 105.010425 -269.561814)
			(xy 104.980401 -269.605851) (xy 104.944149 -269.644922) (xy 104.902478 -269.678153) (xy 104.85632 -269.704802)
			(xy 104.806706 -269.724274) (xy 104.754744 -269.736134) (xy 104.701594 -269.740118) (xy 104.648444 -269.736134)
			(xy 104.596482 -269.724274) (xy 104.546868 -269.704802) (xy 104.50071 -269.678153) (xy 104.459039 -269.644922)
			(xy 104.422787 -269.605851) (xy 104.392763 -269.561814) (xy 104.369637 -269.513793) (xy 104.353927 -269.462863)
			(xy 104.345984 -269.410159) (xy 104.117404 -269.410159) (xy 104.109461 -269.462863) (xy 104.093751 -269.513793)
			(xy 104.070625 -269.561814) (xy 104.040601 -269.605851) (xy 104.004349 -269.644922) (xy 103.962678 -269.678153)
			(xy 103.91652 -269.704802) (xy 103.866906 -269.724274) (xy 103.814944 -269.736134) (xy 103.761794 -269.740118)
			(xy 103.708644 -269.736134) (xy 103.656682 -269.724274) (xy 103.607068 -269.704802) (xy 103.56091 -269.678153)
			(xy 103.519239 -269.644922) (xy 103.482987 -269.605851) (xy 103.452963 -269.561814) (xy 103.429837 -269.513793)
			(xy 103.414127 -269.462863) (xy 103.406184 -269.410159) (xy 103.177604 -269.410159) (xy 103.169661 -269.462863)
			(xy 103.153951 -269.513793) (xy 103.130825 -269.561814) (xy 103.100801 -269.605851) (xy 103.064549 -269.644922)
			(xy 103.022878 -269.678153) (xy 102.97672 -269.704802) (xy 102.927106 -269.724274) (xy 102.875144 -269.736134)
			(xy 102.821994 -269.740118) (xy 102.768844 -269.736134) (xy 102.716882 -269.724274) (xy 102.667268 -269.704802)
			(xy 102.62111 -269.678153) (xy 102.579439 -269.644922) (xy 102.543187 -269.605851) (xy 102.513163 -269.561814)
			(xy 102.490037 -269.513793) (xy 102.474327 -269.462863) (xy 102.466384 -269.410159) (xy 102.238312 -269.410159)
			(xy 102.230369 -269.462863) (xy 102.214659 -269.513793) (xy 102.191533 -269.561814) (xy 102.161509 -269.605851)
			(xy 102.125257 -269.644922) (xy 102.083586 -269.678153) (xy 102.037428 -269.704802) (xy 101.987814 -269.724274)
			(xy 101.935852 -269.736134) (xy 101.882702 -269.740118) (xy 101.829552 -269.736134) (xy 101.77759 -269.724274)
			(xy 101.727976 -269.704802) (xy 101.681818 -269.678153) (xy 101.640147 -269.644922) (xy 101.603895 -269.605851)
			(xy 101.573871 -269.561814) (xy 101.550745 -269.513793) (xy 101.535035 -269.462863) (xy 101.527092 -269.410159)
			(xy 101.298004 -269.410159) (xy 101.290061 -269.462863) (xy 101.274351 -269.513793) (xy 101.251225 -269.561814)
			(xy 101.221201 -269.605851) (xy 101.184949 -269.644922) (xy 101.143278 -269.678153) (xy 101.09712 -269.704802)
			(xy 101.047506 -269.724274) (xy 100.995544 -269.736134) (xy 100.942394 -269.740118) (xy 100.889244 -269.736134)
			(xy 100.837282 -269.724274) (xy 100.787668 -269.704802) (xy 100.74151 -269.678153) (xy 100.699839 -269.644922)
			(xy 100.663587 -269.605851) (xy 100.633563 -269.561814) (xy 100.610437 -269.513793) (xy 100.594727 -269.462863)
			(xy 100.586784 -269.410159) (xy 100.358204 -269.410159) (xy 100.350261 -269.462863) (xy 100.334551 -269.513793)
			(xy 100.311425 -269.561814) (xy 100.281401 -269.605851) (xy 100.245149 -269.644922) (xy 100.203478 -269.678153)
			(xy 100.15732 -269.704802) (xy 100.107706 -269.724274) (xy 100.055744 -269.736134) (xy 100.002594 -269.740118)
			(xy 99.949444 -269.736134) (xy 99.897482 -269.724274) (xy 99.847868 -269.704802) (xy 99.80171 -269.678153)
			(xy 99.760039 -269.644922) (xy 99.723787 -269.605851) (xy 99.693763 -269.561814) (xy 99.670637 -269.513793)
			(xy 99.654927 -269.462863) (xy 99.646984 -269.410159) (xy 99.418404 -269.410159) (xy 99.410461 -269.462863)
			(xy 99.394751 -269.513793) (xy 99.371625 -269.561814) (xy 99.341601 -269.605851) (xy 99.305349 -269.644922)
			(xy 99.263678 -269.678153) (xy 99.21752 -269.704802) (xy 99.167906 -269.724274) (xy 99.115944 -269.736134)
			(xy 99.062794 -269.740118) (xy 99.009644 -269.736134) (xy 98.957682 -269.724274) (xy 98.908068 -269.704802)
			(xy 98.86191 -269.678153) (xy 98.820239 -269.644922) (xy 98.783987 -269.605851) (xy 98.753963 -269.561814)
			(xy 98.730837 -269.513793) (xy 98.715127 -269.462863) (xy 98.707184 -269.410159) (xy 98.478858 -269.410159)
			(xy 98.470915 -269.462863) (xy 98.455205 -269.513793) (xy 98.432079 -269.561814) (xy 98.402055 -269.605851)
			(xy 98.365803 -269.644922) (xy 98.324132 -269.678153) (xy 98.277974 -269.704802) (xy 98.22836 -269.724274)
			(xy 98.176398 -269.736134) (xy 98.123248 -269.740118) (xy 98.070098 -269.736134) (xy 98.018136 -269.724274)
			(xy 97.968522 -269.704802) (xy 97.922364 -269.678153) (xy 97.880693 -269.644922) (xy 97.844441 -269.605851)
			(xy 97.814417 -269.561814) (xy 97.791291 -269.513793) (xy 97.775581 -269.462863) (xy 97.767638 -269.410159)
			(xy 97.538804 -269.410159) (xy 97.530861 -269.462863) (xy 97.515151 -269.513793) (xy 97.492025 -269.561814)
			(xy 97.462001 -269.605851) (xy 97.425749 -269.644922) (xy 97.384078 -269.678153) (xy 97.33792 -269.704802)
			(xy 97.288306 -269.724274) (xy 97.236344 -269.736134) (xy 97.183194 -269.740118) (xy 97.130044 -269.736134)
			(xy 97.078082 -269.724274) (xy 97.028468 -269.704802) (xy 96.98231 -269.678153) (xy 96.940639 -269.644922)
			(xy 96.904387 -269.605851) (xy 96.874363 -269.561814) (xy 96.851237 -269.513793) (xy 96.835527 -269.462863)
			(xy 96.827584 -269.410159) (xy 96.599004 -269.410159) (xy 96.591061 -269.462863) (xy 96.575351 -269.513793)
			(xy 96.552225 -269.561814) (xy 96.522201 -269.605851) (xy 96.485949 -269.644922) (xy 96.444278 -269.678153)
			(xy 96.39812 -269.704802) (xy 96.348506 -269.724274) (xy 96.296544 -269.736134) (xy 96.243394 -269.740118)
			(xy 96.190244 -269.736134) (xy 96.138282 -269.724274) (xy 96.088668 -269.704802) (xy 96.04251 -269.678153)
			(xy 96.000839 -269.644922) (xy 95.964587 -269.605851) (xy 95.934563 -269.561814) (xy 95.911437 -269.513793)
			(xy 95.895727 -269.462863) (xy 95.887784 -269.410159) (xy 95.659204 -269.410159) (xy 95.651261 -269.462863)
			(xy 95.635551 -269.513793) (xy 95.612425 -269.561814) (xy 95.582401 -269.605851) (xy 95.546149 -269.644922)
			(xy 95.504478 -269.678153) (xy 95.45832 -269.704802) (xy 95.408706 -269.724274) (xy 95.356744 -269.736134)
			(xy 95.303594 -269.740118) (xy 95.250444 -269.736134) (xy 95.198482 -269.724274) (xy 95.148868 -269.704802)
			(xy 95.10271 -269.678153) (xy 95.061039 -269.644922) (xy 95.024787 -269.605851) (xy 94.994763 -269.561814)
			(xy 94.971637 -269.513793) (xy 94.955927 -269.462863) (xy 94.947984 -269.410159) (xy 94.719404 -269.410159)
			(xy 94.711461 -269.462863) (xy 94.695751 -269.513793) (xy 94.672625 -269.561814) (xy 94.642601 -269.605851)
			(xy 94.606349 -269.644922) (xy 94.564678 -269.678153) (xy 94.51852 -269.704802) (xy 94.468906 -269.724274)
			(xy 94.416944 -269.736134) (xy 94.363794 -269.740118) (xy 94.310644 -269.736134) (xy 94.258682 -269.724274)
			(xy 94.209068 -269.704802) (xy 94.16291 -269.678153) (xy 94.121239 -269.644922) (xy 94.084987 -269.605851)
			(xy 94.054963 -269.561814) (xy 94.031837 -269.513793) (xy 94.016127 -269.462863) (xy 94.008184 -269.410159)
			(xy 93.779604 -269.410159) (xy 93.771661 -269.462863) (xy 93.755951 -269.513793) (xy 93.732825 -269.561814)
			(xy 93.702801 -269.605851) (xy 93.666549 -269.644922) (xy 93.624878 -269.678153) (xy 93.57872 -269.704802)
			(xy 93.529106 -269.724274) (xy 93.477144 -269.736134) (xy 93.423994 -269.740118) (xy 93.370844 -269.736134)
			(xy 93.318882 -269.724274) (xy 93.269268 -269.704802) (xy 93.22311 -269.678153) (xy 93.181439 -269.644922)
			(xy 93.145187 -269.605851) (xy 93.115163 -269.561814) (xy 93.092037 -269.513793) (xy 93.076327 -269.462863)
			(xy 93.068384 -269.410159) (xy 92.839804 -269.410159) (xy 92.831861 -269.462863) (xy 92.816151 -269.513793)
			(xy 92.793025 -269.561814) (xy 92.763001 -269.605851) (xy 92.726749 -269.644922) (xy 92.685078 -269.678153)
			(xy 92.63892 -269.704802) (xy 92.589306 -269.724274) (xy 92.537344 -269.736134) (xy 92.484194 -269.740118)
			(xy 92.431044 -269.736134) (xy 92.379082 -269.724274) (xy 92.329468 -269.704802) (xy 92.28331 -269.678153)
			(xy 92.241639 -269.644922) (xy 92.205387 -269.605851) (xy 92.175363 -269.561814) (xy 92.152237 -269.513793)
			(xy 92.136527 -269.462863) (xy 92.128584 -269.410159) (xy 91.900258 -269.410159) (xy 91.892315 -269.462863)
			(xy 91.876605 -269.513793) (xy 91.853479 -269.561814) (xy 91.823455 -269.605851) (xy 91.787203 -269.644922)
			(xy 91.745532 -269.678153) (xy 91.699374 -269.704802) (xy 91.64976 -269.724274) (xy 91.597798 -269.736134)
			(xy 91.544648 -269.740118) (xy 91.491498 -269.736134) (xy 91.439536 -269.724274) (xy 91.389922 -269.704802)
			(xy 91.343764 -269.678153) (xy 91.302093 -269.644922) (xy 91.265841 -269.605851) (xy 91.235817 -269.561814)
			(xy 91.212691 -269.513793) (xy 91.196981 -269.462863) (xy 91.189038 -269.410159) (xy 90.960204 -269.410159)
			(xy 90.952261 -269.462863) (xy 90.936551 -269.513793) (xy 90.913425 -269.561814) (xy 90.883401 -269.605851)
			(xy 90.847149 -269.644922) (xy 90.805478 -269.678153) (xy 90.75932 -269.704802) (xy 90.709706 -269.724274)
			(xy 90.657744 -269.736134) (xy 90.604594 -269.740118) (xy 90.551444 -269.736134) (xy 90.499482 -269.724274)
			(xy 90.449868 -269.704802) (xy 90.40371 -269.678153) (xy 90.362039 -269.644922) (xy 90.325787 -269.605851)
			(xy 90.295763 -269.561814) (xy 90.272637 -269.513793) (xy 90.256927 -269.462863) (xy 90.248984 -269.410159)
			(xy 90.020404 -269.410159) (xy 90.012461 -269.462863) (xy 89.996751 -269.513793) (xy 89.973625 -269.561814)
			(xy 89.943601 -269.605851) (xy 89.907349 -269.644922) (xy 89.865678 -269.678153) (xy 89.81952 -269.704802)
			(xy 89.769906 -269.724274) (xy 89.717944 -269.736134) (xy 89.664794 -269.740118) (xy 89.611644 -269.736134)
			(xy 89.559682 -269.724274) (xy 89.510068 -269.704802) (xy 89.46391 -269.678153) (xy 89.422239 -269.644922)
			(xy 89.385987 -269.605851) (xy 89.355963 -269.561814) (xy 89.332837 -269.513793) (xy 89.317127 -269.462863)
			(xy 89.309184 -269.410159) (xy 89.080561 -269.410159) (xy 89.080561 -269.410859) (xy 89.07219 -269.464931)
			(xy 89.055646 -269.517086) (xy 89.031318 -269.566097) (xy 88.999778 -269.610809) (xy 88.961769 -269.650169)
			(xy 88.918187 -269.683252) (xy 88.870056 -269.709277) (xy 88.81851 -269.727633) (xy 88.764763 -269.737888)
			(xy 88.73744 -269.739364) (xy 88.72767 -269.740149) (xy 88.709782 -269.748117) (xy 88.696187 -269.76221)
			(xy 88.688867 -269.780372) (xy 88.688418 -269.790164) (xy 88.688418 -270.224229) (xy 88.839284 -270.224229)
			(xy 88.839284 -270.170931) (xy 88.847227 -270.118227) (xy 88.862937 -270.067297) (xy 88.886063 -270.019276)
			(xy 88.916087 -269.975239) (xy 88.952339 -269.936168) (xy 88.99401 -269.902937) (xy 89.040168 -269.876288)
			(xy 89.089782 -269.856816) (xy 89.141744 -269.844956) (xy 89.194894 -269.840973) (xy 89.248044 -269.844956)
			(xy 89.300006 -269.856816) (xy 89.34962 -269.876288) (xy 89.395778 -269.902937) (xy 89.437449 -269.936168)
			(xy 89.473701 -269.975239) (xy 89.503725 -270.019276) (xy 89.526851 -270.067297) (xy 89.542561 -270.118227)
			(xy 89.550504 -270.170931) (xy 89.551002 -270.19758) (xy 89.550504 -270.224229) (xy 89.779084 -270.224229)
			(xy 89.779084 -270.170931) (xy 89.787027 -270.118227) (xy 89.802737 -270.067297) (xy 89.825863 -270.019276)
			(xy 89.855887 -269.975239) (xy 89.892139 -269.936168) (xy 89.93381 -269.902937) (xy 89.979968 -269.876288)
			(xy 90.029582 -269.856816) (xy 90.081544 -269.844956) (xy 90.134694 -269.840973) (xy 90.187844 -269.844956)
			(xy 90.239806 -269.856816) (xy 90.28942 -269.876288) (xy 90.335578 -269.902937) (xy 90.377249 -269.936168)
			(xy 90.413501 -269.975239) (xy 90.443525 -270.019276) (xy 90.466651 -270.067297) (xy 90.482361 -270.118227)
			(xy 90.490304 -270.170931) (xy 90.490802 -270.19758) (xy 90.490304 -270.224229) (xy 90.719138 -270.224229)
			(xy 90.719138 -270.170931) (xy 90.727081 -270.118227) (xy 90.742791 -270.067297) (xy 90.765917 -270.019276)
			(xy 90.795941 -269.975239) (xy 90.832193 -269.936168) (xy 90.873864 -269.902937) (xy 90.920022 -269.876288)
			(xy 90.969636 -269.856816) (xy 91.021598 -269.844956) (xy 91.074748 -269.840973) (xy 91.127898 -269.844956)
			(xy 91.17986 -269.856816) (xy 91.229474 -269.876288) (xy 91.275632 -269.902937) (xy 91.317303 -269.936168)
			(xy 91.353555 -269.975239) (xy 91.383579 -270.019276) (xy 91.406705 -270.067297) (xy 91.422415 -270.118227)
			(xy 91.430358 -270.170931) (xy 91.430856 -270.19758) (xy 91.430358 -270.224229) (xy 91.658684 -270.224229)
			(xy 91.658684 -270.170931) (xy 91.666627 -270.118227) (xy 91.682337 -270.067297) (xy 91.705463 -270.019276)
			(xy 91.735487 -269.975239) (xy 91.771739 -269.936168) (xy 91.81341 -269.902937) (xy 91.859568 -269.876288)
			(xy 91.909182 -269.856816) (xy 91.961144 -269.844956) (xy 92.014294 -269.840973) (xy 92.067444 -269.844956)
			(xy 92.119406 -269.856816) (xy 92.16902 -269.876288) (xy 92.215178 -269.902937) (xy 92.256849 -269.936168)
			(xy 92.293101 -269.975239) (xy 92.323125 -270.019276) (xy 92.346251 -270.067297) (xy 92.361961 -270.118227)
			(xy 92.369904 -270.170931) (xy 92.370402 -270.19758) (xy 92.369904 -270.224229) (xy 92.598738 -270.224229)
			(xy 92.598738 -270.170931) (xy 92.606681 -270.118227) (xy 92.622391 -270.067297) (xy 92.645517 -270.019276)
			(xy 92.675541 -269.975239) (xy 92.711793 -269.936168) (xy 92.753464 -269.902937) (xy 92.799622 -269.876288)
			(xy 92.849236 -269.856816) (xy 92.901198 -269.844956) (xy 92.954348 -269.840973) (xy 93.007498 -269.844956)
			(xy 93.05946 -269.856816) (xy 93.109074 -269.876288) (xy 93.155232 -269.902937) (xy 93.196903 -269.936168)
			(xy 93.233155 -269.975239) (xy 93.263179 -270.019276) (xy 93.286305 -270.067297) (xy 93.302015 -270.118227)
			(xy 93.309958 -270.170931) (xy 93.310456 -270.19758) (xy 93.309958 -270.224229) (xy 93.538538 -270.224229)
			(xy 93.538538 -270.170931) (xy 93.546481 -270.118227) (xy 93.562191 -270.067297) (xy 93.585317 -270.019276)
			(xy 93.615341 -269.975239) (xy 93.651593 -269.936168) (xy 93.693264 -269.902937) (xy 93.739422 -269.876288)
			(xy 93.789036 -269.856816) (xy 93.840998 -269.844956) (xy 93.894148 -269.840973) (xy 93.947298 -269.844956)
			(xy 93.99926 -269.856816) (xy 94.048874 -269.876288) (xy 94.095032 -269.902937) (xy 94.136703 -269.936168)
			(xy 94.172955 -269.975239) (xy 94.202979 -270.019276) (xy 94.226105 -270.067297) (xy 94.241815 -270.118227)
			(xy 94.249758 -270.170931) (xy 94.250256 -270.19758) (xy 94.249758 -270.224229) (xy 94.478338 -270.224229)
			(xy 94.478338 -270.170931) (xy 94.486281 -270.118227) (xy 94.501991 -270.067297) (xy 94.525117 -270.019276)
			(xy 94.555141 -269.975239) (xy 94.591393 -269.936168) (xy 94.633064 -269.902937) (xy 94.679222 -269.876288)
			(xy 94.728836 -269.856816) (xy 94.780798 -269.844956) (xy 94.833948 -269.840973) (xy 94.887098 -269.844956)
			(xy 94.93906 -269.856816) (xy 94.988674 -269.876288) (xy 95.034832 -269.902937) (xy 95.076503 -269.936168)
			(xy 95.112755 -269.975239) (xy 95.142779 -270.019276) (xy 95.165905 -270.067297) (xy 95.181615 -270.118227)
			(xy 95.189558 -270.170931) (xy 95.190056 -270.19758) (xy 95.189558 -270.224229) (xy 95.418138 -270.224229)
			(xy 95.418138 -270.170931) (xy 95.426081 -270.118227) (xy 95.441791 -270.067297) (xy 95.464917 -270.019276)
			(xy 95.494941 -269.975239) (xy 95.531193 -269.936168) (xy 95.572864 -269.902937) (xy 95.619022 -269.876288)
			(xy 95.668636 -269.856816) (xy 95.720598 -269.844956) (xy 95.773748 -269.840973) (xy 95.826898 -269.844956)
			(xy 95.87886 -269.856816) (xy 95.928474 -269.876288) (xy 95.974632 -269.902937) (xy 96.016303 -269.936168)
			(xy 96.052555 -269.975239) (xy 96.082579 -270.019276) (xy 96.105705 -270.067297) (xy 96.121415 -270.118227)
			(xy 96.129358 -270.170931) (xy 96.129856 -270.19758) (xy 96.129358 -270.224229) (xy 96.357938 -270.224229)
			(xy 96.357938 -270.170931) (xy 96.365881 -270.118227) (xy 96.381591 -270.067297) (xy 96.404717 -270.019276)
			(xy 96.434741 -269.975239) (xy 96.470993 -269.936168) (xy 96.512664 -269.902937) (xy 96.558822 -269.876288)
			(xy 96.608436 -269.856816) (xy 96.660398 -269.844956) (xy 96.713548 -269.840973) (xy 96.766698 -269.844956)
			(xy 96.81866 -269.856816) (xy 96.868274 -269.876288) (xy 96.914432 -269.902937) (xy 96.956103 -269.936168)
			(xy 96.992355 -269.975239) (xy 97.022379 -270.019276) (xy 97.045505 -270.067297) (xy 97.061215 -270.118227)
			(xy 97.069158 -270.170931) (xy 97.069656 -270.19758) (xy 97.069158 -270.224229) (xy 97.297738 -270.224229)
			(xy 97.297738 -270.170931) (xy 97.305681 -270.118227) (xy 97.321391 -270.067297) (xy 97.344517 -270.019276)
			(xy 97.374541 -269.975239) (xy 97.410793 -269.936168) (xy 97.452464 -269.902937) (xy 97.498622 -269.876288)
			(xy 97.548236 -269.856816) (xy 97.600198 -269.844956) (xy 97.653348 -269.840973) (xy 97.706498 -269.844956)
			(xy 97.75846 -269.856816) (xy 97.808074 -269.876288) (xy 97.854232 -269.902937) (xy 97.895903 -269.936168)
			(xy 97.932155 -269.975239) (xy 97.962179 -270.019276) (xy 97.985305 -270.067297) (xy 98.001015 -270.118227)
			(xy 98.008958 -270.170931) (xy 98.009456 -270.19758) (xy 98.008958 -270.224229) (xy 98.237284 -270.224229)
			(xy 98.237284 -270.170931) (xy 98.245227 -270.118227) (xy 98.260937 -270.067297) (xy 98.284063 -270.019276)
			(xy 98.314087 -269.975239) (xy 98.350339 -269.936168) (xy 98.39201 -269.902937) (xy 98.438168 -269.876288)
			(xy 98.487782 -269.856816) (xy 98.539744 -269.844956) (xy 98.592894 -269.840973) (xy 98.646044 -269.844956)
			(xy 98.698006 -269.856816) (xy 98.74762 -269.876288) (xy 98.793778 -269.902937) (xy 98.835449 -269.936168)
			(xy 98.871701 -269.975239) (xy 98.901725 -270.019276) (xy 98.924851 -270.067297) (xy 98.940561 -270.118227)
			(xy 98.948504 -270.170931) (xy 98.949002 -270.19758) (xy 98.948504 -270.224229) (xy 99.177338 -270.224229)
			(xy 99.177338 -270.170931) (xy 99.185281 -270.118227) (xy 99.200991 -270.067297) (xy 99.224117 -270.019276)
			(xy 99.254141 -269.975239) (xy 99.290393 -269.936168) (xy 99.332064 -269.902937) (xy 99.378222 -269.876288)
			(xy 99.427836 -269.856816) (xy 99.479798 -269.844956) (xy 99.532948 -269.840973) (xy 99.586098 -269.844956)
			(xy 99.63806 -269.856816) (xy 99.687674 -269.876288) (xy 99.733832 -269.902937) (xy 99.775503 -269.936168)
			(xy 99.811755 -269.975239) (xy 99.841779 -270.019276) (xy 99.864905 -270.067297) (xy 99.880615 -270.118227)
			(xy 99.888558 -270.170931) (xy 99.889056 -270.19758) (xy 99.888558 -270.224229) (xy 100.117138 -270.224229)
			(xy 100.117138 -270.170931) (xy 100.125081 -270.118227) (xy 100.140791 -270.067297) (xy 100.163917 -270.019276)
			(xy 100.193941 -269.975239) (xy 100.230193 -269.936168) (xy 100.271864 -269.902937) (xy 100.318022 -269.876288)
			(xy 100.367636 -269.856816) (xy 100.419598 -269.844956) (xy 100.472748 -269.840973) (xy 100.525898 -269.844956)
			(xy 100.57786 -269.856816) (xy 100.627474 -269.876288) (xy 100.673632 -269.902937) (xy 100.715303 -269.936168)
			(xy 100.751555 -269.975239) (xy 100.781579 -270.019276) (xy 100.804705 -270.067297) (xy 100.820415 -270.118227)
			(xy 100.828358 -270.170931) (xy 100.828856 -270.19758) (xy 100.828358 -270.224229) (xy 101.056938 -270.224229)
			(xy 101.056938 -270.170931) (xy 101.064881 -270.118227) (xy 101.080591 -270.067297) (xy 101.103717 -270.019276)
			(xy 101.133741 -269.975239) (xy 101.169993 -269.936168) (xy 101.211664 -269.902937) (xy 101.257822 -269.876288)
			(xy 101.307436 -269.856816) (xy 101.359398 -269.844956) (xy 101.412548 -269.840973) (xy 101.465698 -269.844956)
			(xy 101.51766 -269.856816) (xy 101.567274 -269.876288) (xy 101.613432 -269.902937) (xy 101.655103 -269.936168)
			(xy 101.691355 -269.975239) (xy 101.721379 -270.019276) (xy 101.744505 -270.067297) (xy 101.760215 -270.118227)
			(xy 101.768158 -270.170931) (xy 101.768656 -270.19758) (xy 101.768158 -270.224229) (xy 101.996738 -270.224229)
			(xy 101.996738 -270.170931) (xy 102.004681 -270.118227) (xy 102.020391 -270.067297) (xy 102.043517 -270.019276)
			(xy 102.073541 -269.975239) (xy 102.109793 -269.936168) (xy 102.151464 -269.902937) (xy 102.197622 -269.876288)
			(xy 102.247236 -269.856816) (xy 102.299198 -269.844956) (xy 102.352348 -269.840973) (xy 102.405498 -269.844956)
			(xy 102.45746 -269.856816) (xy 102.507074 -269.876288) (xy 102.553232 -269.902937) (xy 102.594903 -269.936168)
			(xy 102.631155 -269.975239) (xy 102.661179 -270.019276) (xy 102.684305 -270.067297) (xy 102.700015 -270.118227)
			(xy 102.707958 -270.170931) (xy 102.708456 -270.19758) (xy 102.707958 -270.224229) (xy 102.936538 -270.224229)
			(xy 102.936538 -270.170931) (xy 102.944481 -270.118227) (xy 102.960191 -270.067297) (xy 102.983317 -270.019276)
			(xy 103.013341 -269.975239) (xy 103.049593 -269.936168) (xy 103.091264 -269.902937) (xy 103.137422 -269.876288)
			(xy 103.187036 -269.856816) (xy 103.238998 -269.844956) (xy 103.292148 -269.840973) (xy 103.345298 -269.844956)
			(xy 103.39726 -269.856816) (xy 103.446874 -269.876288) (xy 103.493032 -269.902937) (xy 103.534703 -269.936168)
			(xy 103.570955 -269.975239) (xy 103.600979 -270.019276) (xy 103.624105 -270.067297) (xy 103.639815 -270.118227)
			(xy 103.647758 -270.170931) (xy 103.648256 -270.19758) (xy 103.647758 -270.224229) (xy 103.876338 -270.224229)
			(xy 103.876338 -270.170931) (xy 103.884281 -270.118227) (xy 103.899991 -270.067297) (xy 103.923117 -270.019276)
			(xy 103.953141 -269.975239) (xy 103.989393 -269.936168) (xy 104.031064 -269.902937) (xy 104.077222 -269.876288)
			(xy 104.126836 -269.856816) (xy 104.178798 -269.844956) (xy 104.231948 -269.840973) (xy 104.285098 -269.844956)
			(xy 104.33706 -269.856816) (xy 104.386674 -269.876288) (xy 104.432832 -269.902937) (xy 104.474503 -269.936168)
			(xy 104.510755 -269.975239) (xy 104.540779 -270.019276) (xy 104.563905 -270.067297) (xy 104.579615 -270.118227)
			(xy 104.587558 -270.170931) (xy 104.588056 -270.19758) (xy 104.587558 -270.224229) (xy 104.816138 -270.224229)
			(xy 104.816138 -270.170931) (xy 104.824081 -270.118227) (xy 104.839791 -270.067297) (xy 104.862917 -270.019276)
			(xy 104.892941 -269.975239) (xy 104.929193 -269.936168) (xy 104.970864 -269.902937) (xy 105.017022 -269.876288)
			(xy 105.066636 -269.856816) (xy 105.118598 -269.844956) (xy 105.171748 -269.840973) (xy 105.224898 -269.844956)
			(xy 105.27686 -269.856816) (xy 105.326474 -269.876288) (xy 105.372632 -269.902937) (xy 105.414303 -269.936168)
			(xy 105.450555 -269.975239) (xy 105.480579 -270.019276) (xy 105.503705 -270.067297) (xy 105.519415 -270.118227)
			(xy 105.527358 -270.170931) (xy 105.527856 -270.19758) (xy 105.527358 -270.224229) (xy 105.755938 -270.224229)
			(xy 105.755938 -270.170931) (xy 105.763881 -270.118227) (xy 105.779591 -270.067297) (xy 105.802717 -270.019276)
			(xy 105.832741 -269.975239) (xy 105.868993 -269.936168) (xy 105.910664 -269.902937) (xy 105.956822 -269.876288)
			(xy 106.006436 -269.856816) (xy 106.058398 -269.844956) (xy 106.111548 -269.840973) (xy 106.164698 -269.844956)
			(xy 106.21666 -269.856816) (xy 106.266274 -269.876288) (xy 106.312432 -269.902937) (xy 106.354103 -269.936168)
			(xy 106.390355 -269.975239) (xy 106.420379 -270.019276) (xy 106.443505 -270.067297) (xy 106.459215 -270.118227)
			(xy 106.467158 -270.170931) (xy 106.467656 -270.19758) (xy 106.467158 -270.224229) (xy 106.695738 -270.224229)
			(xy 106.695738 -270.170931) (xy 106.703681 -270.118227) (xy 106.719391 -270.067297) (xy 106.742517 -270.019276)
			(xy 106.772541 -269.975239) (xy 106.808793 -269.936168) (xy 106.850464 -269.902937) (xy 106.896622 -269.876288)
			(xy 106.946236 -269.856816) (xy 106.998198 -269.844956) (xy 107.051348 -269.840973) (xy 107.104498 -269.844956)
			(xy 107.15646 -269.856816) (xy 107.206074 -269.876288) (xy 107.252232 -269.902937) (xy 107.293903 -269.936168)
			(xy 107.330155 -269.975239) (xy 107.360179 -270.019276) (xy 107.383305 -270.067297) (xy 107.399015 -270.118227)
			(xy 107.406958 -270.170931) (xy 107.407456 -270.19758) (xy 107.406958 -270.224229) (xy 107.635538 -270.224229)
			(xy 107.635538 -270.170931) (xy 107.643481 -270.118227) (xy 107.659191 -270.067297) (xy 107.682317 -270.019276)
			(xy 107.712341 -269.975239) (xy 107.748593 -269.936168) (xy 107.790264 -269.902937) (xy 107.836422 -269.876288)
			(xy 107.886036 -269.856816) (xy 107.937998 -269.844956) (xy 107.991148 -269.840973) (xy 108.044298 -269.844956)
			(xy 108.09626 -269.856816) (xy 108.145874 -269.876288) (xy 108.192032 -269.902937) (xy 108.233703 -269.936168)
			(xy 108.269955 -269.975239) (xy 108.299979 -270.019276) (xy 108.323105 -270.067297) (xy 108.338815 -270.118227)
			(xy 108.346758 -270.170931) (xy 108.347256 -270.19758) (xy 108.346758 -270.224229) (xy 108.338815 -270.276933)
			(xy 108.323105 -270.327863) (xy 108.299979 -270.375884) (xy 108.269955 -270.419921) (xy 108.233703 -270.458992)
			(xy 108.192032 -270.492223) (xy 108.145874 -270.518872) (xy 108.09626 -270.538344) (xy 108.044298 -270.550204)
			(xy 107.991148 -270.554188) (xy 107.937998 -270.550204) (xy 107.886036 -270.538344) (xy 107.836422 -270.518872)
			(xy 107.790264 -270.492223) (xy 107.748593 -270.458992) (xy 107.712341 -270.419921) (xy 107.682317 -270.375884)
			(xy 107.659191 -270.327863) (xy 107.643481 -270.276933) (xy 107.635538 -270.224229) (xy 107.406958 -270.224229)
			(xy 107.399015 -270.276933) (xy 107.383305 -270.327863) (xy 107.360179 -270.375884) (xy 107.330155 -270.419921)
			(xy 107.293903 -270.458992) (xy 107.252232 -270.492223) (xy 107.206074 -270.518872) (xy 107.15646 -270.538344)
			(xy 107.104498 -270.550204) (xy 107.051348 -270.554188) (xy 106.998198 -270.550204) (xy 106.946236 -270.538344)
			(xy 106.896622 -270.518872) (xy 106.850464 -270.492223) (xy 106.808793 -270.458992) (xy 106.772541 -270.419921)
			(xy 106.742517 -270.375884) (xy 106.719391 -270.327863) (xy 106.703681 -270.276933) (xy 106.695738 -270.224229)
			(xy 106.467158 -270.224229) (xy 106.459215 -270.276933) (xy 106.443505 -270.327863) (xy 106.420379 -270.375884)
			(xy 106.390355 -270.419921) (xy 106.354103 -270.458992) (xy 106.312432 -270.492223) (xy 106.266274 -270.518872)
			(xy 106.21666 -270.538344) (xy 106.164698 -270.550204) (xy 106.111548 -270.554188) (xy 106.058398 -270.550204)
			(xy 106.006436 -270.538344) (xy 105.956822 -270.518872) (xy 105.910664 -270.492223) (xy 105.868993 -270.458992)
			(xy 105.832741 -270.419921) (xy 105.802717 -270.375884) (xy 105.779591 -270.327863) (xy 105.763881 -270.276933)
			(xy 105.755938 -270.224229) (xy 105.527358 -270.224229) (xy 105.519415 -270.276933) (xy 105.503705 -270.327863)
			(xy 105.480579 -270.375884) (xy 105.450555 -270.419921) (xy 105.414303 -270.458992) (xy 105.372632 -270.492223)
			(xy 105.326474 -270.518872) (xy 105.27686 -270.538344) (xy 105.224898 -270.550204) (xy 105.171748 -270.554188)
			(xy 105.118598 -270.550204) (xy 105.066636 -270.538344) (xy 105.017022 -270.518872) (xy 104.970864 -270.492223)
			(xy 104.929193 -270.458992) (xy 104.892941 -270.419921) (xy 104.862917 -270.375884) (xy 104.839791 -270.327863)
			(xy 104.824081 -270.276933) (xy 104.816138 -270.224229) (xy 104.587558 -270.224229) (xy 104.579615 -270.276933)
			(xy 104.563905 -270.327863) (xy 104.540779 -270.375884) (xy 104.510755 -270.419921) (xy 104.474503 -270.458992)
			(xy 104.432832 -270.492223) (xy 104.386674 -270.518872) (xy 104.33706 -270.538344) (xy 104.285098 -270.550204)
			(xy 104.231948 -270.554188) (xy 104.178798 -270.550204) (xy 104.126836 -270.538344) (xy 104.077222 -270.518872)
			(xy 104.031064 -270.492223) (xy 103.989393 -270.458992) (xy 103.953141 -270.419921) (xy 103.923117 -270.375884)
			(xy 103.899991 -270.327863) (xy 103.884281 -270.276933) (xy 103.876338 -270.224229) (xy 103.647758 -270.224229)
			(xy 103.639815 -270.276933) (xy 103.624105 -270.327863) (xy 103.600979 -270.375884) (xy 103.570955 -270.419921)
			(xy 103.534703 -270.458992) (xy 103.493032 -270.492223) (xy 103.446874 -270.518872) (xy 103.39726 -270.538344)
			(xy 103.345298 -270.550204) (xy 103.292148 -270.554188) (xy 103.238998 -270.550204) (xy 103.187036 -270.538344)
			(xy 103.137422 -270.518872) (xy 103.091264 -270.492223) (xy 103.049593 -270.458992) (xy 103.013341 -270.419921)
			(xy 102.983317 -270.375884) (xy 102.960191 -270.327863) (xy 102.944481 -270.276933) (xy 102.936538 -270.224229)
			(xy 102.707958 -270.224229) (xy 102.700015 -270.276933) (xy 102.684305 -270.327863) (xy 102.661179 -270.375884)
			(xy 102.631155 -270.419921) (xy 102.594903 -270.458992) (xy 102.553232 -270.492223) (xy 102.507074 -270.518872)
			(xy 102.45746 -270.538344) (xy 102.405498 -270.550204) (xy 102.352348 -270.554188) (xy 102.299198 -270.550204)
			(xy 102.247236 -270.538344) (xy 102.197622 -270.518872) (xy 102.151464 -270.492223) (xy 102.109793 -270.458992)
			(xy 102.073541 -270.419921) (xy 102.043517 -270.375884) (xy 102.020391 -270.327863) (xy 102.004681 -270.276933)
			(xy 101.996738 -270.224229) (xy 101.768158 -270.224229) (xy 101.760215 -270.276933) (xy 101.744505 -270.327863)
			(xy 101.721379 -270.375884) (xy 101.691355 -270.419921) (xy 101.655103 -270.458992) (xy 101.613432 -270.492223)
			(xy 101.567274 -270.518872) (xy 101.51766 -270.538344) (xy 101.465698 -270.550204) (xy 101.412548 -270.554188)
			(xy 101.359398 -270.550204) (xy 101.307436 -270.538344) (xy 101.257822 -270.518872) (xy 101.211664 -270.492223)
			(xy 101.169993 -270.458992) (xy 101.133741 -270.419921) (xy 101.103717 -270.375884) (xy 101.080591 -270.327863)
			(xy 101.064881 -270.276933) (xy 101.056938 -270.224229) (xy 100.828358 -270.224229) (xy 100.820415 -270.276933)
			(xy 100.804705 -270.327863) (xy 100.781579 -270.375884) (xy 100.751555 -270.419921) (xy 100.715303 -270.458992)
			(xy 100.673632 -270.492223) (xy 100.627474 -270.518872) (xy 100.57786 -270.538344) (xy 100.525898 -270.550204)
			(xy 100.472748 -270.554188) (xy 100.419598 -270.550204) (xy 100.367636 -270.538344) (xy 100.318022 -270.518872)
			(xy 100.271864 -270.492223) (xy 100.230193 -270.458992) (xy 100.193941 -270.419921) (xy 100.163917 -270.375884)
			(xy 100.140791 -270.327863) (xy 100.125081 -270.276933) (xy 100.117138 -270.224229) (xy 99.888558 -270.224229)
			(xy 99.880615 -270.276933) (xy 99.864905 -270.327863) (xy 99.841779 -270.375884) (xy 99.811755 -270.419921)
			(xy 99.775503 -270.458992) (xy 99.733832 -270.492223) (xy 99.687674 -270.518872) (xy 99.63806 -270.538344)
			(xy 99.586098 -270.550204) (xy 99.532948 -270.554188) (xy 99.479798 -270.550204) (xy 99.427836 -270.538344)
			(xy 99.378222 -270.518872) (xy 99.332064 -270.492223) (xy 99.290393 -270.458992) (xy 99.254141 -270.419921)
			(xy 99.224117 -270.375884) (xy 99.200991 -270.327863) (xy 99.185281 -270.276933) (xy 99.177338 -270.224229)
			(xy 98.948504 -270.224229) (xy 98.940561 -270.276933) (xy 98.924851 -270.327863) (xy 98.901725 -270.375884)
			(xy 98.871701 -270.419921) (xy 98.835449 -270.458992) (xy 98.793778 -270.492223) (xy 98.74762 -270.518872)
			(xy 98.698006 -270.538344) (xy 98.646044 -270.550204) (xy 98.592894 -270.554188) (xy 98.539744 -270.550204)
			(xy 98.487782 -270.538344) (xy 98.438168 -270.518872) (xy 98.39201 -270.492223) (xy 98.350339 -270.458992)
			(xy 98.314087 -270.419921) (xy 98.284063 -270.375884) (xy 98.260937 -270.327863) (xy 98.245227 -270.276933)
			(xy 98.237284 -270.224229) (xy 98.008958 -270.224229) (xy 98.001015 -270.276933) (xy 97.985305 -270.327863)
			(xy 97.962179 -270.375884) (xy 97.932155 -270.419921) (xy 97.895903 -270.458992) (xy 97.854232 -270.492223)
			(xy 97.808074 -270.518872) (xy 97.75846 -270.538344) (xy 97.706498 -270.550204) (xy 97.653348 -270.554188)
			(xy 97.600198 -270.550204) (xy 97.548236 -270.538344) (xy 97.498622 -270.518872) (xy 97.452464 -270.492223)
			(xy 97.410793 -270.458992) (xy 97.374541 -270.419921) (xy 97.344517 -270.375884) (xy 97.321391 -270.327863)
			(xy 97.305681 -270.276933) (xy 97.297738 -270.224229) (xy 97.069158 -270.224229) (xy 97.061215 -270.276933)
			(xy 97.045505 -270.327863) (xy 97.022379 -270.375884) (xy 96.992355 -270.419921) (xy 96.956103 -270.458992)
			(xy 96.914432 -270.492223) (xy 96.868274 -270.518872) (xy 96.81866 -270.538344) (xy 96.766698 -270.550204)
			(xy 96.713548 -270.554188) (xy 96.660398 -270.550204) (xy 96.608436 -270.538344) (xy 96.558822 -270.518872)
			(xy 96.512664 -270.492223) (xy 96.470993 -270.458992) (xy 96.434741 -270.419921) (xy 96.404717 -270.375884)
			(xy 96.381591 -270.327863) (xy 96.365881 -270.276933) (xy 96.357938 -270.224229) (xy 96.129358 -270.224229)
			(xy 96.121415 -270.276933) (xy 96.105705 -270.327863) (xy 96.082579 -270.375884) (xy 96.052555 -270.419921)
			(xy 96.016303 -270.458992) (xy 95.974632 -270.492223) (xy 95.928474 -270.518872) (xy 95.87886 -270.538344)
			(xy 95.826898 -270.550204) (xy 95.773748 -270.554188) (xy 95.720598 -270.550204) (xy 95.668636 -270.538344)
			(xy 95.619022 -270.518872) (xy 95.572864 -270.492223) (xy 95.531193 -270.458992) (xy 95.494941 -270.419921)
			(xy 95.464917 -270.375884) (xy 95.441791 -270.327863) (xy 95.426081 -270.276933) (xy 95.418138 -270.224229)
			(xy 95.189558 -270.224229) (xy 95.181615 -270.276933) (xy 95.165905 -270.327863) (xy 95.142779 -270.375884)
			(xy 95.112755 -270.419921) (xy 95.076503 -270.458992) (xy 95.034832 -270.492223) (xy 94.988674 -270.518872)
			(xy 94.93906 -270.538344) (xy 94.887098 -270.550204) (xy 94.833948 -270.554188) (xy 94.780798 -270.550204)
			(xy 94.728836 -270.538344) (xy 94.679222 -270.518872) (xy 94.633064 -270.492223) (xy 94.591393 -270.458992)
			(xy 94.555141 -270.419921) (xy 94.525117 -270.375884) (xy 94.501991 -270.327863) (xy 94.486281 -270.276933)
			(xy 94.478338 -270.224229) (xy 94.249758 -270.224229) (xy 94.241815 -270.276933) (xy 94.226105 -270.327863)
			(xy 94.202979 -270.375884) (xy 94.172955 -270.419921) (xy 94.136703 -270.458992) (xy 94.095032 -270.492223)
			(xy 94.048874 -270.518872) (xy 93.99926 -270.538344) (xy 93.947298 -270.550204) (xy 93.894148 -270.554188)
			(xy 93.840998 -270.550204) (xy 93.789036 -270.538344) (xy 93.739422 -270.518872) (xy 93.693264 -270.492223)
			(xy 93.651593 -270.458992) (xy 93.615341 -270.419921) (xy 93.585317 -270.375884) (xy 93.562191 -270.327863)
			(xy 93.546481 -270.276933) (xy 93.538538 -270.224229) (xy 93.309958 -270.224229) (xy 93.302015 -270.276933)
			(xy 93.286305 -270.327863) (xy 93.263179 -270.375884) (xy 93.233155 -270.419921) (xy 93.196903 -270.458992)
			(xy 93.155232 -270.492223) (xy 93.109074 -270.518872) (xy 93.05946 -270.538344) (xy 93.007498 -270.550204)
			(xy 92.954348 -270.554188) (xy 92.901198 -270.550204) (xy 92.849236 -270.538344) (xy 92.799622 -270.518872)
			(xy 92.753464 -270.492223) (xy 92.711793 -270.458992) (xy 92.675541 -270.419921) (xy 92.645517 -270.375884)
			(xy 92.622391 -270.327863) (xy 92.606681 -270.276933) (xy 92.598738 -270.224229) (xy 92.369904 -270.224229)
			(xy 92.361961 -270.276933) (xy 92.346251 -270.327863) (xy 92.323125 -270.375884) (xy 92.293101 -270.419921)
			(xy 92.256849 -270.458992) (xy 92.215178 -270.492223) (xy 92.16902 -270.518872) (xy 92.119406 -270.538344)
			(xy 92.067444 -270.550204) (xy 92.014294 -270.554188) (xy 91.961144 -270.550204) (xy 91.909182 -270.538344)
			(xy 91.859568 -270.518872) (xy 91.81341 -270.492223) (xy 91.771739 -270.458992) (xy 91.735487 -270.419921)
			(xy 91.705463 -270.375884) (xy 91.682337 -270.327863) (xy 91.666627 -270.276933) (xy 91.658684 -270.224229)
			(xy 91.430358 -270.224229) (xy 91.422415 -270.276933) (xy 91.406705 -270.327863) (xy 91.383579 -270.375884)
			(xy 91.353555 -270.419921) (xy 91.317303 -270.458992) (xy 91.275632 -270.492223) (xy 91.229474 -270.518872)
			(xy 91.17986 -270.538344) (xy 91.127898 -270.550204) (xy 91.074748 -270.554188) (xy 91.021598 -270.550204)
			(xy 90.969636 -270.538344) (xy 90.920022 -270.518872) (xy 90.873864 -270.492223) (xy 90.832193 -270.458992)
			(xy 90.795941 -270.419921) (xy 90.765917 -270.375884) (xy 90.742791 -270.327863) (xy 90.727081 -270.276933)
			(xy 90.719138 -270.224229) (xy 90.490304 -270.224229) (xy 90.482361 -270.276933) (xy 90.466651 -270.327863)
			(xy 90.443525 -270.375884) (xy 90.413501 -270.419921) (xy 90.377249 -270.458992) (xy 90.335578 -270.492223)
			(xy 90.28942 -270.518872) (xy 90.239806 -270.538344) (xy 90.187844 -270.550204) (xy 90.134694 -270.554188)
			(xy 90.081544 -270.550204) (xy 90.029582 -270.538344) (xy 89.979968 -270.518872) (xy 89.93381 -270.492223)
			(xy 89.892139 -270.458992) (xy 89.855887 -270.419921) (xy 89.825863 -270.375884) (xy 89.802737 -270.327863)
			(xy 89.787027 -270.276933) (xy 89.779084 -270.224229) (xy 89.550504 -270.224229) (xy 89.542561 -270.276933)
			(xy 89.526851 -270.327863) (xy 89.503725 -270.375884) (xy 89.473701 -270.419921) (xy 89.437449 -270.458992)
			(xy 89.395778 -270.492223) (xy 89.34962 -270.518872) (xy 89.300006 -270.538344) (xy 89.248044 -270.550204)
			(xy 89.194894 -270.554188) (xy 89.141744 -270.550204) (xy 89.089782 -270.538344) (xy 89.040168 -270.518872)
			(xy 88.99401 -270.492223) (xy 88.952339 -270.458992) (xy 88.916087 -270.419921) (xy 88.886063 -270.375884)
			(xy 88.862937 -270.327863) (xy 88.847227 -270.276933) (xy 88.839284 -270.224229) (xy 88.688418 -270.224229)
			(xy 88.688418 -270.604742) (xy 88.688869 -270.61453) (xy 88.696206 -270.632679) (xy 88.709799 -270.646767)
			(xy 88.727674 -270.654748) (xy 88.73744 -270.655542) (xy 88.764765 -270.656998) (xy 88.818514 -270.667253)
			(xy 88.870062 -270.68561) (xy 88.918194 -270.711637) (xy 88.961779 -270.744721) (xy 88.999789 -270.784083)
			(xy 89.03133 -270.828796) (xy 89.055659 -270.877809) (xy 89.072204 -270.929966) (xy 89.080575 -270.984041)
			(xy 89.080575 -271.038045) (xy 89.309184 -271.038045) (xy 89.309184 -270.984747) (xy 89.317127 -270.932043)
			(xy 89.332837 -270.881113) (xy 89.355963 -270.833092) (xy 89.385987 -270.789055) (xy 89.422239 -270.749984)
			(xy 89.46391 -270.716753) (xy 89.510068 -270.690104) (xy 89.559682 -270.670632) (xy 89.611644 -270.658772)
			(xy 89.664794 -270.654789) (xy 89.717944 -270.658772) (xy 89.769906 -270.670632) (xy 89.81952 -270.690104)
			(xy 89.865678 -270.716753) (xy 89.907349 -270.749984) (xy 89.943601 -270.789055) (xy 89.973625 -270.833092)
			(xy 89.996751 -270.881113) (xy 90.012461 -270.932043) (xy 90.020404 -270.984747) (xy 90.020902 -271.011396)
			(xy 90.020404 -271.038045) (xy 90.248984 -271.038045) (xy 90.248984 -270.984747) (xy 90.256927 -270.932043)
			(xy 90.272637 -270.881113) (xy 90.295763 -270.833092) (xy 90.325787 -270.789055) (xy 90.362039 -270.749984)
			(xy 90.40371 -270.716753) (xy 90.449868 -270.690104) (xy 90.499482 -270.670632) (xy 90.551444 -270.658772)
			(xy 90.604594 -270.654789) (xy 90.657744 -270.658772) (xy 90.709706 -270.670632) (xy 90.75932 -270.690104)
			(xy 90.805478 -270.716753) (xy 90.847149 -270.749984) (xy 90.883401 -270.789055) (xy 90.913425 -270.833092)
			(xy 90.936551 -270.881113) (xy 90.952261 -270.932043) (xy 90.960204 -270.984747) (xy 90.960702 -271.011396)
			(xy 90.960204 -271.038045) (xy 91.188784 -271.038045) (xy 91.188784 -270.984747) (xy 91.196727 -270.932043)
			(xy 91.212437 -270.881113) (xy 91.235563 -270.833092) (xy 91.265587 -270.789055) (xy 91.301839 -270.749984)
			(xy 91.34351 -270.716753) (xy 91.389668 -270.690104) (xy 91.439282 -270.670632) (xy 91.491244 -270.658772)
			(xy 91.544394 -270.654789) (xy 91.597544 -270.658772) (xy 91.649506 -270.670632) (xy 91.69912 -270.690104)
			(xy 91.745278 -270.716753) (xy 91.786949 -270.749984) (xy 91.823201 -270.789055) (xy 91.853225 -270.833092)
			(xy 91.876351 -270.881113) (xy 91.892061 -270.932043) (xy 91.900004 -270.984747) (xy 91.900502 -271.011396)
			(xy 91.900004 -271.038045) (xy 92.128584 -271.038045) (xy 92.128584 -270.984747) (xy 92.136527 -270.932043)
			(xy 92.152237 -270.881113) (xy 92.175363 -270.833092) (xy 92.205387 -270.789055) (xy 92.241639 -270.749984)
			(xy 92.28331 -270.716753) (xy 92.329468 -270.690104) (xy 92.379082 -270.670632) (xy 92.431044 -270.658772)
			(xy 92.484194 -270.654789) (xy 92.537344 -270.658772) (xy 92.589306 -270.670632) (xy 92.63892 -270.690104)
			(xy 92.685078 -270.716753) (xy 92.726749 -270.749984) (xy 92.763001 -270.789055) (xy 92.793025 -270.833092)
			(xy 92.816151 -270.881113) (xy 92.831861 -270.932043) (xy 92.839804 -270.984747) (xy 92.840302 -271.011396)
			(xy 92.839804 -271.038045) (xy 93.068384 -271.038045) (xy 93.068384 -270.984747) (xy 93.076327 -270.932043)
			(xy 93.092037 -270.881113) (xy 93.115163 -270.833092) (xy 93.145187 -270.789055) (xy 93.181439 -270.749984)
			(xy 93.22311 -270.716753) (xy 93.269268 -270.690104) (xy 93.318882 -270.670632) (xy 93.370844 -270.658772)
			(xy 93.423994 -270.654789) (xy 93.477144 -270.658772) (xy 93.529106 -270.670632) (xy 93.57872 -270.690104)
			(xy 93.624878 -270.716753) (xy 93.666549 -270.749984) (xy 93.702801 -270.789055) (xy 93.732825 -270.833092)
			(xy 93.755951 -270.881113) (xy 93.771661 -270.932043) (xy 93.779604 -270.984747) (xy 93.780102 -271.011396)
			(xy 93.779604 -271.038045) (xy 94.008438 -271.038045) (xy 94.008438 -270.984747) (xy 94.016381 -270.932043)
			(xy 94.032091 -270.881113) (xy 94.055217 -270.833092) (xy 94.085241 -270.789055) (xy 94.121493 -270.749984)
			(xy 94.163164 -270.716753) (xy 94.209322 -270.690104) (xy 94.258936 -270.670632) (xy 94.310898 -270.658772)
			(xy 94.364048 -270.654789) (xy 94.417198 -270.658772) (xy 94.46916 -270.670632) (xy 94.518774 -270.690104)
			(xy 94.564932 -270.716753) (xy 94.606603 -270.749984) (xy 94.642855 -270.789055) (xy 94.672879 -270.833092)
			(xy 94.696005 -270.881113) (xy 94.711715 -270.932043) (xy 94.719658 -270.984747) (xy 94.720156 -271.011396)
			(xy 94.719658 -271.038045) (xy 94.947984 -271.038045) (xy 94.947984 -270.984747) (xy 94.955927 -270.932043)
			(xy 94.971637 -270.881113) (xy 94.994763 -270.833092) (xy 95.024787 -270.789055) (xy 95.061039 -270.749984)
			(xy 95.10271 -270.716753) (xy 95.148868 -270.690104) (xy 95.198482 -270.670632) (xy 95.250444 -270.658772)
			(xy 95.303594 -270.654789) (xy 95.356744 -270.658772) (xy 95.408706 -270.670632) (xy 95.45832 -270.690104)
			(xy 95.504478 -270.716753) (xy 95.546149 -270.749984) (xy 95.582401 -270.789055) (xy 95.612425 -270.833092)
			(xy 95.635551 -270.881113) (xy 95.651261 -270.932043) (xy 95.659204 -270.984747) (xy 95.659702 -271.011396)
			(xy 95.659204 -271.038045) (xy 95.887784 -271.038045) (xy 95.887784 -270.984747) (xy 95.895727 -270.932043)
			(xy 95.911437 -270.881113) (xy 95.934563 -270.833092) (xy 95.964587 -270.789055) (xy 96.000839 -270.749984)
			(xy 96.04251 -270.716753) (xy 96.088668 -270.690104) (xy 96.138282 -270.670632) (xy 96.190244 -270.658772)
			(xy 96.243394 -270.654789) (xy 96.296544 -270.658772) (xy 96.348506 -270.670632) (xy 96.39812 -270.690104)
			(xy 96.444278 -270.716753) (xy 96.485949 -270.749984) (xy 96.522201 -270.789055) (xy 96.552225 -270.833092)
			(xy 96.575351 -270.881113) (xy 96.591061 -270.932043) (xy 96.599004 -270.984747) (xy 96.599502 -271.011396)
			(xy 96.599004 -271.038045) (xy 96.827584 -271.038045) (xy 96.827584 -270.984747) (xy 96.835527 -270.932043)
			(xy 96.851237 -270.881113) (xy 96.874363 -270.833092) (xy 96.904387 -270.789055) (xy 96.940639 -270.749984)
			(xy 96.98231 -270.716753) (xy 97.028468 -270.690104) (xy 97.078082 -270.670632) (xy 97.130044 -270.658772)
			(xy 97.183194 -270.654789) (xy 97.236344 -270.658772) (xy 97.288306 -270.670632) (xy 97.33792 -270.690104)
			(xy 97.384078 -270.716753) (xy 97.425749 -270.749984) (xy 97.462001 -270.789055) (xy 97.492025 -270.833092)
			(xy 97.515151 -270.881113) (xy 97.530861 -270.932043) (xy 97.538804 -270.984747) (xy 97.539302 -271.011396)
			(xy 97.538804 -271.038045) (xy 97.767384 -271.038045) (xy 97.767384 -270.984747) (xy 97.775327 -270.932043)
			(xy 97.791037 -270.881113) (xy 97.814163 -270.833092) (xy 97.844187 -270.789055) (xy 97.880439 -270.749984)
			(xy 97.92211 -270.716753) (xy 97.968268 -270.690104) (xy 98.017882 -270.670632) (xy 98.069844 -270.658772)
			(xy 98.122994 -270.654789) (xy 98.176144 -270.658772) (xy 98.228106 -270.670632) (xy 98.27772 -270.690104)
			(xy 98.323878 -270.716753) (xy 98.365549 -270.749984) (xy 98.401801 -270.789055) (xy 98.431825 -270.833092)
			(xy 98.454951 -270.881113) (xy 98.470661 -270.932043) (xy 98.478604 -270.984747) (xy 98.479102 -271.011396)
			(xy 98.478604 -271.038045) (xy 98.707184 -271.038045) (xy 98.707184 -270.984747) (xy 98.715127 -270.932043)
			(xy 98.730837 -270.881113) (xy 98.753963 -270.833092) (xy 98.783987 -270.789055) (xy 98.820239 -270.749984)
			(xy 98.86191 -270.716753) (xy 98.908068 -270.690104) (xy 98.957682 -270.670632) (xy 99.009644 -270.658772)
			(xy 99.062794 -270.654789) (xy 99.115944 -270.658772) (xy 99.167906 -270.670632) (xy 99.21752 -270.690104)
			(xy 99.263678 -270.716753) (xy 99.305349 -270.749984) (xy 99.341601 -270.789055) (xy 99.371625 -270.833092)
			(xy 99.394751 -270.881113) (xy 99.410461 -270.932043) (xy 99.418404 -270.984747) (xy 99.418902 -271.011396)
			(xy 99.418404 -271.038045) (xy 99.646984 -271.038045) (xy 99.646984 -270.984747) (xy 99.654927 -270.932043)
			(xy 99.670637 -270.881113) (xy 99.693763 -270.833092) (xy 99.723787 -270.789055) (xy 99.760039 -270.749984)
			(xy 99.80171 -270.716753) (xy 99.847868 -270.690104) (xy 99.897482 -270.670632) (xy 99.949444 -270.658772)
			(xy 100.002594 -270.654789) (xy 100.055744 -270.658772) (xy 100.107706 -270.670632) (xy 100.15732 -270.690104)
			(xy 100.203478 -270.716753) (xy 100.245149 -270.749984) (xy 100.281401 -270.789055) (xy 100.311425 -270.833092)
			(xy 100.334551 -270.881113) (xy 100.350261 -270.932043) (xy 100.358204 -270.984747) (xy 100.358702 -271.011396)
			(xy 100.358204 -271.038045) (xy 100.587038 -271.038045) (xy 100.587038 -270.984747) (xy 100.594981 -270.932043)
			(xy 100.610691 -270.881113) (xy 100.633817 -270.833092) (xy 100.663841 -270.789055) (xy 100.700093 -270.749984)
			(xy 100.741764 -270.716753) (xy 100.787922 -270.690104) (xy 100.837536 -270.670632) (xy 100.889498 -270.658772)
			(xy 100.942648 -270.654789) (xy 100.995798 -270.658772) (xy 101.04776 -270.670632) (xy 101.097374 -270.690104)
			(xy 101.143532 -270.716753) (xy 101.185203 -270.749984) (xy 101.221455 -270.789055) (xy 101.251479 -270.833092)
			(xy 101.274605 -270.881113) (xy 101.290315 -270.932043) (xy 101.298258 -270.984747) (xy 101.298756 -271.011396)
			(xy 101.298258 -271.038045) (xy 101.526838 -271.038045) (xy 101.526838 -270.984747) (xy 101.534781 -270.932043)
			(xy 101.550491 -270.881113) (xy 101.573617 -270.833092) (xy 101.603641 -270.789055) (xy 101.639893 -270.749984)
			(xy 101.681564 -270.716753) (xy 101.727722 -270.690104) (xy 101.777336 -270.670632) (xy 101.829298 -270.658772)
			(xy 101.882448 -270.654789) (xy 101.935598 -270.658772) (xy 101.98756 -270.670632) (xy 102.037174 -270.690104)
			(xy 102.083332 -270.716753) (xy 102.125003 -270.749984) (xy 102.161255 -270.789055) (xy 102.191279 -270.833092)
			(xy 102.214405 -270.881113) (xy 102.230115 -270.932043) (xy 102.238058 -270.984747) (xy 102.238556 -271.011396)
			(xy 102.238058 -271.038045) (xy 102.466384 -271.038045) (xy 102.466384 -270.984747) (xy 102.474327 -270.932043)
			(xy 102.490037 -270.881113) (xy 102.513163 -270.833092) (xy 102.543187 -270.789055) (xy 102.579439 -270.749984)
			(xy 102.62111 -270.716753) (xy 102.667268 -270.690104) (xy 102.716882 -270.670632) (xy 102.768844 -270.658772)
			(xy 102.821994 -270.654789) (xy 102.875144 -270.658772) (xy 102.927106 -270.670632) (xy 102.97672 -270.690104)
			(xy 103.022878 -270.716753) (xy 103.064549 -270.749984) (xy 103.100801 -270.789055) (xy 103.130825 -270.833092)
			(xy 103.153951 -270.881113) (xy 103.169661 -270.932043) (xy 103.177604 -270.984747) (xy 103.178102 -271.011396)
			(xy 103.177604 -271.038045) (xy 103.406184 -271.038045) (xy 103.406184 -270.984747) (xy 103.414127 -270.932043)
			(xy 103.429837 -270.881113) (xy 103.452963 -270.833092) (xy 103.482987 -270.789055) (xy 103.519239 -270.749984)
			(xy 103.56091 -270.716753) (xy 103.607068 -270.690104) (xy 103.656682 -270.670632) (xy 103.708644 -270.658772)
			(xy 103.761794 -270.654789) (xy 103.814944 -270.658772) (xy 103.866906 -270.670632) (xy 103.91652 -270.690104)
			(xy 103.962678 -270.716753) (xy 104.004349 -270.749984) (xy 104.040601 -270.789055) (xy 104.070625 -270.833092)
			(xy 104.093751 -270.881113) (xy 104.109461 -270.932043) (xy 104.117404 -270.984747) (xy 104.117902 -271.011396)
			(xy 104.117404 -271.038045) (xy 104.345984 -271.038045) (xy 104.345984 -270.984747) (xy 104.353927 -270.932043)
			(xy 104.369637 -270.881113) (xy 104.392763 -270.833092) (xy 104.422787 -270.789055) (xy 104.459039 -270.749984)
			(xy 104.50071 -270.716753) (xy 104.546868 -270.690104) (xy 104.596482 -270.670632) (xy 104.648444 -270.658772)
			(xy 104.701594 -270.654789) (xy 104.754744 -270.658772) (xy 104.806706 -270.670632) (xy 104.85632 -270.690104)
			(xy 104.902478 -270.716753) (xy 104.944149 -270.749984) (xy 104.980401 -270.789055) (xy 105.010425 -270.833092)
			(xy 105.033551 -270.881113) (xy 105.049261 -270.932043) (xy 105.057204 -270.984747) (xy 105.057702 -271.011396)
			(xy 105.057204 -271.038045) (xy 105.285784 -271.038045) (xy 105.285784 -270.984747) (xy 105.293727 -270.932043)
			(xy 105.309437 -270.881113) (xy 105.332563 -270.833092) (xy 105.362587 -270.789055) (xy 105.398839 -270.749984)
			(xy 105.44051 -270.716753) (xy 105.486668 -270.690104) (xy 105.536282 -270.670632) (xy 105.588244 -270.658772)
			(xy 105.641394 -270.654789) (xy 105.694544 -270.658772) (xy 105.746506 -270.670632) (xy 105.79612 -270.690104)
			(xy 105.842278 -270.716753) (xy 105.883949 -270.749984) (xy 105.920201 -270.789055) (xy 105.950225 -270.833092)
			(xy 105.973351 -270.881113) (xy 105.989061 -270.932043) (xy 105.997004 -270.984747) (xy 105.997502 -271.011396)
			(xy 105.997004 -271.038045) (xy 106.225584 -271.038045) (xy 106.225584 -270.984747) (xy 106.233527 -270.932043)
			(xy 106.249237 -270.881113) (xy 106.272363 -270.833092) (xy 106.302387 -270.789055) (xy 106.338639 -270.749984)
			(xy 106.38031 -270.716753) (xy 106.426468 -270.690104) (xy 106.476082 -270.670632) (xy 106.528044 -270.658772)
			(xy 106.581194 -270.654789) (xy 106.634344 -270.658772) (xy 106.686306 -270.670632) (xy 106.73592 -270.690104)
			(xy 106.782078 -270.716753) (xy 106.823749 -270.749984) (xy 106.860001 -270.789055) (xy 106.890025 -270.833092)
			(xy 106.913151 -270.881113) (xy 106.928861 -270.932043) (xy 106.936804 -270.984747) (xy 106.937302 -271.011396)
			(xy 106.936804 -271.038045) (xy 107.165384 -271.038045) (xy 107.165384 -270.984747) (xy 107.173327 -270.932043)
			(xy 107.189037 -270.881113) (xy 107.212163 -270.833092) (xy 107.242187 -270.789055) (xy 107.278439 -270.749984)
			(xy 107.32011 -270.716753) (xy 107.366268 -270.690104) (xy 107.415882 -270.670632) (xy 107.467844 -270.658772)
			(xy 107.520994 -270.654789) (xy 107.574144 -270.658772) (xy 107.626106 -270.670632) (xy 107.67572 -270.690104)
			(xy 107.721878 -270.716753) (xy 107.763549 -270.749984) (xy 107.799801 -270.789055) (xy 107.829825 -270.833092)
			(xy 107.852951 -270.881113) (xy 107.868661 -270.932043) (xy 107.876604 -270.984747) (xy 107.877102 -271.011396)
			(xy 107.876604 -271.038045) (xy 107.868661 -271.090749) (xy 107.852951 -271.141679) (xy 107.829825 -271.1897)
			(xy 107.799801 -271.233737) (xy 107.763549 -271.272808) (xy 107.721878 -271.306039) (xy 107.67572 -271.332688)
			(xy 107.626106 -271.35216) (xy 107.574144 -271.36402) (xy 107.520994 -271.368004) (xy 107.467844 -271.36402)
			(xy 107.415882 -271.35216) (xy 107.366268 -271.332688) (xy 107.32011 -271.306039) (xy 107.278439 -271.272808)
			(xy 107.242187 -271.233737) (xy 107.212163 -271.1897) (xy 107.189037 -271.141679) (xy 107.173327 -271.090749)
			(xy 107.165384 -271.038045) (xy 106.936804 -271.038045) (xy 106.928861 -271.090749) (xy 106.913151 -271.141679)
			(xy 106.890025 -271.1897) (xy 106.860001 -271.233737) (xy 106.823749 -271.272808) (xy 106.782078 -271.306039)
			(xy 106.73592 -271.332688) (xy 106.686306 -271.35216) (xy 106.634344 -271.36402) (xy 106.581194 -271.368004)
			(xy 106.528044 -271.36402) (xy 106.476082 -271.35216) (xy 106.426468 -271.332688) (xy 106.38031 -271.306039)
			(xy 106.338639 -271.272808) (xy 106.302387 -271.233737) (xy 106.272363 -271.1897) (xy 106.249237 -271.141679)
			(xy 106.233527 -271.090749) (xy 106.225584 -271.038045) (xy 105.997004 -271.038045) (xy 105.989061 -271.090749)
			(xy 105.973351 -271.141679) (xy 105.950225 -271.1897) (xy 105.920201 -271.233737) (xy 105.883949 -271.272808)
			(xy 105.842278 -271.306039) (xy 105.79612 -271.332688) (xy 105.746506 -271.35216) (xy 105.694544 -271.36402)
			(xy 105.641394 -271.368004) (xy 105.588244 -271.36402) (xy 105.536282 -271.35216) (xy 105.486668 -271.332688)
			(xy 105.44051 -271.306039) (xy 105.398839 -271.272808) (xy 105.362587 -271.233737) (xy 105.332563 -271.1897)
			(xy 105.309437 -271.141679) (xy 105.293727 -271.090749) (xy 105.285784 -271.038045) (xy 105.057204 -271.038045)
			(xy 105.049261 -271.090749) (xy 105.033551 -271.141679) (xy 105.010425 -271.1897) (xy 104.980401 -271.233737)
			(xy 104.944149 -271.272808) (xy 104.902478 -271.306039) (xy 104.85632 -271.332688) (xy 104.806706 -271.35216)
			(xy 104.754744 -271.36402) (xy 104.701594 -271.368004) (xy 104.648444 -271.36402) (xy 104.596482 -271.35216)
			(xy 104.546868 -271.332688) (xy 104.50071 -271.306039) (xy 104.459039 -271.272808) (xy 104.422787 -271.233737)
			(xy 104.392763 -271.1897) (xy 104.369637 -271.141679) (xy 104.353927 -271.090749) (xy 104.345984 -271.038045)
			(xy 104.117404 -271.038045) (xy 104.109461 -271.090749) (xy 104.093751 -271.141679) (xy 104.070625 -271.1897)
			(xy 104.040601 -271.233737) (xy 104.004349 -271.272808) (xy 103.962678 -271.306039) (xy 103.91652 -271.332688)
			(xy 103.866906 -271.35216) (xy 103.814944 -271.36402) (xy 103.761794 -271.368004) (xy 103.708644 -271.36402)
			(xy 103.656682 -271.35216) (xy 103.607068 -271.332688) (xy 103.56091 -271.306039) (xy 103.519239 -271.272808)
			(xy 103.482987 -271.233737) (xy 103.452963 -271.1897) (xy 103.429837 -271.141679) (xy 103.414127 -271.090749)
			(xy 103.406184 -271.038045) (xy 103.177604 -271.038045) (xy 103.169661 -271.090749) (xy 103.153951 -271.141679)
			(xy 103.130825 -271.1897) (xy 103.100801 -271.233737) (xy 103.064549 -271.272808) (xy 103.022878 -271.306039)
			(xy 102.97672 -271.332688) (xy 102.927106 -271.35216) (xy 102.875144 -271.36402) (xy 102.821994 -271.368004)
			(xy 102.768844 -271.36402) (xy 102.716882 -271.35216) (xy 102.667268 -271.332688) (xy 102.62111 -271.306039)
			(xy 102.579439 -271.272808) (xy 102.543187 -271.233737) (xy 102.513163 -271.1897) (xy 102.490037 -271.141679)
			(xy 102.474327 -271.090749) (xy 102.466384 -271.038045) (xy 102.238058 -271.038045) (xy 102.230115 -271.090749)
			(xy 102.214405 -271.141679) (xy 102.191279 -271.1897) (xy 102.161255 -271.233737) (xy 102.125003 -271.272808)
			(xy 102.083332 -271.306039) (xy 102.037174 -271.332688) (xy 101.98756 -271.35216) (xy 101.935598 -271.36402)
			(xy 101.882448 -271.368004) (xy 101.829298 -271.36402) (xy 101.777336 -271.35216) (xy 101.727722 -271.332688)
			(xy 101.681564 -271.306039) (xy 101.639893 -271.272808) (xy 101.603641 -271.233737) (xy 101.573617 -271.1897)
			(xy 101.550491 -271.141679) (xy 101.534781 -271.090749) (xy 101.526838 -271.038045) (xy 101.298258 -271.038045)
			(xy 101.290315 -271.090749) (xy 101.274605 -271.141679) (xy 101.251479 -271.1897) (xy 101.221455 -271.233737)
			(xy 101.185203 -271.272808) (xy 101.143532 -271.306039) (xy 101.097374 -271.332688) (xy 101.04776 -271.35216)
			(xy 100.995798 -271.36402) (xy 100.942648 -271.368004) (xy 100.889498 -271.36402) (xy 100.837536 -271.35216)
			(xy 100.787922 -271.332688) (xy 100.741764 -271.306039) (xy 100.700093 -271.272808) (xy 100.663841 -271.233737)
			(xy 100.633817 -271.1897) (xy 100.610691 -271.141679) (xy 100.594981 -271.090749) (xy 100.587038 -271.038045)
			(xy 100.358204 -271.038045) (xy 100.350261 -271.090749) (xy 100.334551 -271.141679) (xy 100.311425 -271.1897)
			(xy 100.281401 -271.233737) (xy 100.245149 -271.272808) (xy 100.203478 -271.306039) (xy 100.15732 -271.332688)
			(xy 100.107706 -271.35216) (xy 100.055744 -271.36402) (xy 100.002594 -271.368004) (xy 99.949444 -271.36402)
			(xy 99.897482 -271.35216) (xy 99.847868 -271.332688) (xy 99.80171 -271.306039) (xy 99.760039 -271.272808)
			(xy 99.723787 -271.233737) (xy 99.693763 -271.1897) (xy 99.670637 -271.141679) (xy 99.654927 -271.090749)
			(xy 99.646984 -271.038045) (xy 99.418404 -271.038045) (xy 99.410461 -271.090749) (xy 99.394751 -271.141679)
			(xy 99.371625 -271.1897) (xy 99.341601 -271.233737) (xy 99.305349 -271.272808) (xy 99.263678 -271.306039)
			(xy 99.21752 -271.332688) (xy 99.167906 -271.35216) (xy 99.115944 -271.36402) (xy 99.062794 -271.368004)
			(xy 99.009644 -271.36402) (xy 98.957682 -271.35216) (xy 98.908068 -271.332688) (xy 98.86191 -271.306039)
			(xy 98.820239 -271.272808) (xy 98.783987 -271.233737) (xy 98.753963 -271.1897) (xy 98.730837 -271.141679)
			(xy 98.715127 -271.090749) (xy 98.707184 -271.038045) (xy 98.478604 -271.038045) (xy 98.470661 -271.090749)
			(xy 98.454951 -271.141679) (xy 98.431825 -271.1897) (xy 98.401801 -271.233737) (xy 98.365549 -271.272808)
			(xy 98.323878 -271.306039) (xy 98.27772 -271.332688) (xy 98.228106 -271.35216) (xy 98.176144 -271.36402)
			(xy 98.122994 -271.368004) (xy 98.069844 -271.36402) (xy 98.017882 -271.35216) (xy 97.968268 -271.332688)
			(xy 97.92211 -271.306039) (xy 97.880439 -271.272808) (xy 97.844187 -271.233737) (xy 97.814163 -271.1897)
			(xy 97.791037 -271.141679) (xy 97.775327 -271.090749) (xy 97.767384 -271.038045) (xy 97.538804 -271.038045)
			(xy 97.530861 -271.090749) (xy 97.515151 -271.141679) (xy 97.492025 -271.1897) (xy 97.462001 -271.233737)
			(xy 97.425749 -271.272808) (xy 97.384078 -271.306039) (xy 97.33792 -271.332688) (xy 97.288306 -271.35216)
			(xy 97.236344 -271.36402) (xy 97.183194 -271.368004) (xy 97.130044 -271.36402) (xy 97.078082 -271.35216)
			(xy 97.028468 -271.332688) (xy 96.98231 -271.306039) (xy 96.940639 -271.272808) (xy 96.904387 -271.233737)
			(xy 96.874363 -271.1897) (xy 96.851237 -271.141679) (xy 96.835527 -271.090749) (xy 96.827584 -271.038045)
			(xy 96.599004 -271.038045) (xy 96.591061 -271.090749) (xy 96.575351 -271.141679) (xy 96.552225 -271.1897)
			(xy 96.522201 -271.233737) (xy 96.485949 -271.272808) (xy 96.444278 -271.306039) (xy 96.39812 -271.332688)
			(xy 96.348506 -271.35216) (xy 96.296544 -271.36402) (xy 96.243394 -271.368004) (xy 96.190244 -271.36402)
			(xy 96.138282 -271.35216) (xy 96.088668 -271.332688) (xy 96.04251 -271.306039) (xy 96.000839 -271.272808)
			(xy 95.964587 -271.233737) (xy 95.934563 -271.1897) (xy 95.911437 -271.141679) (xy 95.895727 -271.090749)
			(xy 95.887784 -271.038045) (xy 95.659204 -271.038045) (xy 95.651261 -271.090749) (xy 95.635551 -271.141679)
			(xy 95.612425 -271.1897) (xy 95.582401 -271.233737) (xy 95.546149 -271.272808) (xy 95.504478 -271.306039)
			(xy 95.45832 -271.332688) (xy 95.408706 -271.35216) (xy 95.356744 -271.36402) (xy 95.303594 -271.368004)
			(xy 95.250444 -271.36402) (xy 95.198482 -271.35216) (xy 95.148868 -271.332688) (xy 95.10271 -271.306039)
			(xy 95.061039 -271.272808) (xy 95.024787 -271.233737) (xy 94.994763 -271.1897) (xy 94.971637 -271.141679)
			(xy 94.955927 -271.090749) (xy 94.947984 -271.038045) (xy 94.719658 -271.038045) (xy 94.711715 -271.090749)
			(xy 94.696005 -271.141679) (xy 94.672879 -271.1897) (xy 94.642855 -271.233737) (xy 94.606603 -271.272808)
			(xy 94.564932 -271.306039) (xy 94.518774 -271.332688) (xy 94.46916 -271.35216) (xy 94.417198 -271.36402)
			(xy 94.364048 -271.368004) (xy 94.310898 -271.36402) (xy 94.258936 -271.35216) (xy 94.209322 -271.332688)
			(xy 94.163164 -271.306039) (xy 94.121493 -271.272808) (xy 94.085241 -271.233737) (xy 94.055217 -271.1897)
			(xy 94.032091 -271.141679) (xy 94.016381 -271.090749) (xy 94.008438 -271.038045) (xy 93.779604 -271.038045)
			(xy 93.771661 -271.090749) (xy 93.755951 -271.141679) (xy 93.732825 -271.1897) (xy 93.702801 -271.233737)
			(xy 93.666549 -271.272808) (xy 93.624878 -271.306039) (xy 93.57872 -271.332688) (xy 93.529106 -271.35216)
			(xy 93.477144 -271.36402) (xy 93.423994 -271.368004) (xy 93.370844 -271.36402) (xy 93.318882 -271.35216)
			(xy 93.269268 -271.332688) (xy 93.22311 -271.306039) (xy 93.181439 -271.272808) (xy 93.145187 -271.233737)
			(xy 93.115163 -271.1897) (xy 93.092037 -271.141679) (xy 93.076327 -271.090749) (xy 93.068384 -271.038045)
			(xy 92.839804 -271.038045) (xy 92.831861 -271.090749) (xy 92.816151 -271.141679) (xy 92.793025 -271.1897)
			(xy 92.763001 -271.233737) (xy 92.726749 -271.272808) (xy 92.685078 -271.306039) (xy 92.63892 -271.332688)
			(xy 92.589306 -271.35216) (xy 92.537344 -271.36402) (xy 92.484194 -271.368004) (xy 92.431044 -271.36402)
			(xy 92.379082 -271.35216) (xy 92.329468 -271.332688) (xy 92.28331 -271.306039) (xy 92.241639 -271.272808)
			(xy 92.205387 -271.233737) (xy 92.175363 -271.1897) (xy 92.152237 -271.141679) (xy 92.136527 -271.090749)
			(xy 92.128584 -271.038045) (xy 91.900004 -271.038045) (xy 91.892061 -271.090749) (xy 91.876351 -271.141679)
			(xy 91.853225 -271.1897) (xy 91.823201 -271.233737) (xy 91.786949 -271.272808) (xy 91.745278 -271.306039)
			(xy 91.69912 -271.332688) (xy 91.649506 -271.35216) (xy 91.597544 -271.36402) (xy 91.544394 -271.368004)
			(xy 91.491244 -271.36402) (xy 91.439282 -271.35216) (xy 91.389668 -271.332688) (xy 91.34351 -271.306039)
			(xy 91.301839 -271.272808) (xy 91.265587 -271.233737) (xy 91.235563 -271.1897) (xy 91.212437 -271.141679)
			(xy 91.196727 -271.090749) (xy 91.188784 -271.038045) (xy 90.960204 -271.038045) (xy 90.952261 -271.090749)
			(xy 90.936551 -271.141679) (xy 90.913425 -271.1897) (xy 90.883401 -271.233737) (xy 90.847149 -271.272808)
			(xy 90.805478 -271.306039) (xy 90.75932 -271.332688) (xy 90.709706 -271.35216) (xy 90.657744 -271.36402)
			(xy 90.604594 -271.368004) (xy 90.551444 -271.36402) (xy 90.499482 -271.35216) (xy 90.449868 -271.332688)
			(xy 90.40371 -271.306039) (xy 90.362039 -271.272808) (xy 90.325787 -271.233737) (xy 90.295763 -271.1897)
			(xy 90.272637 -271.141679) (xy 90.256927 -271.090749) (xy 90.248984 -271.038045) (xy 90.020404 -271.038045)
			(xy 90.012461 -271.090749) (xy 89.996751 -271.141679) (xy 89.973625 -271.1897) (xy 89.943601 -271.233737)
			(xy 89.907349 -271.272808) (xy 89.865678 -271.306039) (xy 89.81952 -271.332688) (xy 89.769906 -271.35216)
			(xy 89.717944 -271.36402) (xy 89.664794 -271.368004) (xy 89.611644 -271.36402) (xy 89.559682 -271.35216)
			(xy 89.510068 -271.332688) (xy 89.46391 -271.306039) (xy 89.422239 -271.272808) (xy 89.385987 -271.233737)
			(xy 89.355963 -271.1897) (xy 89.332837 -271.141679) (xy 89.317127 -271.090749) (xy 89.309184 -271.038045)
			(xy 89.080575 -271.038045) (xy 89.080575 -271.038759) (xy 89.072204 -271.092834) (xy 89.055659 -271.144991)
			(xy 89.03133 -271.194004) (xy 88.999789 -271.238717) (xy 88.961779 -271.278079) (xy 88.918195 -271.311163)
			(xy 88.870062 -271.33719) (xy 88.818515 -271.355547) (xy 88.764765 -271.365802) (xy 88.73744 -271.36725)
			(xy 88.727669 -271.368035) (xy 88.709779 -271.376002) (xy 88.69618 -271.390095) (xy 88.688856 -271.408258)
			(xy 88.688418 -271.41805) (xy 88.688418 -271.6022) (xy 88.73744 -271.651222) (xy 88.748561 -271.66157)
			(xy 88.775378 -271.675801) (xy 88.805194 -271.681519) (xy 88.835373 -271.678216) (xy 88.863247 -271.666185)
			(xy 88.886352 -271.64649) (xy 88.89492 -271.63395) (xy 88.908999 -271.612641) (xy 88.942292 -271.573913)
			(xy 88.980779 -271.540341) (xy 89.02367 -271.512615) (xy 89.070083 -271.491304) (xy 89.119066 -271.476847)
			(xy 89.169612 -271.469539) (xy 89.195148 -271.469104) (xy 89.223128 -271.469657) (xy 89.278399 -271.478418)
			(xy 89.331619 -271.495717) (xy 89.381478 -271.521127) (xy 89.426748 -271.554025) (xy 89.466314 -271.593598)
			(xy 89.499204 -271.638874) (xy 89.524606 -271.688737) (xy 89.541896 -271.741959) (xy 89.550648 -271.797232)
			(xy 89.551256 -271.825212) (xy 89.550815 -271.850747) (xy 89.550654 -271.851861) (xy 89.779084 -271.851861)
			(xy 89.779084 -271.798563) (xy 89.787027 -271.745859) (xy 89.802737 -271.694929) (xy 89.825863 -271.646908)
			(xy 89.855887 -271.602871) (xy 89.892139 -271.5638) (xy 89.93381 -271.530569) (xy 89.979968 -271.50392)
			(xy 90.029582 -271.484448) (xy 90.081544 -271.472588) (xy 90.134694 -271.468605) (xy 90.187844 -271.472588)
			(xy 90.239806 -271.484448) (xy 90.28942 -271.50392) (xy 90.335578 -271.530569) (xy 90.377249 -271.5638)
			(xy 90.413501 -271.602871) (xy 90.443525 -271.646908) (xy 90.466651 -271.694929) (xy 90.482361 -271.745859)
			(xy 90.490304 -271.798563) (xy 90.490802 -271.825212) (xy 90.490304 -271.851861) (xy 90.718884 -271.851861)
			(xy 90.718884 -271.798563) (xy 90.726827 -271.745859) (xy 90.742537 -271.694929) (xy 90.765663 -271.646908)
			(xy 90.795687 -271.602871) (xy 90.831939 -271.5638) (xy 90.87361 -271.530569) (xy 90.919768 -271.50392)
			(xy 90.969382 -271.484448) (xy 91.021344 -271.472588) (xy 91.074494 -271.468605) (xy 91.127644 -271.472588)
			(xy 91.179606 -271.484448) (xy 91.22922 -271.50392) (xy 91.275378 -271.530569) (xy 91.317049 -271.5638)
			(xy 91.353301 -271.602871) (xy 91.383325 -271.646908) (xy 91.406451 -271.694929) (xy 91.422161 -271.745859)
			(xy 91.430104 -271.798563) (xy 91.430602 -271.825212) (xy 91.430104 -271.851861) (xy 91.658938 -271.851861)
			(xy 91.658938 -271.798563) (xy 91.666881 -271.745859) (xy 91.682591 -271.694929) (xy 91.705717 -271.646908)
			(xy 91.735741 -271.602871) (xy 91.771993 -271.5638) (xy 91.813664 -271.530569) (xy 91.859822 -271.50392)
			(xy 91.909436 -271.484448) (xy 91.961398 -271.472588) (xy 92.014548 -271.468605) (xy 92.067698 -271.472588)
			(xy 92.11966 -271.484448) (xy 92.169274 -271.50392) (xy 92.215432 -271.530569) (xy 92.257103 -271.5638)
			(xy 92.293355 -271.602871) (xy 92.323379 -271.646908) (xy 92.346505 -271.694929) (xy 92.362215 -271.745859)
			(xy 92.370158 -271.798563) (xy 92.370656 -271.825212) (xy 92.370158 -271.851861) (xy 92.598738 -271.851861)
			(xy 92.598738 -271.798563) (xy 92.606681 -271.745859) (xy 92.622391 -271.694929) (xy 92.645517 -271.646908)
			(xy 92.675541 -271.602871) (xy 92.711793 -271.5638) (xy 92.753464 -271.530569) (xy 92.799622 -271.50392)
			(xy 92.849236 -271.484448) (xy 92.901198 -271.472588) (xy 92.954348 -271.468605) (xy 93.007498 -271.472588)
			(xy 93.05946 -271.484448) (xy 93.109074 -271.50392) (xy 93.155232 -271.530569) (xy 93.196903 -271.5638)
			(xy 93.233155 -271.602871) (xy 93.263179 -271.646908) (xy 93.286305 -271.694929) (xy 93.302015 -271.745859)
			(xy 93.309958 -271.798563) (xy 93.310456 -271.825212) (xy 93.309958 -271.851861) (xy 93.538538 -271.851861)
			(xy 93.538538 -271.798563) (xy 93.546481 -271.745859) (xy 93.562191 -271.694929) (xy 93.585317 -271.646908)
			(xy 93.615341 -271.602871) (xy 93.651593 -271.5638) (xy 93.693264 -271.530569) (xy 93.739422 -271.50392)
			(xy 93.789036 -271.484448) (xy 93.840998 -271.472588) (xy 93.894148 -271.468605) (xy 93.947298 -271.472588)
			(xy 93.99926 -271.484448) (xy 94.048874 -271.50392) (xy 94.095032 -271.530569) (xy 94.136703 -271.5638)
			(xy 94.172955 -271.602871) (xy 94.202979 -271.646908) (xy 94.226105 -271.694929) (xy 94.241815 -271.745859)
			(xy 94.249758 -271.798563) (xy 94.250256 -271.825212) (xy 94.249758 -271.851861) (xy 94.478338 -271.851861)
			(xy 94.478338 -271.798563) (xy 94.486281 -271.745859) (xy 94.501991 -271.694929) (xy 94.525117 -271.646908)
			(xy 94.555141 -271.602871) (xy 94.591393 -271.5638) (xy 94.633064 -271.530569) (xy 94.679222 -271.50392)
			(xy 94.728836 -271.484448) (xy 94.780798 -271.472588) (xy 94.833948 -271.468605) (xy 94.887098 -271.472588)
			(xy 94.93906 -271.484448) (xy 94.988674 -271.50392) (xy 95.034832 -271.530569) (xy 95.076503 -271.5638)
			(xy 95.112755 -271.602871) (xy 95.142779 -271.646908) (xy 95.165905 -271.694929) (xy 95.181615 -271.745859)
			(xy 95.189558 -271.798563) (xy 95.190056 -271.825212) (xy 95.189558 -271.851861) (xy 95.418138 -271.851861)
			(xy 95.418138 -271.798563) (xy 95.426081 -271.745859) (xy 95.441791 -271.694929) (xy 95.464917 -271.646908)
			(xy 95.494941 -271.602871) (xy 95.531193 -271.5638) (xy 95.572864 -271.530569) (xy 95.619022 -271.50392)
			(xy 95.668636 -271.484448) (xy 95.720598 -271.472588) (xy 95.773748 -271.468605) (xy 95.826898 -271.472588)
			(xy 95.87886 -271.484448) (xy 95.928474 -271.50392) (xy 95.974632 -271.530569) (xy 96.016303 -271.5638)
			(xy 96.052555 -271.602871) (xy 96.082579 -271.646908) (xy 96.105705 -271.694929) (xy 96.121415 -271.745859)
			(xy 96.129358 -271.798563) (xy 96.129856 -271.825212) (xy 96.129358 -271.851861) (xy 96.357938 -271.851861)
			(xy 96.357938 -271.798563) (xy 96.365881 -271.745859) (xy 96.381591 -271.694929) (xy 96.404717 -271.646908)
			(xy 96.434741 -271.602871) (xy 96.470993 -271.5638) (xy 96.512664 -271.530569) (xy 96.558822 -271.50392)
			(xy 96.608436 -271.484448) (xy 96.660398 -271.472588) (xy 96.713548 -271.468605) (xy 96.766698 -271.472588)
			(xy 96.81866 -271.484448) (xy 96.868274 -271.50392) (xy 96.914432 -271.530569) (xy 96.956103 -271.5638)
			(xy 96.992355 -271.602871) (xy 97.022379 -271.646908) (xy 97.045505 -271.694929) (xy 97.061215 -271.745859)
			(xy 97.069158 -271.798563) (xy 97.069656 -271.825212) (xy 97.069158 -271.851861) (xy 97.297484 -271.851861)
			(xy 97.297484 -271.798563) (xy 97.305427 -271.745859) (xy 97.321137 -271.694929) (xy 97.344263 -271.646908)
			(xy 97.374287 -271.602871) (xy 97.410539 -271.5638) (xy 97.45221 -271.530569) (xy 97.498368 -271.50392)
			(xy 97.547982 -271.484448) (xy 97.599944 -271.472588) (xy 97.653094 -271.468605) (xy 97.706244 -271.472588)
			(xy 97.758206 -271.484448) (xy 97.80782 -271.50392) (xy 97.853978 -271.530569) (xy 97.895649 -271.5638)
			(xy 97.931901 -271.602871) (xy 97.961925 -271.646908) (xy 97.985051 -271.694929) (xy 98.000761 -271.745859)
			(xy 98.008704 -271.798563) (xy 98.009202 -271.825212) (xy 98.008704 -271.851861) (xy 98.237538 -271.851861)
			(xy 98.237538 -271.798563) (xy 98.245481 -271.745859) (xy 98.261191 -271.694929) (xy 98.284317 -271.646908)
			(xy 98.314341 -271.602871) (xy 98.350593 -271.5638) (xy 98.392264 -271.530569) (xy 98.438422 -271.50392)
			(xy 98.488036 -271.484448) (xy 98.539998 -271.472588) (xy 98.593148 -271.468605) (xy 98.646298 -271.472588)
			(xy 98.69826 -271.484448) (xy 98.747874 -271.50392) (xy 98.794032 -271.530569) (xy 98.835703 -271.5638)
			(xy 98.871955 -271.602871) (xy 98.901979 -271.646908) (xy 98.925105 -271.694929) (xy 98.940815 -271.745859)
			(xy 98.948758 -271.798563) (xy 98.949256 -271.825212) (xy 98.948758 -271.851861) (xy 99.177338 -271.851861)
			(xy 99.177338 -271.798563) (xy 99.185281 -271.745859) (xy 99.200991 -271.694929) (xy 99.224117 -271.646908)
			(xy 99.254141 -271.602871) (xy 99.290393 -271.5638) (xy 99.332064 -271.530569) (xy 99.378222 -271.50392)
			(xy 99.427836 -271.484448) (xy 99.479798 -271.472588) (xy 99.532948 -271.468605) (xy 99.586098 -271.472588)
			(xy 99.63806 -271.484448) (xy 99.687674 -271.50392) (xy 99.733832 -271.530569) (xy 99.775503 -271.5638)
			(xy 99.811755 -271.602871) (xy 99.841779 -271.646908) (xy 99.864905 -271.694929) (xy 99.880615 -271.745859)
			(xy 99.888558 -271.798563) (xy 99.889056 -271.825212) (xy 99.888558 -271.851861) (xy 100.117138 -271.851861)
			(xy 100.117138 -271.798563) (xy 100.125081 -271.745859) (xy 100.140791 -271.694929) (xy 100.163917 -271.646908)
			(xy 100.193941 -271.602871) (xy 100.230193 -271.5638) (xy 100.271864 -271.530569) (xy 100.318022 -271.50392)
			(xy 100.367636 -271.484448) (xy 100.419598 -271.472588) (xy 100.472748 -271.468605) (xy 100.525898 -271.472588)
			(xy 100.57786 -271.484448) (xy 100.627474 -271.50392) (xy 100.673632 -271.530569) (xy 100.715303 -271.5638)
			(xy 100.751555 -271.602871) (xy 100.781579 -271.646908) (xy 100.804705 -271.694929) (xy 100.820415 -271.745859)
			(xy 100.828358 -271.798563) (xy 100.828856 -271.825212) (xy 100.828358 -271.851861) (xy 101.056938 -271.851861)
			(xy 101.056938 -271.798563) (xy 101.064881 -271.745859) (xy 101.080591 -271.694929) (xy 101.103717 -271.646908)
			(xy 101.133741 -271.602871) (xy 101.169993 -271.5638) (xy 101.211664 -271.530569) (xy 101.257822 -271.50392)
			(xy 101.307436 -271.484448) (xy 101.359398 -271.472588) (xy 101.412548 -271.468605) (xy 101.465698 -271.472588)
			(xy 101.51766 -271.484448) (xy 101.567274 -271.50392) (xy 101.613432 -271.530569) (xy 101.655103 -271.5638)
			(xy 101.691355 -271.602871) (xy 101.721379 -271.646908) (xy 101.744505 -271.694929) (xy 101.760215 -271.745859)
			(xy 101.768158 -271.798563) (xy 101.768656 -271.825212) (xy 101.768158 -271.851861) (xy 101.996738 -271.851861)
			(xy 101.996738 -271.798563) (xy 102.004681 -271.745859) (xy 102.020391 -271.694929) (xy 102.043517 -271.646908)
			(xy 102.073541 -271.602871) (xy 102.109793 -271.5638) (xy 102.151464 -271.530569) (xy 102.197622 -271.50392)
			(xy 102.247236 -271.484448) (xy 102.299198 -271.472588) (xy 102.352348 -271.468605) (xy 102.405498 -271.472588)
			(xy 102.45746 -271.484448) (xy 102.507074 -271.50392) (xy 102.553232 -271.530569) (xy 102.594903 -271.5638)
			(xy 102.631155 -271.602871) (xy 102.661179 -271.646908) (xy 102.684305 -271.694929) (xy 102.700015 -271.745859)
			(xy 102.707958 -271.798563) (xy 102.708456 -271.825212) (xy 102.707958 -271.851861) (xy 102.936538 -271.851861)
			(xy 102.936538 -271.798563) (xy 102.944481 -271.745859) (xy 102.960191 -271.694929) (xy 102.983317 -271.646908)
			(xy 103.013341 -271.602871) (xy 103.049593 -271.5638) (xy 103.091264 -271.530569) (xy 103.137422 -271.50392)
			(xy 103.187036 -271.484448) (xy 103.238998 -271.472588) (xy 103.292148 -271.468605) (xy 103.345298 -271.472588)
			(xy 103.39726 -271.484448) (xy 103.446874 -271.50392) (xy 103.493032 -271.530569) (xy 103.534703 -271.5638)
			(xy 103.570955 -271.602871) (xy 103.600979 -271.646908) (xy 103.624105 -271.694929) (xy 103.639815 -271.745859)
			(xy 103.647758 -271.798563) (xy 103.648256 -271.825212) (xy 103.647758 -271.851861) (xy 103.876338 -271.851861)
			(xy 103.876338 -271.798563) (xy 103.884281 -271.745859) (xy 103.899991 -271.694929) (xy 103.923117 -271.646908)
			(xy 103.953141 -271.602871) (xy 103.989393 -271.5638) (xy 104.031064 -271.530569) (xy 104.077222 -271.50392)
			(xy 104.126836 -271.484448) (xy 104.178798 -271.472588) (xy 104.231948 -271.468605) (xy 104.285098 -271.472588)
			(xy 104.33706 -271.484448) (xy 104.386674 -271.50392) (xy 104.432832 -271.530569) (xy 104.474503 -271.5638)
			(xy 104.510755 -271.602871) (xy 104.540779 -271.646908) (xy 104.563905 -271.694929) (xy 104.579615 -271.745859)
			(xy 104.587558 -271.798563) (xy 104.588056 -271.825212) (xy 104.587558 -271.851861) (xy 104.816138 -271.851861)
			(xy 104.816138 -271.798563) (xy 104.824081 -271.745859) (xy 104.839791 -271.694929) (xy 104.862917 -271.646908)
			(xy 104.892941 -271.602871) (xy 104.929193 -271.5638) (xy 104.970864 -271.530569) (xy 105.017022 -271.50392)
			(xy 105.066636 -271.484448) (xy 105.118598 -271.472588) (xy 105.171748 -271.468605) (xy 105.224898 -271.472588)
			(xy 105.27686 -271.484448) (xy 105.326474 -271.50392) (xy 105.372632 -271.530569) (xy 105.414303 -271.5638)
			(xy 105.450555 -271.602871) (xy 105.480579 -271.646908) (xy 105.503705 -271.694929) (xy 105.519415 -271.745859)
			(xy 105.527358 -271.798563) (xy 105.527856 -271.825212) (xy 105.527358 -271.851861) (xy 105.755938 -271.851861)
			(xy 105.755938 -271.798563) (xy 105.763881 -271.745859) (xy 105.779591 -271.694929) (xy 105.802717 -271.646908)
			(xy 105.832741 -271.602871) (xy 105.868993 -271.5638) (xy 105.910664 -271.530569) (xy 105.956822 -271.50392)
			(xy 106.006436 -271.484448) (xy 106.058398 -271.472588) (xy 106.111548 -271.468605) (xy 106.164698 -271.472588)
			(xy 106.21666 -271.484448) (xy 106.266274 -271.50392) (xy 106.312432 -271.530569) (xy 106.354103 -271.5638)
			(xy 106.390355 -271.602871) (xy 106.420379 -271.646908) (xy 106.443505 -271.694929) (xy 106.459215 -271.745859)
			(xy 106.467158 -271.798563) (xy 106.467656 -271.825212) (xy 106.467158 -271.851861) (xy 106.695738 -271.851861)
			(xy 106.695738 -271.798563) (xy 106.703681 -271.745859) (xy 106.719391 -271.694929) (xy 106.742517 -271.646908)
			(xy 106.772541 -271.602871) (xy 106.808793 -271.5638) (xy 106.850464 -271.530569) (xy 106.896622 -271.50392)
			(xy 106.946236 -271.484448) (xy 106.998198 -271.472588) (xy 107.051348 -271.468605) (xy 107.104498 -271.472588)
			(xy 107.15646 -271.484448) (xy 107.206074 -271.50392) (xy 107.252232 -271.530569) (xy 107.293903 -271.5638)
			(xy 107.330155 -271.602871) (xy 107.360179 -271.646908) (xy 107.383305 -271.694929) (xy 107.399015 -271.745859)
			(xy 107.406958 -271.798563) (xy 107.407456 -271.825212) (xy 107.406958 -271.851861) (xy 107.635538 -271.851861)
			(xy 107.635538 -271.798563) (xy 107.643481 -271.745859) (xy 107.659191 -271.694929) (xy 107.682317 -271.646908)
			(xy 107.712341 -271.602871) (xy 107.748593 -271.5638) (xy 107.790264 -271.530569) (xy 107.836422 -271.50392)
			(xy 107.886036 -271.484448) (xy 107.937998 -271.472588) (xy 107.991148 -271.468605) (xy 108.044298 -271.472588)
			(xy 108.09626 -271.484448) (xy 108.145874 -271.50392) (xy 108.192032 -271.530569) (xy 108.233703 -271.5638)
			(xy 108.269955 -271.602871) (xy 108.299979 -271.646908) (xy 108.323105 -271.694929) (xy 108.338815 -271.745859)
			(xy 108.346758 -271.798563) (xy 108.347256 -271.825212) (xy 108.346758 -271.851861) (xy 108.338815 -271.904565)
			(xy 108.323105 -271.955495) (xy 108.299979 -272.003516) (xy 108.269955 -272.047553) (xy 108.233703 -272.086624)
			(xy 108.192032 -272.119855) (xy 108.145874 -272.146504) (xy 108.09626 -272.165976) (xy 108.044298 -272.177836)
			(xy 107.991148 -272.18182) (xy 107.937998 -272.177836) (xy 107.886036 -272.165976) (xy 107.836422 -272.146504)
			(xy 107.790264 -272.119855) (xy 107.748593 -272.086624) (xy 107.712341 -272.047553) (xy 107.682317 -272.003516)
			(xy 107.659191 -271.955495) (xy 107.643481 -271.904565) (xy 107.635538 -271.851861) (xy 107.406958 -271.851861)
			(xy 107.399015 -271.904565) (xy 107.383305 -271.955495) (xy 107.360179 -272.003516) (xy 107.330155 -272.047553)
			(xy 107.293903 -272.086624) (xy 107.252232 -272.119855) (xy 107.206074 -272.146504) (xy 107.15646 -272.165976)
			(xy 107.104498 -272.177836) (xy 107.051348 -272.18182) (xy 106.998198 -272.177836) (xy 106.946236 -272.165976)
			(xy 106.896622 -272.146504) (xy 106.850464 -272.119855) (xy 106.808793 -272.086624) (xy 106.772541 -272.047553)
			(xy 106.742517 -272.003516) (xy 106.719391 -271.955495) (xy 106.703681 -271.904565) (xy 106.695738 -271.851861)
			(xy 106.467158 -271.851861) (xy 106.459215 -271.904565) (xy 106.443505 -271.955495) (xy 106.420379 -272.003516)
			(xy 106.390355 -272.047553) (xy 106.354103 -272.086624) (xy 106.312432 -272.119855) (xy 106.266274 -272.146504)
			(xy 106.21666 -272.165976) (xy 106.164698 -272.177836) (xy 106.111548 -272.18182) (xy 106.058398 -272.177836)
			(xy 106.006436 -272.165976) (xy 105.956822 -272.146504) (xy 105.910664 -272.119855) (xy 105.868993 -272.086624)
			(xy 105.832741 -272.047553) (xy 105.802717 -272.003516) (xy 105.779591 -271.955495) (xy 105.763881 -271.904565)
			(xy 105.755938 -271.851861) (xy 105.527358 -271.851861) (xy 105.519415 -271.904565) (xy 105.503705 -271.955495)
			(xy 105.480579 -272.003516) (xy 105.450555 -272.047553) (xy 105.414303 -272.086624) (xy 105.372632 -272.119855)
			(xy 105.326474 -272.146504) (xy 105.27686 -272.165976) (xy 105.224898 -272.177836) (xy 105.171748 -272.18182)
			(xy 105.118598 -272.177836) (xy 105.066636 -272.165976) (xy 105.017022 -272.146504) (xy 104.970864 -272.119855)
			(xy 104.929193 -272.086624) (xy 104.892941 -272.047553) (xy 104.862917 -272.003516) (xy 104.839791 -271.955495)
			(xy 104.824081 -271.904565) (xy 104.816138 -271.851861) (xy 104.587558 -271.851861) (xy 104.579615 -271.904565)
			(xy 104.563905 -271.955495) (xy 104.540779 -272.003516) (xy 104.510755 -272.047553) (xy 104.474503 -272.086624)
			(xy 104.432832 -272.119855) (xy 104.386674 -272.146504) (xy 104.33706 -272.165976) (xy 104.285098 -272.177836)
			(xy 104.231948 -272.18182) (xy 104.178798 -272.177836) (xy 104.126836 -272.165976) (xy 104.077222 -272.146504)
			(xy 104.031064 -272.119855) (xy 103.989393 -272.086624) (xy 103.953141 -272.047553) (xy 103.923117 -272.003516)
			(xy 103.899991 -271.955495) (xy 103.884281 -271.904565) (xy 103.876338 -271.851861) (xy 103.647758 -271.851861)
			(xy 103.639815 -271.904565) (xy 103.624105 -271.955495) (xy 103.600979 -272.003516) (xy 103.570955 -272.047553)
			(xy 103.534703 -272.086624) (xy 103.493032 -272.119855) (xy 103.446874 -272.146504) (xy 103.39726 -272.165976)
			(xy 103.345298 -272.177836) (xy 103.292148 -272.18182) (xy 103.238998 -272.177836) (xy 103.187036 -272.165976)
			(xy 103.137422 -272.146504) (xy 103.091264 -272.119855) (xy 103.049593 -272.086624) (xy 103.013341 -272.047553)
			(xy 102.983317 -272.003516) (xy 102.960191 -271.955495) (xy 102.944481 -271.904565) (xy 102.936538 -271.851861)
			(xy 102.707958 -271.851861) (xy 102.700015 -271.904565) (xy 102.684305 -271.955495) (xy 102.661179 -272.003516)
			(xy 102.631155 -272.047553) (xy 102.594903 -272.086624) (xy 102.553232 -272.119855) (xy 102.507074 -272.146504)
			(xy 102.45746 -272.165976) (xy 102.405498 -272.177836) (xy 102.352348 -272.18182) (xy 102.299198 -272.177836)
			(xy 102.247236 -272.165976) (xy 102.197622 -272.146504) (xy 102.151464 -272.119855) (xy 102.109793 -272.086624)
			(xy 102.073541 -272.047553) (xy 102.043517 -272.003516) (xy 102.020391 -271.955495) (xy 102.004681 -271.904565)
			(xy 101.996738 -271.851861) (xy 101.768158 -271.851861) (xy 101.760215 -271.904565) (xy 101.744505 -271.955495)
			(xy 101.721379 -272.003516) (xy 101.691355 -272.047553) (xy 101.655103 -272.086624) (xy 101.613432 -272.119855)
			(xy 101.567274 -272.146504) (xy 101.51766 -272.165976) (xy 101.465698 -272.177836) (xy 101.412548 -272.18182)
			(xy 101.359398 -272.177836) (xy 101.307436 -272.165976) (xy 101.257822 -272.146504) (xy 101.211664 -272.119855)
			(xy 101.169993 -272.086624) (xy 101.133741 -272.047553) (xy 101.103717 -272.003516) (xy 101.080591 -271.955495)
			(xy 101.064881 -271.904565) (xy 101.056938 -271.851861) (xy 100.828358 -271.851861) (xy 100.820415 -271.904565)
			(xy 100.804705 -271.955495) (xy 100.781579 -272.003516) (xy 100.751555 -272.047553) (xy 100.715303 -272.086624)
			(xy 100.673632 -272.119855) (xy 100.627474 -272.146504) (xy 100.57786 -272.165976) (xy 100.525898 -272.177836)
			(xy 100.472748 -272.18182) (xy 100.419598 -272.177836) (xy 100.367636 -272.165976) (xy 100.318022 -272.146504)
			(xy 100.271864 -272.119855) (xy 100.230193 -272.086624) (xy 100.193941 -272.047553) (xy 100.163917 -272.003516)
			(xy 100.140791 -271.955495) (xy 100.125081 -271.904565) (xy 100.117138 -271.851861) (xy 99.888558 -271.851861)
			(xy 99.880615 -271.904565) (xy 99.864905 -271.955495) (xy 99.841779 -272.003516) (xy 99.811755 -272.047553)
			(xy 99.775503 -272.086624) (xy 99.733832 -272.119855) (xy 99.687674 -272.146504) (xy 99.63806 -272.165976)
			(xy 99.586098 -272.177836) (xy 99.532948 -272.18182) (xy 99.479798 -272.177836) (xy 99.427836 -272.165976)
			(xy 99.378222 -272.146504) (xy 99.332064 -272.119855) (xy 99.290393 -272.086624) (xy 99.254141 -272.047553)
			(xy 99.224117 -272.003516) (xy 99.200991 -271.955495) (xy 99.185281 -271.904565) (xy 99.177338 -271.851861)
			(xy 98.948758 -271.851861) (xy 98.940815 -271.904565) (xy 98.925105 -271.955495) (xy 98.901979 -272.003516)
			(xy 98.871955 -272.047553) (xy 98.835703 -272.086624) (xy 98.794032 -272.119855) (xy 98.747874 -272.146504)
			(xy 98.69826 -272.165976) (xy 98.646298 -272.177836) (xy 98.593148 -272.18182) (xy 98.539998 -272.177836)
			(xy 98.488036 -272.165976) (xy 98.438422 -272.146504) (xy 98.392264 -272.119855) (xy 98.350593 -272.086624)
			(xy 98.314341 -272.047553) (xy 98.284317 -272.003516) (xy 98.261191 -271.955495) (xy 98.245481 -271.904565)
			(xy 98.237538 -271.851861) (xy 98.008704 -271.851861) (xy 98.000761 -271.904565) (xy 97.985051 -271.955495)
			(xy 97.961925 -272.003516) (xy 97.931901 -272.047553) (xy 97.895649 -272.086624) (xy 97.853978 -272.119855)
			(xy 97.80782 -272.146504) (xy 97.758206 -272.165976) (xy 97.706244 -272.177836) (xy 97.653094 -272.18182)
			(xy 97.599944 -272.177836) (xy 97.547982 -272.165976) (xy 97.498368 -272.146504) (xy 97.45221 -272.119855)
			(xy 97.410539 -272.086624) (xy 97.374287 -272.047553) (xy 97.344263 -272.003516) (xy 97.321137 -271.955495)
			(xy 97.305427 -271.904565) (xy 97.297484 -271.851861) (xy 97.069158 -271.851861) (xy 97.061215 -271.904565)
			(xy 97.045505 -271.955495) (xy 97.022379 -272.003516) (xy 96.992355 -272.047553) (xy 96.956103 -272.086624)
			(xy 96.914432 -272.119855) (xy 96.868274 -272.146504) (xy 96.81866 -272.165976) (xy 96.766698 -272.177836)
			(xy 96.713548 -272.18182) (xy 96.660398 -272.177836) (xy 96.608436 -272.165976) (xy 96.558822 -272.146504)
			(xy 96.512664 -272.119855) (xy 96.470993 -272.086624) (xy 96.434741 -272.047553) (xy 96.404717 -272.003516)
			(xy 96.381591 -271.955495) (xy 96.365881 -271.904565) (xy 96.357938 -271.851861) (xy 96.129358 -271.851861)
			(xy 96.121415 -271.904565) (xy 96.105705 -271.955495) (xy 96.082579 -272.003516) (xy 96.052555 -272.047553)
			(xy 96.016303 -272.086624) (xy 95.974632 -272.119855) (xy 95.928474 -272.146504) (xy 95.87886 -272.165976)
			(xy 95.826898 -272.177836) (xy 95.773748 -272.18182) (xy 95.720598 -272.177836) (xy 95.668636 -272.165976)
			(xy 95.619022 -272.146504) (xy 95.572864 -272.119855) (xy 95.531193 -272.086624) (xy 95.494941 -272.047553)
			(xy 95.464917 -272.003516) (xy 95.441791 -271.955495) (xy 95.426081 -271.904565) (xy 95.418138 -271.851861)
			(xy 95.189558 -271.851861) (xy 95.181615 -271.904565) (xy 95.165905 -271.955495) (xy 95.142779 -272.003516)
			(xy 95.112755 -272.047553) (xy 95.076503 -272.086624) (xy 95.034832 -272.119855) (xy 94.988674 -272.146504)
			(xy 94.93906 -272.165976) (xy 94.887098 -272.177836) (xy 94.833948 -272.18182) (xy 94.780798 -272.177836)
			(xy 94.728836 -272.165976) (xy 94.679222 -272.146504) (xy 94.633064 -272.119855) (xy 94.591393 -272.086624)
			(xy 94.555141 -272.047553) (xy 94.525117 -272.003516) (xy 94.501991 -271.955495) (xy 94.486281 -271.904565)
			(xy 94.478338 -271.851861) (xy 94.249758 -271.851861) (xy 94.241815 -271.904565) (xy 94.226105 -271.955495)
			(xy 94.202979 -272.003516) (xy 94.172955 -272.047553) (xy 94.136703 -272.086624) (xy 94.095032 -272.119855)
			(xy 94.048874 -272.146504) (xy 93.99926 -272.165976) (xy 93.947298 -272.177836) (xy 93.894148 -272.18182)
			(xy 93.840998 -272.177836) (xy 93.789036 -272.165976) (xy 93.739422 -272.146504) (xy 93.693264 -272.119855)
			(xy 93.651593 -272.086624) (xy 93.615341 -272.047553) (xy 93.585317 -272.003516) (xy 93.562191 -271.955495)
			(xy 93.546481 -271.904565) (xy 93.538538 -271.851861) (xy 93.309958 -271.851861) (xy 93.302015 -271.904565)
			(xy 93.286305 -271.955495) (xy 93.263179 -272.003516) (xy 93.233155 -272.047553) (xy 93.196903 -272.086624)
			(xy 93.155232 -272.119855) (xy 93.109074 -272.146504) (xy 93.05946 -272.165976) (xy 93.007498 -272.177836)
			(xy 92.954348 -272.18182) (xy 92.901198 -272.177836) (xy 92.849236 -272.165976) (xy 92.799622 -272.146504)
			(xy 92.753464 -272.119855) (xy 92.711793 -272.086624) (xy 92.675541 -272.047553) (xy 92.645517 -272.003516)
			(xy 92.622391 -271.955495) (xy 92.606681 -271.904565) (xy 92.598738 -271.851861) (xy 92.370158 -271.851861)
			(xy 92.362215 -271.904565) (xy 92.346505 -271.955495) (xy 92.323379 -272.003516) (xy 92.293355 -272.047553)
			(xy 92.257103 -272.086624) (xy 92.215432 -272.119855) (xy 92.169274 -272.146504) (xy 92.11966 -272.165976)
			(xy 92.067698 -272.177836) (xy 92.014548 -272.18182) (xy 91.961398 -272.177836) (xy 91.909436 -272.165976)
			(xy 91.859822 -272.146504) (xy 91.813664 -272.119855) (xy 91.771993 -272.086624) (xy 91.735741 -272.047553)
			(xy 91.705717 -272.003516) (xy 91.682591 -271.955495) (xy 91.666881 -271.904565) (xy 91.658938 -271.851861)
			(xy 91.430104 -271.851861) (xy 91.422161 -271.904565) (xy 91.406451 -271.955495) (xy 91.383325 -272.003516)
			(xy 91.353301 -272.047553) (xy 91.317049 -272.086624) (xy 91.275378 -272.119855) (xy 91.22922 -272.146504)
			(xy 91.179606 -272.165976) (xy 91.127644 -272.177836) (xy 91.074494 -272.18182) (xy 91.021344 -272.177836)
			(xy 90.969382 -272.165976) (xy 90.919768 -272.146504) (xy 90.87361 -272.119855) (xy 90.831939 -272.086624)
			(xy 90.795687 -272.047553) (xy 90.765663 -272.003516) (xy 90.742537 -271.955495) (xy 90.726827 -271.904565)
			(xy 90.718884 -271.851861) (xy 90.490304 -271.851861) (xy 90.482361 -271.904565) (xy 90.466651 -271.955495)
			(xy 90.443525 -272.003516) (xy 90.413501 -272.047553) (xy 90.377249 -272.086624) (xy 90.335578 -272.119855)
			(xy 90.28942 -272.146504) (xy 90.239806 -272.165976) (xy 90.187844 -272.177836) (xy 90.134694 -272.18182)
			(xy 90.081544 -272.177836) (xy 90.029582 -272.165976) (xy 89.979968 -272.146504) (xy 89.93381 -272.119855)
			(xy 89.892139 -272.086624) (xy 89.855887 -272.047553) (xy 89.825863 -272.003516) (xy 89.802737 -271.955495)
			(xy 89.787027 -271.904565) (xy 89.779084 -271.851861) (xy 89.550654 -271.851861) (xy 89.54351 -271.901292)
			(xy 89.529054 -271.950273) (xy 89.507741 -271.996684) (xy 89.480012 -272.03957) (xy 89.446435 -272.07805)
			(xy 89.4077 -272.111333) (xy 89.38641 -272.12544) (xy 89.373939 -272.134076) (xy 89.354311 -272.157182)
			(xy 89.342321 -272.185028) (xy 89.339023 -272.215166) (xy 89.344706 -272.244946) (xy 89.35887 -272.271751)
			(xy 89.369138 -272.28292) (xy 89.44356 -272.357342) (xy 89.47785 -272.33626) (xy 89.499018 -272.323696)
			(xy 89.544075 -272.303868) (xy 89.591429 -272.290423) (xy 89.640181 -272.283615) (xy 89.664794 -272.283174)
			(xy 89.692118 -272.283671) (xy 89.746126 -272.292019) (xy 89.798224 -272.308519) (xy 89.84719 -272.332784)
			(xy 89.891874 -272.364245) (xy 89.931228 -272.402162) (xy 89.964327 -272.445647) (xy 89.990395 -272.493677)
			(xy 90.008819 -272.545126) (xy 90.019168 -272.598786) (xy 90.020648 -272.626074) (xy 90.022426 -272.674842)
			(xy 90.247216 -272.674842)
		)
		(stroke
			(width 0)
			(type solid)
		)
		(fill yes)
		(layer "In15.Cu")
		(net "PVCCINFAON_CPU1")
	)
	(gr_line
		(start 19.284188 -396.842996)
		(end 19.578828 -396.548356)
		(stroke
			(width 0.07366)
			(type default)
		)
		(layer "In15.Cu")
	)
	(gr_line
		(start 19.284188 -395.979396)
		(end 19.578828 -396.274036)
		(stroke
			(width 0.07366)
			(type default)
		)
		(layer "In15.Cu")
	)
	(gr_line
		(start 20.261326 -382.893824)
		(end 19.966686 -382.599184)
		(stroke
			(width 0.07366)
			(type default)
		)
		(layer "In15.Cu")
	)
	(gr_line
		(start 20.273518 -382.085342)
		(end 20.444206 -382.085342)
		(stroke
			(width 0.07366)
			(type default)
		)
		(layer "In15.Cu")
	)
	(gr_line
		(start 20.444206 -382.085342)
		(end 20.749768 -381.77978)
		(stroke
			(width 0.07366)
			(type default)
		)
		(layer "In15.Cu")
	)
	(gr_line
		(start 20.749768 -381.77978)
		(end 20.749768 -381.609092)
		(stroke
			(width 0.07366)
			(type default)
		)
		(layer "In15.Cu")
	)
	(gr_line
		(start 21.488146 -381.04699)
		(end 21.608796 -381.16764)
		(stroke
			(width 0.07366)
			(type default)
		)
		(layer "In15.Cu")
	)
	(gr_line
		(start 21.608796 -381.16764)
		(end 22.040596 -381.16764)
		(stroke
			(width 0.07366)
			(type default)
		)
		(layer "In15.Cu")
	)
	(gr_line
		(start 22.040596 -381.16764)
		(end 22.161246 -381.04699)
		(stroke
			(width 0.07366)
			(type default)
		)
		(layer "In15.Cu")
	)
	(gr_line
		(start 26.828496 -381.240538)
		(end 26.923238 -381.382778)
		(stroke
			(width 0.07366)
			(type default)
		)
		(layer "In15.Cu")
	)
	(gr_line
		(start 26.923238 -381.382778)
		(end 27.34691 -381.466852)
		(stroke
			(width 0.07366)
			(type default)
		)
		(layer "In15.Cu")
	)
	(gr_line
		(start 27.34691 -381.466852)
		(end 27.48915 -381.371856)
		(stroke
			(width 0.07366)
			(type default)
		)
		(layer "In15.Cu")
	)
	(gr_line
		(start 27.912314 -381.454914)
		(end 27.913838 -381.455168)
		(stroke
			(width 0.07366)
			(type default)
		)
		(layer "In15.Cu")
	)
	(gr_line
		(start 27.914092 -381.455422)
		(end 27.913838 -381.455168)
		(stroke
			(width 0.07366)
			(type default)
		)
		(layer "In15.Cu")
	)
	(gr_line
		(start 28.0289 -401.36318)
		(end 28.70454 -401.36318)
		(stroke
			(width 0.07366)
			(type default)
		)
		(layer "In15.Cu")
	)
	(gr_line
		(start 28.03017 -401.63877)
		(end 28.15082 -401.75942)
		(stroke
			(width 0.07366)
			(type default)
		)
		(layer "In15.Cu")
	)
	(gr_line
		(start 28.15082 -401.75942)
		(end 28.58262 -401.75942)
		(stroke
			(width 0.07366)
			(type default)
		)
		(layer "In15.Cu")
	)
	(gr_line
		(start 28.338526 -381.54102)
		(end 28.433268 -381.68326)
		(stroke
			(width 0.07366)
			(type default)
		)
		(layer "In15.Cu")
	)
	(gr_line
		(start 28.433268 -381.68326)
		(end 28.85694 -381.767334)
		(stroke
			(width 0.07366)
			(type default)
		)
		(layer "In15.Cu")
	)
	(gr_line
		(start 28.58262 -401.75942)
		(end 28.70327 -401.63877)
		(stroke
			(width 0.07366)
			(type default)
		)
		(layer "In15.Cu")
	)
	(gr_line
		(start 28.85694 -381.767334)
		(end 28.99918 -381.672338)
		(stroke
			(width 0.07366)
			(type default)
		)
		(layer "In15.Cu")
	)
	(gr_line
		(start 29.13634 -401.36318)
		(end 29.81198 -401.36318)
		(stroke
			(width 0.07366)
			(type default)
		)
		(layer "In15.Cu")
	)
	(gr_line
		(start 29.13761 -401.63877)
		(end 29.25826 -401.75942)
		(stroke
			(width 0.07366)
			(type default)
		)
		(layer "In15.Cu")
	)
	(gr_line
		(start 29.25826 -401.75942)
		(end 29.69006 -401.75942)
		(stroke
			(width 0.07366)
			(type default)
		)
		(layer "In15.Cu")
	)
	(gr_line
		(start 29.424884 -381.75692)
		(end 29.519626 -381.899414)
		(stroke
			(width 0.07366)
			(type default)
		)
		(layer "In15.Cu")
	)
	(gr_line
		(start 29.519626 -381.899414)
		(end 29.943298 -381.983488)
		(stroke
			(width 0.07366)
			(type default)
		)
		(layer "In15.Cu")
	)
	(gr_line
		(start 29.69006 -401.75942)
		(end 29.81071 -401.63877)
		(stroke
			(width 0.07366)
			(type default)
		)
		(layer "In15.Cu")
	)
	(gr_line
		(start 29.943298 -381.983488)
		(end 30.085538 -381.888492)
		(stroke
			(width 0.07366)
			(type default)
		)
		(layer "In15.Cu")
	)
	(gr_line
		(start 30.401768 -401.36318)
		(end 31.077408 -401.36318)
		(stroke
			(width 0.07366)
			(type default)
		)
		(layer "In15.Cu")
	)
	(gr_line
		(start 30.403038 -401.63877)
		(end 30.523688 -401.75942)
		(stroke
			(width 0.07366)
			(type default)
		)
		(layer "In15.Cu")
	)
	(gr_line
		(start 30.523688 -401.75942)
		(end 30.955488 -401.75942)
		(stroke
			(width 0.07366)
			(type default)
		)
		(layer "In15.Cu")
	)
	(gr_line
		(start 30.682438 -382.00711)
		(end 30.77718 -382.149604)
		(stroke
			(width 0.07366)
			(type default)
		)
		(layer "In15.Cu")
	)
	(gr_line
		(start 30.77718 -382.149604)
		(end 31.201106 -382.233678)
		(stroke
			(width 0.07366)
			(type default)
		)
		(layer "In15.Cu")
	)
	(gr_line
		(start 30.955488 -401.75942)
		(end 31.076138 -401.63877)
		(stroke
			(width 0.07366)
			(type default)
		)
		(layer "In15.Cu")
	)
	(gr_line
		(start 31.201106 -382.233678)
		(end 31.343346 -382.138682)
		(stroke
			(width 0.07366)
			(type default)
		)
		(layer "In15.Cu")
	)
	(gr_line
		(start 31.509208 -401.36318)
		(end 32.184848 -401.36318)
		(stroke
			(width 0.07366)
			(type default)
		)
		(layer "In15.Cu")
	)
	(gr_line
		(start 31.510478 -401.63877)
		(end 31.631128 -401.75942)
		(stroke
			(width 0.07366)
			(type default)
		)
		(layer "In15.Cu")
	)
	(gr_line
		(start 31.631128 -401.75942)
		(end 32.062928 -401.75942)
		(stroke
			(width 0.07366)
			(type default)
		)
		(layer "In15.Cu")
	)
	(gr_line
		(start 31.768542 -382.223264)
		(end 31.863538 -382.365758)
		(stroke
			(width 0.07366)
			(type default)
		)
		(layer "In15.Cu")
	)
	(gr_line
		(start 31.863538 -382.365758)
		(end 32.28721 -382.449832)
		(stroke
			(width 0.07366)
			(type default)
		)
		(layer "In15.Cu")
	)
	(gr_line
		(start 32.062928 -401.75942)
		(end 32.183578 -401.63877)
		(stroke
			(width 0.07366)
			(type default)
		)
		(layer "In15.Cu")
	)
	(gr_line
		(start 32.28721 -382.449832)
		(end 32.429704 -382.354836)
		(stroke
			(width 0.07366)
			(type default)
		)
		(layer "In15.Cu")
	)
	(gr_line
		(start 32.616648 -401.36318)
		(end 32.681926 -401.36318)
		(stroke
			(width 0.07366)
			(type default)
		)
		(layer "In15.Cu")
	)
	(gr_line
		(start 32.681926 -401.36318)
		(end 32.686244 -401.367498)
		(stroke
			(width 0.07366)
			(type default)
		)
		(layer "In15.Cu")
	)
	(gr_line
		(start 32.686244 -401.367498)
		(end 32.731456 -401.388326)
		(stroke
			(width 0.07366)
			(type default)
		)
		(layer "In15.Cu")
	)
	(gr_line
		(start 33.086294 -382.485392)
		(end 33.181544 -382.627886)
		(stroke
			(width 0.07366)
			(type default)
		)
		(layer "In15.Cu")
	)
	(gr_line
		(start 33.181544 -382.627886)
		(end 33.605216 -382.71196)
		(stroke
			(width 0.07366)
			(type default)
		)
		(layer "In15.Cu")
	)
	(gr_line
		(start 33.605216 -382.71196)
		(end 33.747456 -382.616964)
		(stroke
			(width 0.07366)
			(type default)
		)
		(layer "In15.Cu")
	)
	(gr_line
		(start 33.632902 -402.106892)
		(end 33.70326 -402.297646)
		(stroke
			(width 0.07366)
			(type default)
		)
		(layer "In15.Cu")
	)
	(gr_line
		(start 33.70326 -402.297646)
		(end 34.038032 -402.45157)
		(stroke
			(width 0.07366)
			(type default)
		)
		(layer "In15.Cu")
	)
	(gr_line
		(start 33.747202 -401.85594)
		(end 34.344864 -402.131276)
		(stroke
			(width 0.07366)
			(type default)
		)
		(layer "In15.Cu")
	)
	(gr_line
		(start 34.038032 -402.45157)
		(end 34.228786 -402.381212)
		(stroke
			(width 0.07366)
			(type default)
		)
		(layer "In15.Cu")
	)
	(gr_line
		(start 34.172652 -382.701546)
		(end 34.267648 -382.84404)
		(stroke
			(width 0.07366)
			(type default)
		)
		(layer "In15.Cu")
	)
	(gr_line
		(start 34.267648 -382.84404)
		(end 34.69132 -382.928114)
		(stroke
			(width 0.07366)
			(type default)
		)
		(layer "In15.Cu")
	)
	(gr_line
		(start 34.628074 -402.565108)
		(end 34.698432 -402.755862)
		(stroke
			(width 0.07366)
			(type default)
		)
		(layer "In15.Cu")
	)
	(gr_line
		(start 34.69132 -382.928114)
		(end 34.833814 -382.833118)
		(stroke
			(width 0.07366)
			(type default)
		)
		(layer "In15.Cu")
	)
	(gr_line
		(start 34.698432 -402.755862)
		(end 35.033204 -402.91004)
		(stroke
			(width 0.07366)
			(type default)
		)
		(layer "In15.Cu")
	)
	(gr_line
		(start 34.742374 -402.314156)
		(end 35.340036 -402.589492)
		(stroke
			(width 0.07366)
			(type default)
		)
		(layer "In15.Cu")
	)
	(gr_line
		(start 35.033204 -402.91004)
		(end 35.223958 -402.839428)
		(stroke
			(width 0.07366)
			(type default)
		)
		(layer "In15.Cu")
	)
	(gr_line
		(start 35.7759 -403.092412)
		(end 35.776154 -403.093174)
		(stroke
			(width 0.07366)
			(type default)
		)
		(layer "In15.Cu")
	)
	(gr_line
		(start 35.883342 -403.14245)
		(end 35.884104 -403.142704)
		(stroke
			(width 0.07366)
			(type default)
		)
		(layer "In15.Cu")
	)
	(gr_line
		(start 35.890708 -402.842984)
		(end 35.89147 -402.843238)
		(stroke
			(width 0.07366)
			(type default)
		)
		(layer "In15.Cu")
	)
	(gr_line
		(start 42.13098 -385.280916)
		(end 41.83634 -385.575556)
		(stroke
			(width 0.07366)
			(type default)
		)
		(layer "In15.Cu")
	)
	(gr_line
		(start 45.581062 -407.364438)
		(end 47.258986 -408.059636)
		(stroke
			(width 0.07366)
			(type default)
		)
		(layer "In15.Cu")
	)
	(gr_line
		(start 45.68571 -407.110946)
		(end 47.363888 -407.806144)
		(stroke
			(width 0.07366)
			(type default)
		)
		(layer "In15.Cu")
	)
	(gr_line
		(start 47.258986 -408.059636)
		(end 47.857664 -408.30754)
		(stroke
			(width 0.07366)
			(type default)
		)
		(layer "In15.Cu")
	)
	(gr_line
		(start 47.365666 -407.805382)
		(end 47.546514 -407.730452)
		(stroke
			(width 0.07366)
			(type default)
		)
		(layer "In15.Cu")
	)
	(gr_line
		(start 47.546514 -407.730452)
		(end 47.887128 -407.871422)
		(stroke
			(width 0.07366)
			(type default)
		)
		(layer "In15.Cu")
	)
	(gr_line
		(start 47.887128 -407.871422)
		(end 47.961804 -408.052524)
		(stroke
			(width 0.07366)
			(type default)
		)
		(layer "In15.Cu")
	)
	(gr_line
		(start 68.490592 -415.764472)
		(end 68.751196 -416.025076)
		(stroke
			(width 0.07366)
			(type default)
		)
		(layer "In15.Cu")
	)
	(gr_line
		(start 68.490592 -415.568384)
		(end 68.490592 -415.764472)
		(stroke
			(width 0.07366)
			(type default)
		)
		(layer "In15.Cu")
	)
	(gr_line
		(start 68.650104 -421.089836)
		(end 68.650104 -421.089582)
		(stroke
			(width 0.07366)
			(type default)
		)
		(layer "In15.Cu")
	)
	(gr_line
		(start 68.684648 -415.372804)
		(end 69.142864 -415.83102)
		(stroke
			(width 0.07366)
			(type default)
		)
		(layer "In15.Cu")
	)
	(gr_line
		(start 68.751196 -416.025076)
		(end 68.947284 -416.025076)
		(stroke
			(width 0.07366)
			(type default)
		)
		(layer "In15.Cu")
	)
	(gr_line
		(start 69.063362 -420.303198)
		(end 68.650104 -419.88994)
		(stroke
			(width 0.07366)
			(type default)
		)
		(layer "In15.Cu")
	)
	(gr_line
		(start 69.112638 -420.627048)
		(end 68.650104 -421.089582)
		(stroke
			(width 0.07366)
			(type default)
		)
		(layer "In15.Cu")
	)
	(gr_line
		(start 69.369178 -420.303198)
		(end 69.063362 -420.303198)
		(stroke
			(width 0.07366)
			(type default)
		)
		(layer "In15.Cu")
	)
	(gr_line
		(start 69.434964 -420.627048)
		(end 69.112638 -420.627048)
		(stroke
			(width 0.07366)
			(type default)
		)
		(layer "In15.Cu")
	)
	(gr_line
		(start 69.564758 -420.497254)
		(end 69.434964 -420.627048)
		(stroke
			(width 0.07366)
			(type default)
		)
		(layer "In15.Cu")
	)
	(gr_line
		(start 72.650096 -421.089836)
		(end 72.650096 -421.089582)
		(stroke
			(width 0.07366)
			(type default)
		)
		(layer "In15.Cu")
	)
	(gr_line
		(start 73.063354 -420.303198)
		(end 72.650096 -419.88994)
		(stroke
			(width 0.07366)
			(type default)
		)
		(layer "In15.Cu")
	)
	(gr_line
		(start 73.11263 -420.627048)
		(end 72.650096 -421.089582)
		(stroke
			(width 0.07366)
			(type default)
		)
		(layer "In15.Cu")
	)
	(gr_line
		(start 74.909426 -420.303198)
		(end 73.063354 -420.303198)
		(stroke
			(width 0.07366)
			(type default)
		)
		(layer "In15.Cu")
	)
	(gr_line
		(start 74.975212 -420.627048)
		(end 73.11263 -420.627048)
		(stroke
			(width 0.07366)
			(type default)
		)
		(layer "In15.Cu")
	)
	(gr_line
		(start 75.105006 -420.497254)
		(end 74.975212 -420.627048)
		(stroke
			(width 0.07366)
			(type default)
		)
		(layer "In15.Cu")
	)
	(gr_line
		(start 92.21343 -414.630108)
		(end 92.06992 -414.773618)
		(stroke
			(width 0.07366)
			(type default)
		)
		(layer "In15.Cu")
	)
	(gr_line
		(start 92.58173 -414.630108)
		(end 92.21343 -414.630108)
		(stroke
			(width 0.07366)
			(type default)
		)
		(layer "In15.Cu")
	)
	(gr_line
		(start 92.72524 -414.773618)
		(end 92.58173 -414.630108)
		(stroke
			(width 0.07366)
			(type default)
		)
		(layer "In15.Cu")
	)
	(gr_line
		(start 92.72651 -415.049208)
		(end 92.06865 -415.049208)
		(stroke
			(width 0.07366)
			(type default)
		)
		(layer "In15.Cu")
	)
	(gr_line
		(start 94.406466 -413.805878)
		(end 94.406466 -414.009078)
		(stroke
			(width 0.07366)
			(type default)
		)
		(layer "In15.Cu")
	)
	(gr_line
		(start 94.66707 -413.545274)
		(end 94.406466 -413.805878)
		(stroke
			(width 0.07366)
			(type default)
		)
		(layer "In15.Cu")
	)
	(gr_line
		(start 94.87027 -413.545274)
		(end 94.66707 -413.545274)
		(stroke
			(width 0.07366)
			(type default)
		)
		(layer "In15.Cu")
	)
	(gr_line
		(start 95.06585 -413.73933)
		(end 94.600522 -414.204658)
		(stroke
			(width 0.07366)
			(type default)
		)
		(layer "In15.Cu")
	)
	(gr_line
		(start 95.464376 -412.747968)
		(end 95.464376 -412.951168)
		(stroke
			(width 0.07366)
			(type default)
		)
		(layer "In15.Cu")
	)
	(gr_line
		(start 95.72498 -412.487364)
		(end 95.464376 -412.747968)
		(stroke
			(width 0.07366)
			(type default)
		)
		(layer "In15.Cu")
	)
	(gr_line
		(start 95.92818 -412.487364)
		(end 95.72498 -412.487364)
		(stroke
			(width 0.07366)
			(type default)
		)
		(layer "In15.Cu")
	)
	(gr_line
		(start 96.12376 -412.68142)
		(end 95.658432 -413.146748)
		(stroke
			(width 0.07366)
			(type default)
		)
		(layer "In15.Cu")
	)
	(gr_line
		(start 102.25786 -411.213808)
		(end 102.5525 -411.508448)
		(stroke
			(width 0.07366)
			(type default)
		)
		(layer "In15.Cu")
	)
	(gr_line
		(start 103.12146 -411.213808)
		(end 102.82682 -411.508448)
		(stroke
			(width 0.07366)
			(type default)
		)
		(layer "In15.Cu")
	)
	(gr_poly
		(pts
			(arc
				(start 278.10841 -405.924766)
				(mid 278.127045 -405.923069)
				(end 278.145748 -405.92248)
			)
			(xy 280.90622 -405.92248) (xy 281.051508 -405.777192) (xy 281.051508 -397.72844) (xy 280.706068 -397.383)
			(xy 275.6408 -397.383) (xy 275.3868 -397.637) (xy 275.3868 -405.8285) (xy 275.48332 -405.92502) (xy 278.105616 -405.92502)
		)
		(stroke
			(width 0)
			(type solid)
		)
		(fill yes)
		(layer "In16.Cu")
		(net "P12V_MAIN_R_0")
	)
	(gr_poly
		(pts
			(arc
				(start 273.791172 -406.781)
				(mid 273.810393 -406.777119)
				(end 273.826732 -406.766268)
			)
			(xy 274.30476 -406.28824) (xy 274.32 -406.274016) (xy 274.32 -397.635984) (xy 274.30476 -397.62176)
			(xy 274.083018 -397.400018) (xy 274.067016 -397.383) (xy 240.155984 -397.383) (xy 240.14176 -397.39824)
			(xy 239.666018 -397.873982) (xy 239.665764 -397.874236) (xy 239.649 -397.889984) (xy 239.649 -406.528016)
			(xy 239.66424 -406.54224) (xy 239.88776 -406.76576) (xy 239.901984 -406.781)
		)
		(stroke
			(width 0)
			(type solid)
		)
		(fill yes)
		(layer "In16.Cu")
		(net "P12V_MAIN_R")
	)
	(gr_poly
		(pts
			(xy 230.38054 -434.93182)
			(arc
				(start 230.38054 -423.47642)
				(mid 230.404693 -423.354904)
				(end 230.473504 -423.251884)
			)
			(arc
				(start 233.005884 -420.719504)
				(mid 233.108916 -420.650723)
				(end 233.23042 -420.62654)
			)
			(xy 265.212068 -420.62654) (xy 266.0142 -419.824408)
			(arc
				(start 266.0142 -416.65398)
				(mid 266.038353 -416.532464)
				(end 266.107164 -416.429444)
			)
			(arc
				(start 267.001244 -415.535364)
				(mid 267.104276 -415.466583)
				(end 267.22578 -415.4424)
			)
			(xy 279.79624 -415.4424) (xy 280.19756 -415.04108) (xy 280.19756 -408.29992) (xy 279.96896 -408.07132)
			(xy 239.758728 -408.07132)
			(arc
				(start 239.754156 -408.072082)
				(mid 239.726829 -408.075684)
				(end 239.699292 -408.076908)
			)
			(arc
				(start 239.699292 -408.076908)
				(mid 239.555035 -408.042244)
				(end 239.442244 -407.945844)
			)
			(xy 237.61446 -406.11806)
			(arc
				(start 235.520992 -406.11806)
				(mid 235.399476 -406.093907)
				(end 235.296456 -406.025096)
			)
			(arc
				(start 233.973624 -404.702264)
				(mid 233.904843 -404.599232)
				(end 233.88066 -404.477728)
			)
			(xy 233.88066 -401.03298) (xy 233.86542 -401.01774) (xy 230.47706 -401.01774) (xy 230.46182 -401.03298)
			(arc
				(start 230.46182 -404.473156)
				(mid 230.437667 -404.594672)
				(end 230.368856 -404.697692)
			)
			(xy 230.256588 -404.80996)
			(arc
				(start 230.256588 -407.3906)
				(mid 230.232435 -407.512116)
				(end 230.163624 -407.615136)
			)
			(arc
				(start 228.159564 -409.619196)
				(mid 228.056532 -409.687977)
				(end 227.935028 -409.71216)
			)
			(arc
				(start 225.70694 -409.71216)
				(mid 225.585424 -409.688007)
				(end 225.482404 -409.619196)
			)
			(arc
				(start 223.491552 -407.628344)
				(mid 223.422771 -407.525312)
				(end 223.398588 -407.403808)
			)
			(xy 223.398588 -404.79218)
			(arc
				(start 223.310704 -404.704296)
				(mid 223.241923 -404.601264)
				(end 223.21774 -404.47976)
			)
			(xy 223.21774 -401.04568) (xy 223.19234 -401.02028) (xy 219.81414 -401.02028) (xy 219.79636 -401.03806)
			(arc
				(start 219.79636 -404.490936)
				(mid 219.772207 -404.612452)
				(end 219.703396 -404.715472)
			)
			(xy 219.613988 -404.80488)
			(arc
				(start 219.613988 -407.259028)
				(mid 219.589835 -407.380544)
				(end 219.521024 -407.483564)
			)
			(arc
				(start 217.497152 -409.507436)
				(mid 217.39412 -409.576217)
				(end 217.272616 -409.6004)
			)
			(arc
				(start 214.794592 -409.6004)
				(mid 214.673076 -409.576247)
				(end 214.570056 -409.507436)
			)
			(arc
				(start 212.812884 -407.750264)
				(mid 212.744103 -407.647232)
				(end 212.71992 -407.525728)
			)
			(xy 212.71992 -404.79472)
			(arc
				(start 212.635084 -404.709884)
				(mid 212.566303 -404.606852)
				(end 212.54212 -404.485348)
			)
			(xy 212.54212 -401.02536) (xy 212.53704 -401.02028) (xy 209.14106 -401.02028) (xy 209.13598 -401.02536)
			(arc
				(start 209.13598 -404.452836)
				(mid 209.111827 -404.574352)
				(end 209.043016 -404.677372)
			)
			(xy 208.945988 -404.7744)
			(arc
				(start 208.945988 -407.30424)
				(mid 208.921835 -407.425756)
				(end 208.853024 -407.528776)
			)
			(arc
				(start 206.770224 -409.611576)
				(mid 206.667192 -409.680357)
				(end 206.545688 -409.70454)
			)
			(arc
				(start 204.16012 -409.70454)
				(mid 204.038604 -409.680387)
				(end 203.935584 -409.611576)
			)
			(arc
				(start 202.155552 -407.831544)
				(mid 202.086771 -407.728512)
				(end 202.062588 -407.607008)
			)
			(xy 202.062588 -404.779988)
			(arc
				(start 201.969624 -404.687024)
				(mid 201.900843 -404.583992)
				(end 201.87666 -404.462488)
			)
			(xy 201.87666 -401.03298) (xy 201.86396 -401.02028) (xy 198.47306 -401.02028) (xy 198.46798 -401.02536)
			(arc
				(start 198.46798 -404.487888)
				(mid 198.443827 -404.609404)
				(end 198.375016 -404.712424)
			)
			(arc
				(start 197.194424 -405.893016)
				(mid 197.091392 -405.961797)
				(end 196.969888 -405.98598)
			)
			(arc
				(start 190.870332 -405.98598)
				(mid 190.748816 -405.961827)
				(end 190.645796 -405.893016)
			)
			(arc
				(start 189.455552 -404.702518)
				(mid 189.386771 -404.599486)
				(end 189.362588 -404.477982)
			)
			(xy 189.362588 -404.177754) (xy 189.337188 -404.152354)
			(arc
				(start 189.11316 -404.152354)
				(mid 188.991644 -404.128201)
				(end 188.888624 -404.05939)
			)
			(arc
				(start 188.710824 -403.88159)
				(mid 188.642043 -403.778558)
				(end 188.61786 -403.657054)
			)
			(xy 188.61786 -401.02028) (xy 188.600588 -401.002754) (xy 185.196988 -401.002754) (xy 185.196988 -406.489154)
			(arc
				(start 185.434224 -406.72639)
				(mid 185.480227 -406.78458)
				(end 185.51144 -406.851866)
			)
			(arc
				(start 185.51144 -406.851866)
				(mid 185.548193 -406.942536)
				(end 185.560716 -407.039572)
			)
			(arc
				(start 185.560716 -407.039572)
				(mid 185.553298 -407.114694)
				(end 185.531252 -407.186892)
			)
			(xy 185.527188 -407.19629)
			(arc
				(start 185.527188 -408.287982)
				(mid 185.503035 -408.409498)
				(end 185.434224 -408.512518)
			)
			(xy 185.323988 -408.622754) (xy 185.323988 -413.065976) (xy 192.869312 -420.6113)
			(arc
				(start 197.416928 -420.6113)
				(mid 197.538444 -420.635453)
				(end 197.641464 -420.704264)
			)
			(arc
				(start 206.398876 -429.461676)
				(mid 206.467657 -429.564708)
				(end 206.49184 -429.686212)
			)
			(xy 206.49184 -435.39156) (xy 207.63484 -436.53456) (xy 228.7778 -436.53456)
		)
		(stroke
			(width 0)
			(type solid)
		)
		(fill yes)
		(layer "In16.Cu")
		(net "P12V_PSU")
	)
	(gr_poly
		(pts
			(xy 531.7998 -462.520284) (xy 531.855607 -462.519775) (xy 531.96691 -462.511434) (xy 532.077278 -462.494798)
			(xy 532.186094 -462.469962) (xy 532.29275 -462.437062) (xy 532.396649 -462.396285) (xy 532.49721 -462.347857)
			(xy 532.593871 -462.292049) (xy 532.686092 -462.229174) (xy 532.773355 -462.159583) (xy 532.855174 -462.083666)
			(xy 532.931091 -462.001846) (xy 533.000681 -461.914582) (xy 533.063556 -461.822361) (xy 533.119362 -461.7257)
			(xy 533.16779 -461.625138) (xy 533.208566 -461.521239) (xy 533.241465 -461.414583) (xy 533.266301 -461.305766)
			(xy 533.282935 -461.195398) (xy 533.291275 -461.084095) (xy 533.291796 -461.028288) (xy 533.291796 -455.0283)
			(xy 533.291274 -454.972493) (xy 533.282933 -454.861191) (xy 533.266298 -454.750824) (xy 533.241462 -454.642008)
			(xy 533.208563 -454.535353) (xy 533.167786 -454.431454) (xy 533.119358 -454.330893) (xy 533.063551 -454.234233)
			(xy 533.000677 -454.142013) (xy 532.931086 -454.054749) (xy 532.85517 -453.97293) (xy 532.773351 -453.897014)
			(xy 532.686087 -453.827423) (xy 532.593867 -453.764549) (xy 532.497207 -453.708742) (xy 532.396646 -453.660314)
			(xy 532.292747 -453.619537) (xy 532.186092 -453.586638) (xy 532.077276 -453.561802) (xy 531.966909 -453.545167)
			(xy 531.855607 -453.536826) (xy 531.7998 -453.536304) (xy 516.019796 -453.536304) (xy 515.949442 -453.535811)
			(xy 515.808956 -453.527921) (xy 515.669133 -453.512166) (xy 515.530414 -453.488597) (xy 515.393234 -453.457286)
			(xy 515.258026 -453.418334) (xy 515.125215 -453.371861) (xy 514.995218 -453.318014) (xy 514.868445 -453.256963)
			(xy 514.745294 -453.188901) (xy 514.626154 -453.11404) (xy 514.511398 -453.032616) (xy 514.401389 -452.944887)
			(xy 514.296471 -452.851127) (xy 514.196976 -452.751632) (xy 514.103216 -452.646714) (xy 514.015486 -452.536705)
			(xy 513.934063 -452.421949) (xy 513.859201 -452.302809) (xy 513.791138 -452.179659) (xy 513.730087 -452.052886)
			(xy 513.676241 -451.922889) (xy 513.629768 -451.790078) (xy 513.590815 -451.65487) (xy 513.559504 -451.51769)
			(xy 513.535934 -451.378971) (xy 513.520179 -451.239148) (xy 513.512289 -451.098662) (xy 513.5118 -451.028308)
			(xy 513.5118 -312.408316) (xy 513.512284 -312.337962) (xy 513.520173 -312.197474) (xy 513.535926 -312.05765)
			(xy 513.559495 -311.91893) (xy 513.590805 -311.781749) (xy 513.629757 -311.646539) (xy 513.676229 -311.513726)
			(xy 513.730076 -311.383728) (xy 513.791126 -311.256954) (xy 513.859189 -311.133802) (xy 513.93405 -311.01466)
			(xy 514.015474 -310.899903) (xy 514.103203 -310.789893) (xy 514.196964 -310.684974) (xy 514.296459 -310.585477)
			(xy 514.401377 -310.491716) (xy 514.511387 -310.403986) (xy 514.626144 -310.322561) (xy 514.745285 -310.247699)
			(xy 514.868436 -310.179635) (xy 514.99521 -310.118584) (xy 515.125208 -310.064737) (xy 515.25802 -310.018263)
			(xy 515.393229 -309.97931) (xy 515.53041 -309.947999) (xy 515.669131 -309.924429) (xy 515.808954 -309.908674)
			(xy 515.949442 -309.900784) (xy 516.019796 -309.90032) (xy 531.7998 -309.90032) (xy 531.855607 -309.899798)
			(xy 531.96691 -309.891457) (xy 532.077278 -309.874822) (xy 532.186094 -309.849986) (xy 532.292751 -309.817087)
			(xy 532.39665 -309.77631) (xy 532.497211 -309.727883) (xy 532.593873 -309.672076) (xy 532.686094 -309.609202)
			(xy 532.773358 -309.539612) (xy 532.855178 -309.463695) (xy 532.931096 -309.381876) (xy 533.000687 -309.294613)
			(xy 533.063563 -309.202393) (xy 533.119372 -309.105733) (xy 533.167801 -309.005172) (xy 533.208579 -308.901273)
			(xy 533.24148 -308.794618) (xy 533.266318 -308.685802) (xy 533.282955 -308.575434) (xy 533.291297 -308.464131)
			(xy 533.291796 -308.408324) (xy 533.291796 10.40003) (xy 533.291273 10.455836) (xy 533.28293 10.567137)
			(xy 533.266293 10.677502) (xy 533.241455 10.786316) (xy 533.208555 10.89297) (xy 533.167777 10.996866)
			(xy 533.119348 11.097425) (xy 533.063541 11.194084) (xy 533.000666 11.286302) (xy 532.931076 11.373563)
			(xy 532.855159 11.45538) (xy 532.77334 11.531295) (xy 532.686078 11.600884) (xy 532.593858 11.663757)
			(xy 532.497199 11.719562) (xy 532.396639 11.767989) (xy 532.292741 11.808765) (xy 532.186087 11.841663)
			(xy 532.077273 11.866499) (xy 531.966907 11.883134) (xy 531.855606 11.891474) (xy 531.7998 11.892026)
			(xy 475.799912 11.892026) (xy 475.744104 11.891505) (xy 475.632801 11.883165) (xy 475.522432 11.86653)
			(xy 475.413615 11.841695) (xy 475.306958 11.808796) (xy 475.203057 11.76802) (xy 475.102495 11.719593)
			(xy 475.005832 11.663786) (xy 474.91361 11.600912) (xy 474.826345 11.531322) (xy 474.744524 11.455406)
			(xy 474.668605 11.373587) (xy 474.599013 11.286323) (xy 474.536136 11.194103) (xy 474.480327 11.097442)
			(xy 474.431897 10.996881) (xy 474.391117 10.892982) (xy 474.358216 10.786326) (xy 474.333378 10.677509)
			(xy 474.31674 10.567141) (xy 474.308397 10.455838) (xy 474.307916 10.40003) (xy 474.307916 7.335466)
			(xy 526.704041 7.335466) (xy 526.704041 7.464606) (xy 526.711991 7.593501) (xy 526.727861 7.721661)
			(xy 526.75159 7.848602) (xy 526.783089 7.973841) (xy 526.822238 8.096904) (xy 526.868889 8.217323)
			(xy 526.922864 8.334642) (xy 526.983959 8.448416) (xy 527.051942 8.558213) (xy 527.126556 8.663616)
			(xy 527.207517 8.764226) (xy 527.294517 8.859661) (xy 527.387228 8.94956) (xy 527.485298 9.033581)
			(xy 527.588353 9.111405) (xy 527.696004 9.182737) (xy 527.807843 9.247307) (xy 527.923444 9.304869)
			(xy 528.042369 9.355206) (xy 528.164168 9.398126) (xy 528.288378 9.433467) (xy 528.414527 9.461094)
			(xy 528.542139 9.480903) (xy 528.670728 9.492819) (xy 528.799806 9.496796) (xy 528.928884 9.492819)
			(xy 529.057473 9.480903) (xy 529.185085 9.461094) (xy 529.311234 9.433467) (xy 529.435444 9.398126)
			(xy 529.557243 9.355206) (xy 529.676168 9.304869) (xy 529.791769 9.247307) (xy 529.903608 9.182737)
			(xy 530.011259 9.111405) (xy 530.114314 9.033581) (xy 530.212384 8.94956) (xy 530.305095 8.859661)
			(xy 530.392095 8.764226) (xy 530.473056 8.663616) (xy 530.54767 8.558213) (xy 530.615653 8.448416)
			(xy 530.676748 8.334642) (xy 530.730723 8.217323) (xy 530.777374 8.096904) (xy 530.816523 7.973841)
			(xy 530.848022 7.848602) (xy 530.871751 7.721661) (xy 530.887621 7.593501) (xy 530.895571 7.464606)
			(xy 530.896068 7.400036) (xy 530.895571 7.335466) (xy 530.887621 7.206571) (xy 530.871751 7.078411)
			(xy 530.848022 6.95147) (xy 530.816523 6.826231) (xy 530.777374 6.703168) (xy 530.730723 6.582749)
			(xy 530.676748 6.46543) (xy 530.615653 6.351656) (xy 530.54767 6.241859) (xy 530.473056 6.136456)
			(xy 530.392095 6.035846) (xy 530.305095 5.940411) (xy 530.212384 5.850512) (xy 530.114314 5.766491)
			(xy 530.011259 5.688667) (xy 529.903608 5.617335) (xy 529.791769 5.552765) (xy 529.676168 5.495203)
			(xy 529.557243 5.444866) (xy 529.435444 5.401946) (xy 529.311234 5.366605) (xy 529.185085 5.338978)
			(xy 529.057473 5.319169) (xy 528.928884 5.307253) (xy 528.799806 5.303277) (xy 528.670728 5.307253)
			(xy 528.542139 5.319169) (xy 528.414527 5.338978) (xy 528.288378 5.366605) (xy 528.164168 5.401946)
			(xy 528.042369 5.444866) (xy 527.923444 5.495203) (xy 527.807843 5.552765) (xy 527.696004 5.617335)
			(xy 527.588353 5.688667) (xy 527.485298 5.766491) (xy 527.387228 5.850512) (xy 527.294517 5.940411)
			(xy 527.207517 6.035846) (xy 527.126556 6.136456) (xy 527.051942 6.241859) (xy 526.983959 6.351656)
			(xy 526.922864 6.46543) (xy 526.868889 6.582749) (xy 526.822238 6.703168) (xy 526.783089 6.826231)
			(xy 526.75159 6.95147) (xy 526.727861 7.078411) (xy 526.711991 7.206571) (xy 526.704041 7.335466)
			(xy 474.307916 7.335466) (xy 474.307916 -77.67193) (xy 474.307428 -77.765094) (xy 474.299715 -77.951262)
			(xy 474.284317 -78.136953) (xy 474.261258 -78.321849) (xy 474.23058 -78.505634) (xy 474.192333 -78.687994)
			(xy 474.146584 -78.868619) (xy 474.093411 -79.047199) (xy 474.032904 -79.223429) (xy 473.965167 -79.397008)
			(xy 473.890315 -79.56764) (xy 473.808477 -79.735034) (xy 473.719792 -79.898903) (xy 473.624411 -80.058968)
			(xy 473.522498 -80.214955) (xy 473.414227 -80.366597) (xy 473.299782 -80.513637) (xy 473.17936 -80.655821)
			(xy 473.053165 -80.792909) (xy 472.987624 -80.859122) (xy 471.245184 -82.601562) (xy 471.207836 -82.63956)
			(xy 471.138049 -82.720082) (xy 471.074185 -82.805378) (xy 471.01657 -82.895014) (xy 470.965496 -82.988531)
			(xy 470.921226 -83.085455) (xy 470.883983 -83.18529) (xy 470.853958 -83.287527) (xy 470.831304 -83.391646)
			(xy 470.816136 -83.497117) (xy 470.808532 -83.6034) (xy 470.80805 -83.656678) (xy 470.80805 -404.871936)
			(xy 470.807562 -404.9651) (xy 470.799849 -405.151268) (xy 470.78445 -405.336959) (xy 470.761392 -405.521855)
			(xy 470.730713 -405.70564) (xy 470.692467 -405.888001) (xy 470.646718 -406.068625) (xy 470.593544 -406.247205)
			(xy 470.533038 -406.423435) (xy 470.465301 -406.597015) (xy 470.39045 -406.767647) (xy 470.308612 -406.935041)
			(xy 470.219927 -407.098911) (xy 470.124547 -407.258976) (xy 470.022634 -407.414963) (xy 469.914363 -407.566606)
			(xy 469.799919 -407.713645) (xy 469.679497 -407.855831) (xy 469.553302 -407.992919) (xy 469.487758 -408.059128)
			(xy 468.244936 -409.30195) (xy 468.207612 -409.339964) (xy 468.137859 -409.4205) (xy 468.074028 -409.505805)
			(xy 468.016443 -409.595446) (xy 467.965398 -409.688966) (xy 467.921153 -409.785888) (xy 467.883933 -409.885719)
			(xy 467.853928 -409.98795) (xy 467.831291 -410.092061) (xy 467.816137 -410.197522) (xy 467.808543 -410.303794)
			(xy 467.808056 -410.357066) (xy 467.808056 -439.989976) (xy 467.808577 -440.045784) (xy 467.816916 -440.157089)
			(xy 467.83355 -440.267459) (xy 467.858385 -440.376277) (xy 467.891282 -440.482936) (xy 467.932058 -440.586837)
			(xy 467.980485 -440.687401) (xy 468.036291 -440.784065) (xy 468.099165 -440.876289) (xy 468.168754 -440.963556)
			(xy 468.244671 -441.045378) (xy 468.32649 -441.121299) (xy 468.413753 -441.190893) (xy 468.505974 -441.253771)
			(xy 468.602635 -441.309582) (xy 468.703197 -441.358013) (xy 468.807096 -441.398794) (xy 468.913753 -441.431697)
			(xy 469.02257 -441.456537) (xy 469.13294 -441.473176) (xy 469.244244 -441.48152) (xy 469.300052 -441.481972)
			(xy 471.79992 -441.481972) (xy 471.870274 -441.482466) (xy 472.01076 -441.490356) (xy 472.150582 -441.506112)
			(xy 472.289302 -441.529682) (xy 472.426481 -441.560993) (xy 472.561689 -441.599946) (xy 472.6945 -441.646419)
			(xy 472.824497 -441.700266) (xy 472.95127 -441.761317) (xy 473.07442 -441.82938) (xy 473.19356 -441.904241)
			(xy 473.308316 -441.985664) (xy 473.418325 -442.073394) (xy 473.523243 -442.167153) (xy 473.622738 -442.266648)
			(xy 473.716499 -442.371565) (xy 473.804229 -442.481575) (xy 473.885652 -442.59633) (xy 473.960514 -442.71547)
			(xy 474.028578 -442.83862) (xy 474.089629 -442.965392) (xy 474.143476 -443.095389) (xy 474.18995 -443.2282)
			(xy 474.228904 -443.363407) (xy 474.260216 -443.500587) (xy 474.283787 -443.639306) (xy 474.299543 -443.779128)
			(xy 474.307434 -443.919614) (xy 474.307916 -443.989968) (xy 474.307916 -458.092864) (xy 526.704041 -458.092864)
			(xy 526.704041 -457.963724) (xy 526.711991 -457.834829) (xy 526.727861 -457.706669) (xy 526.75159 -457.579728)
			(xy 526.783089 -457.454489) (xy 526.822238 -457.331426) (xy 526.868889 -457.211007) (xy 526.922864 -457.093688)
			(xy 526.983959 -456.979914) (xy 527.051942 -456.870117) (xy 527.126556 -456.764714) (xy 527.207517 -456.664104)
			(xy 527.294517 -456.568669) (xy 527.387228 -456.47877) (xy 527.485298 -456.394749) (xy 527.588353 -456.316925)
			(xy 527.696004 -456.245593) (xy 527.807843 -456.181023) (xy 527.923444 -456.123461) (xy 528.042369 -456.073124)
			(xy 528.164168 -456.030204) (xy 528.288378 -455.994863) (xy 528.414527 -455.967236) (xy 528.542139 -455.947427)
			(xy 528.670728 -455.935511) (xy 528.799806 -455.931535) (xy 528.928884 -455.935511) (xy 529.057473 -455.947427)
			(xy 529.185085 -455.967236) (xy 529.311234 -455.994863) (xy 529.435444 -456.030204) (xy 529.557243 -456.073124)
			(xy 529.676168 -456.123461) (xy 529.791769 -456.181023) (xy 529.903608 -456.245593) (xy 530.011259 -456.316925)
			(xy 530.114314 -456.394749) (xy 530.212384 -456.47877) (xy 530.305095 -456.568669) (xy 530.392095 -456.664104)
			(xy 530.473056 -456.764714) (xy 530.54767 -456.870117) (xy 530.615653 -456.979914) (xy 530.676748 -457.093688)
			(xy 530.730723 -457.211007) (xy 530.777374 -457.331426) (xy 530.816523 -457.454489) (xy 530.848022 -457.579728)
			(xy 530.871751 -457.706669) (xy 530.887621 -457.834829) (xy 530.895571 -457.963724) (xy 530.896068 -458.028294)
			(xy 530.895571 -458.092864) (xy 530.887621 -458.221759) (xy 530.871751 -458.349919) (xy 530.848022 -458.47686)
			(xy 530.816523 -458.602099) (xy 530.777374 -458.725162) (xy 530.730723 -458.845581) (xy 530.676748 -458.9629)
			(xy 530.615653 -459.076674) (xy 530.54767 -459.186471) (xy 530.473056 -459.291874) (xy 530.392095 -459.392484)
			(xy 530.305095 -459.487919) (xy 530.212384 -459.577818) (xy 530.114314 -459.661839) (xy 530.011259 -459.739663)
			(xy 529.903608 -459.810995) (xy 529.791769 -459.875565) (xy 529.676168 -459.933127) (xy 529.557243 -459.983464)
			(xy 529.435444 -460.026384) (xy 529.311234 -460.061725) (xy 529.185085 -460.089352) (xy 529.057473 -460.109161)
			(xy 528.928884 -460.121077) (xy 528.799806 -460.125054) (xy 528.670728 -460.121077) (xy 528.542139 -460.109161)
			(xy 528.414527 -460.089352) (xy 528.288378 -460.061725) (xy 528.164168 -460.026384) (xy 528.042369 -459.983464)
			(xy 527.923444 -459.933127) (xy 527.807843 -459.875565) (xy 527.696004 -459.810995) (xy 527.588353 -459.739663)
			(xy 527.485298 -459.661839) (xy 527.387228 -459.577818) (xy 527.294517 -459.487919) (xy 527.207517 -459.392484)
			(xy 527.126556 -459.291874) (xy 527.051942 -459.186471) (xy 526.983959 -459.076674) (xy 526.922864 -458.9629)
			(xy 526.868889 -458.845581) (xy 526.822238 -458.725162) (xy 526.783089 -458.602099) (xy 526.75159 -458.47686)
			(xy 526.727861 -458.349919) (xy 526.711991 -458.221759) (xy 526.704041 -458.092864) (xy 474.307916 -458.092864)
			(xy 474.307916 -461.028288) (xy 474.308425 -461.084096) (xy 474.316765 -461.195399) (xy 474.3334 -461.305768)
			(xy 474.358236 -461.414584) (xy 474.391134 -461.521241) (xy 474.431912 -461.625141) (xy 474.480339 -461.725703)
			(xy 474.536147 -461.822365) (xy 474.599022 -461.914586) (xy 474.668612 -462.00185) (xy 474.74453 -462.08367)
			(xy 474.82635 -462.159588) (xy 474.913614 -462.229178) (xy 475.005835 -462.292053) (xy 475.102497 -462.347861)
			(xy 475.203059 -462.396288) (xy 475.306959 -462.437066) (xy 475.413616 -462.469964) (xy 475.522432 -462.4948)
			(xy 475.632801 -462.511435) (xy 475.744104 -462.519775) (xy 475.799912 -462.520284)
		)
		(stroke
			(width 0)
			(type solid)
		)
		(fill yes)
		(layer "In16.Cu")
		(net "T1_GND")
	)
	(gr_poly
		(pts
			(xy 256.292096 -31.120588) (xy 256.292096 -11.780012) (xy 256.29258 -11.709658) (xy 256.300469 -11.56917)
			(xy 256.316223 -11.429347) (xy 256.339792 -11.290626) (xy 256.371101 -11.153445) (xy 256.410054 -11.018236)
			(xy 256.456527 -10.885423) (xy 256.510373 -10.755425) (xy 256.571423 -10.628651) (xy 256.639486 -10.505499)
			(xy 256.714347 -10.386357) (xy 256.795771 -10.2716) (xy 256.883501 -10.16159) (xy 256.977261 -10.056671)
			(xy 257.076757 -9.957175) (xy 257.181674 -9.863414) (xy 257.291684 -9.775683) (xy 257.406441 -9.694258)
			(xy 257.525582 -9.619396) (xy 257.648733 -9.551333) (xy 257.775507 -9.490281) (xy 257.905504 -9.436434)
			(xy 258.038317 -9.38996) (xy 258.173526 -9.351006) (xy 258.310706 -9.319695) (xy 258.449427 -9.296125)
			(xy 258.589251 -9.280371) (xy 258.729738 -9.272481) (xy 258.800092 -9.272016) (xy 383.601976 -9.272016)
			(xy 383.657784 -9.271508) (xy 383.769089 -9.263168) (xy 383.879459 -9.246534) (xy 383.988278 -9.221699)
			(xy 384.094936 -9.188801) (xy 384.198838 -9.148025) (xy 384.299402 -9.099598) (xy 384.396066 -9.043791)
			(xy 384.488289 -8.980916) (xy 384.575555 -8.911326) (xy 384.657377 -8.835408) (xy 384.733297 -8.753588)
			(xy 384.80289 -8.666324) (xy 384.865767 -8.574103) (xy 384.921577 -8.477441) (xy 384.970007 -8.376878)
			(xy 385.010787 -8.272978) (xy 385.043688 -8.16632) (xy 385.068526 -8.057503) (xy 385.085163 -7.947133)
			(xy 385.093506 -7.835828) (xy 385.093972 -7.78002) (xy 385.093972 0.999998) (xy 385.094465 1.070352)
			(xy 385.102355 1.210839) (xy 385.118109 1.350662) (xy 385.141678 1.489383) (xy 385.172988 1.626563)
			(xy 385.211941 1.761772) (xy 385.258413 1.894584) (xy 385.312259 2.024582) (xy 385.37331 2.151356)
			(xy 385.441373 2.274507) (xy 385.516233 2.393649) (xy 385.597656 2.508405) (xy 385.685386 2.618416)
			(xy 385.779146 2.723335) (xy 385.878641 2.822831) (xy 385.983558 2.916592) (xy 386.093567 3.004323)
			(xy 386.208323 3.085748) (xy 386.327463 3.16061) (xy 386.450614 3.228674) (xy 386.577387 3.289727)
			(xy 386.707384 3.343575) (xy 386.840195 3.390049) (xy 386.975404 3.429003) (xy 387.112584 3.460315)
			(xy 387.251304 3.483887) (xy 387.391127 3.499643) (xy 387.531614 3.507534) (xy 387.601968 3.507994)
			(xy 456.202034 3.507994) (xy 456.272387 3.5075) (xy 456.412872 3.499608) (xy 456.552693 3.483853)
			(xy 456.691411 3.460282) (xy 456.828589 3.42897) (xy 456.963796 3.390016) (xy 457.096605 3.343542)
			(xy 457.226601 3.289695) (xy 457.353372 3.228644) (xy 457.476521 3.16058) (xy 457.595659 3.085719)
			(xy 457.710413 3.004295) (xy 457.820421 2.916565) (xy 457.925337 2.822806) (xy 458.02483 2.723311)
			(xy 458.118589 2.618393) (xy 458.206317 2.508384) (xy 458.287739 2.393629) (xy 458.362598 2.27449)
			(xy 458.43066 2.15134) (xy 458.49171 2.024568) (xy 458.545555 1.894572) (xy 458.592027 1.761761)
			(xy 458.630979 1.626554) (xy 458.662289 1.489376) (xy 458.685858 1.350658) (xy 458.701612 1.210836)
			(xy 458.709501 1.070351) (xy 458.71003 0.999998) (xy 458.71003 -7.78002) (xy 458.71054 -7.835827)
			(xy 458.718882 -7.947128) (xy 458.735519 -8.057494) (xy 458.760357 -8.166309) (xy 458.793257 -8.272963)
			(xy 458.834035 -8.37686) (xy 458.882464 -8.47742) (xy 458.938272 -8.574079) (xy 459.001148 -8.666297)
			(xy 459.070739 -8.753559) (xy 459.146656 -8.835376) (xy 459.228476 -8.911291) (xy 459.31574 -8.98088)
			(xy 459.40796 -9.043752) (xy 459.504621 -9.099557) (xy 459.605182 -9.147983) (xy 459.70908 -9.188758)
			(xy 459.815736 -9.221655) (xy 459.924551 -9.24649) (xy 460.034918 -9.263123) (xy 460.146219 -9.271462)
			(xy 460.202026 -9.272016) (xy 464.327748 -9.272016) (xy 464.332574 -9.271) (xy 464.357024 -9.266474)
			(xy 464.406516 -9.261643) (xy 464.43138 -9.261348) (xy 464.456244 -9.26164) (xy 464.505735 -9.266479)
			(xy 464.530186 -9.271) (xy 464.535012 -9.272016) (xy 469.799924 -9.272016) (xy 469.855731 -9.271493)
			(xy 469.967032 -9.263151) (xy 470.077399 -9.246514) (xy 470.186213 -9.221677) (xy 470.292868 -9.188777)
			(xy 470.396765 -9.147999) (xy 470.497325 -9.099571) (xy 470.593985 -9.043764) (xy 470.686204 -8.980889)
			(xy 470.773467 -8.911299) (xy 470.855285 -8.835382) (xy 470.931202 -8.753564) (xy 471.000791 -8.666301)
			(xy 471.063666 -8.574082) (xy 471.119473 -8.477422) (xy 471.167901 -8.376862) (xy 471.208678 -8.272964)
			(xy 471.241578 -8.166309) (xy 471.266415 -8.057495) (xy 471.283051 -7.947128) (xy 471.291394 -7.835827)
			(xy 471.29192 -7.78002) (xy 471.29192 10.40003) (xy 471.291397 10.455837) (xy 471.283054 10.567138)
			(xy 471.266417 10.677504) (xy 471.241579 10.786319) (xy 471.208679 10.892973) (xy 471.167901 10.99687)
			(xy 471.119473 11.09743) (xy 471.063666 11.194089) (xy 471.000791 11.286308) (xy 470.931201 11.373571)
			(xy 470.855284 11.455389) (xy 470.773466 11.531305) (xy 470.686203 11.600895) (xy 470.593984 11.663769)
			(xy 470.497324 11.719576) (xy 470.396765 11.768004) (xy 470.292867 11.808781) (xy 470.186213 11.841681)
			(xy 470.077398 11.866518) (xy 469.967032 11.883155) (xy 469.855731 11.891497) (xy 469.799924 11.892026)
			(xy 1.999996 11.892026) (xy 1.944189 11.891504) (xy 1.832887 11.883163) (xy 1.72252 11.866527) (xy 1.613705 11.841691)
			(xy 1.50705 11.808792) (xy 1.403151 11.768014) (xy 1.302591 11.719587) (xy 1.20593 11.66378) (xy 1.113711 11.600905)
			(xy 1.026448 11.531315) (xy 0.944629 11.455398) (xy 0.868712 11.373579) (xy 0.799122 11.286316) (xy 0.736248 11.194096)
			(xy 0.680441 11.097436) (xy 0.632014 10.996875) (xy 0.591237 10.892977) (xy 0.558338 10.786321) (xy 0.533502 10.677506)
			(xy 0.516867 10.567139) (xy 0.508526 10.455837) (xy 0.508 10.40003) (xy 0.508 7.335466) (xy 2.904225 7.335466)
			(xy 2.904225 7.464606) (xy 2.912175 7.593501) (xy 2.928045 7.721661) (xy 2.951774 7.848602) (xy 2.983273 7.973841)
			(xy 3.022422 8.096904) (xy 3.069073 8.217323) (xy 3.123048 8.334642) (xy 3.184143 8.448416) (xy 3.252126 8.558213)
			(xy 3.32674 8.663616) (xy 3.407701 8.764226) (xy 3.494701 8.859661) (xy 3.587412 8.94956) (xy 3.685482 9.033581)
			(xy 3.788537 9.111405) (xy 3.896188 9.182737) (xy 4.008027 9.247307) (xy 4.123628 9.304869) (xy 4.242553 9.355206)
			(xy 4.364352 9.398126) (xy 4.488562 9.433467) (xy 4.614711 9.461094) (xy 4.742323 9.480903) (xy 4.870912 9.492819)
			(xy 4.99999 9.496796) (xy 5.129068 9.492819) (xy 5.257657 9.480903) (xy 5.385269 9.461094) (xy 5.511418 9.433467)
			(xy 5.635628 9.398126) (xy 5.757427 9.355206) (xy 5.876352 9.304869) (xy 5.991953 9.247307) (xy 6.020338 9.230919)
			(xy 256.921241 9.230919) (xy 256.921241 9.316669) (xy 256.929153 9.402052) (xy 256.944909 9.486342)
			(xy 256.968376 9.568818) (xy 256.999352 9.648777) (xy 257.037574 9.725537) (xy 257.082715 9.798443)
			(xy 257.134391 9.866872) (xy 257.19216 9.930242) (xy 257.25553 9.988011) (xy 257.323959 10.039687)
			(xy 257.396865 10.084828) (xy 257.473625 10.12305) (xy 257.553584 10.154026) (xy 257.63606 10.177493)
			(xy 257.72035 10.193249) (xy 257.805733 10.201161) (xy 257.891483 10.201161) (xy 257.976866 10.193249)
			(xy 258.061156 10.177493) (xy 258.143632 10.154026) (xy 258.223591 10.12305) (xy 258.300351 10.084828)
			(xy 258.373257 10.039687) (xy 258.441686 9.988011) (xy 258.505056 9.930242) (xy 258.562825 9.866872)
			(xy 258.614501 9.798443) (xy 258.659642 9.725537) (xy 258.697864 9.648777) (xy 258.72884 9.568818)
			(xy 258.752307 9.486342) (xy 258.768063 9.402052) (xy 258.775975 9.316669) (xy 258.77647 9.273794)
			(xy 258.775975 9.230919) (xy 263.271241 9.230919) (xy 263.271241 9.316669) (xy 263.279153 9.402052)
			(xy 263.294909 9.486342) (xy 263.318376 9.568818) (xy 263.349352 9.648777) (xy 263.387574 9.725537)
			(xy 263.432715 9.798443) (xy 263.484391 9.866872) (xy 263.54216 9.930242) (xy 263.60553 9.988011)
			(xy 263.673959 10.039687) (xy 263.746865 10.084828) (xy 263.823625 10.12305) (xy 263.903584 10.154026)
			(xy 263.98606 10.177493) (xy 264.07035 10.193249) (xy 264.155733 10.201161) (xy 264.241483 10.201161)
			(xy 264.326866 10.193249) (xy 264.411156 10.177493) (xy 264.493632 10.154026) (xy 264.573591 10.12305)
			(xy 264.650351 10.084828) (xy 264.723257 10.039687) (xy 264.791686 9.988011) (xy 264.855056 9.930242)
			(xy 264.912825 9.866872) (xy 264.964501 9.798443) (xy 265.009642 9.725537) (xy 265.047864 9.648777)
			(xy 265.07884 9.568818) (xy 265.102307 9.486342) (xy 265.118063 9.402052) (xy 265.125975 9.316669)
			(xy 265.12647 9.273794) (xy 265.125975 9.230919) (xy 324.845921 9.230919) (xy 324.845921 9.316669)
			(xy 324.853833 9.402052) (xy 324.869589 9.486342) (xy 324.893056 9.568818) (xy 324.924032 9.648777)
			(xy 324.962254 9.725537) (xy 325.007395 9.798443) (xy 325.059071 9.866872) (xy 325.11684 9.930242)
			(xy 325.18021 9.988011) (xy 325.248639 10.039687) (xy 325.321545 10.084828) (xy 325.398305 10.12305)
			(xy 325.478264 10.154026) (xy 325.56074 10.177493) (xy 325.64503 10.193249) (xy 325.730413 10.201161)
			(xy 325.816163 10.201161) (xy 325.901546 10.193249) (xy 325.985836 10.177493) (xy 326.068312 10.154026)
			(xy 326.148271 10.12305) (xy 326.225031 10.084828) (xy 326.297937 10.039687) (xy 326.366366 9.988011)
			(xy 326.429736 9.930242) (xy 326.487505 9.866872) (xy 326.539181 9.798443) (xy 326.584322 9.725537)
			(xy 326.622544 9.648777) (xy 326.65352 9.568818) (xy 326.676987 9.486342) (xy 326.692743 9.402052)
			(xy 326.700655 9.316669) (xy 326.70115 9.273794) (xy 326.700655 9.230919) (xy 331.195921 9.230919)
			(xy 331.195921 9.316669) (xy 331.203833 9.402052) (xy 331.219589 9.486342) (xy 331.243056 9.568818)
			(xy 331.274032 9.648777) (xy 331.312254 9.725537) (xy 331.357395 9.798443) (xy 331.409071 9.866872)
			(xy 331.46684 9.930242) (xy 331.53021 9.988011) (xy 331.598639 10.039687) (xy 331.671545 10.084828)
			(xy 331.748305 10.12305) (xy 331.828264 10.154026) (xy 331.91074 10.177493) (xy 331.99503 10.193249)
			(xy 332.080413 10.201161) (xy 332.166163 10.201161) (xy 332.251546 10.193249) (xy 332.335836 10.177493)
			(xy 332.418312 10.154026) (xy 332.498271 10.12305) (xy 332.575031 10.084828) (xy 332.647937 10.039687)
			(xy 332.716366 9.988011) (xy 332.779736 9.930242) (xy 332.837505 9.866872) (xy 332.889181 9.798443)
			(xy 332.934322 9.725537) (xy 332.972544 9.648777) (xy 333.00352 9.568818) (xy 333.026987 9.486342)
			(xy 333.042743 9.402052) (xy 333.050655 9.316669) (xy 333.05115 9.273794) (xy 333.050655 9.230919)
			(xy 335.488267 9.230919) (xy 335.488267 9.316669) (xy 335.496179 9.402052) (xy 335.511935 9.486342)
			(xy 335.535402 9.568818) (xy 335.566378 9.648777) (xy 335.6046 9.725537) (xy 335.649741 9.798443)
			(xy 335.701417 9.866872) (xy 335.759186 9.930242) (xy 335.822556 9.988011) (xy 335.890985 10.039687)
			(xy 335.963891 10.084828) (xy 336.040651 10.12305) (xy 336.12061 10.154026) (xy 336.203086 10.177493)
			(xy 336.287376 10.193249) (xy 336.372759 10.201161) (xy 336.458509 10.201161) (xy 336.543892 10.193249)
			(xy 336.628182 10.177493) (xy 336.710658 10.154026) (xy 336.790617 10.12305) (xy 336.867377 10.084828)
			(xy 336.940283 10.039687) (xy 337.008712 9.988011) (xy 337.072082 9.930242) (xy 337.129851 9.866872)
			(xy 337.181527 9.798443) (xy 337.226668 9.725537) (xy 337.26489 9.648777) (xy 337.295866 9.568818)
			(xy 337.319333 9.486342) (xy 337.335089 9.402052) (xy 337.343001 9.316669) (xy 337.343496 9.273794)
			(xy 337.343001 9.230919) (xy 341.838267 9.230919) (xy 341.838267 9.316669) (xy 341.846179 9.402052)
			(xy 341.861935 9.486342) (xy 341.885402 9.568818) (xy 341.916378 9.648777) (xy 341.9546 9.725537)
			(xy 341.999741 9.798443) (xy 342.051417 9.866872) (xy 342.109186 9.930242) (xy 342.172556 9.988011)
			(xy 342.240985 10.039687) (xy 342.313891 10.084828) (xy 342.390651 10.12305) (xy 342.47061 10.154026)
			(xy 342.553086 10.177493) (xy 342.637376 10.193249) (xy 342.722759 10.201161) (xy 342.808509 10.201161)
			(xy 342.893892 10.193249) (xy 342.978182 10.177493) (xy 343.060658 10.154026) (xy 343.140617 10.12305)
			(xy 343.217377 10.084828) (xy 343.290283 10.039687) (xy 343.358712 9.988011) (xy 343.422082 9.930242)
			(xy 343.479851 9.866872) (xy 343.531527 9.798443) (xy 343.576668 9.725537) (xy 343.61489 9.648777)
			(xy 343.645866 9.568818) (xy 343.669333 9.486342) (xy 343.685089 9.402052) (xy 343.693001 9.316669)
			(xy 343.693496 9.273794) (xy 343.693001 9.230919) (xy 373.705107 9.230919) (xy 373.705107 9.316669)
			(xy 373.713019 9.402052) (xy 373.728775 9.486342) (xy 373.752242 9.568818) (xy 373.783218 9.648777)
			(xy 373.82144 9.725537) (xy 373.866581 9.798443) (xy 373.918257 9.866872) (xy 373.976026 9.930242)
			(xy 374.039396 9.988011) (xy 374.107825 10.039687) (xy 374.180731 10.084828) (xy 374.257491 10.12305)
			(xy 374.33745 10.154026) (xy 374.419926 10.177493) (xy 374.504216 10.193249) (xy 374.589599 10.201161)
			(xy 374.675349 10.201161) (xy 374.760732 10.193249) (xy 374.845022 10.177493) (xy 374.927498 10.154026)
			(xy 375.007457 10.12305) (xy 375.084217 10.084828) (xy 375.157123 10.039687) (xy 375.225552 9.988011)
			(xy 375.288922 9.930242) (xy 375.346691 9.866872) (xy 375.398367 9.798443) (xy 375.443508 9.725537)
			(xy 375.48173 9.648777) (xy 375.512706 9.568818) (xy 375.536173 9.486342) (xy 375.551929 9.402052)
			(xy 375.559841 9.316669) (xy 375.560336 9.273794) (xy 375.559841 9.230919) (xy 380.055107 9.230919)
			(xy 380.055107 9.316669) (xy 380.063019 9.402052) (xy 380.078775 9.486342) (xy 380.102242 9.568818)
			(xy 380.133218 9.648777) (xy 380.17144 9.725537) (xy 380.216581 9.798443) (xy 380.268257 9.866872)
			(xy 380.326026 9.930242) (xy 380.389396 9.988011) (xy 380.457825 10.039687) (xy 380.530731 10.084828)
			(xy 380.607491 10.12305) (xy 380.68745 10.154026) (xy 380.769926 10.177493) (xy 380.854216 10.193249)
			(xy 380.939599 10.201161) (xy 381.025349 10.201161) (xy 381.110732 10.193249) (xy 381.195022 10.177493)
			(xy 381.277498 10.154026) (xy 381.357457 10.12305) (xy 381.434217 10.084828) (xy 381.507123 10.039687)
			(xy 381.575552 9.988011) (xy 381.638922 9.930242) (xy 381.696691 9.866872) (xy 381.748367 9.798443)
			(xy 381.793508 9.725537) (xy 381.83173 9.648777) (xy 381.862706 9.568818) (xy 381.886173 9.486342)
			(xy 381.901929 9.402052) (xy 381.909841 9.316669) (xy 381.910336 9.273794) (xy 381.909841 9.230919)
			(xy 381.901929 9.145536) (xy 381.886173 9.061246) (xy 381.862706 8.97877) (xy 381.83173 8.898811)
			(xy 381.793508 8.822051) (xy 381.748367 8.749145) (xy 381.696691 8.680716) (xy 381.638922 8.617346)
			(xy 381.575552 8.559577) (xy 381.507123 8.507901) (xy 381.434217 8.46276) (xy 381.357457 8.424538)
			(xy 381.277498 8.393562) (xy 381.195022 8.370095) (xy 381.110732 8.354339) (xy 381.025349 8.346427)
			(xy 380.939599 8.346427) (xy 380.854216 8.354339) (xy 380.769926 8.370095) (xy 380.68745 8.393562)
			(xy 380.607491 8.424538) (xy 380.530731 8.46276) (xy 380.457825 8.507901) (xy 380.389396 8.559577)
			(xy 380.326026 8.617346) (xy 380.268257 8.680716) (xy 380.216581 8.749145) (xy 380.17144 8.822051)
			(xy 380.133218 8.898811) (xy 380.102242 8.97877) (xy 380.078775 9.061246) (xy 380.063019 9.145536)
			(xy 380.055107 9.230919) (xy 375.559841 9.230919) (xy 375.551929 9.145536) (xy 375.536173 9.061246)
			(xy 375.512706 8.97877) (xy 375.48173 8.898811) (xy 375.443508 8.822051) (xy 375.398367 8.749145)
			(xy 375.346691 8.680716) (xy 375.288922 8.617346) (xy 375.225552 8.559577) (xy 375.157123 8.507901)
			(xy 375.084217 8.46276) (xy 375.007457 8.424538) (xy 374.927498 8.393562) (xy 374.845022 8.370095)
			(xy 374.760732 8.354339) (xy 374.675349 8.346427) (xy 374.589599 8.346427) (xy 374.504216 8.354339)
			(xy 374.419926 8.370095) (xy 374.33745 8.393562) (xy 374.257491 8.424538) (xy 374.180731 8.46276)
			(xy 374.107825 8.507901) (xy 374.039396 8.559577) (xy 373.976026 8.617346) (xy 373.918257 8.680716)
			(xy 373.866581 8.749145) (xy 373.82144 8.822051) (xy 373.783218 8.898811) (xy 373.752242 8.97877)
			(xy 373.728775 9.061246) (xy 373.713019 9.145536) (xy 373.705107 9.230919) (xy 343.693001 9.230919)
			(xy 343.685089 9.145536) (xy 343.669333 9.061246) (xy 343.645866 8.97877) (xy 343.61489 8.898811)
			(xy 343.576668 8.822051) (xy 343.531527 8.749145) (xy 343.479851 8.680716) (xy 343.422082 8.617346)
			(xy 343.358712 8.559577) (xy 343.290283 8.507901) (xy 343.217377 8.46276) (xy 343.140617 8.424538)
			(xy 343.060658 8.393562) (xy 342.978182 8.370095) (xy 342.893892 8.354339) (xy 342.808509 8.346427)
			(xy 342.722759 8.346427) (xy 342.637376 8.354339) (xy 342.553086 8.370095) (xy 342.47061 8.393562)
			(xy 342.390651 8.424538) (xy 342.313891 8.46276) (xy 342.240985 8.507901) (xy 342.172556 8.559577)
			(xy 342.109186 8.617346) (xy 342.051417 8.680716) (xy 341.999741 8.749145) (xy 341.9546 8.822051)
			(xy 341.916378 8.898811) (xy 341.885402 8.97877) (xy 341.861935 9.061246) (xy 341.846179 9.145536)
			(xy 341.838267 9.230919) (xy 337.343001 9.230919) (xy 337.335089 9.145536) (xy 337.319333 9.061246)
			(xy 337.295866 8.97877) (xy 337.26489 8.898811) (xy 337.226668 8.822051) (xy 337.181527 8.749145)
			(xy 337.129851 8.680716) (xy 337.072082 8.617346) (xy 337.008712 8.559577) (xy 336.940283 8.507901)
			(xy 336.867377 8.46276) (xy 336.790617 8.424538) (xy 336.710658 8.393562) (xy 336.628182 8.370095)
			(xy 336.543892 8.354339) (xy 336.458509 8.346427) (xy 336.372759 8.346427) (xy 336.287376 8.354339)
			(xy 336.203086 8.370095) (xy 336.12061 8.393562) (xy 336.040651 8.424538) (xy 335.963891 8.46276)
			(xy 335.890985 8.507901) (xy 335.822556 8.559577) (xy 335.759186 8.617346) (xy 335.701417 8.680716)
			(xy 335.649741 8.749145) (xy 335.6046 8.822051) (xy 335.566378 8.898811) (xy 335.535402 8.97877)
			(xy 335.511935 9.061246) (xy 335.496179 9.145536) (xy 335.488267 9.230919) (xy 333.050655 9.230919)
			(xy 333.042743 9.145536) (xy 333.026987 9.061246) (xy 333.00352 8.97877) (xy 332.972544 8.898811)
			(xy 332.934322 8.822051) (xy 332.889181 8.749145) (xy 332.837505 8.680716) (xy 332.779736 8.617346)
			(xy 332.716366 8.559577) (xy 332.647937 8.507901) (xy 332.575031 8.46276) (xy 332.498271 8.424538)
			(xy 332.418312 8.393562) (xy 332.335836 8.370095) (xy 332.251546 8.354339) (xy 332.166163 8.346427)
			(xy 332.080413 8.346427) (xy 331.99503 8.354339) (xy 331.91074 8.370095) (xy 331.828264 8.393562)
			(xy 331.748305 8.424538) (xy 331.671545 8.46276) (xy 331.598639 8.507901) (xy 331.53021 8.559577)
			(xy 331.46684 8.617346) (xy 331.409071 8.680716) (xy 331.357395 8.749145) (xy 331.312254 8.822051)
			(xy 331.274032 8.898811) (xy 331.243056 8.97877) (xy 331.219589 9.061246) (xy 331.203833 9.145536)
			(xy 331.195921 9.230919) (xy 326.700655 9.230919) (xy 326.692743 9.145536) (xy 326.676987 9.061246)
			(xy 326.65352 8.97877) (xy 326.622544 8.898811) (xy 326.584322 8.822051) (xy 326.539181 8.749145)
			(xy 326.487505 8.680716) (xy 326.429736 8.617346) (xy 326.366366 8.559577) (xy 326.297937 8.507901)
			(xy 326.225031 8.46276) (xy 326.148271 8.424538) (xy 326.068312 8.393562) (xy 325.985836 8.370095)
			(xy 325.901546 8.354339) (xy 325.816163 8.346427) (xy 325.730413 8.346427) (xy 325.64503 8.354339)
			(xy 325.56074 8.370095) (xy 325.478264 8.393562) (xy 325.398305 8.424538) (xy 325.321545 8.46276)
			(xy 325.248639 8.507901) (xy 325.18021 8.559577) (xy 325.11684 8.617346) (xy 325.059071 8.680716)
			(xy 325.007395 8.749145) (xy 324.962254 8.822051) (xy 324.924032 8.898811) (xy 324.893056 8.97877)
			(xy 324.869589 9.061246) (xy 324.853833 9.145536) (xy 324.845921 9.230919) (xy 265.125975 9.230919)
			(xy 265.118063 9.145536) (xy 265.102307 9.061246) (xy 265.07884 8.97877) (xy 265.047864 8.898811)
			(xy 265.009642 8.822051) (xy 264.964501 8.749145) (xy 264.912825 8.680716) (xy 264.855056 8.617346)
			(xy 264.791686 8.559577) (xy 264.723257 8.507901) (xy 264.650351 8.46276) (xy 264.573591 8.424538)
			(xy 264.493632 8.393562) (xy 264.411156 8.370095) (xy 264.326866 8.354339) (xy 264.241483 8.346427)
			(xy 264.155733 8.346427) (xy 264.07035 8.354339) (xy 263.98606 8.370095) (xy 263.903584 8.393562)
			(xy 263.823625 8.424538) (xy 263.746865 8.46276) (xy 263.673959 8.507901) (xy 263.60553 8.559577)
			(xy 263.54216 8.617346) (xy 263.484391 8.680716) (xy 263.432715 8.749145) (xy 263.387574 8.822051)
			(xy 263.349352 8.898811) (xy 263.318376 8.97877) (xy 263.294909 9.061246) (xy 263.279153 9.145536)
			(xy 263.271241 9.230919) (xy 258.775975 9.230919) (xy 258.768063 9.145536) (xy 258.752307 9.061246)
			(xy 258.72884 8.97877) (xy 258.697864 8.898811) (xy 258.659642 8.822051) (xy 258.614501 8.749145)
			(xy 258.562825 8.680716) (xy 258.505056 8.617346) (xy 258.441686 8.559577) (xy 258.373257 8.507901)
			(xy 258.300351 8.46276) (xy 258.223591 8.424538) (xy 258.143632 8.393562) (xy 258.061156 8.370095)
			(xy 257.976866 8.354339) (xy 257.891483 8.346427) (xy 257.805733 8.346427) (xy 257.72035 8.354339)
			(xy 257.63606 8.370095) (xy 257.553584 8.393562) (xy 257.473625 8.424538) (xy 257.396865 8.46276)
			(xy 257.323959 8.507901) (xy 257.25553 8.559577) (xy 257.19216 8.617346) (xy 257.134391 8.680716)
			(xy 257.082715 8.749145) (xy 257.037574 8.822051) (xy 256.999352 8.898811) (xy 256.968376 8.97877)
			(xy 256.944909 9.061246) (xy 256.929153 9.145536) (xy 256.921241 9.230919) (xy 6.020338 9.230919)
			(xy 6.103792 9.182737) (xy 6.211443 9.111405) (xy 6.314498 9.033581) (xy 6.412568 8.94956) (xy 6.505279 8.859661)
			(xy 6.592279 8.764226) (xy 6.67324 8.663616) (xy 6.747854 8.558213) (xy 6.815837 8.448416) (xy 6.876932 8.334642)
			(xy 6.930907 8.217323) (xy 6.977558 8.096904) (xy 7.016707 7.973841) (xy 7.048206 7.848602) (xy 7.071935 7.721661)
			(xy 7.087805 7.593501) (xy 7.095755 7.464606) (xy 7.096252 7.400036) (xy 7.095755 7.335466) (xy 7.087805 7.206571)
			(xy 7.071935 7.078411) (xy 7.048206 6.95147) (xy 7.016707 6.826231) (xy 6.977558 6.703168) (xy 6.97173 6.688125)
			(xy 178.335673 6.688125) (xy 178.335673 6.773875) (xy 178.343585 6.859258) (xy 178.359341 6.943548)
			(xy 178.382808 7.026024) (xy 178.413784 7.105983) (xy 178.452006 7.182743) (xy 178.497147 7.255649)
			(xy 178.548823 7.324078) (xy 178.606592 7.387448) (xy 178.669962 7.445217) (xy 178.738391 7.496893)
			(xy 178.811297 7.542034) (xy 178.888057 7.580256) (xy 178.968016 7.611232) (xy 179.050492 7.634699)
			(xy 179.134782 7.650455) (xy 179.220165 7.658367) (xy 179.305915 7.658367) (xy 179.391298 7.650455)
			(xy 179.475588 7.634699) (xy 179.558064 7.611232) (xy 179.638023 7.580256) (xy 179.714783 7.542034)
			(xy 179.787689 7.496893) (xy 179.856118 7.445217) (xy 179.919488 7.387448) (xy 179.977257 7.324078)
			(xy 180.028933 7.255649) (xy 180.074074 7.182743) (xy 180.112296 7.105983) (xy 180.143272 7.026024)
			(xy 180.166739 6.943548) (xy 180.182495 6.859258) (xy 180.190407 6.773875) (xy 180.190902 6.731)
			(xy 180.190407 6.688125) (xy 184.685673 6.688125) (xy 184.685673 6.773875) (xy 184.693585 6.859258)
			(xy 184.709341 6.943548) (xy 184.732808 7.026024) (xy 184.763784 7.105983) (xy 184.802006 7.182743)
			(xy 184.847147 7.255649) (xy 184.898823 7.324078) (xy 184.956592 7.387448) (xy 185.019962 7.445217)
			(xy 185.088391 7.496893) (xy 185.161297 7.542034) (xy 185.238057 7.580256) (xy 185.318016 7.611232)
			(xy 185.400492 7.634699) (xy 185.484782 7.650455) (xy 185.570165 7.658367) (xy 185.655915 7.658367)
			(xy 185.741298 7.650455) (xy 185.825588 7.634699) (xy 185.908064 7.611232) (xy 185.988023 7.580256)
			(xy 186.064783 7.542034) (xy 186.137689 7.496893) (xy 186.206118 7.445217) (xy 186.269488 7.387448)
			(xy 186.327257 7.324078) (xy 186.378933 7.255649) (xy 186.424074 7.182743) (xy 186.462296 7.105983)
			(xy 186.493272 7.026024) (xy 186.516739 6.943548) (xy 186.532495 6.859258) (xy 186.540407 6.773875)
			(xy 186.540902 6.731) (xy 186.540407 6.688125) (xy 246.260353 6.688125) (xy 246.260353 6.773875)
			(xy 246.268265 6.859258) (xy 246.284021 6.943548) (xy 246.307488 7.026024) (xy 246.338464 7.105983)
			(xy 246.376686 7.182743) (xy 246.421827 7.255649) (xy 246.473503 7.324078) (xy 246.531272 7.387448)
			(xy 246.594642 7.445217) (xy 246.663071 7.496893) (xy 246.735977 7.542034) (xy 246.812737 7.580256)
			(xy 246.892696 7.611232) (xy 246.975172 7.634699) (xy 247.059462 7.650455) (xy 247.144845 7.658367)
			(xy 247.230595 7.658367) (xy 247.315978 7.650455) (xy 247.400268 7.634699) (xy 247.482744 7.611232)
			(xy 247.562703 7.580256) (xy 247.639463 7.542034) (xy 247.712369 7.496893) (xy 247.780798 7.445217)
			(xy 247.844168 7.387448) (xy 247.901937 7.324078) (xy 247.953613 7.255649) (xy 247.998754 7.182743)
			(xy 248.036976 7.105983) (xy 248.067952 7.026024) (xy 248.091419 6.943548) (xy 248.107175 6.859258)
			(xy 248.115087 6.773875) (xy 248.115582 6.731) (xy 248.115087 6.688125) (xy 252.610353 6.688125)
			(xy 252.610353 6.773875) (xy 252.618265 6.859258) (xy 252.634021 6.943548) (xy 252.657488 7.026024)
			(xy 252.688464 7.105983) (xy 252.726686 7.182743) (xy 252.771827 7.255649) (xy 252.823503 7.324078)
			(xy 252.881272 7.387448) (xy 252.944642 7.445217) (xy 253.013071 7.496893) (xy 253.085977 7.542034)
			(xy 253.162737 7.580256) (xy 253.242696 7.611232) (xy 253.325172 7.634699) (xy 253.409462 7.650455)
			(xy 253.494845 7.658367) (xy 253.580595 7.658367) (xy 253.665978 7.650455) (xy 253.750268 7.634699)
			(xy 253.832744 7.611232) (xy 253.912703 7.580256) (xy 253.989463 7.542034) (xy 254.062369 7.496893)
			(xy 254.130798 7.445217) (xy 254.194168 7.387448) (xy 254.251937 7.324078) (xy 254.303613 7.255649)
			(xy 254.348754 7.182743) (xy 254.386976 7.105983) (xy 254.417952 7.026024) (xy 254.441419 6.943548)
			(xy 254.457175 6.859258) (xy 254.465087 6.773875) (xy 254.465582 6.731) (xy 254.465119 6.690919)
			(xy 256.921241 6.690919) (xy 256.921241 6.776669) (xy 256.929153 6.862052) (xy 256.944909 6.946342)
			(xy 256.968376 7.028818) (xy 256.999352 7.108777) (xy 257.037574 7.185537) (xy 257.082715 7.258443)
			(xy 257.134391 7.326872) (xy 257.19216 7.390242) (xy 257.25553 7.448011) (xy 257.323959 7.499687)
			(xy 257.396865 7.544828) (xy 257.473625 7.58305) (xy 257.553584 7.614026) (xy 257.63606 7.637493)
			(xy 257.72035 7.653249) (xy 257.805733 7.661161) (xy 257.891483 7.661161) (xy 257.976866 7.653249)
			(xy 258.061156 7.637493) (xy 258.143632 7.614026) (xy 258.223591 7.58305) (xy 258.300351 7.544828)
			(xy 258.373257 7.499687) (xy 258.428864 7.457694) (xy 261.079996 7.457694) (xy 261.079996 8.554974)
			(xy 261.080529 8.567058) (xy 261.087973 8.59005) (xy 261.102144 8.609627) (xy 261.121661 8.62388)
			(xy 261.144622 8.63142) (xy 261.156704 8.631936) (xy 261.768844 8.631936) (xy 261.777315 8.631685)
			(xy 261.793848 8.627973) (xy 261.80161 8.62457) (xy 261.814596 8.618995) (xy 261.842475 8.61445)
			(xy 261.870532 8.617721) (xy 261.896619 8.628555) (xy 261.918738 8.646125) (xy 261.92734 8.657336)
			(xy 261.942756 8.678198) (xy 261.978318 8.715962) (xy 262.018669 8.748561) (xy 262.063063 8.775392)
			(xy 262.110683 8.795961) (xy 262.160651 8.809889) (xy 262.212046 8.816919) (xy 262.237982 8.817356)
			(xy 262.265253 8.816882) (xy 262.31924 8.809122) (xy 262.371572 8.793758) (xy 262.421186 8.771102)
			(xy 262.46707 8.741615) (xy 262.508291 8.705899) (xy 262.544008 8.66468) (xy 262.573496 8.618797)
			(xy 262.596153 8.569184) (xy 262.611519 8.516851) (xy 262.619281 8.462865) (xy 262.619744 8.435594)
			(xy 262.619744 7.571994) (xy 262.619304 7.544722) (xy 262.611541 7.490733) (xy 262.596173 7.438399)
			(xy 262.573513 7.388785) (xy 262.544023 7.3429) (xy 262.508303 7.30168) (xy 262.46708 7.265962) (xy 262.421194 7.236475)
			(xy 262.371578 7.213819) (xy 262.319243 7.198454) (xy 262.265254 7.190694) (xy 262.237982 7.190232)
			(xy 262.211789 7.1907) (xy 262.159897 7.197893) (xy 262.109477 7.212115) (xy 262.061475 7.233097)
			(xy 262.016793 7.260446) (xy 261.976271 7.293648) (xy 261.940669 7.332079) (xy 261.925308 7.3533)
			(xy 261.916825 7.364535) (xy 261.894967 7.38226) (xy 261.86911 7.393366) (xy 261.841207 7.397016)
			(xy 261.813364 7.392935) (xy 261.80034 7.38759) (xy 261.792854 7.38442) (xy 261.776971 7.380961)
			(xy 261.768844 7.380732) (xy 261.156704 7.380732) (xy 261.144592 7.38112) (xy 261.121559 7.388622)
			(xy 261.101983 7.40289) (xy 261.08779 7.42252) (xy 261.080375 7.445581) (xy 261.079996 7.457694)
			(xy 258.428864 7.457694) (xy 258.441686 7.448011) (xy 258.505056 7.390242) (xy 258.562825 7.326872)
			(xy 258.614501 7.258443) (xy 258.659642 7.185537) (xy 258.697864 7.108777) (xy 258.72884 7.028818)
			(xy 258.752307 6.946342) (xy 258.768063 6.862052) (xy 258.775975 6.776669) (xy 258.77647 6.733794)
			(xy 258.775975 6.690919) (xy 263.271241 6.690919) (xy 263.271241 6.776669) (xy 263.279153 6.862052)
			(xy 263.294909 6.946342) (xy 263.318376 7.028818) (xy 263.349352 7.108777) (xy 263.387574 7.185537)
			(xy 263.432715 7.258443) (xy 263.484391 7.326872) (xy 263.54216 7.390242) (xy 263.60553 7.448011)
			(xy 263.673959 7.499687) (xy 263.746865 7.544828) (xy 263.823625 7.58305) (xy 263.903584 7.614026)
			(xy 263.98606 7.637493) (xy 264.07035 7.653249) (xy 264.155733 7.661161) (xy 264.241483 7.661161)
			(xy 264.326866 7.653249) (xy 264.411156 7.637493) (xy 264.493632 7.614026) (xy 264.573591 7.58305)
			(xy 264.650351 7.544828) (xy 264.723257 7.499687) (xy 264.791686 7.448011) (xy 264.855056 7.390242)
			(xy 264.912825 7.326872) (xy 264.964501 7.258443) (xy 265.009642 7.185537) (xy 265.047864 7.108777)
			(xy 265.07884 7.028818) (xy 265.102307 6.946342) (xy 265.118063 6.862052) (xy 265.125975 6.776669)
			(xy 265.12647 6.733794) (xy 265.125975 6.690919) (xy 324.845921 6.690919) (xy 324.845921 6.776669)
			(xy 324.853833 6.862052) (xy 324.869589 6.946342) (xy 324.893056 7.028818) (xy 324.924032 7.108777)
			(xy 324.962254 7.185537) (xy 325.007395 7.258443) (xy 325.059071 7.326872) (xy 325.11684 7.390242)
			(xy 325.18021 7.448011) (xy 325.248639 7.499687) (xy 325.321545 7.544828) (xy 325.398305 7.58305)
			(xy 325.478264 7.614026) (xy 325.56074 7.637493) (xy 325.64503 7.653249) (xy 325.730413 7.661161)
			(xy 325.816163 7.661161) (xy 325.901546 7.653249) (xy 325.985836 7.637493) (xy 326.068312 7.614026)
			(xy 326.148271 7.58305) (xy 326.170474 7.571994) (xy 327.352152 7.571994) (xy 327.352152 8.435594)
			(xy 327.352607 8.462865) (xy 327.360369 8.516853) (xy 327.375735 8.569187) (xy 327.398393 8.618801)
			(xy 327.427881 8.664686) (xy 327.4636 8.705906) (xy 327.504821 8.741624) (xy 327.550706 8.771111)
			(xy 327.60032 8.793768) (xy 327.652654 8.809133) (xy 327.706642 8.816893) (xy 327.733914 8.817356)
			(xy 327.760108 8.81689) (xy 327.811999 8.809697) (xy 327.86242 8.795476) (xy 327.910422 8.774493)
			(xy 327.955104 8.747144) (xy 327.995626 8.713942) (xy 328.031228 8.67551) (xy 328.046588 8.654288)
			(xy 328.055072 8.643054) (xy 328.07693 8.625331) (xy 328.102787 8.614225) (xy 328.130689 8.610574)
			(xy 328.158532 8.614654) (xy 328.171556 8.619998) (xy 328.179043 8.623167) (xy 328.194925 8.626627)
			(xy 328.203052 8.626856) (xy 328.815192 8.626856) (xy 328.827295 8.626378) (xy 328.850312 8.618887)
			(xy 328.869881 8.60464) (xy 328.884078 8.585035) (xy 328.891509 8.561998) (xy 328.8919 8.549894)
			(xy 328.8919 7.452614) (xy 328.891381 7.440529) (xy 328.883933 7.417536) (xy 328.869759 7.397959)
			(xy 328.850238 7.383707) (xy 328.827275 7.376167) (xy 328.815192 7.375652) (xy 328.203052 7.375652)
			(xy 328.194581 7.375903) (xy 328.178048 7.379615) (xy 328.170286 7.383018) (xy 328.157303 7.388601)
			(xy 328.129422 7.393146) (xy 328.101363 7.389874) (xy 328.075276 7.379037) (xy 328.053157 7.361465)
			(xy 328.044556 7.350252) (xy 328.029145 7.329385) (xy 327.993582 7.291622) (xy 327.953231 7.259024)
			(xy 327.908835 7.232194) (xy 327.861214 7.211625) (xy 327.811245 7.197698) (xy 327.759851 7.190668)
			(xy 327.733914 7.190232) (xy 327.706644 7.190714) (xy 327.652658 7.198475) (xy 327.600326 7.213839)
			(xy 327.550713 7.236494) (xy 327.50483 7.26598) (xy 327.46361 7.301695) (xy 327.427892 7.342914)
			(xy 327.398404 7.388795) (xy 327.375746 7.438407) (xy 327.360379 7.490738) (xy 327.352616 7.544724)
			(xy 327.352152 7.571994) (xy 326.170474 7.571994) (xy 326.225031 7.544828) (xy 326.297937 7.499687)
			(xy 326.366366 7.448011) (xy 326.429736 7.390242) (xy 326.487505 7.326872) (xy 326.539181 7.258443)
			(xy 326.584322 7.185537) (xy 326.622544 7.108777) (xy 326.65352 7.028818) (xy 326.676987 6.946342)
			(xy 326.692743 6.862052) (xy 326.700655 6.776669) (xy 326.70115 6.733794) (xy 326.700655 6.690919)
			(xy 331.195921 6.690919) (xy 331.195921 6.776669) (xy 331.203833 6.862052) (xy 331.219589 6.946342)
			(xy 331.243056 7.028818) (xy 331.274032 7.108777) (xy 331.312254 7.185537) (xy 331.357395 7.258443)
			(xy 331.409071 7.326872) (xy 331.46684 7.390242) (xy 331.53021 7.448011) (xy 331.598639 7.499687)
			(xy 331.671545 7.544828) (xy 331.748305 7.58305) (xy 331.828264 7.614026) (xy 331.91074 7.637493)
			(xy 331.99503 7.653249) (xy 332.080413 7.661161) (xy 332.166163 7.661161) (xy 332.251546 7.653249)
			(xy 332.335836 7.637493) (xy 332.418312 7.614026) (xy 332.498271 7.58305) (xy 332.575031 7.544828)
			(xy 332.647937 7.499687) (xy 332.716366 7.448011) (xy 332.779736 7.390242) (xy 332.837505 7.326872)
			(xy 332.889181 7.258443) (xy 332.934322 7.185537) (xy 332.972544 7.108777) (xy 333.00352 7.028818)
			(xy 333.026987 6.946342) (xy 333.042743 6.862052) (xy 333.050655 6.776669) (xy 333.05115 6.733794)
			(xy 333.050655 6.690919) (xy 335.488267 6.690919) (xy 335.488267 6.776669) (xy 335.496179 6.862052)
			(xy 335.511935 6.946342) (xy 335.535402 7.028818) (xy 335.566378 7.108777) (xy 335.6046 7.185537)
			(xy 335.649741 7.258443) (xy 335.701417 7.326872) (xy 335.759186 7.390242) (xy 335.822556 7.448011)
			(xy 335.890985 7.499687) (xy 335.963891 7.544828) (xy 336.040651 7.58305) (xy 336.12061 7.614026)
			(xy 336.203086 7.637493) (xy 336.287376 7.653249) (xy 336.372759 7.661161) (xy 336.458509 7.661161)
			(xy 336.543892 7.653249) (xy 336.628182 7.637493) (xy 336.710658 7.614026) (xy 336.790617 7.58305)
			(xy 336.867377 7.544828) (xy 336.940283 7.499687) (xy 336.99589 7.457694) (xy 339.646768 7.457694)
			(xy 339.646768 8.554974) (xy 339.647183 8.567098) (xy 339.654671 8.590161) (xy 339.668923 8.60978)
			(xy 339.688542 8.624031) (xy 339.711606 8.631518) (xy 339.72373 8.631936) (xy 340.33587 8.631936)
			(xy 340.344342 8.631693) (xy 340.360875 8.627975) (xy 340.368636 8.62457) (xy 340.381611 8.618968)
			(xy 340.409496 8.614428) (xy 340.437557 8.617705) (xy 340.463646 8.628546) (xy 340.485765 8.646121)
			(xy 340.494366 8.657336) (xy 340.509767 8.67821) (xy 340.545331 8.715974) (xy 340.585684 8.748572)
			(xy 340.630081 8.775401) (xy 340.677704 8.795968) (xy 340.727675 8.809894) (xy 340.779071 8.816921)
			(xy 340.805008 8.817356) (xy 340.83227 8.816851) (xy 340.88624 8.809088) (xy 340.938554 8.793721)
			(xy 340.988148 8.771062) (xy 341.034011 8.741574) (xy 341.075209 8.705857) (xy 341.110903 8.664639)
			(xy 341.140365 8.61876) (xy 341.162996 8.569153) (xy 341.178334 8.51683) (xy 341.186067 8.462857)
			(xy 341.186516 8.435594) (xy 341.186516 7.571994) (xy 341.186082 7.544734) (xy 341.178325 7.490768)
			(xy 341.162969 7.438455) (xy 341.140327 7.388859) (xy 341.11086 7.342988) (xy 341.075167 7.301776)
			(xy 341.033974 7.266061) (xy 340.988119 7.236569) (xy 340.938534 7.213902) (xy 340.886229 7.198518)
			(xy 340.832268 7.190733) (xy 340.805008 7.190232) (xy 340.778815 7.19072) (xy 340.726925 7.197909)
			(xy 340.676505 7.212127) (xy 340.628503 7.233106) (xy 340.583821 7.260452) (xy 340.543298 7.293651)
			(xy 340.507695 7.33208) (xy 340.492334 7.3533) (xy 340.483828 7.364517) (xy 340.461977 7.382242)
			(xy 340.436126 7.393351) (xy 340.408228 7.397006) (xy 340.380389 7.392931) (xy 340.367366 7.38759)
			(xy 340.359877 7.384427) (xy 340.343996 7.380964) (xy 340.33587 7.380732) (xy 339.72373 7.380732)
			(xy 339.711609 7.381185) (xy 339.688553 7.388669) (xy 339.668937 7.402912) (xy 339.654685 7.42252)
			(xy 339.647191 7.445574) (xy 339.646768 7.457694) (xy 336.99589 7.457694) (xy 337.008712 7.448011)
			(xy 337.072082 7.390242) (xy 337.129851 7.326872) (xy 337.181527 7.258443) (xy 337.226668 7.185537)
			(xy 337.26489 7.108777) (xy 337.295866 7.028818) (xy 337.319333 6.946342) (xy 337.335089 6.862052)
			(xy 337.343001 6.776669) (xy 337.343496 6.733794) (xy 337.343001 6.690919) (xy 341.838267 6.690919)
			(xy 341.838267 6.776669) (xy 341.846179 6.862052) (xy 341.861935 6.946342) (xy 341.885402 7.028818)
			(xy 341.916378 7.108777) (xy 341.9546 7.185537) (xy 341.999741 7.258443) (xy 342.051417 7.326872)
			(xy 342.109186 7.390242) (xy 342.172556 7.448011) (xy 342.240985 7.499687) (xy 342.313891 7.544828)
			(xy 342.390651 7.58305) (xy 342.47061 7.614026) (xy 342.553086 7.637493) (xy 342.637376 7.653249)
			(xy 342.722759 7.661161) (xy 342.808509 7.661161) (xy 342.893892 7.653249) (xy 342.978182 7.637493)
			(xy 343.060658 7.614026) (xy 343.140617 7.58305) (xy 343.217377 7.544828) (xy 343.290283 7.499687)
			(xy 343.358712 7.448011) (xy 343.422082 7.390242) (xy 343.479851 7.326872) (xy 343.531527 7.258443)
			(xy 343.576668 7.185537) (xy 343.61489 7.108777) (xy 343.645866 7.028818) (xy 343.669333 6.946342)
			(xy 343.685089 6.862052) (xy 343.693001 6.776669) (xy 343.693496 6.733794) (xy 343.693001 6.690919)
			(xy 373.705107 6.690919) (xy 373.705107 6.776669) (xy 373.713019 6.862052) (xy 373.728775 6.946342)
			(xy 373.752242 7.028818) (xy 373.783218 7.108777) (xy 373.82144 7.185537) (xy 373.866581 7.258443)
			(xy 373.918257 7.326872) (xy 373.976026 7.390242) (xy 374.039396 7.448011) (xy 374.107825 7.499687)
			(xy 374.180731 7.544828) (xy 374.257491 7.58305) (xy 374.33745 7.614026) (xy 374.419926 7.637493)
			(xy 374.504216 7.653249) (xy 374.589599 7.661161) (xy 374.675349 7.661161) (xy 374.760732 7.653249)
			(xy 374.845022 7.637493) (xy 374.927498 7.614026) (xy 375.007457 7.58305) (xy 375.02966 7.571994)
			(xy 376.211592 7.571994) (xy 376.211592 8.435594) (xy 376.212129 8.46285) (xy 376.219882 8.516807)
			(xy 376.235231 8.569112) (xy 376.257865 8.618702) (xy 376.287322 8.664569) (xy 376.323005 8.705779)
			(xy 376.364186 8.741494) (xy 376.410029 8.770988) (xy 376.459601 8.793661) (xy 376.511894 8.809053)
			(xy 376.565845 8.816849) (xy 376.5931 8.817356) (xy 376.619293 8.816879) (xy 376.671184 8.809688)
			(xy 376.721605 8.795469) (xy 376.769607 8.774488) (xy 376.814289 8.747141) (xy 376.854812 8.71394)
			(xy 376.890413 8.675509) (xy 376.905774 8.654288) (xy 376.91427 8.643064) (xy 376.936125 8.625341)
			(xy 376.961978 8.614233) (xy 376.989878 8.61058) (xy 377.017719 8.614656) (xy 377.030742 8.619998)
			(xy 377.038231 8.623163) (xy 377.054112 8.626625) (xy 377.062238 8.626856) (xy 377.674378 8.626856)
			(xy 377.6865 8.626421) (xy 377.709559 8.618934) (xy 377.729175 8.604687) (xy 377.743427 8.585074)
			(xy 377.750919 8.562016) (xy 377.75134 8.549894) (xy 377.75134 7.452614) (xy 377.750928 7.44049)
			(xy 377.743437 7.417428) (xy 377.729184 7.397811) (xy 377.709565 7.38356) (xy 377.686502 7.376071)
			(xy 377.674378 7.375652) (xy 377.062238 7.375652) (xy 377.053766 7.375898) (xy 377.037234 7.379614)
			(xy 377.029472 7.383018) (xy 377.016495 7.388616) (xy 376.988611 7.393158) (xy 376.96055 7.389883)
			(xy 376.934462 7.379042) (xy 376.912343 7.361467) (xy 376.903742 7.350252) (xy 376.88834 7.329379)
			(xy 376.852775 7.291615) (xy 376.812422 7.259018) (xy 376.768025 7.232189) (xy 376.720403 7.211621)
			(xy 376.670433 7.197695) (xy 376.619037 7.190668) (xy 376.5931 7.190232) (xy 376.565834 7.190656)
			(xy 376.511857 7.198421) (xy 376.459536 7.213792) (xy 376.409936 7.236456) (xy 376.364069 7.265951)
			(xy 376.322868 7.301677) (xy 376.287175 7.342904) (xy 376.257715 7.388794) (xy 376.235089 7.438412)
			(xy 376.219758 7.490745) (xy 376.212035 7.544727) (xy 376.211592 7.571994) (xy 375.02966 7.571994)
			(xy 375.084217 7.544828) (xy 375.157123 7.499687) (xy 375.225552 7.448011) (xy 375.288922 7.390242)
			(xy 375.346691 7.326872) (xy 375.398367 7.258443) (xy 375.443508 7.185537) (xy 375.48173 7.108777)
			(xy 375.512706 7.028818) (xy 375.536173 6.946342) (xy 375.551929 6.862052) (xy 375.559841 6.776669)
			(xy 375.560336 6.733794) (xy 375.559841 6.690919) (xy 380.055107 6.690919) (xy 380.055107 6.776669)
			(xy 380.063019 6.862052) (xy 380.078775 6.946342) (xy 380.102242 7.028818) (xy 380.133218 7.108777)
			(xy 380.17144 7.185537) (xy 380.216581 7.258443) (xy 380.268257 7.326872) (xy 380.326026 7.390242)
			(xy 380.389396 7.448011) (xy 380.457825 7.499687) (xy 380.530731 7.544828) (xy 380.607491 7.58305)
			(xy 380.68745 7.614026) (xy 380.769926 7.637493) (xy 380.854216 7.653249) (xy 380.939599 7.661161)
			(xy 381.025349 7.661161) (xy 381.110732 7.653249) (xy 381.195022 7.637493) (xy 381.277498 7.614026)
			(xy 381.357457 7.58305) (xy 381.434217 7.544828) (xy 381.507123 7.499687) (xy 381.575552 7.448011)
			(xy 381.638922 7.390242) (xy 381.688857 7.335466) (xy 464.704165 7.335466) (xy 464.704165 7.464606)
			(xy 464.712115 7.593501) (xy 464.727985 7.721661) (xy 464.751714 7.848602) (xy 464.783213 7.973841)
			(xy 464.822362 8.096904) (xy 464.869013 8.217323) (xy 464.922988 8.334642) (xy 464.984083 8.448416)
			(xy 465.052066 8.558213) (xy 465.12668 8.663616) (xy 465.207641 8.764226) (xy 465.294641 8.859661)
			(xy 465.387352 8.94956) (xy 465.485422 9.033581) (xy 465.588477 9.111405) (xy 465.696128 9.182737)
			(xy 465.807967 9.247307) (xy 465.923568 9.304869) (xy 466.042493 9.355206) (xy 466.164292 9.398126)
			(xy 466.288502 9.433467) (xy 466.414651 9.461094) (xy 466.542263 9.480903) (xy 466.670852 9.492819)
			(xy 466.79993 9.496796) (xy 466.929008 9.492819) (xy 467.057597 9.480903) (xy 467.185209 9.461094)
			(xy 467.311358 9.433467) (xy 467.435568 9.398126) (xy 467.557367 9.355206) (xy 467.676292 9.304869)
			(xy 467.791893 9.247307) (xy 467.903732 9.182737) (xy 468.011383 9.111405) (xy 468.114438 9.033581)
			(xy 468.212508 8.94956) (xy 468.305219 8.859661) (xy 468.392219 8.764226) (xy 468.47318 8.663616)
			(xy 468.547794 8.558213) (xy 468.615777 8.448416) (xy 468.676872 8.334642) (xy 468.730847 8.217323)
			(xy 468.777498 8.096904) (xy 468.816647 7.973841) (xy 468.848146 7.848602) (xy 468.871875 7.721661)
			(xy 468.887745 7.593501) (xy 468.895695 7.464606) (xy 468.896192 7.400036) (xy 468.895695 7.335466)
			(xy 468.887745 7.206571) (xy 468.871875 7.078411) (xy 468.848146 6.95147) (xy 468.816647 6.826231)
			(xy 468.777498 6.703168) (xy 468.730847 6.582749) (xy 468.676872 6.46543) (xy 468.615777 6.351656)
			(xy 468.547794 6.241859) (xy 468.47318 6.136456) (xy 468.392219 6.035846) (xy 468.305219 5.940411)
			(xy 468.212508 5.850512) (xy 468.114438 5.766491) (xy 468.011383 5.688667) (xy 467.903732 5.617335)
			(xy 467.791893 5.552765) (xy 467.676292 5.495203) (xy 467.557367 5.444866) (xy 467.435568 5.401946)
			(xy 467.311358 5.366605) (xy 467.185209 5.338978) (xy 467.057597 5.319169) (xy 466.929008 5.307253)
			(xy 466.79993 5.303277) (xy 466.670852 5.307253) (xy 466.542263 5.319169) (xy 466.414651 5.338978)
			(xy 466.288502 5.366605) (xy 466.164292 5.401946) (xy 466.042493 5.444866) (xy 465.923568 5.495203)
			(xy 465.807967 5.552765) (xy 465.696128 5.617335) (xy 465.588477 5.688667) (xy 465.485422 5.766491)
			(xy 465.387352 5.850512) (xy 465.294641 5.940411) (xy 465.207641 6.035846) (xy 465.12668 6.136456)
			(xy 465.052066 6.241859) (xy 464.984083 6.351656) (xy 464.922988 6.46543) (xy 464.869013 6.582749)
			(xy 464.822362 6.703168) (xy 464.783213 6.826231) (xy 464.751714 6.95147) (xy 464.727985 7.078411)
			(xy 464.712115 7.206571) (xy 464.704165 7.335466) (xy 381.688857 7.335466) (xy 381.696691 7.326872)
			(xy 381.748367 7.258443) (xy 381.793508 7.185537) (xy 381.83173 7.108777) (xy 381.862706 7.028818)
			(xy 381.886173 6.946342) (xy 381.901929 6.862052) (xy 381.909841 6.776669) (xy 381.910336 6.733794)
			(xy 381.909841 6.690919) (xy 381.901929 6.605536) (xy 381.886173 6.521246) (xy 381.862706 6.43877)
			(xy 381.83173 6.358811) (xy 381.793508 6.282051) (xy 381.748367 6.209145) (xy 381.696691 6.140716)
			(xy 381.638922 6.077346) (xy 381.575552 6.019577) (xy 381.507123 5.967901) (xy 381.434217 5.92276)
			(xy 381.357457 5.884538) (xy 381.277498 5.853562) (xy 381.195022 5.830095) (xy 381.110732 5.814339)
			(xy 381.025349 5.806427) (xy 380.939599 5.806427) (xy 380.854216 5.814339) (xy 380.769926 5.830095)
			(xy 380.68745 5.853562) (xy 380.607491 5.884538) (xy 380.530731 5.92276) (xy 380.457825 5.967901)
			(xy 380.389396 6.019577) (xy 380.326026 6.077346) (xy 380.268257 6.140716) (xy 380.216581 6.209145)
			(xy 380.17144 6.282051) (xy 380.133218 6.358811) (xy 380.102242 6.43877) (xy 380.078775 6.521246)
			(xy 380.063019 6.605536) (xy 380.055107 6.690919) (xy 375.559841 6.690919) (xy 375.551929 6.605536)
			(xy 375.536173 6.521246) (xy 375.512706 6.43877) (xy 375.48173 6.358811) (xy 375.443508 6.282051)
			(xy 375.398367 6.209145) (xy 375.346691 6.140716) (xy 375.288922 6.077346) (xy 375.225552 6.019577)
			(xy 375.157123 5.967901) (xy 375.084217 5.92276) (xy 375.007457 5.884538) (xy 374.927498 5.853562)
			(xy 374.845022 5.830095) (xy 374.760732 5.814339) (xy 374.675349 5.806427) (xy 374.589599 5.806427)
			(xy 374.504216 5.814339) (xy 374.419926 5.830095) (xy 374.33745 5.853562) (xy 374.257491 5.884538)
			(xy 374.180731 5.92276) (xy 374.107825 5.967901) (xy 374.039396 6.019577) (xy 373.976026 6.077346)
			(xy 373.918257 6.140716) (xy 373.866581 6.209145) (xy 373.82144 6.282051) (xy 373.783218 6.358811)
			(xy 373.752242 6.43877) (xy 373.728775 6.521246) (xy 373.713019 6.605536) (xy 373.705107 6.690919)
			(xy 343.693001 6.690919) (xy 343.685089 6.605536) (xy 343.669333 6.521246) (xy 343.645866 6.43877)
			(xy 343.61489 6.358811) (xy 343.576668 6.282051) (xy 343.531527 6.209145) (xy 343.479851 6.140716)
			(xy 343.422082 6.077346) (xy 343.358712 6.019577) (xy 343.290283 5.967901) (xy 343.217377 5.92276)
			(xy 343.140617 5.884538) (xy 343.060658 5.853562) (xy 342.978182 5.830095) (xy 342.893892 5.814339)
			(xy 342.808509 5.806427) (xy 342.722759 5.806427) (xy 342.637376 5.814339) (xy 342.553086 5.830095)
			(xy 342.47061 5.853562) (xy 342.390651 5.884538) (xy 342.313891 5.92276) (xy 342.240985 5.967901)
			(xy 342.172556 6.019577) (xy 342.109186 6.077346) (xy 342.051417 6.140716) (xy 341.999741 6.209145)
			(xy 341.9546 6.282051) (xy 341.916378 6.358811) (xy 341.885402 6.43877) (xy 341.861935 6.521246)
			(xy 341.846179 6.605536) (xy 341.838267 6.690919) (xy 337.343001 6.690919) (xy 337.335089 6.605536)
			(xy 337.319333 6.521246) (xy 337.295866 6.43877) (xy 337.26489 6.358811) (xy 337.226668 6.282051)
			(xy 337.181527 6.209145) (xy 337.129851 6.140716) (xy 337.072082 6.077346) (xy 337.008712 6.019577)
			(xy 336.940283 5.967901) (xy 336.867377 5.92276) (xy 336.790617 5.884538) (xy 336.710658 5.853562)
			(xy 336.628182 5.830095) (xy 336.543892 5.814339) (xy 336.458509 5.806427) (xy 336.372759 5.806427)
			(xy 336.287376 5.814339) (xy 336.203086 5.830095) (xy 336.12061 5.853562) (xy 336.040651 5.884538)
			(xy 335.963891 5.92276) (xy 335.890985 5.967901) (xy 335.822556 6.019577) (xy 335.759186 6.077346)
			(xy 335.701417 6.140716) (xy 335.649741 6.209145) (xy 335.6046 6.282051) (xy 335.566378 6.358811)
			(xy 335.535402 6.43877) (xy 335.511935 6.521246) (xy 335.496179 6.605536) (xy 335.488267 6.690919)
			(xy 333.050655 6.690919) (xy 333.042743 6.605536) (xy 333.026987 6.521246) (xy 333.00352 6.43877)
			(xy 332.972544 6.358811) (xy 332.934322 6.282051) (xy 332.889181 6.209145) (xy 332.837505 6.140716)
			(xy 332.779736 6.077346) (xy 332.716366 6.019577) (xy 332.647937 5.967901) (xy 332.575031 5.92276)
			(xy 332.498271 5.884538) (xy 332.418312 5.853562) (xy 332.335836 5.830095) (xy 332.251546 5.814339)
			(xy 332.166163 5.806427) (xy 332.080413 5.806427) (xy 331.99503 5.814339) (xy 331.91074 5.830095)
			(xy 331.828264 5.853562) (xy 331.748305 5.884538) (xy 331.671545 5.92276) (xy 331.598639 5.967901)
			(xy 331.53021 6.019577) (xy 331.46684 6.077346) (xy 331.409071 6.140716) (xy 331.357395 6.209145)
			(xy 331.312254 6.282051) (xy 331.274032 6.358811) (xy 331.243056 6.43877) (xy 331.219589 6.521246)
			(xy 331.203833 6.605536) (xy 331.195921 6.690919) (xy 326.700655 6.690919) (xy 326.692743 6.605536)
			(xy 326.676987 6.521246) (xy 326.65352 6.43877) (xy 326.622544 6.358811) (xy 326.584322 6.282051)
			(xy 326.539181 6.209145) (xy 326.487505 6.140716) (xy 326.429736 6.077346) (xy 326.366366 6.019577)
			(xy 326.297937 5.967901) (xy 326.225031 5.92276) (xy 326.148271 5.884538) (xy 326.068312 5.853562)
			(xy 325.985836 5.830095) (xy 325.901546 5.814339) (xy 325.816163 5.806427) (xy 325.730413 5.806427)
			(xy 325.64503 5.814339) (xy 325.56074 5.830095) (xy 325.478264 5.853562) (xy 325.398305 5.884538)
			(xy 325.321545 5.92276) (xy 325.248639 5.967901) (xy 325.18021 6.019577) (xy 325.11684 6.077346)
			(xy 325.059071 6.140716) (xy 325.007395 6.209145) (xy 324.962254 6.282051) (xy 324.924032 6.358811)
			(xy 324.893056 6.43877) (xy 324.869589 6.521246) (xy 324.853833 6.605536) (xy 324.845921 6.690919)
			(xy 265.125975 6.690919) (xy 265.118063 6.605536) (xy 265.102307 6.521246) (xy 265.07884 6.43877)
			(xy 265.047864 6.358811) (xy 265.009642 6.282051) (xy 264.964501 6.209145) (xy 264.912825 6.140716)
			(xy 264.855056 6.077346) (xy 264.791686 6.019577) (xy 264.723257 5.967901) (xy 264.650351 5.92276)
			(xy 264.573591 5.884538) (xy 264.493632 5.853562) (xy 264.411156 5.830095) (xy 264.326866 5.814339)
			(xy 264.241483 5.806427) (xy 264.155733 5.806427) (xy 264.07035 5.814339) (xy 263.98606 5.830095)
			(xy 263.903584 5.853562) (xy 263.823625 5.884538) (xy 263.746865 5.92276) (xy 263.673959 5.967901)
			(xy 263.60553 6.019577) (xy 263.54216 6.077346) (xy 263.484391 6.140716) (xy 263.432715 6.209145)
			(xy 263.387574 6.282051) (xy 263.349352 6.358811) (xy 263.318376 6.43877) (xy 263.294909 6.521246)
			(xy 263.279153 6.605536) (xy 263.271241 6.690919) (xy 258.775975 6.690919) (xy 258.768063 6.605536)
			(xy 258.752307 6.521246) (xy 258.72884 6.43877) (xy 258.697864 6.358811) (xy 258.659642 6.282051)
			(xy 258.614501 6.209145) (xy 258.562825 6.140716) (xy 258.505056 6.077346) (xy 258.441686 6.019577)
			(xy 258.373257 5.967901) (xy 258.300351 5.92276) (xy 258.223591 5.884538) (xy 258.143632 5.853562)
			(xy 258.061156 5.830095) (xy 257.976866 5.814339) (xy 257.891483 5.806427) (xy 257.805733 5.806427)
			(xy 257.72035 5.814339) (xy 257.63606 5.830095) (xy 257.553584 5.853562) (xy 257.473625 5.884538)
			(xy 257.396865 5.92276) (xy 257.323959 5.967901) (xy 257.25553 6.019577) (xy 257.19216 6.077346)
			(xy 257.134391 6.140716) (xy 257.082715 6.209145) (xy 257.037574 6.282051) (xy 256.999352 6.358811)
			(xy 256.968376 6.43877) (xy 256.944909 6.521246) (xy 256.929153 6.605536) (xy 256.921241 6.690919)
			(xy 254.465119 6.690919) (xy 254.465087 6.688125) (xy 254.457175 6.602742) (xy 254.441419 6.518452)
			(xy 254.417952 6.435976) (xy 254.386976 6.356017) (xy 254.348754 6.279257) (xy 254.303613 6.206351)
			(xy 254.251937 6.137922) (xy 254.194168 6.074552) (xy 254.130798 6.016783) (xy 254.062369 5.965107)
			(xy 253.989463 5.919966) (xy 253.912703 5.881744) (xy 253.832744 5.850768) (xy 253.750268 5.827301)
			(xy 253.665978 5.811545) (xy 253.580595 5.803633) (xy 253.494845 5.803633) (xy 253.409462 5.811545)
			(xy 253.325172 5.827301) (xy 253.242696 5.850768) (xy 253.162737 5.881744) (xy 253.085977 5.919966)
			(xy 253.013071 5.965107) (xy 252.944642 6.016783) (xy 252.881272 6.074552) (xy 252.823503 6.137922)
			(xy 252.771827 6.206351) (xy 252.726686 6.279257) (xy 252.688464 6.356017) (xy 252.657488 6.435976)
			(xy 252.634021 6.518452) (xy 252.618265 6.602742) (xy 252.610353 6.688125) (xy 248.115087 6.688125)
			(xy 248.107175 6.602742) (xy 248.091419 6.518452) (xy 248.067952 6.435976) (xy 248.036976 6.356017)
			(xy 247.998754 6.279257) (xy 247.953613 6.206351) (xy 247.901937 6.137922) (xy 247.844168 6.074552)
			(xy 247.780798 6.016783) (xy 247.712369 5.965107) (xy 247.639463 5.919966) (xy 247.562703 5.881744)
			(xy 247.482744 5.850768) (xy 247.400268 5.827301) (xy 247.315978 5.811545) (xy 247.230595 5.803633)
			(xy 247.144845 5.803633) (xy 247.059462 5.811545) (xy 246.975172 5.827301) (xy 246.892696 5.850768)
			(xy 246.812737 5.881744) (xy 246.735977 5.919966) (xy 246.663071 5.965107) (xy 246.594642 6.016783)
			(xy 246.531272 6.074552) (xy 246.473503 6.137922) (xy 246.421827 6.206351) (xy 246.376686 6.279257)
			(xy 246.338464 6.356017) (xy 246.307488 6.435976) (xy 246.284021 6.518452) (xy 246.268265 6.602742)
			(xy 246.260353 6.688125) (xy 186.540407 6.688125) (xy 186.532495 6.602742) (xy 186.516739 6.518452)
			(xy 186.493272 6.435976) (xy 186.462296 6.356017) (xy 186.424074 6.279257) (xy 186.378933 6.206351)
			(xy 186.327257 6.137922) (xy 186.269488 6.074552) (xy 186.206118 6.016783) (xy 186.137689 5.965107)
			(xy 186.064783 5.919966) (xy 185.988023 5.881744) (xy 185.908064 5.850768) (xy 185.825588 5.827301)
			(xy 185.741298 5.811545) (xy 185.655915 5.803633) (xy 185.570165 5.803633) (xy 185.484782 5.811545)
			(xy 185.400492 5.827301) (xy 185.318016 5.850768) (xy 185.238057 5.881744) (xy 185.161297 5.919966)
			(xy 185.088391 5.965107) (xy 185.019962 6.016783) (xy 184.956592 6.074552) (xy 184.898823 6.137922)
			(xy 184.847147 6.206351) (xy 184.802006 6.279257) (xy 184.763784 6.356017) (xy 184.732808 6.435976)
			(xy 184.709341 6.518452) (xy 184.693585 6.602742) (xy 184.685673 6.688125) (xy 180.190407 6.688125)
			(xy 180.182495 6.602742) (xy 180.166739 6.518452) (xy 180.143272 6.435976) (xy 180.112296 6.356017)
			(xy 180.074074 6.279257) (xy 180.028933 6.206351) (xy 179.977257 6.137922) (xy 179.919488 6.074552)
			(xy 179.856118 6.016783) (xy 179.787689 5.965107) (xy 179.714783 5.919966) (xy 179.638023 5.881744)
			(xy 179.558064 5.850768) (xy 179.475588 5.827301) (xy 179.391298 5.811545) (xy 179.305915 5.803633)
			(xy 179.220165 5.803633) (xy 179.134782 5.811545) (xy 179.050492 5.827301) (xy 178.968016 5.850768)
			(xy 178.888057 5.881744) (xy 178.811297 5.919966) (xy 178.738391 5.965107) (xy 178.669962 6.016783)
			(xy 178.606592 6.074552) (xy 178.548823 6.137922) (xy 178.497147 6.206351) (xy 178.452006 6.279257)
			(xy 178.413784 6.356017) (xy 178.382808 6.435976) (xy 178.359341 6.518452) (xy 178.343585 6.602742)
			(xy 178.335673 6.688125) (xy 6.97173 6.688125) (xy 6.930907 6.582749) (xy 6.876932 6.46543) (xy 6.815837 6.351656)
			(xy 6.747854 6.241859) (xy 6.67324 6.136456) (xy 6.592279 6.035846) (xy 6.505279 5.940411) (xy 6.412568 5.850512)
			(xy 6.314498 5.766491) (xy 6.211443 5.688667) (xy 6.103792 5.617335) (xy 5.991953 5.552765) (xy 5.876352 5.495203)
			(xy 5.757427 5.444866) (xy 5.635628 5.401946) (xy 5.511418 5.366605) (xy 5.385269 5.338978) (xy 5.257657 5.319169)
			(xy 5.129068 5.307253) (xy 4.99999 5.303277) (xy 4.870912 5.307253) (xy 4.742323 5.319169) (xy 4.614711 5.338978)
			(xy 4.488562 5.366605) (xy 4.364352 5.401946) (xy 4.242553 5.444866) (xy 4.123628 5.495203) (xy 4.008027 5.552765)
			(xy 3.896188 5.617335) (xy 3.788537 5.688667) (xy 3.685482 5.766491) (xy 3.587412 5.850512) (xy 3.494701 5.940411)
			(xy 3.407701 6.035846) (xy 3.32674 6.136456) (xy 3.252126 6.241859) (xy 3.184143 6.351656) (xy 3.123048 6.46543)
			(xy 3.069073 6.582749) (xy 3.022422 6.703168) (xy 2.983273 6.826231) (xy 2.951774 6.95147) (xy 2.928045 7.078411)
			(xy 2.912175 7.206571) (xy 2.904225 7.335466) (xy 0.508 7.335466) (xy 0.508 4.148125) (xy 178.335673 4.148125)
			(xy 178.335673 4.233875) (xy 178.343585 4.319258) (xy 178.359341 4.403548) (xy 178.382808 4.486024)
			(xy 178.413784 4.565983) (xy 178.452006 4.642743) (xy 178.497147 4.715649) (xy 178.548823 4.784078)
			(xy 178.606592 4.847448) (xy 178.669962 4.905217) (xy 178.738391 4.956893) (xy 178.811297 5.002034)
			(xy 178.888057 5.040256) (xy 178.968016 5.071232) (xy 179.050492 5.094699) (xy 179.134782 5.110455)
			(xy 179.220165 5.118367) (xy 179.305915 5.118367) (xy 179.391298 5.110455) (xy 179.475588 5.094699)
			(xy 179.558064 5.071232) (xy 179.638023 5.040256) (xy 179.714783 5.002034) (xy 179.787689 4.956893)
			(xy 179.843296 4.9149) (xy 182.494428 4.9149) (xy 182.494428 6.01218) (xy 182.49483 6.024265) (xy 182.502297 6.047253)
			(xy 182.516504 6.066807) (xy 182.536061 6.081011) (xy 182.559051 6.088472) (xy 182.571136 6.088888)
			(xy 183.183276 6.088888) (xy 183.191737 6.088707) (xy 183.208271 6.085126) (xy 183.216042 6.081776)
			(xy 183.229014 6.076165) (xy 183.2569 6.071627) (xy 183.284963 6.074905) (xy 183.311052 6.085748)
			(xy 183.333171 6.103326) (xy 183.341772 6.114542) (xy 183.35718 6.135401) (xy 183.392753 6.173134)
			(xy 183.433113 6.205698) (xy 183.477513 6.232492) (xy 183.525134 6.253022) (xy 183.575099 6.266907)
			(xy 183.626485 6.273893) (xy 183.652414 6.274308) (xy 183.67967 6.27379) (xy 183.733628 6.266034)
			(xy 183.785934 6.250682) (xy 183.835524 6.228046) (xy 183.88139 6.198586) (xy 183.9226 6.162902)
			(xy 183.958315 6.12172) (xy 183.987809 6.075875) (xy 184.010482 6.026302) (xy 184.025873 5.974008)
			(xy 184.033669 5.920056) (xy 184.034176 5.8928) (xy 184.034176 5.0292) (xy 184.033744 5.001934) (xy 184.025979 4.947958)
			(xy 184.010609 4.895637) (xy 183.987946 4.846038) (xy 183.958451 4.800171) (xy 183.922726 4.758971)
			(xy 183.881499 4.723277) (xy 183.83561 4.693817) (xy 183.785994 4.671191) (xy 183.733662 4.65586)
			(xy 183.67968 4.648136) (xy 183.652414 4.647692) (xy 183.626229 4.648097) (xy 183.574353 4.655277)
			(xy 183.523944 4.669478) (xy 183.475948 4.690433) (xy 183.431266 4.717749) (xy 183.390734 4.750913)
			(xy 183.355114 4.789304) (xy 183.33974 4.810506) (xy 183.33123 4.821719) (xy 183.30938 4.839443)
			(xy 183.28353 4.850553) (xy 183.255634 4.854209) (xy 183.227795 4.850136) (xy 183.214772 4.844796)
			(xy 183.207261 4.841727) (xy 183.191387 4.838389) (xy 183.183276 4.838192) (xy 182.571136 4.838192)
			(xy 182.559055 4.838643) (xy 182.536074 4.846101) (xy 182.516523 4.860297) (xy 182.502317 4.879841)
			(xy 182.494849 4.902819) (xy 182.494428 4.9149) (xy 179.843296 4.9149) (xy 179.856118 4.905217) (xy 179.919488 4.847448)
			(xy 179.977257 4.784078) (xy 180.028933 4.715649) (xy 180.074074 4.642743) (xy 180.112296 4.565983)
			(xy 180.143272 4.486024) (xy 180.166739 4.403548) (xy 180.182495 4.319258) (xy 180.190407 4.233875)
			(xy 180.190902 4.191) (xy 180.190407 4.148125) (xy 184.685673 4.148125) (xy 184.685673 4.233875)
			(xy 184.693585 4.319258) (xy 184.709341 4.403548) (xy 184.732808 4.486024) (xy 184.763784 4.565983)
			(xy 184.802006 4.642743) (xy 184.847147 4.715649) (xy 184.898823 4.784078) (xy 184.956592 4.847448)
			(xy 185.019962 4.905217) (xy 185.088391 4.956893) (xy 185.161297 5.002034) (xy 185.238057 5.040256)
			(xy 185.318016 5.071232) (xy 185.400492 5.094699) (xy 185.484782 5.110455) (xy 185.570165 5.118367)
			(xy 185.655915 5.118367) (xy 185.741298 5.110455) (xy 185.825588 5.094699) (xy 185.908064 5.071232)
			(xy 185.988023 5.040256) (xy 186.064783 5.002034) (xy 186.137689 4.956893) (xy 186.206118 4.905217)
			(xy 186.269488 4.847448) (xy 186.327257 4.784078) (xy 186.378933 4.715649) (xy 186.424074 4.642743)
			(xy 186.462296 4.565983) (xy 186.493272 4.486024) (xy 186.516739 4.403548) (xy 186.532495 4.319258)
			(xy 186.540407 4.233875) (xy 186.540902 4.191) (xy 186.540407 4.148125) (xy 246.260353 4.148125)
			(xy 246.260353 4.233875) (xy 246.268265 4.319258) (xy 246.284021 4.403548) (xy 246.307488 4.486024)
			(xy 246.338464 4.565983) (xy 246.376686 4.642743) (xy 246.421827 4.715649) (xy 246.473503 4.784078)
			(xy 246.531272 4.847448) (xy 246.594642 4.905217) (xy 246.663071 4.956893) (xy 246.735977 5.002034)
			(xy 246.812737 5.040256) (xy 246.892696 5.071232) (xy 246.975172 5.094699) (xy 247.059462 5.110455)
			(xy 247.144845 5.118367) (xy 247.230595 5.118367) (xy 247.315978 5.110455) (xy 247.400268 5.094699)
			(xy 247.482744 5.071232) (xy 247.562703 5.040256) (xy 247.584906 5.0292) (xy 248.766584 5.0292) (xy 248.766584 5.8928)
			(xy 248.767056 5.920064) (xy 248.774819 5.974037) (xy 248.790188 6.026354) (xy 248.812848 6.075951)
			(xy 248.842339 6.121816) (xy 248.87806 6.163015) (xy 248.919282 6.198708) (xy 248.965166 6.22817)
			(xy 249.014777 6.250798) (xy 249.067104 6.266133) (xy 249.121082 6.273861) (xy 249.148346 6.274308)
			(xy 249.17453 6.273873) (xy 249.226405 6.266698) (xy 249.276813 6.252502) (xy 249.324809 6.231553)
			(xy 249.369492 6.204241) (xy 249.410024 6.171081) (xy 249.445646 6.132694) (xy 249.46102 6.111494)
			(xy 249.469477 6.100237) (xy 249.491343 6.082514) (xy 249.517206 6.071412) (xy 249.545116 6.067767)
			(xy 249.572963 6.071855) (xy 249.585988 6.077204) (xy 249.593492 6.080291) (xy 249.609372 6.083617)
			(xy 249.617484 6.083808) (xy 250.229624 6.083808) (xy 250.2417 6.083356) (xy 250.264668 6.075887)
			(xy 250.284204 6.061687) (xy 250.298398 6.042146) (xy 250.30586 6.019176) (xy 250.306332 6.0071)
			(xy 250.306332 4.90982) (xy 250.305819 4.897749) (xy 250.298365 4.874786) (xy 250.28418 4.855251)
			(xy 250.264653 4.841055) (xy 250.241695 4.833588) (xy 250.229624 4.833112) (xy 249.617484 4.833112)
			(xy 249.609023 4.83328) (xy 249.592488 4.83687) (xy 249.584718 4.840224) (xy 249.571762 4.845876)
			(xy 249.543868 4.850406) (xy 249.5158 4.847119) (xy 249.489708 4.836266) (xy 249.467588 4.818678)
			(xy 249.458988 4.807458) (xy 249.443604 4.78658) (xy 249.408027 4.748847) (xy 249.367664 4.716285)
			(xy 249.323259 4.689493) (xy 249.275634 4.668967) (xy 249.225665 4.655085) (xy 249.174277 4.648104)
			(xy 249.148346 4.647692) (xy 249.121091 4.648266) (xy 249.067136 4.656014) (xy 249.014831 4.671358)
			(xy 248.965241 4.693987) (xy 248.919374 4.72344) (xy 248.878164 4.759119) (xy 248.842448 4.800297)
			(xy 248.812953 4.846137) (xy 248.790279 4.895706) (xy 248.774888 4.947997) (xy 248.767091 5.001946)
			(xy 248.766584 5.0292) (xy 247.584906 5.0292) (xy 247.639463 5.002034) (xy 247.712369 4.956893) (xy 247.780798 4.905217)
			(xy 247.844168 4.847448) (xy 247.901937 4.784078) (xy 247.953613 4.715649) (xy 247.998754 4.642743)
			(xy 248.036976 4.565983) (xy 248.067952 4.486024) (xy 248.091419 4.403548) (xy 248.107175 4.319258)
			(xy 248.115087 4.233875) (xy 248.115582 4.191) (xy 248.115087 4.148125) (xy 252.610353 4.148125)
			(xy 252.610353 4.233875) (xy 252.618265 4.319258) (xy 252.634021 4.403548) (xy 252.657488 4.486024)
			(xy 252.688464 4.565983) (xy 252.726686 4.642743) (xy 252.771827 4.715649) (xy 252.823503 4.784078)
			(xy 252.881272 4.847448) (xy 252.944642 4.905217) (xy 253.013071 4.956893) (xy 253.085977 5.002034)
			(xy 253.162737 5.040256) (xy 253.242696 5.071232) (xy 253.325172 5.094699) (xy 253.409462 5.110455)
			(xy 253.494845 5.118367) (xy 253.580595 5.118367) (xy 253.665978 5.110455) (xy 253.750268 5.094699)
			(xy 253.832744 5.071232) (xy 253.912703 5.040256) (xy 253.989463 5.002034) (xy 254.062369 4.956893)
			(xy 254.130798 4.905217) (xy 254.194168 4.847448) (xy 254.251937 4.784078) (xy 254.303613 4.715649)
			(xy 254.348754 4.642743) (xy 254.386976 4.565983) (xy 254.417952 4.486024) (xy 254.441419 4.403548)
			(xy 254.457175 4.319258) (xy 254.465087 4.233875) (xy 254.465582 4.191) (xy 254.465119 4.150919)
			(xy 256.921241 4.150919) (xy 256.921241 4.236669) (xy 256.929153 4.322052) (xy 256.944909 4.406342)
			(xy 256.968376 4.488818) (xy 256.999352 4.568777) (xy 257.037574 4.645537) (xy 257.082715 4.718443)
			(xy 257.134391 4.786872) (xy 257.19216 4.850242) (xy 257.25553 4.908011) (xy 257.323959 4.959687)
			(xy 257.396865 5.004828) (xy 257.473625 5.04305) (xy 257.553584 5.074026) (xy 257.63606 5.097493)
			(xy 257.72035 5.113249) (xy 257.805733 5.121161) (xy 257.891483 5.121161) (xy 257.976866 5.113249)
			(xy 258.061156 5.097493) (xy 258.143632 5.074026) (xy 258.223591 5.04305) (xy 258.245794 5.031994)
			(xy 261.85622 5.031994) (xy 261.85622 5.895594) (xy 261.856706 5.922863) (xy 261.864468 5.976847)
			(xy 261.879833 6.029177) (xy 261.90249 6.078787) (xy 261.931976 6.124668) (xy 261.967691 6.165885)
			(xy 262.008908 6.2016) (xy 262.054789 6.231086) (xy 262.104399 6.253743) (xy 262.156729 6.269108)
			(xy 262.210713 6.27687) (xy 262.265251 6.27687) (xy 262.319235 6.269108) (xy 262.371565 6.253743)
			(xy 262.421175 6.231086) (xy 262.467056 6.2016) (xy 262.508273 6.165885) (xy 262.543988 6.124668)
			(xy 262.573474 6.078787) (xy 262.596131 6.029177) (xy 262.611496 5.976847) (xy 262.619258 5.922863)
			(xy 262.619744 5.895594) (xy 262.619744 5.031994) (xy 262.619258 5.004725) (xy 262.611496 4.950741)
			(xy 262.596131 4.898411) (xy 262.573474 4.848801) (xy 262.543988 4.80292) (xy 262.508273 4.761703)
			(xy 262.467056 4.725988) (xy 262.421175 4.696502) (xy 262.371565 4.673845) (xy 262.319235 4.65848)
			(xy 262.265251 4.650718) (xy 262.210713 4.650718) (xy 262.156729 4.65848) (xy 262.104399 4.673845)
			(xy 262.054789 4.696502) (xy 262.008908 4.725988) (xy 261.967691 4.761703) (xy 261.931976 4.80292)
			(xy 261.90249 4.848801) (xy 261.879833 4.898411) (xy 261.864468 4.950741) (xy 261.856706 5.004725)
			(xy 261.85622 5.031994) (xy 258.245794 5.031994) (xy 258.300351 5.004828) (xy 258.373257 4.959687)
			(xy 258.441686 4.908011) (xy 258.505056 4.850242) (xy 258.562825 4.786872) (xy 258.614501 4.718443)
			(xy 258.659642 4.645537) (xy 258.697864 4.568777) (xy 258.72884 4.488818) (xy 258.752307 4.406342)
			(xy 258.768063 4.322052) (xy 258.775975 4.236669) (xy 258.77647 4.193794) (xy 258.775975 4.150919)
			(xy 263.271241 4.150919) (xy 263.271241 4.236669) (xy 263.279153 4.322052) (xy 263.294909 4.406342)
			(xy 263.318376 4.488818) (xy 263.349352 4.568777) (xy 263.387574 4.645537) (xy 263.432715 4.718443)
			(xy 263.484391 4.786872) (xy 263.54216 4.850242) (xy 263.60553 4.908011) (xy 263.673959 4.959687)
			(xy 263.746865 5.004828) (xy 263.823625 5.04305) (xy 263.903584 5.074026) (xy 263.98606 5.097493)
			(xy 264.07035 5.113249) (xy 264.155733 5.121161) (xy 264.241483 5.121161) (xy 264.326866 5.113249)
			(xy 264.411156 5.097493) (xy 264.493632 5.074026) (xy 264.573591 5.04305) (xy 264.650351 5.004828)
			(xy 264.723257 4.959687) (xy 264.791686 4.908011) (xy 264.855056 4.850242) (xy 264.912825 4.786872)
			(xy 264.964501 4.718443) (xy 265.009642 4.645537) (xy 265.047864 4.568777) (xy 265.07884 4.488818)
			(xy 265.102307 4.406342) (xy 265.118063 4.322052) (xy 265.125975 4.236669) (xy 265.12647 4.193794)
			(xy 265.125975 4.150919) (xy 324.845921 4.150919) (xy 324.845921 4.236669) (xy 324.853833 4.322052)
			(xy 324.869589 4.406342) (xy 324.893056 4.488818) (xy 324.924032 4.568777) (xy 324.962254 4.645537)
			(xy 325.007395 4.718443) (xy 325.059071 4.786872) (xy 325.11684 4.850242) (xy 325.18021 4.908011)
			(xy 325.248639 4.959687) (xy 325.321545 5.004828) (xy 325.398305 5.04305) (xy 325.478264 5.074026)
			(xy 325.56074 5.097493) (xy 325.64503 5.113249) (xy 325.730413 5.121161) (xy 325.816163 5.121161)
			(xy 325.901546 5.113249) (xy 325.985836 5.097493) (xy 326.068312 5.074026) (xy 326.148271 5.04305)
			(xy 326.170474 5.031994) (xy 327.352152 5.031994) (xy 327.352152 5.895594) (xy 327.352638 5.922863)
			(xy 327.3604 5.976847) (xy 327.375765 6.029177) (xy 327.398422 6.078787) (xy 327.427908 6.124668)
			(xy 327.463623 6.165885) (xy 327.50484 6.2016) (xy 327.550721 6.231086) (xy 327.600331 6.253743)
			(xy 327.652661 6.269108) (xy 327.706645 6.27687) (xy 327.761183 6.27687) (xy 327.815167 6.269108)
			(xy 327.867497 6.253743) (xy 327.917107 6.231086) (xy 327.962988 6.2016) (xy 328.004205 6.165885)
			(xy 328.03992 6.124668) (xy 328.069406 6.078787) (xy 328.092063 6.029177) (xy 328.107428 5.976847)
			(xy 328.11519 5.922863) (xy 328.115676 5.895594) (xy 328.115676 5.031994) (xy 328.11519 5.004725)
			(xy 328.107428 4.950741) (xy 328.092063 4.898411) (xy 328.069406 4.848801) (xy 328.03992 4.80292)
			(xy 328.004205 4.761703) (xy 327.962988 4.725988) (xy 327.917107 4.696502) (xy 327.867497 4.673845)
			(xy 327.815167 4.65848) (xy 327.761183 4.650718) (xy 327.706645 4.650718) (xy 327.652661 4.65848)
			(xy 327.600331 4.673845) (xy 327.550721 4.696502) (xy 327.50484 4.725988) (xy 327.463623 4.761703)
			(xy 327.427908 4.80292) (xy 327.398422 4.848801) (xy 327.375765 4.898411) (xy 327.3604 4.950741)
			(xy 327.352638 5.004725) (xy 327.352152 5.031994) (xy 326.170474 5.031994) (xy 326.225031 5.004828)
			(xy 326.297937 4.959687) (xy 326.366366 4.908011) (xy 326.429736 4.850242) (xy 326.487505 4.786872)
			(xy 326.539181 4.718443) (xy 326.584322 4.645537) (xy 326.622544 4.568777) (xy 326.65352 4.488818)
			(xy 326.676987 4.406342) (xy 326.692743 4.322052) (xy 326.700655 4.236669) (xy 326.70115 4.193794)
			(xy 326.700655 4.150919) (xy 331.195921 4.150919) (xy 331.195921 4.236669) (xy 331.203833 4.322052)
			(xy 331.219589 4.406342) (xy 331.243056 4.488818) (xy 331.274032 4.568777) (xy 331.312254 4.645537)
			(xy 331.357395 4.718443) (xy 331.409071 4.786872) (xy 331.46684 4.850242) (xy 331.53021 4.908011)
			(xy 331.598639 4.959687) (xy 331.671545 5.004828) (xy 331.748305 5.04305) (xy 331.828264 5.074026)
			(xy 331.91074 5.097493) (xy 331.99503 5.113249) (xy 332.080413 5.121161) (xy 332.166163 5.121161)
			(xy 332.251546 5.113249) (xy 332.335836 5.097493) (xy 332.418312 5.074026) (xy 332.498271 5.04305)
			(xy 332.575031 5.004828) (xy 332.647937 4.959687) (xy 332.716366 4.908011) (xy 332.779736 4.850242)
			(xy 332.837505 4.786872) (xy 332.889181 4.718443) (xy 332.934322 4.645537) (xy 332.972544 4.568777)
			(xy 333.00352 4.488818) (xy 333.026987 4.406342) (xy 333.042743 4.322052) (xy 333.050655 4.236669)
			(xy 333.05115 4.193794) (xy 333.050655 4.150919) (xy 335.488267 4.150919) (xy 335.488267 4.236669)
			(xy 335.496179 4.322052) (xy 335.511935 4.406342) (xy 335.535402 4.488818) (xy 335.566378 4.568777)
			(xy 335.6046 4.645537) (xy 335.649741 4.718443) (xy 335.701417 4.786872) (xy 335.759186 4.850242)
			(xy 335.822556 4.908011) (xy 335.890985 4.959687) (xy 335.963891 5.004828) (xy 336.040651 5.04305)
			(xy 336.12061 5.074026) (xy 336.203086 5.097493) (xy 336.287376 5.113249) (xy 336.372759 5.121161)
			(xy 336.458509 5.121161) (xy 336.543892 5.113249) (xy 336.628182 5.097493) (xy 336.710658 5.074026)
			(xy 336.790617 5.04305) (xy 336.81282 5.031994) (xy 340.4235 5.031994) (xy 340.4235 5.895594) (xy 340.423986 5.922845)
			(xy 340.431742 5.976793) (xy 340.447097 6.029088) (xy 340.469739 6.078665) (xy 340.499205 6.124515)
			(xy 340.534896 6.165706) (xy 340.576087 6.201397) (xy 340.621937 6.230863) (xy 340.671514 6.253505)
			(xy 340.723809 6.26886) (xy 340.777757 6.276616) (xy 340.832259 6.276616) (xy 340.886207 6.26886)
			(xy 340.938502 6.253505) (xy 340.988079 6.230863) (xy 341.033929 6.201397) (xy 341.07512 6.165706)
			(xy 341.110811 6.124515) (xy 341.140277 6.078665) (xy 341.162919 6.029088) (xy 341.178274 5.976793)
			(xy 341.18603 5.922845) (xy 341.186516 5.895594) (xy 341.186516 5.031994) (xy 341.18603 5.004743)
			(xy 341.178274 4.950795) (xy 341.162919 4.8985) (xy 341.140277 4.848923) (xy 341.110811 4.803073)
			(xy 341.07512 4.761882) (xy 341.033929 4.726191) (xy 340.988079 4.696725) (xy 340.938502 4.674083)
			(xy 340.886207 4.658728) (xy 340.832259 4.650972) (xy 340.777757 4.650972) (xy 340.723809 4.658728)
			(xy 340.671514 4.674083) (xy 340.621937 4.696725) (xy 340.576087 4.726191) (xy 340.534896 4.761882)
			(xy 340.499205 4.803073) (xy 340.469739 4.848923) (xy 340.447097 4.8985) (xy 340.431742 4.950795)
			(xy 340.423986 5.004743) (xy 340.4235 5.031994) (xy 336.81282 5.031994) (xy 336.867377 5.004828)
			(xy 336.940283 4.959687) (xy 337.008712 4.908011) (xy 337.072082 4.850242) (xy 337.129851 4.786872)
			(xy 337.181527 4.718443) (xy 337.226668 4.645537) (xy 337.26489 4.568777) (xy 337.295866 4.488818)
			(xy 337.319333 4.406342) (xy 337.335089 4.322052) (xy 337.343001 4.236669) (xy 337.343496 4.193794)
			(xy 337.343001 4.150919) (xy 341.838267 4.150919) (xy 341.838267 4.236669) (xy 341.846179 4.322052)
			(xy 341.861935 4.406342) (xy 341.885402 4.488818) (xy 341.916378 4.568777) (xy 341.9546 4.645537)
			(xy 341.999741 4.718443) (xy 342.051417 4.786872) (xy 342.109186 4.850242) (xy 342.172556 4.908011)
			(xy 342.240985 4.959687) (xy 342.313891 5.004828) (xy 342.390651 5.04305) (xy 342.47061 5.074026)
			(xy 342.553086 5.097493) (xy 342.637376 5.113249) (xy 342.722759 5.121161) (xy 342.808509 5.121161)
			(xy 342.893892 5.113249) (xy 342.978182 5.097493) (xy 343.060658 5.074026) (xy 343.140617 5.04305)
			(xy 343.217377 5.004828) (xy 343.290283 4.959687) (xy 343.358712 4.908011) (xy 343.422082 4.850242)
			(xy 343.479851 4.786872) (xy 343.531527 4.718443) (xy 343.576668 4.645537) (xy 343.61489 4.568777)
			(xy 343.645866 4.488818) (xy 343.669333 4.406342) (xy 343.685089 4.322052) (xy 343.693001 4.236669)
			(xy 343.693496 4.193794) (xy 343.693001 4.150919) (xy 373.705107 4.150919) (xy 373.705107 4.236669)
			(xy 373.713019 4.322052) (xy 373.728775 4.406342) (xy 373.752242 4.488818) (xy 373.783218 4.568777)
			(xy 373.82144 4.645537) (xy 373.866581 4.718443) (xy 373.918257 4.786872) (xy 373.976026 4.850242)
			(xy 374.039396 4.908011) (xy 374.107825 4.959687) (xy 374.180731 5.004828) (xy 374.257491 5.04305)
			(xy 374.33745 5.074026) (xy 374.419926 5.097493) (xy 374.504216 5.113249) (xy 374.589599 5.121161)
			(xy 374.675349 5.121161) (xy 374.760732 5.113249) (xy 374.845022 5.097493) (xy 374.927498 5.074026)
			(xy 375.007457 5.04305) (xy 375.02966 5.031994) (xy 376.211592 5.031994) (xy 376.211592 5.895594)
			(xy 376.212078 5.922845) (xy 376.219834 5.976793) (xy 376.235189 6.029088) (xy 376.257831 6.078665)
			(xy 376.287297 6.124515) (xy 376.322988 6.165706) (xy 376.364179 6.201397) (xy 376.410029 6.230863)
			(xy 376.459606 6.253505) (xy 376.511901 6.26886) (xy 376.565849 6.276616) (xy 376.620351 6.276616)
			(xy 376.674299 6.26886) (xy 376.726594 6.253505) (xy 376.776171 6.230863) (xy 376.822021 6.201397)
			(xy 376.863212 6.165706) (xy 376.898903 6.124515) (xy 376.928369 6.078665) (xy 376.951011 6.029088)
			(xy 376.966366 5.976793) (xy 376.974122 5.922845) (xy 376.974608 5.895594) (xy 376.974608 5.031994)
			(xy 376.974122 5.004743) (xy 376.966366 4.950795) (xy 376.951011 4.8985) (xy 376.928369 4.848923)
			(xy 376.898903 4.803073) (xy 376.863212 4.761882) (xy 376.822021 4.726191) (xy 376.776171 4.696725)
			(xy 376.726594 4.674083) (xy 376.674299 4.658728) (xy 376.620351 4.650972) (xy 376.565849 4.650972)
			(xy 376.511901 4.658728) (xy 376.459606 4.674083) (xy 376.410029 4.696725) (xy 376.364179 4.726191)
			(xy 376.322988 4.761882) (xy 376.287297 4.803073) (xy 376.257831 4.848923) (xy 376.235189 4.8985)
			(xy 376.219834 4.950795) (xy 376.212078 5.004743) (xy 376.211592 5.031994) (xy 375.02966 5.031994)
			(xy 375.084217 5.004828) (xy 375.157123 4.959687) (xy 375.225552 4.908011) (xy 375.288922 4.850242)
			(xy 375.346691 4.786872) (xy 375.398367 4.718443) (xy 375.443508 4.645537) (xy 375.48173 4.568777)
			(xy 375.512706 4.488818) (xy 375.536173 4.406342) (xy 375.551929 4.322052) (xy 375.559841 4.236669)
			(xy 375.560336 4.193794) (xy 375.559841 4.150919) (xy 380.055107 4.150919) (xy 380.055107 4.236669)
			(xy 380.063019 4.322052) (xy 380.078775 4.406342) (xy 380.102242 4.488818) (xy 380.133218 4.568777)
			(xy 380.17144 4.645537) (xy 380.216581 4.718443) (xy 380.268257 4.786872) (xy 380.326026 4.850242)
			(xy 380.389396 4.908011) (xy 380.457825 4.959687) (xy 380.530731 5.004828) (xy 380.607491 5.04305)
			(xy 380.68745 5.074026) (xy 380.769926 5.097493) (xy 380.854216 5.113249) (xy 380.939599 5.121161)
			(xy 381.025349 5.121161) (xy 381.110732 5.113249) (xy 381.195022 5.097493) (xy 381.277498 5.074026)
			(xy 381.357457 5.04305) (xy 381.434217 5.004828) (xy 381.507123 4.959687) (xy 381.575552 4.908011)
			(xy 381.638922 4.850242) (xy 381.696691 4.786872) (xy 381.748367 4.718443) (xy 381.793508 4.645537)
			(xy 381.83173 4.568777) (xy 381.862706 4.488818) (xy 381.886173 4.406342) (xy 381.901929 4.322052)
			(xy 381.909841 4.236669) (xy 381.910336 4.193794) (xy 381.909841 4.150919) (xy 381.901929 4.065536)
			(xy 381.886173 3.981246) (xy 381.862706 3.89877) (xy 381.83173 3.818811) (xy 381.793508 3.742051)
			(xy 381.748367 3.669145) (xy 381.696691 3.600716) (xy 381.638922 3.537346) (xy 381.575552 3.479577)
			(xy 381.507123 3.427901) (xy 381.434217 3.38276) (xy 381.357457 3.344538) (xy 381.277498 3.313562)
			(xy 381.195022 3.290095) (xy 381.110732 3.274339) (xy 381.025349 3.266427) (xy 380.939599 3.266427)
			(xy 380.854216 3.274339) (xy 380.769926 3.290095) (xy 380.68745 3.313562) (xy 380.607491 3.344538)
			(xy 380.530731 3.38276) (xy 380.457825 3.427901) (xy 380.389396 3.479577) (xy 380.326026 3.537346)
			(xy 380.268257 3.600716) (xy 380.216581 3.669145) (xy 380.17144 3.742051) (xy 380.133218 3.818811)
			(xy 380.102242 3.89877) (xy 380.078775 3.981246) (xy 380.063019 4.065536) (xy 380.055107 4.150919)
			(xy 375.559841 4.150919) (xy 375.551929 4.065536) (xy 375.536173 3.981246) (xy 375.512706 3.89877)
			(xy 375.48173 3.818811) (xy 375.443508 3.742051) (xy 375.398367 3.669145) (xy 375.346691 3.600716)
			(xy 375.288922 3.537346) (xy 375.225552 3.479577) (xy 375.157123 3.427901) (xy 375.084217 3.38276)
			(xy 375.007457 3.344538) (xy 374.927498 3.313562) (xy 374.845022 3.290095) (xy 374.760732 3.274339)
			(xy 374.675349 3.266427) (xy 374.589599 3.266427) (xy 374.504216 3.274339) (xy 374.419926 3.290095)
			(xy 374.33745 3.313562) (xy 374.257491 3.344538) (xy 374.180731 3.38276) (xy 374.107825 3.427901)
			(xy 374.039396 3.479577) (xy 373.976026 3.537346) (xy 373.918257 3.600716) (xy 373.866581 3.669145)
			(xy 373.82144 3.742051) (xy 373.783218 3.818811) (xy 373.752242 3.89877) (xy 373.728775 3.981246)
			(xy 373.713019 4.065536) (xy 373.705107 4.150919) (xy 343.693001 4.150919) (xy 343.685089 4.065536)
			(xy 343.669333 3.981246) (xy 343.645866 3.89877) (xy 343.61489 3.818811) (xy 343.576668 3.742051)
			(xy 343.531527 3.669145) (xy 343.479851 3.600716) (xy 343.422082 3.537346) (xy 343.358712 3.479577)
			(xy 343.290283 3.427901) (xy 343.217377 3.38276) (xy 343.140617 3.344538) (xy 343.060658 3.313562)
			(xy 342.978182 3.290095) (xy 342.893892 3.274339) (xy 342.808509 3.266427) (xy 342.722759 3.266427)
			(xy 342.637376 3.274339) (xy 342.553086 3.290095) (xy 342.47061 3.313562) (xy 342.390651 3.344538)
			(xy 342.313891 3.38276) (xy 342.240985 3.427901) (xy 342.172556 3.479577) (xy 342.109186 3.537346)
			(xy 342.051417 3.600716) (xy 341.999741 3.669145) (xy 341.9546 3.742051) (xy 341.916378 3.818811)
			(xy 341.885402 3.89877) (xy 341.861935 3.981246) (xy 341.846179 4.065536) (xy 341.838267 4.150919)
			(xy 337.343001 4.150919) (xy 337.335089 4.065536) (xy 337.319333 3.981246) (xy 337.295866 3.89877)
			(xy 337.26489 3.818811) (xy 337.226668 3.742051) (xy 337.181527 3.669145) (xy 337.129851 3.600716)
			(xy 337.072082 3.537346) (xy 337.008712 3.479577) (xy 336.940283 3.427901) (xy 336.867377 3.38276)
			(xy 336.790617 3.344538) (xy 336.710658 3.313562) (xy 336.628182 3.290095) (xy 336.543892 3.274339)
			(xy 336.458509 3.266427) (xy 336.372759 3.266427) (xy 336.287376 3.274339) (xy 336.203086 3.290095)
			(xy 336.12061 3.313562) (xy 336.040651 3.344538) (xy 335.963891 3.38276) (xy 335.890985 3.427901)
			(xy 335.822556 3.479577) (xy 335.759186 3.537346) (xy 335.701417 3.600716) (xy 335.649741 3.669145)
			(xy 335.6046 3.742051) (xy 335.566378 3.818811) (xy 335.535402 3.89877) (xy 335.511935 3.981246)
			(xy 335.496179 4.065536) (xy 335.488267 4.150919) (xy 333.050655 4.150919) (xy 333.042743 4.065536)
			(xy 333.026987 3.981246) (xy 333.00352 3.89877) (xy 332.972544 3.818811) (xy 332.934322 3.742051)
			(xy 332.889181 3.669145) (xy 332.837505 3.600716) (xy 332.779736 3.537346) (xy 332.716366 3.479577)
			(xy 332.647937 3.427901) (xy 332.575031 3.38276) (xy 332.498271 3.344538) (xy 332.418312 3.313562)
			(xy 332.335836 3.290095) (xy 332.251546 3.274339) (xy 332.166163 3.266427) (xy 332.080413 3.266427)
			(xy 331.99503 3.274339) (xy 331.91074 3.290095) (xy 331.828264 3.313562) (xy 331.748305 3.344538)
			(xy 331.671545 3.38276) (xy 331.598639 3.427901) (xy 331.53021 3.479577) (xy 331.46684 3.537346)
			(xy 331.409071 3.600716) (xy 331.357395 3.669145) (xy 331.312254 3.742051) (xy 331.274032 3.818811)
			(xy 331.243056 3.89877) (xy 331.219589 3.981246) (xy 331.203833 4.065536) (xy 331.195921 4.150919)
			(xy 326.700655 4.150919) (xy 326.692743 4.065536) (xy 326.676987 3.981246) (xy 326.65352 3.89877)
			(xy 326.622544 3.818811) (xy 326.584322 3.742051) (xy 326.539181 3.669145) (xy 326.487505 3.600716)
			(xy 326.429736 3.537346) (xy 326.366366 3.479577) (xy 326.297937 3.427901) (xy 326.225031 3.38276)
			(xy 326.148271 3.344538) (xy 326.068312 3.313562) (xy 325.985836 3.290095) (xy 325.901546 3.274339)
			(xy 325.816163 3.266427) (xy 325.730413 3.266427) (xy 325.64503 3.274339) (xy 325.56074 3.290095)
			(xy 325.478264 3.313562) (xy 325.398305 3.344538) (xy 325.321545 3.38276) (xy 325.248639 3.427901)
			(xy 325.18021 3.479577) (xy 325.11684 3.537346) (xy 325.059071 3.600716) (xy 325.007395 3.669145)
			(xy 324.962254 3.742051) (xy 324.924032 3.818811) (xy 324.893056 3.89877) (xy 324.869589 3.981246)
			(xy 324.853833 4.065536) (xy 324.845921 4.150919) (xy 265.125975 4.150919) (xy 265.118063 4.065536)
			(xy 265.102307 3.981246) (xy 265.07884 3.89877) (xy 265.047864 3.818811) (xy 265.009642 3.742051)
			(xy 264.964501 3.669145) (xy 264.912825 3.600716) (xy 264.855056 3.537346) (xy 264.791686 3.479577)
			(xy 264.723257 3.427901) (xy 264.650351 3.38276) (xy 264.573591 3.344538) (xy 264.493632 3.313562)
			(xy 264.411156 3.290095) (xy 264.326866 3.274339) (xy 264.241483 3.266427) (xy 264.155733 3.266427)
			(xy 264.07035 3.274339) (xy 263.98606 3.290095) (xy 263.903584 3.313562) (xy 263.823625 3.344538)
			(xy 263.746865 3.38276) (xy 263.673959 3.427901) (xy 263.60553 3.479577) (xy 263.54216 3.537346)
			(xy 263.484391 3.600716) (xy 263.432715 3.669145) (xy 263.387574 3.742051) (xy 263.349352 3.818811)
			(xy 263.318376 3.89877) (xy 263.294909 3.981246) (xy 263.279153 4.065536) (xy 263.271241 4.150919)
			(xy 258.775975 4.150919) (xy 258.768063 4.065536) (xy 258.752307 3.981246) (xy 258.72884 3.89877)
			(xy 258.697864 3.818811) (xy 258.659642 3.742051) (xy 258.614501 3.669145) (xy 258.562825 3.600716)
			(xy 258.505056 3.537346) (xy 258.441686 3.479577) (xy 258.373257 3.427901) (xy 258.300351 3.38276)
			(xy 258.223591 3.344538) (xy 258.143632 3.313562) (xy 258.061156 3.290095) (xy 257.976866 3.274339)
			(xy 257.891483 3.266427) (xy 257.805733 3.266427) (xy 257.72035 3.274339) (xy 257.63606 3.290095)
			(xy 257.553584 3.313562) (xy 257.473625 3.344538) (xy 257.396865 3.38276) (xy 257.323959 3.427901)
			(xy 257.25553 3.479577) (xy 257.19216 3.537346) (xy 257.134391 3.600716) (xy 257.082715 3.669145)
			(xy 257.037574 3.742051) (xy 256.999352 3.818811) (xy 256.968376 3.89877) (xy 256.944909 3.981246)
			(xy 256.929153 4.065536) (xy 256.921241 4.150919) (xy 254.465119 4.150919) (xy 254.465087 4.148125)
			(xy 254.457175 4.062742) (xy 254.441419 3.978452) (xy 254.417952 3.895976) (xy 254.386976 3.816017)
			(xy 254.348754 3.739257) (xy 254.303613 3.666351) (xy 254.251937 3.597922) (xy 254.194168 3.534552)
			(xy 254.130798 3.476783) (xy 254.062369 3.425107) (xy 253.989463 3.379966) (xy 253.912703 3.341744)
			(xy 253.832744 3.310768) (xy 253.750268 3.287301) (xy 253.665978 3.271545) (xy 253.580595 3.263633)
			(xy 253.494845 3.263633) (xy 253.409462 3.271545) (xy 253.325172 3.287301) (xy 253.242696 3.310768)
			(xy 253.162737 3.341744) (xy 253.085977 3.379966) (xy 253.013071 3.425107) (xy 252.944642 3.476783)
			(xy 252.881272 3.534552) (xy 252.823503 3.597922) (xy 252.771827 3.666351) (xy 252.726686 3.739257)
			(xy 252.688464 3.816017) (xy 252.657488 3.895976) (xy 252.634021 3.978452) (xy 252.618265 4.062742)
			(xy 252.610353 4.148125) (xy 248.115087 4.148125) (xy 248.107175 4.062742) (xy 248.091419 3.978452)
			(xy 248.067952 3.895976) (xy 248.036976 3.816017) (xy 247.998754 3.739257) (xy 247.953613 3.666351)
			(xy 247.901937 3.597922) (xy 247.844168 3.534552) (xy 247.780798 3.476783) (xy 247.712369 3.425107)
			(xy 247.639463 3.379966) (xy 247.562703 3.341744) (xy 247.482744 3.310768) (xy 247.400268 3.287301)
			(xy 247.315978 3.271545) (xy 247.230595 3.263633) (xy 247.144845 3.263633) (xy 247.059462 3.271545)
			(xy 246.975172 3.287301) (xy 246.892696 3.310768) (xy 246.812737 3.341744) (xy 246.735977 3.379966)
			(xy 246.663071 3.425107) (xy 246.594642 3.476783) (xy 246.531272 3.534552) (xy 246.473503 3.597922)
			(xy 246.421827 3.666351) (xy 246.376686 3.739257) (xy 246.338464 3.816017) (xy 246.307488 3.895976)
			(xy 246.284021 3.978452) (xy 246.268265 4.062742) (xy 246.260353 4.148125) (xy 186.540407 4.148125)
			(xy 186.532495 4.062742) (xy 186.516739 3.978452) (xy 186.493272 3.895976) (xy 186.462296 3.816017)
			(xy 186.424074 3.739257) (xy 186.378933 3.666351) (xy 186.327257 3.597922) (xy 186.269488 3.534552)
			(xy 186.206118 3.476783) (xy 186.137689 3.425107) (xy 186.064783 3.379966) (xy 185.988023 3.341744)
			(xy 185.908064 3.310768) (xy 185.825588 3.287301) (xy 185.741298 3.271545) (xy 185.655915 3.263633)
			(xy 185.570165 3.263633) (xy 185.484782 3.271545) (xy 185.400492 3.287301) (xy 185.318016 3.310768)
			(xy 185.238057 3.341744) (xy 185.161297 3.379966) (xy 185.088391 3.425107) (xy 185.019962 3.476783)
			(xy 184.956592 3.534552) (xy 184.898823 3.597922) (xy 184.847147 3.666351) (xy 184.802006 3.739257)
			(xy 184.763784 3.816017) (xy 184.732808 3.895976) (xy 184.709341 3.978452) (xy 184.693585 4.062742)
			(xy 184.685673 4.148125) (xy 180.190407 4.148125) (xy 180.182495 4.062742) (xy 180.166739 3.978452)
			(xy 180.143272 3.895976) (xy 180.112296 3.816017) (xy 180.074074 3.739257) (xy 180.028933 3.666351)
			(xy 179.977257 3.597922) (xy 179.919488 3.534552) (xy 179.856118 3.476783) (xy 179.787689 3.425107)
			(xy 179.714783 3.379966) (xy 179.638023 3.341744) (xy 179.558064 3.310768) (xy 179.475588 3.287301)
			(xy 179.391298 3.271545) (xy 179.305915 3.263633) (xy 179.220165 3.263633) (xy 179.134782 3.271545)
			(xy 179.050492 3.287301) (xy 178.968016 3.310768) (xy 178.888057 3.341744) (xy 178.811297 3.379966)
			(xy 178.738391 3.425107) (xy 178.669962 3.476783) (xy 178.606592 3.534552) (xy 178.548823 3.597922)
			(xy 178.497147 3.666351) (xy 178.452006 3.739257) (xy 178.413784 3.816017) (xy 178.382808 3.895976)
			(xy 178.359341 3.978452) (xy 178.343585 4.062742) (xy 178.335673 4.148125) (xy 0.508 4.148125) (xy 0.508 -7.78002)
			(xy 0.508522 -7.835827) (xy 0.516863 -7.947129) (xy 0.533498 -8.057497) (xy 0.558334 -8.166312) (xy 0.591233 -8.272968)
			(xy 0.63201 -8.376867) (xy 0.680438 -8.477428) (xy 0.736245 -8.574088) (xy 0.799119 -8.666308) (xy 0.868709 -8.753572)
			(xy 0.944626 -8.835391) (xy 1.026445 -8.911308) (xy 1.113708 -8.980898) (xy 1.205928 -9.043773) (xy 1.302589 -9.09958)
			(xy 1.40315 -9.148008) (xy 1.507048 -9.188786) (xy 1.613704 -9.221685) (xy 1.722519 -9.246521) (xy 1.832887 -9.263157)
			(xy 1.944189 -9.271498) (xy 1.999996 -9.272016) (xy 9.10209 -9.272016) (xy 9.157898 -9.271495) (xy 9.269201 -9.263154)
			(xy 9.379569 -9.24652) (xy 9.488386 -9.221684) (xy 9.595043 -9.188786) (xy 9.698942 -9.148009) (xy 9.799505 -9.099582)
			(xy 9.896167 -9.043775) (xy 9.988388 -8.980901) (xy 10.075653 -8.911311) (xy 10.157473 -8.835394)
			(xy 10.233392 -8.753575) (xy 10.302983 -8.666312) (xy 10.365859 -8.574092) (xy 10.421668 -8.477431)
			(xy 10.470097 -8.37687) (xy 10.510876 -8.272971) (xy 10.543776 -8.166315) (xy 10.568614 -8.057499)
			(xy 10.585251 -7.94713) (xy 10.593594 -7.835828) (xy 10.594086 -7.78002) (xy 10.594086 0.999998)
			(xy 10.59457 1.070352) (xy 10.60246 1.210839) (xy 10.618214 1.350662) (xy 10.641783 1.489382) (xy 10.673094 1.626562)
			(xy 10.712047 1.761771) (xy 10.758519 1.894583) (xy 10.812366 2.02458) (xy 10.873417 2.151354) (xy 10.94148 2.274505)
			(xy 11.016341 2.393646) (xy 11.097765 2.508402) (xy 11.185495 2.618411) (xy 11.279255 2.723329) (xy 11.378751 2.822825)
			(xy 11.483669 2.916585) (xy 11.593678 3.004315) (xy 11.708434 3.085739) (xy 11.827575 3.1606) (xy 11.950726 3.228663)
			(xy 12.0775 3.289714) (xy 12.207497 3.343561) (xy 12.340309 3.390033) (xy 12.475518 3.428986) (xy 12.612698 3.460297)
			(xy 12.751418 3.483866) (xy 12.891241 3.49962) (xy 13.031728 3.50751) (xy 13.102082 3.507994) (xy 81.701894 3.507994)
			(xy 81.772248 3.50751) (xy 81.912735 3.499621) (xy 82.052558 3.483867) (xy 82.191278 3.460297) (xy 82.328459 3.428987)
			(xy 82.463668 3.390034) (xy 82.59648 3.343562) (xy 82.726477 3.289715) (xy 82.853251 3.228664) (xy 82.976402 3.160601)
			(xy 83.095543 3.08574) (xy 83.2103 3.004317) (xy 83.32031 2.916587) (xy 83.425228 2.822826) (xy 83.524724 2.723331)
			(xy 83.618484 2.618413) (xy 83.706214 2.508403) (xy 83.787638 2.393647) (xy 83.862499 2.274506) (xy 83.930563 2.151355)
			(xy 83.991614 2.024581) (xy 84.04546 1.894584) (xy 84.091933 1.761772) (xy 84.130886 1.626563) (xy 84.135094 1.608125)
			(xy 178.335673 1.608125) (xy 178.335673 1.693875) (xy 178.343585 1.779258) (xy 178.359341 1.863548)
			(xy 178.382808 1.946024) (xy 178.413784 2.025983) (xy 178.452006 2.102743) (xy 178.497147 2.175649)
			(xy 178.548823 2.244078) (xy 178.606592 2.307448) (xy 178.669962 2.365217) (xy 178.738391 2.416893)
			(xy 178.811297 2.462034) (xy 178.888057 2.500256) (xy 178.968016 2.531232) (xy 179.050492 2.554699)
			(xy 179.134782 2.570455) (xy 179.220165 2.578367) (xy 179.305915 2.578367) (xy 179.391298 2.570455)
			(xy 179.475588 2.554699) (xy 179.558064 2.531232) (xy 179.638023 2.500256) (xy 179.660226 2.4892)
			(xy 183.270652 2.4892) (xy 183.270652 3.3528) (xy 183.271138 3.380069) (xy 183.2789 3.434053) (xy 183.294265 3.486383)
			(xy 183.316922 3.535993) (xy 183.346408 3.581874) (xy 183.382123 3.623091) (xy 183.42334 3.658806)
			(xy 183.469221 3.688292) (xy 183.518831 3.710949) (xy 183.571161 3.726314) (xy 183.625145 3.734076)
			(xy 183.679683 3.734076) (xy 183.733667 3.726314) (xy 183.785997 3.710949) (xy 183.835607 3.688292)
			(xy 183.881488 3.658806) (xy 183.922705 3.623091) (xy 183.95842 3.581874) (xy 183.987906 3.535993)
			(xy 184.010563 3.486383) (xy 184.025928 3.434053) (xy 184.03369 3.380069) (xy 184.034176 3.3528)
			(xy 184.034176 2.4892) (xy 184.03369 2.461931) (xy 184.025928 2.407947) (xy 184.010563 2.355617)
			(xy 183.987906 2.306007) (xy 183.95842 2.260126) (xy 183.922705 2.218909) (xy 183.881488 2.183194)
			(xy 183.835607 2.153708) (xy 183.785997 2.131051) (xy 183.733667 2.115686) (xy 183.679683 2.107924)
			(xy 183.625145 2.107924) (xy 183.571161 2.115686) (xy 183.518831 2.131051) (xy 183.469221 2.153708)
			(xy 183.42334 2.183194) (xy 183.382123 2.218909) (xy 183.346408 2.260126) (xy 183.316922 2.306007)
			(xy 183.294265 2.355617) (xy 183.2789 2.407947) (xy 183.271138 2.461931) (xy 183.270652 2.4892) (xy 179.660226 2.4892)
			(xy 179.714783 2.462034) (xy 179.787689 2.416893) (xy 179.856118 2.365217) (xy 179.919488 2.307448)
			(xy 179.977257 2.244078) (xy 180.028933 2.175649) (xy 180.074074 2.102743) (xy 180.112296 2.025983)
			(xy 180.143272 1.946024) (xy 180.166739 1.863548) (xy 180.182495 1.779258) (xy 180.190407 1.693875)
			(xy 180.190902 1.651) (xy 180.190407 1.608125) (xy 184.685673 1.608125) (xy 184.685673 1.693875)
			(xy 184.693585 1.779258) (xy 184.709341 1.863548) (xy 184.732808 1.946024) (xy 184.763784 2.025983)
			(xy 184.802006 2.102743) (xy 184.847147 2.175649) (xy 184.898823 2.244078) (xy 184.956592 2.307448)
			(xy 185.019962 2.365217) (xy 185.088391 2.416893) (xy 185.161297 2.462034) (xy 185.238057 2.500256)
			(xy 185.318016 2.531232) (xy 185.400492 2.554699) (xy 185.484782 2.570455) (xy 185.570165 2.578367)
			(xy 185.655915 2.578367) (xy 185.741298 2.570455) (xy 185.825588 2.554699) (xy 185.908064 2.531232)
			(xy 185.988023 2.500256) (xy 186.064783 2.462034) (xy 186.137689 2.416893) (xy 186.206118 2.365217)
			(xy 186.269488 2.307448) (xy 186.327257 2.244078) (xy 186.378933 2.175649) (xy 186.424074 2.102743)
			(xy 186.462296 2.025983) (xy 186.493272 1.946024) (xy 186.516739 1.863548) (xy 186.532495 1.779258)
			(xy 186.540407 1.693875) (xy 186.540902 1.651) (xy 186.540407 1.608125) (xy 246.260353 1.608125)
			(xy 246.260353 1.693875) (xy 246.268265 1.779258) (xy 246.284021 1.863548) (xy 246.307488 1.946024)
			(xy 246.338464 2.025983) (xy 246.376686 2.102743) (xy 246.421827 2.175649) (xy 246.473503 2.244078)
			(xy 246.531272 2.307448) (xy 246.594642 2.365217) (xy 246.663071 2.416893) (xy 246.735977 2.462034)
			(xy 246.812737 2.500256) (xy 246.892696 2.531232) (xy 246.975172 2.554699) (xy 247.059462 2.570455)
			(xy 247.144845 2.578367) (xy 247.230595 2.578367) (xy 247.315978 2.570455) (xy 247.400268 2.554699)
			(xy 247.482744 2.531232) (xy 247.562703 2.500256) (xy 247.584906 2.4892) (xy 248.766584 2.4892) (xy 248.766584 3.3528)
			(xy 248.76707 3.380069) (xy 248.774832 3.434053) (xy 248.790197 3.486383) (xy 248.812854 3.535993)
			(xy 248.84234 3.581874) (xy 248.878055 3.623091) (xy 248.919272 3.658806) (xy 248.965153 3.688292)
			(xy 249.014763 3.710949) (xy 249.067093 3.726314) (xy 249.121077 3.734076) (xy 249.175615 3.734076)
			(xy 249.229599 3.726314) (xy 249.281929 3.710949) (xy 249.331539 3.688292) (xy 249.37742 3.658806)
			(xy 249.418637 3.623091) (xy 249.454352 3.581874) (xy 249.483838 3.535993) (xy 249.506495 3.486383)
			(xy 249.52186 3.434053) (xy 249.529622 3.380069) (xy 249.530108 3.3528) (xy 249.530108 2.4892) (xy 249.529622 2.461931)
			(xy 249.52186 2.407947) (xy 249.506495 2.355617) (xy 249.483838 2.306007) (xy 249.454352 2.260126)
			(xy 249.418637 2.218909) (xy 249.37742 2.183194) (xy 249.331539 2.153708) (xy 249.281929 2.131051)
			(xy 249.229599 2.115686) (xy 249.175615 2.107924) (xy 249.121077 2.107924) (xy 249.067093 2.115686)
			(xy 249.014763 2.131051) (xy 248.965153 2.153708) (xy 248.919272 2.183194) (xy 248.878055 2.218909)
			(xy 248.84234 2.260126) (xy 248.812854 2.306007) (xy 248.790197 2.355617) (xy 248.774832 2.407947)
			(xy 248.76707 2.461931) (xy 248.766584 2.4892) (xy 247.584906 2.4892) (xy 247.639463 2.462034) (xy 247.712369 2.416893)
			(xy 247.780798 2.365217) (xy 247.844168 2.307448) (xy 247.901937 2.244078) (xy 247.953613 2.175649)
			(xy 247.998754 2.102743) (xy 248.036976 2.025983) (xy 248.067952 1.946024) (xy 248.091419 1.863548)
			(xy 248.107175 1.779258) (xy 248.115087 1.693875) (xy 248.115582 1.651) (xy 248.115087 1.608125)
			(xy 252.610353 1.608125) (xy 252.610353 1.693875) (xy 252.618265 1.779258) (xy 252.634021 1.863548)
			(xy 252.657488 1.946024) (xy 252.688464 2.025983) (xy 252.726686 2.102743) (xy 252.771827 2.175649)
			(xy 252.823503 2.244078) (xy 252.881272 2.307448) (xy 252.944642 2.365217) (xy 253.013071 2.416893)
			(xy 253.085977 2.462034) (xy 253.162737 2.500256) (xy 253.242696 2.531232) (xy 253.325172 2.554699)
			(xy 253.409462 2.570455) (xy 253.494845 2.578367) (xy 253.580595 2.578367) (xy 253.665978 2.570455)
			(xy 253.750268 2.554699) (xy 253.832744 2.531232) (xy 253.912703 2.500256) (xy 253.989463 2.462034)
			(xy 254.062369 2.416893) (xy 254.130798 2.365217) (xy 254.194168 2.307448) (xy 254.251937 2.244078)
			(xy 254.303613 2.175649) (xy 254.348754 2.102743) (xy 254.386976 2.025983) (xy 254.417952 1.946024)
			(xy 254.441419 1.863548) (xy 254.457175 1.779258) (xy 254.465087 1.693875) (xy 254.465582 1.651)
			(xy 254.465119 1.610919) (xy 256.921241 1.610919) (xy 256.921241 1.696669) (xy 256.929153 1.782052)
			(xy 256.944909 1.866342) (xy 256.968376 1.948818) (xy 256.999352 2.028777) (xy 257.037574 2.105537)
			(xy 257.082715 2.178443) (xy 257.134391 2.246872) (xy 257.19216 2.310242) (xy 257.25553 2.368011)
			(xy 257.323959 2.419687) (xy 257.396865 2.464828) (xy 257.473625 2.50305) (xy 257.553584 2.534026)
			(xy 257.63606 2.557493) (xy 257.72035 2.573249) (xy 257.805733 2.581161) (xy 257.891483 2.581161)
			(xy 257.976866 2.573249) (xy 258.061156 2.557493) (xy 258.143632 2.534026) (xy 258.223591 2.50305)
			(xy 258.300351 2.464828) (xy 258.373257 2.419687) (xy 258.428864 2.377694) (xy 261.079996 2.377694)
			(xy 261.079996 3.474974) (xy 261.080529 3.487058) (xy 261.087973 3.51005) (xy 261.102144 3.529627)
			(xy 261.121661 3.54388) (xy 261.144622 3.55142) (xy 261.156704 3.551936) (xy 261.768844 3.551936)
			(xy 261.777315 3.551685) (xy 261.793848 3.547973) (xy 261.80161 3.54457) (xy 261.814596 3.538995)
			(xy 261.842475 3.53445) (xy 261.870532 3.537721) (xy 261.896619 3.548555) (xy 261.918738 3.566125)
			(xy 261.92734 3.577336) (xy 261.942756 3.598198) (xy 261.978318 3.635962) (xy 262.018669 3.668561)
			(xy 262.063063 3.695392) (xy 262.110683 3.715961) (xy 262.160651 3.729889) (xy 262.212046 3.736919)
			(xy 262.237982 3.737356) (xy 262.265253 3.736882) (xy 262.31924 3.729122) (xy 262.371572 3.713758)
			(xy 262.421186 3.691102) (xy 262.46707 3.661615) (xy 262.508291 3.625899) (xy 262.544008 3.58468)
			(xy 262.573496 3.538797) (xy 262.596153 3.489184) (xy 262.611519 3.436851) (xy 262.619281 3.382865)
			(xy 262.619744 3.355594) (xy 262.619744 2.491994) (xy 262.619304 2.464722) (xy 262.611541 2.410733)
			(xy 262.596173 2.358399) (xy 262.573513 2.308785) (xy 262.544023 2.2629) (xy 262.508303 2.22168)
			(xy 262.46708 2.185962) (xy 262.421194 2.156475) (xy 262.371578 2.133819) (xy 262.319243 2.118454)
			(xy 262.265254 2.110694) (xy 262.237982 2.110232) (xy 262.211789 2.1107) (xy 262.159897 2.117893)
			(xy 262.109477 2.132115) (xy 262.061475 2.153097) (xy 262.016793 2.180446) (xy 261.976271 2.213648)
			(xy 261.940669 2.252079) (xy 261.925308 2.2733) (xy 261.916825 2.284535) (xy 261.894967 2.30226)
			(xy 261.86911 2.313366) (xy 261.841207 2.317016) (xy 261.813364 2.312935) (xy 261.80034 2.30759)
			(xy 261.792854 2.30442) (xy 261.776971 2.300961) (xy 261.768844 2.300732) (xy 261.156704 2.300732)
			(xy 261.144592 2.30112) (xy 261.121559 2.308622) (xy 261.101983 2.32289) (xy 261.08779 2.34252) (xy 261.080375 2.365581)
			(xy 261.079996 2.377694) (xy 258.428864 2.377694) (xy 258.441686 2.368011) (xy 258.505056 2.310242)
			(xy 258.562825 2.246872) (xy 258.614501 2.178443) (xy 258.659642 2.105537) (xy 258.697864 2.028777)
			(xy 258.72884 1.948818) (xy 258.752307 1.866342) (xy 258.768063 1.782052) (xy 258.775975 1.696669)
			(xy 258.77647 1.653794) (xy 258.775975 1.610919) (xy 263.271241 1.610919) (xy 263.271241 1.696669)
			(xy 263.279153 1.782052) (xy 263.294909 1.866342) (xy 263.318376 1.948818) (xy 263.349352 2.028777)
			(xy 263.387574 2.105537) (xy 263.432715 2.178443) (xy 263.484391 2.246872) (xy 263.54216 2.310242)
			(xy 263.60553 2.368011) (xy 263.673959 2.419687) (xy 263.746865 2.464828) (xy 263.823625 2.50305)
			(xy 263.903584 2.534026) (xy 263.98606 2.557493) (xy 264.07035 2.573249) (xy 264.155733 2.581161)
			(xy 264.241483 2.581161) (xy 264.326866 2.573249) (xy 264.411156 2.557493) (xy 264.493632 2.534026)
			(xy 264.573591 2.50305) (xy 264.650351 2.464828) (xy 264.723257 2.419687) (xy 264.791686 2.368011)
			(xy 264.855056 2.310242) (xy 264.912825 2.246872) (xy 264.964501 2.178443) (xy 265.009642 2.105537)
			(xy 265.047864 2.028777) (xy 265.07884 1.948818) (xy 265.102307 1.866342) (xy 265.118063 1.782052)
			(xy 265.125975 1.696669) (xy 265.12647 1.653794) (xy 265.125975 1.610919) (xy 324.845921 1.610919)
			(xy 324.845921 1.696669) (xy 324.853833 1.782052) (xy 324.869589 1.866342) (xy 324.893056 1.948818)
			(xy 324.924032 2.028777) (xy 324.962254 2.105537) (xy 325.007395 2.178443) (xy 325.059071 2.246872)
			(xy 325.11684 2.310242) (xy 325.18021 2.368011) (xy 325.248639 2.419687) (xy 325.321545 2.464828)
			(xy 325.398305 2.50305) (xy 325.478264 2.534026) (xy 325.56074 2.557493) (xy 325.64503 2.573249)
			(xy 325.730413 2.581161) (xy 325.816163 2.581161) (xy 325.901546 2.573249) (xy 325.985836 2.557493)
			(xy 326.068312 2.534026) (xy 326.148271 2.50305) (xy 326.170474 2.491994) (xy 327.352152 2.491994)
			(xy 327.352152 3.355594) (xy 327.352607 3.382865) (xy 327.360369 3.436853) (xy 327.375735 3.489187)
			(xy 327.398393 3.538801) (xy 327.427881 3.584686) (xy 327.4636 3.625906) (xy 327.504821 3.661624)
			(xy 327.550706 3.691111) (xy 327.60032 3.713768) (xy 327.652654 3.729133) (xy 327.706642 3.736893)
			(xy 327.733914 3.737356) (xy 327.760108 3.73689) (xy 327.811999 3.729697) (xy 327.86242 3.715476)
			(xy 327.910422 3.694493) (xy 327.955104 3.667144) (xy 327.995626 3.633942) (xy 328.031228 3.59551)
			(xy 328.046588 3.574288) (xy 328.055072 3.563054) (xy 328.07693 3.545331) (xy 328.102787 3.534225)
			(xy 328.130689 3.530574) (xy 328.158532 3.534654) (xy 328.171556 3.539998) (xy 328.179043 3.543167)
			(xy 328.194925 3.546627) (xy 328.203052 3.546856) (xy 328.815192 3.546856) (xy 328.827295 3.546378)
			(xy 328.850312 3.538887) (xy 328.869881 3.52464) (xy 328.884078 3.505035) (xy 328.891509 3.481998)
			(xy 328.8919 3.469894) (xy 328.8919 2.372614) (xy 328.891381 2.360529) (xy 328.883933 2.337536) (xy 328.869759 2.317959)
			(xy 328.850238 2.303707) (xy 328.827275 2.296167) (xy 328.815192 2.295652) (xy 328.203052 2.295652)
			(xy 328.194581 2.295903) (xy 328.178048 2.299615) (xy 328.170286 2.303018) (xy 328.157303 2.308601)
			(xy 328.129422 2.313146) (xy 328.101363 2.309874) (xy 328.075276 2.299037) (xy 328.053157 2.281465)
			(xy 328.044556 2.270252) (xy 328.029145 2.249385) (xy 327.993582 2.211622) (xy 327.953231 2.179024)
			(xy 327.908835 2.152194) (xy 327.861214 2.131625) (xy 327.811245 2.117698) (xy 327.759851 2.110668)
			(xy 327.733914 2.110232) (xy 327.706644 2.110714) (xy 327.652658 2.118475) (xy 327.600326 2.133839)
			(xy 327.550713 2.156494) (xy 327.50483 2.18598) (xy 327.46361 2.221695) (xy 327.427892 2.262914)
			(xy 327.398404 2.308795) (xy 327.375746 2.358407) (xy 327.360379 2.410738) (xy 327.352616 2.464724)
			(xy 327.352152 2.491994) (xy 326.170474 2.491994) (xy 326.225031 2.464828) (xy 326.297937 2.419687)
			(xy 326.366366 2.368011) (xy 326.429736 2.310242) (xy 326.487505 2.246872) (xy 326.539181 2.178443)
			(xy 326.584322 2.105537) (xy 326.622544 2.028777) (xy 326.65352 1.948818) (xy 326.676987 1.866342)
			(xy 326.692743 1.782052) (xy 326.700655 1.696669) (xy 326.70115 1.653794) (xy 326.700655 1.610919)
			(xy 331.195921 1.610919) (xy 331.195921 1.696669) (xy 331.203833 1.782052) (xy 331.219589 1.866342)
			(xy 331.243056 1.948818) (xy 331.274032 2.028777) (xy 331.312254 2.105537) (xy 331.357395 2.178443)
			(xy 331.409071 2.246872) (xy 331.46684 2.310242) (xy 331.53021 2.368011) (xy 331.598639 2.419687)
			(xy 331.671545 2.464828) (xy 331.748305 2.50305) (xy 331.828264 2.534026) (xy 331.91074 2.557493)
			(xy 331.99503 2.573249) (xy 332.080413 2.581161) (xy 332.166163 2.581161) (xy 332.251546 2.573249)
			(xy 332.335836 2.557493) (xy 332.418312 2.534026) (xy 332.498271 2.50305) (xy 332.575031 2.464828)
			(xy 332.647937 2.419687) (xy 332.716366 2.368011) (xy 332.779736 2.310242) (xy 332.837505 2.246872)
			(xy 332.889181 2.178443) (xy 332.934322 2.105537) (xy 332.972544 2.028777) (xy 333.00352 1.948818)
			(xy 333.026987 1.866342) (xy 333.042743 1.782052) (xy 333.050655 1.696669) (xy 333.05115 1.653794)
			(xy 333.050655 1.610919) (xy 335.488267 1.610919) (xy 335.488267 1.696669) (xy 335.496179 1.782052)
			(xy 335.511935 1.866342) (xy 335.535402 1.948818) (xy 335.566378 2.028777) (xy 335.6046 2.105537)
			(xy 335.649741 2.178443) (xy 335.701417 2.246872) (xy 335.759186 2.310242) (xy 335.822556 2.368011)
			(xy 335.890985 2.419687) (xy 335.963891 2.464828) (xy 336.040651 2.50305) (xy 336.12061 2.534026)
			(xy 336.203086 2.557493) (xy 336.287376 2.573249) (xy 336.372759 2.581161) (xy 336.458509 2.581161)
			(xy 336.543892 2.573249) (xy 336.628182 2.557493) (xy 336.710658 2.534026) (xy 336.790617 2.50305)
			(xy 336.867377 2.464828) (xy 336.940283 2.419687) (xy 336.99589 2.377694) (xy 339.646768 2.377694)
			(xy 339.646768 3.474974) (xy 339.647183 3.487098) (xy 339.654671 3.510161) (xy 339.668923 3.52978)
			(xy 339.688542 3.544031) (xy 339.711606 3.551518) (xy 339.72373 3.551936) (xy 340.33587 3.551936)
			(xy 340.344342 3.551693) (xy 340.360875 3.547975) (xy 340.368636 3.54457) (xy 340.381611 3.538968)
			(xy 340.409496 3.534428) (xy 340.437557 3.537705) (xy 340.463646 3.548546) (xy 340.485765 3.566121)
			(xy 340.494366 3.577336) (xy 340.509767 3.59821) (xy 340.545331 3.635974) (xy 340.585684 3.668572)
			(xy 340.630081 3.695401) (xy 340.677704 3.715968) (xy 340.727675 3.729894) (xy 340.779071 3.736921)
			(xy 340.805008 3.737356) (xy 340.83227 3.736851) (xy 340.88624 3.729088) (xy 340.938554 3.713721)
			(xy 340.988148 3.691062) (xy 341.034011 3.661574) (xy 341.075209 3.625857) (xy 341.110903 3.584639)
			(xy 341.140365 3.53876) (xy 341.162996 3.489153) (xy 341.178334 3.43683) (xy 341.186067 3.382857)
			(xy 341.186516 3.355594) (xy 341.186516 2.491994) (xy 341.186082 2.464734) (xy 341.178325 2.410768)
			(xy 341.162969 2.358455) (xy 341.140327 2.308859) (xy 341.11086 2.262988) (xy 341.075167 2.221776)
			(xy 341.033974 2.186061) (xy 340.988119 2.156569) (xy 340.938534 2.133902) (xy 340.886229 2.118518)
			(xy 340.832268 2.110733) (xy 340.805008 2.110232) (xy 340.778815 2.11072) (xy 340.726925 2.117909)
			(xy 340.676505 2.132127) (xy 340.628503 2.153106) (xy 340.583821 2.180452) (xy 340.543298 2.213651)
			(xy 340.507695 2.25208) (xy 340.492334 2.2733) (xy 340.483828 2.284517) (xy 340.461977 2.302242)
			(xy 340.436126 2.313351) (xy 340.408228 2.317006) (xy 340.380389 2.312931) (xy 340.367366 2.30759)
			(xy 340.359877 2.304427) (xy 340.343996 2.300964) (xy 340.33587 2.300732) (xy 339.72373 2.300732)
			(xy 339.711609 2.301185) (xy 339.688553 2.308669) (xy 339.668937 2.322912) (xy 339.654685 2.34252)
			(xy 339.647191 2.365574) (xy 339.646768 2.377694) (xy 336.99589 2.377694) (xy 337.008712 2.368011)
			(xy 337.072082 2.310242) (xy 337.129851 2.246872) (xy 337.181527 2.178443) (xy 337.226668 2.105537)
			(xy 337.26489 2.028777) (xy 337.295866 1.948818) (xy 337.319333 1.866342) (xy 337.335089 1.782052)
			(xy 337.343001 1.696669) (xy 337.343496 1.653794) (xy 337.343001 1.610919) (xy 341.838267 1.610919)
			(xy 341.838267 1.696669) (xy 341.846179 1.782052) (xy 341.861935 1.866342) (xy 341.885402 1.948818)
			(xy 341.916378 2.028777) (xy 341.9546 2.105537) (xy 341.999741 2.178443) (xy 342.051417 2.246872)
			(xy 342.109186 2.310242) (xy 342.172556 2.368011) (xy 342.240985 2.419687) (xy 342.313891 2.464828)
			(xy 342.390651 2.50305) (xy 342.47061 2.534026) (xy 342.553086 2.557493) (xy 342.637376 2.573249)
			(xy 342.722759 2.581161) (xy 342.808509 2.581161) (xy 342.893892 2.573249) (xy 342.978182 2.557493)
			(xy 343.060658 2.534026) (xy 343.140617 2.50305) (xy 343.217377 2.464828) (xy 343.290283 2.419687)
			(xy 343.358712 2.368011) (xy 343.422082 2.310242) (xy 343.479851 2.246872) (xy 343.531527 2.178443)
			(xy 343.576668 2.105537) (xy 343.61489 2.028777) (xy 343.645866 1.948818) (xy 343.669333 1.866342)
			(xy 343.685089 1.782052) (xy 343.693001 1.696669) (xy 343.693496 1.653794) (xy 343.693001 1.610919)
			(xy 373.705107 1.610919) (xy 373.705107 1.696669) (xy 373.713019 1.782052) (xy 373.728775 1.866342)
			(xy 373.752242 1.948818) (xy 373.783218 2.028777) (xy 373.82144 2.105537) (xy 373.866581 2.178443)
			(xy 373.918257 2.246872) (xy 373.976026 2.310242) (xy 374.039396 2.368011) (xy 374.107825 2.419687)
			(xy 374.180731 2.464828) (xy 374.257491 2.50305) (xy 374.33745 2.534026) (xy 374.419926 2.557493)
			(xy 374.504216 2.573249) (xy 374.589599 2.581161) (xy 374.675349 2.581161) (xy 374.760732 2.573249)
			(xy 374.845022 2.557493) (xy 374.927498 2.534026) (xy 375.007457 2.50305) (xy 375.02966 2.491994)
			(xy 376.211592 2.491994) (xy 376.211592 3.355594) (xy 376.212129 3.38285) (xy 376.219882 3.436807)
			(xy 376.235231 3.489112) (xy 376.257865 3.538702) (xy 376.287322 3.584569) (xy 376.323005 3.625779)
			(xy 376.364186 3.661494) (xy 376.410029 3.690988) (xy 376.459601 3.713661) (xy 376.511894 3.729053)
			(xy 376.565845 3.736849) (xy 376.5931 3.737356) (xy 376.619293 3.736879) (xy 376.671184 3.729688)
			(xy 376.721605 3.715469) (xy 376.769607 3.694488) (xy 376.814289 3.667141) (xy 376.854812 3.63394)
			(xy 376.890413 3.595509) (xy 376.905774 3.574288) (xy 376.91427 3.563064) (xy 376.936125 3.545341)
			(xy 376.961978 3.534233) (xy 376.989878 3.53058) (xy 377.017719 3.534656) (xy 377.030742 3.539998)
			(xy 377.038231 3.543163) (xy 377.054112 3.546625) (xy 377.062238 3.546856) (xy 377.674378 3.546856)
			(xy 377.6865 3.546421) (xy 377.709559 3.538934) (xy 377.729175 3.524687) (xy 377.743427 3.505074)
			(xy 377.750919 3.482016) (xy 377.75134 3.469894) (xy 377.75134 2.372614) (xy 377.750928 2.36049)
			(xy 377.743437 2.337428) (xy 377.729184 2.317811) (xy 377.709565 2.30356) (xy 377.686502 2.296071)
			(xy 377.674378 2.295652) (xy 377.062238 2.295652) (xy 377.053766 2.295898) (xy 377.037234 2.299614)
			(xy 377.029472 2.303018) (xy 377.016495 2.308616) (xy 376.988611 2.313158) (xy 376.96055 2.309883)
			(xy 376.934462 2.299042) (xy 376.912343 2.281467) (xy 376.903742 2.270252) (xy 376.88834 2.249379)
			(xy 376.852775 2.211615) (xy 376.812422 2.179018) (xy 376.768025 2.152189) (xy 376.720403 2.131621)
			(xy 376.670433 2.117695) (xy 376.619037 2.110668) (xy 376.5931 2.110232) (xy 376.565834 2.110656)
			(xy 376.511857 2.118421) (xy 376.459536 2.133792) (xy 376.409936 2.156456) (xy 376.364069 2.185951)
			(xy 376.322868 2.221677) (xy 376.287175 2.262904) (xy 376.257715 2.308794) (xy 376.235089 2.358412)
			(xy 376.219758 2.410745) (xy 376.212035 2.464727) (xy 376.211592 2.491994) (xy 375.02966 2.491994)
			(xy 375.084217 2.464828) (xy 375.157123 2.419687) (xy 375.225552 2.368011) (xy 375.288922 2.310242)
			(xy 375.346691 2.246872) (xy 375.398367 2.178443) (xy 375.443508 2.105537) (xy 375.48173 2.028777)
			(xy 375.512706 1.948818) (xy 375.536173 1.866342) (xy 375.551929 1.782052) (xy 375.559841 1.696669)
			(xy 375.560336 1.653794) (xy 375.559841 1.610919) (xy 380.055107 1.610919) (xy 380.055107 1.696669)
			(xy 380.063019 1.782052) (xy 380.078775 1.866342) (xy 380.102242 1.948818) (xy 380.133218 2.028777)
			(xy 380.17144 2.105537) (xy 380.216581 2.178443) (xy 380.268257 2.246872) (xy 380.326026 2.310242)
			(xy 380.389396 2.368011) (xy 380.457825 2.419687) (xy 380.530731 2.464828) (xy 380.607491 2.50305)
			(xy 380.68745 2.534026) (xy 380.769926 2.557493) (xy 380.854216 2.573249) (xy 380.939599 2.581161)
			(xy 381.025349 2.581161) (xy 381.110732 2.573249) (xy 381.195022 2.557493) (xy 381.277498 2.534026)
			(xy 381.357457 2.50305) (xy 381.434217 2.464828) (xy 381.507123 2.419687) (xy 381.575552 2.368011)
			(xy 381.638922 2.310242) (xy 381.696691 2.246872) (xy 381.748367 2.178443) (xy 381.793508 2.105537)
			(xy 381.83173 2.028777) (xy 381.862706 1.948818) (xy 381.886173 1.866342) (xy 381.901929 1.782052)
			(xy 381.909841 1.696669) (xy 381.910336 1.653794) (xy 381.909841 1.610919) (xy 381.901929 1.525536)
			(xy 381.886173 1.441246) (xy 381.862706 1.35877) (xy 381.83173 1.278811) (xy 381.793508 1.202051)
			(xy 381.748367 1.129145) (xy 381.696691 1.060716) (xy 381.638922 0.997346) (xy 381.575552 0.939577)
			(xy 381.507123 0.887901) (xy 381.434217 0.84276) (xy 381.357457 0.804538) (xy 381.277498 0.773562)
			(xy 381.195022 0.750095) (xy 381.110732 0.734339) (xy 381.025349 0.726427) (xy 380.939599 0.726427)
			(xy 380.854216 0.734339) (xy 380.769926 0.750095) (xy 380.68745 0.773562) (xy 380.607491 0.804538)
			(xy 380.530731 0.84276) (xy 380.457825 0.887901) (xy 380.389396 0.939577) (xy 380.326026 0.997346)
			(xy 380.268257 1.060716) (xy 380.216581 1.129145) (xy 380.17144 1.202051) (xy 380.133218 1.278811)
			(xy 380.102242 1.35877) (xy 380.078775 1.441246) (xy 380.063019 1.525536) (xy 380.055107 1.610919)
			(xy 375.559841 1.610919) (xy 375.551929 1.525536) (xy 375.536173 1.441246) (xy 375.512706 1.35877)
			(xy 375.48173 1.278811) (xy 375.443508 1.202051) (xy 375.398367 1.129145) (xy 375.346691 1.060716)
			(xy 375.288922 0.997346) (xy 375.225552 0.939577) (xy 375.157123 0.887901) (xy 375.084217 0.84276)
			(xy 375.007457 0.804538) (xy 374.927498 0.773562) (xy 374.845022 0.750095) (xy 374.760732 0.734339)
			(xy 374.675349 0.726427) (xy 374.589599 0.726427) (xy 374.504216 0.734339) (xy 374.419926 0.750095)
			(xy 374.33745 0.773562) (xy 374.257491 0.804538) (xy 374.180731 0.84276) (xy 374.107825 0.887901)
			(xy 374.039396 0.939577) (xy 373.976026 0.997346) (xy 373.918257 1.060716) (xy 373.866581 1.129145)
			(xy 373.82144 1.202051) (xy 373.783218 1.278811) (xy 373.752242 1.35877) (xy 373.728775 1.441246)
			(xy 373.713019 1.525536) (xy 373.705107 1.610919) (xy 343.693001 1.610919) (xy 343.685089 1.525536)
			(xy 343.669333 1.441246) (xy 343.645866 1.35877) (xy 343.61489 1.278811) (xy 343.576668 1.202051)
			(xy 343.531527 1.129145) (xy 343.479851 1.060716) (xy 343.422082 0.997346) (xy 343.358712 0.939577)
			(xy 343.290283 0.887901) (xy 343.217377 0.84276) (xy 343.140617 0.804538) (xy 343.060658 0.773562)
			(xy 342.978182 0.750095) (xy 342.893892 0.734339) (xy 342.808509 0.726427) (xy 342.722759 0.726427)
			(xy 342.637376 0.734339) (xy 342.553086 0.750095) (xy 342.47061 0.773562) (xy 342.390651 0.804538)
			(xy 342.313891 0.84276) (xy 342.240985 0.887901) (xy 342.172556 0.939577) (xy 342.109186 0.997346)
			(xy 342.051417 1.060716) (xy 341.999741 1.129145) (xy 341.9546 1.202051) (xy 341.916378 1.278811)
			(xy 341.885402 1.35877) (xy 341.861935 1.441246) (xy 341.846179 1.525536) (xy 341.838267 1.610919)
			(xy 337.343001 1.610919) (xy 337.335089 1.525536) (xy 337.319333 1.441246) (xy 337.295866 1.35877)
			(xy 337.26489 1.278811) (xy 337.226668 1.202051) (xy 337.181527 1.129145) (xy 337.129851 1.060716)
			(xy 337.072082 0.997346) (xy 337.008712 0.939577) (xy 336.940283 0.887901) (xy 336.867377 0.84276)
			(xy 336.790617 0.804538) (xy 336.710658 0.773562) (xy 336.628182 0.750095) (xy 336.543892 0.734339)
			(xy 336.458509 0.726427) (xy 336.372759 0.726427) (xy 336.287376 0.734339) (xy 336.203086 0.750095)
			(xy 336.12061 0.773562) (xy 336.040651 0.804538) (xy 335.963891 0.84276) (xy 335.890985 0.887901)
			(xy 335.822556 0.939577) (xy 335.759186 0.997346) (xy 335.701417 1.060716) (xy 335.649741 1.129145)
			(xy 335.6046 1.202051) (xy 335.566378 1.278811) (xy 335.535402 1.35877) (xy 335.511935 1.441246)
			(xy 335.496179 1.525536) (xy 335.488267 1.610919) (xy 333.050655 1.610919) (xy 333.042743 1.525536)
			(xy 333.026987 1.441246) (xy 333.00352 1.35877) (xy 332.972544 1.278811) (xy 332.934322 1.202051)
			(xy 332.889181 1.129145) (xy 332.837505 1.060716) (xy 332.779736 0.997346) (xy 332.716366 0.939577)
			(xy 332.647937 0.887901) (xy 332.575031 0.84276) (xy 332.498271 0.804538) (xy 332.418312 0.773562)
			(xy 332.335836 0.750095) (xy 332.251546 0.734339) (xy 332.166163 0.726427) (xy 332.080413 0.726427)
			(xy 331.99503 0.734339) (xy 331.91074 0.750095) (xy 331.828264 0.773562) (xy 331.748305 0.804538)
			(xy 331.671545 0.84276) (xy 331.598639 0.887901) (xy 331.53021 0.939577) (xy 331.46684 0.997346)
			(xy 331.409071 1.060716) (xy 331.357395 1.129145) (xy 331.312254 1.202051) (xy 331.274032 1.278811)
			(xy 331.243056 1.35877) (xy 331.219589 1.441246) (xy 331.203833 1.525536) (xy 331.195921 1.610919)
			(xy 326.700655 1.610919) (xy 326.692743 1.525536) (xy 326.676987 1.441246) (xy 326.65352 1.35877)
			(xy 326.622544 1.278811) (xy 326.584322 1.202051) (xy 326.539181 1.129145) (xy 326.487505 1.060716)
			(xy 326.429736 0.997346) (xy 326.366366 0.939577) (xy 326.297937 0.887901) (xy 326.225031 0.84276)
			(xy 326.148271 0.804538) (xy 326.068312 0.773562) (xy 325.985836 0.750095) (xy 325.901546 0.734339)
			(xy 325.816163 0.726427) (xy 325.730413 0.726427) (xy 325.64503 0.734339) (xy 325.56074 0.750095)
			(xy 325.478264 0.773562) (xy 325.398305 0.804538) (xy 325.321545 0.84276) (xy 325.248639 0.887901)
			(xy 325.18021 0.939577) (xy 325.11684 0.997346) (xy 325.059071 1.060716) (xy 325.007395 1.129145)
			(xy 324.962254 1.202051) (xy 324.924032 1.278811) (xy 324.893056 1.35877) (xy 324.869589 1.441246)
			(xy 324.853833 1.525536) (xy 324.845921 1.610919) (xy 265.125975 1.610919) (xy 265.118063 1.525536)
			(xy 265.102307 1.441246) (xy 265.07884 1.35877) (xy 265.047864 1.278811) (xy 265.009642 1.202051)
			(xy 264.964501 1.129145) (xy 264.912825 1.060716) (xy 264.855056 0.997346) (xy 264.791686 0.939577)
			(xy 264.723257 0.887901) (xy 264.650351 0.84276) (xy 264.573591 0.804538) (xy 264.493632 0.773562)
			(xy 264.411156 0.750095) (xy 264.326866 0.734339) (xy 264.241483 0.726427) (xy 264.155733 0.726427)
			(xy 264.07035 0.734339) (xy 263.98606 0.750095) (xy 263.903584 0.773562) (xy 263.823625 0.804538)
			(xy 263.746865 0.84276) (xy 263.673959 0.887901) (xy 263.60553 0.939577) (xy 263.54216 0.997346)
			(xy 263.484391 1.060716) (xy 263.432715 1.129145) (xy 263.387574 1.202051) (xy 263.349352 1.278811)
			(xy 263.318376 1.35877) (xy 263.294909 1.441246) (xy 263.279153 1.525536) (xy 263.271241 1.610919)
			(xy 258.775975 1.610919) (xy 258.768063 1.525536) (xy 258.752307 1.441246) (xy 258.72884 1.35877)
			(xy 258.697864 1.278811) (xy 258.659642 1.202051) (xy 258.614501 1.129145) (xy 258.562825 1.060716)
			(xy 258.505056 0.997346) (xy 258.441686 0.939577) (xy 258.373257 0.887901) (xy 258.300351 0.84276)
			(xy 258.223591 0.804538) (xy 258.143632 0.773562) (xy 258.061156 0.750095) (xy 257.976866 0.734339)
			(xy 257.891483 0.726427) (xy 257.805733 0.726427) (xy 257.72035 0.734339) (xy 257.63606 0.750095)
			(xy 257.553584 0.773562) (xy 257.473625 0.804538) (xy 257.396865 0.84276) (xy 257.323959 0.887901)
			(xy 257.25553 0.939577) (xy 257.19216 0.997346) (xy 257.134391 1.060716) (xy 257.082715 1.129145)
			(xy 257.037574 1.202051) (xy 256.999352 1.278811) (xy 256.968376 1.35877) (xy 256.944909 1.441246)
			(xy 256.929153 1.525536) (xy 256.921241 1.610919) (xy 254.465119 1.610919) (xy 254.465087 1.608125)
			(xy 254.457175 1.522742) (xy 254.441419 1.438452) (xy 254.417952 1.355976) (xy 254.386976 1.276017)
			(xy 254.348754 1.199257) (xy 254.303613 1.126351) (xy 254.251937 1.057922) (xy 254.194168 0.994552)
			(xy 254.130798 0.936783) (xy 254.062369 0.885107) (xy 253.989463 0.839966) (xy 253.912703 0.801744)
			(xy 253.832744 0.770768) (xy 253.750268 0.747301) (xy 253.665978 0.731545) (xy 253.580595 0.723633)
			(xy 253.494845 0.723633) (xy 253.409462 0.731545) (xy 253.325172 0.747301) (xy 253.242696 0.770768)
			(xy 253.162737 0.801744) (xy 253.085977 0.839966) (xy 253.013071 0.885107) (xy 252.944642 0.936783)
			(xy 252.881272 0.994552) (xy 252.823503 1.057922) (xy 252.771827 1.126351) (xy 252.726686 1.199257)
			(xy 252.688464 1.276017) (xy 252.657488 1.355976) (xy 252.634021 1.438452) (xy 252.618265 1.522742)
			(xy 252.610353 1.608125) (xy 248.115087 1.608125) (xy 248.107175 1.522742) (xy 248.091419 1.438452)
			(xy 248.067952 1.355976) (xy 248.036976 1.276017) (xy 247.998754 1.199257) (xy 247.953613 1.126351)
			(xy 247.901937 1.057922) (xy 247.844168 0.994552) (xy 247.780798 0.936783) (xy 247.712369 0.885107)
			(xy 247.639463 0.839966) (xy 247.562703 0.801744) (xy 247.482744 0.770768) (xy 247.400268 0.747301)
			(xy 247.315978 0.731545) (xy 247.230595 0.723633) (xy 247.144845 0.723633) (xy 247.059462 0.731545)
			(xy 246.975172 0.747301) (xy 246.892696 0.770768) (xy 246.812737 0.801744) (xy 246.735977 0.839966)
			(xy 246.663071 0.885107) (xy 246.594642 0.936783) (xy 246.531272 0.994552) (xy 246.473503 1.057922)
			(xy 246.421827 1.126351) (xy 246.376686 1.199257) (xy 246.338464 1.276017) (xy 246.307488 1.355976)
			(xy 246.284021 1.438452) (xy 246.268265 1.522742) (xy 246.260353 1.608125) (xy 186.540407 1.608125)
			(xy 186.532495 1.522742) (xy 186.516739 1.438452) (xy 186.493272 1.355976) (xy 186.462296 1.276017)
			(xy 186.424074 1.199257) (xy 186.378933 1.126351) (xy 186.327257 1.057922) (xy 186.269488 0.994552)
			(xy 186.206118 0.936783) (xy 186.137689 0.885107) (xy 186.064783 0.839966) (xy 185.988023 0.801744)
			(xy 185.908064 0.770768) (xy 185.825588 0.747301) (xy 185.741298 0.731545) (xy 185.655915 0.723633)
			(xy 185.570165 0.723633) (xy 185.484782 0.731545) (xy 185.400492 0.747301) (xy 185.318016 0.770768)
			(xy 185.238057 0.801744) (xy 185.161297 0.839966) (xy 185.088391 0.885107) (xy 185.019962 0.936783)
			(xy 184.956592 0.994552) (xy 184.898823 1.057922) (xy 184.847147 1.126351) (xy 184.802006 1.199257)
			(xy 184.763784 1.276017) (xy 184.732808 1.355976) (xy 184.709341 1.438452) (xy 184.693585 1.522742)
			(xy 184.685673 1.608125) (xy 180.190407 1.608125) (xy 180.182495 1.522742) (xy 180.166739 1.438452)
			(xy 180.143272 1.355976) (xy 180.112296 1.276017) (xy 180.074074 1.199257) (xy 180.028933 1.126351)
			(xy 179.977257 1.057922) (xy 179.919488 0.994552) (xy 179.856118 0.936783) (xy 179.787689 0.885107)
			(xy 179.714783 0.839966) (xy 179.638023 0.801744) (xy 179.558064 0.770768) (xy 179.475588 0.747301)
			(xy 179.391298 0.731545) (xy 179.305915 0.723633) (xy 179.220165 0.723633) (xy 179.134782 0.731545)
			(xy 179.050492 0.747301) (xy 178.968016 0.770768) (xy 178.888057 0.801744) (xy 178.811297 0.839966)
			(xy 178.738391 0.885107) (xy 178.669962 0.936783) (xy 178.606592 0.994552) (xy 178.548823 1.057922)
			(xy 178.497147 1.126351) (xy 178.452006 1.199257) (xy 178.413784 1.276017) (xy 178.382808 1.355976)
			(xy 178.359341 1.438452) (xy 178.343585 1.522742) (xy 178.335673 1.608125) (xy 84.135094 1.608125)
			(xy 84.162197 1.489382) (xy 84.185766 1.350662) (xy 84.20152 1.210839) (xy 84.20941 1.070352) (xy 84.20989 0.999998)
			(xy 84.20989 -0.931875) (xy 208.043513 -0.931875) (xy 208.043513 -0.846125) (xy 208.051425 -0.760742)
			(xy 208.067181 -0.676452) (xy 208.090648 -0.593976) (xy 208.121624 -0.514017) (xy 208.159846 -0.437257)
			(xy 208.204987 -0.364351) (xy 208.256663 -0.295922) (xy 208.314432 -0.232552) (xy 208.377802 -0.174783)
			(xy 208.446231 -0.123107) (xy 208.519137 -0.077966) (xy 208.595897 -0.039744) (xy 208.675856 -0.008768)
			(xy 208.758332 0.014699) (xy 208.842622 0.030455) (xy 208.928005 0.038367) (xy 209.013755 0.038367)
			(xy 209.099138 0.030455) (xy 209.183428 0.014699) (xy 209.265904 -0.008768) (xy 209.345863 -0.039744)
			(xy 209.422623 -0.077966) (xy 209.495529 -0.123107) (xy 209.563958 -0.174783) (xy 209.627328 -0.232552)
			(xy 209.685097 -0.295922) (xy 209.736773 -0.364351) (xy 209.781914 -0.437257) (xy 209.820136 -0.514017)
			(xy 209.851112 -0.593976) (xy 209.874579 -0.676452) (xy 209.890335 -0.760742) (xy 209.898247 -0.846125)
			(xy 209.898742 -0.889) (xy 209.898247 -0.931875) (xy 214.393513 -0.931875) (xy 214.393513 -0.846125)
			(xy 214.401425 -0.760742) (xy 214.417181 -0.676452) (xy 214.440648 -0.593976) (xy 214.471624 -0.514017)
			(xy 214.509846 -0.437257) (xy 214.554987 -0.364351) (xy 214.606663 -0.295922) (xy 214.664432 -0.232552)
			(xy 214.727802 -0.174783) (xy 214.796231 -0.123107) (xy 214.869137 -0.077966) (xy 214.945897 -0.039744)
			(xy 215.025856 -0.008768) (xy 215.108332 0.014699) (xy 215.192622 0.030455) (xy 215.278005 0.038367)
			(xy 215.363755 0.038367) (xy 215.449138 0.030455) (xy 215.533428 0.014699) (xy 215.615904 -0.008768)
			(xy 215.695863 -0.039744) (xy 215.772623 -0.077966) (xy 215.845529 -0.123107) (xy 215.913958 -0.174783)
			(xy 215.977328 -0.232552) (xy 216.035097 -0.295922) (xy 216.086773 -0.364351) (xy 216.131914 -0.437257)
			(xy 216.170136 -0.514017) (xy 216.201112 -0.593976) (xy 216.224579 -0.676452) (xy 216.240335 -0.760742)
			(xy 216.248247 -0.846125) (xy 216.248742 -0.889) (xy 216.248247 -0.931875) (xy 246.260353 -0.931875)
			(xy 246.260353 -0.846125) (xy 246.268265 -0.760742) (xy 246.284021 -0.676452) (xy 246.307488 -0.593976)
			(xy 246.338464 -0.514017) (xy 246.376686 -0.437257) (xy 246.421827 -0.364351) (xy 246.473503 -0.295922)
			(xy 246.531272 -0.232552) (xy 246.594642 -0.174783) (xy 246.663071 -0.123107) (xy 246.735977 -0.077966)
			(xy 246.812737 -0.039744) (xy 246.892696 -0.008768) (xy 246.975172 0.014699) (xy 247.059462 0.030455)
			(xy 247.144845 0.038367) (xy 247.230595 0.038367) (xy 247.315978 0.030455) (xy 247.400268 0.014699)
			(xy 247.482744 -0.008768) (xy 247.562703 -0.039744) (xy 247.639463 -0.077966) (xy 247.712369 -0.123107)
			(xy 247.780798 -0.174783) (xy 247.844168 -0.232552) (xy 247.901937 -0.295922) (xy 247.953613 -0.364351)
			(xy 247.998754 -0.437257) (xy 248.036976 -0.514017) (xy 248.067952 -0.593976) (xy 248.091419 -0.676452)
			(xy 248.107175 -0.760742) (xy 248.115087 -0.846125) (xy 248.115582 -0.889) (xy 248.115087 -0.931875)
			(xy 252.610353 -0.931875) (xy 252.610353 -0.846125) (xy 252.618265 -0.760742) (xy 252.634021 -0.676452)
			(xy 252.657488 -0.593976) (xy 252.688464 -0.514017) (xy 252.726686 -0.437257) (xy 252.771827 -0.364351)
			(xy 252.823503 -0.295922) (xy 252.881272 -0.232552) (xy 252.944642 -0.174783) (xy 253.013071 -0.123107)
			(xy 253.085977 -0.077966) (xy 253.162737 -0.039744) (xy 253.242696 -0.008768) (xy 253.325172 0.014699)
			(xy 253.409462 0.030455) (xy 253.494845 0.038367) (xy 253.580595 0.038367) (xy 253.665978 0.030455)
			(xy 253.750268 0.014699) (xy 253.832744 -0.008768) (xy 253.912703 -0.039744) (xy 253.989463 -0.077966)
			(xy 254.062369 -0.123107) (xy 254.130798 -0.174783) (xy 254.194168 -0.232552) (xy 254.251937 -0.295922)
			(xy 254.303613 -0.364351) (xy 254.348754 -0.437257) (xy 254.386976 -0.514017) (xy 254.417952 -0.593976)
			(xy 254.441419 -0.676452) (xy 254.457175 -0.760742) (xy 254.465087 -0.846125) (xy 254.465582 -0.889)
			(xy 254.465119 -0.929081) (xy 256.921241 -0.929081) (xy 256.921241 -0.843331) (xy 256.929153 -0.757948)
			(xy 256.944909 -0.673658) (xy 256.968376 -0.591182) (xy 256.999352 -0.511223) (xy 257.037574 -0.434463)
			(xy 257.082715 -0.361557) (xy 257.134391 -0.293128) (xy 257.19216 -0.229758) (xy 257.25553 -0.171989)
			(xy 257.323959 -0.120313) (xy 257.396865 -0.075172) (xy 257.473625 -0.03695) (xy 257.553584 -0.005974)
			(xy 257.63606 0.017493) (xy 257.72035 0.033249) (xy 257.805733 0.041161) (xy 257.891483 0.041161)
			(xy 257.976866 0.033249) (xy 258.061156 0.017493) (xy 258.143632 -0.005974) (xy 258.223591 -0.03695)
			(xy 258.245794 -0.048006) (xy 261.85622 -0.048006) (xy 261.85622 0.815594) (xy 261.856706 0.842863)
			(xy 261.864468 0.896847) (xy 261.879833 0.949177) (xy 261.90249 0.998787) (xy 261.931976 1.044668)
			(xy 261.967691 1.085885) (xy 262.008908 1.1216) (xy 262.054789 1.151086) (xy 262.104399 1.173743)
			(xy 262.156729 1.189108) (xy 262.210713 1.19687) (xy 262.265251 1.19687) (xy 262.319235 1.189108)
			(xy 262.371565 1.173743) (xy 262.421175 1.151086) (xy 262.467056 1.1216) (xy 262.508273 1.085885)
			(xy 262.543988 1.044668) (xy 262.573474 0.998787) (xy 262.596131 0.949177) (xy 262.611496 0.896847)
			(xy 262.619258 0.842863) (xy 262.619744 0.815594) (xy 262.619744 -0.048006) (xy 262.619258 -0.075275)
			(xy 262.611496 -0.129259) (xy 262.596131 -0.181589) (xy 262.573474 -0.231199) (xy 262.543988 -0.27708)
			(xy 262.508273 -0.318297) (xy 262.467056 -0.354012) (xy 262.421175 -0.383498) (xy 262.371565 -0.406155)
			(xy 262.319235 -0.42152) (xy 262.265251 -0.429282) (xy 262.210713 -0.429282) (xy 262.156729 -0.42152)
			(xy 262.104399 -0.406155) (xy 262.054789 -0.383498) (xy 262.008908 -0.354012) (xy 261.967691 -0.318297)
			(xy 261.931976 -0.27708) (xy 261.90249 -0.231199) (xy 261.879833 -0.181589) (xy 261.864468 -0.129259)
			(xy 261.856706 -0.075275) (xy 261.85622 -0.048006) (xy 258.245794 -0.048006) (xy 258.300351 -0.075172)
			(xy 258.373257 -0.120313) (xy 258.441686 -0.171989) (xy 258.505056 -0.229758) (xy 258.562825 -0.293128)
			(xy 258.614501 -0.361557) (xy 258.659642 -0.434463) (xy 258.697864 -0.511223) (xy 258.72884 -0.591182)
			(xy 258.752307 -0.673658) (xy 258.768063 -0.757948) (xy 258.775975 -0.843331) (xy 258.77647 -0.886206)
			(xy 258.775975 -0.929081) (xy 263.271241 -0.929081) (xy 263.271241 -0.843331) (xy 263.279153 -0.757948)
			(xy 263.294909 -0.673658) (xy 263.318376 -0.591182) (xy 263.349352 -0.511223) (xy 263.387574 -0.434463)
			(xy 263.432715 -0.361557) (xy 263.484391 -0.293128) (xy 263.54216 -0.229758) (xy 263.60553 -0.171989)
			(xy 263.673959 -0.120313) (xy 263.746865 -0.075172) (xy 263.823625 -0.03695) (xy 263.903584 -0.005974)
			(xy 263.98606 0.017493) (xy 264.07035 0.033249) (xy 264.155733 0.041161) (xy 264.241483 0.041161)
			(xy 264.326866 0.033249) (xy 264.411156 0.017493) (xy 264.493632 -0.005974) (xy 264.573591 -0.03695)
			(xy 264.650351 -0.075172) (xy 264.723257 -0.120313) (xy 264.791686 -0.171989) (xy 264.855056 -0.229758)
			(xy 264.912825 -0.293128) (xy 264.964501 -0.361557) (xy 265.009642 -0.434463) (xy 265.047864 -0.511223)
			(xy 265.07884 -0.591182) (xy 265.102307 -0.673658) (xy 265.118063 -0.757948) (xy 265.125975 -0.843331)
			(xy 265.12647 -0.886206) (xy 265.125975 -0.929081) (xy 324.845921 -0.929081) (xy 324.845921 -0.843331)
			(xy 324.853833 -0.757948) (xy 324.869589 -0.673658) (xy 324.893056 -0.591182) (xy 324.924032 -0.511223)
			(xy 324.962254 -0.434463) (xy 325.007395 -0.361557) (xy 325.059071 -0.293128) (xy 325.11684 -0.229758)
			(xy 325.18021 -0.171989) (xy 325.248639 -0.120313) (xy 325.321545 -0.075172) (xy 325.398305 -0.03695)
			(xy 325.478264 -0.005974) (xy 325.56074 0.017493) (xy 325.64503 0.033249) (xy 325.730413 0.041161)
			(xy 325.816163 0.041161) (xy 325.901546 0.033249) (xy 325.985836 0.017493) (xy 326.068312 -0.005974)
			(xy 326.148271 -0.03695) (xy 326.170474 -0.048006) (xy 327.352152 -0.048006) (xy 327.352152 0.815594)
			(xy 327.352638 0.842863) (xy 327.3604 0.896847) (xy 327.375765 0.949177) (xy 327.398422 0.998787)
			(xy 327.427908 1.044668) (xy 327.463623 1.085885) (xy 327.50484 1.1216) (xy 327.550721 1.151086)
			(xy 327.600331 1.173743) (xy 327.652661 1.189108) (xy 327.706645 1.19687) (xy 327.761183 1.19687)
			(xy 327.815167 1.189108) (xy 327.867497 1.173743) (xy 327.917107 1.151086) (xy 327.962988 1.1216)
			(xy 328.004205 1.085885) (xy 328.03992 1.044668) (xy 328.069406 0.998787) (xy 328.092063 0.949177)
			(xy 328.107428 0.896847) (xy 328.11519 0.842863) (xy 328.115676 0.815594) (xy 328.115676 -0.048006)
			(xy 328.11519 -0.075275) (xy 328.107428 -0.129259) (xy 328.092063 -0.181589) (xy 328.069406 -0.231199)
			(xy 328.03992 -0.27708) (xy 328.004205 -0.318297) (xy 327.962988 -0.354012) (xy 327.917107 -0.383498)
			(xy 327.867497 -0.406155) (xy 327.815167 -0.42152) (xy 327.761183 -0.429282) (xy 327.706645 -0.429282)
			(xy 327.652661 -0.42152) (xy 327.600331 -0.406155) (xy 327.550721 -0.383498) (xy 327.50484 -0.354012)
			(xy 327.463623 -0.318297) (xy 327.427908 -0.27708) (xy 327.398422 -0.231199) (xy 327.375765 -0.181589)
			(xy 327.3604 -0.129259) (xy 327.352638 -0.075275) (xy 327.352152 -0.048006) (xy 326.170474 -0.048006)
			(xy 326.225031 -0.075172) (xy 326.297937 -0.120313) (xy 326.366366 -0.171989) (xy 326.429736 -0.229758)
			(xy 326.487505 -0.293128) (xy 326.539181 -0.361557) (xy 326.584322 -0.434463) (xy 326.622544 -0.511223)
			(xy 326.65352 -0.591182) (xy 326.676987 -0.673658) (xy 326.692743 -0.757948) (xy 326.700655 -0.843331)
			(xy 326.70115 -0.886206) (xy 326.700655 -0.929081) (xy 331.195921 -0.929081) (xy 331.195921 -0.843331)
			(xy 331.203833 -0.757948) (xy 331.219589 -0.673658) (xy 331.243056 -0.591182) (xy 331.274032 -0.511223)
			(xy 331.312254 -0.434463) (xy 331.357395 -0.361557) (xy 331.409071 -0.293128) (xy 331.46684 -0.229758)
			(xy 331.53021 -0.171989) (xy 331.598639 -0.120313) (xy 331.671545 -0.075172) (xy 331.748305 -0.03695)
			(xy 331.828264 -0.005974) (xy 331.91074 0.017493) (xy 331.99503 0.033249) (xy 332.080413 0.041161)
			(xy 332.166163 0.041161) (xy 332.251546 0.033249) (xy 332.335836 0.017493) (xy 332.418312 -0.005974)
			(xy 332.498271 -0.03695) (xy 332.575031 -0.075172) (xy 332.647937 -0.120313) (xy 332.716366 -0.171989)
			(xy 332.779736 -0.229758) (xy 332.837505 -0.293128) (xy 332.889181 -0.361557) (xy 332.934322 -0.434463)
			(xy 332.972544 -0.511223) (xy 333.00352 -0.591182) (xy 333.026987 -0.673658) (xy 333.042743 -0.757948)
			(xy 333.050655 -0.843331) (xy 333.05115 -0.886206) (xy 333.050655 -0.929081) (xy 335.488267 -0.929081)
			(xy 335.488267 -0.843331) (xy 335.496179 -0.757948) (xy 335.511935 -0.673658) (xy 335.535402 -0.591182)
			(xy 335.566378 -0.511223) (xy 335.6046 -0.434463) (xy 335.649741 -0.361557) (xy 335.701417 -0.293128)
			(xy 335.759186 -0.229758) (xy 335.822556 -0.171989) (xy 335.890985 -0.120313) (xy 335.963891 -0.075172)
			(xy 336.040651 -0.03695) (xy 336.12061 -0.005974) (xy 336.203086 0.017493) (xy 336.287376 0.033249)
			(xy 336.372759 0.041161) (xy 336.458509 0.041161) (xy 336.543892 0.033249) (xy 336.628182 0.017493)
			(xy 336.710658 -0.005974) (xy 336.790617 -0.03695) (xy 336.81282 -0.048006) (xy 340.4235 -0.048006)
			(xy 340.4235 0.815594) (xy 340.423986 0.842845) (xy 340.431742 0.896793) (xy 340.447097 0.949088)
			(xy 340.469739 0.998665) (xy 340.499205 1.044515) (xy 340.534896 1.085706) (xy 340.576087 1.121397)
			(xy 340.621937 1.150863) (xy 340.671514 1.173505) (xy 340.723809 1.18886) (xy 340.777757 1.196616)
			(xy 340.832259 1.196616) (xy 340.886207 1.18886) (xy 340.938502 1.173505) (xy 340.988079 1.150863)
			(xy 341.033929 1.121397) (xy 341.07512 1.085706) (xy 341.110811 1.044515) (xy 341.140277 0.998665)
			(xy 341.162919 0.949088) (xy 341.178274 0.896793) (xy 341.18603 0.842845) (xy 341.186516 0.815594)
			(xy 341.186516 -0.048006) (xy 341.18603 -0.075257) (xy 341.178274 -0.129205) (xy 341.162919 -0.1815)
			(xy 341.140277 -0.231077) (xy 341.110811 -0.276927) (xy 341.07512 -0.318118) (xy 341.033929 -0.353809)
			(xy 340.988079 -0.383275) (xy 340.938502 -0.405917) (xy 340.886207 -0.421272) (xy 340.832259 -0.429028)
			(xy 340.777757 -0.429028) (xy 340.723809 -0.421272) (xy 340.671514 -0.405917) (xy 340.621937 -0.383275)
			(xy 340.576087 -0.353809) (xy 340.534896 -0.318118) (xy 340.499205 -0.276927) (xy 340.469739 -0.231077)
			(xy 340.447097 -0.1815) (xy 340.431742 -0.129205) (xy 340.423986 -0.075257) (xy 340.4235 -0.048006)
			(xy 336.81282 -0.048006) (xy 336.867377 -0.075172) (xy 336.940283 -0.120313) (xy 337.008712 -0.171989)
			(xy 337.072082 -0.229758) (xy 337.129851 -0.293128) (xy 337.181527 -0.361557) (xy 337.226668 -0.434463)
			(xy 337.26489 -0.511223) (xy 337.295866 -0.591182) (xy 337.319333 -0.673658) (xy 337.335089 -0.757948)
			(xy 337.343001 -0.843331) (xy 337.343496 -0.886206) (xy 337.343001 -0.929081) (xy 341.838267 -0.929081)
			(xy 341.838267 -0.843331) (xy 341.846179 -0.757948) (xy 341.861935 -0.673658) (xy 341.885402 -0.591182)
			(xy 341.916378 -0.511223) (xy 341.9546 -0.434463) (xy 341.999741 -0.361557) (xy 342.051417 -0.293128)
			(xy 342.109186 -0.229758) (xy 342.172556 -0.171989) (xy 342.240985 -0.120313) (xy 342.313891 -0.075172)
			(xy 342.390651 -0.03695) (xy 342.47061 -0.005974) (xy 342.553086 0.017493) (xy 342.637376 0.033249)
			(xy 342.722759 0.041161) (xy 342.808509 0.041161) (xy 342.893892 0.033249) (xy 342.978182 0.017493)
			(xy 343.060658 -0.005974) (xy 343.140617 -0.03695) (xy 343.217377 -0.075172) (xy 343.290283 -0.120313)
			(xy 343.358712 -0.171989) (xy 343.422082 -0.229758) (xy 343.479851 -0.293128) (xy 343.531527 -0.361557)
			(xy 343.576668 -0.434463) (xy 343.61489 -0.511223) (xy 343.645866 -0.591182) (xy 343.669333 -0.673658)
			(xy 343.685089 -0.757948) (xy 343.693001 -0.843331) (xy 343.693496 -0.886206) (xy 343.693001 -0.929081)
			(xy 373.705107 -0.929081) (xy 373.705107 -0.843331) (xy 373.713019 -0.757948) (xy 373.728775 -0.673658)
			(xy 373.752242 -0.591182) (xy 373.783218 -0.511223) (xy 373.82144 -0.434463) (xy 373.866581 -0.361557)
			(xy 373.918257 -0.293128) (xy 373.976026 -0.229758) (xy 374.039396 -0.171989) (xy 374.107825 -0.120313)
			(xy 374.180731 -0.075172) (xy 374.257491 -0.03695) (xy 374.33745 -0.005974) (xy 374.419926 0.017493)
			(xy 374.504216 0.033249) (xy 374.589599 0.041161) (xy 374.675349 0.041161) (xy 374.760732 0.033249)
			(xy 374.845022 0.017493) (xy 374.927498 -0.005974) (xy 375.007457 -0.03695) (xy 375.02966 -0.048006)
			(xy 376.211592 -0.048006) (xy 376.211592 0.815594) (xy 376.212078 0.842845) (xy 376.219834 0.896793)
			(xy 376.235189 0.949088) (xy 376.257831 0.998665) (xy 376.287297 1.044515) (xy 376.322988 1.085706)
			(xy 376.364179 1.121397) (xy 376.410029 1.150863) (xy 376.459606 1.173505) (xy 376.511901 1.18886)
			(xy 376.565849 1.196616) (xy 376.620351 1.196616) (xy 376.674299 1.18886) (xy 376.726594 1.173505)
			(xy 376.776171 1.150863) (xy 376.822021 1.121397) (xy 376.863212 1.085706) (xy 376.898903 1.044515)
			(xy 376.928369 0.998665) (xy 376.951011 0.949088) (xy 376.966366 0.896793) (xy 376.974122 0.842845)
			(xy 376.974608 0.815594) (xy 376.974608 -0.048006) (xy 376.974122 -0.075257) (xy 376.966366 -0.129205)
			(xy 376.951011 -0.1815) (xy 376.928369 -0.231077) (xy 376.898903 -0.276927) (xy 376.863212 -0.318118)
			(xy 376.822021 -0.353809) (xy 376.776171 -0.383275) (xy 376.726594 -0.405917) (xy 376.674299 -0.421272)
			(xy 376.620351 -0.429028) (xy 376.565849 -0.429028) (xy 376.511901 -0.421272) (xy 376.459606 -0.405917)
			(xy 376.410029 -0.383275) (xy 376.364179 -0.353809) (xy 376.322988 -0.318118) (xy 376.287297 -0.276927)
			(xy 376.257831 -0.231077) (xy 376.235189 -0.1815) (xy 376.219834 -0.129205) (xy 376.212078 -0.075257)
			(xy 376.211592 -0.048006) (xy 375.02966 -0.048006) (xy 375.084217 -0.075172) (xy 375.157123 -0.120313)
			(xy 375.225552 -0.171989) (xy 375.288922 -0.229758) (xy 375.346691 -0.293128) (xy 375.398367 -0.361557)
			(xy 375.443508 -0.434463) (xy 375.48173 -0.511223) (xy 375.512706 -0.591182) (xy 375.536173 -0.673658)
			(xy 375.551929 -0.757948) (xy 375.559841 -0.843331) (xy 375.560336 -0.886206) (xy 375.559841 -0.929081)
			(xy 380.055107 -0.929081) (xy 380.055107 -0.843331) (xy 380.063019 -0.757948) (xy 380.078775 -0.673658)
			(xy 380.102242 -0.591182) (xy 380.133218 -0.511223) (xy 380.17144 -0.434463) (xy 380.216581 -0.361557)
			(xy 380.268257 -0.293128) (xy 380.326026 -0.229758) (xy 380.389396 -0.171989) (xy 380.457825 -0.120313)
			(xy 380.530731 -0.075172) (xy 380.607491 -0.03695) (xy 380.68745 -0.005974) (xy 380.769926 0.017493)
			(xy 380.854216 0.033249) (xy 380.939599 0.041161) (xy 381.025349 0.041161) (xy 381.110732 0.033249)
			(xy 381.195022 0.017493) (xy 381.277498 -0.005974) (xy 381.357457 -0.03695) (xy 381.434217 -0.075172)
			(xy 381.507123 -0.120313) (xy 381.575552 -0.171989) (xy 381.638922 -0.229758) (xy 381.696691 -0.293128)
			(xy 381.748367 -0.361557) (xy 381.793508 -0.434463) (xy 381.83173 -0.511223) (xy 381.862706 -0.591182)
			(xy 381.886173 -0.673658) (xy 381.901929 -0.757948) (xy 381.909841 -0.843331) (xy 381.910336 -0.886206)
			(xy 381.909841 -0.929081) (xy 381.901929 -1.014464) (xy 381.886173 -1.098754) (xy 381.862706 -1.18123)
			(xy 381.83173 -1.261189) (xy 381.793508 -1.337949) (xy 381.748367 -1.410855) (xy 381.696691 -1.479284)
			(xy 381.638922 -1.542654) (xy 381.575552 -1.600423) (xy 381.507123 -1.652099) (xy 381.434217 -1.69724)
			(xy 381.357457 -1.735462) (xy 381.277498 -1.766438) (xy 381.195022 -1.789905) (xy 381.110732 -1.805661)
			(xy 381.025349 -1.813573) (xy 380.939599 -1.813573) (xy 380.854216 -1.805661) (xy 380.769926 -1.789905)
			(xy 380.68745 -1.766438) (xy 380.607491 -1.735462) (xy 380.530731 -1.69724) (xy 380.457825 -1.652099)
			(xy 380.389396 -1.600423) (xy 380.326026 -1.542654) (xy 380.268257 -1.479284) (xy 380.216581 -1.410855)
			(xy 380.17144 -1.337949) (xy 380.133218 -1.261189) (xy 380.102242 -1.18123) (xy 380.078775 -1.098754)
			(xy 380.063019 -1.014464) (xy 380.055107 -0.929081) (xy 375.559841 -0.929081) (xy 375.551929 -1.014464)
			(xy 375.536173 -1.098754) (xy 375.512706 -1.18123) (xy 375.48173 -1.261189) (xy 375.443508 -1.337949)
			(xy 375.398367 -1.410855) (xy 375.346691 -1.479284) (xy 375.288922 -1.542654) (xy 375.225552 -1.600423)
			(xy 375.157123 -1.652099) (xy 375.084217 -1.69724) (xy 375.007457 -1.735462) (xy 374.927498 -1.766438)
			(xy 374.845022 -1.789905) (xy 374.760732 -1.805661) (xy 374.675349 -1.813573) (xy 374.589599 -1.813573)
			(xy 374.504216 -1.805661) (xy 374.419926 -1.789905) (xy 374.33745 -1.766438) (xy 374.257491 -1.735462)
			(xy 374.180731 -1.69724) (xy 374.107825 -1.652099) (xy 374.039396 -1.600423) (xy 373.976026 -1.542654)
			(xy 373.918257 -1.479284) (xy 373.866581 -1.410855) (xy 373.82144 -1.337949) (xy 373.783218 -1.261189)
			(xy 373.752242 -1.18123) (xy 373.728775 -1.098754) (xy 373.713019 -1.014464) (xy 373.705107 -0.929081)
			(xy 343.693001 -0.929081) (xy 343.685089 -1.014464) (xy 343.669333 -1.098754) (xy 343.645866 -1.18123)
			(xy 343.61489 -1.261189) (xy 343.576668 -1.337949) (xy 343.531527 -1.410855) (xy 343.479851 -1.479284)
			(xy 343.422082 -1.542654) (xy 343.358712 -1.600423) (xy 343.290283 -1.652099) (xy 343.217377 -1.69724)
			(xy 343.140617 -1.735462) (xy 343.060658 -1.766438) (xy 342.978182 -1.789905) (xy 342.893892 -1.805661)
			(xy 342.808509 -1.813573) (xy 342.722759 -1.813573) (xy 342.637376 -1.805661) (xy 342.553086 -1.789905)
			(xy 342.47061 -1.766438) (xy 342.390651 -1.735462) (xy 342.313891 -1.69724) (xy 342.240985 -1.652099)
			(xy 342.172556 -1.600423) (xy 342.109186 -1.542654) (xy 342.051417 -1.479284) (xy 341.999741 -1.410855)
			(xy 341.9546 -1.337949) (xy 341.916378 -1.261189) (xy 341.885402 -1.18123) (xy 341.861935 -1.098754)
			(xy 341.846179 -1.014464) (xy 341.838267 -0.929081) (xy 337.343001 -0.929081) (xy 337.335089 -1.014464)
			(xy 337.319333 -1.098754) (xy 337.295866 -1.18123) (xy 337.26489 -1.261189) (xy 337.226668 -1.337949)
			(xy 337.181527 -1.410855) (xy 337.129851 -1.479284) (xy 337.072082 -1.542654) (xy 337.008712 -1.600423)
			(xy 336.940283 -1.652099) (xy 336.867377 -1.69724) (xy 336.790617 -1.735462) (xy 336.710658 -1.766438)
			(xy 336.628182 -1.789905) (xy 336.543892 -1.805661) (xy 336.458509 -1.813573) (xy 336.372759 -1.813573)
			(xy 336.287376 -1.805661) (xy 336.203086 -1.789905) (xy 336.12061 -1.766438) (xy 336.040651 -1.735462)
			(xy 335.963891 -1.69724) (xy 335.890985 -1.652099) (xy 335.822556 -1.600423) (xy 335.759186 -1.542654)
			(xy 335.701417 -1.479284) (xy 335.649741 -1.410855) (xy 335.6046 -1.337949) (xy 335.566378 -1.261189)
			(xy 335.535402 -1.18123) (xy 335.511935 -1.098754) (xy 335.496179 -1.014464) (xy 335.488267 -0.929081)
			(xy 333.050655 -0.929081) (xy 333.042743 -1.014464) (xy 333.026987 -1.098754) (xy 333.00352 -1.18123)
			(xy 332.972544 -1.261189) (xy 332.934322 -1.337949) (xy 332.889181 -1.410855) (xy 332.837505 -1.479284)
			(xy 332.779736 -1.542654) (xy 332.716366 -1.600423) (xy 332.647937 -1.652099) (xy 332.575031 -1.69724)
			(xy 332.498271 -1.735462) (xy 332.418312 -1.766438) (xy 332.335836 -1.789905) (xy 332.251546 -1.805661)
			(xy 332.166163 -1.813573) (xy 332.080413 -1.813573) (xy 331.99503 -1.805661) (xy 331.91074 -1.789905)
			(xy 331.828264 -1.766438) (xy 331.748305 -1.735462) (xy 331.671545 -1.69724) (xy 331.598639 -1.652099)
			(xy 331.53021 -1.600423) (xy 331.46684 -1.542654) (xy 331.409071 -1.479284) (xy 331.357395 -1.410855)
			(xy 331.312254 -1.337949) (xy 331.274032 -1.261189) (xy 331.243056 -1.18123) (xy 331.219589 -1.098754)
			(xy 331.203833 -1.014464) (xy 331.195921 -0.929081) (xy 326.700655 -0.929081) (xy 326.692743 -1.014464)
			(xy 326.676987 -1.098754) (xy 326.65352 -1.18123) (xy 326.622544 -1.261189) (xy 326.584322 -1.337949)
			(xy 326.539181 -1.410855) (xy 326.487505 -1.479284) (xy 326.429736 -1.542654) (xy 326.366366 -1.600423)
			(xy 326.297937 -1.652099) (xy 326.225031 -1.69724) (xy 326.148271 -1.735462) (xy 326.068312 -1.766438)
			(xy 325.985836 -1.789905) (xy 325.901546 -1.805661) (xy 325.816163 -1.813573) (xy 325.730413 -1.813573)
			(xy 325.64503 -1.805661) (xy 325.56074 -1.789905) (xy 325.478264 -1.766438) (xy 325.398305 -1.735462)
			(xy 325.321545 -1.69724) (xy 325.248639 -1.652099) (xy 325.18021 -1.600423) (xy 325.11684 -1.542654)
			(xy 325.059071 -1.479284) (xy 325.007395 -1.410855) (xy 324.962254 -1.337949) (xy 324.924032 -1.261189)
			(xy 324.893056 -1.18123) (xy 324.869589 -1.098754) (xy 324.853833 -1.014464) (xy 324.845921 -0.929081)
			(xy 265.125975 -0.929081) (xy 265.118063 -1.014464) (xy 265.102307 -1.098754) (xy 265.07884 -1.18123)
			(xy 265.047864 -1.261189) (xy 265.009642 -1.337949) (xy 264.964501 -1.410855) (xy 264.912825 -1.479284)
			(xy 264.855056 -1.542654) (xy 264.791686 -1.600423) (xy 264.723257 -1.652099) (xy 264.650351 -1.69724)
			(xy 264.573591 -1.735462) (xy 264.493632 -1.766438) (xy 264.411156 -1.789905) (xy 264.326866 -1.805661)
			(xy 264.241483 -1.813573) (xy 264.155733 -1.813573) (xy 264.07035 -1.805661) (xy 263.98606 -1.789905)
			(xy 263.903584 -1.766438) (xy 263.823625 -1.735462) (xy 263.746865 -1.69724) (xy 263.673959 -1.652099)
			(xy 263.60553 -1.600423) (xy 263.54216 -1.542654) (xy 263.484391 -1.479284) (xy 263.432715 -1.410855)
			(xy 263.387574 -1.337949) (xy 263.349352 -1.261189) (xy 263.318376 -1.18123) (xy 263.294909 -1.098754)
			(xy 263.279153 -1.014464) (xy 263.271241 -0.929081) (xy 258.775975 -0.929081) (xy 258.768063 -1.014464)
			(xy 258.752307 -1.098754) (xy 258.72884 -1.18123) (xy 258.697864 -1.261189) (xy 258.659642 -1.337949)
			(xy 258.614501 -1.410855) (xy 258.562825 -1.479284) (xy 258.505056 -1.542654) (xy 258.441686 -1.600423)
			(xy 258.373257 -1.652099) (xy 258.300351 -1.69724) (xy 258.223591 -1.735462) (xy 258.143632 -1.766438)
			(xy 258.061156 -1.789905) (xy 257.976866 -1.805661) (xy 257.891483 -1.813573) (xy 257.805733 -1.813573)
			(xy 257.72035 -1.805661) (xy 257.63606 -1.789905) (xy 257.553584 -1.766438) (xy 257.473625 -1.735462)
			(xy 257.396865 -1.69724) (xy 257.323959 -1.652099) (xy 257.25553 -1.600423) (xy 257.19216 -1.542654)
			(xy 257.134391 -1.479284) (xy 257.082715 -1.410855) (xy 257.037574 -1.337949) (xy 256.999352 -1.261189)
			(xy 256.968376 -1.18123) (xy 256.944909 -1.098754) (xy 256.929153 -1.014464) (xy 256.921241 -0.929081)
			(xy 254.465119 -0.929081) (xy 254.465087 -0.931875) (xy 254.457175 -1.017258) (xy 254.441419 -1.101548)
			(xy 254.417952 -1.184024) (xy 254.386976 -1.263983) (xy 254.348754 -1.340743) (xy 254.303613 -1.413649)
			(xy 254.251937 -1.482078) (xy 254.194168 -1.545448) (xy 254.130798 -1.603217) (xy 254.062369 -1.654893)
			(xy 253.989463 -1.700034) (xy 253.912703 -1.738256) (xy 253.832744 -1.769232) (xy 253.750268 -1.792699)
			(xy 253.665978 -1.808455) (xy 253.580595 -1.816367) (xy 253.494845 -1.816367) (xy 253.409462 -1.808455)
			(xy 253.325172 -1.792699) (xy 253.242696 -1.769232) (xy 253.162737 -1.738256) (xy 253.085977 -1.700034)
			(xy 253.013071 -1.654893) (xy 252.944642 -1.603217) (xy 252.881272 -1.545448) (xy 252.823503 -1.482078)
			(xy 252.771827 -1.413649) (xy 252.726686 -1.340743) (xy 252.688464 -1.263983) (xy 252.657488 -1.184024)
			(xy 252.634021 -1.101548) (xy 252.618265 -1.017258) (xy 252.610353 -0.931875) (xy 248.115087 -0.931875)
			(xy 248.107175 -1.017258) (xy 248.091419 -1.101548) (xy 248.067952 -1.184024) (xy 248.036976 -1.263983)
			(xy 247.998754 -1.340743) (xy 247.953613 -1.413649) (xy 247.901937 -1.482078) (xy 247.844168 -1.545448)
			(xy 247.780798 -1.603217) (xy 247.712369 -1.654893) (xy 247.639463 -1.700034) (xy 247.562703 -1.738256)
			(xy 247.482744 -1.769232) (xy 247.400268 -1.792699) (xy 247.315978 -1.808455) (xy 247.230595 -1.816367)
			(xy 247.144845 -1.816367) (xy 247.059462 -1.808455) (xy 246.975172 -1.792699) (xy 246.892696 -1.769232)
			(xy 246.812737 -1.738256) (xy 246.735977 -1.700034) (xy 246.663071 -1.654893) (xy 246.594642 -1.603217)
			(xy 246.531272 -1.545448) (xy 246.473503 -1.482078) (xy 246.421827 -1.413649) (xy 246.376686 -1.340743)
			(xy 246.338464 -1.263983) (xy 246.307488 -1.184024) (xy 246.284021 -1.101548) (xy 246.268265 -1.017258)
			(xy 246.260353 -0.931875) (xy 216.248247 -0.931875) (xy 216.240335 -1.017258) (xy 216.224579 -1.101548)
			(xy 216.201112 -1.184024) (xy 216.170136 -1.263983) (xy 216.131914 -1.340743) (xy 216.086773 -1.413649)
			(xy 216.035097 -1.482078) (xy 215.977328 -1.545448) (xy 215.913958 -1.603217) (xy 215.845529 -1.654893)
			(xy 215.772623 -1.700034) (xy 215.695863 -1.738256) (xy 215.615904 -1.769232) (xy 215.533428 -1.792699)
			(xy 215.449138 -1.808455) (xy 215.363755 -1.816367) (xy 215.278005 -1.816367) (xy 215.192622 -1.808455)
			(xy 215.108332 -1.792699) (xy 215.025856 -1.769232) (xy 214.945897 -1.738256) (xy 214.869137 -1.700034)
			(xy 214.796231 -1.654893) (xy 214.727802 -1.603217) (xy 214.664432 -1.545448) (xy 214.606663 -1.482078)
			(xy 214.554987 -1.413649) (xy 214.509846 -1.340743) (xy 214.471624 -1.263983) (xy 214.440648 -1.184024)
			(xy 214.417181 -1.101548) (xy 214.401425 -1.017258) (xy 214.393513 -0.931875) (xy 209.898247 -0.931875)
			(xy 209.890335 -1.017258) (xy 209.874579 -1.101548) (xy 209.851112 -1.184024) (xy 209.820136 -1.263983)
			(xy 209.781914 -1.340743) (xy 209.736773 -1.413649) (xy 209.685097 -1.482078) (xy 209.627328 -1.545448)
			(xy 209.563958 -1.603217) (xy 209.495529 -1.654893) (xy 209.422623 -1.700034) (xy 209.345863 -1.738256)
			(xy 209.265904 -1.769232) (xy 209.183428 -1.792699) (xy 209.099138 -1.808455) (xy 209.013755 -1.816367)
			(xy 208.928005 -1.816367) (xy 208.842622 -1.808455) (xy 208.758332 -1.792699) (xy 208.675856 -1.769232)
			(xy 208.595897 -1.738256) (xy 208.519137 -1.700034) (xy 208.446231 -1.654893) (xy 208.377802 -1.603217)
			(xy 208.314432 -1.545448) (xy 208.256663 -1.482078) (xy 208.204987 -1.413649) (xy 208.159846 -1.340743)
			(xy 208.121624 -1.263983) (xy 208.090648 -1.184024) (xy 208.067181 -1.101548) (xy 208.051425 -1.017258)
			(xy 208.043513 -0.931875) (xy 84.20989 -0.931875) (xy 84.20989 -7.78002) (xy 84.210412 -7.835827)
			(xy 84.218755 -7.947128) (xy 84.235391 -8.057495) (xy 84.260229 -8.16631) (xy 84.293128 -8.272964)
			(xy 84.333906 -8.376862) (xy 84.382334 -8.477422) (xy 84.438141 -8.574082) (xy 84.501016 -8.666301)
			(xy 84.570606 -8.753563) (xy 84.646523 -8.835382) (xy 84.728341 -8.911298) (xy 84.815604 -8.980888)
			(xy 84.907824 -9.043762) (xy 85.004484 -9.099569) (xy 85.105044 -9.147996) (xy 85.208942 -9.188774)
			(xy 85.315596 -9.221673) (xy 85.424411 -9.24651) (xy 85.534778 -9.263146) (xy 85.646079 -9.271488)
			(xy 85.701886 -9.272016) (xy 122.102118 -9.272016) (xy 122.157925 -9.271494) (xy 122.269226 -9.263152)
			(xy 122.379593 -9.246515) (xy 122.488409 -9.221678) (xy 122.595063 -9.188778) (xy 122.698961 -9.148001)
			(xy 122.799522 -9.099573) (xy 122.896182 -9.043766) (xy 122.988401 -8.980891) (xy 123.075664 -8.911301)
			(xy 123.157483 -8.835384) (xy 123.2334 -8.753566) (xy 123.30299 -8.666303) (xy 123.365865 -8.574084)
			(xy 123.421672 -8.477423) (xy 123.4701 -8.376863) (xy 123.510878 -8.272965) (xy 123.543777 -8.16631)
			(xy 123.568615 -8.057495) (xy 123.585251 -7.947128) (xy 123.593594 -7.835827) (xy 123.594114 -7.78002)
			(xy 123.594114 -4.2799) (xy 123.594598 -4.209546) (xy 123.602488 -4.06906) (xy 123.618242 -3.929237)
			(xy 123.641812 -3.790517) (xy 123.673122 -3.653337) (xy 123.712075 -3.518129) (xy 123.758548 -3.385317)
			(xy 123.812395 -3.25532) (xy 123.873446 -3.128547) (xy 123.941509 -3.005396) (xy 124.01637 -2.886255)
			(xy 124.097794 -2.7715) (xy 124.185524 -2.66149) (xy 124.279284 -2.556573) (xy 124.37878 -2.457077)
			(xy 124.483698 -2.363317) (xy 124.593708 -2.275588) (xy 124.708464 -2.194165) (xy 124.827605 -2.119304)
			(xy 124.950755 -2.051241) (xy 125.077529 -1.990191) (xy 125.207526 -1.936345) (xy 125.340338 -1.889872)
			(xy 125.475547 -1.85092) (xy 125.612727 -1.81961) (xy 125.751447 -1.796041) (xy 125.89127 -1.780287)
			(xy 126.031756 -1.772398) (xy 126.10211 -1.771904) (xy 194.701922 -1.771904) (xy 194.772275 -1.772398)
			(xy 194.912761 -1.780289) (xy 195.052582 -1.796044) (xy 195.191301 -1.819614) (xy 195.32848 -1.850925)
			(xy 195.463687 -1.889879) (xy 195.596497 -1.936352) (xy 195.726493 -1.990199) (xy 195.853265 -2.05125)
			(xy 195.976414 -2.119314) (xy 196.095554 -2.194175) (xy 196.210308 -2.275598) (xy 196.320316 -2.363328)
			(xy 196.425233 -2.457088) (xy 196.524727 -2.556583) (xy 196.618486 -2.6615) (xy 196.706215 -2.77151)
			(xy 196.787637 -2.886265) (xy 196.862497 -3.005405) (xy 196.93056 -3.128555) (xy 196.99161 -3.255327)
			(xy 197.045455 -3.385323) (xy 197.075741 -3.471875) (xy 208.043513 -3.471875) (xy 208.043513 -3.386125)
			(xy 208.051425 -3.300742) (xy 208.067181 -3.216452) (xy 208.090648 -3.133976) (xy 208.121624 -3.054017)
			(xy 208.159846 -2.977257) (xy 208.204987 -2.904351) (xy 208.256663 -2.835922) (xy 208.314432 -2.772552)
			(xy 208.377802 -2.714783) (xy 208.446231 -2.663107) (xy 208.519137 -2.617966) (xy 208.595897 -2.579744)
			(xy 208.675856 -2.548768) (xy 208.758332 -2.525301) (xy 208.842622 -2.509545) (xy 208.928005 -2.501633)
			(xy 209.013755 -2.501633) (xy 209.099138 -2.509545) (xy 209.183428 -2.525301) (xy 209.265904 -2.548768)
			(xy 209.345863 -2.579744) (xy 209.422623 -2.617966) (xy 209.495529 -2.663107) (xy 209.551136 -2.7051)
			(xy 212.202268 -2.7051) (xy 212.202268 -1.60782) (xy 212.202781 -1.595749) (xy 212.210235 -1.572786)
			(xy 212.22442 -1.553251) (xy 212.243947 -1.539055) (xy 212.266905 -1.531588) (xy 212.278976 -1.531112)
			(xy 212.891116 -1.531112) (xy 212.899577 -1.53128) (xy 212.916112 -1.53487) (xy 212.923882 -1.538224)
			(xy 212.936838 -1.543876) (xy 212.964732 -1.548406) (xy 212.9928 -1.545119) (xy 213.018892 -1.534266)
			(xy 213.041012 -1.516678) (xy 213.049612 -1.505458) (xy 213.064996 -1.48458) (xy 213.100573 -1.446847)
			(xy 213.140936 -1.414285) (xy 213.185341 -1.387493) (xy 213.232966 -1.366967) (xy 213.282935 -1.353085)
			(xy 213.334323 -1.346104) (xy 213.360254 -1.345692) (xy 213.387509 -1.346266) (xy 213.441464 -1.354014)
			(xy 213.493769 -1.369358) (xy 213.543359 -1.391987) (xy 213.589226 -1.42144) (xy 213.630436 -1.457119)
			(xy 213.666152 -1.498297) (xy 213.695647 -1.544137) (xy 213.718321 -1.593706) (xy 213.733712 -1.645997)
			(xy 213.741509 -1.699946) (xy 213.742016 -1.7272) (xy 213.742016 -2.5908) (xy 213.741544 -2.618064)
			(xy 213.733781 -2.672037) (xy 213.718412 -2.724354) (xy 213.695752 -2.773951) (xy 213.666261 -2.819816)
			(xy 213.63054 -2.861015) (xy 213.589318 -2.896708) (xy 213.543434 -2.92617) (xy 213.493823 -2.948798)
			(xy 213.441496 -2.964133) (xy 213.387518 -2.971861) (xy 213.360254 -2.972308) (xy 213.33407 -2.971873)
			(xy 213.282195 -2.964698) (xy 213.231787 -2.950502) (xy 213.183791 -2.929553) (xy 213.139108 -2.902241)
			(xy 213.098576 -2.869081) (xy 213.062954 -2.830694) (xy 213.04758 -2.809494) (xy 213.039123 -2.798237)
			(xy 213.017257 -2.780514) (xy 212.991394 -2.769412) (xy 212.963484 -2.765767) (xy 212.935637 -2.769855)
			(xy 212.922612 -2.775204) (xy 212.915108 -2.778291) (xy 212.899228 -2.781617) (xy 212.891116 -2.781808)
			(xy 212.278976 -2.781808) (xy 212.2669 -2.781356) (xy 212.243932 -2.773887) (xy 212.224396 -2.759687)
			(xy 212.210202 -2.740146) (xy 212.20274 -2.717176) (xy 212.202268 -2.7051) (xy 209.551136 -2.7051)
			(xy 209.563958 -2.714783) (xy 209.627328 -2.772552) (xy 209.685097 -2.835922) (xy 209.736773 -2.904351)
			(xy 209.781914 -2.977257) (xy 209.820136 -3.054017) (xy 209.851112 -3.133976) (xy 209.874579 -3.216452)
			(xy 209.890335 -3.300742) (xy 209.898247 -3.386125) (xy 209.898742 -3.429) (xy 209.898247 -3.471875)
			(xy 214.393513 -3.471875) (xy 214.393513 -3.386125) (xy 214.401425 -3.300742) (xy 214.417181 -3.216452)
			(xy 214.440648 -3.133976) (xy 214.471624 -3.054017) (xy 214.509846 -2.977257) (xy 214.554987 -2.904351)
			(xy 214.606663 -2.835922) (xy 214.664432 -2.772552) (xy 214.727802 -2.714783) (xy 214.796231 -2.663107)
			(xy 214.869137 -2.617966) (xy 214.945897 -2.579744) (xy 215.025856 -2.548768) (xy 215.108332 -2.525301)
			(xy 215.192622 -2.509545) (xy 215.278005 -2.501633) (xy 215.363755 -2.501633) (xy 215.449138 -2.509545)
			(xy 215.533428 -2.525301) (xy 215.615904 -2.548768) (xy 215.695863 -2.579744) (xy 215.772623 -2.617966)
			(xy 215.845529 -2.663107) (xy 215.913958 -2.714783) (xy 215.977328 -2.772552) (xy 216.035097 -2.835922)
			(xy 216.086773 -2.904351) (xy 216.131914 -2.977257) (xy 216.170136 -3.054017) (xy 216.201112 -3.133976)
			(xy 216.224579 -3.216452) (xy 216.240335 -3.300742) (xy 216.248247 -3.386125) (xy 216.248742 -3.429)
			(xy 216.248247 -3.471875) (xy 246.260353 -3.471875) (xy 246.260353 -3.386125) (xy 246.268265 -3.300742)
			(xy 246.284021 -3.216452) (xy 246.307488 -3.133976) (xy 246.338464 -3.054017) (xy 246.376686 -2.977257)
			(xy 246.421827 -2.904351) (xy 246.473503 -2.835922) (xy 246.531272 -2.772552) (xy 246.594642 -2.714783)
			(xy 246.663071 -2.663107) (xy 246.735977 -2.617966) (xy 246.812737 -2.579744) (xy 246.892696 -2.548768)
			(xy 246.975172 -2.525301) (xy 247.059462 -2.509545) (xy 247.144845 -2.501633) (xy 247.230595 -2.501633)
			(xy 247.315978 -2.509545) (xy 247.400268 -2.525301) (xy 247.482744 -2.548768) (xy 247.562703 -2.579744)
			(xy 247.584906 -2.5908) (xy 248.766584 -2.5908) (xy 248.766584 -1.7272) (xy 248.767056 -1.699936)
			(xy 248.774819 -1.645963) (xy 248.790188 -1.593646) (xy 248.812848 -1.544049) (xy 248.842339 -1.498184)
			(xy 248.87806 -1.456985) (xy 248.919282 -1.421292) (xy 248.965166 -1.39183) (xy 249.014777 -1.369202)
			(xy 249.067104 -1.353867) (xy 249.121082 -1.346139) (xy 249.148346 -1.345692) (xy 249.17453 -1.346127)
			(xy 249.226405 -1.353302) (xy 249.276813 -1.367498) (xy 249.324809 -1.388447) (xy 249.369492 -1.415759)
			(xy 249.410024 -1.448919) (xy 249.445646 -1.487306) (xy 249.46102 -1.508506) (xy 249.469477 -1.519763)
			(xy 249.491343 -1.537486) (xy 249.517206 -1.548588) (xy 249.545116 -1.552233) (xy 249.572963 -1.548145)
			(xy 249.585988 -1.542796) (xy 249.593492 -1.539709) (xy 249.609372 -1.536383) (xy 249.617484 -1.536192)
			(xy 250.229624 -1.536192) (xy 250.2417 -1.536644) (xy 250.264668 -1.544113) (xy 250.284204 -1.558313)
			(xy 250.298398 -1.577854) (xy 250.30586 -1.600824) (xy 250.306332 -1.6129) (xy 250.306332 -2.71018)
			(xy 250.305819 -2.722251) (xy 250.298365 -2.745214) (xy 250.28418 -2.764749) (xy 250.264653 -2.778945)
			(xy 250.241695 -2.786412) (xy 250.229624 -2.786888) (xy 249.617484 -2.786888) (xy 249.609023 -2.78672)
			(xy 249.592488 -2.78313) (xy 249.584718 -2.779776) (xy 249.571762 -2.774124) (xy 249.543868 -2.769594)
			(xy 249.5158 -2.772881) (xy 249.489708 -2.783734) (xy 249.467588 -2.801322) (xy 249.458988 -2.812542)
			(xy 249.443604 -2.83342) (xy 249.408027 -2.871153) (xy 249.367664 -2.903715) (xy 249.323259 -2.930507)
			(xy 249.275634 -2.951033) (xy 249.225665 -2.964915) (xy 249.174277 -2.971896) (xy 249.148346 -2.972308)
			(xy 249.121091 -2.971734) (xy 249.067136 -2.963986) (xy 249.014831 -2.948642) (xy 248.965241 -2.926013)
			(xy 248.919374 -2.89656) (xy 248.878164 -2.860881) (xy 248.842448 -2.819703) (xy 248.812953 -2.773863)
			(xy 248.790279 -2.724294) (xy 248.774888 -2.672003) (xy 248.767091 -2.618054) (xy 248.766584 -2.5908)
			(xy 247.584906 -2.5908) (xy 247.639463 -2.617966) (xy 247.712369 -2.663107) (xy 247.780798 -2.714783)
			(xy 247.844168 -2.772552) (xy 247.901937 -2.835922) (xy 247.953613 -2.904351) (xy 247.998754 -2.977257)
			(xy 248.036976 -3.054017) (xy 248.067952 -3.133976) (xy 248.091419 -3.216452) (xy 248.107175 -3.300742)
			(xy 248.115087 -3.386125) (xy 248.115582 -3.429) (xy 248.115087 -3.471875) (xy 252.610353 -3.471875)
			(xy 252.610353 -3.386125) (xy 252.618265 -3.300742) (xy 252.634021 -3.216452) (xy 252.657488 -3.133976)
			(xy 252.688464 -3.054017) (xy 252.726686 -2.977257) (xy 252.771827 -2.904351) (xy 252.823503 -2.835922)
			(xy 252.881272 -2.772552) (xy 252.944642 -2.714783) (xy 253.013071 -2.663107) (xy 253.085977 -2.617966)
			(xy 253.162737 -2.579744) (xy 253.242696 -2.548768) (xy 253.325172 -2.525301) (xy 253.409462 -2.509545)
			(xy 253.494845 -2.501633) (xy 253.580595 -2.501633) (xy 253.665978 -2.509545) (xy 253.750268 -2.525301)
			(xy 253.832744 -2.548768) (xy 253.912703 -2.579744) (xy 253.989463 -2.617966) (xy 254.062369 -2.663107)
			(xy 254.130798 -2.714783) (xy 254.194168 -2.772552) (xy 254.251937 -2.835922) (xy 254.303613 -2.904351)
			(xy 254.348754 -2.977257) (xy 254.386976 -3.054017) (xy 254.417952 -3.133976) (xy 254.441419 -3.216452)
			(xy 254.457175 -3.300742) (xy 254.465087 -3.386125) (xy 254.465582 -3.429) (xy 254.465119 -3.469081)
			(xy 256.921241 -3.469081) (xy 256.921241 -3.383331) (xy 256.929153 -3.297948) (xy 256.944909 -3.213658)
			(xy 256.968376 -3.131182) (xy 256.999352 -3.051223) (xy 257.037574 -2.974463) (xy 257.082715 -2.901557)
			(xy 257.134391 -2.833128) (xy 257.19216 -2.769758) (xy 257.25553 -2.711989) (xy 257.323959 -2.660313)
			(xy 257.396865 -2.615172) (xy 257.473625 -2.57695) (xy 257.553584 -2.545974) (xy 257.63606 -2.522507)
			(xy 257.72035 -2.506751) (xy 257.805733 -2.498839) (xy 257.891483 -2.498839) (xy 257.976866 -2.506751)
			(xy 258.061156 -2.522507) (xy 258.143632 -2.545974) (xy 258.223591 -2.57695) (xy 258.300351 -2.615172)
			(xy 258.373257 -2.660313) (xy 258.428864 -2.702306) (xy 261.079996 -2.702306) (xy 261.079996 -1.605026)
			(xy 261.080529 -1.592942) (xy 261.087973 -1.56995) (xy 261.102144 -1.550373) (xy 261.121661 -1.53612)
			(xy 261.144622 -1.52858) (xy 261.156704 -1.528064) (xy 261.768844 -1.528064) (xy 261.780952 -1.528478)
			(xy 261.803974 -1.535986) (xy 261.823543 -1.550249) (xy 261.837738 -1.569868) (xy 261.845164 -1.592917)
			(xy 261.845552 -1.605026) (xy 261.845552 -2.702306) (xy 261.845097 -2.714397) (xy 261.837638 -2.737399)
			(xy 261.823449 -2.756979) (xy 261.803912 -2.771229) (xy 261.780933 -2.77876) (xy 261.768844 -2.779268)
			(xy 261.156704 -2.779268) (xy 261.144592 -2.77888) (xy 261.121559 -2.771378) (xy 261.101983 -2.75711)
			(xy 261.08779 -2.73748) (xy 261.080375 -2.714419) (xy 261.079996 -2.702306) (xy 258.428864 -2.702306)
			(xy 258.441686 -2.711989) (xy 258.505056 -2.769758) (xy 258.562825 -2.833128) (xy 258.614501 -2.901557)
			(xy 258.659642 -2.974463) (xy 258.697864 -3.051223) (xy 258.72884 -3.131182) (xy 258.752307 -3.213658)
			(xy 258.768063 -3.297948) (xy 258.775975 -3.383331) (xy 258.77647 -3.426206) (xy 258.775975 -3.469081)
			(xy 263.271241 -3.469081) (xy 263.271241 -3.383331) (xy 263.279153 -3.297948) (xy 263.294909 -3.213658)
			(xy 263.318376 -3.131182) (xy 263.349352 -3.051223) (xy 263.387574 -2.974463) (xy 263.432715 -2.901557)
			(xy 263.484391 -2.833128) (xy 263.54216 -2.769758) (xy 263.60553 -2.711989) (xy 263.673959 -2.660313)
			(xy 263.746865 -2.615172) (xy 263.823625 -2.57695) (xy 263.903584 -2.545974) (xy 263.98606 -2.522507)
			(xy 264.07035 -2.506751) (xy 264.155733 -2.498839) (xy 264.241483 -2.498839) (xy 264.326866 -2.506751)
			(xy 264.411156 -2.522507) (xy 264.493632 -2.545974) (xy 264.573591 -2.57695) (xy 264.650351 -2.615172)
			(xy 264.723257 -2.660313) (xy 264.791686 -2.711989) (xy 264.855056 -2.769758) (xy 264.912825 -2.833128)
			(xy 264.964501 -2.901557) (xy 265.009642 -2.974463) (xy 265.047864 -3.051223) (xy 265.07884 -3.131182)
			(xy 265.102307 -3.213658) (xy 265.118063 -3.297948) (xy 265.125975 -3.383331) (xy 265.12647 -3.426206)
			(xy 265.125975 -3.469081) (xy 324.845921 -3.469081) (xy 324.845921 -3.383331) (xy 324.853833 -3.297948)
			(xy 324.869589 -3.213658) (xy 324.893056 -3.131182) (xy 324.924032 -3.051223) (xy 324.962254 -2.974463)
			(xy 325.007395 -2.901557) (xy 325.059071 -2.833128) (xy 325.11684 -2.769758) (xy 325.18021 -2.711989)
			(xy 325.248639 -2.660313) (xy 325.321545 -2.615172) (xy 325.398305 -2.57695) (xy 325.478264 -2.545974)
			(xy 325.56074 -2.522507) (xy 325.64503 -2.506751) (xy 325.730413 -2.498839) (xy 325.816163 -2.498839)
			(xy 325.901546 -2.506751) (xy 325.985836 -2.522507) (xy 326.068312 -2.545974) (xy 326.148271 -2.57695)
			(xy 326.225031 -2.615172) (xy 326.297937 -2.660313) (xy 326.360271 -2.707386) (xy 328.126344 -2.707386)
			(xy 328.126344 -1.610106) (xy 328.126813 -1.598016) (xy 328.134268 -1.575015) (xy 328.148454 -1.555435)
			(xy 328.167988 -1.541184) (xy 328.190964 -1.533653) (xy 328.203052 -1.533144) (xy 328.815192 -1.533144)
			(xy 328.827295 -1.533622) (xy 328.850312 -1.541113) (xy 328.869881 -1.55536) (xy 328.884078 -1.574965)
			(xy 328.891509 -1.598002) (xy 328.8919 -1.610106) (xy 328.8919 -2.707386) (xy 328.891381 -2.719471)
			(xy 328.883933 -2.742464) (xy 328.869759 -2.762041) (xy 328.850238 -2.776293) (xy 328.827275 -2.783833)
			(xy 328.815192 -2.784348) (xy 328.203052 -2.784348) (xy 328.190945 -2.783925) (xy 328.167925 -2.776418)
			(xy 328.148357 -2.762157) (xy 328.134162 -2.74254) (xy 328.126734 -2.719494) (xy 328.126344 -2.707386)
			(xy 326.360271 -2.707386) (xy 326.366366 -2.711989) (xy 326.429736 -2.769758) (xy 326.487505 -2.833128)
			(xy 326.539181 -2.901557) (xy 326.584322 -2.974463) (xy 326.622544 -3.051223) (xy 326.65352 -3.131182)
			(xy 326.676987 -3.213658) (xy 326.692743 -3.297948) (xy 326.700655 -3.383331) (xy 326.70115 -3.426206)
			(xy 326.700655 -3.469081) (xy 331.195921 -3.469081) (xy 331.195921 -3.383331) (xy 331.203833 -3.297948)
			(xy 331.219589 -3.213658) (xy 331.243056 -3.131182) (xy 331.274032 -3.051223) (xy 331.312254 -2.974463)
			(xy 331.357395 -2.901557) (xy 331.409071 -2.833128) (xy 331.46684 -2.769758) (xy 331.53021 -2.711989)
			(xy 331.598639 -2.660313) (xy 331.671545 -2.615172) (xy 331.748305 -2.57695) (xy 331.828264 -2.545974)
			(xy 331.91074 -2.522507) (xy 331.99503 -2.506751) (xy 332.080413 -2.498839) (xy 332.166163 -2.498839)
			(xy 332.251546 -2.506751) (xy 332.335836 -2.522507) (xy 332.418312 -2.545974) (xy 332.498271 -2.57695)
			(xy 332.575031 -2.615172) (xy 332.647937 -2.660313) (xy 332.716366 -2.711989) (xy 332.779736 -2.769758)
			(xy 332.837505 -2.833128) (xy 332.889181 -2.901557) (xy 332.934322 -2.974463) (xy 332.972544 -3.051223)
			(xy 333.00352 -3.131182) (xy 333.026987 -3.213658) (xy 333.042743 -3.297948) (xy 333.050655 -3.383331)
			(xy 333.05115 -3.426206) (xy 333.050655 -3.469081) (xy 335.488267 -3.469081) (xy 335.488267 -3.383331)
			(xy 335.496179 -3.297948) (xy 335.511935 -3.213658) (xy 335.535402 -3.131182) (xy 335.566378 -3.051223)
			(xy 335.6046 -2.974463) (xy 335.649741 -2.901557) (xy 335.701417 -2.833128) (xy 335.759186 -2.769758)
			(xy 335.822556 -2.711989) (xy 335.890985 -2.660313) (xy 335.963891 -2.615172) (xy 336.040651 -2.57695)
			(xy 336.12061 -2.545974) (xy 336.203086 -2.522507) (xy 336.287376 -2.506751) (xy 336.372759 -2.498839)
			(xy 336.458509 -2.498839) (xy 336.543892 -2.506751) (xy 336.628182 -2.522507) (xy 336.710658 -2.545974)
			(xy 336.790617 -2.57695) (xy 336.867377 -2.615172) (xy 336.940283 -2.660313) (xy 336.99589 -2.702306)
			(xy 339.646768 -2.702306) (xy 339.646768 -1.605026) (xy 339.647183 -1.592902) (xy 339.654671 -1.569839)
			(xy 339.668923 -1.55022) (xy 339.688542 -1.535969) (xy 339.711606 -1.528482) (xy 339.72373 -1.528064)
			(xy 340.33587 -1.528064) (xy 340.347994 -1.528486) (xy 340.371056 -1.535973) (xy 340.390674 -1.550223)
			(xy 340.404925 -1.56984) (xy 340.412414 -1.592902) (xy 340.412832 -1.605026) (xy 340.412832 -2.702306)
			(xy 340.412445 -2.714432) (xy 340.404947 -2.737496) (xy 340.390688 -2.757114) (xy 340.371064 -2.771363)
			(xy 340.347996 -2.77885) (xy 340.33587 -2.779268) (xy 339.72373 -2.779268) (xy 339.711609 -2.778815)
			(xy 339.688553 -2.771331) (xy 339.668937 -2.757088) (xy 339.654685 -2.73748) (xy 339.647191 -2.714426)
			(xy 339.646768 -2.702306) (xy 336.99589 -2.702306) (xy 337.008712 -2.711989) (xy 337.072082 -2.769758)
			(xy 337.129851 -2.833128) (xy 337.181527 -2.901557) (xy 337.226668 -2.974463) (xy 337.26489 -3.051223)
			(xy 337.295866 -3.131182) (xy 337.319333 -3.213658) (xy 337.335089 -3.297948) (xy 337.343001 -3.383331)
			(xy 337.343496 -3.426206) (xy 337.343001 -3.469081) (xy 341.838267 -3.469081) (xy 341.838267 -3.383331)
			(xy 341.846179 -3.297948) (xy 341.861935 -3.213658) (xy 341.885402 -3.131182) (xy 341.916378 -3.051223)
			(xy 341.9546 -2.974463) (xy 341.999741 -2.901557) (xy 342.051417 -2.833128) (xy 342.109186 -2.769758)
			(xy 342.172556 -2.711989) (xy 342.240985 -2.660313) (xy 342.313891 -2.615172) (xy 342.390651 -2.57695)
			(xy 342.47061 -2.545974) (xy 342.553086 -2.522507) (xy 342.637376 -2.506751) (xy 342.722759 -2.498839)
			(xy 342.808509 -2.498839) (xy 342.893892 -2.506751) (xy 342.978182 -2.522507) (xy 343.060658 -2.545974)
			(xy 343.140617 -2.57695) (xy 343.217377 -2.615172) (xy 343.290283 -2.660313) (xy 343.358712 -2.711989)
			(xy 343.422082 -2.769758) (xy 343.479851 -2.833128) (xy 343.531527 -2.901557) (xy 343.576668 -2.974463)
			(xy 343.61489 -3.051223) (xy 343.645866 -3.131182) (xy 343.669333 -3.213658) (xy 343.685089 -3.297948)
			(xy 343.693001 -3.383331) (xy 343.693496 -3.426206) (xy 343.693001 -3.469081) (xy 373.705107 -3.469081)
			(xy 373.705107 -3.383331) (xy 373.713019 -3.297948) (xy 373.728775 -3.213658) (xy 373.752242 -3.131182)
			(xy 373.783218 -3.051223) (xy 373.82144 -2.974463) (xy 373.866581 -2.901557) (xy 373.918257 -2.833128)
			(xy 373.976026 -2.769758) (xy 374.039396 -2.711989) (xy 374.107825 -2.660313) (xy 374.180731 -2.615172)
			(xy 374.257491 -2.57695) (xy 374.33745 -2.545974) (xy 374.419926 -2.522507) (xy 374.504216 -2.506751)
			(xy 374.589599 -2.498839) (xy 374.675349 -2.498839) (xy 374.760732 -2.506751) (xy 374.845022 -2.522507)
			(xy 374.927498 -2.545974) (xy 375.007457 -2.57695) (xy 375.084217 -2.615172) (xy 375.157123 -2.660313)
			(xy 375.219457 -2.707386) (xy 376.985276 -2.707386) (xy 376.985276 -1.610106) (xy 376.985666 -1.59798)
			(xy 376.993161 -1.574915) (xy 377.007419 -1.555296) (xy 377.027043 -1.541046) (xy 377.050112 -1.533561)
			(xy 377.062238 -1.533144) (xy 377.674378 -1.533144) (xy 377.6865 -1.533579) (xy 377.709559 -1.541066)
			(xy 377.729175 -1.555313) (xy 377.743427 -1.574926) (xy 377.750919 -1.597984) (xy 377.75134 -1.610106)
			(xy 377.75134 -2.707386) (xy 377.750928 -2.71951) (xy 377.743437 -2.742572) (xy 377.729184 -2.762189)
			(xy 377.709565 -2.77644) (xy 377.686502 -2.783929) (xy 377.674378 -2.784348) (xy 377.062238 -2.784348)
			(xy 377.050116 -2.783908) (xy 377.027056 -2.776424) (xy 377.007439 -2.762178) (xy 376.993187 -2.742566)
			(xy 376.985696 -2.719508) (xy 376.985276 -2.707386) (xy 375.219457 -2.707386) (xy 375.225552 -2.711989)
			(xy 375.288922 -2.769758) (xy 375.346691 -2.833128) (xy 375.398367 -2.901557) (xy 375.443508 -2.974463)
			(xy 375.48173 -3.051223) (xy 375.512706 -3.131182) (xy 375.536173 -3.213658) (xy 375.551929 -3.297948)
			(xy 375.559841 -3.383331) (xy 375.560336 -3.426206) (xy 375.559841 -3.469081) (xy 380.055107 -3.469081)
			(xy 380.055107 -3.383331) (xy 380.063019 -3.297948) (xy 380.078775 -3.213658) (xy 380.102242 -3.131182)
			(xy 380.133218 -3.051223) (xy 380.17144 -2.974463) (xy 380.216581 -2.901557) (xy 380.268257 -2.833128)
			(xy 380.326026 -2.769758) (xy 380.389396 -2.711989) (xy 380.457825 -2.660313) (xy 380.530731 -2.615172)
			(xy 380.607491 -2.57695) (xy 380.68745 -2.545974) (xy 380.769926 -2.522507) (xy 380.854216 -2.506751)
			(xy 380.939599 -2.498839) (xy 381.025349 -2.498839) (xy 381.110732 -2.506751) (xy 381.195022 -2.522507)
			(xy 381.277498 -2.545974) (xy 381.357457 -2.57695) (xy 381.434217 -2.615172) (xy 381.507123 -2.660313)
			(xy 381.575552 -2.711989) (xy 381.638922 -2.769758) (xy 381.696691 -2.833128) (xy 381.748367 -2.901557)
			(xy 381.793508 -2.974463) (xy 381.83173 -3.051223) (xy 381.862706 -3.131182) (xy 381.886173 -3.213658)
			(xy 381.901929 -3.297948) (xy 381.909841 -3.383331) (xy 381.910336 -3.426206) (xy 381.909841 -3.469081)
			(xy 381.901929 -3.554464) (xy 381.886173 -3.638754) (xy 381.862706 -3.72123) (xy 381.83173 -3.801189)
			(xy 381.793508 -3.877949) (xy 381.748367 -3.950855) (xy 381.696691 -4.019284) (xy 381.638922 -4.082654)
			(xy 381.575552 -4.140423) (xy 381.507123 -4.192099) (xy 381.434217 -4.23724) (xy 381.357457 -4.275462)
			(xy 381.277498 -4.306438) (xy 381.195022 -4.329905) (xy 381.110732 -4.345661) (xy 381.025349 -4.353573)
			(xy 380.939599 -4.353573) (xy 380.854216 -4.345661) (xy 380.769926 -4.329905) (xy 380.68745 -4.306438)
			(xy 380.607491 -4.275462) (xy 380.530731 -4.23724) (xy 380.457825 -4.192099) (xy 380.389396 -4.140423)
			(xy 380.326026 -4.082654) (xy 380.268257 -4.019284) (xy 380.216581 -3.950855) (xy 380.17144 -3.877949)
			(xy 380.133218 -3.801189) (xy 380.102242 -3.72123) (xy 380.078775 -3.638754) (xy 380.063019 -3.554464)
			(xy 380.055107 -3.469081) (xy 375.559841 -3.469081) (xy 375.551929 -3.554464) (xy 375.536173 -3.638754)
			(xy 375.512706 -3.72123) (xy 375.48173 -3.801189) (xy 375.443508 -3.877949) (xy 375.398367 -3.950855)
			(xy 375.346691 -4.019284) (xy 375.288922 -4.082654) (xy 375.225552 -4.140423) (xy 375.157123 -4.192099)
			(xy 375.084217 -4.23724) (xy 375.007457 -4.275462) (xy 374.927498 -4.306438) (xy 374.845022 -4.329905)
			(xy 374.760732 -4.345661) (xy 374.675349 -4.353573) (xy 374.589599 -4.353573) (xy 374.504216 -4.345661)
			(xy 374.419926 -4.329905) (xy 374.33745 -4.306438) (xy 374.257491 -4.275462) (xy 374.180731 -4.23724)
			(xy 374.107825 -4.192099) (xy 374.039396 -4.140423) (xy 373.976026 -4.082654) (xy 373.918257 -4.019284)
			(xy 373.866581 -3.950855) (xy 373.82144 -3.877949) (xy 373.783218 -3.801189) (xy 373.752242 -3.72123)
			(xy 373.728775 -3.638754) (xy 373.713019 -3.554464) (xy 373.705107 -3.469081) (xy 343.693001 -3.469081)
			(xy 343.685089 -3.554464) (xy 343.669333 -3.638754) (xy 343.645866 -3.72123) (xy 343.61489 -3.801189)
			(xy 343.576668 -3.877949) (xy 343.531527 -3.950855) (xy 343.479851 -4.019284) (xy 343.422082 -4.082654)
			(xy 343.358712 -4.140423) (xy 343.290283 -4.192099) (xy 343.217377 -4.23724) (xy 343.140617 -4.275462)
			(xy 343.060658 -4.306438) (xy 342.978182 -4.329905) (xy 342.893892 -4.345661) (xy 342.808509 -4.353573)
			(xy 342.722759 -4.353573) (xy 342.637376 -4.345661) (xy 342.553086 -4.329905) (xy 342.47061 -4.306438)
			(xy 342.390651 -4.275462) (xy 342.313891 -4.23724) (xy 342.240985 -4.192099) (xy 342.172556 -4.140423)
			(xy 342.109186 -4.082654) (xy 342.051417 -4.019284) (xy 341.999741 -3.950855) (xy 341.9546 -3.877949)
			(xy 341.916378 -3.801189) (xy 341.885402 -3.72123) (xy 341.861935 -3.638754) (xy 341.846179 -3.554464)
			(xy 341.838267 -3.469081) (xy 337.343001 -3.469081) (xy 337.335089 -3.554464) (xy 337.319333 -3.638754)
			(xy 337.295866 -3.72123) (xy 337.26489 -3.801189) (xy 337.226668 -3.877949) (xy 337.181527 -3.950855)
			(xy 337.129851 -4.019284) (xy 337.072082 -4.082654) (xy 337.008712 -4.140423) (xy 336.940283 -4.192099)
			(xy 336.867377 -4.23724) (xy 336.790617 -4.275462) (xy 336.710658 -4.306438) (xy 336.628182 -4.329905)
			(xy 336.543892 -4.345661) (xy 336.458509 -4.353573) (xy 336.372759 -4.353573) (xy 336.287376 -4.345661)
			(xy 336.203086 -4.329905) (xy 336.12061 -4.306438) (xy 336.040651 -4.275462) (xy 335.963891 -4.23724)
			(xy 335.890985 -4.192099) (xy 335.822556 -4.140423) (xy 335.759186 -4.082654) (xy 335.701417 -4.019284)
			(xy 335.649741 -3.950855) (xy 335.6046 -3.877949) (xy 335.566378 -3.801189) (xy 335.535402 -3.72123)
			(xy 335.511935 -3.638754) (xy 335.496179 -3.554464) (xy 335.488267 -3.469081) (xy 333.050655 -3.469081)
			(xy 333.042743 -3.554464) (xy 333.026987 -3.638754) (xy 333.00352 -3.72123) (xy 332.972544 -3.801189)
			(xy 332.934322 -3.877949) (xy 332.889181 -3.950855) (xy 332.837505 -4.019284) (xy 332.779736 -4.082654)
			(xy 332.716366 -4.140423) (xy 332.647937 -4.192099) (xy 332.575031 -4.23724) (xy 332.498271 -4.275462)
			(xy 332.418312 -4.306438) (xy 332.335836 -4.329905) (xy 332.251546 -4.345661) (xy 332.166163 -4.353573)
			(xy 332.080413 -4.353573) (xy 331.99503 -4.345661) (xy 331.91074 -4.329905) (xy 331.828264 -4.306438)
			(xy 331.748305 -4.275462) (xy 331.671545 -4.23724) (xy 331.598639 -4.192099) (xy 331.53021 -4.140423)
			(xy 331.46684 -4.082654) (xy 331.409071 -4.019284) (xy 331.357395 -3.950855) (xy 331.312254 -3.877949)
			(xy 331.274032 -3.801189) (xy 331.243056 -3.72123) (xy 331.219589 -3.638754) (xy 331.203833 -3.554464)
			(xy 331.195921 -3.469081) (xy 326.700655 -3.469081) (xy 326.692743 -3.554464) (xy 326.676987 -3.638754)
			(xy 326.65352 -3.72123) (xy 326.622544 -3.801189) (xy 326.584322 -3.877949) (xy 326.539181 -3.950855)
			(xy 326.487505 -4.019284) (xy 326.429736 -4.082654) (xy 326.366366 -4.140423) (xy 326.297937 -4.192099)
			(xy 326.225031 -4.23724) (xy 326.148271 -4.275462) (xy 326.068312 -4.306438) (xy 325.985836 -4.329905)
			(xy 325.901546 -4.345661) (xy 325.816163 -4.353573) (xy 325.730413 -4.353573) (xy 325.64503 -4.345661)
			(xy 325.56074 -4.329905) (xy 325.478264 -4.306438) (xy 325.398305 -4.275462) (xy 325.321545 -4.23724)
			(xy 325.248639 -4.192099) (xy 325.18021 -4.140423) (xy 325.11684 -4.082654) (xy 325.059071 -4.019284)
			(xy 325.007395 -3.950855) (xy 324.962254 -3.877949) (xy 324.924032 -3.801189) (xy 324.893056 -3.72123)
			(xy 324.869589 -3.638754) (xy 324.853833 -3.554464) (xy 324.845921 -3.469081) (xy 265.125975 -3.469081)
			(xy 265.118063 -3.554464) (xy 265.102307 -3.638754) (xy 265.07884 -3.72123) (xy 265.047864 -3.801189)
			(xy 265.009642 -3.877949) (xy 264.964501 -3.950855) (xy 264.912825 -4.019284) (xy 264.855056 -4.082654)
			(xy 264.791686 -4.140423) (xy 264.723257 -4.192099) (xy 264.650351 -4.23724) (xy 264.573591 -4.275462)
			(xy 264.493632 -4.306438) (xy 264.411156 -4.329905) (xy 264.326866 -4.345661) (xy 264.241483 -4.353573)
			(xy 264.155733 -4.353573) (xy 264.07035 -4.345661) (xy 263.98606 -4.329905) (xy 263.903584 -4.306438)
			(xy 263.823625 -4.275462) (xy 263.746865 -4.23724) (xy 263.673959 -4.192099) (xy 263.60553 -4.140423)
			(xy 263.54216 -4.082654) (xy 263.484391 -4.019284) (xy 263.432715 -3.950855) (xy 263.387574 -3.877949)
			(xy 263.349352 -3.801189) (xy 263.318376 -3.72123) (xy 263.294909 -3.638754) (xy 263.279153 -3.554464)
			(xy 263.271241 -3.469081) (xy 258.775975 -3.469081) (xy 258.768063 -3.554464) (xy 258.752307 -3.638754)
			(xy 258.72884 -3.72123) (xy 258.697864 -3.801189) (xy 258.659642 -3.877949) (xy 258.614501 -3.950855)
			(xy 258.562825 -4.019284) (xy 258.505056 -4.082654) (xy 258.441686 -4.140423) (xy 258.373257 -4.192099)
			(xy 258.300351 -4.23724) (xy 258.223591 -4.275462) (xy 258.143632 -4.306438) (xy 258.061156 -4.329905)
			(xy 257.976866 -4.345661) (xy 257.891483 -4.353573) (xy 257.805733 -4.353573) (xy 257.72035 -4.345661)
			(xy 257.63606 -4.329905) (xy 257.553584 -4.306438) (xy 257.473625 -4.275462) (xy 257.396865 -4.23724)
			(xy 257.323959 -4.192099) (xy 257.25553 -4.140423) (xy 257.19216 -4.082654) (xy 257.134391 -4.019284)
			(xy 257.082715 -3.950855) (xy 257.037574 -3.877949) (xy 256.999352 -3.801189) (xy 256.968376 -3.72123)
			(xy 256.944909 -3.638754) (xy 256.929153 -3.554464) (xy 256.921241 -3.469081) (xy 254.465119 -3.469081)
			(xy 254.465087 -3.471875) (xy 254.457175 -3.557258) (xy 254.441419 -3.641548) (xy 254.417952 -3.724024)
			(xy 254.386976 -3.803983) (xy 254.348754 -3.880743) (xy 254.303613 -3.953649) (xy 254.251937 -4.022078)
			(xy 254.194168 -4.085448) (xy 254.130798 -4.143217) (xy 254.062369 -4.194893) (xy 253.989463 -4.240034)
			(xy 253.912703 -4.278256) (xy 253.832744 -4.309232) (xy 253.750268 -4.332699) (xy 253.665978 -4.348455)
			(xy 253.580595 -4.356367) (xy 253.494845 -4.356367) (xy 253.409462 -4.348455) (xy 253.325172 -4.332699)
			(xy 253.242696 -4.309232) (xy 253.162737 -4.278256) (xy 253.085977 -4.240034) (xy 253.013071 -4.194893)
			(xy 252.944642 -4.143217) (xy 252.881272 -4.085448) (xy 252.823503 -4.022078) (xy 252.771827 -3.953649)
			(xy 252.726686 -3.880743) (xy 252.688464 -3.803983) (xy 252.657488 -3.724024) (xy 252.634021 -3.641548)
			(xy 252.618265 -3.557258) (xy 252.610353 -3.471875) (xy 248.115087 -3.471875) (xy 248.107175 -3.557258)
			(xy 248.091419 -3.641548) (xy 248.067952 -3.724024) (xy 248.036976 -3.803983) (xy 247.998754 -3.880743)
			(xy 247.953613 -3.953649) (xy 247.901937 -4.022078) (xy 247.844168 -4.085448) (xy 247.780798 -4.143217)
			(xy 247.712369 -4.194893) (xy 247.639463 -4.240034) (xy 247.562703 -4.278256) (xy 247.482744 -4.309232)
			(xy 247.400268 -4.332699) (xy 247.315978 -4.348455) (xy 247.230595 -4.356367) (xy 247.144845 -4.356367)
			(xy 247.059462 -4.348455) (xy 246.975172 -4.332699) (xy 246.892696 -4.309232) (xy 246.812737 -4.278256)
			(xy 246.735977 -4.240034) (xy 246.663071 -4.194893) (xy 246.594642 -4.143217) (xy 246.531272 -4.085448)
			(xy 246.473503 -4.022078) (xy 246.421827 -3.953649) (xy 246.376686 -3.880743) (xy 246.338464 -3.803983)
			(xy 246.307488 -3.724024) (xy 246.284021 -3.641548) (xy 246.268265 -3.557258) (xy 246.260353 -3.471875)
			(xy 216.248247 -3.471875) (xy 216.240335 -3.557258) (xy 216.224579 -3.641548) (xy 216.201112 -3.724024)
			(xy 216.170136 -3.803983) (xy 216.131914 -3.880743) (xy 216.086773 -3.953649) (xy 216.035097 -4.022078)
			(xy 215.977328 -4.085448) (xy 215.913958 -4.143217) (xy 215.845529 -4.194893) (xy 215.772623 -4.240034)
			(xy 215.695863 -4.278256) (xy 215.615904 -4.309232) (xy 215.533428 -4.332699) (xy 215.449138 -4.348455)
			(xy 215.363755 -4.356367) (xy 215.278005 -4.356367) (xy 215.192622 -4.348455) (xy 215.108332 -4.332699)
			(xy 215.025856 -4.309232) (xy 214.945897 -4.278256) (xy 214.869137 -4.240034) (xy 214.796231 -4.194893)
			(xy 214.727802 -4.143217) (xy 214.664432 -4.085448) (xy 214.606663 -4.022078) (xy 214.554987 -3.953649)
			(xy 214.509846 -3.880743) (xy 214.471624 -3.803983) (xy 214.440648 -3.724024) (xy 214.417181 -3.641548)
			(xy 214.401425 -3.557258) (xy 214.393513 -3.471875) (xy 209.898247 -3.471875) (xy 209.890335 -3.557258)
			(xy 209.874579 -3.641548) (xy 209.851112 -3.724024) (xy 209.820136 -3.803983) (xy 209.781914 -3.880743)
			(xy 209.736773 -3.953649) (xy 209.685097 -4.022078) (xy 209.627328 -4.085448) (xy 209.563958 -4.143217)
			(xy 209.495529 -4.194893) (xy 209.422623 -4.240034) (xy 209.345863 -4.278256) (xy 209.265904 -4.309232)
			(xy 209.183428 -4.332699) (xy 209.099138 -4.348455) (xy 209.013755 -4.356367) (xy 208.928005 -4.356367)
			(xy 208.842622 -4.348455) (xy 208.758332 -4.332699) (xy 208.675856 -4.309232) (xy 208.595897 -4.278256)
			(xy 208.519137 -4.240034) (xy 208.446231 -4.194893) (xy 208.377802 -4.143217) (xy 208.314432 -4.085448)
			(xy 208.256663 -4.022078) (xy 208.204987 -3.953649) (xy 208.159846 -3.880743) (xy 208.121624 -3.803983)
			(xy 208.090648 -3.724024) (xy 208.067181 -3.641548) (xy 208.051425 -3.557258) (xy 208.043513 -3.471875)
			(xy 197.075741 -3.471875) (xy 197.091928 -3.518134) (xy 197.13088 -3.653342) (xy 197.16219 -3.790521)
			(xy 197.185759 -3.929239) (xy 197.201513 -4.069061) (xy 197.209403 -4.209547) (xy 197.209918 -4.2799)
			(xy 197.209918 -6.011875) (xy 208.043513 -6.011875) (xy 208.043513 -5.926125) (xy 208.051425 -5.840742)
			(xy 208.067181 -5.756452) (xy 208.090648 -5.673976) (xy 208.121624 -5.594017) (xy 208.159846 -5.517257)
			(xy 208.204987 -5.444351) (xy 208.256663 -5.375922) (xy 208.314432 -5.312552) (xy 208.377802 -5.254783)
			(xy 208.446231 -5.203107) (xy 208.519137 -5.157966) (xy 208.595897 -5.119744) (xy 208.675856 -5.088768)
			(xy 208.758332 -5.065301) (xy 208.842622 -5.049545) (xy 208.928005 -5.041633) (xy 209.013755 -5.041633)
			(xy 209.099138 -5.049545) (xy 209.183428 -5.065301) (xy 209.265904 -5.088768) (xy 209.345863 -5.119744)
			(xy 209.368066 -5.1308) (xy 212.978492 -5.1308) (xy 212.978492 -4.2672) (xy 212.978978 -4.239931)
			(xy 212.98674 -4.185947) (xy 213.002105 -4.133617) (xy 213.024762 -4.084007) (xy 213.054248 -4.038126)
			(xy 213.089963 -3.996909) (xy 213.13118 -3.961194) (xy 213.177061 -3.931708) (xy 213.226671 -3.909051)
			(xy 213.279001 -3.893686) (xy 213.332985 -3.885924) (xy 213.387523 -3.885924) (xy 213.441507 -3.893686)
			(xy 213.493837 -3.909051) (xy 213.543447 -3.931708) (xy 213.589328 -3.961194) (xy 213.630545 -3.996909)
			(xy 213.66626 -4.038126) (xy 213.695746 -4.084007) (xy 213.718403 -4.133617) (xy 213.733768 -4.185947)
			(xy 213.74153 -4.239931) (xy 213.742016 -4.2672) (xy 213.742016 -5.1308) (xy 213.74153 -5.158069)
			(xy 213.733768 -5.212053) (xy 213.718403 -5.264383) (xy 213.695746 -5.313993) (xy 213.66626 -5.359874)
			(xy 213.630545 -5.401091) (xy 213.589328 -5.436806) (xy 213.543447 -5.466292) (xy 213.493837 -5.488949)
			(xy 213.441507 -5.504314) (xy 213.387523 -5.512076) (xy 213.332985 -5.512076) (xy 213.279001 -5.504314)
			(xy 213.226671 -5.488949) (xy 213.177061 -5.466292) (xy 213.13118 -5.436806) (xy 213.089963 -5.401091)
			(xy 213.054248 -5.359874) (xy 213.024762 -5.313993) (xy 213.002105 -5.264383) (xy 212.98674 -5.212053)
			(xy 212.978978 -5.158069) (xy 212.978492 -5.1308) (xy 209.368066 -5.1308) (xy 209.422623 -5.157966)
			(xy 209.495529 -5.203107) (xy 209.563958 -5.254783) (xy 209.627328 -5.312552) (xy 209.685097 -5.375922)
			(xy 209.736773 -5.444351) (xy 209.781914 -5.517257) (xy 209.820136 -5.594017) (xy 209.851112 -5.673976)
			(xy 209.874579 -5.756452) (xy 209.890335 -5.840742) (xy 209.898247 -5.926125) (xy 209.898742 -5.969)
			(xy 209.898247 -6.011875) (xy 214.393513 -6.011875) (xy 214.393513 -5.926125) (xy 214.401425 -5.840742)
			(xy 214.417181 -5.756452) (xy 214.440648 -5.673976) (xy 214.471624 -5.594017) (xy 214.509846 -5.517257)
			(xy 214.554987 -5.444351) (xy 214.606663 -5.375922) (xy 214.664432 -5.312552) (xy 214.727802 -5.254783)
			(xy 214.796231 -5.203107) (xy 214.869137 -5.157966) (xy 214.945897 -5.119744) (xy 215.025856 -5.088768)
			(xy 215.108332 -5.065301) (xy 215.192622 -5.049545) (xy 215.278005 -5.041633) (xy 215.363755 -5.041633)
			(xy 215.449138 -5.049545) (xy 215.533428 -5.065301) (xy 215.615904 -5.088768) (xy 215.695863 -5.119744)
			(xy 215.772623 -5.157966) (xy 215.845529 -5.203107) (xy 215.913958 -5.254783) (xy 215.977328 -5.312552)
			(xy 216.035097 -5.375922) (xy 216.086773 -5.444351) (xy 216.131914 -5.517257) (xy 216.170136 -5.594017)
			(xy 216.201112 -5.673976) (xy 216.224579 -5.756452) (xy 216.240335 -5.840742) (xy 216.248247 -5.926125)
			(xy 216.248742 -5.969) (xy 216.248247 -6.011875) (xy 246.260353 -6.011875) (xy 246.260353 -5.926125)
			(xy 246.268265 -5.840742) (xy 246.284021 -5.756452) (xy 246.307488 -5.673976) (xy 246.338464 -5.594017)
			(xy 246.376686 -5.517257) (xy 246.421827 -5.444351) (xy 246.473503 -5.375922) (xy 246.531272 -5.312552)
			(xy 246.594642 -5.254783) (xy 246.663071 -5.203107) (xy 246.735977 -5.157966) (xy 246.812737 -5.119744)
			(xy 246.892696 -5.088768) (xy 246.975172 -5.065301) (xy 247.059462 -5.049545) (xy 247.144845 -5.041633)
			(xy 247.230595 -5.041633) (xy 247.315978 -5.049545) (xy 247.400268 -5.065301) (xy 247.482744 -5.088768)
			(xy 247.562703 -5.119744) (xy 247.584906 -5.1308) (xy 248.766584 -5.1308) (xy 248.766584 -4.2672)
			(xy 248.76707 -4.239931) (xy 248.774832 -4.185947) (xy 248.790197 -4.133617) (xy 248.812854 -4.084007)
			(xy 248.84234 -4.038126) (xy 248.878055 -3.996909) (xy 248.919272 -3.961194) (xy 248.965153 -3.931708)
			(xy 249.014763 -3.909051) (xy 249.067093 -3.893686) (xy 249.121077 -3.885924) (xy 249.175615 -3.885924)
			(xy 249.229599 -3.893686) (xy 249.281929 -3.909051) (xy 249.331539 -3.931708) (xy 249.37742 -3.961194)
			(xy 249.418637 -3.996909) (xy 249.454352 -4.038126) (xy 249.483838 -4.084007) (xy 249.506495 -4.133617)
			(xy 249.52186 -4.185947) (xy 249.529622 -4.239931) (xy 249.530108 -4.2672) (xy 249.530108 -5.1308)
			(xy 249.529622 -5.158069) (xy 249.52186 -5.212053) (xy 249.506495 -5.264383) (xy 249.483838 -5.313993)
			(xy 249.454352 -5.359874) (xy 249.418637 -5.401091) (xy 249.37742 -5.436806) (xy 249.331539 -5.466292)
			(xy 249.281929 -5.488949) (xy 249.229599 -5.504314) (xy 249.175615 -5.512076) (xy 249.121077 -5.512076)
			(xy 249.067093 -5.504314) (xy 249.014763 -5.488949) (xy 248.965153 -5.466292) (xy 248.919272 -5.436806)
			(xy 248.878055 -5.401091) (xy 248.84234 -5.359874) (xy 248.812854 -5.313993) (xy 248.790197 -5.264383)
			(xy 248.774832 -5.212053) (xy 248.76707 -5.158069) (xy 248.766584 -5.1308) (xy 247.584906 -5.1308)
			(xy 247.639463 -5.157966) (xy 247.712369 -5.203107) (xy 247.780798 -5.254783) (xy 247.844168 -5.312552)
			(xy 247.901937 -5.375922) (xy 247.953613 -5.444351) (xy 247.998754 -5.517257) (xy 248.036976 -5.594017)
			(xy 248.067952 -5.673976) (xy 248.091419 -5.756452) (xy 248.107175 -5.840742) (xy 248.115087 -5.926125)
			(xy 248.115582 -5.969) (xy 248.115087 -6.011875) (xy 252.610353 -6.011875) (xy 252.610353 -5.926125)
			(xy 252.618265 -5.840742) (xy 252.634021 -5.756452) (xy 252.657488 -5.673976) (xy 252.688464 -5.594017)
			(xy 252.726686 -5.517257) (xy 252.771827 -5.444351) (xy 252.823503 -5.375922) (xy 252.881272 -5.312552)
			(xy 252.944642 -5.254783) (xy 253.013071 -5.203107) (xy 253.085977 -5.157966) (xy 253.162737 -5.119744)
			(xy 253.242696 -5.088768) (xy 253.325172 -5.065301) (xy 253.409462 -5.049545) (xy 253.494845 -5.041633)
			(xy 253.580595 -5.041633) (xy 253.665978 -5.049545) (xy 253.750268 -5.065301) (xy 253.832744 -5.088768)
			(xy 253.912703 -5.119744) (xy 253.989463 -5.157966) (xy 254.062369 -5.203107) (xy 254.130798 -5.254783)
			(xy 254.194168 -5.312552) (xy 254.251937 -5.375922) (xy 254.303613 -5.444351) (xy 254.348754 -5.517257)
			(xy 254.386976 -5.594017) (xy 254.417952 -5.673976) (xy 254.441419 -5.756452) (xy 254.457175 -5.840742)
			(xy 254.465087 -5.926125) (xy 254.465582 -5.969) (xy 254.465119 -6.009081) (xy 256.921241 -6.009081)
			(xy 256.921241 -5.923331) (xy 256.929153 -5.837948) (xy 256.944909 -5.753658) (xy 256.968376 -5.671182)
			(xy 256.999352 -5.591223) (xy 257.037574 -5.514463) (xy 257.082715 -5.441557) (xy 257.134391 -5.373128)
			(xy 257.19216 -5.309758) (xy 257.25553 -5.251989) (xy 257.323959 -5.200313) (xy 257.396865 -5.155172)
			(xy 257.473625 -5.11695) (xy 257.553584 -5.085974) (xy 257.63606 -5.062507) (xy 257.72035 -5.046751)
			(xy 257.805733 -5.038839) (xy 257.891483 -5.038839) (xy 257.976866 -5.046751) (xy 258.061156 -5.062507)
			(xy 258.143632 -5.085974) (xy 258.223591 -5.11695) (xy 258.300351 -5.155172) (xy 258.373257 -5.200313)
			(xy 258.441686 -5.251989) (xy 258.505056 -5.309758) (xy 258.562825 -5.373128) (xy 258.614501 -5.441557)
			(xy 258.659642 -5.514463) (xy 258.697864 -5.591223) (xy 258.72884 -5.671182) (xy 258.752307 -5.753658)
			(xy 258.768063 -5.837948) (xy 258.775975 -5.923331) (xy 258.77647 -5.966206) (xy 258.775975 -6.009081)
			(xy 263.271241 -6.009081) (xy 263.271241 -5.923331) (xy 263.279153 -5.837948) (xy 263.294909 -5.753658)
			(xy 263.318376 -5.671182) (xy 263.349352 -5.591223) (xy 263.387574 -5.514463) (xy 263.432715 -5.441557)
			(xy 263.484391 -5.373128) (xy 263.54216 -5.309758) (xy 263.60553 -5.251989) (xy 263.673959 -5.200313)
			(xy 263.746865 -5.155172) (xy 263.823625 -5.11695) (xy 263.903584 -5.085974) (xy 263.98606 -5.062507)
			(xy 264.07035 -5.046751) (xy 264.155733 -5.038839) (xy 264.241483 -5.038839) (xy 264.326866 -5.046751)
			(xy 264.411156 -5.062507) (xy 264.493632 -5.085974) (xy 264.573591 -5.11695) (xy 264.650351 -5.155172)
			(xy 264.723257 -5.200313) (xy 264.791686 -5.251989) (xy 264.855056 -5.309758) (xy 264.912825 -5.373128)
			(xy 264.964501 -5.441557) (xy 265.009642 -5.514463) (xy 265.047864 -5.591223) (xy 265.07884 -5.671182)
			(xy 265.102307 -5.753658) (xy 265.118063 -5.837948) (xy 265.125975 -5.923331) (xy 265.12647 -5.966206)
			(xy 265.125975 -6.009081) (xy 324.845921 -6.009081) (xy 324.845921 -5.923331) (xy 324.853833 -5.837948)
			(xy 324.869589 -5.753658) (xy 324.893056 -5.671182) (xy 324.924032 -5.591223) (xy 324.962254 -5.514463)
			(xy 325.007395 -5.441557) (xy 325.059071 -5.373128) (xy 325.11684 -5.309758) (xy 325.18021 -5.251989)
			(xy 325.248639 -5.200313) (xy 325.321545 -5.155172) (xy 325.398305 -5.11695) (xy 325.478264 -5.085974)
			(xy 325.56074 -5.062507) (xy 325.64503 -5.046751) (xy 325.730413 -5.038839) (xy 325.816163 -5.038839)
			(xy 325.901546 -5.046751) (xy 325.985836 -5.062507) (xy 326.068312 -5.085974) (xy 326.148271 -5.11695)
			(xy 326.225031 -5.155172) (xy 326.297937 -5.200313) (xy 326.366366 -5.251989) (xy 326.429736 -5.309758)
			(xy 326.487505 -5.373128) (xy 326.539181 -5.441557) (xy 326.584322 -5.514463) (xy 326.622544 -5.591223)
			(xy 326.65352 -5.671182) (xy 326.676987 -5.753658) (xy 326.692743 -5.837948) (xy 326.700655 -5.923331)
			(xy 326.70115 -5.966206) (xy 326.700655 -6.009081) (xy 331.195921 -6.009081) (xy 331.195921 -5.923331)
			(xy 331.203833 -5.837948) (xy 331.219589 -5.753658) (xy 331.243056 -5.671182) (xy 331.274032 -5.591223)
			(xy 331.312254 -5.514463) (xy 331.357395 -5.441557) (xy 331.409071 -5.373128) (xy 331.46684 -5.309758)
			(xy 331.53021 -5.251989) (xy 331.598639 -5.200313) (xy 331.671545 -5.155172) (xy 331.748305 -5.11695)
			(xy 331.828264 -5.085974) (xy 331.91074 -5.062507) (xy 331.99503 -5.046751) (xy 332.080413 -5.038839)
			(xy 332.166163 -5.038839) (xy 332.251546 -5.046751) (xy 332.335836 -5.062507) (xy 332.418312 -5.085974)
			(xy 332.498271 -5.11695) (xy 332.575031 -5.155172) (xy 332.647937 -5.200313) (xy 332.716366 -5.251989)
			(xy 332.779736 -5.309758) (xy 332.837505 -5.373128) (xy 332.889181 -5.441557) (xy 332.934322 -5.514463)
			(xy 332.972544 -5.591223) (xy 333.00352 -5.671182) (xy 333.026987 -5.753658) (xy 333.042743 -5.837948)
			(xy 333.050655 -5.923331) (xy 333.05115 -5.966206) (xy 333.050655 -6.009081) (xy 335.488267 -6.009081)
			(xy 335.488267 -5.923331) (xy 335.496179 -5.837948) (xy 335.511935 -5.753658) (xy 335.535402 -5.671182)
			(xy 335.566378 -5.591223) (xy 335.6046 -5.514463) (xy 335.649741 -5.441557) (xy 335.701417 -5.373128)
			(xy 335.759186 -5.309758) (xy 335.822556 -5.251989) (xy 335.890985 -5.200313) (xy 335.963891 -5.155172)
			(xy 336.040651 -5.11695) (xy 336.12061 -5.085974) (xy 336.203086 -5.062507) (xy 336.287376 -5.046751)
			(xy 336.372759 -5.038839) (xy 336.458509 -5.038839) (xy 336.543892 -5.046751) (xy 336.628182 -5.062507)
			(xy 336.710658 -5.085974) (xy 336.790617 -5.11695) (xy 336.867377 -5.155172) (xy 336.940283 -5.200313)
			(xy 337.008712 -5.251989) (xy 337.072082 -5.309758) (xy 337.129851 -5.373128) (xy 337.181527 -5.441557)
			(xy 337.226668 -5.514463) (xy 337.26489 -5.591223) (xy 337.295866 -5.671182) (xy 337.319333 -5.753658)
			(xy 337.335089 -5.837948) (xy 337.343001 -5.923331) (xy 337.343496 -5.966206) (xy 337.343001 -6.009081)
			(xy 341.838267 -6.009081) (xy 341.838267 -5.923331) (xy 341.846179 -5.837948) (xy 341.861935 -5.753658)
			(xy 341.885402 -5.671182) (xy 341.916378 -5.591223) (xy 341.9546 -5.514463) (xy 341.999741 -5.441557)
			(xy 342.051417 -5.373128) (xy 342.109186 -5.309758) (xy 342.172556 -5.251989) (xy 342.240985 -5.200313)
			(xy 342.313891 -5.155172) (xy 342.390651 -5.11695) (xy 342.47061 -5.085974) (xy 342.553086 -5.062507)
			(xy 342.637376 -5.046751) (xy 342.722759 -5.038839) (xy 342.808509 -5.038839) (xy 342.893892 -5.046751)
			(xy 342.978182 -5.062507) (xy 343.060658 -5.085974) (xy 343.140617 -5.11695) (xy 343.217377 -5.155172)
			(xy 343.290283 -5.200313) (xy 343.358712 -5.251989) (xy 343.422082 -5.309758) (xy 343.479851 -5.373128)
			(xy 343.531527 -5.441557) (xy 343.576668 -5.514463) (xy 343.61489 -5.591223) (xy 343.645866 -5.671182)
			(xy 343.669333 -5.753658) (xy 343.685089 -5.837948) (xy 343.693001 -5.923331) (xy 343.693496 -5.966206)
			(xy 343.693001 -6.009081) (xy 373.705107 -6.009081) (xy 373.705107 -5.923331) (xy 373.713019 -5.837948)
			(xy 373.728775 -5.753658) (xy 373.752242 -5.671182) (xy 373.783218 -5.591223) (xy 373.82144 -5.514463)
			(xy 373.866581 -5.441557) (xy 373.918257 -5.373128) (xy 373.976026 -5.309758) (xy 374.039396 -5.251989)
			(xy 374.107825 -5.200313) (xy 374.180731 -5.155172) (xy 374.257491 -5.11695) (xy 374.33745 -5.085974)
			(xy 374.419926 -5.062507) (xy 374.504216 -5.046751) (xy 374.589599 -5.038839) (xy 374.675349 -5.038839)
			(xy 374.760732 -5.046751) (xy 374.845022 -5.062507) (xy 374.927498 -5.085974) (xy 375.007457 -5.11695)
			(xy 375.084217 -5.155172) (xy 375.157123 -5.200313) (xy 375.225552 -5.251989) (xy 375.288922 -5.309758)
			(xy 375.346691 -5.373128) (xy 375.398367 -5.441557) (xy 375.443508 -5.514463) (xy 375.48173 -5.591223)
			(xy 375.512706 -5.671182) (xy 375.536173 -5.753658) (xy 375.551929 -5.837948) (xy 375.559841 -5.923331)
			(xy 375.560336 -5.966206) (xy 375.559841 -6.009081) (xy 380.055107 -6.009081) (xy 380.055107 -5.923331)
			(xy 380.063019 -5.837948) (xy 380.078775 -5.753658) (xy 380.102242 -5.671182) (xy 380.133218 -5.591223)
			(xy 380.17144 -5.514463) (xy 380.216581 -5.441557) (xy 380.268257 -5.373128) (xy 380.326026 -5.309758)
			(xy 380.389396 -5.251989) (xy 380.457825 -5.200313) (xy 380.530731 -5.155172) (xy 380.607491 -5.11695)
			(xy 380.68745 -5.085974) (xy 380.769926 -5.062507) (xy 380.854216 -5.046751) (xy 380.939599 -5.038839)
			(xy 381.025349 -5.038839) (xy 381.110732 -5.046751) (xy 381.195022 -5.062507) (xy 381.277498 -5.085974)
			(xy 381.357457 -5.11695) (xy 381.434217 -5.155172) (xy 381.507123 -5.200313) (xy 381.575552 -5.251989)
			(xy 381.638922 -5.309758) (xy 381.696691 -5.373128) (xy 381.748367 -5.441557) (xy 381.793508 -5.514463)
			(xy 381.83173 -5.591223) (xy 381.862706 -5.671182) (xy 381.886173 -5.753658) (xy 381.901929 -5.837948)
			(xy 381.909841 -5.923331) (xy 381.910336 -5.966206) (xy 381.909841 -6.009081) (xy 381.901929 -6.094464)
			(xy 381.886173 -6.178754) (xy 381.862706 -6.26123) (xy 381.83173 -6.341189) (xy 381.793508 -6.417949)
			(xy 381.748367 -6.490855) (xy 381.696691 -6.559284) (xy 381.638922 -6.622654) (xy 381.575552 -6.680423)
			(xy 381.507123 -6.732099) (xy 381.434217 -6.77724) (xy 381.357457 -6.815462) (xy 381.277498 -6.846438)
			(xy 381.195022 -6.869905) (xy 381.110732 -6.885661) (xy 381.025349 -6.893573) (xy 380.939599 -6.893573)
			(xy 380.854216 -6.885661) (xy 380.769926 -6.869905) (xy 380.68745 -6.846438) (xy 380.607491 -6.815462)
			(xy 380.530731 -6.77724) (xy 380.457825 -6.732099) (xy 380.389396 -6.680423) (xy 380.326026 -6.622654)
			(xy 380.268257 -6.559284) (xy 380.216581 -6.490855) (xy 380.17144 -6.417949) (xy 380.133218 -6.341189)
			(xy 380.102242 -6.26123) (xy 380.078775 -6.178754) (xy 380.063019 -6.094464) (xy 380.055107 -6.009081)
			(xy 375.559841 -6.009081) (xy 375.551929 -6.094464) (xy 375.536173 -6.178754) (xy 375.512706 -6.26123)
			(xy 375.48173 -6.341189) (xy 375.443508 -6.417949) (xy 375.398367 -6.490855) (xy 375.346691 -6.559284)
			(xy 375.288922 -6.622654) (xy 375.225552 -6.680423) (xy 375.157123 -6.732099) (xy 375.084217 -6.77724)
			(xy 375.007457 -6.815462) (xy 374.927498 -6.846438) (xy 374.845022 -6.869905) (xy 374.760732 -6.885661)
			(xy 374.675349 -6.893573) (xy 374.589599 -6.893573) (xy 374.504216 -6.885661) (xy 374.419926 -6.869905)
			(xy 374.33745 -6.846438) (xy 374.257491 -6.815462) (xy 374.180731 -6.77724) (xy 374.107825 -6.732099)
			(xy 374.039396 -6.680423) (xy 373.976026 -6.622654) (xy 373.918257 -6.559284) (xy 373.866581 -6.490855)
			(xy 373.82144 -6.417949) (xy 373.783218 -6.341189) (xy 373.752242 -6.26123) (xy 373.728775 -6.178754)
			(xy 373.713019 -6.094464) (xy 373.705107 -6.009081) (xy 343.693001 -6.009081) (xy 343.685089 -6.094464)
			(xy 343.669333 -6.178754) (xy 343.645866 -6.26123) (xy 343.61489 -6.341189) (xy 343.576668 -6.417949)
			(xy 343.531527 -6.490855) (xy 343.479851 -6.559284) (xy 343.422082 -6.622654) (xy 343.358712 -6.680423)
			(xy 343.290283 -6.732099) (xy 343.217377 -6.77724) (xy 343.140617 -6.815462) (xy 343.060658 -6.846438)
			(xy 342.978182 -6.869905) (xy 342.893892 -6.885661) (xy 342.808509 -6.893573) (xy 342.722759 -6.893573)
			(xy 342.637376 -6.885661) (xy 342.553086 -6.869905) (xy 342.47061 -6.846438) (xy 342.390651 -6.815462)
			(xy 342.313891 -6.77724) (xy 342.240985 -6.732099) (xy 342.172556 -6.680423) (xy 342.109186 -6.622654)
			(xy 342.051417 -6.559284) (xy 341.999741 -6.490855) (xy 341.9546 -6.417949) (xy 341.916378 -6.341189)
			(xy 341.885402 -6.26123) (xy 341.861935 -6.178754) (xy 341.846179 -6.094464) (xy 341.838267 -6.009081)
			(xy 337.343001 -6.009081) (xy 337.335089 -6.094464) (xy 337.319333 -6.178754) (xy 337.295866 -6.26123)
			(xy 337.26489 -6.341189) (xy 337.226668 -6.417949) (xy 337.181527 -6.490855) (xy 337.129851 -6.559284)
			(xy 337.072082 -6.622654) (xy 337.008712 -6.680423) (xy 336.940283 -6.732099) (xy 336.867377 -6.77724)
			(xy 336.790617 -6.815462) (xy 336.710658 -6.846438) (xy 336.628182 -6.869905) (xy 336.543892 -6.885661)
			(xy 336.458509 -6.893573) (xy 336.372759 -6.893573) (xy 336.287376 -6.885661) (xy 336.203086 -6.869905)
			(xy 336.12061 -6.846438) (xy 336.040651 -6.815462) (xy 335.963891 -6.77724) (xy 335.890985 -6.732099)
			(xy 335.822556 -6.680423) (xy 335.759186 -6.622654) (xy 335.701417 -6.559284) (xy 335.649741 -6.490855)
			(xy 335.6046 -6.417949) (xy 335.566378 -6.341189) (xy 335.535402 -6.26123) (xy 335.511935 -6.178754)
			(xy 335.496179 -6.094464) (xy 335.488267 -6.009081) (xy 333.050655 -6.009081) (xy 333.042743 -6.094464)
			(xy 333.026987 -6.178754) (xy 333.00352 -6.26123) (xy 332.972544 -6.341189) (xy 332.934322 -6.417949)
			(xy 332.889181 -6.490855) (xy 332.837505 -6.559284) (xy 332.779736 -6.622654) (xy 332.716366 -6.680423)
			(xy 332.647937 -6.732099) (xy 332.575031 -6.77724) (xy 332.498271 -6.815462) (xy 332.418312 -6.846438)
			(xy 332.335836 -6.869905) (xy 332.251546 -6.885661) (xy 332.166163 -6.893573) (xy 332.080413 -6.893573)
			(xy 331.99503 -6.885661) (xy 331.91074 -6.869905) (xy 331.828264 -6.846438) (xy 331.748305 -6.815462)
			(xy 331.671545 -6.77724) (xy 331.598639 -6.732099) (xy 331.53021 -6.680423) (xy 331.46684 -6.622654)
			(xy 331.409071 -6.559284) (xy 331.357395 -6.490855) (xy 331.312254 -6.417949) (xy 331.274032 -6.341189)
			(xy 331.243056 -6.26123) (xy 331.219589 -6.178754) (xy 331.203833 -6.094464) (xy 331.195921 -6.009081)
			(xy 326.700655 -6.009081) (xy 326.692743 -6.094464) (xy 326.676987 -6.178754) (xy 326.65352 -6.26123)
			(xy 326.622544 -6.341189) (xy 326.584322 -6.417949) (xy 326.539181 -6.490855) (xy 326.487505 -6.559284)
			(xy 326.429736 -6.622654) (xy 326.366366 -6.680423) (xy 326.297937 -6.732099) (xy 326.225031 -6.77724)
			(xy 326.148271 -6.815462) (xy 326.068312 -6.846438) (xy 325.985836 -6.869905) (xy 325.901546 -6.885661)
			(xy 325.816163 -6.893573) (xy 325.730413 -6.893573) (xy 325.64503 -6.885661) (xy 325.56074 -6.869905)
			(xy 325.478264 -6.846438) (xy 325.398305 -6.815462) (xy 325.321545 -6.77724) (xy 325.248639 -6.732099)
			(xy 325.18021 -6.680423) (xy 325.11684 -6.622654) (xy 325.059071 -6.559284) (xy 325.007395 -6.490855)
			(xy 324.962254 -6.417949) (xy 324.924032 -6.341189) (xy 324.893056 -6.26123) (xy 324.869589 -6.178754)
			(xy 324.853833 -6.094464) (xy 324.845921 -6.009081) (xy 265.125975 -6.009081) (xy 265.118063 -6.094464)
			(xy 265.102307 -6.178754) (xy 265.07884 -6.26123) (xy 265.047864 -6.341189) (xy 265.009642 -6.417949)
			(xy 264.964501 -6.490855) (xy 264.912825 -6.559284) (xy 264.855056 -6.622654) (xy 264.791686 -6.680423)
			(xy 264.723257 -6.732099) (xy 264.650351 -6.77724) (xy 264.573591 -6.815462) (xy 264.493632 -6.846438)
			(xy 264.411156 -6.869905) (xy 264.326866 -6.885661) (xy 264.241483 -6.893573) (xy 264.155733 -6.893573)
			(xy 264.07035 -6.885661) (xy 263.98606 -6.869905) (xy 263.903584 -6.846438) (xy 263.823625 -6.815462)
			(xy 263.746865 -6.77724) (xy 263.673959 -6.732099) (xy 263.60553 -6.680423) (xy 263.54216 -6.622654)
			(xy 263.484391 -6.559284) (xy 263.432715 -6.490855) (xy 263.387574 -6.417949) (xy 263.349352 -6.341189)
			(xy 263.318376 -6.26123) (xy 263.294909 -6.178754) (xy 263.279153 -6.094464) (xy 263.271241 -6.009081)
			(xy 258.775975 -6.009081) (xy 258.768063 -6.094464) (xy 258.752307 -6.178754) (xy 258.72884 -6.26123)
			(xy 258.697864 -6.341189) (xy 258.659642 -6.417949) (xy 258.614501 -6.490855) (xy 258.562825 -6.559284)
			(xy 258.505056 -6.622654) (xy 258.441686 -6.680423) (xy 258.373257 -6.732099) (xy 258.300351 -6.77724)
			(xy 258.223591 -6.815462) (xy 258.143632 -6.846438) (xy 258.061156 -6.869905) (xy 257.976866 -6.885661)
			(xy 257.891483 -6.893573) (xy 257.805733 -6.893573) (xy 257.72035 -6.885661) (xy 257.63606 -6.869905)
			(xy 257.553584 -6.846438) (xy 257.473625 -6.815462) (xy 257.396865 -6.77724) (xy 257.323959 -6.732099)
			(xy 257.25553 -6.680423) (xy 257.19216 -6.622654) (xy 257.134391 -6.559284) (xy 257.082715 -6.490855)
			(xy 257.037574 -6.417949) (xy 256.999352 -6.341189) (xy 256.968376 -6.26123) (xy 256.944909 -6.178754)
			(xy 256.929153 -6.094464) (xy 256.921241 -6.009081) (xy 254.465119 -6.009081) (xy 254.465087 -6.011875)
			(xy 254.457175 -6.097258) (xy 254.441419 -6.181548) (xy 254.417952 -6.264024) (xy 254.386976 -6.343983)
			(xy 254.348754 -6.420743) (xy 254.303613 -6.493649) (xy 254.251937 -6.562078) (xy 254.194168 -6.625448)
			(xy 254.130798 -6.683217) (xy 254.062369 -6.734893) (xy 253.989463 -6.780034) (xy 253.912703 -6.818256)
			(xy 253.832744 -6.849232) (xy 253.750268 -6.872699) (xy 253.665978 -6.888455) (xy 253.580595 -6.896367)
			(xy 253.494845 -6.896367) (xy 253.409462 -6.888455) (xy 253.325172 -6.872699) (xy 253.242696 -6.849232)
			(xy 253.162737 -6.818256) (xy 253.085977 -6.780034) (xy 253.013071 -6.734893) (xy 252.944642 -6.683217)
			(xy 252.881272 -6.625448) (xy 252.823503 -6.562078) (xy 252.771827 -6.493649) (xy 252.726686 -6.420743)
			(xy 252.688464 -6.343983) (xy 252.657488 -6.264024) (xy 252.634021 -6.181548) (xy 252.618265 -6.097258)
			(xy 252.610353 -6.011875) (xy 248.115087 -6.011875) (xy 248.107175 -6.097258) (xy 248.091419 -6.181548)
			(xy 248.067952 -6.264024) (xy 248.036976 -6.343983) (xy 247.998754 -6.420743) (xy 247.953613 -6.493649)
			(xy 247.901937 -6.562078) (xy 247.844168 -6.625448) (xy 247.780798 -6.683217) (xy 247.712369 -6.734893)
			(xy 247.639463 -6.780034) (xy 247.562703 -6.818256) (xy 247.482744 -6.849232) (xy 247.400268 -6.872699)
			(xy 247.315978 -6.888455) (xy 247.230595 -6.896367) (xy 247.144845 -6.896367) (xy 247.059462 -6.888455)
			(xy 246.975172 -6.872699) (xy 246.892696 -6.849232) (xy 246.812737 -6.818256) (xy 246.735977 -6.780034)
			(xy 246.663071 -6.734893) (xy 246.594642 -6.683217) (xy 246.531272 -6.625448) (xy 246.473503 -6.562078)
			(xy 246.421827 -6.493649) (xy 246.376686 -6.420743) (xy 246.338464 -6.343983) (xy 246.307488 -6.264024)
			(xy 246.284021 -6.181548) (xy 246.268265 -6.097258) (xy 246.260353 -6.011875) (xy 216.248247 -6.011875)
			(xy 216.240335 -6.097258) (xy 216.224579 -6.181548) (xy 216.201112 -6.264024) (xy 216.170136 -6.343983)
			(xy 216.131914 -6.420743) (xy 216.086773 -6.493649) (xy 216.035097 -6.562078) (xy 215.977328 -6.625448)
			(xy 215.913958 -6.683217) (xy 215.845529 -6.734893) (xy 215.772623 -6.780034) (xy 215.695863 -6.818256)
			(xy 215.615904 -6.849232) (xy 215.533428 -6.872699) (xy 215.449138 -6.888455) (xy 215.363755 -6.896367)
			(xy 215.278005 -6.896367) (xy 215.192622 -6.888455) (xy 215.108332 -6.872699) (xy 215.025856 -6.849232)
			(xy 214.945897 -6.818256) (xy 214.869137 -6.780034) (xy 214.796231 -6.734893) (xy 214.727802 -6.683217)
			(xy 214.664432 -6.625448) (xy 214.606663 -6.562078) (xy 214.554987 -6.493649) (xy 214.509846 -6.420743)
			(xy 214.471624 -6.343983) (xy 214.440648 -6.264024) (xy 214.417181 -6.181548) (xy 214.401425 -6.097258)
			(xy 214.393513 -6.011875) (xy 209.898247 -6.011875) (xy 209.890335 -6.097258) (xy 209.874579 -6.181548)
			(xy 209.851112 -6.264024) (xy 209.820136 -6.343983) (xy 209.781914 -6.420743) (xy 209.736773 -6.493649)
			(xy 209.685097 -6.562078) (xy 209.627328 -6.625448) (xy 209.563958 -6.683217) (xy 209.495529 -6.734893)
			(xy 209.422623 -6.780034) (xy 209.345863 -6.818256) (xy 209.265904 -6.849232) (xy 209.183428 -6.872699)
			(xy 209.099138 -6.888455) (xy 209.013755 -6.896367) (xy 208.928005 -6.896367) (xy 208.842622 -6.888455)
			(xy 208.758332 -6.872699) (xy 208.675856 -6.849232) (xy 208.595897 -6.818256) (xy 208.519137 -6.780034)
			(xy 208.446231 -6.734893) (xy 208.377802 -6.683217) (xy 208.314432 -6.625448) (xy 208.256663 -6.562078)
			(xy 208.204987 -6.493649) (xy 208.159846 -6.420743) (xy 208.121624 -6.343983) (xy 208.090648 -6.264024)
			(xy 208.067181 -6.181548) (xy 208.051425 -6.097258) (xy 208.043513 -6.011875) (xy 197.209918 -6.011875)
			(xy 197.209918 -7.78002) (xy 197.21044 -7.835826) (xy 197.218783 -7.947127) (xy 197.235419 -8.057493)
			(xy 197.260257 -8.166307) (xy 197.293157 -8.27296) (xy 197.333935 -8.376857) (xy 197.382363 -8.477416)
			(xy 197.43817 -8.574075) (xy 197.501045 -8.666293) (xy 197.570635 -8.753555) (xy 197.646552 -8.835372)
			(xy 197.728371 -8.911287) (xy 197.815634 -8.980875) (xy 197.907854 -9.043748) (xy 198.004514 -9.099553)
			(xy 198.105074 -9.147979) (xy 198.208972 -9.188755) (xy 198.315626 -9.221652) (xy 198.424441 -9.246487)
			(xy 198.534807 -9.263121) (xy 198.646108 -9.271461) (xy 198.701914 -9.272016) (xy 223.300036 -9.272016)
			(xy 223.370389 -9.27251) (xy 223.510873 -9.280402) (xy 223.650694 -9.296158) (xy 223.789412 -9.319729)
			(xy 223.92659 -9.35104) (xy 224.061796 -9.389995) (xy 224.194606 -9.436468) (xy 224.3246 -9.490316)
			(xy 224.451371 -9.551367) (xy 224.57452 -9.619431) (xy 224.693658 -9.694292) (xy 224.808411 -9.775716)
			(xy 224.918419 -9.863446) (xy 225.023334 -9.957206) (xy 225.122827 -10.056701) (xy 225.216585 -10.161618)
			(xy 225.304313 -10.271627) (xy 225.385734 -10.386382) (xy 225.460594 -10.505522) (xy 225.528655 -10.628671)
			(xy 225.589704 -10.755444) (xy 225.643549 -10.885439) (xy 225.69002 -11.01825) (xy 225.728972 -11.153457)
			(xy 225.760281 -11.290635) (xy 225.783849 -11.429353) (xy 225.799602 -11.569174) (xy 225.807491 -11.709659)
			(xy 225.808032 -11.780012) (xy 225.808032 -31.197296) (xy 227.377752 -32.767016) (xy 254.645668 -32.767016)
		)
		(stroke
			(width 0)
			(type solid)
		)
		(fill yes)
		(layer "In16.Cu")
		(net "DELTA_L_GND_1")
	)
	(gr_poly
		(pts
			(xy 194.495928 -441.17006) (xy 194.49641 -441.126022) (xy 194.50409 -441.03828) (xy 194.519387 -440.951542)
			(xy 194.542185 -440.866466) (xy 194.572311 -440.783702) (xy 194.609536 -440.703878) (xy 194.653576 -440.627602)
			(xy 194.704095 -440.555454) (xy 194.760711 -440.487984) (xy 194.822991 -440.425704) (xy 194.890462 -440.369089)
			(xy 194.96261 -440.31857) (xy 195.038887 -440.274531) (xy 195.118711 -440.237308) (xy 195.201476 -440.207182)
			(xy 195.286551 -440.184385) (xy 195.37329 -440.169088) (xy 195.461032 -440.16141) (xy 195.50507 -440.160918)
			(xy 276.314916 -440.160918) (xy 276.358955 -440.161399) (xy 276.446699 -440.169077) (xy 276.533439 -440.184372)
			(xy 276.618516 -440.207169) (xy 276.701283 -440.237294) (xy 276.781109 -440.274518) (xy 276.857388 -440.318557)
			(xy 276.929538 -440.369076) (xy 276.99701 -440.425692) (xy 277.059292 -440.487972) (xy 277.115909 -440.555443)
			(xy 277.16643 -440.627592) (xy 277.210471 -440.703869) (xy 277.247697 -440.783695) (xy 277.277823 -440.866461)
			(xy 277.300622 -440.951538) (xy 277.31592 -441.038278) (xy 277.3236 -441.126021) (xy 277.324058 -441.17006)
			(xy 277.324058 -441.480956) (xy 463.300064 -441.480956) (xy 463.355834 -441.480449) (xy 463.467062 -441.472116)
			(xy 463.577357 -441.455494) (xy 463.686101 -441.430676) (xy 463.792686 -441.397801) (xy 463.896517 -441.357052)
			(xy 463.997011 -441.308658) (xy 464.093608 -441.252889) (xy 464.185768 -441.190057) (xy 464.272974 -441.120513)
			(xy 464.354739 -441.044647) (xy 464.430606 -440.962883) (xy 464.50015 -440.875677) (xy 464.562982 -440.783519)
			(xy 464.618752 -440.686922) (xy 464.667147 -440.586428) (xy 464.707897 -440.482598) (xy 464.740773 -440.376013)
			(xy 464.765592 -440.267269) (xy 464.782215 -440.156974) (xy 464.790548 -440.045746) (xy 464.791044 -439.989976)
			(xy 464.791044 -419.236652) (xy 464.79206 -419.236652) (xy 464.79206 -419.160198) (xy 464.791552 -419.157912)
			(xy 464.783498 -419.125745) (xy 464.774831 -419.060003) (xy 464.77428 -419.026848) (xy 464.774826 -418.994155)
			(xy 464.783231 -418.929312) (xy 464.791044 -418.897562) (xy 464.791044 -409.528264) (xy 464.791527 -409.457889)
			(xy 464.799416 -409.317359) (xy 464.815173 -409.177493) (xy 464.838748 -409.03873) (xy 464.870067 -408.901508)
			(xy 464.909031 -408.766258) (xy 464.955519 -408.633405) (xy 465.009383 -408.503369) (xy 465.070454 -408.376557)
			(xy 465.138539 -408.25337) (xy 465.213426 -408.134194) (xy 465.294877 -408.019405) (xy 465.382637 -407.909364)
			(xy 465.47643 -407.804418) (xy 465.525866 -407.754328) (xy 467.354412 -405.925782) (xy 467.391723 -405.887821)
			(xy 467.461438 -405.807375) (xy 467.525236 -405.722161) (xy 467.582791 -405.632611) (xy 467.633809 -405.539182)
			(xy 467.678031 -405.442352) (xy 467.715231 -405.342613) (xy 467.74522 -405.240474) (xy 467.767844 -405.136455)
			(xy 467.782988 -405.031087) (xy 467.790575 -404.924907) (xy 467.791038 -404.871682) (xy 467.791038 -82.82813)
			(xy 467.791541 -82.757757) (xy 467.799451 -82.617233) (xy 467.815226 -82.477373) (xy 467.838815 -82.338618)
			(xy 467.870145 -82.201402) (xy 467.909116 -82.066159) (xy 467.955608 -81.933313) (xy 468.009473 -81.803282)
			(xy 468.070541 -81.676474) (xy 468.138622 -81.553289) (xy 468.213501 -81.434114) (xy 468.294942 -81.319323)
			(xy 468.382689 -81.209278) (xy 468.476467 -81.104324) (xy 468.52586 -81.054194) (xy 470.854278 -78.725776)
			(xy 470.891589 -78.687815) (xy 470.961306 -78.60737) (xy 471.025105 -78.522156) (xy 471.082661 -78.432606)
			(xy 471.13368 -78.339178) (xy 471.177903 -78.242348) (xy 471.215103 -78.142608) (xy 471.245092 -78.040469)
			(xy 471.267716 -77.93645) (xy 471.28286 -77.831082) (xy 471.290447 -77.724901) (xy 471.290904 -77.671676)
			(xy 471.290904 -13.780008) (xy 471.290383 -13.724238) (xy 471.282048 -13.613011) (xy 471.265425 -13.502718)
			(xy 471.240606 -13.393975) (xy 471.20773 -13.287391) (xy 471.166981 -13.183562) (xy 471.118587 -13.083068)
			(xy 471.062818 -12.986472) (xy 470.999987 -12.894314) (xy 470.930444 -12.807108) (xy 470.854579 -12.725344)
			(xy 470.772816 -12.649477) (xy 470.685612 -12.579932) (xy 470.593455 -12.517099) (xy 470.49686 -12.461328)
			(xy 470.396367 -12.412932) (xy 470.292539 -12.372181) (xy 470.185956 -12.339303) (xy 470.077214 -12.314481)
			(xy 469.966921 -12.297855) (xy 469.855694 -12.289518) (xy 469.799924 -12.289028) (xy 464.613244 -12.289028)
			(xy 464.613244 -12.288012) (xy 464.272376 -12.288012) (xy 464.272376 -12.289028) (xy 458.20203 -12.289028)
			(xy 458.131647 -12.288544) (xy 457.991102 -12.280653) (xy 457.85122 -12.264894) (xy 457.712443 -12.241316)
			(xy 457.575205 -12.209994) (xy 457.43994 -12.171027) (xy 457.307072 -12.124536) (xy 457.177021 -12.070668)
			(xy 457.050194 -12.009593) (xy 456.926991 -11.941503) (xy 456.8078 -11.866612) (xy 456.692996 -11.785156)
			(xy 456.582939 -11.69739) (xy 456.477977 -11.603592) (xy 456.378439 -11.504056) (xy 456.284639 -11.399096)
			(xy 456.196872 -11.289041) (xy 456.115413 -11.174238) (xy 456.04052 -11.055048) (xy 455.972428 -10.931847)
			(xy 455.911351 -10.805021) (xy 455.857481 -10.674971) (xy 455.810987 -10.542104) (xy 455.772017 -10.406839)
			(xy 455.740693 -10.269603) (xy 455.717113 -10.130825) (xy 455.701351 -9.990944) (xy 455.693457 -9.850399)
			(xy 455.693018 -9.780016) (xy 455.693018 -0.999998) (xy 455.692493 -0.967851) (xy 455.684101 -0.904107)
			(xy 455.667461 -0.842004) (xy 455.642857 -0.782603) (xy 455.610712 -0.726922) (xy 455.571573 -0.675913)
			(xy 455.526112 -0.630449) (xy 455.475106 -0.591307) (xy 455.419427 -0.559158) (xy 455.360029 -0.53455)
			(xy 455.297926 -0.517906) (xy 455.234183 -0.50951) (xy 455.202036 -0.509016) (xy 388.601966 -0.509016)
			(xy 388.569821 -0.509544) (xy 388.506082 -0.517939) (xy 388.443984 -0.534582) (xy 388.384589 -0.559188)
			(xy 388.328914 -0.591335) (xy 388.277911 -0.630474) (xy 388.232453 -0.675936) (xy 388.193318 -0.726941)
			(xy 388.161174 -0.782618) (xy 388.136572 -0.842014) (xy 388.119933 -0.904114) (xy 388.111542 -0.967853)
			(xy 388.110984 -0.999998) (xy 388.110984 -5.169916) (xy 388.850131 -5.169916) (xy 388.854136 -5.082008)
			(xy 388.866119 -4.994828) (xy 388.885979 -4.909099) (xy 388.913554 -4.825531) (xy 388.948613 -4.744817)
			(xy 388.990866 -4.667625) (xy 389.039964 -4.594596) (xy 389.0955 -4.526334) (xy 389.157012 -4.463404)
			(xy 389.223993 -4.40633) (xy 389.295886 -4.355582) (xy 389.372095 -4.311582) (xy 389.45199 -4.274695)
			(xy 389.534909 -4.245226) (xy 389.620164 -4.223419) (xy 389.707048 -4.209455) (xy 389.794842 -4.203449)
			(xy 389.882819 -4.205453) (xy 389.970249 -4.215448) (xy 390.056408 -4.233352) (xy 390.140582 -4.259016)
			(xy 390.222073 -4.292229) (xy 390.300207 -4.332715) (xy 390.374335 -4.380137) (xy 390.443843 -4.434104)
			(xy 390.508157 -4.494169) (xy 390.566741 -4.559833) (xy 390.619112 -4.630552) (xy 390.664835 -4.70574)
			(xy 390.703532 -4.784775) (xy 390.734881 -4.867001) (xy 390.758623 -4.951737) (xy 390.763638 -4.978969)
			(xy 394.947631 -4.978969) (xy 394.947631 -4.924431) (xy 394.955393 -4.870448) (xy 394.970758 -4.81812)
			(xy 394.993414 -4.76851) (xy 395.0229 -4.72263) (xy 395.058614 -4.681413) (xy 395.099832 -4.645698)
			(xy 395.145712 -4.616213) (xy 395.195321 -4.593557) (xy 395.24765 -4.578193) (xy 395.301633 -4.570431)
			(xy 395.328902 -4.569968) (xy 396.192502 -4.569968) (xy 396.219773 -4.570395) (xy 396.273761 -4.578157)
			(xy 396.326094 -4.593524) (xy 396.375708 -4.616182) (xy 396.421593 -4.64567) (xy 396.462813 -4.681388)
			(xy 396.498531 -4.722609) (xy 396.528019 -4.768493) (xy 396.550677 -4.818107) (xy 396.566043 -4.870441)
			(xy 396.573806 -4.924429) (xy 396.573806 -4.978971) (xy 398.547532 -4.978971) (xy 398.547532 -4.924429)
			(xy 398.555294 -4.870443) (xy 398.570661 -4.818111) (xy 398.593321 -4.768498) (xy 398.62281 -4.722616)
			(xy 398.658529 -4.681398) (xy 398.699751 -4.645684) (xy 398.745637 -4.616199) (xy 398.795252 -4.593546)
			(xy 398.847586 -4.578185) (xy 398.901573 -4.570428) (xy 398.928844 -4.569968) (xy 399.792444 -4.569968)
			(xy 399.819713 -4.570398) (xy 399.873697 -4.578165) (xy 399.926025 -4.593535) (xy 399.975633 -4.616196)
			(xy 400.021512 -4.645685) (xy 400.062728 -4.681403) (xy 400.098441 -4.722623) (xy 400.127925 -4.768505)
			(xy 400.15058 -4.818116) (xy 400.165944 -4.870447) (xy 400.173706 -4.92443) (xy 400.173706 -4.978967)
			(xy 402.147554 -4.978967) (xy 402.147554 -4.924433) (xy 402.155315 -4.870455) (xy 402.170678 -4.818131)
			(xy 402.193332 -4.768526) (xy 402.222814 -4.722649) (xy 402.258525 -4.681435) (xy 402.299738 -4.645722)
			(xy 402.345613 -4.616239) (xy 402.395218 -4.593583) (xy 402.447542 -4.578218) (xy 402.501519 -4.570455)
			(xy 402.528786 -4.569968) (xy 403.392386 -4.569968) (xy 403.41966 -4.570371) (xy 403.473652 -4.578132)
			(xy 403.525991 -4.593498) (xy 403.57561 -4.616157) (xy 403.621499 -4.645646) (xy 403.662724 -4.681366)
			(xy 403.698445 -4.72259) (xy 403.727937 -4.768478) (xy 403.750597 -4.818096) (xy 403.765965 -4.870434)
			(xy 403.773728 -4.924426) (xy 403.773728 -4.978966) (xy 405.747754 -4.978966) (xy 405.747754 -4.924434)
			(xy 405.755515 -4.870456) (xy 405.770878 -4.818132) (xy 405.793531 -4.768527) (xy 405.823013 -4.72265)
			(xy 405.858724 -4.681436) (xy 405.899936 -4.645724) (xy 405.945811 -4.61624) (xy 405.995415 -4.593584)
			(xy 406.047738 -4.578219) (xy 406.101716 -4.570456) (xy 406.128982 -4.569968) (xy 406.992582 -4.569968)
			(xy 407.019856 -4.57037) (xy 407.073849 -4.578131) (xy 407.126188 -4.593497) (xy 407.175807 -4.616155)
			(xy 407.221697 -4.645645) (xy 407.262922 -4.681365) (xy 407.298644 -4.722589) (xy 407.328136 -4.768477)
			(xy 407.350797 -4.818095) (xy 407.366165 -4.870433) (xy 407.373928 -4.924426) (xy 407.373928 -4.978971)
			(xy 414.857632 -4.978971) (xy 414.857632 -4.924429) (xy 414.865394 -4.870442) (xy 414.880762 -4.81811)
			(xy 414.903421 -4.768498) (xy 414.93291 -4.722616) (xy 414.96863 -4.681397) (xy 415.009852 -4.645683)
			(xy 415.055738 -4.616199) (xy 415.105353 -4.593546) (xy 415.157687 -4.578184) (xy 415.211675 -4.570428)
			(xy 415.238946 -4.569968) (xy 416.102546 -4.569968) (xy 416.129815 -4.570398) (xy 416.183798 -4.578165)
			(xy 416.236126 -4.593536) (xy 416.285735 -4.616196) (xy 416.331613 -4.645686) (xy 416.372829 -4.681404)
			(xy 416.408542 -4.722624) (xy 416.438026 -4.768506) (xy 416.46068 -4.818117) (xy 416.476045 -4.870447)
			(xy 416.483806 -4.924431) (xy 416.483806 -4.978967) (xy 418.457654 -4.978967) (xy 418.457654 -4.924433)
			(xy 418.465415 -4.870455) (xy 418.480779 -4.818131) (xy 418.503432 -4.768525) (xy 418.532915 -4.722648)
			(xy 418.568626 -4.681434) (xy 418.609839 -4.645722) (xy 418.655715 -4.616238) (xy 418.705319 -4.593583)
			(xy 418.757643 -4.578218) (xy 418.811621 -4.570455) (xy 418.838888 -4.569968) (xy 419.702488 -4.569968)
			(xy 419.729762 -4.570371) (xy 419.783754 -4.578132) (xy 419.836092 -4.593499) (xy 419.885711 -4.616157)
			(xy 419.9316 -4.645647) (xy 419.972824 -4.681367) (xy 420.008546 -4.722591) (xy 420.038037 -4.768479)
			(xy 420.060697 -4.818096) (xy 420.076065 -4.870434) (xy 420.083828 -4.924426) (xy 420.083828 -4.978966)
			(xy 426.067754 -4.978966) (xy 426.067754 -4.924434) (xy 426.075515 -4.870456) (xy 426.090878 -4.818132)
			(xy 426.113531 -4.768527) (xy 426.143013 -4.72265) (xy 426.178724 -4.681436) (xy 426.219936 -4.645724)
			(xy 426.265811 -4.61624) (xy 426.315415 -4.593584) (xy 426.367738 -4.578219) (xy 426.421716 -4.570456)
			(xy 426.448982 -4.569968) (xy 427.312582 -4.569968) (xy 427.339856 -4.57037) (xy 427.393849 -4.578131)
			(xy 427.446188 -4.593497) (xy 427.495807 -4.616155) (xy 427.541697 -4.645645) (xy 427.582922 -4.681365)
			(xy 427.618644 -4.722589) (xy 427.648136 -4.768477) (xy 427.670797 -4.818095) (xy 427.686165 -4.870433)
			(xy 427.693928 -4.924426) (xy 427.693928 -4.97897) (xy 429.667631 -4.97897) (xy 429.667631 -4.92443)
			(xy 429.675394 -4.870445) (xy 429.69076 -4.818115) (xy 429.713417 -4.768504) (xy 429.742905 -4.722623)
			(xy 429.778622 -4.681405) (xy 429.819842 -4.645691) (xy 429.865725 -4.616206) (xy 429.915337 -4.593552)
			(xy 429.967669 -4.578189) (xy 430.021654 -4.57043) (xy 430.048924 -4.569968) (xy 430.912524 -4.569968)
			(xy 430.939794 -4.570396) (xy 430.99378 -4.578161) (xy 431.04611 -4.59353) (xy 431.095721 -4.616189)
			(xy 431.141603 -4.645678) (xy 431.182821 -4.681396) (xy 431.218536 -4.722616) (xy 431.248022 -4.7685)
			(xy 431.270679 -4.818112) (xy 431.286044 -4.870444) (xy 431.293806 -4.92443) (xy 431.293806 -4.97897)
			(xy 431.286044 -5.032956) (xy 431.270679 -5.085288) (xy 431.248022 -5.1349) (xy 431.218536 -5.180784)
			(xy 431.182821 -5.222004) (xy 431.141603 -5.257722) (xy 431.095721 -5.287211) (xy 431.04611 -5.30987)
			(xy 430.99378 -5.325239) (xy 430.939794 -5.333004) (xy 430.912524 -5.333492) (xy 430.048924 -5.333492)
			(xy 430.021654 -5.33297) (xy 429.967669 -5.325211) (xy 429.915337 -5.309848) (xy 429.865725 -5.287194)
			(xy 429.819842 -5.257709) (xy 429.778622 -5.221995) (xy 429.742905 -5.180777) (xy 429.713417 -5.134896)
			(xy 429.69076 -5.085285) (xy 429.675394 -5.032955) (xy 429.667631 -4.97897) (xy 427.693928 -4.97897)
			(xy 427.693928 -4.978974) (xy 427.686165 -5.032967) (xy 427.670797 -5.085305) (xy 427.648136 -5.134923)
			(xy 427.618644 -5.180811) (xy 427.582922 -5.222035) (xy 427.541697 -5.257755) (xy 427.495807 -5.287245)
			(xy 427.446188 -5.309903) (xy 427.393849 -5.325269) (xy 427.339856 -5.33303) (xy 427.312582 -5.333492)
			(xy 426.448982 -5.333492) (xy 426.421716 -5.332944) (xy 426.367738 -5.325181) (xy 426.315415 -5.309816)
			(xy 426.265811 -5.28716) (xy 426.219936 -5.257676) (xy 426.178724 -5.221964) (xy 426.143013 -5.18075)
			(xy 426.113531 -5.134873) (xy 426.090878 -5.085268) (xy 426.075515 -5.032944) (xy 426.067754 -4.978966)
			(xy 420.083828 -4.978966) (xy 420.083828 -4.978974) (xy 420.076065 -5.032966) (xy 420.060697 -5.085304)
			(xy 420.038037 -5.134921) (xy 420.008546 -5.180809) (xy 419.972824 -5.222033) (xy 419.9316 -5.257753)
			(xy 419.885711 -5.287243) (xy 419.836092 -5.309901) (xy 419.783754 -5.325268) (xy 419.729762 -5.333029)
			(xy 419.702488 -5.333492) (xy 418.838888 -5.333492) (xy 418.811621 -5.332945) (xy 418.757643 -5.325182)
			(xy 418.705319 -5.309817) (xy 418.655715 -5.287162) (xy 418.609839 -5.257678) (xy 418.568626 -5.221966)
			(xy 418.532915 -5.180752) (xy 418.503432 -5.134875) (xy 418.480779 -5.085269) (xy 418.465415 -5.032945)
			(xy 418.457654 -4.978967) (xy 416.483806 -4.978967) (xy 416.483806 -4.978969) (xy 416.476045 -5.032953)
			(xy 416.46068 -5.085283) (xy 416.438026 -5.134894) (xy 416.408542 -5.180776) (xy 416.372829 -5.221996)
			(xy 416.331613 -5.257714) (xy 416.285735 -5.287204) (xy 416.236126 -5.309864) (xy 416.183798 -5.325235)
			(xy 416.129815 -5.333002) (xy 416.102546 -5.333492) (xy 415.238946 -5.333492) (xy 415.211675 -5.332972)
			(xy 415.157687 -5.325216) (xy 415.105353 -5.309854) (xy 415.055738 -5.287201) (xy 415.009852 -5.257717)
			(xy 414.96863 -5.222003) (xy 414.93291 -5.180784) (xy 414.903421 -5.134902) (xy 414.880762 -5.08529)
			(xy 414.865394 -5.032958) (xy 414.857632 -4.978971) (xy 407.373928 -4.978971) (xy 407.373928 -4.978974)
			(xy 407.366165 -5.032967) (xy 407.350797 -5.085305) (xy 407.328136 -5.134923) (xy 407.298644 -5.180811)
			(xy 407.262922 -5.222035) (xy 407.221697 -5.257755) (xy 407.175807 -5.287245) (xy 407.126188 -5.309903)
			(xy 407.073849 -5.325269) (xy 407.019856 -5.33303) (xy 406.992582 -5.333492) (xy 406.128982 -5.333492)
			(xy 406.101716 -5.332944) (xy 406.047738 -5.325181) (xy 405.995415 -5.309816) (xy 405.945811 -5.28716)
			(xy 405.899936 -5.257676) (xy 405.858724 -5.221964) (xy 405.823013 -5.18075) (xy 405.793531 -5.134873)
			(xy 405.770878 -5.085268) (xy 405.755515 -5.032944) (xy 405.747754 -4.978966) (xy 403.773728 -4.978966)
			(xy 403.773728 -4.978974) (xy 403.765965 -5.032966) (xy 403.750597 -5.085304) (xy 403.727937 -5.134922)
			(xy 403.698445 -5.18081) (xy 403.662724 -5.222034) (xy 403.621499 -5.257754) (xy 403.57561 -5.287243)
			(xy 403.525991 -5.309902) (xy 403.473652 -5.325268) (xy 403.41966 -5.333029) (xy 403.392386 -5.333492)
			(xy 402.528786 -5.333492) (xy 402.501519 -5.332945) (xy 402.447542 -5.325182) (xy 402.395218 -5.309817)
			(xy 402.345613 -5.287161) (xy 402.299738 -5.257678) (xy 402.258525 -5.221965) (xy 402.222814 -5.180751)
			(xy 402.193332 -5.134874) (xy 402.170678 -5.085269) (xy 402.155315 -5.032945) (xy 402.147554 -4.978967)
			(xy 400.173706 -4.978967) (xy 400.173706 -4.97897) (xy 400.165944 -5.032953) (xy 400.15058 -5.085284)
			(xy 400.127925 -5.134895) (xy 400.098441 -5.180777) (xy 400.062728 -5.221997) (xy 400.021512 -5.257715)
			(xy 399.975633 -5.287204) (xy 399.926025 -5.309865) (xy 399.873697 -5.325235) (xy 399.819713 -5.333002)
			(xy 399.792444 -5.333492) (xy 398.928844 -5.333492) (xy 398.901573 -5.332972) (xy 398.847586 -5.325215)
			(xy 398.795252 -5.309854) (xy 398.745637 -5.287201) (xy 398.699751 -5.257716) (xy 398.658529 -5.222002)
			(xy 398.62281 -5.180784) (xy 398.593321 -5.134902) (xy 398.570661 -5.085289) (xy 398.555294 -5.032957)
			(xy 398.547532 -4.978971) (xy 396.573806 -4.978971) (xy 396.566043 -5.032959) (xy 396.550677 -5.085293)
			(xy 396.528019 -5.134907) (xy 396.498531 -5.180791) (xy 396.462813 -5.222012) (xy 396.421593 -5.25773)
			(xy 396.375708 -5.287218) (xy 396.326094 -5.309876) (xy 396.273761 -5.325243) (xy 396.219773 -5.333005)
			(xy 396.192502 -5.333492) (xy 395.328902 -5.333492) (xy 395.301633 -5.332969) (xy 395.24765 -5.325207)
			(xy 395.195321 -5.309843) (xy 395.145712 -5.287187) (xy 395.099832 -5.257702) (xy 395.058614 -5.221987)
			(xy 395.0229 -5.18077) (xy 394.993414 -5.13489) (xy 394.970758 -5.08528) (xy 394.955393 -5.032952)
			(xy 394.947631 -4.978969) (xy 390.763638 -4.978969) (xy 390.774561 -5.038281) (xy 390.782563 -5.125916)
			(xy 390.783064 -5.169916) (xy 390.782563 -5.213916) (xy 390.774561 -5.301551) (xy 390.758623 -5.388095)
			(xy 390.734881 -5.472831) (xy 390.703532 -5.555057) (xy 390.664835 -5.634092) (xy 390.619112 -5.70928)
			(xy 390.566741 -5.779999) (xy 390.508157 -5.845663) (xy 390.443843 -5.905728) (xy 390.374335 -5.959695)
			(xy 390.300207 -6.007117) (xy 390.222073 -6.047603) (xy 390.140582 -6.080816) (xy 390.056408 -6.10648)
			(xy 389.970249 -6.124384) (xy 389.882819 -6.134379) (xy 389.794842 -6.136383) (xy 389.707048 -6.130377)
			(xy 389.620164 -6.116413) (xy 389.534909 -6.094606) (xy 389.45199 -6.065137) (xy 389.372095 -6.02825)
			(xy 389.295886 -5.98425) (xy 389.223993 -5.933502) (xy 389.157012 -5.876428) (xy 389.0955 -5.813498)
			(xy 389.039964 -5.745236) (xy 388.990866 -5.672207) (xy 388.948613 -5.595015) (xy 388.913554 -5.514301)
			(xy 388.885979 -5.430733) (xy 388.866119 -5.345004) (xy 388.854136 -5.257824) (xy 388.850131 -5.169916)
			(xy 388.110984 -5.169916) (xy 388.110984 -6.169914) (xy 453.015103 -6.169914) (xy 453.019108 -6.082006)
			(xy 453.031091 -5.994826) (xy 453.050951 -5.909097) (xy 453.078526 -5.825529) (xy 453.113585 -5.744815)
			(xy 453.155838 -5.667623) (xy 453.204936 -5.594594) (xy 453.260472 -5.526332) (xy 453.321984 -5.463402)
			(xy 453.388965 -5.406328) (xy 453.460858 -5.35558) (xy 453.537067 -5.31158) (xy 453.616962 -5.274693)
			(xy 453.699881 -5.245224) (xy 453.785136 -5.223417) (xy 453.87202 -5.209453) (xy 453.959814 -5.203447)
			(xy 454.047791 -5.205451) (xy 454.135221 -5.215446) (xy 454.22138 -5.23335) (xy 454.305554 -5.259014)
			(xy 454.387045 -5.292227) (xy 454.465179 -5.332713) (xy 454.539307 -5.380135) (xy 454.608815 -5.434102)
			(xy 454.673129 -5.494167) (xy 454.731713 -5.559831) (xy 454.784084 -5.63055) (xy 454.829807 -5.705738)
			(xy 454.868504 -5.784773) (xy 454.899853 -5.866999) (xy 454.923595 -5.951735) (xy 454.939533 -6.038279)
			(xy 454.947535 -6.125914) (xy 454.948036 -6.169914) (xy 454.947535 -6.213914) (xy 454.939533 -6.301549)
			(xy 454.923595 -6.388093) (xy 454.899853 -6.472829) (xy 454.868504 -6.555055) (xy 454.829807 -6.63409)
			(xy 454.784084 -6.709278) (xy 454.731713 -6.779997) (xy 454.673129 -6.845661) (xy 454.608815 -6.905726)
			(xy 454.539307 -6.959693) (xy 454.465179 -7.007115) (xy 454.387045 -7.047601) (xy 454.305554 -7.080814)
			(xy 454.22138 -7.106478) (xy 454.135221 -7.124382) (xy 454.047791 -7.134377) (xy 453.959814 -7.136381)
			(xy 453.87202 -7.130375) (xy 453.785136 -7.116411) (xy 453.699881 -7.094604) (xy 453.616962 -7.065135)
			(xy 453.537067 -7.028248) (xy 453.460858 -6.984248) (xy 453.388965 -6.9335) (xy 453.321984 -6.876426)
			(xy 453.260472 -6.813496) (xy 453.204936 -6.745234) (xy 453.155838 -6.672205) (xy 453.113585 -6.595013)
			(xy 453.078526 -6.514299) (xy 453.050951 -6.430731) (xy 453.031091 -6.345002) (xy 453.019108 -6.257822)
			(xy 453.015103 -6.169914) (xy 388.110984 -6.169914) (xy 388.110984 -6.740774) (xy 393.142876 -6.740774)
			(xy 393.142876 -6.686226) (xy 393.150639 -6.632232) (xy 393.166008 -6.579894) (xy 393.18867 -6.530275)
			(xy 393.218162 -6.484387) (xy 393.253885 -6.443163) (xy 393.295112 -6.407443) (xy 393.341003 -6.377954)
			(xy 393.390624 -6.355297) (xy 393.442964 -6.339932) (xy 393.496958 -6.332173) (xy 393.524232 -6.331712)
			(xy 394.387832 -6.331712) (xy 394.415098 -6.332253) (xy 394.469074 -6.340017) (xy 394.521397 -6.355384)
			(xy 394.570999 -6.378041) (xy 394.616873 -6.407526) (xy 394.658084 -6.443238) (xy 394.693794 -6.484452)
			(xy 394.723274 -6.530329) (xy 394.745927 -6.579933) (xy 394.761289 -6.632257) (xy 394.76905 -6.686234)
			(xy 394.76905 -6.740766) (xy 394.769049 -6.74077) (xy 396.742898 -6.74077) (xy 396.742898 -6.68623)
			(xy 396.75066 -6.632245) (xy 396.766025 -6.579914) (xy 396.788681 -6.530302) (xy 396.818166 -6.484419)
			(xy 396.853881 -6.4432) (xy 396.895099 -6.407482) (xy 396.940979 -6.377993) (xy 396.99059 -6.355334)
			(xy 397.04292 -6.339965) (xy 397.096904 -6.3322) (xy 397.124174 -6.331712) (xy 397.987774 -6.331712)
			(xy 398.015044 -6.332226) (xy 398.06903 -6.339984) (xy 398.121363 -6.355347) (xy 398.170976 -6.378002)
			(xy 398.216859 -6.407487) (xy 398.25808 -6.443202) (xy 398.293798 -6.48442) (xy 398.323286 -6.530301)
			(xy 398.345944 -6.579913) (xy 398.36131 -6.632244) (xy 398.369072 -6.68623) (xy 398.369072 -6.74077)
			(xy 398.369071 -6.740774) (xy 400.342776 -6.740774) (xy 400.342776 -6.686226) (xy 400.350539 -6.632234)
			(xy 400.365907 -6.579897) (xy 400.388567 -6.530279) (xy 400.418058 -6.484392) (xy 400.45378 -6.443168)
			(xy 400.495005 -6.407449) (xy 400.540893 -6.377959) (xy 400.590512 -6.355301) (xy 400.64285 -6.339935)
			(xy 400.696842 -6.332174) (xy 400.724116 -6.331712) (xy 401.587716 -6.331712) (xy 401.614983 -6.332251)
			(xy 401.668961 -6.340014) (xy 401.721285 -6.35538) (xy 401.77089 -6.378036) (xy 401.816766 -6.40752)
			(xy 401.857978 -6.443233) (xy 401.89369 -6.484447) (xy 401.923172 -6.530324) (xy 401.945825 -6.57993)
			(xy 401.961189 -6.632255) (xy 401.96895 -6.686233) (xy 401.96895 -6.740767) (xy 401.968949 -6.740773)
			(xy 403.942976 -6.740773) (xy 403.942976 -6.686227) (xy 403.950739 -6.632235) (xy 403.966106 -6.579898)
			(xy 403.988766 -6.53028) (xy 404.018257 -6.484393) (xy 404.053978 -6.44317) (xy 404.095203 -6.40745)
			(xy 404.141091 -6.377961) (xy 404.190709 -6.355302) (xy 404.243047 -6.339936) (xy 404.297039 -6.332175)
			(xy 404.324312 -6.331712) (xy 405.187912 -6.331712) (xy 405.215179 -6.332251) (xy 405.269158 -6.340014)
			(xy 405.321482 -6.355379) (xy 405.371087 -6.378034) (xy 405.416964 -6.407519) (xy 405.458177 -6.443231)
			(xy 405.493889 -6.484446) (xy 405.523371 -6.530323) (xy 405.546025 -6.579929) (xy 405.561389 -6.632254)
			(xy 405.56915 -6.686233) (xy 405.56915 -6.740767) (xy 405.56915 -6.74077) (xy 413.052998 -6.74077)
			(xy 413.052998 -6.68623) (xy 413.06076 -6.632245) (xy 413.076125 -6.579914) (xy 413.098781 -6.530302)
			(xy 413.128267 -6.484419) (xy 413.163982 -6.443199) (xy 413.205199 -6.407481) (xy 413.25108 -6.377993)
			(xy 413.300691 -6.355334) (xy 413.353021 -6.339965) (xy 413.407006 -6.3322) (xy 413.434276 -6.331712)
			(xy 414.297876 -6.331712) (xy 414.325146 -6.332226) (xy 414.379132 -6.339985) (xy 414.431464 -6.355348)
			(xy 414.481077 -6.378002) (xy 414.52696 -6.407487) (xy 414.568181 -6.443202) (xy 414.603898 -6.48442)
			(xy 414.633386 -6.530302) (xy 414.656044 -6.579913) (xy 414.67141 -6.632244) (xy 414.679173 -6.68623)
			(xy 414.679173 -6.74077) (xy 414.679172 -6.740774) (xy 416.652876 -6.740774) (xy 416.652876 -6.686226)
			(xy 416.660639 -6.632234) (xy 416.676007 -6.579897) (xy 416.698667 -6.530279) (xy 416.728159 -6.484391)
			(xy 416.763881 -6.443168) (xy 416.805106 -6.407448) (xy 416.850995 -6.377959) (xy 416.900613 -6.355301)
			(xy 416.952952 -6.339935) (xy 417.006944 -6.332174) (xy 417.034218 -6.331712) (xy 417.897818 -6.331712)
			(xy 417.925085 -6.332252) (xy 417.979063 -6.340015) (xy 418.031386 -6.355381) (xy 418.080991 -6.378036)
			(xy 418.126867 -6.407521) (xy 418.168079 -6.443234) (xy 418.20379 -6.484448) (xy 418.233272 -6.530325)
			(xy 418.255926 -6.57993) (xy 418.271289 -6.632255) (xy 418.27905 -6.686233) (xy 418.27905 -6.740767)
			(xy 418.279049 -6.740773) (xy 424.262976 -6.740773) (xy 424.262976 -6.686227) (xy 424.270739 -6.632235)
			(xy 424.286106 -6.579898) (xy 424.308766 -6.53028) (xy 424.338257 -6.484393) (xy 424.373978 -6.44317)
			(xy 424.415203 -6.40745) (xy 424.461091 -6.377961) (xy 424.510709 -6.355302) (xy 424.563047 -6.339936)
			(xy 424.617039 -6.332175) (xy 424.644312 -6.331712) (xy 425.507912 -6.331712) (xy 425.535179 -6.332251)
			(xy 425.589158 -6.340014) (xy 425.641482 -6.355379) (xy 425.691087 -6.378034) (xy 425.736964 -6.407519)
			(xy 425.778177 -6.443231) (xy 425.813889 -6.484446) (xy 425.843371 -6.530323) (xy 425.866025 -6.579929)
			(xy 425.881389 -6.632254) (xy 425.88915 -6.686233) (xy 425.88915 -6.740767) (xy 425.88915 -6.740769)
			(xy 427.862998 -6.740769) (xy 427.862998 -6.686231) (xy 427.870759 -6.632248) (xy 427.886123 -6.579918)
			(xy 427.908778 -6.530308) (xy 427.938261 -6.484426) (xy 427.973974 -6.443207) (xy 428.015189 -6.407489)
			(xy 428.061067 -6.378) (xy 428.110675 -6.35534) (xy 428.163003 -6.339969) (xy 428.216985 -6.332202)
			(xy 428.244254 -6.331712) (xy 429.107854 -6.331712) (xy 429.135125 -6.332224) (xy 429.189113 -6.339981)
			(xy 429.241448 -6.355342) (xy 429.291064 -6.377995) (xy 429.33695 -6.40748) (xy 429.378173 -6.443195)
			(xy 429.413893 -6.484413) (xy 429.443383 -6.530296) (xy 429.466042 -6.579909) (xy 429.48141 -6.632242)
			(xy 429.489172 -6.686229) (xy 429.489172 -6.740771) (xy 429.488151 -6.747873) (xy 431.473788 -6.747873)
			(xy 431.473788 -6.693327) (xy 431.48155 -6.639337) (xy 431.496918 -6.587001) (xy 431.519578 -6.537385)
			(xy 431.549068 -6.491498) (xy 431.584789 -6.450276) (xy 431.626013 -6.414558) (xy 431.6719 -6.385069)
			(xy 431.721518 -6.362412) (xy 431.773854 -6.347047) (xy 431.827845 -6.339286) (xy 431.855118 -6.338824)
			(xy 432.718718 -6.338824) (xy 432.745986 -6.33934) (xy 432.799965 -6.347103) (xy 432.852291 -6.362469)
			(xy 432.901897 -6.385126) (xy 432.947774 -6.414611) (xy 432.988988 -6.450325) (xy 433.0247 -6.491541)
			(xy 433.054183 -6.537419) (xy 433.076837 -6.587026) (xy 433.092201 -6.639352) (xy 433.099962 -6.693332)
			(xy 433.099962 -6.740771) (xy 445.457798 -6.740771) (xy 445.457798 -6.686229) (xy 445.46556 -6.632243)
			(xy 445.480926 -6.579911) (xy 445.503583 -6.530298) (xy 445.53307 -6.484415) (xy 445.568786 -6.443195)
			(xy 445.610005 -6.407477) (xy 445.655888 -6.377989) (xy 445.7055 -6.35533) (xy 445.757831 -6.339963)
			(xy 445.811817 -6.332199) (xy 445.839088 -6.331712) (xy 446.702688 -6.331712) (xy 446.729958 -6.332227)
			(xy 446.783942 -6.339987) (xy 446.836273 -6.355351) (xy 446.885884 -6.378006) (xy 446.931766 -6.407492)
			(xy 446.972985 -6.443207) (xy 447.008701 -6.484424) (xy 447.038188 -6.530305) (xy 447.060845 -6.579916)
			(xy 447.076211 -6.632246) (xy 447.083973 -6.68623) (xy 447.083973 -6.74077) (xy 447.076211 -6.794754)
			(xy 447.060845 -6.847084) (xy 447.038188 -6.896695) (xy 447.008701 -6.942576) (xy 446.972985 -6.983793)
			(xy 446.931766 -7.019508) (xy 446.885884 -7.048994) (xy 446.836273 -7.071649) (xy 446.783942 -7.087013)
			(xy 446.729958 -7.094773) (xy 446.702688 -7.095236) (xy 445.839088 -7.095236) (xy 445.811817 -7.094801)
			(xy 445.757831 -7.087037) (xy 445.7055 -7.07167) (xy 445.655888 -7.049011) (xy 445.610005 -7.019523)
			(xy 445.568786 -6.983805) (xy 445.53307 -6.942585) (xy 445.503583 -6.896702) (xy 445.480926 -6.847089)
			(xy 445.46556 -6.794757) (xy 445.457798 -6.740771) (xy 433.099962 -6.740771) (xy 433.099962 -6.747868)
			(xy 433.092201 -6.801848) (xy 433.076837 -6.854174) (xy 433.054183 -6.903781) (xy 433.0247 -6.949659)
			(xy 432.988988 -6.990875) (xy 432.947774 -7.026589) (xy 432.901897 -7.056074) (xy 432.852291 -7.078731)
			(xy 432.799965 -7.094097) (xy 432.745986 -7.10186) (xy 432.718718 -7.102348) (xy 431.855118 -7.102348)
			(xy 431.827845 -7.101914) (xy 431.773854 -7.094153) (xy 431.721518 -7.078788) (xy 431.6719 -7.056131)
			(xy 431.626013 -7.026642) (xy 431.584789 -6.990924) (xy 431.549068 -6.949702) (xy 431.519578 -6.903815)
			(xy 431.496918 -6.854199) (xy 431.48155 -6.801863) (xy 431.473788 -6.747873) (xy 429.488151 -6.747873)
			(xy 429.48141 -6.794758) (xy 429.466042 -6.847091) (xy 429.443383 -6.896704) (xy 429.413893 -6.942587)
			(xy 429.378173 -6.983805) (xy 429.33695 -7.01952) (xy 429.291064 -7.049005) (xy 429.241448 -7.071658)
			(xy 429.189113 -7.087019) (xy 429.135125 -7.094776) (xy 429.107854 -7.095236) (xy 428.244254 -7.095236)
			(xy 428.216985 -7.094798) (xy 428.163003 -7.087031) (xy 428.110675 -7.07166) (xy 428.061067 -7.049)
			(xy 428.015189 -7.019511) (xy 427.973974 -6.983793) (xy 427.938261 -6.942574) (xy 427.908778 -6.896692)
			(xy 427.886123 -6.847082) (xy 427.870759 -6.794752) (xy 427.862998 -6.740769) (xy 425.88915 -6.740769)
			(xy 425.881389 -6.794746) (xy 425.866025 -6.847071) (xy 425.843371 -6.896677) (xy 425.813889 -6.942554)
			(xy 425.778177 -6.983769) (xy 425.736964 -7.019481) (xy 425.691087 -7.048966) (xy 425.641482 -7.071621)
			(xy 425.589158 -7.086986) (xy 425.535179 -7.094749) (xy 425.507912 -7.095236) (xy 424.644312 -7.095236)
			(xy 424.617039 -7.094825) (xy 424.563047 -7.087064) (xy 424.510709 -7.071698) (xy 424.461091 -7.049039)
			(xy 424.415203 -7.01955) (xy 424.373978 -6.98383) (xy 424.338257 -6.942607) (xy 424.308766 -6.89672)
			(xy 424.286106 -6.847102) (xy 424.270739 -6.794765) (xy 424.262976 -6.740773) (xy 418.279049 -6.740773)
			(xy 418.271289 -6.794745) (xy 418.255926 -6.84707) (xy 418.233272 -6.896675) (xy 418.20379 -6.942552)
			(xy 418.168079 -6.983766) (xy 418.126867 -7.019479) (xy 418.080991 -7.048964) (xy 418.031386 -7.071619)
			(xy 417.979063 -7.086985) (xy 417.925085 -7.094748) (xy 417.897818 -7.095236) (xy 417.034218 -7.095236)
			(xy 417.006944 -7.094826) (xy 416.952952 -7.087065) (xy 416.900613 -7.071699) (xy 416.850995 -7.049041)
			(xy 416.805106 -7.019552) (xy 416.763881 -6.983832) (xy 416.728159 -6.942609) (xy 416.698667 -6.896721)
			(xy 416.676007 -6.847103) (xy 416.660639 -6.794766) (xy 416.652876 -6.740774) (xy 414.679172 -6.740774)
			(xy 414.67141 -6.794756) (xy 414.656044 -6.847087) (xy 414.633386 -6.896698) (xy 414.603898 -6.94258)
			(xy 414.568181 -6.983798) (xy 414.52696 -7.019513) (xy 414.481077 -7.048998) (xy 414.431464 -7.071652)
			(xy 414.379132 -7.087015) (xy 414.325146 -7.094774) (xy 414.297876 -7.095236) (xy 413.434276 -7.095236)
			(xy 413.407006 -7.0948) (xy 413.353021 -7.087035) (xy 413.300691 -7.071666) (xy 413.25108 -7.049007)
			(xy 413.205199 -7.019519) (xy 413.163982 -6.983801) (xy 413.128267 -6.942581) (xy 413.098781 -6.896698)
			(xy 413.076125 -6.847086) (xy 413.06076 -6.794755) (xy 413.052998 -6.74077) (xy 405.56915 -6.74077)
			(xy 405.561389 -6.794746) (xy 405.546025 -6.847071) (xy 405.523371 -6.896677) (xy 405.493889 -6.942554)
			(xy 405.458177 -6.983769) (xy 405.416964 -7.019481) (xy 405.371087 -7.048966) (xy 405.321482 -7.071621)
			(xy 405.269158 -7.086986) (xy 405.215179 -7.094749) (xy 405.187912 -7.095236) (xy 404.324312 -7.095236)
			(xy 404.297039 -7.094825) (xy 404.243047 -7.087064) (xy 404.190709 -7.071698) (xy 404.141091 -7.049039)
			(xy 404.095203 -7.01955) (xy 404.053978 -6.98383) (xy 404.018257 -6.942607) (xy 403.988766 -6.89672)
			(xy 403.966106 -6.847102) (xy 403.950739 -6.794765) (xy 403.942976 -6.740773) (xy 401.968949 -6.740773)
			(xy 401.961189 -6.794745) (xy 401.945825 -6.84707) (xy 401.923172 -6.896676) (xy 401.89369 -6.942553)
			(xy 401.857978 -6.983767) (xy 401.816766 -7.01948) (xy 401.77089 -7.048964) (xy 401.721285 -7.07162)
			(xy 401.668961 -7.086986) (xy 401.614983 -7.094749) (xy 401.587716 -7.095236) (xy 400.724116 -7.095236)
			(xy 400.696842 -7.094826) (xy 400.64285 -7.087065) (xy 400.590512 -7.071699) (xy 400.540893 -7.049041)
			(xy 400.495005 -7.019551) (xy 400.45378 -6.983832) (xy 400.418058 -6.942608) (xy 400.388567 -6.896721)
			(xy 400.365907 -6.847103) (xy 400.350539 -6.794766) (xy 400.342776 -6.740774) (xy 398.369071 -6.740774)
			(xy 398.36131 -6.794756) (xy 398.345944 -6.847087) (xy 398.323286 -6.896699) (xy 398.293798 -6.94258)
			(xy 398.25808 -6.983798) (xy 398.216859 -7.019513) (xy 398.170976 -7.048998) (xy 398.121363 -7.071653)
			(xy 398.06903 -7.087016) (xy 398.015044 -7.094774) (xy 397.987774 -7.095236) (xy 397.124174 -7.095236)
			(xy 397.096904 -7.0948) (xy 397.04292 -7.087035) (xy 396.99059 -7.071666) (xy 396.940979 -7.049007)
			(xy 396.895099 -7.019518) (xy 396.853881 -6.9838) (xy 396.818166 -6.942581) (xy 396.788681 -6.896698)
			(xy 396.766025 -6.847086) (xy 396.75066 -6.794755) (xy 396.742898 -6.74077) (xy 394.769049 -6.74077)
			(xy 394.761289 -6.794743) (xy 394.745927 -6.847067) (xy 394.723274 -6.896671) (xy 394.693794 -6.942548)
			(xy 394.658084 -6.983762) (xy 394.616873 -7.019474) (xy 394.570999 -7.048959) (xy 394.521397 -7.071616)
			(xy 394.469074 -7.086983) (xy 394.415098 -7.094747) (xy 394.387832 -7.095236) (xy 393.524232 -7.095236)
			(xy 393.496958 -7.094827) (xy 393.442964 -7.087068) (xy 393.390624 -7.071703) (xy 393.341003 -7.049046)
			(xy 393.295112 -7.019557) (xy 393.253885 -6.983837) (xy 393.218162 -6.942613) (xy 393.18867 -6.896725)
			(xy 393.166008 -6.847106) (xy 393.150639 -6.794768) (xy 393.142876 -6.740774) (xy 388.110984 -6.740774)
			(xy 388.110984 -9.780016) (xy 388.110499 -9.850398) (xy 388.102605 -9.99094) (xy 388.086844 -10.130819)
			(xy 388.063264 -10.269594) (xy 388.03194 -10.406828) (xy 387.992971 -10.54209) (xy 387.946478 -10.674954)
			(xy 387.892609 -10.805003) (xy 387.831533 -10.931826) (xy 387.763442 -11.055026) (xy 387.68855 -11.174213)
			(xy 387.607093 -11.289014) (xy 387.519328 -11.399067) (xy 387.425529 -11.504025) (xy 387.325993 -11.60356)
			(xy 387.221033 -11.697356) (xy 387.110979 -11.78512) (xy 386.996176 -11.866575) (xy 386.876988 -11.941465)
			(xy 386.753787 -12.009554) (xy 386.626963 -12.070627) (xy 386.496913 -12.124494) (xy 386.364048 -12.170984)
			(xy 386.228785 -12.209951) (xy 386.091551 -12.241273) (xy 385.952775 -12.26485) (xy 385.812896 -12.280609)
			(xy 385.672354 -12.2885) (xy 385.601972 -12.289028) (xy 260.800088 -12.289028) (xy 260.744319 -12.28955)
			(xy 260.633094 -12.297886) (xy 260.522803 -12.314511) (xy 260.414062 -12.339331) (xy 260.30748 -12.372208)
			(xy 260.203654 -12.412958) (xy 260.103162 -12.461353) (xy 260.006569 -12.517122) (xy 259.914413 -12.579954)
			(xy 259.82721 -12.649497) (xy 259.745448 -12.725362) (xy 259.669584 -12.807125) (xy 259.601847 -12.892065)
			(xy 431.46197 -12.892065) (xy 431.46197 -12.837535) (xy 431.46973 -12.783559) (xy 431.485093 -12.731238)
			(xy 431.507745 -12.681635) (xy 431.537225 -12.635761) (xy 431.572934 -12.594548) (xy 431.614145 -12.558837)
			(xy 431.660017 -12.529355) (xy 431.709619 -12.5067) (xy 431.76194 -12.491335) (xy 431.815915 -12.483572)
			(xy 431.84318 -12.483084) (xy 432.70678 -12.483084) (xy 432.734055 -12.483454) (xy 432.788051 -12.491215)
			(xy 432.840392 -12.506581) (xy 432.890014 -12.529241) (xy 432.935905 -12.558731) (xy 432.977133 -12.594453)
			(xy 433.012857 -12.635678) (xy 433.04235 -12.681569) (xy 433.065012 -12.731189) (xy 433.080381 -12.78353)
			(xy 433.088144 -12.837525) (xy 433.088144 -12.864846) (xy 445.45631 -12.864846) (xy 445.45631 -12.864592)
			(xy 445.456564 -12.850622) (xy 445.45717 -12.823469) (xy 445.46523 -12.769758) (xy 445.48082 -12.717731)
			(xy 445.503625 -12.668439) (xy 445.533186 -12.622876) (xy 445.568905 -12.581962) (xy 445.610062 -12.546522)
			(xy 445.655826 -12.517273) (xy 445.705273 -12.494804) (xy 445.757405 -12.47957) (xy 445.81117 -12.471876)
			(xy 445.838326 -12.4714) (xy 446.701926 -12.4714) (xy 446.72908 -12.471883) (xy 446.782838 -12.479582)
			(xy 446.834964 -12.494821) (xy 446.884404 -12.517293) (xy 446.93016 -12.546543) (xy 446.971311 -12.581982)
			(xy 447.007024 -12.622895) (xy 447.03658 -12.668455) (xy 447.059381 -12.717744) (xy 447.074968 -12.769766)
			(xy 447.083027 -12.823472) (xy 447.083688 -12.850622) (xy 447.083942 -12.864592) (xy 447.083942 -12.864846)
			(xy 447.083472 -12.892133) (xy 447.0757 -12.946152) (xy 447.06032 -12.998515) (xy 447.037645 -13.048157)
			(xy 447.008137 -13.094067) (xy 446.972397 -13.135311) (xy 446.931151 -13.171049) (xy 446.885239 -13.200555)
			(xy 446.835597 -13.223227) (xy 446.783233 -13.238604) (xy 446.729214 -13.246374) (xy 446.701926 -13.246862)
			(xy 446.679426 -13.246581) (xy 446.634732 -13.241355) (xy 446.612772 -13.236448) (xy 446.60693 -13.234924)
			(xy 445.933322 -13.234924) (xy 445.92748 -13.236448) (xy 445.905519 -13.241348) (xy 445.860825 -13.246566)
			(xy 445.838326 -13.246862) (xy 445.811041 -13.246305) (xy 445.757027 -13.238543) (xy 445.704666 -13.223173)
			(xy 445.655026 -13.200508) (xy 445.609117 -13.17101) (xy 445.567873 -13.135278) (xy 445.532133 -13.094041)
			(xy 445.502626 -13.048137) (xy 445.479952 -12.998501) (xy 445.464572 -12.946144) (xy 445.4568 -12.892131)
			(xy 445.45631 -12.864846) (xy 433.088144 -12.864846) (xy 433.088144 -12.892075) (xy 433.080381 -12.94607)
			(xy 433.065012 -12.998411) (xy 433.04235 -13.048031) (xy 433.012857 -13.093921) (xy 432.977133 -13.135147)
			(xy 432.935905 -13.170869) (xy 432.890014 -13.200359) (xy 432.840392 -13.223019) (xy 432.788051 -13.238385)
			(xy 432.734055 -13.246146) (xy 432.70678 -13.246608) (xy 431.84318 -13.246608) (xy 431.815915 -13.246028)
			(xy 431.76194 -13.238265) (xy 431.709619 -13.2229) (xy 431.660017 -13.200245) (xy 431.614145 -13.170763)
			(xy 431.572934 -13.135052) (xy 431.537225 -13.093839) (xy 431.507745 -13.047965) (xy 431.485093 -12.998362)
			(xy 431.46973 -12.946041) (xy 431.46197 -12.892065) (xy 259.601847 -12.892065) (xy 259.600042 -12.894329)
			(xy 259.537211 -12.986486) (xy 259.481443 -13.08308) (xy 259.43305 -13.183572) (xy 259.392301 -13.287399)
			(xy 259.359426 -13.393981) (xy 259.334607 -13.502722) (xy 259.317984 -13.613014) (xy 259.309649 -13.724239)
			(xy 259.309108 -13.780008) (xy 259.309108 -17.628666) (xy 389.660162 -17.628666) (xy 389.660162 -17.574134)
			(xy 389.667923 -17.520157) (xy 389.683286 -17.467834) (xy 389.705939 -17.41823) (xy 389.73542 -17.372354)
			(xy 389.77113 -17.331141) (xy 389.812342 -17.29543) (xy 389.858216 -17.265946) (xy 389.907819 -17.243291)
			(xy 389.960142 -17.227926) (xy 390.014118 -17.220163) (xy 390.041384 -17.219676) (xy 390.904984 -17.219676)
			(xy 390.932258 -17.220062) (xy 390.986252 -17.227824) (xy 391.038592 -17.24319) (xy 391.088212 -17.265849)
			(xy 391.134103 -17.295339) (xy 391.175329 -17.33106) (xy 391.211051 -17.372285) (xy 391.240543 -17.418174)
			(xy 391.263204 -17.467793) (xy 391.278573 -17.520132) (xy 391.286336 -17.574126) (xy 391.286336 -17.628666)
			(xy 395.248162 -17.628666) (xy 395.248162 -17.574134) (xy 395.255923 -17.520157) (xy 395.271286 -17.467834)
			(xy 395.293939 -17.41823) (xy 395.32342 -17.372354) (xy 395.35913 -17.331141) (xy 395.400342 -17.29543)
			(xy 395.446216 -17.265946) (xy 395.495819 -17.243291) (xy 395.548142 -17.227926) (xy 395.602118 -17.220163)
			(xy 395.629384 -17.219676) (xy 396.492984 -17.219676) (xy 396.520258 -17.220062) (xy 396.574252 -17.227824)
			(xy 396.626592 -17.24319) (xy 396.676212 -17.265849) (xy 396.722103 -17.295339) (xy 396.763329 -17.33106)
			(xy 396.799051 -17.372285) (xy 396.828543 -17.418174) (xy 396.851204 -17.467793) (xy 396.866573 -17.520132)
			(xy 396.874336 -17.574126) (xy 396.874336 -17.628666) (xy 400.836162 -17.628666) (xy 400.836162 -17.574134)
			(xy 400.843923 -17.520157) (xy 400.859286 -17.467834) (xy 400.881939 -17.41823) (xy 400.91142 -17.372354)
			(xy 400.94713 -17.331141) (xy 400.988342 -17.29543) (xy 401.034216 -17.265946) (xy 401.083819 -17.243291)
			(xy 401.136142 -17.227926) (xy 401.190118 -17.220163) (xy 401.217384 -17.219676) (xy 402.080984 -17.219676)
			(xy 402.108258 -17.220062) (xy 402.162252 -17.227824) (xy 402.214592 -17.24319) (xy 402.264212 -17.265849)
			(xy 402.310103 -17.295339) (xy 402.351329 -17.33106) (xy 402.387051 -17.372285) (xy 402.416543 -17.418174)
			(xy 402.439204 -17.467793) (xy 402.454573 -17.520132) (xy 402.462336 -17.574126) (xy 402.462336 -17.628666)
			(xy 406.424162 -17.628666) (xy 406.424162 -17.574134) (xy 406.431923 -17.520157) (xy 406.447286 -17.467834)
			(xy 406.469939 -17.41823) (xy 406.49942 -17.372354) (xy 406.53513 -17.331141) (xy 406.576342 -17.29543)
			(xy 406.622216 -17.265946) (xy 406.671819 -17.243291) (xy 406.724142 -17.227926) (xy 406.778118 -17.220163)
			(xy 406.805384 -17.219676) (xy 407.668984 -17.219676) (xy 407.696258 -17.220062) (xy 407.750252 -17.227824)
			(xy 407.802592 -17.24319) (xy 407.852212 -17.265849) (xy 407.898103 -17.295339) (xy 407.939329 -17.33106)
			(xy 407.975051 -17.372285) (xy 408.004543 -17.418174) (xy 408.027204 -17.467793) (xy 408.042573 -17.520132)
			(xy 408.050336 -17.574126) (xy 408.050336 -17.628666) (xy 412.012162 -17.628666) (xy 412.012162 -17.574134)
			(xy 412.019923 -17.520157) (xy 412.035286 -17.467834) (xy 412.057939 -17.41823) (xy 412.08742 -17.372354)
			(xy 412.12313 -17.331141) (xy 412.164342 -17.29543) (xy 412.210216 -17.265946) (xy 412.259819 -17.243291)
			(xy 412.312142 -17.227926) (xy 412.366118 -17.220163) (xy 412.393384 -17.219676) (xy 413.256984 -17.219676)
			(xy 413.284258 -17.220062) (xy 413.338252 -17.227824) (xy 413.390592 -17.24319) (xy 413.440212 -17.265849)
			(xy 413.486103 -17.295339) (xy 413.527329 -17.33106) (xy 413.563051 -17.372285) (xy 413.592543 -17.418174)
			(xy 413.615204 -17.467793) (xy 413.630573 -17.520132) (xy 413.638336 -17.574126) (xy 413.638336 -17.628667)
			(xy 417.905962 -17.628667) (xy 417.905962 -17.574133) (xy 417.913723 -17.520155) (xy 417.929087 -17.467831)
			(xy 417.951741 -17.418226) (xy 417.981224 -17.372349) (xy 418.016936 -17.331136) (xy 418.058149 -17.295424)
			(xy 418.104026 -17.265941) (xy 418.153631 -17.243287) (xy 418.205955 -17.227923) (xy 418.259933 -17.220162)
			(xy 418.2872 -17.219676) (xy 419.1508 -17.219676) (xy 419.178072 -17.220087) (xy 419.232061 -17.227849)
			(xy 419.284396 -17.243216) (xy 419.334011 -17.265874) (xy 419.379896 -17.295363) (xy 419.421118 -17.331082)
			(xy 419.456837 -17.372304) (xy 419.486326 -17.418189) (xy 419.508984 -17.467804) (xy 419.524351 -17.520139)
			(xy 419.532113 -17.574128) (xy 419.532113 -17.628667) (xy 423.493962 -17.628667) (xy 423.493962 -17.574133)
			(xy 423.501723 -17.520155) (xy 423.517087 -17.467831) (xy 423.539741 -17.418226) (xy 423.569224 -17.372349)
			(xy 423.604936 -17.331136) (xy 423.646149 -17.295424) (xy 423.692026 -17.265941) (xy 423.741631 -17.243287)
			(xy 423.793955 -17.227923) (xy 423.847933 -17.220162) (xy 423.8752 -17.219676) (xy 424.7388 -17.219676)
			(xy 424.766072 -17.220087) (xy 424.820061 -17.227849) (xy 424.872396 -17.243216) (xy 424.922011 -17.265874)
			(xy 424.967896 -17.295363) (xy 425.009118 -17.331082) (xy 425.044837 -17.372304) (xy 425.074326 -17.418189)
			(xy 425.096984 -17.467804) (xy 425.112351 -17.520139) (xy 425.120113 -17.574128) (xy 425.120113 -17.62867)
			(xy 429.11594 -17.62867) (xy 429.11594 -17.57413) (xy 429.123702 -17.520145) (xy 429.139068 -17.467815)
			(xy 429.161726 -17.418204) (xy 429.191214 -17.372324) (xy 429.226932 -17.331107) (xy 429.268152 -17.295393)
			(xy 429.314036 -17.265909) (xy 429.363649 -17.243256) (xy 429.415981 -17.227894) (xy 429.469966 -17.220137)
			(xy 429.497236 -17.219676) (xy 430.360836 -17.219676) (xy 430.388106 -17.220089) (xy 430.442091 -17.227856)
			(xy 430.494422 -17.243226) (xy 430.544032 -17.265886) (xy 430.589913 -17.295376) (xy 430.631131 -17.331095)
			(xy 430.666846 -17.372315) (xy 430.696331 -17.418199) (xy 430.718987 -17.467812) (xy 430.734352 -17.520144)
			(xy 430.742114 -17.57413) (xy 430.742114 -17.62867) (xy 430.734352 -17.682656) (xy 430.718987 -17.734988)
			(xy 430.696331 -17.784601) (xy 430.666846 -17.830485) (xy 430.631131 -17.871705) (xy 430.589913 -17.907424)
			(xy 430.544032 -17.936914) (xy 430.494422 -17.959574) (xy 430.442091 -17.974944) (xy 430.388106 -17.982711)
			(xy 430.360836 -17.9832) (xy 429.497236 -17.9832) (xy 429.469966 -17.982663) (xy 429.415981 -17.974906)
			(xy 429.363649 -17.959544) (xy 429.314036 -17.936891) (xy 429.268152 -17.907407) (xy 429.226932 -17.871693)
			(xy 429.191214 -17.830476) (xy 429.161726 -17.784596) (xy 429.139068 -17.734985) (xy 429.123702 -17.682655)
			(xy 429.11594 -17.62867) (xy 425.120113 -17.62867) (xy 425.120113 -17.628672) (xy 425.112351 -17.682661)
			(xy 425.096984 -17.734996) (xy 425.074326 -17.784611) (xy 425.044837 -17.830496) (xy 425.009118 -17.871718)
			(xy 424.967896 -17.907437) (xy 424.922011 -17.936926) (xy 424.872396 -17.959584) (xy 424.820061 -17.974951)
			(xy 424.766072 -17.982713) (xy 424.7388 -17.9832) (xy 423.8752 -17.9832) (xy 423.847933 -17.982638)
			(xy 423.793955 -17.974877) (xy 423.741631 -17.959513) (xy 423.692026 -17.936859) (xy 423.646149 -17.907376)
			(xy 423.604936 -17.871664) (xy 423.569224 -17.830451) (xy 423.539741 -17.784574) (xy 423.517087 -17.734969)
			(xy 423.501723 -17.682645) (xy 423.493962 -17.628667) (xy 419.532113 -17.628667) (xy 419.532113 -17.628672)
			(xy 419.524351 -17.682661) (xy 419.508984 -17.734996) (xy 419.486326 -17.784611) (xy 419.456837 -17.830496)
			(xy 419.421118 -17.871718) (xy 419.379896 -17.907437) (xy 419.334011 -17.936926) (xy 419.284396 -17.959584)
			(xy 419.232061 -17.974951) (xy 419.178072 -17.982713) (xy 419.1508 -17.9832) (xy 418.2872 -17.9832)
			(xy 418.259933 -17.982638) (xy 418.205955 -17.974877) (xy 418.153631 -17.959513) (xy 418.104026 -17.936859)
			(xy 418.058149 -17.907376) (xy 418.016936 -17.871664) (xy 417.981224 -17.830451) (xy 417.951741 -17.784574)
			(xy 417.929087 -17.734969) (xy 417.913723 -17.682645) (xy 417.905962 -17.628667) (xy 413.638336 -17.628667)
			(xy 413.638336 -17.628674) (xy 413.630573 -17.682668) (xy 413.615204 -17.735007) (xy 413.592543 -17.784626)
			(xy 413.563051 -17.830515) (xy 413.527329 -17.87174) (xy 413.486103 -17.907461) (xy 413.440212 -17.936951)
			(xy 413.390592 -17.95961) (xy 413.338252 -17.974976) (xy 413.284258 -17.982738) (xy 413.256984 -17.9832)
			(xy 412.393384 -17.9832) (xy 412.366118 -17.982637) (xy 412.312142 -17.974874) (xy 412.259819 -17.959509)
			(xy 412.210216 -17.936854) (xy 412.164342 -17.90737) (xy 412.12313 -17.871659) (xy 412.08742 -17.830446)
			(xy 412.057939 -17.78457) (xy 412.035286 -17.734966) (xy 412.019923 -17.682643) (xy 412.012162 -17.628666)
			(xy 408.050336 -17.628666) (xy 408.050336 -17.628674) (xy 408.042573 -17.682668) (xy 408.027204 -17.735007)
			(xy 408.004543 -17.784626) (xy 407.975051 -17.830515) (xy 407.939329 -17.87174) (xy 407.898103 -17.907461)
			(xy 407.852212 -17.936951) (xy 407.802592 -17.95961) (xy 407.750252 -17.974976) (xy 407.696258 -17.982738)
			(xy 407.668984 -17.9832) (xy 406.805384 -17.9832) (xy 406.778118 -17.982637) (xy 406.724142 -17.974874)
			(xy 406.671819 -17.959509) (xy 406.622216 -17.936854) (xy 406.576342 -17.90737) (xy 406.53513 -17.871659)
			(xy 406.49942 -17.830446) (xy 406.469939 -17.78457) (xy 406.447286 -17.734966) (xy 406.431923 -17.682643)
			(xy 406.424162 -17.628666) (xy 402.462336 -17.628666) (xy 402.462336 -17.628674) (xy 402.454573 -17.682668)
			(xy 402.439204 -17.735007) (xy 402.416543 -17.784626) (xy 402.387051 -17.830515) (xy 402.351329 -17.87174)
			(xy 402.310103 -17.907461) (xy 402.264212 -17.936951) (xy 402.214592 -17.95961) (xy 402.162252 -17.974976)
			(xy 402.108258 -17.982738) (xy 402.080984 -17.9832) (xy 401.217384 -17.9832) (xy 401.190118 -17.982637)
			(xy 401.136142 -17.974874) (xy 401.083819 -17.959509) (xy 401.034216 -17.936854) (xy 400.988342 -17.90737)
			(xy 400.94713 -17.871659) (xy 400.91142 -17.830446) (xy 400.881939 -17.78457) (xy 400.859286 -17.734966)
			(xy 400.843923 -17.682643) (xy 400.836162 -17.628666) (xy 396.874336 -17.628666) (xy 396.874336 -17.628674)
			(xy 396.866573 -17.682668) (xy 396.851204 -17.735007) (xy 396.828543 -17.784626) (xy 396.799051 -17.830515)
			(xy 396.763329 -17.87174) (xy 396.722103 -17.907461) (xy 396.676212 -17.936951) (xy 396.626592 -17.95961)
			(xy 396.574252 -17.974976) (xy 396.520258 -17.982738) (xy 396.492984 -17.9832) (xy 395.629384 -17.9832)
			(xy 395.602118 -17.982637) (xy 395.548142 -17.974874) (xy 395.495819 -17.959509) (xy 395.446216 -17.936854)
			(xy 395.400342 -17.90737) (xy 395.35913 -17.871659) (xy 395.32342 -17.830446) (xy 395.293939 -17.78457)
			(xy 395.271286 -17.734966) (xy 395.255923 -17.682643) (xy 395.248162 -17.628666) (xy 391.286336 -17.628666)
			(xy 391.286336 -17.628674) (xy 391.278573 -17.682668) (xy 391.263204 -17.735007) (xy 391.240543 -17.784626)
			(xy 391.211051 -17.830515) (xy 391.175329 -17.87174) (xy 391.134103 -17.907461) (xy 391.088212 -17.936951)
			(xy 391.038592 -17.95961) (xy 390.986252 -17.974976) (xy 390.932258 -17.982738) (xy 390.904984 -17.9832)
			(xy 390.041384 -17.9832) (xy 390.014118 -17.982637) (xy 389.960142 -17.974874) (xy 389.907819 -17.959509)
			(xy 389.858216 -17.936854) (xy 389.812342 -17.90737) (xy 389.77113 -17.871659) (xy 389.73542 -17.830446)
			(xy 389.705939 -17.78457) (xy 389.683286 -17.734966) (xy 389.667923 -17.682643) (xy 389.660162 -17.628666)
			(xy 259.309108 -17.628666) (xy 259.309108 -19.152666) (xy 392.454162 -19.152666) (xy 392.454162 -19.098134)
			(xy 392.461923 -19.044157) (xy 392.477286 -18.991834) (xy 392.499939 -18.94223) (xy 392.52942 -18.896354)
			(xy 392.56513 -18.855141) (xy 392.606342 -18.81943) (xy 392.652216 -18.789946) (xy 392.701819 -18.767291)
			(xy 392.754142 -18.751926) (xy 392.808118 -18.744163) (xy 392.835384 -18.743676) (xy 393.698984 -18.743676)
			(xy 393.726258 -18.744062) (xy 393.780252 -18.751824) (xy 393.832592 -18.76719) (xy 393.882212 -18.789849)
			(xy 393.928103 -18.819339) (xy 393.969329 -18.85506) (xy 394.005051 -18.896285) (xy 394.034543 -18.942174)
			(xy 394.057204 -18.991793) (xy 394.072573 -19.044132) (xy 394.080336 -19.098126) (xy 394.080336 -19.152666)
			(xy 398.042162 -19.152666) (xy 398.042162 -19.098134) (xy 398.049923 -19.044157) (xy 398.065286 -18.991834)
			(xy 398.087939 -18.94223) (xy 398.11742 -18.896354) (xy 398.15313 -18.855141) (xy 398.194342 -18.81943)
			(xy 398.240216 -18.789946) (xy 398.289819 -18.767291) (xy 398.342142 -18.751926) (xy 398.396118 -18.744163)
			(xy 398.423384 -18.743676) (xy 399.286984 -18.743676) (xy 399.314258 -18.744062) (xy 399.368252 -18.751824)
			(xy 399.420592 -18.76719) (xy 399.470212 -18.789849) (xy 399.516103 -18.819339) (xy 399.557329 -18.85506)
			(xy 399.593051 -18.896285) (xy 399.622543 -18.942174) (xy 399.645204 -18.991793) (xy 399.660573 -19.044132)
			(xy 399.668336 -19.098126) (xy 399.668336 -19.152666) (xy 403.630162 -19.152666) (xy 403.630162 -19.098134)
			(xy 403.637923 -19.044157) (xy 403.653286 -18.991834) (xy 403.675939 -18.94223) (xy 403.70542 -18.896354)
			(xy 403.74113 -18.855141) (xy 403.782342 -18.81943) (xy 403.828216 -18.789946) (xy 403.877819 -18.767291)
			(xy 403.930142 -18.751926) (xy 403.984118 -18.744163) (xy 404.011384 -18.743676) (xy 404.874984 -18.743676)
			(xy 404.902258 -18.744062) (xy 404.956252 -18.751824) (xy 405.008592 -18.76719) (xy 405.058212 -18.789849)
			(xy 405.104103 -18.819339) (xy 405.145329 -18.85506) (xy 405.181051 -18.896285) (xy 405.210543 -18.942174)
			(xy 405.233204 -18.991793) (xy 405.248573 -19.044132) (xy 405.256336 -19.098126) (xy 405.256336 -19.152666)
			(xy 409.218162 -19.152666) (xy 409.218162 -19.098134) (xy 409.225923 -19.044157) (xy 409.241286 -18.991834)
			(xy 409.263939 -18.94223) (xy 409.29342 -18.896354) (xy 409.32913 -18.855141) (xy 409.370342 -18.81943)
			(xy 409.416216 -18.789946) (xy 409.465819 -18.767291) (xy 409.518142 -18.751926) (xy 409.572118 -18.744163)
			(xy 409.599384 -18.743676) (xy 410.462984 -18.743676) (xy 410.490258 -18.744062) (xy 410.544252 -18.751824)
			(xy 410.596592 -18.76719) (xy 410.646212 -18.789849) (xy 410.692103 -18.819339) (xy 410.733329 -18.85506)
			(xy 410.769051 -18.896285) (xy 410.798543 -18.942174) (xy 410.821204 -18.991793) (xy 410.836573 -19.044132)
			(xy 410.844336 -19.098126) (xy 410.844336 -19.152667) (xy 415.111962 -19.152667) (xy 415.111962 -19.098133)
			(xy 415.119723 -19.044155) (xy 415.135087 -18.991831) (xy 415.157741 -18.942226) (xy 415.187224 -18.896349)
			(xy 415.222936 -18.855136) (xy 415.264149 -18.819424) (xy 415.310026 -18.789941) (xy 415.359631 -18.767287)
			(xy 415.411955 -18.751923) (xy 415.465933 -18.744162) (xy 415.4932 -18.743676) (xy 416.3568 -18.743676)
			(xy 416.384072 -18.744087) (xy 416.438061 -18.751849) (xy 416.490396 -18.767216) (xy 416.540011 -18.789874)
			(xy 416.585896 -18.819363) (xy 416.627118 -18.855082) (xy 416.662837 -18.896304) (xy 416.692326 -18.942189)
			(xy 416.714984 -18.991804) (xy 416.730351 -19.044139) (xy 416.738113 -19.098128) (xy 416.738113 -19.152667)
			(xy 420.699962 -19.152667) (xy 420.699962 -19.098133) (xy 420.707723 -19.044155) (xy 420.723087 -18.991831)
			(xy 420.745741 -18.942226) (xy 420.775224 -18.896349) (xy 420.810936 -18.855136) (xy 420.852149 -18.819424)
			(xy 420.898026 -18.789941) (xy 420.947631 -18.767287) (xy 420.999955 -18.751923) (xy 421.053933 -18.744162)
			(xy 421.0812 -18.743676) (xy 421.9448 -18.743676) (xy 421.972072 -18.744087) (xy 422.026061 -18.751849)
			(xy 422.078396 -18.767216) (xy 422.128011 -18.789874) (xy 422.173896 -18.819363) (xy 422.215118 -18.855082)
			(xy 422.250837 -18.896304) (xy 422.280326 -18.942189) (xy 422.302984 -18.991804) (xy 422.318351 -19.044139)
			(xy 422.326113 -19.098128) (xy 422.326113 -19.15267) (xy 426.32194 -19.15267) (xy 426.32194 -19.09813)
			(xy 426.329702 -19.044145) (xy 426.345068 -18.991815) (xy 426.367726 -18.942204) (xy 426.397214 -18.896324)
			(xy 426.432932 -18.855107) (xy 426.474152 -18.819393) (xy 426.520036 -18.789909) (xy 426.569649 -18.767256)
			(xy 426.621981 -18.751894) (xy 426.675966 -18.744137) (xy 426.703236 -18.743676) (xy 427.566836 -18.743676)
			(xy 427.594106 -18.744089) (xy 427.648091 -18.751856) (xy 427.700422 -18.767226) (xy 427.750032 -18.789886)
			(xy 427.795913 -18.819376) (xy 427.837131 -18.855095) (xy 427.872846 -18.896315) (xy 427.902331 -18.942199)
			(xy 427.924987 -18.991812) (xy 427.940352 -19.044144) (xy 427.948114 -19.09813) (xy 427.948114 -19.15267)
			(xy 431.90994 -19.15267) (xy 431.90994 -19.09813) (xy 431.917702 -19.044145) (xy 431.933068 -18.991815)
			(xy 431.955726 -18.942204) (xy 431.985214 -18.896324) (xy 432.020932 -18.855107) (xy 432.062152 -18.819393)
			(xy 432.108036 -18.789909) (xy 432.157649 -18.767256) (xy 432.209981 -18.751894) (xy 432.263966 -18.744137)
			(xy 432.291236 -18.743676) (xy 433.154836 -18.743676) (xy 433.182106 -18.744089) (xy 433.236091 -18.751856)
			(xy 433.288422 -18.767226) (xy 433.338032 -18.789886) (xy 433.383913 -18.819376) (xy 433.425131 -18.855095)
			(xy 433.460846 -18.896315) (xy 433.490331 -18.942199) (xy 433.512987 -18.991812) (xy 433.528352 -19.044144)
			(xy 433.536114 -19.09813) (xy 433.536114 -19.15267) (xy 433.528352 -19.206656) (xy 433.512987 -19.258988)
			(xy 433.490331 -19.308601) (xy 433.460846 -19.354485) (xy 433.425131 -19.395705) (xy 433.383913 -19.431424)
			(xy 433.338032 -19.460914) (xy 433.288422 -19.483574) (xy 433.236091 -19.498944) (xy 433.182106 -19.506711)
			(xy 433.154836 -19.5072) (xy 432.291236 -19.5072) (xy 432.263966 -19.506663) (xy 432.209981 -19.498906)
			(xy 432.157649 -19.483544) (xy 432.108036 -19.460891) (xy 432.062152 -19.431407) (xy 432.020932 -19.395693)
			(xy 431.985214 -19.354476) (xy 431.955726 -19.308596) (xy 431.933068 -19.258985) (xy 431.917702 -19.206655)
			(xy 431.90994 -19.15267) (xy 427.948114 -19.15267) (xy 427.940352 -19.206656) (xy 427.924987 -19.258988)
			(xy 427.902331 -19.308601) (xy 427.872846 -19.354485) (xy 427.837131 -19.395705) (xy 427.795913 -19.431424)
			(xy 427.750032 -19.460914) (xy 427.700422 -19.483574) (xy 427.648091 -19.498944) (xy 427.594106 -19.506711)
			(xy 427.566836 -19.5072) (xy 426.703236 -19.5072) (xy 426.675966 -19.506663) (xy 426.621981 -19.498906)
			(xy 426.569649 -19.483544) (xy 426.520036 -19.460891) (xy 426.474152 -19.431407) (xy 426.432932 -19.395693)
			(xy 426.397214 -19.354476) (xy 426.367726 -19.308596) (xy 426.345068 -19.258985) (xy 426.329702 -19.206655)
			(xy 426.32194 -19.15267) (xy 422.326113 -19.15267) (xy 422.326113 -19.152672) (xy 422.318351 -19.206661)
			(xy 422.302984 -19.258996) (xy 422.280326 -19.308611) (xy 422.250837 -19.354496) (xy 422.215118 -19.395718)
			(xy 422.173896 -19.431437) (xy 422.128011 -19.460926) (xy 422.078396 -19.483584) (xy 422.026061 -19.498951)
			(xy 421.972072 -19.506713) (xy 421.9448 -19.5072) (xy 421.0812 -19.5072) (xy 421.053933 -19.506638)
			(xy 420.999955 -19.498877) (xy 420.947631 -19.483513) (xy 420.898026 -19.460859) (xy 420.852149 -19.431376)
			(xy 420.810936 -19.395664) (xy 420.775224 -19.354451) (xy 420.745741 -19.308574) (xy 420.723087 -19.258969)
			(xy 420.707723 -19.206645) (xy 420.699962 -19.152667) (xy 416.738113 -19.152667) (xy 416.738113 -19.152672)
			(xy 416.730351 -19.206661) (xy 416.714984 -19.258996) (xy 416.692326 -19.308611) (xy 416.662837 -19.354496)
			(xy 416.627118 -19.395718) (xy 416.585896 -19.431437) (xy 416.540011 -19.460926) (xy 416.490396 -19.483584)
			(xy 416.438061 -19.498951) (xy 416.384072 -19.506713) (xy 416.3568 -19.5072) (xy 415.4932 -19.5072)
			(xy 415.465933 -19.506638) (xy 415.411955 -19.498877) (xy 415.359631 -19.483513) (xy 415.310026 -19.460859)
			(xy 415.264149 -19.431376) (xy 415.222936 -19.395664) (xy 415.187224 -19.354451) (xy 415.157741 -19.308574)
			(xy 415.135087 -19.258969) (xy 415.119723 -19.206645) (xy 415.111962 -19.152667) (xy 410.844336 -19.152667)
			(xy 410.844336 -19.152674) (xy 410.836573 -19.206668) (xy 410.821204 -19.259007) (xy 410.798543 -19.308626)
			(xy 410.769051 -19.354515) (xy 410.733329 -19.39574) (xy 410.692103 -19.431461) (xy 410.646212 -19.460951)
			(xy 410.596592 -19.48361) (xy 410.544252 -19.498976) (xy 410.490258 -19.506738) (xy 410.462984 -19.5072)
			(xy 409.599384 -19.5072) (xy 409.572118 -19.506637) (xy 409.518142 -19.498874) (xy 409.465819 -19.483509)
			(xy 409.416216 -19.460854) (xy 409.370342 -19.43137) (xy 409.32913 -19.395659) (xy 409.29342 -19.354446)
			(xy 409.263939 -19.30857) (xy 409.241286 -19.258966) (xy 409.225923 -19.206643) (xy 409.218162 -19.152666)
			(xy 405.256336 -19.152666) (xy 405.256336 -19.152674) (xy 405.248573 -19.206668) (xy 405.233204 -19.259007)
			(xy 405.210543 -19.308626) (xy 405.181051 -19.354515) (xy 405.145329 -19.39574) (xy 405.104103 -19.431461)
			(xy 405.058212 -19.460951) (xy 405.008592 -19.48361) (xy 404.956252 -19.498976) (xy 404.902258 -19.506738)
			(xy 404.874984 -19.5072) (xy 404.011384 -19.5072) (xy 403.984118 -19.506637) (xy 403.930142 -19.498874)
			(xy 403.877819 -19.483509) (xy 403.828216 -19.460854) (xy 403.782342 -19.43137) (xy 403.74113 -19.395659)
			(xy 403.70542 -19.354446) (xy 403.675939 -19.30857) (xy 403.653286 -19.258966) (xy 403.637923 -19.206643)
			(xy 403.630162 -19.152666) (xy 399.668336 -19.152666) (xy 399.668336 -19.152674) (xy 399.660573 -19.206668)
			(xy 399.645204 -19.259007) (xy 399.622543 -19.308626) (xy 399.593051 -19.354515) (xy 399.557329 -19.39574)
			(xy 399.516103 -19.431461) (xy 399.470212 -19.460951) (xy 399.420592 -19.48361) (xy 399.368252 -19.498976)
			(xy 399.314258 -19.506738) (xy 399.286984 -19.5072) (xy 398.423384 -19.5072) (xy 398.396118 -19.506637)
			(xy 398.342142 -19.498874) (xy 398.289819 -19.483509) (xy 398.240216 -19.460854) (xy 398.194342 -19.43137)
			(xy 398.15313 -19.395659) (xy 398.11742 -19.354446) (xy 398.087939 -19.30857) (xy 398.065286 -19.258966)
			(xy 398.049923 -19.206643) (xy 398.042162 -19.152666) (xy 394.080336 -19.152666) (xy 394.080336 -19.152674)
			(xy 394.072573 -19.206668) (xy 394.057204 -19.259007) (xy 394.034543 -19.308626) (xy 394.005051 -19.354515)
			(xy 393.969329 -19.39574) (xy 393.928103 -19.431461) (xy 393.882212 -19.460951) (xy 393.832592 -19.48361)
			(xy 393.780252 -19.498976) (xy 393.726258 -19.506738) (xy 393.698984 -19.5072) (xy 392.835384 -19.5072)
			(xy 392.808118 -19.506637) (xy 392.754142 -19.498874) (xy 392.701819 -19.483509) (xy 392.652216 -19.460854)
			(xy 392.606342 -19.43137) (xy 392.56513 -19.395659) (xy 392.52942 -19.354446) (xy 392.499939 -19.30857)
			(xy 392.477286 -19.258966) (xy 392.461923 -19.206643) (xy 392.454162 -19.152666) (xy 259.309108 -19.152666)
			(xy 259.309108 -25.468351) (xy 388.406603 -25.468351) (xy 388.406603 -25.413849) (xy 388.41436 -25.359901)
			(xy 388.429716 -25.307607) (xy 388.452359 -25.25803) (xy 388.481827 -25.212181) (xy 388.517521 -25.170992)
			(xy 388.558713 -25.135303) (xy 388.604565 -25.10584) (xy 388.654144 -25.083202) (xy 388.70644 -25.067852)
			(xy 388.760389 -25.0601) (xy 388.78764 -25.05964) (xy 389.65124 -25.05964) (xy 389.678493 -25.060033)
			(xy 389.732443 -25.067795) (xy 389.78474 -25.083155) (xy 389.834318 -25.105802) (xy 389.880169 -25.135273)
			(xy 389.92136 -25.170969) (xy 389.957051 -25.212163) (xy 389.986518 -25.258017) (xy 390.009159 -25.307598)
			(xy 390.024514 -25.359896) (xy 390.03227 -25.413847) (xy 390.03227 -25.468353) (xy 390.024514 -25.522304)
			(xy 390.009159 -25.574602) (xy 389.986518 -25.624183) (xy 389.957051 -25.670037) (xy 389.92136 -25.711231)
			(xy 389.880169 -25.746927) (xy 389.834318 -25.776398) (xy 389.78474 -25.799045) (xy 389.732443 -25.814405)
			(xy 389.678493 -25.822167) (xy 389.65124 -25.822656) (xy 388.78764 -25.822656) (xy 388.760389 -25.8221)
			(xy 388.70644 -25.814348) (xy 388.654144 -25.798998) (xy 388.604565 -25.77636) (xy 388.558713 -25.746897)
			(xy 388.517521 -25.711208) (xy 388.481827 -25.670019) (xy 388.452359 -25.62417) (xy 388.429716 -25.574593)
			(xy 388.41436 -25.522299) (xy 388.406603 -25.468351) (xy 259.309108 -25.468351) (xy 259.309108 -28.450032)
			(xy 354.840804 -28.450032) (xy 354.844787 -28.322014) (xy 354.856722 -28.194492) (xy 354.876561 -28.067958)
			(xy 354.904228 -27.942902) (xy 354.939617 -27.819809) (xy 354.98259 -27.699153) (xy 355.032981 -27.581403)
			(xy 355.090595 -27.467013) (xy 355.155209 -27.356426) (xy 355.226573 -27.25007) (xy 355.304411 -27.148357)
			(xy 355.388422 -27.051679) (xy 355.478281 -26.960412) (xy 355.57364 -26.874907) (xy 355.674131 -26.795497)
			(xy 355.779364 -26.722487) (xy 355.888933 -26.656161) (xy 356.002413 -26.596775) (xy 356.119365 -26.544559)
			(xy 356.239338 -26.499715) (xy 356.361866 -26.462417) (xy 356.486477 -26.432808) (xy 356.612686 -26.411003)
			(xy 356.740008 -26.397087) (xy 356.867948 -26.391113) (xy 356.996012 -26.393105) (xy 357.123705 -26.403055)
			(xy 357.250532 -26.420924) (xy 357.376003 -26.446643) (xy 357.499632 -26.480113) (xy 357.620941 -26.521204)
			(xy 357.739461 -26.569758) (xy 357.854733 -26.625586) (xy 357.966311 -26.688472) (xy 358.073764 -26.758174)
			(xy 358.176676 -26.834421) (xy 358.274648 -26.916918) (xy 358.367302 -27.005347) (xy 358.454279 -27.099365)
			(xy 358.535243 -27.198608) (xy 358.60988 -27.302693) (xy 358.677902 -27.411217) (xy 358.739046 -27.52376)
			(xy 358.793074 -27.639886) (xy 358.839779 -27.759147) (xy 358.878979 -27.88108) (xy 358.910522 -28.005215)
			(xy 358.934287 -28.131071) (xy 358.950181 -28.25816) (xy 358.958144 -28.385992) (xy 358.958642 -28.450032)
			(xy 358.958144 -28.514072) (xy 358.950181 -28.641904) (xy 358.934287 -28.768993) (xy 358.910522 -28.894849)
			(xy 358.878979 -29.018984) (xy 358.839779 -29.140917) (xy 358.793074 -29.260178) (xy 358.739046 -29.376304)
			(xy 358.677902 -29.488847) (xy 358.60988 -29.597371) (xy 358.535243 -29.701456) (xy 358.454279 -29.800699)
			(xy 358.367302 -29.894717) (xy 358.274648 -29.983146) (xy 358.176676 -30.065643) (xy 358.073764 -30.14189)
			(xy 357.966311 -30.211592) (xy 357.854733 -30.274478) (xy 357.739461 -30.330306) (xy 357.620941 -30.37886)
			(xy 357.499632 -30.419951) (xy 357.376003 -30.453421) (xy 357.250532 -30.47914) (xy 357.123705 -30.497009)
			(xy 356.996012 -30.506959) (xy 356.867948 -30.508951) (xy 356.740008 -30.502977) (xy 356.612686 -30.489061)
			(xy 356.486477 -30.467256) (xy 356.361866 -30.437647) (xy 356.239338 -30.400349) (xy 356.119365 -30.355505)
			(xy 356.002413 -30.303289) (xy 355.888933 -30.243903) (xy 355.779364 -30.177577) (xy 355.674131 -30.104567)
			(xy 355.57364 -30.025157) (xy 355.478281 -29.939652) (xy 355.388422 -29.848385) (xy 355.304411 -29.751707)
			(xy 355.226573 -29.649994) (xy 355.155209 -29.543638) (xy 355.090595 -29.433051) (xy 355.032981 -29.318661)
			(xy 354.98259 -29.200911) (xy 354.939617 -29.080255) (xy 354.904228 -28.957162) (xy 354.876561 -28.832106)
			(xy 354.856722 -28.705572) (xy 354.844787 -28.57805) (xy 354.840804 -28.450032) (xy 259.309108 -28.450032)
			(xy 259.309108 -33.275016) (xy 259.308614 -33.345398) (xy 259.30072 -33.48594) (xy 259.284959 -33.625819)
			(xy 259.261379 -33.764594) (xy 259.230448 -33.90011) (xy 462.69148 -33.90011) (xy 462.69148 -32.29991)
			(xy 462.691988 -32.23523) (xy 462.700111 -32.106124) (xy 462.716324 -31.977784) (xy 462.740564 -31.850714)
			(xy 462.772734 -31.725418) (xy 462.812709 -31.602388) (xy 462.86033 -31.482112) (xy 462.915409 -31.365063)
			(xy 462.977729 -31.251703) (xy 463.047044 -31.14248) (xy 463.12308 -31.037825) (xy 463.205538 -30.938151)
			(xy 463.294091 -30.843851) (xy 463.388391 -30.755298) (xy 463.488065 -30.67284) (xy 463.59272 -30.596804)
			(xy 463.701943 -30.527489) (xy 463.815303 -30.465169) (xy 463.932352 -30.41009) (xy 464.052628 -30.362469)
			(xy 464.175658 -30.322494) (xy 464.300954 -30.290324) (xy 464.428024 -30.266084) (xy 464.556364 -30.249871)
			(xy 464.68547 -30.241748) (xy 464.81483 -30.241748) (xy 464.943936 -30.249871) (xy 465.072276 -30.266084)
			(xy 465.199346 -30.290324) (xy 465.324642 -30.322494) (xy 465.447672 -30.362469) (xy 465.567948 -30.41009)
			(xy 465.684997 -30.465169) (xy 465.798357 -30.527489) (xy 465.90758 -30.596804) (xy 466.012235 -30.67284)
			(xy 466.111909 -30.755298) (xy 466.206209 -30.843851) (xy 466.294762 -30.938151) (xy 466.37722 -31.037825)
			(xy 466.453256 -31.14248) (xy 466.522571 -31.251703) (xy 466.584891 -31.365063) (xy 466.63997 -31.482112)
			(xy 466.687591 -31.602388) (xy 466.727566 -31.725418) (xy 466.759736 -31.850714) (xy 466.783976 -31.977784)
			(xy 466.800189 -32.106124) (xy 466.808312 -32.23523) (xy 466.80882 -32.29991) (xy 466.80882 -33.90011)
			(xy 466.808312 -33.96479) (xy 466.800189 -34.093896) (xy 466.783976 -34.222236) (xy 466.759736 -34.349306)
			(xy 466.727566 -34.474602) (xy 466.687591 -34.597632) (xy 466.63997 -34.717908) (xy 466.584891 -34.834957)
			(xy 466.522571 -34.948317) (xy 466.453256 -35.05754) (xy 466.37722 -35.162195) (xy 466.294762 -35.261869)
			(xy 466.206209 -35.356169) (xy 466.111909 -35.444722) (xy 466.012235 -35.52718) (xy 465.90758 -35.603216)
			(xy 465.798357 -35.672531) (xy 465.684997 -35.734851) (xy 465.567948 -35.78993) (xy 465.447672 -35.837551)
			(xy 465.324642 -35.877526) (xy 465.199346 -35.909696) (xy 465.072276 -35.933936) (xy 464.943936 -35.950149)
			(xy 464.81483 -35.958272) (xy 464.68547 -35.958272) (xy 464.556364 -35.950149) (xy 464.428024 -35.933936)
			(xy 464.300954 -35.909696) (xy 464.175658 -35.877526) (xy 464.052628 -35.837551) (xy 463.932352 -35.78993)
			(xy 463.815303 -35.734851) (xy 463.701943 -35.672531) (xy 463.59272 -35.603216) (xy 463.488065 -35.52718)
			(xy 463.388391 -35.444722) (xy 463.294091 -35.356169) (xy 463.205538 -35.261869) (xy 463.12308 -35.162195)
			(xy 463.047044 -35.05754) (xy 462.977729 -34.948317) (xy 462.915409 -34.834957) (xy 462.86033 -34.717908)
			(xy 462.812709 -34.597632) (xy 462.772734 -34.474602) (xy 462.740564 -34.349306) (xy 462.716324 -34.222236)
			(xy 462.700111 -34.093896) (xy 462.691988 -33.96479) (xy 462.69148 -33.90011) (xy 259.230448 -33.90011)
			(xy 259.230056 -33.901828) (xy 259.191086 -34.03709) (xy 259.144594 -34.169955) (xy 259.090726 -34.300003)
			(xy 259.02965 -34.426827) (xy 258.961559 -34.550026) (xy 258.886668 -34.669214) (xy 258.805211 -34.784015)
			(xy 258.717446 -34.894068) (xy 258.623648 -34.999027) (xy 258.524113 -35.098562) (xy 258.419153 -35.192359)
			(xy 258.324611 -35.267753) (xy 356.989346 -35.267753) (xy 356.989346 -35.213247) (xy 356.997102 -35.159297)
			(xy 357.012458 -35.106999) (xy 357.035099 -35.057419) (xy 357.064566 -35.011566) (xy 357.100259 -34.970373)
			(xy 357.14145 -34.934678) (xy 357.187302 -34.905209) (xy 357.236881 -34.882565) (xy 357.289177 -34.867207)
			(xy 357.343127 -34.859447) (xy 357.37038 -34.85896) (xy 358.23398 -34.85896) (xy 358.261232 -34.859486)
			(xy 358.31518 -34.86724) (xy 358.367476 -34.882593) (xy 358.417054 -34.905232) (xy 358.462906 -34.934697)
			(xy 358.504098 -34.970388) (xy 358.539791 -35.011578) (xy 358.569258 -35.057428) (xy 358.5919 -35.107005)
			(xy 358.607256 -35.1593) (xy 358.615013 -35.213249) (xy 358.615013 -35.267751) (xy 358.607256 -35.3217)
			(xy 358.5919 -35.373995) (xy 358.569258 -35.423572) (xy 358.539791 -35.469422) (xy 358.504098 -35.510612)
			(xy 358.462906 -35.546303) (xy 358.417054 -35.575768) (xy 358.367476 -35.598407) (xy 358.31518 -35.61376)
			(xy 358.261232 -35.621514) (xy 358.23398 -35.621976) (xy 357.37038 -35.621976) (xy 357.343127 -35.621553)
			(xy 357.289177 -35.613793) (xy 357.236881 -35.598435) (xy 357.187302 -35.575791) (xy 357.14145 -35.546322)
			(xy 357.100259 -35.510627) (xy 357.064566 -35.469434) (xy 357.035099 -35.423581) (xy 357.012458 -35.374001)
			(xy 356.997102 -35.321703) (xy 356.989346 -35.267753) (xy 258.324611 -35.267753) (xy 258.309099 -35.280123)
			(xy 258.194297 -35.361579) (xy 258.075109 -35.436469) (xy 257.951909 -35.504559) (xy 257.825085 -35.565634)
			(xy 257.695036 -35.619502) (xy 257.562171 -35.665993) (xy 257.426909 -35.704961) (xy 257.289674 -35.736283)
			(xy 257.150899 -35.759862) (xy 257.01102 -35.775622) (xy 256.870478 -35.783514) (xy 256.800096 -35.784028)
			(xy 225.300032 -35.784028) (xy 225.229649 -35.783544) (xy 225.089104 -35.775653) (xy 224.949222 -35.759894)
			(xy 224.810444 -35.736316) (xy 224.673207 -35.704995) (xy 224.537941 -35.666027) (xy 224.405074 -35.619536)
			(xy 224.275022 -35.565669) (xy 224.148195 -35.504594) (xy 224.024992 -35.436504) (xy 223.905801 -35.361613)
			(xy 223.790997 -35.280156) (xy 223.68094 -35.192391) (xy 223.575978 -35.098593) (xy 223.47644 -34.999057)
			(xy 223.38264 -34.894096) (xy 223.294872 -34.784042) (xy 223.213414 -34.669239) (xy 223.138521 -34.550049)
			(xy 223.070428 -34.426848) (xy 223.009351 -34.300022) (xy 222.955481 -34.169971) (xy 222.908988 -34.037104)
			(xy 222.870017 -33.90184) (xy 222.838693 -33.764603) (xy 222.815113 -33.625825) (xy 222.799351 -33.485944)
			(xy 222.791457 -33.345399) (xy 222.79102 -33.275016) (xy 222.79102 -13.780008) (xy 222.790499 -13.724238)
			(xy 222.782164 -13.613011) (xy 222.765541 -13.502717) (xy 222.740722 -13.393974) (xy 222.707846 -13.287389)
			(xy 222.667097 -13.183559) (xy 222.618703 -13.083065) (xy 222.562935 -12.986469) (xy 222.500103 -12.894309)
			(xy 222.430561 -12.807103) (xy 222.354696 -12.725338) (xy 222.272933 -12.64947) (xy 222.185729 -12.579925)
			(xy 222.093572 -12.517091) (xy 221.996977 -12.461319) (xy 221.896485 -12.412922) (xy 221.792656 -12.37217)
			(xy 221.686073 -12.339291) (xy 221.57733 -12.314468) (xy 221.467037 -12.297841) (xy 221.35581 -12.289503)
			(xy 221.30004 -12.289028) (xy 196.701918 -12.289028) (xy 196.631535 -12.288544) (xy 196.49099 -12.280652)
			(xy 196.35111 -12.264892) (xy 196.212332 -12.241314) (xy 196.075095 -12.209992) (xy 195.939831 -12.171024)
			(xy 195.806964 -12.124532) (xy 195.676913 -12.070665) (xy 195.550086 -12.009589) (xy 195.426884 -11.941499)
			(xy 195.307694 -11.866608) (xy 195.19289 -11.785152) (xy 195.082834 -11.697386) (xy 194.977873 -11.603588)
			(xy 194.878335 -11.504052) (xy 194.784536 -11.399092) (xy 194.696769 -11.289037) (xy 194.615311 -11.174234)
			(xy 194.540418 -11.055045) (xy 194.472326 -10.931844) (xy 194.411249 -10.805018) (xy 194.35738 -10.674968)
			(xy 194.310887 -10.542102) (xy 194.271917 -10.406837) (xy 194.240593 -10.269601) (xy 194.217013 -10.130824)
			(xy 194.201251 -9.990943) (xy 194.193357 -9.850399) (xy 194.192906 -9.780016) (xy 194.192906 -6.279896)
			(xy 194.19238 -6.247749) (xy 194.183988 -6.184006) (xy 194.167348 -6.121904) (xy 194.142744 -6.062504)
			(xy 194.110598 -6.006824) (xy 194.07146 -5.955816) (xy 194.025999 -5.910353) (xy 193.974992 -5.871213)
			(xy 193.919314 -5.839064) (xy 193.859915 -5.814458) (xy 193.797813 -5.797816) (xy 193.734071 -5.789421)
			(xy 193.701924 -5.788914) (xy 127.102108 -5.788914) (xy 127.06996 -5.789416) (xy 127.006214 -5.797808)
			(xy 126.944108 -5.814448) (xy 126.884706 -5.839052) (xy 126.829023 -5.8712) (xy 126.778013 -5.91034)
			(xy 126.732548 -5.955804) (xy 126.693406 -6.006813) (xy 126.661257 -6.062495) (xy 126.636652 -6.121897)
			(xy 126.62001 -6.184002) (xy 126.611617 -6.247748) (xy 126.611126 -6.279896) (xy 126.611126 -8.987536)
			(xy 168.302432 -8.987536) (xy 168.786556 -8.987536) (xy 169.147744 -8.987536) (xy 169.631868 -8.987536)
			(xy 169.631868 -9.39546) (xy 169.147744 -9.39546) (xy 169.147744 -8.987536) (xy 168.786556 -8.987536)
			(xy 168.786556 -9.394952) (xy 168.302432 -9.394952) (xy 168.302432 -8.987536) (xy 126.611126 -8.987536)
			(xy 126.611126 -9.780016) (xy 126.610632 -9.850398) (xy 126.602738 -9.990941) (xy 126.586977 -10.13082)
			(xy 126.563397 -10.269595) (xy 126.532074 -10.40683) (xy 126.519617 -10.450068) (xy 127.350273 -10.450068)
			(xy 127.354278 -10.36216) (xy 127.366261 -10.27498) (xy 127.386121 -10.189251) (xy 127.413696 -10.105683)
			(xy 127.448755 -10.024969) (xy 127.491008 -9.947777) (xy 127.540106 -9.874748) (xy 127.595642 -9.806486)
			(xy 127.657154 -9.743556) (xy 127.724135 -9.686482) (xy 127.796028 -9.635734) (xy 127.872237 -9.591734)
			(xy 127.952132 -9.554847) (xy 128.035051 -9.525378) (xy 128.120306 -9.503571) (xy 128.20719 -9.489607)
			(xy 128.294984 -9.483601) (xy 128.382961 -9.485605) (xy 128.470391 -9.4956) (xy 128.55655 -9.513504)
			(xy 128.580926 -9.520936) (xy 168.302432 -9.520936) (xy 168.786556 -9.520936) (xy 169.147744 -9.520936)
			(xy 169.631868 -9.520936) (xy 169.631868 -9.92886) (xy 169.147744 -9.92886) (xy 169.147744 -9.520936)
			(xy 168.786556 -9.520936) (xy 168.786556 -9.928352) (xy 168.302432 -9.928352) (xy 168.302432 -9.520936)
			(xy 128.580926 -9.520936) (xy 128.640724 -9.539168) (xy 128.722215 -9.572381) (xy 128.800349 -9.612867)
			(xy 128.874477 -9.660289) (xy 128.943985 -9.714256) (xy 129.008299 -9.774321) (xy 129.066883 -9.839985)
			(xy 129.119254 -9.910704) (xy 129.164977 -9.985892) (xy 129.203674 -10.064927) (xy 129.235023 -10.147153)
			(xy 129.258765 -10.231889) (xy 129.265884 -10.270548) (xy 131.63909 -10.270548) (xy 131.63909 -10.216052)
			(xy 131.646845 -10.16211) (xy 131.662198 -10.10982) (xy 131.684835 -10.060247) (xy 131.714296 -10.014401)
			(xy 131.749982 -9.973213) (xy 131.791165 -9.937522) (xy 131.837009 -9.908056) (xy 131.886579 -9.885413)
			(xy 131.938866 -9.870055) (xy 131.992808 -9.862293) (xy 132.020056 -9.861804) (xy 132.883656 -9.861804)
			(xy 132.910912 -9.86224) (xy 132.964869 -9.869992) (xy 133.017174 -9.885345) (xy 133.066761 -9.907985)
			(xy 133.112622 -9.937453) (xy 133.153821 -9.973148) (xy 133.18952 -10.014343) (xy 133.218993 -10.0602)
			(xy 133.24164 -10.109785) (xy 133.256999 -10.162088) (xy 133.264757 -10.216044) (xy 133.264757 -10.270556)
			(xy 133.256999 -10.324512) (xy 133.24164 -10.376815) (xy 133.218993 -10.4264) (xy 133.18952 -10.472257)
			(xy 133.153821 -10.513452) (xy 133.112622 -10.549147) (xy 133.066761 -10.578615) (xy 133.017174 -10.601255)
			(xy 132.964869 -10.616608) (xy 132.910912 -10.62436) (xy 132.883656 -10.62482) (xy 132.020056 -10.62482)
			(xy 131.992808 -10.624307) (xy 131.938866 -10.616545) (xy 131.886579 -10.601187) (xy 131.837009 -10.578544)
			(xy 131.791165 -10.549078) (xy 131.749982 -10.513387) (xy 131.714296 -10.472199) (xy 131.684835 -10.426353)
			(xy 131.662198 -10.37678) (xy 131.646845 -10.32449) (xy 131.63909 -10.270548) (xy 129.265884 -10.270548)
			(xy 129.274703 -10.318433) (xy 129.282705 -10.406068) (xy 129.283206 -10.450068) (xy 129.282705 -10.494068)
			(xy 129.274703 -10.581703) (xy 129.258765 -10.668247) (xy 129.235023 -10.752983) (xy 129.203674 -10.835209)
			(xy 129.164977 -10.914244) (xy 129.119254 -10.989432) (xy 129.087321 -11.032553) (xy 168.158867 -11.032553)
			(xy 168.158867 -10.978047) (xy 168.166625 -10.924096) (xy 168.181981 -10.871798) (xy 168.204625 -10.822218)
			(xy 168.234094 -10.776365) (xy 168.269789 -10.735173) (xy 168.310983 -10.699481) (xy 168.356837 -10.670014)
			(xy 168.406419 -10.647374) (xy 168.458717 -10.63202) (xy 168.512669 -10.624266) (xy 168.539922 -10.623804)
			(xy 169.403522 -10.623804) (xy 169.430773 -10.624267) (xy 169.48472 -10.632027) (xy 169.537014 -10.647384)
			(xy 169.58659 -10.670027) (xy 169.632439 -10.699495) (xy 169.673628 -10.735188) (xy 169.709318 -10.776379)
			(xy 169.738783 -10.822229) (xy 169.761424 -10.871807) (xy 169.776778 -10.924101) (xy 169.784534 -10.978049)
			(xy 169.784534 -11.032551) (xy 169.776778 -11.086499) (xy 169.761424 -11.138793) (xy 169.738783 -11.188371)
			(xy 169.709318 -11.234221) (xy 169.673628 -11.275412) (xy 169.632439 -11.311105) (xy 169.58659 -11.340573)
			(xy 169.537014 -11.363216) (xy 169.48472 -11.378573) (xy 169.430773 -11.386333) (xy 169.403522 -11.38682)
			(xy 168.539922 -11.38682) (xy 168.512669 -11.386334) (xy 168.458717 -11.37858) (xy 168.406419 -11.363226)
			(xy 168.356837 -11.340586) (xy 168.310983 -11.311119) (xy 168.269789 -11.275427) (xy 168.234094 -11.234235)
			(xy 168.204625 -11.188382) (xy 168.181981 -11.138802) (xy 168.166625 -11.086504) (xy 168.158867 -11.032553)
			(xy 129.087321 -11.032553) (xy 129.066883 -11.060151) (xy 129.008299 -11.125815) (xy 128.943985 -11.18588)
			(xy 128.874477 -11.239847) (xy 128.800349 -11.287269) (xy 128.722215 -11.327755) (xy 128.640724 -11.360968)
			(xy 128.55655 -11.386632) (xy 128.470391 -11.404536) (xy 128.382961 -11.414531) (xy 128.294984 -11.416535)
			(xy 128.20719 -11.410529) (xy 128.120306 -11.396565) (xy 128.035051 -11.374758) (xy 127.952132 -11.345289)
			(xy 127.872237 -11.308402) (xy 127.796028 -11.264402) (xy 127.724135 -11.213654) (xy 127.657154 -11.15658)
			(xy 127.595642 -11.09365) (xy 127.540106 -11.025388) (xy 127.491008 -10.952359) (xy 127.448755 -10.875167)
			(xy 127.413696 -10.794453) (xy 127.386121 -10.710885) (xy 127.366261 -10.625156) (xy 127.354278 -10.537976)
			(xy 127.350273 -10.450068) (xy 126.519617 -10.450068) (xy 126.493105 -10.542092) (xy 126.446613 -10.674957)
			(xy 126.392744 -10.805006) (xy 126.331668 -10.93183) (xy 126.263578 -11.05503) (xy 126.188687 -11.174218)
			(xy 126.10723 -11.28902) (xy 126.019465 -11.399074) (xy 125.973895 -11.450066) (xy 191.515245 -11.450066)
			(xy 191.51925 -11.362158) (xy 191.531233 -11.274978) (xy 191.551093 -11.189249) (xy 191.578668 -11.105681)
			(xy 191.613727 -11.024967) (xy 191.65598 -10.947775) (xy 191.705078 -10.874746) (xy 191.760614 -10.806484)
			(xy 191.822126 -10.743554) (xy 191.889107 -10.68648) (xy 191.961 -10.635732) (xy 192.037209 -10.591732)
			(xy 192.117104 -10.554845) (xy 192.200023 -10.525376) (xy 192.285278 -10.503569) (xy 192.372162 -10.489605)
			(xy 192.459956 -10.483599) (xy 192.547933 -10.485603) (xy 192.635363 -10.495598) (xy 192.721522 -10.513502)
			(xy 192.805696 -10.539166) (xy 192.887187 -10.572379) (xy 192.965321 -10.612865) (xy 193.039449 -10.660287)
			(xy 193.108957 -10.714254) (xy 193.173271 -10.774319) (xy 193.231855 -10.839983) (xy 193.284226 -10.910702)
			(xy 193.329949 -10.98589) (xy 193.368646 -11.064925) (xy 193.399995 -11.147151) (xy 193.423737 -11.231887)
			(xy 193.439675 -11.318431) (xy 193.447677 -11.406066) (xy 193.448178 -11.450066) (xy 193.447677 -11.494066)
			(xy 193.439675 -11.581701) (xy 193.423737 -11.668245) (xy 193.399995 -11.752981) (xy 193.368646 -11.835207)
			(xy 193.329949 -11.914242) (xy 193.284226 -11.98943) (xy 193.231855 -12.060149) (xy 193.173271 -12.125813)
			(xy 193.108957 -12.185878) (xy 193.039449 -12.239845) (xy 192.965321 -12.287267) (xy 192.887187 -12.327753)
			(xy 192.805696 -12.360966) (xy 192.721522 -12.38663) (xy 192.635363 -12.404534) (xy 192.547933 -12.414529)
			(xy 192.459956 -12.416533) (xy 192.372162 -12.410527) (xy 192.285278 -12.396563) (xy 192.200023 -12.374756)
			(xy 192.117104 -12.345287) (xy 192.037209 -12.3084) (xy 191.961 -12.2644) (xy 191.889107 -12.213652)
			(xy 191.822126 -12.156578) (xy 191.760614 -12.093648) (xy 191.705078 -12.025386) (xy 191.65598 -11.952357)
			(xy 191.613727 -11.875165) (xy 191.578668 -11.794451) (xy 191.551093 -11.710883) (xy 191.531233 -11.625154)
			(xy 191.51925 -11.537974) (xy 191.515245 -11.450066) (xy 125.973895 -11.450066) (xy 125.925667 -11.504033)
			(xy 125.826132 -11.603569) (xy 125.721172 -11.697366) (xy 125.611118 -11.785131) (xy 125.496317 -11.866588)
			(xy 125.377128 -11.941479) (xy 125.253928 -12.009569) (xy 125.206611 -12.032356) (xy 166.354411 -12.032356)
			(xy 166.354411 -11.977844) (xy 166.362169 -11.923886) (xy 166.377527 -11.871582) (xy 166.400173 -11.821995)
			(xy 166.429645 -11.776137) (xy 166.465343 -11.734939) (xy 166.506541 -11.699241) (xy 166.552401 -11.66977)
			(xy 166.601987 -11.647125) (xy 166.654292 -11.631768) (xy 166.70825 -11.624011) (xy 166.735506 -11.623548)
			(xy 167.599106 -11.623548) (xy 167.626354 -11.624123) (xy 167.680295 -11.631879) (xy 167.732583 -11.647233)
			(xy 167.782153 -11.669872) (xy 167.827998 -11.699335) (xy 167.869182 -11.735022) (xy 167.904869 -11.776207)
			(xy 167.934331 -11.822052) (xy 167.956969 -11.871623) (xy 167.972322 -11.923911) (xy 167.980078 -11.977852)
			(xy 167.980078 -12.032348) (xy 167.980077 -12.032358) (xy 169.954311 -12.032358) (xy 169.954311 -11.977842)
			(xy 169.96207 -11.92388) (xy 169.97743 -11.871573) (xy 170.000079 -11.821984) (xy 170.029555 -11.776123)
			(xy 170.065258 -11.734924) (xy 170.106461 -11.699226) (xy 170.152326 -11.669756) (xy 170.201918 -11.647114)
			(xy 170.254227 -11.63176) (xy 170.30819 -11.624008) (xy 170.335448 -11.623548) (xy 171.199048 -11.623548)
			(xy 171.226294 -11.624125) (xy 171.28023 -11.631887) (xy 171.332513 -11.647244) (xy 171.382078 -11.669885)
			(xy 171.427917 -11.699349) (xy 171.469097 -11.735037) (xy 171.504779 -11.776221) (xy 171.534238 -11.822064)
			(xy 171.556873 -11.871632) (xy 171.572224 -11.923917) (xy 171.579978 -11.977854) (xy 171.579978 -12.032346)
			(xy 171.572224 -12.086283) (xy 171.556873 -12.138568) (xy 171.534238 -12.188136) (xy 171.504779 -12.233979)
			(xy 171.469097 -12.275163) (xy 171.427917 -12.310851) (xy 171.382078 -12.340315) (xy 171.332513 -12.362956)
			(xy 171.28023 -12.378313) (xy 171.226294 -12.386075) (xy 171.199048 -12.386564) (xy 170.335448 -12.386564)
			(xy 170.30819 -12.386192) (xy 170.254227 -12.37844) (xy 170.201918 -12.363086) (xy 170.152326 -12.340444)
			(xy 170.106461 -12.310974) (xy 170.065258 -12.275276) (xy 170.029555 -12.234077) (xy 170.000079 -12.188216)
			(xy 169.97743 -12.138627) (xy 169.96207 -12.08632) (xy 169.954311 -12.032358) (xy 167.980077 -12.032358)
			(xy 167.972322 -12.086289) (xy 167.956969 -12.138577) (xy 167.934331 -12.188148) (xy 167.904869 -12.233993)
			(xy 167.869182 -12.275178) (xy 167.827998 -12.310865) (xy 167.782153 -12.340328) (xy 167.732583 -12.362967)
			(xy 167.680295 -12.378321) (xy 167.626354 -12.386077) (xy 167.599106 -12.386564) (xy 166.735506 -12.386564)
			(xy 166.70825 -12.386189) (xy 166.654292 -12.378432) (xy 166.601987 -12.363075) (xy 166.552401 -12.34043)
			(xy 166.506541 -12.310959) (xy 166.465343 -12.275261) (xy 166.429645 -12.234063) (xy 166.400173 -12.188205)
			(xy 166.377527 -12.138618) (xy 166.362169 -12.086314) (xy 166.354411 -12.032356) (xy 125.206611 -12.032356)
			(xy 125.127104 -12.070645) (xy 124.997055 -12.124513) (xy 124.86419 -12.171005) (xy 124.728928 -12.209974)
			(xy 124.591693 -12.241298) (xy 124.452918 -12.264877) (xy 124.313039 -12.280639) (xy 124.172496 -12.288532)
			(xy 124.102114 -12.289028) (xy 83.70189 -12.289028) (xy 83.631508 -12.288534) (xy 83.490965 -12.280641)
			(xy 83.351086 -12.26488) (xy 83.21231 -12.2413) (xy 83.075075 -12.209977) (xy 82.939812 -12.171008)
			(xy 82.806947 -12.124516) (xy 82.676898 -12.070648) (xy 82.550073 -12.009572) (xy 82.426873 -11.941482)
			(xy 82.307684 -11.866591) (xy 82.192882 -11.785134) (xy 82.082828 -11.697369) (xy 81.977868 -11.603571)
			(xy 81.878333 -11.504036) (xy 81.784535 -11.399076) (xy 81.696769 -11.289022) (xy 81.615313 -11.174221)
			(xy 81.540421 -11.055032) (xy 81.47233 -10.931832) (xy 81.411254 -10.805008) (xy 81.357386 -10.674959)
			(xy 81.310894 -10.542094) (xy 81.271924 -10.406831) (xy 81.240601 -10.269596) (xy 81.217021 -10.13082)
			(xy 81.20126 -9.990941) (xy 81.193366 -9.850398) (xy 81.192878 -9.780016) (xy 81.192878 -0.999998)
			(xy 81.192375 -0.96785) (xy 81.183982 -0.904106) (xy 81.167341 -0.842001) (xy 81.142736 -0.782601)
			(xy 81.110589 -0.72692) (xy 81.071448 -0.675911) (xy 81.025984 -0.630448) (xy 80.974975 -0.591308)
			(xy 80.919294 -0.559161) (xy 80.859893 -0.534557) (xy 80.797789 -0.517916) (xy 80.734044 -0.509525)
			(xy 80.701896 -0.509016) (xy 14.10208 -0.509016) (xy 14.069935 -0.509543) (xy 14.006194 -0.517937)
			(xy 13.944095 -0.534579) (xy 13.884698 -0.559184) (xy 13.829022 -0.59133) (xy 13.778017 -0.630469)
			(xy 13.732558 -0.675931) (xy 13.69342 -0.726937) (xy 13.661276 -0.782614) (xy 13.636673 -0.842012)
			(xy 13.620034 -0.904112) (xy 13.611642 -0.967853) (xy 13.611098 -0.999998) (xy 13.611098 -5.184498)
			(xy 14.350702 -5.184498) (xy 14.35331 -5.097781) (xy 14.363685 -5.011647) (xy 14.381743 -4.926791)
			(xy 14.40734 -4.843896) (xy 14.440268 -4.763631) (xy 14.480262 -4.686643) (xy 14.526999 -4.613552)
			(xy 14.580104 -4.544948) (xy 14.639148 -4.481383) (xy 14.703655 -4.42337) (xy 14.738096 -4.396994)
			(xy 14.773029 -4.371293) (xy 14.846784 -4.325653) (xy 14.924335 -4.28681) (xy 15.005056 -4.255076)
			(xy 15.088297 -4.230709) (xy 15.173387 -4.213903) (xy 15.259642 -4.204794) (xy 15.346366 -4.203455)
			(xy 15.432861 -4.209898) (xy 15.518429 -4.224071) (xy 15.602382 -4.245858) (xy 15.684044 -4.275086)
			(xy 15.762756 -4.311517) (xy 15.837884 -4.35486) (xy 15.908824 -4.404764) (xy 15.975003 -4.460828)
			(xy 16.035889 -4.5226) (xy 16.090991 -4.589582) (xy 16.139865 -4.661235) (xy 16.182118 -4.736981)
			(xy 16.217409 -4.816211) (xy 16.245454 -4.898286) (xy 16.266027 -4.982545) (xy 16.267136 -4.989901)
			(xy 20.44038 -4.989901) (xy 20.44038 -4.935399) (xy 20.448136 -4.881452) (xy 20.463491 -4.829158)
			(xy 20.486132 -4.779581) (xy 20.515597 -4.733731) (xy 20.551288 -4.692541) (xy 20.592478 -4.65685)
			(xy 20.638328 -4.627384) (xy 20.687904 -4.604742) (xy 20.740198 -4.589387) (xy 20.794145 -4.58163)
			(xy 20.821396 -4.581144) (xy 21.684996 -4.581144) (xy 21.712249 -4.581603) (xy 21.766201 -4.58936)
			(xy 21.818499 -4.604715) (xy 21.86808 -4.627358) (xy 21.913934 -4.656826) (xy 21.955128 -4.69252)
			(xy 21.990822 -4.733713) (xy 22.02029 -4.779566) (xy 22.042933 -4.829147) (xy 22.05829 -4.881445)
			(xy 22.066047 -4.935397) (xy 22.066047 -4.989901) (xy 24.04032 -4.989901) (xy 24.04032 -4.935399)
			(xy 24.048076 -4.881452) (xy 24.063431 -4.829157) (xy 24.086072 -4.779581) (xy 24.115538 -4.73373)
			(xy 24.151229 -4.692541) (xy 24.192419 -4.656849) (xy 24.238269 -4.627383) (xy 24.287846 -4.604742)
			(xy 24.34014 -4.589387) (xy 24.394087 -4.58163) (xy 24.421338 -4.581144) (xy 25.284938 -4.581144)
			(xy 25.312191 -4.581603) (xy 25.366143 -4.58936) (xy 25.418441 -4.604716) (xy 25.468021 -4.627358)
			(xy 25.513875 -4.656827) (xy 25.555068 -4.69252) (xy 25.590762 -4.733713) (xy 25.620231 -4.779567)
			(xy 25.642873 -4.829147) (xy 25.65823 -4.881446) (xy 25.665987 -4.935397) (xy 25.665987 -4.989903)
			(xy 25.66598 -4.989954) (xy 27.64023 -4.989954) (xy 27.64023 -4.935446) (xy 27.647987 -4.881493)
			(xy 27.663343 -4.829194) (xy 27.685985 -4.779612) (xy 27.715454 -4.733756) (xy 27.751147 -4.692562)
			(xy 27.79234 -4.656866) (xy 27.838194 -4.627395) (xy 27.887775 -4.60475) (xy 27.940074 -4.589391)
			(xy 27.994026 -4.581631) (xy 28.02128 -4.581144) (xy 28.88488 -4.581144) (xy 28.91213 -4.581702)
			(xy 28.966077 -4.589456) (xy 29.01837 -4.604808) (xy 29.067947 -4.627446) (xy 29.113797 -4.65691)
			(xy 29.154986 -4.692599) (xy 29.190678 -4.733787) (xy 29.220144 -4.779636) (xy 29.242785 -4.829211)
			(xy 29.25814 -4.881504) (xy 29.265897 -4.93545) (xy 29.265897 -4.98995) (xy 29.265896 -4.989954)
			(xy 31.24043 -4.989954) (xy 31.24043 -4.935446) (xy 31.248187 -4.881494) (xy 31.263543 -4.829195)
			(xy 31.286185 -4.779613) (xy 31.315653 -4.733758) (xy 31.351346 -4.692563) (xy 31.392538 -4.656867)
			(xy 31.438392 -4.627396) (xy 31.487972 -4.604751) (xy 31.540271 -4.589392) (xy 31.594222 -4.581632)
			(xy 31.621476 -4.581144) (xy 32.485076 -4.581144) (xy 32.512327 -4.581702) (xy 32.566273 -4.589455)
			(xy 32.618567 -4.604807) (xy 32.668144 -4.627445) (xy 32.713995 -4.656909) (xy 32.755185 -4.692598)
			(xy 32.790877 -4.733786) (xy 32.820343 -4.779635) (xy 32.842985 -4.82921) (xy 32.85834 -4.881503)
			(xy 32.866097 -4.935449) (xy 32.866097 -4.989951) (xy 32.866096 -4.989958) (xy 40.350307 -4.989958)
			(xy 40.350307 -4.935442) (xy 40.358066 -4.881481) (xy 40.373426 -4.829173) (xy 40.396074 -4.779584)
			(xy 40.42555 -4.733723) (xy 40.461252 -4.692524) (xy 40.502455 -4.656826) (xy 40.548319 -4.627355)
			(xy 40.59791 -4.604712) (xy 40.65022 -4.589358) (xy 40.704182 -4.581604) (xy 40.73144 -4.581144)
			(xy 41.59504 -4.581144) (xy 41.622286 -4.581729) (xy 41.676222 -4.589489) (xy 41.728506 -4.604846)
			(xy 41.778072 -4.627486) (xy 41.823911 -4.65695) (xy 41.865091 -4.692637) (xy 41.900774 -4.733821)
			(xy 41.930233 -4.779663) (xy 41.952868 -4.829232) (xy 41.968219 -4.881517) (xy 41.975974 -4.935454)
			(xy 41.975974 -4.989946) (xy 41.975973 -4.989954) (xy 43.95033 -4.989954) (xy 43.95033 -4.935446)
			(xy 43.958087 -4.881493) (xy 43.973443 -4.829193) (xy 43.996086 -4.779611) (xy 44.025554 -4.733756)
			(xy 44.061248 -4.692561) (xy 44.102441 -4.656865) (xy 44.148295 -4.627394) (xy 44.197876 -4.604749)
			(xy 44.250176 -4.589391) (xy 44.304128 -4.581631) (xy 44.331382 -4.581144) (xy 45.194982 -4.581144)
			(xy 45.222232 -4.581702) (xy 45.276178 -4.589456) (xy 45.328472 -4.604808) (xy 45.378048 -4.627447)
			(xy 45.423898 -4.656911) (xy 45.465087 -4.6926) (xy 45.500778 -4.733788) (xy 45.530244 -4.779636)
			(xy 45.552885 -4.829211) (xy 45.56824 -4.881504) (xy 45.575997 -4.93545) (xy 45.575997 -4.98995)
			(xy 45.575996 -4.989954) (xy 51.56043 -4.989954) (xy 51.56043 -4.935446) (xy 51.568187 -4.881494)
			(xy 51.583543 -4.829195) (xy 51.606185 -4.779613) (xy 51.635653 -4.733758) (xy 51.671346 -4.692563)
			(xy 51.712538 -4.656867) (xy 51.758392 -4.627396) (xy 51.807972 -4.604751) (xy 51.860271 -4.589392)
			(xy 51.914222 -4.581632) (xy 51.941476 -4.581144) (xy 52.805076 -4.581144) (xy 52.832327 -4.581702)
			(xy 52.886273 -4.589455) (xy 52.938567 -4.604807) (xy 52.988144 -4.627445) (xy 53.033995 -4.656909)
			(xy 53.075185 -4.692598) (xy 53.110877 -4.733786) (xy 53.140343 -4.779635) (xy 53.162985 -4.82921)
			(xy 53.17834 -4.881503) (xy 53.186097 -4.935449) (xy 53.186097 -4.989951) (xy 53.186096 -4.989957)
			(xy 55.160307 -4.989957) (xy 55.160307 -4.935443) (xy 55.168065 -4.881484) (xy 55.183424 -4.829178)
			(xy 55.206071 -4.77959) (xy 55.235544 -4.73373) (xy 55.271245 -4.692532) (xy 55.312445 -4.656834)
			(xy 55.358306 -4.627362) (xy 55.407894 -4.604718) (xy 55.460201 -4.589362) (xy 55.514161 -4.581606)
			(xy 55.541418 -4.581144) (xy 56.405018 -4.581144) (xy 56.432265 -4.581727) (xy 56.486204 -4.589485)
			(xy 56.53849 -4.60484) (xy 56.588058 -4.627479) (xy 56.633901 -4.656942) (xy 56.675084 -4.692629)
			(xy 56.710769 -4.733814) (xy 56.74023 -4.779657) (xy 56.762867 -4.829227) (xy 56.778219 -4.881514)
			(xy 56.785974 -4.935453) (xy 56.785974 -4.989947) (xy 56.778219 -5.043886) (xy 56.762867 -5.096173)
			(xy 56.74023 -5.145743) (xy 56.710769 -5.191586) (xy 56.675084 -5.232771) (xy 56.633901 -5.268458)
			(xy 56.588058 -5.297921) (xy 56.53849 -5.32056) (xy 56.486204 -5.335915) (xy 56.432265 -5.343673)
			(xy 56.405018 -5.34416) (xy 55.541418 -5.34416) (xy 55.514161 -5.343794) (xy 55.460201 -5.336038)
			(xy 55.407894 -5.320682) (xy 55.358306 -5.298038) (xy 55.312445 -5.268566) (xy 55.271245 -5.232868)
			(xy 55.235544 -5.19167) (xy 55.206071 -5.14581) (xy 55.183424 -5.096222) (xy 55.168065 -5.043916)
			(xy 55.160307 -4.989957) (xy 53.186096 -4.989957) (xy 53.17834 -5.043897) (xy 53.162985 -5.09619)
			(xy 53.140343 -5.145765) (xy 53.110877 -5.191614) (xy 53.075185 -5.232802) (xy 53.033995 -5.268491)
			(xy 52.988144 -5.297955) (xy 52.938567 -5.320593) (xy 52.886273 -5.335945) (xy 52.832327 -5.343698)
			(xy 52.805076 -5.34416) (xy 51.941476 -5.34416) (xy 51.914222 -5.343768) (xy 51.860271 -5.336008)
			(xy 51.807972 -5.320649) (xy 51.758392 -5.298004) (xy 51.712538 -5.268533) (xy 51.671346 -5.232837)
			(xy 51.635653 -5.191642) (xy 51.606185 -5.145787) (xy 51.583543 -5.096205) (xy 51.568187 -5.043906)
			(xy 51.56043 -4.989954) (xy 45.575996 -4.989954) (xy 45.56824 -5.043896) (xy 45.552885 -5.096189)
			(xy 45.530244 -5.145764) (xy 45.500778 -5.191612) (xy 45.465087 -5.2328) (xy 45.423898 -5.268489)
			(xy 45.378048 -5.297953) (xy 45.328472 -5.320592) (xy 45.276178 -5.335944) (xy 45.222232 -5.343698)
			(xy 45.194982 -5.34416) (xy 44.331382 -5.34416) (xy 44.304128 -5.343769) (xy 44.250176 -5.336009)
			(xy 44.197876 -5.320651) (xy 44.148295 -5.298006) (xy 44.102441 -5.268535) (xy 44.061248 -5.232839)
			(xy 44.025554 -5.191644) (xy 43.996086 -5.145789) (xy 43.973443 -5.096207) (xy 43.958087 -5.043907)
			(xy 43.95033 -4.989954) (xy 41.975973 -4.989954) (xy 41.968219 -5.043883) (xy 41.952868 -5.096168)
			(xy 41.930233 -5.145737) (xy 41.900774 -5.191579) (xy 41.865091 -5.232763) (xy 41.823911 -5.26845)
			(xy 41.778072 -5.297914) (xy 41.728506 -5.320554) (xy 41.676222 -5.335911) (xy 41.622286 -5.343671)
			(xy 41.59504 -5.34416) (xy 40.73144 -5.34416) (xy 40.704182 -5.343796) (xy 40.65022 -5.336042) (xy 40.59791 -5.320688)
			(xy 40.548319 -5.298045) (xy 40.502455 -5.268574) (xy 40.461252 -5.232876) (xy 40.42555 -5.191677)
			(xy 40.396074 -5.145816) (xy 40.373426 -5.096227) (xy 40.358066 -5.043919) (xy 40.350307 -4.989958)
			(xy 32.866096 -4.989958) (xy 32.85834 -5.043897) (xy 32.842985 -5.09619) (xy 32.820343 -5.145765)
			(xy 32.790877 -5.191614) (xy 32.755185 -5.232802) (xy 32.713995 -5.268491) (xy 32.668144 -5.297955)
			(xy 32.618567 -5.320593) (xy 32.566273 -5.335945) (xy 32.512327 -5.343698) (xy 32.485076 -5.34416)
			(xy 31.621476 -5.34416) (xy 31.594222 -5.343768) (xy 31.540271 -5.336008) (xy 31.487972 -5.320649)
			(xy 31.438392 -5.298004) (xy 31.392538 -5.268533) (xy 31.351346 -5.232837) (xy 31.315653 -5.191642)
			(xy 31.286185 -5.145787) (xy 31.263543 -5.096205) (xy 31.248187 -5.043906) (xy 31.24043 -4.989954)
			(xy 29.265896 -4.989954) (xy 29.25814 -5.043896) (xy 29.242785 -5.096189) (xy 29.220144 -5.145764)
			(xy 29.190678 -5.191613) (xy 29.154986 -5.232801) (xy 29.113797 -5.26849) (xy 29.067947 -5.297954)
			(xy 29.01837 -5.320592) (xy 28.966077 -5.335944) (xy 28.91213 -5.343698) (xy 28.88488 -5.34416) (xy 28.02128 -5.34416)
			(xy 27.994026 -5.343769) (xy 27.940074 -5.336009) (xy 27.887775 -5.32065) (xy 27.838194 -5.298005)
			(xy 27.79234 -5.268534) (xy 27.751147 -5.232838) (xy 27.715454 -5.191644) (xy 27.685985 -5.145788)
			(xy 27.663343 -5.096206) (xy 27.647987 -5.043907) (xy 27.64023 -4.989954) (xy 25.66598 -4.989954)
			(xy 25.65823 -5.043854) (xy 25.642873 -5.096153) (xy 25.620231 -5.145733) (xy 25.590762 -5.191587)
			(xy 25.555068 -5.23278) (xy 25.513875 -5.268473) (xy 25.468021 -5.297942) (xy 25.418441 -5.320584)
			(xy 25.366143 -5.33594) (xy 25.312191 -5.343697) (xy 25.284938 -5.34416) (xy 24.421338 -5.34416)
			(xy 24.394087 -5.34367) (xy 24.34014 -5.335913) (xy 24.287846 -5.320558) (xy 24.238269 -5.297917)
			(xy 24.192419 -5.268451) (xy 24.151229 -5.232759) (xy 24.115538 -5.19157) (xy 24.086072 -5.145719)
			(xy 24.063431 -5.096143) (xy 24.048076 -5.043848) (xy 24.04032 -4.989901) (xy 22.066047 -4.989901)
			(xy 22.066047 -4.989903) (xy 22.05829 -5.043855) (xy 22.042933 -5.096153) (xy 22.02029 -5.145734)
			(xy 21.990822 -5.191587) (xy 21.955128 -5.23278) (xy 21.913934 -5.268474) (xy 21.86808 -5.297942)
			(xy 21.818499 -5.320585) (xy 21.766201 -5.33594) (xy 21.712249 -5.343697) (xy 21.684996 -5.34416)
			(xy 20.821396 -5.34416) (xy 20.794145 -5.34367) (xy 20.740198 -5.335913) (xy 20.687904 -5.320558)
			(xy 20.638328 -5.297916) (xy 20.592478 -5.26845) (xy 20.551288 -5.232759) (xy 20.515597 -5.191569)
			(xy 20.486132 -5.145719) (xy 20.463491 -5.096142) (xy 20.448136 -5.043848) (xy 20.44038 -4.989901)
			(xy 16.267136 -4.989901) (xy 16.278962 -5.06831) (xy 16.284155 -5.154889) (xy 16.281564 -5.241584)
			(xy 16.27121 -5.327698) (xy 16.253177 -5.412537) (xy 16.22761 -5.495418) (xy 16.194714 -5.575672)
			(xy 16.154755 -5.652653) (xy 16.108054 -5.725741) (xy 16.054988 -5.794348) (xy 15.995985 -5.85792)
			(xy 15.931519 -5.915946) (xy 15.897098 -5.94233) (xy 15.862132 -5.968006) (xy 15.788377 -6.013689)
			(xy 15.710822 -6.052572) (xy 15.630093 -6.084344) (xy 15.546839 -6.108746) (xy 15.461732 -6.125584)
			(xy 15.375458 -6.13472) (xy 15.288712 -6.136082) (xy 15.202194 -6.129659) (xy 15.116601 -6.115502)
			(xy 15.032622 -6.093724) (xy 14.950935 -6.064503) (xy 14.872197 -6.028073) (xy 14.797045 -5.984729)
			(xy 14.726083 -5.934818) (xy 14.659883 -5.878744) (xy 14.598979 -5.816959) (xy 14.543862 -5.749961)
			(xy 14.494977 -5.678289) (xy 14.452716 -5.602521) (xy 14.417421 -5.523269) (xy 14.389376 -5.44117)
			(xy 14.368808 -5.356887) (xy 14.355882 -5.271099) (xy 14.350702 -5.184498) (xy 13.611098 -5.184498)
			(xy 13.611098 -6.169914) (xy 78.515217 -6.169914) (xy 78.519222 -6.082006) (xy 78.531205 -5.994826)
			(xy 78.551065 -5.909097) (xy 78.57864 -5.825529) (xy 78.613699 -5.744815) (xy 78.655952 -5.667623)
			(xy 78.70505 -5.594594) (xy 78.760586 -5.526332) (xy 78.822098 -5.463402) (xy 78.889079 -5.406328)
			(xy 78.960972 -5.35558) (xy 79.037181 -5.31158) (xy 79.117076 -5.274693) (xy 79.199995 -5.245224)
			(xy 79.28525 -5.223417) (xy 79.372134 -5.209453) (xy 79.459928 -5.203447) (xy 79.547905 -5.205451)
			(xy 79.635335 -5.215446) (xy 79.721494 -5.23335) (xy 79.805668 -5.259014) (xy 79.887159 -5.292227)
			(xy 79.965293 -5.332713) (xy 80.039421 -5.380135) (xy 80.108929 -5.434102) (xy 80.173243 -5.494167)
			(xy 80.231827 -5.559831) (xy 80.284198 -5.63055) (xy 80.329921 -5.705738) (xy 80.368618 -5.784773)
			(xy 80.399967 -5.866999) (xy 80.423709 -5.951735) (xy 80.439647 -6.038279) (xy 80.447649 -6.125914)
			(xy 80.44815 -6.169914) (xy 80.447649 -6.213914) (xy 80.439647 -6.301549) (xy 80.423709 -6.388093)
			(xy 80.399967 -6.472829) (xy 80.368618 -6.555055) (xy 80.329921 -6.63409) (xy 80.284198 -6.709278)
			(xy 80.231827 -6.779997) (xy 80.173243 -6.845661) (xy 80.108929 -6.905726) (xy 80.039421 -6.959693)
			(xy 79.965293 -7.007115) (xy 79.887159 -7.047601) (xy 79.805668 -7.080814) (xy 79.721494 -7.106478)
			(xy 79.635335 -7.124382) (xy 79.547905 -7.134377) (xy 79.459928 -7.136381) (xy 79.372134 -7.130375)
			(xy 79.28525 -7.116411) (xy 79.199995 -7.094604) (xy 79.117076 -7.065135) (xy 79.037181 -7.028248)
			(xy 78.960972 -6.984248) (xy 78.889079 -6.9335) (xy 78.822098 -6.876426) (xy 78.760586 -6.813496)
			(xy 78.70505 -6.745234) (xy 78.655952 -6.672205) (xy 78.613699 -6.595013) (xy 78.57864 -6.514299)
			(xy 78.551065 -6.430731) (xy 78.531205 -6.345002) (xy 78.519222 -6.257822) (xy 78.515217 -6.169914)
			(xy 13.611098 -6.169914) (xy 13.611098 -6.751654) (xy 18.635651 -6.751654) (xy 18.635651 -6.697146)
			(xy 18.643409 -6.643192) (xy 18.658767 -6.590891) (xy 18.681411 -6.541309) (xy 18.710882 -6.495454)
			(xy 18.746579 -6.45426) (xy 18.787775 -6.418566) (xy 18.833632 -6.389099) (xy 18.883216 -6.366458)
			(xy 18.935517 -6.351104) (xy 18.989472 -6.34335) (xy 19.016726 -6.342888) (xy 19.880326 -6.342888)
			(xy 19.907576 -6.343384) (xy 19.96152 -6.351143) (xy 20.013811 -6.3665) (xy 20.063385 -6.389143)
			(xy 20.109231 -6.418609) (xy 20.150418 -6.4543) (xy 20.186106 -6.49549) (xy 20.21557 -6.541338) (xy 20.238209 -6.590913)
			(xy 20.253563 -6.643205) (xy 20.261318 -6.69715) (xy 20.261318 -6.75165) (xy 22.235674 -6.75165)
			(xy 22.235674 -6.69715) (xy 22.243429 -6.643204) (xy 22.258783 -6.590912) (xy 22.281422 -6.541336)
			(xy 22.310886 -6.495487) (xy 22.346574 -6.454297) (xy 22.387761 -6.418605) (xy 22.433608 -6.389138)
			(xy 22.483182 -6.366494) (xy 22.535473 -6.351136) (xy 22.589418 -6.343376) (xy 22.616668 -6.342888)
			(xy 23.480268 -6.342888) (xy 23.507522 -6.343357) (xy 23.561476 -6.35111) (xy 23.613777 -6.366463)
			(xy 23.663361 -6.389104) (xy 23.709217 -6.418571) (xy 23.750413 -6.454264) (xy 23.78611 -6.495457)
			(xy 23.815581 -6.541311) (xy 23.838225 -6.590893) (xy 23.853583 -6.643193) (xy 23.861341 -6.697146)
			(xy 23.861341 -6.751654) (xy 25.835551 -6.751654) (xy 25.835551 -6.697146) (xy 25.843309 -6.643194)
			(xy 25.858665 -6.590895) (xy 25.881309 -6.541314) (xy 25.910778 -6.495459) (xy 25.946473 -6.454266)
			(xy 25.987667 -6.418572) (xy 26.033522 -6.389104) (xy 26.083104 -6.366462) (xy 26.135404 -6.351107)
			(xy 26.189356 -6.343351) (xy 26.21661 -6.342888) (xy 27.08021 -6.342888) (xy 27.10746 -6.343382)
			(xy 27.161407 -6.35114) (xy 27.2137 -6.366496) (xy 27.263275 -6.389137) (xy 27.309124 -6.418604)
			(xy 27.350312 -6.454295) (xy 27.386002 -6.495484) (xy 27.415467 -6.541334) (xy 27.438108 -6.59091)
			(xy 27.453462 -6.643203) (xy 27.461218 -6.697149) (xy 27.461218 -6.751651) (xy 27.461218 -6.751653)
			(xy 29.435751 -6.751653) (xy 29.435751 -6.697147) (xy 29.443509 -6.643195) (xy 29.458865 -6.590896)
			(xy 29.481508 -6.541315) (xy 29.510977 -6.495461) (xy 29.546672 -6.454268) (xy 29.587866 -6.418574)
			(xy 29.63372 -6.389105) (xy 29.683301 -6.366463) (xy 29.7356 -6.351107) (xy 29.789553 -6.343351)
			(xy 29.816806 -6.342888) (xy 30.680406 -6.342888) (xy 30.707657 -6.343382) (xy 30.761603 -6.351139)
			(xy 30.813897 -6.366495) (xy 30.863473 -6.389136) (xy 30.909322 -6.418602) (xy 30.950511 -6.454293)
			(xy 30.986201 -6.495483) (xy 31.015667 -6.541333) (xy 31.038307 -6.590909) (xy 31.053662 -6.643203)
			(xy 31.061418 -6.697149) (xy 31.061418 -6.75165) (xy 38.545774 -6.75165) (xy 38.545774 -6.69715)
			(xy 38.55353 -6.643204) (xy 38.568883 -6.590911) (xy 38.591522 -6.541336) (xy 38.620986 -6.495486)
			(xy 38.656675 -6.454296) (xy 38.697862 -6.418604) (xy 38.743709 -6.389137) (xy 38.793283 -6.366494)
			(xy 38.845575 -6.351136) (xy 38.89952 -6.343376) (xy 38.92677 -6.342888) (xy 39.79037 -6.342888)
			(xy 39.817624 -6.343357) (xy 39.871578 -6.351111) (xy 39.923878 -6.366464) (xy 39.973462 -6.389105)
			(xy 40.019318 -6.418571) (xy 40.060514 -6.454265) (xy 40.096211 -6.495458) (xy 40.125681 -6.541312)
			(xy 40.148326 -6.590893) (xy 40.163683 -6.643193) (xy 40.171441 -6.697146) (xy 40.171441 -6.751654)
			(xy 42.145651 -6.751654) (xy 42.145651 -6.697146) (xy 42.153409 -6.643194) (xy 42.168766 -6.590894)
			(xy 42.191409 -6.541313) (xy 42.220879 -6.495459) (xy 42.256574 -6.454265) (xy 42.297768 -6.418571)
			(xy 42.343624 -6.389103) (xy 42.393206 -6.366461) (xy 42.445506 -6.351106) (xy 42.499458 -6.343351)
			(xy 42.526712 -6.342888) (xy 43.390312 -6.342888) (xy 43.417562 -6.343383) (xy 43.471508 -6.35114)
			(xy 43.523801 -6.366496) (xy 43.573376 -6.389138) (xy 43.619225 -6.418604) (xy 43.660413 -6.454295)
			(xy 43.696103 -6.495485) (xy 43.725568 -6.541334) (xy 43.748208 -6.59091) (xy 43.763562 -6.643203)
			(xy 43.771318 -6.69715) (xy 43.771318 -6.75165) (xy 43.771318 -6.751653) (xy 49.755751 -6.751653)
			(xy 49.755751 -6.697147) (xy 49.763509 -6.643195) (xy 49.778865 -6.590896) (xy 49.801508 -6.541315)
			(xy 49.830977 -6.495461) (xy 49.866672 -6.454268) (xy 49.907866 -6.418574) (xy 49.95372 -6.389105)
			(xy 50.003301 -6.366463) (xy 50.0556 -6.351107) (xy 50.109553 -6.343351) (xy 50.136806 -6.342888)
			(xy 51.000406 -6.342888) (xy 51.027657 -6.343382) (xy 51.081603 -6.351139) (xy 51.133897 -6.366495)
			(xy 51.183473 -6.389136) (xy 51.229322 -6.418602) (xy 51.270511 -6.454293) (xy 51.306201 -6.495483)
			(xy 51.335667 -6.541333) (xy 51.358307 -6.590909) (xy 51.373662 -6.643203) (xy 51.381418 -6.697149)
			(xy 51.381418 -6.751651) (xy 51.381417 -6.751655) (xy 53.355652 -6.751655) (xy 53.355652 -6.697145)
			(xy 53.36341 -6.643189) (xy 53.378768 -6.590887) (xy 53.401415 -6.541303) (xy 53.430887 -6.495447)
			(xy 53.466587 -6.454253) (xy 53.507785 -6.418559) (xy 53.553645 -6.389092) (xy 53.603232 -6.366452)
			(xy 53.655536 -6.3511) (xy 53.709493 -6.343348) (xy 53.736748 -6.342888) (xy 54.600348 -6.342888)
			(xy 54.627597 -6.343385) (xy 54.681539 -6.351147) (xy 54.733827 -6.366506) (xy 54.783398 -6.38915)
			(xy 54.829242 -6.418617) (xy 54.870426 -6.454308) (xy 54.906112 -6.495497) (xy 54.935573 -6.541344)
			(xy 54.958211 -6.590918) (xy 54.973563 -6.643208) (xy 54.981318 -6.697151) (xy 54.981318 -6.751649)
			(xy 54.981318 -6.751651) (xy 56.955674 -6.751651) (xy 56.955674 -6.697149) (xy 56.96343 -6.643201)
			(xy 56.978785 -6.590907) (xy 57.001426 -6.54133) (xy 57.030891 -6.49548) (xy 57.066582 -6.454289)
			(xy 57.107771 -6.418597) (xy 57.153621 -6.38913) (xy 57.203198 -6.366488) (xy 57.255492 -6.351132)
			(xy 57.309439 -6.343374) (xy 57.33669 -6.342888) (xy 58.20029 -6.342888) (xy 58.227543 -6.343359)
			(xy 58.281494 -6.351114) (xy 58.333793 -6.366469) (xy 58.383374 -6.389111) (xy 58.429228 -6.418578)
			(xy 58.470421 -6.454272) (xy 58.506116 -6.495464) (xy 58.535584 -6.541317) (xy 58.558227 -6.590898)
			(xy 58.573583 -6.643196) (xy 58.581341 -6.697147) (xy 58.581341 -6.751651) (xy 70.950574 -6.751651)
			(xy 70.950574 -6.697149) (xy 70.95833 -6.643203) (xy 70.973684 -6.590909) (xy 70.996324 -6.541332)
			(xy 71.025789 -6.495482) (xy 71.061479 -6.454292) (xy 71.102668 -6.4186) (xy 71.148516 -6.389133)
			(xy 71.198092 -6.366491) (xy 71.250385 -6.351134) (xy 71.304331 -6.343375) (xy 71.331582 -6.342888)
			(xy 72.195182 -6.342888) (xy 72.222435 -6.343358) (xy 72.276388 -6.351113) (xy 72.328687 -6.366467)
			(xy 72.378269 -6.389108) (xy 72.424124 -6.418576) (xy 72.465318 -6.454269) (xy 72.501014 -6.495462)
			(xy 72.530483 -6.541315) (xy 72.553126 -6.590896) (xy 72.568483 -6.643195) (xy 72.576241 -6.697147)
			(xy 72.576241 -6.751653) (xy 72.568483 -6.805605) (xy 72.553126 -6.857904) (xy 72.530483 -6.907485)
			(xy 72.501014 -6.953338) (xy 72.465318 -6.994531) (xy 72.424124 -7.030224) (xy 72.378269 -7.059692)
			(xy 72.328687 -7.082333) (xy 72.276388 -7.097687) (xy 72.222435 -7.105442) (xy 72.195182 -7.105904)
			(xy 71.331582 -7.105904) (xy 71.304331 -7.105425) (xy 71.250385 -7.097666) (xy 71.198092 -7.082309)
			(xy 71.148516 -7.059667) (xy 71.102668 -7.0302) (xy 71.061479 -6.994508) (xy 71.025789 -6.953318)
			(xy 70.996324 -6.907468) (xy 70.973684 -6.857891) (xy 70.95833 -6.805597) (xy 70.950574 -6.751651)
			(xy 58.581341 -6.751651) (xy 58.581341 -6.751653) (xy 58.573583 -6.805604) (xy 58.558227 -6.857902)
			(xy 58.535584 -6.907483) (xy 58.506116 -6.953336) (xy 58.470421 -6.994528) (xy 58.429228 -7.030222)
			(xy 58.383374 -7.059689) (xy 58.333793 -7.082331) (xy 58.281494 -7.097686) (xy 58.227543 -7.105441)
			(xy 58.20029 -7.105904) (xy 57.33669 -7.105904) (xy 57.309439 -7.105426) (xy 57.255492 -7.097668)
			(xy 57.203198 -7.082312) (xy 57.153621 -7.05967) (xy 57.107771 -7.030203) (xy 57.066582 -6.994511)
			(xy 57.030891 -6.95332) (xy 57.001426 -6.90747) (xy 56.978785 -6.857893) (xy 56.96343 -6.805599)
			(xy 56.955674 -6.751651) (xy 54.981318 -6.751651) (xy 54.973563 -6.805592) (xy 54.958211 -6.857882)
			(xy 54.935573 -6.907456) (xy 54.906112 -6.953303) (xy 54.870426 -6.994492) (xy 54.829242 -7.030183)
			(xy 54.783398 -7.05965) (xy 54.733827 -7.082294) (xy 54.681539 -7.097653) (xy 54.627597 -7.105415)
			(xy 54.600348 -7.105904) (xy 53.736748 -7.105904) (xy 53.709493 -7.105452) (xy 53.655536 -7.0977)
			(xy 53.603232 -7.082348) (xy 53.553645 -7.059708) (xy 53.507785 -7.030241) (xy 53.466587 -6.994547)
			(xy 53.430887 -6.953353) (xy 53.401415 -6.907497) (xy 53.378768 -6.857913) (xy 53.36341 -6.805611)
			(xy 53.355652 -6.751655) (xy 51.381417 -6.751655) (xy 51.373662 -6.805597) (xy 51.358307 -6.857891)
			(xy 51.335667 -6.907467) (xy 51.306201 -6.953317) (xy 51.270511 -6.994507) (xy 51.229322 -7.030198)
			(xy 51.183473 -7.059664) (xy 51.133897 -7.082305) (xy 51.081603 -7.097661) (xy 51.027657 -7.105418)
			(xy 51.000406 -7.105904) (xy 50.136806 -7.105904) (xy 50.109553 -7.105449) (xy 50.0556 -7.097693)
			(xy 50.003301 -7.082337) (xy 49.95372 -7.059695) (xy 49.907866 -7.030226) (xy 49.866672 -6.994532)
			(xy 49.830977 -6.953339) (xy 49.801508 -6.907485) (xy 49.778865 -6.857904) (xy 49.763509 -6.805605)
			(xy 49.755751 -6.751653) (xy 43.771318 -6.751653) (xy 43.763562 -6.805597) (xy 43.748208 -6.85789)
			(xy 43.725568 -6.907466) (xy 43.696103 -6.953315) (xy 43.660413 -6.994505) (xy 43.619225 -7.030196)
			(xy 43.573376 -7.059662) (xy 43.523801 -7.082304) (xy 43.471508 -7.09766) (xy 43.417562 -7.105417)
			(xy 43.390312 -7.105904) (xy 42.526712 -7.105904) (xy 42.499458 -7.105449) (xy 42.445506 -7.097694)
			(xy 42.393206 -7.082339) (xy 42.343624 -7.059697) (xy 42.297768 -7.030229) (xy 42.256574 -6.994535)
			(xy 42.220879 -6.953341) (xy 42.191409 -6.907487) (xy 42.168766 -6.857906) (xy 42.153409 -6.805606)
			(xy 42.145651 -6.751654) (xy 40.171441 -6.751654) (xy 40.163683 -6.805607) (xy 40.148326 -6.857907)
			(xy 40.125681 -6.907488) (xy 40.096211 -6.953342) (xy 40.060514 -6.994535) (xy 40.019318 -7.030229)
			(xy 39.973462 -7.059695) (xy 39.923878 -7.082336) (xy 39.871578 -7.097689) (xy 39.817624 -7.105443)
			(xy 39.79037 -7.105904) (xy 38.92677 -7.105904) (xy 38.89952 -7.105424) (xy 38.845575 -7.097664)
			(xy 38.793283 -7.082306) (xy 38.743709 -7.059663) (xy 38.697862 -7.030196) (xy 38.656675 -6.994504)
			(xy 38.620986 -6.953314) (xy 38.591522 -6.907464) (xy 38.568883 -6.857889) (xy 38.55353 -6.805596)
			(xy 38.545774 -6.75165) (xy 31.061418 -6.75165) (xy 31.061418 -6.751651) (xy 31.053662 -6.805597)
			(xy 31.038307 -6.857891) (xy 31.015667 -6.907467) (xy 30.986201 -6.953317) (xy 30.950511 -6.994507)
			(xy 30.909322 -7.030198) (xy 30.863473 -7.059664) (xy 30.813897 -7.082305) (xy 30.761603 -7.097661)
			(xy 30.707657 -7.105418) (xy 30.680406 -7.105904) (xy 29.816806 -7.105904) (xy 29.789553 -7.105449)
			(xy 29.7356 -7.097693) (xy 29.683301 -7.082337) (xy 29.63372 -7.059695) (xy 29.587866 -7.030226)
			(xy 29.546672 -6.994532) (xy 29.510977 -6.953339) (xy 29.481508 -6.907485) (xy 29.458865 -6.857904)
			(xy 29.443509 -6.805605) (xy 29.435751 -6.751653) (xy 27.461218 -6.751653) (xy 27.453462 -6.805597)
			(xy 27.438108 -6.85789) (xy 27.415467 -6.907466) (xy 27.386002 -6.953316) (xy 27.350312 -6.994505)
			(xy 27.309124 -7.030196) (xy 27.263275 -7.059663) (xy 27.2137 -7.082304) (xy 27.161407 -7.09766)
			(xy 27.10746 -7.105418) (xy 27.08021 -7.105904) (xy 26.21661 -7.105904) (xy 26.189356 -7.105449)
			(xy 26.135404 -7.097693) (xy 26.083104 -7.082338) (xy 26.033522 -7.059696) (xy 25.987667 -7.030228)
			(xy 25.946473 -6.994534) (xy 25.910778 -6.953341) (xy 25.881309 -6.907486) (xy 25.858665 -6.857905)
			(xy 25.843309 -6.805606) (xy 25.835551 -6.751654) (xy 23.861341 -6.751654) (xy 23.853583 -6.805607)
			(xy 23.838225 -6.857907) (xy 23.815581 -6.907489) (xy 23.78611 -6.953343) (xy 23.750413 -6.994536)
			(xy 23.709217 -7.030229) (xy 23.663361 -7.059696) (xy 23.613777 -7.082337) (xy 23.561476 -7.09769)
			(xy 23.507522 -7.105443) (xy 23.480268 -7.105904) (xy 22.616668 -7.105904) (xy 22.589418 -7.105424)
			(xy 22.535473 -7.097664) (xy 22.483182 -7.082306) (xy 22.433608 -7.059662) (xy 22.387761 -7.030195)
			(xy 22.346574 -6.994503) (xy 22.310886 -6.953313) (xy 22.281422 -6.907464) (xy 22.258783 -6.857888)
			(xy 22.243429 -6.805596) (xy 22.235674 -6.75165) (xy 20.261318 -6.75165) (xy 20.253563 -6.805595)
			(xy 20.238209 -6.857887) (xy 20.21557 -6.907462) (xy 20.186106 -6.95331) (xy 20.150418 -6.9945) (xy 20.109231 -7.030191)
			(xy 20.063385 -7.059657) (xy 20.013811 -7.0823) (xy 19.96152 -7.097657) (xy 19.907576 -7.105416)
			(xy 19.880326 -7.105904) (xy 19.016726 -7.105904) (xy 18.989472 -7.10545) (xy 18.935517 -7.097696)
			(xy 18.883216 -7.082342) (xy 18.833632 -7.059701) (xy 18.787775 -7.030234) (xy 18.746579 -6.99454)
			(xy 18.710882 -6.953346) (xy 18.681411 -6.907491) (xy 18.658767 -6.857909) (xy 18.643409 -6.805608)
			(xy 18.635651 -6.751654) (xy 13.611098 -6.751654) (xy 13.611098 -9.780016) (xy 13.610604 -9.850398)
			(xy 13.602711 -9.990941) (xy 13.58695 -10.13082) (xy 13.563371 -10.269596) (xy 13.532048 -10.406831)
			(xy 13.493079 -10.542094) (xy 13.446587 -10.674959) (xy 13.392719 -10.805008) (xy 13.331643 -10.931832)
			(xy 13.263553 -11.055033) (xy 13.188662 -11.174221) (xy 13.107205 -11.289023) (xy 13.01944 -11.399077)
			(xy 12.925642 -11.504037) (xy 12.826107 -11.603572) (xy 12.721147 -11.69737) (xy 12.611093 -11.785135)
			(xy 12.496291 -11.866592) (xy 12.377103 -11.941483) (xy 12.253902 -12.009573) (xy 12.127078 -12.070649)
			(xy 11.997029 -12.124517) (xy 11.864164 -12.171009) (xy 11.728901 -12.209978) (xy 11.591666 -12.241301)
			(xy 11.45289 -12.26488) (xy 11.313011 -12.280641) (xy 11.172468 -12.288534) (xy 11.102086 -12.289028)
			(xy 1.999996 -12.289028) (xy 1.944227 -12.289537) (xy 1.833 -12.297872) (xy 1.722707 -12.314497)
			(xy 1.613965 -12.339317) (xy 1.507382 -12.372193) (xy 1.403554 -12.412943) (xy 1.303061 -12.461339)
			(xy 1.206466 -12.517108) (xy 1.114309 -12.579941) (xy 1.027105 -12.649484) (xy 0.945341 -12.72535)
			(xy 0.869476 -12.807114) (xy 0.802299 -12.891351) (xy 56.954662 -12.891351) (xy 56.954662 -12.836849)
			(xy 56.962418 -12.782901) (xy 56.977772 -12.730606) (xy 57.000413 -12.681029) (xy 57.029878 -12.635178)
			(xy 57.065568 -12.593986) (xy 57.106757 -12.558293) (xy 57.152606 -12.528825) (xy 57.202182 -12.506181)
			(xy 57.254476 -12.490823) (xy 57.308423 -12.483064) (xy 57.335674 -12.482576) (xy 58.199274 -12.482576)
			(xy 58.226527 -12.48307) (xy 58.280478 -12.490823) (xy 58.332777 -12.506176) (xy 58.382358 -12.528816)
			(xy 58.428213 -12.558282) (xy 58.469407 -12.593975) (xy 58.505102 -12.635166) (xy 58.534571 -12.681019)
			(xy 58.557215 -12.730598) (xy 58.572571 -12.782896) (xy 58.580329 -12.836847) (xy 58.580329 -12.891353)
			(xy 58.580329 -12.891355) (xy 70.949739 -12.891355) (xy 70.949739 -12.836845) (xy 70.957497 -12.78289)
			(xy 70.972854 -12.730588) (xy 70.995499 -12.681005) (xy 71.024971 -12.635149) (xy 71.060668 -12.593954)
			(xy 71.101865 -12.558259) (xy 71.147722 -12.52879) (xy 71.197307 -12.506147) (xy 71.24961 -12.490793)
			(xy 71.303565 -12.483038) (xy 71.33082 -12.482576) (xy 72.19442 -12.482576) (xy 72.221669 -12.483096)
			(xy 72.275612 -12.490854) (xy 72.327902 -12.50621) (xy 72.377475 -12.528852) (xy 72.423321 -12.558317)
			(xy 72.464507 -12.594007) (xy 72.500195 -12.635195) (xy 72.529658 -12.681043) (xy 72.552297 -12.730616)
			(xy 72.56765 -12.782907) (xy 72.575406 -12.836851) (xy 72.575406 -12.891349) (xy 72.56765 -12.945293)
			(xy 72.552297 -12.997584) (xy 72.529658 -13.047157) (xy 72.500195 -13.093005) (xy 72.464507 -13.134193)
			(xy 72.423321 -13.169883) (xy 72.377475 -13.199348) (xy 72.327902 -13.22199) (xy 72.275612 -13.237346)
			(xy 72.221669 -13.245104) (xy 72.19442 -13.245592) (xy 71.33082 -13.245592) (xy 71.303565 -13.245162)
			(xy 71.24961 -13.237407) (xy 71.197307 -13.222053) (xy 71.147722 -13.19941) (xy 71.101865 -13.169941)
			(xy 71.060668 -13.134246) (xy 71.024971 -13.093051) (xy 70.995499 -13.047195) (xy 70.972854 -12.997612)
			(xy 70.957497 -12.94531) (xy 70.949739 -12.891355) (xy 58.580329 -12.891355) (xy 58.572571 -12.945304)
			(xy 58.557215 -12.997602) (xy 58.534571 -13.047181) (xy 58.505102 -13.093034) (xy 58.469407 -13.134225)
			(xy 58.428213 -13.169918) (xy 58.382358 -13.199384) (xy 58.332777 -13.222024) (xy 58.280478 -13.237377)
			(xy 58.226527 -13.24513) (xy 58.199274 -13.245592) (xy 57.335674 -13.245592) (xy 57.308423 -13.245136)
			(xy 57.254476 -13.237377) (xy 57.202182 -13.222019) (xy 57.152606 -13.199375) (xy 57.106757 -13.169907)
			(xy 57.065568 -13.134214) (xy 57.029878 -13.093022) (xy 57.000413 -13.047171) (xy 56.977772 -12.997594)
			(xy 56.962418 -12.945299) (xy 56.954662 -12.891351) (xy 0.802299 -12.891351) (xy 0.799933 -12.894318)
			(xy 0.737102 -12.986476) (xy 0.681333 -13.083072) (xy 0.632939 -13.183565) (xy 0.59219 -13.287393)
			(xy 0.559313 -13.393977) (xy 0.534494 -13.502719) (xy 0.517871 -13.613012) (xy 0.509536 -13.724239)
			(xy 0.509016 -13.780008) (xy 0.509016 -15.222054) (xy 135.233343 -15.222054) (xy 135.233343 -15.167546)
			(xy 135.2411 -15.113592) (xy 135.256457 -15.061292) (xy 135.279101 -15.011709) (xy 135.308571 -14.965854)
			(xy 135.344267 -14.92466) (xy 135.385462 -14.888965) (xy 135.431318 -14.859497) (xy 135.480901 -14.836854)
			(xy 135.533202 -14.821498) (xy 135.587156 -14.813742) (xy 135.61441 -14.81328) (xy 136.47801 -14.81328)
			(xy 136.50526 -14.813791) (xy 136.559205 -14.821548) (xy 136.611497 -14.836904) (xy 136.661071 -14.859545)
			(xy 136.706919 -14.88901) (xy 136.748106 -14.924701) (xy 136.783796 -14.965889) (xy 136.81326 -15.011738)
			(xy 136.8359 -15.061313) (xy 136.851254 -15.113605) (xy 136.85901 -15.16755) (xy 136.85901 -15.22205)
			(xy 136.851254 -15.275995) (xy 136.8359 -15.328287) (xy 136.81326 -15.377862) (xy 136.783796 -15.423711)
			(xy 136.748106 -15.464899) (xy 136.706919 -15.50059) (xy 136.661071 -15.530055) (xy 136.611497 -15.552696)
			(xy 136.559205 -15.568052) (xy 136.50526 -15.575809) (xy 136.47801 -15.576296) (xy 135.61441 -15.576296)
			(xy 135.587156 -15.575858) (xy 135.533202 -15.568102) (xy 135.480901 -15.552746) (xy 135.431318 -15.530103)
			(xy 135.385462 -15.500635) (xy 135.344267 -15.46494) (xy 135.308571 -15.423746) (xy 135.279101 -15.377891)
			(xy 135.256457 -15.328308) (xy 135.2411 -15.276008) (xy 135.233343 -15.222054) (xy 0.509016 -15.222054)
			(xy 0.509016 -17.639611) (xy 15.152858 -17.639611) (xy 15.152858 -17.585109) (xy 15.160614 -17.531161)
			(xy 15.175969 -17.478867) (xy 15.19861 -17.42929) (xy 15.228076 -17.383439) (xy 15.263768 -17.342249)
			(xy 15.304958 -17.306558) (xy 15.350808 -17.277091) (xy 15.400385 -17.25445) (xy 15.452679 -17.239095)
			(xy 15.506627 -17.231338) (xy 15.533878 -17.230852) (xy 16.397478 -17.230852) (xy 16.424731 -17.231315)
			(xy 16.478682 -17.239072) (xy 16.53098 -17.254428) (xy 16.580561 -17.27707) (xy 16.626414 -17.306538)
			(xy 16.667607 -17.342232) (xy 16.703301 -17.383424) (xy 16.732769 -17.429278) (xy 16.755412 -17.478858)
			(xy 16.770768 -17.531156) (xy 16.778525 -17.585107) (xy 16.778525 -17.639611) (xy 20.740858 -17.639611)
			(xy 20.740858 -17.585109) (xy 20.748614 -17.531161) (xy 20.763969 -17.478867) (xy 20.78661 -17.42929)
			(xy 20.816076 -17.383439) (xy 20.851768 -17.342249) (xy 20.892958 -17.306558) (xy 20.938808 -17.277091)
			(xy 20.988385 -17.25445) (xy 21.040679 -17.239095) (xy 21.094627 -17.231338) (xy 21.121878 -17.230852)
			(xy 21.985478 -17.230852) (xy 22.012729 -17.231394) (xy 22.066677 -17.239147) (xy 22.118972 -17.2545)
			(xy 22.168549 -17.277139) (xy 22.2144 -17.306603) (xy 22.255591 -17.342293) (xy 22.291284 -17.383482)
			(xy 22.320751 -17.429331) (xy 22.343392 -17.478908) (xy 22.358748 -17.531202) (xy 22.366505 -17.585149)
			(xy 22.366505 -17.639651) (xy 22.366505 -17.639653) (xy 26.328838 -17.639653) (xy 26.328838 -17.585147)
			(xy 26.336595 -17.531195) (xy 26.35195 -17.478897) (xy 26.374592 -17.429316) (xy 26.404059 -17.383462)
			(xy 26.439752 -17.342268) (xy 26.480944 -17.306573) (xy 26.526797 -17.277103) (xy 26.576376 -17.254458)
			(xy 26.628674 -17.239099) (xy 26.682625 -17.231339) (xy 26.709878 -17.230852) (xy 27.573478 -17.230852)
			(xy 27.600729 -17.231394) (xy 27.654677 -17.239147) (xy 27.706972 -17.2545) (xy 27.756549 -17.277139)
			(xy 27.8024 -17.306603) (xy 27.843591 -17.342293) (xy 27.879284 -17.383482) (xy 27.908751 -17.429331)
			(xy 27.931392 -17.478908) (xy 27.946748 -17.531202) (xy 27.954505 -17.585149) (xy 27.954505 -17.639651)
			(xy 27.954505 -17.639653) (xy 31.916838 -17.639653) (xy 31.916838 -17.585147) (xy 31.924595 -17.531195)
			(xy 31.93995 -17.478897) (xy 31.962592 -17.429316) (xy 31.992059 -17.383462) (xy 32.027752 -17.342268)
			(xy 32.068944 -17.306573) (xy 32.114797 -17.277103) (xy 32.164376 -17.254458) (xy 32.216674 -17.239099)
			(xy 32.270625 -17.231339) (xy 32.297878 -17.230852) (xy 33.161478 -17.230852) (xy 33.188729 -17.231394)
			(xy 33.242677 -17.239147) (xy 33.294972 -17.2545) (xy 33.344549 -17.277139) (xy 33.3904 -17.306603)
			(xy 33.431591 -17.342293) (xy 33.467284 -17.383482) (xy 33.496751 -17.429331) (xy 33.519392 -17.478908)
			(xy 33.534748 -17.531202) (xy 33.542505 -17.585149) (xy 33.542505 -17.639651) (xy 33.542505 -17.639653)
			(xy 37.504838 -17.639653) (xy 37.504838 -17.585147) (xy 37.512595 -17.531195) (xy 37.52795 -17.478897)
			(xy 37.550592 -17.429316) (xy 37.580059 -17.383462) (xy 37.615752 -17.342268) (xy 37.656944 -17.306573)
			(xy 37.702797 -17.277103) (xy 37.752376 -17.254458) (xy 37.804674 -17.239099) (xy 37.858625 -17.231339)
			(xy 37.885878 -17.230852) (xy 38.749478 -17.230852) (xy 38.776729 -17.231394) (xy 38.830677 -17.239147)
			(xy 38.882972 -17.2545) (xy 38.932549 -17.277139) (xy 38.9784 -17.306603) (xy 39.019591 -17.342293)
			(xy 39.055284 -17.383482) (xy 39.084751 -17.429331) (xy 39.107392 -17.478908) (xy 39.122748 -17.531202)
			(xy 39.130505 -17.585149) (xy 39.130505 -17.639651) (xy 39.130505 -17.639654) (xy 43.398638 -17.639654)
			(xy 43.398638 -17.585146) (xy 43.406395 -17.531193) (xy 43.421751 -17.478894) (xy 43.444395 -17.429312)
			(xy 43.473863 -17.383457) (xy 43.509558 -17.342262) (xy 43.550752 -17.306567) (xy 43.596606 -17.277097)
			(xy 43.646188 -17.254454) (xy 43.698487 -17.239096) (xy 43.75244 -17.231338) (xy 43.779694 -17.230852)
			(xy 44.643294 -17.230852) (xy 44.670544 -17.231395) (xy 44.72449 -17.23915) (xy 44.776783 -17.254504)
			(xy 44.826359 -17.277144) (xy 44.872208 -17.306609) (xy 44.913397 -17.342299) (xy 44.949088 -17.383487)
			(xy 44.978553 -17.429336) (xy 45.001194 -17.478911) (xy 45.016548 -17.531204) (xy 45.024305 -17.58515)
			(xy 45.024305 -17.63965) (xy 45.024304 -17.639654) (xy 48.986638 -17.639654) (xy 48.986638 -17.585146)
			(xy 48.994395 -17.531193) (xy 49.009751 -17.478894) (xy 49.032395 -17.429312) (xy 49.061863 -17.383457)
			(xy 49.097558 -17.342262) (xy 49.138752 -17.306567) (xy 49.184606 -17.277097) (xy 49.234188 -17.254454)
			(xy 49.286487 -17.239096) (xy 49.34044 -17.231338) (xy 49.367694 -17.230852) (xy 50.231294 -17.230852)
			(xy 50.258544 -17.231395) (xy 50.31249 -17.23915) (xy 50.364783 -17.254504) (xy 50.414359 -17.277144)
			(xy 50.460208 -17.306609) (xy 50.501397 -17.342299) (xy 50.537088 -17.383487) (xy 50.566553 -17.429336)
			(xy 50.589194 -17.478911) (xy 50.604548 -17.531204) (xy 50.612305 -17.58515) (xy 50.612305 -17.63965)
			(xy 50.612304 -17.639657) (xy 54.608615 -17.639657) (xy 54.608615 -17.585143) (xy 54.616374 -17.531184)
			(xy 54.631733 -17.478878) (xy 54.65438 -17.42929) (xy 54.683854 -17.383431) (xy 54.719554 -17.342233)
			(xy 54.760755 -17.306536) (xy 54.806617 -17.277065) (xy 54.856206 -17.254422) (xy 54.908513 -17.239067)
			(xy 54.962473 -17.231313) (xy 54.98973 -17.230852) (xy 55.85333 -17.230852) (xy 55.880577 -17.23142)
			(xy 55.934516 -17.239179) (xy 55.986801 -17.254535) (xy 56.03637 -17.277176) (xy 56.082211 -17.30664)
			(xy 56.123394 -17.342328) (xy 56.159078 -17.383513) (xy 56.188538 -17.429357) (xy 56.211175 -17.478927)
			(xy 56.226527 -17.531214) (xy 56.234282 -17.585153) (xy 56.234282 -17.639647) (xy 56.226527 -17.693586)
			(xy 56.211175 -17.745873) (xy 56.188538 -17.795443) (xy 56.159078 -17.841287) (xy 56.123394 -17.882472)
			(xy 56.082211 -17.91816) (xy 56.03637 -17.947624) (xy 55.986801 -17.970265) (xy 55.934516 -17.985621)
			(xy 55.880577 -17.99338) (xy 55.85333 -17.993868) (xy 54.98973 -17.993868) (xy 54.962473 -17.993487)
			(xy 54.908513 -17.985733) (xy 54.856206 -17.970378) (xy 54.806617 -17.947735) (xy 54.760755 -17.918264)
			(xy 54.719554 -17.882567) (xy 54.683854 -17.841369) (xy 54.65438 -17.79551) (xy 54.631733 -17.745922)
			(xy 54.616374 -17.693616) (xy 54.608615 -17.639657) (xy 50.612304 -17.639657) (xy 50.604548 -17.693596)
			(xy 50.589194 -17.745889) (xy 50.566553 -17.795464) (xy 50.537088 -17.841313) (xy 50.501397 -17.882501)
			(xy 50.460208 -17.918191) (xy 50.414359 -17.947656) (xy 50.364783 -17.970296) (xy 50.31249 -17.98565)
			(xy 50.258544 -17.993405) (xy 50.231294 -17.993868) (xy 49.367694 -17.993868) (xy 49.34044 -17.993462)
			(xy 49.286487 -17.985704) (xy 49.234188 -17.970346) (xy 49.184606 -17.947703) (xy 49.138752 -17.918233)
			(xy 49.097558 -17.882538) (xy 49.061863 -17.841343) (xy 49.032395 -17.795488) (xy 49.009751 -17.745906)
			(xy 48.994395 -17.693607) (xy 48.986638 -17.639654) (xy 45.024304 -17.639654) (xy 45.016548 -17.693596)
			(xy 45.001194 -17.745889) (xy 44.978553 -17.795464) (xy 44.949088 -17.841313) (xy 44.913397 -17.882501)
			(xy 44.872208 -17.918191) (xy 44.826359 -17.947656) (xy 44.776783 -17.970296) (xy 44.72449 -17.98565)
			(xy 44.670544 -17.993405) (xy 44.643294 -17.993868) (xy 43.779694 -17.993868) (xy 43.75244 -17.993462)
			(xy 43.698487 -17.985704) (xy 43.646188 -17.970346) (xy 43.596606 -17.947703) (xy 43.550752 -17.918233)
			(xy 43.509558 -17.882538) (xy 43.473863 -17.841343) (xy 43.444395 -17.795488) (xy 43.421751 -17.745906)
			(xy 43.406395 -17.693607) (xy 43.398638 -17.639654) (xy 39.130505 -17.639654) (xy 39.122748 -17.693598)
			(xy 39.107392 -17.745892) (xy 39.084751 -17.795469) (xy 39.055284 -17.841318) (xy 39.019591 -17.882507)
			(xy 38.9784 -17.918197) (xy 38.932549 -17.947661) (xy 38.882972 -17.9703) (xy 38.830677 -17.985653)
			(xy 38.776729 -17.993406) (xy 38.749478 -17.993868) (xy 37.885878 -17.993868) (xy 37.858625 -17.993461)
			(xy 37.804674 -17.985701) (xy 37.752376 -17.970342) (xy 37.702797 -17.947697) (xy 37.656944 -17.918227)
			(xy 37.615752 -17.882532) (xy 37.580059 -17.841338) (xy 37.550592 -17.795484) (xy 37.52795 -17.745903)
			(xy 37.512595 -17.693605) (xy 37.504838 -17.639653) (xy 33.542505 -17.639653) (xy 33.534748 -17.693598)
			(xy 33.519392 -17.745892) (xy 33.496751 -17.795469) (xy 33.467284 -17.841318) (xy 33.431591 -17.882507)
			(xy 33.3904 -17.918197) (xy 33.344549 -17.947661) (xy 33.294972 -17.9703) (xy 33.242677 -17.985653)
			(xy 33.188729 -17.993406) (xy 33.161478 -17.993868) (xy 32.297878 -17.993868) (xy 32.270625 -17.993461)
			(xy 32.216674 -17.985701) (xy 32.164376 -17.970342) (xy 32.114797 -17.947697) (xy 32.068944 -17.918227)
			(xy 32.027752 -17.882532) (xy 31.992059 -17.841338) (xy 31.962592 -17.795484) (xy 31.93995 -17.745903)
			(xy 31.924595 -17.693605) (xy 31.916838 -17.639653) (xy 27.954505 -17.639653) (xy 27.946748 -17.693598)
			(xy 27.931392 -17.745892) (xy 27.908751 -17.795469) (xy 27.879284 -17.841318) (xy 27.843591 -17.882507)
			(xy 27.8024 -17.918197) (xy 27.756549 -17.947661) (xy 27.706972 -17.9703) (xy 27.654677 -17.985653)
			(xy 27.600729 -17.993406) (xy 27.573478 -17.993868) (xy 26.709878 -17.993868) (xy 26.682625 -17.993461)
			(xy 26.628674 -17.985701) (xy 26.576376 -17.970342) (xy 26.526797 -17.947697) (xy 26.480944 -17.918227)
			(xy 26.439752 -17.882532) (xy 26.404059 -17.841338) (xy 26.374592 -17.795484) (xy 26.35195 -17.745903)
			(xy 26.336595 -17.693605) (xy 26.328838 -17.639653) (xy 22.366505 -17.639653) (xy 22.358748 -17.693598)
			(xy 22.343392 -17.745892) (xy 22.320751 -17.795469) (xy 22.291284 -17.841318) (xy 22.255591 -17.882507)
			(xy 22.2144 -17.918197) (xy 22.168549 -17.947661) (xy 22.118972 -17.9703) (xy 22.066677 -17.985653)
			(xy 22.012729 -17.993406) (xy 21.985478 -17.993868) (xy 21.121878 -17.993868) (xy 21.094627 -17.993382)
			(xy 21.040679 -17.985625) (xy 20.988385 -17.97027) (xy 20.938808 -17.947629) (xy 20.892958 -17.918162)
			(xy 20.851768 -17.882471) (xy 20.816076 -17.841281) (xy 20.78661 -17.79543) (xy 20.763969 -17.745853)
			(xy 20.748614 -17.693559) (xy 20.740858 -17.639611) (xy 16.778525 -17.639611) (xy 16.778525 -17.639613)
			(xy 16.770768 -17.693564) (xy 16.755412 -17.745862) (xy 16.732769 -17.795442) (xy 16.703301 -17.841296)
			(xy 16.667607 -17.882488) (xy 16.626414 -17.918182) (xy 16.580561 -17.94765) (xy 16.53098 -17.970292)
			(xy 16.478682 -17.985648) (xy 16.424731 -17.993405) (xy 16.397478 -17.993868) (xy 15.533878 -17.993868)
			(xy 15.506627 -17.993382) (xy 15.452679 -17.985625) (xy 15.400385 -17.97027) (xy 15.350808 -17.947629)
			(xy 15.304958 -17.918162) (xy 15.263768 -17.882471) (xy 15.228076 -17.841281) (xy 15.19861 -17.79543)
			(xy 15.175969 -17.745853) (xy 15.160614 -17.693559) (xy 15.152858 -17.639611) (xy 0.509016 -17.639611)
			(xy 0.509016 -18.171947) (xy 131.633522 -18.171947) (xy 131.633522 -18.117453) (xy 131.641277 -18.063515)
			(xy 131.656629 -18.011229) (xy 131.679265 -17.961659) (xy 131.708725 -17.915816) (xy 131.744409 -17.874631)
			(xy 131.78559 -17.838944) (xy 131.831431 -17.80948) (xy 131.880999 -17.78684) (xy 131.933283 -17.771484)
			(xy 131.987221 -17.763724) (xy 132.014468 -17.763236) (xy 132.878068 -17.763236) (xy 132.905326 -17.763609)
			(xy 132.959286 -17.771363) (xy 133.011594 -17.786718) (xy 133.061184 -17.809361) (xy 133.107046 -17.838832)
			(xy 133.148248 -17.87453) (xy 133.183949 -17.915728) (xy 133.213423 -17.961588) (xy 133.236071 -18.011176)
			(xy 133.25143 -18.063483) (xy 133.259189 -18.117443) (xy 133.259189 -18.17195) (xy 137.033499 -18.17195)
			(xy 137.033499 -18.11745) (xy 137.041256 -18.063505) (xy 137.05661 -18.011212) (xy 137.079251 -17.961637)
			(xy 137.108716 -17.915789) (xy 137.144406 -17.874601) (xy 137.185595 -17.838911) (xy 137.231444 -17.809447)
			(xy 137.28102 -17.786807) (xy 137.333312 -17.771454) (xy 137.387258 -17.763699) (xy 137.414508 -17.763236)
			(xy 138.278108 -17.763236) (xy 138.305362 -17.763634) (xy 138.359315 -17.771393) (xy 138.411615 -17.78675)
			(xy 138.461197 -17.809395) (xy 138.507052 -17.838864) (xy 138.548246 -17.87456) (xy 138.58394 -17.915755)
			(xy 138.613409 -17.96161) (xy 138.636052 -18.011193) (xy 138.651409 -18.063493) (xy 138.659166 -18.117446)
			(xy 138.659166 -18.171946) (xy 140.633522 -18.171946) (xy 140.633522 -18.117454) (xy 140.641276 -18.063517)
			(xy 140.656627 -18.011232) (xy 140.679262 -17.961664) (xy 140.70872 -17.915822) (xy 140.744402 -17.874638)
			(xy 140.785582 -17.83895) (xy 140.83142 -17.809486) (xy 140.880986 -17.786845) (xy 140.933268 -17.771487)
			(xy 140.987204 -17.763726) (xy 141.01445 -17.763236) (xy 141.87805 -17.763236) (xy 141.905308 -17.763608)
			(xy 141.959271 -17.77136) (xy 142.011581 -17.786713) (xy 142.061173 -17.809355) (xy 142.107038 -17.838825)
			(xy 142.148241 -17.874523) (xy 142.183945 -17.915722) (xy 142.213421 -17.961583) (xy 142.236069 -18.011172)
			(xy 142.25143 -18.06348) (xy 142.259189 -18.117442) (xy 142.259189 -18.171951) (xy 185.748399 -18.171951)
			(xy 185.748399 -18.117449) (xy 185.756156 -18.063503) (xy 185.771511 -18.011209) (xy 185.794153 -17.961633)
			(xy 185.823619 -17.915784) (xy 185.859311 -17.874596) (xy 185.900502 -17.838906) (xy 185.946353 -17.809442)
			(xy 185.99593 -17.786804) (xy 186.048224 -17.771451) (xy 186.102171 -17.763698) (xy 186.129422 -17.763236)
			(xy 186.993022 -17.763236) (xy 187.020275 -17.763635) (xy 187.074227 -17.771395) (xy 187.126525 -17.786754)
			(xy 187.176105 -17.809399) (xy 187.201242 -17.825555) (xy 218.803143 -17.825555) (xy 218.803143 -17.771045)
			(xy 218.810901 -17.717091) (xy 218.826258 -17.66479) (xy 218.848903 -17.615207) (xy 218.878374 -17.569351)
			(xy 218.914071 -17.528157) (xy 218.955267 -17.492462) (xy 219.001124 -17.462993) (xy 219.050709 -17.440351)
			(xy 219.10301 -17.424996) (xy 219.156965 -17.417242) (xy 219.18422 -17.41678) (xy 220.04782 -17.41678)
			(xy 220.075069 -17.417292) (xy 220.129013 -17.42505) (xy 220.181304 -17.440407) (xy 220.230877 -17.463048)
			(xy 220.276723 -17.492514) (xy 220.31791 -17.528204) (xy 220.353598 -17.569393) (xy 220.383062 -17.615241)
			(xy 220.4057 -17.664815) (xy 220.421054 -17.717106) (xy 220.42881 -17.771051) (xy 220.42881 -17.825549)
			(xy 220.421054 -17.879494) (xy 220.4057 -17.931785) (xy 220.383062 -17.981359) (xy 220.353598 -18.027207)
			(xy 220.31791 -18.068396) (xy 220.276723 -18.104086) (xy 220.230877 -18.133552) (xy 220.181304 -18.156193)
			(xy 220.129013 -18.17155) (xy 220.075069 -18.179308) (xy 220.04782 -18.179796) (xy 219.18422 -18.179796)
			(xy 219.156965 -18.179358) (xy 219.10301 -18.171604) (xy 219.050709 -18.156249) (xy 219.001124 -18.133607)
			(xy 218.955267 -18.104138) (xy 218.914071 -18.068443) (xy 218.878374 -18.027249) (xy 218.848903 -17.981393)
			(xy 218.826258 -17.93181) (xy 218.810901 -17.879509) (xy 218.803143 -17.825555) (xy 187.201242 -17.825555)
			(xy 187.221958 -17.838869) (xy 187.263151 -17.874565) (xy 187.298844 -17.915759) (xy 187.328311 -17.961614)
			(xy 187.350954 -18.011196) (xy 187.366309 -18.063495) (xy 187.374066 -18.117447) (xy 187.374066 -18.171953)
			(xy 187.366309 -18.225905) (xy 187.350954 -18.278204) (xy 187.328311 -18.327786) (xy 187.298844 -18.373641)
			(xy 187.263151 -18.414835) (xy 187.221958 -18.450531) (xy 187.176105 -18.480001) (xy 187.126525 -18.502646)
			(xy 187.074227 -18.518005) (xy 187.020275 -18.525765) (xy 186.993022 -18.526252) (xy 186.129422 -18.526252)
			(xy 186.102171 -18.525702) (xy 186.048224 -18.517949) (xy 185.99593 -18.502596) (xy 185.946353 -18.479958)
			(xy 185.900502 -18.450494) (xy 185.859311 -18.414804) (xy 185.823619 -18.373616) (xy 185.794153 -18.327767)
			(xy 185.771511 -18.278191) (xy 185.756156 -18.225897) (xy 185.748399 -18.171951) (xy 142.259189 -18.171951)
			(xy 142.259189 -18.171958) (xy 142.25143 -18.22592) (xy 142.236069 -18.278228) (xy 142.213421 -18.327817)
			(xy 142.183945 -18.373678) (xy 142.148241 -18.414877) (xy 142.107038 -18.450575) (xy 142.061173 -18.480045)
			(xy 142.011581 -18.502687) (xy 141.959271 -18.51804) (xy 141.905308 -18.525792) (xy 141.87805 -18.526252)
			(xy 141.01445 -18.526252) (xy 140.987204 -18.525674) (xy 140.933268 -18.517913) (xy 140.880986 -18.502555)
			(xy 140.83142 -18.479914) (xy 140.785582 -18.45045) (xy 140.744402 -18.414762) (xy 140.70872 -18.373578)
			(xy 140.679262 -18.327736) (xy 140.656627 -18.278168) (xy 140.641276 -18.225883) (xy 140.633522 -18.171946)
			(xy 138.659166 -18.171946) (xy 138.659166 -18.171954) (xy 138.651409 -18.225907) (xy 138.636052 -18.278207)
			(xy 138.613409 -18.32779) (xy 138.58394 -18.373645) (xy 138.548246 -18.41484) (xy 138.507052 -18.450536)
			(xy 138.461197 -18.480005) (xy 138.411615 -18.50265) (xy 138.359315 -18.518007) (xy 138.305362 -18.525766)
			(xy 138.278108 -18.526252) (xy 137.414508 -18.526252) (xy 137.387258 -18.525701) (xy 137.333312 -18.517946)
			(xy 137.28102 -18.502593) (xy 137.231444 -18.479953) (xy 137.185595 -18.450489) (xy 137.144406 -18.414799)
			(xy 137.108716 -18.373611) (xy 137.079251 -18.327763) (xy 137.05661 -18.278188) (xy 137.041256 -18.225895)
			(xy 137.033499 -18.17195) (xy 133.259189 -18.17195) (xy 133.259189 -18.171957) (xy 133.25143 -18.225917)
			(xy 133.236071 -18.278224) (xy 133.213423 -18.327812) (xy 133.183949 -18.373672) (xy 133.148248 -18.41487)
			(xy 133.107046 -18.450568) (xy 133.061184 -18.480039) (xy 133.011594 -18.502682) (xy 132.959286 -18.518037)
			(xy 132.905326 -18.525791) (xy 132.878068 -18.526252) (xy 132.014468 -18.526252) (xy 131.987221 -18.525676)
			(xy 131.933283 -18.517916) (xy 131.880999 -18.50256) (xy 131.831431 -18.47992) (xy 131.78559 -18.450456)
			(xy 131.744409 -18.414769) (xy 131.708725 -18.373584) (xy 131.679265 -18.327741) (xy 131.656629 -18.278171)
			(xy 131.641277 -18.225885) (xy 131.633522 -18.171947) (xy 0.509016 -18.171947) (xy 0.509016 -19.163611)
			(xy 17.946858 -19.163611) (xy 17.946858 -19.109109) (xy 17.954614 -19.055161) (xy 17.969969 -19.002867)
			(xy 17.99261 -18.95329) (xy 18.022076 -18.907439) (xy 18.057768 -18.866249) (xy 18.098958 -18.830558)
			(xy 18.144808 -18.801091) (xy 18.194385 -18.77845) (xy 18.246679 -18.763095) (xy 18.300627 -18.755338)
			(xy 18.327878 -18.754852) (xy 19.191478 -18.754852) (xy 19.218731 -18.755315) (xy 19.272682 -18.763072)
			(xy 19.32498 -18.778428) (xy 19.374561 -18.80107) (xy 19.420414 -18.830538) (xy 19.461607 -18.866232)
			(xy 19.497301 -18.907424) (xy 19.526769 -18.953278) (xy 19.549412 -19.002858) (xy 19.564768 -19.055156)
			(xy 19.572525 -19.109107) (xy 19.572525 -19.163613) (xy 19.572519 -19.163653) (xy 23.534838 -19.163653)
			(xy 23.534838 -19.109147) (xy 23.542595 -19.055195) (xy 23.55795 -19.002897) (xy 23.580592 -18.953316)
			(xy 23.610059 -18.907462) (xy 23.645752 -18.866268) (xy 23.686944 -18.830573) (xy 23.732797 -18.801103)
			(xy 23.782376 -18.778458) (xy 23.834674 -18.763099) (xy 23.888625 -18.755339) (xy 23.915878 -18.754852)
			(xy 24.779478 -18.754852) (xy 24.806729 -18.755394) (xy 24.860677 -18.763147) (xy 24.912972 -18.7785)
			(xy 24.962549 -18.801139) (xy 25.0084 -18.830603) (xy 25.049591 -18.866293) (xy 25.085284 -18.907482)
			(xy 25.114751 -18.953331) (xy 25.137392 -19.002908) (xy 25.152748 -19.055202) (xy 25.160505 -19.109149)
			(xy 25.160505 -19.163651) (xy 25.160505 -19.163653) (xy 29.122838 -19.163653) (xy 29.122838 -19.109147)
			(xy 29.130595 -19.055195) (xy 29.14595 -19.002897) (xy 29.168592 -18.953316) (xy 29.198059 -18.907462)
			(xy 29.233752 -18.866268) (xy 29.274944 -18.830573) (xy 29.320797 -18.801103) (xy 29.370376 -18.778458)
			(xy 29.422674 -18.763099) (xy 29.476625 -18.755339) (xy 29.503878 -18.754852) (xy 30.367478 -18.754852)
			(xy 30.394729 -18.755394) (xy 30.448677 -18.763147) (xy 30.500972 -18.7785) (xy 30.550549 -18.801139)
			(xy 30.5964 -18.830603) (xy 30.637591 -18.866293) (xy 30.673284 -18.907482) (xy 30.702751 -18.953331)
			(xy 30.725392 -19.002908) (xy 30.740748 -19.055202) (xy 30.748505 -19.109149) (xy 30.748505 -19.163651)
			(xy 30.748505 -19.163653) (xy 34.710838 -19.163653) (xy 34.710838 -19.109147) (xy 34.718595 -19.055195)
			(xy 34.73395 -19.002897) (xy 34.756592 -18.953316) (xy 34.786059 -18.907462) (xy 34.821752 -18.866268)
			(xy 34.862944 -18.830573) (xy 34.908797 -18.801103) (xy 34.958376 -18.778458) (xy 35.010674 -18.763099)
			(xy 35.064625 -18.755339) (xy 35.091878 -18.754852) (xy 35.955478 -18.754852) (xy 35.982729 -18.755394)
			(xy 36.036677 -18.763147) (xy 36.088972 -18.7785) (xy 36.138549 -18.801139) (xy 36.1844 -18.830603)
			(xy 36.225591 -18.866293) (xy 36.261284 -18.907482) (xy 36.290751 -18.953331) (xy 36.313392 -19.002908)
			(xy 36.328748 -19.055202) (xy 36.336505 -19.109149) (xy 36.336505 -19.163651) (xy 36.336505 -19.163654)
			(xy 40.604638 -19.163654) (xy 40.604638 -19.109146) (xy 40.612395 -19.055193) (xy 40.627751 -19.002894)
			(xy 40.650395 -18.953312) (xy 40.679863 -18.907457) (xy 40.715558 -18.866262) (xy 40.756752 -18.830567)
			(xy 40.802606 -18.801097) (xy 40.852188 -18.778454) (xy 40.904487 -18.763096) (xy 40.95844 -18.755338)
			(xy 40.985694 -18.754852) (xy 41.849294 -18.754852) (xy 41.876544 -18.755395) (xy 41.93049 -18.76315)
			(xy 41.982783 -18.778504) (xy 42.032359 -18.801144) (xy 42.078208 -18.830609) (xy 42.119397 -18.866299)
			(xy 42.155088 -18.907487) (xy 42.184553 -18.953336) (xy 42.207194 -19.002911) (xy 42.222548 -19.055204)
			(xy 42.230305 -19.10915) (xy 42.230305 -19.16365) (xy 42.230304 -19.163654) (xy 46.192638 -19.163654)
			(xy 46.192638 -19.109146) (xy 46.200395 -19.055193) (xy 46.215751 -19.002894) (xy 46.238395 -18.953312)
			(xy 46.267863 -18.907457) (xy 46.303558 -18.866262) (xy 46.344752 -18.830567) (xy 46.390606 -18.801097)
			(xy 46.440188 -18.778454) (xy 46.492487 -18.763096) (xy 46.54644 -18.755338) (xy 46.573694 -18.754852)
			(xy 47.437294 -18.754852) (xy 47.464544 -18.755395) (xy 47.51849 -18.76315) (xy 47.570783 -18.778504)
			(xy 47.620359 -18.801144) (xy 47.666208 -18.830609) (xy 47.707397 -18.866299) (xy 47.743088 -18.907487)
			(xy 47.772553 -18.953336) (xy 47.795194 -19.002911) (xy 47.810548 -19.055204) (xy 47.818305 -19.10915)
			(xy 47.818305 -19.16365) (xy 47.818304 -19.163657) (xy 51.814615 -19.163657) (xy 51.814615 -19.109143)
			(xy 51.822374 -19.055184) (xy 51.837733 -19.002878) (xy 51.86038 -18.95329) (xy 51.889854 -18.907431)
			(xy 51.925554 -18.866233) (xy 51.966755 -18.830536) (xy 52.012617 -18.801065) (xy 52.062206 -18.778422)
			(xy 52.114513 -18.763067) (xy 52.168473 -18.755313) (xy 52.19573 -18.754852) (xy 53.05933 -18.754852)
			(xy 53.086577 -18.75542) (xy 53.140516 -18.763179) (xy 53.192801 -18.778535) (xy 53.24237 -18.801176)
			(xy 53.288211 -18.83064) (xy 53.329394 -18.866328) (xy 53.365078 -18.907513) (xy 53.394538 -18.953357)
			(xy 53.417175 -19.002927) (xy 53.432527 -19.055214) (xy 53.440282 -19.109153) (xy 53.440282 -19.163647)
			(xy 53.440281 -19.163657) (xy 57.402615 -19.163657) (xy 57.402615 -19.109143) (xy 57.410374 -19.055184)
			(xy 57.425733 -19.002878) (xy 57.44838 -18.95329) (xy 57.477854 -18.907431) (xy 57.513554 -18.866233)
			(xy 57.554755 -18.830536) (xy 57.600617 -18.801065) (xy 57.650206 -18.778422) (xy 57.702513 -18.763067)
			(xy 57.756473 -18.755313) (xy 57.78373 -18.754852) (xy 58.64733 -18.754852) (xy 58.674577 -18.75542)
			(xy 58.728516 -18.763179) (xy 58.780801 -18.778535) (xy 58.83037 -18.801176) (xy 58.876211 -18.83064)
			(xy 58.917394 -18.866328) (xy 58.953078 -18.907513) (xy 58.982538 -18.953357) (xy 59.005175 -19.002927)
			(xy 59.020527 -19.055214) (xy 59.028282 -19.109153) (xy 59.028282 -19.163647) (xy 59.020527 -19.217586)
			(xy 59.005175 -19.269873) (xy 58.982538 -19.319443) (xy 58.953078 -19.365287) (xy 58.917394 -19.406472)
			(xy 58.876211 -19.44216) (xy 58.83037 -19.471624) (xy 58.780801 -19.494265) (xy 58.728516 -19.509621)
			(xy 58.674577 -19.51738) (xy 58.64733 -19.517868) (xy 57.78373 -19.517868) (xy 57.756473 -19.517487)
			(xy 57.702513 -19.509733) (xy 57.650206 -19.494378) (xy 57.600617 -19.471735) (xy 57.554755 -19.442264)
			(xy 57.513554 -19.406567) (xy 57.477854 -19.365369) (xy 57.44838 -19.31951) (xy 57.425733 -19.269922)
			(xy 57.410374 -19.217616) (xy 57.402615 -19.163657) (xy 53.440281 -19.163657) (xy 53.432527 -19.217586)
			(xy 53.417175 -19.269873) (xy 53.394538 -19.319443) (xy 53.365078 -19.365287) (xy 53.329394 -19.406472)
			(xy 53.288211 -19.44216) (xy 53.24237 -19.471624) (xy 53.192801 -19.494265) (xy 53.140516 -19.509621)
			(xy 53.086577 -19.51738) (xy 53.05933 -19.517868) (xy 52.19573 -19.517868) (xy 52.168473 -19.517487)
			(xy 52.114513 -19.509733) (xy 52.062206 -19.494378) (xy 52.012617 -19.471735) (xy 51.966755 -19.442264)
			(xy 51.925554 -19.406567) (xy 51.889854 -19.365369) (xy 51.86038 -19.31951) (xy 51.837733 -19.269922)
			(xy 51.822374 -19.217616) (xy 51.814615 -19.163657) (xy 47.818304 -19.163657) (xy 47.810548 -19.217596)
			(xy 47.795194 -19.269889) (xy 47.772553 -19.319464) (xy 47.743088 -19.365313) (xy 47.707397 -19.406501)
			(xy 47.666208 -19.442191) (xy 47.620359 -19.471656) (xy 47.570783 -19.494296) (xy 47.51849 -19.50965)
			(xy 47.464544 -19.517405) (xy 47.437294 -19.517868) (xy 46.573694 -19.517868) (xy 46.54644 -19.517462)
			(xy 46.492487 -19.509704) (xy 46.440188 -19.494346) (xy 46.390606 -19.471703) (xy 46.344752 -19.442233)
			(xy 46.303558 -19.406538) (xy 46.267863 -19.365343) (xy 46.238395 -19.319488) (xy 46.215751 -19.269906)
			(xy 46.200395 -19.217607) (xy 46.192638 -19.163654) (xy 42.230304 -19.163654) (xy 42.222548 -19.217596)
			(xy 42.207194 -19.269889) (xy 42.184553 -19.319464) (xy 42.155088 -19.365313) (xy 42.119397 -19.406501)
			(xy 42.078208 -19.442191) (xy 42.032359 -19.471656) (xy 41.982783 -19.494296) (xy 41.93049 -19.50965)
			(xy 41.876544 -19.517405) (xy 41.849294 -19.517868) (xy 40.985694 -19.517868) (xy 40.95844 -19.517462)
			(xy 40.904487 -19.509704) (xy 40.852188 -19.494346) (xy 40.802606 -19.471703) (xy 40.756752 -19.442233)
			(xy 40.715558 -19.406538) (xy 40.679863 -19.365343) (xy 40.650395 -19.319488) (xy 40.627751 -19.269906)
			(xy 40.612395 -19.217607) (xy 40.604638 -19.163654) (xy 36.336505 -19.163654) (xy 36.328748 -19.217598)
			(xy 36.313392 -19.269892) (xy 36.290751 -19.319469) (xy 36.261284 -19.365318) (xy 36.225591 -19.406507)
			(xy 36.1844 -19.442197) (xy 36.138549 -19.471661) (xy 36.088972 -19.4943) (xy 36.036677 -19.509653)
			(xy 35.982729 -19.517406) (xy 35.955478 -19.517868) (xy 35.091878 -19.517868) (xy 35.064625 -19.517461)
			(xy 35.010674 -19.509701) (xy 34.958376 -19.494342) (xy 34.908797 -19.471697) (xy 34.862944 -19.442227)
			(xy 34.821752 -19.406532) (xy 34.786059 -19.365338) (xy 34.756592 -19.319484) (xy 34.73395 -19.269903)
			(xy 34.718595 -19.217605) (xy 34.710838 -19.163653) (xy 30.748505 -19.163653) (xy 30.740748 -19.217598)
			(xy 30.725392 -19.269892) (xy 30.702751 -19.319469) (xy 30.673284 -19.365318) (xy 30.637591 -19.406507)
			(xy 30.5964 -19.442197) (xy 30.550549 -19.471661) (xy 30.500972 -19.4943) (xy 30.448677 -19.509653)
			(xy 30.394729 -19.517406) (xy 30.367478 -19.517868) (xy 29.503878 -19.517868) (xy 29.476625 -19.517461)
			(xy 29.422674 -19.509701) (xy 29.370376 -19.494342) (xy 29.320797 -19.471697) (xy 29.274944 -19.442227)
			(xy 29.233752 -19.406532) (xy 29.198059 -19.365338) (xy 29.168592 -19.319484) (xy 29.14595 -19.269903)
			(xy 29.130595 -19.217605) (xy 29.122838 -19.163653) (xy 25.160505 -19.163653) (xy 25.152748 -19.217598)
			(xy 25.137392 -19.269892) (xy 25.114751 -19.319469) (xy 25.085284 -19.365318) (xy 25.049591 -19.406507)
			(xy 25.0084 -19.442197) (xy 24.962549 -19.471661) (xy 24.912972 -19.4943) (xy 24.860677 -19.509653)
			(xy 24.806729 -19.517406) (xy 24.779478 -19.517868) (xy 23.915878 -19.517868) (xy 23.888625 -19.517461)
			(xy 23.834674 -19.509701) (xy 23.782376 -19.494342) (xy 23.732797 -19.471697) (xy 23.686944 -19.442227)
			(xy 23.645752 -19.406532) (xy 23.610059 -19.365338) (xy 23.580592 -19.319484) (xy 23.55795 -19.269903)
			(xy 23.542595 -19.217605) (xy 23.534838 -19.163653) (xy 19.572519 -19.163653) (xy 19.564768 -19.217564)
			(xy 19.549412 -19.269862) (xy 19.526769 -19.319442) (xy 19.497301 -19.365296) (xy 19.461607 -19.406488)
			(xy 19.420414 -19.442182) (xy 19.374561 -19.47165) (xy 19.32498 -19.494292) (xy 19.272682 -19.509648)
			(xy 19.218731 -19.517405) (xy 19.191478 -19.517868) (xy 18.327878 -19.517868) (xy 18.300627 -19.517382)
			(xy 18.246679 -19.509625) (xy 18.194385 -19.49427) (xy 18.144808 -19.471629) (xy 18.098958 -19.442162)
			(xy 18.057768 -19.406471) (xy 18.022076 -19.365281) (xy 17.99261 -19.31943) (xy 17.969969 -19.269853)
			(xy 17.954614 -19.217559) (xy 17.946858 -19.163611) (xy 0.509016 -19.163611) (xy 0.509016 -20.187751)
			(xy 138.828766 -20.187751) (xy 138.828766 -20.133249) (xy 138.836522 -20.079301) (xy 138.851877 -20.027006)
			(xy 138.874517 -19.977429) (xy 138.903982 -19.931578) (xy 138.939673 -19.890387) (xy 138.980862 -19.854694)
			(xy 139.026711 -19.825227) (xy 139.076288 -19.802584) (xy 139.128582 -19.787226) (xy 139.182529 -19.779467)
			(xy 139.20978 -19.77898) (xy 140.07338 -19.77898) (xy 140.100633 -19.779466) (xy 140.154584 -19.78722)
			(xy 140.206883 -19.802574) (xy 140.256464 -19.825215) (xy 140.302318 -19.854681) (xy 140.343512 -19.890374)
			(xy 140.379207 -19.931566) (xy 140.394269 -19.955002) (xy 185.804556 -19.955002) (xy 185.804556 -18.885662)
			(xy 185.80524 -18.87327) (xy 185.811886 -18.849366) (xy 185.824171 -18.82781) (xy 185.832496 -18.818606)
			(xy 185.842195 -18.809239) (xy 185.865393 -18.795523) (xy 185.891409 -18.788489) (xy 185.904886 -18.788126)
			(xy 185.904886 -18.78838) (xy 186.211718 -18.78838) (xy 186.226061 -18.78957) (xy 186.253172 -18.799203)
			(xy 186.2764 -18.816181) (xy 186.293809 -18.839087) (xy 186.303949 -18.866012) (xy 186.305444 -18.880328)
			(xy 186.305444 -19.80692) (xy 186.305952 -19.80692) (xy 186.305952 -19.949922) (xy 186.305667 -19.955002)
			(xy 186.845956 -19.955002) (xy 186.845956 -18.885662) (xy 186.84664 -18.87327) (xy 186.853286 -18.849366)
			(xy 186.865571 -18.82781) (xy 186.873896 -18.818606) (xy 186.883595 -18.809239) (xy 186.906793 -18.795523)
			(xy 186.932809 -18.788489) (xy 186.946286 -18.788126) (xy 186.946286 -18.78838) (xy 187.253118 -18.78838)
			(xy 187.267461 -18.78957) (xy 187.294572 -18.799203) (xy 187.3178 -18.816181) (xy 187.335209 -18.839087)
			(xy 187.345349 -18.866012) (xy 187.346844 -18.880328) (xy 187.346844 -19.80692) (xy 187.347352 -19.80692)
			(xy 187.347352 -19.949922) (xy 187.346657 -19.962313) (xy 187.340016 -19.986217) (xy 187.327735 -20.007773)
			(xy 187.319412 -20.016978) (xy 187.309749 -20.026386) (xy 187.286534 -20.040091) (xy 187.260504 -20.047107)
			(xy 187.247022 -20.047458) (xy 187.247022 -20.047204) (xy 186.94019 -20.047204) (xy 186.926471 -20.04608)
			(xy 186.900407 -20.03726) (xy 186.877758 -20.021634) (xy 186.86026 -20.000399) (xy 186.849253 -19.975181)
			(xy 186.846972 -19.961606) (xy 186.845956 -19.955002) (xy 186.305667 -19.955002) (xy 186.305257 -19.962313)
			(xy 186.298616 -19.986217) (xy 186.286335 -20.007773) (xy 186.278012 -20.016978) (xy 186.268349 -20.026386)
			(xy 186.245134 -20.040091) (xy 186.219104 -20.047107) (xy 186.205622 -20.047458) (xy 186.205622 -20.047204)
			(xy 185.89879 -20.047204) (xy 185.885071 -20.04608) (xy 185.859007 -20.03726) (xy 185.836358 -20.021634)
			(xy 185.81886 -20.000399) (xy 185.807853 -19.975181) (xy 185.805572 -19.961606) (xy 185.804556 -19.955002)
			(xy 140.394269 -19.955002) (xy 140.408676 -19.977418) (xy 140.431319 -20.026998) (xy 140.446675 -20.079296)
			(xy 140.454433 -20.133247) (xy 140.454433 -20.187753) (xy 140.446675 -20.241704) (xy 140.431319 -20.294002)
			(xy 140.408676 -20.343582) (xy 140.379207 -20.389434) (xy 140.343512 -20.430626) (xy 140.302318 -20.466319)
			(xy 140.256464 -20.495785) (xy 140.206883 -20.518426) (xy 140.154584 -20.53378) (xy 140.100633 -20.541534)
			(xy 140.07338 -20.541996) (xy 139.20978 -20.541996) (xy 139.182529 -20.541533) (xy 139.128582 -20.533774)
			(xy 139.076288 -20.518416) (xy 139.026711 -20.495773) (xy 138.980862 -20.466306) (xy 138.939673 -20.430613)
			(xy 138.903982 -20.389422) (xy 138.874517 -20.343571) (xy 138.851877 -20.293994) (xy 138.836522 -20.241699)
			(xy 138.828766 -20.187751) (xy 0.509016 -20.187751) (xy 0.509016 -21.521251) (xy 15.232366 -21.521251)
			(xy 15.232366 -21.466749) (xy 15.240122 -21.412801) (xy 15.255477 -21.360506) (xy 15.278117 -21.310929)
			(xy 15.307582 -21.265078) (xy 15.343273 -21.223887) (xy 15.384462 -21.188194) (xy 15.430311 -21.158727)
			(xy 15.479888 -21.136084) (xy 15.532182 -21.120726) (xy 15.586129 -21.112967) (xy 15.61338 -21.11248)
			(xy 16.47698 -21.11248) (xy 16.504233 -21.112966) (xy 16.558184 -21.12072) (xy 16.610483 -21.136074)
			(xy 16.660064 -21.158715) (xy 16.705918 -21.188181) (xy 16.747112 -21.223874) (xy 16.782807 -21.265066)
			(xy 16.79026 -21.276663) (xy 186.074814 -21.276663) (xy 186.074814 -21.224649) (xy 186.082951 -21.173275)
			(xy 186.099024 -21.123807) (xy 186.122638 -21.077462) (xy 186.153212 -21.035381) (xy 186.189991 -20.998602)
			(xy 186.232072 -20.968028) (xy 186.278417 -20.944414) (xy 186.327885 -20.928341) (xy 186.379259 -20.920204)
			(xy 186.431273 -20.920204) (xy 186.482647 -20.928341) (xy 186.532115 -20.944414) (xy 186.57846 -20.968028)
			(xy 186.620541 -20.998602) (xy 186.65732 -21.035381) (xy 186.687894 -21.077462) (xy 186.711508 -21.123807)
			(xy 186.727581 -21.173275) (xy 186.735718 -21.224649) (xy 186.736228 -21.250656) (xy 186.735718 -21.276663)
			(xy 186.733706 -21.289363) (xy 187.103514 -21.289363) (xy 187.103514 -21.237349) (xy 187.111651 -21.185975)
			(xy 187.127724 -21.136507) (xy 187.151338 -21.090162) (xy 187.181912 -21.048081) (xy 187.218691 -21.011302)
			(xy 187.260772 -20.980728) (xy 187.307117 -20.957114) (xy 187.356585 -20.941041) (xy 187.407959 -20.932904)
			(xy 187.459973 -20.932904) (xy 187.511347 -20.941041) (xy 187.560815 -20.957114) (xy 187.60716 -20.980728)
			(xy 187.649241 -21.011302) (xy 187.68602 -21.048081) (xy 187.716594 -21.090162) (xy 187.740208 -21.136507)
			(xy 187.756281 -21.185975) (xy 187.764418 -21.237349) (xy 187.764928 -21.263356) (xy 187.764418 -21.289363)
			(xy 187.756281 -21.340737) (xy 187.740208 -21.390205) (xy 187.716594 -21.43655) (xy 187.68602 -21.478631)
			(xy 187.649241 -21.51541) (xy 187.60716 -21.545984) (xy 187.560815 -21.569598) (xy 187.511347 -21.585671)
			(xy 187.459973 -21.593808) (xy 187.407959 -21.593808) (xy 187.356585 -21.585671) (xy 187.307117 -21.569598)
			(xy 187.260772 -21.545984) (xy 187.218691 -21.51541) (xy 187.181912 -21.478631) (xy 187.151338 -21.43655)
			(xy 187.127724 -21.390205) (xy 187.111651 -21.340737) (xy 187.103514 -21.289363) (xy 186.733706 -21.289363)
			(xy 186.727581 -21.328037) (xy 186.711508 -21.377505) (xy 186.687894 -21.42385) (xy 186.65732 -21.465931)
			(xy 186.620541 -21.50271) (xy 186.57846 -21.533284) (xy 186.532115 -21.556898) (xy 186.482647 -21.572971)
			(xy 186.431273 -21.581108) (xy 186.379259 -21.581108) (xy 186.327885 -21.572971) (xy 186.278417 -21.556898)
			(xy 186.232072 -21.533284) (xy 186.189991 -21.50271) (xy 186.153212 -21.465931) (xy 186.122638 -21.42385)
			(xy 186.099024 -21.377505) (xy 186.082951 -21.328037) (xy 186.074814 -21.276663) (xy 16.79026 -21.276663)
			(xy 16.812276 -21.310918) (xy 16.834919 -21.360498) (xy 16.850275 -21.412796) (xy 16.858033 -21.466747)
			(xy 16.858033 -21.521253) (xy 16.850275 -21.575204) (xy 16.834919 -21.627502) (xy 16.812276 -21.677082)
			(xy 16.782807 -21.722934) (xy 16.747112 -21.764126) (xy 16.705918 -21.799819) (xy 16.660064 -21.829285)
			(xy 16.610483 -21.851926) (xy 16.558184 -21.86728) (xy 16.504233 -21.875034) (xy 16.47698 -21.875496)
			(xy 15.61338 -21.875496) (xy 15.586129 -21.875033) (xy 15.532182 -21.867274) (xy 15.479888 -21.851916)
			(xy 15.430311 -21.829273) (xy 15.384462 -21.799806) (xy 15.343273 -21.764113) (xy 15.307582 -21.722922)
			(xy 15.278117 -21.677071) (xy 15.255477 -21.627494) (xy 15.240122 -21.575199) (xy 15.232366 -21.521251)
			(xy 0.509016 -21.521251) (xy 0.509016 -23.480268) (xy 137.257536 -23.480268) (xy 137.257536 -22.410928)
			(xy 137.258158 -22.398549) (xy 137.264729 -22.374656) (xy 137.276936 -22.353091) (xy 137.285222 -22.343872)
			(xy 137.294905 -22.334488) (xy 137.318111 -22.320778) (xy 137.344133 -22.313751) (xy 137.357612 -22.313392)
			(xy 137.664444 -22.313392) (xy 137.678846 -22.314545) (xy 137.706085 -22.324138) (xy 137.729418 -22.341157)
			(xy 137.746873 -22.364164) (xy 137.756978 -22.391218) (xy 137.758424 -22.405594) (xy 137.758424 -23.475188)
			(xy 137.758177 -23.480268) (xy 138.293856 -23.480268) (xy 138.293856 -22.410928) (xy 138.294473 -22.398548)
			(xy 138.301045 -22.374654) (xy 138.313254 -22.35309) (xy 138.321542 -22.343872) (xy 138.331217 -22.334478)
			(xy 138.354427 -22.320771) (xy 138.380452 -22.313749) (xy 138.393932 -22.313392) (xy 138.700764 -22.313392)
			(xy 138.715167 -22.314529) (xy 138.742408 -22.324127) (xy 138.76574 -22.341149) (xy 138.783195 -22.36416)
			(xy 138.793299 -22.391217) (xy 138.794744 -22.405594) (xy 138.794744 -23.475188) (xy 138.794136 -23.487569)
			(xy 138.78756 -23.511463) (xy 138.775347 -23.533027) (xy 138.767058 -23.542244) (xy 138.757386 -23.551641)
			(xy 138.734174 -23.565346) (xy 138.708149 -23.572368) (xy 138.694668 -23.572724) (xy 138.387836 -23.572724)
			(xy 138.374096 -23.571589) (xy 138.347999 -23.562731) (xy 138.325335 -23.547052) (xy 138.307845 -23.525754)
			(xy 138.296872 -23.500473) (xy 138.294618 -23.486872) (xy 138.293856 -23.480268) (xy 137.758177 -23.480268)
			(xy 137.757821 -23.487569) (xy 137.751244 -23.511464) (xy 137.739029 -23.533027) (xy 137.730738 -23.542244)
			(xy 137.721074 -23.55165) (xy 137.697859 -23.565353) (xy 137.67183 -23.57237) (xy 137.658348 -23.572724)
			(xy 137.351516 -23.572724) (xy 137.337774 -23.571605) (xy 137.311676 -23.562743) (xy 137.289013 -23.547059)
			(xy 137.271523 -23.525758) (xy 137.260551 -23.500475) (xy 137.258298 -23.486872) (xy 137.257536 -23.480268)
			(xy 0.509016 -23.480268) (xy 0.509016 -24.74468) (xy 124.582428 -24.74468) (xy 124.989844 -24.74468)
			(xy 125.115828 -24.74468) (xy 125.523244 -24.74468) (xy 125.523244 -24.929338) (xy 133.555232 -24.929338)
			(xy 133.555232 -24.065738) (xy 133.555718 -24.038487) (xy 133.563474 -23.984539) (xy 133.578829 -23.932244)
			(xy 133.601471 -23.882667) (xy 133.630937 -23.836817) (xy 133.666628 -23.795626) (xy 133.707819 -23.759935)
			(xy 133.753669 -23.730469) (xy 133.803246 -23.707827) (xy 133.855541 -23.692472) (xy 133.909489 -23.684716)
			(xy 133.963991 -23.684716) (xy 134.017939 -23.692472) (xy 134.070234 -23.707827) (xy 134.119811 -23.730469)
			(xy 134.165661 -23.759935) (xy 134.206852 -23.795626) (xy 134.242543 -23.836817) (xy 134.272009 -23.882667)
			(xy 134.294651 -23.932244) (xy 134.310006 -23.984539) (xy 134.317762 -24.038487) (xy 134.318248 -24.065738)
			(xy 134.318248 -24.872561) (xy 139.100563 -24.872561) (xy 139.100563 -24.820507) (xy 139.108706 -24.769094)
			(xy 139.124791 -24.719587) (xy 139.148423 -24.673207) (xy 139.17902 -24.631094) (xy 139.215828 -24.594286)
			(xy 139.257941 -24.563689) (xy 139.304321 -24.540057) (xy 139.353828 -24.523972) (xy 139.405241 -24.515829)
			(xy 139.457295 -24.515829) (xy 139.508708 -24.523972) (xy 139.558215 -24.540057) (xy 139.604595 -24.563689)
			(xy 139.646708 -24.594286) (xy 139.683516 -24.631094) (xy 139.714113 -24.673207) (xy 139.737745 -24.719587)
			(xy 139.75383 -24.769094) (xy 139.761973 -24.820507) (xy 139.762484 -24.846534) (xy 139.761973 -24.872561)
			(xy 139.75383 -24.923974) (xy 139.737745 -24.973481) (xy 139.714113 -25.019861) (xy 139.683516 -25.061974)
			(xy 139.646708 -25.098782) (xy 139.604595 -25.129379) (xy 139.558215 -25.153011) (xy 139.508708 -25.169096)
			(xy 139.457295 -25.177239) (xy 139.405241 -25.177239) (xy 139.353828 -25.169096) (xy 139.304321 -25.153011)
			(xy 139.257941 -25.129379) (xy 139.215828 -25.098782) (xy 139.17902 -25.061974) (xy 139.148423 -25.019861)
			(xy 139.124791 -24.973481) (xy 139.108706 -24.923974) (xy 139.100563 -24.872561) (xy 134.318248 -24.872561)
			(xy 134.318248 -24.929338) (xy 134.317762 -24.956589) (xy 134.310006 -25.010537) (xy 134.294651 -25.062832)
			(xy 134.272009 -25.112409) (xy 134.242543 -25.158259) (xy 134.206852 -25.19945) (xy 134.165661 -25.235141)
			(xy 134.119811 -25.264607) (xy 134.070234 -25.287249) (xy 134.017939 -25.302604) (xy 133.963991 -25.31036)
			(xy 133.909489 -25.31036) (xy 133.855541 -25.302604) (xy 133.803246 -25.287249) (xy 133.753669 -25.264607)
			(xy 133.707819 -25.235141) (xy 133.666628 -25.19945) (xy 133.630937 -25.158259) (xy 133.601471 -25.112409)
			(xy 133.578829 -25.062832) (xy 133.563474 -25.010537) (xy 133.555718 -24.956589) (xy 133.555232 -24.929338)
			(xy 125.523244 -24.929338) (xy 125.523244 -25.162764) (xy 126.361444 -25.162764) (xy 126.869952 -25.162764)
			(xy 128.811528 -25.162764) (xy 129.320036 -25.162764) (xy 129.320036 -25.590345) (xy 138.381488 -25.590345)
			(xy 138.381488 -25.538331) (xy 138.389625 -25.486957) (xy 138.405698 -25.437489) (xy 138.429312 -25.391144)
			(xy 138.459886 -25.349063) (xy 138.496665 -25.312284) (xy 138.538746 -25.28171) (xy 138.585091 -25.258096)
			(xy 138.634559 -25.242023) (xy 138.685933 -25.233886) (xy 138.737947 -25.233886) (xy 138.789321 -25.242023)
			(xy 138.838789 -25.258096) (xy 138.885134 -25.28171) (xy 138.927215 -25.312284) (xy 138.963994 -25.349063)
			(xy 138.994568 -25.391144) (xy 139.018182 -25.437489) (xy 139.034255 -25.486957) (xy 139.042392 -25.538331)
			(xy 139.042902 -25.564338) (xy 139.042392 -25.590345) (xy 139.034255 -25.641719) (xy 139.018182 -25.691187)
			(xy 138.994568 -25.737532) (xy 138.963994 -25.779613) (xy 138.927215 -25.816392) (xy 138.885134 -25.846966)
			(xy 138.838789 -25.87058) (xy 138.789321 -25.886653) (xy 138.737947 -25.89479) (xy 138.685933 -25.89479)
			(xy 138.634559 -25.886653) (xy 138.585091 -25.87058) (xy 138.538746 -25.846966) (xy 138.496665 -25.816392)
			(xy 138.459886 -25.779613) (xy 138.429312 -25.737532) (xy 138.405698 -25.691187) (xy 138.389625 -25.641719)
			(xy 138.381488 -25.590345) (xy 129.320036 -25.590345) (xy 129.320036 -25.640792) (xy 128.811528 -25.640792)
			(xy 128.811528 -25.162764) (xy 126.869952 -25.162764) (xy 126.869952 -25.640792) (xy 126.361444 -25.640792)
			(xy 126.361444 -25.162764) (xy 125.523244 -25.162764) (xy 125.523244 -25.228804) (xy 125.115828 -25.228804)
			(xy 125.115828 -24.74468) (xy 124.989844 -24.74468) (xy 124.989844 -25.228804) (xy 124.582428 -25.228804)
			(xy 124.582428 -24.74468) (xy 0.509016 -24.74468) (xy 0.509016 -25.53208) (xy 124.582428 -25.53208)
			(xy 124.989844 -25.53208) (xy 125.115828 -25.53208) (xy 125.523244 -25.53208) (xy 125.523244 -26.016204)
			(xy 125.115828 -26.016204) (xy 125.115828 -25.53208) (xy 124.989844 -25.53208) (xy 124.989844 -26.016204)
			(xy 124.582428 -26.016204) (xy 124.582428 -25.53208) (xy 0.509016 -25.53208) (xy 0.509016 -26.912824)
			(xy 126.361444 -26.912824) (xy 126.869952 -26.912824) (xy 128.811528 -26.912824) (xy 129.320036 -26.912824)
			(xy 129.320036 -27.012392) (xy 131.067048 -27.012392) (xy 131.627372 -27.012392) (xy 131.867148 -27.012392)
			(xy 132.427472 -27.012392) (xy 132.427472 -27.410664) (xy 133.328156 -27.410664) (xy 133.328156 -26.34107)
			(xy 133.328796 -26.328692) (xy 133.335358 -26.304799) (xy 133.347558 -26.283233) (xy 133.355842 -26.274014)
			(xy 133.365523 -26.264627) (xy 133.388729 -26.250916) (xy 133.414752 -26.243891) (xy 133.428232 -26.243534)
			(xy 133.428232 -26.243788) (xy 133.735064 -26.243788) (xy 133.748787 -26.244875) (xy 133.774852 -26.253707)
			(xy 133.797499 -26.269343) (xy 133.814995 -26.290585) (xy 133.826002 -26.315809) (xy 133.828282 -26.329386)
			(xy 133.829044 -26.33599) (xy 133.829044 -27.319732) (xy 140.390372 -27.319732) (xy 140.561568 -27.319732)
			(xy 140.790168 -27.319732) (xy 140.961364 -27.319732) (xy 140.961364 -28.141168) (xy 140.790168 -28.141168)
			(xy 140.790168 -27.319732) (xy 140.561568 -27.319732) (xy 140.561568 -28.141168) (xy 140.390372 -28.141168)
			(xy 140.390372 -27.319732) (xy 133.829044 -27.319732) (xy 133.829044 -27.40533) (xy 133.828404 -27.417708)
			(xy 133.821842 -27.441601) (xy 133.809642 -27.463167) (xy 133.801358 -27.472386) (xy 133.791677 -27.481773)
			(xy 133.768471 -27.495484) (xy 133.742448 -27.502509) (xy 133.728968 -27.502866) (xy 133.728968 -27.502612)
			(xy 133.422136 -27.502612) (xy 133.407772 -27.501393) (xy 133.380595 -27.491823) (xy 133.357297 -27.474871)
			(xy 133.33983 -27.451957) (xy 133.329657 -27.425) (xy 133.328156 -27.410664) (xy 132.427472 -27.410664)
			(xy 132.427472 -27.623008) (xy 131.867148 -27.623008) (xy 131.867148 -27.012392) (xy 131.627372 -27.012392)
			(xy 131.627372 -27.623008) (xy 131.067048 -27.623008) (xy 131.067048 -27.012392) (xy 129.320036 -27.012392)
			(xy 129.320036 -27.390852) (xy 128.811528 -27.390852) (xy 128.811528 -26.912824) (xy 126.869952 -26.912824)
			(xy 126.869952 -27.390852) (xy 126.361444 -27.390852) (xy 126.361444 -26.912824) (xy 0.509016 -26.912824)
			(xy 0.509016 -29.070615) (xy 12.244307 -29.070615) (xy 12.252198 -28.941486) (xy 12.268182 -28.813107)
			(xy 12.292195 -28.685984) (xy 12.324144 -28.560621) (xy 12.363901 -28.437511) (xy 12.41131 -28.31714)
			(xy 12.466183 -28.199984) (xy 12.528305 -28.086504) (xy 12.59743 -27.97715) (xy 12.673285 -27.872351)
			(xy 12.75557 -27.772522) (xy 12.843962 -27.678057) (xy 12.938111 -27.589329) (xy 13.037646 -27.506688)
			(xy 13.142173 -27.43046) (xy 13.25128 -27.360945) (xy 13.364537 -27.298419) (xy 13.481497 -27.243128)
			(xy 13.601698 -27.19529) (xy 13.724665 -27.155093) (xy 13.849914 -27.122698) (xy 13.97695 -27.098231)
			(xy 14.105271 -27.081789) (xy 14.234372 -27.073437) (xy 14.363742 -27.073208) (xy 14.492871 -27.081103)
			(xy 14.62125 -27.097091) (xy 14.748372 -27.121108) (xy 14.873734 -27.15306) (xy 14.996843 -27.19282)
			(xy 15.117212 -27.240232) (xy 15.234367 -27.295109) (xy 15.347845 -27.357234) (xy 15.457198 -27.426362)
			(xy 15.561994 -27.50222) (xy 15.661821 -27.584508) (xy 15.709392 -27.628342) (xy 16.004004 -27.903932)
			(xy 131.067048 -27.903932) (xy 131.627372 -27.903932) (xy 131.867148 -27.903932) (xy 132.427472 -27.903932)
			(xy 132.427472 -28.514548) (xy 131.867148 -28.514548) (xy 131.867148 -27.903932) (xy 131.627372 -27.903932)
			(xy 131.627372 -28.514548) (xy 131.067048 -28.514548) (xy 131.067048 -27.903932) (xy 16.004004 -27.903932)
			(xy 16.877792 -28.721304) (xy 16.92464 -28.765906) (xy 17.013363 -28.860052) (xy 17.096 -28.959584)
			(xy 17.172224 -29.064107) (xy 17.235397 -29.163264) (xy 133.328156 -29.163264) (xy 133.328156 -28.09367)
			(xy 133.328796 -28.081292) (xy 133.335358 -28.057399) (xy 133.347558 -28.035833) (xy 133.355842 -28.026614)
			(xy 133.365523 -28.017227) (xy 133.388729 -28.003516) (xy 133.414752 -27.996491) (xy 133.428232 -27.996134)
			(xy 133.428232 -27.996388) (xy 133.735064 -27.996388) (xy 133.748787 -27.997475) (xy 133.774852 -28.006307)
			(xy 133.797499 -28.021943) (xy 133.814995 -28.043185) (xy 133.826002 -28.068409) (xy 133.828282 -28.081986)
			(xy 133.829044 -28.08859) (xy 133.829044 -28.71978) (xy 140.390372 -28.71978) (xy 140.561568 -28.71978)
			(xy 140.790168 -28.71978) (xy 140.961364 -28.71978) (xy 140.961364 -29.541216) (xy 140.790168 -29.541216)
			(xy 140.790168 -28.71978) (xy 140.561568 -28.71978) (xy 140.561568 -29.541216) (xy 140.390372 -29.541216)
			(xy 140.390372 -28.71978) (xy 133.829044 -28.71978) (xy 133.829044 -29.15793) (xy 133.828404 -29.170308)
			(xy 133.821842 -29.194201) (xy 133.809642 -29.215767) (xy 133.801358 -29.224986) (xy 133.791677 -29.234373)
			(xy 133.768471 -29.248084) (xy 133.742448 -29.255109) (xy 133.728968 -29.255466) (xy 133.728968 -29.255212)
			(xy 133.422136 -29.255212) (xy 133.407772 -29.253993) (xy 133.380595 -29.244423) (xy 133.357297 -29.227471)
			(xy 133.33983 -29.204557) (xy 133.329657 -29.1776) (xy 133.328156 -29.163264) (xy 17.235397 -29.163264)
			(xy 17.241734 -29.17321) (xy 17.304257 -29.286463) (xy 17.359545 -29.403418) (xy 17.407381 -29.523614)
			(xy 17.447575 -29.646576) (xy 17.479969 -29.771819) (xy 17.504435 -29.898849) (xy 17.520877 -30.027165)
			(xy 17.529229 -30.15626) (xy 17.529459 -30.285624) (xy 17.521566 -30.414748) (xy 17.50558 -30.543122)
			(xy 17.481566 -30.670238) (xy 17.449617 -30.795596) (xy 17.40986 -30.9187) (xy 17.362452 -31.039065)
			(xy 17.30758 -31.156215) (xy 17.24546 -31.26969) (xy 17.176338 -31.379039) (xy 17.100486 -31.483833)
			(xy 17.018204 -31.583657) (xy 16.929816 -31.678118) (xy 16.835671 -31.766843) (xy 16.736141 -31.849481)
			(xy 16.631619 -31.925706) (xy 16.522517 -31.995218) (xy 16.409265 -32.057743) (xy 16.292311 -32.113033)
			(xy 16.172116 -32.16087) (xy 16.049154 -32.201066) (xy 15.923911 -32.233462) (xy 15.796882 -32.25793)
			(xy 15.668566 -32.274374) (xy 15.539471 -32.282728) (xy 15.410107 -32.28296) (xy 15.280983 -32.275069)
			(xy 15.152609 -32.259085) (xy 15.025493 -32.235073) (xy 14.900134 -32.203126) (xy 14.77703 -32.163371)
			(xy 14.656664 -32.115965) (xy 14.539512 -32.061094) (xy 14.426037 -31.998976) (xy 14.316687 -31.929855)
			(xy 14.211892 -31.854005) (xy 14.112066 -31.771724) (xy 14.064488 -31.727902) (xy 12.896088 -30.63494)
			(xy 12.849198 -30.590378) (xy 12.760467 -30.496232) (xy 12.677823 -30.3967) (xy 12.601592 -30.292174)
			(xy 12.532074 -30.183069) (xy 12.469545 -30.069814) (xy 12.41425 -29.952855) (xy 12.366409 -29.832656)
			(xy 12.32621 -29.70969) (xy 12.293811 -29.584442) (xy 12.26934 -29.457407) (xy 12.252895 -29.329086)
			(xy 12.244539 -29.199985) (xy 12.244307 -29.070615) (xy 0.509016 -29.070615) (xy 0.509016 -37.099629)
			(xy 170.600616 -37.099629) (xy 170.600616 -37.000299) (xy 170.608608 -36.901292) (xy 170.624542 -36.803249)
			(xy 170.648313 -36.706806) (xy 170.679768 -36.612588) (xy 170.718701 -36.521208) (xy 170.764862 -36.433256)
			(xy 170.81795 -36.349304) (xy 170.877621 -36.269895) (xy 170.943489 -36.195546) (xy 171.015126 -36.126738)
			(xy 171.092067 -36.063918) (xy 171.173813 -36.007493) (xy 171.259835 -35.957828) (xy 171.349574 -35.915246)
			(xy 171.442448 -35.880024) (xy 171.537856 -35.852388) (xy 171.635178 -35.83252) (xy 171.733783 -35.820547)
			(xy 171.833032 -35.816548) (xy 171.932281 -35.820547) (xy 172.030886 -35.83252) (xy 172.128208 -35.852388)
			(xy 172.223616 -35.880024) (xy 172.31649 -35.915246) (xy 172.406229 -35.957828) (xy 172.492251 -36.007493)
			(xy 172.573997 -36.063918) (xy 172.650938 -36.126738) (xy 172.722575 -36.195546) (xy 172.788443 -36.269895)
			(xy 172.848114 -36.349304) (xy 172.901202 -36.433256) (xy 172.947363 -36.521208) (xy 172.986296 -36.612588)
			(xy 173.017751 -36.706806) (xy 173.041522 -36.803249) (xy 173.057456 -36.901292) (xy 173.065448 -37.000299)
			(xy 173.065948 -37.049964) (xy 173.065448 -37.099629) (xy 173.057456 -37.198636) (xy 173.041522 -37.296679)
			(xy 173.017751 -37.393122) (xy 172.986296 -37.48734) (xy 172.947363 -37.57872) (xy 172.901202 -37.666672)
			(xy 172.848114 -37.750624) (xy 172.788443 -37.830033) (xy 172.722575 -37.904382) (xy 172.650938 -37.97319)
			(xy 172.573997 -38.03601) (xy 172.492251 -38.092435) (xy 172.406229 -38.1421) (xy 172.31649 -38.184682)
			(xy 172.223616 -38.219904) (xy 172.128208 -38.24754) (xy 172.030886 -38.267408) (xy 171.932281 -38.279381)
			(xy 171.833032 -38.283381) (xy 171.733783 -38.279381) (xy 171.635178 -38.267408) (xy 171.537856 -38.24754)
			(xy 171.442448 -38.219904) (xy 171.349574 -38.184682) (xy 171.259835 -38.1421) (xy 171.173813 -38.092435)
			(xy 171.092067 -38.03601) (xy 171.015126 -37.97319) (xy 170.943489 -37.904382) (xy 170.877621 -37.830033)
			(xy 170.81795 -37.750624) (xy 170.764862 -37.666672) (xy 170.718701 -37.57872) (xy 170.679768 -37.48734)
			(xy 170.648313 -37.393122) (xy 170.624542 -37.296679) (xy 170.608608 -37.198636) (xy 170.600616 -37.099629)
			(xy 0.509016 -37.099629) (xy 0.509016 -39.657528) (xy 357.003604 -39.657528) (xy 357.003604 -38.793928)
			(xy 357.00409 -38.766659) (xy 357.011852 -38.712675) (xy 357.027217 -38.660345) (xy 357.049874 -38.610735)
			(xy 357.07936 -38.564854) (xy 357.115075 -38.523637) (xy 357.156292 -38.487922) (xy 357.202173 -38.458436)
			(xy 357.251783 -38.435779) (xy 357.304113 -38.420414) (xy 357.358097 -38.412652) (xy 357.412635 -38.412652)
			(xy 357.466619 -38.420414) (xy 357.518949 -38.435779) (xy 357.568559 -38.458436) (xy 357.61444 -38.487922)
			(xy 357.655657 -38.523637) (xy 357.691372 -38.564854) (xy 357.720858 -38.610735) (xy 357.743515 -38.660345)
			(xy 357.75888 -38.712675) (xy 357.766642 -38.766659) (xy 357.767128 -38.793928) (xy 357.767128 -39.657528)
			(xy 357.766642 -39.684797) (xy 357.75888 -39.738781) (xy 357.743515 -39.791111) (xy 357.720858 -39.840721)
			(xy 357.691372 -39.886602) (xy 357.655657 -39.927819) (xy 357.61444 -39.963534) (xy 357.568559 -39.99302)
			(xy 357.518949 -40.015677) (xy 357.466619 -40.031042) (xy 357.412635 -40.038804) (xy 357.358097 -40.038804)
			(xy 357.304113 -40.031042) (xy 357.251783 -40.015677) (xy 357.202173 -39.99302) (xy 357.156292 -39.963534)
			(xy 357.115075 -39.927819) (xy 357.07936 -39.886602) (xy 357.049874 -39.840721) (xy 357.027217 -39.791111)
			(xy 357.011852 -39.738781) (xy 357.00409 -39.684797) (xy 357.003604 -39.657528) (xy 0.509016 -39.657528)
			(xy 0.509016 -40.744902) (xy 235.083357 -40.744902) (xy 235.087362 -40.656994) (xy 235.099345 -40.569814)
			(xy 235.119205 -40.484085) (xy 235.14678 -40.400517) (xy 235.181839 -40.319803) (xy 235.224092 -40.242611)
			(xy 235.27319 -40.169582) (xy 235.328726 -40.10132) (xy 235.390238 -40.03839) (xy 235.457219 -39.981316)
			(xy 235.529112 -39.930568) (xy 235.605321 -39.886568) (xy 235.685216 -39.849681) (xy 235.768135 -39.820212)
			(xy 235.85339 -39.798405) (xy 235.940274 -39.784441) (xy 236.028068 -39.778435) (xy 236.116045 -39.780439)
			(xy 236.203475 -39.790434) (xy 236.289634 -39.808338) (xy 236.373808 -39.834002) (xy 236.455299 -39.867215)
			(xy 236.533433 -39.907701) (xy 236.607561 -39.955123) (xy 236.677069 -40.00909) (xy 236.741383 -40.069155)
			(xy 236.799967 -40.134819) (xy 236.852338 -40.205538) (xy 236.898061 -40.280726) (xy 236.936758 -40.359761)
			(xy 236.968107 -40.441987) (xy 236.991849 -40.526723) (xy 237.007787 -40.613267) (xy 237.015789 -40.700902)
			(xy 237.01629 -40.744902) (xy 237.015789 -40.788902) (xy 237.007787 -40.876537) (xy 236.991849 -40.963081)
			(xy 236.968107 -41.047817) (xy 236.936758 -41.130043) (xy 236.898061 -41.209078) (xy 236.852338 -41.284266)
			(xy 236.799967 -41.354985) (xy 236.741383 -41.420649) (xy 236.677069 -41.480714) (xy 236.607561 -41.534681)
			(xy 236.533433 -41.582103) (xy 236.455299 -41.622589) (xy 236.373808 -41.655802) (xy 236.289634 -41.681466)
			(xy 236.203475 -41.69937) (xy 236.116045 -41.709365) (xy 236.028068 -41.711369) (xy 235.940274 -41.705363)
			(xy 235.85339 -41.691399) (xy 235.768135 -41.669592) (xy 235.685216 -41.640123) (xy 235.605321 -41.603236)
			(xy 235.529112 -41.559236) (xy 235.457219 -41.508488) (xy 235.390238 -41.451414) (xy 235.328726 -41.388484)
			(xy 235.27319 -41.320222) (xy 235.224092 -41.247193) (xy 235.181839 -41.170001) (xy 235.14678 -41.089287)
			(xy 235.119205 -41.005719) (xy 235.099345 -40.91999) (xy 235.087362 -40.83281) (xy 235.083357 -40.744902)
			(xy 0.509016 -40.744902) (xy 0.509016 -43.999912) (xy 16.983969 -43.999912) (xy 16.987993 -43.914144)
			(xy 17.000031 -43.82913) (xy 17.019978 -43.745616) (xy 17.047657 -43.664337) (xy 17.082825 -43.586008)
			(xy 17.125174 -43.511315) (xy 17.174331 -43.440917) (xy 17.229864 -43.375431) (xy 17.291286 -43.315433)
			(xy 17.358055 -43.26145) (xy 17.429587 -43.213957) (xy 17.505251 -43.173371) (xy 17.584384 -43.140048)
			(xy 17.666289 -43.114282) (xy 17.750247 -43.096299) (xy 17.835521 -43.086257) (xy 17.92136 -43.084244)
			(xy 18.00701 -43.090278) (xy 18.091718 -43.104306) (xy 18.174741 -43.126205) (xy 18.255349 -43.155782)
			(xy 18.332833 -43.192777) (xy 18.406512 -43.236865) (xy 18.475738 -43.287659) (xy 18.539905 -43.344712)
			(xy 18.598446 -43.407523) (xy 18.650849 -43.47554) (xy 18.696652 -43.548165) (xy 18.735453 -43.62476)
			(xy 18.766912 -43.704652) (xy 18.790751 -43.787139) (xy 18.806761 -43.871496) (xy 18.814801 -43.956981)
			(xy 18.815304 -43.999912) (xy 18.814801 -44.042843) (xy 18.806761 -44.128328) (xy 18.790751 -44.212685)
			(xy 18.766912 -44.295172) (xy 18.735453 -44.375064) (xy 18.696652 -44.451659) (xy 18.650849 -44.524284)
			(xy 18.598446 -44.592301) (xy 18.539905 -44.655112) (xy 18.475738 -44.712165) (xy 18.406512 -44.762959)
			(xy 18.332833 -44.807047) (xy 18.255349 -44.844042) (xy 18.174741 -44.873619) (xy 18.091718 -44.895518)
			(xy 18.00701 -44.909546) (xy 17.92136 -44.91558) (xy 17.835521 -44.913567) (xy 17.750247 -44.903525)
			(xy 17.666289 -44.885542) (xy 17.584384 -44.859776) (xy 17.505251 -44.826453) (xy 17.429587 -44.785867)
			(xy 17.358055 -44.738374) (xy 17.291286 -44.684391) (xy 17.229864 -44.624393) (xy 17.174331 -44.558907)
			(xy 17.125174 -44.488509) (xy 17.082825 -44.413816) (xy 17.047657 -44.335487) (xy 17.019978 -44.254208)
			(xy 17.000031 -44.170694) (xy 16.987993 -44.08568) (xy 16.983969 -43.999912) (xy 0.509016 -43.999912)
			(xy 0.509016 -47.049813) (xy 59.781451 -47.049813) (xy 59.785436 -46.895317) (xy 59.79737 -46.74123)
			(xy 59.817219 -46.587962) (xy 59.844933 -46.43592) (xy 59.880436 -46.285505) (xy 59.923635 -46.137118)
			(xy 59.974415 -45.991151) (xy 60.032642 -45.847991) (xy 60.098162 -45.708019) (xy 60.1708 -45.571605)
			(xy 60.250363 -45.439111) (xy 60.336642 -45.310889) (xy 60.429407 -45.187278) (xy 60.528412 -45.068606)
			(xy 60.633395 -44.955188) (xy 60.744077 -44.847324) (xy 60.860165 -44.745302) (xy 60.981351 -44.64939)
			(xy 61.107313 -44.559844) (xy 61.237718 -44.476901) (xy 61.37222 -44.400781) (xy 61.510462 -44.331685)
			(xy 61.652077 -44.269798) (xy 61.796691 -44.215282) (xy 61.943919 -44.168283) (xy 62.093371 -44.128926)
			(xy 62.244652 -44.097314) (xy 62.397358 -44.073531) (xy 62.551087 -44.057641) (xy 62.70543 -44.049685)
			(xy 62.782704 -44.049188) (xy 64.383158 -44.049188) (xy 64.460432 -44.049684) (xy 64.614774 -44.057653)
			(xy 64.768502 -44.073557) (xy 64.921207 -44.097353) (xy 65.072484 -44.128978) (xy 65.221933 -44.168349)
			(xy 65.369158 -44.21536) (xy 65.513767 -44.269888) (xy 65.655377 -44.331788) (xy 65.793613 -44.400896)
			(xy 65.928108 -44.477028) (xy 66.058506 -44.559982) (xy 66.184461 -44.649539) (xy 66.305639 -44.745461)
			(xy 66.421718 -44.847494) (xy 66.532391 -44.955367) (xy 66.637364 -45.068794) (xy 66.736359 -45.187475)
			(xy 66.829113 -45.311094) (xy 66.915381 -45.439324) (xy 66.994934 -45.571824) (xy 67.06756 -45.708245)
			(xy 67.133068 -45.848223) (xy 67.191283 -45.991387) (xy 67.242051 -46.137359) (xy 67.285237 -46.28575)
			(xy 67.320727 -46.436168) (xy 67.348428 -46.588213) (xy 67.368264 -46.741483) (xy 67.380185 -46.89557)
			(xy 67.384154 -47.04994) (xy 89.78165 -47.04994) (xy 89.78563 -46.895439) (xy 89.797557 -46.741349)
			(xy 89.817402 -46.588076) (xy 89.84511 -46.436028) (xy 89.880608 -46.285609) (xy 89.923803 -46.137216)
			(xy 89.97458 -45.991243) (xy 90.032804 -45.848078) (xy 90.098321 -45.708101) (xy 90.170957 -45.571681)
			(xy 90.250519 -45.439181) (xy 90.336796 -45.310953) (xy 90.42956 -45.187337) (xy 90.528565 -45.068659)
			(xy 90.633548 -44.955236) (xy 90.74423 -44.847368) (xy 90.860319 -44.74534) (xy 90.981506 -44.649424)
			(xy 91.10747 -44.559873) (xy 91.237877 -44.476926) (xy 91.372381 -44.400801) (xy 91.510626 -44.331702)
			(xy 91.652244 -44.269811) (xy 91.796861 -44.215293) (xy 91.944092 -44.168291) (xy 92.093548 -44.128931)
			(xy 92.244832 -44.097317) (xy 92.397543 -44.073533) (xy 92.551275 -44.057642) (xy 92.705622 -44.049686)
			(xy 92.782898 -44.049188) (xy 94.383098 -44.049188) (xy 94.460374 -44.049669) (xy 94.614722 -44.057625)
			(xy 94.768456 -44.073516) (xy 94.921168 -44.0973) (xy 95.072452 -44.128914) (xy 95.221909 -44.168274)
			(xy 95.369142 -44.215276) (xy 95.513759 -44.269795) (xy 95.655379 -44.331686) (xy 95.793624 -44.400785)
			(xy 95.928129 -44.47691) (xy 96.058537 -44.559858) (xy 96.184502 -44.649409) (xy 96.30569 -44.745326)
			(xy 96.421779 -44.847354) (xy 96.532463 -44.955223) (xy 96.637446 -45.068647) (xy 96.736452 -45.187325)
			(xy 96.829216 -45.310943) (xy 96.915495 -45.439171) (xy 96.995057 -45.571672) (xy 97.038059 -45.652436)
			(xy 155.97378 -45.652436) (xy 155.97378 -44.788836) (xy 155.974266 -44.761567) (xy 155.982028 -44.707583)
			(xy 155.997393 -44.655253) (xy 156.02005 -44.605643) (xy 156.049536 -44.559762) (xy 156.085251 -44.518545)
			(xy 156.126468 -44.48283) (xy 156.172349 -44.453344) (xy 156.221959 -44.430687) (xy 156.274289 -44.415322)
			(xy 156.328273 -44.40756) (xy 156.382811 -44.40756) (xy 156.436795 -44.415322) (xy 156.489125 -44.430687)
			(xy 156.538735 -44.453344) (xy 156.584616 -44.48283) (xy 156.625833 -44.518545) (xy 156.661548 -44.559762)
			(xy 156.691034 -44.605643) (xy 156.713691 -44.655253) (xy 156.72159 -44.682156) (xy 159.179768 -44.682156)
			(xy 159.179768 -43.818556) (xy 159.180254 -43.791287) (xy 159.188016 -43.737303) (xy 159.203381 -43.684973)
			(xy 159.226038 -43.635363) (xy 159.255524 -43.589482) (xy 159.291239 -43.548265) (xy 159.332456 -43.51255)
			(xy 159.378337 -43.483064) (xy 159.427947 -43.460407) (xy 159.480277 -43.445042) (xy 159.534261 -43.43728)
			(xy 159.588799 -43.43728) (xy 159.642783 -43.445042) (xy 159.695113 -43.460407) (xy 159.74185 -43.481752)
			(xy 178.891692 -43.481752) (xy 178.891692 -42.618152) (xy 178.892178 -42.590901) (xy 178.899934 -42.536953)
			(xy 178.915289 -42.484658) (xy 178.937931 -42.435081) (xy 178.967397 -42.389231) (xy 179.003088 -42.34804)
			(xy 179.044279 -42.312349) (xy 179.090129 -42.282883) (xy 179.139706 -42.260241) (xy 179.192001 -42.244886)
			(xy 179.245949 -42.23713) (xy 179.300451 -42.23713) (xy 179.354399 -42.244886) (xy 179.406694 -42.260241)
			(xy 179.456271 -42.282883) (xy 179.502121 -42.312349) (xy 179.543312 -42.34804) (xy 179.579003 -42.389231)
			(xy 179.608469 -42.435081) (xy 179.631111 -42.484658) (xy 179.646466 -42.536953) (xy 179.654222 -42.590901)
			(xy 179.654708 -42.618152) (xy 179.654708 -43.481752) (xy 179.654222 -43.509003) (xy 179.647839 -43.5534)
			(xy 353.767583 -43.5534) (xy 353.771544 -43.500544) (xy 353.783339 -43.44887) (xy 353.802705 -43.39953)
			(xy 353.829208 -43.353628) (xy 353.862256 -43.312189) (xy 353.901112 -43.276139) (xy 353.944908 -43.246283)
			(xy 353.992664 -43.223289) (xy 354.043314 -43.207669) (xy 354.095726 -43.199773) (xy 354.122228 -43.199304)
			(xy 354.122736 -43.199304) (xy 354.153713 -43.199978) (xy 354.214715 -43.210807) (xy 354.272905 -43.232077)
			(xy 354.300028 -43.247056) (xy 354.328004 -43.238767) (xy 354.385663 -43.229845) (xy 354.414836 -43.229276)
			(xy 354.99548 -43.229276) (xy 355.004624 -43.225466) (xy 355.025917 -43.217194) (xy 355.070087 -43.205543)
			(xy 355.115388 -43.199665) (xy 355.138228 -43.199304) (xy 355.162681 -43.199729) (xy 355.211118 -43.206478)
			(xy 355.25817 -43.219815) (xy 355.280722 -43.229276) (xy 355.307866 -43.229907) (xy 355.361565 -43.237931)
			(xy 355.413585 -43.253486) (xy 355.462874 -43.276259) (xy 355.508436 -43.305789) (xy 355.549352 -43.341481)
			(xy 355.584795 -43.382612) (xy 355.61405 -43.428352) (xy 355.636524 -43.477777) (xy 355.651765 -43.52989)
			(xy 355.659465 -43.583636) (xy 355.659944 -43.610784) (xy 355.659468 -43.634951) (xy 356.178591 -43.634951)
			(xy 356.178591 -43.580449) (xy 356.186348 -43.526502) (xy 356.201703 -43.474208) (xy 356.224344 -43.424632)
			(xy 356.253811 -43.378783) (xy 356.289502 -43.337594) (xy 356.330692 -43.301903) (xy 356.376543 -43.272438)
			(xy 356.42612 -43.249799) (xy 356.478414 -43.234445) (xy 356.532361 -43.22669) (xy 356.559612 -43.226228)
			(xy 357.423212 -43.226228) (xy 357.450465 -43.226643) (xy 357.504417 -43.234401) (xy 357.556715 -43.249759)
			(xy 357.606295 -43.272403) (xy 357.652149 -43.301872) (xy 357.693341 -43.337567) (xy 357.729035 -43.378761)
			(xy 357.758503 -43.424615) (xy 357.781145 -43.474196) (xy 357.796501 -43.526495) (xy 357.804258 -43.580447)
			(xy 357.804258 -43.634953) (xy 357.803812 -43.638056) (xy 358.339039 -43.638056) (xy 358.339039 -43.583544)
			(xy 358.346797 -43.529588) (xy 358.362156 -43.477285) (xy 358.384802 -43.4277) (xy 358.414274 -43.381843)
			(xy 358.449974 -43.340648) (xy 358.491172 -43.304953) (xy 358.537032 -43.275485) (xy 358.586619 -43.252843)
			(xy 358.638923 -43.23749) (xy 358.69288 -43.229736) (xy 358.720136 -43.229276) (xy 359.583736 -43.229276)
			(xy 359.610984 -43.229797) (xy 359.664926 -43.237557) (xy 359.717214 -43.252915) (xy 359.766785 -43.275557)
			(xy 359.812629 -43.305023) (xy 359.853813 -43.340713) (xy 359.889499 -43.3819) (xy 359.91896 -43.427747)
			(xy 359.941598 -43.47732) (xy 359.956951 -43.529609) (xy 359.964706 -43.583552) (xy 359.964706 -43.638048)
			(xy 359.956951 -43.691991) (xy 359.941598 -43.74428) (xy 359.91896 -43.793853) (xy 359.889499 -43.8397)
			(xy 359.853813 -43.880887) (xy 359.812629 -43.916577) (xy 359.766785 -43.946043) (xy 359.717214 -43.968685)
			(xy 359.664926 -43.984043) (xy 359.610984 -43.991803) (xy 359.583736 -43.992292) (xy 358.720136 -43.992292)
			(xy 358.69288 -43.991864) (xy 358.638923 -43.98411) (xy 358.586619 -43.968757) (xy 358.537032 -43.946115)
			(xy 358.491172 -43.916647) (xy 358.449974 -43.880952) (xy 358.414274 -43.839757) (xy 358.384802 -43.7939)
			(xy 358.362156 -43.744315) (xy 358.346797 -43.692012) (xy 358.339039 -43.638056) (xy 357.803812 -43.638056)
			(xy 357.796501 -43.688905) (xy 357.781145 -43.741204) (xy 357.758503 -43.790785) (xy 357.729035 -43.836639)
			(xy 357.693341 -43.877833) (xy 357.652149 -43.913528) (xy 357.606295 -43.942997) (xy 357.556715 -43.965641)
			(xy 357.504417 -43.980999) (xy 357.450465 -43.988757) (xy 357.423212 -43.989244) (xy 356.559612 -43.989244)
			(xy 356.532361 -43.98871) (xy 356.478414 -43.980955) (xy 356.42612 -43.965601) (xy 356.376543 -43.942962)
			(xy 356.330692 -43.913497) (xy 356.289502 -43.877806) (xy 356.253811 -43.836617) (xy 356.224344 -43.790768)
			(xy 356.201703 -43.741192) (xy 356.186348 -43.688898) (xy 356.178591 -43.634951) (xy 355.659468 -43.634951)
			(xy 355.659407 -43.638033) (xy 355.651654 -43.691977) (xy 355.636302 -43.744269) (xy 355.613666 -43.793843)
			(xy 355.584204 -43.839692) (xy 355.548518 -43.880882) (xy 355.507334 -43.916573) (xy 355.461489 -43.946041)
			(xy 355.411917 -43.968684) (xy 355.359628 -43.984043) (xy 355.305685 -43.991803) (xy 355.278436 -43.992292)
			(xy 354.414836 -43.992292) (xy 354.388369 -43.991825) (xy 354.335944 -43.984518) (xy 354.285033 -43.970025)
			(xy 354.236619 -43.948625) (xy 354.191633 -43.920731) (xy 354.170996 -43.904154) (xy 354.158864 -43.905712)
			(xy 354.134459 -43.907367) (xy 354.122228 -43.907456) (xy 354.095726 -43.907027) (xy 354.043314 -43.899131)
			(xy 353.992664 -43.883511) (xy 353.944908 -43.860517) (xy 353.901112 -43.830661) (xy 353.862256 -43.794611)
			(xy 353.829208 -43.753172) (xy 353.802705 -43.70727) (xy 353.783339 -43.65793) (xy 353.771544 -43.606256)
			(xy 353.767583 -43.5534) (xy 179.647839 -43.5534) (xy 179.646466 -43.562951) (xy 179.631111 -43.615246)
			(xy 179.608469 -43.664823) (xy 179.579003 -43.710673) (xy 179.543312 -43.751864) (xy 179.502121 -43.787555)
			(xy 179.456271 -43.817021) (xy 179.406694 -43.839663) (xy 179.354399 -43.855018) (xy 179.300451 -43.862774)
			(xy 179.245949 -43.862774) (xy 179.192001 -43.855018) (xy 179.139706 -43.839663) (xy 179.090129 -43.817021)
			(xy 179.044279 -43.787555) (xy 179.003088 -43.751864) (xy 178.967397 -43.710673) (xy 178.937931 -43.664823)
			(xy 178.915289 -43.615246) (xy 178.899934 -43.562951) (xy 178.892178 -43.509003) (xy 178.891692 -43.481752)
			(xy 159.74185 -43.481752) (xy 159.744723 -43.483064) (xy 159.790604 -43.51255) (xy 159.831821 -43.548265)
			(xy 159.867536 -43.589482) (xy 159.897022 -43.635363) (xy 159.919679 -43.684973) (xy 159.935044 -43.737303)
			(xy 159.942806 -43.791287) (xy 159.943292 -43.818556) (xy 159.943292 -44.682156) (xy 159.942806 -44.709425)
			(xy 159.935044 -44.763409) (xy 159.919679 -44.815739) (xy 159.897022 -44.865349) (xy 159.867536 -44.91123)
			(xy 159.831821 -44.952447) (xy 159.79991 -44.980098) (xy 181.659784 -44.980098) (xy 181.659784 -44.116498)
			(xy 181.66027 -44.089247) (xy 181.668026 -44.035299) (xy 181.683381 -43.983004) (xy 181.706023 -43.933427)
			(xy 181.735489 -43.887577) (xy 181.77118 -43.846386) (xy 181.812371 -43.810695) (xy 181.858221 -43.781229)
			(xy 181.907798 -43.758587) (xy 181.960093 -43.743232) (xy 182.014041 -43.735476) (xy 182.068543 -43.735476)
			(xy 182.122491 -43.743232) (xy 182.174786 -43.758587) (xy 182.224363 -43.781229) (xy 182.270213 -43.810695)
			(xy 182.311404 -43.846386) (xy 182.347095 -43.887577) (xy 182.376561 -43.933427) (xy 182.399203 -43.983004)
			(xy 182.414558 -44.035299) (xy 182.422314 -44.089247) (xy 182.4228 -44.116498) (xy 182.4228 -44.840452)
			(xy 348.511075 -44.840452) (xy 348.511075 -44.785948) (xy 348.518832 -44.731999) (xy 348.534188 -44.679702)
			(xy 348.556831 -44.630124) (xy 348.586298 -44.584273) (xy 348.621992 -44.543082) (xy 348.663184 -44.50739)
			(xy 348.709036 -44.477924) (xy 348.758616 -44.455283) (xy 348.810912 -44.439929) (xy 348.864862 -44.432174)
			(xy 348.892114 -44.431712) (xy 349.755714 -44.431712) (xy 349.782966 -44.432159) (xy 349.836915 -44.439917)
			(xy 349.889211 -44.455274) (xy 349.938789 -44.477918) (xy 349.98464 -44.507386) (xy 350.025831 -44.543079)
			(xy 350.061523 -44.584271) (xy 350.090989 -44.630123) (xy 350.11363 -44.679702) (xy 350.128986 -44.731999)
			(xy 350.136742 -44.785948) (xy 350.136742 -44.840452) (xy 350.128986 -44.894401) (xy 350.11363 -44.946698)
			(xy 350.090989 -44.996277) (xy 350.072098 -45.025673) (xy 355.559288 -45.025673) (xy 355.559288 -44.971127)
			(xy 355.56705 -44.917137) (xy 355.582418 -44.864802) (xy 355.605077 -44.815186) (xy 355.634567 -44.7693)
			(xy 355.670288 -44.728078) (xy 355.711511 -44.692359) (xy 355.757398 -44.662871) (xy 355.807015 -44.640213)
			(xy 355.859351 -44.624847) (xy 355.913341 -44.617087) (xy 355.940614 -44.616624) (xy 356.804214 -44.616624)
			(xy 356.831482 -44.617139) (xy 356.885462 -44.624902) (xy 356.937788 -44.640268) (xy 356.987394 -44.662925)
			(xy 357.033272 -44.69241) (xy 357.074486 -44.728124) (xy 357.110199 -44.769339) (xy 357.139682 -44.815218)
			(xy 357.162337 -44.864825) (xy 357.177701 -44.917152) (xy 357.185462 -44.971132) (xy 357.185462 -45.025668)
			(xy 357.177701 -45.079648) (xy 357.162337 -45.131975) (xy 357.139682 -45.181582) (xy 357.110199 -45.227461)
			(xy 357.074486 -45.268676) (xy 357.033272 -45.30439) (xy 356.987394 -45.333875) (xy 356.937788 -45.356532)
			(xy 356.885462 -45.371898) (xy 356.831482 -45.379661) (xy 356.804214 -45.380148) (xy 355.940614 -45.380148)
			(xy 355.913341 -45.379713) (xy 355.859351 -45.371953) (xy 355.807015 -45.356587) (xy 355.757398 -45.333929)
			(xy 355.711511 -45.304441) (xy 355.670288 -45.268722) (xy 355.634567 -45.2275) (xy 355.605077 -45.181614)
			(xy 355.582418 -45.131998) (xy 355.56705 -45.079663) (xy 355.559288 -45.025673) (xy 350.072098 -45.025673)
			(xy 350.061523 -45.042129) (xy 350.025831 -45.083321) (xy 349.98464 -45.119014) (xy 349.938789 -45.148482)
			(xy 349.889211 -45.171126) (xy 349.836915 -45.186483) (xy 349.782966 -45.194241) (xy 349.755714 -45.194728)
			(xy 348.892114 -45.194728) (xy 348.864862 -45.194226) (xy 348.810912 -45.186471) (xy 348.758616 -45.171117)
			(xy 348.709036 -45.148476) (xy 348.663184 -45.11901) (xy 348.621992 -45.083318) (xy 348.586298 -45.042127)
			(xy 348.556831 -44.996276) (xy 348.534188 -44.946698) (xy 348.518832 -44.894401) (xy 348.511075 -44.840452)
			(xy 182.4228 -44.840452) (xy 182.4228 -44.980098) (xy 182.422314 -45.007349) (xy 182.414558 -45.061297)
			(xy 182.399203 -45.113592) (xy 182.376561 -45.163169) (xy 182.347095 -45.209019) (xy 182.311404 -45.25021)
			(xy 182.270213 -45.285901) (xy 182.224363 -45.315367) (xy 182.174786 -45.338009) (xy 182.122491 -45.353364)
			(xy 182.068543 -45.36112) (xy 182.014041 -45.36112) (xy 181.960093 -45.353364) (xy 181.907798 -45.338009)
			(xy 181.858221 -45.315367) (xy 181.812371 -45.285901) (xy 181.77118 -45.25021) (xy 181.735489 -45.209019)
			(xy 181.706023 -45.163169) (xy 181.683381 -45.113592) (xy 181.668026 -45.061297) (xy 181.66027 -45.007349)
			(xy 181.659784 -44.980098) (xy 159.79991 -44.980098) (xy 159.790604 -44.988162) (xy 159.744723 -45.017648)
			(xy 159.695113 -45.040305) (xy 159.642783 -45.05567) (xy 159.588799 -45.063432) (xy 159.534261 -45.063432)
			(xy 159.480277 -45.05567) (xy 159.427947 -45.040305) (xy 159.378337 -45.017648) (xy 159.332456 -44.988162)
			(xy 159.291239 -44.952447) (xy 159.255524 -44.91123) (xy 159.226038 -44.865349) (xy 159.203381 -44.815739)
			(xy 159.188016 -44.763409) (xy 159.180254 -44.709425) (xy 159.179768 -44.682156) (xy 156.72159 -44.682156)
			(xy 156.729056 -44.707583) (xy 156.736818 -44.761567) (xy 156.737304 -44.788836) (xy 156.737304 -45.652436)
			(xy 156.736818 -45.679705) (xy 156.729056 -45.733689) (xy 156.713691 -45.786019) (xy 156.691034 -45.835629)
			(xy 156.661548 -45.88151) (xy 156.625833 -45.922727) (xy 156.584616 -45.958442) (xy 156.538735 -45.987928)
			(xy 156.489125 -46.010585) (xy 156.436795 -46.02595) (xy 156.382811 -46.033712) (xy 156.328273 -46.033712)
			(xy 156.274289 -46.02595) (xy 156.221959 -46.010585) (xy 156.172349 -45.987928) (xy 156.126468 -45.958442)
			(xy 156.085251 -45.922727) (xy 156.049536 -45.88151) (xy 156.02005 -45.835629) (xy 155.997393 -45.786019)
			(xy 155.982028 -45.733689) (xy 155.974266 -45.679705) (xy 155.97378 -45.652436) (xy 97.038059 -45.652436)
			(xy 97.067693 -45.708092) (xy 97.133211 -45.848071) (xy 97.191435 -45.991237) (xy 97.242212 -46.13721)
			(xy 97.285407 -46.285604) (xy 97.320906 -46.436025) (xy 97.329238 -46.481746) (xy 178.630072 -46.481746)
			(xy 178.630072 -45.618146) (xy 178.630558 -45.590895) (xy 178.638314 -45.536947) (xy 178.653669 -45.484652)
			(xy 178.676311 -45.435075) (xy 178.705777 -45.389225) (xy 178.741468 -45.348034) (xy 178.782659 -45.312343)
			(xy 178.828509 -45.282877) (xy 178.878086 -45.260235) (xy 178.930381 -45.24488) (xy 178.984329 -45.237124)
			(xy 179.038831 -45.237124) (xy 179.092779 -45.24488) (xy 179.145074 -45.260235) (xy 179.194651 -45.282877)
			(xy 179.240501 -45.312343) (xy 179.281692 -45.348034) (xy 179.317383 -45.389225) (xy 179.346849 -45.435075)
			(xy 179.369491 -45.484652) (xy 179.384846 -45.536947) (xy 179.392602 -45.590895) (xy 179.393088 -45.618146)
			(xy 179.393088 -46.481746) (xy 179.392602 -46.508997) (xy 179.384846 -46.562945) (xy 179.369491 -46.61524)
			(xy 179.346849 -46.664817) (xy 179.317383 -46.710667) (xy 179.281692 -46.751858) (xy 179.240501 -46.787549)
			(xy 179.194651 -46.817015) (xy 179.145074 -46.839657) (xy 179.092779 -46.855012) (xy 179.038831 -46.862768)
			(xy 178.984329 -46.862768) (xy 178.930381 -46.855012) (xy 178.878086 -46.839657) (xy 178.828509 -46.817015)
			(xy 178.782659 -46.787549) (xy 178.741468 -46.751858) (xy 178.705777 -46.710667) (xy 178.676311 -46.664817)
			(xy 178.653669 -46.61524) (xy 178.638314 -46.562945) (xy 178.630558 -46.508997) (xy 178.630072 -46.481746)
			(xy 97.329238 -46.481746) (xy 97.348615 -46.588073) (xy 97.368459 -46.741347) (xy 97.380387 -46.895438)
			(xy 97.384366 -47.04994) (xy 97.380387 -47.204442) (xy 97.368459 -47.358533) (xy 97.348615 -47.511807)
			(xy 97.320906 -47.663855) (xy 97.285407 -47.814276) (xy 97.242212 -47.96267) (xy 97.239575 -47.97025)
			(xy 155.567386 -47.97025) (xy 155.567386 -47.91575) (xy 155.575142 -47.861805) (xy 155.590495 -47.809513)
			(xy 155.613135 -47.759938) (xy 155.642598 -47.71409) (xy 155.678287 -47.672901) (xy 155.719474 -47.63721)
			(xy 155.765321 -47.607744) (xy 155.814895 -47.585102) (xy 155.867186 -47.569746) (xy 155.92113 -47.561987)
			(xy 155.94838 -47.5615) (xy 156.81198 -47.5615) (xy 156.839234 -47.561946) (xy 156.893189 -47.569701)
			(xy 156.94549 -47.585055) (xy 156.995074 -47.607697) (xy 157.04093 -47.637165) (xy 157.082126 -47.67286)
			(xy 157.117823 -47.714054) (xy 157.147293 -47.759909) (xy 157.169938 -47.809491) (xy 157.185295 -47.861792)
			(xy 157.193053 -47.915746) (xy 157.193053 -47.970249) (xy 158.785586 -47.970249) (xy 158.785586 -47.915751)
			(xy 158.793341 -47.861808) (xy 158.808694 -47.809518) (xy 158.831331 -47.759944) (xy 158.860793 -47.714097)
			(xy 158.89648 -47.672908) (xy 158.937664 -47.637217) (xy 158.983509 -47.607751) (xy 159.03308 -47.585108)
			(xy 159.085369 -47.569749) (xy 159.139311 -47.561988) (xy 159.16656 -47.5615) (xy 160.03016 -47.5615)
			(xy 160.057415 -47.561945) (xy 160.111372 -47.569697) (xy 160.163675 -47.58505) (xy 160.213262 -47.607691)
			(xy 160.259121 -47.637158) (xy 160.300319 -47.672853) (xy 160.336018 -47.714047) (xy 160.36549 -47.759903)
			(xy 160.388136 -47.809487) (xy 160.403494 -47.861789) (xy 160.405067 -47.872729) (xy 167.27856 -47.872729)
			(xy 167.27856 -47.820755) (xy 167.28669 -47.76942) (xy 167.302751 -47.71999) (xy 167.326347 -47.67368)
			(xy 167.356897 -47.631632) (xy 167.393648 -47.594881) (xy 167.435696 -47.564331) (xy 167.482006 -47.540735)
			(xy 167.531436 -47.524674) (xy 167.582771 -47.516544) (xy 167.634745 -47.516544) (xy 167.68608 -47.524674)
			(xy 167.73551 -47.540735) (xy 167.78182 -47.564331) (xy 167.823868 -47.594881) (xy 167.860619 -47.631632)
			(xy 167.891169 -47.67368) (xy 167.914765 -47.71999) (xy 167.930826 -47.76942) (xy 167.938956 -47.820755)
			(xy 167.939466 -47.846742) (xy 167.938956 -47.872729) (xy 167.930826 -47.924064) (xy 167.914765 -47.973494)
			(xy 167.891169 -48.019804) (xy 167.885143 -48.028098) (xy 181.659784 -48.028098) (xy 181.659784 -47.164498)
			(xy 181.66027 -47.137247) (xy 181.668026 -47.083299) (xy 181.683381 -47.031004) (xy 181.706023 -46.981427)
			(xy 181.735489 -46.935577) (xy 181.77118 -46.894386) (xy 181.812371 -46.858695) (xy 181.858221 -46.829229)
			(xy 181.907798 -46.806587) (xy 181.960093 -46.791232) (xy 182.014041 -46.783476) (xy 182.068543 -46.783476)
			(xy 182.122491 -46.791232) (xy 182.174786 -46.806587) (xy 182.224363 -46.829229) (xy 182.225669 -46.830068)
			(xy 356.445326 -46.830068) (xy 356.445326 -46.775532) (xy 356.453087 -46.721552) (xy 356.468451 -46.669225)
			(xy 356.491104 -46.619618) (xy 356.520587 -46.573739) (xy 356.556298 -46.532522) (xy 356.597512 -46.496807)
			(xy 356.643388 -46.467321) (xy 356.692994 -46.444663) (xy 356.745319 -46.429294) (xy 356.799298 -46.421529)
			(xy 356.826566 -46.42104) (xy 357.690166 -46.42104) (xy 357.717439 -46.421497) (xy 357.77143 -46.429255)
			(xy 357.823767 -46.444619) (xy 357.873384 -46.467275) (xy 357.919272 -46.496761) (xy 357.960497 -46.532479)
			(xy 357.996218 -46.5737) (xy 358.025709 -46.619586) (xy 358.048369 -46.669202) (xy 358.063737 -46.721537)
			(xy 358.0715 -46.775527) (xy 358.0715 -46.830069) (xy 358.762026 -46.830069) (xy 358.762026 -46.775531)
			(xy 358.769788 -46.721547) (xy 358.785153 -46.669218) (xy 358.807809 -46.619608) (xy 358.837295 -46.573728)
			(xy 358.87301 -46.53251) (xy 358.914228 -46.496795) (xy 358.960108 -46.467309) (xy 359.009718 -46.444653)
			(xy 359.062047 -46.429288) (xy 359.116031 -46.421526) (xy 359.1433 -46.42104) (xy 360.0069 -46.42104)
			(xy 360.03417 -46.421522) (xy 360.088153 -46.429284) (xy 360.140483 -46.44465) (xy 360.190094 -46.467306)
			(xy 360.235975 -46.496792) (xy 360.277193 -46.532507) (xy 360.312908 -46.573725) (xy 360.342394 -46.619606)
			(xy 360.36505 -46.669217) (xy 360.380416 -46.721547) (xy 360.388178 -46.77553) (xy 360.388178 -46.83007)
			(xy 360.388178 -46.830073) (xy 361.088604 -46.830073) (xy 361.088604 -46.775527) (xy 361.096367 -46.721537)
			(xy 361.111735 -46.669202) (xy 361.134395 -46.619586) (xy 361.163887 -46.573701) (xy 361.199608 -46.53248)
			(xy 361.240833 -46.496763) (xy 361.286721 -46.467276) (xy 361.336339 -46.444621) (xy 361.388676 -46.429258)
			(xy 361.442667 -46.421501) (xy 361.46994 -46.42104) (xy 362.33354 -46.42104) (xy 362.360808 -46.421525)
			(xy 362.414787 -46.429291) (xy 362.467112 -46.44466) (xy 362.516718 -46.467319) (xy 362.562594 -46.496806)
			(xy 362.603807 -46.532522) (xy 362.639518 -46.573738) (xy 362.669 -46.619618) (xy 362.691654 -46.669225)
			(xy 362.707017 -46.721552) (xy 362.714778 -46.775532) (xy 362.714778 -46.830068) (xy 362.707017 -46.884048)
			(xy 362.691654 -46.936375) (xy 362.672751 -46.977768) (xy 396.642323 -46.977768) (xy 396.642323 -46.891996)
			(xy 396.650237 -46.806588) (xy 396.665998 -46.722276) (xy 396.689471 -46.639777) (xy 396.720456 -46.559796)
			(xy 396.758688 -46.483015) (xy 396.803842 -46.41009) (xy 396.855532 -46.341642) (xy 396.913317 -46.278255)
			(xy 396.976704 -46.22047) (xy 397.045152 -46.16878) (xy 397.118077 -46.123626) (xy 397.194858 -46.085394)
			(xy 397.274839 -46.054409) (xy 397.357338 -46.030936) (xy 397.44165 -46.015175) (xy 397.527058 -46.007261)
			(xy 397.61283 -46.007261) (xy 397.698238 -46.015175) (xy 397.78255 -46.030936) (xy 397.865049 -46.054409)
			(xy 397.94503 -46.085394) (xy 398.021811 -46.123626) (xy 398.094736 -46.16878) (xy 398.163184 -46.22047)
			(xy 398.226571 -46.278255) (xy 398.284356 -46.341642) (xy 398.336046 -46.41009) (xy 398.3812 -46.483015)
			(xy 398.419432 -46.559796) (xy 398.450417 -46.639777) (xy 398.47389 -46.722276) (xy 398.489651 -46.806588)
			(xy 398.497565 -46.891996) (xy 398.49806 -46.934882) (xy 398.497565 -46.977768) (xy 398.489651 -47.063176)
			(xy 398.47389 -47.147488) (xy 398.450417 -47.229987) (xy 398.419432 -47.309968) (xy 398.3812 -47.386749)
			(xy 398.336046 -47.459674) (xy 398.284356 -47.528122) (xy 398.226571 -47.591509) (xy 398.163184 -47.649294)
			(xy 398.094736 -47.700984) (xy 398.021811 -47.746138) (xy 397.94503 -47.78437) (xy 397.865049 -47.815355)
			(xy 397.78255 -47.838828) (xy 397.698238 -47.854589) (xy 397.61283 -47.862503) (xy 397.527058 -47.862503)
			(xy 397.44165 -47.854589) (xy 397.357338 -47.838828) (xy 397.274839 -47.815355) (xy 397.194858 -47.78437)
			(xy 397.118077 -47.746138) (xy 397.045152 -47.700984) (xy 396.976704 -47.649294) (xy 396.913317 -47.591509)
			(xy 396.855532 -47.528122) (xy 396.803842 -47.459674) (xy 396.758688 -47.386749) (xy 396.720456 -47.309968)
			(xy 396.689471 -47.229987) (xy 396.665998 -47.147488) (xy 396.650237 -47.063176) (xy 396.642323 -46.977768)
			(xy 362.672751 -46.977768) (xy 362.669 -46.985982) (xy 362.639518 -47.031862) (xy 362.603807 -47.073078)
			(xy 362.562594 -47.108794) (xy 362.516718 -47.138281) (xy 362.467112 -47.16094) (xy 362.414787 -47.176309)
			(xy 362.360808 -47.184075) (xy 362.33354 -47.184564) (xy 361.46994 -47.184564) (xy 361.442667 -47.184099)
			(xy 361.388676 -47.176342) (xy 361.336339 -47.160979) (xy 361.286721 -47.138324) (xy 361.240833 -47.108837)
			(xy 361.199608 -47.07312) (xy 361.163887 -47.031899) (xy 361.134395 -46.986014) (xy 361.111735 -46.936398)
			(xy 361.096367 -46.884063) (xy 361.088604 -46.830073) (xy 360.388178 -46.830073) (xy 360.380416 -46.884053)
			(xy 360.36505 -46.936383) (xy 360.342394 -46.985994) (xy 360.312908 -47.031875) (xy 360.277193 -47.073093)
			(xy 360.235975 -47.108808) (xy 360.190094 -47.138294) (xy 360.140483 -47.16095) (xy 360.088153 -47.176316)
			(xy 360.03417 -47.184078) (xy 360.0069 -47.184564) (xy 359.1433 -47.184564) (xy 359.116031 -47.184074)
			(xy 359.062047 -47.176312) (xy 359.009718 -47.160947) (xy 358.960108 -47.138291) (xy 358.914228 -47.108805)
			(xy 358.87301 -47.07309) (xy 358.837295 -47.031872) (xy 358.807809 -46.985992) (xy 358.785153 -46.936382)
			(xy 358.769788 -46.884053) (xy 358.762026 -46.830069) (xy 358.0715 -46.830069) (xy 358.0715 -46.830073)
			(xy 358.063737 -46.884063) (xy 358.048369 -46.936398) (xy 358.025709 -46.986014) (xy 357.996218 -47.0319)
			(xy 357.960497 -47.073121) (xy 357.919272 -47.108839) (xy 357.873384 -47.138325) (xy 357.823767 -47.160981)
			(xy 357.77143 -47.176345) (xy 357.717439 -47.184103) (xy 357.690166 -47.184564) (xy 356.826566 -47.184564)
			(xy 356.799298 -47.184071) (xy 356.745319 -47.176306) (xy 356.692994 -47.160937) (xy 356.643388 -47.138279)
			(xy 356.597512 -47.108793) (xy 356.556298 -47.073078) (xy 356.520587 -47.031861) (xy 356.491104 -46.985982)
			(xy 356.468451 -46.936375) (xy 356.453087 -46.884048) (xy 356.445326 -46.830068) (xy 182.225669 -46.830068)
			(xy 182.270213 -46.858695) (xy 182.311404 -46.894386) (xy 182.347095 -46.935577) (xy 182.376561 -46.981427)
			(xy 182.399203 -47.031004) (xy 182.414558 -47.083299) (xy 182.422314 -47.137247) (xy 182.4228 -47.164498)
			(xy 182.4228 -48.028098) (xy 182.422314 -48.055349) (xy 182.414558 -48.109297) (xy 182.399203 -48.161592)
			(xy 182.376561 -48.211169) (xy 182.347095 -48.257019) (xy 182.311404 -48.29821) (xy 182.270213 -48.333901)
			(xy 182.224363 -48.363367) (xy 182.174786 -48.386009) (xy 182.122491 -48.401364) (xy 182.068543 -48.40912)
			(xy 182.014041 -48.40912) (xy 181.960093 -48.401364) (xy 181.907798 -48.386009) (xy 181.858221 -48.363367)
			(xy 181.812371 -48.333901) (xy 181.77118 -48.29821) (xy 181.735489 -48.257019) (xy 181.706023 -48.211169)
			(xy 181.683381 -48.161592) (xy 181.668026 -48.109297) (xy 181.66027 -48.055349) (xy 181.659784 -48.028098)
			(xy 167.885143 -48.028098) (xy 167.860619 -48.061852) (xy 167.823868 -48.098603) (xy 167.78182 -48.129153)
			(xy 167.73551 -48.152749) (xy 167.68608 -48.16881) (xy 167.634745 -48.17694) (xy 167.582771 -48.17694)
			(xy 167.531436 -48.16881) (xy 167.482006 -48.152749) (xy 167.435696 -48.129153) (xy 167.393648 -48.098603)
			(xy 167.356897 -48.061852) (xy 167.326347 -48.019804) (xy 167.302751 -47.973494) (xy 167.28669 -47.924064)
			(xy 167.27856 -47.872729) (xy 160.405067 -47.872729) (xy 160.411253 -47.915745) (xy 160.411253 -47.970255)
			(xy 160.403494 -48.024211) (xy 160.388136 -48.076513) (xy 160.36549 -48.126097) (xy 160.336018 -48.171953)
			(xy 160.300319 -48.213147) (xy 160.259121 -48.248842) (xy 160.213262 -48.278309) (xy 160.163675 -48.30095)
			(xy 160.111372 -48.316303) (xy 160.057415 -48.324055) (xy 160.03016 -48.324516) (xy 159.16656 -48.324516)
			(xy 159.139311 -48.324012) (xy 159.085369 -48.316251) (xy 159.03308 -48.300892) (xy 158.983509 -48.278249)
			(xy 158.937664 -48.248783) (xy 158.89648 -48.213092) (xy 158.860793 -48.171903) (xy 158.831331 -48.126056)
			(xy 158.808694 -48.076482) (xy 158.793341 -48.024192) (xy 158.785586 -47.970249) (xy 157.193053 -47.970249)
			(xy 157.193053 -47.970254) (xy 157.185295 -48.024208) (xy 157.169938 -48.076509) (xy 157.147293 -48.126091)
			(xy 157.117823 -48.171946) (xy 157.082126 -48.21314) (xy 157.04093 -48.248835) (xy 156.995074 -48.278303)
			(xy 156.94549 -48.300945) (xy 156.893189 -48.316299) (xy 156.839234 -48.324054) (xy 156.81198 -48.324516)
			(xy 155.94838 -48.324516) (xy 155.92113 -48.324013) (xy 155.867186 -48.316254) (xy 155.814895 -48.300898)
			(xy 155.765321 -48.278256) (xy 155.719474 -48.24879) (xy 155.678287 -48.213099) (xy 155.642598 -48.17191)
			(xy 155.613135 -48.126062) (xy 155.590495 -48.076487) (xy 155.575142 -48.024195) (xy 155.567386 -47.97025)
			(xy 97.239575 -47.97025) (xy 97.191435 -48.108643) (xy 97.133211 -48.251809) (xy 97.067693 -48.391788)
			(xy 96.995057 -48.528208) (xy 96.915495 -48.660709) (xy 96.829216 -48.788937) (xy 96.754492 -48.888515)
			(xy 167.276783 -48.888515) (xy 167.276783 -48.836461) (xy 167.284926 -48.785048) (xy 167.301011 -48.735541)
			(xy 167.324643 -48.689161) (xy 167.35524 -48.647048) (xy 167.392048 -48.61024) (xy 167.434161 -48.579643)
			(xy 167.480541 -48.556011) (xy 167.530048 -48.539926) (xy 167.581461 -48.531783) (xy 167.633515 -48.531783)
			(xy 167.684928 -48.539926) (xy 167.734435 -48.556011) (xy 167.780815 -48.579643) (xy 167.822928 -48.61024)
			(xy 167.859736 -48.647048) (xy 167.890333 -48.689161) (xy 167.913965 -48.735541) (xy 167.93005 -48.785048)
			(xy 167.938193 -48.836461) (xy 167.938704 -48.862488) (xy 167.938193 -48.888515) (xy 167.93005 -48.939928)
			(xy 167.913965 -48.989435) (xy 167.890333 -49.035815) (xy 167.859736 -49.077928) (xy 167.822928 -49.114736)
			(xy 167.780815 -49.145333) (xy 167.734435 -49.168965) (xy 167.684928 -49.18505) (xy 167.633515 -49.193193)
			(xy 167.581461 -49.193193) (xy 167.530048 -49.18505) (xy 167.480541 -49.168965) (xy 167.434161 -49.145333)
			(xy 167.392048 -49.114736) (xy 167.35524 -49.077928) (xy 167.324643 -49.035815) (xy 167.301011 -48.989435)
			(xy 167.284926 -48.939928) (xy 167.276783 -48.888515) (xy 96.754492 -48.888515) (xy 96.736452 -48.912555)
			(xy 96.637446 -49.031233) (xy 96.532463 -49.144657) (xy 96.421779 -49.252526) (xy 96.30569 -49.354554)
			(xy 96.184502 -49.450471) (xy 96.140518 -49.48174) (xy 178.630072 -49.48174) (xy 178.630072 -48.61814)
			(xy 178.630558 -48.590889) (xy 178.638314 -48.536941) (xy 178.653669 -48.484646) (xy 178.676311 -48.435069)
			(xy 178.705777 -48.389219) (xy 178.741468 -48.348028) (xy 178.782659 -48.312337) (xy 178.828509 -48.282871)
			(xy 178.878086 -48.260229) (xy 178.930381 -48.244874) (xy 178.984329 -48.237118) (xy 179.038831 -48.237118)
			(xy 179.092779 -48.244874) (xy 179.145074 -48.260229) (xy 179.194651 -48.282871) (xy 179.240501 -48.312337)
			(xy 179.281692 -48.348028) (xy 179.317383 -48.389219) (xy 179.346849 -48.435069) (xy 179.369491 -48.484646)
			(xy 179.384846 -48.536941) (xy 179.392602 -48.590889) (xy 179.393088 -48.61814) (xy 179.393088 -49.48174)
			(xy 179.392602 -49.508991) (xy 179.384846 -49.562939) (xy 179.369491 -49.615234) (xy 179.346849 -49.664811)
			(xy 179.317383 -49.710661) (xy 179.281692 -49.751852) (xy 179.240501 -49.787543) (xy 179.194651 -49.817009)
			(xy 179.145074 -49.839651) (xy 179.092779 -49.855006) (xy 179.038831 -49.862762) (xy 178.984329 -49.862762)
			(xy 178.930381 -49.855006) (xy 178.878086 -49.839651) (xy 178.828509 -49.817009) (xy 178.782659 -49.787543)
			(xy 178.741468 -49.751852) (xy 178.705777 -49.710661) (xy 178.676311 -49.664811) (xy 178.653669 -49.615234)
			(xy 178.638314 -49.562939) (xy 178.630558 -49.508991) (xy 178.630072 -49.48174) (xy 96.140518 -49.48174)
			(xy 96.058537 -49.540022) (xy 95.928129 -49.62297) (xy 95.793624 -49.699095) (xy 95.655379 -49.768194)
			(xy 95.513759 -49.830085) (xy 95.369142 -49.884604) (xy 95.221909 -49.931606) (xy 95.072452 -49.970966)
			(xy 94.921168 -50.00258) (xy 94.768456 -50.026364) (xy 94.614722 -50.042255) (xy 94.460374 -50.050211)
			(xy 94.383098 -50.0507) (xy 92.782898 -50.0507) (xy 92.705622 -50.050194) (xy 92.551275 -50.042238)
			(xy 92.397543 -50.026347) (xy 92.244832 -50.002563) (xy 92.093548 -49.970949) (xy 91.944092 -49.931589)
			(xy 91.796861 -49.884587) (xy 91.652244 -49.830069) (xy 91.510626 -49.768178) (xy 91.372381 -49.699079)
			(xy 91.237877 -49.622954) (xy 91.10747 -49.540007) (xy 90.981506 -49.450456) (xy 90.860319 -49.35454)
			(xy 90.74423 -49.252512) (xy 90.633548 -49.144644) (xy 90.528565 -49.031221) (xy 90.42956 -48.912543)
			(xy 90.336796 -48.788927) (xy 90.250519 -48.660699) (xy 90.170957 -48.528199) (xy 90.098321 -48.391779)
			(xy 90.032804 -48.251802) (xy 89.97458 -48.108637) (xy 89.923803 -47.962664) (xy 89.880608 -47.814271)
			(xy 89.84511 -47.663852) (xy 89.817402 -47.511804) (xy 89.797557 -47.358531) (xy 89.78563 -47.204441)
			(xy 89.78165 -47.04994) (xy 67.384154 -47.04994) (xy 67.384157 -47.050067) (xy 67.380172 -47.204564)
			(xy 67.368238 -47.35865) (xy 67.348389 -47.511918) (xy 67.320675 -47.663961) (xy 67.285172 -47.814376)
			(xy 67.241973 -47.962763) (xy 67.191193 -48.108731) (xy 67.132966 -48.25189) (xy 67.067447 -48.391863)
			(xy 66.994809 -48.528277) (xy 66.915245 -48.660771) (xy 66.828966 -48.788993) (xy 66.736201 -48.912605)
			(xy 66.637196 -49.031277) (xy 66.532213 -49.144695) (xy 66.421531 -49.252559) (xy 66.305444 -49.354582)
			(xy 66.184258 -49.450493) (xy 66.058295 -49.54004) (xy 65.927891 -49.622983) (xy 65.793389 -49.699104)
			(xy 65.655147 -49.768199) (xy 65.513531 -49.830087) (xy 65.368918 -49.884603) (xy 65.22169 -49.931602)
			(xy 65.072237 -49.970961) (xy 64.920957 -50.002573) (xy 64.76825 -50.026356) (xy 64.614521 -50.042247)
			(xy 64.460178 -50.050202) (xy 64.382904 -50.0507) (xy 62.78245 -50.0507) (xy 62.705176 -50.050188)
			(xy 62.550834 -50.04222) (xy 62.397107 -50.026316) (xy 62.244402 -50.002521) (xy 62.093124 -49.970896)
			(xy 61.943675 -49.931526) (xy 61.796451 -49.884514) (xy 61.651842 -49.829987) (xy 61.510232 -49.768087)
			(xy 61.371996 -49.69898) (xy 61.2375 -49.622848) (xy 61.107102 -49.539894) (xy 60.981148 -49.450337)
			(xy 60.85997 -49.354416) (xy 60.743891 -49.252383) (xy 60.633218 -49.14451) (xy 60.528245 -49.031083)
			(xy 60.429249 -48.912403) (xy 60.336495 -48.788784) (xy 60.250227 -48.660555) (xy 60.170674 -48.528054)
			(xy 60.098048 -48.391634) (xy 60.032541 -48.251656) (xy 59.974326 -48.108492) (xy 59.923558 -47.96252)
			(xy 59.880371 -47.814129) (xy 59.844881 -47.663712) (xy 59.81718 -47.511667) (xy 59.797344 -47.358397)
			(xy 59.785423 -47.20431) (xy 59.781451 -47.049813) (xy 0.509016 -47.049813) (xy 0.509016 -50.949098)
			(xy 181.659784 -50.949098) (xy 181.659784 -50.085498) (xy 181.66027 -50.058247) (xy 181.668026 -50.004299)
			(xy 181.683381 -49.952004) (xy 181.706023 -49.902427) (xy 181.735489 -49.856577) (xy 181.77118 -49.815386)
			(xy 181.812371 -49.779695) (xy 181.858221 -49.750229) (xy 181.907798 -49.727587) (xy 181.960093 -49.712232)
			(xy 182.014041 -49.704476) (xy 182.068543 -49.704476) (xy 182.122491 -49.712232) (xy 182.174786 -49.727587)
			(xy 182.224363 -49.750229) (xy 182.270213 -49.779695) (xy 182.311404 -49.815386) (xy 182.347095 -49.856577)
			(xy 182.376561 -49.902427) (xy 182.399203 -49.952004) (xy 182.414558 -50.004299) (xy 182.422314 -50.058247)
			(xy 182.4228 -50.085498) (xy 182.4228 -50.949098) (xy 182.422314 -50.976349) (xy 182.414558 -51.030297)
			(xy 182.399203 -51.082592) (xy 182.376561 -51.132169) (xy 182.347095 -51.178019) (xy 182.311404 -51.21921)
			(xy 182.270213 -51.254901) (xy 182.224363 -51.284367) (xy 182.174786 -51.307009) (xy 182.122491 -51.322364)
			(xy 182.068543 -51.33012) (xy 182.014041 -51.33012) (xy 181.960093 -51.322364) (xy 181.907798 -51.307009)
			(xy 181.858221 -51.284367) (xy 181.812371 -51.254901) (xy 181.77118 -51.21921) (xy 181.735489 -51.178019)
			(xy 181.706023 -51.132169) (xy 181.683381 -51.082592) (xy 181.668026 -51.030297) (xy 181.66027 -50.976349)
			(xy 181.659784 -50.949098) (xy 0.509016 -50.949098) (xy 0.509016 -52.481734) (xy 178.630072 -52.481734)
			(xy 178.630072 -51.618134) (xy 178.630558 -51.590883) (xy 178.638314 -51.536935) (xy 178.653669 -51.48464)
			(xy 178.676311 -51.435063) (xy 178.705777 -51.389213) (xy 178.741468 -51.348022) (xy 178.782659 -51.312331)
			(xy 178.828509 -51.282865) (xy 178.878086 -51.260223) (xy 178.930381 -51.244868) (xy 178.984329 -51.237112)
			(xy 179.038831 -51.237112) (xy 179.092779 -51.244868) (xy 179.145074 -51.260223) (xy 179.194651 -51.282865)
			(xy 179.240501 -51.312331) (xy 179.281692 -51.348022) (xy 179.317383 -51.389213) (xy 179.346849 -51.435063)
			(xy 179.369491 -51.48464) (xy 179.384846 -51.536935) (xy 179.392602 -51.590883) (xy 179.393088 -51.618134)
			(xy 179.393088 -51.999896) (xy 201.367397 -51.999896) (xy 201.371407 -51.837793) (xy 201.38343 -51.676088)
			(xy 201.403434 -51.515174) (xy 201.431372 -51.355447) (xy 201.467175 -51.197297) (xy 201.510755 -51.041111)
			(xy 201.562006 -50.887271) (xy 201.620802 -50.736154) (xy 201.687 -50.58813) (xy 201.760436 -50.44356)
			(xy 201.840933 -50.302799) (xy 201.928292 -50.166191) (xy 202.0223 -50.034071) (xy 202.122727 -49.906761)
			(xy 202.229327 -49.784573) (xy 202.341839 -49.667807) (xy 202.459987 -49.556748) (xy 202.583484 -49.451667)
			(xy 202.712026 -49.352823) (xy 202.845299 -49.260456) (xy 202.982977 -49.174793) (xy 203.124723 -49.096044)
			(xy 203.27019 -49.024401) (xy 203.419022 -48.960039) (xy 203.570854 -48.903117) (xy 203.725316 -48.853773)
			(xy 203.882029 -48.812128) (xy 204.04061 -48.778283) (xy 204.200671 -48.752323) (xy 204.361819 -48.73431)
			(xy 204.523661 -48.724289) (xy 204.685801 -48.722283) (xy 204.847842 -48.728299) (xy 205.009386 -48.74232)
			(xy 205.17004 -48.764313) (xy 205.32941 -48.794225) (xy 205.487105 -48.831981) (xy 205.64274 -48.877489)
			(xy 205.795934 -48.930639) (xy 205.946312 -48.9913) (xy 206.093507 -49.059323) (xy 206.237157 -49.134542)
			(xy 206.376912 -49.216773) (xy 206.512428 -49.305815) (xy 206.643376 -49.40145) (xy 206.769434 -49.503444)
			(xy 206.890294 -49.611547) (xy 207.00566 -49.725494) (xy 207.115249 -49.845008) (xy 207.218794 -49.969795)
			(xy 207.316041 -50.09955) (xy 207.406753 -50.233955) (xy 207.424818 -50.263806) (xy 239.457992 -50.263806)
			(xy 239.457992 -49.400206) (xy 239.458478 -49.372955) (xy 239.466234 -49.319007) (xy 239.481589 -49.266712)
			(xy 239.504231 -49.217135) (xy 239.533697 -49.171285) (xy 239.569388 -49.130094) (xy 239.610579 -49.094403)
			(xy 239.656429 -49.064937) (xy 239.706006 -49.042295) (xy 239.758301 -49.02694) (xy 239.812249 -49.019184)
			(xy 239.866751 -49.019184) (xy 239.920699 -49.02694) (xy 239.972994 -49.042295) (xy 240.022571 -49.064937)
			(xy 240.068421 -49.094403) (xy 240.109612 -49.130094) (xy 240.145303 -49.171285) (xy 240.174769 -49.217135)
			(xy 240.197411 -49.266712) (xy 240.212766 -49.319007) (xy 240.220522 -49.372955) (xy 240.221008 -49.400206)
			(xy 240.221008 -50.263806) (xy 240.220522 -50.291057) (xy 240.212766 -50.345005) (xy 240.197411 -50.3973)
			(xy 240.174769 -50.446877) (xy 240.145303 -50.492727) (xy 240.109612 -50.533918) (xy 240.068421 -50.569609)
			(xy 240.022571 -50.599075) (xy 239.972994 -50.621717) (xy 239.920699 -50.637072) (xy 239.866751 -50.644828)
			(xy 239.812249 -50.644828) (xy 239.758301 -50.637072) (xy 239.706006 -50.621717) (xy 239.656429 -50.599075)
			(xy 239.610579 -50.569609) (xy 239.569388 -50.533918) (xy 239.533697 -50.492727) (xy 239.504231 -50.446877)
			(xy 239.481589 -50.3973) (xy 239.466234 -50.345005) (xy 239.458478 -50.291057) (xy 239.457992 -50.263806)
			(xy 207.424818 -50.263806) (xy 207.490706 -50.372682) (xy 207.567696 -50.515391) (xy 207.637535 -50.661732)
			(xy 207.70005 -50.811349) (xy 207.755091 -50.963874) (xy 207.802521 -51.118934) (xy 207.842224 -51.27615)
			(xy 207.874105 -51.435138) (xy 207.898083 -51.595507) (xy 207.914102 -51.756866) (xy 207.922121 -51.91882)
			(xy 207.922622 -51.999896) (xy 207.922121 -52.080972) (xy 207.914102 -52.242926) (xy 207.898083 -52.404285)
			(xy 207.874105 -52.564654) (xy 207.842224 -52.723642) (xy 207.802521 -52.880858) (xy 207.794624 -52.906676)
			(xy 228.815392 -52.906676) (xy 228.815392 -52.043076) (xy 228.815878 -52.015825) (xy 228.823634 -51.961877)
			(xy 228.838989 -51.909582) (xy 228.861631 -51.860005) (xy 228.891097 -51.814155) (xy 228.926788 -51.772964)
			(xy 228.967979 -51.737273) (xy 229.013829 -51.707807) (xy 229.063406 -51.685165) (xy 229.115701 -51.66981)
			(xy 229.169649 -51.662054) (xy 229.224151 -51.662054) (xy 229.278099 -51.66981) (xy 229.330394 -51.685165)
			(xy 229.379971 -51.707807) (xy 229.425821 -51.737273) (xy 229.467012 -51.772964) (xy 229.502703 -51.814155)
			(xy 229.532169 -51.860005) (xy 229.554811 -51.909582) (xy 229.570166 -51.961877) (xy 229.577922 -52.015825)
			(xy 229.578408 -52.043076) (xy 229.578408 -52.90185) (xy 241.926872 -52.90185) (xy 241.926872 -52.03825)
			(xy 241.927358 -52.010999) (xy 241.935114 -51.957051) (xy 241.950469 -51.904756) (xy 241.973111 -51.855179)
			(xy 242.002577 -51.809329) (xy 242.038268 -51.768138) (xy 242.079459 -51.732447) (xy 242.125309 -51.702981)
			(xy 242.174886 -51.680339) (xy 242.227181 -51.664984) (xy 242.281129 -51.657228) (xy 242.335631 -51.657228)
			(xy 242.389579 -51.664984) (xy 242.441874 -51.680339) (xy 242.491451 -51.702981) (xy 242.537301 -51.732447)
			(xy 242.578492 -51.768138) (xy 242.614183 -51.809329) (xy 242.643649 -51.855179) (xy 242.666291 -51.904756)
			(xy 242.681646 -51.957051) (xy 242.687806 -51.999896) (xy 265.367269 -51.999896) (xy 265.371279 -51.837793)
			(xy 265.383302 -51.676088) (xy 265.403306 -51.515174) (xy 265.431244 -51.355447) (xy 265.467047 -51.197297)
			(xy 265.510627 -51.041111) (xy 265.561878 -50.887271) (xy 265.620674 -50.736154) (xy 265.686872 -50.58813)
			(xy 265.760308 -50.44356) (xy 265.840805 -50.302799) (xy 265.928164 -50.166191) (xy 266.022172 -50.034071)
			(xy 266.122599 -49.906761) (xy 266.229199 -49.784573) (xy 266.341711 -49.667807) (xy 266.459859 -49.556748)
			(xy 266.583356 -49.451667) (xy 266.711898 -49.352823) (xy 266.845171 -49.260456) (xy 266.982849 -49.174793)
			(xy 267.124595 -49.096044) (xy 267.270062 -49.024401) (xy 267.418894 -48.960039) (xy 267.570726 -48.903117)
			(xy 267.725188 -48.853773) (xy 267.881901 -48.812128) (xy 268.040482 -48.778283) (xy 268.200543 -48.752323)
			(xy 268.361691 -48.73431) (xy 268.523533 -48.724289) (xy 268.685673 -48.722283) (xy 268.847714 -48.728299)
			(xy 269.009258 -48.74232) (xy 269.169912 -48.764313) (xy 269.329282 -48.794225) (xy 269.486977 -48.831981)
			(xy 269.642612 -48.877489) (xy 269.795806 -48.930639) (xy 269.946184 -48.9913) (xy 270.093379 -49.059323)
			(xy 270.237029 -49.134542) (xy 270.376784 -49.216773) (xy 270.5123 -49.305815) (xy 270.643248 -49.40145)
			(xy 270.769306 -49.503444) (xy 270.890166 -49.611547) (xy 271.005532 -49.725494) (xy 271.115121 -49.845008)
			(xy 271.218666 -49.969795) (xy 271.315913 -50.09955) (xy 271.406625 -50.233955) (xy 271.40723 -50.234955)
			(xy 350.291827 -50.234955) (xy 350.291827 -50.180445) (xy 350.299585 -50.126489) (xy 350.314942 -50.074187)
			(xy 350.337587 -50.024602) (xy 350.367058 -49.978745) (xy 350.402755 -49.937549) (xy 350.443952 -49.901853)
			(xy 350.489809 -49.872383) (xy 350.539394 -49.849739) (xy 350.591697 -49.834383) (xy 350.645653 -49.826626)
			(xy 350.672908 -49.826164) (xy 351.536508 -49.826164) (xy 351.563757 -49.826707) (xy 351.6177 -49.834464)
			(xy 351.66999 -49.849818) (xy 351.719562 -49.872458) (xy 351.765408 -49.901922) (xy 351.806594 -49.937611)
			(xy 351.842282 -49.978798) (xy 351.871746 -50.024645) (xy 351.894385 -50.074218) (xy 351.909738 -50.126508)
			(xy 351.917494 -50.180451) (xy 351.917494 -50.234949) (xy 351.917493 -50.234956) (xy 352.489927 -50.234956)
			(xy 352.489927 -50.180444) (xy 352.497685 -50.126487) (xy 352.513044 -50.074183) (xy 352.535689 -50.024598)
			(xy 352.565162 -49.97874) (xy 352.600861 -49.937544) (xy 352.642059 -49.901848) (xy 352.687919 -49.872378)
			(xy 352.737506 -49.849735) (xy 352.78981 -49.83438) (xy 352.843768 -49.826625) (xy 352.871024 -49.826164)
			(xy 353.734624 -49.826164) (xy 353.761872 -49.826708) (xy 353.815813 -49.834467) (xy 353.868101 -49.849823)
			(xy 353.917672 -49.872463) (xy 353.963516 -49.901928) (xy 354.0047 -49.937617) (xy 354.040386 -49.978804)
			(xy 354.069848 -50.024649) (xy 354.092486 -50.074221) (xy 354.107839 -50.12651) (xy 354.115594 -50.180452)
			(xy 354.115594 -50.234948) (xy 354.115593 -50.234956) (xy 354.712427 -50.234956) (xy 354.712427 -50.180444)
			(xy 354.720185 -50.126487) (xy 354.735544 -50.074183) (xy 354.758189 -50.024598) (xy 354.787662 -49.97874)
			(xy 354.823361 -49.937544) (xy 354.864559 -49.901848) (xy 354.910419 -49.872378) (xy 354.960006 -49.849735)
			(xy 355.01231 -49.83438) (xy 355.066268 -49.826625) (xy 355.093524 -49.826164) (xy 355.957124 -49.826164)
			(xy 355.984372 -49.826708) (xy 356.038313 -49.834467) (xy 356.090601 -49.849823) (xy 356.140172 -49.872463)
			(xy 356.186016 -49.901928) (xy 356.2272 -49.937617) (xy 356.262886 -49.978804) (xy 356.292348 -50.024649)
			(xy 356.314986 -50.074221) (xy 356.330339 -50.12651) (xy 356.338094 -50.180452) (xy 356.338094 -50.234948)
			(xy 356.338093 -50.234957) (xy 356.942527 -50.234957) (xy 356.942527 -50.180443) (xy 356.950286 -50.126484)
			(xy 356.965645 -50.074179) (xy 356.988293 -50.024592) (xy 357.017767 -49.978734) (xy 357.053468 -49.937537)
			(xy 357.094669 -49.90184) (xy 357.140531 -49.872371) (xy 357.19012 -49.84973) (xy 357.242427 -49.834376)
			(xy 357.296387 -49.826624) (xy 357.323644 -49.826164) (xy 358.187244 -49.826164) (xy 358.214491 -49.826709)
			(xy 358.26843 -49.83447) (xy 358.320716 -49.849828) (xy 358.370284 -49.87247) (xy 358.416125 -49.901935)
			(xy 358.457307 -49.937624) (xy 358.492991 -49.97881) (xy 358.522451 -50.024655) (xy 358.545087 -50.074226)
			(xy 358.560439 -50.126513) (xy 358.568194 -50.180453) (xy 358.568194 -50.234947) (xy 358.560439 -50.288887)
			(xy 358.545087 -50.341174) (xy 358.522451 -50.390745) (xy 358.492991 -50.43659) (xy 358.457307 -50.477776)
			(xy 358.416125 -50.513465) (xy 358.370284 -50.54293) (xy 358.320716 -50.565572) (xy 358.26843 -50.58093)
			(xy 358.214491 -50.588691) (xy 358.187244 -50.58918) (xy 357.323644 -50.58918) (xy 357.296387 -50.588776)
			(xy 357.242427 -50.581024) (xy 357.19012 -50.56567) (xy 357.140531 -50.543029) (xy 357.094669 -50.51356)
			(xy 357.053468 -50.477863) (xy 357.017767 -50.436666) (xy 356.988293 -50.390808) (xy 356.965645 -50.341221)
			(xy 356.950286 -50.288916) (xy 356.942527 -50.234957) (xy 356.338093 -50.234957) (xy 356.330339 -50.28889)
			(xy 356.314986 -50.341179) (xy 356.292348 -50.390751) (xy 356.262886 -50.436596) (xy 356.2272 -50.477783)
			(xy 356.186016 -50.513472) (xy 356.140172 -50.542937) (xy 356.090601 -50.565577) (xy 356.038313 -50.580933)
			(xy 355.984372 -50.588692) (xy 355.957124 -50.58918) (xy 355.093524 -50.58918) (xy 355.066268 -50.588775)
			(xy 355.01231 -50.58102) (xy 354.960006 -50.565665) (xy 354.910419 -50.543022) (xy 354.864559 -50.513552)
			(xy 354.823361 -50.477856) (xy 354.787662 -50.43666) (xy 354.758189 -50.390802) (xy 354.735544 -50.341217)
			(xy 354.720185 -50.288913) (xy 354.712427 -50.234956) (xy 354.115593 -50.234956) (xy 354.107839 -50.28889)
			(xy 354.092486 -50.341179) (xy 354.069848 -50.390751) (xy 354.040386 -50.436596) (xy 354.0047 -50.477783)
			(xy 353.963516 -50.513472) (xy 353.917672 -50.542937) (xy 353.868101 -50.565577) (xy 353.815813 -50.580933)
			(xy 353.761872 -50.588692) (xy 353.734624 -50.58918) (xy 352.871024 -50.58918) (xy 352.843768 -50.588775)
			(xy 352.78981 -50.58102) (xy 352.737506 -50.565665) (xy 352.687919 -50.543022) (xy 352.642059 -50.513552)
			(xy 352.600861 -50.477856) (xy 352.565162 -50.43666) (xy 352.535689 -50.390802) (xy 352.513044 -50.341217)
			(xy 352.497685 -50.288913) (xy 352.489927 -50.234956) (xy 351.917493 -50.234956) (xy 351.909738 -50.288892)
			(xy 351.894385 -50.341182) (xy 351.871746 -50.390755) (xy 351.842282 -50.436602) (xy 351.806594 -50.477789)
			(xy 351.765408 -50.513477) (xy 351.719562 -50.542942) (xy 351.66999 -50.565582) (xy 351.6177 -50.580936)
			(xy 351.563757 -50.588693) (xy 351.536508 -50.58918) (xy 350.672908 -50.58918) (xy 350.645653 -50.588774)
			(xy 350.591697 -50.581017) (xy 350.539394 -50.565661) (xy 350.489809 -50.543017) (xy 350.443952 -50.513547)
			(xy 350.402755 -50.477851) (xy 350.367058 -50.436655) (xy 350.337587 -50.390798) (xy 350.314942 -50.341213)
			(xy 350.299585 -50.288911) (xy 350.291827 -50.234955) (xy 271.40723 -50.234955) (xy 271.490578 -50.372682)
			(xy 271.567568 -50.515391) (xy 271.637407 -50.661732) (xy 271.699922 -50.811349) (xy 271.754963 -50.963874)
			(xy 271.802393 -51.118934) (xy 271.842096 -51.27615) (xy 271.873977 -51.435138) (xy 271.897955 -51.595507)
			(xy 271.913974 -51.756866) (xy 271.921993 -51.91882) (xy 271.922494 -51.999896) (xy 271.921993 -52.080972)
			(xy 271.913974 -52.242926) (xy 271.897955 -52.404285) (xy 271.873977 -52.564654) (xy 271.842096 -52.723642)
			(xy 271.802393 -52.880858) (xy 271.754963 -53.035918) (xy 271.699922 -53.188443) (xy 271.637407 -53.33806)
			(xy 271.567568 -53.484401) (xy 271.490578 -53.62711) (xy 271.406625 -53.765837) (xy 271.315913 -53.900242)
			(xy 271.218666 -54.029997) (xy 271.115121 -54.154784) (xy 271.005532 -54.274298) (xy 270.890166 -54.388245)
			(xy 270.769306 -54.496348) (xy 270.643248 -54.598342) (xy 270.5123 -54.693977) (xy 270.376784 -54.783019)
			(xy 270.237029 -54.86525) (xy 270.093379 -54.940469) (xy 269.946184 -55.008492) (xy 269.795806 -55.069153)
			(xy 269.642612 -55.122303) (xy 269.486977 -55.167811) (xy 269.329282 -55.205567) (xy 269.169912 -55.235479)
			(xy 269.009258 -55.257472) (xy 268.847714 -55.271493) (xy 268.685673 -55.277509) (xy 268.523533 -55.275503)
			(xy 268.361691 -55.265482) (xy 268.200543 -55.247469) (xy 268.040482 -55.221509) (xy 267.881901 -55.187664)
			(xy 267.725188 -55.146019) (xy 267.570726 -55.096675) (xy 267.418894 -55.039753) (xy 267.270062 -54.975391)
			(xy 267.124595 -54.903748) (xy 266.982849 -54.824999) (xy 266.845171 -54.739336) (xy 266.711898 -54.646969)
			(xy 266.583356 -54.548125) (xy 266.459859 -54.443044) (xy 266.341711 -54.331985) (xy 266.229199 -54.215219)
			(xy 266.122599 -54.093031) (xy 266.022172 -53.965721) (xy 265.928164 -53.833601) (xy 265.840805 -53.696993)
			(xy 265.760308 -53.556232) (xy 265.686872 -53.411662) (xy 265.620674 -53.263638) (xy 265.561878 -53.112521)
			(xy 265.510627 -52.958681) (xy 265.467047 -52.802495) (xy 265.431244 -52.644345) (xy 265.403306 -52.484618)
			(xy 265.383302 -52.323704) (xy 265.371279 -52.161999) (xy 265.367269 -51.999896) (xy 242.687806 -51.999896)
			(xy 242.689402 -52.010999) (xy 242.689888 -52.03825) (xy 242.689888 -52.90185) (xy 242.689402 -52.929101)
			(xy 242.681646 -52.983049) (xy 242.666291 -53.035344) (xy 242.643649 -53.084921) (xy 242.614183 -53.130771)
			(xy 242.578492 -53.171962) (xy 242.537301 -53.207653) (xy 242.491451 -53.237119) (xy 242.441874 -53.259761)
			(xy 242.389579 -53.275116) (xy 242.335631 -53.282872) (xy 242.281129 -53.282872) (xy 242.227181 -53.275116)
			(xy 242.174886 -53.259761) (xy 242.125309 -53.237119) (xy 242.079459 -53.207653) (xy 242.038268 -53.171962)
			(xy 242.002577 -53.130771) (xy 241.973111 -53.084921) (xy 241.950469 -53.035344) (xy 241.935114 -52.983049)
			(xy 241.927358 -52.929101) (xy 241.926872 -52.90185) (xy 229.578408 -52.90185) (xy 229.578408 -52.906676)
			(xy 229.577922 -52.933927) (xy 229.570166 -52.987875) (xy 229.554811 -53.04017) (xy 229.532169 -53.089747)
			(xy 229.502703 -53.135597) (xy 229.467012 -53.176788) (xy 229.425821 -53.212479) (xy 229.379971 -53.241945)
			(xy 229.330394 -53.264587) (xy 229.278099 -53.279942) (xy 229.224151 -53.287698) (xy 229.169649 -53.287698)
			(xy 229.115701 -53.279942) (xy 229.063406 -53.264587) (xy 229.013829 -53.241945) (xy 228.967979 -53.212479)
			(xy 228.926788 -53.176788) (xy 228.891097 -53.135597) (xy 228.861631 -53.089747) (xy 228.838989 -53.04017)
			(xy 228.823634 -52.987875) (xy 228.815878 -52.933927) (xy 228.815392 -52.906676) (xy 207.794624 -52.906676)
			(xy 207.755091 -53.035918) (xy 207.70005 -53.188443) (xy 207.637535 -53.33806) (xy 207.567696 -53.484401)
			(xy 207.490706 -53.62711) (xy 207.406753 -53.765837) (xy 207.316041 -53.900242) (xy 207.218794 -54.029997)
			(xy 207.115249 -54.154784) (xy 207.00566 -54.274298) (xy 206.890294 -54.388245) (xy 206.769434 -54.496348)
			(xy 206.643376 -54.598342) (xy 206.512428 -54.693977) (xy 206.493338 -54.70652) (xy 230.115872 -54.70652)
			(xy 230.115872 -53.84292) (xy 230.116358 -53.815669) (xy 230.124114 -53.761721) (xy 230.139469 -53.709426)
			(xy 230.162111 -53.659849) (xy 230.191577 -53.613999) (xy 230.227268 -53.572808) (xy 230.268459 -53.537117)
			(xy 230.314309 -53.507651) (xy 230.363886 -53.485009) (xy 230.416181 -53.469654) (xy 230.470129 -53.461898)
			(xy 230.524631 -53.461898) (xy 230.578579 -53.469654) (xy 230.630874 -53.485009) (xy 230.680451 -53.507651)
			(xy 230.726301 -53.537117) (xy 230.767492 -53.572808) (xy 230.803183 -53.613999) (xy 230.832649 -53.659849)
			(xy 230.855291 -53.709426) (xy 230.870646 -53.761721) (xy 230.878402 -53.815669) (xy 230.878888 -53.84292)
			(xy 230.878888 -54.70652) (xy 230.878811 -54.710838) (xy 240.282476 -54.710838) (xy 240.282476 -53.847238)
			(xy 240.282962 -53.819987) (xy 240.290718 -53.766039) (xy 240.306073 -53.713744) (xy 240.328715 -53.664167)
			(xy 240.358181 -53.618317) (xy 240.393872 -53.577126) (xy 240.435063 -53.541435) (xy 240.480913 -53.511969)
			(xy 240.53049 -53.489327) (xy 240.582785 -53.473972) (xy 240.636733 -53.466216) (xy 240.691235 -53.466216)
			(xy 240.745183 -53.473972) (xy 240.797478 -53.489327) (xy 240.847055 -53.511969) (xy 240.892905 -53.541435)
			(xy 240.934096 -53.577126) (xy 240.969787 -53.618317) (xy 240.999253 -53.664167) (xy 241.021895 -53.713744)
			(xy 241.03725 -53.766039) (xy 241.045006 -53.819987) (xy 241.045492 -53.847238) (xy 241.045492 -54.710838)
			(xy 241.045006 -54.738089) (xy 241.03725 -54.792037) (xy 241.021895 -54.844332) (xy 240.999253 -54.893909)
			(xy 240.969787 -54.939759) (xy 240.934096 -54.98095) (xy 240.892905 -55.016641) (xy 240.847055 -55.046107)
			(xy 240.797478 -55.068749) (xy 240.745183 -55.084104) (xy 240.691235 -55.09186) (xy 240.636733 -55.09186)
			(xy 240.582785 -55.084104) (xy 240.53049 -55.068749) (xy 240.480913 -55.046107) (xy 240.435063 -55.016641)
			(xy 240.393872 -54.98095) (xy 240.358181 -54.939759) (xy 240.328715 -54.893909) (xy 240.306073 -54.844332)
			(xy 240.290718 -54.792037) (xy 240.282962 -54.738089) (xy 240.282476 -54.710838) (xy 230.878811 -54.710838)
			(xy 230.878402 -54.733771) (xy 230.870646 -54.787719) (xy 230.855291 -54.840014) (xy 230.832649 -54.889591)
			(xy 230.803183 -54.935441) (xy 230.767492 -54.976632) (xy 230.726301 -55.012323) (xy 230.680451 -55.041789)
			(xy 230.630874 -55.064431) (xy 230.578579 -55.079786) (xy 230.524631 -55.087542) (xy 230.470129 -55.087542)
			(xy 230.416181 -55.079786) (xy 230.363886 -55.064431) (xy 230.314309 -55.041789) (xy 230.268459 -55.012323)
			(xy 230.227268 -54.976632) (xy 230.191577 -54.935441) (xy 230.162111 -54.889591) (xy 230.139469 -54.840014)
			(xy 230.124114 -54.787719) (xy 230.116358 -54.733771) (xy 230.115872 -54.70652) (xy 206.493338 -54.70652)
			(xy 206.376912 -54.783019) (xy 206.237157 -54.86525) (xy 206.093507 -54.940469) (xy 205.946312 -55.008492)
			(xy 205.795934 -55.069153) (xy 205.64274 -55.122303) (xy 205.487105 -55.167811) (xy 205.32941 -55.205567)
			(xy 205.17004 -55.235479) (xy 205.009386 -55.257472) (xy 204.847842 -55.271493) (xy 204.685801 -55.277509)
			(xy 204.523661 -55.275503) (xy 204.361819 -55.265482) (xy 204.200671 -55.247469) (xy 204.04061 -55.221509)
			(xy 203.882029 -55.187664) (xy 203.725316 -55.146019) (xy 203.570854 -55.096675) (xy 203.419022 -55.039753)
			(xy 203.27019 -54.975391) (xy 203.124723 -54.903748) (xy 202.982977 -54.824999) (xy 202.845299 -54.739336)
			(xy 202.712026 -54.646969) (xy 202.583484 -54.548125) (xy 202.459987 -54.443044) (xy 202.341839 -54.331985)
			(xy 202.229327 -54.215219) (xy 202.122727 -54.093031) (xy 202.0223 -53.965721) (xy 201.928292 -53.833601)
			(xy 201.840933 -53.696993) (xy 201.760436 -53.556232) (xy 201.687 -53.411662) (xy 201.620802 -53.263638)
			(xy 201.562006 -53.112521) (xy 201.510755 -52.958681) (xy 201.467175 -52.802495) (xy 201.431372 -52.644345)
			(xy 201.403434 -52.484618) (xy 201.38343 -52.323704) (xy 201.371407 -52.161999) (xy 201.367397 -51.999896)
			(xy 179.393088 -51.999896) (xy 179.393088 -52.481734) (xy 179.392602 -52.508985) (xy 179.384846 -52.562933)
			(xy 179.369491 -52.615228) (xy 179.346849 -52.664805) (xy 179.317383 -52.710655) (xy 179.281692 -52.751846)
			(xy 179.240501 -52.787537) (xy 179.194651 -52.817003) (xy 179.145074 -52.839645) (xy 179.092779 -52.855)
			(xy 179.038831 -52.862756) (xy 178.984329 -52.862756) (xy 178.930381 -52.855) (xy 178.878086 -52.839645)
			(xy 178.828509 -52.817003) (xy 178.782659 -52.787537) (xy 178.741468 -52.751846) (xy 178.705777 -52.710655)
			(xy 178.676311 -52.664805) (xy 178.653669 -52.615228) (xy 178.638314 -52.562933) (xy 178.630558 -52.508985)
			(xy 178.630072 -52.481734) (xy 0.509016 -52.481734) (xy 0.509016 -53.954934) (xy 181.659784 -53.954934)
			(xy 181.659784 -53.091334) (xy 181.66027 -53.064083) (xy 181.668026 -53.010135) (xy 181.683381 -52.95784)
			(xy 181.706023 -52.908263) (xy 181.735489 -52.862413) (xy 181.77118 -52.821222) (xy 181.812371 -52.785531)
			(xy 181.858221 -52.756065) (xy 181.907798 -52.733423) (xy 181.960093 -52.718068) (xy 182.014041 -52.710312)
			(xy 182.068543 -52.710312) (xy 182.122491 -52.718068) (xy 182.174786 -52.733423) (xy 182.224363 -52.756065)
			(xy 182.270213 -52.785531) (xy 182.311404 -52.821222) (xy 182.347095 -52.862413) (xy 182.376561 -52.908263)
			(xy 182.399203 -52.95784) (xy 182.414558 -53.010135) (xy 182.422314 -53.064083) (xy 182.4228 -53.091334)
			(xy 182.4228 -53.954934) (xy 182.422314 -53.982185) (xy 182.414558 -54.036133) (xy 182.399203 -54.088428)
			(xy 182.376561 -54.138005) (xy 182.347095 -54.183855) (xy 182.311404 -54.225046) (xy 182.270213 -54.260737)
			(xy 182.224363 -54.290203) (xy 182.174786 -54.312845) (xy 182.122491 -54.3282) (xy 182.068543 -54.335956)
			(xy 182.014041 -54.335956) (xy 181.960093 -54.3282) (xy 181.907798 -54.312845) (xy 181.858221 -54.290203)
			(xy 181.812371 -54.260737) (xy 181.77118 -54.225046) (xy 181.735489 -54.183855) (xy 181.706023 -54.138005)
			(xy 181.683381 -54.088428) (xy 181.668026 -54.036133) (xy 181.66027 -53.982185) (xy 181.659784 -53.954934)
			(xy 0.509016 -53.954934) (xy 0.509016 -55.481728) (xy 178.630072 -55.481728) (xy 178.630072 -54.618128)
			(xy 178.630558 -54.590877) (xy 178.638314 -54.536929) (xy 178.653669 -54.484634) (xy 178.676311 -54.435057)
			(xy 178.705777 -54.389207) (xy 178.741468 -54.348016) (xy 178.782659 -54.312325) (xy 178.828509 -54.282859)
			(xy 178.878086 -54.260217) (xy 178.930381 -54.244862) (xy 178.984329 -54.237106) (xy 179.038831 -54.237106)
			(xy 179.092779 -54.244862) (xy 179.145074 -54.260217) (xy 179.194651 -54.282859) (xy 179.240501 -54.312325)
			(xy 179.281692 -54.348016) (xy 179.317383 -54.389207) (xy 179.346849 -54.435057) (xy 179.369491 -54.484634)
			(xy 179.384846 -54.536929) (xy 179.392602 -54.590877) (xy 179.393088 -54.618128) (xy 179.393088 -55.481728)
			(xy 179.392602 -55.508979) (xy 179.384846 -55.562927) (xy 179.369491 -55.615222) (xy 179.346849 -55.664799)
			(xy 179.317383 -55.710649) (xy 179.281692 -55.75184) (xy 179.240501 -55.787531) (xy 179.194651 -55.816997)
			(xy 179.145074 -55.839639) (xy 179.092779 -55.854994) (xy 179.038831 -55.86275) (xy 178.984329 -55.86275)
			(xy 178.930381 -55.854994) (xy 178.878086 -55.839639) (xy 178.828509 -55.816997) (xy 178.782659 -55.787531)
			(xy 178.741468 -55.75184) (xy 178.705777 -55.710649) (xy 178.676311 -55.664799) (xy 178.653669 -55.615222)
			(xy 178.638314 -55.562927) (xy 178.630558 -55.508979) (xy 178.630072 -55.481728) (xy 0.509016 -55.481728)
			(xy 0.509016 -57.094435) (xy 170.841915 -57.094435) (xy 170.841915 -57.005413) (xy 170.849895 -56.916749)
			(xy 170.865791 -56.829158) (xy 170.889474 -56.743343) (xy 170.920754 -56.659998) (xy 170.95938 -56.579792)
			(xy 171.005039 -56.503371) (xy 171.057365 -56.43135) (xy 171.115936 -56.36431) (xy 171.180281 -56.30279)
			(xy 171.249881 -56.247286) (xy 171.324177 -56.198244) (xy 171.402569 -56.156059) (xy 171.484428 -56.121071)
			(xy 171.569093 -56.093562) (xy 171.655883 -56.073752) (xy 171.744099 -56.061802) (xy 171.833032 -56.057809)
			(xy 171.921965 -56.061802) (xy 172.010181 -56.073752) (xy 172.096971 -56.093562) (xy 172.181636 -56.121071)
			(xy 172.263495 -56.156059) (xy 172.341887 -56.198244) (xy 172.416183 -56.247286) (xy 172.485783 -56.30279)
			(xy 172.550128 -56.36431) (xy 172.608699 -56.43135) (xy 172.661025 -56.503371) (xy 172.663117 -56.506872)
			(xy 228.815392 -56.506872) (xy 228.815392 -55.643272) (xy 228.815878 -55.616021) (xy 228.823634 -55.562073)
			(xy 228.838989 -55.509778) (xy 228.861631 -55.460201) (xy 228.891097 -55.414351) (xy 228.926788 -55.37316)
			(xy 228.967979 -55.337469) (xy 229.013829 -55.308003) (xy 229.063406 -55.285361) (xy 229.115701 -55.270006)
			(xy 229.169649 -55.26225) (xy 229.224151 -55.26225) (xy 229.278099 -55.270006) (xy 229.330394 -55.285361)
			(xy 229.379971 -55.308003) (xy 229.425821 -55.337469) (xy 229.467012 -55.37316) (xy 229.502703 -55.414351)
			(xy 229.532169 -55.460201) (xy 229.554811 -55.509778) (xy 229.570166 -55.562073) (xy 229.577922 -55.616021)
			(xy 229.578408 -55.643272) (xy 229.578408 -55.911852) (xy 357.10365 -55.911852) (xy 357.10365 -55.857348)
			(xy 357.111406 -55.803398) (xy 357.126762 -55.751101) (xy 357.149403 -55.701521) (xy 357.17887 -55.655668)
			(xy 357.214562 -55.614476) (xy 357.255752 -55.578782) (xy 357.301604 -55.549313) (xy 357.351182 -55.526669)
			(xy 357.403478 -55.511311) (xy 357.457428 -55.503551) (xy 357.48468 -55.503064) (xy 358.34828 -55.503064)
			(xy 358.375532 -55.503582) (xy 358.429481 -55.511336) (xy 358.481777 -55.526689) (xy 358.531356 -55.549329)
			(xy 358.577209 -55.578794) (xy 358.618401 -55.614485) (xy 358.654094 -55.655675) (xy 358.683562 -55.701526)
			(xy 358.706204 -55.751104) (xy 358.72156 -55.8034) (xy 358.729317 -55.857348) (xy 358.729317 -55.911852)
			(xy 358.729316 -55.911856) (xy 359.950927 -55.911856) (xy 359.950927 -55.857344) (xy 359.958685 -55.803388)
			(xy 359.974043 -55.751084) (xy 359.996689 -55.701499) (xy 360.026161 -55.655642) (xy 360.061859 -55.614445)
			(xy 360.103058 -55.578749) (xy 360.148917 -55.549279) (xy 360.198503 -55.526636) (xy 360.250807 -55.511281)
			(xy 360.304764 -55.503526) (xy 360.33202 -55.503064) (xy 361.19562 -55.503064) (xy 361.222868 -55.503608)
			(xy 361.27681 -55.511366) (xy 361.329098 -55.526722) (xy 361.378669 -55.549362) (xy 361.424514 -55.578827)
			(xy 361.465699 -55.614516) (xy 361.501385 -55.655702) (xy 361.530847 -55.701548) (xy 361.553485 -55.75112)
			(xy 361.568838 -55.80341) (xy 361.576594 -55.857352) (xy 361.576594 -55.911848) (xy 361.576593 -55.911857)
			(xy 363.514527 -55.911857) (xy 363.514527 -55.857343) (xy 363.522286 -55.803385) (xy 363.537645 -55.75108)
			(xy 363.560292 -55.701493) (xy 363.589766 -55.655635) (xy 363.625466 -55.614438) (xy 363.666667 -55.578742)
			(xy 363.712529 -55.549273) (xy 363.762117 -55.526631) (xy 363.814424 -55.511277) (xy 363.868383 -55.503524)
			(xy 363.89564 -55.503064) (xy 364.75924 -55.503064) (xy 364.786487 -55.503609) (xy 364.840427 -55.511369)
			(xy 364.892713 -55.526727) (xy 364.942281 -55.549369) (xy 364.988123 -55.578834) (xy 365.029306 -55.614523)
			(xy 365.06499 -55.655709) (xy 365.094451 -55.701554) (xy 365.117087 -55.751125) (xy 365.132439 -55.803412)
			(xy 365.140194 -55.857353) (xy 365.140194 -55.911847) (xy 365.132439 -55.965788) (xy 365.117087 -56.018075)
			(xy 365.094451 -56.067646) (xy 365.06499 -56.113491) (xy 365.029306 -56.154677) (xy 364.988123 -56.190366)
			(xy 364.942281 -56.219831) (xy 364.892713 -56.242473) (xy 364.840427 -56.257831) (xy 364.786487 -56.265591)
			(xy 364.75924 -56.26608) (xy 363.89564 -56.26608) (xy 363.868383 -56.265676) (xy 363.814424 -56.257923)
			(xy 363.762117 -56.242569) (xy 363.712529 -56.219927) (xy 363.666667 -56.190458) (xy 363.625466 -56.154762)
			(xy 363.589766 -56.113565) (xy 363.560292 -56.067707) (xy 363.537645 -56.01812) (xy 363.522286 -55.965815)
			(xy 363.514527 -55.911857) (xy 361.576593 -55.911857) (xy 361.568838 -55.96579) (xy 361.553485 -56.01808)
			(xy 361.530847 -56.067652) (xy 361.501385 -56.113498) (xy 361.465699 -56.154684) (xy 361.424514 -56.190373)
			(xy 361.378669 -56.219838) (xy 361.329098 -56.242478) (xy 361.27681 -56.257834) (xy 361.222868 -56.265592)
			(xy 361.19562 -56.26608) (xy 360.33202 -56.26608) (xy 360.304764 -56.265674) (xy 360.250807 -56.257919)
			(xy 360.198503 -56.242564) (xy 360.148917 -56.219921) (xy 360.103058 -56.190451) (xy 360.061859 -56.154755)
			(xy 360.026161 -56.113558) (xy 359.996689 -56.067701) (xy 359.974043 -56.018116) (xy 359.958685 -55.965812)
			(xy 359.950927 -55.911856) (xy 358.729316 -55.911856) (xy 358.72156 -55.9658) (xy 358.706204 -56.018096)
			(xy 358.683562 -56.067674) (xy 358.654094 -56.113525) (xy 358.618401 -56.154715) (xy 358.577209 -56.190406)
			(xy 358.531356 -56.219871) (xy 358.481777 -56.242511) (xy 358.429481 -56.257864) (xy 358.375532 -56.265618)
			(xy 358.34828 -56.26608) (xy 357.48468 -56.26608) (xy 357.457428 -56.265649) (xy 357.403478 -56.257889)
			(xy 357.351182 -56.242531) (xy 357.301604 -56.219887) (xy 357.255752 -56.190418) (xy 357.214562 -56.154724)
			(xy 357.17887 -56.113532) (xy 357.149403 -56.067679) (xy 357.126762 -56.018099) (xy 357.111406 -55.965802)
			(xy 357.10365 -55.911852) (xy 229.578408 -55.911852) (xy 229.578408 -56.506872) (xy 229.577922 -56.534123)
			(xy 229.570166 -56.588071) (xy 229.554811 -56.640366) (xy 229.532169 -56.689943) (xy 229.502703 -56.735793)
			(xy 229.467012 -56.776984) (xy 229.425821 -56.812675) (xy 229.379971 -56.842141) (xy 229.330394 -56.864783)
			(xy 229.278099 -56.880138) (xy 229.224151 -56.887894) (xy 229.169649 -56.887894) (xy 229.115701 -56.880138)
			(xy 229.063406 -56.864783) (xy 229.013829 -56.842141) (xy 228.967979 -56.812675) (xy 228.926788 -56.776984)
			(xy 228.891097 -56.735793) (xy 228.861631 -56.689943) (xy 228.838989 -56.640366) (xy 228.823634 -56.588071)
			(xy 228.815878 -56.534123) (xy 228.815392 -56.506872) (xy 172.663117 -56.506872) (xy 172.706684 -56.579792)
			(xy 172.74531 -56.659998) (xy 172.77659 -56.743343) (xy 172.800273 -56.829158) (xy 172.816169 -56.916749)
			(xy 172.824149 -57.005413) (xy 172.824648 -57.049924) (xy 172.824149 -57.094435) (xy 172.816169 -57.183099)
			(xy 172.800273 -57.27069) (xy 172.77659 -57.356505) (xy 172.74531 -57.43985) (xy 172.706684 -57.520056)
			(xy 172.661025 -57.596477) (xy 172.608699 -57.668498) (xy 172.550128 -57.735538) (xy 172.485783 -57.797058)
			(xy 172.416183 -57.852562) (xy 172.341887 -57.901604) (xy 172.263495 -57.943789) (xy 172.181636 -57.978777)
			(xy 172.096971 -58.006286) (xy 172.010181 -58.026096) (xy 171.921965 -58.038046) (xy 171.833032 -58.04204)
			(xy 171.744099 -58.038046) (xy 171.655883 -58.026096) (xy 171.569093 -58.006286) (xy 171.484428 -57.978777)
			(xy 171.402569 -57.943789) (xy 171.324177 -57.901604) (xy 171.249881 -57.852562) (xy 171.180281 -57.797058)
			(xy 171.115936 -57.735538) (xy 171.057365 -57.668498) (xy 171.005039 -57.596477) (xy 170.95938 -57.520056)
			(xy 170.920754 -57.43985) (xy 170.889474 -57.356505) (xy 170.865791 -57.27069) (xy 170.849895 -57.183099)
			(xy 170.841915 -57.094435) (xy 0.509016 -57.094435) (xy 0.509016 -58.306716) (xy 230.115872 -58.306716)
			(xy 230.115872 -57.443116) (xy 230.116358 -57.415865) (xy 230.124114 -57.361917) (xy 230.139469 -57.309622)
			(xy 230.162111 -57.260045) (xy 230.191577 -57.214195) (xy 230.227268 -57.173004) (xy 230.268459 -57.137313)
			(xy 230.314309 -57.107847) (xy 230.363886 -57.085205) (xy 230.416181 -57.06985) (xy 230.470129 -57.062094)
			(xy 230.524631 -57.062094) (xy 230.578579 -57.06985) (xy 230.630874 -57.085205) (xy 230.680451 -57.107847)
			(xy 230.726301 -57.137313) (xy 230.767492 -57.173004) (xy 230.803183 -57.214195) (xy 230.832649 -57.260045)
			(xy 230.855291 -57.309622) (xy 230.870646 -57.361917) (xy 230.878402 -57.415865) (xy 230.878888 -57.443116)
			(xy 230.878888 -58.30189) (xy 240.282476 -58.30189) (xy 240.282476 -57.43829) (xy 240.282962 -57.411039)
			(xy 240.290718 -57.357091) (xy 240.306073 -57.304796) (xy 240.328715 -57.255219) (xy 240.358181 -57.209369)
			(xy 240.393872 -57.168178) (xy 240.435063 -57.132487) (xy 240.480913 -57.103021) (xy 240.53049 -57.080379)
			(xy 240.582785 -57.065024) (xy 240.636733 -57.057268) (xy 240.691235 -57.057268) (xy 240.745183 -57.065024)
			(xy 240.797478 -57.080379) (xy 240.847055 -57.103021) (xy 240.892905 -57.132487) (xy 240.934096 -57.168178)
			(xy 240.969787 -57.209369) (xy 240.999253 -57.255219) (xy 241.021895 -57.304796) (xy 241.03725 -57.357091)
			(xy 241.045006 -57.411039) (xy 241.045492 -57.43829) (xy 241.045492 -58.30189) (xy 241.045006 -58.329141)
			(xy 241.03725 -58.383089) (xy 241.021895 -58.435384) (xy 240.999253 -58.484961) (xy 240.969787 -58.530811)
			(xy 240.941894 -58.563002) (xy 242.736116 -58.563002) (xy 242.736116 -57.699402) (xy 242.736602 -57.672151)
			(xy 242.744358 -57.618203) (xy 242.759713 -57.565908) (xy 242.782355 -57.516331) (xy 242.811821 -57.470481)
			(xy 242.847512 -57.42929) (xy 242.888703 -57.393599) (xy 242.934553 -57.364133) (xy 242.98413 -57.341491)
			(xy 243.036425 -57.326136) (xy 243.090373 -57.31838) (xy 243.144875 -57.31838) (xy 243.198823 -57.326136)
			(xy 243.251118 -57.341491) (xy 243.300695 -57.364133) (xy 243.346545 -57.393599) (xy 243.387736 -57.42929)
			(xy 243.423427 -57.470481) (xy 243.452893 -57.516331) (xy 243.475535 -57.565908) (xy 243.49089 -57.618203)
			(xy 243.498646 -57.672151) (xy 243.499132 -57.699402) (xy 243.499132 -58.221618) (xy 345.968461 -58.221618)
			(xy 345.97224 -58.197721) (xy 345.983217 -58.176161) (xy 345.991434 -58.16727) (xy 346.22486 -57.933844)
			(xy 346.233751 -57.925623) (xy 346.255314 -57.914636) (xy 346.279216 -57.91085) (xy 346.303118 -57.914636)
			(xy 346.324681 -57.925623) (xy 346.333572 -57.933844) (xy 346.51315 -58.113422) (xy 346.521393 -58.1223)
			(xy 346.53239 -58.143871) (xy 346.536183 -58.167784) (xy 346.5324 -58.191699) (xy 346.521411 -58.213274)
			(xy 346.51315 -58.222134) (xy 346.279724 -58.45556) (xy 346.270833 -58.463781) (xy 346.24927 -58.474768)
			(xy 346.225368 -58.478554) (xy 346.201466 -58.474768) (xy 346.179903 -58.463781) (xy 346.171012 -58.45556)
			(xy 345.991434 -58.275982) (xy 345.983239 -58.267069) (xy 345.972251 -58.245514) (xy 345.968461 -58.221618)
			(xy 243.499132 -58.221618) (xy 243.499132 -58.563002) (xy 243.498646 -58.590253) (xy 243.49089 -58.644201)
			(xy 243.475535 -58.696496) (xy 243.452893 -58.746073) (xy 243.423427 -58.791923) (xy 243.387736 -58.833114)
			(xy 243.34712 -58.868307) (xy 345.321709 -58.868307) (xy 345.325495 -58.84439) (xy 345.336487 -58.822814)
			(xy 345.34475 -58.813954) (xy 345.578176 -58.580274) (xy 345.587095 -58.572049) (xy 345.60871 -58.561063)
			(xy 345.632659 -58.557278) (xy 345.656608 -58.561063) (xy 345.678223 -58.572049) (xy 345.687142 -58.580274)
			(xy 345.705679 -58.598811) (xy 346.345647 -58.598811) (xy 346.349428 -58.574913) (xy 346.360407 -58.553352)
			(xy 346.368624 -58.54446) (xy 346.60205 -58.311034) (xy 346.610941 -58.302813) (xy 346.632504 -58.291826)
			(xy 346.656406 -58.28804) (xy 346.680308 -58.291826) (xy 346.701871 -58.302813) (xy 346.710762 -58.311034)
			(xy 346.89034 -58.490612) (xy 346.898573 -58.499498) (xy 346.909573 -58.521066) (xy 346.913368 -58.544977)
			(xy 346.909587 -58.568891) (xy 346.8986 -58.590465) (xy 346.89034 -58.599324) (xy 346.656914 -58.83275)
			(xy 346.648023 -58.840971) (xy 346.62646 -58.851958) (xy 346.602558 -58.855744) (xy 346.578656 -58.851958)
			(xy 346.557093 -58.840971) (xy 346.548202 -58.83275) (xy 346.368624 -58.653172) (xy 346.36042 -58.644267)
			(xy 346.349435 -58.622709) (xy 346.345647 -58.598811) (xy 345.705679 -58.598811) (xy 345.86672 -58.759852)
			(xy 345.874983 -58.76874) (xy 345.885972 -58.790365) (xy 345.889753 -58.814325) (xy 345.885957 -58.838283)
			(xy 345.874954 -58.8599) (xy 345.86672 -58.868818) (xy 345.63304 -59.102244) (xy 345.624149 -59.110465)
			(xy 345.602586 -59.121452) (xy 345.578684 -59.125238) (xy 345.554782 -59.121452) (xy 345.533219 -59.110465)
			(xy 345.524328 -59.102244) (xy 345.34475 -58.922666) (xy 345.336495 -58.913798) (xy 345.325499 -58.892224)
			(xy 345.321709 -58.868307) (xy 243.34712 -58.868307) (xy 243.346545 -58.868805) (xy 243.300695 -58.898271)
			(xy 243.251118 -58.920913) (xy 243.198823 -58.936268) (xy 243.144875 -58.944024) (xy 243.090373 -58.944024)
			(xy 243.036425 -58.936268) (xy 242.98413 -58.920913) (xy 242.934553 -58.898271) (xy 242.888703 -58.868805)
			(xy 242.847512 -58.833114) (xy 242.811821 -58.791923) (xy 242.782355 -58.746073) (xy 242.759713 -58.696496)
			(xy 242.744358 -58.644201) (xy 242.736602 -58.590253) (xy 242.736116 -58.563002) (xy 240.941894 -58.563002)
			(xy 240.934096 -58.572002) (xy 240.892905 -58.607693) (xy 240.847055 -58.637159) (xy 240.797478 -58.659801)
			(xy 240.745183 -58.675156) (xy 240.691235 -58.682912) (xy 240.636733 -58.682912) (xy 240.582785 -58.675156)
			(xy 240.53049 -58.659801) (xy 240.480913 -58.637159) (xy 240.435063 -58.607693) (xy 240.393872 -58.572002)
			(xy 240.358181 -58.530811) (xy 240.328715 -58.484961) (xy 240.306073 -58.435384) (xy 240.290718 -58.383089)
			(xy 240.282962 -58.329141) (xy 240.282476 -58.30189) (xy 230.878888 -58.30189) (xy 230.878888 -58.306716)
			(xy 230.878402 -58.333967) (xy 230.870646 -58.387915) (xy 230.855291 -58.44021) (xy 230.832649 -58.489787)
			(xy 230.803183 -58.535637) (xy 230.767492 -58.576828) (xy 230.726301 -58.612519) (xy 230.680451 -58.641985)
			(xy 230.630874 -58.664627) (xy 230.578579 -58.679982) (xy 230.524631 -58.687738) (xy 230.470129 -58.687738)
			(xy 230.416181 -58.679982) (xy 230.363886 -58.664627) (xy 230.314309 -58.641985) (xy 230.268459 -58.612519)
			(xy 230.227268 -58.576828) (xy 230.191577 -58.535637) (xy 230.162111 -58.489787) (xy 230.139469 -58.44021)
			(xy 230.124114 -58.387915) (xy 230.116358 -58.333967) (xy 230.115872 -58.306716) (xy 0.509016 -58.306716)
			(xy 0.509016 -59.99988) (xy 16.983969 -59.99988) (xy 16.987993 -59.914112) (xy 17.000031 -59.829098)
			(xy 17.019978 -59.745584) (xy 17.047657 -59.664305) (xy 17.082825 -59.585976) (xy 17.125174 -59.511283)
			(xy 17.174331 -59.440885) (xy 17.229864 -59.375399) (xy 17.291286 -59.315401) (xy 17.358055 -59.261418)
			(xy 17.429587 -59.213925) (xy 17.505251 -59.173339) (xy 17.584384 -59.140016) (xy 17.666289 -59.11425)
			(xy 17.750247 -59.096267) (xy 17.835521 -59.086225) (xy 17.92136 -59.084212) (xy 18.00701 -59.090246)
			(xy 18.091718 -59.104274) (xy 18.174741 -59.126173) (xy 18.255349 -59.15575) (xy 18.332833 -59.192745)
			(xy 18.406512 -59.236833) (xy 18.418162 -59.245381) (xy 345.698698 -59.245381) (xy 345.702524 -59.22138)
			(xy 345.713614 -59.199753) (xy 345.72194 -59.19089) (xy 345.955366 -58.957464) (xy 345.964285 -58.949239)
			(xy 345.9859 -58.938253) (xy 346.009849 -58.934468) (xy 346.033798 -58.938253) (xy 346.055413 -58.949239)
			(xy 346.064332 -58.957464) (xy 346.24391 -59.137042) (xy 346.252155 -59.145942) (xy 346.263132 -59.167565)
			(xy 346.26691 -59.191518) (xy 346.263121 -59.215469) (xy 346.252134 -59.237087) (xy 346.24391 -59.246008)
			(xy 346.01023 -59.479434) (xy 346.001339 -59.487655) (xy 345.979776 -59.498642) (xy 345.955874 -59.502428)
			(xy 345.931972 -59.498642) (xy 345.910409 -59.487655) (xy 345.901518 -59.479434) (xy 345.72194 -59.299856)
			(xy 345.713592 -59.291016) (xy 345.702513 -59.269384) (xy 345.698698 -59.245381) (xy 18.418162 -59.245381)
			(xy 18.475738 -59.287627) (xy 18.539905 -59.34468) (xy 18.598446 -59.407491) (xy 18.650849 -59.475508)
			(xy 18.696652 -59.548133) (xy 18.735453 -59.624728) (xy 18.766912 -59.70462) (xy 18.790751 -59.787107)
			(xy 18.806761 -59.871464) (xy 18.814801 -59.956949) (xy 18.815304 -59.99988) (xy 18.814801 -60.042811)
			(xy 18.806761 -60.128296) (xy 18.790751 -60.212653) (xy 18.766912 -60.29514) (xy 18.735453 -60.375032)
			(xy 18.73545 -60.375038) (xy 233.333297 -60.375038) (xy 233.337302 -60.28713) (xy 233.349285 -60.19995)
			(xy 233.369145 -60.114221) (xy 233.39672 -60.030653) (xy 233.431779 -59.949939) (xy 233.474032 -59.872747)
			(xy 233.52313 -59.799718) (xy 233.578666 -59.731456) (xy 233.640178 -59.668526) (xy 233.707159 -59.611452)
			(xy 233.779052 -59.560704) (xy 233.855261 -59.516704) (xy 233.935156 -59.479817) (xy 234.018075 -59.450348)
			(xy 234.10333 -59.428541) (xy 234.190214 -59.414577) (xy 234.278008 -59.408571) (xy 234.365985 -59.410575)
			(xy 234.453415 -59.42057) (xy 234.539574 -59.438474) (xy 234.623748 -59.464138) (xy 234.705239 -59.497351)
			(xy 234.783373 -59.537837) (xy 234.857501 -59.585259) (xy 234.927009 -59.639226) (xy 234.991323 -59.699291)
			(xy 235.049907 -59.764955) (xy 235.102278 -59.835674) (xy 235.148001 -59.910862) (xy 235.186698 -59.989897)
			(xy 235.218047 -60.072123) (xy 235.241789 -60.156859) (xy 235.257727 -60.243403) (xy 235.265729 -60.331038)
			(xy 235.26623 -60.375038) (xy 235.265729 -60.419038) (xy 235.257727 -60.506673) (xy 235.241789 -60.593217)
			(xy 235.218047 -60.677953) (xy 235.186698 -60.760179) (xy 235.148001 -60.839214) (xy 235.102278 -60.914402)
			(xy 235.049907 -60.985121) (xy 234.991323 -61.050785) (xy 234.927009 -61.11085) (xy 234.857501 -61.164817)
			(xy 234.783373 -61.212239) (xy 234.705239 -61.252725) (xy 234.623748 -61.285938) (xy 234.539574 -61.311602)
			(xy 234.453415 -61.329506) (xy 234.365985 -61.339501) (xy 234.278008 -61.341505) (xy 234.190214 -61.335499)
			(xy 234.10333 -61.321535) (xy 234.018075 -61.299728) (xy 233.935156 -61.270259) (xy 233.855261 -61.233372)
			(xy 233.779052 -61.189372) (xy 233.707159 -61.138624) (xy 233.640178 -61.08155) (xy 233.578666 -61.01862)
			(xy 233.52313 -60.950358) (xy 233.474032 -60.877329) (xy 233.431779 -60.800137) (xy 233.39672 -60.719423)
			(xy 233.369145 -60.635855) (xy 233.349285 -60.550126) (xy 233.337302 -60.462946) (xy 233.333297 -60.375038)
			(xy 18.73545 -60.375038) (xy 18.696652 -60.451627) (xy 18.650849 -60.524252) (xy 18.598446 -60.592269)
			(xy 18.539905 -60.65508) (xy 18.475738 -60.712133) (xy 18.406512 -60.762927) (xy 18.332833 -60.807015)
			(xy 18.255349 -60.84401) (xy 18.174741 -60.873587) (xy 18.091718 -60.895486) (xy 18.00701 -60.909514)
			(xy 17.92136 -60.915548) (xy 17.835521 -60.913535) (xy 17.750247 -60.903493) (xy 17.666289 -60.88551)
			(xy 17.584384 -60.859744) (xy 17.505251 -60.826421) (xy 17.429587 -60.785835) (xy 17.358055 -60.738342)
			(xy 17.291286 -60.684359) (xy 17.229864 -60.624361) (xy 17.174331 -60.558875) (xy 17.125174 -60.488477)
			(xy 17.082825 -60.413784) (xy 17.047657 -60.335455) (xy 17.019978 -60.254176) (xy 17.000031 -60.170662)
			(xy 16.987993 -60.085648) (xy 16.983969 -59.99988) (xy 0.509016 -59.99988) (xy 0.509016 -74.760836)
			(xy 39.554404 -74.760836) (xy 39.554404 -66.060828) (xy 39.554909 -65.955304) (xy 39.562993 -65.74441)
			(xy 39.579149 -65.533981) (xy 39.603352 -65.324324) (xy 39.635569 -65.115749) (xy 39.675751 -64.908561)
			(xy 39.723839 -64.703064) (xy 39.779763 -64.49956) (xy 39.84344 -64.298347) (xy 39.914778 -64.09972)
			(xy 39.993672 -63.903972) (xy 40.080005 -63.71139) (xy 40.173652 -63.522255) (xy 40.274474 -63.336846)
			(xy 40.382324 -63.155435) (xy 40.497043 -62.978288) (xy 40.618463 -62.805666) (xy 40.746406 -62.63782)
			(xy 40.880684 -62.474998) (xy 41.0211 -62.317439) (xy 41.167448 -62.165374) (xy 41.319513 -62.019026)
			(xy 41.477072 -61.87861) (xy 41.639894 -61.744332) (xy 41.80774 -61.616389) (xy 41.980362 -61.494969)
			(xy 42.157509 -61.38025) (xy 42.33892 -61.2724) (xy 42.524329 -61.171578) (xy 42.713464 -61.077931)
			(xy 42.906046 -60.991598) (xy 43.101794 -60.912704) (xy 43.300421 -60.841366) (xy 43.501634 -60.777689)
			(xy 43.705138 -60.721765) (xy 43.910635 -60.673677) (xy 44.117823 -60.633495) (xy 44.326398 -60.601278)
			(xy 44.536055 -60.577075) (xy 44.746484 -60.560919) (xy 44.957378 -60.552835) (xy 45.168426 -60.552835)
			(xy 45.37932 -60.560919) (xy 45.589749 -60.577075) (xy 45.799406 -60.601278) (xy 46.007981 -60.633495)
			(xy 46.215169 -60.673677) (xy 46.420666 -60.721765) (xy 46.62417 -60.777689) (xy 46.825383 -60.841366)
			(xy 47.02401 -60.912704) (xy 47.219758 -60.991598) (xy 47.41234 -61.077931) (xy 47.601475 -61.171578)
			(xy 47.786884 -61.2724) (xy 47.968295 -61.38025) (xy 48.145442 -61.494969) (xy 48.318064 -61.616389)
			(xy 48.48591 -61.744332) (xy 48.648732 -61.87861) (xy 48.806291 -62.019026) (xy 48.958356 -62.165374)
			(xy 49.104704 -62.317439) (xy 49.24512 -62.474998) (xy 49.379398 -62.63782) (xy 49.507341 -62.805666)
			(xy 49.628761 -62.978288) (xy 49.74348 -63.155435) (xy 49.85133 -63.336846) (xy 49.952152 -63.522255)
			(xy 50.045799 -63.71139) (xy 50.132132 -63.903972) (xy 50.211026 -64.09972) (xy 50.282364 -64.298347)
			(xy 50.346041 -64.49956) (xy 50.401965 -64.703064) (xy 50.450053 -64.908561) (xy 50.490235 -65.115749)
			(xy 50.522452 -65.324324) (xy 50.546655 -65.533981) (xy 50.562811 -65.74441) (xy 50.570895 -65.955304)
			(xy 50.5714 -66.060828) (xy 50.5714 -74.760836) (xy 50.571366 -74.767948) (xy 173.354492 -74.767948)
			(xy 173.354492 -66.06794) (xy 173.354997 -65.962416) (xy 173.363081 -65.751522) (xy 173.379237 -65.541093)
			(xy 173.40344 -65.331436) (xy 173.435657 -65.122861) (xy 173.475839 -64.915673) (xy 173.523927 -64.710176)
			(xy 173.579851 -64.506672) (xy 173.643528 -64.305459) (xy 173.714866 -64.106832) (xy 173.79376 -63.911084)
			(xy 173.880093 -63.718502) (xy 173.97374 -63.529367) (xy 174.074562 -63.343958) (xy 174.182412 -63.162547)
			(xy 174.297131 -62.9854) (xy 174.418551 -62.812778) (xy 174.546494 -62.644932) (xy 174.680772 -62.48211)
			(xy 174.821188 -62.324551) (xy 174.967536 -62.172486) (xy 175.119601 -62.026138) (xy 175.27716 -61.885722)
			(xy 175.439982 -61.751444) (xy 175.607828 -61.623501) (xy 175.78045 -61.502081) (xy 175.957597 -61.387362)
			(xy 176.139008 -61.279512) (xy 176.324417 -61.17869) (xy 176.513552 -61.085043) (xy 176.706134 -60.99871)
			(xy 176.901882 -60.919816) (xy 177.100509 -60.848478) (xy 177.301722 -60.784801) (xy 177.505226 -60.728877)
			(xy 177.710723 -60.680789) (xy 177.917911 -60.640607) (xy 178.126486 -60.60839) (xy 178.336143 -60.584187)
			(xy 178.546572 -60.568031) (xy 178.757466 -60.559947) (xy 178.968514 -60.559947) (xy 179.179408 -60.568031)
			(xy 179.389837 -60.584187) (xy 179.599494 -60.60839) (xy 179.808069 -60.640607) (xy 180.015257 -60.680789)
			(xy 180.220754 -60.728877) (xy 180.424258 -60.784801) (xy 180.625471 -60.848478) (xy 180.824098 -60.919816)
			(xy 181.019846 -60.99871) (xy 181.212428 -61.085043) (xy 181.401563 -61.17869) (xy 181.586972 -61.279512)
			(xy 181.768383 -61.387362) (xy 181.94553 -61.502081) (xy 182.118152 -61.623501) (xy 182.285998 -61.751444)
			(xy 182.44882 -61.885722) (xy 182.606379 -62.026138) (xy 182.758444 -62.172486) (xy 182.904792 -62.324551)
			(xy 183.045208 -62.48211) (xy 183.179486 -62.644932) (xy 183.307429 -62.812778) (xy 183.428849 -62.9854)
			(xy 183.543568 -63.162547) (xy 183.651418 -63.343958) (xy 183.75224 -63.529367) (xy 183.845887 -63.718502)
			(xy 183.93222 -63.911084) (xy 184.011114 -64.106832) (xy 184.082452 -64.305459) (xy 184.146129 -64.506672)
			(xy 184.202053 -64.710176) (xy 184.250141 -64.915673) (xy 184.290323 -65.122861) (xy 184.32254 -65.331436)
			(xy 184.346743 -65.541093) (xy 184.362899 -65.751522) (xy 184.370983 -65.962416) (xy 184.371488 -66.06794)
			(xy 184.371488 -74.760836) (xy 287.494472 -74.760836) (xy 287.494472 -66.060828) (xy 287.494977 -65.955304)
			(xy 287.503061 -65.74441) (xy 287.519217 -65.533981) (xy 287.54342 -65.324324) (xy 287.575637 -65.115749)
			(xy 287.615819 -64.908561) (xy 287.663907 -64.703064) (xy 287.719831 -64.49956) (xy 287.783508 -64.298347)
			(xy 287.854846 -64.09972) (xy 287.93374 -63.903972) (xy 288.020073 -63.71139) (xy 288.11372 -63.522255)
			(xy 288.214542 -63.336846) (xy 288.322392 -63.155435) (xy 288.437111 -62.978288) (xy 288.558531 -62.805666)
			(xy 288.686474 -62.63782) (xy 288.820752 -62.474998) (xy 288.961168 -62.317439) (xy 289.107516 -62.165374)
			(xy 289.259581 -62.019026) (xy 289.41714 -61.87861) (xy 289.579962 -61.744332) (xy 289.747808 -61.616389)
			(xy 289.92043 -61.494969) (xy 290.097577 -61.38025) (xy 290.278988 -61.2724) (xy 290.464397 -61.171578)
			(xy 290.653532 -61.077931) (xy 290.846114 -60.991598) (xy 291.041862 -60.912704) (xy 291.240489 -60.841366)
			(xy 291.441702 -60.777689) (xy 291.645206 -60.721765) (xy 291.850703 -60.673677) (xy 292.057891 -60.633495)
			(xy 292.266466 -60.601278) (xy 292.476123 -60.577075) (xy 292.686552 -60.560919) (xy 292.897446 -60.552835)
			(xy 293.108494 -60.552835) (xy 293.319388 -60.560919) (xy 293.529817 -60.577075) (xy 293.739474 -60.601278)
			(xy 293.948049 -60.633495) (xy 294.155237 -60.673677) (xy 294.360734 -60.721765) (xy 294.564238 -60.777689)
			(xy 294.765451 -60.841366) (xy 294.964078 -60.912704) (xy 295.159826 -60.991598) (xy 295.352408 -61.077931)
			(xy 295.541543 -61.171578) (xy 295.726952 -61.2724) (xy 295.908363 -61.38025) (xy 296.063868 -61.480954)
			(xy 351.822512 -61.480954) (xy 351.822512 -60.617354) (xy 351.822998 -60.590103) (xy 351.830754 -60.536155)
			(xy 351.846109 -60.48386) (xy 351.868751 -60.434283) (xy 351.898217 -60.388433) (xy 351.933908 -60.347242)
			(xy 351.975099 -60.311551) (xy 352.020949 -60.282085) (xy 352.070526 -60.259443) (xy 352.122821 -60.244088)
			(xy 352.176769 -60.236332) (xy 352.231271 -60.236332) (xy 352.285219 -60.244088) (xy 352.337514 -60.259443)
			(xy 352.387091 -60.282085) (xy 352.432941 -60.311551) (xy 352.474132 -60.347242) (xy 352.509823 -60.388433)
			(xy 352.539289 -60.434283) (xy 352.561931 -60.48386) (xy 352.577286 -60.536155) (xy 352.585042 -60.590103)
			(xy 352.585528 -60.617354) (xy 352.585528 -61.223271) (xy 355.46889 -61.223271) (xy 355.46889 -61.168729)
			(xy 355.476653 -61.114741) (xy 355.492019 -61.062408) (xy 355.514676 -61.012794) (xy 355.544164 -60.966909)
			(xy 355.579881 -60.925688) (xy 355.621101 -60.88997) (xy 355.666985 -60.860481) (xy 355.716598 -60.837822)
			(xy 355.768931 -60.822455) (xy 355.822919 -60.814691) (xy 355.85019 -60.814204) (xy 356.71379 -60.814204)
			(xy 356.741059 -60.814735) (xy 356.795042 -60.822495) (xy 356.847371 -60.837859) (xy 356.896981 -60.860514)
			(xy 356.942862 -60.889999) (xy 356.98408 -60.925713) (xy 357.019795 -60.96693) (xy 357.049281 -61.01281)
			(xy 357.071937 -61.062419) (xy 357.087303 -61.114748) (xy 357.095065 -61.168731) (xy 357.095065 -61.223269)
			(xy 357.087303 -61.277252) (xy 357.071937 -61.329581) (xy 357.049281 -61.37919) (xy 357.019795 -61.42507)
			(xy 356.98408 -61.466287) (xy 356.942862 -61.502001) (xy 356.896981 -61.531486) (xy 356.847371 -61.554141)
			(xy 356.795042 -61.569505) (xy 356.741059 -61.577265) (xy 356.71379 -61.577728) (xy 355.85019 -61.577728)
			(xy 355.822919 -61.577309) (xy 355.768931 -61.569545) (xy 355.716598 -61.554178) (xy 355.666985 -61.531519)
			(xy 355.621101 -61.50203) (xy 355.579881 -61.466312) (xy 355.544164 -61.425091) (xy 355.514676 -61.379206)
			(xy 355.492019 -61.329592) (xy 355.476653 -61.277259) (xy 355.46889 -61.223271) (xy 352.585528 -61.223271)
			(xy 352.585528 -61.480954) (xy 352.585042 -61.508205) (xy 352.577286 -61.562153) (xy 352.561931 -61.614448)
			(xy 352.539289 -61.664025) (xy 352.509823 -61.709875) (xy 352.474132 -61.751066) (xy 352.432941 -61.786757)
			(xy 352.387091 -61.816223) (xy 352.337514 -61.838865) (xy 352.285219 -61.85422) (xy 352.231271 -61.861976)
			(xy 352.176769 -61.861976) (xy 352.122821 -61.85422) (xy 352.070526 -61.838865) (xy 352.020949 -61.816223)
			(xy 351.975099 -61.786757) (xy 351.933908 -61.751066) (xy 351.898217 -61.709875) (xy 351.868751 -61.664025)
			(xy 351.846109 -61.614448) (xy 351.830754 -61.562153) (xy 351.822998 -61.508205) (xy 351.822512 -61.480954)
			(xy 296.063868 -61.480954) (xy 296.08551 -61.494969) (xy 296.258132 -61.616389) (xy 296.425978 -61.744332)
			(xy 296.5888 -61.87861) (xy 296.631388 -61.916564) (xy 340.16442 -61.916564) (xy 340.16442 -61.662564)
			(xy 340.164834 -61.650485) (xy 340.17231 -61.627512) (xy 340.186518 -61.607973) (xy 340.206069 -61.59378)
			(xy 340.229048 -61.586324) (xy 340.241128 -61.585856) (xy 340.571328 -61.585856) (xy 340.5834 -61.58634)
			(xy 340.606363 -61.593805) (xy 340.625896 -61.607998) (xy 340.640091 -61.62753) (xy 340.647559 -61.650492)
			(xy 340.648036 -61.662564) (xy 340.648036 -61.916564) (xy 341.07882 -61.916564) (xy 341.07882 -61.662564)
			(xy 341.079234 -61.650485) (xy 341.08671 -61.627512) (xy 341.100918 -61.607973) (xy 341.120469 -61.59378)
			(xy 341.143448 -61.586324) (xy 341.155528 -61.585856) (xy 341.485728 -61.585856) (xy 341.4978 -61.58634)
			(xy 341.520763 -61.593805) (xy 341.540296 -61.607998) (xy 341.554491 -61.62753) (xy 341.561959 -61.650492)
			(xy 341.562436 -61.662564) (xy 341.562436 -61.916564) (xy 343.5985 -61.916564) (xy 343.5985 -61.662564)
			(xy 343.598933 -61.650487) (xy 343.606407 -61.627517) (xy 343.620611 -61.60798) (xy 343.640156 -61.593787)
			(xy 343.66313 -61.586327) (xy 343.675208 -61.585856) (xy 344.005408 -61.585856) (xy 344.017479 -61.586357)
			(xy 344.040441 -61.593817) (xy 344.059974 -61.608006) (xy 344.07417 -61.627534) (xy 344.081639 -61.650493)
			(xy 344.082116 -61.662564) (xy 344.082116 -61.916564) (xy 344.5129 -61.916564) (xy 344.5129 -61.662564)
			(xy 344.513333 -61.650487) (xy 344.520807 -61.627517) (xy 344.535011 -61.60798) (xy 344.554556 -61.593787)
			(xy 344.57753 -61.586327) (xy 344.589608 -61.585856) (xy 344.919808 -61.585856) (xy 344.931879 -61.586357)
			(xy 344.954841 -61.593817) (xy 344.974374 -61.608006) (xy 344.98857 -61.627534) (xy 344.996039 -61.650493)
			(xy 344.996516 -61.662564) (xy 344.996516 -61.916564) (xy 344.996057 -61.928644) (xy 344.9886 -61.951624)
			(xy 344.974406 -61.971174) (xy 344.954864 -61.98538) (xy 344.931888 -61.99285) (xy 344.919808 -61.993272)
			(xy 344.589608 -61.993272) (xy 344.577522 -61.99288) (xy 344.554533 -61.985411) (xy 344.53498 -61.9712)
			(xy 344.520777 -61.951641) (xy 344.513315 -61.92865) (xy 344.5129 -61.916564) (xy 344.082116 -61.916564)
			(xy 344.081657 -61.928644) (xy 344.0742 -61.951624) (xy 344.060006 -61.971174) (xy 344.040464 -61.98538)
			(xy 344.017488 -61.99285) (xy 344.005408 -61.993272) (xy 343.675208 -61.993272) (xy 343.663122 -61.99288)
			(xy 343.640133 -61.985411) (xy 343.62058 -61.9712) (xy 343.606377 -61.951641) (xy 343.598915 -61.92865)
			(xy 343.5985 -61.916564) (xy 341.562436 -61.916564) (xy 341.561957 -61.928642) (xy 341.554503 -61.951619)
			(xy 341.540313 -61.971167) (xy 341.520776 -61.985374) (xy 341.497806 -61.992847) (xy 341.485728 -61.993272)
			(xy 341.155528 -61.993272) (xy 341.143443 -61.992863) (xy 341.120455 -61.985399) (xy 341.100901 -61.971193)
			(xy 341.086698 -61.951638) (xy 341.079236 -61.928649) (xy 341.07882 -61.916564) (xy 340.648036 -61.916564)
			(xy 340.647557 -61.928642) (xy 340.640103 -61.951619) (xy 340.625913 -61.971167) (xy 340.606376 -61.985374)
			(xy 340.583406 -61.992847) (xy 340.571328 -61.993272) (xy 340.241128 -61.993272) (xy 340.229043 -61.992863)
			(xy 340.206055 -61.985399) (xy 340.186501 -61.971193) (xy 340.172298 -61.951638) (xy 340.164836 -61.928649)
			(xy 340.16442 -61.916564) (xy 296.631388 -61.916564) (xy 296.746359 -62.019026) (xy 296.898424 -62.165374)
			(xy 297.044772 -62.317439) (xy 297.162878 -62.449964) (xy 340.16442 -62.449964) (xy 340.16442 -62.195964)
			(xy 340.164834 -62.183885) (xy 340.17231 -62.160912) (xy 340.186518 -62.141373) (xy 340.206069 -62.12718)
			(xy 340.229048 -62.119724) (xy 340.241128 -62.119256) (xy 340.571328 -62.119256) (xy 340.5834 -62.11974)
			(xy 340.606363 -62.127205) (xy 340.625896 -62.141398) (xy 340.640091 -62.16093) (xy 340.647559 -62.183892)
			(xy 340.648036 -62.195964) (xy 340.648036 -62.449964) (xy 341.07882 -62.449964) (xy 341.07882 -62.195964)
			(xy 341.079234 -62.183885) (xy 341.08671 -62.160912) (xy 341.100918 -62.141373) (xy 341.120469 -62.12718)
			(xy 341.143448 -62.119724) (xy 341.155528 -62.119256) (xy 341.485728 -62.119256) (xy 341.4978 -62.11974)
			(xy 341.520763 -62.127205) (xy 341.540296 -62.141398) (xy 341.554491 -62.16093) (xy 341.561959 -62.183892)
			(xy 341.562436 -62.195964) (xy 341.562436 -62.449964) (xy 343.5985 -62.449964) (xy 343.5985 -62.195964)
			(xy 343.598933 -62.183887) (xy 343.606407 -62.160917) (xy 343.620611 -62.14138) (xy 343.640156 -62.127187)
			(xy 343.66313 -62.119727) (xy 343.675208 -62.119256) (xy 344.005408 -62.119256) (xy 344.017479 -62.119757)
			(xy 344.040441 -62.127217) (xy 344.059974 -62.141406) (xy 344.07417 -62.160934) (xy 344.081639 -62.183893)
			(xy 344.082116 -62.195964) (xy 344.082116 -62.449964) (xy 344.5129 -62.449964) (xy 344.5129 -62.195964)
			(xy 344.513333 -62.183887) (xy 344.520807 -62.160917) (xy 344.535011 -62.14138) (xy 344.554556 -62.127187)
			(xy 344.57753 -62.119727) (xy 344.589608 -62.119256) (xy 344.919808 -62.119256) (xy 344.931879 -62.119757)
			(xy 344.954841 -62.127217) (xy 344.974374 -62.141406) (xy 344.98857 -62.160934) (xy 344.996039 -62.183893)
			(xy 344.996516 -62.195964) (xy 344.996516 -62.449964) (xy 344.996057 -62.462044) (xy 344.9886 -62.485024)
			(xy 344.974406 -62.504574) (xy 344.954864 -62.51878) (xy 344.931888 -62.52625) (xy 344.919808 -62.526672)
			(xy 344.589608 -62.526672) (xy 344.577522 -62.52628) (xy 344.554533 -62.518811) (xy 344.53498 -62.5046)
			(xy 344.520777 -62.485041) (xy 344.513315 -62.46205) (xy 344.5129 -62.449964) (xy 344.082116 -62.449964)
			(xy 344.081657 -62.462044) (xy 344.0742 -62.485024) (xy 344.060006 -62.504574) (xy 344.040464 -62.51878)
			(xy 344.017488 -62.52625) (xy 344.005408 -62.526672) (xy 343.675208 -62.526672) (xy 343.663122 -62.52628)
			(xy 343.640133 -62.518811) (xy 343.62058 -62.5046) (xy 343.606377 -62.485041) (xy 343.598915 -62.46205)
			(xy 343.5985 -62.449964) (xy 341.562436 -62.449964) (xy 341.561957 -62.462042) (xy 341.554503 -62.485019)
			(xy 341.540313 -62.504567) (xy 341.520776 -62.518774) (xy 341.497806 -62.526247) (xy 341.485728 -62.526672)
			(xy 341.155528 -62.526672) (xy 341.143443 -62.526263) (xy 341.120455 -62.518799) (xy 341.100901 -62.504593)
			(xy 341.086698 -62.485038) (xy 341.079236 -62.462049) (xy 341.07882 -62.449964) (xy 340.648036 -62.449964)
			(xy 340.647557 -62.462042) (xy 340.640103 -62.485019) (xy 340.625913 -62.504567) (xy 340.606376 -62.518774)
			(xy 340.583406 -62.526247) (xy 340.571328 -62.526672) (xy 340.241128 -62.526672) (xy 340.229043 -62.526263)
			(xy 340.206055 -62.518799) (xy 340.186501 -62.504593) (xy 340.172298 -62.485038) (xy 340.164836 -62.462049)
			(xy 340.16442 -62.449964) (xy 297.162878 -62.449964) (xy 297.185188 -62.474998) (xy 297.319466 -62.63782)
			(xy 297.447409 -62.805666) (xy 297.568829 -62.978288) (xy 297.683548 -63.155435) (xy 297.751584 -63.269876)
			(xy 350.300544 -63.269876) (xy 350.300544 -62.406276) (xy 350.30103 -62.379025) (xy 350.308786 -62.325077)
			(xy 350.324141 -62.272782) (xy 350.346783 -62.223205) (xy 350.376249 -62.177355) (xy 350.41194 -62.136164)
			(xy 350.453131 -62.100473) (xy 350.498981 -62.071007) (xy 350.548558 -62.048365) (xy 350.600853 -62.03301)
			(xy 350.654801 -62.025254) (xy 350.709303 -62.025254) (xy 350.763251 -62.03301) (xy 350.815546 -62.048365)
			(xy 350.865123 -62.071007) (xy 350.910973 -62.100473) (xy 350.952164 -62.136164) (xy 350.987855 -62.177355)
			(xy 351.017321 -62.223205) (xy 351.039963 -62.272782) (xy 351.055318 -62.325077) (xy 351.063074 -62.379025)
			(xy 351.06356 -62.406276) (xy 351.06356 -63.269876) (xy 351.063074 -63.297127) (xy 351.055318 -63.351075)
			(xy 351.039963 -63.40337) (xy 351.017321 -63.452947) (xy 350.987855 -63.498797) (xy 350.952164 -63.539988)
			(xy 350.910973 -63.575679) (xy 350.865123 -63.605145) (xy 350.815546 -63.627787) (xy 350.763251 -63.643142)
			(xy 350.709303 -63.650898) (xy 350.654801 -63.650898) (xy 350.600853 -63.643142) (xy 350.548558 -63.627787)
			(xy 350.498981 -63.605145) (xy 350.453131 -63.575679) (xy 350.41194 -63.539988) (xy 350.376249 -63.498797)
			(xy 350.346783 -63.452947) (xy 350.324141 -63.40337) (xy 350.308786 -63.351075) (xy 350.30103 -63.297127)
			(xy 350.300544 -63.269876) (xy 297.751584 -63.269876) (xy 297.791398 -63.336846) (xy 297.89222 -63.522255)
			(xy 297.985867 -63.71139) (xy 298.0722 -63.903972) (xy 298.151094 -64.09972) (xy 298.222432 -64.298347)
			(xy 298.286109 -64.49956) (xy 298.342033 -64.703064) (xy 298.390121 -64.908561) (xy 298.396302 -64.940434)
			(xy 325.410068 -64.940434) (xy 325.410068 -64.076834) (xy 325.410554 -64.049565) (xy 325.418316 -63.995581)
			(xy 325.433681 -63.943251) (xy 325.456338 -63.893641) (xy 325.485824 -63.84776) (xy 325.521539 -63.806543)
			(xy 325.562756 -63.770828) (xy 325.608637 -63.741342) (xy 325.658247 -63.718685) (xy 325.710577 -63.70332)
			(xy 325.764561 -63.695558) (xy 325.819099 -63.695558) (xy 325.873083 -63.70332) (xy 325.925413 -63.718685)
			(xy 325.975023 -63.741342) (xy 326.020904 -63.770828) (xy 326.062121 -63.806543) (xy 326.097836 -63.84776)
			(xy 326.127322 -63.893641) (xy 326.149979 -63.943251) (xy 326.165344 -63.995581) (xy 326.173106 -64.049565)
			(xy 326.173592 -64.076834) (xy 326.173592 -64.176148) (xy 336.97672 -64.176148) (xy 336.97672 -63.922148)
			(xy 336.977157 -63.91004) (xy 336.984646 -63.88701) (xy 336.998901 -63.867435) (xy 337.018521 -63.853239)
			(xy 337.041572 -63.845821) (xy 337.053682 -63.84544) (xy 337.383882 -63.84544) (xy 337.395971 -63.845923)
			(xy 337.418971 -63.853375) (xy 337.438551 -63.867557) (xy 337.452802 -63.887087) (xy 337.460334 -63.910061)
			(xy 337.460844 -63.922148) (xy 337.460844 -64.176148) (xy 337.89112 -64.176148) (xy 337.89112 -63.922148)
			(xy 337.891557 -63.91004) (xy 337.899046 -63.88701) (xy 337.913301 -63.867435) (xy 337.932921 -63.853239)
			(xy 337.955972 -63.845821) (xy 337.968082 -63.84544) (xy 338.298282 -63.84544) (xy 338.310371 -63.845923)
			(xy 338.333371 -63.853375) (xy 338.352951 -63.867557) (xy 338.367202 -63.887087) (xy 338.374734 -63.910061)
			(xy 338.375244 -63.922148) (xy 338.375244 -63.948564) (xy 342.009984 -63.948564) (xy 342.009984 -63.694564)
			(xy 342.010433 -63.682488) (xy 342.017905 -63.659521) (xy 342.032105 -63.639985) (xy 342.051646 -63.625792)
			(xy 342.074616 -63.618329) (xy 342.086692 -63.617856) (xy 342.416892 -63.617856) (xy 342.428963 -63.61837)
			(xy 342.451923 -63.625826) (xy 342.471457 -63.640011) (xy 342.485653 -63.659537) (xy 342.493123 -63.682494)
			(xy 342.4936 -63.694564) (xy 342.4936 -63.948564) (xy 342.924384 -63.948564) (xy 342.924384 -63.694564)
			(xy 342.924833 -63.682488) (xy 342.932305 -63.659521) (xy 342.946505 -63.639985) (xy 342.966046 -63.625792)
			(xy 342.989016 -63.618329) (xy 343.001092 -63.617856) (xy 343.331292 -63.617856) (xy 343.343363 -63.61837)
			(xy 343.366323 -63.625826) (xy 343.385857 -63.640011) (xy 343.400053 -63.659537) (xy 343.407523 -63.682494)
			(xy 343.408 -63.694564) (xy 343.408 -63.948564) (xy 345.312492 -63.948564) (xy 345.312492 -63.694564)
			(xy 345.312933 -63.682488) (xy 345.320406 -63.659519) (xy 345.334608 -63.639983) (xy 345.354151 -63.625789)
			(xy 345.377123 -63.618328) (xy 345.3892 -63.617856) (xy 345.7194 -63.617856) (xy 345.731471 -63.618364)
			(xy 345.754432 -63.625822) (xy 345.773966 -63.640008) (xy 345.788162 -63.659536) (xy 345.795631 -63.682493)
			(xy 345.796108 -63.694564) (xy 345.796108 -63.948564) (xy 346.226892 -63.948564) (xy 346.226892 -63.694564)
			(xy 346.227333 -63.682488) (xy 346.234806 -63.659519) (xy 346.249008 -63.639983) (xy 346.268551 -63.625789)
			(xy 346.291523 -63.618328) (xy 346.3036 -63.617856) (xy 346.6338 -63.617856) (xy 346.645871 -63.618364)
			(xy 346.668832 -63.625822) (xy 346.688366 -63.640008) (xy 346.702562 -63.659536) (xy 346.710031 -63.682493)
			(xy 346.710508 -63.694564) (xy 346.710508 -63.948564) (xy 346.710057 -63.960645) (xy 346.702599 -63.983626)
			(xy 346.688403 -64.003177) (xy 346.668859 -64.017383) (xy 346.645881 -64.024851) (xy 346.6338 -64.025272)
			(xy 346.3036 -64.025272) (xy 346.291514 -64.024887) (xy 346.268525 -64.017415) (xy 346.248971 -64.003203)
			(xy 346.234768 -63.983643) (xy 346.227307 -63.960651) (xy 346.226892 -63.948564) (xy 345.796108 -63.948564)
			(xy 345.795657 -63.960645) (xy 345.788199 -63.983626) (xy 345.774003 -64.003177) (xy 345.754459 -64.017383)
			(xy 345.731481 -64.024851) (xy 345.7194 -64.025272) (xy 345.3892 -64.025272) (xy 345.377114 -64.024887)
			(xy 345.354125 -64.017415) (xy 345.334571 -64.003203) (xy 345.320368 -63.983643) (xy 345.312907 -63.960651)
			(xy 345.312492 -63.948564) (xy 343.408 -63.948564) (xy 343.407556 -63.960646) (xy 343.400098 -63.983629)
			(xy 343.3859 -64.00318) (xy 343.366354 -64.017385) (xy 343.343373 -64.024852) (xy 343.331292 -64.025272)
			(xy 343.001092 -64.025272) (xy 342.989005 -64.024894) (xy 342.966016 -64.01742) (xy 342.946463 -64.003206)
			(xy 342.93226 -63.983644) (xy 342.924799 -63.960651) (xy 342.924384 -63.948564) (xy 342.4936 -63.948564)
			(xy 342.493156 -63.960646) (xy 342.485698 -63.983629) (xy 342.4715 -64.00318) (xy 342.451954 -64.017385)
			(xy 342.428973 -64.024852) (xy 342.416892 -64.025272) (xy 342.086692 -64.025272) (xy 342.074605 -64.024894)
			(xy 342.051616 -64.01742) (xy 342.032063 -64.003206) (xy 342.01786 -63.983644) (xy 342.010399 -63.960651)
			(xy 342.009984 -63.948564) (xy 338.375244 -63.948564) (xy 338.375244 -64.176148) (xy 338.374825 -64.188255)
			(xy 338.367318 -64.211276) (xy 338.353055 -64.230845) (xy 338.333438 -64.245039) (xy 338.31039 -64.252467)
			(xy 338.298282 -64.252856) (xy 337.968082 -64.252856) (xy 337.955991 -64.252408) (xy 337.932989 -64.244946)
			(xy 337.913409 -64.230755) (xy 337.899159 -64.211217) (xy 337.891628 -64.188237) (xy 337.89112 -64.176148)
			(xy 337.460844 -64.176148) (xy 337.460425 -64.188255) (xy 337.452918 -64.211276) (xy 337.438655 -64.230845)
			(xy 337.419038 -64.245039) (xy 337.39599 -64.252467) (xy 337.383882 -64.252856) (xy 337.053682 -64.252856)
			(xy 337.041591 -64.252408) (xy 337.018589 -64.244946) (xy 336.999009 -64.230755) (xy 336.984759 -64.211217)
			(xy 336.977228 -64.188237) (xy 336.97672 -64.176148) (xy 326.173592 -64.176148) (xy 326.173592 -64.709548)
			(xy 336.97672 -64.709548) (xy 336.97672 -64.455548) (xy 336.977157 -64.44344) (xy 336.984646 -64.42041)
			(xy 336.998901 -64.400835) (xy 337.018521 -64.386639) (xy 337.041572 -64.379221) (xy 337.053682 -64.37884)
			(xy 337.383882 -64.37884) (xy 337.395971 -64.379323) (xy 337.418971 -64.386775) (xy 337.438551 -64.400957)
			(xy 337.452802 -64.420487) (xy 337.460334 -64.443461) (xy 337.460844 -64.455548) (xy 337.460844 -64.709548)
			(xy 337.89112 -64.709548) (xy 337.89112 -64.455548) (xy 337.891557 -64.44344) (xy 337.899046 -64.42041)
			(xy 337.913301 -64.400835) (xy 337.932921 -64.386639) (xy 337.955972 -64.379221) (xy 337.968082 -64.37884)
			(xy 338.298282 -64.37884) (xy 338.310371 -64.379323) (xy 338.333371 -64.386775) (xy 338.352951 -64.400957)
			(xy 338.367202 -64.420487) (xy 338.374734 -64.443461) (xy 338.375244 -64.455548) (xy 338.375244 -64.481964)
			(xy 342.009984 -64.481964) (xy 342.009984 -64.227964) (xy 342.010433 -64.215888) (xy 342.017905 -64.192921)
			(xy 342.032105 -64.173385) (xy 342.051646 -64.159192) (xy 342.074616 -64.151729) (xy 342.086692 -64.151256)
			(xy 342.416892 -64.151256) (xy 342.428963 -64.15177) (xy 342.451923 -64.159226) (xy 342.471457 -64.173411)
			(xy 342.485653 -64.192937) (xy 342.493123 -64.215894) (xy 342.4936 -64.227964) (xy 342.4936 -64.481964)
			(xy 342.924384 -64.481964) (xy 342.924384 -64.227964) (xy 342.924833 -64.215888) (xy 342.932305 -64.192921)
			(xy 342.946505 -64.173385) (xy 342.966046 -64.159192) (xy 342.989016 -64.151729) (xy 343.001092 -64.151256)
			(xy 343.331292 -64.151256) (xy 343.343363 -64.15177) (xy 343.366323 -64.159226) (xy 343.385857 -64.173411)
			(xy 343.400053 -64.192937) (xy 343.407523 -64.215894) (xy 343.408 -64.227964) (xy 343.408 -64.481964)
			(xy 345.312492 -64.481964) (xy 345.312492 -64.227964) (xy 345.312933 -64.215888) (xy 345.320406 -64.192919)
			(xy 345.334608 -64.173383) (xy 345.354151 -64.159189) (xy 345.377123 -64.151728) (xy 345.3892 -64.151256)
			(xy 345.7194 -64.151256) (xy 345.731471 -64.151764) (xy 345.754432 -64.159222) (xy 345.773966 -64.173408)
			(xy 345.788162 -64.192936) (xy 345.795631 -64.215893) (xy 345.796108 -64.227964) (xy 345.796108 -64.481964)
			(xy 346.226892 -64.481964) (xy 346.226892 -64.227964) (xy 346.227333 -64.215888) (xy 346.234806 -64.192919)
			(xy 346.249008 -64.173383) (xy 346.268551 -64.159189) (xy 346.291523 -64.151728) (xy 346.3036 -64.151256)
			(xy 346.6338 -64.151256) (xy 346.645871 -64.151764) (xy 346.668832 -64.159222) (xy 346.688366 -64.173408)
			(xy 346.702562 -64.192936) (xy 346.710031 -64.215893) (xy 346.710508 -64.227964) (xy 346.710508 -64.34582)
			(xy 349.205296 -64.34582) (xy 349.205296 -64.01562) (xy 349.20573 -64.003538) (xy 349.213192 -63.980555)
			(xy 349.227393 -63.961004) (xy 349.246941 -63.9468) (xy 349.269922 -63.939332) (xy 349.282004 -63.938912)
			(xy 349.536004 -63.938912) (xy 349.548089 -63.939309) (xy 349.571075 -63.94678) (xy 349.590627 -63.96099)
			(xy 349.604831 -63.980546) (xy 349.612294 -64.003535) (xy 349.612712 -64.01562) (xy 349.612712 -64.34582)
			(xy 349.738696 -64.34582) (xy 349.738696 -64.01562) (xy 349.73913 -64.003538) (xy 349.746592 -63.980555)
			(xy 349.760793 -63.961004) (xy 349.780341 -63.9468) (xy 349.803322 -63.939332) (xy 349.815404 -63.938912)
			(xy 350.069404 -63.938912) (xy 350.081489 -63.939309) (xy 350.104475 -63.94678) (xy 350.124027 -63.96099)
			(xy 350.138231 -63.980546) (xy 350.145694 -64.003535) (xy 350.146112 -64.01562) (xy 350.146112 -64.34582)
			(xy 350.145653 -64.357895) (xy 350.138185 -64.380862) (xy 350.123987 -64.400399) (xy 350.104448 -64.414593)
			(xy 350.081479 -64.422055) (xy 350.069404 -64.422528) (xy 349.815404 -64.422528) (xy 349.803332 -64.422033)
			(xy 349.780368 -64.414574) (xy 349.760833 -64.400384) (xy 349.746637 -64.380854) (xy 349.739171 -64.357892)
			(xy 349.738696 -64.34582) (xy 349.612712 -64.34582) (xy 349.612253 -64.357895) (xy 349.604785 -64.380862)
			(xy 349.590587 -64.400399) (xy 349.571048 -64.414593) (xy 349.548079 -64.422055) (xy 349.536004 -64.422528)
			(xy 349.282004 -64.422528) (xy 349.269932 -64.422033) (xy 349.246968 -64.414574) (xy 349.227433 -64.400384)
			(xy 349.213237 -64.380854) (xy 349.205771 -64.357892) (xy 349.205296 -64.34582) (xy 346.710508 -64.34582)
			(xy 346.710508 -64.481964) (xy 346.710057 -64.494045) (xy 346.702599 -64.517026) (xy 346.688403 -64.536577)
			(xy 346.668859 -64.550783) (xy 346.645881 -64.558251) (xy 346.6338 -64.558672) (xy 346.3036 -64.558672)
			(xy 346.291514 -64.558287) (xy 346.268525 -64.550815) (xy 346.248971 -64.536603) (xy 346.234768 -64.517043)
			(xy 346.227307 -64.494051) (xy 346.226892 -64.481964) (xy 345.796108 -64.481964) (xy 345.795657 -64.494045)
			(xy 345.788199 -64.517026) (xy 345.774003 -64.536577) (xy 345.754459 -64.550783) (xy 345.731481 -64.558251)
			(xy 345.7194 -64.558672) (xy 345.3892 -64.558672) (xy 345.377114 -64.558287) (xy 345.354125 -64.550815)
			(xy 345.334571 -64.536603) (xy 345.320368 -64.517043) (xy 345.312907 -64.494051) (xy 345.312492 -64.481964)
			(xy 343.408 -64.481964) (xy 343.407556 -64.494046) (xy 343.400098 -64.517029) (xy 343.3859 -64.53658)
			(xy 343.366354 -64.550785) (xy 343.343373 -64.558252) (xy 343.331292 -64.558672) (xy 343.001092 -64.558672)
			(xy 342.989005 -64.558294) (xy 342.966016 -64.55082) (xy 342.946463 -64.536606) (xy 342.93226 -64.517044)
			(xy 342.924799 -64.494051) (xy 342.924384 -64.481964) (xy 342.4936 -64.481964) (xy 342.493156 -64.494046)
			(xy 342.485698 -64.517029) (xy 342.4715 -64.53658) (xy 342.451954 -64.550785) (xy 342.428973 -64.558252)
			(xy 342.416892 -64.558672) (xy 342.086692 -64.558672) (xy 342.074605 -64.558294) (xy 342.051616 -64.55082)
			(xy 342.032063 -64.536606) (xy 342.01786 -64.517044) (xy 342.010399 -64.494051) (xy 342.009984 -64.481964)
			(xy 338.375244 -64.481964) (xy 338.375244 -64.709548) (xy 338.374825 -64.721655) (xy 338.367318 -64.744676)
			(xy 338.353055 -64.764245) (xy 338.333438 -64.778439) (xy 338.31039 -64.785867) (xy 338.298282 -64.786256)
			(xy 337.968082 -64.786256) (xy 337.955991 -64.785808) (xy 337.932989 -64.778346) (xy 337.913409 -64.764155)
			(xy 337.899159 -64.744617) (xy 337.891628 -64.721637) (xy 337.89112 -64.709548) (xy 337.460844 -64.709548)
			(xy 337.460425 -64.721655) (xy 337.452918 -64.744676) (xy 337.438655 -64.764245) (xy 337.419038 -64.778439)
			(xy 337.39599 -64.785867) (xy 337.383882 -64.786256) (xy 337.053682 -64.786256) (xy 337.041591 -64.785808)
			(xy 337.018589 -64.778346) (xy 336.999009 -64.764155) (xy 336.984759 -64.744617) (xy 336.977228 -64.721637)
			(xy 336.97672 -64.709548) (xy 326.173592 -64.709548) (xy 326.173592 -64.940434) (xy 326.173106 -64.967703)
			(xy 326.165344 -65.021687) (xy 326.149979 -65.074017) (xy 326.127322 -65.123627) (xy 326.097836 -65.169508)
			(xy 326.062121 -65.210725) (xy 326.020904 -65.24644) (xy 325.999462 -65.26022) (xy 349.205296 -65.26022)
			(xy 349.205296 -64.93002) (xy 349.20573 -64.917938) (xy 349.213192 -64.894955) (xy 349.227393 -64.875404)
			(xy 349.246941 -64.8612) (xy 349.269922 -64.853732) (xy 349.282004 -64.853312) (xy 349.536004 -64.853312)
			(xy 349.548089 -64.853709) (xy 349.571075 -64.86118) (xy 349.590627 -64.87539) (xy 349.604831 -64.894946)
			(xy 349.612294 -64.917935) (xy 349.612712 -64.93002) (xy 349.612712 -65.26022) (xy 349.738696 -65.26022)
			(xy 349.738696 -64.93002) (xy 349.73913 -64.917938) (xy 349.746592 -64.894955) (xy 349.760793 -64.875404)
			(xy 349.780341 -64.8612) (xy 349.803322 -64.853732) (xy 349.815404 -64.853312) (xy 350.069404 -64.853312)
			(xy 350.081489 -64.853709) (xy 350.104475 -64.86118) (xy 350.124027 -64.87539) (xy 350.138231 -64.894946)
			(xy 350.145694 -64.917935) (xy 350.146112 -64.93002) (xy 350.146112 -65.26022) (xy 350.145653 -65.272295)
			(xy 350.138185 -65.295262) (xy 350.123987 -65.314799) (xy 350.104448 -65.328993) (xy 350.102697 -65.329562)
			(xy 352.362008 -65.329562) (xy 352.362008 -64.465962) (xy 352.362494 -64.438711) (xy 352.37025 -64.384763)
			(xy 352.385605 -64.332468) (xy 352.408247 -64.282891) (xy 352.437713 -64.237041) (xy 352.473404 -64.19585)
			(xy 352.514595 -64.160159) (xy 352.560445 -64.130693) (xy 352.610022 -64.108051) (xy 352.662317 -64.092696)
			(xy 352.716265 -64.08494) (xy 352.770767 -64.08494) (xy 352.824715 -64.092696) (xy 352.87701 -64.108051)
			(xy 352.926587 -64.130693) (xy 352.972437 -64.160159) (xy 353.013628 -64.19585) (xy 353.049319 -64.237041)
			(xy 353.078785 -64.282891) (xy 353.101427 -64.332468) (xy 353.116782 -64.384763) (xy 353.124538 -64.438711)
			(xy 353.125024 -64.465962) (xy 353.125024 -65.329562) (xy 353.124538 -65.356813) (xy 353.116782 -65.410761)
			(xy 353.101427 -65.463056) (xy 353.078785 -65.512633) (xy 353.049319 -65.558483) (xy 353.013628 -65.599674)
			(xy 352.972437 -65.635365) (xy 352.926587 -65.664831) (xy 352.87701 -65.687473) (xy 352.824715 -65.702828)
			(xy 352.770767 -65.710584) (xy 352.716265 -65.710584) (xy 352.662317 -65.702828) (xy 352.610022 -65.687473)
			(xy 352.560445 -65.664831) (xy 352.514595 -65.635365) (xy 352.473404 -65.599674) (xy 352.437713 -65.558483)
			(xy 352.408247 -65.512633) (xy 352.385605 -65.463056) (xy 352.37025 -65.410761) (xy 352.362494 -65.356813)
			(xy 352.362008 -65.329562) (xy 350.102697 -65.329562) (xy 350.081479 -65.336455) (xy 350.069404 -65.336928)
			(xy 349.815404 -65.336928) (xy 349.803332 -65.336433) (xy 349.780368 -65.328974) (xy 349.760833 -65.314784)
			(xy 349.746637 -65.295254) (xy 349.739171 -65.272292) (xy 349.738696 -65.26022) (xy 349.612712 -65.26022)
			(xy 349.612253 -65.272295) (xy 349.604785 -65.295262) (xy 349.590587 -65.314799) (xy 349.571048 -65.328993)
			(xy 349.548079 -65.336455) (xy 349.536004 -65.336928) (xy 349.282004 -65.336928) (xy 349.269932 -65.336433)
			(xy 349.246968 -65.328974) (xy 349.227433 -65.314784) (xy 349.213237 -65.295254) (xy 349.205771 -65.272292)
			(xy 349.205296 -65.26022) (xy 325.999462 -65.26022) (xy 325.975023 -65.275926) (xy 325.925413 -65.298583)
			(xy 325.873083 -65.313948) (xy 325.819099 -65.32171) (xy 325.764561 -65.32171) (xy 325.710577 -65.313948)
			(xy 325.658247 -65.298583) (xy 325.608637 -65.275926) (xy 325.562756 -65.24644) (xy 325.521539 -65.210725)
			(xy 325.485824 -65.169508) (xy 325.456338 -65.123627) (xy 325.433681 -65.074017) (xy 325.418316 -65.021687)
			(xy 325.410554 -64.967703) (xy 325.410068 -64.940434) (xy 298.396302 -64.940434) (xy 298.430303 -65.115749)
			(xy 298.46252 -65.324324) (xy 298.486723 -65.533981) (xy 298.502879 -65.74441) (xy 298.510963 -65.955304)
			(xy 298.511468 -66.060828) (xy 298.511468 -66.285364) (xy 339.201252 -66.285364) (xy 339.201252 -66.031364)
			(xy 339.201733 -66.019292) (xy 339.2092 -65.99633) (xy 339.223394 -65.976797) (xy 339.242926 -65.962602)
			(xy 339.265888 -65.955133) (xy 339.27796 -65.954656) (xy 339.60816 -65.954656) (xy 339.620237 -65.955146)
			(xy 339.643212 -65.962598) (xy 339.66276 -65.976786) (xy 339.676967 -65.996319) (xy 339.684442 -66.019287)
			(xy 339.684868 -66.031364) (xy 339.684868 -66.285364) (xy 340.115652 -66.285364) (xy 340.115652 -66.031364)
			(xy 340.116133 -66.019292) (xy 340.1236 -65.99633) (xy 340.137794 -65.976797) (xy 340.157326 -65.962602)
			(xy 340.180288 -65.955133) (xy 340.19236 -65.954656) (xy 340.52256 -65.954656) (xy 340.534637 -65.955146)
			(xy 340.557612 -65.962598) (xy 340.57716 -65.976786) (xy 340.591367 -65.996319) (xy 340.598842 -66.019287)
			(xy 340.599268 -66.031364) (xy 340.599268 -66.285364) (xy 340.598856 -66.297449) (xy 340.591394 -66.320437)
			(xy 340.577189 -66.339991) (xy 340.557634 -66.354195) (xy 340.534645 -66.361657) (xy 340.52256 -66.362072)
			(xy 340.19236 -66.362072) (xy 340.18028 -66.361669) (xy 340.157305 -66.354192) (xy 340.137766 -66.33998)
			(xy 340.123574 -66.320427) (xy 340.116119 -66.297445) (xy 340.115652 -66.285364) (xy 339.684868 -66.285364)
			(xy 339.684456 -66.297449) (xy 339.676994 -66.320437) (xy 339.662789 -66.339991) (xy 339.643234 -66.354195)
			(xy 339.620245 -66.361657) (xy 339.60816 -66.362072) (xy 339.27796 -66.362072) (xy 339.26588 -66.361669)
			(xy 339.242905 -66.354192) (xy 339.223366 -66.33998) (xy 339.209174 -66.320427) (xy 339.201719 -66.297445)
			(xy 339.201252 -66.285364) (xy 298.511468 -66.285364) (xy 298.511468 -68.449952) (xy 314.840884 -68.449952)
			(xy 314.844867 -68.321934) (xy 314.856802 -68.194412) (xy 314.876641 -68.067878) (xy 314.904308 -67.942822)
			(xy 314.939697 -67.819729) (xy 314.98267 -67.699073) (xy 315.033061 -67.581323) (xy 315.090675 -67.466933)
			(xy 315.155289 -67.356346) (xy 315.226653 -67.24999) (xy 315.304491 -67.148277) (xy 315.388502 -67.051599)
			(xy 315.478361 -66.960332) (xy 315.57372 -66.874827) (xy 315.674211 -66.795417) (xy 315.779444 -66.722407)
			(xy 315.889013 -66.656081) (xy 316.002493 -66.596695) (xy 316.119445 -66.544479) (xy 316.239418 -66.499635)
			(xy 316.361946 -66.462337) (xy 316.486557 -66.432728) (xy 316.612766 -66.410923) (xy 316.740088 -66.397007)
			(xy 316.868028 -66.391033) (xy 316.996092 -66.393025) (xy 317.123785 -66.402975) (xy 317.250612 -66.420844)
			(xy 317.376083 -66.446563) (xy 317.499712 -66.480033) (xy 317.621021 -66.521124) (xy 317.739541 -66.569678)
			(xy 317.854813 -66.625506) (xy 317.966391 -66.688392) (xy 318.073844 -66.758094) (xy 318.155731 -66.818764)
			(xy 339.201252 -66.818764) (xy 339.201252 -66.564764) (xy 339.201733 -66.552692) (xy 339.2092 -66.52973)
			(xy 339.223394 -66.510197) (xy 339.242926 -66.496002) (xy 339.265888 -66.488533) (xy 339.27796 -66.488056)
			(xy 339.60816 -66.488056) (xy 339.620237 -66.488546) (xy 339.643212 -66.495998) (xy 339.66276 -66.510186)
			(xy 339.676967 -66.529719) (xy 339.684442 -66.552687) (xy 339.684868 -66.564764) (xy 339.684868 -66.818764)
			(xy 340.115652 -66.818764) (xy 340.115652 -66.564764) (xy 340.116133 -66.552692) (xy 340.1236 -66.52973)
			(xy 340.137794 -66.510197) (xy 340.157326 -66.496002) (xy 340.180288 -66.488533) (xy 340.19236 -66.488056)
			(xy 340.52256 -66.488056) (xy 340.534637 -66.488546) (xy 340.557612 -66.495998) (xy 340.57716 -66.510186)
			(xy 340.591367 -66.529719) (xy 340.598842 -66.552687) (xy 340.599268 -66.564764) (xy 340.599268 -66.818764)
			(xy 340.598856 -66.830849) (xy 340.591394 -66.853837) (xy 340.577189 -66.873391) (xy 340.557634 -66.887595)
			(xy 340.534645 -66.895057) (xy 340.52256 -66.895472) (xy 340.19236 -66.895472) (xy 340.18028 -66.895069)
			(xy 340.157305 -66.887592) (xy 340.137766 -66.87338) (xy 340.123574 -66.853827) (xy 340.116119 -66.830845)
			(xy 340.115652 -66.818764) (xy 339.684868 -66.818764) (xy 339.684456 -66.830849) (xy 339.676994 -66.853837)
			(xy 339.662789 -66.873391) (xy 339.643234 -66.887595) (xy 339.620245 -66.895057) (xy 339.60816 -66.895472)
			(xy 339.27796 -66.895472) (xy 339.26588 -66.895069) (xy 339.242905 -66.887592) (xy 339.223366 -66.87338)
			(xy 339.209174 -66.853827) (xy 339.201719 -66.830845) (xy 339.201252 -66.818764) (xy 318.155731 -66.818764)
			(xy 318.176756 -66.834341) (xy 318.274728 -66.916838) (xy 318.323666 -66.963544) (xy 350.27108 -66.963544)
			(xy 350.27108 -66.099944) (xy 350.271566 -66.072693) (xy 350.279322 -66.018745) (xy 350.294677 -65.96645)
			(xy 350.317319 -65.916873) (xy 350.346785 -65.871023) (xy 350.382476 -65.829832) (xy 350.423667 -65.794141)
			(xy 350.469517 -65.764675) (xy 350.519094 -65.742033) (xy 350.571389 -65.726678) (xy 350.625337 -65.718922)
			(xy 350.679839 -65.718922) (xy 350.733787 -65.726678) (xy 350.786082 -65.742033) (xy 350.835659 -65.764675)
			(xy 350.881509 -65.794141) (xy 350.9227 -65.829832) (xy 350.958391 -65.871023) (xy 350.987857 -65.916873)
			(xy 351.010499 -65.96645) (xy 351.025854 -66.018745) (xy 351.03361 -66.072693) (xy 351.034096 -66.099944)
			(xy 351.034096 -66.963544) (xy 351.03361 -66.990795) (xy 351.025854 -67.044743) (xy 351.010499 -67.097038)
			(xy 351.005595 -67.107776) (xy 396.642323 -67.107776) (xy 396.642323 -67.022004) (xy 396.650237 -66.936596)
			(xy 396.665998 -66.852284) (xy 396.689471 -66.769785) (xy 396.720456 -66.689804) (xy 396.758688 -66.613023)
			(xy 396.803842 -66.540098) (xy 396.855532 -66.47165) (xy 396.913317 -66.408263) (xy 396.976704 -66.350478)
			(xy 397.045152 -66.298788) (xy 397.118077 -66.253634) (xy 397.194858 -66.215402) (xy 397.274839 -66.184417)
			(xy 397.357338 -66.160944) (xy 397.44165 -66.145183) (xy 397.527058 -66.137269) (xy 397.61283 -66.137269)
			(xy 397.698238 -66.145183) (xy 397.78255 -66.160944) (xy 397.865049 -66.184417) (xy 397.94503 -66.215402)
			(xy 398.021811 -66.253634) (xy 398.094736 -66.298788) (xy 398.163184 -66.350478) (xy 398.226571 -66.408263)
			(xy 398.284356 -66.47165) (xy 398.336046 -66.540098) (xy 398.3812 -66.613023) (xy 398.419432 -66.689804)
			(xy 398.450417 -66.769785) (xy 398.47389 -66.852284) (xy 398.489651 -66.936596) (xy 398.497565 -67.022004)
			(xy 398.49806 -67.06489) (xy 398.497565 -67.107776) (xy 398.489651 -67.193184) (xy 398.47389 -67.277496)
			(xy 398.450417 -67.359995) (xy 398.419432 -67.439976) (xy 398.3812 -67.516757) (xy 398.336046 -67.589682)
			(xy 398.284356 -67.65813) (xy 398.226571 -67.721517) (xy 398.163184 -67.779302) (xy 398.094736 -67.830992)
			(xy 398.021811 -67.876146) (xy 397.94503 -67.914378) (xy 397.865049 -67.945363) (xy 397.78255 -67.968836)
			(xy 397.698238 -67.984597) (xy 397.61283 -67.992511) (xy 397.527058 -67.992511) (xy 397.44165 -67.984597)
			(xy 397.357338 -67.968836) (xy 397.274839 -67.945363) (xy 397.194858 -67.914378) (xy 397.118077 -67.876146)
			(xy 397.045152 -67.830992) (xy 396.976704 -67.779302) (xy 396.913317 -67.721517) (xy 396.855532 -67.65813)
			(xy 396.803842 -67.589682) (xy 396.758688 -67.516757) (xy 396.720456 -67.439976) (xy 396.689471 -67.359995)
			(xy 396.665998 -67.277496) (xy 396.650237 -67.193184) (xy 396.642323 -67.107776) (xy 351.005595 -67.107776)
			(xy 350.987857 -67.146615) (xy 350.958391 -67.192465) (xy 350.9227 -67.233656) (xy 350.881509 -67.269347)
			(xy 350.835659 -67.298813) (xy 350.786082 -67.321455) (xy 350.733787 -67.33681) (xy 350.679839 -67.344566)
			(xy 350.625337 -67.344566) (xy 350.571389 -67.33681) (xy 350.519094 -67.321455) (xy 350.469517 -67.298813)
			(xy 350.423667 -67.269347) (xy 350.382476 -67.233656) (xy 350.346785 -67.192465) (xy 350.317319 -67.146615)
			(xy 350.294677 -67.097038) (xy 350.279322 -67.044743) (xy 350.271566 -66.990795) (xy 350.27108 -66.963544)
			(xy 318.323666 -66.963544) (xy 318.367382 -67.005267) (xy 318.454359 -67.099285) (xy 318.535323 -67.198528)
			(xy 318.60996 -67.302613) (xy 318.677982 -67.411137) (xy 318.739126 -67.52368) (xy 318.793154 -67.639806)
			(xy 318.839859 -67.759067) (xy 318.879059 -67.881) (xy 318.910602 -68.005135) (xy 318.934367 -68.130991)
			(xy 318.950261 -68.25808) (xy 318.958224 -68.385912) (xy 318.958722 -68.449952) (xy 318.958224 -68.513992)
			(xy 318.950261 -68.641824) (xy 318.934367 -68.768913) (xy 318.910602 -68.894769) (xy 318.879059 -69.018904)
			(xy 318.851129 -69.10578) (xy 351.73158 -69.10578) (xy 351.73158 -68.24218) (xy 351.732066 -68.214911)
			(xy 351.739828 -68.160927) (xy 351.755193 -68.108597) (xy 351.77785 -68.058987) (xy 351.807336 -68.013106)
			(xy 351.843051 -67.971889) (xy 351.884268 -67.936174) (xy 351.930149 -67.906688) (xy 351.979759 -67.884031)
			(xy 352.032089 -67.868666) (xy 352.086073 -67.860904) (xy 352.140611 -67.860904) (xy 352.194595 -67.868666)
			(xy 352.246925 -67.884031) (xy 352.296535 -67.906688) (xy 352.342416 -67.936174) (xy 352.383633 -67.971889)
			(xy 352.419348 -68.013106) (xy 352.448834 -68.058987) (xy 352.471491 -68.108597) (xy 352.486856 -68.160927)
			(xy 352.494618 -68.214911) (xy 352.495104 -68.24218) (xy 352.495104 -69.10578) (xy 352.494618 -69.133049)
			(xy 352.486856 -69.187033) (xy 352.471491 -69.239363) (xy 352.448834 -69.288973) (xy 352.419348 -69.334854)
			(xy 352.383633 -69.376071) (xy 352.342416 -69.411786) (xy 352.296535 -69.441272) (xy 352.246925 -69.463929)
			(xy 352.194595 -69.479294) (xy 352.140611 -69.487056) (xy 352.086073 -69.487056) (xy 352.032089 -69.479294)
			(xy 351.979759 -69.463929) (xy 351.930149 -69.441272) (xy 351.884268 -69.411786) (xy 351.843051 -69.376071)
			(xy 351.807336 -69.334854) (xy 351.77785 -69.288973) (xy 351.755193 -69.239363) (xy 351.739828 -69.187033)
			(xy 351.732066 -69.133049) (xy 351.73158 -69.10578) (xy 318.851129 -69.10578) (xy 318.839859 -69.140837)
			(xy 318.793154 -69.260098) (xy 318.739126 -69.376224) (xy 318.677982 -69.488767) (xy 318.60996 -69.597291)
			(xy 318.535323 -69.701376) (xy 318.454359 -69.800619) (xy 318.367382 -69.894637) (xy 318.274728 -69.983066)
			(xy 318.176756 -70.065563) (xy 318.073844 -70.14181) (xy 317.966391 -70.211512) (xy 317.854813 -70.274398)
			(xy 317.739541 -70.330226) (xy 317.621021 -70.37878) (xy 317.499712 -70.419871) (xy 317.376083 -70.453341)
			(xy 317.250612 -70.47906) (xy 317.123785 -70.496929) (xy 316.996092 -70.506879) (xy 316.868028 -70.508871)
			(xy 316.740088 -70.502897) (xy 316.612766 -70.488981) (xy 316.486557 -70.467176) (xy 316.361946 -70.437567)
			(xy 316.239418 -70.400269) (xy 316.119445 -70.355425) (xy 316.002493 -70.303209) (xy 315.889013 -70.243823)
			(xy 315.779444 -70.177497) (xy 315.674211 -70.104487) (xy 315.57372 -70.025077) (xy 315.478361 -69.939572)
			(xy 315.388502 -69.848305) (xy 315.304491 -69.751627) (xy 315.226653 -69.649914) (xy 315.155289 -69.543558)
			(xy 315.090675 -69.432971) (xy 315.033061 -69.318581) (xy 314.98267 -69.200831) (xy 314.939697 -69.080175)
			(xy 314.904308 -68.957082) (xy 314.876641 -68.832026) (xy 314.856802 -68.705492) (xy 314.844867 -68.57797)
			(xy 314.840884 -68.449952) (xy 298.511468 -68.449952) (xy 298.511468 -71.213074) (xy 341.168388 -71.213074)
			(xy 341.168388 -71.158526) (xy 341.176151 -71.104534) (xy 341.19152 -71.052197) (xy 341.214181 -71.00258)
			(xy 341.243673 -70.956692) (xy 341.279395 -70.91547) (xy 341.320621 -70.879751) (xy 341.366511 -70.850263)
			(xy 341.416131 -70.827607) (xy 341.46847 -70.812243) (xy 341.522462 -70.804485) (xy 341.549736 -70.804024)
			(xy 342.413336 -70.804024) (xy 342.440603 -70.804541) (xy 342.49458 -70.812306) (xy 342.546904 -70.827674)
			(xy 342.596508 -70.850332) (xy 342.642382 -70.879817) (xy 342.683594 -70.915531) (xy 342.719304 -70.956747)
			(xy 342.748786 -71.002624) (xy 342.771438 -71.05223) (xy 342.786801 -71.104555) (xy 342.794562 -71.158533)
			(xy 342.794562 -71.213067) (xy 342.786801 -71.267045) (xy 342.771438 -71.31937) (xy 342.748786 -71.368976)
			(xy 342.719304 -71.414853) (xy 342.683594 -71.456069) (xy 342.642382 -71.491783) (xy 342.596508 -71.521268)
			(xy 342.546904 -71.543926) (xy 342.49458 -71.559294) (xy 342.440603 -71.567059) (xy 342.413336 -71.567548)
			(xy 341.549736 -71.567548) (xy 341.522462 -71.567115) (xy 341.46847 -71.559357) (xy 341.416131 -71.543993)
			(xy 341.366511 -71.521337) (xy 341.320621 -71.491849) (xy 341.279395 -71.45613) (xy 341.243673 -71.414908)
			(xy 341.214181 -71.36902) (xy 341.19152 -71.319403) (xy 341.176151 -71.267066) (xy 341.168388 -71.213074)
			(xy 298.511468 -71.213074) (xy 298.511468 -71.844253) (xy 346.360454 -71.844253) (xy 346.360454 -71.789747)
			(xy 346.368211 -71.735796) (xy 346.383567 -71.683499) (xy 346.406209 -71.633919) (xy 346.435677 -71.588066)
			(xy 346.47137 -71.546873) (xy 346.512562 -71.511179) (xy 346.558415 -71.481711) (xy 346.607995 -71.459068)
			(xy 346.660293 -71.443712) (xy 346.714243 -71.435954) (xy 346.741496 -71.435468) (xy 347.605096 -71.435468)
			(xy 347.632347 -71.435979) (xy 347.686295 -71.443735) (xy 347.73859 -71.45909) (xy 347.788168 -71.481731)
			(xy 347.834019 -71.511197) (xy 347.875209 -71.546888) (xy 347.910901 -71.588078) (xy 347.940367 -71.633929)
			(xy 347.963009 -71.683506) (xy 347.978364 -71.735801) (xy 347.986121 -71.789749) (xy 347.986121 -71.844251)
			(xy 347.978364 -71.898199) (xy 347.963009 -71.950494) (xy 347.940367 -72.000071) (xy 347.910901 -72.045922)
			(xy 347.875209 -72.087112) (xy 347.834019 -72.122803) (xy 347.788168 -72.152269) (xy 347.73859 -72.17491)
			(xy 347.686295 -72.190265) (xy 347.632347 -72.198021) (xy 347.605096 -72.198484) (xy 346.741496 -72.198484)
			(xy 346.714243 -72.198046) (xy 346.660293 -72.190288) (xy 346.607995 -72.174932) (xy 346.558415 -72.152289)
			(xy 346.512562 -72.122821) (xy 346.47137 -72.087127) (xy 346.435677 -72.045934) (xy 346.406209 -72.000081)
			(xy 346.383567 -71.950501) (xy 346.368211 -71.898204) (xy 346.360454 -71.844253) (xy 298.511468 -71.844253)
			(xy 298.511468 -72.404055) (xy 332.037847 -72.404055) (xy 332.037847 -72.349545) (xy 332.045606 -72.295589)
			(xy 332.060964 -72.243286) (xy 332.083611 -72.193702) (xy 332.113083 -72.147846) (xy 332.148782 -72.106651)
			(xy 332.189981 -72.070957) (xy 332.235841 -72.041489) (xy 332.285427 -72.018849) (xy 332.337732 -72.003496)
			(xy 332.391689 -71.995744) (xy 332.418944 -71.995284) (xy 333.282544 -71.995284) (xy 333.309793 -71.995789)
			(xy 333.363734 -72.00355) (xy 333.416023 -72.018909) (xy 333.465593 -72.041552) (xy 333.511437 -72.071019)
			(xy 333.552622 -72.10671) (xy 333.588308 -72.147898) (xy 333.617769 -72.193745) (xy 333.640407 -72.243318)
			(xy 333.655759 -72.295609) (xy 333.660251 -72.326853) (xy 343.845854 -72.326853) (xy 343.845854 -72.272347)
			(xy 343.853611 -72.218396) (xy 343.868967 -72.166099) (xy 343.891609 -72.116519) (xy 343.921077 -72.070666)
			(xy 343.95677 -72.029473) (xy 343.997962 -71.993779) (xy 344.043815 -71.964311) (xy 344.093395 -71.941668)
			(xy 344.145693 -71.926312) (xy 344.199643 -71.918554) (xy 344.226896 -71.918068) (xy 345.090496 -71.918068)
			(xy 345.117747 -71.918579) (xy 345.171695 -71.926335) (xy 345.22399 -71.94169) (xy 345.273568 -71.964331)
			(xy 345.319419 -71.993797) (xy 345.360609 -72.029488) (xy 345.396301 -72.070678) (xy 345.425767 -72.116529)
			(xy 345.448409 -72.166106) (xy 345.463764 -72.218401) (xy 345.471521 -72.272349) (xy 345.471521 -72.326851)
			(xy 345.463764 -72.380799) (xy 345.448409 -72.433094) (xy 345.425767 -72.482671) (xy 345.396301 -72.528522)
			(xy 345.360609 -72.569712) (xy 345.319419 -72.605403) (xy 345.273568 -72.634869) (xy 345.22399 -72.65751)
			(xy 345.171695 -72.672865) (xy 345.117747 -72.680621) (xy 345.090496 -72.681084) (xy 344.226896 -72.681084)
			(xy 344.199643 -72.680646) (xy 344.145693 -72.672888) (xy 344.093395 -72.657532) (xy 344.043815 -72.634889)
			(xy 343.997962 -72.605421) (xy 343.95677 -72.569727) (xy 343.921077 -72.528534) (xy 343.891609 -72.482681)
			(xy 343.868967 -72.433101) (xy 343.853611 -72.380804) (xy 343.845854 -72.326853) (xy 333.660251 -72.326853)
			(xy 333.663514 -72.349551) (xy 333.663514 -72.404049) (xy 333.655759 -72.457991) (xy 333.640407 -72.510282)
			(xy 333.617769 -72.559855) (xy 333.588308 -72.605702) (xy 333.552622 -72.64689) (xy 333.511437 -72.682581)
			(xy 333.465593 -72.712048) (xy 333.416023 -72.734691) (xy 333.363734 -72.75005) (xy 333.309793 -72.757811)
			(xy 333.282544 -72.7583) (xy 332.418944 -72.7583) (xy 332.391689 -72.757856) (xy 332.337732 -72.750104)
			(xy 332.285427 -72.734751) (xy 332.235841 -72.712111) (xy 332.189981 -72.682643) (xy 332.148782 -72.646949)
			(xy 332.113083 -72.605754) (xy 332.083611 -72.559898) (xy 332.060964 -72.510314) (xy 332.045606 -72.458011)
			(xy 332.037847 -72.404055) (xy 298.511468 -72.404055) (xy 298.511468 -74.617072) (xy 327.277726 -74.617072)
			(xy 327.281813 -74.561227) (xy 327.293988 -74.506573) (xy 327.31399 -74.454274) (xy 327.341395 -74.405445)
			(xy 327.375617 -74.361126) (xy 327.415927 -74.322262) (xy 327.461466 -74.289681) (xy 327.511264 -74.264078)
			(xy 327.564259 -74.245999) (xy 327.619321 -74.235828) (xy 327.675278 -74.233783) (xy 327.730936 -74.239908)
			(xy 327.785109 -74.25407) (xy 327.836643 -74.27597) (xy 327.884439 -74.305139) (xy 327.927478 -74.340957)
			(xy 327.941626 -74.356747) (xy 330.744122 -74.356747) (xy 330.744122 -74.302253) (xy 330.751877 -74.248315)
			(xy 330.767229 -74.196029) (xy 330.789865 -74.146459) (xy 330.819325 -74.100616) (xy 330.855009 -74.059431)
			(xy 330.89619 -74.023744) (xy 330.942031 -73.99428) (xy 330.991599 -73.97164) (xy 331.043883 -73.956284)
			(xy 331.097821 -73.948524) (xy 331.125068 -73.948036) (xy 331.988668 -73.948036) (xy 332.015926 -73.948409)
			(xy 332.069886 -73.956163) (xy 332.122194 -73.971518) (xy 332.171784 -73.994161) (xy 332.217646 -74.023632)
			(xy 332.258848 -74.05933) (xy 332.294549 -74.100528) (xy 332.324023 -74.146388) (xy 332.346671 -74.195976)
			(xy 332.36203 -74.248283) (xy 332.369789 -74.302243) (xy 332.369789 -74.356757) (xy 332.36203 -74.410717)
			(xy 332.346671 -74.463024) (xy 332.324023 -74.512612) (xy 332.294549 -74.558472) (xy 332.26684 -74.590448)
			(xy 336.274202 -74.590448) (xy 336.274202 -74.535953) (xy 336.281957 -74.482012) (xy 336.297309 -74.429724)
			(xy 336.319945 -74.380153) (xy 336.349406 -74.334308) (xy 336.38509 -74.293121) (xy 336.426272 -74.257432)
			(xy 336.472114 -74.227966) (xy 336.521683 -74.205324) (xy 336.573969 -74.189966) (xy 336.627909 -74.182205)
			(xy 336.655156 -74.181716) (xy 337.518756 -74.181716) (xy 337.546013 -74.182128) (xy 337.599972 -74.18988)
			(xy 337.652278 -74.205233) (xy 337.701867 -74.227875) (xy 337.747729 -74.257344) (xy 337.788929 -74.29304)
			(xy 337.82463 -74.334236) (xy 337.854104 -74.380094) (xy 337.876751 -74.42968) (xy 337.89211 -74.481985)
			(xy 337.899869 -74.535943) (xy 337.899869 -74.55185) (xy 339.156294 -74.55185) (xy 339.156294 -74.49735)
			(xy 339.16405 -74.443405) (xy 339.179404 -74.391113) (xy 339.202044 -74.341539) (xy 339.231509 -74.29569)
			(xy 339.267198 -74.254502) (xy 339.308386 -74.218812) (xy 339.354233 -74.189347) (xy 339.403808 -74.166707)
			(xy 339.456099 -74.151352) (xy 339.510044 -74.143595) (xy 339.537294 -74.143108) (xy 340.400894 -74.143108)
			(xy 340.428148 -74.143538) (xy 340.482102 -74.151295) (xy 340.534403 -74.166651) (xy 340.583986 -74.189294)
			(xy 340.629842 -74.218763) (xy 340.671037 -74.254459) (xy 340.706733 -74.295653) (xy 340.736203 -74.341509)
			(xy 340.758847 -74.391091) (xy 340.774204 -74.443392) (xy 340.781961 -74.497346) (xy 340.781961 -74.551854)
			(xy 340.774204 -74.605808) (xy 340.758847 -74.658109) (xy 340.736203 -74.707691) (xy 340.706733 -74.753547)
			(xy 340.694254 -74.767948) (xy 421.29456 -74.767948) (xy 421.29456 -66.06794) (xy 421.295065 -65.962416)
			(xy 421.303149 -65.751522) (xy 421.319305 -65.541093) (xy 421.343508 -65.331436) (xy 421.375725 -65.122861)
			(xy 421.415907 -64.915673) (xy 421.463995 -64.710176) (xy 421.519919 -64.506672) (xy 421.583596 -64.305459)
			(xy 421.654934 -64.106832) (xy 421.733828 -63.911084) (xy 421.820161 -63.718502) (xy 421.913808 -63.529367)
			(xy 422.01463 -63.343958) (xy 422.12248 -63.162547) (xy 422.237199 -62.9854) (xy 422.358619 -62.812778)
			(xy 422.486562 -62.644932) (xy 422.62084 -62.48211) (xy 422.761256 -62.324551) (xy 422.907604 -62.172486)
			(xy 423.059669 -62.026138) (xy 423.217228 -61.885722) (xy 423.38005 -61.751444) (xy 423.547896 -61.623501)
			(xy 423.720518 -61.502081) (xy 423.897665 -61.387362) (xy 424.079076 -61.279512) (xy 424.264485 -61.17869)
			(xy 424.45362 -61.085043) (xy 424.646202 -60.99871) (xy 424.84195 -60.919816) (xy 425.040577 -60.848478)
			(xy 425.24179 -60.784801) (xy 425.445294 -60.728877) (xy 425.650791 -60.680789) (xy 425.857979 -60.640607)
			(xy 426.066554 -60.60839) (xy 426.276211 -60.584187) (xy 426.48664 -60.568031) (xy 426.697534 -60.559947)
			(xy 426.908582 -60.559947) (xy 427.119476 -60.568031) (xy 427.329905 -60.584187) (xy 427.539562 -60.60839)
			(xy 427.748137 -60.640607) (xy 427.955325 -60.680789) (xy 428.160822 -60.728877) (xy 428.364326 -60.784801)
			(xy 428.565539 -60.848478) (xy 428.764166 -60.919816) (xy 428.959914 -60.99871) (xy 429.152496 -61.085043)
			(xy 429.341631 -61.17869) (xy 429.52704 -61.279512) (xy 429.708451 -61.387362) (xy 429.885598 -61.502081)
			(xy 430.05822 -61.623501) (xy 430.226066 -61.751444) (xy 430.388888 -61.885722) (xy 430.546447 -62.026138)
			(xy 430.698512 -62.172486) (xy 430.84486 -62.324551) (xy 430.985276 -62.48211) (xy 431.119554 -62.644932)
			(xy 431.247497 -62.812778) (xy 431.368917 -62.9854) (xy 431.483636 -63.162547) (xy 431.591486 -63.343958)
			(xy 431.692308 -63.529367) (xy 431.785955 -63.718502) (xy 431.872288 -63.911084) (xy 431.951182 -64.106832)
			(xy 432.02252 -64.305459) (xy 432.086197 -64.506672) (xy 432.142121 -64.710176) (xy 432.190209 -64.915673)
			(xy 432.230391 -65.122861) (xy 432.262608 -65.331436) (xy 432.286811 -65.541093) (xy 432.302967 -65.751522)
			(xy 432.311051 -65.962416) (xy 432.311556 -66.06794) (xy 432.311556 -74.767948) (xy 432.311051 -74.873472)
			(xy 432.302967 -75.084366) (xy 432.286811 -75.294795) (xy 432.262608 -75.504452) (xy 432.230391 -75.713027)
			(xy 432.190209 -75.920215) (xy 432.142121 -76.125712) (xy 432.086197 -76.329216) (xy 432.02252 -76.530429)
			(xy 431.951182 -76.729056) (xy 431.872288 -76.924804) (xy 431.785955 -77.117386) (xy 431.692308 -77.306521)
			(xy 431.591486 -77.49193) (xy 431.483636 -77.673341) (xy 431.368917 -77.850488) (xy 431.247497 -78.02311)
			(xy 431.119554 -78.190956) (xy 430.985276 -78.353778) (xy 430.84486 -78.511337) (xy 430.698512 -78.663402)
			(xy 430.546447 -78.80975) (xy 430.388888 -78.950166) (xy 430.226066 -79.084444) (xy 430.05822 -79.212387)
			(xy 429.885598 -79.333807) (xy 429.708451 -79.448526) (xy 429.52704 -79.556376) (xy 429.341631 -79.657198)
			(xy 429.152496 -79.750845) (xy 428.959914 -79.837178) (xy 428.764166 -79.916072) (xy 428.565539 -79.98741)
			(xy 428.364326 -80.051087) (xy 428.160822 -80.107011) (xy 427.955325 -80.155099) (xy 427.748137 -80.195281)
			(xy 427.539562 -80.227498) (xy 427.329905 -80.251701) (xy 427.119476 -80.267857) (xy 426.908582 -80.275941)
			(xy 426.697534 -80.275941) (xy 426.48664 -80.267857) (xy 426.276211 -80.251701) (xy 426.066554 -80.227498)
			(xy 425.857979 -80.195281) (xy 425.650791 -80.155099) (xy 425.445294 -80.107011) (xy 425.24179 -80.051087)
			(xy 425.040577 -79.98741) (xy 424.84195 -79.916072) (xy 424.646202 -79.837178) (xy 424.45362 -79.750845)
			(xy 424.264485 -79.657198) (xy 424.079076 -79.556376) (xy 423.897665 -79.448526) (xy 423.720518 -79.333807)
			(xy 423.547896 -79.212387) (xy 423.38005 -79.084444) (xy 423.217228 -78.950166) (xy 423.059669 -78.80975)
			(xy 422.907604 -78.663402) (xy 422.761256 -78.511337) (xy 422.62084 -78.353778) (xy 422.486562 -78.190956)
			(xy 422.358619 -78.02311) (xy 422.237199 -77.850488) (xy 422.12248 -77.673341) (xy 422.01463 -77.49193)
			(xy 421.913808 -77.306521) (xy 421.820161 -77.117386) (xy 421.733828 -76.924804) (xy 421.654934 -76.729056)
			(xy 421.583596 -76.530429) (xy 421.519919 -76.329216) (xy 421.463995 -76.125712) (xy 421.415907 -75.920215)
			(xy 421.375725 -75.713027) (xy 421.343508 -75.504452) (xy 421.319305 -75.294795) (xy 421.303149 -75.084366)
			(xy 421.295065 -74.873472) (xy 421.29456 -74.767948) (xy 340.694254 -74.767948) (xy 340.671037 -74.794741)
			(xy 340.629842 -74.830437) (xy 340.583986 -74.859906) (xy 340.534403 -74.882549) (xy 340.482102 -74.897905)
			(xy 340.428148 -74.905662) (xy 340.400894 -74.906124) (xy 339.537294 -74.906124) (xy 339.510044 -74.905605)
			(xy 339.456099 -74.897848) (xy 339.403808 -74.882493) (xy 339.354233 -74.859853) (xy 339.308386 -74.830388)
			(xy 339.267198 -74.794698) (xy 339.231509 -74.75351) (xy 339.202044 -74.707661) (xy 339.179404 -74.658087)
			(xy 339.16405 -74.605795) (xy 339.156294 -74.55185) (xy 337.899869 -74.55185) (xy 337.899869 -74.590457)
			(xy 337.89211 -74.644415) (xy 337.876751 -74.69672) (xy 337.854104 -74.746306) (xy 337.82463 -74.792164)
			(xy 337.788929 -74.83336) (xy 337.747729 -74.869056) (xy 337.701867 -74.898525) (xy 337.652278 -74.921167)
			(xy 337.599972 -74.93652) (xy 337.546013 -74.944272) (xy 337.518756 -74.944732) (xy 336.655156 -74.944732)
			(xy 336.627909 -74.944195) (xy 336.573969 -74.936434) (xy 336.521683 -74.921076) (xy 336.472114 -74.898434)
			(xy 336.426272 -74.868968) (xy 336.38509 -74.833279) (xy 336.349406 -74.792092) (xy 336.319945 -74.746247)
			(xy 336.297309 -74.696676) (xy 336.281957 -74.644388) (xy 336.274202 -74.590448) (xy 332.26684 -74.590448)
			(xy 332.258848 -74.59967) (xy 332.217646 -74.635368) (xy 332.171784 -74.664839) (xy 332.122194 -74.687482)
			(xy 332.069886 -74.702837) (xy 332.015926 -74.710591) (xy 331.988668 -74.711052) (xy 331.125068 -74.711052)
			(xy 331.097821 -74.710476) (xy 331.043883 -74.702716) (xy 330.991599 -74.68736) (xy 330.942031 -74.66472)
			(xy 330.89619 -74.635256) (xy 330.855009 -74.599569) (xy 330.819325 -74.558384) (xy 330.789865 -74.512541)
			(xy 330.767229 -74.462971) (xy 330.751877 -74.410685) (xy 330.744122 -74.356747) (xy 327.941626 -74.356747)
			(xy 327.964844 -74.38266) (xy 327.99574 -74.429358) (xy 328.019507 -74.480058) (xy 328.035639 -74.533678)
			(xy 328.043791 -74.589075) (xy 328.044302 -74.617072) (xy 328.043791 -74.645069) (xy 328.035639 -74.700466)
			(xy 328.019507 -74.754086) (xy 327.99574 -74.804786) (xy 327.964844 -74.851484) (xy 327.927478 -74.893187)
			(xy 327.884439 -74.929005) (xy 327.836643 -74.958174) (xy 327.785109 -74.980074) (xy 327.730936 -74.994236)
			(xy 327.675278 -75.000361) (xy 327.619321 -74.998316) (xy 327.564259 -74.988145) (xy 327.511264 -74.970066)
			(xy 327.461466 -74.944463) (xy 327.415927 -74.911882) (xy 327.375617 -74.873018) (xy 327.341395 -74.828699)
			(xy 327.31399 -74.77987) (xy 327.293988 -74.727571) (xy 327.281813 -74.672917) (xy 327.277726 -74.617072)
			(xy 298.511468 -74.617072) (xy 298.511468 -74.760836) (xy 298.510963 -74.86636) (xy 298.502879 -75.077254)
			(xy 298.486723 -75.287683) (xy 298.46252 -75.49734) (xy 298.430303 -75.705915) (xy 298.390121 -75.913103)
			(xy 298.342033 -76.1186) (xy 298.333664 -76.149054) (xy 327.558346 -76.149054) (xy 327.558346 -76.094546)
			(xy 327.566103 -76.040594) (xy 327.581459 -75.988295) (xy 327.604102 -75.938714) (xy 327.633571 -75.892859)
			(xy 327.669266 -75.851666) (xy 327.710459 -75.815971) (xy 327.756314 -75.786502) (xy 327.805895 -75.763859)
			(xy 327.858194 -75.748503) (xy 327.912146 -75.740746) (xy 327.9394 -75.74026) (xy 328.803 -75.74026)
			(xy 328.830249 -75.74081) (xy 328.884192 -75.748566) (xy 328.936482 -75.76392) (xy 328.986055 -75.786559)
			(xy 329.031902 -75.816023) (xy 329.073089 -75.851711) (xy 329.108777 -75.892898) (xy 329.138241 -75.938745)
			(xy 329.16088 -75.988318) (xy 329.169581 -76.017949) (xy 334.874382 -76.017949) (xy 334.874382 -75.963451)
			(xy 334.882137 -75.909507) (xy 334.89749 -75.857216) (xy 334.920128 -75.807642) (xy 334.949591 -75.761793)
			(xy 334.985278 -75.720605) (xy 335.026463 -75.684914) (xy 335.072308 -75.655447) (xy 335.12188 -75.632803)
			(xy 335.17417 -75.617445) (xy 335.228113 -75.609684) (xy 335.255362 -75.609196) (xy 336.118962 -75.609196)
			(xy 336.146217 -75.609649) (xy 336.200173 -75.617401) (xy 336.252475 -75.632754) (xy 336.302061 -75.655395)
			(xy 336.347919 -75.684862) (xy 336.389117 -75.720556) (xy 336.424815 -75.76175) (xy 336.454287 -75.807606)
			(xy 336.476932 -75.857189) (xy 336.49229 -75.90949) (xy 336.500049 -75.963445) (xy 336.500049 -76.017955)
			(xy 336.49229 -76.07191) (xy 336.476932 -76.124211) (xy 336.454287 -76.173794) (xy 336.424815 -76.21965)
			(xy 336.389117 -76.260844) (xy 336.347919 -76.296538) (xy 336.302061 -76.326005) (xy 336.252475 -76.348646)
			(xy 336.200173 -76.363999) (xy 336.146217 -76.371751) (xy 336.118962 -76.372212) (xy 335.255362 -76.372212)
			(xy 335.228113 -76.371716) (xy 335.17417 -76.363955) (xy 335.12188 -76.348597) (xy 335.072308 -76.325953)
			(xy 335.026463 -76.296486) (xy 334.985278 -76.260795) (xy 334.949591 -76.219607) (xy 334.920128 -76.173758)
			(xy 334.89749 -76.124184) (xy 334.882137 -76.071893) (xy 334.874382 -76.017949) (xy 329.169581 -76.017949)
			(xy 329.176234 -76.040608) (xy 329.18399 -76.094551) (xy 329.18399 -76.149049) (xy 329.176234 -76.202992)
			(xy 329.16088 -76.255282) (xy 329.138241 -76.304855) (xy 329.108777 -76.350702) (xy 329.073089 -76.391889)
			(xy 329.031902 -76.427577) (xy 328.986055 -76.457041) (xy 328.936482 -76.47968) (xy 328.884192 -76.495034)
			(xy 328.830249 -76.50279) (xy 328.803 -76.503276) (xy 327.9394 -76.503276) (xy 327.912146 -76.502854)
			(xy 327.858194 -76.495097) (xy 327.805895 -76.479741) (xy 327.756314 -76.457098) (xy 327.710459 -76.427629)
			(xy 327.669266 -76.391934) (xy 327.633571 -76.350741) (xy 327.604102 -76.304886) (xy 327.581459 -76.255305)
			(xy 327.566103 -76.203006) (xy 327.558346 -76.149054) (xy 298.333664 -76.149054) (xy 298.286109 -76.322104)
			(xy 298.222432 -76.523317) (xy 298.151094 -76.721944) (xy 298.0722 -76.917692) (xy 297.985867 -77.110274)
			(xy 297.89222 -77.299409) (xy 297.791398 -77.484818) (xy 297.683548 -77.666229) (xy 297.568829 -77.843376)
			(xy 297.455321 -78.00475) (xy 330.84567 -78.00475) (xy 330.84567 -77.95025) (xy 330.853426 -77.896304)
			(xy 330.868779 -77.84401) (xy 330.891419 -77.794434) (xy 330.920883 -77.748584) (xy 330.956571 -77.707394)
			(xy 330.997759 -77.671702) (xy 331.043606 -77.642234) (xy 331.09318 -77.619591) (xy 331.145472 -77.604232)
			(xy 331.199418 -77.596472) (xy 331.226668 -77.595984) (xy 332.090268 -77.595984) (xy 332.117522 -77.596461)
			(xy 332.171475 -77.604214) (xy 332.223776 -77.619567) (xy 332.273359 -77.642207) (xy 332.319215 -77.671674)
			(xy 332.360411 -77.707367) (xy 332.396107 -77.748559) (xy 332.425577 -77.794413) (xy 332.448222 -77.843994)
			(xy 332.463579 -77.896294) (xy 332.471337 -77.950246) (xy 332.471337 -78.004754) (xy 332.463579 -78.058706)
			(xy 332.448222 -78.111006) (xy 332.425577 -78.160587) (xy 332.396107 -78.206441) (xy 332.360411 -78.247633)
			(xy 332.319215 -78.283326) (xy 332.273359 -78.312793) (xy 332.223776 -78.335433) (xy 332.171475 -78.350786)
			(xy 332.117522 -78.358539) (xy 332.090268 -78.359) (xy 331.226668 -78.359) (xy 331.199418 -78.358528)
			(xy 331.145472 -78.350768) (xy 331.09318 -78.335409) (xy 331.043606 -78.312766) (xy 330.997759 -78.283298)
			(xy 330.956571 -78.247606) (xy 330.920883 -78.206416) (xy 330.891419 -78.160566) (xy 330.868779 -78.11099)
			(xy 330.853426 -78.058696) (xy 330.84567 -78.00475) (xy 297.455321 -78.00475) (xy 297.447409 -78.015998)
			(xy 297.319466 -78.183844) (xy 297.185188 -78.346666) (xy 297.044772 -78.504225) (xy 296.898424 -78.65629)
			(xy 296.746359 -78.802638) (xy 296.5888 -78.943054) (xy 296.425978 -79.077332) (xy 296.258132 -79.205275)
			(xy 296.08551 -79.326695) (xy 295.908363 -79.441414) (xy 295.726952 -79.549264) (xy 295.541543 -79.650086)
			(xy 295.352408 -79.743733) (xy 295.159826 -79.830066) (xy 294.964078 -79.90896) (xy 294.765451 -79.980298)
			(xy 294.564238 -80.043975) (xy 294.360734 -80.099899) (xy 294.155237 -80.147987) (xy 293.948049 -80.188169)
			(xy 293.739474 -80.220386) (xy 293.529817 -80.244589) (xy 293.319388 -80.260745) (xy 293.108494 -80.268829)
			(xy 292.897446 -80.268829) (xy 292.686552 -80.260745) (xy 292.476123 -80.244589) (xy 292.266466 -80.220386)
			(xy 292.057891 -80.188169) (xy 291.850703 -80.147987) (xy 291.645206 -80.099899) (xy 291.441702 -80.043975)
			(xy 291.240489 -79.980298) (xy 291.041862 -79.90896) (xy 290.846114 -79.830066) (xy 290.653532 -79.743733)
			(xy 290.464397 -79.650086) (xy 290.278988 -79.549264) (xy 290.097577 -79.441414) (xy 289.92043 -79.326695)
			(xy 289.747808 -79.205275) (xy 289.579962 -79.077332) (xy 289.41714 -78.943054) (xy 289.259581 -78.802638)
			(xy 289.107516 -78.65629) (xy 288.961168 -78.504225) (xy 288.820752 -78.346666) (xy 288.686474 -78.183844)
			(xy 288.558531 -78.015998) (xy 288.437111 -77.843376) (xy 288.322392 -77.666229) (xy 288.214542 -77.484818)
			(xy 288.11372 -77.299409) (xy 288.020073 -77.110274) (xy 287.93374 -76.917692) (xy 287.854846 -76.721944)
			(xy 287.783508 -76.523317) (xy 287.719831 -76.322104) (xy 287.663907 -76.1186) (xy 287.615819 -75.913103)
			(xy 287.575637 -75.705915) (xy 287.54342 -75.49734) (xy 287.519217 -75.287683) (xy 287.503061 -75.077254)
			(xy 287.494977 -74.86636) (xy 287.494472 -74.760836) (xy 184.371488 -74.760836) (xy 184.371488 -74.767948)
			(xy 184.370983 -74.873472) (xy 184.362899 -75.084366) (xy 184.346743 -75.294795) (xy 184.32254 -75.504452)
			(xy 184.290323 -75.713027) (xy 184.250141 -75.920215) (xy 184.202053 -76.125712) (xy 184.146129 -76.329216)
			(xy 184.082452 -76.530429) (xy 184.011114 -76.729056) (xy 183.93222 -76.924804) (xy 183.845887 -77.117386)
			(xy 183.75224 -77.306521) (xy 183.651418 -77.49193) (xy 183.543568 -77.673341) (xy 183.428849 -77.850488)
			(xy 183.307429 -78.02311) (xy 183.179486 -78.190956) (xy 183.045208 -78.353778) (xy 182.904792 -78.511337)
			(xy 182.758444 -78.663402) (xy 182.606379 -78.80975) (xy 182.44882 -78.950166) (xy 182.285998 -79.084444)
			(xy 182.118152 -79.212387) (xy 181.94553 -79.333807) (xy 181.768383 -79.448526) (xy 181.586972 -79.556376)
			(xy 181.401563 -79.657198) (xy 181.212428 -79.750845) (xy 181.019846 -79.837178) (xy 180.824098 -79.916072)
			(xy 180.625471 -79.98741) (xy 180.424258 -80.051087) (xy 180.220754 -80.107011) (xy 180.015257 -80.155099)
			(xy 179.808069 -80.195281) (xy 179.599494 -80.227498) (xy 179.389837 -80.251701) (xy 179.179408 -80.267857)
			(xy 178.968514 -80.275941) (xy 178.757466 -80.275941) (xy 178.546572 -80.267857) (xy 178.336143 -80.251701)
			(xy 178.126486 -80.227498) (xy 177.917911 -80.195281) (xy 177.710723 -80.155099) (xy 177.505226 -80.107011)
			(xy 177.301722 -80.051087) (xy 177.100509 -79.98741) (xy 176.901882 -79.916072) (xy 176.706134 -79.837178)
			(xy 176.513552 -79.750845) (xy 176.324417 -79.657198) (xy 176.139008 -79.556376) (xy 175.957597 -79.448526)
			(xy 175.78045 -79.333807) (xy 175.607828 -79.212387) (xy 175.439982 -79.084444) (xy 175.27716 -78.950166)
			(xy 175.119601 -78.80975) (xy 174.967536 -78.663402) (xy 174.821188 -78.511337) (xy 174.680772 -78.353778)
			(xy 174.546494 -78.190956) (xy 174.418551 -78.02311) (xy 174.297131 -77.850488) (xy 174.182412 -77.673341)
			(xy 174.074562 -77.49193) (xy 173.97374 -77.306521) (xy 173.880093 -77.117386) (xy 173.79376 -76.924804)
			(xy 173.714866 -76.729056) (xy 173.643528 -76.530429) (xy 173.579851 -76.329216) (xy 173.523927 -76.125712)
			(xy 173.475839 -75.920215) (xy 173.435657 -75.713027) (xy 173.40344 -75.504452) (xy 173.379237 -75.294795)
			(xy 173.363081 -75.084366) (xy 173.354997 -74.873472) (xy 173.354492 -74.767948) (xy 50.571366 -74.767948)
			(xy 50.570895 -74.86636) (xy 50.562811 -75.077254) (xy 50.546655 -75.287683) (xy 50.522452 -75.49734)
			(xy 50.490235 -75.705915) (xy 50.450053 -75.913103) (xy 50.401965 -76.1186) (xy 50.346041 -76.322104)
			(xy 50.282364 -76.523317) (xy 50.211026 -76.721944) (xy 50.132132 -76.917692) (xy 50.045799 -77.110274)
			(xy 49.952152 -77.299409) (xy 49.85133 -77.484818) (xy 49.74348 -77.666229) (xy 49.628761 -77.843376)
			(xy 49.507341 -78.015998) (xy 49.379398 -78.183844) (xy 49.24512 -78.346666) (xy 49.104704 -78.504225)
			(xy 48.958356 -78.65629) (xy 48.806291 -78.802638) (xy 48.648732 -78.943054) (xy 48.48591 -79.077332)
			(xy 48.318064 -79.205275) (xy 48.145442 -79.326695) (xy 47.968295 -79.441414) (xy 47.786884 -79.549264)
			(xy 47.601475 -79.650086) (xy 47.41234 -79.743733) (xy 47.219758 -79.830066) (xy 47.02401 -79.90896)
			(xy 46.825383 -79.980298) (xy 46.62417 -80.043975) (xy 46.420666 -80.099899) (xy 46.215169 -80.147987)
			(xy 46.007981 -80.188169) (xy 45.799406 -80.220386) (xy 45.589749 -80.244589) (xy 45.37932 -80.260745)
			(xy 45.168426 -80.268829) (xy 44.957378 -80.268829) (xy 44.746484 -80.260745) (xy 44.536055 -80.244589)
			(xy 44.326398 -80.220386) (xy 44.117823 -80.188169) (xy 43.910635 -80.147987) (xy 43.705138 -80.099899)
			(xy 43.501634 -80.043975) (xy 43.300421 -79.980298) (xy 43.101794 -79.90896) (xy 42.906046 -79.830066)
			(xy 42.713464 -79.743733) (xy 42.524329 -79.650086) (xy 42.33892 -79.549264) (xy 42.157509 -79.441414)
			(xy 41.980362 -79.326695) (xy 41.80774 -79.205275) (xy 41.639894 -79.077332) (xy 41.477072 -78.943054)
			(xy 41.319513 -78.802638) (xy 41.167448 -78.65629) (xy 41.0211 -78.504225) (xy 40.880684 -78.346666)
			(xy 40.746406 -78.183844) (xy 40.618463 -78.015998) (xy 40.497043 -77.843376) (xy 40.382324 -77.666229)
			(xy 40.274474 -77.484818) (xy 40.173652 -77.299409) (xy 40.080005 -77.110274) (xy 39.993672 -76.917692)
			(xy 39.914778 -76.721944) (xy 39.84344 -76.523317) (xy 39.779763 -76.322104) (xy 39.723839 -76.1186)
			(xy 39.675751 -75.913103) (xy 39.635569 -75.705915) (xy 39.603352 -75.49734) (xy 39.579149 -75.287683)
			(xy 39.562993 -75.077254) (xy 39.554909 -74.86636) (xy 39.554404 -74.760836) (xy 0.509016 -74.760836)
			(xy 0.509016 -77.671676) (xy 0.509504 -77.724899) (xy 0.51712 -77.831071) (xy 0.532286 -77.93643)
			(xy 0.554925 -78.04044) (xy 0.584921 -78.142572) (xy 0.622123 -78.242305) (xy 0.666339 -78.339132)
			(xy 0.717347 -78.43256) (xy 0.774885 -78.522114) (xy 0.838661 -78.607338) (xy 0.908351 -78.687799)
			(xy 0.945642 -78.725776) (xy 1.77419 -79.554324) (xy 1.823602 -79.604436) (xy 1.917388 -79.709385)
			(xy 2.005143 -79.819428) (xy 2.08659 -79.934217) (xy 2.161473 -80.053392) (xy 2.229556 -80.176578)
			(xy 2.290626 -80.303388) (xy 2.344491 -80.433422) (xy 2.39098 -80.566271) (xy 2.429948 -80.701518)
			(xy 2.461272 -80.838737) (xy 2.484853 -80.977496) (xy 2.500618 -81.117359) (xy 2.508516 -81.257886)
			(xy 2.509012 -81.32826) (xy 2.509012 -81.69181) (xy 232.140667 -81.69181) (xy 232.145062 -81.517977)
			(xy 232.15749 -81.344533) (xy 232.177927 -81.171849) (xy 232.206328 -81.000295) (xy 232.242632 -80.830238)
			(xy 232.286762 -80.662042) (xy 232.338623 -80.496067) (xy 232.398104 -80.332668) (xy 232.465078 -80.172194)
			(xy 232.539402 -80.01499) (xy 232.620917 -79.86139) (xy 232.709448 -79.711725) (xy 232.804805 -79.566315)
			(xy 232.906785 -79.425469) (xy 233.01517 -79.289491) (xy 233.129727 -79.158671) (xy 233.250212 -79.033288)
			(xy 233.376366 -78.913612) (xy 233.50792 -78.799897) (xy 233.644592 -78.692389) (xy 233.715052 -78.641448)
			(xy 238.08436 -78.641448) (xy 238.15482 -78.692389) (xy 238.291492 -78.799897) (xy 238.423046 -78.913612)
			(xy 238.5492 -79.033288) (xy 238.669685 -79.158671) (xy 238.784242 -79.289491) (xy 238.892627 -79.425469)
			(xy 238.994607 -79.566315) (xy 239.089964 -79.711725) (xy 239.178495 -79.86139) (xy 239.26001 -80.01499)
			(xy 239.334334 -80.172194) (xy 239.401308 -80.332668) (xy 239.460789 -80.496067) (xy 239.51265 -80.662042)
			(xy 239.553507 -80.817765) (xy 333.938166 -80.817765) (xy 333.938166 -80.763235) (xy 333.945926 -80.70926)
			(xy 333.961289 -80.656938) (xy 333.98394 -80.607335) (xy 334.01342 -80.561461) (xy 334.049129 -80.520248)
			(xy 334.090338 -80.484537) (xy 334.136211 -80.455054) (xy 334.185812 -80.432398) (xy 334.238132 -80.417032)
			(xy 334.292107 -80.409268) (xy 334.319372 -80.40878) (xy 335.182972 -80.40878) (xy 335.210247 -80.409158)
			(xy 335.264243 -80.416917) (xy 335.316585 -80.432283) (xy 335.366207 -80.454941) (xy 335.412099 -80.484432)
			(xy 335.453327 -80.520153) (xy 335.489052 -80.561378) (xy 335.518545 -80.607268) (xy 335.541207 -80.656889)
			(xy 335.556577 -80.709229) (xy 335.56434 -80.763225) (xy 335.56434 -80.817775) (xy 335.556577 -80.871771)
			(xy 335.541207 -80.924111) (xy 335.518545 -80.973732) (xy 335.489052 -81.019622) (xy 335.453327 -81.060847)
			(xy 335.412099 -81.096568) (xy 335.366207 -81.126059) (xy 335.316585 -81.148717) (xy 335.264243 -81.164083)
			(xy 335.210247 -81.171842) (xy 335.182972 -81.172304) (xy 334.319372 -81.172304) (xy 334.292107 -81.171732)
			(xy 334.238132 -81.163968) (xy 334.185812 -81.148602) (xy 334.136211 -81.125946) (xy 334.090338 -81.096463)
			(xy 334.049129 -81.060752) (xy 334.01342 -81.019539) (xy 333.98394 -80.973665) (xy 333.961289 -80.924062)
			(xy 333.945926 -80.87174) (xy 333.938166 -80.817765) (xy 239.553507 -80.817765) (xy 239.55678 -80.830238)
			(xy 239.593084 -81.000295) (xy 239.621485 -81.171849) (xy 239.641922 -81.344533) (xy 239.65435 -81.517977)
			(xy 239.658745 -81.69181) (xy 239.655095 -81.865661) (xy 239.643409 -82.039157) (xy 239.640092 -82.06825)
			(xy 331.768962 -82.06825) (xy 331.768962 -82.01375) (xy 331.776717 -81.959803) (xy 331.792071 -81.90751)
			(xy 331.81471 -81.857933) (xy 331.844174 -81.812083) (xy 331.879862 -81.770892) (xy 331.921049 -81.735199)
			(xy 331.966896 -81.70573) (xy 332.01647 -81.683086) (xy 332.068762 -81.667726) (xy 332.122708 -81.659965)
			(xy 332.149958 -81.659476) (xy 333.013558 -81.659476) (xy 333.040812 -81.659968) (xy 333.094765 -81.66772)
			(xy 333.147066 -81.683072) (xy 333.196649 -81.705711) (xy 333.242505 -81.735177) (xy 333.283701 -81.770869)
			(xy 333.319398 -81.812061) (xy 333.348869 -81.857914) (xy 333.371513 -81.907495) (xy 333.386871 -81.959794)
			(xy 333.394629 -82.013746) (xy 333.394629 -82.068254) (xy 333.386871 -82.122206) (xy 333.371513 -82.174505)
			(xy 333.348869 -82.224086) (xy 333.319398 -82.269939) (xy 333.294774 -82.298353) (xy 336.189263 -82.298353)
			(xy 336.189263 -82.243847) (xy 336.197021 -82.189895) (xy 336.212377 -82.137597) (xy 336.235021 -82.088017)
			(xy 336.26449 -82.042163) (xy 336.300185 -82.000971) (xy 336.341379 -81.965278) (xy 336.387234 -81.935811)
			(xy 336.436816 -81.91317) (xy 336.489115 -81.897816) (xy 336.543067 -81.890062) (xy 336.57032 -81.8896)
			(xy 337.43392 -81.8896) (xy 337.461171 -81.890071) (xy 337.515118 -81.89783) (xy 337.567411 -81.913187)
			(xy 337.616987 -81.93583) (xy 337.662836 -81.965298) (xy 337.692804 -81.991267) (xy 339.478646 -81.991267)
			(xy 339.478646 -81.936733) (xy 339.486407 -81.882755) (xy 339.50177 -81.830431) (xy 339.524423 -81.780825)
			(xy 339.553905 -81.734948) (xy 339.589615 -81.693734) (xy 339.630827 -81.65802) (xy 339.676702 -81.628535)
			(xy 339.726306 -81.605879) (xy 339.77863 -81.590512) (xy 339.832607 -81.582748) (xy 339.859874 -81.58226)
			(xy 340.723474 -81.58226) (xy 340.750748 -81.582678) (xy 340.804741 -81.590437) (xy 340.857079 -81.605802)
			(xy 340.906699 -81.62846) (xy 340.952588 -81.657948) (xy 340.993814 -81.693668) (xy 341.029536 -81.734891)
			(xy 341.059028 -81.780778) (xy 341.081689 -81.830396) (xy 341.097057 -81.882734) (xy 341.10482 -81.936726)
			(xy 341.10482 -81.991274) (xy 341.097057 -82.045266) (xy 341.081689 -82.097604) (xy 341.059028 -82.147222)
			(xy 341.029536 -82.193109) (xy 340.993814 -82.234332) (xy 340.952588 -82.270052) (xy 340.906699 -82.29954)
			(xy 340.857079 -82.322198) (xy 340.804741 -82.337563) (xy 340.750748 -82.345322) (xy 340.723474 -82.345784)
			(xy 339.859874 -82.345784) (xy 339.832607 -82.345252) (xy 339.77863 -82.337488) (xy 339.726306 -82.322121)
			(xy 339.676702 -82.299465) (xy 339.630827 -82.26998) (xy 339.589615 -82.234266) (xy 339.553905 -82.193052)
			(xy 339.524423 -82.147175) (xy 339.50177 -82.097569) (xy 339.486407 -82.045245) (xy 339.478646 -81.991267)
			(xy 337.692804 -81.991267) (xy 337.704024 -82.00099) (xy 337.739714 -82.04218) (xy 337.76918 -82.088031)
			(xy 337.79182 -82.137608) (xy 337.807174 -82.189902) (xy 337.81493 -82.243849) (xy 337.81493 -82.298351)
			(xy 337.807174 -82.352298) (xy 337.79182 -82.404592) (xy 337.769179 -82.454169) (xy 337.739714 -82.50002)
			(xy 337.704024 -82.54121) (xy 337.662836 -82.576902) (xy 337.616987 -82.60637) (xy 337.567411 -82.629013)
			(xy 337.515118 -82.64437) (xy 337.461171 -82.652129) (xy 337.43392 -82.652616) (xy 336.57032 -82.652616)
			(xy 336.543067 -82.652138) (xy 336.489115 -82.644384) (xy 336.436816 -82.62903) (xy 336.387234 -82.606389)
			(xy 336.341379 -82.576922) (xy 336.300185 -82.541229) (xy 336.26449 -82.500037) (xy 336.235021 -82.454183)
			(xy 336.212377 -82.404603) (xy 336.197021 -82.352305) (xy 336.189263 -82.298353) (xy 333.294774 -82.298353)
			(xy 333.283701 -82.311131) (xy 333.242505 -82.346823) (xy 333.196649 -82.376289) (xy 333.147066 -82.398928)
			(xy 333.094765 -82.41428) (xy 333.040812 -82.422032) (xy 333.013558 -82.422492) (xy 332.149958 -82.422492)
			(xy 332.122708 -82.422035) (xy 332.068762 -82.414274) (xy 332.01647 -82.398914) (xy 331.966896 -82.37627)
			(xy 331.921049 -82.346801) (xy 331.879862 -82.311108) (xy 331.844174 -82.269917) (xy 331.81471 -82.224067)
			(xy 331.792071 -82.17449) (xy 331.776717 -82.122197) (xy 331.768962 -82.06825) (xy 239.640092 -82.06825)
			(xy 239.623713 -82.211927) (xy 239.596047 -82.383601) (xy 239.560472 -82.553811) (xy 239.517063 -82.722195)
			(xy 239.465913 -82.888391) (xy 239.407133 -83.052043) (xy 239.340846 -83.212802) (xy 239.267197 -83.370324)
			(xy 239.186341 -83.524271) (xy 239.148735 -83.588471) (xy 341.356398 -83.588471) (xy 341.356398 -83.533929)
			(xy 341.364161 -83.479942) (xy 341.379527 -83.427609) (xy 341.402184 -83.377996) (xy 341.431672 -83.332112)
			(xy 341.467389 -83.290892) (xy 341.508609 -83.255174) (xy 341.554492 -83.225686) (xy 341.604106 -83.203028)
			(xy 341.656438 -83.187661) (xy 341.710425 -83.179899) (xy 341.737696 -83.179412) (xy 342.601296 -83.179412)
			(xy 342.628565 -83.179927) (xy 342.682549 -83.187688) (xy 342.734879 -83.203053) (xy 342.784489 -83.225709)
			(xy 342.83037 -83.255194) (xy 342.871588 -83.290909) (xy 342.907303 -83.332127) (xy 342.936789 -83.378008)
			(xy 342.959445 -83.427618) (xy 342.974811 -83.479947) (xy 342.982573 -83.533931) (xy 342.982573 -83.588469)
			(xy 342.974811 -83.642453) (xy 342.959445 -83.694782) (xy 342.936789 -83.744392) (xy 342.907303 -83.790273)
			(xy 342.871588 -83.831491) (xy 342.83037 -83.867206) (xy 342.784489 -83.896691) (xy 342.734879 -83.919347)
			(xy 342.682549 -83.934712) (xy 342.628565 -83.942473) (xy 342.601296 -83.942936) (xy 341.737696 -83.942936)
			(xy 341.710425 -83.942501) (xy 341.656438 -83.934739) (xy 341.604106 -83.919372) (xy 341.554492 -83.896714)
			(xy 341.508609 -83.867226) (xy 341.467389 -83.831508) (xy 341.431672 -83.790288) (xy 341.402184 -83.744404)
			(xy 341.379527 -83.694791) (xy 341.364161 -83.642458) (xy 341.356398 -83.588471) (xy 239.148735 -83.588471)
			(xy 239.098452 -83.674314) (xy 239.003718 -83.820132) (xy 238.902342 -83.961413) (xy 238.794541 -84.097854)
			(xy 238.680545 -84.229164) (xy 238.560599 -84.355062) (xy 238.434958 -84.475277) (xy 238.393119 -84.511757)
			(xy 337.882119 -84.511757) (xy 337.882119 -84.457243) (xy 337.889878 -84.403284) (xy 337.905237 -84.350979)
			(xy 337.927883 -84.301392) (xy 337.957357 -84.255533) (xy 337.993057 -84.214336) (xy 338.034257 -84.178639)
			(xy 338.080119 -84.149169) (xy 338.129707 -84.126526) (xy 338.182014 -84.111171) (xy 338.235973 -84.103417)
			(xy 338.26323 -84.102956) (xy 339.12683 -84.102956) (xy 339.154077 -84.103516) (xy 339.208017 -84.111275)
			(xy 339.260303 -84.126632) (xy 339.309871 -84.149272) (xy 339.355714 -84.178737) (xy 339.396896 -84.214425)
			(xy 339.432581 -84.25561) (xy 339.462042 -84.301455) (xy 339.484679 -84.351025) (xy 339.500031 -84.403313)
			(xy 339.503159 -84.425069) (xy 344.644951 -84.425069) (xy 344.644951 -84.370531) (xy 344.652713 -84.316548)
			(xy 344.668079 -84.26422) (xy 344.690737 -84.214611) (xy 344.720223 -84.168731) (xy 344.75594 -84.127516)
			(xy 344.797159 -84.091803) (xy 344.843041 -84.06232) (xy 344.892652 -84.039668) (xy 344.944981 -84.024306)
			(xy 344.998965 -84.016549) (xy 345.026234 -84.016088) (xy 345.889834 -84.016088) (xy 345.917105 -84.016477)
			(xy 345.971092 -84.024243) (xy 346.023425 -84.039614) (xy 346.073037 -84.062275) (xy 346.11892 -84.091766)
			(xy 346.160139 -84.127485) (xy 346.195855 -84.168708) (xy 346.225341 -84.214593) (xy 346.247998 -84.264207)
			(xy 346.263364 -84.316541) (xy 346.271126 -84.370529) (xy 346.271126 -84.425071) (xy 346.263364 -84.479059)
			(xy 346.247998 -84.531393) (xy 346.225341 -84.581007) (xy 346.195855 -84.626892) (xy 346.160139 -84.668115)
			(xy 346.11892 -84.703834) (xy 346.073037 -84.733325) (xy 346.023425 -84.755986) (xy 345.971092 -84.771357)
			(xy 345.917105 -84.779123) (xy 345.889834 -84.779612) (xy 345.026234 -84.779612) (xy 344.998965 -84.779051)
			(xy 344.944981 -84.771294) (xy 344.892652 -84.755932) (xy 344.843041 -84.73328) (xy 344.797159 -84.703797)
			(xy 344.75594 -84.668084) (xy 344.720223 -84.626869) (xy 344.690737 -84.580989) (xy 344.668079 -84.53138)
			(xy 344.652713 -84.479052) (xy 344.644951 -84.425069) (xy 339.503159 -84.425069) (xy 339.507786 -84.457253)
			(xy 339.507786 -84.511747) (xy 339.500031 -84.565687) (xy 339.484679 -84.617975) (xy 339.462042 -84.667545)
			(xy 339.432581 -84.71339) (xy 339.396896 -84.754575) (xy 339.355714 -84.790263) (xy 339.309871 -84.819728)
			(xy 339.260303 -84.842368) (xy 339.208017 -84.857725) (xy 339.154077 -84.865484) (xy 339.12683 -84.865972)
			(xy 338.26323 -84.865972) (xy 338.235973 -84.865583) (xy 338.182014 -84.857829) (xy 338.129707 -84.842474)
			(xy 338.080119 -84.819831) (xy 338.034257 -84.790361) (xy 337.993057 -84.754664) (xy 337.957357 -84.713467)
			(xy 337.927883 -84.667608) (xy 337.905237 -84.618021) (xy 337.889878 -84.565716) (xy 337.882119 -84.511757)
			(xy 238.393119 -84.511757) (xy 238.303893 -84.589554) (xy 238.167683 -84.697647) (xy 238.02662 -84.799326)
			(xy 237.881005 -84.894371) (xy 237.73115 -84.982581) (xy 237.577377 -85.063767) (xy 237.420014 -85.137754)
			(xy 237.259397 -85.204384) (xy 237.095871 -85.263515) (xy 236.929785 -85.315021) (xy 236.761494 -85.35879)
			(xy 236.59136 -85.39473) (xy 236.419746 -85.422763) (xy 236.247019 -85.44283) (xy 236.073548 -85.454887)
			(xy 235.899706 -85.458909) (xy 235.725864 -85.454887) (xy 235.552393 -85.44283) (xy 235.379666 -85.422763)
			(xy 235.208052 -85.39473) (xy 235.037918 -85.35879) (xy 234.869627 -85.315021) (xy 234.703541 -85.263515)
			(xy 234.540015 -85.204384) (xy 234.379398 -85.137754) (xy 234.222035 -85.063767) (xy 234.068262 -84.982581)
			(xy 233.918407 -84.894371) (xy 233.772792 -84.799326) (xy 233.631729 -84.697647) (xy 233.495519 -84.589554)
			(xy 233.364454 -84.475277) (xy 233.238813 -84.355062) (xy 233.118867 -84.229164) (xy 233.004871 -84.097854)
			(xy 232.89707 -83.961413) (xy 232.795694 -83.820132) (xy 232.70096 -83.674314) (xy 232.613071 -83.524271)
			(xy 232.532215 -83.370324) (xy 232.458566 -83.212802) (xy 232.392279 -83.052043) (xy 232.333499 -82.888391)
			(xy 232.282349 -82.722195) (xy 232.23894 -82.553811) (xy 232.203365 -82.383601) (xy 232.175699 -82.211927)
			(xy 232.156003 -82.039157) (xy 232.144317 -81.865661) (xy 232.140667 -81.69181) (xy 2.509012 -81.69181)
			(xy 2.509012 -85.764678) (xy 10.421355 -85.764678) (xy 10.421355 -85.635538) (xy 10.429305 -85.506643)
			(xy 10.445175 -85.378483) (xy 10.468904 -85.251542) (xy 10.500403 -85.126303) (xy 10.539552 -85.00324)
			(xy 10.586203 -84.882821) (xy 10.640178 -84.765502) (xy 10.701273 -84.651728) (xy 10.769256 -84.541931)
			(xy 10.84387 -84.436528) (xy 10.924831 -84.335918) (xy 11.011831 -84.240483) (xy 11.104542 -84.150584)
			(xy 11.202612 -84.066563) (xy 11.305667 -83.988739) (xy 11.413318 -83.917407) (xy 11.525157 -83.852837)
			(xy 11.640758 -83.795275) (xy 11.759683 -83.744938) (xy 11.881482 -83.702018) (xy 12.005692 -83.666677)
			(xy 12.131841 -83.63905) (xy 12.259453 -83.619241) (xy 12.388042 -83.607325) (xy 12.51712 -83.603349)
			(xy 12.646198 -83.607325) (xy 12.774787 -83.619241) (xy 12.902399 -83.63905) (xy 13.028548 -83.666677)
			(xy 13.152758 -83.702018) (xy 13.274557 -83.744938) (xy 13.393482 -83.795275) (xy 13.509083 -83.852837)
			(xy 13.620922 -83.917407) (xy 13.728573 -83.988739) (xy 13.831628 -84.066563) (xy 13.929698 -84.150584)
			(xy 14.022409 -84.240483) (xy 14.109409 -84.335918) (xy 14.19037 -84.436528) (xy 14.264984 -84.541931)
			(xy 14.332967 -84.651728) (xy 14.394062 -84.765502) (xy 14.448037 -84.882821) (xy 14.494688 -85.00324)
			(xy 14.533837 -85.126303) (xy 14.565336 -85.251542) (xy 14.589065 -85.378483) (xy 14.604935 -85.506643)
			(xy 14.612885 -85.635538) (xy 14.613382 -85.700108) (xy 14.612885 -85.764678) (xy 14.608278 -85.839368)
			(xy 342.975946 -85.839368) (xy 342.975946 -85.784832) (xy 342.983708 -85.730852) (xy 342.999072 -85.678525)
			(xy 343.021727 -85.628918) (xy 343.051211 -85.58304) (xy 343.086924 -85.541824) (xy 343.12814 -85.506111)
			(xy 343.174018 -85.476627) (xy 343.223625 -85.453972) (xy 343.275952 -85.438608) (xy 343.329932 -85.430846)
			(xy 343.3572 -85.43036) (xy 344.2208 -85.43036) (xy 344.248071 -85.430802) (xy 344.302058 -85.438565)
			(xy 344.35439 -85.453931) (xy 344.404003 -85.476588) (xy 344.449887 -85.506076) (xy 344.491107 -85.541793)
			(xy 344.526824 -85.583013) (xy 344.556312 -85.628897) (xy 344.578969 -85.67851) (xy 344.594335 -85.730842)
			(xy 344.602098 -85.784829) (xy 344.602098 -85.839371) (xy 344.594335 -85.893358) (xy 344.578969 -85.94569)
			(xy 344.556312 -85.995303) (xy 344.526824 -86.041187) (xy 344.491107 -86.082407) (xy 344.449887 -86.118124)
			(xy 344.404003 -86.147612) (xy 344.35439 -86.170269) (xy 344.302058 -86.185635) (xy 344.248071 -86.193398)
			(xy 344.2208 -86.193884) (xy 343.3572 -86.193884) (xy 343.329932 -86.193354) (xy 343.275952 -86.185592)
			(xy 343.223625 -86.170228) (xy 343.174018 -86.147573) (xy 343.12814 -86.118089) (xy 343.086924 -86.082376)
			(xy 343.051211 -86.04116) (xy 343.021727 -85.995282) (xy 342.999072 -85.945675) (xy 342.983708 -85.893348)
			(xy 342.975946 -85.839368) (xy 14.608278 -85.839368) (xy 14.604935 -85.893573) (xy 14.589065 -86.021733)
			(xy 14.565336 -86.148674) (xy 14.533837 -86.273913) (xy 14.494688 -86.396976) (xy 14.448037 -86.517395)
			(xy 14.394062 -86.634714) (xy 14.332967 -86.748488) (xy 14.264984 -86.858285) (xy 14.19037 -86.963688)
			(xy 14.109409 -87.064298) (xy 14.022409 -87.159733) (xy 13.929698 -87.249632) (xy 13.831628 -87.333653)
			(xy 13.728573 -87.411477) (xy 13.620922 -87.482809) (xy 13.509083 -87.547379) (xy 13.393482 -87.604941)
			(xy 13.274557 -87.655278) (xy 13.152758 -87.698198) (xy 13.028548 -87.733539) (xy 12.902399 -87.761166)
			(xy 12.774787 -87.780975) (xy 12.646198 -87.792891) (xy 12.51712 -87.796868) (xy 12.388042 -87.792891)
			(xy 12.259453 -87.780975) (xy 12.131841 -87.761166) (xy 12.005692 -87.733539) (xy 11.881482 -87.698198)
			(xy 11.759683 -87.655278) (xy 11.640758 -87.604941) (xy 11.525157 -87.547379) (xy 11.413318 -87.482809)
			(xy 11.305667 -87.411477) (xy 11.202612 -87.333653) (xy 11.104542 -87.249632) (xy 11.011831 -87.159733)
			(xy 10.924831 -87.064298) (xy 10.84387 -86.963688) (xy 10.769256 -86.858285) (xy 10.701273 -86.748488)
			(xy 10.640178 -86.634714) (xy 10.586203 -86.517395) (xy 10.539552 -86.396976) (xy 10.500403 -86.273913)
			(xy 10.468904 -86.148674) (xy 10.445175 -86.021733) (xy 10.429305 -85.893573) (xy 10.421355 -85.764678)
			(xy 2.509012 -85.764678) (xy 2.509012 -98.341434) (xy 261.733792 -98.341434) (xy 261.733792 -97.477834)
			(xy 261.734278 -97.450583) (xy 261.742034 -97.396635) (xy 261.757389 -97.34434) (xy 261.780031 -97.294763)
			(xy 261.809497 -97.248913) (xy 261.845188 -97.207722) (xy 261.886379 -97.172031) (xy 261.932229 -97.142565)
			(xy 261.981806 -97.119923) (xy 262.034101 -97.104568) (xy 262.088049 -97.096812) (xy 262.142551 -97.096812)
			(xy 262.196499 -97.104568) (xy 262.248794 -97.119923) (xy 262.298371 -97.142565) (xy 262.344221 -97.172031)
			(xy 262.385412 -97.207722) (xy 262.421103 -97.248913) (xy 262.450569 -97.294763) (xy 262.473211 -97.34434)
			(xy 262.488566 -97.396635) (xy 262.496322 -97.450583) (xy 262.496808 -97.477834) (xy 262.496808 -98.341434)
			(xy 262.496322 -98.368685) (xy 262.488566 -98.422633) (xy 262.473211 -98.474928) (xy 262.450569 -98.524505)
			(xy 262.421103 -98.570355) (xy 262.385412 -98.611546) (xy 262.344221 -98.647237) (xy 262.298371 -98.676703)
			(xy 262.248794 -98.699345) (xy 262.196499 -98.7147) (xy 262.142551 -98.722456) (xy 262.088049 -98.722456)
			(xy 262.034101 -98.7147) (xy 261.981806 -98.699345) (xy 261.932229 -98.676703) (xy 261.886379 -98.647237)
			(xy 261.845188 -98.611546) (xy 261.809497 -98.570355) (xy 261.780031 -98.524505) (xy 261.757389 -98.474928)
			(xy 261.742034 -98.422633) (xy 261.734278 -98.368685) (xy 261.733792 -98.341434) (xy 2.509012 -98.341434)
			(xy 2.509012 -106.40187) (xy 11.713464 -106.40187) (xy 11.713464 -105.53827) (xy 11.71395 -105.511001)
			(xy 11.721712 -105.457017) (xy 11.737077 -105.404687) (xy 11.759734 -105.355077) (xy 11.78922 -105.309196)
			(xy 11.824935 -105.267979) (xy 11.866152 -105.232264) (xy 11.912033 -105.202778) (xy 11.961643 -105.180121)
			(xy 12.013973 -105.164756) (xy 12.067957 -105.156994) (xy 12.122495 -105.156994) (xy 12.176479 -105.164756)
			(xy 12.228809 -105.180121) (xy 12.278419 -105.202778) (xy 12.3243 -105.232264) (xy 12.365517 -105.267979)
			(xy 12.401232 -105.309196) (xy 12.430718 -105.355077) (xy 12.453375 -105.404687) (xy 12.46874 -105.457017)
			(xy 12.476502 -105.511001) (xy 12.476988 -105.53827) (xy 12.476988 -105.664) (xy 15.57274 -105.664)
			(xy 15.57274 -104.8004) (xy 15.573226 -104.773131) (xy 15.580988 -104.719147) (xy 15.596353 -104.666817)
			(xy 15.61901 -104.617207) (xy 15.648496 -104.571326) (xy 15.684211 -104.530109) (xy 15.725428 -104.494394)
			(xy 15.771309 -104.464908) (xy 15.820919 -104.442251) (xy 15.873249 -104.426886) (xy 15.927233 -104.419124)
			(xy 15.981771 -104.419124) (xy 16.035755 -104.426886) (xy 16.088085 -104.442251) (xy 16.137695 -104.464908)
			(xy 16.183576 -104.494394) (xy 16.224793 -104.530109) (xy 16.260508 -104.571326) (xy 16.289994 -104.617207)
			(xy 16.312651 -104.666817) (xy 16.328016 -104.719147) (xy 16.335778 -104.773131) (xy 16.336264 -104.8004)
			(xy 16.336264 -105.664) (xy 16.335778 -105.691269) (xy 16.328016 -105.745253) (xy 16.312651 -105.797583)
			(xy 16.289994 -105.847193) (xy 16.260508 -105.893074) (xy 16.224793 -105.934291) (xy 16.183576 -105.970006)
			(xy 16.137695 -105.999492) (xy 16.088085 -106.022149) (xy 16.035755 -106.037514) (xy 15.981771 -106.045276)
			(xy 15.927233 -106.045276) (xy 15.873249 -106.037514) (xy 15.820919 -106.022149) (xy 15.771309 -105.999492)
			(xy 15.725428 -105.970006) (xy 15.684211 -105.934291) (xy 15.648496 -105.893074) (xy 15.61901 -105.847193)
			(xy 15.596353 -105.797583) (xy 15.580988 -105.745253) (xy 15.573226 -105.691269) (xy 15.57274 -105.664)
			(xy 12.476988 -105.664) (xy 12.476988 -106.40187) (xy 12.476502 -106.429139) (xy 12.46874 -106.483123)
			(xy 12.453375 -106.535453) (xy 12.430718 -106.585063) (xy 12.401232 -106.630944) (xy 12.365517 -106.672161)
			(xy 12.3243 -106.707876) (xy 12.278419 -106.737362) (xy 12.228809 -106.760019) (xy 12.176479 -106.775384)
			(xy 12.122495 -106.783146) (xy 12.067957 -106.783146) (xy 12.013973 -106.775384) (xy 11.961643 -106.760019)
			(xy 11.912033 -106.737362) (xy 11.866152 -106.707876) (xy 11.824935 -106.672161) (xy 11.78922 -106.630944)
			(xy 11.759734 -106.585063) (xy 11.737077 -106.535453) (xy 11.721712 -106.483123) (xy 11.71395 -106.429139)
			(xy 11.713464 -106.40187) (xy 2.509012 -106.40187) (xy 2.509012 -108.943971) (xy 11.292822 -108.943971)
			(xy 11.292822 -108.889469) (xy 11.300578 -108.835522) (xy 11.315933 -108.783228) (xy 11.338574 -108.733651)
			(xy 11.36804 -108.687801) (xy 11.403731 -108.646611) (xy 11.444921 -108.61092) (xy 11.490771 -108.581454)
			(xy 11.540348 -108.558813) (xy 11.592642 -108.543458) (xy 11.646589 -108.535702) (xy 11.67384 -108.535216)
			(xy 12.53744 -108.535216) (xy 12.564692 -108.535694) (xy 12.61864 -108.54345) (xy 12.670935 -108.558806)
			(xy 12.720513 -108.581447) (xy 12.766364 -108.610914) (xy 12.807554 -108.646606) (xy 12.843246 -108.687796)
			(xy 12.872713 -108.733647) (xy 12.895354 -108.783225) (xy 12.91071 -108.83552) (xy 12.918466 -108.889468)
			(xy 12.918466 -108.943972) (xy 12.918466 -108.943973) (xy 15.156389 -108.943973) (xy 15.156389 -108.889467)
			(xy 15.164146 -108.835517) (xy 15.179502 -108.783219) (xy 15.202145 -108.733639) (xy 15.231613 -108.687786)
			(xy 15.267307 -108.646594) (xy 15.308499 -108.610901) (xy 15.354353 -108.581433) (xy 15.403933 -108.558791)
			(xy 15.45623 -108.543435) (xy 15.510181 -108.535679) (xy 15.537434 -108.535216) (xy 16.401034 -108.535216)
			(xy 16.428285 -108.535694) (xy 16.482233 -108.543451) (xy 16.534528 -108.558807) (xy 16.584105 -108.581448)
			(xy 16.629956 -108.610915) (xy 16.671146 -108.646607) (xy 16.706837 -108.687798) (xy 16.707863 -108.689394)
			(xy 238.647224 -108.689394) (xy 238.647224 -107.825794) (xy 238.64771 -107.798525) (xy 238.655472 -107.744541)
			(xy 238.670837 -107.692211) (xy 238.693494 -107.642601) (xy 238.72298 -107.59672) (xy 238.758695 -107.555503)
			(xy 238.799912 -107.519788) (xy 238.845793 -107.490302) (xy 238.895403 -107.467645) (xy 238.947733 -107.45228)
			(xy 239.001717 -107.444518) (xy 239.056255 -107.444518) (xy 239.110239 -107.45228) (xy 239.162569 -107.467645)
			(xy 239.212179 -107.490302) (xy 239.25806 -107.519788) (xy 239.299277 -107.555503) (xy 239.334992 -107.59672)
			(xy 239.364478 -107.642601) (xy 239.387135 -107.692211) (xy 239.4025 -107.744541) (xy 239.410262 -107.798525)
			(xy 239.410748 -107.825794) (xy 239.410748 -108.689394) (xy 239.410262 -108.716663) (xy 239.4025 -108.770647)
			(xy 239.387135 -108.822977) (xy 239.364478 -108.872587) (xy 239.334992 -108.918468) (xy 239.299277 -108.959685)
			(xy 239.25806 -108.9954) (xy 239.212179 -109.024886) (xy 239.162569 -109.047543) (xy 239.110239 -109.062908)
			(xy 239.056255 -109.07067) (xy 239.001717 -109.07067) (xy 238.947733 -109.062908) (xy 238.895403 -109.047543)
			(xy 238.845793 -109.024886) (xy 238.799912 -108.9954) (xy 238.758695 -108.959685) (xy 238.72298 -108.918468)
			(xy 238.693494 -108.872587) (xy 238.670837 -108.822977) (xy 238.655472 -108.770647) (xy 238.64771 -108.716663)
			(xy 238.647224 -108.689394) (xy 16.707863 -108.689394) (xy 16.736304 -108.733648) (xy 16.758945 -108.783226)
			(xy 16.7743 -108.835521) (xy 16.782056 -108.889469) (xy 16.782056 -108.943971) (xy 16.7743 -108.997919)
			(xy 16.758945 -109.050214) (xy 16.736304 -109.099792) (xy 16.706837 -109.145642) (xy 16.671146 -109.186833)
			(xy 16.629956 -109.222525) (xy 16.584105 -109.251992) (xy 16.534528 -109.274633) (xy 16.482233 -109.289989)
			(xy 16.428285 -109.297746) (xy 16.401034 -109.298232) (xy 15.537434 -109.298232) (xy 15.510181 -109.297761)
			(xy 15.45623 -109.290005) (xy 15.403933 -109.274649) (xy 15.354353 -109.252007) (xy 15.308499 -109.222539)
			(xy 15.267307 -109.186846) (xy 15.231613 -109.145654) (xy 15.202145 -109.099801) (xy 15.179502 -109.050221)
			(xy 15.164146 -108.997923) (xy 15.156389 -108.943973) (xy 12.918466 -108.943973) (xy 12.91071 -108.99792)
			(xy 12.895354 -109.050215) (xy 12.872713 -109.099793) (xy 12.843246 -109.145644) (xy 12.807554 -109.186834)
			(xy 12.766364 -109.222526) (xy 12.720513 -109.251993) (xy 12.670935 -109.274634) (xy 12.61864 -109.28999)
			(xy 12.564692 -109.297746) (xy 12.53744 -109.298232) (xy 11.67384 -109.298232) (xy 11.646589 -109.297738)
			(xy 11.592642 -109.289982) (xy 11.540348 -109.274627) (xy 11.490771 -109.251986) (xy 11.444921 -109.22252)
			(xy 11.403731 -109.186829) (xy 11.36804 -109.145639) (xy 11.338574 -109.099789) (xy 11.315933 -109.050212)
			(xy 11.300578 -108.997918) (xy 11.292822 -108.943971) (xy 2.509012 -108.943971) (xy 2.509012 -109.550266)
			(xy 250.428546 -109.550266) (xy 250.428546 -109.495734) (xy 250.436306 -109.441757) (xy 250.451669 -109.389434)
			(xy 250.474321 -109.339829) (xy 250.503801 -109.293953) (xy 250.53951 -109.252739) (xy 250.580721 -109.217025)
			(xy 250.626594 -109.18754) (xy 250.676196 -109.164883) (xy 250.728518 -109.149515) (xy 250.782494 -109.141749)
			(xy 250.80976 -109.14126) (xy 251.67336 -109.14126) (xy 251.700634 -109.141677) (xy 251.754629 -109.149435)
			(xy 251.806969 -109.164798) (xy 251.85659 -109.187455) (xy 251.902482 -109.216943) (xy 251.943709 -109.252663)
			(xy 251.979433 -109.293886) (xy 252.008926 -109.339775) (xy 252.031588 -109.389393) (xy 252.046957 -109.441732)
			(xy 252.05472 -109.495726) (xy 252.05472 -109.550274) (xy 252.046957 -109.604268) (xy 252.031588 -109.656607)
			(xy 252.008926 -109.706225) (xy 251.979433 -109.752114) (xy 251.943709 -109.793337) (xy 251.902482 -109.829057)
			(xy 251.85659 -109.858545) (xy 251.806969 -109.881202) (xy 251.754629 -109.896565) (xy 251.700634 -109.904323)
			(xy 251.67336 -109.904784) (xy 250.80976 -109.904784) (xy 250.782494 -109.904251) (xy 250.728518 -109.896485)
			(xy 250.676196 -109.881117) (xy 250.626594 -109.85846) (xy 250.580721 -109.828975) (xy 250.53951 -109.793262)
			(xy 250.503801 -109.752047) (xy 250.474321 -109.706171) (xy 250.451669 -109.656566) (xy 250.436306 -109.604243)
			(xy 250.428546 -109.550266) (xy 2.509012 -109.550266) (xy 2.509012 -111.158274) (xy 239.40262 -111.158274)
			(xy 239.40262 -110.294674) (xy 239.403106 -110.267423) (xy 239.410862 -110.213475) (xy 239.426217 -110.16118)
			(xy 239.448859 -110.111603) (xy 239.478325 -110.065753) (xy 239.514016 -110.024562) (xy 239.555207 -109.988871)
			(xy 239.601057 -109.959405) (xy 239.650634 -109.936763) (xy 239.702929 -109.921408) (xy 239.756877 -109.913652)
			(xy 239.811379 -109.913652) (xy 239.865327 -109.921408) (xy 239.917622 -109.936763) (xy 239.967199 -109.959405)
			(xy 240.000574 -109.980854) (xy 256.88563 -109.980854) (xy 256.88563 -109.926346) (xy 256.893387 -109.872392)
			(xy 256.908744 -109.820091) (xy 256.931388 -109.770508) (xy 256.960857 -109.724652) (xy 256.996552 -109.683457)
			(xy 257.037747 -109.647761) (xy 257.083602 -109.61829) (xy 257.133185 -109.595646) (xy 257.185486 -109.580288)
			(xy 257.23944 -109.57253) (xy 257.266694 -109.572044) (xy 258.130294 -109.572044) (xy 258.157544 -109.572603)
			(xy 258.211488 -109.580358) (xy 258.26378 -109.595712) (xy 258.313355 -109.618351) (xy 258.359203 -109.647815)
			(xy 258.400391 -109.683504) (xy 258.436081 -109.724692) (xy 258.465546 -109.77054) (xy 258.488186 -109.820114)
			(xy 258.503541 -109.872406) (xy 258.511297 -109.92635) (xy 258.511297 -109.98085) (xy 258.503541 -110.034794)
			(xy 258.488186 -110.087086) (xy 258.465546 -110.13666) (xy 258.436081 -110.182508) (xy 258.400391 -110.223696)
			(xy 258.359203 -110.259385) (xy 258.313355 -110.288849) (xy 258.26378 -110.311488) (xy 258.211488 -110.326842)
			(xy 258.157544 -110.334597) (xy 258.130294 -110.33506) (xy 257.266694 -110.33506) (xy 257.23944 -110.33467)
			(xy 257.185486 -110.326912) (xy 257.133185 -110.311554) (xy 257.083602 -110.28891) (xy 257.037747 -110.259439)
			(xy 256.996552 -110.223743) (xy 256.960857 -110.182548) (xy 256.931388 -110.136692) (xy 256.908744 -110.087109)
			(xy 256.893387 -110.034808) (xy 256.88563 -109.980854) (xy 240.000574 -109.980854) (xy 240.013049 -109.988871)
			(xy 240.05424 -110.024562) (xy 240.089931 -110.065753) (xy 240.119397 -110.111603) (xy 240.142039 -110.16118)
			(xy 240.157394 -110.213475) (xy 240.16515 -110.267423) (xy 240.165636 -110.294674) (xy 240.165636 -111.158274)
			(xy 240.16515 -111.185525) (xy 240.157394 -111.239473) (xy 240.142039 -111.291768) (xy 240.119397 -111.341345)
			(xy 240.089931 -111.387195) (xy 240.05424 -111.428386) (xy 240.013049 -111.464077) (xy 239.967199 -111.493543)
			(xy 239.917622 -111.516185) (xy 239.865327 -111.53154) (xy 239.811379 -111.539296) (xy 239.756877 -111.539296)
			(xy 239.702929 -111.53154) (xy 239.650634 -111.516185) (xy 239.601057 -111.493543) (xy 239.555207 -111.464077)
			(xy 239.514016 -111.428386) (xy 239.478325 -111.387195) (xy 239.448859 -111.341345) (xy 239.426217 -111.291768)
			(xy 239.410862 -111.239473) (xy 239.403106 -111.185525) (xy 239.40262 -111.158274) (xy 2.509012 -111.158274)
			(xy 2.509012 -111.209328) (xy 11.789156 -111.209328) (xy 11.960352 -111.209328) (xy 12.188952 -111.209328)
			(xy 12.360148 -111.209328) (xy 12.360148 -112.031272) (xy 12.188952 -112.031272) (xy 12.188952 -111.209328)
			(xy 11.960352 -111.209328) (xy 11.960352 -112.031272) (xy 11.789156 -112.031272) (xy 11.789156 -111.209328)
			(xy 2.509012 -111.209328) (xy 2.509012 -112.609376) (xy 11.789156 -112.609376) (xy 11.960352 -112.609376)
			(xy 12.188952 -112.609376) (xy 12.360148 -112.609376) (xy 12.360148 -113.43132) (xy 12.188952 -113.43132)
			(xy 12.188952 -112.609376) (xy 11.960352 -112.609376) (xy 11.960352 -113.43132) (xy 11.789156 -113.43132)
			(xy 11.789156 -112.609376) (xy 2.509012 -112.609376) (xy 2.509012 -114.734161) (xy 11.255226 -114.734161)
			(xy 11.255226 -114.679659) (xy 11.262982 -114.625711) (xy 11.278337 -114.573416) (xy 11.300979 -114.523839)
			(xy 11.330445 -114.477988) (xy 11.366136 -114.436798) (xy 11.407326 -114.401106) (xy 11.453177 -114.371639)
			(xy 11.502754 -114.348998) (xy 11.555049 -114.333643) (xy 11.608997 -114.325886) (xy 11.636248 -114.3254)
			(xy 12.499848 -114.3254) (xy 12.527101 -114.325867) (xy 12.581052 -114.333624) (xy 12.633349 -114.34898)
			(xy 12.68293 -114.371622) (xy 12.728783 -114.40109) (xy 12.769975 -114.436783) (xy 12.805669 -114.477976)
			(xy 12.835137 -114.523829) (xy 12.85778 -114.573409) (xy 12.873136 -114.625706) (xy 12.880893 -114.679657)
			(xy 12.880893 -114.734163) (xy 12.873136 -114.788114) (xy 12.85778 -114.840411) (xy 12.835137 -114.889991)
			(xy 12.805669 -114.935844) (xy 12.769975 -114.977037) (xy 12.728783 -115.01273) (xy 12.68293 -115.042198)
			(xy 12.633349 -115.06484) (xy 12.581052 -115.080196) (xy 12.527101 -115.087953) (xy 12.499848 -115.088416)
			(xy 11.636248 -115.088416) (xy 11.608997 -115.087934) (xy 11.555049 -115.080177) (xy 11.502754 -115.064822)
			(xy 11.453177 -115.042181) (xy 11.407326 -115.012714) (xy 11.366136 -114.977022) (xy 11.330445 -114.935832)
			(xy 11.300979 -114.889981) (xy 11.278337 -114.840404) (xy 11.262982 -114.788109) (xy 11.255226 -114.734161)
			(xy 2.509012 -114.734161) (xy 2.509012 -116.393573) (xy 230.652992 -116.393573) (xy 230.652992 -116.339027)
			(xy 230.660755 -116.285035) (xy 230.676123 -116.232698) (xy 230.698784 -116.183081) (xy 230.728276 -116.137195)
			(xy 230.763998 -116.095973) (xy 230.805224 -116.060254) (xy 230.851113 -116.030767) (xy 230.900732 -116.008111)
			(xy 230.95307 -115.992747) (xy 231.007063 -115.984989) (xy 231.034336 -115.984528) (xy 231.897936 -115.984528)
			(xy 231.925203 -115.985037) (xy 231.979181 -115.992802) (xy 232.031505 -116.008171) (xy 232.081109 -116.030828)
			(xy 232.126985 -116.060314) (xy 232.168197 -116.096029) (xy 232.203907 -116.137244) (xy 232.233389 -116.183122)
			(xy 232.256042 -116.232729) (xy 232.271405 -116.285054) (xy 232.277026 -116.324151) (xy 236.866903 -116.324151)
			(xy 236.866903 -116.269649) (xy 236.87466 -116.215701) (xy 236.890016 -116.163407) (xy 236.912659 -116.113831)
			(xy 236.942127 -116.067981) (xy 236.97782 -116.026793) (xy 237.019012 -115.991104) (xy 237.064864 -115.961641)
			(xy 237.114443 -115.939003) (xy 237.166739 -115.923652) (xy 237.220687 -115.915901) (xy 237.247938 -115.91544)
			(xy 238.111538 -115.91544) (xy 238.138791 -115.915832) (xy 238.192741 -115.923594) (xy 238.245038 -115.938955)
			(xy 238.294617 -115.961601) (xy 238.340468 -115.991072) (xy 238.381659 -116.026768) (xy 238.417351 -116.067962)
			(xy 238.446817 -116.113817) (xy 238.469459 -116.163398) (xy 238.484814 -116.215696) (xy 238.49257 -116.269647)
			(xy 238.49257 -116.324153) (xy 238.484814 -116.378104) (xy 238.469459 -116.430402) (xy 238.446817 -116.479983)
			(xy 238.417351 -116.525838) (xy 238.381659 -116.567032) (xy 238.340468 -116.602728) (xy 238.294617 -116.632199)
			(xy 238.245038 -116.654845) (xy 238.192741 -116.670206) (xy 238.138791 -116.677968) (xy 238.111538 -116.678456)
			(xy 237.247938 -116.678456) (xy 237.220687 -116.677899) (xy 237.166739 -116.670148) (xy 237.114443 -116.654797)
			(xy 237.064864 -116.632159) (xy 237.019012 -116.602696) (xy 236.97782 -116.567007) (xy 236.942127 -116.525819)
			(xy 236.912659 -116.479969) (xy 236.890016 -116.430393) (xy 236.87466 -116.378099) (xy 236.866903 -116.324151)
			(xy 232.277026 -116.324151) (xy 232.279166 -116.339033) (xy 232.279166 -116.393567) (xy 232.271405 -116.447546)
			(xy 232.256042 -116.499871) (xy 232.233389 -116.549478) (xy 232.203907 -116.595356) (xy 232.168197 -116.636571)
			(xy 232.126985 -116.672286) (xy 232.081109 -116.701772) (xy 232.031505 -116.724429) (xy 231.979181 -116.739798)
			(xy 231.925203 -116.747563) (xy 231.897936 -116.748052) (xy 231.034336 -116.748052) (xy 231.007063 -116.747611)
			(xy 230.95307 -116.739853) (xy 230.900732 -116.724489) (xy 230.851113 -116.701833) (xy 230.805224 -116.672346)
			(xy 230.763998 -116.636627) (xy 230.728276 -116.595405) (xy 230.698784 -116.549519) (xy 230.676123 -116.499902)
			(xy 230.660755 -116.447565) (xy 230.652992 -116.393573) (xy 2.509012 -116.393573) (xy 2.509012 -117.632251)
			(xy 233.564903 -117.632251) (xy 233.564903 -117.577749) (xy 233.57266 -117.523801) (xy 233.588016 -117.471507)
			(xy 233.610659 -117.421931) (xy 233.640127 -117.376081) (xy 233.67582 -117.334893) (xy 233.717012 -117.299204)
			(xy 233.762864 -117.269741) (xy 233.812443 -117.247103) (xy 233.864739 -117.231752) (xy 233.918687 -117.224001)
			(xy 233.945938 -117.22354) (xy 234.809538 -117.22354) (xy 234.836791 -117.223932) (xy 234.890741 -117.231694)
			(xy 234.943038 -117.247055) (xy 234.992617 -117.269701) (xy 235.038468 -117.299172) (xy 235.079659 -117.334868)
			(xy 235.115351 -117.376062) (xy 235.144817 -117.421917) (xy 235.167459 -117.471498) (xy 235.182814 -117.523796)
			(xy 235.19057 -117.577747) (xy 235.19057 -117.632251) (xy 238.898903 -117.632251) (xy 238.898903 -117.577749)
			(xy 238.90666 -117.523801) (xy 238.922016 -117.471507) (xy 238.944659 -117.421931) (xy 238.974127 -117.376081)
			(xy 239.00982 -117.334893) (xy 239.051012 -117.299204) (xy 239.096864 -117.269741) (xy 239.146443 -117.247103)
			(xy 239.198739 -117.231752) (xy 239.252687 -117.224001) (xy 239.279938 -117.22354) (xy 240.143538 -117.22354)
			(xy 240.170791 -117.223932) (xy 240.224741 -117.231694) (xy 240.277038 -117.247055) (xy 240.326617 -117.269701)
			(xy 240.372468 -117.299172) (xy 240.413659 -117.334868) (xy 240.449351 -117.376062) (xy 240.478817 -117.421917)
			(xy 240.501459 -117.471498) (xy 240.516814 -117.523796) (xy 240.52457 -117.577747) (xy 240.52457 -117.632253)
			(xy 240.516814 -117.686204) (xy 240.501459 -117.738502) (xy 240.478817 -117.788083) (xy 240.449351 -117.833938)
			(xy 240.413659 -117.875132) (xy 240.372468 -117.910828) (xy 240.326617 -117.940299) (xy 240.277038 -117.962945)
			(xy 240.224741 -117.978306) (xy 240.170791 -117.986068) (xy 240.143538 -117.986556) (xy 239.279938 -117.986556)
			(xy 239.252687 -117.985999) (xy 239.198739 -117.978248) (xy 239.146443 -117.962897) (xy 239.096864 -117.940259)
			(xy 239.051012 -117.910796) (xy 239.00982 -117.875107) (xy 238.974127 -117.833919) (xy 238.944659 -117.788069)
			(xy 238.922016 -117.738493) (xy 238.90666 -117.686199) (xy 238.898903 -117.632251) (xy 235.19057 -117.632251)
			(xy 235.19057 -117.632253) (xy 235.182814 -117.686204) (xy 235.167459 -117.738502) (xy 235.144817 -117.788083)
			(xy 235.115351 -117.833938) (xy 235.079659 -117.875132) (xy 235.038468 -117.910828) (xy 234.992617 -117.940299)
			(xy 234.943038 -117.962945) (xy 234.890741 -117.978306) (xy 234.836791 -117.986068) (xy 234.809538 -117.986556)
			(xy 233.945938 -117.986556) (xy 233.918687 -117.985999) (xy 233.864739 -117.978248) (xy 233.812443 -117.962897)
			(xy 233.762864 -117.940259) (xy 233.717012 -117.910796) (xy 233.67582 -117.875107) (xy 233.640127 -117.833919)
			(xy 233.610659 -117.788069) (xy 233.588016 -117.738493) (xy 233.57266 -117.686199) (xy 233.564903 -117.632251)
			(xy 2.509012 -117.632251) (xy 2.509012 -123.093988) (xy 227.217732 -123.093988) (xy 227.217732 -122.230388)
			(xy 227.218218 -122.203137) (xy 227.225974 -122.149189) (xy 227.241329 -122.096894) (xy 227.263971 -122.047317)
			(xy 227.293437 -122.001467) (xy 227.329128 -121.960276) (xy 227.370319 -121.924585) (xy 227.416169 -121.895119)
			(xy 227.465746 -121.872477) (xy 227.518041 -121.857122) (xy 227.571989 -121.849366) (xy 227.626491 -121.849366)
			(xy 227.680439 -121.857122) (xy 227.732734 -121.872477) (xy 227.782311 -121.895119) (xy 227.828161 -121.924585)
			(xy 227.869352 -121.960276) (xy 227.905043 -122.001467) (xy 227.934509 -122.047317) (xy 227.957151 -122.096894)
			(xy 227.972506 -122.149189) (xy 227.980262 -122.203137) (xy 227.980748 -122.230388) (xy 227.980748 -122.921014)
			(xy 245.563136 -122.921014) (xy 245.563136 -122.057414) (xy 245.563622 -122.030163) (xy 245.571378 -121.976215)
			(xy 245.586733 -121.92392) (xy 245.609375 -121.874343) (xy 245.638841 -121.828493) (xy 245.674532 -121.787302)
			(xy 245.715723 -121.751611) (xy 245.761573 -121.722145) (xy 245.81115 -121.699503) (xy 245.863445 -121.684148)
			(xy 245.917393 -121.676392) (xy 245.971895 -121.676392) (xy 246.025843 -121.684148) (xy 246.078138 -121.699503)
			(xy 246.127715 -121.722145) (xy 246.173565 -121.751611) (xy 246.214756 -121.787302) (xy 246.250447 -121.828493)
			(xy 246.279913 -121.874343) (xy 246.302555 -121.92392) (xy 246.31791 -121.976215) (xy 246.325666 -122.030163)
			(xy 246.326152 -122.057414) (xy 246.326152 -122.921014) (xy 246.325666 -122.948265) (xy 246.31791 -123.002213)
			(xy 246.302555 -123.054508) (xy 246.279913 -123.104085) (xy 246.250447 -123.149935) (xy 246.214756 -123.191126)
			(xy 246.173565 -123.226817) (xy 246.127715 -123.256283) (xy 246.078138 -123.278925) (xy 246.025843 -123.29428)
			(xy 245.971895 -123.302036) (xy 245.917393 -123.302036) (xy 245.863445 -123.29428) (xy 245.81115 -123.278925)
			(xy 245.761573 -123.256283) (xy 245.715723 -123.226817) (xy 245.674532 -123.191126) (xy 245.638841 -123.149935)
			(xy 245.609375 -123.104085) (xy 245.586733 -123.054508) (xy 245.571378 -123.002213) (xy 245.563622 -122.948265)
			(xy 245.563136 -122.921014) (xy 227.980748 -122.921014) (xy 227.980748 -123.093988) (xy 227.980262 -123.121239)
			(xy 227.972506 -123.175187) (xy 227.957151 -123.227482) (xy 227.934509 -123.277059) (xy 227.905043 -123.322909)
			(xy 227.869352 -123.3641) (xy 227.828161 -123.399791) (xy 227.782311 -123.429257) (xy 227.732734 -123.451899)
			(xy 227.680439 -123.467254) (xy 227.626491 -123.47501) (xy 227.571989 -123.47501) (xy 227.518041 -123.467254)
			(xy 227.465746 -123.451899) (xy 227.416169 -123.429257) (xy 227.370319 -123.399791) (xy 227.329128 -123.3641)
			(xy 227.293437 -123.322909) (xy 227.263971 -123.277059) (xy 227.241329 -123.227482) (xy 227.225974 -123.175187)
			(xy 227.218218 -123.121239) (xy 227.217732 -123.093988) (xy 2.509012 -123.093988) (xy 2.509012 -125.221746)
			(xy 225.535744 -125.221746) (xy 225.535744 -124.358146) (xy 225.53623 -124.330877) (xy 225.543992 -124.276893)
			(xy 225.559357 -124.224563) (xy 225.582014 -124.174953) (xy 225.6115 -124.129072) (xy 225.647215 -124.087855)
			(xy 225.688432 -124.05214) (xy 225.734313 -124.022654) (xy 225.783923 -123.999997) (xy 225.836253 -123.984632)
			(xy 225.890237 -123.97687) (xy 225.944775 -123.97687) (xy 225.998759 -123.984632) (xy 226.051089 -123.999997)
			(xy 226.100699 -124.022654) (xy 226.14658 -124.05214) (xy 226.187797 -124.087855) (xy 226.223512 -124.129072)
			(xy 226.252998 -124.174953) (xy 226.275655 -124.224563) (xy 226.29102 -124.276893) (xy 226.298782 -124.330877)
			(xy 226.299268 -124.358146) (xy 226.299268 -125.221746) (xy 226.298782 -125.249015) (xy 226.29102 -125.302999)
			(xy 226.275655 -125.355329) (xy 226.252998 -125.404939) (xy 226.223512 -125.45082) (xy 226.187797 -125.492037)
			(xy 226.14658 -125.527752) (xy 226.100699 -125.557238) (xy 226.051089 -125.579895) (xy 225.998759 -125.59526)
			(xy 225.944775 -125.603022) (xy 225.890237 -125.603022) (xy 225.836253 -125.59526) (xy 225.783923 -125.579895)
			(xy 225.734313 -125.557238) (xy 225.688432 -125.527752) (xy 225.647215 -125.492037) (xy 225.6115 -125.45082)
			(xy 225.582014 -125.404939) (xy 225.559357 -125.355329) (xy 225.543992 -125.302999) (xy 225.53623 -125.249015)
			(xy 225.535744 -125.221746) (xy 2.509012 -125.221746) (xy 2.509012 -127.325628) (xy 227.034852 -127.325628)
			(xy 227.034852 -126.462028) (xy 227.035338 -126.434777) (xy 227.043094 -126.380829) (xy 227.058449 -126.328534)
			(xy 227.081091 -126.278957) (xy 227.110557 -126.233107) (xy 227.146248 -126.191916) (xy 227.187439 -126.156225)
			(xy 227.233289 -126.126759) (xy 227.282866 -126.104117) (xy 227.335161 -126.088762) (xy 227.389109 -126.081006)
			(xy 227.443611 -126.081006) (xy 227.497559 -126.088762) (xy 227.549854 -126.104117) (xy 227.599431 -126.126759)
			(xy 227.645281 -126.156225) (xy 227.686472 -126.191916) (xy 227.722163 -126.233107) (xy 227.751629 -126.278957)
			(xy 227.774271 -126.328534) (xy 227.789626 -126.380829) (xy 227.797382 -126.434777) (xy 227.797868 -126.462028)
			(xy 227.797868 -127.140208) (xy 242.041172 -127.140208) (xy 242.041172 -126.276608) (xy 242.041658 -126.249357)
			(xy 242.049414 -126.195409) (xy 242.064769 -126.143114) (xy 242.087411 -126.093537) (xy 242.116877 -126.047687)
			(xy 242.152568 -126.006496) (xy 242.193759 -125.970805) (xy 242.239609 -125.941339) (xy 242.289186 -125.918697)
			(xy 242.341481 -125.903342) (xy 242.395429 -125.895586) (xy 242.449931 -125.895586) (xy 242.503879 -125.903342)
			(xy 242.556174 -125.918697) (xy 242.605751 -125.941339) (xy 242.651601 -125.970805) (xy 242.692792 -126.006496)
			(xy 242.728483 -126.047687) (xy 242.757949 -126.093537) (xy 242.780591 -126.143114) (xy 242.795946 -126.195409)
			(xy 242.803702 -126.249357) (xy 242.804188 -126.276608) (xy 242.804188 -127.140208) (xy 242.803702 -127.167459)
			(xy 242.795946 -127.221407) (xy 242.780591 -127.273702) (xy 242.757949 -127.323279) (xy 242.728483 -127.369129)
			(xy 242.692792 -127.41032) (xy 242.651601 -127.446011) (xy 242.605751 -127.475477) (xy 242.556174 -127.498119)
			(xy 242.503879 -127.513474) (xy 242.449931 -127.52123) (xy 242.395429 -127.52123) (xy 242.341481 -127.513474)
			(xy 242.289186 -127.498119) (xy 242.239609 -127.475477) (xy 242.193759 -127.446011) (xy 242.152568 -127.41032)
			(xy 242.116877 -127.369129) (xy 242.087411 -127.323279) (xy 242.064769 -127.273702) (xy 242.049414 -127.221407)
			(xy 242.041658 -127.167459) (xy 242.041172 -127.140208) (xy 227.797868 -127.140208) (xy 227.797868 -127.325628)
			(xy 227.797382 -127.352879) (xy 227.789626 -127.406827) (xy 227.774271 -127.459122) (xy 227.751629 -127.508699)
			(xy 227.722163 -127.554549) (xy 227.686472 -127.59574) (xy 227.645281 -127.631431) (xy 227.599431 -127.660897)
			(xy 227.549854 -127.683539) (xy 227.519478 -127.692458) (xy 458.401155 -127.692458) (xy 458.401155 -127.563318)
			(xy 458.409105 -127.434423) (xy 458.424975 -127.306263) (xy 458.448704 -127.179322) (xy 458.480203 -127.054083)
			(xy 458.519352 -126.93102) (xy 458.566003 -126.810601) (xy 458.619978 -126.693282) (xy 458.681073 -126.579508)
			(xy 458.749056 -126.469711) (xy 458.82367 -126.364308) (xy 458.904631 -126.263698) (xy 458.991631 -126.168263)
			(xy 459.084342 -126.078364) (xy 459.182412 -125.994343) (xy 459.285467 -125.916519) (xy 459.393118 -125.845187)
			(xy 459.504957 -125.780617) (xy 459.620558 -125.723055) (xy 459.739483 -125.672718) (xy 459.861282 -125.629798)
			(xy 459.985492 -125.594457) (xy 460.111641 -125.56683) (xy 460.239253 -125.547021) (xy 460.367842 -125.535105)
			(xy 460.49692 -125.531129) (xy 460.625998 -125.535105) (xy 460.754587 -125.547021) (xy 460.882199 -125.56683)
			(xy 461.008348 -125.594457) (xy 461.132558 -125.629798) (xy 461.254357 -125.672718) (xy 461.373282 -125.723055)
			(xy 461.488883 -125.780617) (xy 461.600722 -125.845187) (xy 461.708373 -125.916519) (xy 461.811428 -125.994343)
			(xy 461.909498 -126.078364) (xy 462.002209 -126.168263) (xy 462.089209 -126.263698) (xy 462.17017 -126.364308)
			(xy 462.244784 -126.469711) (xy 462.312767 -126.579508) (xy 462.373862 -126.693282) (xy 462.427837 -126.810601)
			(xy 462.474488 -126.93102) (xy 462.513637 -127.054083) (xy 462.545136 -127.179322) (xy 462.568865 -127.306263)
			(xy 462.584735 -127.434423) (xy 462.592685 -127.563318) (xy 462.593182 -127.627888) (xy 462.592685 -127.692458)
			(xy 462.584735 -127.821353) (xy 462.568865 -127.949513) (xy 462.545136 -128.076454) (xy 462.513637 -128.201693)
			(xy 462.474488 -128.324756) (xy 462.427837 -128.445175) (xy 462.373862 -128.562494) (xy 462.312767 -128.676268)
			(xy 462.244784 -128.786065) (xy 462.17017 -128.891468) (xy 462.089209 -128.992078) (xy 462.002209 -129.087513)
			(xy 461.909498 -129.177412) (xy 461.811428 -129.261433) (xy 461.708373 -129.339257) (xy 461.600722 -129.410589)
			(xy 461.488883 -129.475159) (xy 461.373282 -129.532721) (xy 461.254357 -129.583058) (xy 461.132558 -129.625978)
			(xy 461.008348 -129.661319) (xy 460.882199 -129.688946) (xy 460.754587 -129.708755) (xy 460.625998 -129.720671)
			(xy 460.49692 -129.724648) (xy 460.367842 -129.720671) (xy 460.239253 -129.708755) (xy 460.111641 -129.688946)
			(xy 459.985492 -129.661319) (xy 459.861282 -129.625978) (xy 459.739483 -129.583058) (xy 459.620558 -129.532721)
			(xy 459.504957 -129.475159) (xy 459.393118 -129.410589) (xy 459.285467 -129.339257) (xy 459.182412 -129.261433)
			(xy 459.084342 -129.177412) (xy 458.991631 -129.087513) (xy 458.904631 -128.992078) (xy 458.82367 -128.891468)
			(xy 458.749056 -128.786065) (xy 458.681073 -128.676268) (xy 458.619978 -128.562494) (xy 458.566003 -128.445175)
			(xy 458.519352 -128.324756) (xy 458.480203 -128.201693) (xy 458.448704 -128.076454) (xy 458.424975 -127.949513)
			(xy 458.409105 -127.821353) (xy 458.401155 -127.692458) (xy 227.519478 -127.692458) (xy 227.497559 -127.698894)
			(xy 227.443611 -127.70665) (xy 227.389109 -127.70665) (xy 227.335161 -127.698894) (xy 227.282866 -127.683539)
			(xy 227.233289 -127.660897) (xy 227.187439 -127.631431) (xy 227.146248 -127.59574) (xy 227.110557 -127.554549)
			(xy 227.081091 -127.508699) (xy 227.058449 -127.459122) (xy 227.043094 -127.406827) (xy 227.035338 -127.352879)
			(xy 227.034852 -127.325628) (xy 2.509012 -127.325628) (xy 2.509012 -129.073148) (xy 223.562672 -129.073148)
			(xy 223.562672 -128.209548) (xy 223.563115 -128.182788) (xy 223.570596 -128.129795) (xy 223.585403 -128.078365)
			(xy 223.607247 -128.029506) (xy 223.621092 -128.006602) (xy 223.636032 -127.983032) (xy 223.671662 -127.940084)
			(xy 223.713174 -127.902792) (xy 223.759681 -127.871951) (xy 223.810187 -127.848221) (xy 223.863614 -127.832109)
			(xy 223.918819 -127.823961) (xy 223.94672 -127.823468) (xy 223.973934 -127.823967) (xy 224.027808 -127.831715)
			(xy 224.080031 -127.84705) (xy 224.12954 -127.869661) (xy 224.175327 -127.899088) (xy 224.216462 -127.93473)
			(xy 224.252105 -127.975863) (xy 224.281533 -128.02165) (xy 224.304145 -128.071158) (xy 224.319483 -128.123381)
			(xy 224.327232 -128.177254) (xy 224.32772 -128.204468) (xy 224.32772 -128.204722) (xy 224.325942 -128.241552)
			(xy 224.325688 -128.243838) (xy 224.325688 -129.019808) (xy 240.086896 -129.019808) (xy 240.086896 -128.156208)
			(xy 240.087382 -128.128939) (xy 240.095144 -128.074955) (xy 240.110509 -128.022625) (xy 240.133166 -127.973015)
			(xy 240.162652 -127.927134) (xy 240.198367 -127.885917) (xy 240.239584 -127.850202) (xy 240.285465 -127.820716)
			(xy 240.335075 -127.798059) (xy 240.387405 -127.782694) (xy 240.441389 -127.774932) (xy 240.495927 -127.774932)
			(xy 240.549911 -127.782694) (xy 240.602241 -127.798059) (xy 240.651851 -127.820716) (xy 240.697732 -127.850202)
			(xy 240.738949 -127.885917) (xy 240.774664 -127.927134) (xy 240.80415 -127.973015) (xy 240.826807 -128.022625)
			(xy 240.842172 -128.074955) (xy 240.849934 -128.128939) (xy 240.85042 -128.156208) (xy 240.85042 -129.019808)
			(xy 240.849934 -129.047077) (xy 240.842172 -129.101061) (xy 240.826807 -129.153391) (xy 240.80415 -129.203001)
			(xy 240.774664 -129.248882) (xy 240.738949 -129.290099) (xy 240.697732 -129.325814) (xy 240.651851 -129.3553)
			(xy 240.602241 -129.377957) (xy 240.549911 -129.393322) (xy 240.495927 -129.401084) (xy 240.441389 -129.401084)
			(xy 240.387405 -129.393322) (xy 240.335075 -129.377957) (xy 240.285465 -129.3553) (xy 240.239584 -129.325814)
			(xy 240.198367 -129.290099) (xy 240.162652 -129.248882) (xy 240.133166 -129.203001) (xy 240.110509 -129.153391)
			(xy 240.095144 -129.101061) (xy 240.087382 -129.047077) (xy 240.086896 -129.019808) (xy 224.325688 -129.019808)
			(xy 224.325942 -129.022602) (xy 224.327226 -129.033861) (xy 224.328622 -129.056482) (xy 224.328736 -129.067814)
			(xy 224.328736 -129.068068) (xy 224.328226 -129.095352) (xy 224.320425 -129.14936) (xy 224.305035 -129.201713)
			(xy 224.282367 -129.251351) (xy 224.26803 -129.27457) (xy 224.253042 -129.297814) (xy 224.217376 -129.340083)
			(xy 224.175977 -129.376756) (xy 224.129714 -129.407061) (xy 224.079557 -129.430365) (xy 224.026559 -129.446176)
			(xy 223.971833 -129.454165) (xy 223.94418 -129.454656) (xy 223.91693 -129.454141) (xy 223.862986 -129.446383)
			(xy 223.810695 -129.431028) (xy 223.761121 -129.408388) (xy 223.715273 -129.378924) (xy 223.674084 -129.343236)
			(xy 223.638393 -129.30205) (xy 223.608926 -129.256204) (xy 223.586282 -129.206631) (xy 223.570923 -129.154341)
			(xy 223.563161 -129.100398) (xy 223.562672 -129.073148) (xy 2.509012 -129.073148) (xy 2.509012 -131.09702)
			(xy 228.682804 -131.09702) (xy 228.682804 -130.23342) (xy 228.68329 -130.206151) (xy 228.691052 -130.152167)
			(xy 228.706417 -130.099837) (xy 228.729074 -130.050227) (xy 228.75856 -130.004346) (xy 228.794275 -129.963129)
			(xy 228.835492 -129.927414) (xy 228.881373 -129.897928) (xy 228.930983 -129.875271) (xy 228.983313 -129.859906)
			(xy 229.037297 -129.852144) (xy 229.091835 -129.852144) (xy 229.145819 -129.859906) (xy 229.198149 -129.875271)
			(xy 229.247759 -129.897928) (xy 229.29364 -129.927414) (xy 229.334857 -129.963129) (xy 229.370572 -130.004346)
			(xy 229.400058 -130.050227) (xy 229.422715 -130.099837) (xy 229.43808 -130.152167) (xy 229.445842 -130.206151)
			(xy 229.446328 -130.23342) (xy 229.446328 -130.721608) (xy 242.041172 -130.721608) (xy 242.041172 -129.858008)
			(xy 242.041658 -129.830757) (xy 242.049414 -129.776809) (xy 242.064769 -129.724514) (xy 242.087411 -129.674937)
			(xy 242.116877 -129.629087) (xy 242.152568 -129.587896) (xy 242.193759 -129.552205) (xy 242.239609 -129.522739)
			(xy 242.289186 -129.500097) (xy 242.341481 -129.484742) (xy 242.395429 -129.476986) (xy 242.449931 -129.476986)
			(xy 242.503879 -129.484742) (xy 242.556174 -129.500097) (xy 242.605751 -129.522739) (xy 242.651601 -129.552205)
			(xy 242.692792 -129.587896) (xy 242.728483 -129.629087) (xy 242.757949 -129.674937) (xy 242.780591 -129.724514)
			(xy 242.795946 -129.776809) (xy 242.803702 -129.830757) (xy 242.804188 -129.858008) (xy 242.804188 -130.721608)
			(xy 242.803702 -130.748859) (xy 242.795946 -130.802807) (xy 242.780591 -130.855102) (xy 242.757949 -130.904679)
			(xy 242.728483 -130.950529) (xy 242.692792 -130.99172) (xy 242.651601 -131.027411) (xy 242.605751 -131.056877)
			(xy 242.556174 -131.079519) (xy 242.503879 -131.094874) (xy 242.449931 -131.10263) (xy 242.395429 -131.10263)
			(xy 242.341481 -131.094874) (xy 242.289186 -131.079519) (xy 242.239609 -131.056877) (xy 242.193759 -131.027411)
			(xy 242.152568 -130.99172) (xy 242.116877 -130.950529) (xy 242.087411 -130.904679) (xy 242.064769 -130.855102)
			(xy 242.049414 -130.802807) (xy 242.041658 -130.748859) (xy 242.041172 -130.721608) (xy 229.446328 -130.721608)
			(xy 229.446328 -131.09702) (xy 229.445842 -131.124289) (xy 229.43808 -131.178273) (xy 229.422715 -131.230603)
			(xy 229.400058 -131.280213) (xy 229.370572 -131.326094) (xy 229.334857 -131.367311) (xy 229.29364 -131.403026)
			(xy 229.247759 -131.432512) (xy 229.198149 -131.455169) (xy 229.145819 -131.470534) (xy 229.091835 -131.478296)
			(xy 229.037297 -131.478296) (xy 228.983313 -131.470534) (xy 228.930983 -131.455169) (xy 228.881373 -131.432512)
			(xy 228.835492 -131.403026) (xy 228.794275 -131.367311) (xy 228.75856 -131.326094) (xy 228.729074 -131.280213)
			(xy 228.706417 -131.230603) (xy 228.691052 -131.178273) (xy 228.68329 -131.124289) (xy 228.682804 -131.09702)
			(xy 2.509012 -131.09702) (xy 2.509012 -132.529347) (xy 231.621126 -132.529347) (xy 231.621126 -132.474853)
			(xy 231.628881 -132.420915) (xy 231.644233 -132.368628) (xy 231.666869 -132.319059) (xy 231.69633 -132.273216)
			(xy 231.732014 -132.232031) (xy 231.773196 -132.196344) (xy 231.819038 -132.166881) (xy 231.868606 -132.144241)
			(xy 231.920891 -132.128886) (xy 231.974829 -132.121128) (xy 232.002076 -132.12064) (xy 232.865676 -132.12064)
			(xy 232.892933 -132.121005) (xy 232.946894 -132.128761) (xy 232.999201 -132.144116) (xy 233.048791 -132.16676)
			(xy 233.094653 -132.196231) (xy 233.135853 -132.23193) (xy 233.171554 -132.273128) (xy 233.201028 -132.318988)
			(xy 233.223675 -132.368576) (xy 233.239034 -132.420883) (xy 233.246793 -132.474843) (xy 233.246793 -132.529357)
			(xy 233.239034 -132.583317) (xy 233.223675 -132.635624) (xy 233.201028 -132.685212) (xy 233.171554 -132.731072)
			(xy 233.135853 -132.77227) (xy 233.094653 -132.807968) (xy 233.048791 -132.83744) (xy 232.999201 -132.860084)
			(xy 232.946894 -132.875439) (xy 232.892933 -132.883195) (xy 232.865676 -132.883656) (xy 232.002076 -132.883656)
			(xy 231.974829 -132.883072) (xy 231.920891 -132.875314) (xy 231.868606 -132.859959) (xy 231.819038 -132.837319)
			(xy 231.773196 -132.807856) (xy 231.732014 -132.772169) (xy 231.69633 -132.730984) (xy 231.666869 -132.685141)
			(xy 231.644233 -132.635572) (xy 231.628881 -132.583285) (xy 231.621126 -132.529347) (xy 2.509012 -132.529347)
			(xy 2.509012 -135.31065) (xy 225.204003 -135.31065) (xy 225.204003 -135.25615) (xy 225.21176 -135.202204)
			(xy 225.227115 -135.149911) (xy 225.249756 -135.100336) (xy 225.279222 -135.054487) (xy 225.314914 -135.013299)
			(xy 225.356103 -134.97761) (xy 225.401953 -134.948146) (xy 225.45153 -134.925508) (xy 225.503823 -134.910156)
			(xy 225.55777 -134.902402) (xy 225.58502 -134.90194) (xy 226.44862 -134.90194) (xy 226.475874 -134.902331)
			(xy 226.529826 -134.910091) (xy 226.582125 -134.92545) (xy 226.631706 -134.948095) (xy 226.67756 -134.977566)
			(xy 226.718753 -135.013262) (xy 226.754446 -135.054456) (xy 226.755856 -135.05665) (xy 228.531403 -135.05665)
			(xy 228.531403 -135.00215) (xy 228.53916 -134.948204) (xy 228.554515 -134.895911) (xy 228.577156 -134.846336)
			(xy 228.606622 -134.800487) (xy 228.642314 -134.759299) (xy 228.683503 -134.72361) (xy 228.729353 -134.694146)
			(xy 228.77893 -134.671508) (xy 228.831223 -134.656156) (xy 228.88517 -134.648402) (xy 228.91242 -134.64794)
			(xy 229.77602 -134.64794) (xy 229.803274 -134.648331) (xy 229.857226 -134.656091) (xy 229.909525 -134.67145)
			(xy 229.959106 -134.694095) (xy 230.00496 -134.723566) (xy 230.046153 -134.759262) (xy 230.081846 -134.800456)
			(xy 230.111315 -134.846312) (xy 230.133957 -134.895894) (xy 230.149313 -134.948193) (xy 230.15707 -135.002146)
			(xy 230.15707 -135.056654) (xy 230.149313 -135.110607) (xy 230.145996 -135.121904) (xy 234.029504 -135.121904)
			(xy 234.029504 -134.258304) (xy 234.02999 -134.231035) (xy 234.037752 -134.177051) (xy 234.053117 -134.124721)
			(xy 234.075774 -134.075111) (xy 234.10526 -134.02923) (xy 234.140975 -133.988013) (xy 234.182192 -133.952298)
			(xy 234.228073 -133.922812) (xy 234.277683 -133.900155) (xy 234.330013 -133.88479) (xy 234.383997 -133.877028)
			(xy 234.438535 -133.877028) (xy 234.492519 -133.88479) (xy 234.544849 -133.900155) (xy 234.594459 -133.922812)
			(xy 234.64034 -133.952298) (xy 234.681557 -133.988013) (xy 234.717272 -134.02923) (xy 234.746758 -134.075111)
			(xy 234.769415 -134.124721) (xy 234.78478 -134.177051) (xy 234.792542 -134.231035) (xy 234.793028 -134.258304)
			(xy 234.793028 -134.768971) (xy 236.02439 -134.768971) (xy 236.02439 -134.714429) (xy 236.032152 -134.660443)
			(xy 236.047518 -134.608111) (xy 236.070174 -134.558498) (xy 236.09966 -134.512615) (xy 236.135376 -134.471394)
			(xy 236.176594 -134.435676) (xy 236.222475 -134.406186) (xy 236.272087 -134.383527) (xy 236.324418 -134.368158)
			(xy 236.378403 -134.360392) (xy 236.405674 -134.359904) (xy 237.178342 -134.359904) (xy 237.205607 -134.360461)
			(xy 237.259581 -134.368227) (xy 237.311901 -134.383595) (xy 237.361502 -134.406251) (xy 237.407373 -134.435736)
			(xy 237.448582 -134.471448) (xy 237.48429 -134.512661) (xy 237.513769 -134.558535) (xy 237.53642 -134.608138)
			(xy 237.551782 -134.66046) (xy 237.559542 -134.714435) (xy 237.559542 -134.768965) (xy 237.551782 -134.82294)
			(xy 237.53642 -134.875262) (xy 237.513769 -134.924865) (xy 237.48429 -134.970739) (xy 237.448582 -135.011952)
			(xy 237.407373 -135.047664) (xy 237.361502 -135.077149) (xy 237.311901 -135.099805) (xy 237.259581 -135.115173)
			(xy 237.205607 -135.122939) (xy 237.178342 -135.123428) (xy 236.405674 -135.123428) (xy 236.378403 -135.123008)
			(xy 236.324418 -135.115242) (xy 236.272087 -135.099873) (xy 236.222475 -135.077214) (xy 236.176594 -135.047724)
			(xy 236.135376 -135.012006) (xy 236.09966 -134.970785) (xy 236.070174 -134.924902) (xy 236.047518 -134.875289)
			(xy 236.032152 -134.822957) (xy 236.02439 -134.768971) (xy 234.793028 -134.768971) (xy 234.793028 -135.121904)
			(xy 234.792542 -135.149173) (xy 234.786383 -135.192008) (xy 238.645192 -135.192008) (xy 238.645192 -134.328408)
			(xy 238.645678 -134.301157) (xy 238.653434 -134.247209) (xy 238.668789 -134.194914) (xy 238.691431 -134.145337)
			(xy 238.720897 -134.099487) (xy 238.756588 -134.058296) (xy 238.797779 -134.022605) (xy 238.843629 -133.993139)
			(xy 238.893206 -133.970497) (xy 238.945501 -133.955142) (xy 238.999449 -133.947386) (xy 239.053951 -133.947386)
			(xy 239.107899 -133.955142) (xy 239.160194 -133.970497) (xy 239.209771 -133.993139) (xy 239.255621 -134.022605)
			(xy 239.271831 -134.036651) (xy 242.034062 -134.036651) (xy 242.034062 -133.982149) (xy 242.041817 -133.928203)
			(xy 242.057171 -133.875909) (xy 242.07981 -133.826333) (xy 242.109274 -133.780482) (xy 242.144963 -133.739291)
			(xy 242.18615 -133.703598) (xy 242.231997 -133.67413) (xy 242.281572 -133.651485) (xy 242.333864 -133.636126)
			(xy 242.387809 -133.628365) (xy 242.41506 -133.627876) (xy 243.27866 -133.627876) (xy 243.305914 -133.628369)
			(xy 243.359867 -133.636121) (xy 243.412167 -133.651473) (xy 243.46175 -133.674112) (xy 243.507606 -133.703577)
			(xy 243.548802 -133.73927) (xy 243.584499 -133.780462) (xy 243.613969 -133.826315) (xy 243.636613 -133.875895)
			(xy 243.651971 -133.928194) (xy 243.659729 -133.982146) (xy 243.659729 -134.036654) (xy 243.651971 -134.090606)
			(xy 243.636613 -134.142905) (xy 243.613969 -134.192485) (xy 243.584499 -134.238338) (xy 243.548802 -134.27953)
			(xy 243.507606 -134.315223) (xy 243.46175 -134.344688) (xy 243.412167 -134.367327) (xy 243.359867 -134.382679)
			(xy 243.305914 -134.390431) (xy 243.27866 -134.390892) (xy 242.41506 -134.390892) (xy 242.387809 -134.390435)
			(xy 242.333864 -134.382674) (xy 242.281572 -134.367315) (xy 242.231997 -134.34467) (xy 242.18615 -134.315202)
			(xy 242.144963 -134.279509) (xy 242.109274 -134.238318) (xy 242.07981 -134.192467) (xy 242.057171 -134.142891)
			(xy 242.041817 -134.090597) (xy 242.034062 -134.036651) (xy 239.271831 -134.036651) (xy 239.296812 -134.058296)
			(xy 239.332503 -134.099487) (xy 239.361969 -134.145337) (xy 239.384611 -134.194914) (xy 239.399966 -134.247209)
			(xy 239.407722 -134.301157) (xy 239.408208 -134.328408) (xy 239.408208 -135.192008) (xy 239.407722 -135.219259)
			(xy 239.399966 -135.273207) (xy 239.384611 -135.325502) (xy 239.361969 -135.375079) (xy 239.332503 -135.420929)
			(xy 239.296812 -135.46212) (xy 239.255621 -135.497811) (xy 239.250425 -135.50115) (xy 244.457203 -135.50115)
			(xy 244.457203 -135.44665) (xy 244.46496 -135.392704) (xy 244.480315 -135.340411) (xy 244.502956 -135.290836)
			(xy 244.532422 -135.244987) (xy 244.568114 -135.203799) (xy 244.609303 -135.16811) (xy 244.655153 -135.138646)
			(xy 244.70473 -135.116008) (xy 244.757023 -135.100656) (xy 244.81097 -135.092902) (xy 244.83822 -135.09244)
			(xy 245.70182 -135.09244) (xy 245.729074 -135.092831) (xy 245.783026 -135.100591) (xy 245.835325 -135.11595)
			(xy 245.884906 -135.138595) (xy 245.93076 -135.168066) (xy 245.971953 -135.203762) (xy 246.007646 -135.244956)
			(xy 246.037115 -135.290812) (xy 246.059757 -135.340394) (xy 246.075113 -135.392693) (xy 246.08287 -135.446646)
			(xy 246.08287 -135.501154) (xy 246.075113 -135.555107) (xy 246.059757 -135.607406) (xy 246.037115 -135.656988)
			(xy 246.007646 -135.702844) (xy 245.971953 -135.744038) (xy 245.93076 -135.779734) (xy 245.884906 -135.809205)
			(xy 245.835325 -135.83185) (xy 245.783026 -135.847209) (xy 245.729074 -135.854969) (xy 245.70182 -135.855456)
			(xy 244.83822 -135.855456) (xy 244.81097 -135.854898) (xy 244.757023 -135.847144) (xy 244.70473 -135.831792)
			(xy 244.655153 -135.809154) (xy 244.609303 -135.77969) (xy 244.568114 -135.744001) (xy 244.532422 -135.702813)
			(xy 244.502956 -135.656964) (xy 244.480315 -135.607389) (xy 244.46496 -135.555096) (xy 244.457203 -135.50115)
			(xy 239.250425 -135.50115) (xy 239.209771 -135.527277) (xy 239.160194 -135.549919) (xy 239.107899 -135.565274)
			(xy 239.053951 -135.57303) (xy 238.999449 -135.57303) (xy 238.945501 -135.565274) (xy 238.893206 -135.549919)
			(xy 238.843629 -135.527277) (xy 238.797779 -135.497811) (xy 238.756588 -135.46212) (xy 238.720897 -135.420929)
			(xy 238.691431 -135.375079) (xy 238.668789 -135.325502) (xy 238.653434 -135.273207) (xy 238.645678 -135.219259)
			(xy 238.645192 -135.192008) (xy 234.786383 -135.192008) (xy 234.78478 -135.203157) (xy 234.769415 -135.255487)
			(xy 234.746758 -135.305097) (xy 234.717272 -135.350978) (xy 234.681557 -135.392195) (xy 234.64034 -135.42791)
			(xy 234.594459 -135.457396) (xy 234.544849 -135.480053) (xy 234.492519 -135.495418) (xy 234.438535 -135.50318)
			(xy 234.383997 -135.50318) (xy 234.330013 -135.495418) (xy 234.277683 -135.480053) (xy 234.228073 -135.457396)
			(xy 234.182192 -135.42791) (xy 234.140975 -135.392195) (xy 234.10526 -135.350978) (xy 234.075774 -135.305097)
			(xy 234.053117 -135.255487) (xy 234.037752 -135.203157) (xy 234.02999 -135.149173) (xy 234.029504 -135.121904)
			(xy 230.145996 -135.121904) (xy 230.133957 -135.162906) (xy 230.111315 -135.212488) (xy 230.081846 -135.258344)
			(xy 230.046153 -135.299538) (xy 230.00496 -135.335234) (xy 229.959106 -135.364705) (xy 229.909525 -135.38735)
			(xy 229.857226 -135.402709) (xy 229.803274 -135.410469) (xy 229.77602 -135.410956) (xy 228.91242 -135.410956)
			(xy 228.88517 -135.410398) (xy 228.831223 -135.402644) (xy 228.77893 -135.387292) (xy 228.729353 -135.364654)
			(xy 228.683503 -135.33519) (xy 228.642314 -135.299501) (xy 228.606622 -135.258313) (xy 228.577156 -135.212464)
			(xy 228.554515 -135.162889) (xy 228.53916 -135.110596) (xy 228.531403 -135.05665) (xy 226.755856 -135.05665)
			(xy 226.783915 -135.100312) (xy 226.806557 -135.149894) (xy 226.821913 -135.202193) (xy 226.82967 -135.256146)
			(xy 226.82967 -135.310654) (xy 226.821913 -135.364607) (xy 226.806557 -135.416906) (xy 226.783915 -135.466488)
			(xy 226.754446 -135.512344) (xy 226.718753 -135.553538) (xy 226.67756 -135.589234) (xy 226.631706 -135.618705)
			(xy 226.582125 -135.64135) (xy 226.529826 -135.656709) (xy 226.475874 -135.664469) (xy 226.44862 -135.664956)
			(xy 225.58502 -135.664956) (xy 225.55777 -135.664398) (xy 225.503823 -135.656644) (xy 225.45153 -135.641292)
			(xy 225.401953 -135.618654) (xy 225.356103 -135.58919) (xy 225.314914 -135.553501) (xy 225.279222 -135.512313)
			(xy 225.249756 -135.466464) (xy 225.227115 -135.416889) (xy 225.21176 -135.364596) (xy 225.204003 -135.31065)
			(xy 2.509012 -135.31065) (xy 2.509012 -137.199664) (xy 337.46447 -137.199664) (xy 337.46447 -137.145136)
			(xy 337.47223 -137.091163) (xy 337.487591 -137.038843) (xy 337.510241 -136.989242) (xy 337.539719 -136.943369)
			(xy 337.575425 -136.902158) (xy 337.616632 -136.866447) (xy 337.662502 -136.836963) (xy 337.7121 -136.814307)
			(xy 337.764418 -136.79894) (xy 337.81839 -136.791173) (xy 337.845654 -136.790684) (xy 338.618322 -136.790684)
			(xy 338.645594 -136.79108) (xy 338.699581 -136.798845) (xy 338.751915 -136.814214) (xy 338.801528 -136.836874)
			(xy 338.847412 -136.866364) (xy 338.888632 -136.902084) (xy 338.924349 -136.943306) (xy 338.953836 -136.989191)
			(xy 338.976493 -137.038806) (xy 338.991859 -137.09114) (xy 338.999622 -137.145128) (xy 338.999622 -137.199672)
			(xy 338.991859 -137.25366) (xy 338.976493 -137.305994) (xy 338.953836 -137.355609) (xy 338.924349 -137.401494)
			(xy 338.888632 -137.442716) (xy 338.847412 -137.478436) (xy 338.801528 -137.507926) (xy 338.751915 -137.530586)
			(xy 338.699581 -137.545955) (xy 338.645594 -137.55372) (xy 338.618322 -137.554208) (xy 337.845654 -137.554208)
			(xy 337.81839 -137.553627) (xy 337.764418 -137.54586) (xy 337.7121 -137.530493) (xy 337.662502 -137.507837)
			(xy 337.616632 -137.478353) (xy 337.575425 -137.442642) (xy 337.539719 -137.401431) (xy 337.510241 -137.355558)
			(xy 337.487591 -137.305957) (xy 337.47223 -137.253637) (xy 337.46447 -137.199664) (xy 2.509012 -137.199664)
			(xy 2.509012 -137.622788) (xy 340.085172 -137.622788) (xy 340.085172 -136.759188) (xy 340.085658 -136.731937)
			(xy 340.093414 -136.677989) (xy 340.108769 -136.625694) (xy 340.131411 -136.576117) (xy 340.160877 -136.530267)
			(xy 340.196568 -136.489076) (xy 340.237759 -136.453385) (xy 340.283609 -136.423919) (xy 340.333186 -136.401277)
			(xy 340.385481 -136.385922) (xy 340.439429 -136.378166) (xy 340.493931 -136.378166) (xy 340.547879 -136.385922)
			(xy 340.600174 -136.401277) (xy 340.649751 -136.423919) (xy 340.695601 -136.453385) (xy 340.736792 -136.489076)
			(xy 340.772483 -136.530267) (xy 340.801949 -136.576117) (xy 340.824591 -136.625694) (xy 340.839946 -136.677989)
			(xy 340.847702 -136.731937) (xy 340.848188 -136.759188) (xy 340.848188 -137.622788) (xy 340.847702 -137.650039)
			(xy 340.839946 -137.703987) (xy 340.824591 -137.756282) (xy 340.801949 -137.805859) (xy 340.772483 -137.851709)
			(xy 340.736792 -137.8929) (xy 340.695601 -137.928591) (xy 340.649751 -137.958057) (xy 340.600174 -137.980699)
			(xy 340.547879 -137.996054) (xy 340.493931 -138.00381) (xy 340.439429 -138.00381) (xy 340.385481 -137.996054)
			(xy 340.333186 -137.980699) (xy 340.283609 -137.958057) (xy 340.237759 -137.928591) (xy 340.196568 -137.8929)
			(xy 340.160877 -137.851709) (xy 340.131411 -137.805859) (xy 340.108769 -137.756282) (xy 340.093414 -137.703987)
			(xy 340.085658 -137.650039) (xy 340.085172 -137.622788) (xy 2.509012 -137.622788) (xy 2.509012 -153.766012)
			(xy 24.445731 -153.766012) (xy 24.449724 -153.556271) (xy 24.4617 -153.346834) (xy 24.481641 -153.138005)
			(xy 24.509518 -152.930086) (xy 24.54529 -152.723379) (xy 24.588905 -152.518184) (xy 24.640301 -152.314799)
			(xy 24.699403 -152.113517) (xy 24.766125 -151.914631) (xy 24.84037 -151.71843) (xy 24.92203 -151.525198)
			(xy 25.010988 -151.335214) (xy 25.107115 -151.148755) (xy 25.21027 -150.966091) (xy 25.320305 -150.787486)
			(xy 25.437059 -150.6132) (xy 25.560364 -150.443485) (xy 25.690041 -150.278587) (xy 25.825902 -150.118746)
			(xy 25.967749 -149.964193) (xy 26.115378 -149.815153) (xy 26.268573 -149.67184) (xy 26.427114 -149.534464)
			(xy 26.590769 -149.403223) (xy 26.759303 -149.278308) (xy 26.932469 -149.1599) (xy 27.110019 -149.04817)
			(xy 27.291693 -148.94328) (xy 27.477228 -148.845383) (xy 27.666356 -148.754621) (xy 27.858803 -148.671124)
			(xy 28.054288 -148.595014) (xy 28.25253 -148.526402) (xy 28.45324 -148.465387) (xy 28.656127 -148.412058)
			(xy 28.860897 -148.366491) (xy 29.067254 -148.328752) (xy 29.274898 -148.298898) (xy 29.483528 -148.27697)
			(xy 29.692841 -148.263001) (xy 29.902535 -148.25701) (xy 30.112304 -148.259007) (xy 30.321846 -148.268989)
			(xy 30.530856 -148.286941) (xy 30.73903 -148.312837) (xy 30.946068 -148.346639) (xy 31.151669 -148.388299)
			(xy 31.355535 -148.437757) (xy 31.55737 -148.49494) (xy 31.756882 -148.559765) (xy 31.953781 -148.632139)
			(xy 32.147782 -148.711956) (xy 32.338604 -148.799102) (xy 32.52597 -148.893449) (xy 32.709608 -148.99486)
			(xy 32.889252 -149.10319) (xy 33.064642 -149.21828) (xy 33.235523 -149.339964) (xy 33.401647 -149.468065)
			(xy 33.562774 -149.602398) (xy 33.718671 -149.742767) (xy 33.86911 -149.88897) (xy 34.013874 -150.040794)
			(xy 34.152753 -150.19802) (xy 34.285546 -150.360419) (xy 34.41206 -150.527755) (xy 34.532112 -150.699787)
			(xy 34.645527 -150.876264) (xy 34.752141 -151.056932) (xy 34.8518 -151.241527) (xy 34.944359 -151.429782)
			(xy 35.029684 -151.621425) (xy 35.107651 -151.816177) (xy 35.178147 -152.013757) (xy 35.24107 -152.213876)
			(xy 35.296329 -152.416247) (xy 35.343843 -152.620574) (xy 35.383544 -152.826562) (xy 35.415374 -153.033913)
			(xy 35.439287 -153.242324) (xy 35.455248 -153.451495) (xy 35.463235 -153.661122) (xy 35.463734 -153.766012)
			(xy 35.463235 -153.870902) (xy 35.455248 -154.080529) (xy 35.44312 -154.239468) (xy 186.742832 -154.239468)
			(xy 186.742832 -153.375868) (xy 186.743318 -153.348617) (xy 186.751074 -153.294669) (xy 186.766429 -153.242374)
			(xy 186.789071 -153.192797) (xy 186.818537 -153.146947) (xy 186.854228 -153.105756) (xy 186.895419 -153.070065)
			(xy 186.941269 -153.040599) (xy 186.990846 -153.017957) (xy 187.043141 -153.002602) (xy 187.097089 -152.994846)
			(xy 187.151591 -152.994846) (xy 187.205539 -153.002602) (xy 187.257834 -153.017957) (xy 187.307411 -153.040599)
			(xy 187.353261 -153.070065) (xy 187.394452 -153.105756) (xy 187.430143 -153.146947) (xy 187.459609 -153.192797)
			(xy 187.482251 -153.242374) (xy 187.497606 -153.294669) (xy 187.505362 -153.348617) (xy 187.505848 -153.375868)
			(xy 187.505848 -153.774902) (xy 188.445657 -153.774902) (xy 188.44965 -153.565161) (xy 188.461626 -153.355724)
			(xy 188.481567 -153.146895) (xy 188.509444 -152.938976) (xy 188.545216 -152.732269) (xy 188.588831 -152.527074)
			(xy 188.640227 -152.323689) (xy 188.699329 -152.122407) (xy 188.766051 -151.923521) (xy 188.840296 -151.72732)
			(xy 188.921956 -151.534088) (xy 189.010914 -151.344104) (xy 189.107041 -151.157645) (xy 189.210196 -150.974981)
			(xy 189.320231 -150.796376) (xy 189.436985 -150.62209) (xy 189.56029 -150.452375) (xy 189.689967 -150.287477)
			(xy 189.825828 -150.127636) (xy 189.967675 -149.973083) (xy 190.115304 -149.824043) (xy 190.268499 -149.68073)
			(xy 190.42704 -149.543354) (xy 190.590695 -149.412113) (xy 190.759229 -149.287198) (xy 190.932395 -149.16879)
			(xy 191.109945 -149.05706) (xy 191.291619 -148.95217) (xy 191.477154 -148.854273) (xy 191.666282 -148.763511)
			(xy 191.858729 -148.680014) (xy 192.054214 -148.603904) (xy 192.252456 -148.535292) (xy 192.453166 -148.474277)
			(xy 192.656053 -148.420948) (xy 192.860823 -148.375381) (xy 193.06718 -148.337642) (xy 193.274824 -148.307788)
			(xy 193.483454 -148.28586) (xy 193.692767 -148.271891) (xy 193.902461 -148.2659) (xy 194.11223 -148.267897)
			(xy 194.321772 -148.277879) (xy 194.530782 -148.295831) (xy 194.738956 -148.321727) (xy 194.945994 -148.355529)
			(xy 195.151595 -148.397189) (xy 195.355461 -148.446647) (xy 195.557296 -148.50383) (xy 195.756808 -148.568655)
			(xy 195.953707 -148.641029) (xy 196.147708 -148.720846) (xy 196.33853 -148.807992) (xy 196.525896 -148.902339)
			(xy 196.709534 -149.00375) (xy 196.889178 -149.11208) (xy 197.064568 -149.22717) (xy 197.235449 -149.348854)
			(xy 197.401573 -149.476955) (xy 197.5627 -149.611288) (xy 197.718597 -149.751657) (xy 197.869036 -149.89786)
			(xy 198.0138 -150.049684) (xy 198.152679 -150.20691) (xy 198.285472 -150.369309) (xy 198.411986 -150.536645)
			(xy 198.532038 -150.708677) (xy 198.645453 -150.885154) (xy 198.752067 -151.065822) (xy 198.851726 -151.250417)
			(xy 198.944285 -151.438672) (xy 199.02961 -151.630315) (xy 199.107577 -151.825067) (xy 199.178073 -152.022647)
			(xy 199.240996 -152.222766) (xy 199.296255 -152.425137) (xy 199.343769 -152.629464) (xy 199.38347 -152.835452)
			(xy 199.4153 -153.042803) (xy 199.439213 -153.251214) (xy 199.455174 -153.460385) (xy 199.463161 -153.670012)
			(xy 199.463618 -153.766012) (xy 272.385799 -153.766012) (xy 272.389792 -153.556271) (xy 272.401768 -153.346834)
			(xy 272.421709 -153.138005) (xy 272.449586 -152.930086) (xy 272.485358 -152.723379) (xy 272.528973 -152.518184)
			(xy 272.580369 -152.314799) (xy 272.639471 -152.113517) (xy 272.706193 -151.914631) (xy 272.780438 -151.71843)
			(xy 272.862098 -151.525198) (xy 272.951056 -151.335214) (xy 273.047183 -151.148755) (xy 273.150338 -150.966091)
			(xy 273.260373 -150.787486) (xy 273.377127 -150.6132) (xy 273.500432 -150.443485) (xy 273.630109 -150.278587)
			(xy 273.76597 -150.118746) (xy 273.907817 -149.964193) (xy 274.055446 -149.815153) (xy 274.208641 -149.67184)
			(xy 274.367182 -149.534464) (xy 274.530837 -149.403223) (xy 274.699371 -149.278308) (xy 274.872537 -149.1599)
			(xy 275.050087 -149.04817) (xy 275.231761 -148.94328) (xy 275.417296 -148.845383) (xy 275.606424 -148.754621)
			(xy 275.798871 -148.671124) (xy 275.994356 -148.595014) (xy 276.192598 -148.526402) (xy 276.393308 -148.465387)
			(xy 276.596195 -148.412058) (xy 276.800965 -148.366491) (xy 277.007322 -148.328752) (xy 277.214966 -148.298898)
			(xy 277.423596 -148.27697) (xy 277.632909 -148.263001) (xy 277.842603 -148.25701) (xy 278.052372 -148.259007)
			(xy 278.261914 -148.268989) (xy 278.470924 -148.286941) (xy 278.679098 -148.312837) (xy 278.886136 -148.346639)
			(xy 279.091737 -148.388299) (xy 279.295603 -148.437757) (xy 279.497438 -148.49494) (xy 279.69695 -148.559765)
			(xy 279.893849 -148.632139) (xy 280.08785 -148.711956) (xy 280.278672 -148.799102) (xy 280.466038 -148.893449)
			(xy 280.649676 -148.99486) (xy 280.82932 -149.10319) (xy 281.00471 -149.21828) (xy 281.175591 -149.339964)
			(xy 281.341715 -149.468065) (xy 281.502842 -149.602398) (xy 281.658739 -149.742767) (xy 281.809178 -149.88897)
			(xy 281.953942 -150.040794) (xy 282.092821 -150.19802) (xy 282.225614 -150.360419) (xy 282.352128 -150.527755)
			(xy 282.47218 -150.699787) (xy 282.585595 -150.876264) (xy 282.692209 -151.056932) (xy 282.791868 -151.241527)
			(xy 282.884427 -151.429782) (xy 282.969752 -151.621425) (xy 283.047719 -151.816177) (xy 283.118215 -152.013757)
			(xy 283.181138 -152.213876) (xy 283.236397 -152.416247) (xy 283.283911 -152.620574) (xy 283.323612 -152.826562)
			(xy 283.355442 -153.033913) (xy 283.379355 -153.242324) (xy 283.395316 -153.451495) (xy 283.403303 -153.661122)
			(xy 283.403802 -153.766012) (xy 283.40376 -153.774902) (xy 436.385725 -153.774902) (xy 436.389718 -153.565161)
			(xy 436.401694 -153.355724) (xy 436.421635 -153.146895) (xy 436.449512 -152.938976) (xy 436.485284 -152.732269)
			(xy 436.528899 -152.527074) (xy 436.580295 -152.323689) (xy 436.639397 -152.122407) (xy 436.706119 -151.923521)
			(xy 436.780364 -151.72732) (xy 436.862024 -151.534088) (xy 436.950982 -151.344104) (xy 437.047109 -151.157645)
			(xy 437.150264 -150.974981) (xy 437.260299 -150.796376) (xy 437.377053 -150.62209) (xy 437.500358 -150.452375)
			(xy 437.630035 -150.287477) (xy 437.765896 -150.127636) (xy 437.907743 -149.973083) (xy 438.055372 -149.824043)
			(xy 438.208567 -149.68073) (xy 438.367108 -149.543354) (xy 438.530763 -149.412113) (xy 438.699297 -149.287198)
			(xy 438.872463 -149.16879) (xy 439.050013 -149.05706) (xy 439.231687 -148.95217) (xy 439.417222 -148.854273)
			(xy 439.60635 -148.763511) (xy 439.798797 -148.680014) (xy 439.994282 -148.603904) (xy 440.192524 -148.535292)
			(xy 440.393234 -148.474277) (xy 440.596121 -148.420948) (xy 440.800891 -148.375381) (xy 441.007248 -148.337642)
			(xy 441.214892 -148.307788) (xy 441.423522 -148.28586) (xy 441.632835 -148.271891) (xy 441.842529 -148.2659)
			(xy 442.052298 -148.267897) (xy 442.26184 -148.277879) (xy 442.47085 -148.295831) (xy 442.679024 -148.321727)
			(xy 442.886062 -148.355529) (xy 443.091663 -148.397189) (xy 443.295529 -148.446647) (xy 443.497364 -148.50383)
			(xy 443.696876 -148.568655) (xy 443.893775 -148.641029) (xy 444.087776 -148.720846) (xy 444.278598 -148.807992)
			(xy 444.465964 -148.902339) (xy 444.649602 -149.00375) (xy 444.829246 -149.11208) (xy 445.004636 -149.22717)
			(xy 445.175517 -149.348854) (xy 445.341641 -149.476955) (xy 445.502768 -149.611288) (xy 445.658665 -149.751657)
			(xy 445.809104 -149.89786) (xy 445.953868 -150.049684) (xy 446.092747 -150.20691) (xy 446.22554 -150.369309)
			(xy 446.352054 -150.536645) (xy 446.472106 -150.708677) (xy 446.585521 -150.885154) (xy 446.692135 -151.065822)
			(xy 446.791794 -151.250417) (xy 446.884353 -151.438672) (xy 446.969678 -151.630315) (xy 447.047645 -151.825067)
			(xy 447.118141 -152.022647) (xy 447.181064 -152.222766) (xy 447.236323 -152.425137) (xy 447.283837 -152.629464)
			(xy 447.323538 -152.835452) (xy 447.355368 -153.042803) (xy 447.379281 -153.251214) (xy 447.395242 -153.460385)
			(xy 447.403229 -153.670012) (xy 447.403728 -153.774902) (xy 447.403229 -153.879792) (xy 447.395242 -154.089419)
			(xy 447.379281 -154.29859) (xy 447.355368 -154.507001) (xy 447.323538 -154.714352) (xy 447.283837 -154.92034)
			(xy 447.236323 -155.124667) (xy 447.181064 -155.327038) (xy 447.118141 -155.527157) (xy 447.047645 -155.724737)
			(xy 446.969678 -155.919489) (xy 446.884353 -156.111132) (xy 446.791794 -156.299387) (xy 446.692135 -156.483982)
			(xy 446.585521 -156.66465) (xy 446.472106 -156.841127) (xy 446.352054 -157.013159) (xy 446.22554 -157.180495)
			(xy 446.092747 -157.342894) (xy 445.953868 -157.50012) (xy 445.809104 -157.651944) (xy 445.658665 -157.798147)
			(xy 445.502768 -157.938516) (xy 445.341641 -158.072849) (xy 445.175517 -158.20095) (xy 445.004636 -158.322634)
			(xy 444.829246 -158.437724) (xy 444.649602 -158.546054) (xy 444.465964 -158.647465) (xy 444.278598 -158.741812)
			(xy 444.087776 -158.828958) (xy 443.893775 -158.908775) (xy 443.696876 -158.981149) (xy 443.497364 -159.045974)
			(xy 443.295529 -159.103157) (xy 443.091663 -159.152615) (xy 442.886062 -159.194275) (xy 442.679024 -159.228077)
			(xy 442.47085 -159.253973) (xy 442.26184 -159.271925) (xy 442.052298 -159.281907) (xy 441.842529 -159.283904)
			(xy 441.632835 -159.277913) (xy 441.423522 -159.263944) (xy 441.214892 -159.242016) (xy 441.007248 -159.212162)
			(xy 440.800891 -159.174423) (xy 440.596121 -159.128856) (xy 440.393234 -159.075527) (xy 440.192524 -159.014512)
			(xy 439.994282 -158.9459) (xy 439.798797 -158.86979) (xy 439.60635 -158.786293) (xy 439.417222 -158.695531)
			(xy 439.231687 -158.597634) (xy 439.050013 -158.492744) (xy 438.872463 -158.381014) (xy 438.699297 -158.262606)
			(xy 438.530763 -158.137691) (xy 438.367108 -158.00645) (xy 438.208567 -157.869074) (xy 438.055372 -157.725761)
			(xy 437.907743 -157.576721) (xy 437.765896 -157.422168) (xy 437.630035 -157.262327) (xy 437.500358 -157.097429)
			(xy 437.377053 -156.927714) (xy 437.260299 -156.753428) (xy 437.150264 -156.574823) (xy 437.047109 -156.392159)
			(xy 436.950982 -156.2057) (xy 436.862024 -156.015716) (xy 436.780364 -155.822484) (xy 436.706119 -155.626283)
			(xy 436.639397 -155.427397) (xy 436.580295 -155.226115) (xy 436.528899 -155.02273) (xy 436.485284 -154.817535)
			(xy 436.449512 -154.610828) (xy 436.421635 -154.402909) (xy 436.401694 -154.19408) (xy 436.389718 -153.984643)
			(xy 436.385725 -153.774902) (xy 283.40376 -153.774902) (xy 283.403303 -153.870902) (xy 283.395316 -154.080529)
			(xy 283.379355 -154.2897) (xy 283.355442 -154.498111) (xy 283.323612 -154.705462) (xy 283.283911 -154.91145)
			(xy 283.236397 -155.115777) (xy 283.181138 -155.318148) (xy 283.118215 -155.518267) (xy 283.047719 -155.715847)
			(xy 282.969752 -155.910599) (xy 282.884427 -156.102242) (xy 282.791868 -156.290497) (xy 282.692209 -156.475092)
			(xy 282.585595 -156.65576) (xy 282.47218 -156.832237) (xy 282.352128 -157.004269) (xy 282.225614 -157.171605)
			(xy 282.092821 -157.334004) (xy 281.953942 -157.49123) (xy 281.809178 -157.643054) (xy 281.658739 -157.789257)
			(xy 281.502842 -157.929626) (xy 281.341715 -158.063959) (xy 281.175591 -158.19206) (xy 281.00471 -158.313744)
			(xy 280.82932 -158.428834) (xy 280.649676 -158.537164) (xy 280.466038 -158.638575) (xy 280.278672 -158.732922)
			(xy 280.08785 -158.820068) (xy 279.893849 -158.899885) (xy 279.69695 -158.972259) (xy 279.497438 -159.037084)
			(xy 279.295603 -159.094267) (xy 279.091737 -159.143725) (xy 278.886136 -159.185385) (xy 278.679098 -159.219187)
			(xy 278.470924 -159.245083) (xy 278.261914 -159.263035) (xy 278.052372 -159.273017) (xy 277.842603 -159.275014)
			(xy 277.632909 -159.269023) (xy 277.423596 -159.255054) (xy 277.214966 -159.233126) (xy 277.007322 -159.203272)
			(xy 276.800965 -159.165533) (xy 276.596195 -159.119966) (xy 276.393308 -159.066637) (xy 276.192598 -159.005622)
			(xy 275.994356 -158.93701) (xy 275.798871 -158.8609) (xy 275.606424 -158.777403) (xy 275.417296 -158.686641)
			(xy 275.231761 -158.588744) (xy 275.050087 -158.483854) (xy 274.872537 -158.372124) (xy 274.699371 -158.253716)
			(xy 274.530837 -158.128801) (xy 274.367182 -157.99756) (xy 274.208641 -157.860184) (xy 274.055446 -157.716871)
			(xy 273.907817 -157.567831) (xy 273.76597 -157.413278) (xy 273.630109 -157.253437) (xy 273.500432 -157.088539)
			(xy 273.377127 -156.918824) (xy 273.260373 -156.744538) (xy 273.150338 -156.565933) (xy 273.047183 -156.383269)
			(xy 272.951056 -156.19681) (xy 272.862098 -156.006826) (xy 272.780438 -155.813594) (xy 272.706193 -155.617393)
			(xy 272.639471 -155.418507) (xy 272.580369 -155.217225) (xy 272.528973 -155.01384) (xy 272.485358 -154.808645)
			(xy 272.449586 -154.601938) (xy 272.421709 -154.394019) (xy 272.401768 -154.18519) (xy 272.389792 -153.975753)
			(xy 272.385799 -153.766012) (xy 199.463618 -153.766012) (xy 199.46366 -153.774902) (xy 199.463161 -153.879792)
			(xy 199.455174 -154.089419) (xy 199.439213 -154.29859) (xy 199.4153 -154.507001) (xy 199.38347 -154.714352)
			(xy 199.343769 -154.92034) (xy 199.296255 -155.124667) (xy 199.240996 -155.327038) (xy 199.178073 -155.527157)
			(xy 199.107577 -155.724737) (xy 199.02961 -155.919489) (xy 198.944285 -156.111132) (xy 198.851726 -156.299387)
			(xy 198.752067 -156.483982) (xy 198.645453 -156.66465) (xy 198.532038 -156.841127) (xy 198.411986 -157.013159)
			(xy 198.285472 -157.180495) (xy 198.152679 -157.342894) (xy 198.0138 -157.50012) (xy 197.869036 -157.651944)
			(xy 197.718597 -157.798147) (xy 197.5627 -157.938516) (xy 197.401573 -158.072849) (xy 197.235449 -158.20095)
			(xy 197.064568 -158.322634) (xy 196.889178 -158.437724) (xy 196.709534 -158.546054) (xy 196.525896 -158.647465)
			(xy 196.33853 -158.741812) (xy 196.147708 -158.828958) (xy 195.953707 -158.908775) (xy 195.756808 -158.981149)
			(xy 195.557296 -159.045974) (xy 195.355461 -159.103157) (xy 195.151595 -159.152615) (xy 194.945994 -159.194275)
			(xy 194.738956 -159.228077) (xy 194.530782 -159.253973) (xy 194.321772 -159.271925) (xy 194.11223 -159.281907)
			(xy 193.902461 -159.283904) (xy 193.692767 -159.277913) (xy 193.483454 -159.263944) (xy 193.274824 -159.242016)
			(xy 193.06718 -159.212162) (xy 192.860823 -159.174423) (xy 192.656053 -159.128856) (xy 192.453166 -159.075527)
			(xy 192.252456 -159.014512) (xy 192.054214 -158.9459) (xy 191.858729 -158.86979) (xy 191.666282 -158.786293)
			(xy 191.477154 -158.695531) (xy 191.291619 -158.597634) (xy 191.109945 -158.492744) (xy 190.932395 -158.381014)
			(xy 190.759229 -158.262606) (xy 190.590695 -158.137691) (xy 190.42704 -158.00645) (xy 190.268499 -157.869074)
			(xy 190.115304 -157.725761) (xy 189.967675 -157.576721) (xy 189.825828 -157.422168) (xy 189.689967 -157.262327)
			(xy 189.56029 -157.097429) (xy 189.436985 -156.927714) (xy 189.320231 -156.753428) (xy 189.210196 -156.574823)
			(xy 189.107041 -156.392159) (xy 189.010914 -156.2057) (xy 188.921956 -156.015716) (xy 188.840296 -155.822484)
			(xy 188.766051 -155.626283) (xy 188.699329 -155.427397) (xy 188.640227 -155.226115) (xy 188.588831 -155.02273)
			(xy 188.545216 -154.817535) (xy 188.509444 -154.610828) (xy 188.481567 -154.402909) (xy 188.461626 -154.19408)
			(xy 188.44965 -153.984643) (xy 188.445657 -153.774902) (xy 187.505848 -153.774902) (xy 187.505848 -154.239468)
			(xy 187.505362 -154.266719) (xy 187.497606 -154.320667) (xy 187.482251 -154.372962) (xy 187.459609 -154.422539)
			(xy 187.430143 -154.468389) (xy 187.394452 -154.50958) (xy 187.353261 -154.545271) (xy 187.307411 -154.574737)
			(xy 187.257834 -154.597379) (xy 187.205539 -154.612734) (xy 187.151591 -154.62049) (xy 187.097089 -154.62049)
			(xy 187.043141 -154.612734) (xy 186.990846 -154.597379) (xy 186.941269 -154.574737) (xy 186.895419 -154.545271)
			(xy 186.854228 -154.50958) (xy 186.818537 -154.468389) (xy 186.789071 -154.422539) (xy 186.766429 -154.372962)
			(xy 186.751074 -154.320667) (xy 186.743318 -154.266719) (xy 186.742832 -154.239468) (xy 35.44312 -154.239468)
			(xy 35.439287 -154.2897) (xy 35.415374 -154.498111) (xy 35.383544 -154.705462) (xy 35.343843 -154.91145)
			(xy 35.296329 -155.115777) (xy 35.24107 -155.318148) (xy 35.178147 -155.518267) (xy 35.107651 -155.715847)
			(xy 35.029684 -155.910599) (xy 34.944359 -156.102242) (xy 34.8518 -156.290497) (xy 34.752141 -156.475092)
			(xy 34.645527 -156.65576) (xy 34.532112 -156.832237) (xy 34.41206 -157.004269) (xy 34.285546 -157.171605)
			(xy 34.152753 -157.334004) (xy 34.013874 -157.49123) (xy 33.86911 -157.643054) (xy 33.718671 -157.789257)
			(xy 33.562774 -157.929626) (xy 33.401647 -158.063959) (xy 33.235523 -158.19206) (xy 33.064642 -158.313744)
			(xy 32.889252 -158.428834) (xy 32.709608 -158.537164) (xy 32.52597 -158.638575) (xy 32.338604 -158.732922)
			(xy 32.147782 -158.820068) (xy 31.953781 -158.899885) (xy 31.756882 -158.972259) (xy 31.55737 -159.037084)
			(xy 31.355535 -159.094267) (xy 31.151669 -159.143725) (xy 30.946068 -159.185385) (xy 30.73903 -159.219187)
			(xy 30.530856 -159.245083) (xy 30.321846 -159.263035) (xy 30.112304 -159.273017) (xy 29.902535 -159.275014)
			(xy 29.692841 -159.269023) (xy 29.483528 -159.255054) (xy 29.274898 -159.233126) (xy 29.067254 -159.203272)
			(xy 28.860897 -159.165533) (xy 28.656127 -159.119966) (xy 28.45324 -159.066637) (xy 28.25253 -159.005622)
			(xy 28.054288 -158.93701) (xy 27.858803 -158.8609) (xy 27.666356 -158.777403) (xy 27.477228 -158.686641)
			(xy 27.291693 -158.588744) (xy 27.110019 -158.483854) (xy 26.932469 -158.372124) (xy 26.759303 -158.253716)
			(xy 26.590769 -158.128801) (xy 26.427114 -157.99756) (xy 26.268573 -157.860184) (xy 26.115378 -157.716871)
			(xy 25.967749 -157.567831) (xy 25.825902 -157.413278) (xy 25.690041 -157.253437) (xy 25.560364 -157.088539)
			(xy 25.437059 -156.918824) (xy 25.320305 -156.744538) (xy 25.21027 -156.565933) (xy 25.107115 -156.383269)
			(xy 25.010988 -156.19681) (xy 24.92203 -156.006826) (xy 24.84037 -155.813594) (xy 24.766125 -155.617393)
			(xy 24.699403 -155.418507) (xy 24.640301 -155.217225) (xy 24.588905 -155.01384) (xy 24.54529 -154.808645)
			(xy 24.509518 -154.601938) (xy 24.481641 -154.394019) (xy 24.4617 -154.18519) (xy 24.449724 -153.975753)
			(xy 24.445731 -153.766012) (xy 2.509012 -153.766012) (xy 2.509012 -160.911354) (xy 372.506163 -160.911354)
			(xy 372.506163 -160.856846) (xy 372.513921 -160.802893) (xy 372.529279 -160.750593) (xy 372.551924 -160.701011)
			(xy 372.581395 -160.655157) (xy 372.617092 -160.613964) (xy 372.658289 -160.578271) (xy 372.704146 -160.548805)
			(xy 372.75373 -160.526165) (xy 372.806032 -160.510813) (xy 372.859986 -160.503061) (xy 372.88724 -160.5026)
			(xy 373.75084 -160.5026) (xy 373.77809 -160.503073) (xy 373.832034 -160.510834) (xy 373.884326 -160.526193)
			(xy 373.933899 -160.548837) (xy 373.979745 -160.578305) (xy 374.020931 -160.613997) (xy 374.056619 -160.655187)
			(xy 374.086083 -160.701036) (xy 374.108721 -160.750612) (xy 374.124075 -160.802905) (xy 374.13183 -160.85685)
			(xy 374.13183 -160.91135) (xy 374.124075 -160.965295) (xy 374.108721 -161.017588) (xy 374.086083 -161.067164)
			(xy 374.056619 -161.113013) (xy 374.020931 -161.154203) (xy 373.979745 -161.189895) (xy 373.933899 -161.219363)
			(xy 373.884326 -161.242007) (xy 373.832034 -161.257366) (xy 373.77809 -161.265127) (xy 373.75084 -161.265616)
			(xy 372.88724 -161.265616) (xy 372.859986 -161.265139) (xy 372.806032 -161.257387) (xy 372.75373 -161.242035)
			(xy 372.704146 -161.219395) (xy 372.658289 -161.189929) (xy 372.617092 -161.154236) (xy 372.581395 -161.113043)
			(xy 372.551924 -161.067189) (xy 372.529279 -161.017607) (xy 372.513921 -160.965307) (xy 372.506163 -160.911354)
			(xy 2.509012 -160.911354) (xy 2.509012 -161.58445) (xy 296.753286 -161.58445) (xy 296.753286 -161.52995)
			(xy 296.761042 -161.476005) (xy 296.776395 -161.423713) (xy 296.799035 -161.374138) (xy 296.828498 -161.32829)
			(xy 296.864187 -161.287101) (xy 296.905374 -161.25141) (xy 296.951221 -161.221944) (xy 297.000795 -161.199302)
			(xy 297.053086 -161.183946) (xy 297.10703 -161.176187) (xy 297.13428 -161.1757) (xy 297.99788 -161.1757)
			(xy 298.025134 -161.176146) (xy 298.079089 -161.183901) (xy 298.13139 -161.199255) (xy 298.180974 -161.221897)
			(xy 298.22683 -161.251365) (xy 298.268026 -161.28706) (xy 298.303723 -161.328254) (xy 298.333193 -161.374109)
			(xy 298.355838 -161.423691) (xy 298.371195 -161.475992) (xy 298.378953 -161.529946) (xy 298.378953 -161.584454)
			(xy 298.371195 -161.638408) (xy 298.355838 -161.690709) (xy 298.333193 -161.740291) (xy 298.303723 -161.786146)
			(xy 298.268026 -161.82734) (xy 298.22683 -161.863035) (xy 298.180974 -161.892503) (xy 298.13139 -161.915145)
			(xy 298.079089 -161.930499) (xy 298.025134 -161.938254) (xy 297.99788 -161.938716) (xy 297.13428 -161.938716)
			(xy 297.10703 -161.938213) (xy 297.053086 -161.930454) (xy 297.000795 -161.915098) (xy 296.951221 -161.892456)
			(xy 296.905374 -161.86299) (xy 296.864187 -161.827299) (xy 296.828498 -161.78611) (xy 296.799035 -161.740262)
			(xy 296.776395 -161.690687) (xy 296.761042 -161.638395) (xy 296.753286 -161.58445) (xy 2.509012 -161.58445)
			(xy 2.509012 -162.128053) (xy 292.574946 -162.128053) (xy 292.574946 -162.073547) (xy 292.582702 -162.019597)
			(xy 292.598058 -161.967299) (xy 292.620699 -161.917719) (xy 292.650166 -161.871866) (xy 292.685859 -161.830673)
			(xy 292.72705 -161.794978) (xy 292.772902 -161.765509) (xy 292.822481 -161.742865) (xy 292.874777 -161.727507)
			(xy 292.928727 -161.719747) (xy 292.95598 -161.71926) (xy 293.81958 -161.71926) (xy 293.846832 -161.719786)
			(xy 293.90078 -161.72754) (xy 293.953076 -161.742893) (xy 294.002654 -161.765532) (xy 294.048506 -161.794997)
			(xy 294.089698 -161.830688) (xy 294.125391 -161.871878) (xy 294.154858 -161.917728) (xy 294.1775 -161.967305)
			(xy 294.192856 -162.0196) (xy 294.200613 -162.073549) (xy 294.200613 -162.128051) (xy 294.192856 -162.182)
			(xy 294.1775 -162.234295) (xy 294.154858 -162.283872) (xy 294.125391 -162.329722) (xy 294.089698 -162.370912)
			(xy 294.048506 -162.406603) (xy 294.002654 -162.436068) (xy 293.953076 -162.458707) (xy 293.90078 -162.47406)
			(xy 293.846832 -162.481814) (xy 293.81958 -162.482276) (xy 292.95598 -162.482276) (xy 292.928727 -162.481853)
			(xy 292.874777 -162.474093) (xy 292.822481 -162.458735) (xy 292.772902 -162.436091) (xy 292.72705 -162.406622)
			(xy 292.685859 -162.370927) (xy 292.650166 -162.329734) (xy 292.620699 -162.283881) (xy 292.598058 -162.234301)
			(xy 292.582702 -162.182003) (xy 292.574946 -162.128053) (xy 2.509012 -162.128053) (xy 2.509012 -163.123651)
			(xy 294.731403 -163.123651) (xy 294.731403 -163.069149) (xy 294.73916 -163.015201) (xy 294.754516 -162.962907)
			(xy 294.777159 -162.91333) (xy 294.806627 -162.867481) (xy 294.842321 -162.826292) (xy 294.883513 -162.790603)
			(xy 294.929365 -162.76114) (xy 294.978944 -162.738502) (xy 295.03124 -162.723152) (xy 295.085189 -162.7154)
			(xy 295.11244 -162.71494) (xy 295.97604 -162.71494) (xy 296.003293 -162.715333) (xy 296.057243 -162.723095)
			(xy 296.10954 -162.738455) (xy 296.159118 -162.761102) (xy 296.204969 -162.790573) (xy 296.24616 -162.826269)
			(xy 296.281851 -162.867463) (xy 296.311318 -162.913317) (xy 296.333959 -162.962898) (xy 296.349314 -163.015196)
			(xy 296.35707 -163.069147) (xy 296.35707 -163.110951) (xy 300.192403 -163.110951) (xy 300.192403 -163.056449)
			(xy 300.20016 -163.002501) (xy 300.215516 -162.950207) (xy 300.238159 -162.90063) (xy 300.267627 -162.854781)
			(xy 300.303321 -162.813592) (xy 300.344513 -162.777903) (xy 300.390365 -162.74844) (xy 300.439944 -162.725802)
			(xy 300.49224 -162.710452) (xy 300.546189 -162.7027) (xy 300.57344 -162.70224) (xy 301.43704 -162.70224)
			(xy 301.464293 -162.702633) (xy 301.518243 -162.710395) (xy 301.57054 -162.725755) (xy 301.620118 -162.748402)
			(xy 301.665969 -162.777873) (xy 301.70716 -162.813569) (xy 301.742851 -162.854763) (xy 301.772318 -162.900617)
			(xy 301.794959 -162.950198) (xy 301.810314 -163.002496) (xy 301.81807 -163.056447) (xy 301.81807 -163.110953)
			(xy 301.810314 -163.164904) (xy 301.794959 -163.217202) (xy 301.772318 -163.266783) (xy 301.742851 -163.312637)
			(xy 301.70716 -163.353831) (xy 301.665969 -163.389527) (xy 301.620118 -163.418998) (xy 301.57054 -163.441645)
			(xy 301.518243 -163.457005) (xy 301.464293 -163.464767) (xy 301.43704 -163.465256) (xy 300.57344 -163.465256)
			(xy 300.546189 -163.4647) (xy 300.49224 -163.456948) (xy 300.439944 -163.441598) (xy 300.390365 -163.41896)
			(xy 300.344513 -163.389497) (xy 300.303321 -163.353808) (xy 300.267627 -163.312619) (xy 300.238159 -163.26677)
			(xy 300.215516 -163.217193) (xy 300.20016 -163.164899) (xy 300.192403 -163.110951) (xy 296.35707 -163.110951)
			(xy 296.35707 -163.123653) (xy 296.349314 -163.177604) (xy 296.333959 -163.229902) (xy 296.311318 -163.279483)
			(xy 296.281851 -163.325337) (xy 296.24616 -163.366531) (xy 296.204969 -163.402227) (xy 296.159118 -163.431698)
			(xy 296.10954 -163.454345) (xy 296.057243 -163.469705) (xy 296.003293 -163.477467) (xy 295.97604 -163.477956)
			(xy 295.11244 -163.477956) (xy 295.085189 -163.4774) (xy 295.03124 -163.469648) (xy 294.978944 -163.454298)
			(xy 294.929365 -163.43166) (xy 294.883513 -163.402197) (xy 294.842321 -163.366508) (xy 294.806627 -163.325319)
			(xy 294.777159 -163.27947) (xy 294.754516 -163.229893) (xy 294.73916 -163.177599) (xy 294.731403 -163.123651)
			(xy 2.509012 -163.123651) (xy 2.509012 -167.565832) (xy 348.657164 -167.565832) (xy 348.657658 -167.532531)
			(xy 348.666337 -167.466499) (xy 348.683566 -167.402165) (xy 348.709048 -167.340632) (xy 348.742347 -167.282953)
			(xy 348.782893 -167.230117) (xy 348.829992 -167.183027) (xy 348.882836 -167.142492) (xy 348.911418 -167.125396)
			(xy 349.83547 -166.591742) (xy 349.864533 -166.575642) (xy 349.925937 -166.550271) (xy 349.990123 -166.533114)
			(xy 350.055996 -166.524463) (xy 350.089216 -166.523924) (xy 350.089724 -166.523924) (xy 350.120458 -166.524315)
			(xy 350.181477 -166.531727) (xy 350.241158 -166.54644) (xy 350.29863 -166.56824) (xy 350.353056 -166.596808)
			(xy 350.403641 -166.631729) (xy 350.449648 -166.672492) (xy 350.490406 -166.718503) (xy 350.525321 -166.769092)
			(xy 350.553883 -166.823521) (xy 350.57377 -166.875968) (xy 369.614196 -166.875968) (xy 369.614752 -166.84267)
			(xy 369.623426 -166.776641) (xy 369.640648 -166.71231) (xy 369.666122 -166.650779) (xy 369.699412 -166.593101)
			(xy 369.739949 -166.540263) (xy 369.787038 -166.493171) (xy 369.839873 -166.452631) (xy 369.86845 -166.435532)
			(xy 370.792502 -165.901878) (xy 370.82156 -165.885769) (xy 370.882966 -165.8604) (xy 370.947153 -165.843245)
			(xy 371.013028 -165.834597) (xy 371.046248 -165.83406) (xy 371.046756 -165.83406) (xy 371.077486 -165.834579)
			(xy 371.138498 -165.841982) (xy 371.198173 -165.856685) (xy 371.255641 -165.878475) (xy 371.310063 -165.907032)
			(xy 371.360647 -165.941941) (xy 371.406653 -165.982693) (xy 371.447412 -166.028694) (xy 371.482329 -166.079272)
			(xy 371.510894 -166.133689) (xy 371.532692 -166.191154) (xy 371.547404 -166.250827) (xy 371.554816 -166.311838)
			(xy 371.555264 -166.342568) (xy 371.554757 -166.375868) (xy 371.546077 -166.4419) (xy 371.52885 -166.506232)
			(xy 371.503369 -166.567765) (xy 371.470072 -166.625443) (xy 371.429528 -166.67828) (xy 371.382432 -166.72537)
			(xy 371.329591 -166.765907) (xy 371.30101 -166.783004) (xy 370.964111 -166.977568) (xy 373.398796 -166.977568)
			(xy 373.399226 -166.946836) (xy 373.406638 -166.885821) (xy 373.421351 -166.826144) (xy 373.443149 -166.768676)
			(xy 373.471715 -166.714254) (xy 373.506633 -166.663671) (xy 373.547392 -166.617667) (xy 373.5934 -166.57691)
			(xy 373.643984 -166.541996) (xy 373.698409 -166.513434) (xy 373.755879 -166.49164) (xy 373.815556 -166.476932)
			(xy 373.876572 -166.469524) (xy 373.907304 -166.46906) (xy 373.907812 -166.46906) (xy 373.941031 -166.469606)
			(xy 374.006903 -166.478264) (xy 374.071088 -166.495419) (xy 374.132496 -166.520778) (xy 374.161558 -166.536878)
			(xy 375.08561 -167.070532) (xy 375.114171 -167.087654) (xy 375.166997 -167.128201) (xy 375.214079 -167.175295)
			(xy 375.254613 -167.22813) (xy 375.287906 -167.285802) (xy 375.313388 -167.347326) (xy 375.330623 -167.411649)
			(xy 375.339318 -167.477672) (xy 375.339864 -167.510968) (xy 375.339432 -167.541701) (xy 375.332026 -167.60272)
			(xy 375.317319 -167.6624) (xy 375.295524 -167.719873) (xy 375.266961 -167.774299) (xy 375.232044 -167.824885)
			(xy 375.191284 -167.870893) (xy 375.145275 -167.911651) (xy 375.094689 -167.946567) (xy 375.040262 -167.975129)
			(xy 374.982789 -167.996923) (xy 374.923108 -168.011629) (xy 374.862089 -168.019033) (xy 374.831356 -168.019476)
			(xy 374.830848 -168.019476) (xy 374.797629 -168.018942) (xy 374.731757 -168.01028) (xy 374.667571 -167.993122)
			(xy 374.606164 -167.967759) (xy 374.577102 -167.951658) (xy 373.65305 -167.418004) (xy 373.624495 -167.400872)
			(xy 373.571672 -167.360325) (xy 373.524591 -167.313232) (xy 373.484057 -167.260398) (xy 373.450764 -167.202727)
			(xy 373.42528 -167.141205) (xy 373.408042 -167.076884) (xy 373.399344 -167.010863) (xy 373.398796 -166.977568)
			(xy 370.964111 -166.977568) (xy 370.376958 -167.316658) (xy 370.34791 -167.332786) (xy 370.2865 -167.35815)
			(xy 370.22231 -167.375299) (xy 370.156433 -167.383942) (xy 370.123212 -167.384476) (xy 370.122704 -167.384476)
			(xy 370.091971 -167.384059) (xy 370.030952 -167.37665) (xy 369.971272 -167.36194) (xy 369.9138 -167.340143)
			(xy 369.859375 -167.311577) (xy 369.808789 -167.276659) (xy 369.762782 -167.235898) (xy 369.722023 -167.189889)
			(xy 369.687108 -167.139301) (xy 369.658546 -167.084874) (xy 369.636752 -167.027401) (xy 369.622045 -166.96772)
			(xy 369.61464 -166.906701) (xy 369.614196 -166.875968) (xy 350.57377 -166.875968) (xy 350.575676 -166.880996)
			(xy 350.590383 -166.940678) (xy 350.597788 -167.001698) (xy 350.598232 -167.032432) (xy 350.597712 -167.065732)
			(xy 350.589036 -167.131763) (xy 350.571812 -167.196097) (xy 350.546334 -167.25763) (xy 350.513038 -167.315309)
			(xy 350.472496 -167.368145) (xy 350.4254 -167.415235) (xy 350.372559 -167.455772) (xy 350.343978 -167.472868)
			(xy 349.419926 -168.006522) (xy 349.390862 -168.02262) (xy 349.329459 -168.047992) (xy 349.265273 -168.06515)
			(xy 349.1994 -168.073802) (xy 349.16618 -168.07434) (xy 349.165672 -168.07434) (xy 349.134942 -168.07387)
			(xy 349.073929 -168.066459) (xy 349.014255 -168.051748) (xy 348.956789 -168.029953) (xy 348.902369 -168.001389)
			(xy 348.851788 -167.966475) (xy 348.805784 -167.925719) (xy 348.765027 -167.879715) (xy 348.730113 -167.829135)
			(xy 348.701549 -167.774715) (xy 348.679753 -167.717249) (xy 348.665041 -167.657575) (xy 348.65763 -167.596562)
			(xy 348.657164 -167.565832) (xy 2.509012 -167.565832) (xy 2.509012 -168.302432) (xy 352.441764 -168.302432)
			(xy 352.442268 -168.271702) (xy 352.449672 -168.210689) (xy 352.464377 -168.151013) (xy 352.486168 -168.093545)
			(xy 352.514727 -168.039122) (xy 352.549637 -167.988539) (xy 352.59039 -167.942533) (xy 352.636392 -167.901774)
			(xy 352.686971 -167.866858) (xy 352.74139 -167.838292) (xy 352.798856 -167.816495) (xy 352.85853 -167.801783)
			(xy 352.919542 -167.794371) (xy 352.950272 -167.793924) (xy 352.95078 -167.793924) (xy 352.983998 -167.794489)
			(xy 353.049869 -167.803142) (xy 353.114055 -167.820291) (xy 353.175463 -167.845645) (xy 353.204526 -167.861742)
			(xy 354.128578 -168.395396) (xy 354.157139 -168.412518) (xy 354.209962 -168.453067) (xy 354.257042 -168.500162)
			(xy 354.297574 -168.552998) (xy 354.330866 -168.61067) (xy 354.356349 -168.672193) (xy 354.373586 -168.736515)
			(xy 354.382284 -168.802536) (xy 354.382832 -168.835832) (xy 354.382374 -168.866563) (xy 354.374962 -168.927576)
			(xy 354.360251 -168.987251) (xy 354.338454 -169.044717) (xy 354.30989 -169.099138) (xy 354.274975 -169.149719)
			(xy 354.234218 -169.195723) (xy 354.188213 -169.23648) (xy 354.137631 -169.271394) (xy 354.08321 -169.299957)
			(xy 354.025743 -169.321753) (xy 353.966068 -169.336464) (xy 353.905055 -169.343875) (xy 353.874324 -169.34434)
			(xy 353.873816 -169.34434) (xy 353.840597 -169.343782) (xy 353.774726 -169.335127) (xy 353.710541 -169.317976)
			(xy 353.649132 -169.292621) (xy 353.62007 -169.276522) (xy 352.696018 -168.742868) (xy 352.667463 -168.725735)
			(xy 352.614637 -168.685191) (xy 352.567553 -168.638099) (xy 352.527018 -168.585266) (xy 352.493724 -168.527595)
			(xy 352.468241 -168.466072) (xy 352.451005 -168.40175) (xy 352.44231 -168.335728) (xy 352.441764 -168.302432)
			(xy 2.509012 -168.302432) (xy 2.509012 -170.613832) (xy 348.657164 -170.613832) (xy 348.657658 -170.580531)
			(xy 348.666337 -170.514499) (xy 348.683566 -170.450165) (xy 348.709048 -170.388632) (xy 348.742347 -170.330953)
			(xy 348.782893 -170.278117) (xy 348.829992 -170.231027) (xy 348.882836 -170.190492) (xy 348.911418 -170.173396)
			(xy 349.83547 -169.639742) (xy 349.864533 -169.623642) (xy 349.925937 -169.598271) (xy 349.990123 -169.581114)
			(xy 350.055996 -169.572463) (xy 350.089216 -169.571924) (xy 350.089724 -169.571924) (xy 350.120458 -169.572315)
			(xy 350.181477 -169.579727) (xy 350.241158 -169.59444) (xy 350.29863 -169.61624) (xy 350.353056 -169.644808)
			(xy 350.403641 -169.679729) (xy 350.449648 -169.720492) (xy 350.490406 -169.766503) (xy 350.525321 -169.817092)
			(xy 350.553883 -169.871521) (xy 350.57377 -169.923968) (xy 369.614196 -169.923968) (xy 369.614752 -169.89067)
			(xy 369.623426 -169.824641) (xy 369.640648 -169.76031) (xy 369.666122 -169.698779) (xy 369.699412 -169.641101)
			(xy 369.739949 -169.588263) (xy 369.787038 -169.541171) (xy 369.839873 -169.500631) (xy 369.86845 -169.483532)
			(xy 370.792502 -168.949878) (xy 370.82156 -168.933769) (xy 370.882966 -168.9084) (xy 370.947153 -168.891245)
			(xy 371.013028 -168.882597) (xy 371.046248 -168.88206) (xy 371.046756 -168.88206) (xy 371.077486 -168.882579)
			(xy 371.138498 -168.889982) (xy 371.198173 -168.904685) (xy 371.255641 -168.926475) (xy 371.310063 -168.955032)
			(xy 371.360647 -168.989941) (xy 371.406653 -169.030693) (xy 371.447412 -169.076694) (xy 371.482329 -169.127272)
			(xy 371.510894 -169.181689) (xy 371.532692 -169.239154) (xy 371.547404 -169.298827) (xy 371.554816 -169.359838)
			(xy 371.555264 -169.390568) (xy 371.554757 -169.423868) (xy 371.546077 -169.4899) (xy 371.52885 -169.554232)
			(xy 371.503369 -169.615765) (xy 371.470072 -169.673443) (xy 371.429528 -169.72628) (xy 371.382432 -169.77337)
			(xy 371.329591 -169.813907) (xy 371.30101 -169.831004) (xy 370.376958 -170.364658) (xy 370.34791 -170.380786)
			(xy 370.2865 -170.40615) (xy 370.22231 -170.423299) (xy 370.156433 -170.431942) (xy 370.123212 -170.432476)
			(xy 370.122704 -170.432476) (xy 370.091971 -170.432059) (xy 370.030952 -170.42465) (xy 369.971272 -170.40994)
			(xy 369.9138 -170.388143) (xy 369.859375 -170.359577) (xy 369.808789 -170.324659) (xy 369.762782 -170.283898)
			(xy 369.722023 -170.237889) (xy 369.687108 -170.187301) (xy 369.658546 -170.132874) (xy 369.636752 -170.075401)
			(xy 369.622045 -170.01572) (xy 369.61464 -169.954701) (xy 369.614196 -169.923968) (xy 350.57377 -169.923968)
			(xy 350.575676 -169.928996) (xy 350.590383 -169.988678) (xy 350.597788 -170.049698) (xy 350.598232 -170.080432)
			(xy 350.597712 -170.113732) (xy 350.589036 -170.179763) (xy 350.571812 -170.244097) (xy 350.546334 -170.30563)
			(xy 350.513038 -170.363309) (xy 350.472496 -170.416145) (xy 350.4254 -170.463235) (xy 350.372559 -170.503772)
			(xy 350.343978 -170.520868) (xy 350.10208 -170.660568) (xy 373.398796 -170.660568) (xy 373.399226 -170.629836)
			(xy 373.406638 -170.568821) (xy 373.421351 -170.509144) (xy 373.443149 -170.451676) (xy 373.471715 -170.397254)
			(xy 373.506633 -170.346671) (xy 373.547392 -170.300667) (xy 373.5934 -170.25991) (xy 373.643984 -170.224996)
			(xy 373.698409 -170.196434) (xy 373.755879 -170.17464) (xy 373.815556 -170.159932) (xy 373.876572 -170.152524)
			(xy 373.907304 -170.15206) (xy 373.907812 -170.15206) (xy 373.941031 -170.152606) (xy 374.006903 -170.161264)
			(xy 374.071088 -170.178419) (xy 374.132496 -170.203778) (xy 374.161558 -170.219878) (xy 375.08561 -170.753532)
			(xy 375.114171 -170.770654) (xy 375.166997 -170.811201) (xy 375.214079 -170.858295) (xy 375.254613 -170.91113)
			(xy 375.287906 -170.968802) (xy 375.313388 -171.030326) (xy 375.330623 -171.094649) (xy 375.339318 -171.160672)
			(xy 375.339864 -171.193968) (xy 375.339432 -171.224701) (xy 375.332026 -171.28572) (xy 375.317319 -171.3454)
			(xy 375.295524 -171.402873) (xy 375.266961 -171.457299) (xy 375.232044 -171.507885) (xy 375.191284 -171.553893)
			(xy 375.145275 -171.594651) (xy 375.094689 -171.629567) (xy 375.040262 -171.658129) (xy 374.982789 -171.679923)
			(xy 374.923108 -171.694629) (xy 374.862089 -171.702033) (xy 374.831356 -171.702476) (xy 374.830848 -171.702476)
			(xy 374.797629 -171.701942) (xy 374.731757 -171.69328) (xy 374.667571 -171.676122) (xy 374.606164 -171.650759)
			(xy 374.577102 -171.634658) (xy 373.65305 -171.101004) (xy 373.624495 -171.083872) (xy 373.571672 -171.043325)
			(xy 373.524591 -170.996232) (xy 373.484057 -170.943398) (xy 373.450764 -170.885727) (xy 373.42528 -170.824205)
			(xy 373.408042 -170.759884) (xy 373.399344 -170.693863) (xy 373.398796 -170.660568) (xy 350.10208 -170.660568)
			(xy 349.419926 -171.054522) (xy 349.390862 -171.07062) (xy 349.329459 -171.095992) (xy 349.265273 -171.11315)
			(xy 349.1994 -171.121802) (xy 349.16618 -171.12234) (xy 349.165672 -171.12234) (xy 349.134942 -171.12187)
			(xy 349.073929 -171.114459) (xy 349.014255 -171.099748) (xy 348.956789 -171.077953) (xy 348.902369 -171.049389)
			(xy 348.851788 -171.014475) (xy 348.805784 -170.973719) (xy 348.765027 -170.927715) (xy 348.730113 -170.877135)
			(xy 348.701549 -170.822715) (xy 348.679753 -170.765249) (xy 348.665041 -170.705575) (xy 348.65763 -170.644562)
			(xy 348.657164 -170.613832) (xy 2.509012 -170.613832) (xy 2.509012 -171.985432) (xy 352.441764 -171.985432)
			(xy 352.442268 -171.954702) (xy 352.449672 -171.893689) (xy 352.464377 -171.834013) (xy 352.486168 -171.776545)
			(xy 352.514727 -171.722122) (xy 352.549637 -171.671539) (xy 352.59039 -171.625533) (xy 352.636392 -171.584774)
			(xy 352.686971 -171.549858) (xy 352.74139 -171.521292) (xy 352.798856 -171.499495) (xy 352.85853 -171.484783)
			(xy 352.919542 -171.477371) (xy 352.950272 -171.476924) (xy 352.95078 -171.476924) (xy 352.983998 -171.477489)
			(xy 353.049869 -171.486142) (xy 353.114055 -171.503291) (xy 353.175463 -171.528645) (xy 353.204526 -171.544742)
			(xy 354.128578 -172.078396) (xy 354.157139 -172.095518) (xy 354.209962 -172.136067) (xy 354.257042 -172.183162)
			(xy 354.297574 -172.235998) (xy 354.330866 -172.29367) (xy 354.356349 -172.355193) (xy 354.373586 -172.419515)
			(xy 354.382284 -172.485536) (xy 354.382832 -172.518832) (xy 354.382374 -172.549563) (xy 354.374962 -172.610576)
			(xy 354.360251 -172.670251) (xy 354.338454 -172.727717) (xy 354.30989 -172.782138) (xy 354.274975 -172.832719)
			(xy 354.234218 -172.878723) (xy 354.188213 -172.91948) (xy 354.137631 -172.954394) (xy 354.104147 -172.971968)
			(xy 369.614196 -172.971968) (xy 369.614752 -172.93867) (xy 369.623426 -172.872641) (xy 369.640648 -172.80831)
			(xy 369.666122 -172.746779) (xy 369.699412 -172.689101) (xy 369.739949 -172.636263) (xy 369.787038 -172.589171)
			(xy 369.839873 -172.548631) (xy 369.86845 -172.531532) (xy 370.792502 -171.997878) (xy 370.82156 -171.981769)
			(xy 370.882966 -171.9564) (xy 370.947153 -171.939245) (xy 371.013028 -171.930597) (xy 371.046248 -171.93006)
			(xy 371.046756 -171.93006) (xy 371.077486 -171.930579) (xy 371.138498 -171.937982) (xy 371.198173 -171.952685)
			(xy 371.255641 -171.974475) (xy 371.310063 -172.003032) (xy 371.360647 -172.037941) (xy 371.406653 -172.078693)
			(xy 371.447412 -172.124694) (xy 371.482329 -172.175272) (xy 371.510894 -172.229689) (xy 371.532692 -172.287154)
			(xy 371.547404 -172.346827) (xy 371.554816 -172.407838) (xy 371.555264 -172.438568) (xy 371.554757 -172.471868)
			(xy 371.546077 -172.5379) (xy 371.52885 -172.602232) (xy 371.503369 -172.663765) (xy 371.470072 -172.721443)
			(xy 371.429528 -172.77428) (xy 371.382432 -172.82137) (xy 371.329591 -172.861907) (xy 371.30101 -172.879004)
			(xy 370.376958 -173.412658) (xy 370.34791 -173.428786) (xy 370.2865 -173.45415) (xy 370.22231 -173.471299)
			(xy 370.156433 -173.479942) (xy 370.123212 -173.480476) (xy 370.122704 -173.480476) (xy 370.091971 -173.480059)
			(xy 370.030952 -173.47265) (xy 369.971272 -173.45794) (xy 369.9138 -173.436143) (xy 369.859375 -173.407577)
			(xy 369.808789 -173.372659) (xy 369.762782 -173.331898) (xy 369.722023 -173.285889) (xy 369.687108 -173.235301)
			(xy 369.658546 -173.180874) (xy 369.636752 -173.123401) (xy 369.622045 -173.06372) (xy 369.61464 -173.002701)
			(xy 369.614196 -172.971968) (xy 354.104147 -172.971968) (xy 354.08321 -172.982957) (xy 354.025743 -173.004753)
			(xy 353.966068 -173.019464) (xy 353.905055 -173.026875) (xy 353.874324 -173.02734) (xy 353.873816 -173.02734)
			(xy 353.840597 -173.026782) (xy 353.774726 -173.018127) (xy 353.710541 -173.000976) (xy 353.649132 -172.975621)
			(xy 353.62007 -172.959522) (xy 352.696018 -172.425868) (xy 352.667463 -172.408735) (xy 352.614637 -172.368191)
			(xy 352.567553 -172.321099) (xy 352.527018 -172.268266) (xy 352.493724 -172.210595) (xy 352.468241 -172.149072)
			(xy 352.451005 -172.08475) (xy 352.44231 -172.018728) (xy 352.441764 -171.985432) (xy 2.509012 -171.985432)
			(xy 2.509012 -173.661832) (xy 348.657164 -173.661832) (xy 348.657658 -173.628531) (xy 348.666337 -173.562499)
			(xy 348.683566 -173.498165) (xy 348.709048 -173.436632) (xy 348.742347 -173.378953) (xy 348.782893 -173.326117)
			(xy 348.829992 -173.279027) (xy 348.882836 -173.238492) (xy 348.911418 -173.221396) (xy 349.83547 -172.687742)
			(xy 349.864533 -172.671642) (xy 349.925937 -172.646271) (xy 349.990123 -172.629114) (xy 350.055996 -172.620463)
			(xy 350.089216 -172.619924) (xy 350.089724 -172.619924) (xy 350.120458 -172.620315) (xy 350.181477 -172.627727)
			(xy 350.241158 -172.64244) (xy 350.29863 -172.66424) (xy 350.353056 -172.692808) (xy 350.403641 -172.727729)
			(xy 350.449648 -172.768492) (xy 350.490406 -172.814503) (xy 350.525321 -172.865092) (xy 350.553883 -172.919521)
			(xy 350.575676 -172.976996) (xy 350.590383 -173.036678) (xy 350.597788 -173.097698) (xy 350.598232 -173.128432)
			(xy 350.597712 -173.161732) (xy 350.589036 -173.227763) (xy 350.571812 -173.292097) (xy 350.546334 -173.35363)
			(xy 350.513038 -173.411309) (xy 350.472496 -173.464145) (xy 350.4254 -173.511235) (xy 350.372559 -173.551772)
			(xy 350.343978 -173.568868) (xy 349.419926 -174.102522) (xy 349.390862 -174.11862) (xy 349.329459 -174.143992)
			(xy 349.265273 -174.16115) (xy 349.1994 -174.169802) (xy 349.16618 -174.17034) (xy 349.165672 -174.17034)
			(xy 349.134942 -174.16987) (xy 349.073929 -174.162459) (xy 349.014255 -174.147748) (xy 348.956789 -174.125953)
			(xy 348.902369 -174.097389) (xy 348.851788 -174.062475) (xy 348.805784 -174.021719) (xy 348.765027 -173.975715)
			(xy 348.730113 -173.925135) (xy 348.701549 -173.870715) (xy 348.679753 -173.813249) (xy 348.665041 -173.753575)
			(xy 348.65763 -173.692562) (xy 348.657164 -173.661832) (xy 2.509012 -173.661832) (xy 2.509012 -174.343568)
			(xy 373.398796 -174.343568) (xy 373.399226 -174.312836) (xy 373.406638 -174.251821) (xy 373.421351 -174.192144)
			(xy 373.443149 -174.134676) (xy 373.471715 -174.080254) (xy 373.506633 -174.029671) (xy 373.547392 -173.983667)
			(xy 373.5934 -173.94291) (xy 373.643984 -173.907996) (xy 373.698409 -173.879434) (xy 373.755879 -173.85764)
			(xy 373.815556 -173.842932) (xy 373.876572 -173.835524) (xy 373.907304 -173.83506) (xy 373.907812 -173.83506)
			(xy 373.941031 -173.835606) (xy 374.006903 -173.844264) (xy 374.071088 -173.861419) (xy 374.132496 -173.886778)
			(xy 374.161558 -173.902878) (xy 375.08561 -174.436532) (xy 375.114171 -174.453654) (xy 375.166997 -174.494201)
			(xy 375.214079 -174.541295) (xy 375.254613 -174.59413) (xy 375.287906 -174.651802) (xy 375.313388 -174.713326)
			(xy 375.330623 -174.777649) (xy 375.339318 -174.843672) (xy 375.339864 -174.876968) (xy 375.339432 -174.907701)
			(xy 375.332026 -174.96872) (xy 375.317319 -175.0284) (xy 375.295524 -175.085873) (xy 375.266961 -175.140299)
			(xy 375.232044 -175.190885) (xy 375.191284 -175.236893) (xy 375.145275 -175.277651) (xy 375.094689 -175.312567)
			(xy 375.040262 -175.341129) (xy 374.982789 -175.362923) (xy 374.923108 -175.377629) (xy 374.862089 -175.385033)
			(xy 374.831356 -175.385476) (xy 374.830848 -175.385476) (xy 374.797629 -175.384942) (xy 374.731757 -175.37628)
			(xy 374.667571 -175.359122) (xy 374.606164 -175.333759) (xy 374.577102 -175.317658) (xy 373.65305 -174.784004)
			(xy 373.624495 -174.766872) (xy 373.571672 -174.726325) (xy 373.524591 -174.679232) (xy 373.484057 -174.626398)
			(xy 373.450764 -174.568727) (xy 373.42528 -174.507205) (xy 373.408042 -174.442884) (xy 373.399344 -174.376863)
			(xy 373.398796 -174.343568) (xy 2.509012 -174.343568) (xy 2.509012 -175.83404) (xy 23.37714 -175.83404)
			(xy 23.381229 -175.778158) (xy 23.393412 -175.723468) (xy 23.413428 -175.671134) (xy 23.440851 -175.622272)
			(xy 23.475096 -175.577924) (xy 23.515432 -175.539034) (xy 23.561002 -175.506432) (xy 23.610833 -175.480813)
			(xy 23.663863 -175.462721) (xy 23.718961 -175.452544) (xy 23.774955 -175.450498) (xy 23.83065 -175.456626)
			(xy 23.884859 -175.470798) (xy 23.936427 -175.492712) (xy 23.984255 -175.521901) (xy 24.027323 -175.557742)
			(xy 24.064713 -175.599472) (xy 24.095629 -175.646202) (xy 24.119412 -175.696935) (xy 24.135554 -175.750591)
			(xy 24.143713 -175.806025) (xy 24.144224 -175.83404) (xy 24.143713 -175.862055) (xy 24.135554 -175.917489)
			(xy 24.119412 -175.971145) (xy 24.095629 -176.021878) (xy 24.064713 -176.068608) (xy 24.027323 -176.110338)
			(xy 23.984255 -176.146179) (xy 23.936427 -176.175368) (xy 23.884859 -176.197282) (xy 23.83065 -176.211454)
			(xy 23.774955 -176.217582) (xy 23.718961 -176.215536) (xy 23.663863 -176.205359) (xy 23.610833 -176.187267)
			(xy 23.561002 -176.161648) (xy 23.515432 -176.129046) (xy 23.475096 -176.090156) (xy 23.440851 -176.045808)
			(xy 23.413428 -175.996946) (xy 23.393412 -175.944612) (xy 23.381229 -175.889922) (xy 23.37714 -175.83404)
			(xy 2.509012 -175.83404) (xy 2.509012 -176.709832) (xy 348.657164 -176.709832) (xy 348.657658 -176.676531)
			(xy 348.666337 -176.610499) (xy 348.683566 -176.546165) (xy 348.709048 -176.484632) (xy 348.742347 -176.426953)
			(xy 348.782893 -176.374117) (xy 348.829992 -176.327027) (xy 348.882836 -176.286492) (xy 348.911418 -176.269396)
			(xy 349.83547 -175.735742) (xy 349.864533 -175.719642) (xy 349.925937 -175.694271) (xy 349.990123 -175.677114)
			(xy 350.055996 -175.668463) (xy 350.089216 -175.667924) (xy 350.089724 -175.667924) (xy 350.120458 -175.668315)
			(xy 350.121421 -175.668432) (xy 352.441764 -175.668432) (xy 352.442268 -175.637702) (xy 352.449672 -175.576689)
			(xy 352.464377 -175.517013) (xy 352.486168 -175.459545) (xy 352.514727 -175.405122) (xy 352.549637 -175.354539)
			(xy 352.59039 -175.308533) (xy 352.636392 -175.267774) (xy 352.686971 -175.232858) (xy 352.74139 -175.204292)
			(xy 352.798856 -175.182495) (xy 352.85853 -175.167783) (xy 352.919542 -175.160371) (xy 352.950272 -175.159924)
			(xy 352.95078 -175.159924) (xy 352.983998 -175.160489) (xy 353.049869 -175.169142) (xy 353.114055 -175.186291)
			(xy 353.175463 -175.211645) (xy 353.204526 -175.227742) (xy 354.128578 -175.761396) (xy 354.157139 -175.778518)
			(xy 354.209962 -175.819067) (xy 354.257042 -175.866162) (xy 354.297574 -175.918998) (xy 354.330866 -175.97667)
			(xy 354.3488 -176.019968) (xy 369.614196 -176.019968) (xy 369.614752 -175.98667) (xy 369.623426 -175.920641)
			(xy 369.640648 -175.85631) (xy 369.666122 -175.794779) (xy 369.699412 -175.737101) (xy 369.739949 -175.684263)
			(xy 369.787038 -175.637171) (xy 369.839873 -175.596631) (xy 369.86845 -175.579532) (xy 370.792502 -175.045878)
			(xy 370.82156 -175.029769) (xy 370.882966 -175.0044) (xy 370.947153 -174.987245) (xy 371.013028 -174.978597)
			(xy 371.046248 -174.97806) (xy 371.046756 -174.97806) (xy 371.077486 -174.978579) (xy 371.138498 -174.985982)
			(xy 371.198173 -175.000685) (xy 371.255641 -175.022475) (xy 371.310063 -175.051032) (xy 371.360647 -175.085941)
			(xy 371.406653 -175.126693) (xy 371.447412 -175.172694) (xy 371.482329 -175.223272) (xy 371.510894 -175.277689)
			(xy 371.532692 -175.335154) (xy 371.547404 -175.394827) (xy 371.554816 -175.455838) (xy 371.555264 -175.486568)
			(xy 371.554757 -175.519868) (xy 371.546077 -175.5859) (xy 371.543089 -175.597058) (xy 434.095902 -175.597058)
			(xy 434.099991 -175.541176) (xy 434.112174 -175.486486) (xy 434.13219 -175.434152) (xy 434.159613 -175.38529)
			(xy 434.193858 -175.340942) (xy 434.234194 -175.302052) (xy 434.279764 -175.26945) (xy 434.329595 -175.243831)
			(xy 434.382625 -175.225739) (xy 434.437723 -175.215562) (xy 434.493717 -175.213516) (xy 434.549412 -175.219644)
			(xy 434.603621 -175.233816) (xy 434.655189 -175.25573) (xy 434.703017 -175.284919) (xy 434.746085 -175.32076)
			(xy 434.783475 -175.36249) (xy 434.814391 -175.40922) (xy 434.838174 -175.459953) (xy 434.854316 -175.513609)
			(xy 434.862475 -175.569043) (xy 434.862986 -175.597058) (xy 434.862475 -175.625073) (xy 434.854316 -175.680507)
			(xy 434.838174 -175.734163) (xy 434.814391 -175.784896) (xy 434.783475 -175.831626) (xy 434.746085 -175.873356)
			(xy 434.703017 -175.909197) (xy 434.655189 -175.938386) (xy 434.603621 -175.9603) (xy 434.549412 -175.974472)
			(xy 434.493717 -175.9806) (xy 434.437723 -175.978554) (xy 434.382625 -175.968377) (xy 434.329595 -175.950285)
			(xy 434.279764 -175.924666) (xy 434.234194 -175.892064) (xy 434.193858 -175.853174) (xy 434.159613 -175.808826)
			(xy 434.13219 -175.759964) (xy 434.112174 -175.70763) (xy 434.099991 -175.65294) (xy 434.095902 -175.597058)
			(xy 371.543089 -175.597058) (xy 371.52885 -175.650232) (xy 371.503369 -175.711765) (xy 371.470072 -175.769443)
			(xy 371.429528 -175.82228) (xy 371.382432 -175.86937) (xy 371.329591 -175.909907) (xy 371.30101 -175.927004)
			(xy 370.376958 -176.460658) (xy 370.34791 -176.476786) (xy 370.2865 -176.50215) (xy 370.22231 -176.519299)
			(xy 370.156433 -176.527942) (xy 370.123212 -176.528476) (xy 370.122704 -176.528476) (xy 370.091971 -176.528059)
			(xy 370.030952 -176.52065) (xy 369.971272 -176.50594) (xy 369.9138 -176.484143) (xy 369.859375 -176.455577)
			(xy 369.808789 -176.420659) (xy 369.762782 -176.379898) (xy 369.722023 -176.333889) (xy 369.687108 -176.283301)
			(xy 369.658546 -176.228874) (xy 369.636752 -176.171401) (xy 369.622045 -176.11172) (xy 369.61464 -176.050701)
			(xy 369.614196 -176.019968) (xy 354.3488 -176.019968) (xy 354.356349 -176.038193) (xy 354.373586 -176.102515)
			(xy 354.382284 -176.168536) (xy 354.382832 -176.201832) (xy 354.382374 -176.232563) (xy 354.374962 -176.293576)
			(xy 354.360251 -176.353251) (xy 354.338454 -176.410717) (xy 354.30989 -176.465138) (xy 354.274975 -176.515719)
			(xy 354.234218 -176.561723) (xy 354.188213 -176.60248) (xy 354.137631 -176.637394) (xy 354.08321 -176.665957)
			(xy 354.025743 -176.687753) (xy 353.966068 -176.702464) (xy 353.905055 -176.709875) (xy 353.874324 -176.71034)
			(xy 353.873816 -176.71034) (xy 353.840597 -176.709782) (xy 353.774726 -176.701127) (xy 353.710541 -176.683976)
			(xy 353.649132 -176.658621) (xy 353.62007 -176.642522) (xy 352.696018 -176.108868) (xy 352.667463 -176.091735)
			(xy 352.614637 -176.051191) (xy 352.567553 -176.004099) (xy 352.527018 -175.951266) (xy 352.493724 -175.893595)
			(xy 352.468241 -175.832072) (xy 352.451005 -175.76775) (xy 352.44231 -175.701728) (xy 352.441764 -175.668432)
			(xy 350.121421 -175.668432) (xy 350.181477 -175.675727) (xy 350.241158 -175.69044) (xy 350.29863 -175.71224)
			(xy 350.353056 -175.740808) (xy 350.403641 -175.775729) (xy 350.449648 -175.816492) (xy 350.490406 -175.862503)
			(xy 350.525321 -175.913092) (xy 350.553883 -175.967521) (xy 350.575676 -176.024996) (xy 350.590383 -176.084678)
			(xy 350.597788 -176.145698) (xy 350.598232 -176.176432) (xy 350.597712 -176.209732) (xy 350.589036 -176.275763)
			(xy 350.571812 -176.340097) (xy 350.546334 -176.40163) (xy 350.513038 -176.459309) (xy 350.472496 -176.512145)
			(xy 350.4254 -176.559235) (xy 350.372559 -176.599772) (xy 350.343978 -176.616868) (xy 349.419926 -177.150522)
			(xy 349.390862 -177.16662) (xy 349.329459 -177.191992) (xy 349.265273 -177.20915) (xy 349.1994 -177.217802)
			(xy 349.16618 -177.21834) (xy 349.165672 -177.21834) (xy 349.134942 -177.21787) (xy 349.073929 -177.210459)
			(xy 349.014255 -177.195748) (xy 348.956789 -177.173953) (xy 348.902369 -177.145389) (xy 348.851788 -177.110475)
			(xy 348.805784 -177.069719) (xy 348.765027 -177.023715) (xy 348.730113 -176.973135) (xy 348.701549 -176.918715)
			(xy 348.679753 -176.861249) (xy 348.665041 -176.801575) (xy 348.65763 -176.740562) (xy 348.657164 -176.709832)
			(xy 2.509012 -176.709832) (xy 2.509012 -179.757832) (xy 348.657164 -179.757832) (xy 348.657658 -179.724531)
			(xy 348.666337 -179.658499) (xy 348.683566 -179.594165) (xy 348.709048 -179.532632) (xy 348.742347 -179.474953)
			(xy 348.782893 -179.422117) (xy 348.829992 -179.375027) (xy 348.882836 -179.334492) (xy 348.911418 -179.317396)
			(xy 349.83547 -178.783742) (xy 349.864533 -178.767642) (xy 349.925937 -178.742271) (xy 349.990123 -178.725114)
			(xy 350.055996 -178.716463) (xy 350.089216 -178.715924) (xy 350.089724 -178.715924) (xy 350.120458 -178.716315)
			(xy 350.181477 -178.723727) (xy 350.241158 -178.73844) (xy 350.29863 -178.76024) (xy 350.353056 -178.788808)
			(xy 350.403641 -178.823729) (xy 350.449648 -178.864492) (xy 350.490406 -178.910503) (xy 350.525321 -178.961092)
			(xy 350.553883 -179.015521) (xy 350.575676 -179.072996) (xy 350.590383 -179.132678) (xy 350.597788 -179.193698)
			(xy 350.598232 -179.224432) (xy 350.597712 -179.257732) (xy 350.589036 -179.323763) (xy 350.581628 -179.351432)
			(xy 352.441764 -179.351432) (xy 352.442268 -179.320702) (xy 352.449672 -179.259689) (xy 352.464377 -179.200013)
			(xy 352.486168 -179.142545) (xy 352.514727 -179.088122) (xy 352.549637 -179.037539) (xy 352.59039 -178.991533)
			(xy 352.636392 -178.950774) (xy 352.686971 -178.915858) (xy 352.74139 -178.887292) (xy 352.798856 -178.865495)
			(xy 352.85853 -178.850783) (xy 352.919542 -178.843371) (xy 352.950272 -178.842924) (xy 352.95078 -178.842924)
			(xy 352.983998 -178.843489) (xy 353.049869 -178.852142) (xy 353.114055 -178.869291) (xy 353.175463 -178.894645)
			(xy 353.204526 -178.910742) (xy 353.476772 -179.067968) (xy 369.614196 -179.067968) (xy 369.614752 -179.03467)
			(xy 369.623426 -178.968641) (xy 369.640648 -178.90431) (xy 369.666122 -178.842779) (xy 369.699412 -178.785101)
			(xy 369.739949 -178.732263) (xy 369.787038 -178.685171) (xy 369.839873 -178.644631) (xy 369.86845 -178.627532)
			(xy 370.792502 -178.093878) (xy 370.82156 -178.077769) (xy 370.882966 -178.0524) (xy 370.947153 -178.035245)
			(xy 371.013028 -178.026597) (xy 371.046248 -178.02606) (xy 371.046756 -178.02606) (xy 371.076835 -178.026568)
			(xy 373.398796 -178.026568) (xy 373.399226 -177.995836) (xy 373.406638 -177.934821) (xy 373.421351 -177.875144)
			(xy 373.443149 -177.817676) (xy 373.471715 -177.763254) (xy 373.506633 -177.712671) (xy 373.547392 -177.666667)
			(xy 373.5934 -177.62591) (xy 373.643984 -177.590996) (xy 373.698409 -177.562434) (xy 373.755879 -177.54064)
			(xy 373.815556 -177.525932) (xy 373.876572 -177.518524) (xy 373.907304 -177.51806) (xy 373.907812 -177.51806)
			(xy 373.941031 -177.518606) (xy 374.006903 -177.527264) (xy 374.071088 -177.544419) (xy 374.132496 -177.569778)
			(xy 374.161558 -177.585878) (xy 375.08561 -178.119532) (xy 375.114171 -178.136654) (xy 375.166997 -178.177201)
			(xy 375.214079 -178.224295) (xy 375.254613 -178.27713) (xy 375.287906 -178.334802) (xy 375.313388 -178.396326)
			(xy 375.330623 -178.460649) (xy 375.339318 -178.526672) (xy 375.339864 -178.559968) (xy 375.339432 -178.590701)
			(xy 375.332026 -178.65172) (xy 375.317319 -178.7114) (xy 375.295524 -178.768873) (xy 375.266961 -178.823299)
			(xy 375.232044 -178.873885) (xy 375.191284 -178.919893) (xy 375.145275 -178.960651) (xy 375.094689 -178.995567)
			(xy 375.040262 -179.024129) (xy 374.982789 -179.045923) (xy 374.923108 -179.060629) (xy 374.862089 -179.068033)
			(xy 374.831356 -179.068476) (xy 374.830848 -179.068476) (xy 374.797629 -179.067942) (xy 374.731757 -179.05928)
			(xy 374.667571 -179.042122) (xy 374.606164 -179.016759) (xy 374.577102 -179.000658) (xy 373.65305 -178.467004)
			(xy 373.624495 -178.449872) (xy 373.571672 -178.409325) (xy 373.524591 -178.362232) (xy 373.484057 -178.309398)
			(xy 373.450764 -178.251727) (xy 373.42528 -178.190205) (xy 373.408042 -178.125884) (xy 373.399344 -178.059863)
			(xy 373.398796 -178.026568) (xy 371.076835 -178.026568) (xy 371.077486 -178.026579) (xy 371.138498 -178.033982)
			(xy 371.198173 -178.048685) (xy 371.255641 -178.070475) (xy 371.310063 -178.099032) (xy 371.360647 -178.133941)
			(xy 371.406653 -178.174693) (xy 371.447412 -178.220694) (xy 371.482329 -178.271272) (xy 371.510894 -178.325689)
			(xy 371.532692 -178.383154) (xy 371.547404 -178.442827) (xy 371.554816 -178.503838) (xy 371.555264 -178.534568)
			(xy 371.554757 -178.567868) (xy 371.546077 -178.6339) (xy 371.52885 -178.698232) (xy 371.503369 -178.759765)
			(xy 371.470072 -178.817443) (xy 371.429528 -178.87028) (xy 371.382432 -178.91737) (xy 371.329591 -178.957907)
			(xy 371.30101 -178.975004) (xy 370.376958 -179.508658) (xy 370.34791 -179.524786) (xy 370.2865 -179.55015)
			(xy 370.22231 -179.567299) (xy 370.156433 -179.575942) (xy 370.123212 -179.576476) (xy 370.122704 -179.576476)
			(xy 370.091971 -179.576059) (xy 370.030952 -179.56865) (xy 369.971272 -179.55394) (xy 369.9138 -179.532143)
			(xy 369.859375 -179.503577) (xy 369.808789 -179.468659) (xy 369.762782 -179.427898) (xy 369.722023 -179.381889)
			(xy 369.687108 -179.331301) (xy 369.658546 -179.276874) (xy 369.636752 -179.219401) (xy 369.622045 -179.15972)
			(xy 369.61464 -179.098701) (xy 369.614196 -179.067968) (xy 353.476772 -179.067968) (xy 354.128578 -179.444396)
			(xy 354.157139 -179.461518) (xy 354.209962 -179.502067) (xy 354.257042 -179.549162) (xy 354.297574 -179.601998)
			(xy 354.330866 -179.65967) (xy 354.356349 -179.721193) (xy 354.373586 -179.785515) (xy 354.382284 -179.851536)
			(xy 354.382832 -179.884832) (xy 354.382374 -179.915563) (xy 354.374962 -179.976576) (xy 354.360251 -180.036251)
			(xy 354.338454 -180.093717) (xy 354.30989 -180.148138) (xy 354.274975 -180.198719) (xy 354.234218 -180.244723)
			(xy 354.188213 -180.28548) (xy 354.137631 -180.320394) (xy 354.08321 -180.348957) (xy 354.025743 -180.370753)
			(xy 353.966068 -180.385464) (xy 353.905055 -180.392875) (xy 353.874324 -180.39334) (xy 353.873816 -180.39334)
			(xy 353.840597 -180.392782) (xy 353.774726 -180.384127) (xy 353.710541 -180.366976) (xy 353.649132 -180.341621)
			(xy 353.62007 -180.325522) (xy 352.696018 -179.791868) (xy 352.667463 -179.774735) (xy 352.614637 -179.734191)
			(xy 352.567553 -179.687099) (xy 352.527018 -179.634266) (xy 352.493724 -179.576595) (xy 352.468241 -179.515072)
			(xy 352.451005 -179.45075) (xy 352.44231 -179.384728) (xy 352.441764 -179.351432) (xy 350.581628 -179.351432)
			(xy 350.571812 -179.388097) (xy 350.546334 -179.44963) (xy 350.513038 -179.507309) (xy 350.472496 -179.560145)
			(xy 350.4254 -179.607235) (xy 350.372559 -179.647772) (xy 350.343978 -179.664868) (xy 349.419926 -180.198522)
			(xy 349.390862 -180.21462) (xy 349.329459 -180.239992) (xy 349.265273 -180.25715) (xy 349.1994 -180.265802)
			(xy 349.16618 -180.26634) (xy 349.165672 -180.26634) (xy 349.134942 -180.26587) (xy 349.073929 -180.258459)
			(xy 349.014255 -180.243748) (xy 348.956789 -180.221953) (xy 348.902369 -180.193389) (xy 348.851788 -180.158475)
			(xy 348.805784 -180.117719) (xy 348.765027 -180.071715) (xy 348.730113 -180.021135) (xy 348.701549 -179.966715)
			(xy 348.679753 -179.909249) (xy 348.665041 -179.849575) (xy 348.65763 -179.788562) (xy 348.657164 -179.757832)
			(xy 2.509012 -179.757832) (xy 2.509012 -182.805832) (xy 348.657164 -182.805832) (xy 348.657658 -182.772531)
			(xy 348.666337 -182.706499) (xy 348.683566 -182.642165) (xy 348.709048 -182.580632) (xy 348.742347 -182.522953)
			(xy 348.782893 -182.470117) (xy 348.829992 -182.423027) (xy 348.882836 -182.382492) (xy 348.911418 -182.365396)
			(xy 349.83547 -181.831742) (xy 349.864533 -181.815642) (xy 349.925937 -181.790271) (xy 349.990123 -181.773114)
			(xy 350.055996 -181.764463) (xy 350.089216 -181.763924) (xy 350.089724 -181.763924) (xy 350.120458 -181.764315)
			(xy 350.181477 -181.771727) (xy 350.241158 -181.78644) (xy 350.29863 -181.80824) (xy 350.353056 -181.836808)
			(xy 350.403641 -181.871729) (xy 350.449648 -181.912492) (xy 350.490406 -181.958503) (xy 350.525321 -182.009092)
			(xy 350.553883 -182.063521) (xy 350.57377 -182.115968) (xy 369.614196 -182.115968) (xy 369.614752 -182.08267)
			(xy 369.623426 -182.016641) (xy 369.640648 -181.95231) (xy 369.666122 -181.890779) (xy 369.699412 -181.833101)
			(xy 369.739949 -181.780263) (xy 369.787038 -181.733171) (xy 369.839873 -181.692631) (xy 369.86845 -181.675532)
			(xy 370.792502 -181.141878) (xy 370.82156 -181.125769) (xy 370.882966 -181.1004) (xy 370.947153 -181.083245)
			(xy 371.013028 -181.074597) (xy 371.046248 -181.07406) (xy 371.046756 -181.07406) (xy 371.077486 -181.074579)
			(xy 371.138498 -181.081982) (xy 371.198173 -181.096685) (xy 371.255641 -181.118475) (xy 371.310063 -181.147032)
			(xy 371.360647 -181.181941) (xy 371.406653 -181.222693) (xy 371.447412 -181.268694) (xy 371.482329 -181.319272)
			(xy 371.510894 -181.373689) (xy 371.532692 -181.431154) (xy 371.547404 -181.490827) (xy 371.554816 -181.551838)
			(xy 371.555264 -181.582568) (xy 371.554757 -181.615868) (xy 371.546077 -181.6819) (xy 371.538668 -181.709568)
			(xy 373.398796 -181.709568) (xy 373.399226 -181.678836) (xy 373.406638 -181.617821) (xy 373.421351 -181.558144)
			(xy 373.443149 -181.500676) (xy 373.471715 -181.446254) (xy 373.506633 -181.395671) (xy 373.547392 -181.349667)
			(xy 373.5934 -181.30891) (xy 373.643984 -181.273996) (xy 373.698409 -181.245434) (xy 373.755879 -181.22364)
			(xy 373.815556 -181.208932) (xy 373.876572 -181.201524) (xy 373.907304 -181.20106) (xy 373.907812 -181.20106)
			(xy 373.941031 -181.201606) (xy 374.006903 -181.210264) (xy 374.071088 -181.227419) (xy 374.132496 -181.252778)
			(xy 374.161558 -181.268878) (xy 375.08561 -181.802532) (xy 375.114171 -181.819654) (xy 375.166997 -181.860201)
			(xy 375.214079 -181.907295) (xy 375.254613 -181.96013) (xy 375.287906 -182.017802) (xy 375.313388 -182.079326)
			(xy 375.330623 -182.143649) (xy 375.339318 -182.209672) (xy 375.339864 -182.242968) (xy 375.339432 -182.273701)
			(xy 375.332026 -182.33472) (xy 375.317319 -182.3944) (xy 375.295524 -182.451873) (xy 375.266961 -182.506299)
			(xy 375.232044 -182.556885) (xy 375.191284 -182.602893) (xy 375.145275 -182.643651) (xy 375.094689 -182.678567)
			(xy 375.040262 -182.707129) (xy 374.982789 -182.728923) (xy 374.923108 -182.743629) (xy 374.862089 -182.751033)
			(xy 374.831356 -182.751476) (xy 374.830848 -182.751476) (xy 374.797629 -182.750942) (xy 374.731757 -182.74228)
			(xy 374.667571 -182.725122) (xy 374.606164 -182.699759) (xy 374.577102 -182.683658) (xy 373.65305 -182.150004)
			(xy 373.624495 -182.132872) (xy 373.571672 -182.092325) (xy 373.524591 -182.045232) (xy 373.484057 -181.992398)
			(xy 373.450764 -181.934727) (xy 373.42528 -181.873205) (xy 373.408042 -181.808884) (xy 373.399344 -181.742863)
			(xy 373.398796 -181.709568) (xy 371.538668 -181.709568) (xy 371.52885 -181.746232) (xy 371.503369 -181.807765)
			(xy 371.470072 -181.865443) (xy 371.429528 -181.91828) (xy 371.382432 -181.96537) (xy 371.329591 -182.005907)
			(xy 371.30101 -182.023004) (xy 370.376958 -182.556658) (xy 370.34791 -182.572786) (xy 370.2865 -182.59815)
			(xy 370.22231 -182.615299) (xy 370.156433 -182.623942) (xy 370.123212 -182.624476) (xy 370.122704 -182.624476)
			(xy 370.091971 -182.624059) (xy 370.030952 -182.61665) (xy 369.971272 -182.60194) (xy 369.9138 -182.580143)
			(xy 369.859375 -182.551577) (xy 369.808789 -182.516659) (xy 369.762782 -182.475898) (xy 369.722023 -182.429889)
			(xy 369.687108 -182.379301) (xy 369.658546 -182.324874) (xy 369.636752 -182.267401) (xy 369.622045 -182.20772)
			(xy 369.61464 -182.146701) (xy 369.614196 -182.115968) (xy 350.57377 -182.115968) (xy 350.575676 -182.120996)
			(xy 350.590383 -182.180678) (xy 350.597788 -182.241698) (xy 350.598232 -182.272432) (xy 350.597712 -182.305732)
			(xy 350.589036 -182.371763) (xy 350.571812 -182.436097) (xy 350.546334 -182.49763) (xy 350.513038 -182.555309)
			(xy 350.472496 -182.608145) (xy 350.4254 -182.655235) (xy 350.372559 -182.695772) (xy 350.343978 -182.712868)
			(xy 349.775297 -183.04129) (xy 352.441764 -183.04129) (xy 352.442192 -183.010552) (xy 352.449601 -182.949525)
			(xy 352.46431 -182.889835) (xy 352.486105 -182.832352) (xy 352.514667 -182.777914) (xy 352.549581 -182.727315)
			(xy 352.590338 -182.681292) (xy 352.636344 -182.640516) (xy 352.686928 -182.60558) (xy 352.741353 -182.576994)
			(xy 352.798826 -182.555175) (xy 352.85851 -182.540441) (xy 352.919534 -182.533005) (xy 352.950272 -182.532528)
			(xy 352.95078 -182.532528) (xy 352.984007 -182.533118) (xy 353.049889 -182.541823) (xy 353.114077 -182.559036)
			(xy 353.175475 -182.584464) (xy 353.204526 -182.6006) (xy 354.128578 -183.134254) (xy 354.157165 -183.151335)
			(xy 354.209988 -183.19189) (xy 354.257067 -183.238991) (xy 354.297597 -183.291832) (xy 354.330886 -183.34951)
			(xy 354.356365 -183.411039) (xy 354.373597 -183.475367) (xy 354.382288 -183.541392) (xy 354.382832 -183.57469)
			(xy 354.382389 -183.605428) (xy 354.374982 -183.666455) (xy 354.360275 -183.726145) (xy 354.338483 -183.783627)
			(xy 354.309922 -183.838065) (xy 354.275009 -183.888665) (xy 354.234254 -183.934688) (xy 354.188249 -183.975465)
			(xy 354.137666 -184.010401) (xy 354.083241 -184.038987) (xy 354.025768 -184.060806) (xy 353.966085 -184.07554)
			(xy 353.905061 -184.082975) (xy 353.874324 -184.083452) (xy 353.873816 -184.083452) (xy 353.840589 -184.082867)
			(xy 353.774706 -184.07416) (xy 353.710519 -184.056946) (xy 353.649121 -184.031517) (xy 353.62007 -184.01538)
			(xy 352.696018 -183.481726) (xy 352.667489 -183.464552) (xy 352.614663 -183.424014) (xy 352.567578 -183.376928)
			(xy 352.527041 -183.324101) (xy 352.493744 -183.266436) (xy 352.468257 -183.204918) (xy 352.451015 -183.140601)
			(xy 352.442314 -183.074584) (xy 352.441764 -183.04129) (xy 349.775297 -183.04129) (xy 349.419926 -183.246522)
			(xy 349.390862 -183.26262) (xy 349.329459 -183.287992) (xy 349.265273 -183.30515) (xy 349.1994 -183.313802)
			(xy 349.16618 -183.31434) (xy 349.165672 -183.31434) (xy 349.134942 -183.31387) (xy 349.073929 -183.306459)
			(xy 349.014255 -183.291748) (xy 348.956789 -183.269953) (xy 348.902369 -183.241389) (xy 348.851788 -183.206475)
			(xy 348.805784 -183.165719) (xy 348.765027 -183.119715) (xy 348.730113 -183.069135) (xy 348.701549 -183.014715)
			(xy 348.679753 -182.957249) (xy 348.665041 -182.897575) (xy 348.65763 -182.836562) (xy 348.657164 -182.805832)
			(xy 2.509012 -182.805832) (xy 2.509012 -185.011568) (xy 372.585996 -185.011568) (xy 372.586426 -184.980836)
			(xy 372.593838 -184.919821) (xy 372.608551 -184.860144) (xy 372.630349 -184.802676) (xy 372.658915 -184.748254)
			(xy 372.693833 -184.697671) (xy 372.734592 -184.651667) (xy 372.7806 -184.61091) (xy 372.831184 -184.575996)
			(xy 372.885609 -184.547434) (xy 372.943079 -184.52564) (xy 373.002756 -184.510932) (xy 373.063772 -184.503524)
			(xy 373.094504 -184.50306) (xy 373.095012 -184.50306) (xy 373.128231 -184.503606) (xy 373.194103 -184.512264)
			(xy 373.258288 -184.529419) (xy 373.319696 -184.554778) (xy 373.348758 -184.570878) (xy 374.27281 -185.104532)
			(xy 374.301371 -185.121654) (xy 374.354197 -185.162201) (xy 374.401279 -185.209295) (xy 374.441813 -185.26213)
			(xy 374.475106 -185.319802) (xy 374.500588 -185.381326) (xy 374.517823 -185.445649) (xy 374.526518 -185.511672)
			(xy 374.527064 -185.544968) (xy 374.526632 -185.575701) (xy 374.519226 -185.63672) (xy 374.504519 -185.6964)
			(xy 374.482724 -185.753873) (xy 374.454161 -185.808299) (xy 374.419244 -185.858885) (xy 374.378484 -185.904893)
			(xy 374.332475 -185.945651) (xy 374.281889 -185.980567) (xy 374.227462 -186.009129) (xy 374.169989 -186.030923)
			(xy 374.110308 -186.045629) (xy 374.049289 -186.053033) (xy 374.018556 -186.053476) (xy 374.018048 -186.053476)
			(xy 373.984829 -186.052942) (xy 373.918957 -186.04428) (xy 373.854771 -186.027122) (xy 373.793364 -186.001759)
			(xy 373.764302 -185.985658) (xy 372.84025 -185.452004) (xy 372.811695 -185.434872) (xy 372.758872 -185.394325)
			(xy 372.711791 -185.347232) (xy 372.671257 -185.294398) (xy 372.637964 -185.236727) (xy 372.61248 -185.175205)
			(xy 372.595242 -185.110884) (xy 372.586544 -185.044863) (xy 372.585996 -185.011568) (xy 2.509012 -185.011568)
			(xy 2.509012 -186.714892) (xy 351.367344 -186.714892) (xy 351.367848 -186.684163) (xy 351.375257 -186.623152)
			(xy 351.389965 -186.563479) (xy 351.411758 -186.506014) (xy 351.440318 -186.451595) (xy 351.475229 -186.401014)
			(xy 351.515982 -186.355011) (xy 351.561983 -186.314254) (xy 351.612561 -186.279339) (xy 351.666978 -186.250774)
			(xy 351.724441 -186.228977) (xy 351.784113 -186.214264) (xy 351.845123 -186.206851) (xy 351.875852 -186.206384)
			(xy 351.87636 -186.206384) (xy 351.90958 -186.206906) (xy 351.975453 -186.215571) (xy 352.039638 -186.232732)
			(xy 352.101045 -186.258098) (xy 352.130106 -186.274202) (xy 353.054158 -186.807856) (xy 353.082741 -186.824943)
			(xy 353.135565 -186.865496) (xy 353.182645 -186.912596) (xy 353.223176 -186.965436) (xy 353.256466 -187.023114)
			(xy 353.281945 -187.084642) (xy 353.299177 -187.148969) (xy 353.307868 -187.214995) (xy 353.308412 -187.248292)
			(xy 353.307955 -187.279024) (xy 353.300547 -187.340039) (xy 353.285839 -187.399717) (xy 353.264044 -187.457187)
			(xy 353.235482 -187.51161) (xy 353.200567 -187.562194) (xy 353.15981 -187.608201) (xy 353.113804 -187.648959)
			(xy 353.063221 -187.683875) (xy 353.008798 -187.712439) (xy 352.951329 -187.734235) (xy 352.891651 -187.748945)
			(xy 352.830636 -187.756354) (xy 352.799904 -187.7568) (xy 352.799396 -187.7568) (xy 352.766177 -187.756256)
			(xy 352.700305 -187.747598) (xy 352.636119 -187.730443) (xy 352.574711 -187.705083) (xy 352.54565 -187.688982)
			(xy 351.621598 -187.155328) (xy 351.593065 -187.13816) (xy 351.54024 -187.09762) (xy 351.493156 -187.050533)
			(xy 351.45262 -186.997705) (xy 351.419323 -186.940039) (xy 351.393837 -186.878521) (xy 351.376595 -186.814204)
			(xy 351.367894 -186.748186) (xy 351.367344 -186.714892) (xy 2.509012 -186.714892) (xy 2.509012 -206.024988)
			(xy 86.700624 -206.024988) (xy 86.704605 -205.891968) (xy 86.716534 -205.759423) (xy 86.736369 -205.62783)
			(xy 86.764038 -205.497658) (xy 86.799442 -205.369373) (xy 86.842455 -205.243436) (xy 86.892922 -205.120297)
			(xy 86.950663 -205.000396) (xy 87.015472 -204.884163) (xy 87.087116 -204.772013) (xy 87.165338 -204.664349)
			(xy 87.249859 -204.561556) (xy 87.340377 -204.464001) (xy 87.436566 -204.372035) (xy 87.538084 -204.285985)
			(xy 87.644565 -204.206161) (xy 87.75563 -204.132848) (xy 87.870881 -204.066308) (xy 87.989905 -204.006779)
			(xy 88.112276 -203.954475) (xy 88.237555 -203.909583) (xy 88.365296 -203.872264) (xy 88.495039 -203.842651)
			(xy 88.626321 -203.82085) (xy 88.758672 -203.80694) (xy 88.891618 -203.800969) (xy 89.024683 -203.80296)
			(xy 89.157391 -203.812905) (xy 89.289267 -203.830769) (xy 89.419838 -203.856487) (xy 89.548638 -203.889968)
			(xy 89.675204 -203.931092) (xy 89.799085 -203.979712) (xy 89.919836 -204.035653) (xy 90.037026 -204.098715)
			(xy 90.150235 -204.168673) (xy 90.259057 -204.245277) (xy 90.363103 -204.328251) (xy 90.462001 -204.417299)
			(xy 90.555396 -204.512102) (xy 90.642954 -204.61232) (xy 90.724363 -204.717596) (xy 90.799329 -204.827552)
			(xy 90.867586 -204.941794) (xy 90.928888 -205.059914) (xy 90.983017 -205.181489) (xy 91.029778 -205.306083)
			(xy 91.069004 -205.433251) (xy 91.100554 -205.562537) (xy 91.124317 -205.693478) (xy 91.140206 -205.825606)
			(xy 91.148164 -205.958448) (xy 91.148662 -206.024988) (xy 132.710692 -206.024988) (xy 132.714673 -205.891968)
			(xy 132.726602 -205.759423) (xy 132.746437 -205.62783) (xy 132.774106 -205.497658) (xy 132.80951 -205.369373)
			(xy 132.852523 -205.243436) (xy 132.90299 -205.120297) (xy 132.960731 -205.000396) (xy 133.02554 -204.884163)
			(xy 133.097184 -204.772013) (xy 133.175406 -204.664349) (xy 133.259927 -204.561556) (xy 133.350445 -204.464001)
			(xy 133.446634 -204.372035) (xy 133.548152 -204.285985) (xy 133.654633 -204.206161) (xy 133.765698 -204.132848)
			(xy 133.880949 -204.066308) (xy 133.999973 -204.006779) (xy 134.122344 -203.954475) (xy 134.247623 -203.909583)
			(xy 134.375364 -203.872264) (xy 134.505107 -203.842651) (xy 134.636389 -203.82085) (xy 134.76874 -203.80694)
			(xy 134.901686 -203.800969) (xy 135.034751 -203.80296) (xy 135.167459 -203.812905) (xy 135.299335 -203.830769)
			(xy 135.429906 -203.856487) (xy 135.558706 -203.889968) (xy 135.685272 -203.931092) (xy 135.809153 -203.979712)
			(xy 135.929904 -204.035653) (xy 136.047094 -204.098715) (xy 136.160303 -204.168673) (xy 136.269125 -204.245277)
			(xy 136.373171 -204.328251) (xy 136.472069 -204.417299) (xy 136.565464 -204.512102) (xy 136.653022 -204.61232)
			(xy 136.734431 -204.717596) (xy 136.809397 -204.827552) (xy 136.877654 -204.941794) (xy 136.938956 -205.059914)
			(xy 136.993085 -205.181489) (xy 137.039846 -205.306083) (xy 137.079072 -205.433251) (xy 137.110622 -205.562537)
			(xy 137.134385 -205.693478) (xy 137.150274 -205.825606) (xy 137.158232 -205.958448) (xy 137.15873 -206.024988)
			(xy 334.640692 -206.024988) (xy 334.644673 -205.891968) (xy 334.656602 -205.759423) (xy 334.676437 -205.62783)
			(xy 334.704106 -205.497658) (xy 334.73951 -205.369373) (xy 334.782523 -205.243436) (xy 334.83299 -205.120297)
			(xy 334.890731 -205.000396) (xy 334.95554 -204.884163) (xy 335.027184 -204.772013) (xy 335.105406 -204.664349)
			(xy 335.189927 -204.561556) (xy 335.280445 -204.464001) (xy 335.376634 -204.372035) (xy 335.478152 -204.285985)
			(xy 335.584633 -204.206161) (xy 335.695698 -204.132848) (xy 335.810949 -204.066308) (xy 335.929973 -204.006779)
			(xy 336.052344 -203.954475) (xy 336.177623 -203.909583) (xy 336.305364 -203.872264) (xy 336.435107 -203.842651)
			(xy 336.566389 -203.82085) (xy 336.69874 -203.80694) (xy 336.831686 -203.800969) (xy 336.964751 -203.80296)
			(xy 337.097459 -203.812905) (xy 337.229335 -203.830769) (xy 337.359906 -203.856487) (xy 337.488706 -203.889968)
			(xy 337.615272 -203.931092) (xy 337.739153 -203.979712) (xy 337.859904 -204.035653) (xy 337.977094 -204.098715)
			(xy 338.090303 -204.168673) (xy 338.199125 -204.245277) (xy 338.303171 -204.328251) (xy 338.402069 -204.417299)
			(xy 338.495464 -204.512102) (xy 338.583022 -204.61232) (xy 338.664431 -204.717596) (xy 338.739397 -204.827552)
			(xy 338.807654 -204.941794) (xy 338.868956 -205.059914) (xy 338.923085 -205.181489) (xy 338.969846 -205.306083)
			(xy 339.009072 -205.433251) (xy 339.040622 -205.562537) (xy 339.064385 -205.693478) (xy 339.080274 -205.825606)
			(xy 339.088232 -205.958448) (xy 339.08873 -206.024988) (xy 380.650506 -206.024988) (xy 380.654487 -205.891968)
			(xy 380.666416 -205.759423) (xy 380.686251 -205.62783) (xy 380.71392 -205.497658) (xy 380.749324 -205.369373)
			(xy 380.792337 -205.243436) (xy 380.842804 -205.120297) (xy 380.900545 -205.000396) (xy 380.965354 -204.884163)
			(xy 381.036998 -204.772013) (xy 381.11522 -204.664349) (xy 381.199741 -204.561556) (xy 381.290259 -204.464001)
			(xy 381.386448 -204.372035) (xy 381.487966 -204.285985) (xy 381.594447 -204.206161) (xy 381.705512 -204.132848)
			(xy 381.820763 -204.066308) (xy 381.939787 -204.006779) (xy 382.062158 -203.954475) (xy 382.187437 -203.909583)
			(xy 382.315178 -203.872264) (xy 382.444921 -203.842651) (xy 382.576203 -203.82085) (xy 382.708554 -203.80694)
			(xy 382.8415 -203.800969) (xy 382.974565 -203.80296) (xy 383.107273 -203.812905) (xy 383.239149 -203.830769)
			(xy 383.36972 -203.856487) (xy 383.49852 -203.889968) (xy 383.625086 -203.931092) (xy 383.748967 -203.979712)
			(xy 383.869718 -204.035653) (xy 383.986908 -204.098715) (xy 384.100117 -204.168673) (xy 384.208939 -204.245277)
			(xy 384.312985 -204.328251) (xy 384.411883 -204.417299) (xy 384.505278 -204.512102) (xy 384.592836 -204.61232)
			(xy 384.674245 -204.717596) (xy 384.749211 -204.827552) (xy 384.817468 -204.941794) (xy 384.87877 -205.059914)
			(xy 384.932899 -205.181489) (xy 384.97966 -205.306083) (xy 385.018886 -205.433251) (xy 385.050436 -205.562537)
			(xy 385.074199 -205.693478) (xy 385.090088 -205.825606) (xy 385.098046 -205.958448) (xy 385.098544 -206.024988)
			(xy 385.098046 -206.091528) (xy 385.090088 -206.22437) (xy 385.074199 -206.356498) (xy 385.050436 -206.487439)
			(xy 385.018886 -206.616725) (xy 384.97966 -206.743893) (xy 384.932899 -206.868487) (xy 384.87877 -206.990062)
			(xy 384.817468 -207.108182) (xy 384.749211 -207.222424) (xy 384.674245 -207.33238) (xy 384.592836 -207.437656)
			(xy 384.505278 -207.537874) (xy 384.411883 -207.632677) (xy 384.312985 -207.721725) (xy 384.208939 -207.804699)
			(xy 384.100117 -207.881303) (xy 383.986908 -207.951261) (xy 383.869718 -208.014323) (xy 383.748967 -208.070264)
			(xy 383.625086 -208.118884) (xy 383.49852 -208.160008) (xy 383.36972 -208.193489) (xy 383.239149 -208.219207)
			(xy 383.107273 -208.237071) (xy 382.974565 -208.247016) (xy 382.8415 -208.249007) (xy 382.708554 -208.243036)
			(xy 382.576203 -208.229126) (xy 382.444921 -208.207325) (xy 382.315178 -208.177712) (xy 382.187437 -208.140393)
			(xy 382.062158 -208.095501) (xy 381.939787 -208.043197) (xy 381.820763 -207.983668) (xy 381.705512 -207.917128)
			(xy 381.594447 -207.843815) (xy 381.487966 -207.763991) (xy 381.386448 -207.677941) (xy 381.290259 -207.585975)
			(xy 381.199741 -207.48842) (xy 381.11522 -207.385627) (xy 381.036998 -207.277963) (xy 380.965354 -207.165813)
			(xy 380.900545 -207.04958) (xy 380.842804 -206.929679) (xy 380.792337 -206.80654) (xy 380.749324 -206.680603)
			(xy 380.71392 -206.552318) (xy 380.686251 -206.422146) (xy 380.666416 -206.290553) (xy 380.654487 -206.158008)
			(xy 380.650506 -206.024988) (xy 339.08873 -206.024988) (xy 339.088232 -206.091528) (xy 339.080274 -206.22437)
			(xy 339.064385 -206.356498) (xy 339.040622 -206.487439) (xy 339.009072 -206.616725) (xy 338.969846 -206.743893)
			(xy 338.923085 -206.868487) (xy 338.868956 -206.990062) (xy 338.807654 -207.108182) (xy 338.739397 -207.222424)
			(xy 338.664431 -207.33238) (xy 338.583022 -207.437656) (xy 338.495464 -207.537874) (xy 338.402069 -207.632677)
			(xy 338.303171 -207.721725) (xy 338.199125 -207.804699) (xy 338.090303 -207.881303) (xy 337.977094 -207.951261)
			(xy 337.859904 -208.014323) (xy 337.739153 -208.070264) (xy 337.615272 -208.118884) (xy 337.488706 -208.160008)
			(xy 337.359906 -208.193489) (xy 337.229335 -208.219207) (xy 337.097459 -208.237071) (xy 336.964751 -208.247016)
			(xy 336.831686 -208.249007) (xy 336.69874 -208.243036) (xy 336.566389 -208.229126) (xy 336.435107 -208.207325)
			(xy 336.305364 -208.177712) (xy 336.177623 -208.140393) (xy 336.052344 -208.095501) (xy 335.929973 -208.043197)
			(xy 335.810949 -207.983668) (xy 335.695698 -207.917128) (xy 335.584633 -207.843815) (xy 335.478152 -207.763991)
			(xy 335.376634 -207.677941) (xy 335.280445 -207.585975) (xy 335.189927 -207.48842) (xy 335.105406 -207.385627)
			(xy 335.027184 -207.277963) (xy 334.95554 -207.165813) (xy 334.890731 -207.04958) (xy 334.83299 -206.929679)
			(xy 334.782523 -206.80654) (xy 334.73951 -206.680603) (xy 334.704106 -206.552318) (xy 334.676437 -206.422146)
			(xy 334.656602 -206.290553) (xy 334.644673 -206.158008) (xy 334.640692 -206.024988) (xy 137.15873 -206.024988)
			(xy 137.158232 -206.091528) (xy 137.150274 -206.22437) (xy 137.134385 -206.356498) (xy 137.110622 -206.487439)
			(xy 137.079072 -206.616725) (xy 137.039846 -206.743893) (xy 136.993085 -206.868487) (xy 136.938956 -206.990062)
			(xy 136.877654 -207.108182) (xy 136.809397 -207.222424) (xy 136.734431 -207.33238) (xy 136.653022 -207.437656)
			(xy 136.565464 -207.537874) (xy 136.472069 -207.632677) (xy 136.373171 -207.721725) (xy 136.269125 -207.804699)
			(xy 136.160303 -207.881303) (xy 136.047094 -207.951261) (xy 135.929904 -208.014323) (xy 135.809153 -208.070264)
			(xy 135.685272 -208.118884) (xy 135.558706 -208.160008) (xy 135.429906 -208.193489) (xy 135.299335 -208.219207)
			(xy 135.167459 -208.237071) (xy 135.034751 -208.247016) (xy 134.901686 -208.249007) (xy 134.76874 -208.243036)
			(xy 134.636389 -208.229126) (xy 134.505107 -208.207325) (xy 134.375364 -208.177712) (xy 134.247623 -208.140393)
			(xy 134.122344 -208.095501) (xy 133.999973 -208.043197) (xy 133.880949 -207.983668) (xy 133.765698 -207.917128)
			(xy 133.654633 -207.843815) (xy 133.548152 -207.763991) (xy 133.446634 -207.677941) (xy 133.350445 -207.585975)
			(xy 133.259927 -207.48842) (xy 133.175406 -207.385627) (xy 133.097184 -207.277963) (xy 133.02554 -207.165813)
			(xy 132.960731 -207.04958) (xy 132.90299 -206.929679) (xy 132.852523 -206.80654) (xy 132.80951 -206.680603)
			(xy 132.774106 -206.552318) (xy 132.746437 -206.422146) (xy 132.726602 -206.290553) (xy 132.714673 -206.158008)
			(xy 132.710692 -206.024988) (xy 91.148662 -206.024988) (xy 91.148164 -206.091528) (xy 91.140206 -206.22437)
			(xy 91.124317 -206.356498) (xy 91.100554 -206.487439) (xy 91.069004 -206.616725) (xy 91.029778 -206.743893)
			(xy 90.983017 -206.868487) (xy 90.928888 -206.990062) (xy 90.867586 -207.108182) (xy 90.799329 -207.222424)
			(xy 90.724363 -207.33238) (xy 90.642954 -207.437656) (xy 90.555396 -207.537874) (xy 90.462001 -207.632677)
			(xy 90.363103 -207.721725) (xy 90.259057 -207.804699) (xy 90.150235 -207.881303) (xy 90.037026 -207.951261)
			(xy 89.919836 -208.014323) (xy 89.799085 -208.070264) (xy 89.675204 -208.118884) (xy 89.548638 -208.160008)
			(xy 89.419838 -208.193489) (xy 89.289267 -208.219207) (xy 89.157391 -208.237071) (xy 89.024683 -208.247016)
			(xy 88.891618 -208.249007) (xy 88.758672 -208.243036) (xy 88.626321 -208.229126) (xy 88.495039 -208.207325)
			(xy 88.365296 -208.177712) (xy 88.237555 -208.140393) (xy 88.112276 -208.095501) (xy 87.989905 -208.043197)
			(xy 87.870881 -207.983668) (xy 87.75563 -207.917128) (xy 87.644565 -207.843815) (xy 87.538084 -207.763991)
			(xy 87.436566 -207.677941) (xy 87.340377 -207.585975) (xy 87.249859 -207.48842) (xy 87.165338 -207.385627)
			(xy 87.087116 -207.277963) (xy 87.015472 -207.165813) (xy 86.950663 -207.04958) (xy 86.892922 -206.929679)
			(xy 86.842455 -206.80654) (xy 86.799442 -206.680603) (xy 86.764038 -206.552318) (xy 86.736369 -206.422146)
			(xy 86.716534 -206.290553) (xy 86.704605 -206.158008) (xy 86.700624 -206.024988) (xy 2.509012 -206.024988)
			(xy 2.509012 -213.732618) (xy 90.165428 -213.732618) (xy 90.165936 -213.706731) (xy 90.174035 -213.655593)
			(xy 90.190034 -213.606353) (xy 90.21354 -213.560221) (xy 90.243972 -213.518334) (xy 90.280582 -213.481724)
			(xy 90.322469 -213.451292) (xy 90.368601 -213.427786) (xy 90.417841 -213.411787) (xy 90.468979 -213.403688)
			(xy 90.520753 -213.403688) (xy 90.571891 -213.411787) (xy 90.621131 -213.427786) (xy 90.667263 -213.451292)
			(xy 90.70915 -213.481724) (xy 90.74576 -213.518334) (xy 90.776192 -213.560221) (xy 90.799698 -213.606353)
			(xy 90.815697 -213.655593) (xy 90.823796 -213.706731) (xy 90.824304 -213.732618) (xy 92.045028 -213.732618)
			(xy 92.045536 -213.706731) (xy 92.053635 -213.655593) (xy 92.069634 -213.606353) (xy 92.09314 -213.560221)
			(xy 92.123572 -213.518334) (xy 92.160182 -213.481724) (xy 92.202069 -213.451292) (xy 92.248201 -213.427786)
			(xy 92.297441 -213.411787) (xy 92.348579 -213.403688) (xy 92.400353 -213.403688) (xy 92.451491 -213.411787)
			(xy 92.500731 -213.427786) (xy 92.546863 -213.451292) (xy 92.58875 -213.481724) (xy 92.62536 -213.518334)
			(xy 92.655792 -213.560221) (xy 92.679298 -213.606353) (xy 92.695297 -213.655593) (xy 92.703396 -213.706731)
			(xy 92.703904 -213.732618) (xy 93.924628 -213.732618) (xy 93.925136 -213.706731) (xy 93.933235 -213.655593)
			(xy 93.949234 -213.606353) (xy 93.97274 -213.560221) (xy 94.003172 -213.518334) (xy 94.039782 -213.481724)
			(xy 94.081669 -213.451292) (xy 94.127801 -213.427786) (xy 94.177041 -213.411787) (xy 94.228179 -213.403688)
			(xy 94.279953 -213.403688) (xy 94.331091 -213.411787) (xy 94.380331 -213.427786) (xy 94.426463 -213.451292)
			(xy 94.46835 -213.481724) (xy 94.50496 -213.518334) (xy 94.535392 -213.560221) (xy 94.558898 -213.606353)
			(xy 94.574897 -213.655593) (xy 94.582996 -213.706731) (xy 94.583504 -213.732618) (xy 95.804228 -213.732618)
			(xy 95.804736 -213.706731) (xy 95.812835 -213.655593) (xy 95.828834 -213.606353) (xy 95.85234 -213.560221)
			(xy 95.882772 -213.518334) (xy 95.919382 -213.481724) (xy 95.961269 -213.451292) (xy 96.007401 -213.427786)
			(xy 96.056641 -213.411787) (xy 96.107779 -213.403688) (xy 96.159553 -213.403688) (xy 96.210691 -213.411787)
			(xy 96.259931 -213.427786) (xy 96.306063 -213.451292) (xy 96.34795 -213.481724) (xy 96.38456 -213.518334)
			(xy 96.414992 -213.560221) (xy 96.438498 -213.606353) (xy 96.454497 -213.655593) (xy 96.462596 -213.706731)
			(xy 96.463104 -213.732618) (xy 97.683828 -213.732618) (xy 97.684336 -213.706731) (xy 97.692435 -213.655593)
			(xy 97.708434 -213.606353) (xy 97.73194 -213.560221) (xy 97.762372 -213.518334) (xy 97.798982 -213.481724)
			(xy 97.840869 -213.451292) (xy 97.887001 -213.427786) (xy 97.936241 -213.411787) (xy 97.987379 -213.403688)
			(xy 98.039153 -213.403688) (xy 98.090291 -213.411787) (xy 98.139531 -213.427786) (xy 98.185663 -213.451292)
			(xy 98.22755 -213.481724) (xy 98.26416 -213.518334) (xy 98.294592 -213.560221) (xy 98.318098 -213.606353)
			(xy 98.334097 -213.655593) (xy 98.342196 -213.706731) (xy 98.342704 -213.732618) (xy 99.563428 -213.732618)
			(xy 99.563936 -213.706731) (xy 99.572035 -213.655593) (xy 99.588034 -213.606353) (xy 99.61154 -213.560221)
			(xy 99.641972 -213.518334) (xy 99.678582 -213.481724) (xy 99.720469 -213.451292) (xy 99.766601 -213.427786)
			(xy 99.815841 -213.411787) (xy 99.866979 -213.403688) (xy 99.918753 -213.403688) (xy 99.969891 -213.411787)
			(xy 100.019131 -213.427786) (xy 100.065263 -213.451292) (xy 100.10715 -213.481724) (xy 100.14376 -213.518334)
			(xy 100.174192 -213.560221) (xy 100.197698 -213.606353) (xy 100.213697 -213.655593) (xy 100.221796 -213.706731)
			(xy 100.222304 -213.732618) (xy 101.443028 -213.732618) (xy 101.443536 -213.706731) (xy 101.451635 -213.655593)
			(xy 101.467634 -213.606353) (xy 101.49114 -213.560221) (xy 101.521572 -213.518334) (xy 101.558182 -213.481724)
			(xy 101.600069 -213.451292) (xy 101.646201 -213.427786) (xy 101.695441 -213.411787) (xy 101.746579 -213.403688)
			(xy 101.798353 -213.403688) (xy 101.849491 -213.411787) (xy 101.898731 -213.427786) (xy 101.944863 -213.451292)
			(xy 101.98675 -213.481724) (xy 102.02336 -213.518334) (xy 102.053792 -213.560221) (xy 102.077298 -213.606353)
			(xy 102.093297 -213.655593) (xy 102.101396 -213.706731) (xy 102.101904 -213.732618) (xy 103.322628 -213.732618)
			(xy 103.323136 -213.706731) (xy 103.331235 -213.655593) (xy 103.347234 -213.606353) (xy 103.37074 -213.560221)
			(xy 103.401172 -213.518334) (xy 103.437782 -213.481724) (xy 103.479669 -213.451292) (xy 103.525801 -213.427786)
			(xy 103.575041 -213.411787) (xy 103.626179 -213.403688) (xy 103.677953 -213.403688) (xy 103.729091 -213.411787)
			(xy 103.778331 -213.427786) (xy 103.824463 -213.451292) (xy 103.86635 -213.481724) (xy 103.90296 -213.518334)
			(xy 103.933392 -213.560221) (xy 103.956898 -213.606353) (xy 103.972897 -213.655593) (xy 103.980996 -213.706731)
			(xy 103.981504 -213.732618) (xy 105.202228 -213.732618) (xy 105.202736 -213.706731) (xy 105.210835 -213.655593)
			(xy 105.226834 -213.606353) (xy 105.25034 -213.560221) (xy 105.280772 -213.518334) (xy 105.317382 -213.481724)
			(xy 105.359269 -213.451292) (xy 105.405401 -213.427786) (xy 105.454641 -213.411787) (xy 105.505779 -213.403688)
			(xy 105.557553 -213.403688) (xy 105.608691 -213.411787) (xy 105.657931 -213.427786) (xy 105.704063 -213.451292)
			(xy 105.74595 -213.481724) (xy 105.78256 -213.518334) (xy 105.812992 -213.560221) (xy 105.836498 -213.606353)
			(xy 105.852497 -213.655593) (xy 105.860596 -213.706731) (xy 105.861104 -213.732618) (xy 107.081828 -213.732618)
			(xy 107.082336 -213.706731) (xy 107.090435 -213.655593) (xy 107.106434 -213.606353) (xy 107.12994 -213.560221)
			(xy 107.160372 -213.518334) (xy 107.196982 -213.481724) (xy 107.238869 -213.451292) (xy 107.285001 -213.427786)
			(xy 107.334241 -213.411787) (xy 107.385379 -213.403688) (xy 107.437153 -213.403688) (xy 107.488291 -213.411787)
			(xy 107.537531 -213.427786) (xy 107.583663 -213.451292) (xy 107.62555 -213.481724) (xy 107.66216 -213.518334)
			(xy 107.692592 -213.560221) (xy 107.716098 -213.606353) (xy 107.732097 -213.655593) (xy 107.740196 -213.706731)
			(xy 107.740704 -213.732618) (xy 114.600228 -213.732618) (xy 114.600736 -213.706731) (xy 114.608835 -213.655593)
			(xy 114.624834 -213.606353) (xy 114.64834 -213.560221) (xy 114.678772 -213.518334) (xy 114.715382 -213.481724)
			(xy 114.757269 -213.451292) (xy 114.803401 -213.427786) (xy 114.852641 -213.411787) (xy 114.903779 -213.403688)
			(xy 114.955553 -213.403688) (xy 115.006691 -213.411787) (xy 115.055931 -213.427786) (xy 115.102063 -213.451292)
			(xy 115.14395 -213.481724) (xy 115.18056 -213.518334) (xy 115.210992 -213.560221) (xy 115.234498 -213.606353)
			(xy 115.250497 -213.655593) (xy 115.258596 -213.706731) (xy 115.259104 -213.732618) (xy 116.479828 -213.732618)
			(xy 116.480336 -213.706731) (xy 116.488435 -213.655593) (xy 116.504434 -213.606353) (xy 116.52794 -213.560221)
			(xy 116.558372 -213.518334) (xy 116.594982 -213.481724) (xy 116.636869 -213.451292) (xy 116.683001 -213.427786)
			(xy 116.732241 -213.411787) (xy 116.783379 -213.403688) (xy 116.835153 -213.403688) (xy 116.886291 -213.411787)
			(xy 116.935531 -213.427786) (xy 116.981663 -213.451292) (xy 117.02355 -213.481724) (xy 117.06016 -213.518334)
			(xy 117.090592 -213.560221) (xy 117.114098 -213.606353) (xy 117.130097 -213.655593) (xy 117.138196 -213.706731)
			(xy 117.138704 -213.732618) (xy 118.359428 -213.732618) (xy 118.359936 -213.706731) (xy 118.368035 -213.655593)
			(xy 118.384034 -213.606353) (xy 118.40754 -213.560221) (xy 118.437972 -213.518334) (xy 118.474582 -213.481724)
			(xy 118.516469 -213.451292) (xy 118.562601 -213.427786) (xy 118.611841 -213.411787) (xy 118.662979 -213.403688)
			(xy 118.714753 -213.403688) (xy 118.765891 -213.411787) (xy 118.815131 -213.427786) (xy 118.861263 -213.451292)
			(xy 118.90315 -213.481724) (xy 118.93976 -213.518334) (xy 118.970192 -213.560221) (xy 118.993698 -213.606353)
			(xy 119.009697 -213.655593) (xy 119.017796 -213.706731) (xy 119.018304 -213.732618) (xy 120.239028 -213.732618)
			(xy 120.239536 -213.706731) (xy 120.247635 -213.655593) (xy 120.263634 -213.606353) (xy 120.28714 -213.560221)
			(xy 120.317572 -213.518334) (xy 120.354182 -213.481724) (xy 120.396069 -213.451292) (xy 120.442201 -213.427786)
			(xy 120.491441 -213.411787) (xy 120.542579 -213.403688) (xy 120.594353 -213.403688) (xy 120.645491 -213.411787)
			(xy 120.694731 -213.427786) (xy 120.740863 -213.451292) (xy 120.78275 -213.481724) (xy 120.81936 -213.518334)
			(xy 120.849792 -213.560221) (xy 120.873298 -213.606353) (xy 120.889297 -213.655593) (xy 120.897396 -213.706731)
			(xy 120.897904 -213.732618) (xy 122.118628 -213.732618) (xy 122.119136 -213.706731) (xy 122.127235 -213.655593)
			(xy 122.143234 -213.606353) (xy 122.16674 -213.560221) (xy 122.197172 -213.518334) (xy 122.233782 -213.481724)
			(xy 122.275669 -213.451292) (xy 122.321801 -213.427786) (xy 122.371041 -213.411787) (xy 122.422179 -213.403688)
			(xy 122.473953 -213.403688) (xy 122.525091 -213.411787) (xy 122.574331 -213.427786) (xy 122.620463 -213.451292)
			(xy 122.66235 -213.481724) (xy 122.69896 -213.518334) (xy 122.729392 -213.560221) (xy 122.752898 -213.606353)
			(xy 122.768897 -213.655593) (xy 122.776996 -213.706731) (xy 122.777504 -213.732618) (xy 123.99772 -213.732618)
			(xy 123.998228 -213.706711) (xy 124.006334 -213.655534) (xy 124.022346 -213.606255) (xy 124.045869 -213.560088)
			(xy 124.076325 -213.518169) (xy 124.112963 -213.481531) (xy 124.154882 -213.451075) (xy 124.201049 -213.427552)
			(xy 124.250328 -213.41154) (xy 124.301505 -213.403434) (xy 124.353319 -213.403434) (xy 124.404496 -213.41154)
			(xy 124.453775 -213.427552) (xy 124.499942 -213.451075) (xy 124.541861 -213.481531) (xy 124.578499 -213.518169)
			(xy 124.608955 -213.560088) (xy 124.632478 -213.606255) (xy 124.64849 -213.655534) (xy 124.656596 -213.706711)
			(xy 124.657104 -213.732618) (xy 125.87732 -213.732618) (xy 125.877828 -213.706711) (xy 125.885934 -213.655534)
			(xy 125.901946 -213.606255) (xy 125.925469 -213.560088) (xy 125.955925 -213.518169) (xy 125.992563 -213.481531)
			(xy 126.034482 -213.451075) (xy 126.080649 -213.427552) (xy 126.129928 -213.41154) (xy 126.181105 -213.403434)
			(xy 126.232919 -213.403434) (xy 126.284096 -213.41154) (xy 126.333375 -213.427552) (xy 126.379542 -213.451075)
			(xy 126.421461 -213.481531) (xy 126.458099 -213.518169) (xy 126.488555 -213.560088) (xy 126.512078 -213.606255)
			(xy 126.52809 -213.655534) (xy 126.536196 -213.706711) (xy 126.536704 -213.732618) (xy 127.757428 -213.732618)
			(xy 127.757936 -213.706731) (xy 127.766035 -213.655593) (xy 127.782034 -213.606353) (xy 127.80554 -213.560221)
			(xy 127.835972 -213.518334) (xy 127.872582 -213.481724) (xy 127.914469 -213.451292) (xy 127.960601 -213.427786)
			(xy 128.009841 -213.411787) (xy 128.060979 -213.403688) (xy 128.112753 -213.403688) (xy 128.163891 -213.411787)
			(xy 128.213131 -213.427786) (xy 128.259263 -213.451292) (xy 128.30115 -213.481724) (xy 128.33776 -213.518334)
			(xy 128.368192 -213.560221) (xy 128.391698 -213.606353) (xy 128.407697 -213.655593) (xy 128.415796 -213.706731)
			(xy 128.416304 -213.732618) (xy 129.637028 -213.732618) (xy 129.637536 -213.706731) (xy 129.645635 -213.655593)
			(xy 129.661634 -213.606353) (xy 129.68514 -213.560221) (xy 129.715572 -213.518334) (xy 129.752182 -213.481724)
			(xy 129.794069 -213.451292) (xy 129.840201 -213.427786) (xy 129.889441 -213.411787) (xy 129.940579 -213.403688)
			(xy 129.992353 -213.403688) (xy 130.043491 -213.411787) (xy 130.092731 -213.427786) (xy 130.138863 -213.451292)
			(xy 130.18075 -213.481724) (xy 130.21736 -213.518334) (xy 130.247792 -213.560221) (xy 130.271298 -213.606353)
			(xy 130.287297 -213.655593) (xy 130.295396 -213.706731) (xy 130.295904 -213.732618) (xy 131.516628 -213.732618)
			(xy 131.517136 -213.706731) (xy 131.525235 -213.655593) (xy 131.541234 -213.606353) (xy 131.56474 -213.560221)
			(xy 131.595172 -213.518334) (xy 131.631782 -213.481724) (xy 131.673669 -213.451292) (xy 131.719801 -213.427786)
			(xy 131.769041 -213.411787) (xy 131.820179 -213.403688) (xy 131.871953 -213.403688) (xy 131.923091 -213.411787)
			(xy 131.972331 -213.427786) (xy 132.018463 -213.451292) (xy 132.06035 -213.481724) (xy 132.09696 -213.518334)
			(xy 132.127392 -213.560221) (xy 132.150898 -213.606353) (xy 132.166897 -213.655593) (xy 132.174996 -213.706731)
			(xy 132.175504 -213.732618) (xy 338.105496 -213.732618) (xy 338.106004 -213.706731) (xy 338.114103 -213.655593)
			(xy 338.130102 -213.606353) (xy 338.153608 -213.560221) (xy 338.18404 -213.518334) (xy 338.22065 -213.481724)
			(xy 338.262537 -213.451292) (xy 338.308669 -213.427786) (xy 338.357909 -213.411787) (xy 338.409047 -213.403688)
			(xy 338.460821 -213.403688) (xy 338.511959 -213.411787) (xy 338.561199 -213.427786) (xy 338.607331 -213.451292)
			(xy 338.649218 -213.481724) (xy 338.685828 -213.518334) (xy 338.71626 -213.560221) (xy 338.739766 -213.606353)
			(xy 338.755765 -213.655593) (xy 338.763864 -213.706731) (xy 338.764372 -213.732618) (xy 339.985096 -213.732618)
			(xy 339.985604 -213.706731) (xy 339.993703 -213.655593) (xy 340.009702 -213.606353) (xy 340.033208 -213.560221)
			(xy 340.06364 -213.518334) (xy 340.10025 -213.481724) (xy 340.142137 -213.451292) (xy 340.188269 -213.427786)
			(xy 340.237509 -213.411787) (xy 340.288647 -213.403688) (xy 340.340421 -213.403688) (xy 340.391559 -213.411787)
			(xy 340.440799 -213.427786) (xy 340.486931 -213.451292) (xy 340.528818 -213.481724) (xy 340.565428 -213.518334)
			(xy 340.59586 -213.560221) (xy 340.619366 -213.606353) (xy 340.635365 -213.655593) (xy 340.643464 -213.706731)
			(xy 340.643972 -213.732618) (xy 341.864696 -213.732618) (xy 341.865204 -213.706731) (xy 341.873303 -213.655593)
			(xy 341.889302 -213.606353) (xy 341.912808 -213.560221) (xy 341.94324 -213.518334) (xy 341.97985 -213.481724)
			(xy 342.021737 -213.451292) (xy 342.067869 -213.427786) (xy 342.117109 -213.411787) (xy 342.168247 -213.403688)
			(xy 342.220021 -213.403688) (xy 342.271159 -213.411787) (xy 342.320399 -213.427786) (xy 342.366531 -213.451292)
			(xy 342.408418 -213.481724) (xy 342.445028 -213.518334) (xy 342.47546 -213.560221) (xy 342.498966 -213.606353)
			(xy 342.514965 -213.655593) (xy 342.523064 -213.706731) (xy 342.523572 -213.732618) (xy 343.744296 -213.732618)
			(xy 343.744804 -213.706731) (xy 343.752903 -213.655593) (xy 343.768902 -213.606353) (xy 343.792408 -213.560221)
			(xy 343.82284 -213.518334) (xy 343.85945 -213.481724) (xy 343.901337 -213.451292) (xy 343.947469 -213.427786)
			(xy 343.996709 -213.411787) (xy 344.047847 -213.403688) (xy 344.099621 -213.403688) (xy 344.150759 -213.411787)
			(xy 344.199999 -213.427786) (xy 344.246131 -213.451292) (xy 344.288018 -213.481724) (xy 344.324628 -213.518334)
			(xy 344.35506 -213.560221) (xy 344.378566 -213.606353) (xy 344.394565 -213.655593) (xy 344.402664 -213.706731)
			(xy 344.403172 -213.732618) (xy 345.623896 -213.732618) (xy 345.624404 -213.706731) (xy 345.632503 -213.655593)
			(xy 345.648502 -213.606353) (xy 345.672008 -213.560221) (xy 345.70244 -213.518334) (xy 345.73905 -213.481724)
			(xy 345.780937 -213.451292) (xy 345.827069 -213.427786) (xy 345.876309 -213.411787) (xy 345.927447 -213.403688)
			(xy 345.979221 -213.403688) (xy 346.030359 -213.411787) (xy 346.079599 -213.427786) (xy 346.125731 -213.451292)
			(xy 346.167618 -213.481724) (xy 346.204228 -213.518334) (xy 346.23466 -213.560221) (xy 346.258166 -213.606353)
			(xy 346.274165 -213.655593) (xy 346.282264 -213.706731) (xy 346.282772 -213.732618) (xy 347.503496 -213.732618)
			(xy 347.504004 -213.706731) (xy 347.512103 -213.655593) (xy 347.528102 -213.606353) (xy 347.551608 -213.560221)
			(xy 347.58204 -213.518334) (xy 347.61865 -213.481724) (xy 347.660537 -213.451292) (xy 347.706669 -213.427786)
			(xy 347.755909 -213.411787) (xy 347.807047 -213.403688) (xy 347.858821 -213.403688) (xy 347.909959 -213.411787)
			(xy 347.959199 -213.427786) (xy 348.005331 -213.451292) (xy 348.047218 -213.481724) (xy 348.083828 -213.518334)
			(xy 348.11426 -213.560221) (xy 348.137766 -213.606353) (xy 348.153765 -213.655593) (xy 348.161864 -213.706731)
			(xy 348.162372 -213.732618) (xy 349.383096 -213.732618) (xy 349.383604 -213.706731) (xy 349.391703 -213.655593)
			(xy 349.407702 -213.606353) (xy 349.431208 -213.560221) (xy 349.46164 -213.518334) (xy 349.49825 -213.481724)
			(xy 349.540137 -213.451292) (xy 349.586269 -213.427786) (xy 349.635509 -213.411787) (xy 349.686647 -213.403688)
			(xy 349.738421 -213.403688) (xy 349.789559 -213.411787) (xy 349.838799 -213.427786) (xy 349.884931 -213.451292)
			(xy 349.926818 -213.481724) (xy 349.963428 -213.518334) (xy 349.99386 -213.560221) (xy 350.017366 -213.606353)
			(xy 350.033365 -213.655593) (xy 350.041464 -213.706731) (xy 350.041972 -213.732618) (xy 351.262696 -213.732618)
			(xy 351.263204 -213.706731) (xy 351.271303 -213.655593) (xy 351.287302 -213.606353) (xy 351.310808 -213.560221)
			(xy 351.34124 -213.518334) (xy 351.37785 -213.481724) (xy 351.419737 -213.451292) (xy 351.465869 -213.427786)
			(xy 351.515109 -213.411787) (xy 351.566247 -213.403688) (xy 351.618021 -213.403688) (xy 351.669159 -213.411787)
			(xy 351.718399 -213.427786) (xy 351.764531 -213.451292) (xy 351.806418 -213.481724) (xy 351.843028 -213.518334)
			(xy 351.87346 -213.560221) (xy 351.896966 -213.606353) (xy 351.912965 -213.655593) (xy 351.921064 -213.706731)
			(xy 351.921572 -213.732618) (xy 353.142296 -213.732618) (xy 353.142804 -213.706731) (xy 353.150903 -213.655593)
			(xy 353.166902 -213.606353) (xy 353.190408 -213.560221) (xy 353.22084 -213.518334) (xy 353.25745 -213.481724)
			(xy 353.299337 -213.451292) (xy 353.345469 -213.427786) (xy 353.394709 -213.411787) (xy 353.445847 -213.403688)
			(xy 353.497621 -213.403688) (xy 353.548759 -213.411787) (xy 353.597999 -213.427786) (xy 353.644131 -213.451292)
			(xy 353.686018 -213.481724) (xy 353.722628 -213.518334) (xy 353.75306 -213.560221) (xy 353.776566 -213.606353)
			(xy 353.792565 -213.655593) (xy 353.800664 -213.706731) (xy 353.801172 -213.732618) (xy 355.021896 -213.732618)
			(xy 355.022404 -213.706731) (xy 355.030503 -213.655593) (xy 355.046502 -213.606353) (xy 355.070008 -213.560221)
			(xy 355.10044 -213.518334) (xy 355.13705 -213.481724) (xy 355.178937 -213.451292) (xy 355.225069 -213.427786)
			(xy 355.274309 -213.411787) (xy 355.325447 -213.403688) (xy 355.377221 -213.403688) (xy 355.428359 -213.411787)
			(xy 355.477599 -213.427786) (xy 355.523731 -213.451292) (xy 355.565618 -213.481724) (xy 355.602228 -213.518334)
			(xy 355.63266 -213.560221) (xy 355.656166 -213.606353) (xy 355.672165 -213.655593) (xy 355.680264 -213.706731)
			(xy 355.680772 -213.732618) (xy 355.680423 -213.755595) (xy 355.674102 -213.801111) (xy 355.661516 -213.845306)
			(xy 355.652578 -213.866476) (xy 355.642672 -213.888828) (xy 355.856286 -214.293958) (xy 355.880416 -214.29853)
			(xy 355.90533 -214.303664) (xy 355.95334 -214.320459) (xy 355.998199 -214.344434) (xy 356.038841 -214.375017)
			(xy 356.074299 -214.411484) (xy 356.103732 -214.452967) (xy 356.12644 -214.49848) (xy 356.141883 -214.546942)
			(xy 356.149695 -214.597202) (xy 356.150164 -214.622634) (xy 356.149656 -214.648521) (xy 356.141557 -214.699659)
			(xy 356.125558 -214.748899) (xy 356.102052 -214.795031) (xy 356.07162 -214.836918) (xy 356.03501 -214.873528)
			(xy 355.993123 -214.90396) (xy 355.946991 -214.927466) (xy 355.897751 -214.943465) (xy 355.846613 -214.951564)
			(xy 355.794839 -214.951564) (xy 355.743701 -214.943465) (xy 355.694461 -214.927466) (xy 355.648329 -214.90396)
			(xy 355.606442 -214.873528) (xy 355.569832 -214.836918) (xy 355.5394 -214.795031) (xy 355.515894 -214.748899)
			(xy 355.499895 -214.699659) (xy 355.491796 -214.648521) (xy 355.491288 -214.622634) (xy 355.491658 -214.599658)
			(xy 355.49797 -214.554143) (xy 355.510548 -214.509947) (xy 355.519482 -214.488776) (xy 355.529388 -214.466424)
			(xy 355.315774 -214.061294) (xy 355.291644 -214.056722) (xy 355.266713 -214.051663) (xy 355.218699 -214.034858)
			(xy 355.173839 -214.010874) (xy 355.133197 -213.980281) (xy 355.097739 -213.943805) (xy 355.068309 -213.902313)
			(xy 355.045605 -213.856791) (xy 355.030167 -213.80832) (xy 355.022362 -213.758053) (xy 355.021896 -213.732618)
			(xy 353.801172 -213.732618) (xy 353.800823 -213.755595) (xy 353.794502 -213.801111) (xy 353.781916 -213.845306)
			(xy 353.772978 -213.866476) (xy 353.763072 -213.888828) (xy 353.976686 -214.293958) (xy 354.000816 -214.29853)
			(xy 354.02573 -214.303664) (xy 354.07374 -214.320459) (xy 354.118599 -214.344434) (xy 354.159241 -214.375017)
			(xy 354.194699 -214.411484) (xy 354.224132 -214.452967) (xy 354.24684 -214.49848) (xy 354.262283 -214.546942)
			(xy 354.270095 -214.597202) (xy 354.270564 -214.622634) (xy 354.270056 -214.648521) (xy 354.261957 -214.699659)
			(xy 354.245958 -214.748899) (xy 354.222452 -214.795031) (xy 354.19202 -214.836918) (xy 354.15541 -214.873528)
			(xy 354.113523 -214.90396) (xy 354.067391 -214.927466) (xy 354.018151 -214.943465) (xy 353.967013 -214.951564)
			(xy 353.915239 -214.951564) (xy 353.864101 -214.943465) (xy 353.814861 -214.927466) (xy 353.768729 -214.90396)
			(xy 353.726842 -214.873528) (xy 353.690232 -214.836918) (xy 353.6598 -214.795031) (xy 353.636294 -214.748899)
			(xy 353.620295 -214.699659) (xy 353.612196 -214.648521) (xy 353.611688 -214.622634) (xy 353.612058 -214.599658)
			(xy 353.61837 -214.554143) (xy 353.630948 -214.509947) (xy 353.639882 -214.488776) (xy 353.649788 -214.466424)
			(xy 353.436174 -214.061294) (xy 353.412044 -214.056722) (xy 353.387113 -214.051663) (xy 353.339099 -214.034858)
			(xy 353.294239 -214.010874) (xy 353.253597 -213.980281) (xy 353.218139 -213.943805) (xy 353.188709 -213.902313)
			(xy 353.166005 -213.856791) (xy 353.150567 -213.80832) (xy 353.142762 -213.758053) (xy 353.142296 -213.732618)
			(xy 351.921572 -213.732618) (xy 351.921223 -213.755595) (xy 351.914902 -213.801111) (xy 351.902316 -213.845306)
			(xy 351.893378 -213.866476) (xy 351.883472 -213.888828) (xy 352.097086 -214.293958) (xy 352.121216 -214.29853)
			(xy 352.14613 -214.303664) (xy 352.19414 -214.320459) (xy 352.238999 -214.344434) (xy 352.279641 -214.375017)
			(xy 352.315099 -214.411484) (xy 352.344532 -214.452967) (xy 352.36724 -214.49848) (xy 352.382683 -214.546942)
			(xy 352.390495 -214.597202) (xy 352.390964 -214.622634) (xy 352.390456 -214.648521) (xy 352.382357 -214.699659)
			(xy 352.366358 -214.748899) (xy 352.342852 -214.795031) (xy 352.31242 -214.836918) (xy 352.27581 -214.873528)
			(xy 352.233923 -214.90396) (xy 352.187791 -214.927466) (xy 352.138551 -214.943465) (xy 352.087413 -214.951564)
			(xy 352.035639 -214.951564) (xy 351.984501 -214.943465) (xy 351.935261 -214.927466) (xy 351.889129 -214.90396)
			(xy 351.847242 -214.873528) (xy 351.810632 -214.836918) (xy 351.7802 -214.795031) (xy 351.756694 -214.748899)
			(xy 351.740695 -214.699659) (xy 351.732596 -214.648521) (xy 351.732088 -214.622634) (xy 351.732458 -214.599658)
			(xy 351.73877 -214.554143) (xy 351.751348 -214.509947) (xy 351.760282 -214.488776) (xy 351.770188 -214.466424)
			(xy 351.556574 -214.061294) (xy 351.532444 -214.056722) (xy 351.507513 -214.051663) (xy 351.459499 -214.034858)
			(xy 351.414639 -214.010874) (xy 351.373997 -213.980281) (xy 351.338539 -213.943805) (xy 351.309109 -213.902313)
			(xy 351.286405 -213.856791) (xy 351.270967 -213.80832) (xy 351.263162 -213.758053) (xy 351.262696 -213.732618)
			(xy 350.041972 -213.732618) (xy 350.041623 -213.755595) (xy 350.035302 -213.801111) (xy 350.022716 -213.845306)
			(xy 350.013778 -213.866476) (xy 350.003872 -213.888828) (xy 350.217486 -214.293958) (xy 350.241616 -214.29853)
			(xy 350.26653 -214.303664) (xy 350.31454 -214.320459) (xy 350.359399 -214.344434) (xy 350.400041 -214.375017)
			(xy 350.435499 -214.411484) (xy 350.464932 -214.452967) (xy 350.48764 -214.49848) (xy 350.503083 -214.546942)
			(xy 350.510895 -214.597202) (xy 350.511364 -214.622634) (xy 350.510856 -214.648521) (xy 350.502757 -214.699659)
			(xy 350.486758 -214.748899) (xy 350.463252 -214.795031) (xy 350.43282 -214.836918) (xy 350.39621 -214.873528)
			(xy 350.354323 -214.90396) (xy 350.308191 -214.927466) (xy 350.258951 -214.943465) (xy 350.207813 -214.951564)
			(xy 350.156039 -214.951564) (xy 350.104901 -214.943465) (xy 350.055661 -214.927466) (xy 350.009529 -214.90396)
			(xy 349.967642 -214.873528) (xy 349.931032 -214.836918) (xy 349.9006 -214.795031) (xy 349.877094 -214.748899)
			(xy 349.861095 -214.699659) (xy 349.852996 -214.648521) (xy 349.852488 -214.622634) (xy 349.852858 -214.599658)
			(xy 349.85917 -214.554143) (xy 349.871748 -214.509947) (xy 349.880682 -214.488776) (xy 349.890588 -214.466424)
			(xy 349.676974 -214.061294) (xy 349.652844 -214.056722) (xy 349.627913 -214.051663) (xy 349.579899 -214.034858)
			(xy 349.535039 -214.010874) (xy 349.494397 -213.980281) (xy 349.458939 -213.943805) (xy 349.429509 -213.902313)
			(xy 349.406805 -213.856791) (xy 349.391367 -213.80832) (xy 349.383562 -213.758053) (xy 349.383096 -213.732618)
			(xy 348.162372 -213.732618) (xy 348.162023 -213.755595) (xy 348.155702 -213.801111) (xy 348.143116 -213.845306)
			(xy 348.134178 -213.866476) (xy 348.124272 -213.888828) (xy 348.337886 -214.293958) (xy 348.362016 -214.29853)
			(xy 348.38693 -214.303664) (xy 348.43494 -214.320459) (xy 348.479799 -214.344434) (xy 348.520441 -214.375017)
			(xy 348.555899 -214.411484) (xy 348.585332 -214.452967) (xy 348.60804 -214.49848) (xy 348.623483 -214.546942)
			(xy 348.631295 -214.597202) (xy 348.631764 -214.622634) (xy 348.631256 -214.648521) (xy 348.623157 -214.699659)
			(xy 348.607158 -214.748899) (xy 348.583652 -214.795031) (xy 348.55322 -214.836918) (xy 348.51661 -214.873528)
			(xy 348.474723 -214.90396) (xy 348.428591 -214.927466) (xy 348.379351 -214.943465) (xy 348.328213 -214.951564)
			(xy 348.276439 -214.951564) (xy 348.225301 -214.943465) (xy 348.176061 -214.927466) (xy 348.129929 -214.90396)
			(xy 348.088042 -214.873528) (xy 348.051432 -214.836918) (xy 348.021 -214.795031) (xy 347.997494 -214.748899)
			(xy 347.981495 -214.699659) (xy 347.973396 -214.648521) (xy 347.972888 -214.622634) (xy 347.973258 -214.599658)
			(xy 347.97957 -214.554143) (xy 347.992148 -214.509947) (xy 348.001082 -214.488776) (xy 348.010988 -214.466424)
			(xy 347.797374 -214.061294) (xy 347.773244 -214.056722) (xy 347.748313 -214.051663) (xy 347.700299 -214.034858)
			(xy 347.655439 -214.010874) (xy 347.614797 -213.980281) (xy 347.579339 -213.943805) (xy 347.549909 -213.902313)
			(xy 347.527205 -213.856791) (xy 347.511767 -213.80832) (xy 347.503962 -213.758053) (xy 347.503496 -213.732618)
			(xy 346.282772 -213.732618) (xy 346.282423 -213.755595) (xy 346.276102 -213.801111) (xy 346.263516 -213.845306)
			(xy 346.254578 -213.866476) (xy 346.244672 -213.888828) (xy 346.458286 -214.293958) (xy 346.482416 -214.29853)
			(xy 346.50733 -214.303664) (xy 346.55534 -214.320459) (xy 346.600199 -214.344434) (xy 346.640841 -214.375017)
			(xy 346.676299 -214.411484) (xy 346.705732 -214.452967) (xy 346.72844 -214.49848) (xy 346.743883 -214.546942)
			(xy 346.751695 -214.597202) (xy 346.752164 -214.622634) (xy 346.751656 -214.648521) (xy 346.743557 -214.699659)
			(xy 346.727558 -214.748899) (xy 346.704052 -214.795031) (xy 346.67362 -214.836918) (xy 346.63701 -214.873528)
			(xy 346.595123 -214.90396) (xy 346.548991 -214.927466) (xy 346.499751 -214.943465) (xy 346.448613 -214.951564)
			(xy 346.396839 -214.951564) (xy 346.345701 -214.943465) (xy 346.296461 -214.927466) (xy 346.250329 -214.90396)
			(xy 346.208442 -214.873528) (xy 346.171832 -214.836918) (xy 346.1414 -214.795031) (xy 346.117894 -214.748899)
			(xy 346.101895 -214.699659) (xy 346.093796 -214.648521) (xy 346.093288 -214.622634) (xy 346.093658 -214.599658)
			(xy 346.09997 -214.554143) (xy 346.112548 -214.509947) (xy 346.121482 -214.488776) (xy 346.131388 -214.466424)
			(xy 345.917774 -214.061294) (xy 345.893644 -214.056722) (xy 345.868713 -214.051663) (xy 345.820699 -214.034858)
			(xy 345.775839 -214.010874) (xy 345.735197 -213.980281) (xy 345.699739 -213.943805) (xy 345.670309 -213.902313)
			(xy 345.647605 -213.856791) (xy 345.632167 -213.80832) (xy 345.624362 -213.758053) (xy 345.623896 -213.732618)
			(xy 344.403172 -213.732618) (xy 344.402823 -213.755595) (xy 344.396502 -213.801111) (xy 344.383916 -213.845306)
			(xy 344.374978 -213.866476) (xy 344.365072 -213.888828) (xy 344.578686 -214.293958) (xy 344.602816 -214.29853)
			(xy 344.62773 -214.303664) (xy 344.67574 -214.320459) (xy 344.720599 -214.344434) (xy 344.761241 -214.375017)
			(xy 344.796699 -214.411484) (xy 344.826132 -214.452967) (xy 344.84884 -214.49848) (xy 344.864283 -214.546942)
			(xy 344.872095 -214.597202) (xy 344.872564 -214.622634) (xy 344.872056 -214.648521) (xy 344.863957 -214.699659)
			(xy 344.847958 -214.748899) (xy 344.824452 -214.795031) (xy 344.79402 -214.836918) (xy 344.75741 -214.873528)
			(xy 344.715523 -214.90396) (xy 344.669391 -214.927466) (xy 344.620151 -214.943465) (xy 344.569013 -214.951564)
			(xy 344.517239 -214.951564) (xy 344.466101 -214.943465) (xy 344.416861 -214.927466) (xy 344.370729 -214.90396)
			(xy 344.328842 -214.873528) (xy 344.292232 -214.836918) (xy 344.2618 -214.795031) (xy 344.238294 -214.748899)
			(xy 344.222295 -214.699659) (xy 344.214196 -214.648521) (xy 344.213688 -214.622634) (xy 344.214058 -214.599658)
			(xy 344.22037 -214.554143) (xy 344.232948 -214.509947) (xy 344.241882 -214.488776) (xy 344.251788 -214.466424)
			(xy 344.038174 -214.061294) (xy 344.014044 -214.056722) (xy 343.989113 -214.051663) (xy 343.941099 -214.034858)
			(xy 343.896239 -214.010874) (xy 343.855597 -213.980281) (xy 343.820139 -213.943805) (xy 343.790709 -213.902313)
			(xy 343.768005 -213.856791) (xy 343.752567 -213.80832) (xy 343.744762 -213.758053) (xy 343.744296 -213.732618)
			(xy 342.523572 -213.732618) (xy 342.523223 -213.755595) (xy 342.516902 -213.801111) (xy 342.504316 -213.845306)
			(xy 342.495378 -213.866476) (xy 342.485472 -213.888828) (xy 342.699086 -214.293958) (xy 342.723216 -214.29853)
			(xy 342.74813 -214.303664) (xy 342.79614 -214.320459) (xy 342.840999 -214.344434) (xy 342.881641 -214.375017)
			(xy 342.917099 -214.411484) (xy 342.946532 -214.452967) (xy 342.96924 -214.49848) (xy 342.984683 -214.546942)
			(xy 342.992495 -214.597202) (xy 342.992964 -214.622634) (xy 342.992456 -214.648521) (xy 342.984357 -214.699659)
			(xy 342.968358 -214.748899) (xy 342.944852 -214.795031) (xy 342.91442 -214.836918) (xy 342.87781 -214.873528)
			(xy 342.835923 -214.90396) (xy 342.789791 -214.927466) (xy 342.740551 -214.943465) (xy 342.689413 -214.951564)
			(xy 342.637639 -214.951564) (xy 342.586501 -214.943465) (xy 342.537261 -214.927466) (xy 342.491129 -214.90396)
			(xy 342.449242 -214.873528) (xy 342.412632 -214.836918) (xy 342.3822 -214.795031) (xy 342.358694 -214.748899)
			(xy 342.342695 -214.699659) (xy 342.334596 -214.648521) (xy 342.334088 -214.622634) (xy 342.334458 -214.599658)
			(xy 342.34077 -214.554143) (xy 342.353348 -214.509947) (xy 342.362282 -214.488776) (xy 342.372188 -214.466424)
			(xy 342.158574 -214.061294) (xy 342.134444 -214.056722) (xy 342.109513 -214.051663) (xy 342.061499 -214.034858)
			(xy 342.016639 -214.010874) (xy 341.975997 -213.980281) (xy 341.940539 -213.943805) (xy 341.911109 -213.902313)
			(xy 341.888405 -213.856791) (xy 341.872967 -213.80832) (xy 341.865162 -213.758053) (xy 341.864696 -213.732618)
			(xy 340.643972 -213.732618) (xy 340.643623 -213.755595) (xy 340.637302 -213.801111) (xy 340.624716 -213.845306)
			(xy 340.615778 -213.866476) (xy 340.605872 -213.888828) (xy 340.819486 -214.293958) (xy 340.843616 -214.29853)
			(xy 340.86853 -214.303664) (xy 340.91654 -214.320459) (xy 340.961399 -214.344434) (xy 341.002041 -214.375017)
			(xy 341.037499 -214.411484) (xy 341.066932 -214.452967) (xy 341.08964 -214.49848) (xy 341.105083 -214.546942)
			(xy 341.112895 -214.597202) (xy 341.113364 -214.622634) (xy 341.112856 -214.648521) (xy 341.104757 -214.699659)
			(xy 341.088758 -214.748899) (xy 341.065252 -214.795031) (xy 341.03482 -214.836918) (xy 340.99821 -214.873528)
			(xy 340.956323 -214.90396) (xy 340.910191 -214.927466) (xy 340.860951 -214.943465) (xy 340.809813 -214.951564)
			(xy 340.758039 -214.951564) (xy 340.706901 -214.943465) (xy 340.657661 -214.927466) (xy 340.611529 -214.90396)
			(xy 340.569642 -214.873528) (xy 340.533032 -214.836918) (xy 340.5026 -214.795031) (xy 340.479094 -214.748899)
			(xy 340.463095 -214.699659) (xy 340.454996 -214.648521) (xy 340.454488 -214.622634) (xy 340.454858 -214.599658)
			(xy 340.46117 -214.554143) (xy 340.473748 -214.509947) (xy 340.482682 -214.488776) (xy 340.492588 -214.466424)
			(xy 340.278974 -214.061294) (xy 340.254844 -214.056722) (xy 340.229913 -214.051663) (xy 340.181899 -214.034858)
			(xy 340.137039 -214.010874) (xy 340.096397 -213.980281) (xy 340.060939 -213.943805) (xy 340.031509 -213.902313)
			(xy 340.008805 -213.856791) (xy 339.993367 -213.80832) (xy 339.985562 -213.758053) (xy 339.985096 -213.732618)
			(xy 338.764372 -213.732618) (xy 338.764023 -213.755595) (xy 338.757702 -213.801111) (xy 338.745116 -213.845306)
			(xy 338.736178 -213.866476) (xy 338.726272 -213.888828) (xy 338.939886 -214.293958) (xy 338.964016 -214.29853)
			(xy 338.98893 -214.303664) (xy 339.03694 -214.320459) (xy 339.081799 -214.344434) (xy 339.122441 -214.375017)
			(xy 339.157899 -214.411484) (xy 339.187332 -214.452967) (xy 339.21004 -214.49848) (xy 339.225483 -214.546942)
			(xy 339.233295 -214.597202) (xy 339.233764 -214.622634) (xy 339.233256 -214.648521) (xy 339.225157 -214.699659)
			(xy 339.209158 -214.748899) (xy 339.185652 -214.795031) (xy 339.15522 -214.836918) (xy 339.11861 -214.873528)
			(xy 339.076723 -214.90396) (xy 339.030591 -214.927466) (xy 338.981351 -214.943465) (xy 338.930213 -214.951564)
			(xy 338.878439 -214.951564) (xy 338.827301 -214.943465) (xy 338.778061 -214.927466) (xy 338.731929 -214.90396)
			(xy 338.690042 -214.873528) (xy 338.653432 -214.836918) (xy 338.623 -214.795031) (xy 338.599494 -214.748899)
			(xy 338.583495 -214.699659) (xy 338.575396 -214.648521) (xy 338.574888 -214.622634) (xy 338.575258 -214.599658)
			(xy 338.58157 -214.554143) (xy 338.594148 -214.509947) (xy 338.603082 -214.488776) (xy 338.612988 -214.466424)
			(xy 338.399374 -214.061294) (xy 338.375244 -214.056722) (xy 338.350313 -214.051663) (xy 338.302299 -214.034858)
			(xy 338.257439 -214.010874) (xy 338.216797 -213.980281) (xy 338.181339 -213.943805) (xy 338.151909 -213.902313)
			(xy 338.129205 -213.856791) (xy 338.113767 -213.80832) (xy 338.105962 -213.758053) (xy 338.105496 -213.732618)
			(xy 132.175504 -213.732618) (xy 132.175153 -213.755595) (xy 132.168832 -213.80111) (xy 132.156248 -213.845306)
			(xy 132.14731 -213.866476) (xy 132.137404 -213.888828) (xy 132.351018 -214.293958) (xy 132.375148 -214.29853)
			(xy 132.400067 -214.303641) (xy 132.448077 -214.320441) (xy 132.492936 -214.344419) (xy 132.533576 -214.375006)
			(xy 132.569034 -214.411476) (xy 132.598466 -214.452961) (xy 132.621173 -214.498476) (xy 132.636615 -214.54694)
			(xy 132.644427 -214.597201) (xy 132.644896 -214.622634) (xy 132.644388 -214.648521) (xy 132.636289 -214.699659)
			(xy 132.62029 -214.748899) (xy 132.596784 -214.795031) (xy 132.566352 -214.836918) (xy 132.529742 -214.873528)
			(xy 132.487855 -214.90396) (xy 132.441723 -214.927466) (xy 132.392483 -214.943465) (xy 132.341345 -214.951564)
			(xy 132.289571 -214.951564) (xy 132.238433 -214.943465) (xy 132.189193 -214.927466) (xy 132.143061 -214.90396)
			(xy 132.101174 -214.873528) (xy 132.064564 -214.836918) (xy 132.034132 -214.795031) (xy 132.010626 -214.748899)
			(xy 131.994627 -214.699659) (xy 131.986528 -214.648521) (xy 131.98602 -214.622634) (xy 131.986387 -214.599658)
			(xy 131.9927 -214.554143) (xy 132.005279 -214.509947) (xy 132.014214 -214.488776) (xy 132.02412 -214.466424)
			(xy 131.810506 -214.061294) (xy 131.786376 -214.056722) (xy 131.76145 -214.051639) (xy 131.713436 -214.034839)
			(xy 131.668575 -214.010859) (xy 131.627932 -213.980269) (xy 131.592474 -213.943796) (xy 131.563043 -213.902307)
			(xy 131.540338 -213.856787) (xy 131.5249 -213.808318) (xy 131.517094 -213.758052) (xy 131.516628 -213.732618)
			(xy 130.295904 -213.732618) (xy 130.295553 -213.755595) (xy 130.289232 -213.80111) (xy 130.276648 -213.845306)
			(xy 130.26771 -213.866476) (xy 130.257804 -213.888828) (xy 130.471418 -214.293958) (xy 130.495548 -214.29853)
			(xy 130.520467 -214.303641) (xy 130.568477 -214.320441) (xy 130.613336 -214.344419) (xy 130.653976 -214.375006)
			(xy 130.689434 -214.411476) (xy 130.718866 -214.452961) (xy 130.741573 -214.498476) (xy 130.757015 -214.54694)
			(xy 130.764827 -214.597201) (xy 130.765296 -214.622634) (xy 130.764788 -214.648521) (xy 130.756689 -214.699659)
			(xy 130.74069 -214.748899) (xy 130.717184 -214.795031) (xy 130.686752 -214.836918) (xy 130.650142 -214.873528)
			(xy 130.608255 -214.90396) (xy 130.562123 -214.927466) (xy 130.512883 -214.943465) (xy 130.461745 -214.951564)
			(xy 130.409971 -214.951564) (xy 130.358833 -214.943465) (xy 130.309593 -214.927466) (xy 130.263461 -214.90396)
			(xy 130.221574 -214.873528) (xy 130.184964 -214.836918) (xy 130.154532 -214.795031) (xy 130.131026 -214.748899)
			(xy 130.115027 -214.699659) (xy 130.106928 -214.648521) (xy 130.10642 -214.622634) (xy 130.106787 -214.599658)
			(xy 130.1131 -214.554143) (xy 130.125679 -214.509947) (xy 130.134614 -214.488776) (xy 130.14452 -214.466424)
			(xy 129.930906 -214.061294) (xy 129.906776 -214.056722) (xy 129.88185 -214.051639) (xy 129.833836 -214.034839)
			(xy 129.788975 -214.010859) (xy 129.748332 -213.980269) (xy 129.712874 -213.943796) (xy 129.683443 -213.902307)
			(xy 129.660738 -213.856787) (xy 129.6453 -213.808318) (xy 129.637494 -213.758052) (xy 129.637028 -213.732618)
			(xy 128.416304 -213.732618) (xy 128.415953 -213.755595) (xy 128.409632 -213.80111) (xy 128.397048 -213.845306)
			(xy 128.38811 -213.866476) (xy 128.378204 -213.888828) (xy 128.591818 -214.293958) (xy 128.615948 -214.29853)
			(xy 128.640867 -214.303641) (xy 128.688877 -214.320441) (xy 128.733736 -214.344419) (xy 128.774376 -214.375006)
			(xy 128.809834 -214.411476) (xy 128.839266 -214.452961) (xy 128.861973 -214.498476) (xy 128.877415 -214.54694)
			(xy 128.885227 -214.597201) (xy 128.885696 -214.622634) (xy 128.885188 -214.648521) (xy 128.877089 -214.699659)
			(xy 128.86109 -214.748899) (xy 128.837584 -214.795031) (xy 128.807152 -214.836918) (xy 128.770542 -214.873528)
			(xy 128.728655 -214.90396) (xy 128.682523 -214.927466) (xy 128.633283 -214.943465) (xy 128.582145 -214.951564)
			(xy 128.530371 -214.951564) (xy 128.479233 -214.943465) (xy 128.429993 -214.927466) (xy 128.383861 -214.90396)
			(xy 128.341974 -214.873528) (xy 128.305364 -214.836918) (xy 128.274932 -214.795031) (xy 128.251426 -214.748899)
			(xy 128.235427 -214.699659) (xy 128.227328 -214.648521) (xy 128.22682 -214.622634) (xy 128.227187 -214.599658)
			(xy 128.2335 -214.554143) (xy 128.246079 -214.509947) (xy 128.255014 -214.488776) (xy 128.26492 -214.466424)
			(xy 128.051306 -214.061294) (xy 128.027176 -214.056722) (xy 128.00225 -214.051639) (xy 127.954236 -214.034839)
			(xy 127.909375 -214.010859) (xy 127.868732 -213.980269) (xy 127.833274 -213.943796) (xy 127.803843 -213.902307)
			(xy 127.781138 -213.856787) (xy 127.7657 -213.808318) (xy 127.757894 -213.758052) (xy 127.757428 -213.732618)
			(xy 126.536704 -213.732618) (xy 126.536283 -213.755559) (xy 126.529855 -213.80099) (xy 126.517209 -213.845096)
			(xy 126.508256 -213.866222) (xy 126.49835 -213.888574) (xy 126.712218 -214.293958) (xy 126.736348 -214.29853)
			(xy 126.761267 -214.303641) (xy 126.809277 -214.320441) (xy 126.854136 -214.344419) (xy 126.894776 -214.375006)
			(xy 126.930234 -214.411476) (xy 126.959666 -214.452961) (xy 126.982373 -214.498476) (xy 126.997815 -214.54694)
			(xy 127.005627 -214.597201) (xy 127.006096 -214.622634) (xy 127.005588 -214.648521) (xy 126.997489 -214.699659)
			(xy 126.98149 -214.748899) (xy 126.957984 -214.795031) (xy 126.927552 -214.836918) (xy 126.890942 -214.873528)
			(xy 126.849055 -214.90396) (xy 126.802923 -214.927466) (xy 126.753683 -214.943465) (xy 126.702545 -214.951564)
			(xy 126.650771 -214.951564) (xy 126.599633 -214.943465) (xy 126.550393 -214.927466) (xy 126.504261 -214.90396)
			(xy 126.462374 -214.873528) (xy 126.425764 -214.836918) (xy 126.395332 -214.795031) (xy 126.371826 -214.748899)
			(xy 126.355827 -214.699659) (xy 126.347728 -214.648521) (xy 126.34722 -214.622634) (xy 126.347587 -214.599658)
			(xy 126.3539 -214.554143) (xy 126.366479 -214.509947) (xy 126.375414 -214.488776) (xy 126.38532 -214.466424)
			(xy 126.171706 -214.061294) (xy 126.147576 -214.056722) (xy 126.12262 -214.051672) (xy 126.074538 -214.034924)
			(xy 126.029605 -214.010979) (xy 125.98889 -213.980407) (xy 125.953363 -213.943936) (xy 125.92387 -213.902434)
			(xy 125.901111 -213.856888) (xy 125.88563 -213.808384) (xy 125.877795 -213.758075) (xy 125.87732 -213.732618)
			(xy 124.657104 -213.732618) (xy 124.656681 -213.756953) (xy 124.649527 -213.805095) (xy 124.635379 -213.851663)
			(xy 124.625354 -213.873842) (xy 124.614432 -213.896448) (xy 124.820172 -214.292942) (xy 124.845826 -214.296752)
			(xy 124.87151 -214.301109) (xy 124.921167 -214.316849) (xy 124.967731 -214.340204) (xy 125.010041 -214.370592)
			(xy 125.047044 -214.407258) (xy 125.077819 -214.449288) (xy 125.101599 -214.495635) (xy 125.117793 -214.545146)
			(xy 125.125998 -214.596588) (xy 125.126496 -214.622634) (xy 125.125988 -214.648521) (xy 125.117889 -214.699659)
			(xy 125.10189 -214.748899) (xy 125.078384 -214.795031) (xy 125.047952 -214.836918) (xy 125.011342 -214.873528)
			(xy 124.969455 -214.90396) (xy 124.923323 -214.927466) (xy 124.874083 -214.943465) (xy 124.822945 -214.951564)
			(xy 124.771171 -214.951564) (xy 124.720033 -214.943465) (xy 124.670793 -214.927466) (xy 124.624661 -214.90396)
			(xy 124.582774 -214.873528) (xy 124.546164 -214.836918) (xy 124.515732 -214.795031) (xy 124.492226 -214.748899)
			(xy 124.476227 -214.699659) (xy 124.468128 -214.648521) (xy 124.46762 -214.622634) (xy 124.468099 -214.597068)
			(xy 124.476002 -214.546552) (xy 124.491623 -214.497866) (xy 124.502672 -214.474806) (xy 124.514102 -214.451438)
			(xy 124.31268 -214.062818) (xy 124.28601 -214.059516) (xy 124.259814 -214.055663) (xy 124.20902 -214.04073)
			(xy 124.161267 -214.017866) (xy 124.117785 -213.987661) (xy 124.079693 -213.950891) (xy 124.047971 -213.908503)
			(xy 124.023436 -213.861587) (xy 124.006718 -213.811352) (xy 123.998249 -213.75909) (xy 123.99772 -213.732618)
			(xy 122.777504 -213.732618) (xy 122.777153 -213.755595) (xy 122.770832 -213.80111) (xy 122.758248 -213.845306)
			(xy 122.74931 -213.866476) (xy 122.739404 -213.888828) (xy 122.953018 -214.293958) (xy 122.977148 -214.29853)
			(xy 123.002067 -214.303641) (xy 123.050077 -214.320441) (xy 123.094936 -214.344419) (xy 123.135576 -214.375006)
			(xy 123.171034 -214.411476) (xy 123.200466 -214.452961) (xy 123.223173 -214.498476) (xy 123.238615 -214.54694)
			(xy 123.246427 -214.597201) (xy 123.246896 -214.622634) (xy 123.246388 -214.648521) (xy 123.238289 -214.699659)
			(xy 123.22229 -214.748899) (xy 123.198784 -214.795031) (xy 123.168352 -214.836918) (xy 123.131742 -214.873528)
			(xy 123.089855 -214.90396) (xy 123.043723 -214.927466) (xy 122.994483 -214.943465) (xy 122.943345 -214.951564)
			(xy 122.891571 -214.951564) (xy 122.840433 -214.943465) (xy 122.791193 -214.927466) (xy 122.745061 -214.90396)
			(xy 122.703174 -214.873528) (xy 122.666564 -214.836918) (xy 122.636132 -214.795031) (xy 122.612626 -214.748899)
			(xy 122.596627 -214.699659) (xy 122.588528 -214.648521) (xy 122.58802 -214.622634) (xy 122.588387 -214.599658)
			(xy 122.5947 -214.554143) (xy 122.607279 -214.509947) (xy 122.616214 -214.488776) (xy 122.62612 -214.466424)
			(xy 122.412506 -214.061294) (xy 122.388376 -214.056722) (xy 122.36345 -214.051639) (xy 122.315436 -214.034839)
			(xy 122.270575 -214.010859) (xy 122.229932 -213.980269) (xy 122.194474 -213.943796) (xy 122.165043 -213.902307)
			(xy 122.142338 -213.856787) (xy 122.1269 -213.808318) (xy 122.119094 -213.758052) (xy 122.118628 -213.732618)
			(xy 120.897904 -213.732618) (xy 120.897553 -213.755595) (xy 120.891232 -213.80111) (xy 120.878648 -213.845306)
			(xy 120.86971 -213.866476) (xy 120.859804 -213.888828) (xy 121.073418 -214.293958) (xy 121.097548 -214.29853)
			(xy 121.122467 -214.303641) (xy 121.170477 -214.320441) (xy 121.215336 -214.344419) (xy 121.255976 -214.375006)
			(xy 121.291434 -214.411476) (xy 121.320866 -214.452961) (xy 121.343573 -214.498476) (xy 121.359015 -214.54694)
			(xy 121.366827 -214.597201) (xy 121.367296 -214.622634) (xy 121.366788 -214.648521) (xy 121.358689 -214.699659)
			(xy 121.34269 -214.748899) (xy 121.319184 -214.795031) (xy 121.288752 -214.836918) (xy 121.252142 -214.873528)
			(xy 121.210255 -214.90396) (xy 121.164123 -214.927466) (xy 121.114883 -214.943465) (xy 121.063745 -214.951564)
			(xy 121.011971 -214.951564) (xy 120.960833 -214.943465) (xy 120.911593 -214.927466) (xy 120.865461 -214.90396)
			(xy 120.823574 -214.873528) (xy 120.786964 -214.836918) (xy 120.756532 -214.795031) (xy 120.733026 -214.748899)
			(xy 120.717027 -214.699659) (xy 120.708928 -214.648521) (xy 120.70842 -214.622634) (xy 120.708787 -214.599658)
			(xy 120.7151 -214.554143) (xy 120.727679 -214.509947) (xy 120.736614 -214.488776) (xy 120.74652 -214.466424)
			(xy 120.532906 -214.061294) (xy 120.508776 -214.056722) (xy 120.48385 -214.051639) (xy 120.435836 -214.034839)
			(xy 120.390975 -214.010859) (xy 120.350332 -213.980269) (xy 120.314874 -213.943796) (xy 120.285443 -213.902307)
			(xy 120.262738 -213.856787) (xy 120.2473 -213.808318) (xy 120.239494 -213.758052) (xy 120.239028 -213.732618)
			(xy 119.018304 -213.732618) (xy 119.017953 -213.755595) (xy 119.011632 -213.80111) (xy 118.999048 -213.845306)
			(xy 118.99011 -213.866476) (xy 118.980204 -213.888828) (xy 119.193818 -214.293958) (xy 119.217948 -214.29853)
			(xy 119.242867 -214.303641) (xy 119.290877 -214.320441) (xy 119.335736 -214.344419) (xy 119.376376 -214.375006)
			(xy 119.411834 -214.411476) (xy 119.441266 -214.452961) (xy 119.463973 -214.498476) (xy 119.479415 -214.54694)
			(xy 119.487227 -214.597201) (xy 119.487696 -214.622634) (xy 119.487188 -214.648521) (xy 119.479089 -214.699659)
			(xy 119.46309 -214.748899) (xy 119.439584 -214.795031) (xy 119.409152 -214.836918) (xy 119.372542 -214.873528)
			(xy 119.330655 -214.90396) (xy 119.284523 -214.927466) (xy 119.235283 -214.943465) (xy 119.184145 -214.951564)
			(xy 119.132371 -214.951564) (xy 119.081233 -214.943465) (xy 119.031993 -214.927466) (xy 118.985861 -214.90396)
			(xy 118.943974 -214.873528) (xy 118.907364 -214.836918) (xy 118.876932 -214.795031) (xy 118.853426 -214.748899)
			(xy 118.837427 -214.699659) (xy 118.829328 -214.648521) (xy 118.82882 -214.622634) (xy 118.829187 -214.599658)
			(xy 118.8355 -214.554143) (xy 118.848079 -214.509947) (xy 118.857014 -214.488776) (xy 118.86692 -214.466424)
			(xy 118.653306 -214.061294) (xy 118.629176 -214.056722) (xy 118.60425 -214.051639) (xy 118.556236 -214.034839)
			(xy 118.511375 -214.010859) (xy 118.470732 -213.980269) (xy 118.435274 -213.943796) (xy 118.405843 -213.902307)
			(xy 118.383138 -213.856787) (xy 118.3677 -213.808318) (xy 118.359894 -213.758052) (xy 118.359428 -213.732618)
			(xy 117.138704 -213.732618) (xy 117.138353 -213.755595) (xy 117.132032 -213.80111) (xy 117.119448 -213.845306)
			(xy 117.11051 -213.866476) (xy 117.100604 -213.888828) (xy 117.314218 -214.293958) (xy 117.338348 -214.29853)
			(xy 117.363267 -214.303641) (xy 117.411277 -214.320441) (xy 117.456136 -214.344419) (xy 117.496776 -214.375006)
			(xy 117.532234 -214.411476) (xy 117.561666 -214.452961) (xy 117.584373 -214.498476) (xy 117.599815 -214.54694)
			(xy 117.607627 -214.597201) (xy 117.608096 -214.622634) (xy 117.607588 -214.648521) (xy 117.599489 -214.699659)
			(xy 117.58349 -214.748899) (xy 117.559984 -214.795031) (xy 117.529552 -214.836918) (xy 117.492942 -214.873528)
			(xy 117.451055 -214.90396) (xy 117.404923 -214.927466) (xy 117.355683 -214.943465) (xy 117.304545 -214.951564)
			(xy 117.252771 -214.951564) (xy 117.201633 -214.943465) (xy 117.152393 -214.927466) (xy 117.106261 -214.90396)
			(xy 117.064374 -214.873528) (xy 117.027764 -214.836918) (xy 116.997332 -214.795031) (xy 116.973826 -214.748899)
			(xy 116.957827 -214.699659) (xy 116.949728 -214.648521) (xy 116.94922 -214.622634) (xy 116.949587 -214.599658)
			(xy 116.9559 -214.554143) (xy 116.968479 -214.509947) (xy 116.977414 -214.488776) (xy 116.98732 -214.466424)
			(xy 116.773706 -214.061294) (xy 116.749576 -214.056722) (xy 116.72465 -214.051639) (xy 116.676636 -214.034839)
			(xy 116.631775 -214.010859) (xy 116.591132 -213.980269) (xy 116.555674 -213.943796) (xy 116.526243 -213.902307)
			(xy 116.503538 -213.856787) (xy 116.4881 -213.808318) (xy 116.480294 -213.758052) (xy 116.479828 -213.732618)
			(xy 115.259104 -213.732618) (xy 115.258753 -213.755595) (xy 115.252432 -213.80111) (xy 115.239848 -213.845306)
			(xy 115.23091 -213.866476) (xy 115.221004 -213.888828) (xy 115.434618 -214.293958) (xy 115.458748 -214.29853)
			(xy 115.483667 -214.303641) (xy 115.531677 -214.320441) (xy 115.576536 -214.344419) (xy 115.617176 -214.375006)
			(xy 115.652634 -214.411476) (xy 115.682066 -214.452961) (xy 115.704773 -214.498476) (xy 115.720215 -214.54694)
			(xy 115.728027 -214.597201) (xy 115.728496 -214.622634) (xy 115.727988 -214.648521) (xy 115.719889 -214.699659)
			(xy 115.70389 -214.748899) (xy 115.680384 -214.795031) (xy 115.649952 -214.836918) (xy 115.613342 -214.873528)
			(xy 115.571455 -214.90396) (xy 115.525323 -214.927466) (xy 115.476083 -214.943465) (xy 115.424945 -214.951564)
			(xy 115.373171 -214.951564) (xy 115.322033 -214.943465) (xy 115.272793 -214.927466) (xy 115.226661 -214.90396)
			(xy 115.184774 -214.873528) (xy 115.148164 -214.836918) (xy 115.117732 -214.795031) (xy 115.094226 -214.748899)
			(xy 115.078227 -214.699659) (xy 115.070128 -214.648521) (xy 115.06962 -214.622634) (xy 115.069987 -214.599658)
			(xy 115.0763 -214.554143) (xy 115.088879 -214.509947) (xy 115.097814 -214.488776) (xy 115.10772 -214.466424)
			(xy 114.894106 -214.061294) (xy 114.869976 -214.056722) (xy 114.84505 -214.051639) (xy 114.797036 -214.034839)
			(xy 114.752175 -214.010859) (xy 114.711532 -213.980269) (xy 114.676074 -213.943796) (xy 114.646643 -213.902307)
			(xy 114.623938 -213.856787) (xy 114.6085 -213.808318) (xy 114.600694 -213.758052) (xy 114.600228 -213.732618)
			(xy 107.740704 -213.732618) (xy 107.740353 -213.755595) (xy 107.734032 -213.80111) (xy 107.721448 -213.845306)
			(xy 107.71251 -213.866476) (xy 107.702604 -213.888828) (xy 107.916218 -214.293958) (xy 107.940348 -214.29853)
			(xy 107.965267 -214.303641) (xy 108.013277 -214.320441) (xy 108.058136 -214.344419) (xy 108.098776 -214.375006)
			(xy 108.134234 -214.411476) (xy 108.163666 -214.452961) (xy 108.186373 -214.498476) (xy 108.201815 -214.54694)
			(xy 108.209627 -214.597201) (xy 108.210096 -214.622634) (xy 108.209588 -214.648521) (xy 108.201489 -214.699659)
			(xy 108.18549 -214.748899) (xy 108.161984 -214.795031) (xy 108.131552 -214.836918) (xy 108.094942 -214.873528)
			(xy 108.053055 -214.90396) (xy 108.006923 -214.927466) (xy 107.957683 -214.943465) (xy 107.906545 -214.951564)
			(xy 107.854771 -214.951564) (xy 107.803633 -214.943465) (xy 107.754393 -214.927466) (xy 107.708261 -214.90396)
			(xy 107.666374 -214.873528) (xy 107.629764 -214.836918) (xy 107.599332 -214.795031) (xy 107.575826 -214.748899)
			(xy 107.559827 -214.699659) (xy 107.551728 -214.648521) (xy 107.55122 -214.622634) (xy 107.551587 -214.599658)
			(xy 107.5579 -214.554143) (xy 107.570479 -214.509947) (xy 107.579414 -214.488776) (xy 107.58932 -214.466424)
			(xy 107.375706 -214.061294) (xy 107.351576 -214.056722) (xy 107.32665 -214.051639) (xy 107.278636 -214.034839)
			(xy 107.233775 -214.010859) (xy 107.193132 -213.980269) (xy 107.157674 -213.943796) (xy 107.128243 -213.902307)
			(xy 107.105538 -213.856787) (xy 107.0901 -213.808318) (xy 107.082294 -213.758052) (xy 107.081828 -213.732618)
			(xy 105.861104 -213.732618) (xy 105.860753 -213.755595) (xy 105.854432 -213.80111) (xy 105.841848 -213.845306)
			(xy 105.83291 -213.866476) (xy 105.823004 -213.888828) (xy 106.036618 -214.293958) (xy 106.060748 -214.29853)
			(xy 106.085667 -214.303641) (xy 106.133677 -214.320441) (xy 106.178536 -214.344419) (xy 106.219176 -214.375006)
			(xy 106.254634 -214.411476) (xy 106.284066 -214.452961) (xy 106.306773 -214.498476) (xy 106.322215 -214.54694)
			(xy 106.330027 -214.597201) (xy 106.330496 -214.622634) (xy 106.329988 -214.648521) (xy 106.321889 -214.699659)
			(xy 106.30589 -214.748899) (xy 106.282384 -214.795031) (xy 106.251952 -214.836918) (xy 106.215342 -214.873528)
			(xy 106.173455 -214.90396) (xy 106.127323 -214.927466) (xy 106.078083 -214.943465) (xy 106.026945 -214.951564)
			(xy 105.975171 -214.951564) (xy 105.924033 -214.943465) (xy 105.874793 -214.927466) (xy 105.828661 -214.90396)
			(xy 105.786774 -214.873528) (xy 105.750164 -214.836918) (xy 105.719732 -214.795031) (xy 105.696226 -214.748899)
			(xy 105.680227 -214.699659) (xy 105.672128 -214.648521) (xy 105.67162 -214.622634) (xy 105.671987 -214.599658)
			(xy 105.6783 -214.554143) (xy 105.690879 -214.509947) (xy 105.699814 -214.488776) (xy 105.70972 -214.466424)
			(xy 105.496106 -214.061294) (xy 105.471976 -214.056722) (xy 105.44705 -214.051639) (xy 105.399036 -214.034839)
			(xy 105.354175 -214.010859) (xy 105.313532 -213.980269) (xy 105.278074 -213.943796) (xy 105.248643 -213.902307)
			(xy 105.225938 -213.856787) (xy 105.2105 -213.808318) (xy 105.202694 -213.758052) (xy 105.202228 -213.732618)
			(xy 103.981504 -213.732618) (xy 103.981153 -213.755595) (xy 103.974832 -213.80111) (xy 103.962248 -213.845306)
			(xy 103.95331 -213.866476) (xy 103.943404 -213.888828) (xy 104.157018 -214.293958) (xy 104.181148 -214.29853)
			(xy 104.206067 -214.303641) (xy 104.254077 -214.320441) (xy 104.298936 -214.344419) (xy 104.339576 -214.375006)
			(xy 104.375034 -214.411476) (xy 104.404466 -214.452961) (xy 104.427173 -214.498476) (xy 104.442615 -214.54694)
			(xy 104.450427 -214.597201) (xy 104.450896 -214.622634) (xy 104.450388 -214.648521) (xy 104.442289 -214.699659)
			(xy 104.42629 -214.748899) (xy 104.402784 -214.795031) (xy 104.372352 -214.836918) (xy 104.335742 -214.873528)
			(xy 104.293855 -214.90396) (xy 104.247723 -214.927466) (xy 104.198483 -214.943465) (xy 104.147345 -214.951564)
			(xy 104.095571 -214.951564) (xy 104.044433 -214.943465) (xy 103.995193 -214.927466) (xy 103.949061 -214.90396)
			(xy 103.907174 -214.873528) (xy 103.870564 -214.836918) (xy 103.840132 -214.795031) (xy 103.816626 -214.748899)
			(xy 103.800627 -214.699659) (xy 103.792528 -214.648521) (xy 103.79202 -214.622634) (xy 103.792387 -214.599658)
			(xy 103.7987 -214.554143) (xy 103.811279 -214.509947) (xy 103.820214 -214.488776) (xy 103.83012 -214.466424)
			(xy 103.616506 -214.061294) (xy 103.592376 -214.056722) (xy 103.56745 -214.051639) (xy 103.519436 -214.034839)
			(xy 103.474575 -214.010859) (xy 103.433932 -213.980269) (xy 103.398474 -213.943796) (xy 103.369043 -213.902307)
			(xy 103.346338 -213.856787) (xy 103.3309 -213.808318) (xy 103.323094 -213.758052) (xy 103.322628 -213.732618)
			(xy 102.101904 -213.732618) (xy 102.101553 -213.755595) (xy 102.095232 -213.80111) (xy 102.082648 -213.845306)
			(xy 102.07371 -213.866476) (xy 102.063804 -213.888828) (xy 102.277418 -214.293958) (xy 102.301548 -214.29853)
			(xy 102.326467 -214.303641) (xy 102.374477 -214.320441) (xy 102.419336 -214.344419) (xy 102.459976 -214.375006)
			(xy 102.495434 -214.411476) (xy 102.524866 -214.452961) (xy 102.547573 -214.498476) (xy 102.563015 -214.54694)
			(xy 102.570827 -214.597201) (xy 102.571296 -214.622634) (xy 102.570788 -214.648521) (xy 102.562689 -214.699659)
			(xy 102.54669 -214.748899) (xy 102.523184 -214.795031) (xy 102.492752 -214.836918) (xy 102.456142 -214.873528)
			(xy 102.414255 -214.90396) (xy 102.368123 -214.927466) (xy 102.318883 -214.943465) (xy 102.267745 -214.951564)
			(xy 102.215971 -214.951564) (xy 102.164833 -214.943465) (xy 102.115593 -214.927466) (xy 102.069461 -214.90396)
			(xy 102.027574 -214.873528) (xy 101.990964 -214.836918) (xy 101.960532 -214.795031) (xy 101.937026 -214.748899)
			(xy 101.921027 -214.699659) (xy 101.912928 -214.648521) (xy 101.91242 -214.622634) (xy 101.912787 -214.599658)
			(xy 101.9191 -214.554143) (xy 101.931679 -214.509947) (xy 101.940614 -214.488776) (xy 101.95052 -214.466424)
			(xy 101.736906 -214.061294) (xy 101.712776 -214.056722) (xy 101.68785 -214.051639) (xy 101.639836 -214.034839)
			(xy 101.594975 -214.010859) (xy 101.554332 -213.980269) (xy 101.518874 -213.943796) (xy 101.489443 -213.902307)
			(xy 101.466738 -213.856787) (xy 101.4513 -213.808318) (xy 101.443494 -213.758052) (xy 101.443028 -213.732618)
			(xy 100.222304 -213.732618) (xy 100.221953 -213.755595) (xy 100.215632 -213.80111) (xy 100.203048 -213.845306)
			(xy 100.19411 -213.866476) (xy 100.184204 -213.888828) (xy 100.397818 -214.293958) (xy 100.421948 -214.29853)
			(xy 100.446867 -214.303641) (xy 100.494877 -214.320441) (xy 100.539736 -214.344419) (xy 100.580376 -214.375006)
			(xy 100.615834 -214.411476) (xy 100.645266 -214.452961) (xy 100.667973 -214.498476) (xy 100.683415 -214.54694)
			(xy 100.691227 -214.597201) (xy 100.691696 -214.622634) (xy 100.691188 -214.648521) (xy 100.683089 -214.699659)
			(xy 100.66709 -214.748899) (xy 100.643584 -214.795031) (xy 100.613152 -214.836918) (xy 100.576542 -214.873528)
			(xy 100.534655 -214.90396) (xy 100.488523 -214.927466) (xy 100.439283 -214.943465) (xy 100.388145 -214.951564)
			(xy 100.336371 -214.951564) (xy 100.285233 -214.943465) (xy 100.235993 -214.927466) (xy 100.189861 -214.90396)
			(xy 100.147974 -214.873528) (xy 100.111364 -214.836918) (xy 100.080932 -214.795031) (xy 100.057426 -214.748899)
			(xy 100.041427 -214.699659) (xy 100.033328 -214.648521) (xy 100.03282 -214.622634) (xy 100.033187 -214.599658)
			(xy 100.0395 -214.554143) (xy 100.052079 -214.509947) (xy 100.061014 -214.488776) (xy 100.07092 -214.466424)
			(xy 99.857306 -214.061294) (xy 99.833176 -214.056722) (xy 99.80825 -214.051639) (xy 99.760236 -214.034839)
			(xy 99.715375 -214.010859) (xy 99.674732 -213.980269) (xy 99.639274 -213.943796) (xy 99.609843 -213.902307)
			(xy 99.587138 -213.856787) (xy 99.5717 -213.808318) (xy 99.563894 -213.758052) (xy 99.563428 -213.732618)
			(xy 98.342704 -213.732618) (xy 98.342353 -213.755595) (xy 98.336032 -213.80111) (xy 98.323448 -213.845306)
			(xy 98.31451 -213.866476) (xy 98.304604 -213.888828) (xy 98.518218 -214.293958) (xy 98.542348 -214.29853)
			(xy 98.567267 -214.303641) (xy 98.615277 -214.320441) (xy 98.660136 -214.344419) (xy 98.700776 -214.375006)
			(xy 98.736234 -214.411476) (xy 98.765666 -214.452961) (xy 98.788373 -214.498476) (xy 98.803815 -214.54694)
			(xy 98.811627 -214.597201) (xy 98.812096 -214.622634) (xy 98.811588 -214.648521) (xy 98.803489 -214.699659)
			(xy 98.78749 -214.748899) (xy 98.763984 -214.795031) (xy 98.733552 -214.836918) (xy 98.696942 -214.873528)
			(xy 98.655055 -214.90396) (xy 98.608923 -214.927466) (xy 98.559683 -214.943465) (xy 98.508545 -214.951564)
			(xy 98.456771 -214.951564) (xy 98.405633 -214.943465) (xy 98.356393 -214.927466) (xy 98.310261 -214.90396)
			(xy 98.268374 -214.873528) (xy 98.231764 -214.836918) (xy 98.201332 -214.795031) (xy 98.177826 -214.748899)
			(xy 98.161827 -214.699659) (xy 98.153728 -214.648521) (xy 98.15322 -214.622634) (xy 98.153587 -214.599658)
			(xy 98.1599 -214.554143) (xy 98.172479 -214.509947) (xy 98.181414 -214.488776) (xy 98.19132 -214.466424)
			(xy 97.977706 -214.061294) (xy 97.953576 -214.056722) (xy 97.92865 -214.051639) (xy 97.880636 -214.034839)
			(xy 97.835775 -214.010859) (xy 97.795132 -213.980269) (xy 97.759674 -213.943796) (xy 97.730243 -213.902307)
			(xy 97.707538 -213.856787) (xy 97.6921 -213.808318) (xy 97.684294 -213.758052) (xy 97.683828 -213.732618)
			(xy 96.463104 -213.732618) (xy 96.462753 -213.755595) (xy 96.456432 -213.80111) (xy 96.443848 -213.845306)
			(xy 96.43491 -213.866476) (xy 96.425004 -213.888828) (xy 96.638618 -214.293958) (xy 96.662748 -214.29853)
			(xy 96.687667 -214.303641) (xy 96.735677 -214.320441) (xy 96.780536 -214.344419) (xy 96.821176 -214.375006)
			(xy 96.856634 -214.411476) (xy 96.886066 -214.452961) (xy 96.908773 -214.498476) (xy 96.924215 -214.54694)
			(xy 96.932027 -214.597201) (xy 96.932496 -214.622634) (xy 96.931988 -214.648521) (xy 96.923889 -214.699659)
			(xy 96.90789 -214.748899) (xy 96.884384 -214.795031) (xy 96.853952 -214.836918) (xy 96.817342 -214.873528)
			(xy 96.775455 -214.90396) (xy 96.729323 -214.927466) (xy 96.680083 -214.943465) (xy 96.628945 -214.951564)
			(xy 96.577171 -214.951564) (xy 96.526033 -214.943465) (xy 96.476793 -214.927466) (xy 96.430661 -214.90396)
			(xy 96.388774 -214.873528) (xy 96.352164 -214.836918) (xy 96.321732 -214.795031) (xy 96.298226 -214.748899)
			(xy 96.282227 -214.699659) (xy 96.274128 -214.648521) (xy 96.27362 -214.622634) (xy 96.273987 -214.599658)
			(xy 96.2803 -214.554143) (xy 96.292879 -214.509947) (xy 96.301814 -214.488776) (xy 96.31172 -214.466424)
			(xy 96.098106 -214.061294) (xy 96.073976 -214.056722) (xy 96.04905 -214.051639) (xy 96.001036 -214.034839)
			(xy 95.956175 -214.010859) (xy 95.915532 -213.980269) (xy 95.880074 -213.943796) (xy 95.850643 -213.902307)
			(xy 95.827938 -213.856787) (xy 95.8125 -213.808318) (xy 95.804694 -213.758052) (xy 95.804228 -213.732618)
			(xy 94.583504 -213.732618) (xy 94.583153 -213.755595) (xy 94.576832 -213.80111) (xy 94.564248 -213.845306)
			(xy 94.55531 -213.866476) (xy 94.545404 -213.888828) (xy 94.759018 -214.293958) (xy 94.783148 -214.29853)
			(xy 94.808067 -214.303641) (xy 94.856077 -214.320441) (xy 94.900936 -214.344419) (xy 94.941576 -214.375006)
			(xy 94.977034 -214.411476) (xy 95.006466 -214.452961) (xy 95.029173 -214.498476) (xy 95.044615 -214.54694)
			(xy 95.052427 -214.597201) (xy 95.052896 -214.622634) (xy 95.052388 -214.648521) (xy 95.044289 -214.699659)
			(xy 95.02829 -214.748899) (xy 95.004784 -214.795031) (xy 94.974352 -214.836918) (xy 94.937742 -214.873528)
			(xy 94.895855 -214.90396) (xy 94.849723 -214.927466) (xy 94.800483 -214.943465) (xy 94.749345 -214.951564)
			(xy 94.697571 -214.951564) (xy 94.646433 -214.943465) (xy 94.597193 -214.927466) (xy 94.551061 -214.90396)
			(xy 94.509174 -214.873528) (xy 94.472564 -214.836918) (xy 94.442132 -214.795031) (xy 94.418626 -214.748899)
			(xy 94.402627 -214.699659) (xy 94.394528 -214.648521) (xy 94.39402 -214.622634) (xy 94.394387 -214.599658)
			(xy 94.4007 -214.554143) (xy 94.413279 -214.509947) (xy 94.422214 -214.488776) (xy 94.43212 -214.466424)
			(xy 94.218506 -214.061294) (xy 94.194376 -214.056722) (xy 94.16945 -214.051639) (xy 94.121436 -214.034839)
			(xy 94.076575 -214.010859) (xy 94.035932 -213.980269) (xy 94.000474 -213.943796) (xy 93.971043 -213.902307)
			(xy 93.948338 -213.856787) (xy 93.9329 -213.808318) (xy 93.925094 -213.758052) (xy 93.924628 -213.732618)
			(xy 92.703904 -213.732618) (xy 92.703553 -213.755595) (xy 92.697232 -213.80111) (xy 92.684648 -213.845306)
			(xy 92.67571 -213.866476) (xy 92.665804 -213.888828) (xy 92.879418 -214.293958) (xy 92.903548 -214.29853)
			(xy 92.928467 -214.303641) (xy 92.976477 -214.320441) (xy 93.021336 -214.344419) (xy 93.061976 -214.375006)
			(xy 93.097434 -214.411476) (xy 93.126866 -214.452961) (xy 93.149573 -214.498476) (xy 93.165015 -214.54694)
			(xy 93.172827 -214.597201) (xy 93.173296 -214.622634) (xy 93.172788 -214.648521) (xy 93.164689 -214.699659)
			(xy 93.14869 -214.748899) (xy 93.125184 -214.795031) (xy 93.094752 -214.836918) (xy 93.058142 -214.873528)
			(xy 93.016255 -214.90396) (xy 92.970123 -214.927466) (xy 92.920883 -214.943465) (xy 92.869745 -214.951564)
			(xy 92.817971 -214.951564) (xy 92.766833 -214.943465) (xy 92.717593 -214.927466) (xy 92.671461 -214.90396)
			(xy 92.629574 -214.873528) (xy 92.592964 -214.836918) (xy 92.562532 -214.795031) (xy 92.539026 -214.748899)
			(xy 92.523027 -214.699659) (xy 92.514928 -214.648521) (xy 92.51442 -214.622634) (xy 92.514787 -214.599658)
			(xy 92.5211 -214.554143) (xy 92.533679 -214.509947) (xy 92.542614 -214.488776) (xy 92.55252 -214.466424)
			(xy 92.338906 -214.061294) (xy 92.314776 -214.056722) (xy 92.28985 -214.051639) (xy 92.241836 -214.034839)
			(xy 92.196975 -214.010859) (xy 92.156332 -213.980269) (xy 92.120874 -213.943796) (xy 92.091443 -213.902307)
			(xy 92.068738 -213.856787) (xy 92.0533 -213.808318) (xy 92.045494 -213.758052) (xy 92.045028 -213.732618)
			(xy 90.824304 -213.732618) (xy 90.823953 -213.755595) (xy 90.817632 -213.80111) (xy 90.805048 -213.845306)
			(xy 90.79611 -213.866476) (xy 90.786204 -213.888828) (xy 90.999818 -214.293958) (xy 91.023948 -214.29853)
			(xy 91.048867 -214.303641) (xy 91.096877 -214.320441) (xy 91.141736 -214.344419) (xy 91.182376 -214.375006)
			(xy 91.217834 -214.411476) (xy 91.247266 -214.452961) (xy 91.269973 -214.498476) (xy 91.285415 -214.54694)
			(xy 91.293227 -214.597201) (xy 91.293696 -214.622634) (xy 91.293188 -214.648521) (xy 91.285089 -214.699659)
			(xy 91.26909 -214.748899) (xy 91.245584 -214.795031) (xy 91.215152 -214.836918) (xy 91.178542 -214.873528)
			(xy 91.136655 -214.90396) (xy 91.090523 -214.927466) (xy 91.041283 -214.943465) (xy 90.990145 -214.951564)
			(xy 90.938371 -214.951564) (xy 90.887233 -214.943465) (xy 90.837993 -214.927466) (xy 90.791861 -214.90396)
			(xy 90.749974 -214.873528) (xy 90.713364 -214.836918) (xy 90.682932 -214.795031) (xy 90.659426 -214.748899)
			(xy 90.643427 -214.699659) (xy 90.635328 -214.648521) (xy 90.63482 -214.622634) (xy 90.635187 -214.599658)
			(xy 90.6415 -214.554143) (xy 90.654079 -214.509947) (xy 90.663014 -214.488776) (xy 90.67292 -214.466424)
			(xy 90.459306 -214.061294) (xy 90.435176 -214.056722) (xy 90.41025 -214.051639) (xy 90.362236 -214.034839)
			(xy 90.317375 -214.010859) (xy 90.276732 -213.980269) (xy 90.241274 -213.943796) (xy 90.211843 -213.902307)
			(xy 90.189138 -213.856787) (xy 90.1737 -213.808318) (xy 90.165894 -213.758052) (xy 90.165428 -213.732618)
			(xy 2.509012 -213.732618) (xy 2.509012 -215.436704) (xy 88.28532 -215.436704) (xy 88.285828 -215.410797)
			(xy 88.293934 -215.35962) (xy 88.309946 -215.310341) (xy 88.333469 -215.264174) (xy 88.363925 -215.222255)
			(xy 88.400563 -215.185617) (xy 88.442482 -215.155161) (xy 88.488649 -215.131638) (xy 88.537928 -215.115626)
			(xy 88.589105 -215.10752) (xy 88.640919 -215.10752) (xy 88.692096 -215.115626) (xy 88.741375 -215.131638)
			(xy 88.787542 -215.155161) (xy 88.829461 -215.185617) (xy 88.866099 -215.222255) (xy 88.896555 -215.264174)
			(xy 88.920078 -215.310341) (xy 88.93609 -215.35962) (xy 88.944196 -215.410797) (xy 88.944704 -215.436704)
			(xy 89.22512 -215.436704) (xy 89.225629 -215.41136) (xy 89.2334 -215.36127) (xy 89.248746 -215.31296)
			(xy 89.271303 -215.267567) (xy 89.300542 -215.226161) (xy 89.335773 -215.189717) (xy 89.376165 -215.159094)
			(xy 89.420769 -215.135013) (xy 89.468532 -215.118041) (xy 89.493344 -215.112854) (xy 89.516204 -215.108536)
			(xy 89.721182 -214.753444) (xy 89.713308 -214.7316) (xy 89.704729 -214.705181) (xy 89.695532 -214.650406)
			(xy 89.69502 -214.622634) (xy 89.695528 -214.596747) (xy 89.703627 -214.545609) (xy 89.719626 -214.496369)
			(xy 89.743132 -214.450237) (xy 89.773564 -214.40835) (xy 89.810174 -214.37174) (xy 89.852061 -214.341308)
			(xy 89.898193 -214.317802) (xy 89.947433 -214.301803) (xy 89.998571 -214.293704) (xy 90.050345 -214.293704)
			(xy 90.101483 -214.301803) (xy 90.150723 -214.317802) (xy 90.196855 -214.341308) (xy 90.238742 -214.37174)
			(xy 90.275352 -214.40835) (xy 90.305784 -214.450237) (xy 90.32929 -214.496369) (xy 90.345289 -214.545609)
			(xy 90.353388 -214.596747) (xy 90.353896 -214.622634) (xy 90.353447 -214.64797) (xy 90.34569 -214.698044)
			(xy 90.330363 -214.746341) (xy 90.307827 -214.791726) (xy 90.278612 -214.833128) (xy 90.243408 -214.869572)
			(xy 90.203042 -214.900202) (xy 90.158465 -214.924296) (xy 90.110727 -214.941286) (xy 90.085926 -214.946484)
			(xy 90.063066 -214.950802) (xy 89.858088 -215.305894) (xy 89.865962 -215.327738) (xy 89.87461 -215.354146)
			(xy 89.883929 -215.408922) (xy 89.884504 -215.436704) (xy 91.10472 -215.436704) (xy 91.105229 -215.41136)
			(xy 91.113 -215.36127) (xy 91.128346 -215.31296) (xy 91.150903 -215.267567) (xy 91.180142 -215.226161)
			(xy 91.215373 -215.189717) (xy 91.255765 -215.159094) (xy 91.300369 -215.135013) (xy 91.348132 -215.118041)
			(xy 91.372944 -215.112854) (xy 91.395804 -215.108536) (xy 91.600782 -214.753444) (xy 91.592908 -214.7316)
			(xy 91.584329 -214.705181) (xy 91.575132 -214.650406) (xy 91.57462 -214.622634) (xy 91.575128 -214.596747)
			(xy 91.583227 -214.545609) (xy 91.599226 -214.496369) (xy 91.622732 -214.450237) (xy 91.653164 -214.40835)
			(xy 91.689774 -214.37174) (xy 91.731661 -214.341308) (xy 91.777793 -214.317802) (xy 91.827033 -214.301803)
			(xy 91.878171 -214.293704) (xy 91.929945 -214.293704) (xy 91.981083 -214.301803) (xy 92.030323 -214.317802)
			(xy 92.076455 -214.341308) (xy 92.118342 -214.37174) (xy 92.154952 -214.40835) (xy 92.185384 -214.450237)
			(xy 92.20889 -214.496369) (xy 92.224889 -214.545609) (xy 92.232988 -214.596747) (xy 92.233496 -214.622634)
			(xy 92.233047 -214.64797) (xy 92.22529 -214.698044) (xy 92.209963 -214.746341) (xy 92.187427 -214.791726)
			(xy 92.158212 -214.833128) (xy 92.123008 -214.869572) (xy 92.082642 -214.900202) (xy 92.038065 -214.924296)
			(xy 91.990327 -214.941286) (xy 91.965526 -214.946484) (xy 91.942666 -214.950802) (xy 91.737688 -215.305894)
			(xy 91.745562 -215.327738) (xy 91.75421 -215.354146) (xy 91.763529 -215.408922) (xy 91.764104 -215.436704)
			(xy 92.98432 -215.436704) (xy 92.984829 -215.41136) (xy 92.9926 -215.36127) (xy 93.007946 -215.31296)
			(xy 93.030503 -215.267567) (xy 93.059742 -215.226161) (xy 93.094973 -215.189717) (xy 93.135365 -215.159094)
			(xy 93.179969 -215.135013) (xy 93.227732 -215.118041) (xy 93.252544 -215.112854) (xy 93.275404 -215.108536)
			(xy 93.480382 -214.753444) (xy 93.472508 -214.7316) (xy 93.463929 -214.705181) (xy 93.454732 -214.650406)
			(xy 93.45422 -214.622634) (xy 93.454728 -214.596747) (xy 93.462827 -214.545609) (xy 93.478826 -214.496369)
			(xy 93.502332 -214.450237) (xy 93.532764 -214.40835) (xy 93.569374 -214.37174) (xy 93.611261 -214.341308)
			(xy 93.657393 -214.317802) (xy 93.706633 -214.301803) (xy 93.757771 -214.293704) (xy 93.809545 -214.293704)
			(xy 93.860683 -214.301803) (xy 93.909923 -214.317802) (xy 93.956055 -214.341308) (xy 93.997942 -214.37174)
			(xy 94.034552 -214.40835) (xy 94.064984 -214.450237) (xy 94.08849 -214.496369) (xy 94.104489 -214.545609)
			(xy 94.112588 -214.596747) (xy 94.113096 -214.622634) (xy 94.112647 -214.64797) (xy 94.10489 -214.698044)
			(xy 94.089563 -214.746341) (xy 94.067027 -214.791726) (xy 94.037812 -214.833128) (xy 94.002608 -214.869572)
			(xy 93.962242 -214.900202) (xy 93.917665 -214.924296) (xy 93.869927 -214.941286) (xy 93.845126 -214.946484)
			(xy 93.822266 -214.950802) (xy 93.617288 -215.305894) (xy 93.625162 -215.327738) (xy 93.63381 -215.354146)
			(xy 93.643129 -215.408922) (xy 93.643704 -215.436704) (xy 94.86392 -215.436704) (xy 94.864429 -215.41136)
			(xy 94.8722 -215.36127) (xy 94.887546 -215.31296) (xy 94.910103 -215.267567) (xy 94.939342 -215.226161)
			(xy 94.974573 -215.189717) (xy 95.014965 -215.159094) (xy 95.059569 -215.135013) (xy 95.107332 -215.118041)
			(xy 95.132144 -215.112854) (xy 95.155004 -215.108536) (xy 95.359982 -214.753444) (xy 95.352108 -214.7316)
			(xy 95.343529 -214.705181) (xy 95.334332 -214.650406) (xy 95.33382 -214.622634) (xy 95.334328 -214.596747)
			(xy 95.342427 -214.545609) (xy 95.358426 -214.496369) (xy 95.381932 -214.450237) (xy 95.412364 -214.40835)
			(xy 95.448974 -214.37174) (xy 95.490861 -214.341308) (xy 95.536993 -214.317802) (xy 95.586233 -214.301803)
			(xy 95.637371 -214.293704) (xy 95.689145 -214.293704) (xy 95.740283 -214.301803) (xy 95.789523 -214.317802)
			(xy 95.835655 -214.341308) (xy 95.877542 -214.37174) (xy 95.914152 -214.40835) (xy 95.944584 -214.450237)
			(xy 95.96809 -214.496369) (xy 95.984089 -214.545609) (xy 95.992188 -214.596747) (xy 95.992696 -214.622634)
			(xy 95.992247 -214.64797) (xy 95.98449 -214.698044) (xy 95.969163 -214.746341) (xy 95.946627 -214.791726)
			(xy 95.917412 -214.833128) (xy 95.882208 -214.869572) (xy 95.841842 -214.900202) (xy 95.797265 -214.924296)
			(xy 95.749527 -214.941286) (xy 95.724726 -214.946484) (xy 95.701866 -214.950802) (xy 95.496888 -215.305894)
			(xy 95.504762 -215.327738) (xy 95.51341 -215.354146) (xy 95.522729 -215.408922) (xy 95.523304 -215.436704)
			(xy 96.74352 -215.436704) (xy 96.744029 -215.41136) (xy 96.7518 -215.36127) (xy 96.767146 -215.31296)
			(xy 96.789703 -215.267567) (xy 96.818942 -215.226161) (xy 96.854173 -215.189717) (xy 96.894565 -215.159094)
			(xy 96.939169 -215.135013) (xy 96.986932 -215.118041) (xy 97.011744 -215.112854) (xy 97.034604 -215.108536)
			(xy 97.239582 -214.753444) (xy 97.231708 -214.7316) (xy 97.223129 -214.705181) (xy 97.213932 -214.650406)
			(xy 97.21342 -214.622634) (xy 97.213928 -214.596747) (xy 97.222027 -214.545609) (xy 97.238026 -214.496369)
			(xy 97.261532 -214.450237) (xy 97.291964 -214.40835) (xy 97.328574 -214.37174) (xy 97.370461 -214.341308)
			(xy 97.416593 -214.317802) (xy 97.465833 -214.301803) (xy 97.516971 -214.293704) (xy 97.568745 -214.293704)
			(xy 97.619883 -214.301803) (xy 97.669123 -214.317802) (xy 97.715255 -214.341308) (xy 97.757142 -214.37174)
			(xy 97.793752 -214.40835) (xy 97.824184 -214.450237) (xy 97.84769 -214.496369) (xy 97.863689 -214.545609)
			(xy 97.871788 -214.596747) (xy 97.872296 -214.622634) (xy 97.871847 -214.64797) (xy 97.86409 -214.698044)
			(xy 97.848763 -214.746341) (xy 97.826227 -214.791726) (xy 97.797012 -214.833128) (xy 97.761808 -214.869572)
			(xy 97.721442 -214.900202) (xy 97.676865 -214.924296) (xy 97.629127 -214.941286) (xy 97.604326 -214.946484)
			(xy 97.581466 -214.950802) (xy 97.376488 -215.305894) (xy 97.384362 -215.327738) (xy 97.39301 -215.354146)
			(xy 97.402329 -215.408922) (xy 97.402904 -215.436704) (xy 98.62312 -215.436704) (xy 98.623629 -215.41136)
			(xy 98.6314 -215.36127) (xy 98.646746 -215.31296) (xy 98.669303 -215.267567) (xy 98.698542 -215.226161)
			(xy 98.733773 -215.189717) (xy 98.774165 -215.159094) (xy 98.818769 -215.135013) (xy 98.866532 -215.118041)
			(xy 98.891344 -215.112854) (xy 98.914204 -215.108536) (xy 99.119182 -214.753444) (xy 99.111308 -214.7316)
			(xy 99.102729 -214.705181) (xy 99.093532 -214.650406) (xy 99.09302 -214.622634) (xy 99.093528 -214.596747)
			(xy 99.101627 -214.545609) (xy 99.117626 -214.496369) (xy 99.141132 -214.450237) (xy 99.171564 -214.40835)
			(xy 99.208174 -214.37174) (xy 99.250061 -214.341308) (xy 99.296193 -214.317802) (xy 99.345433 -214.301803)
			(xy 99.396571 -214.293704) (xy 99.448345 -214.293704) (xy 99.499483 -214.301803) (xy 99.548723 -214.317802)
			(xy 99.594855 -214.341308) (xy 99.636742 -214.37174) (xy 99.673352 -214.40835) (xy 99.703784 -214.450237)
			(xy 99.72729 -214.496369) (xy 99.743289 -214.545609) (xy 99.751388 -214.596747) (xy 99.751896 -214.622634)
			(xy 99.751447 -214.64797) (xy 99.74369 -214.698044) (xy 99.728363 -214.746341) (xy 99.705827 -214.791726)
			(xy 99.676612 -214.833128) (xy 99.641408 -214.869572) (xy 99.601042 -214.900202) (xy 99.556465 -214.924296)
			(xy 99.508727 -214.941286) (xy 99.483926 -214.946484) (xy 99.461066 -214.950802) (xy 99.256088 -215.305894)
			(xy 99.263962 -215.327738) (xy 99.27261 -215.354146) (xy 99.281929 -215.408922) (xy 99.282504 -215.436704)
			(xy 100.50272 -215.436704) (xy 100.503229 -215.41136) (xy 100.511 -215.36127) (xy 100.526346 -215.31296)
			(xy 100.548903 -215.267567) (xy 100.578142 -215.226161) (xy 100.613373 -215.189717) (xy 100.653765 -215.159094)
			(xy 100.698369 -215.135013) (xy 100.746132 -215.118041) (xy 100.770944 -215.112854) (xy 100.793804 -215.108536)
			(xy 100.998782 -214.753444) (xy 100.990908 -214.7316) (xy 100.982329 -214.705181) (xy 100.973132 -214.650406)
			(xy 100.97262 -214.622634) (xy 100.973128 -214.596747) (xy 100.981227 -214.545609) (xy 100.997226 -214.496369)
			(xy 101.020732 -214.450237) (xy 101.051164 -214.40835) (xy 101.087774 -214.37174) (xy 101.129661 -214.341308)
			(xy 101.175793 -214.317802) (xy 101.225033 -214.301803) (xy 101.276171 -214.293704) (xy 101.327945 -214.293704)
			(xy 101.379083 -214.301803) (xy 101.428323 -214.317802) (xy 101.474455 -214.341308) (xy 101.516342 -214.37174)
			(xy 101.552952 -214.40835) (xy 101.583384 -214.450237) (xy 101.60689 -214.496369) (xy 101.622889 -214.545609)
			(xy 101.630988 -214.596747) (xy 101.631496 -214.622634) (xy 101.631047 -214.64797) (xy 101.62329 -214.698044)
			(xy 101.607963 -214.746341) (xy 101.585427 -214.791726) (xy 101.556212 -214.833128) (xy 101.521008 -214.869572)
			(xy 101.480642 -214.900202) (xy 101.436065 -214.924296) (xy 101.388327 -214.941286) (xy 101.363526 -214.946484)
			(xy 101.340666 -214.950802) (xy 101.135688 -215.305894) (xy 101.143562 -215.327738) (xy 101.15221 -215.354146)
			(xy 101.161529 -215.408922) (xy 101.162104 -215.436704) (xy 102.38232 -215.436704) (xy 102.382829 -215.41136)
			(xy 102.3906 -215.36127) (xy 102.405946 -215.31296) (xy 102.428503 -215.267567) (xy 102.457742 -215.226161)
			(xy 102.492973 -215.189717) (xy 102.533365 -215.159094) (xy 102.577969 -215.135013) (xy 102.625732 -215.118041)
			(xy 102.650544 -215.112854) (xy 102.673404 -215.108536) (xy 102.878382 -214.753444) (xy 102.870508 -214.7316)
			(xy 102.861929 -214.705181) (xy 102.852732 -214.650406) (xy 102.85222 -214.622634) (xy 102.852728 -214.596747)
			(xy 102.860827 -214.545609) (xy 102.876826 -214.496369) (xy 102.900332 -214.450237) (xy 102.930764 -214.40835)
			(xy 102.967374 -214.37174) (xy 103.009261 -214.341308) (xy 103.055393 -214.317802) (xy 103.104633 -214.301803)
			(xy 103.155771 -214.293704) (xy 103.207545 -214.293704) (xy 103.258683 -214.301803) (xy 103.307923 -214.317802)
			(xy 103.354055 -214.341308) (xy 103.395942 -214.37174) (xy 103.432552 -214.40835) (xy 103.462984 -214.450237)
			(xy 103.48649 -214.496369) (xy 103.502489 -214.545609) (xy 103.510588 -214.596747) (xy 103.511096 -214.622634)
			(xy 103.510647 -214.64797) (xy 103.50289 -214.698044) (xy 103.487563 -214.746341) (xy 103.465027 -214.791726)
			(xy 103.435812 -214.833128) (xy 103.400608 -214.869572) (xy 103.360242 -214.900202) (xy 103.315665 -214.924296)
			(xy 103.267927 -214.941286) (xy 103.243126 -214.946484) (xy 103.220266 -214.950802) (xy 103.015288 -215.305894)
			(xy 103.023162 -215.327738) (xy 103.03181 -215.354146) (xy 103.041129 -215.408922) (xy 103.041704 -215.436704)
			(xy 104.26192 -215.436704) (xy 104.262429 -215.41136) (xy 104.2702 -215.36127) (xy 104.285546 -215.31296)
			(xy 104.308103 -215.267567) (xy 104.337342 -215.226161) (xy 104.372573 -215.189717) (xy 104.412965 -215.159094)
			(xy 104.457569 -215.135013) (xy 104.505332 -215.118041) (xy 104.530144 -215.112854) (xy 104.553004 -215.108536)
			(xy 104.757982 -214.753444) (xy 104.750108 -214.7316) (xy 104.741529 -214.705181) (xy 104.732332 -214.650406)
			(xy 104.73182 -214.622634) (xy 104.732328 -214.596747) (xy 104.740427 -214.545609) (xy 104.756426 -214.496369)
			(xy 104.779932 -214.450237) (xy 104.810364 -214.40835) (xy 104.846974 -214.37174) (xy 104.888861 -214.341308)
			(xy 104.934993 -214.317802) (xy 104.984233 -214.301803) (xy 105.035371 -214.293704) (xy 105.087145 -214.293704)
			(xy 105.138283 -214.301803) (xy 105.187523 -214.317802) (xy 105.233655 -214.341308) (xy 105.275542 -214.37174)
			(xy 105.312152 -214.40835) (xy 105.342584 -214.450237) (xy 105.36609 -214.496369) (xy 105.382089 -214.545609)
			(xy 105.390188 -214.596747) (xy 105.390696 -214.622634) (xy 105.390247 -214.64797) (xy 105.38249 -214.698044)
			(xy 105.367163 -214.746341) (xy 105.344627 -214.791726) (xy 105.315412 -214.833128) (xy 105.280208 -214.869572)
			(xy 105.239842 -214.900202) (xy 105.195265 -214.924296) (xy 105.147527 -214.941286) (xy 105.122726 -214.946484)
			(xy 105.099866 -214.950802) (xy 104.894888 -215.305894) (xy 104.902762 -215.327738) (xy 104.91141 -215.354146)
			(xy 104.920729 -215.408922) (xy 104.921304 -215.436704) (xy 106.14152 -215.436704) (xy 106.142029 -215.41136)
			(xy 106.1498 -215.36127) (xy 106.165146 -215.31296) (xy 106.187703 -215.267567) (xy 106.216942 -215.226161)
			(xy 106.252173 -215.189717) (xy 106.292565 -215.159094) (xy 106.337169 -215.135013) (xy 106.384932 -215.118041)
			(xy 106.409744 -215.112854) (xy 106.432604 -215.108536) (xy 106.637582 -214.753444) (xy 106.629708 -214.7316)
			(xy 106.621129 -214.705181) (xy 106.611932 -214.650406) (xy 106.61142 -214.622634) (xy 106.611928 -214.596747)
			(xy 106.620027 -214.545609) (xy 106.636026 -214.496369) (xy 106.659532 -214.450237) (xy 106.689964 -214.40835)
			(xy 106.726574 -214.37174) (xy 106.768461 -214.341308) (xy 106.814593 -214.317802) (xy 106.863833 -214.301803)
			(xy 106.914971 -214.293704) (xy 106.966745 -214.293704) (xy 107.017883 -214.301803) (xy 107.067123 -214.317802)
			(xy 107.113255 -214.341308) (xy 107.155142 -214.37174) (xy 107.191752 -214.40835) (xy 107.222184 -214.450237)
			(xy 107.24569 -214.496369) (xy 107.261689 -214.545609) (xy 107.269788 -214.596747) (xy 107.270296 -214.622634)
			(xy 107.269847 -214.64797) (xy 107.26209 -214.698044) (xy 107.246763 -214.746341) (xy 107.224227 -214.791726)
			(xy 107.195012 -214.833128) (xy 107.159808 -214.869572) (xy 107.119442 -214.900202) (xy 107.074865 -214.924296)
			(xy 107.027127 -214.941286) (xy 107.002326 -214.946484) (xy 106.979466 -214.950802) (xy 106.774488 -215.305894)
			(xy 106.782362 -215.327738) (xy 106.79101 -215.354146) (xy 106.800329 -215.408922) (xy 106.800904 -215.436704)
			(xy 108.02112 -215.436704) (xy 108.021629 -215.41136) (xy 108.0294 -215.36127) (xy 108.044746 -215.31296)
			(xy 108.067303 -215.267567) (xy 108.096542 -215.226161) (xy 108.131773 -215.189717) (xy 108.172165 -215.159094)
			(xy 108.216769 -215.135013) (xy 108.264532 -215.118041) (xy 108.289344 -215.112854) (xy 108.312204 -215.108536)
			(xy 108.517182 -214.753444) (xy 108.509308 -214.7316) (xy 108.500729 -214.705181) (xy 108.491532 -214.650406)
			(xy 108.49102 -214.622634) (xy 108.491528 -214.596747) (xy 108.499627 -214.545609) (xy 108.515626 -214.496369)
			(xy 108.539132 -214.450237) (xy 108.569564 -214.40835) (xy 108.606174 -214.37174) (xy 108.648061 -214.341308)
			(xy 108.694193 -214.317802) (xy 108.743433 -214.301803) (xy 108.794571 -214.293704) (xy 108.846345 -214.293704)
			(xy 108.897483 -214.301803) (xy 108.946723 -214.317802) (xy 108.992855 -214.341308) (xy 109.034742 -214.37174)
			(xy 109.071352 -214.40835) (xy 109.101784 -214.450237) (xy 109.12529 -214.496369) (xy 109.141289 -214.545609)
			(xy 109.14142 -214.546434) (xy 110.371128 -214.546434) (xy 110.371636 -214.520547) (xy 110.379735 -214.469409)
			(xy 110.395734 -214.420169) (xy 110.41924 -214.374037) (xy 110.449672 -214.33215) (xy 110.486282 -214.29554)
			(xy 110.528169 -214.265108) (xy 110.574301 -214.241602) (xy 110.623541 -214.225603) (xy 110.674679 -214.217504)
			(xy 110.726453 -214.217504) (xy 110.777591 -214.225603) (xy 110.826831 -214.241602) (xy 110.872963 -214.265108)
			(xy 110.91485 -214.29554) (xy 110.95146 -214.33215) (xy 110.981892 -214.374037) (xy 111.005398 -214.420169)
			(xy 111.021397 -214.469409) (xy 111.029496 -214.520547) (xy 111.030004 -214.546434) (xy 111.030004 -214.546942)
			(xy 111.029596 -214.56979) (xy 111.029246 -214.572283) (xy 112.250803 -214.572283) (xy 112.250803 -214.520517)
			(xy 112.258901 -214.469389) (xy 112.274896 -214.420157) (xy 112.298395 -214.374033) (xy 112.32882 -214.332153)
			(xy 112.365421 -214.295547) (xy 112.407297 -214.265117) (xy 112.453418 -214.241612) (xy 112.502648 -214.22561)
			(xy 112.553775 -214.217507) (xy 112.579658 -214.216996) (xy 112.605169 -214.217509) (xy 112.655581 -214.225363)
			(xy 112.704182 -214.24089) (xy 112.749811 -214.263719) (xy 112.791377 -214.293306) (xy 112.827889 -214.328944)
			(xy 112.843564 -214.349076) (xy 113.255552 -214.349076) (xy 113.271247 -214.328958) (xy 113.307753 -214.293314)
			(xy 113.349314 -214.263719) (xy 113.394938 -214.24088) (xy 113.443536 -214.225342) (xy 113.493947 -214.217476)
			(xy 113.519458 -214.216996) (xy 113.545352 -214.217406) (xy 113.596504 -214.225502) (xy 113.645759 -214.2415)
			(xy 113.691905 -214.265008) (xy 113.733805 -214.295445) (xy 113.770428 -214.332063) (xy 113.80087 -214.373959)
			(xy 113.824384 -214.420102) (xy 113.840388 -214.469355) (xy 113.848491 -214.520506) (xy 113.848491 -214.572294)
			(xy 113.840388 -214.623445) (xy 113.824384 -214.672698) (xy 113.80087 -214.718841) (xy 113.770428 -214.760737)
			(xy 113.733805 -214.797355) (xy 113.691905 -214.827792) (xy 113.645759 -214.8513) (xy 113.596504 -214.867298)
			(xy 113.545352 -214.875394) (xy 113.519458 -214.875872) (xy 113.493944 -214.875433) (xy 113.443527 -214.867566)
			(xy 113.394925 -214.852025) (xy 113.349296 -214.829181) (xy 113.307732 -214.799581) (xy 113.271224 -214.763931)
			(xy 113.255552 -214.743792) (xy 112.843564 -214.743792) (xy 112.827909 -214.763943) (xy 112.791396 -214.799586)
			(xy 112.749827 -214.829178) (xy 112.704195 -214.852012) (xy 112.655589 -214.867542) (xy 112.605171 -214.875398)
			(xy 112.579658 -214.875872) (xy 112.553775 -214.875293) (xy 112.502648 -214.86719) (xy 112.453418 -214.851188)
			(xy 112.407297 -214.827683) (xy 112.365421 -214.797253) (xy 112.32882 -214.760647) (xy 112.298395 -214.718767)
			(xy 112.274896 -214.672643) (xy 112.258901 -214.623411) (xy 112.250803 -214.572283) (xy 111.029246 -214.572283)
			(xy 111.023246 -214.615045) (xy 111.010702 -214.658987) (xy 111.00181 -214.680038) (xy 110.991904 -214.702644)
			(xy 111.205772 -215.108028) (xy 111.229902 -215.1126) (xy 111.254835 -215.117694) (xy 111.302873 -215.134477)
			(xy 111.347761 -215.158443) (xy 111.388433 -215.189024) (xy 111.423922 -215.225492) (xy 111.453384 -215.266981)
			(xy 111.47612 -215.312505) (xy 111.491589 -215.360982) (xy 111.499424 -215.411261) (xy 111.499904 -215.436704)
			(xy 113.65992 -215.436704) (xy 113.660429 -215.41136) (xy 113.6682 -215.36127) (xy 113.683546 -215.31296)
			(xy 113.706103 -215.267567) (xy 113.735342 -215.226161) (xy 113.770573 -215.189717) (xy 113.810965 -215.159094)
			(xy 113.855569 -215.135013) (xy 113.903332 -215.118041) (xy 113.928144 -215.112854) (xy 113.951004 -215.108536)
			(xy 114.156236 -214.753444) (xy 114.148362 -214.731346) (xy 114.139733 -214.704999) (xy 114.130411 -214.650352)
			(xy 114.12982 -214.622634) (xy 114.130328 -214.596727) (xy 114.138434 -214.54555) (xy 114.154446 -214.496271)
			(xy 114.177969 -214.450104) (xy 114.208425 -214.408185) (xy 114.245063 -214.371547) (xy 114.286982 -214.341091)
			(xy 114.333149 -214.317568) (xy 114.382428 -214.301556) (xy 114.433605 -214.29345) (xy 114.485419 -214.29345)
			(xy 114.536596 -214.301556) (xy 114.585875 -214.317568) (xy 114.632042 -214.341091) (xy 114.673961 -214.371547)
			(xy 114.710599 -214.408185) (xy 114.741055 -214.450104) (xy 114.764578 -214.496271) (xy 114.78059 -214.54555)
			(xy 114.788696 -214.596727) (xy 114.789204 -214.622634) (xy 114.78871 -214.647978) (xy 114.780934 -214.698068)
			(xy 114.765584 -214.746377) (xy 114.743024 -214.791769) (xy 114.713783 -214.833174) (xy 114.678552 -214.869617)
			(xy 114.638158 -214.90024) (xy 114.593555 -214.924322) (xy 114.545792 -214.941296) (xy 114.52098 -214.946484)
			(xy 114.49812 -214.950802) (xy 114.292888 -215.305894) (xy 114.300762 -215.327992) (xy 114.309397 -215.354337)
			(xy 114.318716 -215.408986) (xy 114.319304 -215.436704) (xy 115.53952 -215.436704) (xy 115.540029 -215.41136)
			(xy 115.5478 -215.36127) (xy 115.563146 -215.31296) (xy 115.585703 -215.267567) (xy 115.614942 -215.226161)
			(xy 115.650173 -215.189717) (xy 115.690565 -215.159094) (xy 115.735169 -215.135013) (xy 115.782932 -215.118041)
			(xy 115.807744 -215.112854) (xy 115.830604 -215.108536) (xy 116.035582 -214.753444) (xy 116.027708 -214.7316)
			(xy 116.019129 -214.705181) (xy 116.009932 -214.650406) (xy 116.00942 -214.622634) (xy 116.009928 -214.596747)
			(xy 116.018027 -214.545609) (xy 116.034026 -214.496369) (xy 116.057532 -214.450237) (xy 116.087964 -214.40835)
			(xy 116.124574 -214.37174) (xy 116.166461 -214.341308) (xy 116.212593 -214.317802) (xy 116.261833 -214.301803)
			(xy 116.312971 -214.293704) (xy 116.364745 -214.293704) (xy 116.415883 -214.301803) (xy 116.465123 -214.317802)
			(xy 116.511255 -214.341308) (xy 116.553142 -214.37174) (xy 116.589752 -214.40835) (xy 116.620184 -214.450237)
			(xy 116.64369 -214.496369) (xy 116.659689 -214.545609) (xy 116.667788 -214.596747) (xy 116.668296 -214.622634)
			(xy 116.667847 -214.64797) (xy 116.66009 -214.698044) (xy 116.644763 -214.746341) (xy 116.622227 -214.791726)
			(xy 116.593012 -214.833128) (xy 116.557808 -214.869572) (xy 116.517442 -214.900202) (xy 116.472865 -214.924296)
			(xy 116.425127 -214.941286) (xy 116.400326 -214.946484) (xy 116.377466 -214.950802) (xy 116.172488 -215.305894)
			(xy 116.180362 -215.327738) (xy 116.18901 -215.354146) (xy 116.198329 -215.408922) (xy 116.198904 -215.436704)
			(xy 117.41912 -215.436704) (xy 117.419629 -215.41136) (xy 117.4274 -215.36127) (xy 117.442746 -215.31296)
			(xy 117.465303 -215.267567) (xy 117.494542 -215.226161) (xy 117.529773 -215.189717) (xy 117.570165 -215.159094)
			(xy 117.614769 -215.135013) (xy 117.662532 -215.118041) (xy 117.687344 -215.112854) (xy 117.710204 -215.108536)
			(xy 117.915182 -214.753444) (xy 117.907308 -214.7316) (xy 117.898729 -214.705181) (xy 117.889532 -214.650406)
			(xy 117.88902 -214.622634) (xy 117.889528 -214.596747) (xy 117.897627 -214.545609) (xy 117.913626 -214.496369)
			(xy 117.937132 -214.450237) (xy 117.967564 -214.40835) (xy 118.004174 -214.37174) (xy 118.046061 -214.341308)
			(xy 118.092193 -214.317802) (xy 118.141433 -214.301803) (xy 118.192571 -214.293704) (xy 118.244345 -214.293704)
			(xy 118.295483 -214.301803) (xy 118.344723 -214.317802) (xy 118.390855 -214.341308) (xy 118.432742 -214.37174)
			(xy 118.469352 -214.40835) (xy 118.499784 -214.450237) (xy 118.52329 -214.496369) (xy 118.539289 -214.545609)
			(xy 118.547388 -214.596747) (xy 118.547896 -214.622634) (xy 118.547447 -214.64797) (xy 118.53969 -214.698044)
			(xy 118.524363 -214.746341) (xy 118.501827 -214.791726) (xy 118.472612 -214.833128) (xy 118.437408 -214.869572)
			(xy 118.397042 -214.900202) (xy 118.352465 -214.924296) (xy 118.304727 -214.941286) (xy 118.279926 -214.946484)
			(xy 118.257066 -214.950802) (xy 118.052088 -215.305894) (xy 118.059962 -215.327738) (xy 118.06861 -215.354146)
			(xy 118.077929 -215.408922) (xy 118.078504 -215.436704) (xy 119.29872 -215.436704) (xy 119.299229 -215.41136)
			(xy 119.307 -215.36127) (xy 119.322346 -215.31296) (xy 119.344903 -215.267567) (xy 119.374142 -215.226161)
			(xy 119.409373 -215.189717) (xy 119.449765 -215.159094) (xy 119.494369 -215.135013) (xy 119.542132 -215.118041)
			(xy 119.566944 -215.112854) (xy 119.589804 -215.108536) (xy 119.794782 -214.753444) (xy 119.786908 -214.7316)
			(xy 119.778329 -214.705181) (xy 119.769132 -214.650406) (xy 119.76862 -214.622634) (xy 119.769128 -214.596747)
			(xy 119.777227 -214.545609) (xy 119.793226 -214.496369) (xy 119.816732 -214.450237) (xy 119.847164 -214.40835)
			(xy 119.883774 -214.37174) (xy 119.925661 -214.341308) (xy 119.971793 -214.317802) (xy 120.021033 -214.301803)
			(xy 120.072171 -214.293704) (xy 120.123945 -214.293704) (xy 120.175083 -214.301803) (xy 120.224323 -214.317802)
			(xy 120.270455 -214.341308) (xy 120.312342 -214.37174) (xy 120.348952 -214.40835) (xy 120.379384 -214.450237)
			(xy 120.40289 -214.496369) (xy 120.418889 -214.545609) (xy 120.426988 -214.596747) (xy 120.427496 -214.622634)
			(xy 120.427047 -214.64797) (xy 120.41929 -214.698044) (xy 120.403963 -214.746341) (xy 120.381427 -214.791726)
			(xy 120.352212 -214.833128) (xy 120.317008 -214.869572) (xy 120.276642 -214.900202) (xy 120.232065 -214.924296)
			(xy 120.184327 -214.941286) (xy 120.159526 -214.946484) (xy 120.136666 -214.950802) (xy 119.931688 -215.305894)
			(xy 119.939562 -215.327738) (xy 119.94821 -215.354146) (xy 119.957529 -215.408922) (xy 119.958104 -215.436704)
			(xy 121.17832 -215.436704) (xy 121.178829 -215.41136) (xy 121.1866 -215.36127) (xy 121.201946 -215.31296)
			(xy 121.224503 -215.267567) (xy 121.253742 -215.226161) (xy 121.288973 -215.189717) (xy 121.329365 -215.159094)
			(xy 121.373969 -215.135013) (xy 121.421732 -215.118041) (xy 121.446544 -215.112854) (xy 121.469404 -215.108536)
			(xy 121.674382 -214.753444) (xy 121.666508 -214.7316) (xy 121.657929 -214.705181) (xy 121.648732 -214.650406)
			(xy 121.64822 -214.622634) (xy 121.648728 -214.596747) (xy 121.656827 -214.545609) (xy 121.672826 -214.496369)
			(xy 121.696332 -214.450237) (xy 121.726764 -214.40835) (xy 121.763374 -214.37174) (xy 121.805261 -214.341308)
			(xy 121.851393 -214.317802) (xy 121.900633 -214.301803) (xy 121.951771 -214.293704) (xy 122.003545 -214.293704)
			(xy 122.054683 -214.301803) (xy 122.103923 -214.317802) (xy 122.150055 -214.341308) (xy 122.191942 -214.37174)
			(xy 122.228552 -214.40835) (xy 122.258984 -214.450237) (xy 122.28249 -214.496369) (xy 122.298489 -214.545609)
			(xy 122.306588 -214.596747) (xy 122.307096 -214.622634) (xy 122.306647 -214.64797) (xy 122.29889 -214.698044)
			(xy 122.283563 -214.746341) (xy 122.261027 -214.791726) (xy 122.231812 -214.833128) (xy 122.196608 -214.869572)
			(xy 122.156242 -214.900202) (xy 122.111665 -214.924296) (xy 122.063927 -214.941286) (xy 122.039126 -214.946484)
			(xy 122.016266 -214.950802) (xy 121.811288 -215.305894) (xy 121.819162 -215.327738) (xy 121.82781 -215.354146)
			(xy 121.837129 -215.408922) (xy 121.837704 -215.436704) (xy 123.05792 -215.436704) (xy 123.058429 -215.41136)
			(xy 123.0662 -215.36127) (xy 123.081546 -215.31296) (xy 123.104103 -215.267567) (xy 123.133342 -215.226161)
			(xy 123.168573 -215.189717) (xy 123.208965 -215.159094) (xy 123.253569 -215.135013) (xy 123.301332 -215.118041)
			(xy 123.326144 -215.112854) (xy 123.349004 -215.108536) (xy 123.553982 -214.753444) (xy 123.546108 -214.7316)
			(xy 123.537529 -214.705181) (xy 123.528332 -214.650406) (xy 123.52782 -214.622634) (xy 123.528328 -214.596747)
			(xy 123.536427 -214.545609) (xy 123.552426 -214.496369) (xy 123.575932 -214.450237) (xy 123.606364 -214.40835)
			(xy 123.642974 -214.37174) (xy 123.684861 -214.341308) (xy 123.730993 -214.317802) (xy 123.780233 -214.301803)
			(xy 123.831371 -214.293704) (xy 123.883145 -214.293704) (xy 123.934283 -214.301803) (xy 123.983523 -214.317802)
			(xy 124.029655 -214.341308) (xy 124.071542 -214.37174) (xy 124.108152 -214.40835) (xy 124.138584 -214.450237)
			(xy 124.16209 -214.496369) (xy 124.178089 -214.545609) (xy 124.186188 -214.596747) (xy 124.186696 -214.622634)
			(xy 124.186247 -214.64797) (xy 124.17849 -214.698044) (xy 124.163163 -214.746341) (xy 124.140627 -214.791726)
			(xy 124.111412 -214.833128) (xy 124.076208 -214.869572) (xy 124.035842 -214.900202) (xy 123.991265 -214.924296)
			(xy 123.943527 -214.941286) (xy 123.918726 -214.946484) (xy 123.895866 -214.950802) (xy 123.690888 -215.305894)
			(xy 123.698762 -215.327738) (xy 123.70741 -215.354146) (xy 123.716729 -215.408922) (xy 123.717304 -215.436704)
			(xy 124.93752 -215.436704) (xy 124.938029 -215.41136) (xy 124.9458 -215.36127) (xy 124.961146 -215.31296)
			(xy 124.983703 -215.267567) (xy 125.012942 -215.226161) (xy 125.048173 -215.189717) (xy 125.088565 -215.159094)
			(xy 125.133169 -215.135013) (xy 125.180932 -215.118041) (xy 125.205744 -215.112854) (xy 125.228604 -215.108536)
			(xy 125.433582 -214.753444) (xy 125.425708 -214.7316) (xy 125.417129 -214.705181) (xy 125.407932 -214.650406)
			(xy 125.40742 -214.622634) (xy 125.407928 -214.596747) (xy 125.416027 -214.545609) (xy 125.432026 -214.496369)
			(xy 125.455532 -214.450237) (xy 125.485964 -214.40835) (xy 125.522574 -214.37174) (xy 125.564461 -214.341308)
			(xy 125.610593 -214.317802) (xy 125.659833 -214.301803) (xy 125.710971 -214.293704) (xy 125.762745 -214.293704)
			(xy 125.813883 -214.301803) (xy 125.863123 -214.317802) (xy 125.909255 -214.341308) (xy 125.951142 -214.37174)
			(xy 125.987752 -214.40835) (xy 126.018184 -214.450237) (xy 126.04169 -214.496369) (xy 126.057689 -214.545609)
			(xy 126.065788 -214.596747) (xy 126.066296 -214.622634) (xy 126.065847 -214.64797) (xy 126.05809 -214.698044)
			(xy 126.042763 -214.746341) (xy 126.020227 -214.791726) (xy 125.991012 -214.833128) (xy 125.955808 -214.869572)
			(xy 125.915442 -214.900202) (xy 125.870865 -214.924296) (xy 125.823127 -214.941286) (xy 125.798326 -214.946484)
			(xy 125.775466 -214.950802) (xy 125.570488 -215.305894) (xy 125.578362 -215.327738) (xy 125.58701 -215.354146)
			(xy 125.596329 -215.408922) (xy 125.596904 -215.436704) (xy 126.81712 -215.436704) (xy 126.817629 -215.41136)
			(xy 126.8254 -215.36127) (xy 126.840746 -215.31296) (xy 126.863303 -215.267567) (xy 126.892542 -215.226161)
			(xy 126.927773 -215.189717) (xy 126.968165 -215.159094) (xy 127.012769 -215.135013) (xy 127.060532 -215.118041)
			(xy 127.085344 -215.112854) (xy 127.108204 -215.108536) (xy 127.313182 -214.753444) (xy 127.305308 -214.7316)
			(xy 127.296729 -214.705181) (xy 127.287532 -214.650406) (xy 127.28702 -214.622634) (xy 127.287528 -214.596747)
			(xy 127.295627 -214.545609) (xy 127.311626 -214.496369) (xy 127.335132 -214.450237) (xy 127.365564 -214.40835)
			(xy 127.402174 -214.37174) (xy 127.444061 -214.341308) (xy 127.490193 -214.317802) (xy 127.539433 -214.301803)
			(xy 127.590571 -214.293704) (xy 127.642345 -214.293704) (xy 127.693483 -214.301803) (xy 127.742723 -214.317802)
			(xy 127.788855 -214.341308) (xy 127.830742 -214.37174) (xy 127.867352 -214.40835) (xy 127.897784 -214.450237)
			(xy 127.92129 -214.496369) (xy 127.937289 -214.545609) (xy 127.945388 -214.596747) (xy 127.945896 -214.622634)
			(xy 127.945447 -214.64797) (xy 127.93769 -214.698044) (xy 127.922363 -214.746341) (xy 127.899827 -214.791726)
			(xy 127.870612 -214.833128) (xy 127.835408 -214.869572) (xy 127.795042 -214.900202) (xy 127.750465 -214.924296)
			(xy 127.702727 -214.941286) (xy 127.677926 -214.946484) (xy 127.655066 -214.950802) (xy 127.450088 -215.305894)
			(xy 127.457962 -215.327738) (xy 127.46661 -215.354146) (xy 127.475929 -215.408922) (xy 127.476504 -215.436704)
			(xy 128.69672 -215.436704) (xy 128.697229 -215.41136) (xy 128.705 -215.36127) (xy 128.720346 -215.31296)
			(xy 128.742903 -215.267567) (xy 128.772142 -215.226161) (xy 128.807373 -215.189717) (xy 128.847765 -215.159094)
			(xy 128.892369 -215.135013) (xy 128.940132 -215.118041) (xy 128.964944 -215.112854) (xy 128.987804 -215.108536)
			(xy 129.192782 -214.753444) (xy 129.184908 -214.7316) (xy 129.176329 -214.705181) (xy 129.167132 -214.650406)
			(xy 129.16662 -214.622634) (xy 129.167128 -214.596747) (xy 129.175227 -214.545609) (xy 129.191226 -214.496369)
			(xy 129.214732 -214.450237) (xy 129.245164 -214.40835) (xy 129.281774 -214.37174) (xy 129.323661 -214.341308)
			(xy 129.369793 -214.317802) (xy 129.419033 -214.301803) (xy 129.470171 -214.293704) (xy 129.521945 -214.293704)
			(xy 129.573083 -214.301803) (xy 129.622323 -214.317802) (xy 129.668455 -214.341308) (xy 129.710342 -214.37174)
			(xy 129.746952 -214.40835) (xy 129.777384 -214.450237) (xy 129.80089 -214.496369) (xy 129.816889 -214.545609)
			(xy 129.824988 -214.596747) (xy 129.825496 -214.622634) (xy 129.825047 -214.64797) (xy 129.81729 -214.698044)
			(xy 129.801963 -214.746341) (xy 129.779427 -214.791726) (xy 129.750212 -214.833128) (xy 129.715008 -214.869572)
			(xy 129.674642 -214.900202) (xy 129.630065 -214.924296) (xy 129.582327 -214.941286) (xy 129.557526 -214.946484)
			(xy 129.534666 -214.950802) (xy 129.329688 -215.305894) (xy 129.337562 -215.327738) (xy 129.34621 -215.354146)
			(xy 129.355529 -215.408922) (xy 129.356104 -215.436704) (xy 130.57632 -215.436704) (xy 130.576829 -215.41136)
			(xy 130.5846 -215.36127) (xy 130.599946 -215.31296) (xy 130.622503 -215.267567) (xy 130.651742 -215.226161)
			(xy 130.686973 -215.189717) (xy 130.727365 -215.159094) (xy 130.771969 -215.135013) (xy 130.819732 -215.118041)
			(xy 130.844544 -215.112854) (xy 130.867404 -215.108536) (xy 131.072382 -214.753444) (xy 131.064508 -214.7316)
			(xy 131.055929 -214.705181) (xy 131.046732 -214.650406) (xy 131.04622 -214.622634) (xy 131.046728 -214.596747)
			(xy 131.054827 -214.545609) (xy 131.070826 -214.496369) (xy 131.094332 -214.450237) (xy 131.124764 -214.40835)
			(xy 131.161374 -214.37174) (xy 131.203261 -214.341308) (xy 131.249393 -214.317802) (xy 131.298633 -214.301803)
			(xy 131.349771 -214.293704) (xy 131.401545 -214.293704) (xy 131.452683 -214.301803) (xy 131.501923 -214.317802)
			(xy 131.548055 -214.341308) (xy 131.589942 -214.37174) (xy 131.626552 -214.40835) (xy 131.656984 -214.450237)
			(xy 131.68049 -214.496369) (xy 131.696489 -214.545609) (xy 131.704588 -214.596747) (xy 131.705096 -214.622634)
			(xy 131.704647 -214.64797) (xy 131.69689 -214.698044) (xy 131.681563 -214.746341) (xy 131.659027 -214.791726)
			(xy 131.629812 -214.833128) (xy 131.594608 -214.869572) (xy 131.554242 -214.900202) (xy 131.509665 -214.924296)
			(xy 131.461927 -214.941286) (xy 131.437126 -214.946484) (xy 131.414266 -214.950802) (xy 131.209288 -215.305894)
			(xy 131.217162 -215.327738) (xy 131.22581 -215.354146) (xy 131.235129 -215.408922) (xy 131.235704 -215.436704)
			(xy 132.45592 -215.436704) (xy 132.456429 -215.41136) (xy 132.4642 -215.36127) (xy 132.479546 -215.31296)
			(xy 132.502103 -215.267567) (xy 132.531342 -215.226161) (xy 132.566573 -215.189717) (xy 132.606965 -215.159094)
			(xy 132.651569 -215.135013) (xy 132.699332 -215.118041) (xy 132.724144 -215.112854) (xy 132.747004 -215.108536)
			(xy 132.951982 -214.753444) (xy 132.944108 -214.7316) (xy 132.935529 -214.705181) (xy 132.926332 -214.650406)
			(xy 132.92582 -214.622634) (xy 132.926328 -214.596747) (xy 132.934427 -214.545609) (xy 132.950426 -214.496369)
			(xy 132.973932 -214.450237) (xy 133.004364 -214.40835) (xy 133.040974 -214.37174) (xy 133.082861 -214.341308)
			(xy 133.128993 -214.317802) (xy 133.178233 -214.301803) (xy 133.229371 -214.293704) (xy 133.281145 -214.293704)
			(xy 133.332283 -214.301803) (xy 133.381523 -214.317802) (xy 133.427655 -214.341308) (xy 133.469542 -214.37174)
			(xy 133.506152 -214.40835) (xy 133.536584 -214.450237) (xy 133.56009 -214.496369) (xy 133.576089 -214.545609)
			(xy 133.57622 -214.546434) (xy 134.80542 -214.546434) (xy 134.805928 -214.520527) (xy 134.814034 -214.46935)
			(xy 134.830046 -214.420071) (xy 134.853569 -214.373904) (xy 134.884025 -214.331985) (xy 134.920663 -214.295347)
			(xy 134.962582 -214.264891) (xy 135.008749 -214.241368) (xy 135.058028 -214.225356) (xy 135.109205 -214.21725)
			(xy 135.161019 -214.21725) (xy 135.212196 -214.225356) (xy 135.261475 -214.241368) (xy 135.307642 -214.264891)
			(xy 135.349561 -214.295347) (xy 135.386199 -214.331985) (xy 135.416655 -214.373904) (xy 135.440178 -214.420071)
			(xy 135.45619 -214.46935) (xy 135.464296 -214.520527) (xy 135.464804 -214.546434) (xy 135.464102 -214.577275)
			(xy 135.452589 -214.637875) (xy 135.441944 -214.66683) (xy 135.433308 -214.688674) (xy 135.656066 -215.110314)
			(xy 135.678672 -215.115394) (xy 135.702597 -215.121362) (xy 135.748484 -215.139404) (xy 135.791171 -215.164081)
			(xy 135.829706 -215.194841) (xy 135.863229 -215.230999) (xy 135.890992 -215.271747) (xy 135.912374 -215.316176)
			(xy 135.9269 -215.363294) (xy 135.934244 -215.412051) (xy 135.934704 -215.436704) (xy 336.225388 -215.436704)
			(xy 336.225896 -215.410797) (xy 336.234002 -215.35962) (xy 336.250014 -215.310341) (xy 336.273537 -215.264174)
			(xy 336.303993 -215.222255) (xy 336.340631 -215.185617) (xy 336.38255 -215.155161) (xy 336.428717 -215.131638)
			(xy 336.477996 -215.115626) (xy 336.529173 -215.10752) (xy 336.580987 -215.10752) (xy 336.632164 -215.115626)
			(xy 336.681443 -215.131638) (xy 336.72761 -215.155161) (xy 336.769529 -215.185617) (xy 336.806167 -215.222255)
			(xy 336.836623 -215.264174) (xy 336.860146 -215.310341) (xy 336.876158 -215.35962) (xy 336.884264 -215.410797)
			(xy 336.884772 -215.436704) (xy 337.165188 -215.436704) (xy 337.165723 -215.411361) (xy 337.173493 -215.361274)
			(xy 337.188837 -215.312966) (xy 337.211392 -215.267575) (xy 337.240627 -215.226169) (xy 337.275854 -215.189725)
			(xy 337.316243 -215.159101) (xy 337.360842 -215.135018) (xy 337.408601 -215.118043) (xy 337.433412 -215.112854)
			(xy 337.456272 -215.108536) (xy 337.66125 -214.753444) (xy 337.653376 -214.7316) (xy 337.644799 -214.705181)
			(xy 337.6356 -214.650406) (xy 337.635088 -214.622634) (xy 337.635596 -214.596747) (xy 337.643695 -214.545609)
			(xy 337.659694 -214.496369) (xy 337.6832 -214.450237) (xy 337.713632 -214.40835) (xy 337.750242 -214.37174)
			(xy 337.792129 -214.341308) (xy 337.838261 -214.317802) (xy 337.887501 -214.301803) (xy 337.938639 -214.293704)
			(xy 337.990413 -214.293704) (xy 338.041551 -214.301803) (xy 338.090791 -214.317802) (xy 338.136923 -214.341308)
			(xy 338.17881 -214.37174) (xy 338.21542 -214.40835) (xy 338.245852 -214.450237) (xy 338.269358 -214.496369)
			(xy 338.285357 -214.545609) (xy 338.293456 -214.596747) (xy 338.293964 -214.622634) (xy 338.293541 -214.647971)
			(xy 338.285783 -214.698047) (xy 338.270454 -214.746347) (xy 338.247915 -214.791733) (xy 338.218698 -214.833136)
			(xy 338.18349 -214.869581) (xy 338.14312 -214.90021) (xy 338.098539 -214.924301) (xy 338.050797 -214.941288)
			(xy 338.025994 -214.946484) (xy 338.003134 -214.950802) (xy 337.798156 -215.305894) (xy 337.80603 -215.327738)
			(xy 337.814677 -215.354146) (xy 337.823997 -215.408922) (xy 337.824572 -215.436704) (xy 339.044788 -215.436704)
			(xy 339.045323 -215.411361) (xy 339.053093 -215.361274) (xy 339.068437 -215.312966) (xy 339.090992 -215.267575)
			(xy 339.120227 -215.226169) (xy 339.155454 -215.189725) (xy 339.195843 -215.159101) (xy 339.240442 -215.135018)
			(xy 339.288201 -215.118043) (xy 339.313012 -215.112854) (xy 339.335872 -215.108536) (xy 339.54085 -214.753444)
			(xy 339.532976 -214.7316) (xy 339.524399 -214.705181) (xy 339.5152 -214.650406) (xy 339.514688 -214.622634)
			(xy 339.515196 -214.596747) (xy 339.523295 -214.545609) (xy 339.539294 -214.496369) (xy 339.5628 -214.450237)
			(xy 339.593232 -214.40835) (xy 339.629842 -214.37174) (xy 339.671729 -214.341308) (xy 339.717861 -214.317802)
			(xy 339.767101 -214.301803) (xy 339.818239 -214.293704) (xy 339.870013 -214.293704) (xy 339.921151 -214.301803)
			(xy 339.970391 -214.317802) (xy 340.016523 -214.341308) (xy 340.05841 -214.37174) (xy 340.09502 -214.40835)
			(xy 340.125452 -214.450237) (xy 340.148958 -214.496369) (xy 340.164957 -214.545609) (xy 340.173056 -214.596747)
			(xy 340.173564 -214.622634) (xy 340.173141 -214.647971) (xy 340.165383 -214.698047) (xy 340.150054 -214.746347)
			(xy 340.127515 -214.791733) (xy 340.098298 -214.833136) (xy 340.06309 -214.869581) (xy 340.02272 -214.90021)
			(xy 339.978139 -214.924301) (xy 339.930397 -214.941288) (xy 339.905594 -214.946484) (xy 339.882734 -214.950802)
			(xy 339.677756 -215.305894) (xy 339.68563 -215.327738) (xy 339.694277 -215.354146) (xy 339.703597 -215.408922)
			(xy 339.704172 -215.436704) (xy 340.924388 -215.436704) (xy 340.924923 -215.411361) (xy 340.932693 -215.361274)
			(xy 340.948037 -215.312966) (xy 340.970592 -215.267575) (xy 340.999827 -215.226169) (xy 341.035054 -215.189725)
			(xy 341.075443 -215.159101) (xy 341.120042 -215.135018) (xy 341.167801 -215.118043) (xy 341.192612 -215.112854)
			(xy 341.215472 -215.108536) (xy 341.42045 -214.753444) (xy 341.412576 -214.7316) (xy 341.403999 -214.705181)
			(xy 341.3948 -214.650406) (xy 341.394288 -214.622634) (xy 341.394796 -214.596747) (xy 341.402895 -214.545609)
			(xy 341.418894 -214.496369) (xy 341.4424 -214.450237) (xy 341.472832 -214.40835) (xy 341.509442 -214.37174)
			(xy 341.551329 -214.341308) (xy 341.597461 -214.317802) (xy 341.646701 -214.301803) (xy 341.697839 -214.293704)
			(xy 341.749613 -214.293704) (xy 341.800751 -214.301803) (xy 341.849991 -214.317802) (xy 341.896123 -214.341308)
			(xy 341.93801 -214.37174) (xy 341.97462 -214.40835) (xy 342.005052 -214.450237) (xy 342.028558 -214.496369)
			(xy 342.044557 -214.545609) (xy 342.052656 -214.596747) (xy 342.053164 -214.622634) (xy 342.052741 -214.647971)
			(xy 342.044983 -214.698047) (xy 342.029654 -214.746347) (xy 342.007115 -214.791733) (xy 341.977898 -214.833136)
			(xy 341.94269 -214.869581) (xy 341.90232 -214.90021) (xy 341.857739 -214.924301) (xy 341.809997 -214.941288)
			(xy 341.785194 -214.946484) (xy 341.762334 -214.950802) (xy 341.557356 -215.305894) (xy 341.56523 -215.327738)
			(xy 341.573877 -215.354146) (xy 341.583197 -215.408922) (xy 341.583772 -215.436704) (xy 342.803988 -215.436704)
			(xy 342.804523 -215.411361) (xy 342.812293 -215.361274) (xy 342.827637 -215.312966) (xy 342.850192 -215.267575)
			(xy 342.879427 -215.226169) (xy 342.914654 -215.189725) (xy 342.955043 -215.159101) (xy 342.999642 -215.135018)
			(xy 343.047401 -215.118043) (xy 343.072212 -215.112854) (xy 343.095072 -215.108536) (xy 343.30005 -214.753444)
			(xy 343.292176 -214.7316) (xy 343.283599 -214.705181) (xy 343.2744 -214.650406) (xy 343.273888 -214.622634)
			(xy 343.274396 -214.596747) (xy 343.282495 -214.545609) (xy 343.298494 -214.496369) (xy 343.322 -214.450237)
			(xy 343.352432 -214.40835) (xy 343.389042 -214.37174) (xy 343.430929 -214.341308) (xy 343.477061 -214.317802)
			(xy 343.526301 -214.301803) (xy 343.577439 -214.293704) (xy 343.629213 -214.293704) (xy 343.680351 -214.301803)
			(xy 343.729591 -214.317802) (xy 343.775723 -214.341308) (xy 343.81761 -214.37174) (xy 343.85422 -214.40835)
			(xy 343.884652 -214.450237) (xy 343.908158 -214.496369) (xy 343.924157 -214.545609) (xy 343.932256 -214.596747)
			(xy 343.932764 -214.622634) (xy 343.932341 -214.647971) (xy 343.924583 -214.698047) (xy 343.909254 -214.746347)
			(xy 343.886715 -214.791733) (xy 343.857498 -214.833136) (xy 343.82229 -214.869581) (xy 343.78192 -214.90021)
			(xy 343.737339 -214.924301) (xy 343.689597 -214.941288) (xy 343.664794 -214.946484) (xy 343.641934 -214.950802)
			(xy 343.436956 -215.305894) (xy 343.44483 -215.327738) (xy 343.453477 -215.354146) (xy 343.462797 -215.408922)
			(xy 343.463372 -215.436704) (xy 344.683588 -215.436704) (xy 344.684123 -215.411361) (xy 344.691893 -215.361274)
			(xy 344.707237 -215.312966) (xy 344.729792 -215.267575) (xy 344.759027 -215.226169) (xy 344.794254 -215.189725)
			(xy 344.834643 -215.159101) (xy 344.879242 -215.135018) (xy 344.927001 -215.118043) (xy 344.951812 -215.112854)
			(xy 344.974672 -215.108536) (xy 345.17965 -214.753444) (xy 345.171776 -214.7316) (xy 345.163199 -214.705181)
			(xy 345.154 -214.650406) (xy 345.153488 -214.622634) (xy 345.153996 -214.596747) (xy 345.162095 -214.545609)
			(xy 345.178094 -214.496369) (xy 345.2016 -214.450237) (xy 345.232032 -214.40835) (xy 345.268642 -214.37174)
			(xy 345.310529 -214.341308) (xy 345.356661 -214.317802) (xy 345.405901 -214.301803) (xy 345.457039 -214.293704)
			(xy 345.508813 -214.293704) (xy 345.559951 -214.301803) (xy 345.609191 -214.317802) (xy 345.655323 -214.341308)
			(xy 345.69721 -214.37174) (xy 345.73382 -214.40835) (xy 345.764252 -214.450237) (xy 345.787758 -214.496369)
			(xy 345.803757 -214.545609) (xy 345.811856 -214.596747) (xy 345.812364 -214.622634) (xy 345.811941 -214.647971)
			(xy 345.804183 -214.698047) (xy 345.788854 -214.746347) (xy 345.766315 -214.791733) (xy 345.737098 -214.833136)
			(xy 345.70189 -214.869581) (xy 345.66152 -214.90021) (xy 345.616939 -214.924301) (xy 345.569197 -214.941288)
			(xy 345.544394 -214.946484) (xy 345.521534 -214.950802) (xy 345.316556 -215.305894) (xy 345.32443 -215.327738)
			(xy 345.333077 -215.354146) (xy 345.342397 -215.408922) (xy 345.342972 -215.436704) (xy 346.563188 -215.436704)
			(xy 346.563723 -215.411361) (xy 346.571493 -215.361274) (xy 346.586837 -215.312966) (xy 346.609392 -215.267575)
			(xy 346.638627 -215.226169) (xy 346.673854 -215.189725) (xy 346.714243 -215.159101) (xy 346.758842 -215.135018)
			(xy 346.806601 -215.118043) (xy 346.831412 -215.112854) (xy 346.854272 -215.108536) (xy 347.05925 -214.753444)
			(xy 347.051376 -214.7316) (xy 347.042799 -214.705181) (xy 347.0336 -214.650406) (xy 347.033088 -214.622634)
			(xy 347.033596 -214.596747) (xy 347.041695 -214.545609) (xy 347.057694 -214.496369) (xy 347.0812 -214.450237)
			(xy 347.111632 -214.40835) (xy 347.148242 -214.37174) (xy 347.190129 -214.341308) (xy 347.236261 -214.317802)
			(xy 347.285501 -214.301803) (xy 347.336639 -214.293704) (xy 347.388413 -214.293704) (xy 347.439551 -214.301803)
			(xy 347.488791 -214.317802) (xy 347.534923 -214.341308) (xy 347.57681 -214.37174) (xy 347.61342 -214.40835)
			(xy 347.643852 -214.450237) (xy 347.667358 -214.496369) (xy 347.683357 -214.545609) (xy 347.691456 -214.596747)
			(xy 347.691964 -214.622634) (xy 347.691541 -214.647971) (xy 347.683783 -214.698047) (xy 347.668454 -214.746347)
			(xy 347.645915 -214.791733) (xy 347.616698 -214.833136) (xy 347.58149 -214.869581) (xy 347.54112 -214.90021)
			(xy 347.496539 -214.924301) (xy 347.448797 -214.941288) (xy 347.423994 -214.946484) (xy 347.401134 -214.950802)
			(xy 347.196156 -215.305894) (xy 347.20403 -215.327738) (xy 347.212677 -215.354146) (xy 347.221997 -215.408922)
			(xy 347.222572 -215.436704) (xy 348.442788 -215.436704) (xy 348.443323 -215.411361) (xy 348.451093 -215.361274)
			(xy 348.466437 -215.312966) (xy 348.488992 -215.267575) (xy 348.518227 -215.226169) (xy 348.553454 -215.189725)
			(xy 348.593843 -215.159101) (xy 348.638442 -215.135018) (xy 348.686201 -215.118043) (xy 348.711012 -215.112854)
			(xy 348.733872 -215.108536) (xy 348.93885 -214.753444) (xy 348.930976 -214.7316) (xy 348.922399 -214.705181)
			(xy 348.9132 -214.650406) (xy 348.912688 -214.622634) (xy 348.913196 -214.596747) (xy 348.921295 -214.545609)
			(xy 348.937294 -214.496369) (xy 348.9608 -214.450237) (xy 348.991232 -214.40835) (xy 349.027842 -214.37174)
			(xy 349.069729 -214.341308) (xy 349.115861 -214.317802) (xy 349.165101 -214.301803) (xy 349.216239 -214.293704)
			(xy 349.268013 -214.293704) (xy 349.319151 -214.301803) (xy 349.368391 -214.317802) (xy 349.414523 -214.341308)
			(xy 349.45641 -214.37174) (xy 349.49302 -214.40835) (xy 349.523452 -214.450237) (xy 349.546958 -214.496369)
			(xy 349.562957 -214.545609) (xy 349.571056 -214.596747) (xy 349.571564 -214.622634) (xy 349.571141 -214.647971)
			(xy 349.563383 -214.698047) (xy 349.548054 -214.746347) (xy 349.525515 -214.791733) (xy 349.496298 -214.833136)
			(xy 349.46109 -214.869581) (xy 349.42072 -214.90021) (xy 349.376139 -214.924301) (xy 349.328397 -214.941288)
			(xy 349.303594 -214.946484) (xy 349.280734 -214.950802) (xy 349.075756 -215.305894) (xy 349.08363 -215.327738)
			(xy 349.092277 -215.354146) (xy 349.101597 -215.408922) (xy 349.102172 -215.436704) (xy 350.322388 -215.436704)
			(xy 350.322923 -215.411361) (xy 350.330693 -215.361274) (xy 350.346037 -215.312966) (xy 350.368592 -215.267575)
			(xy 350.397827 -215.226169) (xy 350.433054 -215.189725) (xy 350.473443 -215.159101) (xy 350.518042 -215.135018)
			(xy 350.565801 -215.118043) (xy 350.590612 -215.112854) (xy 350.613472 -215.108536) (xy 350.81845 -214.753444)
			(xy 350.810576 -214.7316) (xy 350.801999 -214.705181) (xy 350.7928 -214.650406) (xy 350.792288 -214.622634)
			(xy 350.792796 -214.596747) (xy 350.800895 -214.545609) (xy 350.816894 -214.496369) (xy 350.8404 -214.450237)
			(xy 350.870832 -214.40835) (xy 350.907442 -214.37174) (xy 350.949329 -214.341308) (xy 350.995461 -214.317802)
			(xy 351.044701 -214.301803) (xy 351.095839 -214.293704) (xy 351.147613 -214.293704) (xy 351.198751 -214.301803)
			(xy 351.247991 -214.317802) (xy 351.294123 -214.341308) (xy 351.33601 -214.37174) (xy 351.37262 -214.40835)
			(xy 351.403052 -214.450237) (xy 351.426558 -214.496369) (xy 351.442557 -214.545609) (xy 351.450656 -214.596747)
			(xy 351.451164 -214.622634) (xy 351.450741 -214.647971) (xy 351.442983 -214.698047) (xy 351.427654 -214.746347)
			(xy 351.405115 -214.791733) (xy 351.375898 -214.833136) (xy 351.34069 -214.869581) (xy 351.30032 -214.90021)
			(xy 351.255739 -214.924301) (xy 351.207997 -214.941288) (xy 351.183194 -214.946484) (xy 351.160334 -214.950802)
			(xy 350.955356 -215.305894) (xy 350.96323 -215.327738) (xy 350.971877 -215.354146) (xy 350.981197 -215.408922)
			(xy 350.981772 -215.436704) (xy 352.201988 -215.436704) (xy 352.202523 -215.411361) (xy 352.210293 -215.361274)
			(xy 352.225637 -215.312966) (xy 352.248192 -215.267575) (xy 352.277427 -215.226169) (xy 352.312654 -215.189725)
			(xy 352.353043 -215.159101) (xy 352.397642 -215.135018) (xy 352.445401 -215.118043) (xy 352.470212 -215.112854)
			(xy 352.493072 -215.108536) (xy 352.69805 -214.753444) (xy 352.690176 -214.7316) (xy 352.681599 -214.705181)
			(xy 352.6724 -214.650406) (xy 352.671888 -214.622634) (xy 352.672396 -214.596747) (xy 352.680495 -214.545609)
			(xy 352.696494 -214.496369) (xy 352.72 -214.450237) (xy 352.750432 -214.40835) (xy 352.787042 -214.37174)
			(xy 352.828929 -214.341308) (xy 352.875061 -214.317802) (xy 352.924301 -214.301803) (xy 352.975439 -214.293704)
			(xy 353.027213 -214.293704) (xy 353.078351 -214.301803) (xy 353.127591 -214.317802) (xy 353.173723 -214.341308)
			(xy 353.21561 -214.37174) (xy 353.25222 -214.40835) (xy 353.282652 -214.450237) (xy 353.306158 -214.496369)
			(xy 353.322157 -214.545609) (xy 353.330256 -214.596747) (xy 353.330764 -214.622634) (xy 353.330341 -214.647971)
			(xy 353.322583 -214.698047) (xy 353.307254 -214.746347) (xy 353.284715 -214.791733) (xy 353.255498 -214.833136)
			(xy 353.22029 -214.869581) (xy 353.17992 -214.90021) (xy 353.135339 -214.924301) (xy 353.087597 -214.941288)
			(xy 353.062794 -214.946484) (xy 353.039934 -214.950802) (xy 352.834956 -215.305894) (xy 352.84283 -215.327738)
			(xy 352.851477 -215.354146) (xy 352.860797 -215.408922) (xy 352.861372 -215.436704) (xy 354.081588 -215.436704)
			(xy 354.082123 -215.411361) (xy 354.089893 -215.361274) (xy 354.105237 -215.312966) (xy 354.127792 -215.267575)
			(xy 354.157027 -215.226169) (xy 354.192254 -215.189725) (xy 354.232643 -215.159101) (xy 354.277242 -215.135018)
			(xy 354.325001 -215.118043) (xy 354.349812 -215.112854) (xy 354.372672 -215.108536) (xy 354.57765 -214.753444)
			(xy 354.569776 -214.7316) (xy 354.561199 -214.705181) (xy 354.552 -214.650406) (xy 354.551488 -214.622634)
			(xy 354.551996 -214.596747) (xy 354.560095 -214.545609) (xy 354.576094 -214.496369) (xy 354.5996 -214.450237)
			(xy 354.630032 -214.40835) (xy 354.666642 -214.37174) (xy 354.708529 -214.341308) (xy 354.754661 -214.317802)
			(xy 354.803901 -214.301803) (xy 354.855039 -214.293704) (xy 354.906813 -214.293704) (xy 354.957951 -214.301803)
			(xy 355.007191 -214.317802) (xy 355.053323 -214.341308) (xy 355.09521 -214.37174) (xy 355.13182 -214.40835)
			(xy 355.162252 -214.450237) (xy 355.185758 -214.496369) (xy 355.201757 -214.545609) (xy 355.209856 -214.596747)
			(xy 355.210364 -214.622634) (xy 355.209941 -214.647971) (xy 355.202183 -214.698047) (xy 355.186854 -214.746347)
			(xy 355.164315 -214.791733) (xy 355.135098 -214.833136) (xy 355.09989 -214.869581) (xy 355.05952 -214.90021)
			(xy 355.014939 -214.924301) (xy 354.967197 -214.941288) (xy 354.942394 -214.946484) (xy 354.919534 -214.950802)
			(xy 354.714556 -215.305894) (xy 354.72243 -215.327738) (xy 354.731077 -215.354146) (xy 354.740397 -215.408922)
			(xy 354.740972 -215.436704) (xy 355.961188 -215.436704) (xy 355.961723 -215.411361) (xy 355.969493 -215.361274)
			(xy 355.984837 -215.312966) (xy 356.007392 -215.267575) (xy 356.036627 -215.226169) (xy 356.071854 -215.189725)
			(xy 356.112243 -215.159101) (xy 356.156842 -215.135018) (xy 356.204601 -215.118043) (xy 356.229412 -215.112854)
			(xy 356.252272 -215.108536) (xy 356.45725 -214.753444) (xy 356.449376 -214.7316) (xy 356.440799 -214.705181)
			(xy 356.4316 -214.650406) (xy 356.431088 -214.622634) (xy 356.431596 -214.596747) (xy 356.439695 -214.545609)
			(xy 356.455694 -214.496369) (xy 356.4792 -214.450237) (xy 356.509632 -214.40835) (xy 356.546242 -214.37174)
			(xy 356.588129 -214.341308) (xy 356.634261 -214.317802) (xy 356.683501 -214.301803) (xy 356.734639 -214.293704)
			(xy 356.786413 -214.293704) (xy 356.837551 -214.301803) (xy 356.886791 -214.317802) (xy 356.932923 -214.341308)
			(xy 356.97481 -214.37174) (xy 357.01142 -214.40835) (xy 357.041852 -214.450237) (xy 357.065358 -214.496369)
			(xy 357.081357 -214.545609) (xy 357.089456 -214.596747) (xy 357.089964 -214.622634) (xy 358.310688 -214.622634)
			(xy 358.311196 -214.596747) (xy 358.319295 -214.545609) (xy 358.335294 -214.496369) (xy 358.3588 -214.450237)
			(xy 358.389232 -214.40835) (xy 358.425842 -214.37174) (xy 358.467729 -214.341308) (xy 358.513861 -214.317802)
			(xy 358.563101 -214.301803) (xy 358.614239 -214.293704) (xy 358.666013 -214.293704) (xy 358.717151 -214.301803)
			(xy 358.766391 -214.317802) (xy 358.812523 -214.341308) (xy 358.85441 -214.37174) (xy 358.89102 -214.40835)
			(xy 358.921452 -214.450237) (xy 358.944958 -214.496369) (xy 358.960957 -214.545609) (xy 358.969056 -214.596747)
			(xy 358.969564 -214.622634) (xy 358.969564 -214.623142) (xy 358.968984 -214.650659) (xy 358.959791 -214.70492)
			(xy 358.951276 -214.731092) (xy 358.943656 -214.75319) (xy 359.148888 -215.108536) (xy 359.171748 -215.112854)
			(xy 359.196559 -215.118062) (xy 359.244336 -215.135013) (xy 359.288953 -215.15908) (xy 359.329358 -215.189696)
			(xy 359.364599 -215.226137) (xy 359.393844 -215.267545) (xy 359.416403 -215.312943) (xy 359.431745 -215.36126)
			(xy 359.439507 -215.411357) (xy 359.439972 -215.436704) (xy 359.439464 -215.462611) (xy 359.431358 -215.513788)
			(xy 359.415346 -215.563067) (xy 359.391823 -215.609234) (xy 359.361367 -215.651153) (xy 359.324729 -215.687791)
			(xy 359.28281 -215.718247) (xy 359.236643 -215.74177) (xy 359.187364 -215.757782) (xy 359.136187 -215.765888)
			(xy 359.084373 -215.765888) (xy 359.033196 -215.757782) (xy 358.983917 -215.74177) (xy 358.93775 -215.718247)
			(xy 358.895831 -215.687791) (xy 358.859193 -215.651153) (xy 358.828737 -215.609234) (xy 358.805214 -215.563067)
			(xy 358.789202 -215.513788) (xy 358.781096 -215.462611) (xy 358.780588 -215.436704) (xy 358.781184 -215.408987)
			(xy 358.790506 -215.35434) (xy 358.79913 -215.327992) (xy 358.80675 -215.306148) (xy 358.601772 -214.950802)
			(xy 358.578912 -214.946484) (xy 358.554096 -214.941291) (xy 358.506315 -214.924344) (xy 358.461694 -214.900279)
			(xy 358.421285 -214.869663) (xy 358.386043 -214.833219) (xy 358.356798 -214.791807) (xy 358.33424 -214.746405)
			(xy 358.318903 -214.698083) (xy 358.311148 -214.647983) (xy 358.310688 -214.622634) (xy 357.089964 -214.622634)
			(xy 357.089541 -214.647971) (xy 357.081783 -214.698047) (xy 357.066454 -214.746347) (xy 357.043915 -214.791733)
			(xy 357.014698 -214.833136) (xy 356.97949 -214.869581) (xy 356.93912 -214.90021) (xy 356.894539 -214.924301)
			(xy 356.846797 -214.941288) (xy 356.821994 -214.946484) (xy 356.799134 -214.950802) (xy 356.594156 -215.305894)
			(xy 356.60203 -215.327738) (xy 356.610677 -215.354146) (xy 356.619997 -215.408922) (xy 356.620572 -215.436704)
			(xy 356.620064 -215.462606) (xy 356.90152 -215.462606) (xy 356.90152 -215.410794) (xy 356.909625 -215.35962)
			(xy 356.925635 -215.310344) (xy 356.949157 -215.264178) (xy 356.97961 -215.222261) (xy 357.016246 -215.185623)
			(xy 357.058161 -215.155167) (xy 357.104325 -215.131643) (xy 357.1536 -215.11563) (xy 357.204774 -215.107522)
			(xy 357.23068 -215.107012) (xy 357.256191 -215.107502) (xy 357.306606 -215.11536) (xy 357.355207 -215.130891)
			(xy 357.400836 -215.153725) (xy 357.442402 -215.183316) (xy 357.478912 -215.218958) (xy 357.494586 -215.239092)
			(xy 357.906574 -215.239092) (xy 357.92226 -215.218967) (xy 357.958768 -215.183323) (xy 358.000331 -215.153729)
			(xy 358.045956 -215.130891) (xy 358.094556 -215.115355) (xy 358.144969 -215.107491) (xy 358.17048 -215.107012)
			(xy 358.196391 -215.107484) (xy 358.247575 -215.115588) (xy 358.296861 -215.131599) (xy 358.343035 -215.155124)
			(xy 358.38496 -215.185582) (xy 358.421605 -215.222224) (xy 358.452066 -215.264148) (xy 358.475593 -215.310321)
			(xy 358.491607 -215.359606) (xy 358.499714 -215.410789) (xy 358.499714 -215.462611) (xy 358.491607 -215.513794)
			(xy 358.475593 -215.563079) (xy 358.452066 -215.609252) (xy 358.421605 -215.651176) (xy 358.38496 -215.687818)
			(xy 358.343035 -215.718276) (xy 358.296861 -215.741801) (xy 358.247575 -215.757812) (xy 358.196391 -215.765916)
			(xy 358.17048 -215.766396) (xy 358.144968 -215.765932) (xy 358.094552 -215.758068) (xy 358.04595 -215.742532)
			(xy 358.000322 -215.719693) (xy 357.958757 -215.690098) (xy 357.922247 -215.654452) (xy 357.906574 -215.634316)
			(xy 357.494586 -215.634316) (xy 357.478925 -215.654461) (xy 357.442412 -215.690104) (xy 357.400844 -215.719696)
			(xy 357.355213 -215.74253) (xy 357.306609 -215.758062) (xy 357.256193 -215.76592) (xy 357.23068 -215.766396)
			(xy 357.204774 -215.765878) (xy 357.1536 -215.75777) (xy 357.104325 -215.741757) (xy 357.058161 -215.718233)
			(xy 357.016246 -215.687777) (xy 356.97961 -215.651139) (xy 356.949157 -215.609222) (xy 356.925635 -215.563056)
			(xy 356.909625 -215.51378) (xy 356.90152 -215.462606) (xy 356.620064 -215.462606) (xy 356.620064 -215.462611)
			(xy 356.611958 -215.513788) (xy 356.595946 -215.563067) (xy 356.572423 -215.609234) (xy 356.541967 -215.651153)
			(xy 356.505329 -215.687791) (xy 356.46341 -215.718247) (xy 356.417243 -215.74177) (xy 356.367964 -215.757782)
			(xy 356.316787 -215.765888) (xy 356.264973 -215.765888) (xy 356.213796 -215.757782) (xy 356.164517 -215.74177)
			(xy 356.11835 -215.718247) (xy 356.076431 -215.687791) (xy 356.039793 -215.651153) (xy 356.009337 -215.609234)
			(xy 355.985814 -215.563067) (xy 355.969802 -215.513788) (xy 355.961696 -215.462611) (xy 355.961188 -215.436704)
			(xy 354.740972 -215.436704) (xy 354.740464 -215.462611) (xy 354.732358 -215.513788) (xy 354.716346 -215.563067)
			(xy 354.692823 -215.609234) (xy 354.662367 -215.651153) (xy 354.625729 -215.687791) (xy 354.58381 -215.718247)
			(xy 354.537643 -215.74177) (xy 354.488364 -215.757782) (xy 354.437187 -215.765888) (xy 354.385373 -215.765888)
			(xy 354.334196 -215.757782) (xy 354.284917 -215.74177) (xy 354.23875 -215.718247) (xy 354.196831 -215.687791)
			(xy 354.160193 -215.651153) (xy 354.129737 -215.609234) (xy 354.106214 -215.563067) (xy 354.090202 -215.513788)
			(xy 354.082096 -215.462611) (xy 354.081588 -215.436704) (xy 352.861372 -215.436704) (xy 352.860864 -215.462611)
			(xy 352.852758 -215.513788) (xy 352.836746 -215.563067) (xy 352.813223 -215.609234) (xy 352.782767 -215.651153)
			(xy 352.746129 -215.687791) (xy 352.70421 -215.718247) (xy 352.658043 -215.74177) (xy 352.608764 -215.757782)
			(xy 352.557587 -215.765888) (xy 352.505773 -215.765888) (xy 352.454596 -215.757782) (xy 352.405317 -215.74177)
			(xy 352.35915 -215.718247) (xy 352.317231 -215.687791) (xy 352.280593 -215.651153) (xy 352.250137 -215.609234)
			(xy 352.226614 -215.563067) (xy 352.210602 -215.513788) (xy 352.202496 -215.462611) (xy 352.201988 -215.436704)
			(xy 350.981772 -215.436704) (xy 350.981264 -215.462611) (xy 350.973158 -215.513788) (xy 350.957146 -215.563067)
			(xy 350.933623 -215.609234) (xy 350.903167 -215.651153) (xy 350.866529 -215.687791) (xy 350.82461 -215.718247)
			(xy 350.778443 -215.74177) (xy 350.729164 -215.757782) (xy 350.677987 -215.765888) (xy 350.626173 -215.765888)
			(xy 350.574996 -215.757782) (xy 350.525717 -215.74177) (xy 350.47955 -215.718247) (xy 350.437631 -215.687791)
			(xy 350.400993 -215.651153) (xy 350.370537 -215.609234) (xy 350.347014 -215.563067) (xy 350.331002 -215.513788)
			(xy 350.322896 -215.462611) (xy 350.322388 -215.436704) (xy 349.102172 -215.436704) (xy 349.101664 -215.462611)
			(xy 349.093558 -215.513788) (xy 349.077546 -215.563067) (xy 349.054023 -215.609234) (xy 349.023567 -215.651153)
			(xy 348.986929 -215.687791) (xy 348.94501 -215.718247) (xy 348.898843 -215.74177) (xy 348.849564 -215.757782)
			(xy 348.798387 -215.765888) (xy 348.746573 -215.765888) (xy 348.695396 -215.757782) (xy 348.646117 -215.74177)
			(xy 348.59995 -215.718247) (xy 348.558031 -215.687791) (xy 348.521393 -215.651153) (xy 348.490937 -215.609234)
			(xy 348.467414 -215.563067) (xy 348.451402 -215.513788) (xy 348.443296 -215.462611) (xy 348.442788 -215.436704)
			(xy 347.222572 -215.436704) (xy 347.222064 -215.462611) (xy 347.213958 -215.513788) (xy 347.197946 -215.563067)
			(xy 347.174423 -215.609234) (xy 347.143967 -215.651153) (xy 347.107329 -215.687791) (xy 347.06541 -215.718247)
			(xy 347.019243 -215.74177) (xy 346.969964 -215.757782) (xy 346.918787 -215.765888) (xy 346.866973 -215.765888)
			(xy 346.815796 -215.757782) (xy 346.766517 -215.74177) (xy 346.72035 -215.718247) (xy 346.678431 -215.687791)
			(xy 346.641793 -215.651153) (xy 346.611337 -215.609234) (xy 346.587814 -215.563067) (xy 346.571802 -215.513788)
			(xy 346.563696 -215.462611) (xy 346.563188 -215.436704) (xy 345.342972 -215.436704) (xy 345.342464 -215.462611)
			(xy 345.334358 -215.513788) (xy 345.318346 -215.563067) (xy 345.294823 -215.609234) (xy 345.264367 -215.651153)
			(xy 345.227729 -215.687791) (xy 345.18581 -215.718247) (xy 345.139643 -215.74177) (xy 345.090364 -215.757782)
			(xy 345.039187 -215.765888) (xy 344.987373 -215.765888) (xy 344.936196 -215.757782) (xy 344.886917 -215.74177)
			(xy 344.84075 -215.718247) (xy 344.798831 -215.687791) (xy 344.762193 -215.651153) (xy 344.731737 -215.609234)
			(xy 344.708214 -215.563067) (xy 344.692202 -215.513788) (xy 344.684096 -215.462611) (xy 344.683588 -215.436704)
			(xy 343.463372 -215.436704) (xy 343.462864 -215.462611) (xy 343.454758 -215.513788) (xy 343.438746 -215.563067)
			(xy 343.415223 -215.609234) (xy 343.384767 -215.651153) (xy 343.348129 -215.687791) (xy 343.30621 -215.718247)
			(xy 343.260043 -215.74177) (xy 343.210764 -215.757782) (xy 343.159587 -215.765888) (xy 343.107773 -215.765888)
			(xy 343.056596 -215.757782) (xy 343.007317 -215.74177) (xy 342.96115 -215.718247) (xy 342.919231 -215.687791)
			(xy 342.882593 -215.651153) (xy 342.852137 -215.609234) (xy 342.828614 -215.563067) (xy 342.812602 -215.513788)
			(xy 342.804496 -215.462611) (xy 342.803988 -215.436704) (xy 341.583772 -215.436704) (xy 341.583264 -215.462611)
			(xy 341.575158 -215.513788) (xy 341.559146 -215.563067) (xy 341.535623 -215.609234) (xy 341.505167 -215.651153)
			(xy 341.468529 -215.687791) (xy 341.42661 -215.718247) (xy 341.380443 -215.74177) (xy 341.331164 -215.757782)
			(xy 341.279987 -215.765888) (xy 341.228173 -215.765888) (xy 341.176996 -215.757782) (xy 341.127717 -215.74177)
			(xy 341.08155 -215.718247) (xy 341.039631 -215.687791) (xy 341.002993 -215.651153) (xy 340.972537 -215.609234)
			(xy 340.949014 -215.563067) (xy 340.933002 -215.513788) (xy 340.924896 -215.462611) (xy 340.924388 -215.436704)
			(xy 339.704172 -215.436704) (xy 339.703664 -215.462611) (xy 339.695558 -215.513788) (xy 339.679546 -215.563067)
			(xy 339.656023 -215.609234) (xy 339.625567 -215.651153) (xy 339.588929 -215.687791) (xy 339.54701 -215.718247)
			(xy 339.500843 -215.74177) (xy 339.451564 -215.757782) (xy 339.400387 -215.765888) (xy 339.348573 -215.765888)
			(xy 339.297396 -215.757782) (xy 339.248117 -215.74177) (xy 339.20195 -215.718247) (xy 339.160031 -215.687791)
			(xy 339.123393 -215.651153) (xy 339.092937 -215.609234) (xy 339.069414 -215.563067) (xy 339.053402 -215.513788)
			(xy 339.045296 -215.462611) (xy 339.044788 -215.436704) (xy 337.824572 -215.436704) (xy 337.824064 -215.462611)
			(xy 337.815958 -215.513788) (xy 337.799946 -215.563067) (xy 337.776423 -215.609234) (xy 337.745967 -215.651153)
			(xy 337.709329 -215.687791) (xy 337.66741 -215.718247) (xy 337.621243 -215.74177) (xy 337.571964 -215.757782)
			(xy 337.520787 -215.765888) (xy 337.468973 -215.765888) (xy 337.417796 -215.757782) (xy 337.368517 -215.74177)
			(xy 337.32235 -215.718247) (xy 337.280431 -215.687791) (xy 337.243793 -215.651153) (xy 337.213337 -215.609234)
			(xy 337.189814 -215.563067) (xy 337.173802 -215.513788) (xy 337.165696 -215.462611) (xy 337.165188 -215.436704)
			(xy 336.884772 -215.436704) (xy 336.884181 -215.464421) (xy 336.874856 -215.519068) (xy 336.86623 -215.545416)
			(xy 336.858356 -215.567514) (xy 337.063334 -215.922352) (xy 337.086194 -215.92667) (xy 337.110997 -215.931858)
			(xy 337.158737 -215.948846) (xy 337.203315 -215.972939) (xy 337.243681 -216.00357) (xy 337.278884 -216.040017)
			(xy 337.308096 -216.081421) (xy 337.330629 -216.126808) (xy 337.345951 -216.175108) (xy 337.353702 -216.225184)
			(xy 337.354164 -216.25052) (xy 337.353656 -216.276407) (xy 337.345557 -216.327545) (xy 337.329558 -216.376785)
			(xy 337.306052 -216.422917) (xy 337.27562 -216.464804) (xy 337.23901 -216.501414) (xy 337.197123 -216.531846)
			(xy 337.150991 -216.555352) (xy 337.101751 -216.571351) (xy 337.050613 -216.57945) (xy 336.998839 -216.57945)
			(xy 336.947701 -216.571351) (xy 336.898461 -216.555352) (xy 336.852329 -216.531846) (xy 336.810442 -216.501414)
			(xy 336.773832 -216.464804) (xy 336.7434 -216.422917) (xy 336.719894 -216.376785) (xy 336.703895 -216.327545)
			(xy 336.695796 -216.276407) (xy 336.695288 -216.25052) (xy 336.695823 -216.222812) (xy 336.705015 -216.168165)
			(xy 336.713576 -216.141808) (xy 336.72145 -216.11971) (xy 336.516472 -215.764872) (xy 336.493612 -215.760554)
			(xy 336.46879 -215.755389) (xy 336.421007 -215.73844) (xy 336.376384 -215.714372) (xy 336.335974 -215.683753)
			(xy 336.300731 -215.647305) (xy 336.271487 -215.60589) (xy 336.248932 -215.560483) (xy 336.233597 -215.512158)
			(xy 336.225846 -215.462054) (xy 336.225388 -215.436704) (xy 135.934704 -215.436704) (xy 135.934196 -215.462611)
			(xy 135.92609 -215.513788) (xy 135.910078 -215.563067) (xy 135.886555 -215.609234) (xy 135.856099 -215.651153)
			(xy 135.819461 -215.687791) (xy 135.777542 -215.718247) (xy 135.731375 -215.74177) (xy 135.682096 -215.757782)
			(xy 135.630919 -215.765888) (xy 135.579105 -215.765888) (xy 135.527928 -215.757782) (xy 135.478649 -215.74177)
			(xy 135.432482 -215.718247) (xy 135.390563 -215.687791) (xy 135.353925 -215.651153) (xy 135.323469 -215.609234)
			(xy 135.299946 -215.563067) (xy 135.283934 -215.513788) (xy 135.275828 -215.462611) (xy 135.27532 -215.436704)
			(xy 135.27603 -215.405863) (xy 135.287538 -215.345263) (xy 135.29818 -215.316308) (xy 135.306816 -215.294464)
			(xy 135.084058 -214.872824) (xy 135.061452 -214.867744) (xy 135.037516 -214.861817) (xy 134.991624 -214.843773)
			(xy 134.948934 -214.819093) (xy 134.910397 -214.788329) (xy 134.876873 -214.752166) (xy 134.849112 -214.711412)
			(xy 134.827733 -214.666976) (xy 134.813212 -214.619852) (xy 134.805875 -214.57109) (xy 134.80542 -214.546434)
			(xy 133.57622 -214.546434) (xy 133.584188 -214.596747) (xy 133.584696 -214.622634) (xy 133.584247 -214.64797)
			(xy 133.57649 -214.698044) (xy 133.561163 -214.746341) (xy 133.538627 -214.791726) (xy 133.509412 -214.833128)
			(xy 133.474208 -214.869572) (xy 133.433842 -214.900202) (xy 133.389265 -214.924296) (xy 133.341527 -214.941286)
			(xy 133.316726 -214.946484) (xy 133.293866 -214.950802) (xy 133.088888 -215.305894) (xy 133.096762 -215.327738)
			(xy 133.10541 -215.354146) (xy 133.114729 -215.408922) (xy 133.115304 -215.436704) (xy 133.114796 -215.46261)
			(xy 133.396194 -215.46261) (xy 133.396194 -215.41079) (xy 133.4043 -215.359609) (xy 133.420313 -215.310326)
			(xy 133.44384 -215.264155) (xy 133.474299 -215.222232) (xy 133.510941 -215.185591) (xy 133.552865 -215.155133)
			(xy 133.599037 -215.131609) (xy 133.648321 -215.115597) (xy 133.699502 -215.107493) (xy 133.725412 -215.107012)
			(xy 133.750924 -215.107479) (xy 133.80134 -215.115342) (xy 133.849942 -215.130878) (xy 133.89557 -215.153716)
			(xy 133.937135 -215.183311) (xy 133.973645 -215.218956) (xy 133.989318 -215.239092) (xy 134.401306 -215.239092)
			(xy 134.416974 -215.218952) (xy 134.453485 -215.183309) (xy 134.495052 -215.153716) (xy 134.540681 -215.130881)
			(xy 134.589284 -215.115348) (xy 134.6397 -215.107489) (xy 134.665212 -215.107012) (xy 134.691119 -215.107513)
			(xy 134.742295 -215.11562) (xy 134.791573 -215.131633) (xy 134.837739 -215.155158) (xy 134.879656 -215.185614)
			(xy 134.916294 -215.222253) (xy 134.946749 -215.264172) (xy 134.970271 -215.310339) (xy 134.986282 -215.359617)
			(xy 134.994388 -215.410793) (xy 134.994388 -215.462607) (xy 134.986282 -215.513783) (xy 134.970271 -215.563061)
			(xy 134.946749 -215.609228) (xy 134.916294 -215.651147) (xy 134.879656 -215.687786) (xy 134.837739 -215.718242)
			(xy 134.791573 -215.741767) (xy 134.742295 -215.75778) (xy 134.691119 -215.765887) (xy 134.665212 -215.766396)
			(xy 134.6397 -215.765908) (xy 134.589286 -215.758049) (xy 134.540685 -215.742517) (xy 134.495056 -215.719683)
			(xy 134.453491 -215.690092) (xy 134.41698 -215.65445) (xy 134.401306 -215.634316) (xy 133.989318 -215.634316)
			(xy 133.973638 -215.654446) (xy 133.937129 -215.69009) (xy 133.895565 -215.719683) (xy 133.849938 -215.74252)
			(xy 133.801337 -215.758055) (xy 133.750924 -215.765918) (xy 133.725412 -215.766396) (xy 133.699502 -215.765907)
			(xy 133.648321 -215.757803) (xy 133.599037 -215.741791) (xy 133.552865 -215.718267) (xy 133.510941 -215.687809)
			(xy 133.474299 -215.651168) (xy 133.44384 -215.609245) (xy 133.420313 -215.563074) (xy 133.4043 -215.513791)
			(xy 133.396194 -215.46261) (xy 133.114796 -215.46261) (xy 133.114796 -215.462611) (xy 133.10669 -215.513788)
			(xy 133.090678 -215.563067) (xy 133.067155 -215.609234) (xy 133.036699 -215.651153) (xy 133.000061 -215.687791)
			(xy 132.958142 -215.718247) (xy 132.911975 -215.74177) (xy 132.862696 -215.757782) (xy 132.811519 -215.765888)
			(xy 132.759705 -215.765888) (xy 132.708528 -215.757782) (xy 132.659249 -215.74177) (xy 132.613082 -215.718247)
			(xy 132.571163 -215.687791) (xy 132.534525 -215.651153) (xy 132.504069 -215.609234) (xy 132.480546 -215.563067)
			(xy 132.464534 -215.513788) (xy 132.456428 -215.462611) (xy 132.45592 -215.436704) (xy 131.235704 -215.436704)
			(xy 131.235196 -215.462611) (xy 131.22709 -215.513788) (xy 131.211078 -215.563067) (xy 131.187555 -215.609234)
			(xy 131.157099 -215.651153) (xy 131.120461 -215.687791) (xy 131.078542 -215.718247) (xy 131.032375 -215.74177)
			(xy 130.983096 -215.757782) (xy 130.931919 -215.765888) (xy 130.880105 -215.765888) (xy 130.828928 -215.757782)
			(xy 130.779649 -215.74177) (xy 130.733482 -215.718247) (xy 130.691563 -215.687791) (xy 130.654925 -215.651153)
			(xy 130.624469 -215.609234) (xy 130.600946 -215.563067) (xy 130.584934 -215.513788) (xy 130.576828 -215.462611)
			(xy 130.57632 -215.436704) (xy 129.356104 -215.436704) (xy 129.355596 -215.462611) (xy 129.34749 -215.513788)
			(xy 129.331478 -215.563067) (xy 129.307955 -215.609234) (xy 129.277499 -215.651153) (xy 129.240861 -215.687791)
			(xy 129.198942 -215.718247) (xy 129.152775 -215.74177) (xy 129.103496 -215.757782) (xy 129.052319 -215.765888)
			(xy 129.000505 -215.765888) (xy 128.949328 -215.757782) (xy 128.900049 -215.74177) (xy 128.853882 -215.718247)
			(xy 128.811963 -215.687791) (xy 128.775325 -215.651153) (xy 128.744869 -215.609234) (xy 128.721346 -215.563067)
			(xy 128.705334 -215.513788) (xy 128.697228 -215.462611) (xy 128.69672 -215.436704) (xy 127.476504 -215.436704)
			(xy 127.475996 -215.462611) (xy 127.46789 -215.513788) (xy 127.451878 -215.563067) (xy 127.428355 -215.609234)
			(xy 127.397899 -215.651153) (xy 127.361261 -215.687791) (xy 127.319342 -215.718247) (xy 127.273175 -215.74177)
			(xy 127.223896 -215.757782) (xy 127.172719 -215.765888) (xy 127.120905 -215.765888) (xy 127.069728 -215.757782)
			(xy 127.020449 -215.74177) (xy 126.974282 -215.718247) (xy 126.932363 -215.687791) (xy 126.895725 -215.651153)
			(xy 126.865269 -215.609234) (xy 126.841746 -215.563067) (xy 126.825734 -215.513788) (xy 126.817628 -215.462611)
			(xy 126.81712 -215.436704) (xy 125.596904 -215.436704) (xy 125.596396 -215.462611) (xy 125.58829 -215.513788)
			(xy 125.572278 -215.563067) (xy 125.548755 -215.609234) (xy 125.518299 -215.651153) (xy 125.481661 -215.687791)
			(xy 125.439742 -215.718247) (xy 125.393575 -215.74177) (xy 125.344296 -215.757782) (xy 125.293119 -215.765888)
			(xy 125.241305 -215.765888) (xy 125.190128 -215.757782) (xy 125.140849 -215.74177) (xy 125.094682 -215.718247)
			(xy 125.052763 -215.687791) (xy 125.016125 -215.651153) (xy 124.985669 -215.609234) (xy 124.962146 -215.563067)
			(xy 124.946134 -215.513788) (xy 124.938028 -215.462611) (xy 124.93752 -215.436704) (xy 123.717304 -215.436704)
			(xy 123.716796 -215.462611) (xy 123.70869 -215.513788) (xy 123.692678 -215.563067) (xy 123.669155 -215.609234)
			(xy 123.638699 -215.651153) (xy 123.602061 -215.687791) (xy 123.560142 -215.718247) (xy 123.513975 -215.74177)
			(xy 123.464696 -215.757782) (xy 123.413519 -215.765888) (xy 123.361705 -215.765888) (xy 123.310528 -215.757782)
			(xy 123.261249 -215.74177) (xy 123.215082 -215.718247) (xy 123.173163 -215.687791) (xy 123.136525 -215.651153)
			(xy 123.106069 -215.609234) (xy 123.082546 -215.563067) (xy 123.066534 -215.513788) (xy 123.058428 -215.462611)
			(xy 123.05792 -215.436704) (xy 121.837704 -215.436704) (xy 121.837196 -215.462611) (xy 121.82909 -215.513788)
			(xy 121.813078 -215.563067) (xy 121.789555 -215.609234) (xy 121.759099 -215.651153) (xy 121.722461 -215.687791)
			(xy 121.680542 -215.718247) (xy 121.634375 -215.74177) (xy 121.585096 -215.757782) (xy 121.533919 -215.765888)
			(xy 121.482105 -215.765888) (xy 121.430928 -215.757782) (xy 121.381649 -215.74177) (xy 121.335482 -215.718247)
			(xy 121.293563 -215.687791) (xy 121.256925 -215.651153) (xy 121.226469 -215.609234) (xy 121.202946 -215.563067)
			(xy 121.186934 -215.513788) (xy 121.178828 -215.462611) (xy 121.17832 -215.436704) (xy 119.958104 -215.436704)
			(xy 119.957596 -215.462611) (xy 119.94949 -215.513788) (xy 119.933478 -215.563067) (xy 119.909955 -215.609234)
			(xy 119.879499 -215.651153) (xy 119.842861 -215.687791) (xy 119.800942 -215.718247) (xy 119.754775 -215.74177)
			(xy 119.705496 -215.757782) (xy 119.654319 -215.765888) (xy 119.602505 -215.765888) (xy 119.551328 -215.757782)
			(xy 119.502049 -215.74177) (xy 119.455882 -215.718247) (xy 119.413963 -215.687791) (xy 119.377325 -215.651153)
			(xy 119.346869 -215.609234) (xy 119.323346 -215.563067) (xy 119.307334 -215.513788) (xy 119.299228 -215.462611)
			(xy 119.29872 -215.436704) (xy 118.078504 -215.436704) (xy 118.077996 -215.462611) (xy 118.06989 -215.513788)
			(xy 118.053878 -215.563067) (xy 118.030355 -215.609234) (xy 117.999899 -215.651153) (xy 117.963261 -215.687791)
			(xy 117.921342 -215.718247) (xy 117.875175 -215.74177) (xy 117.825896 -215.757782) (xy 117.774719 -215.765888)
			(xy 117.722905 -215.765888) (xy 117.671728 -215.757782) (xy 117.622449 -215.74177) (xy 117.576282 -215.718247)
			(xy 117.534363 -215.687791) (xy 117.497725 -215.651153) (xy 117.467269 -215.609234) (xy 117.443746 -215.563067)
			(xy 117.427734 -215.513788) (xy 117.419628 -215.462611) (xy 117.41912 -215.436704) (xy 116.198904 -215.436704)
			(xy 116.198396 -215.462611) (xy 116.19029 -215.513788) (xy 116.174278 -215.563067) (xy 116.150755 -215.609234)
			(xy 116.120299 -215.651153) (xy 116.083661 -215.687791) (xy 116.041742 -215.718247) (xy 115.995575 -215.74177)
			(xy 115.946296 -215.757782) (xy 115.895119 -215.765888) (xy 115.843305 -215.765888) (xy 115.792128 -215.757782)
			(xy 115.742849 -215.74177) (xy 115.696682 -215.718247) (xy 115.654763 -215.687791) (xy 115.618125 -215.651153)
			(xy 115.587669 -215.609234) (xy 115.564146 -215.563067) (xy 115.548134 -215.513788) (xy 115.540028 -215.462611)
			(xy 115.53952 -215.436704) (xy 114.319304 -215.436704) (xy 114.318796 -215.462611) (xy 114.31069 -215.513788)
			(xy 114.294678 -215.563067) (xy 114.271155 -215.609234) (xy 114.240699 -215.651153) (xy 114.204061 -215.687791)
			(xy 114.162142 -215.718247) (xy 114.115975 -215.74177) (xy 114.066696 -215.757782) (xy 114.015519 -215.765888)
			(xy 113.963705 -215.765888) (xy 113.912528 -215.757782) (xy 113.863249 -215.74177) (xy 113.817082 -215.718247)
			(xy 113.775163 -215.687791) (xy 113.738525 -215.651153) (xy 113.708069 -215.609234) (xy 113.684546 -215.563067)
			(xy 113.668534 -215.513788) (xy 113.660428 -215.462611) (xy 113.65992 -215.436704) (xy 111.499904 -215.436704)
			(xy 111.499396 -215.462611) (xy 111.49129 -215.513788) (xy 111.475278 -215.563067) (xy 111.451755 -215.609234)
			(xy 111.421299 -215.651153) (xy 111.384661 -215.687791) (xy 111.342742 -215.718247) (xy 111.296575 -215.74177)
			(xy 111.247296 -215.757782) (xy 111.196119 -215.765888) (xy 111.144305 -215.765888) (xy 111.093128 -215.757782)
			(xy 111.043849 -215.74177) (xy 110.997682 -215.718247) (xy 110.955763 -215.687791) (xy 110.919125 -215.651153)
			(xy 110.888669 -215.609234) (xy 110.865146 -215.563067) (xy 110.849134 -215.513788) (xy 110.841028 -215.462611)
			(xy 110.84052 -215.436704) (xy 110.840955 -215.413764) (xy 110.847378 -215.368334) (xy 110.860018 -215.324227)
			(xy 110.868968 -215.3031) (xy 110.878874 -215.280494) (xy 110.665006 -214.87511) (xy 110.640876 -214.870538)
			(xy 110.615954 -214.86544) (xy 110.567941 -214.848641) (xy 110.523081 -214.824663) (xy 110.482438 -214.794075)
			(xy 110.44698 -214.757604) (xy 110.417549 -214.716116) (xy 110.394843 -214.670598) (xy 110.379403 -214.622131)
			(xy 110.371595 -214.571867) (xy 110.371128 -214.546434) (xy 109.14142 -214.546434) (xy 109.149388 -214.596747)
			(xy 109.149896 -214.622634) (xy 109.149447 -214.64797) (xy 109.14169 -214.698044) (xy 109.126363 -214.746341)
			(xy 109.103827 -214.791726) (xy 109.074612 -214.833128) (xy 109.039408 -214.869572) (xy 108.999042 -214.900202)
			(xy 108.954465 -214.924296) (xy 108.906727 -214.941286) (xy 108.881926 -214.946484) (xy 108.859066 -214.950802)
			(xy 108.654088 -215.305894) (xy 108.661962 -215.327738) (xy 108.67061 -215.354146) (xy 108.679929 -215.408922)
			(xy 108.680504 -215.436704) (xy 108.679996 -215.46261) (xy 108.961394 -215.46261) (xy 108.961394 -215.41079)
			(xy 108.9695 -215.359609) (xy 108.985513 -215.310326) (xy 109.00904 -215.264155) (xy 109.039499 -215.222232)
			(xy 109.076141 -215.185591) (xy 109.118065 -215.155133) (xy 109.164237 -215.131609) (xy 109.213521 -215.115597)
			(xy 109.264702 -215.107493) (xy 109.290612 -215.107012) (xy 109.316124 -215.107479) (xy 109.36654 -215.115342)
			(xy 109.415142 -215.130878) (xy 109.46077 -215.153716) (xy 109.502335 -215.183311) (xy 109.538845 -215.218956)
			(xy 109.554518 -215.239092) (xy 109.966506 -215.239092) (xy 109.982174 -215.218952) (xy 110.018685 -215.183309)
			(xy 110.060252 -215.153716) (xy 110.105881 -215.130881) (xy 110.154484 -215.115348) (xy 110.2049 -215.107489)
			(xy 110.230412 -215.107012) (xy 110.256319 -215.107513) (xy 110.307495 -215.11562) (xy 110.356773 -215.131633)
			(xy 110.402939 -215.155158) (xy 110.444856 -215.185614) (xy 110.481494 -215.222253) (xy 110.511949 -215.264172)
			(xy 110.535471 -215.310339) (xy 110.551482 -215.359617) (xy 110.559588 -215.410793) (xy 110.559588 -215.462607)
			(xy 110.551482 -215.513783) (xy 110.535471 -215.563061) (xy 110.511949 -215.609228) (xy 110.481494 -215.651147)
			(xy 110.444856 -215.687786) (xy 110.402939 -215.718242) (xy 110.356773 -215.741767) (xy 110.307495 -215.75778)
			(xy 110.256319 -215.765887) (xy 110.230412 -215.766396) (xy 110.2049 -215.765908) (xy 110.154486 -215.758049)
			(xy 110.105885 -215.742517) (xy 110.060256 -215.719683) (xy 110.018691 -215.690092) (xy 109.98218 -215.65445)
			(xy 109.966506 -215.634316) (xy 109.554518 -215.634316) (xy 109.538838 -215.654446) (xy 109.502329 -215.69009)
			(xy 109.460765 -215.719683) (xy 109.415138 -215.74252) (xy 109.366537 -215.758055) (xy 109.316124 -215.765918)
			(xy 109.290612 -215.766396) (xy 109.264702 -215.765907) (xy 109.213521 -215.757803) (xy 109.164237 -215.741791)
			(xy 109.118065 -215.718267) (xy 109.076141 -215.687809) (xy 109.039499 -215.651168) (xy 109.00904 -215.609245)
			(xy 108.985513 -215.563074) (xy 108.9695 -215.513791) (xy 108.961394 -215.46261) (xy 108.679996 -215.46261)
			(xy 108.679996 -215.462611) (xy 108.67189 -215.513788) (xy 108.655878 -215.563067) (xy 108.632355 -215.609234)
			(xy 108.601899 -215.651153) (xy 108.565261 -215.687791) (xy 108.523342 -215.718247) (xy 108.477175 -215.74177)
			(xy 108.427896 -215.757782) (xy 108.376719 -215.765888) (xy 108.324905 -215.765888) (xy 108.273728 -215.757782)
			(xy 108.224449 -215.74177) (xy 108.178282 -215.718247) (xy 108.136363 -215.687791) (xy 108.099725 -215.651153)
			(xy 108.069269 -215.609234) (xy 108.045746 -215.563067) (xy 108.029734 -215.513788) (xy 108.021628 -215.462611)
			(xy 108.02112 -215.436704) (xy 106.800904 -215.436704) (xy 106.800396 -215.462611) (xy 106.79229 -215.513788)
			(xy 106.776278 -215.563067) (xy 106.752755 -215.609234) (xy 106.722299 -215.651153) (xy 106.685661 -215.687791)
			(xy 106.643742 -215.718247) (xy 106.597575 -215.74177) (xy 106.548296 -215.757782) (xy 106.497119 -215.765888)
			(xy 106.445305 -215.765888) (xy 106.394128 -215.757782) (xy 106.344849 -215.74177) (xy 106.298682 -215.718247)
			(xy 106.256763 -215.687791) (xy 106.220125 -215.651153) (xy 106.189669 -215.609234) (xy 106.166146 -215.563067)
			(xy 106.150134 -215.513788) (xy 106.142028 -215.462611) (xy 106.14152 -215.436704) (xy 104.921304 -215.436704)
			(xy 104.920796 -215.462611) (xy 104.91269 -215.513788) (xy 104.896678 -215.563067) (xy 104.873155 -215.609234)
			(xy 104.842699 -215.651153) (xy 104.806061 -215.687791) (xy 104.764142 -215.718247) (xy 104.717975 -215.74177)
			(xy 104.668696 -215.757782) (xy 104.617519 -215.765888) (xy 104.565705 -215.765888) (xy 104.514528 -215.757782)
			(xy 104.465249 -215.74177) (xy 104.419082 -215.718247) (xy 104.377163 -215.687791) (xy 104.340525 -215.651153)
			(xy 104.310069 -215.609234) (xy 104.286546 -215.563067) (xy 104.270534 -215.513788) (xy 104.262428 -215.462611)
			(xy 104.26192 -215.436704) (xy 103.041704 -215.436704) (xy 103.041196 -215.462611) (xy 103.03309 -215.513788)
			(xy 103.017078 -215.563067) (xy 102.993555 -215.609234) (xy 102.963099 -215.651153) (xy 102.926461 -215.687791)
			(xy 102.884542 -215.718247) (xy 102.838375 -215.74177) (xy 102.789096 -215.757782) (xy 102.737919 -215.765888)
			(xy 102.686105 -215.765888) (xy 102.634928 -215.757782) (xy 102.585649 -215.74177) (xy 102.539482 -215.718247)
			(xy 102.497563 -215.687791) (xy 102.460925 -215.651153) (xy 102.430469 -215.609234) (xy 102.406946 -215.563067)
			(xy 102.390934 -215.513788) (xy 102.382828 -215.462611) (xy 102.38232 -215.436704) (xy 101.162104 -215.436704)
			(xy 101.161596 -215.462611) (xy 101.15349 -215.513788) (xy 101.137478 -215.563067) (xy 101.113955 -215.609234)
			(xy 101.083499 -215.651153) (xy 101.046861 -215.687791) (xy 101.004942 -215.718247) (xy 100.958775 -215.74177)
			(xy 100.909496 -215.757782) (xy 100.858319 -215.765888) (xy 100.806505 -215.765888) (xy 100.755328 -215.757782)
			(xy 100.706049 -215.74177) (xy 100.659882 -215.718247) (xy 100.617963 -215.687791) (xy 100.581325 -215.651153)
			(xy 100.550869 -215.609234) (xy 100.527346 -215.563067) (xy 100.511334 -215.513788) (xy 100.503228 -215.462611)
			(xy 100.50272 -215.436704) (xy 99.282504 -215.436704) (xy 99.281996 -215.462611) (xy 99.27389 -215.513788)
			(xy 99.257878 -215.563067) (xy 99.234355 -215.609234) (xy 99.203899 -215.651153) (xy 99.167261 -215.687791)
			(xy 99.125342 -215.718247) (xy 99.079175 -215.74177) (xy 99.029896 -215.757782) (xy 98.978719 -215.765888)
			(xy 98.926905 -215.765888) (xy 98.875728 -215.757782) (xy 98.826449 -215.74177) (xy 98.780282 -215.718247)
			(xy 98.738363 -215.687791) (xy 98.701725 -215.651153) (xy 98.671269 -215.609234) (xy 98.647746 -215.563067)
			(xy 98.631734 -215.513788) (xy 98.623628 -215.462611) (xy 98.62312 -215.436704) (xy 97.402904 -215.436704)
			(xy 97.402396 -215.462611) (xy 97.39429 -215.513788) (xy 97.378278 -215.563067) (xy 97.354755 -215.609234)
			(xy 97.324299 -215.651153) (xy 97.287661 -215.687791) (xy 97.245742 -215.718247) (xy 97.199575 -215.74177)
			(xy 97.150296 -215.757782) (xy 97.099119 -215.765888) (xy 97.047305 -215.765888) (xy 96.996128 -215.757782)
			(xy 96.946849 -215.74177) (xy 96.900682 -215.718247) (xy 96.858763 -215.687791) (xy 96.822125 -215.651153)
			(xy 96.791669 -215.609234) (xy 96.768146 -215.563067) (xy 96.752134 -215.513788) (xy 96.744028 -215.462611)
			(xy 96.74352 -215.436704) (xy 95.523304 -215.436704) (xy 95.522796 -215.462611) (xy 95.51469 -215.513788)
			(xy 95.498678 -215.563067) (xy 95.475155 -215.609234) (xy 95.444699 -215.651153) (xy 95.408061 -215.687791)
			(xy 95.366142 -215.718247) (xy 95.319975 -215.74177) (xy 95.270696 -215.757782) (xy 95.219519 -215.765888)
			(xy 95.167705 -215.765888) (xy 95.116528 -215.757782) (xy 95.067249 -215.74177) (xy 95.021082 -215.718247)
			(xy 94.979163 -215.687791) (xy 94.942525 -215.651153) (xy 94.912069 -215.609234) (xy 94.888546 -215.563067)
			(xy 94.872534 -215.513788) (xy 94.864428 -215.462611) (xy 94.86392 -215.436704) (xy 93.643704 -215.436704)
			(xy 93.643196 -215.462611) (xy 93.63509 -215.513788) (xy 93.619078 -215.563067) (xy 93.595555 -215.609234)
			(xy 93.565099 -215.651153) (xy 93.528461 -215.687791) (xy 93.486542 -215.718247) (xy 93.440375 -215.74177)
			(xy 93.391096 -215.757782) (xy 93.339919 -215.765888) (xy 93.288105 -215.765888) (xy 93.236928 -215.757782)
			(xy 93.187649 -215.74177) (xy 93.141482 -215.718247) (xy 93.099563 -215.687791) (xy 93.062925 -215.651153)
			(xy 93.032469 -215.609234) (xy 93.008946 -215.563067) (xy 92.992934 -215.513788) (xy 92.984828 -215.462611)
			(xy 92.98432 -215.436704) (xy 91.764104 -215.436704) (xy 91.763596 -215.462611) (xy 91.75549 -215.513788)
			(xy 91.739478 -215.563067) (xy 91.715955 -215.609234) (xy 91.685499 -215.651153) (xy 91.648861 -215.687791)
			(xy 91.606942 -215.718247) (xy 91.560775 -215.74177) (xy 91.511496 -215.757782) (xy 91.460319 -215.765888)
			(xy 91.408505 -215.765888) (xy 91.357328 -215.757782) (xy 91.308049 -215.74177) (xy 91.261882 -215.718247)
			(xy 91.219963 -215.687791) (xy 91.183325 -215.651153) (xy 91.152869 -215.609234) (xy 91.129346 -215.563067)
			(xy 91.113334 -215.513788) (xy 91.105228 -215.462611) (xy 91.10472 -215.436704) (xy 89.884504 -215.436704)
			(xy 89.883996 -215.462611) (xy 89.87589 -215.513788) (xy 89.859878 -215.563067) (xy 89.836355 -215.609234)
			(xy 89.805899 -215.651153) (xy 89.769261 -215.687791) (xy 89.727342 -215.718247) (xy 89.681175 -215.74177)
			(xy 89.631896 -215.757782) (xy 89.580719 -215.765888) (xy 89.528905 -215.765888) (xy 89.477728 -215.757782)
			(xy 89.428449 -215.74177) (xy 89.382282 -215.718247) (xy 89.340363 -215.687791) (xy 89.303725 -215.651153)
			(xy 89.273269 -215.609234) (xy 89.249746 -215.563067) (xy 89.233734 -215.513788) (xy 89.225628 -215.462611)
			(xy 89.22512 -215.436704) (xy 88.944704 -215.436704) (xy 88.944111 -215.464421) (xy 88.934787 -215.519068)
			(xy 88.926162 -215.545416) (xy 88.918288 -215.567514) (xy 89.123266 -215.922352) (xy 89.146126 -215.92667)
			(xy 89.170934 -215.931835) (xy 89.218674 -215.948828) (xy 89.263251 -215.972925) (xy 89.303616 -216.003559)
			(xy 89.338819 -216.040009) (xy 89.36803 -216.081415) (xy 89.390562 -216.126804) (xy 89.405883 -216.175106)
			(xy 89.413634 -216.225183) (xy 89.414096 -216.25052) (xy 89.413588 -216.276407) (xy 89.405489 -216.327545)
			(xy 89.38949 -216.376785) (xy 89.365984 -216.422917) (xy 89.335552 -216.464804) (xy 89.298942 -216.501414)
			(xy 89.257055 -216.531846) (xy 89.210923 -216.555352) (xy 89.161683 -216.571351) (xy 89.110545 -216.57945)
			(xy 89.058771 -216.57945) (xy 89.007633 -216.571351) (xy 88.958393 -216.555352) (xy 88.912261 -216.531846)
			(xy 88.870374 -216.501414) (xy 88.833764 -216.464804) (xy 88.803332 -216.422917) (xy 88.779826 -216.376785)
			(xy 88.763827 -216.327545) (xy 88.755728 -216.276407) (xy 88.75522 -216.25052) (xy 88.755754 -216.222812)
			(xy 88.764946 -216.168165) (xy 88.773508 -216.141808) (xy 88.781382 -216.11971) (xy 88.576404 -215.764872)
			(xy 88.553544 -215.760554) (xy 88.528711 -215.755439) (xy 88.480928 -215.73848) (xy 88.436306 -215.714403)
			(xy 88.395898 -215.683776) (xy 88.360658 -215.647323) (xy 88.331415 -215.605902) (xy 88.308862 -215.560492)
			(xy 88.293529 -215.512163) (xy 88.285778 -215.462056) (xy 88.28532 -215.436704) (xy 2.509012 -215.436704)
			(xy 2.509012 -217.878406) (xy 88.755728 -217.878406) (xy 88.756236 -217.852519) (xy 88.764335 -217.801381)
			(xy 88.780334 -217.752141) (xy 88.80384 -217.706009) (xy 88.834272 -217.664122) (xy 88.870882 -217.627512)
			(xy 88.912769 -217.59708) (xy 88.958901 -217.573574) (xy 89.008141 -217.557575) (xy 89.059279 -217.549476)
			(xy 89.111053 -217.549476) (xy 89.162191 -217.557575) (xy 89.211431 -217.573574) (xy 89.257563 -217.59708)
			(xy 89.29945 -217.627512) (xy 89.33606 -217.664122) (xy 89.366492 -217.706009) (xy 89.389998 -217.752141)
			(xy 89.405997 -217.801381) (xy 89.414096 -217.852519) (xy 89.414604 -217.878406) (xy 89.695528 -217.878406)
			(xy 89.695994 -217.853071) (xy 89.703746 -217.802996) (xy 89.719069 -217.754698) (xy 89.741602 -217.709313)
			(xy 89.770814 -217.66791) (xy 89.806017 -217.631464) (xy 89.846382 -217.600835) (xy 89.890959 -217.576742)
			(xy 89.938697 -217.559754) (xy 89.963498 -217.554556) (xy 89.986358 -217.550238) (xy 90.191336 -217.195146)
			(xy 90.183462 -217.173302) (xy 90.174824 -217.146891) (xy 90.165499 -217.092117) (xy 90.16492 -217.064336)
			(xy 90.165428 -217.038429) (xy 90.173534 -216.987252) (xy 90.189546 -216.937973) (xy 90.213069 -216.891806)
			(xy 90.243525 -216.849887) (xy 90.280163 -216.813249) (xy 90.322082 -216.782793) (xy 90.368249 -216.75927)
			(xy 90.417528 -216.743258) (xy 90.468705 -216.735152) (xy 90.520519 -216.735152) (xy 90.571696 -216.743258)
			(xy 90.620975 -216.75927) (xy 90.667142 -216.782793) (xy 90.709061 -216.813249) (xy 90.745699 -216.849887)
			(xy 90.776155 -216.891806) (xy 90.799678 -216.937973) (xy 90.81569 -216.987252) (xy 90.823796 -217.038429)
			(xy 90.824304 -217.064336) (xy 90.823812 -217.08968) (xy 90.816035 -217.13977) (xy 90.800686 -217.188079)
			(xy 90.778125 -217.233471) (xy 90.748884 -217.274876) (xy 90.713652 -217.311319) (xy 90.673259 -217.341943)
			(xy 90.628655 -217.366024) (xy 90.580892 -217.382998) (xy 90.55608 -217.388186) (xy 90.53322 -217.392504)
			(xy 90.328242 -217.747596) (xy 90.336116 -217.76944) (xy 90.344706 -217.795856) (xy 90.353895 -217.850633)
			(xy 90.354404 -217.878406) (xy 90.635328 -217.878406) (xy 90.635836 -217.852519) (xy 90.643935 -217.801381)
			(xy 90.659934 -217.752141) (xy 90.68344 -217.706009) (xy 90.713872 -217.664122) (xy 90.750482 -217.627512)
			(xy 90.792369 -217.59708) (xy 90.838501 -217.573574) (xy 90.887741 -217.557575) (xy 90.938879 -217.549476)
			(xy 90.990653 -217.549476) (xy 91.041791 -217.557575) (xy 91.091031 -217.573574) (xy 91.137163 -217.59708)
			(xy 91.17905 -217.627512) (xy 91.21566 -217.664122) (xy 91.246092 -217.706009) (xy 91.269598 -217.752141)
			(xy 91.285597 -217.801381) (xy 91.293696 -217.852519) (xy 91.294204 -217.878406) (xy 91.575128 -217.878406)
			(xy 91.575594 -217.853071) (xy 91.583346 -217.802996) (xy 91.598669 -217.754698) (xy 91.621202 -217.709313)
			(xy 91.650414 -217.66791) (xy 91.685617 -217.631464) (xy 91.725982 -217.600835) (xy 91.770559 -217.576742)
			(xy 91.818297 -217.559754) (xy 91.843098 -217.554556) (xy 91.865958 -217.550238) (xy 92.070936 -217.195146)
			(xy 92.063062 -217.173302) (xy 92.054424 -217.146891) (xy 92.045099 -217.092117) (xy 92.04452 -217.064336)
			(xy 92.045028 -217.038429) (xy 92.053134 -216.987252) (xy 92.069146 -216.937973) (xy 92.092669 -216.891806)
			(xy 92.123125 -216.849887) (xy 92.159763 -216.813249) (xy 92.201682 -216.782793) (xy 92.247849 -216.75927)
			(xy 92.297128 -216.743258) (xy 92.348305 -216.735152) (xy 92.400119 -216.735152) (xy 92.451296 -216.743258)
			(xy 92.500575 -216.75927) (xy 92.546742 -216.782793) (xy 92.588661 -216.813249) (xy 92.625299 -216.849887)
			(xy 92.655755 -216.891806) (xy 92.679278 -216.937973) (xy 92.69529 -216.987252) (xy 92.703396 -217.038429)
			(xy 92.703904 -217.064336) (xy 92.703412 -217.08968) (xy 92.695635 -217.13977) (xy 92.680286 -217.188079)
			(xy 92.657725 -217.233471) (xy 92.628484 -217.274876) (xy 92.593252 -217.311319) (xy 92.552859 -217.341943)
			(xy 92.508255 -217.366024) (xy 92.460492 -217.382998) (xy 92.43568 -217.388186) (xy 92.41282 -217.392504)
			(xy 92.207842 -217.747596) (xy 92.215716 -217.76944) (xy 92.224306 -217.795856) (xy 92.233495 -217.850633)
			(xy 92.234004 -217.878406) (xy 92.514928 -217.878406) (xy 92.515436 -217.852519) (xy 92.523535 -217.801381)
			(xy 92.539534 -217.752141) (xy 92.56304 -217.706009) (xy 92.593472 -217.664122) (xy 92.630082 -217.627512)
			(xy 92.671969 -217.59708) (xy 92.718101 -217.573574) (xy 92.767341 -217.557575) (xy 92.818479 -217.549476)
			(xy 92.870253 -217.549476) (xy 92.921391 -217.557575) (xy 92.970631 -217.573574) (xy 93.016763 -217.59708)
			(xy 93.05865 -217.627512) (xy 93.09526 -217.664122) (xy 93.125692 -217.706009) (xy 93.149198 -217.752141)
			(xy 93.165197 -217.801381) (xy 93.173296 -217.852519) (xy 93.173804 -217.878406) (xy 93.454728 -217.878406)
			(xy 93.455194 -217.853071) (xy 93.462946 -217.802996) (xy 93.478269 -217.754698) (xy 93.500802 -217.709313)
			(xy 93.530014 -217.66791) (xy 93.565217 -217.631464) (xy 93.605582 -217.600835) (xy 93.650159 -217.576742)
			(xy 93.697897 -217.559754) (xy 93.722698 -217.554556) (xy 93.745558 -217.550238) (xy 93.950536 -217.195146)
			(xy 93.942662 -217.173302) (xy 93.934024 -217.146891) (xy 93.924699 -217.092117) (xy 93.92412 -217.064336)
			(xy 93.924628 -217.038429) (xy 93.932734 -216.987252) (xy 93.948746 -216.937973) (xy 93.972269 -216.891806)
			(xy 94.002725 -216.849887) (xy 94.039363 -216.813249) (xy 94.081282 -216.782793) (xy 94.127449 -216.75927)
			(xy 94.176728 -216.743258) (xy 94.227905 -216.735152) (xy 94.279719 -216.735152) (xy 94.330896 -216.743258)
			(xy 94.380175 -216.75927) (xy 94.426342 -216.782793) (xy 94.468261 -216.813249) (xy 94.504899 -216.849887)
			(xy 94.535355 -216.891806) (xy 94.558878 -216.937973) (xy 94.57489 -216.987252) (xy 94.582996 -217.038429)
			(xy 94.583504 -217.064336) (xy 94.583012 -217.08968) (xy 94.575235 -217.13977) (xy 94.559886 -217.188079)
			(xy 94.537325 -217.233471) (xy 94.508084 -217.274876) (xy 94.472852 -217.311319) (xy 94.432459 -217.341943)
			(xy 94.387855 -217.366024) (xy 94.340092 -217.382998) (xy 94.31528 -217.388186) (xy 94.29242 -217.392504)
			(xy 94.087442 -217.747596) (xy 94.095316 -217.76944) (xy 94.103906 -217.795856) (xy 94.113095 -217.850633)
			(xy 94.113604 -217.878406) (xy 94.394528 -217.878406) (xy 94.395036 -217.852519) (xy 94.403135 -217.801381)
			(xy 94.419134 -217.752141) (xy 94.44264 -217.706009) (xy 94.473072 -217.664122) (xy 94.509682 -217.627512)
			(xy 94.551569 -217.59708) (xy 94.597701 -217.573574) (xy 94.646941 -217.557575) (xy 94.698079 -217.549476)
			(xy 94.749853 -217.549476) (xy 94.800991 -217.557575) (xy 94.850231 -217.573574) (xy 94.896363 -217.59708)
			(xy 94.93825 -217.627512) (xy 94.97486 -217.664122) (xy 95.005292 -217.706009) (xy 95.028798 -217.752141)
			(xy 95.044797 -217.801381) (xy 95.052896 -217.852519) (xy 95.053404 -217.878406) (xy 95.334328 -217.878406)
			(xy 95.334794 -217.853071) (xy 95.342546 -217.802996) (xy 95.357869 -217.754698) (xy 95.380402 -217.709313)
			(xy 95.409614 -217.66791) (xy 95.444817 -217.631464) (xy 95.485182 -217.600835) (xy 95.529759 -217.576742)
			(xy 95.577497 -217.559754) (xy 95.602298 -217.554556) (xy 95.625158 -217.550238) (xy 95.830136 -217.195146)
			(xy 95.822262 -217.173302) (xy 95.813624 -217.146891) (xy 95.804299 -217.092117) (xy 95.80372 -217.064336)
			(xy 95.804228 -217.038429) (xy 95.812334 -216.987252) (xy 95.828346 -216.937973) (xy 95.851869 -216.891806)
			(xy 95.882325 -216.849887) (xy 95.918963 -216.813249) (xy 95.960882 -216.782793) (xy 96.007049 -216.75927)
			(xy 96.056328 -216.743258) (xy 96.107505 -216.735152) (xy 96.159319 -216.735152) (xy 96.210496 -216.743258)
			(xy 96.259775 -216.75927) (xy 96.305942 -216.782793) (xy 96.347861 -216.813249) (xy 96.384499 -216.849887)
			(xy 96.414955 -216.891806) (xy 96.438478 -216.937973) (xy 96.45449 -216.987252) (xy 96.462596 -217.038429)
			(xy 96.463104 -217.064336) (xy 96.462612 -217.08968) (xy 96.454835 -217.13977) (xy 96.439486 -217.188079)
			(xy 96.416925 -217.233471) (xy 96.387684 -217.274876) (xy 96.352452 -217.311319) (xy 96.312059 -217.341943)
			(xy 96.267455 -217.366024) (xy 96.219692 -217.382998) (xy 96.19488 -217.388186) (xy 96.17202 -217.392504)
			(xy 95.967042 -217.747596) (xy 95.974916 -217.76944) (xy 95.983506 -217.795856) (xy 95.992695 -217.850633)
			(xy 95.993204 -217.878406) (xy 96.274128 -217.878406) (xy 96.274636 -217.852519) (xy 96.282735 -217.801381)
			(xy 96.298734 -217.752141) (xy 96.32224 -217.706009) (xy 96.352672 -217.664122) (xy 96.389282 -217.627512)
			(xy 96.431169 -217.59708) (xy 96.477301 -217.573574) (xy 96.526541 -217.557575) (xy 96.577679 -217.549476)
			(xy 96.629453 -217.549476) (xy 96.680591 -217.557575) (xy 96.729831 -217.573574) (xy 96.775963 -217.59708)
			(xy 96.81785 -217.627512) (xy 96.85446 -217.664122) (xy 96.884892 -217.706009) (xy 96.908398 -217.752141)
			(xy 96.924397 -217.801381) (xy 96.932496 -217.852519) (xy 96.933004 -217.878406) (xy 97.213928 -217.878406)
			(xy 97.214394 -217.853071) (xy 97.222146 -217.802996) (xy 97.237469 -217.754698) (xy 97.260002 -217.709313)
			(xy 97.289214 -217.66791) (xy 97.324417 -217.631464) (xy 97.364782 -217.600835) (xy 97.409359 -217.576742)
			(xy 97.457097 -217.559754) (xy 97.481898 -217.554556) (xy 97.504758 -217.550238) (xy 97.709736 -217.195146)
			(xy 97.701862 -217.173302) (xy 97.693224 -217.146891) (xy 97.683899 -217.092117) (xy 97.68332 -217.064336)
			(xy 97.683828 -217.038429) (xy 97.691934 -216.987252) (xy 97.707946 -216.937973) (xy 97.731469 -216.891806)
			(xy 97.761925 -216.849887) (xy 97.798563 -216.813249) (xy 97.840482 -216.782793) (xy 97.886649 -216.75927)
			(xy 97.935928 -216.743258) (xy 97.987105 -216.735152) (xy 98.038919 -216.735152) (xy 98.090096 -216.743258)
			(xy 98.139375 -216.75927) (xy 98.185542 -216.782793) (xy 98.227461 -216.813249) (xy 98.264099 -216.849887)
			(xy 98.294555 -216.891806) (xy 98.318078 -216.937973) (xy 98.33409 -216.987252) (xy 98.342196 -217.038429)
			(xy 98.342704 -217.064336) (xy 98.342212 -217.08968) (xy 98.334435 -217.13977) (xy 98.319086 -217.188079)
			(xy 98.296525 -217.233471) (xy 98.267284 -217.274876) (xy 98.232052 -217.311319) (xy 98.191659 -217.341943)
			(xy 98.147055 -217.366024) (xy 98.099292 -217.382998) (xy 98.07448 -217.388186) (xy 98.05162 -217.392504)
			(xy 97.846642 -217.747596) (xy 97.854516 -217.76944) (xy 97.863106 -217.795856) (xy 97.872295 -217.850633)
			(xy 97.872804 -217.878406) (xy 98.153728 -217.878406) (xy 98.154236 -217.852519) (xy 98.162335 -217.801381)
			(xy 98.178334 -217.752141) (xy 98.20184 -217.706009) (xy 98.232272 -217.664122) (xy 98.268882 -217.627512)
			(xy 98.310769 -217.59708) (xy 98.356901 -217.573574) (xy 98.406141 -217.557575) (xy 98.457279 -217.549476)
			(xy 98.509053 -217.549476) (xy 98.560191 -217.557575) (xy 98.609431 -217.573574) (xy 98.655563 -217.59708)
			(xy 98.69745 -217.627512) (xy 98.73406 -217.664122) (xy 98.764492 -217.706009) (xy 98.787998 -217.752141)
			(xy 98.803997 -217.801381) (xy 98.812096 -217.852519) (xy 98.812604 -217.878406) (xy 99.093528 -217.878406)
			(xy 99.093994 -217.853071) (xy 99.101746 -217.802996) (xy 99.117069 -217.754698) (xy 99.139602 -217.709313)
			(xy 99.168814 -217.66791) (xy 99.204017 -217.631464) (xy 99.244382 -217.600835) (xy 99.288959 -217.576742)
			(xy 99.336697 -217.559754) (xy 99.361498 -217.554556) (xy 99.384358 -217.550238) (xy 99.589336 -217.195146)
			(xy 99.581462 -217.173302) (xy 99.572824 -217.146891) (xy 99.563499 -217.092117) (xy 99.56292 -217.064336)
			(xy 99.563428 -217.038429) (xy 99.571534 -216.987252) (xy 99.587546 -216.937973) (xy 99.611069 -216.891806)
			(xy 99.641525 -216.849887) (xy 99.678163 -216.813249) (xy 99.720082 -216.782793) (xy 99.766249 -216.75927)
			(xy 99.815528 -216.743258) (xy 99.866705 -216.735152) (xy 99.918519 -216.735152) (xy 99.969696 -216.743258)
			(xy 100.018975 -216.75927) (xy 100.065142 -216.782793) (xy 100.107061 -216.813249) (xy 100.143699 -216.849887)
			(xy 100.174155 -216.891806) (xy 100.197678 -216.937973) (xy 100.21369 -216.987252) (xy 100.221796 -217.038429)
			(xy 100.222304 -217.064336) (xy 100.221812 -217.08968) (xy 100.214035 -217.13977) (xy 100.198686 -217.188079)
			(xy 100.176125 -217.233471) (xy 100.146884 -217.274876) (xy 100.111652 -217.311319) (xy 100.071259 -217.341943)
			(xy 100.026655 -217.366024) (xy 99.978892 -217.382998) (xy 99.95408 -217.388186) (xy 99.93122 -217.392504)
			(xy 99.726242 -217.747596) (xy 99.734116 -217.76944) (xy 99.742706 -217.795856) (xy 99.751895 -217.850633)
			(xy 99.752404 -217.878406) (xy 100.033328 -217.878406) (xy 100.033836 -217.852519) (xy 100.041935 -217.801381)
			(xy 100.057934 -217.752141) (xy 100.08144 -217.706009) (xy 100.111872 -217.664122) (xy 100.148482 -217.627512)
			(xy 100.190369 -217.59708) (xy 100.236501 -217.573574) (xy 100.285741 -217.557575) (xy 100.336879 -217.549476)
			(xy 100.388653 -217.549476) (xy 100.439791 -217.557575) (xy 100.489031 -217.573574) (xy 100.535163 -217.59708)
			(xy 100.57705 -217.627512) (xy 100.61366 -217.664122) (xy 100.644092 -217.706009) (xy 100.667598 -217.752141)
			(xy 100.683597 -217.801381) (xy 100.691696 -217.852519) (xy 100.692204 -217.878406) (xy 100.973128 -217.878406)
			(xy 100.973594 -217.853071) (xy 100.981346 -217.802996) (xy 100.996669 -217.754698) (xy 101.019202 -217.709313)
			(xy 101.048414 -217.66791) (xy 101.083617 -217.631464) (xy 101.123982 -217.600835) (xy 101.168559 -217.576742)
			(xy 101.216297 -217.559754) (xy 101.241098 -217.554556) (xy 101.263958 -217.550238) (xy 101.468936 -217.195146)
			(xy 101.461062 -217.173302) (xy 101.452424 -217.146891) (xy 101.443099 -217.092117) (xy 101.44252 -217.064336)
			(xy 101.443028 -217.038429) (xy 101.451134 -216.987252) (xy 101.467146 -216.937973) (xy 101.490669 -216.891806)
			(xy 101.521125 -216.849887) (xy 101.557763 -216.813249) (xy 101.599682 -216.782793) (xy 101.645849 -216.75927)
			(xy 101.695128 -216.743258) (xy 101.746305 -216.735152) (xy 101.798119 -216.735152) (xy 101.849296 -216.743258)
			(xy 101.898575 -216.75927) (xy 101.944742 -216.782793) (xy 101.986661 -216.813249) (xy 102.023299 -216.849887)
			(xy 102.053755 -216.891806) (xy 102.077278 -216.937973) (xy 102.09329 -216.987252) (xy 102.101396 -217.038429)
			(xy 102.101904 -217.064336) (xy 102.101412 -217.08968) (xy 102.093635 -217.13977) (xy 102.078286 -217.188079)
			(xy 102.055725 -217.233471) (xy 102.026484 -217.274876) (xy 101.991252 -217.311319) (xy 101.950859 -217.341943)
			(xy 101.906255 -217.366024) (xy 101.858492 -217.382998) (xy 101.83368 -217.388186) (xy 101.81082 -217.392504)
			(xy 101.605842 -217.747596) (xy 101.613716 -217.76944) (xy 101.622306 -217.795856) (xy 101.631495 -217.850633)
			(xy 101.632004 -217.878406) (xy 101.912928 -217.878406) (xy 101.913436 -217.852519) (xy 101.921535 -217.801381)
			(xy 101.937534 -217.752141) (xy 101.96104 -217.706009) (xy 101.991472 -217.664122) (xy 102.028082 -217.627512)
			(xy 102.069969 -217.59708) (xy 102.116101 -217.573574) (xy 102.165341 -217.557575) (xy 102.216479 -217.549476)
			(xy 102.268253 -217.549476) (xy 102.319391 -217.557575) (xy 102.368631 -217.573574) (xy 102.414763 -217.59708)
			(xy 102.45665 -217.627512) (xy 102.49326 -217.664122) (xy 102.523692 -217.706009) (xy 102.547198 -217.752141)
			(xy 102.563197 -217.801381) (xy 102.571296 -217.852519) (xy 102.571804 -217.878406) (xy 102.852728 -217.878406)
			(xy 102.853194 -217.853071) (xy 102.860946 -217.802996) (xy 102.876269 -217.754698) (xy 102.898802 -217.709313)
			(xy 102.928014 -217.66791) (xy 102.963217 -217.631464) (xy 103.003582 -217.600835) (xy 103.048159 -217.576742)
			(xy 103.095897 -217.559754) (xy 103.120698 -217.554556) (xy 103.143558 -217.550238) (xy 103.348536 -217.195146)
			(xy 103.340662 -217.173302) (xy 103.332024 -217.146891) (xy 103.322699 -217.092117) (xy 103.32212 -217.064336)
			(xy 103.322628 -217.038429) (xy 103.330734 -216.987252) (xy 103.346746 -216.937973) (xy 103.370269 -216.891806)
			(xy 103.400725 -216.849887) (xy 103.437363 -216.813249) (xy 103.479282 -216.782793) (xy 103.525449 -216.75927)
			(xy 103.574728 -216.743258) (xy 103.625905 -216.735152) (xy 103.677719 -216.735152) (xy 103.728896 -216.743258)
			(xy 103.778175 -216.75927) (xy 103.824342 -216.782793) (xy 103.866261 -216.813249) (xy 103.902899 -216.849887)
			(xy 103.933355 -216.891806) (xy 103.956878 -216.937973) (xy 103.97289 -216.987252) (xy 103.980996 -217.038429)
			(xy 103.981504 -217.064336) (xy 103.981012 -217.08968) (xy 103.973235 -217.13977) (xy 103.957886 -217.188079)
			(xy 103.935325 -217.233471) (xy 103.906084 -217.274876) (xy 103.870852 -217.311319) (xy 103.830459 -217.341943)
			(xy 103.785855 -217.366024) (xy 103.738092 -217.382998) (xy 103.71328 -217.388186) (xy 103.69042 -217.392504)
			(xy 103.485442 -217.747596) (xy 103.493316 -217.76944) (xy 103.501906 -217.795856) (xy 103.511095 -217.850633)
			(xy 103.511604 -217.878406) (xy 103.792528 -217.878406) (xy 103.793036 -217.852519) (xy 103.801135 -217.801381)
			(xy 103.817134 -217.752141) (xy 103.84064 -217.706009) (xy 103.871072 -217.664122) (xy 103.907682 -217.627512)
			(xy 103.949569 -217.59708) (xy 103.995701 -217.573574) (xy 104.044941 -217.557575) (xy 104.096079 -217.549476)
			(xy 104.147853 -217.549476) (xy 104.198991 -217.557575) (xy 104.248231 -217.573574) (xy 104.294363 -217.59708)
			(xy 104.33625 -217.627512) (xy 104.37286 -217.664122) (xy 104.403292 -217.706009) (xy 104.426798 -217.752141)
			(xy 104.442797 -217.801381) (xy 104.450896 -217.852519) (xy 104.451404 -217.878406) (xy 104.732328 -217.878406)
			(xy 104.732794 -217.853071) (xy 104.740546 -217.802996) (xy 104.755869 -217.754698) (xy 104.778402 -217.709313)
			(xy 104.807614 -217.66791) (xy 104.842817 -217.631464) (xy 104.883182 -217.600835) (xy 104.927759 -217.576742)
			(xy 104.975497 -217.559754) (xy 105.000298 -217.554556) (xy 105.023158 -217.550238) (xy 105.228136 -217.195146)
			(xy 105.220262 -217.173302) (xy 105.211624 -217.146891) (xy 105.202299 -217.092117) (xy 105.20172 -217.064336)
			(xy 105.202228 -217.038429) (xy 105.210334 -216.987252) (xy 105.226346 -216.937973) (xy 105.249869 -216.891806)
			(xy 105.280325 -216.849887) (xy 105.316963 -216.813249) (xy 105.358882 -216.782793) (xy 105.405049 -216.75927)
			(xy 105.454328 -216.743258) (xy 105.505505 -216.735152) (xy 105.557319 -216.735152) (xy 105.608496 -216.743258)
			(xy 105.657775 -216.75927) (xy 105.703942 -216.782793) (xy 105.745861 -216.813249) (xy 105.782499 -216.849887)
			(xy 105.812955 -216.891806) (xy 105.836478 -216.937973) (xy 105.85249 -216.987252) (xy 105.860596 -217.038429)
			(xy 105.861104 -217.064336) (xy 105.860612 -217.08968) (xy 105.852835 -217.13977) (xy 105.837486 -217.188079)
			(xy 105.814925 -217.233471) (xy 105.785684 -217.274876) (xy 105.750452 -217.311319) (xy 105.710059 -217.341943)
			(xy 105.665455 -217.366024) (xy 105.617692 -217.382998) (xy 105.59288 -217.388186) (xy 105.57002 -217.392504)
			(xy 105.365042 -217.747596) (xy 105.372916 -217.76944) (xy 105.381506 -217.795856) (xy 105.390695 -217.850633)
			(xy 105.391204 -217.878406) (xy 105.672128 -217.878406) (xy 105.672636 -217.852519) (xy 105.680735 -217.801381)
			(xy 105.696734 -217.752141) (xy 105.72024 -217.706009) (xy 105.750672 -217.664122) (xy 105.787282 -217.627512)
			(xy 105.829169 -217.59708) (xy 105.875301 -217.573574) (xy 105.924541 -217.557575) (xy 105.975679 -217.549476)
			(xy 106.027453 -217.549476) (xy 106.078591 -217.557575) (xy 106.127831 -217.573574) (xy 106.173963 -217.59708)
			(xy 106.21585 -217.627512) (xy 106.25246 -217.664122) (xy 106.282892 -217.706009) (xy 106.306398 -217.752141)
			(xy 106.322397 -217.801381) (xy 106.330496 -217.852519) (xy 106.331004 -217.878406) (xy 106.611928 -217.878406)
			(xy 106.612394 -217.853071) (xy 106.620146 -217.802996) (xy 106.635469 -217.754698) (xy 106.658002 -217.709313)
			(xy 106.687214 -217.66791) (xy 106.722417 -217.631464) (xy 106.762782 -217.600835) (xy 106.807359 -217.576742)
			(xy 106.855097 -217.559754) (xy 106.879898 -217.554556) (xy 106.902758 -217.550238) (xy 107.107736 -217.195146)
			(xy 107.099862 -217.173302) (xy 107.091224 -217.146891) (xy 107.081899 -217.092117) (xy 107.08132 -217.064336)
			(xy 107.081828 -217.038429) (xy 107.089934 -216.987252) (xy 107.105946 -216.937973) (xy 107.129469 -216.891806)
			(xy 107.159925 -216.849887) (xy 107.196563 -216.813249) (xy 107.238482 -216.782793) (xy 107.284649 -216.75927)
			(xy 107.333928 -216.743258) (xy 107.385105 -216.735152) (xy 107.436919 -216.735152) (xy 107.488096 -216.743258)
			(xy 107.537375 -216.75927) (xy 107.583542 -216.782793) (xy 107.625461 -216.813249) (xy 107.662099 -216.849887)
			(xy 107.692555 -216.891806) (xy 107.716078 -216.937973) (xy 107.73209 -216.987252) (xy 107.740196 -217.038429)
			(xy 107.740704 -217.064336) (xy 107.740212 -217.08968) (xy 107.732435 -217.13977) (xy 107.717086 -217.188079)
			(xy 107.694525 -217.233471) (xy 107.665284 -217.274876) (xy 107.630052 -217.311319) (xy 107.589659 -217.341943)
			(xy 107.545055 -217.366024) (xy 107.497292 -217.382998) (xy 107.47248 -217.388186) (xy 107.44962 -217.392504)
			(xy 107.244642 -217.747596) (xy 107.252516 -217.76944) (xy 107.261106 -217.795856) (xy 107.270295 -217.850633)
			(xy 107.270804 -217.878406) (xy 107.551728 -217.878406) (xy 107.552236 -217.852519) (xy 107.560335 -217.801381)
			(xy 107.576334 -217.752141) (xy 107.59984 -217.706009) (xy 107.630272 -217.664122) (xy 107.666882 -217.627512)
			(xy 107.708769 -217.59708) (xy 107.754901 -217.573574) (xy 107.804141 -217.557575) (xy 107.855279 -217.549476)
			(xy 107.907053 -217.549476) (xy 107.958191 -217.557575) (xy 108.007431 -217.573574) (xy 108.053563 -217.59708)
			(xy 108.09545 -217.627512) (xy 108.13206 -217.664122) (xy 108.162492 -217.706009) (xy 108.185998 -217.752141)
			(xy 108.201997 -217.801381) (xy 108.210096 -217.852519) (xy 108.210604 -217.878406) (xy 108.491528 -217.878406)
			(xy 108.491994 -217.853071) (xy 108.499746 -217.802996) (xy 108.515069 -217.754698) (xy 108.537602 -217.709313)
			(xy 108.566814 -217.66791) (xy 108.602017 -217.631464) (xy 108.642382 -217.600835) (xy 108.686959 -217.576742)
			(xy 108.734697 -217.559754) (xy 108.759498 -217.554556) (xy 108.782358 -217.550238) (xy 108.987336 -217.195146)
			(xy 108.979462 -217.173302) (xy 108.970824 -217.146891) (xy 108.961499 -217.092117) (xy 108.96092 -217.064336)
			(xy 108.961428 -217.038429) (xy 108.969534 -216.987252) (xy 108.985546 -216.937973) (xy 109.009069 -216.891806)
			(xy 109.039525 -216.849887) (xy 109.076163 -216.813249) (xy 109.118082 -216.782793) (xy 109.164249 -216.75927)
			(xy 109.213528 -216.743258) (xy 109.264705 -216.735152) (xy 109.316519 -216.735152) (xy 109.367696 -216.743258)
			(xy 109.416975 -216.75927) (xy 109.463142 -216.782793) (xy 109.505061 -216.813249) (xy 109.541699 -216.849887)
			(xy 109.572155 -216.891806) (xy 109.595678 -216.937973) (xy 109.61169 -216.987252) (xy 109.619796 -217.038429)
			(xy 109.620304 -217.064336) (xy 109.619812 -217.08968) (xy 109.612035 -217.13977) (xy 109.596686 -217.188079)
			(xy 109.574125 -217.233471) (xy 109.544884 -217.274876) (xy 109.509652 -217.311319) (xy 109.469259 -217.341943)
			(xy 109.424655 -217.366024) (xy 109.376892 -217.382998) (xy 109.35208 -217.388186) (xy 109.32922 -217.392504)
			(xy 109.124242 -217.747596) (xy 109.132116 -217.76944) (xy 109.140706 -217.795856) (xy 109.149895 -217.850633)
			(xy 109.150404 -217.878406) (xy 109.431328 -217.878406) (xy 109.431836 -217.852519) (xy 109.439935 -217.801381)
			(xy 109.455934 -217.752141) (xy 109.47944 -217.706009) (xy 109.509872 -217.664122) (xy 109.546482 -217.627512)
			(xy 109.588369 -217.59708) (xy 109.634501 -217.573574) (xy 109.683741 -217.557575) (xy 109.734879 -217.549476)
			(xy 109.786653 -217.549476) (xy 109.837791 -217.557575) (xy 109.887031 -217.573574) (xy 109.933163 -217.59708)
			(xy 109.97505 -217.627512) (xy 110.01166 -217.664122) (xy 110.042092 -217.706009) (xy 110.065598 -217.752141)
			(xy 110.081597 -217.801381) (xy 110.089696 -217.852519) (xy 110.090204 -217.878406) (xy 110.371128 -217.878406)
			(xy 110.371594 -217.853071) (xy 110.379346 -217.802996) (xy 110.394669 -217.754698) (xy 110.417202 -217.709313)
			(xy 110.446414 -217.66791) (xy 110.481617 -217.631464) (xy 110.521982 -217.600835) (xy 110.566559 -217.576742)
			(xy 110.614297 -217.559754) (xy 110.639098 -217.554556) (xy 110.661958 -217.550238) (xy 110.866936 -217.194892)
			(xy 110.859316 -217.173048) (xy 110.850741 -217.146694) (xy 110.841552 -217.092045) (xy 110.841028 -217.064336)
			(xy 110.841536 -217.038449) (xy 110.849635 -216.987311) (xy 110.865634 -216.938071) (xy 110.88914 -216.891939)
			(xy 110.919572 -216.850052) (xy 110.956182 -216.813442) (xy 110.998069 -216.78301) (xy 111.044201 -216.759504)
			(xy 111.093441 -216.743505) (xy 111.144579 -216.735406) (xy 111.196353 -216.735406) (xy 111.247491 -216.743505)
			(xy 111.296731 -216.759504) (xy 111.342863 -216.78301) (xy 111.38475 -216.813442) (xy 111.42136 -216.850052)
			(xy 111.451792 -216.891939) (xy 111.475298 -216.938071) (xy 111.491297 -216.987311) (xy 111.499396 -217.038449)
			(xy 111.499904 -217.064336) (xy 112.72012 -217.064336) (xy 112.720628 -217.038429) (xy 112.728734 -216.987252)
			(xy 112.744746 -216.937973) (xy 112.768269 -216.891806) (xy 112.798725 -216.849887) (xy 112.835363 -216.813249)
			(xy 112.877282 -216.782793) (xy 112.923449 -216.75927) (xy 112.972728 -216.743258) (xy 113.023905 -216.735152)
			(xy 113.075719 -216.735152) (xy 113.126896 -216.743258) (xy 113.176175 -216.75927) (xy 113.222342 -216.782793)
			(xy 113.264261 -216.813249) (xy 113.300899 -216.849887) (xy 113.331355 -216.891806) (xy 113.354878 -216.937973)
			(xy 113.37089 -216.987252) (xy 113.378996 -217.038429) (xy 113.379504 -217.064336) (xy 114.59972 -217.064336)
			(xy 114.600228 -217.038429) (xy 114.608334 -216.987252) (xy 114.624346 -216.937973) (xy 114.647869 -216.891806)
			(xy 114.678325 -216.849887) (xy 114.714963 -216.813249) (xy 114.756882 -216.782793) (xy 114.803049 -216.75927)
			(xy 114.852328 -216.743258) (xy 114.903505 -216.735152) (xy 114.955319 -216.735152) (xy 115.006496 -216.743258)
			(xy 115.055775 -216.75927) (xy 115.101942 -216.782793) (xy 115.143861 -216.813249) (xy 115.180499 -216.849887)
			(xy 115.210955 -216.891806) (xy 115.234478 -216.937973) (xy 115.25049 -216.987252) (xy 115.258596 -217.038429)
			(xy 115.259104 -217.064336) (xy 116.47932 -217.064336) (xy 116.479828 -217.038429) (xy 116.487934 -216.987252)
			(xy 116.503946 -216.937973) (xy 116.527469 -216.891806) (xy 116.557925 -216.849887) (xy 116.594563 -216.813249)
			(xy 116.636482 -216.782793) (xy 116.682649 -216.75927) (xy 116.731928 -216.743258) (xy 116.783105 -216.735152)
			(xy 116.834919 -216.735152) (xy 116.886096 -216.743258) (xy 116.935375 -216.75927) (xy 116.981542 -216.782793)
			(xy 117.023461 -216.813249) (xy 117.060099 -216.849887) (xy 117.090555 -216.891806) (xy 117.114078 -216.937973)
			(xy 117.13009 -216.987252) (xy 117.138196 -217.038429) (xy 117.138704 -217.064336) (xy 118.35892 -217.064336)
			(xy 118.359428 -217.038429) (xy 118.367534 -216.987252) (xy 118.383546 -216.937973) (xy 118.407069 -216.891806)
			(xy 118.437525 -216.849887) (xy 118.474163 -216.813249) (xy 118.516082 -216.782793) (xy 118.562249 -216.75927)
			(xy 118.611528 -216.743258) (xy 118.662705 -216.735152) (xy 118.714519 -216.735152) (xy 118.765696 -216.743258)
			(xy 118.814975 -216.75927) (xy 118.861142 -216.782793) (xy 118.903061 -216.813249) (xy 118.939699 -216.849887)
			(xy 118.970155 -216.891806) (xy 118.993678 -216.937973) (xy 119.00969 -216.987252) (xy 119.017796 -217.038429)
			(xy 119.018304 -217.064336) (xy 120.23852 -217.064336) (xy 120.239028 -217.038429) (xy 120.247134 -216.987252)
			(xy 120.263146 -216.937973) (xy 120.286669 -216.891806) (xy 120.317125 -216.849887) (xy 120.353763 -216.813249)
			(xy 120.395682 -216.782793) (xy 120.441849 -216.75927) (xy 120.491128 -216.743258) (xy 120.542305 -216.735152)
			(xy 120.594119 -216.735152) (xy 120.645296 -216.743258) (xy 120.694575 -216.75927) (xy 120.740742 -216.782793)
			(xy 120.782661 -216.813249) (xy 120.819299 -216.849887) (xy 120.849755 -216.891806) (xy 120.873278 -216.937973)
			(xy 120.88929 -216.987252) (xy 120.897396 -217.038429) (xy 120.897904 -217.064336) (xy 122.11812 -217.064336)
			(xy 122.118628 -217.038429) (xy 122.126734 -216.987252) (xy 122.142746 -216.937973) (xy 122.166269 -216.891806)
			(xy 122.196725 -216.849887) (xy 122.233363 -216.813249) (xy 122.275282 -216.782793) (xy 122.321449 -216.75927)
			(xy 122.370728 -216.743258) (xy 122.421905 -216.735152) (xy 122.473719 -216.735152) (xy 122.524896 -216.743258)
			(xy 122.574175 -216.75927) (xy 122.620342 -216.782793) (xy 122.662261 -216.813249) (xy 122.698899 -216.849887)
			(xy 122.729355 -216.891806) (xy 122.752878 -216.937973) (xy 122.76889 -216.987252) (xy 122.776996 -217.038429)
			(xy 122.777504 -217.064336) (xy 123.99772 -217.064336) (xy 123.998228 -217.038429) (xy 124.006334 -216.987252)
			(xy 124.022346 -216.937973) (xy 124.045869 -216.891806) (xy 124.076325 -216.849887) (xy 124.112963 -216.813249)
			(xy 124.154882 -216.782793) (xy 124.201049 -216.75927) (xy 124.250328 -216.743258) (xy 124.301505 -216.735152)
			(xy 124.353319 -216.735152) (xy 124.404496 -216.743258) (xy 124.453775 -216.75927) (xy 124.499942 -216.782793)
			(xy 124.541861 -216.813249) (xy 124.578499 -216.849887) (xy 124.608955 -216.891806) (xy 124.632478 -216.937973)
			(xy 124.64849 -216.987252) (xy 124.656596 -217.038429) (xy 124.657104 -217.064336) (xy 125.87732 -217.064336)
			(xy 125.877828 -217.038429) (xy 125.885934 -216.987252) (xy 125.901946 -216.937973) (xy 125.925469 -216.891806)
			(xy 125.955925 -216.849887) (xy 125.992563 -216.813249) (xy 126.034482 -216.782793) (xy 126.080649 -216.75927)
			(xy 126.129928 -216.743258) (xy 126.181105 -216.735152) (xy 126.232919 -216.735152) (xy 126.284096 -216.743258)
			(xy 126.333375 -216.75927) (xy 126.379542 -216.782793) (xy 126.421461 -216.813249) (xy 126.458099 -216.849887)
			(xy 126.488555 -216.891806) (xy 126.512078 -216.937973) (xy 126.52809 -216.987252) (xy 126.536196 -217.038429)
			(xy 126.536704 -217.064336) (xy 127.75692 -217.064336) (xy 127.757428 -217.038429) (xy 127.765534 -216.987252)
			(xy 127.781546 -216.937973) (xy 127.805069 -216.891806) (xy 127.835525 -216.849887) (xy 127.872163 -216.813249)
			(xy 127.914082 -216.782793) (xy 127.960249 -216.75927) (xy 128.009528 -216.743258) (xy 128.060705 -216.735152)
			(xy 128.112519 -216.735152) (xy 128.163696 -216.743258) (xy 128.212975 -216.75927) (xy 128.259142 -216.782793)
			(xy 128.301061 -216.813249) (xy 128.337699 -216.849887) (xy 128.368155 -216.891806) (xy 128.391678 -216.937973)
			(xy 128.40769 -216.987252) (xy 128.415796 -217.038429) (xy 128.416304 -217.064336) (xy 129.63652 -217.064336)
			(xy 129.637028 -217.038429) (xy 129.645134 -216.987252) (xy 129.661146 -216.937973) (xy 129.684669 -216.891806)
			(xy 129.715125 -216.849887) (xy 129.751763 -216.813249) (xy 129.793682 -216.782793) (xy 129.839849 -216.75927)
			(xy 129.889128 -216.743258) (xy 129.940305 -216.735152) (xy 129.992119 -216.735152) (xy 130.043296 -216.743258)
			(xy 130.092575 -216.75927) (xy 130.138742 -216.782793) (xy 130.180661 -216.813249) (xy 130.217299 -216.849887)
			(xy 130.247755 -216.891806) (xy 130.271278 -216.937973) (xy 130.28729 -216.987252) (xy 130.295396 -217.038429)
			(xy 130.295904 -217.064336) (xy 131.51612 -217.064336) (xy 131.516628 -217.038429) (xy 131.524734 -216.987252)
			(xy 131.540746 -216.937973) (xy 131.564269 -216.891806) (xy 131.594725 -216.849887) (xy 131.631363 -216.813249)
			(xy 131.673282 -216.782793) (xy 131.719449 -216.75927) (xy 131.768728 -216.743258) (xy 131.819905 -216.735152)
			(xy 131.871719 -216.735152) (xy 131.922896 -216.743258) (xy 131.972175 -216.75927) (xy 132.018342 -216.782793)
			(xy 132.060261 -216.813249) (xy 132.096899 -216.849887) (xy 132.127355 -216.891806) (xy 132.150878 -216.937973)
			(xy 132.16689 -216.987252) (xy 132.174996 -217.038429) (xy 132.175504 -217.064336) (xy 133.39572 -217.064336)
			(xy 133.396228 -217.038429) (xy 133.404334 -216.987252) (xy 133.420346 -216.937973) (xy 133.443869 -216.891806)
			(xy 133.474325 -216.849887) (xy 133.510963 -216.813249) (xy 133.552882 -216.782793) (xy 133.599049 -216.75927)
			(xy 133.648328 -216.743258) (xy 133.699505 -216.735152) (xy 133.751319 -216.735152) (xy 133.802496 -216.743258)
			(xy 133.851775 -216.75927) (xy 133.897942 -216.782793) (xy 133.939861 -216.813249) (xy 133.976499 -216.849887)
			(xy 134.006955 -216.891806) (xy 134.030478 -216.937973) (xy 134.04649 -216.987252) (xy 134.054596 -217.038429)
			(xy 134.055104 -217.064336) (xy 134.054489 -217.091989) (xy 134.045169 -217.146507) (xy 134.036562 -217.172794)
			(xy 134.028942 -217.194892) (xy 134.234174 -217.550238) (xy 134.257034 -217.554556) (xy 134.281841 -217.559728)
			(xy 134.329579 -217.576721) (xy 134.374156 -217.600818) (xy 134.41452 -217.631451) (xy 134.449723 -217.6679)
			(xy 134.478934 -217.709305) (xy 134.501466 -217.754693) (xy 134.516789 -217.802993) (xy 134.524541 -217.85307)
			(xy 134.525004 -217.878406) (xy 336.695796 -217.878406) (xy 336.696304 -217.852519) (xy 336.704403 -217.801381)
			(xy 336.720402 -217.752141) (xy 336.743908 -217.706009) (xy 336.77434 -217.664122) (xy 336.81095 -217.627512)
			(xy 336.852837 -217.59708) (xy 336.898969 -217.573574) (xy 336.948209 -217.557575) (xy 336.999347 -217.549476)
			(xy 337.051121 -217.549476) (xy 337.102259 -217.557575) (xy 337.151499 -217.573574) (xy 337.197631 -217.59708)
			(xy 337.239518 -217.627512) (xy 337.276128 -217.664122) (xy 337.30656 -217.706009) (xy 337.330066 -217.752141)
			(xy 337.346065 -217.801381) (xy 337.354164 -217.852519) (xy 337.354672 -217.878406) (xy 337.635596 -217.878406)
			(xy 337.636088 -217.853072) (xy 337.643839 -217.803) (xy 337.65916 -217.754704) (xy 337.681691 -217.70932)
			(xy 337.710899 -217.667918) (xy 337.746099 -217.631473) (xy 337.78646 -217.600842) (xy 337.831033 -217.576747)
			(xy 337.878767 -217.559756) (xy 337.903566 -217.554556) (xy 337.926426 -217.550238) (xy 338.131404 -217.195146)
			(xy 338.12353 -217.173302) (xy 338.114891 -217.146892) (xy 338.105567 -217.092117) (xy 338.104988 -217.064336)
			(xy 338.105496 -217.038429) (xy 338.113602 -216.987252) (xy 338.129614 -216.937973) (xy 338.153137 -216.891806)
			(xy 338.183593 -216.849887) (xy 338.220231 -216.813249) (xy 338.26215 -216.782793) (xy 338.308317 -216.75927)
			(xy 338.357596 -216.743258) (xy 338.408773 -216.735152) (xy 338.460587 -216.735152) (xy 338.511764 -216.743258)
			(xy 338.561043 -216.75927) (xy 338.60721 -216.782793) (xy 338.649129 -216.813249) (xy 338.685767 -216.849887)
			(xy 338.716223 -216.891806) (xy 338.739746 -216.937973) (xy 338.755758 -216.987252) (xy 338.763864 -217.038429)
			(xy 338.764372 -217.064336) (xy 338.763906 -217.089682) (xy 338.756128 -217.139773) (xy 338.740777 -217.188085)
			(xy 338.718213 -217.233478) (xy 338.688969 -217.274884) (xy 338.653734 -217.311328) (xy 338.613336 -217.34195)
			(xy 338.568729 -217.36603) (xy 338.520962 -217.383) (xy 338.496148 -217.388186) (xy 338.473288 -217.392504)
			(xy 338.26831 -217.747596) (xy 338.276184 -217.76944) (xy 338.284773 -217.795856) (xy 338.293963 -217.850633)
			(xy 338.294472 -217.878406) (xy 338.575396 -217.878406) (xy 338.575904 -217.852519) (xy 338.584003 -217.801381)
			(xy 338.600002 -217.752141) (xy 338.623508 -217.706009) (xy 338.65394 -217.664122) (xy 338.69055 -217.627512)
			(xy 338.732437 -217.59708) (xy 338.778569 -217.573574) (xy 338.827809 -217.557575) (xy 338.878947 -217.549476)
			(xy 338.930721 -217.549476) (xy 338.981859 -217.557575) (xy 339.031099 -217.573574) (xy 339.077231 -217.59708)
			(xy 339.119118 -217.627512) (xy 339.155728 -217.664122) (xy 339.18616 -217.706009) (xy 339.209666 -217.752141)
			(xy 339.225665 -217.801381) (xy 339.233764 -217.852519) (xy 339.234272 -217.878406) (xy 339.515196 -217.878406)
			(xy 339.515688 -217.853072) (xy 339.523439 -217.803) (xy 339.53876 -217.754704) (xy 339.561291 -217.70932)
			(xy 339.590499 -217.667918) (xy 339.625699 -217.631473) (xy 339.66606 -217.600842) (xy 339.710633 -217.576747)
			(xy 339.758367 -217.559756) (xy 339.783166 -217.554556) (xy 339.806026 -217.550238) (xy 340.011004 -217.195146)
			(xy 340.00313 -217.173302) (xy 339.994491 -217.146892) (xy 339.985167 -217.092117) (xy 339.984588 -217.064336)
			(xy 339.985096 -217.038429) (xy 339.993202 -216.987252) (xy 340.009214 -216.937973) (xy 340.032737 -216.891806)
			(xy 340.063193 -216.849887) (xy 340.099831 -216.813249) (xy 340.14175 -216.782793) (xy 340.187917 -216.75927)
			(xy 340.237196 -216.743258) (xy 340.288373 -216.735152) (xy 340.340187 -216.735152) (xy 340.391364 -216.743258)
			(xy 340.440643 -216.75927) (xy 340.48681 -216.782793) (xy 340.528729 -216.813249) (xy 340.565367 -216.849887)
			(xy 340.595823 -216.891806) (xy 340.619346 -216.937973) (xy 340.635358 -216.987252) (xy 340.643464 -217.038429)
			(xy 340.643972 -217.064336) (xy 340.643506 -217.089682) (xy 340.635728 -217.139773) (xy 340.620377 -217.188085)
			(xy 340.597813 -217.233478) (xy 340.568569 -217.274884) (xy 340.533334 -217.311328) (xy 340.492936 -217.34195)
			(xy 340.448329 -217.36603) (xy 340.400562 -217.383) (xy 340.375748 -217.388186) (xy 340.352888 -217.392504)
			(xy 340.14791 -217.747596) (xy 340.155784 -217.76944) (xy 340.164373 -217.795856) (xy 340.173563 -217.850633)
			(xy 340.174072 -217.878406) (xy 340.454996 -217.878406) (xy 340.455504 -217.852519) (xy 340.463603 -217.801381)
			(xy 340.479602 -217.752141) (xy 340.503108 -217.706009) (xy 340.53354 -217.664122) (xy 340.57015 -217.627512)
			(xy 340.612037 -217.59708) (xy 340.658169 -217.573574) (xy 340.707409 -217.557575) (xy 340.758547 -217.549476)
			(xy 340.810321 -217.549476) (xy 340.861459 -217.557575) (xy 340.910699 -217.573574) (xy 340.956831 -217.59708)
			(xy 340.998718 -217.627512) (xy 341.035328 -217.664122) (xy 341.06576 -217.706009) (xy 341.089266 -217.752141)
			(xy 341.105265 -217.801381) (xy 341.113364 -217.852519) (xy 341.113872 -217.878406) (xy 341.394796 -217.878406)
			(xy 341.395288 -217.853072) (xy 341.403039 -217.803) (xy 341.41836 -217.754704) (xy 341.440891 -217.70932)
			(xy 341.470099 -217.667918) (xy 341.505299 -217.631473) (xy 341.54566 -217.600842) (xy 341.590233 -217.576747)
			(xy 341.637967 -217.559756) (xy 341.662766 -217.554556) (xy 341.685626 -217.550238) (xy 341.890604 -217.195146)
			(xy 341.88273 -217.173302) (xy 341.874091 -217.146892) (xy 341.864767 -217.092117) (xy 341.864188 -217.064336)
			(xy 341.864696 -217.038429) (xy 341.872802 -216.987252) (xy 341.888814 -216.937973) (xy 341.912337 -216.891806)
			(xy 341.942793 -216.849887) (xy 341.979431 -216.813249) (xy 342.02135 -216.782793) (xy 342.067517 -216.75927)
			(xy 342.116796 -216.743258) (xy 342.167973 -216.735152) (xy 342.219787 -216.735152) (xy 342.270964 -216.743258)
			(xy 342.320243 -216.75927) (xy 342.36641 -216.782793) (xy 342.408329 -216.813249) (xy 342.444967 -216.849887)
			(xy 342.475423 -216.891806) (xy 342.498946 -216.937973) (xy 342.514958 -216.987252) (xy 342.523064 -217.038429)
			(xy 342.523572 -217.064336) (xy 342.523106 -217.089682) (xy 342.515328 -217.139773) (xy 342.499977 -217.188085)
			(xy 342.477413 -217.233478) (xy 342.448169 -217.274884) (xy 342.412934 -217.311328) (xy 342.372536 -217.34195)
			(xy 342.327929 -217.36603) (xy 342.280162 -217.383) (xy 342.255348 -217.388186) (xy 342.232488 -217.392504)
			(xy 342.02751 -217.747596) (xy 342.035384 -217.76944) (xy 342.043973 -217.795856) (xy 342.053163 -217.850633)
			(xy 342.053672 -217.878406) (xy 342.334596 -217.878406) (xy 342.335104 -217.852519) (xy 342.343203 -217.801381)
			(xy 342.359202 -217.752141) (xy 342.382708 -217.706009) (xy 342.41314 -217.664122) (xy 342.44975 -217.627512)
			(xy 342.491637 -217.59708) (xy 342.537769 -217.573574) (xy 342.587009 -217.557575) (xy 342.638147 -217.549476)
			(xy 342.689921 -217.549476) (xy 342.741059 -217.557575) (xy 342.790299 -217.573574) (xy 342.836431 -217.59708)
			(xy 342.878318 -217.627512) (xy 342.914928 -217.664122) (xy 342.94536 -217.706009) (xy 342.968866 -217.752141)
			(xy 342.984865 -217.801381) (xy 342.992964 -217.852519) (xy 342.993472 -217.878406) (xy 343.274396 -217.878406)
			(xy 343.274888 -217.853072) (xy 343.282639 -217.803) (xy 343.29796 -217.754704) (xy 343.320491 -217.70932)
			(xy 343.349699 -217.667918) (xy 343.384899 -217.631473) (xy 343.42526 -217.600842) (xy 343.469833 -217.576747)
			(xy 343.517567 -217.559756) (xy 343.542366 -217.554556) (xy 343.565226 -217.550238) (xy 343.770204 -217.195146)
			(xy 343.76233 -217.173302) (xy 343.753691 -217.146892) (xy 343.744367 -217.092117) (xy 343.743788 -217.064336)
			(xy 343.744296 -217.038429) (xy 343.752402 -216.987252) (xy 343.768414 -216.937973) (xy 343.791937 -216.891806)
			(xy 343.822393 -216.849887) (xy 343.859031 -216.813249) (xy 343.90095 -216.782793) (xy 343.947117 -216.75927)
			(xy 343.996396 -216.743258) (xy 344.047573 -216.735152) (xy 344.099387 -216.735152) (xy 344.150564 -216.743258)
			(xy 344.199843 -216.75927) (xy 344.24601 -216.782793) (xy 344.287929 -216.813249) (xy 344.324567 -216.849887)
			(xy 344.355023 -216.891806) (xy 344.378546 -216.937973) (xy 344.394558 -216.987252) (xy 344.402664 -217.038429)
			(xy 344.403172 -217.064336) (xy 344.402706 -217.089682) (xy 344.394928 -217.139773) (xy 344.379577 -217.188085)
			(xy 344.357013 -217.233478) (xy 344.327769 -217.274884) (xy 344.292534 -217.311328) (xy 344.252136 -217.34195)
			(xy 344.207529 -217.36603) (xy 344.159762 -217.383) (xy 344.134948 -217.388186) (xy 344.112088 -217.392504)
			(xy 343.90711 -217.747596) (xy 343.914984 -217.76944) (xy 343.923573 -217.795856) (xy 343.932763 -217.850633)
			(xy 343.933272 -217.878406) (xy 344.214196 -217.878406) (xy 344.214704 -217.852519) (xy 344.222803 -217.801381)
			(xy 344.238802 -217.752141) (xy 344.262308 -217.706009) (xy 344.29274 -217.664122) (xy 344.32935 -217.627512)
			(xy 344.371237 -217.59708) (xy 344.417369 -217.573574) (xy 344.466609 -217.557575) (xy 344.517747 -217.549476)
			(xy 344.569521 -217.549476) (xy 344.620659 -217.557575) (xy 344.669899 -217.573574) (xy 344.716031 -217.59708)
			(xy 344.757918 -217.627512) (xy 344.794528 -217.664122) (xy 344.82496 -217.706009) (xy 344.848466 -217.752141)
			(xy 344.864465 -217.801381) (xy 344.872564 -217.852519) (xy 344.873072 -217.878406) (xy 345.153996 -217.878406)
			(xy 345.154488 -217.853072) (xy 345.162239 -217.803) (xy 345.17756 -217.754704) (xy 345.200091 -217.70932)
			(xy 345.229299 -217.667918) (xy 345.264499 -217.631473) (xy 345.30486 -217.600842) (xy 345.349433 -217.576747)
			(xy 345.397167 -217.559756) (xy 345.421966 -217.554556) (xy 345.444826 -217.550238) (xy 345.649804 -217.195146)
			(xy 345.64193 -217.173302) (xy 345.633291 -217.146892) (xy 345.623967 -217.092117) (xy 345.623388 -217.064336)
			(xy 345.623896 -217.038429) (xy 345.632002 -216.987252) (xy 345.648014 -216.937973) (xy 345.671537 -216.891806)
			(xy 345.701993 -216.849887) (xy 345.738631 -216.813249) (xy 345.78055 -216.782793) (xy 345.826717 -216.75927)
			(xy 345.875996 -216.743258) (xy 345.927173 -216.735152) (xy 345.978987 -216.735152) (xy 346.030164 -216.743258)
			(xy 346.079443 -216.75927) (xy 346.12561 -216.782793) (xy 346.167529 -216.813249) (xy 346.204167 -216.849887)
			(xy 346.234623 -216.891806) (xy 346.258146 -216.937973) (xy 346.274158 -216.987252) (xy 346.282264 -217.038429)
			(xy 346.282772 -217.064336) (xy 346.282306 -217.089682) (xy 346.274528 -217.139773) (xy 346.259177 -217.188085)
			(xy 346.236613 -217.233478) (xy 346.207369 -217.274884) (xy 346.172134 -217.311328) (xy 346.131736 -217.34195)
			(xy 346.087129 -217.36603) (xy 346.039362 -217.383) (xy 346.014548 -217.388186) (xy 345.991688 -217.392504)
			(xy 345.78671 -217.747596) (xy 345.794584 -217.76944) (xy 345.803173 -217.795856) (xy 345.812363 -217.850633)
			(xy 345.812872 -217.878406) (xy 346.093796 -217.878406) (xy 346.094304 -217.852519) (xy 346.102403 -217.801381)
			(xy 346.118402 -217.752141) (xy 346.141908 -217.706009) (xy 346.17234 -217.664122) (xy 346.20895 -217.627512)
			(xy 346.250837 -217.59708) (xy 346.296969 -217.573574) (xy 346.346209 -217.557575) (xy 346.397347 -217.549476)
			(xy 346.449121 -217.549476) (xy 346.500259 -217.557575) (xy 346.549499 -217.573574) (xy 346.595631 -217.59708)
			(xy 346.637518 -217.627512) (xy 346.674128 -217.664122) (xy 346.70456 -217.706009) (xy 346.728066 -217.752141)
			(xy 346.744065 -217.801381) (xy 346.752164 -217.852519) (xy 346.752672 -217.878406) (xy 347.033596 -217.878406)
			(xy 347.034088 -217.853072) (xy 347.041839 -217.803) (xy 347.05716 -217.754704) (xy 347.079691 -217.70932)
			(xy 347.108899 -217.667918) (xy 347.144099 -217.631473) (xy 347.18446 -217.600842) (xy 347.229033 -217.576747)
			(xy 347.276767 -217.559756) (xy 347.301566 -217.554556) (xy 347.324426 -217.550238) (xy 347.529404 -217.195146)
			(xy 347.52153 -217.173302) (xy 347.512891 -217.146892) (xy 347.503567 -217.092117) (xy 347.502988 -217.064336)
			(xy 347.503496 -217.038429) (xy 347.511602 -216.987252) (xy 347.527614 -216.937973) (xy 347.551137 -216.891806)
			(xy 347.581593 -216.849887) (xy 347.618231 -216.813249) (xy 347.66015 -216.782793) (xy 347.706317 -216.75927)
			(xy 347.755596 -216.743258) (xy 347.806773 -216.735152) (xy 347.858587 -216.735152) (xy 347.909764 -216.743258)
			(xy 347.959043 -216.75927) (xy 348.00521 -216.782793) (xy 348.047129 -216.813249) (xy 348.083767 -216.849887)
			(xy 348.114223 -216.891806) (xy 348.137746 -216.937973) (xy 348.153758 -216.987252) (xy 348.161864 -217.038429)
			(xy 348.162372 -217.064336) (xy 348.161906 -217.089682) (xy 348.154128 -217.139773) (xy 348.138777 -217.188085)
			(xy 348.116213 -217.233478) (xy 348.086969 -217.274884) (xy 348.051734 -217.311328) (xy 348.011336 -217.34195)
			(xy 347.966729 -217.36603) (xy 347.918962 -217.383) (xy 347.894148 -217.388186) (xy 347.871288 -217.392504)
			(xy 347.66631 -217.747596) (xy 347.674184 -217.76944) (xy 347.682773 -217.795856) (xy 347.691963 -217.850633)
			(xy 347.692472 -217.878406) (xy 347.973396 -217.878406) (xy 347.973904 -217.852519) (xy 347.982003 -217.801381)
			(xy 347.998002 -217.752141) (xy 348.021508 -217.706009) (xy 348.05194 -217.664122) (xy 348.08855 -217.627512)
			(xy 348.130437 -217.59708) (xy 348.176569 -217.573574) (xy 348.225809 -217.557575) (xy 348.276947 -217.549476)
			(xy 348.328721 -217.549476) (xy 348.379859 -217.557575) (xy 348.429099 -217.573574) (xy 348.475231 -217.59708)
			(xy 348.517118 -217.627512) (xy 348.553728 -217.664122) (xy 348.58416 -217.706009) (xy 348.607666 -217.752141)
			(xy 348.623665 -217.801381) (xy 348.631764 -217.852519) (xy 348.632272 -217.878406) (xy 348.913196 -217.878406)
			(xy 348.913688 -217.853072) (xy 348.921439 -217.803) (xy 348.93676 -217.754704) (xy 348.959291 -217.70932)
			(xy 348.988499 -217.667918) (xy 349.023699 -217.631473) (xy 349.06406 -217.600842) (xy 349.108633 -217.576747)
			(xy 349.156367 -217.559756) (xy 349.181166 -217.554556) (xy 349.204026 -217.550238) (xy 349.409004 -217.195146)
			(xy 349.40113 -217.173302) (xy 349.392491 -217.146892) (xy 349.383167 -217.092117) (xy 349.382588 -217.064336)
			(xy 349.383096 -217.038429) (xy 349.391202 -216.987252) (xy 349.407214 -216.937973) (xy 349.430737 -216.891806)
			(xy 349.461193 -216.849887) (xy 349.497831 -216.813249) (xy 349.53975 -216.782793) (xy 349.585917 -216.75927)
			(xy 349.635196 -216.743258) (xy 349.686373 -216.735152) (xy 349.738187 -216.735152) (xy 349.789364 -216.743258)
			(xy 349.838643 -216.75927) (xy 349.88481 -216.782793) (xy 349.926729 -216.813249) (xy 349.963367 -216.849887)
			(xy 349.993823 -216.891806) (xy 350.017346 -216.937973) (xy 350.033358 -216.987252) (xy 350.041464 -217.038429)
			(xy 350.041972 -217.064336) (xy 350.041506 -217.089682) (xy 350.033728 -217.139773) (xy 350.018377 -217.188085)
			(xy 349.995813 -217.233478) (xy 349.966569 -217.274884) (xy 349.931334 -217.311328) (xy 349.890936 -217.34195)
			(xy 349.846329 -217.36603) (xy 349.798562 -217.383) (xy 349.773748 -217.388186) (xy 349.750888 -217.392504)
			(xy 349.54591 -217.747596) (xy 349.553784 -217.76944) (xy 349.562373 -217.795856) (xy 349.571563 -217.850633)
			(xy 349.572072 -217.878406) (xy 349.852996 -217.878406) (xy 349.853504 -217.852519) (xy 349.861603 -217.801381)
			(xy 349.877602 -217.752141) (xy 349.901108 -217.706009) (xy 349.93154 -217.664122) (xy 349.96815 -217.627512)
			(xy 350.010037 -217.59708) (xy 350.056169 -217.573574) (xy 350.105409 -217.557575) (xy 350.156547 -217.549476)
			(xy 350.208321 -217.549476) (xy 350.259459 -217.557575) (xy 350.308699 -217.573574) (xy 350.354831 -217.59708)
			(xy 350.396718 -217.627512) (xy 350.433328 -217.664122) (xy 350.46376 -217.706009) (xy 350.487266 -217.752141)
			(xy 350.503265 -217.801381) (xy 350.511364 -217.852519) (xy 350.511872 -217.878406) (xy 350.792796 -217.878406)
			(xy 350.793288 -217.853072) (xy 350.801039 -217.803) (xy 350.81636 -217.754704) (xy 350.838891 -217.70932)
			(xy 350.868099 -217.667918) (xy 350.903299 -217.631473) (xy 350.94366 -217.600842) (xy 350.988233 -217.576747)
			(xy 351.035967 -217.559756) (xy 351.060766 -217.554556) (xy 351.083626 -217.550238) (xy 351.288604 -217.195146)
			(xy 351.28073 -217.173302) (xy 351.272091 -217.146892) (xy 351.262767 -217.092117) (xy 351.262188 -217.064336)
			(xy 351.262696 -217.038429) (xy 351.270802 -216.987252) (xy 351.286814 -216.937973) (xy 351.310337 -216.891806)
			(xy 351.340793 -216.849887) (xy 351.377431 -216.813249) (xy 351.41935 -216.782793) (xy 351.465517 -216.75927)
			(xy 351.514796 -216.743258) (xy 351.565973 -216.735152) (xy 351.617787 -216.735152) (xy 351.668964 -216.743258)
			(xy 351.718243 -216.75927) (xy 351.76441 -216.782793) (xy 351.806329 -216.813249) (xy 351.842967 -216.849887)
			(xy 351.873423 -216.891806) (xy 351.896946 -216.937973) (xy 351.912958 -216.987252) (xy 351.921064 -217.038429)
			(xy 351.921572 -217.064336) (xy 351.921106 -217.089682) (xy 351.913328 -217.139773) (xy 351.897977 -217.188085)
			(xy 351.875413 -217.233478) (xy 351.846169 -217.274884) (xy 351.810934 -217.311328) (xy 351.770536 -217.34195)
			(xy 351.725929 -217.36603) (xy 351.678162 -217.383) (xy 351.653348 -217.388186) (xy 351.630488 -217.392504)
			(xy 351.42551 -217.747596) (xy 351.433384 -217.76944) (xy 351.441973 -217.795856) (xy 351.451163 -217.850633)
			(xy 351.451672 -217.878406) (xy 351.732596 -217.878406) (xy 351.733104 -217.852519) (xy 351.741203 -217.801381)
			(xy 351.757202 -217.752141) (xy 351.780708 -217.706009) (xy 351.81114 -217.664122) (xy 351.84775 -217.627512)
			(xy 351.889637 -217.59708) (xy 351.935769 -217.573574) (xy 351.985009 -217.557575) (xy 352.036147 -217.549476)
			(xy 352.087921 -217.549476) (xy 352.139059 -217.557575) (xy 352.188299 -217.573574) (xy 352.234431 -217.59708)
			(xy 352.276318 -217.627512) (xy 352.312928 -217.664122) (xy 352.34336 -217.706009) (xy 352.366866 -217.752141)
			(xy 352.382865 -217.801381) (xy 352.390964 -217.852519) (xy 352.391472 -217.878406) (xy 352.672396 -217.878406)
			(xy 352.672888 -217.853072) (xy 352.680639 -217.803) (xy 352.69596 -217.754704) (xy 352.718491 -217.70932)
			(xy 352.747699 -217.667918) (xy 352.782899 -217.631473) (xy 352.82326 -217.600842) (xy 352.867833 -217.576747)
			(xy 352.915567 -217.559756) (xy 352.940366 -217.554556) (xy 352.963226 -217.550238) (xy 353.168204 -217.195146)
			(xy 353.16033 -217.173302) (xy 353.151691 -217.146892) (xy 353.142367 -217.092117) (xy 353.141788 -217.064336)
			(xy 353.142296 -217.038429) (xy 353.150402 -216.987252) (xy 353.166414 -216.937973) (xy 353.189937 -216.891806)
			(xy 353.220393 -216.849887) (xy 353.257031 -216.813249) (xy 353.29895 -216.782793) (xy 353.345117 -216.75927)
			(xy 353.394396 -216.743258) (xy 353.445573 -216.735152) (xy 353.497387 -216.735152) (xy 353.548564 -216.743258)
			(xy 353.597843 -216.75927) (xy 353.64401 -216.782793) (xy 353.685929 -216.813249) (xy 353.722567 -216.849887)
			(xy 353.753023 -216.891806) (xy 353.776546 -216.937973) (xy 353.792558 -216.987252) (xy 353.800664 -217.038429)
			(xy 353.801172 -217.064336) (xy 353.800706 -217.089682) (xy 353.792928 -217.139773) (xy 353.777577 -217.188085)
			(xy 353.755013 -217.233478) (xy 353.725769 -217.274884) (xy 353.690534 -217.311328) (xy 353.650136 -217.34195)
			(xy 353.605529 -217.36603) (xy 353.557762 -217.383) (xy 353.532948 -217.388186) (xy 353.510088 -217.392504)
			(xy 353.30511 -217.747596) (xy 353.312984 -217.76944) (xy 353.321573 -217.795856) (xy 353.330763 -217.850633)
			(xy 353.331272 -217.878406) (xy 353.612196 -217.878406) (xy 353.612704 -217.852519) (xy 353.620803 -217.801381)
			(xy 353.636802 -217.752141) (xy 353.660308 -217.706009) (xy 353.69074 -217.664122) (xy 353.72735 -217.627512)
			(xy 353.769237 -217.59708) (xy 353.815369 -217.573574) (xy 353.864609 -217.557575) (xy 353.915747 -217.549476)
			(xy 353.967521 -217.549476) (xy 354.018659 -217.557575) (xy 354.067899 -217.573574) (xy 354.114031 -217.59708)
			(xy 354.155918 -217.627512) (xy 354.192528 -217.664122) (xy 354.22296 -217.706009) (xy 354.246466 -217.752141)
			(xy 354.262465 -217.801381) (xy 354.270564 -217.852519) (xy 354.271072 -217.878406) (xy 354.551996 -217.878406)
			(xy 354.552488 -217.853072) (xy 354.560239 -217.803) (xy 354.57556 -217.754704) (xy 354.598091 -217.70932)
			(xy 354.627299 -217.667918) (xy 354.662499 -217.631473) (xy 354.70286 -217.600842) (xy 354.747433 -217.576747)
			(xy 354.795167 -217.559756) (xy 354.819966 -217.554556) (xy 354.842826 -217.550238) (xy 355.047804 -217.195146)
			(xy 355.03993 -217.173302) (xy 355.031291 -217.146892) (xy 355.021967 -217.092117) (xy 355.021388 -217.064336)
			(xy 355.021896 -217.038429) (xy 355.030002 -216.987252) (xy 355.046014 -216.937973) (xy 355.069537 -216.891806)
			(xy 355.099993 -216.849887) (xy 355.136631 -216.813249) (xy 355.17855 -216.782793) (xy 355.224717 -216.75927)
			(xy 355.273996 -216.743258) (xy 355.325173 -216.735152) (xy 355.376987 -216.735152) (xy 355.428164 -216.743258)
			(xy 355.477443 -216.75927) (xy 355.52361 -216.782793) (xy 355.565529 -216.813249) (xy 355.602167 -216.849887)
			(xy 355.632623 -216.891806) (xy 355.656146 -216.937973) (xy 355.672158 -216.987252) (xy 355.680264 -217.038429)
			(xy 355.680772 -217.064336) (xy 355.680306 -217.089682) (xy 355.672528 -217.139773) (xy 355.657177 -217.188085)
			(xy 355.634613 -217.233478) (xy 355.605369 -217.274884) (xy 355.570134 -217.311328) (xy 355.529736 -217.34195)
			(xy 355.485129 -217.36603) (xy 355.437362 -217.383) (xy 355.412548 -217.388186) (xy 355.389688 -217.392504)
			(xy 355.18471 -217.747596) (xy 355.192584 -217.76944) (xy 355.201173 -217.795856) (xy 355.210363 -217.850633)
			(xy 355.210872 -217.878406) (xy 355.491796 -217.878406) (xy 355.492304 -217.852519) (xy 355.500403 -217.801381)
			(xy 355.516402 -217.752141) (xy 355.539908 -217.706009) (xy 355.57034 -217.664122) (xy 355.60695 -217.627512)
			(xy 355.648837 -217.59708) (xy 355.694969 -217.573574) (xy 355.744209 -217.557575) (xy 355.795347 -217.549476)
			(xy 355.847121 -217.549476) (xy 355.898259 -217.557575) (xy 355.947499 -217.573574) (xy 355.993631 -217.59708)
			(xy 356.035518 -217.627512) (xy 356.072128 -217.664122) (xy 356.10256 -217.706009) (xy 356.126066 -217.752141)
			(xy 356.142065 -217.801381) (xy 356.150164 -217.852519) (xy 356.150672 -217.878406) (xy 356.431596 -217.878406)
			(xy 356.432088 -217.853072) (xy 356.439839 -217.803) (xy 356.45516 -217.754704) (xy 356.477691 -217.70932)
			(xy 356.506899 -217.667918) (xy 356.542099 -217.631473) (xy 356.58246 -217.600842) (xy 356.627033 -217.576747)
			(xy 356.674767 -217.559756) (xy 356.699566 -217.554556) (xy 356.722426 -217.550238) (xy 356.927404 -217.195146)
			(xy 356.91953 -217.173302) (xy 356.910891 -217.146892) (xy 356.901567 -217.092117) (xy 356.900988 -217.064336)
			(xy 356.901496 -217.038429) (xy 356.909602 -216.987252) (xy 356.925614 -216.937973) (xy 356.949137 -216.891806)
			(xy 356.979593 -216.849887) (xy 357.016231 -216.813249) (xy 357.05815 -216.782793) (xy 357.104317 -216.75927)
			(xy 357.153596 -216.743258) (xy 357.204773 -216.735152) (xy 357.256587 -216.735152) (xy 357.307764 -216.743258)
			(xy 357.357043 -216.75927) (xy 357.40321 -216.782793) (xy 357.445129 -216.813249) (xy 357.481767 -216.849887)
			(xy 357.512223 -216.891806) (xy 357.535746 -216.937973) (xy 357.551758 -216.987252) (xy 357.559864 -217.038429)
			(xy 357.560372 -217.064336) (xy 357.559906 -217.089682) (xy 357.552128 -217.139773) (xy 357.536777 -217.188085)
			(xy 357.514213 -217.233478) (xy 357.484969 -217.274884) (xy 357.449734 -217.311328) (xy 357.409336 -217.34195)
			(xy 357.364729 -217.36603) (xy 357.316962 -217.383) (xy 357.292148 -217.388186) (xy 357.269288 -217.392504)
			(xy 357.06431 -217.747596) (xy 357.072184 -217.76944) (xy 357.080773 -217.795856) (xy 357.089963 -217.850633)
			(xy 357.090472 -217.878406) (xy 357.371396 -217.878406) (xy 357.371904 -217.852519) (xy 357.380003 -217.801381)
			(xy 357.396002 -217.752141) (xy 357.419508 -217.706009) (xy 357.44994 -217.664122) (xy 357.48655 -217.627512)
			(xy 357.528437 -217.59708) (xy 357.574569 -217.573574) (xy 357.623809 -217.557575) (xy 357.674947 -217.549476)
			(xy 357.726721 -217.549476) (xy 357.777859 -217.557575) (xy 357.827099 -217.573574) (xy 357.873231 -217.59708)
			(xy 357.915118 -217.627512) (xy 357.951728 -217.664122) (xy 357.98216 -217.706009) (xy 358.005666 -217.752141)
			(xy 358.021665 -217.801381) (xy 358.029764 -217.852519) (xy 358.030272 -217.878406) (xy 358.311196 -217.878406)
			(xy 358.311688 -217.853072) (xy 358.319439 -217.803) (xy 358.33476 -217.754704) (xy 358.357291 -217.70932)
			(xy 358.386499 -217.667918) (xy 358.421699 -217.631473) (xy 358.46206 -217.600842) (xy 358.506633 -217.576747)
			(xy 358.554367 -217.559756) (xy 358.579166 -217.554556) (xy 358.602026 -217.550238) (xy 358.807004 -217.194892)
			(xy 358.799384 -217.173048) (xy 358.790811 -217.146694) (xy 358.78162 -217.092045) (xy 358.781096 -217.064336)
			(xy 358.781604 -217.038449) (xy 358.789703 -216.987311) (xy 358.805702 -216.938071) (xy 358.829208 -216.891939)
			(xy 358.85964 -216.850052) (xy 358.89625 -216.813442) (xy 358.938137 -216.78301) (xy 358.984269 -216.759504)
			(xy 359.033509 -216.743505) (xy 359.084647 -216.735406) (xy 359.136421 -216.735406) (xy 359.187559 -216.743505)
			(xy 359.236799 -216.759504) (xy 359.282931 -216.78301) (xy 359.324818 -216.813442) (xy 359.361428 -216.850052)
			(xy 359.39186 -216.891939) (xy 359.415366 -216.938071) (xy 359.431365 -216.987311) (xy 359.439464 -217.038449)
			(xy 359.439972 -217.064336) (xy 360.660188 -217.064336) (xy 360.660696 -217.038429) (xy 360.668802 -216.987252)
			(xy 360.684814 -216.937973) (xy 360.708337 -216.891806) (xy 360.738793 -216.849887) (xy 360.775431 -216.813249)
			(xy 360.81735 -216.782793) (xy 360.863517 -216.75927) (xy 360.912796 -216.743258) (xy 360.963973 -216.735152)
			(xy 361.015787 -216.735152) (xy 361.066964 -216.743258) (xy 361.116243 -216.75927) (xy 361.16241 -216.782793)
			(xy 361.204329 -216.813249) (xy 361.240967 -216.849887) (xy 361.271423 -216.891806) (xy 361.294946 -216.937973)
			(xy 361.310958 -216.987252) (xy 361.319064 -217.038429) (xy 361.319572 -217.064336) (xy 362.539788 -217.064336)
			(xy 362.540296 -217.038429) (xy 362.548402 -216.987252) (xy 362.564414 -216.937973) (xy 362.587937 -216.891806)
			(xy 362.618393 -216.849887) (xy 362.655031 -216.813249) (xy 362.69695 -216.782793) (xy 362.743117 -216.75927)
			(xy 362.792396 -216.743258) (xy 362.843573 -216.735152) (xy 362.895387 -216.735152) (xy 362.946564 -216.743258)
			(xy 362.995843 -216.75927) (xy 363.04201 -216.782793) (xy 363.083929 -216.813249) (xy 363.120567 -216.849887)
			(xy 363.151023 -216.891806) (xy 363.174546 -216.937973) (xy 363.190558 -216.987252) (xy 363.198664 -217.038429)
			(xy 363.199172 -217.064336) (xy 364.419388 -217.064336) (xy 364.419896 -217.038429) (xy 364.428002 -216.987252)
			(xy 364.444014 -216.937973) (xy 364.467537 -216.891806) (xy 364.497993 -216.849887) (xy 364.534631 -216.813249)
			(xy 364.57655 -216.782793) (xy 364.622717 -216.75927) (xy 364.671996 -216.743258) (xy 364.723173 -216.735152)
			(xy 364.774987 -216.735152) (xy 364.826164 -216.743258) (xy 364.875443 -216.75927) (xy 364.92161 -216.782793)
			(xy 364.963529 -216.813249) (xy 365.000167 -216.849887) (xy 365.030623 -216.891806) (xy 365.054146 -216.937973)
			(xy 365.070158 -216.987252) (xy 365.078264 -217.038429) (xy 365.078772 -217.064336) (xy 366.298988 -217.064336)
			(xy 366.299496 -217.038429) (xy 366.307602 -216.987252) (xy 366.323614 -216.937973) (xy 366.347137 -216.891806)
			(xy 366.377593 -216.849887) (xy 366.414231 -216.813249) (xy 366.45615 -216.782793) (xy 366.502317 -216.75927)
			(xy 366.551596 -216.743258) (xy 366.602773 -216.735152) (xy 366.654587 -216.735152) (xy 366.705764 -216.743258)
			(xy 366.755043 -216.75927) (xy 366.80121 -216.782793) (xy 366.843129 -216.813249) (xy 366.879767 -216.849887)
			(xy 366.910223 -216.891806) (xy 366.933746 -216.937973) (xy 366.949758 -216.987252) (xy 366.957864 -217.038429)
			(xy 366.958372 -217.064336) (xy 368.178588 -217.064336) (xy 368.179096 -217.038429) (xy 368.187202 -216.987252)
			(xy 368.203214 -216.937973) (xy 368.226737 -216.891806) (xy 368.257193 -216.849887) (xy 368.293831 -216.813249)
			(xy 368.33575 -216.782793) (xy 368.381917 -216.75927) (xy 368.431196 -216.743258) (xy 368.482373 -216.735152)
			(xy 368.534187 -216.735152) (xy 368.585364 -216.743258) (xy 368.634643 -216.75927) (xy 368.68081 -216.782793)
			(xy 368.722729 -216.813249) (xy 368.759367 -216.849887) (xy 368.789823 -216.891806) (xy 368.813346 -216.937973)
			(xy 368.829358 -216.987252) (xy 368.837464 -217.038429) (xy 368.837972 -217.064336) (xy 370.058188 -217.064336)
			(xy 370.058696 -217.038429) (xy 370.066802 -216.987252) (xy 370.082814 -216.937973) (xy 370.106337 -216.891806)
			(xy 370.136793 -216.849887) (xy 370.173431 -216.813249) (xy 370.21535 -216.782793) (xy 370.261517 -216.75927)
			(xy 370.310796 -216.743258) (xy 370.361973 -216.735152) (xy 370.413787 -216.735152) (xy 370.464964 -216.743258)
			(xy 370.514243 -216.75927) (xy 370.56041 -216.782793) (xy 370.602329 -216.813249) (xy 370.638967 -216.849887)
			(xy 370.669423 -216.891806) (xy 370.692946 -216.937973) (xy 370.708958 -216.987252) (xy 370.717064 -217.038429)
			(xy 370.717572 -217.064336) (xy 371.937788 -217.064336) (xy 371.938296 -217.038429) (xy 371.946402 -216.987252)
			(xy 371.962414 -216.937973) (xy 371.985937 -216.891806) (xy 372.016393 -216.849887) (xy 372.053031 -216.813249)
			(xy 372.09495 -216.782793) (xy 372.141117 -216.75927) (xy 372.190396 -216.743258) (xy 372.241573 -216.735152)
			(xy 372.293387 -216.735152) (xy 372.344564 -216.743258) (xy 372.393843 -216.75927) (xy 372.44001 -216.782793)
			(xy 372.481929 -216.813249) (xy 372.518567 -216.849887) (xy 372.549023 -216.891806) (xy 372.572546 -216.937973)
			(xy 372.588558 -216.987252) (xy 372.596664 -217.038429) (xy 372.597172 -217.064336) (xy 373.817388 -217.064336)
			(xy 373.817896 -217.038429) (xy 373.826002 -216.987252) (xy 373.842014 -216.937973) (xy 373.865537 -216.891806)
			(xy 373.895993 -216.849887) (xy 373.932631 -216.813249) (xy 373.97455 -216.782793) (xy 374.020717 -216.75927)
			(xy 374.069996 -216.743258) (xy 374.121173 -216.735152) (xy 374.172987 -216.735152) (xy 374.224164 -216.743258)
			(xy 374.273443 -216.75927) (xy 374.31961 -216.782793) (xy 374.361529 -216.813249) (xy 374.398167 -216.849887)
			(xy 374.428623 -216.891806) (xy 374.452146 -216.937973) (xy 374.468158 -216.987252) (xy 374.476264 -217.038429)
			(xy 374.476772 -217.064336) (xy 375.696988 -217.064336) (xy 375.697496 -217.038429) (xy 375.705602 -216.987252)
			(xy 375.721614 -216.937973) (xy 375.745137 -216.891806) (xy 375.775593 -216.849887) (xy 375.812231 -216.813249)
			(xy 375.85415 -216.782793) (xy 375.900317 -216.75927) (xy 375.949596 -216.743258) (xy 376.000773 -216.735152)
			(xy 376.052587 -216.735152) (xy 376.103764 -216.743258) (xy 376.153043 -216.75927) (xy 376.19921 -216.782793)
			(xy 376.241129 -216.813249) (xy 376.277767 -216.849887) (xy 376.308223 -216.891806) (xy 376.331746 -216.937973)
			(xy 376.347758 -216.987252) (xy 376.355864 -217.038429) (xy 376.356372 -217.064336) (xy 377.576588 -217.064336)
			(xy 377.577096 -217.038429) (xy 377.585202 -216.987252) (xy 377.601214 -216.937973) (xy 377.624737 -216.891806)
			(xy 377.655193 -216.849887) (xy 377.691831 -216.813249) (xy 377.73375 -216.782793) (xy 377.779917 -216.75927)
			(xy 377.829196 -216.743258) (xy 377.880373 -216.735152) (xy 377.932187 -216.735152) (xy 377.983364 -216.743258)
			(xy 378.032643 -216.75927) (xy 378.07881 -216.782793) (xy 378.120729 -216.813249) (xy 378.157367 -216.849887)
			(xy 378.187823 -216.891806) (xy 378.211346 -216.937973) (xy 378.227358 -216.987252) (xy 378.235464 -217.038429)
			(xy 378.235972 -217.064336) (xy 379.456188 -217.064336) (xy 379.456696 -217.038429) (xy 379.464802 -216.987252)
			(xy 379.480814 -216.937973) (xy 379.504337 -216.891806) (xy 379.534793 -216.849887) (xy 379.571431 -216.813249)
			(xy 379.61335 -216.782793) (xy 379.659517 -216.75927) (xy 379.708796 -216.743258) (xy 379.759973 -216.735152)
			(xy 379.811787 -216.735152) (xy 379.862964 -216.743258) (xy 379.912243 -216.75927) (xy 379.95841 -216.782793)
			(xy 380.000329 -216.813249) (xy 380.036967 -216.849887) (xy 380.067423 -216.891806) (xy 380.090946 -216.937973)
			(xy 380.106958 -216.987252) (xy 380.115064 -217.038429) (xy 380.115572 -217.064336) (xy 381.335788 -217.064336)
			(xy 381.336296 -217.038429) (xy 381.344402 -216.987252) (xy 381.360414 -216.937973) (xy 381.383937 -216.891806)
			(xy 381.414393 -216.849887) (xy 381.451031 -216.813249) (xy 381.49295 -216.782793) (xy 381.539117 -216.75927)
			(xy 381.588396 -216.743258) (xy 381.639573 -216.735152) (xy 381.691387 -216.735152) (xy 381.742564 -216.743258)
			(xy 381.791843 -216.75927) (xy 381.83801 -216.782793) (xy 381.879929 -216.813249) (xy 381.916567 -216.849887)
			(xy 381.947023 -216.891806) (xy 381.970546 -216.937973) (xy 381.986558 -216.987252) (xy 381.994664 -217.038429)
			(xy 381.995172 -217.064336) (xy 381.994559 -217.091989) (xy 381.985238 -217.146507) (xy 381.97663 -217.172794)
			(xy 381.96901 -217.194892) (xy 382.174242 -217.550238) (xy 382.197102 -217.554556) (xy 382.221903 -217.559751)
			(xy 382.269642 -217.57674) (xy 382.314219 -217.600833) (xy 382.354584 -217.631463) (xy 382.389788 -217.667908)
			(xy 382.419 -217.709312) (xy 382.441533 -217.754697) (xy 382.456856 -217.802996) (xy 382.464608 -217.85307)
			(xy 382.465072 -217.878406) (xy 382.464564 -217.904293) (xy 382.456465 -217.955431) (xy 382.440466 -218.004671)
			(xy 382.41696 -218.050803) (xy 382.386528 -218.09269) (xy 382.349918 -218.1293) (xy 382.308031 -218.159732)
			(xy 382.261899 -218.183238) (xy 382.212659 -218.199237) (xy 382.161521 -218.207336) (xy 382.109747 -218.207336)
			(xy 382.058609 -218.199237) (xy 382.009369 -218.183238) (xy 381.963237 -218.159732) (xy 381.92135 -218.1293)
			(xy 381.88474 -218.09269) (xy 381.854308 -218.050803) (xy 381.830802 -218.004671) (xy 381.814803 -217.955431)
			(xy 381.806704 -217.904293) (xy 381.806196 -217.878406) (xy 381.806727 -217.850698) (xy 381.815921 -217.796051)
			(xy 381.824484 -217.769694) (xy 381.832358 -217.747596) (xy 381.62738 -217.392504) (xy 381.60452 -217.388186)
			(xy 381.579675 -217.38302) (xy 381.531826 -217.366126) (xy 381.487133 -217.342096) (xy 381.446653 -217.311499)
			(xy 381.411341 -217.275058) (xy 381.382033 -217.233634) (xy 381.359422 -217.188207) (xy 381.344043 -217.13985)
			(xy 381.336258 -217.089708) (xy 381.335788 -217.064336) (xy 380.115572 -217.064336) (xy 380.114959 -217.091989)
			(xy 380.105638 -217.146507) (xy 380.09703 -217.172794) (xy 380.08941 -217.194892) (xy 380.294642 -217.550238)
			(xy 380.317502 -217.554556) (xy 380.342303 -217.559751) (xy 380.390042 -217.57674) (xy 380.434619 -217.600833)
			(xy 380.474984 -217.631463) (xy 380.510188 -217.667908) (xy 380.5394 -217.709312) (xy 380.561933 -217.754697)
			(xy 380.577256 -217.802996) (xy 380.585008 -217.85307) (xy 380.585472 -217.878406) (xy 380.584964 -217.904293)
			(xy 380.576865 -217.955431) (xy 380.560866 -218.004671) (xy 380.53736 -218.050803) (xy 380.506928 -218.09269)
			(xy 380.470318 -218.1293) (xy 380.428431 -218.159732) (xy 380.382299 -218.183238) (xy 380.333059 -218.199237)
			(xy 380.281921 -218.207336) (xy 380.230147 -218.207336) (xy 380.179009 -218.199237) (xy 380.129769 -218.183238)
			(xy 380.083637 -218.159732) (xy 380.04175 -218.1293) (xy 380.00514 -218.09269) (xy 379.974708 -218.050803)
			(xy 379.951202 -218.004671) (xy 379.935203 -217.955431) (xy 379.927104 -217.904293) (xy 379.926596 -217.878406)
			(xy 379.927127 -217.850698) (xy 379.936321 -217.796051) (xy 379.944884 -217.769694) (xy 379.952758 -217.747596)
			(xy 379.74778 -217.392504) (xy 379.72492 -217.388186) (xy 379.700075 -217.38302) (xy 379.652226 -217.366126)
			(xy 379.607533 -217.342096) (xy 379.567053 -217.311499) (xy 379.531741 -217.275058) (xy 379.502433 -217.233634)
			(xy 379.479822 -217.188207) (xy 379.464443 -217.13985) (xy 379.456658 -217.089708) (xy 379.456188 -217.064336)
			(xy 378.235972 -217.064336) (xy 378.235359 -217.091989) (xy 378.226038 -217.146507) (xy 378.21743 -217.172794)
			(xy 378.20981 -217.194892) (xy 378.415042 -217.550238) (xy 378.437902 -217.554556) (xy 378.462703 -217.559751)
			(xy 378.510442 -217.57674) (xy 378.555019 -217.600833) (xy 378.595384 -217.631463) (xy 378.630588 -217.667908)
			(xy 378.6598 -217.709312) (xy 378.682333 -217.754697) (xy 378.697656 -217.802996) (xy 378.705408 -217.85307)
			(xy 378.705872 -217.878406) (xy 378.705364 -217.904293) (xy 378.697265 -217.955431) (xy 378.681266 -218.004671)
			(xy 378.65776 -218.050803) (xy 378.627328 -218.09269) (xy 378.590718 -218.1293) (xy 378.548831 -218.159732)
			(xy 378.502699 -218.183238) (xy 378.453459 -218.199237) (xy 378.402321 -218.207336) (xy 378.350547 -218.207336)
			(xy 378.299409 -218.199237) (xy 378.250169 -218.183238) (xy 378.204037 -218.159732) (xy 378.16215 -218.1293)
			(xy 378.12554 -218.09269) (xy 378.095108 -218.050803) (xy 378.071602 -218.004671) (xy 378.055603 -217.955431)
			(xy 378.047504 -217.904293) (xy 378.046996 -217.878406) (xy 378.047527 -217.850698) (xy 378.056721 -217.796051)
			(xy 378.065284 -217.769694) (xy 378.073158 -217.747596) (xy 377.86818 -217.392504) (xy 377.84532 -217.388186)
			(xy 377.820475 -217.38302) (xy 377.772626 -217.366126) (xy 377.727933 -217.342096) (xy 377.687453 -217.311499)
			(xy 377.652141 -217.275058) (xy 377.622833 -217.233634) (xy 377.600222 -217.188207) (xy 377.584843 -217.13985)
			(xy 377.577058 -217.089708) (xy 377.576588 -217.064336) (xy 376.356372 -217.064336) (xy 376.355759 -217.091989)
			(xy 376.346438 -217.146507) (xy 376.33783 -217.172794) (xy 376.33021 -217.194892) (xy 376.535442 -217.550238)
			(xy 376.558302 -217.554556) (xy 376.583103 -217.559751) (xy 376.630842 -217.57674) (xy 376.675419 -217.600833)
			(xy 376.715784 -217.631463) (xy 376.750988 -217.667908) (xy 376.7802 -217.709312) (xy 376.802733 -217.754697)
			(xy 376.818056 -217.802996) (xy 376.825808 -217.85307) (xy 376.826272 -217.878406) (xy 376.825764 -217.904293)
			(xy 376.817665 -217.955431) (xy 376.801666 -218.004671) (xy 376.77816 -218.050803) (xy 376.747728 -218.09269)
			(xy 376.711118 -218.1293) (xy 376.669231 -218.159732) (xy 376.623099 -218.183238) (xy 376.573859 -218.199237)
			(xy 376.522721 -218.207336) (xy 376.470947 -218.207336) (xy 376.419809 -218.199237) (xy 376.370569 -218.183238)
			(xy 376.324437 -218.159732) (xy 376.28255 -218.1293) (xy 376.24594 -218.09269) (xy 376.215508 -218.050803)
			(xy 376.192002 -218.004671) (xy 376.176003 -217.955431) (xy 376.167904 -217.904293) (xy 376.167396 -217.878406)
			(xy 376.167927 -217.850698) (xy 376.177121 -217.796051) (xy 376.185684 -217.769694) (xy 376.193558 -217.747596)
			(xy 375.98858 -217.392504) (xy 375.96572 -217.388186) (xy 375.940875 -217.38302) (xy 375.893026 -217.366126)
			(xy 375.848333 -217.342096) (xy 375.807853 -217.311499) (xy 375.772541 -217.275058) (xy 375.743233 -217.233634)
			(xy 375.720622 -217.188207) (xy 375.705243 -217.13985) (xy 375.697458 -217.089708) (xy 375.696988 -217.064336)
			(xy 374.476772 -217.064336) (xy 374.476159 -217.091989) (xy 374.466838 -217.146507) (xy 374.45823 -217.172794)
			(xy 374.45061 -217.194892) (xy 374.655842 -217.550238) (xy 374.678702 -217.554556) (xy 374.703503 -217.559751)
			(xy 374.751242 -217.57674) (xy 374.795819 -217.600833) (xy 374.836184 -217.631463) (xy 374.871388 -217.667908)
			(xy 374.9006 -217.709312) (xy 374.923133 -217.754697) (xy 374.938456 -217.802996) (xy 374.946208 -217.85307)
			(xy 374.946672 -217.878406) (xy 374.946164 -217.904293) (xy 374.938065 -217.955431) (xy 374.922066 -218.004671)
			(xy 374.89856 -218.050803) (xy 374.868128 -218.09269) (xy 374.831518 -218.1293) (xy 374.789631 -218.159732)
			(xy 374.743499 -218.183238) (xy 374.694259 -218.199237) (xy 374.643121 -218.207336) (xy 374.591347 -218.207336)
			(xy 374.540209 -218.199237) (xy 374.490969 -218.183238) (xy 374.444837 -218.159732) (xy 374.40295 -218.1293)
			(xy 374.36634 -218.09269) (xy 374.335908 -218.050803) (xy 374.312402 -218.004671) (xy 374.296403 -217.955431)
			(xy 374.288304 -217.904293) (xy 374.287796 -217.878406) (xy 374.288327 -217.850698) (xy 374.297521 -217.796051)
			(xy 374.306084 -217.769694) (xy 374.313958 -217.747596) (xy 374.10898 -217.392504) (xy 374.08612 -217.388186)
			(xy 374.061275 -217.38302) (xy 374.013426 -217.366126) (xy 373.968733 -217.342096) (xy 373.928253 -217.311499)
			(xy 373.892941 -217.275058) (xy 373.863633 -217.233634) (xy 373.841022 -217.188207) (xy 373.825643 -217.13985)
			(xy 373.817858 -217.089708) (xy 373.817388 -217.064336) (xy 372.597172 -217.064336) (xy 372.596559 -217.091989)
			(xy 372.587238 -217.146507) (xy 372.57863 -217.172794) (xy 372.57101 -217.194892) (xy 372.776242 -217.550238)
			(xy 372.799102 -217.554556) (xy 372.823903 -217.559751) (xy 372.871642 -217.57674) (xy 372.916219 -217.600833)
			(xy 372.956584 -217.631463) (xy 372.991788 -217.667908) (xy 373.021 -217.709312) (xy 373.043533 -217.754697)
			(xy 373.058856 -217.802996) (xy 373.066608 -217.85307) (xy 373.067072 -217.878406) (xy 373.066564 -217.904293)
			(xy 373.058465 -217.955431) (xy 373.042466 -218.004671) (xy 373.01896 -218.050803) (xy 372.988528 -218.09269)
			(xy 372.951918 -218.1293) (xy 372.910031 -218.159732) (xy 372.863899 -218.183238) (xy 372.814659 -218.199237)
			(xy 372.763521 -218.207336) (xy 372.711747 -218.207336) (xy 372.660609 -218.199237) (xy 372.611369 -218.183238)
			(xy 372.565237 -218.159732) (xy 372.52335 -218.1293) (xy 372.48674 -218.09269) (xy 372.456308 -218.050803)
			(xy 372.432802 -218.004671) (xy 372.416803 -217.955431) (xy 372.408704 -217.904293) (xy 372.408196 -217.878406)
			(xy 372.408727 -217.850698) (xy 372.417921 -217.796051) (xy 372.426484 -217.769694) (xy 372.434358 -217.747596)
			(xy 372.22938 -217.392504) (xy 372.20652 -217.388186) (xy 372.181675 -217.38302) (xy 372.133826 -217.366126)
			(xy 372.089133 -217.342096) (xy 372.048653 -217.311499) (xy 372.013341 -217.275058) (xy 371.984033 -217.233634)
			(xy 371.961422 -217.188207) (xy 371.946043 -217.13985) (xy 371.938258 -217.089708) (xy 371.937788 -217.064336)
			(xy 370.717572 -217.064336) (xy 370.716959 -217.091989) (xy 370.707638 -217.146507) (xy 370.69903 -217.172794)
			(xy 370.69141 -217.194892) (xy 370.896642 -217.550238) (xy 370.919502 -217.554556) (xy 370.944303 -217.559751)
			(xy 370.992042 -217.57674) (xy 371.036619 -217.600833) (xy 371.076984 -217.631463) (xy 371.112188 -217.667908)
			(xy 371.1414 -217.709312) (xy 371.163933 -217.754697) (xy 371.179256 -217.802996) (xy 371.187008 -217.85307)
			(xy 371.187472 -217.878406) (xy 371.186964 -217.904293) (xy 371.178865 -217.955431) (xy 371.162866 -218.004671)
			(xy 371.13936 -218.050803) (xy 371.108928 -218.09269) (xy 371.072318 -218.1293) (xy 371.030431 -218.159732)
			(xy 370.984299 -218.183238) (xy 370.935059 -218.199237) (xy 370.883921 -218.207336) (xy 370.832147 -218.207336)
			(xy 370.781009 -218.199237) (xy 370.731769 -218.183238) (xy 370.685637 -218.159732) (xy 370.64375 -218.1293)
			(xy 370.60714 -218.09269) (xy 370.576708 -218.050803) (xy 370.553202 -218.004671) (xy 370.537203 -217.955431)
			(xy 370.529104 -217.904293) (xy 370.528596 -217.878406) (xy 370.529127 -217.850698) (xy 370.538321 -217.796051)
			(xy 370.546884 -217.769694) (xy 370.554758 -217.747596) (xy 370.34978 -217.392504) (xy 370.32692 -217.388186)
			(xy 370.302075 -217.38302) (xy 370.254226 -217.366126) (xy 370.209533 -217.342096) (xy 370.169053 -217.311499)
			(xy 370.133741 -217.275058) (xy 370.104433 -217.233634) (xy 370.081822 -217.188207) (xy 370.066443 -217.13985)
			(xy 370.058658 -217.089708) (xy 370.058188 -217.064336) (xy 368.837972 -217.064336) (xy 368.837359 -217.091989)
			(xy 368.828038 -217.146507) (xy 368.81943 -217.172794) (xy 368.81181 -217.194892) (xy 369.017042 -217.550238)
			(xy 369.039902 -217.554556) (xy 369.064703 -217.559751) (xy 369.112442 -217.57674) (xy 369.157019 -217.600833)
			(xy 369.197384 -217.631463) (xy 369.232588 -217.667908) (xy 369.2618 -217.709312) (xy 369.284333 -217.754697)
			(xy 369.299656 -217.802996) (xy 369.307408 -217.85307) (xy 369.307872 -217.878406) (xy 369.307364 -217.904293)
			(xy 369.299265 -217.955431) (xy 369.283266 -218.004671) (xy 369.25976 -218.050803) (xy 369.229328 -218.09269)
			(xy 369.192718 -218.1293) (xy 369.150831 -218.159732) (xy 369.104699 -218.183238) (xy 369.055459 -218.199237)
			(xy 369.004321 -218.207336) (xy 368.952547 -218.207336) (xy 368.901409 -218.199237) (xy 368.852169 -218.183238)
			(xy 368.806037 -218.159732) (xy 368.76415 -218.1293) (xy 368.72754 -218.09269) (xy 368.697108 -218.050803)
			(xy 368.673602 -218.004671) (xy 368.657603 -217.955431) (xy 368.649504 -217.904293) (xy 368.648996 -217.878406)
			(xy 368.649527 -217.850698) (xy 368.658721 -217.796051) (xy 368.667284 -217.769694) (xy 368.675158 -217.747596)
			(xy 368.47018 -217.392504) (xy 368.44732 -217.388186) (xy 368.422475 -217.38302) (xy 368.374626 -217.366126)
			(xy 368.329933 -217.342096) (xy 368.289453 -217.311499) (xy 368.254141 -217.275058) (xy 368.224833 -217.233634)
			(xy 368.202222 -217.188207) (xy 368.186843 -217.13985) (xy 368.179058 -217.089708) (xy 368.178588 -217.064336)
			(xy 366.958372 -217.064336) (xy 366.957759 -217.091989) (xy 366.948438 -217.146507) (xy 366.93983 -217.172794)
			(xy 366.93221 -217.194892) (xy 367.137442 -217.550238) (xy 367.160302 -217.554556) (xy 367.185103 -217.559751)
			(xy 367.232842 -217.57674) (xy 367.277419 -217.600833) (xy 367.317784 -217.631463) (xy 367.352988 -217.667908)
			(xy 367.3822 -217.709312) (xy 367.404733 -217.754697) (xy 367.420056 -217.802996) (xy 367.427808 -217.85307)
			(xy 367.428272 -217.878406) (xy 367.427764 -217.904293) (xy 367.419665 -217.955431) (xy 367.403666 -218.004671)
			(xy 367.38016 -218.050803) (xy 367.349728 -218.09269) (xy 367.313118 -218.1293) (xy 367.271231 -218.159732)
			(xy 367.225099 -218.183238) (xy 367.175859 -218.199237) (xy 367.124721 -218.207336) (xy 367.072947 -218.207336)
			(xy 367.021809 -218.199237) (xy 366.972569 -218.183238) (xy 366.926437 -218.159732) (xy 366.88455 -218.1293)
			(xy 366.84794 -218.09269) (xy 366.817508 -218.050803) (xy 366.794002 -218.004671) (xy 366.778003 -217.955431)
			(xy 366.769904 -217.904293) (xy 366.769396 -217.878406) (xy 366.769927 -217.850698) (xy 366.779121 -217.796051)
			(xy 366.787684 -217.769694) (xy 366.795558 -217.747596) (xy 366.59058 -217.392504) (xy 366.56772 -217.388186)
			(xy 366.542875 -217.38302) (xy 366.495026 -217.366126) (xy 366.450333 -217.342096) (xy 366.409853 -217.311499)
			(xy 366.374541 -217.275058) (xy 366.345233 -217.233634) (xy 366.322622 -217.188207) (xy 366.307243 -217.13985)
			(xy 366.299458 -217.089708) (xy 366.298988 -217.064336) (xy 365.078772 -217.064336) (xy 365.078159 -217.091989)
			(xy 365.068838 -217.146507) (xy 365.06023 -217.172794) (xy 365.05261 -217.194892) (xy 365.257842 -217.550238)
			(xy 365.280702 -217.554556) (xy 365.305503 -217.559751) (xy 365.353242 -217.57674) (xy 365.397819 -217.600833)
			(xy 365.438184 -217.631463) (xy 365.473388 -217.667908) (xy 365.5026 -217.709312) (xy 365.525133 -217.754697)
			(xy 365.540456 -217.802996) (xy 365.548208 -217.85307) (xy 365.548672 -217.878406) (xy 365.548164 -217.904293)
			(xy 365.540065 -217.955431) (xy 365.524066 -218.004671) (xy 365.50056 -218.050803) (xy 365.470128 -218.09269)
			(xy 365.433518 -218.1293) (xy 365.391631 -218.159732) (xy 365.345499 -218.183238) (xy 365.296259 -218.199237)
			(xy 365.245121 -218.207336) (xy 365.193347 -218.207336) (xy 365.142209 -218.199237) (xy 365.092969 -218.183238)
			(xy 365.046837 -218.159732) (xy 365.00495 -218.1293) (xy 364.96834 -218.09269) (xy 364.937908 -218.050803)
			(xy 364.914402 -218.004671) (xy 364.898403 -217.955431) (xy 364.890304 -217.904293) (xy 364.889796 -217.878406)
			(xy 364.890327 -217.850698) (xy 364.899521 -217.796051) (xy 364.908084 -217.769694) (xy 364.915958 -217.747596)
			(xy 364.71098 -217.392504) (xy 364.68812 -217.388186) (xy 364.663275 -217.38302) (xy 364.615426 -217.366126)
			(xy 364.570733 -217.342096) (xy 364.530253 -217.311499) (xy 364.494941 -217.275058) (xy 364.465633 -217.233634)
			(xy 364.443022 -217.188207) (xy 364.427643 -217.13985) (xy 364.419858 -217.089708) (xy 364.419388 -217.064336)
			(xy 363.199172 -217.064336) (xy 363.198559 -217.091989) (xy 363.189238 -217.146507) (xy 363.18063 -217.172794)
			(xy 363.17301 -217.194892) (xy 363.378242 -217.550238) (xy 363.401102 -217.554556) (xy 363.425903 -217.559751)
			(xy 363.473642 -217.57674) (xy 363.518219 -217.600833) (xy 363.558584 -217.631463) (xy 363.593788 -217.667908)
			(xy 363.623 -217.709312) (xy 363.645533 -217.754697) (xy 363.660856 -217.802996) (xy 363.668608 -217.85307)
			(xy 363.669072 -217.878406) (xy 363.668564 -217.904293) (xy 363.660465 -217.955431) (xy 363.644466 -218.004671)
			(xy 363.62096 -218.050803) (xy 363.590528 -218.09269) (xy 363.553918 -218.1293) (xy 363.512031 -218.159732)
			(xy 363.465899 -218.183238) (xy 363.416659 -218.199237) (xy 363.365521 -218.207336) (xy 363.313747 -218.207336)
			(xy 363.262609 -218.199237) (xy 363.213369 -218.183238) (xy 363.167237 -218.159732) (xy 363.12535 -218.1293)
			(xy 363.08874 -218.09269) (xy 363.058308 -218.050803) (xy 363.034802 -218.004671) (xy 363.018803 -217.955431)
			(xy 363.010704 -217.904293) (xy 363.010196 -217.878406) (xy 363.010727 -217.850698) (xy 363.019921 -217.796051)
			(xy 363.028484 -217.769694) (xy 363.036358 -217.747596) (xy 362.83138 -217.392504) (xy 362.80852 -217.388186)
			(xy 362.783675 -217.38302) (xy 362.735826 -217.366126) (xy 362.691133 -217.342096) (xy 362.650653 -217.311499)
			(xy 362.615341 -217.275058) (xy 362.586033 -217.233634) (xy 362.563422 -217.188207) (xy 362.548043 -217.13985)
			(xy 362.540258 -217.089708) (xy 362.539788 -217.064336) (xy 361.319572 -217.064336) (xy 361.318959 -217.091989)
			(xy 361.309638 -217.146507) (xy 361.30103 -217.172794) (xy 361.29341 -217.194892) (xy 361.498642 -217.550238)
			(xy 361.521502 -217.554556) (xy 361.546303 -217.559751) (xy 361.594042 -217.57674) (xy 361.638619 -217.600833)
			(xy 361.678984 -217.631463) (xy 361.714188 -217.667908) (xy 361.7434 -217.709312) (xy 361.765933 -217.754697)
			(xy 361.781256 -217.802996) (xy 361.789008 -217.85307) (xy 361.789472 -217.878406) (xy 361.788964 -217.904293)
			(xy 361.780865 -217.955431) (xy 361.764866 -218.004671) (xy 361.74136 -218.050803) (xy 361.710928 -218.09269)
			(xy 361.674318 -218.1293) (xy 361.632431 -218.159732) (xy 361.586299 -218.183238) (xy 361.537059 -218.199237)
			(xy 361.485921 -218.207336) (xy 361.434147 -218.207336) (xy 361.383009 -218.199237) (xy 361.333769 -218.183238)
			(xy 361.287637 -218.159732) (xy 361.24575 -218.1293) (xy 361.20914 -218.09269) (xy 361.178708 -218.050803)
			(xy 361.155202 -218.004671) (xy 361.139203 -217.955431) (xy 361.131104 -217.904293) (xy 361.130596 -217.878406)
			(xy 361.131127 -217.850698) (xy 361.140321 -217.796051) (xy 361.148884 -217.769694) (xy 361.156758 -217.747596)
			(xy 360.95178 -217.392504) (xy 360.92892 -217.388186) (xy 360.904075 -217.38302) (xy 360.856226 -217.366126)
			(xy 360.811533 -217.342096) (xy 360.771053 -217.311499) (xy 360.735741 -217.275058) (xy 360.706433 -217.233634)
			(xy 360.683822 -217.188207) (xy 360.668443 -217.13985) (xy 360.660658 -217.089708) (xy 360.660188 -217.064336)
			(xy 359.439972 -217.064336) (xy 359.439506 -217.089682) (xy 359.431728 -217.139773) (xy 359.416377 -217.188085)
			(xy 359.393813 -217.233478) (xy 359.364569 -217.274884) (xy 359.329334 -217.311328) (xy 359.288936 -217.34195)
			(xy 359.244329 -217.36603) (xy 359.196562 -217.383) (xy 359.171748 -217.388186) (xy 359.148888 -217.392504)
			(xy 358.94391 -217.747596) (xy 358.951784 -217.76944) (xy 358.960373 -217.795856) (xy 358.969563 -217.850633)
			(xy 358.970072 -217.878406) (xy 358.969564 -217.904293) (xy 358.961465 -217.955431) (xy 358.945466 -218.004671)
			(xy 358.92196 -218.050803) (xy 358.891528 -218.09269) (xy 358.854918 -218.1293) (xy 358.813031 -218.159732)
			(xy 358.766899 -218.183238) (xy 358.717659 -218.199237) (xy 358.666521 -218.207336) (xy 358.614747 -218.207336)
			(xy 358.563609 -218.199237) (xy 358.514369 -218.183238) (xy 358.468237 -218.159732) (xy 358.42635 -218.1293)
			(xy 358.38974 -218.09269) (xy 358.359308 -218.050803) (xy 358.335802 -218.004671) (xy 358.319803 -217.955431)
			(xy 358.311704 -217.904293) (xy 358.311196 -217.878406) (xy 358.030272 -217.878406) (xy 358.029741 -217.906114)
			(xy 358.020546 -217.960761) (xy 358.011984 -217.987118) (xy 358.004364 -218.008962) (xy 358.209342 -218.364054)
			(xy 358.232202 -218.368372) (xy 358.257007 -218.373552) (xy 358.304747 -218.390542) (xy 358.349324 -218.414636)
			(xy 358.38969 -218.445268) (xy 358.424894 -218.481716) (xy 358.454106 -218.523121) (xy 358.476638 -218.568508)
			(xy 358.491959 -218.616809) (xy 358.49971 -218.666886) (xy 358.500172 -218.692222) (xy 359.720388 -218.692222)
			(xy 359.720939 -218.66688) (xy 359.728707 -218.616793) (xy 359.744048 -218.568485) (xy 359.766601 -218.523094)
			(xy 359.795834 -218.481689) (xy 359.831059 -218.445245) (xy 359.871446 -218.41462) (xy 359.916044 -218.390537)
			(xy 359.963802 -218.373561) (xy 359.988612 -218.368372) (xy 360.011472 -218.364054) (xy 360.216704 -218.008708)
			(xy 360.20883 -217.98661) (xy 360.200361 -217.960367) (xy 360.191292 -217.905977) (xy 360.190796 -217.878406)
			(xy 360.191304 -217.852519) (xy 360.199403 -217.801381) (xy 360.215402 -217.752141) (xy 360.238908 -217.706009)
			(xy 360.26934 -217.664122) (xy 360.30595 -217.627512) (xy 360.347837 -217.59708) (xy 360.393969 -217.573574)
			(xy 360.443209 -217.557575) (xy 360.494347 -217.549476) (xy 360.546121 -217.549476) (xy 360.597259 -217.557575)
			(xy 360.646499 -217.573574) (xy 360.692631 -217.59708) (xy 360.734518 -217.627512) (xy 360.771128 -217.664122)
			(xy 360.80156 -217.706009) (xy 360.825066 -217.752141) (xy 360.841065 -217.801381) (xy 360.849164 -217.852519)
			(xy 360.849672 -217.878406) (xy 360.849225 -217.903782) (xy 360.841455 -217.953934) (xy 360.826085 -218.002302)
			(xy 360.803477 -218.047739) (xy 360.774167 -218.089171) (xy 360.73885 -218.125617) (xy 360.69836 -218.156215)
			(xy 360.653656 -218.18024) (xy 360.605796 -218.197124) (xy 360.58094 -218.202256) (xy 360.55808 -218.206574)
			(xy 360.353356 -218.561412) (xy 360.36123 -218.583256) (xy 360.369881 -218.609663) (xy 360.379198 -218.66444)
			(xy 360.379772 -218.692222) (xy 361.600496 -218.692222) (xy 361.601002 -218.666888) (xy 361.608751 -218.616817)
			(xy 361.62407 -218.568521) (xy 361.646599 -218.523138) (xy 361.675805 -218.481736) (xy 361.711003 -218.44529)
			(xy 361.751363 -218.414659) (xy 361.795934 -218.390564) (xy 361.843667 -218.373572) (xy 361.868466 -218.368372)
			(xy 361.891326 -218.364054) (xy 362.096304 -218.008962) (xy 362.088684 -217.986864) (xy 362.080159 -217.960694)
			(xy 362.070969 -217.906431) (xy 362.070396 -217.878914) (xy 362.070396 -217.878406) (xy 362.070904 -217.852519)
			(xy 362.079003 -217.801381) (xy 362.095002 -217.752141) (xy 362.118508 -217.706009) (xy 362.14894 -217.664122)
			(xy 362.18555 -217.627512) (xy 362.227437 -217.59708) (xy 362.273569 -217.573574) (xy 362.322809 -217.557575)
			(xy 362.373947 -217.549476) (xy 362.425721 -217.549476) (xy 362.476859 -217.557575) (xy 362.526099 -217.573574)
			(xy 362.572231 -217.59708) (xy 362.614118 -217.627512) (xy 362.650728 -217.664122) (xy 362.68116 -217.706009)
			(xy 362.704666 -217.752141) (xy 362.720665 -217.801381) (xy 362.728764 -217.852519) (xy 362.729272 -217.878406)
			(xy 362.728863 -217.903772) (xy 362.721112 -217.953909) (xy 362.705764 -218.002264) (xy 362.683182 -218.047694)
			(xy 362.6539 -218.089122) (xy 362.61861 -218.12557) (xy 362.578149 -218.156175) (xy 362.533472 -218.180212)
			(xy 362.485638 -218.197113) (xy 362.460794 -218.202256) (xy 362.437934 -218.206574) (xy 362.23321 -218.561412)
			(xy 362.241084 -218.583256) (xy 362.249677 -218.609671) (xy 362.258865 -218.664449) (xy 362.259372 -218.692222)
			(xy 363.479588 -218.692222) (xy 363.480139 -218.66688) (xy 363.487907 -218.616793) (xy 363.503248 -218.568485)
			(xy 363.525801 -218.523094) (xy 363.555034 -218.481689) (xy 363.590259 -218.445245) (xy 363.630646 -218.41462)
			(xy 363.675244 -218.390537) (xy 363.723002 -218.373561) (xy 363.747812 -218.368372) (xy 363.770672 -218.364054)
			(xy 363.975904 -218.008708) (xy 363.96803 -217.98661) (xy 363.959561 -217.960367) (xy 363.950492 -217.905977)
			(xy 363.949996 -217.878406) (xy 363.950504 -217.852519) (xy 363.958603 -217.801381) (xy 363.974602 -217.752141)
			(xy 363.998108 -217.706009) (xy 364.02854 -217.664122) (xy 364.06515 -217.627512) (xy 364.107037 -217.59708)
			(xy 364.153169 -217.573574) (xy 364.202409 -217.557575) (xy 364.253547 -217.549476) (xy 364.305321 -217.549476)
			(xy 364.356459 -217.557575) (xy 364.405699 -217.573574) (xy 364.451831 -217.59708) (xy 364.493718 -217.627512)
			(xy 364.530328 -217.664122) (xy 364.56076 -217.706009) (xy 364.584266 -217.752141) (xy 364.600265 -217.801381)
			(xy 364.608364 -217.852519) (xy 364.608872 -217.878406) (xy 364.608425 -217.903782) (xy 364.600655 -217.953934)
			(xy 364.585285 -218.002302) (xy 364.562677 -218.047739) (xy 364.533367 -218.089171) (xy 364.49805 -218.125617)
			(xy 364.45756 -218.156215) (xy 364.412856 -218.18024) (xy 364.364996 -218.197124) (xy 364.34014 -218.202256)
			(xy 364.31728 -218.206574) (xy 364.112556 -218.561412) (xy 364.12043 -218.583256) (xy 364.129081 -218.609663)
			(xy 364.138398 -218.66444) (xy 364.138972 -218.692222) (xy 365.359188 -218.692222) (xy 365.359739 -218.66688)
			(xy 365.367507 -218.616793) (xy 365.382848 -218.568485) (xy 365.405401 -218.523094) (xy 365.434634 -218.481689)
			(xy 365.469859 -218.445245) (xy 365.510246 -218.41462) (xy 365.554844 -218.390537) (xy 365.602602 -218.373561)
			(xy 365.627412 -218.368372) (xy 365.650272 -218.364054) (xy 365.855504 -218.008708) (xy 365.84763 -217.98661)
			(xy 365.839161 -217.960367) (xy 365.830092 -217.905977) (xy 365.829596 -217.878406) (xy 365.830104 -217.852519)
			(xy 365.838203 -217.801381) (xy 365.854202 -217.752141) (xy 365.877708 -217.706009) (xy 365.90814 -217.664122)
			(xy 365.94475 -217.627512) (xy 365.986637 -217.59708) (xy 366.032769 -217.573574) (xy 366.082009 -217.557575)
			(xy 366.133147 -217.549476) (xy 366.184921 -217.549476) (xy 366.236059 -217.557575) (xy 366.285299 -217.573574)
			(xy 366.331431 -217.59708) (xy 366.373318 -217.627512) (xy 366.409928 -217.664122) (xy 366.44036 -217.706009)
			(xy 366.463866 -217.752141) (xy 366.479865 -217.801381) (xy 366.487964 -217.852519) (xy 366.488472 -217.878406)
			(xy 366.488025 -217.903782) (xy 366.480255 -217.953934) (xy 366.464885 -218.002302) (xy 366.442277 -218.047739)
			(xy 366.412967 -218.089171) (xy 366.37765 -218.125617) (xy 366.33716 -218.156215) (xy 366.292456 -218.18024)
			(xy 366.244596 -218.197124) (xy 366.21974 -218.202256) (xy 366.19688 -218.206574) (xy 365.992156 -218.561412)
			(xy 366.00003 -218.583256) (xy 366.008681 -218.609663) (xy 366.017998 -218.66444) (xy 366.018572 -218.692222)
			(xy 367.238788 -218.692222) (xy 367.239339 -218.66688) (xy 367.247107 -218.616793) (xy 367.262448 -218.568485)
			(xy 367.285001 -218.523094) (xy 367.314234 -218.481689) (xy 367.349459 -218.445245) (xy 367.389846 -218.41462)
			(xy 367.434444 -218.390537) (xy 367.482202 -218.373561) (xy 367.507012 -218.368372) (xy 367.529872 -218.364054)
			(xy 367.735104 -218.008708) (xy 367.72723 -217.98661) (xy 367.718761 -217.960367) (xy 367.709692 -217.905977)
			(xy 367.709196 -217.878406) (xy 367.709704 -217.852519) (xy 367.717803 -217.801381) (xy 367.733802 -217.752141)
			(xy 367.757308 -217.706009) (xy 367.78774 -217.664122) (xy 367.82435 -217.627512) (xy 367.866237 -217.59708)
			(xy 367.912369 -217.573574) (xy 367.961609 -217.557575) (xy 368.012747 -217.549476) (xy 368.064521 -217.549476)
			(xy 368.115659 -217.557575) (xy 368.164899 -217.573574) (xy 368.211031 -217.59708) (xy 368.252918 -217.627512)
			(xy 368.289528 -217.664122) (xy 368.31996 -217.706009) (xy 368.343466 -217.752141) (xy 368.359465 -217.801381)
			(xy 368.367564 -217.852519) (xy 368.368072 -217.878406) (xy 368.367625 -217.903782) (xy 368.359855 -217.953934)
			(xy 368.344485 -218.002302) (xy 368.321877 -218.047739) (xy 368.292567 -218.089171) (xy 368.25725 -218.125617)
			(xy 368.21676 -218.156215) (xy 368.172056 -218.18024) (xy 368.124196 -218.197124) (xy 368.09934 -218.202256)
			(xy 368.07648 -218.206574) (xy 367.871756 -218.561412) (xy 367.87963 -218.583256) (xy 367.888281 -218.609663)
			(xy 367.897598 -218.66444) (xy 367.898172 -218.692222) (xy 369.118388 -218.692222) (xy 369.118939 -218.66688)
			(xy 369.126707 -218.616793) (xy 369.142048 -218.568485) (xy 369.164601 -218.523094) (xy 369.193834 -218.481689)
			(xy 369.229059 -218.445245) (xy 369.269446 -218.41462) (xy 369.314044 -218.390537) (xy 369.361802 -218.373561)
			(xy 369.386612 -218.368372) (xy 369.409472 -218.364054) (xy 369.614704 -218.008708) (xy 369.60683 -217.98661)
			(xy 369.598361 -217.960367) (xy 369.589292 -217.905977) (xy 369.588796 -217.878406) (xy 369.589304 -217.852519)
			(xy 369.597403 -217.801381) (xy 369.613402 -217.752141) (xy 369.636908 -217.706009) (xy 369.66734 -217.664122)
			(xy 369.70395 -217.627512) (xy 369.745837 -217.59708) (xy 369.791969 -217.573574) (xy 369.841209 -217.557575)
			(xy 369.892347 -217.549476) (xy 369.944121 -217.549476) (xy 369.995259 -217.557575) (xy 370.044499 -217.573574)
			(xy 370.090631 -217.59708) (xy 370.132518 -217.627512) (xy 370.169128 -217.664122) (xy 370.19956 -217.706009)
			(xy 370.223066 -217.752141) (xy 370.239065 -217.801381) (xy 370.247164 -217.852519) (xy 370.247672 -217.878406)
			(xy 370.247225 -217.903782) (xy 370.239455 -217.953934) (xy 370.224085 -218.002302) (xy 370.201477 -218.047739)
			(xy 370.172167 -218.089171) (xy 370.13685 -218.125617) (xy 370.09636 -218.156215) (xy 370.051656 -218.18024)
			(xy 370.003796 -218.197124) (xy 369.97894 -218.202256) (xy 369.95608 -218.206574) (xy 369.751356 -218.561412)
			(xy 369.75923 -218.583256) (xy 369.767881 -218.609663) (xy 369.777198 -218.66444) (xy 369.777772 -218.692222)
			(xy 370.997988 -218.692222) (xy 370.998539 -218.66688) (xy 371.006307 -218.616793) (xy 371.021648 -218.568485)
			(xy 371.044201 -218.523094) (xy 371.073434 -218.481689) (xy 371.108659 -218.445245) (xy 371.149046 -218.41462)
			(xy 371.193644 -218.390537) (xy 371.241402 -218.373561) (xy 371.266212 -218.368372) (xy 371.289072 -218.364054)
			(xy 371.494304 -218.008708) (xy 371.48643 -217.98661) (xy 371.477961 -217.960367) (xy 371.468892 -217.905977)
			(xy 371.468396 -217.878406) (xy 371.468904 -217.852519) (xy 371.477003 -217.801381) (xy 371.493002 -217.752141)
			(xy 371.516508 -217.706009) (xy 371.54694 -217.664122) (xy 371.58355 -217.627512) (xy 371.625437 -217.59708)
			(xy 371.671569 -217.573574) (xy 371.720809 -217.557575) (xy 371.771947 -217.549476) (xy 371.823721 -217.549476)
			(xy 371.874859 -217.557575) (xy 371.924099 -217.573574) (xy 371.970231 -217.59708) (xy 372.012118 -217.627512)
			(xy 372.048728 -217.664122) (xy 372.07916 -217.706009) (xy 372.102666 -217.752141) (xy 372.118665 -217.801381)
			(xy 372.126764 -217.852519) (xy 372.127272 -217.878406) (xy 372.126825 -217.903782) (xy 372.119055 -217.953934)
			(xy 372.103685 -218.002302) (xy 372.081077 -218.047739) (xy 372.051767 -218.089171) (xy 372.01645 -218.125617)
			(xy 371.97596 -218.156215) (xy 371.931256 -218.18024) (xy 371.883396 -218.197124) (xy 371.85854 -218.202256)
			(xy 371.83568 -218.206574) (xy 371.630956 -218.561412) (xy 371.63883 -218.583256) (xy 371.647481 -218.609663)
			(xy 371.656798 -218.66444) (xy 371.657372 -218.692222) (xy 372.877588 -218.692222) (xy 372.878139 -218.66688)
			(xy 372.885907 -218.616793) (xy 372.901248 -218.568485) (xy 372.923801 -218.523094) (xy 372.953034 -218.481689)
			(xy 372.988259 -218.445245) (xy 373.028646 -218.41462) (xy 373.073244 -218.390537) (xy 373.121002 -218.373561)
			(xy 373.145812 -218.368372) (xy 373.168672 -218.364054) (xy 373.373904 -218.008708) (xy 373.36603 -217.98661)
			(xy 373.357561 -217.960367) (xy 373.348492 -217.905977) (xy 373.347996 -217.878406) (xy 373.348504 -217.852519)
			(xy 373.356603 -217.801381) (xy 373.372602 -217.752141) (xy 373.396108 -217.706009) (xy 373.42654 -217.664122)
			(xy 373.46315 -217.627512) (xy 373.505037 -217.59708) (xy 373.551169 -217.573574) (xy 373.600409 -217.557575)
			(xy 373.651547 -217.549476) (xy 373.703321 -217.549476) (xy 373.754459 -217.557575) (xy 373.803699 -217.573574)
			(xy 373.849831 -217.59708) (xy 373.891718 -217.627512) (xy 373.928328 -217.664122) (xy 373.95876 -217.706009)
			(xy 373.982266 -217.752141) (xy 373.998265 -217.801381) (xy 374.006364 -217.852519) (xy 374.006872 -217.878406)
			(xy 374.006425 -217.903782) (xy 373.998655 -217.953934) (xy 373.983285 -218.002302) (xy 373.960677 -218.047739)
			(xy 373.931367 -218.089171) (xy 373.89605 -218.125617) (xy 373.85556 -218.156215) (xy 373.810856 -218.18024)
			(xy 373.762996 -218.197124) (xy 373.73814 -218.202256) (xy 373.71528 -218.206574) (xy 373.510556 -218.561412)
			(xy 373.51843 -218.583256) (xy 373.527081 -218.609663) (xy 373.536398 -218.66444) (xy 373.536972 -218.692222)
			(xy 374.757188 -218.692222) (xy 374.757739 -218.66688) (xy 374.765507 -218.616793) (xy 374.780848 -218.568485)
			(xy 374.803401 -218.523094) (xy 374.832634 -218.481689) (xy 374.867859 -218.445245) (xy 374.908246 -218.41462)
			(xy 374.952844 -218.390537) (xy 375.000602 -218.373561) (xy 375.025412 -218.368372) (xy 375.048272 -218.364054)
			(xy 375.253504 -218.008708) (xy 375.24563 -217.98661) (xy 375.237161 -217.960367) (xy 375.228092 -217.905977)
			(xy 375.227596 -217.878406) (xy 375.228104 -217.852519) (xy 375.236203 -217.801381) (xy 375.252202 -217.752141)
			(xy 375.275708 -217.706009) (xy 375.30614 -217.664122) (xy 375.34275 -217.627512) (xy 375.384637 -217.59708)
			(xy 375.430769 -217.573574) (xy 375.480009 -217.557575) (xy 375.531147 -217.549476) (xy 375.582921 -217.549476)
			(xy 375.634059 -217.557575) (xy 375.683299 -217.573574) (xy 375.729431 -217.59708) (xy 375.771318 -217.627512)
			(xy 375.807928 -217.664122) (xy 375.83836 -217.706009) (xy 375.861866 -217.752141) (xy 375.877865 -217.801381)
			(xy 375.885964 -217.852519) (xy 375.886472 -217.878406) (xy 375.886025 -217.903782) (xy 375.878255 -217.953934)
			(xy 375.862885 -218.002302) (xy 375.840277 -218.047739) (xy 375.810967 -218.089171) (xy 375.77565 -218.125617)
			(xy 375.73516 -218.156215) (xy 375.690456 -218.18024) (xy 375.642596 -218.197124) (xy 375.61774 -218.202256)
			(xy 375.59488 -218.206574) (xy 375.390156 -218.561412) (xy 375.39803 -218.583256) (xy 375.406681 -218.609663)
			(xy 375.415998 -218.66444) (xy 375.416572 -218.692222) (xy 376.636788 -218.692222) (xy 376.637339 -218.66688)
			(xy 376.645107 -218.616793) (xy 376.660448 -218.568485) (xy 376.683001 -218.523094) (xy 376.712234 -218.481689)
			(xy 376.747459 -218.445245) (xy 376.787846 -218.41462) (xy 376.832444 -218.390537) (xy 376.880202 -218.373561)
			(xy 376.905012 -218.368372) (xy 376.927872 -218.364054) (xy 377.133104 -218.008708) (xy 377.12523 -217.98661)
			(xy 377.116761 -217.960367) (xy 377.107692 -217.905977) (xy 377.107196 -217.878406) (xy 377.107704 -217.852519)
			(xy 377.115803 -217.801381) (xy 377.131802 -217.752141) (xy 377.155308 -217.706009) (xy 377.18574 -217.664122)
			(xy 377.22235 -217.627512) (xy 377.264237 -217.59708) (xy 377.310369 -217.573574) (xy 377.359609 -217.557575)
			(xy 377.410747 -217.549476) (xy 377.462521 -217.549476) (xy 377.513659 -217.557575) (xy 377.562899 -217.573574)
			(xy 377.609031 -217.59708) (xy 377.650918 -217.627512) (xy 377.687528 -217.664122) (xy 377.71796 -217.706009)
			(xy 377.741466 -217.752141) (xy 377.757465 -217.801381) (xy 377.765564 -217.852519) (xy 377.766072 -217.878406)
			(xy 377.765625 -217.903782) (xy 377.757855 -217.953934) (xy 377.742485 -218.002302) (xy 377.719877 -218.047739)
			(xy 377.690567 -218.089171) (xy 377.65525 -218.125617) (xy 377.61476 -218.156215) (xy 377.570056 -218.18024)
			(xy 377.522196 -218.197124) (xy 377.49734 -218.202256) (xy 377.47448 -218.206574) (xy 377.269756 -218.561412)
			(xy 377.27763 -218.583256) (xy 377.286281 -218.609663) (xy 377.295598 -218.66444) (xy 377.296172 -218.692222)
			(xy 378.516388 -218.692222) (xy 378.516939 -218.66688) (xy 378.524707 -218.616793) (xy 378.540048 -218.568485)
			(xy 378.562601 -218.523094) (xy 378.591834 -218.481689) (xy 378.627059 -218.445245) (xy 378.667446 -218.41462)
			(xy 378.712044 -218.390537) (xy 378.759802 -218.373561) (xy 378.784612 -218.368372) (xy 378.807472 -218.364054)
			(xy 379.012704 -218.008708) (xy 379.00483 -217.98661) (xy 378.996361 -217.960367) (xy 378.987292 -217.905977)
			(xy 378.986796 -217.878406) (xy 378.987304 -217.852519) (xy 378.995403 -217.801381) (xy 379.011402 -217.752141)
			(xy 379.034908 -217.706009) (xy 379.06534 -217.664122) (xy 379.10195 -217.627512) (xy 379.143837 -217.59708)
			(xy 379.189969 -217.573574) (xy 379.239209 -217.557575) (xy 379.290347 -217.549476) (xy 379.342121 -217.549476)
			(xy 379.393259 -217.557575) (xy 379.442499 -217.573574) (xy 379.488631 -217.59708) (xy 379.530518 -217.627512)
			(xy 379.567128 -217.664122) (xy 379.59756 -217.706009) (xy 379.621066 -217.752141) (xy 379.637065 -217.801381)
			(xy 379.645164 -217.852519) (xy 379.645672 -217.878406) (xy 379.645225 -217.903782) (xy 379.637455 -217.953934)
			(xy 379.622085 -218.002302) (xy 379.599477 -218.047739) (xy 379.570167 -218.089171) (xy 379.53485 -218.125617)
			(xy 379.49436 -218.156215) (xy 379.449656 -218.18024) (xy 379.401796 -218.197124) (xy 379.37694 -218.202256)
			(xy 379.35408 -218.206574) (xy 379.149356 -218.561412) (xy 379.15723 -218.583256) (xy 379.165881 -218.609663)
			(xy 379.175198 -218.66444) (xy 379.175772 -218.692222) (xy 380.395988 -218.692222) (xy 380.396539 -218.66688)
			(xy 380.404307 -218.616793) (xy 380.419648 -218.568485) (xy 380.442201 -218.523094) (xy 380.471434 -218.481689)
			(xy 380.506659 -218.445245) (xy 380.547046 -218.41462) (xy 380.591644 -218.390537) (xy 380.639402 -218.373561)
			(xy 380.664212 -218.368372) (xy 380.687072 -218.364054) (xy 380.892304 -218.008708) (xy 380.88443 -217.98661)
			(xy 380.875961 -217.960367) (xy 380.866892 -217.905977) (xy 380.866396 -217.878406) (xy 380.866904 -217.852519)
			(xy 380.875003 -217.801381) (xy 380.891002 -217.752141) (xy 380.914508 -217.706009) (xy 380.94494 -217.664122)
			(xy 380.98155 -217.627512) (xy 381.023437 -217.59708) (xy 381.069569 -217.573574) (xy 381.118809 -217.557575)
			(xy 381.169947 -217.549476) (xy 381.221721 -217.549476) (xy 381.272859 -217.557575) (xy 381.322099 -217.573574)
			(xy 381.368231 -217.59708) (xy 381.410118 -217.627512) (xy 381.446728 -217.664122) (xy 381.47716 -217.706009)
			(xy 381.500666 -217.752141) (xy 381.516665 -217.801381) (xy 381.524764 -217.852519) (xy 381.525272 -217.878406)
			(xy 381.524825 -217.903782) (xy 381.517055 -217.953934) (xy 381.501685 -218.002302) (xy 381.479077 -218.047739)
			(xy 381.449767 -218.089171) (xy 381.41445 -218.125617) (xy 381.37396 -218.156215) (xy 381.329256 -218.18024)
			(xy 381.281396 -218.197124) (xy 381.25654 -218.202256) (xy 381.23368 -218.206574) (xy 381.028956 -218.561412)
			(xy 381.03683 -218.583256) (xy 381.045481 -218.609663) (xy 381.054798 -218.66444) (xy 381.055372 -218.692222)
			(xy 381.054864 -218.718129) (xy 381.046758 -218.769306) (xy 381.030746 -218.818585) (xy 381.007223 -218.864752)
			(xy 380.976767 -218.906671) (xy 380.940129 -218.943309) (xy 380.89821 -218.973765) (xy 380.852043 -218.997288)
			(xy 380.802764 -219.0133) (xy 380.751587 -219.021406) (xy 380.699773 -219.021406) (xy 380.648596 -219.0133)
			(xy 380.599317 -218.997288) (xy 380.55315 -218.973765) (xy 380.511231 -218.943309) (xy 380.474593 -218.906671)
			(xy 380.444137 -218.864752) (xy 380.420614 -218.818585) (xy 380.404602 -218.769306) (xy 380.396496 -218.718129)
			(xy 380.395988 -218.692222) (xy 379.175772 -218.692222) (xy 379.175264 -218.718129) (xy 379.167158 -218.769306)
			(xy 379.151146 -218.818585) (xy 379.127623 -218.864752) (xy 379.097167 -218.906671) (xy 379.060529 -218.943309)
			(xy 379.01861 -218.973765) (xy 378.972443 -218.997288) (xy 378.923164 -219.0133) (xy 378.871987 -219.021406)
			(xy 378.820173 -219.021406) (xy 378.768996 -219.0133) (xy 378.719717 -218.997288) (xy 378.67355 -218.973765)
			(xy 378.631631 -218.943309) (xy 378.594993 -218.906671) (xy 378.564537 -218.864752) (xy 378.541014 -218.818585)
			(xy 378.525002 -218.769306) (xy 378.516896 -218.718129) (xy 378.516388 -218.692222) (xy 377.296172 -218.692222)
			(xy 377.295664 -218.718129) (xy 377.287558 -218.769306) (xy 377.271546 -218.818585) (xy 377.248023 -218.864752)
			(xy 377.217567 -218.906671) (xy 377.180929 -218.943309) (xy 377.13901 -218.973765) (xy 377.092843 -218.997288)
			(xy 377.043564 -219.0133) (xy 376.992387 -219.021406) (xy 376.940573 -219.021406) (xy 376.889396 -219.0133)
			(xy 376.840117 -218.997288) (xy 376.79395 -218.973765) (xy 376.752031 -218.943309) (xy 376.715393 -218.906671)
			(xy 376.684937 -218.864752) (xy 376.661414 -218.818585) (xy 376.645402 -218.769306) (xy 376.637296 -218.718129)
			(xy 376.636788 -218.692222) (xy 375.416572 -218.692222) (xy 375.416064 -218.718129) (xy 375.407958 -218.769306)
			(xy 375.391946 -218.818585) (xy 375.368423 -218.864752) (xy 375.337967 -218.906671) (xy 375.301329 -218.943309)
			(xy 375.25941 -218.973765) (xy 375.213243 -218.997288) (xy 375.163964 -219.0133) (xy 375.112787 -219.021406)
			(xy 375.060973 -219.021406) (xy 375.009796 -219.0133) (xy 374.960517 -218.997288) (xy 374.91435 -218.973765)
			(xy 374.872431 -218.943309) (xy 374.835793 -218.906671) (xy 374.805337 -218.864752) (xy 374.781814 -218.818585)
			(xy 374.765802 -218.769306) (xy 374.757696 -218.718129) (xy 374.757188 -218.692222) (xy 373.536972 -218.692222)
			(xy 373.536464 -218.718129) (xy 373.528358 -218.769306) (xy 373.512346 -218.818585) (xy 373.488823 -218.864752)
			(xy 373.458367 -218.906671) (xy 373.421729 -218.943309) (xy 373.37981 -218.973765) (xy 373.333643 -218.997288)
			(xy 373.284364 -219.0133) (xy 373.233187 -219.021406) (xy 373.181373 -219.021406) (xy 373.130196 -219.0133)
			(xy 373.080917 -218.997288) (xy 373.03475 -218.973765) (xy 372.992831 -218.943309) (xy 372.956193 -218.906671)
			(xy 372.925737 -218.864752) (xy 372.902214 -218.818585) (xy 372.886202 -218.769306) (xy 372.878096 -218.718129)
			(xy 372.877588 -218.692222) (xy 371.657372 -218.692222) (xy 371.656864 -218.718129) (xy 371.648758 -218.769306)
			(xy 371.632746 -218.818585) (xy 371.609223 -218.864752) (xy 371.578767 -218.906671) (xy 371.542129 -218.943309)
			(xy 371.50021 -218.973765) (xy 371.454043 -218.997288) (xy 371.404764 -219.0133) (xy 371.353587 -219.021406)
			(xy 371.301773 -219.021406) (xy 371.250596 -219.0133) (xy 371.201317 -218.997288) (xy 371.15515 -218.973765)
			(xy 371.113231 -218.943309) (xy 371.076593 -218.906671) (xy 371.046137 -218.864752) (xy 371.022614 -218.818585)
			(xy 371.006602 -218.769306) (xy 370.998496 -218.718129) (xy 370.997988 -218.692222) (xy 369.777772 -218.692222)
			(xy 369.777264 -218.718129) (xy 369.769158 -218.769306) (xy 369.753146 -218.818585) (xy 369.729623 -218.864752)
			(xy 369.699167 -218.906671) (xy 369.662529 -218.943309) (xy 369.62061 -218.973765) (xy 369.574443 -218.997288)
			(xy 369.525164 -219.0133) (xy 369.473987 -219.021406) (xy 369.422173 -219.021406) (xy 369.370996 -219.0133)
			(xy 369.321717 -218.997288) (xy 369.27555 -218.973765) (xy 369.233631 -218.943309) (xy 369.196993 -218.906671)
			(xy 369.166537 -218.864752) (xy 369.143014 -218.818585) (xy 369.127002 -218.769306) (xy 369.118896 -218.718129)
			(xy 369.118388 -218.692222) (xy 367.898172 -218.692222) (xy 367.897664 -218.718129) (xy 367.889558 -218.769306)
			(xy 367.873546 -218.818585) (xy 367.850023 -218.864752) (xy 367.819567 -218.906671) (xy 367.782929 -218.943309)
			(xy 367.74101 -218.973765) (xy 367.694843 -218.997288) (xy 367.645564 -219.0133) (xy 367.594387 -219.021406)
			(xy 367.542573 -219.021406) (xy 367.491396 -219.0133) (xy 367.442117 -218.997288) (xy 367.39595 -218.973765)
			(xy 367.354031 -218.943309) (xy 367.317393 -218.906671) (xy 367.286937 -218.864752) (xy 367.263414 -218.818585)
			(xy 367.247402 -218.769306) (xy 367.239296 -218.718129) (xy 367.238788 -218.692222) (xy 366.018572 -218.692222)
			(xy 366.018064 -218.718129) (xy 366.009958 -218.769306) (xy 365.993946 -218.818585) (xy 365.970423 -218.864752)
			(xy 365.939967 -218.906671) (xy 365.903329 -218.943309) (xy 365.86141 -218.973765) (xy 365.815243 -218.997288)
			(xy 365.765964 -219.0133) (xy 365.714787 -219.021406) (xy 365.662973 -219.021406) (xy 365.611796 -219.0133)
			(xy 365.562517 -218.997288) (xy 365.51635 -218.973765) (xy 365.474431 -218.943309) (xy 365.437793 -218.906671)
			(xy 365.407337 -218.864752) (xy 365.383814 -218.818585) (xy 365.367802 -218.769306) (xy 365.359696 -218.718129)
			(xy 365.359188 -218.692222) (xy 364.138972 -218.692222) (xy 364.138464 -218.718129) (xy 364.130358 -218.769306)
			(xy 364.114346 -218.818585) (xy 364.090823 -218.864752) (xy 364.060367 -218.906671) (xy 364.023729 -218.943309)
			(xy 363.98181 -218.973765) (xy 363.935643 -218.997288) (xy 363.886364 -219.0133) (xy 363.835187 -219.021406)
			(xy 363.783373 -219.021406) (xy 363.732196 -219.0133) (xy 363.682917 -218.997288) (xy 363.63675 -218.973765)
			(xy 363.594831 -218.943309) (xy 363.558193 -218.906671) (xy 363.527737 -218.864752) (xy 363.504214 -218.818585)
			(xy 363.488202 -218.769306) (xy 363.480096 -218.718129) (xy 363.479588 -218.692222) (xy 362.259372 -218.692222)
			(xy 362.258864 -218.718109) (xy 362.250765 -218.769247) (xy 362.234766 -218.818487) (xy 362.21126 -218.864619)
			(xy 362.180828 -218.906506) (xy 362.144218 -218.943116) (xy 362.102331 -218.973548) (xy 362.056199 -218.997054)
			(xy 362.006959 -219.013053) (xy 361.955821 -219.021152) (xy 361.904047 -219.021152) (xy 361.852909 -219.013053)
			(xy 361.803669 -218.997054) (xy 361.757537 -218.973548) (xy 361.71565 -218.943116) (xy 361.67904 -218.906506)
			(xy 361.648608 -218.864619) (xy 361.625102 -218.818487) (xy 361.609103 -218.769247) (xy 361.601004 -218.718109)
			(xy 361.600496 -218.692222) (xy 360.379772 -218.692222) (xy 360.379264 -218.718129) (xy 360.371158 -218.769306)
			(xy 360.355146 -218.818585) (xy 360.331623 -218.864752) (xy 360.301167 -218.906671) (xy 360.264529 -218.943309)
			(xy 360.22261 -218.973765) (xy 360.176443 -218.997288) (xy 360.127164 -219.0133) (xy 360.075987 -219.021406)
			(xy 360.024173 -219.021406) (xy 359.972996 -219.0133) (xy 359.923717 -218.997288) (xy 359.87755 -218.973765)
			(xy 359.835631 -218.943309) (xy 359.798993 -218.906671) (xy 359.768537 -218.864752) (xy 359.745014 -218.818585)
			(xy 359.729002 -218.769306) (xy 359.720896 -218.718129) (xy 359.720388 -218.692222) (xy 358.500172 -218.692222)
			(xy 358.499664 -218.718109) (xy 358.491565 -218.769247) (xy 358.475566 -218.818487) (xy 358.45206 -218.864619)
			(xy 358.421628 -218.906506) (xy 358.385018 -218.943116) (xy 358.343131 -218.973548) (xy 358.296999 -218.997054)
			(xy 358.247759 -219.013053) (xy 358.196621 -219.021152) (xy 358.144847 -219.021152) (xy 358.093709 -219.013053)
			(xy 358.044469 -218.997054) (xy 357.998337 -218.973548) (xy 357.95645 -218.943116) (xy 357.91984 -218.906506)
			(xy 357.889408 -218.864619) (xy 357.865902 -218.818487) (xy 357.849903 -218.769247) (xy 357.841804 -218.718109)
			(xy 357.841296 -218.692222) (xy 357.841831 -218.664514) (xy 357.851023 -218.609867) (xy 357.859584 -218.58351)
			(xy 357.867458 -218.561412) (xy 357.66248 -218.206574) (xy 357.63962 -218.202256) (xy 357.614783 -218.197156)
			(xy 357.567001 -218.180194) (xy 357.52238 -218.156114) (xy 357.481972 -218.125486) (xy 357.446732 -218.08903)
			(xy 357.417491 -218.047608) (xy 357.394937 -218.002196) (xy 357.379605 -217.953866) (xy 357.371854 -217.903758)
			(xy 357.371396 -217.878406) (xy 357.090472 -217.878406) (xy 357.089964 -217.904293) (xy 357.081865 -217.955431)
			(xy 357.065866 -218.004671) (xy 357.04236 -218.050803) (xy 357.011928 -218.09269) (xy 356.975318 -218.1293)
			(xy 356.933431 -218.159732) (xy 356.887299 -218.183238) (xy 356.838059 -218.199237) (xy 356.786921 -218.207336)
			(xy 356.735147 -218.207336) (xy 356.684009 -218.199237) (xy 356.634769 -218.183238) (xy 356.588637 -218.159732)
			(xy 356.54675 -218.1293) (xy 356.51014 -218.09269) (xy 356.479708 -218.050803) (xy 356.456202 -218.004671)
			(xy 356.440203 -217.955431) (xy 356.432104 -217.904293) (xy 356.431596 -217.878406) (xy 356.150672 -217.878406)
			(xy 356.150141 -217.906114) (xy 356.140946 -217.960761) (xy 356.132384 -217.987118) (xy 356.12451 -218.009216)
			(xy 356.329488 -218.364054) (xy 356.352348 -218.368372) (xy 356.377163 -218.373563) (xy 356.424941 -218.390515)
			(xy 356.469559 -218.414584) (xy 356.509965 -218.445202) (xy 356.545206 -218.481645) (xy 356.57445 -218.523056)
			(xy 356.597009 -218.568456) (xy 356.612349 -218.616776) (xy 356.620108 -218.666874) (xy 356.620572 -218.692222)
			(xy 356.620064 -218.718129) (xy 356.611958 -218.769306) (xy 356.595946 -218.818585) (xy 356.572423 -218.864752)
			(xy 356.541967 -218.906671) (xy 356.505329 -218.943309) (xy 356.46341 -218.973765) (xy 356.417243 -218.997288)
			(xy 356.367964 -219.0133) (xy 356.316787 -219.021406) (xy 356.264973 -219.021406) (xy 356.213796 -219.0133)
			(xy 356.164517 -218.997288) (xy 356.11835 -218.973765) (xy 356.076431 -218.943309) (xy 356.039793 -218.906671)
			(xy 356.009337 -218.864752) (xy 355.985814 -218.818585) (xy 355.969802 -218.769306) (xy 355.961696 -218.718129)
			(xy 355.961188 -218.692222) (xy 355.961788 -218.664505) (xy 355.971107 -218.609859) (xy 355.97973 -218.58351)
			(xy 355.987604 -218.561412) (xy 355.782626 -218.206574) (xy 355.759766 -218.202256) (xy 355.734962 -218.197073)
			(xy 355.687224 -218.180081) (xy 355.642649 -218.155985) (xy 355.602284 -218.125353) (xy 355.567082 -218.088906)
			(xy 355.53787 -218.047502) (xy 355.515337 -218.002116) (xy 355.500013 -217.953817) (xy 355.49226 -217.903742)
			(xy 355.491796 -217.878406) (xy 355.210872 -217.878406) (xy 355.210364 -217.904293) (xy 355.202265 -217.955431)
			(xy 355.186266 -218.004671) (xy 355.16276 -218.050803) (xy 355.132328 -218.09269) (xy 355.095718 -218.1293)
			(xy 355.053831 -218.159732) (xy 355.007699 -218.183238) (xy 354.958459 -218.199237) (xy 354.907321 -218.207336)
			(xy 354.855547 -218.207336) (xy 354.804409 -218.199237) (xy 354.755169 -218.183238) (xy 354.709037 -218.159732)
			(xy 354.66715 -218.1293) (xy 354.63054 -218.09269) (xy 354.600108 -218.050803) (xy 354.576602 -218.004671)
			(xy 354.560603 -217.955431) (xy 354.552504 -217.904293) (xy 354.551996 -217.878406) (xy 354.271072 -217.878406)
			(xy 354.270541 -217.906114) (xy 354.261346 -217.960761) (xy 354.252784 -217.987118) (xy 354.24491 -218.009216)
			(xy 354.449888 -218.364054) (xy 354.472748 -218.368372) (xy 354.497563 -218.373563) (xy 354.545341 -218.390515)
			(xy 354.589959 -218.414584) (xy 354.630365 -218.445202) (xy 354.665606 -218.481645) (xy 354.69485 -218.523056)
			(xy 354.717409 -218.568456) (xy 354.732749 -218.616776) (xy 354.740508 -218.666874) (xy 354.740972 -218.692222)
			(xy 354.740464 -218.718129) (xy 354.732358 -218.769306) (xy 354.716346 -218.818585) (xy 354.692823 -218.864752)
			(xy 354.662367 -218.906671) (xy 354.625729 -218.943309) (xy 354.58381 -218.973765) (xy 354.537643 -218.997288)
			(xy 354.488364 -219.0133) (xy 354.437187 -219.021406) (xy 354.385373 -219.021406) (xy 354.334196 -219.0133)
			(xy 354.284917 -218.997288) (xy 354.23875 -218.973765) (xy 354.196831 -218.943309) (xy 354.160193 -218.906671)
			(xy 354.129737 -218.864752) (xy 354.106214 -218.818585) (xy 354.090202 -218.769306) (xy 354.082096 -218.718129)
			(xy 354.081588 -218.692222) (xy 354.082188 -218.664505) (xy 354.091507 -218.609859) (xy 354.10013 -218.58351)
			(xy 354.108004 -218.561412) (xy 353.903026 -218.206574) (xy 353.880166 -218.202256) (xy 353.855362 -218.197073)
			(xy 353.807624 -218.180081) (xy 353.763049 -218.155985) (xy 353.722684 -218.125353) (xy 353.687482 -218.088906)
			(xy 353.65827 -218.047502) (xy 353.635737 -218.002116) (xy 353.620413 -217.953817) (xy 353.61266 -217.903742)
			(xy 353.612196 -217.878406) (xy 353.331272 -217.878406) (xy 353.330764 -217.904293) (xy 353.322665 -217.955431)
			(xy 353.306666 -218.004671) (xy 353.28316 -218.050803) (xy 353.252728 -218.09269) (xy 353.216118 -218.1293)
			(xy 353.174231 -218.159732) (xy 353.128099 -218.183238) (xy 353.078859 -218.199237) (xy 353.027721 -218.207336)
			(xy 352.975947 -218.207336) (xy 352.924809 -218.199237) (xy 352.875569 -218.183238) (xy 352.829437 -218.159732)
			(xy 352.78755 -218.1293) (xy 352.75094 -218.09269) (xy 352.720508 -218.050803) (xy 352.697002 -218.004671)
			(xy 352.681003 -217.955431) (xy 352.672904 -217.904293) (xy 352.672396 -217.878406) (xy 352.391472 -217.878406)
			(xy 352.390941 -217.906114) (xy 352.381746 -217.960761) (xy 352.373184 -217.987118) (xy 352.36531 -218.009216)
			(xy 352.570288 -218.364054) (xy 352.593148 -218.368372) (xy 352.617963 -218.373563) (xy 352.665741 -218.390515)
			(xy 352.710359 -218.414584) (xy 352.750765 -218.445202) (xy 352.786006 -218.481645) (xy 352.81525 -218.523056)
			(xy 352.837809 -218.568456) (xy 352.853149 -218.616776) (xy 352.860908 -218.666874) (xy 352.861372 -218.692222)
			(xy 352.860864 -218.718129) (xy 352.852758 -218.769306) (xy 352.836746 -218.818585) (xy 352.813223 -218.864752)
			(xy 352.782767 -218.906671) (xy 352.746129 -218.943309) (xy 352.70421 -218.973765) (xy 352.658043 -218.997288)
			(xy 352.608764 -219.0133) (xy 352.557587 -219.021406) (xy 352.505773 -219.021406) (xy 352.454596 -219.0133)
			(xy 352.405317 -218.997288) (xy 352.35915 -218.973765) (xy 352.317231 -218.943309) (xy 352.280593 -218.906671)
			(xy 352.250137 -218.864752) (xy 352.226614 -218.818585) (xy 352.210602 -218.769306) (xy 352.202496 -218.718129)
			(xy 352.201988 -218.692222) (xy 352.202588 -218.664505) (xy 352.211907 -218.609859) (xy 352.22053 -218.58351)
			(xy 352.228404 -218.561412) (xy 352.023426 -218.206574) (xy 352.000566 -218.202256) (xy 351.975762 -218.197073)
			(xy 351.928024 -218.180081) (xy 351.883449 -218.155985) (xy 351.843084 -218.125353) (xy 351.807882 -218.088906)
			(xy 351.77867 -218.047502) (xy 351.756137 -218.002116) (xy 351.740813 -217.953817) (xy 351.73306 -217.903742)
			(xy 351.732596 -217.878406) (xy 351.451672 -217.878406) (xy 351.451164 -217.904293) (xy 351.443065 -217.955431)
			(xy 351.427066 -218.004671) (xy 351.40356 -218.050803) (xy 351.373128 -218.09269) (xy 351.336518 -218.1293)
			(xy 351.294631 -218.159732) (xy 351.248499 -218.183238) (xy 351.199259 -218.199237) (xy 351.148121 -218.207336)
			(xy 351.096347 -218.207336) (xy 351.045209 -218.199237) (xy 350.995969 -218.183238) (xy 350.949837 -218.159732)
			(xy 350.90795 -218.1293) (xy 350.87134 -218.09269) (xy 350.840908 -218.050803) (xy 350.817402 -218.004671)
			(xy 350.801403 -217.955431) (xy 350.793304 -217.904293) (xy 350.792796 -217.878406) (xy 350.511872 -217.878406)
			(xy 350.511341 -217.906114) (xy 350.502146 -217.960761) (xy 350.493584 -217.987118) (xy 350.48571 -218.009216)
			(xy 350.690688 -218.364054) (xy 350.713548 -218.368372) (xy 350.738363 -218.373563) (xy 350.786141 -218.390515)
			(xy 350.830759 -218.414584) (xy 350.871165 -218.445202) (xy 350.906406 -218.481645) (xy 350.93565 -218.523056)
			(xy 350.958209 -218.568456) (xy 350.973549 -218.616776) (xy 350.981308 -218.666874) (xy 350.981772 -218.692222)
			(xy 350.981264 -218.718129) (xy 350.973158 -218.769306) (xy 350.957146 -218.818585) (xy 350.933623 -218.864752)
			(xy 350.903167 -218.906671) (xy 350.866529 -218.943309) (xy 350.82461 -218.973765) (xy 350.778443 -218.997288)
			(xy 350.729164 -219.0133) (xy 350.677987 -219.021406) (xy 350.626173 -219.021406) (xy 350.574996 -219.0133)
			(xy 350.525717 -218.997288) (xy 350.47955 -218.973765) (xy 350.437631 -218.943309) (xy 350.400993 -218.906671)
			(xy 350.370537 -218.864752) (xy 350.347014 -218.818585) (xy 350.331002 -218.769306) (xy 350.322896 -218.718129)
			(xy 350.322388 -218.692222) (xy 350.322988 -218.664505) (xy 350.332307 -218.609859) (xy 350.34093 -218.58351)
			(xy 350.348804 -218.561412) (xy 350.143826 -218.206574) (xy 350.120966 -218.202256) (xy 350.096162 -218.197073)
			(xy 350.048424 -218.180081) (xy 350.003849 -218.155985) (xy 349.963484 -218.125353) (xy 349.928282 -218.088906)
			(xy 349.89907 -218.047502) (xy 349.876537 -218.002116) (xy 349.861213 -217.953817) (xy 349.85346 -217.903742)
			(xy 349.852996 -217.878406) (xy 349.572072 -217.878406) (xy 349.571564 -217.904293) (xy 349.563465 -217.955431)
			(xy 349.547466 -218.004671) (xy 349.52396 -218.050803) (xy 349.493528 -218.09269) (xy 349.456918 -218.1293)
			(xy 349.415031 -218.159732) (xy 349.368899 -218.183238) (xy 349.319659 -218.199237) (xy 349.268521 -218.207336)
			(xy 349.216747 -218.207336) (xy 349.165609 -218.199237) (xy 349.116369 -218.183238) (xy 349.070237 -218.159732)
			(xy 349.02835 -218.1293) (xy 348.99174 -218.09269) (xy 348.961308 -218.050803) (xy 348.937802 -218.004671)
			(xy 348.921803 -217.955431) (xy 348.913704 -217.904293) (xy 348.913196 -217.878406) (xy 348.632272 -217.878406)
			(xy 348.631741 -217.906114) (xy 348.622546 -217.960761) (xy 348.613984 -217.987118) (xy 348.60611 -218.009216)
			(xy 348.811088 -218.364054) (xy 348.833948 -218.368372) (xy 348.858763 -218.373563) (xy 348.906541 -218.390515)
			(xy 348.951159 -218.414584) (xy 348.991565 -218.445202) (xy 349.026806 -218.481645) (xy 349.05605 -218.523056)
			(xy 349.078609 -218.568456) (xy 349.093949 -218.616776) (xy 349.101708 -218.666874) (xy 349.102172 -218.692222)
			(xy 349.101664 -218.718129) (xy 349.093558 -218.769306) (xy 349.077546 -218.818585) (xy 349.054023 -218.864752)
			(xy 349.023567 -218.906671) (xy 348.986929 -218.943309) (xy 348.94501 -218.973765) (xy 348.898843 -218.997288)
			(xy 348.849564 -219.0133) (xy 348.798387 -219.021406) (xy 348.746573 -219.021406) (xy 348.695396 -219.0133)
			(xy 348.646117 -218.997288) (xy 348.59995 -218.973765) (xy 348.558031 -218.943309) (xy 348.521393 -218.906671)
			(xy 348.490937 -218.864752) (xy 348.467414 -218.818585) (xy 348.451402 -218.769306) (xy 348.443296 -218.718129)
			(xy 348.442788 -218.692222) (xy 348.443388 -218.664505) (xy 348.452707 -218.609859) (xy 348.46133 -218.58351)
			(xy 348.469204 -218.561412) (xy 348.264226 -218.206574) (xy 348.241366 -218.202256) (xy 348.216562 -218.197073)
			(xy 348.168824 -218.180081) (xy 348.124249 -218.155985) (xy 348.083884 -218.125353) (xy 348.048682 -218.088906)
			(xy 348.01947 -218.047502) (xy 347.996937 -218.002116) (xy 347.981613 -217.953817) (xy 347.97386 -217.903742)
			(xy 347.973396 -217.878406) (xy 347.692472 -217.878406) (xy 347.691964 -217.904293) (xy 347.683865 -217.955431)
			(xy 347.667866 -218.004671) (xy 347.64436 -218.050803) (xy 347.613928 -218.09269) (xy 347.577318 -218.1293)
			(xy 347.535431 -218.159732) (xy 347.489299 -218.183238) (xy 347.440059 -218.199237) (xy 347.388921 -218.207336)
			(xy 347.337147 -218.207336) (xy 347.286009 -218.199237) (xy 347.236769 -218.183238) (xy 347.190637 -218.159732)
			(xy 347.14875 -218.1293) (xy 347.11214 -218.09269) (xy 347.081708 -218.050803) (xy 347.058202 -218.004671)
			(xy 347.042203 -217.955431) (xy 347.034104 -217.904293) (xy 347.033596 -217.878406) (xy 346.752672 -217.878406)
			(xy 346.752141 -217.906114) (xy 346.742946 -217.960761) (xy 346.734384 -217.987118) (xy 346.72651 -218.009216)
			(xy 346.931488 -218.364054) (xy 346.954348 -218.368372) (xy 346.979163 -218.373563) (xy 347.026941 -218.390515)
			(xy 347.071559 -218.414584) (xy 347.111965 -218.445202) (xy 347.147206 -218.481645) (xy 347.17645 -218.523056)
			(xy 347.199009 -218.568456) (xy 347.214349 -218.616776) (xy 347.222108 -218.666874) (xy 347.222572 -218.692222)
			(xy 347.222064 -218.718129) (xy 347.213958 -218.769306) (xy 347.197946 -218.818585) (xy 347.174423 -218.864752)
			(xy 347.143967 -218.906671) (xy 347.107329 -218.943309) (xy 347.06541 -218.973765) (xy 347.019243 -218.997288)
			(xy 346.969964 -219.0133) (xy 346.918787 -219.021406) (xy 346.866973 -219.021406) (xy 346.815796 -219.0133)
			(xy 346.766517 -218.997288) (xy 346.72035 -218.973765) (xy 346.678431 -218.943309) (xy 346.641793 -218.906671)
			(xy 346.611337 -218.864752) (xy 346.587814 -218.818585) (xy 346.571802 -218.769306) (xy 346.563696 -218.718129)
			(xy 346.563188 -218.692222) (xy 346.563788 -218.664505) (xy 346.573107 -218.609859) (xy 346.58173 -218.58351)
			(xy 346.589604 -218.561412) (xy 346.384626 -218.206574) (xy 346.361766 -218.202256) (xy 346.336962 -218.197073)
			(xy 346.289224 -218.180081) (xy 346.244649 -218.155985) (xy 346.204284 -218.125353) (xy 346.169082 -218.088906)
			(xy 346.13987 -218.047502) (xy 346.117337 -218.002116) (xy 346.102013 -217.953817) (xy 346.09426 -217.903742)
			(xy 346.093796 -217.878406) (xy 345.812872 -217.878406) (xy 345.812364 -217.904293) (xy 345.804265 -217.955431)
			(xy 345.788266 -218.004671) (xy 345.76476 -218.050803) (xy 345.734328 -218.09269) (xy 345.697718 -218.1293)
			(xy 345.655831 -218.159732) (xy 345.609699 -218.183238) (xy 345.560459 -218.199237) (xy 345.509321 -218.207336)
			(xy 345.457547 -218.207336) (xy 345.406409 -218.199237) (xy 345.357169 -218.183238) (xy 345.311037 -218.159732)
			(xy 345.26915 -218.1293) (xy 345.23254 -218.09269) (xy 345.202108 -218.050803) (xy 345.178602 -218.004671)
			(xy 345.162603 -217.955431) (xy 345.154504 -217.904293) (xy 345.153996 -217.878406) (xy 344.873072 -217.878406)
			(xy 344.872541 -217.906114) (xy 344.863346 -217.960761) (xy 344.854784 -217.987118) (xy 344.84691 -218.009216)
			(xy 345.051888 -218.364054) (xy 345.074748 -218.368372) (xy 345.099563 -218.373563) (xy 345.147341 -218.390515)
			(xy 345.191959 -218.414584) (xy 345.232365 -218.445202) (xy 345.267606 -218.481645) (xy 345.29685 -218.523056)
			(xy 345.319409 -218.568456) (xy 345.334749 -218.616776) (xy 345.342508 -218.666874) (xy 345.342972 -218.692222)
			(xy 345.342464 -218.718129) (xy 345.334358 -218.769306) (xy 345.318346 -218.818585) (xy 345.294823 -218.864752)
			(xy 345.264367 -218.906671) (xy 345.227729 -218.943309) (xy 345.18581 -218.973765) (xy 345.139643 -218.997288)
			(xy 345.090364 -219.0133) (xy 345.039187 -219.021406) (xy 344.987373 -219.021406) (xy 344.936196 -219.0133)
			(xy 344.886917 -218.997288) (xy 344.84075 -218.973765) (xy 344.798831 -218.943309) (xy 344.762193 -218.906671)
			(xy 344.731737 -218.864752) (xy 344.708214 -218.818585) (xy 344.692202 -218.769306) (xy 344.684096 -218.718129)
			(xy 344.683588 -218.692222) (xy 344.684188 -218.664505) (xy 344.693507 -218.609859) (xy 344.70213 -218.58351)
			(xy 344.710004 -218.561412) (xy 344.505026 -218.206574) (xy 344.482166 -218.202256) (xy 344.457362 -218.197073)
			(xy 344.409624 -218.180081) (xy 344.365049 -218.155985) (xy 344.324684 -218.125353) (xy 344.289482 -218.088906)
			(xy 344.26027 -218.047502) (xy 344.237737 -218.002116) (xy 344.222413 -217.953817) (xy 344.21466 -217.903742)
			(xy 344.214196 -217.878406) (xy 343.933272 -217.878406) (xy 343.932764 -217.904293) (xy 343.924665 -217.955431)
			(xy 343.908666 -218.004671) (xy 343.88516 -218.050803) (xy 343.854728 -218.09269) (xy 343.818118 -218.1293)
			(xy 343.776231 -218.159732) (xy 343.730099 -218.183238) (xy 343.680859 -218.199237) (xy 343.629721 -218.207336)
			(xy 343.577947 -218.207336) (xy 343.526809 -218.199237) (xy 343.477569 -218.183238) (xy 343.431437 -218.159732)
			(xy 343.38955 -218.1293) (xy 343.35294 -218.09269) (xy 343.322508 -218.050803) (xy 343.299002 -218.004671)
			(xy 343.283003 -217.955431) (xy 343.274904 -217.904293) (xy 343.274396 -217.878406) (xy 342.993472 -217.878406)
			(xy 342.992941 -217.906114) (xy 342.983746 -217.960761) (xy 342.975184 -217.987118) (xy 342.96731 -218.009216)
			(xy 343.172288 -218.364054) (xy 343.195148 -218.368372) (xy 343.219963 -218.373563) (xy 343.267741 -218.390515)
			(xy 343.312359 -218.414584) (xy 343.352765 -218.445202) (xy 343.388006 -218.481645) (xy 343.41725 -218.523056)
			(xy 343.439809 -218.568456) (xy 343.455149 -218.616776) (xy 343.462908 -218.666874) (xy 343.463372 -218.692222)
			(xy 343.462864 -218.718129) (xy 343.454758 -218.769306) (xy 343.438746 -218.818585) (xy 343.415223 -218.864752)
			(xy 343.384767 -218.906671) (xy 343.348129 -218.943309) (xy 343.30621 -218.973765) (xy 343.260043 -218.997288)
			(xy 343.210764 -219.0133) (xy 343.159587 -219.021406) (xy 343.107773 -219.021406) (xy 343.056596 -219.0133)
			(xy 343.007317 -218.997288) (xy 342.96115 -218.973765) (xy 342.919231 -218.943309) (xy 342.882593 -218.906671)
			(xy 342.852137 -218.864752) (xy 342.828614 -218.818585) (xy 342.812602 -218.769306) (xy 342.804496 -218.718129)
			(xy 342.803988 -218.692222) (xy 342.804588 -218.664505) (xy 342.813907 -218.609859) (xy 342.82253 -218.58351)
			(xy 342.830404 -218.561412) (xy 342.625426 -218.206574) (xy 342.602566 -218.202256) (xy 342.577762 -218.197073)
			(xy 342.530024 -218.180081) (xy 342.485449 -218.155985) (xy 342.445084 -218.125353) (xy 342.409882 -218.088906)
			(xy 342.38067 -218.047502) (xy 342.358137 -218.002116) (xy 342.342813 -217.953817) (xy 342.33506 -217.903742)
			(xy 342.334596 -217.878406) (xy 342.053672 -217.878406) (xy 342.053164 -217.904293) (xy 342.045065 -217.955431)
			(xy 342.029066 -218.004671) (xy 342.00556 -218.050803) (xy 341.975128 -218.09269) (xy 341.938518 -218.1293)
			(xy 341.896631 -218.159732) (xy 341.850499 -218.183238) (xy 341.801259 -218.199237) (xy 341.750121 -218.207336)
			(xy 341.698347 -218.207336) (xy 341.647209 -218.199237) (xy 341.597969 -218.183238) (xy 341.551837 -218.159732)
			(xy 341.50995 -218.1293) (xy 341.47334 -218.09269) (xy 341.442908 -218.050803) (xy 341.419402 -218.004671)
			(xy 341.403403 -217.955431) (xy 341.395304 -217.904293) (xy 341.394796 -217.878406) (xy 341.113872 -217.878406)
			(xy 341.113341 -217.906114) (xy 341.104146 -217.960761) (xy 341.095584 -217.987118) (xy 341.08771 -218.009216)
			(xy 341.292688 -218.364054) (xy 341.315548 -218.368372) (xy 341.340363 -218.373563) (xy 341.388141 -218.390515)
			(xy 341.432759 -218.414584) (xy 341.473165 -218.445202) (xy 341.508406 -218.481645) (xy 341.53765 -218.523056)
			(xy 341.560209 -218.568456) (xy 341.575549 -218.616776) (xy 341.583308 -218.666874) (xy 341.583772 -218.692222)
			(xy 341.583264 -218.718129) (xy 341.575158 -218.769306) (xy 341.559146 -218.818585) (xy 341.535623 -218.864752)
			(xy 341.505167 -218.906671) (xy 341.468529 -218.943309) (xy 341.42661 -218.973765) (xy 341.380443 -218.997288)
			(xy 341.331164 -219.0133) (xy 341.279987 -219.021406) (xy 341.228173 -219.021406) (xy 341.176996 -219.0133)
			(xy 341.127717 -218.997288) (xy 341.08155 -218.973765) (xy 341.039631 -218.943309) (xy 341.002993 -218.906671)
			(xy 340.972537 -218.864752) (xy 340.949014 -218.818585) (xy 340.933002 -218.769306) (xy 340.924896 -218.718129)
			(xy 340.924388 -218.692222) (xy 340.924988 -218.664505) (xy 340.934307 -218.609859) (xy 340.94293 -218.58351)
			(xy 340.950804 -218.561412) (xy 340.745826 -218.206574) (xy 340.722966 -218.202256) (xy 340.698162 -218.197073)
			(xy 340.650424 -218.180081) (xy 340.605849 -218.155985) (xy 340.565484 -218.125353) (xy 340.530282 -218.088906)
			(xy 340.50107 -218.047502) (xy 340.478537 -218.002116) (xy 340.463213 -217.953817) (xy 340.45546 -217.903742)
			(xy 340.454996 -217.878406) (xy 340.174072 -217.878406) (xy 340.173564 -217.904293) (xy 340.165465 -217.955431)
			(xy 340.149466 -218.004671) (xy 340.12596 -218.050803) (xy 340.095528 -218.09269) (xy 340.058918 -218.1293)
			(xy 340.017031 -218.159732) (xy 339.970899 -218.183238) (xy 339.921659 -218.199237) (xy 339.870521 -218.207336)
			(xy 339.818747 -218.207336) (xy 339.767609 -218.199237) (xy 339.718369 -218.183238) (xy 339.672237 -218.159732)
			(xy 339.63035 -218.1293) (xy 339.59374 -218.09269) (xy 339.563308 -218.050803) (xy 339.539802 -218.004671)
			(xy 339.523803 -217.955431) (xy 339.515704 -217.904293) (xy 339.515196 -217.878406) (xy 339.234272 -217.878406)
			(xy 339.233741 -217.906114) (xy 339.224546 -217.960761) (xy 339.215984 -217.987118) (xy 339.20811 -218.009216)
			(xy 339.413088 -218.364054) (xy 339.435948 -218.368372) (xy 339.460763 -218.373563) (xy 339.508541 -218.390515)
			(xy 339.553159 -218.414584) (xy 339.593565 -218.445202) (xy 339.628806 -218.481645) (xy 339.65805 -218.523056)
			(xy 339.680609 -218.568456) (xy 339.695949 -218.616776) (xy 339.703708 -218.666874) (xy 339.704172 -218.692222)
			(xy 339.703664 -218.718129) (xy 339.695558 -218.769306) (xy 339.679546 -218.818585) (xy 339.656023 -218.864752)
			(xy 339.625567 -218.906671) (xy 339.588929 -218.943309) (xy 339.54701 -218.973765) (xy 339.500843 -218.997288)
			(xy 339.451564 -219.0133) (xy 339.400387 -219.021406) (xy 339.348573 -219.021406) (xy 339.297396 -219.0133)
			(xy 339.248117 -218.997288) (xy 339.20195 -218.973765) (xy 339.160031 -218.943309) (xy 339.123393 -218.906671)
			(xy 339.092937 -218.864752) (xy 339.069414 -218.818585) (xy 339.053402 -218.769306) (xy 339.045296 -218.718129)
			(xy 339.044788 -218.692222) (xy 339.045388 -218.664505) (xy 339.054707 -218.609859) (xy 339.06333 -218.58351)
			(xy 339.071204 -218.561412) (xy 338.866226 -218.206574) (xy 338.843366 -218.202256) (xy 338.818562 -218.197073)
			(xy 338.770824 -218.180081) (xy 338.726249 -218.155985) (xy 338.685884 -218.125353) (xy 338.650682 -218.088906)
			(xy 338.62147 -218.047502) (xy 338.598937 -218.002116) (xy 338.583613 -217.953817) (xy 338.57586 -217.903742)
			(xy 338.575396 -217.878406) (xy 338.294472 -217.878406) (xy 338.293964 -217.904293) (xy 338.285865 -217.955431)
			(xy 338.269866 -218.004671) (xy 338.24636 -218.050803) (xy 338.215928 -218.09269) (xy 338.179318 -218.1293)
			(xy 338.137431 -218.159732) (xy 338.091299 -218.183238) (xy 338.042059 -218.199237) (xy 337.990921 -218.207336)
			(xy 337.939147 -218.207336) (xy 337.888009 -218.199237) (xy 337.838769 -218.183238) (xy 337.792637 -218.159732)
			(xy 337.75075 -218.1293) (xy 337.71414 -218.09269) (xy 337.683708 -218.050803) (xy 337.660202 -218.004671)
			(xy 337.644203 -217.955431) (xy 337.636104 -217.904293) (xy 337.635596 -217.878406) (xy 337.354672 -217.878406)
			(xy 337.354141 -217.906114) (xy 337.344946 -217.960761) (xy 337.336384 -217.987118) (xy 337.32851 -218.009216)
			(xy 337.533488 -218.364054) (xy 337.556348 -218.368372) (xy 337.581163 -218.373563) (xy 337.628941 -218.390515)
			(xy 337.673559 -218.414584) (xy 337.713965 -218.445202) (xy 337.749206 -218.481645) (xy 337.77845 -218.523056)
			(xy 337.801009 -218.568456) (xy 337.816349 -218.616776) (xy 337.824108 -218.666874) (xy 337.824572 -218.692222)
			(xy 337.824064 -218.718129) (xy 337.815958 -218.769306) (xy 337.799946 -218.818585) (xy 337.776423 -218.864752)
			(xy 337.745967 -218.906671) (xy 337.709329 -218.943309) (xy 337.66741 -218.973765) (xy 337.621243 -218.997288)
			(xy 337.571964 -219.0133) (xy 337.520787 -219.021406) (xy 337.468973 -219.021406) (xy 337.417796 -219.0133)
			(xy 337.368517 -218.997288) (xy 337.32235 -218.973765) (xy 337.280431 -218.943309) (xy 337.243793 -218.906671)
			(xy 337.213337 -218.864752) (xy 337.189814 -218.818585) (xy 337.173802 -218.769306) (xy 337.165696 -218.718129)
			(xy 337.165188 -218.692222) (xy 337.165788 -218.664505) (xy 337.175107 -218.609859) (xy 337.18373 -218.58351)
			(xy 337.191604 -218.561412) (xy 336.986626 -218.206574) (xy 336.963766 -218.202256) (xy 336.938962 -218.197073)
			(xy 336.891224 -218.180081) (xy 336.846649 -218.155985) (xy 336.806284 -218.125353) (xy 336.771082 -218.088906)
			(xy 336.74187 -218.047502) (xy 336.719337 -218.002116) (xy 336.704013 -217.953817) (xy 336.69626 -217.903742)
			(xy 336.695796 -217.878406) (xy 134.525004 -217.878406) (xy 134.524496 -217.904293) (xy 134.516397 -217.955431)
			(xy 134.500398 -218.004671) (xy 134.476892 -218.050803) (xy 134.44646 -218.09269) (xy 134.40985 -218.1293)
			(xy 134.367963 -218.159732) (xy 134.321831 -218.183238) (xy 134.272591 -218.199237) (xy 134.221453 -218.207336)
			(xy 134.169679 -218.207336) (xy 134.118541 -218.199237) (xy 134.069301 -218.183238) (xy 134.023169 -218.159732)
			(xy 133.981282 -218.1293) (xy 133.944672 -218.09269) (xy 133.91424 -218.050803) (xy 133.890734 -218.004671)
			(xy 133.874735 -217.955431) (xy 133.866636 -217.904293) (xy 133.866128 -217.878406) (xy 133.866662 -217.850698)
			(xy 133.875855 -217.796051) (xy 133.884416 -217.769694) (xy 133.89229 -217.747596) (xy 133.687312 -217.392504)
			(xy 133.664452 -217.388186) (xy 133.639596 -217.383069) (xy 133.591748 -217.366166) (xy 133.547056 -217.342128)
			(xy 133.506577 -217.311523) (xy 133.471267 -217.275076) (xy 133.441961 -217.233647) (xy 133.419352 -217.188215)
			(xy 133.403974 -217.139855) (xy 133.39619 -217.089709) (xy 133.39572 -217.064336) (xy 132.175504 -217.064336)
			(xy 132.174889 -217.091989) (xy 132.165569 -217.146507) (xy 132.156962 -217.172794) (xy 132.149342 -217.194892)
			(xy 132.354574 -217.550238) (xy 132.377434 -217.554556) (xy 132.402241 -217.559728) (xy 132.449979 -217.576721)
			(xy 132.494556 -217.600818) (xy 132.53492 -217.631451) (xy 132.570123 -217.6679) (xy 132.599334 -217.709305)
			(xy 132.621866 -217.754693) (xy 132.637189 -217.802993) (xy 132.644941 -217.85307) (xy 132.645404 -217.878406)
			(xy 132.644896 -217.904293) (xy 132.636797 -217.955431) (xy 132.620798 -218.004671) (xy 132.597292 -218.050803)
			(xy 132.56686 -218.09269) (xy 132.53025 -218.1293) (xy 132.488363 -218.159732) (xy 132.442231 -218.183238)
			(xy 132.392991 -218.199237) (xy 132.341853 -218.207336) (xy 132.290079 -218.207336) (xy 132.238941 -218.199237)
			(xy 132.189701 -218.183238) (xy 132.143569 -218.159732) (xy 132.101682 -218.1293) (xy 132.065072 -218.09269)
			(xy 132.03464 -218.050803) (xy 132.011134 -218.004671) (xy 131.995135 -217.955431) (xy 131.987036 -217.904293)
			(xy 131.986528 -217.878406) (xy 131.987062 -217.850698) (xy 131.996255 -217.796051) (xy 132.004816 -217.769694)
			(xy 132.01269 -217.747596) (xy 131.807712 -217.392504) (xy 131.784852 -217.388186) (xy 131.759996 -217.383069)
			(xy 131.712148 -217.366166) (xy 131.667456 -217.342128) (xy 131.626977 -217.311523) (xy 131.591667 -217.275076)
			(xy 131.562361 -217.233647) (xy 131.539752 -217.188215) (xy 131.524374 -217.139855) (xy 131.51659 -217.089709)
			(xy 131.51612 -217.064336) (xy 130.295904 -217.064336) (xy 130.295289 -217.091989) (xy 130.285969 -217.146507)
			(xy 130.277362 -217.172794) (xy 130.269742 -217.194892) (xy 130.474974 -217.550238) (xy 130.497834 -217.554556)
			(xy 130.522641 -217.559728) (xy 130.570379 -217.576721) (xy 130.614956 -217.600818) (xy 130.65532 -217.631451)
			(xy 130.690523 -217.6679) (xy 130.719734 -217.709305) (xy 130.742266 -217.754693) (xy 130.757589 -217.802993)
			(xy 130.765341 -217.85307) (xy 130.765804 -217.878406) (xy 130.765296 -217.904293) (xy 130.757197 -217.955431)
			(xy 130.741198 -218.004671) (xy 130.717692 -218.050803) (xy 130.68726 -218.09269) (xy 130.65065 -218.1293)
			(xy 130.608763 -218.159732) (xy 130.562631 -218.183238) (xy 130.513391 -218.199237) (xy 130.462253 -218.207336)
			(xy 130.410479 -218.207336) (xy 130.359341 -218.199237) (xy 130.310101 -218.183238) (xy 130.263969 -218.159732)
			(xy 130.222082 -218.1293) (xy 130.185472 -218.09269) (xy 130.15504 -218.050803) (xy 130.131534 -218.004671)
			(xy 130.115535 -217.955431) (xy 130.107436 -217.904293) (xy 130.106928 -217.878406) (xy 130.107462 -217.850698)
			(xy 130.116655 -217.796051) (xy 130.125216 -217.769694) (xy 130.13309 -217.747596) (xy 129.928112 -217.392504)
			(xy 129.905252 -217.388186) (xy 129.880396 -217.383069) (xy 129.832548 -217.366166) (xy 129.787856 -217.342128)
			(xy 129.747377 -217.311523) (xy 129.712067 -217.275076) (xy 129.682761 -217.233647) (xy 129.660152 -217.188215)
			(xy 129.644774 -217.139855) (xy 129.63699 -217.089709) (xy 129.63652 -217.064336) (xy 128.416304 -217.064336)
			(xy 128.415689 -217.091989) (xy 128.406369 -217.146507) (xy 128.397762 -217.172794) (xy 128.390142 -217.194892)
			(xy 128.595374 -217.550238) (xy 128.618234 -217.554556) (xy 128.643041 -217.559728) (xy 128.690779 -217.576721)
			(xy 128.735356 -217.600818) (xy 128.77572 -217.631451) (xy 128.810923 -217.6679) (xy 128.840134 -217.709305)
			(xy 128.862666 -217.754693) (xy 128.877989 -217.802993) (xy 128.885741 -217.85307) (xy 128.886204 -217.878406)
			(xy 128.885696 -217.904293) (xy 128.877597 -217.955431) (xy 128.861598 -218.004671) (xy 128.838092 -218.050803)
			(xy 128.80766 -218.09269) (xy 128.77105 -218.1293) (xy 128.729163 -218.159732) (xy 128.683031 -218.183238)
			(xy 128.633791 -218.199237) (xy 128.582653 -218.207336) (xy 128.530879 -218.207336) (xy 128.479741 -218.199237)
			(xy 128.430501 -218.183238) (xy 128.384369 -218.159732) (xy 128.342482 -218.1293) (xy 128.305872 -218.09269)
			(xy 128.27544 -218.050803) (xy 128.251934 -218.004671) (xy 128.235935 -217.955431) (xy 128.227836 -217.904293)
			(xy 128.227328 -217.878406) (xy 128.227862 -217.850698) (xy 128.237055 -217.796051) (xy 128.245616 -217.769694)
			(xy 128.25349 -217.747596) (xy 128.048512 -217.392504) (xy 128.025652 -217.388186) (xy 128.000796 -217.383069)
			(xy 127.952948 -217.366166) (xy 127.908256 -217.342128) (xy 127.867777 -217.311523) (xy 127.832467 -217.275076)
			(xy 127.803161 -217.233647) (xy 127.780552 -217.188215) (xy 127.765174 -217.139855) (xy 127.75739 -217.089709)
			(xy 127.75692 -217.064336) (xy 126.536704 -217.064336) (xy 126.536089 -217.091989) (xy 126.526769 -217.146507)
			(xy 126.518162 -217.172794) (xy 126.510542 -217.194892) (xy 126.715774 -217.550238) (xy 126.738634 -217.554556)
			(xy 126.763441 -217.559728) (xy 126.811179 -217.576721) (xy 126.855756 -217.600818) (xy 126.89612 -217.631451)
			(xy 126.931323 -217.6679) (xy 126.960534 -217.709305) (xy 126.983066 -217.754693) (xy 126.998389 -217.802993)
			(xy 127.006141 -217.85307) (xy 127.006604 -217.878406) (xy 127.006096 -217.904293) (xy 126.997997 -217.955431)
			(xy 126.981998 -218.004671) (xy 126.958492 -218.050803) (xy 126.92806 -218.09269) (xy 126.89145 -218.1293)
			(xy 126.849563 -218.159732) (xy 126.803431 -218.183238) (xy 126.754191 -218.199237) (xy 126.703053 -218.207336)
			(xy 126.651279 -218.207336) (xy 126.600141 -218.199237) (xy 126.550901 -218.183238) (xy 126.504769 -218.159732)
			(xy 126.462882 -218.1293) (xy 126.426272 -218.09269) (xy 126.39584 -218.050803) (xy 126.372334 -218.004671)
			(xy 126.356335 -217.955431) (xy 126.348236 -217.904293) (xy 126.347728 -217.878406) (xy 126.348262 -217.850698)
			(xy 126.357455 -217.796051) (xy 126.366016 -217.769694) (xy 126.37389 -217.747596) (xy 126.168912 -217.392504)
			(xy 126.146052 -217.388186) (xy 126.121196 -217.383069) (xy 126.073348 -217.366166) (xy 126.028656 -217.342128)
			(xy 125.988177 -217.311523) (xy 125.952867 -217.275076) (xy 125.923561 -217.233647) (xy 125.900952 -217.188215)
			(xy 125.885574 -217.139855) (xy 125.87779 -217.089709) (xy 125.87732 -217.064336) (xy 124.657104 -217.064336)
			(xy 124.656489 -217.091989) (xy 124.647169 -217.146507) (xy 124.638562 -217.172794) (xy 124.630942 -217.194892)
			(xy 124.836174 -217.550238) (xy 124.859034 -217.554556) (xy 124.883841 -217.559728) (xy 124.931579 -217.576721)
			(xy 124.976156 -217.600818) (xy 125.01652 -217.631451) (xy 125.051723 -217.6679) (xy 125.080934 -217.709305)
			(xy 125.103466 -217.754693) (xy 125.118789 -217.802993) (xy 125.126541 -217.85307) (xy 125.127004 -217.878406)
			(xy 125.126496 -217.904293) (xy 125.118397 -217.955431) (xy 125.102398 -218.004671) (xy 125.078892 -218.050803)
			(xy 125.04846 -218.09269) (xy 125.01185 -218.1293) (xy 124.969963 -218.159732) (xy 124.923831 -218.183238)
			(xy 124.874591 -218.199237) (xy 124.823453 -218.207336) (xy 124.771679 -218.207336) (xy 124.720541 -218.199237)
			(xy 124.671301 -218.183238) (xy 124.625169 -218.159732) (xy 124.583282 -218.1293) (xy 124.546672 -218.09269)
			(xy 124.51624 -218.050803) (xy 124.492734 -218.004671) (xy 124.476735 -217.955431) (xy 124.468636 -217.904293)
			(xy 124.468128 -217.878406) (xy 124.468662 -217.850698) (xy 124.477855 -217.796051) (xy 124.486416 -217.769694)
			(xy 124.49429 -217.747596) (xy 124.289312 -217.392504) (xy 124.266452 -217.388186) (xy 124.241596 -217.383069)
			(xy 124.193748 -217.366166) (xy 124.149056 -217.342128) (xy 124.108577 -217.311523) (xy 124.073267 -217.275076)
			(xy 124.043961 -217.233647) (xy 124.021352 -217.188215) (xy 124.005974 -217.139855) (xy 123.99819 -217.089709)
			(xy 123.99772 -217.064336) (xy 122.777504 -217.064336) (xy 122.776889 -217.091989) (xy 122.767569 -217.146507)
			(xy 122.758962 -217.172794) (xy 122.751342 -217.194892) (xy 122.956574 -217.550238) (xy 122.979434 -217.554556)
			(xy 123.004241 -217.559728) (xy 123.051979 -217.576721) (xy 123.096556 -217.600818) (xy 123.13692 -217.631451)
			(xy 123.172123 -217.6679) (xy 123.201334 -217.709305) (xy 123.223866 -217.754693) (xy 123.239189 -217.802993)
			(xy 123.246941 -217.85307) (xy 123.247404 -217.878406) (xy 123.246896 -217.904293) (xy 123.238797 -217.955431)
			(xy 123.222798 -218.004671) (xy 123.199292 -218.050803) (xy 123.16886 -218.09269) (xy 123.13225 -218.1293)
			(xy 123.090363 -218.159732) (xy 123.044231 -218.183238) (xy 122.994991 -218.199237) (xy 122.943853 -218.207336)
			(xy 122.892079 -218.207336) (xy 122.840941 -218.199237) (xy 122.791701 -218.183238) (xy 122.745569 -218.159732)
			(xy 122.703682 -218.1293) (xy 122.667072 -218.09269) (xy 122.63664 -218.050803) (xy 122.613134 -218.004671)
			(xy 122.597135 -217.955431) (xy 122.589036 -217.904293) (xy 122.588528 -217.878406) (xy 122.589062 -217.850698)
			(xy 122.598255 -217.796051) (xy 122.606816 -217.769694) (xy 122.61469 -217.747596) (xy 122.409712 -217.392504)
			(xy 122.386852 -217.388186) (xy 122.361996 -217.383069) (xy 122.314148 -217.366166) (xy 122.269456 -217.342128)
			(xy 122.228977 -217.311523) (xy 122.193667 -217.275076) (xy 122.164361 -217.233647) (xy 122.141752 -217.188215)
			(xy 122.126374 -217.139855) (xy 122.11859 -217.089709) (xy 122.11812 -217.064336) (xy 120.897904 -217.064336)
			(xy 120.897289 -217.091989) (xy 120.887969 -217.146507) (xy 120.879362 -217.172794) (xy 120.871742 -217.194892)
			(xy 121.076974 -217.550238) (xy 121.099834 -217.554556) (xy 121.124641 -217.559728) (xy 121.172379 -217.576721)
			(xy 121.216956 -217.600818) (xy 121.25732 -217.631451) (xy 121.292523 -217.6679) (xy 121.321734 -217.709305)
			(xy 121.344266 -217.754693) (xy 121.359589 -217.802993) (xy 121.367341 -217.85307) (xy 121.367804 -217.878406)
			(xy 121.367296 -217.904293) (xy 121.359197 -217.955431) (xy 121.343198 -218.004671) (xy 121.319692 -218.050803)
			(xy 121.28926 -218.09269) (xy 121.25265 -218.1293) (xy 121.210763 -218.159732) (xy 121.164631 -218.183238)
			(xy 121.115391 -218.199237) (xy 121.064253 -218.207336) (xy 121.012479 -218.207336) (xy 120.961341 -218.199237)
			(xy 120.912101 -218.183238) (xy 120.865969 -218.159732) (xy 120.824082 -218.1293) (xy 120.787472 -218.09269)
			(xy 120.75704 -218.050803) (xy 120.733534 -218.004671) (xy 120.717535 -217.955431) (xy 120.709436 -217.904293)
			(xy 120.708928 -217.878406) (xy 120.709462 -217.850698) (xy 120.718655 -217.796051) (xy 120.727216 -217.769694)
			(xy 120.73509 -217.747596) (xy 120.530112 -217.392504) (xy 120.507252 -217.388186) (xy 120.482396 -217.383069)
			(xy 120.434548 -217.366166) (xy 120.389856 -217.342128) (xy 120.349377 -217.311523) (xy 120.314067 -217.275076)
			(xy 120.284761 -217.233647) (xy 120.262152 -217.188215) (xy 120.246774 -217.139855) (xy 120.23899 -217.089709)
			(xy 120.23852 -217.064336) (xy 119.018304 -217.064336) (xy 119.017689 -217.091989) (xy 119.008369 -217.146507)
			(xy 118.999762 -217.172794) (xy 118.992142 -217.194892) (xy 119.197374 -217.550238) (xy 119.220234 -217.554556)
			(xy 119.245041 -217.559728) (xy 119.292779 -217.576721) (xy 119.337356 -217.600818) (xy 119.37772 -217.631451)
			(xy 119.412923 -217.6679) (xy 119.442134 -217.709305) (xy 119.464666 -217.754693) (xy 119.479989 -217.802993)
			(xy 119.487741 -217.85307) (xy 119.488204 -217.878406) (xy 119.487696 -217.904293) (xy 119.479597 -217.955431)
			(xy 119.463598 -218.004671) (xy 119.440092 -218.050803) (xy 119.40966 -218.09269) (xy 119.37305 -218.1293)
			(xy 119.331163 -218.159732) (xy 119.285031 -218.183238) (xy 119.235791 -218.199237) (xy 119.184653 -218.207336)
			(xy 119.132879 -218.207336) (xy 119.081741 -218.199237) (xy 119.032501 -218.183238) (xy 118.986369 -218.159732)
			(xy 118.944482 -218.1293) (xy 118.907872 -218.09269) (xy 118.87744 -218.050803) (xy 118.853934 -218.004671)
			(xy 118.837935 -217.955431) (xy 118.829836 -217.904293) (xy 118.829328 -217.878406) (xy 118.829862 -217.850698)
			(xy 118.839055 -217.796051) (xy 118.847616 -217.769694) (xy 118.85549 -217.747596) (xy 118.650512 -217.392504)
			(xy 118.627652 -217.388186) (xy 118.602796 -217.383069) (xy 118.554948 -217.366166) (xy 118.510256 -217.342128)
			(xy 118.469777 -217.311523) (xy 118.434467 -217.275076) (xy 118.405161 -217.233647) (xy 118.382552 -217.188215)
			(xy 118.367174 -217.139855) (xy 118.35939 -217.089709) (xy 118.35892 -217.064336) (xy 117.138704 -217.064336)
			(xy 117.138089 -217.091989) (xy 117.128769 -217.146507) (xy 117.120162 -217.172794) (xy 117.112542 -217.194892)
			(xy 117.317774 -217.550238) (xy 117.340634 -217.554556) (xy 117.365441 -217.559728) (xy 117.413179 -217.576721)
			(xy 117.457756 -217.600818) (xy 117.49812 -217.631451) (xy 117.533323 -217.6679) (xy 117.562534 -217.709305)
			(xy 117.585066 -217.754693) (xy 117.600389 -217.802993) (xy 117.608141 -217.85307) (xy 117.608604 -217.878406)
			(xy 117.608096 -217.904293) (xy 117.599997 -217.955431) (xy 117.583998 -218.004671) (xy 117.560492 -218.050803)
			(xy 117.53006 -218.09269) (xy 117.49345 -218.1293) (xy 117.451563 -218.159732) (xy 117.405431 -218.183238)
			(xy 117.356191 -218.199237) (xy 117.305053 -218.207336) (xy 117.253279 -218.207336) (xy 117.202141 -218.199237)
			(xy 117.152901 -218.183238) (xy 117.106769 -218.159732) (xy 117.064882 -218.1293) (xy 117.028272 -218.09269)
			(xy 116.99784 -218.050803) (xy 116.974334 -218.004671) (xy 116.958335 -217.955431) (xy 116.950236 -217.904293)
			(xy 116.949728 -217.878406) (xy 116.950262 -217.850698) (xy 116.959455 -217.796051) (xy 116.968016 -217.769694)
			(xy 116.97589 -217.747596) (xy 116.770912 -217.392504) (xy 116.748052 -217.388186) (xy 116.723196 -217.383069)
			(xy 116.675348 -217.366166) (xy 116.630656 -217.342128) (xy 116.590177 -217.311523) (xy 116.554867 -217.275076)
			(xy 116.525561 -217.233647) (xy 116.502952 -217.188215) (xy 116.487574 -217.139855) (xy 116.47979 -217.089709)
			(xy 116.47932 -217.064336) (xy 115.259104 -217.064336) (xy 115.258489 -217.091989) (xy 115.249169 -217.146507)
			(xy 115.240562 -217.172794) (xy 115.232942 -217.194892) (xy 115.438174 -217.550238) (xy 115.461034 -217.554556)
			(xy 115.485841 -217.559728) (xy 115.533579 -217.576721) (xy 115.578156 -217.600818) (xy 115.61852 -217.631451)
			(xy 115.653723 -217.6679) (xy 115.682934 -217.709305) (xy 115.705466 -217.754693) (xy 115.720789 -217.802993)
			(xy 115.728541 -217.85307) (xy 115.729004 -217.878406) (xy 115.728496 -217.904293) (xy 115.720397 -217.955431)
			(xy 115.704398 -218.004671) (xy 115.680892 -218.050803) (xy 115.65046 -218.09269) (xy 115.61385 -218.1293)
			(xy 115.571963 -218.159732) (xy 115.525831 -218.183238) (xy 115.476591 -218.199237) (xy 115.425453 -218.207336)
			(xy 115.373679 -218.207336) (xy 115.322541 -218.199237) (xy 115.273301 -218.183238) (xy 115.227169 -218.159732)
			(xy 115.185282 -218.1293) (xy 115.148672 -218.09269) (xy 115.11824 -218.050803) (xy 115.094734 -218.004671)
			(xy 115.078735 -217.955431) (xy 115.070636 -217.904293) (xy 115.070128 -217.878406) (xy 115.070662 -217.850698)
			(xy 115.079855 -217.796051) (xy 115.088416 -217.769694) (xy 115.09629 -217.747596) (xy 114.891312 -217.392504)
			(xy 114.868452 -217.388186) (xy 114.843596 -217.383069) (xy 114.795748 -217.366166) (xy 114.751056 -217.342128)
			(xy 114.710577 -217.311523) (xy 114.675267 -217.275076) (xy 114.645961 -217.233647) (xy 114.623352 -217.188215)
			(xy 114.607974 -217.139855) (xy 114.60019 -217.089709) (xy 114.59972 -217.064336) (xy 113.379504 -217.064336)
			(xy 113.378889 -217.091989) (xy 113.369569 -217.146507) (xy 113.360962 -217.172794) (xy 113.353342 -217.194892)
			(xy 113.558574 -217.550238) (xy 113.581434 -217.554556) (xy 113.606241 -217.559728) (xy 113.653979 -217.576721)
			(xy 113.698556 -217.600818) (xy 113.73892 -217.631451) (xy 113.774123 -217.6679) (xy 113.803334 -217.709305)
			(xy 113.825866 -217.754693) (xy 113.841189 -217.802993) (xy 113.848941 -217.85307) (xy 113.849404 -217.878406)
			(xy 113.848896 -217.904293) (xy 113.840797 -217.955431) (xy 113.824798 -218.004671) (xy 113.801292 -218.050803)
			(xy 113.77086 -218.09269) (xy 113.73425 -218.1293) (xy 113.692363 -218.159732) (xy 113.646231 -218.183238)
			(xy 113.596991 -218.199237) (xy 113.545853 -218.207336) (xy 113.494079 -218.207336) (xy 113.442941 -218.199237)
			(xy 113.393701 -218.183238) (xy 113.347569 -218.159732) (xy 113.305682 -218.1293) (xy 113.269072 -218.09269)
			(xy 113.23864 -218.050803) (xy 113.215134 -218.004671) (xy 113.199135 -217.955431) (xy 113.191036 -217.904293)
			(xy 113.190528 -217.878406) (xy 113.191062 -217.850698) (xy 113.200255 -217.796051) (xy 113.208816 -217.769694)
			(xy 113.21669 -217.747596) (xy 113.011712 -217.392504) (xy 112.988852 -217.388186) (xy 112.963996 -217.383069)
			(xy 112.916148 -217.366166) (xy 112.871456 -217.342128) (xy 112.830977 -217.311523) (xy 112.795667 -217.275076)
			(xy 112.766361 -217.233647) (xy 112.743752 -217.188215) (xy 112.728374 -217.139855) (xy 112.72059 -217.089709)
			(xy 112.72012 -217.064336) (xy 111.499904 -217.064336) (xy 111.499412 -217.08968) (xy 111.491635 -217.13977)
			(xy 111.476286 -217.188079) (xy 111.453725 -217.233471) (xy 111.424484 -217.274876) (xy 111.389252 -217.311319)
			(xy 111.348859 -217.341943) (xy 111.304255 -217.366024) (xy 111.256492 -217.382998) (xy 111.23168 -217.388186)
			(xy 111.20882 -217.392504) (xy 111.003842 -217.747596) (xy 111.011716 -217.76944) (xy 111.020306 -217.795856)
			(xy 111.029495 -217.850633) (xy 111.030004 -217.878406) (xy 111.029496 -217.904293) (xy 111.021397 -217.955431)
			(xy 111.005398 -218.004671) (xy 110.981892 -218.050803) (xy 110.95146 -218.09269) (xy 110.91485 -218.1293)
			(xy 110.872963 -218.159732) (xy 110.826831 -218.183238) (xy 110.777591 -218.199237) (xy 110.726453 -218.207336)
			(xy 110.674679 -218.207336) (xy 110.623541 -218.199237) (xy 110.574301 -218.183238) (xy 110.528169 -218.159732)
			(xy 110.486282 -218.1293) (xy 110.449672 -218.09269) (xy 110.41924 -218.050803) (xy 110.395734 -218.004671)
			(xy 110.379735 -217.955431) (xy 110.371636 -217.904293) (xy 110.371128 -217.878406) (xy 110.090204 -217.878406)
			(xy 110.089676 -217.906114) (xy 110.08048 -217.960761) (xy 110.071916 -217.987118) (xy 110.064296 -218.008962)
			(xy 110.269274 -218.364054) (xy 110.292134 -218.368372) (xy 110.316944 -218.373529) (xy 110.364684 -218.390523)
			(xy 110.409261 -218.414621) (xy 110.449626 -218.445257) (xy 110.484829 -218.481707) (xy 110.51404 -218.523115)
			(xy 110.536571 -218.568504) (xy 110.551892 -218.616807) (xy 110.559642 -218.666885) (xy 110.560104 -218.692222)
			(xy 111.78032 -218.692222) (xy 111.780845 -218.666878) (xy 111.788614 -218.616789) (xy 111.803957 -218.56848)
			(xy 111.826512 -218.523087) (xy 111.855749 -218.481681) (xy 111.890978 -218.445236) (xy 111.931369 -218.414613)
			(xy 111.97597 -218.390531) (xy 112.023732 -218.373559) (xy 112.048544 -218.368372) (xy 112.071404 -218.364054)
			(xy 112.276636 -218.008708) (xy 112.268762 -217.98661) (xy 112.260294 -217.960366) (xy 112.251224 -217.905977)
			(xy 112.250728 -217.878406) (xy 112.251236 -217.852519) (xy 112.259335 -217.801381) (xy 112.275334 -217.752141)
			(xy 112.29884 -217.706009) (xy 112.329272 -217.664122) (xy 112.365882 -217.627512) (xy 112.407769 -217.59708)
			(xy 112.453901 -217.573574) (xy 112.503141 -217.557575) (xy 112.554279 -217.549476) (xy 112.606053 -217.549476)
			(xy 112.657191 -217.557575) (xy 112.706431 -217.573574) (xy 112.752563 -217.59708) (xy 112.79445 -217.627512)
			(xy 112.83106 -217.664122) (xy 112.861492 -217.706009) (xy 112.884998 -217.752141) (xy 112.900997 -217.801381)
			(xy 112.909096 -217.852519) (xy 112.909604 -217.878406) (xy 112.909131 -217.90378) (xy 112.901362 -217.953931)
			(xy 112.885993 -218.002296) (xy 112.863388 -218.047732) (xy 112.834082 -218.089163) (xy 112.798768 -218.125609)
			(xy 112.758282 -218.156208) (xy 112.713582 -218.180235) (xy 112.665726 -218.197122) (xy 112.640872 -218.202256)
			(xy 112.618012 -218.206574) (xy 112.413288 -218.561412) (xy 112.421162 -218.583256) (xy 112.429814 -218.609662)
			(xy 112.43913 -218.66444) (xy 112.439704 -218.692222) (xy 113.660428 -218.692222) (xy 113.660908 -218.666887)
			(xy 113.668658 -218.616813) (xy 113.683979 -218.568515) (xy 113.70651 -218.52313) (xy 113.73572 -218.481727)
			(xy 113.770922 -218.445282) (xy 113.811285 -218.414651) (xy 113.855861 -218.390558) (xy 113.903598 -218.37357)
			(xy 113.928398 -218.368372) (xy 113.951258 -218.364054) (xy 114.156236 -218.008962) (xy 114.148616 -217.986864)
			(xy 114.140092 -217.960694) (xy 114.130901 -217.906431) (xy 114.130328 -217.878914) (xy 114.130328 -217.878406)
			(xy 114.130836 -217.852519) (xy 114.138935 -217.801381) (xy 114.154934 -217.752141) (xy 114.17844 -217.706009)
			(xy 114.208872 -217.664122) (xy 114.245482 -217.627512) (xy 114.287369 -217.59708) (xy 114.333501 -217.573574)
			(xy 114.382741 -217.557575) (xy 114.433879 -217.549476) (xy 114.485653 -217.549476) (xy 114.536791 -217.557575)
			(xy 114.586031 -217.573574) (xy 114.632163 -217.59708) (xy 114.67405 -217.627512) (xy 114.71066 -217.664122)
			(xy 114.741092 -217.706009) (xy 114.764598 -217.752141) (xy 114.780597 -217.801381) (xy 114.788696 -217.852519)
			(xy 114.789204 -217.878406) (xy 114.788769 -217.903771) (xy 114.781019 -217.953906) (xy 114.765673 -218.002259)
			(xy 114.743093 -218.047686) (xy 114.713814 -218.089114) (xy 114.678529 -218.125562) (xy 114.638071 -218.156167)
			(xy 114.593399 -218.180207) (xy 114.545568 -218.197111) (xy 114.520726 -218.202256) (xy 114.497866 -218.206574)
			(xy 114.293142 -218.561412) (xy 114.301016 -218.583256) (xy 114.309609 -218.609671) (xy 114.318797 -218.664449)
			(xy 114.319304 -218.692222) (xy 115.53952 -218.692222) (xy 115.540045 -218.666878) (xy 115.547814 -218.616789)
			(xy 115.563157 -218.56848) (xy 115.585712 -218.523087) (xy 115.614949 -218.481681) (xy 115.650178 -218.445236)
			(xy 115.690569 -218.414613) (xy 115.73517 -218.390531) (xy 115.782932 -218.373559) (xy 115.807744 -218.368372)
			(xy 115.830604 -218.364054) (xy 116.035836 -218.008708) (xy 116.027962 -217.98661) (xy 116.019494 -217.960366)
			(xy 116.010424 -217.905977) (xy 116.009928 -217.878406) (xy 116.010436 -217.852519) (xy 116.018535 -217.801381)
			(xy 116.034534 -217.752141) (xy 116.05804 -217.706009) (xy 116.088472 -217.664122) (xy 116.125082 -217.627512)
			(xy 116.166969 -217.59708) (xy 116.213101 -217.573574) (xy 116.262341 -217.557575) (xy 116.313479 -217.549476)
			(xy 116.365253 -217.549476) (xy 116.416391 -217.557575) (xy 116.465631 -217.573574) (xy 116.511763 -217.59708)
			(xy 116.55365 -217.627512) (xy 116.59026 -217.664122) (xy 116.620692 -217.706009) (xy 116.644198 -217.752141)
			(xy 116.660197 -217.801381) (xy 116.668296 -217.852519) (xy 116.668804 -217.878406) (xy 116.668331 -217.90378)
			(xy 116.660562 -217.953931) (xy 116.645193 -218.002296) (xy 116.622588 -218.047732) (xy 116.593282 -218.089163)
			(xy 116.557968 -218.125609) (xy 116.517482 -218.156208) (xy 116.472782 -218.180235) (xy 116.424926 -218.197122)
			(xy 116.400072 -218.202256) (xy 116.377212 -218.206574) (xy 116.172488 -218.561412) (xy 116.180362 -218.583256)
			(xy 116.189014 -218.609662) (xy 116.19833 -218.66444) (xy 116.198904 -218.692222) (xy 117.41912 -218.692222)
			(xy 117.419645 -218.666878) (xy 117.427414 -218.616789) (xy 117.442757 -218.56848) (xy 117.465312 -218.523087)
			(xy 117.494549 -218.481681) (xy 117.529778 -218.445236) (xy 117.570169 -218.414613) (xy 117.61477 -218.390531)
			(xy 117.662532 -218.373559) (xy 117.687344 -218.368372) (xy 117.710204 -218.364054) (xy 117.915436 -218.008708)
			(xy 117.907562 -217.98661) (xy 117.899094 -217.960366) (xy 117.890024 -217.905977) (xy 117.889528 -217.878406)
			(xy 117.890036 -217.852519) (xy 117.898135 -217.801381) (xy 117.914134 -217.752141) (xy 117.93764 -217.706009)
			(xy 117.968072 -217.664122) (xy 118.004682 -217.627512) (xy 118.046569 -217.59708) (xy 118.092701 -217.573574)
			(xy 118.141941 -217.557575) (xy 118.193079 -217.549476) (xy 118.244853 -217.549476) (xy 118.295991 -217.557575)
			(xy 118.345231 -217.573574) (xy 118.391363 -217.59708) (xy 118.43325 -217.627512) (xy 118.46986 -217.664122)
			(xy 118.500292 -217.706009) (xy 118.523798 -217.752141) (xy 118.539797 -217.801381) (xy 118.547896 -217.852519)
			(xy 118.548404 -217.878406) (xy 118.547931 -217.90378) (xy 118.540162 -217.953931) (xy 118.524793 -218.002296)
			(xy 118.502188 -218.047732) (xy 118.472882 -218.089163) (xy 118.437568 -218.125609) (xy 118.397082 -218.156208)
			(xy 118.352382 -218.180235) (xy 118.304526 -218.197122) (xy 118.279672 -218.202256) (xy 118.256812 -218.206574)
			(xy 118.052088 -218.561412) (xy 118.059962 -218.583256) (xy 118.068614 -218.609662) (xy 118.07793 -218.66444)
			(xy 118.078504 -218.692222) (xy 119.29872 -218.692222) (xy 119.299245 -218.666878) (xy 119.307014 -218.616789)
			(xy 119.322357 -218.56848) (xy 119.344912 -218.523087) (xy 119.374149 -218.481681) (xy 119.409378 -218.445236)
			(xy 119.449769 -218.414613) (xy 119.49437 -218.390531) (xy 119.542132 -218.373559) (xy 119.566944 -218.368372)
			(xy 119.589804 -218.364054) (xy 119.795036 -218.008708) (xy 119.787162 -217.98661) (xy 119.778694 -217.960366)
			(xy 119.769624 -217.905977) (xy 119.769128 -217.878406) (xy 119.769636 -217.852519) (xy 119.777735 -217.801381)
			(xy 119.793734 -217.752141) (xy 119.81724 -217.706009) (xy 119.847672 -217.664122) (xy 119.884282 -217.627512)
			(xy 119.926169 -217.59708) (xy 119.972301 -217.573574) (xy 120.021541 -217.557575) (xy 120.072679 -217.549476)
			(xy 120.124453 -217.549476) (xy 120.175591 -217.557575) (xy 120.224831 -217.573574) (xy 120.270963 -217.59708)
			(xy 120.31285 -217.627512) (xy 120.34946 -217.664122) (xy 120.379892 -217.706009) (xy 120.403398 -217.752141)
			(xy 120.419397 -217.801381) (xy 120.427496 -217.852519) (xy 120.428004 -217.878406) (xy 120.427531 -217.90378)
			(xy 120.419762 -217.953931) (xy 120.404393 -218.002296) (xy 120.381788 -218.047732) (xy 120.352482 -218.089163)
			(xy 120.317168 -218.125609) (xy 120.276682 -218.156208) (xy 120.231982 -218.180235) (xy 120.184126 -218.197122)
			(xy 120.159272 -218.202256) (xy 120.136412 -218.206574) (xy 119.931688 -218.561412) (xy 119.939562 -218.583256)
			(xy 119.948214 -218.609662) (xy 119.95753 -218.66444) (xy 119.958104 -218.692222) (xy 121.17832 -218.692222)
			(xy 121.178845 -218.666878) (xy 121.186614 -218.616789) (xy 121.201957 -218.56848) (xy 121.224512 -218.523087)
			(xy 121.253749 -218.481681) (xy 121.288978 -218.445236) (xy 121.329369 -218.414613) (xy 121.37397 -218.390531)
			(xy 121.421732 -218.373559) (xy 121.446544 -218.368372) (xy 121.469404 -218.364054) (xy 121.674636 -218.008708)
			(xy 121.666762 -217.98661) (xy 121.658294 -217.960366) (xy 121.649224 -217.905977) (xy 121.648728 -217.878406)
			(xy 121.649236 -217.852519) (xy 121.657335 -217.801381) (xy 121.673334 -217.752141) (xy 121.69684 -217.706009)
			(xy 121.727272 -217.664122) (xy 121.763882 -217.627512) (xy 121.805769 -217.59708) (xy 121.851901 -217.573574)
			(xy 121.901141 -217.557575) (xy 121.952279 -217.549476) (xy 122.004053 -217.549476) (xy 122.055191 -217.557575)
			(xy 122.104431 -217.573574) (xy 122.150563 -217.59708) (xy 122.19245 -217.627512) (xy 122.22906 -217.664122)
			(xy 122.259492 -217.706009) (xy 122.282998 -217.752141) (xy 122.298997 -217.801381) (xy 122.307096 -217.852519)
			(xy 122.307604 -217.878406) (xy 122.307131 -217.90378) (xy 122.299362 -217.953931) (xy 122.283993 -218.002296)
			(xy 122.261388 -218.047732) (xy 122.232082 -218.089163) (xy 122.196768 -218.125609) (xy 122.156282 -218.156208)
			(xy 122.111582 -218.180235) (xy 122.063726 -218.197122) (xy 122.038872 -218.202256) (xy 122.016012 -218.206574)
			(xy 121.811288 -218.561412) (xy 121.819162 -218.583256) (xy 121.827814 -218.609662) (xy 121.83713 -218.66444)
			(xy 121.837704 -218.692222) (xy 123.05792 -218.692222) (xy 123.058445 -218.666878) (xy 123.066214 -218.616789)
			(xy 123.081557 -218.56848) (xy 123.104112 -218.523087) (xy 123.133349 -218.481681) (xy 123.168578 -218.445236)
			(xy 123.208969 -218.414613) (xy 123.25357 -218.390531) (xy 123.301332 -218.373559) (xy 123.326144 -218.368372)
			(xy 123.349004 -218.364054) (xy 123.554236 -218.008708) (xy 123.546362 -217.98661) (xy 123.537894 -217.960366)
			(xy 123.528824 -217.905977) (xy 123.528328 -217.878406) (xy 123.528836 -217.852519) (xy 123.536935 -217.801381)
			(xy 123.552934 -217.752141) (xy 123.57644 -217.706009) (xy 123.606872 -217.664122) (xy 123.643482 -217.627512)
			(xy 123.685369 -217.59708) (xy 123.731501 -217.573574) (xy 123.780741 -217.557575) (xy 123.831879 -217.549476)
			(xy 123.883653 -217.549476) (xy 123.934791 -217.557575) (xy 123.984031 -217.573574) (xy 124.030163 -217.59708)
			(xy 124.07205 -217.627512) (xy 124.10866 -217.664122) (xy 124.139092 -217.706009) (xy 124.162598 -217.752141)
			(xy 124.178597 -217.801381) (xy 124.186696 -217.852519) (xy 124.187204 -217.878406) (xy 124.186731 -217.90378)
			(xy 124.178962 -217.953931) (xy 124.163593 -218.002296) (xy 124.140988 -218.047732) (xy 124.111682 -218.089163)
			(xy 124.076368 -218.125609) (xy 124.035882 -218.156208) (xy 123.991182 -218.180235) (xy 123.943326 -218.197122)
			(xy 123.918472 -218.202256) (xy 123.895612 -218.206574) (xy 123.690888 -218.561412) (xy 123.698762 -218.583256)
			(xy 123.707414 -218.609662) (xy 123.71673 -218.66444) (xy 123.717304 -218.692222) (xy 124.93752 -218.692222)
			(xy 124.938045 -218.666878) (xy 124.945814 -218.616789) (xy 124.961157 -218.56848) (xy 124.983712 -218.523087)
			(xy 125.012949 -218.481681) (xy 125.048178 -218.445236) (xy 125.088569 -218.414613) (xy 125.13317 -218.390531)
			(xy 125.180932 -218.373559) (xy 125.205744 -218.368372) (xy 125.228604 -218.364054) (xy 125.433836 -218.008708)
			(xy 125.425962 -217.98661) (xy 125.417494 -217.960366) (xy 125.408424 -217.905977) (xy 125.407928 -217.878406)
			(xy 125.408436 -217.852519) (xy 125.416535 -217.801381) (xy 125.432534 -217.752141) (xy 125.45604 -217.706009)
			(xy 125.486472 -217.664122) (xy 125.523082 -217.627512) (xy 125.564969 -217.59708) (xy 125.611101 -217.573574)
			(xy 125.660341 -217.557575) (xy 125.711479 -217.549476) (xy 125.763253 -217.549476) (xy 125.814391 -217.557575)
			(xy 125.863631 -217.573574) (xy 125.909763 -217.59708) (xy 125.95165 -217.627512) (xy 125.98826 -217.664122)
			(xy 126.018692 -217.706009) (xy 126.042198 -217.752141) (xy 126.058197 -217.801381) (xy 126.066296 -217.852519)
			(xy 126.066804 -217.878406) (xy 126.066331 -217.90378) (xy 126.058562 -217.953931) (xy 126.043193 -218.002296)
			(xy 126.020588 -218.047732) (xy 125.991282 -218.089163) (xy 125.955968 -218.125609) (xy 125.915482 -218.156208)
			(xy 125.870782 -218.180235) (xy 125.822926 -218.197122) (xy 125.798072 -218.202256) (xy 125.775212 -218.206574)
			(xy 125.570488 -218.561412) (xy 125.578362 -218.583256) (xy 125.587014 -218.609662) (xy 125.59633 -218.66444)
			(xy 125.596904 -218.692222) (xy 126.81712 -218.692222) (xy 126.817645 -218.666878) (xy 126.825414 -218.616789)
			(xy 126.840757 -218.56848) (xy 126.863312 -218.523087) (xy 126.892549 -218.481681) (xy 126.927778 -218.445236)
			(xy 126.968169 -218.414613) (xy 127.01277 -218.390531) (xy 127.060532 -218.373559) (xy 127.085344 -218.368372)
			(xy 127.108204 -218.364054) (xy 127.313436 -218.008708) (xy 127.305562 -217.98661) (xy 127.297094 -217.960366)
			(xy 127.288024 -217.905977) (xy 127.287528 -217.878406) (xy 127.288036 -217.852519) (xy 127.296135 -217.801381)
			(xy 127.312134 -217.752141) (xy 127.33564 -217.706009) (xy 127.366072 -217.664122) (xy 127.402682 -217.627512)
			(xy 127.444569 -217.59708) (xy 127.490701 -217.573574) (xy 127.539941 -217.557575) (xy 127.591079 -217.549476)
			(xy 127.642853 -217.549476) (xy 127.693991 -217.557575) (xy 127.743231 -217.573574) (xy 127.789363 -217.59708)
			(xy 127.83125 -217.627512) (xy 127.86786 -217.664122) (xy 127.898292 -217.706009) (xy 127.921798 -217.752141)
			(xy 127.937797 -217.801381) (xy 127.945896 -217.852519) (xy 127.946404 -217.878406) (xy 127.945931 -217.90378)
			(xy 127.938162 -217.953931) (xy 127.922793 -218.002296) (xy 127.900188 -218.047732) (xy 127.870882 -218.089163)
			(xy 127.835568 -218.125609) (xy 127.795082 -218.156208) (xy 127.750382 -218.180235) (xy 127.702526 -218.197122)
			(xy 127.677672 -218.202256) (xy 127.654812 -218.206574) (xy 127.450088 -218.561412) (xy 127.457962 -218.583256)
			(xy 127.466614 -218.609662) (xy 127.47593 -218.66444) (xy 127.476504 -218.692222) (xy 128.69672 -218.692222)
			(xy 128.697245 -218.666878) (xy 128.705014 -218.616789) (xy 128.720357 -218.56848) (xy 128.742912 -218.523087)
			(xy 128.772149 -218.481681) (xy 128.807378 -218.445236) (xy 128.847769 -218.414613) (xy 128.89237 -218.390531)
			(xy 128.940132 -218.373559) (xy 128.964944 -218.368372) (xy 128.987804 -218.364054) (xy 129.193036 -218.008708)
			(xy 129.185162 -217.98661) (xy 129.176694 -217.960366) (xy 129.167624 -217.905977) (xy 129.167128 -217.878406)
			(xy 129.167636 -217.852519) (xy 129.175735 -217.801381) (xy 129.191734 -217.752141) (xy 129.21524 -217.706009)
			(xy 129.245672 -217.664122) (xy 129.282282 -217.627512) (xy 129.324169 -217.59708) (xy 129.370301 -217.573574)
			(xy 129.419541 -217.557575) (xy 129.470679 -217.549476) (xy 129.522453 -217.549476) (xy 129.573591 -217.557575)
			(xy 129.622831 -217.573574) (xy 129.668963 -217.59708) (xy 129.71085 -217.627512) (xy 129.74746 -217.664122)
			(xy 129.777892 -217.706009) (xy 129.801398 -217.752141) (xy 129.817397 -217.801381) (xy 129.825496 -217.852519)
			(xy 129.826004 -217.878406) (xy 129.825531 -217.90378) (xy 129.817762 -217.953931) (xy 129.802393 -218.002296)
			(xy 129.779788 -218.047732) (xy 129.750482 -218.089163) (xy 129.715168 -218.125609) (xy 129.674682 -218.156208)
			(xy 129.629982 -218.180235) (xy 129.582126 -218.197122) (xy 129.557272 -218.202256) (xy 129.534412 -218.206574)
			(xy 129.329688 -218.561412) (xy 129.337562 -218.583256) (xy 129.346214 -218.609662) (xy 129.35553 -218.66444)
			(xy 129.356104 -218.692222) (xy 130.57632 -218.692222) (xy 130.576845 -218.666878) (xy 130.584614 -218.616789)
			(xy 130.599957 -218.56848) (xy 130.622512 -218.523087) (xy 130.651749 -218.481681) (xy 130.686978 -218.445236)
			(xy 130.727369 -218.414613) (xy 130.77197 -218.390531) (xy 130.819732 -218.373559) (xy 130.844544 -218.368372)
			(xy 130.867404 -218.364054) (xy 131.072636 -218.008708) (xy 131.064762 -217.98661) (xy 131.056294 -217.960366)
			(xy 131.047224 -217.905977) (xy 131.046728 -217.878406) (xy 131.047236 -217.852519) (xy 131.055335 -217.801381)
			(xy 131.071334 -217.752141) (xy 131.09484 -217.706009) (xy 131.125272 -217.664122) (xy 131.161882 -217.627512)
			(xy 131.203769 -217.59708) (xy 131.249901 -217.573574) (xy 131.299141 -217.557575) (xy 131.350279 -217.549476)
			(xy 131.402053 -217.549476) (xy 131.453191 -217.557575) (xy 131.502431 -217.573574) (xy 131.548563 -217.59708)
			(xy 131.59045 -217.627512) (xy 131.62706 -217.664122) (xy 131.657492 -217.706009) (xy 131.680998 -217.752141)
			(xy 131.696997 -217.801381) (xy 131.705096 -217.852519) (xy 131.705604 -217.878406) (xy 131.705131 -217.90378)
			(xy 131.697362 -217.953931) (xy 131.681993 -218.002296) (xy 131.659388 -218.047732) (xy 131.630082 -218.089163)
			(xy 131.594768 -218.125609) (xy 131.554282 -218.156208) (xy 131.509582 -218.180235) (xy 131.461726 -218.197122)
			(xy 131.436872 -218.202256) (xy 131.414012 -218.206574) (xy 131.209288 -218.561412) (xy 131.217162 -218.583256)
			(xy 131.225814 -218.609662) (xy 131.23513 -218.66444) (xy 131.235704 -218.692222) (xy 132.45592 -218.692222)
			(xy 132.456445 -218.666878) (xy 132.464214 -218.616789) (xy 132.479557 -218.56848) (xy 132.502112 -218.523087)
			(xy 132.531349 -218.481681) (xy 132.566578 -218.445236) (xy 132.606969 -218.414613) (xy 132.65157 -218.390531)
			(xy 132.699332 -218.373559) (xy 132.724144 -218.368372) (xy 132.747004 -218.364054) (xy 132.952236 -218.008708)
			(xy 132.944362 -217.98661) (xy 132.935894 -217.960366) (xy 132.926824 -217.905977) (xy 132.926328 -217.878406)
			(xy 132.926836 -217.852519) (xy 132.934935 -217.801381) (xy 132.950934 -217.752141) (xy 132.97444 -217.706009)
			(xy 133.004872 -217.664122) (xy 133.041482 -217.627512) (xy 133.083369 -217.59708) (xy 133.129501 -217.573574)
			(xy 133.178741 -217.557575) (xy 133.229879 -217.549476) (xy 133.281653 -217.549476) (xy 133.332791 -217.557575)
			(xy 133.382031 -217.573574) (xy 133.428163 -217.59708) (xy 133.47005 -217.627512) (xy 133.50666 -217.664122)
			(xy 133.537092 -217.706009) (xy 133.560598 -217.752141) (xy 133.576597 -217.801381) (xy 133.584696 -217.852519)
			(xy 133.585204 -217.878406) (xy 133.584731 -217.90378) (xy 133.576962 -217.953931) (xy 133.561593 -218.002296)
			(xy 133.538988 -218.047732) (xy 133.509682 -218.089163) (xy 133.474368 -218.125609) (xy 133.433882 -218.156208)
			(xy 133.389182 -218.180235) (xy 133.341326 -218.197122) (xy 133.316472 -218.202256) (xy 133.293612 -218.206574)
			(xy 133.088888 -218.561412) (xy 133.096762 -218.583256) (xy 133.105414 -218.609662) (xy 133.11473 -218.66444)
			(xy 133.115304 -218.692222) (xy 133.114796 -218.718129) (xy 133.10669 -218.769306) (xy 133.090678 -218.818585)
			(xy 133.067155 -218.864752) (xy 133.036699 -218.906671) (xy 133.000061 -218.943309) (xy 132.958142 -218.973765)
			(xy 132.911975 -218.997288) (xy 132.862696 -219.0133) (xy 132.811519 -219.021406) (xy 132.759705 -219.021406)
			(xy 132.708528 -219.0133) (xy 132.659249 -218.997288) (xy 132.613082 -218.973765) (xy 132.571163 -218.943309)
			(xy 132.534525 -218.906671) (xy 132.504069 -218.864752) (xy 132.480546 -218.818585) (xy 132.464534 -218.769306)
			(xy 132.456428 -218.718129) (xy 132.45592 -218.692222) (xy 131.235704 -218.692222) (xy 131.235196 -218.718129)
			(xy 131.22709 -218.769306) (xy 131.211078 -218.818585) (xy 131.187555 -218.864752) (xy 131.157099 -218.906671)
			(xy 131.120461 -218.943309) (xy 131.078542 -218.973765) (xy 131.032375 -218.997288) (xy 130.983096 -219.0133)
			(xy 130.931919 -219.021406) (xy 130.880105 -219.021406) (xy 130.828928 -219.0133) (xy 130.779649 -218.997288)
			(xy 130.733482 -218.973765) (xy 130.691563 -218.943309) (xy 130.654925 -218.906671) (xy 130.624469 -218.864752)
			(xy 130.600946 -218.818585) (xy 130.584934 -218.769306) (xy 130.576828 -218.718129) (xy 130.57632 -218.692222)
			(xy 129.356104 -218.692222) (xy 129.355596 -218.718129) (xy 129.34749 -218.769306) (xy 129.331478 -218.818585)
			(xy 129.307955 -218.864752) (xy 129.277499 -218.906671) (xy 129.240861 -218.943309) (xy 129.198942 -218.973765)
			(xy 129.152775 -218.997288) (xy 129.103496 -219.0133) (xy 129.052319 -219.021406) (xy 129.000505 -219.021406)
			(xy 128.949328 -219.0133) (xy 128.900049 -218.997288) (xy 128.853882 -218.973765) (xy 128.811963 -218.943309)
			(xy 128.775325 -218.906671) (xy 128.744869 -218.864752) (xy 128.721346 -218.818585) (xy 128.705334 -218.769306)
			(xy 128.697228 -218.718129) (xy 128.69672 -218.692222) (xy 127.476504 -218.692222) (xy 127.475996 -218.718129)
			(xy 127.46789 -218.769306) (xy 127.451878 -218.818585) (xy 127.428355 -218.864752) (xy 127.397899 -218.906671)
			(xy 127.361261 -218.943309) (xy 127.319342 -218.973765) (xy 127.273175 -218.997288) (xy 127.223896 -219.0133)
			(xy 127.172719 -219.021406) (xy 127.120905 -219.021406) (xy 127.069728 -219.0133) (xy 127.020449 -218.997288)
			(xy 126.974282 -218.973765) (xy 126.932363 -218.943309) (xy 126.895725 -218.906671) (xy 126.865269 -218.864752)
			(xy 126.841746 -218.818585) (xy 126.825734 -218.769306) (xy 126.817628 -218.718129) (xy 126.81712 -218.692222)
			(xy 125.596904 -218.692222) (xy 125.596396 -218.718129) (xy 125.58829 -218.769306) (xy 125.572278 -218.818585)
			(xy 125.548755 -218.864752) (xy 125.518299 -218.906671) (xy 125.481661 -218.943309) (xy 125.439742 -218.973765)
			(xy 125.393575 -218.997288) (xy 125.344296 -219.0133) (xy 125.293119 -219.021406) (xy 125.241305 -219.021406)
			(xy 125.190128 -219.0133) (xy 125.140849 -218.997288) (xy 125.094682 -218.973765) (xy 125.052763 -218.943309)
			(xy 125.016125 -218.906671) (xy 124.985669 -218.864752) (xy 124.962146 -218.818585) (xy 124.946134 -218.769306)
			(xy 124.938028 -218.718129) (xy 124.93752 -218.692222) (xy 123.717304 -218.692222) (xy 123.716796 -218.718129)
			(xy 123.70869 -218.769306) (xy 123.692678 -218.818585) (xy 123.669155 -218.864752) (xy 123.638699 -218.906671)
			(xy 123.602061 -218.943309) (xy 123.560142 -218.973765) (xy 123.513975 -218.997288) (xy 123.464696 -219.0133)
			(xy 123.413519 -219.021406) (xy 123.361705 -219.021406) (xy 123.310528 -219.0133) (xy 123.261249 -218.997288)
			(xy 123.215082 -218.973765) (xy 123.173163 -218.943309) (xy 123.136525 -218.906671) (xy 123.106069 -218.864752)
			(xy 123.082546 -218.818585) (xy 123.066534 -218.769306) (xy 123.058428 -218.718129) (xy 123.05792 -218.692222)
			(xy 121.837704 -218.692222) (xy 121.837196 -218.718129) (xy 121.82909 -218.769306) (xy 121.813078 -218.818585)
			(xy 121.789555 -218.864752) (xy 121.759099 -218.906671) (xy 121.722461 -218.943309) (xy 121.680542 -218.973765)
			(xy 121.634375 -218.997288) (xy 121.585096 -219.0133) (xy 121.533919 -219.021406) (xy 121.482105 -219.021406)
			(xy 121.430928 -219.0133) (xy 121.381649 -218.997288) (xy 121.335482 -218.973765) (xy 121.293563 -218.943309)
			(xy 121.256925 -218.906671) (xy 121.226469 -218.864752) (xy 121.202946 -218.818585) (xy 121.186934 -218.769306)
			(xy 121.178828 -218.718129) (xy 121.17832 -218.692222) (xy 119.958104 -218.692222) (xy 119.957596 -218.718129)
			(xy 119.94949 -218.769306) (xy 119.933478 -218.818585) (xy 119.909955 -218.864752) (xy 119.879499 -218.906671)
			(xy 119.842861 -218.943309) (xy 119.800942 -218.973765) (xy 119.754775 -218.997288) (xy 119.705496 -219.0133)
			(xy 119.654319 -219.021406) (xy 119.602505 -219.021406) (xy 119.551328 -219.0133) (xy 119.502049 -218.997288)
			(xy 119.455882 -218.973765) (xy 119.413963 -218.943309) (xy 119.377325 -218.906671) (xy 119.346869 -218.864752)
			(xy 119.323346 -218.818585) (xy 119.307334 -218.769306) (xy 119.299228 -218.718129) (xy 119.29872 -218.692222)
			(xy 118.078504 -218.692222) (xy 118.077996 -218.718129) (xy 118.06989 -218.769306) (xy 118.053878 -218.818585)
			(xy 118.030355 -218.864752) (xy 117.999899 -218.906671) (xy 117.963261 -218.943309) (xy 117.921342 -218.973765)
			(xy 117.875175 -218.997288) (xy 117.825896 -219.0133) (xy 117.774719 -219.021406) (xy 117.722905 -219.021406)
			(xy 117.671728 -219.0133) (xy 117.622449 -218.997288) (xy 117.576282 -218.973765) (xy 117.534363 -218.943309)
			(xy 117.497725 -218.906671) (xy 117.467269 -218.864752) (xy 117.443746 -218.818585) (xy 117.427734 -218.769306)
			(xy 117.419628 -218.718129) (xy 117.41912 -218.692222) (xy 116.198904 -218.692222) (xy 116.198396 -218.718129)
			(xy 116.19029 -218.769306) (xy 116.174278 -218.818585) (xy 116.150755 -218.864752) (xy 116.120299 -218.906671)
			(xy 116.083661 -218.943309) (xy 116.041742 -218.973765) (xy 115.995575 -218.997288) (xy 115.946296 -219.0133)
			(xy 115.895119 -219.021406) (xy 115.843305 -219.021406) (xy 115.792128 -219.0133) (xy 115.742849 -218.997288)
			(xy 115.696682 -218.973765) (xy 115.654763 -218.943309) (xy 115.618125 -218.906671) (xy 115.587669 -218.864752)
			(xy 115.564146 -218.818585) (xy 115.548134 -218.769306) (xy 115.540028 -218.718129) (xy 115.53952 -218.692222)
			(xy 114.319304 -218.692222) (xy 114.318796 -218.718109) (xy 114.310697 -218.769247) (xy 114.294698 -218.818487)
			(xy 114.271192 -218.864619) (xy 114.24076 -218.906506) (xy 114.20415 -218.943116) (xy 114.162263 -218.973548)
			(xy 114.116131 -218.997054) (xy 114.066891 -219.013053) (xy 114.015753 -219.021152) (xy 113.963979 -219.021152)
			(xy 113.912841 -219.013053) (xy 113.863601 -218.997054) (xy 113.817469 -218.973548) (xy 113.775582 -218.943116)
			(xy 113.738972 -218.906506) (xy 113.70854 -218.864619) (xy 113.685034 -218.818487) (xy 113.669035 -218.769247)
			(xy 113.660936 -218.718109) (xy 113.660428 -218.692222) (xy 112.439704 -218.692222) (xy 112.439196 -218.718129)
			(xy 112.43109 -218.769306) (xy 112.415078 -218.818585) (xy 112.391555 -218.864752) (xy 112.361099 -218.906671)
			(xy 112.324461 -218.943309) (xy 112.282542 -218.973765) (xy 112.236375 -218.997288) (xy 112.187096 -219.0133)
			(xy 112.135919 -219.021406) (xy 112.084105 -219.021406) (xy 112.032928 -219.0133) (xy 111.983649 -218.997288)
			(xy 111.937482 -218.973765) (xy 111.895563 -218.943309) (xy 111.858925 -218.906671) (xy 111.828469 -218.864752)
			(xy 111.804946 -218.818585) (xy 111.788934 -218.769306) (xy 111.780828 -218.718129) (xy 111.78032 -218.692222)
			(xy 110.560104 -218.692222) (xy 110.559596 -218.718109) (xy 110.551497 -218.769247) (xy 110.535498 -218.818487)
			(xy 110.511992 -218.864619) (xy 110.48156 -218.906506) (xy 110.44495 -218.943116) (xy 110.403063 -218.973548)
			(xy 110.356931 -218.997054) (xy 110.307691 -219.013053) (xy 110.256553 -219.021152) (xy 110.204779 -219.021152)
			(xy 110.153641 -219.013053) (xy 110.104401 -218.997054) (xy 110.058269 -218.973548) (xy 110.016382 -218.943116)
			(xy 109.979772 -218.906506) (xy 109.94934 -218.864619) (xy 109.925834 -218.818487) (xy 109.909835 -218.769247)
			(xy 109.901736 -218.718109) (xy 109.901228 -218.692222) (xy 109.901766 -218.664514) (xy 109.910956 -218.609868)
			(xy 109.919516 -218.58351) (xy 109.92739 -218.561412) (xy 109.722412 -218.206574) (xy 109.699552 -218.202256)
			(xy 109.67472 -218.197133) (xy 109.626938 -218.180175) (xy 109.582316 -218.1561) (xy 109.541908 -218.125474)
			(xy 109.506667 -218.089022) (xy 109.477424 -218.047602) (xy 109.45487 -218.002192) (xy 109.439537 -217.953864)
			(xy 109.431786 -217.903757) (xy 109.431328 -217.878406) (xy 109.150404 -217.878406) (xy 109.149896 -217.904293)
			(xy 109.141797 -217.955431) (xy 109.125798 -218.004671) (xy 109.102292 -218.050803) (xy 109.07186 -218.09269)
			(xy 109.03525 -218.1293) (xy 108.993363 -218.159732) (xy 108.947231 -218.183238) (xy 108.897991 -218.199237)
			(xy 108.846853 -218.207336) (xy 108.795079 -218.207336) (xy 108.743941 -218.199237) (xy 108.694701 -218.183238)
			(xy 108.648569 -218.159732) (xy 108.606682 -218.1293) (xy 108.570072 -218.09269) (xy 108.53964 -218.050803)
			(xy 108.516134 -218.004671) (xy 108.500135 -217.955431) (xy 108.492036 -217.904293) (xy 108.491528 -217.878406)
			(xy 108.210604 -217.878406) (xy 108.210076 -217.906114) (xy 108.20088 -217.960761) (xy 108.192316 -217.987118)
			(xy 108.184442 -218.009216) (xy 108.38942 -218.364054) (xy 108.41228 -218.368372) (xy 108.4371 -218.37354)
			(xy 108.484878 -218.390497) (xy 108.529495 -218.41457) (xy 108.5699 -218.44519) (xy 108.60514 -218.481637)
			(xy 108.634384 -218.52305) (xy 108.656942 -218.568452) (xy 108.672281 -218.616773) (xy 108.680041 -218.666873)
			(xy 108.680504 -218.692222) (xy 108.679996 -218.718129) (xy 108.67189 -218.769306) (xy 108.655878 -218.818585)
			(xy 108.632355 -218.864752) (xy 108.601899 -218.906671) (xy 108.565261 -218.943309) (xy 108.523342 -218.973765)
			(xy 108.477175 -218.997288) (xy 108.427896 -219.0133) (xy 108.376719 -219.021406) (xy 108.324905 -219.021406)
			(xy 108.273728 -219.0133) (xy 108.224449 -218.997288) (xy 108.178282 -218.973765) (xy 108.136363 -218.943309)
			(xy 108.099725 -218.906671) (xy 108.069269 -218.864752) (xy 108.045746 -218.818585) (xy 108.029734 -218.769306)
			(xy 108.021628 -218.718129) (xy 108.02112 -218.692222) (xy 108.021718 -218.664505) (xy 108.031039 -218.609858)
			(xy 108.039662 -218.58351) (xy 108.047536 -218.561412) (xy 107.842558 -218.206574) (xy 107.819698 -218.202256)
			(xy 107.794899 -218.197049) (xy 107.747162 -218.180062) (xy 107.702585 -218.15597) (xy 107.66222 -218.125341)
			(xy 107.627017 -218.088897) (xy 107.597804 -218.047495) (xy 107.575271 -218.002112) (xy 107.559946 -217.953814)
			(xy 107.552192 -217.903741) (xy 107.551728 -217.878406) (xy 107.270804 -217.878406) (xy 107.270296 -217.904293)
			(xy 107.262197 -217.955431) (xy 107.246198 -218.004671) (xy 107.222692 -218.050803) (xy 107.19226 -218.09269)
			(xy 107.15565 -218.1293) (xy 107.113763 -218.159732) (xy 107.067631 -218.183238) (xy 107.018391 -218.199237)
			(xy 106.967253 -218.207336) (xy 106.915479 -218.207336) (xy 106.864341 -218.199237) (xy 106.815101 -218.183238)
			(xy 106.768969 -218.159732) (xy 106.727082 -218.1293) (xy 106.690472 -218.09269) (xy 106.66004 -218.050803)
			(xy 106.636534 -218.004671) (xy 106.620535 -217.955431) (xy 106.612436 -217.904293) (xy 106.611928 -217.878406)
			(xy 106.331004 -217.878406) (xy 106.330476 -217.906114) (xy 106.32128 -217.960761) (xy 106.312716 -217.987118)
			(xy 106.304842 -218.009216) (xy 106.50982 -218.364054) (xy 106.53268 -218.368372) (xy 106.5575 -218.37354)
			(xy 106.605278 -218.390497) (xy 106.649895 -218.41457) (xy 106.6903 -218.44519) (xy 106.72554 -218.481637)
			(xy 106.754784 -218.52305) (xy 106.777342 -218.568452) (xy 106.792681 -218.616773) (xy 106.800441 -218.666873)
			(xy 106.800904 -218.692222) (xy 106.800396 -218.718129) (xy 106.79229 -218.769306) (xy 106.776278 -218.818585)
			(xy 106.752755 -218.864752) (xy 106.722299 -218.906671) (xy 106.685661 -218.943309) (xy 106.643742 -218.973765)
			(xy 106.597575 -218.997288) (xy 106.548296 -219.0133) (xy 106.497119 -219.021406) (xy 106.445305 -219.021406)
			(xy 106.394128 -219.0133) (xy 106.344849 -218.997288) (xy 106.298682 -218.973765) (xy 106.256763 -218.943309)
			(xy 106.220125 -218.906671) (xy 106.189669 -218.864752) (xy 106.166146 -218.818585) (xy 106.150134 -218.769306)
			(xy 106.142028 -218.718129) (xy 106.14152 -218.692222) (xy 106.142118 -218.664505) (xy 106.151439 -218.609858)
			(xy 106.160062 -218.58351) (xy 106.167936 -218.561412) (xy 105.962958 -218.206574) (xy 105.940098 -218.202256)
			(xy 105.915299 -218.197049) (xy 105.867562 -218.180062) (xy 105.822985 -218.15597) (xy 105.78262 -218.125341)
			(xy 105.747417 -218.088897) (xy 105.718204 -218.047495) (xy 105.695671 -218.002112) (xy 105.680346 -217.953814)
			(xy 105.672592 -217.903741) (xy 105.672128 -217.878406) (xy 105.391204 -217.878406) (xy 105.390696 -217.904293)
			(xy 105.382597 -217.955431) (xy 105.366598 -218.004671) (xy 105.343092 -218.050803) (xy 105.31266 -218.09269)
			(xy 105.27605 -218.1293) (xy 105.234163 -218.159732) (xy 105.188031 -218.183238) (xy 105.138791 -218.199237)
			(xy 105.087653 -218.207336) (xy 105.035879 -218.207336) (xy 104.984741 -218.199237) (xy 104.935501 -218.183238)
			(xy 104.889369 -218.159732) (xy 104.847482 -218.1293) (xy 104.810872 -218.09269) (xy 104.78044 -218.050803)
			(xy 104.756934 -218.004671) (xy 104.740935 -217.955431) (xy 104.732836 -217.904293) (xy 104.732328 -217.878406)
			(xy 104.451404 -217.878406) (xy 104.450876 -217.906114) (xy 104.44168 -217.960761) (xy 104.433116 -217.987118)
			(xy 104.425242 -218.009216) (xy 104.63022 -218.364054) (xy 104.65308 -218.368372) (xy 104.6779 -218.37354)
			(xy 104.725678 -218.390497) (xy 104.770295 -218.41457) (xy 104.8107 -218.44519) (xy 104.84594 -218.481637)
			(xy 104.875184 -218.52305) (xy 104.897742 -218.568452) (xy 104.913081 -218.616773) (xy 104.920841 -218.666873)
			(xy 104.921304 -218.692222) (xy 104.920796 -218.718129) (xy 104.91269 -218.769306) (xy 104.896678 -218.818585)
			(xy 104.873155 -218.864752) (xy 104.842699 -218.906671) (xy 104.806061 -218.943309) (xy 104.764142 -218.973765)
			(xy 104.717975 -218.997288) (xy 104.668696 -219.0133) (xy 104.617519 -219.021406) (xy 104.565705 -219.021406)
			(xy 104.514528 -219.0133) (xy 104.465249 -218.997288) (xy 104.419082 -218.973765) (xy 104.377163 -218.943309)
			(xy 104.340525 -218.906671) (xy 104.310069 -218.864752) (xy 104.286546 -218.818585) (xy 104.270534 -218.769306)
			(xy 104.262428 -218.718129) (xy 104.26192 -218.692222) (xy 104.262518 -218.664505) (xy 104.271839 -218.609858)
			(xy 104.280462 -218.58351) (xy 104.288336 -218.561412) (xy 104.083358 -218.206574) (xy 104.060498 -218.202256)
			(xy 104.035699 -218.197049) (xy 103.987962 -218.180062) (xy 103.943385 -218.15597) (xy 103.90302 -218.125341)
			(xy 103.867817 -218.088897) (xy 103.838604 -218.047495) (xy 103.816071 -218.002112) (xy 103.800746 -217.953814)
			(xy 103.792992 -217.903741) (xy 103.792528 -217.878406) (xy 103.511604 -217.878406) (xy 103.511096 -217.904293)
			(xy 103.502997 -217.955431) (xy 103.486998 -218.004671) (xy 103.463492 -218.050803) (xy 103.43306 -218.09269)
			(xy 103.39645 -218.1293) (xy 103.354563 -218.159732) (xy 103.308431 -218.183238) (xy 103.259191 -218.199237)
			(xy 103.208053 -218.207336) (xy 103.156279 -218.207336) (xy 103.105141 -218.199237) (xy 103.055901 -218.183238)
			(xy 103.009769 -218.159732) (xy 102.967882 -218.1293) (xy 102.931272 -218.09269) (xy 102.90084 -218.050803)
			(xy 102.877334 -218.004671) (xy 102.861335 -217.955431) (xy 102.853236 -217.904293) (xy 102.852728 -217.878406)
			(xy 102.571804 -217.878406) (xy 102.571276 -217.906114) (xy 102.56208 -217.960761) (xy 102.553516 -217.987118)
			(xy 102.545642 -218.009216) (xy 102.75062 -218.364054) (xy 102.77348 -218.368372) (xy 102.7983 -218.37354)
			(xy 102.846078 -218.390497) (xy 102.890695 -218.41457) (xy 102.9311 -218.44519) (xy 102.96634 -218.481637)
			(xy 102.995584 -218.52305) (xy 103.018142 -218.568452) (xy 103.033481 -218.616773) (xy 103.041241 -218.666873)
			(xy 103.041704 -218.692222) (xy 103.041196 -218.718129) (xy 103.03309 -218.769306) (xy 103.017078 -218.818585)
			(xy 102.993555 -218.864752) (xy 102.963099 -218.906671) (xy 102.926461 -218.943309) (xy 102.884542 -218.973765)
			(xy 102.838375 -218.997288) (xy 102.789096 -219.0133) (xy 102.737919 -219.021406) (xy 102.686105 -219.021406)
			(xy 102.634928 -219.0133) (xy 102.585649 -218.997288) (xy 102.539482 -218.973765) (xy 102.497563 -218.943309)
			(xy 102.460925 -218.906671) (xy 102.430469 -218.864752) (xy 102.406946 -218.818585) (xy 102.390934 -218.769306)
			(xy 102.382828 -218.718129) (xy 102.38232 -218.692222) (xy 102.382918 -218.664505) (xy 102.392239 -218.609858)
			(xy 102.400862 -218.58351) (xy 102.408736 -218.561412) (xy 102.203758 -218.206574) (xy 102.180898 -218.202256)
			(xy 102.156099 -218.197049) (xy 102.108362 -218.180062) (xy 102.063785 -218.15597) (xy 102.02342 -218.125341)
			(xy 101.988217 -218.088897) (xy 101.959004 -218.047495) (xy 101.936471 -218.002112) (xy 101.921146 -217.953814)
			(xy 101.913392 -217.903741) (xy 101.912928 -217.878406) (xy 101.632004 -217.878406) (xy 101.631496 -217.904293)
			(xy 101.623397 -217.955431) (xy 101.607398 -218.004671) (xy 101.583892 -218.050803) (xy 101.55346 -218.09269)
			(xy 101.51685 -218.1293) (xy 101.474963 -218.159732) (xy 101.428831 -218.183238) (xy 101.379591 -218.199237)
			(xy 101.328453 -218.207336) (xy 101.276679 -218.207336) (xy 101.225541 -218.199237) (xy 101.176301 -218.183238)
			(xy 101.130169 -218.159732) (xy 101.088282 -218.1293) (xy 101.051672 -218.09269) (xy 101.02124 -218.050803)
			(xy 100.997734 -218.004671) (xy 100.981735 -217.955431) (xy 100.973636 -217.904293) (xy 100.973128 -217.878406)
			(xy 100.692204 -217.878406) (xy 100.691676 -217.906114) (xy 100.68248 -217.960761) (xy 100.673916 -217.987118)
			(xy 100.666042 -218.009216) (xy 100.87102 -218.364054) (xy 100.89388 -218.368372) (xy 100.9187 -218.37354)
			(xy 100.966478 -218.390497) (xy 101.011095 -218.41457) (xy 101.0515 -218.44519) (xy 101.08674 -218.481637)
			(xy 101.115984 -218.52305) (xy 101.138542 -218.568452) (xy 101.153881 -218.616773) (xy 101.161641 -218.666873)
			(xy 101.162104 -218.692222) (xy 101.161596 -218.718129) (xy 101.15349 -218.769306) (xy 101.137478 -218.818585)
			(xy 101.113955 -218.864752) (xy 101.083499 -218.906671) (xy 101.046861 -218.943309) (xy 101.004942 -218.973765)
			(xy 100.958775 -218.997288) (xy 100.909496 -219.0133) (xy 100.858319 -219.021406) (xy 100.806505 -219.021406)
			(xy 100.755328 -219.0133) (xy 100.706049 -218.997288) (xy 100.659882 -218.973765) (xy 100.617963 -218.943309)
			(xy 100.581325 -218.906671) (xy 100.550869 -218.864752) (xy 100.527346 -218.818585) (xy 100.511334 -218.769306)
			(xy 100.503228 -218.718129) (xy 100.50272 -218.692222) (xy 100.503318 -218.664505) (xy 100.512639 -218.609858)
			(xy 100.521262 -218.58351) (xy 100.529136 -218.561412) (xy 100.324158 -218.206574) (xy 100.301298 -218.202256)
			(xy 100.276499 -218.197049) (xy 100.228762 -218.180062) (xy 100.184185 -218.15597) (xy 100.14382 -218.125341)
			(xy 100.108617 -218.088897) (xy 100.079404 -218.047495) (xy 100.056871 -218.002112) (xy 100.041546 -217.953814)
			(xy 100.033792 -217.903741) (xy 100.033328 -217.878406) (xy 99.752404 -217.878406) (xy 99.751896 -217.904293)
			(xy 99.743797 -217.955431) (xy 99.727798 -218.004671) (xy 99.704292 -218.050803) (xy 99.67386 -218.09269)
			(xy 99.63725 -218.1293) (xy 99.595363 -218.159732) (xy 99.549231 -218.183238) (xy 99.499991 -218.199237)
			(xy 99.448853 -218.207336) (xy 99.397079 -218.207336) (xy 99.345941 -218.199237) (xy 99.296701 -218.183238)
			(xy 99.250569 -218.159732) (xy 99.208682 -218.1293) (xy 99.172072 -218.09269) (xy 99.14164 -218.050803)
			(xy 99.118134 -218.004671) (xy 99.102135 -217.955431) (xy 99.094036 -217.904293) (xy 99.093528 -217.878406)
			(xy 98.812604 -217.878406) (xy 98.812076 -217.906114) (xy 98.80288 -217.960761) (xy 98.794316 -217.987118)
			(xy 98.786442 -218.009216) (xy 98.99142 -218.364054) (xy 99.01428 -218.368372) (xy 99.0391 -218.37354)
			(xy 99.086878 -218.390497) (xy 99.131495 -218.41457) (xy 99.1719 -218.44519) (xy 99.20714 -218.481637)
			(xy 99.236384 -218.52305) (xy 99.258942 -218.568452) (xy 99.274281 -218.616773) (xy 99.282041 -218.666873)
			(xy 99.282504 -218.692222) (xy 99.281996 -218.718129) (xy 99.27389 -218.769306) (xy 99.257878 -218.818585)
			(xy 99.234355 -218.864752) (xy 99.203899 -218.906671) (xy 99.167261 -218.943309) (xy 99.125342 -218.973765)
			(xy 99.079175 -218.997288) (xy 99.029896 -219.0133) (xy 98.978719 -219.021406) (xy 98.926905 -219.021406)
			(xy 98.875728 -219.0133) (xy 98.826449 -218.997288) (xy 98.780282 -218.973765) (xy 98.738363 -218.943309)
			(xy 98.701725 -218.906671) (xy 98.671269 -218.864752) (xy 98.647746 -218.818585) (xy 98.631734 -218.769306)
			(xy 98.623628 -218.718129) (xy 98.62312 -218.692222) (xy 98.623718 -218.664505) (xy 98.633039 -218.609858)
			(xy 98.641662 -218.58351) (xy 98.649536 -218.561412) (xy 98.444558 -218.206574) (xy 98.421698 -218.202256)
			(xy 98.396899 -218.197049) (xy 98.349162 -218.180062) (xy 98.304585 -218.15597) (xy 98.26422 -218.125341)
			(xy 98.229017 -218.088897) (xy 98.199804 -218.047495) (xy 98.177271 -218.002112) (xy 98.161946 -217.953814)
			(xy 98.154192 -217.903741) (xy 98.153728 -217.878406) (xy 97.872804 -217.878406) (xy 97.872296 -217.904293)
			(xy 97.864197 -217.955431) (xy 97.848198 -218.004671) (xy 97.824692 -218.050803) (xy 97.79426 -218.09269)
			(xy 97.75765 -218.1293) (xy 97.715763 -218.159732) (xy 97.669631 -218.183238) (xy 97.620391 -218.199237)
			(xy 97.569253 -218.207336) (xy 97.517479 -218.207336) (xy 97.466341 -218.199237) (xy 97.417101 -218.183238)
			(xy 97.370969 -218.159732) (xy 97.329082 -218.1293) (xy 97.292472 -218.09269) (xy 97.26204 -218.050803)
			(xy 97.238534 -218.004671) (xy 97.222535 -217.955431) (xy 97.214436 -217.904293) (xy 97.213928 -217.878406)
			(xy 96.933004 -217.878406) (xy 96.932476 -217.906114) (xy 96.92328 -217.960761) (xy 96.914716 -217.987118)
			(xy 96.906842 -218.009216) (xy 97.11182 -218.364054) (xy 97.13468 -218.368372) (xy 97.1595 -218.37354)
			(xy 97.207278 -218.390497) (xy 97.251895 -218.41457) (xy 97.2923 -218.44519) (xy 97.32754 -218.481637)
			(xy 97.356784 -218.52305) (xy 97.379342 -218.568452) (xy 97.394681 -218.616773) (xy 97.402441 -218.666873)
			(xy 97.402904 -218.692222) (xy 97.402396 -218.718129) (xy 97.39429 -218.769306) (xy 97.378278 -218.818585)
			(xy 97.354755 -218.864752) (xy 97.324299 -218.906671) (xy 97.287661 -218.943309) (xy 97.245742 -218.973765)
			(xy 97.199575 -218.997288) (xy 97.150296 -219.0133) (xy 97.099119 -219.021406) (xy 97.047305 -219.021406)
			(xy 96.996128 -219.0133) (xy 96.946849 -218.997288) (xy 96.900682 -218.973765) (xy 96.858763 -218.943309)
			(xy 96.822125 -218.906671) (xy 96.791669 -218.864752) (xy 96.768146 -218.818585) (xy 96.752134 -218.769306)
			(xy 96.744028 -218.718129) (xy 96.74352 -218.692222) (xy 96.744118 -218.664505) (xy 96.753439 -218.609858)
			(xy 96.762062 -218.58351) (xy 96.769936 -218.561412) (xy 96.564958 -218.206574) (xy 96.542098 -218.202256)
			(xy 96.517299 -218.197049) (xy 96.469562 -218.180062) (xy 96.424985 -218.15597) (xy 96.38462 -218.125341)
			(xy 96.349417 -218.088897) (xy 96.320204 -218.047495) (xy 96.297671 -218.002112) (xy 96.282346 -217.953814)
			(xy 96.274592 -217.903741) (xy 96.274128 -217.878406) (xy 95.993204 -217.878406) (xy 95.992696 -217.904293)
			(xy 95.984597 -217.955431) (xy 95.968598 -218.004671) (xy 95.945092 -218.050803) (xy 95.91466 -218.09269)
			(xy 95.87805 -218.1293) (xy 95.836163 -218.159732) (xy 95.790031 -218.183238) (xy 95.740791 -218.199237)
			(xy 95.689653 -218.207336) (xy 95.637879 -218.207336) (xy 95.586741 -218.199237) (xy 95.537501 -218.183238)
			(xy 95.491369 -218.159732) (xy 95.449482 -218.1293) (xy 95.412872 -218.09269) (xy 95.38244 -218.050803)
			(xy 95.358934 -218.004671) (xy 95.342935 -217.955431) (xy 95.334836 -217.904293) (xy 95.334328 -217.878406)
			(xy 95.053404 -217.878406) (xy 95.052876 -217.906114) (xy 95.04368 -217.960761) (xy 95.035116 -217.987118)
			(xy 95.027242 -218.009216) (xy 95.23222 -218.364054) (xy 95.25508 -218.368372) (xy 95.2799 -218.37354)
			(xy 95.327678 -218.390497) (xy 95.372295 -218.41457) (xy 95.4127 -218.44519) (xy 95.44794 -218.481637)
			(xy 95.477184 -218.52305) (xy 95.499742 -218.568452) (xy 95.515081 -218.616773) (xy 95.522841 -218.666873)
			(xy 95.523304 -218.692222) (xy 95.522796 -218.718129) (xy 95.51469 -218.769306) (xy 95.498678 -218.818585)
			(xy 95.475155 -218.864752) (xy 95.444699 -218.906671) (xy 95.408061 -218.943309) (xy 95.366142 -218.973765)
			(xy 95.319975 -218.997288) (xy 95.270696 -219.0133) (xy 95.219519 -219.021406) (xy 95.167705 -219.021406)
			(xy 95.116528 -219.0133) (xy 95.067249 -218.997288) (xy 95.021082 -218.973765) (xy 94.979163 -218.943309)
			(xy 94.942525 -218.906671) (xy 94.912069 -218.864752) (xy 94.888546 -218.818585) (xy 94.872534 -218.769306)
			(xy 94.864428 -218.718129) (xy 94.86392 -218.692222) (xy 94.864518 -218.664505) (xy 94.873839 -218.609858)
			(xy 94.882462 -218.58351) (xy 94.890336 -218.561412) (xy 94.685358 -218.206574) (xy 94.662498 -218.202256)
			(xy 94.637699 -218.197049) (xy 94.589962 -218.180062) (xy 94.545385 -218.15597) (xy 94.50502 -218.125341)
			(xy 94.469817 -218.088897) (xy 94.440604 -218.047495) (xy 94.418071 -218.002112) (xy 94.402746 -217.953814)
			(xy 94.394992 -217.903741) (xy 94.394528 -217.878406) (xy 94.113604 -217.878406) (xy 94.113096 -217.904293)
			(xy 94.104997 -217.955431) (xy 94.088998 -218.004671) (xy 94.065492 -218.050803) (xy 94.03506 -218.09269)
			(xy 93.99845 -218.1293) (xy 93.956563 -218.159732) (xy 93.910431 -218.183238) (xy 93.861191 -218.199237)
			(xy 93.810053 -218.207336) (xy 93.758279 -218.207336) (xy 93.707141 -218.199237) (xy 93.657901 -218.183238)
			(xy 93.611769 -218.159732) (xy 93.569882 -218.1293) (xy 93.533272 -218.09269) (xy 93.50284 -218.050803)
			(xy 93.479334 -218.004671) (xy 93.463335 -217.955431) (xy 93.455236 -217.904293) (xy 93.454728 -217.878406)
			(xy 93.173804 -217.878406) (xy 93.173276 -217.906114) (xy 93.16408 -217.960761) (xy 93.155516 -217.987118)
			(xy 93.147642 -218.009216) (xy 93.35262 -218.364054) (xy 93.37548 -218.368372) (xy 93.4003 -218.37354)
			(xy 93.448078 -218.390497) (xy 93.492695 -218.41457) (xy 93.5331 -218.44519) (xy 93.56834 -218.481637)
			(xy 93.597584 -218.52305) (xy 93.620142 -218.568452) (xy 93.635481 -218.616773) (xy 93.643241 -218.666873)
			(xy 93.643704 -218.692222) (xy 93.643196 -218.718129) (xy 93.63509 -218.769306) (xy 93.619078 -218.818585)
			(xy 93.595555 -218.864752) (xy 93.565099 -218.906671) (xy 93.528461 -218.943309) (xy 93.486542 -218.973765)
			(xy 93.440375 -218.997288) (xy 93.391096 -219.0133) (xy 93.339919 -219.021406) (xy 93.288105 -219.021406)
			(xy 93.236928 -219.0133) (xy 93.187649 -218.997288) (xy 93.141482 -218.973765) (xy 93.099563 -218.943309)
			(xy 93.062925 -218.906671) (xy 93.032469 -218.864752) (xy 93.008946 -218.818585) (xy 92.992934 -218.769306)
			(xy 92.984828 -218.718129) (xy 92.98432 -218.692222) (xy 92.984918 -218.664505) (xy 92.994239 -218.609858)
			(xy 93.002862 -218.58351) (xy 93.010736 -218.561412) (xy 92.805758 -218.206574) (xy 92.782898 -218.202256)
			(xy 92.758099 -218.197049) (xy 92.710362 -218.180062) (xy 92.665785 -218.15597) (xy 92.62542 -218.125341)
			(xy 92.590217 -218.088897) (xy 92.561004 -218.047495) (xy 92.538471 -218.002112) (xy 92.523146 -217.953814)
			(xy 92.515392 -217.903741) (xy 92.514928 -217.878406) (xy 92.234004 -217.878406) (xy 92.233496 -217.904293)
			(xy 92.225397 -217.955431) (xy 92.209398 -218.004671) (xy 92.185892 -218.050803) (xy 92.15546 -218.09269)
			(xy 92.11885 -218.1293) (xy 92.076963 -218.159732) (xy 92.030831 -218.183238) (xy 91.981591 -218.199237)
			(xy 91.930453 -218.207336) (xy 91.878679 -218.207336) (xy 91.827541 -218.199237) (xy 91.778301 -218.183238)
			(xy 91.732169 -218.159732) (xy 91.690282 -218.1293) (xy 91.653672 -218.09269) (xy 91.62324 -218.050803)
			(xy 91.599734 -218.004671) (xy 91.583735 -217.955431) (xy 91.575636 -217.904293) (xy 91.575128 -217.878406)
			(xy 91.294204 -217.878406) (xy 91.293676 -217.906114) (xy 91.28448 -217.960761) (xy 91.275916 -217.987118)
			(xy 91.268042 -218.009216) (xy 91.47302 -218.364054) (xy 91.49588 -218.368372) (xy 91.5207 -218.37354)
			(xy 91.568478 -218.390497) (xy 91.613095 -218.41457) (xy 91.6535 -218.44519) (xy 91.68874 -218.481637)
			(xy 91.717984 -218.52305) (xy 91.740542 -218.568452) (xy 91.755881 -218.616773) (xy 91.763641 -218.666873)
			(xy 91.764104 -218.692222) (xy 91.763596 -218.718129) (xy 91.75549 -218.769306) (xy 91.739478 -218.818585)
			(xy 91.715955 -218.864752) (xy 91.685499 -218.906671) (xy 91.648861 -218.943309) (xy 91.606942 -218.973765)
			(xy 91.560775 -218.997288) (xy 91.511496 -219.0133) (xy 91.460319 -219.021406) (xy 91.408505 -219.021406)
			(xy 91.357328 -219.0133) (xy 91.308049 -218.997288) (xy 91.261882 -218.973765) (xy 91.219963 -218.943309)
			(xy 91.183325 -218.906671) (xy 91.152869 -218.864752) (xy 91.129346 -218.818585) (xy 91.113334 -218.769306)
			(xy 91.105228 -218.718129) (xy 91.10472 -218.692222) (xy 91.105318 -218.664505) (xy 91.114639 -218.609858)
			(xy 91.123262 -218.58351) (xy 91.131136 -218.561412) (xy 90.926158 -218.206574) (xy 90.903298 -218.202256)
			(xy 90.878499 -218.197049) (xy 90.830762 -218.180062) (xy 90.786185 -218.15597) (xy 90.74582 -218.125341)
			(xy 90.710617 -218.088897) (xy 90.681404 -218.047495) (xy 90.658871 -218.002112) (xy 90.643546 -217.953814)
			(xy 90.635792 -217.903741) (xy 90.635328 -217.878406) (xy 90.354404 -217.878406) (xy 90.353896 -217.904293)
			(xy 90.345797 -217.955431) (xy 90.329798 -218.004671) (xy 90.306292 -218.050803) (xy 90.27586 -218.09269)
			(xy 90.23925 -218.1293) (xy 90.197363 -218.159732) (xy 90.151231 -218.183238) (xy 90.101991 -218.199237)
			(xy 90.050853 -218.207336) (xy 89.999079 -218.207336) (xy 89.947941 -218.199237) (xy 89.898701 -218.183238)
			(xy 89.852569 -218.159732) (xy 89.810682 -218.1293) (xy 89.774072 -218.09269) (xy 89.74364 -218.050803)
			(xy 89.720134 -218.004671) (xy 89.704135 -217.955431) (xy 89.696036 -217.904293) (xy 89.695528 -217.878406)
			(xy 89.414604 -217.878406) (xy 89.414076 -217.906114) (xy 89.40488 -217.960761) (xy 89.396316 -217.987118)
			(xy 89.388442 -218.009216) (xy 89.59342 -218.364054) (xy 89.61628 -218.368372) (xy 89.6411 -218.37354)
			(xy 89.688878 -218.390497) (xy 89.733495 -218.41457) (xy 89.7739 -218.44519) (xy 89.80914 -218.481637)
			(xy 89.838384 -218.52305) (xy 89.860942 -218.568452) (xy 89.876281 -218.616773) (xy 89.884041 -218.666873)
			(xy 89.884504 -218.692222) (xy 89.883996 -218.718129) (xy 89.87589 -218.769306) (xy 89.859878 -218.818585)
			(xy 89.836355 -218.864752) (xy 89.805899 -218.906671) (xy 89.769261 -218.943309) (xy 89.727342 -218.973765)
			(xy 89.681175 -218.997288) (xy 89.631896 -219.0133) (xy 89.580719 -219.021406) (xy 89.528905 -219.021406)
			(xy 89.477728 -219.0133) (xy 89.428449 -218.997288) (xy 89.382282 -218.973765) (xy 89.340363 -218.943309)
			(xy 89.303725 -218.906671) (xy 89.273269 -218.864752) (xy 89.249746 -218.818585) (xy 89.233734 -218.769306)
			(xy 89.225628 -218.718129) (xy 89.22512 -218.692222) (xy 89.225718 -218.664505) (xy 89.235039 -218.609858)
			(xy 89.243662 -218.58351) (xy 89.251536 -218.561412) (xy 89.046558 -218.206574) (xy 89.023698 -218.202256)
			(xy 88.998899 -218.197049) (xy 88.951162 -218.180062) (xy 88.906585 -218.15597) (xy 88.86622 -218.125341)
			(xy 88.831017 -218.088897) (xy 88.801804 -218.047495) (xy 88.779271 -218.002112) (xy 88.763946 -217.953814)
			(xy 88.756192 -217.903741) (xy 88.755728 -217.878406) (xy 2.509012 -217.878406) (xy 2.509012 -221.133924)
			(xy 88.755728 -221.133924) (xy 88.756236 -221.108037) (xy 88.764335 -221.056899) (xy 88.780334 -221.007659)
			(xy 88.80384 -220.961527) (xy 88.834272 -220.91964) (xy 88.870882 -220.88303) (xy 88.912769 -220.852598)
			(xy 88.958901 -220.829092) (xy 89.008141 -220.813093) (xy 89.059279 -220.804994) (xy 89.111053 -220.804994)
			(xy 89.162191 -220.813093) (xy 89.211431 -220.829092) (xy 89.257563 -220.852598) (xy 89.29945 -220.88303)
			(xy 89.33606 -220.91964) (xy 89.366492 -220.961527) (xy 89.389998 -221.007659) (xy 89.405997 -221.056899)
			(xy 89.414096 -221.108037) (xy 89.414604 -221.133924) (xy 89.695528 -221.133924) (xy 89.69601 -221.108589)
			(xy 89.70376 -221.058515) (xy 89.71908 -221.010217) (xy 89.741611 -220.964832) (xy 89.770821 -220.923429)
			(xy 89.806022 -220.886984) (xy 89.846386 -220.856354) (xy 89.890961 -220.83226) (xy 89.938698 -220.815272)
			(xy 89.963498 -220.810074) (xy 89.986358 -220.805756) (xy 90.191336 -220.450664) (xy 90.183462 -220.42882)
			(xy 90.174829 -220.402408) (xy 90.1655 -220.347635) (xy 90.16492 -220.319854) (xy 90.165428 -220.293947)
			(xy 90.173534 -220.24277) (xy 90.189546 -220.193491) (xy 90.213069 -220.147324) (xy 90.243525 -220.105405)
			(xy 90.280163 -220.068767) (xy 90.322082 -220.038311) (xy 90.368249 -220.014788) (xy 90.417528 -219.998776)
			(xy 90.468705 -219.99067) (xy 90.520519 -219.99067) (xy 90.571696 -219.998776) (xy 90.620975 -220.014788)
			(xy 90.667142 -220.038311) (xy 90.709061 -220.068767) (xy 90.745699 -220.105405) (xy 90.776155 -220.147324)
			(xy 90.799678 -220.193491) (xy 90.81569 -220.24277) (xy 90.823796 -220.293947) (xy 90.824304 -220.319854)
			(xy 90.823828 -220.345199) (xy 90.816049 -220.395289) (xy 90.800697 -220.443599) (xy 90.778134 -220.48899)
			(xy 90.748891 -220.530396) (xy 90.713657 -220.566839) (xy 90.673262 -220.597461) (xy 90.628657 -220.621543)
			(xy 90.580893 -220.638516) (xy 90.55608 -220.643704) (xy 90.53322 -220.648022) (xy 90.328242 -221.003114)
			(xy 90.336116 -221.024958) (xy 90.34471 -221.051373) (xy 90.353897 -221.106151) (xy 90.354404 -221.133924)
			(xy 90.635328 -221.133924) (xy 90.635836 -221.108037) (xy 90.643935 -221.056899) (xy 90.659934 -221.007659)
			(xy 90.68344 -220.961527) (xy 90.713872 -220.91964) (xy 90.750482 -220.88303) (xy 90.792369 -220.852598)
			(xy 90.838501 -220.829092) (xy 90.887741 -220.813093) (xy 90.938879 -220.804994) (xy 90.990653 -220.804994)
			(xy 91.041791 -220.813093) (xy 91.091031 -220.829092) (xy 91.137163 -220.852598) (xy 91.17905 -220.88303)
			(xy 91.21566 -220.91964) (xy 91.246092 -220.961527) (xy 91.269598 -221.007659) (xy 91.285597 -221.056899)
			(xy 91.293696 -221.108037) (xy 91.294204 -221.133924) (xy 91.575128 -221.133924) (xy 91.57561 -221.108589)
			(xy 91.58336 -221.058515) (xy 91.59868 -221.010217) (xy 91.621211 -220.964832) (xy 91.650421 -220.923429)
			(xy 91.685622 -220.886984) (xy 91.725986 -220.856354) (xy 91.770561 -220.83226) (xy 91.818298 -220.815272)
			(xy 91.843098 -220.810074) (xy 91.865958 -220.805756) (xy 92.070936 -220.450664) (xy 92.063062 -220.42882)
			(xy 92.054429 -220.402408) (xy 92.0451 -220.347635) (xy 92.04452 -220.319854) (xy 92.045028 -220.293947)
			(xy 92.053134 -220.24277) (xy 92.069146 -220.193491) (xy 92.092669 -220.147324) (xy 92.123125 -220.105405)
			(xy 92.159763 -220.068767) (xy 92.201682 -220.038311) (xy 92.247849 -220.014788) (xy 92.297128 -219.998776)
			(xy 92.348305 -219.99067) (xy 92.400119 -219.99067) (xy 92.451296 -219.998776) (xy 92.500575 -220.014788)
			(xy 92.546742 -220.038311) (xy 92.588661 -220.068767) (xy 92.625299 -220.105405) (xy 92.655755 -220.147324)
			(xy 92.679278 -220.193491) (xy 92.69529 -220.24277) (xy 92.703396 -220.293947) (xy 92.703904 -220.319854)
			(xy 92.703428 -220.345199) (xy 92.695649 -220.395289) (xy 92.680297 -220.443599) (xy 92.657734 -220.48899)
			(xy 92.628491 -220.530396) (xy 92.593257 -220.566839) (xy 92.552862 -220.597461) (xy 92.508257 -220.621543)
			(xy 92.460493 -220.638516) (xy 92.43568 -220.643704) (xy 92.41282 -220.648022) (xy 92.207842 -221.003114)
			(xy 92.215716 -221.024958) (xy 92.22431 -221.051373) (xy 92.233497 -221.106151) (xy 92.234004 -221.133924)
			(xy 92.514928 -221.133924) (xy 92.515436 -221.108037) (xy 92.523535 -221.056899) (xy 92.539534 -221.007659)
			(xy 92.56304 -220.961527) (xy 92.593472 -220.91964) (xy 92.630082 -220.88303) (xy 92.671969 -220.852598)
			(xy 92.718101 -220.829092) (xy 92.767341 -220.813093) (xy 92.818479 -220.804994) (xy 92.870253 -220.804994)
			(xy 92.921391 -220.813093) (xy 92.970631 -220.829092) (xy 93.016763 -220.852598) (xy 93.05865 -220.88303)
			(xy 93.09526 -220.91964) (xy 93.125692 -220.961527) (xy 93.149198 -221.007659) (xy 93.165197 -221.056899)
			(xy 93.173296 -221.108037) (xy 93.173804 -221.133924) (xy 93.454728 -221.133924) (xy 93.45521 -221.108589)
			(xy 93.46296 -221.058515) (xy 93.47828 -221.010217) (xy 93.500811 -220.964832) (xy 93.530021 -220.923429)
			(xy 93.565222 -220.886984) (xy 93.605586 -220.856354) (xy 93.650161 -220.83226) (xy 93.697898 -220.815272)
			(xy 93.722698 -220.810074) (xy 93.745558 -220.805756) (xy 93.950536 -220.450664) (xy 93.942662 -220.42882)
			(xy 93.934029 -220.402408) (xy 93.9247 -220.347635) (xy 93.92412 -220.319854) (xy 93.924628 -220.293947)
			(xy 93.932734 -220.24277) (xy 93.948746 -220.193491) (xy 93.972269 -220.147324) (xy 94.002725 -220.105405)
			(xy 94.039363 -220.068767) (xy 94.081282 -220.038311) (xy 94.127449 -220.014788) (xy 94.176728 -219.998776)
			(xy 94.227905 -219.99067) (xy 94.279719 -219.99067) (xy 94.330896 -219.998776) (xy 94.380175 -220.014788)
			(xy 94.426342 -220.038311) (xy 94.468261 -220.068767) (xy 94.504899 -220.105405) (xy 94.535355 -220.147324)
			(xy 94.558878 -220.193491) (xy 94.57489 -220.24277) (xy 94.582996 -220.293947) (xy 94.583504 -220.319854)
			(xy 94.583028 -220.345199) (xy 94.575249 -220.395289) (xy 94.559897 -220.443599) (xy 94.537334 -220.48899)
			(xy 94.508091 -220.530396) (xy 94.472857 -220.566839) (xy 94.432462 -220.597461) (xy 94.387857 -220.621543)
			(xy 94.340093 -220.638516) (xy 94.31528 -220.643704) (xy 94.29242 -220.648022) (xy 94.087442 -221.003114)
			(xy 94.095316 -221.024958) (xy 94.10391 -221.051373) (xy 94.113097 -221.106151) (xy 94.113604 -221.133924)
			(xy 94.394528 -221.133924) (xy 94.395036 -221.108037) (xy 94.403135 -221.056899) (xy 94.419134 -221.007659)
			(xy 94.44264 -220.961527) (xy 94.473072 -220.91964) (xy 94.509682 -220.88303) (xy 94.551569 -220.852598)
			(xy 94.597701 -220.829092) (xy 94.646941 -220.813093) (xy 94.698079 -220.804994) (xy 94.749853 -220.804994)
			(xy 94.800991 -220.813093) (xy 94.850231 -220.829092) (xy 94.896363 -220.852598) (xy 94.93825 -220.88303)
			(xy 94.97486 -220.91964) (xy 95.005292 -220.961527) (xy 95.028798 -221.007659) (xy 95.044797 -221.056899)
			(xy 95.052896 -221.108037) (xy 95.053404 -221.133924) (xy 95.334328 -221.133924) (xy 95.33481 -221.108589)
			(xy 95.34256 -221.058515) (xy 95.35788 -221.010217) (xy 95.380411 -220.964832) (xy 95.409621 -220.923429)
			(xy 95.444822 -220.886984) (xy 95.485186 -220.856354) (xy 95.529761 -220.83226) (xy 95.577498 -220.815272)
			(xy 95.602298 -220.810074) (xy 95.625158 -220.805756) (xy 95.830136 -220.450664) (xy 95.822262 -220.42882)
			(xy 95.813629 -220.402408) (xy 95.8043 -220.347635) (xy 95.80372 -220.319854) (xy 95.804228 -220.293947)
			(xy 95.812334 -220.24277) (xy 95.828346 -220.193491) (xy 95.851869 -220.147324) (xy 95.882325 -220.105405)
			(xy 95.918963 -220.068767) (xy 95.960882 -220.038311) (xy 96.007049 -220.014788) (xy 96.056328 -219.998776)
			(xy 96.107505 -219.99067) (xy 96.159319 -219.99067) (xy 96.210496 -219.998776) (xy 96.259775 -220.014788)
			(xy 96.305942 -220.038311) (xy 96.347861 -220.068767) (xy 96.384499 -220.105405) (xy 96.414955 -220.147324)
			(xy 96.438478 -220.193491) (xy 96.45449 -220.24277) (xy 96.462596 -220.293947) (xy 96.463104 -220.319854)
			(xy 96.462628 -220.345199) (xy 96.454849 -220.395289) (xy 96.439497 -220.443599) (xy 96.416934 -220.48899)
			(xy 96.387691 -220.530396) (xy 96.352457 -220.566839) (xy 96.312062 -220.597461) (xy 96.267457 -220.621543)
			(xy 96.219693 -220.638516) (xy 96.19488 -220.643704) (xy 96.17202 -220.648022) (xy 95.967042 -221.003114)
			(xy 95.974916 -221.024958) (xy 95.98351 -221.051373) (xy 95.992697 -221.106151) (xy 95.993204 -221.133924)
			(xy 96.274128 -221.133924) (xy 96.274636 -221.108037) (xy 96.282735 -221.056899) (xy 96.298734 -221.007659)
			(xy 96.32224 -220.961527) (xy 96.352672 -220.91964) (xy 96.389282 -220.88303) (xy 96.431169 -220.852598)
			(xy 96.477301 -220.829092) (xy 96.526541 -220.813093) (xy 96.577679 -220.804994) (xy 96.629453 -220.804994)
			(xy 96.680591 -220.813093) (xy 96.729831 -220.829092) (xy 96.775963 -220.852598) (xy 96.81785 -220.88303)
			(xy 96.85446 -220.91964) (xy 96.884892 -220.961527) (xy 96.908398 -221.007659) (xy 96.924397 -221.056899)
			(xy 96.932496 -221.108037) (xy 96.933004 -221.133924) (xy 97.213928 -221.133924) (xy 97.21441 -221.108589)
			(xy 97.22216 -221.058515) (xy 97.23748 -221.010217) (xy 97.260011 -220.964832) (xy 97.289221 -220.923429)
			(xy 97.324422 -220.886984) (xy 97.364786 -220.856354) (xy 97.409361 -220.83226) (xy 97.457098 -220.815272)
			(xy 97.481898 -220.810074) (xy 97.504758 -220.805756) (xy 97.709736 -220.450664) (xy 97.701862 -220.42882)
			(xy 97.693229 -220.402408) (xy 97.6839 -220.347635) (xy 97.68332 -220.319854) (xy 97.683828 -220.293947)
			(xy 97.691934 -220.24277) (xy 97.707946 -220.193491) (xy 97.731469 -220.147324) (xy 97.761925 -220.105405)
			(xy 97.798563 -220.068767) (xy 97.840482 -220.038311) (xy 97.886649 -220.014788) (xy 97.935928 -219.998776)
			(xy 97.987105 -219.99067) (xy 98.038919 -219.99067) (xy 98.090096 -219.998776) (xy 98.139375 -220.014788)
			(xy 98.185542 -220.038311) (xy 98.227461 -220.068767) (xy 98.264099 -220.105405) (xy 98.294555 -220.147324)
			(xy 98.318078 -220.193491) (xy 98.33409 -220.24277) (xy 98.342196 -220.293947) (xy 98.342704 -220.319854)
			(xy 98.342228 -220.345199) (xy 98.334449 -220.395289) (xy 98.319097 -220.443599) (xy 98.296534 -220.48899)
			(xy 98.267291 -220.530396) (xy 98.232057 -220.566839) (xy 98.191662 -220.597461) (xy 98.147057 -220.621543)
			(xy 98.099293 -220.638516) (xy 98.07448 -220.643704) (xy 98.05162 -220.648022) (xy 97.846642 -221.003114)
			(xy 97.854516 -221.024958) (xy 97.86311 -221.051373) (xy 97.872297 -221.106151) (xy 97.872804 -221.133924)
			(xy 98.153728 -221.133924) (xy 98.154236 -221.108037) (xy 98.162335 -221.056899) (xy 98.178334 -221.007659)
			(xy 98.20184 -220.961527) (xy 98.232272 -220.91964) (xy 98.268882 -220.88303) (xy 98.310769 -220.852598)
			(xy 98.356901 -220.829092) (xy 98.406141 -220.813093) (xy 98.457279 -220.804994) (xy 98.509053 -220.804994)
			(xy 98.560191 -220.813093) (xy 98.609431 -220.829092) (xy 98.655563 -220.852598) (xy 98.69745 -220.88303)
			(xy 98.73406 -220.91964) (xy 98.764492 -220.961527) (xy 98.787998 -221.007659) (xy 98.803997 -221.056899)
			(xy 98.812096 -221.108037) (xy 98.812604 -221.133924) (xy 99.093528 -221.133924) (xy 99.09401 -221.108589)
			(xy 99.10176 -221.058515) (xy 99.11708 -221.010217) (xy 99.139611 -220.964832) (xy 99.168821 -220.923429)
			(xy 99.204022 -220.886984) (xy 99.244386 -220.856354) (xy 99.288961 -220.83226) (xy 99.336698 -220.815272)
			(xy 99.361498 -220.810074) (xy 99.384358 -220.805756) (xy 99.589336 -220.450664) (xy 99.581462 -220.42882)
			(xy 99.572829 -220.402408) (xy 99.5635 -220.347635) (xy 99.56292 -220.319854) (xy 99.563428 -220.293947)
			(xy 99.571534 -220.24277) (xy 99.587546 -220.193491) (xy 99.611069 -220.147324) (xy 99.641525 -220.105405)
			(xy 99.678163 -220.068767) (xy 99.720082 -220.038311) (xy 99.766249 -220.014788) (xy 99.815528 -219.998776)
			(xy 99.866705 -219.99067) (xy 99.918519 -219.99067) (xy 99.969696 -219.998776) (xy 100.018975 -220.014788)
			(xy 100.065142 -220.038311) (xy 100.107061 -220.068767) (xy 100.143699 -220.105405) (xy 100.174155 -220.147324)
			(xy 100.197678 -220.193491) (xy 100.21369 -220.24277) (xy 100.221796 -220.293947) (xy 100.222304 -220.319854)
			(xy 100.221828 -220.345199) (xy 100.214049 -220.395289) (xy 100.198697 -220.443599) (xy 100.176134 -220.48899)
			(xy 100.146891 -220.530396) (xy 100.111657 -220.566839) (xy 100.071262 -220.597461) (xy 100.026657 -220.621543)
			(xy 99.978893 -220.638516) (xy 99.95408 -220.643704) (xy 99.93122 -220.648022) (xy 99.726242 -221.003114)
			(xy 99.734116 -221.024958) (xy 99.74271 -221.051373) (xy 99.751897 -221.106151) (xy 99.752404 -221.133924)
			(xy 100.033328 -221.133924) (xy 100.033836 -221.108037) (xy 100.041935 -221.056899) (xy 100.057934 -221.007659)
			(xy 100.08144 -220.961527) (xy 100.111872 -220.91964) (xy 100.148482 -220.88303) (xy 100.190369 -220.852598)
			(xy 100.236501 -220.829092) (xy 100.285741 -220.813093) (xy 100.336879 -220.804994) (xy 100.388653 -220.804994)
			(xy 100.439791 -220.813093) (xy 100.489031 -220.829092) (xy 100.535163 -220.852598) (xy 100.57705 -220.88303)
			(xy 100.61366 -220.91964) (xy 100.644092 -220.961527) (xy 100.667598 -221.007659) (xy 100.683597 -221.056899)
			(xy 100.691696 -221.108037) (xy 100.692204 -221.133924) (xy 100.973128 -221.133924) (xy 100.97361 -221.108589)
			(xy 100.98136 -221.058515) (xy 100.99668 -221.010217) (xy 101.019211 -220.964832) (xy 101.048421 -220.923429)
			(xy 101.083622 -220.886984) (xy 101.123986 -220.856354) (xy 101.168561 -220.83226) (xy 101.216298 -220.815272)
			(xy 101.241098 -220.810074) (xy 101.263958 -220.805756) (xy 101.468936 -220.450664) (xy 101.461062 -220.42882)
			(xy 101.452429 -220.402408) (xy 101.4431 -220.347635) (xy 101.44252 -220.319854) (xy 101.443028 -220.293947)
			(xy 101.451134 -220.24277) (xy 101.467146 -220.193491) (xy 101.490669 -220.147324) (xy 101.521125 -220.105405)
			(xy 101.557763 -220.068767) (xy 101.599682 -220.038311) (xy 101.645849 -220.014788) (xy 101.695128 -219.998776)
			(xy 101.746305 -219.99067) (xy 101.798119 -219.99067) (xy 101.849296 -219.998776) (xy 101.898575 -220.014788)
			(xy 101.944742 -220.038311) (xy 101.986661 -220.068767) (xy 102.023299 -220.105405) (xy 102.053755 -220.147324)
			(xy 102.077278 -220.193491) (xy 102.09329 -220.24277) (xy 102.101396 -220.293947) (xy 102.101904 -220.319854)
			(xy 102.101428 -220.345199) (xy 102.093649 -220.395289) (xy 102.078297 -220.443599) (xy 102.055734 -220.48899)
			(xy 102.026491 -220.530396) (xy 101.991257 -220.566839) (xy 101.950862 -220.597461) (xy 101.906257 -220.621543)
			(xy 101.858493 -220.638516) (xy 101.83368 -220.643704) (xy 101.81082 -220.648022) (xy 101.605842 -221.003114)
			(xy 101.613716 -221.024958) (xy 101.62231 -221.051373) (xy 101.631497 -221.106151) (xy 101.632004 -221.133924)
			(xy 101.912928 -221.133924) (xy 101.913436 -221.108037) (xy 101.921535 -221.056899) (xy 101.937534 -221.007659)
			(xy 101.96104 -220.961527) (xy 101.991472 -220.91964) (xy 102.028082 -220.88303) (xy 102.069969 -220.852598)
			(xy 102.116101 -220.829092) (xy 102.165341 -220.813093) (xy 102.216479 -220.804994) (xy 102.268253 -220.804994)
			(xy 102.319391 -220.813093) (xy 102.368631 -220.829092) (xy 102.414763 -220.852598) (xy 102.45665 -220.88303)
			(xy 102.49326 -220.91964) (xy 102.523692 -220.961527) (xy 102.547198 -221.007659) (xy 102.563197 -221.056899)
			(xy 102.571296 -221.108037) (xy 102.571804 -221.133924) (xy 102.852728 -221.133924) (xy 102.85321 -221.108589)
			(xy 102.86096 -221.058515) (xy 102.87628 -221.010217) (xy 102.898811 -220.964832) (xy 102.928021 -220.923429)
			(xy 102.963222 -220.886984) (xy 103.003586 -220.856354) (xy 103.048161 -220.83226) (xy 103.095898 -220.815272)
			(xy 103.120698 -220.810074) (xy 103.143558 -220.805756) (xy 103.348536 -220.450664) (xy 103.340662 -220.42882)
			(xy 103.332029 -220.402408) (xy 103.3227 -220.347635) (xy 103.32212 -220.319854) (xy 103.322628 -220.293947)
			(xy 103.330734 -220.24277) (xy 103.346746 -220.193491) (xy 103.370269 -220.147324) (xy 103.400725 -220.105405)
			(xy 103.437363 -220.068767) (xy 103.479282 -220.038311) (xy 103.525449 -220.014788) (xy 103.574728 -219.998776)
			(xy 103.625905 -219.99067) (xy 103.677719 -219.99067) (xy 103.728896 -219.998776) (xy 103.778175 -220.014788)
			(xy 103.824342 -220.038311) (xy 103.866261 -220.068767) (xy 103.902899 -220.105405) (xy 103.933355 -220.147324)
			(xy 103.956878 -220.193491) (xy 103.97289 -220.24277) (xy 103.980996 -220.293947) (xy 103.981504 -220.319854)
			(xy 105.20172 -220.319854) (xy 105.202228 -220.293947) (xy 105.210334 -220.24277) (xy 105.226346 -220.193491)
			(xy 105.249869 -220.147324) (xy 105.280325 -220.105405) (xy 105.316963 -220.068767) (xy 105.358882 -220.038311)
			(xy 105.405049 -220.014788) (xy 105.454328 -219.998776) (xy 105.505505 -219.99067) (xy 105.557319 -219.99067)
			(xy 105.608496 -219.998776) (xy 105.657775 -220.014788) (xy 105.703942 -220.038311) (xy 105.745861 -220.068767)
			(xy 105.782499 -220.105405) (xy 105.812955 -220.147324) (xy 105.836478 -220.193491) (xy 105.85249 -220.24277)
			(xy 105.860596 -220.293947) (xy 105.861104 -220.319854) (xy 107.08132 -220.319854) (xy 107.081828 -220.293947)
			(xy 107.089934 -220.24277) (xy 107.105946 -220.193491) (xy 107.129469 -220.147324) (xy 107.159925 -220.105405)
			(xy 107.196563 -220.068767) (xy 107.238482 -220.038311) (xy 107.284649 -220.014788) (xy 107.333928 -219.998776)
			(xy 107.385105 -219.99067) (xy 107.436919 -219.99067) (xy 107.488096 -219.998776) (xy 107.537375 -220.014788)
			(xy 107.583542 -220.038311) (xy 107.625461 -220.068767) (xy 107.662099 -220.105405) (xy 107.692555 -220.147324)
			(xy 107.716078 -220.193491) (xy 107.73209 -220.24277) (xy 107.740196 -220.293947) (xy 107.740704 -220.319854)
			(xy 108.96092 -220.319854) (xy 108.961428 -220.293947) (xy 108.969534 -220.24277) (xy 108.985546 -220.193491)
			(xy 109.009069 -220.147324) (xy 109.039525 -220.105405) (xy 109.076163 -220.068767) (xy 109.118082 -220.038311)
			(xy 109.164249 -220.014788) (xy 109.213528 -219.998776) (xy 109.264705 -219.99067) (xy 109.316519 -219.99067)
			(xy 109.367696 -219.998776) (xy 109.416975 -220.014788) (xy 109.463142 -220.038311) (xy 109.505061 -220.068767)
			(xy 109.541699 -220.105405) (xy 109.572155 -220.147324) (xy 109.595678 -220.193491) (xy 109.61169 -220.24277)
			(xy 109.619796 -220.293947) (xy 109.620304 -220.319854) (xy 110.84052 -220.319854) (xy 110.841028 -220.293947)
			(xy 110.849134 -220.24277) (xy 110.865146 -220.193491) (xy 110.888669 -220.147324) (xy 110.919125 -220.105405)
			(xy 110.955763 -220.068767) (xy 110.997682 -220.038311) (xy 111.043849 -220.014788) (xy 111.093128 -219.998776)
			(xy 111.144305 -219.99067) (xy 111.196119 -219.99067) (xy 111.247296 -219.998776) (xy 111.296575 -220.014788)
			(xy 111.342742 -220.038311) (xy 111.384661 -220.068767) (xy 111.421299 -220.105405) (xy 111.451755 -220.147324)
			(xy 111.475278 -220.193491) (xy 111.49129 -220.24277) (xy 111.499396 -220.293947) (xy 111.499904 -220.319854)
			(xy 112.72012 -220.319854) (xy 112.720628 -220.293947) (xy 112.728734 -220.24277) (xy 112.744746 -220.193491)
			(xy 112.768269 -220.147324) (xy 112.798725 -220.105405) (xy 112.835363 -220.068767) (xy 112.877282 -220.038311)
			(xy 112.923449 -220.014788) (xy 112.972728 -219.998776) (xy 113.023905 -219.99067) (xy 113.075719 -219.99067)
			(xy 113.126896 -219.998776) (xy 113.176175 -220.014788) (xy 113.222342 -220.038311) (xy 113.264261 -220.068767)
			(xy 113.300899 -220.105405) (xy 113.331355 -220.147324) (xy 113.354878 -220.193491) (xy 113.37089 -220.24277)
			(xy 113.378996 -220.293947) (xy 113.379504 -220.319854) (xy 114.59972 -220.319854) (xy 114.600228 -220.293947)
			(xy 114.608334 -220.24277) (xy 114.624346 -220.193491) (xy 114.647869 -220.147324) (xy 114.678325 -220.105405)
			(xy 114.714963 -220.068767) (xy 114.756882 -220.038311) (xy 114.803049 -220.014788) (xy 114.852328 -219.998776)
			(xy 114.903505 -219.99067) (xy 114.955319 -219.99067) (xy 115.006496 -219.998776) (xy 115.055775 -220.014788)
			(xy 115.101942 -220.038311) (xy 115.143861 -220.068767) (xy 115.180499 -220.105405) (xy 115.210955 -220.147324)
			(xy 115.234478 -220.193491) (xy 115.25049 -220.24277) (xy 115.258596 -220.293947) (xy 115.259104 -220.319854)
			(xy 116.47932 -220.319854) (xy 116.479828 -220.293947) (xy 116.487934 -220.24277) (xy 116.503946 -220.193491)
			(xy 116.527469 -220.147324) (xy 116.557925 -220.105405) (xy 116.594563 -220.068767) (xy 116.636482 -220.038311)
			(xy 116.682649 -220.014788) (xy 116.731928 -219.998776) (xy 116.783105 -219.99067) (xy 116.834919 -219.99067)
			(xy 116.886096 -219.998776) (xy 116.935375 -220.014788) (xy 116.981542 -220.038311) (xy 117.023461 -220.068767)
			(xy 117.060099 -220.105405) (xy 117.090555 -220.147324) (xy 117.114078 -220.193491) (xy 117.13009 -220.24277)
			(xy 117.138196 -220.293947) (xy 117.138704 -220.319854) (xy 118.35892 -220.319854) (xy 118.359428 -220.293947)
			(xy 118.367534 -220.24277) (xy 118.383546 -220.193491) (xy 118.407069 -220.147324) (xy 118.437525 -220.105405)
			(xy 118.474163 -220.068767) (xy 118.516082 -220.038311) (xy 118.562249 -220.014788) (xy 118.611528 -219.998776)
			(xy 118.662705 -219.99067) (xy 118.714519 -219.99067) (xy 118.765696 -219.998776) (xy 118.814975 -220.014788)
			(xy 118.861142 -220.038311) (xy 118.903061 -220.068767) (xy 118.939699 -220.105405) (xy 118.970155 -220.147324)
			(xy 118.993678 -220.193491) (xy 119.00969 -220.24277) (xy 119.017796 -220.293947) (xy 119.018304 -220.319854)
			(xy 120.23852 -220.319854) (xy 120.239028 -220.293947) (xy 120.247134 -220.24277) (xy 120.263146 -220.193491)
			(xy 120.286669 -220.147324) (xy 120.317125 -220.105405) (xy 120.353763 -220.068767) (xy 120.395682 -220.038311)
			(xy 120.441849 -220.014788) (xy 120.491128 -219.998776) (xy 120.542305 -219.99067) (xy 120.594119 -219.99067)
			(xy 120.645296 -219.998776) (xy 120.694575 -220.014788) (xy 120.740742 -220.038311) (xy 120.782661 -220.068767)
			(xy 120.819299 -220.105405) (xy 120.849755 -220.147324) (xy 120.873278 -220.193491) (xy 120.88929 -220.24277)
			(xy 120.897396 -220.293947) (xy 120.897904 -220.319854) (xy 122.11812 -220.319854) (xy 122.118628 -220.293947)
			(xy 122.126734 -220.24277) (xy 122.142746 -220.193491) (xy 122.166269 -220.147324) (xy 122.196725 -220.105405)
			(xy 122.233363 -220.068767) (xy 122.275282 -220.038311) (xy 122.321449 -220.014788) (xy 122.370728 -219.998776)
			(xy 122.421905 -219.99067) (xy 122.473719 -219.99067) (xy 122.524896 -219.998776) (xy 122.574175 -220.014788)
			(xy 122.620342 -220.038311) (xy 122.662261 -220.068767) (xy 122.698899 -220.105405) (xy 122.729355 -220.147324)
			(xy 122.752878 -220.193491) (xy 122.76889 -220.24277) (xy 122.776996 -220.293947) (xy 122.777504 -220.319854)
			(xy 123.99772 -220.319854) (xy 123.998228 -220.293947) (xy 124.006334 -220.24277) (xy 124.022346 -220.193491)
			(xy 124.045869 -220.147324) (xy 124.076325 -220.105405) (xy 124.112963 -220.068767) (xy 124.154882 -220.038311)
			(xy 124.201049 -220.014788) (xy 124.250328 -219.998776) (xy 124.301505 -219.99067) (xy 124.353319 -219.99067)
			(xy 124.404496 -219.998776) (xy 124.453775 -220.014788) (xy 124.499942 -220.038311) (xy 124.541861 -220.068767)
			(xy 124.578499 -220.105405) (xy 124.608955 -220.147324) (xy 124.632478 -220.193491) (xy 124.64849 -220.24277)
			(xy 124.656596 -220.293947) (xy 124.657104 -220.319854) (xy 125.87732 -220.319854) (xy 125.877828 -220.293947)
			(xy 125.885934 -220.24277) (xy 125.901946 -220.193491) (xy 125.925469 -220.147324) (xy 125.955925 -220.105405)
			(xy 125.992563 -220.068767) (xy 126.034482 -220.038311) (xy 126.080649 -220.014788) (xy 126.129928 -219.998776)
			(xy 126.181105 -219.99067) (xy 126.232919 -219.99067) (xy 126.284096 -219.998776) (xy 126.333375 -220.014788)
			(xy 126.379542 -220.038311) (xy 126.421461 -220.068767) (xy 126.458099 -220.105405) (xy 126.488555 -220.147324)
			(xy 126.512078 -220.193491) (xy 126.52809 -220.24277) (xy 126.536196 -220.293947) (xy 126.536704 -220.319854)
			(xy 127.75692 -220.319854) (xy 127.757428 -220.293947) (xy 127.765534 -220.24277) (xy 127.781546 -220.193491)
			(xy 127.805069 -220.147324) (xy 127.835525 -220.105405) (xy 127.872163 -220.068767) (xy 127.914082 -220.038311)
			(xy 127.960249 -220.014788) (xy 128.009528 -219.998776) (xy 128.060705 -219.99067) (xy 128.112519 -219.99067)
			(xy 128.163696 -219.998776) (xy 128.212975 -220.014788) (xy 128.259142 -220.038311) (xy 128.301061 -220.068767)
			(xy 128.337699 -220.105405) (xy 128.368155 -220.147324) (xy 128.391678 -220.193491) (xy 128.40769 -220.24277)
			(xy 128.415796 -220.293947) (xy 128.416304 -220.319854) (xy 129.63652 -220.319854) (xy 129.637028 -220.293947)
			(xy 129.645134 -220.24277) (xy 129.661146 -220.193491) (xy 129.684669 -220.147324) (xy 129.715125 -220.105405)
			(xy 129.751763 -220.068767) (xy 129.793682 -220.038311) (xy 129.839849 -220.014788) (xy 129.889128 -219.998776)
			(xy 129.940305 -219.99067) (xy 129.992119 -219.99067) (xy 130.043296 -219.998776) (xy 130.092575 -220.014788)
			(xy 130.138742 -220.038311) (xy 130.180661 -220.068767) (xy 130.217299 -220.105405) (xy 130.247755 -220.147324)
			(xy 130.271278 -220.193491) (xy 130.28729 -220.24277) (xy 130.295396 -220.293947) (xy 130.295904 -220.319854)
			(xy 131.51612 -220.319854) (xy 131.516628 -220.293947) (xy 131.524734 -220.24277) (xy 131.540746 -220.193491)
			(xy 131.564269 -220.147324) (xy 131.594725 -220.105405) (xy 131.631363 -220.068767) (xy 131.673282 -220.038311)
			(xy 131.719449 -220.014788) (xy 131.768728 -219.998776) (xy 131.819905 -219.99067) (xy 131.871719 -219.99067)
			(xy 131.922896 -219.998776) (xy 131.972175 -220.014788) (xy 132.018342 -220.038311) (xy 132.060261 -220.068767)
			(xy 132.096899 -220.105405) (xy 132.127355 -220.147324) (xy 132.150878 -220.193491) (xy 132.16689 -220.24277)
			(xy 132.174996 -220.293947) (xy 132.175504 -220.319854) (xy 133.396228 -220.319854) (xy 133.396736 -220.293967)
			(xy 133.404835 -220.242829) (xy 133.420834 -220.193589) (xy 133.44434 -220.147457) (xy 133.474772 -220.10557)
			(xy 133.511382 -220.06896) (xy 133.553269 -220.038528) (xy 133.599401 -220.015022) (xy 133.648641 -219.999023)
			(xy 133.699779 -219.990924) (xy 133.751553 -219.990924) (xy 133.802691 -219.999023) (xy 133.851931 -220.015022)
			(xy 133.898063 -220.038528) (xy 133.93995 -220.06896) (xy 133.97656 -220.10557) (xy 134.006992 -220.147457)
			(xy 134.030498 -220.193589) (xy 134.046497 -220.242829) (xy 134.054596 -220.293967) (xy 134.055104 -220.319854)
			(xy 134.054563 -220.347562) (xy 134.045375 -220.402208) (xy 134.036816 -220.428566) (xy 134.029196 -220.450664)
			(xy 134.234174 -220.805756) (xy 134.257034 -220.810074) (xy 134.281845 -220.815229) (xy 134.329584 -220.832223)
			(xy 134.374162 -220.856322) (xy 134.414527 -220.886957) (xy 134.44973 -220.923408) (xy 134.47894 -220.964816)
			(xy 134.501472 -221.010206) (xy 134.516792 -221.058509) (xy 134.524542 -221.108587) (xy 134.525004 -221.133924)
			(xy 134.524496 -221.159811) (xy 134.516397 -221.210949) (xy 134.500398 -221.260189) (xy 134.476892 -221.306321)
			(xy 134.44646 -221.348208) (xy 134.40985 -221.384818) (xy 134.367963 -221.41525) (xy 134.321831 -221.438756)
			(xy 134.272591 -221.454755) (xy 134.221453 -221.462854) (xy 134.169679 -221.462854) (xy 134.118541 -221.454755)
			(xy 134.069301 -221.438756) (xy 134.023169 -221.41525) (xy 133.981282 -221.384818) (xy 133.944672 -221.348208)
			(xy 133.91424 -221.306321) (xy 133.890734 -221.260189) (xy 133.874735 -221.210949) (xy 133.866636 -221.159811)
			(xy 133.866128 -221.133924) (xy 133.866667 -221.106216) (xy 133.875856 -221.05157) (xy 133.884416 -221.025212)
			(xy 133.89229 -221.003114) (xy 133.687312 -220.648022) (xy 133.664452 -220.643704) (xy 133.639631 -220.638536)
			(xy 133.591852 -220.621582) (xy 133.547233 -220.59751) (xy 133.506826 -220.56689) (xy 133.471585 -220.530444)
			(xy 133.442341 -220.48903) (xy 133.419784 -220.443627) (xy 133.404447 -220.395304) (xy 133.39669 -220.345203)
			(xy 133.396228 -220.319854) (xy 132.175504 -220.319854) (xy 132.174894 -220.347507) (xy 132.165571 -220.402025)
			(xy 132.156962 -220.428312) (xy 132.149342 -220.45041) (xy 132.354574 -220.805756) (xy 132.377434 -220.810074)
			(xy 132.402245 -220.815229) (xy 132.449984 -220.832223) (xy 132.494562 -220.856322) (xy 132.534927 -220.886957)
			(xy 132.57013 -220.923408) (xy 132.59934 -220.964816) (xy 132.621872 -221.010206) (xy 132.637192 -221.058509)
			(xy 132.644942 -221.108587) (xy 132.645404 -221.133924) (xy 132.644896 -221.159811) (xy 132.636797 -221.210949)
			(xy 132.620798 -221.260189) (xy 132.597292 -221.306321) (xy 132.56686 -221.348208) (xy 132.53025 -221.384818)
			(xy 132.488363 -221.41525) (xy 132.442231 -221.438756) (xy 132.392991 -221.454755) (xy 132.341853 -221.462854)
			(xy 132.290079 -221.462854) (xy 132.238941 -221.454755) (xy 132.189701 -221.438756) (xy 132.143569 -221.41525)
			(xy 132.101682 -221.384818) (xy 132.065072 -221.348208) (xy 132.03464 -221.306321) (xy 132.011134 -221.260189)
			(xy 131.995135 -221.210949) (xy 131.987036 -221.159811) (xy 131.986528 -221.133924) (xy 131.987067 -221.106216)
			(xy 131.996256 -221.05157) (xy 132.004816 -221.025212) (xy 132.01269 -221.003114) (xy 131.807712 -220.648022)
			(xy 131.784852 -220.643704) (xy 131.76 -220.63857) (xy 131.712153 -220.621668) (xy 131.667462 -220.597632)
			(xy 131.626984 -220.567029) (xy 131.591674 -220.530584) (xy 131.562368 -220.489157) (xy 131.539757 -220.443728)
			(xy 131.524377 -220.39537) (xy 131.516591 -220.345226) (xy 131.51612 -220.319854) (xy 130.295904 -220.319854)
			(xy 130.295294 -220.347507) (xy 130.285971 -220.402025) (xy 130.277362 -220.428312) (xy 130.269742 -220.45041)
			(xy 130.474974 -220.805756) (xy 130.497834 -220.810074) (xy 130.522645 -220.815229) (xy 130.570384 -220.832223)
			(xy 130.614962 -220.856322) (xy 130.655327 -220.886957) (xy 130.69053 -220.923408) (xy 130.71974 -220.964816)
			(xy 130.742272 -221.010206) (xy 130.757592 -221.058509) (xy 130.765342 -221.108587) (xy 130.765804 -221.133924)
			(xy 130.765296 -221.159811) (xy 130.757197 -221.210949) (xy 130.741198 -221.260189) (xy 130.717692 -221.306321)
			(xy 130.68726 -221.348208) (xy 130.65065 -221.384818) (xy 130.608763 -221.41525) (xy 130.562631 -221.438756)
			(xy 130.513391 -221.454755) (xy 130.462253 -221.462854) (xy 130.410479 -221.462854) (xy 130.359341 -221.454755)
			(xy 130.310101 -221.438756) (xy 130.263969 -221.41525) (xy 130.222082 -221.384818) (xy 130.185472 -221.348208)
			(xy 130.15504 -221.306321) (xy 130.131534 -221.260189) (xy 130.115535 -221.210949) (xy 130.107436 -221.159811)
			(xy 130.106928 -221.133924) (xy 130.107467 -221.106216) (xy 130.116656 -221.05157) (xy 130.125216 -221.025212)
			(xy 130.13309 -221.003114) (xy 129.928112 -220.648022) (xy 129.905252 -220.643704) (xy 129.8804 -220.63857)
			(xy 129.832553 -220.621668) (xy 129.787862 -220.597632) (xy 129.747384 -220.567029) (xy 129.712074 -220.530584)
			(xy 129.682768 -220.489157) (xy 129.660157 -220.443728) (xy 129.644777 -220.39537) (xy 129.636991 -220.345226)
			(xy 129.63652 -220.319854) (xy 128.416304 -220.319854) (xy 128.415694 -220.347507) (xy 128.406371 -220.402025)
			(xy 128.397762 -220.428312) (xy 128.390142 -220.45041) (xy 128.595374 -220.805756) (xy 128.618234 -220.810074)
			(xy 128.643045 -220.815229) (xy 128.690784 -220.832223) (xy 128.735362 -220.856322) (xy 128.775727 -220.886957)
			(xy 128.81093 -220.923408) (xy 128.84014 -220.964816) (xy 128.862672 -221.010206) (xy 128.877992 -221.058509)
			(xy 128.885742 -221.108587) (xy 128.886204 -221.133924) (xy 128.885696 -221.159811) (xy 128.877597 -221.210949)
			(xy 128.861598 -221.260189) (xy 128.838092 -221.306321) (xy 128.80766 -221.348208) (xy 128.77105 -221.384818)
			(xy 128.729163 -221.41525) (xy 128.683031 -221.438756) (xy 128.633791 -221.454755) (xy 128.582653 -221.462854)
			(xy 128.530879 -221.462854) (xy 128.479741 -221.454755) (xy 128.430501 -221.438756) (xy 128.384369 -221.41525)
			(xy 128.342482 -221.384818) (xy 128.305872 -221.348208) (xy 128.27544 -221.306321) (xy 128.251934 -221.260189)
			(xy 128.235935 -221.210949) (xy 128.227836 -221.159811) (xy 128.227328 -221.133924) (xy 128.227867 -221.106216)
			(xy 128.237056 -221.05157) (xy 128.245616 -221.025212) (xy 128.25349 -221.003114) (xy 128.048512 -220.648022)
			(xy 128.025652 -220.643704) (xy 128.0008 -220.63857) (xy 127.952953 -220.621668) (xy 127.908262 -220.597632)
			(xy 127.867784 -220.567029) (xy 127.832474 -220.530584) (xy 127.803168 -220.489157) (xy 127.780557 -220.443728)
			(xy 127.765177 -220.39537) (xy 127.757391 -220.345226) (xy 127.75692 -220.319854) (xy 126.536704 -220.319854)
			(xy 126.536094 -220.347507) (xy 126.526771 -220.402025) (xy 126.518162 -220.428312) (xy 126.510542 -220.45041)
			(xy 126.715774 -220.805756) (xy 126.738634 -220.810074) (xy 126.763445 -220.815229) (xy 126.811184 -220.832223)
			(xy 126.855762 -220.856322) (xy 126.896127 -220.886957) (xy 126.93133 -220.923408) (xy 126.96054 -220.964816)
			(xy 126.983072 -221.010206) (xy 126.998392 -221.058509) (xy 127.006142 -221.108587) (xy 127.006604 -221.133924)
			(xy 127.006096 -221.159811) (xy 126.997997 -221.210949) (xy 126.981998 -221.260189) (xy 126.958492 -221.306321)
			(xy 126.92806 -221.348208) (xy 126.89145 -221.384818) (xy 126.849563 -221.41525) (xy 126.803431 -221.438756)
			(xy 126.754191 -221.454755) (xy 126.703053 -221.462854) (xy 126.651279 -221.462854) (xy 126.600141 -221.454755)
			(xy 126.550901 -221.438756) (xy 126.504769 -221.41525) (xy 126.462882 -221.384818) (xy 126.426272 -221.348208)
			(xy 126.39584 -221.306321) (xy 126.372334 -221.260189) (xy 126.356335 -221.210949) (xy 126.348236 -221.159811)
			(xy 126.347728 -221.133924) (xy 126.348267 -221.106216) (xy 126.357456 -221.05157) (xy 126.366016 -221.025212)
			(xy 126.37389 -221.003114) (xy 126.168912 -220.648022) (xy 126.146052 -220.643704) (xy 126.1212 -220.63857)
			(xy 126.073353 -220.621668) (xy 126.028662 -220.597632) (xy 125.988184 -220.567029) (xy 125.952874 -220.530584)
			(xy 125.923568 -220.489157) (xy 125.900957 -220.443728) (xy 125.885577 -220.39537) (xy 125.877791 -220.345226)
			(xy 125.87732 -220.319854) (xy 124.657104 -220.319854) (xy 124.656494 -220.347507) (xy 124.647171 -220.402025)
			(xy 124.638562 -220.428312) (xy 124.630942 -220.45041) (xy 124.836174 -220.805756) (xy 124.859034 -220.810074)
			(xy 124.883845 -220.815229) (xy 124.931584 -220.832223) (xy 124.976162 -220.856322) (xy 125.016527 -220.886957)
			(xy 125.05173 -220.923408) (xy 125.08094 -220.964816) (xy 125.103472 -221.010206) (xy 125.118792 -221.058509)
			(xy 125.126542 -221.108587) (xy 125.127004 -221.133924) (xy 125.126496 -221.159811) (xy 125.118397 -221.210949)
			(xy 125.102398 -221.260189) (xy 125.078892 -221.306321) (xy 125.04846 -221.348208) (xy 125.01185 -221.384818)
			(xy 124.969963 -221.41525) (xy 124.923831 -221.438756) (xy 124.874591 -221.454755) (xy 124.823453 -221.462854)
			(xy 124.771679 -221.462854) (xy 124.720541 -221.454755) (xy 124.671301 -221.438756) (xy 124.625169 -221.41525)
			(xy 124.583282 -221.384818) (xy 124.546672 -221.348208) (xy 124.51624 -221.306321) (xy 124.492734 -221.260189)
			(xy 124.476735 -221.210949) (xy 124.468636 -221.159811) (xy 124.468128 -221.133924) (xy 124.468667 -221.106216)
			(xy 124.477856 -221.05157) (xy 124.486416 -221.025212) (xy 124.49429 -221.003114) (xy 124.289312 -220.648022)
			(xy 124.266452 -220.643704) (xy 124.2416 -220.63857) (xy 124.193753 -220.621668) (xy 124.149062 -220.597632)
			(xy 124.108584 -220.567029) (xy 124.073274 -220.530584) (xy 124.043968 -220.489157) (xy 124.021357 -220.443728)
			(xy 124.005977 -220.39537) (xy 123.998191 -220.345226) (xy 123.99772 -220.319854) (xy 122.777504 -220.319854)
			(xy 122.776894 -220.347507) (xy 122.767571 -220.402025) (xy 122.758962 -220.428312) (xy 122.751342 -220.45041)
			(xy 122.956574 -220.805756) (xy 122.979434 -220.810074) (xy 123.004245 -220.815229) (xy 123.051984 -220.832223)
			(xy 123.096562 -220.856322) (xy 123.136927 -220.886957) (xy 123.17213 -220.923408) (xy 123.20134 -220.964816)
			(xy 123.223872 -221.010206) (xy 123.239192 -221.058509) (xy 123.246942 -221.108587) (xy 123.247404 -221.133924)
			(xy 123.246896 -221.159811) (xy 123.238797 -221.210949) (xy 123.222798 -221.260189) (xy 123.199292 -221.306321)
			(xy 123.16886 -221.348208) (xy 123.13225 -221.384818) (xy 123.090363 -221.41525) (xy 123.044231 -221.438756)
			(xy 122.994991 -221.454755) (xy 122.943853 -221.462854) (xy 122.892079 -221.462854) (xy 122.840941 -221.454755)
			(xy 122.791701 -221.438756) (xy 122.745569 -221.41525) (xy 122.703682 -221.384818) (xy 122.667072 -221.348208)
			(xy 122.63664 -221.306321) (xy 122.613134 -221.260189) (xy 122.597135 -221.210949) (xy 122.589036 -221.159811)
			(xy 122.588528 -221.133924) (xy 122.589067 -221.106216) (xy 122.598256 -221.05157) (xy 122.606816 -221.025212)
			(xy 122.61469 -221.003114) (xy 122.409712 -220.648022) (xy 122.386852 -220.643704) (xy 122.362 -220.63857)
			(xy 122.314153 -220.621668) (xy 122.269462 -220.597632) (xy 122.228984 -220.567029) (xy 122.193674 -220.530584)
			(xy 122.164368 -220.489157) (xy 122.141757 -220.443728) (xy 122.126377 -220.39537) (xy 122.118591 -220.345226)
			(xy 122.11812 -220.319854) (xy 120.897904 -220.319854) (xy 120.897294 -220.347507) (xy 120.887971 -220.402025)
			(xy 120.879362 -220.428312) (xy 120.871742 -220.45041) (xy 121.076974 -220.805756) (xy 121.099834 -220.810074)
			(xy 121.124645 -220.815229) (xy 121.172384 -220.832223) (xy 121.216962 -220.856322) (xy 121.257327 -220.886957)
			(xy 121.29253 -220.923408) (xy 121.32174 -220.964816) (xy 121.344272 -221.010206) (xy 121.359592 -221.058509)
			(xy 121.367342 -221.108587) (xy 121.367804 -221.133924) (xy 121.367296 -221.159811) (xy 121.359197 -221.210949)
			(xy 121.343198 -221.260189) (xy 121.319692 -221.306321) (xy 121.28926 -221.348208) (xy 121.25265 -221.384818)
			(xy 121.210763 -221.41525) (xy 121.164631 -221.438756) (xy 121.115391 -221.454755) (xy 121.064253 -221.462854)
			(xy 121.012479 -221.462854) (xy 120.961341 -221.454755) (xy 120.912101 -221.438756) (xy 120.865969 -221.41525)
			(xy 120.824082 -221.384818) (xy 120.787472 -221.348208) (xy 120.75704 -221.306321) (xy 120.733534 -221.260189)
			(xy 120.717535 -221.210949) (xy 120.709436 -221.159811) (xy 120.708928 -221.133924) (xy 120.709467 -221.106216)
			(xy 120.718656 -221.05157) (xy 120.727216 -221.025212) (xy 120.73509 -221.003114) (xy 120.530112 -220.648022)
			(xy 120.507252 -220.643704) (xy 120.4824 -220.63857) (xy 120.434553 -220.621668) (xy 120.389862 -220.597632)
			(xy 120.349384 -220.567029) (xy 120.314074 -220.530584) (xy 120.284768 -220.489157) (xy 120.262157 -220.443728)
			(xy 120.246777 -220.39537) (xy 120.238991 -220.345226) (xy 120.23852 -220.319854) (xy 119.018304 -220.319854)
			(xy 119.017694 -220.347507) (xy 119.008371 -220.402025) (xy 118.999762 -220.428312) (xy 118.992142 -220.45041)
			(xy 119.197374 -220.805756) (xy 119.220234 -220.810074) (xy 119.245045 -220.815229) (xy 119.292784 -220.832223)
			(xy 119.337362 -220.856322) (xy 119.377727 -220.886957) (xy 119.41293 -220.923408) (xy 119.44214 -220.964816)
			(xy 119.464672 -221.010206) (xy 119.479992 -221.058509) (xy 119.487742 -221.108587) (xy 119.488204 -221.133924)
			(xy 119.487696 -221.159811) (xy 119.479597 -221.210949) (xy 119.463598 -221.260189) (xy 119.440092 -221.306321)
			(xy 119.40966 -221.348208) (xy 119.37305 -221.384818) (xy 119.331163 -221.41525) (xy 119.285031 -221.438756)
			(xy 119.235791 -221.454755) (xy 119.184653 -221.462854) (xy 119.132879 -221.462854) (xy 119.081741 -221.454755)
			(xy 119.032501 -221.438756) (xy 118.986369 -221.41525) (xy 118.944482 -221.384818) (xy 118.907872 -221.348208)
			(xy 118.87744 -221.306321) (xy 118.853934 -221.260189) (xy 118.837935 -221.210949) (xy 118.829836 -221.159811)
			(xy 118.829328 -221.133924) (xy 118.829867 -221.106216) (xy 118.839056 -221.05157) (xy 118.847616 -221.025212)
			(xy 118.85549 -221.003114) (xy 118.650512 -220.648022) (xy 118.627652 -220.643704) (xy 118.6028 -220.63857)
			(xy 118.554953 -220.621668) (xy 118.510262 -220.597632) (xy 118.469784 -220.567029) (xy 118.434474 -220.530584)
			(xy 118.405168 -220.489157) (xy 118.382557 -220.443728) (xy 118.367177 -220.39537) (xy 118.359391 -220.345226)
			(xy 118.35892 -220.319854) (xy 117.138704 -220.319854) (xy 117.138094 -220.347507) (xy 117.128771 -220.402025)
			(xy 117.120162 -220.428312) (xy 117.112542 -220.45041) (xy 117.317774 -220.805756) (xy 117.340634 -220.810074)
			(xy 117.365445 -220.815229) (xy 117.413184 -220.832223) (xy 117.457762 -220.856322) (xy 117.498127 -220.886957)
			(xy 117.53333 -220.923408) (xy 117.56254 -220.964816) (xy 117.585072 -221.010206) (xy 117.600392 -221.058509)
			(xy 117.608142 -221.108587) (xy 117.608604 -221.133924) (xy 117.608096 -221.159811) (xy 117.599997 -221.210949)
			(xy 117.583998 -221.260189) (xy 117.560492 -221.306321) (xy 117.53006 -221.348208) (xy 117.49345 -221.384818)
			(xy 117.451563 -221.41525) (xy 117.405431 -221.438756) (xy 117.356191 -221.454755) (xy 117.305053 -221.462854)
			(xy 117.253279 -221.462854) (xy 117.202141 -221.454755) (xy 117.152901 -221.438756) (xy 117.106769 -221.41525)
			(xy 117.064882 -221.384818) (xy 117.028272 -221.348208) (xy 116.99784 -221.306321) (xy 116.974334 -221.260189)
			(xy 116.958335 -221.210949) (xy 116.950236 -221.159811) (xy 116.949728 -221.133924) (xy 116.950267 -221.106216)
			(xy 116.959456 -221.05157) (xy 116.968016 -221.025212) (xy 116.97589 -221.003114) (xy 116.770912 -220.648022)
			(xy 116.748052 -220.643704) (xy 116.7232 -220.63857) (xy 116.675353 -220.621668) (xy 116.630662 -220.597632)
			(xy 116.590184 -220.567029) (xy 116.554874 -220.530584) (xy 116.525568 -220.489157) (xy 116.502957 -220.443728)
			(xy 116.487577 -220.39537) (xy 116.479791 -220.345226) (xy 116.47932 -220.319854) (xy 115.259104 -220.319854)
			(xy 115.258494 -220.347507) (xy 115.249171 -220.402025) (xy 115.240562 -220.428312) (xy 115.232942 -220.45041)
			(xy 115.438174 -220.805756) (xy 115.461034 -220.810074) (xy 115.485845 -220.815229) (xy 115.533584 -220.832223)
			(xy 115.578162 -220.856322) (xy 115.618527 -220.886957) (xy 115.65373 -220.923408) (xy 115.68294 -220.964816)
			(xy 115.705472 -221.010206) (xy 115.720792 -221.058509) (xy 115.728542 -221.108587) (xy 115.729004 -221.133924)
			(xy 115.728496 -221.159811) (xy 115.720397 -221.210949) (xy 115.704398 -221.260189) (xy 115.680892 -221.306321)
			(xy 115.65046 -221.348208) (xy 115.61385 -221.384818) (xy 115.571963 -221.41525) (xy 115.525831 -221.438756)
			(xy 115.476591 -221.454755) (xy 115.425453 -221.462854) (xy 115.373679 -221.462854) (xy 115.322541 -221.454755)
			(xy 115.273301 -221.438756) (xy 115.227169 -221.41525) (xy 115.185282 -221.384818) (xy 115.148672 -221.348208)
			(xy 115.11824 -221.306321) (xy 115.094734 -221.260189) (xy 115.078735 -221.210949) (xy 115.070636 -221.159811)
			(xy 115.070128 -221.133924) (xy 115.070667 -221.106216) (xy 115.079856 -221.05157) (xy 115.088416 -221.025212)
			(xy 115.09629 -221.003114) (xy 114.891312 -220.648022) (xy 114.868452 -220.643704) (xy 114.8436 -220.63857)
			(xy 114.795753 -220.621668) (xy 114.751062 -220.597632) (xy 114.710584 -220.567029) (xy 114.675274 -220.530584)
			(xy 114.645968 -220.489157) (xy 114.623357 -220.443728) (xy 114.607977 -220.39537) (xy 114.600191 -220.345226)
			(xy 114.59972 -220.319854) (xy 113.379504 -220.319854) (xy 113.378894 -220.347507) (xy 113.369571 -220.402025)
			(xy 113.360962 -220.428312) (xy 113.353342 -220.45041) (xy 113.558574 -220.805756) (xy 113.581434 -220.810074)
			(xy 113.606245 -220.815229) (xy 113.653984 -220.832223) (xy 113.698562 -220.856322) (xy 113.738927 -220.886957)
			(xy 113.77413 -220.923408) (xy 113.80334 -220.964816) (xy 113.825872 -221.010206) (xy 113.841192 -221.058509)
			(xy 113.848942 -221.108587) (xy 113.849404 -221.133924) (xy 113.848896 -221.159811) (xy 113.840797 -221.210949)
			(xy 113.824798 -221.260189) (xy 113.801292 -221.306321) (xy 113.77086 -221.348208) (xy 113.73425 -221.384818)
			(xy 113.692363 -221.41525) (xy 113.646231 -221.438756) (xy 113.596991 -221.454755) (xy 113.545853 -221.462854)
			(xy 113.494079 -221.462854) (xy 113.442941 -221.454755) (xy 113.393701 -221.438756) (xy 113.347569 -221.41525)
			(xy 113.305682 -221.384818) (xy 113.269072 -221.348208) (xy 113.23864 -221.306321) (xy 113.215134 -221.260189)
			(xy 113.199135 -221.210949) (xy 113.191036 -221.159811) (xy 113.190528 -221.133924) (xy 113.191067 -221.106216)
			(xy 113.200256 -221.05157) (xy 113.208816 -221.025212) (xy 113.21669 -221.003114) (xy 113.011712 -220.648022)
			(xy 112.988852 -220.643704) (xy 112.964 -220.63857) (xy 112.916153 -220.621668) (xy 112.871462 -220.597632)
			(xy 112.830984 -220.567029) (xy 112.795674 -220.530584) (xy 112.766368 -220.489157) (xy 112.743757 -220.443728)
			(xy 112.728377 -220.39537) (xy 112.720591 -220.345226) (xy 112.72012 -220.319854) (xy 111.499904 -220.319854)
			(xy 111.499294 -220.347507) (xy 111.489971 -220.402025) (xy 111.481362 -220.428312) (xy 111.473742 -220.45041)
			(xy 111.678974 -220.805756) (xy 111.701834 -220.810074) (xy 111.726645 -220.815229) (xy 111.774384 -220.832223)
			(xy 111.818962 -220.856322) (xy 111.859327 -220.886957) (xy 111.89453 -220.923408) (xy 111.92374 -220.964816)
			(xy 111.946272 -221.010206) (xy 111.961592 -221.058509) (xy 111.969342 -221.108587) (xy 111.969804 -221.133924)
			(xy 111.969296 -221.159811) (xy 111.961197 -221.210949) (xy 111.945198 -221.260189) (xy 111.921692 -221.306321)
			(xy 111.89126 -221.348208) (xy 111.85465 -221.384818) (xy 111.812763 -221.41525) (xy 111.766631 -221.438756)
			(xy 111.717391 -221.454755) (xy 111.666253 -221.462854) (xy 111.614479 -221.462854) (xy 111.563341 -221.454755)
			(xy 111.514101 -221.438756) (xy 111.467969 -221.41525) (xy 111.426082 -221.384818) (xy 111.389472 -221.348208)
			(xy 111.35904 -221.306321) (xy 111.335534 -221.260189) (xy 111.319535 -221.210949) (xy 111.311436 -221.159811)
			(xy 111.310928 -221.133924) (xy 111.311467 -221.106216) (xy 111.320656 -221.05157) (xy 111.329216 -221.025212)
			(xy 111.33709 -221.003114) (xy 111.132112 -220.648022) (xy 111.109252 -220.643704) (xy 111.0844 -220.63857)
			(xy 111.036553 -220.621668) (xy 110.991862 -220.597632) (xy 110.951384 -220.567029) (xy 110.916074 -220.530584)
			(xy 110.886768 -220.489157) (xy 110.864157 -220.443728) (xy 110.848777 -220.39537) (xy 110.840991 -220.345226)
			(xy 110.84052 -220.319854) (xy 109.620304 -220.319854) (xy 109.619694 -220.347507) (xy 109.610371 -220.402025)
			(xy 109.601762 -220.428312) (xy 109.594142 -220.45041) (xy 109.799374 -220.805756) (xy 109.822234 -220.810074)
			(xy 109.847045 -220.815229) (xy 109.894784 -220.832223) (xy 109.939362 -220.856322) (xy 109.979727 -220.886957)
			(xy 110.01493 -220.923408) (xy 110.04414 -220.964816) (xy 110.066672 -221.010206) (xy 110.081992 -221.058509)
			(xy 110.089742 -221.108587) (xy 110.090204 -221.133924) (xy 110.089696 -221.159811) (xy 110.081597 -221.210949)
			(xy 110.065598 -221.260189) (xy 110.042092 -221.306321) (xy 110.01166 -221.348208) (xy 109.97505 -221.384818)
			(xy 109.933163 -221.41525) (xy 109.887031 -221.438756) (xy 109.837791 -221.454755) (xy 109.786653 -221.462854)
			(xy 109.734879 -221.462854) (xy 109.683741 -221.454755) (xy 109.634501 -221.438756) (xy 109.588369 -221.41525)
			(xy 109.546482 -221.384818) (xy 109.509872 -221.348208) (xy 109.47944 -221.306321) (xy 109.455934 -221.260189)
			(xy 109.439935 -221.210949) (xy 109.431836 -221.159811) (xy 109.431328 -221.133924) (xy 109.431867 -221.106216)
			(xy 109.441056 -221.05157) (xy 109.449616 -221.025212) (xy 109.45749 -221.003114) (xy 109.252512 -220.648022)
			(xy 109.229652 -220.643704) (xy 109.2048 -220.63857) (xy 109.156953 -220.621668) (xy 109.112262 -220.597632)
			(xy 109.071784 -220.567029) (xy 109.036474 -220.530584) (xy 109.007168 -220.489157) (xy 108.984557 -220.443728)
			(xy 108.969177 -220.39537) (xy 108.961391 -220.345226) (xy 108.96092 -220.319854) (xy 107.740704 -220.319854)
			(xy 107.740094 -220.347507) (xy 107.730771 -220.402025) (xy 107.722162 -220.428312) (xy 107.714542 -220.45041)
			(xy 107.919774 -220.805756) (xy 107.942634 -220.810074) (xy 107.967445 -220.815229) (xy 108.015184 -220.832223)
			(xy 108.059762 -220.856322) (xy 108.100127 -220.886957) (xy 108.13533 -220.923408) (xy 108.16454 -220.964816)
			(xy 108.187072 -221.010206) (xy 108.202392 -221.058509) (xy 108.210142 -221.108587) (xy 108.210604 -221.133924)
			(xy 108.210096 -221.159811) (xy 108.201997 -221.210949) (xy 108.185998 -221.260189) (xy 108.162492 -221.306321)
			(xy 108.13206 -221.348208) (xy 108.09545 -221.384818) (xy 108.053563 -221.41525) (xy 108.007431 -221.438756)
			(xy 107.958191 -221.454755) (xy 107.907053 -221.462854) (xy 107.855279 -221.462854) (xy 107.804141 -221.454755)
			(xy 107.754901 -221.438756) (xy 107.708769 -221.41525) (xy 107.666882 -221.384818) (xy 107.630272 -221.348208)
			(xy 107.59984 -221.306321) (xy 107.576334 -221.260189) (xy 107.560335 -221.210949) (xy 107.552236 -221.159811)
			(xy 107.551728 -221.133924) (xy 107.552267 -221.106216) (xy 107.561456 -221.05157) (xy 107.570016 -221.025212)
			(xy 107.57789 -221.003114) (xy 107.372912 -220.648022) (xy 107.350052 -220.643704) (xy 107.3252 -220.63857)
			(xy 107.277353 -220.621668) (xy 107.232662 -220.597632) (xy 107.192184 -220.567029) (xy 107.156874 -220.530584)
			(xy 107.127568 -220.489157) (xy 107.104957 -220.443728) (xy 107.089577 -220.39537) (xy 107.081791 -220.345226)
			(xy 107.08132 -220.319854) (xy 105.861104 -220.319854) (xy 105.860494 -220.347507) (xy 105.851171 -220.402025)
			(xy 105.842562 -220.428312) (xy 105.834942 -220.45041) (xy 106.040174 -220.805756) (xy 106.063034 -220.810074)
			(xy 106.087845 -220.815229) (xy 106.135584 -220.832223) (xy 106.180162 -220.856322) (xy 106.220527 -220.886957)
			(xy 106.25573 -220.923408) (xy 106.28494 -220.964816) (xy 106.307472 -221.010206) (xy 106.322792 -221.058509)
			(xy 106.330542 -221.108587) (xy 106.331004 -221.133924) (xy 106.330496 -221.159811) (xy 106.322397 -221.210949)
			(xy 106.306398 -221.260189) (xy 106.282892 -221.306321) (xy 106.25246 -221.348208) (xy 106.21585 -221.384818)
			(xy 106.173963 -221.41525) (xy 106.127831 -221.438756) (xy 106.078591 -221.454755) (xy 106.027453 -221.462854)
			(xy 105.975679 -221.462854) (xy 105.924541 -221.454755) (xy 105.875301 -221.438756) (xy 105.829169 -221.41525)
			(xy 105.787282 -221.384818) (xy 105.750672 -221.348208) (xy 105.72024 -221.306321) (xy 105.696734 -221.260189)
			(xy 105.680735 -221.210949) (xy 105.672636 -221.159811) (xy 105.672128 -221.133924) (xy 105.672667 -221.106216)
			(xy 105.681856 -221.05157) (xy 105.690416 -221.025212) (xy 105.69829 -221.003114) (xy 105.493312 -220.648022)
			(xy 105.470452 -220.643704) (xy 105.4456 -220.63857) (xy 105.397753 -220.621668) (xy 105.353062 -220.597632)
			(xy 105.312584 -220.567029) (xy 105.277274 -220.530584) (xy 105.247968 -220.489157) (xy 105.225357 -220.443728)
			(xy 105.209977 -220.39537) (xy 105.202191 -220.345226) (xy 105.20172 -220.319854) (xy 103.981504 -220.319854)
			(xy 103.981028 -220.345199) (xy 103.973249 -220.395289) (xy 103.957897 -220.443599) (xy 103.935334 -220.48899)
			(xy 103.906091 -220.530396) (xy 103.870857 -220.566839) (xy 103.830462 -220.597461) (xy 103.785857 -220.621543)
			(xy 103.738093 -220.638516) (xy 103.71328 -220.643704) (xy 103.69042 -220.648022) (xy 103.485442 -221.003114)
			(xy 103.493316 -221.024958) (xy 103.50191 -221.051373) (xy 103.511097 -221.106151) (xy 103.511604 -221.133924)
			(xy 103.511096 -221.159811) (xy 103.502997 -221.210949) (xy 103.486998 -221.260189) (xy 103.463492 -221.306321)
			(xy 103.43306 -221.348208) (xy 103.39645 -221.384818) (xy 103.354563 -221.41525) (xy 103.308431 -221.438756)
			(xy 103.259191 -221.454755) (xy 103.208053 -221.462854) (xy 103.156279 -221.462854) (xy 103.105141 -221.454755)
			(xy 103.055901 -221.438756) (xy 103.009769 -221.41525) (xy 102.967882 -221.384818) (xy 102.931272 -221.348208)
			(xy 102.90084 -221.306321) (xy 102.877334 -221.260189) (xy 102.861335 -221.210949) (xy 102.853236 -221.159811)
			(xy 102.852728 -221.133924) (xy 102.571804 -221.133924) (xy 102.57128 -221.161632) (xy 102.562081 -221.216279)
			(xy 102.553516 -221.242636) (xy 102.545642 -221.264734) (xy 102.75062 -221.619572) (xy 102.77348 -221.62389)
			(xy 102.798305 -221.629041) (xy 102.846083 -221.645999) (xy 102.890702 -221.670074) (xy 102.931107 -221.700696)
			(xy 102.966347 -221.737145) (xy 102.99559 -221.778561) (xy 103.018147 -221.823965) (xy 103.033485 -221.872289)
			(xy 103.041242 -221.92239) (xy 103.041704 -221.94774) (xy 104.26192 -221.94774) (xy 104.262371 -221.922394)
			(xy 104.270152 -221.872302) (xy 104.285506 -221.82399) (xy 104.308072 -221.778597) (xy 104.337318 -221.737192)
			(xy 104.372555 -221.700749) (xy 104.412954 -221.670127) (xy 104.457562 -221.646047) (xy 104.50533 -221.629076)
			(xy 104.530144 -221.62389) (xy 104.553004 -221.619572) (xy 104.758236 -221.264226) (xy 104.750362 -221.242128)
			(xy 104.741898 -221.215883) (xy 104.732825 -221.161495) (xy 104.732328 -221.133924) (xy 104.732836 -221.108037)
			(xy 104.740935 -221.056899) (xy 104.756934 -221.007659) (xy 104.78044 -220.961527) (xy 104.810872 -220.91964)
			(xy 104.847482 -220.88303) (xy 104.889369 -220.852598) (xy 104.935501 -220.829092) (xy 104.984741 -220.813093)
			(xy 105.035879 -220.804994) (xy 105.087653 -220.804994) (xy 105.138791 -220.813093) (xy 105.188031 -220.829092)
			(xy 105.234163 -220.852598) (xy 105.27605 -220.88303) (xy 105.31266 -220.91964) (xy 105.343092 -220.961527)
			(xy 105.366598 -221.007659) (xy 105.382597 -221.056899) (xy 105.390696 -221.108037) (xy 105.391204 -221.133924)
			(xy 105.390748 -221.159299) (xy 105.382976 -221.20945) (xy 105.367604 -221.257815) (xy 105.344997 -221.303251)
			(xy 105.315689 -221.344682) (xy 105.280373 -221.381128) (xy 105.239885 -221.411727) (xy 105.195184 -221.435754)
			(xy 105.147326 -221.452641) (xy 105.122472 -221.457774) (xy 105.099612 -221.462092) (xy 104.894888 -221.81693)
			(xy 104.902762 -221.838774) (xy 104.911419 -221.865179) (xy 104.920732 -221.919958) (xy 104.921304 -221.94774)
			(xy 106.14152 -221.94774) (xy 106.141971 -221.922394) (xy 106.149752 -221.872302) (xy 106.165106 -221.82399)
			(xy 106.187672 -221.778597) (xy 106.216918 -221.737192) (xy 106.252155 -221.700749) (xy 106.292554 -221.670127)
			(xy 106.337162 -221.646047) (xy 106.38493 -221.629076) (xy 106.409744 -221.62389) (xy 106.432604 -221.619572)
			(xy 106.637836 -221.264226) (xy 106.629962 -221.242128) (xy 106.621498 -221.215883) (xy 106.612425 -221.161495)
			(xy 106.611928 -221.133924) (xy 106.612436 -221.108037) (xy 106.620535 -221.056899) (xy 106.636534 -221.007659)
			(xy 106.66004 -220.961527) (xy 106.690472 -220.91964) (xy 106.727082 -220.88303) (xy 106.768969 -220.852598)
			(xy 106.815101 -220.829092) (xy 106.864341 -220.813093) (xy 106.915479 -220.804994) (xy 106.967253 -220.804994)
			(xy 107.018391 -220.813093) (xy 107.067631 -220.829092) (xy 107.113763 -220.852598) (xy 107.15565 -220.88303)
			(xy 107.19226 -220.91964) (xy 107.222692 -220.961527) (xy 107.246198 -221.007659) (xy 107.262197 -221.056899)
			(xy 107.270296 -221.108037) (xy 107.270804 -221.133924) (xy 107.270348 -221.159299) (xy 107.262576 -221.20945)
			(xy 107.247204 -221.257815) (xy 107.224597 -221.303251) (xy 107.195289 -221.344682) (xy 107.159973 -221.381128)
			(xy 107.119485 -221.411727) (xy 107.074784 -221.435754) (xy 107.026926 -221.452641) (xy 107.002072 -221.457774)
			(xy 106.979212 -221.462092) (xy 106.774488 -221.81693) (xy 106.782362 -221.838774) (xy 106.791019 -221.865179)
			(xy 106.800332 -221.919958) (xy 106.800904 -221.94774) (xy 108.02112 -221.94774) (xy 108.021571 -221.922394)
			(xy 108.029352 -221.872302) (xy 108.044706 -221.82399) (xy 108.067272 -221.778597) (xy 108.096518 -221.737192)
			(xy 108.131755 -221.700749) (xy 108.172154 -221.670127) (xy 108.216762 -221.646047) (xy 108.26453 -221.629076)
			(xy 108.289344 -221.62389) (xy 108.312204 -221.619572) (xy 108.517436 -221.264226) (xy 108.509562 -221.242128)
			(xy 108.501098 -221.215883) (xy 108.492025 -221.161495) (xy 108.491528 -221.133924) (xy 108.492036 -221.108037)
			(xy 108.500135 -221.056899) (xy 108.516134 -221.007659) (xy 108.53964 -220.961527) (xy 108.570072 -220.91964)
			(xy 108.606682 -220.88303) (xy 108.648569 -220.852598) (xy 108.694701 -220.829092) (xy 108.743941 -220.813093)
			(xy 108.795079 -220.804994) (xy 108.846853 -220.804994) (xy 108.897991 -220.813093) (xy 108.947231 -220.829092)
			(xy 108.993363 -220.852598) (xy 109.03525 -220.88303) (xy 109.07186 -220.91964) (xy 109.102292 -220.961527)
			(xy 109.125798 -221.007659) (xy 109.141797 -221.056899) (xy 109.149896 -221.108037) (xy 109.150404 -221.133924)
			(xy 109.149948 -221.159299) (xy 109.142176 -221.20945) (xy 109.126804 -221.257815) (xy 109.104197 -221.303251)
			(xy 109.074889 -221.344682) (xy 109.039573 -221.381128) (xy 108.999085 -221.411727) (xy 108.954384 -221.435754)
			(xy 108.906526 -221.452641) (xy 108.881672 -221.457774) (xy 108.858812 -221.462092) (xy 108.654088 -221.81693)
			(xy 108.661962 -221.838774) (xy 108.670619 -221.865179) (xy 108.679932 -221.919958) (xy 108.680504 -221.94774)
			(xy 109.901228 -221.94774) (xy 109.901634 -221.922403) (xy 109.909396 -221.872326) (xy 109.924728 -221.824026)
			(xy 109.947269 -221.77864) (xy 109.976489 -221.737238) (xy 110.011699 -221.700794) (xy 110.05207 -221.670165)
			(xy 110.096652 -221.646074) (xy 110.144395 -221.629087) (xy 110.169198 -221.62389) (xy 110.192058 -221.619572)
			(xy 110.397036 -221.26448) (xy 110.389416 -221.242382) (xy 110.380897 -221.216211) (xy 110.371703 -221.161949)
			(xy 110.371128 -221.134432) (xy 110.371128 -221.133924) (xy 110.371636 -221.108037) (xy 110.379735 -221.056899)
			(xy 110.395734 -221.007659) (xy 110.41924 -220.961527) (xy 110.449672 -220.91964) (xy 110.486282 -220.88303)
			(xy 110.528169 -220.852598) (xy 110.574301 -220.829092) (xy 110.623541 -220.813093) (xy 110.674679 -220.804994)
			(xy 110.726453 -220.804994) (xy 110.777591 -220.813093) (xy 110.826831 -220.829092) (xy 110.872963 -220.852598)
			(xy 110.91485 -220.88303) (xy 110.95146 -220.91964) (xy 110.981892 -220.961527) (xy 111.005398 -221.007659)
			(xy 111.021397 -221.056899) (xy 111.029496 -221.108037) (xy 111.030004 -221.133924) (xy 111.029585 -221.15929)
			(xy 111.021833 -221.209425) (xy 111.006484 -221.257778) (xy 110.983902 -221.303206) (xy 110.954621 -221.344633)
			(xy 110.919333 -221.381081) (xy 110.878874 -221.411686) (xy 110.8342 -221.435725) (xy 110.786369 -221.45263)
			(xy 110.761526 -221.457774) (xy 110.738666 -221.462092) (xy 110.533942 -221.81693) (xy 110.541816 -221.838774)
			(xy 110.550414 -221.865187) (xy 110.559598 -221.919967) (xy 110.560104 -221.94774) (xy 111.78032 -221.94774)
			(xy 111.780771 -221.922394) (xy 111.788552 -221.872302) (xy 111.803906 -221.82399) (xy 111.826472 -221.778597)
			(xy 111.855718 -221.737192) (xy 111.890955 -221.700749) (xy 111.931354 -221.670127) (xy 111.975962 -221.646047)
			(xy 112.02373 -221.629076) (xy 112.048544 -221.62389) (xy 112.071404 -221.619572) (xy 112.276636 -221.264226)
			(xy 112.268762 -221.242128) (xy 112.260298 -221.215883) (xy 112.251225 -221.161495) (xy 112.250728 -221.133924)
			(xy 112.251236 -221.108037) (xy 112.259335 -221.056899) (xy 112.275334 -221.007659) (xy 112.29884 -220.961527)
			(xy 112.329272 -220.91964) (xy 112.365882 -220.88303) (xy 112.407769 -220.852598) (xy 112.453901 -220.829092)
			(xy 112.503141 -220.813093) (xy 112.554279 -220.804994) (xy 112.606053 -220.804994) (xy 112.657191 -220.813093)
			(xy 112.706431 -220.829092) (xy 112.752563 -220.852598) (xy 112.79445 -220.88303) (xy 112.83106 -220.91964)
			(xy 112.861492 -220.961527) (xy 112.884998 -221.007659) (xy 112.900997 -221.056899) (xy 112.909096 -221.108037)
			(xy 112.909604 -221.133924) (xy 112.909148 -221.159299) (xy 112.901376 -221.20945) (xy 112.886004 -221.257815)
			(xy 112.863397 -221.303251) (xy 112.834089 -221.344682) (xy 112.798773 -221.381128) (xy 112.758285 -221.411727)
			(xy 112.713584 -221.435754) (xy 112.665726 -221.452641) (xy 112.640872 -221.457774) (xy 112.618012 -221.462092)
			(xy 112.413288 -221.81693) (xy 112.421162 -221.838774) (xy 112.429819 -221.865179) (xy 112.439132 -221.919958)
			(xy 112.439704 -221.94774) (xy 113.660428 -221.94774) (xy 113.660834 -221.922403) (xy 113.668596 -221.872326)
			(xy 113.683928 -221.824026) (xy 113.706469 -221.77864) (xy 113.735689 -221.737238) (xy 113.770899 -221.700794)
			(xy 113.81127 -221.670165) (xy 113.855852 -221.646074) (xy 113.903595 -221.629087) (xy 113.928398 -221.62389)
			(xy 113.951258 -221.619572) (xy 114.156236 -221.26448) (xy 114.148616 -221.242382) (xy 114.140097 -221.216211)
			(xy 114.130903 -221.161949) (xy 114.130328 -221.134432) (xy 114.130328 -221.133924) (xy 114.130836 -221.108037)
			(xy 114.138935 -221.056899) (xy 114.154934 -221.007659) (xy 114.17844 -220.961527) (xy 114.208872 -220.91964)
			(xy 114.245482 -220.88303) (xy 114.287369 -220.852598) (xy 114.333501 -220.829092) (xy 114.382741 -220.813093)
			(xy 114.433879 -220.804994) (xy 114.485653 -220.804994) (xy 114.536791 -220.813093) (xy 114.586031 -220.829092)
			(xy 114.632163 -220.852598) (xy 114.67405 -220.88303) (xy 114.71066 -220.91964) (xy 114.741092 -220.961527)
			(xy 114.764598 -221.007659) (xy 114.780597 -221.056899) (xy 114.788696 -221.108037) (xy 114.789204 -221.133924)
			(xy 114.788785 -221.15929) (xy 114.781033 -221.209425) (xy 114.765684 -221.257778) (xy 114.743102 -221.303206)
			(xy 114.713821 -221.344633) (xy 114.678533 -221.381081) (xy 114.638074 -221.411686) (xy 114.5934 -221.435725)
			(xy 114.545569 -221.45263) (xy 114.520726 -221.457774) (xy 114.497866 -221.462092) (xy 114.293142 -221.81693)
			(xy 114.301016 -221.838774) (xy 114.309614 -221.865187) (xy 114.318798 -221.919967) (xy 114.319304 -221.94774)
			(xy 115.53952 -221.94774) (xy 115.539971 -221.922394) (xy 115.547752 -221.872302) (xy 115.563106 -221.82399)
			(xy 115.585672 -221.778597) (xy 115.614918 -221.737192) (xy 115.650155 -221.700749) (xy 115.690554 -221.670127)
			(xy 115.735162 -221.646047) (xy 115.78293 -221.629076) (xy 115.807744 -221.62389) (xy 115.830604 -221.619572)
			(xy 116.035836 -221.264226) (xy 116.027962 -221.242128) (xy 116.019498 -221.215883) (xy 116.010425 -221.161495)
			(xy 116.009928 -221.133924) (xy 116.010436 -221.108037) (xy 116.018535 -221.056899) (xy 116.034534 -221.007659)
			(xy 116.05804 -220.961527) (xy 116.088472 -220.91964) (xy 116.125082 -220.88303) (xy 116.166969 -220.852598)
			(xy 116.213101 -220.829092) (xy 116.262341 -220.813093) (xy 116.313479 -220.804994) (xy 116.365253 -220.804994)
			(xy 116.416391 -220.813093) (xy 116.465631 -220.829092) (xy 116.511763 -220.852598) (xy 116.55365 -220.88303)
			(xy 116.59026 -220.91964) (xy 116.620692 -220.961527) (xy 116.644198 -221.007659) (xy 116.660197 -221.056899)
			(xy 116.668296 -221.108037) (xy 116.668804 -221.133924) (xy 116.668348 -221.159299) (xy 116.660576 -221.20945)
			(xy 116.645204 -221.257815) (xy 116.622597 -221.303251) (xy 116.593289 -221.344682) (xy 116.557973 -221.381128)
			(xy 116.517485 -221.411727) (xy 116.472784 -221.435754) (xy 116.424926 -221.452641) (xy 116.400072 -221.457774)
			(xy 116.377212 -221.462092) (xy 116.172488 -221.81693) (xy 116.180362 -221.838774) (xy 116.189019 -221.865179)
			(xy 116.198332 -221.919958) (xy 116.198904 -221.94774) (xy 117.41912 -221.94774) (xy 117.419571 -221.922394)
			(xy 117.427352 -221.872302) (xy 117.442706 -221.82399) (xy 117.465272 -221.778597) (xy 117.494518 -221.737192)
			(xy 117.529755 -221.700749) (xy 117.570154 -221.670127) (xy 117.614762 -221.646047) (xy 117.66253 -221.629076)
			(xy 117.687344 -221.62389) (xy 117.710204 -221.619572) (xy 117.915436 -221.264226) (xy 117.907562 -221.242128)
			(xy 117.899098 -221.215883) (xy 117.890025 -221.161495) (xy 117.889528 -221.133924) (xy 117.890036 -221.108037)
			(xy 117.898135 -221.056899) (xy 117.914134 -221.007659) (xy 117.93764 -220.961527) (xy 117.968072 -220.91964)
			(xy 118.004682 -220.88303) (xy 118.046569 -220.852598) (xy 118.092701 -220.829092) (xy 118.141941 -220.813093)
			(xy 118.193079 -220.804994) (xy 118.244853 -220.804994) (xy 118.295991 -220.813093) (xy 118.345231 -220.829092)
			(xy 118.391363 -220.852598) (xy 118.43325 -220.88303) (xy 118.46986 -220.91964) (xy 118.500292 -220.961527)
			(xy 118.523798 -221.007659) (xy 118.539797 -221.056899) (xy 118.547896 -221.108037) (xy 118.548404 -221.133924)
			(xy 118.547948 -221.159299) (xy 118.540176 -221.20945) (xy 118.524804 -221.257815) (xy 118.502197 -221.303251)
			(xy 118.472889 -221.344682) (xy 118.437573 -221.381128) (xy 118.397085 -221.411727) (xy 118.352384 -221.435754)
			(xy 118.304526 -221.452641) (xy 118.279672 -221.457774) (xy 118.256812 -221.462092) (xy 118.052088 -221.81693)
			(xy 118.059962 -221.838774) (xy 118.068619 -221.865179) (xy 118.077932 -221.919958) (xy 118.078504 -221.94774)
			(xy 121.17832 -221.94774) (xy 121.178771 -221.922394) (xy 121.186552 -221.872302) (xy 121.201906 -221.82399)
			(xy 121.224472 -221.778597) (xy 121.253718 -221.737192) (xy 121.288955 -221.700749) (xy 121.329354 -221.670127)
			(xy 121.373962 -221.646047) (xy 121.42173 -221.629076) (xy 121.446544 -221.62389) (xy 121.469404 -221.619572)
			(xy 121.674636 -221.264226) (xy 121.666762 -221.242128) (xy 121.658298 -221.215883) (xy 121.649225 -221.161495)
			(xy 121.648728 -221.133924) (xy 121.649236 -221.108037) (xy 121.657335 -221.056899) (xy 121.673334 -221.007659)
			(xy 121.69684 -220.961527) (xy 121.727272 -220.91964) (xy 121.763882 -220.88303) (xy 121.805769 -220.852598)
			(xy 121.851901 -220.829092) (xy 121.901141 -220.813093) (xy 121.952279 -220.804994) (xy 122.004053 -220.804994)
			(xy 122.055191 -220.813093) (xy 122.104431 -220.829092) (xy 122.150563 -220.852598) (xy 122.19245 -220.88303)
			(xy 122.22906 -220.91964) (xy 122.259492 -220.961527) (xy 122.282998 -221.007659) (xy 122.298997 -221.056899)
			(xy 122.307096 -221.108037) (xy 122.307604 -221.133924) (xy 122.307148 -221.159299) (xy 122.299376 -221.20945)
			(xy 122.284004 -221.257815) (xy 122.261397 -221.303251) (xy 122.232089 -221.344682) (xy 122.196773 -221.381128)
			(xy 122.156285 -221.411727) (xy 122.111584 -221.435754) (xy 122.063726 -221.452641) (xy 122.038872 -221.457774)
			(xy 122.016012 -221.462092) (xy 121.811288 -221.81693) (xy 121.819162 -221.838774) (xy 121.827819 -221.865179)
			(xy 121.837132 -221.919958) (xy 121.837704 -221.94774) (xy 123.05792 -221.94774) (xy 123.058371 -221.922394)
			(xy 123.066152 -221.872302) (xy 123.081506 -221.82399) (xy 123.104072 -221.778597) (xy 123.133318 -221.737192)
			(xy 123.168555 -221.700749) (xy 123.208954 -221.670127) (xy 123.253562 -221.646047) (xy 123.30133 -221.629076)
			(xy 123.326144 -221.62389) (xy 123.349004 -221.619572) (xy 123.554236 -221.264226) (xy 123.546362 -221.242128)
			(xy 123.537898 -221.215883) (xy 123.528825 -221.161495) (xy 123.528328 -221.133924) (xy 123.528836 -221.108037)
			(xy 123.536935 -221.056899) (xy 123.552934 -221.007659) (xy 123.57644 -220.961527) (xy 123.606872 -220.91964)
			(xy 123.643482 -220.88303) (xy 123.685369 -220.852598) (xy 123.731501 -220.829092) (xy 123.780741 -220.813093)
			(xy 123.831879 -220.804994) (xy 123.883653 -220.804994) (xy 123.934791 -220.813093) (xy 123.984031 -220.829092)
			(xy 124.030163 -220.852598) (xy 124.07205 -220.88303) (xy 124.10866 -220.91964) (xy 124.139092 -220.961527)
			(xy 124.162598 -221.007659) (xy 124.178597 -221.056899) (xy 124.186696 -221.108037) (xy 124.187204 -221.133924)
			(xy 124.186748 -221.159299) (xy 124.178976 -221.20945) (xy 124.163604 -221.257815) (xy 124.140997 -221.303251)
			(xy 124.111689 -221.344682) (xy 124.076373 -221.381128) (xy 124.035885 -221.411727) (xy 123.991184 -221.435754)
			(xy 123.943326 -221.452641) (xy 123.918472 -221.457774) (xy 123.895612 -221.462092) (xy 123.690888 -221.81693)
			(xy 123.698762 -221.838774) (xy 123.707419 -221.865179) (xy 123.716732 -221.919958) (xy 123.717304 -221.94774)
			(xy 124.93752 -221.94774) (xy 124.937971 -221.922394) (xy 124.945752 -221.872302) (xy 124.961106 -221.82399)
			(xy 124.983672 -221.778597) (xy 125.012918 -221.737192) (xy 125.048155 -221.700749) (xy 125.088554 -221.670127)
			(xy 125.133162 -221.646047) (xy 125.18093 -221.629076) (xy 125.205744 -221.62389) (xy 125.228604 -221.619572)
			(xy 125.433836 -221.264226) (xy 125.425962 -221.242128) (xy 125.417498 -221.215883) (xy 125.408425 -221.161495)
			(xy 125.407928 -221.133924) (xy 125.408436 -221.108037) (xy 125.416535 -221.056899) (xy 125.432534 -221.007659)
			(xy 125.45604 -220.961527) (xy 125.486472 -220.91964) (xy 125.523082 -220.88303) (xy 125.564969 -220.852598)
			(xy 125.611101 -220.829092) (xy 125.660341 -220.813093) (xy 125.711479 -220.804994) (xy 125.763253 -220.804994)
			(xy 125.814391 -220.813093) (xy 125.863631 -220.829092) (xy 125.909763 -220.852598) (xy 125.95165 -220.88303)
			(xy 125.98826 -220.91964) (xy 126.018692 -220.961527) (xy 126.042198 -221.007659) (xy 126.058197 -221.056899)
			(xy 126.066296 -221.108037) (xy 126.066804 -221.133924) (xy 126.066348 -221.159299) (xy 126.058576 -221.20945)
			(xy 126.043204 -221.257815) (xy 126.020597 -221.303251) (xy 125.991289 -221.344682) (xy 125.955973 -221.381128)
			(xy 125.915485 -221.411727) (xy 125.870784 -221.435754) (xy 125.822926 -221.452641) (xy 125.798072 -221.457774)
			(xy 125.775212 -221.462092) (xy 125.570488 -221.81693) (xy 125.578362 -221.838774) (xy 125.587019 -221.865179)
			(xy 125.596332 -221.919958) (xy 125.596904 -221.94774) (xy 126.81712 -221.94774) (xy 126.817571 -221.922394)
			(xy 126.825352 -221.872302) (xy 126.840706 -221.82399) (xy 126.863272 -221.778597) (xy 126.892518 -221.737192)
			(xy 126.927755 -221.700749) (xy 126.968154 -221.670127) (xy 127.012762 -221.646047) (xy 127.06053 -221.629076)
			(xy 127.085344 -221.62389) (xy 127.108204 -221.619572) (xy 127.313436 -221.264226) (xy 127.305562 -221.242128)
			(xy 127.297098 -221.215883) (xy 127.288025 -221.161495) (xy 127.287528 -221.133924) (xy 127.288036 -221.108037)
			(xy 127.296135 -221.056899) (xy 127.312134 -221.007659) (xy 127.33564 -220.961527) (xy 127.366072 -220.91964)
			(xy 127.402682 -220.88303) (xy 127.444569 -220.852598) (xy 127.490701 -220.829092) (xy 127.539941 -220.813093)
			(xy 127.591079 -220.804994) (xy 127.642853 -220.804994) (xy 127.693991 -220.813093) (xy 127.743231 -220.829092)
			(xy 127.789363 -220.852598) (xy 127.83125 -220.88303) (xy 127.86786 -220.91964) (xy 127.898292 -220.961527)
			(xy 127.921798 -221.007659) (xy 127.937797 -221.056899) (xy 127.945896 -221.108037) (xy 127.946404 -221.133924)
			(xy 127.945948 -221.159299) (xy 127.938176 -221.20945) (xy 127.922804 -221.257815) (xy 127.900197 -221.303251)
			(xy 127.870889 -221.344682) (xy 127.835573 -221.381128) (xy 127.795085 -221.411727) (xy 127.750384 -221.435754)
			(xy 127.702526 -221.452641) (xy 127.677672 -221.457774) (xy 127.654812 -221.462092) (xy 127.450088 -221.81693)
			(xy 127.457962 -221.838774) (xy 127.466619 -221.865179) (xy 127.475932 -221.919958) (xy 127.476504 -221.94774)
			(xy 128.69672 -221.94774) (xy 128.697171 -221.922394) (xy 128.704952 -221.872302) (xy 128.720306 -221.82399)
			(xy 128.742872 -221.778597) (xy 128.772118 -221.737192) (xy 128.807355 -221.700749) (xy 128.847754 -221.670127)
			(xy 128.892362 -221.646047) (xy 128.94013 -221.629076) (xy 128.964944 -221.62389) (xy 128.987804 -221.619572)
			(xy 129.193036 -221.264226) (xy 129.185162 -221.242128) (xy 129.176698 -221.215883) (xy 129.167625 -221.161495)
			(xy 129.167128 -221.133924) (xy 129.167636 -221.108037) (xy 129.175735 -221.056899) (xy 129.191734 -221.007659)
			(xy 129.21524 -220.961527) (xy 129.245672 -220.91964) (xy 129.282282 -220.88303) (xy 129.324169 -220.852598)
			(xy 129.370301 -220.829092) (xy 129.419541 -220.813093) (xy 129.470679 -220.804994) (xy 129.522453 -220.804994)
			(xy 129.573591 -220.813093) (xy 129.622831 -220.829092) (xy 129.668963 -220.852598) (xy 129.71085 -220.88303)
			(xy 129.74746 -220.91964) (xy 129.777892 -220.961527) (xy 129.801398 -221.007659) (xy 129.817397 -221.056899)
			(xy 129.825496 -221.108037) (xy 129.826004 -221.133924) (xy 129.825548 -221.159299) (xy 129.817776 -221.20945)
			(xy 129.802404 -221.257815) (xy 129.779797 -221.303251) (xy 129.750489 -221.344682) (xy 129.715173 -221.381128)
			(xy 129.674685 -221.411727) (xy 129.629984 -221.435754) (xy 129.582126 -221.452641) (xy 129.557272 -221.457774)
			(xy 129.534412 -221.462092) (xy 129.329688 -221.81693) (xy 129.337562 -221.838774) (xy 129.346219 -221.865179)
			(xy 129.355532 -221.919958) (xy 129.356104 -221.94774) (xy 130.57632 -221.94774) (xy 130.576771 -221.922394)
			(xy 130.584552 -221.872302) (xy 130.599906 -221.82399) (xy 130.622472 -221.778597) (xy 130.651718 -221.737192)
			(xy 130.686955 -221.700749) (xy 130.727354 -221.670127) (xy 130.771962 -221.646047) (xy 130.81973 -221.629076)
			(xy 130.844544 -221.62389) (xy 130.867404 -221.619572) (xy 131.072636 -221.264226) (xy 131.064762 -221.242128)
			(xy 131.056298 -221.215883) (xy 131.047225 -221.161495) (xy 131.046728 -221.133924) (xy 131.047236 -221.108037)
			(xy 131.055335 -221.056899) (xy 131.071334 -221.007659) (xy 131.09484 -220.961527) (xy 131.125272 -220.91964)
			(xy 131.161882 -220.88303) (xy 131.203769 -220.852598) (xy 131.249901 -220.829092) (xy 131.299141 -220.813093)
			(xy 131.350279 -220.804994) (xy 131.402053 -220.804994) (xy 131.453191 -220.813093) (xy 131.502431 -220.829092)
			(xy 131.548563 -220.852598) (xy 131.59045 -220.88303) (xy 131.62706 -220.91964) (xy 131.657492 -220.961527)
			(xy 131.680998 -221.007659) (xy 131.696997 -221.056899) (xy 131.705096 -221.108037) (xy 131.705604 -221.133924)
			(xy 131.705148 -221.159299) (xy 131.697376 -221.20945) (xy 131.682004 -221.257815) (xy 131.659397 -221.303251)
			(xy 131.630089 -221.344682) (xy 131.594773 -221.381128) (xy 131.554285 -221.411727) (xy 131.509584 -221.435754)
			(xy 131.461726 -221.452641) (xy 131.436872 -221.457774) (xy 131.414012 -221.462092) (xy 131.209288 -221.81693)
			(xy 131.217162 -221.838774) (xy 131.225819 -221.865179) (xy 131.235132 -221.919958) (xy 131.235704 -221.94774)
			(xy 132.45592 -221.94774) (xy 132.456371 -221.922394) (xy 132.464152 -221.872302) (xy 132.479506 -221.82399)
			(xy 132.502072 -221.778597) (xy 132.531318 -221.737192) (xy 132.566555 -221.700749) (xy 132.606954 -221.670127)
			(xy 132.651562 -221.646047) (xy 132.69933 -221.629076) (xy 132.724144 -221.62389) (xy 132.747004 -221.619572)
			(xy 132.951982 -221.263972) (xy 132.944362 -221.242128) (xy 132.935911 -221.215946) (xy 132.92684 -221.161685)
			(xy 132.926328 -221.134178) (xy 132.926328 -221.133924) (xy 132.926836 -221.108037) (xy 132.934935 -221.056899)
			(xy 132.950934 -221.007659) (xy 132.97444 -220.961527) (xy 133.004872 -220.91964) (xy 133.041482 -220.88303)
			(xy 133.083369 -220.852598) (xy 133.129501 -220.829092) (xy 133.178741 -220.813093) (xy 133.229879 -220.804994)
			(xy 133.281653 -220.804994) (xy 133.332791 -220.813093) (xy 133.382031 -220.829092) (xy 133.428163 -220.852598)
			(xy 133.47005 -220.88303) (xy 133.50666 -220.91964) (xy 133.537092 -220.961527) (xy 133.560598 -221.007659)
			(xy 133.576597 -221.056899) (xy 133.584696 -221.108037) (xy 133.585204 -221.133924) (xy 133.584785 -221.15929)
			(xy 133.577033 -221.209425) (xy 133.561684 -221.257778) (xy 133.539102 -221.303206) (xy 133.509821 -221.344633)
			(xy 133.474533 -221.381081) (xy 133.434074 -221.411686) (xy 133.3894 -221.435725) (xy 133.341569 -221.45263)
			(xy 133.316726 -221.457774) (xy 133.293866 -221.462092) (xy 133.089142 -221.81693) (xy 133.096762 -221.838774)
			(xy 133.105377 -221.865059) (xy 133.114698 -221.919578) (xy 133.115304 -221.947232) (xy 133.115304 -221.94774)
			(xy 134.33552 -221.94774) (xy 134.335971 -221.922394) (xy 134.343752 -221.872302) (xy 134.359106 -221.82399)
			(xy 134.381672 -221.778597) (xy 134.410918 -221.737192) (xy 134.446155 -221.700749) (xy 134.486554 -221.670127)
			(xy 134.531162 -221.646047) (xy 134.57893 -221.629076) (xy 134.603744 -221.62389) (xy 134.626604 -221.619572)
			(xy 134.831582 -221.263972) (xy 134.823962 -221.242128) (xy 134.815511 -221.215946) (xy 134.80644 -221.161685)
			(xy 134.805928 -221.134178) (xy 134.805928 -221.133924) (xy 134.806436 -221.108037) (xy 134.814535 -221.056899)
			(xy 134.830534 -221.007659) (xy 134.85404 -220.961527) (xy 134.884472 -220.91964) (xy 134.921082 -220.88303)
			(xy 134.962969 -220.852598) (xy 135.009101 -220.829092) (xy 135.058341 -220.813093) (xy 135.109479 -220.804994)
			(xy 135.161253 -220.804994) (xy 135.212391 -220.813093) (xy 135.261631 -220.829092) (xy 135.307763 -220.852598)
			(xy 135.34965 -220.88303) (xy 135.38626 -220.91964) (xy 135.416692 -220.961527) (xy 135.440198 -221.007659)
			(xy 135.456197 -221.056899) (xy 135.464296 -221.108037) (xy 135.464804 -221.133924) (xy 336.695796 -221.133924)
			(xy 336.696304 -221.108037) (xy 336.704403 -221.056899) (xy 336.720402 -221.007659) (xy 336.743908 -220.961527)
			(xy 336.77434 -220.91964) (xy 336.81095 -220.88303) (xy 336.852837 -220.852598) (xy 336.898969 -220.829092)
			(xy 336.948209 -220.813093) (xy 336.999347 -220.804994) (xy 337.051121 -220.804994) (xy 337.102259 -220.813093)
			(xy 337.151499 -220.829092) (xy 337.197631 -220.852598) (xy 337.239518 -220.88303) (xy 337.276128 -220.91964)
			(xy 337.30656 -220.961527) (xy 337.330066 -221.007659) (xy 337.346065 -221.056899) (xy 337.354164 -221.108037)
			(xy 337.354672 -221.133924) (xy 337.635596 -221.133924) (xy 337.636104 -221.10859) (xy 337.643853 -221.058519)
			(xy 337.659172 -221.010223) (xy 337.6817 -220.96484) (xy 337.710906 -220.923438) (xy 337.746104 -220.886992)
			(xy 337.786463 -220.856361) (xy 337.831034 -220.832266) (xy 337.878767 -220.815274) (xy 337.903566 -220.810074)
			(xy 337.926426 -220.805756) (xy 338.131404 -220.450664) (xy 338.12353 -220.42882) (xy 338.114896 -220.402408)
			(xy 338.105568 -220.347635) (xy 338.104988 -220.319854) (xy 338.105496 -220.293947) (xy 338.113602 -220.24277)
			(xy 338.129614 -220.193491) (xy 338.153137 -220.147324) (xy 338.183593 -220.105405) (xy 338.220231 -220.068767)
			(xy 338.26215 -220.038311) (xy 338.308317 -220.014788) (xy 338.357596 -219.998776) (xy 338.408773 -219.99067)
			(xy 338.460587 -219.99067) (xy 338.511764 -219.998776) (xy 338.561043 -220.014788) (xy 338.60721 -220.038311)
			(xy 338.649129 -220.068767) (xy 338.685767 -220.105405) (xy 338.716223 -220.147324) (xy 338.739746 -220.193491)
			(xy 338.755758 -220.24277) (xy 338.763864 -220.293947) (xy 338.764372 -220.319854) (xy 338.763922 -220.3452)
			(xy 338.756142 -220.395293) (xy 338.740788 -220.443604) (xy 338.718222 -220.488998) (xy 338.688976 -220.530404)
			(xy 338.653739 -220.566847) (xy 338.61334 -220.597469) (xy 338.568731 -220.621548) (xy 338.520963 -220.638518)
			(xy 338.496148 -220.643704) (xy 338.473288 -220.648022) (xy 338.26831 -221.003114) (xy 338.276184 -221.024958)
			(xy 338.284777 -221.051373) (xy 338.293965 -221.106151) (xy 338.294472 -221.133924) (xy 338.575396 -221.133924)
			(xy 338.575904 -221.108037) (xy 338.584003 -221.056899) (xy 338.600002 -221.007659) (xy 338.623508 -220.961527)
			(xy 338.65394 -220.91964) (xy 338.69055 -220.88303) (xy 338.732437 -220.852598) (xy 338.778569 -220.829092)
			(xy 338.827809 -220.813093) (xy 338.878947 -220.804994) (xy 338.930721 -220.804994) (xy 338.981859 -220.813093)
			(xy 339.031099 -220.829092) (xy 339.077231 -220.852598) (xy 339.119118 -220.88303) (xy 339.155728 -220.91964)
			(xy 339.18616 -220.961527) (xy 339.209666 -221.007659) (xy 339.225665 -221.056899) (xy 339.233764 -221.108037)
			(xy 339.234272 -221.133924) (xy 339.515196 -221.133924) (xy 339.515704 -221.10859) (xy 339.523453 -221.058519)
			(xy 339.538772 -221.010223) (xy 339.5613 -220.96484) (xy 339.590506 -220.923438) (xy 339.625704 -220.886992)
			(xy 339.666063 -220.856361) (xy 339.710634 -220.832266) (xy 339.758367 -220.815274) (xy 339.783166 -220.810074)
			(xy 339.806026 -220.805756) (xy 340.011004 -220.450664) (xy 340.00313 -220.42882) (xy 339.994496 -220.402408)
			(xy 339.985168 -220.347635) (xy 339.984588 -220.319854) (xy 339.985096 -220.293947) (xy 339.993202 -220.24277)
			(xy 340.009214 -220.193491) (xy 340.032737 -220.147324) (xy 340.063193 -220.105405) (xy 340.099831 -220.068767)
			(xy 340.14175 -220.038311) (xy 340.187917 -220.014788) (xy 340.237196 -219.998776) (xy 340.288373 -219.99067)
			(xy 340.340187 -219.99067) (xy 340.391364 -219.998776) (xy 340.440643 -220.014788) (xy 340.48681 -220.038311)
			(xy 340.528729 -220.068767) (xy 340.565367 -220.105405) (xy 340.595823 -220.147324) (xy 340.619346 -220.193491)
			(xy 340.635358 -220.24277) (xy 340.643464 -220.293947) (xy 340.643972 -220.319854) (xy 340.643522 -220.3452)
			(xy 340.635742 -220.395293) (xy 340.620388 -220.443604) (xy 340.597822 -220.488998) (xy 340.568576 -220.530404)
			(xy 340.533339 -220.566847) (xy 340.49294 -220.597469) (xy 340.448331 -220.621548) (xy 340.400563 -220.638518)
			(xy 340.375748 -220.643704) (xy 340.352888 -220.648022) (xy 340.14791 -221.003114) (xy 340.155784 -221.024958)
			(xy 340.164377 -221.051373) (xy 340.173565 -221.106151) (xy 340.174072 -221.133924) (xy 340.454996 -221.133924)
			(xy 340.455504 -221.108037) (xy 340.463603 -221.056899) (xy 340.479602 -221.007659) (xy 340.503108 -220.961527)
			(xy 340.53354 -220.91964) (xy 340.57015 -220.88303) (xy 340.612037 -220.852598) (xy 340.658169 -220.829092)
			(xy 340.707409 -220.813093) (xy 340.758547 -220.804994) (xy 340.810321 -220.804994) (xy 340.861459 -220.813093)
			(xy 340.910699 -220.829092) (xy 340.956831 -220.852598) (xy 340.998718 -220.88303) (xy 341.035328 -220.91964)
			(xy 341.06576 -220.961527) (xy 341.089266 -221.007659) (xy 341.105265 -221.056899) (xy 341.113364 -221.108037)
			(xy 341.113872 -221.133924) (xy 341.394796 -221.133924) (xy 341.395304 -221.10859) (xy 341.403053 -221.058519)
			(xy 341.418372 -221.010223) (xy 341.4409 -220.96484) (xy 341.470106 -220.923438) (xy 341.505304 -220.886992)
			(xy 341.545663 -220.856361) (xy 341.590234 -220.832266) (xy 341.637967 -220.815274) (xy 341.662766 -220.810074)
			(xy 341.685626 -220.805756) (xy 341.890604 -220.450664) (xy 341.88273 -220.42882) (xy 341.874096 -220.402408)
			(xy 341.864768 -220.347635) (xy 341.864188 -220.319854) (xy 341.864696 -220.293947) (xy 341.872802 -220.24277)
			(xy 341.888814 -220.193491) (xy 341.912337 -220.147324) (xy 341.942793 -220.105405) (xy 341.979431 -220.068767)
			(xy 342.02135 -220.038311) (xy 342.067517 -220.014788) (xy 342.116796 -219.998776) (xy 342.167973 -219.99067)
			(xy 342.219787 -219.99067) (xy 342.270964 -219.998776) (xy 342.320243 -220.014788) (xy 342.36641 -220.038311)
			(xy 342.408329 -220.068767) (xy 342.444967 -220.105405) (xy 342.475423 -220.147324) (xy 342.498946 -220.193491)
			(xy 342.514958 -220.24277) (xy 342.523064 -220.293947) (xy 342.523572 -220.319854) (xy 342.523122 -220.3452)
			(xy 342.515342 -220.395293) (xy 342.499988 -220.443604) (xy 342.477422 -220.488998) (xy 342.448176 -220.530404)
			(xy 342.412939 -220.566847) (xy 342.37254 -220.597469) (xy 342.327931 -220.621548) (xy 342.280163 -220.638518)
			(xy 342.255348 -220.643704) (xy 342.232488 -220.648022) (xy 342.02751 -221.003114) (xy 342.035384 -221.024958)
			(xy 342.043977 -221.051373) (xy 342.053165 -221.106151) (xy 342.053672 -221.133924) (xy 342.334596 -221.133924)
			(xy 342.335104 -221.108037) (xy 342.343203 -221.056899) (xy 342.359202 -221.007659) (xy 342.382708 -220.961527)
			(xy 342.41314 -220.91964) (xy 342.44975 -220.88303) (xy 342.491637 -220.852598) (xy 342.537769 -220.829092)
			(xy 342.587009 -220.813093) (xy 342.638147 -220.804994) (xy 342.689921 -220.804994) (xy 342.741059 -220.813093)
			(xy 342.790299 -220.829092) (xy 342.836431 -220.852598) (xy 342.878318 -220.88303) (xy 342.914928 -220.91964)
			(xy 342.94536 -220.961527) (xy 342.968866 -221.007659) (xy 342.984865 -221.056899) (xy 342.992964 -221.108037)
			(xy 342.993472 -221.133924) (xy 343.274396 -221.133924) (xy 343.274904 -221.10859) (xy 343.282653 -221.058519)
			(xy 343.297972 -221.010223) (xy 343.3205 -220.96484) (xy 343.349706 -220.923438) (xy 343.384904 -220.886992)
			(xy 343.425263 -220.856361) (xy 343.469834 -220.832266) (xy 343.517567 -220.815274) (xy 343.542366 -220.810074)
			(xy 343.565226 -220.805756) (xy 343.770204 -220.450664) (xy 343.76233 -220.42882) (xy 343.753696 -220.402408)
			(xy 343.744368 -220.347635) (xy 343.743788 -220.319854) (xy 343.744296 -220.293947) (xy 343.752402 -220.24277)
			(xy 343.768414 -220.193491) (xy 343.791937 -220.147324) (xy 343.822393 -220.105405) (xy 343.859031 -220.068767)
			(xy 343.90095 -220.038311) (xy 343.947117 -220.014788) (xy 343.996396 -219.998776) (xy 344.047573 -219.99067)
			(xy 344.099387 -219.99067) (xy 344.150564 -219.998776) (xy 344.199843 -220.014788) (xy 344.24601 -220.038311)
			(xy 344.287929 -220.068767) (xy 344.324567 -220.105405) (xy 344.355023 -220.147324) (xy 344.378546 -220.193491)
			(xy 344.394558 -220.24277) (xy 344.402664 -220.293947) (xy 344.403172 -220.319854) (xy 344.402722 -220.3452)
			(xy 344.394942 -220.395293) (xy 344.379588 -220.443604) (xy 344.357022 -220.488998) (xy 344.327776 -220.530404)
			(xy 344.292539 -220.566847) (xy 344.25214 -220.597469) (xy 344.207531 -220.621548) (xy 344.159763 -220.638518)
			(xy 344.134948 -220.643704) (xy 344.112088 -220.648022) (xy 343.90711 -221.003114) (xy 343.914984 -221.024958)
			(xy 343.923577 -221.051373) (xy 343.932765 -221.106151) (xy 343.933272 -221.133924) (xy 344.214196 -221.133924)
			(xy 344.214704 -221.108037) (xy 344.222803 -221.056899) (xy 344.238802 -221.007659) (xy 344.262308 -220.961527)
			(xy 344.29274 -220.91964) (xy 344.32935 -220.88303) (xy 344.371237 -220.852598) (xy 344.417369 -220.829092)
			(xy 344.466609 -220.813093) (xy 344.517747 -220.804994) (xy 344.569521 -220.804994) (xy 344.620659 -220.813093)
			(xy 344.669899 -220.829092) (xy 344.716031 -220.852598) (xy 344.757918 -220.88303) (xy 344.794528 -220.91964)
			(xy 344.82496 -220.961527) (xy 344.848466 -221.007659) (xy 344.864465 -221.056899) (xy 344.872564 -221.108037)
			(xy 344.873072 -221.133924) (xy 345.153996 -221.133924) (xy 345.154504 -221.10859) (xy 345.162253 -221.058519)
			(xy 345.177572 -221.010223) (xy 345.2001 -220.96484) (xy 345.229306 -220.923438) (xy 345.264504 -220.886992)
			(xy 345.304863 -220.856361) (xy 345.349434 -220.832266) (xy 345.397167 -220.815274) (xy 345.421966 -220.810074)
			(xy 345.444826 -220.805756) (xy 345.649804 -220.450664) (xy 345.64193 -220.42882) (xy 345.633296 -220.402408)
			(xy 345.623968 -220.347635) (xy 345.623388 -220.319854) (xy 345.623896 -220.293947) (xy 345.632002 -220.24277)
			(xy 345.648014 -220.193491) (xy 345.671537 -220.147324) (xy 345.701993 -220.105405) (xy 345.738631 -220.068767)
			(xy 345.78055 -220.038311) (xy 345.826717 -220.014788) (xy 345.875996 -219.998776) (xy 345.927173 -219.99067)
			(xy 345.978987 -219.99067) (xy 346.030164 -219.998776) (xy 346.079443 -220.014788) (xy 346.12561 -220.038311)
			(xy 346.167529 -220.068767) (xy 346.204167 -220.105405) (xy 346.234623 -220.147324) (xy 346.258146 -220.193491)
			(xy 346.274158 -220.24277) (xy 346.282264 -220.293947) (xy 346.282772 -220.319854) (xy 346.282322 -220.3452)
			(xy 346.274542 -220.395293) (xy 346.259188 -220.443604) (xy 346.236622 -220.488998) (xy 346.207376 -220.530404)
			(xy 346.172139 -220.566847) (xy 346.13174 -220.597469) (xy 346.087131 -220.621548) (xy 346.039363 -220.638518)
			(xy 346.014548 -220.643704) (xy 345.991688 -220.648022) (xy 345.78671 -221.003114) (xy 345.794584 -221.024958)
			(xy 345.803177 -221.051373) (xy 345.812365 -221.106151) (xy 345.812872 -221.133924) (xy 346.093796 -221.133924)
			(xy 346.094304 -221.108037) (xy 346.102403 -221.056899) (xy 346.118402 -221.007659) (xy 346.141908 -220.961527)
			(xy 346.17234 -220.91964) (xy 346.20895 -220.88303) (xy 346.250837 -220.852598) (xy 346.296969 -220.829092)
			(xy 346.346209 -220.813093) (xy 346.397347 -220.804994) (xy 346.449121 -220.804994) (xy 346.500259 -220.813093)
			(xy 346.549499 -220.829092) (xy 346.595631 -220.852598) (xy 346.637518 -220.88303) (xy 346.674128 -220.91964)
			(xy 346.70456 -220.961527) (xy 346.728066 -221.007659) (xy 346.744065 -221.056899) (xy 346.752164 -221.108037)
			(xy 346.752672 -221.133924) (xy 347.033596 -221.133924) (xy 347.034104 -221.10859) (xy 347.041853 -221.058519)
			(xy 347.057172 -221.010223) (xy 347.0797 -220.96484) (xy 347.108906 -220.923438) (xy 347.144104 -220.886992)
			(xy 347.184463 -220.856361) (xy 347.229034 -220.832266) (xy 347.276767 -220.815274) (xy 347.301566 -220.810074)
			(xy 347.324426 -220.805756) (xy 347.529404 -220.450664) (xy 347.52153 -220.42882) (xy 347.512896 -220.402408)
			(xy 347.503568 -220.347635) (xy 347.502988 -220.319854) (xy 347.503496 -220.293947) (xy 347.511602 -220.24277)
			(xy 347.527614 -220.193491) (xy 347.551137 -220.147324) (xy 347.581593 -220.105405) (xy 347.618231 -220.068767)
			(xy 347.66015 -220.038311) (xy 347.706317 -220.014788) (xy 347.755596 -219.998776) (xy 347.806773 -219.99067)
			(xy 347.858587 -219.99067) (xy 347.909764 -219.998776) (xy 347.959043 -220.014788) (xy 348.00521 -220.038311)
			(xy 348.047129 -220.068767) (xy 348.083767 -220.105405) (xy 348.114223 -220.147324) (xy 348.137746 -220.193491)
			(xy 348.153758 -220.24277) (xy 348.161864 -220.293947) (xy 348.162372 -220.319854) (xy 348.161922 -220.3452)
			(xy 348.154142 -220.395293) (xy 348.138788 -220.443604) (xy 348.116222 -220.488998) (xy 348.086976 -220.530404)
			(xy 348.051739 -220.566847) (xy 348.01134 -220.597469) (xy 347.966731 -220.621548) (xy 347.918963 -220.638518)
			(xy 347.894148 -220.643704) (xy 347.871288 -220.648022) (xy 347.66631 -221.003114) (xy 347.674184 -221.024958)
			(xy 347.682777 -221.051373) (xy 347.691965 -221.106151) (xy 347.692472 -221.133924) (xy 347.973396 -221.133924)
			(xy 347.973904 -221.108037) (xy 347.982003 -221.056899) (xy 347.998002 -221.007659) (xy 348.021508 -220.961527)
			(xy 348.05194 -220.91964) (xy 348.08855 -220.88303) (xy 348.130437 -220.852598) (xy 348.176569 -220.829092)
			(xy 348.225809 -220.813093) (xy 348.276947 -220.804994) (xy 348.328721 -220.804994) (xy 348.379859 -220.813093)
			(xy 348.429099 -220.829092) (xy 348.475231 -220.852598) (xy 348.517118 -220.88303) (xy 348.553728 -220.91964)
			(xy 348.58416 -220.961527) (xy 348.607666 -221.007659) (xy 348.623665 -221.056899) (xy 348.631764 -221.108037)
			(xy 348.632272 -221.133924) (xy 348.913196 -221.133924) (xy 348.913704 -221.10859) (xy 348.921453 -221.058519)
			(xy 348.936772 -221.010223) (xy 348.9593 -220.96484) (xy 348.988506 -220.923438) (xy 349.023704 -220.886992)
			(xy 349.064063 -220.856361) (xy 349.108634 -220.832266) (xy 349.156367 -220.815274) (xy 349.181166 -220.810074)
			(xy 349.204026 -220.805756) (xy 349.409004 -220.450664) (xy 349.40113 -220.42882) (xy 349.392496 -220.402408)
			(xy 349.383168 -220.347635) (xy 349.382588 -220.319854) (xy 349.383096 -220.293947) (xy 349.391202 -220.24277)
			(xy 349.407214 -220.193491) (xy 349.430737 -220.147324) (xy 349.461193 -220.105405) (xy 349.497831 -220.068767)
			(xy 349.53975 -220.038311) (xy 349.585917 -220.014788) (xy 349.635196 -219.998776) (xy 349.686373 -219.99067)
			(xy 349.738187 -219.99067) (xy 349.789364 -219.998776) (xy 349.838643 -220.014788) (xy 349.88481 -220.038311)
			(xy 349.926729 -220.068767) (xy 349.963367 -220.105405) (xy 349.993823 -220.147324) (xy 350.017346 -220.193491)
			(xy 350.033358 -220.24277) (xy 350.041464 -220.293947) (xy 350.041972 -220.319854) (xy 350.041522 -220.3452)
			(xy 350.033742 -220.395293) (xy 350.018388 -220.443604) (xy 349.995822 -220.488998) (xy 349.966576 -220.530404)
			(xy 349.931339 -220.566847) (xy 349.89094 -220.597469) (xy 349.846331 -220.621548) (xy 349.798563 -220.638518)
			(xy 349.773748 -220.643704) (xy 349.750888 -220.648022) (xy 349.54591 -221.003114) (xy 349.553784 -221.024958)
			(xy 349.562377 -221.051373) (xy 349.571565 -221.106151) (xy 349.572072 -221.133924) (xy 349.852996 -221.133924)
			(xy 349.853504 -221.108037) (xy 349.861603 -221.056899) (xy 349.877602 -221.007659) (xy 349.901108 -220.961527)
			(xy 349.93154 -220.91964) (xy 349.96815 -220.88303) (xy 350.010037 -220.852598) (xy 350.056169 -220.829092)
			(xy 350.105409 -220.813093) (xy 350.156547 -220.804994) (xy 350.208321 -220.804994) (xy 350.259459 -220.813093)
			(xy 350.308699 -220.829092) (xy 350.354831 -220.852598) (xy 350.396718 -220.88303) (xy 350.433328 -220.91964)
			(xy 350.46376 -220.961527) (xy 350.487266 -221.007659) (xy 350.503265 -221.056899) (xy 350.511364 -221.108037)
			(xy 350.511872 -221.133924) (xy 350.792796 -221.133924) (xy 350.793304 -221.10859) (xy 350.801053 -221.058519)
			(xy 350.816372 -221.010223) (xy 350.8389 -220.96484) (xy 350.868106 -220.923438) (xy 350.903304 -220.886992)
			(xy 350.943663 -220.856361) (xy 350.988234 -220.832266) (xy 351.035967 -220.815274) (xy 351.060766 -220.810074)
			(xy 351.083626 -220.805756) (xy 351.288604 -220.450664) (xy 351.28073 -220.42882) (xy 351.272096 -220.402408)
			(xy 351.262768 -220.347635) (xy 351.262188 -220.319854) (xy 351.262696 -220.293947) (xy 351.270802 -220.24277)
			(xy 351.286814 -220.193491) (xy 351.310337 -220.147324) (xy 351.340793 -220.105405) (xy 351.377431 -220.068767)
			(xy 351.41935 -220.038311) (xy 351.465517 -220.014788) (xy 351.514796 -219.998776) (xy 351.565973 -219.99067)
			(xy 351.617787 -219.99067) (xy 351.668964 -219.998776) (xy 351.718243 -220.014788) (xy 351.76441 -220.038311)
			(xy 351.806329 -220.068767) (xy 351.842967 -220.105405) (xy 351.873423 -220.147324) (xy 351.896946 -220.193491)
			(xy 351.912958 -220.24277) (xy 351.921064 -220.293947) (xy 351.921572 -220.319854) (xy 353.141788 -220.319854)
			(xy 353.142296 -220.293947) (xy 353.150402 -220.24277) (xy 353.166414 -220.193491) (xy 353.189937 -220.147324)
			(xy 353.220393 -220.105405) (xy 353.257031 -220.068767) (xy 353.29895 -220.038311) (xy 353.345117 -220.014788)
			(xy 353.394396 -219.998776) (xy 353.445573 -219.99067) (xy 353.497387 -219.99067) (xy 353.548564 -219.998776)
			(xy 353.597843 -220.014788) (xy 353.64401 -220.038311) (xy 353.685929 -220.068767) (xy 353.722567 -220.105405)
			(xy 353.753023 -220.147324) (xy 353.776546 -220.193491) (xy 353.792558 -220.24277) (xy 353.800664 -220.293947)
			(xy 353.801172 -220.319854) (xy 355.021388 -220.319854) (xy 355.021896 -220.293947) (xy 355.030002 -220.24277)
			(xy 355.046014 -220.193491) (xy 355.069537 -220.147324) (xy 355.099993 -220.105405) (xy 355.136631 -220.068767)
			(xy 355.17855 -220.038311) (xy 355.224717 -220.014788) (xy 355.273996 -219.998776) (xy 355.325173 -219.99067)
			(xy 355.376987 -219.99067) (xy 355.428164 -219.998776) (xy 355.477443 -220.014788) (xy 355.52361 -220.038311)
			(xy 355.565529 -220.068767) (xy 355.602167 -220.105405) (xy 355.632623 -220.147324) (xy 355.656146 -220.193491)
			(xy 355.672158 -220.24277) (xy 355.680264 -220.293947) (xy 355.680772 -220.319854) (xy 356.900988 -220.319854)
			(xy 356.901496 -220.293947) (xy 356.909602 -220.24277) (xy 356.925614 -220.193491) (xy 356.949137 -220.147324)
			(xy 356.979593 -220.105405) (xy 357.016231 -220.068767) (xy 357.05815 -220.038311) (xy 357.104317 -220.014788)
			(xy 357.153596 -219.998776) (xy 357.204773 -219.99067) (xy 357.256587 -219.99067) (xy 357.307764 -219.998776)
			(xy 357.357043 -220.014788) (xy 357.40321 -220.038311) (xy 357.445129 -220.068767) (xy 357.481767 -220.105405)
			(xy 357.512223 -220.147324) (xy 357.535746 -220.193491) (xy 357.551758 -220.24277) (xy 357.559864 -220.293947)
			(xy 357.560372 -220.319854) (xy 358.780588 -220.319854) (xy 358.781096 -220.293947) (xy 358.789202 -220.24277)
			(xy 358.805214 -220.193491) (xy 358.828737 -220.147324) (xy 358.859193 -220.105405) (xy 358.895831 -220.068767)
			(xy 358.93775 -220.038311) (xy 358.983917 -220.014788) (xy 359.033196 -219.998776) (xy 359.084373 -219.99067)
			(xy 359.136187 -219.99067) (xy 359.187364 -219.998776) (xy 359.236643 -220.014788) (xy 359.28281 -220.038311)
			(xy 359.324729 -220.068767) (xy 359.361367 -220.105405) (xy 359.391823 -220.147324) (xy 359.415346 -220.193491)
			(xy 359.431358 -220.24277) (xy 359.439464 -220.293947) (xy 359.439972 -220.319854) (xy 360.660188 -220.319854)
			(xy 360.660696 -220.293947) (xy 360.668802 -220.24277) (xy 360.684814 -220.193491) (xy 360.708337 -220.147324)
			(xy 360.738793 -220.105405) (xy 360.775431 -220.068767) (xy 360.81735 -220.038311) (xy 360.863517 -220.014788)
			(xy 360.912796 -219.998776) (xy 360.963973 -219.99067) (xy 361.015787 -219.99067) (xy 361.066964 -219.998776)
			(xy 361.116243 -220.014788) (xy 361.16241 -220.038311) (xy 361.204329 -220.068767) (xy 361.240967 -220.105405)
			(xy 361.271423 -220.147324) (xy 361.294946 -220.193491) (xy 361.310958 -220.24277) (xy 361.319064 -220.293947)
			(xy 361.319572 -220.319854) (xy 362.539788 -220.319854) (xy 362.540296 -220.293947) (xy 362.548402 -220.24277)
			(xy 362.564414 -220.193491) (xy 362.587937 -220.147324) (xy 362.618393 -220.105405) (xy 362.655031 -220.068767)
			(xy 362.69695 -220.038311) (xy 362.743117 -220.014788) (xy 362.792396 -219.998776) (xy 362.843573 -219.99067)
			(xy 362.895387 -219.99067) (xy 362.946564 -219.998776) (xy 362.995843 -220.014788) (xy 363.04201 -220.038311)
			(xy 363.083929 -220.068767) (xy 363.120567 -220.105405) (xy 363.151023 -220.147324) (xy 363.174546 -220.193491)
			(xy 363.190558 -220.24277) (xy 363.198664 -220.293947) (xy 363.199172 -220.319854) (xy 364.419388 -220.319854)
			(xy 364.419896 -220.293947) (xy 364.428002 -220.24277) (xy 364.444014 -220.193491) (xy 364.467537 -220.147324)
			(xy 364.497993 -220.105405) (xy 364.534631 -220.068767) (xy 364.57655 -220.038311) (xy 364.622717 -220.014788)
			(xy 364.671996 -219.998776) (xy 364.723173 -219.99067) (xy 364.774987 -219.99067) (xy 364.826164 -219.998776)
			(xy 364.875443 -220.014788) (xy 364.92161 -220.038311) (xy 364.963529 -220.068767) (xy 365.000167 -220.105405)
			(xy 365.030623 -220.147324) (xy 365.054146 -220.193491) (xy 365.070158 -220.24277) (xy 365.078264 -220.293947)
			(xy 365.078772 -220.319854) (xy 366.298988 -220.319854) (xy 366.299496 -220.293947) (xy 366.307602 -220.24277)
			(xy 366.323614 -220.193491) (xy 366.347137 -220.147324) (xy 366.377593 -220.105405) (xy 366.414231 -220.068767)
			(xy 366.45615 -220.038311) (xy 366.502317 -220.014788) (xy 366.551596 -219.998776) (xy 366.602773 -219.99067)
			(xy 366.654587 -219.99067) (xy 366.705764 -219.998776) (xy 366.755043 -220.014788) (xy 366.80121 -220.038311)
			(xy 366.843129 -220.068767) (xy 366.879767 -220.105405) (xy 366.910223 -220.147324) (xy 366.933746 -220.193491)
			(xy 366.949758 -220.24277) (xy 366.957864 -220.293947) (xy 366.958372 -220.319854) (xy 368.178588 -220.319854)
			(xy 368.179096 -220.293947) (xy 368.187202 -220.24277) (xy 368.203214 -220.193491) (xy 368.226737 -220.147324)
			(xy 368.257193 -220.105405) (xy 368.293831 -220.068767) (xy 368.33575 -220.038311) (xy 368.381917 -220.014788)
			(xy 368.431196 -219.998776) (xy 368.482373 -219.99067) (xy 368.534187 -219.99067) (xy 368.585364 -219.998776)
			(xy 368.634643 -220.014788) (xy 368.68081 -220.038311) (xy 368.722729 -220.068767) (xy 368.759367 -220.105405)
			(xy 368.789823 -220.147324) (xy 368.813346 -220.193491) (xy 368.829358 -220.24277) (xy 368.837464 -220.293947)
			(xy 368.837972 -220.319854) (xy 370.058188 -220.319854) (xy 370.058696 -220.293947) (xy 370.066802 -220.24277)
			(xy 370.082814 -220.193491) (xy 370.106337 -220.147324) (xy 370.136793 -220.105405) (xy 370.173431 -220.068767)
			(xy 370.21535 -220.038311) (xy 370.261517 -220.014788) (xy 370.310796 -219.998776) (xy 370.361973 -219.99067)
			(xy 370.413787 -219.99067) (xy 370.464964 -219.998776) (xy 370.514243 -220.014788) (xy 370.56041 -220.038311)
			(xy 370.602329 -220.068767) (xy 370.638967 -220.105405) (xy 370.669423 -220.147324) (xy 370.692946 -220.193491)
			(xy 370.708958 -220.24277) (xy 370.717064 -220.293947) (xy 370.717572 -220.319854) (xy 371.937788 -220.319854)
			(xy 371.938296 -220.293947) (xy 371.946402 -220.24277) (xy 371.962414 -220.193491) (xy 371.985937 -220.147324)
			(xy 372.016393 -220.105405) (xy 372.053031 -220.068767) (xy 372.09495 -220.038311) (xy 372.141117 -220.014788)
			(xy 372.190396 -219.998776) (xy 372.241573 -219.99067) (xy 372.293387 -219.99067) (xy 372.344564 -219.998776)
			(xy 372.393843 -220.014788) (xy 372.44001 -220.038311) (xy 372.481929 -220.068767) (xy 372.518567 -220.105405)
			(xy 372.549023 -220.147324) (xy 372.572546 -220.193491) (xy 372.588558 -220.24277) (xy 372.596664 -220.293947)
			(xy 372.597172 -220.319854) (xy 373.817388 -220.319854) (xy 373.817896 -220.293947) (xy 373.826002 -220.24277)
			(xy 373.842014 -220.193491) (xy 373.865537 -220.147324) (xy 373.895993 -220.105405) (xy 373.932631 -220.068767)
			(xy 373.97455 -220.038311) (xy 374.020717 -220.014788) (xy 374.069996 -219.998776) (xy 374.121173 -219.99067)
			(xy 374.172987 -219.99067) (xy 374.224164 -219.998776) (xy 374.273443 -220.014788) (xy 374.31961 -220.038311)
			(xy 374.361529 -220.068767) (xy 374.398167 -220.105405) (xy 374.428623 -220.147324) (xy 374.452146 -220.193491)
			(xy 374.468158 -220.24277) (xy 374.476264 -220.293947) (xy 374.476772 -220.319854) (xy 375.696988 -220.319854)
			(xy 375.697496 -220.293947) (xy 375.705602 -220.24277) (xy 375.721614 -220.193491) (xy 375.745137 -220.147324)
			(xy 375.775593 -220.105405) (xy 375.812231 -220.068767) (xy 375.85415 -220.038311) (xy 375.900317 -220.014788)
			(xy 375.949596 -219.998776) (xy 376.000773 -219.99067) (xy 376.052587 -219.99067) (xy 376.103764 -219.998776)
			(xy 376.153043 -220.014788) (xy 376.19921 -220.038311) (xy 376.241129 -220.068767) (xy 376.277767 -220.105405)
			(xy 376.308223 -220.147324) (xy 376.331746 -220.193491) (xy 376.347758 -220.24277) (xy 376.355864 -220.293947)
			(xy 376.356372 -220.319854) (xy 377.576588 -220.319854) (xy 377.577096 -220.293947) (xy 377.585202 -220.24277)
			(xy 377.601214 -220.193491) (xy 377.624737 -220.147324) (xy 377.655193 -220.105405) (xy 377.691831 -220.068767)
			(xy 377.73375 -220.038311) (xy 377.779917 -220.014788) (xy 377.829196 -219.998776) (xy 377.880373 -219.99067)
			(xy 377.932187 -219.99067) (xy 377.983364 -219.998776) (xy 378.032643 -220.014788) (xy 378.07881 -220.038311)
			(xy 378.120729 -220.068767) (xy 378.157367 -220.105405) (xy 378.187823 -220.147324) (xy 378.211346 -220.193491)
			(xy 378.227358 -220.24277) (xy 378.235464 -220.293947) (xy 378.235972 -220.319854) (xy 379.456188 -220.319854)
			(xy 379.456696 -220.293947) (xy 379.464802 -220.24277) (xy 379.480814 -220.193491) (xy 379.504337 -220.147324)
			(xy 379.534793 -220.105405) (xy 379.571431 -220.068767) (xy 379.61335 -220.038311) (xy 379.659517 -220.014788)
			(xy 379.708796 -219.998776) (xy 379.759973 -219.99067) (xy 379.811787 -219.99067) (xy 379.862964 -219.998776)
			(xy 379.912243 -220.014788) (xy 379.95841 -220.038311) (xy 380.000329 -220.068767) (xy 380.036967 -220.105405)
			(xy 380.067423 -220.147324) (xy 380.090946 -220.193491) (xy 380.106958 -220.24277) (xy 380.115064 -220.293947)
			(xy 380.115572 -220.319854) (xy 381.336296 -220.319854) (xy 381.336804 -220.293967) (xy 381.344903 -220.242829)
			(xy 381.360902 -220.193589) (xy 381.384408 -220.147457) (xy 381.41484 -220.10557) (xy 381.45145 -220.06896)
			(xy 381.493337 -220.038528) (xy 381.539469 -220.015022) (xy 381.588709 -219.999023) (xy 381.639847 -219.990924)
			(xy 381.691621 -219.990924) (xy 381.742759 -219.999023) (xy 381.791999 -220.015022) (xy 381.838131 -220.038528)
			(xy 381.880018 -220.06896) (xy 381.916628 -220.10557) (xy 381.94706 -220.147457) (xy 381.970566 -220.193589)
			(xy 381.986565 -220.242829) (xy 381.994664 -220.293967) (xy 381.995172 -220.319854) (xy 381.994628 -220.347561)
			(xy 381.985442 -220.402208) (xy 381.976884 -220.428566) (xy 381.969264 -220.450664) (xy 382.174242 -220.805756)
			(xy 382.197102 -220.810074) (xy 382.221908 -220.815252) (xy 382.269647 -220.832242) (xy 382.314225 -220.856337)
			(xy 382.354591 -220.886969) (xy 382.389795 -220.923417) (xy 382.419006 -220.964822) (xy 382.441538 -221.01021)
			(xy 382.45686 -221.058511) (xy 382.46461 -221.108588) (xy 382.465072 -221.133924) (xy 382.464564 -221.159811)
			(xy 382.456465 -221.210949) (xy 382.440466 -221.260189) (xy 382.41696 -221.306321) (xy 382.386528 -221.348208)
			(xy 382.349918 -221.384818) (xy 382.308031 -221.41525) (xy 382.261899 -221.438756) (xy 382.212659 -221.454755)
			(xy 382.161521 -221.462854) (xy 382.109747 -221.462854) (xy 382.058609 -221.454755) (xy 382.009369 -221.438756)
			(xy 381.963237 -221.41525) (xy 381.92135 -221.384818) (xy 381.88474 -221.348208) (xy 381.854308 -221.306321)
			(xy 381.830802 -221.260189) (xy 381.814803 -221.210949) (xy 381.806704 -221.159811) (xy 381.806196 -221.133924)
			(xy 381.806732 -221.106216) (xy 381.815923 -221.051569) (xy 381.824484 -221.025212) (xy 381.832358 -221.003114)
			(xy 381.62738 -220.648022) (xy 381.60452 -220.643704) (xy 381.579694 -220.638559) (xy 381.531915 -220.6216)
			(xy 381.487296 -220.597525) (xy 381.446891 -220.566902) (xy 381.41165 -220.530452) (xy 381.382408 -220.489036)
			(xy 381.359851 -220.44363) (xy 381.344514 -220.395306) (xy 381.336758 -220.345204) (xy 381.336296 -220.319854)
			(xy 380.115572 -220.319854) (xy 380.114963 -220.347508) (xy 380.105639 -220.402026) (xy 380.09703 -220.428312)
			(xy 380.08941 -220.45041) (xy 380.294642 -220.805756) (xy 380.317502 -220.810074) (xy 380.342308 -220.815252)
			(xy 380.390047 -220.832242) (xy 380.434625 -220.856337) (xy 380.474991 -220.886969) (xy 380.510195 -220.923417)
			(xy 380.539406 -220.964822) (xy 380.561938 -221.01021) (xy 380.57726 -221.058511) (xy 380.58501 -221.108588)
			(xy 380.585472 -221.133924) (xy 380.584964 -221.159811) (xy 380.576865 -221.210949) (xy 380.560866 -221.260189)
			(xy 380.53736 -221.306321) (xy 380.506928 -221.348208) (xy 380.470318 -221.384818) (xy 380.428431 -221.41525)
			(xy 380.382299 -221.438756) (xy 380.333059 -221.454755) (xy 380.281921 -221.462854) (xy 380.230147 -221.462854)
			(xy 380.179009 -221.454755) (xy 380.129769 -221.438756) (xy 380.083637 -221.41525) (xy 380.04175 -221.384818)
			(xy 380.00514 -221.348208) (xy 379.974708 -221.306321) (xy 379.951202 -221.260189) (xy 379.935203 -221.210949)
			(xy 379.927104 -221.159811) (xy 379.926596 -221.133924) (xy 379.927132 -221.106216) (xy 379.936323 -221.051569)
			(xy 379.944884 -221.025212) (xy 379.952758 -221.003114) (xy 379.74778 -220.648022) (xy 379.72492 -220.643704)
			(xy 379.700079 -220.638521) (xy 379.652232 -220.621628) (xy 379.60754 -220.5976) (xy 379.567059 -220.567005)
			(xy 379.531748 -220.530566) (xy 379.502439 -220.489145) (xy 379.479827 -220.44372) (xy 379.464446 -220.395365)
			(xy 379.456659 -220.345225) (xy 379.456188 -220.319854) (xy 378.235972 -220.319854) (xy 378.235363 -220.347508)
			(xy 378.226039 -220.402026) (xy 378.21743 -220.428312) (xy 378.20981 -220.45041) (xy 378.415042 -220.805756)
			(xy 378.437902 -220.810074) (xy 378.462708 -220.815252) (xy 378.510447 -220.832242) (xy 378.555025 -220.856337)
			(xy 378.595391 -220.886969) (xy 378.630595 -220.923417) (xy 378.659806 -220.964822) (xy 378.682338 -221.01021)
			(xy 378.69766 -221.058511) (xy 378.70541 -221.108588) (xy 378.705872 -221.133924) (xy 378.705364 -221.159811)
			(xy 378.697265 -221.210949) (xy 378.681266 -221.260189) (xy 378.65776 -221.306321) (xy 378.627328 -221.348208)
			(xy 378.590718 -221.384818) (xy 378.548831 -221.41525) (xy 378.502699 -221.438756) (xy 378.453459 -221.454755)
			(xy 378.402321 -221.462854) (xy 378.350547 -221.462854) (xy 378.299409 -221.454755) (xy 378.250169 -221.438756)
			(xy 378.204037 -221.41525) (xy 378.16215 -221.384818) (xy 378.12554 -221.348208) (xy 378.095108 -221.306321)
			(xy 378.071602 -221.260189) (xy 378.055603 -221.210949) (xy 378.047504 -221.159811) (xy 378.046996 -221.133924)
			(xy 378.047532 -221.106216) (xy 378.056723 -221.051569) (xy 378.065284 -221.025212) (xy 378.073158 -221.003114)
			(xy 377.86818 -220.648022) (xy 377.84532 -220.643704) (xy 377.820479 -220.638521) (xy 377.772632 -220.621628)
			(xy 377.72794 -220.5976) (xy 377.687459 -220.567005) (xy 377.652148 -220.530566) (xy 377.622839 -220.489145)
			(xy 377.600227 -220.44372) (xy 377.584846 -220.395365) (xy 377.577059 -220.345225) (xy 377.576588 -220.319854)
			(xy 376.356372 -220.319854) (xy 376.355763 -220.347508) (xy 376.346439 -220.402026) (xy 376.33783 -220.428312)
			(xy 376.33021 -220.45041) (xy 376.535442 -220.805756) (xy 376.558302 -220.810074) (xy 376.583108 -220.815252)
			(xy 376.630847 -220.832242) (xy 376.675425 -220.856337) (xy 376.715791 -220.886969) (xy 376.750995 -220.923417)
			(xy 376.780206 -220.964822) (xy 376.802738 -221.01021) (xy 376.81806 -221.058511) (xy 376.82581 -221.108588)
			(xy 376.826272 -221.133924) (xy 376.825764 -221.159811) (xy 376.817665 -221.210949) (xy 376.801666 -221.260189)
			(xy 376.77816 -221.306321) (xy 376.747728 -221.348208) (xy 376.711118 -221.384818) (xy 376.669231 -221.41525)
			(xy 376.623099 -221.438756) (xy 376.573859 -221.454755) (xy 376.522721 -221.462854) (xy 376.470947 -221.462854)
			(xy 376.419809 -221.454755) (xy 376.370569 -221.438756) (xy 376.324437 -221.41525) (xy 376.28255 -221.384818)
			(xy 376.24594 -221.348208) (xy 376.215508 -221.306321) (xy 376.192002 -221.260189) (xy 376.176003 -221.210949)
			(xy 376.167904 -221.159811) (xy 376.167396 -221.133924) (xy 376.167932 -221.106216) (xy 376.177123 -221.051569)
			(xy 376.185684 -221.025212) (xy 376.193558 -221.003114) (xy 375.98858 -220.648022) (xy 375.96572 -220.643704)
			(xy 375.940879 -220.638521) (xy 375.893032 -220.621628) (xy 375.84834 -220.5976) (xy 375.807859 -220.567005)
			(xy 375.772548 -220.530566) (xy 375.743239 -220.489145) (xy 375.720627 -220.44372) (xy 375.705246 -220.395365)
			(xy 375.697459 -220.345225) (xy 375.696988 -220.319854) (xy 374.476772 -220.319854) (xy 374.476163 -220.347508)
			(xy 374.466839 -220.402026) (xy 374.45823 -220.428312) (xy 374.45061 -220.45041) (xy 374.655842 -220.805756)
			(xy 374.678702 -220.810074) (xy 374.703508 -220.815252) (xy 374.751247 -220.832242) (xy 374.795825 -220.856337)
			(xy 374.836191 -220.886969) (xy 374.871395 -220.923417) (xy 374.900606 -220.964822) (xy 374.923138 -221.01021)
			(xy 374.93846 -221.058511) (xy 374.94621 -221.108588) (xy 374.946672 -221.133924) (xy 374.946164 -221.159811)
			(xy 374.938065 -221.210949) (xy 374.922066 -221.260189) (xy 374.89856 -221.306321) (xy 374.868128 -221.348208)
			(xy 374.831518 -221.384818) (xy 374.789631 -221.41525) (xy 374.743499 -221.438756) (xy 374.694259 -221.454755)
			(xy 374.643121 -221.462854) (xy 374.591347 -221.462854) (xy 374.540209 -221.454755) (xy 374.490969 -221.438756)
			(xy 374.444837 -221.41525) (xy 374.40295 -221.384818) (xy 374.36634 -221.348208) (xy 374.335908 -221.306321)
			(xy 374.312402 -221.260189) (xy 374.296403 -221.210949) (xy 374.288304 -221.159811) (xy 374.287796 -221.133924)
			(xy 374.288332 -221.106216) (xy 374.297523 -221.051569) (xy 374.306084 -221.025212) (xy 374.313958 -221.003114)
			(xy 374.10898 -220.648022) (xy 374.08612 -220.643704) (xy 374.061279 -220.638521) (xy 374.013432 -220.621628)
			(xy 373.96874 -220.5976) (xy 373.928259 -220.567005) (xy 373.892948 -220.530566) (xy 373.863639 -220.489145)
			(xy 373.841027 -220.44372) (xy 373.825646 -220.395365) (xy 373.817859 -220.345225) (xy 373.817388 -220.319854)
			(xy 372.597172 -220.319854) (xy 372.596563 -220.347508) (xy 372.587239 -220.402026) (xy 372.57863 -220.428312)
			(xy 372.57101 -220.45041) (xy 372.776242 -220.805756) (xy 372.799102 -220.810074) (xy 372.823908 -220.815252)
			(xy 372.871647 -220.832242) (xy 372.916225 -220.856337) (xy 372.956591 -220.886969) (xy 372.991795 -220.923417)
			(xy 373.021006 -220.964822) (xy 373.043538 -221.01021) (xy 373.05886 -221.058511) (xy 373.06661 -221.108588)
			(xy 373.067072 -221.133924) (xy 373.066564 -221.159811) (xy 373.058465 -221.210949) (xy 373.042466 -221.260189)
			(xy 373.01896 -221.306321) (xy 372.988528 -221.348208) (xy 372.951918 -221.384818) (xy 372.910031 -221.41525)
			(xy 372.863899 -221.438756) (xy 372.814659 -221.454755) (xy 372.763521 -221.462854) (xy 372.711747 -221.462854)
			(xy 372.660609 -221.454755) (xy 372.611369 -221.438756) (xy 372.565237 -221.41525) (xy 372.52335 -221.384818)
			(xy 372.48674 -221.348208) (xy 372.456308 -221.306321) (xy 372.432802 -221.260189) (xy 372.416803 -221.210949)
			(xy 372.408704 -221.159811) (xy 372.408196 -221.133924) (xy 372.408732 -221.106216) (xy 372.417923 -221.051569)
			(xy 372.426484 -221.025212) (xy 372.434358 -221.003114) (xy 372.22938 -220.648022) (xy 372.20652 -220.643704)
			(xy 372.181679 -220.638521) (xy 372.133832 -220.621628) (xy 372.08914 -220.5976) (xy 372.048659 -220.567005)
			(xy 372.013348 -220.530566) (xy 371.984039 -220.489145) (xy 371.961427 -220.44372) (xy 371.946046 -220.395365)
			(xy 371.938259 -220.345225) (xy 371.937788 -220.319854) (xy 370.717572 -220.319854) (xy 370.716963 -220.347508)
			(xy 370.707639 -220.402026) (xy 370.69903 -220.428312) (xy 370.69141 -220.45041) (xy 370.896642 -220.805756)
			(xy 370.919502 -220.810074) (xy 370.944308 -220.815252) (xy 370.992047 -220.832242) (xy 371.036625 -220.856337)
			(xy 371.076991 -220.886969) (xy 371.112195 -220.923417) (xy 371.141406 -220.964822) (xy 371.163938 -221.01021)
			(xy 371.17926 -221.058511) (xy 371.18701 -221.108588) (xy 371.187472 -221.133924) (xy 371.186964 -221.159811)
			(xy 371.178865 -221.210949) (xy 371.162866 -221.260189) (xy 371.13936 -221.306321) (xy 371.108928 -221.348208)
			(xy 371.072318 -221.384818) (xy 371.030431 -221.41525) (xy 370.984299 -221.438756) (xy 370.935059 -221.454755)
			(xy 370.883921 -221.462854) (xy 370.832147 -221.462854) (xy 370.781009 -221.454755) (xy 370.731769 -221.438756)
			(xy 370.685637 -221.41525) (xy 370.64375 -221.384818) (xy 370.60714 -221.348208) (xy 370.576708 -221.306321)
			(xy 370.553202 -221.260189) (xy 370.537203 -221.210949) (xy 370.529104 -221.159811) (xy 370.528596 -221.133924)
			(xy 370.529132 -221.106216) (xy 370.538323 -221.051569) (xy 370.546884 -221.025212) (xy 370.554758 -221.003114)
			(xy 370.34978 -220.648022) (xy 370.32692 -220.643704) (xy 370.302079 -220.638521) (xy 370.254232 -220.621628)
			(xy 370.20954 -220.5976) (xy 370.169059 -220.567005) (xy 370.133748 -220.530566) (xy 370.104439 -220.489145)
			(xy 370.081827 -220.44372) (xy 370.066446 -220.395365) (xy 370.058659 -220.345225) (xy 370.058188 -220.319854)
			(xy 368.837972 -220.319854) (xy 368.837363 -220.347508) (xy 368.828039 -220.402026) (xy 368.81943 -220.428312)
			(xy 368.81181 -220.45041) (xy 369.017042 -220.805756) (xy 369.039902 -220.810074) (xy 369.064708 -220.815252)
			(xy 369.112447 -220.832242) (xy 369.157025 -220.856337) (xy 369.197391 -220.886969) (xy 369.232595 -220.923417)
			(xy 369.261806 -220.964822) (xy 369.284338 -221.01021) (xy 369.29966 -221.058511) (xy 369.30741 -221.108588)
			(xy 369.307872 -221.133924) (xy 369.307364 -221.159811) (xy 369.299265 -221.210949) (xy 369.283266 -221.260189)
			(xy 369.25976 -221.306321) (xy 369.229328 -221.348208) (xy 369.192718 -221.384818) (xy 369.150831 -221.41525)
			(xy 369.104699 -221.438756) (xy 369.055459 -221.454755) (xy 369.004321 -221.462854) (xy 368.952547 -221.462854)
			(xy 368.901409 -221.454755) (xy 368.852169 -221.438756) (xy 368.806037 -221.41525) (xy 368.76415 -221.384818)
			(xy 368.72754 -221.348208) (xy 368.697108 -221.306321) (xy 368.673602 -221.260189) (xy 368.657603 -221.210949)
			(xy 368.649504 -221.159811) (xy 368.648996 -221.133924) (xy 368.649532 -221.106216) (xy 368.658723 -221.051569)
			(xy 368.667284 -221.025212) (xy 368.675158 -221.003114) (xy 368.47018 -220.648022) (xy 368.44732 -220.643704)
			(xy 368.422479 -220.638521) (xy 368.374632 -220.621628) (xy 368.32994 -220.5976) (xy 368.289459 -220.567005)
			(xy 368.254148 -220.530566) (xy 368.224839 -220.489145) (xy 368.202227 -220.44372) (xy 368.186846 -220.395365)
			(xy 368.179059 -220.345225) (xy 368.178588 -220.319854) (xy 366.958372 -220.319854) (xy 366.957763 -220.347508)
			(xy 366.948439 -220.402026) (xy 366.93983 -220.428312) (xy 366.93221 -220.45041) (xy 367.137442 -220.805756)
			(xy 367.160302 -220.810074) (xy 367.185108 -220.815252) (xy 367.232847 -220.832242) (xy 367.277425 -220.856337)
			(xy 367.317791 -220.886969) (xy 367.352995 -220.923417) (xy 367.382206 -220.964822) (xy 367.404738 -221.01021)
			(xy 367.42006 -221.058511) (xy 367.42781 -221.108588) (xy 367.428272 -221.133924) (xy 367.427764 -221.159811)
			(xy 367.419665 -221.210949) (xy 367.403666 -221.260189) (xy 367.38016 -221.306321) (xy 367.349728 -221.348208)
			(xy 367.313118 -221.384818) (xy 367.271231 -221.41525) (xy 367.225099 -221.438756) (xy 367.175859 -221.454755)
			(xy 367.124721 -221.462854) (xy 367.072947 -221.462854) (xy 367.021809 -221.454755) (xy 366.972569 -221.438756)
			(xy 366.926437 -221.41525) (xy 366.88455 -221.384818) (xy 366.84794 -221.348208) (xy 366.817508 -221.306321)
			(xy 366.794002 -221.260189) (xy 366.778003 -221.210949) (xy 366.769904 -221.159811) (xy 366.769396 -221.133924)
			(xy 366.769932 -221.106216) (xy 366.779123 -221.051569) (xy 366.787684 -221.025212) (xy 366.795558 -221.003114)
			(xy 366.59058 -220.648022) (xy 366.56772 -220.643704) (xy 366.542879 -220.638521) (xy 366.495032 -220.621628)
			(xy 366.45034 -220.5976) (xy 366.409859 -220.567005) (xy 366.374548 -220.530566) (xy 366.345239 -220.489145)
			(xy 366.322627 -220.44372) (xy 366.307246 -220.395365) (xy 366.299459 -220.345225) (xy 366.298988 -220.319854)
			(xy 365.078772 -220.319854) (xy 365.078163 -220.347508) (xy 365.068839 -220.402026) (xy 365.06023 -220.428312)
			(xy 365.05261 -220.45041) (xy 365.257842 -220.805756) (xy 365.280702 -220.810074) (xy 365.305508 -220.815252)
			(xy 365.353247 -220.832242) (xy 365.397825 -220.856337) (xy 365.438191 -220.886969) (xy 365.473395 -220.923417)
			(xy 365.502606 -220.964822) (xy 365.525138 -221.01021) (xy 365.54046 -221.058511) (xy 365.54821 -221.108588)
			(xy 365.548672 -221.133924) (xy 365.548164 -221.159811) (xy 365.540065 -221.210949) (xy 365.524066 -221.260189)
			(xy 365.50056 -221.306321) (xy 365.470128 -221.348208) (xy 365.433518 -221.384818) (xy 365.391631 -221.41525)
			(xy 365.345499 -221.438756) (xy 365.296259 -221.454755) (xy 365.245121 -221.462854) (xy 365.193347 -221.462854)
			(xy 365.142209 -221.454755) (xy 365.092969 -221.438756) (xy 365.046837 -221.41525) (xy 365.00495 -221.384818)
			(xy 364.96834 -221.348208) (xy 364.937908 -221.306321) (xy 364.914402 -221.260189) (xy 364.898403 -221.210949)
			(xy 364.890304 -221.159811) (xy 364.889796 -221.133924) (xy 364.890332 -221.106216) (xy 364.899523 -221.051569)
			(xy 364.908084 -221.025212) (xy 364.915958 -221.003114) (xy 364.71098 -220.648022) (xy 364.68812 -220.643704)
			(xy 364.663279 -220.638521) (xy 364.615432 -220.621628) (xy 364.57074 -220.5976) (xy 364.530259 -220.567005)
			(xy 364.494948 -220.530566) (xy 364.465639 -220.489145) (xy 364.443027 -220.44372) (xy 364.427646 -220.395365)
			(xy 364.419859 -220.345225) (xy 364.419388 -220.319854) (xy 363.199172 -220.319854) (xy 363.198563 -220.347508)
			(xy 363.189239 -220.402026) (xy 363.18063 -220.428312) (xy 363.17301 -220.45041) (xy 363.378242 -220.805756)
			(xy 363.401102 -220.810074) (xy 363.425908 -220.815252) (xy 363.473647 -220.832242) (xy 363.518225 -220.856337)
			(xy 363.558591 -220.886969) (xy 363.593795 -220.923417) (xy 363.623006 -220.964822) (xy 363.645538 -221.01021)
			(xy 363.66086 -221.058511) (xy 363.66861 -221.108588) (xy 363.669072 -221.133924) (xy 363.668564 -221.159811)
			(xy 363.660465 -221.210949) (xy 363.644466 -221.260189) (xy 363.62096 -221.306321) (xy 363.590528 -221.348208)
			(xy 363.553918 -221.384818) (xy 363.512031 -221.41525) (xy 363.465899 -221.438756) (xy 363.416659 -221.454755)
			(xy 363.365521 -221.462854) (xy 363.313747 -221.462854) (xy 363.262609 -221.454755) (xy 363.213369 -221.438756)
			(xy 363.167237 -221.41525) (xy 363.12535 -221.384818) (xy 363.08874 -221.348208) (xy 363.058308 -221.306321)
			(xy 363.034802 -221.260189) (xy 363.018803 -221.210949) (xy 363.010704 -221.159811) (xy 363.010196 -221.133924)
			(xy 363.010732 -221.106216) (xy 363.019923 -221.051569) (xy 363.028484 -221.025212) (xy 363.036358 -221.003114)
			(xy 362.83138 -220.648022) (xy 362.80852 -220.643704) (xy 362.783679 -220.638521) (xy 362.735832 -220.621628)
			(xy 362.69114 -220.5976) (xy 362.650659 -220.567005) (xy 362.615348 -220.530566) (xy 362.586039 -220.489145)
			(xy 362.563427 -220.44372) (xy 362.548046 -220.395365) (xy 362.540259 -220.345225) (xy 362.539788 -220.319854)
			(xy 361.319572 -220.319854) (xy 361.318963 -220.347508) (xy 361.309639 -220.402026) (xy 361.30103 -220.428312)
			(xy 361.29341 -220.45041) (xy 361.498642 -220.805756) (xy 361.521502 -220.810074) (xy 361.546308 -220.815252)
			(xy 361.594047 -220.832242) (xy 361.638625 -220.856337) (xy 361.678991 -220.886969) (xy 361.714195 -220.923417)
			(xy 361.743406 -220.964822) (xy 361.765938 -221.01021) (xy 361.78126 -221.058511) (xy 361.78901 -221.108588)
			(xy 361.789472 -221.133924) (xy 361.788964 -221.159811) (xy 361.780865 -221.210949) (xy 361.764866 -221.260189)
			(xy 361.74136 -221.306321) (xy 361.710928 -221.348208) (xy 361.674318 -221.384818) (xy 361.632431 -221.41525)
			(xy 361.586299 -221.438756) (xy 361.537059 -221.454755) (xy 361.485921 -221.462854) (xy 361.434147 -221.462854)
			(xy 361.383009 -221.454755) (xy 361.333769 -221.438756) (xy 361.287637 -221.41525) (xy 361.24575 -221.384818)
			(xy 361.20914 -221.348208) (xy 361.178708 -221.306321) (xy 361.155202 -221.260189) (xy 361.139203 -221.210949)
			(xy 361.131104 -221.159811) (xy 361.130596 -221.133924) (xy 361.131132 -221.106216) (xy 361.140323 -221.051569)
			(xy 361.148884 -221.025212) (xy 361.156758 -221.003114) (xy 360.95178 -220.648022) (xy 360.92892 -220.643704)
			(xy 360.904079 -220.638521) (xy 360.856232 -220.621628) (xy 360.81154 -220.5976) (xy 360.771059 -220.567005)
			(xy 360.735748 -220.530566) (xy 360.706439 -220.489145) (xy 360.683827 -220.44372) (xy 360.668446 -220.395365)
			(xy 360.660659 -220.345225) (xy 360.660188 -220.319854) (xy 359.439972 -220.319854) (xy 359.439363 -220.347508)
			(xy 359.430039 -220.402026) (xy 359.42143 -220.428312) (xy 359.41381 -220.45041) (xy 359.619042 -220.805756)
			(xy 359.641902 -220.810074) (xy 359.666708 -220.815252) (xy 359.714447 -220.832242) (xy 359.759025 -220.856337)
			(xy 359.799391 -220.886969) (xy 359.834595 -220.923417) (xy 359.863806 -220.964822) (xy 359.886338 -221.01021)
			(xy 359.90166 -221.058511) (xy 359.90941 -221.108588) (xy 359.909872 -221.133924) (xy 359.909364 -221.159811)
			(xy 359.901265 -221.210949) (xy 359.885266 -221.260189) (xy 359.86176 -221.306321) (xy 359.831328 -221.348208)
			(xy 359.794718 -221.384818) (xy 359.752831 -221.41525) (xy 359.706699 -221.438756) (xy 359.657459 -221.454755)
			(xy 359.606321 -221.462854) (xy 359.554547 -221.462854) (xy 359.503409 -221.454755) (xy 359.454169 -221.438756)
			(xy 359.408037 -221.41525) (xy 359.36615 -221.384818) (xy 359.32954 -221.348208) (xy 359.299108 -221.306321)
			(xy 359.275602 -221.260189) (xy 359.259603 -221.210949) (xy 359.251504 -221.159811) (xy 359.250996 -221.133924)
			(xy 359.251532 -221.106216) (xy 359.260723 -221.051569) (xy 359.269284 -221.025212) (xy 359.277158 -221.003114)
			(xy 359.07218 -220.648022) (xy 359.04932 -220.643704) (xy 359.024479 -220.638521) (xy 358.976632 -220.621628)
			(xy 358.93194 -220.5976) (xy 358.891459 -220.567005) (xy 358.856148 -220.530566) (xy 358.826839 -220.489145)
			(xy 358.804227 -220.44372) (xy 358.788846 -220.395365) (xy 358.781059 -220.345225) (xy 358.780588 -220.319854)
			(xy 357.560372 -220.319854) (xy 357.559763 -220.347508) (xy 357.550439 -220.402026) (xy 357.54183 -220.428312)
			(xy 357.53421 -220.45041) (xy 357.739442 -220.805756) (xy 357.762302 -220.810074) (xy 357.787108 -220.815252)
			(xy 357.834847 -220.832242) (xy 357.879425 -220.856337) (xy 357.919791 -220.886969) (xy 357.954995 -220.923417)
			(xy 357.984206 -220.964822) (xy 358.006738 -221.01021) (xy 358.02206 -221.058511) (xy 358.02981 -221.108588)
			(xy 358.030272 -221.133924) (xy 358.029764 -221.159811) (xy 358.021665 -221.210949) (xy 358.005666 -221.260189)
			(xy 357.98216 -221.306321) (xy 357.951728 -221.348208) (xy 357.915118 -221.384818) (xy 357.873231 -221.41525)
			(xy 357.827099 -221.438756) (xy 357.777859 -221.454755) (xy 357.726721 -221.462854) (xy 357.674947 -221.462854)
			(xy 357.623809 -221.454755) (xy 357.574569 -221.438756) (xy 357.528437 -221.41525) (xy 357.48655 -221.384818)
			(xy 357.44994 -221.348208) (xy 357.419508 -221.306321) (xy 357.396002 -221.260189) (xy 357.380003 -221.210949)
			(xy 357.371904 -221.159811) (xy 357.371396 -221.133924) (xy 357.371932 -221.106216) (xy 357.381123 -221.051569)
			(xy 357.389684 -221.025212) (xy 357.397558 -221.003114) (xy 357.19258 -220.648022) (xy 357.16972 -220.643704)
			(xy 357.144879 -220.638521) (xy 357.097032 -220.621628) (xy 357.05234 -220.5976) (xy 357.011859 -220.567005)
			(xy 356.976548 -220.530566) (xy 356.947239 -220.489145) (xy 356.924627 -220.44372) (xy 356.909246 -220.395365)
			(xy 356.901459 -220.345225) (xy 356.900988 -220.319854) (xy 355.680772 -220.319854) (xy 355.680163 -220.347508)
			(xy 355.670839 -220.402026) (xy 355.66223 -220.428312) (xy 355.65461 -220.45041) (xy 355.859842 -220.805756)
			(xy 355.882702 -220.810074) (xy 355.907508 -220.815252) (xy 355.955247 -220.832242) (xy 355.999825 -220.856337)
			(xy 356.040191 -220.886969) (xy 356.075395 -220.923417) (xy 356.104606 -220.964822) (xy 356.127138 -221.01021)
			(xy 356.14246 -221.058511) (xy 356.15021 -221.108588) (xy 356.150672 -221.133924) (xy 356.150164 -221.159811)
			(xy 356.142065 -221.210949) (xy 356.126066 -221.260189) (xy 356.10256 -221.306321) (xy 356.072128 -221.348208)
			(xy 356.035518 -221.384818) (xy 355.993631 -221.41525) (xy 355.947499 -221.438756) (xy 355.898259 -221.454755)
			(xy 355.847121 -221.462854) (xy 355.795347 -221.462854) (xy 355.744209 -221.454755) (xy 355.694969 -221.438756)
			(xy 355.648837 -221.41525) (xy 355.60695 -221.384818) (xy 355.57034 -221.348208) (xy 355.539908 -221.306321)
			(xy 355.516402 -221.260189) (xy 355.500403 -221.210949) (xy 355.492304 -221.159811) (xy 355.491796 -221.133924)
			(xy 355.492332 -221.106216) (xy 355.501523 -221.051569) (xy 355.510084 -221.025212) (xy 355.517958 -221.003114)
			(xy 355.31298 -220.648022) (xy 355.29012 -220.643704) (xy 355.265279 -220.638521) (xy 355.217432 -220.621628)
			(xy 355.17274 -220.5976) (xy 355.132259 -220.567005) (xy 355.096948 -220.530566) (xy 355.067639 -220.489145)
			(xy 355.045027 -220.44372) (xy 355.029646 -220.395365) (xy 355.021859 -220.345225) (xy 355.021388 -220.319854)
			(xy 353.801172 -220.319854) (xy 353.800563 -220.347508) (xy 353.791239 -220.402026) (xy 353.78263 -220.428312)
			(xy 353.77501 -220.45041) (xy 353.980242 -220.805756) (xy 354.003102 -220.810074) (xy 354.027908 -220.815252)
			(xy 354.075647 -220.832242) (xy 354.120225 -220.856337) (xy 354.160591 -220.886969) (xy 354.195795 -220.923417)
			(xy 354.225006 -220.964822) (xy 354.247538 -221.01021) (xy 354.26286 -221.058511) (xy 354.27061 -221.108588)
			(xy 354.271072 -221.133924) (xy 354.270564 -221.159811) (xy 354.262465 -221.210949) (xy 354.246466 -221.260189)
			(xy 354.22296 -221.306321) (xy 354.192528 -221.348208) (xy 354.155918 -221.384818) (xy 354.114031 -221.41525)
			(xy 354.067899 -221.438756) (xy 354.018659 -221.454755) (xy 353.967521 -221.462854) (xy 353.915747 -221.462854)
			(xy 353.864609 -221.454755) (xy 353.815369 -221.438756) (xy 353.769237 -221.41525) (xy 353.72735 -221.384818)
			(xy 353.69074 -221.348208) (xy 353.660308 -221.306321) (xy 353.636802 -221.260189) (xy 353.620803 -221.210949)
			(xy 353.612704 -221.159811) (xy 353.612196 -221.133924) (xy 353.612732 -221.106216) (xy 353.621923 -221.051569)
			(xy 353.630484 -221.025212) (xy 353.638358 -221.003114) (xy 353.43338 -220.648022) (xy 353.41052 -220.643704)
			(xy 353.385679 -220.638521) (xy 353.337832 -220.621628) (xy 353.29314 -220.5976) (xy 353.252659 -220.567005)
			(xy 353.217348 -220.530566) (xy 353.188039 -220.489145) (xy 353.165427 -220.44372) (xy 353.150046 -220.395365)
			(xy 353.142259 -220.345225) (xy 353.141788 -220.319854) (xy 351.921572 -220.319854) (xy 351.921122 -220.3452)
			(xy 351.913342 -220.395293) (xy 351.897988 -220.443604) (xy 351.875422 -220.488998) (xy 351.846176 -220.530404)
			(xy 351.810939 -220.566847) (xy 351.77054 -220.597469) (xy 351.725931 -220.621548) (xy 351.678163 -220.638518)
			(xy 351.653348 -220.643704) (xy 351.630488 -220.648022) (xy 351.42551 -221.003114) (xy 351.433384 -221.024958)
			(xy 351.441977 -221.051373) (xy 351.451165 -221.106151) (xy 351.451672 -221.133924) (xy 351.451164 -221.159811)
			(xy 351.443065 -221.210949) (xy 351.427066 -221.260189) (xy 351.40356 -221.306321) (xy 351.373128 -221.348208)
			(xy 351.336518 -221.384818) (xy 351.294631 -221.41525) (xy 351.248499 -221.438756) (xy 351.199259 -221.454755)
			(xy 351.148121 -221.462854) (xy 351.096347 -221.462854) (xy 351.045209 -221.454755) (xy 350.995969 -221.438756)
			(xy 350.949837 -221.41525) (xy 350.90795 -221.384818) (xy 350.87134 -221.348208) (xy 350.840908 -221.306321)
			(xy 350.817402 -221.260189) (xy 350.801403 -221.210949) (xy 350.793304 -221.159811) (xy 350.792796 -221.133924)
			(xy 350.511872 -221.133924) (xy 350.511345 -221.161632) (xy 350.502148 -221.216279) (xy 350.493584 -221.242636)
			(xy 350.48571 -221.264734) (xy 350.690688 -221.619572) (xy 350.713548 -221.62389) (xy 350.738367 -221.629064)
			(xy 350.786146 -221.646018) (xy 350.830765 -221.670088) (xy 350.871172 -221.700708) (xy 350.906413 -221.737154)
			(xy 350.935657 -221.778566) (xy 350.958214 -221.823969) (xy 350.973552 -221.872291) (xy 350.98131 -221.922391)
			(xy 350.981772 -221.94774) (xy 352.201988 -221.94774) (xy 352.202465 -221.922395) (xy 352.210245 -221.872306)
			(xy 352.225597 -221.823996) (xy 352.24816 -221.778605) (xy 352.277403 -221.7372) (xy 352.312637 -221.700757)
			(xy 352.353031 -221.670134) (xy 352.397636 -221.646052) (xy 352.445399 -221.629078) (xy 352.470212 -221.62389)
			(xy 352.493072 -221.619572) (xy 352.698304 -221.264226) (xy 352.69043 -221.242128) (xy 352.681965 -221.215883)
			(xy 352.672893 -221.161495) (xy 352.672396 -221.133924) (xy 352.672904 -221.108037) (xy 352.681003 -221.056899)
			(xy 352.697002 -221.007659) (xy 352.720508 -220.961527) (xy 352.75094 -220.91964) (xy 352.78755 -220.88303)
			(xy 352.829437 -220.852598) (xy 352.875569 -220.829092) (xy 352.924809 -220.813093) (xy 352.975947 -220.804994)
			(xy 353.027721 -220.804994) (xy 353.078859 -220.813093) (xy 353.128099 -220.829092) (xy 353.174231 -220.852598)
			(xy 353.216118 -220.88303) (xy 353.252728 -220.91964) (xy 353.28316 -220.961527) (xy 353.306666 -221.007659)
			(xy 353.322665 -221.056899) (xy 353.330764 -221.108037) (xy 353.331272 -221.133924) (xy 353.330842 -221.1593)
			(xy 353.323069 -221.209454) (xy 353.307696 -221.257821) (xy 353.285086 -221.303259) (xy 353.255774 -221.344691)
			(xy 353.220455 -221.381137) (xy 353.179963 -221.411734) (xy 353.135258 -221.435759) (xy 353.087396 -221.452643)
			(xy 353.06254 -221.457774) (xy 353.03968 -221.462092) (xy 352.834956 -221.81693) (xy 352.84283 -221.838774)
			(xy 352.851486 -221.865179) (xy 352.8608 -221.919958) (xy 352.861372 -221.94774) (xy 354.081588 -221.94774)
			(xy 354.082065 -221.922395) (xy 354.089845 -221.872306) (xy 354.105197 -221.823996) (xy 354.12776 -221.778605)
			(xy 354.157003 -221.7372) (xy 354.192237 -221.700757) (xy 354.232631 -221.670134) (xy 354.277236 -221.646052)
			(xy 354.324999 -221.629078) (xy 354.349812 -221.62389) (xy 354.372672 -221.619572) (xy 354.577904 -221.264226)
			(xy 354.57003 -221.242128) (xy 354.561565 -221.215883) (xy 354.552493 -221.161495) (xy 354.551996 -221.133924)
			(xy 354.552504 -221.108037) (xy 354.560603 -221.056899) (xy 354.576602 -221.007659) (xy 354.600108 -220.961527)
			(xy 354.63054 -220.91964) (xy 354.66715 -220.88303) (xy 354.709037 -220.852598) (xy 354.755169 -220.829092)
			(xy 354.804409 -220.813093) (xy 354.855547 -220.804994) (xy 354.907321 -220.804994) (xy 354.958459 -220.813093)
			(xy 355.007699 -220.829092) (xy 355.053831 -220.852598) (xy 355.095718 -220.88303) (xy 355.132328 -220.91964)
			(xy 355.16276 -220.961527) (xy 355.186266 -221.007659) (xy 355.202265 -221.056899) (xy 355.210364 -221.108037)
			(xy 355.210872 -221.133924) (xy 355.210442 -221.1593) (xy 355.202669 -221.209454) (xy 355.187296 -221.257821)
			(xy 355.164686 -221.303259) (xy 355.135374 -221.344691) (xy 355.100055 -221.381137) (xy 355.059563 -221.411734)
			(xy 355.014858 -221.435759) (xy 354.966996 -221.452643) (xy 354.94214 -221.457774) (xy 354.91928 -221.462092)
			(xy 354.714556 -221.81693) (xy 354.72243 -221.838774) (xy 354.731086 -221.865179) (xy 354.7404 -221.919958)
			(xy 354.740972 -221.94774) (xy 355.961188 -221.94774) (xy 355.961665 -221.922395) (xy 355.969445 -221.872306)
			(xy 355.984797 -221.823996) (xy 356.00736 -221.778605) (xy 356.036603 -221.7372) (xy 356.071837 -221.700757)
			(xy 356.112231 -221.670134) (xy 356.156836 -221.646052) (xy 356.204599 -221.629078) (xy 356.229412 -221.62389)
			(xy 356.252272 -221.619572) (xy 356.457504 -221.264226) (xy 356.44963 -221.242128) (xy 356.441165 -221.215883)
			(xy 356.432093 -221.161495) (xy 356.431596 -221.133924) (xy 356.432104 -221.108037) (xy 356.440203 -221.056899)
			(xy 356.456202 -221.007659) (xy 356.479708 -220.961527) (xy 356.51014 -220.91964) (xy 356.54675 -220.88303)
			(xy 356.588637 -220.852598) (xy 356.634769 -220.829092) (xy 356.684009 -220.813093) (xy 356.735147 -220.804994)
			(xy 356.786921 -220.804994) (xy 356.838059 -220.813093) (xy 356.887299 -220.829092) (xy 356.933431 -220.852598)
			(xy 356.975318 -220.88303) (xy 357.011928 -220.91964) (xy 357.04236 -220.961527) (xy 357.065866 -221.007659)
			(xy 357.081865 -221.056899) (xy 357.089964 -221.108037) (xy 357.090472 -221.133924) (xy 357.090042 -221.1593)
			(xy 357.082269 -221.209454) (xy 357.066896 -221.257821) (xy 357.044286 -221.303259) (xy 357.014974 -221.344691)
			(xy 356.979655 -221.381137) (xy 356.939163 -221.411734) (xy 356.894458 -221.435759) (xy 356.846596 -221.452643)
			(xy 356.82174 -221.457774) (xy 356.79888 -221.462092) (xy 356.594156 -221.81693) (xy 356.60203 -221.838774)
			(xy 356.610686 -221.865179) (xy 356.62 -221.919958) (xy 356.620572 -221.94774) (xy 357.841296 -221.94774)
			(xy 357.841727 -221.922404) (xy 357.849489 -221.872329) (xy 357.864819 -221.824032) (xy 357.887358 -221.778648)
			(xy 357.916574 -221.737246) (xy 357.95178 -221.700802) (xy 357.992148 -221.670172) (xy 358.036725 -221.646079)
			(xy 358.084465 -221.629089) (xy 358.109266 -221.62389) (xy 358.132126 -221.619572) (xy 358.337104 -221.26448)
			(xy 358.329484 -221.242382) (xy 358.320964 -221.216211) (xy 358.311771 -221.161949) (xy 358.311196 -221.134432)
			(xy 358.311196 -221.133924) (xy 358.311704 -221.108037) (xy 358.319803 -221.056899) (xy 358.335802 -221.007659)
			(xy 358.359308 -220.961527) (xy 358.38974 -220.91964) (xy 358.42635 -220.88303) (xy 358.468237 -220.852598)
			(xy 358.514369 -220.829092) (xy 358.563609 -220.813093) (xy 358.614747 -220.804994) (xy 358.666521 -220.804994)
			(xy 358.717659 -220.813093) (xy 358.766899 -220.829092) (xy 358.813031 -220.852598) (xy 358.854918 -220.88303)
			(xy 358.891528 -220.91964) (xy 358.92196 -220.961527) (xy 358.945466 -221.007659) (xy 358.961465 -221.056899)
			(xy 358.969564 -221.108037) (xy 358.970072 -221.133924) (xy 358.969679 -221.159291) (xy 358.961926 -221.209429)
			(xy 358.946575 -221.257784) (xy 358.923991 -221.303213) (xy 358.894706 -221.344642) (xy 358.859415 -221.381089)
			(xy 358.818952 -221.411694) (xy 358.774274 -221.435731) (xy 358.726438 -221.452632) (xy 358.701594 -221.457774)
			(xy 358.678734 -221.462092) (xy 358.47401 -221.81693) (xy 358.481884 -221.838774) (xy 358.490481 -221.865188)
			(xy 358.499666 -221.919967) (xy 358.500172 -221.94774) (xy 359.720388 -221.94774) (xy 359.720865 -221.922395)
			(xy 359.728645 -221.872306) (xy 359.743997 -221.823996) (xy 359.76656 -221.778605) (xy 359.795803 -221.7372)
			(xy 359.831037 -221.700757) (xy 359.871431 -221.670134) (xy 359.916036 -221.646052) (xy 359.963799 -221.629078)
			(xy 359.988612 -221.62389) (xy 360.011472 -221.619572) (xy 360.216704 -221.264226) (xy 360.20883 -221.242128)
			(xy 360.200365 -221.215883) (xy 360.191293 -221.161495) (xy 360.190796 -221.133924) (xy 360.191304 -221.108037)
			(xy 360.199403 -221.056899) (xy 360.215402 -221.007659) (xy 360.238908 -220.961527) (xy 360.26934 -220.91964)
			(xy 360.30595 -220.88303) (xy 360.347837 -220.852598) (xy 360.393969 -220.829092) (xy 360.443209 -220.813093)
			(xy 360.494347 -220.804994) (xy 360.546121 -220.804994) (xy 360.597259 -220.813093) (xy 360.646499 -220.829092)
			(xy 360.692631 -220.852598) (xy 360.734518 -220.88303) (xy 360.771128 -220.91964) (xy 360.80156 -220.961527)
			(xy 360.825066 -221.007659) (xy 360.841065 -221.056899) (xy 360.849164 -221.108037) (xy 360.849672 -221.133924)
			(xy 360.849242 -221.1593) (xy 360.841469 -221.209454) (xy 360.826096 -221.257821) (xy 360.803486 -221.303259)
			(xy 360.774174 -221.344691) (xy 360.738855 -221.381137) (xy 360.698363 -221.411734) (xy 360.653658 -221.435759)
			(xy 360.605796 -221.452643) (xy 360.58094 -221.457774) (xy 360.55808 -221.462092) (xy 360.353356 -221.81693)
			(xy 360.36123 -221.838774) (xy 360.369886 -221.865179) (xy 360.3792 -221.919958) (xy 360.379772 -221.94774)
			(xy 361.600496 -221.94774) (xy 361.600927 -221.922404) (xy 361.608689 -221.872329) (xy 361.624019 -221.824032)
			(xy 361.646558 -221.778648) (xy 361.675774 -221.737246) (xy 361.71098 -221.700802) (xy 361.751348 -221.670172)
			(xy 361.795925 -221.646079) (xy 361.843665 -221.629089) (xy 361.868466 -221.62389) (xy 361.891326 -221.619572)
			(xy 362.096304 -221.26448) (xy 362.088684 -221.242382) (xy 362.080164 -221.216211) (xy 362.070971 -221.161949)
			(xy 362.070396 -221.134432) (xy 362.070396 -221.133924) (xy 362.070904 -221.108037) (xy 362.079003 -221.056899)
			(xy 362.095002 -221.007659) (xy 362.118508 -220.961527) (xy 362.14894 -220.91964) (xy 362.18555 -220.88303)
			(xy 362.227437 -220.852598) (xy 362.273569 -220.829092) (xy 362.322809 -220.813093) (xy 362.373947 -220.804994)
			(xy 362.425721 -220.804994) (xy 362.476859 -220.813093) (xy 362.526099 -220.829092) (xy 362.572231 -220.852598)
			(xy 362.614118 -220.88303) (xy 362.650728 -220.91964) (xy 362.68116 -220.961527) (xy 362.704666 -221.007659)
			(xy 362.720665 -221.056899) (xy 362.728764 -221.108037) (xy 362.729272 -221.133924) (xy 362.728879 -221.159291)
			(xy 362.721126 -221.209429) (xy 362.705775 -221.257784) (xy 362.683191 -221.303213) (xy 362.653906 -221.344642)
			(xy 362.618615 -221.381089) (xy 362.578152 -221.411694) (xy 362.533474 -221.435731) (xy 362.485638 -221.452632)
			(xy 362.460794 -221.457774) (xy 362.437934 -221.462092) (xy 362.23321 -221.81693) (xy 362.241084 -221.838774)
			(xy 362.249681 -221.865188) (xy 362.258866 -221.919967) (xy 362.259372 -221.94774) (xy 363.479588 -221.94774)
			(xy 363.480065 -221.922395) (xy 363.487845 -221.872306) (xy 363.503197 -221.823996) (xy 363.52576 -221.778605)
			(xy 363.555003 -221.7372) (xy 363.590237 -221.700757) (xy 363.630631 -221.670134) (xy 363.675236 -221.646052)
			(xy 363.722999 -221.629078) (xy 363.747812 -221.62389) (xy 363.770672 -221.619572) (xy 363.975904 -221.264226)
			(xy 363.96803 -221.242128) (xy 363.959565 -221.215883) (xy 363.950493 -221.161495) (xy 363.949996 -221.133924)
			(xy 363.950504 -221.108037) (xy 363.958603 -221.056899) (xy 363.974602 -221.007659) (xy 363.998108 -220.961527)
			(xy 364.02854 -220.91964) (xy 364.06515 -220.88303) (xy 364.107037 -220.852598) (xy 364.153169 -220.829092)
			(xy 364.202409 -220.813093) (xy 364.253547 -220.804994) (xy 364.305321 -220.804994) (xy 364.356459 -220.813093)
			(xy 364.405699 -220.829092) (xy 364.451831 -220.852598) (xy 364.493718 -220.88303) (xy 364.530328 -220.91964)
			(xy 364.56076 -220.961527) (xy 364.584266 -221.007659) (xy 364.600265 -221.056899) (xy 364.608364 -221.108037)
			(xy 364.608872 -221.133924) (xy 364.608442 -221.1593) (xy 364.600669 -221.209454) (xy 364.585296 -221.257821)
			(xy 364.562686 -221.303259) (xy 364.533374 -221.344691) (xy 364.498055 -221.381137) (xy 364.457563 -221.411734)
			(xy 364.412858 -221.435759) (xy 364.364996 -221.452643) (xy 364.34014 -221.457774) (xy 364.31728 -221.462092)
			(xy 364.112556 -221.81693) (xy 364.12043 -221.838774) (xy 364.129086 -221.865179) (xy 364.1384 -221.919958)
			(xy 364.138972 -221.94774) (xy 365.359188 -221.94774) (xy 365.359665 -221.922395) (xy 365.367445 -221.872306)
			(xy 365.382797 -221.823996) (xy 365.40536 -221.778605) (xy 365.434603 -221.7372) (xy 365.469837 -221.700757)
			(xy 365.510231 -221.670134) (xy 365.554836 -221.646052) (xy 365.602599 -221.629078) (xy 365.627412 -221.62389)
			(xy 365.650272 -221.619572) (xy 365.855504 -221.264226) (xy 365.84763 -221.242128) (xy 365.839165 -221.215883)
			(xy 365.830093 -221.161495) (xy 365.829596 -221.133924) (xy 365.830104 -221.108037) (xy 365.838203 -221.056899)
			(xy 365.854202 -221.007659) (xy 365.877708 -220.961527) (xy 365.90814 -220.91964) (xy 365.94475 -220.88303)
			(xy 365.986637 -220.852598) (xy 366.032769 -220.829092) (xy 366.082009 -220.813093) (xy 366.133147 -220.804994)
			(xy 366.184921 -220.804994) (xy 366.236059 -220.813093) (xy 366.285299 -220.829092) (xy 366.331431 -220.852598)
			(xy 366.373318 -220.88303) (xy 366.409928 -220.91964) (xy 366.44036 -220.961527) (xy 366.463866 -221.007659)
			(xy 366.479865 -221.056899) (xy 366.487964 -221.108037) (xy 366.488472 -221.133924) (xy 366.488042 -221.1593)
			(xy 366.480269 -221.209454) (xy 366.464896 -221.257821) (xy 366.442286 -221.303259) (xy 366.412974 -221.344691)
			(xy 366.377655 -221.381137) (xy 366.337163 -221.411734) (xy 366.292458 -221.435759) (xy 366.244596 -221.452643)
			(xy 366.21974 -221.457774) (xy 366.19688 -221.462092) (xy 365.992156 -221.81693) (xy 366.00003 -221.838774)
			(xy 366.008686 -221.865179) (xy 366.018 -221.919958) (xy 366.018572 -221.94774) (xy 369.118388 -221.94774)
			(xy 369.118865 -221.922395) (xy 369.126645 -221.872306) (xy 369.141997 -221.823996) (xy 369.16456 -221.778605)
			(xy 369.193803 -221.7372) (xy 369.229037 -221.700757) (xy 369.269431 -221.670134) (xy 369.314036 -221.646052)
			(xy 369.361799 -221.629078) (xy 369.386612 -221.62389) (xy 369.409472 -221.619572) (xy 369.614704 -221.264226)
			(xy 369.60683 -221.242128) (xy 369.598365 -221.215883) (xy 369.589293 -221.161495) (xy 369.588796 -221.133924)
			(xy 369.589304 -221.108037) (xy 369.597403 -221.056899) (xy 369.613402 -221.007659) (xy 369.636908 -220.961527)
			(xy 369.66734 -220.91964) (xy 369.70395 -220.88303) (xy 369.745837 -220.852598) (xy 369.791969 -220.829092)
			(xy 369.841209 -220.813093) (xy 369.892347 -220.804994) (xy 369.944121 -220.804994) (xy 369.995259 -220.813093)
			(xy 370.044499 -220.829092) (xy 370.090631 -220.852598) (xy 370.132518 -220.88303) (xy 370.169128 -220.91964)
			(xy 370.19956 -220.961527) (xy 370.223066 -221.007659) (xy 370.239065 -221.056899) (xy 370.247164 -221.108037)
			(xy 370.247672 -221.133924) (xy 370.247242 -221.1593) (xy 370.239469 -221.209454) (xy 370.224096 -221.257821)
			(xy 370.201486 -221.303259) (xy 370.172174 -221.344691) (xy 370.136855 -221.381137) (xy 370.096363 -221.411734)
			(xy 370.051658 -221.435759) (xy 370.003796 -221.452643) (xy 369.97894 -221.457774) (xy 369.95608 -221.462092)
			(xy 369.751356 -221.81693) (xy 369.75923 -221.838774) (xy 369.767886 -221.865179) (xy 369.7772 -221.919958)
			(xy 369.777772 -221.94774) (xy 370.997988 -221.94774) (xy 370.998465 -221.922395) (xy 371.006245 -221.872306)
			(xy 371.021597 -221.823996) (xy 371.04416 -221.778605) (xy 371.073403 -221.7372) (xy 371.108637 -221.700757)
			(xy 371.149031 -221.670134) (xy 371.193636 -221.646052) (xy 371.241399 -221.629078) (xy 371.266212 -221.62389)
			(xy 371.289072 -221.619572) (xy 371.494304 -221.264226) (xy 371.48643 -221.242128) (xy 371.477965 -221.215883)
			(xy 371.468893 -221.161495) (xy 371.468396 -221.133924) (xy 371.468904 -221.108037) (xy 371.477003 -221.056899)
			(xy 371.493002 -221.007659) (xy 371.516508 -220.961527) (xy 371.54694 -220.91964) (xy 371.58355 -220.88303)
			(xy 371.625437 -220.852598) (xy 371.671569 -220.829092) (xy 371.720809 -220.813093) (xy 371.771947 -220.804994)
			(xy 371.823721 -220.804994) (xy 371.874859 -220.813093) (xy 371.924099 -220.829092) (xy 371.970231 -220.852598)
			(xy 372.012118 -220.88303) (xy 372.048728 -220.91964) (xy 372.07916 -220.961527) (xy 372.102666 -221.007659)
			(xy 372.118665 -221.056899) (xy 372.126764 -221.108037) (xy 372.127272 -221.133924) (xy 372.126842 -221.1593)
			(xy 372.119069 -221.209454) (xy 372.103696 -221.257821) (xy 372.081086 -221.303259) (xy 372.051774 -221.344691)
			(xy 372.016455 -221.381137) (xy 371.975963 -221.411734) (xy 371.931258 -221.435759) (xy 371.883396 -221.452643)
			(xy 371.85854 -221.457774) (xy 371.83568 -221.462092) (xy 371.630956 -221.81693) (xy 371.63883 -221.838774)
			(xy 371.647486 -221.865179) (xy 371.6568 -221.919958) (xy 371.657372 -221.94774) (xy 372.877588 -221.94774)
			(xy 372.878065 -221.922395) (xy 372.885845 -221.872306) (xy 372.901197 -221.823996) (xy 372.92376 -221.778605)
			(xy 372.953003 -221.7372) (xy 372.988237 -221.700757) (xy 373.028631 -221.670134) (xy 373.073236 -221.646052)
			(xy 373.120999 -221.629078) (xy 373.145812 -221.62389) (xy 373.168672 -221.619572) (xy 373.373904 -221.264226)
			(xy 373.36603 -221.242128) (xy 373.357565 -221.215883) (xy 373.348493 -221.161495) (xy 373.347996 -221.133924)
			(xy 373.348504 -221.108037) (xy 373.356603 -221.056899) (xy 373.372602 -221.007659) (xy 373.396108 -220.961527)
			(xy 373.42654 -220.91964) (xy 373.46315 -220.88303) (xy 373.505037 -220.852598) (xy 373.551169 -220.829092)
			(xy 373.600409 -220.813093) (xy 373.651547 -220.804994) (xy 373.703321 -220.804994) (xy 373.754459 -220.813093)
			(xy 373.803699 -220.829092) (xy 373.849831 -220.852598) (xy 373.891718 -220.88303) (xy 373.928328 -220.91964)
			(xy 373.95876 -220.961527) (xy 373.982266 -221.007659) (xy 373.998265 -221.056899) (xy 374.006364 -221.108037)
			(xy 374.006872 -221.133924) (xy 374.006442 -221.1593) (xy 373.998669 -221.209454) (xy 373.983296 -221.257821)
			(xy 373.960686 -221.303259) (xy 373.931374 -221.344691) (xy 373.896055 -221.381137) (xy 373.855563 -221.411734)
			(xy 373.810858 -221.435759) (xy 373.762996 -221.452643) (xy 373.73814 -221.457774) (xy 373.71528 -221.462092)
			(xy 373.510556 -221.81693) (xy 373.51843 -221.838774) (xy 373.527086 -221.865179) (xy 373.5364 -221.919958)
			(xy 373.536972 -221.94774) (xy 374.757188 -221.94774) (xy 374.757665 -221.922395) (xy 374.765445 -221.872306)
			(xy 374.780797 -221.823996) (xy 374.80336 -221.778605) (xy 374.832603 -221.7372) (xy 374.867837 -221.700757)
			(xy 374.908231 -221.670134) (xy 374.952836 -221.646052) (xy 375.000599 -221.629078) (xy 375.025412 -221.62389)
			(xy 375.048272 -221.619572) (xy 375.253504 -221.264226) (xy 375.24563 -221.242128) (xy 375.237165 -221.215883)
			(xy 375.228093 -221.161495) (xy 375.227596 -221.133924) (xy 375.228104 -221.108037) (xy 375.236203 -221.056899)
			(xy 375.252202 -221.007659) (xy 375.275708 -220.961527) (xy 375.30614 -220.91964) (xy 375.34275 -220.88303)
			(xy 375.384637 -220.852598) (xy 375.430769 -220.829092) (xy 375.480009 -220.813093) (xy 375.531147 -220.804994)
			(xy 375.582921 -220.804994) (xy 375.634059 -220.813093) (xy 375.683299 -220.829092) (xy 375.729431 -220.852598)
			(xy 375.771318 -220.88303) (xy 375.807928 -220.91964) (xy 375.83836 -220.961527) (xy 375.861866 -221.007659)
			(xy 375.877865 -221.056899) (xy 375.885964 -221.108037) (xy 375.886472 -221.133924) (xy 375.886042 -221.1593)
			(xy 375.878269 -221.209454) (xy 375.862896 -221.257821) (xy 375.840286 -221.303259) (xy 375.810974 -221.344691)
			(xy 375.775655 -221.381137) (xy 375.735163 -221.411734) (xy 375.690458 -221.435759) (xy 375.642596 -221.452643)
			(xy 375.61774 -221.457774) (xy 375.59488 -221.462092) (xy 375.390156 -221.81693) (xy 375.39803 -221.838774)
			(xy 375.406686 -221.865179) (xy 375.416 -221.919958) (xy 375.416572 -221.94774) (xy 376.636788 -221.94774)
			(xy 376.637265 -221.922395) (xy 376.645045 -221.872306) (xy 376.660397 -221.823996) (xy 376.68296 -221.778605)
			(xy 376.712203 -221.7372) (xy 376.747437 -221.700757) (xy 376.787831 -221.670134) (xy 376.832436 -221.646052)
			(xy 376.880199 -221.629078) (xy 376.905012 -221.62389) (xy 376.927872 -221.619572) (xy 377.133104 -221.264226)
			(xy 377.12523 -221.242128) (xy 377.116765 -221.215883) (xy 377.107693 -221.161495) (xy 377.107196 -221.133924)
			(xy 377.107704 -221.108037) (xy 377.115803 -221.056899) (xy 377.131802 -221.007659) (xy 377.155308 -220.961527)
			(xy 377.18574 -220.91964) (xy 377.22235 -220.88303) (xy 377.264237 -220.852598) (xy 377.310369 -220.829092)
			(xy 377.359609 -220.813093) (xy 377.410747 -220.804994) (xy 377.462521 -220.804994) (xy 377.513659 -220.813093)
			(xy 377.562899 -220.829092) (xy 377.609031 -220.852598) (xy 377.650918 -220.88303) (xy 377.687528 -220.91964)
			(xy 377.71796 -220.961527) (xy 377.741466 -221.007659) (xy 377.757465 -221.056899) (xy 377.765564 -221.108037)
			(xy 377.766072 -221.133924) (xy 377.765642 -221.1593) (xy 377.757869 -221.209454) (xy 377.742496 -221.257821)
			(xy 377.719886 -221.303259) (xy 377.690574 -221.344691) (xy 377.655255 -221.381137) (xy 377.614763 -221.411734)
			(xy 377.570058 -221.435759) (xy 377.522196 -221.452643) (xy 377.49734 -221.457774) (xy 377.47448 -221.462092)
			(xy 377.269756 -221.81693) (xy 377.27763 -221.838774) (xy 377.286286 -221.865179) (xy 377.2956 -221.919958)
			(xy 377.296172 -221.94774) (xy 378.516388 -221.94774) (xy 378.516865 -221.922395) (xy 378.524645 -221.872306)
			(xy 378.539997 -221.823996) (xy 378.56256 -221.778605) (xy 378.591803 -221.7372) (xy 378.627037 -221.700757)
			(xy 378.667431 -221.670134) (xy 378.712036 -221.646052) (xy 378.759799 -221.629078) (xy 378.784612 -221.62389)
			(xy 378.807472 -221.619572) (xy 379.012704 -221.264226) (xy 379.00483 -221.242128) (xy 378.996365 -221.215883)
			(xy 378.987293 -221.161495) (xy 378.986796 -221.133924) (xy 378.987304 -221.108037) (xy 378.995403 -221.056899)
			(xy 379.011402 -221.007659) (xy 379.034908 -220.961527) (xy 379.06534 -220.91964) (xy 379.10195 -220.88303)
			(xy 379.143837 -220.852598) (xy 379.189969 -220.829092) (xy 379.239209 -220.813093) (xy 379.290347 -220.804994)
			(xy 379.342121 -220.804994) (xy 379.393259 -220.813093) (xy 379.442499 -220.829092) (xy 379.488631 -220.852598)
			(xy 379.530518 -220.88303) (xy 379.567128 -220.91964) (xy 379.59756 -220.961527) (xy 379.621066 -221.007659)
			(xy 379.637065 -221.056899) (xy 379.645164 -221.108037) (xy 379.645672 -221.133924) (xy 379.645242 -221.1593)
			(xy 379.637469 -221.209454) (xy 379.622096 -221.257821) (xy 379.599486 -221.303259) (xy 379.570174 -221.344691)
			(xy 379.534855 -221.381137) (xy 379.494363 -221.411734) (xy 379.449658 -221.435759) (xy 379.401796 -221.452643)
			(xy 379.37694 -221.457774) (xy 379.35408 -221.462092) (xy 379.149356 -221.81693) (xy 379.15723 -221.838774)
			(xy 379.165886 -221.865179) (xy 379.1752 -221.919958) (xy 379.175772 -221.94774) (xy 380.395988 -221.94774)
			(xy 380.396465 -221.922395) (xy 380.404245 -221.872306) (xy 380.419597 -221.823996) (xy 380.44216 -221.778605)
			(xy 380.471403 -221.7372) (xy 380.506637 -221.700757) (xy 380.547031 -221.670134) (xy 380.591636 -221.646052)
			(xy 380.639399 -221.629078) (xy 380.664212 -221.62389) (xy 380.687072 -221.619572) (xy 380.89205 -221.263972)
			(xy 380.88443 -221.242128) (xy 380.875981 -221.215945) (xy 380.866909 -221.161685) (xy 380.866396 -221.134178)
			(xy 380.866396 -221.133924) (xy 380.866904 -221.108037) (xy 380.875003 -221.056899) (xy 380.891002 -221.007659)
			(xy 380.914508 -220.961527) (xy 380.94494 -220.91964) (xy 380.98155 -220.88303) (xy 381.023437 -220.852598)
			(xy 381.069569 -220.829092) (xy 381.118809 -220.813093) (xy 381.169947 -220.804994) (xy 381.221721 -220.804994)
			(xy 381.272859 -220.813093) (xy 381.322099 -220.829092) (xy 381.368231 -220.852598) (xy 381.410118 -220.88303)
			(xy 381.446728 -220.91964) (xy 381.47716 -220.961527) (xy 381.500666 -221.007659) (xy 381.516665 -221.056899)
			(xy 381.524764 -221.108037) (xy 381.525272 -221.133924) (xy 381.524879 -221.159291) (xy 381.517126 -221.209429)
			(xy 381.501775 -221.257784) (xy 381.479191 -221.303213) (xy 381.449906 -221.344642) (xy 381.414615 -221.381089)
			(xy 381.374152 -221.411694) (xy 381.329474 -221.435731) (xy 381.281638 -221.452632) (xy 381.256794 -221.457774)
			(xy 381.233934 -221.462092) (xy 381.02921 -221.81693) (xy 381.03683 -221.838774) (xy 381.045444 -221.865059)
			(xy 381.054766 -221.919578) (xy 381.055372 -221.947232) (xy 381.055372 -221.94774) (xy 382.275588 -221.94774)
			(xy 382.276065 -221.922395) (xy 382.283845 -221.872306) (xy 382.299197 -221.823996) (xy 382.32176 -221.778605)
			(xy 382.351003 -221.7372) (xy 382.386237 -221.700757) (xy 382.426631 -221.670134) (xy 382.471236 -221.646052)
			(xy 382.518999 -221.629078) (xy 382.543812 -221.62389) (xy 382.566672 -221.619572) (xy 382.77165 -221.263972)
			(xy 382.76403 -221.242128) (xy 382.755581 -221.215945) (xy 382.746509 -221.161685) (xy 382.745996 -221.134178)
			(xy 382.745996 -221.133924) (xy 382.746504 -221.108037) (xy 382.754603 -221.056899) (xy 382.770602 -221.007659)
			(xy 382.794108 -220.961527) (xy 382.82454 -220.91964) (xy 382.86115 -220.88303) (xy 382.903037 -220.852598)
			(xy 382.949169 -220.829092) (xy 382.998409 -220.813093) (xy 383.049547 -220.804994) (xy 383.101321 -220.804994)
			(xy 383.152459 -220.813093) (xy 383.201699 -220.829092) (xy 383.247831 -220.852598) (xy 383.289718 -220.88303)
			(xy 383.326328 -220.91964) (xy 383.35676 -220.961527) (xy 383.380266 -221.007659) (xy 383.396265 -221.056899)
			(xy 383.404364 -221.108037) (xy 383.404872 -221.133924) (xy 383.404479 -221.159291) (xy 383.396726 -221.209429)
			(xy 383.381375 -221.257784) (xy 383.358791 -221.303213) (xy 383.329506 -221.344642) (xy 383.294215 -221.381089)
			(xy 383.253752 -221.411694) (xy 383.209074 -221.435731) (xy 383.161238 -221.452632) (xy 383.136394 -221.457774)
			(xy 383.113534 -221.462092) (xy 382.90881 -221.81693) (xy 382.91643 -221.838774) (xy 382.925044 -221.865059)
			(xy 382.934366 -221.919578) (xy 382.934972 -221.947232) (xy 382.934972 -221.94774) (xy 382.934464 -221.973647)
			(xy 382.926358 -222.024824) (xy 382.910346 -222.074103) (xy 382.886823 -222.12027) (xy 382.856367 -222.162189)
			(xy 382.819729 -222.198827) (xy 382.77781 -222.229283) (xy 382.731643 -222.252806) (xy 382.682364 -222.268818)
			(xy 382.631187 -222.276924) (xy 382.579373 -222.276924) (xy 382.528196 -222.268818) (xy 382.478917 -222.252806)
			(xy 382.43275 -222.229283) (xy 382.390831 -222.198827) (xy 382.354193 -222.162189) (xy 382.323737 -222.12027)
			(xy 382.300214 -222.074103) (xy 382.284202 -222.024824) (xy 382.276096 -221.973647) (xy 382.275588 -221.94774)
			(xy 381.055372 -221.94774) (xy 381.054864 -221.973647) (xy 381.046758 -222.024824) (xy 381.030746 -222.074103)
			(xy 381.007223 -222.12027) (xy 380.976767 -222.162189) (xy 380.940129 -222.198827) (xy 380.89821 -222.229283)
			(xy 380.852043 -222.252806) (xy 380.802764 -222.268818) (xy 380.751587 -222.276924) (xy 380.699773 -222.276924)
			(xy 380.648596 -222.268818) (xy 380.599317 -222.252806) (xy 380.55315 -222.229283) (xy 380.511231 -222.198827)
			(xy 380.474593 -222.162189) (xy 380.444137 -222.12027) (xy 380.420614 -222.074103) (xy 380.404602 -222.024824)
			(xy 380.396496 -221.973647) (xy 380.395988 -221.94774) (xy 379.175772 -221.94774) (xy 379.175264 -221.973647)
			(xy 379.167158 -222.024824) (xy 379.151146 -222.074103) (xy 379.127623 -222.12027) (xy 379.097167 -222.162189)
			(xy 379.060529 -222.198827) (xy 379.01861 -222.229283) (xy 378.972443 -222.252806) (xy 378.923164 -222.268818)
			(xy 378.871987 -222.276924) (xy 378.820173 -222.276924) (xy 378.768996 -222.268818) (xy 378.719717 -222.252806)
			(xy 378.67355 -222.229283) (xy 378.631631 -222.198827) (xy 378.594993 -222.162189) (xy 378.564537 -222.12027)
			(xy 378.541014 -222.074103) (xy 378.525002 -222.024824) (xy 378.516896 -221.973647) (xy 378.516388 -221.94774)
			(xy 377.296172 -221.94774) (xy 377.295664 -221.973647) (xy 377.287558 -222.024824) (xy 377.271546 -222.074103)
			(xy 377.248023 -222.12027) (xy 377.217567 -222.162189) (xy 377.180929 -222.198827) (xy 377.13901 -222.229283)
			(xy 377.092843 -222.252806) (xy 377.043564 -222.268818) (xy 376.992387 -222.276924) (xy 376.940573 -222.276924)
			(xy 376.889396 -222.268818) (xy 376.840117 -222.252806) (xy 376.79395 -222.229283) (xy 376.752031 -222.198827)
			(xy 376.715393 -222.162189) (xy 376.684937 -222.12027) (xy 376.661414 -222.074103) (xy 376.645402 -222.024824)
			(xy 376.637296 -221.973647) (xy 376.636788 -221.94774) (xy 375.416572 -221.94774) (xy 375.416064 -221.973647)
			(xy 375.407958 -222.024824) (xy 375.391946 -222.074103) (xy 375.368423 -222.12027) (xy 375.337967 -222.162189)
			(xy 375.301329 -222.198827) (xy 375.25941 -222.229283) (xy 375.213243 -222.252806) (xy 375.163964 -222.268818)
			(xy 375.112787 -222.276924) (xy 375.060973 -222.276924) (xy 375.009796 -222.268818) (xy 374.960517 -222.252806)
			(xy 374.91435 -222.229283) (xy 374.872431 -222.198827) (xy 374.835793 -222.162189) (xy 374.805337 -222.12027)
			(xy 374.781814 -222.074103) (xy 374.765802 -222.024824) (xy 374.757696 -221.973647) (xy 374.757188 -221.94774)
			(xy 373.536972 -221.94774) (xy 373.536464 -221.973647) (xy 373.528358 -222.024824) (xy 373.512346 -222.074103)
			(xy 373.488823 -222.12027) (xy 373.458367 -222.162189) (xy 373.421729 -222.198827) (xy 373.37981 -222.229283)
			(xy 373.333643 -222.252806) (xy 373.284364 -222.268818) (xy 373.233187 -222.276924) (xy 373.181373 -222.276924)
			(xy 373.130196 -222.268818) (xy 373.080917 -222.252806) (xy 373.03475 -222.229283) (xy 372.992831 -222.198827)
			(xy 372.956193 -222.162189) (xy 372.925737 -222.12027) (xy 372.902214 -222.074103) (xy 372.886202 -222.024824)
			(xy 372.878096 -221.973647) (xy 372.877588 -221.94774) (xy 371.657372 -221.94774) (xy 371.656864 -221.973647)
			(xy 371.648758 -222.024824) (xy 371.632746 -222.074103) (xy 371.609223 -222.12027) (xy 371.578767 -222.162189)
			(xy 371.542129 -222.198827) (xy 371.50021 -222.229283) (xy 371.454043 -222.252806) (xy 371.404764 -222.268818)
			(xy 371.353587 -222.276924) (xy 371.301773 -222.276924) (xy 371.250596 -222.268818) (xy 371.201317 -222.252806)
			(xy 371.15515 -222.229283) (xy 371.113231 -222.198827) (xy 371.076593 -222.162189) (xy 371.046137 -222.12027)
			(xy 371.022614 -222.074103) (xy 371.006602 -222.024824) (xy 370.998496 -221.973647) (xy 370.997988 -221.94774)
			(xy 369.777772 -221.94774) (xy 369.777264 -221.973647) (xy 369.769158 -222.024824) (xy 369.753146 -222.074103)
			(xy 369.729623 -222.12027) (xy 369.699167 -222.162189) (xy 369.662529 -222.198827) (xy 369.62061 -222.229283)
			(xy 369.574443 -222.252806) (xy 369.525164 -222.268818) (xy 369.473987 -222.276924) (xy 369.422173 -222.276924)
			(xy 369.370996 -222.268818) (xy 369.321717 -222.252806) (xy 369.27555 -222.229283) (xy 369.233631 -222.198827)
			(xy 369.196993 -222.162189) (xy 369.166537 -222.12027) (xy 369.143014 -222.074103) (xy 369.127002 -222.024824)
			(xy 369.118896 -221.973647) (xy 369.118388 -221.94774) (xy 366.018572 -221.94774) (xy 366.018064 -221.973647)
			(xy 366.009958 -222.024824) (xy 365.993946 -222.074103) (xy 365.970423 -222.12027) (xy 365.939967 -222.162189)
			(xy 365.903329 -222.198827) (xy 365.86141 -222.229283) (xy 365.815243 -222.252806) (xy 365.765964 -222.268818)
			(xy 365.714787 -222.276924) (xy 365.662973 -222.276924) (xy 365.611796 -222.268818) (xy 365.562517 -222.252806)
			(xy 365.51635 -222.229283) (xy 365.474431 -222.198827) (xy 365.437793 -222.162189) (xy 365.407337 -222.12027)
			(xy 365.383814 -222.074103) (xy 365.367802 -222.024824) (xy 365.359696 -221.973647) (xy 365.359188 -221.94774)
			(xy 364.138972 -221.94774) (xy 364.138464 -221.973647) (xy 364.130358 -222.024824) (xy 364.114346 -222.074103)
			(xy 364.090823 -222.12027) (xy 364.060367 -222.162189) (xy 364.023729 -222.198827) (xy 363.98181 -222.229283)
			(xy 363.935643 -222.252806) (xy 363.886364 -222.268818) (xy 363.835187 -222.276924) (xy 363.783373 -222.276924)
			(xy 363.732196 -222.268818) (xy 363.682917 -222.252806) (xy 363.63675 -222.229283) (xy 363.594831 -222.198827)
			(xy 363.558193 -222.162189) (xy 363.527737 -222.12027) (xy 363.504214 -222.074103) (xy 363.488202 -222.024824)
			(xy 363.480096 -221.973647) (xy 363.479588 -221.94774) (xy 362.259372 -221.94774) (xy 362.258864 -221.973627)
			(xy 362.250765 -222.024765) (xy 362.234766 -222.074005) (xy 362.21126 -222.120137) (xy 362.180828 -222.162024)
			(xy 362.144218 -222.198634) (xy 362.102331 -222.229066) (xy 362.056199 -222.252572) (xy 362.006959 -222.268571)
			(xy 361.955821 -222.27667) (xy 361.904047 -222.27667) (xy 361.852909 -222.268571) (xy 361.803669 -222.252572)
			(xy 361.757537 -222.229066) (xy 361.71565 -222.198634) (xy 361.67904 -222.162024) (xy 361.648608 -222.120137)
			(xy 361.625102 -222.074005) (xy 361.609103 -222.024765) (xy 361.601004 -221.973627) (xy 361.600496 -221.94774)
			(xy 360.379772 -221.94774) (xy 360.379264 -221.973647) (xy 360.371158 -222.024824) (xy 360.355146 -222.074103)
			(xy 360.331623 -222.12027) (xy 360.301167 -222.162189) (xy 360.264529 -222.198827) (xy 360.22261 -222.229283)
			(xy 360.176443 -222.252806) (xy 360.127164 -222.268818) (xy 360.075987 -222.276924) (xy 360.024173 -222.276924)
			(xy 359.972996 -222.268818) (xy 359.923717 -222.252806) (xy 359.87755 -222.229283) (xy 359.835631 -222.198827)
			(xy 359.798993 -222.162189) (xy 359.768537 -222.12027) (xy 359.745014 -222.074103) (xy 359.729002 -222.024824)
			(xy 359.720896 -221.973647) (xy 359.720388 -221.94774) (xy 358.500172 -221.94774) (xy 358.499664 -221.973627)
			(xy 358.491565 -222.024765) (xy 358.475566 -222.074005) (xy 358.45206 -222.120137) (xy 358.421628 -222.162024)
			(xy 358.385018 -222.198634) (xy 358.343131 -222.229066) (xy 358.296999 -222.252572) (xy 358.247759 -222.268571)
			(xy 358.196621 -222.27667) (xy 358.144847 -222.27667) (xy 358.093709 -222.268571) (xy 358.044469 -222.252572)
			(xy 357.998337 -222.229066) (xy 357.95645 -222.198634) (xy 357.91984 -222.162024) (xy 357.889408 -222.120137)
			(xy 357.865902 -222.074005) (xy 357.849903 -222.024765) (xy 357.841804 -221.973627) (xy 357.841296 -221.94774)
			(xy 356.620572 -221.94774) (xy 356.620064 -221.973647) (xy 356.611958 -222.024824) (xy 356.595946 -222.074103)
			(xy 356.572423 -222.12027) (xy 356.541967 -222.162189) (xy 356.505329 -222.198827) (xy 356.46341 -222.229283)
			(xy 356.417243 -222.252806) (xy 356.367964 -222.268818) (xy 356.316787 -222.276924) (xy 356.264973 -222.276924)
			(xy 356.213796 -222.268818) (xy 356.164517 -222.252806) (xy 356.11835 -222.229283) (xy 356.076431 -222.198827)
			(xy 356.039793 -222.162189) (xy 356.009337 -222.12027) (xy 355.985814 -222.074103) (xy 355.969802 -222.024824)
			(xy 355.961696 -221.973647) (xy 355.961188 -221.94774) (xy 354.740972 -221.94774) (xy 354.740464 -221.973647)
			(xy 354.732358 -222.024824) (xy 354.716346 -222.074103) (xy 354.692823 -222.12027) (xy 354.662367 -222.162189)
			(xy 354.625729 -222.198827) (xy 354.58381 -222.229283) (xy 354.537643 -222.252806) (xy 354.488364 -222.268818)
			(xy 354.437187 -222.276924) (xy 354.385373 -222.276924) (xy 354.334196 -222.268818) (xy 354.284917 -222.252806)
			(xy 354.23875 -222.229283) (xy 354.196831 -222.198827) (xy 354.160193 -222.162189) (xy 354.129737 -222.12027)
			(xy 354.106214 -222.074103) (xy 354.090202 -222.024824) (xy 354.082096 -221.973647) (xy 354.081588 -221.94774)
			(xy 352.861372 -221.94774) (xy 352.860864 -221.973647) (xy 352.852758 -222.024824) (xy 352.836746 -222.074103)
			(xy 352.813223 -222.12027) (xy 352.782767 -222.162189) (xy 352.746129 -222.198827) (xy 352.70421 -222.229283)
			(xy 352.658043 -222.252806) (xy 352.608764 -222.268818) (xy 352.557587 -222.276924) (xy 352.505773 -222.276924)
			(xy 352.454596 -222.268818) (xy 352.405317 -222.252806) (xy 352.35915 -222.229283) (xy 352.317231 -222.198827)
			(xy 352.280593 -222.162189) (xy 352.250137 -222.12027) (xy 352.226614 -222.074103) (xy 352.210602 -222.024824)
			(xy 352.202496 -221.973647) (xy 352.201988 -221.94774) (xy 350.981772 -221.94774) (xy 350.981264 -221.973647)
			(xy 350.973158 -222.024824) (xy 350.957146 -222.074103) (xy 350.933623 -222.12027) (xy 350.903167 -222.162189)
			(xy 350.866529 -222.198827) (xy 350.82461 -222.229283) (xy 350.778443 -222.252806) (xy 350.729164 -222.268818)
			(xy 350.677987 -222.276924) (xy 350.626173 -222.276924) (xy 350.574996 -222.268818) (xy 350.525717 -222.252806)
			(xy 350.47955 -222.229283) (xy 350.437631 -222.198827) (xy 350.400993 -222.162189) (xy 350.370537 -222.12027)
			(xy 350.347014 -222.074103) (xy 350.331002 -222.024824) (xy 350.322896 -221.973647) (xy 350.322388 -221.94774)
			(xy 350.322992 -221.920023) (xy 350.332309 -221.865377) (xy 350.34093 -221.839028) (xy 350.348804 -221.81693)
			(xy 350.143826 -221.462092) (xy 350.120966 -221.457774) (xy 350.096166 -221.452574) (xy 350.04843 -221.435583)
			(xy 350.003855 -221.411489) (xy 349.963491 -221.380859) (xy 349.928289 -221.344414) (xy 349.899076 -221.303012)
			(xy 349.876542 -221.257629) (xy 349.861217 -221.209332) (xy 349.853461 -221.159259) (xy 349.852996 -221.133924)
			(xy 349.572072 -221.133924) (xy 349.571564 -221.159811) (xy 349.563465 -221.210949) (xy 349.547466 -221.260189)
			(xy 349.52396 -221.306321) (xy 349.493528 -221.348208) (xy 349.456918 -221.384818) (xy 349.415031 -221.41525)
			(xy 349.368899 -221.438756) (xy 349.319659 -221.454755) (xy 349.268521 -221.462854) (xy 349.216747 -221.462854)
			(xy 349.165609 -221.454755) (xy 349.116369 -221.438756) (xy 349.070237 -221.41525) (xy 349.02835 -221.384818)
			(xy 348.99174 -221.348208) (xy 348.961308 -221.306321) (xy 348.937802 -221.260189) (xy 348.921803 -221.210949)
			(xy 348.913704 -221.159811) (xy 348.913196 -221.133924) (xy 348.632272 -221.133924) (xy 348.631745 -221.161632)
			(xy 348.622548 -221.216279) (xy 348.613984 -221.242636) (xy 348.60611 -221.264734) (xy 348.811088 -221.619572)
			(xy 348.833948 -221.62389) (xy 348.858767 -221.629064) (xy 348.906546 -221.646018) (xy 348.951165 -221.670088)
			(xy 348.991572 -221.700708) (xy 349.026813 -221.737154) (xy 349.056057 -221.778566) (xy 349.078614 -221.823969)
			(xy 349.093952 -221.872291) (xy 349.10171 -221.922391) (xy 349.102172 -221.94774) (xy 349.101664 -221.973647)
			(xy 349.093558 -222.024824) (xy 349.077546 -222.074103) (xy 349.054023 -222.12027) (xy 349.023567 -222.162189)
			(xy 348.986929 -222.198827) (xy 348.94501 -222.229283) (xy 348.898843 -222.252806) (xy 348.849564 -222.268818)
			(xy 348.798387 -222.276924) (xy 348.746573 -222.276924) (xy 348.695396 -222.268818) (xy 348.646117 -222.252806)
			(xy 348.59995 -222.229283) (xy 348.558031 -222.198827) (xy 348.521393 -222.162189) (xy 348.490937 -222.12027)
			(xy 348.467414 -222.074103) (xy 348.451402 -222.024824) (xy 348.443296 -221.973647) (xy 348.442788 -221.94774)
			(xy 348.443392 -221.920023) (xy 348.452709 -221.865377) (xy 348.46133 -221.839028) (xy 348.469204 -221.81693)
			(xy 348.264226 -221.462092) (xy 348.241366 -221.457774) (xy 348.216566 -221.452574) (xy 348.16883 -221.435583)
			(xy 348.124255 -221.411489) (xy 348.083891 -221.380859) (xy 348.048689 -221.344414) (xy 348.019476 -221.303012)
			(xy 347.996942 -221.257629) (xy 347.981617 -221.209332) (xy 347.973861 -221.159259) (xy 347.973396 -221.133924)
			(xy 347.692472 -221.133924) (xy 347.691964 -221.159811) (xy 347.683865 -221.210949) (xy 347.667866 -221.260189)
			(xy 347.64436 -221.306321) (xy 347.613928 -221.348208) (xy 347.577318 -221.384818) (xy 347.535431 -221.41525)
			(xy 347.489299 -221.438756) (xy 347.440059 -221.454755) (xy 347.388921 -221.462854) (xy 347.337147 -221.462854)
			(xy 347.286009 -221.454755) (xy 347.236769 -221.438756) (xy 347.190637 -221.41525) (xy 347.14875 -221.384818)
			(xy 347.11214 -221.348208) (xy 347.081708 -221.306321) (xy 347.058202 -221.260189) (xy 347.042203 -221.210949)
			(xy 347.034104 -221.159811) (xy 347.033596 -221.133924) (xy 346.752672 -221.133924) (xy 346.752145 -221.161632)
			(xy 346.742948 -221.216279) (xy 346.734384 -221.242636) (xy 346.72651 -221.264734) (xy 346.931488 -221.619572)
			(xy 346.954348 -221.62389) (xy 346.979167 -221.629064) (xy 347.026946 -221.646018) (xy 347.071565 -221.670088)
			(xy 347.111972 -221.700708) (xy 347.147213 -221.737154) (xy 347.176457 -221.778566) (xy 347.199014 -221.823969)
			(xy 347.214352 -221.872291) (xy 347.22211 -221.922391) (xy 347.222572 -221.94774) (xy 347.222064 -221.973647)
			(xy 347.213958 -222.024824) (xy 347.197946 -222.074103) (xy 347.174423 -222.12027) (xy 347.143967 -222.162189)
			(xy 347.107329 -222.198827) (xy 347.06541 -222.229283) (xy 347.019243 -222.252806) (xy 346.969964 -222.268818)
			(xy 346.918787 -222.276924) (xy 346.866973 -222.276924) (xy 346.815796 -222.268818) (xy 346.766517 -222.252806)
			(xy 346.72035 -222.229283) (xy 346.678431 -222.198827) (xy 346.641793 -222.162189) (xy 346.611337 -222.12027)
			(xy 346.587814 -222.074103) (xy 346.571802 -222.024824) (xy 346.563696 -221.973647) (xy 346.563188 -221.94774)
			(xy 346.563792 -221.920023) (xy 346.573109 -221.865377) (xy 346.58173 -221.839028) (xy 346.589604 -221.81693)
			(xy 346.384626 -221.462092) (xy 346.361766 -221.457774) (xy 346.336966 -221.452574) (xy 346.28923 -221.435583)
			(xy 346.244655 -221.411489) (xy 346.204291 -221.380859) (xy 346.169089 -221.344414) (xy 346.139876 -221.303012)
			(xy 346.117342 -221.257629) (xy 346.102017 -221.209332) (xy 346.094261 -221.159259) (xy 346.093796 -221.133924)
			(xy 345.812872 -221.133924) (xy 345.812364 -221.159811) (xy 345.804265 -221.210949) (xy 345.788266 -221.260189)
			(xy 345.76476 -221.306321) (xy 345.734328 -221.348208) (xy 345.697718 -221.384818) (xy 345.655831 -221.41525)
			(xy 345.609699 -221.438756) (xy 345.560459 -221.454755) (xy 345.509321 -221.462854) (xy 345.457547 -221.462854)
			(xy 345.406409 -221.454755) (xy 345.357169 -221.438756) (xy 345.311037 -221.41525) (xy 345.26915 -221.384818)
			(xy 345.23254 -221.348208) (xy 345.202108 -221.306321) (xy 345.178602 -221.260189) (xy 345.162603 -221.210949)
			(xy 345.154504 -221.159811) (xy 345.153996 -221.133924) (xy 344.873072 -221.133924) (xy 344.872545 -221.161632)
			(xy 344.863348 -221.216279) (xy 344.854784 -221.242636) (xy 344.84691 -221.264734) (xy 345.051888 -221.619572)
			(xy 345.074748 -221.62389) (xy 345.099567 -221.629064) (xy 345.147346 -221.646018) (xy 345.191965 -221.670088)
			(xy 345.232372 -221.700708) (xy 345.267613 -221.737154) (xy 345.296857 -221.778566) (xy 345.319414 -221.823969)
			(xy 345.334752 -221.872291) (xy 345.34251 -221.922391) (xy 345.342972 -221.94774) (xy 345.342464 -221.973647)
			(xy 345.334358 -222.024824) (xy 345.318346 -222.074103) (xy 345.294823 -222.12027) (xy 345.264367 -222.162189)
			(xy 345.227729 -222.198827) (xy 345.18581 -222.229283) (xy 345.139643 -222.252806) (xy 345.090364 -222.268818)
			(xy 345.039187 -222.276924) (xy 344.987373 -222.276924) (xy 344.936196 -222.268818) (xy 344.886917 -222.252806)
			(xy 344.84075 -222.229283) (xy 344.798831 -222.198827) (xy 344.762193 -222.162189) (xy 344.731737 -222.12027)
			(xy 344.708214 -222.074103) (xy 344.692202 -222.024824) (xy 344.684096 -221.973647) (xy 344.683588 -221.94774)
			(xy 344.684192 -221.920023) (xy 344.693509 -221.865377) (xy 344.70213 -221.839028) (xy 344.710004 -221.81693)
			(xy 344.505026 -221.462092) (xy 344.482166 -221.457774) (xy 344.457366 -221.452574) (xy 344.40963 -221.435583)
			(xy 344.365055 -221.411489) (xy 344.324691 -221.380859) (xy 344.289489 -221.344414) (xy 344.260276 -221.303012)
			(xy 344.237742 -221.257629) (xy 344.222417 -221.209332) (xy 344.214661 -221.159259) (xy 344.214196 -221.133924)
			(xy 343.933272 -221.133924) (xy 343.932764 -221.159811) (xy 343.924665 -221.210949) (xy 343.908666 -221.260189)
			(xy 343.88516 -221.306321) (xy 343.854728 -221.348208) (xy 343.818118 -221.384818) (xy 343.776231 -221.41525)
			(xy 343.730099 -221.438756) (xy 343.680859 -221.454755) (xy 343.629721 -221.462854) (xy 343.577947 -221.462854)
			(xy 343.526809 -221.454755) (xy 343.477569 -221.438756) (xy 343.431437 -221.41525) (xy 343.38955 -221.384818)
			(xy 343.35294 -221.348208) (xy 343.322508 -221.306321) (xy 343.299002 -221.260189) (xy 343.283003 -221.210949)
			(xy 343.274904 -221.159811) (xy 343.274396 -221.133924) (xy 342.993472 -221.133924) (xy 342.992945 -221.161632)
			(xy 342.983748 -221.216279) (xy 342.975184 -221.242636) (xy 342.96731 -221.264734) (xy 343.172288 -221.619572)
			(xy 343.195148 -221.62389) (xy 343.219967 -221.629064) (xy 343.267746 -221.646018) (xy 343.312365 -221.670088)
			(xy 343.352772 -221.700708) (xy 343.388013 -221.737154) (xy 343.417257 -221.778566) (xy 343.439814 -221.823969)
			(xy 343.455152 -221.872291) (xy 343.46291 -221.922391) (xy 343.463372 -221.94774) (xy 343.462864 -221.973647)
			(xy 343.454758 -222.024824) (xy 343.438746 -222.074103) (xy 343.415223 -222.12027) (xy 343.384767 -222.162189)
			(xy 343.348129 -222.198827) (xy 343.30621 -222.229283) (xy 343.260043 -222.252806) (xy 343.210764 -222.268818)
			(xy 343.159587 -222.276924) (xy 343.107773 -222.276924) (xy 343.056596 -222.268818) (xy 343.007317 -222.252806)
			(xy 342.96115 -222.229283) (xy 342.919231 -222.198827) (xy 342.882593 -222.162189) (xy 342.852137 -222.12027)
			(xy 342.828614 -222.074103) (xy 342.812602 -222.024824) (xy 342.804496 -221.973647) (xy 342.803988 -221.94774)
			(xy 342.804592 -221.920023) (xy 342.813909 -221.865377) (xy 342.82253 -221.839028) (xy 342.830404 -221.81693)
			(xy 342.625426 -221.462092) (xy 342.602566 -221.457774) (xy 342.577766 -221.452574) (xy 342.53003 -221.435583)
			(xy 342.485455 -221.411489) (xy 342.445091 -221.380859) (xy 342.409889 -221.344414) (xy 342.380676 -221.303012)
			(xy 342.358142 -221.257629) (xy 342.342817 -221.209332) (xy 342.335061 -221.159259) (xy 342.334596 -221.133924)
			(xy 342.053672 -221.133924) (xy 342.053164 -221.159811) (xy 342.045065 -221.210949) (xy 342.029066 -221.260189)
			(xy 342.00556 -221.306321) (xy 341.975128 -221.348208) (xy 341.938518 -221.384818) (xy 341.896631 -221.41525)
			(xy 341.850499 -221.438756) (xy 341.801259 -221.454755) (xy 341.750121 -221.462854) (xy 341.698347 -221.462854)
			(xy 341.647209 -221.454755) (xy 341.597969 -221.438756) (xy 341.551837 -221.41525) (xy 341.50995 -221.384818)
			(xy 341.47334 -221.348208) (xy 341.442908 -221.306321) (xy 341.419402 -221.260189) (xy 341.403403 -221.210949)
			(xy 341.395304 -221.159811) (xy 341.394796 -221.133924) (xy 341.113872 -221.133924) (xy 341.113345 -221.161632)
			(xy 341.104148 -221.216279) (xy 341.095584 -221.242636) (xy 341.08771 -221.264734) (xy 341.292688 -221.619572)
			(xy 341.315548 -221.62389) (xy 341.340367 -221.629064) (xy 341.388146 -221.646018) (xy 341.432765 -221.670088)
			(xy 341.473172 -221.700708) (xy 341.508413 -221.737154) (xy 341.537657 -221.778566) (xy 341.560214 -221.823969)
			(xy 341.575552 -221.872291) (xy 341.58331 -221.922391) (xy 341.583772 -221.94774) (xy 341.583264 -221.973647)
			(xy 341.575158 -222.024824) (xy 341.559146 -222.074103) (xy 341.535623 -222.12027) (xy 341.505167 -222.162189)
			(xy 341.468529 -222.198827) (xy 341.42661 -222.229283) (xy 341.380443 -222.252806) (xy 341.331164 -222.268818)
			(xy 341.279987 -222.276924) (xy 341.228173 -222.276924) (xy 341.176996 -222.268818) (xy 341.127717 -222.252806)
			(xy 341.08155 -222.229283) (xy 341.039631 -222.198827) (xy 341.002993 -222.162189) (xy 340.972537 -222.12027)
			(xy 340.949014 -222.074103) (xy 340.933002 -222.024824) (xy 340.924896 -221.973647) (xy 340.924388 -221.94774)
			(xy 340.924992 -221.920023) (xy 340.934309 -221.865377) (xy 340.94293 -221.839028) (xy 340.950804 -221.81693)
			(xy 340.745826 -221.462092) (xy 340.722966 -221.457774) (xy 340.698166 -221.452574) (xy 340.65043 -221.435583)
			(xy 340.605855 -221.411489) (xy 340.565491 -221.380859) (xy 340.530289 -221.344414) (xy 340.501076 -221.303012)
			(xy 340.478542 -221.257629) (xy 340.463217 -221.209332) (xy 340.455461 -221.159259) (xy 340.454996 -221.133924)
			(xy 340.174072 -221.133924) (xy 340.173564 -221.159811) (xy 340.165465 -221.210949) (xy 340.149466 -221.260189)
			(xy 340.12596 -221.306321) (xy 340.095528 -221.348208) (xy 340.058918 -221.384818) (xy 340.017031 -221.41525)
			(xy 339.970899 -221.438756) (xy 339.921659 -221.454755) (xy 339.870521 -221.462854) (xy 339.818747 -221.462854)
			(xy 339.767609 -221.454755) (xy 339.718369 -221.438756) (xy 339.672237 -221.41525) (xy 339.63035 -221.384818)
			(xy 339.59374 -221.348208) (xy 339.563308 -221.306321) (xy 339.539802 -221.260189) (xy 339.523803 -221.210949)
			(xy 339.515704 -221.159811) (xy 339.515196 -221.133924) (xy 339.234272 -221.133924) (xy 339.233745 -221.161632)
			(xy 339.224548 -221.216279) (xy 339.215984 -221.242636) (xy 339.20811 -221.264734) (xy 339.413088 -221.619572)
			(xy 339.435948 -221.62389) (xy 339.460767 -221.629064) (xy 339.508546 -221.646018) (xy 339.553165 -221.670088)
			(xy 339.593572 -221.700708) (xy 339.628813 -221.737154) (xy 339.658057 -221.778566) (xy 339.680614 -221.823969)
			(xy 339.695952 -221.872291) (xy 339.70371 -221.922391) (xy 339.704172 -221.94774) (xy 339.703664 -221.973647)
			(xy 339.695558 -222.024824) (xy 339.679546 -222.074103) (xy 339.656023 -222.12027) (xy 339.625567 -222.162189)
			(xy 339.588929 -222.198827) (xy 339.54701 -222.229283) (xy 339.500843 -222.252806) (xy 339.451564 -222.268818)
			(xy 339.400387 -222.276924) (xy 339.348573 -222.276924) (xy 339.297396 -222.268818) (xy 339.248117 -222.252806)
			(xy 339.20195 -222.229283) (xy 339.160031 -222.198827) (xy 339.123393 -222.162189) (xy 339.092937 -222.12027)
			(xy 339.069414 -222.074103) (xy 339.053402 -222.024824) (xy 339.045296 -221.973647) (xy 339.044788 -221.94774)
			(xy 339.045392 -221.920023) (xy 339.054709 -221.865377) (xy 339.06333 -221.839028) (xy 339.071204 -221.81693)
			(xy 338.866226 -221.462092) (xy 338.843366 -221.457774) (xy 338.818566 -221.452574) (xy 338.77083 -221.435583)
			(xy 338.726255 -221.411489) (xy 338.685891 -221.380859) (xy 338.650689 -221.344414) (xy 338.621476 -221.303012)
			(xy 338.598942 -221.257629) (xy 338.583617 -221.209332) (xy 338.575861 -221.159259) (xy 338.575396 -221.133924)
			(xy 338.294472 -221.133924) (xy 338.293964 -221.159811) (xy 338.285865 -221.210949) (xy 338.269866 -221.260189)
			(xy 338.24636 -221.306321) (xy 338.215928 -221.348208) (xy 338.179318 -221.384818) (xy 338.137431 -221.41525)
			(xy 338.091299 -221.438756) (xy 338.042059 -221.454755) (xy 337.990921 -221.462854) (xy 337.939147 -221.462854)
			(xy 337.888009 -221.454755) (xy 337.838769 -221.438756) (xy 337.792637 -221.41525) (xy 337.75075 -221.384818)
			(xy 337.71414 -221.348208) (xy 337.683708 -221.306321) (xy 337.660202 -221.260189) (xy 337.644203 -221.210949)
			(xy 337.636104 -221.159811) (xy 337.635596 -221.133924) (xy 337.354672 -221.133924) (xy 337.354145 -221.161632)
			(xy 337.344948 -221.216279) (xy 337.336384 -221.242636) (xy 337.32851 -221.264734) (xy 337.533488 -221.619572)
			(xy 337.556348 -221.62389) (xy 337.581167 -221.629064) (xy 337.628946 -221.646018) (xy 337.673565 -221.670088)
			(xy 337.713972 -221.700708) (xy 337.749213 -221.737154) (xy 337.778457 -221.778566) (xy 337.801014 -221.823969)
			(xy 337.816352 -221.872291) (xy 337.82411 -221.922391) (xy 337.824572 -221.94774) (xy 337.824064 -221.973647)
			(xy 337.815958 -222.024824) (xy 337.799946 -222.074103) (xy 337.776423 -222.12027) (xy 337.745967 -222.162189)
			(xy 337.709329 -222.198827) (xy 337.66741 -222.229283) (xy 337.621243 -222.252806) (xy 337.571964 -222.268818)
			(xy 337.520787 -222.276924) (xy 337.468973 -222.276924) (xy 337.417796 -222.268818) (xy 337.368517 -222.252806)
			(xy 337.32235 -222.229283) (xy 337.280431 -222.198827) (xy 337.243793 -222.162189) (xy 337.213337 -222.12027)
			(xy 337.189814 -222.074103) (xy 337.173802 -222.024824) (xy 337.165696 -221.973647) (xy 337.165188 -221.94774)
			(xy 337.165792 -221.920023) (xy 337.175109 -221.865377) (xy 337.18373 -221.839028) (xy 337.191604 -221.81693)
			(xy 336.986626 -221.462092) (xy 336.963766 -221.457774) (xy 336.938966 -221.452574) (xy 336.89123 -221.435583)
			(xy 336.846655 -221.411489) (xy 336.806291 -221.380859) (xy 336.771089 -221.344414) (xy 336.741876 -221.303012)
			(xy 336.719342 -221.257629) (xy 336.704017 -221.209332) (xy 336.696261 -221.159259) (xy 336.695796 -221.133924)
			(xy 135.464804 -221.133924) (xy 135.464385 -221.15929) (xy 135.456633 -221.209425) (xy 135.441284 -221.257778)
			(xy 135.418702 -221.303206) (xy 135.389421 -221.344633) (xy 135.354133 -221.381081) (xy 135.313674 -221.411686)
			(xy 135.269 -221.435725) (xy 135.221169 -221.45263) (xy 135.196326 -221.457774) (xy 135.173466 -221.462092)
			(xy 134.968742 -221.81693) (xy 134.976362 -221.838774) (xy 134.984977 -221.865059) (xy 134.994298 -221.919578)
			(xy 134.994904 -221.947232) (xy 134.994904 -221.94774) (xy 134.994396 -221.973647) (xy 134.98629 -222.024824)
			(xy 134.970278 -222.074103) (xy 134.946755 -222.12027) (xy 134.916299 -222.162189) (xy 134.879661 -222.198827)
			(xy 134.837742 -222.229283) (xy 134.791575 -222.252806) (xy 134.742296 -222.268818) (xy 134.691119 -222.276924)
			(xy 134.639305 -222.276924) (xy 134.588128 -222.268818) (xy 134.538849 -222.252806) (xy 134.492682 -222.229283)
			(xy 134.450763 -222.198827) (xy 134.414125 -222.162189) (xy 134.383669 -222.12027) (xy 134.360146 -222.074103)
			(xy 134.344134 -222.024824) (xy 134.336028 -221.973647) (xy 134.33552 -221.94774) (xy 133.115304 -221.94774)
			(xy 133.114796 -221.973647) (xy 133.10669 -222.024824) (xy 133.090678 -222.074103) (xy 133.067155 -222.12027)
			(xy 133.036699 -222.162189) (xy 133.000061 -222.198827) (xy 132.958142 -222.229283) (xy 132.911975 -222.252806)
			(xy 132.862696 -222.268818) (xy 132.811519 -222.276924) (xy 132.759705 -222.276924) (xy 132.708528 -222.268818)
			(xy 132.659249 -222.252806) (xy 132.613082 -222.229283) (xy 132.571163 -222.198827) (xy 132.534525 -222.162189)
			(xy 132.504069 -222.12027) (xy 132.480546 -222.074103) (xy 132.464534 -222.024824) (xy 132.456428 -221.973647)
			(xy 132.45592 -221.94774) (xy 131.235704 -221.94774) (xy 131.235196 -221.973647) (xy 131.22709 -222.024824)
			(xy 131.211078 -222.074103) (xy 131.187555 -222.12027) (xy 131.157099 -222.162189) (xy 131.120461 -222.198827)
			(xy 131.078542 -222.229283) (xy 131.032375 -222.252806) (xy 130.983096 -222.268818) (xy 130.931919 -222.276924)
			(xy 130.880105 -222.276924) (xy 130.828928 -222.268818) (xy 130.779649 -222.252806) (xy 130.733482 -222.229283)
			(xy 130.691563 -222.198827) (xy 130.654925 -222.162189) (xy 130.624469 -222.12027) (xy 130.600946 -222.074103)
			(xy 130.584934 -222.024824) (xy 130.576828 -221.973647) (xy 130.57632 -221.94774) (xy 129.356104 -221.94774)
			(xy 129.355596 -221.973647) (xy 129.34749 -222.024824) (xy 129.331478 -222.074103) (xy 129.307955 -222.12027)
			(xy 129.277499 -222.162189) (xy 129.240861 -222.198827) (xy 129.198942 -222.229283) (xy 129.152775 -222.252806)
			(xy 129.103496 -222.268818) (xy 129.052319 -222.276924) (xy 129.000505 -222.276924) (xy 128.949328 -222.268818)
			(xy 128.900049 -222.252806) (xy 128.853882 -222.229283) (xy 128.811963 -222.198827) (xy 128.775325 -222.162189)
			(xy 128.744869 -222.12027) (xy 128.721346 -222.074103) (xy 128.705334 -222.024824) (xy 128.697228 -221.973647)
			(xy 128.69672 -221.94774) (xy 127.476504 -221.94774) (xy 127.475996 -221.973647) (xy 127.46789 -222.024824)
			(xy 127.451878 -222.074103) (xy 127.428355 -222.12027) (xy 127.397899 -222.162189) (xy 127.361261 -222.198827)
			(xy 127.319342 -222.229283) (xy 127.273175 -222.252806) (xy 127.223896 -222.268818) (xy 127.172719 -222.276924)
			(xy 127.120905 -222.276924) (xy 127.069728 -222.268818) (xy 127.020449 -222.252806) (xy 126.974282 -222.229283)
			(xy 126.932363 -222.198827) (xy 126.895725 -222.162189) (xy 126.865269 -222.12027) (xy 126.841746 -222.074103)
			(xy 126.825734 -222.024824) (xy 126.817628 -221.973647) (xy 126.81712 -221.94774) (xy 125.596904 -221.94774)
			(xy 125.596396 -221.973647) (xy 125.58829 -222.024824) (xy 125.572278 -222.074103) (xy 125.548755 -222.12027)
			(xy 125.518299 -222.162189) (xy 125.481661 -222.198827) (xy 125.439742 -222.229283) (xy 125.393575 -222.252806)
			(xy 125.344296 -222.268818) (xy 125.293119 -222.276924) (xy 125.241305 -222.276924) (xy 125.190128 -222.268818)
			(xy 125.140849 -222.252806) (xy 125.094682 -222.229283) (xy 125.052763 -222.198827) (xy 125.016125 -222.162189)
			(xy 124.985669 -222.12027) (xy 124.962146 -222.074103) (xy 124.946134 -222.024824) (xy 124.938028 -221.973647)
			(xy 124.93752 -221.94774) (xy 123.717304 -221.94774) (xy 123.716796 -221.973647) (xy 123.70869 -222.024824)
			(xy 123.692678 -222.074103) (xy 123.669155 -222.12027) (xy 123.638699 -222.162189) (xy 123.602061 -222.198827)
			(xy 123.560142 -222.229283) (xy 123.513975 -222.252806) (xy 123.464696 -222.268818) (xy 123.413519 -222.276924)
			(xy 123.361705 -222.276924) (xy 123.310528 -222.268818) (xy 123.261249 -222.252806) (xy 123.215082 -222.229283)
			(xy 123.173163 -222.198827) (xy 123.136525 -222.162189) (xy 123.106069 -222.12027) (xy 123.082546 -222.074103)
			(xy 123.066534 -222.024824) (xy 123.058428 -221.973647) (xy 123.05792 -221.94774) (xy 121.837704 -221.94774)
			(xy 121.837196 -221.973647) (xy 121.82909 -222.024824) (xy 121.813078 -222.074103) (xy 121.789555 -222.12027)
			(xy 121.759099 -222.162189) (xy 121.722461 -222.198827) (xy 121.680542 -222.229283) (xy 121.634375 -222.252806)
			(xy 121.585096 -222.268818) (xy 121.533919 -222.276924) (xy 121.482105 -222.276924) (xy 121.430928 -222.268818)
			(xy 121.381649 -222.252806) (xy 121.335482 -222.229283) (xy 121.293563 -222.198827) (xy 121.256925 -222.162189)
			(xy 121.226469 -222.12027) (xy 121.202946 -222.074103) (xy 121.186934 -222.024824) (xy 121.178828 -221.973647)
			(xy 121.17832 -221.94774) (xy 118.078504 -221.94774) (xy 118.077996 -221.973647) (xy 118.06989 -222.024824)
			(xy 118.053878 -222.074103) (xy 118.030355 -222.12027) (xy 117.999899 -222.162189) (xy 117.963261 -222.198827)
			(xy 117.921342 -222.229283) (xy 117.875175 -222.252806) (xy 117.825896 -222.268818) (xy 117.774719 -222.276924)
			(xy 117.722905 -222.276924) (xy 117.671728 -222.268818) (xy 117.622449 -222.252806) (xy 117.576282 -222.229283)
			(xy 117.534363 -222.198827) (xy 117.497725 -222.162189) (xy 117.467269 -222.12027) (xy 117.443746 -222.074103)
			(xy 117.427734 -222.024824) (xy 117.419628 -221.973647) (xy 117.41912 -221.94774) (xy 116.198904 -221.94774)
			(xy 116.198396 -221.973647) (xy 116.19029 -222.024824) (xy 116.174278 -222.074103) (xy 116.150755 -222.12027)
			(xy 116.120299 -222.162189) (xy 116.083661 -222.198827) (xy 116.041742 -222.229283) (xy 115.995575 -222.252806)
			(xy 115.946296 -222.268818) (xy 115.895119 -222.276924) (xy 115.843305 -222.276924) (xy 115.792128 -222.268818)
			(xy 115.742849 -222.252806) (xy 115.696682 -222.229283) (xy 115.654763 -222.198827) (xy 115.618125 -222.162189)
			(xy 115.587669 -222.12027) (xy 115.564146 -222.074103) (xy 115.548134 -222.024824) (xy 115.540028 -221.973647)
			(xy 115.53952 -221.94774) (xy 114.319304 -221.94774) (xy 114.318796 -221.973627) (xy 114.310697 -222.024765)
			(xy 114.294698 -222.074005) (xy 114.271192 -222.120137) (xy 114.24076 -222.162024) (xy 114.20415 -222.198634)
			(xy 114.162263 -222.229066) (xy 114.116131 -222.252572) (xy 114.066891 -222.268571) (xy 114.015753 -222.27667)
			(xy 113.963979 -222.27667) (xy 113.912841 -222.268571) (xy 113.863601 -222.252572) (xy 113.817469 -222.229066)
			(xy 113.775582 -222.198634) (xy 113.738972 -222.162024) (xy 113.70854 -222.120137) (xy 113.685034 -222.074005)
			(xy 113.669035 -222.024765) (xy 113.660936 -221.973627) (xy 113.660428 -221.94774) (xy 112.439704 -221.94774)
			(xy 112.439196 -221.973647) (xy 112.43109 -222.024824) (xy 112.415078 -222.074103) (xy 112.391555 -222.12027)
			(xy 112.361099 -222.162189) (xy 112.324461 -222.198827) (xy 112.282542 -222.229283) (xy 112.236375 -222.252806)
			(xy 112.187096 -222.268818) (xy 112.135919 -222.276924) (xy 112.084105 -222.276924) (xy 112.032928 -222.268818)
			(xy 111.983649 -222.252806) (xy 111.937482 -222.229283) (xy 111.895563 -222.198827) (xy 111.858925 -222.162189)
			(xy 111.828469 -222.12027) (xy 111.804946 -222.074103) (xy 111.788934 -222.024824) (xy 111.780828 -221.973647)
			(xy 111.78032 -221.94774) (xy 110.560104 -221.94774) (xy 110.559596 -221.973627) (xy 110.551497 -222.024765)
			(xy 110.535498 -222.074005) (xy 110.511992 -222.120137) (xy 110.48156 -222.162024) (xy 110.44495 -222.198634)
			(xy 110.403063 -222.229066) (xy 110.356931 -222.252572) (xy 110.307691 -222.268571) (xy 110.256553 -222.27667)
			(xy 110.204779 -222.27667) (xy 110.153641 -222.268571) (xy 110.104401 -222.252572) (xy 110.058269 -222.229066)
			(xy 110.016382 -222.198634) (xy 109.979772 -222.162024) (xy 109.94934 -222.120137) (xy 109.925834 -222.074005)
			(xy 109.909835 -222.024765) (xy 109.901736 -221.973627) (xy 109.901228 -221.94774) (xy 108.680504 -221.94774)
			(xy 108.679996 -221.973647) (xy 108.67189 -222.024824) (xy 108.655878 -222.074103) (xy 108.632355 -222.12027)
			(xy 108.601899 -222.162189) (xy 108.565261 -222.198827) (xy 108.523342 -222.229283) (xy 108.477175 -222.252806)
			(xy 108.427896 -222.268818) (xy 108.376719 -222.276924) (xy 108.324905 -222.276924) (xy 108.273728 -222.268818)
			(xy 108.224449 -222.252806) (xy 108.178282 -222.229283) (xy 108.136363 -222.198827) (xy 108.099725 -222.162189)
			(xy 108.069269 -222.12027) (xy 108.045746 -222.074103) (xy 108.029734 -222.024824) (xy 108.021628 -221.973647)
			(xy 108.02112 -221.94774) (xy 106.800904 -221.94774) (xy 106.800396 -221.973647) (xy 106.79229 -222.024824)
			(xy 106.776278 -222.074103) (xy 106.752755 -222.12027) (xy 106.722299 -222.162189) (xy 106.685661 -222.198827)
			(xy 106.643742 -222.229283) (xy 106.597575 -222.252806) (xy 106.548296 -222.268818) (xy 106.497119 -222.276924)
			(xy 106.445305 -222.276924) (xy 106.394128 -222.268818) (xy 106.344849 -222.252806) (xy 106.298682 -222.229283)
			(xy 106.256763 -222.198827) (xy 106.220125 -222.162189) (xy 106.189669 -222.12027) (xy 106.166146 -222.074103)
			(xy 106.150134 -222.024824) (xy 106.142028 -221.973647) (xy 106.14152 -221.94774) (xy 104.921304 -221.94774)
			(xy 104.920796 -221.973647) (xy 104.91269 -222.024824) (xy 104.896678 -222.074103) (xy 104.873155 -222.12027)
			(xy 104.842699 -222.162189) (xy 104.806061 -222.198827) (xy 104.764142 -222.229283) (xy 104.717975 -222.252806)
			(xy 104.668696 -222.268818) (xy 104.617519 -222.276924) (xy 104.565705 -222.276924) (xy 104.514528 -222.268818)
			(xy 104.465249 -222.252806) (xy 104.419082 -222.229283) (xy 104.377163 -222.198827) (xy 104.340525 -222.162189)
			(xy 104.310069 -222.12027) (xy 104.286546 -222.074103) (xy 104.270534 -222.024824) (xy 104.262428 -221.973647)
			(xy 104.26192 -221.94774) (xy 103.041704 -221.94774) (xy 103.041196 -221.973647) (xy 103.03309 -222.024824)
			(xy 103.017078 -222.074103) (xy 102.993555 -222.12027) (xy 102.963099 -222.162189) (xy 102.926461 -222.198827)
			(xy 102.884542 -222.229283) (xy 102.838375 -222.252806) (xy 102.789096 -222.268818) (xy 102.737919 -222.276924)
			(xy 102.686105 -222.276924) (xy 102.634928 -222.268818) (xy 102.585649 -222.252806) (xy 102.539482 -222.229283)
			(xy 102.497563 -222.198827) (xy 102.460925 -222.162189) (xy 102.430469 -222.12027) (xy 102.406946 -222.074103)
			(xy 102.390934 -222.024824) (xy 102.382828 -221.973647) (xy 102.38232 -221.94774) (xy 102.382923 -221.920023)
			(xy 102.39224 -221.865377) (xy 102.400862 -221.839028) (xy 102.408736 -221.81693) (xy 102.203758 -221.462092)
			(xy 102.180898 -221.457774) (xy 102.156103 -221.45255) (xy 102.108367 -221.435564) (xy 102.063792 -221.411474)
			(xy 102.023427 -221.380847) (xy 101.988224 -221.344405) (xy 101.959011 -221.303006) (xy 101.936476 -221.257625)
			(xy 101.92115 -221.20933) (xy 101.913394 -221.159258) (xy 101.912928 -221.133924) (xy 101.632004 -221.133924)
			(xy 101.631496 -221.159811) (xy 101.623397 -221.210949) (xy 101.607398 -221.260189) (xy 101.583892 -221.306321)
			(xy 101.55346 -221.348208) (xy 101.51685 -221.384818) (xy 101.474963 -221.41525) (xy 101.428831 -221.438756)
			(xy 101.379591 -221.454755) (xy 101.328453 -221.462854) (xy 101.276679 -221.462854) (xy 101.225541 -221.454755)
			(xy 101.176301 -221.438756) (xy 101.130169 -221.41525) (xy 101.088282 -221.384818) (xy 101.051672 -221.348208)
			(xy 101.02124 -221.306321) (xy 100.997734 -221.260189) (xy 100.981735 -221.210949) (xy 100.973636 -221.159811)
			(xy 100.973128 -221.133924) (xy 100.692204 -221.133924) (xy 100.69168 -221.161632) (xy 100.682481 -221.216279)
			(xy 100.673916 -221.242636) (xy 100.666042 -221.264734) (xy 100.87102 -221.619572) (xy 100.89388 -221.62389)
			(xy 100.918705 -221.629041) (xy 100.966483 -221.645999) (xy 101.011102 -221.670074) (xy 101.051507 -221.700696)
			(xy 101.086747 -221.737145) (xy 101.11599 -221.778561) (xy 101.138547 -221.823965) (xy 101.153885 -221.872289)
			(xy 101.161642 -221.92239) (xy 101.162104 -221.94774) (xy 101.161596 -221.973647) (xy 101.15349 -222.024824)
			(xy 101.137478 -222.074103) (xy 101.113955 -222.12027) (xy 101.083499 -222.162189) (xy 101.046861 -222.198827)
			(xy 101.004942 -222.229283) (xy 100.958775 -222.252806) (xy 100.909496 -222.268818) (xy 100.858319 -222.276924)
			(xy 100.806505 -222.276924) (xy 100.755328 -222.268818) (xy 100.706049 -222.252806) (xy 100.659882 -222.229283)
			(xy 100.617963 -222.198827) (xy 100.581325 -222.162189) (xy 100.550869 -222.12027) (xy 100.527346 -222.074103)
			(xy 100.511334 -222.024824) (xy 100.503228 -221.973647) (xy 100.50272 -221.94774) (xy 100.503323 -221.920023)
			(xy 100.51264 -221.865377) (xy 100.521262 -221.839028) (xy 100.529136 -221.81693) (xy 100.324158 -221.462092)
			(xy 100.301298 -221.457774) (xy 100.276503 -221.45255) (xy 100.228767 -221.435564) (xy 100.184192 -221.411474)
			(xy 100.143827 -221.380847) (xy 100.108624 -221.344405) (xy 100.079411 -221.303006) (xy 100.056876 -221.257625)
			(xy 100.04155 -221.20933) (xy 100.033794 -221.159258) (xy 100.033328 -221.133924) (xy 99.752404 -221.133924)
			(xy 99.751896 -221.159811) (xy 99.743797 -221.210949) (xy 99.727798 -221.260189) (xy 99.704292 -221.306321)
			(xy 99.67386 -221.348208) (xy 99.63725 -221.384818) (xy 99.595363 -221.41525) (xy 99.549231 -221.438756)
			(xy 99.499991 -221.454755) (xy 99.448853 -221.462854) (xy 99.397079 -221.462854) (xy 99.345941 -221.454755)
			(xy 99.296701 -221.438756) (xy 99.250569 -221.41525) (xy 99.208682 -221.384818) (xy 99.172072 -221.348208)
			(xy 99.14164 -221.306321) (xy 99.118134 -221.260189) (xy 99.102135 -221.210949) (xy 99.094036 -221.159811)
			(xy 99.093528 -221.133924) (xy 98.812604 -221.133924) (xy 98.81208 -221.161632) (xy 98.802881 -221.216279)
			(xy 98.794316 -221.242636) (xy 98.786442 -221.264734) (xy 98.99142 -221.619572) (xy 99.01428 -221.62389)
			(xy 99.039105 -221.629041) (xy 99.086883 -221.645999) (xy 99.131502 -221.670074) (xy 99.171907 -221.700696)
			(xy 99.207147 -221.737145) (xy 99.23639 -221.778561) (xy 99.258947 -221.823965) (xy 99.274285 -221.872289)
			(xy 99.282042 -221.92239) (xy 99.282504 -221.94774) (xy 99.281996 -221.973647) (xy 99.27389 -222.024824)
			(xy 99.257878 -222.074103) (xy 99.234355 -222.12027) (xy 99.203899 -222.162189) (xy 99.167261 -222.198827)
			(xy 99.125342 -222.229283) (xy 99.079175 -222.252806) (xy 99.029896 -222.268818) (xy 98.978719 -222.276924)
			(xy 98.926905 -222.276924) (xy 98.875728 -222.268818) (xy 98.826449 -222.252806) (xy 98.780282 -222.229283)
			(xy 98.738363 -222.198827) (xy 98.701725 -222.162189) (xy 98.671269 -222.12027) (xy 98.647746 -222.074103)
			(xy 98.631734 -222.024824) (xy 98.623628 -221.973647) (xy 98.62312 -221.94774) (xy 98.623723 -221.920023)
			(xy 98.63304 -221.865377) (xy 98.641662 -221.839028) (xy 98.649536 -221.81693) (xy 98.444558 -221.462092)
			(xy 98.421698 -221.457774) (xy 98.396903 -221.45255) (xy 98.349167 -221.435564) (xy 98.304592 -221.411474)
			(xy 98.264227 -221.380847) (xy 98.229024 -221.344405) (xy 98.199811 -221.303006) (xy 98.177276 -221.257625)
			(xy 98.16195 -221.20933) (xy 98.154194 -221.159258) (xy 98.153728 -221.133924) (xy 97.872804 -221.133924)
			(xy 97.872296 -221.159811) (xy 97.864197 -221.210949) (xy 97.848198 -221.260189) (xy 97.824692 -221.306321)
			(xy 97.79426 -221.348208) (xy 97.75765 -221.384818) (xy 97.715763 -221.41525) (xy 97.669631 -221.438756)
			(xy 97.620391 -221.454755) (xy 97.569253 -221.462854) (xy 97.517479 -221.462854) (xy 97.466341 -221.454755)
			(xy 97.417101 -221.438756) (xy 97.370969 -221.41525) (xy 97.329082 -221.384818) (xy 97.292472 -221.348208)
			(xy 97.26204 -221.306321) (xy 97.238534 -221.260189) (xy 97.222535 -221.210949) (xy 97.214436 -221.159811)
			(xy 97.213928 -221.133924) (xy 96.933004 -221.133924) (xy 96.93248 -221.161632) (xy 96.923281 -221.216279)
			(xy 96.914716 -221.242636) (xy 96.906842 -221.264734) (xy 97.11182 -221.619572) (xy 97.13468 -221.62389)
			(xy 97.159505 -221.629041) (xy 97.207283 -221.645999) (xy 97.251902 -221.670074) (xy 97.292307 -221.700696)
			(xy 97.327547 -221.737145) (xy 97.35679 -221.778561) (xy 97.379347 -221.823965) (xy 97.394685 -221.872289)
			(xy 97.402442 -221.92239) (xy 97.402904 -221.94774) (xy 97.402396 -221.973647) (xy 97.39429 -222.024824)
			(xy 97.378278 -222.074103) (xy 97.354755 -222.12027) (xy 97.324299 -222.162189) (xy 97.287661 -222.198827)
			(xy 97.245742 -222.229283) (xy 97.199575 -222.252806) (xy 97.150296 -222.268818) (xy 97.099119 -222.276924)
			(xy 97.047305 -222.276924) (xy 96.996128 -222.268818) (xy 96.946849 -222.252806) (xy 96.900682 -222.229283)
			(xy 96.858763 -222.198827) (xy 96.822125 -222.162189) (xy 96.791669 -222.12027) (xy 96.768146 -222.074103)
			(xy 96.752134 -222.024824) (xy 96.744028 -221.973647) (xy 96.74352 -221.94774) (xy 96.744123 -221.920023)
			(xy 96.75344 -221.865377) (xy 96.762062 -221.839028) (xy 96.769936 -221.81693) (xy 96.564958 -221.462092)
			(xy 96.542098 -221.457774) (xy 96.517303 -221.45255) (xy 96.469567 -221.435564) (xy 96.424992 -221.411474)
			(xy 96.384627 -221.380847) (xy 96.349424 -221.344405) (xy 96.320211 -221.303006) (xy 96.297676 -221.257625)
			(xy 96.28235 -221.20933) (xy 96.274594 -221.159258) (xy 96.274128 -221.133924) (xy 95.993204 -221.133924)
			(xy 95.992696 -221.159811) (xy 95.984597 -221.210949) (xy 95.968598 -221.260189) (xy 95.945092 -221.306321)
			(xy 95.91466 -221.348208) (xy 95.87805 -221.384818) (xy 95.836163 -221.41525) (xy 95.790031 -221.438756)
			(xy 95.740791 -221.454755) (xy 95.689653 -221.462854) (xy 95.637879 -221.462854) (xy 95.586741 -221.454755)
			(xy 95.537501 -221.438756) (xy 95.491369 -221.41525) (xy 95.449482 -221.384818) (xy 95.412872 -221.348208)
			(xy 95.38244 -221.306321) (xy 95.358934 -221.260189) (xy 95.342935 -221.210949) (xy 95.334836 -221.159811)
			(xy 95.334328 -221.133924) (xy 95.053404 -221.133924) (xy 95.05288 -221.161632) (xy 95.043681 -221.216279)
			(xy 95.035116 -221.242636) (xy 95.027242 -221.264734) (xy 95.23222 -221.619572) (xy 95.25508 -221.62389)
			(xy 95.279905 -221.629041) (xy 95.327683 -221.645999) (xy 95.372302 -221.670074) (xy 95.412707 -221.700696)
			(xy 95.447947 -221.737145) (xy 95.47719 -221.778561) (xy 95.499747 -221.823965) (xy 95.515085 -221.872289)
			(xy 95.522842 -221.92239) (xy 95.523304 -221.94774) (xy 95.522796 -221.973647) (xy 95.51469 -222.024824)
			(xy 95.498678 -222.074103) (xy 95.475155 -222.12027) (xy 95.444699 -222.162189) (xy 95.408061 -222.198827)
			(xy 95.366142 -222.229283) (xy 95.319975 -222.252806) (xy 95.270696 -222.268818) (xy 95.219519 -222.276924)
			(xy 95.167705 -222.276924) (xy 95.116528 -222.268818) (xy 95.067249 -222.252806) (xy 95.021082 -222.229283)
			(xy 94.979163 -222.198827) (xy 94.942525 -222.162189) (xy 94.912069 -222.12027) (xy 94.888546 -222.074103)
			(xy 94.872534 -222.024824) (xy 94.864428 -221.973647) (xy 94.86392 -221.94774) (xy 94.864523 -221.920023)
			(xy 94.87384 -221.865377) (xy 94.882462 -221.839028) (xy 94.890336 -221.81693) (xy 94.685358 -221.462092)
			(xy 94.662498 -221.457774) (xy 94.637703 -221.45255) (xy 94.589967 -221.435564) (xy 94.545392 -221.411474)
			(xy 94.505027 -221.380847) (xy 94.469824 -221.344405) (xy 94.440611 -221.303006) (xy 94.418076 -221.257625)
			(xy 94.40275 -221.20933) (xy 94.394994 -221.159258) (xy 94.394528 -221.133924) (xy 94.113604 -221.133924)
			(xy 94.113096 -221.159811) (xy 94.104997 -221.210949) (xy 94.088998 -221.260189) (xy 94.065492 -221.306321)
			(xy 94.03506 -221.348208) (xy 93.99845 -221.384818) (xy 93.956563 -221.41525) (xy 93.910431 -221.438756)
			(xy 93.861191 -221.454755) (xy 93.810053 -221.462854) (xy 93.758279 -221.462854) (xy 93.707141 -221.454755)
			(xy 93.657901 -221.438756) (xy 93.611769 -221.41525) (xy 93.569882 -221.384818) (xy 93.533272 -221.348208)
			(xy 93.50284 -221.306321) (xy 93.479334 -221.260189) (xy 93.463335 -221.210949) (xy 93.455236 -221.159811)
			(xy 93.454728 -221.133924) (xy 93.173804 -221.133924) (xy 93.17328 -221.161632) (xy 93.164081 -221.216279)
			(xy 93.155516 -221.242636) (xy 93.147642 -221.264734) (xy 93.35262 -221.619572) (xy 93.37548 -221.62389)
			(xy 93.400305 -221.629041) (xy 93.448083 -221.645999) (xy 93.492702 -221.670074) (xy 93.533107 -221.700696)
			(xy 93.568347 -221.737145) (xy 93.59759 -221.778561) (xy 93.620147 -221.823965) (xy 93.635485 -221.872289)
			(xy 93.643242 -221.92239) (xy 93.643704 -221.94774) (xy 93.643196 -221.973647) (xy 93.63509 -222.024824)
			(xy 93.619078 -222.074103) (xy 93.595555 -222.12027) (xy 93.565099 -222.162189) (xy 93.528461 -222.198827)
			(xy 93.486542 -222.229283) (xy 93.440375 -222.252806) (xy 93.391096 -222.268818) (xy 93.339919 -222.276924)
			(xy 93.288105 -222.276924) (xy 93.236928 -222.268818) (xy 93.187649 -222.252806) (xy 93.141482 -222.229283)
			(xy 93.099563 -222.198827) (xy 93.062925 -222.162189) (xy 93.032469 -222.12027) (xy 93.008946 -222.074103)
			(xy 92.992934 -222.024824) (xy 92.984828 -221.973647) (xy 92.98432 -221.94774) (xy 92.984923 -221.920023)
			(xy 92.99424 -221.865377) (xy 93.002862 -221.839028) (xy 93.010736 -221.81693) (xy 92.805758 -221.462092)
			(xy 92.782898 -221.457774) (xy 92.758103 -221.45255) (xy 92.710367 -221.435564) (xy 92.665792 -221.411474)
			(xy 92.625427 -221.380847) (xy 92.590224 -221.344405) (xy 92.561011 -221.303006) (xy 92.538476 -221.257625)
			(xy 92.52315 -221.20933) (xy 92.515394 -221.159258) (xy 92.514928 -221.133924) (xy 92.234004 -221.133924)
			(xy 92.233496 -221.159811) (xy 92.225397 -221.210949) (xy 92.209398 -221.260189) (xy 92.185892 -221.306321)
			(xy 92.15546 -221.348208) (xy 92.11885 -221.384818) (xy 92.076963 -221.41525) (xy 92.030831 -221.438756)
			(xy 91.981591 -221.454755) (xy 91.930453 -221.462854) (xy 91.878679 -221.462854) (xy 91.827541 -221.454755)
			(xy 91.778301 -221.438756) (xy 91.732169 -221.41525) (xy 91.690282 -221.384818) (xy 91.653672 -221.348208)
			(xy 91.62324 -221.306321) (xy 91.599734 -221.260189) (xy 91.583735 -221.210949) (xy 91.575636 -221.159811)
			(xy 91.575128 -221.133924) (xy 91.294204 -221.133924) (xy 91.29368 -221.161632) (xy 91.284481 -221.216279)
			(xy 91.275916 -221.242636) (xy 91.268042 -221.264734) (xy 91.47302 -221.619572) (xy 91.49588 -221.62389)
			(xy 91.520705 -221.629041) (xy 91.568483 -221.645999) (xy 91.613102 -221.670074) (xy 91.653507 -221.700696)
			(xy 91.688747 -221.737145) (xy 91.71799 -221.778561) (xy 91.740547 -221.823965) (xy 91.755885 -221.872289)
			(xy 91.763642 -221.92239) (xy 91.764104 -221.94774) (xy 91.763596 -221.973647) (xy 91.75549 -222.024824)
			(xy 91.739478 -222.074103) (xy 91.715955 -222.12027) (xy 91.685499 -222.162189) (xy 91.648861 -222.198827)
			(xy 91.606942 -222.229283) (xy 91.560775 -222.252806) (xy 91.511496 -222.268818) (xy 91.460319 -222.276924)
			(xy 91.408505 -222.276924) (xy 91.357328 -222.268818) (xy 91.308049 -222.252806) (xy 91.261882 -222.229283)
			(xy 91.219963 -222.198827) (xy 91.183325 -222.162189) (xy 91.152869 -222.12027) (xy 91.129346 -222.074103)
			(xy 91.113334 -222.024824) (xy 91.105228 -221.973647) (xy 91.10472 -221.94774) (xy 91.105323 -221.920023)
			(xy 91.11464 -221.865377) (xy 91.123262 -221.839028) (xy 91.131136 -221.81693) (xy 90.926158 -221.462092)
			(xy 90.903298 -221.457774) (xy 90.878503 -221.45255) (xy 90.830767 -221.435564) (xy 90.786192 -221.411474)
			(xy 90.745827 -221.380847) (xy 90.710624 -221.344405) (xy 90.681411 -221.303006) (xy 90.658876 -221.257625)
			(xy 90.64355 -221.20933) (xy 90.635794 -221.159258) (xy 90.635328 -221.133924) (xy 90.354404 -221.133924)
			(xy 90.353896 -221.159811) (xy 90.345797 -221.210949) (xy 90.329798 -221.260189) (xy 90.306292 -221.306321)
			(xy 90.27586 -221.348208) (xy 90.23925 -221.384818) (xy 90.197363 -221.41525) (xy 90.151231 -221.438756)
			(xy 90.101991 -221.454755) (xy 90.050853 -221.462854) (xy 89.999079 -221.462854) (xy 89.947941 -221.454755)
			(xy 89.898701 -221.438756) (xy 89.852569 -221.41525) (xy 89.810682 -221.384818) (xy 89.774072 -221.348208)
			(xy 89.74364 -221.306321) (xy 89.720134 -221.260189) (xy 89.704135 -221.210949) (xy 89.696036 -221.159811)
			(xy 89.695528 -221.133924) (xy 89.414604 -221.133924) (xy 89.41408 -221.161632) (xy 89.404881 -221.216279)
			(xy 89.396316 -221.242636) (xy 89.388442 -221.264734) (xy 89.59342 -221.619572) (xy 89.61628 -221.62389)
			(xy 89.641105 -221.629041) (xy 89.688883 -221.645999) (xy 89.733502 -221.670074) (xy 89.773907 -221.700696)
			(xy 89.809147 -221.737145) (xy 89.83839 -221.778561) (xy 89.860947 -221.823965) (xy 89.876285 -221.872289)
			(xy 89.884042 -221.92239) (xy 89.884504 -221.94774) (xy 89.883996 -221.973647) (xy 89.87589 -222.024824)
			(xy 89.859878 -222.074103) (xy 89.836355 -222.12027) (xy 89.805899 -222.162189) (xy 89.769261 -222.198827)
			(xy 89.727342 -222.229283) (xy 89.681175 -222.252806) (xy 89.631896 -222.268818) (xy 89.580719 -222.276924)
			(xy 89.528905 -222.276924) (xy 89.477728 -222.268818) (xy 89.428449 -222.252806) (xy 89.382282 -222.229283)
			(xy 89.340363 -222.198827) (xy 89.303725 -222.162189) (xy 89.273269 -222.12027) (xy 89.249746 -222.074103)
			(xy 89.233734 -222.024824) (xy 89.225628 -221.973647) (xy 89.22512 -221.94774) (xy 89.225723 -221.920023)
			(xy 89.23504 -221.865377) (xy 89.243662 -221.839028) (xy 89.251536 -221.81693) (xy 89.046558 -221.462092)
			(xy 89.023698 -221.457774) (xy 88.998903 -221.45255) (xy 88.951167 -221.435564) (xy 88.906592 -221.411474)
			(xy 88.866227 -221.380847) (xy 88.831024 -221.344405) (xy 88.801811 -221.303006) (xy 88.779276 -221.257625)
			(xy 88.76395 -221.20933) (xy 88.756194 -221.159258) (xy 88.755728 -221.133924) (xy 2.509012 -221.133924)
			(xy 2.509012 -224.389442) (xy 89.695528 -224.389442) (xy 89.695935 -224.364105) (xy 89.703697 -224.314028)
			(xy 89.719029 -224.265728) (xy 89.74157 -224.220343) (xy 89.770789 -224.17894) (xy 89.805999 -224.142496)
			(xy 89.84637 -224.111867) (xy 89.890952 -224.087776) (xy 89.938695 -224.070789) (xy 89.963498 -224.065592)
			(xy 89.986358 -224.061274) (xy 90.191082 -223.706182) (xy 90.183462 -223.684338) (xy 90.174817 -223.657995)
			(xy 90.165504 -223.603345) (xy 90.16492 -223.575626) (xy 90.165428 -223.549719) (xy 90.173534 -223.498542)
			(xy 90.189546 -223.449263) (xy 90.213069 -223.403096) (xy 90.243525 -223.361177) (xy 90.280163 -223.324539)
			(xy 90.322082 -223.294083) (xy 90.368249 -223.27056) (xy 90.417528 -223.254548) (xy 90.468705 -223.246442)
			(xy 90.520519 -223.246442) (xy 90.571696 -223.254548) (xy 90.620975 -223.27056) (xy 90.667142 -223.294083)
			(xy 90.709061 -223.324539) (xy 90.745699 -223.361177) (xy 90.776155 -223.403096) (xy 90.799678 -223.449263)
			(xy 90.81569 -223.498542) (xy 90.823796 -223.549719) (xy 90.824304 -223.575626) (xy 90.823803 -223.60097)
			(xy 90.816028 -223.651059) (xy 90.800679 -223.699368) (xy 90.77812 -223.74476) (xy 90.74888 -223.786165)
			(xy 90.713649 -223.822609) (xy 90.673257 -223.853232) (xy 90.628654 -223.877314) (xy 90.580892 -223.894288)
			(xy 90.55608 -223.899476) (xy 90.53322 -223.903794) (xy 90.328496 -224.258632) (xy 90.336116 -224.280476)
			(xy 90.344672 -224.306769) (xy 90.353865 -224.361289) (xy 90.354404 -224.388934) (xy 90.354404 -224.389442)
			(xy 90.635328 -224.389442) (xy 90.635836 -224.363555) (xy 90.643935 -224.312417) (xy 90.659934 -224.263177)
			(xy 90.68344 -224.217045) (xy 90.713872 -224.175158) (xy 90.750482 -224.138548) (xy 90.792369 -224.108116)
			(xy 90.838501 -224.08461) (xy 90.887741 -224.068611) (xy 90.938879 -224.060512) (xy 90.990653 -224.060512)
			(xy 91.041791 -224.068611) (xy 91.091031 -224.08461) (xy 91.137163 -224.108116) (xy 91.17905 -224.138548)
			(xy 91.21566 -224.175158) (xy 91.246092 -224.217045) (xy 91.269598 -224.263177) (xy 91.285597 -224.312417)
			(xy 91.293696 -224.363555) (xy 91.294204 -224.389442) (xy 91.575128 -224.389442) (xy 91.575535 -224.364105)
			(xy 91.583297 -224.314028) (xy 91.598629 -224.265728) (xy 91.62117 -224.220343) (xy 91.650389 -224.17894)
			(xy 91.685599 -224.142496) (xy 91.72597 -224.111867) (xy 91.770552 -224.087776) (xy 91.818295 -224.070789)
			(xy 91.843098 -224.065592) (xy 91.865958 -224.061274) (xy 92.070682 -223.706182) (xy 92.063062 -223.684338)
			(xy 92.054417 -223.657995) (xy 92.045104 -223.603345) (xy 92.04452 -223.575626) (xy 92.045028 -223.549719)
			(xy 92.053134 -223.498542) (xy 92.069146 -223.449263) (xy 92.092669 -223.403096) (xy 92.123125 -223.361177)
			(xy 92.159763 -223.324539) (xy 92.201682 -223.294083) (xy 92.247849 -223.27056) (xy 92.297128 -223.254548)
			(xy 92.348305 -223.246442) (xy 92.400119 -223.246442) (xy 92.451296 -223.254548) (xy 92.500575 -223.27056)
			(xy 92.546742 -223.294083) (xy 92.588661 -223.324539) (xy 92.625299 -223.361177) (xy 92.655755 -223.403096)
			(xy 92.679278 -223.449263) (xy 92.69529 -223.498542) (xy 92.703396 -223.549719) (xy 92.703904 -223.575626)
			(xy 92.703403 -223.60097) (xy 92.695628 -223.651059) (xy 92.680279 -223.699368) (xy 92.65772 -223.74476)
			(xy 92.62848 -223.786165) (xy 92.593249 -223.822609) (xy 92.552857 -223.853232) (xy 92.508254 -223.877314)
			(xy 92.460492 -223.894288) (xy 92.43568 -223.899476) (xy 92.41282 -223.903794) (xy 92.208096 -224.258632)
			(xy 92.215716 -224.280476) (xy 92.224272 -224.306769) (xy 92.233465 -224.361289) (xy 92.234004 -224.388934)
			(xy 92.234004 -224.389442) (xy 92.514928 -224.389442) (xy 92.515436 -224.363555) (xy 92.523535 -224.312417)
			(xy 92.539534 -224.263177) (xy 92.56304 -224.217045) (xy 92.593472 -224.175158) (xy 92.630082 -224.138548)
			(xy 92.671969 -224.108116) (xy 92.718101 -224.08461) (xy 92.767341 -224.068611) (xy 92.818479 -224.060512)
			(xy 92.870253 -224.060512) (xy 92.921391 -224.068611) (xy 92.970631 -224.08461) (xy 93.016763 -224.108116)
			(xy 93.05865 -224.138548) (xy 93.09526 -224.175158) (xy 93.125692 -224.217045) (xy 93.149198 -224.263177)
			(xy 93.165197 -224.312417) (xy 93.173296 -224.363555) (xy 93.173804 -224.389442) (xy 93.454728 -224.389442)
			(xy 93.455135 -224.364105) (xy 93.462897 -224.314028) (xy 93.478229 -224.265728) (xy 93.50077 -224.220343)
			(xy 93.529989 -224.17894) (xy 93.565199 -224.142496) (xy 93.60557 -224.111867) (xy 93.650152 -224.087776)
			(xy 93.697895 -224.070789) (xy 93.722698 -224.065592) (xy 93.745558 -224.061274) (xy 93.950282 -223.706436)
			(xy 93.942662 -223.684338) (xy 93.934031 -223.657991) (xy 93.92471 -223.603344) (xy 93.92412 -223.575626)
			(xy 93.924628 -223.549719) (xy 93.932734 -223.498542) (xy 93.948746 -223.449263) (xy 93.972269 -223.403096)
			(xy 94.002725 -223.361177) (xy 94.039363 -223.324539) (xy 94.081282 -223.294083) (xy 94.127449 -223.27056)
			(xy 94.176728 -223.254548) (xy 94.227905 -223.246442) (xy 94.279719 -223.246442) (xy 94.330896 -223.254548)
			(xy 94.380175 -223.27056) (xy 94.426342 -223.294083) (xy 94.468261 -223.324539) (xy 94.504899 -223.361177)
			(xy 94.535355 -223.403096) (xy 94.558878 -223.449263) (xy 94.57489 -223.498542) (xy 94.582996 -223.549719)
			(xy 94.583504 -223.575626) (xy 94.583087 -223.600992) (xy 94.575334 -223.651127) (xy 94.559985 -223.69948)
			(xy 94.537403 -223.744908) (xy 94.508122 -223.786336) (xy 94.472834 -223.822783) (xy 94.432375 -223.853388)
			(xy 94.387701 -223.877427) (xy 94.339869 -223.894332) (xy 94.315026 -223.899476) (xy 94.292166 -223.903794)
			(xy 94.087442 -224.258632) (xy 94.095316 -224.280476) (xy 94.10389 -224.306896) (xy 94.11309 -224.36167)
			(xy 94.113604 -224.389442) (xy 94.394528 -224.389442) (xy 94.395036 -224.363555) (xy 94.403135 -224.312417)
			(xy 94.419134 -224.263177) (xy 94.44264 -224.217045) (xy 94.473072 -224.175158) (xy 94.509682 -224.138548)
			(xy 94.551569 -224.108116) (xy 94.597701 -224.08461) (xy 94.646941 -224.068611) (xy 94.698079 -224.060512)
			(xy 94.749853 -224.060512) (xy 94.800991 -224.068611) (xy 94.850231 -224.08461) (xy 94.896363 -224.108116)
			(xy 94.93825 -224.138548) (xy 94.97486 -224.175158) (xy 95.005292 -224.217045) (xy 95.028798 -224.263177)
			(xy 95.044797 -224.312417) (xy 95.052896 -224.363555) (xy 95.053404 -224.389442) (xy 95.334328 -224.389442)
			(xy 95.334735 -224.364105) (xy 95.342497 -224.314028) (xy 95.357829 -224.265728) (xy 95.38037 -224.220343)
			(xy 95.409589 -224.17894) (xy 95.444799 -224.142496) (xy 95.48517 -224.111867) (xy 95.529752 -224.087776)
			(xy 95.577495 -224.070789) (xy 95.602298 -224.065592) (xy 95.625158 -224.061274) (xy 95.829882 -223.706436)
			(xy 95.822262 -223.684338) (xy 95.813631 -223.657991) (xy 95.80431 -223.603344) (xy 95.80372 -223.575626)
			(xy 95.804228 -223.549719) (xy 95.812334 -223.498542) (xy 95.828346 -223.449263) (xy 95.851869 -223.403096)
			(xy 95.882325 -223.361177) (xy 95.918963 -223.324539) (xy 95.960882 -223.294083) (xy 96.007049 -223.27056)
			(xy 96.056328 -223.254548) (xy 96.107505 -223.246442) (xy 96.159319 -223.246442) (xy 96.210496 -223.254548)
			(xy 96.259775 -223.27056) (xy 96.305942 -223.294083) (xy 96.347861 -223.324539) (xy 96.384499 -223.361177)
			(xy 96.414955 -223.403096) (xy 96.438478 -223.449263) (xy 96.45449 -223.498542) (xy 96.462596 -223.549719)
			(xy 96.463104 -223.575626) (xy 96.462687 -223.600992) (xy 96.454934 -223.651127) (xy 96.439585 -223.69948)
			(xy 96.417003 -223.744908) (xy 96.387722 -223.786336) (xy 96.352434 -223.822783) (xy 96.311975 -223.853388)
			(xy 96.267301 -223.877427) (xy 96.219469 -223.894332) (xy 96.194626 -223.899476) (xy 96.171766 -223.903794)
			(xy 95.967042 -224.258632) (xy 95.974916 -224.280476) (xy 95.98349 -224.306896) (xy 95.99269 -224.36167)
			(xy 95.993204 -224.389442) (xy 96.274128 -224.389442) (xy 96.274636 -224.363555) (xy 96.282735 -224.312417)
			(xy 96.298734 -224.263177) (xy 96.32224 -224.217045) (xy 96.352672 -224.175158) (xy 96.389282 -224.138548)
			(xy 96.431169 -224.108116) (xy 96.477301 -224.08461) (xy 96.526541 -224.068611) (xy 96.577679 -224.060512)
			(xy 96.629453 -224.060512) (xy 96.680591 -224.068611) (xy 96.729831 -224.08461) (xy 96.775963 -224.108116)
			(xy 96.81785 -224.138548) (xy 96.85446 -224.175158) (xy 96.884892 -224.217045) (xy 96.908398 -224.263177)
			(xy 96.924397 -224.312417) (xy 96.932496 -224.363555) (xy 96.933004 -224.389442) (xy 97.213928 -224.389442)
			(xy 97.214335 -224.364105) (xy 97.222097 -224.314028) (xy 97.237429 -224.265728) (xy 97.25997 -224.220343)
			(xy 97.289189 -224.17894) (xy 97.324399 -224.142496) (xy 97.36477 -224.111867) (xy 97.409352 -224.087776)
			(xy 97.457095 -224.070789) (xy 97.481898 -224.065592) (xy 97.504758 -224.061274) (xy 97.709482 -223.706436)
			(xy 97.701862 -223.684338) (xy 97.693231 -223.657991) (xy 97.68391 -223.603344) (xy 97.68332 -223.575626)
			(xy 97.683828 -223.549719) (xy 97.691934 -223.498542) (xy 97.707946 -223.449263) (xy 97.731469 -223.403096)
			(xy 97.761925 -223.361177) (xy 97.798563 -223.324539) (xy 97.840482 -223.294083) (xy 97.886649 -223.27056)
			(xy 97.935928 -223.254548) (xy 97.987105 -223.246442) (xy 98.038919 -223.246442) (xy 98.090096 -223.254548)
			(xy 98.139375 -223.27056) (xy 98.185542 -223.294083) (xy 98.227461 -223.324539) (xy 98.264099 -223.361177)
			(xy 98.294555 -223.403096) (xy 98.318078 -223.449263) (xy 98.33409 -223.498542) (xy 98.342196 -223.549719)
			(xy 98.342704 -223.575626) (xy 98.342287 -223.600992) (xy 98.334534 -223.651127) (xy 98.319185 -223.69948)
			(xy 98.296603 -223.744908) (xy 98.267322 -223.786336) (xy 98.232034 -223.822783) (xy 98.191575 -223.853388)
			(xy 98.146901 -223.877427) (xy 98.099069 -223.894332) (xy 98.074226 -223.899476) (xy 98.051366 -223.903794)
			(xy 97.846642 -224.258632) (xy 97.854516 -224.280476) (xy 97.86309 -224.306896) (xy 97.87229 -224.36167)
			(xy 97.872804 -224.389442) (xy 98.153728 -224.389442) (xy 98.154236 -224.363555) (xy 98.162335 -224.312417)
			(xy 98.178334 -224.263177) (xy 98.20184 -224.217045) (xy 98.232272 -224.175158) (xy 98.268882 -224.138548)
			(xy 98.310769 -224.108116) (xy 98.356901 -224.08461) (xy 98.406141 -224.068611) (xy 98.457279 -224.060512)
			(xy 98.509053 -224.060512) (xy 98.560191 -224.068611) (xy 98.609431 -224.08461) (xy 98.655563 -224.108116)
			(xy 98.69745 -224.138548) (xy 98.73406 -224.175158) (xy 98.764492 -224.217045) (xy 98.787998 -224.263177)
			(xy 98.803997 -224.312417) (xy 98.812096 -224.363555) (xy 98.812604 -224.389442) (xy 99.093528 -224.389442)
			(xy 99.093935 -224.364105) (xy 99.101697 -224.314028) (xy 99.117029 -224.265728) (xy 99.13957 -224.220343)
			(xy 99.168789 -224.17894) (xy 99.203999 -224.142496) (xy 99.24437 -224.111867) (xy 99.288952 -224.087776)
			(xy 99.336695 -224.070789) (xy 99.361498 -224.065592) (xy 99.384358 -224.061274) (xy 99.589082 -223.706436)
			(xy 99.581462 -223.684338) (xy 99.572831 -223.657991) (xy 99.56351 -223.603344) (xy 99.56292 -223.575626)
			(xy 99.563428 -223.549719) (xy 99.571534 -223.498542) (xy 99.587546 -223.449263) (xy 99.611069 -223.403096)
			(xy 99.641525 -223.361177) (xy 99.678163 -223.324539) (xy 99.720082 -223.294083) (xy 99.766249 -223.27056)
			(xy 99.815528 -223.254548) (xy 99.866705 -223.246442) (xy 99.918519 -223.246442) (xy 99.969696 -223.254548)
			(xy 100.018975 -223.27056) (xy 100.065142 -223.294083) (xy 100.107061 -223.324539) (xy 100.143699 -223.361177)
			(xy 100.174155 -223.403096) (xy 100.197678 -223.449263) (xy 100.21369 -223.498542) (xy 100.221796 -223.549719)
			(xy 100.222304 -223.575626) (xy 100.221887 -223.600992) (xy 100.214134 -223.651127) (xy 100.198785 -223.69948)
			(xy 100.176203 -223.744908) (xy 100.146922 -223.786336) (xy 100.111634 -223.822783) (xy 100.071175 -223.853388)
			(xy 100.026501 -223.877427) (xy 99.978669 -223.894332) (xy 99.953826 -223.899476) (xy 99.930966 -223.903794)
			(xy 99.726242 -224.258632) (xy 99.734116 -224.280476) (xy 99.74269 -224.306896) (xy 99.75189 -224.36167)
			(xy 99.752404 -224.389442) (xy 100.033328 -224.389442) (xy 100.033836 -224.363555) (xy 100.041935 -224.312417)
			(xy 100.057934 -224.263177) (xy 100.08144 -224.217045) (xy 100.111872 -224.175158) (xy 100.148482 -224.138548)
			(xy 100.190369 -224.108116) (xy 100.236501 -224.08461) (xy 100.285741 -224.068611) (xy 100.336879 -224.060512)
			(xy 100.388653 -224.060512) (xy 100.439791 -224.068611) (xy 100.489031 -224.08461) (xy 100.535163 -224.108116)
			(xy 100.57705 -224.138548) (xy 100.61366 -224.175158) (xy 100.644092 -224.217045) (xy 100.667598 -224.263177)
			(xy 100.683597 -224.312417) (xy 100.691696 -224.363555) (xy 100.692204 -224.389442) (xy 100.973128 -224.389442)
			(xy 100.973535 -224.364105) (xy 100.981297 -224.314028) (xy 100.996629 -224.265728) (xy 101.01917 -224.220343)
			(xy 101.048389 -224.17894) (xy 101.083599 -224.142496) (xy 101.12397 -224.111867) (xy 101.168552 -224.087776)
			(xy 101.216295 -224.070789) (xy 101.241098 -224.065592) (xy 101.263958 -224.061274) (xy 101.468682 -223.706436)
			(xy 101.461062 -223.684338) (xy 101.452431 -223.657991) (xy 101.44311 -223.603344) (xy 101.44252 -223.575626)
			(xy 101.443028 -223.549719) (xy 101.451134 -223.498542) (xy 101.467146 -223.449263) (xy 101.490669 -223.403096)
			(xy 101.521125 -223.361177) (xy 101.557763 -223.324539) (xy 101.599682 -223.294083) (xy 101.645849 -223.27056)
			(xy 101.695128 -223.254548) (xy 101.746305 -223.246442) (xy 101.798119 -223.246442) (xy 101.849296 -223.254548)
			(xy 101.898575 -223.27056) (xy 101.944742 -223.294083) (xy 101.986661 -223.324539) (xy 102.023299 -223.361177)
			(xy 102.053755 -223.403096) (xy 102.077278 -223.449263) (xy 102.09329 -223.498542) (xy 102.101396 -223.549719)
			(xy 102.101904 -223.575626) (xy 102.101487 -223.600992) (xy 102.093734 -223.651127) (xy 102.078385 -223.69948)
			(xy 102.055803 -223.744908) (xy 102.026522 -223.786336) (xy 101.991234 -223.822783) (xy 101.950775 -223.853388)
			(xy 101.906101 -223.877427) (xy 101.858269 -223.894332) (xy 101.833426 -223.899476) (xy 101.810566 -223.903794)
			(xy 101.605842 -224.258632) (xy 101.613716 -224.280476) (xy 101.62229 -224.306896) (xy 101.63149 -224.36167)
			(xy 101.632004 -224.389442) (xy 101.912928 -224.389442) (xy 101.913436 -224.363555) (xy 101.921535 -224.312417)
			(xy 101.937534 -224.263177) (xy 101.96104 -224.217045) (xy 101.991472 -224.175158) (xy 102.028082 -224.138548)
			(xy 102.069969 -224.108116) (xy 102.116101 -224.08461) (xy 102.165341 -224.068611) (xy 102.216479 -224.060512)
			(xy 102.268253 -224.060512) (xy 102.319391 -224.068611) (xy 102.368631 -224.08461) (xy 102.414763 -224.108116)
			(xy 102.45665 -224.138548) (xy 102.49326 -224.175158) (xy 102.523692 -224.217045) (xy 102.547198 -224.263177)
			(xy 102.563197 -224.312417) (xy 102.571296 -224.363555) (xy 102.571804 -224.389442) (xy 102.852728 -224.389442)
			(xy 102.853135 -224.364105) (xy 102.860897 -224.314028) (xy 102.876229 -224.265728) (xy 102.89877 -224.220343)
			(xy 102.927989 -224.17894) (xy 102.963199 -224.142496) (xy 103.00357 -224.111867) (xy 103.048152 -224.087776)
			(xy 103.095895 -224.070789) (xy 103.120698 -224.065592) (xy 103.143558 -224.061274) (xy 103.348282 -223.706436)
			(xy 103.340662 -223.684338) (xy 103.332031 -223.657991) (xy 103.32271 -223.603344) (xy 103.32212 -223.575626)
			(xy 103.322628 -223.549719) (xy 103.330734 -223.498542) (xy 103.346746 -223.449263) (xy 103.370269 -223.403096)
			(xy 103.400725 -223.361177) (xy 103.437363 -223.324539) (xy 103.479282 -223.294083) (xy 103.525449 -223.27056)
			(xy 103.574728 -223.254548) (xy 103.625905 -223.246442) (xy 103.677719 -223.246442) (xy 103.728896 -223.254548)
			(xy 103.778175 -223.27056) (xy 103.824342 -223.294083) (xy 103.866261 -223.324539) (xy 103.902899 -223.361177)
			(xy 103.933355 -223.403096) (xy 103.956878 -223.449263) (xy 103.97289 -223.498542) (xy 103.980996 -223.549719)
			(xy 103.981504 -223.575626) (xy 103.981087 -223.600992) (xy 103.973334 -223.651127) (xy 103.957985 -223.69948)
			(xy 103.935403 -223.744908) (xy 103.906122 -223.786336) (xy 103.870834 -223.822783) (xy 103.830375 -223.853388)
			(xy 103.785701 -223.877427) (xy 103.737869 -223.894332) (xy 103.713026 -223.899476) (xy 103.690166 -223.903794)
			(xy 103.485442 -224.258632) (xy 103.493316 -224.280476) (xy 103.50189 -224.306896) (xy 103.51109 -224.36167)
			(xy 103.511604 -224.389442) (xy 103.792528 -224.389442) (xy 103.793036 -224.363555) (xy 103.801135 -224.312417)
			(xy 103.817134 -224.263177) (xy 103.84064 -224.217045) (xy 103.871072 -224.175158) (xy 103.907682 -224.138548)
			(xy 103.949569 -224.108116) (xy 103.995701 -224.08461) (xy 104.044941 -224.068611) (xy 104.096079 -224.060512)
			(xy 104.147853 -224.060512) (xy 104.198991 -224.068611) (xy 104.248231 -224.08461) (xy 104.294363 -224.108116)
			(xy 104.33625 -224.138548) (xy 104.37286 -224.175158) (xy 104.403292 -224.217045) (xy 104.426798 -224.263177)
			(xy 104.442797 -224.312417) (xy 104.450896 -224.363555) (xy 104.451404 -224.389442) (xy 104.732328 -224.389442)
			(xy 104.732735 -224.364105) (xy 104.740497 -224.314028) (xy 104.755829 -224.265728) (xy 104.77837 -224.220343)
			(xy 104.807589 -224.17894) (xy 104.842799 -224.142496) (xy 104.88317 -224.111867) (xy 104.927752 -224.087776)
			(xy 104.975495 -224.070789) (xy 105.000298 -224.065592) (xy 105.023158 -224.061274) (xy 105.227882 -223.706436)
			(xy 105.220262 -223.684338) (xy 105.211631 -223.657991) (xy 105.20231 -223.603344) (xy 105.20172 -223.575626)
			(xy 105.202228 -223.549719) (xy 105.210334 -223.498542) (xy 105.226346 -223.449263) (xy 105.249869 -223.403096)
			(xy 105.280325 -223.361177) (xy 105.316963 -223.324539) (xy 105.358882 -223.294083) (xy 105.405049 -223.27056)
			(xy 105.454328 -223.254548) (xy 105.505505 -223.246442) (xy 105.557319 -223.246442) (xy 105.608496 -223.254548)
			(xy 105.657775 -223.27056) (xy 105.703942 -223.294083) (xy 105.745861 -223.324539) (xy 105.782499 -223.361177)
			(xy 105.812955 -223.403096) (xy 105.836478 -223.449263) (xy 105.85249 -223.498542) (xy 105.860596 -223.549719)
			(xy 105.861104 -223.575626) (xy 105.860687 -223.600992) (xy 105.852934 -223.651127) (xy 105.837585 -223.69948)
			(xy 105.815003 -223.744908) (xy 105.785722 -223.786336) (xy 105.750434 -223.822783) (xy 105.709975 -223.853388)
			(xy 105.665301 -223.877427) (xy 105.617469 -223.894332) (xy 105.592626 -223.899476) (xy 105.569766 -223.903794)
			(xy 105.365042 -224.258632) (xy 105.372916 -224.280476) (xy 105.38149 -224.306896) (xy 105.39069 -224.36167)
			(xy 105.391204 -224.389442) (xy 105.672128 -224.389442) (xy 105.672636 -224.363555) (xy 105.680735 -224.312417)
			(xy 105.696734 -224.263177) (xy 105.72024 -224.217045) (xy 105.750672 -224.175158) (xy 105.787282 -224.138548)
			(xy 105.829169 -224.108116) (xy 105.875301 -224.08461) (xy 105.924541 -224.068611) (xy 105.975679 -224.060512)
			(xy 106.027453 -224.060512) (xy 106.078591 -224.068611) (xy 106.127831 -224.08461) (xy 106.173963 -224.108116)
			(xy 106.21585 -224.138548) (xy 106.25246 -224.175158) (xy 106.282892 -224.217045) (xy 106.306398 -224.263177)
			(xy 106.322397 -224.312417) (xy 106.330496 -224.363555) (xy 106.331004 -224.389442) (xy 106.611928 -224.389442)
			(xy 106.612335 -224.364105) (xy 106.620097 -224.314028) (xy 106.635429 -224.265728) (xy 106.65797 -224.220343)
			(xy 106.687189 -224.17894) (xy 106.722399 -224.142496) (xy 106.76277 -224.111867) (xy 106.807352 -224.087776)
			(xy 106.855095 -224.070789) (xy 106.879898 -224.065592) (xy 106.902758 -224.061274) (xy 107.107482 -223.706436)
			(xy 107.099862 -223.684338) (xy 107.091231 -223.657991) (xy 107.08191 -223.603344) (xy 107.08132 -223.575626)
			(xy 107.081828 -223.549719) (xy 107.089934 -223.498542) (xy 107.105946 -223.449263) (xy 107.129469 -223.403096)
			(xy 107.159925 -223.361177) (xy 107.196563 -223.324539) (xy 107.238482 -223.294083) (xy 107.284649 -223.27056)
			(xy 107.333928 -223.254548) (xy 107.385105 -223.246442) (xy 107.436919 -223.246442) (xy 107.488096 -223.254548)
			(xy 107.537375 -223.27056) (xy 107.583542 -223.294083) (xy 107.625461 -223.324539) (xy 107.662099 -223.361177)
			(xy 107.692555 -223.403096) (xy 107.716078 -223.449263) (xy 107.73209 -223.498542) (xy 107.740196 -223.549719)
			(xy 107.740704 -223.575626) (xy 107.740287 -223.600992) (xy 107.732534 -223.651127) (xy 107.717185 -223.69948)
			(xy 107.694603 -223.744908) (xy 107.665322 -223.786336) (xy 107.630034 -223.822783) (xy 107.589575 -223.853388)
			(xy 107.544901 -223.877427) (xy 107.497069 -223.894332) (xy 107.472226 -223.899476) (xy 107.449366 -223.903794)
			(xy 107.244642 -224.258632) (xy 107.252516 -224.280476) (xy 107.26109 -224.306896) (xy 107.27029 -224.36167)
			(xy 107.270804 -224.389442) (xy 107.551728 -224.389442) (xy 107.552236 -224.363555) (xy 107.560335 -224.312417)
			(xy 107.576334 -224.263177) (xy 107.59984 -224.217045) (xy 107.630272 -224.175158) (xy 107.666882 -224.138548)
			(xy 107.708769 -224.108116) (xy 107.754901 -224.08461) (xy 107.804141 -224.068611) (xy 107.855279 -224.060512)
			(xy 107.907053 -224.060512) (xy 107.958191 -224.068611) (xy 108.007431 -224.08461) (xy 108.053563 -224.108116)
			(xy 108.09545 -224.138548) (xy 108.13206 -224.175158) (xy 108.162492 -224.217045) (xy 108.185998 -224.263177)
			(xy 108.201997 -224.312417) (xy 108.210096 -224.363555) (xy 108.210604 -224.389442) (xy 108.491528 -224.389442)
			(xy 108.491935 -224.364105) (xy 108.499697 -224.314028) (xy 108.515029 -224.265728) (xy 108.53757 -224.220343)
			(xy 108.566789 -224.17894) (xy 108.601999 -224.142496) (xy 108.64237 -224.111867) (xy 108.686952 -224.087776)
			(xy 108.734695 -224.070789) (xy 108.759498 -224.065592) (xy 108.782358 -224.061274) (xy 108.987082 -223.706436)
			(xy 108.979462 -223.684338) (xy 108.970831 -223.657991) (xy 108.96151 -223.603344) (xy 108.96092 -223.575626)
			(xy 108.961428 -223.549719) (xy 108.969534 -223.498542) (xy 108.985546 -223.449263) (xy 109.009069 -223.403096)
			(xy 109.039525 -223.361177) (xy 109.076163 -223.324539) (xy 109.118082 -223.294083) (xy 109.164249 -223.27056)
			(xy 109.213528 -223.254548) (xy 109.264705 -223.246442) (xy 109.316519 -223.246442) (xy 109.367696 -223.254548)
			(xy 109.416975 -223.27056) (xy 109.463142 -223.294083) (xy 109.505061 -223.324539) (xy 109.541699 -223.361177)
			(xy 109.572155 -223.403096) (xy 109.595678 -223.449263) (xy 109.61169 -223.498542) (xy 109.619796 -223.549719)
			(xy 109.620304 -223.575626) (xy 109.619887 -223.600992) (xy 109.612134 -223.651127) (xy 109.596785 -223.69948)
			(xy 109.574203 -223.744908) (xy 109.544922 -223.786336) (xy 109.509634 -223.822783) (xy 109.469175 -223.853388)
			(xy 109.424501 -223.877427) (xy 109.376669 -223.894332) (xy 109.351826 -223.899476) (xy 109.328966 -223.903794)
			(xy 109.124242 -224.258632) (xy 109.132116 -224.280476) (xy 109.14069 -224.306896) (xy 109.14989 -224.36167)
			(xy 109.150404 -224.389442) (xy 109.431328 -224.389442) (xy 109.431836 -224.363555) (xy 109.439935 -224.312417)
			(xy 109.455934 -224.263177) (xy 109.47944 -224.217045) (xy 109.509872 -224.175158) (xy 109.546482 -224.138548)
			(xy 109.588369 -224.108116) (xy 109.634501 -224.08461) (xy 109.683741 -224.068611) (xy 109.734879 -224.060512)
			(xy 109.786653 -224.060512) (xy 109.837791 -224.068611) (xy 109.887031 -224.08461) (xy 109.933163 -224.108116)
			(xy 109.97505 -224.138548) (xy 110.01166 -224.175158) (xy 110.042092 -224.217045) (xy 110.065598 -224.263177)
			(xy 110.081597 -224.312417) (xy 110.089696 -224.363555) (xy 110.090204 -224.389442) (xy 110.371128 -224.389442)
			(xy 110.371535 -224.364105) (xy 110.379297 -224.314028) (xy 110.394629 -224.265728) (xy 110.41717 -224.220343)
			(xy 110.446389 -224.17894) (xy 110.481599 -224.142496) (xy 110.52197 -224.111867) (xy 110.566552 -224.087776)
			(xy 110.614295 -224.070789) (xy 110.639098 -224.065592) (xy 110.661958 -224.061274) (xy 110.866682 -223.706436)
			(xy 110.859062 -223.684338) (xy 110.850431 -223.657991) (xy 110.84111 -223.603344) (xy 110.84052 -223.575626)
			(xy 110.841028 -223.549719) (xy 110.849134 -223.498542) (xy 110.865146 -223.449263) (xy 110.888669 -223.403096)
			(xy 110.919125 -223.361177) (xy 110.955763 -223.324539) (xy 110.997682 -223.294083) (xy 111.043849 -223.27056)
			(xy 111.093128 -223.254548) (xy 111.144305 -223.246442) (xy 111.196119 -223.246442) (xy 111.247296 -223.254548)
			(xy 111.296575 -223.27056) (xy 111.342742 -223.294083) (xy 111.384661 -223.324539) (xy 111.421299 -223.361177)
			(xy 111.451755 -223.403096) (xy 111.475278 -223.449263) (xy 111.49129 -223.498542) (xy 111.499396 -223.549719)
			(xy 111.499904 -223.575626) (xy 111.499487 -223.600992) (xy 111.491734 -223.651127) (xy 111.476385 -223.69948)
			(xy 111.453803 -223.744908) (xy 111.424522 -223.786336) (xy 111.389234 -223.822783) (xy 111.348775 -223.853388)
			(xy 111.304101 -223.877427) (xy 111.256269 -223.894332) (xy 111.231426 -223.899476) (xy 111.208566 -223.903794)
			(xy 111.003842 -224.258632) (xy 111.011716 -224.280476) (xy 111.02029 -224.306896) (xy 111.02949 -224.36167)
			(xy 111.030004 -224.389442) (xy 111.310928 -224.389442) (xy 111.311436 -224.363555) (xy 111.319535 -224.312417)
			(xy 111.335534 -224.263177) (xy 111.35904 -224.217045) (xy 111.389472 -224.175158) (xy 111.426082 -224.138548)
			(xy 111.467969 -224.108116) (xy 111.514101 -224.08461) (xy 111.563341 -224.068611) (xy 111.614479 -224.060512)
			(xy 111.666253 -224.060512) (xy 111.717391 -224.068611) (xy 111.766631 -224.08461) (xy 111.812763 -224.108116)
			(xy 111.85465 -224.138548) (xy 111.89126 -224.175158) (xy 111.921692 -224.217045) (xy 111.945198 -224.263177)
			(xy 111.961197 -224.312417) (xy 111.969296 -224.363555) (xy 111.969804 -224.389442) (xy 112.250728 -224.389442)
			(xy 112.251135 -224.364105) (xy 112.258897 -224.314028) (xy 112.274229 -224.265728) (xy 112.29677 -224.220343)
			(xy 112.325989 -224.17894) (xy 112.361199 -224.142496) (xy 112.40157 -224.111867) (xy 112.446152 -224.087776)
			(xy 112.493895 -224.070789) (xy 112.518698 -224.065592) (xy 112.541558 -224.061274) (xy 112.746282 -223.706436)
			(xy 112.738662 -223.684338) (xy 112.730031 -223.657991) (xy 112.72071 -223.603344) (xy 112.72012 -223.575626)
			(xy 112.720628 -223.549719) (xy 112.728734 -223.498542) (xy 112.744746 -223.449263) (xy 112.768269 -223.403096)
			(xy 112.798725 -223.361177) (xy 112.835363 -223.324539) (xy 112.877282 -223.294083) (xy 112.923449 -223.27056)
			(xy 112.972728 -223.254548) (xy 113.023905 -223.246442) (xy 113.075719 -223.246442) (xy 113.126896 -223.254548)
			(xy 113.176175 -223.27056) (xy 113.222342 -223.294083) (xy 113.264261 -223.324539) (xy 113.300899 -223.361177)
			(xy 113.331355 -223.403096) (xy 113.354878 -223.449263) (xy 113.37089 -223.498542) (xy 113.378996 -223.549719)
			(xy 113.379504 -223.575626) (xy 113.379087 -223.600992) (xy 113.371334 -223.651127) (xy 113.355985 -223.69948)
			(xy 113.333403 -223.744908) (xy 113.304122 -223.786336) (xy 113.268834 -223.822783) (xy 113.228375 -223.853388)
			(xy 113.183701 -223.877427) (xy 113.135869 -223.894332) (xy 113.111026 -223.899476) (xy 113.088166 -223.903794)
			(xy 112.883442 -224.258632) (xy 112.891316 -224.280476) (xy 112.89989 -224.306896) (xy 112.90909 -224.36167)
			(xy 112.909604 -224.389442) (xy 113.190528 -224.389442) (xy 113.191036 -224.363555) (xy 113.199135 -224.312417)
			(xy 113.215134 -224.263177) (xy 113.23864 -224.217045) (xy 113.269072 -224.175158) (xy 113.305682 -224.138548)
			(xy 113.347569 -224.108116) (xy 113.393701 -224.08461) (xy 113.442941 -224.068611) (xy 113.494079 -224.060512)
			(xy 113.545853 -224.060512) (xy 113.596991 -224.068611) (xy 113.646231 -224.08461) (xy 113.692363 -224.108116)
			(xy 113.73425 -224.138548) (xy 113.77086 -224.175158) (xy 113.801292 -224.217045) (xy 113.824798 -224.263177)
			(xy 113.840797 -224.312417) (xy 113.848896 -224.363555) (xy 113.849404 -224.389442) (xy 114.130328 -224.389442)
			(xy 114.130735 -224.364105) (xy 114.138497 -224.314028) (xy 114.153829 -224.265728) (xy 114.17637 -224.220343)
			(xy 114.205589 -224.17894) (xy 114.240799 -224.142496) (xy 114.28117 -224.111867) (xy 114.325752 -224.087776)
			(xy 114.373495 -224.070789) (xy 114.398298 -224.065592) (xy 114.421158 -224.061274) (xy 114.626136 -223.706182)
			(xy 114.618516 -223.684084) (xy 114.609997 -223.657912) (xy 114.600803 -223.603651) (xy 114.600228 -223.576134)
			(xy 114.600228 -223.575626) (xy 114.600736 -223.549739) (xy 114.608835 -223.498601) (xy 114.624834 -223.449361)
			(xy 114.64834 -223.403229) (xy 114.678772 -223.361342) (xy 114.715382 -223.324732) (xy 114.757269 -223.2943)
			(xy 114.803401 -223.270794) (xy 114.852641 -223.254795) (xy 114.903779 -223.246696) (xy 114.955553 -223.246696)
			(xy 115.006691 -223.254795) (xy 115.055931 -223.270794) (xy 115.102063 -223.2943) (xy 115.14395 -223.324732)
			(xy 115.18056 -223.361342) (xy 115.210992 -223.403229) (xy 115.234498 -223.449361) (xy 115.250497 -223.498601)
			(xy 115.258596 -223.549739) (xy 115.259104 -223.575626) (xy 115.258687 -223.600992) (xy 115.250934 -223.651127)
			(xy 115.235585 -223.69948) (xy 115.213003 -223.744908) (xy 115.183722 -223.786336) (xy 115.148434 -223.822783)
			(xy 115.107975 -223.853388) (xy 115.063301 -223.877427) (xy 115.015469 -223.894332) (xy 114.990626 -223.899476)
			(xy 114.967766 -223.903794) (xy 114.763042 -224.258632) (xy 114.770916 -224.280476) (xy 114.77949 -224.306896)
			(xy 114.78869 -224.36167) (xy 114.789204 -224.389442) (xy 115.070128 -224.389442) (xy 115.070636 -224.363555)
			(xy 115.078735 -224.312417) (xy 115.094734 -224.263177) (xy 115.11824 -224.217045) (xy 115.148672 -224.175158)
			(xy 115.185282 -224.138548) (xy 115.227169 -224.108116) (xy 115.273301 -224.08461) (xy 115.322541 -224.068611)
			(xy 115.373679 -224.060512) (xy 115.425453 -224.060512) (xy 115.476591 -224.068611) (xy 115.525831 -224.08461)
			(xy 115.571963 -224.108116) (xy 115.61385 -224.138548) (xy 115.65046 -224.175158) (xy 115.680892 -224.217045)
			(xy 115.704398 -224.263177) (xy 115.720397 -224.312417) (xy 115.728496 -224.363555) (xy 115.729004 -224.389442)
			(xy 116.009928 -224.389442) (xy 116.010335 -224.364105) (xy 116.018097 -224.314028) (xy 116.033429 -224.265728)
			(xy 116.05597 -224.220343) (xy 116.085189 -224.17894) (xy 116.120399 -224.142496) (xy 116.16077 -224.111867)
			(xy 116.205352 -224.087776) (xy 116.253095 -224.070789) (xy 116.277898 -224.065592) (xy 116.300758 -224.061274)
			(xy 116.505482 -223.706436) (xy 116.497862 -223.684338) (xy 116.489231 -223.657991) (xy 116.47991 -223.603344)
			(xy 116.47932 -223.575626) (xy 116.479828 -223.549719) (xy 116.487934 -223.498542) (xy 116.503946 -223.449263)
			(xy 116.527469 -223.403096) (xy 116.557925 -223.361177) (xy 116.594563 -223.324539) (xy 116.636482 -223.294083)
			(xy 116.682649 -223.27056) (xy 116.731928 -223.254548) (xy 116.783105 -223.246442) (xy 116.834919 -223.246442)
			(xy 116.886096 -223.254548) (xy 116.935375 -223.27056) (xy 116.981542 -223.294083) (xy 117.023461 -223.324539)
			(xy 117.060099 -223.361177) (xy 117.090555 -223.403096) (xy 117.114078 -223.449263) (xy 117.13009 -223.498542)
			(xy 117.138196 -223.549719) (xy 117.138704 -223.575626) (xy 117.138287 -223.600992) (xy 117.130534 -223.651127)
			(xy 117.115185 -223.69948) (xy 117.092603 -223.744908) (xy 117.063322 -223.786336) (xy 117.028034 -223.822783)
			(xy 116.987575 -223.853388) (xy 116.942901 -223.877427) (xy 116.895069 -223.894332) (xy 116.870226 -223.899476)
			(xy 116.847366 -223.903794) (xy 116.642642 -224.258632) (xy 116.650516 -224.280476) (xy 116.65909 -224.306896)
			(xy 116.66829 -224.36167) (xy 116.668804 -224.389442) (xy 116.949728 -224.389442) (xy 116.950236 -224.363555)
			(xy 116.958335 -224.312417) (xy 116.974334 -224.263177) (xy 116.99784 -224.217045) (xy 117.028272 -224.175158)
			(xy 117.064882 -224.138548) (xy 117.106769 -224.108116) (xy 117.152901 -224.08461) (xy 117.202141 -224.068611)
			(xy 117.253279 -224.060512) (xy 117.305053 -224.060512) (xy 117.356191 -224.068611) (xy 117.405431 -224.08461)
			(xy 117.451563 -224.108116) (xy 117.49345 -224.138548) (xy 117.53006 -224.175158) (xy 117.560492 -224.217045)
			(xy 117.583998 -224.263177) (xy 117.599997 -224.312417) (xy 117.608096 -224.363555) (xy 117.608604 -224.389442)
			(xy 117.889528 -224.389442) (xy 117.889935 -224.364105) (xy 117.897697 -224.314028) (xy 117.913029 -224.265728)
			(xy 117.93557 -224.220343) (xy 117.964789 -224.17894) (xy 117.999999 -224.142496) (xy 118.04037 -224.111867)
			(xy 118.084952 -224.087776) (xy 118.132695 -224.070789) (xy 118.157498 -224.065592) (xy 118.180358 -224.061274)
			(xy 118.385082 -223.706436) (xy 118.377462 -223.684338) (xy 118.368831 -223.657991) (xy 118.35951 -223.603344)
			(xy 118.35892 -223.575626) (xy 118.359428 -223.549719) (xy 118.367534 -223.498542) (xy 118.383546 -223.449263)
			(xy 118.407069 -223.403096) (xy 118.437525 -223.361177) (xy 118.474163 -223.324539) (xy 118.516082 -223.294083)
			(xy 118.562249 -223.27056) (xy 118.611528 -223.254548) (xy 118.662705 -223.246442) (xy 118.714519 -223.246442)
			(xy 118.765696 -223.254548) (xy 118.814975 -223.27056) (xy 118.861142 -223.294083) (xy 118.903061 -223.324539)
			(xy 118.939699 -223.361177) (xy 118.970155 -223.403096) (xy 118.993678 -223.449263) (xy 119.00969 -223.498542)
			(xy 119.017796 -223.549719) (xy 119.018304 -223.575626) (xy 119.017887 -223.600992) (xy 119.010134 -223.651127)
			(xy 118.994785 -223.69948) (xy 118.972203 -223.744908) (xy 118.942922 -223.786336) (xy 118.907634 -223.822783)
			(xy 118.867175 -223.853388) (xy 118.822501 -223.877427) (xy 118.774669 -223.894332) (xy 118.749826 -223.899476)
			(xy 118.726966 -223.903794) (xy 118.522242 -224.258632) (xy 118.530116 -224.280476) (xy 118.53869 -224.306896)
			(xy 118.54789 -224.36167) (xy 118.548404 -224.389442) (xy 118.829328 -224.389442) (xy 118.829836 -224.363555)
			(xy 118.837935 -224.312417) (xy 118.853934 -224.263177) (xy 118.87744 -224.217045) (xy 118.907872 -224.175158)
			(xy 118.944482 -224.138548) (xy 118.986369 -224.108116) (xy 119.032501 -224.08461) (xy 119.081741 -224.068611)
			(xy 119.132879 -224.060512) (xy 119.184653 -224.060512) (xy 119.235791 -224.068611) (xy 119.285031 -224.08461)
			(xy 119.331163 -224.108116) (xy 119.37305 -224.138548) (xy 119.40966 -224.175158) (xy 119.440092 -224.217045)
			(xy 119.463598 -224.263177) (xy 119.479597 -224.312417) (xy 119.487696 -224.363555) (xy 119.488204 -224.389442)
			(xy 119.769128 -224.389442) (xy 119.769535 -224.364105) (xy 119.777297 -224.314028) (xy 119.792629 -224.265728)
			(xy 119.81517 -224.220343) (xy 119.844389 -224.17894) (xy 119.879599 -224.142496) (xy 119.91997 -224.111867)
			(xy 119.964552 -224.087776) (xy 120.012295 -224.070789) (xy 120.037098 -224.065592) (xy 120.059958 -224.061274)
			(xy 120.264682 -223.706436) (xy 120.257062 -223.684338) (xy 120.248431 -223.657991) (xy 120.23911 -223.603344)
			(xy 120.23852 -223.575626) (xy 120.239028 -223.549719) (xy 120.247134 -223.498542) (xy 120.263146 -223.449263)
			(xy 120.286669 -223.403096) (xy 120.317125 -223.361177) (xy 120.353763 -223.324539) (xy 120.395682 -223.294083)
			(xy 120.441849 -223.27056) (xy 120.491128 -223.254548) (xy 120.542305 -223.246442) (xy 120.594119 -223.246442)
			(xy 120.645296 -223.254548) (xy 120.694575 -223.27056) (xy 120.740742 -223.294083) (xy 120.782661 -223.324539)
			(xy 120.819299 -223.361177) (xy 120.849755 -223.403096) (xy 120.873278 -223.449263) (xy 120.88929 -223.498542)
			(xy 120.897396 -223.549719) (xy 120.897904 -223.575626) (xy 120.897487 -223.600992) (xy 120.889734 -223.651127)
			(xy 120.874385 -223.69948) (xy 120.851803 -223.744908) (xy 120.822522 -223.786336) (xy 120.787234 -223.822783)
			(xy 120.746775 -223.853388) (xy 120.702101 -223.877427) (xy 120.654269 -223.894332) (xy 120.629426 -223.899476)
			(xy 120.606566 -223.903794) (xy 120.401842 -224.258632) (xy 120.409716 -224.280476) (xy 120.41829 -224.306896)
			(xy 120.42749 -224.36167) (xy 120.428004 -224.389442) (xy 120.708928 -224.389442) (xy 120.709436 -224.363555)
			(xy 120.717535 -224.312417) (xy 120.733534 -224.263177) (xy 120.75704 -224.217045) (xy 120.787472 -224.175158)
			(xy 120.824082 -224.138548) (xy 120.865969 -224.108116) (xy 120.912101 -224.08461) (xy 120.961341 -224.068611)
			(xy 121.012479 -224.060512) (xy 121.064253 -224.060512) (xy 121.115391 -224.068611) (xy 121.164631 -224.08461)
			(xy 121.210763 -224.108116) (xy 121.25265 -224.138548) (xy 121.28926 -224.175158) (xy 121.319692 -224.217045)
			(xy 121.343198 -224.263177) (xy 121.359197 -224.312417) (xy 121.367296 -224.363555) (xy 121.367804 -224.389442)
			(xy 121.648728 -224.389442) (xy 121.649135 -224.364105) (xy 121.656897 -224.314028) (xy 121.672229 -224.265728)
			(xy 121.69477 -224.220343) (xy 121.723989 -224.17894) (xy 121.759199 -224.142496) (xy 121.79957 -224.111867)
			(xy 121.844152 -224.087776) (xy 121.891895 -224.070789) (xy 121.916698 -224.065592) (xy 121.939558 -224.061274)
			(xy 122.144282 -223.706436) (xy 122.136662 -223.684338) (xy 122.128031 -223.657991) (xy 122.11871 -223.603344)
			(xy 122.11812 -223.575626) (xy 122.118628 -223.549719) (xy 122.126734 -223.498542) (xy 122.142746 -223.449263)
			(xy 122.166269 -223.403096) (xy 122.196725 -223.361177) (xy 122.233363 -223.324539) (xy 122.275282 -223.294083)
			(xy 122.321449 -223.27056) (xy 122.370728 -223.254548) (xy 122.421905 -223.246442) (xy 122.473719 -223.246442)
			(xy 122.524896 -223.254548) (xy 122.574175 -223.27056) (xy 122.620342 -223.294083) (xy 122.662261 -223.324539)
			(xy 122.698899 -223.361177) (xy 122.729355 -223.403096) (xy 122.752878 -223.449263) (xy 122.76889 -223.498542)
			(xy 122.776996 -223.549719) (xy 122.777504 -223.575626) (xy 122.777087 -223.600992) (xy 122.769334 -223.651127)
			(xy 122.753985 -223.69948) (xy 122.731403 -223.744908) (xy 122.702122 -223.786336) (xy 122.666834 -223.822783)
			(xy 122.626375 -223.853388) (xy 122.581701 -223.877427) (xy 122.533869 -223.894332) (xy 122.509026 -223.899476)
			(xy 122.486166 -223.903794) (xy 122.281442 -224.258632) (xy 122.289316 -224.280476) (xy 122.29789 -224.306896)
			(xy 122.30709 -224.36167) (xy 122.307604 -224.389442) (xy 122.588528 -224.389442) (xy 122.589036 -224.363555)
			(xy 122.597135 -224.312417) (xy 122.613134 -224.263177) (xy 122.63664 -224.217045) (xy 122.667072 -224.175158)
			(xy 122.703682 -224.138548) (xy 122.745569 -224.108116) (xy 122.791701 -224.08461) (xy 122.840941 -224.068611)
			(xy 122.892079 -224.060512) (xy 122.943853 -224.060512) (xy 122.994991 -224.068611) (xy 123.044231 -224.08461)
			(xy 123.090363 -224.108116) (xy 123.13225 -224.138548) (xy 123.16886 -224.175158) (xy 123.199292 -224.217045)
			(xy 123.222798 -224.263177) (xy 123.238797 -224.312417) (xy 123.246896 -224.363555) (xy 123.247404 -224.389442)
			(xy 123.528328 -224.389442) (xy 123.528735 -224.364105) (xy 123.536497 -224.314028) (xy 123.551829 -224.265728)
			(xy 123.57437 -224.220343) (xy 123.603589 -224.17894) (xy 123.638799 -224.142496) (xy 123.67917 -224.111867)
			(xy 123.723752 -224.087776) (xy 123.771495 -224.070789) (xy 123.796298 -224.065592) (xy 123.819158 -224.061274)
			(xy 124.023882 -223.706436) (xy 124.016262 -223.684338) (xy 124.007631 -223.657991) (xy 123.99831 -223.603344)
			(xy 123.99772 -223.575626) (xy 123.998228 -223.549719) (xy 124.006334 -223.498542) (xy 124.022346 -223.449263)
			(xy 124.045869 -223.403096) (xy 124.076325 -223.361177) (xy 124.112963 -223.324539) (xy 124.154882 -223.294083)
			(xy 124.201049 -223.27056) (xy 124.250328 -223.254548) (xy 124.301505 -223.246442) (xy 124.353319 -223.246442)
			(xy 124.404496 -223.254548) (xy 124.453775 -223.27056) (xy 124.499942 -223.294083) (xy 124.541861 -223.324539)
			(xy 124.578499 -223.361177) (xy 124.608955 -223.403096) (xy 124.632478 -223.449263) (xy 124.64849 -223.498542)
			(xy 124.656596 -223.549719) (xy 124.657104 -223.575626) (xy 124.656687 -223.600992) (xy 124.648934 -223.651127)
			(xy 124.633585 -223.69948) (xy 124.611003 -223.744908) (xy 124.581722 -223.786336) (xy 124.546434 -223.822783)
			(xy 124.505975 -223.853388) (xy 124.461301 -223.877427) (xy 124.413469 -223.894332) (xy 124.388626 -223.899476)
			(xy 124.365766 -223.903794) (xy 124.161042 -224.258632) (xy 124.168916 -224.280476) (xy 124.17749 -224.306896)
			(xy 124.18669 -224.36167) (xy 124.187204 -224.389442) (xy 124.468128 -224.389442) (xy 124.468636 -224.363555)
			(xy 124.476735 -224.312417) (xy 124.492734 -224.263177) (xy 124.51624 -224.217045) (xy 124.546672 -224.175158)
			(xy 124.583282 -224.138548) (xy 124.625169 -224.108116) (xy 124.671301 -224.08461) (xy 124.720541 -224.068611)
			(xy 124.771679 -224.060512) (xy 124.823453 -224.060512) (xy 124.874591 -224.068611) (xy 124.923831 -224.08461)
			(xy 124.969963 -224.108116) (xy 125.01185 -224.138548) (xy 125.04846 -224.175158) (xy 125.078892 -224.217045)
			(xy 125.102398 -224.263177) (xy 125.118397 -224.312417) (xy 125.126496 -224.363555) (xy 125.127004 -224.389442)
			(xy 125.407928 -224.389442) (xy 125.408335 -224.364105) (xy 125.416097 -224.314028) (xy 125.431429 -224.265728)
			(xy 125.45397 -224.220343) (xy 125.483189 -224.17894) (xy 125.518399 -224.142496) (xy 125.55877 -224.111867)
			(xy 125.603352 -224.087776) (xy 125.651095 -224.070789) (xy 125.675898 -224.065592) (xy 125.698758 -224.061274)
			(xy 125.903482 -223.706436) (xy 125.895862 -223.684338) (xy 125.887231 -223.657991) (xy 125.87791 -223.603344)
			(xy 125.87732 -223.575626) (xy 125.877828 -223.549719) (xy 125.885934 -223.498542) (xy 125.901946 -223.449263)
			(xy 125.925469 -223.403096) (xy 125.955925 -223.361177) (xy 125.992563 -223.324539) (xy 126.034482 -223.294083)
			(xy 126.080649 -223.27056) (xy 126.129928 -223.254548) (xy 126.181105 -223.246442) (xy 126.232919 -223.246442)
			(xy 126.284096 -223.254548) (xy 126.333375 -223.27056) (xy 126.379542 -223.294083) (xy 126.421461 -223.324539)
			(xy 126.458099 -223.361177) (xy 126.488555 -223.403096) (xy 126.512078 -223.449263) (xy 126.52809 -223.498542)
			(xy 126.536196 -223.549719) (xy 126.536704 -223.575626) (xy 126.536287 -223.600992) (xy 126.528534 -223.651127)
			(xy 126.513185 -223.69948) (xy 126.490603 -223.744908) (xy 126.461322 -223.786336) (xy 126.426034 -223.822783)
			(xy 126.385575 -223.853388) (xy 126.340901 -223.877427) (xy 126.293069 -223.894332) (xy 126.268226 -223.899476)
			(xy 126.245366 -223.903794) (xy 126.040642 -224.258632) (xy 126.048516 -224.280476) (xy 126.05709 -224.306896)
			(xy 126.06629 -224.36167) (xy 126.066804 -224.389442) (xy 126.347728 -224.389442) (xy 126.348236 -224.363555)
			(xy 126.356335 -224.312417) (xy 126.372334 -224.263177) (xy 126.39584 -224.217045) (xy 126.426272 -224.175158)
			(xy 126.462882 -224.138548) (xy 126.504769 -224.108116) (xy 126.550901 -224.08461) (xy 126.600141 -224.068611)
			(xy 126.651279 -224.060512) (xy 126.703053 -224.060512) (xy 126.754191 -224.068611) (xy 126.803431 -224.08461)
			(xy 126.849563 -224.108116) (xy 126.89145 -224.138548) (xy 126.92806 -224.175158) (xy 126.958492 -224.217045)
			(xy 126.981998 -224.263177) (xy 126.997997 -224.312417) (xy 127.006096 -224.363555) (xy 127.006604 -224.389442)
			(xy 127.287528 -224.389442) (xy 127.287935 -224.364105) (xy 127.295697 -224.314028) (xy 127.311029 -224.265728)
			(xy 127.33357 -224.220343) (xy 127.362789 -224.17894) (xy 127.397999 -224.142496) (xy 127.43837 -224.111867)
			(xy 127.482952 -224.087776) (xy 127.530695 -224.070789) (xy 127.555498 -224.065592) (xy 127.578358 -224.061274)
			(xy 127.783082 -223.706436) (xy 127.775462 -223.684338) (xy 127.766831 -223.657991) (xy 127.75751 -223.603344)
			(xy 127.75692 -223.575626) (xy 127.757428 -223.549719) (xy 127.765534 -223.498542) (xy 127.781546 -223.449263)
			(xy 127.805069 -223.403096) (xy 127.835525 -223.361177) (xy 127.872163 -223.324539) (xy 127.914082 -223.294083)
			(xy 127.960249 -223.27056) (xy 128.009528 -223.254548) (xy 128.060705 -223.246442) (xy 128.112519 -223.246442)
			(xy 128.163696 -223.254548) (xy 128.212975 -223.27056) (xy 128.259142 -223.294083) (xy 128.301061 -223.324539)
			(xy 128.337699 -223.361177) (xy 128.368155 -223.403096) (xy 128.391678 -223.449263) (xy 128.40769 -223.498542)
			(xy 128.415796 -223.549719) (xy 128.416304 -223.575626) (xy 128.415887 -223.600992) (xy 128.408134 -223.651127)
			(xy 128.392785 -223.69948) (xy 128.370203 -223.744908) (xy 128.340922 -223.786336) (xy 128.305634 -223.822783)
			(xy 128.265175 -223.853388) (xy 128.220501 -223.877427) (xy 128.172669 -223.894332) (xy 128.147826 -223.899476)
			(xy 128.124966 -223.903794) (xy 127.920242 -224.258632) (xy 127.928116 -224.280476) (xy 127.93669 -224.306896)
			(xy 127.94589 -224.36167) (xy 127.946404 -224.389442) (xy 128.227328 -224.389442) (xy 128.227836 -224.363555)
			(xy 128.235935 -224.312417) (xy 128.251934 -224.263177) (xy 128.27544 -224.217045) (xy 128.305872 -224.175158)
			(xy 128.342482 -224.138548) (xy 128.384369 -224.108116) (xy 128.430501 -224.08461) (xy 128.479741 -224.068611)
			(xy 128.530879 -224.060512) (xy 128.582653 -224.060512) (xy 128.633791 -224.068611) (xy 128.683031 -224.08461)
			(xy 128.729163 -224.108116) (xy 128.77105 -224.138548) (xy 128.80766 -224.175158) (xy 128.838092 -224.217045)
			(xy 128.861598 -224.263177) (xy 128.877597 -224.312417) (xy 128.885696 -224.363555) (xy 128.886204 -224.389442)
			(xy 129.167128 -224.389442) (xy 129.167535 -224.364105) (xy 129.175297 -224.314028) (xy 129.190629 -224.265728)
			(xy 129.21317 -224.220343) (xy 129.242389 -224.17894) (xy 129.277599 -224.142496) (xy 129.31797 -224.111867)
			(xy 129.362552 -224.087776) (xy 129.410295 -224.070789) (xy 129.435098 -224.065592) (xy 129.457958 -224.061274)
			(xy 129.662682 -223.706436) (xy 129.655062 -223.684338) (xy 129.646431 -223.657991) (xy 129.63711 -223.603344)
			(xy 129.63652 -223.575626) (xy 129.637028 -223.549719) (xy 129.645134 -223.498542) (xy 129.661146 -223.449263)
			(xy 129.684669 -223.403096) (xy 129.715125 -223.361177) (xy 129.751763 -223.324539) (xy 129.793682 -223.294083)
			(xy 129.839849 -223.27056) (xy 129.889128 -223.254548) (xy 129.940305 -223.246442) (xy 129.992119 -223.246442)
			(xy 130.043296 -223.254548) (xy 130.092575 -223.27056) (xy 130.138742 -223.294083) (xy 130.180661 -223.324539)
			(xy 130.217299 -223.361177) (xy 130.247755 -223.403096) (xy 130.271278 -223.449263) (xy 130.28729 -223.498542)
			(xy 130.295396 -223.549719) (xy 130.295904 -223.575626) (xy 130.295487 -223.600992) (xy 130.287734 -223.651127)
			(xy 130.272385 -223.69948) (xy 130.249803 -223.744908) (xy 130.220522 -223.786336) (xy 130.185234 -223.822783)
			(xy 130.144775 -223.853388) (xy 130.100101 -223.877427) (xy 130.052269 -223.894332) (xy 130.027426 -223.899476)
			(xy 130.004566 -223.903794) (xy 129.799842 -224.258632) (xy 129.807716 -224.280476) (xy 129.81629 -224.306896)
			(xy 129.82549 -224.36167) (xy 129.826004 -224.389442) (xy 130.106928 -224.389442) (xy 130.107436 -224.363555)
			(xy 130.115535 -224.312417) (xy 130.131534 -224.263177) (xy 130.15504 -224.217045) (xy 130.185472 -224.175158)
			(xy 130.222082 -224.138548) (xy 130.263969 -224.108116) (xy 130.310101 -224.08461) (xy 130.359341 -224.068611)
			(xy 130.410479 -224.060512) (xy 130.462253 -224.060512) (xy 130.513391 -224.068611) (xy 130.562631 -224.08461)
			(xy 130.608763 -224.108116) (xy 130.65065 -224.138548) (xy 130.68726 -224.175158) (xy 130.717692 -224.217045)
			(xy 130.741198 -224.263177) (xy 130.757197 -224.312417) (xy 130.765296 -224.363555) (xy 130.765804 -224.389442)
			(xy 131.046728 -224.389442) (xy 131.047135 -224.364105) (xy 131.054897 -224.314028) (xy 131.070229 -224.265728)
			(xy 131.09277 -224.220343) (xy 131.121989 -224.17894) (xy 131.157199 -224.142496) (xy 131.19757 -224.111867)
			(xy 131.242152 -224.087776) (xy 131.289895 -224.070789) (xy 131.314698 -224.065592) (xy 131.337558 -224.061274)
			(xy 131.542282 -223.706182) (xy 131.534662 -223.684338) (xy 131.526017 -223.657995) (xy 131.516704 -223.603345)
			(xy 131.51612 -223.575626) (xy 131.516628 -223.549719) (xy 131.524734 -223.498542) (xy 131.540746 -223.449263)
			(xy 131.564269 -223.403096) (xy 131.594725 -223.361177) (xy 131.631363 -223.324539) (xy 131.673282 -223.294083)
			(xy 131.719449 -223.27056) (xy 131.768728 -223.254548) (xy 131.819905 -223.246442) (xy 131.871719 -223.246442)
			(xy 131.922896 -223.254548) (xy 131.972175 -223.27056) (xy 132.018342 -223.294083) (xy 132.060261 -223.324539)
			(xy 132.096899 -223.361177) (xy 132.127355 -223.403096) (xy 132.150878 -223.449263) (xy 132.16689 -223.498542)
			(xy 132.174996 -223.549719) (xy 132.175504 -223.575626) (xy 132.175003 -223.60097) (xy 132.167228 -223.651059)
			(xy 132.151879 -223.699368) (xy 132.12932 -223.74476) (xy 132.10008 -223.786165) (xy 132.064849 -223.822609)
			(xy 132.024457 -223.853232) (xy 131.979854 -223.877314) (xy 131.932092 -223.894288) (xy 131.90728 -223.899476)
			(xy 131.88442 -223.903794) (xy 131.679696 -224.258632) (xy 131.687316 -224.280476) (xy 131.695872 -224.306769)
			(xy 131.705065 -224.361289) (xy 131.705604 -224.388934) (xy 131.705604 -224.389442) (xy 131.986528 -224.389442)
			(xy 131.987036 -224.363555) (xy 131.995135 -224.312417) (xy 132.011134 -224.263177) (xy 132.03464 -224.217045)
			(xy 132.065072 -224.175158) (xy 132.101682 -224.138548) (xy 132.143569 -224.108116) (xy 132.189701 -224.08461)
			(xy 132.238941 -224.068611) (xy 132.290079 -224.060512) (xy 132.341853 -224.060512) (xy 132.392991 -224.068611)
			(xy 132.442231 -224.08461) (xy 132.488363 -224.108116) (xy 132.53025 -224.138548) (xy 132.56686 -224.175158)
			(xy 132.597292 -224.217045) (xy 132.620798 -224.263177) (xy 132.636797 -224.312417) (xy 132.644896 -224.363555)
			(xy 132.645404 -224.389442) (xy 132.926328 -224.389442) (xy 132.926735 -224.364105) (xy 132.934497 -224.314028)
			(xy 132.949829 -224.265728) (xy 132.97237 -224.220343) (xy 133.001589 -224.17894) (xy 133.036799 -224.142496)
			(xy 133.07717 -224.111867) (xy 133.121752 -224.087776) (xy 133.169495 -224.070789) (xy 133.194298 -224.065592)
			(xy 133.217158 -224.061274) (xy 133.422136 -223.705928) (xy 133.414516 -223.684084) (xy 133.405997 -223.657912)
			(xy 133.396803 -223.603651) (xy 133.396228 -223.576134) (xy 133.396228 -223.575626) (xy 133.396736 -223.549739)
			(xy 133.404835 -223.498601) (xy 133.420834 -223.449361) (xy 133.44434 -223.403229) (xy 133.474772 -223.361342)
			(xy 133.511382 -223.324732) (xy 133.553269 -223.2943) (xy 133.599401 -223.270794) (xy 133.648641 -223.254795)
			(xy 133.699779 -223.246696) (xy 133.751553 -223.246696) (xy 133.802691 -223.254795) (xy 133.851931 -223.270794)
			(xy 133.898063 -223.2943) (xy 133.93995 -223.324732) (xy 133.97656 -223.361342) (xy 134.006992 -223.403229)
			(xy 134.030498 -223.449361) (xy 134.046497 -223.498601) (xy 134.054596 -223.549739) (xy 134.055104 -223.575626)
			(xy 134.054603 -223.60097) (xy 134.046828 -223.651059) (xy 134.031479 -223.699368) (xy 134.00892 -223.74476)
			(xy 133.97968 -223.786165) (xy 133.944449 -223.822609) (xy 133.904057 -223.853232) (xy 133.859454 -223.877314)
			(xy 133.811692 -223.894288) (xy 133.78688 -223.899476) (xy 133.76402 -223.903794) (xy 133.559296 -224.258632)
			(xy 133.566916 -224.280476) (xy 133.575472 -224.306769) (xy 133.584665 -224.361289) (xy 133.585204 -224.388934)
			(xy 133.585204 -224.389442) (xy 133.866128 -224.389442) (xy 133.866636 -224.363555) (xy 133.874735 -224.312417)
			(xy 133.890734 -224.263177) (xy 133.91424 -224.217045) (xy 133.944672 -224.175158) (xy 133.981282 -224.138548)
			(xy 134.023169 -224.108116) (xy 134.069301 -224.08461) (xy 134.118541 -224.068611) (xy 134.169679 -224.060512)
			(xy 134.221453 -224.060512) (xy 134.272591 -224.068611) (xy 134.321831 -224.08461) (xy 134.367963 -224.108116)
			(xy 134.40985 -224.138548) (xy 134.44646 -224.175158) (xy 134.476892 -224.217045) (xy 134.500398 -224.263177)
			(xy 134.516397 -224.312417) (xy 134.524496 -224.363555) (xy 134.525004 -224.389442) (xy 337.635596 -224.389442)
			(xy 337.636029 -224.364106) (xy 337.64379 -224.314032) (xy 337.65912 -224.265734) (xy 337.681659 -224.22035)
			(xy 337.710875 -224.178949) (xy 337.746081 -224.142504) (xy 337.786448 -224.111874) (xy 337.831026 -224.087781)
			(xy 337.878765 -224.070791) (xy 337.903566 -224.065592) (xy 337.926426 -224.061274) (xy 338.13115 -223.706182)
			(xy 338.12353 -223.684338) (xy 338.114887 -223.657995) (xy 338.105572 -223.603345) (xy 338.104988 -223.575626)
			(xy 338.105496 -223.549719) (xy 338.113602 -223.498542) (xy 338.129614 -223.449263) (xy 338.153137 -223.403096)
			(xy 338.183593 -223.361177) (xy 338.220231 -223.324539) (xy 338.26215 -223.294083) (xy 338.308317 -223.27056)
			(xy 338.357596 -223.254548) (xy 338.408773 -223.246442) (xy 338.460587 -223.246442) (xy 338.511764 -223.254548)
			(xy 338.561043 -223.27056) (xy 338.60721 -223.294083) (xy 338.649129 -223.324539) (xy 338.685767 -223.361177)
			(xy 338.716223 -223.403096) (xy 338.739746 -223.449263) (xy 338.755758 -223.498542) (xy 338.763864 -223.549719)
			(xy 338.764372 -223.575626) (xy 338.763897 -223.600971) (xy 338.756121 -223.651063) (xy 338.740771 -223.699374)
			(xy 338.718208 -223.744767) (xy 338.688966 -223.786173) (xy 338.653731 -223.822617) (xy 338.613335 -223.853239)
			(xy 338.568728 -223.877319) (xy 338.520962 -223.89429) (xy 338.496148 -223.899476) (xy 338.473288 -223.903794)
			(xy 338.268564 -224.258632) (xy 338.276184 -224.280476) (xy 338.284739 -224.306769) (xy 338.293932 -224.361289)
			(xy 338.294472 -224.388934) (xy 338.294472 -224.389442) (xy 338.575396 -224.389442) (xy 338.575904 -224.363555)
			(xy 338.584003 -224.312417) (xy 338.600002 -224.263177) (xy 338.623508 -224.217045) (xy 338.65394 -224.175158)
			(xy 338.69055 -224.138548) (xy 338.732437 -224.108116) (xy 338.778569 -224.08461) (xy 338.827809 -224.068611)
			(xy 338.878947 -224.060512) (xy 338.930721 -224.060512) (xy 338.981859 -224.068611) (xy 339.031099 -224.08461)
			(xy 339.077231 -224.108116) (xy 339.119118 -224.138548) (xy 339.155728 -224.175158) (xy 339.18616 -224.217045)
			(xy 339.209666 -224.263177) (xy 339.225665 -224.312417) (xy 339.233764 -224.363555) (xy 339.234272 -224.389442)
			(xy 339.515196 -224.389442) (xy 339.515629 -224.364106) (xy 339.52339 -224.314032) (xy 339.53872 -224.265734)
			(xy 339.561259 -224.22035) (xy 339.590475 -224.178949) (xy 339.625681 -224.142504) (xy 339.666048 -224.111874)
			(xy 339.710626 -224.087781) (xy 339.758365 -224.070791) (xy 339.783166 -224.065592) (xy 339.806026 -224.061274)
			(xy 340.01075 -223.706182) (xy 340.00313 -223.684338) (xy 339.994487 -223.657995) (xy 339.985172 -223.603345)
			(xy 339.984588 -223.575626) (xy 339.985096 -223.549719) (xy 339.993202 -223.498542) (xy 340.009214 -223.449263)
			(xy 340.032737 -223.403096) (xy 340.063193 -223.361177) (xy 340.099831 -223.324539) (xy 340.14175 -223.294083)
			(xy 340.187917 -223.27056) (xy 340.237196 -223.254548) (xy 340.288373 -223.246442) (xy 340.340187 -223.246442)
			(xy 340.391364 -223.254548) (xy 340.440643 -223.27056) (xy 340.48681 -223.294083) (xy 340.528729 -223.324539)
			(xy 340.565367 -223.361177) (xy 340.595823 -223.403096) (xy 340.619346 -223.449263) (xy 340.635358 -223.498542)
			(xy 340.643464 -223.549719) (xy 340.643972 -223.575626) (xy 340.643497 -223.600971) (xy 340.635721 -223.651063)
			(xy 340.620371 -223.699374) (xy 340.597808 -223.744767) (xy 340.568566 -223.786173) (xy 340.533331 -223.822617)
			(xy 340.492935 -223.853239) (xy 340.448328 -223.877319) (xy 340.400562 -223.89429) (xy 340.375748 -223.899476)
			(xy 340.352888 -223.903794) (xy 340.148164 -224.258632) (xy 340.155784 -224.280476) (xy 340.164339 -224.306769)
			(xy 340.173532 -224.361289) (xy 340.174072 -224.388934) (xy 340.174072 -224.389442) (xy 340.454996 -224.389442)
			(xy 340.455504 -224.363555) (xy 340.463603 -224.312417) (xy 340.479602 -224.263177) (xy 340.503108 -224.217045)
			(xy 340.53354 -224.175158) (xy 340.57015 -224.138548) (xy 340.612037 -224.108116) (xy 340.658169 -224.08461)
			(xy 340.707409 -224.068611) (xy 340.758547 -224.060512) (xy 340.810321 -224.060512) (xy 340.861459 -224.068611)
			(xy 340.910699 -224.08461) (xy 340.956831 -224.108116) (xy 340.998718 -224.138548) (xy 341.035328 -224.175158)
			(xy 341.06576 -224.217045) (xy 341.089266 -224.263177) (xy 341.105265 -224.312417) (xy 341.113364 -224.363555)
			(xy 341.113872 -224.389442) (xy 341.394796 -224.389442) (xy 341.395229 -224.364106) (xy 341.40299 -224.314032)
			(xy 341.41832 -224.265734) (xy 341.440859 -224.22035) (xy 341.470075 -224.178949) (xy 341.505281 -224.142504)
			(xy 341.545648 -224.111874) (xy 341.590226 -224.087781) (xy 341.637965 -224.070791) (xy 341.662766 -224.065592)
			(xy 341.685626 -224.061274) (xy 341.89035 -223.706436) (xy 341.88273 -223.684338) (xy 341.874102 -223.657991)
			(xy 341.864779 -223.603344) (xy 341.864188 -223.575626) (xy 341.864696 -223.549719) (xy 341.872802 -223.498542)
			(xy 341.888814 -223.449263) (xy 341.912337 -223.403096) (xy 341.942793 -223.361177) (xy 341.979431 -223.324539)
			(xy 342.02135 -223.294083) (xy 342.067517 -223.27056) (xy 342.116796 -223.254548) (xy 342.167973 -223.246442)
			(xy 342.219787 -223.246442) (xy 342.270964 -223.254548) (xy 342.320243 -223.27056) (xy 342.36641 -223.294083)
			(xy 342.408329 -223.324539) (xy 342.444967 -223.361177) (xy 342.475423 -223.403096) (xy 342.498946 -223.449263)
			(xy 342.514958 -223.498542) (xy 342.523064 -223.549719) (xy 342.523572 -223.575626) (xy 342.523181 -223.600993)
			(xy 342.515428 -223.651131) (xy 342.500077 -223.699486) (xy 342.477492 -223.744915) (xy 342.448207 -223.786344)
			(xy 342.412916 -223.822791) (xy 342.372452 -223.853396) (xy 342.327774 -223.877433) (xy 342.279939 -223.894334)
			(xy 342.255094 -223.899476) (xy 342.232234 -223.903794) (xy 342.02751 -224.258632) (xy 342.035384 -224.280476)
			(xy 342.043957 -224.306897) (xy 342.053158 -224.36167) (xy 342.053672 -224.389442) (xy 342.334596 -224.389442)
			(xy 342.335104 -224.363555) (xy 342.343203 -224.312417) (xy 342.359202 -224.263177) (xy 342.382708 -224.217045)
			(xy 342.41314 -224.175158) (xy 342.44975 -224.138548) (xy 342.491637 -224.108116) (xy 342.537769 -224.08461)
			(xy 342.587009 -224.068611) (xy 342.638147 -224.060512) (xy 342.689921 -224.060512) (xy 342.741059 -224.068611)
			(xy 342.790299 -224.08461) (xy 342.836431 -224.108116) (xy 342.878318 -224.138548) (xy 342.914928 -224.175158)
			(xy 342.94536 -224.217045) (xy 342.968866 -224.263177) (xy 342.984865 -224.312417) (xy 342.992964 -224.363555)
			(xy 342.993472 -224.389442) (xy 343.274396 -224.389442) (xy 343.274829 -224.364106) (xy 343.28259 -224.314032)
			(xy 343.29792 -224.265734) (xy 343.320459 -224.22035) (xy 343.349675 -224.178949) (xy 343.384881 -224.142504)
			(xy 343.425248 -224.111874) (xy 343.469826 -224.087781) (xy 343.517565 -224.070791) (xy 343.542366 -224.065592)
			(xy 343.565226 -224.061274) (xy 343.76995 -223.706436) (xy 343.76233 -223.684338) (xy 343.753702 -223.657991)
			(xy 343.744379 -223.603344) (xy 343.743788 -223.575626) (xy 343.744296 -223.549719) (xy 343.752402 -223.498542)
			(xy 343.768414 -223.449263) (xy 343.791937 -223.403096) (xy 343.822393 -223.361177) (xy 343.859031 -223.324539)
			(xy 343.90095 -223.294083) (xy 343.947117 -223.27056) (xy 343.996396 -223.254548) (xy 344.047573 -223.246442)
			(xy 344.099387 -223.246442) (xy 344.150564 -223.254548) (xy 344.199843 -223.27056) (xy 344.24601 -223.294083)
			(xy 344.287929 -223.324539) (xy 344.324567 -223.361177) (xy 344.355023 -223.403096) (xy 344.378546 -223.449263)
			(xy 344.394558 -223.498542) (xy 344.402664 -223.549719) (xy 344.403172 -223.575626) (xy 344.402781 -223.600993)
			(xy 344.395028 -223.651131) (xy 344.379677 -223.699486) (xy 344.357092 -223.744915) (xy 344.327807 -223.786344)
			(xy 344.292516 -223.822791) (xy 344.252052 -223.853396) (xy 344.207374 -223.877433) (xy 344.159539 -223.894334)
			(xy 344.134694 -223.899476) (xy 344.111834 -223.903794) (xy 343.90711 -224.258632) (xy 343.914984 -224.280476)
			(xy 343.923557 -224.306897) (xy 343.932758 -224.36167) (xy 343.933272 -224.389442) (xy 344.214196 -224.389442)
			(xy 344.214704 -224.363555) (xy 344.222803 -224.312417) (xy 344.238802 -224.263177) (xy 344.262308 -224.217045)
			(xy 344.29274 -224.175158) (xy 344.32935 -224.138548) (xy 344.371237 -224.108116) (xy 344.417369 -224.08461)
			(xy 344.466609 -224.068611) (xy 344.517747 -224.060512) (xy 344.569521 -224.060512) (xy 344.620659 -224.068611)
			(xy 344.669899 -224.08461) (xy 344.716031 -224.108116) (xy 344.757918 -224.138548) (xy 344.794528 -224.175158)
			(xy 344.82496 -224.217045) (xy 344.848466 -224.263177) (xy 344.864465 -224.312417) (xy 344.872564 -224.363555)
			(xy 344.873072 -224.389442) (xy 345.153996 -224.389442) (xy 345.154429 -224.364106) (xy 345.16219 -224.314032)
			(xy 345.17752 -224.265734) (xy 345.200059 -224.22035) (xy 345.229275 -224.178949) (xy 345.264481 -224.142504)
			(xy 345.304848 -224.111874) (xy 345.349426 -224.087781) (xy 345.397165 -224.070791) (xy 345.421966 -224.065592)
			(xy 345.444826 -224.061274) (xy 345.64955 -223.706436) (xy 345.64193 -223.684338) (xy 345.633302 -223.657991)
			(xy 345.623979 -223.603344) (xy 345.623388 -223.575626) (xy 345.623896 -223.549719) (xy 345.632002 -223.498542)
			(xy 345.648014 -223.449263) (xy 345.671537 -223.403096) (xy 345.701993 -223.361177) (xy 345.738631 -223.324539)
			(xy 345.78055 -223.294083) (xy 345.826717 -223.27056) (xy 345.875996 -223.254548) (xy 345.927173 -223.246442)
			(xy 345.978987 -223.246442) (xy 346.030164 -223.254548) (xy 346.079443 -223.27056) (xy 346.12561 -223.294083)
			(xy 346.167529 -223.324539) (xy 346.204167 -223.361177) (xy 346.234623 -223.403096) (xy 346.258146 -223.449263)
			(xy 346.274158 -223.498542) (xy 346.282264 -223.549719) (xy 346.282772 -223.575626) (xy 346.282381 -223.600993)
			(xy 346.274628 -223.651131) (xy 346.259277 -223.699486) (xy 346.236692 -223.744915) (xy 346.207407 -223.786344)
			(xy 346.172116 -223.822791) (xy 346.131652 -223.853396) (xy 346.086974 -223.877433) (xy 346.039139 -223.894334)
			(xy 346.014294 -223.899476) (xy 345.991434 -223.903794) (xy 345.78671 -224.258632) (xy 345.794584 -224.280476)
			(xy 345.803157 -224.306897) (xy 345.812358 -224.36167) (xy 345.812872 -224.389442) (xy 346.093796 -224.389442)
			(xy 346.094304 -224.363555) (xy 346.102403 -224.312417) (xy 346.118402 -224.263177) (xy 346.141908 -224.217045)
			(xy 346.17234 -224.175158) (xy 346.20895 -224.138548) (xy 346.250837 -224.108116) (xy 346.296969 -224.08461)
			(xy 346.346209 -224.068611) (xy 346.397347 -224.060512) (xy 346.449121 -224.060512) (xy 346.500259 -224.068611)
			(xy 346.549499 -224.08461) (xy 346.595631 -224.108116) (xy 346.637518 -224.138548) (xy 346.674128 -224.175158)
			(xy 346.70456 -224.217045) (xy 346.728066 -224.263177) (xy 346.744065 -224.312417) (xy 346.752164 -224.363555)
			(xy 346.752672 -224.389442) (xy 347.033596 -224.389442) (xy 347.034029 -224.364106) (xy 347.04179 -224.314032)
			(xy 347.05712 -224.265734) (xy 347.079659 -224.22035) (xy 347.108875 -224.178949) (xy 347.144081 -224.142504)
			(xy 347.184448 -224.111874) (xy 347.229026 -224.087781) (xy 347.276765 -224.070791) (xy 347.301566 -224.065592)
			(xy 347.324426 -224.061274) (xy 347.52915 -223.706436) (xy 347.52153 -223.684338) (xy 347.512902 -223.657991)
			(xy 347.503579 -223.603344) (xy 347.502988 -223.575626) (xy 347.503496 -223.549719) (xy 347.511602 -223.498542)
			(xy 347.527614 -223.449263) (xy 347.551137 -223.403096) (xy 347.581593 -223.361177) (xy 347.618231 -223.324539)
			(xy 347.66015 -223.294083) (xy 347.706317 -223.27056) (xy 347.755596 -223.254548) (xy 347.806773 -223.246442)
			(xy 347.858587 -223.246442) (xy 347.909764 -223.254548) (xy 347.959043 -223.27056) (xy 348.00521 -223.294083)
			(xy 348.047129 -223.324539) (xy 348.083767 -223.361177) (xy 348.114223 -223.403096) (xy 348.137746 -223.449263)
			(xy 348.153758 -223.498542) (xy 348.161864 -223.549719) (xy 348.162372 -223.575626) (xy 348.161981 -223.600993)
			(xy 348.154228 -223.651131) (xy 348.138877 -223.699486) (xy 348.116292 -223.744915) (xy 348.087007 -223.786344)
			(xy 348.051716 -223.822791) (xy 348.011252 -223.853396) (xy 347.966574 -223.877433) (xy 347.918739 -223.894334)
			(xy 347.893894 -223.899476) (xy 347.871034 -223.903794) (xy 347.66631 -224.258632) (xy 347.674184 -224.280476)
			(xy 347.682757 -224.306897) (xy 347.691958 -224.36167) (xy 347.692472 -224.389442) (xy 347.973396 -224.389442)
			(xy 347.973904 -224.363555) (xy 347.982003 -224.312417) (xy 347.998002 -224.263177) (xy 348.021508 -224.217045)
			(xy 348.05194 -224.175158) (xy 348.08855 -224.138548) (xy 348.130437 -224.108116) (xy 348.176569 -224.08461)
			(xy 348.225809 -224.068611) (xy 348.276947 -224.060512) (xy 348.328721 -224.060512) (xy 348.379859 -224.068611)
			(xy 348.429099 -224.08461) (xy 348.475231 -224.108116) (xy 348.517118 -224.138548) (xy 348.553728 -224.175158)
			(xy 348.58416 -224.217045) (xy 348.607666 -224.263177) (xy 348.623665 -224.312417) (xy 348.631764 -224.363555)
			(xy 348.632272 -224.389442) (xy 348.913196 -224.389442) (xy 348.913629 -224.364106) (xy 348.92139 -224.314032)
			(xy 348.93672 -224.265734) (xy 348.959259 -224.22035) (xy 348.988475 -224.178949) (xy 349.023681 -224.142504)
			(xy 349.064048 -224.111874) (xy 349.108626 -224.087781) (xy 349.156365 -224.070791) (xy 349.181166 -224.065592)
			(xy 349.204026 -224.061274) (xy 349.40875 -223.706436) (xy 349.40113 -223.684338) (xy 349.392502 -223.657991)
			(xy 349.383179 -223.603344) (xy 349.382588 -223.575626) (xy 349.383096 -223.549719) (xy 349.391202 -223.498542)
			(xy 349.407214 -223.449263) (xy 349.430737 -223.403096) (xy 349.461193 -223.361177) (xy 349.497831 -223.324539)
			(xy 349.53975 -223.294083) (xy 349.585917 -223.27056) (xy 349.635196 -223.254548) (xy 349.686373 -223.246442)
			(xy 349.738187 -223.246442) (xy 349.789364 -223.254548) (xy 349.838643 -223.27056) (xy 349.88481 -223.294083)
			(xy 349.926729 -223.324539) (xy 349.963367 -223.361177) (xy 349.993823 -223.403096) (xy 350.017346 -223.449263)
			(xy 350.033358 -223.498542) (xy 350.041464 -223.549719) (xy 350.041972 -223.575626) (xy 350.041581 -223.600993)
			(xy 350.033828 -223.651131) (xy 350.018477 -223.699486) (xy 349.995892 -223.744915) (xy 349.966607 -223.786344)
			(xy 349.931316 -223.822791) (xy 349.890852 -223.853396) (xy 349.846174 -223.877433) (xy 349.798339 -223.894334)
			(xy 349.773494 -223.899476) (xy 349.750634 -223.903794) (xy 349.54591 -224.258632) (xy 349.553784 -224.280476)
			(xy 349.562357 -224.306897) (xy 349.571558 -224.36167) (xy 349.572072 -224.389442) (xy 349.852996 -224.389442)
			(xy 349.853504 -224.363555) (xy 349.861603 -224.312417) (xy 349.877602 -224.263177) (xy 349.901108 -224.217045)
			(xy 349.93154 -224.175158) (xy 349.96815 -224.138548) (xy 350.010037 -224.108116) (xy 350.056169 -224.08461)
			(xy 350.105409 -224.068611) (xy 350.156547 -224.060512) (xy 350.208321 -224.060512) (xy 350.259459 -224.068611)
			(xy 350.308699 -224.08461) (xy 350.354831 -224.108116) (xy 350.396718 -224.138548) (xy 350.433328 -224.175158)
			(xy 350.46376 -224.217045) (xy 350.487266 -224.263177) (xy 350.503265 -224.312417) (xy 350.511364 -224.363555)
			(xy 350.511872 -224.389442) (xy 350.792796 -224.389442) (xy 350.793229 -224.364106) (xy 350.80099 -224.314032)
			(xy 350.81632 -224.265734) (xy 350.838859 -224.22035) (xy 350.868075 -224.178949) (xy 350.903281 -224.142504)
			(xy 350.943648 -224.111874) (xy 350.988226 -224.087781) (xy 351.035965 -224.070791) (xy 351.060766 -224.065592)
			(xy 351.083626 -224.061274) (xy 351.28835 -223.706436) (xy 351.28073 -223.684338) (xy 351.272102 -223.657991)
			(xy 351.262779 -223.603344) (xy 351.262188 -223.575626) (xy 351.262696 -223.549719) (xy 351.270802 -223.498542)
			(xy 351.286814 -223.449263) (xy 351.310337 -223.403096) (xy 351.340793 -223.361177) (xy 351.377431 -223.324539)
			(xy 351.41935 -223.294083) (xy 351.465517 -223.27056) (xy 351.514796 -223.254548) (xy 351.565973 -223.246442)
			(xy 351.617787 -223.246442) (xy 351.668964 -223.254548) (xy 351.718243 -223.27056) (xy 351.76441 -223.294083)
			(xy 351.806329 -223.324539) (xy 351.842967 -223.361177) (xy 351.873423 -223.403096) (xy 351.896946 -223.449263)
			(xy 351.912958 -223.498542) (xy 351.921064 -223.549719) (xy 351.921572 -223.575626) (xy 351.921181 -223.600993)
			(xy 351.913428 -223.651131) (xy 351.898077 -223.699486) (xy 351.875492 -223.744915) (xy 351.846207 -223.786344)
			(xy 351.810916 -223.822791) (xy 351.770452 -223.853396) (xy 351.725774 -223.877433) (xy 351.677939 -223.894334)
			(xy 351.653094 -223.899476) (xy 351.630234 -223.903794) (xy 351.42551 -224.258632) (xy 351.433384 -224.280476)
			(xy 351.441957 -224.306897) (xy 351.451158 -224.36167) (xy 351.451672 -224.389442) (xy 351.732596 -224.389442)
			(xy 351.733104 -224.363555) (xy 351.741203 -224.312417) (xy 351.757202 -224.263177) (xy 351.780708 -224.217045)
			(xy 351.81114 -224.175158) (xy 351.84775 -224.138548) (xy 351.889637 -224.108116) (xy 351.935769 -224.08461)
			(xy 351.985009 -224.068611) (xy 352.036147 -224.060512) (xy 352.087921 -224.060512) (xy 352.139059 -224.068611)
			(xy 352.188299 -224.08461) (xy 352.234431 -224.108116) (xy 352.276318 -224.138548) (xy 352.312928 -224.175158)
			(xy 352.34336 -224.217045) (xy 352.366866 -224.263177) (xy 352.382865 -224.312417) (xy 352.390964 -224.363555)
			(xy 352.391472 -224.389442) (xy 352.672396 -224.389442) (xy 352.672829 -224.364106) (xy 352.68059 -224.314032)
			(xy 352.69592 -224.265734) (xy 352.718459 -224.22035) (xy 352.747675 -224.178949) (xy 352.782881 -224.142504)
			(xy 352.823248 -224.111874) (xy 352.867826 -224.087781) (xy 352.915565 -224.070791) (xy 352.940366 -224.065592)
			(xy 352.963226 -224.061274) (xy 353.16795 -223.706436) (xy 353.16033 -223.684338) (xy 353.151702 -223.657991)
			(xy 353.142379 -223.603344) (xy 353.141788 -223.575626) (xy 353.142296 -223.549719) (xy 353.150402 -223.498542)
			(xy 353.166414 -223.449263) (xy 353.189937 -223.403096) (xy 353.220393 -223.361177) (xy 353.257031 -223.324539)
			(xy 353.29895 -223.294083) (xy 353.345117 -223.27056) (xy 353.394396 -223.254548) (xy 353.445573 -223.246442)
			(xy 353.497387 -223.246442) (xy 353.548564 -223.254548) (xy 353.597843 -223.27056) (xy 353.64401 -223.294083)
			(xy 353.685929 -223.324539) (xy 353.722567 -223.361177) (xy 353.753023 -223.403096) (xy 353.776546 -223.449263)
			(xy 353.792558 -223.498542) (xy 353.800664 -223.549719) (xy 353.801172 -223.575626) (xy 353.800781 -223.600993)
			(xy 353.793028 -223.651131) (xy 353.777677 -223.699486) (xy 353.755092 -223.744915) (xy 353.725807 -223.786344)
			(xy 353.690516 -223.822791) (xy 353.650052 -223.853396) (xy 353.605374 -223.877433) (xy 353.557539 -223.894334)
			(xy 353.532694 -223.899476) (xy 353.509834 -223.903794) (xy 353.30511 -224.258632) (xy 353.312984 -224.280476)
			(xy 353.321557 -224.306897) (xy 353.330758 -224.36167) (xy 353.331272 -224.389442) (xy 353.612196 -224.389442)
			(xy 353.612704 -224.363555) (xy 353.620803 -224.312417) (xy 353.636802 -224.263177) (xy 353.660308 -224.217045)
			(xy 353.69074 -224.175158) (xy 353.72735 -224.138548) (xy 353.769237 -224.108116) (xy 353.815369 -224.08461)
			(xy 353.864609 -224.068611) (xy 353.915747 -224.060512) (xy 353.967521 -224.060512) (xy 354.018659 -224.068611)
			(xy 354.067899 -224.08461) (xy 354.114031 -224.108116) (xy 354.155918 -224.138548) (xy 354.192528 -224.175158)
			(xy 354.22296 -224.217045) (xy 354.246466 -224.263177) (xy 354.262465 -224.312417) (xy 354.270564 -224.363555)
			(xy 354.271072 -224.389442) (xy 354.551996 -224.389442) (xy 354.552429 -224.364106) (xy 354.56019 -224.314032)
			(xy 354.57552 -224.265734) (xy 354.598059 -224.22035) (xy 354.627275 -224.178949) (xy 354.662481 -224.142504)
			(xy 354.702848 -224.111874) (xy 354.747426 -224.087781) (xy 354.795165 -224.070791) (xy 354.819966 -224.065592)
			(xy 354.842826 -224.061274) (xy 355.04755 -223.706436) (xy 355.03993 -223.684338) (xy 355.031302 -223.657991)
			(xy 355.021979 -223.603344) (xy 355.021388 -223.575626) (xy 355.021896 -223.549719) (xy 355.030002 -223.498542)
			(xy 355.046014 -223.449263) (xy 355.069537 -223.403096) (xy 355.099993 -223.361177) (xy 355.136631 -223.324539)
			(xy 355.17855 -223.294083) (xy 355.224717 -223.27056) (xy 355.273996 -223.254548) (xy 355.325173 -223.246442)
			(xy 355.376987 -223.246442) (xy 355.428164 -223.254548) (xy 355.477443 -223.27056) (xy 355.52361 -223.294083)
			(xy 355.565529 -223.324539) (xy 355.602167 -223.361177) (xy 355.632623 -223.403096) (xy 355.656146 -223.449263)
			(xy 355.672158 -223.498542) (xy 355.680264 -223.549719) (xy 355.680772 -223.575626) (xy 355.680381 -223.600993)
			(xy 355.672628 -223.651131) (xy 355.657277 -223.699486) (xy 355.634692 -223.744915) (xy 355.605407 -223.786344)
			(xy 355.570116 -223.822791) (xy 355.529652 -223.853396) (xy 355.484974 -223.877433) (xy 355.437139 -223.894334)
			(xy 355.412294 -223.899476) (xy 355.389434 -223.903794) (xy 355.18471 -224.258632) (xy 355.192584 -224.280476)
			(xy 355.201157 -224.306897) (xy 355.210358 -224.36167) (xy 355.210872 -224.389442) (xy 355.491796 -224.389442)
			(xy 355.492304 -224.363555) (xy 355.500403 -224.312417) (xy 355.516402 -224.263177) (xy 355.539908 -224.217045)
			(xy 355.57034 -224.175158) (xy 355.60695 -224.138548) (xy 355.648837 -224.108116) (xy 355.694969 -224.08461)
			(xy 355.744209 -224.068611) (xy 355.795347 -224.060512) (xy 355.847121 -224.060512) (xy 355.898259 -224.068611)
			(xy 355.947499 -224.08461) (xy 355.993631 -224.108116) (xy 356.035518 -224.138548) (xy 356.072128 -224.175158)
			(xy 356.10256 -224.217045) (xy 356.126066 -224.263177) (xy 356.142065 -224.312417) (xy 356.150164 -224.363555)
			(xy 356.150672 -224.389442) (xy 356.431596 -224.389442) (xy 356.432029 -224.364106) (xy 356.43979 -224.314032)
			(xy 356.45512 -224.265734) (xy 356.477659 -224.22035) (xy 356.506875 -224.178949) (xy 356.542081 -224.142504)
			(xy 356.582448 -224.111874) (xy 356.627026 -224.087781) (xy 356.674765 -224.070791) (xy 356.699566 -224.065592)
			(xy 356.722426 -224.061274) (xy 356.92715 -223.706436) (xy 356.91953 -223.684338) (xy 356.910902 -223.657991)
			(xy 356.901579 -223.603344) (xy 356.900988 -223.575626) (xy 356.901496 -223.549719) (xy 356.909602 -223.498542)
			(xy 356.925614 -223.449263) (xy 356.949137 -223.403096) (xy 356.979593 -223.361177) (xy 357.016231 -223.324539)
			(xy 357.05815 -223.294083) (xy 357.104317 -223.27056) (xy 357.153596 -223.254548) (xy 357.204773 -223.246442)
			(xy 357.256587 -223.246442) (xy 357.307764 -223.254548) (xy 357.357043 -223.27056) (xy 357.40321 -223.294083)
			(xy 357.445129 -223.324539) (xy 357.481767 -223.361177) (xy 357.512223 -223.403096) (xy 357.535746 -223.449263)
			(xy 357.551758 -223.498542) (xy 357.559864 -223.549719) (xy 357.560372 -223.575626) (xy 357.559981 -223.600993)
			(xy 357.552228 -223.651131) (xy 357.536877 -223.699486) (xy 357.514292 -223.744915) (xy 357.485007 -223.786344)
			(xy 357.449716 -223.822791) (xy 357.409252 -223.853396) (xy 357.364574 -223.877433) (xy 357.316739 -223.894334)
			(xy 357.291894 -223.899476) (xy 357.269034 -223.903794) (xy 357.06431 -224.258632) (xy 357.072184 -224.280476)
			(xy 357.080757 -224.306897) (xy 357.089958 -224.36167) (xy 357.090472 -224.389442) (xy 357.371396 -224.389442)
			(xy 357.371904 -224.363555) (xy 357.380003 -224.312417) (xy 357.396002 -224.263177) (xy 357.419508 -224.217045)
			(xy 357.44994 -224.175158) (xy 357.48655 -224.138548) (xy 357.528437 -224.108116) (xy 357.574569 -224.08461)
			(xy 357.623809 -224.068611) (xy 357.674947 -224.060512) (xy 357.726721 -224.060512) (xy 357.777859 -224.068611)
			(xy 357.827099 -224.08461) (xy 357.873231 -224.108116) (xy 357.915118 -224.138548) (xy 357.951728 -224.175158)
			(xy 357.98216 -224.217045) (xy 358.005666 -224.263177) (xy 358.021665 -224.312417) (xy 358.029764 -224.363555)
			(xy 358.030272 -224.389442) (xy 358.311196 -224.389442) (xy 358.311629 -224.364106) (xy 358.31939 -224.314032)
			(xy 358.33472 -224.265734) (xy 358.357259 -224.22035) (xy 358.386475 -224.178949) (xy 358.421681 -224.142504)
			(xy 358.462048 -224.111874) (xy 358.506626 -224.087781) (xy 358.554365 -224.070791) (xy 358.579166 -224.065592)
			(xy 358.602026 -224.061274) (xy 358.80675 -223.706436) (xy 358.79913 -223.684338) (xy 358.790502 -223.657991)
			(xy 358.781179 -223.603344) (xy 358.780588 -223.575626) (xy 358.781096 -223.549719) (xy 358.789202 -223.498542)
			(xy 358.805214 -223.449263) (xy 358.828737 -223.403096) (xy 358.859193 -223.361177) (xy 358.895831 -223.324539)
			(xy 358.93775 -223.294083) (xy 358.983917 -223.27056) (xy 359.033196 -223.254548) (xy 359.084373 -223.246442)
			(xy 359.136187 -223.246442) (xy 359.187364 -223.254548) (xy 359.236643 -223.27056) (xy 359.28281 -223.294083)
			(xy 359.324729 -223.324539) (xy 359.361367 -223.361177) (xy 359.391823 -223.403096) (xy 359.415346 -223.449263)
			(xy 359.431358 -223.498542) (xy 359.439464 -223.549719) (xy 359.439972 -223.575626) (xy 359.439581 -223.600993)
			(xy 359.431828 -223.651131) (xy 359.416477 -223.699486) (xy 359.393892 -223.744915) (xy 359.364607 -223.786344)
			(xy 359.329316 -223.822791) (xy 359.288852 -223.853396) (xy 359.244174 -223.877433) (xy 359.196339 -223.894334)
			(xy 359.171494 -223.899476) (xy 359.148634 -223.903794) (xy 358.94391 -224.258632) (xy 358.951784 -224.280476)
			(xy 358.960357 -224.306897) (xy 358.969558 -224.36167) (xy 358.970072 -224.389442) (xy 359.250996 -224.389442)
			(xy 359.251504 -224.363555) (xy 359.259603 -224.312417) (xy 359.275602 -224.263177) (xy 359.299108 -224.217045)
			(xy 359.32954 -224.175158) (xy 359.36615 -224.138548) (xy 359.408037 -224.108116) (xy 359.454169 -224.08461)
			(xy 359.503409 -224.068611) (xy 359.554547 -224.060512) (xy 359.606321 -224.060512) (xy 359.657459 -224.068611)
			(xy 359.706699 -224.08461) (xy 359.752831 -224.108116) (xy 359.794718 -224.138548) (xy 359.831328 -224.175158)
			(xy 359.86176 -224.217045) (xy 359.885266 -224.263177) (xy 359.901265 -224.312417) (xy 359.909364 -224.363555)
			(xy 359.909872 -224.389442) (xy 360.190796 -224.389442) (xy 360.191229 -224.364106) (xy 360.19899 -224.314032)
			(xy 360.21432 -224.265734) (xy 360.236859 -224.22035) (xy 360.266075 -224.178949) (xy 360.301281 -224.142504)
			(xy 360.341648 -224.111874) (xy 360.386226 -224.087781) (xy 360.433965 -224.070791) (xy 360.458766 -224.065592)
			(xy 360.481626 -224.061274) (xy 360.68635 -223.706436) (xy 360.67873 -223.684338) (xy 360.670102 -223.657991)
			(xy 360.660779 -223.603344) (xy 360.660188 -223.575626) (xy 360.660696 -223.549719) (xy 360.668802 -223.498542)
			(xy 360.684814 -223.449263) (xy 360.708337 -223.403096) (xy 360.738793 -223.361177) (xy 360.775431 -223.324539)
			(xy 360.81735 -223.294083) (xy 360.863517 -223.27056) (xy 360.912796 -223.254548) (xy 360.963973 -223.246442)
			(xy 361.015787 -223.246442) (xy 361.066964 -223.254548) (xy 361.116243 -223.27056) (xy 361.16241 -223.294083)
			(xy 361.204329 -223.324539) (xy 361.240967 -223.361177) (xy 361.271423 -223.403096) (xy 361.294946 -223.449263)
			(xy 361.310958 -223.498542) (xy 361.319064 -223.549719) (xy 361.319572 -223.575626) (xy 361.319181 -223.600993)
			(xy 361.311428 -223.651131) (xy 361.296077 -223.699486) (xy 361.273492 -223.744915) (xy 361.244207 -223.786344)
			(xy 361.208916 -223.822791) (xy 361.168452 -223.853396) (xy 361.123774 -223.877433) (xy 361.075939 -223.894334)
			(xy 361.051094 -223.899476) (xy 361.028234 -223.903794) (xy 360.82351 -224.258632) (xy 360.831384 -224.280476)
			(xy 360.839957 -224.306897) (xy 360.849158 -224.36167) (xy 360.849672 -224.389442) (xy 361.130596 -224.389442)
			(xy 361.131104 -224.363555) (xy 361.139203 -224.312417) (xy 361.155202 -224.263177) (xy 361.178708 -224.217045)
			(xy 361.20914 -224.175158) (xy 361.24575 -224.138548) (xy 361.287637 -224.108116) (xy 361.333769 -224.08461)
			(xy 361.383009 -224.068611) (xy 361.434147 -224.060512) (xy 361.485921 -224.060512) (xy 361.537059 -224.068611)
			(xy 361.586299 -224.08461) (xy 361.632431 -224.108116) (xy 361.674318 -224.138548) (xy 361.710928 -224.175158)
			(xy 361.74136 -224.217045) (xy 361.764866 -224.263177) (xy 361.780865 -224.312417) (xy 361.788964 -224.363555)
			(xy 361.789472 -224.389442) (xy 362.070396 -224.389442) (xy 362.070829 -224.364106) (xy 362.07859 -224.314032)
			(xy 362.09392 -224.265734) (xy 362.116459 -224.22035) (xy 362.145675 -224.178949) (xy 362.180881 -224.142504)
			(xy 362.221248 -224.111874) (xy 362.265826 -224.087781) (xy 362.313565 -224.070791) (xy 362.338366 -224.065592)
			(xy 362.361226 -224.061274) (xy 362.566204 -223.706182) (xy 362.558584 -223.684084) (xy 362.550064 -223.657913)
			(xy 362.540871 -223.603651) (xy 362.540296 -223.576134) (xy 362.540296 -223.575626) (xy 362.540804 -223.549739)
			(xy 362.548903 -223.498601) (xy 362.564902 -223.449361) (xy 362.588408 -223.403229) (xy 362.61884 -223.361342)
			(xy 362.65545 -223.324732) (xy 362.697337 -223.2943) (xy 362.743469 -223.270794) (xy 362.792709 -223.254795)
			(xy 362.843847 -223.246696) (xy 362.895621 -223.246696) (xy 362.946759 -223.254795) (xy 362.995999 -223.270794)
			(xy 363.042131 -223.2943) (xy 363.084018 -223.324732) (xy 363.120628 -223.361342) (xy 363.15106 -223.403229)
			(xy 363.174566 -223.449361) (xy 363.190565 -223.498601) (xy 363.198664 -223.549739) (xy 363.199172 -223.575626)
			(xy 363.198781 -223.600993) (xy 363.191028 -223.651131) (xy 363.175677 -223.699486) (xy 363.153092 -223.744915)
			(xy 363.123807 -223.786344) (xy 363.088516 -223.822791) (xy 363.048052 -223.853396) (xy 363.003374 -223.877433)
			(xy 362.955539 -223.894334) (xy 362.930694 -223.899476) (xy 362.907834 -223.903794) (xy 362.70311 -224.258632)
			(xy 362.710984 -224.280476) (xy 362.719557 -224.306897) (xy 362.728758 -224.36167) (xy 362.729272 -224.389442)
			(xy 363.010196 -224.389442) (xy 363.010704 -224.363555) (xy 363.018803 -224.312417) (xy 363.034802 -224.263177)
			(xy 363.058308 -224.217045) (xy 363.08874 -224.175158) (xy 363.12535 -224.138548) (xy 363.167237 -224.108116)
			(xy 363.213369 -224.08461) (xy 363.262609 -224.068611) (xy 363.313747 -224.060512) (xy 363.365521 -224.060512)
			(xy 363.416659 -224.068611) (xy 363.465899 -224.08461) (xy 363.512031 -224.108116) (xy 363.553918 -224.138548)
			(xy 363.590528 -224.175158) (xy 363.62096 -224.217045) (xy 363.644466 -224.263177) (xy 363.660465 -224.312417)
			(xy 363.668564 -224.363555) (xy 363.669072 -224.389442) (xy 363.949996 -224.389442) (xy 363.950429 -224.364106)
			(xy 363.95819 -224.314032) (xy 363.97352 -224.265734) (xy 363.996059 -224.22035) (xy 364.025275 -224.178949)
			(xy 364.060481 -224.142504) (xy 364.100848 -224.111874) (xy 364.145426 -224.087781) (xy 364.193165 -224.070791)
			(xy 364.217966 -224.065592) (xy 364.240826 -224.061274) (xy 364.44555 -223.706436) (xy 364.43793 -223.684338)
			(xy 364.429302 -223.657991) (xy 364.419979 -223.603344) (xy 364.419388 -223.575626) (xy 364.419896 -223.549719)
			(xy 364.428002 -223.498542) (xy 364.444014 -223.449263) (xy 364.467537 -223.403096) (xy 364.497993 -223.361177)
			(xy 364.534631 -223.324539) (xy 364.57655 -223.294083) (xy 364.622717 -223.27056) (xy 364.671996 -223.254548)
			(xy 364.723173 -223.246442) (xy 364.774987 -223.246442) (xy 364.826164 -223.254548) (xy 364.875443 -223.27056)
			(xy 364.92161 -223.294083) (xy 364.963529 -223.324539) (xy 365.000167 -223.361177) (xy 365.030623 -223.403096)
			(xy 365.054146 -223.449263) (xy 365.070158 -223.498542) (xy 365.078264 -223.549719) (xy 365.078772 -223.575626)
			(xy 365.078381 -223.600993) (xy 365.070628 -223.651131) (xy 365.055277 -223.699486) (xy 365.032692 -223.744915)
			(xy 365.003407 -223.786344) (xy 364.968116 -223.822791) (xy 364.927652 -223.853396) (xy 364.882974 -223.877433)
			(xy 364.835139 -223.894334) (xy 364.810294 -223.899476) (xy 364.787434 -223.903794) (xy 364.58271 -224.258632)
			(xy 364.590584 -224.280476) (xy 364.599157 -224.306897) (xy 364.608358 -224.36167) (xy 364.608872 -224.389442)
			(xy 364.889796 -224.389442) (xy 364.890304 -224.363555) (xy 364.898403 -224.312417) (xy 364.914402 -224.263177)
			(xy 364.937908 -224.217045) (xy 364.96834 -224.175158) (xy 365.00495 -224.138548) (xy 365.046837 -224.108116)
			(xy 365.092969 -224.08461) (xy 365.142209 -224.068611) (xy 365.193347 -224.060512) (xy 365.245121 -224.060512)
			(xy 365.296259 -224.068611) (xy 365.345499 -224.08461) (xy 365.391631 -224.108116) (xy 365.433518 -224.138548)
			(xy 365.470128 -224.175158) (xy 365.50056 -224.217045) (xy 365.524066 -224.263177) (xy 365.540065 -224.312417)
			(xy 365.548164 -224.363555) (xy 365.548672 -224.389442) (xy 365.829596 -224.389442) (xy 365.830029 -224.364106)
			(xy 365.83779 -224.314032) (xy 365.85312 -224.265734) (xy 365.875659 -224.22035) (xy 365.904875 -224.178949)
			(xy 365.940081 -224.142504) (xy 365.980448 -224.111874) (xy 366.025026 -224.087781) (xy 366.072765 -224.070791)
			(xy 366.097566 -224.065592) (xy 366.120426 -224.061274) (xy 366.32515 -223.706436) (xy 366.31753 -223.684338)
			(xy 366.308902 -223.657991) (xy 366.299579 -223.603344) (xy 366.298988 -223.575626) (xy 366.299496 -223.549719)
			(xy 366.307602 -223.498542) (xy 366.323614 -223.449263) (xy 366.347137 -223.403096) (xy 366.377593 -223.361177)
			(xy 366.414231 -223.324539) (xy 366.45615 -223.294083) (xy 366.502317 -223.27056) (xy 366.551596 -223.254548)
			(xy 366.602773 -223.246442) (xy 366.654587 -223.246442) (xy 366.705764 -223.254548) (xy 366.755043 -223.27056)
			(xy 366.80121 -223.294083) (xy 366.843129 -223.324539) (xy 366.879767 -223.361177) (xy 366.910223 -223.403096)
			(xy 366.933746 -223.449263) (xy 366.949758 -223.498542) (xy 366.957864 -223.549719) (xy 366.958372 -223.575626)
			(xy 366.957981 -223.600993) (xy 366.950228 -223.651131) (xy 366.934877 -223.699486) (xy 366.912292 -223.744915)
			(xy 366.883007 -223.786344) (xy 366.847716 -223.822791) (xy 366.807252 -223.853396) (xy 366.762574 -223.877433)
			(xy 366.714739 -223.894334) (xy 366.689894 -223.899476) (xy 366.667034 -223.903794) (xy 366.46231 -224.258632)
			(xy 366.470184 -224.280476) (xy 366.478757 -224.306897) (xy 366.487958 -224.36167) (xy 366.488472 -224.389442)
			(xy 366.769396 -224.389442) (xy 366.769904 -224.363555) (xy 366.778003 -224.312417) (xy 366.794002 -224.263177)
			(xy 366.817508 -224.217045) (xy 366.84794 -224.175158) (xy 366.88455 -224.138548) (xy 366.926437 -224.108116)
			(xy 366.972569 -224.08461) (xy 367.021809 -224.068611) (xy 367.072947 -224.060512) (xy 367.124721 -224.060512)
			(xy 367.175859 -224.068611) (xy 367.225099 -224.08461) (xy 367.271231 -224.108116) (xy 367.313118 -224.138548)
			(xy 367.349728 -224.175158) (xy 367.38016 -224.217045) (xy 367.403666 -224.263177) (xy 367.419665 -224.312417)
			(xy 367.427764 -224.363555) (xy 367.428272 -224.389442) (xy 367.709196 -224.389442) (xy 367.709629 -224.364106)
			(xy 367.71739 -224.314032) (xy 367.73272 -224.265734) (xy 367.755259 -224.22035) (xy 367.784475 -224.178949)
			(xy 367.819681 -224.142504) (xy 367.860048 -224.111874) (xy 367.904626 -224.087781) (xy 367.952365 -224.070791)
			(xy 367.977166 -224.065592) (xy 368.000026 -224.061274) (xy 368.20475 -223.706436) (xy 368.19713 -223.684338)
			(xy 368.188502 -223.657991) (xy 368.179179 -223.603344) (xy 368.178588 -223.575626) (xy 368.179096 -223.549719)
			(xy 368.187202 -223.498542) (xy 368.203214 -223.449263) (xy 368.226737 -223.403096) (xy 368.257193 -223.361177)
			(xy 368.293831 -223.324539) (xy 368.33575 -223.294083) (xy 368.381917 -223.27056) (xy 368.431196 -223.254548)
			(xy 368.482373 -223.246442) (xy 368.534187 -223.246442) (xy 368.585364 -223.254548) (xy 368.634643 -223.27056)
			(xy 368.68081 -223.294083) (xy 368.722729 -223.324539) (xy 368.759367 -223.361177) (xy 368.789823 -223.403096)
			(xy 368.813346 -223.449263) (xy 368.829358 -223.498542) (xy 368.837464 -223.549719) (xy 368.837972 -223.575626)
			(xy 368.837581 -223.600993) (xy 368.829828 -223.651131) (xy 368.814477 -223.699486) (xy 368.791892 -223.744915)
			(xy 368.762607 -223.786344) (xy 368.727316 -223.822791) (xy 368.686852 -223.853396) (xy 368.642174 -223.877433)
			(xy 368.594339 -223.894334) (xy 368.569494 -223.899476) (xy 368.546634 -223.903794) (xy 368.34191 -224.258632)
			(xy 368.349784 -224.280476) (xy 368.358357 -224.306897) (xy 368.367558 -224.36167) (xy 368.368072 -224.389442)
			(xy 368.648996 -224.389442) (xy 368.649504 -224.363555) (xy 368.657603 -224.312417) (xy 368.673602 -224.263177)
			(xy 368.697108 -224.217045) (xy 368.72754 -224.175158) (xy 368.76415 -224.138548) (xy 368.806037 -224.108116)
			(xy 368.852169 -224.08461) (xy 368.901409 -224.068611) (xy 368.952547 -224.060512) (xy 369.004321 -224.060512)
			(xy 369.055459 -224.068611) (xy 369.104699 -224.08461) (xy 369.150831 -224.108116) (xy 369.192718 -224.138548)
			(xy 369.229328 -224.175158) (xy 369.25976 -224.217045) (xy 369.283266 -224.263177) (xy 369.299265 -224.312417)
			(xy 369.307364 -224.363555) (xy 369.307872 -224.389442) (xy 369.588796 -224.389442) (xy 369.589229 -224.364106)
			(xy 369.59699 -224.314032) (xy 369.61232 -224.265734) (xy 369.634859 -224.22035) (xy 369.664075 -224.178949)
			(xy 369.699281 -224.142504) (xy 369.739648 -224.111874) (xy 369.784226 -224.087781) (xy 369.831965 -224.070791)
			(xy 369.856766 -224.065592) (xy 369.879626 -224.061274) (xy 370.08435 -223.706436) (xy 370.07673 -223.684338)
			(xy 370.068102 -223.657991) (xy 370.058779 -223.603344) (xy 370.058188 -223.575626) (xy 370.058696 -223.549719)
			(xy 370.066802 -223.498542) (xy 370.082814 -223.449263) (xy 370.106337 -223.403096) (xy 370.136793 -223.361177)
			(xy 370.173431 -223.324539) (xy 370.21535 -223.294083) (xy 370.261517 -223.27056) (xy 370.310796 -223.254548)
			(xy 370.361973 -223.246442) (xy 370.413787 -223.246442) (xy 370.464964 -223.254548) (xy 370.514243 -223.27056)
			(xy 370.56041 -223.294083) (xy 370.602329 -223.324539) (xy 370.638967 -223.361177) (xy 370.669423 -223.403096)
			(xy 370.692946 -223.449263) (xy 370.708958 -223.498542) (xy 370.717064 -223.549719) (xy 370.717572 -223.575626)
			(xy 370.717181 -223.600993) (xy 370.709428 -223.651131) (xy 370.694077 -223.699486) (xy 370.671492 -223.744915)
			(xy 370.642207 -223.786344) (xy 370.606916 -223.822791) (xy 370.566452 -223.853396) (xy 370.521774 -223.877433)
			(xy 370.473939 -223.894334) (xy 370.449094 -223.899476) (xy 370.426234 -223.903794) (xy 370.22151 -224.258632)
			(xy 370.229384 -224.280476) (xy 370.237957 -224.306897) (xy 370.247158 -224.36167) (xy 370.247672 -224.389442)
			(xy 370.528596 -224.389442) (xy 370.529104 -224.363555) (xy 370.537203 -224.312417) (xy 370.553202 -224.263177)
			(xy 370.576708 -224.217045) (xy 370.60714 -224.175158) (xy 370.64375 -224.138548) (xy 370.685637 -224.108116)
			(xy 370.731769 -224.08461) (xy 370.781009 -224.068611) (xy 370.832147 -224.060512) (xy 370.883921 -224.060512)
			(xy 370.935059 -224.068611) (xy 370.984299 -224.08461) (xy 371.030431 -224.108116) (xy 371.072318 -224.138548)
			(xy 371.108928 -224.175158) (xy 371.13936 -224.217045) (xy 371.162866 -224.263177) (xy 371.178865 -224.312417)
			(xy 371.186964 -224.363555) (xy 371.187472 -224.389442) (xy 371.468396 -224.389442) (xy 371.468829 -224.364106)
			(xy 371.47659 -224.314032) (xy 371.49192 -224.265734) (xy 371.514459 -224.22035) (xy 371.543675 -224.178949)
			(xy 371.578881 -224.142504) (xy 371.619248 -224.111874) (xy 371.663826 -224.087781) (xy 371.711565 -224.070791)
			(xy 371.736366 -224.065592) (xy 371.759226 -224.061274) (xy 371.96395 -223.706436) (xy 371.95633 -223.684338)
			(xy 371.947702 -223.657991) (xy 371.938379 -223.603344) (xy 371.937788 -223.575626) (xy 371.938296 -223.549719)
			(xy 371.946402 -223.498542) (xy 371.962414 -223.449263) (xy 371.985937 -223.403096) (xy 372.016393 -223.361177)
			(xy 372.053031 -223.324539) (xy 372.09495 -223.294083) (xy 372.141117 -223.27056) (xy 372.190396 -223.254548)
			(xy 372.241573 -223.246442) (xy 372.293387 -223.246442) (xy 372.344564 -223.254548) (xy 372.393843 -223.27056)
			(xy 372.44001 -223.294083) (xy 372.481929 -223.324539) (xy 372.518567 -223.361177) (xy 372.549023 -223.403096)
			(xy 372.572546 -223.449263) (xy 372.588558 -223.498542) (xy 372.596664 -223.549719) (xy 372.597172 -223.575626)
			(xy 372.596781 -223.600993) (xy 372.589028 -223.651131) (xy 372.573677 -223.699486) (xy 372.551092 -223.744915)
			(xy 372.521807 -223.786344) (xy 372.486516 -223.822791) (xy 372.446052 -223.853396) (xy 372.401374 -223.877433)
			(xy 372.353539 -223.894334) (xy 372.328694 -223.899476) (xy 372.305834 -223.903794) (xy 372.10111 -224.258632)
			(xy 372.108984 -224.280476) (xy 372.117557 -224.306897) (xy 372.126758 -224.36167) (xy 372.127272 -224.389442)
			(xy 372.408196 -224.389442) (xy 372.408704 -224.363555) (xy 372.416803 -224.312417) (xy 372.432802 -224.263177)
			(xy 372.456308 -224.217045) (xy 372.48674 -224.175158) (xy 372.52335 -224.138548) (xy 372.565237 -224.108116)
			(xy 372.611369 -224.08461) (xy 372.660609 -224.068611) (xy 372.711747 -224.060512) (xy 372.763521 -224.060512)
			(xy 372.814659 -224.068611) (xy 372.863899 -224.08461) (xy 372.910031 -224.108116) (xy 372.951918 -224.138548)
			(xy 372.988528 -224.175158) (xy 373.01896 -224.217045) (xy 373.042466 -224.263177) (xy 373.058465 -224.312417)
			(xy 373.066564 -224.363555) (xy 373.067072 -224.389442) (xy 373.347996 -224.389442) (xy 373.348429 -224.364106)
			(xy 373.35619 -224.314032) (xy 373.37152 -224.265734) (xy 373.394059 -224.22035) (xy 373.423275 -224.178949)
			(xy 373.458481 -224.142504) (xy 373.498848 -224.111874) (xy 373.543426 -224.087781) (xy 373.591165 -224.070791)
			(xy 373.615966 -224.065592) (xy 373.638826 -224.061274) (xy 373.84355 -223.706436) (xy 373.83593 -223.684338)
			(xy 373.827302 -223.657991) (xy 373.817979 -223.603344) (xy 373.817388 -223.575626) (xy 373.817896 -223.549719)
			(xy 373.826002 -223.498542) (xy 373.842014 -223.449263) (xy 373.865537 -223.403096) (xy 373.895993 -223.361177)
			(xy 373.932631 -223.324539) (xy 373.97455 -223.294083) (xy 374.020717 -223.27056) (xy 374.069996 -223.254548)
			(xy 374.121173 -223.246442) (xy 374.172987 -223.246442) (xy 374.224164 -223.254548) (xy 374.273443 -223.27056)
			(xy 374.31961 -223.294083) (xy 374.361529 -223.324539) (xy 374.398167 -223.361177) (xy 374.428623 -223.403096)
			(xy 374.452146 -223.449263) (xy 374.468158 -223.498542) (xy 374.476264 -223.549719) (xy 374.476772 -223.575626)
			(xy 374.476381 -223.600993) (xy 374.468628 -223.651131) (xy 374.453277 -223.699486) (xy 374.430692 -223.744915)
			(xy 374.401407 -223.786344) (xy 374.366116 -223.822791) (xy 374.325652 -223.853396) (xy 374.280974 -223.877433)
			(xy 374.233139 -223.894334) (xy 374.208294 -223.899476) (xy 374.185434 -223.903794) (xy 373.98071 -224.258632)
			(xy 373.988584 -224.280476) (xy 373.997157 -224.306897) (xy 374.006358 -224.36167) (xy 374.006872 -224.389442)
			(xy 374.287796 -224.389442) (xy 374.288304 -224.363555) (xy 374.296403 -224.312417) (xy 374.312402 -224.263177)
			(xy 374.335908 -224.217045) (xy 374.36634 -224.175158) (xy 374.40295 -224.138548) (xy 374.444837 -224.108116)
			(xy 374.490969 -224.08461) (xy 374.540209 -224.068611) (xy 374.591347 -224.060512) (xy 374.643121 -224.060512)
			(xy 374.694259 -224.068611) (xy 374.743499 -224.08461) (xy 374.789631 -224.108116) (xy 374.831518 -224.138548)
			(xy 374.868128 -224.175158) (xy 374.89856 -224.217045) (xy 374.922066 -224.263177) (xy 374.938065 -224.312417)
			(xy 374.946164 -224.363555) (xy 374.946672 -224.389442) (xy 375.227596 -224.389442) (xy 375.228029 -224.364106)
			(xy 375.23579 -224.314032) (xy 375.25112 -224.265734) (xy 375.273659 -224.22035) (xy 375.302875 -224.178949)
			(xy 375.338081 -224.142504) (xy 375.378448 -224.111874) (xy 375.423026 -224.087781) (xy 375.470765 -224.070791)
			(xy 375.495566 -224.065592) (xy 375.518426 -224.061274) (xy 375.72315 -223.706436) (xy 375.71553 -223.684338)
			(xy 375.706902 -223.657991) (xy 375.697579 -223.603344) (xy 375.696988 -223.575626) (xy 375.697496 -223.549719)
			(xy 375.705602 -223.498542) (xy 375.721614 -223.449263) (xy 375.745137 -223.403096) (xy 375.775593 -223.361177)
			(xy 375.812231 -223.324539) (xy 375.85415 -223.294083) (xy 375.900317 -223.27056) (xy 375.949596 -223.254548)
			(xy 376.000773 -223.246442) (xy 376.052587 -223.246442) (xy 376.103764 -223.254548) (xy 376.153043 -223.27056)
			(xy 376.19921 -223.294083) (xy 376.241129 -223.324539) (xy 376.277767 -223.361177) (xy 376.308223 -223.403096)
			(xy 376.331746 -223.449263) (xy 376.347758 -223.498542) (xy 376.355864 -223.549719) (xy 376.356372 -223.575626)
			(xy 376.355981 -223.600993) (xy 376.348228 -223.651131) (xy 376.332877 -223.699486) (xy 376.310292 -223.744915)
			(xy 376.281007 -223.786344) (xy 376.245716 -223.822791) (xy 376.205252 -223.853396) (xy 376.160574 -223.877433)
			(xy 376.112739 -223.894334) (xy 376.087894 -223.899476) (xy 376.065034 -223.903794) (xy 375.86031 -224.258632)
			(xy 375.868184 -224.280476) (xy 375.876757 -224.306897) (xy 375.885958 -224.36167) (xy 375.886472 -224.389442)
			(xy 376.167396 -224.389442) (xy 376.167904 -224.363555) (xy 376.176003 -224.312417) (xy 376.192002 -224.263177)
			(xy 376.215508 -224.217045) (xy 376.24594 -224.175158) (xy 376.28255 -224.138548) (xy 376.324437 -224.108116)
			(xy 376.370569 -224.08461) (xy 376.419809 -224.068611) (xy 376.470947 -224.060512) (xy 376.522721 -224.060512)
			(xy 376.573859 -224.068611) (xy 376.623099 -224.08461) (xy 376.669231 -224.108116) (xy 376.711118 -224.138548)
			(xy 376.747728 -224.175158) (xy 376.77816 -224.217045) (xy 376.801666 -224.263177) (xy 376.817665 -224.312417)
			(xy 376.825764 -224.363555) (xy 376.826272 -224.389442) (xy 377.107196 -224.389442) (xy 377.107629 -224.364106)
			(xy 377.11539 -224.314032) (xy 377.13072 -224.265734) (xy 377.153259 -224.22035) (xy 377.182475 -224.178949)
			(xy 377.217681 -224.142504) (xy 377.258048 -224.111874) (xy 377.302626 -224.087781) (xy 377.350365 -224.070791)
			(xy 377.375166 -224.065592) (xy 377.398026 -224.061274) (xy 377.60275 -223.706436) (xy 377.59513 -223.684338)
			(xy 377.586502 -223.657991) (xy 377.577179 -223.603344) (xy 377.576588 -223.575626) (xy 377.577096 -223.549719)
			(xy 377.585202 -223.498542) (xy 377.601214 -223.449263) (xy 377.624737 -223.403096) (xy 377.655193 -223.361177)
			(xy 377.691831 -223.324539) (xy 377.73375 -223.294083) (xy 377.779917 -223.27056) (xy 377.829196 -223.254548)
			(xy 377.880373 -223.246442) (xy 377.932187 -223.246442) (xy 377.983364 -223.254548) (xy 378.032643 -223.27056)
			(xy 378.07881 -223.294083) (xy 378.120729 -223.324539) (xy 378.157367 -223.361177) (xy 378.187823 -223.403096)
			(xy 378.211346 -223.449263) (xy 378.227358 -223.498542) (xy 378.235464 -223.549719) (xy 378.235972 -223.575626)
			(xy 378.235581 -223.600993) (xy 378.227828 -223.651131) (xy 378.212477 -223.699486) (xy 378.189892 -223.744915)
			(xy 378.160607 -223.786344) (xy 378.125316 -223.822791) (xy 378.084852 -223.853396) (xy 378.040174 -223.877433)
			(xy 377.992339 -223.894334) (xy 377.967494 -223.899476) (xy 377.944634 -223.903794) (xy 377.73991 -224.258632)
			(xy 377.747784 -224.280476) (xy 377.756357 -224.306897) (xy 377.765558 -224.36167) (xy 377.766072 -224.389442)
			(xy 378.046996 -224.389442) (xy 378.047504 -224.363555) (xy 378.055603 -224.312417) (xy 378.071602 -224.263177)
			(xy 378.095108 -224.217045) (xy 378.12554 -224.175158) (xy 378.16215 -224.138548) (xy 378.204037 -224.108116)
			(xy 378.250169 -224.08461) (xy 378.299409 -224.068611) (xy 378.350547 -224.060512) (xy 378.402321 -224.060512)
			(xy 378.453459 -224.068611) (xy 378.502699 -224.08461) (xy 378.548831 -224.108116) (xy 378.590718 -224.138548)
			(xy 378.627328 -224.175158) (xy 378.65776 -224.217045) (xy 378.681266 -224.263177) (xy 378.697265 -224.312417)
			(xy 378.705364 -224.363555) (xy 378.705872 -224.389442) (xy 378.986796 -224.389442) (xy 378.987229 -224.364106)
			(xy 378.99499 -224.314032) (xy 379.01032 -224.265734) (xy 379.032859 -224.22035) (xy 379.062075 -224.178949)
			(xy 379.097281 -224.142504) (xy 379.137648 -224.111874) (xy 379.182226 -224.087781) (xy 379.229965 -224.070791)
			(xy 379.254766 -224.065592) (xy 379.277626 -224.061274) (xy 379.48235 -223.706182) (xy 379.47473 -223.684338)
			(xy 379.466087 -223.657995) (xy 379.456772 -223.603345) (xy 379.456188 -223.575626) (xy 379.456696 -223.549719)
			(xy 379.464802 -223.498542) (xy 379.480814 -223.449263) (xy 379.504337 -223.403096) (xy 379.534793 -223.361177)
			(xy 379.571431 -223.324539) (xy 379.61335 -223.294083) (xy 379.659517 -223.27056) (xy 379.708796 -223.254548)
			(xy 379.759973 -223.246442) (xy 379.811787 -223.246442) (xy 379.862964 -223.254548) (xy 379.912243 -223.27056)
			(xy 379.95841 -223.294083) (xy 380.000329 -223.324539) (xy 380.036967 -223.361177) (xy 380.067423 -223.403096)
			(xy 380.090946 -223.449263) (xy 380.106958 -223.498542) (xy 380.115064 -223.549719) (xy 380.115572 -223.575626)
			(xy 380.115097 -223.600971) (xy 380.107321 -223.651063) (xy 380.091971 -223.699374) (xy 380.069408 -223.744767)
			(xy 380.040166 -223.786173) (xy 380.004931 -223.822617) (xy 379.964535 -223.853239) (xy 379.919928 -223.877319)
			(xy 379.872162 -223.89429) (xy 379.847348 -223.899476) (xy 379.824488 -223.903794) (xy 379.619764 -224.258632)
			(xy 379.627384 -224.280476) (xy 379.635939 -224.306769) (xy 379.645132 -224.361289) (xy 379.645672 -224.388934)
			(xy 379.645672 -224.389442) (xy 379.926596 -224.389442) (xy 379.927104 -224.363555) (xy 379.935203 -224.312417)
			(xy 379.951202 -224.263177) (xy 379.974708 -224.217045) (xy 380.00514 -224.175158) (xy 380.04175 -224.138548)
			(xy 380.083637 -224.108116) (xy 380.129769 -224.08461) (xy 380.179009 -224.068611) (xy 380.230147 -224.060512)
			(xy 380.281921 -224.060512) (xy 380.333059 -224.068611) (xy 380.382299 -224.08461) (xy 380.428431 -224.108116)
			(xy 380.470318 -224.138548) (xy 380.506928 -224.175158) (xy 380.53736 -224.217045) (xy 380.560866 -224.263177)
			(xy 380.576865 -224.312417) (xy 380.584964 -224.363555) (xy 380.585472 -224.389442) (xy 380.866396 -224.389442)
			(xy 380.866829 -224.364106) (xy 380.87459 -224.314032) (xy 380.88992 -224.265734) (xy 380.912459 -224.22035)
			(xy 380.941675 -224.178949) (xy 380.976881 -224.142504) (xy 381.017248 -224.111874) (xy 381.061826 -224.087781)
			(xy 381.109565 -224.070791) (xy 381.134366 -224.065592) (xy 381.157226 -224.061274) (xy 381.362204 -223.705928)
			(xy 381.354584 -223.684084) (xy 381.346064 -223.657913) (xy 381.336871 -223.603651) (xy 381.336296 -223.576134)
			(xy 381.336296 -223.575626) (xy 381.336804 -223.549739) (xy 381.344903 -223.498601) (xy 381.360902 -223.449361)
			(xy 381.384408 -223.403229) (xy 381.41484 -223.361342) (xy 381.45145 -223.324732) (xy 381.493337 -223.2943)
			(xy 381.539469 -223.270794) (xy 381.588709 -223.254795) (xy 381.639847 -223.246696) (xy 381.691621 -223.246696)
			(xy 381.742759 -223.254795) (xy 381.791999 -223.270794) (xy 381.838131 -223.2943) (xy 381.880018 -223.324732)
			(xy 381.916628 -223.361342) (xy 381.94706 -223.403229) (xy 381.970566 -223.449361) (xy 381.986565 -223.498601)
			(xy 381.994664 -223.549739) (xy 381.995172 -223.575626) (xy 381.994697 -223.600971) (xy 381.986921 -223.651063)
			(xy 381.971571 -223.699374) (xy 381.949008 -223.744767) (xy 381.919766 -223.786173) (xy 381.884531 -223.822617)
			(xy 381.844135 -223.853239) (xy 381.799528 -223.877319) (xy 381.751762 -223.89429) (xy 381.726948 -223.899476)
			(xy 381.704088 -223.903794) (xy 381.499364 -224.258632) (xy 381.506984 -224.280476) (xy 381.515539 -224.306769)
			(xy 381.524732 -224.361289) (xy 381.525272 -224.388934) (xy 381.525272 -224.389442) (xy 381.806196 -224.389442)
			(xy 381.806704 -224.363555) (xy 381.814803 -224.312417) (xy 381.830802 -224.263177) (xy 381.854308 -224.217045)
			(xy 381.88474 -224.175158) (xy 381.92135 -224.138548) (xy 381.963237 -224.108116) (xy 382.009369 -224.08461)
			(xy 382.058609 -224.068611) (xy 382.109747 -224.060512) (xy 382.161521 -224.060512) (xy 382.212659 -224.068611)
			(xy 382.261899 -224.08461) (xy 382.308031 -224.108116) (xy 382.349918 -224.138548) (xy 382.386528 -224.175158)
			(xy 382.41696 -224.217045) (xy 382.440466 -224.263177) (xy 382.456465 -224.312417) (xy 382.464564 -224.363555)
			(xy 382.465072 -224.389442) (xy 382.464539 -224.41715) (xy 382.455342 -224.471795) (xy 382.446784 -224.498154)
			(xy 382.439164 -224.519998) (xy 382.644142 -224.87509) (xy 382.667002 -224.879408) (xy 382.691815 -224.884555)
			(xy 382.739557 -224.901547) (xy 382.784137 -224.925644) (xy 382.824504 -224.95628) (xy 382.859707 -224.992732)
			(xy 382.888918 -225.034142) (xy 382.911448 -225.079534) (xy 382.926766 -225.12784) (xy 382.934512 -225.17792)
			(xy 382.934972 -225.203258) (xy 382.934464 -225.229145) (xy 382.926365 -225.280283) (xy 382.910366 -225.329523)
			(xy 382.88686 -225.375655) (xy 382.856428 -225.417542) (xy 382.819818 -225.454152) (xy 382.777931 -225.484584)
			(xy 382.731799 -225.50809) (xy 382.682559 -225.524089) (xy 382.631421 -225.532188) (xy 382.579647 -225.532188)
			(xy 382.528509 -225.524089) (xy 382.479269 -225.50809) (xy 382.433137 -225.484584) (xy 382.39125 -225.454152)
			(xy 382.35464 -225.417542) (xy 382.324208 -225.375655) (xy 382.300702 -225.329523) (xy 382.284703 -225.280283)
			(xy 382.276604 -225.229145) (xy 382.276096 -225.203258) (xy 382.276096 -225.20275) (xy 382.276653 -225.175107)
			(xy 382.285844 -225.120589) (xy 382.294384 -225.094292) (xy 382.302004 -225.072448) (xy 382.09728 -224.71761)
			(xy 382.07442 -224.713292) (xy 382.049591 -224.708158) (xy 382.001812 -224.691199) (xy 381.957192 -224.667122)
			(xy 381.916786 -224.636498) (xy 381.881546 -224.600046) (xy 381.852303 -224.558629) (xy 381.829748 -224.513222)
			(xy 381.814412 -224.464896) (xy 381.806657 -224.414792) (xy 381.806196 -224.389442) (xy 381.525272 -224.389442)
			(xy 381.524764 -224.415329) (xy 381.516665 -224.466467) (xy 381.500666 -224.515707) (xy 381.47716 -224.561839)
			(xy 381.446728 -224.603726) (xy 381.410118 -224.640336) (xy 381.368231 -224.670768) (xy 381.322099 -224.694274)
			(xy 381.272859 -224.710273) (xy 381.221721 -224.718372) (xy 381.169947 -224.718372) (xy 381.118809 -224.710273)
			(xy 381.069569 -224.694274) (xy 381.023437 -224.670768) (xy 380.98155 -224.640336) (xy 380.94494 -224.603726)
			(xy 380.914508 -224.561839) (xy 380.891002 -224.515707) (xy 380.875003 -224.466467) (xy 380.866904 -224.415329)
			(xy 380.866396 -224.389442) (xy 380.585472 -224.389442) (xy 380.584925 -224.417149) (xy 380.575741 -224.471796)
			(xy 380.567184 -224.498154) (xy 380.55931 -224.520252) (xy 380.764288 -224.87509) (xy 380.787148 -224.879408)
			(xy 380.811971 -224.884565) (xy 380.859751 -224.90152) (xy 380.904371 -224.925592) (xy 380.944778 -224.956214)
			(xy 380.980019 -224.992662) (xy 381.009263 -225.034077) (xy 381.031819 -225.079482) (xy 381.047156 -225.127806)
			(xy 381.054911 -225.177908) (xy 381.055372 -225.203258) (xy 381.054864 -225.229165) (xy 381.046758 -225.280342)
			(xy 381.030746 -225.329621) (xy 381.007223 -225.375788) (xy 380.976767 -225.417707) (xy 380.940129 -225.454345)
			(xy 380.89821 -225.484801) (xy 380.852043 -225.508324) (xy 380.802764 -225.524336) (xy 380.751587 -225.532442)
			(xy 380.699773 -225.532442) (xy 380.648596 -225.524336) (xy 380.599317 -225.508324) (xy 380.55315 -225.484801)
			(xy 380.511231 -225.454345) (xy 380.474593 -225.417707) (xy 380.444137 -225.375788) (xy 380.420614 -225.329621)
			(xy 380.404602 -225.280342) (xy 380.396496 -225.229165) (xy 380.395988 -225.203258) (xy 380.396597 -225.175541)
			(xy 380.40591 -225.120895) (xy 380.41453 -225.094546) (xy 380.422404 -225.072448) (xy 380.217426 -224.71761)
			(xy 380.194566 -224.713292) (xy 380.169748 -224.708169) (xy 380.122005 -224.691172) (xy 380.077426 -224.667071)
			(xy 380.03706 -224.636431) (xy 380.001857 -224.599976) (xy 379.972648 -224.558564) (xy 379.950119 -224.51317)
			(xy 379.934801 -224.464863) (xy 379.927055 -224.414781) (xy 379.926596 -224.389442) (xy 379.645672 -224.389442)
			(xy 379.645164 -224.415329) (xy 379.637065 -224.466467) (xy 379.621066 -224.515707) (xy 379.59756 -224.561839)
			(xy 379.567128 -224.603726) (xy 379.530518 -224.640336) (xy 379.488631 -224.670768) (xy 379.442499 -224.694274)
			(xy 379.393259 -224.710273) (xy 379.342121 -224.718372) (xy 379.290347 -224.718372) (xy 379.239209 -224.710273)
			(xy 379.189969 -224.694274) (xy 379.143837 -224.670768) (xy 379.10195 -224.640336) (xy 379.06534 -224.603726)
			(xy 379.034908 -224.561839) (xy 379.011402 -224.515707) (xy 378.995403 -224.466467) (xy 378.987304 -224.415329)
			(xy 378.986796 -224.389442) (xy 378.705872 -224.389442) (xy 378.705325 -224.417149) (xy 378.696141 -224.471796)
			(xy 378.687584 -224.498154) (xy 378.67971 -224.520252) (xy 378.884688 -224.87509) (xy 378.907548 -224.879408)
			(xy 378.932371 -224.884565) (xy 378.980151 -224.90152) (xy 379.024771 -224.925592) (xy 379.065178 -224.956214)
			(xy 379.100419 -224.992662) (xy 379.129663 -225.034077) (xy 379.152219 -225.079482) (xy 379.167556 -225.127806)
			(xy 379.175311 -225.177908) (xy 379.175772 -225.203258) (xy 379.175264 -225.229165) (xy 379.167158 -225.280342)
			(xy 379.151146 -225.329621) (xy 379.127623 -225.375788) (xy 379.097167 -225.417707) (xy 379.060529 -225.454345)
			(xy 379.01861 -225.484801) (xy 378.972443 -225.508324) (xy 378.923164 -225.524336) (xy 378.871987 -225.532442)
			(xy 378.820173 -225.532442) (xy 378.768996 -225.524336) (xy 378.719717 -225.508324) (xy 378.67355 -225.484801)
			(xy 378.631631 -225.454345) (xy 378.594993 -225.417707) (xy 378.564537 -225.375788) (xy 378.541014 -225.329621)
			(xy 378.525002 -225.280342) (xy 378.516896 -225.229165) (xy 378.516388 -225.203258) (xy 378.516997 -225.175541)
			(xy 378.52631 -225.120895) (xy 378.53493 -225.094546) (xy 378.542804 -225.072448) (xy 378.337826 -224.71761)
			(xy 378.314966 -224.713292) (xy 378.290148 -224.708169) (xy 378.242405 -224.691172) (xy 378.197826 -224.667071)
			(xy 378.15746 -224.636431) (xy 378.122257 -224.599976) (xy 378.093048 -224.558564) (xy 378.070519 -224.51317)
			(xy 378.055201 -224.464863) (xy 378.047455 -224.414781) (xy 378.046996 -224.389442) (xy 377.766072 -224.389442)
			(xy 377.765564 -224.415329) (xy 377.757465 -224.466467) (xy 377.741466 -224.515707) (xy 377.71796 -224.561839)
			(xy 377.687528 -224.603726) (xy 377.650918 -224.640336) (xy 377.609031 -224.670768) (xy 377.562899 -224.694274)
			(xy 377.513659 -224.710273) (xy 377.462521 -224.718372) (xy 377.410747 -224.718372) (xy 377.359609 -224.710273)
			(xy 377.310369 -224.694274) (xy 377.264237 -224.670768) (xy 377.22235 -224.640336) (xy 377.18574 -224.603726)
			(xy 377.155308 -224.561839) (xy 377.131802 -224.515707) (xy 377.115803 -224.466467) (xy 377.107704 -224.415329)
			(xy 377.107196 -224.389442) (xy 376.826272 -224.389442) (xy 376.825725 -224.417149) (xy 376.816541 -224.471796)
			(xy 376.807984 -224.498154) (xy 376.80011 -224.520252) (xy 377.005088 -224.87509) (xy 377.027948 -224.879408)
			(xy 377.052771 -224.884565) (xy 377.100551 -224.90152) (xy 377.145171 -224.925592) (xy 377.185578 -224.956214)
			(xy 377.220819 -224.992662) (xy 377.250063 -225.034077) (xy 377.272619 -225.079482) (xy 377.287956 -225.127806)
			(xy 377.295711 -225.177908) (xy 377.296172 -225.203258) (xy 377.295664 -225.229165) (xy 377.287558 -225.280342)
			(xy 377.271546 -225.329621) (xy 377.248023 -225.375788) (xy 377.217567 -225.417707) (xy 377.180929 -225.454345)
			(xy 377.13901 -225.484801) (xy 377.092843 -225.508324) (xy 377.043564 -225.524336) (xy 376.992387 -225.532442)
			(xy 376.940573 -225.532442) (xy 376.889396 -225.524336) (xy 376.840117 -225.508324) (xy 376.79395 -225.484801)
			(xy 376.752031 -225.454345) (xy 376.715393 -225.417707) (xy 376.684937 -225.375788) (xy 376.661414 -225.329621)
			(xy 376.645402 -225.280342) (xy 376.637296 -225.229165) (xy 376.636788 -225.203258) (xy 376.637397 -225.175541)
			(xy 376.64671 -225.120895) (xy 376.65533 -225.094546) (xy 376.663204 -225.072448) (xy 376.458226 -224.71761)
			(xy 376.435366 -224.713292) (xy 376.410548 -224.708169) (xy 376.362805 -224.691172) (xy 376.318226 -224.667071)
			(xy 376.27786 -224.636431) (xy 376.242657 -224.599976) (xy 376.213448 -224.558564) (xy 376.190919 -224.51317)
			(xy 376.175601 -224.464863) (xy 376.167855 -224.414781) (xy 376.167396 -224.389442) (xy 375.886472 -224.389442)
			(xy 375.885964 -224.415329) (xy 375.877865 -224.466467) (xy 375.861866 -224.515707) (xy 375.83836 -224.561839)
			(xy 375.807928 -224.603726) (xy 375.771318 -224.640336) (xy 375.729431 -224.670768) (xy 375.683299 -224.694274)
			(xy 375.634059 -224.710273) (xy 375.582921 -224.718372) (xy 375.531147 -224.718372) (xy 375.480009 -224.710273)
			(xy 375.430769 -224.694274) (xy 375.384637 -224.670768) (xy 375.34275 -224.640336) (xy 375.30614 -224.603726)
			(xy 375.275708 -224.561839) (xy 375.252202 -224.515707) (xy 375.236203 -224.466467) (xy 375.228104 -224.415329)
			(xy 375.227596 -224.389442) (xy 374.946672 -224.389442) (xy 374.946125 -224.417149) (xy 374.936941 -224.471796)
			(xy 374.928384 -224.498154) (xy 374.92051 -224.520252) (xy 375.125488 -224.87509) (xy 375.148348 -224.879408)
			(xy 375.173171 -224.884565) (xy 375.220951 -224.90152) (xy 375.265571 -224.925592) (xy 375.305978 -224.956214)
			(xy 375.341219 -224.992662) (xy 375.370463 -225.034077) (xy 375.393019 -225.079482) (xy 375.408356 -225.127806)
			(xy 375.416111 -225.177908) (xy 375.416572 -225.203258) (xy 375.416064 -225.229165) (xy 375.407958 -225.280342)
			(xy 375.391946 -225.329621) (xy 375.368423 -225.375788) (xy 375.337967 -225.417707) (xy 375.301329 -225.454345)
			(xy 375.25941 -225.484801) (xy 375.213243 -225.508324) (xy 375.163964 -225.524336) (xy 375.112787 -225.532442)
			(xy 375.060973 -225.532442) (xy 375.009796 -225.524336) (xy 374.960517 -225.508324) (xy 374.91435 -225.484801)
			(xy 374.872431 -225.454345) (xy 374.835793 -225.417707) (xy 374.805337 -225.375788) (xy 374.781814 -225.329621)
			(xy 374.765802 -225.280342) (xy 374.757696 -225.229165) (xy 374.757188 -225.203258) (xy 374.757797 -225.175541)
			(xy 374.76711 -225.120895) (xy 374.77573 -225.094546) (xy 374.783604 -225.072448) (xy 374.578626 -224.71761)
			(xy 374.555766 -224.713292) (xy 374.530948 -224.708169) (xy 374.483205 -224.691172) (xy 374.438626 -224.667071)
			(xy 374.39826 -224.636431) (xy 374.363057 -224.599976) (xy 374.333848 -224.558564) (xy 374.311319 -224.51317)
			(xy 374.296001 -224.464863) (xy 374.288255 -224.414781) (xy 374.287796 -224.389442) (xy 374.006872 -224.389442)
			(xy 374.006364 -224.415329) (xy 373.998265 -224.466467) (xy 373.982266 -224.515707) (xy 373.95876 -224.561839)
			(xy 373.928328 -224.603726) (xy 373.891718 -224.640336) (xy 373.849831 -224.670768) (xy 373.803699 -224.694274)
			(xy 373.754459 -224.710273) (xy 373.703321 -224.718372) (xy 373.651547 -224.718372) (xy 373.600409 -224.710273)
			(xy 373.551169 -224.694274) (xy 373.505037 -224.670768) (xy 373.46315 -224.640336) (xy 373.42654 -224.603726)
			(xy 373.396108 -224.561839) (xy 373.372602 -224.515707) (xy 373.356603 -224.466467) (xy 373.348504 -224.415329)
			(xy 373.347996 -224.389442) (xy 373.067072 -224.389442) (xy 373.066525 -224.417149) (xy 373.057341 -224.471796)
			(xy 373.048784 -224.498154) (xy 373.04091 -224.520252) (xy 373.245888 -224.87509) (xy 373.268748 -224.879408)
			(xy 373.293571 -224.884565) (xy 373.341351 -224.90152) (xy 373.385971 -224.925592) (xy 373.426378 -224.956214)
			(xy 373.461619 -224.992662) (xy 373.490863 -225.034077) (xy 373.513419 -225.079482) (xy 373.528756 -225.127806)
			(xy 373.536511 -225.177908) (xy 373.536972 -225.203258) (xy 373.536464 -225.229165) (xy 373.528358 -225.280342)
			(xy 373.512346 -225.329621) (xy 373.488823 -225.375788) (xy 373.458367 -225.417707) (xy 373.421729 -225.454345)
			(xy 373.37981 -225.484801) (xy 373.333643 -225.508324) (xy 373.284364 -225.524336) (xy 373.233187 -225.532442)
			(xy 373.181373 -225.532442) (xy 373.130196 -225.524336) (xy 373.080917 -225.508324) (xy 373.03475 -225.484801)
			(xy 372.992831 -225.454345) (xy 372.956193 -225.417707) (xy 372.925737 -225.375788) (xy 372.902214 -225.329621)
			(xy 372.886202 -225.280342) (xy 372.878096 -225.229165) (xy 372.877588 -225.203258) (xy 372.878197 -225.175541)
			(xy 372.88751 -225.120895) (xy 372.89613 -225.094546) (xy 372.904004 -225.072448) (xy 372.699026 -224.71761)
			(xy 372.676166 -224.713292) (xy 372.651348 -224.708169) (xy 372.603605 -224.691172) (xy 372.559026 -224.667071)
			(xy 372.51866 -224.636431) (xy 372.483457 -224.599976) (xy 372.454248 -224.558564) (xy 372.431719 -224.51317)
			(xy 372.416401 -224.464863) (xy 372.408655 -224.414781) (xy 372.408196 -224.389442) (xy 372.127272 -224.389442)
			(xy 372.126764 -224.415329) (xy 372.118665 -224.466467) (xy 372.102666 -224.515707) (xy 372.07916 -224.561839)
			(xy 372.048728 -224.603726) (xy 372.012118 -224.640336) (xy 371.970231 -224.670768) (xy 371.924099 -224.694274)
			(xy 371.874859 -224.710273) (xy 371.823721 -224.718372) (xy 371.771947 -224.718372) (xy 371.720809 -224.710273)
			(xy 371.671569 -224.694274) (xy 371.625437 -224.670768) (xy 371.58355 -224.640336) (xy 371.54694 -224.603726)
			(xy 371.516508 -224.561839) (xy 371.493002 -224.515707) (xy 371.477003 -224.466467) (xy 371.468904 -224.415329)
			(xy 371.468396 -224.389442) (xy 371.187472 -224.389442) (xy 371.186925 -224.417149) (xy 371.177741 -224.471796)
			(xy 371.169184 -224.498154) (xy 371.16131 -224.520252) (xy 371.366288 -224.87509) (xy 371.389148 -224.879408)
			(xy 371.413971 -224.884565) (xy 371.461751 -224.90152) (xy 371.506371 -224.925592) (xy 371.546778 -224.956214)
			(xy 371.582019 -224.992662) (xy 371.611263 -225.034077) (xy 371.633819 -225.079482) (xy 371.649156 -225.127806)
			(xy 371.656911 -225.177908) (xy 371.657372 -225.203258) (xy 371.656864 -225.229165) (xy 371.648758 -225.280342)
			(xy 371.632746 -225.329621) (xy 371.609223 -225.375788) (xy 371.578767 -225.417707) (xy 371.542129 -225.454345)
			(xy 371.50021 -225.484801) (xy 371.454043 -225.508324) (xy 371.404764 -225.524336) (xy 371.353587 -225.532442)
			(xy 371.301773 -225.532442) (xy 371.250596 -225.524336) (xy 371.201317 -225.508324) (xy 371.15515 -225.484801)
			(xy 371.113231 -225.454345) (xy 371.076593 -225.417707) (xy 371.046137 -225.375788) (xy 371.022614 -225.329621)
			(xy 371.006602 -225.280342) (xy 370.998496 -225.229165) (xy 370.997988 -225.203258) (xy 370.998597 -225.175541)
			(xy 371.00791 -225.120895) (xy 371.01653 -225.094546) (xy 371.024404 -225.072448) (xy 370.819426 -224.71761)
			(xy 370.796566 -224.713292) (xy 370.771748 -224.708169) (xy 370.724005 -224.691172) (xy 370.679426 -224.667071)
			(xy 370.63906 -224.636431) (xy 370.603857 -224.599976) (xy 370.574648 -224.558564) (xy 370.552119 -224.51317)
			(xy 370.536801 -224.464863) (xy 370.529055 -224.414781) (xy 370.528596 -224.389442) (xy 370.247672 -224.389442)
			(xy 370.247164 -224.415329) (xy 370.239065 -224.466467) (xy 370.223066 -224.515707) (xy 370.19956 -224.561839)
			(xy 370.169128 -224.603726) (xy 370.132518 -224.640336) (xy 370.090631 -224.670768) (xy 370.044499 -224.694274)
			(xy 369.995259 -224.710273) (xy 369.944121 -224.718372) (xy 369.892347 -224.718372) (xy 369.841209 -224.710273)
			(xy 369.791969 -224.694274) (xy 369.745837 -224.670768) (xy 369.70395 -224.640336) (xy 369.66734 -224.603726)
			(xy 369.636908 -224.561839) (xy 369.613402 -224.515707) (xy 369.597403 -224.466467) (xy 369.589304 -224.415329)
			(xy 369.588796 -224.389442) (xy 369.307872 -224.389442) (xy 369.307325 -224.417149) (xy 369.298141 -224.471796)
			(xy 369.289584 -224.498154) (xy 369.28171 -224.520252) (xy 369.486688 -224.87509) (xy 369.509548 -224.879408)
			(xy 369.534371 -224.884565) (xy 369.582151 -224.90152) (xy 369.626771 -224.925592) (xy 369.667178 -224.956214)
			(xy 369.702419 -224.992662) (xy 369.731663 -225.034077) (xy 369.754219 -225.079482) (xy 369.769556 -225.127806)
			(xy 369.777311 -225.177908) (xy 369.777772 -225.203258) (xy 369.777264 -225.229165) (xy 369.769158 -225.280342)
			(xy 369.753146 -225.329621) (xy 369.729623 -225.375788) (xy 369.699167 -225.417707) (xy 369.662529 -225.454345)
			(xy 369.62061 -225.484801) (xy 369.574443 -225.508324) (xy 369.525164 -225.524336) (xy 369.473987 -225.532442)
			(xy 369.422173 -225.532442) (xy 369.370996 -225.524336) (xy 369.321717 -225.508324) (xy 369.27555 -225.484801)
			(xy 369.233631 -225.454345) (xy 369.196993 -225.417707) (xy 369.166537 -225.375788) (xy 369.143014 -225.329621)
			(xy 369.127002 -225.280342) (xy 369.118896 -225.229165) (xy 369.118388 -225.203258) (xy 369.118997 -225.175541)
			(xy 369.12831 -225.120895) (xy 369.13693 -225.094546) (xy 369.144804 -225.072448) (xy 368.939826 -224.71761)
			(xy 368.916966 -224.713292) (xy 368.892148 -224.708169) (xy 368.844405 -224.691172) (xy 368.799826 -224.667071)
			(xy 368.75946 -224.636431) (xy 368.724257 -224.599976) (xy 368.695048 -224.558564) (xy 368.672519 -224.51317)
			(xy 368.657201 -224.464863) (xy 368.649455 -224.414781) (xy 368.648996 -224.389442) (xy 368.368072 -224.389442)
			(xy 368.367564 -224.415329) (xy 368.359465 -224.466467) (xy 368.343466 -224.515707) (xy 368.31996 -224.561839)
			(xy 368.289528 -224.603726) (xy 368.252918 -224.640336) (xy 368.211031 -224.670768) (xy 368.164899 -224.694274)
			(xy 368.115659 -224.710273) (xy 368.064521 -224.718372) (xy 368.012747 -224.718372) (xy 367.961609 -224.710273)
			(xy 367.912369 -224.694274) (xy 367.866237 -224.670768) (xy 367.82435 -224.640336) (xy 367.78774 -224.603726)
			(xy 367.757308 -224.561839) (xy 367.733802 -224.515707) (xy 367.717803 -224.466467) (xy 367.709704 -224.415329)
			(xy 367.709196 -224.389442) (xy 367.428272 -224.389442) (xy 367.427725 -224.417149) (xy 367.418541 -224.471796)
			(xy 367.409984 -224.498154) (xy 367.40211 -224.520252) (xy 367.607088 -224.87509) (xy 367.629948 -224.879408)
			(xy 367.654771 -224.884565) (xy 367.702551 -224.90152) (xy 367.747171 -224.925592) (xy 367.787578 -224.956214)
			(xy 367.822819 -224.992662) (xy 367.852063 -225.034077) (xy 367.874619 -225.079482) (xy 367.889956 -225.127806)
			(xy 367.897711 -225.177908) (xy 367.898172 -225.203258) (xy 367.897664 -225.229165) (xy 367.889558 -225.280342)
			(xy 367.873546 -225.329621) (xy 367.850023 -225.375788) (xy 367.819567 -225.417707) (xy 367.782929 -225.454345)
			(xy 367.74101 -225.484801) (xy 367.694843 -225.508324) (xy 367.645564 -225.524336) (xy 367.594387 -225.532442)
			(xy 367.542573 -225.532442) (xy 367.491396 -225.524336) (xy 367.442117 -225.508324) (xy 367.39595 -225.484801)
			(xy 367.354031 -225.454345) (xy 367.317393 -225.417707) (xy 367.286937 -225.375788) (xy 367.263414 -225.329621)
			(xy 367.247402 -225.280342) (xy 367.239296 -225.229165) (xy 367.238788 -225.203258) (xy 367.239397 -225.175541)
			(xy 367.24871 -225.120895) (xy 367.25733 -225.094546) (xy 367.265204 -225.072448) (xy 367.060226 -224.71761)
			(xy 367.037366 -224.713292) (xy 367.012548 -224.708169) (xy 366.964805 -224.691172) (xy 366.920226 -224.667071)
			(xy 366.87986 -224.636431) (xy 366.844657 -224.599976) (xy 366.815448 -224.558564) (xy 366.792919 -224.51317)
			(xy 366.777601 -224.464863) (xy 366.769855 -224.414781) (xy 366.769396 -224.389442) (xy 366.488472 -224.389442)
			(xy 366.487964 -224.415329) (xy 366.479865 -224.466467) (xy 366.463866 -224.515707) (xy 366.44036 -224.561839)
			(xy 366.409928 -224.603726) (xy 366.373318 -224.640336) (xy 366.331431 -224.670768) (xy 366.285299 -224.694274)
			(xy 366.236059 -224.710273) (xy 366.184921 -224.718372) (xy 366.133147 -224.718372) (xy 366.082009 -224.710273)
			(xy 366.032769 -224.694274) (xy 365.986637 -224.670768) (xy 365.94475 -224.640336) (xy 365.90814 -224.603726)
			(xy 365.877708 -224.561839) (xy 365.854202 -224.515707) (xy 365.838203 -224.466467) (xy 365.830104 -224.415329)
			(xy 365.829596 -224.389442) (xy 365.548672 -224.389442) (xy 365.548125 -224.417149) (xy 365.538941 -224.471796)
			(xy 365.530384 -224.498154) (xy 365.52251 -224.520252) (xy 365.727488 -224.87509) (xy 365.750348 -224.879408)
			(xy 365.775171 -224.884565) (xy 365.822951 -224.90152) (xy 365.867571 -224.925592) (xy 365.907978 -224.956214)
			(xy 365.943219 -224.992662) (xy 365.972463 -225.034077) (xy 365.995019 -225.079482) (xy 366.010356 -225.127806)
			(xy 366.018111 -225.177908) (xy 366.018572 -225.203258) (xy 366.018064 -225.229165) (xy 366.009958 -225.280342)
			(xy 365.993946 -225.329621) (xy 365.970423 -225.375788) (xy 365.939967 -225.417707) (xy 365.903329 -225.454345)
			(xy 365.86141 -225.484801) (xy 365.815243 -225.508324) (xy 365.765964 -225.524336) (xy 365.714787 -225.532442)
			(xy 365.662973 -225.532442) (xy 365.611796 -225.524336) (xy 365.562517 -225.508324) (xy 365.51635 -225.484801)
			(xy 365.474431 -225.454345) (xy 365.437793 -225.417707) (xy 365.407337 -225.375788) (xy 365.383814 -225.329621)
			(xy 365.367802 -225.280342) (xy 365.359696 -225.229165) (xy 365.359188 -225.203258) (xy 365.359797 -225.175541)
			(xy 365.36911 -225.120895) (xy 365.37773 -225.094546) (xy 365.385604 -225.072448) (xy 365.180626 -224.71761)
			(xy 365.157766 -224.713292) (xy 365.132948 -224.708169) (xy 365.085205 -224.691172) (xy 365.040626 -224.667071)
			(xy 365.00026 -224.636431) (xy 364.965057 -224.599976) (xy 364.935848 -224.558564) (xy 364.913319 -224.51317)
			(xy 364.898001 -224.464863) (xy 364.890255 -224.414781) (xy 364.889796 -224.389442) (xy 364.608872 -224.389442)
			(xy 364.608364 -224.415329) (xy 364.600265 -224.466467) (xy 364.584266 -224.515707) (xy 364.56076 -224.561839)
			(xy 364.530328 -224.603726) (xy 364.493718 -224.640336) (xy 364.451831 -224.670768) (xy 364.405699 -224.694274)
			(xy 364.356459 -224.710273) (xy 364.305321 -224.718372) (xy 364.253547 -224.718372) (xy 364.202409 -224.710273)
			(xy 364.153169 -224.694274) (xy 364.107037 -224.670768) (xy 364.06515 -224.640336) (xy 364.02854 -224.603726)
			(xy 363.998108 -224.561839) (xy 363.974602 -224.515707) (xy 363.958603 -224.466467) (xy 363.950504 -224.415329)
			(xy 363.949996 -224.389442) (xy 363.669072 -224.389442) (xy 363.668525 -224.417149) (xy 363.659341 -224.471796)
			(xy 363.650784 -224.498154) (xy 363.64291 -224.520252) (xy 363.847888 -224.87509) (xy 363.870748 -224.879408)
			(xy 363.895571 -224.884565) (xy 363.943351 -224.90152) (xy 363.987971 -224.925592) (xy 364.028378 -224.956214)
			(xy 364.063619 -224.992662) (xy 364.092863 -225.034077) (xy 364.115419 -225.079482) (xy 364.130756 -225.127806)
			(xy 364.138511 -225.177908) (xy 364.138972 -225.203258) (xy 364.138464 -225.229165) (xy 364.130358 -225.280342)
			(xy 364.114346 -225.329621) (xy 364.090823 -225.375788) (xy 364.060367 -225.417707) (xy 364.023729 -225.454345)
			(xy 363.98181 -225.484801) (xy 363.935643 -225.508324) (xy 363.886364 -225.524336) (xy 363.835187 -225.532442)
			(xy 363.783373 -225.532442) (xy 363.732196 -225.524336) (xy 363.682917 -225.508324) (xy 363.63675 -225.484801)
			(xy 363.594831 -225.454345) (xy 363.558193 -225.417707) (xy 363.527737 -225.375788) (xy 363.504214 -225.329621)
			(xy 363.488202 -225.280342) (xy 363.480096 -225.229165) (xy 363.479588 -225.203258) (xy 363.480197 -225.175541)
			(xy 363.48951 -225.120895) (xy 363.49813 -225.094546) (xy 363.506004 -225.072448) (xy 363.301026 -224.71761)
			(xy 363.278166 -224.713292) (xy 363.253348 -224.708169) (xy 363.205605 -224.691172) (xy 363.161026 -224.667071)
			(xy 363.12066 -224.636431) (xy 363.085457 -224.599976) (xy 363.056248 -224.558564) (xy 363.033719 -224.51317)
			(xy 363.018401 -224.464863) (xy 363.010655 -224.414781) (xy 363.010196 -224.389442) (xy 362.729272 -224.389442)
			(xy 362.728764 -224.415329) (xy 362.720665 -224.466467) (xy 362.704666 -224.515707) (xy 362.68116 -224.561839)
			(xy 362.650728 -224.603726) (xy 362.614118 -224.640336) (xy 362.572231 -224.670768) (xy 362.526099 -224.694274)
			(xy 362.476859 -224.710273) (xy 362.425721 -224.718372) (xy 362.373947 -224.718372) (xy 362.322809 -224.710273)
			(xy 362.273569 -224.694274) (xy 362.227437 -224.670768) (xy 362.18555 -224.640336) (xy 362.14894 -224.603726)
			(xy 362.118508 -224.561839) (xy 362.095002 -224.515707) (xy 362.079003 -224.466467) (xy 362.070904 -224.415329)
			(xy 362.070396 -224.389442) (xy 361.789472 -224.389442) (xy 361.788925 -224.417149) (xy 361.779741 -224.471796)
			(xy 361.771184 -224.498154) (xy 361.76331 -224.520252) (xy 361.968288 -224.87509) (xy 361.991148 -224.879408)
			(xy 362.015971 -224.884565) (xy 362.063751 -224.90152) (xy 362.108371 -224.925592) (xy 362.148778 -224.956214)
			(xy 362.184019 -224.992662) (xy 362.213263 -225.034077) (xy 362.235819 -225.079482) (xy 362.251156 -225.127806)
			(xy 362.258911 -225.177908) (xy 362.259372 -225.203258) (xy 362.258864 -225.229165) (xy 362.250758 -225.280342)
			(xy 362.234746 -225.329621) (xy 362.211223 -225.375788) (xy 362.180767 -225.417707) (xy 362.144129 -225.454345)
			(xy 362.10221 -225.484801) (xy 362.056043 -225.508324) (xy 362.006764 -225.524336) (xy 361.955587 -225.532442)
			(xy 361.903773 -225.532442) (xy 361.852596 -225.524336) (xy 361.803317 -225.508324) (xy 361.75715 -225.484801)
			(xy 361.715231 -225.454345) (xy 361.678593 -225.417707) (xy 361.648137 -225.375788) (xy 361.624614 -225.329621)
			(xy 361.608602 -225.280342) (xy 361.600496 -225.229165) (xy 361.599988 -225.203258) (xy 361.600597 -225.175541)
			(xy 361.60991 -225.120895) (xy 361.61853 -225.094546) (xy 361.626404 -225.072448) (xy 361.421426 -224.71761)
			(xy 361.398566 -224.713292) (xy 361.373748 -224.708169) (xy 361.326005 -224.691172) (xy 361.281426 -224.667071)
			(xy 361.24106 -224.636431) (xy 361.205857 -224.599976) (xy 361.176648 -224.558564) (xy 361.154119 -224.51317)
			(xy 361.138801 -224.464863) (xy 361.131055 -224.414781) (xy 361.130596 -224.389442) (xy 360.849672 -224.389442)
			(xy 360.849164 -224.415329) (xy 360.841065 -224.466467) (xy 360.825066 -224.515707) (xy 360.80156 -224.561839)
			(xy 360.771128 -224.603726) (xy 360.734518 -224.640336) (xy 360.692631 -224.670768) (xy 360.646499 -224.694274)
			(xy 360.597259 -224.710273) (xy 360.546121 -224.718372) (xy 360.494347 -224.718372) (xy 360.443209 -224.710273)
			(xy 360.393969 -224.694274) (xy 360.347837 -224.670768) (xy 360.30595 -224.640336) (xy 360.26934 -224.603726)
			(xy 360.238908 -224.561839) (xy 360.215402 -224.515707) (xy 360.199403 -224.466467) (xy 360.191304 -224.415329)
			(xy 360.190796 -224.389442) (xy 359.909872 -224.389442) (xy 359.909325 -224.417149) (xy 359.900141 -224.471796)
			(xy 359.891584 -224.498154) (xy 359.88371 -224.520252) (xy 360.088688 -224.87509) (xy 360.111548 -224.879408)
			(xy 360.136371 -224.884565) (xy 360.184151 -224.90152) (xy 360.228771 -224.925592) (xy 360.269178 -224.956214)
			(xy 360.304419 -224.992662) (xy 360.333663 -225.034077) (xy 360.356219 -225.079482) (xy 360.371556 -225.127806)
			(xy 360.379311 -225.177908) (xy 360.379772 -225.203258) (xy 360.379264 -225.229165) (xy 360.371158 -225.280342)
			(xy 360.355146 -225.329621) (xy 360.331623 -225.375788) (xy 360.301167 -225.417707) (xy 360.264529 -225.454345)
			(xy 360.22261 -225.484801) (xy 360.176443 -225.508324) (xy 360.127164 -225.524336) (xy 360.075987 -225.532442)
			(xy 360.024173 -225.532442) (xy 359.972996 -225.524336) (xy 359.923717 -225.508324) (xy 359.87755 -225.484801)
			(xy 359.835631 -225.454345) (xy 359.798993 -225.417707) (xy 359.768537 -225.375788) (xy 359.745014 -225.329621)
			(xy 359.729002 -225.280342) (xy 359.720896 -225.229165) (xy 359.720388 -225.203258) (xy 359.720997 -225.175541)
			(xy 359.73031 -225.120895) (xy 359.73893 -225.094546) (xy 359.746804 -225.072448) (xy 359.541826 -224.71761)
			(xy 359.518966 -224.713292) (xy 359.494148 -224.708169) (xy 359.446405 -224.691172) (xy 359.401826 -224.667071)
			(xy 359.36146 -224.636431) (xy 359.326257 -224.599976) (xy 359.297048 -224.558564) (xy 359.274519 -224.51317)
			(xy 359.259201 -224.464863) (xy 359.251455 -224.414781) (xy 359.250996 -224.389442) (xy 358.970072 -224.389442)
			(xy 358.969564 -224.415329) (xy 358.961465 -224.466467) (xy 358.945466 -224.515707) (xy 358.92196 -224.561839)
			(xy 358.891528 -224.603726) (xy 358.854918 -224.640336) (xy 358.813031 -224.670768) (xy 358.766899 -224.694274)
			(xy 358.717659 -224.710273) (xy 358.666521 -224.718372) (xy 358.614747 -224.718372) (xy 358.563609 -224.710273)
			(xy 358.514369 -224.694274) (xy 358.468237 -224.670768) (xy 358.42635 -224.640336) (xy 358.38974 -224.603726)
			(xy 358.359308 -224.561839) (xy 358.335802 -224.515707) (xy 358.319803 -224.466467) (xy 358.311704 -224.415329)
			(xy 358.311196 -224.389442) (xy 358.030272 -224.389442) (xy 358.029725 -224.417149) (xy 358.020541 -224.471796)
			(xy 358.011984 -224.498154) (xy 358.00411 -224.520252) (xy 358.209088 -224.87509) (xy 358.231948 -224.879408)
			(xy 358.256771 -224.884565) (xy 358.304551 -224.90152) (xy 358.349171 -224.925592) (xy 358.389578 -224.956214)
			(xy 358.424819 -224.992662) (xy 358.454063 -225.034077) (xy 358.476619 -225.079482) (xy 358.491956 -225.127806)
			(xy 358.499711 -225.177908) (xy 358.500172 -225.203258) (xy 358.499664 -225.229165) (xy 358.491558 -225.280342)
			(xy 358.475546 -225.329621) (xy 358.452023 -225.375788) (xy 358.421567 -225.417707) (xy 358.384929 -225.454345)
			(xy 358.34301 -225.484801) (xy 358.296843 -225.508324) (xy 358.247564 -225.524336) (xy 358.196387 -225.532442)
			(xy 358.144573 -225.532442) (xy 358.093396 -225.524336) (xy 358.044117 -225.508324) (xy 357.99795 -225.484801)
			(xy 357.956031 -225.454345) (xy 357.919393 -225.417707) (xy 357.888937 -225.375788) (xy 357.865414 -225.329621)
			(xy 357.849402 -225.280342) (xy 357.841296 -225.229165) (xy 357.840788 -225.203258) (xy 357.841397 -225.175541)
			(xy 357.85071 -225.120895) (xy 357.85933 -225.094546) (xy 357.867204 -225.072448) (xy 357.662226 -224.71761)
			(xy 357.639366 -224.713292) (xy 357.614548 -224.708169) (xy 357.566805 -224.691172) (xy 357.522226 -224.667071)
			(xy 357.48186 -224.636431) (xy 357.446657 -224.599976) (xy 357.417448 -224.558564) (xy 357.394919 -224.51317)
			(xy 357.379601 -224.464863) (xy 357.371855 -224.414781) (xy 357.371396 -224.389442) (xy 357.090472 -224.389442)
			(xy 357.089964 -224.415329) (xy 357.081865 -224.466467) (xy 357.065866 -224.515707) (xy 357.04236 -224.561839)
			(xy 357.011928 -224.603726) (xy 356.975318 -224.640336) (xy 356.933431 -224.670768) (xy 356.887299 -224.694274)
			(xy 356.838059 -224.710273) (xy 356.786921 -224.718372) (xy 356.735147 -224.718372) (xy 356.684009 -224.710273)
			(xy 356.634769 -224.694274) (xy 356.588637 -224.670768) (xy 356.54675 -224.640336) (xy 356.51014 -224.603726)
			(xy 356.479708 -224.561839) (xy 356.456202 -224.515707) (xy 356.440203 -224.466467) (xy 356.432104 -224.415329)
			(xy 356.431596 -224.389442) (xy 356.150672 -224.389442) (xy 356.150125 -224.417149) (xy 356.140941 -224.471796)
			(xy 356.132384 -224.498154) (xy 356.12451 -224.520252) (xy 356.329488 -224.87509) (xy 356.352348 -224.879408)
			(xy 356.377171 -224.884565) (xy 356.424951 -224.90152) (xy 356.469571 -224.925592) (xy 356.509978 -224.956214)
			(xy 356.545219 -224.992662) (xy 356.574463 -225.034077) (xy 356.597019 -225.079482) (xy 356.612356 -225.127806)
			(xy 356.620111 -225.177908) (xy 356.620572 -225.203258) (xy 356.620064 -225.229165) (xy 356.611958 -225.280342)
			(xy 356.595946 -225.329621) (xy 356.572423 -225.375788) (xy 356.541967 -225.417707) (xy 356.505329 -225.454345)
			(xy 356.46341 -225.484801) (xy 356.417243 -225.508324) (xy 356.367964 -225.524336) (xy 356.316787 -225.532442)
			(xy 356.264973 -225.532442) (xy 356.213796 -225.524336) (xy 356.164517 -225.508324) (xy 356.11835 -225.484801)
			(xy 356.076431 -225.454345) (xy 356.039793 -225.417707) (xy 356.009337 -225.375788) (xy 355.985814 -225.329621)
			(xy 355.969802 -225.280342) (xy 355.961696 -225.229165) (xy 355.961188 -225.203258) (xy 355.961797 -225.175541)
			(xy 355.97111 -225.120895) (xy 355.97973 -225.094546) (xy 355.987604 -225.072448) (xy 355.782626 -224.71761)
			(xy 355.759766 -224.713292) (xy 355.734948 -224.708169) (xy 355.687205 -224.691172) (xy 355.642626 -224.667071)
			(xy 355.60226 -224.636431) (xy 355.567057 -224.599976) (xy 355.537848 -224.558564) (xy 355.515319 -224.51317)
			(xy 355.500001 -224.464863) (xy 355.492255 -224.414781) (xy 355.491796 -224.389442) (xy 355.210872 -224.389442)
			(xy 355.210364 -224.415329) (xy 355.202265 -224.466467) (xy 355.186266 -224.515707) (xy 355.16276 -224.561839)
			(xy 355.132328 -224.603726) (xy 355.095718 -224.640336) (xy 355.053831 -224.670768) (xy 355.007699 -224.694274)
			(xy 354.958459 -224.710273) (xy 354.907321 -224.718372) (xy 354.855547 -224.718372) (xy 354.804409 -224.710273)
			(xy 354.755169 -224.694274) (xy 354.709037 -224.670768) (xy 354.66715 -224.640336) (xy 354.63054 -224.603726)
			(xy 354.600108 -224.561839) (xy 354.576602 -224.515707) (xy 354.560603 -224.466467) (xy 354.552504 -224.415329)
			(xy 354.551996 -224.389442) (xy 354.271072 -224.389442) (xy 354.270525 -224.417149) (xy 354.261341 -224.471796)
			(xy 354.252784 -224.498154) (xy 354.24491 -224.520252) (xy 354.449888 -224.87509) (xy 354.472748 -224.879408)
			(xy 354.497571 -224.884565) (xy 354.545351 -224.90152) (xy 354.589971 -224.925592) (xy 354.630378 -224.956214)
			(xy 354.665619 -224.992662) (xy 354.694863 -225.034077) (xy 354.717419 -225.079482) (xy 354.732756 -225.127806)
			(xy 354.740511 -225.177908) (xy 354.740972 -225.203258) (xy 354.740464 -225.229165) (xy 354.732358 -225.280342)
			(xy 354.716346 -225.329621) (xy 354.692823 -225.375788) (xy 354.662367 -225.417707) (xy 354.625729 -225.454345)
			(xy 354.58381 -225.484801) (xy 354.537643 -225.508324) (xy 354.488364 -225.524336) (xy 354.437187 -225.532442)
			(xy 354.385373 -225.532442) (xy 354.334196 -225.524336) (xy 354.284917 -225.508324) (xy 354.23875 -225.484801)
			(xy 354.196831 -225.454345) (xy 354.160193 -225.417707) (xy 354.129737 -225.375788) (xy 354.106214 -225.329621)
			(xy 354.090202 -225.280342) (xy 354.082096 -225.229165) (xy 354.081588 -225.203258) (xy 354.082197 -225.175541)
			(xy 354.09151 -225.120895) (xy 354.10013 -225.094546) (xy 354.108004 -225.072448) (xy 353.903026 -224.71761)
			(xy 353.880166 -224.713292) (xy 353.855348 -224.708169) (xy 353.807605 -224.691172) (xy 353.763026 -224.667071)
			(xy 353.72266 -224.636431) (xy 353.687457 -224.599976) (xy 353.658248 -224.558564) (xy 353.635719 -224.51317)
			(xy 353.620401 -224.464863) (xy 353.612655 -224.414781) (xy 353.612196 -224.389442) (xy 353.331272 -224.389442)
			(xy 353.330764 -224.415329) (xy 353.322665 -224.466467) (xy 353.306666 -224.515707) (xy 353.28316 -224.561839)
			(xy 353.252728 -224.603726) (xy 353.216118 -224.640336) (xy 353.174231 -224.670768) (xy 353.128099 -224.694274)
			(xy 353.078859 -224.710273) (xy 353.027721 -224.718372) (xy 352.975947 -224.718372) (xy 352.924809 -224.710273)
			(xy 352.875569 -224.694274) (xy 352.829437 -224.670768) (xy 352.78755 -224.640336) (xy 352.75094 -224.603726)
			(xy 352.720508 -224.561839) (xy 352.697002 -224.515707) (xy 352.681003 -224.466467) (xy 352.672904 -224.415329)
			(xy 352.672396 -224.389442) (xy 352.391472 -224.389442) (xy 352.390925 -224.417149) (xy 352.381741 -224.471796)
			(xy 352.373184 -224.498154) (xy 352.36531 -224.520252) (xy 352.570288 -224.87509) (xy 352.593148 -224.879408)
			(xy 352.617971 -224.884565) (xy 352.665751 -224.90152) (xy 352.710371 -224.925592) (xy 352.750778 -224.956214)
			(xy 352.786019 -224.992662) (xy 352.815263 -225.034077) (xy 352.837819 -225.079482) (xy 352.853156 -225.127806)
			(xy 352.860911 -225.177908) (xy 352.861372 -225.203258) (xy 352.860864 -225.229165) (xy 352.852758 -225.280342)
			(xy 352.836746 -225.329621) (xy 352.813223 -225.375788) (xy 352.782767 -225.417707) (xy 352.746129 -225.454345)
			(xy 352.70421 -225.484801) (xy 352.658043 -225.508324) (xy 352.608764 -225.524336) (xy 352.557587 -225.532442)
			(xy 352.505773 -225.532442) (xy 352.454596 -225.524336) (xy 352.405317 -225.508324) (xy 352.35915 -225.484801)
			(xy 352.317231 -225.454345) (xy 352.280593 -225.417707) (xy 352.250137 -225.375788) (xy 352.226614 -225.329621)
			(xy 352.210602 -225.280342) (xy 352.202496 -225.229165) (xy 352.201988 -225.203258) (xy 352.202597 -225.175541)
			(xy 352.21191 -225.120895) (xy 352.22053 -225.094546) (xy 352.228404 -225.072448) (xy 352.023426 -224.71761)
			(xy 352.000566 -224.713292) (xy 351.975748 -224.708169) (xy 351.928005 -224.691172) (xy 351.883426 -224.667071)
			(xy 351.84306 -224.636431) (xy 351.807857 -224.599976) (xy 351.778648 -224.558564) (xy 351.756119 -224.51317)
			(xy 351.740801 -224.464863) (xy 351.733055 -224.414781) (xy 351.732596 -224.389442) (xy 351.451672 -224.389442)
			(xy 351.451164 -224.415329) (xy 351.443065 -224.466467) (xy 351.427066 -224.515707) (xy 351.40356 -224.561839)
			(xy 351.373128 -224.603726) (xy 351.336518 -224.640336) (xy 351.294631 -224.670768) (xy 351.248499 -224.694274)
			(xy 351.199259 -224.710273) (xy 351.148121 -224.718372) (xy 351.096347 -224.718372) (xy 351.045209 -224.710273)
			(xy 350.995969 -224.694274) (xy 350.949837 -224.670768) (xy 350.90795 -224.640336) (xy 350.87134 -224.603726)
			(xy 350.840908 -224.561839) (xy 350.817402 -224.515707) (xy 350.801403 -224.466467) (xy 350.793304 -224.415329)
			(xy 350.792796 -224.389442) (xy 350.511872 -224.389442) (xy 350.511325 -224.417149) (xy 350.502141 -224.471796)
			(xy 350.493584 -224.498154) (xy 350.48571 -224.520252) (xy 350.690688 -224.87509) (xy 350.713548 -224.879408)
			(xy 350.738371 -224.884565) (xy 350.786151 -224.90152) (xy 350.830771 -224.925592) (xy 350.871178 -224.956214)
			(xy 350.906419 -224.992662) (xy 350.935663 -225.034077) (xy 350.958219 -225.079482) (xy 350.973556 -225.127806)
			(xy 350.981311 -225.177908) (xy 350.981772 -225.203258) (xy 350.981264 -225.229165) (xy 350.973158 -225.280342)
			(xy 350.957146 -225.329621) (xy 350.933623 -225.375788) (xy 350.903167 -225.417707) (xy 350.866529 -225.454345)
			(xy 350.82461 -225.484801) (xy 350.778443 -225.508324) (xy 350.729164 -225.524336) (xy 350.677987 -225.532442)
			(xy 350.626173 -225.532442) (xy 350.574996 -225.524336) (xy 350.525717 -225.508324) (xy 350.47955 -225.484801)
			(xy 350.437631 -225.454345) (xy 350.400993 -225.417707) (xy 350.370537 -225.375788) (xy 350.347014 -225.329621)
			(xy 350.331002 -225.280342) (xy 350.322896 -225.229165) (xy 350.322388 -225.203258) (xy 350.322997 -225.175541)
			(xy 350.33231 -225.120895) (xy 350.34093 -225.094546) (xy 350.348804 -225.072448) (xy 350.143826 -224.71761)
			(xy 350.120966 -224.713292) (xy 350.096148 -224.708169) (xy 350.048405 -224.691172) (xy 350.003826 -224.667071)
			(xy 349.96346 -224.636431) (xy 349.928257 -224.599976) (xy 349.899048 -224.558564) (xy 349.876519 -224.51317)
			(xy 349.861201 -224.464863) (xy 349.853455 -224.414781) (xy 349.852996 -224.389442) (xy 349.572072 -224.389442)
			(xy 349.571564 -224.415329) (xy 349.563465 -224.466467) (xy 349.547466 -224.515707) (xy 349.52396 -224.561839)
			(xy 349.493528 -224.603726) (xy 349.456918 -224.640336) (xy 349.415031 -224.670768) (xy 349.368899 -224.694274)
			(xy 349.319659 -224.710273) (xy 349.268521 -224.718372) (xy 349.216747 -224.718372) (xy 349.165609 -224.710273)
			(xy 349.116369 -224.694274) (xy 349.070237 -224.670768) (xy 349.02835 -224.640336) (xy 348.99174 -224.603726)
			(xy 348.961308 -224.561839) (xy 348.937802 -224.515707) (xy 348.921803 -224.466467) (xy 348.913704 -224.415329)
			(xy 348.913196 -224.389442) (xy 348.632272 -224.389442) (xy 348.631725 -224.417149) (xy 348.622541 -224.471796)
			(xy 348.613984 -224.498154) (xy 348.60611 -224.520252) (xy 348.811088 -224.87509) (xy 348.833948 -224.879408)
			(xy 348.858771 -224.884565) (xy 348.906551 -224.90152) (xy 348.951171 -224.925592) (xy 348.991578 -224.956214)
			(xy 349.026819 -224.992662) (xy 349.056063 -225.034077) (xy 349.078619 -225.079482) (xy 349.093956 -225.127806)
			(xy 349.101711 -225.177908) (xy 349.102172 -225.203258) (xy 349.101664 -225.229165) (xy 349.093558 -225.280342)
			(xy 349.077546 -225.329621) (xy 349.054023 -225.375788) (xy 349.023567 -225.417707) (xy 348.986929 -225.454345)
			(xy 348.94501 -225.484801) (xy 348.898843 -225.508324) (xy 348.849564 -225.524336) (xy 348.798387 -225.532442)
			(xy 348.746573 -225.532442) (xy 348.695396 -225.524336) (xy 348.646117 -225.508324) (xy 348.59995 -225.484801)
			(xy 348.558031 -225.454345) (xy 348.521393 -225.417707) (xy 348.490937 -225.375788) (xy 348.467414 -225.329621)
			(xy 348.451402 -225.280342) (xy 348.443296 -225.229165) (xy 348.442788 -225.203258) (xy 348.443397 -225.175541)
			(xy 348.45271 -225.120895) (xy 348.46133 -225.094546) (xy 348.469204 -225.072448) (xy 348.264226 -224.71761)
			(xy 348.241366 -224.713292) (xy 348.216548 -224.708169) (xy 348.168805 -224.691172) (xy 348.124226 -224.667071)
			(xy 348.08386 -224.636431) (xy 348.048657 -224.599976) (xy 348.019448 -224.558564) (xy 347.996919 -224.51317)
			(xy 347.981601 -224.464863) (xy 347.973855 -224.414781) (xy 347.973396 -224.389442) (xy 347.692472 -224.389442)
			(xy 347.691964 -224.415329) (xy 347.683865 -224.466467) (xy 347.667866 -224.515707) (xy 347.64436 -224.561839)
			(xy 347.613928 -224.603726) (xy 347.577318 -224.640336) (xy 347.535431 -224.670768) (xy 347.489299 -224.694274)
			(xy 347.440059 -224.710273) (xy 347.388921 -224.718372) (xy 347.337147 -224.718372) (xy 347.286009 -224.710273)
			(xy 347.236769 -224.694274) (xy 347.190637 -224.670768) (xy 347.14875 -224.640336) (xy 347.11214 -224.603726)
			(xy 347.081708 -224.561839) (xy 347.058202 -224.515707) (xy 347.042203 -224.466467) (xy 347.034104 -224.415329)
			(xy 347.033596 -224.389442) (xy 346.752672 -224.389442) (xy 346.752125 -224.417149) (xy 346.742941 -224.471796)
			(xy 346.734384 -224.498154) (xy 346.72651 -224.520252) (xy 346.931488 -224.87509) (xy 346.954348 -224.879408)
			(xy 346.979171 -224.884565) (xy 347.026951 -224.90152) (xy 347.071571 -224.925592) (xy 347.111978 -224.956214)
			(xy 347.147219 -224.992662) (xy 347.176463 -225.034077) (xy 347.199019 -225.079482) (xy 347.214356 -225.127806)
			(xy 347.222111 -225.177908) (xy 347.222572 -225.203258) (xy 347.222064 -225.229165) (xy 347.213958 -225.280342)
			(xy 347.197946 -225.329621) (xy 347.174423 -225.375788) (xy 347.143967 -225.417707) (xy 347.107329 -225.454345)
			(xy 347.06541 -225.484801) (xy 347.019243 -225.508324) (xy 346.969964 -225.524336) (xy 346.918787 -225.532442)
			(xy 346.866973 -225.532442) (xy 346.815796 -225.524336) (xy 346.766517 -225.508324) (xy 346.72035 -225.484801)
			(xy 346.678431 -225.454345) (xy 346.641793 -225.417707) (xy 346.611337 -225.375788) (xy 346.587814 -225.329621)
			(xy 346.571802 -225.280342) (xy 346.563696 -225.229165) (xy 346.563188 -225.203258) (xy 346.563797 -225.175541)
			(xy 346.57311 -225.120895) (xy 346.58173 -225.094546) (xy 346.589604 -225.072448) (xy 346.384626 -224.71761)
			(xy 346.361766 -224.713292) (xy 346.336948 -224.708169) (xy 346.289205 -224.691172) (xy 346.244626 -224.667071)
			(xy 346.20426 -224.636431) (xy 346.169057 -224.599976) (xy 346.139848 -224.558564) (xy 346.117319 -224.51317)
			(xy 346.102001 -224.464863) (xy 346.094255 -224.414781) (xy 346.093796 -224.389442) (xy 345.812872 -224.389442)
			(xy 345.812364 -224.415329) (xy 345.804265 -224.466467) (xy 345.788266 -224.515707) (xy 345.76476 -224.561839)
			(xy 345.734328 -224.603726) (xy 345.697718 -224.640336) (xy 345.655831 -224.670768) (xy 345.609699 -224.694274)
			(xy 345.560459 -224.710273) (xy 345.509321 -224.718372) (xy 345.457547 -224.718372) (xy 345.406409 -224.710273)
			(xy 345.357169 -224.694274) (xy 345.311037 -224.670768) (xy 345.26915 -224.640336) (xy 345.23254 -224.603726)
			(xy 345.202108 -224.561839) (xy 345.178602 -224.515707) (xy 345.162603 -224.466467) (xy 345.154504 -224.415329)
			(xy 345.153996 -224.389442) (xy 344.873072 -224.389442) (xy 344.872525 -224.417149) (xy 344.863341 -224.471796)
			(xy 344.854784 -224.498154) (xy 344.84691 -224.520252) (xy 345.051888 -224.87509) (xy 345.074748 -224.879408)
			(xy 345.099571 -224.884565) (xy 345.147351 -224.90152) (xy 345.191971 -224.925592) (xy 345.232378 -224.956214)
			(xy 345.267619 -224.992662) (xy 345.296863 -225.034077) (xy 345.319419 -225.079482) (xy 345.334756 -225.127806)
			(xy 345.342511 -225.177908) (xy 345.342972 -225.203258) (xy 345.342464 -225.229165) (xy 345.334358 -225.280342)
			(xy 345.318346 -225.329621) (xy 345.294823 -225.375788) (xy 345.264367 -225.417707) (xy 345.227729 -225.454345)
			(xy 345.18581 -225.484801) (xy 345.139643 -225.508324) (xy 345.090364 -225.524336) (xy 345.039187 -225.532442)
			(xy 344.987373 -225.532442) (xy 344.936196 -225.524336) (xy 344.886917 -225.508324) (xy 344.84075 -225.484801)
			(xy 344.798831 -225.454345) (xy 344.762193 -225.417707) (xy 344.731737 -225.375788) (xy 344.708214 -225.329621)
			(xy 344.692202 -225.280342) (xy 344.684096 -225.229165) (xy 344.683588 -225.203258) (xy 344.684197 -225.175541)
			(xy 344.69351 -225.120895) (xy 344.70213 -225.094546) (xy 344.710004 -225.072448) (xy 344.505026 -224.71761)
			(xy 344.482166 -224.713292) (xy 344.457348 -224.708169) (xy 344.409605 -224.691172) (xy 344.365026 -224.667071)
			(xy 344.32466 -224.636431) (xy 344.289457 -224.599976) (xy 344.260248 -224.558564) (xy 344.237719 -224.51317)
			(xy 344.222401 -224.464863) (xy 344.214655 -224.414781) (xy 344.214196 -224.389442) (xy 343.933272 -224.389442)
			(xy 343.932764 -224.415329) (xy 343.924665 -224.466467) (xy 343.908666 -224.515707) (xy 343.88516 -224.561839)
			(xy 343.854728 -224.603726) (xy 343.818118 -224.640336) (xy 343.776231 -224.670768) (xy 343.730099 -224.694274)
			(xy 343.680859 -224.710273) (xy 343.629721 -224.718372) (xy 343.577947 -224.718372) (xy 343.526809 -224.710273)
			(xy 343.477569 -224.694274) (xy 343.431437 -224.670768) (xy 343.38955 -224.640336) (xy 343.35294 -224.603726)
			(xy 343.322508 -224.561839) (xy 343.299002 -224.515707) (xy 343.283003 -224.466467) (xy 343.274904 -224.415329)
			(xy 343.274396 -224.389442) (xy 342.993472 -224.389442) (xy 342.992925 -224.417149) (xy 342.983741 -224.471796)
			(xy 342.975184 -224.498154) (xy 342.96731 -224.520252) (xy 343.172288 -224.87509) (xy 343.195148 -224.879408)
			(xy 343.219971 -224.884565) (xy 343.267751 -224.90152) (xy 343.312371 -224.925592) (xy 343.352778 -224.956214)
			(xy 343.388019 -224.992662) (xy 343.417263 -225.034077) (xy 343.439819 -225.079482) (xy 343.455156 -225.127806)
			(xy 343.462911 -225.177908) (xy 343.463372 -225.203258) (xy 343.462864 -225.229165) (xy 343.454758 -225.280342)
			(xy 343.438746 -225.329621) (xy 343.415223 -225.375788) (xy 343.384767 -225.417707) (xy 343.348129 -225.454345)
			(xy 343.30621 -225.484801) (xy 343.260043 -225.508324) (xy 343.210764 -225.524336) (xy 343.159587 -225.532442)
			(xy 343.107773 -225.532442) (xy 343.056596 -225.524336) (xy 343.007317 -225.508324) (xy 342.96115 -225.484801)
			(xy 342.919231 -225.454345) (xy 342.882593 -225.417707) (xy 342.852137 -225.375788) (xy 342.828614 -225.329621)
			(xy 342.812602 -225.280342) (xy 342.804496 -225.229165) (xy 342.803988 -225.203258) (xy 342.804597 -225.175541)
			(xy 342.81391 -225.120895) (xy 342.82253 -225.094546) (xy 342.830404 -225.072448) (xy 342.625426 -224.71761)
			(xy 342.602566 -224.713292) (xy 342.577748 -224.708169) (xy 342.530005 -224.691172) (xy 342.485426 -224.667071)
			(xy 342.44506 -224.636431) (xy 342.409857 -224.599976) (xy 342.380648 -224.558564) (xy 342.358119 -224.51317)
			(xy 342.342801 -224.464863) (xy 342.335055 -224.414781) (xy 342.334596 -224.389442) (xy 342.053672 -224.389442)
			(xy 342.053164 -224.415329) (xy 342.045065 -224.466467) (xy 342.029066 -224.515707) (xy 342.00556 -224.561839)
			(xy 341.975128 -224.603726) (xy 341.938518 -224.640336) (xy 341.896631 -224.670768) (xy 341.850499 -224.694274)
			(xy 341.801259 -224.710273) (xy 341.750121 -224.718372) (xy 341.698347 -224.718372) (xy 341.647209 -224.710273)
			(xy 341.597969 -224.694274) (xy 341.551837 -224.670768) (xy 341.50995 -224.640336) (xy 341.47334 -224.603726)
			(xy 341.442908 -224.561839) (xy 341.419402 -224.515707) (xy 341.403403 -224.466467) (xy 341.395304 -224.415329)
			(xy 341.394796 -224.389442) (xy 341.113872 -224.389442) (xy 341.113872 -224.38995) (xy 341.113311 -224.417593)
			(xy 341.104122 -224.472111) (xy 341.095584 -224.498408) (xy 341.087964 -224.520252) (xy 341.292688 -224.87509)
			(xy 341.315548 -224.879408) (xy 341.340371 -224.884565) (xy 341.388151 -224.90152) (xy 341.432771 -224.925592)
			(xy 341.473178 -224.956214) (xy 341.508419 -224.992662) (xy 341.537663 -225.034077) (xy 341.560219 -225.079482)
			(xy 341.575556 -225.127806) (xy 341.583311 -225.177908) (xy 341.583772 -225.203258) (xy 341.583264 -225.229165)
			(xy 341.575158 -225.280342) (xy 341.559146 -225.329621) (xy 341.535623 -225.375788) (xy 341.505167 -225.417707)
			(xy 341.468529 -225.454345) (xy 341.42661 -225.484801) (xy 341.380443 -225.508324) (xy 341.331164 -225.524336)
			(xy 341.279987 -225.532442) (xy 341.228173 -225.532442) (xy 341.176996 -225.524336) (xy 341.127717 -225.508324)
			(xy 341.08155 -225.484801) (xy 341.039631 -225.454345) (xy 341.002993 -225.417707) (xy 340.972537 -225.375788)
			(xy 340.949014 -225.329621) (xy 340.933002 -225.280342) (xy 340.924896 -225.229165) (xy 340.924388 -225.203258)
			(xy 340.924388 -225.20275) (xy 340.924995 -225.175096) (xy 340.93432 -225.120578) (xy 340.94293 -225.094292)
			(xy 340.95055 -225.072448) (xy 340.745826 -224.71761) (xy 340.722966 -224.713292) (xy 340.698148 -224.708169)
			(xy 340.650405 -224.691172) (xy 340.605826 -224.667071) (xy 340.56546 -224.636431) (xy 340.530257 -224.599976)
			(xy 340.501048 -224.558564) (xy 340.478519 -224.51317) (xy 340.463201 -224.464863) (xy 340.455455 -224.414781)
			(xy 340.454996 -224.389442) (xy 340.174072 -224.389442) (xy 340.173564 -224.415329) (xy 340.165465 -224.466467)
			(xy 340.149466 -224.515707) (xy 340.12596 -224.561839) (xy 340.095528 -224.603726) (xy 340.058918 -224.640336)
			(xy 340.017031 -224.670768) (xy 339.970899 -224.694274) (xy 339.921659 -224.710273) (xy 339.870521 -224.718372)
			(xy 339.818747 -224.718372) (xy 339.767609 -224.710273) (xy 339.718369 -224.694274) (xy 339.672237 -224.670768)
			(xy 339.63035 -224.640336) (xy 339.59374 -224.603726) (xy 339.563308 -224.561839) (xy 339.539802 -224.515707)
			(xy 339.523803 -224.466467) (xy 339.515704 -224.415329) (xy 339.515196 -224.389442) (xy 339.234272 -224.389442)
			(xy 339.234272 -224.38995) (xy 339.233711 -224.417593) (xy 339.224522 -224.472111) (xy 339.215984 -224.498408)
			(xy 339.208364 -224.520252) (xy 339.413088 -224.87509) (xy 339.435948 -224.879408) (xy 339.460771 -224.884565)
			(xy 339.508551 -224.90152) (xy 339.553171 -224.925592) (xy 339.593578 -224.956214) (xy 339.628819 -224.992662)
			(xy 339.658063 -225.034077) (xy 339.680619 -225.079482) (xy 339.695956 -225.127806) (xy 339.703711 -225.177908)
			(xy 339.704172 -225.203258) (xy 339.703664 -225.229165) (xy 339.695558 -225.280342) (xy 339.679546 -225.329621)
			(xy 339.656023 -225.375788) (xy 339.625567 -225.417707) (xy 339.588929 -225.454345) (xy 339.54701 -225.484801)
			(xy 339.500843 -225.508324) (xy 339.451564 -225.524336) (xy 339.400387 -225.532442) (xy 339.348573 -225.532442)
			(xy 339.297396 -225.524336) (xy 339.248117 -225.508324) (xy 339.20195 -225.484801) (xy 339.160031 -225.454345)
			(xy 339.123393 -225.417707) (xy 339.092937 -225.375788) (xy 339.069414 -225.329621) (xy 339.053402 -225.280342)
			(xy 339.045296 -225.229165) (xy 339.044788 -225.203258) (xy 339.044788 -225.20275) (xy 339.045395 -225.175096)
			(xy 339.05472 -225.120578) (xy 339.06333 -225.094292) (xy 339.07095 -225.072448) (xy 338.866226 -224.71761)
			(xy 338.843366 -224.713292) (xy 338.818548 -224.708169) (xy 338.770805 -224.691172) (xy 338.726226 -224.667071)
			(xy 338.68586 -224.636431) (xy 338.650657 -224.599976) (xy 338.621448 -224.558564) (xy 338.598919 -224.51317)
			(xy 338.583601 -224.464863) (xy 338.575855 -224.414781) (xy 338.575396 -224.389442) (xy 338.294472 -224.389442)
			(xy 338.293964 -224.415329) (xy 338.285865 -224.466467) (xy 338.269866 -224.515707) (xy 338.24636 -224.561839)
			(xy 338.215928 -224.603726) (xy 338.179318 -224.640336) (xy 338.137431 -224.670768) (xy 338.091299 -224.694274)
			(xy 338.042059 -224.710273) (xy 337.990921 -224.718372) (xy 337.939147 -224.718372) (xy 337.888009 -224.710273)
			(xy 337.838769 -224.694274) (xy 337.792637 -224.670768) (xy 337.75075 -224.640336) (xy 337.71414 -224.603726)
			(xy 337.683708 -224.561839) (xy 337.660202 -224.515707) (xy 337.644203 -224.466467) (xy 337.636104 -224.415329)
			(xy 337.635596 -224.389442) (xy 134.525004 -224.389442) (xy 134.524474 -224.41715) (xy 134.515275 -224.471796)
			(xy 134.506716 -224.498154) (xy 134.499096 -224.519998) (xy 134.704074 -224.87509) (xy 134.726934 -224.879408)
			(xy 134.751752 -224.884531) (xy 134.799495 -224.901528) (xy 134.844074 -224.925629) (xy 134.88444 -224.956269)
			(xy 134.919643 -224.992724) (xy 134.948852 -225.034136) (xy 134.971381 -225.07953) (xy 134.986699 -225.127837)
			(xy 134.994445 -225.177919) (xy 134.994904 -225.203258) (xy 134.994396 -225.229145) (xy 134.986297 -225.280283)
			(xy 134.970298 -225.329523) (xy 134.946792 -225.375655) (xy 134.91636 -225.417542) (xy 134.87975 -225.454152)
			(xy 134.837863 -225.484584) (xy 134.791731 -225.50809) (xy 134.742491 -225.524089) (xy 134.691353 -225.532188)
			(xy 134.639579 -225.532188) (xy 134.588441 -225.524089) (xy 134.539201 -225.50809) (xy 134.493069 -225.484584)
			(xy 134.451182 -225.454152) (xy 134.414572 -225.417542) (xy 134.38414 -225.375655) (xy 134.360634 -225.329523)
			(xy 134.344635 -225.280283) (xy 134.336536 -225.229145) (xy 134.336028 -225.203258) (xy 134.336028 -225.20275)
			(xy 134.336589 -225.175107) (xy 134.345778 -225.120589) (xy 134.354316 -225.094292) (xy 134.361936 -225.072448)
			(xy 134.157212 -224.71761) (xy 134.134352 -224.713292) (xy 134.109529 -224.708135) (xy 134.061749 -224.69118)
			(xy 134.017129 -224.667108) (xy 133.976722 -224.636486) (xy 133.941481 -224.600038) (xy 133.912237 -224.558623)
			(xy 133.889681 -224.513218) (xy 133.874344 -224.464894) (xy 133.866589 -224.414792) (xy 133.866128 -224.389442)
			(xy 133.585204 -224.389442) (xy 133.584696 -224.415329) (xy 133.576597 -224.466467) (xy 133.560598 -224.515707)
			(xy 133.537092 -224.561839) (xy 133.50666 -224.603726) (xy 133.47005 -224.640336) (xy 133.428163 -224.670768)
			(xy 133.382031 -224.694274) (xy 133.332791 -224.710273) (xy 133.281653 -224.718372) (xy 133.229879 -224.718372)
			(xy 133.178741 -224.710273) (xy 133.129501 -224.694274) (xy 133.083369 -224.670768) (xy 133.041482 -224.640336)
			(xy 133.004872 -224.603726) (xy 132.97444 -224.561839) (xy 132.950934 -224.515707) (xy 132.934935 -224.466467)
			(xy 132.926836 -224.415329) (xy 132.926328 -224.389442) (xy 132.645404 -224.389442) (xy 132.64486 -224.417149)
			(xy 132.635674 -224.471796) (xy 132.627116 -224.498154) (xy 132.619242 -224.520252) (xy 132.82422 -224.87509)
			(xy 132.84708 -224.879408) (xy 132.871909 -224.884542) (xy 132.919688 -224.901501) (xy 132.964308 -224.925578)
			(xy 133.004714 -224.956202) (xy 133.039954 -224.992654) (xy 133.069197 -225.034071) (xy 133.091752 -225.079478)
			(xy 133.107088 -225.127804) (xy 133.114843 -225.177908) (xy 133.115304 -225.203258) (xy 133.114796 -225.229165)
			(xy 133.10669 -225.280342) (xy 133.090678 -225.329621) (xy 133.067155 -225.375788) (xy 133.036699 -225.417707)
			(xy 133.000061 -225.454345) (xy 132.958142 -225.484801) (xy 132.911975 -225.508324) (xy 132.862696 -225.524336)
			(xy 132.811519 -225.532442) (xy 132.759705 -225.532442) (xy 132.708528 -225.524336) (xy 132.659249 -225.508324)
			(xy 132.613082 -225.484801) (xy 132.571163 -225.454345) (xy 132.534525 -225.417707) (xy 132.504069 -225.375788)
			(xy 132.480546 -225.329621) (xy 132.464534 -225.280342) (xy 132.456428 -225.229165) (xy 132.45592 -225.203258)
			(xy 132.456527 -225.175541) (xy 132.465842 -225.120895) (xy 132.474462 -225.094546) (xy 132.482336 -225.072448)
			(xy 132.277358 -224.71761) (xy 132.254498 -224.713292) (xy 132.229685 -224.708145) (xy 132.181943 -224.691153)
			(xy 132.137363 -224.667056) (xy 132.096996 -224.63642) (xy 132.061793 -224.599968) (xy 132.032582 -224.558558)
			(xy 132.010052 -224.513166) (xy 131.994734 -224.46486) (xy 131.986988 -224.41478) (xy 131.986528 -224.389442)
			(xy 131.705604 -224.389442) (xy 131.705096 -224.415329) (xy 131.696997 -224.466467) (xy 131.680998 -224.515707)
			(xy 131.657492 -224.561839) (xy 131.62706 -224.603726) (xy 131.59045 -224.640336) (xy 131.548563 -224.670768)
			(xy 131.502431 -224.694274) (xy 131.453191 -224.710273) (xy 131.402053 -224.718372) (xy 131.350279 -224.718372)
			(xy 131.299141 -224.710273) (xy 131.249901 -224.694274) (xy 131.203769 -224.670768) (xy 131.161882 -224.640336)
			(xy 131.125272 -224.603726) (xy 131.09484 -224.561839) (xy 131.071334 -224.515707) (xy 131.055335 -224.466467)
			(xy 131.047236 -224.415329) (xy 131.046728 -224.389442) (xy 130.765804 -224.389442) (xy 130.76526 -224.417149)
			(xy 130.756074 -224.471796) (xy 130.747516 -224.498154) (xy 130.739642 -224.520252) (xy 130.94462 -224.87509)
			(xy 130.96748 -224.879408) (xy 130.992309 -224.884542) (xy 131.040088 -224.901501) (xy 131.084708 -224.925578)
			(xy 131.125114 -224.956202) (xy 131.160354 -224.992654) (xy 131.189597 -225.034071) (xy 131.212152 -225.079478)
			(xy 131.227488 -225.127804) (xy 131.235243 -225.177908) (xy 131.235704 -225.203258) (xy 131.235196 -225.229165)
			(xy 131.22709 -225.280342) (xy 131.211078 -225.329621) (xy 131.187555 -225.375788) (xy 131.157099 -225.417707)
			(xy 131.120461 -225.454345) (xy 131.078542 -225.484801) (xy 131.032375 -225.508324) (xy 130.983096 -225.524336)
			(xy 130.931919 -225.532442) (xy 130.880105 -225.532442) (xy 130.828928 -225.524336) (xy 130.779649 -225.508324)
			(xy 130.733482 -225.484801) (xy 130.691563 -225.454345) (xy 130.654925 -225.417707) (xy 130.624469 -225.375788)
			(xy 130.600946 -225.329621) (xy 130.584934 -225.280342) (xy 130.576828 -225.229165) (xy 130.57632 -225.203258)
			(xy 130.576927 -225.175541) (xy 130.586242 -225.120895) (xy 130.594862 -225.094546) (xy 130.602736 -225.072448)
			(xy 130.397758 -224.71761) (xy 130.374898 -224.713292) (xy 130.350085 -224.708145) (xy 130.302343 -224.691153)
			(xy 130.257763 -224.667056) (xy 130.217396 -224.63642) (xy 130.182193 -224.599968) (xy 130.152982 -224.558558)
			(xy 130.130452 -224.513166) (xy 130.115134 -224.46486) (xy 130.107388 -224.41478) (xy 130.106928 -224.389442)
			(xy 129.826004 -224.389442) (xy 129.825496 -224.415329) (xy 129.817397 -224.466467) (xy 129.801398 -224.515707)
			(xy 129.777892 -224.561839) (xy 129.74746 -224.603726) (xy 129.71085 -224.640336) (xy 129.668963 -224.670768)
			(xy 129.622831 -224.694274) (xy 129.573591 -224.710273) (xy 129.522453 -224.718372) (xy 129.470679 -224.718372)
			(xy 129.419541 -224.710273) (xy 129.370301 -224.694274) (xy 129.324169 -224.670768) (xy 129.282282 -224.640336)
			(xy 129.245672 -224.603726) (xy 129.21524 -224.561839) (xy 129.191734 -224.515707) (xy 129.175735 -224.466467)
			(xy 129.167636 -224.415329) (xy 129.167128 -224.389442) (xy 128.886204 -224.389442) (xy 128.88566 -224.417149)
			(xy 128.876474 -224.471796) (xy 128.867916 -224.498154) (xy 128.860042 -224.520252) (xy 129.06502 -224.87509)
			(xy 129.08788 -224.879408) (xy 129.112709 -224.884542) (xy 129.160488 -224.901501) (xy 129.205108 -224.925578)
			(xy 129.245514 -224.956202) (xy 129.280754 -224.992654) (xy 129.309997 -225.034071) (xy 129.332552 -225.079478)
			(xy 129.347888 -225.127804) (xy 129.355643 -225.177908) (xy 129.356104 -225.203258) (xy 129.355596 -225.229165)
			(xy 129.34749 -225.280342) (xy 129.331478 -225.329621) (xy 129.307955 -225.375788) (xy 129.277499 -225.417707)
			(xy 129.240861 -225.454345) (xy 129.198942 -225.484801) (xy 129.152775 -225.508324) (xy 129.103496 -225.524336)
			(xy 129.052319 -225.532442) (xy 129.000505 -225.532442) (xy 128.949328 -225.524336) (xy 128.900049 -225.508324)
			(xy 128.853882 -225.484801) (xy 128.811963 -225.454345) (xy 128.775325 -225.417707) (xy 128.744869 -225.375788)
			(xy 128.721346 -225.329621) (xy 128.705334 -225.280342) (xy 128.697228 -225.229165) (xy 128.69672 -225.203258)
			(xy 128.697327 -225.175541) (xy 128.706642 -225.120895) (xy 128.715262 -225.094546) (xy 128.723136 -225.072448)
			(xy 128.518158 -224.71761) (xy 128.495298 -224.713292) (xy 128.470485 -224.708145) (xy 128.422743 -224.691153)
			(xy 128.378163 -224.667056) (xy 128.337796 -224.63642) (xy 128.302593 -224.599968) (xy 128.273382 -224.558558)
			(xy 128.250852 -224.513166) (xy 128.235534 -224.46486) (xy 128.227788 -224.41478) (xy 128.227328 -224.389442)
			(xy 127.946404 -224.389442) (xy 127.945896 -224.415329) (xy 127.937797 -224.466467) (xy 127.921798 -224.515707)
			(xy 127.898292 -224.561839) (xy 127.86786 -224.603726) (xy 127.83125 -224.640336) (xy 127.789363 -224.670768)
			(xy 127.743231 -224.694274) (xy 127.693991 -224.710273) (xy 127.642853 -224.718372) (xy 127.591079 -224.718372)
			(xy 127.539941 -224.710273) (xy 127.490701 -224.694274) (xy 127.444569 -224.670768) (xy 127.402682 -224.640336)
			(xy 127.366072 -224.603726) (xy 127.33564 -224.561839) (xy 127.312134 -224.515707) (xy 127.296135 -224.466467)
			(xy 127.288036 -224.415329) (xy 127.287528 -224.389442) (xy 127.006604 -224.389442) (xy 127.00606 -224.417149)
			(xy 126.996874 -224.471796) (xy 126.988316 -224.498154) (xy 126.980442 -224.520252) (xy 127.18542 -224.87509)
			(xy 127.20828 -224.879408) (xy 127.233109 -224.884542) (xy 127.280888 -224.901501) (xy 127.325508 -224.925578)
			(xy 127.365914 -224.956202) (xy 127.401154 -224.992654) (xy 127.430397 -225.034071) (xy 127.452952 -225.079478)
			(xy 127.468288 -225.127804) (xy 127.476043 -225.177908) (xy 127.476504 -225.203258) (xy 127.475996 -225.229165)
			(xy 127.46789 -225.280342) (xy 127.451878 -225.329621) (xy 127.428355 -225.375788) (xy 127.397899 -225.417707)
			(xy 127.361261 -225.454345) (xy 127.319342 -225.484801) (xy 127.273175 -225.508324) (xy 127.223896 -225.524336)
			(xy 127.172719 -225.532442) (xy 127.120905 -225.532442) (xy 127.069728 -225.524336) (xy 127.020449 -225.508324)
			(xy 126.974282 -225.484801) (xy 126.932363 -225.454345) (xy 126.895725 -225.417707) (xy 126.865269 -225.375788)
			(xy 126.841746 -225.329621) (xy 126.825734 -225.280342) (xy 126.817628 -225.229165) (xy 126.81712 -225.203258)
			(xy 126.817727 -225.175541) (xy 126.827042 -225.120895) (xy 126.835662 -225.094546) (xy 126.843536 -225.072448)
			(xy 126.638558 -224.71761) (xy 126.615698 -224.713292) (xy 126.590885 -224.708145) (xy 126.543143 -224.691153)
			(xy 126.498563 -224.667056) (xy 126.458196 -224.63642) (xy 126.422993 -224.599968) (xy 126.393782 -224.558558)
			(xy 126.371252 -224.513166) (xy 126.355934 -224.46486) (xy 126.348188 -224.41478) (xy 126.347728 -224.389442)
			(xy 126.066804 -224.389442) (xy 126.066296 -224.415329) (xy 126.058197 -224.466467) (xy 126.042198 -224.515707)
			(xy 126.018692 -224.561839) (xy 125.98826 -224.603726) (xy 125.95165 -224.640336) (xy 125.909763 -224.670768)
			(xy 125.863631 -224.694274) (xy 125.814391 -224.710273) (xy 125.763253 -224.718372) (xy 125.711479 -224.718372)
			(xy 125.660341 -224.710273) (xy 125.611101 -224.694274) (xy 125.564969 -224.670768) (xy 125.523082 -224.640336)
			(xy 125.486472 -224.603726) (xy 125.45604 -224.561839) (xy 125.432534 -224.515707) (xy 125.416535 -224.466467)
			(xy 125.408436 -224.415329) (xy 125.407928 -224.389442) (xy 125.127004 -224.389442) (xy 125.12646 -224.417149)
			(xy 125.117274 -224.471796) (xy 125.108716 -224.498154) (xy 125.100842 -224.520252) (xy 125.30582 -224.87509)
			(xy 125.32868 -224.879408) (xy 125.353509 -224.884542) (xy 125.401288 -224.901501) (xy 125.445908 -224.925578)
			(xy 125.486314 -224.956202) (xy 125.521554 -224.992654) (xy 125.550797 -225.034071) (xy 125.573352 -225.079478)
			(xy 125.588688 -225.127804) (xy 125.596443 -225.177908) (xy 125.596904 -225.203258) (xy 125.596396 -225.229165)
			(xy 125.58829 -225.280342) (xy 125.572278 -225.329621) (xy 125.548755 -225.375788) (xy 125.518299 -225.417707)
			(xy 125.481661 -225.454345) (xy 125.439742 -225.484801) (xy 125.393575 -225.508324) (xy 125.344296 -225.524336)
			(xy 125.293119 -225.532442) (xy 125.241305 -225.532442) (xy 125.190128 -225.524336) (xy 125.140849 -225.508324)
			(xy 125.094682 -225.484801) (xy 125.052763 -225.454345) (xy 125.016125 -225.417707) (xy 124.985669 -225.375788)
			(xy 124.962146 -225.329621) (xy 124.946134 -225.280342) (xy 124.938028 -225.229165) (xy 124.93752 -225.203258)
			(xy 124.938127 -225.175541) (xy 124.947442 -225.120895) (xy 124.956062 -225.094546) (xy 124.963936 -225.072448)
			(xy 124.758958 -224.71761) (xy 124.736098 -224.713292) (xy 124.711285 -224.708145) (xy 124.663543 -224.691153)
			(xy 124.618963 -224.667056) (xy 124.578596 -224.63642) (xy 124.543393 -224.599968) (xy 124.514182 -224.558558)
			(xy 124.491652 -224.513166) (xy 124.476334 -224.46486) (xy 124.468588 -224.41478) (xy 124.468128 -224.389442)
			(xy 124.187204 -224.389442) (xy 124.186696 -224.415329) (xy 124.178597 -224.466467) (xy 124.162598 -224.515707)
			(xy 124.139092 -224.561839) (xy 124.10866 -224.603726) (xy 124.07205 -224.640336) (xy 124.030163 -224.670768)
			(xy 123.984031 -224.694274) (xy 123.934791 -224.710273) (xy 123.883653 -224.718372) (xy 123.831879 -224.718372)
			(xy 123.780741 -224.710273) (xy 123.731501 -224.694274) (xy 123.685369 -224.670768) (xy 123.643482 -224.640336)
			(xy 123.606872 -224.603726) (xy 123.57644 -224.561839) (xy 123.552934 -224.515707) (xy 123.536935 -224.466467)
			(xy 123.528836 -224.415329) (xy 123.528328 -224.389442) (xy 123.247404 -224.389442) (xy 123.24686 -224.417149)
			(xy 123.237674 -224.471796) (xy 123.229116 -224.498154) (xy 123.221242 -224.520252) (xy 123.42622 -224.87509)
			(xy 123.44908 -224.879408) (xy 123.473909 -224.884542) (xy 123.521688 -224.901501) (xy 123.566308 -224.925578)
			(xy 123.606714 -224.956202) (xy 123.641954 -224.992654) (xy 123.671197 -225.034071) (xy 123.693752 -225.079478)
			(xy 123.709088 -225.127804) (xy 123.716843 -225.177908) (xy 123.717304 -225.203258) (xy 123.716796 -225.229165)
			(xy 123.70869 -225.280342) (xy 123.692678 -225.329621) (xy 123.669155 -225.375788) (xy 123.638699 -225.417707)
			(xy 123.602061 -225.454345) (xy 123.560142 -225.484801) (xy 123.513975 -225.508324) (xy 123.464696 -225.524336)
			(xy 123.413519 -225.532442) (xy 123.361705 -225.532442) (xy 123.310528 -225.524336) (xy 123.261249 -225.508324)
			(xy 123.215082 -225.484801) (xy 123.173163 -225.454345) (xy 123.136525 -225.417707) (xy 123.106069 -225.375788)
			(xy 123.082546 -225.329621) (xy 123.066534 -225.280342) (xy 123.058428 -225.229165) (xy 123.05792 -225.203258)
			(xy 123.058527 -225.175541) (xy 123.067842 -225.120895) (xy 123.076462 -225.094546) (xy 123.084336 -225.072448)
			(xy 122.879358 -224.71761) (xy 122.856498 -224.713292) (xy 122.831685 -224.708145) (xy 122.783943 -224.691153)
			(xy 122.739363 -224.667056) (xy 122.698996 -224.63642) (xy 122.663793 -224.599968) (xy 122.634582 -224.558558)
			(xy 122.612052 -224.513166) (xy 122.596734 -224.46486) (xy 122.588988 -224.41478) (xy 122.588528 -224.389442)
			(xy 122.307604 -224.389442) (xy 122.307096 -224.415329) (xy 122.298997 -224.466467) (xy 122.282998 -224.515707)
			(xy 122.259492 -224.561839) (xy 122.22906 -224.603726) (xy 122.19245 -224.640336) (xy 122.150563 -224.670768)
			(xy 122.104431 -224.694274) (xy 122.055191 -224.710273) (xy 122.004053 -224.718372) (xy 121.952279 -224.718372)
			(xy 121.901141 -224.710273) (xy 121.851901 -224.694274) (xy 121.805769 -224.670768) (xy 121.763882 -224.640336)
			(xy 121.727272 -224.603726) (xy 121.69684 -224.561839) (xy 121.673334 -224.515707) (xy 121.657335 -224.466467)
			(xy 121.649236 -224.415329) (xy 121.648728 -224.389442) (xy 121.367804 -224.389442) (xy 121.36726 -224.417149)
			(xy 121.358074 -224.471796) (xy 121.349516 -224.498154) (xy 121.341642 -224.520252) (xy 121.54662 -224.87509)
			(xy 121.56948 -224.879408) (xy 121.594309 -224.884542) (xy 121.642088 -224.901501) (xy 121.686708 -224.925578)
			(xy 121.727114 -224.956202) (xy 121.762354 -224.992654) (xy 121.791597 -225.034071) (xy 121.814152 -225.079478)
			(xy 121.829488 -225.127804) (xy 121.837243 -225.177908) (xy 121.837704 -225.203258) (xy 121.837196 -225.229165)
			(xy 121.82909 -225.280342) (xy 121.813078 -225.329621) (xy 121.789555 -225.375788) (xy 121.759099 -225.417707)
			(xy 121.722461 -225.454345) (xy 121.680542 -225.484801) (xy 121.634375 -225.508324) (xy 121.585096 -225.524336)
			(xy 121.533919 -225.532442) (xy 121.482105 -225.532442) (xy 121.430928 -225.524336) (xy 121.381649 -225.508324)
			(xy 121.335482 -225.484801) (xy 121.293563 -225.454345) (xy 121.256925 -225.417707) (xy 121.226469 -225.375788)
			(xy 121.202946 -225.329621) (xy 121.186934 -225.280342) (xy 121.178828 -225.229165) (xy 121.17832 -225.203258)
			(xy 121.178927 -225.175541) (xy 121.188242 -225.120895) (xy 121.196862 -225.094546) (xy 121.204736 -225.072448)
			(xy 120.999758 -224.71761) (xy 120.976898 -224.713292) (xy 120.952085 -224.708145) (xy 120.904343 -224.691153)
			(xy 120.859763 -224.667056) (xy 120.819396 -224.63642) (xy 120.784193 -224.599968) (xy 120.754982 -224.558558)
			(xy 120.732452 -224.513166) (xy 120.717134 -224.46486) (xy 120.709388 -224.41478) (xy 120.708928 -224.389442)
			(xy 120.428004 -224.389442) (xy 120.427496 -224.415329) (xy 120.419397 -224.466467) (xy 120.403398 -224.515707)
			(xy 120.379892 -224.561839) (xy 120.34946 -224.603726) (xy 120.31285 -224.640336) (xy 120.270963 -224.670768)
			(xy 120.224831 -224.694274) (xy 120.175591 -224.710273) (xy 120.124453 -224.718372) (xy 120.072679 -224.718372)
			(xy 120.021541 -224.710273) (xy 119.972301 -224.694274) (xy 119.926169 -224.670768) (xy 119.884282 -224.640336)
			(xy 119.847672 -224.603726) (xy 119.81724 -224.561839) (xy 119.793734 -224.515707) (xy 119.777735 -224.466467)
			(xy 119.769636 -224.415329) (xy 119.769128 -224.389442) (xy 119.488204 -224.389442) (xy 119.48766 -224.417149)
			(xy 119.478474 -224.471796) (xy 119.469916 -224.498154) (xy 119.462042 -224.520252) (xy 119.66702 -224.87509)
			(xy 119.68988 -224.879408) (xy 119.714709 -224.884542) (xy 119.762488 -224.901501) (xy 119.807108 -224.925578)
			(xy 119.847514 -224.956202) (xy 119.882754 -224.992654) (xy 119.911997 -225.034071) (xy 119.934552 -225.079478)
			(xy 119.949888 -225.127804) (xy 119.957643 -225.177908) (xy 119.958104 -225.203258) (xy 119.957596 -225.229165)
			(xy 119.94949 -225.280342) (xy 119.933478 -225.329621) (xy 119.909955 -225.375788) (xy 119.879499 -225.417707)
			(xy 119.842861 -225.454345) (xy 119.800942 -225.484801) (xy 119.754775 -225.508324) (xy 119.705496 -225.524336)
			(xy 119.654319 -225.532442) (xy 119.602505 -225.532442) (xy 119.551328 -225.524336) (xy 119.502049 -225.508324)
			(xy 119.455882 -225.484801) (xy 119.413963 -225.454345) (xy 119.377325 -225.417707) (xy 119.346869 -225.375788)
			(xy 119.323346 -225.329621) (xy 119.307334 -225.280342) (xy 119.299228 -225.229165) (xy 119.29872 -225.203258)
			(xy 119.299327 -225.175541) (xy 119.308642 -225.120895) (xy 119.317262 -225.094546) (xy 119.325136 -225.072448)
			(xy 119.120158 -224.71761) (xy 119.097298 -224.713292) (xy 119.072485 -224.708145) (xy 119.024743 -224.691153)
			(xy 118.980163 -224.667056) (xy 118.939796 -224.63642) (xy 118.904593 -224.599968) (xy 118.875382 -224.558558)
			(xy 118.852852 -224.513166) (xy 118.837534 -224.46486) (xy 118.829788 -224.41478) (xy 118.829328 -224.389442)
			(xy 118.548404 -224.389442) (xy 118.547896 -224.415329) (xy 118.539797 -224.466467) (xy 118.523798 -224.515707)
			(xy 118.500292 -224.561839) (xy 118.46986 -224.603726) (xy 118.43325 -224.640336) (xy 118.391363 -224.670768)
			(xy 118.345231 -224.694274) (xy 118.295991 -224.710273) (xy 118.244853 -224.718372) (xy 118.193079 -224.718372)
			(xy 118.141941 -224.710273) (xy 118.092701 -224.694274) (xy 118.046569 -224.670768) (xy 118.004682 -224.640336)
			(xy 117.968072 -224.603726) (xy 117.93764 -224.561839) (xy 117.914134 -224.515707) (xy 117.898135 -224.466467)
			(xy 117.890036 -224.415329) (xy 117.889528 -224.389442) (xy 117.608604 -224.389442) (xy 117.60806 -224.417149)
			(xy 117.598874 -224.471796) (xy 117.590316 -224.498154) (xy 117.582442 -224.520252) (xy 117.78742 -224.87509)
			(xy 117.81028 -224.879408) (xy 117.835109 -224.884542) (xy 117.882888 -224.901501) (xy 117.927508 -224.925578)
			(xy 117.967914 -224.956202) (xy 118.003154 -224.992654) (xy 118.032397 -225.034071) (xy 118.054952 -225.079478)
			(xy 118.070288 -225.127804) (xy 118.078043 -225.177908) (xy 118.078504 -225.203258) (xy 118.077996 -225.229165)
			(xy 118.06989 -225.280342) (xy 118.053878 -225.329621) (xy 118.030355 -225.375788) (xy 117.999899 -225.417707)
			(xy 117.963261 -225.454345) (xy 117.921342 -225.484801) (xy 117.875175 -225.508324) (xy 117.825896 -225.524336)
			(xy 117.774719 -225.532442) (xy 117.722905 -225.532442) (xy 117.671728 -225.524336) (xy 117.622449 -225.508324)
			(xy 117.576282 -225.484801) (xy 117.534363 -225.454345) (xy 117.497725 -225.417707) (xy 117.467269 -225.375788)
			(xy 117.443746 -225.329621) (xy 117.427734 -225.280342) (xy 117.419628 -225.229165) (xy 117.41912 -225.203258)
			(xy 117.419727 -225.175541) (xy 117.429042 -225.120895) (xy 117.437662 -225.094546) (xy 117.445536 -225.072448)
			(xy 117.240558 -224.71761) (xy 117.217698 -224.713292) (xy 117.192885 -224.708145) (xy 117.145143 -224.691153)
			(xy 117.100563 -224.667056) (xy 117.060196 -224.63642) (xy 117.024993 -224.599968) (xy 116.995782 -224.558558)
			(xy 116.973252 -224.513166) (xy 116.957934 -224.46486) (xy 116.950188 -224.41478) (xy 116.949728 -224.389442)
			(xy 116.668804 -224.389442) (xy 116.668296 -224.415329) (xy 116.660197 -224.466467) (xy 116.644198 -224.515707)
			(xy 116.620692 -224.561839) (xy 116.59026 -224.603726) (xy 116.55365 -224.640336) (xy 116.511763 -224.670768)
			(xy 116.465631 -224.694274) (xy 116.416391 -224.710273) (xy 116.365253 -224.718372) (xy 116.313479 -224.718372)
			(xy 116.262341 -224.710273) (xy 116.213101 -224.694274) (xy 116.166969 -224.670768) (xy 116.125082 -224.640336)
			(xy 116.088472 -224.603726) (xy 116.05804 -224.561839) (xy 116.034534 -224.515707) (xy 116.018535 -224.466467)
			(xy 116.010436 -224.415329) (xy 116.009928 -224.389442) (xy 115.729004 -224.389442) (xy 115.72846 -224.417149)
			(xy 115.719274 -224.471796) (xy 115.710716 -224.498154) (xy 115.702842 -224.520252) (xy 115.90782 -224.87509)
			(xy 115.93068 -224.879408) (xy 115.955509 -224.884542) (xy 116.003288 -224.901501) (xy 116.047908 -224.925578)
			(xy 116.088314 -224.956202) (xy 116.123554 -224.992654) (xy 116.152797 -225.034071) (xy 116.175352 -225.079478)
			(xy 116.190688 -225.127804) (xy 116.198443 -225.177908) (xy 116.198904 -225.203258) (xy 116.198396 -225.229165)
			(xy 116.19029 -225.280342) (xy 116.174278 -225.329621) (xy 116.150755 -225.375788) (xy 116.120299 -225.417707)
			(xy 116.083661 -225.454345) (xy 116.041742 -225.484801) (xy 115.995575 -225.508324) (xy 115.946296 -225.524336)
			(xy 115.895119 -225.532442) (xy 115.843305 -225.532442) (xy 115.792128 -225.524336) (xy 115.742849 -225.508324)
			(xy 115.696682 -225.484801) (xy 115.654763 -225.454345) (xy 115.618125 -225.417707) (xy 115.587669 -225.375788)
			(xy 115.564146 -225.329621) (xy 115.548134 -225.280342) (xy 115.540028 -225.229165) (xy 115.53952 -225.203258)
			(xy 115.540127 -225.175541) (xy 115.549442 -225.120895) (xy 115.558062 -225.094546) (xy 115.565936 -225.072448)
			(xy 115.360958 -224.71761) (xy 115.338098 -224.713292) (xy 115.313285 -224.708145) (xy 115.265543 -224.691153)
			(xy 115.220963 -224.667056) (xy 115.180596 -224.63642) (xy 115.145393 -224.599968) (xy 115.116182 -224.558558)
			(xy 115.093652 -224.513166) (xy 115.078334 -224.46486) (xy 115.070588 -224.41478) (xy 115.070128 -224.389442)
			(xy 114.789204 -224.389442) (xy 114.788696 -224.415329) (xy 114.780597 -224.466467) (xy 114.764598 -224.515707)
			(xy 114.741092 -224.561839) (xy 114.71066 -224.603726) (xy 114.67405 -224.640336) (xy 114.632163 -224.670768)
			(xy 114.586031 -224.694274) (xy 114.536791 -224.710273) (xy 114.485653 -224.718372) (xy 114.433879 -224.718372)
			(xy 114.382741 -224.710273) (xy 114.333501 -224.694274) (xy 114.287369 -224.670768) (xy 114.245482 -224.640336)
			(xy 114.208872 -224.603726) (xy 114.17844 -224.561839) (xy 114.154934 -224.515707) (xy 114.138935 -224.466467)
			(xy 114.130836 -224.415329) (xy 114.130328 -224.389442) (xy 113.849404 -224.389442) (xy 113.84886 -224.417149)
			(xy 113.839674 -224.471796) (xy 113.831116 -224.498154) (xy 113.823242 -224.520252) (xy 114.02822 -224.87509)
			(xy 114.05108 -224.879408) (xy 114.075909 -224.884542) (xy 114.123688 -224.901501) (xy 114.168308 -224.925578)
			(xy 114.208714 -224.956202) (xy 114.243954 -224.992654) (xy 114.273197 -225.034071) (xy 114.295752 -225.079478)
			(xy 114.311088 -225.127804) (xy 114.318843 -225.177908) (xy 114.319304 -225.203258) (xy 114.318796 -225.229165)
			(xy 114.31069 -225.280342) (xy 114.294678 -225.329621) (xy 114.271155 -225.375788) (xy 114.240699 -225.417707)
			(xy 114.204061 -225.454345) (xy 114.162142 -225.484801) (xy 114.115975 -225.508324) (xy 114.066696 -225.524336)
			(xy 114.015519 -225.532442) (xy 113.963705 -225.532442) (xy 113.912528 -225.524336) (xy 113.863249 -225.508324)
			(xy 113.817082 -225.484801) (xy 113.775163 -225.454345) (xy 113.738525 -225.417707) (xy 113.708069 -225.375788)
			(xy 113.684546 -225.329621) (xy 113.668534 -225.280342) (xy 113.660428 -225.229165) (xy 113.65992 -225.203258)
			(xy 113.660527 -225.175541) (xy 113.669842 -225.120895) (xy 113.678462 -225.094546) (xy 113.686336 -225.072448)
			(xy 113.481358 -224.71761) (xy 113.458498 -224.713292) (xy 113.433685 -224.708145) (xy 113.385943 -224.691153)
			(xy 113.341363 -224.667056) (xy 113.300996 -224.63642) (xy 113.265793 -224.599968) (xy 113.236582 -224.558558)
			(xy 113.214052 -224.513166) (xy 113.198734 -224.46486) (xy 113.190988 -224.41478) (xy 113.190528 -224.389442)
			(xy 112.909604 -224.389442) (xy 112.909096 -224.415329) (xy 112.900997 -224.466467) (xy 112.884998 -224.515707)
			(xy 112.861492 -224.561839) (xy 112.83106 -224.603726) (xy 112.79445 -224.640336) (xy 112.752563 -224.670768)
			(xy 112.706431 -224.694274) (xy 112.657191 -224.710273) (xy 112.606053 -224.718372) (xy 112.554279 -224.718372)
			(xy 112.503141 -224.710273) (xy 112.453901 -224.694274) (xy 112.407769 -224.670768) (xy 112.365882 -224.640336)
			(xy 112.329272 -224.603726) (xy 112.29884 -224.561839) (xy 112.275334 -224.515707) (xy 112.259335 -224.466467)
			(xy 112.251236 -224.415329) (xy 112.250728 -224.389442) (xy 111.969804 -224.389442) (xy 111.96926 -224.417149)
			(xy 111.960074 -224.471796) (xy 111.951516 -224.498154) (xy 111.943642 -224.520252) (xy 112.14862 -224.87509)
			(xy 112.17148 -224.879408) (xy 112.196309 -224.884542) (xy 112.244088 -224.901501) (xy 112.288708 -224.925578)
			(xy 112.329114 -224.956202) (xy 112.364354 -224.992654) (xy 112.393597 -225.034071) (xy 112.416152 -225.079478)
			(xy 112.431488 -225.127804) (xy 112.439243 -225.177908) (xy 112.439704 -225.203258) (xy 112.439196 -225.229165)
			(xy 112.43109 -225.280342) (xy 112.415078 -225.329621) (xy 112.391555 -225.375788) (xy 112.361099 -225.417707)
			(xy 112.324461 -225.454345) (xy 112.282542 -225.484801) (xy 112.236375 -225.508324) (xy 112.187096 -225.524336)
			(xy 112.135919 -225.532442) (xy 112.084105 -225.532442) (xy 112.032928 -225.524336) (xy 111.983649 -225.508324)
			(xy 111.937482 -225.484801) (xy 111.895563 -225.454345) (xy 111.858925 -225.417707) (xy 111.828469 -225.375788)
			(xy 111.804946 -225.329621) (xy 111.788934 -225.280342) (xy 111.780828 -225.229165) (xy 111.78032 -225.203258)
			(xy 111.780927 -225.175541) (xy 111.790242 -225.120895) (xy 111.798862 -225.094546) (xy 111.806736 -225.072448)
			(xy 111.601758 -224.71761) (xy 111.578898 -224.713292) (xy 111.554085 -224.708145) (xy 111.506343 -224.691153)
			(xy 111.461763 -224.667056) (xy 111.421396 -224.63642) (xy 111.386193 -224.599968) (xy 111.356982 -224.558558)
			(xy 111.334452 -224.513166) (xy 111.319134 -224.46486) (xy 111.311388 -224.41478) (xy 111.310928 -224.389442)
			(xy 111.030004 -224.389442) (xy 111.029496 -224.415329) (xy 111.021397 -224.466467) (xy 111.005398 -224.515707)
			(xy 110.981892 -224.561839) (xy 110.95146 -224.603726) (xy 110.91485 -224.640336) (xy 110.872963 -224.670768)
			(xy 110.826831 -224.694274) (xy 110.777591 -224.710273) (xy 110.726453 -224.718372) (xy 110.674679 -224.718372)
			(xy 110.623541 -224.710273) (xy 110.574301 -224.694274) (xy 110.528169 -224.670768) (xy 110.486282 -224.640336)
			(xy 110.449672 -224.603726) (xy 110.41924 -224.561839) (xy 110.395734 -224.515707) (xy 110.379735 -224.466467)
			(xy 110.371636 -224.415329) (xy 110.371128 -224.389442) (xy 110.090204 -224.389442) (xy 110.08966 -224.417149)
			(xy 110.080474 -224.471796) (xy 110.071916 -224.498154) (xy 110.064042 -224.520252) (xy 110.26902 -224.87509)
			(xy 110.29188 -224.879408) (xy 110.316709 -224.884542) (xy 110.364488 -224.901501) (xy 110.409108 -224.925578)
			(xy 110.449514 -224.956202) (xy 110.484754 -224.992654) (xy 110.513997 -225.034071) (xy 110.536552 -225.079478)
			(xy 110.551888 -225.127804) (xy 110.559643 -225.177908) (xy 110.560104 -225.203258) (xy 110.559596 -225.229165)
			(xy 110.55149 -225.280342) (xy 110.535478 -225.329621) (xy 110.511955 -225.375788) (xy 110.481499 -225.417707)
			(xy 110.444861 -225.454345) (xy 110.402942 -225.484801) (xy 110.356775 -225.508324) (xy 110.307496 -225.524336)
			(xy 110.256319 -225.532442) (xy 110.204505 -225.532442) (xy 110.153328 -225.524336) (xy 110.104049 -225.508324)
			(xy 110.057882 -225.484801) (xy 110.015963 -225.454345) (xy 109.979325 -225.417707) (xy 109.948869 -225.375788)
			(xy 109.925346 -225.329621) (xy 109.909334 -225.280342) (xy 109.901228 -225.229165) (xy 109.90072 -225.203258)
			(xy 109.901327 -225.175541) (xy 109.910642 -225.120895) (xy 109.919262 -225.094546) (xy 109.927136 -225.072448)
			(xy 109.722158 -224.71761) (xy 109.699298 -224.713292) (xy 109.674485 -224.708145) (xy 109.626743 -224.691153)
			(xy 109.582163 -224.667056) (xy 109.541796 -224.63642) (xy 109.506593 -224.599968) (xy 109.477382 -224.558558)
			(xy 109.454852 -224.513166) (xy 109.439534 -224.46486) (xy 109.431788 -224.41478) (xy 109.431328 -224.389442)
			(xy 109.150404 -224.389442) (xy 109.149896 -224.415329) (xy 109.141797 -224.466467) (xy 109.125798 -224.515707)
			(xy 109.102292 -224.561839) (xy 109.07186 -224.603726) (xy 109.03525 -224.640336) (xy 108.993363 -224.670768)
			(xy 108.947231 -224.694274) (xy 108.897991 -224.710273) (xy 108.846853 -224.718372) (xy 108.795079 -224.718372)
			(xy 108.743941 -224.710273) (xy 108.694701 -224.694274) (xy 108.648569 -224.670768) (xy 108.606682 -224.640336)
			(xy 108.570072 -224.603726) (xy 108.53964 -224.561839) (xy 108.516134 -224.515707) (xy 108.500135 -224.466467)
			(xy 108.492036 -224.415329) (xy 108.491528 -224.389442) (xy 108.210604 -224.389442) (xy 108.21006 -224.417149)
			(xy 108.200874 -224.471796) (xy 108.192316 -224.498154) (xy 108.184442 -224.520252) (xy 108.38942 -224.87509)
			(xy 108.41228 -224.879408) (xy 108.437109 -224.884542) (xy 108.484888 -224.901501) (xy 108.529508 -224.925578)
			(xy 108.569914 -224.956202) (xy 108.605154 -224.992654) (xy 108.634397 -225.034071) (xy 108.656952 -225.079478)
			(xy 108.672288 -225.127804) (xy 108.680043 -225.177908) (xy 108.680504 -225.203258) (xy 108.679996 -225.229165)
			(xy 108.67189 -225.280342) (xy 108.655878 -225.329621) (xy 108.632355 -225.375788) (xy 108.601899 -225.417707)
			(xy 108.565261 -225.454345) (xy 108.523342 -225.484801) (xy 108.477175 -225.508324) (xy 108.427896 -225.524336)
			(xy 108.376719 -225.532442) (xy 108.324905 -225.532442) (xy 108.273728 -225.524336) (xy 108.224449 -225.508324)
			(xy 108.178282 -225.484801) (xy 108.136363 -225.454345) (xy 108.099725 -225.417707) (xy 108.069269 -225.375788)
			(xy 108.045746 -225.329621) (xy 108.029734 -225.280342) (xy 108.021628 -225.229165) (xy 108.02112 -225.203258)
			(xy 108.021727 -225.175541) (xy 108.031042 -225.120895) (xy 108.039662 -225.094546) (xy 108.047536 -225.072448)
			(xy 107.842558 -224.71761) (xy 107.819698 -224.713292) (xy 107.794885 -224.708145) (xy 107.747143 -224.691153)
			(xy 107.702563 -224.667056) (xy 107.662196 -224.63642) (xy 107.626993 -224.599968) (xy 107.597782 -224.558558)
			(xy 107.575252 -224.513166) (xy 107.559934 -224.46486) (xy 107.552188 -224.41478) (xy 107.551728 -224.389442)
			(xy 107.270804 -224.389442) (xy 107.270296 -224.415329) (xy 107.262197 -224.466467) (xy 107.246198 -224.515707)
			(xy 107.222692 -224.561839) (xy 107.19226 -224.603726) (xy 107.15565 -224.640336) (xy 107.113763 -224.670768)
			(xy 107.067631 -224.694274) (xy 107.018391 -224.710273) (xy 106.967253 -224.718372) (xy 106.915479 -224.718372)
			(xy 106.864341 -224.710273) (xy 106.815101 -224.694274) (xy 106.768969 -224.670768) (xy 106.727082 -224.640336)
			(xy 106.690472 -224.603726) (xy 106.66004 -224.561839) (xy 106.636534 -224.515707) (xy 106.620535 -224.466467)
			(xy 106.612436 -224.415329) (xy 106.611928 -224.389442) (xy 106.331004 -224.389442) (xy 106.33046 -224.417149)
			(xy 106.321274 -224.471796) (xy 106.312716 -224.498154) (xy 106.304842 -224.520252) (xy 106.50982 -224.87509)
			(xy 106.53268 -224.879408) (xy 106.557509 -224.884542) (xy 106.605288 -224.901501) (xy 106.649908 -224.925578)
			(xy 106.690314 -224.956202) (xy 106.725554 -224.992654) (xy 106.754797 -225.034071) (xy 106.777352 -225.079478)
			(xy 106.792688 -225.127804) (xy 106.800443 -225.177908) (xy 106.800904 -225.203258) (xy 106.800396 -225.229165)
			(xy 106.79229 -225.280342) (xy 106.776278 -225.329621) (xy 106.752755 -225.375788) (xy 106.722299 -225.417707)
			(xy 106.685661 -225.454345) (xy 106.643742 -225.484801) (xy 106.597575 -225.508324) (xy 106.548296 -225.524336)
			(xy 106.497119 -225.532442) (xy 106.445305 -225.532442) (xy 106.394128 -225.524336) (xy 106.344849 -225.508324)
			(xy 106.298682 -225.484801) (xy 106.256763 -225.454345) (xy 106.220125 -225.417707) (xy 106.189669 -225.375788)
			(xy 106.166146 -225.329621) (xy 106.150134 -225.280342) (xy 106.142028 -225.229165) (xy 106.14152 -225.203258)
			(xy 106.142127 -225.175541) (xy 106.151442 -225.120895) (xy 106.160062 -225.094546) (xy 106.167936 -225.072448)
			(xy 105.962958 -224.71761) (xy 105.940098 -224.713292) (xy 105.915285 -224.708145) (xy 105.867543 -224.691153)
			(xy 105.822963 -224.667056) (xy 105.782596 -224.63642) (xy 105.747393 -224.599968) (xy 105.718182 -224.558558)
			(xy 105.695652 -224.513166) (xy 105.680334 -224.46486) (xy 105.672588 -224.41478) (xy 105.672128 -224.389442)
			(xy 105.391204 -224.389442) (xy 105.390696 -224.415329) (xy 105.382597 -224.466467) (xy 105.366598 -224.515707)
			(xy 105.343092 -224.561839) (xy 105.31266 -224.603726) (xy 105.27605 -224.640336) (xy 105.234163 -224.670768)
			(xy 105.188031 -224.694274) (xy 105.138791 -224.710273) (xy 105.087653 -224.718372) (xy 105.035879 -224.718372)
			(xy 104.984741 -224.710273) (xy 104.935501 -224.694274) (xy 104.889369 -224.670768) (xy 104.847482 -224.640336)
			(xy 104.810872 -224.603726) (xy 104.78044 -224.561839) (xy 104.756934 -224.515707) (xy 104.740935 -224.466467)
			(xy 104.732836 -224.415329) (xy 104.732328 -224.389442) (xy 104.451404 -224.389442) (xy 104.45086 -224.417149)
			(xy 104.441674 -224.471796) (xy 104.433116 -224.498154) (xy 104.425242 -224.520252) (xy 104.63022 -224.87509)
			(xy 104.65308 -224.879408) (xy 104.677909 -224.884542) (xy 104.725688 -224.901501) (xy 104.770308 -224.925578)
			(xy 104.810714 -224.956202) (xy 104.845954 -224.992654) (xy 104.875197 -225.034071) (xy 104.897752 -225.079478)
			(xy 104.913088 -225.127804) (xy 104.920843 -225.177908) (xy 104.921304 -225.203258) (xy 104.920796 -225.229165)
			(xy 104.91269 -225.280342) (xy 104.896678 -225.329621) (xy 104.873155 -225.375788) (xy 104.842699 -225.417707)
			(xy 104.806061 -225.454345) (xy 104.764142 -225.484801) (xy 104.717975 -225.508324) (xy 104.668696 -225.524336)
			(xy 104.617519 -225.532442) (xy 104.565705 -225.532442) (xy 104.514528 -225.524336) (xy 104.465249 -225.508324)
			(xy 104.419082 -225.484801) (xy 104.377163 -225.454345) (xy 104.340525 -225.417707) (xy 104.310069 -225.375788)
			(xy 104.286546 -225.329621) (xy 104.270534 -225.280342) (xy 104.262428 -225.229165) (xy 104.26192 -225.203258)
			(xy 104.262527 -225.175541) (xy 104.271842 -225.120895) (xy 104.280462 -225.094546) (xy 104.288336 -225.072448)
			(xy 104.083358 -224.71761) (xy 104.060498 -224.713292) (xy 104.035685 -224.708145) (xy 103.987943 -224.691153)
			(xy 103.943363 -224.667056) (xy 103.902996 -224.63642) (xy 103.867793 -224.599968) (xy 103.838582 -224.558558)
			(xy 103.816052 -224.513166) (xy 103.800734 -224.46486) (xy 103.792988 -224.41478) (xy 103.792528 -224.389442)
			(xy 103.511604 -224.389442) (xy 103.511096 -224.415329) (xy 103.502997 -224.466467) (xy 103.486998 -224.515707)
			(xy 103.463492 -224.561839) (xy 103.43306 -224.603726) (xy 103.39645 -224.640336) (xy 103.354563 -224.670768)
			(xy 103.308431 -224.694274) (xy 103.259191 -224.710273) (xy 103.208053 -224.718372) (xy 103.156279 -224.718372)
			(xy 103.105141 -224.710273) (xy 103.055901 -224.694274) (xy 103.009769 -224.670768) (xy 102.967882 -224.640336)
			(xy 102.931272 -224.603726) (xy 102.90084 -224.561839) (xy 102.877334 -224.515707) (xy 102.861335 -224.466467)
			(xy 102.853236 -224.415329) (xy 102.852728 -224.389442) (xy 102.571804 -224.389442) (xy 102.57126 -224.417149)
			(xy 102.562074 -224.471796) (xy 102.553516 -224.498154) (xy 102.545642 -224.520252) (xy 102.75062 -224.87509)
			(xy 102.77348 -224.879408) (xy 102.798309 -224.884542) (xy 102.846088 -224.901501) (xy 102.890708 -224.925578)
			(xy 102.931114 -224.956202) (xy 102.966354 -224.992654) (xy 102.995597 -225.034071) (xy 103.018152 -225.079478)
			(xy 103.033488 -225.127804) (xy 103.041243 -225.177908) (xy 103.041704 -225.203258) (xy 103.041196 -225.229165)
			(xy 103.03309 -225.280342) (xy 103.017078 -225.329621) (xy 102.993555 -225.375788) (xy 102.963099 -225.417707)
			(xy 102.926461 -225.454345) (xy 102.884542 -225.484801) (xy 102.838375 -225.508324) (xy 102.789096 -225.524336)
			(xy 102.737919 -225.532442) (xy 102.686105 -225.532442) (xy 102.634928 -225.524336) (xy 102.585649 -225.508324)
			(xy 102.539482 -225.484801) (xy 102.497563 -225.454345) (xy 102.460925 -225.417707) (xy 102.430469 -225.375788)
			(xy 102.406946 -225.329621) (xy 102.390934 -225.280342) (xy 102.382828 -225.229165) (xy 102.38232 -225.203258)
			(xy 102.382927 -225.175541) (xy 102.392242 -225.120895) (xy 102.400862 -225.094546) (xy 102.408736 -225.072448)
			(xy 102.203758 -224.71761) (xy 102.180898 -224.713292) (xy 102.156085 -224.708145) (xy 102.108343 -224.691153)
			(xy 102.063763 -224.667056) (xy 102.023396 -224.63642) (xy 101.988193 -224.599968) (xy 101.958982 -224.558558)
			(xy 101.936452 -224.513166) (xy 101.921134 -224.46486) (xy 101.913388 -224.41478) (xy 101.912928 -224.389442)
			(xy 101.632004 -224.389442) (xy 101.631496 -224.415329) (xy 101.623397 -224.466467) (xy 101.607398 -224.515707)
			(xy 101.583892 -224.561839) (xy 101.55346 -224.603726) (xy 101.51685 -224.640336) (xy 101.474963 -224.670768)
			(xy 101.428831 -224.694274) (xy 101.379591 -224.710273) (xy 101.328453 -224.718372) (xy 101.276679 -224.718372)
			(xy 101.225541 -224.710273) (xy 101.176301 -224.694274) (xy 101.130169 -224.670768) (xy 101.088282 -224.640336)
			(xy 101.051672 -224.603726) (xy 101.02124 -224.561839) (xy 100.997734 -224.515707) (xy 100.981735 -224.466467)
			(xy 100.973636 -224.415329) (xy 100.973128 -224.389442) (xy 100.692204 -224.389442) (xy 100.69166 -224.417149)
			(xy 100.682474 -224.471796) (xy 100.673916 -224.498154) (xy 100.666042 -224.520252) (xy 100.87102 -224.87509)
			(xy 100.89388 -224.879408) (xy 100.918709 -224.884542) (xy 100.966488 -224.901501) (xy 101.011108 -224.925578)
			(xy 101.051514 -224.956202) (xy 101.086754 -224.992654) (xy 101.115997 -225.034071) (xy 101.138552 -225.079478)
			(xy 101.153888 -225.127804) (xy 101.161643 -225.177908) (xy 101.162104 -225.203258) (xy 101.161596 -225.229165)
			(xy 101.15349 -225.280342) (xy 101.137478 -225.329621) (xy 101.113955 -225.375788) (xy 101.083499 -225.417707)
			(xy 101.046861 -225.454345) (xy 101.004942 -225.484801) (xy 100.958775 -225.508324) (xy 100.909496 -225.524336)
			(xy 100.858319 -225.532442) (xy 100.806505 -225.532442) (xy 100.755328 -225.524336) (xy 100.706049 -225.508324)
			(xy 100.659882 -225.484801) (xy 100.617963 -225.454345) (xy 100.581325 -225.417707) (xy 100.550869 -225.375788)
			(xy 100.527346 -225.329621) (xy 100.511334 -225.280342) (xy 100.503228 -225.229165) (xy 100.50272 -225.203258)
			(xy 100.503327 -225.175541) (xy 100.512642 -225.120895) (xy 100.521262 -225.094546) (xy 100.529136 -225.072448)
			(xy 100.324158 -224.71761) (xy 100.301298 -224.713292) (xy 100.276485 -224.708145) (xy 100.228743 -224.691153)
			(xy 100.184163 -224.667056) (xy 100.143796 -224.63642) (xy 100.108593 -224.599968) (xy 100.079382 -224.558558)
			(xy 100.056852 -224.513166) (xy 100.041534 -224.46486) (xy 100.033788 -224.41478) (xy 100.033328 -224.389442)
			(xy 99.752404 -224.389442) (xy 99.751896 -224.415329) (xy 99.743797 -224.466467) (xy 99.727798 -224.515707)
			(xy 99.704292 -224.561839) (xy 99.67386 -224.603726) (xy 99.63725 -224.640336) (xy 99.595363 -224.670768)
			(xy 99.549231 -224.694274) (xy 99.499991 -224.710273) (xy 99.448853 -224.718372) (xy 99.397079 -224.718372)
			(xy 99.345941 -224.710273) (xy 99.296701 -224.694274) (xy 99.250569 -224.670768) (xy 99.208682 -224.640336)
			(xy 99.172072 -224.603726) (xy 99.14164 -224.561839) (xy 99.118134 -224.515707) (xy 99.102135 -224.466467)
			(xy 99.094036 -224.415329) (xy 99.093528 -224.389442) (xy 98.812604 -224.389442) (xy 98.81206 -224.417149)
			(xy 98.802874 -224.471796) (xy 98.794316 -224.498154) (xy 98.786442 -224.520252) (xy 98.99142 -224.87509)
			(xy 99.01428 -224.879408) (xy 99.039109 -224.884542) (xy 99.086888 -224.901501) (xy 99.131508 -224.925578)
			(xy 99.171914 -224.956202) (xy 99.207154 -224.992654) (xy 99.236397 -225.034071) (xy 99.258952 -225.079478)
			(xy 99.274288 -225.127804) (xy 99.282043 -225.177908) (xy 99.282504 -225.203258) (xy 99.281996 -225.229165)
			(xy 99.27389 -225.280342) (xy 99.257878 -225.329621) (xy 99.234355 -225.375788) (xy 99.203899 -225.417707)
			(xy 99.167261 -225.454345) (xy 99.125342 -225.484801) (xy 99.079175 -225.508324) (xy 99.029896 -225.524336)
			(xy 98.978719 -225.532442) (xy 98.926905 -225.532442) (xy 98.875728 -225.524336) (xy 98.826449 -225.508324)
			(xy 98.780282 -225.484801) (xy 98.738363 -225.454345) (xy 98.701725 -225.417707) (xy 98.671269 -225.375788)
			(xy 98.647746 -225.329621) (xy 98.631734 -225.280342) (xy 98.623628 -225.229165) (xy 98.62312 -225.203258)
			(xy 98.623727 -225.175541) (xy 98.633042 -225.120895) (xy 98.641662 -225.094546) (xy 98.649536 -225.072448)
			(xy 98.444558 -224.71761) (xy 98.421698 -224.713292) (xy 98.396885 -224.708145) (xy 98.349143 -224.691153)
			(xy 98.304563 -224.667056) (xy 98.264196 -224.63642) (xy 98.228993 -224.599968) (xy 98.199782 -224.558558)
			(xy 98.177252 -224.513166) (xy 98.161934 -224.46486) (xy 98.154188 -224.41478) (xy 98.153728 -224.389442)
			(xy 97.872804 -224.389442) (xy 97.872296 -224.415329) (xy 97.864197 -224.466467) (xy 97.848198 -224.515707)
			(xy 97.824692 -224.561839) (xy 97.79426 -224.603726) (xy 97.75765 -224.640336) (xy 97.715763 -224.670768)
			(xy 97.669631 -224.694274) (xy 97.620391 -224.710273) (xy 97.569253 -224.718372) (xy 97.517479 -224.718372)
			(xy 97.466341 -224.710273) (xy 97.417101 -224.694274) (xy 97.370969 -224.670768) (xy 97.329082 -224.640336)
			(xy 97.292472 -224.603726) (xy 97.26204 -224.561839) (xy 97.238534 -224.515707) (xy 97.222535 -224.466467)
			(xy 97.214436 -224.415329) (xy 97.213928 -224.389442) (xy 96.933004 -224.389442) (xy 96.93246 -224.417149)
			(xy 96.923274 -224.471796) (xy 96.914716 -224.498154) (xy 96.906842 -224.520252) (xy 97.11182 -224.87509)
			(xy 97.13468 -224.879408) (xy 97.159509 -224.884542) (xy 97.207288 -224.901501) (xy 97.251908 -224.925578)
			(xy 97.292314 -224.956202) (xy 97.327554 -224.992654) (xy 97.356797 -225.034071) (xy 97.379352 -225.079478)
			(xy 97.394688 -225.127804) (xy 97.402443 -225.177908) (xy 97.402904 -225.203258) (xy 97.402396 -225.229165)
			(xy 97.39429 -225.280342) (xy 97.378278 -225.329621) (xy 97.354755 -225.375788) (xy 97.324299 -225.417707)
			(xy 97.287661 -225.454345) (xy 97.245742 -225.484801) (xy 97.199575 -225.508324) (xy 97.150296 -225.524336)
			(xy 97.099119 -225.532442) (xy 97.047305 -225.532442) (xy 96.996128 -225.524336) (xy 96.946849 -225.508324)
			(xy 96.900682 -225.484801) (xy 96.858763 -225.454345) (xy 96.822125 -225.417707) (xy 96.791669 -225.375788)
			(xy 96.768146 -225.329621) (xy 96.752134 -225.280342) (xy 96.744028 -225.229165) (xy 96.74352 -225.203258)
			(xy 96.744127 -225.175541) (xy 96.753442 -225.120895) (xy 96.762062 -225.094546) (xy 96.769936 -225.072448)
			(xy 96.564958 -224.71761) (xy 96.542098 -224.713292) (xy 96.517285 -224.708145) (xy 96.469543 -224.691153)
			(xy 96.424963 -224.667056) (xy 96.384596 -224.63642) (xy 96.349393 -224.599968) (xy 96.320182 -224.558558)
			(xy 96.297652 -224.513166) (xy 96.282334 -224.46486) (xy 96.274588 -224.41478) (xy 96.274128 -224.389442)
			(xy 95.993204 -224.389442) (xy 95.992696 -224.415329) (xy 95.984597 -224.466467) (xy 95.968598 -224.515707)
			(xy 95.945092 -224.561839) (xy 95.91466 -224.603726) (xy 95.87805 -224.640336) (xy 95.836163 -224.670768)
			(xy 95.790031 -224.694274) (xy 95.740791 -224.710273) (xy 95.689653 -224.718372) (xy 95.637879 -224.718372)
			(xy 95.586741 -224.710273) (xy 95.537501 -224.694274) (xy 95.491369 -224.670768) (xy 95.449482 -224.640336)
			(xy 95.412872 -224.603726) (xy 95.38244 -224.561839) (xy 95.358934 -224.515707) (xy 95.342935 -224.466467)
			(xy 95.334836 -224.415329) (xy 95.334328 -224.389442) (xy 95.053404 -224.389442) (xy 95.05286 -224.417149)
			(xy 95.043674 -224.471796) (xy 95.035116 -224.498154) (xy 95.027242 -224.520252) (xy 95.23222 -224.87509)
			(xy 95.25508 -224.879408) (xy 95.279909 -224.884542) (xy 95.327688 -224.901501) (xy 95.372308 -224.925578)
			(xy 95.412714 -224.956202) (xy 95.447954 -224.992654) (xy 95.477197 -225.034071) (xy 95.499752 -225.079478)
			(xy 95.515088 -225.127804) (xy 95.522843 -225.177908) (xy 95.523304 -225.203258) (xy 95.522796 -225.229165)
			(xy 95.51469 -225.280342) (xy 95.498678 -225.329621) (xy 95.475155 -225.375788) (xy 95.444699 -225.417707)
			(xy 95.408061 -225.454345) (xy 95.366142 -225.484801) (xy 95.319975 -225.508324) (xy 95.270696 -225.524336)
			(xy 95.219519 -225.532442) (xy 95.167705 -225.532442) (xy 95.116528 -225.524336) (xy 95.067249 -225.508324)
			(xy 95.021082 -225.484801) (xy 94.979163 -225.454345) (xy 94.942525 -225.417707) (xy 94.912069 -225.375788)
			(xy 94.888546 -225.329621) (xy 94.872534 -225.280342) (xy 94.864428 -225.229165) (xy 94.86392 -225.203258)
			(xy 94.864527 -225.175541) (xy 94.873842 -225.120895) (xy 94.882462 -225.094546) (xy 94.890336 -225.072448)
			(xy 94.685358 -224.71761) (xy 94.662498 -224.713292) (xy 94.637685 -224.708145) (xy 94.589943 -224.691153)
			(xy 94.545363 -224.667056) (xy 94.504996 -224.63642) (xy 94.469793 -224.599968) (xy 94.440582 -224.558558)
			(xy 94.418052 -224.513166) (xy 94.402734 -224.46486) (xy 94.394988 -224.41478) (xy 94.394528 -224.389442)
			(xy 94.113604 -224.389442) (xy 94.113096 -224.415329) (xy 94.104997 -224.466467) (xy 94.088998 -224.515707)
			(xy 94.065492 -224.561839) (xy 94.03506 -224.603726) (xy 93.99845 -224.640336) (xy 93.956563 -224.670768)
			(xy 93.910431 -224.694274) (xy 93.861191 -224.710273) (xy 93.810053 -224.718372) (xy 93.758279 -224.718372)
			(xy 93.707141 -224.710273) (xy 93.657901 -224.694274) (xy 93.611769 -224.670768) (xy 93.569882 -224.640336)
			(xy 93.533272 -224.603726) (xy 93.50284 -224.561839) (xy 93.479334 -224.515707) (xy 93.463335 -224.466467)
			(xy 93.455236 -224.415329) (xy 93.454728 -224.389442) (xy 93.173804 -224.389442) (xy 93.173804 -224.38995)
			(xy 93.173247 -224.417593) (xy 93.164056 -224.472111) (xy 93.155516 -224.498408) (xy 93.147896 -224.520252)
			(xy 93.35262 -224.87509) (xy 93.37548 -224.879408) (xy 93.400309 -224.884542) (xy 93.448088 -224.901501)
			(xy 93.492708 -224.925578) (xy 93.533114 -224.956202) (xy 93.568354 -224.992654) (xy 93.597597 -225.034071)
			(xy 93.620152 -225.079478) (xy 93.635488 -225.127804) (xy 93.643243 -225.177908) (xy 93.643704 -225.203258)
			(xy 93.643196 -225.229165) (xy 93.63509 -225.280342) (xy 93.619078 -225.329621) (xy 93.595555 -225.375788)
			(xy 93.565099 -225.417707) (xy 93.528461 -225.454345) (xy 93.486542 -225.484801) (xy 93.440375 -225.508324)
			(xy 93.391096 -225.524336) (xy 93.339919 -225.532442) (xy 93.288105 -225.532442) (xy 93.236928 -225.524336)
			(xy 93.187649 -225.508324) (xy 93.141482 -225.484801) (xy 93.099563 -225.454345) (xy 93.062925 -225.417707)
			(xy 93.032469 -225.375788) (xy 93.008946 -225.329621) (xy 92.992934 -225.280342) (xy 92.984828 -225.229165)
			(xy 92.98432 -225.203258) (xy 92.98432 -225.20275) (xy 92.98493 -225.175096) (xy 92.994253 -225.120579)
			(xy 93.002862 -225.094292) (xy 93.010482 -225.072448) (xy 92.805758 -224.71761) (xy 92.782898 -224.713292)
			(xy 92.758085 -224.708145) (xy 92.710343 -224.691153) (xy 92.665763 -224.667056) (xy 92.625396 -224.63642)
			(xy 92.590193 -224.599968) (xy 92.560982 -224.558558) (xy 92.538452 -224.513166) (xy 92.523134 -224.46486)
			(xy 92.515388 -224.41478) (xy 92.514928 -224.389442) (xy 92.234004 -224.389442) (xy 92.233496 -224.415329)
			(xy 92.225397 -224.466467) (xy 92.209398 -224.515707) (xy 92.185892 -224.561839) (xy 92.15546 -224.603726)
			(xy 92.11885 -224.640336) (xy 92.076963 -224.670768) (xy 92.030831 -224.694274) (xy 91.981591 -224.710273)
			(xy 91.930453 -224.718372) (xy 91.878679 -224.718372) (xy 91.827541 -224.710273) (xy 91.778301 -224.694274)
			(xy 91.732169 -224.670768) (xy 91.690282 -224.640336) (xy 91.653672 -224.603726) (xy 91.62324 -224.561839)
			(xy 91.599734 -224.515707) (xy 91.583735 -224.466467) (xy 91.575636 -224.415329) (xy 91.575128 -224.389442)
			(xy 91.294204 -224.389442) (xy 91.294204 -224.38995) (xy 91.293647 -224.417593) (xy 91.284456 -224.472111)
			(xy 91.275916 -224.498408) (xy 91.268296 -224.520252) (xy 91.47302 -224.87509) (xy 91.49588 -224.879408)
			(xy 91.520709 -224.884542) (xy 91.568488 -224.901501) (xy 91.613108 -224.925578) (xy 91.653514 -224.956202)
			(xy 91.688754 -224.992654) (xy 91.717997 -225.034071) (xy 91.740552 -225.079478) (xy 91.755888 -225.127804)
			(xy 91.763643 -225.177908) (xy 91.764104 -225.203258) (xy 91.763596 -225.229165) (xy 91.75549 -225.280342)
			(xy 91.739478 -225.329621) (xy 91.715955 -225.375788) (xy 91.685499 -225.417707) (xy 91.648861 -225.454345)
			(xy 91.606942 -225.484801) (xy 91.560775 -225.508324) (xy 91.511496 -225.524336) (xy 91.460319 -225.532442)
			(xy 91.408505 -225.532442) (xy 91.357328 -225.524336) (xy 91.308049 -225.508324) (xy 91.261882 -225.484801)
			(xy 91.219963 -225.454345) (xy 91.183325 -225.417707) (xy 91.152869 -225.375788) (xy 91.129346 -225.329621)
			(xy 91.113334 -225.280342) (xy 91.105228 -225.229165) (xy 91.10472 -225.203258) (xy 91.10472 -225.20275)
			(xy 91.10533 -225.175096) (xy 91.114653 -225.120579) (xy 91.123262 -225.094292) (xy 91.130882 -225.072448)
			(xy 90.926158 -224.71761) (xy 90.903298 -224.713292) (xy 90.878485 -224.708145) (xy 90.830743 -224.691153)
			(xy 90.786163 -224.667056) (xy 90.745796 -224.63642) (xy 90.710593 -224.599968) (xy 90.681382 -224.558558)
			(xy 90.658852 -224.513166) (xy 90.643534 -224.46486) (xy 90.635788 -224.41478) (xy 90.635328 -224.389442)
			(xy 90.354404 -224.389442) (xy 90.353896 -224.415329) (xy 90.345797 -224.466467) (xy 90.329798 -224.515707)
			(xy 90.306292 -224.561839) (xy 90.27586 -224.603726) (xy 90.23925 -224.640336) (xy 90.197363 -224.670768)
			(xy 90.151231 -224.694274) (xy 90.101991 -224.710273) (xy 90.050853 -224.718372) (xy 89.999079 -224.718372)
			(xy 89.947941 -224.710273) (xy 89.898701 -224.694274) (xy 89.852569 -224.670768) (xy 89.810682 -224.640336)
			(xy 89.774072 -224.603726) (xy 89.74364 -224.561839) (xy 89.720134 -224.515707) (xy 89.704135 -224.466467)
			(xy 89.696036 -224.415329) (xy 89.695528 -224.389442) (xy 2.509012 -224.389442) (xy 2.509012 -247.620536)
			(xy 228.175312 -247.620536) (xy 228.175312 -246.756936) (xy 228.175798 -246.729685) (xy 228.183554 -246.675737)
			(xy 228.198909 -246.623442) (xy 228.221551 -246.573865) (xy 228.251017 -246.528015) (xy 228.286708 -246.486824)
			(xy 228.327899 -246.451133) (xy 228.373749 -246.421667) (xy 228.423326 -246.399025) (xy 228.475621 -246.38367)
			(xy 228.529569 -246.375914) (xy 228.584071 -246.375914) (xy 228.638019 -246.38367) (xy 228.690314 -246.399025)
			(xy 228.739891 -246.421667) (xy 228.785741 -246.451133) (xy 228.826932 -246.486824) (xy 228.862623 -246.528015)
			(xy 228.892089 -246.573865) (xy 228.914731 -246.623442) (xy 228.930086 -246.675737) (xy 228.937842 -246.729685)
			(xy 228.938328 -246.756936) (xy 228.938328 -247.620536) (xy 228.937842 -247.647787) (xy 228.930086 -247.701735)
			(xy 228.914731 -247.75403) (xy 228.892089 -247.803607) (xy 228.862623 -247.849457) (xy 228.826932 -247.890648)
			(xy 228.785741 -247.926339) (xy 228.739891 -247.955805) (xy 228.690314 -247.978447) (xy 228.638019 -247.993802)
			(xy 228.584071 -248.001558) (xy 228.529569 -248.001558) (xy 228.475621 -247.993802) (xy 228.423326 -247.978447)
			(xy 228.373749 -247.955805) (xy 228.327899 -247.926339) (xy 228.286708 -247.890648) (xy 228.251017 -247.849457)
			(xy 228.221551 -247.803607) (xy 228.198909 -247.75403) (xy 228.183554 -247.701735) (xy 228.175798 -247.647787)
			(xy 228.175312 -247.620536) (xy 2.509012 -247.620536) (xy 2.509012 -251.76988) (xy 75.695566 -251.76988)
			(xy 75.699547 -251.63686) (xy 75.711476 -251.504315) (xy 75.731311 -251.372722) (xy 75.75898 -251.24255)
			(xy 75.794384 -251.114265) (xy 75.837397 -250.988328) (xy 75.887864 -250.865189) (xy 75.945605 -250.745288)
			(xy 76.010414 -250.629055) (xy 76.082058 -250.516905) (xy 76.16028 -250.409241) (xy 76.244801 -250.306448)
			(xy 76.335319 -250.208893) (xy 76.431508 -250.116927) (xy 76.533026 -250.030877) (xy 76.639507 -249.951053)
			(xy 76.750572 -249.87774) (xy 76.865823 -249.8112) (xy 76.984847 -249.751671) (xy 77.107218 -249.699367)
			(xy 77.232497 -249.654475) (xy 77.360238 -249.617156) (xy 77.489981 -249.587543) (xy 77.621263 -249.565742)
			(xy 77.753614 -249.551832) (xy 77.88656 -249.545861) (xy 78.019625 -249.547852) (xy 78.152333 -249.557797)
			(xy 78.284209 -249.575661) (xy 78.41478 -249.601379) (xy 78.54358 -249.63486) (xy 78.670146 -249.675984)
			(xy 78.794027 -249.724604) (xy 78.914778 -249.780545) (xy 79.031968 -249.843607) (xy 79.145177 -249.913565)
			(xy 79.253999 -249.990169) (xy 79.358045 -250.073143) (xy 79.456943 -250.162191) (xy 79.550338 -250.256994)
			(xy 79.637896 -250.357212) (xy 79.719305 -250.462488) (xy 79.794271 -250.572444) (xy 79.862528 -250.686686)
			(xy 79.92383 -250.804806) (xy 79.977959 -250.926381) (xy 80.02472 -251.050975) (xy 80.063946 -251.178143)
			(xy 80.095496 -251.307429) (xy 80.119259 -251.43837) (xy 80.135148 -251.570498) (xy 80.143106 -251.70334)
			(xy 80.143604 -251.76988) (xy 143.715496 -251.76988) (xy 143.719477 -251.63686) (xy 143.731406 -251.504315)
			(xy 143.751241 -251.372722) (xy 143.77891 -251.24255) (xy 143.814314 -251.114265) (xy 143.857327 -250.988328)
			(xy 143.907794 -250.865189) (xy 143.965535 -250.745288) (xy 144.030344 -250.629055) (xy 144.101988 -250.516905)
			(xy 144.18021 -250.409241) (xy 144.264731 -250.306448) (xy 144.355249 -250.208893) (xy 144.451438 -250.116927)
			(xy 144.552956 -250.030877) (xy 144.659437 -249.951053) (xy 144.770502 -249.87774) (xy 144.885753 -249.8112)
			(xy 145.004777 -249.751671) (xy 145.127148 -249.699367) (xy 145.252427 -249.654475) (xy 145.380168 -249.617156)
			(xy 145.509911 -249.587543) (xy 145.641193 -249.565742) (xy 145.773544 -249.551832) (xy 145.90649 -249.545861)
			(xy 146.039555 -249.547852) (xy 146.172263 -249.557797) (xy 146.304139 -249.575661) (xy 146.43471 -249.601379)
			(xy 146.56351 -249.63486) (xy 146.690076 -249.675984) (xy 146.813957 -249.724604) (xy 146.934708 -249.780545)
			(xy 147.051898 -249.843607) (xy 147.165107 -249.913565) (xy 147.273929 -249.990169) (xy 147.377975 -250.073143)
			(xy 147.476873 -250.162191) (xy 147.570268 -250.256994) (xy 147.657826 -250.357212) (xy 147.739235 -250.462488)
			(xy 147.814201 -250.572444) (xy 147.882458 -250.686686) (xy 147.94376 -250.804806) (xy 147.997889 -250.926381)
			(xy 148.04465 -251.050975) (xy 148.083876 -251.178143) (xy 148.115426 -251.307429) (xy 148.139189 -251.43837)
			(xy 148.155078 -251.570498) (xy 148.163036 -251.70334) (xy 148.163534 -251.76988) (xy 323.635634 -251.76988)
			(xy 323.639615 -251.63686) (xy 323.651544 -251.504315) (xy 323.671379 -251.372722) (xy 323.699048 -251.24255)
			(xy 323.734452 -251.114265) (xy 323.777465 -250.988328) (xy 323.827932 -250.865189) (xy 323.885673 -250.745288)
			(xy 323.950482 -250.629055) (xy 324.022126 -250.516905) (xy 324.100348 -250.409241) (xy 324.184869 -250.306448)
			(xy 324.275387 -250.208893) (xy 324.371576 -250.116927) (xy 324.473094 -250.030877) (xy 324.579575 -249.951053)
			(xy 324.69064 -249.87774) (xy 324.805891 -249.8112) (xy 324.924915 -249.751671) (xy 325.047286 -249.699367)
			(xy 325.172565 -249.654475) (xy 325.300306 -249.617156) (xy 325.430049 -249.587543) (xy 325.561331 -249.565742)
			(xy 325.693682 -249.551832) (xy 325.826628 -249.545861) (xy 325.959693 -249.547852) (xy 326.092401 -249.557797)
			(xy 326.224277 -249.575661) (xy 326.354848 -249.601379) (xy 326.483648 -249.63486) (xy 326.610214 -249.675984)
			(xy 326.734095 -249.724604) (xy 326.854846 -249.780545) (xy 326.972036 -249.843607) (xy 327.085245 -249.913565)
			(xy 327.194067 -249.990169) (xy 327.298113 -250.073143) (xy 327.397011 -250.162191) (xy 327.490406 -250.256994)
			(xy 327.577964 -250.357212) (xy 327.659373 -250.462488) (xy 327.734339 -250.572444) (xy 327.802596 -250.686686)
			(xy 327.863898 -250.804806) (xy 327.918027 -250.926381) (xy 327.964788 -251.050975) (xy 328.004014 -251.178143)
			(xy 328.035564 -251.307429) (xy 328.059327 -251.43837) (xy 328.075216 -251.570498) (xy 328.083174 -251.70334)
			(xy 328.083672 -251.76988) (xy 391.655564 -251.76988) (xy 391.659545 -251.63686) (xy 391.671474 -251.504315)
			(xy 391.691309 -251.372722) (xy 391.718978 -251.24255) (xy 391.754382 -251.114265) (xy 391.797395 -250.988328)
			(xy 391.847862 -250.865189) (xy 391.905603 -250.745288) (xy 391.970412 -250.629055) (xy 392.042056 -250.516905)
			(xy 392.120278 -250.409241) (xy 392.204799 -250.306448) (xy 392.295317 -250.208893) (xy 392.391506 -250.116927)
			(xy 392.493024 -250.030877) (xy 392.599505 -249.951053) (xy 392.71057 -249.87774) (xy 392.825821 -249.8112)
			(xy 392.944845 -249.751671) (xy 393.067216 -249.699367) (xy 393.192495 -249.654475) (xy 393.320236 -249.617156)
			(xy 393.449979 -249.587543) (xy 393.581261 -249.565742) (xy 393.713612 -249.551832) (xy 393.846558 -249.545861)
			(xy 393.979623 -249.547852) (xy 394.112331 -249.557797) (xy 394.244207 -249.575661) (xy 394.374778 -249.601379)
			(xy 394.503578 -249.63486) (xy 394.630144 -249.675984) (xy 394.754025 -249.724604) (xy 394.874776 -249.780545)
			(xy 394.991966 -249.843607) (xy 395.105175 -249.913565) (xy 395.213997 -249.990169) (xy 395.318043 -250.073143)
			(xy 395.416941 -250.162191) (xy 395.510336 -250.256994) (xy 395.597894 -250.357212) (xy 395.679303 -250.462488)
			(xy 395.754269 -250.572444) (xy 395.822526 -250.686686) (xy 395.883828 -250.804806) (xy 395.937957 -250.926381)
			(xy 395.984718 -251.050975) (xy 396.023944 -251.178143) (xy 396.055494 -251.307429) (xy 396.079257 -251.43837)
			(xy 396.095146 -251.570498) (xy 396.103104 -251.70334) (xy 396.103602 -251.76988) (xy 396.103104 -251.83642)
			(xy 396.095146 -251.969262) (xy 396.079257 -252.10139) (xy 396.055494 -252.232331) (xy 396.023944 -252.361617)
			(xy 395.984718 -252.488785) (xy 395.937957 -252.613379) (xy 395.883828 -252.734954) (xy 395.822526 -252.853074)
			(xy 395.754269 -252.967316) (xy 395.679303 -253.077272) (xy 395.597894 -253.182548) (xy 395.510336 -253.282766)
			(xy 395.416941 -253.377569) (xy 395.318043 -253.466617) (xy 395.213997 -253.549591) (xy 395.105175 -253.626195)
			(xy 394.991966 -253.696153) (xy 394.874776 -253.759215) (xy 394.754025 -253.815156) (xy 394.630144 -253.863776)
			(xy 394.503578 -253.9049) (xy 394.374778 -253.938381) (xy 394.244207 -253.964099) (xy 394.112331 -253.981963)
			(xy 393.979623 -253.991908) (xy 393.846558 -253.993899) (xy 393.713612 -253.987928) (xy 393.581261 -253.974018)
			(xy 393.449979 -253.952217) (xy 393.320236 -253.922604) (xy 393.192495 -253.885285) (xy 393.067216 -253.840393)
			(xy 392.944845 -253.788089) (xy 392.825821 -253.72856) (xy 392.71057 -253.66202) (xy 392.599505 -253.588707)
			(xy 392.493024 -253.508883) (xy 392.391506 -253.422833) (xy 392.295317 -253.330867) (xy 392.204799 -253.233312)
			(xy 392.120278 -253.130519) (xy 392.042056 -253.022855) (xy 391.970412 -252.910705) (xy 391.905603 -252.794472)
			(xy 391.847862 -252.674571) (xy 391.797395 -252.551432) (xy 391.754382 -252.425495) (xy 391.718978 -252.29721)
			(xy 391.691309 -252.167038) (xy 391.671474 -252.035445) (xy 391.659545 -251.9029) (xy 391.655564 -251.76988)
			(xy 328.083672 -251.76988) (xy 328.083174 -251.83642) (xy 328.075216 -251.969262) (xy 328.059327 -252.10139)
			(xy 328.035564 -252.232331) (xy 328.004014 -252.361617) (xy 327.964788 -252.488785) (xy 327.918027 -252.613379)
			(xy 327.863898 -252.734954) (xy 327.802596 -252.853074) (xy 327.734339 -252.967316) (xy 327.659373 -253.077272)
			(xy 327.577964 -253.182548) (xy 327.490406 -253.282766) (xy 327.397011 -253.377569) (xy 327.298113 -253.466617)
			(xy 327.194067 -253.549591) (xy 327.085245 -253.626195) (xy 326.972036 -253.696153) (xy 326.854846 -253.759215)
			(xy 326.734095 -253.815156) (xy 326.610214 -253.863776) (xy 326.483648 -253.9049) (xy 326.354848 -253.938381)
			(xy 326.224277 -253.964099) (xy 326.092401 -253.981963) (xy 325.959693 -253.991908) (xy 325.826628 -253.993899)
			(xy 325.693682 -253.987928) (xy 325.561331 -253.974018) (xy 325.430049 -253.952217) (xy 325.300306 -253.922604)
			(xy 325.172565 -253.885285) (xy 325.047286 -253.840393) (xy 324.924915 -253.788089) (xy 324.805891 -253.72856)
			(xy 324.69064 -253.66202) (xy 324.579575 -253.588707) (xy 324.473094 -253.508883) (xy 324.371576 -253.422833)
			(xy 324.275387 -253.330867) (xy 324.184869 -253.233312) (xy 324.100348 -253.130519) (xy 324.022126 -253.022855)
			(xy 323.950482 -252.910705) (xy 323.885673 -252.794472) (xy 323.827932 -252.674571) (xy 323.777465 -252.551432)
			(xy 323.734452 -252.425495) (xy 323.699048 -252.29721) (xy 323.671379 -252.167038) (xy 323.651544 -252.035445)
			(xy 323.639615 -251.9029) (xy 323.635634 -251.76988) (xy 148.163534 -251.76988) (xy 148.163036 -251.83642)
			(xy 148.155078 -251.969262) (xy 148.139189 -252.10139) (xy 148.115426 -252.232331) (xy 148.083876 -252.361617)
			(xy 148.04465 -252.488785) (xy 147.997889 -252.613379) (xy 147.94376 -252.734954) (xy 147.882458 -252.853074)
			(xy 147.814201 -252.967316) (xy 147.739235 -253.077272) (xy 147.657826 -253.182548) (xy 147.570268 -253.282766)
			(xy 147.476873 -253.377569) (xy 147.377975 -253.466617) (xy 147.273929 -253.549591) (xy 147.165107 -253.626195)
			(xy 147.051898 -253.696153) (xy 146.934708 -253.759215) (xy 146.813957 -253.815156) (xy 146.690076 -253.863776)
			(xy 146.56351 -253.9049) (xy 146.43471 -253.938381) (xy 146.304139 -253.964099) (xy 146.172263 -253.981963)
			(xy 146.039555 -253.991908) (xy 145.90649 -253.993899) (xy 145.773544 -253.987928) (xy 145.641193 -253.974018)
			(xy 145.509911 -253.952217) (xy 145.380168 -253.922604) (xy 145.252427 -253.885285) (xy 145.127148 -253.840393)
			(xy 145.004777 -253.788089) (xy 144.885753 -253.72856) (xy 144.770502 -253.66202) (xy 144.659437 -253.588707)
			(xy 144.552956 -253.508883) (xy 144.451438 -253.422833) (xy 144.355249 -253.330867) (xy 144.264731 -253.233312)
			(xy 144.18021 -253.130519) (xy 144.101988 -253.022855) (xy 144.030344 -252.910705) (xy 143.965535 -252.794472)
			(xy 143.907794 -252.674571) (xy 143.857327 -252.551432) (xy 143.814314 -252.425495) (xy 143.77891 -252.29721)
			(xy 143.751241 -252.167038) (xy 143.731406 -252.035445) (xy 143.719477 -251.9029) (xy 143.715496 -251.76988)
			(xy 80.143604 -251.76988) (xy 80.143106 -251.83642) (xy 80.135148 -251.969262) (xy 80.119259 -252.10139)
			(xy 80.095496 -252.232331) (xy 80.063946 -252.361617) (xy 80.02472 -252.488785) (xy 79.977959 -252.613379)
			(xy 79.92383 -252.734954) (xy 79.862528 -252.853074) (xy 79.794271 -252.967316) (xy 79.719305 -253.077272)
			(xy 79.637896 -253.182548) (xy 79.550338 -253.282766) (xy 79.456943 -253.377569) (xy 79.358045 -253.466617)
			(xy 79.253999 -253.549591) (xy 79.145177 -253.626195) (xy 79.031968 -253.696153) (xy 78.914778 -253.759215)
			(xy 78.794027 -253.815156) (xy 78.670146 -253.863776) (xy 78.54358 -253.9049) (xy 78.41478 -253.938381)
			(xy 78.284209 -253.964099) (xy 78.152333 -253.981963) (xy 78.019625 -253.991908) (xy 77.88656 -253.993899)
			(xy 77.753614 -253.987928) (xy 77.621263 -253.974018) (xy 77.489981 -253.952217) (xy 77.360238 -253.922604)
			(xy 77.232497 -253.885285) (xy 77.107218 -253.840393) (xy 76.984847 -253.788089) (xy 76.865823 -253.72856)
			(xy 76.750572 -253.66202) (xy 76.639507 -253.588707) (xy 76.533026 -253.508883) (xy 76.431508 -253.422833)
			(xy 76.335319 -253.330867) (xy 76.244801 -253.233312) (xy 76.16028 -253.130519) (xy 76.082058 -253.022855)
			(xy 76.010414 -252.910705) (xy 75.945605 -252.794472) (xy 75.887864 -252.674571) (xy 75.837397 -252.551432)
			(xy 75.794384 -252.425495) (xy 75.75898 -252.29721) (xy 75.731311 -252.167038) (xy 75.711476 -252.035445)
			(xy 75.699547 -251.9029) (xy 75.695566 -251.76988) (xy 2.509012 -251.76988) (xy 2.509012 -273.453098)
			(xy 108.601256 -273.453098) (xy 108.601764 -273.427211) (xy 108.609863 -273.376073) (xy 108.625862 -273.326833)
			(xy 108.649368 -273.280701) (xy 108.6798 -273.238814) (xy 108.71641 -273.202204) (xy 108.758297 -273.171772)
			(xy 108.804429 -273.148266) (xy 108.853669 -273.132267) (xy 108.904807 -273.124168) (xy 108.956581 -273.124168)
			(xy 109.007719 -273.132267) (xy 109.056959 -273.148266) (xy 109.103091 -273.171772) (xy 109.144978 -273.202204)
			(xy 109.181588 -273.238814) (xy 109.21202 -273.280701) (xy 109.235526 -273.326833) (xy 109.251525 -273.376073)
			(xy 109.259624 -273.427211) (xy 109.260132 -273.453098) (xy 356.541324 -273.453098) (xy 356.541832 -273.427211)
			(xy 356.549931 -273.376073) (xy 356.56593 -273.326833) (xy 356.589436 -273.280701) (xy 356.619868 -273.238814)
			(xy 356.656478 -273.202204) (xy 356.698365 -273.171772) (xy 356.744497 -273.148266) (xy 356.793737 -273.132267)
			(xy 356.844875 -273.124168) (xy 356.896649 -273.124168) (xy 356.947787 -273.132267) (xy 356.997027 -273.148266)
			(xy 357.043159 -273.171772) (xy 357.085046 -273.202204) (xy 357.121656 -273.238814) (xy 357.152088 -273.280701)
			(xy 357.175594 -273.326833) (xy 357.191593 -273.376073) (xy 357.199692 -273.427211) (xy 357.2002 -273.453098)
			(xy 357.19967 -273.480806) (xy 357.190475 -273.535453) (xy 357.181912 -273.56181) (xy 357.174292 -273.583654)
			(xy 357.37927 -273.938746) (xy 357.40213 -273.943064) (xy 357.426938 -273.948232) (xy 357.474677 -273.965225)
			(xy 357.519254 -273.989322) (xy 357.559619 -274.019956) (xy 357.594821 -274.056405) (xy 357.624032 -274.097811)
			(xy 357.646564 -274.143199) (xy 357.661886 -274.191501) (xy 357.669637 -274.241577) (xy 357.6701 -274.266914)
			(xy 357.669592 -274.292801) (xy 357.661493 -274.343939) (xy 357.645494 -274.393179) (xy 357.621988 -274.439311)
			(xy 357.591556 -274.481198) (xy 357.554946 -274.517808) (xy 357.513059 -274.54824) (xy 357.466927 -274.571746)
			(xy 357.417687 -274.587745) (xy 357.366549 -274.595844) (xy 357.314775 -274.595844) (xy 357.263637 -274.587745)
			(xy 357.214397 -274.571746) (xy 357.168265 -274.54824) (xy 357.126378 -274.517808) (xy 357.089768 -274.481198)
			(xy 357.059336 -274.439311) (xy 357.03583 -274.393179) (xy 357.019831 -274.343939) (xy 357.011732 -274.292801)
			(xy 357.011224 -274.266914) (xy 357.011756 -274.239206) (xy 357.020949 -274.184559) (xy 357.029512 -274.158202)
			(xy 357.037386 -274.136104) (xy 356.832408 -273.781266) (xy 356.809548 -273.776948) (xy 356.784736 -273.771741)
			(xy 356.73696 -273.75479) (xy 356.692344 -273.730722) (xy 356.651938 -273.700106) (xy 356.616698 -273.663665)
			(xy 356.587453 -273.622257) (xy 356.564893 -273.576859) (xy 356.549551 -273.528542) (xy 356.541789 -273.478445)
			(xy 356.541324 -273.453098) (xy 109.260132 -273.453098) (xy 109.259601 -273.480806) (xy 109.250407 -273.535453)
			(xy 109.241844 -273.56181) (xy 109.234224 -273.583654) (xy 109.439202 -273.938746) (xy 109.462062 -273.943064)
			(xy 109.486859 -273.948281) (xy 109.534598 -273.965264) (xy 109.579176 -273.989353) (xy 109.619543 -274.019979)
			(xy 109.654747 -274.056422) (xy 109.683961 -274.097824) (xy 109.706494 -274.143208) (xy 109.721817 -274.191505)
			(xy 109.729569 -274.241579) (xy 109.730032 -274.266914) (xy 351.372424 -274.266914) (xy 351.372932 -274.241027)
			(xy 351.381031 -274.189889) (xy 351.39703 -274.140649) (xy 351.420536 -274.094517) (xy 351.450968 -274.05263)
			(xy 351.487578 -274.01602) (xy 351.529465 -273.985588) (xy 351.575597 -273.962082) (xy 351.624837 -273.946083)
			(xy 351.675975 -273.937984) (xy 351.727749 -273.937984) (xy 351.778887 -273.946083) (xy 351.828127 -273.962082)
			(xy 351.874259 -273.985588) (xy 351.916146 -274.01602) (xy 351.952756 -274.05263) (xy 351.983188 -274.094517)
			(xy 352.006694 -274.140649) (xy 352.022693 -274.189889) (xy 352.030792 -274.241027) (xy 352.0313 -274.266914)
			(xy 352.0313 -274.267422) (xy 352.030713 -274.294938) (xy 352.021525 -274.349199) (xy 352.013012 -274.375372)
			(xy 352.005392 -274.397216) (xy 352.210624 -274.752562) (xy 352.233484 -274.75688) (xy 352.258307 -274.762037)
			(xy 352.306085 -274.778995) (xy 352.350703 -274.80307) (xy 352.391108 -274.833692) (xy 352.426348 -274.87014)
			(xy 352.455591 -274.911554) (xy 352.478148 -274.956958) (xy 352.493487 -275.00528) (xy 352.501245 -275.055381)
			(xy 352.501708 -275.08073) (xy 352.5012 -275.106637) (xy 352.493094 -275.157814) (xy 352.477082 -275.207093)
			(xy 352.453559 -275.25326) (xy 352.423103 -275.295179) (xy 352.386465 -275.331817) (xy 352.344546 -275.362273)
			(xy 352.298379 -275.385796) (xy 352.2491 -275.401808) (xy 352.197923 -275.409914) (xy 352.146109 -275.409914)
			(xy 352.094932 -275.401808) (xy 352.045653 -275.385796) (xy 351.999486 -275.362273) (xy 351.957567 -275.331817)
			(xy 351.920929 -275.295179) (xy 351.890473 -275.25326) (xy 351.86695 -275.207093) (xy 351.850938 -275.157814)
			(xy 351.842832 -275.106637) (xy 351.842324 -275.08073) (xy 351.842924 -275.053013) (xy 351.852243 -274.998366)
			(xy 351.860866 -274.972018) (xy 351.86874 -274.94992) (xy 351.663762 -274.595082) (xy 351.640902 -274.590764)
			(xy 351.616074 -274.585582) (xy 351.568269 -274.568647) (xy 351.523622 -274.544591) (xy 351.483185 -274.513981)
			(xy 351.447913 -274.47754) (xy 351.418638 -274.436127) (xy 351.39605 -274.390718) (xy 351.380683 -274.342387)
			(xy 351.372898 -274.292272) (xy 351.372424 -274.266914) (xy 109.730032 -274.266914) (xy 109.729524 -274.292801)
			(xy 109.721425 -274.343939) (xy 109.705426 -274.393179) (xy 109.68192 -274.439311) (xy 109.651488 -274.481198)
			(xy 109.614878 -274.517808) (xy 109.572991 -274.54824) (xy 109.526859 -274.571746) (xy 109.477619 -274.587745)
			(xy 109.426481 -274.595844) (xy 109.374707 -274.595844) (xy 109.323569 -274.587745) (xy 109.274329 -274.571746)
			(xy 109.228197 -274.54824) (xy 109.18631 -274.517808) (xy 109.1497 -274.481198) (xy 109.119268 -274.439311)
			(xy 109.095762 -274.393179) (xy 109.079763 -274.343939) (xy 109.071664 -274.292801) (xy 109.071156 -274.266914)
			(xy 109.071691 -274.239206) (xy 109.080883 -274.184559) (xy 109.089444 -274.158202) (xy 109.097318 -274.136104)
			(xy 108.89234 -273.781266) (xy 108.86948 -273.776948) (xy 108.844673 -273.771718) (xy 108.796897 -273.754771)
			(xy 108.75228 -273.730708) (xy 108.711874 -273.700095) (xy 108.676632 -273.663656) (xy 108.647386 -273.622251)
			(xy 108.624826 -273.576855) (xy 108.609484 -273.528539) (xy 108.601721 -273.478444) (xy 108.601256 -273.453098)
			(xy 2.509012 -273.453098) (xy 2.509012 -274.266914) (xy 103.432356 -274.266914) (xy 103.432864 -274.241027)
			(xy 103.440963 -274.189889) (xy 103.456962 -274.140649) (xy 103.480468 -274.094517) (xy 103.5109 -274.05263)
			(xy 103.54751 -274.01602) (xy 103.589397 -273.985588) (xy 103.635529 -273.962082) (xy 103.684769 -273.946083)
			(xy 103.735907 -273.937984) (xy 103.787681 -273.937984) (xy 103.838819 -273.946083) (xy 103.888059 -273.962082)
			(xy 103.934191 -273.985588) (xy 103.976078 -274.01602) (xy 104.012688 -274.05263) (xy 104.04312 -274.094517)
			(xy 104.066626 -274.140649) (xy 104.082625 -274.189889) (xy 104.090724 -274.241027) (xy 104.091232 -274.266914)
			(xy 104.091232 -274.267422) (xy 104.090643 -274.294938) (xy 104.081456 -274.349199) (xy 104.072944 -274.375372)
			(xy 104.065324 -274.397216) (xy 104.270556 -274.752562) (xy 104.293416 -274.75688) (xy 104.318228 -274.762086)
			(xy 104.366006 -274.779035) (xy 104.410625 -274.803101) (xy 104.451032 -274.833715) (xy 104.486274 -274.870157)
			(xy 104.515519 -274.911566) (xy 104.538078 -274.956966) (xy 104.553418 -275.005285) (xy 104.561177 -275.055382)
			(xy 104.56164 -275.08073) (xy 104.561132 -275.106637) (xy 104.553026 -275.157814) (xy 104.537014 -275.207093)
			(xy 104.513491 -275.25326) (xy 104.483035 -275.295179) (xy 104.446397 -275.331817) (xy 104.404478 -275.362273)
			(xy 104.358311 -275.385796) (xy 104.309032 -275.401808) (xy 104.257855 -275.409914) (xy 104.206041 -275.409914)
			(xy 104.154864 -275.401808) (xy 104.105585 -275.385796) (xy 104.059418 -275.362273) (xy 104.017499 -275.331817)
			(xy 103.980861 -275.295179) (xy 103.950405 -275.25326) (xy 103.926882 -275.207093) (xy 103.91087 -275.157814)
			(xy 103.902764 -275.106637) (xy 103.902256 -275.08073) (xy 103.902854 -275.053013) (xy 103.912174 -274.998366)
			(xy 103.920798 -274.972018) (xy 103.928672 -274.94992) (xy 103.723694 -274.595082) (xy 103.700834 -274.590764)
			(xy 103.676011 -274.585559) (xy 103.628206 -274.568629) (xy 103.583558 -274.544577) (xy 103.543121 -274.51397)
			(xy 103.507847 -274.477532) (xy 103.478571 -274.436121) (xy 103.455983 -274.390715) (xy 103.440615 -274.342385)
			(xy 103.43283 -274.292271) (xy 103.432356 -274.266914) (xy 2.509012 -274.266914) (xy 2.509012 -275.10659)
			(xy 102.023373 -275.10659) (xy 102.023373 -275.05481) (xy 102.031474 -275.003669) (xy 102.047476 -274.954425)
			(xy 102.070985 -274.90829) (xy 102.101423 -274.866402) (xy 102.138039 -274.829791) (xy 102.179931 -274.79936)
			(xy 102.226069 -274.775858) (xy 102.275316 -274.759863) (xy 102.326458 -274.75177) (xy 102.352348 -274.751292)
			(xy 102.377861 -274.751741) (xy 102.428277 -274.759608) (xy 102.476879 -274.775148) (xy 102.522507 -274.79799)
			(xy 102.564072 -274.827588) (xy 102.600581 -274.863235) (xy 102.616254 -274.883372) (xy 103.028242 -274.883372)
			(xy 103.043883 -274.86321) (xy 103.0804 -274.827569) (xy 103.121973 -274.797979) (xy 103.167607 -274.775148)
			(xy 103.216215 -274.75962) (xy 103.266634 -274.751765) (xy 103.292148 -274.751292) (xy 103.318035 -274.751743)
			(xy 103.369171 -274.759849) (xy 103.41841 -274.775854) (xy 103.464539 -274.799364) (xy 103.506423 -274.8298)
			(xy 103.543031 -274.866413) (xy 103.573461 -274.908302) (xy 103.596964 -274.954434) (xy 103.612962 -275.003675)
			(xy 103.62106 -275.054813) (xy 103.62106 -275.106587) (xy 103.612962 -275.157725) (xy 103.596964 -275.206966)
			(xy 103.573461 -275.253098) (xy 103.543031 -275.294987) (xy 103.506423 -275.3316) (xy 103.464539 -275.362036)
			(xy 103.41841 -275.385546) (xy 103.369171 -275.401551) (xy 103.318035 -275.409657) (xy 103.292148 -275.410168)
			(xy 103.266637 -275.409665) (xy 103.216223 -275.401811) (xy 103.167621 -275.386283) (xy 103.121992 -275.363452)
			(xy 103.080426 -275.333862) (xy 103.043916 -275.298222) (xy 103.028242 -275.278088) (xy 102.616254 -275.278088)
			(xy 102.600546 -275.298195) (xy 102.564044 -275.333841) (xy 102.522486 -275.363438) (xy 102.476864 -275.386279)
			(xy 102.428268 -275.401819) (xy 102.377858 -275.409687) (xy 102.352348 -275.410168) (xy 102.326458 -275.40963)
			(xy 102.275316 -275.401537) (xy 102.226069 -275.385542) (xy 102.179931 -275.36204) (xy 102.138039 -275.331609)
			(xy 102.101423 -275.294998) (xy 102.070985 -275.25311) (xy 102.047476 -275.206975) (xy 102.031474 -275.157731)
			(xy 102.023373 -275.10659) (xy 2.509012 -275.10659) (xy 2.509012 -276.708616) (xy 102.022656 -276.708616)
			(xy 102.023189 -276.683284) (xy 102.030938 -276.633215) (xy 102.046256 -276.584922) (xy 102.068781 -276.53954)
			(xy 102.097985 -276.498139) (xy 102.133179 -276.461694) (xy 102.173534 -276.431062) (xy 102.218101 -276.406964)
			(xy 102.265829 -276.389968) (xy 102.290626 -276.384766) (xy 102.313486 -276.380448) (xy 102.518464 -276.025356)
			(xy 102.510844 -276.003512) (xy 102.502285 -275.977153) (xy 102.493085 -275.922508) (xy 102.492556 -275.8948)
			(xy 102.493064 -275.868913) (xy 102.501163 -275.817775) (xy 102.517162 -275.768535) (xy 102.540668 -275.722403)
			(xy 102.5711 -275.680516) (xy 102.60771 -275.643906) (xy 102.649597 -275.613474) (xy 102.695729 -275.589968)
			(xy 102.744969 -275.573969) (xy 102.796107 -275.56587) (xy 102.847881 -275.56587) (xy 102.899019 -275.573969)
			(xy 102.948259 -275.589968) (xy 102.994391 -275.613474) (xy 103.036278 -275.643906) (xy 103.072888 -275.680516)
			(xy 103.10332 -275.722403) (xy 103.126826 -275.768535) (xy 103.142825 -275.817775) (xy 103.150924 -275.868913)
			(xy 103.151432 -275.8948) (xy 104.372156 -275.8948) (xy 104.372675 -275.869467) (xy 104.380426 -275.819398)
			(xy 104.395746 -275.771105) (xy 104.418273 -275.725723) (xy 104.447479 -275.684322) (xy 104.482674 -275.647877)
			(xy 104.523031 -275.617245) (xy 104.567599 -275.593147) (xy 104.615329 -275.576152) (xy 104.640126 -275.57095)
			(xy 104.662986 -275.566632) (xy 104.868218 -275.211286) (xy 104.860598 -275.189188) (xy 104.851972 -275.162906)
			(xy 104.842659 -275.108385) (xy 104.842056 -275.08073) (xy 104.842564 -275.054823) (xy 104.85067 -275.003646)
			(xy 104.866682 -274.954367) (xy 104.890205 -274.9082) (xy 104.920661 -274.866281) (xy 104.957299 -274.829643)
			(xy 104.999218 -274.799187) (xy 105.045385 -274.775664) (xy 105.094664 -274.759652) (xy 105.145841 -274.751546)
			(xy 105.197655 -274.751546) (xy 105.248832 -274.759652) (xy 105.298111 -274.775664) (xy 105.344278 -274.799187)
			(xy 105.386197 -274.829643) (xy 105.422835 -274.866281) (xy 105.453291 -274.9082) (xy 105.476814 -274.954367)
			(xy 105.492826 -275.003646) (xy 105.500932 -275.054823) (xy 105.50144 -275.08073) (xy 107.661456 -275.08073)
			(xy 107.661964 -275.054823) (xy 107.67007 -275.003646) (xy 107.686082 -274.954367) (xy 107.709605 -274.9082)
			(xy 107.740061 -274.866281) (xy 107.776699 -274.829643) (xy 107.818618 -274.799187) (xy 107.864785 -274.775664)
			(xy 107.914064 -274.759652) (xy 107.965241 -274.751546) (xy 108.017055 -274.751546) (xy 108.068232 -274.759652)
			(xy 108.117511 -274.775664) (xy 108.163678 -274.799187) (xy 108.205597 -274.829643) (xy 108.242235 -274.866281)
			(xy 108.272691 -274.9082) (xy 108.296214 -274.954367) (xy 108.312226 -275.003646) (xy 108.320332 -275.054823)
			(xy 108.32084 -275.08073) (xy 108.320273 -275.106588) (xy 349.963473 -275.106588) (xy 349.963473 -275.054812)
			(xy 349.971573 -275.003674) (xy 349.987573 -274.954432) (xy 350.011079 -274.9083) (xy 350.041513 -274.866413)
			(xy 350.078125 -274.829803) (xy 350.120014 -274.799371) (xy 350.166147 -274.775867) (xy 350.215389 -274.759869)
			(xy 350.266528 -274.751772) (xy 350.292416 -274.751292) (xy 350.317928 -274.751764) (xy 350.368343 -274.759627)
			(xy 350.416945 -274.775162) (xy 350.462573 -274.797999) (xy 350.504138 -274.827593) (xy 350.540648 -274.863237)
			(xy 350.556322 -274.883372) (xy 350.96831 -274.883372) (xy 350.98397 -274.863226) (xy 351.020483 -274.827584)
			(xy 351.062052 -274.797992) (xy 351.107683 -274.775158) (xy 351.156287 -274.759626) (xy 351.206703 -274.751768)
			(xy 351.232216 -274.751292) (xy 351.258105 -274.751741) (xy 351.309245 -274.759843) (xy 351.358488 -274.775845)
			(xy 351.404622 -274.799353) (xy 351.44651 -274.829789) (xy 351.483122 -274.866402) (xy 351.513555 -274.908292)
			(xy 351.537061 -274.954427) (xy 351.553061 -275.003671) (xy 351.56116 -275.054811) (xy 351.56116 -275.106589)
			(xy 351.553061 -275.157729) (xy 351.537061 -275.206973) (xy 351.513555 -275.253108) (xy 351.483122 -275.294998)
			(xy 351.44651 -275.331611) (xy 351.404622 -275.362047) (xy 351.358488 -275.385555) (xy 351.309245 -275.401557)
			(xy 351.258105 -275.409659) (xy 351.232216 -275.410168) (xy 351.206704 -275.409689) (xy 351.156289 -275.401829)
			(xy 351.107687 -275.386297) (xy 351.062058 -275.363461) (xy 351.020493 -275.333868) (xy 350.983983 -275.298224)
			(xy 350.96831 -275.278088) (xy 350.556322 -275.278088) (xy 350.540633 -275.29821) (xy 350.504126 -275.333856)
			(xy 350.462565 -275.363451) (xy 350.416939 -275.386289) (xy 350.36834 -275.401826) (xy 350.317927 -275.409689)
			(xy 350.292416 -275.410168) (xy 350.266528 -275.409628) (xy 350.215389 -275.401531) (xy 350.166147 -275.385533)
			(xy 350.120014 -275.362029) (xy 350.078125 -275.331597) (xy 350.041513 -275.294987) (xy 350.011079 -275.2531)
			(xy 349.987573 -275.206968) (xy 349.971573 -275.157726) (xy 349.963473 -275.106588) (xy 108.320273 -275.106588)
			(xy 108.320232 -275.108447) (xy 108.310918 -275.163093) (xy 108.302298 -275.189442) (xy 108.294424 -275.21154)
			(xy 108.499656 -275.566632) (xy 108.522516 -275.57095) (xy 108.547321 -275.576185) (xy 108.595097 -275.593131)
			(xy 108.639715 -275.617194) (xy 108.680121 -275.647805) (xy 108.715363 -275.684244) (xy 108.744609 -275.725649)
			(xy 108.767169 -275.771044) (xy 108.782512 -275.819359) (xy 108.790275 -275.869454) (xy 108.79074 -275.8948)
			(xy 108.790232 -275.920707) (xy 108.782126 -275.971884) (xy 108.766114 -276.021163) (xy 108.742591 -276.06733)
			(xy 108.712135 -276.109249) (xy 108.675497 -276.145887) (xy 108.633578 -276.176343) (xy 108.587411 -276.199866)
			(xy 108.538132 -276.215878) (xy 108.486955 -276.223984) (xy 108.435141 -276.223984) (xy 108.383964 -276.215878)
			(xy 108.334685 -276.199866) (xy 108.288518 -276.176343) (xy 108.246599 -276.145887) (xy 108.209961 -276.109249)
			(xy 108.179505 -276.06733) (xy 108.155982 -276.021163) (xy 108.13997 -275.971884) (xy 108.131864 -275.920707)
			(xy 108.131356 -275.8948) (xy 108.131947 -275.867082) (xy 108.141272 -275.812436) (xy 108.149898 -275.786088)
			(xy 108.157772 -275.76399) (xy 107.95254 -275.408898) (xy 107.92968 -275.40458) (xy 107.904858 -275.399414)
			(xy 107.857077 -275.382462) (xy 107.812456 -275.358392) (xy 107.772048 -275.327773) (xy 107.736806 -275.291325)
			(xy 107.707562 -275.249911) (xy 107.685006 -275.204506) (xy 107.66967 -275.156182) (xy 107.661916 -275.10608)
			(xy 107.661456 -275.08073) (xy 105.50144 -275.08073) (xy 105.500998 -275.106094) (xy 105.493245 -275.156227)
			(xy 105.477898 -275.204578) (xy 105.455318 -275.250004) (xy 105.42604 -275.291431) (xy 105.390756 -275.327878)
			(xy 105.350301 -275.358484) (xy 105.305631 -275.382526) (xy 105.257803 -275.399433) (xy 105.232962 -275.40458)
			(xy 105.209848 -275.408898) (xy 105.00487 -275.76399) (xy 105.012744 -275.786088) (xy 105.021303 -275.812447)
			(xy 105.030503 -275.867092) (xy 105.031032 -275.8948) (xy 105.030524 -275.920687) (xy 105.030521 -275.920707)
			(xy 106.252016 -275.920707) (xy 106.252016 -275.868893) (xy 106.260122 -275.817717) (xy 106.276133 -275.768439)
			(xy 106.299656 -275.722272) (xy 106.330111 -275.680353) (xy 106.366749 -275.643715) (xy 106.408667 -275.613259)
			(xy 106.454833 -275.589735) (xy 106.504111 -275.573723) (xy 106.555287 -275.565617) (xy 106.581194 -275.565108)
			(xy 106.606706 -275.56559) (xy 106.65712 -275.57345) (xy 106.705722 -275.588983) (xy 106.75135 -275.611818)
			(xy 106.792916 -275.64141) (xy 106.829426 -275.677053) (xy 106.8451 -275.697188) (xy 107.257088 -275.697188)
			(xy 107.272765 -275.677056) (xy 107.309275 -275.641412) (xy 107.350839 -275.611819) (xy 107.396467 -275.588982)
			(xy 107.445068 -275.573448) (xy 107.495482 -275.565586) (xy 107.520994 -275.565108) (xy 107.546904 -275.565589)
			(xy 107.598085 -275.573695) (xy 107.647369 -275.589707) (xy 107.693541 -275.613232) (xy 107.735464 -275.64369)
			(xy 107.772106 -275.680332) (xy 107.802565 -275.722254) (xy 107.826091 -275.768426) (xy 107.842104 -275.817709)
			(xy 107.85021 -275.86889) (xy 107.85021 -275.92071) (xy 107.842104 -275.971891) (xy 107.826091 -276.021174)
			(xy 107.802565 -276.067346) (xy 107.772106 -276.109268) (xy 107.735464 -276.14591) (xy 107.693541 -276.176368)
			(xy 107.647369 -276.199893) (xy 107.598085 -276.215905) (xy 107.546904 -276.224011) (xy 107.520994 -276.224492)
			(xy 107.495482 -276.224019) (xy 107.445067 -276.216157) (xy 107.396465 -276.200622) (xy 107.350837 -276.177785)
			(xy 107.309271 -276.148192) (xy 107.272762 -276.112547) (xy 107.257088 -276.092412) (xy 106.8451 -276.092412)
			(xy 106.82943 -276.11255) (xy 106.792919 -276.148193) (xy 106.751353 -276.177786) (xy 106.705724 -276.200622)
			(xy 106.657121 -276.216155) (xy 106.606706 -276.224015) (xy 106.581194 -276.224492) (xy 106.555287 -276.223983)
			(xy 106.504111 -276.215877) (xy 106.454833 -276.199865) (xy 106.408667 -276.176341) (xy 106.366749 -276.145885)
			(xy 106.330111 -276.109247) (xy 106.299656 -276.067328) (xy 106.276133 -276.021161) (xy 106.260122 -275.971883)
			(xy 106.252016 -275.920707) (xy 105.030521 -275.920707) (xy 105.022425 -275.971825) (xy 105.006426 -276.021065)
			(xy 104.98292 -276.067197) (xy 104.952488 -276.109084) (xy 104.915878 -276.145694) (xy 104.873991 -276.176126)
			(xy 104.827859 -276.199632) (xy 104.778619 -276.215631) (xy 104.727481 -276.22373) (xy 104.675707 -276.22373)
			(xy 104.624569 -276.215631) (xy 104.575329 -276.199632) (xy 104.529197 -276.176126) (xy 104.48731 -276.145694)
			(xy 104.4507 -276.109084) (xy 104.420268 -276.067197) (xy 104.396762 -276.021065) (xy 104.380763 -275.971825)
			(xy 104.372664 -275.920687) (xy 104.372156 -275.8948) (xy 103.151432 -275.8948) (xy 103.150966 -275.920146)
			(xy 103.143192 -275.97024) (xy 103.127843 -276.018553) (xy 103.105281 -276.063948) (xy 103.076038 -276.105356)
			(xy 103.040801 -276.1418) (xy 103.000402 -276.172421) (xy 102.955792 -276.196499) (xy 102.908023 -276.213466)
			(xy 102.883208 -276.21865) (xy 102.860348 -276.222968) (xy 102.65537 -276.577806) (xy 102.663244 -276.599904)
			(xy 102.671807 -276.626262) (xy 102.681004 -276.680908) (xy 102.681532 -276.708616) (xy 102.962456 -276.708616)
			(xy 102.962964 -276.682709) (xy 102.97107 -276.631532) (xy 102.987082 -276.582253) (xy 103.010605 -276.536086)
			(xy 103.041061 -276.494167) (xy 103.077699 -276.457529) (xy 103.119618 -276.427073) (xy 103.165785 -276.40355)
			(xy 103.215064 -276.387538) (xy 103.266241 -276.379432) (xy 103.318055 -276.379432) (xy 103.369232 -276.387538)
			(xy 103.418511 -276.40355) (xy 103.464678 -276.427073) (xy 103.506597 -276.457529) (xy 103.543235 -276.494167)
			(xy 103.573691 -276.536086) (xy 103.597214 -276.582253) (xy 103.613226 -276.631532) (xy 103.621332 -276.682709)
			(xy 103.62184 -276.708616) (xy 103.621308 -276.734511) (xy 103.902706 -276.734511) (xy 103.902706 -276.682689)
			(xy 103.910813 -276.631506) (xy 103.926828 -276.582222) (xy 103.950356 -276.53605) (xy 103.980818 -276.494128)
			(xy 104.017464 -276.457487) (xy 104.059391 -276.427031) (xy 104.105566 -276.40351) (xy 104.154853 -276.387502)
			(xy 104.206037 -276.379402) (xy 104.231948 -276.378924) (xy 104.257462 -276.37936) (xy 104.307879 -276.387228)
			(xy 104.356482 -276.40277) (xy 104.40211 -276.425614) (xy 104.443674 -276.455215) (xy 104.480182 -276.490865)
			(xy 104.495854 -276.511004) (xy 104.907842 -276.511004) (xy 104.923492 -276.490849) (xy 104.960006 -276.455206)
			(xy 105.001577 -276.425615) (xy 105.04721 -276.402782) (xy 105.095816 -276.387253) (xy 105.146235 -276.379398)
			(xy 105.171748 -276.378924) (xy 105.197654 -276.379404) (xy 105.248828 -276.387515) (xy 105.298102 -276.403532)
			(xy 105.344265 -276.427059) (xy 105.38618 -276.457517) (xy 105.422814 -276.494157) (xy 105.453266 -276.536076)
			(xy 105.476786 -276.582242) (xy 105.492796 -276.631519) (xy 105.5009 -276.682694) (xy 105.5009 -276.734506)
			(xy 105.492796 -276.785681) (xy 105.476786 -276.834958) (xy 105.453266 -276.881124) (xy 105.422814 -276.923043)
			(xy 105.38618 -276.959683) (xy 105.344265 -276.990141) (xy 105.298102 -277.013668) (xy 105.248828 -277.029685)
			(xy 105.197654 -277.037796) (xy 105.171748 -277.038308) (xy 105.146238 -277.037789) (xy 105.095825 -277.029936)
			(xy 105.047224 -277.01441) (xy 105.001596 -276.991582) (xy 104.960029 -276.961996) (xy 104.923517 -276.92636)
			(xy 104.907842 -276.906228) (xy 104.495854 -276.906228) (xy 104.480157 -276.926344) (xy 104.443651 -276.961988)
			(xy 104.40209 -276.991583) (xy 104.356467 -277.014422) (xy 104.307869 -277.029961) (xy 104.257458 -277.037827)
			(xy 104.231948 -277.038308) (xy 104.206037 -277.037798) (xy 104.154853 -277.029698) (xy 104.105566 -277.01369)
			(xy 104.059391 -276.990169) (xy 104.017464 -276.959713) (xy 103.980818 -276.923072) (xy 103.950356 -276.88115)
			(xy 103.926828 -276.834978) (xy 103.910813 -276.785694) (xy 103.902706 -276.734511) (xy 103.621308 -276.734511)
			(xy 103.621269 -276.736398) (xy 103.611945 -276.791174) (xy 103.603298 -276.817582) (xy 103.595424 -276.839426)
			(xy 103.800402 -277.194264) (xy 103.823262 -277.198582) (xy 103.848063 -277.203782) (xy 103.895803 -277.220766)
			(xy 103.940382 -277.244857) (xy 103.98075 -277.275485) (xy 104.015954 -277.311931) (xy 104.045167 -277.353334)
			(xy 104.067699 -277.398721) (xy 104.083021 -277.44702) (xy 104.09077 -277.497096) (xy 104.091232 -277.522432)
			(xy 106.251756 -277.522432) (xy 106.252213 -277.497097) (xy 106.259974 -277.447026) (xy 106.275303 -277.39873)
			(xy 106.297839 -277.353349) (xy 106.327053 -277.311948) (xy 106.362255 -277.275504) (xy 106.402618 -277.244873)
			(xy 106.447192 -277.220777) (xy 106.494926 -277.203783) (xy 106.519726 -277.198582) (xy 106.542586 -277.194264)
			(xy 106.747818 -276.838918) (xy 106.740198 -276.817074) (xy 106.731593 -276.790786) (xy 106.722266 -276.736269)
			(xy 106.721656 -276.708616) (xy 106.722164 -276.682709) (xy 106.73027 -276.631532) (xy 106.746282 -276.582253)
			(xy 106.769805 -276.536086) (xy 106.800261 -276.494167) (xy 106.836899 -276.457529) (xy 106.878818 -276.427073)
			(xy 106.924985 -276.40355) (xy 106.974264 -276.387538) (xy 107.025441 -276.379432) (xy 107.077255 -276.379432)
			(xy 107.128432 -276.387538) (xy 107.177711 -276.40355) (xy 107.223878 -276.427073) (xy 107.265797 -276.457529)
			(xy 107.302435 -276.494167) (xy 107.332891 -276.536086) (xy 107.356414 -276.582253) (xy 107.372426 -276.631532)
			(xy 107.380532 -276.682709) (xy 107.38104 -276.708616) (xy 108.601256 -276.708616) (xy 108.601789 -276.683284)
			(xy 108.609538 -276.633215) (xy 108.624856 -276.584922) (xy 108.647381 -276.53954) (xy 108.676585 -276.498139)
			(xy 108.711779 -276.461694) (xy 108.752134 -276.431062) (xy 108.796701 -276.406964) (xy 108.844429 -276.389968)
			(xy 108.869226 -276.384766) (xy 108.892086 -276.380448) (xy 109.097064 -276.02561) (xy 109.08919 -276.003766)
			(xy 109.080545 -275.977358) (xy 109.071224 -275.922582) (xy 109.070648 -275.8948) (xy 109.071156 -275.868893)
			(xy 109.079262 -275.817716) (xy 109.095274 -275.768437) (xy 109.118797 -275.72227) (xy 109.149253 -275.680351)
			(xy 109.185891 -275.643713) (xy 109.22781 -275.613257) (xy 109.273977 -275.589734) (xy 109.323256 -275.573722)
			(xy 109.374433 -275.565616) (xy 109.426247 -275.565616) (xy 109.477424 -275.573722) (xy 109.526703 -275.589734)
			(xy 109.57287 -275.613257) (xy 109.614789 -275.643713) (xy 109.651427 -275.680351) (xy 109.681883 -275.72227)
			(xy 109.705406 -275.768437) (xy 109.721418 -275.817716) (xy 109.729524 -275.868893) (xy 109.730032 -275.8948)
			(xy 109.729566 -275.920146) (xy 109.721792 -275.97024) (xy 109.706443 -276.018553) (xy 109.683881 -276.063948)
			(xy 109.654638 -276.105356) (xy 109.619401 -276.1418) (xy 109.579002 -276.172421) (xy 109.534392 -276.196499)
			(xy 109.486623 -276.213466) (xy 109.461808 -276.21865) (xy 109.438948 -276.222968) (xy 109.23397 -276.577806)
			(xy 109.241844 -276.599904) (xy 109.250407 -276.626262) (xy 109.259604 -276.680908) (xy 109.260132 -276.708616)
			(xy 349.962724 -276.708616) (xy 349.963202 -276.683281) (xy 349.970953 -276.633207) (xy 349.986274 -276.584909)
			(xy 350.008806 -276.539525) (xy 350.038016 -276.498122) (xy 350.073218 -276.461676) (xy 350.113581 -276.431046)
			(xy 350.158157 -276.406953) (xy 350.205894 -276.389964) (xy 350.230694 -276.384766) (xy 350.253554 -276.380448)
			(xy 350.458532 -276.025356) (xy 350.450912 -276.003512) (xy 350.442352 -275.977154) (xy 350.433153 -275.922508)
			(xy 350.432624 -275.8948) (xy 350.433132 -275.868913) (xy 350.441231 -275.817775) (xy 350.45723 -275.768535)
			(xy 350.480736 -275.722403) (xy 350.511168 -275.680516) (xy 350.547778 -275.643906) (xy 350.589665 -275.613474)
			(xy 350.635797 -275.589968) (xy 350.685037 -275.573969) (xy 350.736175 -275.56587) (xy 350.787949 -275.56587)
			(xy 350.839087 -275.573969) (xy 350.888327 -275.589968) (xy 350.934459 -275.613474) (xy 350.976346 -275.643906)
			(xy 351.012956 -275.680516) (xy 351.043388 -275.722403) (xy 351.066894 -275.768535) (xy 351.082893 -275.817775)
			(xy 351.090992 -275.868913) (xy 351.0915 -275.8948) (xy 352.312224 -275.8948) (xy 352.312688 -275.869465)
			(xy 352.320441 -275.81939) (xy 352.335764 -275.771092) (xy 352.358298 -275.725707) (xy 352.38751 -275.684304)
			(xy 352.422713 -275.647859) (xy 352.463078 -275.617229) (xy 352.507655 -275.593136) (xy 352.555393 -275.576148)
			(xy 352.580194 -275.57095) (xy 352.603054 -275.566632) (xy 352.808286 -275.211286) (xy 352.800666 -275.189188)
			(xy 352.792042 -275.162906) (xy 352.782727 -275.108385) (xy 352.782124 -275.08073) (xy 352.782632 -275.054823)
			(xy 352.790738 -275.003646) (xy 352.80675 -274.954367) (xy 352.830273 -274.9082) (xy 352.860729 -274.866281)
			(xy 352.897367 -274.829643) (xy 352.939286 -274.799187) (xy 352.985453 -274.775664) (xy 353.034732 -274.759652)
			(xy 353.085909 -274.751546) (xy 353.137723 -274.751546) (xy 353.1889 -274.759652) (xy 353.238179 -274.775664)
			(xy 353.284346 -274.799187) (xy 353.326265 -274.829643) (xy 353.362903 -274.866281) (xy 353.393359 -274.9082)
			(xy 353.416882 -274.954367) (xy 353.432894 -275.003646) (xy 353.441 -275.054823) (xy 353.441508 -275.08073)
			(xy 355.601524 -275.08073) (xy 355.602032 -275.054823) (xy 355.610138 -275.003646) (xy 355.62615 -274.954367)
			(xy 355.649673 -274.9082) (xy 355.680129 -274.866281) (xy 355.716767 -274.829643) (xy 355.758686 -274.799187)
			(xy 355.804853 -274.775664) (xy 355.854132 -274.759652) (xy 355.905309 -274.751546) (xy 355.957123 -274.751546)
			(xy 356.0083 -274.759652) (xy 356.057579 -274.775664) (xy 356.103746 -274.799187) (xy 356.145665 -274.829643)
			(xy 356.182303 -274.866281) (xy 356.212759 -274.9082) (xy 356.236282 -274.954367) (xy 356.252294 -275.003646)
			(xy 356.2604 -275.054823) (xy 356.260908 -275.08073) (xy 356.260296 -275.108446) (xy 356.250985 -275.163093)
			(xy 356.242366 -275.189442) (xy 356.234492 -275.21154) (xy 356.439724 -275.566632) (xy 356.462584 -275.57095)
			(xy 356.4874 -275.576135) (xy 356.535176 -275.593092) (xy 356.579792 -275.617163) (xy 356.620197 -275.647782)
			(xy 356.655436 -275.684226) (xy 356.684681 -275.725636) (xy 356.707239 -275.771036) (xy 356.722581 -275.819355)
			(xy 356.730343 -275.869452) (xy 356.730808 -275.8948) (xy 356.7303 -275.920707) (xy 356.722194 -275.971884)
			(xy 356.706182 -276.021163) (xy 356.682659 -276.06733) (xy 356.652203 -276.109249) (xy 356.615565 -276.145887)
			(xy 356.573646 -276.176343) (xy 356.527479 -276.199866) (xy 356.4782 -276.215878) (xy 356.427023 -276.223984)
			(xy 356.375209 -276.223984) (xy 356.324032 -276.215878) (xy 356.274753 -276.199866) (xy 356.228586 -276.176343)
			(xy 356.186667 -276.145887) (xy 356.150029 -276.109249) (xy 356.119573 -276.06733) (xy 356.09605 -276.021163)
			(xy 356.080038 -275.971884) (xy 356.071932 -275.920707) (xy 356.071424 -275.8948) (xy 356.072017 -275.867083)
			(xy 356.081341 -275.812436) (xy 356.089966 -275.786088) (xy 356.09784 -275.76399) (xy 355.892608 -275.408898)
			(xy 355.869748 -275.40458) (xy 355.844921 -275.399437) (xy 355.79714 -275.382481) (xy 355.75252 -275.358407)
			(xy 355.712113 -275.327784) (xy 355.676872 -275.291334) (xy 355.647629 -275.249917) (xy 355.625073 -275.20451)
			(xy 355.609738 -275.156184) (xy 355.601984 -275.10608) (xy 355.601524 -275.08073) (xy 353.441508 -275.08073)
			(xy 353.441092 -275.106096) (xy 353.433338 -275.156231) (xy 353.417989 -275.204584) (xy 353.395406 -275.250011)
			(xy 353.366125 -275.291439) (xy 353.330837 -275.327886) (xy 353.290378 -275.358492) (xy 353.245704 -275.382531)
			(xy 353.197873 -275.399435) (xy 353.17303 -275.40458) (xy 353.149916 -275.408898) (xy 352.944938 -275.76399)
			(xy 352.952812 -275.786088) (xy 352.96137 -275.812447) (xy 352.97057 -275.867092) (xy 352.9711 -275.8948)
			(xy 352.970592 -275.920687) (xy 352.970589 -275.920705) (xy 354.192116 -275.920705) (xy 354.192116 -275.868895)
			(xy 354.200221 -275.817722) (xy 354.21623 -275.768446) (xy 354.23975 -275.722282) (xy 354.270202 -275.680364)
			(xy 354.306835 -275.643726) (xy 354.348749 -275.61327) (xy 354.394911 -275.589745) (xy 354.444185 -275.57373)
			(xy 354.495357 -275.565619) (xy 354.521262 -275.565108) (xy 354.546773 -275.565613) (xy 354.597186 -275.573468)
			(xy 354.645788 -275.588996) (xy 354.691416 -275.611827) (xy 354.732982 -275.641416) (xy 354.769494 -275.677055)
			(xy 354.785168 -275.697188) (xy 355.197156 -275.697188) (xy 355.212852 -275.677071) (xy 355.249357 -275.641427)
			(xy 355.290918 -275.611831) (xy 355.336542 -275.588992) (xy 355.38514 -275.573454) (xy 355.435551 -275.565588)
			(xy 355.461062 -275.565108) (xy 355.486973 -275.565587) (xy 355.538159 -275.573688) (xy 355.587447 -275.589698)
			(xy 355.633623 -275.613221) (xy 355.67555 -275.643679) (xy 355.712197 -275.680321) (xy 355.742659 -275.722245)
			(xy 355.766188 -275.768418) (xy 355.782203 -275.817704) (xy 355.79031 -275.868889) (xy 355.79031 -275.920711)
			(xy 355.782203 -275.971896) (xy 355.766188 -276.021182) (xy 355.742659 -276.067355) (xy 355.712197 -276.109279)
			(xy 355.67555 -276.145921) (xy 355.633623 -276.176379) (xy 355.587447 -276.199902) (xy 355.538159 -276.215912)
			(xy 355.486973 -276.224013) (xy 355.461062 -276.224492) (xy 355.435549 -276.224043) (xy 355.385133 -276.216176)
			(xy 355.336531 -276.200636) (xy 355.290902 -276.177795) (xy 355.249337 -276.148197) (xy 355.212829 -276.112549)
			(xy 355.197156 -276.092412) (xy 354.785168 -276.092412) (xy 354.769516 -276.112565) (xy 354.733002 -276.148208)
			(xy 354.691432 -276.177799) (xy 354.645799 -276.200632) (xy 354.597193 -276.216162) (xy 354.546775 -276.224017)
			(xy 354.521262 -276.224492) (xy 354.495357 -276.223981) (xy 354.444185 -276.21587) (xy 354.394911 -276.199855)
			(xy 354.348749 -276.17633) (xy 354.306835 -276.145874) (xy 354.270202 -276.109236) (xy 354.23975 -276.067318)
			(xy 354.21623 -276.021154) (xy 354.200221 -275.971878) (xy 354.192116 -275.920705) (xy 352.970589 -275.920705)
			(xy 352.962493 -275.971825) (xy 352.946494 -276.021065) (xy 352.922988 -276.067197) (xy 352.892556 -276.109084)
			(xy 352.855946 -276.145694) (xy 352.814059 -276.176126) (xy 352.767927 -276.199632) (xy 352.718687 -276.215631)
			(xy 352.667549 -276.22373) (xy 352.615775 -276.22373) (xy 352.564637 -276.215631) (xy 352.515397 -276.199632)
			(xy 352.469265 -276.176126) (xy 352.427378 -276.145694) (xy 352.390768 -276.109084) (xy 352.360336 -276.067197)
			(xy 352.33683 -276.021065) (xy 352.320831 -275.971825) (xy 352.312732 -275.920687) (xy 352.312224 -275.8948)
			(xy 351.0915 -275.8948) (xy 351.090979 -275.920144) (xy 351.083207 -275.970232) (xy 351.067862 -276.018541)
			(xy 351.045306 -276.063932) (xy 351.016069 -276.105338) (xy 350.98084 -276.141782) (xy 350.940449 -276.172406)
			(xy 350.895848 -276.196488) (xy 350.848087 -276.213462) (xy 350.823276 -276.21865) (xy 350.800416 -276.222968)
			(xy 350.595438 -276.577806) (xy 350.603312 -276.599904) (xy 350.611874 -276.626262) (xy 350.621072 -276.680908)
			(xy 350.6216 -276.708616) (xy 350.902524 -276.708616) (xy 350.903032 -276.682709) (xy 350.911138 -276.631532)
			(xy 350.92715 -276.582253) (xy 350.950673 -276.536086) (xy 350.981129 -276.494167) (xy 351.017767 -276.457529)
			(xy 351.059686 -276.427073) (xy 351.105853 -276.40355) (xy 351.155132 -276.387538) (xy 351.206309 -276.379432)
			(xy 351.258123 -276.379432) (xy 351.3093 -276.387538) (xy 351.358579 -276.40355) (xy 351.404746 -276.427073)
			(xy 351.446665 -276.457529) (xy 351.483303 -276.494167) (xy 351.513759 -276.536086) (xy 351.537282 -276.582253)
			(xy 351.553294 -276.631532) (xy 351.5614 -276.682709) (xy 351.561908 -276.708616) (xy 351.561377 -276.734509)
			(xy 351.842805 -276.734509) (xy 351.842805 -276.682691) (xy 351.850912 -276.631511) (xy 351.866925 -276.582229)
			(xy 351.89045 -276.53606) (xy 351.920909 -276.494139) (xy 351.957551 -276.457499) (xy 351.999473 -276.427042)
			(xy 352.045644 -276.403519) (xy 352.094927 -276.387508) (xy 352.146107 -276.379404) (xy 352.172016 -276.378924)
			(xy 352.197529 -276.379383) (xy 352.247945 -276.387247) (xy 352.296547 -276.402784) (xy 352.342175 -276.425624)
			(xy 352.38374 -276.45522) (xy 352.420249 -276.490867) (xy 352.435922 -276.511004) (xy 352.84791 -276.511004)
			(xy 352.863579 -276.490865) (xy 352.900089 -276.455221) (xy 352.941656 -276.425628) (xy 352.987285 -276.402792)
			(xy 353.035888 -276.387259) (xy 353.086304 -276.3794) (xy 353.111816 -276.378924) (xy 353.137724 -276.379401)
			(xy 353.188901 -276.387509) (xy 353.23818 -276.403523) (xy 353.284347 -276.427048) (xy 353.326266 -276.457506)
			(xy 353.362904 -276.494146) (xy 353.39336 -276.536066) (xy 353.416883 -276.582235) (xy 353.432895 -276.631514)
			(xy 353.441 -276.682692) (xy 353.441 -276.734508) (xy 353.432895 -276.785686) (xy 353.416883 -276.834965)
			(xy 353.39336 -276.881134) (xy 353.362904 -276.923054) (xy 353.326266 -276.959694) (xy 353.284347 -276.990152)
			(xy 353.23818 -277.013677) (xy 353.188901 -277.029691) (xy 353.137724 -277.037799) (xy 353.111816 -277.038308)
			(xy 353.086305 -277.037813) (xy 353.035891 -277.029955) (xy 352.98729 -277.014424) (xy 352.941662 -276.991591)
			(xy 352.900096 -276.962001) (xy 352.863585 -276.926361) (xy 352.84791 -276.906228) (xy 352.435922 -276.906228)
			(xy 352.420244 -276.926359) (xy 352.383734 -276.962002) (xy 352.342169 -276.991595) (xy 352.296542 -277.014432)
			(xy 352.247941 -277.029967) (xy 352.197528 -277.03783) (xy 352.172016 -277.038308) (xy 352.146107 -277.037796)
			(xy 352.094927 -277.029692) (xy 352.045644 -277.013681) (xy 351.999473 -276.990158) (xy 351.957551 -276.959701)
			(xy 351.920909 -276.923061) (xy 351.89045 -276.88114) (xy 351.866925 -276.834971) (xy 351.850912 -276.785689)
			(xy 351.842805 -276.734509) (xy 351.561377 -276.734509) (xy 351.561338 -276.736398) (xy 351.552014 -276.791174)
			(xy 351.543366 -276.817582) (xy 351.535492 -276.839426) (xy 351.74047 -277.194264) (xy 351.76333 -277.198582)
			(xy 351.788142 -277.203733) (xy 351.835882 -277.220727) (xy 351.88046 -277.244826) (xy 351.920825 -277.275462)
			(xy 351.956028 -277.311913) (xy 351.985239 -277.353322) (xy 352.007769 -277.398712) (xy 352.02309 -277.447016)
			(xy 352.030838 -277.497095) (xy 352.0313 -277.522432) (xy 354.191824 -277.522432) (xy 354.192226 -277.497095)
			(xy 354.199989 -277.447018) (xy 354.215322 -277.398718) (xy 354.237864 -277.353333) (xy 354.267084 -277.31193)
			(xy 354.302294 -277.275486) (xy 354.342666 -277.244857) (xy 354.387248 -277.220766) (xy 354.434991 -277.203779)
			(xy 354.459794 -277.198582) (xy 354.482654 -277.194264) (xy 354.687886 -276.838918) (xy 354.680266 -276.817074)
			(xy 354.671663 -276.790785) (xy 354.662334 -276.736269) (xy 354.661724 -276.708616) (xy 354.662232 -276.682709)
			(xy 354.670338 -276.631532) (xy 354.68635 -276.582253) (xy 354.709873 -276.536086) (xy 354.740329 -276.494167)
			(xy 354.776967 -276.457529) (xy 354.818886 -276.427073) (xy 354.865053 -276.40355) (xy 354.914332 -276.387538)
			(xy 354.965509 -276.379432) (xy 355.017323 -276.379432) (xy 355.0685 -276.387538) (xy 355.117779 -276.40355)
			(xy 355.163946 -276.427073) (xy 355.205865 -276.457529) (xy 355.242503 -276.494167) (xy 355.272959 -276.536086)
			(xy 355.296482 -276.582253) (xy 355.312494 -276.631532) (xy 355.3206 -276.682709) (xy 355.321108 -276.708616)
			(xy 356.541324 -276.708616) (xy 356.541802 -276.683281) (xy 356.549553 -276.633207) (xy 356.564874 -276.584909)
			(xy 356.587406 -276.539525) (xy 356.616616 -276.498122) (xy 356.651818 -276.461676) (xy 356.692181 -276.431046)
			(xy 356.736757 -276.406953) (xy 356.784494 -276.389964) (xy 356.809294 -276.384766) (xy 356.832154 -276.380448)
			(xy 357.037132 -276.02561) (xy 357.029258 -276.003766) (xy 357.020612 -275.977358) (xy 357.011292 -275.922582)
			(xy 357.010716 -275.8948) (xy 357.011224 -275.868893) (xy 357.01933 -275.817716) (xy 357.035342 -275.768437)
			(xy 357.058865 -275.72227) (xy 357.089321 -275.680351) (xy 357.125959 -275.643713) (xy 357.167878 -275.613257)
			(xy 357.214045 -275.589734) (xy 357.263324 -275.573722) (xy 357.314501 -275.565616) (xy 357.366315 -275.565616)
			(xy 357.417492 -275.573722) (xy 357.466771 -275.589734) (xy 357.512938 -275.613257) (xy 357.554857 -275.643713)
			(xy 357.591495 -275.680351) (xy 357.621951 -275.72227) (xy 357.645474 -275.768437) (xy 357.661486 -275.817716)
			(xy 357.669592 -275.868893) (xy 357.6701 -275.8948) (xy 357.669579 -275.920144) (xy 357.661807 -275.970232)
			(xy 357.646462 -276.018541) (xy 357.623906 -276.063932) (xy 357.594669 -276.105338) (xy 357.55944 -276.141782)
			(xy 357.519049 -276.172406) (xy 357.474448 -276.196488) (xy 357.426687 -276.213462) (xy 357.401876 -276.21865)
			(xy 357.379016 -276.222968) (xy 357.174038 -276.577806) (xy 357.181912 -276.599904) (xy 357.190474 -276.626262)
			(xy 357.199672 -276.680908) (xy 357.2002 -276.708616) (xy 357.199692 -276.734503) (xy 357.191593 -276.785641)
			(xy 357.175594 -276.834881) (xy 357.152088 -276.881013) (xy 357.121656 -276.9229) (xy 357.085046 -276.95951)
			(xy 357.043159 -276.989942) (xy 356.997027 -277.013448) (xy 356.947787 -277.029447) (xy 356.896649 -277.037546)
			(xy 356.844875 -277.037546) (xy 356.793737 -277.029447) (xy 356.744497 -277.013448) (xy 356.698365 -276.989942)
			(xy 356.656478 -276.95951) (xy 356.619868 -276.9229) (xy 356.589436 -276.881013) (xy 356.56593 -276.834881)
			(xy 356.549931 -276.785641) (xy 356.541832 -276.734503) (xy 356.541324 -276.708616) (xy 355.321108 -276.708616)
			(xy 355.320641 -276.73399) (xy 355.312871 -276.784141) (xy 355.297501 -276.832506) (xy 355.274895 -276.877942)
			(xy 355.245588 -276.919373) (xy 355.210273 -276.955819) (xy 355.169787 -276.986418) (xy 355.125087 -277.010445)
			(xy 355.07723 -277.027332) (xy 355.052376 -277.032466) (xy 355.029516 -277.036784) (xy 354.824538 -277.391622)
			(xy 354.832412 -277.41372) (xy 354.840977 -277.440077) (xy 354.850173 -277.494724) (xy 354.8507 -277.522432)
			(xy 355.131624 -277.522432) (xy 355.132132 -277.496545) (xy 355.140231 -277.445407) (xy 355.15623 -277.396167)
			(xy 355.179736 -277.350035) (xy 355.210168 -277.308148) (xy 355.246778 -277.271538) (xy 355.288665 -277.241106)
			(xy 355.334797 -277.2176) (xy 355.384037 -277.201601) (xy 355.435175 -277.193502) (xy 355.486949 -277.193502)
			(xy 355.538087 -277.201601) (xy 355.587327 -277.2176) (xy 355.633459 -277.241106) (xy 355.675346 -277.271538)
			(xy 355.711956 -277.308148) (xy 355.742388 -277.350035) (xy 355.765894 -277.396167) (xy 355.781893 -277.445407)
			(xy 355.789992 -277.496545) (xy 355.7905 -277.522432) (xy 355.7905 -277.52294) (xy 355.789963 -277.548303)
			(xy 356.071748 -277.548303) (xy 356.071748 -277.496497) (xy 356.079852 -277.445329) (xy 356.09586 -277.396058)
			(xy 356.119377 -277.349898) (xy 356.149826 -277.307985) (xy 356.186456 -277.271351) (xy 356.228366 -277.240897)
			(xy 356.274523 -277.217374) (xy 356.323792 -277.201361) (xy 356.374959 -277.193251) (xy 356.400862 -277.19274)
			(xy 356.426374 -277.193232) (xy 356.476788 -277.201088) (xy 356.52539 -277.216618) (xy 356.571019 -277.239452)
			(xy 356.612585 -277.269043) (xy 356.649095 -277.304685) (xy 356.664768 -277.32482) (xy 357.076756 -277.32482)
			(xy 357.09246 -277.30471) (xy 357.128963 -277.269063) (xy 357.170522 -277.239467) (xy 357.216144 -277.216626)
			(xy 357.264741 -277.201087) (xy 357.315152 -277.19322) (xy 357.340662 -277.19274) (xy 357.366576 -277.193155)
			(xy 357.417766 -277.201257) (xy 357.467059 -277.217268) (xy 357.51324 -277.240794) (xy 357.555171 -277.271254)
			(xy 357.591821 -277.3079) (xy 357.622286 -277.349828) (xy 357.645817 -277.396006) (xy 357.661834 -277.445297)
			(xy 357.669942 -277.496486) (xy 357.669942 -277.548314) (xy 357.661834 -277.599503) (xy 357.645817 -277.648794)
			(xy 357.622286 -277.694972) (xy 357.591821 -277.7369) (xy 357.555171 -277.773546) (xy 357.51324 -277.804006)
			(xy 357.467059 -277.827532) (xy 357.417766 -277.843543) (xy 357.366576 -277.851645) (xy 357.340662 -277.852124)
			(xy 357.31515 -277.851662) (xy 357.264735 -277.843796) (xy 357.216133 -277.828258) (xy 357.170505 -277.805419)
			(xy 357.12894 -277.775824) (xy 357.09243 -277.74018) (xy 357.076756 -277.720044) (xy 356.664768 -277.720044)
			(xy 356.649125 -277.740204) (xy 356.612608 -277.775845) (xy 356.571036 -277.805434) (xy 356.525401 -277.828266)
			(xy 356.476795 -277.843795) (xy 356.426376 -277.85165) (xy 356.400862 -277.852124) (xy 356.374959 -277.851549)
			(xy 356.323792 -277.843439) (xy 356.274523 -277.827426) (xy 356.228366 -277.803903) (xy 356.186456 -277.773449)
			(xy 356.149826 -277.736815) (xy 356.119377 -277.694902) (xy 356.09586 -277.648742) (xy 356.079852 -277.599471)
			(xy 356.071748 -277.548303) (xy 355.789963 -277.548303) (xy 355.789917 -277.550456) (xy 355.780726 -277.604717)
			(xy 355.772212 -277.63089) (xy 355.764592 -277.652988) (xy 355.969824 -278.008334) (xy 355.992684 -278.012652)
			(xy 356.017501 -278.017836) (xy 356.065277 -278.034792) (xy 356.109893 -278.058863) (xy 356.150297 -278.089482)
			(xy 356.185537 -278.125927) (xy 356.214781 -278.167338) (xy 356.23734 -278.212738) (xy 356.252681 -278.261056)
			(xy 356.260443 -278.311154) (xy 356.260908 -278.336502) (xy 356.2604 -278.362409) (xy 356.252294 -278.413586)
			(xy 356.236282 -278.462865) (xy 356.212759 -278.509032) (xy 356.182303 -278.550951) (xy 356.145665 -278.587589)
			(xy 356.103746 -278.618045) (xy 356.057579 -278.641568) (xy 356.0083 -278.65758) (xy 355.957123 -278.665686)
			(xy 355.905309 -278.665686) (xy 355.854132 -278.65758) (xy 355.804853 -278.641568) (xy 355.758686 -278.618045)
			(xy 355.716767 -278.587589) (xy 355.680129 -278.550951) (xy 355.649673 -278.509032) (xy 355.62615 -278.462865)
			(xy 355.610138 -278.413586) (xy 355.602032 -278.362409) (xy 355.601524 -278.336502) (xy 355.602117 -278.308785)
			(xy 355.611441 -278.254138) (xy 355.620066 -278.22779) (xy 355.62794 -278.205692) (xy 355.422962 -277.8506)
			(xy 355.399848 -277.846282) (xy 355.375022 -277.841137) (xy 355.327241 -277.824181) (xy 355.282621 -277.800107)
			(xy 355.242213 -277.769484) (xy 355.206972 -277.733035) (xy 355.177729 -277.691618) (xy 355.155174 -277.646211)
			(xy 355.139838 -277.597886) (xy 355.132084 -277.547782) (xy 355.131624 -277.522432) (xy 354.8507 -277.522432)
			(xy 354.850192 -277.548319) (xy 354.842093 -277.599457) (xy 354.826094 -277.648697) (xy 354.802588 -277.694829)
			(xy 354.772156 -277.736716) (xy 354.735546 -277.773326) (xy 354.693659 -277.803758) (xy 354.647527 -277.827264)
			(xy 354.598287 -277.843263) (xy 354.547149 -277.851362) (xy 354.495375 -277.851362) (xy 354.444237 -277.843263)
			(xy 354.394997 -277.827264) (xy 354.348865 -277.803758) (xy 354.306978 -277.773326) (xy 354.270368 -277.736716)
			(xy 354.239936 -277.694829) (xy 354.21643 -277.648697) (xy 354.200431 -277.599457) (xy 354.192332 -277.548319)
			(xy 354.191824 -277.522432) (xy 352.0313 -277.522432) (xy 352.030792 -277.548319) (xy 352.022693 -277.599457)
			(xy 352.006694 -277.648697) (xy 351.983188 -277.694829) (xy 351.952756 -277.736716) (xy 351.916146 -277.773326)
			(xy 351.874259 -277.803758) (xy 351.828127 -277.827264) (xy 351.778887 -277.843263) (xy 351.727749 -277.851362)
			(xy 351.675975 -277.851362) (xy 351.624837 -277.843263) (xy 351.575597 -277.827264) (xy 351.529465 -277.803758)
			(xy 351.487578 -277.773326) (xy 351.450968 -277.736716) (xy 351.420536 -277.694829) (xy 351.39703 -277.648697)
			(xy 351.381031 -277.599457) (xy 351.372932 -277.548319) (xy 351.372424 -277.522432) (xy 351.37296 -277.494724)
			(xy 351.382151 -277.440077) (xy 351.390712 -277.41372) (xy 351.398586 -277.391622) (xy 351.193608 -277.036784)
			(xy 351.170748 -277.032466) (xy 351.145918 -277.027336) (xy 351.098136 -277.010379) (xy 351.053515 -276.986304)
			(xy 351.013107 -276.955679) (xy 350.977866 -276.919227) (xy 350.948624 -276.877808) (xy 350.926069 -276.8324)
			(xy 350.910735 -276.784072) (xy 350.902983 -276.733967) (xy 350.902524 -276.708616) (xy 350.6216 -276.708616)
			(xy 350.621092 -276.734503) (xy 350.612993 -276.785641) (xy 350.596994 -276.834881) (xy 350.573488 -276.881013)
			(xy 350.543056 -276.9229) (xy 350.506446 -276.95951) (xy 350.464559 -276.989942) (xy 350.418427 -277.013448)
			(xy 350.369187 -277.029447) (xy 350.318049 -277.037546) (xy 350.266275 -277.037546) (xy 350.215137 -277.029447)
			(xy 350.165897 -277.013448) (xy 350.119765 -276.989942) (xy 350.077878 -276.95951) (xy 350.041268 -276.9229)
			(xy 350.010836 -276.881013) (xy 349.98733 -276.834881) (xy 349.971331 -276.785641) (xy 349.963232 -276.734503)
			(xy 349.962724 -276.708616) (xy 109.260132 -276.708616) (xy 109.259624 -276.734503) (xy 109.251525 -276.785641)
			(xy 109.235526 -276.834881) (xy 109.21202 -276.881013) (xy 109.181588 -276.9229) (xy 109.144978 -276.95951)
			(xy 109.103091 -276.989942) (xy 109.056959 -277.013448) (xy 109.007719 -277.029447) (xy 108.956581 -277.037546)
			(xy 108.904807 -277.037546) (xy 108.853669 -277.029447) (xy 108.804429 -277.013448) (xy 108.758297 -276.989942)
			(xy 108.71641 -276.95951) (xy 108.6798 -276.9229) (xy 108.649368 -276.881013) (xy 108.625862 -276.834881)
			(xy 108.609863 -276.785641) (xy 108.601764 -276.734503) (xy 108.601256 -276.708616) (xy 107.38104 -276.708616)
			(xy 107.380628 -276.733993) (xy 107.372856 -276.784149) (xy 107.357482 -276.832518) (xy 107.334871 -276.877958)
			(xy 107.305557 -276.91939) (xy 107.270234 -276.955836) (xy 107.229739 -276.986433) (xy 107.18503 -277.010456)
			(xy 107.137166 -277.027337) (xy 107.112308 -277.032466) (xy 107.089448 -277.036784) (xy 106.88447 -277.391622)
			(xy 106.892344 -277.41372) (xy 106.90091 -277.440076) (xy 106.910105 -277.494723) (xy 106.910632 -277.522432)
			(xy 107.191556 -277.522432) (xy 107.192064 -277.496545) (xy 107.200163 -277.445407) (xy 107.216162 -277.396167)
			(xy 107.239668 -277.350035) (xy 107.2701 -277.308148) (xy 107.30671 -277.271538) (xy 107.348597 -277.241106)
			(xy 107.394729 -277.2176) (xy 107.443969 -277.201601) (xy 107.495107 -277.193502) (xy 107.546881 -277.193502)
			(xy 107.598019 -277.201601) (xy 107.647259 -277.2176) (xy 107.693391 -277.241106) (xy 107.735278 -277.271538)
			(xy 107.771888 -277.308148) (xy 107.80232 -277.350035) (xy 107.825826 -277.396167) (xy 107.841825 -277.445407)
			(xy 107.849924 -277.496545) (xy 107.850432 -277.522432) (xy 107.850432 -277.52294) (xy 107.849894 -277.548305)
			(xy 108.131648 -277.548305) (xy 108.131648 -277.496495) (xy 108.139753 -277.445324) (xy 108.155763 -277.396051)
			(xy 108.179283 -277.349889) (xy 108.209735 -277.307974) (xy 108.24637 -277.271339) (xy 108.288284 -277.240886)
			(xy 108.334445 -277.217365) (xy 108.383718 -277.201354) (xy 108.43489 -277.193249) (xy 108.460794 -277.19274)
			(xy 108.486306 -277.193209) (xy 108.536722 -277.20107) (xy 108.585325 -277.216605) (xy 108.630953 -277.239442)
			(xy 108.672518 -277.269037) (xy 108.709027 -277.304684) (xy 108.7247 -277.32482) (xy 109.136688 -277.32482)
			(xy 109.152374 -277.304695) (xy 109.18888 -277.269049) (xy 109.230443 -277.239454) (xy 109.276069 -277.216616)
			(xy 109.324669 -277.20108) (xy 109.375083 -277.193218) (xy 109.400594 -277.19274) (xy 109.426506 -277.193157)
			(xy 109.477693 -277.201263) (xy 109.526981 -277.217277) (xy 109.573157 -277.240805) (xy 109.615085 -277.271266)
			(xy 109.65173 -277.307911) (xy 109.682192 -277.349838) (xy 109.70572 -277.396013) (xy 109.721735 -277.445301)
			(xy 109.729842 -277.496488) (xy 109.729842 -277.548312) (xy 109.721735 -277.599499) (xy 109.70572 -277.648787)
			(xy 109.682192 -277.694962) (xy 109.65173 -277.736889) (xy 109.615085 -277.773534) (xy 109.573157 -277.803995)
			(xy 109.526981 -277.827523) (xy 109.477693 -277.843537) (xy 109.426506 -277.851643) (xy 109.400594 -277.852124)
			(xy 109.375083 -277.851639) (xy 109.324669 -277.843778) (xy 109.276068 -277.828245) (xy 109.230439 -277.80541)
			(xy 109.188874 -277.775819) (xy 109.152362 -277.740178) (xy 109.136688 -277.720044) (xy 108.7247 -277.720044)
			(xy 108.709039 -277.740189) (xy 108.672525 -277.77583) (xy 108.630957 -277.805422) (xy 108.585326 -277.828256)
			(xy 108.536723 -277.843788) (xy 108.486307 -277.851647) (xy 108.460794 -277.852124) (xy 108.43489 -277.851551)
			(xy 108.383718 -277.843446) (xy 108.334445 -277.827435) (xy 108.288284 -277.803914) (xy 108.24637 -277.773461)
			(xy 108.209735 -277.736826) (xy 108.179283 -277.694911) (xy 108.155763 -277.648749) (xy 108.139753 -277.599476)
			(xy 108.131648 -277.548305) (xy 107.849894 -277.548305) (xy 107.849848 -277.550456) (xy 107.840658 -277.604717)
			(xy 107.832144 -277.63089) (xy 107.824524 -277.652988) (xy 108.029756 -278.008334) (xy 108.052616 -278.012652)
			(xy 108.077422 -278.017885) (xy 108.125198 -278.034831) (xy 108.169815 -278.058894) (xy 108.210222 -278.089506)
			(xy 108.245463 -278.125945) (xy 108.27471 -278.16735) (xy 108.29727 -278.212746) (xy 108.312612 -278.261061)
			(xy 108.320375 -278.311156) (xy 108.32084 -278.336502) (xy 108.320332 -278.362409) (xy 108.312226 -278.413586)
			(xy 108.296214 -278.462865) (xy 108.272691 -278.509032) (xy 108.242235 -278.550951) (xy 108.205597 -278.587589)
			(xy 108.163678 -278.618045) (xy 108.117511 -278.641568) (xy 108.068232 -278.65758) (xy 108.017055 -278.665686)
			(xy 107.965241 -278.665686) (xy 107.914064 -278.65758) (xy 107.864785 -278.641568) (xy 107.818618 -278.618045)
			(xy 107.776699 -278.587589) (xy 107.740061 -278.550951) (xy 107.709605 -278.509032) (xy 107.686082 -278.462865)
			(xy 107.67007 -278.413586) (xy 107.661964 -278.362409) (xy 107.661456 -278.336502) (xy 107.662047 -278.308784)
			(xy 107.671372 -278.254138) (xy 107.679998 -278.22779) (xy 107.687872 -278.205692) (xy 107.482894 -277.8506)
			(xy 107.45978 -277.846282) (xy 107.434959 -277.841114) (xy 107.387178 -277.824162) (xy 107.342557 -277.800093)
			(xy 107.302149 -277.769473) (xy 107.266907 -277.733026) (xy 107.237663 -277.691612) (xy 107.215107 -277.646207)
			(xy 107.199771 -277.597884) (xy 107.192016 -277.547781) (xy 107.191556 -277.522432) (xy 106.910632 -277.522432)
			(xy 106.910124 -277.548319) (xy 106.902025 -277.599457) (xy 106.886026 -277.648697) (xy 106.86252 -277.694829)
			(xy 106.832088 -277.736716) (xy 106.795478 -277.773326) (xy 106.753591 -277.803758) (xy 106.707459 -277.827264)
			(xy 106.658219 -277.843263) (xy 106.607081 -277.851362) (xy 106.555307 -277.851362) (xy 106.504169 -277.843263)
			(xy 106.454929 -277.827264) (xy 106.408797 -277.803758) (xy 106.36691 -277.773326) (xy 106.3303 -277.736716)
			(xy 106.299868 -277.694829) (xy 106.276362 -277.648697) (xy 106.260363 -277.599457) (xy 106.252264 -277.548319)
			(xy 106.251756 -277.522432) (xy 104.091232 -277.522432) (xy 104.090724 -277.548319) (xy 104.082625 -277.599457)
			(xy 104.066626 -277.648697) (xy 104.04312 -277.694829) (xy 104.012688 -277.736716) (xy 103.976078 -277.773326)
			(xy 103.934191 -277.803758) (xy 103.888059 -277.827264) (xy 103.838819 -277.843263) (xy 103.787681 -277.851362)
			(xy 103.735907 -277.851362) (xy 103.684769 -277.843263) (xy 103.635529 -277.827264) (xy 103.589397 -277.803758)
			(xy 103.54751 -277.773326) (xy 103.5109 -277.736716) (xy 103.480468 -277.694829) (xy 103.456962 -277.648697)
			(xy 103.440963 -277.599457) (xy 103.432864 -277.548319) (xy 103.432356 -277.522432) (xy 103.432895 -277.494724)
			(xy 103.442084 -277.440078) (xy 103.450644 -277.41372) (xy 103.458518 -277.391622) (xy 103.25354 -277.036784)
			(xy 103.23068 -277.032466) (xy 103.205855 -277.027313) (xy 103.158073 -277.01036) (xy 103.113452 -276.986289)
			(xy 103.073043 -276.955668) (xy 103.037801 -276.919219) (xy 103.008557 -276.877803) (xy 102.986002 -276.832396)
			(xy 102.970667 -276.78407) (xy 102.962915 -276.733966) (xy 102.962456 -276.708616) (xy 102.681532 -276.708616)
			(xy 102.681024 -276.734503) (xy 102.672925 -276.785641) (xy 102.656926 -276.834881) (xy 102.63342 -276.881013)
			(xy 102.602988 -276.9229) (xy 102.566378 -276.95951) (xy 102.524491 -276.989942) (xy 102.478359 -277.013448)
			(xy 102.429119 -277.029447) (xy 102.377981 -277.037546) (xy 102.326207 -277.037546) (xy 102.275069 -277.029447)
			(xy 102.225829 -277.013448) (xy 102.179697 -276.989942) (xy 102.13781 -276.95951) (xy 102.1012 -276.9229)
			(xy 102.070768 -276.881013) (xy 102.047262 -276.834881) (xy 102.031263 -276.785641) (xy 102.023164 -276.734503)
			(xy 102.022656 -276.708616) (xy 2.509012 -276.708616) (xy 2.509012 -279.150318) (xy 101.552756 -279.150318)
			(xy 101.553264 -279.124431) (xy 101.561363 -279.073293) (xy 101.577362 -279.024053) (xy 101.600868 -278.977921)
			(xy 101.6313 -278.936034) (xy 101.66791 -278.899424) (xy 101.709797 -278.868992) (xy 101.755929 -278.845486)
			(xy 101.805169 -278.829487) (xy 101.856307 -278.821388) (xy 101.908081 -278.821388) (xy 101.959219 -278.829487)
			(xy 102.008459 -278.845486) (xy 102.054591 -278.868992) (xy 102.096478 -278.899424) (xy 102.133088 -278.936034)
			(xy 102.16352 -278.977921) (xy 102.187026 -279.024053) (xy 102.203025 -279.073293) (xy 102.211124 -279.124431)
			(xy 102.211632 -279.150318) (xy 102.211632 -279.150826) (xy 102.21109 -279.176186) (xy 102.493088 -279.176186)
			(xy 102.493088 -279.124414) (xy 102.501186 -279.07328) (xy 102.517184 -279.024043) (xy 102.540688 -278.977914)
			(xy 102.571118 -278.93603) (xy 102.607725 -278.899422) (xy 102.649609 -278.868991) (xy 102.695737 -278.845487)
			(xy 102.744975 -278.829488) (xy 102.796108 -278.821388) (xy 102.821994 -278.82088) (xy 102.847505 -278.821372)
			(xy 102.897919 -278.829232) (xy 102.94652 -278.844763) (xy 102.992148 -278.867597) (xy 103.033714 -278.897186)
			(xy 103.070226 -278.932826) (xy 103.0859 -278.95296) (xy 103.497888 -278.95296) (xy 103.513557 -278.932822)
			(xy 103.550069 -278.89718) (xy 103.591636 -278.867588) (xy 103.637265 -278.844752) (xy 103.685867 -278.829219)
			(xy 103.736282 -278.821357) (xy 103.761794 -278.82088) (xy 103.787685 -278.821325) (xy 103.83883 -278.829425)
			(xy 103.888078 -278.845425) (xy 103.934217 -278.868934) (xy 103.97611 -278.89937) (xy 104.012726 -278.935985)
			(xy 104.043163 -278.977878) (xy 104.066672 -279.024016) (xy 104.082674 -279.073264) (xy 104.090775 -279.124409)
			(xy 104.090775 -279.150318) (xy 349.492824 -279.150318) (xy 349.493332 -279.124431) (xy 349.501431 -279.073293)
			(xy 349.51743 -279.024053) (xy 349.540936 -278.977921) (xy 349.571368 -278.936034) (xy 349.607978 -278.899424)
			(xy 349.649865 -278.868992) (xy 349.695997 -278.845486) (xy 349.745237 -278.829487) (xy 349.796375 -278.821388)
			(xy 349.848149 -278.821388) (xy 349.899287 -278.829487) (xy 349.948527 -278.845486) (xy 349.994659 -278.868992)
			(xy 350.036546 -278.899424) (xy 350.073156 -278.936034) (xy 350.103588 -278.977921) (xy 350.127094 -279.024053)
			(xy 350.143093 -279.073293) (xy 350.151192 -279.124431) (xy 350.1517 -279.150318) (xy 350.1517 -279.150826)
			(xy 350.15116 -279.176184) (xy 350.433187 -279.176184) (xy 350.433187 -279.124416) (xy 350.441285 -279.073285)
			(xy 350.457281 -279.02405) (xy 350.480782 -278.977924) (xy 350.511209 -278.936041) (xy 350.547812 -278.899433)
			(xy 350.589691 -278.869002) (xy 350.635815 -278.845496) (xy 350.685048 -278.829494) (xy 350.736178 -278.82139)
			(xy 350.762062 -278.82088) (xy 350.787572 -278.821396) (xy 350.837985 -278.82925) (xy 350.886585 -278.844777)
			(xy 350.932214 -278.867606) (xy 350.97378 -278.897192) (xy 351.010293 -278.932828) (xy 351.025968 -278.95296)
			(xy 351.437956 -278.95296) (xy 351.453644 -278.932837) (xy 351.490152 -278.897194) (xy 351.531715 -278.8676)
			(xy 351.57734 -278.844762) (xy 351.625939 -278.829225) (xy 351.676351 -278.82136) (xy 351.701862 -278.82088)
			(xy 351.727755 -278.821322) (xy 351.778904 -278.829418) (xy 351.828156 -278.845416) (xy 351.874299 -278.868923)
			(xy 351.916197 -278.899359) (xy 351.952817 -278.935974) (xy 351.983257 -278.977868) (xy 352.006769 -279.024009)
			(xy 352.022773 -279.073259) (xy 352.030875 -279.124407) (xy 352.030875 -279.176193) (xy 352.022773 -279.227341)
			(xy 352.006769 -279.276591) (xy 351.983257 -279.322732) (xy 351.952817 -279.364626) (xy 351.916197 -279.401241)
			(xy 351.874299 -279.431677) (xy 351.828156 -279.455184) (xy 351.778904 -279.471182) (xy 351.727755 -279.479278)
			(xy 351.701862 -279.479756) (xy 351.676348 -279.47932) (xy 351.625931 -279.471453) (xy 351.577328 -279.455912)
			(xy 351.531699 -279.433068) (xy 351.490135 -279.403466) (xy 351.453628 -279.367815) (xy 351.437956 -279.347676)
			(xy 351.025968 -279.347676) (xy 351.010307 -279.367822) (xy 350.973795 -279.403466) (xy 350.932228 -279.433059)
			(xy 350.886597 -279.455894) (xy 350.837992 -279.471425) (xy 350.787575 -279.479281) (xy 350.762062 -279.479756)
			(xy 350.736178 -279.47921) (xy 350.685048 -279.471106) (xy 350.635815 -279.455104) (xy 350.589691 -279.431598)
			(xy 350.547812 -279.401167) (xy 350.511209 -279.364559) (xy 350.480782 -279.322676) (xy 350.457281 -279.27655)
			(xy 350.441285 -279.227315) (xy 350.433187 -279.176184) (xy 350.15116 -279.176184) (xy 350.151114 -279.178342)
			(xy 350.141925 -279.232603) (xy 350.133412 -279.258776) (xy 350.125792 -279.28062) (xy 350.331024 -279.635966)
			(xy 350.353884 -279.640284) (xy 350.378708 -279.645438) (xy 350.426486 -279.662396) (xy 350.471104 -279.68647)
			(xy 350.511509 -279.717093) (xy 350.546749 -279.753542) (xy 350.575992 -279.794956) (xy 350.598549 -279.84036)
			(xy 350.613887 -279.888683) (xy 350.621645 -279.938785) (xy 350.622108 -279.964134) (xy 350.6216 -279.990041)
			(xy 350.613494 -280.041218) (xy 350.597482 -280.090497) (xy 350.573959 -280.136664) (xy 350.543503 -280.178583)
			(xy 350.506865 -280.215221) (xy 350.464946 -280.245677) (xy 350.418779 -280.2692) (xy 350.3695 -280.285212)
			(xy 350.318323 -280.293318) (xy 350.266509 -280.293318) (xy 350.215332 -280.285212) (xy 350.166053 -280.2692)
			(xy 350.119886 -280.245677) (xy 350.077967 -280.215221) (xy 350.041329 -280.178583) (xy 350.010873 -280.136664)
			(xy 349.98735 -280.090497) (xy 349.971338 -280.041218) (xy 349.963232 -279.990041) (xy 349.962724 -279.964134)
			(xy 349.963325 -279.936417) (xy 349.972644 -279.88177) (xy 349.981266 -279.855422) (xy 349.98914 -279.833324)
			(xy 349.784162 -279.478486) (xy 349.761302 -279.474168) (xy 349.736475 -279.468982) (xy 349.688671 -279.452048)
			(xy 349.644023 -279.427992) (xy 349.603586 -279.397383) (xy 349.568314 -279.360942) (xy 349.539039 -279.319529)
			(xy 349.516451 -279.274121) (xy 349.501083 -279.22579) (xy 349.493299 -279.175676) (xy 349.492824 -279.150318)
			(xy 104.090775 -279.150318) (xy 104.090775 -279.176191) (xy 104.082674 -279.227336) (xy 104.066672 -279.276584)
			(xy 104.043163 -279.322722) (xy 104.012726 -279.364615) (xy 103.97611 -279.40123) (xy 103.934217 -279.431666)
			(xy 103.888078 -279.455175) (xy 103.83883 -279.471175) (xy 103.787685 -279.479275) (xy 103.761794 -279.479756)
			(xy 103.736281 -279.479297) (xy 103.685865 -279.471435) (xy 103.637262 -279.455898) (xy 103.591633 -279.433058)
			(xy 103.550069 -279.403461) (xy 103.51356 -279.367813) (xy 103.497888 -279.347676) (xy 103.0859 -279.347676)
			(xy 103.07022 -279.367806) (xy 103.033713 -279.403452) (xy 102.992149 -279.433046) (xy 102.946521 -279.455884)
			(xy 102.89792 -279.471418) (xy 102.847506 -279.479279) (xy 102.821994 -279.479756) (xy 102.796108 -279.479212)
			(xy 102.744975 -279.471112) (xy 102.695737 -279.455113) (xy 102.649609 -279.431609) (xy 102.607725 -279.401178)
			(xy 102.571118 -279.36457) (xy 102.540688 -279.322686) (xy 102.517184 -279.276557) (xy 102.501186 -279.22732)
			(xy 102.493088 -279.176186) (xy 102.21109 -279.176186) (xy 102.211044 -279.178342) (xy 102.201856 -279.232603)
			(xy 102.193344 -279.258776) (xy 102.185724 -279.28062) (xy 102.390956 -279.635966) (xy 102.413816 -279.640284)
			(xy 102.438629 -279.645487) (xy 102.486407 -279.662435) (xy 102.531027 -279.686501) (xy 102.571434 -279.717117)
			(xy 102.606676 -279.753559) (xy 102.635921 -279.794969) (xy 102.658479 -279.840369) (xy 102.673819 -279.888688)
			(xy 102.681577 -279.938786) (xy 102.68204 -279.964134) (xy 102.681532 -279.990041) (xy 102.673426 -280.041218)
			(xy 102.657414 -280.090497) (xy 102.633891 -280.136664) (xy 102.603435 -280.178583) (xy 102.566797 -280.215221)
			(xy 102.524878 -280.245677) (xy 102.478711 -280.2692) (xy 102.429432 -280.285212) (xy 102.378255 -280.293318)
			(xy 102.326441 -280.293318) (xy 102.275264 -280.285212) (xy 102.225985 -280.2692) (xy 102.179818 -280.245677)
			(xy 102.137899 -280.215221) (xy 102.101261 -280.178583) (xy 102.070805 -280.136664) (xy 102.047282 -280.090497)
			(xy 102.03127 -280.041218) (xy 102.023164 -279.990041) (xy 102.022656 -279.964134) (xy 102.023255 -279.936417)
			(xy 102.032575 -279.88177) (xy 102.041198 -279.855422) (xy 102.049072 -279.833324) (xy 101.844094 -279.478486)
			(xy 101.821234 -279.474168) (xy 101.796412 -279.468959) (xy 101.748608 -279.452029) (xy 101.70396 -279.427978)
			(xy 101.663522 -279.397372) (xy 101.628249 -279.360934) (xy 101.598973 -279.319523) (xy 101.576384 -279.274117)
			(xy 101.561016 -279.225788) (xy 101.553231 -279.175675) (xy 101.552756 -279.150318) (xy 2.509012 -279.150318)
			(xy 2.509012 -279.989984) (xy 88.866003 -279.989984) (xy 88.866003 -279.938216) (xy 88.874102 -279.887084)
			(xy 88.890099 -279.837849) (xy 88.913601 -279.791722) (xy 88.94403 -279.74984) (xy 88.980636 -279.713234)
			(xy 89.022517 -279.682805) (xy 89.068643 -279.659301) (xy 89.117878 -279.643303) (xy 89.16901 -279.635204)
			(xy 89.194894 -279.634696) (xy 89.220406 -279.635183) (xy 89.27082 -279.643042) (xy 89.319421 -279.658575)
			(xy 89.365049 -279.681409) (xy 89.406615 -279.711) (xy 89.443126 -279.746642) (xy 89.4588 -279.766776)
			(xy 89.870788 -279.766776) (xy 89.886462 -279.746641) (xy 89.922972 -279.710998) (xy 89.964538 -279.681405)
			(xy 90.010166 -279.658569) (xy 90.058768 -279.643035) (xy 90.109182 -279.635173) (xy 90.134694 -279.634696)
			(xy 90.160586 -279.635109) (xy 90.211734 -279.643209) (xy 90.260984 -279.659211) (xy 90.307125 -279.68272)
			(xy 90.349021 -279.713158) (xy 90.385638 -279.749775) (xy 90.416077 -279.791669) (xy 90.439587 -279.83781)
			(xy 90.45559 -279.88706) (xy 90.463691 -279.938208) (xy 90.463691 -279.964134) (xy 96.383856 -279.964134)
			(xy 96.384364 -279.938227) (xy 96.39247 -279.88705) (xy 96.408482 -279.837771) (xy 96.432005 -279.791604)
			(xy 96.462461 -279.749685) (xy 96.499099 -279.713047) (xy 96.541018 -279.682591) (xy 96.587185 -279.659068)
			(xy 96.636464 -279.643056) (xy 96.687641 -279.63495) (xy 96.739455 -279.63495) (xy 96.790632 -279.643056)
			(xy 96.839911 -279.659068) (xy 96.886078 -279.682591) (xy 96.927997 -279.713047) (xy 96.964635 -279.749685)
			(xy 96.995091 -279.791604) (xy 97.018614 -279.837771) (xy 97.034626 -279.88705) (xy 97.042732 -279.938227)
			(xy 97.04324 -279.964134) (xy 97.042606 -279.991926) (xy 97.033158 -280.046702) (xy 97.024444 -280.0731)
			(xy 97.016824 -280.095198) (xy 97.221802 -280.450036) (xy 97.244662 -280.454354) (xy 97.269457 -280.45958)
			(xy 97.317195 -280.476563) (xy 97.361773 -280.50065) (xy 97.402139 -280.531276) (xy 97.437344 -280.567718)
			(xy 97.466557 -280.609118) (xy 97.489091 -280.6545) (xy 97.504415 -280.702797) (xy 97.512168 -280.752869)
			(xy 97.512632 -280.778204) (xy 97.512124 -280.804091) (xy 97.504025 -280.855229) (xy 97.488026 -280.904469)
			(xy 97.46452 -280.950601) (xy 97.434088 -280.992488) (xy 97.397478 -281.029098) (xy 97.355591 -281.05953)
			(xy 97.309459 -281.083036) (xy 97.260219 -281.099035) (xy 97.209081 -281.107134) (xy 97.157307 -281.107134)
			(xy 97.106169 -281.099035) (xy 97.056929 -281.083036) (xy 97.010797 -281.05953) (xy 96.96891 -281.029098)
			(xy 96.9323 -280.992488) (xy 96.901868 -280.950601) (xy 96.878362 -280.904469) (xy 96.862363 -280.855229)
			(xy 96.854264 -280.804091) (xy 96.853756 -280.778204) (xy 96.854288 -280.750496) (xy 96.863482 -280.695849)
			(xy 96.872044 -280.669492) (xy 96.879918 -280.647394) (xy 96.674686 -280.292302) (xy 96.651826 -280.287984)
			(xy 96.627038 -280.282731) (xy 96.579302 -280.265749) (xy 96.534727 -280.241664) (xy 96.494362 -280.211041)
			(xy 96.459158 -280.174603) (xy 96.429944 -280.133207) (xy 96.407407 -280.087828) (xy 96.39208 -280.039536)
			(xy 96.384322 -279.989467) (xy 96.383856 -279.964134) (xy 90.463691 -279.964134) (xy 90.463691 -279.989992)
			(xy 90.45559 -280.04114) (xy 90.439587 -280.09039) (xy 90.416077 -280.13653) (xy 90.385638 -280.178425)
			(xy 90.349021 -280.215042) (xy 90.307125 -280.24548) (xy 90.260984 -280.268989) (xy 90.211734 -280.284991)
			(xy 90.160586 -280.293091) (xy 90.134694 -280.293572) (xy 90.109181 -280.293107) (xy 90.058766 -280.285245)
			(xy 90.010163 -280.269709) (xy 89.964535 -280.24687) (xy 89.92297 -280.217275) (xy 89.886461 -280.181628)
			(xy 89.870788 -280.161492) (xy 89.4588 -280.161492) (xy 89.443124 -280.181626) (xy 89.406615 -280.21727)
			(xy 89.365051 -280.246864) (xy 89.319422 -280.269701) (xy 89.270821 -280.285235) (xy 89.220406 -280.293095)
			(xy 89.194894 -280.293572) (xy 89.16901 -280.292996) (xy 89.117878 -280.284897) (xy 89.068643 -280.268899)
			(xy 89.022517 -280.245395) (xy 88.980636 -280.214966) (xy 88.94403 -280.17836) (xy 88.913601 -280.136478)
			(xy 88.890099 -280.090351) (xy 88.874102 -280.041116) (xy 88.866003 -279.989984) (xy 2.509012 -279.989984)
			(xy 2.509012 -280.804107) (xy 86.51622 -280.804107) (xy 86.51622 -280.752293) (xy 86.524326 -280.701118)
			(xy 86.540337 -280.65184) (xy 86.563859 -280.605674) (xy 86.594314 -280.563756) (xy 86.630951 -280.527118)
			(xy 86.672869 -280.496662) (xy 86.719035 -280.473139) (xy 86.768312 -280.457127) (xy 86.819487 -280.449021)
			(xy 86.845394 -280.448512) (xy 86.870888 -280.448996) (xy 86.921265 -280.456856) (xy 86.969828 -280.472391)
			(xy 87.015416 -280.495227) (xy 87.056936 -280.52482) (xy 87.093398 -280.56046) (xy 87.109046 -280.580592)
			(xy 87.521542 -280.580592) (xy 87.537192 -280.560462) (xy 87.573653 -280.52482) (xy 87.615173 -280.495227)
			(xy 87.66076 -280.472389) (xy 87.709323 -280.456853) (xy 87.7597 -280.448991) (xy 87.785194 -280.448512)
			(xy 87.811104 -280.448985) (xy 87.862286 -280.457091) (xy 87.91157 -280.473103) (xy 87.957743 -280.496628)
			(xy 87.999666 -280.527087) (xy 88.036309 -280.563729) (xy 88.066768 -280.605652) (xy 88.090294 -280.651824)
			(xy 88.106308 -280.701108) (xy 88.114414 -280.75229) (xy 88.114414 -280.80411) (xy 88.106308 -280.855292)
			(xy 88.090294 -280.904576) (xy 88.066768 -280.950748) (xy 88.036309 -280.992671) (xy 87.999666 -281.029313)
			(xy 87.957743 -281.059772) (xy 87.91157 -281.083297) (xy 87.862286 -281.099309) (xy 87.811104 -281.107415)
			(xy 87.785194 -281.107896) (xy 87.7597 -281.107418) (xy 87.709323 -281.099555) (xy 87.660759 -281.08402)
			(xy 87.615172 -281.061182) (xy 87.573652 -281.031589) (xy 87.53719 -280.995948) (xy 87.521542 -280.975816)
			(xy 87.109046 -280.975816) (xy 87.093405 -280.995954) (xy 87.056942 -281.031594) (xy 87.01542 -281.061187)
			(xy 86.969831 -281.084023) (xy 86.921267 -281.099558) (xy 86.870888 -281.107418) (xy 86.845394 -281.107896)
			(xy 86.819487 -281.107379) (xy 86.768312 -281.099273) (xy 86.719035 -281.083261) (xy 86.672869 -281.059738)
			(xy 86.630951 -281.029282) (xy 86.594314 -280.992644) (xy 86.563859 -280.950726) (xy 86.540337 -280.90456)
			(xy 86.524326 -280.855282) (xy 86.51622 -280.804107) (xy 2.509012 -280.804107) (xy 2.509012 -282.405836)
			(xy 86.515956 -282.405836) (xy 86.516374 -282.380488) (xy 86.524157 -282.330393) (xy 86.539514 -282.282079)
			(xy 86.562083 -282.236685) (xy 86.591333 -282.195278) (xy 86.626575 -282.158835) (xy 86.666978 -282.128214)
			(xy 86.711591 -282.104137) (xy 86.759364 -282.08717) (xy 86.78418 -282.081986) (xy 86.80704 -282.077668)
			(xy 87.012018 -281.722576) (xy 87.004398 -281.700732) (xy 86.995753 -281.67439) (xy 86.986439 -281.619739)
			(xy 86.985856 -281.59202) (xy 86.986364 -281.566113) (xy 86.99447 -281.514936) (xy 87.010482 -281.465657)
			(xy 87.034005 -281.41949) (xy 87.064461 -281.377571) (xy 87.101099 -281.340933) (xy 87.143018 -281.310477)
			(xy 87.189185 -281.286954) (xy 87.238464 -281.270942) (xy 87.289641 -281.262836) (xy 87.341455 -281.262836)
			(xy 87.392632 -281.270942) (xy 87.441911 -281.286954) (xy 87.488078 -281.310477) (xy 87.529997 -281.340933)
			(xy 87.566635 -281.377571) (xy 87.597091 -281.41949) (xy 87.620614 -281.465657) (xy 87.636626 -281.514936)
			(xy 87.644732 -281.566113) (xy 87.64524 -281.59202) (xy 88.865456 -281.59202) (xy 88.86595 -281.566675)
			(xy 88.87372 -281.516583) (xy 88.889066 -281.468271) (xy 88.911624 -281.422876) (xy 88.940864 -281.381469)
			(xy 88.976098 -281.345025) (xy 89.016493 -281.314403) (xy 89.0611 -281.290323) (xy 89.108866 -281.273355)
			(xy 89.13368 -281.26817) (xy 89.15654 -281.263852) (xy 89.361518 -280.909014) (xy 89.353898 -280.88717)
			(xy 89.345254 -280.860761) (xy 89.335932 -280.805986) (xy 89.335356 -280.778204) (xy 89.335819 -280.752307)
			(xy 89.343918 -280.70115) (xy 89.359916 -280.651889) (xy 89.383421 -280.605736) (xy 89.413854 -280.563826)
			(xy 89.450466 -280.527191) (xy 89.492357 -280.496731) (xy 89.538495 -280.473197) (xy 89.587746 -280.457167)
			(xy 89.638897 -280.449036) (xy 89.664794 -280.448512) (xy 89.690671 -280.448974) (xy 89.741789 -280.457066)
			(xy 89.791012 -280.473052) (xy 89.83713 -280.496539) (xy 89.879007 -280.526949) (xy 89.915615 -280.563533)
			(xy 89.946051 -280.605391) (xy 89.969567 -280.651494) (xy 89.985584 -280.700707) (xy 89.993709 -280.751819)
			(xy 89.994232 -280.777696) (xy 89.994232 -280.778204) (xy 92.154756 -280.778204) (xy 92.155193 -280.752292)
			(xy 92.163301 -280.701107) (xy 92.179316 -280.65182) (xy 92.202845 -280.605646) (xy 92.233308 -280.563722)
			(xy 92.269955 -280.527079) (xy 92.311884 -280.496622) (xy 92.358061 -280.473099) (xy 92.40735 -280.45709)
			(xy 92.458536 -280.44899) (xy 92.484448 -280.448512) (xy 92.510327 -280.448924) (xy 92.561446 -280.457025)
			(xy 92.61067 -280.473018) (xy 92.656788 -280.496511) (xy 92.698665 -280.526927) (xy 92.735272 -280.563516)
			(xy 92.765707 -280.605379) (xy 92.789222 -280.651486) (xy 92.805239 -280.700702) (xy 92.813363 -280.751818)
			(xy 92.813886 -280.777696) (xy 92.813886 -280.778204) (xy 92.813354 -280.804107) (xy 94.97442 -280.804107)
			(xy 94.97442 -280.752293) (xy 94.982526 -280.701118) (xy 94.998537 -280.65184) (xy 95.022059 -280.605674)
			(xy 95.052514 -280.563756) (xy 95.089151 -280.527118) (xy 95.131069 -280.496662) (xy 95.177235 -280.473139)
			(xy 95.226512 -280.457127) (xy 95.277687 -280.449021) (xy 95.303594 -280.448512) (xy 95.329106 -280.448992)
			(xy 95.379521 -280.456852) (xy 95.428122 -280.472385) (xy 95.473751 -280.495221) (xy 95.515316 -280.524814)
			(xy 95.551826 -280.560457) (xy 95.5675 -280.580592) (xy 95.979742 -280.580592) (xy 95.995389 -280.560435)
			(xy 96.031904 -280.524793) (xy 96.073475 -280.495202) (xy 96.119109 -280.472369) (xy 96.167716 -280.45684)
			(xy 96.218134 -280.448986) (xy 96.243648 -280.448512) (xy 96.269553 -280.449016) (xy 96.320725 -280.457128)
			(xy 96.369997 -280.473144) (xy 96.416159 -280.49667) (xy 96.458071 -280.527127) (xy 96.494704 -280.563765)
			(xy 96.525155 -280.605682) (xy 96.548675 -280.651847) (xy 96.564684 -280.701122) (xy 96.572788 -280.752295)
			(xy 96.572788 -280.804105) (xy 96.564684 -280.855278) (xy 96.548675 -280.904553) (xy 96.525155 -280.950718)
			(xy 96.494704 -280.992635) (xy 96.458071 -281.029273) (xy 96.416159 -281.05973) (xy 96.369997 -281.083256)
			(xy 96.320725 -281.099272) (xy 96.269553 -281.107384) (xy 96.243648 -281.107896) (xy 96.218137 -281.107382)
			(xy 96.167724 -281.099529) (xy 96.119123 -281.084002) (xy 96.073495 -281.061173) (xy 96.031928 -281.031586)
			(xy 95.995417 -280.995948) (xy 95.979742 -280.975816) (xy 95.5675 -280.975816) (xy 95.551831 -280.995955)
			(xy 95.51532 -281.031598) (xy 95.473753 -281.06119) (xy 95.428124 -281.084026) (xy 95.379522 -281.099559)
			(xy 95.329106 -281.107419) (xy 95.303594 -281.107896) (xy 95.277687 -281.107379) (xy 95.226512 -281.099273)
			(xy 95.177235 -281.083261) (xy 95.131069 -281.059738) (xy 95.089151 -281.029282) (xy 95.052514 -280.992644)
			(xy 95.022059 -280.950726) (xy 94.998537 -280.90456) (xy 94.982526 -280.855282) (xy 94.97442 -280.804107)
			(xy 92.813354 -280.804107) (xy 92.813315 -280.805986) (xy 92.803991 -280.860762) (xy 92.795344 -280.88717)
			(xy 92.787724 -280.909014) (xy 92.992702 -281.263852) (xy 93.015562 -281.26817) (xy 93.04036 -281.273381)
			(xy 93.0881 -281.290365) (xy 93.132678 -281.314454) (xy 93.173045 -281.345081) (xy 93.20825 -281.381525)
			(xy 93.237463 -281.422927) (xy 93.259996 -281.468312) (xy 93.275318 -281.51661) (xy 93.283069 -281.566685)
			(xy 93.283532 -281.59202) (xy 93.283024 -281.617907) (xy 93.274925 -281.669045) (xy 93.258926 -281.718285)
			(xy 93.23542 -281.764417) (xy 93.204988 -281.806304) (xy 93.168378 -281.842914) (xy 93.126491 -281.873346)
			(xy 93.080359 -281.896852) (xy 93.031119 -281.912851) (xy 92.979981 -281.92095) (xy 92.928207 -281.92095)
			(xy 92.877069 -281.912851) (xy 92.827829 -281.896852) (xy 92.781697 -281.873346) (xy 92.73981 -281.842914)
			(xy 92.7032 -281.806304) (xy 92.672768 -281.764417) (xy 92.649262 -281.718285) (xy 92.633263 -281.669045)
			(xy 92.625164 -281.617907) (xy 92.624656 -281.59202) (xy 92.625203 -281.564313) (xy 92.634391 -281.509667)
			(xy 92.642944 -281.483308) (xy 92.650564 -281.461464) (xy 92.445586 -281.106372) (xy 92.422726 -281.102054)
			(xy 92.397931 -281.096829) (xy 92.350193 -281.079845) (xy 92.305616 -281.055757) (xy 92.265251 -281.025131)
			(xy 92.230046 -280.988689) (xy 92.200833 -280.947289) (xy 92.178299 -280.901907) (xy 92.162974 -280.853611)
			(xy 92.15522 -280.803539) (xy 92.154756 -280.778204) (xy 89.994232 -280.778204) (xy 89.993765 -280.803528)
			(xy 89.986033 -280.853583) (xy 89.970734 -280.901865) (xy 89.94823 -280.947239) (xy 89.91905 -280.988637)
			(xy 89.883881 -281.025084) (xy 89.843551 -281.055722) (xy 89.799008 -281.079831) (xy 89.751302 -281.096842)
			(xy 89.726516 -281.102054) (xy 89.703656 -281.106372) (xy 89.498678 -281.46121) (xy 89.506298 -281.483054)
			(xy 89.51491 -281.50934) (xy 89.524233 -281.563858) (xy 89.52484 -281.591512) (xy 89.52484 -281.59202)
			(xy 89.524332 -281.617905) (xy 90.745336 -281.617905) (xy 90.745336 -281.566095) (xy 90.753441 -281.514922)
			(xy 90.769451 -281.465646) (xy 90.792973 -281.419482) (xy 90.823426 -281.377566) (xy 90.860062 -281.34093)
			(xy 90.901977 -281.310476) (xy 90.948141 -281.286954) (xy 90.997416 -281.270943) (xy 91.048589 -281.262837)
			(xy 91.074494 -281.262328) (xy 91.100006 -281.262802) (xy 91.150421 -281.270662) (xy 91.199024 -281.286196)
			(xy 91.244652 -281.309033) (xy 91.286218 -281.338627) (xy 91.322727 -281.374272) (xy 91.3384 -281.394408)
			(xy 91.750388 -281.394408) (xy 91.766071 -281.37428) (xy 91.802578 -281.338635) (xy 91.844142 -281.309041)
			(xy 91.889768 -281.286203) (xy 91.938369 -281.270668) (xy 91.988782 -281.262806) (xy 92.014294 -281.262328)
			(xy 92.040205 -281.262769) (xy 92.09139 -281.270875) (xy 92.140676 -281.286888) (xy 92.186851 -281.310415)
			(xy 92.228777 -281.340875) (xy 92.265421 -281.377519) (xy 92.295882 -281.419444) (xy 92.319409 -281.465618)
			(xy 92.335423 -281.514904) (xy 92.34353 -281.566089) (xy 92.34353 -281.617911) (xy 92.335423 -281.669096)
			(xy 92.319409 -281.718382) (xy 92.295882 -281.764556) (xy 92.265421 -281.806481) (xy 92.228777 -281.843125)
			(xy 92.186851 -281.873585) (xy 92.140676 -281.897112) (xy 92.09139 -281.913125) (xy 92.040205 -281.921231)
			(xy 92.014294 -281.921712) (xy 91.988782 -281.921231) (xy 91.938368 -281.91337) (xy 91.889767 -281.897836)
			(xy 91.844138 -281.875001) (xy 91.802573 -281.845409) (xy 91.766062 -281.809767) (xy 91.750388 -281.789632)
			(xy 91.3384 -281.789632) (xy 91.322735 -281.809774) (xy 91.286223 -281.845417) (xy 91.244655 -281.875008)
			(xy 91.199025 -281.897843) (xy 91.150422 -281.913376) (xy 91.100006 -281.921235) (xy 91.074494 -281.921712)
			(xy 91.048589 -281.921163) (xy 90.997416 -281.913057) (xy 90.948141 -281.897046) (xy 90.901977 -281.873524)
			(xy 90.860062 -281.84307) (xy 90.823426 -281.806434) (xy 90.792973 -281.764518) (xy 90.769451 -281.718354)
			(xy 90.753441 -281.669078) (xy 90.745336 -281.617905) (xy 89.524332 -281.617905) (xy 89.524332 -281.617927)
			(xy 89.516226 -281.669104) (xy 89.500214 -281.718383) (xy 89.476691 -281.76455) (xy 89.446235 -281.806469)
			(xy 89.409597 -281.843107) (xy 89.367678 -281.873563) (xy 89.321511 -281.897086) (xy 89.272232 -281.913098)
			(xy 89.221055 -281.921204) (xy 89.169241 -281.921204) (xy 89.118064 -281.913098) (xy 89.068785 -281.897086)
			(xy 89.022618 -281.873563) (xy 88.980699 -281.843107) (xy 88.944061 -281.806469) (xy 88.913605 -281.76455)
			(xy 88.890082 -281.718383) (xy 88.87407 -281.669104) (xy 88.865964 -281.617927) (xy 88.865456 -281.59202)
			(xy 87.64524 -281.59202) (xy 87.644785 -281.617367) (xy 87.637009 -281.66746) (xy 87.621658 -281.715773)
			(xy 87.599094 -281.761168) (xy 87.569849 -281.802575) (xy 87.534611 -281.839019) (xy 87.494211 -281.86964)
			(xy 87.449601 -281.893718) (xy 87.401831 -281.910686) (xy 87.377016 -281.91587) (xy 87.354156 -281.920188)
			(xy 87.149178 -282.27528) (xy 87.156798 -282.297124) (xy 87.165433 -282.32347) (xy 87.174753 -282.378118)
			(xy 87.17534 -282.405836) (xy 87.455756 -282.405836) (xy 87.456264 -282.379949) (xy 87.464363 -282.328811)
			(xy 87.480362 -282.279571) (xy 87.503868 -282.233439) (xy 87.5343 -282.191552) (xy 87.57091 -282.154942)
			(xy 87.612797 -282.12451) (xy 87.658929 -282.101004) (xy 87.708169 -282.085005) (xy 87.759307 -282.076906)
			(xy 87.811081 -282.076906) (xy 87.862219 -282.085005) (xy 87.911459 -282.101004) (xy 87.957591 -282.12451)
			(xy 87.999478 -282.154942) (xy 88.036088 -282.191552) (xy 88.06652 -282.233439) (xy 88.090026 -282.279571)
			(xy 88.106025 -282.328811) (xy 88.114124 -282.379949) (xy 88.114632 -282.405836) (xy 88.114145 -282.431709)
			(xy 88.396026 -282.431709) (xy 88.396026 -282.379891) (xy 88.404133 -282.328711) (xy 88.420147 -282.27943)
			(xy 88.443674 -282.233261) (xy 88.474134 -282.191341) (xy 88.510778 -282.154703) (xy 88.552702 -282.124249)
			(xy 88.598874 -282.100729) (xy 88.648158 -282.084722) (xy 88.699339 -282.076622) (xy 88.725248 -282.076144)
			(xy 88.750741 -282.076648) (xy 88.801118 -282.084503) (xy 88.849682 -282.100032) (xy 88.895269 -282.122865)
			(xy 88.936791 -282.152454) (xy 88.973252 -282.188093) (xy 88.9889 -282.208224) (xy 89.401396 -282.208224)
			(xy 89.417024 -282.188075) (xy 89.453488 -282.152433) (xy 89.495013 -282.122841) (xy 89.540604 -282.100006)
			(xy 89.589171 -282.084474) (xy 89.639553 -282.076619) (xy 89.665048 -282.076144) (xy 89.690956 -282.076584)
			(xy 89.742132 -282.084696) (xy 89.79141 -282.100714) (xy 89.837576 -282.124242) (xy 89.879493 -282.154702)
			(xy 89.916129 -282.191344) (xy 89.946583 -282.233265) (xy 89.970105 -282.279434) (xy 89.986115 -282.328714)
			(xy 89.99422 -282.379892) (xy 89.99422 -282.431708) (xy 89.986115 -282.482886) (xy 89.970105 -282.532166)
			(xy 89.946583 -282.578335) (xy 89.916129 -282.620256) (xy 89.879493 -282.656898) (xy 89.837576 -282.687358)
			(xy 89.79141 -282.710886) (xy 89.742132 -282.726904) (xy 89.690956 -282.735016) (xy 89.665048 -282.735528)
			(xy 89.639556 -282.734998) (xy 89.589182 -282.727145) (xy 89.54062 -282.711619) (xy 89.495033 -282.688791)
			(xy 89.453511 -282.659207) (xy 89.417046 -282.623576) (xy 89.401396 -282.603448) (xy 88.9889 -282.603448)
			(xy 88.973236 -282.623567) (xy 88.936776 -282.659207) (xy 88.895259 -282.6888) (xy 88.849675 -282.71164)
			(xy 88.801115 -282.727179) (xy 88.750741 -282.735046) (xy 88.725248 -282.735528) (xy 88.699339 -282.734978)
			(xy 88.648158 -282.726878) (xy 88.598874 -282.710871) (xy 88.552702 -282.687351) (xy 88.510778 -282.656897)
			(xy 88.474134 -282.620259) (xy 88.443674 -282.578339) (xy 88.420147 -282.53217) (xy 88.404133 -282.482889)
			(xy 88.396026 -282.431709) (xy 88.114145 -282.431709) (xy 88.11411 -282.433545) (xy 88.10491 -282.488191)
			(xy 88.096344 -282.514548) (xy 88.08847 -282.536646) (xy 88.293702 -282.891738) (xy 88.316562 -282.896056)
			(xy 88.341357 -282.90128) (xy 88.389096 -282.918263) (xy 88.433673 -282.942351) (xy 88.47404 -282.972977)
			(xy 88.509244 -283.009419) (xy 88.538458 -283.050819) (xy 88.560992 -283.096202) (xy 88.576316 -283.144498)
			(xy 88.584068 -283.194571) (xy 88.584532 -283.219906) (xy 90.745056 -283.219906) (xy 90.74558 -283.194573)
			(xy 90.75333 -283.144505) (xy 90.768649 -283.096211) (xy 90.791176 -283.05083) (xy 90.820381 -283.009429)
			(xy 90.855576 -282.972983) (xy 90.895932 -282.942351) (xy 90.9405 -282.918254) (xy 90.988229 -282.901258)
			(xy 91.013026 -282.896056) (xy 91.035886 -282.891738) (xy 91.241118 -282.536392) (xy 91.233498 -282.514548)
			(xy 91.224857 -282.488204) (xy 91.215541 -282.433555) (xy 91.214956 -282.405836) (xy 91.215464 -282.379929)
			(xy 91.22357 -282.328752) (xy 91.239582 -282.279473) (xy 91.263105 -282.233306) (xy 91.293561 -282.191387)
			(xy 91.330199 -282.154749) (xy 91.372118 -282.124293) (xy 91.418285 -282.10077) (xy 91.467564 -282.084758)
			(xy 91.518741 -282.076652) (xy 91.570555 -282.076652) (xy 91.621732 -282.084758) (xy 91.671011 -282.10077)
			(xy 91.717178 -282.124293) (xy 91.759097 -282.154749) (xy 91.795735 -282.191387) (xy 91.826191 -282.233306)
			(xy 91.849714 -282.279473) (xy 91.865726 -282.328752) (xy 91.873832 -282.379929) (xy 91.87434 -282.405836)
			(xy 93.094556 -282.405836) (xy 93.094974 -282.380488) (xy 93.102757 -282.330393) (xy 93.118114 -282.282079)
			(xy 93.140683 -282.236685) (xy 93.169933 -282.195278) (xy 93.205175 -282.158835) (xy 93.245578 -282.128214)
			(xy 93.290191 -282.104137) (xy 93.337964 -282.08717) (xy 93.36278 -282.081986) (xy 93.38564 -282.077668)
			(xy 93.590618 -281.72283) (xy 93.582744 -281.700986) (xy 93.574162 -281.674568) (xy 93.564967 -281.619792)
			(xy 93.564456 -281.59202) (xy 93.564964 -281.566133) (xy 93.573063 -281.514995) (xy 93.589062 -281.465755)
			(xy 93.612568 -281.419623) (xy 93.643 -281.377736) (xy 93.67961 -281.341126) (xy 93.721497 -281.310694)
			(xy 93.767629 -281.287188) (xy 93.816869 -281.271189) (xy 93.868007 -281.26309) (xy 93.919781 -281.26309)
			(xy 93.970919 -281.271189) (xy 94.020159 -281.287188) (xy 94.066291 -281.310694) (xy 94.108178 -281.341126)
			(xy 94.144788 -281.377736) (xy 94.17522 -281.419623) (xy 94.198726 -281.465755) (xy 94.214725 -281.514995)
			(xy 94.222824 -281.566133) (xy 94.223332 -281.59202) (xy 94.222842 -281.617354) (xy 94.215087 -281.667425)
			(xy 94.199764 -281.71572) (xy 94.177233 -281.761102) (xy 94.148024 -281.802503) (xy 94.112825 -281.838948)
			(xy 94.072465 -281.869579) (xy 94.027893 -281.893676) (xy 93.980161 -281.910669) (xy 93.955362 -281.91587)
			(xy 93.932502 -281.920188) (xy 93.727524 -282.275026) (xy 93.735398 -282.297124) (xy 93.744018 -282.323474)
			(xy 93.753346 -282.378119) (xy 93.75394 -282.405836) (xy 94.974156 -282.405836) (xy 94.974616 -282.380501)
			(xy 94.982377 -282.33043) (xy 94.997705 -282.282135) (xy 95.020241 -282.236753) (xy 95.049454 -282.195352)
			(xy 95.084656 -282.158908) (xy 95.125019 -282.128277) (xy 95.169592 -282.104181) (xy 95.217327 -282.087187)
			(xy 95.242126 -282.081986) (xy 95.264986 -282.077668) (xy 95.470218 -281.722322) (xy 95.462598 -281.700478)
			(xy 95.45397 -281.674197) (xy 95.444658 -281.619675) (xy 95.444056 -281.59202) (xy 95.444564 -281.566113)
			(xy 95.45267 -281.514936) (xy 95.468682 -281.465657) (xy 95.492205 -281.41949) (xy 95.522661 -281.377571)
			(xy 95.559299 -281.340933) (xy 95.601218 -281.310477) (xy 95.647385 -281.286954) (xy 95.696664 -281.270942)
			(xy 95.747841 -281.262836) (xy 95.799655 -281.262836) (xy 95.850832 -281.270942) (xy 95.900111 -281.286954)
			(xy 95.946278 -281.310477) (xy 95.988197 -281.340933) (xy 96.024835 -281.377571) (xy 96.055291 -281.41949)
			(xy 96.078814 -281.465657) (xy 96.094826 -281.514936) (xy 96.102932 -281.566113) (xy 96.10344 -281.59202)
			(xy 97.323656 -281.59202) (xy 97.32415 -281.566675) (xy 97.33192 -281.516583) (xy 97.347266 -281.468271)
			(xy 97.369824 -281.422876) (xy 97.399064 -281.381469) (xy 97.434298 -281.345025) (xy 97.474693 -281.314403)
			(xy 97.5193 -281.290323) (xy 97.567066 -281.273355) (xy 97.59188 -281.26817) (xy 97.61474 -281.263852)
			(xy 97.819718 -280.909014) (xy 97.811844 -280.88717) (xy 97.803259 -280.860753) (xy 97.794066 -280.805977)
			(xy 97.793556 -280.778204) (xy 97.794064 -280.752317) (xy 97.802163 -280.701179) (xy 97.818162 -280.651939)
			(xy 97.841668 -280.605807) (xy 97.8721 -280.56392) (xy 97.90871 -280.52731) (xy 97.950597 -280.496878)
			(xy 97.996729 -280.473372) (xy 98.045969 -280.457373) (xy 98.097107 -280.449274) (xy 98.148881 -280.449274)
			(xy 98.200019 -280.457373) (xy 98.249259 -280.473372) (xy 98.295391 -280.496878) (xy 98.337278 -280.52731)
			(xy 98.373888 -280.56392) (xy 98.40432 -280.605807) (xy 98.427826 -280.651939) (xy 98.443825 -280.701179)
			(xy 98.451924 -280.752317) (xy 98.452432 -280.778204) (xy 100.612956 -280.778204) (xy 100.613464 -280.752317)
			(xy 100.621563 -280.701179) (xy 100.637562 -280.651939) (xy 100.661068 -280.605807) (xy 100.6915 -280.56392)
			(xy 100.72811 -280.52731) (xy 100.769997 -280.496878) (xy 100.816129 -280.473372) (xy 100.865369 -280.457373)
			(xy 100.916507 -280.449274) (xy 100.968281 -280.449274) (xy 101.019419 -280.457373) (xy 101.068659 -280.473372)
			(xy 101.114791 -280.496878) (xy 101.156678 -280.52731) (xy 101.193288 -280.56392) (xy 101.22372 -280.605807)
			(xy 101.247226 -280.651939) (xy 101.263225 -280.701179) (xy 101.271324 -280.752317) (xy 101.271832 -280.778204)
			(xy 103.432356 -280.778204) (xy 103.432864 -280.752317) (xy 103.440963 -280.701179) (xy 103.456962 -280.651939)
			(xy 103.480468 -280.605807) (xy 103.5109 -280.56392) (xy 103.54751 -280.52731) (xy 103.589397 -280.496878)
			(xy 103.635529 -280.473372) (xy 103.684769 -280.457373) (xy 103.735907 -280.449274) (xy 103.787681 -280.449274)
			(xy 103.838819 -280.457373) (xy 103.888059 -280.473372) (xy 103.934191 -280.496878) (xy 103.976078 -280.52731)
			(xy 104.012688 -280.56392) (xy 104.04312 -280.605807) (xy 104.066626 -280.651939) (xy 104.082625 -280.701179)
			(xy 104.090724 -280.752317) (xy 104.091232 -280.778204) (xy 104.372156 -280.778204) (xy 104.372678 -280.752871)
			(xy 104.380429 -280.702803) (xy 104.395748 -280.654509) (xy 104.418275 -280.609127) (xy 104.44748 -280.567726)
			(xy 104.482675 -280.531281) (xy 104.523032 -280.500649) (xy 104.567599 -280.476552) (xy 104.615329 -280.459556)
			(xy 104.640126 -280.454354) (xy 104.662986 -280.450036) (xy 104.868218 -280.09469) (xy 104.860598 -280.072592)
			(xy 104.851973 -280.04631) (xy 104.842659 -279.991789) (xy 104.842056 -279.964134) (xy 104.842564 -279.938227)
			(xy 104.85067 -279.88705) (xy 104.866682 -279.837771) (xy 104.890205 -279.791604) (xy 104.920661 -279.749685)
			(xy 104.957299 -279.713047) (xy 104.999218 -279.682591) (xy 105.045385 -279.659068) (xy 105.094664 -279.643056)
			(xy 105.145841 -279.63495) (xy 105.197655 -279.63495) (xy 105.248832 -279.643056) (xy 105.298111 -279.659068)
			(xy 105.344278 -279.682591) (xy 105.386197 -279.713047) (xy 105.422835 -279.749685) (xy 105.453291 -279.791604)
			(xy 105.476814 -279.837771) (xy 105.492826 -279.88705) (xy 105.500932 -279.938227) (xy 105.50144 -279.964134)
			(xy 105.501001 -279.989499) (xy 105.500926 -279.989983) (xy 336.806103 -279.989983) (xy 336.806103 -279.938217)
			(xy 336.814201 -279.887089) (xy 336.830196 -279.837856) (xy 336.853696 -279.791732) (xy 336.884121 -279.749851)
			(xy 336.920722 -279.713245) (xy 336.9626 -279.682815) (xy 337.008721 -279.659311) (xy 337.057952 -279.64331)
			(xy 337.109079 -279.635206) (xy 337.134962 -279.634696) (xy 337.160473 -279.635206) (xy 337.210886 -279.64306)
			(xy 337.259487 -279.658588) (xy 337.305115 -279.681418) (xy 337.346681 -279.711006) (xy 337.383193 -279.746643)
			(xy 337.398868 -279.766776) (xy 337.810856 -279.766776) (xy 337.826548 -279.746656) (xy 337.863055 -279.711012)
			(xy 337.904617 -279.681418) (xy 337.950241 -279.658579) (xy 337.998839 -279.643041) (xy 338.049251 -279.635176)
			(xy 338.074762 -279.634696) (xy 338.100656 -279.635106) (xy 338.151807 -279.643203) (xy 338.201062 -279.659201)
			(xy 338.247208 -279.682709) (xy 338.289107 -279.713146) (xy 338.325729 -279.749764) (xy 338.356171 -279.79166)
			(xy 338.379684 -279.837803) (xy 338.395689 -279.887056) (xy 338.403791 -279.938206) (xy 338.403791 -279.964134)
			(xy 344.323924 -279.964134) (xy 344.324432 -279.938227) (xy 344.332538 -279.88705) (xy 344.34855 -279.837771)
			(xy 344.372073 -279.791604) (xy 344.402529 -279.749685) (xy 344.439167 -279.713047) (xy 344.481086 -279.682591)
			(xy 344.527253 -279.659068) (xy 344.576532 -279.643056) (xy 344.627709 -279.63495) (xy 344.679523 -279.63495)
			(xy 344.7307 -279.643056) (xy 344.779979 -279.659068) (xy 344.826146 -279.682591) (xy 344.868065 -279.713047)
			(xy 344.904703 -279.749685) (xy 344.935159 -279.791604) (xy 344.958682 -279.837771) (xy 344.974694 -279.88705)
			(xy 344.9828 -279.938227) (xy 344.983308 -279.964134) (xy 344.982671 -279.991925) (xy 344.973225 -280.046702)
			(xy 344.964512 -280.0731) (xy 344.956892 -280.095198) (xy 345.16187 -280.450036) (xy 345.18473 -280.454354)
			(xy 345.209535 -280.459531) (xy 345.257274 -280.476523) (xy 345.30185 -280.500619) (xy 345.342215 -280.531252)
			(xy 345.377417 -280.5677) (xy 345.406629 -280.609105) (xy 345.429161 -280.654492) (xy 345.444484 -280.702792)
			(xy 345.452236 -280.752868) (xy 345.4527 -280.778204) (xy 345.452192 -280.804091) (xy 345.444093 -280.855229)
			(xy 345.428094 -280.904469) (xy 345.404588 -280.950601) (xy 345.374156 -280.992488) (xy 345.337546 -281.029098)
			(xy 345.295659 -281.05953) (xy 345.249527 -281.083036) (xy 345.200287 -281.099035) (xy 345.149149 -281.107134)
			(xy 345.097375 -281.107134) (xy 345.046237 -281.099035) (xy 344.996997 -281.083036) (xy 344.950865 -281.05953)
			(xy 344.908978 -281.029098) (xy 344.872368 -280.992488) (xy 344.841936 -280.950601) (xy 344.81843 -280.904469)
			(xy 344.802431 -280.855229) (xy 344.794332 -280.804091) (xy 344.793824 -280.778204) (xy 344.794353 -280.750496)
			(xy 344.803549 -280.695849) (xy 344.812112 -280.669492) (xy 344.819986 -280.647394) (xy 344.614754 -280.292302)
			(xy 344.591894 -280.287984) (xy 344.567101 -280.282754) (xy 344.519365 -280.265768) (xy 344.47479 -280.241678)
			(xy 344.434426 -280.211052) (xy 344.399223 -280.174611) (xy 344.37001 -280.133213) (xy 344.347475 -280.087832)
			(xy 344.332148 -280.039538) (xy 344.32439 -279.989468) (xy 344.323924 -279.964134) (xy 338.403791 -279.964134)
			(xy 338.403791 -279.989994) (xy 338.395689 -280.041144) (xy 338.379684 -280.090397) (xy 338.356171 -280.13654)
			(xy 338.325729 -280.178436) (xy 338.289107 -280.215054) (xy 338.247208 -280.245491) (xy 338.201062 -280.268999)
			(xy 338.151807 -280.284997) (xy 338.100656 -280.293094) (xy 338.074762 -280.293572) (xy 338.049249 -280.293131)
			(xy 337.998832 -280.285263) (xy 337.950229 -280.269723) (xy 337.9046 -280.24688) (xy 337.863036 -280.21728)
			(xy 337.826528 -280.18163) (xy 337.810856 -280.161492) (xy 337.398868 -280.161492) (xy 337.383211 -280.181641)
			(xy 337.346698 -280.217284) (xy 337.305129 -280.246877) (xy 337.259498 -280.269711) (xy 337.210893 -280.285241)
			(xy 337.160475 -280.293097) (xy 337.134962 -280.293572) (xy 337.109079 -280.292994) (xy 337.057952 -280.28489)
			(xy 337.008721 -280.268889) (xy 336.9626 -280.245385) (xy 336.920722 -280.214955) (xy 336.884121 -280.178349)
			(xy 336.853696 -280.136468) (xy 336.830196 -280.090344) (xy 336.814201 -280.041111) (xy 336.806103 -279.989983)
			(xy 105.500926 -279.989983) (xy 105.493248 -280.039631) (xy 105.4779 -280.087982) (xy 105.45532 -280.133408)
			(xy 105.426041 -280.174835) (xy 105.390757 -280.211282) (xy 105.350301 -280.241888) (xy 105.305631 -280.26593)
			(xy 105.257803 -280.282837) (xy 105.232962 -280.287984) (xy 105.209848 -280.292302) (xy 105.00487 -280.647394)
			(xy 105.012744 -280.669492) (xy 105.021304 -280.69585) (xy 105.030503 -280.750496) (xy 105.031032 -280.778204)
			(xy 105.030524 -280.804091) (xy 105.030521 -280.804107) (xy 105.31222 -280.804107) (xy 105.31222 -280.752293)
			(xy 105.320326 -280.701118) (xy 105.336337 -280.65184) (xy 105.359859 -280.605674) (xy 105.390314 -280.563756)
			(xy 105.426951 -280.527118) (xy 105.468869 -280.496662) (xy 105.515035 -280.473139) (xy 105.564312 -280.457127)
			(xy 105.615487 -280.449021) (xy 105.641394 -280.448512) (xy 105.666906 -280.448992) (xy 105.717321 -280.456852)
			(xy 105.765922 -280.472385) (xy 105.811551 -280.495221) (xy 105.853116 -280.524814) (xy 105.889626 -280.560457)
			(xy 105.9053 -280.580592) (xy 106.317288 -280.580592) (xy 106.332966 -280.560461) (xy 106.369475 -280.524817)
			(xy 106.41104 -280.495223) (xy 106.456667 -280.472386) (xy 106.505268 -280.456852) (xy 106.555682 -280.44899)
			(xy 106.581194 -280.448512) (xy 106.607104 -280.448985) (xy 106.658286 -280.457091) (xy 106.70757 -280.473103)
			(xy 106.753743 -280.496628) (xy 106.795666 -280.527087) (xy 106.832309 -280.563729) (xy 106.862768 -280.605652)
			(xy 106.886294 -280.651824) (xy 106.902308 -280.701108) (xy 106.910414 -280.75229) (xy 106.910414 -280.804105)
			(xy 334.45632 -280.804105) (xy 334.45632 -280.752295) (xy 334.464425 -280.701122) (xy 334.480434 -280.651848)
			(xy 334.503953 -280.605684) (xy 334.534405 -280.563767) (xy 334.571038 -280.527129) (xy 334.612951 -280.496673)
			(xy 334.659113 -280.473148) (xy 334.708385 -280.457133) (xy 334.759557 -280.449023) (xy 334.785462 -280.448512)
			(xy 334.810955 -280.449019) (xy 334.861331 -280.456875) (xy 334.909894 -280.472404) (xy 334.955481 -280.495237)
			(xy 334.997003 -280.524825) (xy 335.033465 -280.560462) (xy 335.049114 -280.580592) (xy 335.46161 -280.580592)
			(xy 335.477279 -280.560477) (xy 335.513736 -280.524835) (xy 335.555252 -280.495239) (xy 335.600835 -280.472399)
			(xy 335.649395 -280.45686) (xy 335.699769 -280.448993) (xy 335.725262 -280.448512) (xy 335.751174 -280.448983)
			(xy 335.80236 -280.457084) (xy 335.851648 -280.473094) (xy 335.897825 -280.496618) (xy 335.939753 -280.527076)
			(xy 335.9764 -280.563718) (xy 336.006863 -280.605643) (xy 336.030391 -280.651817) (xy 336.046407 -280.701103)
			(xy 336.054514 -280.752288) (xy 336.054514 -280.804112) (xy 336.046407 -280.855297) (xy 336.030391 -280.904583)
			(xy 336.006863 -280.950757) (xy 335.9764 -280.992682) (xy 335.939753 -281.029324) (xy 335.897825 -281.059782)
			(xy 335.851648 -281.083306) (xy 335.80236 -281.099316) (xy 335.751174 -281.107417) (xy 335.725262 -281.107896)
			(xy 335.699767 -281.107441) (xy 335.649389 -281.099574) (xy 335.600825 -281.084033) (xy 335.555238 -281.061192)
			(xy 335.513718 -281.031594) (xy 335.477257 -280.99595) (xy 335.46161 -280.975816) (xy 335.049114 -280.975816)
			(xy 335.033491 -280.995969) (xy 334.997025 -281.031609) (xy 334.955498 -281.061199) (xy 334.909906 -281.084033)
			(xy 334.861339 -281.099564) (xy 334.810957 -281.107421) (xy 334.785462 -281.107896) (xy 334.759557 -281.107377)
			(xy 334.708385 -281.099267) (xy 334.659113 -281.083252) (xy 334.612951 -281.059727) (xy 334.571038 -281.029271)
			(xy 334.534405 -280.992633) (xy 334.503953 -280.950716) (xy 334.480434 -280.904552) (xy 334.464425 -280.855278)
			(xy 334.45632 -280.804105) (xy 106.910414 -280.804105) (xy 106.910414 -280.80411) (xy 106.902308 -280.855292)
			(xy 106.886294 -280.904576) (xy 106.862768 -280.950748) (xy 106.832309 -280.992671) (xy 106.795666 -281.029313)
			(xy 106.753743 -281.059772) (xy 106.70757 -281.083297) (xy 106.658286 -281.099309) (xy 106.607104 -281.107415)
			(xy 106.581194 -281.107896) (xy 106.555682 -281.107421) (xy 106.505267 -281.09956) (xy 106.456665 -281.084025)
			(xy 106.411037 -281.061188) (xy 106.369472 -281.031595) (xy 106.332962 -280.995951) (xy 106.317288 -280.975816)
			(xy 105.9053 -280.975816) (xy 105.889631 -280.995955) (xy 105.85312 -281.031598) (xy 105.811553 -281.06119)
			(xy 105.765924 -281.084026) (xy 105.717322 -281.099559) (xy 105.666906 -281.107419) (xy 105.641394 -281.107896)
			(xy 105.615487 -281.107379) (xy 105.564312 -281.099273) (xy 105.515035 -281.083261) (xy 105.468869 -281.059738)
			(xy 105.426951 -281.029282) (xy 105.390314 -280.992644) (xy 105.359859 -280.950726) (xy 105.336337 -280.90456)
			(xy 105.320326 -280.855282) (xy 105.31222 -280.804107) (xy 105.030521 -280.804107) (xy 105.022425 -280.855229)
			(xy 105.006426 -280.904469) (xy 104.98292 -280.950601) (xy 104.952488 -280.992488) (xy 104.915878 -281.029098)
			(xy 104.873991 -281.05953) (xy 104.827859 -281.083036) (xy 104.778619 -281.099035) (xy 104.727481 -281.107134)
			(xy 104.675707 -281.107134) (xy 104.624569 -281.099035) (xy 104.575329 -281.083036) (xy 104.529197 -281.05953)
			(xy 104.48731 -281.029098) (xy 104.4507 -280.992488) (xy 104.420268 -280.950601) (xy 104.396762 -280.904469)
			(xy 104.380763 -280.855229) (xy 104.372664 -280.804091) (xy 104.372156 -280.778204) (xy 104.091232 -280.778204)
			(xy 104.091232 -280.778712) (xy 104.090641 -280.806228) (xy 104.081455 -280.860489) (xy 104.072944 -280.886662)
			(xy 104.065324 -280.908506) (xy 104.270556 -281.263852) (xy 104.293416 -281.26817) (xy 104.318226 -281.273386)
			(xy 104.366003 -281.290334) (xy 104.410622 -281.314398) (xy 104.451028 -281.345012) (xy 104.48627 -281.381453)
			(xy 104.515516 -281.422861) (xy 104.538075 -281.468259) (xy 104.553416 -281.516576) (xy 104.561176 -281.566673)
			(xy 104.56164 -281.59202) (xy 105.781856 -281.59202) (xy 105.782364 -281.566113) (xy 105.79047 -281.514936)
			(xy 105.806482 -281.465657) (xy 105.830005 -281.41949) (xy 105.860461 -281.377571) (xy 105.897099 -281.340933)
			(xy 105.939018 -281.310477) (xy 105.985185 -281.286954) (xy 106.034464 -281.270942) (xy 106.085641 -281.262836)
			(xy 106.137455 -281.262836) (xy 106.188632 -281.270942) (xy 106.237911 -281.286954) (xy 106.284078 -281.310477)
			(xy 106.325997 -281.340933) (xy 106.362635 -281.377571) (xy 106.393091 -281.41949) (xy 106.416614 -281.465657)
			(xy 106.432626 -281.514936) (xy 106.440732 -281.566113) (xy 106.44124 -281.59202) (xy 106.44067 -281.619802)
			(xy 106.431345 -281.674578) (xy 106.422698 -281.700986) (xy 106.414824 -281.72283) (xy 106.619802 -282.077668)
			(xy 106.642662 -282.081986) (xy 106.667464 -282.087182) (xy 106.715205 -282.104167) (xy 106.759784 -282.128258)
			(xy 106.800151 -282.158887) (xy 106.835356 -282.195333) (xy 106.864568 -282.236737) (xy 106.8871 -282.282123)
			(xy 106.902422 -282.330424) (xy 106.910171 -282.3805) (xy 106.910632 -282.405836) (xy 334.456024 -282.405836)
			(xy 334.456468 -282.38049) (xy 334.46425 -282.330397) (xy 334.479605 -282.282085) (xy 334.502171 -282.236692)
			(xy 334.531418 -282.195286) (xy 334.566656 -282.158843) (xy 334.607056 -282.128222) (xy 334.651665 -282.104142)
			(xy 334.699433 -282.087172) (xy 334.724248 -282.081986) (xy 334.747108 -282.077668) (xy 334.952086 -281.722576)
			(xy 334.944466 -281.700732) (xy 334.93582 -281.67439) (xy 334.926507 -281.619739) (xy 334.925924 -281.59202)
			(xy 334.926432 -281.566113) (xy 334.934538 -281.514936) (xy 334.95055 -281.465657) (xy 334.974073 -281.41949)
			(xy 335.004529 -281.377571) (xy 335.041167 -281.340933) (xy 335.083086 -281.310477) (xy 335.129253 -281.286954)
			(xy 335.178532 -281.270942) (xy 335.229709 -281.262836) (xy 335.281523 -281.262836) (xy 335.3327 -281.270942)
			(xy 335.381979 -281.286954) (xy 335.428146 -281.310477) (xy 335.470065 -281.340933) (xy 335.506703 -281.377571)
			(xy 335.537159 -281.41949) (xy 335.560682 -281.465657) (xy 335.576694 -281.514936) (xy 335.5848 -281.566113)
			(xy 335.585308 -281.59202) (xy 336.805524 -281.59202) (xy 336.806044 -281.566676) (xy 336.813813 -281.516587)
			(xy 336.829157 -281.468277) (xy 336.851713 -281.422884) (xy 336.88095 -281.381477) (xy 336.916179 -281.345033)
			(xy 336.956571 -281.31441) (xy 337.001174 -281.290329) (xy 337.048936 -281.273357) (xy 337.073748 -281.26817)
			(xy 337.096608 -281.263852) (xy 337.301586 -280.909014) (xy 337.293966 -280.88717) (xy 337.285321 -280.860761)
			(xy 337.276 -280.805986) (xy 337.275424 -280.778204) (xy 337.275919 -280.752309) (xy 337.284017 -280.701155)
			(xy 337.300013 -280.651897) (xy 337.323515 -280.605746) (xy 337.353945 -280.563837) (xy 337.390553 -280.527202)
			(xy 337.432439 -280.496742) (xy 337.478573 -280.473206) (xy 337.527819 -280.457173) (xy 337.578967 -280.449038)
			(xy 337.604862 -280.448512) (xy 337.630738 -280.449004) (xy 337.681855 -280.457091) (xy 337.731077 -280.473073)
			(xy 337.777195 -280.496556) (xy 337.819073 -280.526962) (xy 337.855681 -280.563542) (xy 337.886118 -280.605398)
			(xy 337.909634 -280.651499) (xy 337.925652 -280.70071) (xy 337.933777 -280.75182) (xy 337.9343 -280.777696)
			(xy 337.9343 -280.778204) (xy 340.094824 -280.778204) (xy 340.095293 -280.752294) (xy 340.103399 -280.701112)
			(xy 340.119413 -280.651828) (xy 340.142939 -280.605656) (xy 340.173399 -280.563733) (xy 340.210042 -280.527091)
			(xy 340.251966 -280.496633) (xy 340.298139 -280.473108) (xy 340.347423 -280.457097) (xy 340.398606 -280.448992)
			(xy 340.424516 -280.448512) (xy 340.450394 -280.448954) (xy 340.501512 -280.457049) (xy 340.550736 -280.473038)
			(xy 340.596853 -280.496528) (xy 340.638731 -280.52694) (xy 340.675338 -280.563526) (xy 340.705774 -280.605386)
			(xy 340.729289 -280.651491) (xy 340.745307 -280.700705) (xy 340.753431 -280.751819) (xy 340.753954 -280.777696)
			(xy 340.753954 -280.778204) (xy 340.753418 -280.804105) (xy 342.91452 -280.804105) (xy 342.91452 -280.752295)
			(xy 342.922625 -280.701122) (xy 342.938634 -280.651848) (xy 342.962153 -280.605684) (xy 342.992605 -280.563767)
			(xy 343.029238 -280.527129) (xy 343.071151 -280.496673) (xy 343.117313 -280.473148) (xy 343.166585 -280.457133)
			(xy 343.217757 -280.449023) (xy 343.243662 -280.448512) (xy 343.269173 -280.449015) (xy 343.319587 -280.45687)
			(xy 343.368188 -280.472399) (xy 343.413817 -280.49523) (xy 343.455383 -280.524819) (xy 343.491894 -280.560459)
			(xy 343.507568 -280.580592) (xy 343.91981 -280.580592) (xy 343.935476 -280.56045) (xy 343.971987 -280.524807)
			(xy 344.013554 -280.495214) (xy 344.059184 -280.472379) (xy 344.107788 -280.456847) (xy 344.158204 -280.448988)
			(xy 344.183716 -280.448512) (xy 344.209623 -280.449014) (xy 344.260798 -280.457121) (xy 344.310075 -280.473134)
			(xy 344.356241 -280.496659) (xy 344.398158 -280.527115) (xy 344.434795 -280.563754) (xy 344.465249 -280.605673)
			(xy 344.488772 -280.65184) (xy 344.504782 -280.701117) (xy 344.512888 -280.752293) (xy 344.512888 -280.804107)
			(xy 344.504782 -280.855283) (xy 344.488772 -280.90456) (xy 344.465249 -280.950727) (xy 344.434795 -280.992646)
			(xy 344.398158 -281.029285) (xy 344.356241 -281.059741) (xy 344.310075 -281.083266) (xy 344.260798 -281.099279)
			(xy 344.209623 -281.107386) (xy 344.183716 -281.107896) (xy 344.158205 -281.107405) (xy 344.107791 -281.099547)
			(xy 344.059189 -281.084016) (xy 344.013561 -281.061182) (xy 343.971995 -281.031591) (xy 343.935484 -280.99595)
			(xy 343.91981 -280.975816) (xy 343.507568 -280.975816) (xy 343.491917 -280.99597) (xy 343.455403 -281.031612)
			(xy 343.413832 -281.061203) (xy 343.368199 -281.084036) (xy 343.319593 -281.099566) (xy 343.269175 -281.107421)
			(xy 343.243662 -281.107896) (xy 343.217757 -281.107377) (xy 343.166585 -281.099267) (xy 343.117313 -281.083252)
			(xy 343.071151 -281.059727) (xy 343.029238 -281.029271) (xy 342.992605 -280.992633) (xy 342.962153 -280.950716)
			(xy 342.938634 -280.904552) (xy 342.922625 -280.855278) (xy 342.91452 -280.804105) (xy 340.753418 -280.804105)
			(xy 340.753379 -280.805986) (xy 340.744058 -280.860762) (xy 340.735412 -280.88717) (xy 340.727792 -280.909014)
			(xy 340.93277 -281.263852) (xy 340.95563 -281.26817) (xy 340.980439 -281.273332) (xy 341.028178 -281.290325)
			(xy 341.072756 -281.314423) (xy 341.113121 -281.345058) (xy 341.148323 -281.381508) (xy 341.177534 -281.422915)
			(xy 341.200066 -281.468304) (xy 341.215387 -281.516606) (xy 341.223138 -281.566683) (xy 341.2236 -281.59202)
			(xy 341.223092 -281.617907) (xy 341.214993 -281.669045) (xy 341.198994 -281.718285) (xy 341.175488 -281.764417)
			(xy 341.145056 -281.806304) (xy 341.108446 -281.842914) (xy 341.066559 -281.873346) (xy 341.020427 -281.896852)
			(xy 340.971187 -281.912851) (xy 340.920049 -281.92095) (xy 340.868275 -281.92095) (xy 340.817137 -281.912851)
			(xy 340.767897 -281.896852) (xy 340.721765 -281.873346) (xy 340.679878 -281.842914) (xy 340.643268 -281.806304)
			(xy 340.612836 -281.764417) (xy 340.58933 -281.718285) (xy 340.573331 -281.669045) (xy 340.565232 -281.617907)
			(xy 340.564724 -281.59202) (xy 340.565273 -281.564313) (xy 340.574459 -281.509667) (xy 340.583012 -281.483308)
			(xy 340.590632 -281.461464) (xy 340.385654 -281.106372) (xy 340.362794 -281.102054) (xy 340.337994 -281.096852)
			(xy 340.290256 -281.079864) (xy 340.24568 -281.055771) (xy 340.205315 -281.025142) (xy 340.170112 -280.988697)
			(xy 340.140899 -280.947295) (xy 340.118366 -280.901911) (xy 340.103042 -280.853613) (xy 340.095288 -280.803539)
			(xy 340.094824 -280.778204) (xy 337.9343 -280.778204) (xy 337.933779 -280.803526) (xy 337.926048 -280.853575)
			(xy 337.910753 -280.901853) (xy 337.888254 -280.947223) (xy 337.859081 -280.988619) (xy 337.82392 -281.025066)
			(xy 337.783598 -281.055707) (xy 337.739064 -281.07982) (xy 337.691367 -281.096838) (xy 337.666584 -281.102054)
			(xy 337.643724 -281.106372) (xy 337.438746 -281.46121) (xy 337.446366 -281.483054) (xy 337.454977 -281.50934)
			(xy 337.464301 -281.563858) (xy 337.464908 -281.591512) (xy 337.464908 -281.59202) (xy 337.4644 -281.617904)
			(xy 338.685436 -281.617904) (xy 338.685436 -281.566096) (xy 338.69354 -281.514926) (xy 338.709548 -281.465654)
			(xy 338.733067 -281.419492) (xy 338.763517 -281.377577) (xy 338.800148 -281.340942) (xy 338.84206 -281.310487)
			(xy 338.888219 -281.286963) (xy 338.937489 -281.270949) (xy 338.988658 -281.262839) (xy 339.014562 -281.262328)
			(xy 339.040073 -281.262825) (xy 339.090487 -281.270681) (xy 339.139089 -281.28621) (xy 339.184718 -281.309042)
			(xy 339.226284 -281.338633) (xy 339.262794 -281.374274) (xy 339.278468 -281.394408) (xy 339.690456 -281.394408)
			(xy 339.706157 -281.374295) (xy 339.742661 -281.33865) (xy 339.784221 -281.309053) (xy 339.829844 -281.286213)
			(xy 339.878441 -281.270675) (xy 339.928852 -281.262808) (xy 339.954362 -281.262328) (xy 339.980275 -281.262767)
			(xy 340.031464 -281.270869) (xy 340.080754 -281.286879) (xy 340.126933 -281.310404) (xy 340.168863 -281.340863)
			(xy 340.205512 -281.377508) (xy 340.235976 -281.419434) (xy 340.259506 -281.465611) (xy 340.275522 -281.514899)
			(xy 340.28363 -281.566087) (xy 340.28363 -281.617913) (xy 340.275522 -281.669101) (xy 340.259506 -281.718389)
			(xy 340.235976 -281.764566) (xy 340.205512 -281.806492) (xy 340.168863 -281.843137) (xy 340.126933 -281.873596)
			(xy 340.080754 -281.897121) (xy 340.031464 -281.913131) (xy 339.980275 -281.921233) (xy 339.954362 -281.921712)
			(xy 339.928849 -281.921255) (xy 339.878434 -281.913389) (xy 339.829832 -281.89785) (xy 339.784204 -281.87501)
			(xy 339.742639 -281.845414) (xy 339.706129 -281.809768) (xy 339.690456 -281.789632) (xy 339.278468 -281.789632)
			(xy 339.262822 -281.80979) (xy 339.226306 -281.845431) (xy 339.184734 -281.875021) (xy 339.139101 -281.897853)
			(xy 339.090494 -281.913382) (xy 339.040076 -281.921238) (xy 339.014562 -281.921712) (xy 338.988658 -281.921161)
			(xy 338.937489 -281.913051) (xy 338.888219 -281.897037) (xy 338.84206 -281.873513) (xy 338.800148 -281.843058)
			(xy 338.763517 -281.806423) (xy 338.733067 -281.764508) (xy 338.709548 -281.718346) (xy 338.69354 -281.669074)
			(xy 338.685436 -281.617904) (xy 337.4644 -281.617904) (xy 337.4644 -281.617927) (xy 337.456294 -281.669104)
			(xy 337.440282 -281.718383) (xy 337.416759 -281.76455) (xy 337.386303 -281.806469) (xy 337.349665 -281.843107)
			(xy 337.307746 -281.873563) (xy 337.261579 -281.897086) (xy 337.2123 -281.913098) (xy 337.161123 -281.921204)
			(xy 337.109309 -281.921204) (xy 337.058132 -281.913098) (xy 337.008853 -281.897086) (xy 336.962686 -281.873563)
			(xy 336.920767 -281.843107) (xy 336.884129 -281.806469) (xy 336.853673 -281.76455) (xy 336.83015 -281.718383)
			(xy 336.814138 -281.669104) (xy 336.806032 -281.617927) (xy 336.805524 -281.59202) (xy 335.585308 -281.59202)
			(xy 335.584798 -281.617364) (xy 335.577024 -281.667452) (xy 335.561677 -281.715761) (xy 335.539118 -281.761152)
			(xy 335.50988 -281.802558) (xy 335.47465 -281.839001) (xy 335.434259 -281.869625) (xy 335.389657 -281.893707)
			(xy 335.341896 -281.910681) (xy 335.317084 -281.91587) (xy 335.294224 -281.920188) (xy 335.089246 -282.27528)
			(xy 335.096866 -282.297124) (xy 335.1055 -282.32347) (xy 335.114821 -282.378118) (xy 335.115408 -282.405836)
			(xy 335.395824 -282.405836) (xy 335.396332 -282.379949) (xy 335.404431 -282.328811) (xy 335.42043 -282.279571)
			(xy 335.443936 -282.233439) (xy 335.474368 -282.191552) (xy 335.510978 -282.154942) (xy 335.552865 -282.12451)
			(xy 335.598997 -282.101004) (xy 335.648237 -282.085005) (xy 335.699375 -282.076906) (xy 335.751149 -282.076906)
			(xy 335.802287 -282.085005) (xy 335.851527 -282.101004) (xy 335.897659 -282.12451) (xy 335.939546 -282.154942)
			(xy 335.976156 -282.191552) (xy 336.006588 -282.233439) (xy 336.030094 -282.279571) (xy 336.046093 -282.328811)
			(xy 336.054192 -282.379949) (xy 336.0547 -282.405836) (xy 336.054214 -282.431707) (xy 336.336126 -282.431707)
			(xy 336.336126 -282.379893) (xy 336.344232 -282.328716) (xy 336.360244 -282.279437) (xy 336.383768 -282.23327)
			(xy 336.414225 -282.191352) (xy 336.450864 -282.154714) (xy 336.492784 -282.12426) (xy 336.538952 -282.100738)
			(xy 336.588231 -282.084728) (xy 336.639409 -282.076625) (xy 336.665316 -282.076144) (xy 336.690811 -282.076599)
			(xy 336.74119 -282.084464) (xy 336.789755 -282.100003) (xy 336.835342 -282.122845) (xy 336.876862 -282.152443)
			(xy 336.913321 -282.188089) (xy 336.928968 -282.208224) (xy 337.341464 -282.208224) (xy 337.35711 -282.18809)
			(xy 337.393571 -282.152447) (xy 337.435092 -282.122853) (xy 337.480679 -282.100016) (xy 337.529243 -282.084481)
			(xy 337.579622 -282.076621) (xy 337.605116 -282.076144) (xy 337.631025 -282.076581) (xy 337.682206 -282.08469)
			(xy 337.731488 -282.100704) (xy 337.777658 -282.124231) (xy 337.819579 -282.154691) (xy 337.85622 -282.191333)
			(xy 337.886677 -282.233256) (xy 337.910202 -282.279427) (xy 337.926214 -282.32871) (xy 337.93432 -282.379891)
			(xy 337.93432 -282.431709) (xy 337.926214 -282.48289) (xy 337.910202 -282.532173) (xy 337.886677 -282.578344)
			(xy 337.85622 -282.620267) (xy 337.819579 -282.656909) (xy 337.777658 -282.687369) (xy 337.731488 -282.710896)
			(xy 337.682206 -282.72691) (xy 337.631025 -282.735019) (xy 337.605116 -282.735528) (xy 337.579623 -282.735021)
			(xy 337.529248 -282.727163) (xy 337.480686 -282.711632) (xy 337.435099 -282.6888) (xy 337.393577 -282.659213)
			(xy 337.357114 -282.623577) (xy 337.341464 -282.603448) (xy 336.928968 -282.603448) (xy 336.913322 -282.623582)
			(xy 336.876859 -282.659221) (xy 336.835338 -282.688813) (xy 336.78975 -282.71165) (xy 336.741187 -282.727186)
			(xy 336.69081 -282.735049) (xy 336.665316 -282.735528) (xy 336.639409 -282.734975) (xy 336.588231 -282.726872)
			(xy 336.538952 -282.710862) (xy 336.492784 -282.68734) (xy 336.450864 -282.656886) (xy 336.414225 -282.620248)
			(xy 336.383768 -282.57833) (xy 336.360244 -282.532163) (xy 336.344232 -282.482884) (xy 336.336126 -282.431707)
			(xy 336.054214 -282.431707) (xy 336.054179 -282.433545) (xy 336.044978 -282.488191) (xy 336.036412 -282.514548)
			(xy 336.028538 -282.536646) (xy 336.23377 -282.891738) (xy 336.25663 -282.896056) (xy 336.281436 -282.901231)
			(xy 336.329174 -282.918223) (xy 336.373751 -282.94232) (xy 336.414116 -282.972953) (xy 336.449318 -283.009401)
			(xy 336.478529 -283.050806) (xy 336.501062 -283.096194) (xy 336.516384 -283.144494) (xy 336.524137 -283.19457)
			(xy 336.5246 -283.219906) (xy 338.685124 -283.219906) (xy 338.685593 -283.194571) (xy 338.693345 -283.144497)
			(xy 338.708668 -283.096199) (xy 338.731201 -283.050814) (xy 338.760412 -283.009411) (xy 338.795615 -282.972966)
			(xy 338.83598 -282.942336) (xy 338.880556 -282.918243) (xy 338.928293 -282.901254) (xy 338.953094 -282.896056)
			(xy 338.975954 -282.891738) (xy 339.181186 -282.536392) (xy 339.173566 -282.514548) (xy 339.164924 -282.488205)
			(xy 339.155609 -282.433555) (xy 339.155024 -282.405836) (xy 339.155532 -282.379929) (xy 339.163638 -282.328752)
			(xy 339.17965 -282.279473) (xy 339.203173 -282.233306) (xy 339.233629 -282.191387) (xy 339.270267 -282.154749)
			(xy 339.312186 -282.124293) (xy 339.358353 -282.10077) (xy 339.407632 -282.084758) (xy 339.458809 -282.076652)
			(xy 339.510623 -282.076652) (xy 339.5618 -282.084758) (xy 339.611079 -282.10077) (xy 339.657246 -282.124293)
			(xy 339.699165 -282.154749) (xy 339.735803 -282.191387) (xy 339.766259 -282.233306) (xy 339.789782 -282.279473)
			(xy 339.805794 -282.328752) (xy 339.8139 -282.379929) (xy 339.814408 -282.405836) (xy 341.034624 -282.405836)
			(xy 341.035068 -282.38049) (xy 341.04285 -282.330397) (xy 341.058205 -282.282085) (xy 341.080771 -282.236692)
			(xy 341.110018 -282.195286) (xy 341.145256 -282.158843) (xy 341.185656 -282.128222) (xy 341.230265 -282.104142)
			(xy 341.278033 -282.087172) (xy 341.302848 -282.081986) (xy 341.325708 -282.077668) (xy 341.530686 -281.72283)
			(xy 341.522812 -281.700986) (xy 341.514229 -281.674568) (xy 341.505035 -281.619792) (xy 341.504524 -281.59202)
			(xy 341.505032 -281.566133) (xy 341.513131 -281.514995) (xy 341.52913 -281.465755) (xy 341.552636 -281.419623)
			(xy 341.583068 -281.377736) (xy 341.619678 -281.341126) (xy 341.661565 -281.310694) (xy 341.707697 -281.287188)
			(xy 341.756937 -281.271189) (xy 341.808075 -281.26309) (xy 341.859849 -281.26309) (xy 341.910987 -281.271189)
			(xy 341.960227 -281.287188) (xy 342.006359 -281.310694) (xy 342.048246 -281.341126) (xy 342.084856 -281.377736)
			(xy 342.115288 -281.419623) (xy 342.138794 -281.465755) (xy 342.154793 -281.514995) (xy 342.162892 -281.566133)
			(xy 342.1634 -281.59202) (xy 342.162935 -281.617355) (xy 342.15518 -281.667428) (xy 342.139855 -281.715725)
			(xy 342.117321 -281.761109) (xy 342.088109 -281.802511) (xy 342.052906 -281.838956) (xy 342.012542 -281.869586)
			(xy 341.967967 -281.89368) (xy 341.92023 -281.910671) (xy 341.89543 -281.91587) (xy 341.87257 -281.920188)
			(xy 341.667592 -282.275026) (xy 341.675466 -282.297124) (xy 341.684085 -282.323474) (xy 341.693414 -282.378119)
			(xy 341.694008 -282.405836) (xy 342.914224 -282.405836) (xy 342.914629 -282.380499) (xy 342.922392 -282.330422)
			(xy 342.937724 -282.282122) (xy 342.960266 -282.236737) (xy 342.989485 -282.195335) (xy 343.024695 -282.15889)
			(xy 343.065066 -282.128262) (xy 343.109648 -282.10417) (xy 343.157391 -282.087183) (xy 343.182194 -282.081986)
			(xy 343.205054 -282.077668) (xy 343.410286 -281.722322) (xy 343.402666 -281.700478) (xy 343.39404 -281.674196)
			(xy 343.384726 -281.619675) (xy 343.384124 -281.59202) (xy 343.384632 -281.566113) (xy 343.392738 -281.514936)
			(xy 343.40875 -281.465657) (xy 343.432273 -281.41949) (xy 343.462729 -281.377571) (xy 343.499367 -281.340933)
			(xy 343.541286 -281.310477) (xy 343.587453 -281.286954) (xy 343.636732 -281.270942) (xy 343.687909 -281.262836)
			(xy 343.739723 -281.262836) (xy 343.7909 -281.270942) (xy 343.840179 -281.286954) (xy 343.886346 -281.310477)
			(xy 343.928265 -281.340933) (xy 343.964903 -281.377571) (xy 343.995359 -281.41949) (xy 344.018882 -281.465657)
			(xy 344.034894 -281.514936) (xy 344.043 -281.566113) (xy 344.043508 -281.59202) (xy 345.263724 -281.59202)
			(xy 345.264244 -281.566676) (xy 345.272013 -281.516587) (xy 345.287357 -281.468277) (xy 345.309913 -281.422884)
			(xy 345.33915 -281.381477) (xy 345.374379 -281.345033) (xy 345.414771 -281.31441) (xy 345.459374 -281.290329)
			(xy 345.507136 -281.273357) (xy 345.531948 -281.26817) (xy 345.554808 -281.263852) (xy 345.759786 -280.909014)
			(xy 345.751912 -280.88717) (xy 345.743326 -280.860753) (xy 345.734134 -280.805977) (xy 345.733624 -280.778204)
			(xy 345.734132 -280.752317) (xy 345.742231 -280.701179) (xy 345.75823 -280.651939) (xy 345.781736 -280.605807)
			(xy 345.812168 -280.56392) (xy 345.848778 -280.52731) (xy 345.890665 -280.496878) (xy 345.936797 -280.473372)
			(xy 345.986037 -280.457373) (xy 346.037175 -280.449274) (xy 346.088949 -280.449274) (xy 346.140087 -280.457373)
			(xy 346.189327 -280.473372) (xy 346.235459 -280.496878) (xy 346.277346 -280.52731) (xy 346.313956 -280.56392)
			(xy 346.344388 -280.605807) (xy 346.367894 -280.651939) (xy 346.383893 -280.701179) (xy 346.391992 -280.752317)
			(xy 346.3925 -280.778204) (xy 348.553024 -280.778204) (xy 348.553532 -280.752317) (xy 348.561631 -280.701179)
			(xy 348.57763 -280.651939) (xy 348.601136 -280.605807) (xy 348.631568 -280.56392) (xy 348.668178 -280.52731)
			(xy 348.710065 -280.496878) (xy 348.756197 -280.473372) (xy 348.805437 -280.457373) (xy 348.856575 -280.449274)
			(xy 348.908349 -280.449274) (xy 348.959487 -280.457373) (xy 349.008727 -280.473372) (xy 349.054859 -280.496878)
			(xy 349.096746 -280.52731) (xy 349.133356 -280.56392) (xy 349.163788 -280.605807) (xy 349.187294 -280.651939)
			(xy 349.203293 -280.701179) (xy 349.211392 -280.752317) (xy 349.2119 -280.778204) (xy 351.372424 -280.778204)
			(xy 351.372932 -280.752317) (xy 351.381031 -280.701179) (xy 351.39703 -280.651939) (xy 351.420536 -280.605807)
			(xy 351.450968 -280.56392) (xy 351.487578 -280.52731) (xy 351.529465 -280.496878) (xy 351.575597 -280.473372)
			(xy 351.624837 -280.457373) (xy 351.675975 -280.449274) (xy 351.727749 -280.449274) (xy 351.778887 -280.457373)
			(xy 351.828127 -280.473372) (xy 351.874259 -280.496878) (xy 351.916146 -280.52731) (xy 351.952756 -280.56392)
			(xy 351.983188 -280.605807) (xy 352.006694 -280.651939) (xy 352.022693 -280.701179) (xy 352.030792 -280.752317)
			(xy 352.0313 -280.778204) (xy 352.312224 -280.778204) (xy 352.312691 -280.752869) (xy 352.320444 -280.702795)
			(xy 352.335767 -280.654496) (xy 352.3583 -280.609112) (xy 352.387511 -280.567709) (xy 352.422714 -280.531263)
			(xy 352.463079 -280.500633) (xy 352.507655 -280.47654) (xy 352.555393 -280.459552) (xy 352.580194 -280.454354)
			(xy 352.603054 -280.450036) (xy 352.808286 -280.09469) (xy 352.800666 -280.072592) (xy 352.792043 -280.046309)
			(xy 352.782727 -279.991789) (xy 352.782124 -279.964134) (xy 352.782632 -279.938227) (xy 352.790738 -279.88705)
			(xy 352.80675 -279.837771) (xy 352.830273 -279.791604) (xy 352.860729 -279.749685) (xy 352.897367 -279.713047)
			(xy 352.939286 -279.682591) (xy 352.985453 -279.659068) (xy 353.034732 -279.643056) (xy 353.085909 -279.63495)
			(xy 353.137723 -279.63495) (xy 353.1889 -279.643056) (xy 353.238179 -279.659068) (xy 353.284346 -279.682591)
			(xy 353.326265 -279.713047) (xy 353.362903 -279.749685) (xy 353.393359 -279.791604) (xy 353.416882 -279.837771)
			(xy 353.432894 -279.88705) (xy 353.441 -279.938227) (xy 353.441508 -279.964134) (xy 353.441095 -279.9895)
			(xy 353.433341 -280.039635) (xy 353.417991 -280.087988) (xy 353.395408 -280.133416) (xy 353.366127 -280.174843)
			(xy 353.330839 -280.211291) (xy 353.290379 -280.241896) (xy 353.245705 -280.265935) (xy 353.197873 -280.282839)
			(xy 353.17303 -280.287984) (xy 353.149916 -280.292302) (xy 352.944938 -280.647394) (xy 352.952812 -280.669492)
			(xy 352.961371 -280.695851) (xy 352.970571 -280.750496) (xy 352.9711 -280.778204) (xy 352.970592 -280.804091)
			(xy 352.97059 -280.804105) (xy 353.25232 -280.804105) (xy 353.25232 -280.752295) (xy 353.260425 -280.701122)
			(xy 353.276434 -280.651848) (xy 353.299953 -280.605684) (xy 353.330405 -280.563767) (xy 353.367038 -280.527129)
			(xy 353.408951 -280.496673) (xy 353.455113 -280.473148) (xy 353.504385 -280.457133) (xy 353.555557 -280.449023)
			(xy 353.581462 -280.448512) (xy 353.606973 -280.449015) (xy 353.657387 -280.45687) (xy 353.705988 -280.472399)
			(xy 353.751617 -280.49523) (xy 353.793183 -280.524819) (xy 353.829694 -280.560459) (xy 353.845368 -280.580592)
			(xy 354.257356 -280.580592) (xy 354.273053 -280.560476) (xy 354.309558 -280.524831) (xy 354.351119 -280.495236)
			(xy 354.396742 -280.472396) (xy 354.44534 -280.456858) (xy 354.495751 -280.448992) (xy 354.521262 -280.448512)
			(xy 354.547174 -280.448983) (xy 354.59836 -280.457084) (xy 354.647648 -280.473094) (xy 354.693825 -280.496618)
			(xy 354.735753 -280.527076) (xy 354.7724 -280.563718) (xy 354.802863 -280.605643) (xy 354.826391 -280.651817)
			(xy 354.842407 -280.701103) (xy 354.850514 -280.752288) (xy 354.850514 -280.804112) (xy 354.842407 -280.855297)
			(xy 354.826391 -280.904583) (xy 354.802863 -280.950757) (xy 354.7724 -280.992682) (xy 354.735753 -281.029324)
			(xy 354.693825 -281.059782) (xy 354.647648 -281.083306) (xy 354.59836 -281.099316) (xy 354.547174 -281.107417)
			(xy 354.521262 -281.107896) (xy 354.495749 -281.107445) (xy 354.445333 -281.099578) (xy 354.396731 -281.084039)
			(xy 354.351103 -281.061198) (xy 354.309538 -281.031601) (xy 354.273029 -280.995953) (xy 354.257356 -280.975816)
			(xy 353.845368 -280.975816) (xy 353.829717 -280.99597) (xy 353.793203 -281.031612) (xy 353.751632 -281.061203)
			(xy 353.705999 -281.084036) (xy 353.657393 -281.099566) (xy 353.606975 -281.107421) (xy 353.581462 -281.107896)
			(xy 353.555557 -281.107377) (xy 353.504385 -281.099267) (xy 353.455113 -281.083252) (xy 353.408951 -281.059727)
			(xy 353.367038 -281.029271) (xy 353.330405 -280.992633) (xy 353.299953 -280.950716) (xy 353.276434 -280.904552)
			(xy 353.260425 -280.855278) (xy 353.25232 -280.804105) (xy 352.97059 -280.804105) (xy 352.962493 -280.855229)
			(xy 352.946494 -280.904469) (xy 352.922988 -280.950601) (xy 352.892556 -280.992488) (xy 352.855946 -281.029098)
			(xy 352.814059 -281.05953) (xy 352.767927 -281.083036) (xy 352.718687 -281.099035) (xy 352.667549 -281.107134)
			(xy 352.615775 -281.107134) (xy 352.564637 -281.099035) (xy 352.515397 -281.083036) (xy 352.469265 -281.05953)
			(xy 352.427378 -281.029098) (xy 352.390768 -280.992488) (xy 352.360336 -280.950601) (xy 352.33683 -280.904469)
			(xy 352.320831 -280.855229) (xy 352.312732 -280.804091) (xy 352.312224 -280.778204) (xy 352.0313 -280.778204)
			(xy 352.0313 -280.778712) (xy 352.03071 -280.806228) (xy 352.021524 -280.860489) (xy 352.013012 -280.886662)
			(xy 352.005392 -280.908506) (xy 352.210624 -281.263852) (xy 352.233484 -281.26817) (xy 352.258305 -281.273337)
			(xy 352.306082 -281.290294) (xy 352.350699 -281.314367) (xy 352.391104 -281.344988) (xy 352.426344 -281.381435)
			(xy 352.455588 -281.422848) (xy 352.478145 -281.46825) (xy 352.493485 -281.516571) (xy 352.501244 -281.566671)
			(xy 352.501708 -281.59202) (xy 353.721924 -281.59202) (xy 353.722432 -281.566113) (xy 353.730538 -281.514936)
			(xy 353.74655 -281.465657) (xy 353.770073 -281.41949) (xy 353.800529 -281.377571) (xy 353.837167 -281.340933)
			(xy 353.879086 -281.310477) (xy 353.925253 -281.286954) (xy 353.974532 -281.270942) (xy 354.025709 -281.262836)
			(xy 354.077523 -281.262836) (xy 354.1287 -281.270942) (xy 354.177979 -281.286954) (xy 354.224146 -281.310477)
			(xy 354.266065 -281.340933) (xy 354.302703 -281.377571) (xy 354.333159 -281.41949) (xy 354.356682 -281.465657)
			(xy 354.372694 -281.514936) (xy 354.3808 -281.566113) (xy 354.381308 -281.59202) (xy 354.380739 -281.619802)
			(xy 354.371414 -281.674578) (xy 354.362766 -281.700986) (xy 354.354892 -281.72283) (xy 354.55987 -282.077668)
			(xy 354.58273 -282.081986) (xy 354.607543 -282.087133) (xy 354.655283 -282.104127) (xy 354.699861 -282.128227)
			(xy 354.740227 -282.158863) (xy 354.775429 -282.195315) (xy 354.80464 -282.236724) (xy 354.82717 -282.282115)
			(xy 354.84249 -282.330419) (xy 354.850239 -282.380498) (xy 354.8507 -282.405836) (xy 354.850192 -282.431723)
			(xy 354.842093 -282.482861) (xy 354.826094 -282.532101) (xy 354.802588 -282.578233) (xy 354.772156 -282.62012)
			(xy 354.735546 -282.65673) (xy 354.693659 -282.687162) (xy 354.647527 -282.710668) (xy 354.598287 -282.726667)
			(xy 354.547149 -282.734766) (xy 354.495375 -282.734766) (xy 354.444237 -282.726667) (xy 354.394997 -282.710668)
			(xy 354.348865 -282.687162) (xy 354.306978 -282.65673) (xy 354.270368 -282.62012) (xy 354.239936 -282.578233)
			(xy 354.21643 -282.532101) (xy 354.200431 -282.482861) (xy 354.192332 -282.431723) (xy 354.191824 -282.405836)
			(xy 354.192361 -282.378128) (xy 354.201551 -282.323481) (xy 354.210112 -282.297124) (xy 354.217986 -282.275026)
			(xy 354.013008 -281.920188) (xy 353.990148 -281.91587) (xy 353.965319 -281.910737) (xy 353.917537 -281.893779)
			(xy 353.872916 -281.869705) (xy 353.832509 -281.83908) (xy 353.797268 -281.802629) (xy 353.768025 -281.761211)
			(xy 353.74547 -281.715803) (xy 353.730136 -281.667476) (xy 353.722383 -281.617371) (xy 353.721924 -281.59202)
			(xy 352.501708 -281.59202) (xy 352.5012 -281.617927) (xy 352.493094 -281.669104) (xy 352.477082 -281.718383)
			(xy 352.453559 -281.76455) (xy 352.423103 -281.806469) (xy 352.386465 -281.843107) (xy 352.344546 -281.873563)
			(xy 352.298379 -281.897086) (xy 352.2491 -281.913098) (xy 352.197923 -281.921204) (xy 352.146109 -281.921204)
			(xy 352.094932 -281.913098) (xy 352.045653 -281.897086) (xy 351.999486 -281.873563) (xy 351.957567 -281.843107)
			(xy 351.920929 -281.806469) (xy 351.890473 -281.76455) (xy 351.86695 -281.718383) (xy 351.850938 -281.669104)
			(xy 351.842832 -281.617927) (xy 351.842324 -281.59202) (xy 351.842922 -281.564303) (xy 351.852242 -281.509656)
			(xy 351.860866 -281.483308) (xy 351.86874 -281.46121) (xy 351.663762 -281.106372) (xy 351.640902 -281.102054)
			(xy 351.616072 -281.096882) (xy 351.568266 -281.079946) (xy 351.523618 -281.055889) (xy 351.483181 -281.025278)
			(xy 351.447909 -280.988835) (xy 351.418634 -280.947421) (xy 351.396047 -280.902011) (xy 351.380681 -280.853678)
			(xy 351.372898 -280.803562) (xy 351.372424 -280.778204) (xy 349.2119 -280.778204) (xy 349.2119 -280.778712)
			(xy 349.21131 -280.806228) (xy 349.202124 -280.860489) (xy 349.193612 -280.886662) (xy 349.185992 -280.908506)
			(xy 349.391224 -281.263852) (xy 349.414084 -281.26817) (xy 349.438905 -281.273337) (xy 349.486682 -281.290294)
			(xy 349.531299 -281.314367) (xy 349.571704 -281.344988) (xy 349.606944 -281.381435) (xy 349.636188 -281.422848)
			(xy 349.658745 -281.46825) (xy 349.674085 -281.516571) (xy 349.681844 -281.566671) (xy 349.682308 -281.59202)
			(xy 349.6818 -281.617927) (xy 349.673694 -281.669104) (xy 349.657682 -281.718383) (xy 349.634159 -281.76455)
			(xy 349.603703 -281.806469) (xy 349.567065 -281.843107) (xy 349.525146 -281.873563) (xy 349.478979 -281.897086)
			(xy 349.4297 -281.913098) (xy 349.378523 -281.921204) (xy 349.326709 -281.921204) (xy 349.275532 -281.913098)
			(xy 349.226253 -281.897086) (xy 349.180086 -281.873563) (xy 349.138167 -281.843107) (xy 349.101529 -281.806469)
			(xy 349.071073 -281.76455) (xy 349.04755 -281.718383) (xy 349.031538 -281.669104) (xy 349.023432 -281.617927)
			(xy 349.022924 -281.59202) (xy 349.023522 -281.564303) (xy 349.032842 -281.509656) (xy 349.041466 -281.483308)
			(xy 349.04934 -281.46121) (xy 348.844362 -281.106372) (xy 348.821502 -281.102054) (xy 348.796672 -281.096882)
			(xy 348.748866 -281.079946) (xy 348.704218 -281.055889) (xy 348.663781 -281.025278) (xy 348.628509 -280.988835)
			(xy 348.599234 -280.947421) (xy 348.576647 -280.902011) (xy 348.561281 -280.853678) (xy 348.553498 -280.803562)
			(xy 348.553024 -280.778204) (xy 346.3925 -280.778204) (xy 346.392021 -280.803539) (xy 346.384268 -280.853611)
			(xy 346.368945 -280.901908) (xy 346.346413 -280.947292) (xy 346.317203 -280.988694) (xy 346.282002 -281.025139)
			(xy 346.241639 -281.055769) (xy 346.197065 -281.079864) (xy 346.14933 -281.096855) (xy 346.12453 -281.102054)
			(xy 346.10167 -281.106372) (xy 345.896692 -281.46121) (xy 345.904566 -281.483308) (xy 345.913205 -281.509652)
			(xy 345.922521 -281.564301) (xy 345.923108 -281.59202) (xy 345.9226 -281.617909) (xy 347.143809 -281.617909)
			(xy 347.143809 -281.566091) (xy 347.151916 -281.514912) (xy 347.167929 -281.465631) (xy 347.191454 -281.419462)
			(xy 347.221912 -281.377541) (xy 347.258553 -281.340902) (xy 347.300475 -281.310446) (xy 347.346646 -281.286923)
			(xy 347.395928 -281.270912) (xy 347.447107 -281.262808) (xy 347.473016 -281.262328) (xy 347.498529 -281.262786)
			(xy 347.548945 -281.27065) (xy 347.597547 -281.286187) (xy 347.643176 -281.309027) (xy 347.684741 -281.338624)
			(xy 347.721249 -281.374271) (xy 347.736922 -281.394408) (xy 348.14891 -281.394408) (xy 348.16458 -281.37427)
			(xy 348.20109 -281.338625) (xy 348.242656 -281.309032) (xy 348.288285 -281.286196) (xy 348.336888 -281.270663)
			(xy 348.387304 -281.262804) (xy 348.412816 -281.262328) (xy 348.438724 -281.262797) (xy 348.489902 -281.270905)
			(xy 348.539182 -281.286919) (xy 348.585349 -281.310445) (xy 348.627269 -281.340903) (xy 348.663907 -281.377543)
			(xy 348.694363 -281.419464) (xy 348.717887 -281.465633) (xy 348.733899 -281.514914) (xy 348.742004 -281.566092)
			(xy 348.742004 -281.617908) (xy 348.733899 -281.669086) (xy 348.717887 -281.718367) (xy 348.694363 -281.764536)
			(xy 348.663907 -281.806457) (xy 348.627269 -281.843097) (xy 348.585349 -281.873555) (xy 348.539182 -281.897081)
			(xy 348.489902 -281.913095) (xy 348.438724 -281.921203) (xy 348.412816 -281.921712) (xy 348.387305 -281.921215)
			(xy 348.336891 -281.913357) (xy 348.28829 -281.897827) (xy 348.242662 -281.874994) (xy 348.201096 -281.845405)
			(xy 348.164585 -281.809765) (xy 348.14891 -281.789632) (xy 347.736922 -281.789632) (xy 347.721245 -281.809764)
			(xy 347.684735 -281.845407) (xy 347.64317 -281.875) (xy 347.597542 -281.897836) (xy 347.548942 -281.913371)
			(xy 347.498528 -281.921234) (xy 347.473016 -281.921712) (xy 347.447107 -281.921192) (xy 347.395928 -281.913088)
			(xy 347.346646 -281.897077) (xy 347.300475 -281.873554) (xy 347.258553 -281.843098) (xy 347.221912 -281.806459)
			(xy 347.191454 -281.764538) (xy 347.167929 -281.718369) (xy 347.151916 -281.669088) (xy 347.143809 -281.617909)
			(xy 345.9226 -281.617909) (xy 345.9226 -281.617927) (xy 345.914494 -281.669104) (xy 345.898482 -281.718383)
			(xy 345.874959 -281.76455) (xy 345.844503 -281.806469) (xy 345.807865 -281.843107) (xy 345.765946 -281.873563)
			(xy 345.719779 -281.897086) (xy 345.6705 -281.913098) (xy 345.619323 -281.921204) (xy 345.567509 -281.921204)
			(xy 345.516332 -281.913098) (xy 345.467053 -281.897086) (xy 345.420886 -281.873563) (xy 345.378967 -281.843107)
			(xy 345.342329 -281.806469) (xy 345.311873 -281.76455) (xy 345.28835 -281.718383) (xy 345.272338 -281.669104)
			(xy 345.264232 -281.617927) (xy 345.263724 -281.59202) (xy 344.043508 -281.59202) (xy 344.043045 -281.617395)
			(xy 344.035274 -281.667545) (xy 344.019903 -281.71591) (xy 343.997297 -281.761346) (xy 343.967989 -281.802777)
			(xy 343.932674 -281.839223) (xy 343.892188 -281.869822) (xy 343.847487 -281.893849) (xy 343.79963 -281.910736)
			(xy 343.774776 -281.91587) (xy 343.751916 -281.920188) (xy 343.546938 -282.275026) (xy 343.554812 -282.297124)
			(xy 343.563378 -282.32348) (xy 343.572573 -282.378127) (xy 343.5731 -282.405836) (xy 343.854024 -282.405836)
			(xy 343.854532 -282.379949) (xy 343.862631 -282.328811) (xy 343.87863 -282.279571) (xy 343.902136 -282.233439)
			(xy 343.932568 -282.191552) (xy 343.969178 -282.154942) (xy 344.011065 -282.12451) (xy 344.057197 -282.101004)
			(xy 344.106437 -282.085005) (xy 344.157575 -282.076906) (xy 344.209349 -282.076906) (xy 344.260487 -282.085005)
			(xy 344.309727 -282.101004) (xy 344.355859 -282.12451) (xy 344.397746 -282.154942) (xy 344.434356 -282.191552)
			(xy 344.464788 -282.233439) (xy 344.488294 -282.279571) (xy 344.504293 -282.328811) (xy 344.512392 -282.379949)
			(xy 344.5129 -282.405836) (xy 344.5129 -282.406344) (xy 344.512364 -282.431703) (xy 344.794152 -282.431703)
			(xy 344.794152 -282.379897) (xy 344.802256 -282.32873) (xy 344.818263 -282.27946) (xy 344.841781 -282.2333)
			(xy 344.872229 -282.191388) (xy 344.908859 -282.154754) (xy 344.950768 -282.124301) (xy 344.996925 -282.100778)
			(xy 345.046193 -282.084765) (xy 345.097359 -282.076655) (xy 345.123262 -282.076144) (xy 345.148774 -282.076635)
			(xy 345.199188 -282.084491) (xy 345.247791 -282.100021) (xy 345.293419 -282.122855) (xy 345.334985 -282.152446)
			(xy 345.371495 -282.188089) (xy 345.387168 -282.208224) (xy 345.799156 -282.208224) (xy 345.814861 -282.188115)
			(xy 345.851364 -282.152468) (xy 345.892922 -282.122871) (xy 345.938545 -282.10003) (xy 345.987141 -282.084491)
			(xy 346.037552 -282.076624) (xy 346.063062 -282.076144) (xy 346.088976 -282.076551) (xy 346.140167 -282.084653)
			(xy 346.18946 -282.100664) (xy 346.235642 -282.12419) (xy 346.277574 -282.154651) (xy 346.314224 -282.191297)
			(xy 346.34469 -282.233226) (xy 346.368221 -282.279404) (xy 346.384238 -282.328696) (xy 346.392346 -282.379886)
			(xy 346.392346 -282.431714) (xy 346.384238 -282.482904) (xy 346.368221 -282.532196) (xy 346.34469 -282.578374)
			(xy 346.314224 -282.620303) (xy 346.277574 -282.656949) (xy 346.235642 -282.68741) (xy 346.18946 -282.710936)
			(xy 346.140167 -282.726947) (xy 346.088976 -282.735049) (xy 346.063062 -282.735528) (xy 346.03755 -282.735064)
			(xy 345.987135 -282.727199) (xy 345.938534 -282.711661) (xy 345.892906 -282.688822) (xy 345.85134 -282.659228)
			(xy 345.81483 -282.623584) (xy 345.799156 -282.603448) (xy 345.387168 -282.603448) (xy 345.371526 -282.623609)
			(xy 345.335009 -282.659249) (xy 345.293436 -282.688839) (xy 345.247802 -282.71167) (xy 345.199195 -282.727199)
			(xy 345.148776 -282.735054) (xy 345.123262 -282.735528) (xy 345.097359 -282.734945) (xy 345.046193 -282.726835)
			(xy 344.996925 -282.710822) (xy 344.950768 -282.687299) (xy 344.908859 -282.656846) (xy 344.872229 -282.620212)
			(xy 344.841781 -282.5783) (xy 344.818263 -282.53214) (xy 344.802256 -282.48287) (xy 344.794152 -282.431703)
			(xy 344.512364 -282.431703) (xy 344.512318 -282.43386) (xy 344.503126 -282.488122) (xy 344.494612 -282.514294)
			(xy 344.486992 -282.536392) (xy 344.692224 -282.891738) (xy 344.715084 -282.896056) (xy 344.739902 -282.901236)
			(xy 344.787678 -282.918192) (xy 344.832294 -282.942264) (xy 344.872699 -282.972884) (xy 344.907939 -283.009329)
			(xy 344.937183 -283.05074) (xy 344.959741 -283.09614) (xy 344.975082 -283.14446) (xy 344.982843 -283.194558)
			(xy 344.983308 -283.219906) (xy 347.143324 -283.219906) (xy 347.143831 -283.194562) (xy 347.151603 -283.144472)
			(xy 347.166948 -283.096161) (xy 347.189506 -283.050768) (xy 347.218745 -283.009362) (xy 347.253975 -282.972918)
			(xy 347.294368 -282.942295) (xy 347.338972 -282.918214) (xy 347.386736 -282.901243) (xy 347.411548 -282.896056)
			(xy 347.434408 -282.891738) (xy 347.639386 -282.5369) (xy 347.631766 -282.514802) (xy 347.623129 -282.488391)
			(xy 347.613803 -282.433617) (xy 347.613224 -282.405836) (xy 347.613732 -282.379949) (xy 347.621831 -282.328811)
			(xy 347.63783 -282.279571) (xy 347.661336 -282.233439) (xy 347.691768 -282.191552) (xy 347.728378 -282.154942)
			(xy 347.770265 -282.12451) (xy 347.816397 -282.101004) (xy 347.865637 -282.085005) (xy 347.916775 -282.076906)
			(xy 347.968549 -282.076906) (xy 348.019687 -282.085005) (xy 348.068927 -282.101004) (xy 348.115059 -282.12451)
			(xy 348.156946 -282.154942) (xy 348.193556 -282.191552) (xy 348.223988 -282.233439) (xy 348.247494 -282.279571)
			(xy 348.263493 -282.328811) (xy 348.271592 -282.379949) (xy 348.2721 -282.405836) (xy 349.492824 -282.405836)
			(xy 349.493229 -282.380499) (xy 349.500992 -282.330422) (xy 349.516324 -282.282122) (xy 349.538866 -282.236737)
			(xy 349.568085 -282.195335) (xy 349.603295 -282.15889) (xy 349.643666 -282.128262) (xy 349.688248 -282.10417)
			(xy 349.735991 -282.087183) (xy 349.760794 -282.081986) (xy 349.783654 -282.077668) (xy 349.988886 -281.722322)
			(xy 349.981266 -281.700478) (xy 349.97264 -281.674196) (xy 349.963326 -281.619675) (xy 349.962724 -281.59202)
			(xy 349.963232 -281.566113) (xy 349.971338 -281.514936) (xy 349.98735 -281.465657) (xy 350.010873 -281.41949)
			(xy 350.041329 -281.377571) (xy 350.077967 -281.340933) (xy 350.119886 -281.310477) (xy 350.166053 -281.286954)
			(xy 350.215332 -281.270942) (xy 350.266509 -281.262836) (xy 350.318323 -281.262836) (xy 350.3695 -281.270942)
			(xy 350.418779 -281.286954) (xy 350.464946 -281.310477) (xy 350.506865 -281.340933) (xy 350.543503 -281.377571)
			(xy 350.573959 -281.41949) (xy 350.597482 -281.465657) (xy 350.613494 -281.514936) (xy 350.6216 -281.566113)
			(xy 350.622108 -281.59202) (xy 350.621645 -281.617395) (xy 350.613874 -281.667545) (xy 350.598503 -281.71591)
			(xy 350.575897 -281.761346) (xy 350.546589 -281.802777) (xy 350.511274 -281.839223) (xy 350.470788 -281.869822)
			(xy 350.426087 -281.893849) (xy 350.37823 -281.910736) (xy 350.353376 -281.91587) (xy 350.330516 -281.920188)
			(xy 350.125538 -282.275026) (xy 350.133412 -282.297124) (xy 350.141978 -282.32348) (xy 350.151173 -282.378127)
			(xy 350.1517 -282.405836) (xy 350.151192 -282.431703) (xy 351.372752 -282.431703) (xy 351.372752 -282.379897)
			(xy 351.380856 -282.32873) (xy 351.396863 -282.27946) (xy 351.420381 -282.2333) (xy 351.450829 -282.191388)
			(xy 351.487459 -282.154754) (xy 351.529368 -282.124301) (xy 351.575525 -282.100778) (xy 351.624793 -282.084765)
			(xy 351.675959 -282.076655) (xy 351.701862 -282.076144) (xy 351.727374 -282.076635) (xy 351.777788 -282.084491)
			(xy 351.826391 -282.100021) (xy 351.872019 -282.122855) (xy 351.913585 -282.152446) (xy 351.950095 -282.188089)
			(xy 351.965768 -282.208224) (xy 352.377756 -282.208224) (xy 352.393461 -282.188115) (xy 352.429964 -282.152468)
			(xy 352.471522 -282.122871) (xy 352.517145 -282.10003) (xy 352.565741 -282.084491) (xy 352.616152 -282.076624)
			(xy 352.641662 -282.076144) (xy 352.667576 -282.076551) (xy 352.718767 -282.084653) (xy 352.76806 -282.100664)
			(xy 352.814242 -282.12419) (xy 352.856174 -282.154651) (xy 352.892824 -282.191297) (xy 352.92329 -282.233226)
			(xy 352.946821 -282.279404) (xy 352.962838 -282.328696) (xy 352.970946 -282.379886) (xy 352.970946 -282.431714)
			(xy 352.962838 -282.482904) (xy 352.946821 -282.532196) (xy 352.92329 -282.578374) (xy 352.892824 -282.620303)
			(xy 352.856174 -282.656949) (xy 352.814242 -282.68741) (xy 352.76806 -282.710936) (xy 352.718767 -282.726947)
			(xy 352.667576 -282.735049) (xy 352.641662 -282.735528) (xy 352.61615 -282.735064) (xy 352.565735 -282.727199)
			(xy 352.517134 -282.711661) (xy 352.471506 -282.688822) (xy 352.42994 -282.659228) (xy 352.39343 -282.623584)
			(xy 352.377756 -282.603448) (xy 351.965768 -282.603448) (xy 351.950126 -282.623609) (xy 351.913609 -282.659249)
			(xy 351.872036 -282.688839) (xy 351.826402 -282.71167) (xy 351.777795 -282.727199) (xy 351.727376 -282.735054)
			(xy 351.701862 -282.735528) (xy 351.675959 -282.734945) (xy 351.624793 -282.726835) (xy 351.575525 -282.710822)
			(xy 351.529368 -282.687299) (xy 351.487459 -282.656846) (xy 351.450829 -282.620212) (xy 351.420381 -282.5783)
			(xy 351.396863 -282.53214) (xy 351.380856 -282.48287) (xy 351.372752 -282.431703) (xy 350.151192 -282.431703)
			(xy 350.151192 -282.431723) (xy 350.143093 -282.482861) (xy 350.127094 -282.532101) (xy 350.103588 -282.578233)
			(xy 350.073156 -282.62012) (xy 350.036546 -282.65673) (xy 349.994659 -282.687162) (xy 349.948527 -282.710668)
			(xy 349.899287 -282.726667) (xy 349.848149 -282.734766) (xy 349.796375 -282.734766) (xy 349.745237 -282.726667)
			(xy 349.695997 -282.710668) (xy 349.649865 -282.687162) (xy 349.607978 -282.65673) (xy 349.571368 -282.62012)
			(xy 349.540936 -282.578233) (xy 349.51743 -282.532101) (xy 349.501431 -282.482861) (xy 349.493332 -282.431723)
			(xy 349.492824 -282.405836) (xy 348.2721 -282.405836) (xy 348.271608 -282.431158) (xy 348.263872 -282.481209)
			(xy 348.248573 -282.529487) (xy 348.22607 -282.574858) (xy 348.196893 -282.616254) (xy 348.161729 -282.6527)
			(xy 348.121404 -282.68334) (xy 348.076868 -282.707453) (xy 348.029168 -282.72447) (xy 348.004384 -282.729686)
			(xy 347.981524 -282.734004) (xy 347.776292 -283.089096) (xy 347.784166 -283.111194) (xy 347.792802 -283.137539)
			(xy 347.80212 -283.192188) (xy 347.802708 -283.219906) (xy 347.8022 -283.24579) (xy 349.023649 -283.24579)
			(xy 349.023649 -283.19401) (xy 349.03175 -283.142868) (xy 349.047751 -283.093623) (xy 349.071259 -283.047487)
			(xy 349.101695 -283.005597) (xy 349.13831 -282.968985) (xy 349.180201 -282.938551) (xy 349.226338 -282.915045)
			(xy 349.275584 -282.899046) (xy 349.326726 -282.890948) (xy 349.352616 -282.890468) (xy 349.378128 -282.890949)
			(xy 349.428541 -282.898811) (xy 349.477143 -282.914346) (xy 349.522771 -282.937181) (xy 349.564336 -282.966773)
			(xy 349.600848 -283.002414) (xy 349.616522 -283.022548) (xy 350.02851 -283.022548) (xy 350.044163 -283.002397)
			(xy 350.080679 -282.966756) (xy 350.122249 -282.937166) (xy 350.167881 -282.914333) (xy 350.216486 -282.898802)
			(xy 350.266903 -282.890944) (xy 350.292416 -282.890468) (xy 350.318303 -282.890965) (xy 350.369439 -282.899066)
			(xy 350.418679 -282.915067) (xy 350.464809 -282.938574) (xy 350.506694 -282.969007) (xy 350.543303 -283.005618)
			(xy 350.573735 -283.047505) (xy 350.597239 -283.093636) (xy 350.613237 -283.142876) (xy 350.621336 -283.194013)
			(xy 350.621336 -283.219906) (xy 352.782124 -283.219906) (xy 352.782631 -283.194562) (xy 352.790403 -283.144472)
			(xy 352.805748 -283.096161) (xy 352.828306 -283.050768) (xy 352.857545 -283.009362) (xy 352.892775 -282.972918)
			(xy 352.933168 -282.942295) (xy 352.977772 -282.918214) (xy 353.025536 -282.901243) (xy 353.050348 -282.896056)
			(xy 353.073208 -282.891738) (xy 353.278186 -282.5369) (xy 353.270566 -282.514802) (xy 353.261929 -282.488391)
			(xy 353.252603 -282.433617) (xy 353.252024 -282.405836) (xy 353.252532 -282.379949) (xy 353.260631 -282.328811)
			(xy 353.27663 -282.279571) (xy 353.300136 -282.233439) (xy 353.330568 -282.191552) (xy 353.367178 -282.154942)
			(xy 353.409065 -282.12451) (xy 353.455197 -282.101004) (xy 353.504437 -282.085005) (xy 353.555575 -282.076906)
			(xy 353.607349 -282.076906) (xy 353.658487 -282.085005) (xy 353.707727 -282.101004) (xy 353.753859 -282.12451)
			(xy 353.795746 -282.154942) (xy 353.832356 -282.191552) (xy 353.862788 -282.233439) (xy 353.886294 -282.279571)
			(xy 353.902293 -282.328811) (xy 353.910392 -282.379949) (xy 353.9109 -282.405836) (xy 353.910408 -282.431158)
			(xy 353.902672 -282.481209) (xy 353.887373 -282.529487) (xy 353.86487 -282.574858) (xy 353.835693 -282.616254)
			(xy 353.800529 -282.6527) (xy 353.760204 -282.68334) (xy 353.715668 -282.707453) (xy 353.667968 -282.72447)
			(xy 353.643184 -282.729686) (xy 353.620324 -282.734004) (xy 353.415092 -283.089096) (xy 353.422966 -283.111194)
			(xy 353.431602 -283.137539) (xy 353.44092 -283.192188) (xy 353.441508 -283.219906) (xy 353.441 -283.245813)
			(xy 353.432894 -283.29699) (xy 353.416882 -283.346269) (xy 353.393359 -283.392436) (xy 353.362903 -283.434355)
			(xy 353.326265 -283.470993) (xy 353.284346 -283.501449) (xy 353.238179 -283.524972) (xy 353.1889 -283.540984)
			(xy 353.137723 -283.54909) (xy 353.085909 -283.54909) (xy 353.034732 -283.540984) (xy 352.985453 -283.524972)
			(xy 352.939286 -283.501449) (xy 352.897367 -283.470993) (xy 352.860729 -283.434355) (xy 352.830273 -283.392436)
			(xy 352.80675 -283.346269) (xy 352.790738 -283.29699) (xy 352.782632 -283.245813) (xy 352.782124 -283.219906)
			(xy 350.621336 -283.219906) (xy 350.621336 -283.245787) (xy 350.613237 -283.296924) (xy 350.597239 -283.346164)
			(xy 350.573735 -283.392295) (xy 350.543303 -283.434182) (xy 350.506694 -283.470793) (xy 350.464809 -283.501226)
			(xy 350.418679 -283.524733) (xy 350.369439 -283.540734) (xy 350.318303 -283.548835) (xy 350.292416 -283.549344)
			(xy 350.266904 -283.548874) (xy 350.216488 -283.541014) (xy 350.167885 -283.52548) (xy 350.122256 -283.502643)
			(xy 350.080691 -283.473047) (xy 350.044182 -283.437401) (xy 350.02851 -283.417264) (xy 349.616522 -283.417264)
			(xy 349.600826 -283.437381) (xy 349.564322 -283.473028) (xy 349.522762 -283.502625) (xy 349.477138 -283.525464)
			(xy 349.428539 -283.541001) (xy 349.378127 -283.548865) (xy 349.352616 -283.549344) (xy 349.326726 -283.548852)
			(xy 349.275584 -283.540754) (xy 349.226338 -283.524755) (xy 349.180201 -283.501249) (xy 349.13831 -283.470815)
			(xy 349.101695 -283.434203) (xy 349.071259 -283.392313) (xy 349.047751 -283.346177) (xy 349.03175 -283.296932)
			(xy 349.023649 -283.24579) (xy 347.8022 -283.24579) (xy 347.8022 -283.245813) (xy 347.794094 -283.29699)
			(xy 347.778082 -283.346269) (xy 347.754559 -283.392436) (xy 347.724103 -283.434355) (xy 347.687465 -283.470993)
			(xy 347.645546 -283.501449) (xy 347.599379 -283.524972) (xy 347.5501 -283.540984) (xy 347.498923 -283.54909)
			(xy 347.447109 -283.54909) (xy 347.395932 -283.540984) (xy 347.346653 -283.524972) (xy 347.300486 -283.501449)
			(xy 347.258567 -283.470993) (xy 347.221929 -283.434355) (xy 347.191473 -283.392436) (xy 347.16795 -283.346269)
			(xy 347.151938 -283.29699) (xy 347.143832 -283.245813) (xy 347.143324 -283.219906) (xy 344.983308 -283.219906)
			(xy 344.9828 -283.245813) (xy 344.974694 -283.29699) (xy 344.958682 -283.346269) (xy 344.935159 -283.392436)
			(xy 344.904703 -283.434355) (xy 344.868065 -283.470993) (xy 344.826146 -283.501449) (xy 344.779979 -283.524972)
			(xy 344.7307 -283.540984) (xy 344.679523 -283.54909) (xy 344.627709 -283.54909) (xy 344.576532 -283.540984)
			(xy 344.527253 -283.524972) (xy 344.481086 -283.501449) (xy 344.439167 -283.470993) (xy 344.402529 -283.434355)
			(xy 344.372073 -283.392436) (xy 344.34855 -283.346269) (xy 344.332538 -283.29699) (xy 344.324432 -283.245813)
			(xy 344.323924 -283.219906) (xy 344.324518 -283.192189) (xy 344.333841 -283.137542) (xy 344.342466 -283.111194)
			(xy 344.35034 -283.089096) (xy 344.145362 -282.734004) (xy 344.122248 -282.729686) (xy 344.097423 -282.724538)
			(xy 344.049642 -282.707582) (xy 344.005022 -282.683508) (xy 343.964615 -282.652886) (xy 343.929374 -282.616436)
			(xy 343.900131 -282.57502) (xy 343.877575 -282.529614) (xy 343.862239 -282.481289) (xy 343.854484 -282.431186)
			(xy 343.854024 -282.405836) (xy 343.5731 -282.405836) (xy 343.572592 -282.431723) (xy 343.564493 -282.482861)
			(xy 343.548494 -282.532101) (xy 343.524988 -282.578233) (xy 343.494556 -282.62012) (xy 343.457946 -282.65673)
			(xy 343.416059 -282.687162) (xy 343.369927 -282.710668) (xy 343.320687 -282.726667) (xy 343.269549 -282.734766)
			(xy 343.217775 -282.734766) (xy 343.166637 -282.726667) (xy 343.117397 -282.710668) (xy 343.071265 -282.687162)
			(xy 343.029378 -282.65673) (xy 342.992768 -282.62012) (xy 342.962336 -282.578233) (xy 342.93883 -282.532101)
			(xy 342.922831 -282.482861) (xy 342.914732 -282.431723) (xy 342.914224 -282.405836) (xy 341.694008 -282.405836)
			(xy 341.6935 -282.431743) (xy 341.685394 -282.48292) (xy 341.669382 -282.532199) (xy 341.645859 -282.578366)
			(xy 341.615403 -282.620285) (xy 341.578765 -282.656923) (xy 341.536846 -282.687379) (xy 341.490679 -282.710902)
			(xy 341.4414 -282.726914) (xy 341.390223 -282.73502) (xy 341.338409 -282.73502) (xy 341.287232 -282.726914)
			(xy 341.237953 -282.710902) (xy 341.191786 -282.687379) (xy 341.149867 -282.656923) (xy 341.113229 -282.620285)
			(xy 341.082773 -282.578366) (xy 341.05925 -282.532199) (xy 341.043238 -282.48292) (xy 341.035132 -282.431743)
			(xy 341.034624 -282.405836) (xy 339.814408 -282.405836) (xy 339.813997 -282.431202) (xy 339.806243 -282.481337)
			(xy 339.790893 -282.52969) (xy 339.768309 -282.575118) (xy 339.739027 -282.616545) (xy 339.703739 -282.652993)
			(xy 339.663279 -282.683598) (xy 339.618605 -282.707637) (xy 339.570773 -282.724541) (xy 339.54593 -282.729686)
			(xy 339.52307 -282.734004) (xy 339.318092 -283.089096) (xy 339.325712 -283.11094) (xy 339.33426 -283.137236)
			(xy 339.343458 -283.191753) (xy 339.344 -283.219398) (xy 339.344 -283.219906) (xy 339.343492 -283.245785)
			(xy 340.565275 -283.245785) (xy 340.565275 -283.194015) (xy 340.573373 -283.142882) (xy 340.58937 -283.093646)
			(xy 340.612872 -283.047517) (xy 340.643299 -283.005633) (xy 340.679904 -282.969024) (xy 340.721785 -282.938592)
			(xy 340.76791 -282.915085) (xy 340.817145 -282.899082) (xy 340.868277 -282.890978) (xy 340.894162 -282.890468)
			(xy 340.919672 -282.890989) (xy 340.970084 -282.898843) (xy 341.018684 -282.914369) (xy 341.064312 -282.937197)
			(xy 341.105879 -282.966782) (xy 341.142392 -283.002417) (xy 341.158068 -283.022548) (xy 341.570056 -283.022548)
			(xy 341.585741 -283.002422) (xy 341.62225 -282.96678) (xy 341.663813 -282.937187) (xy 341.709439 -282.91435)
			(xy 341.758039 -282.898813) (xy 341.808451 -282.890948) (xy 341.833962 -282.890468) (xy 341.859854 -282.890934)
			(xy 341.911001 -282.89903) (xy 341.960252 -282.915027) (xy 342.006393 -282.938533) (xy 342.048289 -282.968968)
			(xy 342.084908 -283.005582) (xy 342.115347 -283.047475) (xy 342.138858 -283.093613) (xy 342.154861 -283.142862)
			(xy 342.162963 -283.194008) (xy 342.162963 -283.245792) (xy 342.154861 -283.296938) (xy 342.138858 -283.346187)
			(xy 342.115347 -283.392325) (xy 342.084908 -283.434218) (xy 342.048289 -283.470832) (xy 342.006393 -283.501267)
			(xy 341.960252 -283.524773) (xy 341.911001 -283.54077) (xy 341.859854 -283.548866) (xy 341.833962 -283.549344)
			(xy 341.808448 -283.548913) (xy 341.75803 -283.541045) (xy 341.709427 -283.525503) (xy 341.663798 -283.502658)
			(xy 341.622234 -283.473056) (xy 341.585727 -283.437404) (xy 341.570056 -283.417264) (xy 341.158068 -283.417264)
			(xy 341.142404 -283.437407) (xy 341.105893 -283.473052) (xy 341.064326 -283.502646) (xy 341.018696 -283.525481)
			(xy 340.970092 -283.541013) (xy 340.919675 -283.548869) (xy 340.894162 -283.549344) (xy 340.868277 -283.548822)
			(xy 340.817145 -283.540718) (xy 340.76791 -283.524715) (xy 340.721785 -283.501208) (xy 340.679904 -283.470776)
			(xy 340.643299 -283.434167) (xy 340.612872 -283.392283) (xy 340.58937 -283.346154) (xy 340.573373 -283.296918)
			(xy 340.565275 -283.245785) (xy 339.343492 -283.245785) (xy 339.343492 -283.245793) (xy 339.335393 -283.296931)
			(xy 339.319394 -283.346171) (xy 339.295888 -283.392303) (xy 339.265456 -283.43419) (xy 339.228846 -283.4708)
			(xy 339.186959 -283.501232) (xy 339.140827 -283.524738) (xy 339.091587 -283.540737) (xy 339.040449 -283.548836)
			(xy 338.988675 -283.548836) (xy 338.937537 -283.540737) (xy 338.888297 -283.524738) (xy 338.842165 -283.501232)
			(xy 338.800278 -283.4708) (xy 338.763668 -283.43419) (xy 338.733236 -283.392303) (xy 338.70973 -283.346171)
			(xy 338.693731 -283.296931) (xy 338.685632 -283.245793) (xy 338.685124 -283.219906) (xy 336.5246 -283.219906)
			(xy 336.524092 -283.245793) (xy 336.515993 -283.296931) (xy 336.499994 -283.346171) (xy 336.476488 -283.392303)
			(xy 336.446056 -283.43419) (xy 336.409446 -283.4708) (xy 336.367559 -283.501232) (xy 336.321427 -283.524738)
			(xy 336.272187 -283.540737) (xy 336.221049 -283.548836) (xy 336.169275 -283.548836) (xy 336.118137 -283.540737)
			(xy 336.068897 -283.524738) (xy 336.022765 -283.501232) (xy 335.980878 -283.4708) (xy 335.944268 -283.43419)
			(xy 335.913836 -283.392303) (xy 335.89033 -283.346171) (xy 335.874331 -283.296931) (xy 335.866232 -283.245793)
			(xy 335.865724 -283.219906) (xy 335.866254 -283.192198) (xy 335.875449 -283.137551) (xy 335.884012 -283.111194)
			(xy 335.891886 -283.089096) (xy 335.686654 -282.734004) (xy 335.663794 -282.729686) (xy 335.639001 -282.724454)
			(xy 335.591266 -282.707468) (xy 335.546691 -282.683379) (xy 335.506327 -282.652753) (xy 335.471124 -282.616312)
			(xy 335.441911 -282.574914) (xy 335.419375 -282.529534) (xy 335.404048 -282.48124) (xy 335.396291 -282.43117)
			(xy 335.395824 -282.405836) (xy 335.115408 -282.405836) (xy 335.1149 -282.431743) (xy 335.106794 -282.48292)
			(xy 335.090782 -282.532199) (xy 335.067259 -282.578366) (xy 335.036803 -282.620285) (xy 335.000165 -282.656923)
			(xy 334.958246 -282.687379) (xy 334.912079 -282.710902) (xy 334.8628 -282.726914) (xy 334.811623 -282.73502)
			(xy 334.759809 -282.73502) (xy 334.708632 -282.726914) (xy 334.659353 -282.710902) (xy 334.613186 -282.687379)
			(xy 334.571267 -282.656923) (xy 334.534629 -282.620285) (xy 334.504173 -282.578366) (xy 334.48065 -282.532199)
			(xy 334.464638 -282.48292) (xy 334.456532 -282.431743) (xy 334.456024 -282.405836) (xy 106.910632 -282.405836)
			(xy 106.910124 -282.431723) (xy 106.902025 -282.482861) (xy 106.886026 -282.532101) (xy 106.86252 -282.578233)
			(xy 106.832088 -282.62012) (xy 106.795478 -282.65673) (xy 106.753591 -282.687162) (xy 106.707459 -282.710668)
			(xy 106.658219 -282.726667) (xy 106.607081 -282.734766) (xy 106.555307 -282.734766) (xy 106.504169 -282.726667)
			(xy 106.454929 -282.710668) (xy 106.408797 -282.687162) (xy 106.36691 -282.65673) (xy 106.3303 -282.62012)
			(xy 106.299868 -282.578233) (xy 106.276362 -282.532101) (xy 106.260363 -282.482861) (xy 106.252264 -282.431723)
			(xy 106.251756 -282.405836) (xy 106.252296 -282.378128) (xy 106.261484 -282.323482) (xy 106.270044 -282.297124)
			(xy 106.277918 -282.275026) (xy 106.07294 -281.920188) (xy 106.05008 -281.91587) (xy 106.025256 -281.910713)
			(xy 105.977474 -281.893761) (xy 105.932853 -281.86969) (xy 105.892445 -281.839069) (xy 105.857203 -281.802621)
			(xy 105.827959 -281.761205) (xy 105.805403 -281.715799) (xy 105.790068 -281.667474) (xy 105.782315 -281.61737)
			(xy 105.781856 -281.59202) (xy 104.56164 -281.59202) (xy 104.561132 -281.617927) (xy 104.553026 -281.669104)
			(xy 104.537014 -281.718383) (xy 104.513491 -281.76455) (xy 104.483035 -281.806469) (xy 104.446397 -281.843107)
			(xy 104.404478 -281.873563) (xy 104.358311 -281.897086) (xy 104.309032 -281.913098) (xy 104.257855 -281.921204)
			(xy 104.206041 -281.921204) (xy 104.154864 -281.913098) (xy 104.105585 -281.897086) (xy 104.059418 -281.873563)
			(xy 104.017499 -281.843107) (xy 103.980861 -281.806469) (xy 103.950405 -281.76455) (xy 103.926882 -281.718383)
			(xy 103.91087 -281.669104) (xy 103.902764 -281.617927) (xy 103.902256 -281.59202) (xy 103.902852 -281.564303)
			(xy 103.912174 -281.509656) (xy 103.920798 -281.483308) (xy 103.928672 -281.46121) (xy 103.723694 -281.106372)
			(xy 103.700834 -281.102054) (xy 103.676009 -281.096858) (xy 103.628203 -281.079927) (xy 103.583555 -281.055874)
			(xy 103.543117 -281.025267) (xy 103.507844 -280.988827) (xy 103.478568 -280.947415) (xy 103.45598 -280.902007)
			(xy 103.440613 -280.853676) (xy 103.43283 -280.803562) (xy 103.432356 -280.778204) (xy 101.271832 -280.778204)
			(xy 101.271832 -280.778712) (xy 101.271241 -280.806228) (xy 101.262055 -280.860489) (xy 101.253544 -280.886662)
			(xy 101.245924 -280.908506) (xy 101.451156 -281.263852) (xy 101.474016 -281.26817) (xy 101.498826 -281.273386)
			(xy 101.546603 -281.290334) (xy 101.591222 -281.314398) (xy 101.631628 -281.345012) (xy 101.66687 -281.381453)
			(xy 101.696116 -281.422861) (xy 101.718675 -281.468259) (xy 101.734016 -281.516576) (xy 101.741776 -281.566673)
			(xy 101.74224 -281.59202) (xy 101.741732 -281.617927) (xy 101.733626 -281.669104) (xy 101.717614 -281.718383)
			(xy 101.694091 -281.76455) (xy 101.663635 -281.806469) (xy 101.626997 -281.843107) (xy 101.585078 -281.873563)
			(xy 101.538911 -281.897086) (xy 101.489632 -281.913098) (xy 101.438455 -281.921204) (xy 101.386641 -281.921204)
			(xy 101.335464 -281.913098) (xy 101.286185 -281.897086) (xy 101.240018 -281.873563) (xy 101.198099 -281.843107)
			(xy 101.161461 -281.806469) (xy 101.131005 -281.76455) (xy 101.107482 -281.718383) (xy 101.09147 -281.669104)
			(xy 101.083364 -281.617927) (xy 101.082856 -281.59202) (xy 101.083452 -281.564303) (xy 101.092774 -281.509656)
			(xy 101.101398 -281.483308) (xy 101.109272 -281.46121) (xy 100.904294 -281.106372) (xy 100.881434 -281.102054)
			(xy 100.856609 -281.096858) (xy 100.808803 -281.079927) (xy 100.764155 -281.055874) (xy 100.723717 -281.025267)
			(xy 100.688444 -280.988827) (xy 100.659168 -280.947415) (xy 100.63658 -280.902007) (xy 100.621213 -280.853676)
			(xy 100.61343 -280.803562) (xy 100.612956 -280.778204) (xy 98.452432 -280.778204) (xy 98.451927 -280.803537)
			(xy 98.444175 -280.853607) (xy 98.428854 -280.901902) (xy 98.406324 -280.947284) (xy 98.377117 -280.988685)
			(xy 98.34192 -281.025131) (xy 98.301561 -281.055762) (xy 98.256992 -281.079859) (xy 98.20926 -281.096853)
			(xy 98.184462 -281.102054) (xy 98.161602 -281.106372) (xy 97.956624 -281.46121) (xy 97.964498 -281.483308)
			(xy 97.973138 -281.509652) (xy 97.982453 -281.564301) (xy 97.98304 -281.59202) (xy 97.982532 -281.61791)
			(xy 99.20371 -281.61791) (xy 99.20371 -281.56609) (xy 99.211817 -281.514907) (xy 99.227832 -281.465624)
			(xy 99.25136 -281.419452) (xy 99.281822 -281.37753) (xy 99.318467 -281.34089) (xy 99.360393 -281.310435)
			(xy 99.406568 -281.286913) (xy 99.455854 -281.270906) (xy 99.507038 -281.262806) (xy 99.532948 -281.262328)
			(xy 99.558462 -281.262762) (xy 99.608879 -281.270631) (xy 99.657482 -281.286173) (xy 99.70311 -281.309017)
			(xy 99.744675 -281.338618) (xy 99.781182 -281.374269) (xy 99.796854 -281.394408) (xy 100.208842 -281.394408)
			(xy 100.224493 -281.374254) (xy 100.261007 -281.338611) (xy 100.302577 -281.309019) (xy 100.34821 -281.286186)
			(xy 100.396816 -281.270657) (xy 100.447235 -281.262802) (xy 100.472748 -281.262328) (xy 100.498654 -281.2628)
			(xy 100.549829 -281.270912) (xy 100.599104 -281.286928) (xy 100.645267 -281.310456) (xy 100.687182 -281.340914)
			(xy 100.723817 -281.377554) (xy 100.754269 -281.419474) (xy 100.77779 -281.465641) (xy 100.7938 -281.514918)
			(xy 100.801904 -281.566093) (xy 100.801904 -281.617907) (xy 100.7938 -281.669082) (xy 100.77779 -281.718359)
			(xy 100.754269 -281.764526) (xy 100.723817 -281.806446) (xy 100.687182 -281.843086) (xy 100.645267 -281.873544)
			(xy 100.599104 -281.897072) (xy 100.549829 -281.913088) (xy 100.498654 -281.9212) (xy 100.472748 -281.921712)
			(xy 100.447238 -281.921192) (xy 100.396825 -281.913339) (xy 100.348225 -281.897813) (xy 100.302596 -281.874985)
			(xy 100.26103 -281.8454) (xy 100.224517 -281.809764) (xy 100.208842 -281.789632) (xy 99.796854 -281.789632)
			(xy 99.781158 -281.809749) (xy 99.744652 -281.845392) (xy 99.703091 -281.874987) (xy 99.657467 -281.897826)
			(xy 99.60887 -281.913365) (xy 99.558459 -281.921231) (xy 99.532948 -281.921712) (xy 99.507038 -281.921194)
			(xy 99.455854 -281.913094) (xy 99.406568 -281.897087) (xy 99.360393 -281.873565) (xy 99.318467 -281.84311)
			(xy 99.281822 -281.80647) (xy 99.25136 -281.764548) (xy 99.227832 -281.718376) (xy 99.211817 -281.669093)
			(xy 99.20371 -281.61791) (xy 97.982532 -281.61791) (xy 97.982532 -281.617927) (xy 97.974426 -281.669104)
			(xy 97.958414 -281.718383) (xy 97.934891 -281.76455) (xy 97.904435 -281.806469) (xy 97.867797 -281.843107)
			(xy 97.825878 -281.873563) (xy 97.779711 -281.897086) (xy 97.730432 -281.913098) (xy 97.679255 -281.921204)
			(xy 97.627441 -281.921204) (xy 97.576264 -281.913098) (xy 97.526985 -281.897086) (xy 97.480818 -281.873563)
			(xy 97.438899 -281.843107) (xy 97.402261 -281.806469) (xy 97.371805 -281.76455) (xy 97.348282 -281.718383)
			(xy 97.33227 -281.669104) (xy 97.324164 -281.617927) (xy 97.323656 -281.59202) (xy 96.10344 -281.59202)
			(xy 96.103032 -281.617397) (xy 96.095259 -281.667553) (xy 96.079885 -281.715923) (xy 96.057273 -281.761362)
			(xy 96.027958 -281.802795) (xy 95.992635 -281.839241) (xy 95.95214 -281.869837) (xy 95.907431 -281.89386)
			(xy 95.859566 -281.910741) (xy 95.834708 -281.91587) (xy 95.811848 -281.920188) (xy 95.60687 -282.275026)
			(xy 95.614744 -282.297124) (xy 95.623311 -282.32348) (xy 95.632506 -282.378127) (xy 95.633032 -282.405836)
			(xy 95.913956 -282.405836) (xy 95.914464 -282.379949) (xy 95.922563 -282.328811) (xy 95.938562 -282.279571)
			(xy 95.962068 -282.233439) (xy 95.9925 -282.191552) (xy 96.02911 -282.154942) (xy 96.070997 -282.12451)
			(xy 96.117129 -282.101004) (xy 96.166369 -282.085005) (xy 96.217507 -282.076906) (xy 96.269281 -282.076906)
			(xy 96.320419 -282.085005) (xy 96.369659 -282.101004) (xy 96.415791 -282.12451) (xy 96.457678 -282.154942)
			(xy 96.494288 -282.191552) (xy 96.52472 -282.233439) (xy 96.548226 -282.279571) (xy 96.564225 -282.328811)
			(xy 96.572324 -282.379949) (xy 96.572832 -282.405836) (xy 96.572832 -282.406344) (xy 96.572295 -282.431704)
			(xy 96.854052 -282.431704) (xy 96.854052 -282.379896) (xy 96.862157 -282.328725) (xy 96.878166 -282.279453)
			(xy 96.901687 -282.233291) (xy 96.932138 -282.191377) (xy 96.968772 -282.154742) (xy 97.010686 -282.12429)
			(xy 97.056847 -282.100769) (xy 97.106119 -282.084758) (xy 97.15729 -282.076653) (xy 97.183194 -282.076144)
			(xy 97.208707 -282.076611) (xy 97.259122 -282.084472) (xy 97.307725 -282.100007) (xy 97.353354 -282.122845)
			(xy 97.394919 -282.152441) (xy 97.431427 -282.188087) (xy 97.4471 -282.208224) (xy 97.859088 -282.208224)
			(xy 97.874775 -282.188099) (xy 97.911281 -282.152454) (xy 97.952843 -282.122858) (xy 97.998469 -282.10002)
			(xy 98.047069 -282.084484) (xy 98.097483 -282.076622) (xy 98.122994 -282.076144) (xy 98.148907 -282.076553)
			(xy 98.200094 -282.08466) (xy 98.249383 -282.100674) (xy 98.295559 -282.124201) (xy 98.337487 -282.154663)
			(xy 98.374133 -282.191308) (xy 98.404596 -282.233235) (xy 98.428124 -282.279412) (xy 98.444139 -282.3287)
			(xy 98.452246 -282.379887) (xy 98.452246 -282.431713) (xy 98.444139 -282.4829) (xy 98.428124 -282.532188)
			(xy 98.404596 -282.578365) (xy 98.374133 -282.620292) (xy 98.337487 -282.656937) (xy 98.295559 -282.687399)
			(xy 98.249383 -282.710926) (xy 98.200094 -282.72694) (xy 98.148907 -282.735047) (xy 98.122994 -282.735528)
			(xy 98.097483 -282.735041) (xy 98.047069 -282.72718) (xy 97.998468 -282.711647) (xy 97.95284 -282.688813)
			(xy 97.911274 -282.659222) (xy 97.874762 -282.623582) (xy 97.859088 -282.603448) (xy 97.4471 -282.603448)
			(xy 97.43144 -282.623594) (xy 97.394926 -282.659235) (xy 97.353357 -282.688826) (xy 97.307726 -282.71166)
			(xy 97.259123 -282.727192) (xy 97.208707 -282.735052) (xy 97.183194 -282.735528) (xy 97.15729 -282.734947)
			(xy 97.106119 -282.726842) (xy 97.056847 -282.710831) (xy 97.010686 -282.68731) (xy 96.968772 -282.656858)
			(xy 96.932138 -282.620223) (xy 96.901687 -282.578309) (xy 96.878166 -282.532147) (xy 96.862157 -282.482875)
			(xy 96.854052 -282.431704) (xy 96.572295 -282.431704) (xy 96.572249 -282.43386) (xy 96.563058 -282.488121)
			(xy 96.554544 -282.514294) (xy 96.546924 -282.536392) (xy 96.752156 -282.891738) (xy 96.775016 -282.896056)
			(xy 96.799823 -282.901285) (xy 96.847599 -282.918232) (xy 96.892217 -282.942295) (xy 96.932623 -282.972907)
			(xy 96.967865 -283.009346) (xy 96.997111 -283.050752) (xy 97.019671 -283.096149) (xy 97.035013 -283.144464)
			(xy 97.042775 -283.194559) (xy 97.04324 -283.219906) (xy 99.203256 -283.219906) (xy 99.203737 -283.19456)
			(xy 99.21151 -283.144468) (xy 99.226857 -283.096156) (xy 99.249417 -283.050761) (xy 99.278659 -283.009354)
			(xy 99.313894 -282.97291) (xy 99.354291 -282.942288) (xy 99.398899 -282.918209) (xy 99.446666 -282.901241)
			(xy 99.47148 -282.896056) (xy 99.49434 -282.891738) (xy 99.699318 -282.5369) (xy 99.691698 -282.514802)
			(xy 99.683062 -282.488391) (xy 99.673735 -282.433617) (xy 99.673156 -282.405836) (xy 99.673664 -282.379949)
			(xy 99.681763 -282.328811) (xy 99.697762 -282.279571) (xy 99.721268 -282.233439) (xy 99.7517 -282.191552)
			(xy 99.78831 -282.154942) (xy 99.830197 -282.12451) (xy 99.876329 -282.101004) (xy 99.925569 -282.085005)
			(xy 99.976707 -282.076906) (xy 100.028481 -282.076906) (xy 100.079619 -282.085005) (xy 100.128859 -282.101004)
			(xy 100.174991 -282.12451) (xy 100.216878 -282.154942) (xy 100.253488 -282.191552) (xy 100.28392 -282.233439)
			(xy 100.307426 -282.279571) (xy 100.323425 -282.328811) (xy 100.331524 -282.379949) (xy 100.332032 -282.405836)
			(xy 101.552756 -282.405836) (xy 101.553216 -282.380501) (xy 101.560977 -282.33043) (xy 101.576305 -282.282135)
			(xy 101.598841 -282.236753) (xy 101.628054 -282.195352) (xy 101.663256 -282.158908) (xy 101.703619 -282.128277)
			(xy 101.748192 -282.104181) (xy 101.795927 -282.087187) (xy 101.820726 -282.081986) (xy 101.843586 -282.077668)
			(xy 102.048818 -281.722322) (xy 102.041198 -281.700478) (xy 102.03257 -281.674197) (xy 102.023258 -281.619675)
			(xy 102.022656 -281.59202) (xy 102.023164 -281.566113) (xy 102.03127 -281.514936) (xy 102.047282 -281.465657)
			(xy 102.070805 -281.41949) (xy 102.101261 -281.377571) (xy 102.137899 -281.340933) (xy 102.179818 -281.310477)
			(xy 102.225985 -281.286954) (xy 102.275264 -281.270942) (xy 102.326441 -281.262836) (xy 102.378255 -281.262836)
			(xy 102.429432 -281.270942) (xy 102.478711 -281.286954) (xy 102.524878 -281.310477) (xy 102.566797 -281.340933)
			(xy 102.603435 -281.377571) (xy 102.633891 -281.41949) (xy 102.657414 -281.465657) (xy 102.673426 -281.514936)
			(xy 102.681532 -281.566113) (xy 102.68204 -281.59202) (xy 102.681632 -281.617397) (xy 102.673859 -281.667553)
			(xy 102.658485 -281.715923) (xy 102.635873 -281.761362) (xy 102.606558 -281.802795) (xy 102.571235 -281.839241)
			(xy 102.53074 -281.869837) (xy 102.486031 -281.89386) (xy 102.438166 -281.910741) (xy 102.413308 -281.91587)
			(xy 102.390448 -281.920188) (xy 102.18547 -282.275026) (xy 102.193344 -282.297124) (xy 102.201911 -282.32348)
			(xy 102.211106 -282.378127) (xy 102.211632 -282.405836) (xy 102.211124 -282.431704) (xy 103.432652 -282.431704)
			(xy 103.432652 -282.379896) (xy 103.440757 -282.328725) (xy 103.456766 -282.279453) (xy 103.480287 -282.233291)
			(xy 103.510738 -282.191377) (xy 103.547372 -282.154742) (xy 103.589286 -282.12429) (xy 103.635447 -282.100769)
			(xy 103.684719 -282.084758) (xy 103.73589 -282.076653) (xy 103.761794 -282.076144) (xy 103.787307 -282.076611)
			(xy 103.837722 -282.084472) (xy 103.886325 -282.100007) (xy 103.931954 -282.122845) (xy 103.973519 -282.152441)
			(xy 104.010027 -282.188087) (xy 104.0257 -282.208224) (xy 104.437688 -282.208224) (xy 104.453375 -282.188099)
			(xy 104.489881 -282.152454) (xy 104.531443 -282.122858) (xy 104.577069 -282.10002) (xy 104.625669 -282.084484)
			(xy 104.676083 -282.076622) (xy 104.701594 -282.076144) (xy 104.727507 -282.076553) (xy 104.778694 -282.08466)
			(xy 104.827983 -282.100674) (xy 104.874159 -282.124201) (xy 104.916087 -282.154663) (xy 104.952733 -282.191308)
			(xy 104.983196 -282.233235) (xy 105.006724 -282.279412) (xy 105.022739 -282.3287) (xy 105.030846 -282.379887)
			(xy 105.030846 -282.431713) (xy 105.022739 -282.4829) (xy 105.006724 -282.532188) (xy 104.983196 -282.578365)
			(xy 104.952733 -282.620292) (xy 104.916087 -282.656937) (xy 104.874159 -282.687399) (xy 104.827983 -282.710926)
			(xy 104.778694 -282.72694) (xy 104.727507 -282.735047) (xy 104.701594 -282.735528) (xy 104.676083 -282.735041)
			(xy 104.625669 -282.72718) (xy 104.577068 -282.711647) (xy 104.53144 -282.688813) (xy 104.489874 -282.659222)
			(xy 104.453362 -282.623582) (xy 104.437688 -282.603448) (xy 104.0257 -282.603448) (xy 104.01004 -282.623594)
			(xy 103.973526 -282.659235) (xy 103.931957 -282.688826) (xy 103.886326 -282.71166) (xy 103.837723 -282.727192)
			(xy 103.787307 -282.735052) (xy 103.761794 -282.735528) (xy 103.73589 -282.734947) (xy 103.684719 -282.726842)
			(xy 103.635447 -282.710831) (xy 103.589286 -282.68731) (xy 103.547372 -282.656858) (xy 103.510738 -282.620223)
			(xy 103.480287 -282.578309) (xy 103.456766 -282.532147) (xy 103.440757 -282.482875) (xy 103.432652 -282.431704)
			(xy 102.211124 -282.431704) (xy 102.211124 -282.431723) (xy 102.203025 -282.482861) (xy 102.187026 -282.532101)
			(xy 102.16352 -282.578233) (xy 102.133088 -282.62012) (xy 102.096478 -282.65673) (xy 102.054591 -282.687162)
			(xy 102.008459 -282.710668) (xy 101.959219 -282.726667) (xy 101.908081 -282.734766) (xy 101.856307 -282.734766)
			(xy 101.805169 -282.726667) (xy 101.755929 -282.710668) (xy 101.709797 -282.687162) (xy 101.66791 -282.65673)
			(xy 101.6313 -282.62012) (xy 101.600868 -282.578233) (xy 101.577362 -282.532101) (xy 101.561363 -282.482861)
			(xy 101.553264 -282.431723) (xy 101.552756 -282.405836) (xy 100.332032 -282.405836) (xy 100.331594 -282.431161)
			(xy 100.323857 -282.481217) (xy 100.308554 -282.5295) (xy 100.286046 -282.574874) (xy 100.256862 -282.616272)
			(xy 100.22169 -282.652718) (xy 100.181356 -282.683356) (xy 100.136812 -282.707464) (xy 100.089103 -282.724474)
			(xy 100.064316 -282.729686) (xy 100.041456 -282.734004) (xy 99.836224 -283.089096) (xy 99.844098 -283.111194)
			(xy 99.852735 -283.137539) (xy 99.862052 -283.192188) (xy 99.86264 -283.219906) (xy 99.862132 -283.245791)
			(xy 101.083549 -283.245791) (xy 101.083549 -283.194009) (xy 101.091651 -283.142863) (xy 101.107654 -283.093616)
			(xy 101.131165 -283.047478) (xy 101.161604 -283.005586) (xy 101.198223 -282.968973) (xy 101.240119 -282.93854)
			(xy 101.28626 -282.915036) (xy 101.33551 -282.89904) (xy 101.386657 -282.890946) (xy 101.412548 -282.890468)
			(xy 101.43806 -282.890926) (xy 101.488475 -282.898793) (xy 101.537077 -282.914332) (xy 101.582705 -282.937172)
			(xy 101.62427 -282.966767) (xy 101.66078 -283.002412) (xy 101.676454 -283.022548) (xy 102.088442 -283.022548)
			(xy 102.104077 -283.002381) (xy 102.140596 -282.966741) (xy 102.18217 -282.937153) (xy 102.227806 -282.914323)
			(xy 102.276414 -282.898795) (xy 102.326834 -282.890941) (xy 102.352348 -282.890468) (xy 102.378233 -282.890967)
			(xy 102.429366 -282.899073) (xy 102.478601 -282.915077) (xy 102.524727 -282.938585) (xy 102.566608 -282.969019)
			(xy 102.603213 -283.005629) (xy 102.63364 -283.047514) (xy 102.657142 -283.093643) (xy 102.673139 -283.142881)
			(xy 102.681237 -283.194015) (xy 102.681237 -283.219906) (xy 104.842056 -283.219906) (xy 104.842537 -283.19456)
			(xy 104.85031 -283.144468) (xy 104.865657 -283.096156) (xy 104.888217 -283.050761) (xy 104.917459 -283.009354)
			(xy 104.952694 -282.97291) (xy 104.993091 -282.942288) (xy 105.037699 -282.918209) (xy 105.085466 -282.901241)
			(xy 105.11028 -282.896056) (xy 105.13314 -282.891738) (xy 105.338118 -282.5369) (xy 105.330498 -282.514802)
			(xy 105.321862 -282.488391) (xy 105.312535 -282.433617) (xy 105.311956 -282.405836) (xy 105.312464 -282.379949)
			(xy 105.320563 -282.328811) (xy 105.336562 -282.279571) (xy 105.360068 -282.233439) (xy 105.3905 -282.191552)
			(xy 105.42711 -282.154942) (xy 105.468997 -282.12451) (xy 105.515129 -282.101004) (xy 105.564369 -282.085005)
			(xy 105.615507 -282.076906) (xy 105.667281 -282.076906) (xy 105.718419 -282.085005) (xy 105.767659 -282.101004)
			(xy 105.813791 -282.12451) (xy 105.855678 -282.154942) (xy 105.892288 -282.191552) (xy 105.92272 -282.233439)
			(xy 105.946226 -282.279571) (xy 105.962225 -282.328811) (xy 105.970324 -282.379949) (xy 105.970832 -282.405836)
			(xy 105.970394 -282.431161) (xy 105.962657 -282.481217) (xy 105.947354 -282.5295) (xy 105.924846 -282.574874)
			(xy 105.895662 -282.616272) (xy 105.86049 -282.652718) (xy 105.820156 -282.683356) (xy 105.775612 -282.707464)
			(xy 105.727903 -282.724474) (xy 105.703116 -282.729686) (xy 105.680256 -282.734004) (xy 105.475024 -283.089096)
			(xy 105.482898 -283.111194) (xy 105.491535 -283.137539) (xy 105.500852 -283.192188) (xy 105.50144 -283.219906)
			(xy 105.500932 -283.245813) (xy 105.492826 -283.29699) (xy 105.476814 -283.346269) (xy 105.453291 -283.392436)
			(xy 105.422835 -283.434355) (xy 105.386197 -283.470993) (xy 105.344278 -283.501449) (xy 105.298111 -283.524972)
			(xy 105.248832 -283.540984) (xy 105.197655 -283.54909) (xy 105.145841 -283.54909) (xy 105.094664 -283.540984)
			(xy 105.045385 -283.524972) (xy 104.999218 -283.501449) (xy 104.957299 -283.470993) (xy 104.920661 -283.434355)
			(xy 104.890205 -283.392436) (xy 104.866682 -283.346269) (xy 104.85067 -283.29699) (xy 104.842564 -283.245813)
			(xy 104.842056 -283.219906) (xy 102.681237 -283.219906) (xy 102.681237 -283.245785) (xy 102.673139 -283.296919)
			(xy 102.657142 -283.346157) (xy 102.63364 -283.392286) (xy 102.603213 -283.434171) (xy 102.566608 -283.470781)
			(xy 102.524727 -283.501215) (xy 102.478601 -283.524723) (xy 102.429366 -283.540727) (xy 102.378233 -283.548833)
			(xy 102.352348 -283.549344) (xy 102.326836 -283.548851) (xy 102.276422 -283.540996) (xy 102.227819 -283.525467)
			(xy 102.18219 -283.502633) (xy 102.140624 -283.473042) (xy 102.104115 -283.437399) (xy 102.088442 -283.417264)
			(xy 101.676454 -283.417264) (xy 101.660739 -283.437366) (xy 101.624239 -283.473014) (xy 101.582683 -283.502612)
			(xy 101.537062 -283.525454) (xy 101.488467 -283.540995) (xy 101.438058 -283.548863) (xy 101.412548 -283.549344)
			(xy 101.386657 -283.548854) (xy 101.33551 -283.54076) (xy 101.28626 -283.524764) (xy 101.240119 -283.50126)
			(xy 101.198223 -283.470827) (xy 101.161604 -283.434214) (xy 101.131165 -283.392322) (xy 101.107654 -283.346184)
			(xy 101.091651 -283.296937) (xy 101.083549 -283.245791) (xy 99.862132 -283.245791) (xy 99.862132 -283.245813)
			(xy 99.854026 -283.29699) (xy 99.838014 -283.346269) (xy 99.814491 -283.392436) (xy 99.784035 -283.434355)
			(xy 99.747397 -283.470993) (xy 99.705478 -283.501449) (xy 99.659311 -283.524972) (xy 99.610032 -283.540984)
			(xy 99.558855 -283.54909) (xy 99.507041 -283.54909) (xy 99.455864 -283.540984) (xy 99.406585 -283.524972)
			(xy 99.360418 -283.501449) (xy 99.318499 -283.470993) (xy 99.281861 -283.434355) (xy 99.251405 -283.392436)
			(xy 99.227882 -283.346269) (xy 99.21187 -283.29699) (xy 99.203764 -283.245813) (xy 99.203256 -283.219906)
			(xy 97.04324 -283.219906) (xy 97.042732 -283.245813) (xy 97.034626 -283.29699) (xy 97.018614 -283.346269)
			(xy 96.995091 -283.392436) (xy 96.964635 -283.434355) (xy 96.927997 -283.470993) (xy 96.886078 -283.501449)
			(xy 96.839911 -283.524972) (xy 96.790632 -283.540984) (xy 96.739455 -283.54909) (xy 96.687641 -283.54909)
			(xy 96.636464 -283.540984) (xy 96.587185 -283.524972) (xy 96.541018 -283.501449) (xy 96.499099 -283.470993)
			(xy 96.462461 -283.434355) (xy 96.432005 -283.392436) (xy 96.408482 -283.346269) (xy 96.39247 -283.29699)
			(xy 96.384364 -283.245813) (xy 96.383856 -283.219906) (xy 96.384448 -283.192189) (xy 96.393773 -283.137542)
			(xy 96.402398 -283.111194) (xy 96.410272 -283.089096) (xy 96.205294 -282.734004) (xy 96.18218 -282.729686)
			(xy 96.15736 -282.724514) (xy 96.109579 -282.707563) (xy 96.064958 -282.683494) (xy 96.024551 -282.652875)
			(xy 95.989309 -282.616428) (xy 95.960065 -282.575014) (xy 95.937508 -282.52961) (xy 95.922171 -282.481287)
			(xy 95.914416 -282.431185) (xy 95.913956 -282.405836) (xy 95.633032 -282.405836) (xy 95.632524 -282.431723)
			(xy 95.624425 -282.482861) (xy 95.608426 -282.532101) (xy 95.58492 -282.578233) (xy 95.554488 -282.62012)
			(xy 95.517878 -282.65673) (xy 95.475991 -282.687162) (xy 95.429859 -282.710668) (xy 95.380619 -282.726667)
			(xy 95.329481 -282.734766) (xy 95.277707 -282.734766) (xy 95.226569 -282.726667) (xy 95.177329 -282.710668)
			(xy 95.131197 -282.687162) (xy 95.08931 -282.65673) (xy 95.0527 -282.62012) (xy 95.022268 -282.578233)
			(xy 94.998762 -282.532101) (xy 94.982763 -282.482861) (xy 94.974664 -282.431723) (xy 94.974156 -282.405836)
			(xy 93.75394 -282.405836) (xy 93.753432 -282.431743) (xy 93.745326 -282.48292) (xy 93.729314 -282.532199)
			(xy 93.705791 -282.578366) (xy 93.675335 -282.620285) (xy 93.638697 -282.656923) (xy 93.596778 -282.687379)
			(xy 93.550611 -282.710902) (xy 93.501332 -282.726914) (xy 93.450155 -282.73502) (xy 93.398341 -282.73502)
			(xy 93.347164 -282.726914) (xy 93.297885 -282.710902) (xy 93.251718 -282.687379) (xy 93.209799 -282.656923)
			(xy 93.173161 -282.620285) (xy 93.142705 -282.578366) (xy 93.119182 -282.532199) (xy 93.10317 -282.48292)
			(xy 93.095064 -282.431743) (xy 93.094556 -282.405836) (xy 91.87434 -282.405836) (xy 91.873903 -282.431201)
			(xy 91.86615 -282.481333) (xy 91.850801 -282.529685) (xy 91.828221 -282.575111) (xy 91.798942 -282.616537)
			(xy 91.763657 -282.652984) (xy 91.723202 -282.683591) (xy 91.678531 -282.707632) (xy 91.630703 -282.724539)
			(xy 91.605862 -282.729686) (xy 91.583002 -282.734004) (xy 91.378024 -283.089096) (xy 91.385644 -283.11094)
			(xy 91.394193 -283.137235) (xy 91.40339 -283.191753) (xy 91.403932 -283.219398) (xy 91.403932 -283.219906)
			(xy 91.403424 -283.245787) (xy 92.625176 -283.245787) (xy 92.625176 -283.194013) (xy 92.633275 -283.142878)
			(xy 92.649273 -283.093638) (xy 92.672778 -283.047508) (xy 92.703209 -283.005622) (xy 92.739818 -282.969013)
			(xy 92.781703 -282.938581) (xy 92.827833 -282.915076) (xy 92.877072 -282.899076) (xy 92.928207 -282.890976)
			(xy 92.954094 -282.890468) (xy 92.979605 -282.890965) (xy 93.030018 -282.898824) (xy 93.078619 -282.914355)
			(xy 93.124247 -282.937187) (xy 93.165813 -282.966776) (xy 93.202325 -283.002415) (xy 93.218 -283.022548)
			(xy 93.629988 -283.022548) (xy 93.645654 -283.002407) (xy 93.682167 -282.966766) (xy 93.723734 -282.937174)
			(xy 93.769364 -282.91434) (xy 93.817967 -282.898806) (xy 93.868382 -282.890945) (xy 93.893894 -282.890468)
			(xy 93.919784 -282.890937) (xy 93.970927 -282.899036) (xy 94.020174 -282.915037) (xy 94.066311 -282.938544)
			(xy 94.108202 -282.968979) (xy 94.144817 -283.005593) (xy 94.175253 -283.047484) (xy 94.198761 -283.093621)
			(xy 94.214762 -283.142867) (xy 94.222863 -283.19401) (xy 94.222863 -283.24579) (xy 94.214762 -283.296933)
			(xy 94.198761 -283.346179) (xy 94.175253 -283.392316) (xy 94.144817 -283.434207) (xy 94.108202 -283.470821)
			(xy 94.066311 -283.501256) (xy 94.020174 -283.524763) (xy 93.970927 -283.540764) (xy 93.919784 -283.548863)
			(xy 93.893894 -283.549344) (xy 93.868381 -283.54889) (xy 93.817964 -283.541027) (xy 93.769361 -283.52549)
			(xy 93.723732 -283.502649) (xy 93.682168 -283.473051) (xy 93.64566 -283.437402) (xy 93.629988 -283.417264)
			(xy 93.218 -283.417264) (xy 93.202317 -283.437392) (xy 93.16581 -283.473038) (xy 93.124247 -283.502633)
			(xy 93.078621 -283.525471) (xy 93.03002 -283.541006) (xy 92.979606 -283.548867) (xy 92.954094 -283.549344)
			(xy 92.928207 -283.548824) (xy 92.877072 -283.540724) (xy 92.827833 -283.524724) (xy 92.781703 -283.501219)
			(xy 92.739818 -283.470787) (xy 92.703209 -283.434178) (xy 92.672778 -283.392292) (xy 92.649273 -283.346162)
			(xy 92.633275 -283.296922) (xy 92.625176 -283.245787) (xy 91.403424 -283.245787) (xy 91.403424 -283.245793)
			(xy 91.395325 -283.296931) (xy 91.379326 -283.346171) (xy 91.35582 -283.392303) (xy 91.325388 -283.43419)
			(xy 91.288778 -283.4708) (xy 91.246891 -283.501232) (xy 91.200759 -283.524738) (xy 91.151519 -283.540737)
			(xy 91.100381 -283.548836) (xy 91.048607 -283.548836) (xy 90.997469 -283.540737) (xy 90.948229 -283.524738)
			(xy 90.902097 -283.501232) (xy 90.86021 -283.4708) (xy 90.8236 -283.43419) (xy 90.793168 -283.392303)
			(xy 90.769662 -283.346171) (xy 90.753663 -283.296931) (xy 90.745564 -283.245793) (xy 90.745056 -283.219906)
			(xy 88.584532 -283.219906) (xy 88.584024 -283.245793) (xy 88.575925 -283.296931) (xy 88.559926 -283.346171)
			(xy 88.53642 -283.392303) (xy 88.505988 -283.43419) (xy 88.469378 -283.4708) (xy 88.427491 -283.501232)
			(xy 88.381359 -283.524738) (xy 88.332119 -283.540737) (xy 88.280981 -283.548836) (xy 88.229207 -283.548836)
			(xy 88.178069 -283.540737) (xy 88.128829 -283.524738) (xy 88.082697 -283.501232) (xy 88.04081 -283.4708)
			(xy 88.0042 -283.43419) (xy 87.973768 -283.392303) (xy 87.950262 -283.346171) (xy 87.934263 -283.296931)
			(xy 87.926164 -283.245793) (xy 87.925656 -283.219906) (xy 87.926189 -283.192198) (xy 87.935382 -283.137551)
			(xy 87.943944 -283.111194) (xy 87.951818 -283.089096) (xy 87.746586 -282.734004) (xy 87.723726 -282.729686)
			(xy 87.698938 -282.724431) (xy 87.651203 -282.70745) (xy 87.606628 -282.683364) (xy 87.566263 -282.652742)
			(xy 87.531059 -282.616304) (xy 87.501844 -282.574908) (xy 87.479308 -282.52953) (xy 87.463981 -282.481238)
			(xy 87.456223 -282.431169) (xy 87.455756 -282.405836) (xy 87.17534 -282.405836) (xy 87.174832 -282.431743)
			(xy 87.166726 -282.48292) (xy 87.150714 -282.532199) (xy 87.127191 -282.578366) (xy 87.096735 -282.620285)
			(xy 87.060097 -282.656923) (xy 87.018178 -282.687379) (xy 86.972011 -282.710902) (xy 86.922732 -282.726914)
			(xy 86.871555 -282.73502) (xy 86.819741 -282.73502) (xy 86.768564 -282.726914) (xy 86.719285 -282.710902)
			(xy 86.673118 -282.687379) (xy 86.631199 -282.656923) (xy 86.594561 -282.620285) (xy 86.564105 -282.578366)
			(xy 86.540582 -282.532199) (xy 86.52457 -282.48292) (xy 86.516464 -282.431743) (xy 86.515956 -282.405836)
			(xy 2.509012 -282.405836) (xy 2.509012 -284.033722) (xy 86.515956 -284.033722) (xy 86.516464 -284.007815)
			(xy 86.52457 -283.956638) (xy 86.540582 -283.907359) (xy 86.564105 -283.861192) (xy 86.594561 -283.819273)
			(xy 86.631199 -283.782635) (xy 86.673118 -283.752179) (xy 86.719285 -283.728656) (xy 86.768564 -283.712644)
			(xy 86.819741 -283.704538) (xy 86.871555 -283.704538) (xy 86.922732 -283.712644) (xy 86.972011 -283.728656)
			(xy 87.018178 -283.752179) (xy 87.060097 -283.782635) (xy 87.096735 -283.819273) (xy 87.127191 -283.861192)
			(xy 87.150714 -283.907359) (xy 87.166726 -283.956638) (xy 87.174832 -284.007815) (xy 87.17534 -284.033722)
			(xy 334.456024 -284.033722) (xy 334.456532 -284.007815) (xy 334.464638 -283.956638) (xy 334.48065 -283.907359)
			(xy 334.504173 -283.861192) (xy 334.534629 -283.819273) (xy 334.571267 -283.782635) (xy 334.613186 -283.752179)
			(xy 334.659353 -283.728656) (xy 334.708632 -283.712644) (xy 334.759809 -283.704538) (xy 334.811623 -283.704538)
			(xy 334.8628 -283.712644) (xy 334.912079 -283.728656) (xy 334.958246 -283.752179) (xy 335.000165 -283.782635)
			(xy 335.036803 -283.819273) (xy 335.067259 -283.861192) (xy 335.090782 -283.907359) (xy 335.106794 -283.956638)
			(xy 335.1149 -284.007815) (xy 335.115408 -284.033722) (xy 335.114819 -284.06144) (xy 335.105492 -284.116086)
			(xy 335.096866 -284.142434) (xy 335.088992 -284.164532) (xy 335.29397 -284.51937) (xy 335.31683 -284.523688)
			(xy 335.341643 -284.528833) (xy 335.389384 -284.545828) (xy 335.433962 -284.569927) (xy 335.474328 -284.600564)
			(xy 335.50953 -284.637016) (xy 335.538741 -284.678425) (xy 335.561271 -284.723817) (xy 335.576591 -284.772121)
			(xy 335.584339 -284.8222) (xy 335.5848 -284.847538) (xy 335.584292 -284.873425) (xy 335.576193 -284.924563)
			(xy 335.560194 -284.973803) (xy 335.536688 -285.019935) (xy 335.506256 -285.061822) (xy 335.469646 -285.098432)
			(xy 335.427759 -285.128864) (xy 335.381627 -285.15237) (xy 335.332387 -285.168369) (xy 335.281249 -285.176468)
			(xy 335.229475 -285.176468) (xy 335.178337 -285.168369) (xy 335.129097 -285.15237) (xy 335.082965 -285.128864)
			(xy 335.041078 -285.098432) (xy 335.004468 -285.061822) (xy 334.974036 -285.019935) (xy 334.95053 -284.973803)
			(xy 334.934531 -284.924563) (xy 334.926432 -284.873425) (xy 334.925924 -284.847538) (xy 334.926462 -284.81983)
			(xy 334.935651 -284.765183) (xy 334.944212 -284.738826) (xy 334.952086 -284.716728) (xy 334.747108 -284.36189)
			(xy 334.724248 -284.357572) (xy 334.699419 -284.352437) (xy 334.651638 -284.33548) (xy 334.607017 -284.311405)
			(xy 334.56661 -284.280781) (xy 334.531369 -284.24433) (xy 334.502126 -284.202912) (xy 334.479571 -284.157504)
			(xy 334.464236 -284.109178) (xy 334.456483 -284.059073) (xy 334.456024 -284.033722) (xy 87.17534 -284.033722)
			(xy 87.174755 -284.06144) (xy 87.165426 -284.116086) (xy 87.156798 -284.142434) (xy 87.148924 -284.164532)
			(xy 87.353902 -284.51937) (xy 87.376762 -284.523688) (xy 87.401564 -284.528882) (xy 87.449305 -284.545867)
			(xy 87.493884 -284.569958) (xy 87.534252 -284.600587) (xy 87.569457 -284.637033) (xy 87.598669 -284.678438)
			(xy 87.621201 -284.723825) (xy 87.636522 -284.772125) (xy 87.644271 -284.822202) (xy 87.644732 -284.847538)
			(xy 87.644224 -284.873425) (xy 87.636125 -284.924563) (xy 87.620126 -284.973803) (xy 87.59662 -285.019935)
			(xy 87.566188 -285.061822) (xy 87.529578 -285.098432) (xy 87.487691 -285.128864) (xy 87.441559 -285.15237)
			(xy 87.392319 -285.168369) (xy 87.341181 -285.176468) (xy 87.289407 -285.176468) (xy 87.238269 -285.168369)
			(xy 87.189029 -285.15237) (xy 87.142897 -285.128864) (xy 87.10101 -285.098432) (xy 87.0644 -285.061822)
			(xy 87.033968 -285.019935) (xy 87.010462 -284.973803) (xy 86.994463 -284.924563) (xy 86.986364 -284.873425)
			(xy 86.985856 -284.847538) (xy 86.986397 -284.81983) (xy 86.995584 -284.765184) (xy 87.004144 -284.738826)
			(xy 87.012018 -284.716728) (xy 86.80704 -284.36189) (xy 86.78418 -284.357572) (xy 86.759356 -284.352414)
			(xy 86.711575 -284.335461) (xy 86.666954 -284.311391) (xy 86.626545 -284.28077) (xy 86.591303 -284.244322)
			(xy 86.56206 -284.202906) (xy 86.539504 -284.1575) (xy 86.524169 -284.109175) (xy 86.516415 -284.059072)
			(xy 86.515956 -284.033722) (xy 2.509012 -284.033722) (xy 2.509012 -284.873384) (xy 85.106807 -284.873384)
			(xy 85.106807 -284.821616) (xy 85.114906 -284.770485) (xy 85.130903 -284.72125) (xy 85.154405 -284.675125)
			(xy 85.184833 -284.633243) (xy 85.221438 -284.596637) (xy 85.263319 -284.566208) (xy 85.309445 -284.542705)
			(xy 85.358679 -284.526707) (xy 85.40981 -284.518608) (xy 85.435694 -284.5181) (xy 85.461187 -284.518588)
			(xy 85.511565 -284.526449) (xy 85.560127 -284.541983) (xy 85.605714 -284.564818) (xy 85.647235 -284.594409)
			(xy 85.683698 -284.630049) (xy 85.699346 -284.65018) (xy 86.111842 -284.65018) (xy 86.127489 -284.630047)
			(xy 86.163951 -284.594407) (xy 86.205472 -284.564814) (xy 86.251059 -284.541976) (xy 86.299622 -284.526441)
			(xy 86.35 -284.518579) (xy 86.375494 -284.5181) (xy 86.401387 -284.518505) (xy 86.452535 -284.526605)
			(xy 86.501786 -284.542607) (xy 86.547927 -284.566116) (xy 86.589823 -284.596555) (xy 86.626441 -284.633172)
			(xy 86.65688 -284.675067) (xy 86.680391 -284.721208) (xy 86.696394 -284.770459) (xy 86.704495 -284.821607)
			(xy 86.704495 -284.873393) (xy 86.696394 -284.924541) (xy 86.680391 -284.973792) (xy 86.65688 -285.019933)
			(xy 86.626441 -285.061828) (xy 86.589823 -285.098445) (xy 86.547927 -285.128884) (xy 86.501786 -285.152393)
			(xy 86.452535 -285.168395) (xy 86.401387 -285.176495) (xy 86.375494 -285.176976) (xy 86.35 -285.176506)
			(xy 86.299621 -285.168643) (xy 86.251058 -285.153106) (xy 86.205471 -285.130267) (xy 86.16395 -285.100672)
			(xy 86.127489 -285.065029) (xy 86.111842 -285.044896) (xy 85.699346 -285.044896) (xy 85.683699 -285.065029)
			(xy 85.647238 -285.100671) (xy 85.605717 -285.130265) (xy 85.56013 -285.153102) (xy 85.511566 -285.168637)
			(xy 85.461188 -285.176498) (xy 85.435694 -285.176976) (xy 85.40981 -285.176392) (xy 85.358679 -285.168293)
			(xy 85.309445 -285.152295) (xy 85.263319 -285.128792) (xy 85.221438 -285.098363) (xy 85.184833 -285.061757)
			(xy 85.154405 -285.019875) (xy 85.130903 -284.97375) (xy 85.114906 -284.924515) (xy 85.106807 -284.873384)
			(xy 2.509012 -284.873384) (xy 2.509012 -285.661354) (xy 87.455756 -285.661354) (xy 87.456232 -285.63602)
			(xy 87.46399 -285.585949) (xy 87.479317 -285.537654) (xy 87.50185 -285.492273) (xy 87.531061 -285.450872)
			(xy 87.566261 -285.414427) (xy 87.606622 -285.383796) (xy 87.651194 -285.3597) (xy 87.698927 -285.342705)
			(xy 87.723726 -285.337504) (xy 87.746586 -285.333186) (xy 87.951564 -284.978094) (xy 87.943944 -284.95625)
			(xy 87.935376 -284.929894) (xy 87.926181 -284.875247) (xy 87.925656 -284.847538) (xy 87.926164 -284.821651)
			(xy 87.934263 -284.770513) (xy 87.950262 -284.721273) (xy 87.973768 -284.675141) (xy 88.0042 -284.633254)
			(xy 88.04081 -284.596644) (xy 88.082697 -284.566212) (xy 88.128829 -284.542706) (xy 88.178069 -284.526707)
			(xy 88.229207 -284.518608) (xy 88.280981 -284.518608) (xy 88.332119 -284.526707) (xy 88.381359 -284.542706)
			(xy 88.427491 -284.566212) (xy 88.469378 -284.596644) (xy 88.505988 -284.633254) (xy 88.53642 -284.675141)
			(xy 88.559926 -284.721273) (xy 88.575925 -284.770513) (xy 88.584024 -284.821651) (xy 88.584532 -284.847538)
			(xy 88.584058 -284.872872) (xy 88.576301 -284.922944) (xy 88.560975 -284.971239) (xy 88.538441 -285.016622)
			(xy 88.50923 -285.058022) (xy 88.47403 -285.094467) (xy 88.433668 -285.125098) (xy 88.389095 -285.149194)
			(xy 88.341361 -285.166187) (xy 88.316562 -285.171388) (xy 88.293702 -285.175706) (xy 88.088724 -285.530798)
			(xy 88.096344 -285.552642) (xy 88.104909 -285.578999) (xy 88.114106 -285.633646) (xy 88.114632 -285.661354)
			(xy 89.335356 -285.661354) (xy 89.335864 -285.635467) (xy 89.343963 -285.584329) (xy 89.359962 -285.535089)
			(xy 89.383468 -285.488957) (xy 89.4139 -285.44707) (xy 89.45051 -285.41046) (xy 89.492397 -285.380028)
			(xy 89.538529 -285.356522) (xy 89.587769 -285.340523) (xy 89.638907 -285.332424) (xy 89.690681 -285.332424)
			(xy 89.741819 -285.340523) (xy 89.791059 -285.356522) (xy 89.837191 -285.380028) (xy 89.879078 -285.41046)
			(xy 89.915688 -285.44707) (xy 89.94612 -285.488957) (xy 89.969626 -285.535089) (xy 89.985625 -285.584329)
			(xy 89.993724 -285.635467) (xy 89.994232 -285.661354) (xy 90.275156 -285.661354) (xy 90.27559 -285.636007)
			(xy 90.28337 -285.585913) (xy 90.298725 -285.537599) (xy 90.321292 -285.492204) (xy 90.35054 -285.450798)
			(xy 90.385779 -285.414354) (xy 90.426181 -285.383733) (xy 90.470793 -285.359656) (xy 90.518564 -285.342688)
			(xy 90.54338 -285.337504) (xy 90.56624 -285.333186) (xy 90.771218 -284.978348) (xy 90.763344 -284.956504)
			(xy 90.754767 -284.930085) (xy 90.745569 -284.87531) (xy 90.745056 -284.847538) (xy 90.745564 -284.821651)
			(xy 90.753663 -284.770513) (xy 90.769662 -284.721273) (xy 90.793168 -284.675141) (xy 90.8236 -284.633254)
			(xy 90.86021 -284.596644) (xy 90.902097 -284.566212) (xy 90.948229 -284.542706) (xy 90.997469 -284.526707)
			(xy 91.048607 -284.518608) (xy 91.100381 -284.518608) (xy 91.151519 -284.526707) (xy 91.200759 -284.542706)
			(xy 91.246891 -284.566212) (xy 91.288778 -284.596644) (xy 91.325388 -284.633254) (xy 91.35582 -284.675141)
			(xy 91.379326 -284.721273) (xy 91.395325 -284.770513) (xy 91.403424 -284.821651) (xy 91.403932 -284.847538)
			(xy 91.403458 -284.872872) (xy 91.395701 -284.922944) (xy 91.380375 -284.971239) (xy 91.357841 -285.016622)
			(xy 91.32863 -285.058022) (xy 91.29343 -285.094467) (xy 91.253068 -285.125098) (xy 91.208495 -285.149194)
			(xy 91.160761 -285.166187) (xy 91.135962 -285.171388) (xy 91.113102 -285.175706) (xy 90.908124 -285.530544)
			(xy 90.915998 -285.552642) (xy 90.924622 -285.57899) (xy 90.933948 -285.633636) (xy 90.93454 -285.661354)
			(xy 91.214956 -285.661354) (xy 91.215464 -285.635447) (xy 91.22357 -285.58427) (xy 91.239582 -285.534991)
			(xy 91.263105 -285.488824) (xy 91.293561 -285.446905) (xy 91.330199 -285.410267) (xy 91.372118 -285.379811)
			(xy 91.418285 -285.356288) (xy 91.467564 -285.340276) (xy 91.518741 -285.33217) (xy 91.570555 -285.33217)
			(xy 91.621732 -285.340276) (xy 91.671011 -285.356288) (xy 91.717178 -285.379811) (xy 91.759097 -285.410267)
			(xy 91.795735 -285.446905) (xy 91.826191 -285.488824) (xy 91.849714 -285.534991) (xy 91.865726 -285.58427)
			(xy 91.873832 -285.635447) (xy 91.87434 -285.661354) (xy 92.154756 -285.661354) (xy 92.155232 -285.63602)
			(xy 92.16299 -285.585949) (xy 92.178317 -285.537654) (xy 92.20085 -285.492273) (xy 92.230061 -285.450872)
			(xy 92.265261 -285.414427) (xy 92.305622 -285.383796) (xy 92.350194 -285.3597) (xy 92.397927 -285.342705)
			(xy 92.422726 -285.337504) (xy 92.445586 -285.333186) (xy 92.650818 -284.97784) (xy 92.643198 -284.955996)
			(xy 92.634574 -284.929714) (xy 92.625259 -284.875193) (xy 92.624656 -284.847538) (xy 92.625164 -284.821631)
			(xy 92.63327 -284.770454) (xy 92.649282 -284.721175) (xy 92.672805 -284.675008) (xy 92.703261 -284.633089)
			(xy 92.739899 -284.596451) (xy 92.781818 -284.565995) (xy 92.827985 -284.542472) (xy 92.877264 -284.52646)
			(xy 92.928441 -284.518354) (xy 92.980255 -284.518354) (xy 93.031432 -284.52646) (xy 93.080711 -284.542472)
			(xy 93.126878 -284.565995) (xy 93.168797 -284.596451) (xy 93.205435 -284.633089) (xy 93.235891 -284.675008)
			(xy 93.259414 -284.721175) (xy 93.275426 -284.770454) (xy 93.283532 -284.821631) (xy 93.28404 -284.847538)
			(xy 93.283648 -284.872916) (xy 93.275873 -284.923072) (xy 93.260496 -284.971442) (xy 93.237881 -285.016882)
			(xy 93.208565 -285.058314) (xy 93.17324 -285.09476) (xy 93.132743 -285.125356) (xy 93.088033 -285.149379)
			(xy 93.040166 -285.166259) (xy 93.015308 -285.171388) (xy 92.992448 -285.175706) (xy 92.78747 -285.530544)
			(xy 92.795344 -285.552642) (xy 92.803916 -285.578997) (xy 92.813107 -285.633645) (xy 92.813632 -285.661354)
			(xy 93.094556 -285.661354) (xy 93.095064 -285.635467) (xy 93.103163 -285.584329) (xy 93.119162 -285.535089)
			(xy 93.142668 -285.488957) (xy 93.1731 -285.44707) (xy 93.20971 -285.41046) (xy 93.251597 -285.380028)
			(xy 93.297729 -285.356522) (xy 93.346969 -285.340523) (xy 93.398107 -285.332424) (xy 93.449881 -285.332424)
			(xy 93.501019 -285.340523) (xy 93.550259 -285.356522) (xy 93.596391 -285.380028) (xy 93.638278 -285.41046)
			(xy 93.674888 -285.44707) (xy 93.70532 -285.488957) (xy 93.728826 -285.535089) (xy 93.744825 -285.584329)
			(xy 93.752924 -285.635467) (xy 93.753432 -285.661354) (xy 94.034356 -285.661354) (xy 94.034832 -285.63602)
			(xy 94.04259 -285.585949) (xy 94.057917 -285.537654) (xy 94.08045 -285.492273) (xy 94.109661 -285.450872)
			(xy 94.144861 -285.414427) (xy 94.185222 -285.383796) (xy 94.229794 -285.3597) (xy 94.277527 -285.342705)
			(xy 94.302326 -285.337504) (xy 94.325186 -285.333186) (xy 94.530418 -284.97784) (xy 94.522798 -284.955996)
			(xy 94.514174 -284.929714) (xy 94.504859 -284.875193) (xy 94.504256 -284.847538) (xy 94.504764 -284.821631)
			(xy 94.51287 -284.770454) (xy 94.528882 -284.721175) (xy 94.552405 -284.675008) (xy 94.582861 -284.633089)
			(xy 94.619499 -284.596451) (xy 94.661418 -284.565995) (xy 94.707585 -284.542472) (xy 94.756864 -284.52646)
			(xy 94.808041 -284.518354) (xy 94.859855 -284.518354) (xy 94.911032 -284.52646) (xy 94.960311 -284.542472)
			(xy 95.006478 -284.565995) (xy 95.048397 -284.596451) (xy 95.085035 -284.633089) (xy 95.115491 -284.675008)
			(xy 95.139014 -284.721175) (xy 95.155026 -284.770454) (xy 95.163132 -284.821631) (xy 95.16364 -284.847538)
			(xy 95.163248 -284.872916) (xy 95.155473 -284.923072) (xy 95.140096 -284.971442) (xy 95.117481 -285.016882)
			(xy 95.088165 -285.058314) (xy 95.05284 -285.09476) (xy 95.012343 -285.125356) (xy 94.967633 -285.149379)
			(xy 94.919766 -285.166259) (xy 94.894908 -285.171388) (xy 94.872048 -285.175706) (xy 94.66707 -285.530544)
			(xy 94.674944 -285.552642) (xy 94.683516 -285.578997) (xy 94.692707 -285.633645) (xy 94.693232 -285.661354)
			(xy 94.974156 -285.661354) (xy 94.974664 -285.635467) (xy 94.982763 -285.584329) (xy 94.998762 -285.535089)
			(xy 95.022268 -285.488957) (xy 95.0527 -285.44707) (xy 95.08931 -285.41046) (xy 95.131197 -285.380028)
			(xy 95.177329 -285.356522) (xy 95.226569 -285.340523) (xy 95.277707 -285.332424) (xy 95.329481 -285.332424)
			(xy 95.380619 -285.340523) (xy 95.429859 -285.356522) (xy 95.475991 -285.380028) (xy 95.517878 -285.41046)
			(xy 95.554488 -285.44707) (xy 95.58492 -285.488957) (xy 95.608426 -285.535089) (xy 95.624425 -285.584329)
			(xy 95.632524 -285.635467) (xy 95.633032 -285.661354) (xy 95.913956 -285.661354) (xy 95.914432 -285.63602)
			(xy 95.92219 -285.585949) (xy 95.937517 -285.537654) (xy 95.96005 -285.492273) (xy 95.989261 -285.450872)
			(xy 96.024461 -285.414427) (xy 96.064822 -285.383796) (xy 96.109394 -285.3597) (xy 96.157127 -285.342705)
			(xy 96.181926 -285.337504) (xy 96.204786 -285.333186) (xy 96.410018 -284.97784) (xy 96.402398 -284.955996)
			(xy 96.393774 -284.929714) (xy 96.384459 -284.875193) (xy 96.383856 -284.847538) (xy 96.384364 -284.821631)
			(xy 96.39247 -284.770454) (xy 96.408482 -284.721175) (xy 96.432005 -284.675008) (xy 96.462461 -284.633089)
			(xy 96.499099 -284.596451) (xy 96.541018 -284.565995) (xy 96.587185 -284.542472) (xy 96.636464 -284.52646)
			(xy 96.687641 -284.518354) (xy 96.739455 -284.518354) (xy 96.790632 -284.52646) (xy 96.839911 -284.542472)
			(xy 96.886078 -284.565995) (xy 96.927997 -284.596451) (xy 96.964635 -284.633089) (xy 96.995091 -284.675008)
			(xy 97.018614 -284.721175) (xy 97.034626 -284.770454) (xy 97.042732 -284.821631) (xy 97.04324 -284.847538)
			(xy 97.042848 -284.872916) (xy 97.035073 -284.923072) (xy 97.019696 -284.971442) (xy 96.997081 -285.016882)
			(xy 96.967765 -285.058314) (xy 96.93244 -285.09476) (xy 96.891943 -285.125356) (xy 96.847233 -285.149379)
			(xy 96.799366 -285.166259) (xy 96.774508 -285.171388) (xy 96.751648 -285.175706) (xy 96.54667 -285.530544)
			(xy 96.554544 -285.552642) (xy 96.563116 -285.578997) (xy 96.572307 -285.633645) (xy 96.572832 -285.661354)
			(xy 96.853756 -285.661354) (xy 96.854264 -285.635467) (xy 96.862363 -285.584329) (xy 96.878362 -285.535089)
			(xy 96.901868 -285.488957) (xy 96.9323 -285.44707) (xy 96.96891 -285.41046) (xy 97.010797 -285.380028)
			(xy 97.056929 -285.356522) (xy 97.106169 -285.340523) (xy 97.157307 -285.332424) (xy 97.209081 -285.332424)
			(xy 97.260219 -285.340523) (xy 97.309459 -285.356522) (xy 97.355591 -285.380028) (xy 97.397478 -285.41046)
			(xy 97.434088 -285.44707) (xy 97.46452 -285.488957) (xy 97.488026 -285.535089) (xy 97.504025 -285.584329)
			(xy 97.512124 -285.635467) (xy 97.512632 -285.661354) (xy 97.793556 -285.661354) (xy 97.794032 -285.63602)
			(xy 97.80179 -285.585949) (xy 97.817117 -285.537654) (xy 97.83965 -285.492273) (xy 97.868861 -285.450872)
			(xy 97.904061 -285.414427) (xy 97.944422 -285.383796) (xy 97.988994 -285.3597) (xy 98.036727 -285.342705)
			(xy 98.061526 -285.337504) (xy 98.084386 -285.333186) (xy 98.289618 -284.97784) (xy 98.281998 -284.955996)
			(xy 98.273374 -284.929714) (xy 98.264059 -284.875193) (xy 98.263456 -284.847538) (xy 98.263964 -284.821631)
			(xy 98.27207 -284.770454) (xy 98.288082 -284.721175) (xy 98.311605 -284.675008) (xy 98.342061 -284.633089)
			(xy 98.378699 -284.596451) (xy 98.420618 -284.565995) (xy 98.466785 -284.542472) (xy 98.516064 -284.52646)
			(xy 98.567241 -284.518354) (xy 98.619055 -284.518354) (xy 98.670232 -284.52646) (xy 98.719511 -284.542472)
			(xy 98.765678 -284.565995) (xy 98.807597 -284.596451) (xy 98.844235 -284.633089) (xy 98.874691 -284.675008)
			(xy 98.898214 -284.721175) (xy 98.914226 -284.770454) (xy 98.922332 -284.821631) (xy 98.92284 -284.847538)
			(xy 98.922448 -284.872916) (xy 98.914673 -284.923072) (xy 98.899296 -284.971442) (xy 98.876681 -285.016882)
			(xy 98.847365 -285.058314) (xy 98.81204 -285.09476) (xy 98.771543 -285.125356) (xy 98.726833 -285.149379)
			(xy 98.678966 -285.166259) (xy 98.654108 -285.171388) (xy 98.631248 -285.175706) (xy 98.42627 -285.530544)
			(xy 98.434144 -285.552642) (xy 98.442716 -285.578997) (xy 98.451907 -285.633645) (xy 98.452432 -285.661354)
			(xy 98.733356 -285.661354) (xy 98.733864 -285.635467) (xy 98.741963 -285.584329) (xy 98.757962 -285.535089)
			(xy 98.781468 -285.488957) (xy 98.8119 -285.44707) (xy 98.84851 -285.41046) (xy 98.890397 -285.380028)
			(xy 98.936529 -285.356522) (xy 98.985769 -285.340523) (xy 99.036907 -285.332424) (xy 99.088681 -285.332424)
			(xy 99.139819 -285.340523) (xy 99.189059 -285.356522) (xy 99.235191 -285.380028) (xy 99.277078 -285.41046)
			(xy 99.313688 -285.44707) (xy 99.34412 -285.488957) (xy 99.367626 -285.535089) (xy 99.383625 -285.584329)
			(xy 99.391724 -285.635467) (xy 99.392232 -285.661354) (xy 99.673156 -285.661354) (xy 99.673632 -285.63602)
			(xy 99.68139 -285.585949) (xy 99.696717 -285.537654) (xy 99.71925 -285.492273) (xy 99.748461 -285.450872)
			(xy 99.783661 -285.414427) (xy 99.824022 -285.383796) (xy 99.868594 -285.3597) (xy 99.916327 -285.342705)
			(xy 99.941126 -285.337504) (xy 99.963986 -285.333186) (xy 100.169218 -284.97784) (xy 100.161598 -284.955996)
			(xy 100.152974 -284.929714) (xy 100.143659 -284.875193) (xy 100.143056 -284.847538) (xy 100.143564 -284.821631)
			(xy 100.15167 -284.770454) (xy 100.167682 -284.721175) (xy 100.191205 -284.675008) (xy 100.221661 -284.633089)
			(xy 100.258299 -284.596451) (xy 100.300218 -284.565995) (xy 100.346385 -284.542472) (xy 100.395664 -284.52646)
			(xy 100.446841 -284.518354) (xy 100.498655 -284.518354) (xy 100.549832 -284.52646) (xy 100.599111 -284.542472)
			(xy 100.645278 -284.565995) (xy 100.687197 -284.596451) (xy 100.723835 -284.633089) (xy 100.754291 -284.675008)
			(xy 100.777814 -284.721175) (xy 100.793826 -284.770454) (xy 100.801932 -284.821631) (xy 100.80244 -284.847538)
			(xy 100.802048 -284.872916) (xy 100.794273 -284.923072) (xy 100.778896 -284.971442) (xy 100.756281 -285.016882)
			(xy 100.726965 -285.058314) (xy 100.69164 -285.09476) (xy 100.651143 -285.125356) (xy 100.606433 -285.149379)
			(xy 100.558566 -285.166259) (xy 100.533708 -285.171388) (xy 100.510848 -285.175706) (xy 100.30587 -285.530544)
			(xy 100.313744 -285.552642) (xy 100.322316 -285.578997) (xy 100.331507 -285.633645) (xy 100.332032 -285.661354)
			(xy 100.612956 -285.661354) (xy 100.613464 -285.635467) (xy 100.621563 -285.584329) (xy 100.637562 -285.535089)
			(xy 100.661068 -285.488957) (xy 100.6915 -285.44707) (xy 100.72811 -285.41046) (xy 100.769997 -285.380028)
			(xy 100.816129 -285.356522) (xy 100.865369 -285.340523) (xy 100.916507 -285.332424) (xy 100.968281 -285.332424)
			(xy 101.019419 -285.340523) (xy 101.068659 -285.356522) (xy 101.114791 -285.380028) (xy 101.156678 -285.41046)
			(xy 101.193288 -285.44707) (xy 101.22372 -285.488957) (xy 101.247226 -285.535089) (xy 101.263225 -285.584329)
			(xy 101.271324 -285.635467) (xy 101.271832 -285.661354) (xy 101.552756 -285.661354) (xy 101.553232 -285.63602)
			(xy 101.56099 -285.585949) (xy 101.576317 -285.537654) (xy 101.59885 -285.492273) (xy 101.628061 -285.450872)
			(xy 101.663261 -285.414427) (xy 101.703622 -285.383796) (xy 101.748194 -285.3597) (xy 101.795927 -285.342705)
			(xy 101.820726 -285.337504) (xy 101.843586 -285.333186) (xy 102.048818 -284.97784) (xy 102.041198 -284.955996)
			(xy 102.032574 -284.929714) (xy 102.023259 -284.875193) (xy 102.022656 -284.847538) (xy 102.023164 -284.821631)
			(xy 102.03127 -284.770454) (xy 102.047282 -284.721175) (xy 102.070805 -284.675008) (xy 102.101261 -284.633089)
			(xy 102.137899 -284.596451) (xy 102.179818 -284.565995) (xy 102.225985 -284.542472) (xy 102.275264 -284.52646)
			(xy 102.326441 -284.518354) (xy 102.378255 -284.518354) (xy 102.429432 -284.52646) (xy 102.478711 -284.542472)
			(xy 102.524878 -284.565995) (xy 102.566797 -284.596451) (xy 102.603435 -284.633089) (xy 102.633891 -284.675008)
			(xy 102.657414 -284.721175) (xy 102.673426 -284.770454) (xy 102.681532 -284.821631) (xy 102.68204 -284.847538)
			(xy 102.681648 -284.872916) (xy 102.673873 -284.923072) (xy 102.658496 -284.971442) (xy 102.635881 -285.016882)
			(xy 102.606565 -285.058314) (xy 102.57124 -285.09476) (xy 102.530743 -285.125356) (xy 102.486033 -285.149379)
			(xy 102.438166 -285.166259) (xy 102.413308 -285.171388) (xy 102.390448 -285.175706) (xy 102.18547 -285.530544)
			(xy 102.193344 -285.552642) (xy 102.201916 -285.578997) (xy 102.211107 -285.633645) (xy 102.211632 -285.661354)
			(xy 102.492556 -285.661354) (xy 102.493064 -285.635467) (xy 102.501163 -285.584329) (xy 102.517162 -285.535089)
			(xy 102.540668 -285.488957) (xy 102.5711 -285.44707) (xy 102.60771 -285.41046) (xy 102.649597 -285.380028)
			(xy 102.695729 -285.356522) (xy 102.744969 -285.340523) (xy 102.796107 -285.332424) (xy 102.847881 -285.332424)
			(xy 102.899019 -285.340523) (xy 102.948259 -285.356522) (xy 102.994391 -285.380028) (xy 103.036278 -285.41046)
			(xy 103.072888 -285.44707) (xy 103.10332 -285.488957) (xy 103.126826 -285.535089) (xy 103.142825 -285.584329)
			(xy 103.150924 -285.635467) (xy 103.151432 -285.661354) (xy 103.432356 -285.661354) (xy 103.432832 -285.63602)
			(xy 103.44059 -285.585949) (xy 103.455917 -285.537654) (xy 103.47845 -285.492273) (xy 103.507661 -285.450872)
			(xy 103.542861 -285.414427) (xy 103.583222 -285.383796) (xy 103.627794 -285.3597) (xy 103.675527 -285.342705)
			(xy 103.700326 -285.337504) (xy 103.723186 -285.333186) (xy 103.928418 -284.97784) (xy 103.920798 -284.955996)
			(xy 103.912174 -284.929714) (xy 103.902859 -284.875193) (xy 103.902256 -284.847538) (xy 103.902764 -284.821631)
			(xy 103.91087 -284.770454) (xy 103.926882 -284.721175) (xy 103.950405 -284.675008) (xy 103.980861 -284.633089)
			(xy 104.017499 -284.596451) (xy 104.059418 -284.565995) (xy 104.105585 -284.542472) (xy 104.154864 -284.52646)
			(xy 104.206041 -284.518354) (xy 104.257855 -284.518354) (xy 104.309032 -284.52646) (xy 104.358311 -284.542472)
			(xy 104.404478 -284.565995) (xy 104.446397 -284.596451) (xy 104.483035 -284.633089) (xy 104.513491 -284.675008)
			(xy 104.537014 -284.721175) (xy 104.553026 -284.770454) (xy 104.561132 -284.821631) (xy 104.56164 -284.847538)
			(xy 118.939056 -284.847538) (xy 118.939564 -284.821631) (xy 118.94767 -284.770454) (xy 118.963682 -284.721175)
			(xy 118.987205 -284.675008) (xy 119.017661 -284.633089) (xy 119.054299 -284.596451) (xy 119.096218 -284.565995)
			(xy 119.142385 -284.542472) (xy 119.191664 -284.52646) (xy 119.242841 -284.518354) (xy 119.294655 -284.518354)
			(xy 119.345832 -284.52646) (xy 119.395111 -284.542472) (xy 119.441278 -284.565995) (xy 119.483197 -284.596451)
			(xy 119.519835 -284.633089) (xy 119.550291 -284.675008) (xy 119.573814 -284.721175) (xy 119.589826 -284.770454)
			(xy 119.597932 -284.821631) (xy 119.59844 -284.847538) (xy 120.818656 -284.847538) (xy 120.819164 -284.821631)
			(xy 120.82727 -284.770454) (xy 120.843282 -284.721175) (xy 120.866805 -284.675008) (xy 120.897261 -284.633089)
			(xy 120.933899 -284.596451) (xy 120.975818 -284.565995) (xy 121.021985 -284.542472) (xy 121.071264 -284.52646)
			(xy 121.122441 -284.518354) (xy 121.174255 -284.518354) (xy 121.225432 -284.52646) (xy 121.274711 -284.542472)
			(xy 121.320878 -284.565995) (xy 121.362797 -284.596451) (xy 121.399435 -284.633089) (xy 121.429891 -284.675008)
			(xy 121.453414 -284.721175) (xy 121.469426 -284.770454) (xy 121.477532 -284.821631) (xy 121.47804 -284.847538)
			(xy 122.698256 -284.847538) (xy 122.698764 -284.821631) (xy 122.70687 -284.770454) (xy 122.722882 -284.721175)
			(xy 122.746405 -284.675008) (xy 122.776861 -284.633089) (xy 122.813499 -284.596451) (xy 122.855418 -284.565995)
			(xy 122.901585 -284.542472) (xy 122.950864 -284.52646) (xy 123.002041 -284.518354) (xy 123.053855 -284.518354)
			(xy 123.105032 -284.52646) (xy 123.154311 -284.542472) (xy 123.200478 -284.565995) (xy 123.242397 -284.596451)
			(xy 123.279035 -284.633089) (xy 123.309491 -284.675008) (xy 123.333014 -284.721175) (xy 123.349026 -284.770454)
			(xy 123.357132 -284.821631) (xy 123.35764 -284.847538) (xy 124.577856 -284.847538) (xy 124.578364 -284.821631)
			(xy 124.58647 -284.770454) (xy 124.602482 -284.721175) (xy 124.626005 -284.675008) (xy 124.656461 -284.633089)
			(xy 124.693099 -284.596451) (xy 124.735018 -284.565995) (xy 124.781185 -284.542472) (xy 124.830464 -284.52646)
			(xy 124.881641 -284.518354) (xy 124.933455 -284.518354) (xy 124.984632 -284.52646) (xy 125.033911 -284.542472)
			(xy 125.080078 -284.565995) (xy 125.121997 -284.596451) (xy 125.158635 -284.633089) (xy 125.189091 -284.675008)
			(xy 125.212614 -284.721175) (xy 125.228626 -284.770454) (xy 125.236732 -284.821631) (xy 125.23724 -284.847538)
			(xy 126.457456 -284.847538) (xy 126.457964 -284.821631) (xy 126.46607 -284.770454) (xy 126.482082 -284.721175)
			(xy 126.505605 -284.675008) (xy 126.536061 -284.633089) (xy 126.572699 -284.596451) (xy 126.614618 -284.565995)
			(xy 126.660785 -284.542472) (xy 126.710064 -284.52646) (xy 126.761241 -284.518354) (xy 126.813055 -284.518354)
			(xy 126.864232 -284.52646) (xy 126.913511 -284.542472) (xy 126.959678 -284.565995) (xy 127.001597 -284.596451)
			(xy 127.038235 -284.633089) (xy 127.068691 -284.675008) (xy 127.092214 -284.721175) (xy 127.108226 -284.770454)
			(xy 127.116332 -284.821631) (xy 127.11684 -284.847538) (xy 128.337056 -284.847538) (xy 128.337564 -284.821631)
			(xy 128.34567 -284.770454) (xy 128.361682 -284.721175) (xy 128.385205 -284.675008) (xy 128.415661 -284.633089)
			(xy 128.452299 -284.596451) (xy 128.494218 -284.565995) (xy 128.540385 -284.542472) (xy 128.589664 -284.52646)
			(xy 128.640841 -284.518354) (xy 128.692655 -284.518354) (xy 128.743832 -284.52646) (xy 128.793111 -284.542472)
			(xy 128.839278 -284.565995) (xy 128.881197 -284.596451) (xy 128.917835 -284.633089) (xy 128.948291 -284.675008)
			(xy 128.971814 -284.721175) (xy 128.987826 -284.770454) (xy 128.995932 -284.821631) (xy 128.99644 -284.847538)
			(xy 130.216656 -284.847538) (xy 130.217164 -284.821631) (xy 130.22527 -284.770454) (xy 130.241282 -284.721175)
			(xy 130.264805 -284.675008) (xy 130.295261 -284.633089) (xy 130.331899 -284.596451) (xy 130.373818 -284.565995)
			(xy 130.419985 -284.542472) (xy 130.469264 -284.52646) (xy 130.520441 -284.518354) (xy 130.572255 -284.518354)
			(xy 130.623432 -284.52646) (xy 130.672711 -284.542472) (xy 130.718878 -284.565995) (xy 130.760797 -284.596451)
			(xy 130.797435 -284.633089) (xy 130.827891 -284.675008) (xy 130.851414 -284.721175) (xy 130.867426 -284.770454)
			(xy 130.875532 -284.821631) (xy 130.87604 -284.847538) (xy 132.096256 -284.847538) (xy 132.096764 -284.821631)
			(xy 132.10487 -284.770454) (xy 132.120882 -284.721175) (xy 132.144405 -284.675008) (xy 132.174861 -284.633089)
			(xy 132.211499 -284.596451) (xy 132.253418 -284.565995) (xy 132.299585 -284.542472) (xy 132.348864 -284.52646)
			(xy 132.400041 -284.518354) (xy 132.451855 -284.518354) (xy 132.503032 -284.52646) (xy 132.552311 -284.542472)
			(xy 132.598478 -284.565995) (xy 132.640397 -284.596451) (xy 132.677035 -284.633089) (xy 132.707491 -284.675008)
			(xy 132.731014 -284.721175) (xy 132.747026 -284.770454) (xy 132.755132 -284.821631) (xy 132.75564 -284.847538)
			(xy 132.755075 -284.873383) (xy 333.046907 -284.873383) (xy 333.046907 -284.821618) (xy 333.055005 -284.77049)
			(xy 333.071 -284.721258) (xy 333.094499 -284.675134) (xy 333.124924 -284.633254) (xy 333.161525 -284.596648)
			(xy 333.203402 -284.566219) (xy 333.249523 -284.542714) (xy 333.298753 -284.526713) (xy 333.34988 -284.51861)
			(xy 333.375762 -284.5181) (xy 333.401254 -284.518612) (xy 333.451631 -284.526467) (xy 333.500193 -284.541996)
			(xy 333.54578 -284.564827) (xy 333.587302 -284.594415) (xy 333.623765 -284.63005) (xy 333.639414 -284.65018)
			(xy 334.05191 -284.65018) (xy 334.067576 -284.630063) (xy 334.104034 -284.594421) (xy 334.145551 -284.564826)
			(xy 334.191135 -284.541986) (xy 334.239694 -284.526447) (xy 334.290069 -284.518581) (xy 334.315562 -284.5181)
			(xy 334.341456 -284.518502) (xy 334.392608 -284.526599) (xy 334.441864 -284.542598) (xy 334.48801 -284.566106)
			(xy 334.52991 -284.596543) (xy 334.566532 -284.633161) (xy 334.596975 -284.675058) (xy 334.620488 -284.721201)
			(xy 334.636492 -284.770455) (xy 334.644595 -284.821606) (xy 334.644595 -284.873394) (xy 334.636492 -284.924545)
			(xy 334.620488 -284.973799) (xy 334.596975 -285.019942) (xy 334.566532 -285.061839) (xy 334.52991 -285.098457)
			(xy 334.48801 -285.128894) (xy 334.441864 -285.152402) (xy 334.392608 -285.168401) (xy 334.341456 -285.176498)
			(xy 334.315562 -285.176976) (xy 334.290067 -285.176529) (xy 334.239687 -285.168661) (xy 334.191123 -285.15312)
			(xy 334.145536 -285.130277) (xy 334.104016 -285.100678) (xy 334.067557 -285.065031) (xy 334.05191 -285.044896)
			(xy 333.639414 -285.044896) (xy 333.623786 -285.065045) (xy 333.587321 -285.100686) (xy 333.545796 -285.130277)
			(xy 333.500205 -285.153112) (xy 333.451638 -285.168644) (xy 333.401257 -285.176501) (xy 333.375762 -285.176976)
			(xy 333.34988 -285.17639) (xy 333.298753 -285.168287) (xy 333.249523 -285.152286) (xy 333.203402 -285.128781)
			(xy 333.161525 -285.098352) (xy 333.124924 -285.061746) (xy 333.094499 -285.019866) (xy 333.071 -284.973742)
			(xy 333.055005 -284.92451) (xy 333.046907 -284.873383) (xy 132.755075 -284.873383) (xy 132.755034 -284.875255)
			(xy 132.745719 -284.929901) (xy 132.737098 -284.95625) (xy 132.729224 -284.978348) (xy 132.934202 -285.333186)
			(xy 132.957062 -285.337504) (xy 132.981868 -285.342683) (xy 133.02961 -285.359669) (xy 133.07419 -285.383762)
			(xy 133.114558 -285.414393) (xy 133.149763 -285.450841) (xy 133.178975 -285.492247) (xy 133.201506 -285.537636)
			(xy 133.216825 -285.585939) (xy 133.224572 -285.636017) (xy 133.225032 -285.661354) (xy 133.224524 -285.687241)
			(xy 133.216425 -285.738379) (xy 133.200426 -285.787619) (xy 133.17692 -285.833751) (xy 133.146488 -285.875638)
			(xy 133.109878 -285.912248) (xy 133.067991 -285.94268) (xy 133.021859 -285.966186) (xy 132.972619 -285.982185)
			(xy 132.921481 -285.990284) (xy 132.869707 -285.990284) (xy 132.818569 -285.982185) (xy 132.769329 -285.966186)
			(xy 132.723197 -285.94268) (xy 132.68131 -285.912248) (xy 132.6447 -285.875638) (xy 132.614268 -285.833751)
			(xy 132.590762 -285.787619) (xy 132.574763 -285.738379) (xy 132.566664 -285.687241) (xy 132.566156 -285.661354)
			(xy 132.566701 -285.633647) (xy 132.575886 -285.579) (xy 132.584444 -285.552642) (xy 132.592318 -285.530544)
			(xy 132.38734 -285.175706) (xy 132.36448 -285.171388) (xy 132.33966 -285.166215) (xy 132.29188 -285.149263)
			(xy 132.247259 -285.125194) (xy 132.206851 -285.094575) (xy 132.171609 -285.058129) (xy 132.142365 -285.016715)
			(xy 132.119809 -284.971312) (xy 132.104472 -284.922989) (xy 132.096717 -284.872887) (xy 132.096256 -284.847538)
			(xy 130.87604 -284.847538) (xy 130.875434 -284.875255) (xy 130.866119 -284.929901) (xy 130.857498 -284.95625)
			(xy 130.849624 -284.978348) (xy 131.054602 -285.333186) (xy 131.077462 -285.337504) (xy 131.102268 -285.342683)
			(xy 131.15001 -285.359669) (xy 131.19459 -285.383762) (xy 131.234958 -285.414393) (xy 131.270163 -285.450841)
			(xy 131.299375 -285.492247) (xy 131.321906 -285.537636) (xy 131.337225 -285.585939) (xy 131.344972 -285.636017)
			(xy 131.345432 -285.661354) (xy 131.344924 -285.687241) (xy 131.336825 -285.738379) (xy 131.320826 -285.787619)
			(xy 131.29732 -285.833751) (xy 131.266888 -285.875638) (xy 131.230278 -285.912248) (xy 131.188391 -285.94268)
			(xy 131.142259 -285.966186) (xy 131.093019 -285.982185) (xy 131.041881 -285.990284) (xy 130.990107 -285.990284)
			(xy 130.938969 -285.982185) (xy 130.889729 -285.966186) (xy 130.843597 -285.94268) (xy 130.80171 -285.912248)
			(xy 130.7651 -285.875638) (xy 130.734668 -285.833751) (xy 130.711162 -285.787619) (xy 130.695163 -285.738379)
			(xy 130.687064 -285.687241) (xy 130.686556 -285.661354) (xy 130.687101 -285.633647) (xy 130.696286 -285.579)
			(xy 130.704844 -285.552642) (xy 130.712718 -285.530544) (xy 130.50774 -285.175706) (xy 130.48488 -285.171388)
			(xy 130.46006 -285.166215) (xy 130.41228 -285.149263) (xy 130.367659 -285.125194) (xy 130.327251 -285.094575)
			(xy 130.292009 -285.058129) (xy 130.262765 -285.016715) (xy 130.240209 -284.971312) (xy 130.224872 -284.922989)
			(xy 130.217117 -284.872887) (xy 130.216656 -284.847538) (xy 128.99644 -284.847538) (xy 128.995834 -284.875255)
			(xy 128.986519 -284.929901) (xy 128.977898 -284.95625) (xy 128.970024 -284.978348) (xy 129.175002 -285.333186)
			(xy 129.197862 -285.337504) (xy 129.222668 -285.342683) (xy 129.27041 -285.359669) (xy 129.31499 -285.383762)
			(xy 129.355358 -285.414393) (xy 129.390563 -285.450841) (xy 129.419775 -285.492247) (xy 129.442306 -285.537636)
			(xy 129.457625 -285.585939) (xy 129.465372 -285.636017) (xy 129.465832 -285.661354) (xy 129.465324 -285.687241)
			(xy 129.457225 -285.738379) (xy 129.441226 -285.787619) (xy 129.41772 -285.833751) (xy 129.387288 -285.875638)
			(xy 129.350678 -285.912248) (xy 129.308791 -285.94268) (xy 129.262659 -285.966186) (xy 129.213419 -285.982185)
			(xy 129.162281 -285.990284) (xy 129.110507 -285.990284) (xy 129.059369 -285.982185) (xy 129.010129 -285.966186)
			(xy 128.963997 -285.94268) (xy 128.92211 -285.912248) (xy 128.8855 -285.875638) (xy 128.855068 -285.833751)
			(xy 128.831562 -285.787619) (xy 128.815563 -285.738379) (xy 128.807464 -285.687241) (xy 128.806956 -285.661354)
			(xy 128.807501 -285.633647) (xy 128.816686 -285.579) (xy 128.825244 -285.552642) (xy 128.833118 -285.530544)
			(xy 128.62814 -285.175706) (xy 128.60528 -285.171388) (xy 128.58046 -285.166215) (xy 128.53268 -285.149263)
			(xy 128.488059 -285.125194) (xy 128.447651 -285.094575) (xy 128.412409 -285.058129) (xy 128.383165 -285.016715)
			(xy 128.360609 -284.971312) (xy 128.345272 -284.922989) (xy 128.337517 -284.872887) (xy 128.337056 -284.847538)
			(xy 127.11684 -284.847538) (xy 127.116234 -284.875255) (xy 127.106919 -284.929901) (xy 127.098298 -284.95625)
			(xy 127.090424 -284.978348) (xy 127.295402 -285.333186) (xy 127.318262 -285.337504) (xy 127.343068 -285.342683)
			(xy 127.39081 -285.359669) (xy 127.43539 -285.383762) (xy 127.475758 -285.414393) (xy 127.510963 -285.450841)
			(xy 127.540175 -285.492247) (xy 127.562706 -285.537636) (xy 127.578025 -285.585939) (xy 127.585772 -285.636017)
			(xy 127.586232 -285.661354) (xy 127.585724 -285.687241) (xy 127.577625 -285.738379) (xy 127.561626 -285.787619)
			(xy 127.53812 -285.833751) (xy 127.507688 -285.875638) (xy 127.471078 -285.912248) (xy 127.429191 -285.94268)
			(xy 127.383059 -285.966186) (xy 127.333819 -285.982185) (xy 127.282681 -285.990284) (xy 127.230907 -285.990284)
			(xy 127.179769 -285.982185) (xy 127.130529 -285.966186) (xy 127.084397 -285.94268) (xy 127.04251 -285.912248)
			(xy 127.0059 -285.875638) (xy 126.975468 -285.833751) (xy 126.951962 -285.787619) (xy 126.935963 -285.738379)
			(xy 126.927864 -285.687241) (xy 126.927356 -285.661354) (xy 126.927901 -285.633647) (xy 126.937086 -285.579)
			(xy 126.945644 -285.552642) (xy 126.953518 -285.530544) (xy 126.74854 -285.175706) (xy 126.72568 -285.171388)
			(xy 126.70086 -285.166215) (xy 126.65308 -285.149263) (xy 126.608459 -285.125194) (xy 126.568051 -285.094575)
			(xy 126.532809 -285.058129) (xy 126.503565 -285.016715) (xy 126.481009 -284.971312) (xy 126.465672 -284.922989)
			(xy 126.457917 -284.872887) (xy 126.457456 -284.847538) (xy 125.23724 -284.847538) (xy 125.236634 -284.875255)
			(xy 125.227319 -284.929901) (xy 125.218698 -284.95625) (xy 125.210824 -284.978348) (xy 125.415802 -285.333186)
			(xy 125.438662 -285.337504) (xy 125.463468 -285.342683) (xy 125.51121 -285.359669) (xy 125.55579 -285.383762)
			(xy 125.596158 -285.414393) (xy 125.631363 -285.450841) (xy 125.660575 -285.492247) (xy 125.683106 -285.537636)
			(xy 125.698425 -285.585939) (xy 125.706172 -285.636017) (xy 125.706632 -285.661354) (xy 125.706124 -285.687241)
			(xy 125.698025 -285.738379) (xy 125.682026 -285.787619) (xy 125.65852 -285.833751) (xy 125.628088 -285.875638)
			(xy 125.591478 -285.912248) (xy 125.549591 -285.94268) (xy 125.503459 -285.966186) (xy 125.454219 -285.982185)
			(xy 125.403081 -285.990284) (xy 125.351307 -285.990284) (xy 125.300169 -285.982185) (xy 125.250929 -285.966186)
			(xy 125.204797 -285.94268) (xy 125.16291 -285.912248) (xy 125.1263 -285.875638) (xy 125.095868 -285.833751)
			(xy 125.072362 -285.787619) (xy 125.056363 -285.738379) (xy 125.048264 -285.687241) (xy 125.047756 -285.661354)
			(xy 125.048301 -285.633647) (xy 125.057486 -285.579) (xy 125.066044 -285.552642) (xy 125.073918 -285.530544)
			(xy 124.86894 -285.175706) (xy 124.84608 -285.171388) (xy 124.82126 -285.166215) (xy 124.77348 -285.149263)
			(xy 124.728859 -285.125194) (xy 124.688451 -285.094575) (xy 124.653209 -285.058129) (xy 124.623965 -285.016715)
			(xy 124.601409 -284.971312) (xy 124.586072 -284.922989) (xy 124.578317 -284.872887) (xy 124.577856 -284.847538)
			(xy 123.35764 -284.847538) (xy 123.357034 -284.875255) (xy 123.347719 -284.929901) (xy 123.339098 -284.95625)
			(xy 123.331224 -284.978348) (xy 123.536202 -285.333186) (xy 123.559062 -285.337504) (xy 123.583868 -285.342683)
			(xy 123.63161 -285.359669) (xy 123.67619 -285.383762) (xy 123.716558 -285.414393) (xy 123.751763 -285.450841)
			(xy 123.780975 -285.492247) (xy 123.803506 -285.537636) (xy 123.818825 -285.585939) (xy 123.826572 -285.636017)
			(xy 123.827032 -285.661354) (xy 123.826524 -285.687241) (xy 123.818425 -285.738379) (xy 123.802426 -285.787619)
			(xy 123.77892 -285.833751) (xy 123.748488 -285.875638) (xy 123.711878 -285.912248) (xy 123.669991 -285.94268)
			(xy 123.623859 -285.966186) (xy 123.574619 -285.982185) (xy 123.523481 -285.990284) (xy 123.471707 -285.990284)
			(xy 123.420569 -285.982185) (xy 123.371329 -285.966186) (xy 123.325197 -285.94268) (xy 123.28331 -285.912248)
			(xy 123.2467 -285.875638) (xy 123.216268 -285.833751) (xy 123.192762 -285.787619) (xy 123.176763 -285.738379)
			(xy 123.168664 -285.687241) (xy 123.168156 -285.661354) (xy 123.168701 -285.633647) (xy 123.177886 -285.579)
			(xy 123.186444 -285.552642) (xy 123.194318 -285.530544) (xy 122.98934 -285.175706) (xy 122.96648 -285.171388)
			(xy 122.94166 -285.166215) (xy 122.89388 -285.149263) (xy 122.849259 -285.125194) (xy 122.808851 -285.094575)
			(xy 122.773609 -285.058129) (xy 122.744365 -285.016715) (xy 122.721809 -284.971312) (xy 122.706472 -284.922989)
			(xy 122.698717 -284.872887) (xy 122.698256 -284.847538) (xy 121.47804 -284.847538) (xy 121.477434 -284.875255)
			(xy 121.468119 -284.929901) (xy 121.459498 -284.95625) (xy 121.451624 -284.978348) (xy 121.656602 -285.333186)
			(xy 121.679462 -285.337504) (xy 121.704268 -285.342683) (xy 121.75201 -285.359669) (xy 121.79659 -285.383762)
			(xy 121.836958 -285.414393) (xy 121.872163 -285.450841) (xy 121.901375 -285.492247) (xy 121.923906 -285.537636)
			(xy 121.939225 -285.585939) (xy 121.946972 -285.636017) (xy 121.947432 -285.661354) (xy 121.946924 -285.687241)
			(xy 121.938825 -285.738379) (xy 121.922826 -285.787619) (xy 121.89932 -285.833751) (xy 121.868888 -285.875638)
			(xy 121.832278 -285.912248) (xy 121.790391 -285.94268) (xy 121.744259 -285.966186) (xy 121.695019 -285.982185)
			(xy 121.643881 -285.990284) (xy 121.592107 -285.990284) (xy 121.540969 -285.982185) (xy 121.491729 -285.966186)
			(xy 121.445597 -285.94268) (xy 121.40371 -285.912248) (xy 121.3671 -285.875638) (xy 121.336668 -285.833751)
			(xy 121.313162 -285.787619) (xy 121.297163 -285.738379) (xy 121.289064 -285.687241) (xy 121.288556 -285.661354)
			(xy 121.289101 -285.633647) (xy 121.298286 -285.579) (xy 121.306844 -285.552642) (xy 121.314718 -285.530544)
			(xy 121.10974 -285.175706) (xy 121.08688 -285.171388) (xy 121.06206 -285.166215) (xy 121.01428 -285.149263)
			(xy 120.969659 -285.125194) (xy 120.929251 -285.094575) (xy 120.894009 -285.058129) (xy 120.864765 -285.016715)
			(xy 120.842209 -284.971312) (xy 120.826872 -284.922989) (xy 120.819117 -284.872887) (xy 120.818656 -284.847538)
			(xy 119.59844 -284.847538) (xy 119.597834 -284.875255) (xy 119.588519 -284.929901) (xy 119.579898 -284.95625)
			(xy 119.572024 -284.978348) (xy 119.777002 -285.333186) (xy 119.799862 -285.337504) (xy 119.824668 -285.342683)
			(xy 119.87241 -285.359669) (xy 119.91699 -285.383762) (xy 119.957358 -285.414393) (xy 119.992563 -285.450841)
			(xy 120.021775 -285.492247) (xy 120.044306 -285.537636) (xy 120.059625 -285.585939) (xy 120.067372 -285.636017)
			(xy 120.067832 -285.661354) (xy 120.067324 -285.687241) (xy 120.059225 -285.738379) (xy 120.043226 -285.787619)
			(xy 120.01972 -285.833751) (xy 119.989288 -285.875638) (xy 119.952678 -285.912248) (xy 119.910791 -285.94268)
			(xy 119.864659 -285.966186) (xy 119.815419 -285.982185) (xy 119.764281 -285.990284) (xy 119.712507 -285.990284)
			(xy 119.661369 -285.982185) (xy 119.612129 -285.966186) (xy 119.565997 -285.94268) (xy 119.52411 -285.912248)
			(xy 119.4875 -285.875638) (xy 119.457068 -285.833751) (xy 119.433562 -285.787619) (xy 119.417563 -285.738379)
			(xy 119.409464 -285.687241) (xy 119.408956 -285.661354) (xy 119.409501 -285.633647) (xy 119.418686 -285.579)
			(xy 119.427244 -285.552642) (xy 119.435118 -285.530544) (xy 119.23014 -285.175706) (xy 119.20728 -285.171388)
			(xy 119.18246 -285.166215) (xy 119.13468 -285.149263) (xy 119.090059 -285.125194) (xy 119.049651 -285.094575)
			(xy 119.014409 -285.058129) (xy 118.985165 -285.016715) (xy 118.962609 -284.971312) (xy 118.947272 -284.922989)
			(xy 118.939517 -284.872887) (xy 118.939056 -284.847538) (xy 104.56164 -284.847538) (xy 104.561248 -284.872916)
			(xy 104.553473 -284.923072) (xy 104.538096 -284.971442) (xy 104.515481 -285.016882) (xy 104.486165 -285.058314)
			(xy 104.45084 -285.09476) (xy 104.410343 -285.125356) (xy 104.365633 -285.149379) (xy 104.317766 -285.166259)
			(xy 104.292908 -285.171388) (xy 104.270048 -285.175706) (xy 104.06507 -285.530544) (xy 104.072944 -285.552642)
			(xy 104.081516 -285.578997) (xy 104.090707 -285.633645) (xy 104.091232 -285.661354) (xy 104.090724 -285.687241)
			(xy 104.082625 -285.738379) (xy 104.066626 -285.787619) (xy 104.04312 -285.833751) (xy 104.012688 -285.875638)
			(xy 103.976078 -285.912248) (xy 103.934191 -285.94268) (xy 103.888059 -285.966186) (xy 103.838819 -285.982185)
			(xy 103.787681 -285.990284) (xy 103.735907 -285.990284) (xy 103.684769 -285.982185) (xy 103.635529 -285.966186)
			(xy 103.589397 -285.94268) (xy 103.54751 -285.912248) (xy 103.5109 -285.875638) (xy 103.480468 -285.833751)
			(xy 103.456962 -285.787619) (xy 103.440963 -285.738379) (xy 103.432864 -285.687241) (xy 103.432356 -285.661354)
			(xy 103.151432 -285.661354) (xy 103.151432 -285.661862) (xy 103.150853 -285.689379) (xy 103.141659 -285.74364)
			(xy 103.133144 -285.769812) (xy 103.125524 -285.79191) (xy 103.330756 -286.147256) (xy 103.353616 -286.151574)
			(xy 103.378427 -286.156786) (xy 103.426204 -286.173734) (xy 103.470823 -286.197799) (xy 103.51123 -286.228413)
			(xy 103.546472 -286.264855) (xy 103.575717 -286.306263) (xy 103.598276 -286.351662) (xy 103.613617 -286.399979)
			(xy 103.621377 -286.450077) (xy 103.62184 -286.475424) (xy 119.878856 -286.475424) (xy 119.879354 -286.450079)
			(xy 119.887123 -286.399987) (xy 119.902468 -286.351675) (xy 119.925026 -286.306281) (xy 119.954266 -286.264873)
			(xy 119.989499 -286.228429) (xy 120.029894 -286.197807) (xy 120.0745 -286.173728) (xy 120.122266 -286.156759)
			(xy 120.14708 -286.151574) (xy 120.16994 -286.147256) (xy 120.374918 -285.792164) (xy 120.367044 -285.77032)
			(xy 120.358471 -285.743899) (xy 120.34927 -285.689126) (xy 120.348756 -285.661354) (xy 120.349264 -285.635467)
			(xy 120.357363 -285.584329) (xy 120.373362 -285.535089) (xy 120.396868 -285.488957) (xy 120.4273 -285.44707)
			(xy 120.46391 -285.41046) (xy 120.505797 -285.380028) (xy 120.551929 -285.356522) (xy 120.601169 -285.340523)
			(xy 120.652307 -285.332424) (xy 120.704081 -285.332424) (xy 120.755219 -285.340523) (xy 120.804459 -285.356522)
			(xy 120.850591 -285.380028) (xy 120.892478 -285.41046) (xy 120.929088 -285.44707) (xy 120.95952 -285.488957)
			(xy 120.983026 -285.535089) (xy 120.999025 -285.584329) (xy 121.007124 -285.635467) (xy 121.007632 -285.661354)
			(xy 121.007172 -285.686689) (xy 120.999413 -285.736761) (xy 120.984085 -285.785057) (xy 120.961549 -285.830439)
			(xy 120.932336 -285.87184) (xy 120.897134 -285.908285) (xy 120.856771 -285.938915) (xy 120.812197 -285.963011)
			(xy 120.764462 -285.980004) (xy 120.739662 -285.985204) (xy 120.716802 -285.989522) (xy 120.511824 -286.344614)
			(xy 120.519698 -286.366458) (xy 120.528349 -286.392865) (xy 120.537666 -286.447642) (xy 120.53824 -286.475424)
			(xy 121.758456 -286.475424) (xy 121.758954 -286.450079) (xy 121.766723 -286.399987) (xy 121.782068 -286.351675)
			(xy 121.804626 -286.306281) (xy 121.833866 -286.264873) (xy 121.869099 -286.228429) (xy 121.909494 -286.197807)
			(xy 121.9541 -286.173728) (xy 122.001866 -286.156759) (xy 122.02668 -286.151574) (xy 122.04954 -286.147256)
			(xy 122.254518 -285.792164) (xy 122.246644 -285.77032) (xy 122.238071 -285.743899) (xy 122.22887 -285.689126)
			(xy 122.228356 -285.661354) (xy 122.228864 -285.635467) (xy 122.236963 -285.584329) (xy 122.252962 -285.535089)
			(xy 122.276468 -285.488957) (xy 122.3069 -285.44707) (xy 122.34351 -285.41046) (xy 122.385397 -285.380028)
			(xy 122.431529 -285.356522) (xy 122.480769 -285.340523) (xy 122.531907 -285.332424) (xy 122.583681 -285.332424)
			(xy 122.634819 -285.340523) (xy 122.684059 -285.356522) (xy 122.730191 -285.380028) (xy 122.772078 -285.41046)
			(xy 122.808688 -285.44707) (xy 122.83912 -285.488957) (xy 122.862626 -285.535089) (xy 122.878625 -285.584329)
			(xy 122.886724 -285.635467) (xy 122.887232 -285.661354) (xy 122.886772 -285.686689) (xy 122.879013 -285.736761)
			(xy 122.863685 -285.785057) (xy 122.841149 -285.830439) (xy 122.811936 -285.87184) (xy 122.776734 -285.908285)
			(xy 122.736371 -285.938915) (xy 122.691797 -285.963011) (xy 122.644062 -285.980004) (xy 122.619262 -285.985204)
			(xy 122.596402 -285.989522) (xy 122.391424 -286.344614) (xy 122.399298 -286.366458) (xy 122.407949 -286.392865)
			(xy 122.417266 -286.447642) (xy 122.41784 -286.475424) (xy 123.638056 -286.475424) (xy 123.638554 -286.450079)
			(xy 123.646323 -286.399987) (xy 123.661668 -286.351675) (xy 123.684226 -286.306281) (xy 123.713466 -286.264873)
			(xy 123.748699 -286.228429) (xy 123.789094 -286.197807) (xy 123.8337 -286.173728) (xy 123.881466 -286.156759)
			(xy 123.90628 -286.151574) (xy 123.92914 -286.147256) (xy 124.134118 -285.792164) (xy 124.126244 -285.77032)
			(xy 124.117671 -285.743899) (xy 124.10847 -285.689126) (xy 124.107956 -285.661354) (xy 124.108464 -285.635467)
			(xy 124.116563 -285.584329) (xy 124.132562 -285.535089) (xy 124.156068 -285.488957) (xy 124.1865 -285.44707)
			(xy 124.22311 -285.41046) (xy 124.264997 -285.380028) (xy 124.311129 -285.356522) (xy 124.360369 -285.340523)
			(xy 124.411507 -285.332424) (xy 124.463281 -285.332424) (xy 124.514419 -285.340523) (xy 124.563659 -285.356522)
			(xy 124.609791 -285.380028) (xy 124.651678 -285.41046) (xy 124.688288 -285.44707) (xy 124.71872 -285.488957)
			(xy 124.742226 -285.535089) (xy 124.758225 -285.584329) (xy 124.766324 -285.635467) (xy 124.766832 -285.661354)
			(xy 124.766372 -285.686689) (xy 124.758613 -285.736761) (xy 124.743285 -285.785057) (xy 124.720749 -285.830439)
			(xy 124.691536 -285.87184) (xy 124.656334 -285.908285) (xy 124.615971 -285.938915) (xy 124.571397 -285.963011)
			(xy 124.523662 -285.980004) (xy 124.498862 -285.985204) (xy 124.476002 -285.989522) (xy 124.271024 -286.344614)
			(xy 124.278898 -286.366458) (xy 124.287549 -286.392865) (xy 124.296866 -286.447642) (xy 124.29744 -286.475424)
			(xy 125.517656 -286.475424) (xy 125.518154 -286.450079) (xy 125.525923 -286.399987) (xy 125.541268 -286.351675)
			(xy 125.563826 -286.306281) (xy 125.593066 -286.264873) (xy 125.628299 -286.228429) (xy 125.668694 -286.197807)
			(xy 125.7133 -286.173728) (xy 125.761066 -286.156759) (xy 125.78588 -286.151574) (xy 125.80874 -286.147256)
			(xy 126.013718 -285.792164) (xy 126.005844 -285.77032) (xy 125.997271 -285.743899) (xy 125.98807 -285.689126)
			(xy 125.987556 -285.661354) (xy 125.988064 -285.635467) (xy 125.996163 -285.584329) (xy 126.012162 -285.535089)
			(xy 126.035668 -285.488957) (xy 126.0661 -285.44707) (xy 126.10271 -285.41046) (xy 126.144597 -285.380028)
			(xy 126.190729 -285.356522) (xy 126.239969 -285.340523) (xy 126.291107 -285.332424) (xy 126.342881 -285.332424)
			(xy 126.394019 -285.340523) (xy 126.443259 -285.356522) (xy 126.489391 -285.380028) (xy 126.531278 -285.41046)
			(xy 126.567888 -285.44707) (xy 126.59832 -285.488957) (xy 126.621826 -285.535089) (xy 126.637825 -285.584329)
			(xy 126.645924 -285.635467) (xy 126.646432 -285.661354) (xy 126.645972 -285.686689) (xy 126.638213 -285.736761)
			(xy 126.622885 -285.785057) (xy 126.600349 -285.830439) (xy 126.571136 -285.87184) (xy 126.535934 -285.908285)
			(xy 126.495571 -285.938915) (xy 126.450997 -285.963011) (xy 126.403262 -285.980004) (xy 126.378462 -285.985204)
			(xy 126.355602 -285.989522) (xy 126.150624 -286.344614) (xy 126.158498 -286.366458) (xy 126.167149 -286.392865)
			(xy 126.176466 -286.447642) (xy 126.17704 -286.475424) (xy 127.397256 -286.475424) (xy 127.397754 -286.450079)
			(xy 127.405523 -286.399987) (xy 127.420868 -286.351675) (xy 127.443426 -286.306281) (xy 127.472666 -286.264873)
			(xy 127.507899 -286.228429) (xy 127.548294 -286.197807) (xy 127.5929 -286.173728) (xy 127.640666 -286.156759)
			(xy 127.66548 -286.151574) (xy 127.68834 -286.147256) (xy 127.893318 -285.792164) (xy 127.885444 -285.77032)
			(xy 127.876871 -285.743899) (xy 127.86767 -285.689126) (xy 127.867156 -285.661354) (xy 127.867664 -285.635467)
			(xy 127.875763 -285.584329) (xy 127.891762 -285.535089) (xy 127.915268 -285.488957) (xy 127.9457 -285.44707)
			(xy 127.98231 -285.41046) (xy 128.024197 -285.380028) (xy 128.070329 -285.356522) (xy 128.119569 -285.340523)
			(xy 128.170707 -285.332424) (xy 128.222481 -285.332424) (xy 128.273619 -285.340523) (xy 128.322859 -285.356522)
			(xy 128.368991 -285.380028) (xy 128.410878 -285.41046) (xy 128.447488 -285.44707) (xy 128.47792 -285.488957)
			(xy 128.501426 -285.535089) (xy 128.517425 -285.584329) (xy 128.525524 -285.635467) (xy 128.526032 -285.661354)
			(xy 128.525572 -285.686689) (xy 128.517813 -285.736761) (xy 128.502485 -285.785057) (xy 128.479949 -285.830439)
			(xy 128.450736 -285.87184) (xy 128.415534 -285.908285) (xy 128.375171 -285.938915) (xy 128.330597 -285.963011)
			(xy 128.282862 -285.980004) (xy 128.258062 -285.985204) (xy 128.235202 -285.989522) (xy 128.030224 -286.344614)
			(xy 128.038098 -286.366458) (xy 128.046749 -286.392865) (xy 128.056066 -286.447642) (xy 128.05664 -286.475424)
			(xy 129.276856 -286.475424) (xy 129.277354 -286.450079) (xy 129.285123 -286.399987) (xy 129.300468 -286.351675)
			(xy 129.323026 -286.306281) (xy 129.352266 -286.264873) (xy 129.387499 -286.228429) (xy 129.427894 -286.197807)
			(xy 129.4725 -286.173728) (xy 129.520266 -286.156759) (xy 129.54508 -286.151574) (xy 129.56794 -286.147256)
			(xy 129.772918 -285.792164) (xy 129.765044 -285.77032) (xy 129.756471 -285.743899) (xy 129.74727 -285.689126)
			(xy 129.746756 -285.661354) (xy 129.747264 -285.635467) (xy 129.755363 -285.584329) (xy 129.771362 -285.535089)
			(xy 129.794868 -285.488957) (xy 129.8253 -285.44707) (xy 129.86191 -285.41046) (xy 129.903797 -285.380028)
			(xy 129.949929 -285.356522) (xy 129.999169 -285.340523) (xy 130.050307 -285.332424) (xy 130.102081 -285.332424)
			(xy 130.153219 -285.340523) (xy 130.202459 -285.356522) (xy 130.248591 -285.380028) (xy 130.290478 -285.41046)
			(xy 130.327088 -285.44707) (xy 130.35752 -285.488957) (xy 130.381026 -285.535089) (xy 130.397025 -285.584329)
			(xy 130.405124 -285.635467) (xy 130.405632 -285.661354) (xy 130.405172 -285.686689) (xy 130.397413 -285.736761)
			(xy 130.382085 -285.785057) (xy 130.359549 -285.830439) (xy 130.330336 -285.87184) (xy 130.295134 -285.908285)
			(xy 130.254771 -285.938915) (xy 130.210197 -285.963011) (xy 130.162462 -285.980004) (xy 130.137662 -285.985204)
			(xy 130.114802 -285.989522) (xy 129.909824 -286.344614) (xy 129.917698 -286.366458) (xy 129.926349 -286.392865)
			(xy 129.935666 -286.447642) (xy 129.93624 -286.475424) (xy 131.156456 -286.475424) (xy 131.156954 -286.450079)
			(xy 131.164723 -286.399987) (xy 131.180068 -286.351675) (xy 131.202626 -286.306281) (xy 131.231866 -286.264873)
			(xy 131.267099 -286.228429) (xy 131.307494 -286.197807) (xy 131.3521 -286.173728) (xy 131.399866 -286.156759)
			(xy 131.42468 -286.151574) (xy 131.44754 -286.147256) (xy 131.652518 -285.792164) (xy 131.644644 -285.77032)
			(xy 131.636071 -285.743899) (xy 131.62687 -285.689126) (xy 131.626356 -285.661354) (xy 131.626864 -285.635467)
			(xy 131.634963 -285.584329) (xy 131.650962 -285.535089) (xy 131.674468 -285.488957) (xy 131.7049 -285.44707)
			(xy 131.74151 -285.41046) (xy 131.783397 -285.380028) (xy 131.829529 -285.356522) (xy 131.878769 -285.340523)
			(xy 131.929907 -285.332424) (xy 131.981681 -285.332424) (xy 132.032819 -285.340523) (xy 132.082059 -285.356522)
			(xy 132.128191 -285.380028) (xy 132.170078 -285.41046) (xy 132.206688 -285.44707) (xy 132.23712 -285.488957)
			(xy 132.260626 -285.535089) (xy 132.276625 -285.584329) (xy 132.284724 -285.635467) (xy 132.285232 -285.661354)
			(xy 132.284772 -285.686689) (xy 132.277013 -285.736761) (xy 132.261685 -285.785057) (xy 132.239149 -285.830439)
			(xy 132.209936 -285.87184) (xy 132.174734 -285.908285) (xy 132.134371 -285.938915) (xy 132.089797 -285.963011)
			(xy 132.042062 -285.980004) (xy 132.017262 -285.985204) (xy 131.994402 -285.989522) (xy 131.789424 -286.344614)
			(xy 131.797298 -286.366458) (xy 131.805949 -286.392865) (xy 131.815266 -286.447642) (xy 131.81584 -286.475424)
			(xy 133.036056 -286.475424) (xy 133.036554 -286.450079) (xy 133.044323 -286.399987) (xy 133.059668 -286.351675)
			(xy 133.082226 -286.306281) (xy 133.111466 -286.264873) (xy 133.146699 -286.228429) (xy 133.187094 -286.197807)
			(xy 133.2317 -286.173728) (xy 133.279466 -286.156759) (xy 133.30428 -286.151574) (xy 133.32714 -286.147256)
			(xy 133.532118 -285.792164) (xy 133.524244 -285.77032) (xy 133.515671 -285.743899) (xy 133.50647 -285.689126)
			(xy 133.505956 -285.661354) (xy 133.506464 -285.635467) (xy 133.514563 -285.584329) (xy 133.530562 -285.535089)
			(xy 133.554068 -285.488957) (xy 133.5845 -285.44707) (xy 133.62111 -285.41046) (xy 133.662997 -285.380028)
			(xy 133.709129 -285.356522) (xy 133.758369 -285.340523) (xy 133.809507 -285.332424) (xy 133.861281 -285.332424)
			(xy 133.912419 -285.340523) (xy 133.961659 -285.356522) (xy 134.007791 -285.380028) (xy 134.049678 -285.41046)
			(xy 134.086288 -285.44707) (xy 134.11672 -285.488957) (xy 134.140226 -285.535089) (xy 134.156225 -285.584329)
			(xy 134.164324 -285.635467) (xy 134.164832 -285.661354) (xy 335.395824 -285.661354) (xy 335.396245 -285.636017)
			(xy 335.404005 -285.585941) (xy 335.419335 -285.537642) (xy 335.441875 -285.492257) (xy 335.471092 -285.450854)
			(xy 335.5063 -285.41441) (xy 335.54667 -285.383781) (xy 335.59125 -285.359689) (xy 335.638992 -285.342701)
			(xy 335.663794 -285.337504) (xy 335.686654 -285.333186) (xy 335.891632 -284.978094) (xy 335.884012 -284.95625)
			(xy 335.875447 -284.929893) (xy 335.86625 -284.875247) (xy 335.865724 -284.847538) (xy 335.866232 -284.821651)
			(xy 335.874331 -284.770513) (xy 335.89033 -284.721273) (xy 335.913836 -284.675141) (xy 335.944268 -284.633254)
			(xy 335.980878 -284.596644) (xy 336.022765 -284.566212) (xy 336.068897 -284.542706) (xy 336.118137 -284.526707)
			(xy 336.169275 -284.518608) (xy 336.221049 -284.518608) (xy 336.272187 -284.526707) (xy 336.321427 -284.542706)
			(xy 336.367559 -284.566212) (xy 336.409446 -284.596644) (xy 336.446056 -284.633254) (xy 336.476488 -284.675141)
			(xy 336.499994 -284.721273) (xy 336.515993 -284.770513) (xy 336.524092 -284.821651) (xy 336.5246 -284.847538)
			(xy 336.524152 -284.872874) (xy 336.516394 -284.922948) (xy 336.501066 -284.971245) (xy 336.47853 -285.016629)
			(xy 336.449316 -285.058031) (xy 336.414111 -285.094476) (xy 336.373746 -285.125106) (xy 336.329169 -285.149199)
			(xy 336.281431 -285.16619) (xy 336.25663 -285.171388) (xy 336.23377 -285.175706) (xy 336.028792 -285.530798)
			(xy 336.036412 -285.552642) (xy 336.044976 -285.578999) (xy 336.054174 -285.633646) (xy 336.0547 -285.661354)
			(xy 337.275424 -285.661354) (xy 337.275932 -285.635467) (xy 337.284031 -285.584329) (xy 337.30003 -285.535089)
			(xy 337.323536 -285.488957) (xy 337.353968 -285.44707) (xy 337.390578 -285.41046) (xy 337.432465 -285.380028)
			(xy 337.478597 -285.356522) (xy 337.527837 -285.340523) (xy 337.578975 -285.332424) (xy 337.630749 -285.332424)
			(xy 337.681887 -285.340523) (xy 337.731127 -285.356522) (xy 337.777259 -285.380028) (xy 337.819146 -285.41046)
			(xy 337.855756 -285.44707) (xy 337.886188 -285.488957) (xy 337.909694 -285.535089) (xy 337.925693 -285.584329)
			(xy 337.933792 -285.635467) (xy 337.9343 -285.661354) (xy 338.215224 -285.661354) (xy 338.215684 -285.636008)
			(xy 338.223463 -285.585916) (xy 338.238816 -285.537605) (xy 338.26138 -285.492212) (xy 338.290625 -285.450806)
			(xy 338.325861 -285.414363) (xy 338.366259 -285.383741) (xy 338.410867 -285.359661) (xy 338.458634 -285.34269)
			(xy 338.483448 -285.337504) (xy 338.506308 -285.333186) (xy 338.711286 -284.978348) (xy 338.703412 -284.956504)
			(xy 338.694834 -284.930085) (xy 338.685636 -284.87531) (xy 338.685124 -284.847538) (xy 338.685632 -284.821651)
			(xy 338.693731 -284.770513) (xy 338.70973 -284.721273) (xy 338.733236 -284.675141) (xy 338.763668 -284.633254)
			(xy 338.800278 -284.596644) (xy 338.842165 -284.566212) (xy 338.888297 -284.542706) (xy 338.937537 -284.526707)
			(xy 338.988675 -284.518608) (xy 339.040449 -284.518608) (xy 339.091587 -284.526707) (xy 339.140827 -284.542706)
			(xy 339.186959 -284.566212) (xy 339.228846 -284.596644) (xy 339.265456 -284.633254) (xy 339.295888 -284.675141)
			(xy 339.319394 -284.721273) (xy 339.335393 -284.770513) (xy 339.343492 -284.821651) (xy 339.344 -284.847538)
			(xy 339.343552 -284.872874) (xy 339.335794 -284.922948) (xy 339.320466 -284.971245) (xy 339.29793 -285.016629)
			(xy 339.268716 -285.058031) (xy 339.233511 -285.094476) (xy 339.193146 -285.125106) (xy 339.148569 -285.149199)
			(xy 339.100831 -285.16619) (xy 339.07603 -285.171388) (xy 339.05317 -285.175706) (xy 338.848192 -285.530544)
			(xy 338.856066 -285.552642) (xy 338.86469 -285.578991) (xy 338.874015 -285.633637) (xy 338.874608 -285.661354)
			(xy 339.155024 -285.661354) (xy 339.155532 -285.635447) (xy 339.163638 -285.58427) (xy 339.17965 -285.534991)
			(xy 339.203173 -285.488824) (xy 339.233629 -285.446905) (xy 339.270267 -285.410267) (xy 339.312186 -285.379811)
			(xy 339.358353 -285.356288) (xy 339.407632 -285.340276) (xy 339.458809 -285.33217) (xy 339.510623 -285.33217)
			(xy 339.5618 -285.340276) (xy 339.611079 -285.356288) (xy 339.657246 -285.379811) (xy 339.699165 -285.410267)
			(xy 339.735803 -285.446905) (xy 339.766259 -285.488824) (xy 339.789782 -285.534991) (xy 339.805794 -285.58427)
			(xy 339.8139 -285.635447) (xy 339.814408 -285.661354) (xy 340.094824 -285.661354) (xy 340.095245 -285.636017)
			(xy 340.103005 -285.585941) (xy 340.118335 -285.537642) (xy 340.140875 -285.492257) (xy 340.170092 -285.450854)
			(xy 340.2053 -285.41441) (xy 340.24567 -285.383781) (xy 340.29025 -285.359689) (xy 340.337992 -285.342701)
			(xy 340.362794 -285.337504) (xy 340.385654 -285.333186) (xy 340.590886 -284.97784) (xy 340.583266 -284.955996)
			(xy 340.574644 -284.929713) (xy 340.565327 -284.875193) (xy 340.564724 -284.847538) (xy 340.565232 -284.821631)
			(xy 340.573338 -284.770454) (xy 340.58935 -284.721175) (xy 340.612873 -284.675008) (xy 340.643329 -284.633089)
			(xy 340.679967 -284.596451) (xy 340.721886 -284.565995) (xy 340.768053 -284.542472) (xy 340.817332 -284.52646)
			(xy 340.868509 -284.518354) (xy 340.920323 -284.518354) (xy 340.9715 -284.52646) (xy 341.020779 -284.542472)
			(xy 341.066946 -284.565995) (xy 341.108865 -284.596451) (xy 341.145503 -284.633089) (xy 341.175959 -284.675008)
			(xy 341.199482 -284.721175) (xy 341.215494 -284.770454) (xy 341.2236 -284.821631) (xy 341.224108 -284.847538)
			(xy 341.223661 -284.872913) (xy 341.215887 -284.923064) (xy 341.200514 -284.97143) (xy 341.177905 -285.016866)
			(xy 341.148596 -285.058297) (xy 341.113279 -285.094742) (xy 341.072791 -285.125341) (xy 341.028089 -285.149367)
			(xy 340.980231 -285.166254) (xy 340.955376 -285.171388) (xy 340.932516 -285.175706) (xy 340.727538 -285.530544)
			(xy 340.735412 -285.552642) (xy 340.743983 -285.578997) (xy 340.753175 -285.633645) (xy 340.7537 -285.661354)
			(xy 341.034624 -285.661354) (xy 341.035132 -285.635467) (xy 341.043231 -285.584329) (xy 341.05923 -285.535089)
			(xy 341.082736 -285.488957) (xy 341.113168 -285.44707) (xy 341.149778 -285.41046) (xy 341.191665 -285.380028)
			(xy 341.237797 -285.356522) (xy 341.287037 -285.340523) (xy 341.338175 -285.332424) (xy 341.389949 -285.332424)
			(xy 341.441087 -285.340523) (xy 341.490327 -285.356522) (xy 341.536459 -285.380028) (xy 341.578346 -285.41046)
			(xy 341.614956 -285.44707) (xy 341.645388 -285.488957) (xy 341.668894 -285.535089) (xy 341.684893 -285.584329)
			(xy 341.692992 -285.635467) (xy 341.6935 -285.661354) (xy 341.974424 -285.661354) (xy 341.974845 -285.636017)
			(xy 341.982605 -285.585941) (xy 341.997935 -285.537642) (xy 342.020475 -285.492257) (xy 342.049692 -285.450854)
			(xy 342.0849 -285.41441) (xy 342.12527 -285.383781) (xy 342.16985 -285.359689) (xy 342.217592 -285.342701)
			(xy 342.242394 -285.337504) (xy 342.265254 -285.333186) (xy 342.470486 -284.97784) (xy 342.462866 -284.955996)
			(xy 342.454244 -284.929713) (xy 342.444927 -284.875193) (xy 342.444324 -284.847538) (xy 342.444832 -284.821631)
			(xy 342.452938 -284.770454) (xy 342.46895 -284.721175) (xy 342.492473 -284.675008) (xy 342.522929 -284.633089)
			(xy 342.559567 -284.596451) (xy 342.601486 -284.565995) (xy 342.647653 -284.542472) (xy 342.696932 -284.52646)
			(xy 342.748109 -284.518354) (xy 342.799923 -284.518354) (xy 342.8511 -284.52646) (xy 342.900379 -284.542472)
			(xy 342.946546 -284.565995) (xy 342.988465 -284.596451) (xy 343.025103 -284.633089) (xy 343.055559 -284.675008)
			(xy 343.079082 -284.721175) (xy 343.095094 -284.770454) (xy 343.1032 -284.821631) (xy 343.103708 -284.847538)
			(xy 343.103261 -284.872913) (xy 343.095487 -284.923064) (xy 343.080114 -284.97143) (xy 343.057505 -285.016866)
			(xy 343.028196 -285.058297) (xy 342.992879 -285.094742) (xy 342.952391 -285.125341) (xy 342.907689 -285.149367)
			(xy 342.859831 -285.166254) (xy 342.834976 -285.171388) (xy 342.812116 -285.175706) (xy 342.607138 -285.530544)
			(xy 342.615012 -285.552642) (xy 342.623583 -285.578997) (xy 342.632775 -285.633645) (xy 342.6333 -285.661354)
			(xy 342.914224 -285.661354) (xy 342.914732 -285.635467) (xy 342.922831 -285.584329) (xy 342.93883 -285.535089)
			(xy 342.962336 -285.488957) (xy 342.992768 -285.44707) (xy 343.029378 -285.41046) (xy 343.071265 -285.380028)
			(xy 343.117397 -285.356522) (xy 343.166637 -285.340523) (xy 343.217775 -285.332424) (xy 343.269549 -285.332424)
			(xy 343.320687 -285.340523) (xy 343.369927 -285.356522) (xy 343.416059 -285.380028) (xy 343.457946 -285.41046)
			(xy 343.494556 -285.44707) (xy 343.524988 -285.488957) (xy 343.548494 -285.535089) (xy 343.564493 -285.584329)
			(xy 343.572592 -285.635467) (xy 343.5731 -285.661354) (xy 343.854024 -285.661354) (xy 343.854445 -285.636017)
			(xy 343.862205 -285.585941) (xy 343.877535 -285.537642) (xy 343.900075 -285.492257) (xy 343.929292 -285.450854)
			(xy 343.9645 -285.41441) (xy 344.00487 -285.383781) (xy 344.04945 -285.359689) (xy 344.097192 -285.342701)
			(xy 344.121994 -285.337504) (xy 344.144854 -285.333186) (xy 344.350086 -284.97784) (xy 344.342466 -284.955996)
			(xy 344.333844 -284.929713) (xy 344.324527 -284.875193) (xy 344.323924 -284.847538) (xy 344.324432 -284.821631)
			(xy 344.332538 -284.770454) (xy 344.34855 -284.721175) (xy 344.372073 -284.675008) (xy 344.402529 -284.633089)
			(xy 344.439167 -284.596451) (xy 344.481086 -284.565995) (xy 344.527253 -284.542472) (xy 344.576532 -284.52646)
			(xy 344.627709 -284.518354) (xy 344.679523 -284.518354) (xy 344.7307 -284.52646) (xy 344.779979 -284.542472)
			(xy 344.826146 -284.565995) (xy 344.868065 -284.596451) (xy 344.904703 -284.633089) (xy 344.935159 -284.675008)
			(xy 344.958682 -284.721175) (xy 344.974694 -284.770454) (xy 344.9828 -284.821631) (xy 344.983308 -284.847538)
			(xy 344.982861 -284.872913) (xy 344.975087 -284.923064) (xy 344.959714 -284.97143) (xy 344.937105 -285.016866)
			(xy 344.907796 -285.058297) (xy 344.872479 -285.094742) (xy 344.831991 -285.125341) (xy 344.787289 -285.149367)
			(xy 344.739431 -285.166254) (xy 344.714576 -285.171388) (xy 344.691716 -285.175706) (xy 344.486738 -285.530544)
			(xy 344.494612 -285.552642) (xy 344.503183 -285.578997) (xy 344.512375 -285.633645) (xy 344.5129 -285.661354)
			(xy 344.793824 -285.661354) (xy 344.794332 -285.635467) (xy 344.802431 -285.584329) (xy 344.81843 -285.535089)
			(xy 344.841936 -285.488957) (xy 344.872368 -285.44707) (xy 344.908978 -285.41046) (xy 344.950865 -285.380028)
			(xy 344.996997 -285.356522) (xy 345.046237 -285.340523) (xy 345.097375 -285.332424) (xy 345.149149 -285.332424)
			(xy 345.200287 -285.340523) (xy 345.249527 -285.356522) (xy 345.295659 -285.380028) (xy 345.337546 -285.41046)
			(xy 345.374156 -285.44707) (xy 345.404588 -285.488957) (xy 345.428094 -285.535089) (xy 345.444093 -285.584329)
			(xy 345.452192 -285.635467) (xy 345.4527 -285.661354) (xy 345.733624 -285.661354) (xy 345.734045 -285.636017)
			(xy 345.741805 -285.585941) (xy 345.757135 -285.537642) (xy 345.779675 -285.492257) (xy 345.808892 -285.450854)
			(xy 345.8441 -285.41441) (xy 345.88447 -285.383781) (xy 345.92905 -285.359689) (xy 345.976792 -285.342701)
			(xy 346.001594 -285.337504) (xy 346.024454 -285.333186) (xy 346.229686 -284.97784) (xy 346.222066 -284.955996)
			(xy 346.213444 -284.929713) (xy 346.204127 -284.875193) (xy 346.203524 -284.847538) (xy 346.204032 -284.821631)
			(xy 346.212138 -284.770454) (xy 346.22815 -284.721175) (xy 346.251673 -284.675008) (xy 346.282129 -284.633089)
			(xy 346.318767 -284.596451) (xy 346.360686 -284.565995) (xy 346.406853 -284.542472) (xy 346.456132 -284.52646)
			(xy 346.507309 -284.518354) (xy 346.559123 -284.518354) (xy 346.6103 -284.52646) (xy 346.659579 -284.542472)
			(xy 346.705746 -284.565995) (xy 346.747665 -284.596451) (xy 346.784303 -284.633089) (xy 346.814759 -284.675008)
			(xy 346.838282 -284.721175) (xy 346.854294 -284.770454) (xy 346.8624 -284.821631) (xy 346.862908 -284.847538)
			(xy 346.862461 -284.872913) (xy 346.854687 -284.923064) (xy 346.839314 -284.97143) (xy 346.816705 -285.016866)
			(xy 346.787396 -285.058297) (xy 346.752079 -285.094742) (xy 346.711591 -285.125341) (xy 346.666889 -285.149367)
			(xy 346.619031 -285.166254) (xy 346.594176 -285.171388) (xy 346.571316 -285.175706) (xy 346.366338 -285.530544)
			(xy 346.374212 -285.552642) (xy 346.382783 -285.578997) (xy 346.391975 -285.633645) (xy 346.3925 -285.661354)
			(xy 346.673424 -285.661354) (xy 346.673932 -285.635467) (xy 346.682031 -285.584329) (xy 346.69803 -285.535089)
			(xy 346.721536 -285.488957) (xy 346.751968 -285.44707) (xy 346.788578 -285.41046) (xy 346.830465 -285.380028)
			(xy 346.876597 -285.356522) (xy 346.925837 -285.340523) (xy 346.976975 -285.332424) (xy 347.028749 -285.332424)
			(xy 347.079887 -285.340523) (xy 347.129127 -285.356522) (xy 347.175259 -285.380028) (xy 347.217146 -285.41046)
			(xy 347.253756 -285.44707) (xy 347.284188 -285.488957) (xy 347.307694 -285.535089) (xy 347.323693 -285.584329)
			(xy 347.331792 -285.635467) (xy 347.3323 -285.661354) (xy 347.613224 -285.661354) (xy 347.613645 -285.636017)
			(xy 347.621405 -285.585941) (xy 347.636735 -285.537642) (xy 347.659275 -285.492257) (xy 347.688492 -285.450854)
			(xy 347.7237 -285.41441) (xy 347.76407 -285.383781) (xy 347.80865 -285.359689) (xy 347.856392 -285.342701)
			(xy 347.881194 -285.337504) (xy 347.904054 -285.333186) (xy 348.109286 -284.97784) (xy 348.101666 -284.955996)
			(xy 348.093044 -284.929713) (xy 348.083727 -284.875193) (xy 348.083124 -284.847538) (xy 348.083632 -284.821631)
			(xy 348.091738 -284.770454) (xy 348.10775 -284.721175) (xy 348.131273 -284.675008) (xy 348.161729 -284.633089)
			(xy 348.198367 -284.596451) (xy 348.240286 -284.565995) (xy 348.286453 -284.542472) (xy 348.335732 -284.52646)
			(xy 348.386909 -284.518354) (xy 348.438723 -284.518354) (xy 348.4899 -284.52646) (xy 348.539179 -284.542472)
			(xy 348.585346 -284.565995) (xy 348.627265 -284.596451) (xy 348.663903 -284.633089) (xy 348.694359 -284.675008)
			(xy 348.717882 -284.721175) (xy 348.733894 -284.770454) (xy 348.742 -284.821631) (xy 348.742508 -284.847538)
			(xy 348.742061 -284.872913) (xy 348.734287 -284.923064) (xy 348.718914 -284.97143) (xy 348.696305 -285.016866)
			(xy 348.666996 -285.058297) (xy 348.631679 -285.094742) (xy 348.591191 -285.125341) (xy 348.546489 -285.149367)
			(xy 348.498631 -285.166254) (xy 348.473776 -285.171388) (xy 348.450916 -285.175706) (xy 348.245938 -285.530544)
			(xy 348.253812 -285.552642) (xy 348.262383 -285.578997) (xy 348.271575 -285.633645) (xy 348.2721 -285.661354)
			(xy 348.553024 -285.661354) (xy 348.553532 -285.635467) (xy 348.561631 -285.584329) (xy 348.57763 -285.535089)
			(xy 348.601136 -285.488957) (xy 348.631568 -285.44707) (xy 348.668178 -285.41046) (xy 348.710065 -285.380028)
			(xy 348.756197 -285.356522) (xy 348.805437 -285.340523) (xy 348.856575 -285.332424) (xy 348.908349 -285.332424)
			(xy 348.959487 -285.340523) (xy 349.008727 -285.356522) (xy 349.054859 -285.380028) (xy 349.096746 -285.41046)
			(xy 349.133356 -285.44707) (xy 349.163788 -285.488957) (xy 349.187294 -285.535089) (xy 349.203293 -285.584329)
			(xy 349.211392 -285.635467) (xy 349.2119 -285.661354) (xy 349.492824 -285.661354) (xy 349.493245 -285.636017)
			(xy 349.501005 -285.585941) (xy 349.516335 -285.537642) (xy 349.538875 -285.492257) (xy 349.568092 -285.450854)
			(xy 349.6033 -285.41441) (xy 349.64367 -285.383781) (xy 349.68825 -285.359689) (xy 349.735992 -285.342701)
			(xy 349.760794 -285.337504) (xy 349.783654 -285.333186) (xy 349.988886 -284.97784) (xy 349.981266 -284.955996)
			(xy 349.972644 -284.929713) (xy 349.963327 -284.875193) (xy 349.962724 -284.847538) (xy 349.963232 -284.821631)
			(xy 349.971338 -284.770454) (xy 349.98735 -284.721175) (xy 350.010873 -284.675008) (xy 350.041329 -284.633089)
			(xy 350.077967 -284.596451) (xy 350.119886 -284.565995) (xy 350.166053 -284.542472) (xy 350.215332 -284.52646)
			(xy 350.266509 -284.518354) (xy 350.318323 -284.518354) (xy 350.3695 -284.52646) (xy 350.418779 -284.542472)
			(xy 350.464946 -284.565995) (xy 350.506865 -284.596451) (xy 350.543503 -284.633089) (xy 350.573959 -284.675008)
			(xy 350.597482 -284.721175) (xy 350.613494 -284.770454) (xy 350.6216 -284.821631) (xy 350.622108 -284.847538)
			(xy 350.621661 -284.872913) (xy 350.613887 -284.923064) (xy 350.598514 -284.97143) (xy 350.575905 -285.016866)
			(xy 350.546596 -285.058297) (xy 350.511279 -285.094742) (xy 350.470791 -285.125341) (xy 350.426089 -285.149367)
			(xy 350.378231 -285.166254) (xy 350.353376 -285.171388) (xy 350.330516 -285.175706) (xy 350.125538 -285.530544)
			(xy 350.133412 -285.552642) (xy 350.141983 -285.578997) (xy 350.151175 -285.633645) (xy 350.1517 -285.661354)
			(xy 350.432624 -285.661354) (xy 350.433132 -285.635467) (xy 350.441231 -285.584329) (xy 350.45723 -285.535089)
			(xy 350.480736 -285.488957) (xy 350.511168 -285.44707) (xy 350.547778 -285.41046) (xy 350.589665 -285.380028)
			(xy 350.635797 -285.356522) (xy 350.685037 -285.340523) (xy 350.736175 -285.332424) (xy 350.787949 -285.332424)
			(xy 350.839087 -285.340523) (xy 350.888327 -285.356522) (xy 350.934459 -285.380028) (xy 350.976346 -285.41046)
			(xy 351.012956 -285.44707) (xy 351.043388 -285.488957) (xy 351.066894 -285.535089) (xy 351.082893 -285.584329)
			(xy 351.090992 -285.635467) (xy 351.0915 -285.661354) (xy 351.372424 -285.661354) (xy 351.372845 -285.636017)
			(xy 351.380605 -285.585941) (xy 351.395935 -285.537642) (xy 351.418475 -285.492257) (xy 351.447692 -285.450854)
			(xy 351.4829 -285.41441) (xy 351.52327 -285.383781) (xy 351.56785 -285.359689) (xy 351.615592 -285.342701)
			(xy 351.640394 -285.337504) (xy 351.663254 -285.333186) (xy 351.868486 -284.97784) (xy 351.860866 -284.955996)
			(xy 351.852244 -284.929713) (xy 351.842927 -284.875193) (xy 351.842324 -284.847538) (xy 351.842832 -284.821631)
			(xy 351.850938 -284.770454) (xy 351.86695 -284.721175) (xy 351.890473 -284.675008) (xy 351.920929 -284.633089)
			(xy 351.957567 -284.596451) (xy 351.999486 -284.565995) (xy 352.045653 -284.542472) (xy 352.094932 -284.52646)
			(xy 352.146109 -284.518354) (xy 352.197923 -284.518354) (xy 352.2491 -284.52646) (xy 352.298379 -284.542472)
			(xy 352.344546 -284.565995) (xy 352.386465 -284.596451) (xy 352.423103 -284.633089) (xy 352.453559 -284.675008)
			(xy 352.477082 -284.721175) (xy 352.493094 -284.770454) (xy 352.5012 -284.821631) (xy 352.501708 -284.847538)
			(xy 366.879124 -284.847538) (xy 366.879632 -284.821631) (xy 366.887738 -284.770454) (xy 366.90375 -284.721175)
			(xy 366.927273 -284.675008) (xy 366.957729 -284.633089) (xy 366.994367 -284.596451) (xy 367.036286 -284.565995)
			(xy 367.082453 -284.542472) (xy 367.131732 -284.52646) (xy 367.182909 -284.518354) (xy 367.234723 -284.518354)
			(xy 367.2859 -284.52646) (xy 367.335179 -284.542472) (xy 367.381346 -284.565995) (xy 367.423265 -284.596451)
			(xy 367.459903 -284.633089) (xy 367.490359 -284.675008) (xy 367.513882 -284.721175) (xy 367.529894 -284.770454)
			(xy 367.538 -284.821631) (xy 367.538508 -284.847538) (xy 368.758724 -284.847538) (xy 368.759232 -284.821631)
			(xy 368.767338 -284.770454) (xy 368.78335 -284.721175) (xy 368.806873 -284.675008) (xy 368.837329 -284.633089)
			(xy 368.873967 -284.596451) (xy 368.915886 -284.565995) (xy 368.962053 -284.542472) (xy 369.011332 -284.52646)
			(xy 369.062509 -284.518354) (xy 369.114323 -284.518354) (xy 369.1655 -284.52646) (xy 369.214779 -284.542472)
			(xy 369.260946 -284.565995) (xy 369.302865 -284.596451) (xy 369.339503 -284.633089) (xy 369.369959 -284.675008)
			(xy 369.393482 -284.721175) (xy 369.409494 -284.770454) (xy 369.4176 -284.821631) (xy 369.418108 -284.847538)
			(xy 370.638324 -284.847538) (xy 370.638832 -284.821631) (xy 370.646938 -284.770454) (xy 370.66295 -284.721175)
			(xy 370.686473 -284.675008) (xy 370.716929 -284.633089) (xy 370.753567 -284.596451) (xy 370.795486 -284.565995)
			(xy 370.841653 -284.542472) (xy 370.890932 -284.52646) (xy 370.942109 -284.518354) (xy 370.993923 -284.518354)
			(xy 371.0451 -284.52646) (xy 371.094379 -284.542472) (xy 371.140546 -284.565995) (xy 371.182465 -284.596451)
			(xy 371.219103 -284.633089) (xy 371.249559 -284.675008) (xy 371.273082 -284.721175) (xy 371.289094 -284.770454)
			(xy 371.2972 -284.821631) (xy 371.297708 -284.847538) (xy 372.517924 -284.847538) (xy 372.518432 -284.821631)
			(xy 372.526538 -284.770454) (xy 372.54255 -284.721175) (xy 372.566073 -284.675008) (xy 372.596529 -284.633089)
			(xy 372.633167 -284.596451) (xy 372.675086 -284.565995) (xy 372.721253 -284.542472) (xy 372.770532 -284.52646)
			(xy 372.821709 -284.518354) (xy 372.873523 -284.518354) (xy 372.9247 -284.52646) (xy 372.973979 -284.542472)
			(xy 373.020146 -284.565995) (xy 373.062065 -284.596451) (xy 373.098703 -284.633089) (xy 373.129159 -284.675008)
			(xy 373.152682 -284.721175) (xy 373.168694 -284.770454) (xy 373.1768 -284.821631) (xy 373.177308 -284.847538)
			(xy 374.397524 -284.847538) (xy 374.398032 -284.821631) (xy 374.406138 -284.770454) (xy 374.42215 -284.721175)
			(xy 374.445673 -284.675008) (xy 374.476129 -284.633089) (xy 374.512767 -284.596451) (xy 374.554686 -284.565995)
			(xy 374.600853 -284.542472) (xy 374.650132 -284.52646) (xy 374.701309 -284.518354) (xy 374.753123 -284.518354)
			(xy 374.8043 -284.52646) (xy 374.853579 -284.542472) (xy 374.899746 -284.565995) (xy 374.941665 -284.596451)
			(xy 374.978303 -284.633089) (xy 375.008759 -284.675008) (xy 375.032282 -284.721175) (xy 375.048294 -284.770454)
			(xy 375.0564 -284.821631) (xy 375.056908 -284.847538) (xy 376.277124 -284.847538) (xy 376.277632 -284.821631)
			(xy 376.285738 -284.770454) (xy 376.30175 -284.721175) (xy 376.325273 -284.675008) (xy 376.355729 -284.633089)
			(xy 376.392367 -284.596451) (xy 376.434286 -284.565995) (xy 376.480453 -284.542472) (xy 376.529732 -284.52646)
			(xy 376.580909 -284.518354) (xy 376.632723 -284.518354) (xy 376.6839 -284.52646) (xy 376.733179 -284.542472)
			(xy 376.779346 -284.565995) (xy 376.821265 -284.596451) (xy 376.857903 -284.633089) (xy 376.888359 -284.675008)
			(xy 376.911882 -284.721175) (xy 376.927894 -284.770454) (xy 376.936 -284.821631) (xy 376.936508 -284.847538)
			(xy 378.156724 -284.847538) (xy 378.157232 -284.821631) (xy 378.165338 -284.770454) (xy 378.18135 -284.721175)
			(xy 378.204873 -284.675008) (xy 378.235329 -284.633089) (xy 378.271967 -284.596451) (xy 378.313886 -284.565995)
			(xy 378.360053 -284.542472) (xy 378.409332 -284.52646) (xy 378.460509 -284.518354) (xy 378.512323 -284.518354)
			(xy 378.5635 -284.52646) (xy 378.612779 -284.542472) (xy 378.658946 -284.565995) (xy 378.700865 -284.596451)
			(xy 378.737503 -284.633089) (xy 378.767959 -284.675008) (xy 378.791482 -284.721175) (xy 378.807494 -284.770454)
			(xy 378.8156 -284.821631) (xy 378.816108 -284.847538) (xy 380.036324 -284.847538) (xy 380.036832 -284.821631)
			(xy 380.044938 -284.770454) (xy 380.06095 -284.721175) (xy 380.084473 -284.675008) (xy 380.114929 -284.633089)
			(xy 380.151567 -284.596451) (xy 380.193486 -284.565995) (xy 380.239653 -284.542472) (xy 380.288932 -284.52646)
			(xy 380.340109 -284.518354) (xy 380.391923 -284.518354) (xy 380.4431 -284.52646) (xy 380.492379 -284.542472)
			(xy 380.538546 -284.565995) (xy 380.580465 -284.596451) (xy 380.617103 -284.633089) (xy 380.647559 -284.675008)
			(xy 380.671082 -284.721175) (xy 380.687094 -284.770454) (xy 380.6952 -284.821631) (xy 380.695708 -284.847538)
			(xy 380.695098 -284.875255) (xy 380.685785 -284.929901) (xy 380.677166 -284.95625) (xy 380.669292 -284.978348)
			(xy 380.87427 -285.333186) (xy 380.89713 -285.337504) (xy 380.921947 -285.342634) (xy 380.969689 -285.35963)
			(xy 381.014267 -285.383731) (xy 381.054634 -285.414369) (xy 381.089836 -285.450823) (xy 381.119046 -285.492235)
			(xy 381.141576 -285.537628) (xy 381.156894 -285.585934) (xy 381.16464 -285.636016) (xy 381.1651 -285.661354)
			(xy 381.164592 -285.687241) (xy 381.156493 -285.738379) (xy 381.140494 -285.787619) (xy 381.116988 -285.833751)
			(xy 381.086556 -285.875638) (xy 381.049946 -285.912248) (xy 381.008059 -285.94268) (xy 380.961927 -285.966186)
			(xy 380.912687 -285.982185) (xy 380.861549 -285.990284) (xy 380.809775 -285.990284) (xy 380.758637 -285.982185)
			(xy 380.709397 -285.966186) (xy 380.663265 -285.94268) (xy 380.621378 -285.912248) (xy 380.584768 -285.875638)
			(xy 380.554336 -285.833751) (xy 380.53083 -285.787619) (xy 380.514831 -285.738379) (xy 380.506732 -285.687241)
			(xy 380.506224 -285.661354) (xy 380.506766 -285.633646) (xy 380.515953 -285.579) (xy 380.524512 -285.552642)
			(xy 380.532386 -285.530544) (xy 380.327408 -285.175706) (xy 380.304548 -285.171388) (xy 380.279723 -285.166238)
			(xy 380.231943 -285.149282) (xy 380.187323 -285.125209) (xy 380.146916 -285.094586) (xy 380.111675 -285.058137)
			(xy 380.082431 -285.016721) (xy 380.059876 -284.971315) (xy 380.044539 -284.922991) (xy 380.036785 -284.872888)
			(xy 380.036324 -284.847538) (xy 378.816108 -284.847538) (xy 378.815498 -284.875255) (xy 378.806185 -284.929901)
			(xy 378.797566 -284.95625) (xy 378.789692 -284.978348) (xy 378.99467 -285.333186) (xy 379.01753 -285.337504)
			(xy 379.042347 -285.342634) (xy 379.090089 -285.35963) (xy 379.134667 -285.383731) (xy 379.175034 -285.414369)
			(xy 379.210236 -285.450823) (xy 379.239446 -285.492235) (xy 379.261976 -285.537628) (xy 379.277294 -285.585934)
			(xy 379.28504 -285.636016) (xy 379.2855 -285.661354) (xy 379.284992 -285.687241) (xy 379.276893 -285.738379)
			(xy 379.260894 -285.787619) (xy 379.237388 -285.833751) (xy 379.206956 -285.875638) (xy 379.170346 -285.912248)
			(xy 379.128459 -285.94268) (xy 379.082327 -285.966186) (xy 379.033087 -285.982185) (xy 378.981949 -285.990284)
			(xy 378.930175 -285.990284) (xy 378.879037 -285.982185) (xy 378.829797 -285.966186) (xy 378.783665 -285.94268)
			(xy 378.741778 -285.912248) (xy 378.705168 -285.875638) (xy 378.674736 -285.833751) (xy 378.65123 -285.787619)
			(xy 378.635231 -285.738379) (xy 378.627132 -285.687241) (xy 378.626624 -285.661354) (xy 378.627166 -285.633646)
			(xy 378.636353 -285.579) (xy 378.644912 -285.552642) (xy 378.652786 -285.530544) (xy 378.447808 -285.175706)
			(xy 378.424948 -285.171388) (xy 378.400123 -285.166238) (xy 378.352343 -285.149282) (xy 378.307723 -285.125209)
			(xy 378.267316 -285.094586) (xy 378.232075 -285.058137) (xy 378.202831 -285.016721) (xy 378.180276 -284.971315)
			(xy 378.164939 -284.922991) (xy 378.157185 -284.872888) (xy 378.156724 -284.847538) (xy 376.936508 -284.847538)
			(xy 376.935898 -284.875255) (xy 376.926585 -284.929901) (xy 376.917966 -284.95625) (xy 376.910092 -284.978348)
			(xy 377.11507 -285.333186) (xy 377.13793 -285.337504) (xy 377.162747 -285.342634) (xy 377.210489 -285.35963)
			(xy 377.255067 -285.383731) (xy 377.295434 -285.414369) (xy 377.330636 -285.450823) (xy 377.359846 -285.492235)
			(xy 377.382376 -285.537628) (xy 377.397694 -285.585934) (xy 377.40544 -285.636016) (xy 377.4059 -285.661354)
			(xy 377.405392 -285.687241) (xy 377.397293 -285.738379) (xy 377.381294 -285.787619) (xy 377.357788 -285.833751)
			(xy 377.327356 -285.875638) (xy 377.290746 -285.912248) (xy 377.248859 -285.94268) (xy 377.202727 -285.966186)
			(xy 377.153487 -285.982185) (xy 377.102349 -285.990284) (xy 377.050575 -285.990284) (xy 376.999437 -285.982185)
			(xy 376.950197 -285.966186) (xy 376.904065 -285.94268) (xy 376.862178 -285.912248) (xy 376.825568 -285.875638)
			(xy 376.795136 -285.833751) (xy 376.77163 -285.787619) (xy 376.755631 -285.738379) (xy 376.747532 -285.687241)
			(xy 376.747024 -285.661354) (xy 376.747566 -285.633646) (xy 376.756753 -285.579) (xy 376.765312 -285.552642)
			(xy 376.773186 -285.530544) (xy 376.568208 -285.175706) (xy 376.545348 -285.171388) (xy 376.520523 -285.166238)
			(xy 376.472743 -285.149282) (xy 376.428123 -285.125209) (xy 376.387716 -285.094586) (xy 376.352475 -285.058137)
			(xy 376.323231 -285.016721) (xy 376.300676 -284.971315) (xy 376.285339 -284.922991) (xy 376.277585 -284.872888)
			(xy 376.277124 -284.847538) (xy 375.056908 -284.847538) (xy 375.056298 -284.875255) (xy 375.046985 -284.929901)
			(xy 375.038366 -284.95625) (xy 375.030492 -284.978348) (xy 375.23547 -285.333186) (xy 375.25833 -285.337504)
			(xy 375.283147 -285.342634) (xy 375.330889 -285.35963) (xy 375.375467 -285.383731) (xy 375.415834 -285.414369)
			(xy 375.451036 -285.450823) (xy 375.480246 -285.492235) (xy 375.502776 -285.537628) (xy 375.518094 -285.585934)
			(xy 375.52584 -285.636016) (xy 375.5263 -285.661354) (xy 375.525792 -285.687241) (xy 375.517693 -285.738379)
			(xy 375.501694 -285.787619) (xy 375.478188 -285.833751) (xy 375.447756 -285.875638) (xy 375.411146 -285.912248)
			(xy 375.369259 -285.94268) (xy 375.323127 -285.966186) (xy 375.273887 -285.982185) (xy 375.222749 -285.990284)
			(xy 375.170975 -285.990284) (xy 375.119837 -285.982185) (xy 375.070597 -285.966186) (xy 375.024465 -285.94268)
			(xy 374.982578 -285.912248) (xy 374.945968 -285.875638) (xy 374.915536 -285.833751) (xy 374.89203 -285.787619)
			(xy 374.876031 -285.738379) (xy 374.867932 -285.687241) (xy 374.867424 -285.661354) (xy 374.867966 -285.633646)
			(xy 374.877153 -285.579) (xy 374.885712 -285.552642) (xy 374.893586 -285.530544) (xy 374.688608 -285.175706)
			(xy 374.665748 -285.171388) (xy 374.640923 -285.166238) (xy 374.593143 -285.149282) (xy 374.548523 -285.125209)
			(xy 374.508116 -285.094586) (xy 374.472875 -285.058137) (xy 374.443631 -285.016721) (xy 374.421076 -284.971315)
			(xy 374.405739 -284.922991) (xy 374.397985 -284.872888) (xy 374.397524 -284.847538) (xy 373.177308 -284.847538)
			(xy 373.176698 -284.875255) (xy 373.167385 -284.929901) (xy 373.158766 -284.95625) (xy 373.150892 -284.978348)
			(xy 373.35587 -285.333186) (xy 373.37873 -285.337504) (xy 373.403547 -285.342634) (xy 373.451289 -285.35963)
			(xy 373.495867 -285.383731) (xy 373.536234 -285.414369) (xy 373.571436 -285.450823) (xy 373.600646 -285.492235)
			(xy 373.623176 -285.537628) (xy 373.638494 -285.585934) (xy 373.64624 -285.636016) (xy 373.6467 -285.661354)
			(xy 373.646192 -285.687241) (xy 373.638093 -285.738379) (xy 373.622094 -285.787619) (xy 373.598588 -285.833751)
			(xy 373.568156 -285.875638) (xy 373.531546 -285.912248) (xy 373.489659 -285.94268) (xy 373.443527 -285.966186)
			(xy 373.394287 -285.982185) (xy 373.343149 -285.990284) (xy 373.291375 -285.990284) (xy 373.240237 -285.982185)
			(xy 373.190997 -285.966186) (xy 373.144865 -285.94268) (xy 373.102978 -285.912248) (xy 373.066368 -285.875638)
			(xy 373.035936 -285.833751) (xy 373.01243 -285.787619) (xy 372.996431 -285.738379) (xy 372.988332 -285.687241)
			(xy 372.987824 -285.661354) (xy 372.988366 -285.633646) (xy 372.997553 -285.579) (xy 373.006112 -285.552642)
			(xy 373.013986 -285.530544) (xy 372.809008 -285.175706) (xy 372.786148 -285.171388) (xy 372.761323 -285.166238)
			(xy 372.713543 -285.149282) (xy 372.668923 -285.125209) (xy 372.628516 -285.094586) (xy 372.593275 -285.058137)
			(xy 372.564031 -285.016721) (xy 372.541476 -284.971315) (xy 372.526139 -284.922991) (xy 372.518385 -284.872888)
			(xy 372.517924 -284.847538) (xy 371.297708 -284.847538) (xy 371.297098 -284.875255) (xy 371.287785 -284.929901)
			(xy 371.279166 -284.95625) (xy 371.271292 -284.978348) (xy 371.47627 -285.333186) (xy 371.49913 -285.337504)
			(xy 371.523947 -285.342634) (xy 371.571689 -285.35963) (xy 371.616267 -285.383731) (xy 371.656634 -285.414369)
			(xy 371.691836 -285.450823) (xy 371.721046 -285.492235) (xy 371.743576 -285.537628) (xy 371.758894 -285.585934)
			(xy 371.76664 -285.636016) (xy 371.7671 -285.661354) (xy 371.766592 -285.687241) (xy 371.758493 -285.738379)
			(xy 371.742494 -285.787619) (xy 371.718988 -285.833751) (xy 371.688556 -285.875638) (xy 371.651946 -285.912248)
			(xy 371.610059 -285.94268) (xy 371.563927 -285.966186) (xy 371.514687 -285.982185) (xy 371.463549 -285.990284)
			(xy 371.411775 -285.990284) (xy 371.360637 -285.982185) (xy 371.311397 -285.966186) (xy 371.265265 -285.94268)
			(xy 371.223378 -285.912248) (xy 371.186768 -285.875638) (xy 371.156336 -285.833751) (xy 371.13283 -285.787619)
			(xy 371.116831 -285.738379) (xy 371.108732 -285.687241) (xy 371.108224 -285.661354) (xy 371.108766 -285.633646)
			(xy 371.117953 -285.579) (xy 371.126512 -285.552642) (xy 371.134386 -285.530544) (xy 370.929408 -285.175706)
			(xy 370.906548 -285.171388) (xy 370.881723 -285.166238) (xy 370.833943 -285.149282) (xy 370.789323 -285.125209)
			(xy 370.748916 -285.094586) (xy 370.713675 -285.058137) (xy 370.684431 -285.016721) (xy 370.661876 -284.971315)
			(xy 370.646539 -284.922991) (xy 370.638785 -284.872888) (xy 370.638324 -284.847538) (xy 369.418108 -284.847538)
			(xy 369.417498 -284.875255) (xy 369.408185 -284.929901) (xy 369.399566 -284.95625) (xy 369.391692 -284.978348)
			(xy 369.59667 -285.333186) (xy 369.61953 -285.337504) (xy 369.644347 -285.342634) (xy 369.692089 -285.35963)
			(xy 369.736667 -285.383731) (xy 369.777034 -285.414369) (xy 369.812236 -285.450823) (xy 369.841446 -285.492235)
			(xy 369.863976 -285.537628) (xy 369.879294 -285.585934) (xy 369.88704 -285.636016) (xy 369.8875 -285.661354)
			(xy 369.886992 -285.687241) (xy 369.878893 -285.738379) (xy 369.862894 -285.787619) (xy 369.839388 -285.833751)
			(xy 369.808956 -285.875638) (xy 369.772346 -285.912248) (xy 369.730459 -285.94268) (xy 369.684327 -285.966186)
			(xy 369.635087 -285.982185) (xy 369.583949 -285.990284) (xy 369.532175 -285.990284) (xy 369.481037 -285.982185)
			(xy 369.431797 -285.966186) (xy 369.385665 -285.94268) (xy 369.343778 -285.912248) (xy 369.307168 -285.875638)
			(xy 369.276736 -285.833751) (xy 369.25323 -285.787619) (xy 369.237231 -285.738379) (xy 369.229132 -285.687241)
			(xy 369.228624 -285.661354) (xy 369.229166 -285.633646) (xy 369.238353 -285.579) (xy 369.246912 -285.552642)
			(xy 369.254786 -285.530544) (xy 369.049808 -285.175706) (xy 369.026948 -285.171388) (xy 369.002123 -285.166238)
			(xy 368.954343 -285.149282) (xy 368.909723 -285.125209) (xy 368.869316 -285.094586) (xy 368.834075 -285.058137)
			(xy 368.804831 -285.016721) (xy 368.782276 -284.971315) (xy 368.766939 -284.922991) (xy 368.759185 -284.872888)
			(xy 368.758724 -284.847538) (xy 367.538508 -284.847538) (xy 367.537898 -284.875255) (xy 367.528585 -284.929901)
			(xy 367.519966 -284.95625) (xy 367.512092 -284.978348) (xy 367.71707 -285.333186) (xy 367.73993 -285.337504)
			(xy 367.764747 -285.342634) (xy 367.812489 -285.35963) (xy 367.857067 -285.383731) (xy 367.897434 -285.414369)
			(xy 367.932636 -285.450823) (xy 367.961846 -285.492235) (xy 367.984376 -285.537628) (xy 367.999694 -285.585934)
			(xy 368.00744 -285.636016) (xy 368.0079 -285.661354) (xy 368.007392 -285.687241) (xy 367.999293 -285.738379)
			(xy 367.983294 -285.787619) (xy 367.959788 -285.833751) (xy 367.929356 -285.875638) (xy 367.892746 -285.912248)
			(xy 367.850859 -285.94268) (xy 367.804727 -285.966186) (xy 367.755487 -285.982185) (xy 367.704349 -285.990284)
			(xy 367.652575 -285.990284) (xy 367.601437 -285.982185) (xy 367.552197 -285.966186) (xy 367.506065 -285.94268)
			(xy 367.464178 -285.912248) (xy 367.427568 -285.875638) (xy 367.397136 -285.833751) (xy 367.37363 -285.787619)
			(xy 367.357631 -285.738379) (xy 367.349532 -285.687241) (xy 367.349024 -285.661354) (xy 367.349566 -285.633646)
			(xy 367.358753 -285.579) (xy 367.367312 -285.552642) (xy 367.375186 -285.530544) (xy 367.170208 -285.175706)
			(xy 367.147348 -285.171388) (xy 367.122523 -285.166238) (xy 367.074743 -285.149282) (xy 367.030123 -285.125209)
			(xy 366.989716 -285.094586) (xy 366.954475 -285.058137) (xy 366.925231 -285.016721) (xy 366.902676 -284.971315)
			(xy 366.887339 -284.922991) (xy 366.879585 -284.872888) (xy 366.879124 -284.847538) (xy 352.501708 -284.847538)
			(xy 352.501261 -284.872913) (xy 352.493487 -284.923064) (xy 352.478114 -284.97143) (xy 352.455505 -285.016866)
			(xy 352.426196 -285.058297) (xy 352.390879 -285.094742) (xy 352.350391 -285.125341) (xy 352.305689 -285.149367)
			(xy 352.257831 -285.166254) (xy 352.232976 -285.171388) (xy 352.210116 -285.175706) (xy 352.005138 -285.530544)
			(xy 352.013012 -285.552642) (xy 352.021583 -285.578997) (xy 352.030775 -285.633645) (xy 352.0313 -285.661354)
			(xy 352.030792 -285.687241) (xy 352.022693 -285.738379) (xy 352.006694 -285.787619) (xy 351.983188 -285.833751)
			(xy 351.952756 -285.875638) (xy 351.916146 -285.912248) (xy 351.874259 -285.94268) (xy 351.828127 -285.966186)
			(xy 351.778887 -285.982185) (xy 351.727749 -285.990284) (xy 351.675975 -285.990284) (xy 351.624837 -285.982185)
			(xy 351.575597 -285.966186) (xy 351.529465 -285.94268) (xy 351.487578 -285.912248) (xy 351.450968 -285.875638)
			(xy 351.420536 -285.833751) (xy 351.39703 -285.787619) (xy 351.381031 -285.738379) (xy 351.372932 -285.687241)
			(xy 351.372424 -285.661354) (xy 351.0915 -285.661354) (xy 351.0915 -285.661862) (xy 351.090923 -285.689379)
			(xy 351.081728 -285.74364) (xy 351.073212 -285.769812) (xy 351.065592 -285.79191) (xy 351.270824 -286.147256)
			(xy 351.293684 -286.151574) (xy 351.318506 -286.156737) (xy 351.366283 -286.173695) (xy 351.410901 -286.197768)
			(xy 351.451306 -286.22839) (xy 351.486546 -286.264837) (xy 351.515789 -286.30625) (xy 351.538346 -286.351653)
			(xy 351.553685 -286.399975) (xy 351.561445 -286.450075) (xy 351.561908 -286.475424) (xy 367.818924 -286.475424)
			(xy 367.819448 -286.45008) (xy 367.827216 -286.399991) (xy 367.842559 -286.351681) (xy 367.865115 -286.306288)
			(xy 367.894351 -286.264882) (xy 367.92958 -286.228438) (xy 367.969972 -286.197814) (xy 368.014574 -286.173733)
			(xy 368.062336 -286.156761) (xy 368.087148 -286.151574) (xy 368.110008 -286.147256) (xy 368.314986 -285.792164)
			(xy 368.307112 -285.77032) (xy 368.298538 -285.7439) (xy 368.289338 -285.689126) (xy 368.288824 -285.661354)
			(xy 368.289332 -285.635467) (xy 368.297431 -285.584329) (xy 368.31343 -285.535089) (xy 368.336936 -285.488957)
			(xy 368.367368 -285.44707) (xy 368.403978 -285.41046) (xy 368.445865 -285.380028) (xy 368.491997 -285.356522)
			(xy 368.541237 -285.340523) (xy 368.592375 -285.332424) (xy 368.644149 -285.332424) (xy 368.695287 -285.340523)
			(xy 368.744527 -285.356522) (xy 368.790659 -285.380028) (xy 368.832546 -285.41046) (xy 368.869156 -285.44707)
			(xy 368.899588 -285.488957) (xy 368.923094 -285.535089) (xy 368.939093 -285.584329) (xy 368.947192 -285.635467)
			(xy 368.9477 -285.661354) (xy 368.947266 -285.68669) (xy 368.939506 -285.736765) (xy 368.924176 -285.785062)
			(xy 368.901638 -285.830446) (xy 368.872422 -285.871848) (xy 368.837216 -285.908293) (xy 368.796849 -285.938922)
			(xy 368.752271 -285.963016) (xy 368.704531 -285.980006) (xy 368.67973 -285.985204) (xy 368.65687 -285.989522)
			(xy 368.451892 -286.344614) (xy 368.459766 -286.366458) (xy 368.468419 -286.392864) (xy 368.477734 -286.447642)
			(xy 368.478308 -286.475424) (xy 369.698524 -286.475424) (xy 369.699048 -286.45008) (xy 369.706816 -286.399991)
			(xy 369.722159 -286.351681) (xy 369.744715 -286.306288) (xy 369.773951 -286.264882) (xy 369.80918 -286.228438)
			(xy 369.849572 -286.197814) (xy 369.894174 -286.173733) (xy 369.941936 -286.156761) (xy 369.966748 -286.151574)
			(xy 369.989608 -286.147256) (xy 370.194586 -285.792164) (xy 370.186712 -285.77032) (xy 370.178138 -285.7439)
			(xy 370.168938 -285.689126) (xy 370.168424 -285.661354) (xy 370.168932 -285.635467) (xy 370.177031 -285.584329)
			(xy 370.19303 -285.535089) (xy 370.216536 -285.488957) (xy 370.246968 -285.44707) (xy 370.283578 -285.41046)
			(xy 370.325465 -285.380028) (xy 370.371597 -285.356522) (xy 370.420837 -285.340523) (xy 370.471975 -285.332424)
			(xy 370.523749 -285.332424) (xy 370.574887 -285.340523) (xy 370.624127 -285.356522) (xy 370.670259 -285.380028)
			(xy 370.712146 -285.41046) (xy 370.748756 -285.44707) (xy 370.779188 -285.488957) (xy 370.802694 -285.535089)
			(xy 370.818693 -285.584329) (xy 370.826792 -285.635467) (xy 370.8273 -285.661354) (xy 370.826866 -285.68669)
			(xy 370.819106 -285.736765) (xy 370.803776 -285.785062) (xy 370.781238 -285.830446) (xy 370.752022 -285.871848)
			(xy 370.716816 -285.908293) (xy 370.676449 -285.938922) (xy 370.631871 -285.963016) (xy 370.584131 -285.980006)
			(xy 370.55933 -285.985204) (xy 370.53647 -285.989522) (xy 370.331492 -286.344614) (xy 370.339366 -286.366458)
			(xy 370.348019 -286.392864) (xy 370.357334 -286.447642) (xy 370.357908 -286.475424) (xy 371.578124 -286.475424)
			(xy 371.578648 -286.45008) (xy 371.586416 -286.399991) (xy 371.601759 -286.351681) (xy 371.624315 -286.306288)
			(xy 371.653551 -286.264882) (xy 371.68878 -286.228438) (xy 371.729172 -286.197814) (xy 371.773774 -286.173733)
			(xy 371.821536 -286.156761) (xy 371.846348 -286.151574) (xy 371.869208 -286.147256) (xy 372.074186 -285.792164)
			(xy 372.066312 -285.77032) (xy 372.057738 -285.7439) (xy 372.048538 -285.689126) (xy 372.048024 -285.661354)
			(xy 372.048532 -285.635467) (xy 372.056631 -285.584329) (xy 372.07263 -285.535089) (xy 372.096136 -285.488957)
			(xy 372.126568 -285.44707) (xy 372.163178 -285.41046) (xy 372.205065 -285.380028) (xy 372.251197 -285.356522)
			(xy 372.300437 -285.340523) (xy 372.351575 -285.332424) (xy 372.403349 -285.332424) (xy 372.454487 -285.340523)
			(xy 372.503727 -285.356522) (xy 372.549859 -285.380028) (xy 372.591746 -285.41046) (xy 372.628356 -285.44707)
			(xy 372.658788 -285.488957) (xy 372.682294 -285.535089) (xy 372.698293 -285.584329) (xy 372.706392 -285.635467)
			(xy 372.7069 -285.661354) (xy 372.706466 -285.68669) (xy 372.698706 -285.736765) (xy 372.683376 -285.785062)
			(xy 372.660838 -285.830446) (xy 372.631622 -285.871848) (xy 372.596416 -285.908293) (xy 372.556049 -285.938922)
			(xy 372.511471 -285.963016) (xy 372.463731 -285.980006) (xy 372.43893 -285.985204) (xy 372.41607 -285.989522)
			(xy 372.211092 -286.344614) (xy 372.218966 -286.366458) (xy 372.227619 -286.392864) (xy 372.236934 -286.447642)
			(xy 372.237508 -286.475424) (xy 373.457724 -286.475424) (xy 373.458248 -286.45008) (xy 373.466016 -286.399991)
			(xy 373.481359 -286.351681) (xy 373.503915 -286.306288) (xy 373.533151 -286.264882) (xy 373.56838 -286.228438)
			(xy 373.608772 -286.197814) (xy 373.653374 -286.173733) (xy 373.701136 -286.156761) (xy 373.725948 -286.151574)
			(xy 373.748808 -286.147256) (xy 373.953786 -285.792164) (xy 373.945912 -285.77032) (xy 373.937338 -285.7439)
			(xy 373.928138 -285.689126) (xy 373.927624 -285.661354) (xy 373.928132 -285.635467) (xy 373.936231 -285.584329)
			(xy 373.95223 -285.535089) (xy 373.975736 -285.488957) (xy 374.006168 -285.44707) (xy 374.042778 -285.41046)
			(xy 374.084665 -285.380028) (xy 374.130797 -285.356522) (xy 374.180037 -285.340523) (xy 374.231175 -285.332424)
			(xy 374.282949 -285.332424) (xy 374.334087 -285.340523) (xy 374.383327 -285.356522) (xy 374.429459 -285.380028)
			(xy 374.471346 -285.41046) (xy 374.507956 -285.44707) (xy 374.538388 -285.488957) (xy 374.561894 -285.535089)
			(xy 374.577893 -285.584329) (xy 374.585992 -285.635467) (xy 374.5865 -285.661354) (xy 374.586066 -285.68669)
			(xy 374.578306 -285.736765) (xy 374.562976 -285.785062) (xy 374.540438 -285.830446) (xy 374.511222 -285.871848)
			(xy 374.476016 -285.908293) (xy 374.435649 -285.938922) (xy 374.391071 -285.963016) (xy 374.343331 -285.980006)
			(xy 374.31853 -285.985204) (xy 374.29567 -285.989522) (xy 374.090692 -286.344614) (xy 374.098566 -286.366458)
			(xy 374.107219 -286.392864) (xy 374.116534 -286.447642) (xy 374.117108 -286.475424) (xy 375.337324 -286.475424)
			(xy 375.337848 -286.45008) (xy 375.345616 -286.399991) (xy 375.360959 -286.351681) (xy 375.383515 -286.306288)
			(xy 375.412751 -286.264882) (xy 375.44798 -286.228438) (xy 375.488372 -286.197814) (xy 375.532974 -286.173733)
			(xy 375.580736 -286.156761) (xy 375.605548 -286.151574) (xy 375.628408 -286.147256) (xy 375.833386 -285.792164)
			(xy 375.825512 -285.77032) (xy 375.816938 -285.7439) (xy 375.807738 -285.689126) (xy 375.807224 -285.661354)
			(xy 375.807732 -285.635467) (xy 375.815831 -285.584329) (xy 375.83183 -285.535089) (xy 375.855336 -285.488957)
			(xy 375.885768 -285.44707) (xy 375.922378 -285.41046) (xy 375.964265 -285.380028) (xy 376.010397 -285.356522)
			(xy 376.059637 -285.340523) (xy 376.110775 -285.332424) (xy 376.162549 -285.332424) (xy 376.213687 -285.340523)
			(xy 376.262927 -285.356522) (xy 376.309059 -285.380028) (xy 376.350946 -285.41046) (xy 376.387556 -285.44707)
			(xy 376.417988 -285.488957) (xy 376.441494 -285.535089) (xy 376.457493 -285.584329) (xy 376.465592 -285.635467)
			(xy 376.4661 -285.661354) (xy 376.465666 -285.68669) (xy 376.457906 -285.736765) (xy 376.442576 -285.785062)
			(xy 376.420038 -285.830446) (xy 376.390822 -285.871848) (xy 376.355616 -285.908293) (xy 376.315249 -285.938922)
			(xy 376.270671 -285.963016) (xy 376.222931 -285.980006) (xy 376.19813 -285.985204) (xy 376.17527 -285.989522)
			(xy 375.970292 -286.344614) (xy 375.978166 -286.366458) (xy 375.986819 -286.392864) (xy 375.996134 -286.447642)
			(xy 375.996708 -286.475424) (xy 377.216924 -286.475424) (xy 377.217448 -286.45008) (xy 377.225216 -286.399991)
			(xy 377.240559 -286.351681) (xy 377.263115 -286.306288) (xy 377.292351 -286.264882) (xy 377.32758 -286.228438)
			(xy 377.367972 -286.197814) (xy 377.412574 -286.173733) (xy 377.460336 -286.156761) (xy 377.485148 -286.151574)
			(xy 377.508008 -286.147256) (xy 377.712986 -285.792164) (xy 377.705112 -285.77032) (xy 377.696538 -285.7439)
			(xy 377.687338 -285.689126) (xy 377.686824 -285.661354) (xy 377.687332 -285.635467) (xy 377.695431 -285.584329)
			(xy 377.71143 -285.535089) (xy 377.734936 -285.488957) (xy 377.765368 -285.44707) (xy 377.801978 -285.41046)
			(xy 377.843865 -285.380028) (xy 377.889997 -285.356522) (xy 377.939237 -285.340523) (xy 377.990375 -285.332424)
			(xy 378.042149 -285.332424) (xy 378.093287 -285.340523) (xy 378.142527 -285.356522) (xy 378.188659 -285.380028)
			(xy 378.230546 -285.41046) (xy 378.267156 -285.44707) (xy 378.297588 -285.488957) (xy 378.321094 -285.535089)
			(xy 378.337093 -285.584329) (xy 378.345192 -285.635467) (xy 378.3457 -285.661354) (xy 378.345266 -285.68669)
			(xy 378.337506 -285.736765) (xy 378.322176 -285.785062) (xy 378.299638 -285.830446) (xy 378.270422 -285.871848)
			(xy 378.235216 -285.908293) (xy 378.194849 -285.938922) (xy 378.150271 -285.963016) (xy 378.102531 -285.980006)
			(xy 378.07773 -285.985204) (xy 378.05487 -285.989522) (xy 377.849892 -286.344614) (xy 377.857766 -286.366458)
			(xy 377.866419 -286.392864) (xy 377.875734 -286.447642) (xy 377.876308 -286.475424) (xy 379.096524 -286.475424)
			(xy 379.097048 -286.45008) (xy 379.104816 -286.399991) (xy 379.120159 -286.351681) (xy 379.142715 -286.306288)
			(xy 379.171951 -286.264882) (xy 379.20718 -286.228438) (xy 379.247572 -286.197814) (xy 379.292174 -286.173733)
			(xy 379.339936 -286.156761) (xy 379.364748 -286.151574) (xy 379.387608 -286.147256) (xy 379.592586 -285.792164)
			(xy 379.584712 -285.77032) (xy 379.576138 -285.7439) (xy 379.566938 -285.689126) (xy 379.566424 -285.661354)
			(xy 379.566932 -285.635467) (xy 379.575031 -285.584329) (xy 379.59103 -285.535089) (xy 379.614536 -285.488957)
			(xy 379.644968 -285.44707) (xy 379.681578 -285.41046) (xy 379.723465 -285.380028) (xy 379.769597 -285.356522)
			(xy 379.818837 -285.340523) (xy 379.869975 -285.332424) (xy 379.921749 -285.332424) (xy 379.972887 -285.340523)
			(xy 380.022127 -285.356522) (xy 380.068259 -285.380028) (xy 380.110146 -285.41046) (xy 380.146756 -285.44707)
			(xy 380.177188 -285.488957) (xy 380.200694 -285.535089) (xy 380.216693 -285.584329) (xy 380.224792 -285.635467)
			(xy 380.2253 -285.661354) (xy 380.224866 -285.68669) (xy 380.217106 -285.736765) (xy 380.201776 -285.785062)
			(xy 380.179238 -285.830446) (xy 380.150022 -285.871848) (xy 380.114816 -285.908293) (xy 380.074449 -285.938922)
			(xy 380.029871 -285.963016) (xy 379.982131 -285.980006) (xy 379.95733 -285.985204) (xy 379.93447 -285.989522)
			(xy 379.729492 -286.344614) (xy 379.737366 -286.366458) (xy 379.746019 -286.392864) (xy 379.755334 -286.447642)
			(xy 379.755908 -286.475424) (xy 380.976124 -286.475424) (xy 380.976648 -286.45008) (xy 380.984416 -286.399991)
			(xy 380.999759 -286.351681) (xy 381.022315 -286.306288) (xy 381.051551 -286.264882) (xy 381.08678 -286.228438)
			(xy 381.127172 -286.197814) (xy 381.171774 -286.173733) (xy 381.219536 -286.156761) (xy 381.244348 -286.151574)
			(xy 381.267208 -286.147256) (xy 381.472186 -285.792164) (xy 381.464312 -285.77032) (xy 381.455738 -285.7439)
			(xy 381.446538 -285.689126) (xy 381.446024 -285.661354) (xy 381.446532 -285.635467) (xy 381.454631 -285.584329)
			(xy 381.47063 -285.535089) (xy 381.494136 -285.488957) (xy 381.524568 -285.44707) (xy 381.561178 -285.41046)
			(xy 381.603065 -285.380028) (xy 381.649197 -285.356522) (xy 381.698437 -285.340523) (xy 381.749575 -285.332424)
			(xy 381.801349 -285.332424) (xy 381.852487 -285.340523) (xy 381.901727 -285.356522) (xy 381.947859 -285.380028)
			(xy 381.989746 -285.41046) (xy 382.026356 -285.44707) (xy 382.056788 -285.488957) (xy 382.080294 -285.535089)
			(xy 382.096293 -285.584329) (xy 382.104392 -285.635467) (xy 382.1049 -285.661354) (xy 382.104466 -285.68669)
			(xy 382.096706 -285.736765) (xy 382.081376 -285.785062) (xy 382.058838 -285.830446) (xy 382.029622 -285.871848)
			(xy 381.994416 -285.908293) (xy 381.954049 -285.938922) (xy 381.909471 -285.963016) (xy 381.861731 -285.980006)
			(xy 381.83693 -285.985204) (xy 381.81407 -285.989522) (xy 381.609092 -286.344614) (xy 381.616966 -286.366458)
			(xy 381.625619 -286.392864) (xy 381.634934 -286.447642) (xy 381.635508 -286.475424) (xy 381.635 -286.501331)
			(xy 381.626894 -286.552508) (xy 381.610882 -286.601787) (xy 381.587359 -286.647954) (xy 381.556903 -286.689873)
			(xy 381.520265 -286.726511) (xy 381.478346 -286.756967) (xy 381.432179 -286.78049) (xy 381.3829 -286.796502)
			(xy 381.331723 -286.804608) (xy 381.279909 -286.804608) (xy 381.228732 -286.796502) (xy 381.179453 -286.78049)
			(xy 381.133286 -286.756967) (xy 381.091367 -286.726511) (xy 381.054729 -286.689873) (xy 381.024273 -286.647954)
			(xy 381.00075 -286.601787) (xy 380.984738 -286.552508) (xy 380.976632 -286.501331) (xy 380.976124 -286.475424)
			(xy 379.755908 -286.475424) (xy 379.7554 -286.501331) (xy 379.747294 -286.552508) (xy 379.731282 -286.601787)
			(xy 379.707759 -286.647954) (xy 379.677303 -286.689873) (xy 379.640665 -286.726511) (xy 379.598746 -286.756967)
			(xy 379.552579 -286.78049) (xy 379.5033 -286.796502) (xy 379.452123 -286.804608) (xy 379.400309 -286.804608)
			(xy 379.349132 -286.796502) (xy 379.299853 -286.78049) (xy 379.253686 -286.756967) (xy 379.211767 -286.726511)
			(xy 379.175129 -286.689873) (xy 379.144673 -286.647954) (xy 379.12115 -286.601787) (xy 379.105138 -286.552508)
			(xy 379.097032 -286.501331) (xy 379.096524 -286.475424) (xy 377.876308 -286.475424) (xy 377.8758 -286.501331)
			(xy 377.867694 -286.552508) (xy 377.851682 -286.601787) (xy 377.828159 -286.647954) (xy 377.797703 -286.689873)
			(xy 377.761065 -286.726511) (xy 377.719146 -286.756967) (xy 377.672979 -286.78049) (xy 377.6237 -286.796502)
			(xy 377.572523 -286.804608) (xy 377.520709 -286.804608) (xy 377.469532 -286.796502) (xy 377.420253 -286.78049)
			(xy 377.374086 -286.756967) (xy 377.332167 -286.726511) (xy 377.295529 -286.689873) (xy 377.265073 -286.647954)
			(xy 377.24155 -286.601787) (xy 377.225538 -286.552508) (xy 377.217432 -286.501331) (xy 377.216924 -286.475424)
			(xy 375.996708 -286.475424) (xy 375.9962 -286.501331) (xy 375.988094 -286.552508) (xy 375.972082 -286.601787)
			(xy 375.948559 -286.647954) (xy 375.918103 -286.689873) (xy 375.881465 -286.726511) (xy 375.839546 -286.756967)
			(xy 375.793379 -286.78049) (xy 375.7441 -286.796502) (xy 375.692923 -286.804608) (xy 375.641109 -286.804608)
			(xy 375.589932 -286.796502) (xy 375.540653 -286.78049) (xy 375.494486 -286.756967) (xy 375.452567 -286.726511)
			(xy 375.415929 -286.689873) (xy 375.385473 -286.647954) (xy 375.36195 -286.601787) (xy 375.345938 -286.552508)
			(xy 375.337832 -286.501331) (xy 375.337324 -286.475424) (xy 374.117108 -286.475424) (xy 374.1166 -286.501331)
			(xy 374.108494 -286.552508) (xy 374.092482 -286.601787) (xy 374.068959 -286.647954) (xy 374.038503 -286.689873)
			(xy 374.001865 -286.726511) (xy 373.959946 -286.756967) (xy 373.913779 -286.78049) (xy 373.8645 -286.796502)
			(xy 373.813323 -286.804608) (xy 373.761509 -286.804608) (xy 373.710332 -286.796502) (xy 373.661053 -286.78049)
			(xy 373.614886 -286.756967) (xy 373.572967 -286.726511) (xy 373.536329 -286.689873) (xy 373.505873 -286.647954)
			(xy 373.48235 -286.601787) (xy 373.466338 -286.552508) (xy 373.458232 -286.501331) (xy 373.457724 -286.475424)
			(xy 372.237508 -286.475424) (xy 372.237 -286.501331) (xy 372.228894 -286.552508) (xy 372.212882 -286.601787)
			(xy 372.189359 -286.647954) (xy 372.158903 -286.689873) (xy 372.122265 -286.726511) (xy 372.080346 -286.756967)
			(xy 372.034179 -286.78049) (xy 371.9849 -286.796502) (xy 371.933723 -286.804608) (xy 371.881909 -286.804608)
			(xy 371.830732 -286.796502) (xy 371.781453 -286.78049) (xy 371.735286 -286.756967) (xy 371.693367 -286.726511)
			(xy 371.656729 -286.689873) (xy 371.626273 -286.647954) (xy 371.60275 -286.601787) (xy 371.586738 -286.552508)
			(xy 371.578632 -286.501331) (xy 371.578124 -286.475424) (xy 370.357908 -286.475424) (xy 370.3574 -286.501331)
			(xy 370.349294 -286.552508) (xy 370.333282 -286.601787) (xy 370.309759 -286.647954) (xy 370.279303 -286.689873)
			(xy 370.242665 -286.726511) (xy 370.200746 -286.756967) (xy 370.154579 -286.78049) (xy 370.1053 -286.796502)
			(xy 370.054123 -286.804608) (xy 370.002309 -286.804608) (xy 369.951132 -286.796502) (xy 369.901853 -286.78049)
			(xy 369.855686 -286.756967) (xy 369.813767 -286.726511) (xy 369.777129 -286.689873) (xy 369.746673 -286.647954)
			(xy 369.72315 -286.601787) (xy 369.707138 -286.552508) (xy 369.699032 -286.501331) (xy 369.698524 -286.475424)
			(xy 368.478308 -286.475424) (xy 368.4778 -286.501331) (xy 368.469694 -286.552508) (xy 368.453682 -286.601787)
			(xy 368.430159 -286.647954) (xy 368.399703 -286.689873) (xy 368.363065 -286.726511) (xy 368.321146 -286.756967)
			(xy 368.274979 -286.78049) (xy 368.2257 -286.796502) (xy 368.174523 -286.804608) (xy 368.122709 -286.804608)
			(xy 368.071532 -286.796502) (xy 368.022253 -286.78049) (xy 367.976086 -286.756967) (xy 367.934167 -286.726511)
			(xy 367.897529 -286.689873) (xy 367.867073 -286.647954) (xy 367.84355 -286.601787) (xy 367.827538 -286.552508)
			(xy 367.819432 -286.501331) (xy 367.818924 -286.475424) (xy 351.561908 -286.475424) (xy 351.5614 -286.501331)
			(xy 351.553294 -286.552508) (xy 351.537282 -286.601787) (xy 351.513759 -286.647954) (xy 351.483303 -286.689873)
			(xy 351.446665 -286.726511) (xy 351.404746 -286.756967) (xy 351.358579 -286.78049) (xy 351.3093 -286.796502)
			(xy 351.258123 -286.804608) (xy 351.206309 -286.804608) (xy 351.155132 -286.796502) (xy 351.105853 -286.78049)
			(xy 351.059686 -286.756967) (xy 351.017767 -286.726511) (xy 350.981129 -286.689873) (xy 350.950673 -286.647954)
			(xy 350.92715 -286.601787) (xy 350.911138 -286.552508) (xy 350.903032 -286.501331) (xy 350.902524 -286.475424)
			(xy 350.903123 -286.447707) (xy 350.912443 -286.39306) (xy 350.921066 -286.366712) (xy 350.92894 -286.344614)
			(xy 350.723962 -285.989522) (xy 350.700848 -285.985204) (xy 350.676027 -285.980039) (xy 350.628247 -285.963084)
			(xy 350.583628 -285.939012) (xy 350.543222 -285.908392) (xy 350.507981 -285.871945) (xy 350.478737 -285.830531)
			(xy 350.45618 -285.785127) (xy 350.440843 -285.736804) (xy 350.433086 -285.686703) (xy 350.432624 -285.661354)
			(xy 350.1517 -285.661354) (xy 350.151192 -285.687241) (xy 350.143093 -285.738379) (xy 350.127094 -285.787619)
			(xy 350.103588 -285.833751) (xy 350.073156 -285.875638) (xy 350.036546 -285.912248) (xy 349.994659 -285.94268)
			(xy 349.948527 -285.966186) (xy 349.899287 -285.982185) (xy 349.848149 -285.990284) (xy 349.796375 -285.990284)
			(xy 349.745237 -285.982185) (xy 349.695997 -285.966186) (xy 349.649865 -285.94268) (xy 349.607978 -285.912248)
			(xy 349.571368 -285.875638) (xy 349.540936 -285.833751) (xy 349.51743 -285.787619) (xy 349.501431 -285.738379)
			(xy 349.493332 -285.687241) (xy 349.492824 -285.661354) (xy 349.2119 -285.661354) (xy 349.2119 -285.661862)
			(xy 349.211323 -285.689379) (xy 349.202128 -285.74364) (xy 349.193612 -285.769812) (xy 349.185992 -285.79191)
			(xy 349.391224 -286.147256) (xy 349.414084 -286.151574) (xy 349.438906 -286.156737) (xy 349.486683 -286.173695)
			(xy 349.531301 -286.197768) (xy 349.571706 -286.22839) (xy 349.606946 -286.264837) (xy 349.636189 -286.30625)
			(xy 349.658746 -286.351653) (xy 349.674085 -286.399975) (xy 349.681845 -286.450075) (xy 349.682308 -286.475424)
			(xy 349.6818 -286.501331) (xy 349.673694 -286.552508) (xy 349.657682 -286.601787) (xy 349.634159 -286.647954)
			(xy 349.603703 -286.689873) (xy 349.567065 -286.726511) (xy 349.525146 -286.756967) (xy 349.478979 -286.78049)
			(xy 349.4297 -286.796502) (xy 349.378523 -286.804608) (xy 349.326709 -286.804608) (xy 349.275532 -286.796502)
			(xy 349.226253 -286.78049) (xy 349.180086 -286.756967) (xy 349.138167 -286.726511) (xy 349.101529 -286.689873)
			(xy 349.071073 -286.647954) (xy 349.04755 -286.601787) (xy 349.031538 -286.552508) (xy 349.023432 -286.501331)
			(xy 349.022924 -286.475424) (xy 349.023523 -286.447707) (xy 349.032843 -286.39306) (xy 349.041466 -286.366712)
			(xy 349.04934 -286.344614) (xy 348.844362 -285.989522) (xy 348.821248 -285.985204) (xy 348.796427 -285.980039)
			(xy 348.748647 -285.963084) (xy 348.704028 -285.939012) (xy 348.663622 -285.908392) (xy 348.628381 -285.871945)
			(xy 348.599137 -285.830531) (xy 348.57658 -285.785127) (xy 348.561243 -285.736804) (xy 348.553486 -285.686703)
			(xy 348.553024 -285.661354) (xy 348.2721 -285.661354) (xy 348.271592 -285.687241) (xy 348.263493 -285.738379)
			(xy 348.247494 -285.787619) (xy 348.223988 -285.833751) (xy 348.193556 -285.875638) (xy 348.156946 -285.912248)
			(xy 348.115059 -285.94268) (xy 348.068927 -285.966186) (xy 348.019687 -285.982185) (xy 347.968549 -285.990284)
			(xy 347.916775 -285.990284) (xy 347.865637 -285.982185) (xy 347.816397 -285.966186) (xy 347.770265 -285.94268)
			(xy 347.728378 -285.912248) (xy 347.691768 -285.875638) (xy 347.661336 -285.833751) (xy 347.63783 -285.787619)
			(xy 347.621831 -285.738379) (xy 347.613732 -285.687241) (xy 347.613224 -285.661354) (xy 347.3323 -285.661354)
			(xy 347.3323 -285.661862) (xy 347.331723 -285.689379) (xy 347.322528 -285.74364) (xy 347.314012 -285.769812)
			(xy 347.306392 -285.79191) (xy 347.511624 -286.147256) (xy 347.534484 -286.151574) (xy 347.559306 -286.156737)
			(xy 347.607083 -286.173695) (xy 347.651701 -286.197768) (xy 347.692106 -286.22839) (xy 347.727346 -286.264837)
			(xy 347.756589 -286.30625) (xy 347.779146 -286.351653) (xy 347.794485 -286.399975) (xy 347.802245 -286.450075)
			(xy 347.802708 -286.475424) (xy 347.8022 -286.501331) (xy 347.794094 -286.552508) (xy 347.778082 -286.601787)
			(xy 347.754559 -286.647954) (xy 347.724103 -286.689873) (xy 347.687465 -286.726511) (xy 347.645546 -286.756967)
			(xy 347.599379 -286.78049) (xy 347.5501 -286.796502) (xy 347.498923 -286.804608) (xy 347.447109 -286.804608)
			(xy 347.395932 -286.796502) (xy 347.346653 -286.78049) (xy 347.300486 -286.756967) (xy 347.258567 -286.726511)
			(xy 347.221929 -286.689873) (xy 347.191473 -286.647954) (xy 347.16795 -286.601787) (xy 347.151938 -286.552508)
			(xy 347.143832 -286.501331) (xy 347.143324 -286.475424) (xy 347.143923 -286.447707) (xy 347.153243 -286.39306)
			(xy 347.161866 -286.366712) (xy 347.16974 -286.344614) (xy 346.964762 -285.989522) (xy 346.941648 -285.985204)
			(xy 346.916827 -285.980039) (xy 346.869047 -285.963084) (xy 346.824428 -285.939012) (xy 346.784022 -285.908392)
			(xy 346.748781 -285.871945) (xy 346.719537 -285.830531) (xy 346.69698 -285.785127) (xy 346.681643 -285.736804)
			(xy 346.673886 -285.686703) (xy 346.673424 -285.661354) (xy 346.3925 -285.661354) (xy 346.391992 -285.687241)
			(xy 346.383893 -285.738379) (xy 346.367894 -285.787619) (xy 346.344388 -285.833751) (xy 346.313956 -285.875638)
			(xy 346.277346 -285.912248) (xy 346.235459 -285.94268) (xy 346.189327 -285.966186) (xy 346.140087 -285.982185)
			(xy 346.088949 -285.990284) (xy 346.037175 -285.990284) (xy 345.986037 -285.982185) (xy 345.936797 -285.966186)
			(xy 345.890665 -285.94268) (xy 345.848778 -285.912248) (xy 345.812168 -285.875638) (xy 345.781736 -285.833751)
			(xy 345.75823 -285.787619) (xy 345.742231 -285.738379) (xy 345.734132 -285.687241) (xy 345.733624 -285.661354)
			(xy 345.4527 -285.661354) (xy 345.4527 -285.661862) (xy 345.452123 -285.689379) (xy 345.442928 -285.74364)
			(xy 345.434412 -285.769812) (xy 345.426792 -285.79191) (xy 345.632024 -286.147256) (xy 345.654884 -286.151574)
			(xy 345.679706 -286.156737) (xy 345.727483 -286.173695) (xy 345.772101 -286.197768) (xy 345.812506 -286.22839)
			(xy 345.847746 -286.264837) (xy 345.876989 -286.30625) (xy 345.899546 -286.351653) (xy 345.914885 -286.399975)
			(xy 345.922645 -286.450075) (xy 345.923108 -286.475424) (xy 345.9226 -286.501331) (xy 345.914494 -286.552508)
			(xy 345.898482 -286.601787) (xy 345.874959 -286.647954) (xy 345.844503 -286.689873) (xy 345.807865 -286.726511)
			(xy 345.765946 -286.756967) (xy 345.719779 -286.78049) (xy 345.6705 -286.796502) (xy 345.619323 -286.804608)
			(xy 345.567509 -286.804608) (xy 345.516332 -286.796502) (xy 345.467053 -286.78049) (xy 345.420886 -286.756967)
			(xy 345.378967 -286.726511) (xy 345.342329 -286.689873) (xy 345.311873 -286.647954) (xy 345.28835 -286.601787)
			(xy 345.272338 -286.552508) (xy 345.264232 -286.501331) (xy 345.263724 -286.475424) (xy 345.264323 -286.447707)
			(xy 345.273643 -286.39306) (xy 345.282266 -286.366712) (xy 345.29014 -286.344614) (xy 345.085162 -285.989522)
			(xy 345.062048 -285.985204) (xy 345.037227 -285.980039) (xy 344.989447 -285.963084) (xy 344.944828 -285.939012)
			(xy 344.904422 -285.908392) (xy 344.869181 -285.871945) (xy 344.839937 -285.830531) (xy 344.81738 -285.785127)
			(xy 344.802043 -285.736804) (xy 344.794286 -285.686703) (xy 344.793824 -285.661354) (xy 344.5129 -285.661354)
			(xy 344.512392 -285.687241) (xy 344.504293 -285.738379) (xy 344.488294 -285.787619) (xy 344.464788 -285.833751)
			(xy 344.434356 -285.875638) (xy 344.397746 -285.912248) (xy 344.355859 -285.94268) (xy 344.309727 -285.966186)
			(xy 344.260487 -285.982185) (xy 344.209349 -285.990284) (xy 344.157575 -285.990284) (xy 344.106437 -285.982185)
			(xy 344.057197 -285.966186) (xy 344.011065 -285.94268) (xy 343.969178 -285.912248) (xy 343.932568 -285.875638)
			(xy 343.902136 -285.833751) (xy 343.87863 -285.787619) (xy 343.862631 -285.738379) (xy 343.854532 -285.687241)
			(xy 343.854024 -285.661354) (xy 343.5731 -285.661354) (xy 343.5731 -285.661862) (xy 343.572523 -285.689379)
			(xy 343.563328 -285.74364) (xy 343.554812 -285.769812) (xy 343.547192 -285.79191) (xy 343.752424 -286.147256)
			(xy 343.775284 -286.151574) (xy 343.800106 -286.156737) (xy 343.847883 -286.173695) (xy 343.892501 -286.197768)
			(xy 343.932906 -286.22839) (xy 343.968146 -286.264837) (xy 343.997389 -286.30625) (xy 344.019946 -286.351653)
			(xy 344.035285 -286.399975) (xy 344.043045 -286.450075) (xy 344.043508 -286.475424) (xy 344.043 -286.501331)
			(xy 344.034894 -286.552508) (xy 344.018882 -286.601787) (xy 343.995359 -286.647954) (xy 343.964903 -286.689873)
			(xy 343.928265 -286.726511) (xy 343.886346 -286.756967) (xy 343.840179 -286.78049) (xy 343.7909 -286.796502)
			(xy 343.739723 -286.804608) (xy 343.687909 -286.804608) (xy 343.636732 -286.796502) (xy 343.587453 -286.78049)
			(xy 343.541286 -286.756967) (xy 343.499367 -286.726511) (xy 343.462729 -286.689873) (xy 343.432273 -286.647954)
			(xy 343.40875 -286.601787) (xy 343.392738 -286.552508) (xy 343.384632 -286.501331) (xy 343.384124 -286.475424)
			(xy 343.384723 -286.447707) (xy 343.394043 -286.39306) (xy 343.402666 -286.366712) (xy 343.41054 -286.344614)
			(xy 343.205562 -285.989522) (xy 343.182448 -285.985204) (xy 343.157627 -285.980039) (xy 343.109847 -285.963084)
			(xy 343.065228 -285.939012) (xy 343.024822 -285.908392) (xy 342.989581 -285.871945) (xy 342.960337 -285.830531)
			(xy 342.93778 -285.785127) (xy 342.922443 -285.736804) (xy 342.914686 -285.686703) (xy 342.914224 -285.661354)
			(xy 342.6333 -285.661354) (xy 342.632792 -285.687241) (xy 342.624693 -285.738379) (xy 342.608694 -285.787619)
			(xy 342.585188 -285.833751) (xy 342.554756 -285.875638) (xy 342.518146 -285.912248) (xy 342.476259 -285.94268)
			(xy 342.430127 -285.966186) (xy 342.380887 -285.982185) (xy 342.329749 -285.990284) (xy 342.277975 -285.990284)
			(xy 342.226837 -285.982185) (xy 342.177597 -285.966186) (xy 342.131465 -285.94268) (xy 342.089578 -285.912248)
			(xy 342.052968 -285.875638) (xy 342.022536 -285.833751) (xy 341.99903 -285.787619) (xy 341.983031 -285.738379)
			(xy 341.974932 -285.687241) (xy 341.974424 -285.661354) (xy 341.6935 -285.661354) (xy 341.6935 -285.661862)
			(xy 341.692923 -285.689379) (xy 341.683728 -285.74364) (xy 341.675212 -285.769812) (xy 341.667592 -285.79191)
			(xy 341.872824 -286.147256) (xy 341.895684 -286.151574) (xy 341.920506 -286.156737) (xy 341.968283 -286.173695)
			(xy 342.012901 -286.197768) (xy 342.053306 -286.22839) (xy 342.088546 -286.264837) (xy 342.117789 -286.30625)
			(xy 342.140346 -286.351653) (xy 342.155685 -286.399975) (xy 342.163445 -286.450075) (xy 342.163908 -286.475424)
			(xy 342.1634 -286.501331) (xy 342.155294 -286.552508) (xy 342.139282 -286.601787) (xy 342.115759 -286.647954)
			(xy 342.085303 -286.689873) (xy 342.048665 -286.726511) (xy 342.006746 -286.756967) (xy 341.960579 -286.78049)
			(xy 341.9113 -286.796502) (xy 341.860123 -286.804608) (xy 341.808309 -286.804608) (xy 341.757132 -286.796502)
			(xy 341.707853 -286.78049) (xy 341.661686 -286.756967) (xy 341.619767 -286.726511) (xy 341.583129 -286.689873)
			(xy 341.552673 -286.647954) (xy 341.52915 -286.601787) (xy 341.513138 -286.552508) (xy 341.505032 -286.501331)
			(xy 341.504524 -286.475424) (xy 341.505123 -286.447707) (xy 341.514443 -286.39306) (xy 341.523066 -286.366712)
			(xy 341.53094 -286.344614) (xy 341.325962 -285.989522) (xy 341.302848 -285.985204) (xy 341.278027 -285.980039)
			(xy 341.230247 -285.963084) (xy 341.185628 -285.939012) (xy 341.145222 -285.908392) (xy 341.109981 -285.871945)
			(xy 341.080737 -285.830531) (xy 341.05818 -285.785127) (xy 341.042843 -285.736804) (xy 341.035086 -285.686703)
			(xy 341.034624 -285.661354) (xy 340.7537 -285.661354) (xy 340.753192 -285.687241) (xy 340.745093 -285.738379)
			(xy 340.729094 -285.787619) (xy 340.705588 -285.833751) (xy 340.675156 -285.875638) (xy 340.638546 -285.912248)
			(xy 340.596659 -285.94268) (xy 340.550527 -285.966186) (xy 340.501287 -285.982185) (xy 340.450149 -285.990284)
			(xy 340.398375 -285.990284) (xy 340.347237 -285.982185) (xy 340.297997 -285.966186) (xy 340.251865 -285.94268)
			(xy 340.209978 -285.912248) (xy 340.173368 -285.875638) (xy 340.142936 -285.833751) (xy 340.11943 -285.787619)
			(xy 340.103431 -285.738379) (xy 340.095332 -285.687241) (xy 340.094824 -285.661354) (xy 339.814408 -285.661354)
			(xy 339.813802 -285.689071) (xy 339.804487 -285.743717) (xy 339.795866 -285.770066) (xy 339.787992 -285.792164)
			(xy 339.993224 -286.147256) (xy 340.016084 -286.151574) (xy 340.040906 -286.156737) (xy 340.088683 -286.173695)
			(xy 340.133301 -286.197768) (xy 340.173706 -286.22839) (xy 340.208946 -286.264837) (xy 340.238189 -286.30625)
			(xy 340.260746 -286.351653) (xy 340.276085 -286.399975) (xy 340.283845 -286.450075) (xy 340.284308 -286.475424)
			(xy 340.2838 -286.501331) (xy 340.275694 -286.552508) (xy 340.259682 -286.601787) (xy 340.236159 -286.647954)
			(xy 340.205703 -286.689873) (xy 340.169065 -286.726511) (xy 340.127146 -286.756967) (xy 340.080979 -286.78049)
			(xy 340.0317 -286.796502) (xy 339.980523 -286.804608) (xy 339.928709 -286.804608) (xy 339.877532 -286.796502)
			(xy 339.828253 -286.78049) (xy 339.782086 -286.756967) (xy 339.740167 -286.726511) (xy 339.703529 -286.689873)
			(xy 339.673073 -286.647954) (xy 339.64955 -286.601787) (xy 339.633538 -286.552508) (xy 339.625432 -286.501331)
			(xy 339.624924 -286.475424) (xy 339.625523 -286.447707) (xy 339.634843 -286.39306) (xy 339.643466 -286.366712)
			(xy 339.65134 -286.344614) (xy 339.446108 -285.989522) (xy 339.423248 -285.985204) (xy 339.398427 -285.980039)
			(xy 339.350647 -285.963084) (xy 339.306028 -285.939012) (xy 339.265622 -285.908392) (xy 339.230381 -285.871945)
			(xy 339.201137 -285.830531) (xy 339.17858 -285.785127) (xy 339.163243 -285.736804) (xy 339.155486 -285.686703)
			(xy 339.155024 -285.661354) (xy 338.874608 -285.661354) (xy 338.8741 -285.687261) (xy 338.865994 -285.738438)
			(xy 338.849982 -285.787717) (xy 338.826459 -285.833884) (xy 338.796003 -285.875803) (xy 338.759365 -285.912441)
			(xy 338.717446 -285.942897) (xy 338.671279 -285.96642) (xy 338.622 -285.982432) (xy 338.570823 -285.990538)
			(xy 338.519009 -285.990538) (xy 338.467832 -285.982432) (xy 338.418553 -285.96642) (xy 338.372386 -285.942897)
			(xy 338.330467 -285.912441) (xy 338.293829 -285.875803) (xy 338.263373 -285.833884) (xy 338.23985 -285.787717)
			(xy 338.223838 -285.738438) (xy 338.215732 -285.687261) (xy 338.215224 -285.661354) (xy 337.9343 -285.661354)
			(xy 337.933759 -285.689062) (xy 337.924571 -285.743708) (xy 337.916012 -285.770066) (xy 337.908138 -285.792164)
			(xy 338.11337 -286.147256) (xy 338.13623 -286.151574) (xy 338.16104 -286.156732) (xy 338.20878 -286.173726)
			(xy 338.253357 -286.197824) (xy 338.293722 -286.228459) (xy 338.328925 -286.264909) (xy 338.358136 -286.306317)
			(xy 338.380667 -286.351707) (xy 338.395988 -286.400009) (xy 338.403738 -286.450087) (xy 338.4042 -286.475424)
			(xy 338.403692 -286.501311) (xy 338.395593 -286.552449) (xy 338.379594 -286.601689) (xy 338.356088 -286.647821)
			(xy 338.325656 -286.689708) (xy 338.289046 -286.726318) (xy 338.247159 -286.75675) (xy 338.201027 -286.780256)
			(xy 338.151787 -286.796255) (xy 338.100649 -286.804354) (xy 338.048875 -286.804354) (xy 337.997737 -286.796255)
			(xy 337.948497 -286.780256) (xy 337.902365 -286.75675) (xy 337.860478 -286.726318) (xy 337.823868 -286.689708)
			(xy 337.793436 -286.647821) (xy 337.76993 -286.601689) (xy 337.753931 -286.552449) (xy 337.745832 -286.501311)
			(xy 337.745324 -286.475424) (xy 337.745858 -286.447716) (xy 337.75505 -286.393069) (xy 337.763612 -286.366712)
			(xy 337.771486 -286.344614) (xy 337.566254 -285.989522) (xy 337.543394 -285.985204) (xy 337.518583 -285.980049)
			(xy 337.470842 -285.963057) (xy 337.426263 -285.93896) (xy 337.385896 -285.908325) (xy 337.350693 -285.871874)
			(xy 337.321482 -285.830466) (xy 337.298951 -285.785075) (xy 337.283632 -285.736771) (xy 337.275885 -285.686692)
			(xy 337.275424 -285.661354) (xy 336.0547 -285.661354) (xy 336.054192 -285.687241) (xy 336.046093 -285.738379)
			(xy 336.030094 -285.787619) (xy 336.006588 -285.833751) (xy 335.976156 -285.875638) (xy 335.939546 -285.912248)
			(xy 335.897659 -285.94268) (xy 335.851527 -285.966186) (xy 335.802287 -285.982185) (xy 335.751149 -285.990284)
			(xy 335.699375 -285.990284) (xy 335.648237 -285.982185) (xy 335.598997 -285.966186) (xy 335.552865 -285.94268)
			(xy 335.510978 -285.912248) (xy 335.474368 -285.875638) (xy 335.443936 -285.833751) (xy 335.42043 -285.787619)
			(xy 335.404431 -285.738379) (xy 335.396332 -285.687241) (xy 335.395824 -285.661354) (xy 134.164832 -285.661354)
			(xy 134.164372 -285.686689) (xy 134.156613 -285.736761) (xy 134.141285 -285.785057) (xy 134.118749 -285.830439)
			(xy 134.089536 -285.87184) (xy 134.054334 -285.908285) (xy 134.013971 -285.938915) (xy 133.969397 -285.963011)
			(xy 133.921662 -285.980004) (xy 133.896862 -285.985204) (xy 133.874002 -285.989522) (xy 133.669024 -286.344614)
			(xy 133.676898 -286.366458) (xy 133.685549 -286.392865) (xy 133.694866 -286.447642) (xy 133.69544 -286.475424)
			(xy 333.986124 -286.475424) (xy 333.986632 -286.449537) (xy 333.994731 -286.398399) (xy 334.01073 -286.349159)
			(xy 334.034236 -286.303027) (xy 334.064668 -286.26114) (xy 334.101278 -286.22453) (xy 334.143165 -286.194098)
			(xy 334.189297 -286.170592) (xy 334.238537 -286.154593) (xy 334.289675 -286.146494) (xy 334.341449 -286.146494)
			(xy 334.392587 -286.154593) (xy 334.441827 -286.170592) (xy 334.487959 -286.194098) (xy 334.529846 -286.22453)
			(xy 334.566456 -286.26114) (xy 334.596888 -286.303027) (xy 334.620394 -286.349159) (xy 334.636393 -286.398399)
			(xy 334.644492 -286.449537) (xy 334.645 -286.475424) (xy 334.644511 -286.501304) (xy 334.92624 -286.501304)
			(xy 334.92624 -286.449496) (xy 334.934344 -286.398327) (xy 334.950352 -286.349055) (xy 334.97387 -286.302894)
			(xy 335.00432 -286.26098) (xy 335.040951 -286.224345) (xy 335.082862 -286.19389) (xy 335.12902 -286.170367)
			(xy 335.17829 -286.154353) (xy 335.229459 -286.146243) (xy 335.255362 -286.145732) (xy 335.280855 -286.146231)
			(xy 335.331232 -286.154087) (xy 335.379796 -286.169618) (xy 335.425383 -286.192452) (xy 335.466904 -286.222042)
			(xy 335.503366 -286.257681) (xy 335.519014 -286.277812) (xy 335.93151 -286.277812) (xy 335.947185 -286.257701)
			(xy 335.98364 -286.222058) (xy 336.025155 -286.192461) (xy 336.070737 -286.16962) (xy 336.119296 -286.15408)
			(xy 336.16967 -286.146213) (xy 336.195162 -286.145732) (xy 336.221075 -286.146163) (xy 336.272264 -286.154265)
			(xy 336.321556 -286.170276) (xy 336.367735 -286.193801) (xy 336.409666 -286.22426) (xy 336.446315 -286.260905)
			(xy 336.47678 -286.302832) (xy 336.50031 -286.349009) (xy 336.516326 -286.398299) (xy 336.524434 -286.449487)
			(xy 336.524434 -286.501313) (xy 336.516326 -286.552501) (xy 336.50031 -286.601791) (xy 336.47678 -286.647968)
			(xy 336.446315 -286.689895) (xy 336.409666 -286.72654) (xy 336.367735 -286.756999) (xy 336.321556 -286.780524)
			(xy 336.272264 -286.796535) (xy 336.221075 -286.804637) (xy 336.195162 -286.805116) (xy 336.169668 -286.804653)
			(xy 336.11929 -286.796786) (xy 336.070727 -286.781247) (xy 336.02514 -286.758407) (xy 335.98362 -286.728811)
			(xy 335.947158 -286.693169) (xy 335.93151 -286.673036) (xy 335.519014 -286.673036) (xy 335.503397 -286.693193)
			(xy 335.466928 -286.728832) (xy 335.425401 -286.758421) (xy 335.379808 -286.781254) (xy 335.33124 -286.796785)
			(xy 335.280857 -286.804641) (xy 335.255362 -286.805116) (xy 335.229459 -286.804557) (xy 335.17829 -286.796447)
			(xy 335.12902 -286.780433) (xy 335.082862 -286.75691) (xy 335.040951 -286.726455) (xy 335.00432 -286.68982)
			(xy 334.97387 -286.647906) (xy 334.950352 -286.601745) (xy 334.934344 -286.552473) (xy 334.92624 -286.501304)
			(xy 334.644511 -286.501304) (xy 334.644476 -286.503132) (xy 334.635277 -286.557779) (xy 334.626712 -286.584136)
			(xy 334.619092 -286.60598) (xy 334.82407 -286.961072) (xy 334.84693 -286.96539) (xy 334.871744 -286.970533)
			(xy 334.919484 -286.987528) (xy 334.964063 -287.011628) (xy 335.004428 -287.042264) (xy 335.039631 -287.078717)
			(xy 335.068841 -287.120126) (xy 335.091372 -287.165518) (xy 335.106691 -287.213822) (xy 335.114439 -287.263902)
			(xy 335.1149 -287.28924) (xy 335.114392 -287.315127) (xy 335.106293 -287.366265) (xy 335.090294 -287.415505)
			(xy 335.066788 -287.461637) (xy 335.036356 -287.503524) (xy 334.999746 -287.540134) (xy 334.957859 -287.570566)
			(xy 334.911727 -287.594072) (xy 334.862487 -287.610071) (xy 334.811349 -287.61817) (xy 334.759575 -287.61817)
			(xy 334.708437 -287.610071) (xy 334.659197 -287.594072) (xy 334.613065 -287.570566) (xy 334.571178 -287.540134)
			(xy 334.534568 -287.503524) (xy 334.504136 -287.461637) (xy 334.48063 -287.415505) (xy 334.464631 -287.366265)
			(xy 334.456532 -287.315127) (xy 334.456024 -287.28924) (xy 334.456562 -287.261532) (xy 334.465751 -287.206885)
			(xy 334.474312 -287.180528) (xy 334.481932 -287.158684) (xy 334.276954 -286.803592) (xy 334.254094 -286.799274)
			(xy 334.229299 -286.794053) (xy 334.181562 -286.777067) (xy 334.136987 -286.752976) (xy 334.096622 -286.722349)
			(xy 334.061419 -286.685906) (xy 334.032206 -286.644507) (xy 334.009672 -286.599125) (xy 333.994346 -286.55083)
			(xy 333.98659 -286.500758) (xy 333.986124 -286.475424) (xy 133.69544 -286.475424) (xy 133.694932 -286.501331)
			(xy 133.686826 -286.552508) (xy 133.670814 -286.601787) (xy 133.647291 -286.647954) (xy 133.616835 -286.689873)
			(xy 133.580197 -286.726511) (xy 133.538278 -286.756967) (xy 133.492111 -286.78049) (xy 133.442832 -286.796502)
			(xy 133.391655 -286.804608) (xy 133.339841 -286.804608) (xy 133.288664 -286.796502) (xy 133.239385 -286.78049)
			(xy 133.193218 -286.756967) (xy 133.151299 -286.726511) (xy 133.114661 -286.689873) (xy 133.084205 -286.647954)
			(xy 133.060682 -286.601787) (xy 133.04467 -286.552508) (xy 133.036564 -286.501331) (xy 133.036056 -286.475424)
			(xy 131.81584 -286.475424) (xy 131.815332 -286.501331) (xy 131.807226 -286.552508) (xy 131.791214 -286.601787)
			(xy 131.767691 -286.647954) (xy 131.737235 -286.689873) (xy 131.700597 -286.726511) (xy 131.658678 -286.756967)
			(xy 131.612511 -286.78049) (xy 131.563232 -286.796502) (xy 131.512055 -286.804608) (xy 131.460241 -286.804608)
			(xy 131.409064 -286.796502) (xy 131.359785 -286.78049) (xy 131.313618 -286.756967) (xy 131.271699 -286.726511)
			(xy 131.235061 -286.689873) (xy 131.204605 -286.647954) (xy 131.181082 -286.601787) (xy 131.16507 -286.552508)
			(xy 131.156964 -286.501331) (xy 131.156456 -286.475424) (xy 129.93624 -286.475424) (xy 129.935732 -286.501331)
			(xy 129.927626 -286.552508) (xy 129.911614 -286.601787) (xy 129.888091 -286.647954) (xy 129.857635 -286.689873)
			(xy 129.820997 -286.726511) (xy 129.779078 -286.756967) (xy 129.732911 -286.78049) (xy 129.683632 -286.796502)
			(xy 129.632455 -286.804608) (xy 129.580641 -286.804608) (xy 129.529464 -286.796502) (xy 129.480185 -286.78049)
			(xy 129.434018 -286.756967) (xy 129.392099 -286.726511) (xy 129.355461 -286.689873) (xy 129.325005 -286.647954)
			(xy 129.301482 -286.601787) (xy 129.28547 -286.552508) (xy 129.277364 -286.501331) (xy 129.276856 -286.475424)
			(xy 128.05664 -286.475424) (xy 128.056132 -286.501331) (xy 128.048026 -286.552508) (xy 128.032014 -286.601787)
			(xy 128.008491 -286.647954) (xy 127.978035 -286.689873) (xy 127.941397 -286.726511) (xy 127.899478 -286.756967)
			(xy 127.853311 -286.78049) (xy 127.804032 -286.796502) (xy 127.752855 -286.804608) (xy 127.701041 -286.804608)
			(xy 127.649864 -286.796502) (xy 127.600585 -286.78049) (xy 127.554418 -286.756967) (xy 127.512499 -286.726511)
			(xy 127.475861 -286.689873) (xy 127.445405 -286.647954) (xy 127.421882 -286.601787) (xy 127.40587 -286.552508)
			(xy 127.397764 -286.501331) (xy 127.397256 -286.475424) (xy 126.17704 -286.475424) (xy 126.176532 -286.501331)
			(xy 126.168426 -286.552508) (xy 126.152414 -286.601787) (xy 126.128891 -286.647954) (xy 126.098435 -286.689873)
			(xy 126.061797 -286.726511) (xy 126.019878 -286.756967) (xy 125.973711 -286.78049) (xy 125.924432 -286.796502)
			(xy 125.873255 -286.804608) (xy 125.821441 -286.804608) (xy 125.770264 -286.796502) (xy 125.720985 -286.78049)
			(xy 125.674818 -286.756967) (xy 125.632899 -286.726511) (xy 125.596261 -286.689873) (xy 125.565805 -286.647954)
			(xy 125.542282 -286.601787) (xy 125.52627 -286.552508) (xy 125.518164 -286.501331) (xy 125.517656 -286.475424)
			(xy 124.29744 -286.475424) (xy 124.296932 -286.501331) (xy 124.288826 -286.552508) (xy 124.272814 -286.601787)
			(xy 124.249291 -286.647954) (xy 124.218835 -286.689873) (xy 124.182197 -286.726511) (xy 124.140278 -286.756967)
			(xy 124.094111 -286.78049) (xy 124.044832 -286.796502) (xy 123.993655 -286.804608) (xy 123.941841 -286.804608)
			(xy 123.890664 -286.796502) (xy 123.841385 -286.78049) (xy 123.795218 -286.756967) (xy 123.753299 -286.726511)
			(xy 123.716661 -286.689873) (xy 123.686205 -286.647954) (xy 123.662682 -286.601787) (xy 123.64667 -286.552508)
			(xy 123.638564 -286.501331) (xy 123.638056 -286.475424) (xy 122.41784 -286.475424) (xy 122.417332 -286.501331)
			(xy 122.409226 -286.552508) (xy 122.393214 -286.601787) (xy 122.369691 -286.647954) (xy 122.339235 -286.689873)
			(xy 122.302597 -286.726511) (xy 122.260678 -286.756967) (xy 122.214511 -286.78049) (xy 122.165232 -286.796502)
			(xy 122.114055 -286.804608) (xy 122.062241 -286.804608) (xy 122.011064 -286.796502) (xy 121.961785 -286.78049)
			(xy 121.915618 -286.756967) (xy 121.873699 -286.726511) (xy 121.837061 -286.689873) (xy 121.806605 -286.647954)
			(xy 121.783082 -286.601787) (xy 121.76707 -286.552508) (xy 121.758964 -286.501331) (xy 121.758456 -286.475424)
			(xy 120.53824 -286.475424) (xy 120.537732 -286.501331) (xy 120.529626 -286.552508) (xy 120.513614 -286.601787)
			(xy 120.490091 -286.647954) (xy 120.459635 -286.689873) (xy 120.422997 -286.726511) (xy 120.381078 -286.756967)
			(xy 120.334911 -286.78049) (xy 120.285632 -286.796502) (xy 120.234455 -286.804608) (xy 120.182641 -286.804608)
			(xy 120.131464 -286.796502) (xy 120.082185 -286.78049) (xy 120.036018 -286.756967) (xy 119.994099 -286.726511)
			(xy 119.957461 -286.689873) (xy 119.927005 -286.647954) (xy 119.903482 -286.601787) (xy 119.88747 -286.552508)
			(xy 119.879364 -286.501331) (xy 119.878856 -286.475424) (xy 103.62184 -286.475424) (xy 103.621332 -286.501331)
			(xy 103.613226 -286.552508) (xy 103.597214 -286.601787) (xy 103.573691 -286.647954) (xy 103.543235 -286.689873)
			(xy 103.506597 -286.726511) (xy 103.464678 -286.756967) (xy 103.418511 -286.78049) (xy 103.369232 -286.796502)
			(xy 103.318055 -286.804608) (xy 103.266241 -286.804608) (xy 103.215064 -286.796502) (xy 103.165785 -286.78049)
			(xy 103.119618 -286.756967) (xy 103.077699 -286.726511) (xy 103.041061 -286.689873) (xy 103.010605 -286.647954)
			(xy 102.987082 -286.601787) (xy 102.97107 -286.552508) (xy 102.962964 -286.501331) (xy 102.962456 -286.475424)
			(xy 102.963053 -286.447707) (xy 102.972374 -286.39306) (xy 102.980998 -286.366712) (xy 102.988872 -286.344614)
			(xy 102.783894 -285.989522) (xy 102.76078 -285.985204) (xy 102.735964 -285.980016) (xy 102.688184 -285.963065)
			(xy 102.643565 -285.938998) (xy 102.603157 -285.908381) (xy 102.567916 -285.871936) (xy 102.538671 -285.830525)
			(xy 102.516113 -285.785123) (xy 102.500775 -285.736802) (xy 102.493018 -285.686702) (xy 102.492556 -285.661354)
			(xy 102.211632 -285.661354) (xy 102.211124 -285.687241) (xy 102.203025 -285.738379) (xy 102.187026 -285.787619)
			(xy 102.16352 -285.833751) (xy 102.133088 -285.875638) (xy 102.096478 -285.912248) (xy 102.054591 -285.94268)
			(xy 102.008459 -285.966186) (xy 101.959219 -285.982185) (xy 101.908081 -285.990284) (xy 101.856307 -285.990284)
			(xy 101.805169 -285.982185) (xy 101.755929 -285.966186) (xy 101.709797 -285.94268) (xy 101.66791 -285.912248)
			(xy 101.6313 -285.875638) (xy 101.600868 -285.833751) (xy 101.577362 -285.787619) (xy 101.561363 -285.738379)
			(xy 101.553264 -285.687241) (xy 101.552756 -285.661354) (xy 101.271832 -285.661354) (xy 101.271832 -285.661862)
			(xy 101.271253 -285.689379) (xy 101.262059 -285.74364) (xy 101.253544 -285.769812) (xy 101.245924 -285.79191)
			(xy 101.451156 -286.147256) (xy 101.474016 -286.151574) (xy 101.498827 -286.156786) (xy 101.546604 -286.173734)
			(xy 101.591223 -286.197799) (xy 101.63163 -286.228413) (xy 101.666872 -286.264855) (xy 101.696117 -286.306263)
			(xy 101.718676 -286.351662) (xy 101.734017 -286.399979) (xy 101.741777 -286.450077) (xy 101.74224 -286.475424)
			(xy 101.741732 -286.501331) (xy 101.733626 -286.552508) (xy 101.717614 -286.601787) (xy 101.694091 -286.647954)
			(xy 101.663635 -286.689873) (xy 101.626997 -286.726511) (xy 101.585078 -286.756967) (xy 101.538911 -286.78049)
			(xy 101.489632 -286.796502) (xy 101.438455 -286.804608) (xy 101.386641 -286.804608) (xy 101.335464 -286.796502)
			(xy 101.286185 -286.78049) (xy 101.240018 -286.756967) (xy 101.198099 -286.726511) (xy 101.161461 -286.689873)
			(xy 101.131005 -286.647954) (xy 101.107482 -286.601787) (xy 101.09147 -286.552508) (xy 101.083364 -286.501331)
			(xy 101.082856 -286.475424) (xy 101.083453 -286.447707) (xy 101.092774 -286.39306) (xy 101.101398 -286.366712)
			(xy 101.109272 -286.344614) (xy 100.904294 -285.989522) (xy 100.88118 -285.985204) (xy 100.856364 -285.980016)
			(xy 100.808584 -285.963065) (xy 100.763965 -285.938998) (xy 100.723557 -285.908381) (xy 100.688316 -285.871936)
			(xy 100.659071 -285.830525) (xy 100.636513 -285.785123) (xy 100.621175 -285.736802) (xy 100.613418 -285.686702)
			(xy 100.612956 -285.661354) (xy 100.332032 -285.661354) (xy 100.331524 -285.687241) (xy 100.323425 -285.738379)
			(xy 100.307426 -285.787619) (xy 100.28392 -285.833751) (xy 100.253488 -285.875638) (xy 100.216878 -285.912248)
			(xy 100.174991 -285.94268) (xy 100.128859 -285.966186) (xy 100.079619 -285.982185) (xy 100.028481 -285.990284)
			(xy 99.976707 -285.990284) (xy 99.925569 -285.982185) (xy 99.876329 -285.966186) (xy 99.830197 -285.94268)
			(xy 99.78831 -285.912248) (xy 99.7517 -285.875638) (xy 99.721268 -285.833751) (xy 99.697762 -285.787619)
			(xy 99.681763 -285.738379) (xy 99.673664 -285.687241) (xy 99.673156 -285.661354) (xy 99.392232 -285.661354)
			(xy 99.392232 -285.661862) (xy 99.391653 -285.689379) (xy 99.382459 -285.74364) (xy 99.373944 -285.769812)
			(xy 99.366324 -285.79191) (xy 99.571556 -286.147256) (xy 99.594416 -286.151574) (xy 99.619227 -286.156786)
			(xy 99.667004 -286.173734) (xy 99.711623 -286.197799) (xy 99.75203 -286.228413) (xy 99.787272 -286.264855)
			(xy 99.816517 -286.306263) (xy 99.839076 -286.351662) (xy 99.854417 -286.399979) (xy 99.862177 -286.450077)
			(xy 99.86264 -286.475424) (xy 99.862132 -286.501331) (xy 99.854026 -286.552508) (xy 99.838014 -286.601787)
			(xy 99.814491 -286.647954) (xy 99.784035 -286.689873) (xy 99.747397 -286.726511) (xy 99.705478 -286.756967)
			(xy 99.659311 -286.78049) (xy 99.610032 -286.796502) (xy 99.558855 -286.804608) (xy 99.507041 -286.804608)
			(xy 99.455864 -286.796502) (xy 99.406585 -286.78049) (xy 99.360418 -286.756967) (xy 99.318499 -286.726511)
			(xy 99.281861 -286.689873) (xy 99.251405 -286.647954) (xy 99.227882 -286.601787) (xy 99.21187 -286.552508)
			(xy 99.203764 -286.501331) (xy 99.203256 -286.475424) (xy 99.203853 -286.447707) (xy 99.213174 -286.39306)
			(xy 99.221798 -286.366712) (xy 99.229672 -286.344614) (xy 99.024694 -285.989522) (xy 99.00158 -285.985204)
			(xy 98.976764 -285.980016) (xy 98.928984 -285.963065) (xy 98.884365 -285.938998) (xy 98.843957 -285.908381)
			(xy 98.808716 -285.871936) (xy 98.779471 -285.830525) (xy 98.756913 -285.785123) (xy 98.741575 -285.736802)
			(xy 98.733818 -285.686702) (xy 98.733356 -285.661354) (xy 98.452432 -285.661354) (xy 98.451924 -285.687241)
			(xy 98.443825 -285.738379) (xy 98.427826 -285.787619) (xy 98.40432 -285.833751) (xy 98.373888 -285.875638)
			(xy 98.337278 -285.912248) (xy 98.295391 -285.94268) (xy 98.249259 -285.966186) (xy 98.200019 -285.982185)
			(xy 98.148881 -285.990284) (xy 98.097107 -285.990284) (xy 98.045969 -285.982185) (xy 97.996729 -285.966186)
			(xy 97.950597 -285.94268) (xy 97.90871 -285.912248) (xy 97.8721 -285.875638) (xy 97.841668 -285.833751)
			(xy 97.818162 -285.787619) (xy 97.802163 -285.738379) (xy 97.794064 -285.687241) (xy 97.793556 -285.661354)
			(xy 97.512632 -285.661354) (xy 97.512632 -285.661862) (xy 97.512053 -285.689379) (xy 97.502859 -285.74364)
			(xy 97.494344 -285.769812) (xy 97.486724 -285.79191) (xy 97.691956 -286.147256) (xy 97.714816 -286.151574)
			(xy 97.739627 -286.156786) (xy 97.787404 -286.173734) (xy 97.832023 -286.197799) (xy 97.87243 -286.228413)
			(xy 97.907672 -286.264855) (xy 97.936917 -286.306263) (xy 97.959476 -286.351662) (xy 97.974817 -286.399979)
			(xy 97.982577 -286.450077) (xy 97.98304 -286.475424) (xy 97.982532 -286.501331) (xy 97.974426 -286.552508)
			(xy 97.958414 -286.601787) (xy 97.934891 -286.647954) (xy 97.904435 -286.689873) (xy 97.867797 -286.726511)
			(xy 97.825878 -286.756967) (xy 97.779711 -286.78049) (xy 97.730432 -286.796502) (xy 97.679255 -286.804608)
			(xy 97.627441 -286.804608) (xy 97.576264 -286.796502) (xy 97.526985 -286.78049) (xy 97.480818 -286.756967)
			(xy 97.438899 -286.726511) (xy 97.402261 -286.689873) (xy 97.371805 -286.647954) (xy 97.348282 -286.601787)
			(xy 97.33227 -286.552508) (xy 97.324164 -286.501331) (xy 97.323656 -286.475424) (xy 97.324253 -286.447707)
			(xy 97.333574 -286.39306) (xy 97.342198 -286.366712) (xy 97.350072 -286.344614) (xy 97.145094 -285.989522)
			(xy 97.12198 -285.985204) (xy 97.097164 -285.980016) (xy 97.049384 -285.963065) (xy 97.004765 -285.938998)
			(xy 96.964357 -285.908381) (xy 96.929116 -285.871936) (xy 96.899871 -285.830525) (xy 96.877313 -285.785123)
			(xy 96.861975 -285.736802) (xy 96.854218 -285.686702) (xy 96.853756 -285.661354) (xy 96.572832 -285.661354)
			(xy 96.572324 -285.687241) (xy 96.564225 -285.738379) (xy 96.548226 -285.787619) (xy 96.52472 -285.833751)
			(xy 96.494288 -285.875638) (xy 96.457678 -285.912248) (xy 96.415791 -285.94268) (xy 96.369659 -285.966186)
			(xy 96.320419 -285.982185) (xy 96.269281 -285.990284) (xy 96.217507 -285.990284) (xy 96.166369 -285.982185)
			(xy 96.117129 -285.966186) (xy 96.070997 -285.94268) (xy 96.02911 -285.912248) (xy 95.9925 -285.875638)
			(xy 95.962068 -285.833751) (xy 95.938562 -285.787619) (xy 95.922563 -285.738379) (xy 95.914464 -285.687241)
			(xy 95.913956 -285.661354) (xy 95.633032 -285.661354) (xy 95.633032 -285.661862) (xy 95.632453 -285.689379)
			(xy 95.623259 -285.74364) (xy 95.614744 -285.769812) (xy 95.607124 -285.79191) (xy 95.812356 -286.147256)
			(xy 95.835216 -286.151574) (xy 95.860027 -286.156786) (xy 95.907804 -286.173734) (xy 95.952423 -286.197799)
			(xy 95.99283 -286.228413) (xy 96.028072 -286.264855) (xy 96.057317 -286.306263) (xy 96.079876 -286.351662)
			(xy 96.095217 -286.399979) (xy 96.102977 -286.450077) (xy 96.10344 -286.475424) (xy 96.102932 -286.501331)
			(xy 96.094826 -286.552508) (xy 96.078814 -286.601787) (xy 96.055291 -286.647954) (xy 96.024835 -286.689873)
			(xy 95.988197 -286.726511) (xy 95.946278 -286.756967) (xy 95.900111 -286.78049) (xy 95.850832 -286.796502)
			(xy 95.799655 -286.804608) (xy 95.747841 -286.804608) (xy 95.696664 -286.796502) (xy 95.647385 -286.78049)
			(xy 95.601218 -286.756967) (xy 95.559299 -286.726511) (xy 95.522661 -286.689873) (xy 95.492205 -286.647954)
			(xy 95.468682 -286.601787) (xy 95.45267 -286.552508) (xy 95.444564 -286.501331) (xy 95.444056 -286.475424)
			(xy 95.444653 -286.447707) (xy 95.453974 -286.39306) (xy 95.462598 -286.366712) (xy 95.470472 -286.344614)
			(xy 95.265494 -285.989522) (xy 95.24238 -285.985204) (xy 95.217564 -285.980016) (xy 95.169784 -285.963065)
			(xy 95.125165 -285.938998) (xy 95.084757 -285.908381) (xy 95.049516 -285.871936) (xy 95.020271 -285.830525)
			(xy 94.997713 -285.785123) (xy 94.982375 -285.736802) (xy 94.974618 -285.686702) (xy 94.974156 -285.661354)
			(xy 94.693232 -285.661354) (xy 94.692724 -285.687241) (xy 94.684625 -285.738379) (xy 94.668626 -285.787619)
			(xy 94.64512 -285.833751) (xy 94.614688 -285.875638) (xy 94.578078 -285.912248) (xy 94.536191 -285.94268)
			(xy 94.490059 -285.966186) (xy 94.440819 -285.982185) (xy 94.389681 -285.990284) (xy 94.337907 -285.990284)
			(xy 94.286769 -285.982185) (xy 94.237529 -285.966186) (xy 94.191397 -285.94268) (xy 94.14951 -285.912248)
			(xy 94.1129 -285.875638) (xy 94.082468 -285.833751) (xy 94.058962 -285.787619) (xy 94.042963 -285.738379)
			(xy 94.034864 -285.687241) (xy 94.034356 -285.661354) (xy 93.753432 -285.661354) (xy 93.753432 -285.661862)
			(xy 93.752853 -285.689379) (xy 93.743659 -285.74364) (xy 93.735144 -285.769812) (xy 93.727524 -285.79191)
			(xy 93.932756 -286.147256) (xy 93.955616 -286.151574) (xy 93.980427 -286.156786) (xy 94.028204 -286.173734)
			(xy 94.072823 -286.197799) (xy 94.11323 -286.228413) (xy 94.148472 -286.264855) (xy 94.177717 -286.306263)
			(xy 94.200276 -286.351662) (xy 94.215617 -286.399979) (xy 94.223377 -286.450077) (xy 94.22384 -286.475424)
			(xy 94.223332 -286.501331) (xy 94.215226 -286.552508) (xy 94.199214 -286.601787) (xy 94.175691 -286.647954)
			(xy 94.145235 -286.689873) (xy 94.108597 -286.726511) (xy 94.066678 -286.756967) (xy 94.020511 -286.78049)
			(xy 93.971232 -286.796502) (xy 93.920055 -286.804608) (xy 93.868241 -286.804608) (xy 93.817064 -286.796502)
			(xy 93.767785 -286.78049) (xy 93.721618 -286.756967) (xy 93.679699 -286.726511) (xy 93.643061 -286.689873)
			(xy 93.612605 -286.647954) (xy 93.589082 -286.601787) (xy 93.57307 -286.552508) (xy 93.564964 -286.501331)
			(xy 93.564456 -286.475424) (xy 93.565053 -286.447707) (xy 93.574374 -286.39306) (xy 93.582998 -286.366712)
			(xy 93.590872 -286.344614) (xy 93.385894 -285.989522) (xy 93.36278 -285.985204) (xy 93.337964 -285.980016)
			(xy 93.290184 -285.963065) (xy 93.245565 -285.938998) (xy 93.205157 -285.908381) (xy 93.169916 -285.871936)
			(xy 93.140671 -285.830525) (xy 93.118113 -285.785123) (xy 93.102775 -285.736802) (xy 93.095018 -285.686702)
			(xy 93.094556 -285.661354) (xy 92.813632 -285.661354) (xy 92.813124 -285.687241) (xy 92.805025 -285.738379)
			(xy 92.789026 -285.787619) (xy 92.76552 -285.833751) (xy 92.735088 -285.875638) (xy 92.698478 -285.912248)
			(xy 92.656591 -285.94268) (xy 92.610459 -285.966186) (xy 92.561219 -285.982185) (xy 92.510081 -285.990284)
			(xy 92.458307 -285.990284) (xy 92.407169 -285.982185) (xy 92.357929 -285.966186) (xy 92.311797 -285.94268)
			(xy 92.26991 -285.912248) (xy 92.2333 -285.875638) (xy 92.202868 -285.833751) (xy 92.179362 -285.787619)
			(xy 92.163363 -285.738379) (xy 92.155264 -285.687241) (xy 92.154756 -285.661354) (xy 91.87434 -285.661354)
			(xy 91.873738 -285.689071) (xy 91.86442 -285.743718) (xy 91.855798 -285.770066) (xy 91.847924 -285.792164)
			(xy 92.053156 -286.147256) (xy 92.076016 -286.151574) (xy 92.100827 -286.156786) (xy 92.148604 -286.173734)
			(xy 92.193223 -286.197799) (xy 92.23363 -286.228413) (xy 92.268872 -286.264855) (xy 92.298117 -286.306263)
			(xy 92.320676 -286.351662) (xy 92.336017 -286.399979) (xy 92.343777 -286.450077) (xy 92.34424 -286.475424)
			(xy 92.343732 -286.501331) (xy 92.335626 -286.552508) (xy 92.319614 -286.601787) (xy 92.296091 -286.647954)
			(xy 92.265635 -286.689873) (xy 92.228997 -286.726511) (xy 92.187078 -286.756967) (xy 92.140911 -286.78049)
			(xy 92.091632 -286.796502) (xy 92.040455 -286.804608) (xy 91.988641 -286.804608) (xy 91.937464 -286.796502)
			(xy 91.888185 -286.78049) (xy 91.842018 -286.756967) (xy 91.800099 -286.726511) (xy 91.763461 -286.689873)
			(xy 91.733005 -286.647954) (xy 91.709482 -286.601787) (xy 91.69347 -286.552508) (xy 91.685364 -286.501331)
			(xy 91.684856 -286.475424) (xy 91.685453 -286.447707) (xy 91.694774 -286.39306) (xy 91.703398 -286.366712)
			(xy 91.711272 -286.344614) (xy 91.50604 -285.989522) (xy 91.48318 -285.985204) (xy 91.458364 -285.980016)
			(xy 91.410584 -285.963065) (xy 91.365965 -285.938998) (xy 91.325557 -285.908381) (xy 91.290316 -285.871936)
			(xy 91.261071 -285.830525) (xy 91.238513 -285.785123) (xy 91.223175 -285.736802) (xy 91.215418 -285.686702)
			(xy 91.214956 -285.661354) (xy 90.93454 -285.661354) (xy 90.934032 -285.687261) (xy 90.925926 -285.738438)
			(xy 90.909914 -285.787717) (xy 90.886391 -285.833884) (xy 90.855935 -285.875803) (xy 90.819297 -285.912441)
			(xy 90.777378 -285.942897) (xy 90.731211 -285.96642) (xy 90.681932 -285.982432) (xy 90.630755 -285.990538)
			(xy 90.578941 -285.990538) (xy 90.527764 -285.982432) (xy 90.478485 -285.96642) (xy 90.432318 -285.942897)
			(xy 90.390399 -285.912441) (xy 90.353761 -285.875803) (xy 90.323305 -285.833884) (xy 90.299782 -285.787717)
			(xy 90.28377 -285.738438) (xy 90.275664 -285.687261) (xy 90.275156 -285.661354) (xy 89.994232 -285.661354)
			(xy 89.993689 -285.689062) (xy 89.984503 -285.743708) (xy 89.975944 -285.770066) (xy 89.96807 -285.792164)
			(xy 90.173302 -286.147256) (xy 90.196162 -286.151574) (xy 90.220961 -286.156781) (xy 90.268701 -286.173765)
			(xy 90.31328 -286.197855) (xy 90.353647 -286.228483) (xy 90.388851 -286.264927) (xy 90.418064 -286.30633)
			(xy 90.440597 -286.351715) (xy 90.455919 -286.400014) (xy 90.46367 -286.450088) (xy 90.464132 -286.475424)
			(xy 90.463624 -286.501311) (xy 90.455525 -286.552449) (xy 90.439526 -286.601689) (xy 90.41602 -286.647821)
			(xy 90.385588 -286.689708) (xy 90.348978 -286.726318) (xy 90.307091 -286.75675) (xy 90.260959 -286.780256)
			(xy 90.211719 -286.796255) (xy 90.160581 -286.804354) (xy 90.108807 -286.804354) (xy 90.057669 -286.796255)
			(xy 90.008429 -286.780256) (xy 89.962297 -286.75675) (xy 89.92041 -286.726318) (xy 89.8838 -286.689708)
			(xy 89.853368 -286.647821) (xy 89.829862 -286.601689) (xy 89.813863 -286.552449) (xy 89.805764 -286.501311)
			(xy 89.805256 -286.475424) (xy 89.805793 -286.447716) (xy 89.814983 -286.393069) (xy 89.823544 -286.366712)
			(xy 89.831418 -286.344614) (xy 89.626186 -285.989522) (xy 89.603326 -285.985204) (xy 89.57852 -285.980026)
			(xy 89.530779 -285.963039) (xy 89.486199 -285.938946) (xy 89.445832 -285.908314) (xy 89.410627 -285.871866)
			(xy 89.381416 -285.83046) (xy 89.358884 -285.785071) (xy 89.343564 -285.736769) (xy 89.335817 -285.686691)
			(xy 89.335356 -285.661354) (xy 88.114632 -285.661354) (xy 88.114124 -285.687241) (xy 88.106025 -285.738379)
			(xy 88.090026 -285.787619) (xy 88.06652 -285.833751) (xy 88.036088 -285.875638) (xy 87.999478 -285.912248)
			(xy 87.957591 -285.94268) (xy 87.911459 -285.966186) (xy 87.862219 -285.982185) (xy 87.811081 -285.990284)
			(xy 87.759307 -285.990284) (xy 87.708169 -285.982185) (xy 87.658929 -285.966186) (xy 87.612797 -285.94268)
			(xy 87.57091 -285.912248) (xy 87.5343 -285.875638) (xy 87.503868 -285.833751) (xy 87.480362 -285.787619)
			(xy 87.464363 -285.738379) (xy 87.456264 -285.687241) (xy 87.455756 -285.661354) (xy 2.509012 -285.661354)
			(xy 2.509012 -286.475424) (xy 86.046056 -286.475424) (xy 86.046564 -286.449537) (xy 86.054663 -286.398399)
			(xy 86.070662 -286.349159) (xy 86.094168 -286.303027) (xy 86.1246 -286.26114) (xy 86.16121 -286.22453)
			(xy 86.203097 -286.194098) (xy 86.249229 -286.170592) (xy 86.298469 -286.154593) (xy 86.349607 -286.146494)
			(xy 86.401381 -286.146494) (xy 86.452519 -286.154593) (xy 86.501759 -286.170592) (xy 86.547891 -286.194098)
			(xy 86.589778 -286.22453) (xy 86.626388 -286.26114) (xy 86.65682 -286.303027) (xy 86.680326 -286.349159)
			(xy 86.696325 -286.398399) (xy 86.704424 -286.449537) (xy 86.704932 -286.475424) (xy 86.704442 -286.501305)
			(xy 86.98614 -286.501305) (xy 86.98614 -286.449495) (xy 86.994245 -286.398322) (xy 87.010255 -286.349048)
			(xy 87.033776 -286.302885) (xy 87.064229 -286.260969) (xy 87.100864 -286.224333) (xy 87.142779 -286.193879)
			(xy 87.188942 -286.170357) (xy 87.238217 -286.154347) (xy 87.289389 -286.146241) (xy 87.315294 -286.145732)
			(xy 87.340788 -286.146208) (xy 87.391166 -286.154069) (xy 87.43973 -286.169604) (xy 87.485317 -286.192442)
			(xy 87.526838 -286.222037) (xy 87.563299 -286.257679) (xy 87.578946 -286.277812) (xy 87.991442 -286.277812)
			(xy 88.007098 -286.257686) (xy 88.043557 -286.222043) (xy 88.085076 -286.192449) (xy 88.130661 -286.16961)
			(xy 88.179224 -286.154073) (xy 88.229601 -286.146211) (xy 88.255094 -286.145732) (xy 88.281006 -286.146165)
			(xy 88.332191 -286.154271) (xy 88.381478 -286.170285) (xy 88.427653 -286.193811) (xy 88.469579 -286.224272)
			(xy 88.506224 -286.260916) (xy 88.536685 -286.302842) (xy 88.560213 -286.349016) (xy 88.576227 -286.398303)
			(xy 88.584334 -286.449488) (xy 88.584334 -286.501312) (xy 88.576227 -286.552497) (xy 88.560213 -286.601784)
			(xy 88.536685 -286.647958) (xy 88.506224 -286.689884) (xy 88.469579 -286.726528) (xy 88.427653 -286.756989)
			(xy 88.381478 -286.780515) (xy 88.332191 -286.796529) (xy 88.281006 -286.804635) (xy 88.255094 -286.805116)
			(xy 88.229601 -286.80463) (xy 88.179224 -286.796768) (xy 88.130661 -286.781233) (xy 88.085074 -286.758397)
			(xy 88.043553 -286.728806) (xy 88.007091 -286.693167) (xy 87.991442 -286.673036) (xy 87.578946 -286.673036)
			(xy 87.56331 -286.693178) (xy 87.526845 -286.728817) (xy 87.485322 -286.758409) (xy 87.439733 -286.781244)
			(xy 87.391168 -286.796778) (xy 87.340788 -286.804638) (xy 87.315294 -286.805116) (xy 87.289389 -286.804559)
			(xy 87.238217 -286.796453) (xy 87.188942 -286.780443) (xy 87.142779 -286.756921) (xy 87.100864 -286.726467)
			(xy 87.064229 -286.689831) (xy 87.033776 -286.647915) (xy 87.010255 -286.601752) (xy 86.994245 -286.552478)
			(xy 86.98614 -286.501305) (xy 86.704442 -286.501305) (xy 86.704407 -286.503132) (xy 86.695209 -286.557779)
			(xy 86.686644 -286.584136) (xy 86.679024 -286.60598) (xy 86.884002 -286.961072) (xy 86.906862 -286.96539)
			(xy 86.931665 -286.970582) (xy 86.979406 -286.987567) (xy 87.023985 -287.011659) (xy 87.064353 -287.042288)
			(xy 87.099557 -287.078734) (xy 87.12877 -287.120139) (xy 87.151302 -287.165526) (xy 87.166622 -287.213827)
			(xy 87.174371 -287.263904) (xy 87.174832 -287.28924) (xy 87.174324 -287.315127) (xy 87.166225 -287.366265)
			(xy 87.150226 -287.415505) (xy 87.12672 -287.461637) (xy 87.096288 -287.503524) (xy 87.059678 -287.540134)
			(xy 87.017791 -287.570566) (xy 86.971659 -287.594072) (xy 86.922419 -287.610071) (xy 86.871281 -287.61817)
			(xy 86.819507 -287.61817) (xy 86.768369 -287.610071) (xy 86.719129 -287.594072) (xy 86.672997 -287.570566)
			(xy 86.63111 -287.540134) (xy 86.5945 -287.503524) (xy 86.564068 -287.461637) (xy 86.540562 -287.415505)
			(xy 86.524563 -287.366265) (xy 86.516464 -287.315127) (xy 86.515956 -287.28924) (xy 86.516497 -287.261532)
			(xy 86.525685 -287.206886) (xy 86.534244 -287.180528) (xy 86.541864 -287.158684) (xy 86.336886 -286.803592)
			(xy 86.314026 -286.799274) (xy 86.289236 -286.79403) (xy 86.241499 -286.777048) (xy 86.196923 -286.752961)
			(xy 86.156558 -286.722338) (xy 86.121354 -286.685898) (xy 86.09214 -286.644501) (xy 86.069605 -286.599121)
			(xy 86.054278 -286.550828) (xy 86.046522 -286.500758) (xy 86.046056 -286.475424) (xy 2.509012 -286.475424)
			(xy 2.509012 -288.917126) (xy 88.395556 -288.917126) (xy 88.396056 -288.891781) (xy 88.403825 -288.84169)
			(xy 88.419169 -288.793377) (xy 88.441727 -288.747983) (xy 88.470967 -288.706576) (xy 88.506199 -288.670131)
			(xy 88.546595 -288.639509) (xy 88.591201 -288.61543) (xy 88.638966 -288.598461) (xy 88.66378 -288.593276)
			(xy 88.68664 -288.588958) (xy 88.891618 -288.233866) (xy 88.883744 -288.212022) (xy 88.875171 -288.185601)
			(xy 88.86597 -288.130828) (xy 88.865456 -288.103056) (xy 88.865964 -288.077169) (xy 88.874063 -288.026031)
			(xy 88.890062 -287.976791) (xy 88.913568 -287.930659) (xy 88.944 -287.888772) (xy 88.98061 -287.852162)
			(xy 89.022497 -287.82173) (xy 89.068629 -287.798224) (xy 89.117869 -287.782225) (xy 89.169007 -287.774126)
			(xy 89.220781 -287.774126) (xy 89.271919 -287.782225) (xy 89.321159 -287.798224) (xy 89.367291 -287.82173)
			(xy 89.409178 -287.852162) (xy 89.445788 -287.888772) (xy 89.47622 -287.930659) (xy 89.499726 -287.976791)
			(xy 89.515725 -288.026031) (xy 89.523824 -288.077169) (xy 89.524332 -288.103056) (xy 89.523874 -288.128391)
			(xy 89.516115 -288.178463) (xy 89.500786 -288.226759) (xy 89.47825 -288.272141) (xy 89.449037 -288.313542)
			(xy 89.413835 -288.349987) (xy 89.373471 -288.380617) (xy 89.328897 -288.404713) (xy 89.281162 -288.421706)
			(xy 89.256362 -288.426906) (xy 89.233502 -288.431224) (xy 89.028524 -288.786316) (xy 89.036398 -288.80816)
			(xy 89.045049 -288.834567) (xy 89.054366 -288.889344) (xy 89.05494 -288.917126) (xy 90.275156 -288.917126)
			(xy 90.275656 -288.891781) (xy 90.283425 -288.84169) (xy 90.298769 -288.793377) (xy 90.321327 -288.747983)
			(xy 90.350567 -288.706576) (xy 90.385799 -288.670131) (xy 90.426195 -288.639509) (xy 90.470801 -288.61543)
			(xy 90.518566 -288.598461) (xy 90.54338 -288.593276) (xy 90.56624 -288.588958) (xy 90.771218 -288.233866)
			(xy 90.763344 -288.212022) (xy 90.754771 -288.185601) (xy 90.74557 -288.130828) (xy 90.745056 -288.103056)
			(xy 90.745564 -288.077169) (xy 90.753663 -288.026031) (xy 90.769662 -287.976791) (xy 90.793168 -287.930659)
			(xy 90.8236 -287.888772) (xy 90.86021 -287.852162) (xy 90.902097 -287.82173) (xy 90.948229 -287.798224)
			(xy 90.997469 -287.782225) (xy 91.048607 -287.774126) (xy 91.100381 -287.774126) (xy 91.151519 -287.782225)
			(xy 91.200759 -287.798224) (xy 91.246891 -287.82173) (xy 91.288778 -287.852162) (xy 91.325388 -287.888772)
			(xy 91.35582 -287.930659) (xy 91.379326 -287.976791) (xy 91.395325 -288.026031) (xy 91.403424 -288.077169)
			(xy 91.403932 -288.103056) (xy 91.403474 -288.128391) (xy 91.395715 -288.178463) (xy 91.380386 -288.226759)
			(xy 91.35785 -288.272141) (xy 91.328637 -288.313542) (xy 91.293435 -288.349987) (xy 91.253071 -288.380617)
			(xy 91.208497 -288.404713) (xy 91.160762 -288.421706) (xy 91.135962 -288.426906) (xy 91.113102 -288.431224)
			(xy 90.908124 -288.786316) (xy 90.915998 -288.80816) (xy 90.924649 -288.834567) (xy 90.933966 -288.889344)
			(xy 90.93454 -288.917126) (xy 91.214956 -288.917126) (xy 91.215464 -288.891219) (xy 91.22357 -288.840042)
			(xy 91.239582 -288.790763) (xy 91.263105 -288.744596) (xy 91.293561 -288.702677) (xy 91.330199 -288.666039)
			(xy 91.372118 -288.635583) (xy 91.418285 -288.61206) (xy 91.467564 -288.596048) (xy 91.518741 -288.587942)
			(xy 91.570555 -288.587942) (xy 91.621732 -288.596048) (xy 91.671011 -288.61206) (xy 91.717178 -288.635583)
			(xy 91.759097 -288.666039) (xy 91.795735 -288.702677) (xy 91.826191 -288.744596) (xy 91.849714 -288.790763)
			(xy 91.865726 -288.840042) (xy 91.873832 -288.891219) (xy 91.87434 -288.917126) (xy 92.154756 -288.917126)
			(xy 92.155256 -288.891781) (xy 92.163025 -288.84169) (xy 92.178369 -288.793377) (xy 92.200927 -288.747983)
			(xy 92.230167 -288.706576) (xy 92.265399 -288.670131) (xy 92.305795 -288.639509) (xy 92.350401 -288.61543)
			(xy 92.398166 -288.598461) (xy 92.42298 -288.593276) (xy 92.44584 -288.588958) (xy 92.651072 -288.233866)
			(xy 92.643198 -288.211768) (xy 92.634576 -288.185419) (xy 92.625249 -288.130773) (xy 92.624656 -288.103056)
			(xy 92.625164 -288.077149) (xy 92.63327 -288.025972) (xy 92.649282 -287.976693) (xy 92.672805 -287.930526)
			(xy 92.703261 -287.888607) (xy 92.739899 -287.851969) (xy 92.781818 -287.821513) (xy 92.827985 -287.79799)
			(xy 92.877264 -287.781978) (xy 92.928441 -287.773872) (xy 92.980255 -287.773872) (xy 93.031432 -287.781978)
			(xy 93.080711 -287.79799) (xy 93.126878 -287.821513) (xy 93.168797 -287.851969) (xy 93.205435 -287.888607)
			(xy 93.235891 -287.930526) (xy 93.259414 -287.976693) (xy 93.275426 -288.025972) (xy 93.283532 -288.077149)
			(xy 93.28404 -288.103056) (xy 93.283618 -288.128404) (xy 93.275836 -288.178499) (xy 93.26048 -288.226813)
			(xy 93.237912 -288.272208) (xy 93.208662 -288.313614) (xy 93.173421 -288.350057) (xy 93.133018 -288.380678)
			(xy 93.088405 -288.404755) (xy 93.040632 -288.421722) (xy 93.015816 -288.426906) (xy 92.992956 -288.431224)
			(xy 92.787724 -288.786316) (xy 92.795598 -288.808414) (xy 92.80424 -288.834757) (xy 92.813554 -288.889407)
			(xy 92.81414 -288.917126) (xy 93.094556 -288.917126) (xy 93.095064 -288.891219) (xy 93.10317 -288.840042)
			(xy 93.119182 -288.790763) (xy 93.142705 -288.744596) (xy 93.173161 -288.702677) (xy 93.209799 -288.666039)
			(xy 93.251718 -288.635583) (xy 93.297885 -288.61206) (xy 93.347164 -288.596048) (xy 93.398341 -288.587942)
			(xy 93.450155 -288.587942) (xy 93.501332 -288.596048) (xy 93.550611 -288.61206) (xy 93.596778 -288.635583)
			(xy 93.638697 -288.666039) (xy 93.675335 -288.702677) (xy 93.705791 -288.744596) (xy 93.729314 -288.790763)
			(xy 93.745326 -288.840042) (xy 93.753432 -288.891219) (xy 93.75394 -288.917126) (xy 94.034356 -288.917126)
			(xy 94.034856 -288.891781) (xy 94.042625 -288.84169) (xy 94.057969 -288.793377) (xy 94.080527 -288.747983)
			(xy 94.109767 -288.706576) (xy 94.144999 -288.670131) (xy 94.185395 -288.639509) (xy 94.230001 -288.61543)
			(xy 94.277766 -288.598461) (xy 94.30258 -288.593276) (xy 94.32544 -288.588958) (xy 94.530672 -288.233866)
			(xy 94.522798 -288.211768) (xy 94.514176 -288.185419) (xy 94.504849 -288.130773) (xy 94.504256 -288.103056)
			(xy 94.504764 -288.077149) (xy 94.51287 -288.025972) (xy 94.528882 -287.976693) (xy 94.552405 -287.930526)
			(xy 94.582861 -287.888607) (xy 94.619499 -287.851969) (xy 94.661418 -287.821513) (xy 94.707585 -287.79799)
			(xy 94.756864 -287.781978) (xy 94.808041 -287.773872) (xy 94.859855 -287.773872) (xy 94.911032 -287.781978)
			(xy 94.960311 -287.79799) (xy 95.006478 -287.821513) (xy 95.048397 -287.851969) (xy 95.085035 -287.888607)
			(xy 95.115491 -287.930526) (xy 95.139014 -287.976693) (xy 95.155026 -288.025972) (xy 95.163132 -288.077149)
			(xy 95.16364 -288.103056) (xy 95.163218 -288.128404) (xy 95.155436 -288.178499) (xy 95.14008 -288.226813)
			(xy 95.117512 -288.272208) (xy 95.088262 -288.313614) (xy 95.053021 -288.350057) (xy 95.012618 -288.380678)
			(xy 94.968005 -288.404755) (xy 94.920232 -288.421722) (xy 94.895416 -288.426906) (xy 94.872556 -288.431224)
			(xy 94.667324 -288.786316) (xy 94.675198 -288.808414) (xy 94.68384 -288.834757) (xy 94.693154 -288.889407)
			(xy 94.69374 -288.917126) (xy 94.974156 -288.917126) (xy 94.974664 -288.891219) (xy 94.98277 -288.840042)
			(xy 94.998782 -288.790763) (xy 95.022305 -288.744596) (xy 95.052761 -288.702677) (xy 95.089399 -288.666039)
			(xy 95.131318 -288.635583) (xy 95.177485 -288.61206) (xy 95.226764 -288.596048) (xy 95.277941 -288.587942)
			(xy 95.329755 -288.587942) (xy 95.380932 -288.596048) (xy 95.430211 -288.61206) (xy 95.476378 -288.635583)
			(xy 95.518297 -288.666039) (xy 95.554935 -288.702677) (xy 95.585391 -288.744596) (xy 95.608914 -288.790763)
			(xy 95.624926 -288.840042) (xy 95.633032 -288.891219) (xy 95.63354 -288.917126) (xy 95.913956 -288.917126)
			(xy 95.914456 -288.891781) (xy 95.922225 -288.84169) (xy 95.937569 -288.793377) (xy 95.960127 -288.747983)
			(xy 95.989367 -288.706576) (xy 96.024599 -288.670131) (xy 96.064995 -288.639509) (xy 96.109601 -288.61543)
			(xy 96.157366 -288.598461) (xy 96.18218 -288.593276) (xy 96.20504 -288.588958) (xy 96.410272 -288.233866)
			(xy 96.402398 -288.211768) (xy 96.393776 -288.185419) (xy 96.384449 -288.130773) (xy 96.383856 -288.103056)
			(xy 96.384364 -288.077149) (xy 96.39247 -288.025972) (xy 96.408482 -287.976693) (xy 96.432005 -287.930526)
			(xy 96.462461 -287.888607) (xy 96.499099 -287.851969) (xy 96.541018 -287.821513) (xy 96.587185 -287.79799)
			(xy 96.636464 -287.781978) (xy 96.687641 -287.773872) (xy 96.739455 -287.773872) (xy 96.790632 -287.781978)
			(xy 96.839911 -287.79799) (xy 96.886078 -287.821513) (xy 96.927997 -287.851969) (xy 96.964635 -287.888607)
			(xy 96.995091 -287.930526) (xy 97.018614 -287.976693) (xy 97.034626 -288.025972) (xy 97.042732 -288.077149)
			(xy 97.04324 -288.103056) (xy 97.042818 -288.128404) (xy 97.035036 -288.178499) (xy 97.01968 -288.226813)
			(xy 96.997112 -288.272208) (xy 96.967862 -288.313614) (xy 96.932621 -288.350057) (xy 96.892218 -288.380678)
			(xy 96.847605 -288.404755) (xy 96.799832 -288.421722) (xy 96.775016 -288.426906) (xy 96.752156 -288.431224)
			(xy 96.546924 -288.786316) (xy 96.554798 -288.808414) (xy 96.56344 -288.834757) (xy 96.572754 -288.889407)
			(xy 96.57334 -288.917126) (xy 96.853756 -288.917126) (xy 96.854264 -288.891219) (xy 96.86237 -288.840042)
			(xy 96.878382 -288.790763) (xy 96.901905 -288.744596) (xy 96.932361 -288.702677) (xy 96.968999 -288.666039)
			(xy 97.010918 -288.635583) (xy 97.057085 -288.61206) (xy 97.106364 -288.596048) (xy 97.157541 -288.587942)
			(xy 97.209355 -288.587942) (xy 97.260532 -288.596048) (xy 97.309811 -288.61206) (xy 97.355978 -288.635583)
			(xy 97.397897 -288.666039) (xy 97.434535 -288.702677) (xy 97.464991 -288.744596) (xy 97.488514 -288.790763)
			(xy 97.504526 -288.840042) (xy 97.512632 -288.891219) (xy 97.51314 -288.917126) (xy 97.793556 -288.917126)
			(xy 97.794056 -288.891781) (xy 97.801825 -288.84169) (xy 97.817169 -288.793377) (xy 97.839727 -288.747983)
			(xy 97.868967 -288.706576) (xy 97.904199 -288.670131) (xy 97.944595 -288.639509) (xy 97.989201 -288.61543)
			(xy 98.036966 -288.598461) (xy 98.06178 -288.593276) (xy 98.08464 -288.588958) (xy 98.289872 -288.233866)
			(xy 98.281998 -288.211768) (xy 98.273376 -288.185419) (xy 98.264049 -288.130773) (xy 98.263456 -288.103056)
			(xy 98.263964 -288.077149) (xy 98.27207 -288.025972) (xy 98.288082 -287.976693) (xy 98.311605 -287.930526)
			(xy 98.342061 -287.888607) (xy 98.378699 -287.851969) (xy 98.420618 -287.821513) (xy 98.466785 -287.79799)
			(xy 98.516064 -287.781978) (xy 98.567241 -287.773872) (xy 98.619055 -287.773872) (xy 98.670232 -287.781978)
			(xy 98.719511 -287.79799) (xy 98.765678 -287.821513) (xy 98.807597 -287.851969) (xy 98.844235 -287.888607)
			(xy 98.874691 -287.930526) (xy 98.898214 -287.976693) (xy 98.914226 -288.025972) (xy 98.922332 -288.077149)
			(xy 98.92284 -288.103056) (xy 98.922418 -288.128404) (xy 98.914636 -288.178499) (xy 98.89928 -288.226813)
			(xy 98.876712 -288.272208) (xy 98.847462 -288.313614) (xy 98.812221 -288.350057) (xy 98.771818 -288.380678)
			(xy 98.727205 -288.404755) (xy 98.679432 -288.421722) (xy 98.654616 -288.426906) (xy 98.631756 -288.431224)
			(xy 98.426524 -288.786316) (xy 98.434398 -288.808414) (xy 98.44304 -288.834757) (xy 98.452354 -288.889407)
			(xy 98.45294 -288.917126) (xy 98.733356 -288.917126) (xy 98.733864 -288.891219) (xy 98.74197 -288.840042)
			(xy 98.757982 -288.790763) (xy 98.781505 -288.744596) (xy 98.811961 -288.702677) (xy 98.848599 -288.666039)
			(xy 98.890518 -288.635583) (xy 98.936685 -288.61206) (xy 98.985964 -288.596048) (xy 99.037141 -288.587942)
			(xy 99.088955 -288.587942) (xy 99.140132 -288.596048) (xy 99.189411 -288.61206) (xy 99.235578 -288.635583)
			(xy 99.277497 -288.666039) (xy 99.314135 -288.702677) (xy 99.344591 -288.744596) (xy 99.368114 -288.790763)
			(xy 99.384126 -288.840042) (xy 99.392232 -288.891219) (xy 99.39274 -288.917126) (xy 99.673156 -288.917126)
			(xy 99.673656 -288.891781) (xy 99.681425 -288.84169) (xy 99.696769 -288.793377) (xy 99.719327 -288.747983)
			(xy 99.748567 -288.706576) (xy 99.783799 -288.670131) (xy 99.824195 -288.639509) (xy 99.868801 -288.61543)
			(xy 99.916566 -288.598461) (xy 99.94138 -288.593276) (xy 99.96424 -288.588958) (xy 100.169472 -288.233866)
			(xy 100.161598 -288.211768) (xy 100.152976 -288.185419) (xy 100.143649 -288.130773) (xy 100.143056 -288.103056)
			(xy 100.143564 -288.077149) (xy 100.15167 -288.025972) (xy 100.167682 -287.976693) (xy 100.191205 -287.930526)
			(xy 100.221661 -287.888607) (xy 100.258299 -287.851969) (xy 100.300218 -287.821513) (xy 100.346385 -287.79799)
			(xy 100.395664 -287.781978) (xy 100.446841 -287.773872) (xy 100.498655 -287.773872) (xy 100.549832 -287.781978)
			(xy 100.599111 -287.79799) (xy 100.645278 -287.821513) (xy 100.687197 -287.851969) (xy 100.723835 -287.888607)
			(xy 100.754291 -287.930526) (xy 100.777814 -287.976693) (xy 100.793826 -288.025972) (xy 100.801932 -288.077149)
			(xy 100.80244 -288.103056) (xy 100.802018 -288.128404) (xy 100.794236 -288.178499) (xy 100.77888 -288.226813)
			(xy 100.756312 -288.272208) (xy 100.727062 -288.313614) (xy 100.691821 -288.350057) (xy 100.651418 -288.380678)
			(xy 100.606805 -288.404755) (xy 100.559032 -288.421722) (xy 100.534216 -288.426906) (xy 100.511356 -288.431224)
			(xy 100.306124 -288.786316) (xy 100.313998 -288.808414) (xy 100.32264 -288.834757) (xy 100.331954 -288.889407)
			(xy 100.33254 -288.917126) (xy 100.612956 -288.917126) (xy 100.613464 -288.891219) (xy 100.62157 -288.840042)
			(xy 100.637582 -288.790763) (xy 100.661105 -288.744596) (xy 100.691561 -288.702677) (xy 100.728199 -288.666039)
			(xy 100.770118 -288.635583) (xy 100.816285 -288.61206) (xy 100.865564 -288.596048) (xy 100.916741 -288.587942)
			(xy 100.968555 -288.587942) (xy 101.019732 -288.596048) (xy 101.069011 -288.61206) (xy 101.115178 -288.635583)
			(xy 101.157097 -288.666039) (xy 101.193735 -288.702677) (xy 101.224191 -288.744596) (xy 101.247714 -288.790763)
			(xy 101.263726 -288.840042) (xy 101.271832 -288.891219) (xy 101.27234 -288.917126) (xy 101.552756 -288.917126)
			(xy 101.553256 -288.891781) (xy 101.561025 -288.84169) (xy 101.576369 -288.793377) (xy 101.598927 -288.747983)
			(xy 101.628167 -288.706576) (xy 101.663399 -288.670131) (xy 101.703795 -288.639509) (xy 101.748401 -288.61543)
			(xy 101.796166 -288.598461) (xy 101.82098 -288.593276) (xy 101.84384 -288.588958) (xy 102.049072 -288.233866)
			(xy 102.041198 -288.211768) (xy 102.032576 -288.185419) (xy 102.023249 -288.130773) (xy 102.022656 -288.103056)
			(xy 102.023164 -288.077149) (xy 102.03127 -288.025972) (xy 102.047282 -287.976693) (xy 102.070805 -287.930526)
			(xy 102.101261 -287.888607) (xy 102.137899 -287.851969) (xy 102.179818 -287.821513) (xy 102.225985 -287.79799)
			(xy 102.275264 -287.781978) (xy 102.326441 -287.773872) (xy 102.378255 -287.773872) (xy 102.429432 -287.781978)
			(xy 102.478711 -287.79799) (xy 102.524878 -287.821513) (xy 102.566797 -287.851969) (xy 102.603435 -287.888607)
			(xy 102.633891 -287.930526) (xy 102.657414 -287.976693) (xy 102.673426 -288.025972) (xy 102.681532 -288.077149)
			(xy 102.68204 -288.103056) (xy 102.681618 -288.128404) (xy 102.673836 -288.178499) (xy 102.65848 -288.226813)
			(xy 102.635912 -288.272208) (xy 102.606662 -288.313614) (xy 102.571421 -288.350057) (xy 102.531018 -288.380678)
			(xy 102.486405 -288.404755) (xy 102.438632 -288.421722) (xy 102.413816 -288.426906) (xy 102.390956 -288.431224)
			(xy 102.185724 -288.786316) (xy 102.193598 -288.808414) (xy 102.20224 -288.834757) (xy 102.211554 -288.889407)
			(xy 102.21214 -288.917126) (xy 102.492556 -288.917126) (xy 102.493064 -288.891219) (xy 102.50117 -288.840042)
			(xy 102.517182 -288.790763) (xy 102.540705 -288.744596) (xy 102.571161 -288.702677) (xy 102.607799 -288.666039)
			(xy 102.649718 -288.635583) (xy 102.695885 -288.61206) (xy 102.745164 -288.596048) (xy 102.796341 -288.587942)
			(xy 102.848155 -288.587942) (xy 102.899332 -288.596048) (xy 102.948611 -288.61206) (xy 102.994778 -288.635583)
			(xy 103.036697 -288.666039) (xy 103.073335 -288.702677) (xy 103.103791 -288.744596) (xy 103.127314 -288.790763)
			(xy 103.143326 -288.840042) (xy 103.151432 -288.891219) (xy 103.15194 -288.917126) (xy 103.432356 -288.917126)
			(xy 103.432856 -288.891781) (xy 103.440625 -288.84169) (xy 103.455969 -288.793377) (xy 103.478527 -288.747983)
			(xy 103.507767 -288.706576) (xy 103.542999 -288.670131) (xy 103.583395 -288.639509) (xy 103.628001 -288.61543)
			(xy 103.675766 -288.598461) (xy 103.70058 -288.593276) (xy 103.72344 -288.588958) (xy 103.928672 -288.233866)
			(xy 103.920798 -288.211768) (xy 103.912176 -288.185419) (xy 103.902849 -288.130773) (xy 103.902256 -288.103056)
			(xy 103.902764 -288.077149) (xy 103.91087 -288.025972) (xy 103.926882 -287.976693) (xy 103.950405 -287.930526)
			(xy 103.980861 -287.888607) (xy 104.017499 -287.851969) (xy 104.059418 -287.821513) (xy 104.105585 -287.79799)
			(xy 104.154864 -287.781978) (xy 104.206041 -287.773872) (xy 104.257855 -287.773872) (xy 104.309032 -287.781978)
			(xy 104.358311 -287.79799) (xy 104.404478 -287.821513) (xy 104.446397 -287.851969) (xy 104.483035 -287.888607)
			(xy 104.513491 -287.930526) (xy 104.537014 -287.976693) (xy 104.553026 -288.025972) (xy 104.561132 -288.077149)
			(xy 104.56164 -288.103056) (xy 120.818656 -288.103056) (xy 120.819164 -288.077149) (xy 120.82727 -288.025972)
			(xy 120.843282 -287.976693) (xy 120.866805 -287.930526) (xy 120.897261 -287.888607) (xy 120.933899 -287.851969)
			(xy 120.975818 -287.821513) (xy 121.021985 -287.79799) (xy 121.071264 -287.781978) (xy 121.122441 -287.773872)
			(xy 121.174255 -287.773872) (xy 121.225432 -287.781978) (xy 121.274711 -287.79799) (xy 121.320878 -287.821513)
			(xy 121.362797 -287.851969) (xy 121.399435 -287.888607) (xy 121.429891 -287.930526) (xy 121.453414 -287.976693)
			(xy 121.469426 -288.025972) (xy 121.477532 -288.077149) (xy 121.47804 -288.103056) (xy 122.698256 -288.103056)
			(xy 122.698764 -288.077149) (xy 122.70687 -288.025972) (xy 122.722882 -287.976693) (xy 122.746405 -287.930526)
			(xy 122.776861 -287.888607) (xy 122.813499 -287.851969) (xy 122.855418 -287.821513) (xy 122.901585 -287.79799)
			(xy 122.950864 -287.781978) (xy 123.002041 -287.773872) (xy 123.053855 -287.773872) (xy 123.105032 -287.781978)
			(xy 123.154311 -287.79799) (xy 123.200478 -287.821513) (xy 123.242397 -287.851969) (xy 123.279035 -287.888607)
			(xy 123.309491 -287.930526) (xy 123.333014 -287.976693) (xy 123.349026 -288.025972) (xy 123.357132 -288.077149)
			(xy 123.35764 -288.103056) (xy 124.577856 -288.103056) (xy 124.578364 -288.077149) (xy 124.58647 -288.025972)
			(xy 124.602482 -287.976693) (xy 124.626005 -287.930526) (xy 124.656461 -287.888607) (xy 124.693099 -287.851969)
			(xy 124.735018 -287.821513) (xy 124.781185 -287.79799) (xy 124.830464 -287.781978) (xy 124.881641 -287.773872)
			(xy 124.933455 -287.773872) (xy 124.984632 -287.781978) (xy 125.033911 -287.79799) (xy 125.080078 -287.821513)
			(xy 125.121997 -287.851969) (xy 125.158635 -287.888607) (xy 125.189091 -287.930526) (xy 125.212614 -287.976693)
			(xy 125.228626 -288.025972) (xy 125.236732 -288.077149) (xy 125.23724 -288.103056) (xy 126.457456 -288.103056)
			(xy 126.457964 -288.077149) (xy 126.46607 -288.025972) (xy 126.482082 -287.976693) (xy 126.505605 -287.930526)
			(xy 126.536061 -287.888607) (xy 126.572699 -287.851969) (xy 126.614618 -287.821513) (xy 126.660785 -287.79799)
			(xy 126.710064 -287.781978) (xy 126.761241 -287.773872) (xy 126.813055 -287.773872) (xy 126.864232 -287.781978)
			(xy 126.913511 -287.79799) (xy 126.959678 -287.821513) (xy 127.001597 -287.851969) (xy 127.038235 -287.888607)
			(xy 127.068691 -287.930526) (xy 127.092214 -287.976693) (xy 127.108226 -288.025972) (xy 127.116332 -288.077149)
			(xy 127.11684 -288.103056) (xy 128.337056 -288.103056) (xy 128.337564 -288.077149) (xy 128.34567 -288.025972)
			(xy 128.361682 -287.976693) (xy 128.385205 -287.930526) (xy 128.415661 -287.888607) (xy 128.452299 -287.851969)
			(xy 128.494218 -287.821513) (xy 128.540385 -287.79799) (xy 128.589664 -287.781978) (xy 128.640841 -287.773872)
			(xy 128.692655 -287.773872) (xy 128.743832 -287.781978) (xy 128.793111 -287.79799) (xy 128.839278 -287.821513)
			(xy 128.881197 -287.851969) (xy 128.917835 -287.888607) (xy 128.948291 -287.930526) (xy 128.971814 -287.976693)
			(xy 128.987826 -288.025972) (xy 128.995932 -288.077149) (xy 128.99644 -288.103056) (xy 130.216656 -288.103056)
			(xy 130.217164 -288.077149) (xy 130.22527 -288.025972) (xy 130.241282 -287.976693) (xy 130.264805 -287.930526)
			(xy 130.295261 -287.888607) (xy 130.331899 -287.851969) (xy 130.373818 -287.821513) (xy 130.419985 -287.79799)
			(xy 130.469264 -287.781978) (xy 130.520441 -287.773872) (xy 130.572255 -287.773872) (xy 130.623432 -287.781978)
			(xy 130.672711 -287.79799) (xy 130.718878 -287.821513) (xy 130.760797 -287.851969) (xy 130.797435 -287.888607)
			(xy 130.827891 -287.930526) (xy 130.851414 -287.976693) (xy 130.867426 -288.025972) (xy 130.875532 -288.077149)
			(xy 130.87604 -288.103056) (xy 132.096256 -288.103056) (xy 132.096764 -288.077149) (xy 132.10487 -288.025972)
			(xy 132.120882 -287.976693) (xy 132.144405 -287.930526) (xy 132.174861 -287.888607) (xy 132.211499 -287.851969)
			(xy 132.253418 -287.821513) (xy 132.299585 -287.79799) (xy 132.348864 -287.781978) (xy 132.400041 -287.773872)
			(xy 132.451855 -287.773872) (xy 132.503032 -287.781978) (xy 132.552311 -287.79799) (xy 132.598478 -287.821513)
			(xy 132.640397 -287.851969) (xy 132.677035 -287.888607) (xy 132.707491 -287.930526) (xy 132.731014 -287.976693)
			(xy 132.747026 -288.025972) (xy 132.755132 -288.077149) (xy 132.75564 -288.103056) (xy 134.915656 -288.103056)
			(xy 134.916164 -288.077149) (xy 134.92427 -288.025972) (xy 134.940282 -287.976693) (xy 134.963805 -287.930526)
			(xy 134.994261 -287.888607) (xy 135.030899 -287.851969) (xy 135.072818 -287.821513) (xy 135.118985 -287.79799)
			(xy 135.168264 -287.781978) (xy 135.219441 -287.773872) (xy 135.271255 -287.773872) (xy 135.322432 -287.781978)
			(xy 135.371711 -287.79799) (xy 135.417878 -287.821513) (xy 135.459797 -287.851969) (xy 135.496435 -287.888607)
			(xy 135.526891 -287.930526) (xy 135.550414 -287.976693) (xy 135.566426 -288.025972) (xy 135.574532 -288.077149)
			(xy 135.57504 -288.103056) (xy 135.574438 -288.130773) (xy 135.56512 -288.18542) (xy 135.556498 -288.211768)
			(xy 135.548624 -288.233866) (xy 135.753856 -288.588958) (xy 135.776716 -288.593276) (xy 135.801527 -288.598486)
			(xy 135.849305 -288.615434) (xy 135.893924 -288.6395) (xy 135.934331 -288.670114) (xy 135.969573 -288.706556)
			(xy 135.998818 -288.747964) (xy 136.021377 -288.793363) (xy 136.036717 -288.841681) (xy 136.044477 -288.891779)
			(xy 136.04494 -288.917126) (xy 336.335624 -288.917126) (xy 336.336149 -288.891782) (xy 336.343918 -288.841693)
			(xy 336.359261 -288.793383) (xy 336.381816 -288.74799) (xy 336.411052 -288.706584) (xy 336.446281 -288.67014)
			(xy 336.486672 -288.639516) (xy 336.531274 -288.615435) (xy 336.579036 -288.598463) (xy 336.603848 -288.593276)
			(xy 336.626708 -288.588958) (xy 336.831686 -288.233866) (xy 336.823812 -288.212022) (xy 336.815238 -288.185602)
			(xy 336.806038 -288.130828) (xy 336.805524 -288.103056) (xy 336.806032 -288.077169) (xy 336.814131 -288.026031)
			(xy 336.83013 -287.976791) (xy 336.853636 -287.930659) (xy 336.884068 -287.888772) (xy 336.920678 -287.852162)
			(xy 336.962565 -287.82173) (xy 337.008697 -287.798224) (xy 337.057937 -287.782225) (xy 337.109075 -287.774126)
			(xy 337.160849 -287.774126) (xy 337.211987 -287.782225) (xy 337.261227 -287.798224) (xy 337.307359 -287.82173)
			(xy 337.349246 -287.852162) (xy 337.385856 -287.888772) (xy 337.416288 -287.930659) (xy 337.439794 -287.976791)
			(xy 337.455793 -288.026031) (xy 337.463892 -288.077169) (xy 337.4644 -288.103056) (xy 337.463968 -288.128392)
			(xy 337.456207 -288.178467) (xy 337.440877 -288.226765) (xy 337.418339 -288.272149) (xy 337.389123 -288.31355)
			(xy 337.353916 -288.349995) (xy 337.313549 -288.380624) (xy 337.268971 -288.404718) (xy 337.221232 -288.421708)
			(xy 337.19643 -288.426906) (xy 337.17357 -288.431224) (xy 336.968592 -288.786316) (xy 336.976466 -288.80816)
			(xy 336.985119 -288.834566) (xy 336.994435 -288.889344) (xy 336.995008 -288.917126) (xy 338.215224 -288.917126)
			(xy 338.215749 -288.891782) (xy 338.223518 -288.841693) (xy 338.238861 -288.793383) (xy 338.261416 -288.74799)
			(xy 338.290652 -288.706584) (xy 338.325881 -288.67014) (xy 338.366272 -288.639516) (xy 338.410874 -288.615435)
			(xy 338.458636 -288.598463) (xy 338.483448 -288.593276) (xy 338.506308 -288.588958) (xy 338.711286 -288.233866)
			(xy 338.703412 -288.212022) (xy 338.694838 -288.185602) (xy 338.685638 -288.130828) (xy 338.685124 -288.103056)
			(xy 338.685632 -288.077169) (xy 338.693731 -288.026031) (xy 338.70973 -287.976791) (xy 338.733236 -287.930659)
			(xy 338.763668 -287.888772) (xy 338.800278 -287.852162) (xy 338.842165 -287.82173) (xy 338.888297 -287.798224)
			(xy 338.937537 -287.782225) (xy 338.988675 -287.774126) (xy 339.040449 -287.774126) (xy 339.091587 -287.782225)
			(xy 339.140827 -287.798224) (xy 339.186959 -287.82173) (xy 339.228846 -287.852162) (xy 339.265456 -287.888772)
			(xy 339.295888 -287.930659) (xy 339.319394 -287.976791) (xy 339.335393 -288.026031) (xy 339.343492 -288.077169)
			(xy 339.344 -288.103056) (xy 339.343568 -288.128392) (xy 339.335807 -288.178467) (xy 339.320477 -288.226765)
			(xy 339.297939 -288.272149) (xy 339.268723 -288.31355) (xy 339.233516 -288.349995) (xy 339.193149 -288.380624)
			(xy 339.148571 -288.404718) (xy 339.100832 -288.421708) (xy 339.07603 -288.426906) (xy 339.05317 -288.431224)
			(xy 338.848192 -288.786316) (xy 338.856066 -288.80816) (xy 338.864719 -288.834566) (xy 338.874035 -288.889344)
			(xy 338.874608 -288.917126) (xy 339.155024 -288.917126) (xy 339.155532 -288.891219) (xy 339.163638 -288.840042)
			(xy 339.17965 -288.790763) (xy 339.203173 -288.744596) (xy 339.233629 -288.702677) (xy 339.270267 -288.666039)
			(xy 339.312186 -288.635583) (xy 339.358353 -288.61206) (xy 339.407632 -288.596048) (xy 339.458809 -288.587942)
			(xy 339.510623 -288.587942) (xy 339.5618 -288.596048) (xy 339.611079 -288.61206) (xy 339.657246 -288.635583)
			(xy 339.699165 -288.666039) (xy 339.735803 -288.702677) (xy 339.766259 -288.744596) (xy 339.789782 -288.790763)
			(xy 339.805794 -288.840042) (xy 339.8139 -288.891219) (xy 339.814408 -288.917126) (xy 340.094824 -288.917126)
			(xy 340.095349 -288.891782) (xy 340.103118 -288.841693) (xy 340.118461 -288.793383) (xy 340.141016 -288.74799)
			(xy 340.170252 -288.706584) (xy 340.205481 -288.67014) (xy 340.245872 -288.639516) (xy 340.290474 -288.615435)
			(xy 340.338236 -288.598463) (xy 340.363048 -288.593276) (xy 340.385908 -288.588958) (xy 340.59114 -288.233866)
			(xy 340.583266 -288.211768) (xy 340.574642 -288.185419) (xy 340.565317 -288.130773) (xy 340.564724 -288.103056)
			(xy 340.565232 -288.077149) (xy 340.573338 -288.025972) (xy 340.58935 -287.976693) (xy 340.612873 -287.930526)
			(xy 340.643329 -287.888607) (xy 340.679967 -287.851969) (xy 340.721886 -287.821513) (xy 340.768053 -287.79799)
			(xy 340.817332 -287.781978) (xy 340.868509 -287.773872) (xy 340.920323 -287.773872) (xy 340.9715 -287.781978)
			(xy 341.020779 -287.79799) (xy 341.066946 -287.821513) (xy 341.108865 -287.851969) (xy 341.145503 -287.888607)
			(xy 341.175959 -287.930526) (xy 341.199482 -287.976693) (xy 341.215494 -288.025972) (xy 341.2236 -288.077149)
			(xy 341.224108 -288.103056) (xy 341.223631 -288.128401) (xy 341.215851 -288.178491) (xy 341.200499 -288.2268)
			(xy 341.177936 -288.272192) (xy 341.148694 -288.313597) (xy 341.11346 -288.35004) (xy 341.073065 -288.380663)
			(xy 341.028461 -288.404744) (xy 340.980697 -288.421718) (xy 340.955884 -288.426906) (xy 340.933024 -288.431224)
			(xy 340.727792 -288.786316) (xy 340.735666 -288.808414) (xy 340.744307 -288.834758) (xy 340.753621 -288.889407)
			(xy 340.754208 -288.917126) (xy 341.034624 -288.917126) (xy 341.035132 -288.891219) (xy 341.043238 -288.840042)
			(xy 341.05925 -288.790763) (xy 341.082773 -288.744596) (xy 341.113229 -288.702677) (xy 341.149867 -288.666039)
			(xy 341.191786 -288.635583) (xy 341.237953 -288.61206) (xy 341.287232 -288.596048) (xy 341.338409 -288.587942)
			(xy 341.390223 -288.587942) (xy 341.4414 -288.596048) (xy 341.490679 -288.61206) (xy 341.536846 -288.635583)
			(xy 341.578765 -288.666039) (xy 341.615403 -288.702677) (xy 341.645859 -288.744596) (xy 341.669382 -288.790763)
			(xy 341.685394 -288.840042) (xy 341.6935 -288.891219) (xy 341.694008 -288.917126) (xy 341.974424 -288.917126)
			(xy 341.974949 -288.891782) (xy 341.982718 -288.841693) (xy 341.998061 -288.793383) (xy 342.020616 -288.74799)
			(xy 342.049852 -288.706584) (xy 342.085081 -288.67014) (xy 342.125472 -288.639516) (xy 342.170074 -288.615435)
			(xy 342.217836 -288.598463) (xy 342.242648 -288.593276) (xy 342.265508 -288.588958) (xy 342.47074 -288.233866)
			(xy 342.462866 -288.211768) (xy 342.454242 -288.185419) (xy 342.444917 -288.130773) (xy 342.444324 -288.103056)
			(xy 342.444832 -288.077149) (xy 342.452938 -288.025972) (xy 342.46895 -287.976693) (xy 342.492473 -287.930526)
			(xy 342.522929 -287.888607) (xy 342.559567 -287.851969) (xy 342.601486 -287.821513) (xy 342.647653 -287.79799)
			(xy 342.696932 -287.781978) (xy 342.748109 -287.773872) (xy 342.799923 -287.773872) (xy 342.8511 -287.781978)
			(xy 342.900379 -287.79799) (xy 342.946546 -287.821513) (xy 342.988465 -287.851969) (xy 343.025103 -287.888607)
			(xy 343.055559 -287.930526) (xy 343.079082 -287.976693) (xy 343.095094 -288.025972) (xy 343.1032 -288.077149)
			(xy 343.103708 -288.103056) (xy 343.103231 -288.128401) (xy 343.095451 -288.178491) (xy 343.080099 -288.2268)
			(xy 343.057536 -288.272192) (xy 343.028294 -288.313597) (xy 342.99306 -288.35004) (xy 342.952665 -288.380663)
			(xy 342.908061 -288.404744) (xy 342.860297 -288.421718) (xy 342.835484 -288.426906) (xy 342.812624 -288.431224)
			(xy 342.607392 -288.786316) (xy 342.615266 -288.808414) (xy 342.623907 -288.834758) (xy 342.633221 -288.889407)
			(xy 342.633808 -288.917126) (xy 342.914224 -288.917126) (xy 342.914732 -288.891219) (xy 342.922838 -288.840042)
			(xy 342.93885 -288.790763) (xy 342.962373 -288.744596) (xy 342.992829 -288.702677) (xy 343.029467 -288.666039)
			(xy 343.071386 -288.635583) (xy 343.117553 -288.61206) (xy 343.166832 -288.596048) (xy 343.218009 -288.587942)
			(xy 343.269823 -288.587942) (xy 343.321 -288.596048) (xy 343.370279 -288.61206) (xy 343.416446 -288.635583)
			(xy 343.458365 -288.666039) (xy 343.495003 -288.702677) (xy 343.525459 -288.744596) (xy 343.548982 -288.790763)
			(xy 343.564994 -288.840042) (xy 343.5731 -288.891219) (xy 343.573608 -288.917126) (xy 343.854024 -288.917126)
			(xy 343.854549 -288.891782) (xy 343.862318 -288.841693) (xy 343.877661 -288.793383) (xy 343.900216 -288.74799)
			(xy 343.929452 -288.706584) (xy 343.964681 -288.67014) (xy 344.005072 -288.639516) (xy 344.049674 -288.615435)
			(xy 344.097436 -288.598463) (xy 344.122248 -288.593276) (xy 344.145108 -288.588958) (xy 344.35034 -288.233866)
			(xy 344.342466 -288.211768) (xy 344.333842 -288.185419) (xy 344.324517 -288.130773) (xy 344.323924 -288.103056)
			(xy 344.324432 -288.077149) (xy 344.332538 -288.025972) (xy 344.34855 -287.976693) (xy 344.372073 -287.930526)
			(xy 344.402529 -287.888607) (xy 344.439167 -287.851969) (xy 344.481086 -287.821513) (xy 344.527253 -287.79799)
			(xy 344.576532 -287.781978) (xy 344.627709 -287.773872) (xy 344.679523 -287.773872) (xy 344.7307 -287.781978)
			(xy 344.779979 -287.79799) (xy 344.826146 -287.821513) (xy 344.868065 -287.851969) (xy 344.904703 -287.888607)
			(xy 344.935159 -287.930526) (xy 344.958682 -287.976693) (xy 344.974694 -288.025972) (xy 344.9828 -288.077149)
			(xy 344.983308 -288.103056) (xy 344.982831 -288.128401) (xy 344.975051 -288.178491) (xy 344.959699 -288.2268)
			(xy 344.937136 -288.272192) (xy 344.907894 -288.313597) (xy 344.87266 -288.35004) (xy 344.832265 -288.380663)
			(xy 344.787661 -288.404744) (xy 344.739897 -288.421718) (xy 344.715084 -288.426906) (xy 344.692224 -288.431224)
			(xy 344.486992 -288.786316) (xy 344.494866 -288.808414) (xy 344.503507 -288.834758) (xy 344.512821 -288.889407)
			(xy 344.513408 -288.917126) (xy 344.793824 -288.917126) (xy 344.794332 -288.891219) (xy 344.802438 -288.840042)
			(xy 344.81845 -288.790763) (xy 344.841973 -288.744596) (xy 344.872429 -288.702677) (xy 344.909067 -288.666039)
			(xy 344.950986 -288.635583) (xy 344.997153 -288.61206) (xy 345.046432 -288.596048) (xy 345.097609 -288.587942)
			(xy 345.149423 -288.587942) (xy 345.2006 -288.596048) (xy 345.249879 -288.61206) (xy 345.296046 -288.635583)
			(xy 345.337965 -288.666039) (xy 345.374603 -288.702677) (xy 345.405059 -288.744596) (xy 345.428582 -288.790763)
			(xy 345.444594 -288.840042) (xy 345.4527 -288.891219) (xy 345.453208 -288.917126) (xy 345.733624 -288.917126)
			(xy 345.734149 -288.891782) (xy 345.741918 -288.841693) (xy 345.757261 -288.793383) (xy 345.779816 -288.74799)
			(xy 345.809052 -288.706584) (xy 345.844281 -288.67014) (xy 345.884672 -288.639516) (xy 345.929274 -288.615435)
			(xy 345.977036 -288.598463) (xy 346.001848 -288.593276) (xy 346.024708 -288.588958) (xy 346.22994 -288.233866)
			(xy 346.222066 -288.211768) (xy 346.213442 -288.185419) (xy 346.204117 -288.130773) (xy 346.203524 -288.103056)
			(xy 346.204032 -288.077149) (xy 346.212138 -288.025972) (xy 346.22815 -287.976693) (xy 346.251673 -287.930526)
			(xy 346.282129 -287.888607) (xy 346.318767 -287.851969) (xy 346.360686 -287.821513) (xy 346.406853 -287.79799)
			(xy 346.456132 -287.781978) (xy 346.507309 -287.773872) (xy 346.559123 -287.773872) (xy 346.6103 -287.781978)
			(xy 346.659579 -287.79799) (xy 346.705746 -287.821513) (xy 346.747665 -287.851969) (xy 346.784303 -287.888607)
			(xy 346.814759 -287.930526) (xy 346.838282 -287.976693) (xy 346.854294 -288.025972) (xy 346.8624 -288.077149)
			(xy 346.862908 -288.103056) (xy 346.862431 -288.128401) (xy 346.854651 -288.178491) (xy 346.839299 -288.2268)
			(xy 346.816736 -288.272192) (xy 346.787494 -288.313597) (xy 346.75226 -288.35004) (xy 346.711865 -288.380663)
			(xy 346.667261 -288.404744) (xy 346.619497 -288.421718) (xy 346.594684 -288.426906) (xy 346.571824 -288.431224)
			(xy 346.366592 -288.786316) (xy 346.374466 -288.808414) (xy 346.383107 -288.834758) (xy 346.392421 -288.889407)
			(xy 346.393008 -288.917126) (xy 346.673424 -288.917126) (xy 346.673932 -288.891219) (xy 346.682038 -288.840042)
			(xy 346.69805 -288.790763) (xy 346.721573 -288.744596) (xy 346.752029 -288.702677) (xy 346.788667 -288.666039)
			(xy 346.830586 -288.635583) (xy 346.876753 -288.61206) (xy 346.926032 -288.596048) (xy 346.977209 -288.587942)
			(xy 347.029023 -288.587942) (xy 347.0802 -288.596048) (xy 347.129479 -288.61206) (xy 347.175646 -288.635583)
			(xy 347.217565 -288.666039) (xy 347.254203 -288.702677) (xy 347.284659 -288.744596) (xy 347.308182 -288.790763)
			(xy 347.324194 -288.840042) (xy 347.3323 -288.891219) (xy 347.332808 -288.917126) (xy 347.613224 -288.917126)
			(xy 347.613749 -288.891782) (xy 347.621518 -288.841693) (xy 347.636861 -288.793383) (xy 347.659416 -288.74799)
			(xy 347.688652 -288.706584) (xy 347.723881 -288.67014) (xy 347.764272 -288.639516) (xy 347.808874 -288.615435)
			(xy 347.856636 -288.598463) (xy 347.881448 -288.593276) (xy 347.904308 -288.588958) (xy 348.10954 -288.233866)
			(xy 348.101666 -288.211768) (xy 348.093042 -288.185419) (xy 348.083717 -288.130773) (xy 348.083124 -288.103056)
			(xy 348.083632 -288.077149) (xy 348.091738 -288.025972) (xy 348.10775 -287.976693) (xy 348.131273 -287.930526)
			(xy 348.161729 -287.888607) (xy 348.198367 -287.851969) (xy 348.240286 -287.821513) (xy 348.286453 -287.79799)
			(xy 348.335732 -287.781978) (xy 348.386909 -287.773872) (xy 348.438723 -287.773872) (xy 348.4899 -287.781978)
			(xy 348.539179 -287.79799) (xy 348.585346 -287.821513) (xy 348.627265 -287.851969) (xy 348.663903 -287.888607)
			(xy 348.694359 -287.930526) (xy 348.717882 -287.976693) (xy 348.733894 -288.025972) (xy 348.742 -288.077149)
			(xy 348.742508 -288.103056) (xy 348.742031 -288.128401) (xy 348.734251 -288.178491) (xy 348.718899 -288.2268)
			(xy 348.696336 -288.272192) (xy 348.667094 -288.313597) (xy 348.63186 -288.35004) (xy 348.591465 -288.380663)
			(xy 348.546861 -288.404744) (xy 348.499097 -288.421718) (xy 348.474284 -288.426906) (xy 348.451424 -288.431224)
			(xy 348.246192 -288.786316) (xy 348.254066 -288.808414) (xy 348.262707 -288.834758) (xy 348.272021 -288.889407)
			(xy 348.272608 -288.917126) (xy 348.553024 -288.917126) (xy 348.553532 -288.891219) (xy 348.561638 -288.840042)
			(xy 348.57765 -288.790763) (xy 348.601173 -288.744596) (xy 348.631629 -288.702677) (xy 348.668267 -288.666039)
			(xy 348.710186 -288.635583) (xy 348.756353 -288.61206) (xy 348.805632 -288.596048) (xy 348.856809 -288.587942)
			(xy 348.908623 -288.587942) (xy 348.9598 -288.596048) (xy 349.009079 -288.61206) (xy 349.055246 -288.635583)
			(xy 349.097165 -288.666039) (xy 349.133803 -288.702677) (xy 349.164259 -288.744596) (xy 349.187782 -288.790763)
			(xy 349.203794 -288.840042) (xy 349.2119 -288.891219) (xy 349.212408 -288.917126) (xy 349.492824 -288.917126)
			(xy 349.493349 -288.891782) (xy 349.501118 -288.841693) (xy 349.516461 -288.793383) (xy 349.539016 -288.74799)
			(xy 349.568252 -288.706584) (xy 349.603481 -288.67014) (xy 349.643872 -288.639516) (xy 349.688474 -288.615435)
			(xy 349.736236 -288.598463) (xy 349.761048 -288.593276) (xy 349.783908 -288.588958) (xy 349.98914 -288.233866)
			(xy 349.981266 -288.211768) (xy 349.972642 -288.185419) (xy 349.963317 -288.130773) (xy 349.962724 -288.103056)
			(xy 349.963232 -288.077149) (xy 349.971338 -288.025972) (xy 349.98735 -287.976693) (xy 350.010873 -287.930526)
			(xy 350.041329 -287.888607) (xy 350.077967 -287.851969) (xy 350.119886 -287.821513) (xy 350.166053 -287.79799)
			(xy 350.215332 -287.781978) (xy 350.266509 -287.773872) (xy 350.318323 -287.773872) (xy 350.3695 -287.781978)
			(xy 350.418779 -287.79799) (xy 350.464946 -287.821513) (xy 350.506865 -287.851969) (xy 350.543503 -287.888607)
			(xy 350.573959 -287.930526) (xy 350.597482 -287.976693) (xy 350.613494 -288.025972) (xy 350.6216 -288.077149)
			(xy 350.622108 -288.103056) (xy 350.621631 -288.128401) (xy 350.613851 -288.178491) (xy 350.598499 -288.2268)
			(xy 350.575936 -288.272192) (xy 350.546694 -288.313597) (xy 350.51146 -288.35004) (xy 350.471065 -288.380663)
			(xy 350.426461 -288.404744) (xy 350.378697 -288.421718) (xy 350.353884 -288.426906) (xy 350.331024 -288.431224)
			(xy 350.125792 -288.786316) (xy 350.133666 -288.808414) (xy 350.142307 -288.834758) (xy 350.151621 -288.889407)
			(xy 350.152208 -288.917126) (xy 350.432624 -288.917126) (xy 350.433132 -288.891219) (xy 350.441238 -288.840042)
			(xy 350.45725 -288.790763) (xy 350.480773 -288.744596) (xy 350.511229 -288.702677) (xy 350.547867 -288.666039)
			(xy 350.589786 -288.635583) (xy 350.635953 -288.61206) (xy 350.685232 -288.596048) (xy 350.736409 -288.587942)
			(xy 350.788223 -288.587942) (xy 350.8394 -288.596048) (xy 350.888679 -288.61206) (xy 350.934846 -288.635583)
			(xy 350.976765 -288.666039) (xy 351.013403 -288.702677) (xy 351.043859 -288.744596) (xy 351.067382 -288.790763)
			(xy 351.083394 -288.840042) (xy 351.0915 -288.891219) (xy 351.092008 -288.917126) (xy 351.372424 -288.917126)
			(xy 351.372949 -288.891782) (xy 351.380718 -288.841693) (xy 351.396061 -288.793383) (xy 351.418616 -288.74799)
			(xy 351.447852 -288.706584) (xy 351.483081 -288.67014) (xy 351.523472 -288.639516) (xy 351.568074 -288.615435)
			(xy 351.615836 -288.598463) (xy 351.640648 -288.593276) (xy 351.663508 -288.588958) (xy 351.86874 -288.233866)
			(xy 351.860866 -288.211768) (xy 351.852242 -288.185419) (xy 351.842917 -288.130773) (xy 351.842324 -288.103056)
			(xy 351.842832 -288.077149) (xy 351.850938 -288.025972) (xy 351.86695 -287.976693) (xy 351.890473 -287.930526)
			(xy 351.920929 -287.888607) (xy 351.957567 -287.851969) (xy 351.999486 -287.821513) (xy 352.045653 -287.79799)
			(xy 352.094932 -287.781978) (xy 352.146109 -287.773872) (xy 352.197923 -287.773872) (xy 352.2491 -287.781978)
			(xy 352.298379 -287.79799) (xy 352.344546 -287.821513) (xy 352.386465 -287.851969) (xy 352.423103 -287.888607)
			(xy 352.453559 -287.930526) (xy 352.477082 -287.976693) (xy 352.493094 -288.025972) (xy 352.5012 -288.077149)
			(xy 352.501708 -288.103056) (xy 368.758724 -288.103056) (xy 368.759232 -288.077149) (xy 368.767338 -288.025972)
			(xy 368.78335 -287.976693) (xy 368.806873 -287.930526) (xy 368.837329 -287.888607) (xy 368.873967 -287.851969)
			(xy 368.915886 -287.821513) (xy 368.962053 -287.79799) (xy 369.011332 -287.781978) (xy 369.062509 -287.773872)
			(xy 369.114323 -287.773872) (xy 369.1655 -287.781978) (xy 369.214779 -287.79799) (xy 369.260946 -287.821513)
			(xy 369.302865 -287.851969) (xy 369.339503 -287.888607) (xy 369.369959 -287.930526) (xy 369.393482 -287.976693)
			(xy 369.409494 -288.025972) (xy 369.4176 -288.077149) (xy 369.418108 -288.103056) (xy 370.638324 -288.103056)
			(xy 370.638832 -288.077149) (xy 370.646938 -288.025972) (xy 370.66295 -287.976693) (xy 370.686473 -287.930526)
			(xy 370.716929 -287.888607) (xy 370.753567 -287.851969) (xy 370.795486 -287.821513) (xy 370.841653 -287.79799)
			(xy 370.890932 -287.781978) (xy 370.942109 -287.773872) (xy 370.993923 -287.773872) (xy 371.0451 -287.781978)
			(xy 371.094379 -287.79799) (xy 371.140546 -287.821513) (xy 371.182465 -287.851969) (xy 371.219103 -287.888607)
			(xy 371.249559 -287.930526) (xy 371.273082 -287.976693) (xy 371.289094 -288.025972) (xy 371.2972 -288.077149)
			(xy 371.297708 -288.103056) (xy 372.517924 -288.103056) (xy 372.518432 -288.077149) (xy 372.526538 -288.025972)
			(xy 372.54255 -287.976693) (xy 372.566073 -287.930526) (xy 372.596529 -287.888607) (xy 372.633167 -287.851969)
			(xy 372.675086 -287.821513) (xy 372.721253 -287.79799) (xy 372.770532 -287.781978) (xy 372.821709 -287.773872)
			(xy 372.873523 -287.773872) (xy 372.9247 -287.781978) (xy 372.973979 -287.79799) (xy 373.020146 -287.821513)
			(xy 373.062065 -287.851969) (xy 373.098703 -287.888607) (xy 373.129159 -287.930526) (xy 373.152682 -287.976693)
			(xy 373.168694 -288.025972) (xy 373.1768 -288.077149) (xy 373.177308 -288.103056) (xy 374.397524 -288.103056)
			(xy 374.398032 -288.077149) (xy 374.406138 -288.025972) (xy 374.42215 -287.976693) (xy 374.445673 -287.930526)
			(xy 374.476129 -287.888607) (xy 374.512767 -287.851969) (xy 374.554686 -287.821513) (xy 374.600853 -287.79799)
			(xy 374.650132 -287.781978) (xy 374.701309 -287.773872) (xy 374.753123 -287.773872) (xy 374.8043 -287.781978)
			(xy 374.853579 -287.79799) (xy 374.899746 -287.821513) (xy 374.941665 -287.851969) (xy 374.978303 -287.888607)
			(xy 375.008759 -287.930526) (xy 375.032282 -287.976693) (xy 375.048294 -288.025972) (xy 375.0564 -288.077149)
			(xy 375.056908 -288.103056) (xy 376.277124 -288.103056) (xy 376.277632 -288.077149) (xy 376.285738 -288.025972)
			(xy 376.30175 -287.976693) (xy 376.325273 -287.930526) (xy 376.355729 -287.888607) (xy 376.392367 -287.851969)
			(xy 376.434286 -287.821513) (xy 376.480453 -287.79799) (xy 376.529732 -287.781978) (xy 376.580909 -287.773872)
			(xy 376.632723 -287.773872) (xy 376.6839 -287.781978) (xy 376.733179 -287.79799) (xy 376.779346 -287.821513)
			(xy 376.821265 -287.851969) (xy 376.857903 -287.888607) (xy 376.888359 -287.930526) (xy 376.911882 -287.976693)
			(xy 376.927894 -288.025972) (xy 376.936 -288.077149) (xy 376.936508 -288.103056) (xy 378.156724 -288.103056)
			(xy 378.157232 -288.077149) (xy 378.165338 -288.025972) (xy 378.18135 -287.976693) (xy 378.204873 -287.930526)
			(xy 378.235329 -287.888607) (xy 378.271967 -287.851969) (xy 378.313886 -287.821513) (xy 378.360053 -287.79799)
			(xy 378.409332 -287.781978) (xy 378.460509 -287.773872) (xy 378.512323 -287.773872) (xy 378.5635 -287.781978)
			(xy 378.612779 -287.79799) (xy 378.658946 -287.821513) (xy 378.700865 -287.851969) (xy 378.737503 -287.888607)
			(xy 378.767959 -287.930526) (xy 378.791482 -287.976693) (xy 378.807494 -288.025972) (xy 378.8156 -288.077149)
			(xy 378.816108 -288.103056) (xy 380.036324 -288.103056) (xy 380.036832 -288.077149) (xy 380.044938 -288.025972)
			(xy 380.06095 -287.976693) (xy 380.084473 -287.930526) (xy 380.114929 -287.888607) (xy 380.151567 -287.851969)
			(xy 380.193486 -287.821513) (xy 380.239653 -287.79799) (xy 380.288932 -287.781978) (xy 380.340109 -287.773872)
			(xy 380.391923 -287.773872) (xy 380.4431 -287.781978) (xy 380.492379 -287.79799) (xy 380.538546 -287.821513)
			(xy 380.580465 -287.851969) (xy 380.617103 -287.888607) (xy 380.647559 -287.930526) (xy 380.671082 -287.976693)
			(xy 380.687094 -288.025972) (xy 380.6952 -288.077149) (xy 380.695708 -288.103056) (xy 382.855724 -288.103056)
			(xy 382.856232 -288.077149) (xy 382.864338 -288.025972) (xy 382.88035 -287.976693) (xy 382.903873 -287.930526)
			(xy 382.934329 -287.888607) (xy 382.970967 -287.851969) (xy 383.012886 -287.821513) (xy 383.059053 -287.79799)
			(xy 383.108332 -287.781978) (xy 383.159509 -287.773872) (xy 383.211323 -287.773872) (xy 383.2625 -287.781978)
			(xy 383.311779 -287.79799) (xy 383.357946 -287.821513) (xy 383.399865 -287.851969) (xy 383.436503 -287.888607)
			(xy 383.466959 -287.930526) (xy 383.490482 -287.976693) (xy 383.506494 -288.025972) (xy 383.5146 -288.077149)
			(xy 383.515108 -288.103056) (xy 383.514503 -288.130773) (xy 383.505187 -288.185419) (xy 383.496566 -288.211768)
			(xy 383.488692 -288.233866) (xy 383.693924 -288.588958) (xy 383.716784 -288.593276) (xy 383.741606 -288.598437)
			(xy 383.789384 -288.615395) (xy 383.834001 -288.639469) (xy 383.874406 -288.67009) (xy 383.909646 -288.706538)
			(xy 383.93889 -288.747952) (xy 383.961447 -288.793355) (xy 383.976786 -288.841676) (xy 383.984545 -288.891777)
			(xy 383.985008 -288.917126) (xy 383.9845 -288.943033) (xy 383.976394 -288.99421) (xy 383.960382 -289.043489)
			(xy 383.936859 -289.089656) (xy 383.906403 -289.131575) (xy 383.869765 -289.168213) (xy 383.827846 -289.198669)
			(xy 383.781679 -289.222192) (xy 383.7324 -289.238204) (xy 383.681223 -289.24631) (xy 383.629409 -289.24631)
			(xy 383.578232 -289.238204) (xy 383.528953 -289.222192) (xy 383.482786 -289.198669) (xy 383.440867 -289.168213)
			(xy 383.404229 -289.131575) (xy 383.373773 -289.089656) (xy 383.35025 -289.043489) (xy 383.334238 -288.99421)
			(xy 383.326132 -288.943033) (xy 383.325624 -288.917126) (xy 383.326223 -288.889409) (xy 383.335543 -288.834762)
			(xy 383.344166 -288.808414) (xy 383.35204 -288.786316) (xy 383.146808 -288.431224) (xy 383.123948 -288.426906)
			(xy 383.099127 -288.421739) (xy 383.051348 -288.404784) (xy 383.006729 -288.380713) (xy 382.966322 -288.350092)
			(xy 382.931082 -288.313646) (xy 382.901838 -288.272232) (xy 382.879281 -288.226828) (xy 382.863943 -288.178506)
			(xy 382.856186 -288.128405) (xy 382.855724 -288.103056) (xy 380.695708 -288.103056) (xy 380.695103 -288.130773)
			(xy 380.685787 -288.185419) (xy 380.677166 -288.211768) (xy 380.669546 -288.233866) (xy 380.874524 -288.588958)
			(xy 380.897384 -288.593276) (xy 380.922206 -288.598437) (xy 380.969984 -288.615395) (xy 381.014601 -288.639469)
			(xy 381.055006 -288.67009) (xy 381.090246 -288.706538) (xy 381.11949 -288.747952) (xy 381.142047 -288.793355)
			(xy 381.157386 -288.841676) (xy 381.165145 -288.891777) (xy 381.165608 -288.917126) (xy 381.1651 -288.943033)
			(xy 381.156994 -288.99421) (xy 381.140982 -289.043489) (xy 381.117459 -289.089656) (xy 381.087003 -289.131575)
			(xy 381.050365 -289.168213) (xy 381.008446 -289.198669) (xy 380.962279 -289.222192) (xy 380.913 -289.238204)
			(xy 380.861823 -289.24631) (xy 380.810009 -289.24631) (xy 380.758832 -289.238204) (xy 380.709553 -289.222192)
			(xy 380.663386 -289.198669) (xy 380.621467 -289.168213) (xy 380.584829 -289.131575) (xy 380.554373 -289.089656)
			(xy 380.53085 -289.043489) (xy 380.514838 -288.99421) (xy 380.506732 -288.943033) (xy 380.506224 -288.917126)
			(xy 380.506823 -288.889409) (xy 380.516143 -288.834762) (xy 380.524766 -288.808414) (xy 380.53264 -288.786316)
			(xy 380.327662 -288.431224) (xy 380.304802 -288.426906) (xy 380.279961 -288.421779) (xy 380.232152 -288.40484)
			(xy 380.187502 -288.380778) (xy 380.147063 -288.350162) (xy 380.111791 -288.313713) (xy 380.082517 -288.272293)
			(xy 380.059933 -288.226877) (xy 380.044571 -288.178538) (xy 380.036794 -288.128417) (xy 380.036324 -288.103056)
			(xy 378.816108 -288.103056) (xy 378.815503 -288.130773) (xy 378.806187 -288.185419) (xy 378.797566 -288.211768)
			(xy 378.789946 -288.233866) (xy 378.994924 -288.588958) (xy 379.017784 -288.593276) (xy 379.042606 -288.598437)
			(xy 379.090384 -288.615395) (xy 379.135001 -288.639469) (xy 379.175406 -288.67009) (xy 379.210646 -288.706538)
			(xy 379.23989 -288.747952) (xy 379.262447 -288.793355) (xy 379.277786 -288.841676) (xy 379.285545 -288.891777)
			(xy 379.286008 -288.917126) (xy 379.2855 -288.943033) (xy 379.277394 -288.99421) (xy 379.261382 -289.043489)
			(xy 379.237859 -289.089656) (xy 379.207403 -289.131575) (xy 379.170765 -289.168213) (xy 379.128846 -289.198669)
			(xy 379.082679 -289.222192) (xy 379.0334 -289.238204) (xy 378.982223 -289.24631) (xy 378.930409 -289.24631)
			(xy 378.879232 -289.238204) (xy 378.829953 -289.222192) (xy 378.783786 -289.198669) (xy 378.741867 -289.168213)
			(xy 378.705229 -289.131575) (xy 378.674773 -289.089656) (xy 378.65125 -289.043489) (xy 378.635238 -288.99421)
			(xy 378.627132 -288.943033) (xy 378.626624 -288.917126) (xy 378.627223 -288.889409) (xy 378.636543 -288.834762)
			(xy 378.645166 -288.808414) (xy 378.65304 -288.786316) (xy 378.448062 -288.431224) (xy 378.425202 -288.426906)
			(xy 378.400361 -288.421779) (xy 378.352552 -288.40484) (xy 378.307902 -288.380778) (xy 378.267463 -288.350162)
			(xy 378.232191 -288.313713) (xy 378.202917 -288.272293) (xy 378.180333 -288.226877) (xy 378.164971 -288.178538)
			(xy 378.157194 -288.128417) (xy 378.156724 -288.103056) (xy 376.936508 -288.103056) (xy 376.935903 -288.130773)
			(xy 376.926587 -288.185419) (xy 376.917966 -288.211768) (xy 376.910346 -288.233866) (xy 377.115324 -288.588958)
			(xy 377.138184 -288.593276) (xy 377.163006 -288.598437) (xy 377.210784 -288.615395) (xy 377.255401 -288.639469)
			(xy 377.295806 -288.67009) (xy 377.331046 -288.706538) (xy 377.36029 -288.747952) (xy 377.382847 -288.793355)
			(xy 377.398186 -288.841676) (xy 377.405945 -288.891777) (xy 377.406408 -288.917126) (xy 377.4059 -288.943033)
			(xy 377.397794 -288.99421) (xy 377.381782 -289.043489) (xy 377.358259 -289.089656) (xy 377.327803 -289.131575)
			(xy 377.291165 -289.168213) (xy 377.249246 -289.198669) (xy 377.203079 -289.222192) (xy 377.1538 -289.238204)
			(xy 377.102623 -289.24631) (xy 377.050809 -289.24631) (xy 376.999632 -289.238204) (xy 376.950353 -289.222192)
			(xy 376.904186 -289.198669) (xy 376.862267 -289.168213) (xy 376.825629 -289.131575) (xy 376.795173 -289.089656)
			(xy 376.77165 -289.043489) (xy 376.755638 -288.99421) (xy 376.747532 -288.943033) (xy 376.747024 -288.917126)
			(xy 376.747623 -288.889409) (xy 376.756943 -288.834762) (xy 376.765566 -288.808414) (xy 376.77344 -288.786316)
			(xy 376.568462 -288.431224) (xy 376.545602 -288.426906) (xy 376.520761 -288.421779) (xy 376.472952 -288.40484)
			(xy 376.428302 -288.380778) (xy 376.387863 -288.350162) (xy 376.352591 -288.313713) (xy 376.323317 -288.272293)
			(xy 376.300733 -288.226877) (xy 376.285371 -288.178538) (xy 376.277594 -288.128417) (xy 376.277124 -288.103056)
			(xy 375.056908 -288.103056) (xy 375.056303 -288.130773) (xy 375.046987 -288.185419) (xy 375.038366 -288.211768)
			(xy 375.030746 -288.233866) (xy 375.235724 -288.588958) (xy 375.258584 -288.593276) (xy 375.283406 -288.598437)
			(xy 375.331184 -288.615395) (xy 375.375801 -288.639469) (xy 375.416206 -288.67009) (xy 375.451446 -288.706538)
			(xy 375.48069 -288.747952) (xy 375.503247 -288.793355) (xy 375.518586 -288.841676) (xy 375.526345 -288.891777)
			(xy 375.526808 -288.917126) (xy 375.5263 -288.943033) (xy 375.518194 -288.99421) (xy 375.502182 -289.043489)
			(xy 375.478659 -289.089656) (xy 375.448203 -289.131575) (xy 375.411565 -289.168213) (xy 375.369646 -289.198669)
			(xy 375.323479 -289.222192) (xy 375.2742 -289.238204) (xy 375.223023 -289.24631) (xy 375.171209 -289.24631)
			(xy 375.120032 -289.238204) (xy 375.070753 -289.222192) (xy 375.024586 -289.198669) (xy 374.982667 -289.168213)
			(xy 374.946029 -289.131575) (xy 374.915573 -289.089656) (xy 374.89205 -289.043489) (xy 374.876038 -288.99421)
			(xy 374.867932 -288.943033) (xy 374.867424 -288.917126) (xy 374.868023 -288.889409) (xy 374.877343 -288.834762)
			(xy 374.885966 -288.808414) (xy 374.89384 -288.786316) (xy 374.688862 -288.431224) (xy 374.666002 -288.426906)
			(xy 374.641161 -288.421779) (xy 374.593352 -288.40484) (xy 374.548702 -288.380778) (xy 374.508263 -288.350162)
			(xy 374.472991 -288.313713) (xy 374.443717 -288.272293) (xy 374.421133 -288.226877) (xy 374.405771 -288.178538)
			(xy 374.397994 -288.128417) (xy 374.397524 -288.103056) (xy 373.177308 -288.103056) (xy 373.176703 -288.130773)
			(xy 373.167387 -288.185419) (xy 373.158766 -288.211768) (xy 373.151146 -288.233866) (xy 373.356124 -288.588958)
			(xy 373.378984 -288.593276) (xy 373.403806 -288.598437) (xy 373.451584 -288.615395) (xy 373.496201 -288.639469)
			(xy 373.536606 -288.67009) (xy 373.571846 -288.706538) (xy 373.60109 -288.747952) (xy 373.623647 -288.793355)
			(xy 373.638986 -288.841676) (xy 373.646745 -288.891777) (xy 373.647208 -288.917126) (xy 373.6467 -288.943033)
			(xy 373.638594 -288.99421) (xy 373.622582 -289.043489) (xy 373.599059 -289.089656) (xy 373.568603 -289.131575)
			(xy 373.531965 -289.168213) (xy 373.490046 -289.198669) (xy 373.443879 -289.222192) (xy 373.3946 -289.238204)
			(xy 373.343423 -289.24631) (xy 373.291609 -289.24631) (xy 373.240432 -289.238204) (xy 373.191153 -289.222192)
			(xy 373.144986 -289.198669) (xy 373.103067 -289.168213) (xy 373.066429 -289.131575) (xy 373.035973 -289.089656)
			(xy 373.01245 -289.043489) (xy 372.996438 -288.99421) (xy 372.988332 -288.943033) (xy 372.987824 -288.917126)
			(xy 372.988423 -288.889409) (xy 372.997743 -288.834762) (xy 373.006366 -288.808414) (xy 373.01424 -288.786316)
			(xy 372.809262 -288.431224) (xy 372.786402 -288.426906) (xy 372.761561 -288.421779) (xy 372.713752 -288.40484)
			(xy 372.669102 -288.380778) (xy 372.628663 -288.350162) (xy 372.593391 -288.313713) (xy 372.564117 -288.272293)
			(xy 372.541533 -288.226877) (xy 372.526171 -288.178538) (xy 372.518394 -288.128417) (xy 372.517924 -288.103056)
			(xy 371.297708 -288.103056) (xy 371.297103 -288.130773) (xy 371.287787 -288.185419) (xy 371.279166 -288.211768)
			(xy 371.271546 -288.233866) (xy 371.476524 -288.588958) (xy 371.499384 -288.593276) (xy 371.524206 -288.598437)
			(xy 371.571984 -288.615395) (xy 371.616601 -288.639469) (xy 371.657006 -288.67009) (xy 371.692246 -288.706538)
			(xy 371.72149 -288.747952) (xy 371.744047 -288.793355) (xy 371.759386 -288.841676) (xy 371.767145 -288.891777)
			(xy 371.767608 -288.917126) (xy 371.7671 -288.943033) (xy 371.758994 -288.99421) (xy 371.742982 -289.043489)
			(xy 371.719459 -289.089656) (xy 371.689003 -289.131575) (xy 371.652365 -289.168213) (xy 371.610446 -289.198669)
			(xy 371.564279 -289.222192) (xy 371.515 -289.238204) (xy 371.463823 -289.24631) (xy 371.412009 -289.24631)
			(xy 371.360832 -289.238204) (xy 371.311553 -289.222192) (xy 371.265386 -289.198669) (xy 371.223467 -289.168213)
			(xy 371.186829 -289.131575) (xy 371.156373 -289.089656) (xy 371.13285 -289.043489) (xy 371.116838 -288.99421)
			(xy 371.108732 -288.943033) (xy 371.108224 -288.917126) (xy 371.108823 -288.889409) (xy 371.118143 -288.834762)
			(xy 371.126766 -288.808414) (xy 371.13464 -288.786316) (xy 370.929662 -288.431224) (xy 370.906802 -288.426906)
			(xy 370.881961 -288.421779) (xy 370.834152 -288.40484) (xy 370.789502 -288.380778) (xy 370.749063 -288.350162)
			(xy 370.713791 -288.313713) (xy 370.684517 -288.272293) (xy 370.661933 -288.226877) (xy 370.646571 -288.178538)
			(xy 370.638794 -288.128417) (xy 370.638324 -288.103056) (xy 369.418108 -288.103056) (xy 369.417503 -288.130773)
			(xy 369.408187 -288.185419) (xy 369.399566 -288.211768) (xy 369.391692 -288.233866) (xy 369.596924 -288.588958)
			(xy 369.619784 -288.593276) (xy 369.644606 -288.598437) (xy 369.692384 -288.615395) (xy 369.737001 -288.639469)
			(xy 369.777406 -288.67009) (xy 369.812646 -288.706538) (xy 369.84189 -288.747952) (xy 369.864447 -288.793355)
			(xy 369.879786 -288.841676) (xy 369.887545 -288.891777) (xy 369.888008 -288.917126) (xy 369.8875 -288.943033)
			(xy 369.879394 -288.99421) (xy 369.863382 -289.043489) (xy 369.839859 -289.089656) (xy 369.809403 -289.131575)
			(xy 369.772765 -289.168213) (xy 369.730846 -289.198669) (xy 369.684679 -289.222192) (xy 369.6354 -289.238204)
			(xy 369.584223 -289.24631) (xy 369.532409 -289.24631) (xy 369.481232 -289.238204) (xy 369.431953 -289.222192)
			(xy 369.385786 -289.198669) (xy 369.343867 -289.168213) (xy 369.307229 -289.131575) (xy 369.276773 -289.089656)
			(xy 369.25325 -289.043489) (xy 369.237238 -288.99421) (xy 369.229132 -288.943033) (xy 369.228624 -288.917126)
			(xy 369.229223 -288.889409) (xy 369.238543 -288.834762) (xy 369.247166 -288.808414) (xy 369.25504 -288.786316)
			(xy 369.049808 -288.431224) (xy 369.026948 -288.426906) (xy 369.002127 -288.421739) (xy 368.954348 -288.404784)
			(xy 368.909729 -288.380713) (xy 368.869322 -288.350092) (xy 368.834082 -288.313646) (xy 368.804838 -288.272232)
			(xy 368.782281 -288.226828) (xy 368.766943 -288.178506) (xy 368.759186 -288.128405) (xy 368.758724 -288.103056)
			(xy 352.501708 -288.103056) (xy 352.501231 -288.128401) (xy 352.493451 -288.178491) (xy 352.478099 -288.2268)
			(xy 352.455536 -288.272192) (xy 352.426294 -288.313597) (xy 352.39106 -288.35004) (xy 352.350665 -288.380663)
			(xy 352.306061 -288.404744) (xy 352.258297 -288.421718) (xy 352.233484 -288.426906) (xy 352.210624 -288.431224)
			(xy 352.005392 -288.786316) (xy 352.013266 -288.808414) (xy 352.021907 -288.834758) (xy 352.031221 -288.889407)
			(xy 352.031808 -288.917126) (xy 352.0313 -288.943033) (xy 352.023194 -288.99421) (xy 352.007182 -289.043489)
			(xy 351.983659 -289.089656) (xy 351.953203 -289.131575) (xy 351.916565 -289.168213) (xy 351.874646 -289.198669)
			(xy 351.828479 -289.222192) (xy 351.7792 -289.238204) (xy 351.728023 -289.24631) (xy 351.676209 -289.24631)
			(xy 351.625032 -289.238204) (xy 351.575753 -289.222192) (xy 351.529586 -289.198669) (xy 351.487667 -289.168213)
			(xy 351.451029 -289.131575) (xy 351.420573 -289.089656) (xy 351.39705 -289.043489) (xy 351.381038 -288.99421)
			(xy 351.372932 -288.943033) (xy 351.372424 -288.917126) (xy 351.092008 -288.917126) (xy 351.091589 -288.940067)
			(xy 351.08516 -288.985498) (xy 351.072513 -289.029604) (xy 351.06356 -289.05073) (xy 351.053654 -289.073336)
			(xy 351.267522 -289.478466) (xy 351.291652 -289.483038) (xy 351.316573 -289.488138) (xy 351.364584 -289.504939)
			(xy 351.409443 -289.528919) (xy 351.450084 -289.559507) (xy 351.485541 -289.595978) (xy 351.514973 -289.637465)
			(xy 351.537679 -289.682981) (xy 351.553121 -289.731446) (xy 351.560931 -289.781709) (xy 351.5614 -289.807142)
			(xy 367.818924 -289.807142) (xy 367.819411 -289.781712) (xy 367.827244 -289.73146) (xy 367.842699 -289.683005)
			(xy 367.86541 -289.637498) (xy 367.894839 -289.596018) (xy 367.930287 -289.559547) (xy 367.970914 -289.528951)
			(xy 368.015757 -289.504956) (xy 368.063753 -289.48813) (xy 368.088672 -289.483038) (xy 368.112802 -289.478466)
			(xy 368.327178 -289.073082) (xy 368.317272 -289.050476) (xy 368.308309 -289.029398) (xy 368.295664 -288.985377)
			(xy 368.289249 -288.940026) (xy 368.288824 -288.917126) (xy 368.289332 -288.891219) (xy 368.297438 -288.840042)
			(xy 368.31345 -288.790763) (xy 368.336973 -288.744596) (xy 368.367429 -288.702677) (xy 368.404067 -288.666039)
			(xy 368.445986 -288.635583) (xy 368.492153 -288.61206) (xy 368.541432 -288.596048) (xy 368.592609 -288.587942)
			(xy 368.644423 -288.587942) (xy 368.6956 -288.596048) (xy 368.744879 -288.61206) (xy 368.791046 -288.635583)
			(xy 368.832965 -288.666039) (xy 368.869603 -288.702677) (xy 368.900059 -288.744596) (xy 368.923582 -288.790763)
			(xy 368.939594 -288.840042) (xy 368.9477 -288.891219) (xy 368.948208 -288.917126) (xy 368.947753 -288.942575)
			(xy 368.939949 -288.992871) (xy 368.924499 -289.041367) (xy 368.901771 -289.086909) (xy 368.872307 -289.128411)
			(xy 368.836809 -289.164887) (xy 368.796121 -289.195466) (xy 368.751213 -289.21942) (xy 368.703153 -289.23618)
			(xy 368.678206 -289.24123) (xy 368.654076 -289.245802) (xy 368.4397 -289.651186) (xy 368.449606 -289.673792)
			(xy 368.458528 -289.694877) (xy 368.471078 -289.738907) (xy 368.47741 -289.78425) (xy 368.4778 -289.807142)
			(xy 369.698524 -289.807142) (xy 369.699011 -289.781712) (xy 369.706844 -289.73146) (xy 369.722299 -289.683005)
			(xy 369.74501 -289.637498) (xy 369.774439 -289.596018) (xy 369.809887 -289.559547) (xy 369.850514 -289.528951)
			(xy 369.895357 -289.504956) (xy 369.943353 -289.48813) (xy 369.968272 -289.483038) (xy 369.992402 -289.478466)
			(xy 370.206778 -289.073082) (xy 370.196872 -289.050476) (xy 370.187909 -289.029398) (xy 370.175264 -288.985377)
			(xy 370.168849 -288.940026) (xy 370.168424 -288.917126) (xy 370.168932 -288.891219) (xy 370.177038 -288.840042)
			(xy 370.19305 -288.790763) (xy 370.216573 -288.744596) (xy 370.247029 -288.702677) (xy 370.283667 -288.666039)
			(xy 370.325586 -288.635583) (xy 370.371753 -288.61206) (xy 370.421032 -288.596048) (xy 370.472209 -288.587942)
			(xy 370.524023 -288.587942) (xy 370.5752 -288.596048) (xy 370.624479 -288.61206) (xy 370.670646 -288.635583)
			(xy 370.712565 -288.666039) (xy 370.749203 -288.702677) (xy 370.779659 -288.744596) (xy 370.803182 -288.790763)
			(xy 370.819194 -288.840042) (xy 370.8273 -288.891219) (xy 370.827808 -288.917126) (xy 370.827353 -288.942575)
			(xy 370.819549 -288.992871) (xy 370.804099 -289.041367) (xy 370.781371 -289.086909) (xy 370.751907 -289.128411)
			(xy 370.716409 -289.164887) (xy 370.675721 -289.195466) (xy 370.630813 -289.21942) (xy 370.582753 -289.23618)
			(xy 370.557806 -289.24123) (xy 370.533676 -289.245802) (xy 370.3193 -289.651186) (xy 370.329206 -289.673792)
			(xy 370.338128 -289.694877) (xy 370.350678 -289.738907) (xy 370.35701 -289.78425) (xy 370.3574 -289.807142)
			(xy 371.578124 -289.807142) (xy 371.578611 -289.781712) (xy 371.586444 -289.73146) (xy 371.601899 -289.683005)
			(xy 371.62461 -289.637498) (xy 371.654039 -289.596018) (xy 371.689487 -289.559547) (xy 371.730114 -289.528951)
			(xy 371.774957 -289.504956) (xy 371.822953 -289.48813) (xy 371.847872 -289.483038) (xy 371.872002 -289.478466)
			(xy 372.086378 -289.073082) (xy 372.076472 -289.050476) (xy 372.067509 -289.029398) (xy 372.054864 -288.985377)
			(xy 372.048449 -288.940026) (xy 372.048024 -288.917126) (xy 372.048532 -288.891219) (xy 372.056638 -288.840042)
			(xy 372.07265 -288.790763) (xy 372.096173 -288.744596) (xy 372.126629 -288.702677) (xy 372.163267 -288.666039)
			(xy 372.205186 -288.635583) (xy 372.251353 -288.61206) (xy 372.300632 -288.596048) (xy 372.351809 -288.587942)
			(xy 372.403623 -288.587942) (xy 372.4548 -288.596048) (xy 372.504079 -288.61206) (xy 372.550246 -288.635583)
			(xy 372.592165 -288.666039) (xy 372.628803 -288.702677) (xy 372.659259 -288.744596) (xy 372.682782 -288.790763)
			(xy 372.698794 -288.840042) (xy 372.7069 -288.891219) (xy 372.707408 -288.917126) (xy 372.706953 -288.942575)
			(xy 372.699149 -288.992871) (xy 372.683699 -289.041367) (xy 372.660971 -289.086909) (xy 372.631507 -289.128411)
			(xy 372.596009 -289.164887) (xy 372.555321 -289.195466) (xy 372.510413 -289.21942) (xy 372.462353 -289.23618)
			(xy 372.437406 -289.24123) (xy 372.413276 -289.245802) (xy 372.1989 -289.651186) (xy 372.208806 -289.673792)
			(xy 372.217728 -289.694877) (xy 372.230278 -289.738907) (xy 372.23661 -289.78425) (xy 372.237 -289.807142)
			(xy 373.457724 -289.807142) (xy 373.458211 -289.781712) (xy 373.466044 -289.73146) (xy 373.481499 -289.683005)
			(xy 373.50421 -289.637498) (xy 373.533639 -289.596018) (xy 373.569087 -289.559547) (xy 373.609714 -289.528951)
			(xy 373.654557 -289.504956) (xy 373.702553 -289.48813) (xy 373.727472 -289.483038) (xy 373.751602 -289.478466)
			(xy 373.965978 -289.073082) (xy 373.956072 -289.050476) (xy 373.947109 -289.029398) (xy 373.934464 -288.985377)
			(xy 373.928049 -288.940026) (xy 373.927624 -288.917126) (xy 373.928132 -288.891219) (xy 373.936238 -288.840042)
			(xy 373.95225 -288.790763) (xy 373.975773 -288.744596) (xy 374.006229 -288.702677) (xy 374.042867 -288.666039)
			(xy 374.084786 -288.635583) (xy 374.130953 -288.61206) (xy 374.180232 -288.596048) (xy 374.231409 -288.587942)
			(xy 374.283223 -288.587942) (xy 374.3344 -288.596048) (xy 374.383679 -288.61206) (xy 374.429846 -288.635583)
			(xy 374.471765 -288.666039) (xy 374.508403 -288.702677) (xy 374.538859 -288.744596) (xy 374.562382 -288.790763)
			(xy 374.578394 -288.840042) (xy 374.5865 -288.891219) (xy 374.587008 -288.917126) (xy 374.586553 -288.942575)
			(xy 374.578749 -288.992871) (xy 374.563299 -289.041367) (xy 374.540571 -289.086909) (xy 374.511107 -289.128411)
			(xy 374.475609 -289.164887) (xy 374.434921 -289.195466) (xy 374.390013 -289.21942) (xy 374.341953 -289.23618)
			(xy 374.317006 -289.24123) (xy 374.292876 -289.245802) (xy 374.0785 -289.651186) (xy 374.088406 -289.673792)
			(xy 374.097328 -289.694877) (xy 374.109878 -289.738907) (xy 374.11621 -289.78425) (xy 374.1166 -289.807142)
			(xy 375.337324 -289.807142) (xy 375.337811 -289.781712) (xy 375.345644 -289.73146) (xy 375.361099 -289.683005)
			(xy 375.38381 -289.637498) (xy 375.413239 -289.596018) (xy 375.448687 -289.559547) (xy 375.489314 -289.528951)
			(xy 375.534157 -289.504956) (xy 375.582153 -289.48813) (xy 375.607072 -289.483038) (xy 375.631202 -289.478466)
			(xy 375.845578 -289.073082) (xy 375.835672 -289.050476) (xy 375.826709 -289.029398) (xy 375.814064 -288.985377)
			(xy 375.807649 -288.940026) (xy 375.807224 -288.917126) (xy 375.807732 -288.891219) (xy 375.815838 -288.840042)
			(xy 375.83185 -288.790763) (xy 375.855373 -288.744596) (xy 375.885829 -288.702677) (xy 375.922467 -288.666039)
			(xy 375.964386 -288.635583) (xy 376.010553 -288.61206) (xy 376.059832 -288.596048) (xy 376.111009 -288.587942)
			(xy 376.162823 -288.587942) (xy 376.214 -288.596048) (xy 376.263279 -288.61206) (xy 376.309446 -288.635583)
			(xy 376.351365 -288.666039) (xy 376.388003 -288.702677) (xy 376.418459 -288.744596) (xy 376.441982 -288.790763)
			(xy 376.457994 -288.840042) (xy 376.4661 -288.891219) (xy 376.466608 -288.917126) (xy 376.466153 -288.942575)
			(xy 376.458349 -288.992871) (xy 376.442899 -289.041367) (xy 376.420171 -289.086909) (xy 376.390707 -289.128411)
			(xy 376.355209 -289.164887) (xy 376.314521 -289.195466) (xy 376.269613 -289.21942) (xy 376.221553 -289.23618)
			(xy 376.196606 -289.24123) (xy 376.172476 -289.245802) (xy 375.9581 -289.651186) (xy 375.968006 -289.673792)
			(xy 375.976928 -289.694877) (xy 375.989478 -289.738907) (xy 375.99581 -289.78425) (xy 375.9962 -289.807142)
			(xy 377.216924 -289.807142) (xy 377.217411 -289.781712) (xy 377.225244 -289.73146) (xy 377.240699 -289.683005)
			(xy 377.26341 -289.637498) (xy 377.292839 -289.596018) (xy 377.328287 -289.559547) (xy 377.368914 -289.528951)
			(xy 377.413757 -289.504956) (xy 377.461753 -289.48813) (xy 377.486672 -289.483038) (xy 377.510802 -289.478466)
			(xy 377.725178 -289.073082) (xy 377.715272 -289.050476) (xy 377.706309 -289.029398) (xy 377.693664 -288.985377)
			(xy 377.687249 -288.940026) (xy 377.686824 -288.917126) (xy 377.687332 -288.891219) (xy 377.695438 -288.840042)
			(xy 377.71145 -288.790763) (xy 377.734973 -288.744596) (xy 377.765429 -288.702677) (xy 377.802067 -288.666039)
			(xy 377.843986 -288.635583) (xy 377.890153 -288.61206) (xy 377.939432 -288.596048) (xy 377.990609 -288.587942)
			(xy 378.042423 -288.587942) (xy 378.0936 -288.596048) (xy 378.142879 -288.61206) (xy 378.189046 -288.635583)
			(xy 378.230965 -288.666039) (xy 378.267603 -288.702677) (xy 378.298059 -288.744596) (xy 378.321582 -288.790763)
			(xy 378.337594 -288.840042) (xy 378.3457 -288.891219) (xy 378.346208 -288.917126) (xy 378.345753 -288.942575)
			(xy 378.337949 -288.992871) (xy 378.322499 -289.041367) (xy 378.299771 -289.086909) (xy 378.270307 -289.128411)
			(xy 378.234809 -289.164887) (xy 378.194121 -289.195466) (xy 378.149213 -289.21942) (xy 378.101153 -289.23618)
			(xy 378.076206 -289.24123) (xy 378.052076 -289.245802) (xy 377.8377 -289.651186) (xy 377.847606 -289.673792)
			(xy 377.856528 -289.694877) (xy 377.869078 -289.738907) (xy 377.87541 -289.78425) (xy 377.8758 -289.807142)
			(xy 379.096524 -289.807142) (xy 379.097011 -289.781712) (xy 379.104844 -289.73146) (xy 379.120299 -289.683005)
			(xy 379.14301 -289.637498) (xy 379.172439 -289.596018) (xy 379.207887 -289.559547) (xy 379.248514 -289.528951)
			(xy 379.293357 -289.504956) (xy 379.341353 -289.48813) (xy 379.366272 -289.483038) (xy 379.390402 -289.478466)
			(xy 379.604778 -289.073082) (xy 379.594872 -289.050476) (xy 379.585909 -289.029398) (xy 379.573264 -288.985377)
			(xy 379.566849 -288.940026) (xy 379.566424 -288.917126) (xy 379.566932 -288.891219) (xy 379.575038 -288.840042)
			(xy 379.59105 -288.790763) (xy 379.614573 -288.744596) (xy 379.645029 -288.702677) (xy 379.681667 -288.666039)
			(xy 379.723586 -288.635583) (xy 379.769753 -288.61206) (xy 379.819032 -288.596048) (xy 379.870209 -288.587942)
			(xy 379.922023 -288.587942) (xy 379.9732 -288.596048) (xy 380.022479 -288.61206) (xy 380.068646 -288.635583)
			(xy 380.110565 -288.666039) (xy 380.147203 -288.702677) (xy 380.177659 -288.744596) (xy 380.201182 -288.790763)
			(xy 380.217194 -288.840042) (xy 380.2253 -288.891219) (xy 380.225808 -288.917126) (xy 380.225353 -288.942575)
			(xy 380.217549 -288.992871) (xy 380.202099 -289.041367) (xy 380.179371 -289.086909) (xy 380.149907 -289.128411)
			(xy 380.114409 -289.164887) (xy 380.073721 -289.195466) (xy 380.028813 -289.21942) (xy 379.980753 -289.23618)
			(xy 379.955806 -289.24123) (xy 379.931676 -289.245802) (xy 379.7173 -289.651186) (xy 379.727206 -289.673792)
			(xy 379.736128 -289.694877) (xy 379.748678 -289.738907) (xy 379.75501 -289.78425) (xy 379.7554 -289.807142)
			(xy 380.976124 -289.807142) (xy 380.976611 -289.781712) (xy 380.984444 -289.73146) (xy 380.999899 -289.683005)
			(xy 381.02261 -289.637498) (xy 381.052039 -289.596018) (xy 381.087487 -289.559547) (xy 381.128114 -289.528951)
			(xy 381.172957 -289.504956) (xy 381.220953 -289.48813) (xy 381.245872 -289.483038) (xy 381.270002 -289.478466)
			(xy 381.484378 -289.073082) (xy 381.474472 -289.050476) (xy 381.465509 -289.029398) (xy 381.452864 -288.985377)
			(xy 381.446449 -288.940026) (xy 381.446024 -288.917126) (xy 381.446532 -288.891219) (xy 381.454638 -288.840042)
			(xy 381.47065 -288.790763) (xy 381.494173 -288.744596) (xy 381.524629 -288.702677) (xy 381.561267 -288.666039)
			(xy 381.603186 -288.635583) (xy 381.649353 -288.61206) (xy 381.698632 -288.596048) (xy 381.749809 -288.587942)
			(xy 381.801623 -288.587942) (xy 381.8528 -288.596048) (xy 381.902079 -288.61206) (xy 381.948246 -288.635583)
			(xy 381.990165 -288.666039) (xy 382.026803 -288.702677) (xy 382.057259 -288.744596) (xy 382.080782 -288.790763)
			(xy 382.096794 -288.840042) (xy 382.1049 -288.891219) (xy 382.105408 -288.917126) (xy 382.104953 -288.942575)
			(xy 382.097149 -288.992871) (xy 382.081699 -289.041367) (xy 382.058971 -289.086909) (xy 382.029507 -289.128411)
			(xy 381.994009 -289.164887) (xy 381.953321 -289.195466) (xy 381.908413 -289.21942) (xy 381.860353 -289.23618)
			(xy 381.835406 -289.24123) (xy 381.811276 -289.245802) (xy 381.5969 -289.651186) (xy 381.606806 -289.673792)
			(xy 381.615728 -289.694877) (xy 381.628278 -289.738907) (xy 381.63461 -289.78425) (xy 381.635 -289.807142)
			(xy 381.634492 -289.833029) (xy 381.626393 -289.884167) (xy 381.610394 -289.933407) (xy 381.586888 -289.979539)
			(xy 381.556456 -290.021426) (xy 381.519846 -290.058036) (xy 381.477959 -290.088468) (xy 381.431827 -290.111974)
			(xy 381.382587 -290.127973) (xy 381.331449 -290.136072) (xy 381.279675 -290.136072) (xy 381.228537 -290.127973)
			(xy 381.179297 -290.111974) (xy 381.133165 -290.088468) (xy 381.091278 -290.058036) (xy 381.054668 -290.021426)
			(xy 381.024236 -289.979539) (xy 381.00073 -289.933407) (xy 380.984731 -289.884167) (xy 380.976632 -289.833029)
			(xy 380.976124 -289.807142) (xy 379.7554 -289.807142) (xy 379.754892 -289.833029) (xy 379.746793 -289.884167)
			(xy 379.730794 -289.933407) (xy 379.707288 -289.979539) (xy 379.676856 -290.021426) (xy 379.640246 -290.058036)
			(xy 379.598359 -290.088468) (xy 379.552227 -290.111974) (xy 379.502987 -290.127973) (xy 379.451849 -290.136072)
			(xy 379.400075 -290.136072) (xy 379.348937 -290.127973) (xy 379.299697 -290.111974) (xy 379.253565 -290.088468)
			(xy 379.211678 -290.058036) (xy 379.175068 -290.021426) (xy 379.144636 -289.979539) (xy 379.12113 -289.933407)
			(xy 379.105131 -289.884167) (xy 379.097032 -289.833029) (xy 379.096524 -289.807142) (xy 377.8758 -289.807142)
			(xy 377.875292 -289.833029) (xy 377.867193 -289.884167) (xy 377.851194 -289.933407) (xy 377.827688 -289.979539)
			(xy 377.797256 -290.021426) (xy 377.760646 -290.058036) (xy 377.718759 -290.088468) (xy 377.672627 -290.111974)
			(xy 377.623387 -290.127973) (xy 377.572249 -290.136072) (xy 377.520475 -290.136072) (xy 377.469337 -290.127973)
			(xy 377.420097 -290.111974) (xy 377.373965 -290.088468) (xy 377.332078 -290.058036) (xy 377.295468 -290.021426)
			(xy 377.265036 -289.979539) (xy 377.24153 -289.933407) (xy 377.225531 -289.884167) (xy 377.217432 -289.833029)
			(xy 377.216924 -289.807142) (xy 375.9962 -289.807142) (xy 375.995692 -289.833029) (xy 375.987593 -289.884167)
			(xy 375.971594 -289.933407) (xy 375.948088 -289.979539) (xy 375.917656 -290.021426) (xy 375.881046 -290.058036)
			(xy 375.839159 -290.088468) (xy 375.793027 -290.111974) (xy 375.743787 -290.127973) (xy 375.692649 -290.136072)
			(xy 375.640875 -290.136072) (xy 375.589737 -290.127973) (xy 375.540497 -290.111974) (xy 375.494365 -290.088468)
			(xy 375.452478 -290.058036) (xy 375.415868 -290.021426) (xy 375.385436 -289.979539) (xy 375.36193 -289.933407)
			(xy 375.345931 -289.884167) (xy 375.337832 -289.833029) (xy 375.337324 -289.807142) (xy 374.1166 -289.807142)
			(xy 374.116092 -289.833029) (xy 374.107993 -289.884167) (xy 374.091994 -289.933407) (xy 374.068488 -289.979539)
			(xy 374.038056 -290.021426) (xy 374.001446 -290.058036) (xy 373.959559 -290.088468) (xy 373.913427 -290.111974)
			(xy 373.864187 -290.127973) (xy 373.813049 -290.136072) (xy 373.761275 -290.136072) (xy 373.710137 -290.127973)
			(xy 373.660897 -290.111974) (xy 373.614765 -290.088468) (xy 373.572878 -290.058036) (xy 373.536268 -290.021426)
			(xy 373.505836 -289.979539) (xy 373.48233 -289.933407) (xy 373.466331 -289.884167) (xy 373.458232 -289.833029)
			(xy 373.457724 -289.807142) (xy 372.237 -289.807142) (xy 372.236492 -289.833029) (xy 372.228393 -289.884167)
			(xy 372.212394 -289.933407) (xy 372.188888 -289.979539) (xy 372.158456 -290.021426) (xy 372.121846 -290.058036)
			(xy 372.079959 -290.088468) (xy 372.033827 -290.111974) (xy 371.984587 -290.127973) (xy 371.933449 -290.136072)
			(xy 371.881675 -290.136072) (xy 371.830537 -290.127973) (xy 371.781297 -290.111974) (xy 371.735165 -290.088468)
			(xy 371.693278 -290.058036) (xy 371.656668 -290.021426) (xy 371.626236 -289.979539) (xy 371.60273 -289.933407)
			(xy 371.586731 -289.884167) (xy 371.578632 -289.833029) (xy 371.578124 -289.807142) (xy 370.3574 -289.807142)
			(xy 370.356892 -289.833029) (xy 370.348793 -289.884167) (xy 370.332794 -289.933407) (xy 370.309288 -289.979539)
			(xy 370.278856 -290.021426) (xy 370.242246 -290.058036) (xy 370.200359 -290.088468) (xy 370.154227 -290.111974)
			(xy 370.104987 -290.127973) (xy 370.053849 -290.136072) (xy 370.002075 -290.136072) (xy 369.950937 -290.127973)
			(xy 369.901697 -290.111974) (xy 369.855565 -290.088468) (xy 369.813678 -290.058036) (xy 369.777068 -290.021426)
			(xy 369.746636 -289.979539) (xy 369.72313 -289.933407) (xy 369.707131 -289.884167) (xy 369.699032 -289.833029)
			(xy 369.698524 -289.807142) (xy 368.4778 -289.807142) (xy 368.477292 -289.833029) (xy 368.469193 -289.884167)
			(xy 368.453194 -289.933407) (xy 368.429688 -289.979539) (xy 368.399256 -290.021426) (xy 368.362646 -290.058036)
			(xy 368.320759 -290.088468) (xy 368.274627 -290.111974) (xy 368.225387 -290.127973) (xy 368.174249 -290.136072)
			(xy 368.122475 -290.136072) (xy 368.071337 -290.127973) (xy 368.022097 -290.111974) (xy 367.975965 -290.088468)
			(xy 367.934078 -290.058036) (xy 367.897468 -290.021426) (xy 367.867036 -289.979539) (xy 367.84353 -289.933407)
			(xy 367.827531 -289.884167) (xy 367.819432 -289.833029) (xy 367.818924 -289.807142) (xy 351.5614 -289.807142)
			(xy 351.560892 -289.833029) (xy 351.552793 -289.884167) (xy 351.536794 -289.933407) (xy 351.513288 -289.979539)
			(xy 351.482856 -290.021426) (xy 351.446246 -290.058036) (xy 351.404359 -290.088468) (xy 351.358227 -290.111974)
			(xy 351.308987 -290.127973) (xy 351.257849 -290.136072) (xy 351.206075 -290.136072) (xy 351.154937 -290.127973)
			(xy 351.105697 -290.111974) (xy 351.059565 -290.088468) (xy 351.017678 -290.058036) (xy 350.981068 -290.021426)
			(xy 350.950636 -289.979539) (xy 350.92713 -289.933407) (xy 350.911131 -289.884167) (xy 350.903032 -289.833029)
			(xy 350.902524 -289.807142) (xy 350.902524 -289.806634) (xy 350.902922 -289.783785) (xy 350.909275 -289.738531)
			(xy 350.921824 -289.694589) (xy 350.930718 -289.673538) (xy 350.940624 -289.650932) (xy 350.726756 -289.245802)
			(xy 350.702626 -289.24123) (xy 350.677682 -289.236182) (xy 350.629639 -289.219398) (xy 350.584746 -289.195428)
			(xy 350.544072 -289.164843) (xy 350.508582 -289.128369) (xy 350.479121 -289.086873) (xy 350.456389 -289.041341)
			(xy 350.440925 -288.992857) (xy 350.433099 -288.942571) (xy 350.432624 -288.917126) (xy 350.152208 -288.917126)
			(xy 350.1517 -288.943033) (xy 350.143594 -288.99421) (xy 350.127582 -289.043489) (xy 350.104059 -289.089656)
			(xy 350.073603 -289.131575) (xy 350.036965 -289.168213) (xy 349.995046 -289.198669) (xy 349.948879 -289.222192)
			(xy 349.8996 -289.238204) (xy 349.848423 -289.24631) (xy 349.796609 -289.24631) (xy 349.745432 -289.238204)
			(xy 349.696153 -289.222192) (xy 349.649986 -289.198669) (xy 349.608067 -289.168213) (xy 349.571429 -289.131575)
			(xy 349.540973 -289.089656) (xy 349.51745 -289.043489) (xy 349.501438 -288.99421) (xy 349.493332 -288.943033)
			(xy 349.492824 -288.917126) (xy 349.212408 -288.917126) (xy 349.211989 -288.940067) (xy 349.20556 -288.985498)
			(xy 349.192913 -289.029604) (xy 349.18396 -289.05073) (xy 349.174054 -289.073336) (xy 349.387922 -289.478466)
			(xy 349.412052 -289.483038) (xy 349.436973 -289.488138) (xy 349.484984 -289.504939) (xy 349.529843 -289.528919)
			(xy 349.570484 -289.559507) (xy 349.605941 -289.595978) (xy 349.635373 -289.637465) (xy 349.658079 -289.682981)
			(xy 349.673521 -289.731446) (xy 349.681331 -289.781709) (xy 349.6818 -289.807142) (xy 349.681292 -289.833029)
			(xy 349.673193 -289.884167) (xy 349.657194 -289.933407) (xy 349.633688 -289.979539) (xy 349.603256 -290.021426)
			(xy 349.566646 -290.058036) (xy 349.524759 -290.088468) (xy 349.478627 -290.111974) (xy 349.429387 -290.127973)
			(xy 349.378249 -290.136072) (xy 349.326475 -290.136072) (xy 349.275337 -290.127973) (xy 349.226097 -290.111974)
			(xy 349.179965 -290.088468) (xy 349.138078 -290.058036) (xy 349.101468 -290.021426) (xy 349.071036 -289.979539)
			(xy 349.04753 -289.933407) (xy 349.031531 -289.884167) (xy 349.023432 -289.833029) (xy 349.022924 -289.807142)
			(xy 349.022924 -289.806634) (xy 349.023322 -289.783785) (xy 349.029675 -289.738531) (xy 349.042224 -289.694589)
			(xy 349.051118 -289.673538) (xy 349.061024 -289.650932) (xy 348.847156 -289.245802) (xy 348.823026 -289.24123)
			(xy 348.798082 -289.236182) (xy 348.750039 -289.219398) (xy 348.705146 -289.195428) (xy 348.664472 -289.164843)
			(xy 348.628982 -289.128369) (xy 348.599521 -289.086873) (xy 348.576789 -289.041341) (xy 348.561325 -288.992857)
			(xy 348.553499 -288.942571) (xy 348.553024 -288.917126) (xy 348.272608 -288.917126) (xy 348.2721 -288.943033)
			(xy 348.263994 -288.99421) (xy 348.247982 -289.043489) (xy 348.224459 -289.089656) (xy 348.194003 -289.131575)
			(xy 348.157365 -289.168213) (xy 348.115446 -289.198669) (xy 348.069279 -289.222192) (xy 348.02 -289.238204)
			(xy 347.968823 -289.24631) (xy 347.917009 -289.24631) (xy 347.865832 -289.238204) (xy 347.816553 -289.222192)
			(xy 347.770386 -289.198669) (xy 347.728467 -289.168213) (xy 347.691829 -289.131575) (xy 347.661373 -289.089656)
			(xy 347.63785 -289.043489) (xy 347.621838 -288.99421) (xy 347.613732 -288.943033) (xy 347.613224 -288.917126)
			(xy 347.332808 -288.917126) (xy 347.332389 -288.940067) (xy 347.32596 -288.985498) (xy 347.313313 -289.029604)
			(xy 347.30436 -289.05073) (xy 347.294454 -289.073336) (xy 347.508322 -289.478466) (xy 347.532452 -289.483038)
			(xy 347.557373 -289.488138) (xy 347.605384 -289.504939) (xy 347.650243 -289.528919) (xy 347.690884 -289.559507)
			(xy 347.726341 -289.595978) (xy 347.755773 -289.637465) (xy 347.778479 -289.682981) (xy 347.793921 -289.731446)
			(xy 347.801731 -289.781709) (xy 347.8022 -289.807142) (xy 347.801692 -289.833029) (xy 347.793593 -289.884167)
			(xy 347.777594 -289.933407) (xy 347.754088 -289.979539) (xy 347.723656 -290.021426) (xy 347.687046 -290.058036)
			(xy 347.645159 -290.088468) (xy 347.599027 -290.111974) (xy 347.549787 -290.127973) (xy 347.498649 -290.136072)
			(xy 347.446875 -290.136072) (xy 347.395737 -290.127973) (xy 347.346497 -290.111974) (xy 347.300365 -290.088468)
			(xy 347.258478 -290.058036) (xy 347.221868 -290.021426) (xy 347.191436 -289.979539) (xy 347.16793 -289.933407)
			(xy 347.151931 -289.884167) (xy 347.143832 -289.833029) (xy 347.143324 -289.807142) (xy 347.143324 -289.806634)
			(xy 347.143722 -289.783785) (xy 347.150075 -289.738531) (xy 347.162624 -289.694589) (xy 347.171518 -289.673538)
			(xy 347.181424 -289.650932) (xy 346.967556 -289.245802) (xy 346.943426 -289.24123) (xy 346.918482 -289.236182)
			(xy 346.870439 -289.219398) (xy 346.825546 -289.195428) (xy 346.784872 -289.164843) (xy 346.749382 -289.128369)
			(xy 346.719921 -289.086873) (xy 346.697189 -289.041341) (xy 346.681725 -288.992857) (xy 346.673899 -288.942571)
			(xy 346.673424 -288.917126) (xy 346.393008 -288.917126) (xy 346.3925 -288.943033) (xy 346.384394 -288.99421)
			(xy 346.368382 -289.043489) (xy 346.344859 -289.089656) (xy 346.314403 -289.131575) (xy 346.277765 -289.168213)
			(xy 346.235846 -289.198669) (xy 346.189679 -289.222192) (xy 346.1404 -289.238204) (xy 346.089223 -289.24631)
			(xy 346.037409 -289.24631) (xy 345.986232 -289.238204) (xy 345.936953 -289.222192) (xy 345.890786 -289.198669)
			(xy 345.848867 -289.168213) (xy 345.812229 -289.131575) (xy 345.781773 -289.089656) (xy 345.75825 -289.043489)
			(xy 345.742238 -288.99421) (xy 345.734132 -288.943033) (xy 345.733624 -288.917126) (xy 345.453208 -288.917126)
			(xy 345.452789 -288.940067) (xy 345.44636 -288.985498) (xy 345.433713 -289.029604) (xy 345.42476 -289.05073)
			(xy 345.414854 -289.073336) (xy 345.628722 -289.478466) (xy 345.652852 -289.483038) (xy 345.677773 -289.488138)
			(xy 345.725784 -289.504939) (xy 345.770643 -289.528919) (xy 345.811284 -289.559507) (xy 345.846741 -289.595978)
			(xy 345.876173 -289.637465) (xy 345.898879 -289.682981) (xy 345.914321 -289.731446) (xy 345.922131 -289.781709)
			(xy 345.9226 -289.807142) (xy 345.922092 -289.833029) (xy 345.913993 -289.884167) (xy 345.897994 -289.933407)
			(xy 345.874488 -289.979539) (xy 345.844056 -290.021426) (xy 345.807446 -290.058036) (xy 345.765559 -290.088468)
			(xy 345.719427 -290.111974) (xy 345.670187 -290.127973) (xy 345.619049 -290.136072) (xy 345.567275 -290.136072)
			(xy 345.516137 -290.127973) (xy 345.466897 -290.111974) (xy 345.420765 -290.088468) (xy 345.378878 -290.058036)
			(xy 345.342268 -290.021426) (xy 345.311836 -289.979539) (xy 345.28833 -289.933407) (xy 345.272331 -289.884167)
			(xy 345.264232 -289.833029) (xy 345.263724 -289.807142) (xy 345.263724 -289.806634) (xy 345.264122 -289.783785)
			(xy 345.270475 -289.738531) (xy 345.283024 -289.694589) (xy 345.291918 -289.673538) (xy 345.301824 -289.650932)
			(xy 345.087956 -289.245802) (xy 345.063826 -289.24123) (xy 345.038882 -289.236182) (xy 344.990839 -289.219398)
			(xy 344.945946 -289.195428) (xy 344.905272 -289.164843) (xy 344.869782 -289.128369) (xy 344.840321 -289.086873)
			(xy 344.817589 -289.041341) (xy 344.802125 -288.992857) (xy 344.794299 -288.942571) (xy 344.793824 -288.917126)
			(xy 344.513408 -288.917126) (xy 344.5129 -288.943033) (xy 344.504794 -288.99421) (xy 344.488782 -289.043489)
			(xy 344.465259 -289.089656) (xy 344.434803 -289.131575) (xy 344.398165 -289.168213) (xy 344.356246 -289.198669)
			(xy 344.310079 -289.222192) (xy 344.2608 -289.238204) (xy 344.209623 -289.24631) (xy 344.157809 -289.24631)
			(xy 344.106632 -289.238204) (xy 344.057353 -289.222192) (xy 344.011186 -289.198669) (xy 343.969267 -289.168213)
			(xy 343.932629 -289.131575) (xy 343.902173 -289.089656) (xy 343.87865 -289.043489) (xy 343.862638 -288.99421)
			(xy 343.854532 -288.943033) (xy 343.854024 -288.917126) (xy 343.573608 -288.917126) (xy 343.573189 -288.940067)
			(xy 343.56676 -288.985498) (xy 343.554113 -289.029604) (xy 343.54516 -289.05073) (xy 343.535254 -289.073336)
			(xy 343.749122 -289.478466) (xy 343.773252 -289.483038) (xy 343.798173 -289.488138) (xy 343.846184 -289.504939)
			(xy 343.891043 -289.528919) (xy 343.931684 -289.559507) (xy 343.967141 -289.595978) (xy 343.996573 -289.637465)
			(xy 344.019279 -289.682981) (xy 344.034721 -289.731446) (xy 344.042531 -289.781709) (xy 344.043 -289.807142)
			(xy 344.042492 -289.833029) (xy 344.034393 -289.884167) (xy 344.018394 -289.933407) (xy 343.994888 -289.979539)
			(xy 343.964456 -290.021426) (xy 343.927846 -290.058036) (xy 343.885959 -290.088468) (xy 343.839827 -290.111974)
			(xy 343.790587 -290.127973) (xy 343.739449 -290.136072) (xy 343.687675 -290.136072) (xy 343.636537 -290.127973)
			(xy 343.587297 -290.111974) (xy 343.541165 -290.088468) (xy 343.499278 -290.058036) (xy 343.462668 -290.021426)
			(xy 343.432236 -289.979539) (xy 343.40873 -289.933407) (xy 343.392731 -289.884167) (xy 343.384632 -289.833029)
			(xy 343.384124 -289.807142) (xy 343.384124 -289.806634) (xy 343.384522 -289.783785) (xy 343.390875 -289.738531)
			(xy 343.403424 -289.694589) (xy 343.412318 -289.673538) (xy 343.422224 -289.650932) (xy 343.208356 -289.245802)
			(xy 343.184226 -289.24123) (xy 343.159282 -289.236182) (xy 343.111239 -289.219398) (xy 343.066346 -289.195428)
			(xy 343.025672 -289.164843) (xy 342.990182 -289.128369) (xy 342.960721 -289.086873) (xy 342.937989 -289.041341)
			(xy 342.922525 -288.992857) (xy 342.914699 -288.942571) (xy 342.914224 -288.917126) (xy 342.633808 -288.917126)
			(xy 342.6333 -288.943033) (xy 342.625194 -288.99421) (xy 342.609182 -289.043489) (xy 342.585659 -289.089656)
			(xy 342.555203 -289.131575) (xy 342.518565 -289.168213) (xy 342.476646 -289.198669) (xy 342.430479 -289.222192)
			(xy 342.3812 -289.238204) (xy 342.330023 -289.24631) (xy 342.278209 -289.24631) (xy 342.227032 -289.238204)
			(xy 342.177753 -289.222192) (xy 342.131586 -289.198669) (xy 342.089667 -289.168213) (xy 342.053029 -289.131575)
			(xy 342.022573 -289.089656) (xy 341.99905 -289.043489) (xy 341.983038 -288.99421) (xy 341.974932 -288.943033)
			(xy 341.974424 -288.917126) (xy 341.694008 -288.917126) (xy 341.693589 -288.940067) (xy 341.68716 -288.985498)
			(xy 341.674513 -289.029604) (xy 341.66556 -289.05073) (xy 341.655654 -289.073336) (xy 341.869522 -289.478466)
			(xy 341.893652 -289.483038) (xy 341.918573 -289.488138) (xy 341.966584 -289.504939) (xy 342.011443 -289.528919)
			(xy 342.052084 -289.559507) (xy 342.087541 -289.595978) (xy 342.116973 -289.637465) (xy 342.139679 -289.682981)
			(xy 342.155121 -289.731446) (xy 342.162931 -289.781709) (xy 342.1634 -289.807142) (xy 342.162892 -289.833029)
			(xy 342.154793 -289.884167) (xy 342.138794 -289.933407) (xy 342.115288 -289.979539) (xy 342.084856 -290.021426)
			(xy 342.048246 -290.058036) (xy 342.006359 -290.088468) (xy 341.960227 -290.111974) (xy 341.910987 -290.127973)
			(xy 341.859849 -290.136072) (xy 341.808075 -290.136072) (xy 341.756937 -290.127973) (xy 341.707697 -290.111974)
			(xy 341.661565 -290.088468) (xy 341.619678 -290.058036) (xy 341.583068 -290.021426) (xy 341.552636 -289.979539)
			(xy 341.52913 -289.933407) (xy 341.513131 -289.884167) (xy 341.505032 -289.833029) (xy 341.504524 -289.807142)
			(xy 341.504524 -289.806634) (xy 341.504922 -289.783785) (xy 341.511275 -289.738531) (xy 341.523824 -289.694589)
			(xy 341.532718 -289.673538) (xy 341.542624 -289.650932) (xy 341.328756 -289.245802) (xy 341.304626 -289.24123)
			(xy 341.279682 -289.236182) (xy 341.231639 -289.219398) (xy 341.186746 -289.195428) (xy 341.146072 -289.164843)
			(xy 341.110582 -289.128369) (xy 341.081121 -289.086873) (xy 341.058389 -289.041341) (xy 341.042925 -288.992857)
			(xy 341.035099 -288.942571) (xy 341.034624 -288.917126) (xy 340.754208 -288.917126) (xy 340.7537 -288.943033)
			(xy 340.745594 -288.99421) (xy 340.729582 -289.043489) (xy 340.706059 -289.089656) (xy 340.675603 -289.131575)
			(xy 340.638965 -289.168213) (xy 340.597046 -289.198669) (xy 340.550879 -289.222192) (xy 340.5016 -289.238204)
			(xy 340.450423 -289.24631) (xy 340.398609 -289.24631) (xy 340.347432 -289.238204) (xy 340.298153 -289.222192)
			(xy 340.251986 -289.198669) (xy 340.210067 -289.168213) (xy 340.173429 -289.131575) (xy 340.142973 -289.089656)
			(xy 340.11945 -289.043489) (xy 340.103438 -288.99421) (xy 340.095332 -288.943033) (xy 340.094824 -288.917126)
			(xy 339.814408 -288.917126) (xy 339.813989 -288.940067) (xy 339.80756 -288.985498) (xy 339.794913 -289.029604)
			(xy 339.78596 -289.05073) (xy 339.776054 -289.073336) (xy 339.989922 -289.478466) (xy 340.014052 -289.483038)
			(xy 340.038973 -289.488138) (xy 340.086984 -289.504939) (xy 340.131843 -289.528919) (xy 340.172484 -289.559507)
			(xy 340.207941 -289.595978) (xy 340.237373 -289.637465) (xy 340.260079 -289.682981) (xy 340.275521 -289.731446)
			(xy 340.283331 -289.781709) (xy 340.2838 -289.807142) (xy 340.283292 -289.833029) (xy 340.275193 -289.884167)
			(xy 340.259194 -289.933407) (xy 340.235688 -289.979539) (xy 340.205256 -290.021426) (xy 340.168646 -290.058036)
			(xy 340.126759 -290.088468) (xy 340.080627 -290.111974) (xy 340.031387 -290.127973) (xy 339.980249 -290.136072)
			(xy 339.928475 -290.136072) (xy 339.877337 -290.127973) (xy 339.828097 -290.111974) (xy 339.781965 -290.088468)
			(xy 339.740078 -290.058036) (xy 339.703468 -290.021426) (xy 339.673036 -289.979539) (xy 339.64953 -289.933407)
			(xy 339.633531 -289.884167) (xy 339.625432 -289.833029) (xy 339.624924 -289.807142) (xy 339.624924 -289.806634)
			(xy 339.625322 -289.783785) (xy 339.631675 -289.738531) (xy 339.644224 -289.694589) (xy 339.653118 -289.673538)
			(xy 339.663024 -289.650932) (xy 339.449156 -289.245802) (xy 339.425026 -289.24123) (xy 339.400082 -289.236182)
			(xy 339.352039 -289.219398) (xy 339.307146 -289.195428) (xy 339.266472 -289.164843) (xy 339.230982 -289.128369)
			(xy 339.201521 -289.086873) (xy 339.178789 -289.041341) (xy 339.163325 -288.992857) (xy 339.155499 -288.942571)
			(xy 339.155024 -288.917126) (xy 338.874608 -288.917126) (xy 338.8741 -288.943033) (xy 338.865994 -288.99421)
			(xy 338.849982 -289.043489) (xy 338.826459 -289.089656) (xy 338.796003 -289.131575) (xy 338.759365 -289.168213)
			(xy 338.717446 -289.198669) (xy 338.671279 -289.222192) (xy 338.622 -289.238204) (xy 338.570823 -289.24631)
			(xy 338.519009 -289.24631) (xy 338.467832 -289.238204) (xy 338.418553 -289.222192) (xy 338.372386 -289.198669)
			(xy 338.330467 -289.168213) (xy 338.293829 -289.131575) (xy 338.263373 -289.089656) (xy 338.23985 -289.043489)
			(xy 338.223838 -288.99421) (xy 338.215732 -288.943033) (xy 338.215224 -288.917126) (xy 336.995008 -288.917126)
			(xy 336.9945 -288.943033) (xy 336.986394 -288.99421) (xy 336.970382 -289.043489) (xy 336.946859 -289.089656)
			(xy 336.916403 -289.131575) (xy 336.879765 -289.168213) (xy 336.837846 -289.198669) (xy 336.791679 -289.222192)
			(xy 336.7424 -289.238204) (xy 336.691223 -289.24631) (xy 336.639409 -289.24631) (xy 336.588232 -289.238204)
			(xy 336.538953 -289.222192) (xy 336.492786 -289.198669) (xy 336.450867 -289.168213) (xy 336.414229 -289.131575)
			(xy 336.383773 -289.089656) (xy 336.36025 -289.043489) (xy 336.344238 -288.99421) (xy 336.336132 -288.943033)
			(xy 336.335624 -288.917126) (xy 136.04494 -288.917126) (xy 136.044432 -288.943033) (xy 136.036326 -288.99421)
			(xy 136.020314 -289.043489) (xy 135.996791 -289.089656) (xy 135.966335 -289.131575) (xy 135.929697 -289.168213)
			(xy 135.887778 -289.198669) (xy 135.841611 -289.222192) (xy 135.792332 -289.238204) (xy 135.741155 -289.24631)
			(xy 135.689341 -289.24631) (xy 135.638164 -289.238204) (xy 135.588885 -289.222192) (xy 135.542718 -289.198669)
			(xy 135.500799 -289.168213) (xy 135.464161 -289.131575) (xy 135.433705 -289.089656) (xy 135.410182 -289.043489)
			(xy 135.39417 -288.99421) (xy 135.386064 -288.943033) (xy 135.385556 -288.917126) (xy 135.386153 -288.889409)
			(xy 135.395474 -288.834762) (xy 135.404098 -288.808414) (xy 135.411972 -288.786316) (xy 135.20674 -288.431224)
			(xy 135.18388 -288.426906) (xy 135.159064 -288.421716) (xy 135.111285 -288.404766) (xy 135.066665 -288.380698)
			(xy 135.026258 -288.350081) (xy 134.991016 -288.313637) (xy 134.961772 -288.272226) (xy 134.939214 -288.226825)
			(xy 134.923875 -288.178504) (xy 134.916118 -288.128404) (xy 134.915656 -288.103056) (xy 132.75564 -288.103056)
			(xy 132.755038 -288.130773) (xy 132.74572 -288.18542) (xy 132.737098 -288.211768) (xy 132.729478 -288.233866)
			(xy 132.934456 -288.588958) (xy 132.957316 -288.593276) (xy 132.982127 -288.598486) (xy 133.029905 -288.615434)
			(xy 133.074524 -288.6395) (xy 133.114931 -288.670114) (xy 133.150173 -288.706556) (xy 133.179418 -288.747964)
			(xy 133.201977 -288.793363) (xy 133.217317 -288.841681) (xy 133.225077 -288.891779) (xy 133.22554 -288.917126)
			(xy 133.225032 -288.943033) (xy 133.216926 -288.99421) (xy 133.200914 -289.043489) (xy 133.177391 -289.089656)
			(xy 133.146935 -289.131575) (xy 133.110297 -289.168213) (xy 133.068378 -289.198669) (xy 133.022211 -289.222192)
			(xy 132.972932 -289.238204) (xy 132.921755 -289.24631) (xy 132.869941 -289.24631) (xy 132.818764 -289.238204)
			(xy 132.769485 -289.222192) (xy 132.723318 -289.198669) (xy 132.681399 -289.168213) (xy 132.644761 -289.131575)
			(xy 132.614305 -289.089656) (xy 132.590782 -289.043489) (xy 132.57477 -288.99421) (xy 132.566664 -288.943033)
			(xy 132.566156 -288.917126) (xy 132.566753 -288.889409) (xy 132.576074 -288.834762) (xy 132.584698 -288.808414)
			(xy 132.592572 -288.786316) (xy 132.387594 -288.431224) (xy 132.364734 -288.426906) (xy 132.339899 -288.421756)
			(xy 132.292089 -288.404821) (xy 132.247438 -288.380764) (xy 132.206999 -288.350151) (xy 132.171726 -288.313705)
			(xy 132.142451 -288.272287) (xy 132.119866 -288.226873) (xy 132.104504 -288.178536) (xy 132.096726 -288.128416)
			(xy 132.096256 -288.103056) (xy 130.87604 -288.103056) (xy 130.875438 -288.130773) (xy 130.86612 -288.18542)
			(xy 130.857498 -288.211768) (xy 130.849878 -288.233866) (xy 131.054856 -288.588958) (xy 131.077716 -288.593276)
			(xy 131.102527 -288.598486) (xy 131.150305 -288.615434) (xy 131.194924 -288.6395) (xy 131.235331 -288.670114)
			(xy 131.270573 -288.706556) (xy 131.299818 -288.747964) (xy 131.322377 -288.793363) (xy 131.337717 -288.841681)
			(xy 131.345477 -288.891779) (xy 131.34594 -288.917126) (xy 131.345432 -288.943033) (xy 131.337326 -288.99421)
			(xy 131.321314 -289.043489) (xy 131.297791 -289.089656) (xy 131.267335 -289.131575) (xy 131.230697 -289.168213)
			(xy 131.188778 -289.198669) (xy 131.142611 -289.222192) (xy 131.093332 -289.238204) (xy 131.042155 -289.24631)
			(xy 130.990341 -289.24631) (xy 130.939164 -289.238204) (xy 130.889885 -289.222192) (xy 130.843718 -289.198669)
			(xy 130.801799 -289.168213) (xy 130.765161 -289.131575) (xy 130.734705 -289.089656) (xy 130.711182 -289.043489)
			(xy 130.69517 -288.99421) (xy 130.687064 -288.943033) (xy 130.686556 -288.917126) (xy 130.687153 -288.889409)
			(xy 130.696474 -288.834762) (xy 130.705098 -288.808414) (xy 130.712972 -288.786316) (xy 130.507994 -288.431224)
			(xy 130.485134 -288.426906) (xy 130.460299 -288.421756) (xy 130.412489 -288.404821) (xy 130.367838 -288.380764)
			(xy 130.327399 -288.350151) (xy 130.292126 -288.313705) (xy 130.262851 -288.272287) (xy 130.240266 -288.226873)
			(xy 130.224904 -288.178536) (xy 130.217126 -288.128416) (xy 130.216656 -288.103056) (xy 128.99644 -288.103056)
			(xy 128.995838 -288.130773) (xy 128.98652 -288.18542) (xy 128.977898 -288.211768) (xy 128.970278 -288.233866)
			(xy 129.175256 -288.588958) (xy 129.198116 -288.593276) (xy 129.222927 -288.598486) (xy 129.270705 -288.615434)
			(xy 129.315324 -288.6395) (xy 129.355731 -288.670114) (xy 129.390973 -288.706556) (xy 129.420218 -288.747964)
			(xy 129.442777 -288.793363) (xy 129.458117 -288.841681) (xy 129.465877 -288.891779) (xy 129.46634 -288.917126)
			(xy 129.465832 -288.943033) (xy 129.457726 -288.99421) (xy 129.441714 -289.043489) (xy 129.418191 -289.089656)
			(xy 129.387735 -289.131575) (xy 129.351097 -289.168213) (xy 129.309178 -289.198669) (xy 129.263011 -289.222192)
			(xy 129.213732 -289.238204) (xy 129.162555 -289.24631) (xy 129.110741 -289.24631) (xy 129.059564 -289.238204)
			(xy 129.010285 -289.222192) (xy 128.964118 -289.198669) (xy 128.922199 -289.168213) (xy 128.885561 -289.131575)
			(xy 128.855105 -289.089656) (xy 128.831582 -289.043489) (xy 128.81557 -288.99421) (xy 128.807464 -288.943033)
			(xy 128.806956 -288.917126) (xy 128.807553 -288.889409) (xy 128.816874 -288.834762) (xy 128.825498 -288.808414)
			(xy 128.833372 -288.786316) (xy 128.628394 -288.431224) (xy 128.605534 -288.426906) (xy 128.580699 -288.421756)
			(xy 128.532889 -288.404821) (xy 128.488238 -288.380764) (xy 128.447799 -288.350151) (xy 128.412526 -288.313705)
			(xy 128.383251 -288.272287) (xy 128.360666 -288.226873) (xy 128.345304 -288.178536) (xy 128.337526 -288.128416)
			(xy 128.337056 -288.103056) (xy 127.11684 -288.103056) (xy 127.116238 -288.130773) (xy 127.10692 -288.18542)
			(xy 127.098298 -288.211768) (xy 127.090678 -288.233866) (xy 127.295656 -288.588958) (xy 127.318516 -288.593276)
			(xy 127.343327 -288.598486) (xy 127.391105 -288.615434) (xy 127.435724 -288.6395) (xy 127.476131 -288.670114)
			(xy 127.511373 -288.706556) (xy 127.540618 -288.747964) (xy 127.563177 -288.793363) (xy 127.578517 -288.841681)
			(xy 127.586277 -288.891779) (xy 127.58674 -288.917126) (xy 127.586232 -288.943033) (xy 127.578126 -288.99421)
			(xy 127.562114 -289.043489) (xy 127.538591 -289.089656) (xy 127.508135 -289.131575) (xy 127.471497 -289.168213)
			(xy 127.429578 -289.198669) (xy 127.383411 -289.222192) (xy 127.334132 -289.238204) (xy 127.282955 -289.24631)
			(xy 127.231141 -289.24631) (xy 127.179964 -289.238204) (xy 127.130685 -289.222192) (xy 127.084518 -289.198669)
			(xy 127.042599 -289.168213) (xy 127.005961 -289.131575) (xy 126.975505 -289.089656) (xy 126.951982 -289.043489)
			(xy 126.93597 -288.99421) (xy 126.927864 -288.943033) (xy 126.927356 -288.917126) (xy 126.927953 -288.889409)
			(xy 126.937274 -288.834762) (xy 126.945898 -288.808414) (xy 126.953772 -288.786316) (xy 126.748794 -288.431224)
			(xy 126.725934 -288.426906) (xy 126.701099 -288.421756) (xy 126.653289 -288.404821) (xy 126.608638 -288.380764)
			(xy 126.568199 -288.350151) (xy 126.532926 -288.313705) (xy 126.503651 -288.272287) (xy 126.481066 -288.226873)
			(xy 126.465704 -288.178536) (xy 126.457926 -288.128416) (xy 126.457456 -288.103056) (xy 125.23724 -288.103056)
			(xy 125.236638 -288.130773) (xy 125.22732 -288.18542) (xy 125.218698 -288.211768) (xy 125.211078 -288.233866)
			(xy 125.416056 -288.588958) (xy 125.438916 -288.593276) (xy 125.463727 -288.598486) (xy 125.511505 -288.615434)
			(xy 125.556124 -288.6395) (xy 125.596531 -288.670114) (xy 125.631773 -288.706556) (xy 125.661018 -288.747964)
			(xy 125.683577 -288.793363) (xy 125.698917 -288.841681) (xy 125.706677 -288.891779) (xy 125.70714 -288.917126)
			(xy 125.706632 -288.943033) (xy 125.698526 -288.99421) (xy 125.682514 -289.043489) (xy 125.658991 -289.089656)
			(xy 125.628535 -289.131575) (xy 125.591897 -289.168213) (xy 125.549978 -289.198669) (xy 125.503811 -289.222192)
			(xy 125.454532 -289.238204) (xy 125.403355 -289.24631) (xy 125.351541 -289.24631) (xy 125.300364 -289.238204)
			(xy 125.251085 -289.222192) (xy 125.204918 -289.198669) (xy 125.162999 -289.168213) (xy 125.126361 -289.131575)
			(xy 125.095905 -289.089656) (xy 125.072382 -289.043489) (xy 125.05637 -288.99421) (xy 125.048264 -288.943033)
			(xy 125.047756 -288.917126) (xy 125.048353 -288.889409) (xy 125.057674 -288.834762) (xy 125.066298 -288.808414)
			(xy 125.074172 -288.786316) (xy 124.869194 -288.431224) (xy 124.846334 -288.426906) (xy 124.821499 -288.421756)
			(xy 124.773689 -288.404821) (xy 124.729038 -288.380764) (xy 124.688599 -288.350151) (xy 124.653326 -288.313705)
			(xy 124.624051 -288.272287) (xy 124.601466 -288.226873) (xy 124.586104 -288.178536) (xy 124.578326 -288.128416)
			(xy 124.577856 -288.103056) (xy 123.35764 -288.103056) (xy 123.357038 -288.130773) (xy 123.34772 -288.18542)
			(xy 123.339098 -288.211768) (xy 123.331478 -288.233866) (xy 123.536456 -288.588958) (xy 123.559316 -288.593276)
			(xy 123.584127 -288.598486) (xy 123.631905 -288.615434) (xy 123.676524 -288.6395) (xy 123.716931 -288.670114)
			(xy 123.752173 -288.706556) (xy 123.781418 -288.747964) (xy 123.803977 -288.793363) (xy 123.819317 -288.841681)
			(xy 123.827077 -288.891779) (xy 123.82754 -288.917126) (xy 123.827032 -288.943033) (xy 123.818926 -288.99421)
			(xy 123.802914 -289.043489) (xy 123.779391 -289.089656) (xy 123.748935 -289.131575) (xy 123.712297 -289.168213)
			(xy 123.670378 -289.198669) (xy 123.624211 -289.222192) (xy 123.574932 -289.238204) (xy 123.523755 -289.24631)
			(xy 123.471941 -289.24631) (xy 123.420764 -289.238204) (xy 123.371485 -289.222192) (xy 123.325318 -289.198669)
			(xy 123.283399 -289.168213) (xy 123.246761 -289.131575) (xy 123.216305 -289.089656) (xy 123.192782 -289.043489)
			(xy 123.17677 -288.99421) (xy 123.168664 -288.943033) (xy 123.168156 -288.917126) (xy 123.168753 -288.889409)
			(xy 123.178074 -288.834762) (xy 123.186698 -288.808414) (xy 123.194572 -288.786316) (xy 122.989594 -288.431224)
			(xy 122.966734 -288.426906) (xy 122.941899 -288.421756) (xy 122.894089 -288.404821) (xy 122.849438 -288.380764)
			(xy 122.808999 -288.350151) (xy 122.773726 -288.313705) (xy 122.744451 -288.272287) (xy 122.721866 -288.226873)
			(xy 122.706504 -288.178536) (xy 122.698726 -288.128416) (xy 122.698256 -288.103056) (xy 121.47804 -288.103056)
			(xy 121.477438 -288.130773) (xy 121.46812 -288.18542) (xy 121.459498 -288.211768) (xy 121.451624 -288.233866)
			(xy 121.656856 -288.588958) (xy 121.679716 -288.593276) (xy 121.704527 -288.598486) (xy 121.752305 -288.615434)
			(xy 121.796924 -288.6395) (xy 121.837331 -288.670114) (xy 121.872573 -288.706556) (xy 121.901818 -288.747964)
			(xy 121.924377 -288.793363) (xy 121.939717 -288.841681) (xy 121.947477 -288.891779) (xy 121.94794 -288.917126)
			(xy 121.947432 -288.943033) (xy 121.939326 -288.99421) (xy 121.923314 -289.043489) (xy 121.899791 -289.089656)
			(xy 121.869335 -289.131575) (xy 121.832697 -289.168213) (xy 121.790778 -289.198669) (xy 121.744611 -289.222192)
			(xy 121.695332 -289.238204) (xy 121.644155 -289.24631) (xy 121.592341 -289.24631) (xy 121.541164 -289.238204)
			(xy 121.491885 -289.222192) (xy 121.445718 -289.198669) (xy 121.403799 -289.168213) (xy 121.367161 -289.131575)
			(xy 121.336705 -289.089656) (xy 121.313182 -289.043489) (xy 121.29717 -288.99421) (xy 121.289064 -288.943033)
			(xy 121.288556 -288.917126) (xy 121.289153 -288.889409) (xy 121.298474 -288.834762) (xy 121.307098 -288.808414)
			(xy 121.314972 -288.786316) (xy 121.10974 -288.431224) (xy 121.08688 -288.426906) (xy 121.062064 -288.421716)
			(xy 121.014285 -288.404766) (xy 120.969665 -288.380698) (xy 120.929258 -288.350081) (xy 120.894016 -288.313637)
			(xy 120.864772 -288.272226) (xy 120.842214 -288.226825) (xy 120.826875 -288.178504) (xy 120.819118 -288.128404)
			(xy 120.818656 -288.103056) (xy 104.56164 -288.103056) (xy 104.561218 -288.128404) (xy 104.553436 -288.178499)
			(xy 104.53808 -288.226813) (xy 104.515512 -288.272208) (xy 104.486262 -288.313614) (xy 104.451021 -288.350057)
			(xy 104.410618 -288.380678) (xy 104.366005 -288.404755) (xy 104.318232 -288.421722) (xy 104.293416 -288.426906)
			(xy 104.270556 -288.431224) (xy 104.065324 -288.786316) (xy 104.073198 -288.808414) (xy 104.08184 -288.834757)
			(xy 104.091154 -288.889407) (xy 104.09174 -288.917126) (xy 104.091232 -288.943033) (xy 104.083126 -288.99421)
			(xy 104.067114 -289.043489) (xy 104.043591 -289.089656) (xy 104.013135 -289.131575) (xy 103.976497 -289.168213)
			(xy 103.934578 -289.198669) (xy 103.888411 -289.222192) (xy 103.839132 -289.238204) (xy 103.787955 -289.24631)
			(xy 103.736141 -289.24631) (xy 103.684964 -289.238204) (xy 103.635685 -289.222192) (xy 103.589518 -289.198669)
			(xy 103.547599 -289.168213) (xy 103.510961 -289.131575) (xy 103.480505 -289.089656) (xy 103.456982 -289.043489)
			(xy 103.44097 -288.99421) (xy 103.432864 -288.943033) (xy 103.432356 -288.917126) (xy 103.15194 -288.917126)
			(xy 103.151518 -288.940067) (xy 103.14509 -288.985498) (xy 103.132444 -289.029604) (xy 103.123492 -289.05073)
			(xy 103.113586 -289.073336) (xy 103.327454 -289.478466) (xy 103.351584 -289.483038) (xy 103.37651 -289.488115)
			(xy 103.424521 -289.50492) (xy 103.469379 -289.528904) (xy 103.510019 -289.559496) (xy 103.545476 -289.59597)
			(xy 103.574906 -289.637459) (xy 103.597612 -289.682977) (xy 103.613053 -289.731444) (xy 103.620863 -289.781708)
			(xy 103.621332 -289.807142) (xy 119.878856 -289.807142) (xy 119.879399 -289.781715) (xy 119.887229 -289.731468)
			(xy 119.90268 -289.683018) (xy 119.925386 -289.637514) (xy 119.954808 -289.596036) (xy 119.990248 -289.559565)
			(xy 120.030867 -289.528967) (xy 120.075701 -289.504967) (xy 120.123688 -289.488134) (xy 120.148604 -289.483038)
			(xy 120.172734 -289.478466) (xy 120.38711 -289.073082) (xy 120.377204 -289.050476) (xy 120.368243 -289.029398)
			(xy 120.355596 -288.985377) (xy 120.349182 -288.940026) (xy 120.348756 -288.917126) (xy 120.349264 -288.891219)
			(xy 120.35737 -288.840042) (xy 120.373382 -288.790763) (xy 120.396905 -288.744596) (xy 120.427361 -288.702677)
			(xy 120.463999 -288.666039) (xy 120.505918 -288.635583) (xy 120.552085 -288.61206) (xy 120.601364 -288.596048)
			(xy 120.652541 -288.587942) (xy 120.704355 -288.587942) (xy 120.755532 -288.596048) (xy 120.804811 -288.61206)
			(xy 120.850978 -288.635583) (xy 120.892897 -288.666039) (xy 120.929535 -288.702677) (xy 120.959991 -288.744596)
			(xy 120.983514 -288.790763) (xy 120.999526 -288.840042) (xy 121.007632 -288.891219) (xy 121.00814 -288.917126)
			(xy 121.007659 -288.942574) (xy 120.999856 -288.992867) (xy 120.984408 -289.041361) (xy 120.961683 -289.086901)
			(xy 120.932222 -289.128403) (xy 120.896727 -289.164878) (xy 120.856043 -289.195458) (xy 120.811139 -289.219415)
			(xy 120.763084 -289.236178) (xy 120.738138 -289.24123) (xy 120.714008 -289.245802) (xy 120.499632 -289.651186)
			(xy 120.509538 -289.673792) (xy 120.518456 -289.694878) (xy 120.531008 -289.738907) (xy 120.537342 -289.78425)
			(xy 120.537732 -289.807142) (xy 121.758456 -289.807142) (xy 121.758999 -289.781715) (xy 121.766829 -289.731468)
			(xy 121.78228 -289.683018) (xy 121.804986 -289.637514) (xy 121.834408 -289.596036) (xy 121.869848 -289.559565)
			(xy 121.910467 -289.528967) (xy 121.955301 -289.504967) (xy 122.003288 -289.488134) (xy 122.028204 -289.483038)
			(xy 122.052334 -289.478466) (xy 122.26671 -289.073082) (xy 122.256804 -289.050476) (xy 122.247843 -289.029398)
			(xy 122.235196 -288.985377) (xy 122.228782 -288.940026) (xy 122.228356 -288.917126) (xy 122.228864 -288.891219)
			(xy 122.23697 -288.840042) (xy 122.252982 -288.790763) (xy 122.276505 -288.744596) (xy 122.306961 -288.702677)
			(xy 122.343599 -288.666039) (xy 122.385518 -288.635583) (xy 122.431685 -288.61206) (xy 122.480964 -288.596048)
			(xy 122.532141 -288.587942) (xy 122.583955 -288.587942) (xy 122.635132 -288.596048) (xy 122.684411 -288.61206)
			(xy 122.730578 -288.635583) (xy 122.772497 -288.666039) (xy 122.809135 -288.702677) (xy 122.839591 -288.744596)
			(xy 122.863114 -288.790763) (xy 122.879126 -288.840042) (xy 122.887232 -288.891219) (xy 122.88774 -288.917126)
			(xy 122.887259 -288.942574) (xy 122.879456 -288.992867) (xy 122.864008 -289.041361) (xy 122.841283 -289.086901)
			(xy 122.811822 -289.128403) (xy 122.776327 -289.164878) (xy 122.735643 -289.195458) (xy 122.690739 -289.219415)
			(xy 122.642684 -289.236178) (xy 122.617738 -289.24123) (xy 122.593608 -289.245802) (xy 122.379232 -289.651186)
			(xy 122.389138 -289.673792) (xy 122.398056 -289.694878) (xy 122.410608 -289.738907) (xy 122.416942 -289.78425)
			(xy 122.417332 -289.807142) (xy 123.638056 -289.807142) (xy 123.638599 -289.781715) (xy 123.646429 -289.731468)
			(xy 123.66188 -289.683018) (xy 123.684586 -289.637514) (xy 123.714008 -289.596036) (xy 123.749448 -289.559565)
			(xy 123.790067 -289.528967) (xy 123.834901 -289.504967) (xy 123.882888 -289.488134) (xy 123.907804 -289.483038)
			(xy 123.931934 -289.478466) (xy 124.14631 -289.073082) (xy 124.136404 -289.050476) (xy 124.127443 -289.029398)
			(xy 124.114796 -288.985377) (xy 124.108382 -288.940026) (xy 124.107956 -288.917126) (xy 124.108464 -288.891219)
			(xy 124.11657 -288.840042) (xy 124.132582 -288.790763) (xy 124.156105 -288.744596) (xy 124.186561 -288.702677)
			(xy 124.223199 -288.666039) (xy 124.265118 -288.635583) (xy 124.311285 -288.61206) (xy 124.360564 -288.596048)
			(xy 124.411741 -288.587942) (xy 124.463555 -288.587942) (xy 124.514732 -288.596048) (xy 124.564011 -288.61206)
			(xy 124.610178 -288.635583) (xy 124.652097 -288.666039) (xy 124.688735 -288.702677) (xy 124.719191 -288.744596)
			(xy 124.742714 -288.790763) (xy 124.758726 -288.840042) (xy 124.766832 -288.891219) (xy 124.76734 -288.917126)
			(xy 124.766859 -288.942574) (xy 124.759056 -288.992867) (xy 124.743608 -289.041361) (xy 124.720883 -289.086901)
			(xy 124.691422 -289.128403) (xy 124.655927 -289.164878) (xy 124.615243 -289.195458) (xy 124.570339 -289.219415)
			(xy 124.522284 -289.236178) (xy 124.497338 -289.24123) (xy 124.473208 -289.245802) (xy 124.258832 -289.651186)
			(xy 124.268738 -289.673792) (xy 124.277656 -289.694878) (xy 124.290208 -289.738907) (xy 124.296542 -289.78425)
			(xy 124.296932 -289.807142) (xy 125.517656 -289.807142) (xy 125.518199 -289.781715) (xy 125.526029 -289.731468)
			(xy 125.54148 -289.683018) (xy 125.564186 -289.637514) (xy 125.593608 -289.596036) (xy 125.629048 -289.559565)
			(xy 125.669667 -289.528967) (xy 125.714501 -289.504967) (xy 125.762488 -289.488134) (xy 125.787404 -289.483038)
			(xy 125.811534 -289.478466) (xy 126.02591 -289.073082) (xy 126.016004 -289.050476) (xy 126.007043 -289.029398)
			(xy 125.994396 -288.985377) (xy 125.987982 -288.940026) (xy 125.987556 -288.917126) (xy 125.988064 -288.891219)
			(xy 125.99617 -288.840042) (xy 126.012182 -288.790763) (xy 126.035705 -288.744596) (xy 126.066161 -288.702677)
			(xy 126.102799 -288.666039) (xy 126.144718 -288.635583) (xy 126.190885 -288.61206) (xy 126.240164 -288.596048)
			(xy 126.291341 -288.587942) (xy 126.343155 -288.587942) (xy 126.394332 -288.596048) (xy 126.443611 -288.61206)
			(xy 126.489778 -288.635583) (xy 126.531697 -288.666039) (xy 126.568335 -288.702677) (xy 126.598791 -288.744596)
			(xy 126.622314 -288.790763) (xy 126.638326 -288.840042) (xy 126.646432 -288.891219) (xy 126.64694 -288.917126)
			(xy 126.646459 -288.942574) (xy 126.638656 -288.992867) (xy 126.623208 -289.041361) (xy 126.600483 -289.086901)
			(xy 126.571022 -289.128403) (xy 126.535527 -289.164878) (xy 126.494843 -289.195458) (xy 126.449939 -289.219415)
			(xy 126.401884 -289.236178) (xy 126.376938 -289.24123) (xy 126.352808 -289.245802) (xy 126.138432 -289.651186)
			(xy 126.148338 -289.673792) (xy 126.157256 -289.694878) (xy 126.169808 -289.738907) (xy 126.176142 -289.78425)
			(xy 126.176532 -289.807142) (xy 127.397256 -289.807142) (xy 127.397799 -289.781715) (xy 127.405629 -289.731468)
			(xy 127.42108 -289.683018) (xy 127.443786 -289.637514) (xy 127.473208 -289.596036) (xy 127.508648 -289.559565)
			(xy 127.549267 -289.528967) (xy 127.594101 -289.504967) (xy 127.642088 -289.488134) (xy 127.667004 -289.483038)
			(xy 127.691134 -289.478466) (xy 127.90551 -289.073082) (xy 127.895604 -289.050476) (xy 127.886643 -289.029398)
			(xy 127.873996 -288.985377) (xy 127.867582 -288.940026) (xy 127.867156 -288.917126) (xy 127.867664 -288.891219)
			(xy 127.87577 -288.840042) (xy 127.891782 -288.790763) (xy 127.915305 -288.744596) (xy 127.945761 -288.702677)
			(xy 127.982399 -288.666039) (xy 128.024318 -288.635583) (xy 128.070485 -288.61206) (xy 128.119764 -288.596048)
			(xy 128.170941 -288.587942) (xy 128.222755 -288.587942) (xy 128.273932 -288.596048) (xy 128.323211 -288.61206)
			(xy 128.369378 -288.635583) (xy 128.411297 -288.666039) (xy 128.447935 -288.702677) (xy 128.478391 -288.744596)
			(xy 128.501914 -288.790763) (xy 128.517926 -288.840042) (xy 128.526032 -288.891219) (xy 128.52654 -288.917126)
			(xy 128.526059 -288.942574) (xy 128.518256 -288.992867) (xy 128.502808 -289.041361) (xy 128.480083 -289.086901)
			(xy 128.450622 -289.128403) (xy 128.415127 -289.164878) (xy 128.374443 -289.195458) (xy 128.329539 -289.219415)
			(xy 128.281484 -289.236178) (xy 128.256538 -289.24123) (xy 128.232408 -289.245802) (xy 128.018032 -289.651186)
			(xy 128.027938 -289.673792) (xy 128.036856 -289.694878) (xy 128.049408 -289.738907) (xy 128.055742 -289.78425)
			(xy 128.056132 -289.807142) (xy 129.276856 -289.807142) (xy 129.277399 -289.781715) (xy 129.285229 -289.731468)
			(xy 129.30068 -289.683018) (xy 129.323386 -289.637514) (xy 129.352808 -289.596036) (xy 129.388248 -289.559565)
			(xy 129.428867 -289.528967) (xy 129.473701 -289.504967) (xy 129.521688 -289.488134) (xy 129.546604 -289.483038)
			(xy 129.570734 -289.478466) (xy 129.78511 -289.073082) (xy 129.775204 -289.050476) (xy 129.766243 -289.029398)
			(xy 129.753596 -288.985377) (xy 129.747182 -288.940026) (xy 129.746756 -288.917126) (xy 129.747264 -288.891219)
			(xy 129.75537 -288.840042) (xy 129.771382 -288.790763) (xy 129.794905 -288.744596) (xy 129.825361 -288.702677)
			(xy 129.861999 -288.666039) (xy 129.903918 -288.635583) (xy 129.950085 -288.61206) (xy 129.999364 -288.596048)
			(xy 130.050541 -288.587942) (xy 130.102355 -288.587942) (xy 130.153532 -288.596048) (xy 130.202811 -288.61206)
			(xy 130.248978 -288.635583) (xy 130.290897 -288.666039) (xy 130.327535 -288.702677) (xy 130.357991 -288.744596)
			(xy 130.381514 -288.790763) (xy 130.397526 -288.840042) (xy 130.405632 -288.891219) (xy 130.40614 -288.917126)
			(xy 130.405659 -288.942574) (xy 130.397856 -288.992867) (xy 130.382408 -289.041361) (xy 130.359683 -289.086901)
			(xy 130.330222 -289.128403) (xy 130.294727 -289.164878) (xy 130.254043 -289.195458) (xy 130.209139 -289.219415)
			(xy 130.161084 -289.236178) (xy 130.136138 -289.24123) (xy 130.112008 -289.245802) (xy 129.897632 -289.651186)
			(xy 129.907538 -289.673792) (xy 129.916456 -289.694878) (xy 129.929008 -289.738907) (xy 129.935342 -289.78425)
			(xy 129.935732 -289.807142) (xy 131.156456 -289.807142) (xy 131.156999 -289.781715) (xy 131.164829 -289.731468)
			(xy 131.18028 -289.683018) (xy 131.202986 -289.637514) (xy 131.232408 -289.596036) (xy 131.267848 -289.559565)
			(xy 131.308467 -289.528967) (xy 131.353301 -289.504967) (xy 131.401288 -289.488134) (xy 131.426204 -289.483038)
			(xy 131.450334 -289.478466) (xy 131.66471 -289.073082) (xy 131.654804 -289.050476) (xy 131.645843 -289.029398)
			(xy 131.633196 -288.985377) (xy 131.626782 -288.940026) (xy 131.626356 -288.917126) (xy 131.626864 -288.891219)
			(xy 131.63497 -288.840042) (xy 131.650982 -288.790763) (xy 131.674505 -288.744596) (xy 131.704961 -288.702677)
			(xy 131.741599 -288.666039) (xy 131.783518 -288.635583) (xy 131.829685 -288.61206) (xy 131.878964 -288.596048)
			(xy 131.930141 -288.587942) (xy 131.981955 -288.587942) (xy 132.033132 -288.596048) (xy 132.082411 -288.61206)
			(xy 132.128578 -288.635583) (xy 132.170497 -288.666039) (xy 132.207135 -288.702677) (xy 132.237591 -288.744596)
			(xy 132.261114 -288.790763) (xy 132.277126 -288.840042) (xy 132.285232 -288.891219) (xy 132.28574 -288.917126)
			(xy 132.285259 -288.942574) (xy 132.277456 -288.992867) (xy 132.262008 -289.041361) (xy 132.239283 -289.086901)
			(xy 132.209822 -289.128403) (xy 132.174327 -289.164878) (xy 132.133643 -289.195458) (xy 132.088739 -289.219415)
			(xy 132.040684 -289.236178) (xy 132.015738 -289.24123) (xy 131.991608 -289.245802) (xy 131.777232 -289.651186)
			(xy 131.787138 -289.673792) (xy 131.796056 -289.694878) (xy 131.808608 -289.738907) (xy 131.814942 -289.78425)
			(xy 131.815332 -289.807142) (xy 133.036056 -289.807142) (xy 133.036599 -289.781715) (xy 133.044429 -289.731468)
			(xy 133.05988 -289.683018) (xy 133.082586 -289.637514) (xy 133.112008 -289.596036) (xy 133.147448 -289.559565)
			(xy 133.188067 -289.528967) (xy 133.232901 -289.504967) (xy 133.280888 -289.488134) (xy 133.305804 -289.483038)
			(xy 133.329934 -289.478466) (xy 133.54431 -289.073082) (xy 133.534404 -289.050476) (xy 133.525443 -289.029398)
			(xy 133.512796 -288.985377) (xy 133.506382 -288.940026) (xy 133.505956 -288.917126) (xy 133.506464 -288.891219)
			(xy 133.51457 -288.840042) (xy 133.530582 -288.790763) (xy 133.554105 -288.744596) (xy 133.584561 -288.702677)
			(xy 133.621199 -288.666039) (xy 133.663118 -288.635583) (xy 133.709285 -288.61206) (xy 133.758564 -288.596048)
			(xy 133.809741 -288.587942) (xy 133.861555 -288.587942) (xy 133.912732 -288.596048) (xy 133.962011 -288.61206)
			(xy 134.008178 -288.635583) (xy 134.050097 -288.666039) (xy 134.086735 -288.702677) (xy 134.117191 -288.744596)
			(xy 134.140714 -288.790763) (xy 134.156726 -288.840042) (xy 134.164832 -288.891219) (xy 134.16534 -288.917126)
			(xy 134.164859 -288.942574) (xy 134.157056 -288.992867) (xy 134.141608 -289.041361) (xy 134.118883 -289.086901)
			(xy 134.089422 -289.128403) (xy 134.053927 -289.164878) (xy 134.013243 -289.195458) (xy 133.968339 -289.219415)
			(xy 133.920284 -289.236178) (xy 133.895338 -289.24123) (xy 133.871208 -289.245802) (xy 133.656832 -289.651186)
			(xy 133.666738 -289.673792) (xy 133.675656 -289.694878) (xy 133.688208 -289.738907) (xy 133.694542 -289.78425)
			(xy 133.694932 -289.807142) (xy 133.694424 -289.833029) (xy 133.686325 -289.884167) (xy 133.670326 -289.933407)
			(xy 133.64682 -289.979539) (xy 133.616388 -290.021426) (xy 133.579778 -290.058036) (xy 133.537891 -290.088468)
			(xy 133.491759 -290.111974) (xy 133.442519 -290.127973) (xy 133.391381 -290.136072) (xy 133.339607 -290.136072)
			(xy 133.288469 -290.127973) (xy 133.239229 -290.111974) (xy 133.193097 -290.088468) (xy 133.15121 -290.058036)
			(xy 133.1146 -290.021426) (xy 133.084168 -289.979539) (xy 133.060662 -289.933407) (xy 133.044663 -289.884167)
			(xy 133.036564 -289.833029) (xy 133.036056 -289.807142) (xy 131.815332 -289.807142) (xy 131.814824 -289.833029)
			(xy 131.806725 -289.884167) (xy 131.790726 -289.933407) (xy 131.76722 -289.979539) (xy 131.736788 -290.021426)
			(xy 131.700178 -290.058036) (xy 131.658291 -290.088468) (xy 131.612159 -290.111974) (xy 131.562919 -290.127973)
			(xy 131.511781 -290.136072) (xy 131.460007 -290.136072) (xy 131.408869 -290.127973) (xy 131.359629 -290.111974)
			(xy 131.313497 -290.088468) (xy 131.27161 -290.058036) (xy 131.235 -290.021426) (xy 131.204568 -289.979539)
			(xy 131.181062 -289.933407) (xy 131.165063 -289.884167) (xy 131.156964 -289.833029) (xy 131.156456 -289.807142)
			(xy 129.935732 -289.807142) (xy 129.935224 -289.833029) (xy 129.927125 -289.884167) (xy 129.911126 -289.933407)
			(xy 129.88762 -289.979539) (xy 129.857188 -290.021426) (xy 129.820578 -290.058036) (xy 129.778691 -290.088468)
			(xy 129.732559 -290.111974) (xy 129.683319 -290.127973) (xy 129.632181 -290.136072) (xy 129.580407 -290.136072)
			(xy 129.529269 -290.127973) (xy 129.480029 -290.111974) (xy 129.433897 -290.088468) (xy 129.39201 -290.058036)
			(xy 129.3554 -290.021426) (xy 129.324968 -289.979539) (xy 129.301462 -289.933407) (xy 129.285463 -289.884167)
			(xy 129.277364 -289.833029) (xy 129.276856 -289.807142) (xy 128.056132 -289.807142) (xy 128.055624 -289.833029)
			(xy 128.047525 -289.884167) (xy 128.031526 -289.933407) (xy 128.00802 -289.979539) (xy 127.977588 -290.021426)
			(xy 127.940978 -290.058036) (xy 127.899091 -290.088468) (xy 127.852959 -290.111974) (xy 127.803719 -290.127973)
			(xy 127.752581 -290.136072) (xy 127.700807 -290.136072) (xy 127.649669 -290.127973) (xy 127.600429 -290.111974)
			(xy 127.554297 -290.088468) (xy 127.51241 -290.058036) (xy 127.4758 -290.021426) (xy 127.445368 -289.979539)
			(xy 127.421862 -289.933407) (xy 127.405863 -289.884167) (xy 127.397764 -289.833029) (xy 127.397256 -289.807142)
			(xy 126.176532 -289.807142) (xy 126.176024 -289.833029) (xy 126.167925 -289.884167) (xy 126.151926 -289.933407)
			(xy 126.12842 -289.979539) (xy 126.097988 -290.021426) (xy 126.061378 -290.058036) (xy 126.019491 -290.088468)
			(xy 125.973359 -290.111974) (xy 125.924119 -290.127973) (xy 125.872981 -290.136072) (xy 125.821207 -290.136072)
			(xy 125.770069 -290.127973) (xy 125.720829 -290.111974) (xy 125.674697 -290.088468) (xy 125.63281 -290.058036)
			(xy 125.5962 -290.021426) (xy 125.565768 -289.979539) (xy 125.542262 -289.933407) (xy 125.526263 -289.884167)
			(xy 125.518164 -289.833029) (xy 125.517656 -289.807142) (xy 124.296932 -289.807142) (xy 124.296424 -289.833029)
			(xy 124.288325 -289.884167) (xy 124.272326 -289.933407) (xy 124.24882 -289.979539) (xy 124.218388 -290.021426)
			(xy 124.181778 -290.058036) (xy 124.139891 -290.088468) (xy 124.093759 -290.111974) (xy 124.044519 -290.127973)
			(xy 123.993381 -290.136072) (xy 123.941607 -290.136072) (xy 123.890469 -290.127973) (xy 123.841229 -290.111974)
			(xy 123.795097 -290.088468) (xy 123.75321 -290.058036) (xy 123.7166 -290.021426) (xy 123.686168 -289.979539)
			(xy 123.662662 -289.933407) (xy 123.646663 -289.884167) (xy 123.638564 -289.833029) (xy 123.638056 -289.807142)
			(xy 122.417332 -289.807142) (xy 122.416824 -289.833029) (xy 122.408725 -289.884167) (xy 122.392726 -289.933407)
			(xy 122.36922 -289.979539) (xy 122.338788 -290.021426) (xy 122.302178 -290.058036) (xy 122.260291 -290.088468)
			(xy 122.214159 -290.111974) (xy 122.164919 -290.127973) (xy 122.113781 -290.136072) (xy 122.062007 -290.136072)
			(xy 122.010869 -290.127973) (xy 121.961629 -290.111974) (xy 121.915497 -290.088468) (xy 121.87361 -290.058036)
			(xy 121.837 -290.021426) (xy 121.806568 -289.979539) (xy 121.783062 -289.933407) (xy 121.767063 -289.884167)
			(xy 121.758964 -289.833029) (xy 121.758456 -289.807142) (xy 120.537732 -289.807142) (xy 120.537224 -289.833029)
			(xy 120.529125 -289.884167) (xy 120.513126 -289.933407) (xy 120.48962 -289.979539) (xy 120.459188 -290.021426)
			(xy 120.422578 -290.058036) (xy 120.380691 -290.088468) (xy 120.334559 -290.111974) (xy 120.285319 -290.127973)
			(xy 120.234181 -290.136072) (xy 120.182407 -290.136072) (xy 120.131269 -290.127973) (xy 120.082029 -290.111974)
			(xy 120.035897 -290.088468) (xy 119.99401 -290.058036) (xy 119.9574 -290.021426) (xy 119.926968 -289.979539)
			(xy 119.903462 -289.933407) (xy 119.887463 -289.884167) (xy 119.879364 -289.833029) (xy 119.878856 -289.807142)
			(xy 103.621332 -289.807142) (xy 103.620824 -289.833029) (xy 103.612725 -289.884167) (xy 103.596726 -289.933407)
			(xy 103.57322 -289.979539) (xy 103.542788 -290.021426) (xy 103.506178 -290.058036) (xy 103.464291 -290.088468)
			(xy 103.418159 -290.111974) (xy 103.368919 -290.127973) (xy 103.317781 -290.136072) (xy 103.266007 -290.136072)
			(xy 103.214869 -290.127973) (xy 103.165629 -290.111974) (xy 103.119497 -290.088468) (xy 103.07761 -290.058036)
			(xy 103.041 -290.021426) (xy 103.010568 -289.979539) (xy 102.987062 -289.933407) (xy 102.971063 -289.884167)
			(xy 102.962964 -289.833029) (xy 102.962456 -289.807142) (xy 102.962456 -289.806634) (xy 102.962859 -289.783785)
			(xy 102.969212 -289.738531) (xy 102.981758 -289.694589) (xy 102.99065 -289.673538) (xy 103.000556 -289.650932)
			(xy 102.786688 -289.245802) (xy 102.762558 -289.24123) (xy 102.737619 -289.236158) (xy 102.689576 -289.219379)
			(xy 102.644683 -289.195414) (xy 102.604007 -289.164832) (xy 102.568517 -289.12836) (xy 102.539055 -289.086867)
			(xy 102.516322 -289.041337) (xy 102.500858 -288.992854) (xy 102.493031 -288.942571) (xy 102.492556 -288.917126)
			(xy 102.21214 -288.917126) (xy 102.211632 -288.943033) (xy 102.203526 -288.99421) (xy 102.187514 -289.043489)
			(xy 102.163991 -289.089656) (xy 102.133535 -289.131575) (xy 102.096897 -289.168213) (xy 102.054978 -289.198669)
			(xy 102.008811 -289.222192) (xy 101.959532 -289.238204) (xy 101.908355 -289.24631) (xy 101.856541 -289.24631)
			(xy 101.805364 -289.238204) (xy 101.756085 -289.222192) (xy 101.709918 -289.198669) (xy 101.667999 -289.168213)
			(xy 101.631361 -289.131575) (xy 101.600905 -289.089656) (xy 101.577382 -289.043489) (xy 101.56137 -288.99421)
			(xy 101.553264 -288.943033) (xy 101.552756 -288.917126) (xy 101.27234 -288.917126) (xy 101.271918 -288.940067)
			(xy 101.26549 -288.985498) (xy 101.252844 -289.029604) (xy 101.243892 -289.05073) (xy 101.233986 -289.073336)
			(xy 101.447854 -289.478466) (xy 101.471984 -289.483038) (xy 101.49691 -289.488115) (xy 101.544921 -289.50492)
			(xy 101.589779 -289.528904) (xy 101.630419 -289.559496) (xy 101.665876 -289.59597) (xy 101.695306 -289.637459)
			(xy 101.718012 -289.682977) (xy 101.733453 -289.731444) (xy 101.741263 -289.781708) (xy 101.741732 -289.807142)
			(xy 101.741224 -289.833029) (xy 101.733125 -289.884167) (xy 101.717126 -289.933407) (xy 101.69362 -289.979539)
			(xy 101.663188 -290.021426) (xy 101.626578 -290.058036) (xy 101.584691 -290.088468) (xy 101.538559 -290.111974)
			(xy 101.489319 -290.127973) (xy 101.438181 -290.136072) (xy 101.386407 -290.136072) (xy 101.335269 -290.127973)
			(xy 101.286029 -290.111974) (xy 101.239897 -290.088468) (xy 101.19801 -290.058036) (xy 101.1614 -290.021426)
			(xy 101.130968 -289.979539) (xy 101.107462 -289.933407) (xy 101.091463 -289.884167) (xy 101.083364 -289.833029)
			(xy 101.082856 -289.807142) (xy 101.082856 -289.806634) (xy 101.083259 -289.783785) (xy 101.089612 -289.738531)
			(xy 101.102158 -289.694589) (xy 101.11105 -289.673538) (xy 101.120956 -289.650932) (xy 100.907088 -289.245802)
			(xy 100.882958 -289.24123) (xy 100.858019 -289.236158) (xy 100.809976 -289.219379) (xy 100.765083 -289.195414)
			(xy 100.724407 -289.164832) (xy 100.688917 -289.12836) (xy 100.659455 -289.086867) (xy 100.636722 -289.041337)
			(xy 100.621258 -288.992854) (xy 100.613431 -288.942571) (xy 100.612956 -288.917126) (xy 100.33254 -288.917126)
			(xy 100.332032 -288.943033) (xy 100.323926 -288.99421) (xy 100.307914 -289.043489) (xy 100.284391 -289.089656)
			(xy 100.253935 -289.131575) (xy 100.217297 -289.168213) (xy 100.175378 -289.198669) (xy 100.129211 -289.222192)
			(xy 100.079932 -289.238204) (xy 100.028755 -289.24631) (xy 99.976941 -289.24631) (xy 99.925764 -289.238204)
			(xy 99.876485 -289.222192) (xy 99.830318 -289.198669) (xy 99.788399 -289.168213) (xy 99.751761 -289.131575)
			(xy 99.721305 -289.089656) (xy 99.697782 -289.043489) (xy 99.68177 -288.99421) (xy 99.673664 -288.943033)
			(xy 99.673156 -288.917126) (xy 99.39274 -288.917126) (xy 99.392318 -288.940067) (xy 99.38589 -288.985498)
			(xy 99.373244 -289.029604) (xy 99.364292 -289.05073) (xy 99.354386 -289.073336) (xy 99.568254 -289.478466)
			(xy 99.592384 -289.483038) (xy 99.61731 -289.488115) (xy 99.665321 -289.50492) (xy 99.710179 -289.528904)
			(xy 99.750819 -289.559496) (xy 99.786276 -289.59597) (xy 99.815706 -289.637459) (xy 99.838412 -289.682977)
			(xy 99.853853 -289.731444) (xy 99.861663 -289.781708) (xy 99.862132 -289.807142) (xy 99.861624 -289.833029)
			(xy 99.853525 -289.884167) (xy 99.837526 -289.933407) (xy 99.81402 -289.979539) (xy 99.783588 -290.021426)
			(xy 99.746978 -290.058036) (xy 99.705091 -290.088468) (xy 99.658959 -290.111974) (xy 99.609719 -290.127973)
			(xy 99.558581 -290.136072) (xy 99.506807 -290.136072) (xy 99.455669 -290.127973) (xy 99.406429 -290.111974)
			(xy 99.360297 -290.088468) (xy 99.31841 -290.058036) (xy 99.2818 -290.021426) (xy 99.251368 -289.979539)
			(xy 99.227862 -289.933407) (xy 99.211863 -289.884167) (xy 99.203764 -289.833029) (xy 99.203256 -289.807142)
			(xy 99.203256 -289.806634) (xy 99.203659 -289.783785) (xy 99.210012 -289.738531) (xy 99.222558 -289.694589)
			(xy 99.23145 -289.673538) (xy 99.241356 -289.650932) (xy 99.027488 -289.245802) (xy 99.003358 -289.24123)
			(xy 98.978419 -289.236158) (xy 98.930376 -289.219379) (xy 98.885483 -289.195414) (xy 98.844807 -289.164832)
			(xy 98.809317 -289.12836) (xy 98.779855 -289.086867) (xy 98.757122 -289.041337) (xy 98.741658 -288.992854)
			(xy 98.733831 -288.942571) (xy 98.733356 -288.917126) (xy 98.45294 -288.917126) (xy 98.452432 -288.943033)
			(xy 98.444326 -288.99421) (xy 98.428314 -289.043489) (xy 98.404791 -289.089656) (xy 98.374335 -289.131575)
			(xy 98.337697 -289.168213) (xy 98.295778 -289.198669) (xy 98.249611 -289.222192) (xy 98.200332 -289.238204)
			(xy 98.149155 -289.24631) (xy 98.097341 -289.24631) (xy 98.046164 -289.238204) (xy 97.996885 -289.222192)
			(xy 97.950718 -289.198669) (xy 97.908799 -289.168213) (xy 97.872161 -289.131575) (xy 97.841705 -289.089656)
			(xy 97.818182 -289.043489) (xy 97.80217 -288.99421) (xy 97.794064 -288.943033) (xy 97.793556 -288.917126)
			(xy 97.51314 -288.917126) (xy 97.512718 -288.940067) (xy 97.50629 -288.985498) (xy 97.493644 -289.029604)
			(xy 97.484692 -289.05073) (xy 97.474786 -289.073336) (xy 97.688654 -289.478466) (xy 97.712784 -289.483038)
			(xy 97.73771 -289.488115) (xy 97.785721 -289.50492) (xy 97.830579 -289.528904) (xy 97.871219 -289.559496)
			(xy 97.906676 -289.59597) (xy 97.936106 -289.637459) (xy 97.958812 -289.682977) (xy 97.974253 -289.731444)
			(xy 97.982063 -289.781708) (xy 97.982532 -289.807142) (xy 97.982024 -289.833029) (xy 97.973925 -289.884167)
			(xy 97.957926 -289.933407) (xy 97.93442 -289.979539) (xy 97.903988 -290.021426) (xy 97.867378 -290.058036)
			(xy 97.825491 -290.088468) (xy 97.779359 -290.111974) (xy 97.730119 -290.127973) (xy 97.678981 -290.136072)
			(xy 97.627207 -290.136072) (xy 97.576069 -290.127973) (xy 97.526829 -290.111974) (xy 97.480697 -290.088468)
			(xy 97.43881 -290.058036) (xy 97.4022 -290.021426) (xy 97.371768 -289.979539) (xy 97.348262 -289.933407)
			(xy 97.332263 -289.884167) (xy 97.324164 -289.833029) (xy 97.323656 -289.807142) (xy 97.323656 -289.806634)
			(xy 97.324059 -289.783785) (xy 97.330412 -289.738531) (xy 97.342958 -289.694589) (xy 97.35185 -289.673538)
			(xy 97.361756 -289.650932) (xy 97.147888 -289.245802) (xy 97.123758 -289.24123) (xy 97.098819 -289.236158)
			(xy 97.050776 -289.219379) (xy 97.005883 -289.195414) (xy 96.965207 -289.164832) (xy 96.929717 -289.12836)
			(xy 96.900255 -289.086867) (xy 96.877522 -289.041337) (xy 96.862058 -288.992854) (xy 96.854231 -288.942571)
			(xy 96.853756 -288.917126) (xy 96.57334 -288.917126) (xy 96.572832 -288.943033) (xy 96.564726 -288.99421)
			(xy 96.548714 -289.043489) (xy 96.525191 -289.089656) (xy 96.494735 -289.131575) (xy 96.458097 -289.168213)
			(xy 96.416178 -289.198669) (xy 96.370011 -289.222192) (xy 96.320732 -289.238204) (xy 96.269555 -289.24631)
			(xy 96.217741 -289.24631) (xy 96.166564 -289.238204) (xy 96.117285 -289.222192) (xy 96.071118 -289.198669)
			(xy 96.029199 -289.168213) (xy 95.992561 -289.131575) (xy 95.962105 -289.089656) (xy 95.938582 -289.043489)
			(xy 95.92257 -288.99421) (xy 95.914464 -288.943033) (xy 95.913956 -288.917126) (xy 95.63354 -288.917126)
			(xy 95.633118 -288.940067) (xy 95.62669 -288.985498) (xy 95.614044 -289.029604) (xy 95.605092 -289.05073)
			(xy 95.595186 -289.073336) (xy 95.809054 -289.478466) (xy 95.833184 -289.483038) (xy 95.85811 -289.488115)
			(xy 95.906121 -289.50492) (xy 95.950979 -289.528904) (xy 95.991619 -289.559496) (xy 96.027076 -289.59597)
			(xy 96.056506 -289.637459) (xy 96.079212 -289.682977) (xy 96.094653 -289.731444) (xy 96.102463 -289.781708)
			(xy 96.102932 -289.807142) (xy 96.102424 -289.833029) (xy 96.094325 -289.884167) (xy 96.078326 -289.933407)
			(xy 96.05482 -289.979539) (xy 96.024388 -290.021426) (xy 95.987778 -290.058036) (xy 95.945891 -290.088468)
			(xy 95.899759 -290.111974) (xy 95.850519 -290.127973) (xy 95.799381 -290.136072) (xy 95.747607 -290.136072)
			(xy 95.696469 -290.127973) (xy 95.647229 -290.111974) (xy 95.601097 -290.088468) (xy 95.55921 -290.058036)
			(xy 95.5226 -290.021426) (xy 95.492168 -289.979539) (xy 95.468662 -289.933407) (xy 95.452663 -289.884167)
			(xy 95.444564 -289.833029) (xy 95.444056 -289.807142) (xy 95.444056 -289.806634) (xy 95.444459 -289.783785)
			(xy 95.450812 -289.738531) (xy 95.463358 -289.694589) (xy 95.47225 -289.673538) (xy 95.482156 -289.650932)
			(xy 95.268288 -289.245802) (xy 95.244158 -289.24123) (xy 95.219219 -289.236158) (xy 95.171176 -289.219379)
			(xy 95.126283 -289.195414) (xy 95.085607 -289.164832) (xy 95.050117 -289.12836) (xy 95.020655 -289.086867)
			(xy 94.997922 -289.041337) (xy 94.982458 -288.992854) (xy 94.974631 -288.942571) (xy 94.974156 -288.917126)
			(xy 94.69374 -288.917126) (xy 94.693232 -288.943033) (xy 94.685126 -288.99421) (xy 94.669114 -289.043489)
			(xy 94.645591 -289.089656) (xy 94.615135 -289.131575) (xy 94.578497 -289.168213) (xy 94.536578 -289.198669)
			(xy 94.490411 -289.222192) (xy 94.441132 -289.238204) (xy 94.389955 -289.24631) (xy 94.338141 -289.24631)
			(xy 94.286964 -289.238204) (xy 94.237685 -289.222192) (xy 94.191518 -289.198669) (xy 94.149599 -289.168213)
			(xy 94.112961 -289.131575) (xy 94.082505 -289.089656) (xy 94.058982 -289.043489) (xy 94.04297 -288.99421)
			(xy 94.034864 -288.943033) (xy 94.034356 -288.917126) (xy 93.75394 -288.917126) (xy 93.753518 -288.940067)
			(xy 93.74709 -288.985498) (xy 93.734444 -289.029604) (xy 93.725492 -289.05073) (xy 93.715586 -289.073336)
			(xy 93.929454 -289.478466) (xy 93.953584 -289.483038) (xy 93.97851 -289.488115) (xy 94.026521 -289.50492)
			(xy 94.071379 -289.528904) (xy 94.112019 -289.559496) (xy 94.147476 -289.59597) (xy 94.176906 -289.637459)
			(xy 94.199612 -289.682977) (xy 94.215053 -289.731444) (xy 94.222863 -289.781708) (xy 94.223332 -289.807142)
			(xy 94.222824 -289.833029) (xy 94.214725 -289.884167) (xy 94.198726 -289.933407) (xy 94.17522 -289.979539)
			(xy 94.144788 -290.021426) (xy 94.108178 -290.058036) (xy 94.066291 -290.088468) (xy 94.020159 -290.111974)
			(xy 93.970919 -290.127973) (xy 93.919781 -290.136072) (xy 93.868007 -290.136072) (xy 93.816869 -290.127973)
			(xy 93.767629 -290.111974) (xy 93.721497 -290.088468) (xy 93.67961 -290.058036) (xy 93.643 -290.021426)
			(xy 93.612568 -289.979539) (xy 93.589062 -289.933407) (xy 93.573063 -289.884167) (xy 93.564964 -289.833029)
			(xy 93.564456 -289.807142) (xy 93.564456 -289.806634) (xy 93.564859 -289.783785) (xy 93.571212 -289.738531)
			(xy 93.583758 -289.694589) (xy 93.59265 -289.673538) (xy 93.602556 -289.650932) (xy 93.388688 -289.245802)
			(xy 93.364558 -289.24123) (xy 93.339619 -289.236158) (xy 93.291576 -289.219379) (xy 93.246683 -289.195414)
			(xy 93.206007 -289.164832) (xy 93.170517 -289.12836) (xy 93.141055 -289.086867) (xy 93.118322 -289.041337)
			(xy 93.102858 -288.992854) (xy 93.095031 -288.942571) (xy 93.094556 -288.917126) (xy 92.81414 -288.917126)
			(xy 92.813632 -288.943033) (xy 92.805526 -288.99421) (xy 92.789514 -289.043489) (xy 92.765991 -289.089656)
			(xy 92.735535 -289.131575) (xy 92.698897 -289.168213) (xy 92.656978 -289.198669) (xy 92.610811 -289.222192)
			(xy 92.561532 -289.238204) (xy 92.510355 -289.24631) (xy 92.458541 -289.24631) (xy 92.407364 -289.238204)
			(xy 92.358085 -289.222192) (xy 92.311918 -289.198669) (xy 92.269999 -289.168213) (xy 92.233361 -289.131575)
			(xy 92.202905 -289.089656) (xy 92.179382 -289.043489) (xy 92.16337 -288.99421) (xy 92.155264 -288.943033)
			(xy 92.154756 -288.917126) (xy 91.87434 -288.917126) (xy 91.873918 -288.940067) (xy 91.86749 -288.985498)
			(xy 91.854844 -289.029604) (xy 91.845892 -289.05073) (xy 91.835986 -289.073336) (xy 92.049854 -289.478466)
			(xy 92.073984 -289.483038) (xy 92.09891 -289.488115) (xy 92.146921 -289.50492) (xy 92.191779 -289.528904)
			(xy 92.232419 -289.559496) (xy 92.267876 -289.59597) (xy 92.297306 -289.637459) (xy 92.320012 -289.682977)
			(xy 92.335453 -289.731444) (xy 92.343263 -289.781708) (xy 92.343732 -289.807142) (xy 92.343224 -289.833029)
			(xy 92.335125 -289.884167) (xy 92.319126 -289.933407) (xy 92.29562 -289.979539) (xy 92.265188 -290.021426)
			(xy 92.228578 -290.058036) (xy 92.186691 -290.088468) (xy 92.140559 -290.111974) (xy 92.091319 -290.127973)
			(xy 92.040181 -290.136072) (xy 91.988407 -290.136072) (xy 91.937269 -290.127973) (xy 91.888029 -290.111974)
			(xy 91.841897 -290.088468) (xy 91.80001 -290.058036) (xy 91.7634 -290.021426) (xy 91.732968 -289.979539)
			(xy 91.709462 -289.933407) (xy 91.693463 -289.884167) (xy 91.685364 -289.833029) (xy 91.684856 -289.807142)
			(xy 91.684856 -289.806634) (xy 91.685259 -289.783785) (xy 91.691612 -289.738531) (xy 91.704158 -289.694589)
			(xy 91.71305 -289.673538) (xy 91.722956 -289.650932) (xy 91.509088 -289.245802) (xy 91.484958 -289.24123)
			(xy 91.460019 -289.236158) (xy 91.411976 -289.219379) (xy 91.367083 -289.195414) (xy 91.326407 -289.164832)
			(xy 91.290917 -289.12836) (xy 91.261455 -289.086867) (xy 91.238722 -289.041337) (xy 91.223258 -288.992854)
			(xy 91.215431 -288.942571) (xy 91.214956 -288.917126) (xy 90.93454 -288.917126) (xy 90.934032 -288.943033)
			(xy 90.925926 -288.99421) (xy 90.909914 -289.043489) (xy 90.886391 -289.089656) (xy 90.855935 -289.131575)
			(xy 90.819297 -289.168213) (xy 90.777378 -289.198669) (xy 90.731211 -289.222192) (xy 90.681932 -289.238204)
			(xy 90.630755 -289.24631) (xy 90.578941 -289.24631) (xy 90.527764 -289.238204) (xy 90.478485 -289.222192)
			(xy 90.432318 -289.198669) (xy 90.390399 -289.168213) (xy 90.353761 -289.131575) (xy 90.323305 -289.089656)
			(xy 90.299782 -289.043489) (xy 90.28377 -288.99421) (xy 90.275664 -288.943033) (xy 90.275156 -288.917126)
			(xy 89.05494 -288.917126) (xy 89.054432 -288.943033) (xy 89.046326 -288.99421) (xy 89.030314 -289.043489)
			(xy 89.006791 -289.089656) (xy 88.976335 -289.131575) (xy 88.939697 -289.168213) (xy 88.897778 -289.198669)
			(xy 88.851611 -289.222192) (xy 88.802332 -289.238204) (xy 88.751155 -289.24631) (xy 88.699341 -289.24631)
			(xy 88.648164 -289.238204) (xy 88.598885 -289.222192) (xy 88.552718 -289.198669) (xy 88.510799 -289.168213)
			(xy 88.474161 -289.131575) (xy 88.443705 -289.089656) (xy 88.420182 -289.043489) (xy 88.40417 -288.99421)
			(xy 88.396064 -288.943033) (xy 88.395556 -288.917126) (xy 2.509012 -288.917126) (xy 2.509012 -297.515026)
			(xy 88.21548 -297.515026) (xy 88.219461 -297.382006) (xy 88.23139 -297.249461) (xy 88.251225 -297.117868)
			(xy 88.278894 -296.987696) (xy 88.314298 -296.859411) (xy 88.357311 -296.733474) (xy 88.407778 -296.610335)
			(xy 88.465519 -296.490434) (xy 88.530328 -296.374201) (xy 88.601972 -296.262051) (xy 88.680194 -296.154387)
			(xy 88.764715 -296.051594) (xy 88.855233 -295.954039) (xy 88.951422 -295.862073) (xy 89.05294 -295.776023)
			(xy 89.159421 -295.696199) (xy 89.270486 -295.622886) (xy 89.385737 -295.556346) (xy 89.504761 -295.496817)
			(xy 89.627132 -295.444513) (xy 89.752411 -295.399621) (xy 89.880152 -295.362302) (xy 90.009895 -295.332689)
			(xy 90.141177 -295.310888) (xy 90.273528 -295.296978) (xy 90.406474 -295.291007) (xy 90.539539 -295.292998)
			(xy 90.672247 -295.302943) (xy 90.804123 -295.320807) (xy 90.934694 -295.346525) (xy 91.063494 -295.380006)
			(xy 91.19006 -295.42113) (xy 91.313941 -295.46975) (xy 91.434692 -295.525691) (xy 91.551882 -295.588753)
			(xy 91.665091 -295.658711) (xy 91.773913 -295.735315) (xy 91.877959 -295.818289) (xy 91.976857 -295.907337)
			(xy 92.070252 -296.00214) (xy 92.15781 -296.102358) (xy 92.239219 -296.207634) (xy 92.314185 -296.31759)
			(xy 92.382442 -296.431832) (xy 92.443744 -296.549952) (xy 92.497873 -296.671527) (xy 92.544634 -296.796121)
			(xy 92.58386 -296.923289) (xy 92.61541 -297.052575) (xy 92.639173 -297.183516) (xy 92.655062 -297.315644)
			(xy 92.66302 -297.448486) (xy 92.663518 -297.515026) (xy 131.195582 -297.515026) (xy 131.199563 -297.382006)
			(xy 131.211492 -297.249461) (xy 131.231327 -297.117868) (xy 131.258996 -296.987696) (xy 131.2944 -296.859411)
			(xy 131.337413 -296.733474) (xy 131.38788 -296.610335) (xy 131.445621 -296.490434) (xy 131.51043 -296.374201)
			(xy 131.582074 -296.262051) (xy 131.660296 -296.154387) (xy 131.744817 -296.051594) (xy 131.835335 -295.954039)
			(xy 131.931524 -295.862073) (xy 132.033042 -295.776023) (xy 132.139523 -295.696199) (xy 132.250588 -295.622886)
			(xy 132.365839 -295.556346) (xy 132.484863 -295.496817) (xy 132.607234 -295.444513) (xy 132.732513 -295.399621)
			(xy 132.860254 -295.362302) (xy 132.989997 -295.332689) (xy 133.121279 -295.310888) (xy 133.25363 -295.296978)
			(xy 133.386576 -295.291007) (xy 133.519641 -295.292998) (xy 133.652349 -295.302943) (xy 133.784225 -295.320807)
			(xy 133.914796 -295.346525) (xy 134.043596 -295.380006) (xy 134.170162 -295.42113) (xy 134.294043 -295.46975)
			(xy 134.414794 -295.525691) (xy 134.531984 -295.588753) (xy 134.645193 -295.658711) (xy 134.754015 -295.735315)
			(xy 134.858061 -295.818289) (xy 134.956959 -295.907337) (xy 135.050354 -296.00214) (xy 135.137912 -296.102358)
			(xy 135.219321 -296.207634) (xy 135.294287 -296.31759) (xy 135.362544 -296.431832) (xy 135.423846 -296.549952)
			(xy 135.477975 -296.671527) (xy 135.524736 -296.796121) (xy 135.563962 -296.923289) (xy 135.595512 -297.052575)
			(xy 135.619275 -297.183516) (xy 135.635164 -297.315644) (xy 135.643122 -297.448486) (xy 135.64362 -297.515026)
			(xy 336.155548 -297.515026) (xy 336.159529 -297.382006) (xy 336.171458 -297.249461) (xy 336.191293 -297.117868)
			(xy 336.218962 -296.987696) (xy 336.254366 -296.859411) (xy 336.297379 -296.733474) (xy 336.347846 -296.610335)
			(xy 336.405587 -296.490434) (xy 336.470396 -296.374201) (xy 336.54204 -296.262051) (xy 336.620262 -296.154387)
			(xy 336.704783 -296.051594) (xy 336.795301 -295.954039) (xy 336.89149 -295.862073) (xy 336.993008 -295.776023)
			(xy 337.099489 -295.696199) (xy 337.210554 -295.622886) (xy 337.325805 -295.556346) (xy 337.444829 -295.496817)
			(xy 337.5672 -295.444513) (xy 337.692479 -295.399621) (xy 337.82022 -295.362302) (xy 337.949963 -295.332689)
			(xy 338.081245 -295.310888) (xy 338.213596 -295.296978) (xy 338.346542 -295.291007) (xy 338.479607 -295.292998)
			(xy 338.612315 -295.302943) (xy 338.744191 -295.320807) (xy 338.874762 -295.346525) (xy 339.003562 -295.380006)
			(xy 339.130128 -295.42113) (xy 339.254009 -295.46975) (xy 339.37476 -295.525691) (xy 339.49195 -295.588753)
			(xy 339.605159 -295.658711) (xy 339.713981 -295.735315) (xy 339.818027 -295.818289) (xy 339.916925 -295.907337)
			(xy 340.01032 -296.00214) (xy 340.097878 -296.102358) (xy 340.179287 -296.207634) (xy 340.254253 -296.31759)
			(xy 340.32251 -296.431832) (xy 340.383812 -296.549952) (xy 340.437941 -296.671527) (xy 340.484702 -296.796121)
			(xy 340.523928 -296.923289) (xy 340.555478 -297.052575) (xy 340.579241 -297.183516) (xy 340.59513 -297.315644)
			(xy 340.603088 -297.448486) (xy 340.603586 -297.515026) (xy 379.13565 -297.515026) (xy 379.139631 -297.382006)
			(xy 379.15156 -297.249461) (xy 379.171395 -297.117868) (xy 379.199064 -296.987696) (xy 379.234468 -296.859411)
			(xy 379.277481 -296.733474) (xy 379.327948 -296.610335) (xy 379.385689 -296.490434) (xy 379.450498 -296.374201)
			(xy 379.522142 -296.262051) (xy 379.600364 -296.154387) (xy 379.684885 -296.051594) (xy 379.775403 -295.954039)
			(xy 379.871592 -295.862073) (xy 379.97311 -295.776023) (xy 380.079591 -295.696199) (xy 380.190656 -295.622886)
			(xy 380.305907 -295.556346) (xy 380.424931 -295.496817) (xy 380.547302 -295.444513) (xy 380.672581 -295.399621)
			(xy 380.800322 -295.362302) (xy 380.930065 -295.332689) (xy 381.061347 -295.310888) (xy 381.193698 -295.296978)
			(xy 381.326644 -295.291007) (xy 381.459709 -295.292998) (xy 381.592417 -295.302943) (xy 381.724293 -295.320807)
			(xy 381.854864 -295.346525) (xy 381.983664 -295.380006) (xy 382.11023 -295.42113) (xy 382.234111 -295.46975)
			(xy 382.354862 -295.525691) (xy 382.472052 -295.588753) (xy 382.585261 -295.658711) (xy 382.694083 -295.735315)
			(xy 382.798129 -295.818289) (xy 382.897027 -295.907337) (xy 382.990422 -296.00214) (xy 383.07798 -296.102358)
			(xy 383.159389 -296.207634) (xy 383.234355 -296.31759) (xy 383.302612 -296.431832) (xy 383.363914 -296.549952)
			(xy 383.418043 -296.671527) (xy 383.464804 -296.796121) (xy 383.50403 -296.923289) (xy 383.53558 -297.052575)
			(xy 383.559343 -297.183516) (xy 383.575232 -297.315644) (xy 383.58319 -297.448486) (xy 383.583688 -297.515026)
			(xy 383.58319 -297.581566) (xy 383.575232 -297.714408) (xy 383.559343 -297.846536) (xy 383.53558 -297.977477)
			(xy 383.50403 -298.106763) (xy 383.464804 -298.233931) (xy 383.418043 -298.358525) (xy 383.363914 -298.4801)
			(xy 383.302612 -298.59822) (xy 383.234355 -298.712462) (xy 383.159389 -298.822418) (xy 383.07798 -298.927694)
			(xy 382.990422 -299.027912) (xy 382.897027 -299.122715) (xy 382.798129 -299.211763) (xy 382.694083 -299.294737)
			(xy 382.585261 -299.371341) (xy 382.472052 -299.441299) (xy 382.354862 -299.504361) (xy 382.234111 -299.560302)
			(xy 382.11023 -299.608922) (xy 381.983664 -299.650046) (xy 381.854864 -299.683527) (xy 381.724293 -299.709245)
			(xy 381.592417 -299.727109) (xy 381.459709 -299.737054) (xy 381.326644 -299.739045) (xy 381.193698 -299.733074)
			(xy 381.061347 -299.719164) (xy 380.930065 -299.697363) (xy 380.800322 -299.66775) (xy 380.672581 -299.630431)
			(xy 380.547302 -299.585539) (xy 380.424931 -299.533235) (xy 380.305907 -299.473706) (xy 380.190656 -299.407166)
			(xy 380.079591 -299.333853) (xy 379.97311 -299.254029) (xy 379.871592 -299.167979) (xy 379.775403 -299.076013)
			(xy 379.684885 -298.978458) (xy 379.600364 -298.875665) (xy 379.522142 -298.768001) (xy 379.450498 -298.655851)
			(xy 379.385689 -298.539618) (xy 379.327948 -298.419717) (xy 379.277481 -298.296578) (xy 379.234468 -298.170641)
			(xy 379.199064 -298.042356) (xy 379.171395 -297.912184) (xy 379.15156 -297.780591) (xy 379.139631 -297.648046)
			(xy 379.13565 -297.515026) (xy 340.603586 -297.515026) (xy 340.603088 -297.581566) (xy 340.59513 -297.714408)
			(xy 340.579241 -297.846536) (xy 340.555478 -297.977477) (xy 340.523928 -298.106763) (xy 340.484702 -298.233931)
			(xy 340.437941 -298.358525) (xy 340.383812 -298.4801) (xy 340.32251 -298.59822) (xy 340.254253 -298.712462)
			(xy 340.179287 -298.822418) (xy 340.097878 -298.927694) (xy 340.01032 -299.027912) (xy 339.916925 -299.122715)
			(xy 339.818027 -299.211763) (xy 339.713981 -299.294737) (xy 339.605159 -299.371341) (xy 339.49195 -299.441299)
			(xy 339.37476 -299.504361) (xy 339.254009 -299.560302) (xy 339.130128 -299.608922) (xy 339.003562 -299.650046)
			(xy 338.874762 -299.683527) (xy 338.744191 -299.709245) (xy 338.612315 -299.727109) (xy 338.479607 -299.737054)
			(xy 338.346542 -299.739045) (xy 338.213596 -299.733074) (xy 338.081245 -299.719164) (xy 337.949963 -299.697363)
			(xy 337.82022 -299.66775) (xy 337.692479 -299.630431) (xy 337.5672 -299.585539) (xy 337.444829 -299.533235)
			(xy 337.325805 -299.473706) (xy 337.210554 -299.407166) (xy 337.099489 -299.333853) (xy 336.993008 -299.254029)
			(xy 336.89149 -299.167979) (xy 336.795301 -299.076013) (xy 336.704783 -298.978458) (xy 336.620262 -298.875665)
			(xy 336.54204 -298.768001) (xy 336.470396 -298.655851) (xy 336.405587 -298.539618) (xy 336.347846 -298.419717)
			(xy 336.297379 -298.296578) (xy 336.254366 -298.170641) (xy 336.218962 -298.042356) (xy 336.191293 -297.912184)
			(xy 336.171458 -297.780591) (xy 336.159529 -297.648046) (xy 336.155548 -297.515026) (xy 135.64362 -297.515026)
			(xy 135.643122 -297.581566) (xy 135.635164 -297.714408) (xy 135.619275 -297.846536) (xy 135.595512 -297.977477)
			(xy 135.563962 -298.106763) (xy 135.524736 -298.233931) (xy 135.477975 -298.358525) (xy 135.423846 -298.4801)
			(xy 135.362544 -298.59822) (xy 135.294287 -298.712462) (xy 135.219321 -298.822418) (xy 135.137912 -298.927694)
			(xy 135.050354 -299.027912) (xy 134.956959 -299.122715) (xy 134.858061 -299.211763) (xy 134.754015 -299.294737)
			(xy 134.645193 -299.371341) (xy 134.531984 -299.441299) (xy 134.414794 -299.504361) (xy 134.294043 -299.560302)
			(xy 134.170162 -299.608922) (xy 134.043596 -299.650046) (xy 133.914796 -299.683527) (xy 133.784225 -299.709245)
			(xy 133.652349 -299.727109) (xy 133.519641 -299.737054) (xy 133.386576 -299.739045) (xy 133.25363 -299.733074)
			(xy 133.121279 -299.719164) (xy 132.989997 -299.697363) (xy 132.860254 -299.66775) (xy 132.732513 -299.630431)
			(xy 132.607234 -299.585539) (xy 132.484863 -299.533235) (xy 132.365839 -299.473706) (xy 132.250588 -299.407166)
			(xy 132.139523 -299.333853) (xy 132.033042 -299.254029) (xy 131.931524 -299.167979) (xy 131.835335 -299.076013)
			(xy 131.744817 -298.978458) (xy 131.660296 -298.875665) (xy 131.582074 -298.768001) (xy 131.51043 -298.655851)
			(xy 131.445621 -298.539618) (xy 131.38788 -298.419717) (xy 131.337413 -298.296578) (xy 131.2944 -298.170641)
			(xy 131.258996 -298.042356) (xy 131.231327 -297.912184) (xy 131.211492 -297.780591) (xy 131.199563 -297.648046)
			(xy 131.195582 -297.515026) (xy 92.663518 -297.515026) (xy 92.66302 -297.581566) (xy 92.655062 -297.714408)
			(xy 92.639173 -297.846536) (xy 92.61541 -297.977477) (xy 92.58386 -298.106763) (xy 92.544634 -298.233931)
			(xy 92.497873 -298.358525) (xy 92.443744 -298.4801) (xy 92.382442 -298.59822) (xy 92.314185 -298.712462)
			(xy 92.239219 -298.822418) (xy 92.15781 -298.927694) (xy 92.070252 -299.027912) (xy 91.976857 -299.122715)
			(xy 91.877959 -299.211763) (xy 91.773913 -299.294737) (xy 91.665091 -299.371341) (xy 91.551882 -299.441299)
			(xy 91.434692 -299.504361) (xy 91.313941 -299.560302) (xy 91.19006 -299.608922) (xy 91.063494 -299.650046)
			(xy 90.934694 -299.683527) (xy 90.804123 -299.709245) (xy 90.672247 -299.727109) (xy 90.539539 -299.737054)
			(xy 90.406474 -299.739045) (xy 90.273528 -299.733074) (xy 90.141177 -299.719164) (xy 90.009895 -299.697363)
			(xy 89.880152 -299.66775) (xy 89.752411 -299.630431) (xy 89.627132 -299.585539) (xy 89.504761 -299.533235)
			(xy 89.385737 -299.473706) (xy 89.270486 -299.407166) (xy 89.159421 -299.333853) (xy 89.05294 -299.254029)
			(xy 88.951422 -299.167979) (xy 88.855233 -299.076013) (xy 88.764715 -298.978458) (xy 88.680194 -298.875665)
			(xy 88.601972 -298.768001) (xy 88.530328 -298.655851) (xy 88.465519 -298.539618) (xy 88.407778 -298.419717)
			(xy 88.357311 -298.296578) (xy 88.314298 -298.170641) (xy 88.278894 -298.042356) (xy 88.251225 -297.912184)
			(xy 88.23139 -297.780591) (xy 88.219461 -297.648046) (xy 88.21548 -297.515026) (xy 2.509012 -297.515026)
			(xy 2.509012 -360.76382) (xy 4.226823 -360.76382) (xy 4.230819 -360.553934) (xy 4.242804 -360.344352)
			(xy 4.262758 -360.135378) (xy 4.290654 -359.927316) (xy 4.326451 -359.720466) (xy 4.370096 -359.515129)
			(xy 4.421528 -359.311603) (xy 4.48067 -359.110182) (xy 4.547438 -358.911159) (xy 4.621734 -358.714822)
			(xy 4.703452 -358.521456) (xy 4.792471 -358.331341) (xy 4.888664 -358.144753) (xy 4.991891 -357.961962)
			(xy 5.102002 -357.783234) (xy 5.218837 -357.608827) (xy 5.342227 -357.438995) (xy 5.471994 -357.273983)
			(xy 5.607948 -357.114032) (xy 5.749894 -356.959372) (xy 5.897624 -356.810228) (xy 6.050926 -356.666817)
			(xy 6.209576 -356.529346) (xy 6.373345 -356.398014) (xy 6.541995 -356.273013) (xy 6.715281 -356.154522)
			(xy 6.892953 -356.042715) (xy 7.074753 -355.937753) (xy 7.260417 -355.839788) (xy 7.449675 -355.748963)
			(xy 7.642255 -355.665409) (xy 7.837876 -355.589246) (xy 8.036254 -355.520587) (xy 8.237103 -355.45953)
			(xy 8.44013 -355.406163) (xy 8.645043 -355.360565) (xy 8.851542 -355.3228) (xy 9.059329 -355.292925)
			(xy 9.268104 -355.270982) (xy 9.477562 -355.257003) (xy 9.687401 -355.251008) (xy 9.897315 -355.253007)
			(xy 10.107002 -355.262995) (xy 10.316156 -355.28096) (xy 10.524474 -355.306874) (xy 10.731655 -355.340699)
			(xy 10.937399 -355.382388) (xy 11.141405 -355.43188) (xy 11.34338 -355.489102) (xy 11.54303 -355.553972)
			(xy 11.740065 -355.626396) (xy 11.934201 -355.706269) (xy 12.125154 -355.793475) (xy 12.31265 -355.887887)
			(xy 12.496415 -355.989369) (xy 12.676183 -356.097773) (xy 12.851694 -356.212943) (xy 13.022693 -356.334711)
			(xy 13.188933 -356.4629) (xy 13.350172 -356.597326) (xy 13.506176 -356.737793) (xy 13.656719 -356.884097)
			(xy 13.801583 -357.036026) (xy 13.940558 -357.19336) (xy 14.073443 -357.355871) (xy 14.200044 -357.523324)
			(xy 14.320179 -357.695474) (xy 14.433673 -357.872074) (xy 14.540361 -358.052866) (xy 14.640088 -358.237589)
			(xy 14.732711 -358.425975) (xy 14.818095 -358.61775) (xy 14.896116 -358.812637) (xy 14.966661 -359.010353)
			(xy 15.029628 -359.210611) (xy 15.084925 -359.413121) (xy 15.132472 -359.61759) (xy 15.1722 -359.823721)
			(xy 15.204052 -360.031214) (xy 15.227982 -360.23977) (xy 15.243954 -360.449086) (xy 15.251946 -360.658858)
			(xy 15.252446 -360.76382) (xy 15.251946 -360.868782) (xy 15.243954 -361.078554) (xy 15.239789 -361.133136)
			(xy 121.446286 -361.133136) (xy 121.450375 -361.077254) (xy 121.462558 -361.022564) (xy 121.482574 -360.97023)
			(xy 121.509997 -360.921368) (xy 121.544242 -360.87702) (xy 121.584578 -360.83813) (xy 121.630148 -360.805528)
			(xy 121.679979 -360.779909) (xy 121.733009 -360.761817) (xy 121.788107 -360.75164) (xy 121.844101 -360.749594)
			(xy 121.899796 -360.755722) (xy 121.930771 -360.76382) (xy 211.161635 -360.76382) (xy 211.16566 -360.621628)
			(xy 211.177723 -360.479892) (xy 211.197786 -360.339066) (xy 211.225784 -360.1996) (xy 211.261628 -360.061941)
			(xy 211.305202 -359.926531) (xy 211.356367 -359.793803) (xy 211.41496 -359.664182) (xy 211.480791 -359.538084)
			(xy 211.553652 -359.415912) (xy 211.633307 -359.298058) (xy 211.719503 -359.184899) (xy 211.811962 -359.076797)
			(xy 211.91039 -358.9741) (xy 212.014469 -358.877136) (xy 212.123868 -358.786216) (xy 212.238236 -358.70163)
			(xy 212.357205 -358.62365) (xy 212.480396 -358.552526) (xy 212.607413 -358.488485) (xy 212.73785 -358.431733)
			(xy 212.871289 -358.382451) (xy 213.007302 -358.340797) (xy 213.145454 -358.306905) (xy 213.285303 -358.280884)
			(xy 213.426399 -358.262816) (xy 213.568291 -358.252759) (xy 213.710526 -358.250746) (xy 213.852646 -358.256783)
			(xy 213.994197 -358.270851) (xy 214.134726 -358.292905) (xy 214.273781 -358.322874) (xy 214.410919 -358.360662)
			(xy 214.545699 -358.406148) (xy 214.67769 -358.459186) (xy 214.806469 -358.519607) (xy 214.931623 -358.587216)
			(xy 215.052751 -358.661798) (xy 215.169467 -358.743114) (xy 215.281395 -358.830902) (xy 215.388177 -358.924882)
			(xy 215.489471 -359.024752) (xy 215.584952 -359.130194) (xy 215.674316 -359.240868) (xy 215.757274 -359.356421)
			(xy 215.833563 -359.476482) (xy 215.902937 -359.600667) (xy 215.965174 -359.728578) (xy 216.020075 -359.859805)
			(xy 216.067463 -359.993928) (xy 216.107188 -360.130517) (xy 216.139121 -360.269135) (xy 216.163162 -360.409337)
			(xy 216.179231 -360.550675) (xy 216.187279 -360.692696) (xy 216.187782 -360.76382) (xy 255.611635 -360.76382)
			(xy 255.61566 -360.621628) (xy 255.627723 -360.479892) (xy 255.647786 -360.339066) (xy 255.675784 -360.1996)
			(xy 255.711628 -360.061941) (xy 255.755202 -359.926531) (xy 255.806367 -359.793803) (xy 255.86496 -359.664182)
			(xy 255.930791 -359.538084) (xy 256.003652 -359.415912) (xy 256.083307 -359.298058) (xy 256.169503 -359.184899)
			(xy 256.261962 -359.076797) (xy 256.36039 -358.9741) (xy 256.464469 -358.877136) (xy 256.573868 -358.786216)
			(xy 256.688236 -358.70163) (xy 256.807205 -358.62365) (xy 256.930396 -358.552526) (xy 257.057413 -358.488485)
			(xy 257.18785 -358.431733) (xy 257.321289 -358.382451) (xy 257.457302 -358.340797) (xy 257.595454 -358.306905)
			(xy 257.735303 -358.280884) (xy 257.876399 -358.262816) (xy 258.018291 -358.252759) (xy 258.160526 -358.250746)
			(xy 258.302646 -358.256783) (xy 258.444197 -358.270851) (xy 258.584726 -358.292905) (xy 258.723781 -358.322874)
			(xy 258.860919 -358.360662) (xy 258.995699 -358.406148) (xy 259.12769 -358.459186) (xy 259.256469 -358.519607)
			(xy 259.381623 -358.587216) (xy 259.502751 -358.661798) (xy 259.619467 -358.743114) (xy 259.731395 -358.830902)
			(xy 259.838177 -358.924882) (xy 259.939471 -359.024752) (xy 260.034952 -359.130194) (xy 260.124316 -359.240868)
			(xy 260.207274 -359.356421) (xy 260.283563 -359.476482) (xy 260.352937 -359.600667) (xy 260.415174 -359.728578)
			(xy 260.470075 -359.859805) (xy 260.517463 -359.993928) (xy 260.557188 -360.130517) (xy 260.589121 -360.269135)
			(xy 260.613162 -360.409337) (xy 260.629231 -360.550675) (xy 260.637279 -360.692696) (xy 260.637782 -360.76382)
			(xy 260.637279 -360.834944) (xy 260.629231 -360.976965) (xy 260.613162 -361.118303) (xy 260.610619 -361.133136)
			(xy 369.3861 -361.133136) (xy 369.390189 -361.077254) (xy 369.402372 -361.022564) (xy 369.422388 -360.97023)
			(xy 369.449811 -360.921368) (xy 369.484056 -360.87702) (xy 369.524392 -360.83813) (xy 369.569962 -360.805528)
			(xy 369.619793 -360.779909) (xy 369.672823 -360.761817) (xy 369.727921 -360.75164) (xy 369.783915 -360.749594)
			(xy 369.83961 -360.755722) (xy 369.870585 -360.76382) (xy 456.565771 -360.76382) (xy 456.569767 -360.553934)
			(xy 456.581752 -360.344352) (xy 456.601706 -360.135378) (xy 456.629602 -359.927316) (xy 456.665399 -359.720466)
			(xy 456.709044 -359.515129) (xy 456.760476 -359.311603) (xy 456.819618 -359.110182) (xy 456.886386 -358.911159)
			(xy 456.960682 -358.714822) (xy 457.0424 -358.521456) (xy 457.131419 -358.331341) (xy 457.227612 -358.144753)
			(xy 457.330839 -357.961962) (xy 457.44095 -357.783234) (xy 457.557785 -357.608827) (xy 457.681175 -357.438995)
			(xy 457.810942 -357.273983) (xy 457.946896 -357.114032) (xy 458.088842 -356.959372) (xy 458.236572 -356.810228)
			(xy 458.389874 -356.666817) (xy 458.548524 -356.529346) (xy 458.712293 -356.398014) (xy 458.880943 -356.273013)
			(xy 459.054229 -356.154522) (xy 459.231901 -356.042715) (xy 459.413701 -355.937753) (xy 459.599365 -355.839788)
			(xy 459.788623 -355.748963) (xy 459.981203 -355.665409) (xy 460.176824 -355.589246) (xy 460.375202 -355.520587)
			(xy 460.576051 -355.45953) (xy 460.779078 -355.406163) (xy 460.983991 -355.360565) (xy 461.19049 -355.3228)
			(xy 461.398277 -355.292925) (xy 461.607052 -355.270982) (xy 461.81651 -355.257003) (xy 462.026349 -355.251008)
			(xy 462.236263 -355.253007) (xy 462.44595 -355.262995) (xy 462.655104 -355.28096) (xy 462.863422 -355.306874)
			(xy 463.070603 -355.340699) (xy 463.276347 -355.382388) (xy 463.480353 -355.43188) (xy 463.682328 -355.489102)
			(xy 463.881978 -355.553972) (xy 464.079013 -355.626396) (xy 464.273149 -355.706269) (xy 464.464102 -355.793475)
			(xy 464.651598 -355.887887) (xy 464.835363 -355.989369) (xy 465.015131 -356.097773) (xy 465.190642 -356.212943)
			(xy 465.361641 -356.334711) (xy 465.527881 -356.4629) (xy 465.68912 -356.597326) (xy 465.845124 -356.737793)
			(xy 465.995667 -356.884097) (xy 466.140531 -357.036026) (xy 466.279506 -357.19336) (xy 466.412391 -357.355871)
			(xy 466.538992 -357.523324) (xy 466.659127 -357.695474) (xy 466.772621 -357.872074) (xy 466.879309 -358.052866)
			(xy 466.979036 -358.237589) (xy 467.071659 -358.425975) (xy 467.157043 -358.61775) (xy 467.235064 -358.812637)
			(xy 467.305609 -359.010353) (xy 467.368576 -359.210611) (xy 467.423873 -359.413121) (xy 467.47142 -359.61759)
			(xy 467.511148 -359.823721) (xy 467.543 -360.031214) (xy 467.56693 -360.23977) (xy 467.582902 -360.449086)
			(xy 467.590894 -360.658858) (xy 467.591394 -360.76382) (xy 467.590894 -360.868782) (xy 467.582902 -361.078554)
			(xy 467.56693 -361.28787) (xy 467.543 -361.496426) (xy 467.511148 -361.703919) (xy 467.47142 -361.91005)
			(xy 467.423873 -362.114519) (xy 467.368576 -362.317029) (xy 467.305609 -362.517287) (xy 467.235064 -362.715003)
			(xy 467.157043 -362.90989) (xy 467.071659 -363.101665) (xy 466.979036 -363.290051) (xy 466.879309 -363.474774)
			(xy 466.772621 -363.655566) (xy 466.659127 -363.832166) (xy 466.538992 -364.004316) (xy 466.412391 -364.171769)
			(xy 466.279506 -364.33428) (xy 466.140531 -364.491614) (xy 465.995667 -364.643543) (xy 465.845124 -364.789847)
			(xy 465.68912 -364.930314) (xy 465.527881 -365.06474) (xy 465.361641 -365.192929) (xy 465.190642 -365.314697)
			(xy 465.015131 -365.429867) (xy 464.835363 -365.538271) (xy 464.651598 -365.639753) (xy 464.464102 -365.734165)
			(xy 464.273149 -365.821371) (xy 464.079013 -365.901244) (xy 463.881978 -365.973668) (xy 463.682328 -366.038538)
			(xy 463.480353 -366.09576) (xy 463.276347 -366.145252) (xy 463.070603 -366.186941) (xy 462.863422 -366.220766)
			(xy 462.655104 -366.24668) (xy 462.44595 -366.264645) (xy 462.236263 -366.274633) (xy 462.026349 -366.276632)
			(xy 461.81651 -366.270637) (xy 461.607052 -366.256658) (xy 461.398277 -366.234715) (xy 461.19049 -366.20484)
			(xy 460.983991 -366.167075) (xy 460.779078 -366.121477) (xy 460.576051 -366.06811) (xy 460.375202 -366.007053)
			(xy 460.176824 -365.938394) (xy 459.981203 -365.862231) (xy 459.788623 -365.778677) (xy 459.599365 -365.687852)
			(xy 459.413701 -365.589887) (xy 459.231901 -365.484925) (xy 459.054229 -365.373118) (xy 458.880943 -365.254627)
			(xy 458.712293 -365.129626) (xy 458.548524 -364.998294) (xy 458.389874 -364.860823) (xy 458.236572 -364.717412)
			(xy 458.088842 -364.568268) (xy 457.946896 -364.413608) (xy 457.810942 -364.253657) (xy 457.681175 -364.088645)
			(xy 457.557785 -363.918813) (xy 457.44095 -363.744406) (xy 457.330839 -363.565678) (xy 457.227612 -363.382887)
			(xy 457.131419 -363.196299) (xy 457.0424 -363.006184) (xy 456.960682 -362.812818) (xy 456.886386 -362.616481)
			(xy 456.819618 -362.417458) (xy 456.760476 -362.216037) (xy 456.709044 -362.012511) (xy 456.665399 -361.807174)
			(xy 456.629602 -361.600324) (xy 456.601706 -361.392262) (xy 456.581752 -361.183288) (xy 456.569767 -360.973706)
			(xy 456.565771 -360.76382) (xy 369.870585 -360.76382) (xy 369.893819 -360.769894) (xy 369.945387 -360.791808)
			(xy 369.993215 -360.820997) (xy 370.036283 -360.856838) (xy 370.073673 -360.898568) (xy 370.104589 -360.945298)
			(xy 370.128372 -360.996031) (xy 370.144514 -361.049687) (xy 370.152673 -361.105121) (xy 370.153184 -361.133136)
			(xy 370.152673 -361.161151) (xy 370.144514 -361.216585) (xy 370.128372 -361.270241) (xy 370.104589 -361.320974)
			(xy 370.073673 -361.367704) (xy 370.036283 -361.409434) (xy 369.993215 -361.445275) (xy 369.945387 -361.474464)
			(xy 369.893819 -361.496378) (xy 369.83961 -361.51055) (xy 369.783915 -361.516678) (xy 369.727921 -361.514632)
			(xy 369.672823 -361.504455) (xy 369.619793 -361.486363) (xy 369.569962 -361.460744) (xy 369.524392 -361.428142)
			(xy 369.484056 -361.389252) (xy 369.449811 -361.344904) (xy 369.422388 -361.296042) (xy 369.402372 -361.243708)
			(xy 369.390189 -361.189018) (xy 369.3861 -361.133136) (xy 260.610619 -361.133136) (xy 260.589121 -361.258505)
			(xy 260.557188 -361.397123) (xy 260.517463 -361.533712) (xy 260.470075 -361.667835) (xy 260.415174 -361.799062)
			(xy 260.352937 -361.926973) (xy 260.283563 -362.051158) (xy 260.207274 -362.171219) (xy 260.124316 -362.286772)
			(xy 260.034952 -362.397446) (xy 259.939471 -362.502888) (xy 259.838177 -362.602758) (xy 259.731395 -362.696738)
			(xy 259.619467 -362.784526) (xy 259.502751 -362.865842) (xy 259.381623 -362.940424) (xy 259.256469 -363.008033)
			(xy 259.12769 -363.068454) (xy 258.995699 -363.121492) (xy 258.860919 -363.166978) (xy 258.723781 -363.204766)
			(xy 258.584726 -363.234735) (xy 258.444197 -363.256789) (xy 258.302646 -363.270857) (xy 258.160526 -363.276894)
			(xy 258.018291 -363.274881) (xy 257.876399 -363.264824) (xy 257.735303 -363.246756) (xy 257.595454 -363.220735)
			(xy 257.457302 -363.186843) (xy 257.321289 -363.145189) (xy 257.18785 -363.095907) (xy 257.057413 -363.039155)
			(xy 256.930396 -362.975114) (xy 256.807205 -362.90399) (xy 256.688236 -362.82601) (xy 256.573868 -362.741424)
			(xy 256.464469 -362.650504) (xy 256.36039 -362.55354) (xy 256.261962 -362.450843) (xy 256.169503 -362.342741)
			(xy 256.083307 -362.229582) (xy 256.003652 -362.111728) (xy 255.930791 -361.989556) (xy 255.86496 -361.863458)
			(xy 255.806367 -361.733837) (xy 255.755202 -361.601109) (xy 255.711628 -361.465699) (xy 255.675784 -361.32804)
			(xy 255.647786 -361.188574) (xy 255.627723 -361.047748) (xy 255.61566 -360.906012) (xy 255.611635 -360.76382)
			(xy 216.187782 -360.76382) (xy 216.187279 -360.834944) (xy 216.179231 -360.976965) (xy 216.163162 -361.118303)
			(xy 216.139121 -361.258505) (xy 216.107188 -361.397123) (xy 216.067463 -361.533712) (xy 216.020075 -361.667835)
			(xy 215.965174 -361.799062) (xy 215.902937 -361.926973) (xy 215.833563 -362.051158) (xy 215.757274 -362.171219)
			(xy 215.674316 -362.286772) (xy 215.584952 -362.397446) (xy 215.489471 -362.502888) (xy 215.388177 -362.602758)
			(xy 215.281395 -362.696738) (xy 215.169467 -362.784526) (xy 215.052751 -362.865842) (xy 214.931623 -362.940424)
			(xy 214.806469 -363.008033) (xy 214.67769 -363.068454) (xy 214.545699 -363.121492) (xy 214.410919 -363.166978)
			(xy 214.273781 -363.204766) (xy 214.134726 -363.234735) (xy 213.994197 -363.256789) (xy 213.852646 -363.270857)
			(xy 213.710526 -363.276894) (xy 213.568291 -363.274881) (xy 213.426399 -363.264824) (xy 213.285303 -363.246756)
			(xy 213.145454 -363.220735) (xy 213.007302 -363.186843) (xy 212.871289 -363.145189) (xy 212.73785 -363.095907)
			(xy 212.607413 -363.039155) (xy 212.480396 -362.975114) (xy 212.357205 -362.90399) (xy 212.238236 -362.82601)
			(xy 212.123868 -362.741424) (xy 212.014469 -362.650504) (xy 211.91039 -362.55354) (xy 211.811962 -362.450843)
			(xy 211.719503 -362.342741) (xy 211.633307 -362.229582) (xy 211.553652 -362.111728) (xy 211.480791 -361.989556)
			(xy 211.41496 -361.863458) (xy 211.356367 -361.733837) (xy 211.305202 -361.601109) (xy 211.261628 -361.465699)
			(xy 211.225784 -361.32804) (xy 211.197786 -361.188574) (xy 211.177723 -361.047748) (xy 211.16566 -360.906012)
			(xy 211.161635 -360.76382) (xy 121.930771 -360.76382) (xy 121.954005 -360.769894) (xy 122.005573 -360.791808)
			(xy 122.053401 -360.820997) (xy 122.096469 -360.856838) (xy 122.133859 -360.898568) (xy 122.164775 -360.945298)
			(xy 122.188558 -360.996031) (xy 122.2047 -361.049687) (xy 122.212859 -361.105121) (xy 122.21337 -361.133136)
			(xy 122.212859 -361.161151) (xy 122.2047 -361.216585) (xy 122.188558 -361.270241) (xy 122.164775 -361.320974)
			(xy 122.133859 -361.367704) (xy 122.096469 -361.409434) (xy 122.053401 -361.445275) (xy 122.005573 -361.474464)
			(xy 121.954005 -361.496378) (xy 121.899796 -361.51055) (xy 121.844101 -361.516678) (xy 121.788107 -361.514632)
			(xy 121.733009 -361.504455) (xy 121.679979 -361.486363) (xy 121.630148 -361.460744) (xy 121.584578 -361.428142)
			(xy 121.544242 -361.389252) (xy 121.509997 -361.344904) (xy 121.482574 -361.296042) (xy 121.462558 -361.243708)
			(xy 121.450375 -361.189018) (xy 121.446286 -361.133136) (xy 15.239789 -361.133136) (xy 15.227982 -361.28787)
			(xy 15.204052 -361.496426) (xy 15.1722 -361.703919) (xy 15.132472 -361.91005) (xy 15.084925 -362.114519)
			(xy 15.029628 -362.317029) (xy 14.966661 -362.517287) (xy 14.896116 -362.715003) (xy 14.818095 -362.90989)
			(xy 14.732711 -363.101665) (xy 14.640088 -363.290051) (xy 14.540361 -363.474774) (xy 14.433673 -363.655566)
			(xy 14.320179 -363.832166) (xy 14.200044 -364.004316) (xy 14.073443 -364.171769) (xy 13.940558 -364.33428)
			(xy 13.801583 -364.491614) (xy 13.656719 -364.643543) (xy 13.506176 -364.789847) (xy 13.350172 -364.930314)
			(xy 13.188933 -365.06474) (xy 13.022693 -365.192929) (xy 12.851694 -365.314697) (xy 12.676183 -365.429867)
			(xy 12.496415 -365.538271) (xy 12.31265 -365.639753) (xy 12.125154 -365.734165) (xy 11.934201 -365.821371)
			(xy 11.740065 -365.901244) (xy 11.54303 -365.973668) (xy 11.34338 -366.038538) (xy 11.141405 -366.09576)
			(xy 10.937399 -366.145252) (xy 10.731655 -366.186941) (xy 10.524474 -366.220766) (xy 10.316156 -366.24668)
			(xy 10.107002 -366.264645) (xy 9.897315 -366.274633) (xy 9.687401 -366.276632) (xy 9.477562 -366.270637)
			(xy 9.268104 -366.256658) (xy 9.059329 -366.234715) (xy 8.851542 -366.20484) (xy 8.645043 -366.167075)
			(xy 8.44013 -366.121477) (xy 8.237103 -366.06811) (xy 8.036254 -366.007053) (xy 7.837876 -365.938394)
			(xy 7.642255 -365.862231) (xy 7.449675 -365.778677) (xy 7.260417 -365.687852) (xy 7.074753 -365.589887)
			(xy 6.892953 -365.484925) (xy 6.715281 -365.373118) (xy 6.541995 -365.254627) (xy 6.373345 -365.129626)
			(xy 6.209576 -364.998294) (xy 6.050926 -364.860823) (xy 5.897624 -364.717412) (xy 5.749894 -364.568268)
			(xy 5.607948 -364.413608) (xy 5.471994 -364.253657) (xy 5.342227 -364.088645) (xy 5.218837 -363.918813)
			(xy 5.102002 -363.744406) (xy 4.991891 -363.565678) (xy 4.888664 -363.382887) (xy 4.792471 -363.196299)
			(xy 4.703452 -363.006184) (xy 4.621734 -362.812818) (xy 4.547438 -362.616481) (xy 4.48067 -362.417458)
			(xy 4.421528 -362.216037) (xy 4.370096 -362.012511) (xy 4.326451 -361.807174) (xy 4.290654 -361.600324)
			(xy 4.262758 -361.392262) (xy 4.242804 -361.183288) (xy 4.230819 -360.973706) (xy 4.226823 -360.76382)
			(xy 2.509012 -360.76382) (xy 2.509012 -383.932484) (xy 8.539215 -383.932484) (xy 8.539215 -383.803344)
			(xy 8.547165 -383.674449) (xy 8.563035 -383.546289) (xy 8.586764 -383.419348) (xy 8.618263 -383.294109)
			(xy 8.657412 -383.171046) (xy 8.704063 -383.050627) (xy 8.758038 -382.933308) (xy 8.819133 -382.819534)
			(xy 8.887116 -382.709737) (xy 8.96173 -382.604334) (xy 9.042691 -382.503724) (xy 9.129691 -382.408289)
			(xy 9.222402 -382.31839) (xy 9.320472 -382.234369) (xy 9.423527 -382.156545) (xy 9.531178 -382.085213)
			(xy 9.643017 -382.020643) (xy 9.758618 -381.963081) (xy 9.877543 -381.912744) (xy 9.999342 -381.869824)
			(xy 10.123552 -381.834483) (xy 10.249701 -381.806856) (xy 10.377313 -381.787047) (xy 10.505902 -381.775131)
			(xy 10.63498 -381.771155) (xy 10.764058 -381.775131) (xy 10.892647 -381.787047) (xy 11.020259 -381.806856)
			(xy 11.146408 -381.834483) (xy 11.270618 -381.869824) (xy 11.392417 -381.912744) (xy 11.511342 -381.963081)
			(xy 11.626943 -382.020643) (xy 11.738782 -382.085213) (xy 11.846433 -382.156545) (xy 11.949488 -382.234369)
			(xy 12.047558 -382.31839) (xy 12.140269 -382.408289) (xy 12.227269 -382.503724) (xy 12.30823 -382.604334)
			(xy 12.382844 -382.709737) (xy 12.450827 -382.819534) (xy 12.505341 -382.921052) (xy 19.016679 -382.921052)
			(xy 19.016679 -382.866548) (xy 19.024437 -382.812598) (xy 19.039793 -382.760301) (xy 19.062436 -382.710722)
			(xy 19.091904 -382.664871) (xy 19.127599 -382.62368) (xy 19.168792 -382.587989) (xy 19.214645 -382.558523)
			(xy 19.264226 -382.535884) (xy 19.316523 -382.520531) (xy 19.370474 -382.512778) (xy 19.397726 -382.512316)
			(xy 20.261326 -382.512316) (xy 20.288578 -382.512756) (xy 20.342526 -382.520516) (xy 20.394821 -382.535874)
			(xy 20.444398 -382.558518) (xy 20.490248 -382.587987) (xy 20.531438 -382.623681) (xy 20.567129 -382.664873)
			(xy 20.596594 -382.710725) (xy 20.619235 -382.760303) (xy 20.63459 -382.812599) (xy 20.642346 -382.866548)
			(xy 20.642346 -382.921052) (xy 20.636681 -382.960459) (xy 22.291788 -382.960459) (xy 22.291788 -382.905921)
			(xy 22.29955 -382.851938) (xy 22.314915 -382.79961) (xy 22.337571 -382.75) (xy 22.367056 -382.70412)
			(xy 22.40277 -382.662903) (xy 22.443987 -382.627188) (xy 22.489867 -382.597702) (xy 22.539476 -382.575046)
			(xy 22.591804 -382.559681) (xy 22.645787 -382.551919) (xy 22.673056 -382.551432) (xy 23.536656 -382.551432)
			(xy 23.563927 -382.551887) (xy 23.617915 -382.559649) (xy 23.670249 -382.575015) (xy 23.719863 -382.597673)
			(xy 23.765748 -382.62716) (xy 23.806969 -382.662878) (xy 23.842687 -382.704099) (xy 23.872175 -382.749983)
			(xy 23.894834 -382.799597) (xy 23.9102 -382.851931) (xy 23.917962 -382.905919) (xy 23.917962 -382.960461)
			(xy 23.9102 -383.014449) (xy 23.894834 -383.066783) (xy 23.872175 -383.116397) (xy 23.842687 -383.162281)
			(xy 23.806969 -383.203502) (xy 23.765748 -383.23922) (xy 23.719863 -383.268707) (xy 23.670249 -383.291365)
			(xy 23.617915 -383.306731) (xy 23.563927 -383.314493) (xy 23.536656 -383.314956) (xy 22.673056 -383.314956)
			(xy 22.645787 -383.314461) (xy 22.591804 -383.306699) (xy 22.539476 -383.291334) (xy 22.489867 -383.268678)
			(xy 22.443987 -383.239192) (xy 22.40277 -383.203477) (xy 22.367056 -383.16226) (xy 22.337571 -383.11638)
			(xy 22.314915 -383.06677) (xy 22.29955 -383.014442) (xy 22.291788 -382.960459) (xy 20.636681 -382.960459)
			(xy 20.63459 -382.975001) (xy 20.619235 -383.027297) (xy 20.596594 -383.076875) (xy 20.567129 -383.122727)
			(xy 20.531438 -383.163919) (xy 20.490248 -383.199613) (xy 20.444398 -383.229082) (xy 20.394821 -383.251726)
			(xy 20.342526 -383.267084) (xy 20.288578 -383.274844) (xy 20.261326 -383.275332) (xy 19.397726 -383.275332)
			(xy 19.370474 -383.274822) (xy 19.316523 -383.267069) (xy 19.264226 -383.251716) (xy 19.214645 -383.229077)
			(xy 19.168792 -383.199611) (xy 19.127599 -383.16392) (xy 19.091904 -383.122729) (xy 19.062436 -383.076878)
			(xy 19.039793 -383.027299) (xy 19.024437 -382.975002) (xy 19.016679 -382.921052) (xy 12.505341 -382.921052)
			(xy 12.511922 -382.933308) (xy 12.565897 -383.050627) (xy 12.612548 -383.171046) (xy 12.651697 -383.294109)
			(xy 12.683196 -383.419348) (xy 12.706925 -383.546289) (xy 12.722795 -383.674449) (xy 12.730745 -383.803344)
			(xy 12.731242 -383.867914) (xy 12.730745 -383.932484) (xy 12.722795 -384.061379) (xy 12.706925 -384.189539)
			(xy 12.683196 -384.31648) (xy 12.651697 -384.441719) (xy 12.612548 -384.564782) (xy 12.565897 -384.685201)
			(xy 12.511922 -384.80252) (xy 12.450827 -384.916294) (xy 12.382844 -385.026091) (xy 12.30823 -385.131494)
			(xy 12.227269 -385.232104) (xy 12.140269 -385.327539) (xy 12.047558 -385.417438) (xy 11.949488 -385.501459)
			(xy 11.846433 -385.579283) (xy 11.738782 -385.650615) (xy 11.626943 -385.715185) (xy 11.511342 -385.772747)
			(xy 11.483943 -385.784344) (xy 19.460972 -385.784344) (xy 19.460972 -384.920744) (xy 19.461458 -384.893493)
			(xy 19.469214 -384.839545) (xy 19.484569 -384.78725) (xy 19.507211 -384.737673) (xy 19.536677 -384.691823)
			(xy 19.572368 -384.650632) (xy 19.613559 -384.614941) (xy 19.659409 -384.585475) (xy 19.708986 -384.562833)
			(xy 19.761281 -384.547478) (xy 19.815229 -384.539722) (xy 19.869731 -384.539722) (xy 19.923679 -384.547478)
			(xy 19.975974 -384.562833) (xy 20.025551 -384.585475) (xy 20.071401 -384.614941) (xy 20.112592 -384.650632)
			(xy 20.148283 -384.691823) (xy 20.177749 -384.737673) (xy 20.200391 -384.78725) (xy 20.215746 -384.839545)
			(xy 20.223502 -384.893493) (xy 20.223988 -384.920744) (xy 20.223988 -385.784344) (xy 20.22353 -385.809998)
			(xy 22.731984 -385.809998) (xy 22.731984 -384.946398) (xy 22.73247 -384.919147) (xy 22.740226 -384.865199)
			(xy 22.755581 -384.812904) (xy 22.778223 -384.763327) (xy 22.807689 -384.717477) (xy 22.84338 -384.676286)
			(xy 22.884571 -384.640595) (xy 22.930421 -384.611129) (xy 22.979998 -384.588487) (xy 23.032293 -384.573132)
			(xy 23.086241 -384.565376) (xy 23.140743 -384.565376) (xy 23.194691 -384.573132) (xy 23.246986 -384.588487)
			(xy 23.296563 -384.611129) (xy 23.342413 -384.640595) (xy 23.383604 -384.676286) (xy 23.419295 -384.717477)
			(xy 23.448761 -384.763327) (xy 23.471403 -384.812904) (xy 23.486758 -384.865199) (xy 23.494514 -384.919147)
			(xy 23.495 -384.946398) (xy 23.495 -385.440249) (xy 36.585674 -385.440249) (xy 36.585674 -385.385751)
			(xy 36.593429 -385.331807) (xy 36.608782 -385.279515) (xy 36.63142 -385.229941) (xy 36.660882 -385.184092)
			(xy 36.696569 -385.142903) (xy 36.737753 -385.107211) (xy 36.783598 -385.077743) (xy 36.83317 -385.055099)
			(xy 36.88546 -385.039739) (xy 36.939403 -385.031977) (xy 36.966652 -385.031488) (xy 37.830252 -385.031488)
			(xy 37.857507 -385.031956) (xy 37.911462 -385.039707) (xy 37.963765 -385.055059) (xy 38.013351 -385.077699)
			(xy 38.05921 -385.107165) (xy 38.100408 -385.142858) (xy 38.136106 -385.184052) (xy 38.165578 -385.229907)
			(xy 38.188224 -385.27949) (xy 38.203582 -385.331791) (xy 38.211341 -385.385745) (xy 38.211341 -385.440255)
			(xy 38.203582 -385.494209) (xy 38.188224 -385.54651) (xy 38.165578 -385.596093) (xy 38.16123 -385.602858)
			(xy 41.455211 -385.602858) (xy 41.455211 -385.548342) (xy 41.46297 -385.494381) (xy 41.47833 -385.442074)
			(xy 41.500978 -385.392486) (xy 41.530453 -385.346625) (xy 41.566155 -385.305427) (xy 41.607357 -385.269729)
			(xy 41.653221 -385.240259) (xy 41.702812 -385.217616) (xy 41.755121 -385.202261) (xy 41.809082 -385.194508)
			(xy 41.83634 -385.194048) (xy 42.69994 -385.194048) (xy 42.727186 -385.194625) (xy 42.781123 -385.202385)
			(xy 42.833407 -385.217742) (xy 42.882974 -385.240383) (xy 42.928814 -385.269847) (xy 42.969994 -385.305534)
			(xy 43.005677 -385.346718) (xy 43.035136 -385.392562) (xy 43.057772 -385.44213) (xy 43.073123 -385.494416)
			(xy 43.080878 -385.548354) (xy 43.080878 -385.602846) (xy 43.073123 -385.656784) (xy 43.057772 -385.70907)
			(xy 43.035136 -385.758638) (xy 43.005677 -385.804482) (xy 42.969994 -385.845666) (xy 42.928814 -385.881353)
			(xy 42.882974 -385.910817) (xy 42.833407 -385.933458) (xy 42.781123 -385.948815) (xy 42.727186 -385.956575)
			(xy 42.69994 -385.957064) (xy 41.83634 -385.957064) (xy 41.809082 -385.956692) (xy 41.755121 -385.948939)
			(xy 41.702812 -385.933584) (xy 41.653221 -385.910941) (xy 41.607357 -385.881471) (xy 41.566155 -385.845773)
			(xy 41.530453 -385.804575) (xy 41.500978 -385.758714) (xy 41.47833 -385.709126) (xy 41.46297 -385.656819)
			(xy 41.455211 -385.602858) (xy 38.16123 -385.602858) (xy 38.136106 -385.641948) (xy 38.100408 -385.683142)
			(xy 38.05921 -385.718835) (xy 38.013351 -385.748301) (xy 37.963765 -385.770941) (xy 37.911462 -385.786293)
			(xy 37.857507 -385.794044) (xy 37.830252 -385.794504) (xy 36.966652 -385.794504) (xy 36.939403 -385.794023)
			(xy 36.88546 -385.786261) (xy 36.83317 -385.770901) (xy 36.783598 -385.748257) (xy 36.737753 -385.718789)
			(xy 36.696569 -385.683097) (xy 36.660882 -385.641908) (xy 36.63142 -385.596059) (xy 36.608782 -385.546485)
			(xy 36.593429 -385.494193) (xy 36.585674 -385.440249) (xy 23.495 -385.440249) (xy 23.495 -385.809998)
			(xy 23.494514 -385.837249) (xy 23.486758 -385.891197) (xy 23.471403 -385.943492) (xy 23.448761 -385.993069)
			(xy 23.419295 -386.038919) (xy 23.383604 -386.08011) (xy 23.342413 -386.115801) (xy 23.296563 -386.145267)
			(xy 23.246986 -386.167909) (xy 23.194691 -386.183264) (xy 23.140743 -386.19102) (xy 23.086241 -386.19102)
			(xy 23.032293 -386.183264) (xy 22.979998 -386.167909) (xy 22.930421 -386.145267) (xy 22.884571 -386.115801)
			(xy 22.84338 -386.08011) (xy 22.807689 -386.038919) (xy 22.778223 -385.993069) (xy 22.755581 -385.943492)
			(xy 22.740226 -385.891197) (xy 22.73247 -385.837249) (xy 22.731984 -385.809998) (xy 20.22353 -385.809998)
			(xy 20.223502 -385.811595) (xy 20.215746 -385.865543) (xy 20.200391 -385.917838) (xy 20.177749 -385.967415)
			(xy 20.148283 -386.013265) (xy 20.112592 -386.054456) (xy 20.071401 -386.090147) (xy 20.025551 -386.119613)
			(xy 19.975974 -386.142255) (xy 19.923679 -386.15761) (xy 19.869731 -386.165366) (xy 19.815229 -386.165366)
			(xy 19.761281 -386.15761) (xy 19.708986 -386.142255) (xy 19.659409 -386.119613) (xy 19.613559 -386.090147)
			(xy 19.572368 -386.054456) (xy 19.536677 -386.013265) (xy 19.507211 -385.967415) (xy 19.484569 -385.917838)
			(xy 19.469214 -385.865543) (xy 19.461458 -385.811595) (xy 19.460972 -385.784344) (xy 11.483943 -385.784344)
			(xy 11.392417 -385.823084) (xy 11.270618 -385.866004) (xy 11.146408 -385.901345) (xy 11.020259 -385.928972)
			(xy 10.892647 -385.948781) (xy 10.764058 -385.960697) (xy 10.63498 -385.964674) (xy 10.505902 -385.960697)
			(xy 10.377313 -385.948781) (xy 10.249701 -385.928972) (xy 10.123552 -385.901345) (xy 9.999342 -385.866004)
			(xy 9.877543 -385.823084) (xy 9.758618 -385.772747) (xy 9.643017 -385.715185) (xy 9.531178 -385.650615)
			(xy 9.423527 -385.579283) (xy 9.320472 -385.501459) (xy 9.222402 -385.417438) (xy 9.129691 -385.327539)
			(xy 9.042691 -385.232104) (xy 8.96173 -385.131494) (xy 8.887116 -385.026091) (xy 8.819133 -384.916294)
			(xy 8.758038 -384.80252) (xy 8.704063 -384.685201) (xy 8.657412 -384.564782) (xy 8.618263 -384.441719)
			(xy 8.586764 -384.31648) (xy 8.563035 -384.189539) (xy 8.547165 -384.061379) (xy 8.539215 -383.932484)
			(xy 2.509012 -383.932484) (xy 2.509012 -389.402275) (xy 286.566098 -389.402275) (xy 286.566098 -389.317529)
			(xy 286.574154 -389.233168) (xy 286.590192 -389.149954) (xy 286.614067 -389.068641) (xy 286.645564 -388.989966)
			(xy 286.684397 -388.914642) (xy 286.730213 -388.843349) (xy 286.7826 -388.776735) (xy 286.84108 -388.715402)
			(xy 286.905127 -388.659906) (xy 286.974158 -388.610748) (xy 287.04755 -388.568376) (xy 287.124637 -388.533171)
			(xy 287.204721 -388.505454) (xy 287.287078 -388.485474) (xy 287.370961 -388.473414) (xy 287.45561 -388.469382)
			(xy 287.540259 -388.473414) (xy 287.624142 -388.485474) (xy 287.706499 -388.505454) (xy 287.786583 -388.533171)
			(xy 287.86367 -388.568376) (xy 287.937062 -388.610748) (xy 288.006093 -388.659906) (xy 288.07014 -388.715402)
			(xy 288.12862 -388.776735) (xy 288.181007 -388.843349) (xy 288.226823 -388.914642) (xy 288.265656 -388.989966)
			(xy 288.297153 -389.068641) (xy 288.321028 -389.149954) (xy 288.337066 -389.233168) (xy 288.345122 -389.317529)
			(xy 288.345626 -389.359902) (xy 288.345122 -389.402275) (xy 297.615098 -389.402275) (xy 297.615098 -389.317529)
			(xy 297.623154 -389.233168) (xy 297.639192 -389.149954) (xy 297.663067 -389.068641) (xy 297.694564 -388.989966)
			(xy 297.733397 -388.914642) (xy 297.779213 -388.843349) (xy 297.8316 -388.776735) (xy 297.89008 -388.715402)
			(xy 297.954127 -388.659906) (xy 298.023158 -388.610748) (xy 298.09655 -388.568376) (xy 298.173637 -388.533171)
			(xy 298.253721 -388.505454) (xy 298.336078 -388.485474) (xy 298.419961 -388.473414) (xy 298.50461 -388.469382)
			(xy 298.589259 -388.473414) (xy 298.673142 -388.485474) (xy 298.755499 -388.505454) (xy 298.835583 -388.533171)
			(xy 298.91267 -388.568376) (xy 298.986062 -388.610748) (xy 299.055093 -388.659906) (xy 299.11914 -388.715402)
			(xy 299.17762 -388.776735) (xy 299.230007 -388.843349) (xy 299.275823 -388.914642) (xy 299.314656 -388.989966)
			(xy 299.346153 -389.068641) (xy 299.370028 -389.149954) (xy 299.386066 -389.233168) (xy 299.394122 -389.317529)
			(xy 299.394626 -389.359902) (xy 299.394122 -389.402275) (xy 299.386066 -389.486636) (xy 299.370028 -389.56985)
			(xy 299.346153 -389.651163) (xy 299.314656 -389.729838) (xy 299.275823 -389.805162) (xy 299.230007 -389.876455)
			(xy 299.17762 -389.943069) (xy 299.11914 -390.004402) (xy 299.055093 -390.059898) (xy 298.986062 -390.109056)
			(xy 298.91267 -390.151428) (xy 298.835583 -390.186633) (xy 298.755499 -390.21435) (xy 298.673142 -390.23433)
			(xy 298.589259 -390.24639) (xy 298.50461 -390.250423) (xy 298.419961 -390.24639) (xy 298.336078 -390.23433)
			(xy 298.253721 -390.21435) (xy 298.173637 -390.186633) (xy 298.09655 -390.151428) (xy 298.023158 -390.109056)
			(xy 297.954127 -390.059898) (xy 297.89008 -390.004402) (xy 297.8316 -389.943069) (xy 297.779213 -389.876455)
			(xy 297.733397 -389.805162) (xy 297.694564 -389.729838) (xy 297.663067 -389.651163) (xy 297.639192 -389.56985)
			(xy 297.623154 -389.486636) (xy 297.615098 -389.402275) (xy 288.345122 -389.402275) (xy 288.337066 -389.486636)
			(xy 288.321028 -389.56985) (xy 288.297153 -389.651163) (xy 288.265656 -389.729838) (xy 288.226823 -389.805162)
			(xy 288.181007 -389.876455) (xy 288.12862 -389.943069) (xy 288.07014 -390.004402) (xy 288.006093 -390.059898)
			(xy 287.937062 -390.109056) (xy 287.86367 -390.151428) (xy 287.786583 -390.186633) (xy 287.706499 -390.21435)
			(xy 287.624142 -390.23433) (xy 287.540259 -390.24639) (xy 287.45561 -390.250423) (xy 287.370961 -390.24639)
			(xy 287.287078 -390.23433) (xy 287.204721 -390.21435) (xy 287.124637 -390.186633) (xy 287.04755 -390.151428)
			(xy 286.974158 -390.109056) (xy 286.905127 -390.059898) (xy 286.84108 -390.004402) (xy 286.7826 -389.943069)
			(xy 286.730213 -389.876455) (xy 286.684397 -389.805162) (xy 286.645564 -389.729838) (xy 286.614067 -389.651163)
			(xy 286.590192 -389.56985) (xy 286.574154 -389.486636) (xy 286.566098 -389.402275) (xy 2.509012 -389.402275)
			(xy 2.509012 -390.74852) (xy 289.828732 -390.74852) (xy 289.829157 -390.717787) (xy 289.836564 -390.656768)
			(xy 289.851272 -390.597088) (xy 289.873068 -390.539615) (xy 289.901633 -390.485189) (xy 289.93655 -390.434604)
			(xy 289.97731 -390.388596) (xy 290.023319 -390.347837) (xy 290.073907 -390.312922) (xy 290.128334 -390.28436)
			(xy 290.185807 -390.262566) (xy 290.245488 -390.24786) (xy 290.306507 -390.240455) (xy 290.33724 -390.240012)
			(xy 290.369283 -390.240508) (xy 290.432859 -390.248584) (xy 290.494917 -390.264579) (xy 290.554476 -390.288239)
			(xy 290.610594 -390.31919) (xy 290.662381 -390.356941) (xy 290.709019 -390.400896) (xy 290.749768 -390.450359)
			(xy 290.783985 -390.504546) (xy 290.811128 -390.562601) (xy 290.830767 -390.623604) (xy 290.842591 -390.686591)
			(xy 290.844986 -390.718548) (xy 290.846452 -390.733661) (xy 290.857061 -390.762093) (xy 290.875562 -390.786147)
			(xy 290.900318 -390.803698) (xy 290.929141 -390.813192) (xy 290.9443 -390.814052) (xy 290.977155 -390.815239)
			(xy 291.042167 -390.825028) (xy 291.105376 -390.843112) (xy 291.165728 -390.86919) (xy 291.222216 -390.902827)
			(xy 291.2739 -390.943462) (xy 291.319917 -390.990417) (xy 291.359501 -391.04291) (xy 291.391992 -391.100065)
			(xy 291.416847 -391.160931) (xy 291.433653 -391.224491) (xy 291.442129 -391.289688) (xy 291.442648 -391.32256)
			(xy 291.442106 -391.353289) (xy 291.434703 -391.414298) (xy 291.42 -391.473971) (xy 291.398212 -391.531436)
			(xy 291.369656 -391.585856) (xy 291.334748 -391.636437) (xy 291.293998 -391.682441) (xy 291.248 -391.723199)
			(xy 291.197424 -391.758114) (xy 291.143009 -391.786679) (xy 291.085547 -391.808477) (xy 291.025877 -391.823189)
			(xy 290.964869 -391.830602) (xy 290.93414 -391.831068) (xy 290.902098 -391.830516) (xy 290.838523 -391.822449)
			(xy 290.776465 -391.806463) (xy 290.716905 -391.78281) (xy 290.660787 -391.751866) (xy 290.608999 -391.71412)
			(xy 290.56236 -391.670169) (xy 290.521609 -391.620711) (xy 290.487392 -391.566526) (xy 290.460249 -391.508474)
			(xy 290.440611 -391.447473) (xy 290.428788 -391.384488) (xy 290.426394 -391.352532) (xy 290.424962 -391.337414)
			(xy 290.414346 -391.308979) (xy 290.395837 -391.284924) (xy 290.371072 -391.267376) (xy 290.342242 -391.257886)
			(xy 290.32708 -391.257028) (xy 290.294229 -391.25578) (xy 290.229223 -391.24599) (xy 290.166019 -391.227907)
			(xy 290.105673 -391.201832) (xy 290.049188 -391.1682) (xy 289.997507 -391.127571) (xy 289.95149 -391.080623)
			(xy 289.911906 -391.028137) (xy 289.879413 -390.97099) (xy 289.854553 -390.910132) (xy 289.837741 -390.846579)
			(xy 289.829256 -390.78139) (xy 289.828732 -390.74852) (xy 2.509012 -390.74852) (xy 2.509012 -394.8085)
			(xy 243.179528 -394.8085) (xy 243.183558 -394.723892) (xy 243.195613 -394.640051) (xy 243.215583 -394.557735)
			(xy 243.243287 -394.47769) (xy 243.278475 -394.400641) (xy 243.320827 -394.327286) (xy 243.36996 -394.258289)
			(xy 243.42543 -394.194274) (xy 243.486733 -394.135823) (xy 243.553315 -394.083463) (xy 243.624573 -394.03767)
			(xy 243.699861 -393.998857) (xy 243.778498 -393.967377) (xy 243.859771 -393.943515) (xy 243.942944 -393.927486)
			(xy 244.027264 -393.919435) (xy 244.069616 -393.918948) (xy 244.11084 -393.919417) (xy 244.192933 -393.927053)
			(xy 244.273968 -393.94225) (xy 244.35325 -393.964876) (xy 244.430099 -393.994739) (xy 244.503857 -394.031582)
			(xy 244.573891 -394.075088) (xy 244.639601 -394.124886) (xy 244.670326 -394.152374) (xy 244.677558 -394.158461)
			(xy 244.695171 -394.165287) (xy 244.714061 -394.165287) (xy 244.731674 -394.158461) (xy 244.738906 -394.152374)
			(xy 244.769639 -394.124894) (xy 244.835341 -394.075085) (xy 244.905371 -394.03157) (xy 244.979128 -393.994723)
			(xy 245.055977 -393.964858) (xy 245.13526 -393.942233) (xy 245.216297 -393.927041) (xy 245.298392 -393.919413)
			(xy 245.339616 -393.918948) (xy 245.380184 -393.919416) (xy 245.460981 -393.926807) (xy 245.54077 -393.941524)
			(xy 245.618888 -393.963447) (xy 245.694684 -393.992392) (xy 245.767529 -394.02812) (xy 245.836818 -394.070333)
			(xy 245.901975 -394.118681) (xy 245.962458 -394.172761) (xy 246.017765 -394.232125) (xy 246.067436 -394.296278)
			(xy 246.111059 -394.364689) (xy 246.130064 -394.400532) (xy 246.157157 -394.401367) (xy 246.21073 -394.409598)
			(xy 246.262601 -394.42532) (xy 246.31173 -394.448214) (xy 246.357129 -394.477824) (xy 246.397887 -394.513553)
			(xy 246.433186 -394.554684) (xy 246.462317 -394.600391) (xy 246.484695 -394.649758) (xy 246.499871 -394.701791)
			(xy 246.507539 -394.755447) (xy 246.508016 -394.782548) (xy 246.507582 -394.8085) (xy 249.114543 -394.8085)
			(xy 249.118574 -394.723896) (xy 249.130628 -394.640058) (xy 249.150596 -394.557746) (xy 249.178298 -394.477704)
			(xy 249.213483 -394.400658) (xy 249.255833 -394.327305) (xy 249.304963 -394.25831) (xy 249.360429 -394.194298)
			(xy 249.421729 -394.135847) (xy 249.488307 -394.083488) (xy 249.55956 -394.037695) (xy 249.634844 -393.998882)
			(xy 249.713476 -393.967401) (xy 249.794745 -393.943537) (xy 249.877914 -393.927506) (xy 249.96223 -393.919453)
			(xy 250.00458 -393.918948) (xy 250.045803 -393.919439) (xy 250.127896 -393.927072) (xy 250.20893 -393.942266)
			(xy 250.288212 -393.964889) (xy 250.365061 -393.994749) (xy 250.438819 -394.031588) (xy 250.508854 -394.075092)
			(xy 250.574564 -394.124887) (xy 250.60529 -394.152374) (xy 250.612522 -394.158461) (xy 250.630135 -394.165287)
			(xy 250.649025 -394.165287) (xy 250.666638 -394.158461) (xy 250.67387 -394.152374) (xy 250.704576 -394.124863)
			(xy 250.770283 -394.075057) (xy 250.840317 -394.031545) (xy 250.914078 -393.994701) (xy 250.990931 -393.96484)
			(xy 251.070218 -393.942219) (xy 251.151257 -393.927032) (xy 251.233355 -393.91941) (xy 251.27458 -393.918948)
			(xy 251.315219 -393.919386) (xy 251.396157 -393.926808) (xy 251.47608 -393.941582) (xy 251.554323 -393.963585)
			(xy 251.630232 -393.992634) (xy 251.703174 -394.028487) (xy 251.772542 -394.070844) (xy 251.837756 -394.119353)
			(xy 251.898274 -394.173608) (xy 251.95359 -394.233158) (xy 252.003243 -394.297505) (xy 252.046819 -394.366114)
			(xy 252.06579 -394.402056) (xy 252.086364 -394.401548) (xy 252.113582 -394.401996) (xy 252.167464 -394.409739)
			(xy 252.219695 -394.425073) (xy 252.269213 -394.447684) (xy 252.315007 -394.477114) (xy 252.356147 -394.512762)
			(xy 252.391793 -394.553902) (xy 252.421221 -394.599698) (xy 252.443832 -394.649216) (xy 252.459163 -394.701448)
			(xy 252.466905 -394.75533) (xy 252.467364 -394.782548) (xy 252.466916 -394.8085) (xy 255.049428 -394.8085)
			(xy 255.053459 -394.723891) (xy 255.065514 -394.640048) (xy 255.085484 -394.55773) (xy 255.11319 -394.477684)
			(xy 255.148379 -394.400634) (xy 255.190732 -394.327277) (xy 255.239868 -394.258279) (xy 255.295339 -394.194265)
			(xy 255.356645 -394.135813) (xy 255.423229 -394.083453) (xy 255.494489 -394.03766) (xy 255.56978 -393.998849)
			(xy 255.648419 -393.96737) (xy 255.729694 -393.943509) (xy 255.812869 -393.927482) (xy 255.897191 -393.919434)
			(xy 255.939544 -393.918948) (xy 255.980768 -393.919399) (xy 256.062862 -393.927038) (xy 256.143897 -393.942237)
			(xy 256.223179 -393.964866) (xy 256.300029 -393.994731) (xy 256.373786 -394.031576) (xy 256.44382 -394.075085)
			(xy 256.509529 -394.124885) (xy 256.540254 -394.152374) (xy 256.547486 -394.158461) (xy 256.565099 -394.165287)
			(xy 256.583989 -394.165287) (xy 256.601602 -394.158461) (xy 256.608834 -394.152374) (xy 256.639555 -394.12488)
			(xy 256.70526 -394.075073) (xy 256.775292 -394.031559) (xy 256.849049 -393.994713) (xy 256.925901 -393.96485)
			(xy 257.005185 -393.942227) (xy 257.086223 -393.927037) (xy 257.168319 -393.919412) (xy 257.209544 -393.918948)
			(xy 257.250365 -393.919407) (xy 257.331665 -393.926876) (xy 257.411938 -393.941765) (xy 257.490509 -393.963948)
			(xy 257.566715 -393.993239) (xy 257.639917 -394.029392) (xy 257.709496 -394.072102) (xy 257.774868 -394.121009)
			(xy 257.835483 -394.175702) (xy 257.890829 -394.235721) (xy 257.940442 -394.300559) (xy 257.983902 -394.369672)
			(xy 258.002786 -394.405866) (xy 258.01873 -394.403337) (xy 258.050905 -394.400664) (xy 258.067048 -394.400532)
			(xy 258.094337 -394.400926) (xy 258.148358 -394.408699) (xy 258.200723 -394.424081) (xy 258.250366 -394.446758)
			(xy 258.296278 -394.476268) (xy 258.337522 -394.512012) (xy 258.37326 -394.553261) (xy 258.402765 -394.599176)
			(xy 258.425436 -394.648822) (xy 258.440811 -394.701189) (xy 258.448577 -394.755211) (xy 258.448577 -394.8085)
			(xy 260.984428 -394.8085) (xy 260.988458 -394.723893) (xy 261.000513 -394.640052) (xy 261.020483 -394.557736)
			(xy 261.048186 -394.477692) (xy 261.083374 -394.400643) (xy 261.125725 -394.327288) (xy 261.174858 -394.258291)
			(xy 261.230327 -394.194277) (xy 261.29163 -394.135826) (xy 261.358212 -394.083466) (xy 261.429469 -394.037672)
			(xy 261.504756 -393.99886) (xy 261.583392 -393.967379) (xy 261.664664 -393.943516) (xy 261.747837 -393.927487)
			(xy 261.832156 -393.919436) (xy 261.874508 -393.918948) (xy 261.915732 -393.919422) (xy 261.997825 -393.927057)
			(xy 262.078859 -393.942253) (xy 262.158141 -393.964879) (xy 262.234991 -393.994741) (xy 262.308749 -394.031583)
			(xy 262.378783 -394.075089) (xy 262.444493 -394.124886) (xy 262.475218 -394.152374) (xy 262.48245 -394.158461)
			(xy 262.500063 -394.165287) (xy 262.518953 -394.165287) (xy 262.536566 -394.158461) (xy 262.543798 -394.152374)
			(xy 262.574534 -394.124897) (xy 262.640236 -394.075089) (xy 262.710266 -394.031574) (xy 262.784021 -393.994725)
			(xy 262.86087 -393.96486) (xy 262.940153 -393.942234) (xy 263.021189 -393.927042) (xy 263.103284 -393.919413)
			(xy 263.144508 -393.918948) (xy 263.185239 -393.919443) (xy 263.26636 -393.9269) (xy 263.346458 -393.941743)
			(xy 263.424865 -393.963847) (xy 263.500922 -393.993026) (xy 263.573993 -394.029037) (xy 263.643465 -394.071577)
			(xy 263.708758 -394.120291) (xy 263.769323 -394.174771) (xy 263.824654 -394.234559) (xy 263.874287 -394.299155)
			(xy 263.917806 -394.368019) (xy 263.936734 -394.404088) (xy 263.947933 -394.402872) (xy 263.970427 -394.401601)
			(xy 263.981692 -394.401548) (xy 264.008912 -394.401914) (xy 264.062799 -394.409661) (xy 264.115035 -394.424998)
			(xy 264.164556 -394.447612) (xy 264.210355 -394.477045) (xy 264.251499 -394.512695) (xy 264.287151 -394.553838)
			(xy 264.316584 -394.599637) (xy 264.3392 -394.649158) (xy 264.354537 -394.701393) (xy 264.362285 -394.75528)
			(xy 264.362285 -394.8085) (xy 266.919443 -394.8085) (xy 266.923474 -394.723896) (xy 266.935527 -394.640059)
			(xy 266.955496 -394.557747) (xy 266.983198 -394.477706) (xy 267.018382 -394.40066) (xy 267.060731 -394.327308)
			(xy 267.109861 -394.258313) (xy 267.165326 -394.194301) (xy 267.226625 -394.13585) (xy 267.293203 -394.083491)
			(xy 267.364456 -394.037698) (xy 267.439739 -393.998885) (xy 267.51837 -393.967403) (xy 267.599638 -393.943538)
			(xy 267.682807 -393.927507) (xy 267.767122 -393.919453) (xy 267.809472 -393.918948) (xy 267.850695 -393.919444)
			(xy 267.932787 -393.927077) (xy 268.013822 -393.942269) (xy 268.093103 -393.964892) (xy 268.169953 -393.994751)
			(xy 268.243711 -394.03159) (xy 268.313746 -394.075093) (xy 268.379456 -394.124888) (xy 268.410182 -394.152374)
			(xy 268.417414 -394.158461) (xy 268.435027 -394.165287) (xy 268.453917 -394.165287) (xy 268.47153 -394.158461)
			(xy 268.478762 -394.152374) (xy 268.509471 -394.124866) (xy 268.575178 -394.07506) (xy 268.645212 -394.031548)
			(xy 268.718971 -393.994703) (xy 268.795824 -393.964842) (xy 268.87511 -393.942221) (xy 268.95615 -393.927033)
			(xy 269.038247 -393.91941) (xy 269.079472 -393.918948) (xy 269.120039 -393.919454) (xy 269.200835 -393.92684)
			(xy 269.280624 -393.941554) (xy 269.35874 -393.963472) (xy 269.434536 -393.992414) (xy 269.507381 -394.028138)
			(xy 269.576671 -394.070348) (xy 269.641828 -394.118693) (xy 269.702312 -394.17277) (xy 269.757619 -394.232131)
			(xy 269.807291 -394.296282) (xy 269.850914 -394.36469) (xy 269.86992 -394.400532) (xy 269.897015 -394.401316)
			(xy 269.95059 -394.409555) (xy 270.002462 -394.425283) (xy 270.051591 -394.448184) (xy 270.096989 -394.477799)
			(xy 270.137747 -394.513533) (xy 270.173045 -394.554669) (xy 270.202175 -394.60038) (xy 270.224552 -394.64975)
			(xy 270.239727 -394.701787) (xy 270.247395 -394.755446) (xy 270.247872 -394.782548) (xy 270.24739 -394.8085)
			(xy 272.854328 -394.8085) (xy 272.858359 -394.723891) (xy 272.870414 -394.640048) (xy 272.890384 -394.557731)
			(xy 272.918089 -394.477686) (xy 272.953277 -394.400636) (xy 272.995631 -394.32728) (xy 273.044766 -394.258282)
			(xy 273.100237 -394.194267) (xy 273.161542 -394.135816) (xy 273.228125 -394.083456) (xy 273.299385 -394.037663)
			(xy 273.374675 -393.998851) (xy 273.453313 -393.967372) (xy 273.534587 -393.943511) (xy 273.617762 -393.927483)
			(xy 273.702084 -393.919434) (xy 273.744436 -393.918948) (xy 273.78566 -393.919404) (xy 273.867754 -393.927042)
			(xy 273.948789 -393.942241) (xy 274.028071 -393.964869) (xy 274.10492 -393.994734) (xy 274.178678 -394.031578)
			(xy 274.248712 -394.075086) (xy 274.314421 -394.124886) (xy 274.345146 -394.152374) (xy 274.352378 -394.158461)
			(xy 274.369991 -394.165287) (xy 274.388881 -394.165287) (xy 274.406494 -394.158461) (xy 274.413726 -394.152374)
			(xy 274.44445 -394.124884) (xy 274.510154 -394.075076) (xy 274.580186 -394.031562) (xy 274.653943 -393.994716)
			(xy 274.730794 -393.964852) (xy 274.810078 -393.942228) (xy 274.891116 -393.927038) (xy 274.973211 -393.919412)
			(xy 275.014436 -393.918948) (xy 275.055004 -393.9194) (xy 275.135802 -393.926792) (xy 275.215592 -393.941511)
			(xy 275.293709 -393.963435) (xy 275.369506 -393.992382) (xy 275.442351 -394.028112) (xy 275.51164 -394.070326)
			(xy 275.576797 -394.118675) (xy 275.63728 -394.172757) (xy 275.692586 -394.232122) (xy 275.742257 -394.296277)
			(xy 275.785879 -394.364688) (xy 275.804884 -394.400532) (xy 275.831978 -394.401349) (xy 275.885551 -394.409583)
			(xy 275.937423 -394.425306) (xy 275.986552 -394.448204) (xy 276.031951 -394.477815) (xy 276.072709 -394.513546)
			(xy 276.108007 -394.554678) (xy 276.137138 -394.600387) (xy 276.159515 -394.649755) (xy 276.174691 -394.70179)
			(xy 276.182359 -394.755447) (xy 276.182836 -394.782548) (xy 276.182385 -394.808456) (xy 278.916892 -394.808456)
			(xy 278.917356 -394.766262) (xy 278.925335 -394.682252) (xy 278.941234 -394.599376) (xy 278.964912 -394.518378)
			(xy 278.996156 -394.439987) (xy 279.034684 -394.364908) (xy 279.08015 -394.293815) (xy 279.132146 -394.227349)
			(xy 279.190203 -394.166106) (xy 279.2538 -394.110638) (xy 279.322365 -394.061443) (xy 279.395282 -394.018964)
			(xy 279.471894 -393.983582) (xy 279.551513 -393.955615) (xy 279.633423 -393.935316) (xy 279.675082 -393.9286)
			(xy 279.689459 -393.925944) (xy 279.715949 -393.913606) (xy 279.737852 -393.894262) (xy 279.753368 -393.869499)
			(xy 279.761223 -393.841352) (xy 279.760772 -393.812133) (xy 279.75687 -393.798044) (xy 279.744165 -393.755179)
			(xy 279.726399 -393.667554) (xy 279.717507 -393.578589) (xy 279.716992 -393.533884) (xy 279.717496 -393.491536)
			(xy 279.725547 -393.407222) (xy 279.741576 -393.324056) (xy 279.765437 -393.242789) (xy 279.796916 -393.164159)
			(xy 279.835727 -393.088878) (xy 279.881517 -393.017626) (xy 279.933873 -392.95105) (xy 279.992321 -392.889752)
			(xy 280.056331 -392.834287) (xy 280.125323 -392.785158) (xy 280.198673 -392.742809) (xy 280.275716 -392.707625)
			(xy 280.355755 -392.679923) (xy 280.438064 -392.659955) (xy 280.521899 -392.647902) (xy 280.6065 -392.643872)
			(xy 280.691101 -392.647902) (xy 280.774936 -392.659955) (xy 280.857245 -392.679923) (xy 280.937284 -392.707625)
			(xy 281.014327 -392.742809) (xy 281.087677 -392.785158) (xy 281.156669 -392.834287) (xy 281.220679 -392.889752)
			(xy 281.279127 -392.95105) (xy 281.331483 -393.017626) (xy 281.377273 -393.088878) (xy 281.416084 -393.164159)
			(xy 281.447563 -393.242789) (xy 281.471424 -393.324056) (xy 281.487453 -393.407222) (xy 281.495504 -393.491536)
			(xy 281.496008 -393.533884) (xy 281.495487 -393.576077) (xy 281.487514 -393.660085) (xy 281.47162 -393.74296)
			(xy 281.461756 -393.776708) (xy 289.471608 -393.776708) (xy 289.471608 -393.776454) (xy 289.47211 -393.744493)
			(xy 289.480121 -393.681075) (xy 289.496018 -393.619161) (xy 289.51955 -393.559728) (xy 289.550344 -393.503713)
			(xy 289.587917 -393.451998) (xy 289.631674 -393.405401) (xy 289.680927 -393.364656) (xy 289.734898 -393.330405)
			(xy 289.792737 -393.303188) (xy 289.85353 -393.283435) (xy 289.91632 -393.271457) (xy 289.980116 -393.267444)
			(xy 290.043912 -393.271457) (xy 290.106702 -393.283435) (xy 290.167495 -393.303188) (xy 290.225334 -393.330405)
			(xy 290.279305 -393.364656) (xy 290.328558 -393.405401) (xy 290.372315 -393.451998) (xy 290.409888 -393.503713)
			(xy 290.440682 -393.559728) (xy 290.464214 -393.619161) (xy 290.480111 -393.681075) (xy 290.488122 -393.744493)
			(xy 290.488624 -393.776454) (xy 290.488624 -393.7765) (xy 291.470768 -393.7765) (xy 291.474784 -393.712663)
			(xy 291.48677 -393.649832) (xy 291.506536 -393.589) (xy 291.533771 -393.531124) (xy 291.568045 -393.477118)
			(xy 291.608817 -393.427834) (xy 291.655445 -393.384049) (xy 291.707193 -393.346453) (xy 291.763245 -393.315639)
			(xy 291.822717 -393.292094) (xy 291.884671 -393.276188) (xy 291.94813 -393.268172) (xy 291.980112 -393.267692)
			(xy 292.010658 -393.268138) (xy 292.071311 -393.275449) (xy 292.13065 -393.289975) (xy 292.187822 -393.311508)
			(xy 292.242001 -393.339737) (xy 292.292406 -393.374254) (xy 292.338312 -393.414564) (xy 292.379057 -393.460084)
			(xy 292.396926 -393.484862) (xy 292.405296 -393.496027) (xy 292.426903 -393.51367) (xy 292.452477 -393.52481)
			(xy 292.480111 -393.528618) (xy 292.507745 -393.52481) (xy 292.533319 -393.51367) (xy 292.554926 -393.496027)
			(xy 292.563296 -393.484862) (xy 292.582389 -393.458454) (xy 292.626241 -393.410247) (xy 292.675892 -393.368039)
			(xy 292.730528 -393.332518) (xy 292.789254 -393.304269) (xy 292.851108 -393.283754) (xy 292.915076 -393.271309)
			(xy 292.98011 -393.267138) (xy 293.045144 -393.271309) (xy 293.109112 -393.283754) (xy 293.170966 -393.304269)
			(xy 293.229692 -393.332518) (xy 293.284328 -393.368039) (xy 293.333979 -393.410247) (xy 293.377831 -393.458454)
			(xy 293.396924 -393.484862) (xy 293.405294 -393.496027) (xy 293.426901 -393.51367) (xy 293.452475 -393.52481)
			(xy 293.480109 -393.528618) (xy 293.507743 -393.52481) (xy 293.533317 -393.51367) (xy 293.554924 -393.496027)
			(xy 293.563294 -393.484862) (xy 293.582387 -393.458454) (xy 293.626239 -393.410247) (xy 293.67589 -393.368039)
			(xy 293.730526 -393.332518) (xy 293.789252 -393.304269) (xy 293.851106 -393.283754) (xy 293.915074 -393.271309)
			(xy 293.980108 -393.267138) (xy 294.045142 -393.271309) (xy 294.10911 -393.283754) (xy 294.170964 -393.304269)
			(xy 294.22969 -393.332518) (xy 294.284326 -393.368039) (xy 294.333977 -393.410247) (xy 294.377829 -393.458454)
			(xy 294.396922 -393.484862) (xy 294.405292 -393.496027) (xy 294.426899 -393.51367) (xy 294.452473 -393.52481)
			(xy 294.480107 -393.528618) (xy 294.507741 -393.52481) (xy 294.533315 -393.51367) (xy 294.554922 -393.496027)
			(xy 294.563292 -393.484862) (xy 294.582385 -393.458454) (xy 294.626237 -393.410247) (xy 294.675888 -393.368039)
			(xy 294.730524 -393.332518) (xy 294.78925 -393.304269) (xy 294.851104 -393.283754) (xy 294.915072 -393.271309)
			(xy 294.980106 -393.267138) (xy 295.04514 -393.271309) (xy 295.109108 -393.283754) (xy 295.170962 -393.304269)
			(xy 295.229688 -393.332518) (xy 295.284324 -393.368039) (xy 295.333975 -393.410247) (xy 295.377827 -393.458454)
			(xy 295.39692 -393.484862) (xy 295.40529 -393.496027) (xy 295.426897 -393.51367) (xy 295.452471 -393.52481)
			(xy 295.480105 -393.528618) (xy 295.507739 -393.52481) (xy 295.533313 -393.51367) (xy 295.55492 -393.496027)
			(xy 295.56329 -393.484862) (xy 295.582383 -393.458454) (xy 295.626235 -393.410247) (xy 295.675886 -393.368039)
			(xy 295.730522 -393.332518) (xy 295.789248 -393.304269) (xy 295.851102 -393.283754) (xy 295.91507 -393.271309)
			(xy 295.980104 -393.267138) (xy 296.045138 -393.271309) (xy 296.109106 -393.283754) (xy 296.17096 -393.304269)
			(xy 296.229686 -393.332518) (xy 296.284322 -393.368039) (xy 296.333973 -393.410247) (xy 296.377825 -393.458454)
			(xy 296.396918 -393.484862) (xy 296.405288 -393.496027) (xy 296.426895 -393.51367) (xy 296.452469 -393.52481)
			(xy 296.480103 -393.528618) (xy 296.507737 -393.52481) (xy 296.533311 -393.51367) (xy 296.554918 -393.496027)
			(xy 296.563288 -393.484862) (xy 296.581151 -393.46008) (xy 296.621903 -393.414568) (xy 296.667813 -393.374265)
			(xy 296.71822 -393.339752) (xy 296.772399 -393.311525) (xy 296.829568 -393.289992) (xy 296.888906 -393.275462)
			(xy 296.949557 -393.268144) (xy 296.980102 -393.267692) (xy 297.012076 -393.268286) (xy 297.07552 -393.276301)
			(xy 297.137459 -393.292204) (xy 297.196916 -393.315745) (xy 297.252954 -393.346553) (xy 297.304689 -393.384141)
			(xy 297.351305 -393.427916) (xy 297.392067 -393.477189) (xy 297.426332 -393.531182) (xy 297.45356 -393.589044)
			(xy 297.473321 -393.649863) (xy 297.485304 -393.712678) (xy 297.489319 -393.7765) (xy 297.485304 -393.840322)
			(xy 297.473321 -393.903137) (xy 297.45356 -393.963956) (xy 297.426332 -394.021818) (xy 297.392067 -394.075811)
			(xy 297.351305 -394.125084) (xy 297.304689 -394.168859) (xy 297.252954 -394.206447) (xy 297.196916 -394.237255)
			(xy 297.137459 -394.260796) (xy 297.07552 -394.276699) (xy 297.012076 -394.284714) (xy 296.980102 -394.285216)
			(xy 296.949556 -394.284756) (xy 296.888904 -394.277447) (xy 296.829565 -394.262922) (xy 296.772394 -394.241392)
			(xy 296.718215 -394.213165) (xy 296.667809 -394.178649) (xy 296.621903 -394.138341) (xy 296.581158 -394.092823)
			(xy 296.563288 -394.068046) (xy 296.554946 -394.056837) (xy 296.53336 -394.03911) (xy 296.507771 -394.027912)
			(xy 296.480103 -394.024083) (xy 296.452435 -394.027912) (xy 296.426846 -394.03911) (xy 296.40526 -394.056837)
			(xy 296.396918 -394.068046) (xy 296.377825 -394.094454) (xy 296.333973 -394.142661) (xy 296.284322 -394.184869)
			(xy 296.229686 -394.22039) (xy 296.17096 -394.248639) (xy 296.109106 -394.269154) (xy 296.045138 -394.281599)
			(xy 295.980104 -394.28577) (xy 295.91507 -394.281599) (xy 295.851102 -394.269154) (xy 295.789248 -394.248639)
			(xy 295.730522 -394.22039) (xy 295.675886 -394.184869) (xy 295.626235 -394.142661) (xy 295.582383 -394.094454)
			(xy 295.56329 -394.068046) (xy 295.554948 -394.056837) (xy 295.533362 -394.03911) (xy 295.507773 -394.027912)
			(xy 295.480105 -394.024083) (xy 295.452437 -394.027912) (xy 295.426848 -394.03911) (xy 295.405262 -394.056837)
			(xy 295.39692 -394.068046) (xy 295.377827 -394.094454) (xy 295.333975 -394.142661) (xy 295.284324 -394.184869)
			(xy 295.229688 -394.22039) (xy 295.170962 -394.248639) (xy 295.109108 -394.269154) (xy 295.04514 -394.281599)
			(xy 294.980106 -394.28577) (xy 294.915072 -394.281599) (xy 294.851104 -394.269154) (xy 294.78925 -394.248639)
			(xy 294.730524 -394.22039) (xy 294.675888 -394.184869) (xy 294.626237 -394.142661) (xy 294.582385 -394.094454)
			(xy 294.563292 -394.068046) (xy 294.55495 -394.056837) (xy 294.533364 -394.03911) (xy 294.507775 -394.027912)
			(xy 294.480107 -394.024083) (xy 294.452439 -394.027912) (xy 294.42685 -394.03911) (xy 294.405264 -394.056837)
			(xy 294.396922 -394.068046) (xy 294.377829 -394.094454) (xy 294.333977 -394.142661) (xy 294.284326 -394.184869)
			(xy 294.22969 -394.22039) (xy 294.170964 -394.248639) (xy 294.10911 -394.269154) (xy 294.045142 -394.281599)
			(xy 293.980108 -394.28577) (xy 293.915074 -394.281599) (xy 293.851106 -394.269154) (xy 293.789252 -394.248639)
			(xy 293.730526 -394.22039) (xy 293.67589 -394.184869) (xy 293.626239 -394.142661) (xy 293.582387 -394.094454)
			(xy 293.563294 -394.068046) (xy 293.554952 -394.056837) (xy 293.533366 -394.03911) (xy 293.507777 -394.027912)
			(xy 293.480109 -394.024083) (xy 293.452441 -394.027912) (xy 293.426852 -394.03911) (xy 293.405266 -394.056837)
			(xy 293.396924 -394.068046) (xy 293.377831 -394.094454) (xy 293.333979 -394.142661) (xy 293.284328 -394.184869)
			(xy 293.229692 -394.22039) (xy 293.170966 -394.248639) (xy 293.109112 -394.269154) (xy 293.045144 -394.281599)
			(xy 292.98011 -394.28577) (xy 292.915076 -394.281599) (xy 292.851108 -394.269154) (xy 292.789254 -394.248639)
			(xy 292.730528 -394.22039) (xy 292.675892 -394.184869) (xy 292.626241 -394.142661) (xy 292.582389 -394.094454)
			(xy 292.563296 -394.068046) (xy 292.554954 -394.056837) (xy 292.533368 -394.03911) (xy 292.507779 -394.027912)
			(xy 292.480111 -394.024083) (xy 292.452443 -394.027912) (xy 292.426854 -394.03911) (xy 292.405268 -394.056837)
			(xy 292.396926 -394.068046) (xy 292.379057 -394.092823) (xy 292.338306 -394.138335) (xy 292.292396 -394.178638)
			(xy 292.24199 -394.213151) (xy 292.187812 -394.241378) (xy 292.130644 -394.262913) (xy 292.071307 -394.277444)
			(xy 292.010657 -394.284763) (xy 291.980112 -394.285216) (xy 291.94813 -394.284828) (xy 291.884671 -394.276812)
			(xy 291.822717 -394.260906) (xy 291.763245 -394.237361) (xy 291.707193 -394.206547) (xy 291.655445 -394.168951)
			(xy 291.608817 -394.125166) (xy 291.568045 -394.075882) (xy 291.533771 -394.021876) (xy 291.506536 -393.964)
			(xy 291.48677 -393.903168) (xy 291.474784 -393.840337) (xy 291.470768 -393.7765) (xy 290.488624 -393.7765)
			(xy 290.488624 -393.776962) (xy 290.488202 -393.806564) (xy 290.481324 -393.865367) (xy 290.467658 -393.922971)
			(xy 290.447389 -393.978597) (xy 290.420792 -394.03149) (xy 290.388226 -394.080932) (xy 290.369498 -394.10386)
			(xy 290.389588 -394.127178) (xy 290.424612 -394.17779) (xy 290.453267 -394.232263) (xy 290.475133 -394.289797)
			(xy 290.48989 -394.349552) (xy 290.497321 -394.410651) (xy 290.497768 -394.441426) (xy 290.497768 -394.44168)
			(xy 290.497266 -394.473641) (xy 290.489255 -394.537059) (xy 290.473358 -394.598973) (xy 290.449826 -394.658406)
			(xy 290.419032 -394.714421) (xy 290.381459 -394.766136) (xy 290.337702 -394.812733) (xy 290.288449 -394.853478)
			(xy 290.234478 -394.887729) (xy 290.176639 -394.914946) (xy 290.115846 -394.934699) (xy 290.053056 -394.946677)
			(xy 289.98926 -394.950691) (xy 289.925464 -394.946677) (xy 289.862674 -394.934699) (xy 289.801881 -394.914946)
			(xy 289.744042 -394.887729) (xy 289.690071 -394.853478) (xy 289.640818 -394.812733) (xy 289.597061 -394.766136)
			(xy 289.559488 -394.714421) (xy 289.528694 -394.658406) (xy 289.505162 -394.598973) (xy 289.489265 -394.537059)
			(xy 289.481254 -394.473641) (xy 289.480752 -394.44168) (xy 289.480752 -394.441172) (xy 289.481141 -394.411569)
			(xy 289.488026 -394.352765) (xy 289.501699 -394.29516) (xy 289.521974 -394.239535) (xy 289.548577 -394.186643)
			(xy 289.581148 -394.137202) (xy 289.599878 -394.114274) (xy 289.579769 -394.090972) (xy 289.544745 -394.040357)
			(xy 289.516091 -393.985882) (xy 289.494228 -393.928344) (xy 289.479476 -393.868586) (xy 289.472051 -393.807484)
			(xy 289.471608 -393.776708) (xy 281.461756 -393.776708) (xy 281.447947 -393.823957) (xy 281.416708 -393.902348)
			(xy 281.378185 -393.977427) (xy 281.332723 -394.04852) (xy 281.280732 -394.114986) (xy 281.222678 -394.176229)
			(xy 281.159084 -394.231698) (xy 281.090523 -394.280894) (xy 281.017609 -394.323374) (xy 280.941 -394.358757)
			(xy 280.861383 -394.386724) (xy 280.779476 -394.407024) (xy 280.737818 -394.41374) (xy 280.72343 -394.416347)
			(xy 280.696933 -394.428691) (xy 280.675026 -394.448046) (xy 280.659511 -394.472819) (xy 280.651661 -394.500977)
			(xy 280.652122 -394.530204) (xy 280.65603 -394.544296) (xy 280.668744 -394.587158) (xy 280.686507 -394.674785)
			(xy 280.695395 -394.763751) (xy 280.695908 -394.808456) (xy 280.695404 -394.850804) (xy 280.687353 -394.935118)
			(xy 280.671324 -395.018284) (xy 280.647463 -395.099551) (xy 280.615984 -395.178181) (xy 280.577173 -395.253462)
			(xy 280.531383 -395.324714) (xy 280.479027 -395.39129) (xy 280.420579 -395.452588) (xy 280.356569 -395.508053)
			(xy 280.287577 -395.557182) (xy 280.214227 -395.599531) (xy 280.137184 -395.634715) (xy 280.057145 -395.662417)
			(xy 279.974836 -395.682385) (xy 279.891001 -395.694438) (xy 279.8064 -395.698469) (xy 279.721799 -395.694438)
			(xy 279.637964 -395.682385) (xy 279.555655 -395.662417) (xy 279.475616 -395.634715) (xy 279.398573 -395.599531)
			(xy 279.325223 -395.557182) (xy 279.256231 -395.508053) (xy 279.192221 -395.452588) (xy 279.133773 -395.39129)
			(xy 279.081417 -395.324714) (xy 279.035627 -395.253462) (xy 278.996816 -395.178181) (xy 278.965337 -395.099551)
			(xy 278.941476 -395.018284) (xy 278.925447 -394.935118) (xy 278.917396 -394.850804) (xy 278.916892 -394.808456)
			(xy 276.182385 -394.808456) (xy 276.182339 -394.81111) (xy 276.173854 -394.867601) (xy 276.157051 -394.922198)
			(xy 276.132304 -394.973684) (xy 276.100165 -395.02091) (xy 276.061351 -395.062822) (xy 276.016728 -395.098487)
			(xy 275.967291 -395.127109) (xy 275.914142 -395.148048) (xy 275.858468 -395.160839) (xy 275.83003 -395.163548)
			(xy 275.812369 -395.202766) (xy 275.770577 -395.277947) (xy 275.721724 -395.348744) (xy 275.666266 -395.414494)
			(xy 275.60472 -395.474584) (xy 275.537661 -395.528453) (xy 275.465716 -395.575598) (xy 275.389556 -395.615578)
			(xy 275.309893 -395.648021) (xy 275.22747 -395.672622) (xy 275.143058 -395.689153) (xy 275.057444 -395.697459)
			(xy 275.014436 -395.697964) (xy 274.973213 -395.69746) (xy 274.891121 -395.689828) (xy 274.810087 -395.674636)
			(xy 274.730806 -395.652015) (xy 274.653956 -395.622157) (xy 274.580198 -395.585319) (xy 274.510163 -395.541817)
			(xy 274.444452 -395.492024) (xy 274.413726 -395.464538) (xy 274.406494 -395.458451) (xy 274.388881 -395.451625)
			(xy 274.369991 -395.451625) (xy 274.352378 -395.458451) (xy 274.345146 -395.464538) (xy 274.314435 -395.492044)
			(xy 274.248729 -395.54185) (xy 274.178695 -395.585362) (xy 274.104936 -395.622207) (xy 274.028083 -395.652068)
			(xy 273.948797 -395.67469) (xy 273.867758 -395.689878) (xy 273.785661 -395.697501) (xy 273.744436 -395.697964)
			(xy 273.702084 -395.697566) (xy 273.617762 -395.689517) (xy 273.534587 -395.673489) (xy 273.453313 -395.649628)
			(xy 273.374675 -395.618149) (xy 273.299385 -395.579337) (xy 273.228125 -395.533544) (xy 273.161542 -395.481184)
			(xy 273.100237 -395.422733) (xy 273.044766 -395.358718) (xy 272.995631 -395.28972) (xy 272.953277 -395.216364)
			(xy 272.918089 -395.139314) (xy 272.890384 -395.059269) (xy 272.870414 -394.976952) (xy 272.858359 -394.893109)
			(xy 272.854328 -394.8085) (xy 270.24739 -394.8085) (xy 270.247342 -394.811109) (xy 270.238858 -394.867596)
			(xy 270.222057 -394.922191) (xy 270.197312 -394.973674) (xy 270.165177 -395.020899) (xy 270.126367 -395.062811)
			(xy 270.081748 -395.098476) (xy 270.032316 -395.127099) (xy 269.979172 -395.148042) (xy 269.923503 -395.160836)
			(xy 269.895066 -395.163548) (xy 269.877376 -395.202752) (xy 269.835586 -395.277933) (xy 269.786736 -395.348729)
			(xy 269.73128 -395.414479) (xy 269.669737 -395.474569) (xy 269.602681 -395.528439) (xy 269.530739 -395.575585)
			(xy 269.454582 -395.615566) (xy 269.374921 -395.648011) (xy 269.292501 -395.672615) (xy 269.208091 -395.689148)
			(xy 269.122479 -395.697457) (xy 269.079472 -395.697964) (xy 269.038248 -395.6975) (xy 268.956155 -395.689862)
			(xy 268.87512 -395.674665) (xy 268.795838 -395.652037) (xy 268.718989 -395.622174) (xy 268.645231 -395.585331)
			(xy 268.575197 -395.541824) (xy 268.509487 -395.492026) (xy 268.478762 -395.464538) (xy 268.47153 -395.458451)
			(xy 268.453917 -395.451625) (xy 268.435027 -395.451625) (xy 268.417414 -395.458451) (xy 268.410182 -395.464538)
			(xy 268.379456 -395.492026) (xy 268.313752 -395.541834) (xy 268.243721 -395.585348) (xy 268.169964 -395.622194)
			(xy 268.093113 -395.652058) (xy 268.013829 -395.674682) (xy 267.932792 -395.689873) (xy 267.850696 -395.6975)
			(xy 267.809472 -395.697964) (xy 267.767122 -395.697547) (xy 267.682807 -395.689493) (xy 267.599638 -395.673462)
			(xy 267.51837 -395.649597) (xy 267.439739 -395.618115) (xy 267.364456 -395.579302) (xy 267.293203 -395.533509)
			(xy 267.226625 -395.48115) (xy 267.165326 -395.422699) (xy 267.109861 -395.358687) (xy 267.060731 -395.289692)
			(xy 267.018382 -395.21634) (xy 266.983198 -395.139294) (xy 266.955496 -395.059253) (xy 266.935527 -394.976941)
			(xy 266.923474 -394.893104) (xy 266.919443 -394.8085) (xy 264.362285 -394.8085) (xy 264.362285 -394.80972)
			(xy 264.354537 -394.863607) (xy 264.3392 -394.915842) (xy 264.316584 -394.965363) (xy 264.287151 -395.011162)
			(xy 264.251499 -395.052305) (xy 264.210355 -395.087955) (xy 264.164556 -395.117388) (xy 264.115035 -395.140002)
			(xy 264.062799 -395.155339) (xy 264.008912 -395.163086) (xy 263.981692 -395.163548) (xy 263.960356 -395.16304)
			(xy 263.942674 -395.202274) (xy 263.9009 -395.277517) (xy 263.852055 -395.348375) (xy 263.796597 -395.414185)
			(xy 263.735042 -395.474332) (xy 263.667968 -395.528254) (xy 263.596 -395.575447) (xy 263.519811 -395.61547)
			(xy 263.440113 -395.647949) (xy 263.357652 -395.67258) (xy 263.273197 -395.689134) (xy 263.187539 -395.697455)
			(xy 263.144508 -395.697964) (xy 263.103285 -395.697477) (xy 263.021192 -395.689843) (xy 262.940158 -395.674649)
			(xy 262.860876 -395.652025) (xy 262.784027 -395.622164) (xy 262.710269 -395.585324) (xy 262.640234 -395.54182)
			(xy 262.574524 -395.492025) (xy 262.543798 -395.464538) (xy 262.536566 -395.458451) (xy 262.518953 -395.451625)
			(xy 262.500063 -395.451625) (xy 262.48245 -395.458451) (xy 262.475218 -395.464538) (xy 262.444477 -395.492009)
			(xy 262.378775 -395.541818) (xy 262.308747 -395.585333) (xy 262.234992 -395.622182) (xy 262.158144 -395.652048)
			(xy 262.078861 -395.674675) (xy 261.997826 -395.689868) (xy 261.915732 -395.697498) (xy 261.874508 -395.697964)
			(xy 261.832156 -395.697564) (xy 261.747837 -395.689513) (xy 261.664664 -395.673484) (xy 261.583392 -395.649621)
			(xy 261.504756 -395.61814) (xy 261.429469 -395.579328) (xy 261.358212 -395.533534) (xy 261.29163 -395.481174)
			(xy 261.230327 -395.422723) (xy 261.174858 -395.358709) (xy 261.125725 -395.289712) (xy 261.083374 -395.216357)
			(xy 261.048186 -395.139308) (xy 261.020483 -395.059264) (xy 261.000513 -394.976948) (xy 260.988458 -394.893107)
			(xy 260.984428 -394.8085) (xy 258.448577 -394.8085) (xy 258.448577 -394.809789) (xy 258.440811 -394.863811)
			(xy 258.425436 -394.916178) (xy 258.402765 -394.965824) (xy 258.37326 -395.011739) (xy 258.337522 -395.052988)
			(xy 258.296278 -395.088732) (xy 258.250366 -395.118242) (xy 258.200723 -395.140919) (xy 258.148358 -395.156301)
			(xy 258.094337 -395.164074) (xy 258.067048 -395.164564) (xy 258.056676 -395.164479) (xy 258.035964 -395.163337)
			(xy 258.025646 -395.162278) (xy 258.008 -395.201564) (xy 257.966267 -395.276906) (xy 257.917448 -395.347861)
			(xy 257.861999 -395.413765) (xy 257.80044 -395.474001) (xy 257.733346 -395.528004) (xy 257.661347 -395.575269)
			(xy 257.585116 -395.615354) (xy 257.505368 -395.647883) (xy 257.422848 -395.672551) (xy 257.338331 -395.689127)
			(xy 257.252608 -395.697456) (xy 257.209544 -395.697964) (xy 257.168321 -395.697455) (xy 257.08623 -395.689824)
			(xy 257.005196 -395.674633) (xy 256.925914 -395.652012) (xy 256.849065 -395.622155) (xy 256.775306 -395.585317)
			(xy 256.705271 -395.541816) (xy 256.63956 -395.492023) (xy 256.608834 -395.464538) (xy 256.601602 -395.458451)
			(xy 256.583989 -395.451625) (xy 256.565099 -395.451625) (xy 256.547486 -395.458451) (xy 256.540254 -395.464538)
			(xy 256.50954 -395.49204) (xy 256.443834 -395.541846) (xy 256.373801 -395.585359) (xy 256.300042 -395.622204)
			(xy 256.22319 -395.652066) (xy 256.143904 -395.674688) (xy 256.062865 -395.689877) (xy 255.980769 -395.697501)
			(xy 255.939544 -395.697964) (xy 255.897191 -395.697566) (xy 255.812869 -395.689518) (xy 255.729694 -395.673491)
			(xy 255.648419 -395.64963) (xy 255.56978 -395.618151) (xy 255.494489 -395.57934) (xy 255.423229 -395.533547)
			(xy 255.356645 -395.481187) (xy 255.295339 -395.422735) (xy 255.239868 -395.358721) (xy 255.190732 -395.289723)
			(xy 255.148379 -395.216366) (xy 255.11319 -395.139316) (xy 255.085484 -395.05927) (xy 255.065514 -394.976952)
			(xy 255.053459 -394.893109) (xy 255.049428 -394.8085) (xy 252.466916 -394.8085) (xy 252.466897 -394.809592)
			(xy 252.459254 -394.863136) (xy 252.444116 -394.915061) (xy 252.421785 -394.964324) (xy 252.392711 -395.009932)
			(xy 252.357479 -395.05097) (xy 252.316797 -395.086613) (xy 252.271483 -395.116143) (xy 252.222447 -395.138967)
			(xy 252.170677 -395.154627) (xy 252.117212 -395.162807) (xy 252.090174 -395.163548) (xy 252.072477 -395.202749)
			(xy 252.030688 -395.27793) (xy 251.981838 -395.348725) (xy 251.926383 -395.414475) (xy 251.864841 -395.474566)
			(xy 251.797785 -395.528436) (xy 251.725844 -395.575582) (xy 251.649687 -395.615564) (xy 251.570027 -395.648009)
			(xy 251.487608 -395.672613) (xy 251.403198 -395.689147) (xy 251.317587 -395.697457) (xy 251.27458 -395.697964)
			(xy 251.233356 -395.697495) (xy 251.151263 -395.689858) (xy 251.070228 -395.674661) (xy 250.990947 -395.652035)
			(xy 250.914097 -395.622172) (xy 250.840339 -395.58533) (xy 250.770305 -395.541823) (xy 250.704595 -395.492026)
			(xy 250.67387 -395.464538) (xy 250.666638 -395.458451) (xy 250.649025 -395.451625) (xy 250.630135 -395.451625)
			(xy 250.612522 -395.458451) (xy 250.60529 -395.464538) (xy 250.574561 -395.492023) (xy 250.508857 -395.54183)
			(xy 250.438827 -395.585344) (xy 250.36507 -395.622192) (xy 250.28822 -395.652056) (xy 250.208936 -395.67468)
			(xy 250.127899 -395.689872) (xy 250.045804 -395.697499) (xy 250.00458 -395.697964) (xy 249.96223 -395.697547)
			(xy 249.877914 -395.689494) (xy 249.794745 -395.673463) (xy 249.713476 -395.649599) (xy 249.634844 -395.618118)
			(xy 249.55956 -395.579305) (xy 249.488307 -395.533512) (xy 249.421729 -395.481153) (xy 249.360429 -395.422702)
			(xy 249.304963 -395.35869) (xy 249.255833 -395.289695) (xy 249.213483 -395.216342) (xy 249.178298 -395.139296)
			(xy 249.150596 -395.059254) (xy 249.130628 -394.976942) (xy 249.118574 -394.893104) (xy 249.114543 -394.8085)
			(xy 246.507582 -394.8085) (xy 246.507538 -394.811111) (xy 246.499052 -394.867604) (xy 246.482248 -394.922202)
			(xy 246.457499 -394.973689) (xy 246.425358 -395.020916) (xy 246.386542 -395.062829) (xy 246.341916 -395.098493)
			(xy 246.292476 -395.127114) (xy 246.239326 -395.148052) (xy 246.183649 -395.16084) (xy 246.15521 -395.163548)
			(xy 246.137565 -395.202774) (xy 246.095772 -395.277955) (xy 246.046918 -395.348752) (xy 245.991458 -395.414502)
			(xy 245.929911 -395.474592) (xy 245.86285 -395.528461) (xy 245.790904 -395.575605) (xy 245.714742 -395.615585)
			(xy 245.635078 -395.648026) (xy 245.552653 -395.672626) (xy 245.46824 -395.689156) (xy 245.382624 -395.69746)
			(xy 245.339616 -395.697964) (xy 245.298393 -395.697472) (xy 245.216301 -395.689839) (xy 245.135266 -395.674645)
			(xy 245.055985 -395.652022) (xy 244.979135 -395.622162) (xy 244.905377 -395.585323) (xy 244.835342 -395.541819)
			(xy 244.769632 -395.492024) (xy 244.738906 -395.464538) (xy 244.731674 -395.458451) (xy 244.714061 -395.451625)
			(xy 244.695171 -395.451625) (xy 244.677558 -395.458451) (xy 244.670326 -395.464538) (xy 244.639624 -395.492053)
			(xy 244.573916 -395.541859) (xy 244.503881 -395.58537) (xy 244.43012 -395.622214) (xy 244.353266 -395.652074)
			(xy 244.273979 -395.674694) (xy 244.192939 -395.68988) (xy 244.110841 -395.697502) (xy 244.069616 -395.697964)
			(xy 244.027264 -395.697565) (xy 243.942944 -395.689514) (xy 243.859771 -395.673485) (xy 243.778498 -395.649623)
			(xy 243.699861 -395.618143) (xy 243.624573 -395.57933) (xy 243.553315 -395.533537) (xy 243.486733 -395.481177)
			(xy 243.42543 -395.422726) (xy 243.36996 -395.358711) (xy 243.320827 -395.289714) (xy 243.278475 -395.216359)
			(xy 243.243287 -395.13931) (xy 243.215583 -395.059265) (xy 243.195613 -394.976949) (xy 243.183558 -394.893108)
			(xy 243.179528 -394.8085) (xy 2.509012 -394.8085) (xy 2.509012 -396.842996) (xy 18.90268 -396.842996)
			(xy 18.90268 -395.979396) (xy 18.903166 -395.952145) (xy 18.910922 -395.898197) (xy 18.926277 -395.845902)
			(xy 18.948919 -395.796325) (xy 18.978385 -395.750475) (xy 19.014076 -395.709284) (xy 19.055267 -395.673593)
			(xy 19.101117 -395.644127) (xy 19.150694 -395.621485) (xy 19.202989 -395.60613) (xy 19.256937 -395.598374)
			(xy 19.311439 -395.598374) (xy 19.365387 -395.60613) (xy 19.417682 -395.621485) (xy 19.467259 -395.644127)
			(xy 19.513109 -395.673593) (xy 19.5543 -395.709284) (xy 19.589991 -395.750475) (xy 19.601933 -395.769057)
			(xy 288.471858 -395.769057) (xy 288.471858 -395.705103) (xy 288.479873 -395.641653) (xy 288.495778 -395.579708)
			(xy 288.519321 -395.520246) (xy 288.550131 -395.464202) (xy 288.587723 -395.412462) (xy 288.631502 -395.365842)
			(xy 288.68078 -395.325076) (xy 288.734778 -395.290808) (xy 288.792645 -395.263577) (xy 288.853469 -395.243814)
			(xy 288.91629 -395.231831) (xy 288.980118 -395.227815) (xy 289.043946 -395.231831) (xy 289.106767 -395.243814)
			(xy 289.167591 -395.263577) (xy 289.225458 -395.290808) (xy 289.279456 -395.325076) (xy 289.328734 -395.365842)
			(xy 289.372513 -395.412462) (xy 289.410105 -395.464202) (xy 289.440915 -395.520246) (xy 289.464458 -395.579708)
			(xy 289.480363 -395.641653) (xy 289.488378 -395.705103) (xy 289.48888 -395.73708) (xy 289.488378 -395.769057)
			(xy 289.480363 -395.832507) (xy 289.464458 -395.894452) (xy 289.440915 -395.953914) (xy 289.410105 -396.009958)
			(xy 289.372513 -396.061698) (xy 289.328734 -396.108318) (xy 289.279456 -396.149084) (xy 289.225458 -396.183352)
			(xy 289.167591 -396.210583) (xy 289.106767 -396.230346) (xy 289.043946 -396.242329) (xy 288.980118 -396.246345)
			(xy 288.91629 -396.242329) (xy 288.853469 -396.230346) (xy 288.792645 -396.210583) (xy 288.734778 -396.183352)
			(xy 288.68078 -396.149084) (xy 288.631502 -396.108318) (xy 288.587723 -396.061698) (xy 288.550131 -396.009958)
			(xy 288.519321 -395.953914) (xy 288.495778 -395.894452) (xy 288.479873 -395.832507) (xy 288.471858 -395.769057)
			(xy 19.601933 -395.769057) (xy 19.619457 -395.796325) (xy 19.642099 -395.845902) (xy 19.657454 -395.898197)
			(xy 19.66521 -395.952145) (xy 19.665696 -395.979396) (xy 19.665696 -396.842996) (xy 19.66521 -396.870247)
			(xy 19.657454 -396.924195) (xy 19.642099 -396.97649) (xy 19.619457 -397.026067) (xy 19.589991 -397.071917)
			(xy 19.5543 -397.113108) (xy 19.513109 -397.148799) (xy 19.467259 -397.178265) (xy 19.417682 -397.200907)
			(xy 19.365387 -397.216262) (xy 19.311439 -397.224018) (xy 19.256937 -397.224018) (xy 19.202989 -397.216262)
			(xy 19.150694 -397.200907) (xy 19.101117 -397.178265) (xy 19.055267 -397.148799) (xy 19.014076 -397.113108)
			(xy 18.978385 -397.071917) (xy 18.948919 -397.026067) (xy 18.926277 -396.97649) (xy 18.910922 -396.924195)
			(xy 18.903166 -396.870247) (xy 18.90268 -396.842996) (xy 2.509012 -396.842996) (xy 2.509012 -397.606012)
			(xy 24.954992 -397.606012) (xy 24.954992 -396.742412) (xy 24.955478 -396.715161) (xy 24.963234 -396.661213)
			(xy 24.978589 -396.608918) (xy 25.001231 -396.559341) (xy 25.030697 -396.513491) (xy 25.066388 -396.4723)
			(xy 25.107579 -396.436609) (xy 25.153429 -396.407143) (xy 25.203006 -396.384501) (xy 25.255301 -396.369146)
			(xy 25.309249 -396.36139) (xy 25.363751 -396.36139) (xy 25.417699 -396.369146) (xy 25.469994 -396.384501)
			(xy 25.519571 -396.407143) (xy 25.565421 -396.436609) (xy 25.606612 -396.4723) (xy 25.642303 -396.513491)
			(xy 25.671769 -396.559341) (xy 25.694411 -396.608918) (xy 25.709766 -396.661213) (xy 25.717522 -396.715161)
			(xy 25.718008 -396.742412) (xy 25.718008 -397.606012) (xy 25.717522 -397.633263) (xy 25.709766 -397.687211)
			(xy 25.694411 -397.739506) (xy 25.671769 -397.789083) (xy 25.642303 -397.834933) (xy 25.606612 -397.876124)
			(xy 25.565421 -397.911815) (xy 25.519571 -397.941281) (xy 25.469994 -397.963923) (xy 25.417699 -397.979278)
			(xy 25.363751 -397.987034) (xy 25.309249 -397.987034) (xy 25.255301 -397.979278) (xy 25.203006 -397.963923)
			(xy 25.153429 -397.941281) (xy 25.107579 -397.911815) (xy 25.066388 -397.876124) (xy 25.030697 -397.834933)
			(xy 25.001231 -397.789083) (xy 24.978589 -397.739506) (xy 24.963234 -397.687211) (xy 24.955478 -397.633263)
			(xy 24.954992 -397.606012) (xy 2.509012 -397.606012) (xy 2.509012 -398.68657) (xy 36.781952 -398.68657)
			(xy 36.781952 -398.63203) (xy 36.789714 -398.578046) (xy 36.805081 -398.525717) (xy 36.827739 -398.476107)
			(xy 36.857227 -398.430227) (xy 36.892945 -398.389011) (xy 36.934165 -398.353298) (xy 36.980049 -398.323816)
			(xy 37.029662 -398.301164) (xy 37.081993 -398.285804) (xy 37.135978 -398.278048) (xy 37.163248 -398.277588)
			(xy 38.026848 -398.277588) (xy 38.054119 -398.277978) (xy 38.108104 -398.285746) (xy 38.160435 -398.301118)
			(xy 38.210045 -398.323779) (xy 38.255926 -398.353271) (xy 38.297144 -398.38899) (xy 38.332858 -398.430212)
			(xy 38.362344 -398.476097) (xy 38.384999 -398.52571) (xy 38.400364 -398.578043) (xy 38.408126 -398.632029)
			(xy 38.408126 -398.686571) (xy 38.400364 -398.740557) (xy 38.384999 -398.79289) (xy 38.38214 -398.799152)
			(xy 42.10455 -398.799152) (xy 42.10455 -398.744648) (xy 42.112306 -398.6907) (xy 42.12766 -398.638404)
			(xy 42.150301 -398.588826) (xy 42.179766 -398.542974) (xy 42.215456 -398.501781) (xy 42.256645 -398.466087)
			(xy 42.302494 -398.436618) (xy 42.35207 -398.413973) (xy 42.404365 -398.398614) (xy 42.458312 -398.390852)
			(xy 42.485564 -398.390364) (xy 43.349164 -398.390364) (xy 43.376417 -398.390881) (xy 43.430367 -398.398633)
			(xy 43.482666 -398.413985) (xy 43.532247 -398.436624) (xy 43.578101 -398.466088) (xy 43.619295 -398.50178)
			(xy 43.65499 -398.54297) (xy 43.684459 -398.588822) (xy 43.707103 -398.638401) (xy 43.722459 -398.690697)
			(xy 43.730217 -398.744648) (xy 43.730217 -398.799152) (xy 43.722459 -398.853103) (xy 43.707103 -398.9054)
			(xy 43.684459 -398.954978) (xy 43.65499 -399.00083) (xy 43.619295 -399.04202) (xy 43.578101 -399.077712)
			(xy 43.532247 -399.107176) (xy 43.482666 -399.129815) (xy 43.430367 -399.145167) (xy 43.376417 -399.152919)
			(xy 43.349164 -399.15338) (xy 42.485564 -399.15338) (xy 42.458312 -399.152948) (xy 42.404365 -399.145186)
			(xy 42.35207 -399.129827) (xy 42.302494 -399.107182) (xy 42.256645 -399.077713) (xy 42.215456 -399.042019)
			(xy 42.179766 -399.000826) (xy 42.150301 -398.954974) (xy 42.12766 -398.905396) (xy 42.112306 -398.8531)
			(xy 42.10455 -398.799152) (xy 38.38214 -398.799152) (xy 38.362344 -398.842503) (xy 38.332858 -398.888388)
			(xy 38.297144 -398.92961) (xy 38.255926 -398.965329) (xy 38.210045 -398.994821) (xy 38.160435 -399.017482)
			(xy 38.108104 -399.032854) (xy 38.054119 -399.040622) (xy 38.026848 -399.041112) (xy 37.163248 -399.041112)
			(xy 37.135978 -399.040552) (xy 37.081993 -399.032796) (xy 37.029662 -399.017436) (xy 36.980049 -398.994784)
			(xy 36.934165 -398.965302) (xy 36.892945 -398.929589) (xy 36.857227 -398.888373) (xy 36.827739 -398.842493)
			(xy 36.805081 -398.792883) (xy 36.789714 -398.740554) (xy 36.781952 -398.68657) (xy 2.509012 -398.68657)
			(xy 2.509012 -399.443249) (xy 18.470394 -399.443249) (xy 18.470394 -399.388751) (xy 18.47815 -399.334808)
			(xy 18.493503 -399.282518) (xy 18.516141 -399.232945) (xy 18.545603 -399.187098) (xy 18.58129 -399.14591)
			(xy 18.622475 -399.11022) (xy 18.66832 -399.080754) (xy 18.717892 -399.058112) (xy 18.770181 -399.042756)
			(xy 18.824123 -399.034996) (xy 18.851372 -399.034508) (xy 19.714972 -399.034508) (xy 19.742227 -399.034937)
			(xy 19.796184 -399.042691) (xy 19.848487 -399.058045) (xy 19.898073 -399.080687) (xy 19.943931 -399.110156)
			(xy 19.985129 -399.145851) (xy 20.020827 -399.187046) (xy 20.050299 -399.232903) (xy 20.072945 -399.282487)
			(xy 20.088303 -399.334789) (xy 20.096061 -399.388745) (xy 20.096061 -399.443255) (xy 20.088303 -399.497211)
			(xy 20.072945 -399.549513) (xy 20.050299 -399.599097) (xy 20.020828 -399.644954) (xy 19.985129 -399.686149)
			(xy 19.943931 -399.721844) (xy 19.898073 -399.751313) (xy 19.848487 -399.773955) (xy 19.796184 -399.789309)
			(xy 19.742227 -399.797063) (xy 19.714972 -399.797524) (xy 18.851372 -399.797524) (xy 18.824123 -399.797004)
			(xy 18.770181 -399.789244) (xy 18.717892 -399.773888) (xy 18.66832 -399.751246) (xy 18.622475 -399.72178)
			(xy 18.58129 -399.68609) (xy 18.545603 -399.644902) (xy 18.516141 -399.599055) (xy 18.493503 -399.549482)
			(xy 18.47815 -399.497192) (xy 18.470394 -399.443249) (xy 2.509012 -399.443249) (xy 2.509012 -400.459248)
			(xy 25.590794 -400.459248) (xy 25.590794 -400.404752) (xy 25.598549 -400.350811) (xy 25.613901 -400.298522)
			(xy 25.636538 -400.24895) (xy 25.665999 -400.203104) (xy 25.701684 -400.161916) (xy 25.742867 -400.126226)
			(xy 25.788709 -400.09676) (xy 25.838279 -400.074117) (xy 25.890566 -400.058759) (xy 25.944506 -400.050997)
			(xy 25.971754 -400.050508) (xy 26.835354 -400.050508) (xy 26.86261 -400.050936) (xy 26.916568 -400.058688)
			(xy 26.968874 -400.07404) (xy 27.018462 -400.096681) (xy 27.064323 -400.126149) (xy 27.105523 -400.161845)
			(xy 27.141223 -400.20304) (xy 27.170697 -400.248897) (xy 27.193343 -400.298483) (xy 27.208702 -400.350787)
			(xy 27.216461 -400.404744) (xy 27.216461 -400.459256) (xy 27.208702 -400.513213) (xy 27.193343 -400.565517)
			(xy 27.170697 -400.615103) (xy 27.141223 -400.66096) (xy 27.105523 -400.702155) (xy 27.064323 -400.737851)
			(xy 27.018462 -400.767319) (xy 26.968874 -400.78996) (xy 26.916568 -400.805312) (xy 26.86261 -400.813064)
			(xy 26.835354 -400.813524) (xy 25.971754 -400.813524) (xy 25.944506 -400.813003) (xy 25.890566 -400.805241)
			(xy 25.838279 -400.789883) (xy 25.788709 -400.76724) (xy 25.742867 -400.737774) (xy 25.701684 -400.702084)
			(xy 25.665999 -400.660896) (xy 25.636538 -400.61505) (xy 25.613901 -400.565478) (xy 25.598549 -400.513189)
			(xy 25.590794 -400.459248) (xy 2.509012 -400.459248) (xy 2.509012 -400.885453) (xy 47.598783 -400.885453)
			(xy 47.598783 -400.830947) (xy 47.606541 -400.776997) (xy 47.621898 -400.7247) (xy 47.644541 -400.675121)
			(xy 47.674011 -400.629269) (xy 47.709706 -400.588079) (xy 47.7509 -400.552388) (xy 47.796754 -400.522923)
			(xy 47.846336 -400.500284) (xy 47.898634 -400.484933) (xy 47.952585 -400.477181) (xy 47.979838 -400.47672)
			(xy 48.843438 -400.47672) (xy 48.870689 -400.477152) (xy 48.924637 -400.484914) (xy 48.976931 -400.500273)
			(xy 49.026507 -400.522918) (xy 49.072356 -400.552388) (xy 49.113545 -400.588082) (xy 49.149235 -400.629274)
			(xy 49.1787 -400.675126) (xy 49.20134 -400.724705) (xy 49.216694 -400.777) (xy 49.22445 -400.830948)
			(xy 49.22445 -400.885448) (xy 50.662106 -400.885448) (xy 50.662106 -400.830952) (xy 50.669862 -400.77701)
			(xy 50.685214 -400.724721) (xy 50.707852 -400.675149) (xy 50.737314 -400.629303) (xy 50.773001 -400.588116)
			(xy 50.814185 -400.552427) (xy 50.86003 -400.522963) (xy 50.9096 -400.500322) (xy 50.961888 -400.484966)
			(xy 51.01583 -400.477208) (xy 51.043078 -400.47672) (xy 51.906678 -400.47672) (xy 51.933934 -400.477125)
			(xy 51.987891 -400.48488) (xy 52.040196 -400.500236) (xy 52.089782 -400.522879) (xy 52.135642 -400.552348)
			(xy 52.17684 -400.588045) (xy 52.212539 -400.629241) (xy 52.242011 -400.675098) (xy 52.264657 -400.724684)
			(xy 52.280015 -400.776987) (xy 52.287773 -400.830944) (xy 52.287773 -400.885452) (xy 53.725283 -400.885452)
			(xy 53.725283 -400.830948) (xy 53.73304 -400.777) (xy 53.748396 -400.724704) (xy 53.771038 -400.675127)
			(xy 53.800506 -400.629276) (xy 53.836199 -400.588086) (xy 53.87739 -400.552395) (xy 53.923242 -400.52293)
			(xy 53.972821 -400.50029) (xy 54.025117 -400.484936) (xy 54.079066 -400.477182) (xy 54.106318 -400.47672)
			(xy 54.969918 -400.47672) (xy 54.99717 -400.477151) (xy 55.05112 -400.48491) (xy 55.103417 -400.500268)
			(xy 55.152995 -400.522912) (xy 55.198847 -400.552381) (xy 55.240038 -400.588075) (xy 55.27573 -400.629268)
			(xy 55.305197 -400.675121) (xy 55.327838 -400.7247) (xy 55.343194 -400.776997) (xy 55.35095 -400.830948)
			(xy 55.35095 -400.885447) (xy 56.788606 -400.885447) (xy 56.788606 -400.830953) (xy 56.796361 -400.777013)
			(xy 56.811713 -400.724725) (xy 56.834349 -400.675154) (xy 56.863809 -400.629309) (xy 56.899494 -400.588123)
			(xy 56.940676 -400.552435) (xy 56.986518 -400.522969) (xy 57.036086 -400.500327) (xy 57.088372 -400.48497)
			(xy 57.142311 -400.477209) (xy 57.169558 -400.47672) (xy 58.033158 -400.47672) (xy 58.060415 -400.477124)
			(xy 58.114374 -400.484877) (xy 58.166681 -400.50023) (xy 58.21627 -400.522872) (xy 58.262132 -400.552341)
			(xy 58.303333 -400.588037) (xy 58.339034 -400.629234) (xy 58.368508 -400.675093) (xy 58.391155 -400.724679)
			(xy 58.406514 -400.776985) (xy 58.414273 -400.830943) (xy 58.414273 -400.885449) (xy 59.851806 -400.885449)
			(xy 59.851806 -400.830951) (xy 59.859562 -400.777007) (xy 59.874916 -400.724717) (xy 59.897555 -400.675143)
			(xy 59.927019 -400.629296) (xy 59.962708 -400.588109) (xy 60.003895 -400.55242) (xy 60.049742 -400.522956)
			(xy 60.099315 -400.500317) (xy 60.151605 -400.484963) (xy 60.205549 -400.477206) (xy 60.232798 -400.47672)
			(xy 61.096398 -400.47672) (xy 61.123653 -400.477127) (xy 61.177608 -400.484884) (xy 61.22991 -400.500241)
			(xy 61.279494 -400.522885) (xy 61.325351 -400.552355) (xy 61.366547 -400.588052) (xy 61.402243 -400.629247)
			(xy 61.431714 -400.675104) (xy 61.454358 -400.724688) (xy 61.469715 -400.77699) (xy 61.477473 -400.830945)
			(xy 61.477473 -400.885453) (xy 62.914983 -400.885453) (xy 62.914983 -400.830947) (xy 62.922741 -400.776997)
			(xy 62.938098 -400.7247) (xy 62.960741 -400.675121) (xy 62.990211 -400.629269) (xy 63.025906 -400.588079)
			(xy 63.0671 -400.552388) (xy 63.112954 -400.522923) (xy 63.162536 -400.500284) (xy 63.214834 -400.484933)
			(xy 63.268785 -400.477181) (xy 63.296038 -400.47672) (xy 64.159638 -400.47672) (xy 64.186889 -400.477152)
			(xy 64.240837 -400.484914) (xy 64.293131 -400.500273) (xy 64.342707 -400.522918) (xy 64.388556 -400.552388)
			(xy 64.429745 -400.588082) (xy 64.465435 -400.629274) (xy 64.4949 -400.675126) (xy 64.51754 -400.724705)
			(xy 64.532894 -400.777) (xy 64.54065 -400.830948) (xy 64.54065 -400.885448) (xy 65.978306 -400.885448)
			(xy 65.978306 -400.830952) (xy 65.986062 -400.77701) (xy 66.001414 -400.724721) (xy 66.024052 -400.675149)
			(xy 66.053514 -400.629303) (xy 66.089201 -400.588116) (xy 66.130385 -400.552427) (xy 66.17623 -400.522963)
			(xy 66.2258 -400.500322) (xy 66.278088 -400.484966) (xy 66.33203 -400.477208) (xy 66.359278 -400.47672)
			(xy 67.222878 -400.47672) (xy 67.250134 -400.477125) (xy 67.304091 -400.48488) (xy 67.356396 -400.500236)
			(xy 67.405982 -400.522879) (xy 67.451842 -400.552348) (xy 67.49304 -400.588045) (xy 67.528739 -400.629241)
			(xy 67.558211 -400.675098) (xy 67.580857 -400.724684) (xy 67.596215 -400.776987) (xy 67.603973 -400.830944)
			(xy 67.603973 -400.885452) (xy 69.041483 -400.885452) (xy 69.041483 -400.830948) (xy 69.04924 -400.777)
			(xy 69.064596 -400.724704) (xy 69.087238 -400.675127) (xy 69.116706 -400.629276) (xy 69.152399 -400.588086)
			(xy 69.19359 -400.552395) (xy 69.239442 -400.52293) (xy 69.289021 -400.50029) (xy 69.341317 -400.484936)
			(xy 69.395266 -400.477182) (xy 69.422518 -400.47672) (xy 70.286118 -400.47672) (xy 70.31337 -400.477151)
			(xy 70.36732 -400.48491) (xy 70.419617 -400.500268) (xy 70.469195 -400.522912) (xy 70.515047 -400.552381)
			(xy 70.556238 -400.588075) (xy 70.59193 -400.629268) (xy 70.621397 -400.675121) (xy 70.644038 -400.7247)
			(xy 70.659394 -400.776997) (xy 70.66715 -400.830948) (xy 70.66715 -400.885447) (xy 72.104806 -400.885447)
			(xy 72.104806 -400.830953) (xy 72.112561 -400.777013) (xy 72.127913 -400.724725) (xy 72.150549 -400.675154)
			(xy 72.180009 -400.629309) (xy 72.215694 -400.588123) (xy 72.256876 -400.552435) (xy 72.302718 -400.522969)
			(xy 72.352286 -400.500327) (xy 72.404572 -400.48497) (xy 72.458511 -400.477209) (xy 72.485758 -400.47672)
			(xy 73.349358 -400.47672) (xy 73.376615 -400.477124) (xy 73.430574 -400.484877) (xy 73.482881 -400.50023)
			(xy 73.53247 -400.522872) (xy 73.578332 -400.552341) (xy 73.619533 -400.588037) (xy 73.655234 -400.629234)
			(xy 73.684708 -400.675093) (xy 73.707355 -400.724679) (xy 73.722714 -400.776985) (xy 73.730473 -400.830943)
			(xy 73.730473 -400.885449) (xy 75.168006 -400.885449) (xy 75.168006 -400.830951) (xy 75.175762 -400.777007)
			(xy 75.191116 -400.724717) (xy 75.213755 -400.675143) (xy 75.243219 -400.629296) (xy 75.278908 -400.588109)
			(xy 75.320095 -400.55242) (xy 75.365942 -400.522956) (xy 75.415515 -400.500317) (xy 75.467805 -400.484963)
			(xy 75.521749 -400.477206) (xy 75.548998 -400.47672) (xy 76.412598 -400.47672) (xy 76.439853 -400.477127)
			(xy 76.493808 -400.484884) (xy 76.54611 -400.500241) (xy 76.595694 -400.522885) (xy 76.641551 -400.552355)
			(xy 76.682747 -400.588052) (xy 76.718443 -400.629247) (xy 76.747914 -400.675104) (xy 76.770558 -400.724688)
			(xy 76.785915 -400.77699) (xy 76.793673 -400.830945) (xy 76.793673 -400.885453) (xy 78.231183 -400.885453)
			(xy 78.231183 -400.830947) (xy 78.238941 -400.776997) (xy 78.254298 -400.7247) (xy 78.276941 -400.675121)
			(xy 78.306411 -400.629269) (xy 78.342106 -400.588079) (xy 78.3833 -400.552388) (xy 78.429154 -400.522923)
			(xy 78.478736 -400.500284) (xy 78.531034 -400.484933) (xy 78.584985 -400.477181) (xy 78.612238 -400.47672)
			(xy 79.475838 -400.47672) (xy 79.503089 -400.477152) (xy 79.557037 -400.484914) (xy 79.609331 -400.500273)
			(xy 79.658907 -400.522918) (xy 79.704756 -400.552388) (xy 79.745945 -400.588082) (xy 79.781635 -400.629274)
			(xy 79.8111 -400.675126) (xy 79.83374 -400.724705) (xy 79.849094 -400.777) (xy 79.85685 -400.830948)
			(xy 79.85685 -400.885448) (xy 81.294506 -400.885448) (xy 81.294506 -400.830952) (xy 81.302262 -400.77701)
			(xy 81.317614 -400.724721) (xy 81.340252 -400.675149) (xy 81.369714 -400.629303) (xy 81.405401 -400.588116)
			(xy 81.446585 -400.552427) (xy 81.49243 -400.522963) (xy 81.542 -400.500322) (xy 81.594288 -400.484966)
			(xy 81.64823 -400.477208) (xy 81.675478 -400.47672) (xy 82.539078 -400.47672) (xy 82.566334 -400.477125)
			(xy 82.620291 -400.48488) (xy 82.672596 -400.500236) (xy 82.722182 -400.522879) (xy 82.768042 -400.552348)
			(xy 82.80924 -400.588045) (xy 82.844939 -400.629241) (xy 82.874411 -400.675098) (xy 82.897057 -400.724684)
			(xy 82.912415 -400.776987) (xy 82.920173 -400.830944) (xy 82.920173 -400.885452) (xy 84.357683 -400.885452)
			(xy 84.357683 -400.830948) (xy 84.36544 -400.777) (xy 84.380796 -400.724704) (xy 84.403438 -400.675127)
			(xy 84.432906 -400.629276) (xy 84.468599 -400.588086) (xy 84.50979 -400.552395) (xy 84.555642 -400.52293)
			(xy 84.605221 -400.50029) (xy 84.657517 -400.484936) (xy 84.711466 -400.477182) (xy 84.738718 -400.47672)
			(xy 85.602318 -400.47672) (xy 85.62957 -400.477151) (xy 85.68352 -400.48491) (xy 85.735817 -400.500268)
			(xy 85.785395 -400.522912) (xy 85.831247 -400.552381) (xy 85.872438 -400.588075) (xy 85.90813 -400.629268)
			(xy 85.937597 -400.675121) (xy 85.960238 -400.7247) (xy 85.975594 -400.776997) (xy 85.98335 -400.830948)
			(xy 85.98335 -400.885447) (xy 87.421006 -400.885447) (xy 87.421006 -400.830953) (xy 87.428761 -400.777013)
			(xy 87.444113 -400.724725) (xy 87.466749 -400.675154) (xy 87.496209 -400.629309) (xy 87.531894 -400.588123)
			(xy 87.573076 -400.552435) (xy 87.618918 -400.522969) (xy 87.668486 -400.500327) (xy 87.720772 -400.48497)
			(xy 87.774711 -400.477209) (xy 87.801958 -400.47672) (xy 88.665558 -400.47672) (xy 88.692815 -400.477124)
			(xy 88.746774 -400.484877) (xy 88.799081 -400.50023) (xy 88.84867 -400.522872) (xy 88.894532 -400.552341)
			(xy 88.935733 -400.588037) (xy 88.971434 -400.629234) (xy 89.000908 -400.675093) (xy 89.023555 -400.724679)
			(xy 89.038914 -400.776985) (xy 89.046673 -400.830943) (xy 89.046673 -400.885449) (xy 90.484206 -400.885449)
			(xy 90.484206 -400.830951) (xy 90.491962 -400.777007) (xy 90.507316 -400.724717) (xy 90.529955 -400.675143)
			(xy 90.559419 -400.629296) (xy 90.595108 -400.588109) (xy 90.636295 -400.55242) (xy 90.682142 -400.522956)
			(xy 90.731715 -400.500317) (xy 90.784005 -400.484963) (xy 90.837949 -400.477206) (xy 90.865198 -400.47672)
			(xy 91.728798 -400.47672) (xy 91.756053 -400.477127) (xy 91.810008 -400.484884) (xy 91.86231 -400.500241)
			(xy 91.911894 -400.522885) (xy 91.957751 -400.552355) (xy 91.998947 -400.588052) (xy 92.034643 -400.629247)
			(xy 92.064114 -400.675104) (xy 92.086758 -400.724688) (xy 92.102115 -400.77699) (xy 92.109873 -400.830945)
			(xy 92.109873 -400.885453) (xy 93.547383 -400.885453) (xy 93.547383 -400.830947) (xy 93.555141 -400.776997)
			(xy 93.570498 -400.7247) (xy 93.593141 -400.675121) (xy 93.622611 -400.629269) (xy 93.658306 -400.588079)
			(xy 93.6995 -400.552388) (xy 93.745354 -400.522923) (xy 93.794936 -400.500284) (xy 93.847234 -400.484933)
			(xy 93.901185 -400.477181) (xy 93.928438 -400.47672) (xy 94.792038 -400.47672) (xy 94.819289 -400.477152)
			(xy 94.873237 -400.484914) (xy 94.925531 -400.500273) (xy 94.975107 -400.522918) (xy 95.020956 -400.552388)
			(xy 95.062145 -400.588082) (xy 95.097835 -400.629274) (xy 95.1273 -400.675126) (xy 95.14994 -400.724705)
			(xy 95.165294 -400.777) (xy 95.17305 -400.830948) (xy 95.17305 -400.885447) (xy 119.774006 -400.885447)
			(xy 119.774006 -400.830953) (xy 119.781761 -400.777013) (xy 119.797112 -400.724726) (xy 119.819749 -400.675156)
			(xy 119.849208 -400.629311) (xy 119.884892 -400.588125) (xy 119.926074 -400.552436) (xy 119.971915 -400.522971)
			(xy 120.021483 -400.500329) (xy 120.073768 -400.484971) (xy 120.127707 -400.477209) (xy 120.154954 -400.47672)
			(xy 121.018554 -400.47672) (xy 121.045811 -400.477124) (xy 121.099771 -400.484876) (xy 121.152078 -400.500229)
			(xy 121.201668 -400.522871) (xy 121.24753 -400.55234) (xy 121.288731 -400.588036) (xy 121.324433 -400.629233)
			(xy 121.353907 -400.675092) (xy 121.376555 -400.724679) (xy 121.391914 -400.776984) (xy 121.399673 -400.830943)
			(xy 121.399673 -400.885449) (xy 122.837206 -400.885449) (xy 122.837206 -400.830951) (xy 122.844962 -400.777008)
			(xy 122.860316 -400.724717) (xy 122.882955 -400.675144) (xy 122.912418 -400.629298) (xy 122.948106 -400.588111)
			(xy 122.989293 -400.552422) (xy 123.035139 -400.522958) (xy 123.084712 -400.500318) (xy 123.137002 -400.484963)
			(xy 123.190945 -400.477207) (xy 123.218194 -400.47672) (xy 124.081794 -400.47672) (xy 124.109049 -400.477127)
			(xy 124.163005 -400.484883) (xy 124.215307 -400.50024) (xy 124.264892 -400.522884) (xy 124.310749 -400.552354)
			(xy 124.351946 -400.58805) (xy 124.387643 -400.629246) (xy 124.417113 -400.675103) (xy 124.439758 -400.724687)
			(xy 124.455115 -400.776989) (xy 124.462873 -400.830945) (xy 124.462873 -400.885452) (xy 125.900383 -400.885452)
			(xy 125.900383 -400.830948) (xy 125.908141 -400.776998) (xy 125.923497 -400.724701) (xy 125.946141 -400.675122)
			(xy 125.97561 -400.629271) (xy 126.011304 -400.58808) (xy 126.052498 -400.552389) (xy 126.098352 -400.522924)
			(xy 126.147933 -400.500285) (xy 126.200231 -400.484933) (xy 126.254182 -400.477181) (xy 126.281434 -400.47672)
			(xy 127.145034 -400.47672) (xy 127.172286 -400.477152) (xy 127.226234 -400.484913) (xy 127.278528 -400.500272)
			(xy 127.328105 -400.522917) (xy 127.373954 -400.552386) (xy 127.415143 -400.588081) (xy 127.450834 -400.629273)
			(xy 127.480299 -400.675125) (xy 127.50294 -400.724704) (xy 127.518294 -400.777) (xy 127.52605 -400.830948)
			(xy 127.52605 -400.885448) (xy 128.963706 -400.885448) (xy 128.963706 -400.830952) (xy 128.971461 -400.777011)
			(xy 128.986814 -400.724722) (xy 129.009452 -400.67515) (xy 129.038913 -400.629304) (xy 129.074599 -400.588118)
			(xy 129.115783 -400.552429) (xy 129.161627 -400.522964) (xy 129.211197 -400.500323) (xy 129.263485 -400.484967)
			(xy 129.317426 -400.477208) (xy 129.344674 -400.47672) (xy 130.208274 -400.47672) (xy 130.23553 -400.477125)
			(xy 130.289488 -400.48488) (xy 130.341793 -400.500235) (xy 130.39138 -400.522877) (xy 130.43724 -400.552347)
			(xy 130.478438 -400.588043) (xy 130.514138 -400.62924) (xy 130.54361 -400.675097) (xy 130.566256 -400.724683)
			(xy 130.581615 -400.776987) (xy 130.589373 -400.830944) (xy 130.589373 -400.885451) (xy 132.026883 -400.885451)
			(xy 132.026883 -400.830949) (xy 132.03464 -400.777) (xy 132.049996 -400.724705) (xy 132.072638 -400.675128)
			(xy 132.102105 -400.629277) (xy 132.137797 -400.588087) (xy 132.178989 -400.552396) (xy 132.22484 -400.522931)
			(xy 132.274418 -400.500291) (xy 132.326714 -400.484937) (xy 132.380662 -400.477182) (xy 132.407914 -400.47672)
			(xy 133.271514 -400.47672) (xy 133.298767 -400.477151) (xy 133.352717 -400.48491) (xy 133.405014 -400.500267)
			(xy 133.454593 -400.522911) (xy 133.500445 -400.552379) (xy 133.541636 -400.588074) (xy 133.577329 -400.629266)
			(xy 133.606796 -400.67512) (xy 133.629438 -400.724699) (xy 133.644793 -400.776997) (xy 133.65255 -400.830947)
			(xy 133.65255 -400.885447) (xy 135.090206 -400.885447) (xy 135.090206 -400.830953) (xy 135.097961 -400.777013)
			(xy 135.113312 -400.724726) (xy 135.135949 -400.675156) (xy 135.165408 -400.629311) (xy 135.201092 -400.588125)
			(xy 135.242274 -400.552436) (xy 135.288115 -400.522971) (xy 135.337683 -400.500329) (xy 135.389968 -400.484971)
			(xy 135.443907 -400.477209) (xy 135.471154 -400.47672) (xy 136.334754 -400.47672) (xy 136.362011 -400.477124)
			(xy 136.415971 -400.484876) (xy 136.468278 -400.500229) (xy 136.517868 -400.522871) (xy 136.56373 -400.55234)
			(xy 136.604931 -400.588036) (xy 136.640633 -400.629233) (xy 136.670107 -400.675092) (xy 136.692755 -400.724679)
			(xy 136.708114 -400.776984) (xy 136.715873 -400.830943) (xy 136.715873 -400.885449) (xy 138.153406 -400.885449)
			(xy 138.153406 -400.830951) (xy 138.161162 -400.777008) (xy 138.176516 -400.724717) (xy 138.199155 -400.675144)
			(xy 138.228618 -400.629298) (xy 138.264306 -400.588111) (xy 138.305493 -400.552422) (xy 138.351339 -400.522958)
			(xy 138.400912 -400.500318) (xy 138.453202 -400.484963) (xy 138.507145 -400.477207) (xy 138.534394 -400.47672)
			(xy 139.397994 -400.47672) (xy 139.425249 -400.477127) (xy 139.479205 -400.484883) (xy 139.531507 -400.50024)
			(xy 139.581092 -400.522884) (xy 139.626949 -400.552354) (xy 139.668146 -400.58805) (xy 139.703843 -400.629246)
			(xy 139.733313 -400.675103) (xy 139.755958 -400.724687) (xy 139.771315 -400.776989) (xy 139.779073 -400.830945)
			(xy 139.779073 -400.885452) (xy 141.216583 -400.885452) (xy 141.216583 -400.830948) (xy 141.224341 -400.776998)
			(xy 141.239697 -400.724701) (xy 141.262341 -400.675122) (xy 141.29181 -400.629271) (xy 141.327504 -400.58808)
			(xy 141.368698 -400.552389) (xy 141.414552 -400.522924) (xy 141.464133 -400.500285) (xy 141.516431 -400.484933)
			(xy 141.570382 -400.477181) (xy 141.597634 -400.47672) (xy 142.461234 -400.47672) (xy 142.488486 -400.477152)
			(xy 142.542434 -400.484913) (xy 142.594728 -400.500272) (xy 142.644305 -400.522917) (xy 142.690154 -400.552386)
			(xy 142.731343 -400.588081) (xy 142.767034 -400.629273) (xy 142.796499 -400.675125) (xy 142.81914 -400.724704)
			(xy 142.834494 -400.777) (xy 142.84225 -400.830948) (xy 142.84225 -400.885448) (xy 144.279906 -400.885448)
			(xy 144.279906 -400.830952) (xy 144.287661 -400.777011) (xy 144.303014 -400.724722) (xy 144.325652 -400.67515)
			(xy 144.355113 -400.629304) (xy 144.390799 -400.588118) (xy 144.431983 -400.552429) (xy 144.477827 -400.522964)
			(xy 144.527397 -400.500323) (xy 144.579685 -400.484967) (xy 144.633626 -400.477208) (xy 144.660874 -400.47672)
			(xy 145.524474 -400.47672) (xy 145.55173 -400.477125) (xy 145.605688 -400.48488) (xy 145.657993 -400.500235)
			(xy 145.70758 -400.522877) (xy 145.75344 -400.552347) (xy 145.794638 -400.588043) (xy 145.830338 -400.62924)
			(xy 145.85981 -400.675097) (xy 145.882456 -400.724683) (xy 145.897815 -400.776987) (xy 145.905573 -400.830944)
			(xy 145.905573 -400.885451) (xy 147.343083 -400.885451) (xy 147.343083 -400.830949) (xy 147.35084 -400.777)
			(xy 147.366196 -400.724705) (xy 147.388838 -400.675128) (xy 147.418305 -400.629277) (xy 147.453997 -400.588087)
			(xy 147.495189 -400.552396) (xy 147.54104 -400.522931) (xy 147.590618 -400.500291) (xy 147.642914 -400.484937)
			(xy 147.696862 -400.477182) (xy 147.724114 -400.47672) (xy 148.587714 -400.47672) (xy 148.614967 -400.477151)
			(xy 148.668917 -400.48491) (xy 148.721214 -400.500267) (xy 148.770793 -400.522911) (xy 148.816645 -400.552379)
			(xy 148.857836 -400.588074) (xy 148.893529 -400.629266) (xy 148.922996 -400.67512) (xy 148.945638 -400.724699)
			(xy 148.960993 -400.776997) (xy 148.96875 -400.830947) (xy 148.96875 -400.885447) (xy 150.406406 -400.885447)
			(xy 150.406406 -400.830953) (xy 150.414161 -400.777013) (xy 150.429512 -400.724726) (xy 150.452149 -400.675156)
			(xy 150.481608 -400.629311) (xy 150.517292 -400.588125) (xy 150.558474 -400.552436) (xy 150.604315 -400.522971)
			(xy 150.653883 -400.500329) (xy 150.706168 -400.484971) (xy 150.760107 -400.477209) (xy 150.787354 -400.47672)
			(xy 151.650954 -400.47672) (xy 151.678211 -400.477124) (xy 151.732171 -400.484876) (xy 151.784478 -400.500229)
			(xy 151.834068 -400.522871) (xy 151.87993 -400.55234) (xy 151.921131 -400.588036) (xy 151.956833 -400.629233)
			(xy 151.986307 -400.675092) (xy 152.008955 -400.724679) (xy 152.024314 -400.776984) (xy 152.032073 -400.830943)
			(xy 152.032073 -400.885449) (xy 153.469606 -400.885449) (xy 153.469606 -400.830951) (xy 153.477362 -400.777008)
			(xy 153.492716 -400.724717) (xy 153.515355 -400.675144) (xy 153.544818 -400.629298) (xy 153.580506 -400.588111)
			(xy 153.621693 -400.552422) (xy 153.667539 -400.522958) (xy 153.717112 -400.500318) (xy 153.769402 -400.484963)
			(xy 153.823345 -400.477207) (xy 153.850594 -400.47672) (xy 154.714194 -400.47672) (xy 154.741449 -400.477127)
			(xy 154.795405 -400.484883) (xy 154.847707 -400.50024) (xy 154.897292 -400.522884) (xy 154.943149 -400.552354)
			(xy 154.984346 -400.58805) (xy 155.020043 -400.629246) (xy 155.049513 -400.675103) (xy 155.072158 -400.724687)
			(xy 155.087515 -400.776989) (xy 155.095273 -400.830945) (xy 155.095273 -400.885452) (xy 156.532783 -400.885452)
			(xy 156.532783 -400.830948) (xy 156.540541 -400.776998) (xy 156.555897 -400.724701) (xy 156.578541 -400.675122)
			(xy 156.60801 -400.629271) (xy 156.643704 -400.58808) (xy 156.684898 -400.552389) (xy 156.730752 -400.522924)
			(xy 156.780333 -400.500285) (xy 156.832631 -400.484933) (xy 156.886582 -400.477181) (xy 156.913834 -400.47672)
			(xy 157.777434 -400.47672) (xy 157.804686 -400.477152) (xy 157.858634 -400.484913) (xy 157.910928 -400.500272)
			(xy 157.960505 -400.522917) (xy 158.006354 -400.552386) (xy 158.047543 -400.588081) (xy 158.083234 -400.629273)
			(xy 158.112699 -400.675125) (xy 158.13534 -400.724704) (xy 158.150694 -400.777) (xy 158.15845 -400.830948)
			(xy 158.15845 -400.885448) (xy 159.596106 -400.885448) (xy 159.596106 -400.830952) (xy 159.603861 -400.777011)
			(xy 159.619214 -400.724722) (xy 159.641852 -400.67515) (xy 159.671313 -400.629304) (xy 159.706999 -400.588118)
			(xy 159.748183 -400.552429) (xy 159.794027 -400.522964) (xy 159.843597 -400.500323) (xy 159.895885 -400.484967)
			(xy 159.949826 -400.477208) (xy 159.977074 -400.47672) (xy 160.840674 -400.47672) (xy 160.86793 -400.477125)
			(xy 160.921888 -400.48488) (xy 160.974193 -400.500235) (xy 161.02378 -400.522877) (xy 161.06964 -400.552347)
			(xy 161.110838 -400.588043) (xy 161.146538 -400.62924) (xy 161.17601 -400.675097) (xy 161.198656 -400.724683)
			(xy 161.214015 -400.776987) (xy 161.221773 -400.830944) (xy 161.221773 -400.885451) (xy 162.659283 -400.885451)
			(xy 162.659283 -400.830949) (xy 162.66704 -400.777) (xy 162.682396 -400.724705) (xy 162.705038 -400.675128)
			(xy 162.734505 -400.629277) (xy 162.770197 -400.588087) (xy 162.811389 -400.552396) (xy 162.85724 -400.522931)
			(xy 162.906818 -400.500291) (xy 162.959114 -400.484937) (xy 163.013062 -400.477182) (xy 163.040314 -400.47672)
			(xy 163.903914 -400.47672) (xy 163.931167 -400.477151) (xy 163.985117 -400.48491) (xy 164.037414 -400.500267)
			(xy 164.086993 -400.522911) (xy 164.132845 -400.552379) (xy 164.174036 -400.588074) (xy 164.209729 -400.629266)
			(xy 164.239196 -400.67512) (xy 164.261838 -400.724699) (xy 164.277193 -400.776997) (xy 164.28495 -400.830947)
			(xy 164.28495 -400.885447) (xy 165.722606 -400.885447) (xy 165.722606 -400.830953) (xy 165.730361 -400.777013)
			(xy 165.745712 -400.724726) (xy 165.768349 -400.675156) (xy 165.797808 -400.629311) (xy 165.833492 -400.588125)
			(xy 165.874674 -400.552436) (xy 165.920515 -400.522971) (xy 165.970083 -400.500329) (xy 166.022368 -400.484971)
			(xy 166.076307 -400.477209) (xy 166.103554 -400.47672) (xy 166.967154 -400.47672) (xy 166.994411 -400.477124)
			(xy 167.048371 -400.484876) (xy 167.100678 -400.500229) (xy 167.150268 -400.522871) (xy 167.19613 -400.55234)
			(xy 167.237331 -400.588036) (xy 167.273033 -400.629233) (xy 167.302507 -400.675092) (xy 167.325155 -400.724679)
			(xy 167.340514 -400.776984) (xy 167.348273 -400.830943) (xy 167.348273 -400.885457) (xy 167.340514 -400.939416)
			(xy 167.325155 -400.991721) (xy 167.302507 -401.041308) (xy 167.273033 -401.087167) (xy 167.237331 -401.128364)
			(xy 167.19613 -401.16406) (xy 167.150268 -401.193529) (xy 167.100678 -401.216171) (xy 167.048371 -401.231524)
			(xy 166.994411 -401.239276) (xy 166.967154 -401.239736) (xy 166.103554 -401.239736) (xy 166.076307 -401.239191)
			(xy 166.022368 -401.231429) (xy 165.970083 -401.216071) (xy 165.920515 -401.193429) (xy 165.874674 -401.163964)
			(xy 165.833492 -401.128275) (xy 165.797808 -401.087089) (xy 165.768349 -401.041244) (xy 165.745712 -400.991674)
			(xy 165.730361 -400.939387) (xy 165.722606 -400.885447) (xy 164.28495 -400.885447) (xy 164.28495 -400.885453)
			(xy 164.277193 -400.939403) (xy 164.261838 -400.991701) (xy 164.239196 -401.04128) (xy 164.209729 -401.087134)
			(xy 164.174036 -401.128326) (xy 164.132845 -401.164021) (xy 164.086993 -401.193489) (xy 164.037414 -401.216133)
			(xy 163.985117 -401.23149) (xy 163.931167 -401.239249) (xy 163.903914 -401.239736) (xy 163.040314 -401.239736)
			(xy 163.013062 -401.239218) (xy 162.959114 -401.231463) (xy 162.906818 -401.216109) (xy 162.85724 -401.193469)
			(xy 162.811389 -401.164004) (xy 162.770197 -401.128313) (xy 162.734505 -401.087123) (xy 162.705038 -401.041272)
			(xy 162.682396 -400.991695) (xy 162.66704 -400.9394) (xy 162.659283 -400.885451) (xy 161.221773 -400.885451)
			(xy 161.221773 -400.885456) (xy 161.214015 -400.939413) (xy 161.198656 -400.991717) (xy 161.17601 -401.041303)
			(xy 161.146538 -401.08716) (xy 161.110838 -401.128357) (xy 161.06964 -401.164053) (xy 161.02378 -401.193523)
			(xy 160.974193 -401.216165) (xy 160.921888 -401.23152) (xy 160.86793 -401.239275) (xy 160.840674 -401.239736)
			(xy 159.977074 -401.239736) (xy 159.949826 -401.239192) (xy 159.895885 -401.231433) (xy 159.843597 -401.216077)
			(xy 159.794027 -401.193436) (xy 159.748183 -401.163971) (xy 159.706999 -401.128282) (xy 159.671313 -401.087096)
			(xy 159.641852 -401.04125) (xy 159.619214 -400.991678) (xy 159.603861 -400.939389) (xy 159.596106 -400.885448)
			(xy 158.15845 -400.885448) (xy 158.15845 -400.885452) (xy 158.150694 -400.9394) (xy 158.13534 -400.991696)
			(xy 158.112699 -401.041275) (xy 158.083234 -401.087127) (xy 158.047543 -401.128319) (xy 158.006354 -401.164014)
			(xy 157.960505 -401.193483) (xy 157.910928 -401.216128) (xy 157.858634 -401.231487) (xy 157.804686 -401.239248)
			(xy 157.777434 -401.239736) (xy 156.913834 -401.239736) (xy 156.886582 -401.239219) (xy 156.832631 -401.231467)
			(xy 156.780333 -401.216115) (xy 156.730752 -401.193476) (xy 156.684898 -401.164011) (xy 156.643704 -401.12832)
			(xy 156.60801 -401.087129) (xy 156.578541 -401.041278) (xy 156.555897 -400.991699) (xy 156.540541 -400.939402)
			(xy 156.532783 -400.885452) (xy 155.095273 -400.885452) (xy 155.095273 -400.885455) (xy 155.087515 -400.939411)
			(xy 155.072158 -400.991713) (xy 155.049513 -401.041297) (xy 155.020043 -401.087154) (xy 154.984346 -401.12835)
			(xy 154.943149 -401.164046) (xy 154.897292 -401.193516) (xy 154.847707 -401.21616) (xy 154.795405 -401.231517)
			(xy 154.741449 -401.239273) (xy 154.714194 -401.239736) (xy 153.850594 -401.239736) (xy 153.823345 -401.239193)
			(xy 153.769402 -401.231437) (xy 153.717112 -401.216082) (xy 153.667539 -401.193442) (xy 153.621693 -401.163978)
			(xy 153.580506 -401.128289) (xy 153.544818 -401.087102) (xy 153.515355 -401.041256) (xy 153.492716 -400.991683)
			(xy 153.477362 -400.939392) (xy 153.469606 -400.885449) (xy 152.032073 -400.885449) (xy 152.032073 -400.885457)
			(xy 152.024314 -400.939416) (xy 152.008955 -400.991721) (xy 151.986307 -401.041308) (xy 151.956833 -401.087167)
			(xy 151.921131 -401.128364) (xy 151.87993 -401.16406) (xy 151.834068 -401.193529) (xy 151.784478 -401.216171)
			(xy 151.732171 -401.231524) (xy 151.678211 -401.239276) (xy 151.650954 -401.239736) (xy 150.787354 -401.239736)
			(xy 150.760107 -401.239191) (xy 150.706168 -401.231429) (xy 150.653883 -401.216071) (xy 150.604315 -401.193429)
			(xy 150.558474 -401.163964) (xy 150.517292 -401.128275) (xy 150.481608 -401.087089) (xy 150.452149 -401.041244)
			(xy 150.429512 -400.991674) (xy 150.414161 -400.939387) (xy 150.406406 -400.885447) (xy 148.96875 -400.885447)
			(xy 148.96875 -400.885453) (xy 148.960993 -400.939403) (xy 148.945638 -400.991701) (xy 148.922996 -401.04128)
			(xy 148.893529 -401.087134) (xy 148.857836 -401.128326) (xy 148.816645 -401.164021) (xy 148.770793 -401.193489)
			(xy 148.721214 -401.216133) (xy 148.668917 -401.23149) (xy 148.614967 -401.239249) (xy 148.587714 -401.239736)
			(xy 147.724114 -401.239736) (xy 147.696862 -401.239218) (xy 147.642914 -401.231463) (xy 147.590618 -401.216109)
			(xy 147.54104 -401.193469) (xy 147.495189 -401.164004) (xy 147.453997 -401.128313) (xy 147.418305 -401.087123)
			(xy 147.388838 -401.041272) (xy 147.366196 -400.991695) (xy 147.35084 -400.9394) (xy 147.343083 -400.885451)
			(xy 145.905573 -400.885451) (xy 145.905573 -400.885456) (xy 145.897815 -400.939413) (xy 145.882456 -400.991717)
			(xy 145.85981 -401.041303) (xy 145.830338 -401.08716) (xy 145.794638 -401.128357) (xy 145.75344 -401.164053)
			(xy 145.70758 -401.193523) (xy 145.657993 -401.216165) (xy 145.605688 -401.23152) (xy 145.55173 -401.239275)
			(xy 145.524474 -401.239736) (xy 144.660874 -401.239736) (xy 144.633626 -401.239192) (xy 144.579685 -401.231433)
			(xy 144.527397 -401.216077) (xy 144.477827 -401.193436) (xy 144.431983 -401.163971) (xy 144.390799 -401.128282)
			(xy 144.355113 -401.087096) (xy 144.325652 -401.04125) (xy 144.303014 -400.991678) (xy 144.287661 -400.939389)
			(xy 144.279906 -400.885448) (xy 142.84225 -400.885448) (xy 142.84225 -400.885452) (xy 142.834494 -400.9394)
			(xy 142.81914 -400.991696) (xy 142.796499 -401.041275) (xy 142.767034 -401.087127) (xy 142.731343 -401.128319)
			(xy 142.690154 -401.164014) (xy 142.644305 -401.193483) (xy 142.594728 -401.216128) (xy 142.542434 -401.231487)
			(xy 142.488486 -401.239248) (xy 142.461234 -401.239736) (xy 141.597634 -401.239736) (xy 141.570382 -401.239219)
			(xy 141.516431 -401.231467) (xy 141.464133 -401.216115) (xy 141.414552 -401.193476) (xy 141.368698 -401.164011)
			(xy 141.327504 -401.12832) (xy 141.29181 -401.087129) (xy 141.262341 -401.041278) (xy 141.239697 -400.991699)
			(xy 141.224341 -400.939402) (xy 141.216583 -400.885452) (xy 139.779073 -400.885452) (xy 139.779073 -400.885455)
			(xy 139.771315 -400.939411) (xy 139.755958 -400.991713) (xy 139.733313 -401.041297) (xy 139.703843 -401.087154)
			(xy 139.668146 -401.12835) (xy 139.626949 -401.164046) (xy 139.581092 -401.193516) (xy 139.531507 -401.21616)
			(xy 139.479205 -401.231517) (xy 139.425249 -401.239273) (xy 139.397994 -401.239736) (xy 138.534394 -401.239736)
			(xy 138.507145 -401.239193) (xy 138.453202 -401.231437) (xy 138.400912 -401.216082) (xy 138.351339 -401.193442)
			(xy 138.305493 -401.163978) (xy 138.264306 -401.128289) (xy 138.228618 -401.087102) (xy 138.199155 -401.041256)
			(xy 138.176516 -400.991683) (xy 138.161162 -400.939392) (xy 138.153406 -400.885449) (xy 136.715873 -400.885449)
			(xy 136.715873 -400.885457) (xy 136.708114 -400.939416) (xy 136.692755 -400.991721) (xy 136.670107 -401.041308)
			(xy 136.640633 -401.087167) (xy 136.604931 -401.128364) (xy 136.56373 -401.16406) (xy 136.517868 -401.193529)
			(xy 136.468278 -401.216171) (xy 136.415971 -401.231524) (xy 136.362011 -401.239276) (xy 136.334754 -401.239736)
			(xy 135.471154 -401.239736) (xy 135.443907 -401.239191) (xy 135.389968 -401.231429) (xy 135.337683 -401.216071)
			(xy 135.288115 -401.193429) (xy 135.242274 -401.163964) (xy 135.201092 -401.128275) (xy 135.165408 -401.087089)
			(xy 135.135949 -401.041244) (xy 135.113312 -400.991674) (xy 135.097961 -400.939387) (xy 135.090206 -400.885447)
			(xy 133.65255 -400.885447) (xy 133.65255 -400.885453) (xy 133.644793 -400.939403) (xy 133.629438 -400.991701)
			(xy 133.606796 -401.04128) (xy 133.577329 -401.087134) (xy 133.541636 -401.128326) (xy 133.500445 -401.164021)
			(xy 133.454593 -401.193489) (xy 133.405014 -401.216133) (xy 133.352717 -401.23149) (xy 133.298767 -401.239249)
			(xy 133.271514 -401.239736) (xy 132.407914 -401.239736) (xy 132.380662 -401.239218) (xy 132.326714 -401.231463)
			(xy 132.274418 -401.216109) (xy 132.22484 -401.193469) (xy 132.178989 -401.164004) (xy 132.137797 -401.128313)
			(xy 132.102105 -401.087123) (xy 132.072638 -401.041272) (xy 132.049996 -400.991695) (xy 132.03464 -400.9394)
			(xy 132.026883 -400.885451) (xy 130.589373 -400.885451) (xy 130.589373 -400.885456) (xy 130.581615 -400.939413)
			(xy 130.566256 -400.991717) (xy 130.54361 -401.041303) (xy 130.514138 -401.08716) (xy 130.478438 -401.128357)
			(xy 130.43724 -401.164053) (xy 130.39138 -401.193523) (xy 130.341793 -401.216165) (xy 130.289488 -401.23152)
			(xy 130.23553 -401.239275) (xy 130.208274 -401.239736) (xy 129.344674 -401.239736) (xy 129.317426 -401.239192)
			(xy 129.263485 -401.231433) (xy 129.211197 -401.216077) (xy 129.161627 -401.193436) (xy 129.115783 -401.163971)
			(xy 129.074599 -401.128282) (xy 129.038913 -401.087096) (xy 129.009452 -401.04125) (xy 128.986814 -400.991678)
			(xy 128.971461 -400.939389) (xy 128.963706 -400.885448) (xy 127.52605 -400.885448) (xy 127.52605 -400.885452)
			(xy 127.518294 -400.9394) (xy 127.50294 -400.991696) (xy 127.480299 -401.041275) (xy 127.450834 -401.087127)
			(xy 127.415143 -401.128319) (xy 127.373954 -401.164014) (xy 127.328105 -401.193483) (xy 127.278528 -401.216128)
			(xy 127.226234 -401.231487) (xy 127.172286 -401.239248) (xy 127.145034 -401.239736) (xy 126.281434 -401.239736)
			(xy 126.254182 -401.239219) (xy 126.200231 -401.231467) (xy 126.147933 -401.216115) (xy 126.098352 -401.193476)
			(xy 126.052498 -401.164011) (xy 126.011304 -401.12832) (xy 125.97561 -401.087129) (xy 125.946141 -401.041278)
			(xy 125.923497 -400.991699) (xy 125.908141 -400.939402) (xy 125.900383 -400.885452) (xy 124.462873 -400.885452)
			(xy 124.462873 -400.885455) (xy 124.455115 -400.939411) (xy 124.439758 -400.991713) (xy 124.417113 -401.041297)
			(xy 124.387643 -401.087154) (xy 124.351946 -401.12835) (xy 124.310749 -401.164046) (xy 124.264892 -401.193516)
			(xy 124.215307 -401.21616) (xy 124.163005 -401.231517) (xy 124.109049 -401.239273) (xy 124.081794 -401.239736)
			(xy 123.218194 -401.239736) (xy 123.190945 -401.239193) (xy 123.137002 -401.231437) (xy 123.084712 -401.216082)
			(xy 123.035139 -401.193442) (xy 122.989293 -401.163978) (xy 122.948106 -401.128289) (xy 122.912418 -401.087102)
			(xy 122.882955 -401.041256) (xy 122.860316 -400.991683) (xy 122.844962 -400.939392) (xy 122.837206 -400.885449)
			(xy 121.399673 -400.885449) (xy 121.399673 -400.885457) (xy 121.391914 -400.939416) (xy 121.376555 -400.991721)
			(xy 121.353907 -401.041308) (xy 121.324433 -401.087167) (xy 121.288731 -401.128364) (xy 121.24753 -401.16406)
			(xy 121.201668 -401.193529) (xy 121.152078 -401.216171) (xy 121.099771 -401.231524) (xy 121.045811 -401.239276)
			(xy 121.018554 -401.239736) (xy 120.154954 -401.239736) (xy 120.127707 -401.239191) (xy 120.073768 -401.231429)
			(xy 120.021483 -401.216071) (xy 119.971915 -401.193429) (xy 119.926074 -401.163964) (xy 119.884892 -401.128275)
			(xy 119.849208 -401.087089) (xy 119.819749 -401.041244) (xy 119.797112 -400.991674) (xy 119.781761 -400.939387)
			(xy 119.774006 -400.885447) (xy 95.17305 -400.885447) (xy 95.17305 -400.885452) (xy 95.165294 -400.9394)
			(xy 95.14994 -400.991695) (xy 95.1273 -401.041274) (xy 95.097835 -401.087126) (xy 95.062145 -401.128318)
			(xy 95.020956 -401.164012) (xy 94.975107 -401.193482) (xy 94.925531 -401.216127) (xy 94.873237 -401.231486)
			(xy 94.819289 -401.239248) (xy 94.792038 -401.239736) (xy 93.928438 -401.239736) (xy 93.901185 -401.239219)
			(xy 93.847234 -401.231467) (xy 93.794936 -401.216116) (xy 93.745354 -401.193477) (xy 93.6995 -401.164012)
			(xy 93.658306 -401.128321) (xy 93.622611 -401.087131) (xy 93.593141 -401.041279) (xy 93.570498 -400.9917)
			(xy 93.555141 -400.939403) (xy 93.547383 -400.885453) (xy 92.109873 -400.885453) (xy 92.109873 -400.885455)
			(xy 92.102115 -400.93941) (xy 92.086758 -400.991712) (xy 92.064114 -401.041296) (xy 92.034643 -401.087153)
			(xy 91.998947 -401.128348) (xy 91.957751 -401.164045) (xy 91.911894 -401.193515) (xy 91.86231 -401.216159)
			(xy 91.810008 -401.231516) (xy 91.756053 -401.239273) (xy 91.728798 -401.239736) (xy 90.865198 -401.239736)
			(xy 90.837949 -401.239194) (xy 90.784005 -401.231437) (xy 90.731715 -401.216083) (xy 90.682142 -401.193444)
			(xy 90.636295 -401.16398) (xy 90.595108 -401.128291) (xy 90.559419 -401.087104) (xy 90.529955 -401.041257)
			(xy 90.507316 -400.991683) (xy 90.491962 -400.939393) (xy 90.484206 -400.885449) (xy 89.046673 -400.885449)
			(xy 89.046673 -400.885457) (xy 89.038914 -400.939415) (xy 89.023555 -400.991721) (xy 89.000908 -401.041307)
			(xy 88.971434 -401.087166) (xy 88.935733 -401.128363) (xy 88.894532 -401.164059) (xy 88.84867 -401.193528)
			(xy 88.799081 -401.21617) (xy 88.746774 -401.231523) (xy 88.692815 -401.239276) (xy 88.665558 -401.239736)
			(xy 87.801958 -401.239736) (xy 87.774711 -401.239191) (xy 87.720772 -401.23143) (xy 87.668486 -401.216073)
			(xy 87.618918 -401.193431) (xy 87.573076 -401.163965) (xy 87.531894 -401.128277) (xy 87.496209 -401.087091)
			(xy 87.466749 -401.041246) (xy 87.444113 -400.991675) (xy 87.428761 -400.939387) (xy 87.421006 -400.885447)
			(xy 85.98335 -400.885447) (xy 85.98335 -400.885452) (xy 85.975594 -400.939403) (xy 85.960238 -400.9917)
			(xy 85.937597 -401.041279) (xy 85.90813 -401.087132) (xy 85.872438 -401.128325) (xy 85.831247 -401.164019)
			(xy 85.785395 -401.193488) (xy 85.735817 -401.216132) (xy 85.68352 -401.23149) (xy 85.62957 -401.239249)
			(xy 85.602318 -401.239736) (xy 84.738718 -401.239736) (xy 84.711466 -401.239218) (xy 84.657517 -401.231464)
			(xy 84.605221 -401.21611) (xy 84.555642 -401.19347) (xy 84.50979 -401.164005) (xy 84.468599 -401.128314)
			(xy 84.432906 -401.087124) (xy 84.403438 -401.041273) (xy 84.380796 -400.991696) (xy 84.36544 -400.9394)
			(xy 84.357683 -400.885452) (xy 82.920173 -400.885452) (xy 82.920173 -400.885456) (xy 82.912415 -400.939413)
			(xy 82.897057 -400.991716) (xy 82.874411 -401.041302) (xy 82.844939 -401.087159) (xy 82.80924 -401.128355)
			(xy 82.768042 -401.164052) (xy 82.722182 -401.193521) (xy 82.672596 -401.216164) (xy 82.620291 -401.23152)
			(xy 82.566334 -401.239275) (xy 82.539078 -401.239736) (xy 81.675478 -401.239736) (xy 81.64823 -401.239192)
			(xy 81.594288 -401.231434) (xy 81.542 -401.216078) (xy 81.49243 -401.193437) (xy 81.446585 -401.163973)
			(xy 81.405401 -401.128284) (xy 81.369714 -401.087097) (xy 81.340252 -401.041251) (xy 81.317614 -400.991679)
			(xy 81.302262 -400.93939) (xy 81.294506 -400.885448) (xy 79.85685 -400.885448) (xy 79.85685 -400.885452)
			(xy 79.849094 -400.9394) (xy 79.83374 -400.991695) (xy 79.8111 -401.041274) (xy 79.781635 -401.087126)
			(xy 79.745945 -401.128318) (xy 79.704756 -401.164012) (xy 79.658907 -401.193482) (xy 79.609331 -401.216127)
			(xy 79.557037 -401.231486) (xy 79.503089 -401.239248) (xy 79.475838 -401.239736) (xy 78.612238 -401.239736)
			(xy 78.584985 -401.239219) (xy 78.531034 -401.231467) (xy 78.478736 -401.216116) (xy 78.429154 -401.193477)
			(xy 78.3833 -401.164012) (xy 78.342106 -401.128321) (xy 78.306411 -401.087131) (xy 78.276941 -401.041279)
			(xy 78.254298 -400.9917) (xy 78.238941 -400.939403) (xy 78.231183 -400.885453) (xy 76.793673 -400.885453)
			(xy 76.793673 -400.885455) (xy 76.785915 -400.93941) (xy 76.770558 -400.991712) (xy 76.747914 -401.041296)
			(xy 76.718443 -401.087153) (xy 76.682747 -401.128348) (xy 76.641551 -401.164045) (xy 76.595694 -401.193515)
			(xy 76.54611 -401.216159) (xy 76.493808 -401.231516) (xy 76.439853 -401.239273) (xy 76.412598 -401.239736)
			(xy 75.548998 -401.239736) (xy 75.521749 -401.239194) (xy 75.467805 -401.231437) (xy 75.415515 -401.216083)
			(xy 75.365942 -401.193444) (xy 75.320095 -401.16398) (xy 75.278908 -401.128291) (xy 75.243219 -401.087104)
			(xy 75.213755 -401.041257) (xy 75.191116 -400.991683) (xy 75.175762 -400.939393) (xy 75.168006 -400.885449)
			(xy 73.730473 -400.885449) (xy 73.730473 -400.885457) (xy 73.722714 -400.939415) (xy 73.707355 -400.991721)
			(xy 73.684708 -401.041307) (xy 73.655234 -401.087166) (xy 73.619533 -401.128363) (xy 73.578332 -401.164059)
			(xy 73.53247 -401.193528) (xy 73.482881 -401.21617) (xy 73.430574 -401.231523) (xy 73.376615 -401.239276)
			(xy 73.349358 -401.239736) (xy 72.485758 -401.239736) (xy 72.458511 -401.239191) (xy 72.404572 -401.23143)
			(xy 72.352286 -401.216073) (xy 72.302718 -401.193431) (xy 72.256876 -401.163965) (xy 72.215694 -401.128277)
			(xy 72.180009 -401.087091) (xy 72.150549 -401.041246) (xy 72.127913 -400.991675) (xy 72.112561 -400.939387)
			(xy 72.104806 -400.885447) (xy 70.66715 -400.885447) (xy 70.66715 -400.885452) (xy 70.659394 -400.939403)
			(xy 70.644038 -400.9917) (xy 70.621397 -401.041279) (xy 70.59193 -401.087132) (xy 70.556238 -401.128325)
			(xy 70.515047 -401.164019) (xy 70.469195 -401.193488) (xy 70.419617 -401.216132) (xy 70.36732 -401.23149)
			(xy 70.31337 -401.239249) (xy 70.286118 -401.239736) (xy 69.422518 -401.239736) (xy 69.395266 -401.239218)
			(xy 69.341317 -401.231464) (xy 69.289021 -401.21611) (xy 69.239442 -401.19347) (xy 69.19359 -401.164005)
			(xy 69.152399 -401.128314) (xy 69.116706 -401.087124) (xy 69.087238 -401.041273) (xy 69.064596 -400.991696)
			(xy 69.04924 -400.9394) (xy 69.041483 -400.885452) (xy 67.603973 -400.885452) (xy 67.603973 -400.885456)
			(xy 67.596215 -400.939413) (xy 67.580857 -400.991716) (xy 67.558211 -401.041302) (xy 67.528739 -401.087159)
			(xy 67.49304 -401.128355) (xy 67.451842 -401.164052) (xy 67.405982 -401.193521) (xy 67.356396 -401.216164)
			(xy 67.304091 -401.23152) (xy 67.250134 -401.239275) (xy 67.222878 -401.239736) (xy 66.359278 -401.239736)
			(xy 66.33203 -401.239192) (xy 66.278088 -401.231434) (xy 66.2258 -401.216078) (xy 66.17623 -401.193437)
			(xy 66.130385 -401.163973) (xy 66.089201 -401.128284) (xy 66.053514 -401.087097) (xy 66.024052 -401.041251)
			(xy 66.001414 -400.991679) (xy 65.986062 -400.93939) (xy 65.978306 -400.885448) (xy 64.54065 -400.885448)
			(xy 64.54065 -400.885452) (xy 64.532894 -400.9394) (xy 64.51754 -400.991695) (xy 64.4949 -401.041274)
			(xy 64.465435 -401.087126) (xy 64.429745 -401.128318) (xy 64.388556 -401.164012) (xy 64.342707 -401.193482)
			(xy 64.293131 -401.216127) (xy 64.240837 -401.231486) (xy 64.186889 -401.239248) (xy 64.159638 -401.239736)
			(xy 63.296038 -401.239736) (xy 63.268785 -401.239219) (xy 63.214834 -401.231467) (xy 63.162536 -401.216116)
			(xy 63.112954 -401.193477) (xy 63.0671 -401.164012) (xy 63.025906 -401.128321) (xy 62.990211 -401.087131)
			(xy 62.960741 -401.041279) (xy 62.938098 -400.9917) (xy 62.922741 -400.939403) (xy 62.914983 -400.885453)
			(xy 61.477473 -400.885453) (xy 61.477473 -400.885455) (xy 61.469715 -400.93941) (xy 61.454358 -400.991712)
			(xy 61.431714 -401.041296) (xy 61.402243 -401.087153) (xy 61.366547 -401.128348) (xy 61.325351 -401.164045)
			(xy 61.279494 -401.193515) (xy 61.22991 -401.216159) (xy 61.177608 -401.231516) (xy 61.123653 -401.239273)
			(xy 61.096398 -401.239736) (xy 60.232798 -401.239736) (xy 60.205549 -401.239194) (xy 60.151605 -401.231437)
			(xy 60.099315 -401.216083) (xy 60.049742 -401.193444) (xy 60.003895 -401.16398) (xy 59.962708 -401.128291)
			(xy 59.927019 -401.087104) (xy 59.897555 -401.041257) (xy 59.874916 -400.991683) (xy 59.859562 -400.939393)
			(xy 59.851806 -400.885449) (xy 58.414273 -400.885449) (xy 58.414273 -400.885457) (xy 58.406514 -400.939415)
			(xy 58.391155 -400.991721) (xy 58.368508 -401.041307) (xy 58.339034 -401.087166) (xy 58.303333 -401.128363)
			(xy 58.262132 -401.164059) (xy 58.21627 -401.193528) (xy 58.166681 -401.21617) (xy 58.114374 -401.231523)
			(xy 58.060415 -401.239276) (xy 58.033158 -401.239736) (xy 57.169558 -401.239736) (xy 57.142311 -401.239191)
			(xy 57.088372 -401.23143) (xy 57.036086 -401.216073) (xy 56.986518 -401.193431) (xy 56.940676 -401.163965)
			(xy 56.899494 -401.128277) (xy 56.863809 -401.087091) (xy 56.834349 -401.041246) (xy 56.811713 -400.991675)
			(xy 56.796361 -400.939387) (xy 56.788606 -400.885447) (xy 55.35095 -400.885447) (xy 55.35095 -400.885452)
			(xy 55.343194 -400.939403) (xy 55.327838 -400.9917) (xy 55.305197 -401.041279) (xy 55.27573 -401.087132)
			(xy 55.240038 -401.128325) (xy 55.198847 -401.164019) (xy 55.152995 -401.193488) (xy 55.103417 -401.216132)
			(xy 55.05112 -401.23149) (xy 54.99717 -401.239249) (xy 54.969918 -401.239736) (xy 54.106318 -401.239736)
			(xy 54.079066 -401.239218) (xy 54.025117 -401.231464) (xy 53.972821 -401.21611) (xy 53.923242 -401.19347)
			(xy 53.87739 -401.164005) (xy 53.836199 -401.128314) (xy 53.800506 -401.087124) (xy 53.771038 -401.041273)
			(xy 53.748396 -400.991696) (xy 53.73304 -400.9394) (xy 53.725283 -400.885452) (xy 52.287773 -400.885452)
			(xy 52.287773 -400.885456) (xy 52.280015 -400.939413) (xy 52.264657 -400.991716) (xy 52.242011 -401.041302)
			(xy 52.212539 -401.087159) (xy 52.17684 -401.128355) (xy 52.135642 -401.164052) (xy 52.089782 -401.193521)
			(xy 52.040196 -401.216164) (xy 51.987891 -401.23152) (xy 51.933934 -401.239275) (xy 51.906678 -401.239736)
			(xy 51.043078 -401.239736) (xy 51.01583 -401.239192) (xy 50.961888 -401.231434) (xy 50.9096 -401.216078)
			(xy 50.86003 -401.193437) (xy 50.814185 -401.163973) (xy 50.773001 -401.128284) (xy 50.737314 -401.087097)
			(xy 50.707852 -401.041251) (xy 50.685214 -400.991679) (xy 50.669862 -400.93939) (xy 50.662106 -400.885448)
			(xy 49.22445 -400.885448) (xy 49.22445 -400.885452) (xy 49.216694 -400.9394) (xy 49.20134 -400.991695)
			(xy 49.1787 -401.041274) (xy 49.149235 -401.087126) (xy 49.113545 -401.128318) (xy 49.072356 -401.164012)
			(xy 49.026507 -401.193482) (xy 48.976931 -401.216127) (xy 48.924637 -401.231486) (xy 48.870689 -401.239248)
			(xy 48.843438 -401.239736) (xy 47.979838 -401.239736) (xy 47.952585 -401.239219) (xy 47.898634 -401.231467)
			(xy 47.846336 -401.216116) (xy 47.796754 -401.193477) (xy 47.7509 -401.164012) (xy 47.709706 -401.128321)
			(xy 47.674011 -401.087131) (xy 47.644541 -401.041279) (xy 47.621898 -400.9917) (xy 47.606541 -400.939403)
			(xy 47.598783 -400.885453) (xy 2.509012 -400.885453) (xy 2.509012 -402.656674) (xy 98.152872 -402.656674)
			(xy 98.152872 -402.602126) (xy 98.160635 -402.548133) (xy 98.176003 -402.495795) (xy 98.198664 -402.446176)
			(xy 98.228156 -402.400288) (xy 98.263878 -402.359064) (xy 98.305104 -402.323344) (xy 98.350994 -402.293855)
			(xy 98.400613 -402.271196) (xy 98.452953 -402.255831) (xy 98.506946 -402.24807) (xy 98.53422 -402.247608)
			(xy 99.39782 -402.247608) (xy 99.425086 -402.248156) (xy 99.479063 -402.255919) (xy 99.531387 -402.271285)
			(xy 99.58099 -402.293941) (xy 99.626865 -402.323425) (xy 99.668077 -402.359137) (xy 99.703787 -402.400351)
			(xy 99.733269 -402.446227) (xy 99.755922 -402.495832) (xy 99.771285 -402.548156) (xy 99.779046 -402.602134)
			(xy 99.779046 -402.656666) (xy 99.771285 -402.710644) (xy 99.755922 -402.762968) (xy 99.733269 -402.812573)
			(xy 99.703787 -402.858449) (xy 99.668077 -402.899663) (xy 99.626865 -402.935375) (xy 99.58099 -402.964859)
			(xy 99.531387 -402.987515) (xy 99.479063 -403.002881) (xy 99.425086 -403.010644) (xy 99.39782 -403.011132)
			(xy 98.53422 -403.011132) (xy 98.506946 -403.01073) (xy 98.452953 -403.002969) (xy 98.400613 -402.987604)
			(xy 98.350994 -402.964945) (xy 98.305104 -402.935456) (xy 98.263878 -402.899736) (xy 98.228156 -402.858512)
			(xy 98.198664 -402.812624) (xy 98.176003 -402.763005) (xy 98.160635 -402.710667) (xy 98.152872 -402.656674)
			(xy 2.509012 -402.656674) (xy 2.509012 -403.371812) (xy 2.5095 -403.425034) (xy 2.517117 -403.531207)
			(xy 2.532283 -403.636566) (xy 2.554922 -403.740575) (xy 2.584919 -403.842706) (xy 2.610452 -403.911156)
			(xy 47.598731 -403.911156) (xy 47.598731 -403.856644) (xy 47.606489 -403.802686) (xy 47.621848 -403.750382)
			(xy 47.644495 -403.700796) (xy 47.673969 -403.654938) (xy 47.709669 -403.613742) (xy 47.750868 -403.578046)
			(xy 47.796729 -403.548577) (xy 47.846317 -403.525935) (xy 47.898623 -403.510581) (xy 47.952582 -403.502828)
			(xy 47.979838 -403.502368) (xy 48.843438 -403.502368) (xy 48.870686 -403.502905) (xy 48.924626 -403.510665)
			(xy 48.976913 -403.526023) (xy 49.026482 -403.548665) (xy 49.072325 -403.57813) (xy 49.113508 -403.613819)
			(xy 49.149193 -403.655006) (xy 49.178654 -403.700851) (xy 49.201291 -403.750423) (xy 49.216643 -403.802711)
			(xy 49.224398 -403.856652) (xy 49.224398 -403.911148) (xy 49.224397 -403.911152) (xy 50.662054 -403.911152)
			(xy 50.662054 -403.856648) (xy 50.66981 -403.802699) (xy 50.685165 -403.750403) (xy 50.707806 -403.700824)
			(xy 50.737272 -403.654971) (xy 50.772964 -403.613779) (xy 50.814154 -403.578085) (xy 50.860004 -403.548617)
			(xy 50.909582 -403.525973) (xy 50.961877 -403.510615) (xy 51.015826 -403.502855) (xy 51.043078 -403.502368)
			(xy 51.906678 -403.502368) (xy 51.93393 -403.502878) (xy 51.98788 -403.510632) (xy 52.040177 -403.525985)
			(xy 52.089757 -403.548625) (xy 52.13561 -403.57809) (xy 52.176803 -403.613782) (xy 52.212497 -403.654972)
			(xy 52.241965 -403.700824) (xy 52.264607 -403.750402) (xy 52.279964 -403.802698) (xy 52.287721 -403.856648)
			(xy 52.287721 -403.911152) (xy 52.287721 -403.911155) (xy 53.725231 -403.911155) (xy 53.725231 -403.856645)
			(xy 53.732989 -403.802689) (xy 53.748347 -403.750386) (xy 53.770992 -403.700801) (xy 53.800464 -403.654945)
			(xy 53.836162 -403.613749) (xy 53.877359 -403.578053) (xy 53.923217 -403.548583) (xy 53.972803 -403.525941)
			(xy 54.025106 -403.510585) (xy 54.079063 -403.50283) (xy 54.106318 -403.502368) (xy 54.969918 -403.502368)
			(xy 54.997167 -403.502903) (xy 55.051109 -403.510662) (xy 55.103398 -403.526017) (xy 55.15297 -403.548658)
			(xy 55.198815 -403.578123) (xy 55.240001 -403.613812) (xy 55.275688 -403.654999) (xy 55.305151 -403.700846)
			(xy 55.327789 -403.750419) (xy 55.343142 -403.802709) (xy 55.350898 -403.856651) (xy 55.350898 -403.911149)
			(xy 55.350898 -403.911151) (xy 56.788554 -403.911151) (xy 56.788554 -403.856649) (xy 56.79631 -403.802702)
			(xy 56.811664 -403.750407) (xy 56.834303 -403.700829) (xy 56.863767 -403.654978) (xy 56.899457 -403.613786)
			(xy 56.940644 -403.578093) (xy 56.986492 -403.548623) (xy 57.036067 -403.525978) (xy 57.08836 -403.510619)
			(xy 57.142307 -403.502857) (xy 57.169558 -403.502368) (xy 58.033158 -403.502368) (xy 58.060411 -403.502876)
			(xy 58.114363 -403.510628) (xy 58.166663 -403.525979) (xy 58.216245 -403.548618) (xy 58.262101 -403.578083)
			(xy 58.303296 -403.613775) (xy 58.338992 -403.654966) (xy 58.368462 -403.700818) (xy 58.391106 -403.750398)
			(xy 58.406463 -403.802696) (xy 58.414221 -403.856647) (xy 58.414221 -403.911153) (xy 59.851754 -403.911153)
			(xy 59.851754 -403.856647) (xy 59.859511 -403.802696) (xy 59.874867 -403.750398) (xy 59.897509 -403.700818)
			(xy 59.926977 -403.654965) (xy 59.962671 -403.613772) (xy 60.003863 -403.578078) (xy 60.049716 -403.54861)
			(xy 60.099296 -403.525967) (xy 60.151594 -403.510611) (xy 60.205545 -403.502854) (xy 60.232798 -403.502368)
			(xy 61.096398 -403.502368) (xy 61.123649 -403.502879) (xy 61.177597 -403.510635) (xy 61.229892 -403.52599)
			(xy 61.279469 -403.548631) (xy 61.32532 -403.578097) (xy 61.36651 -403.613789) (xy 61.402201 -403.654979)
			(xy 61.431668 -403.700829) (xy 61.454309 -403.750406) (xy 61.469664 -403.802701) (xy 61.477421 -403.856649)
			(xy 61.477421 -403.911151) (xy 61.47742 -403.911156) (xy 62.914931 -403.911156) (xy 62.914931 -403.856644)
			(xy 62.922689 -403.802686) (xy 62.938048 -403.750382) (xy 62.960695 -403.700796) (xy 62.990169 -403.654938)
			(xy 63.025869 -403.613742) (xy 63.067068 -403.578046) (xy 63.112929 -403.548577) (xy 63.162517 -403.525935)
			(xy 63.214823 -403.510581) (xy 63.268782 -403.502828) (xy 63.296038 -403.502368) (xy 64.159638 -403.502368)
			(xy 64.186886 -403.502905) (xy 64.240826 -403.510665) (xy 64.293113 -403.526023) (xy 64.342682 -403.548665)
			(xy 64.388525 -403.57813) (xy 64.429708 -403.613819) (xy 64.465393 -403.655006) (xy 64.494854 -403.700851)
			(xy 64.517491 -403.750423) (xy 64.532843 -403.802711) (xy 64.540598 -403.856652) (xy 64.540598 -403.911148)
			(xy 64.540597 -403.911152) (xy 65.978254 -403.911152) (xy 65.978254 -403.856648) (xy 65.98601 -403.802699)
			(xy 66.001365 -403.750403) (xy 66.024006 -403.700824) (xy 66.053472 -403.654971) (xy 66.089164 -403.613779)
			(xy 66.130354 -403.578085) (xy 66.176204 -403.548617) (xy 66.225782 -403.525973) (xy 66.278077 -403.510615)
			(xy 66.332026 -403.502855) (xy 66.359278 -403.502368) (xy 67.222878 -403.502368) (xy 67.25013 -403.502878)
			(xy 67.30408 -403.510632) (xy 67.356377 -403.525985) (xy 67.405957 -403.548625) (xy 67.45181 -403.57809)
			(xy 67.493003 -403.613782) (xy 67.528697 -403.654972) (xy 67.558165 -403.700824) (xy 67.580807 -403.750402)
			(xy 67.596164 -403.802698) (xy 67.603921 -403.856648) (xy 67.603921 -403.911152) (xy 67.603921 -403.911155)
			(xy 69.041431 -403.911155) (xy 69.041431 -403.856645) (xy 69.049189 -403.802689) (xy 69.064547 -403.750386)
			(xy 69.087192 -403.700801) (xy 69.116664 -403.654945) (xy 69.152362 -403.613749) (xy 69.193559 -403.578053)
			(xy 69.239417 -403.548583) (xy 69.289003 -403.525941) (xy 69.341306 -403.510585) (xy 69.395263 -403.50283)
			(xy 69.422518 -403.502368) (xy 70.286118 -403.502368) (xy 70.313367 -403.502903) (xy 70.367309 -403.510662)
			(xy 70.419598 -403.526017) (xy 70.46917 -403.548658) (xy 70.515015 -403.578123) (xy 70.556201 -403.613812)
			(xy 70.591888 -403.654999) (xy 70.621351 -403.700846) (xy 70.643989 -403.750419) (xy 70.659342 -403.802709)
			(xy 70.667098 -403.856651) (xy 70.667098 -403.911149) (xy 70.667098 -403.911151) (xy 72.104754 -403.911151)
			(xy 72.104754 -403.856649) (xy 72.11251 -403.802702) (xy 72.127864 -403.750407) (xy 72.150503 -403.700829)
			(xy 72.179967 -403.654978) (xy 72.215657 -403.613786) (xy 72.256844 -403.578093) (xy 72.302692 -403.548623)
			(xy 72.352267 -403.525978) (xy 72.40456 -403.510619) (xy 72.458507 -403.502857) (xy 72.485758 -403.502368)
			(xy 73.349358 -403.502368) (xy 73.376611 -403.502876) (xy 73.430563 -403.510628) (xy 73.482863 -403.525979)
			(xy 73.532445 -403.548618) (xy 73.578301 -403.578083) (xy 73.619496 -403.613775) (xy 73.655192 -403.654966)
			(xy 73.684662 -403.700818) (xy 73.707306 -403.750398) (xy 73.722663 -403.802696) (xy 73.730421 -403.856647)
			(xy 73.730421 -403.911153) (xy 75.167954 -403.911153) (xy 75.167954 -403.856647) (xy 75.175711 -403.802696)
			(xy 75.191067 -403.750398) (xy 75.213709 -403.700818) (xy 75.243177 -403.654965) (xy 75.278871 -403.613772)
			(xy 75.320063 -403.578078) (xy 75.365916 -403.54861) (xy 75.415496 -403.525967) (xy 75.467794 -403.510611)
			(xy 75.521745 -403.502854) (xy 75.548998 -403.502368) (xy 76.412598 -403.502368) (xy 76.439849 -403.502879)
			(xy 76.493797 -403.510635) (xy 76.546092 -403.52599) (xy 76.595669 -403.548631) (xy 76.64152 -403.578097)
			(xy 76.68271 -403.613789) (xy 76.718401 -403.654979) (xy 76.747868 -403.700829) (xy 76.770509 -403.750406)
			(xy 76.785864 -403.802701) (xy 76.793621 -403.856649) (xy 76.793621 -403.911151) (xy 76.79362 -403.911156)
			(xy 78.231131 -403.911156) (xy 78.231131 -403.856644) (xy 78.238889 -403.802686) (xy 78.254248 -403.750382)
			(xy 78.276895 -403.700796) (xy 78.306369 -403.654938) (xy 78.342069 -403.613742) (xy 78.383268 -403.578046)
			(xy 78.429129 -403.548577) (xy 78.478717 -403.525935) (xy 78.531023 -403.510581) (xy 78.584982 -403.502828)
			(xy 78.612238 -403.502368) (xy 79.475838 -403.502368) (xy 79.503086 -403.502905) (xy 79.557026 -403.510665)
			(xy 79.609313 -403.526023) (xy 79.658882 -403.548665) (xy 79.704725 -403.57813) (xy 79.745908 -403.613819)
			(xy 79.781593 -403.655006) (xy 79.811054 -403.700851) (xy 79.833691 -403.750423) (xy 79.849043 -403.802711)
			(xy 79.856798 -403.856652) (xy 79.856798 -403.911148) (xy 79.856797 -403.911152) (xy 81.294454 -403.911152)
			(xy 81.294454 -403.856648) (xy 81.30221 -403.802699) (xy 81.317565 -403.750403) (xy 81.340206 -403.700824)
			(xy 81.369672 -403.654971) (xy 81.405364 -403.613779) (xy 81.446554 -403.578085) (xy 81.492404 -403.548617)
			(xy 81.541982 -403.525973) (xy 81.594277 -403.510615) (xy 81.648226 -403.502855) (xy 81.675478 -403.502368)
			(xy 82.539078 -403.502368) (xy 82.56633 -403.502878) (xy 82.62028 -403.510632) (xy 82.672577 -403.525985)
			(xy 82.722157 -403.548625) (xy 82.76801 -403.57809) (xy 82.809203 -403.613782) (xy 82.844897 -403.654972)
			(xy 82.874365 -403.700824) (xy 82.897007 -403.750402) (xy 82.912364 -403.802698) (xy 82.920121 -403.856648)
			(xy 82.920121 -403.911152) (xy 82.920121 -403.911155) (xy 84.357631 -403.911155) (xy 84.357631 -403.856645)
			(xy 84.365389 -403.802689) (xy 84.380747 -403.750386) (xy 84.403392 -403.700801) (xy 84.432864 -403.654945)
			(xy 84.468562 -403.613749) (xy 84.509759 -403.578053) (xy 84.555617 -403.548583) (xy 84.605203 -403.525941)
			(xy 84.657506 -403.510585) (xy 84.711463 -403.50283) (xy 84.738718 -403.502368) (xy 85.602318 -403.502368)
			(xy 85.629567 -403.502903) (xy 85.683509 -403.510662) (xy 85.735798 -403.526017) (xy 85.78537 -403.548658)
			(xy 85.831215 -403.578123) (xy 85.872401 -403.613812) (xy 85.908088 -403.654999) (xy 85.937551 -403.700846)
			(xy 85.960189 -403.750419) (xy 85.975542 -403.802709) (xy 85.983298 -403.856651) (xy 85.983298 -403.911149)
			(xy 85.983298 -403.911151) (xy 87.420954 -403.911151) (xy 87.420954 -403.856649) (xy 87.42871 -403.802702)
			(xy 87.444064 -403.750407) (xy 87.466703 -403.700829) (xy 87.496167 -403.654978) (xy 87.531857 -403.613786)
			(xy 87.573044 -403.578093) (xy 87.618892 -403.548623) (xy 87.668467 -403.525978) (xy 87.72076 -403.510619)
			(xy 87.774707 -403.502857) (xy 87.801958 -403.502368) (xy 88.665558 -403.502368) (xy 88.692811 -403.502876)
			(xy 88.746763 -403.510628) (xy 88.799063 -403.525979) (xy 88.848645 -403.548618) (xy 88.894501 -403.578083)
			(xy 88.935696 -403.613775) (xy 88.971392 -403.654966) (xy 89.000862 -403.700818) (xy 89.023506 -403.750398)
			(xy 89.038863 -403.802696) (xy 89.046621 -403.856647) (xy 89.046621 -403.911153) (xy 90.484154 -403.911153)
			(xy 90.484154 -403.856647) (xy 90.491911 -403.802696) (xy 90.507267 -403.750398) (xy 90.529909 -403.700818)
			(xy 90.559377 -403.654965) (xy 90.595071 -403.613772) (xy 90.636263 -403.578078) (xy 90.682116 -403.54861)
			(xy 90.731696 -403.525967) (xy 90.783994 -403.510611) (xy 90.837945 -403.502854) (xy 90.865198 -403.502368)
			(xy 91.728798 -403.502368) (xy 91.756049 -403.502879) (xy 91.809997 -403.510635) (xy 91.862292 -403.52599)
			(xy 91.911869 -403.548631) (xy 91.95772 -403.578097) (xy 91.99891 -403.613789) (xy 92.034601 -403.654979)
			(xy 92.064068 -403.700829) (xy 92.086709 -403.750406) (xy 92.102064 -403.802701) (xy 92.109821 -403.856649)
			(xy 92.109821 -403.911151) (xy 92.10982 -403.911156) (xy 93.547331 -403.911156) (xy 93.547331 -403.856644)
			(xy 93.555089 -403.802686) (xy 93.570448 -403.750382) (xy 93.593095 -403.700796) (xy 93.622569 -403.654938)
			(xy 93.658269 -403.613742) (xy 93.699468 -403.578046) (xy 93.745329 -403.548577) (xy 93.794917 -403.525935)
			(xy 93.847223 -403.510581) (xy 93.901182 -403.502828) (xy 93.928438 -403.502368) (xy 94.792038 -403.502368)
			(xy 94.819286 -403.502905) (xy 94.873226 -403.510665) (xy 94.925513 -403.526023) (xy 94.975082 -403.548665)
			(xy 95.020925 -403.57813) (xy 95.062108 -403.613819) (xy 95.097793 -403.655006) (xy 95.127254 -403.700851)
			(xy 95.149891 -403.750423) (xy 95.165243 -403.802711) (xy 95.172998 -403.856652) (xy 95.172998 -403.911148)
			(xy 95.172998 -403.911151) (xy 119.773954 -403.911151) (xy 119.773954 -403.856649) (xy 119.78171 -403.802702)
			(xy 119.797063 -403.750408) (xy 119.819702 -403.70083) (xy 119.849166 -403.654979) (xy 119.884855 -403.613788)
			(xy 119.926042 -403.578094) (xy 119.97189 -403.548625) (xy 120.021465 -403.525979) (xy 120.073757 -403.510619)
			(xy 120.127703 -403.502857) (xy 120.154954 -403.502368) (xy 121.018554 -403.502368) (xy 121.045807 -403.502876)
			(xy 121.09976 -403.510627) (xy 121.15206 -403.525978) (xy 121.201643 -403.548617) (xy 121.247499 -403.578082)
			(xy 121.288694 -403.613773) (xy 121.324391 -403.654964) (xy 121.353861 -403.700817) (xy 121.376506 -403.750397)
			(xy 121.391863 -403.802695) (xy 121.399621 -403.856647) (xy 121.399621 -403.911153) (xy 122.837154 -403.911153)
			(xy 122.837154 -403.856647) (xy 122.844911 -403.802697) (xy 122.860266 -403.750399) (xy 122.882909 -403.700819)
			(xy 122.912376 -403.654966) (xy 122.948069 -403.613774) (xy 122.989261 -403.57808) (xy 123.035114 -403.548611)
			(xy 123.084694 -403.525969) (xy 123.136991 -403.510612) (xy 123.190941 -403.502854) (xy 123.218194 -403.502368)
			(xy 124.081794 -403.502368) (xy 124.109045 -403.502879) (xy 124.162994 -403.510635) (xy 124.215289 -403.525989)
			(xy 124.264867 -403.54863) (xy 124.310718 -403.578096) (xy 124.351908 -403.613787) (xy 124.3876 -403.654978)
			(xy 124.417067 -403.700828) (xy 124.439709 -403.750406) (xy 124.455064 -403.802701) (xy 124.462821 -403.856649)
			(xy 124.462821 -403.911151) (xy 124.46282 -403.911156) (xy 125.900331 -403.911156) (xy 125.900331 -403.856644)
			(xy 125.908089 -403.802686) (xy 125.923448 -403.750383) (xy 125.946095 -403.700797) (xy 125.975568 -403.654939)
			(xy 126.011267 -403.613743) (xy 126.052467 -403.578047) (xy 126.098327 -403.548578) (xy 126.147914 -403.525936)
			(xy 126.20022 -403.510582) (xy 126.254178 -403.502829) (xy 126.281434 -403.502368) (xy 127.145034 -403.502368)
			(xy 127.172282 -403.502905) (xy 127.226223 -403.510664) (xy 127.27851 -403.526022) (xy 127.32808 -403.548663)
			(xy 127.373923 -403.578129) (xy 127.415106 -403.613818) (xy 127.450792 -403.655004) (xy 127.480253 -403.70085)
			(xy 127.50289 -403.750422) (xy 127.518243 -403.802711) (xy 127.525998 -403.856652) (xy 127.525998 -403.911148)
			(xy 127.525997 -403.911152) (xy 128.963654 -403.911152) (xy 128.963654 -403.856648) (xy 128.97141 -403.802699)
			(xy 128.986765 -403.750403) (xy 129.009406 -403.700825) (xy 129.038871 -403.654973) (xy 129.074562 -403.613781)
			(xy 129.115752 -403.578087) (xy 129.161602 -403.548618) (xy 129.211179 -403.525974) (xy 129.263474 -403.510616)
			(xy 129.317422 -403.502856) (xy 129.344674 -403.502368) (xy 130.208274 -403.502368) (xy 130.235526 -403.502878)
			(xy 130.289477 -403.510631) (xy 130.341774 -403.525984) (xy 130.391355 -403.548623) (xy 130.437208 -403.578089)
			(xy 130.478401 -403.61378) (xy 130.514096 -403.654971) (xy 130.543564 -403.700822) (xy 130.566207 -403.750401)
			(xy 130.581563 -403.802698) (xy 130.589321 -403.856648) (xy 130.589321 -403.911152) (xy 130.589321 -403.911155)
			(xy 132.026831 -403.911155) (xy 132.026831 -403.856645) (xy 132.034589 -403.802689) (xy 132.049946 -403.750387)
			(xy 132.072591 -403.700803) (xy 132.102063 -403.654946) (xy 132.13776 -403.61375) (xy 132.178957 -403.578054)
			(xy 132.224815 -403.548585) (xy 132.2744 -403.525942) (xy 132.326703 -403.510586) (xy 132.380659 -403.50283)
			(xy 132.407914 -403.502368) (xy 133.271514 -403.502368) (xy 133.298763 -403.502903) (xy 133.352706 -403.510661)
			(xy 133.404995 -403.526016) (xy 133.454568 -403.548657) (xy 133.500413 -403.578121) (xy 133.541599 -403.613811)
			(xy 133.577287 -403.654998) (xy 133.60675 -403.700845) (xy 133.629389 -403.750418) (xy 133.644742 -403.802708)
			(xy 133.652498 -403.856651) (xy 133.652498 -403.911149) (xy 133.652498 -403.911151) (xy 135.090154 -403.911151)
			(xy 135.090154 -403.856649) (xy 135.09791 -403.802702) (xy 135.113263 -403.750408) (xy 135.135902 -403.70083)
			(xy 135.165366 -403.654979) (xy 135.201055 -403.613788) (xy 135.242242 -403.578094) (xy 135.28809 -403.548625)
			(xy 135.337665 -403.525979) (xy 135.389957 -403.510619) (xy 135.443903 -403.502857) (xy 135.471154 -403.502368)
			(xy 136.334754 -403.502368) (xy 136.362007 -403.502876) (xy 136.41596 -403.510627) (xy 136.46826 -403.525978)
			(xy 136.517843 -403.548617) (xy 136.563699 -403.578082) (xy 136.604894 -403.613773) (xy 136.640591 -403.654964)
			(xy 136.670061 -403.700817) (xy 136.692706 -403.750397) (xy 136.708063 -403.802695) (xy 136.715821 -403.856647)
			(xy 136.715821 -403.911153) (xy 138.153354 -403.911153) (xy 138.153354 -403.856647) (xy 138.161111 -403.802697)
			(xy 138.176466 -403.750399) (xy 138.199109 -403.700819) (xy 138.228576 -403.654966) (xy 138.264269 -403.613774)
			(xy 138.305461 -403.57808) (xy 138.351314 -403.548611) (xy 138.400894 -403.525969) (xy 138.453191 -403.510612)
			(xy 138.507141 -403.502854) (xy 138.534394 -403.502368) (xy 139.397994 -403.502368) (xy 139.425245 -403.502879)
			(xy 139.479194 -403.510635) (xy 139.531489 -403.525989) (xy 139.581067 -403.54863) (xy 139.626918 -403.578096)
			(xy 139.668108 -403.613787) (xy 139.7038 -403.654978) (xy 139.733267 -403.700828) (xy 139.755909 -403.750406)
			(xy 139.771264 -403.802701) (xy 139.779021 -403.856649) (xy 139.779021 -403.911151) (xy 139.77902 -403.911156)
			(xy 141.216531 -403.911156) (xy 141.216531 -403.856644) (xy 141.224289 -403.802686) (xy 141.239648 -403.750383)
			(xy 141.262295 -403.700797) (xy 141.291768 -403.654939) (xy 141.327467 -403.613743) (xy 141.368667 -403.578047)
			(xy 141.414527 -403.548578) (xy 141.464114 -403.525936) (xy 141.51642 -403.510582) (xy 141.570378 -403.502829)
			(xy 141.597634 -403.502368) (xy 142.461234 -403.502368) (xy 142.488482 -403.502905) (xy 142.542423 -403.510664)
			(xy 142.59471 -403.526022) (xy 142.64428 -403.548663) (xy 142.690123 -403.578129) (xy 142.731306 -403.613818)
			(xy 142.766992 -403.655004) (xy 142.796453 -403.70085) (xy 142.81909 -403.750422) (xy 142.834443 -403.802711)
			(xy 142.842198 -403.856652) (xy 142.842198 -403.911148) (xy 142.842197 -403.911152) (xy 144.279854 -403.911152)
			(xy 144.279854 -403.856648) (xy 144.28761 -403.802699) (xy 144.302965 -403.750403) (xy 144.325606 -403.700825)
			(xy 144.355071 -403.654973) (xy 144.390762 -403.613781) (xy 144.431952 -403.578087) (xy 144.477802 -403.548618)
			(xy 144.527379 -403.525974) (xy 144.579674 -403.510616) (xy 144.633622 -403.502856) (xy 144.660874 -403.502368)
			(xy 145.524474 -403.502368) (xy 145.551726 -403.502878) (xy 145.605677 -403.510631) (xy 145.657974 -403.525984)
			(xy 145.707555 -403.548623) (xy 145.753408 -403.578089) (xy 145.794601 -403.61378) (xy 145.830296 -403.654971)
			(xy 145.859764 -403.700822) (xy 145.882407 -403.750401) (xy 145.897763 -403.802698) (xy 145.905521 -403.856648)
			(xy 145.905521 -403.911152) (xy 145.905521 -403.911155) (xy 147.343031 -403.911155) (xy 147.343031 -403.856645)
			(xy 147.350789 -403.802689) (xy 147.366146 -403.750387) (xy 147.388791 -403.700803) (xy 147.418263 -403.654946)
			(xy 147.45396 -403.61375) (xy 147.495157 -403.578054) (xy 147.541015 -403.548585) (xy 147.5906 -403.525942)
			(xy 147.642903 -403.510586) (xy 147.696859 -403.50283) (xy 147.724114 -403.502368) (xy 148.587714 -403.502368)
			(xy 148.614963 -403.502903) (xy 148.668906 -403.510661) (xy 148.721195 -403.526016) (xy 148.770768 -403.548657)
			(xy 148.816613 -403.578121) (xy 148.857799 -403.613811) (xy 148.893487 -403.654998) (xy 148.92295 -403.700845)
			(xy 148.945589 -403.750418) (xy 148.960942 -403.802708) (xy 148.968698 -403.856651) (xy 148.968698 -403.911149)
			(xy 148.968698 -403.911151) (xy 150.406354 -403.911151) (xy 150.406354 -403.856649) (xy 150.41411 -403.802702)
			(xy 150.429463 -403.750408) (xy 150.452102 -403.70083) (xy 150.481566 -403.654979) (xy 150.517255 -403.613788)
			(xy 150.558442 -403.578094) (xy 150.60429 -403.548625) (xy 150.653865 -403.525979) (xy 150.706157 -403.510619)
			(xy 150.760103 -403.502857) (xy 150.787354 -403.502368) (xy 151.650954 -403.502368) (xy 151.678207 -403.502876)
			(xy 151.73216 -403.510627) (xy 151.78446 -403.525978) (xy 151.834043 -403.548617) (xy 151.879899 -403.578082)
			(xy 151.921094 -403.613773) (xy 151.956791 -403.654964) (xy 151.986261 -403.700817) (xy 152.008906 -403.750397)
			(xy 152.024263 -403.802695) (xy 152.032021 -403.856647) (xy 152.032021 -403.911153) (xy 153.469554 -403.911153)
			(xy 153.469554 -403.856647) (xy 153.477311 -403.802697) (xy 153.492666 -403.750399) (xy 153.515309 -403.700819)
			(xy 153.544776 -403.654966) (xy 153.580469 -403.613774) (xy 153.621661 -403.57808) (xy 153.667514 -403.548611)
			(xy 153.717094 -403.525969) (xy 153.769391 -403.510612) (xy 153.823341 -403.502854) (xy 153.850594 -403.502368)
			(xy 154.714194 -403.502368) (xy 154.741445 -403.502879) (xy 154.795394 -403.510635) (xy 154.847689 -403.525989)
			(xy 154.897267 -403.54863) (xy 154.943118 -403.578096) (xy 154.984308 -403.613787) (xy 155.02 -403.654978)
			(xy 155.049467 -403.700828) (xy 155.072109 -403.750406) (xy 155.087464 -403.802701) (xy 155.095221 -403.856649)
			(xy 155.095221 -403.911151) (xy 155.09522 -403.911156) (xy 156.532731 -403.911156) (xy 156.532731 -403.856644)
			(xy 156.540489 -403.802686) (xy 156.555848 -403.750383) (xy 156.578495 -403.700797) (xy 156.607968 -403.654939)
			(xy 156.643667 -403.613743) (xy 156.684867 -403.578047) (xy 156.730727 -403.548578) (xy 156.780314 -403.525936)
			(xy 156.83262 -403.510582) (xy 156.886578 -403.502829) (xy 156.913834 -403.502368) (xy 157.777434 -403.502368)
			(xy 157.804682 -403.502905) (xy 157.858623 -403.510664) (xy 157.91091 -403.526022) (xy 157.96048 -403.548663)
			(xy 158.006323 -403.578129) (xy 158.047506 -403.613818) (xy 158.083192 -403.655004) (xy 158.112653 -403.70085)
			(xy 158.13529 -403.750422) (xy 158.150643 -403.802711) (xy 158.158398 -403.856652) (xy 158.158398 -403.911148)
			(xy 158.158397 -403.911152) (xy 159.596054 -403.911152) (xy 159.596054 -403.856648) (xy 159.60381 -403.802699)
			(xy 159.619165 -403.750403) (xy 159.641806 -403.700825) (xy 159.671271 -403.654973) (xy 159.706962 -403.613781)
			(xy 159.748152 -403.578087) (xy 159.794002 -403.548618) (xy 159.843579 -403.525974) (xy 159.895874 -403.510616)
			(xy 159.949822 -403.502856) (xy 159.977074 -403.502368) (xy 160.840674 -403.502368) (xy 160.867926 -403.502878)
			(xy 160.921877 -403.510631) (xy 160.974174 -403.525984) (xy 161.023755 -403.548623) (xy 161.069608 -403.578089)
			(xy 161.110801 -403.61378) (xy 161.146496 -403.654971) (xy 161.175964 -403.700822) (xy 161.198607 -403.750401)
			(xy 161.213963 -403.802698) (xy 161.221721 -403.856648) (xy 161.221721 -403.911152) (xy 161.221721 -403.911155)
			(xy 162.659231 -403.911155) (xy 162.659231 -403.856645) (xy 162.666989 -403.802689) (xy 162.682346 -403.750387)
			(xy 162.704991 -403.700803) (xy 162.734463 -403.654946) (xy 162.77016 -403.61375) (xy 162.811357 -403.578054)
			(xy 162.857215 -403.548585) (xy 162.9068 -403.525942) (xy 162.959103 -403.510586) (xy 163.013059 -403.50283)
			(xy 163.040314 -403.502368) (xy 163.903914 -403.502368) (xy 163.931163 -403.502903) (xy 163.985106 -403.510661)
			(xy 164.037395 -403.526016) (xy 164.086968 -403.548657) (xy 164.132813 -403.578121) (xy 164.173999 -403.613811)
			(xy 164.209687 -403.654998) (xy 164.23915 -403.700845) (xy 164.261789 -403.750418) (xy 164.277142 -403.802708)
			(xy 164.284898 -403.856651) (xy 164.284898 -403.911149) (xy 164.284898 -403.911151) (xy 165.722554 -403.911151)
			(xy 165.722554 -403.856649) (xy 165.73031 -403.802702) (xy 165.745663 -403.750408) (xy 165.768302 -403.70083)
			(xy 165.797766 -403.654979) (xy 165.833455 -403.613788) (xy 165.874642 -403.578094) (xy 165.92049 -403.548625)
			(xy 165.970065 -403.525979) (xy 166.022357 -403.510619) (xy 166.076303 -403.502857) (xy 166.103554 -403.502368)
			(xy 166.967154 -403.502368) (xy 166.994407 -403.502876) (xy 167.04836 -403.510627) (xy 167.10066 -403.525978)
			(xy 167.150243 -403.548617) (xy 167.196099 -403.578082) (xy 167.237294 -403.613773) (xy 167.272991 -403.654964)
			(xy 167.302461 -403.700817) (xy 167.325106 -403.750397) (xy 167.340463 -403.802695) (xy 167.348221 -403.856647)
			(xy 167.348221 -403.911153) (xy 167.340463 -403.965105) (xy 167.325106 -404.017403) (xy 167.302461 -404.066983)
			(xy 167.272991 -404.112836) (xy 167.237294 -404.154027) (xy 167.196099 -404.189718) (xy 167.150243 -404.219183)
			(xy 167.10066 -404.241822) (xy 167.04836 -404.257173) (xy 166.994407 -404.264924) (xy 166.967154 -404.265384)
			(xy 166.103554 -404.265384) (xy 166.076303 -404.264943) (xy 166.022357 -404.257181) (xy 165.970065 -404.241821)
			(xy 165.92049 -404.219175) (xy 165.874642 -404.189706) (xy 165.833455 -404.154012) (xy 165.797766 -404.112821)
			(xy 165.768302 -404.06697) (xy 165.745663 -404.017392) (xy 165.73031 -403.965098) (xy 165.722554 -403.911151)
			(xy 164.284898 -403.911151) (xy 164.277142 -403.965092) (xy 164.261789 -404.017382) (xy 164.23915 -404.066955)
			(xy 164.209687 -404.112802) (xy 164.173999 -404.153989) (xy 164.132813 -404.189679) (xy 164.086968 -404.219143)
			(xy 164.037395 -404.241784) (xy 163.985106 -404.257139) (xy 163.931163 -404.264897) (xy 163.903914 -404.265384)
			(xy 163.040314 -404.265384) (xy 163.013059 -404.26497) (xy 162.959103 -404.257214) (xy 162.9068 -404.241858)
			(xy 162.857215 -404.219215) (xy 162.811357 -404.189746) (xy 162.77016 -404.15405) (xy 162.734463 -404.112854)
			(xy 162.704991 -404.066997) (xy 162.682346 -404.017413) (xy 162.666989 -403.965111) (xy 162.659231 -403.911155)
			(xy 161.221721 -403.911155) (xy 161.213963 -403.965102) (xy 161.198607 -404.017399) (xy 161.175964 -404.066978)
			(xy 161.146496 -404.112829) (xy 161.110801 -404.15402) (xy 161.069608 -404.189711) (xy 161.023755 -404.219177)
			(xy 160.974174 -404.241816) (xy 160.921877 -404.257169) (xy 160.867926 -404.264922) (xy 160.840674 -404.265384)
			(xy 159.977074 -404.265384) (xy 159.949822 -404.264944) (xy 159.895874 -404.257184) (xy 159.843579 -404.241826)
			(xy 159.794002 -404.219182) (xy 159.748152 -404.189713) (xy 159.706962 -404.154019) (xy 159.671271 -404.112827)
			(xy 159.641806 -404.066975) (xy 159.619165 -404.017397) (xy 159.60381 -403.965101) (xy 159.596054 -403.911152)
			(xy 158.158397 -403.911152) (xy 158.150643 -403.965089) (xy 158.13529 -404.017378) (xy 158.112653 -404.06695)
			(xy 158.083192 -404.112796) (xy 158.047506 -404.153982) (xy 158.006323 -404.189671) (xy 157.96048 -404.219137)
			(xy 157.91091 -404.241778) (xy 157.858623 -404.257136) (xy 157.804682 -404.264895) (xy 157.777434 -404.265384)
			(xy 156.913834 -404.265384) (xy 156.886578 -404.264971) (xy 156.83262 -404.257218) (xy 156.780314 -404.241864)
			(xy 156.730727 -404.219222) (xy 156.684867 -404.189753) (xy 156.643667 -404.154057) (xy 156.607968 -404.112861)
			(xy 156.578495 -404.067003) (xy 156.555848 -404.017417) (xy 156.540489 -403.965114) (xy 156.532731 -403.911156)
			(xy 155.09522 -403.911156) (xy 155.087464 -403.965099) (xy 155.072109 -404.017394) (xy 155.049467 -404.066972)
			(xy 155.02 -404.112822) (xy 154.984308 -404.154013) (xy 154.943118 -404.189704) (xy 154.897267 -404.21917)
			(xy 154.847689 -404.241811) (xy 154.795394 -404.257165) (xy 154.741445 -404.264921) (xy 154.714194 -404.265384)
			(xy 153.850594 -404.265384) (xy 153.823341 -404.264946) (xy 153.769391 -404.257188) (xy 153.717094 -404.241831)
			(xy 153.667514 -404.219189) (xy 153.621661 -404.18972) (xy 153.580469 -404.154026) (xy 153.544776 -404.112834)
			(xy 153.515309 -404.066981) (xy 153.492666 -404.017401) (xy 153.477311 -403.965103) (xy 153.469554 -403.911153)
			(xy 152.032021 -403.911153) (xy 152.024263 -403.965105) (xy 152.008906 -404.017403) (xy 151.986261 -404.066983)
			(xy 151.956791 -404.112836) (xy 151.921094 -404.154027) (xy 151.879899 -404.189718) (xy 151.834043 -404.219183)
			(xy 151.78446 -404.241822) (xy 151.73216 -404.257173) (xy 151.678207 -404.264924) (xy 151.650954 -404.265384)
			(xy 150.787354 -404.265384) (xy 150.760103 -404.264943) (xy 150.706157 -404.257181) (xy 150.653865 -404.241821)
			(xy 150.60429 -404.219175) (xy 150.558442 -404.189706) (xy 150.517255 -404.154012) (xy 150.481566 -404.112821)
			(xy 150.452102 -404.06697) (xy 150.429463 -404.017392) (xy 150.41411 -403.965098) (xy 150.406354 -403.911151)
			(xy 148.968698 -403.911151) (xy 148.960942 -403.965092) (xy 148.945589 -404.017382) (xy 148.92295 -404.066955)
			(xy 148.893487 -404.112802) (xy 148.857799 -404.153989) (xy 148.816613 -404.189679) (xy 148.770768 -404.219143)
			(xy 148.721195 -404.241784) (xy 148.668906 -404.257139) (xy 148.614963 -404.264897) (xy 148.587714 -404.265384)
			(xy 147.724114 -404.265384) (xy 147.696859 -404.26497) (xy 147.642903 -404.257214) (xy 147.5906 -404.241858)
			(xy 147.541015 -404.219215) (xy 147.495157 -404.189746) (xy 147.45396 -404.15405) (xy 147.418263 -404.112854)
			(xy 147.388791 -404.066997) (xy 147.366146 -404.017413) (xy 147.350789 -403.965111) (xy 147.343031 -403.911155)
			(xy 145.905521 -403.911155) (xy 145.897763 -403.965102) (xy 145.882407 -404.017399) (xy 145.859764 -404.066978)
			(xy 145.830296 -404.112829) (xy 145.794601 -404.15402) (xy 145.753408 -404.189711) (xy 145.707555 -404.219177)
			(xy 145.657974 -404.241816) (xy 145.605677 -404.257169) (xy 145.551726 -404.264922) (xy 145.524474 -404.265384)
			(xy 144.660874 -404.265384) (xy 144.633622 -404.264944) (xy 144.579674 -404.257184) (xy 144.527379 -404.241826)
			(xy 144.477802 -404.219182) (xy 144.431952 -404.189713) (xy 144.390762 -404.154019) (xy 144.355071 -404.112827)
			(xy 144.325606 -404.066975) (xy 144.302965 -404.017397) (xy 144.28761 -403.965101) (xy 144.279854 -403.911152)
			(xy 142.842197 -403.911152) (xy 142.834443 -403.965089) (xy 142.81909 -404.017378) (xy 142.796453 -404.06695)
			(xy 142.766992 -404.112796) (xy 142.731306 -404.153982) (xy 142.690123 -404.189671) (xy 142.64428 -404.219137)
			(xy 142.59471 -404.241778) (xy 142.542423 -404.257136) (xy 142.488482 -404.264895) (xy 142.461234 -404.265384)
			(xy 141.597634 -404.265384) (xy 141.570378 -404.264971) (xy 141.51642 -404.257218) (xy 141.464114 -404.241864)
			(xy 141.414527 -404.219222) (xy 141.368667 -404.189753) (xy 141.327467 -404.154057) (xy 141.291768 -404.112861)
			(xy 141.262295 -404.067003) (xy 141.239648 -404.017417) (xy 141.224289 -403.965114) (xy 141.216531 -403.911156)
			(xy 139.77902 -403.911156) (xy 139.771264 -403.965099) (xy 139.755909 -404.017394) (xy 139.733267 -404.066972)
			(xy 139.7038 -404.112822) (xy 139.668108 -404.154013) (xy 139.626918 -404.189704) (xy 139.581067 -404.21917)
			(xy 139.531489 -404.241811) (xy 139.479194 -404.257165) (xy 139.425245 -404.264921) (xy 139.397994 -404.265384)
			(xy 138.534394 -404.265384) (xy 138.507141 -404.264946) (xy 138.453191 -404.257188) (xy 138.400894 -404.241831)
			(xy 138.351314 -404.219189) (xy 138.305461 -404.18972) (xy 138.264269 -404.154026) (xy 138.228576 -404.112834)
			(xy 138.199109 -404.066981) (xy 138.176466 -404.017401) (xy 138.161111 -403.965103) (xy 138.153354 -403.911153)
			(xy 136.715821 -403.911153) (xy 136.708063 -403.965105) (xy 136.692706 -404.017403) (xy 136.670061 -404.066983)
			(xy 136.640591 -404.112836) (xy 136.604894 -404.154027) (xy 136.563699 -404.189718) (xy 136.517843 -404.219183)
			(xy 136.46826 -404.241822) (xy 136.41596 -404.257173) (xy 136.362007 -404.264924) (xy 136.334754 -404.265384)
			(xy 135.471154 -404.265384) (xy 135.443903 -404.264943) (xy 135.389957 -404.257181) (xy 135.337665 -404.241821)
			(xy 135.28809 -404.219175) (xy 135.242242 -404.189706) (xy 135.201055 -404.154012) (xy 135.165366 -404.112821)
			(xy 135.135902 -404.06697) (xy 135.113263 -404.017392) (xy 135.09791 -403.965098) (xy 135.090154 -403.911151)
			(xy 133.652498 -403.911151) (xy 133.644742 -403.965092) (xy 133.629389 -404.017382) (xy 133.60675 -404.066955)
			(xy 133.577287 -404.112802) (xy 133.541599 -404.153989) (xy 133.500413 -404.189679) (xy 133.454568 -404.219143)
			(xy 133.404995 -404.241784) (xy 133.352706 -404.257139) (xy 133.298763 -404.264897) (xy 133.271514 -404.265384)
			(xy 132.407914 -404.265384) (xy 132.380659 -404.26497) (xy 132.326703 -404.257214) (xy 132.2744 -404.241858)
			(xy 132.224815 -404.219215) (xy 132.178957 -404.189746) (xy 132.13776 -404.15405) (xy 132.102063 -404.112854)
			(xy 132.072591 -404.066997) (xy 132.049946 -404.017413) (xy 132.034589 -403.965111) (xy 132.026831 -403.911155)
			(xy 130.589321 -403.911155) (xy 130.581563 -403.965102) (xy 130.566207 -404.017399) (xy 130.543564 -404.066978)
			(xy 130.514096 -404.112829) (xy 130.478401 -404.15402) (xy 130.437208 -404.189711) (xy 130.391355 -404.219177)
			(xy 130.341774 -404.241816) (xy 130.289477 -404.257169) (xy 130.235526 -404.264922) (xy 130.208274 -404.265384)
			(xy 129.344674 -404.265384) (xy 129.317422 -404.264944) (xy 129.263474 -404.257184) (xy 129.211179 -404.241826)
			(xy 129.161602 -404.219182) (xy 129.115752 -404.189713) (xy 129.074562 -404.154019) (xy 129.038871 -404.112827)
			(xy 129.009406 -404.066975) (xy 128.986765 -404.017397) (xy 128.97141 -403.965101) (xy 128.963654 -403.911152)
			(xy 127.525997 -403.911152) (xy 127.518243 -403.965089) (xy 127.50289 -404.017378) (xy 127.480253 -404.06695)
			(xy 127.450792 -404.112796) (xy 127.415106 -404.153982) (xy 127.373923 -404.189671) (xy 127.32808 -404.219137)
			(xy 127.27851 -404.241778) (xy 127.226223 -404.257136) (xy 127.172282 -404.264895) (xy 127.145034 -404.265384)
			(xy 126.281434 -404.265384) (xy 126.254178 -404.264971) (xy 126.20022 -404.257218) (xy 126.147914 -404.241864)
			(xy 126.098327 -404.219222) (xy 126.052467 -404.189753) (xy 126.011267 -404.154057) (xy 125.975568 -404.112861)
			(xy 125.946095 -404.067003) (xy 125.923448 -404.017417) (xy 125.908089 -403.965114) (xy 125.900331 -403.911156)
			(xy 124.46282 -403.911156) (xy 124.455064 -403.965099) (xy 124.439709 -404.017394) (xy 124.417067 -404.066972)
			(xy 124.3876 -404.112822) (xy 124.351908 -404.154013) (xy 124.310718 -404.189704) (xy 124.264867 -404.21917)
			(xy 124.215289 -404.241811) (xy 124.162994 -404.257165) (xy 124.109045 -404.264921) (xy 124.081794 -404.265384)
			(xy 123.218194 -404.265384) (xy 123.190941 -404.264946) (xy 123.136991 -404.257188) (xy 123.084694 -404.241831)
			(xy 123.035114 -404.219189) (xy 122.989261 -404.18972) (xy 122.948069 -404.154026) (xy 122.912376 -404.112834)
			(xy 122.882909 -404.066981) (xy 122.860266 -404.017401) (xy 122.844911 -403.965103) (xy 122.837154 -403.911153)
			(xy 121.399621 -403.911153) (xy 121.391863 -403.965105) (xy 121.376506 -404.017403) (xy 121.353861 -404.066983)
			(xy 121.324391 -404.112836) (xy 121.288694 -404.154027) (xy 121.247499 -404.189718) (xy 121.201643 -404.219183)
			(xy 121.15206 -404.241822) (xy 121.09976 -404.257173) (xy 121.045807 -404.264924) (xy 121.018554 -404.265384)
			(xy 120.154954 -404.265384) (xy 120.127703 -404.264943) (xy 120.073757 -404.257181) (xy 120.021465 -404.241821)
			(xy 119.97189 -404.219175) (xy 119.926042 -404.189706) (xy 119.884855 -404.154012) (xy 119.849166 -404.112821)
			(xy 119.819702 -404.06697) (xy 119.797063 -404.017392) (xy 119.78171 -403.965098) (xy 119.773954 -403.911151)
			(xy 95.172998 -403.911151) (xy 95.165243 -403.965089) (xy 95.149891 -404.017377) (xy 95.127254 -404.066949)
			(xy 95.097793 -404.112794) (xy 95.062108 -404.153981) (xy 95.020925 -404.18967) (xy 94.975082 -404.219135)
			(xy 94.925513 -404.241777) (xy 94.873226 -404.257135) (xy 94.819286 -404.264895) (xy 94.792038 -404.265384)
			(xy 93.928438 -404.265384) (xy 93.901182 -404.264972) (xy 93.847223 -404.257219) (xy 93.794917 -404.241865)
			(xy 93.745329 -404.219223) (xy 93.699468 -404.189754) (xy 93.658269 -404.154058) (xy 93.622569 -404.112862)
			(xy 93.593095 -404.067004) (xy 93.570448 -404.017418) (xy 93.555089 -403.965114) (xy 93.547331 -403.911156)
			(xy 92.10982 -403.911156) (xy 92.102064 -403.965099) (xy 92.086709 -404.017394) (xy 92.064068 -404.066971)
			(xy 92.034601 -404.112821) (xy 91.99891 -404.154011) (xy 91.95772 -404.189703) (xy 91.911869 -404.219169)
			(xy 91.862292 -404.24181) (xy 91.809997 -404.257165) (xy 91.756049 -404.264921) (xy 91.728798 -404.265384)
			(xy 90.865198 -404.265384) (xy 90.837945 -404.264946) (xy 90.783994 -404.257189) (xy 90.731696 -404.241833)
			(xy 90.682116 -404.21919) (xy 90.636263 -404.189722) (xy 90.595071 -404.154028) (xy 90.559377 -404.112835)
			(xy 90.529909 -404.066982) (xy 90.507267 -404.017402) (xy 90.491911 -403.965104) (xy 90.484154 -403.911153)
			(xy 89.046621 -403.911153) (xy 89.038863 -403.965104) (xy 89.023506 -404.017402) (xy 89.000862 -404.066982)
			(xy 88.971392 -404.112834) (xy 88.935696 -404.154025) (xy 88.894501 -404.189717) (xy 88.848645 -404.219182)
			(xy 88.799063 -404.241821) (xy 88.746763 -404.257172) (xy 88.692811 -404.264924) (xy 88.665558 -404.265384)
			(xy 87.801958 -404.265384) (xy 87.774707 -404.264943) (xy 87.72076 -404.257181) (xy 87.668467 -404.241822)
			(xy 87.618892 -404.219177) (xy 87.573044 -404.189707) (xy 87.531857 -404.154014) (xy 87.496167 -404.112822)
			(xy 87.466703 -404.066971) (xy 87.444064 -404.017393) (xy 87.42871 -403.965098) (xy 87.420954 -403.911151)
			(xy 85.983298 -403.911151) (xy 85.975542 -403.965091) (xy 85.960189 -404.017381) (xy 85.937551 -404.066954)
			(xy 85.908088 -404.112801) (xy 85.872401 -404.153988) (xy 85.831215 -404.189677) (xy 85.78537 -404.219142)
			(xy 85.735798 -404.241783) (xy 85.683509 -404.257138) (xy 85.629567 -404.264897) (xy 85.602318 -404.265384)
			(xy 84.738718 -404.265384) (xy 84.711463 -404.26497) (xy 84.657506 -404.257215) (xy 84.605203 -404.241859)
			(xy 84.555617 -404.219217) (xy 84.509759 -404.189747) (xy 84.468562 -404.154051) (xy 84.432864 -404.112855)
			(xy 84.403392 -404.066999) (xy 84.380747 -404.017414) (xy 84.365389 -403.965111) (xy 84.357631 -403.911155)
			(xy 82.920121 -403.911155) (xy 82.912364 -403.965102) (xy 82.897007 -404.017398) (xy 82.874365 -404.066976)
			(xy 82.844897 -404.112828) (xy 82.809203 -404.154018) (xy 82.76801 -404.18971) (xy 82.722157 -404.219175)
			(xy 82.672577 -404.241815) (xy 82.62028 -404.257168) (xy 82.56633 -404.264922) (xy 82.539078 -404.265384)
			(xy 81.675478 -404.265384) (xy 81.648226 -404.264945) (xy 81.594277 -404.257185) (xy 81.541982 -404.241827)
			(xy 81.492404 -404.219183) (xy 81.446554 -404.189715) (xy 81.405364 -404.154021) (xy 81.369672 -404.112829)
			(xy 81.340206 -404.066976) (xy 81.317565 -404.017397) (xy 81.30221 -403.965101) (xy 81.294454 -403.911152)
			(xy 79.856797 -403.911152) (xy 79.849043 -403.965089) (xy 79.833691 -404.017377) (xy 79.811054 -404.066949)
			(xy 79.781593 -404.112794) (xy 79.745908 -404.153981) (xy 79.704725 -404.18967) (xy 79.658882 -404.219135)
			(xy 79.609313 -404.241777) (xy 79.557026 -404.257135) (xy 79.503086 -404.264895) (xy 79.475838 -404.265384)
			(xy 78.612238 -404.265384) (xy 78.584982 -404.264972) (xy 78.531023 -404.257219) (xy 78.478717 -404.241865)
			(xy 78.429129 -404.219223) (xy 78.383268 -404.189754) (xy 78.342069 -404.154058) (xy 78.306369 -404.112862)
			(xy 78.276895 -404.067004) (xy 78.254248 -404.017418) (xy 78.238889 -403.965114) (xy 78.231131 -403.911156)
			(xy 76.79362 -403.911156) (xy 76.785864 -403.965099) (xy 76.770509 -404.017394) (xy 76.747868 -404.066971)
			(xy 76.718401 -404.112821) (xy 76.68271 -404.154011) (xy 76.64152 -404.189703) (xy 76.595669 -404.219169)
			(xy 76.546092 -404.24181) (xy 76.493797 -404.257165) (xy 76.439849 -404.264921) (xy 76.412598 -404.265384)
			(xy 75.548998 -404.265384) (xy 75.521745 -404.264946) (xy 75.467794 -404.257189) (xy 75.415496 -404.241833)
			(xy 75.365916 -404.21919) (xy 75.320063 -404.189722) (xy 75.278871 -404.154028) (xy 75.243177 -404.112835)
			(xy 75.213709 -404.066982) (xy 75.191067 -404.017402) (xy 75.175711 -403.965104) (xy 75.167954 -403.911153)
			(xy 73.730421 -403.911153) (xy 73.722663 -403.965104) (xy 73.707306 -404.017402) (xy 73.684662 -404.066982)
			(xy 73.655192 -404.112834) (xy 73.619496 -404.154025) (xy 73.578301 -404.189717) (xy 73.532445 -404.219182)
			(xy 73.482863 -404.241821) (xy 73.430563 -404.257172) (xy 73.376611 -404.264924) (xy 73.349358 -404.265384)
			(xy 72.485758 -404.265384) (xy 72.458507 -404.264943) (xy 72.40456 -404.257181) (xy 72.352267 -404.241822)
			(xy 72.302692 -404.219177) (xy 72.256844 -404.189707) (xy 72.215657 -404.154014) (xy 72.179967 -404.112822)
			(xy 72.150503 -404.066971) (xy 72.127864 -404.017393) (xy 72.11251 -403.965098) (xy 72.104754 -403.911151)
			(xy 70.667098 -403.911151) (xy 70.659342 -403.965091) (xy 70.643989 -404.017381) (xy 70.621351 -404.066954)
			(xy 70.591888 -404.112801) (xy 70.556201 -404.153988) (xy 70.515015 -404.189677) (xy 70.46917 -404.219142)
			(xy 70.419598 -404.241783) (xy 70.367309 -404.257138) (xy 70.313367 -404.264897) (xy 70.286118 -404.265384)
			(xy 69.422518 -404.265384) (xy 69.395263 -404.26497) (xy 69.341306 -404.257215) (xy 69.289003 -404.241859)
			(xy 69.239417 -404.219217) (xy 69.193559 -404.189747) (xy 69.152362 -404.154051) (xy 69.116664 -404.112855)
			(xy 69.087192 -404.066999) (xy 69.064547 -404.017414) (xy 69.049189 -403.965111) (xy 69.041431 -403.911155)
			(xy 67.603921 -403.911155) (xy 67.596164 -403.965102) (xy 67.580807 -404.017398) (xy 67.558165 -404.066976)
			(xy 67.528697 -404.112828) (xy 67.493003 -404.154018) (xy 67.45181 -404.18971) (xy 67.405957 -404.219175)
			(xy 67.356377 -404.241815) (xy 67.30408 -404.257168) (xy 67.25013 -404.264922) (xy 67.222878 -404.265384)
			(xy 66.359278 -404.265384) (xy 66.332026 -404.264945) (xy 66.278077 -404.257185) (xy 66.225782 -404.241827)
			(xy 66.176204 -404.219183) (xy 66.130354 -404.189715) (xy 66.089164 -404.154021) (xy 66.053472 -404.112829)
			(xy 66.024006 -404.066976) (xy 66.001365 -404.017397) (xy 65.98601 -403.965101) (xy 65.978254 -403.911152)
			(xy 64.540597 -403.911152) (xy 64.532843 -403.965089) (xy 64.517491 -404.017377) (xy 64.494854 -404.066949)
			(xy 64.465393 -404.112794) (xy 64.429708 -404.153981) (xy 64.388525 -404.18967) (xy 64.342682 -404.219135)
			(xy 64.293113 -404.241777) (xy 64.240826 -404.257135) (xy 64.186886 -404.264895) (xy 64.159638 -404.265384)
			(xy 63.296038 -404.265384) (xy 63.268782 -404.264972) (xy 63.214823 -404.257219) (xy 63.162517 -404.241865)
			(xy 63.112929 -404.219223) (xy 63.067068 -404.189754) (xy 63.025869 -404.154058) (xy 62.990169 -404.112862)
			(xy 62.960695 -404.067004) (xy 62.938048 -404.017418) (xy 62.922689 -403.965114) (xy 62.914931 -403.911156)
			(xy 61.47742 -403.911156) (xy 61.469664 -403.965099) (xy 61.454309 -404.017394) (xy 61.431668 -404.066971)
			(xy 61.402201 -404.112821) (xy 61.36651 -404.154011) (xy 61.32532 -404.189703) (xy 61.279469 -404.219169)
			(xy 61.229892 -404.24181) (xy 61.177597 -404.257165) (xy 61.123649 -404.264921) (xy 61.096398 -404.265384)
			(xy 60.232798 -404.265384) (xy 60.205545 -404.264946) (xy 60.151594 -404.257189) (xy 60.099296 -404.241833)
			(xy 60.049716 -404.21919) (xy 60.003863 -404.189722) (xy 59.962671 -404.154028) (xy 59.926977 -404.112835)
			(xy 59.897509 -404.066982) (xy 59.874867 -404.017402) (xy 59.859511 -403.965104) (xy 59.851754 -403.911153)
			(xy 58.414221 -403.911153) (xy 58.406463 -403.965104) (xy 58.391106 -404.017402) (xy 58.368462 -404.066982)
			(xy 58.338992 -404.112834) (xy 58.303296 -404.154025) (xy 58.262101 -404.189717) (xy 58.216245 -404.219182)
			(xy 58.166663 -404.241821) (xy 58.114363 -404.257172) (xy 58.060411 -404.264924) (xy 58.033158 -404.265384)
			(xy 57.169558 -404.265384) (xy 57.142307 -404.264943) (xy 57.08836 -404.257181) (xy 57.036067 -404.241822)
			(xy 56.986492 -404.219177) (xy 56.940644 -404.189707) (xy 56.899457 -404.154014) (xy 56.863767 -404.112822)
			(xy 56.834303 -404.066971) (xy 56.811664 -404.017393) (xy 56.79631 -403.965098) (xy 56.788554 -403.911151)
			(xy 55.350898 -403.911151) (xy 55.343142 -403.965091) (xy 55.327789 -404.017381) (xy 55.305151 -404.066954)
			(xy 55.275688 -404.112801) (xy 55.240001 -404.153988) (xy 55.198815 -404.189677) (xy 55.15297 -404.219142)
			(xy 55.103398 -404.241783) (xy 55.051109 -404.257138) (xy 54.997167 -404.264897) (xy 54.969918 -404.265384)
			(xy 54.106318 -404.265384) (xy 54.079063 -404.26497) (xy 54.025106 -404.257215) (xy 53.972803 -404.241859)
			(xy 53.923217 -404.219217) (xy 53.877359 -404.189747) (xy 53.836162 -404.154051) (xy 53.800464 -404.112855)
			(xy 53.770992 -404.066999) (xy 53.748347 -404.017414) (xy 53.732989 -403.965111) (xy 53.725231 -403.911155)
			(xy 52.287721 -403.911155) (xy 52.279964 -403.965102) (xy 52.264607 -404.017398) (xy 52.241965 -404.066976)
			(xy 52.212497 -404.112828) (xy 52.176803 -404.154018) (xy 52.13561 -404.18971) (xy 52.089757 -404.219175)
			(xy 52.040177 -404.241815) (xy 51.98788 -404.257168) (xy 51.93393 -404.264922) (xy 51.906678 -404.265384)
			(xy 51.043078 -404.265384) (xy 51.015826 -404.264945) (xy 50.961877 -404.257185) (xy 50.909582 -404.241827)
			(xy 50.860004 -404.219183) (xy 50.814154 -404.189715) (xy 50.772964 -404.154021) (xy 50.737272 -404.112829)
			(xy 50.707806 -404.066976) (xy 50.685165 -404.017397) (xy 50.66981 -403.965101) (xy 50.662054 -403.911152)
			(xy 49.224397 -403.911152) (xy 49.216643 -403.965089) (xy 49.201291 -404.017377) (xy 49.178654 -404.066949)
			(xy 49.149193 -404.112794) (xy 49.113508 -404.153981) (xy 49.072325 -404.18967) (xy 49.026482 -404.219135)
			(xy 48.976913 -404.241777) (xy 48.924626 -404.257135) (xy 48.870686 -404.264895) (xy 48.843438 -404.265384)
			(xy 47.979838 -404.265384) (xy 47.952582 -404.264972) (xy 47.898623 -404.257219) (xy 47.846317 -404.241865)
			(xy 47.796729 -404.219223) (xy 47.750868 -404.189754) (xy 47.709669 -404.154058) (xy 47.673969 -404.112862)
			(xy 47.644495 -404.067004) (xy 47.621848 -404.017418) (xy 47.606489 -403.965114) (xy 47.598731 -403.911156)
			(xy 2.610452 -403.911156) (xy 2.622121 -403.942439) (xy 2.666338 -404.039266) (xy 2.717346 -404.132693)
			(xy 2.774884 -404.222247) (xy 2.838661 -404.307471) (xy 2.872828 -404.346918) (xy 98.27006 -404.346918)
			(xy 98.27006 -404.092918) (xy 98.270523 -404.080827) (xy 98.277977 -404.057824) (xy 98.292164 -404.038242)
			(xy 98.3117 -404.023992) (xy 98.334679 -404.016463) (xy 98.346768 -404.015956) (xy 98.676968 -404.015956)
			(xy 98.689071 -404.016443) (xy 98.71209 -404.023928) (xy 98.731659 -404.038173) (xy 98.745857 -404.057777)
			(xy 98.753286 -404.080814) (xy 98.753676 -404.092918) (xy 98.753676 -404.346918) (xy 99.177856 -404.346918)
			(xy 99.177856 -404.092918) (xy 99.178276 -404.080794) (xy 99.185765 -404.057733) (xy 99.200016 -404.038116)
			(xy 99.219633 -404.023865) (xy 99.242694 -404.016376) (xy 99.254818 -404.015956) (xy 99.585018 -404.015956)
			(xy 99.597135 -404.016396) (xy 99.620182 -404.023891) (xy 99.639785 -404.03814) (xy 99.654026 -404.05775)
			(xy 99.661509 -404.0808) (xy 99.66198 -404.092918) (xy 99.66198 -404.346918) (xy 99.661504 -404.359032)
			(xy 99.654014 -404.382073) (xy 99.639772 -404.401672) (xy 99.620173 -404.415914) (xy 99.597132 -404.423404)
			(xy 99.585018 -404.42388) (xy 99.254818 -404.42388) (xy 99.242706 -404.423373) (xy 99.219667 -404.415893)
			(xy 99.200066 -404.401659) (xy 99.185823 -404.382066) (xy 99.178333 -404.35903) (xy 99.177856 -404.346918)
			(xy 98.753676 -404.346918) (xy 98.753208 -404.359007) (xy 98.745749 -404.382006) (xy 98.731562 -404.401584)
			(xy 98.71203 -404.415834) (xy 98.689055 -404.423369) (xy 98.676968 -404.42388) (xy 98.346768 -404.42388)
			(xy 98.334655 -404.423511) (xy 98.311624 -404.416) (xy 98.292049 -404.401727) (xy 98.277857 -404.382094)
			(xy 98.27044 -404.359032) (xy 98.27006 -404.346918) (xy 2.872828 -404.346918) (xy 2.908351 -404.387931)
			(xy 2.945638 -404.425912) (xy 3.400044 -404.880318) (xy 98.27006 -404.880318) (xy 98.27006 -404.626318)
			(xy 98.270523 -404.614227) (xy 98.277977 -404.591224) (xy 98.292164 -404.571642) (xy 98.3117 -404.557392)
			(xy 98.334679 -404.549863) (xy 98.346768 -404.549356) (xy 98.676968 -404.549356) (xy 98.689071 -404.549843)
			(xy 98.71209 -404.557328) (xy 98.731659 -404.571573) (xy 98.745857 -404.591177) (xy 98.753286 -404.614214)
			(xy 98.753676 -404.626318) (xy 98.753676 -404.880318) (xy 99.177856 -404.880318) (xy 99.177856 -404.626318)
			(xy 99.178276 -404.614194) (xy 99.185765 -404.591133) (xy 99.200016 -404.571516) (xy 99.219633 -404.557265)
			(xy 99.242694 -404.549776) (xy 99.254818 -404.549356) (xy 99.585018 -404.549356) (xy 99.597135 -404.549796)
			(xy 99.620182 -404.557291) (xy 99.639785 -404.57154) (xy 99.654026 -404.59115) (xy 99.661509 -404.6142)
			(xy 99.66198 -404.626318) (xy 99.66198 -404.880318) (xy 99.661504 -404.892432) (xy 99.654014 -404.915473)
			(xy 99.639772 -404.935072) (xy 99.620173 -404.949314) (xy 99.597132 -404.956804) (xy 99.585018 -404.95728)
			(xy 99.254818 -404.95728) (xy 99.242706 -404.956773) (xy 99.219667 -404.949293) (xy 99.200066 -404.935059)
			(xy 99.185823 -404.915466) (xy 99.178333 -404.89243) (xy 99.177856 -404.880318) (xy 98.753676 -404.880318)
			(xy 98.753208 -404.892407) (xy 98.745749 -404.915406) (xy 98.731562 -404.934984) (xy 98.71203 -404.949234)
			(xy 98.689055 -404.956769) (xy 98.676968 -404.95728) (xy 98.346768 -404.95728) (xy 98.334655 -404.956911)
			(xy 98.311624 -404.9494) (xy 98.292049 -404.935127) (xy 98.277857 -404.915494) (xy 98.27044 -404.892432)
			(xy 98.27006 -404.880318) (xy 3.400044 -404.880318) (xy 3.748786 -405.22906) (xy 102.242112 -405.22906)
			(xy 102.242112 -404.36546) (xy 102.242598 -404.338209) (xy 102.250354 -404.284261) (xy 102.265709 -404.231966)
			(xy 102.288351 -404.182389) (xy 102.317817 -404.136539) (xy 102.353508 -404.095348) (xy 102.394699 -404.059657)
			(xy 102.440549 -404.030191) (xy 102.490126 -404.007549) (xy 102.542421 -403.992194) (xy 102.596369 -403.984438)
			(xy 102.650871 -403.984438) (xy 102.704819 -403.992194) (xy 102.757114 -404.007549) (xy 102.806691 -404.030191)
			(xy 102.852541 -404.059657) (xy 102.893732 -404.095348) (xy 102.929423 -404.136539) (xy 102.958889 -404.182389)
			(xy 102.981531 -404.231966) (xy 102.996886 -404.284261) (xy 103.004642 -404.338209) (xy 103.005128 -404.36546)
			(xy 103.005128 -405.22906) (xy 103.004642 -405.256311) (xy 102.996886 -405.310259) (xy 102.981531 -405.362554)
			(xy 102.958889 -405.412131) (xy 102.929423 -405.457981) (xy 102.893732 -405.499172) (xy 102.852541 -405.534863)
			(xy 102.806691 -405.564329) (xy 102.757114 -405.586971) (xy 102.704819 -405.602326) (xy 102.650871 -405.610082)
			(xy 102.596369 -405.610082) (xy 102.542421 -405.602326) (xy 102.490126 -405.586971) (xy 102.440549 -405.564329)
			(xy 102.394699 -405.534863) (xy 102.353508 -405.499172) (xy 102.317817 -405.457981) (xy 102.288351 -405.412131)
			(xy 102.265709 -405.362554) (xy 102.250354 -405.310259) (xy 102.242598 -405.256311) (xy 102.242112 -405.22906)
			(xy 3.748786 -405.22906) (xy 5.555234 -407.035508) (xy 15.978632 -407.035508) (xy 15.978632 -406.171908)
			(xy 15.979118 -406.144657) (xy 15.986874 -406.090709) (xy 16.002229 -406.038414) (xy 16.024871 -405.988837)
			(xy 16.054337 -405.942987) (xy 16.090028 -405.901796) (xy 16.131219 -405.866105) (xy 16.177069 -405.836639)
			(xy 16.226646 -405.813997) (xy 16.278941 -405.798642) (xy 16.332889 -405.790886) (xy 16.387391 -405.790886)
			(xy 16.441339 -405.798642) (xy 16.493634 -405.813997) (xy 16.543211 -405.836639) (xy 16.589061 -405.866105)
			(xy 16.630252 -405.901796) (xy 16.665943 -405.942987) (xy 16.695409 -405.988837) (xy 16.710613 -406.022127)
			(xy 34.34639 -406.022127) (xy 34.34639 -405.970153) (xy 34.35452 -405.918818) (xy 34.370581 -405.869388)
			(xy 34.394177 -405.823078) (xy 34.424727 -405.78103) (xy 34.461478 -405.744279) (xy 34.503526 -405.713729)
			(xy 34.549836 -405.690133) (xy 34.599266 -405.674072) (xy 34.650601 -405.665942) (xy 34.702575 -405.665942)
			(xy 34.75391 -405.674072) (xy 34.80334 -405.690133) (xy 34.84965 -405.713729) (xy 34.891698 -405.744279)
			(xy 34.928449 -405.78103) (xy 34.958999 -405.823078) (xy 34.982595 -405.869388) (xy 34.998656 -405.918818)
			(xy 35.006786 -405.970153) (xy 35.007296 -405.99614) (xy 35.006786 -406.022127) (xy 34.998656 -406.073462)
			(xy 34.995967 -406.081738) (xy 35.858958 -406.081738) (xy 35.859212 -406.081738) (xy 35.859212 -405.774906)
			(xy 35.860392 -405.760561) (xy 35.870023 -405.733446) (xy 35.887002 -405.710216) (xy 35.909912 -405.692807)
			(xy 35.936842 -405.682672) (xy 35.95116 -405.68118) (xy 36.877752 -405.68118) (xy 36.877752 -405.680672)
			(xy 37.020754 -405.680672) (xy 37.033148 -405.681343) (xy 37.057052 -405.687994) (xy 37.078607 -405.700284)
			(xy 37.08781 -405.708612) (xy 37.097187 -405.718302) (xy 37.1109 -405.741505) (xy 37.117929 -405.767524)
			(xy 37.11829 -405.781002) (xy 37.118036 -405.781002) (xy 37.118036 -406.087834) (xy 37.116904 -406.101552)
			(xy 37.108082 -406.127612) (xy 37.092457 -406.150259) (xy 37.071225 -406.167757) (xy 37.046011 -406.178768)
			(xy 37.032438 -406.181052) (xy 37.025834 -406.182068) (xy 35.956494 -406.182068) (xy 35.944099 -406.181414)
			(xy 35.920195 -406.174754) (xy 35.898641 -406.162458) (xy 35.889438 -406.154128) (xy 35.880024 -406.144471)
			(xy 35.866325 -406.121252) (xy 35.85931 -406.09522) (xy 35.858958 -406.081738) (xy 34.995967 -406.081738)
			(xy 34.982595 -406.122892) (xy 34.958999 -406.169202) (xy 34.928449 -406.21125) (xy 34.891698 -406.248001)
			(xy 34.84965 -406.278551) (xy 34.80334 -406.302147) (xy 34.75391 -406.318208) (xy 34.702575 -406.326338)
			(xy 34.650601 -406.326338) (xy 34.599266 -406.318208) (xy 34.549836 -406.302147) (xy 34.503526 -406.278551)
			(xy 34.461478 -406.248001) (xy 34.424727 -406.21125) (xy 34.394177 -406.169202) (xy 34.370581 -406.122892)
			(xy 34.35452 -406.073462) (xy 34.34639 -406.022127) (xy 16.710613 -406.022127) (xy 16.718051 -406.038414)
			(xy 16.733406 -406.090709) (xy 16.741162 -406.144657) (xy 16.741648 -406.171908) (xy 16.741648 -406.620726)
			(xy 184.561988 -406.620726) (xy 184.561988 -400.685254) (xy 184.562447 -400.660304) (xy 184.570259 -400.611019)
			(xy 184.585684 -400.563563) (xy 184.608342 -400.519104) (xy 184.637676 -400.478736) (xy 184.672962 -400.443454)
			(xy 184.713333 -400.414125) (xy 184.757795 -400.391471) (xy 184.805253 -400.376051) (xy 184.854538 -400.368244)
			(xy 184.879488 -400.367754) (xy 188.73343 -400.367754) (xy 188.758609 -400.368272) (xy 188.808334 -400.376233)
			(xy 188.856176 -400.39195) (xy 188.900934 -400.415029) (xy 188.941484 -400.444889) (xy 188.95949 -400.462496)
			(xy 189.16142 -400.667474) (xy 189.178411 -400.68542) (xy 189.207232 -400.725562) (xy 189.229493 -400.76968)
			(xy 189.244658 -400.816712) (xy 189.252363 -400.865524) (xy 189.25286 -400.890232) (xy 189.25286 -403.517354)
			(xy 189.46876 -403.517354) (xy 189.49371 -403.51783) (xy 189.542993 -403.525649) (xy 189.590451 -403.541071)
			(xy 189.634916 -403.563718) (xy 189.675298 -403.593032) (xy 189.693296 -403.610318) (xy 189.904624 -403.821646)
			(xy 189.921945 -403.839613) (xy 189.951264 -403.879997) (xy 189.973905 -403.92447) (xy 189.989312 -403.971937)
			(xy 189.997105 -404.021229) (xy 189.997588 -404.046182) (xy 189.997588 -404.34641) (xy 190.325756 -404.674832)
			(xy 190.350648 -404.671276) (xy 190.363288 -404.669701) (xy 190.38871 -404.668051) (xy 190.401448 -404.667974)
			(xy 190.4287 -404.668433) (xy 190.482647 -404.676196) (xy 190.534941 -404.691556) (xy 190.584518 -404.714201)
			(xy 190.630367 -404.743671) (xy 190.671556 -404.779365) (xy 190.707247 -404.820557) (xy 190.736713 -404.866409)
			(xy 190.759355 -404.915987) (xy 190.774711 -404.968282) (xy 190.782469 -405.02223) (xy 190.782956 -405.049482)
			(xy 190.782871 -405.06222) (xy 190.781219 -405.087641) (xy 190.779654 -405.100282) (xy 190.776098 -405.125174)
			(xy 191.001904 -405.35098) (xy 196.838316 -405.35098) (xy 197.83298 -404.356316) (xy 197.83298 -400.893788)
			(xy 197.833478 -400.868839) (xy 197.841291 -400.819556) (xy 197.856708 -400.772099) (xy 197.879349 -400.727633)
			(xy 197.908659 -400.68725) (xy 197.925944 -400.669252) (xy 198.116952 -400.478244) (xy 198.134911 -400.460913)
			(xy 198.175295 -400.431588) (xy 198.219769 -400.408941) (xy 198.267238 -400.393531) (xy 198.316534 -400.385737)
			(xy 198.341488 -400.38528) (xy 201.995532 -400.38528) (xy 202.020482 -400.385766) (xy 202.069765 -400.393582)
			(xy 202.117222 -400.409001) (xy 202.161688 -400.431645) (xy 202.20207 -400.460958) (xy 202.220068 -400.478244)
			(xy 202.418696 -400.676872) (xy 202.435977 -400.694876) (xy 202.465302 -400.73525) (xy 202.487952 -400.779713)
			(xy 202.503368 -400.827172) (xy 202.511171 -400.876458) (xy 202.51166 -400.901408) (xy 202.51166 -404.330916)
			(xy 202.604624 -404.42388) (xy 202.621913 -404.441876) (xy 202.651236 -404.482252) (xy 202.673884 -404.526718)
			(xy 202.689298 -404.574178) (xy 202.6971 -404.623466) (xy 202.697588 -404.648416) (xy 202.697588 -407.475436)
			(xy 204.291692 -409.06954) (xy 206.414116 -409.06954) (xy 208.310988 -407.172668) (xy 208.310988 -404.642828)
			(xy 208.311509 -404.61788) (xy 208.319316 -404.568598) (xy 208.334727 -404.521141) (xy 208.357363 -404.476674)
			(xy 208.386669 -404.436291) (xy 208.403952 -404.418292) (xy 208.50098 -404.321264) (xy 208.50098 -400.893788)
			(xy 208.501478 -400.868839) (xy 208.509291 -400.819556) (xy 208.524708 -400.772099) (xy 208.547349 -400.727633)
			(xy 208.576659 -400.68725) (xy 208.593944 -400.669252) (xy 208.784952 -400.478244) (xy 208.802911 -400.460913)
			(xy 208.843295 -400.431588) (xy 208.887769 -400.408941) (xy 208.935238 -400.393531) (xy 208.984534 -400.385737)
			(xy 209.009488 -400.38528) (xy 212.668612 -400.38528) (xy 212.693561 -400.385778) (xy 212.742844 -400.393591)
			(xy 212.790301 -400.409008) (xy 212.834767 -400.431649) (xy 212.87515 -400.460959) (xy 212.893148 -400.478244)
			(xy 213.084156 -400.669252) (xy 213.101487 -400.687211) (xy 213.130812 -400.727595) (xy 213.153459 -400.772069)
			(xy 213.168869 -400.819538) (xy 213.176663 -400.868834) (xy 213.17712 -400.893788) (xy 213.17712 -404.353776)
			(xy 213.261956 -404.438612) (xy 213.279249 -404.456605) (xy 213.308574 -404.496981) (xy 213.331222 -404.541447)
			(xy 213.346636 -404.588909) (xy 213.354434 -404.638197) (xy 213.35492 -404.663148) (xy 213.35492 -407.394156)
			(xy 214.926164 -408.9654) (xy 217.141044 -408.9654) (xy 218.978988 -407.127456) (xy 218.978988 -404.673308)
			(xy 218.979496 -404.648359) (xy 218.987307 -404.599077) (xy 219.00272 -404.55162) (xy 219.02536 -404.507153)
			(xy 219.054668 -404.46677) (xy 219.071952 -404.448772) (xy 219.16136 -404.359364) (xy 219.16136 -400.906488)
			(xy 219.161864 -400.881539) (xy 219.169676 -400.832257) (xy 219.185092 -400.7848) (xy 219.207732 -400.740334)
			(xy 219.23704 -400.699951) (xy 219.254324 -400.681952) (xy 219.458032 -400.478244) (xy 219.476 -400.460922)
			(xy 219.516381 -400.431596) (xy 219.560853 -400.408948) (xy 219.60832 -400.393535) (xy 219.657614 -400.385739)
			(xy 219.682568 -400.38528) (xy 223.323912 -400.38528) (xy 223.348861 -400.385778) (xy 223.398144 -400.393591)
			(xy 223.445601 -400.409008) (xy 223.490067 -400.431649) (xy 223.53045 -400.460959) (xy 223.548448 -400.478244)
			(xy 223.759776 -400.689572) (xy 223.777053 -400.707579) (xy 223.80638 -400.747952) (xy 223.82903 -400.792414)
			(xy 223.844447 -400.839873) (xy 223.852251 -400.889158) (xy 223.85274 -400.914108) (xy 223.85274 -404.348188)
			(xy 223.940624 -404.436072) (xy 223.957909 -404.454071) (xy 223.987233 -404.494447) (xy 224.009881 -404.538912)
			(xy 224.025297 -404.586371) (xy 224.0331 -404.635658) (xy 224.033588 -404.660608) (xy 224.033588 -407.272236)
			(xy 225.838512 -409.07716) (xy 227.803456 -409.07716) (xy 229.621588 -407.259028) (xy 229.621588 -404.678388)
			(xy 229.622084 -404.653439) (xy 229.629897 -404.604156) (xy 229.645314 -404.556698) (xy 229.667956 -404.512233)
			(xy 229.697267 -404.47185) (xy 229.714552 -404.453852) (xy 229.82682 -404.341584) (xy 229.82682 -400.901408)
			(xy 229.827348 -400.87646) (xy 229.835156 -400.82718) (xy 229.850567 -400.779723) (xy 229.873201 -400.735257)
			(xy 229.902503 -400.694872) (xy 229.919784 -400.676872) (xy 230.120952 -400.475704) (xy 230.138921 -400.458385)
			(xy 230.179304 -400.429065) (xy 230.223776 -400.406422) (xy 230.271243 -400.391015) (xy 230.320536 -400.383222)
			(xy 230.345488 -400.38274) (xy 233.996992 -400.38274) (xy 234.02194 -400.383262) (xy 234.071221 -400.391071)
			(xy 234.118678 -400.406483) (xy 234.163144 -400.429118) (xy 234.203528 -400.458422) (xy 234.221528 -400.475704)
			(xy 234.422696 -400.676872) (xy 234.439977 -400.694876) (xy 234.469302 -400.73525) (xy 234.491952 -400.779713)
			(xy 234.507368 -400.827172) (xy 234.515171 -400.876458) (xy 234.51566 -400.901408) (xy 234.51566 -404.346156)
			(xy 235.652564 -405.48306) (xy 237.746032 -405.48306) (xy 237.770981 -405.483551) (xy 237.820264 -405.491367)
			(xy 237.867721 -405.506785) (xy 237.912187 -405.529428) (xy 237.95257 -405.558739) (xy 237.970568 -405.576024)
			(xy 238.814356 -406.419812) (xy 238.968788 -406.419812) (xy 239.014 -406.3746) (xy 239.014 -397.839946)
			(xy 239.014705 -397.809318) (xy 239.02648 -397.749203) (xy 239.037368 -397.720566) (xy 239.093502 -397.582136)
			(xy 239.102124 -397.561821) (xy 239.124183 -397.523596) (xy 239.151323 -397.488796) (xy 239.166908 -397.47317)
			(xy 239.218978 -397.423132) (xy 239.692688 -396.949422) (xy 239.720237 -396.922524) (xy 239.780375 -396.87444)
			(xy 239.845524 -396.833399) (xy 239.914862 -396.799918) (xy 239.987515 -396.774419) (xy 240.062568 -396.757222)
			(xy 240.139075 -396.748545) (xy 240.177574 -396.748) (xy 274.117054 -396.748) (xy 274.147682 -396.748705)
			(xy 274.207797 -396.76048) (xy 274.236434 -396.771368) (xy 274.374864 -396.827502) (xy 274.395179 -396.836124)
			(xy 274.433404 -396.858183) (xy 274.468204 -396.885323) (xy 274.48383 -396.900908) (xy 274.533868 -396.952978)
			(xy 274.753578 -397.172688) (xy 274.777454 -397.19758) (xy 274.787032 -397.207432) (xy 274.810234 -397.222125)
			(xy 274.836515 -397.230094) (xy 274.86397 -397.230762) (xy 274.890608 -397.22408) (xy 274.914497 -397.210532)
			(xy 274.92452 -397.201136) (xy 275.284692 -396.840964) (xy 275.302681 -396.823665) (xy 275.343056 -396.794335)
			(xy 275.387522 -396.771682) (xy 275.434985 -396.756264) (xy 275.484276 -396.748462) (xy 275.509228 -396.748)
			(xy 280.83764 -396.748) (xy 280.86259 -396.748475) (xy 280.911874 -396.756293) (xy 280.959332 -396.771714)
			(xy 281.003797 -396.794361) (xy 281.044179 -396.823677) (xy 281.062176 -396.840964) (xy 281.593544 -397.372332)
			(xy 281.610864 -397.390302) (xy 281.640191 -397.430682) (xy 281.66284 -397.475154) (xy 281.678252 -397.522621)
			(xy 281.686049 -397.571915) (xy 281.686508 -397.596868) (xy 281.686508 -398.65534) (xy 457.185003 -398.65534)
			(xy 457.185003 -398.5262) (xy 457.192953 -398.397305) (xy 457.208823 -398.269145) (xy 457.232552 -398.142204)
			(xy 457.264051 -398.016965) (xy 457.3032 -397.893902) (xy 457.349851 -397.773483) (xy 457.403826 -397.656164)
			(xy 457.464921 -397.54239) (xy 457.532904 -397.432593) (xy 457.607518 -397.32719) (xy 457.688479 -397.22658)
			(xy 457.775479 -397.131145) (xy 457.86819 -397.041246) (xy 457.96626 -396.957225) (xy 458.069315 -396.879401)
			(xy 458.176966 -396.808069) (xy 458.288805 -396.743499) (xy 458.404406 -396.685937) (xy 458.523331 -396.6356)
			(xy 458.64513 -396.59268) (xy 458.76934 -396.557339) (xy 458.895489 -396.529712) (xy 459.023101 -396.509903)
			(xy 459.15169 -396.497987) (xy 459.280768 -396.494011) (xy 459.409846 -396.497987) (xy 459.538435 -396.509903)
			(xy 459.666047 -396.529712) (xy 459.792196 -396.557339) (xy 459.916406 -396.59268) (xy 460.038205 -396.6356)
			(xy 460.15713 -396.685937) (xy 460.272731 -396.743499) (xy 460.38457 -396.808069) (xy 460.492221 -396.879401)
			(xy 460.595276 -396.957225) (xy 460.693346 -397.041246) (xy 460.786057 -397.131145) (xy 460.873057 -397.22658)
			(xy 460.954018 -397.32719) (xy 461.028632 -397.432593) (xy 461.096615 -397.54239) (xy 461.15771 -397.656164)
			(xy 461.211685 -397.773483) (xy 461.258336 -397.893902) (xy 461.297485 -398.016965) (xy 461.328984 -398.142204)
			(xy 461.352713 -398.269145) (xy 461.368583 -398.397305) (xy 461.376533 -398.5262) (xy 461.37703 -398.59077)
			(xy 461.376533 -398.65534) (xy 461.368583 -398.784235) (xy 461.352713 -398.912395) (xy 461.328984 -399.039336)
			(xy 461.297485 -399.164575) (xy 461.258336 -399.287638) (xy 461.211685 -399.408057) (xy 461.15771 -399.525376)
			(xy 461.096615 -399.63915) (xy 461.028632 -399.748947) (xy 460.954018 -399.85435) (xy 460.873057 -399.95496)
			(xy 460.786057 -400.050395) (xy 460.693346 -400.140294) (xy 460.595276 -400.224315) (xy 460.492221 -400.302139)
			(xy 460.38457 -400.373471) (xy 460.272731 -400.438041) (xy 460.15713 -400.495603) (xy 460.038205 -400.54594)
			(xy 459.916406 -400.58886) (xy 459.792196 -400.624201) (xy 459.666047 -400.651828) (xy 459.538435 -400.671637)
			(xy 459.409846 -400.683553) (xy 459.280768 -400.68753) (xy 459.15169 -400.683553) (xy 459.023101 -400.671637)
			(xy 458.895489 -400.651828) (xy 458.76934 -400.624201) (xy 458.64513 -400.58886) (xy 458.523331 -400.54594)
			(xy 458.404406 -400.495603) (xy 458.288805 -400.438041) (xy 458.176966 -400.373471) (xy 458.069315 -400.302139)
			(xy 457.96626 -400.224315) (xy 457.86819 -400.140294) (xy 457.775479 -400.050395) (xy 457.688479 -399.95496)
			(xy 457.607518 -399.85435) (xy 457.532904 -399.748947) (xy 457.464921 -399.63915) (xy 457.403826 -399.525376)
			(xy 457.349851 -399.408057) (xy 457.3032 -399.287638) (xy 457.264051 -399.164575) (xy 457.232552 -399.039336)
			(xy 457.208823 -398.912395) (xy 457.192953 -398.784235) (xy 457.185003 -398.65534) (xy 281.686508 -398.65534)
			(xy 281.686508 -399.9835) (xy 289.606441 -399.9835) (xy 289.610455 -399.919698) (xy 289.622434 -399.856902)
			(xy 289.642189 -399.796103) (xy 289.669408 -399.73826) (xy 289.703662 -399.684283) (xy 289.744411 -399.635026)
			(xy 289.791013 -399.591264) (xy 289.842731 -399.553688) (xy 289.898752 -399.52289) (xy 289.958191 -399.499357)
			(xy 290.02011 -399.483458) (xy 290.083534 -399.475446) (xy 290.115498 -399.474944) (xy 290.115752 -399.474944)
			(xy 290.147498 -399.475464) (xy 290.210494 -399.483393) (xy 290.272014 -399.499096) (xy 290.331102 -399.52233)
			(xy 290.386842 -399.552733) (xy 290.438367 -399.589834) (xy 290.461954 -399.611088) (xy 290.469217 -399.617272)
			(xy 290.486967 -399.624223) (xy 290.506029 -399.624223) (xy 290.523779 -399.617272) (xy 290.531042 -399.611088)
			(xy 290.554631 -399.589832) (xy 290.60614 -399.5527) (xy 290.661874 -399.522276) (xy 290.720965 -399.499035)
			(xy 290.782492 -399.483338) (xy 290.845495 -399.475431) (xy 290.877244 -399.474944) (xy 290.877498 -399.474944)
			(xy 290.909457 -399.475521) (xy 290.972872 -399.483532) (xy 291.034783 -399.499427) (xy 291.094213 -399.522957)
			(xy 291.150226 -399.55375) (xy 291.201937 -399.591321) (xy 291.248532 -399.635076) (xy 291.289276 -399.684326)
			(xy 291.323525 -399.738295) (xy 291.350741 -399.79613) (xy 291.370493 -399.856921) (xy 291.38247 -399.919707)
			(xy 291.386484 -399.9835) (xy 292.146441 -399.9835) (xy 292.150455 -399.919698) (xy 292.162434 -399.856902)
			(xy 292.182189 -399.796103) (xy 292.209408 -399.73826) (xy 292.243662 -399.684283) (xy 292.284411 -399.635026)
			(xy 292.331013 -399.591264) (xy 292.382731 -399.553688) (xy 292.438752 -399.52289) (xy 292.498191 -399.499357)
			(xy 292.56011 -399.483458) (xy 292.623534 -399.475446) (xy 292.655498 -399.474944) (xy 292.655752 -399.474944)
			(xy 292.687498 -399.475464) (xy 292.750494 -399.483393) (xy 292.812014 -399.499096) (xy 292.871102 -399.52233)
			(xy 292.926842 -399.552733) (xy 292.978367 -399.589834) (xy 293.001954 -399.611088) (xy 293.009217 -399.617272)
			(xy 293.026967 -399.624223) (xy 293.046029 -399.624223) (xy 293.063779 -399.617272) (xy 293.071042 -399.611088)
			(xy 293.094631 -399.589832) (xy 293.14614 -399.5527) (xy 293.201874 -399.522276) (xy 293.260965 -399.499035)
			(xy 293.322492 -399.483338) (xy 293.385495 -399.475431) (xy 293.417244 -399.474944) (xy 293.417498 -399.474944)
			(xy 293.449457 -399.475521) (xy 293.512872 -399.483532) (xy 293.574783 -399.499427) (xy 293.634213 -399.522957)
			(xy 293.690226 -399.55375) (xy 293.741937 -399.591321) (xy 293.788532 -399.635076) (xy 293.829276 -399.684326)
			(xy 293.863525 -399.738295) (xy 293.890741 -399.79613) (xy 293.910493 -399.856921) (xy 293.92247 -399.919707)
			(xy 293.926484 -399.9835) (xy 294.53602 -399.9835) (xy 294.540035 -399.919693) (xy 294.552015 -399.856892)
			(xy 294.571773 -399.796089) (xy 294.598995 -399.738241) (xy 294.633253 -399.684261) (xy 294.674007 -399.635001)
			(xy 294.720613 -399.591237) (xy 294.772338 -399.55366) (xy 294.828364 -399.522862) (xy 294.887809 -399.499329)
			(xy 294.949734 -399.483433) (xy 295.013163 -399.475423) (xy 295.04513 -399.474944) (xy 295.045384 -399.474944)
			(xy 295.077131 -399.475444) (xy 295.140127 -399.483377) (xy 295.201647 -399.499084) (xy 295.260736 -399.522322)
			(xy 295.316476 -399.552728) (xy 295.368 -399.589832) (xy 295.391586 -399.611088) (xy 295.398849 -399.617272)
			(xy 295.416599 -399.624223) (xy 295.435661 -399.624223) (xy 295.453411 -399.617272) (xy 295.460674 -399.611088)
			(xy 295.48425 -399.589817) (xy 295.535761 -399.552686) (xy 295.591498 -399.522265) (xy 295.650592 -399.499026)
			(xy 295.712121 -399.483332) (xy 295.775126 -399.475429) (xy 295.806876 -399.474944) (xy 295.80713 -399.474944)
			(xy 295.839087 -399.475544) (xy 295.902496 -399.483558) (xy 295.964401 -399.499455) (xy 296.023825 -399.522986)
			(xy 296.079832 -399.553779) (xy 296.131538 -399.591348) (xy 296.178128 -399.635102) (xy 296.218866 -399.684349)
			(xy 296.253112 -399.738314) (xy 296.280324 -399.796145) (xy 296.300074 -399.856931) (xy 296.312049 -399.919712)
			(xy 296.316063 -399.9835) (xy 297.07602 -399.9835) (xy 297.080035 -399.919693) (xy 297.092015 -399.856892)
			(xy 297.111773 -399.796089) (xy 297.138995 -399.738241) (xy 297.173253 -399.684261) (xy 297.214007 -399.635001)
			(xy 297.260613 -399.591237) (xy 297.312338 -399.55366) (xy 297.368364 -399.522862) (xy 297.427809 -399.499329)
			(xy 297.489734 -399.483433) (xy 297.553163 -399.475423) (xy 297.58513 -399.474944) (xy 297.585384 -399.474944)
			(xy 297.617131 -399.475444) (xy 297.680127 -399.483377) (xy 297.741647 -399.499084) (xy 297.800736 -399.522322)
			(xy 297.856476 -399.552728) (xy 297.908 -399.589832) (xy 297.931586 -399.611088) (xy 297.938849 -399.617272)
			(xy 297.956599 -399.624223) (xy 297.975661 -399.624223) (xy 297.993411 -399.617272) (xy 298.000674 -399.611088)
			(xy 298.02425 -399.589817) (xy 298.075761 -399.552686) (xy 298.131498 -399.522265) (xy 298.190592 -399.499026)
			(xy 298.252121 -399.483332) (xy 298.315126 -399.475429) (xy 298.346876 -399.474944) (xy 298.34713 -399.474944)
			(xy 298.379087 -399.475544) (xy 298.442496 -399.483558) (xy 298.504401 -399.499455) (xy 298.563825 -399.522986)
			(xy 298.619832 -399.553779) (xy 298.671538 -399.591348) (xy 298.718128 -399.635102) (xy 298.758866 -399.684349)
			(xy 298.793112 -399.738314) (xy 298.820324 -399.796145) (xy 298.840074 -399.856931) (xy 298.852049 -399.919712)
			(xy 298.856063 -399.9835) (xy 298.852049 -400.047288) (xy 298.840074 -400.110069) (xy 298.820324 -400.170855)
			(xy 298.793112 -400.228686) (xy 298.758866 -400.282651) (xy 298.718128 -400.331898) (xy 298.671538 -400.375652)
			(xy 298.619832 -400.413221) (xy 298.563825 -400.444014) (xy 298.504401 -400.467545) (xy 298.442496 -400.483442)
			(xy 298.379087 -400.491456) (xy 298.34713 -400.49196) (xy 298.346876 -400.49196) (xy 298.315131 -400.491422)
			(xy 298.252136 -400.483497) (xy 298.190616 -400.467797) (xy 298.131527 -400.444566) (xy 298.075787 -400.414166)
			(xy 298.024261 -400.377069) (xy 298.000674 -400.355816) (xy 297.993411 -400.349632) (xy 297.975661 -400.342681)
			(xy 297.956599 -400.342681) (xy 297.938849 -400.349632) (xy 297.931586 -400.355816) (xy 297.908028 -400.377107)
			(xy 297.856512 -400.414235) (xy 297.800771 -400.444654) (xy 297.741674 -400.467889) (xy 297.680142 -400.483579)
			(xy 297.617135 -400.491478) (xy 297.585384 -400.49196) (xy 297.58513 -400.49196) (xy 297.553163 -400.491577)
			(xy 297.489734 -400.483567) (xy 297.427809 -400.467671) (xy 297.368364 -400.444138) (xy 297.312338 -400.41334)
			(xy 297.260613 -400.375763) (xy 297.214007 -400.331999) (xy 297.173253 -400.282739) (xy 297.138995 -400.228759)
			(xy 297.111773 -400.170911) (xy 297.092015 -400.110108) (xy 297.080035 -400.047307) (xy 297.07602 -399.9835)
			(xy 296.316063 -399.9835) (xy 296.312049 -400.047288) (xy 296.300074 -400.110069) (xy 296.280324 -400.170855)
			(xy 296.253112 -400.228686) (xy 296.218866 -400.282651) (xy 296.178128 -400.331898) (xy 296.131538 -400.375652)
			(xy 296.079832 -400.413221) (xy 296.023825 -400.444014) (xy 295.964401 -400.467545) (xy 295.902496 -400.483442)
			(xy 295.839087 -400.491456) (xy 295.80713 -400.49196) (xy 295.806876 -400.49196) (xy 295.775131 -400.491422)
			(xy 295.712136 -400.483497) (xy 295.650616 -400.467797) (xy 295.591527 -400.444566) (xy 295.535787 -400.414166)
			(xy 295.484261 -400.377069) (xy 295.460674 -400.355816) (xy 295.453411 -400.349632) (xy 295.435661 -400.342681)
			(xy 295.416599 -400.342681) (xy 295.398849 -400.349632) (xy 295.391586 -400.355816) (xy 295.368028 -400.377107)
			(xy 295.316512 -400.414235) (xy 295.260771 -400.444654) (xy 295.201674 -400.467889) (xy 295.140142 -400.483579)
			(xy 295.077135 -400.491478) (xy 295.045384 -400.49196) (xy 295.04513 -400.49196) (xy 295.013163 -400.491577)
			(xy 294.949734 -400.483567) (xy 294.887809 -400.467671) (xy 294.828364 -400.444138) (xy 294.772338 -400.41334)
			(xy 294.720613 -400.375763) (xy 294.674007 -400.331999) (xy 294.633253 -400.282739) (xy 294.598995 -400.228759)
			(xy 294.571773 -400.170911) (xy 294.552015 -400.110108) (xy 294.540035 -400.047307) (xy 294.53602 -399.9835)
			(xy 293.926484 -399.9835) (xy 293.92247 -400.047293) (xy 293.910493 -400.110079) (xy 293.890741 -400.17087)
			(xy 293.863525 -400.228705) (xy 293.829276 -400.282674) (xy 293.788532 -400.331924) (xy 293.741937 -400.375679)
			(xy 293.690226 -400.41325) (xy 293.634213 -400.444043) (xy 293.574783 -400.467573) (xy 293.512872 -400.483468)
			(xy 293.449457 -400.491479) (xy 293.417498 -400.49196) (xy 293.417244 -400.49196) (xy 293.385498 -400.491442)
			(xy 293.322502 -400.483512) (xy 293.260982 -400.467809) (xy 293.201894 -400.444575) (xy 293.146154 -400.414171)
			(xy 293.094629 -400.37707) (xy 293.071042 -400.355816) (xy 293.063779 -400.349632) (xy 293.046029 -400.342681)
			(xy 293.026967 -400.342681) (xy 293.009217 -400.349632) (xy 293.001954 -400.355816) (xy 292.978367 -400.377074)
			(xy 292.926858 -400.414206) (xy 292.871123 -400.44463) (xy 292.812032 -400.467871) (xy 292.750504 -400.483567)
			(xy 292.687501 -400.491474) (xy 292.655752 -400.49196) (xy 292.655498 -400.49196) (xy 292.623534 -400.491554)
			(xy 292.56011 -400.483542) (xy 292.498191 -400.467643) (xy 292.438752 -400.44411) (xy 292.382731 -400.413312)
			(xy 292.331013 -400.375736) (xy 292.284411 -400.331974) (xy 292.243662 -400.282717) (xy 292.209408 -400.22874)
			(xy 292.182189 -400.170897) (xy 292.162434 -400.110098) (xy 292.150455 -400.047302) (xy 292.146441 -399.9835)
			(xy 291.386484 -399.9835) (xy 291.38247 -400.047293) (xy 291.370493 -400.110079) (xy 291.350741 -400.17087)
			(xy 291.323525 -400.228705) (xy 291.289276 -400.282674) (xy 291.248532 -400.331924) (xy 291.201937 -400.375679)
			(xy 291.150226 -400.41325) (xy 291.094213 -400.444043) (xy 291.034783 -400.467573) (xy 290.972872 -400.483468)
			(xy 290.909457 -400.491479) (xy 290.877498 -400.49196) (xy 290.877244 -400.49196) (xy 290.845498 -400.491442)
			(xy 290.782502 -400.483512) (xy 290.720982 -400.467809) (xy 290.661894 -400.444575) (xy 290.606154 -400.414171)
			(xy 290.554629 -400.37707) (xy 290.531042 -400.355816) (xy 290.523779 -400.349632) (xy 290.506029 -400.342681)
			(xy 290.486967 -400.342681) (xy 290.469217 -400.349632) (xy 290.461954 -400.355816) (xy 290.438367 -400.377074)
			(xy 290.386858 -400.414206) (xy 290.331123 -400.44463) (xy 290.272032 -400.467871) (xy 290.210504 -400.483567)
			(xy 290.147501 -400.491474) (xy 290.115752 -400.49196) (xy 290.115498 -400.49196) (xy 290.083534 -400.491554)
			(xy 290.02011 -400.483542) (xy 289.958191 -400.467643) (xy 289.898752 -400.44411) (xy 289.842731 -400.413312)
			(xy 289.791013 -400.375736) (xy 289.744411 -400.331974) (xy 289.703662 -400.282717) (xy 289.669408 -400.22874)
			(xy 289.642189 -400.170897) (xy 289.622434 -400.110098) (xy 289.610455 -400.047302) (xy 289.606441 -399.9835)
			(xy 281.686508 -399.9835) (xy 281.686508 -400.885449) (xy 303.599106 -400.885449) (xy 303.599106 -400.830951)
			(xy 303.606862 -400.777009) (xy 303.622215 -400.724719) (xy 303.644854 -400.675146) (xy 303.674317 -400.6293)
			(xy 303.710004 -400.588113) (xy 303.75119 -400.552424) (xy 303.797036 -400.52296) (xy 303.846608 -400.500319)
			(xy 303.898897 -400.484964) (xy 303.952839 -400.477207) (xy 303.980088 -400.47672) (xy 304.843688 -400.47672)
			(xy 304.870943 -400.477126) (xy 304.9249 -400.484882) (xy 304.977203 -400.500238) (xy 305.026788 -400.522882)
			(xy 305.072646 -400.552352) (xy 305.113843 -400.588048) (xy 305.149541 -400.629244) (xy 305.179012 -400.675101)
			(xy 305.201657 -400.724686) (xy 305.217015 -400.776989) (xy 305.224773 -400.830945) (xy 305.224773 -400.885452)
			(xy 306.662283 -400.885452) (xy 306.662283 -400.830948) (xy 306.67004 -400.776998) (xy 306.685397 -400.724702)
			(xy 306.70804 -400.675124) (xy 306.737508 -400.629273) (xy 306.773202 -400.588082) (xy 306.814395 -400.552391)
			(xy 306.860248 -400.522926) (xy 306.909828 -400.500287) (xy 306.962126 -400.484935) (xy 307.016076 -400.477181)
			(xy 307.043328 -400.47672) (xy 307.906928 -400.47672) (xy 307.93418 -400.477152) (xy 307.988129 -400.484912)
			(xy 308.040424 -400.500271) (xy 308.090001 -400.522915) (xy 308.135851 -400.552384) (xy 308.177041 -400.588079)
			(xy 308.212732 -400.629271) (xy 308.242198 -400.675123) (xy 308.264839 -400.724702) (xy 308.280194 -400.776999)
			(xy 308.28795 -400.830948) (xy 308.28795 -400.885448) (xy 309.725606 -400.885448) (xy 309.725606 -400.830952)
			(xy 309.733361 -400.777011) (xy 309.748714 -400.724723) (xy 309.771351 -400.675152) (xy 309.800812 -400.629306)
			(xy 309.836497 -400.58812) (xy 309.877681 -400.552431) (xy 309.923524 -400.522966) (xy 309.973093 -400.500325)
			(xy 310.02538 -400.484968) (xy 310.07932 -400.477208) (xy 310.106568 -400.47672) (xy 310.970168 -400.47672)
			(xy 310.997424 -400.477125) (xy 311.051383 -400.484879) (xy 311.103688 -400.500233) (xy 311.153276 -400.522875)
			(xy 311.199137 -400.552345) (xy 311.240336 -400.588041) (xy 311.276036 -400.629238) (xy 311.305509 -400.675096)
			(xy 311.328156 -400.724682) (xy 311.343515 -400.776986) (xy 311.351273 -400.830944) (xy 311.351273 -400.885451)
			(xy 312.788783 -400.885451) (xy 312.788783 -400.830949) (xy 312.79654 -400.777001) (xy 312.811895 -400.724706)
			(xy 312.834537 -400.675129) (xy 312.864003 -400.629279) (xy 312.899695 -400.588089) (xy 312.940886 -400.552398)
			(xy 312.986736 -400.522933) (xy 313.036314 -400.500292) (xy 313.088609 -400.484938) (xy 313.142557 -400.477183)
			(xy 313.169808 -400.47672) (xy 314.033408 -400.47672) (xy 314.060661 -400.47715) (xy 314.114612 -400.484908)
			(xy 314.166909 -400.500265) (xy 314.216489 -400.522909) (xy 314.262342 -400.552377) (xy 314.303534 -400.588071)
			(xy 314.339228 -400.629264) (xy 314.368695 -400.675118) (xy 314.391337 -400.724698) (xy 314.406693 -400.776996)
			(xy 314.41445 -400.830947) (xy 314.41445 -400.885453) (xy 315.851983 -400.885453) (xy 315.851983 -400.830947)
			(xy 315.859741 -400.776996) (xy 315.875098 -400.724698) (xy 315.897743 -400.675118) (xy 315.927213 -400.629266)
			(xy 315.962909 -400.588075) (xy 316.004105 -400.552384) (xy 316.04996 -400.52292) (xy 316.099543 -400.500282)
			(xy 316.151843 -400.484931) (xy 316.205795 -400.47718) (xy 316.233048 -400.47672) (xy 317.096648 -400.47672)
			(xy 317.123899 -400.477153) (xy 317.177846 -400.484916) (xy 317.230138 -400.500276) (xy 317.279713 -400.522922)
			(xy 317.325561 -400.552391) (xy 317.366748 -400.588086) (xy 317.402437 -400.629278) (xy 317.431901 -400.675129)
			(xy 317.454541 -400.724707) (xy 317.469894 -400.777001) (xy 317.47765 -400.830949) (xy 317.47765 -400.885449)
			(xy 318.915306 -400.885449) (xy 318.915306 -400.830951) (xy 318.923062 -400.777009) (xy 318.938415 -400.724719)
			(xy 318.961054 -400.675146) (xy 318.990517 -400.6293) (xy 319.026204 -400.588113) (xy 319.06739 -400.552424)
			(xy 319.113236 -400.52296) (xy 319.162808 -400.500319) (xy 319.215097 -400.484964) (xy 319.269039 -400.477207)
			(xy 319.296288 -400.47672) (xy 320.159888 -400.47672) (xy 320.187143 -400.477126) (xy 320.2411 -400.484882)
			(xy 320.293403 -400.500238) (xy 320.342988 -400.522882) (xy 320.388846 -400.552352) (xy 320.430043 -400.588048)
			(xy 320.465741 -400.629244) (xy 320.495212 -400.675101) (xy 320.517857 -400.724686) (xy 320.533215 -400.776989)
			(xy 320.540973 -400.830945) (xy 320.540973 -400.885452) (xy 321.978483 -400.885452) (xy 321.978483 -400.830948)
			(xy 321.98624 -400.776998) (xy 322.001597 -400.724702) (xy 322.02424 -400.675124) (xy 322.053708 -400.629273)
			(xy 322.089402 -400.588082) (xy 322.130595 -400.552391) (xy 322.176448 -400.522926) (xy 322.226028 -400.500287)
			(xy 322.278326 -400.484935) (xy 322.332276 -400.477181) (xy 322.359528 -400.47672) (xy 323.223128 -400.47672)
			(xy 323.25038 -400.477152) (xy 323.304329 -400.484912) (xy 323.356624 -400.500271) (xy 323.406201 -400.522915)
			(xy 323.452051 -400.552384) (xy 323.493241 -400.588079) (xy 323.528932 -400.629271) (xy 323.558398 -400.675123)
			(xy 323.581039 -400.724702) (xy 323.596394 -400.776999) (xy 323.60415 -400.830948) (xy 323.60415 -400.885448)
			(xy 325.041806 -400.885448) (xy 325.041806 -400.830952) (xy 325.049561 -400.777011) (xy 325.064914 -400.724723)
			(xy 325.087551 -400.675152) (xy 325.117012 -400.629306) (xy 325.152697 -400.58812) (xy 325.193881 -400.552431)
			(xy 325.239724 -400.522966) (xy 325.289293 -400.500325) (xy 325.34158 -400.484968) (xy 325.39552 -400.477208)
			(xy 325.422768 -400.47672) (xy 326.286368 -400.47672) (xy 326.313624 -400.477125) (xy 326.367583 -400.484879)
			(xy 326.419888 -400.500233) (xy 326.469476 -400.522875) (xy 326.515337 -400.552345) (xy 326.556536 -400.588041)
			(xy 326.592236 -400.629238) (xy 326.621709 -400.675096) (xy 326.644356 -400.724682) (xy 326.659715 -400.776986)
			(xy 326.667473 -400.830944) (xy 326.667473 -400.885451) (xy 328.104983 -400.885451) (xy 328.104983 -400.830949)
			(xy 328.11274 -400.777001) (xy 328.128095 -400.724706) (xy 328.150737 -400.675129) (xy 328.180203 -400.629279)
			(xy 328.215895 -400.588089) (xy 328.257086 -400.552398) (xy 328.302936 -400.522933) (xy 328.352514 -400.500292)
			(xy 328.404809 -400.484938) (xy 328.458757 -400.477183) (xy 328.486008 -400.47672) (xy 329.349608 -400.47672)
			(xy 329.376861 -400.47715) (xy 329.430812 -400.484908) (xy 329.483109 -400.500265) (xy 329.532689 -400.522909)
			(xy 329.578542 -400.552377) (xy 329.619734 -400.588071) (xy 329.655428 -400.629264) (xy 329.684895 -400.675118)
			(xy 329.707537 -400.724698) (xy 329.722893 -400.776996) (xy 329.73065 -400.830947) (xy 329.73065 -400.885453)
			(xy 331.168183 -400.885453) (xy 331.168183 -400.830947) (xy 331.175941 -400.776996) (xy 331.191298 -400.724698)
			(xy 331.213943 -400.675118) (xy 331.243413 -400.629266) (xy 331.279109 -400.588075) (xy 331.320305 -400.552384)
			(xy 331.36616 -400.52292) (xy 331.415743 -400.500282) (xy 331.468043 -400.484931) (xy 331.521995 -400.47718)
			(xy 331.549248 -400.47672) (xy 332.412848 -400.47672) (xy 332.440099 -400.477153) (xy 332.494046 -400.484916)
			(xy 332.546338 -400.500276) (xy 332.595913 -400.522922) (xy 332.641761 -400.552391) (xy 332.682948 -400.588086)
			(xy 332.718637 -400.629278) (xy 332.748101 -400.675129) (xy 332.770741 -400.724707) (xy 332.786094 -400.777001)
			(xy 332.79385 -400.830949) (xy 332.79385 -400.885449) (xy 334.231506 -400.885449) (xy 334.231506 -400.830951)
			(xy 334.239262 -400.777009) (xy 334.254615 -400.724719) (xy 334.277254 -400.675146) (xy 334.306717 -400.6293)
			(xy 334.342404 -400.588113) (xy 334.38359 -400.552424) (xy 334.429436 -400.52296) (xy 334.479008 -400.500319)
			(xy 334.531297 -400.484964) (xy 334.585239 -400.477207) (xy 334.612488 -400.47672) (xy 335.476088 -400.47672)
			(xy 335.503343 -400.477126) (xy 335.5573 -400.484882) (xy 335.609603 -400.500238) (xy 335.659188 -400.522882)
			(xy 335.705046 -400.552352) (xy 335.746243 -400.588048) (xy 335.781941 -400.629244) (xy 335.811412 -400.675101)
			(xy 335.834057 -400.724686) (xy 335.849415 -400.776989) (xy 335.857173 -400.830945) (xy 335.857173 -400.885452)
			(xy 337.294683 -400.885452) (xy 337.294683 -400.830948) (xy 337.30244 -400.776998) (xy 337.317797 -400.724702)
			(xy 337.34044 -400.675124) (xy 337.369908 -400.629273) (xy 337.405602 -400.588082) (xy 337.446795 -400.552391)
			(xy 337.492648 -400.522926) (xy 337.542228 -400.500287) (xy 337.594526 -400.484935) (xy 337.648476 -400.477181)
			(xy 337.675728 -400.47672) (xy 338.539328 -400.47672) (xy 338.56658 -400.477152) (xy 338.620529 -400.484912)
			(xy 338.672824 -400.500271) (xy 338.722401 -400.522915) (xy 338.768251 -400.552384) (xy 338.809441 -400.588079)
			(xy 338.845132 -400.629271) (xy 338.874598 -400.675123) (xy 338.897239 -400.724702) (xy 338.912594 -400.776999)
			(xy 338.92035 -400.830948) (xy 338.92035 -400.885448) (xy 340.358006 -400.885448) (xy 340.358006 -400.830952)
			(xy 340.365761 -400.777011) (xy 340.381114 -400.724723) (xy 340.403751 -400.675152) (xy 340.433212 -400.629306)
			(xy 340.468897 -400.58812) (xy 340.510081 -400.552431) (xy 340.555924 -400.522966) (xy 340.605493 -400.500325)
			(xy 340.65778 -400.484968) (xy 340.71172 -400.477208) (xy 340.738968 -400.47672) (xy 341.602568 -400.47672)
			(xy 341.629824 -400.477125) (xy 341.683783 -400.484879) (xy 341.736088 -400.500233) (xy 341.785676 -400.522875)
			(xy 341.831537 -400.552345) (xy 341.872736 -400.588041) (xy 341.908436 -400.629238) (xy 341.937909 -400.675096)
			(xy 341.960556 -400.724682) (xy 341.975915 -400.776986) (xy 341.983673 -400.830944) (xy 341.983673 -400.885451)
			(xy 343.421183 -400.885451) (xy 343.421183 -400.830949) (xy 343.42894 -400.777001) (xy 343.444295 -400.724706)
			(xy 343.466937 -400.675129) (xy 343.496403 -400.629279) (xy 343.532095 -400.588089) (xy 343.573286 -400.552398)
			(xy 343.619136 -400.522933) (xy 343.668714 -400.500292) (xy 343.721009 -400.484938) (xy 343.774957 -400.477183)
			(xy 343.802208 -400.47672) (xy 344.665808 -400.47672) (xy 344.693061 -400.47715) (xy 344.747012 -400.484908)
			(xy 344.799309 -400.500265) (xy 344.848889 -400.522909) (xy 344.894742 -400.552377) (xy 344.935934 -400.588071)
			(xy 344.971628 -400.629264) (xy 345.001095 -400.675118) (xy 345.023737 -400.724698) (xy 345.039093 -400.776996)
			(xy 345.04685 -400.830947) (xy 345.04685 -400.885453) (xy 346.484383 -400.885453) (xy 346.484383 -400.830947)
			(xy 346.492141 -400.776996) (xy 346.507498 -400.724698) (xy 346.530143 -400.675118) (xy 346.559613 -400.629266)
			(xy 346.595309 -400.588075) (xy 346.636505 -400.552384) (xy 346.68236 -400.52292) (xy 346.731943 -400.500282)
			(xy 346.784243 -400.484931) (xy 346.838195 -400.47718) (xy 346.865448 -400.47672) (xy 347.729048 -400.47672)
			(xy 347.756299 -400.477153) (xy 347.810246 -400.484916) (xy 347.862538 -400.500276) (xy 347.912113 -400.522922)
			(xy 347.957961 -400.552391) (xy 347.999148 -400.588086) (xy 348.034837 -400.629278) (xy 348.064301 -400.675129)
			(xy 348.086941 -400.724707) (xy 348.102294 -400.777001) (xy 348.11005 -400.830949) (xy 348.11005 -400.885449)
			(xy 349.547706 -400.885449) (xy 349.547706 -400.830951) (xy 349.555462 -400.777009) (xy 349.570815 -400.724719)
			(xy 349.593454 -400.675146) (xy 349.622917 -400.6293) (xy 349.658604 -400.588113) (xy 349.69979 -400.552424)
			(xy 349.745636 -400.52296) (xy 349.795208 -400.500319) (xy 349.847497 -400.484964) (xy 349.901439 -400.477207)
			(xy 349.928688 -400.47672) (xy 350.792288 -400.47672) (xy 350.819543 -400.477126) (xy 350.8735 -400.484882)
			(xy 350.925803 -400.500238) (xy 350.975388 -400.522882) (xy 351.021246 -400.552352) (xy 351.062443 -400.588048)
			(xy 351.098141 -400.629244) (xy 351.127612 -400.675101) (xy 351.150257 -400.724686) (xy 351.165615 -400.776989)
			(xy 351.173373 -400.830945) (xy 351.173373 -400.885452) (xy 371.041883 -400.885452) (xy 371.041883 -400.830948)
			(xy 371.049641 -400.776998) (xy 371.064997 -400.724702) (xy 371.08764 -400.675123) (xy 371.117109 -400.629272)
			(xy 371.152803 -400.588082) (xy 371.193996 -400.552391) (xy 371.23985 -400.522926) (xy 371.28943 -400.500286)
			(xy 371.341728 -400.484934) (xy 371.395678 -400.477181) (xy 371.42293 -400.47672) (xy 372.28653 -400.47672)
			(xy 372.313782 -400.477152) (xy 372.36773 -400.484912) (xy 372.420025 -400.500271) (xy 372.469602 -400.522916)
			(xy 372.515452 -400.552385) (xy 372.556642 -400.588079) (xy 372.592333 -400.629272) (xy 372.621799 -400.675124)
			(xy 372.644439 -400.724703) (xy 372.659794 -400.776999) (xy 372.66755 -400.830948) (xy 372.66755 -400.885448)
			(xy 374.105206 -400.885448) (xy 374.105206 -400.830952) (xy 374.112961 -400.777011) (xy 374.128314 -400.724723)
			(xy 374.150951 -400.675151) (xy 374.180412 -400.629306) (xy 374.216098 -400.588119) (xy 374.257281 -400.55243)
			(xy 374.303125 -400.522965) (xy 374.352694 -400.500324) (xy 374.404982 -400.484968) (xy 374.458922 -400.477208)
			(xy 374.48617 -400.47672) (xy 375.34977 -400.47672) (xy 375.377026 -400.477125) (xy 375.430984 -400.484879)
			(xy 375.48329 -400.500234) (xy 375.532877 -400.522876) (xy 375.578738 -400.552345) (xy 375.619937 -400.588042)
			(xy 375.655637 -400.629238) (xy 375.68511 -400.675096) (xy 375.707756 -400.724682) (xy 375.723115 -400.776986)
			(xy 375.730873 -400.830944) (xy 375.730873 -400.885451) (xy 377.168383 -400.885451) (xy 377.168383 -400.830949)
			(xy 377.17614 -400.777001) (xy 377.191495 -400.724706) (xy 377.214137 -400.675129) (xy 377.243604 -400.629279)
			(xy 377.279296 -400.588089) (xy 377.320487 -400.552398) (xy 377.366338 -400.522932) (xy 377.415915 -400.500292)
			(xy 377.468211 -400.484938) (xy 377.522159 -400.477183) (xy 377.54941 -400.47672) (xy 378.41301 -400.47672)
			(xy 378.440263 -400.477151) (xy 378.494213 -400.484909) (xy 378.546511 -400.500266) (xy 378.59609 -400.522909)
			(xy 378.641943 -400.552378) (xy 378.683135 -400.588072) (xy 378.718828 -400.629265) (xy 378.748296 -400.675118)
			(xy 378.770938 -400.724699) (xy 378.786293 -400.776996) (xy 378.79405 -400.830947) (xy 378.79405 -400.885447)
			(xy 380.231706 -400.885447) (xy 380.231706 -400.830953) (xy 380.239461 -400.777014) (xy 380.254812 -400.724727)
			(xy 380.277448 -400.675157) (xy 380.306907 -400.629312) (xy 380.342591 -400.588126) (xy 380.383772 -400.552437)
			(xy 380.429613 -400.522972) (xy 380.47918 -400.50033) (xy 380.531465 -400.484971) (xy 380.585403 -400.47721)
			(xy 380.61265 -400.47672) (xy 381.47625 -400.47672) (xy 381.503507 -400.477124) (xy 381.557468 -400.484875)
			(xy 381.609775 -400.500228) (xy 381.659365 -400.522869) (xy 381.705228 -400.552338) (xy 381.74643 -400.588035)
			(xy 381.782132 -400.629232) (xy 381.811607 -400.675091) (xy 381.834254 -400.724678) (xy 381.849614 -400.776983)
			(xy 381.857373 -400.830943) (xy 381.857373 -400.885449) (xy 383.294906 -400.885449) (xy 383.294906 -400.830951)
			(xy 383.302662 -400.777008) (xy 383.318015 -400.724718) (xy 383.340654 -400.675145) (xy 383.370117 -400.629299)
			(xy 383.405805 -400.588112) (xy 383.446991 -400.552423) (xy 383.492837 -400.522959) (xy 383.542409 -400.500319)
			(xy 383.594699 -400.484964) (xy 383.648641 -400.477207) (xy 383.67589 -400.47672) (xy 384.53949 -400.47672)
			(xy 384.566745 -400.477126) (xy 384.620701 -400.484883) (xy 384.673004 -400.500239) (xy 384.722589 -400.522883)
			(xy 384.768447 -400.552352) (xy 384.809644 -400.588049) (xy 384.845342 -400.629245) (xy 384.874813 -400.675102)
			(xy 384.897458 -400.724686) (xy 384.912815 -400.776989) (xy 384.920573 -400.830945) (xy 384.920573 -400.885452)
			(xy 386.358083 -400.885452) (xy 386.358083 -400.830948) (xy 386.365841 -400.776998) (xy 386.381197 -400.724702)
			(xy 386.40384 -400.675123) (xy 386.433309 -400.629272) (xy 386.469003 -400.588082) (xy 386.510196 -400.552391)
			(xy 386.55605 -400.522926) (xy 386.60563 -400.500286) (xy 386.657928 -400.484934) (xy 386.711878 -400.477181)
			(xy 386.73913 -400.47672) (xy 387.60273 -400.47672) (xy 387.629982 -400.477152) (xy 387.68393 -400.484912)
			(xy 387.736225 -400.500271) (xy 387.785802 -400.522916) (xy 387.831652 -400.552385) (xy 387.872842 -400.588079)
			(xy 387.908533 -400.629272) (xy 387.937999 -400.675124) (xy 387.960639 -400.724703) (xy 387.975994 -400.776999)
			(xy 387.98375 -400.830948) (xy 387.98375 -400.885448) (xy 389.421406 -400.885448) (xy 389.421406 -400.830952)
			(xy 389.429161 -400.777011) (xy 389.444514 -400.724723) (xy 389.467151 -400.675151) (xy 389.496612 -400.629306)
			(xy 389.532298 -400.588119) (xy 389.573481 -400.55243) (xy 389.619325 -400.522965) (xy 389.668894 -400.500324)
			(xy 389.721182 -400.484968) (xy 389.775122 -400.477208) (xy 389.80237 -400.47672) (xy 390.66597 -400.47672)
			(xy 390.693226 -400.477125) (xy 390.747184 -400.484879) (xy 390.79949 -400.500234) (xy 390.849077 -400.522876)
			(xy 390.894938 -400.552345) (xy 390.936137 -400.588042) (xy 390.971837 -400.629238) (xy 391.00131 -400.675096)
			(xy 391.023956 -400.724682) (xy 391.039315 -400.776986) (xy 391.047073 -400.830944) (xy 391.047073 -400.885451)
			(xy 392.484583 -400.885451) (xy 392.484583 -400.830949) (xy 392.49234 -400.777001) (xy 392.507695 -400.724706)
			(xy 392.530337 -400.675129) (xy 392.559804 -400.629279) (xy 392.595496 -400.588089) (xy 392.636687 -400.552398)
			(xy 392.682538 -400.522932) (xy 392.732115 -400.500292) (xy 392.784411 -400.484938) (xy 392.838359 -400.477183)
			(xy 392.86561 -400.47672) (xy 393.72921 -400.47672) (xy 393.756463 -400.477151) (xy 393.810413 -400.484909)
			(xy 393.862711 -400.500266) (xy 393.91229 -400.522909) (xy 393.958143 -400.552378) (xy 393.999335 -400.588072)
			(xy 394.035028 -400.629265) (xy 394.064496 -400.675118) (xy 394.087138 -400.724699) (xy 394.102493 -400.776996)
			(xy 394.11025 -400.830947) (xy 394.11025 -400.885447) (xy 395.547906 -400.885447) (xy 395.547906 -400.830953)
			(xy 395.555661 -400.777014) (xy 395.571012 -400.724727) (xy 395.593648 -400.675157) (xy 395.623107 -400.629312)
			(xy 395.658791 -400.588126) (xy 395.699972 -400.552437) (xy 395.745813 -400.522972) (xy 395.79538 -400.50033)
			(xy 395.847665 -400.484971) (xy 395.901603 -400.47721) (xy 395.92885 -400.47672) (xy 396.79245 -400.47672)
			(xy 396.819707 -400.477124) (xy 396.873668 -400.484875) (xy 396.925975 -400.500228) (xy 396.975565 -400.522869)
			(xy 397.021428 -400.552338) (xy 397.06263 -400.588035) (xy 397.098332 -400.629232) (xy 397.127807 -400.675091)
			(xy 397.150454 -400.724678) (xy 397.165814 -400.776983) (xy 397.173573 -400.830943) (xy 397.173573 -400.885449)
			(xy 398.611106 -400.885449) (xy 398.611106 -400.830951) (xy 398.618862 -400.777008) (xy 398.634215 -400.724718)
			(xy 398.656854 -400.675145) (xy 398.686317 -400.629299) (xy 398.722005 -400.588112) (xy 398.763191 -400.552423)
			(xy 398.809037 -400.522959) (xy 398.858609 -400.500319) (xy 398.910899 -400.484964) (xy 398.964841 -400.477207)
			(xy 398.99209 -400.47672) (xy 399.85569 -400.47672) (xy 399.882945 -400.477126) (xy 399.936901 -400.484883)
			(xy 399.989204 -400.500239) (xy 400.038789 -400.522883) (xy 400.084647 -400.552352) (xy 400.125844 -400.588049)
			(xy 400.161542 -400.629245) (xy 400.191013 -400.675102) (xy 400.213658 -400.724686) (xy 400.229015 -400.776989)
			(xy 400.236773 -400.830945) (xy 400.236773 -400.885452) (xy 401.674283 -400.885452) (xy 401.674283 -400.830948)
			(xy 401.682041 -400.776998) (xy 401.697397 -400.724702) (xy 401.72004 -400.675123) (xy 401.749509 -400.629272)
			(xy 401.785203 -400.588082) (xy 401.826396 -400.552391) (xy 401.87225 -400.522926) (xy 401.92183 -400.500286)
			(xy 401.974128 -400.484934) (xy 402.028078 -400.477181) (xy 402.05533 -400.47672) (xy 402.91893 -400.47672)
			(xy 402.946182 -400.477152) (xy 403.00013 -400.484912) (xy 403.052425 -400.500271) (xy 403.102002 -400.522916)
			(xy 403.147852 -400.552385) (xy 403.189042 -400.588079) (xy 403.224733 -400.629272) (xy 403.254199 -400.675124)
			(xy 403.276839 -400.724703) (xy 403.292194 -400.776999) (xy 403.29995 -400.830948) (xy 403.29995 -400.885448)
			(xy 404.737606 -400.885448) (xy 404.737606 -400.830952) (xy 404.745361 -400.777011) (xy 404.760714 -400.724723)
			(xy 404.783351 -400.675151) (xy 404.812812 -400.629306) (xy 404.848498 -400.588119) (xy 404.889681 -400.55243)
			(xy 404.935525 -400.522965) (xy 404.985094 -400.500324) (xy 405.037382 -400.484968) (xy 405.091322 -400.477208)
			(xy 405.11857 -400.47672) (xy 405.98217 -400.47672) (xy 406.009426 -400.477125) (xy 406.063384 -400.484879)
			(xy 406.11569 -400.500234) (xy 406.165277 -400.522876) (xy 406.211138 -400.552345) (xy 406.252337 -400.588042)
			(xy 406.288037 -400.629238) (xy 406.31751 -400.675096) (xy 406.340156 -400.724682) (xy 406.355515 -400.776986)
			(xy 406.363273 -400.830944) (xy 406.363273 -400.885451) (xy 407.800783 -400.885451) (xy 407.800783 -400.830949)
			(xy 407.80854 -400.777001) (xy 407.823895 -400.724706) (xy 407.846537 -400.675129) (xy 407.876004 -400.629279)
			(xy 407.911696 -400.588089) (xy 407.952887 -400.552398) (xy 407.998738 -400.522932) (xy 408.048315 -400.500292)
			(xy 408.100611 -400.484938) (xy 408.154559 -400.477183) (xy 408.18181 -400.47672) (xy 409.04541 -400.47672)
			(xy 409.072663 -400.477151) (xy 409.126613 -400.484909) (xy 409.178911 -400.500266) (xy 409.22849 -400.522909)
			(xy 409.274343 -400.552378) (xy 409.315535 -400.588072) (xy 409.351228 -400.629265) (xy 409.380696 -400.675118)
			(xy 409.403338 -400.724699) (xy 409.418693 -400.776996) (xy 409.42645 -400.830947) (xy 409.42645 -400.885447)
			(xy 410.864106 -400.885447) (xy 410.864106 -400.830953) (xy 410.871861 -400.777014) (xy 410.887212 -400.724727)
			(xy 410.909848 -400.675157) (xy 410.939307 -400.629312) (xy 410.974991 -400.588126) (xy 411.016172 -400.552437)
			(xy 411.062013 -400.522972) (xy 411.11158 -400.50033) (xy 411.163865 -400.484971) (xy 411.217803 -400.47721)
			(xy 411.24505 -400.47672) (xy 412.10865 -400.47672) (xy 412.135907 -400.477124) (xy 412.189868 -400.484875)
			(xy 412.242175 -400.500228) (xy 412.291765 -400.522869) (xy 412.337628 -400.552338) (xy 412.37883 -400.588035)
			(xy 412.414532 -400.629232) (xy 412.444007 -400.675091) (xy 412.466654 -400.724678) (xy 412.482014 -400.776983)
			(xy 412.489773 -400.830943) (xy 412.489773 -400.885449) (xy 413.927306 -400.885449) (xy 413.927306 -400.830951)
			(xy 413.935062 -400.777008) (xy 413.950415 -400.724718) (xy 413.973054 -400.675145) (xy 414.002517 -400.629299)
			(xy 414.038205 -400.588112) (xy 414.079391 -400.552423) (xy 414.125237 -400.522959) (xy 414.174809 -400.500319)
			(xy 414.227099 -400.484964) (xy 414.281041 -400.477207) (xy 414.30829 -400.47672) (xy 415.17189 -400.47672)
			(xy 415.199145 -400.477126) (xy 415.253101 -400.484883) (xy 415.305404 -400.500239) (xy 415.354989 -400.522883)
			(xy 415.400847 -400.552352) (xy 415.442044 -400.588049) (xy 415.477742 -400.629245) (xy 415.507213 -400.675102)
			(xy 415.529858 -400.724686) (xy 415.545215 -400.776989) (xy 415.552973 -400.830945) (xy 415.552973 -400.885452)
			(xy 416.990483 -400.885452) (xy 416.990483 -400.830948) (xy 416.998241 -400.776998) (xy 417.013597 -400.724702)
			(xy 417.03624 -400.675123) (xy 417.065709 -400.629272) (xy 417.101403 -400.588082) (xy 417.142596 -400.552391)
			(xy 417.18845 -400.522926) (xy 417.23803 -400.500286) (xy 417.290328 -400.484934) (xy 417.344278 -400.477181)
			(xy 417.37153 -400.47672) (xy 418.23513 -400.47672) (xy 418.262382 -400.477152) (xy 418.31633 -400.484912)
			(xy 418.368625 -400.500271) (xy 418.418202 -400.522916) (xy 418.464052 -400.552385) (xy 418.505242 -400.588079)
			(xy 418.540933 -400.629272) (xy 418.570399 -400.675124) (xy 418.593039 -400.724703) (xy 418.608394 -400.776999)
			(xy 418.61615 -400.830948) (xy 418.61615 -400.885452) (xy 418.608394 -400.939401) (xy 418.593039 -400.991697)
			(xy 418.570399 -401.041276) (xy 418.540933 -401.087128) (xy 418.505242 -401.128321) (xy 418.464052 -401.164015)
			(xy 418.418202 -401.193484) (xy 418.368625 -401.216129) (xy 418.31633 -401.231488) (xy 418.262382 -401.239248)
			(xy 418.23513 -401.239736) (xy 417.37153 -401.239736) (xy 417.344278 -401.239219) (xy 417.290328 -401.231466)
			(xy 417.23803 -401.216114) (xy 417.18845 -401.193474) (xy 417.142596 -401.164009) (xy 417.101403 -401.128318)
			(xy 417.065709 -401.087128) (xy 417.03624 -401.041277) (xy 417.013597 -400.991698) (xy 416.998241 -400.939402)
			(xy 416.990483 -400.885452) (xy 415.552973 -400.885452) (xy 415.552973 -400.885455) (xy 415.545215 -400.939411)
			(xy 415.529858 -400.991714) (xy 415.507213 -401.041298) (xy 415.477742 -401.087155) (xy 415.442044 -401.128351)
			(xy 415.400847 -401.164048) (xy 415.354989 -401.193517) (xy 415.305404 -401.216161) (xy 415.253101 -401.231517)
			(xy 415.199145 -401.239274) (xy 415.17189 -401.239736) (xy 414.30829 -401.239736) (xy 414.281041 -401.239193)
			(xy 414.227099 -401.231436) (xy 414.174809 -401.216081) (xy 414.125237 -401.193441) (xy 414.079391 -401.163977)
			(xy 414.038205 -401.128288) (xy 414.002517 -401.087101) (xy 413.973054 -401.041255) (xy 413.950415 -400.991682)
			(xy 413.935062 -400.939392) (xy 413.927306 -400.885449) (xy 412.489773 -400.885449) (xy 412.489773 -400.885457)
			(xy 412.482014 -400.939416) (xy 412.466654 -400.991722) (xy 412.444007 -401.041309) (xy 412.414532 -401.087168)
			(xy 412.37883 -401.128365) (xy 412.337628 -401.164062) (xy 412.291765 -401.193531) (xy 412.242175 -401.216172)
			(xy 412.189868 -401.231525) (xy 412.135907 -401.239276) (xy 412.10865 -401.239736) (xy 411.24505 -401.239736)
			(xy 411.217803 -401.23919) (xy 411.163865 -401.231429) (xy 411.11158 -401.21607) (xy 411.062013 -401.193428)
			(xy 411.016172 -401.163963) (xy 410.974991 -401.128274) (xy 410.939307 -401.087088) (xy 410.909848 -401.041243)
			(xy 410.887212 -400.991673) (xy 410.871861 -400.939386) (xy 410.864106 -400.885447) (xy 409.42645 -400.885447)
			(xy 409.42645 -400.885453) (xy 409.418693 -400.939404) (xy 409.403338 -400.991701) (xy 409.380696 -401.041282)
			(xy 409.351228 -401.087135) (xy 409.315535 -401.128328) (xy 409.274343 -401.164022) (xy 409.22849 -401.193491)
			(xy 409.178911 -401.216134) (xy 409.126613 -401.231491) (xy 409.072663 -401.239249) (xy 409.04541 -401.239736)
			(xy 408.18181 -401.239736) (xy 408.154559 -401.239217) (xy 408.100611 -401.231462) (xy 408.048315 -401.216108)
			(xy 407.998738 -401.193468) (xy 407.952887 -401.164002) (xy 407.911696 -401.128311) (xy 407.876004 -401.087121)
			(xy 407.846537 -401.041271) (xy 407.823895 -400.991694) (xy 407.80854 -400.939399) (xy 407.800783 -400.885451)
			(xy 406.363273 -400.885451) (xy 406.363273 -400.885456) (xy 406.355515 -400.939414) (xy 406.340156 -400.991718)
			(xy 406.31751 -401.041304) (xy 406.288037 -401.087162) (xy 406.252337 -401.128358) (xy 406.211138 -401.164055)
			(xy 406.165277 -401.193524) (xy 406.11569 -401.216166) (xy 406.063384 -401.231521) (xy 406.009426 -401.239275)
			(xy 405.98217 -401.239736) (xy 405.11857 -401.239736) (xy 405.091322 -401.239192) (xy 405.037382 -401.231432)
			(xy 404.985094 -401.216076) (xy 404.935525 -401.193435) (xy 404.889682 -401.16397) (xy 404.848498 -401.128281)
			(xy 404.812812 -401.087094) (xy 404.783351 -401.041249) (xy 404.760714 -400.991677) (xy 404.745361 -400.939389)
			(xy 404.737606 -400.885448) (xy 403.29995 -400.885448) (xy 403.29995 -400.885452) (xy 403.292194 -400.939401)
			(xy 403.276839 -400.991697) (xy 403.254199 -401.041276) (xy 403.224733 -401.087128) (xy 403.189042 -401.128321)
			(xy 403.147852 -401.164015) (xy 403.102002 -401.193484) (xy 403.052425 -401.216129) (xy 403.00013 -401.231488)
			(xy 402.946182 -401.239248) (xy 402.91893 -401.239736) (xy 402.05533 -401.239736) (xy 402.028078 -401.239219)
			(xy 401.974128 -401.231466) (xy 401.92183 -401.216114) (xy 401.87225 -401.193474) (xy 401.826396 -401.164009)
			(xy 401.785203 -401.128318) (xy 401.749509 -401.087128) (xy 401.72004 -401.041277) (xy 401.697397 -400.991698)
			(xy 401.682041 -400.939402) (xy 401.674283 -400.885452) (xy 400.236773 -400.885452) (xy 400.236773 -400.885455)
			(xy 400.229015 -400.939411) (xy 400.213658 -400.991714) (xy 400.191013 -401.041298) (xy 400.161542 -401.087155)
			(xy 400.125844 -401.128351) (xy 400.084647 -401.164048) (xy 400.038789 -401.193517) (xy 399.989204 -401.216161)
			(xy 399.936901 -401.231517) (xy 399.882945 -401.239274) (xy 399.85569 -401.239736) (xy 398.99209 -401.239736)
			(xy 398.964841 -401.239193) (xy 398.910899 -401.231436) (xy 398.858609 -401.216081) (xy 398.809037 -401.193441)
			(xy 398.763191 -401.163977) (xy 398.722005 -401.128288) (xy 398.686317 -401.087101) (xy 398.656854 -401.041255)
			(xy 398.634215 -400.991682) (xy 398.618862 -400.939392) (xy 398.611106 -400.885449) (xy 397.173573 -400.885449)
			(xy 397.173573 -400.885457) (xy 397.165814 -400.939416) (xy 397.150454 -400.991722) (xy 397.127807 -401.041309)
			(xy 397.098332 -401.087168) (xy 397.06263 -401.128365) (xy 397.021428 -401.164062) (xy 396.975565 -401.193531)
			(xy 396.925975 -401.216172) (xy 396.873668 -401.231525) (xy 396.819707 -401.239276) (xy 396.79245 -401.239736)
			(xy 395.92885 -401.239736) (xy 395.901603 -401.23919) (xy 395.847665 -401.231429) (xy 395.79538 -401.21607)
			(xy 395.745813 -401.193428) (xy 395.699972 -401.163963) (xy 395.658791 -401.128274) (xy 395.623107 -401.087088)
			(xy 395.593648 -401.041243) (xy 395.571012 -400.991673) (xy 395.555661 -400.939386) (xy 395.547906 -400.885447)
			(xy 394.11025 -400.885447) (xy 394.11025 -400.885453) (xy 394.102493 -400.939404) (xy 394.087138 -400.991701)
			(xy 394.064496 -401.041282) (xy 394.035028 -401.087135) (xy 393.999335 -401.128328) (xy 393.958143 -401.164022)
			(xy 393.91229 -401.193491) (xy 393.862711 -401.216134) (xy 393.810413 -401.231491) (xy 393.756463 -401.239249)
			(xy 393.72921 -401.239736) (xy 392.86561 -401.239736) (xy 392.838359 -401.239217) (xy 392.784411 -401.231462)
			(xy 392.732115 -401.216108) (xy 392.682538 -401.193468) (xy 392.636687 -401.164002) (xy 392.595496 -401.128311)
			(xy 392.559804 -401.087121) (xy 392.530337 -401.041271) (xy 392.507695 -400.991694) (xy 392.49234 -400.939399)
			(xy 392.484583 -400.885451) (xy 391.047073 -400.885451) (xy 391.047073 -400.885456) (xy 391.039315 -400.939414)
			(xy 391.023956 -400.991718) (xy 391.00131 -401.041304) (xy 390.971837 -401.087162) (xy 390.936137 -401.128358)
			(xy 390.894938 -401.164055) (xy 390.849077 -401.193524) (xy 390.79949 -401.216166) (xy 390.747184 -401.231521)
			(xy 390.693226 -401.239275) (xy 390.66597 -401.239736) (xy 389.80237 -401.239736) (xy 389.775122 -401.239192)
			(xy 389.721182 -401.231432) (xy 389.668894 -401.216076) (xy 389.619325 -401.193435) (xy 389.573482 -401.16397)
			(xy 389.532298 -401.128281) (xy 389.496612 -401.087094) (xy 389.467151 -401.041249) (xy 389.444514 -400.991677)
			(xy 389.429161 -400.939389) (xy 389.421406 -400.885448) (xy 387.98375 -400.885448) (xy 387.98375 -400.885452)
			(xy 387.975994 -400.939401) (xy 387.960639 -400.991697) (xy 387.937999 -401.041276) (xy 387.908533 -401.087128)
			(xy 387.872842 -401.128321) (xy 387.831652 -401.164015) (xy 387.785802 -401.193484) (xy 387.736225 -401.216129)
			(xy 387.68393 -401.231488) (xy 387.629982 -401.239248) (xy 387.60273 -401.239736) (xy 386.73913 -401.239736)
			(xy 386.711878 -401.239219) (xy 386.657928 -401.231466) (xy 386.60563 -401.216114) (xy 386.55605 -401.193474)
			(xy 386.510196 -401.164009) (xy 386.469003 -401.128318) (xy 386.433309 -401.087128) (xy 386.40384 -401.041277)
			(xy 386.381197 -400.991698) (xy 386.365841 -400.939402) (xy 386.358083 -400.885452) (xy 384.920573 -400.885452)
			(xy 384.920573 -400.885455) (xy 384.912815 -400.939411) (xy 384.897458 -400.991714) (xy 384.874813 -401.041298)
			(xy 384.845342 -401.087155) (xy 384.809644 -401.128351) (xy 384.768447 -401.164048) (xy 384.722589 -401.193517)
			(xy 384.673004 -401.216161) (xy 384.620701 -401.231517) (xy 384.566745 -401.239274) (xy 384.53949 -401.239736)
			(xy 383.67589 -401.239736) (xy 383.648641 -401.239193) (xy 383.594699 -401.231436) (xy 383.542409 -401.216081)
			(xy 383.492837 -401.193441) (xy 383.446991 -401.163977) (xy 383.405805 -401.128288) (xy 383.370117 -401.087101)
			(xy 383.340654 -401.041255) (xy 383.318015 -400.991682) (xy 383.302662 -400.939392) (xy 383.294906 -400.885449)
			(xy 381.857373 -400.885449) (xy 381.857373 -400.885457) (xy 381.849614 -400.939416) (xy 381.834254 -400.991722)
			(xy 381.811607 -401.041309) (xy 381.782132 -401.087168) (xy 381.74643 -401.128365) (xy 381.705228 -401.164062)
			(xy 381.659365 -401.193531) (xy 381.609775 -401.216172) (xy 381.557468 -401.231525) (xy 381.503507 -401.239276)
			(xy 381.47625 -401.239736) (xy 380.61265 -401.239736) (xy 380.585403 -401.23919) (xy 380.531465 -401.231429)
			(xy 380.47918 -401.21607) (xy 380.429613 -401.193428) (xy 380.383772 -401.163963) (xy 380.342591 -401.128274)
			(xy 380.306907 -401.087088) (xy 380.277448 -401.041243) (xy 380.254812 -400.991673) (xy 380.239461 -400.939386)
			(xy 380.231706 -400.885447) (xy 378.79405 -400.885447) (xy 378.79405 -400.885453) (xy 378.786293 -400.939404)
			(xy 378.770938 -400.991701) (xy 378.748296 -401.041282) (xy 378.718828 -401.087135) (xy 378.683135 -401.128328)
			(xy 378.641943 -401.164022) (xy 378.59609 -401.193491) (xy 378.546511 -401.216134) (xy 378.494213 -401.231491)
			(xy 378.440263 -401.239249) (xy 378.41301 -401.239736) (xy 377.54941 -401.239736) (xy 377.522159 -401.239217)
			(xy 377.468211 -401.231462) (xy 377.415915 -401.216108) (xy 377.366338 -401.193468) (xy 377.320487 -401.164002)
			(xy 377.279296 -401.128311) (xy 377.243604 -401.087121) (xy 377.214137 -401.041271) (xy 377.191495 -400.991694)
			(xy 377.17614 -400.939399) (xy 377.168383 -400.885451) (xy 375.730873 -400.885451) (xy 375.730873 -400.885456)
			(xy 375.723115 -400.939414) (xy 375.707756 -400.991718) (xy 375.68511 -401.041304) (xy 375.655637 -401.087162)
			(xy 375.619937 -401.128358) (xy 375.578738 -401.164055) (xy 375.532877 -401.193524) (xy 375.48329 -401.216166)
			(xy 375.430984 -401.231521) (xy 375.377026 -401.239275) (xy 375.34977 -401.239736) (xy 374.48617 -401.239736)
			(xy 374.458922 -401.239192) (xy 374.404982 -401.231432) (xy 374.352694 -401.216076) (xy 374.303125 -401.193435)
			(xy 374.257282 -401.16397) (xy 374.216098 -401.128281) (xy 374.180412 -401.087094) (xy 374.150951 -401.041249)
			(xy 374.128314 -400.991677) (xy 374.112961 -400.939389) (xy 374.105206 -400.885448) (xy 372.66755 -400.885448)
			(xy 372.66755 -400.885452) (xy 372.659794 -400.939401) (xy 372.644439 -400.991697) (xy 372.621799 -401.041276)
			(xy 372.592333 -401.087128) (xy 372.556642 -401.128321) (xy 372.515452 -401.164015) (xy 372.469602 -401.193484)
			(xy 372.420025 -401.216129) (xy 372.36773 -401.231488) (xy 372.313782 -401.239248) (xy 372.28653 -401.239736)
			(xy 371.42293 -401.239736) (xy 371.395678 -401.239219) (xy 371.341728 -401.231466) (xy 371.28943 -401.216114)
			(xy 371.23985 -401.193474) (xy 371.193996 -401.164009) (xy 371.152803 -401.128318) (xy 371.117109 -401.087128)
			(xy 371.08764 -401.041277) (xy 371.064997 -400.991698) (xy 371.049641 -400.939402) (xy 371.041883 -400.885452)
			(xy 351.173373 -400.885452) (xy 351.173373 -400.885455) (xy 351.165615 -400.939411) (xy 351.150257 -400.991714)
			(xy 351.127612 -401.041299) (xy 351.098141 -401.087156) (xy 351.062443 -401.128352) (xy 351.021246 -401.164048)
			(xy 350.975388 -401.193518) (xy 350.925803 -401.216162) (xy 350.8735 -401.231518) (xy 350.819543 -401.239274)
			(xy 350.792288 -401.239736) (xy 349.928688 -401.239736) (xy 349.901439 -401.239193) (xy 349.847497 -401.231436)
			(xy 349.795208 -401.216081) (xy 349.745636 -401.19344) (xy 349.69979 -401.163976) (xy 349.658604 -401.128287)
			(xy 349.622917 -401.0871) (xy 349.593454 -401.041254) (xy 349.570815 -400.991681) (xy 349.555462 -400.939391)
			(xy 349.547706 -400.885449) (xy 348.11005 -400.885449) (xy 348.11005 -400.885451) (xy 348.102294 -400.939399)
			(xy 348.086941 -400.991693) (xy 348.064301 -401.041271) (xy 348.034837 -401.087122) (xy 347.999148 -401.128314)
			(xy 347.957961 -401.164009) (xy 347.912113 -401.193478) (xy 347.862538 -401.216124) (xy 347.810245 -401.231484)
			(xy 347.756299 -401.239247) (xy 347.729048 -401.239736) (xy 346.865448 -401.239736) (xy 346.838195 -401.23922)
			(xy 346.784243 -401.231469) (xy 346.731943 -401.216118) (xy 346.68236 -401.19348) (xy 346.636505 -401.164016)
			(xy 346.595309 -401.128325) (xy 346.559613 -401.087134) (xy 346.530143 -401.041282) (xy 346.507498 -400.991702)
			(xy 346.492141 -400.939404) (xy 346.484383 -400.885453) (xy 345.04685 -400.885453) (xy 345.039093 -400.939404)
			(xy 345.023737 -400.991702) (xy 345.001095 -401.041282) (xy 344.971628 -401.087136) (xy 344.935934 -401.128329)
			(xy 344.894742 -401.164023) (xy 344.848889 -401.193491) (xy 344.799309 -401.216135) (xy 344.747012 -401.231492)
			(xy 344.693061 -401.23925) (xy 344.665808 -401.239736) (xy 343.802208 -401.239736) (xy 343.774957 -401.239217)
			(xy 343.721009 -401.231462) (xy 343.668714 -401.216108) (xy 343.619136 -401.193467) (xy 343.573286 -401.164002)
			(xy 343.532095 -401.128311) (xy 343.496403 -401.087121) (xy 343.466937 -401.041271) (xy 343.444295 -400.991694)
			(xy 343.42894 -400.939399) (xy 343.421183 -400.885451) (xy 341.983673 -400.885451) (xy 341.983673 -400.885456)
			(xy 341.975915 -400.939414) (xy 341.960556 -400.991718) (xy 341.937909 -401.041304) (xy 341.908436 -401.087162)
			(xy 341.872736 -401.128359) (xy 341.831537 -401.164055) (xy 341.785676 -401.193525) (xy 341.736088 -401.216167)
			(xy 341.683783 -401.231521) (xy 341.629824 -401.239275) (xy 341.602568 -401.239736) (xy 340.738968 -401.239736)
			(xy 340.71172 -401.239192) (xy 340.65778 -401.231432) (xy 340.605493 -401.216075) (xy 340.555924 -401.193434)
			(xy 340.510081 -401.163969) (xy 340.468897 -401.12828) (xy 340.433212 -401.087094) (xy 340.403751 -401.041248)
			(xy 340.381114 -400.991677) (xy 340.365761 -400.939389) (xy 340.358006 -400.885448) (xy 338.92035 -400.885448)
			(xy 338.92035 -400.885452) (xy 338.912594 -400.939401) (xy 338.897239 -400.991698) (xy 338.874598 -401.041277)
			(xy 338.845132 -401.087129) (xy 338.809441 -401.128321) (xy 338.768251 -401.164016) (xy 338.722401 -401.193485)
			(xy 338.672824 -401.216129) (xy 338.620529 -401.231488) (xy 338.56658 -401.239248) (xy 338.539328 -401.239736)
			(xy 337.675728 -401.239736) (xy 337.648476 -401.239219) (xy 337.594526 -401.231465) (xy 337.542228 -401.216113)
			(xy 337.492648 -401.193474) (xy 337.446795 -401.164009) (xy 337.405602 -401.128318) (xy 337.369908 -401.087127)
			(xy 337.34044 -401.041276) (xy 337.317797 -400.991698) (xy 337.30244 -400.939402) (xy 337.294683 -400.885452)
			(xy 335.857173 -400.885452) (xy 335.857173 -400.885455) (xy 335.849415 -400.939411) (xy 335.834057 -400.991714)
			(xy 335.811412 -401.041299) (xy 335.781941 -401.087156) (xy 335.746243 -401.128352) (xy 335.705046 -401.164048)
			(xy 335.659188 -401.193518) (xy 335.609603 -401.216162) (xy 335.5573 -401.231518) (xy 335.503343 -401.239274)
			(xy 335.476088 -401.239736) (xy 334.612488 -401.239736) (xy 334.585239 -401.239193) (xy 334.531297 -401.231436)
			(xy 334.479008 -401.216081) (xy 334.429436 -401.19344) (xy 334.38359 -401.163976) (xy 334.342404 -401.128287)
			(xy 334.306717 -401.0871) (xy 334.277254 -401.041254) (xy 334.254615 -400.991681) (xy 334.239262 -400.939391)
			(xy 334.231506 -400.885449) (xy 332.79385 -400.885449) (xy 332.79385 -400.885451) (xy 332.786094 -400.939399)
			(xy 332.770741 -400.991693) (xy 332.748101 -401.041271) (xy 332.718637 -401.087122) (xy 332.682948 -401.128314)
			(xy 332.641761 -401.164009) (xy 332.595913 -401.193478) (xy 332.546338 -401.216124) (xy 332.494045 -401.231484)
			(xy 332.440099 -401.239247) (xy 332.412848 -401.239736) (xy 331.549248 -401.239736) (xy 331.521995 -401.23922)
			(xy 331.468043 -401.231469) (xy 331.415743 -401.216118) (xy 331.36616 -401.19348) (xy 331.320305 -401.164016)
			(xy 331.279109 -401.128325) (xy 331.243413 -401.087134) (xy 331.213943 -401.041282) (xy 331.191298 -400.991702)
			(xy 331.175941 -400.939404) (xy 331.168183 -400.885453) (xy 329.73065 -400.885453) (xy 329.722893 -400.939404)
			(xy 329.707537 -400.991702) (xy 329.684895 -401.041282) (xy 329.655428 -401.087136) (xy 329.619734 -401.128329)
			(xy 329.578542 -401.164023) (xy 329.532689 -401.193491) (xy 329.483109 -401.216135) (xy 329.430812 -401.231492)
			(xy 329.376861 -401.23925) (xy 329.349608 -401.239736) (xy 328.486008 -401.239736) (xy 328.458757 -401.239217)
			(xy 328.404809 -401.231462) (xy 328.352514 -401.216108) (xy 328.302936 -401.193467) (xy 328.257086 -401.164002)
			(xy 328.215895 -401.128311) (xy 328.180203 -401.087121) (xy 328.150737 -401.041271) (xy 328.128095 -400.991694)
			(xy 328.11274 -400.939399) (xy 328.104983 -400.885451) (xy 326.667473 -400.885451) (xy 326.667473 -400.885456)
			(xy 326.659715 -400.939414) (xy 326.644356 -400.991718) (xy 326.621709 -401.041304) (xy 326.592236 -401.087162)
			(xy 326.556536 -401.128359) (xy 326.515337 -401.164055) (xy 326.469476 -401.193525) (xy 326.419888 -401.216167)
			(xy 326.367583 -401.231521) (xy 326.313624 -401.239275) (xy 326.286368 -401.239736) (xy 325.422768 -401.239736)
			(xy 325.39552 -401.239192) (xy 325.34158 -401.231432) (xy 325.289293 -401.216075) (xy 325.239724 -401.193434)
			(xy 325.193881 -401.163969) (xy 325.152697 -401.12828) (xy 325.117012 -401.087094) (xy 325.087551 -401.041248)
			(xy 325.064914 -400.991677) (xy 325.049561 -400.939389) (xy 325.041806 -400.885448) (xy 323.60415 -400.885448)
			(xy 323.60415 -400.885452) (xy 323.596394 -400.939401) (xy 323.581039 -400.991698) (xy 323.558398 -401.041277)
			(xy 323.528932 -401.087129) (xy 323.493241 -401.128321) (xy 323.452051 -401.164016) (xy 323.406201 -401.193485)
			(xy 323.356624 -401.216129) (xy 323.304329 -401.231488) (xy 323.25038 -401.239248) (xy 323.223128 -401.239736)
			(xy 322.359528 -401.239736) (xy 322.332276 -401.239219) (xy 322.278326 -401.231465) (xy 322.226028 -401.216113)
			(xy 322.176448 -401.193474) (xy 322.130595 -401.164009) (xy 322.089402 -401.128318) (xy 322.053708 -401.087127)
			(xy 322.02424 -401.041276) (xy 322.001597 -400.991698) (xy 321.98624 -400.939402) (xy 321.978483 -400.885452)
			(xy 320.540973 -400.885452) (xy 320.540973 -400.885455) (xy 320.533215 -400.939411) (xy 320.517857 -400.991714)
			(xy 320.495212 -401.041299) (xy 320.465741 -401.087156) (xy 320.430043 -401.128352) (xy 320.388846 -401.164048)
			(xy 320.342988 -401.193518) (xy 320.293403 -401.216162) (xy 320.2411 -401.231518) (xy 320.187143 -401.239274)
			(xy 320.159888 -401.239736) (xy 319.296288 -401.239736) (xy 319.269039 -401.239193) (xy 319.215097 -401.231436)
			(xy 319.162808 -401.216081) (xy 319.113236 -401.19344) (xy 319.06739 -401.163976) (xy 319.026204 -401.128287)
			(xy 318.990517 -401.0871) (xy 318.961054 -401.041254) (xy 318.938415 -400.991681) (xy 318.923062 -400.939391)
			(xy 318.915306 -400.885449) (xy 317.47765 -400.885449) (xy 317.47765 -400.885451) (xy 317.469894 -400.939399)
			(xy 317.454541 -400.991693) (xy 317.431901 -401.041271) (xy 317.402437 -401.087122) (xy 317.366748 -401.128314)
			(xy 317.325561 -401.164009) (xy 317.279713 -401.193478) (xy 317.230138 -401.216124) (xy 317.177845 -401.231484)
			(xy 317.123899 -401.239247) (xy 317.096648 -401.239736) (xy 316.233048 -401.239736) (xy 316.205795 -401.23922)
			(xy 316.151843 -401.231469) (xy 316.099543 -401.216118) (xy 316.04996 -401.19348) (xy 316.004105 -401.164016)
			(xy 315.962909 -401.128325) (xy 315.927213 -401.087134) (xy 315.897743 -401.041282) (xy 315.875098 -400.991702)
			(xy 315.859741 -400.939404) (xy 315.851983 -400.885453) (xy 314.41445 -400.885453) (xy 314.406693 -400.939404)
			(xy 314.391337 -400.991702) (xy 314.368695 -401.041282) (xy 314.339228 -401.087136) (xy 314.303534 -401.128329)
			(xy 314.262342 -401.164023) (xy 314.216489 -401.193491) (xy 314.166909 -401.216135) (xy 314.114612 -401.231492)
			(xy 314.060661 -401.23925) (xy 314.033408 -401.239736) (xy 313.169808 -401.239736) (xy 313.142557 -401.239217)
			(xy 313.088609 -401.231462) (xy 313.036314 -401.216108) (xy 312.986736 -401.193467) (xy 312.940886 -401.164002)
			(xy 312.899695 -401.128311) (xy 312.864003 -401.087121) (xy 312.834537 -401.041271) (xy 312.811895 -400.991694)
			(xy 312.79654 -400.939399) (xy 312.788783 -400.885451) (xy 311.351273 -400.885451) (xy 311.351273 -400.885456)
			(xy 311.343515 -400.939414) (xy 311.328156 -400.991718) (xy 311.305509 -401.041304) (xy 311.276036 -401.087162)
			(xy 311.240336 -401.128359) (xy 311.199137 -401.164055) (xy 311.153276 -401.193525) (xy 311.103688 -401.216167)
			(xy 311.051383 -401.231521) (xy 310.997424 -401.239275) (xy 310.970168 -401.239736) (xy 310.106568 -401.239736)
			(xy 310.07932 -401.239192) (xy 310.02538 -401.231432) (xy 309.973093 -401.216075) (xy 309.923524 -401.193434)
			(xy 309.877681 -401.163969) (xy 309.836497 -401.12828) (xy 309.800812 -401.087094) (xy 309.771351 -401.041248)
			(xy 309.748714 -400.991677) (xy 309.733361 -400.939389) (xy 309.725606 -400.885448) (xy 308.28795 -400.885448)
			(xy 308.28795 -400.885452) (xy 308.280194 -400.939401) (xy 308.264839 -400.991698) (xy 308.242198 -401.041277)
			(xy 308.212732 -401.087129) (xy 308.177041 -401.128321) (xy 308.135851 -401.164016) (xy 308.090001 -401.193485)
			(xy 308.040424 -401.216129) (xy 307.988129 -401.231488) (xy 307.93418 -401.239248) (xy 307.906928 -401.239736)
			(xy 307.043328 -401.239736) (xy 307.016076 -401.239219) (xy 306.962126 -401.231465) (xy 306.909828 -401.216113)
			(xy 306.860248 -401.193474) (xy 306.814395 -401.164009) (xy 306.773202 -401.128318) (xy 306.737508 -401.087127)
			(xy 306.70804 -401.041276) (xy 306.685397 -400.991698) (xy 306.67004 -400.939402) (xy 306.662283 -400.885452)
			(xy 305.224773 -400.885452) (xy 305.224773 -400.885455) (xy 305.217015 -400.939411) (xy 305.201657 -400.991714)
			(xy 305.179012 -401.041299) (xy 305.149541 -401.087156) (xy 305.113843 -401.128352) (xy 305.072646 -401.164048)
			(xy 305.026788 -401.193518) (xy 304.977203 -401.216162) (xy 304.9249 -401.231518) (xy 304.870943 -401.239274)
			(xy 304.843688 -401.239736) (xy 303.980088 -401.239736) (xy 303.952839 -401.239193) (xy 303.898897 -401.231436)
			(xy 303.846608 -401.216081) (xy 303.797036 -401.19344) (xy 303.75119 -401.163976) (xy 303.710004 -401.128287)
			(xy 303.674317 -401.0871) (xy 303.644854 -401.041254) (xy 303.622215 -400.991681) (xy 303.606862 -400.939391)
			(xy 303.599106 -400.885449) (xy 281.686508 -400.885449) (xy 281.686508 -402.0155) (xy 287.066441 -402.0155)
			(xy 287.070455 -401.951698) (xy 287.082434 -401.888902) (xy 287.102189 -401.828103) (xy 287.129408 -401.77026)
			(xy 287.163662 -401.716283) (xy 287.204411 -401.667026) (xy 287.251013 -401.623264) (xy 287.302731 -401.585688)
			(xy 287.358752 -401.55489) (xy 287.418191 -401.531357) (xy 287.48011 -401.515458) (xy 287.543534 -401.507446)
			(xy 287.575498 -401.506944) (xy 287.575752 -401.506944) (xy 287.607498 -401.507464) (xy 287.670494 -401.515393)
			(xy 287.732014 -401.531096) (xy 287.791102 -401.55433) (xy 287.846842 -401.584733) (xy 287.898367 -401.621834)
			(xy 287.921954 -401.643088) (xy 287.929217 -401.649272) (xy 287.946967 -401.656223) (xy 287.966029 -401.656223)
			(xy 287.983779 -401.649272) (xy 287.991042 -401.643088) (xy 288.014631 -401.621832) (xy 288.06614 -401.5847)
			(xy 288.121874 -401.554276) (xy 288.180965 -401.531035) (xy 288.242492 -401.515338) (xy 288.305495 -401.507431)
			(xy 288.337244 -401.506944) (xy 288.337498 -401.506944) (xy 288.369457 -401.507521) (xy 288.432872 -401.515532)
			(xy 288.494783 -401.531427) (xy 288.554213 -401.554957) (xy 288.610226 -401.58575) (xy 288.661937 -401.623321)
			(xy 288.708532 -401.667076) (xy 288.749276 -401.716326) (xy 288.783525 -401.770295) (xy 288.810741 -401.82813)
			(xy 288.830493 -401.888921) (xy 288.84247 -401.951707) (xy 288.846484 -402.0155) (xy 289.606441 -402.0155)
			(xy 289.610455 -401.951698) (xy 289.622434 -401.888902) (xy 289.642189 -401.828103) (xy 289.669408 -401.77026)
			(xy 289.703662 -401.716283) (xy 289.744411 -401.667026) (xy 289.791013 -401.623264) (xy 289.842731 -401.585688)
			(xy 289.898752 -401.55489) (xy 289.958191 -401.531357) (xy 290.02011 -401.515458) (xy 290.083534 -401.507446)
			(xy 290.115498 -401.506944) (xy 290.115752 -401.506944) (xy 290.147498 -401.507464) (xy 290.210494 -401.515393)
			(xy 290.272014 -401.531096) (xy 290.331102 -401.55433) (xy 290.386842 -401.584733) (xy 290.438367 -401.621834)
			(xy 290.461954 -401.643088) (xy 290.469217 -401.649272) (xy 290.486967 -401.656223) (xy 290.506029 -401.656223)
			(xy 290.523779 -401.649272) (xy 290.531042 -401.643088) (xy 290.554631 -401.621832) (xy 290.60614 -401.5847)
			(xy 290.661874 -401.554276) (xy 290.720965 -401.531035) (xy 290.782492 -401.515338) (xy 290.845495 -401.507431)
			(xy 290.877244 -401.506944) (xy 290.877498 -401.506944) (xy 290.909457 -401.507521) (xy 290.972872 -401.515532)
			(xy 291.034783 -401.531427) (xy 291.094213 -401.554957) (xy 291.150226 -401.58575) (xy 291.201937 -401.623321)
			(xy 291.248532 -401.667076) (xy 291.289276 -401.716326) (xy 291.323525 -401.770295) (xy 291.350741 -401.82813)
			(xy 291.370493 -401.888921) (xy 291.38247 -401.951707) (xy 291.386484 -402.0155) (xy 292.146441 -402.0155)
			(xy 292.150455 -401.951698) (xy 292.162434 -401.888902) (xy 292.182189 -401.828103) (xy 292.209408 -401.77026)
			(xy 292.243662 -401.716283) (xy 292.284411 -401.667026) (xy 292.331013 -401.623264) (xy 292.382731 -401.585688)
			(xy 292.438752 -401.55489) (xy 292.498191 -401.531357) (xy 292.56011 -401.515458) (xy 292.623534 -401.507446)
			(xy 292.655498 -401.506944) (xy 292.655752 -401.506944) (xy 292.687498 -401.507464) (xy 292.750494 -401.515393)
			(xy 292.812014 -401.531096) (xy 292.871102 -401.55433) (xy 292.926842 -401.584733) (xy 292.978367 -401.621834)
			(xy 293.001954 -401.643088) (xy 293.009217 -401.649272) (xy 293.026967 -401.656223) (xy 293.046029 -401.656223)
			(xy 293.063779 -401.649272) (xy 293.071042 -401.643088) (xy 293.094631 -401.621832) (xy 293.14614 -401.5847)
			(xy 293.201874 -401.554276) (xy 293.260965 -401.531035) (xy 293.322492 -401.515338) (xy 293.385495 -401.507431)
			(xy 293.417244 -401.506944) (xy 293.417498 -401.506944) (xy 293.449457 -401.507521) (xy 293.512872 -401.515532)
			(xy 293.574783 -401.531427) (xy 293.634213 -401.554957) (xy 293.690226 -401.58575) (xy 293.741937 -401.623321)
			(xy 293.788532 -401.667076) (xy 293.829276 -401.716326) (xy 293.863525 -401.770295) (xy 293.890741 -401.82813)
			(xy 293.910493 -401.888921) (xy 293.92247 -401.951707) (xy 293.926484 -402.0155) (xy 294.53602 -402.0155)
			(xy 294.540035 -401.951693) (xy 294.552015 -401.888892) (xy 294.571773 -401.828089) (xy 294.598995 -401.770241)
			(xy 294.633253 -401.716261) (xy 294.674007 -401.667001) (xy 294.720613 -401.623237) (xy 294.772338 -401.58566)
			(xy 294.828364 -401.554862) (xy 294.887809 -401.531329) (xy 294.949734 -401.515433) (xy 295.013163 -401.507423)
			(xy 295.04513 -401.506944) (xy 295.045384 -401.506944) (xy 295.077131 -401.507444) (xy 295.140127 -401.515377)
			(xy 295.201647 -401.531084) (xy 295.260736 -401.554322) (xy 295.316476 -401.584728) (xy 295.368 -401.621832)
			(xy 295.391586 -401.643088) (xy 295.398849 -401.649272) (xy 295.416599 -401.656223) (xy 295.435661 -401.656223)
			(xy 295.453411 -401.649272) (xy 295.460674 -401.643088) (xy 295.48425 -401.621817) (xy 295.535761 -401.584686)
			(xy 295.591498 -401.554265) (xy 295.650592 -401.531026) (xy 295.712121 -401.515332) (xy 295.775126 -401.507429)
			(xy 295.806876 -401.506944) (xy 295.80713 -401.506944) (xy 295.839087 -401.507544) (xy 295.902496 -401.515558)
			(xy 295.964401 -401.531455) (xy 296.023825 -401.554986) (xy 296.079832 -401.585779) (xy 296.131538 -401.623348)
			(xy 296.178128 -401.667102) (xy 296.218866 -401.716349) (xy 296.253112 -401.770314) (xy 296.280324 -401.828145)
			(xy 296.300074 -401.888931) (xy 296.312049 -401.951712) (xy 296.316063 -402.0155) (xy 297.07602 -402.0155)
			(xy 297.080035 -401.951693) (xy 297.092015 -401.888892) (xy 297.111773 -401.828089) (xy 297.138995 -401.770241)
			(xy 297.173253 -401.716261) (xy 297.214007 -401.667001) (xy 297.260613 -401.623237) (xy 297.312338 -401.58566)
			(xy 297.368364 -401.554862) (xy 297.427809 -401.531329) (xy 297.489734 -401.515433) (xy 297.553163 -401.507423)
			(xy 297.58513 -401.506944) (xy 297.585384 -401.506944) (xy 297.617131 -401.507444) (xy 297.680127 -401.515377)
			(xy 297.741647 -401.531084) (xy 297.800736 -401.554322) (xy 297.856476 -401.584728) (xy 297.908 -401.621832)
			(xy 297.931586 -401.643088) (xy 297.938849 -401.649272) (xy 297.956599 -401.656223) (xy 297.975661 -401.656223)
			(xy 297.993411 -401.649272) (xy 298.000674 -401.643088) (xy 298.02425 -401.621817) (xy 298.075761 -401.584686)
			(xy 298.131498 -401.554265) (xy 298.190592 -401.531026) (xy 298.252121 -401.515332) (xy 298.315126 -401.507429)
			(xy 298.346876 -401.506944) (xy 298.34713 -401.506944) (xy 298.379087 -401.507544) (xy 298.442496 -401.515558)
			(xy 298.504401 -401.531455) (xy 298.563825 -401.554986) (xy 298.619832 -401.585779) (xy 298.671538 -401.623348)
			(xy 298.718128 -401.667102) (xy 298.758866 -401.716349) (xy 298.793112 -401.770314) (xy 298.820324 -401.828145)
			(xy 298.840074 -401.888931) (xy 298.852049 -401.951712) (xy 298.856063 -402.0155) (xy 298.852049 -402.079288)
			(xy 298.840074 -402.142069) (xy 298.820324 -402.202855) (xy 298.793112 -402.260686) (xy 298.758866 -402.314651)
			(xy 298.718128 -402.363898) (xy 298.671538 -402.407652) (xy 298.619832 -402.445221) (xy 298.563825 -402.476014)
			(xy 298.504401 -402.499545) (xy 298.442496 -402.515442) (xy 298.379087 -402.523456) (xy 298.34713 -402.52396)
			(xy 298.346876 -402.52396) (xy 298.315131 -402.523422) (xy 298.252136 -402.515497) (xy 298.190616 -402.499797)
			(xy 298.131527 -402.476566) (xy 298.075787 -402.446166) (xy 298.024261 -402.409069) (xy 298.000674 -402.387816)
			(xy 297.993411 -402.381632) (xy 297.975661 -402.374681) (xy 297.956599 -402.374681) (xy 297.938849 -402.381632)
			(xy 297.931586 -402.387816) (xy 297.908028 -402.409107) (xy 297.856512 -402.446235) (xy 297.800771 -402.476654)
			(xy 297.741674 -402.499889) (xy 297.680142 -402.515579) (xy 297.617135 -402.523478) (xy 297.585384 -402.52396)
			(xy 297.58513 -402.52396) (xy 297.553163 -402.523577) (xy 297.489734 -402.515567) (xy 297.427809 -402.499671)
			(xy 297.368364 -402.476138) (xy 297.312338 -402.44534) (xy 297.260613 -402.407763) (xy 297.214007 -402.363999)
			(xy 297.173253 -402.314739) (xy 297.138995 -402.260759) (xy 297.111773 -402.202911) (xy 297.092015 -402.142108)
			(xy 297.080035 -402.079307) (xy 297.07602 -402.0155) (xy 296.316063 -402.0155) (xy 296.312049 -402.079288)
			(xy 296.300074 -402.142069) (xy 296.280324 -402.202855) (xy 296.253112 -402.260686) (xy 296.218866 -402.314651)
			(xy 296.178128 -402.363898) (xy 296.131538 -402.407652) (xy 296.079832 -402.445221) (xy 296.023825 -402.476014)
			(xy 295.964401 -402.499545) (xy 295.902496 -402.515442) (xy 295.839087 -402.523456) (xy 295.80713 -402.52396)
			(xy 295.806876 -402.52396) (xy 295.775131 -402.523422) (xy 295.712136 -402.515497) (xy 295.650616 -402.499797)
			(xy 295.591527 -402.476566) (xy 295.535787 -402.446166) (xy 295.484261 -402.409069) (xy 295.460674 -402.387816)
			(xy 295.453411 -402.381632) (xy 295.435661 -402.374681) (xy 295.416599 -402.374681) (xy 295.398849 -402.381632)
			(xy 295.391586 -402.387816) (xy 295.368028 -402.409107) (xy 295.316512 -402.446235) (xy 295.260771 -402.476654)
			(xy 295.201674 -402.499889) (xy 295.140142 -402.515579) (xy 295.077135 -402.523478) (xy 295.045384 -402.52396)
			(xy 295.04513 -402.52396) (xy 295.013163 -402.523577) (xy 294.949734 -402.515567) (xy 294.887809 -402.499671)
			(xy 294.828364 -402.476138) (xy 294.772338 -402.44534) (xy 294.720613 -402.407763) (xy 294.674007 -402.363999)
			(xy 294.633253 -402.314739) (xy 294.598995 -402.260759) (xy 294.571773 -402.202911) (xy 294.552015 -402.142108)
			(xy 294.540035 -402.079307) (xy 294.53602 -402.0155) (xy 293.926484 -402.0155) (xy 293.92247 -402.079293)
			(xy 293.910493 -402.142079) (xy 293.890741 -402.20287) (xy 293.863525 -402.260705) (xy 293.829276 -402.314674)
			(xy 293.788532 -402.363924) (xy 293.741937 -402.407679) (xy 293.690226 -402.44525) (xy 293.634213 -402.476043)
			(xy 293.574783 -402.499573) (xy 293.512872 -402.515468) (xy 293.449457 -402.523479) (xy 293.417498 -402.52396)
			(xy 293.417244 -402.52396) (xy 293.385498 -402.523442) (xy 293.322502 -402.515512) (xy 293.260982 -402.499809)
			(xy 293.201894 -402.476575) (xy 293.146154 -402.446171) (xy 293.094629 -402.40907) (xy 293.071042 -402.387816)
			(xy 293.063779 -402.381632) (xy 293.046029 -402.374681) (xy 293.026967 -402.374681) (xy 293.009217 -402.381632)
			(xy 293.001954 -402.387816) (xy 292.978367 -402.409074) (xy 292.926858 -402.446206) (xy 292.871123 -402.47663)
			(xy 292.812032 -402.499871) (xy 292.750504 -402.515567) (xy 292.687501 -402.523474) (xy 292.655752 -402.52396)
			(xy 292.655498 -402.52396) (xy 292.623534 -402.523554) (xy 292.56011 -402.515542) (xy 292.498191 -402.499643)
			(xy 292.438752 -402.47611) (xy 292.382731 -402.445312) (xy 292.331013 -402.407736) (xy 292.284411 -402.363974)
			(xy 292.243662 -402.314717) (xy 292.209408 -402.26074) (xy 292.182189 -402.202897) (xy 292.162434 -402.142098)
			(xy 292.150455 -402.079302) (xy 292.146441 -402.0155) (xy 291.386484 -402.0155) (xy 291.38247 -402.079293)
			(xy 291.370493 -402.142079) (xy 291.350741 -402.20287) (xy 291.323525 -402.260705) (xy 291.289276 -402.314674)
			(xy 291.248532 -402.363924) (xy 291.201937 -402.407679) (xy 291.150226 -402.44525) (xy 291.094213 -402.476043)
			(xy 291.034783 -402.499573) (xy 290.972872 -402.515468) (xy 290.909457 -402.523479) (xy 290.877498 -402.52396)
			(xy 290.877244 -402.52396) (xy 290.845498 -402.523442) (xy 290.782502 -402.515512) (xy 290.720982 -402.499809)
			(xy 290.661894 -402.476575) (xy 290.606154 -402.446171) (xy 290.554629 -402.40907) (xy 290.531042 -402.387816)
			(xy 290.523779 -402.381632) (xy 290.506029 -402.374681) (xy 290.486967 -402.374681) (xy 290.469217 -402.381632)
			(xy 290.461954 -402.387816) (xy 290.438367 -402.409074) (xy 290.386858 -402.446206) (xy 290.331123 -402.47663)
			(xy 290.272032 -402.499871) (xy 290.210504 -402.515567) (xy 290.147501 -402.523474) (xy 290.115752 -402.52396)
			(xy 290.115498 -402.52396) (xy 290.083534 -402.523554) (xy 290.02011 -402.515542) (xy 289.958191 -402.499643)
			(xy 289.898752 -402.47611) (xy 289.842731 -402.445312) (xy 289.791013 -402.407736) (xy 289.744411 -402.363974)
			(xy 289.703662 -402.314717) (xy 289.669408 -402.26074) (xy 289.642189 -402.202897) (xy 289.622434 -402.142098)
			(xy 289.610455 -402.079302) (xy 289.606441 -402.0155) (xy 288.846484 -402.0155) (xy 288.84247 -402.079293)
			(xy 288.830493 -402.142079) (xy 288.810741 -402.20287) (xy 288.783525 -402.260705) (xy 288.749276 -402.314674)
			(xy 288.708532 -402.363924) (xy 288.661937 -402.407679) (xy 288.610226 -402.44525) (xy 288.554213 -402.476043)
			(xy 288.494783 -402.499573) (xy 288.432872 -402.515468) (xy 288.369457 -402.523479) (xy 288.337498 -402.52396)
			(xy 288.337244 -402.52396) (xy 288.305498 -402.523442) (xy 288.242502 -402.515512) (xy 288.180982 -402.499809)
			(xy 288.121894 -402.476575) (xy 288.066154 -402.446171) (xy 288.014629 -402.40907) (xy 287.991042 -402.387816)
			(xy 287.983779 -402.381632) (xy 287.966029 -402.374681) (xy 287.946967 -402.374681) (xy 287.929217 -402.381632)
			(xy 287.921954 -402.387816) (xy 287.898367 -402.409074) (xy 287.846858 -402.446206) (xy 287.791123 -402.47663)
			(xy 287.732032 -402.499871) (xy 287.670504 -402.515567) (xy 287.607501 -402.523474) (xy 287.575752 -402.52396)
			(xy 287.575498 -402.52396) (xy 287.543534 -402.523554) (xy 287.48011 -402.515542) (xy 287.418191 -402.499643)
			(xy 287.358752 -402.47611) (xy 287.302731 -402.445312) (xy 287.251013 -402.407736) (xy 287.204411 -402.363974)
			(xy 287.163662 -402.314717) (xy 287.129408 -402.26074) (xy 287.102189 -402.202897) (xy 287.082434 -402.142098)
			(xy 287.070455 -402.079302) (xy 287.066441 -402.0155) (xy 281.686508 -402.0155) (xy 281.686508 -404.0475)
			(xy 287.066441 -404.0475) (xy 287.070455 -403.983698) (xy 287.082434 -403.920902) (xy 287.102189 -403.860103)
			(xy 287.129408 -403.80226) (xy 287.163662 -403.748283) (xy 287.204411 -403.699026) (xy 287.251013 -403.655264)
			(xy 287.302731 -403.617688) (xy 287.358752 -403.58689) (xy 287.418191 -403.563357) (xy 287.48011 -403.547458)
			(xy 287.543534 -403.539446) (xy 287.575498 -403.538944) (xy 287.575752 -403.538944) (xy 287.607498 -403.539464)
			(xy 287.670494 -403.547393) (xy 287.732014 -403.563096) (xy 287.791102 -403.58633) (xy 287.846842 -403.616733)
			(xy 287.898367 -403.653834) (xy 287.921954 -403.675088) (xy 287.929217 -403.681272) (xy 287.946967 -403.688223)
			(xy 287.966029 -403.688223) (xy 287.983779 -403.681272) (xy 287.991042 -403.675088) (xy 288.014631 -403.653832)
			(xy 288.06614 -403.6167) (xy 288.121874 -403.586276) (xy 288.180965 -403.563035) (xy 288.242492 -403.547338)
			(xy 288.305495 -403.539431) (xy 288.337244 -403.538944) (xy 288.337498 -403.538944) (xy 288.369457 -403.539521)
			(xy 288.432872 -403.547532) (xy 288.494783 -403.563427) (xy 288.554213 -403.586957) (xy 288.610226 -403.61775)
			(xy 288.661937 -403.655321) (xy 288.708532 -403.699076) (xy 288.749276 -403.748326) (xy 288.783525 -403.802295)
			(xy 288.810741 -403.86013) (xy 288.830493 -403.920921) (xy 288.84247 -403.983707) (xy 288.846484 -404.0475)
			(xy 289.606441 -404.0475) (xy 289.610455 -403.983698) (xy 289.622434 -403.920902) (xy 289.642189 -403.860103)
			(xy 289.669408 -403.80226) (xy 289.703662 -403.748283) (xy 289.744411 -403.699026) (xy 289.791013 -403.655264)
			(xy 289.842731 -403.617688) (xy 289.898752 -403.58689) (xy 289.958191 -403.563357) (xy 290.02011 -403.547458)
			(xy 290.083534 -403.539446) (xy 290.115498 -403.538944) (xy 290.115752 -403.538944) (xy 290.147498 -403.539464)
			(xy 290.210494 -403.547393) (xy 290.272014 -403.563096) (xy 290.331102 -403.58633) (xy 290.386842 -403.616733)
			(xy 290.438367 -403.653834) (xy 290.461954 -403.675088) (xy 290.469217 -403.681272) (xy 290.486967 -403.688223)
			(xy 290.506029 -403.688223) (xy 290.523779 -403.681272) (xy 290.531042 -403.675088) (xy 290.554631 -403.653832)
			(xy 290.60614 -403.6167) (xy 290.661874 -403.586276) (xy 290.720965 -403.563035) (xy 290.782492 -403.547338)
			(xy 290.845495 -403.539431) (xy 290.877244 -403.538944) (xy 290.877498 -403.538944) (xy 290.909457 -403.539521)
			(xy 290.972872 -403.547532) (xy 291.034783 -403.563427) (xy 291.094213 -403.586957) (xy 291.150226 -403.61775)
			(xy 291.201937 -403.655321) (xy 291.248532 -403.699076) (xy 291.289276 -403.748326) (xy 291.323525 -403.802295)
			(xy 291.350741 -403.86013) (xy 291.370493 -403.920921) (xy 291.38247 -403.983707) (xy 291.386484 -404.0475)
			(xy 292.146441 -404.0475) (xy 292.150455 -403.983698) (xy 292.162434 -403.920902) (xy 292.182189 -403.860103)
			(xy 292.209408 -403.80226) (xy 292.243662 -403.748283) (xy 292.284411 -403.699026) (xy 292.331013 -403.655264)
			(xy 292.382731 -403.617688) (xy 292.438752 -403.58689) (xy 292.498191 -403.563357) (xy 292.56011 -403.547458)
			(xy 292.623534 -403.539446) (xy 292.655498 -403.538944) (xy 292.655752 -403.538944) (xy 292.687498 -403.539464)
			(xy 292.750494 -403.547393) (xy 292.812014 -403.563096) (xy 292.871102 -403.58633) (xy 292.926842 -403.616733)
			(xy 292.978367 -403.653834) (xy 293.001954 -403.675088) (xy 293.009217 -403.681272) (xy 293.026967 -403.688223)
			(xy 293.046029 -403.688223) (xy 293.063779 -403.681272) (xy 293.071042 -403.675088) (xy 293.094631 -403.653832)
			(xy 293.14614 -403.6167) (xy 293.201874 -403.586276) (xy 293.260965 -403.563035) (xy 293.322492 -403.547338)
			(xy 293.385495 -403.539431) (xy 293.417244 -403.538944) (xy 293.417498 -403.538944) (xy 293.449457 -403.539521)
			(xy 293.512872 -403.547532) (xy 293.574783 -403.563427) (xy 293.634213 -403.586957) (xy 293.690226 -403.61775)
			(xy 293.741937 -403.655321) (xy 293.788532 -403.699076) (xy 293.829276 -403.748326) (xy 293.863525 -403.802295)
			(xy 293.890741 -403.86013) (xy 293.910493 -403.920921) (xy 293.92247 -403.983707) (xy 293.926484 -404.0475)
			(xy 294.53602 -404.0475) (xy 294.540035 -403.983693) (xy 294.552015 -403.920892) (xy 294.571773 -403.860089)
			(xy 294.598995 -403.802241) (xy 294.633253 -403.748261) (xy 294.674007 -403.699001) (xy 294.720613 -403.655237)
			(xy 294.772338 -403.61766) (xy 294.828364 -403.586862) (xy 294.887809 -403.563329) (xy 294.949734 -403.547433)
			(xy 295.013163 -403.539423) (xy 295.04513 -403.538944) (xy 295.045384 -403.538944) (xy 295.077131 -403.539444)
			(xy 295.140127 -403.547377) (xy 295.201647 -403.563084) (xy 295.260736 -403.586322) (xy 295.316476 -403.616728)
			(xy 295.368 -403.653832) (xy 295.391586 -403.675088) (xy 295.398849 -403.681272) (xy 295.416599 -403.688223)
			(xy 295.435661 -403.688223) (xy 295.453411 -403.681272) (xy 295.460674 -403.675088) (xy 295.48425 -403.653817)
			(xy 295.535761 -403.616686) (xy 295.591498 -403.586265) (xy 295.650592 -403.563026) (xy 295.712121 -403.547332)
			(xy 295.775126 -403.539429) (xy 295.806876 -403.538944) (xy 295.80713 -403.538944) (xy 295.839087 -403.539544)
			(xy 295.902496 -403.547558) (xy 295.964401 -403.563455) (xy 296.023825 -403.586986) (xy 296.079832 -403.617779)
			(xy 296.131538 -403.655348) (xy 296.178128 -403.699102) (xy 296.218866 -403.748349) (xy 296.253112 -403.802314)
			(xy 296.280324 -403.860145) (xy 296.300074 -403.920931) (xy 296.312049 -403.983712) (xy 296.316063 -404.0475)
			(xy 297.07602 -404.0475) (xy 297.080035 -403.983693) (xy 297.092015 -403.920892) (xy 297.111773 -403.860089)
			(xy 297.138995 -403.802241) (xy 297.173253 -403.748261) (xy 297.214007 -403.699001) (xy 297.260613 -403.655237)
			(xy 297.312338 -403.61766) (xy 297.368364 -403.586862) (xy 297.427809 -403.563329) (xy 297.489734 -403.547433)
			(xy 297.553163 -403.539423) (xy 297.58513 -403.538944) (xy 297.585384 -403.538944) (xy 297.617131 -403.539444)
			(xy 297.680127 -403.547377) (xy 297.741647 -403.563084) (xy 297.800736 -403.586322) (xy 297.856476 -403.616728)
			(xy 297.908 -403.653832) (xy 297.931586 -403.675088) (xy 297.938849 -403.681272) (xy 297.956599 -403.688223)
			(xy 297.975661 -403.688223) (xy 297.993411 -403.681272) (xy 298.000674 -403.675088) (xy 298.02425 -403.653817)
			(xy 298.075761 -403.616686) (xy 298.131498 -403.586265) (xy 298.190592 -403.563026) (xy 298.252121 -403.547332)
			(xy 298.315126 -403.539429) (xy 298.346876 -403.538944) (xy 298.34713 -403.538944) (xy 298.379087 -403.539544)
			(xy 298.442496 -403.547558) (xy 298.504401 -403.563455) (xy 298.563825 -403.586986) (xy 298.619832 -403.617779)
			(xy 298.671538 -403.655348) (xy 298.718128 -403.699102) (xy 298.758866 -403.748349) (xy 298.793112 -403.802314)
			(xy 298.820324 -403.860145) (xy 298.836897 -403.911152) (xy 303.599054 -403.911152) (xy 303.599054 -403.856648)
			(xy 303.60681 -403.802698) (xy 303.622166 -403.7504) (xy 303.644808 -403.700821) (xy 303.674275 -403.654968)
			(xy 303.709967 -403.613776) (xy 303.751159 -403.578082) (xy 303.79701 -403.548613) (xy 303.846589 -403.52597)
			(xy 303.898886 -403.510613) (xy 303.952836 -403.502855) (xy 303.980088 -403.502368) (xy 304.843688 -403.502368)
			(xy 304.87094 -403.502878) (xy 304.924889 -403.510634) (xy 304.977185 -403.525988) (xy 305.026763 -403.548628)
			(xy 305.072615 -403.578094) (xy 305.113806 -403.613785) (xy 305.149499 -403.654976) (xy 305.178966 -403.700826)
			(xy 305.201608 -403.750404) (xy 305.216964 -403.8027) (xy 305.224721 -403.856648) (xy 305.224721 -403.911152)
			(xy 305.22472 -403.911156) (xy 306.662231 -403.911156) (xy 306.662231 -403.856644) (xy 306.669989 -403.802687)
			(xy 306.685348 -403.750384) (xy 306.707994 -403.700799) (xy 306.737466 -403.654941) (xy 306.773165 -403.613745)
			(xy 306.814364 -403.578049) (xy 306.860223 -403.54858) (xy 306.90981 -403.525938) (xy 306.962115 -403.510583)
			(xy 307.016072 -403.502829) (xy 307.043328 -403.502368) (xy 307.906928 -403.502368) (xy 307.934176 -403.502904)
			(xy 307.988117 -403.510663) (xy 308.040405 -403.52602) (xy 308.089976 -403.548661) (xy 308.13582 -403.578126)
			(xy 308.177004 -403.613816) (xy 308.21269 -403.655002) (xy 308.242152 -403.700849) (xy 308.26479 -403.750421)
			(xy 308.280143 -403.80271) (xy 308.287898 -403.856652) (xy 308.287898 -403.911148) (xy 308.287897 -403.911152)
			(xy 309.725554 -403.911152) (xy 309.725554 -403.856648) (xy 309.73331 -403.8027) (xy 309.748664 -403.750405)
			(xy 309.771305 -403.700826) (xy 309.80077 -403.654975) (xy 309.83646 -403.613783) (xy 309.877649 -403.578089)
			(xy 309.923498 -403.54862) (xy 309.973075 -403.525976) (xy 310.025369 -403.510617) (xy 310.079317 -403.502856)
			(xy 310.106568 -403.502368) (xy 310.970168 -403.502368) (xy 310.997421 -403.502877) (xy 311.051372 -403.51063)
			(xy 311.10367 -403.525982) (xy 311.153251 -403.548621) (xy 311.199105 -403.578087) (xy 311.240299 -403.613778)
			(xy 311.275994 -403.654969) (xy 311.305463 -403.700821) (xy 311.328107 -403.7504) (xy 311.343463 -403.802697)
			(xy 311.351221 -403.856647) (xy 311.351221 -403.911153) (xy 311.351221 -403.911155) (xy 312.788731 -403.911155)
			(xy 312.788731 -403.856645) (xy 312.796489 -403.80269) (xy 312.811846 -403.750388) (xy 312.834491 -403.700804)
			(xy 312.863961 -403.654948) (xy 312.899658 -403.613752) (xy 312.940854 -403.578056) (xy 312.986711 -403.548587)
			(xy 313.036296 -403.525943) (xy 313.088598 -403.510587) (xy 313.142553 -403.50283) (xy 313.169808 -403.502368)
			(xy 314.033408 -403.502368) (xy 314.060657 -403.502903) (xy 314.114601 -403.51066) (xy 314.166891 -403.526015)
			(xy 314.216464 -403.548655) (xy 314.26231 -403.578119) (xy 314.303497 -403.613809) (xy 314.339186 -403.654996)
			(xy 314.368649 -403.700843) (xy 314.391288 -403.750417) (xy 314.406642 -403.802707) (xy 314.414398 -403.856651)
			(xy 314.414398 -403.911149) (xy 314.414397 -403.911157) (xy 315.851931 -403.911157) (xy 315.851931 -403.856643)
			(xy 315.85969 -403.802685) (xy 315.875049 -403.75038) (xy 315.897697 -403.700793) (xy 315.927171 -403.654935)
			(xy 315.962872 -403.613738) (xy 316.004073 -403.578042) (xy 316.049935 -403.548574) (xy 316.099525 -403.525932)
			(xy 316.151832 -403.51058) (xy 316.205791 -403.502828) (xy 316.233048 -403.502368) (xy 317.096648 -403.502368)
			(xy 317.123895 -403.502905) (xy 317.177834 -403.510667) (xy 317.23012 -403.526025) (xy 317.279688 -403.548668)
			(xy 317.325529 -403.578133) (xy 317.366711 -403.613823) (xy 317.402395 -403.655009) (xy 317.431855 -403.700854)
			(xy 317.454491 -403.750425) (xy 317.469843 -403.802713) (xy 317.477598 -403.856653) (xy 317.477598 -403.911147)
			(xy 317.477597 -403.911152) (xy 318.915254 -403.911152) (xy 318.915254 -403.856648) (xy 318.92301 -403.802698)
			(xy 318.938366 -403.7504) (xy 318.961008 -403.700821) (xy 318.990475 -403.654968) (xy 319.026167 -403.613776)
			(xy 319.067359 -403.578082) (xy 319.11321 -403.548613) (xy 319.162789 -403.52597) (xy 319.215086 -403.510613)
			(xy 319.269036 -403.502855) (xy 319.296288 -403.502368) (xy 320.159888 -403.502368) (xy 320.18714 -403.502878)
			(xy 320.241089 -403.510634) (xy 320.293385 -403.525988) (xy 320.342963 -403.548628) (xy 320.388815 -403.578094)
			(xy 320.430006 -403.613785) (xy 320.465699 -403.654976) (xy 320.495166 -403.700826) (xy 320.517808 -403.750404)
			(xy 320.533164 -403.8027) (xy 320.540921 -403.856648) (xy 320.540921 -403.911152) (xy 320.54092 -403.911156)
			(xy 321.978431 -403.911156) (xy 321.978431 -403.856644) (xy 321.986189 -403.802687) (xy 322.001548 -403.750384)
			(xy 322.024194 -403.700799) (xy 322.053666 -403.654941) (xy 322.089365 -403.613745) (xy 322.130564 -403.578049)
			(xy 322.176423 -403.54858) (xy 322.22601 -403.525938) (xy 322.278315 -403.510583) (xy 322.332272 -403.502829)
			(xy 322.359528 -403.502368) (xy 323.223128 -403.502368) (xy 323.250376 -403.502904) (xy 323.304317 -403.510663)
			(xy 323.356605 -403.52602) (xy 323.406176 -403.548661) (xy 323.45202 -403.578126) (xy 323.493204 -403.613816)
			(xy 323.52889 -403.655002) (xy 323.558352 -403.700849) (xy 323.58099 -403.750421) (xy 323.596343 -403.80271)
			(xy 323.604098 -403.856652) (xy 323.604098 -403.911148) (xy 323.604097 -403.911152) (xy 325.041754 -403.911152)
			(xy 325.041754 -403.856648) (xy 325.04951 -403.8027) (xy 325.064864 -403.750405) (xy 325.087505 -403.700826)
			(xy 325.11697 -403.654975) (xy 325.15266 -403.613783) (xy 325.193849 -403.578089) (xy 325.239698 -403.54862)
			(xy 325.289275 -403.525976) (xy 325.341569 -403.510617) (xy 325.395517 -403.502856) (xy 325.422768 -403.502368)
			(xy 326.286368 -403.502368) (xy 326.313621 -403.502877) (xy 326.367572 -403.51063) (xy 326.41987 -403.525982)
			(xy 326.469451 -403.548621) (xy 326.515305 -403.578087) (xy 326.556499 -403.613778) (xy 326.592194 -403.654969)
			(xy 326.621663 -403.700821) (xy 326.644307 -403.7504) (xy 326.659663 -403.802697) (xy 326.667421 -403.856647)
			(xy 326.667421 -403.911153) (xy 326.667421 -403.911155) (xy 328.104931 -403.911155) (xy 328.104931 -403.856645)
			(xy 328.112689 -403.80269) (xy 328.128046 -403.750388) (xy 328.150691 -403.700804) (xy 328.180161 -403.654948)
			(xy 328.215858 -403.613752) (xy 328.257054 -403.578056) (xy 328.302911 -403.548587) (xy 328.352496 -403.525943)
			(xy 328.404798 -403.510587) (xy 328.458753 -403.50283) (xy 328.486008 -403.502368) (xy 329.349608 -403.502368)
			(xy 329.376857 -403.502903) (xy 329.430801 -403.51066) (xy 329.483091 -403.526015) (xy 329.532664 -403.548655)
			(xy 329.57851 -403.578119) (xy 329.619697 -403.613809) (xy 329.655386 -403.654996) (xy 329.684849 -403.700843)
			(xy 329.707488 -403.750417) (xy 329.722842 -403.802707) (xy 329.730598 -403.856651) (xy 329.730598 -403.911149)
			(xy 329.730597 -403.911157) (xy 331.168131 -403.911157) (xy 331.168131 -403.856643) (xy 331.17589 -403.802685)
			(xy 331.191249 -403.75038) (xy 331.213897 -403.700793) (xy 331.243371 -403.654935) (xy 331.279072 -403.613738)
			(xy 331.320273 -403.578042) (xy 331.366135 -403.548574) (xy 331.415725 -403.525932) (xy 331.468032 -403.51058)
			(xy 331.521991 -403.502828) (xy 331.549248 -403.502368) (xy 332.412848 -403.502368) (xy 332.440095 -403.502905)
			(xy 332.494034 -403.510667) (xy 332.54632 -403.526025) (xy 332.595888 -403.548668) (xy 332.641729 -403.578133)
			(xy 332.682911 -403.613823) (xy 332.718595 -403.655009) (xy 332.748055 -403.700854) (xy 332.770691 -403.750425)
			(xy 332.786043 -403.802713) (xy 332.793798 -403.856653) (xy 332.793798 -403.911147) (xy 332.793797 -403.911152)
			(xy 334.231454 -403.911152) (xy 334.231454 -403.856648) (xy 334.23921 -403.802698) (xy 334.254566 -403.7504)
			(xy 334.277208 -403.700821) (xy 334.306675 -403.654968) (xy 334.342367 -403.613776) (xy 334.383559 -403.578082)
			(xy 334.42941 -403.548613) (xy 334.478989 -403.52597) (xy 334.531286 -403.510613) (xy 334.585236 -403.502855)
			(xy 334.612488 -403.502368) (xy 335.476088 -403.502368) (xy 335.50334 -403.502878) (xy 335.557289 -403.510634)
			(xy 335.609585 -403.525988) (xy 335.659163 -403.548628) (xy 335.705015 -403.578094) (xy 335.746206 -403.613785)
			(xy 335.781899 -403.654976) (xy 335.811366 -403.700826) (xy 335.834008 -403.750404) (xy 335.849364 -403.8027)
			(xy 335.857121 -403.856648) (xy 335.857121 -403.911152) (xy 335.85712 -403.911156) (xy 337.294631 -403.911156)
			(xy 337.294631 -403.856644) (xy 337.302389 -403.802687) (xy 337.317748 -403.750384) (xy 337.340394 -403.700799)
			(xy 337.369866 -403.654941) (xy 337.405565 -403.613745) (xy 337.446764 -403.578049) (xy 337.492623 -403.54858)
			(xy 337.54221 -403.525938) (xy 337.594515 -403.510583) (xy 337.648472 -403.502829) (xy 337.675728 -403.502368)
			(xy 338.539328 -403.502368) (xy 338.566576 -403.502904) (xy 338.620517 -403.510663) (xy 338.672805 -403.52602)
			(xy 338.722376 -403.548661) (xy 338.76822 -403.578126) (xy 338.809404 -403.613816) (xy 338.84509 -403.655002)
			(xy 338.874552 -403.700849) (xy 338.89719 -403.750421) (xy 338.912543 -403.80271) (xy 338.920298 -403.856652)
			(xy 338.920298 -403.911148) (xy 338.920297 -403.911152) (xy 340.357954 -403.911152) (xy 340.357954 -403.856648)
			(xy 340.36571 -403.8027) (xy 340.381064 -403.750405) (xy 340.403705 -403.700826) (xy 340.43317 -403.654975)
			(xy 340.46886 -403.613783) (xy 340.510049 -403.578089) (xy 340.555898 -403.54862) (xy 340.605475 -403.525976)
			(xy 340.657769 -403.510617) (xy 340.711717 -403.502856) (xy 340.738968 -403.502368) (xy 341.602568 -403.502368)
			(xy 341.629821 -403.502877) (xy 341.683772 -403.51063) (xy 341.73607 -403.525982) (xy 341.785651 -403.548621)
			(xy 341.831505 -403.578087) (xy 341.872699 -403.613778) (xy 341.908394 -403.654969) (xy 341.937863 -403.700821)
			(xy 341.960507 -403.7504) (xy 341.975863 -403.802697) (xy 341.983621 -403.856647) (xy 341.983621 -403.911153)
			(xy 341.983621 -403.911155) (xy 343.421131 -403.911155) (xy 343.421131 -403.856645) (xy 343.428889 -403.80269)
			(xy 343.444246 -403.750388) (xy 343.466891 -403.700804) (xy 343.496361 -403.654948) (xy 343.532058 -403.613752)
			(xy 343.573254 -403.578056) (xy 343.619111 -403.548587) (xy 343.668696 -403.525943) (xy 343.720998 -403.510587)
			(xy 343.774953 -403.50283) (xy 343.802208 -403.502368) (xy 344.665808 -403.502368) (xy 344.693057 -403.502903)
			(xy 344.747001 -403.51066) (xy 344.799291 -403.526015) (xy 344.848864 -403.548655) (xy 344.89471 -403.578119)
			(xy 344.935897 -403.613809) (xy 344.971586 -403.654996) (xy 345.001049 -403.700843) (xy 345.023688 -403.750417)
			(xy 345.039042 -403.802707) (xy 345.046798 -403.856651) (xy 345.046798 -403.911149) (xy 345.046797 -403.911157)
			(xy 346.484331 -403.911157) (xy 346.484331 -403.856643) (xy 346.49209 -403.802685) (xy 346.507449 -403.75038)
			(xy 346.530097 -403.700793) (xy 346.559571 -403.654935) (xy 346.595272 -403.613738) (xy 346.636473 -403.578042)
			(xy 346.682335 -403.548574) (xy 346.731925 -403.525932) (xy 346.784232 -403.51058) (xy 346.838191 -403.502828)
			(xy 346.865448 -403.502368) (xy 347.729048 -403.502368) (xy 347.756295 -403.502905) (xy 347.810234 -403.510667)
			(xy 347.86252 -403.526025) (xy 347.912088 -403.548668) (xy 347.957929 -403.578133) (xy 347.999111 -403.613823)
			(xy 348.034795 -403.655009) (xy 348.064255 -403.700854) (xy 348.086891 -403.750425) (xy 348.102243 -403.802713)
			(xy 348.109998 -403.856653) (xy 348.109998 -403.911147) (xy 348.109997 -403.911152) (xy 349.547654 -403.911152)
			(xy 349.547654 -403.856648) (xy 349.55541 -403.802698) (xy 349.570766 -403.7504) (xy 349.593408 -403.700821)
			(xy 349.622875 -403.654968) (xy 349.658567 -403.613776) (xy 349.699759 -403.578082) (xy 349.74561 -403.548613)
			(xy 349.795189 -403.52597) (xy 349.847486 -403.510613) (xy 349.901436 -403.502855) (xy 349.928688 -403.502368)
			(xy 350.792288 -403.502368) (xy 350.81954 -403.502878) (xy 350.873489 -403.510634) (xy 350.925785 -403.525988)
			(xy 350.975363 -403.548628) (xy 351.021215 -403.578094) (xy 351.062406 -403.613785) (xy 351.098099 -403.654976)
			(xy 351.127566 -403.700826) (xy 351.150208 -403.750404) (xy 351.165564 -403.8027) (xy 351.173321 -403.856648)
			(xy 351.173321 -403.911152) (xy 351.17332 -403.911156) (xy 371.041831 -403.911156) (xy 371.041831 -403.856644)
			(xy 371.049589 -403.802687) (xy 371.064948 -403.750383) (xy 371.087594 -403.700798) (xy 371.117067 -403.654941)
			(xy 371.152766 -403.613745) (xy 371.193965 -403.578049) (xy 371.239824 -403.54858) (xy 371.289412 -403.525937)
			(xy 371.341716 -403.510583) (xy 371.395674 -403.502829) (xy 371.42293 -403.502368) (xy 372.28653 -403.502368)
			(xy 372.313778 -403.502904) (xy 372.367719 -403.510664) (xy 372.420007 -403.52602) (xy 372.469577 -403.548662)
			(xy 372.515421 -403.578127) (xy 372.556605 -403.613816) (xy 372.592291 -403.655003) (xy 372.621753 -403.700849)
			(xy 372.64439 -403.750421) (xy 372.659743 -403.80271) (xy 372.667498 -403.856652) (xy 372.667498 -403.911148)
			(xy 372.667497 -403.911152) (xy 374.105154 -403.911152) (xy 374.105154 -403.856648) (xy 374.11291 -403.8027)
			(xy 374.128265 -403.750404) (xy 374.150905 -403.700826) (xy 374.18037 -403.654974) (xy 374.216061 -403.613782)
			(xy 374.25725 -403.578088) (xy 374.3031 -403.548619) (xy 374.352676 -403.525975) (xy 374.404971 -403.510616)
			(xy 374.458918 -403.502856) (xy 374.48617 -403.502368) (xy 375.34977 -403.502368) (xy 375.377023 -403.502877)
			(xy 375.430973 -403.51063) (xy 375.483271 -403.525983) (xy 375.532852 -403.548622) (xy 375.578706 -403.578087)
			(xy 375.6199 -403.613779) (xy 375.655595 -403.65497) (xy 375.685064 -403.700821) (xy 375.707707 -403.7504)
			(xy 375.723063 -403.802697) (xy 375.730821 -403.856647) (xy 375.730821 -403.911153) (xy 375.730821 -403.911155)
			(xy 377.168331 -403.911155) (xy 377.168331 -403.856645) (xy 377.176089 -403.80269) (xy 377.191446 -403.750388)
			(xy 377.214091 -403.700804) (xy 377.243562 -403.654947) (xy 377.279259 -403.613752) (xy 377.320455 -403.578056)
			(xy 377.366313 -403.548586) (xy 377.415897 -403.525943) (xy 377.468199 -403.510587) (xy 377.522155 -403.50283)
			(xy 377.54941 -403.502368) (xy 378.41301 -403.502368) (xy 378.440259 -403.502903) (xy 378.494202 -403.51066)
			(xy 378.546492 -403.526015) (xy 378.596065 -403.548655) (xy 378.641911 -403.57812) (xy 378.683098 -403.613809)
			(xy 378.718786 -403.654997) (xy 378.748249 -403.700844) (xy 378.770888 -403.750417) (xy 378.786242 -403.802708)
			(xy 378.793998 -403.856651) (xy 378.793998 -403.911149) (xy 378.793998 -403.911151) (xy 380.231654 -403.911151)
			(xy 380.231654 -403.856649) (xy 380.239409 -403.802703) (xy 380.254763 -403.750409) (xy 380.277402 -403.700832)
			(xy 380.306865 -403.654981) (xy 380.342554 -403.613789) (xy 380.383741 -403.578095) (xy 380.429588 -403.548626)
			(xy 380.479162 -403.52598) (xy 380.531454 -403.51062) (xy 380.585399 -403.502857) (xy 380.61265 -403.502368)
			(xy 381.47625 -403.502368) (xy 381.503503 -403.502876) (xy 381.557456 -403.510627) (xy 381.609757 -403.525977)
			(xy 381.65934 -403.548616) (xy 381.705197 -403.57808) (xy 381.746393 -403.613772) (xy 381.78209 -403.654963)
			(xy 381.81156 -403.700816) (xy 381.834205 -403.750396) (xy 381.849563 -403.802695) (xy 381.857321 -403.856647)
			(xy 381.857321 -403.911153) (xy 383.294854 -403.911153) (xy 383.294854 -403.856647) (xy 383.302611 -403.802697)
			(xy 383.317966 -403.7504) (xy 383.340608 -403.70082) (xy 383.370075 -403.654968) (xy 383.405768 -403.613775)
			(xy 383.44696 -403.578081) (xy 383.492812 -403.548613) (xy 383.542391 -403.52597) (xy 383.594687 -403.510613)
			(xy 383.648638 -403.502855) (xy 383.67589 -403.502368) (xy 384.53949 -403.502368) (xy 384.566742 -403.502879)
			(xy 384.62069 -403.510634) (xy 384.672986 -403.525988) (xy 384.722564 -403.548629) (xy 384.768416 -403.578095)
			(xy 384.809607 -403.613786) (xy 384.845299 -403.654976) (xy 384.874767 -403.700827) (xy 384.897408 -403.750405)
			(xy 384.912764 -403.8027) (xy 384.920521 -403.856648) (xy 384.920521 -403.911152) (xy 384.92052 -403.911156)
			(xy 386.358031 -403.911156) (xy 386.358031 -403.856644) (xy 386.365789 -403.802687) (xy 386.381148 -403.750383)
			(xy 386.403794 -403.700798) (xy 386.433267 -403.654941) (xy 386.468966 -403.613745) (xy 386.510165 -403.578049)
			(xy 386.556024 -403.54858) (xy 386.605612 -403.525937) (xy 386.657916 -403.510583) (xy 386.711874 -403.502829)
			(xy 386.73913 -403.502368) (xy 387.60273 -403.502368) (xy 387.629978 -403.502904) (xy 387.683919 -403.510664)
			(xy 387.736207 -403.52602) (xy 387.785777 -403.548662) (xy 387.831621 -403.578127) (xy 387.872805 -403.613816)
			(xy 387.908491 -403.655003) (xy 387.937953 -403.700849) (xy 387.96059 -403.750421) (xy 387.975943 -403.80271)
			(xy 387.983698 -403.856652) (xy 387.983698 -403.911148) (xy 387.983697 -403.911152) (xy 389.421354 -403.911152)
			(xy 389.421354 -403.856648) (xy 389.42911 -403.8027) (xy 389.444465 -403.750404) (xy 389.467105 -403.700826)
			(xy 389.49657 -403.654974) (xy 389.532261 -403.613782) (xy 389.57345 -403.578088) (xy 389.6193 -403.548619)
			(xy 389.668876 -403.525975) (xy 389.721171 -403.510616) (xy 389.775118 -403.502856) (xy 389.80237 -403.502368)
			(xy 390.66597 -403.502368) (xy 390.693223 -403.502877) (xy 390.747173 -403.51063) (xy 390.799471 -403.525983)
			(xy 390.849052 -403.548622) (xy 390.894906 -403.578087) (xy 390.9361 -403.613779) (xy 390.971795 -403.65497)
			(xy 391.001264 -403.700821) (xy 391.023907 -403.7504) (xy 391.039263 -403.802697) (xy 391.047021 -403.856647)
			(xy 391.047021 -403.911153) (xy 391.047021 -403.911155) (xy 392.484531 -403.911155) (xy 392.484531 -403.856645)
			(xy 392.492289 -403.80269) (xy 392.507646 -403.750388) (xy 392.530291 -403.700804) (xy 392.559762 -403.654947)
			(xy 392.595459 -403.613752) (xy 392.636655 -403.578056) (xy 392.682513 -403.548586) (xy 392.732097 -403.525943)
			(xy 392.784399 -403.510587) (xy 392.838355 -403.50283) (xy 392.86561 -403.502368) (xy 393.72921 -403.502368)
			(xy 393.756459 -403.502903) (xy 393.810402 -403.51066) (xy 393.862692 -403.526015) (xy 393.912265 -403.548655)
			(xy 393.958111 -403.57812) (xy 393.999298 -403.613809) (xy 394.034986 -403.654997) (xy 394.064449 -403.700844)
			(xy 394.087088 -403.750417) (xy 394.102442 -403.802708) (xy 394.110198 -403.856651) (xy 394.110198 -403.911149)
			(xy 394.110198 -403.911151) (xy 395.547854 -403.911151) (xy 395.547854 -403.856649) (xy 395.555609 -403.802703)
			(xy 395.570963 -403.750409) (xy 395.593602 -403.700832) (xy 395.623065 -403.654981) (xy 395.658754 -403.613789)
			(xy 395.699941 -403.578095) (xy 395.745788 -403.548626) (xy 395.795362 -403.52598) (xy 395.847654 -403.51062)
			(xy 395.901599 -403.502857) (xy 395.92885 -403.502368) (xy 396.79245 -403.502368) (xy 396.819703 -403.502876)
			(xy 396.873656 -403.510627) (xy 396.925957 -403.525977) (xy 396.97554 -403.548616) (xy 397.021397 -403.57808)
			(xy 397.062593 -403.613772) (xy 397.09829 -403.654963) (xy 397.12776 -403.700816) (xy 397.150405 -403.750396)
			(xy 397.165763 -403.802695) (xy 397.173521 -403.856647) (xy 397.173521 -403.911153) (xy 398.611054 -403.911153)
			(xy 398.611054 -403.856647) (xy 398.618811 -403.802697) (xy 398.634166 -403.7504) (xy 398.656808 -403.70082)
			(xy 398.686275 -403.654968) (xy 398.721968 -403.613775) (xy 398.76316 -403.578081) (xy 398.809012 -403.548613)
			(xy 398.858591 -403.52597) (xy 398.910887 -403.510613) (xy 398.964838 -403.502855) (xy 398.99209 -403.502368)
			(xy 399.85569 -403.502368) (xy 399.882942 -403.502879) (xy 399.93689 -403.510634) (xy 399.989186 -403.525988)
			(xy 400.038764 -403.548629) (xy 400.084616 -403.578095) (xy 400.125807 -403.613786) (xy 400.161499 -403.654976)
			(xy 400.190967 -403.700827) (xy 400.213608 -403.750405) (xy 400.228964 -403.8027) (xy 400.236721 -403.856648)
			(xy 400.236721 -403.911152) (xy 400.23672 -403.911156) (xy 401.674231 -403.911156) (xy 401.674231 -403.856644)
			(xy 401.681989 -403.802687) (xy 401.697348 -403.750383) (xy 401.719994 -403.700798) (xy 401.749467 -403.654941)
			(xy 401.785166 -403.613745) (xy 401.826365 -403.578049) (xy 401.872224 -403.54858) (xy 401.921812 -403.525937)
			(xy 401.974116 -403.510583) (xy 402.028074 -403.502829) (xy 402.05533 -403.502368) (xy 402.91893 -403.502368)
			(xy 402.946178 -403.502904) (xy 403.000119 -403.510664) (xy 403.052407 -403.52602) (xy 403.101977 -403.548662)
			(xy 403.147821 -403.578127) (xy 403.189005 -403.613816) (xy 403.224691 -403.655003) (xy 403.254153 -403.700849)
			(xy 403.27679 -403.750421) (xy 403.292143 -403.80271) (xy 403.299898 -403.856652) (xy 403.299898 -403.911148)
			(xy 403.299897 -403.911152) (xy 404.737554 -403.911152) (xy 404.737554 -403.856648) (xy 404.74531 -403.8027)
			(xy 404.760665 -403.750404) (xy 404.783305 -403.700826) (xy 404.81277 -403.654974) (xy 404.848461 -403.613782)
			(xy 404.88965 -403.578088) (xy 404.9355 -403.548619) (xy 404.985076 -403.525975) (xy 405.037371 -403.510616)
			(xy 405.091318 -403.502856) (xy 405.11857 -403.502368) (xy 405.98217 -403.502368) (xy 406.009423 -403.502877)
			(xy 406.063373 -403.51063) (xy 406.115671 -403.525983) (xy 406.165252 -403.548622) (xy 406.211106 -403.578087)
			(xy 406.2523 -403.613779) (xy 406.287995 -403.65497) (xy 406.317464 -403.700821) (xy 406.340107 -403.7504)
			(xy 406.355463 -403.802697) (xy 406.363221 -403.856647) (xy 406.363221 -403.911153) (xy 406.363221 -403.911155)
			(xy 407.800731 -403.911155) (xy 407.800731 -403.856645) (xy 407.808489 -403.80269) (xy 407.823846 -403.750388)
			(xy 407.846491 -403.700804) (xy 407.875962 -403.654947) (xy 407.911659 -403.613752) (xy 407.952855 -403.578056)
			(xy 407.998713 -403.548586) (xy 408.048297 -403.525943) (xy 408.100599 -403.510587) (xy 408.154555 -403.50283)
			(xy 408.18181 -403.502368) (xy 409.04541 -403.502368) (xy 409.072659 -403.502903) (xy 409.126602 -403.51066)
			(xy 409.178892 -403.526015) (xy 409.228465 -403.548655) (xy 409.274311 -403.57812) (xy 409.315498 -403.613809)
			(xy 409.351186 -403.654997) (xy 409.380649 -403.700844) (xy 409.403288 -403.750417) (xy 409.418642 -403.802708)
			(xy 409.426398 -403.856651) (xy 409.426398 -403.911149) (xy 409.426398 -403.911151) (xy 410.864054 -403.911151)
			(xy 410.864054 -403.856649) (xy 410.871809 -403.802703) (xy 410.887163 -403.750409) (xy 410.909802 -403.700832)
			(xy 410.939265 -403.654981) (xy 410.974954 -403.613789) (xy 411.016141 -403.578095) (xy 411.061988 -403.548626)
			(xy 411.111562 -403.52598) (xy 411.163854 -403.51062) (xy 411.217799 -403.502857) (xy 411.24505 -403.502368)
			(xy 412.10865 -403.502368) (xy 412.135903 -403.502876) (xy 412.189856 -403.510627) (xy 412.242157 -403.525977)
			(xy 412.29174 -403.548616) (xy 412.337597 -403.57808) (xy 412.378793 -403.613772) (xy 412.41449 -403.654963)
			(xy 412.44396 -403.700816) (xy 412.466605 -403.750396) (xy 412.481963 -403.802695) (xy 412.489721 -403.856647)
			(xy 412.489721 -403.911153) (xy 413.927254 -403.911153) (xy 413.927254 -403.856647) (xy 413.935011 -403.802697)
			(xy 413.950366 -403.7504) (xy 413.973008 -403.70082) (xy 414.002475 -403.654968) (xy 414.038168 -403.613775)
			(xy 414.07936 -403.578081) (xy 414.125212 -403.548613) (xy 414.174791 -403.52597) (xy 414.227087 -403.510613)
			(xy 414.281038 -403.502855) (xy 414.30829 -403.502368) (xy 415.17189 -403.502368) (xy 415.199142 -403.502879)
			(xy 415.25309 -403.510634) (xy 415.305386 -403.525988) (xy 415.354964 -403.548629) (xy 415.400816 -403.578095)
			(xy 415.442007 -403.613786) (xy 415.477699 -403.654976) (xy 415.507167 -403.700827) (xy 415.529808 -403.750405)
			(xy 415.545164 -403.8027) (xy 415.552921 -403.856648) (xy 415.552921 -403.911152) (xy 415.55292 -403.911156)
			(xy 416.990431 -403.911156) (xy 416.990431 -403.856644) (xy 416.998189 -403.802687) (xy 417.013548 -403.750383)
			(xy 417.036194 -403.700798) (xy 417.065667 -403.654941) (xy 417.101366 -403.613745) (xy 417.142565 -403.578049)
			(xy 417.188424 -403.54858) (xy 417.238012 -403.525937) (xy 417.290316 -403.510583) (xy 417.344274 -403.502829)
			(xy 417.37153 -403.502368) (xy 418.23513 -403.502368) (xy 418.262378 -403.502904) (xy 418.316319 -403.510664)
			(xy 418.368607 -403.52602) (xy 418.418177 -403.548662) (xy 418.464021 -403.578127) (xy 418.505205 -403.613816)
			(xy 418.540891 -403.655003) (xy 418.570353 -403.700849) (xy 418.59299 -403.750421) (xy 418.608343 -403.80271)
			(xy 418.616098 -403.856652) (xy 418.616098 -403.911148) (xy 418.608343 -403.96509) (xy 418.59299 -404.017379)
			(xy 418.570353 -404.066951) (xy 418.540891 -404.112797) (xy 418.505205 -404.153984) (xy 418.464021 -404.189673)
			(xy 418.418177 -404.219138) (xy 418.368607 -404.24178) (xy 418.316319 -404.257136) (xy 418.262378 -404.264896)
			(xy 418.23513 -404.265384) (xy 417.37153 -404.265384) (xy 417.344274 -404.264971) (xy 417.290316 -404.257217)
			(xy 417.238012 -404.241863) (xy 417.188424 -404.21922) (xy 417.142565 -404.189751) (xy 417.101366 -404.154055)
			(xy 417.065667 -404.112859) (xy 417.036194 -404.067002) (xy 417.013548 -404.017417) (xy 416.998189 -403.965113)
			(xy 416.990431 -403.911156) (xy 415.55292 -403.911156) (xy 415.545164 -403.9651) (xy 415.529808 -404.017395)
			(xy 415.507167 -404.066973) (xy 415.477699 -404.112824) (xy 415.442007 -404.154014) (xy 415.400816 -404.189705)
			(xy 415.354964 -404.219171) (xy 415.305386 -404.241812) (xy 415.25309 -404.257166) (xy 415.199142 -404.264921)
			(xy 415.17189 -404.265384) (xy 414.30829 -404.265384) (xy 414.281038 -404.264945) (xy 414.227087 -404.257187)
			(xy 414.174791 -404.24183) (xy 414.125212 -404.219187) (xy 414.07936 -404.189719) (xy 414.038168 -404.154025)
			(xy 414.002475 -404.112832) (xy 413.973008 -404.06698) (xy 413.950366 -404.0174) (xy 413.935011 -403.965103)
			(xy 413.927254 -403.911153) (xy 412.489721 -403.911153) (xy 412.481963 -403.965105) (xy 412.466605 -404.017404)
			(xy 412.44396 -404.066984) (xy 412.41449 -404.112837) (xy 412.378793 -404.154028) (xy 412.337597 -404.18972)
			(xy 412.29174 -404.219184) (xy 412.242157 -404.241823) (xy 412.189856 -404.257173) (xy 412.135903 -404.264924)
			(xy 412.10865 -404.265384) (xy 411.24505 -404.265384) (xy 411.217799 -404.264943) (xy 411.163854 -404.25718)
			(xy 411.111562 -404.24182) (xy 411.061988 -404.219174) (xy 411.016141 -404.189705) (xy 410.974954 -404.154011)
			(xy 410.939265 -404.112819) (xy 410.909802 -404.066968) (xy 410.887163 -404.017391) (xy 410.871809 -403.965097)
			(xy 410.864054 -403.911151) (xy 409.426398 -403.911151) (xy 409.418642 -403.965092) (xy 409.403288 -404.017383)
			(xy 409.380649 -404.066956) (xy 409.351186 -404.112803) (xy 409.315498 -404.153991) (xy 409.274311 -404.18968)
			(xy 409.228465 -404.219145) (xy 409.178892 -404.241785) (xy 409.126602 -404.25714) (xy 409.072659 -404.264897)
			(xy 409.04541 -404.265384) (xy 408.18181 -404.265384) (xy 408.154555 -404.26497) (xy 408.100599 -404.257213)
			(xy 408.048297 -404.241857) (xy 407.998713 -404.219214) (xy 407.952855 -404.189744) (xy 407.911659 -404.154048)
			(xy 407.875962 -404.112853) (xy 407.846491 -404.066996) (xy 407.823846 -404.017412) (xy 407.808489 -403.96511)
			(xy 407.800731 -403.911155) (xy 406.363221 -403.911155) (xy 406.355463 -403.965103) (xy 406.340107 -404.0174)
			(xy 406.317464 -404.066979) (xy 406.287995 -404.11283) (xy 406.2523 -404.154021) (xy 406.211106 -404.189713)
			(xy 406.165252 -404.219178) (xy 406.115671 -404.241817) (xy 406.063373 -404.25717) (xy 406.009423 -404.264923)
			(xy 405.98217 -404.265384) (xy 405.11857 -404.265384) (xy 405.091318 -404.264944) (xy 405.037371 -404.257184)
			(xy 404.985076 -404.241825) (xy 404.9355 -404.219181) (xy 404.88965 -404.189712) (xy 404.848461 -404.154018)
			(xy 404.81277 -404.112826) (xy 404.783305 -404.066974) (xy 404.760665 -404.017396) (xy 404.74531 -403.9651)
			(xy 404.737554 -403.911152) (xy 403.299897 -403.911152) (xy 403.292143 -403.96509) (xy 403.27679 -404.017379)
			(xy 403.254153 -404.066951) (xy 403.224691 -404.112797) (xy 403.189005 -404.153984) (xy 403.147821 -404.189673)
			(xy 403.101977 -404.219138) (xy 403.052407 -404.24178) (xy 403.000119 -404.257136) (xy 402.946178 -404.264896)
			(xy 402.91893 -404.265384) (xy 402.05533 -404.265384) (xy 402.028074 -404.264971) (xy 401.974116 -404.257217)
			(xy 401.921812 -404.241863) (xy 401.872224 -404.21922) (xy 401.826365 -404.189751) (xy 401.785166 -404.154055)
			(xy 401.749467 -404.112859) (xy 401.719994 -404.067002) (xy 401.697348 -404.017417) (xy 401.681989 -403.965113)
			(xy 401.674231 -403.911156) (xy 400.23672 -403.911156) (xy 400.228964 -403.9651) (xy 400.213608 -404.017395)
			(xy 400.190967 -404.066973) (xy 400.161499 -404.112824) (xy 400.125807 -404.154014) (xy 400.084616 -404.189705)
			(xy 400.038764 -404.219171) (xy 399.989186 -404.241812) (xy 399.93689 -404.257166) (xy 399.882942 -404.264921)
			(xy 399.85569 -404.265384) (xy 398.99209 -404.265384) (xy 398.964838 -404.264945) (xy 398.910887 -404.257187)
			(xy 398.858591 -404.24183) (xy 398.809012 -404.219187) (xy 398.76316 -404.189719) (xy 398.721968 -404.154025)
			(xy 398.686275 -404.112832) (xy 398.656808 -404.06698) (xy 398.634166 -404.0174) (xy 398.618811 -403.965103)
			(xy 398.611054 -403.911153) (xy 397.173521 -403.911153) (xy 397.165763 -403.965105) (xy 397.150405 -404.017404)
			(xy 397.12776 -404.066984) (xy 397.09829 -404.112837) (xy 397.062593 -404.154028) (xy 397.021397 -404.18972)
			(xy 396.97554 -404.219184) (xy 396.925957 -404.241823) (xy 396.873656 -404.257173) (xy 396.819703 -404.264924)
			(xy 396.79245 -404.265384) (xy 395.92885 -404.265384) (xy 395.901599 -404.264943) (xy 395.847654 -404.25718)
			(xy 395.795362 -404.24182) (xy 395.745788 -404.219174) (xy 395.699941 -404.189705) (xy 395.658754 -404.154011)
			(xy 395.623065 -404.112819) (xy 395.593602 -404.066968) (xy 395.570963 -404.017391) (xy 395.555609 -403.965097)
			(xy 395.547854 -403.911151) (xy 394.110198 -403.911151) (xy 394.102442 -403.965092) (xy 394.087088 -404.017383)
			(xy 394.064449 -404.066956) (xy 394.034986 -404.112803) (xy 393.999298 -404.153991) (xy 393.958111 -404.18968)
			(xy 393.912265 -404.219145) (xy 393.862692 -404.241785) (xy 393.810402 -404.25714) (xy 393.756459 -404.264897)
			(xy 393.72921 -404.265384) (xy 392.86561 -404.265384) (xy 392.838355 -404.26497) (xy 392.784399 -404.257213)
			(xy 392.732097 -404.241857) (xy 392.682513 -404.219214) (xy 392.636655 -404.189744) (xy 392.595459 -404.154048)
			(xy 392.559762 -404.112853) (xy 392.530291 -404.066996) (xy 392.507646 -404.017412) (xy 392.492289 -403.96511)
			(xy 392.484531 -403.911155) (xy 391.047021 -403.911155) (xy 391.039263 -403.965103) (xy 391.023907 -404.0174)
			(xy 391.001264 -404.066979) (xy 390.971795 -404.11283) (xy 390.9361 -404.154021) (xy 390.894906 -404.189713)
			(xy 390.849052 -404.219178) (xy 390.799471 -404.241817) (xy 390.747173 -404.25717) (xy 390.693223 -404.264923)
			(xy 390.66597 -404.265384) (xy 389.80237 -404.265384) (xy 389.775118 -404.264944) (xy 389.721171 -404.257184)
			(xy 389.668876 -404.241825) (xy 389.6193 -404.219181) (xy 389.57345 -404.189712) (xy 389.532261 -404.154018)
			(xy 389.49657 -404.112826) (xy 389.467105 -404.066974) (xy 389.444465 -404.017396) (xy 389.42911 -403.9651)
			(xy 389.421354 -403.911152) (xy 387.983697 -403.911152) (xy 387.975943 -403.96509) (xy 387.96059 -404.017379)
			(xy 387.937953 -404.066951) (xy 387.908491 -404.112797) (xy 387.872805 -404.153984) (xy 387.831621 -404.189673)
			(xy 387.785777 -404.219138) (xy 387.736207 -404.24178) (xy 387.683919 -404.257136) (xy 387.629978 -404.264896)
			(xy 387.60273 -404.265384) (xy 386.73913 -404.265384) (xy 386.711874 -404.264971) (xy 386.657916 -404.257217)
			(xy 386.605612 -404.241863) (xy 386.556024 -404.21922) (xy 386.510165 -404.189751) (xy 386.468966 -404.154055)
			(xy 386.433267 -404.112859) (xy 386.403794 -404.067002) (xy 386.381148 -404.017417) (xy 386.365789 -403.965113)
			(xy 386.358031 -403.911156) (xy 384.92052 -403.911156) (xy 384.912764 -403.9651) (xy 384.897408 -404.017395)
			(xy 384.874767 -404.066973) (xy 384.845299 -404.112824) (xy 384.809607 -404.154014) (xy 384.768416 -404.189705)
			(xy 384.722564 -404.219171) (xy 384.672986 -404.241812) (xy 384.62069 -404.257166) (xy 384.566742 -404.264921)
			(xy 384.53949 -404.265384) (xy 383.67589 -404.265384) (xy 383.648638 -404.264945) (xy 383.594687 -404.257187)
			(xy 383.542391 -404.24183) (xy 383.492812 -404.219187) (xy 383.44696 -404.189719) (xy 383.405768 -404.154025)
			(xy 383.370075 -404.112832) (xy 383.340608 -404.06698) (xy 383.317966 -404.0174) (xy 383.302611 -403.965103)
			(xy 383.294854 -403.911153) (xy 381.857321 -403.911153) (xy 381.849563 -403.965105) (xy 381.834205 -404.017404)
			(xy 381.81156 -404.066984) (xy 381.78209 -404.112837) (xy 381.746393 -404.154028) (xy 381.705197 -404.18972)
			(xy 381.65934 -404.219184) (xy 381.609757 -404.241823) (xy 381.557456 -404.257173) (xy 381.503503 -404.264924)
			(xy 381.47625 -404.265384) (xy 380.61265 -404.265384) (xy 380.585399 -404.264943) (xy 380.531454 -404.25718)
			(xy 380.479162 -404.24182) (xy 380.429588 -404.219174) (xy 380.383741 -404.189705) (xy 380.342554 -404.154011)
			(xy 380.306865 -404.112819) (xy 380.277402 -404.066968) (xy 380.254763 -404.017391) (xy 380.239409 -403.965097)
			(xy 380.231654 -403.911151) (xy 378.793998 -403.911151) (xy 378.786242 -403.965092) (xy 378.770888 -404.017383)
			(xy 378.748249 -404.066956) (xy 378.718786 -404.112803) (xy 378.683098 -404.153991) (xy 378.641911 -404.18968)
			(xy 378.596065 -404.219145) (xy 378.546492 -404.241785) (xy 378.494202 -404.25714) (xy 378.440259 -404.264897)
			(xy 378.41301 -404.265384) (xy 377.54941 -404.265384) (xy 377.522155 -404.26497) (xy 377.468199 -404.257213)
			(xy 377.415897 -404.241857) (xy 377.366313 -404.219214) (xy 377.320455 -404.189744) (xy 377.279259 -404.154048)
			(xy 377.243562 -404.112853) (xy 377.214091 -404.066996) (xy 377.191446 -404.017412) (xy 377.176089 -403.96511)
			(xy 377.168331 -403.911155) (xy 375.730821 -403.911155) (xy 375.723063 -403.965103) (xy 375.707707 -404.0174)
			(xy 375.685064 -404.066979) (xy 375.655595 -404.11283) (xy 375.6199 -404.154021) (xy 375.578706 -404.189713)
			(xy 375.532852 -404.219178) (xy 375.483271 -404.241817) (xy 375.430973 -404.25717) (xy 375.377023 -404.264923)
			(xy 375.34977 -404.265384) (xy 374.48617 -404.265384) (xy 374.458918 -404.264944) (xy 374.404971 -404.257184)
			(xy 374.352676 -404.241825) (xy 374.3031 -404.219181) (xy 374.25725 -404.189712) (xy 374.216061 -404.154018)
			(xy 374.18037 -404.112826) (xy 374.150905 -404.066974) (xy 374.128265 -404.017396) (xy 374.11291 -403.9651)
			(xy 374.105154 -403.911152) (xy 372.667497 -403.911152) (xy 372.659743 -403.96509) (xy 372.64439 -404.017379)
			(xy 372.621753 -404.066951) (xy 372.592291 -404.112797) (xy 372.556605 -404.153984) (xy 372.515421 -404.189673)
			(xy 372.469577 -404.219138) (xy 372.420007 -404.24178) (xy 372.367719 -404.257136) (xy 372.313778 -404.264896)
			(xy 372.28653 -404.265384) (xy 371.42293 -404.265384) (xy 371.395674 -404.264971) (xy 371.341716 -404.257217)
			(xy 371.289412 -404.241863) (xy 371.239824 -404.21922) (xy 371.193965 -404.189751) (xy 371.152766 -404.154055)
			(xy 371.117067 -404.112859) (xy 371.087594 -404.067002) (xy 371.064948 -404.017417) (xy 371.049589 -403.965113)
			(xy 371.041831 -403.911156) (xy 351.17332 -403.911156) (xy 351.165564 -403.9651) (xy 351.150208 -404.017396)
			(xy 351.127566 -404.066974) (xy 351.098099 -404.112824) (xy 351.062406 -404.154015) (xy 351.021215 -404.189706)
			(xy 350.975363 -404.219172) (xy 350.925785 -404.241812) (xy 350.873489 -404.257166) (xy 350.81954 -404.264922)
			(xy 350.792288 -404.265384) (xy 349.928688 -404.265384) (xy 349.901436 -404.264945) (xy 349.847486 -404.257187)
			(xy 349.795189 -404.24183) (xy 349.74561 -404.219187) (xy 349.699759 -404.189718) (xy 349.658567 -404.154024)
			(xy 349.622875 -404.112832) (xy 349.593408 -404.066979) (xy 349.570766 -404.0174) (xy 349.55541 -403.965102)
			(xy 349.547654 -403.911152) (xy 348.109997 -403.911152) (xy 348.102243 -403.965087) (xy 348.086891 -404.017375)
			(xy 348.064255 -404.066946) (xy 348.034795 -404.112791) (xy 347.999111 -404.153977) (xy 347.957929 -404.189667)
			(xy 347.912088 -404.219132) (xy 347.86252 -404.241775) (xy 347.810234 -404.257133) (xy 347.756295 -404.264895)
			(xy 347.729048 -404.265384) (xy 346.865448 -404.265384) (xy 346.838191 -404.264972) (xy 346.784232 -404.25722)
			(xy 346.731925 -404.241868) (xy 346.682335 -404.219226) (xy 346.636473 -404.189758) (xy 346.595272 -404.154062)
			(xy 346.559571 -404.112865) (xy 346.530097 -404.067007) (xy 346.507449 -404.01742) (xy 346.49209 -403.965115)
			(xy 346.484331 -403.911157) (xy 345.046797 -403.911157) (xy 345.039042 -403.965093) (xy 345.023688 -404.017383)
			(xy 345.001049 -404.066957) (xy 344.971586 -404.112804) (xy 344.935897 -404.153991) (xy 344.89471 -404.189681)
			(xy 344.848864 -404.219145) (xy 344.799291 -404.241785) (xy 344.747001 -404.25714) (xy 344.693057 -404.264897)
			(xy 344.665808 -404.265384) (xy 343.802208 -404.265384) (xy 343.774953 -404.26497) (xy 343.720998 -404.257213)
			(xy 343.668696 -404.241857) (xy 343.619111 -404.219213) (xy 343.573254 -404.189744) (xy 343.532058 -404.154048)
			(xy 343.496361 -404.112852) (xy 343.466891 -404.066996) (xy 343.444246 -404.017412) (xy 343.428889 -403.96511)
			(xy 343.421131 -403.911155) (xy 341.983621 -403.911155) (xy 341.975863 -403.965103) (xy 341.960507 -404.0174)
			(xy 341.937863 -404.066979) (xy 341.908394 -404.112831) (xy 341.872699 -404.154022) (xy 341.831505 -404.189713)
			(xy 341.785651 -404.219179) (xy 341.73607 -404.241818) (xy 341.683772 -404.25717) (xy 341.629821 -404.264923)
			(xy 341.602568 -404.265384) (xy 340.738968 -404.265384) (xy 340.711717 -404.264944) (xy 340.657769 -404.257183)
			(xy 340.605475 -404.241824) (xy 340.555898 -404.21918) (xy 340.510049 -404.189711) (xy 340.46886 -404.154017)
			(xy 340.43317 -404.112825) (xy 340.403705 -404.066974) (xy 340.381064 -404.017395) (xy 340.36571 -403.9651)
			(xy 340.357954 -403.911152) (xy 338.920297 -403.911152) (xy 338.912543 -403.96509) (xy 338.89719 -404.017379)
			(xy 338.874552 -404.066951) (xy 338.84509 -404.112798) (xy 338.809404 -404.153984) (xy 338.76822 -404.189674)
			(xy 338.722376 -404.219139) (xy 338.672805 -404.24178) (xy 338.620517 -404.257137) (xy 338.566576 -404.264896)
			(xy 338.539328 -404.265384) (xy 337.675728 -404.265384) (xy 337.648472 -404.264971) (xy 337.594515 -404.257217)
			(xy 337.54221 -404.241862) (xy 337.492623 -404.21922) (xy 337.446764 -404.189751) (xy 337.405565 -404.154055)
			(xy 337.369866 -404.112859) (xy 337.340394 -404.067001) (xy 337.317748 -404.017416) (xy 337.302389 -403.965113)
			(xy 337.294631 -403.911156) (xy 335.85712 -403.911156) (xy 335.849364 -403.9651) (xy 335.834008 -404.017396)
			(xy 335.811366 -404.066974) (xy 335.781899 -404.112824) (xy 335.746206 -404.154015) (xy 335.705015 -404.189706)
			(xy 335.659163 -404.219172) (xy 335.609585 -404.241812) (xy 335.557289 -404.257166) (xy 335.50334 -404.264922)
			(xy 335.476088 -404.265384) (xy 334.612488 -404.265384) (xy 334.585236 -404.264945) (xy 334.531286 -404.257187)
			(xy 334.478989 -404.24183) (xy 334.42941 -404.219187) (xy 334.383559 -404.189718) (xy 334.342367 -404.154024)
			(xy 334.306675 -404.112832) (xy 334.277208 -404.066979) (xy 334.254566 -404.0174) (xy 334.23921 -403.965102)
			(xy 334.231454 -403.911152) (xy 332.793797 -403.911152) (xy 332.786043 -403.965087) (xy 332.770691 -404.017375)
			(xy 332.748055 -404.066946) (xy 332.718595 -404.112791) (xy 332.682911 -404.153977) (xy 332.641729 -404.189667)
			(xy 332.595888 -404.219132) (xy 332.54632 -404.241775) (xy 332.494034 -404.257133) (xy 332.440095 -404.264895)
			(xy 332.412848 -404.265384) (xy 331.549248 -404.265384) (xy 331.521991 -404.264972) (xy 331.468032 -404.25722)
			(xy 331.415725 -404.241868) (xy 331.366135 -404.219226) (xy 331.320273 -404.189758) (xy 331.279072 -404.154062)
			(xy 331.243371 -404.112865) (xy 331.213897 -404.067007) (xy 331.191249 -404.01742) (xy 331.17589 -403.965115)
			(xy 331.168131 -403.911157) (xy 329.730597 -403.911157) (xy 329.722842 -403.965093) (xy 329.707488 -404.017383)
			(xy 329.684849 -404.066957) (xy 329.655386 -404.112804) (xy 329.619697 -404.153991) (xy 329.57851 -404.189681)
			(xy 329.532664 -404.219145) (xy 329.483091 -404.241785) (xy 329.430801 -404.25714) (xy 329.376857 -404.264897)
			(xy 329.349608 -404.265384) (xy 328.486008 -404.265384) (xy 328.458753 -404.26497) (xy 328.404798 -404.257213)
			(xy 328.352496 -404.241857) (xy 328.302911 -404.219213) (xy 328.257054 -404.189744) (xy 328.215858 -404.154048)
			(xy 328.180161 -404.112852) (xy 328.150691 -404.066996) (xy 328.128046 -404.017412) (xy 328.112689 -403.96511)
			(xy 328.104931 -403.911155) (xy 326.667421 -403.911155) (xy 326.659663 -403.965103) (xy 326.644307 -404.0174)
			(xy 326.621663 -404.066979) (xy 326.592194 -404.112831) (xy 326.556499 -404.154022) (xy 326.515305 -404.189713)
			(xy 326.469451 -404.219179) (xy 326.41987 -404.241818) (xy 326.367572 -404.25717) (xy 326.313621 -404.264923)
			(xy 326.286368 -404.265384) (xy 325.422768 -404.265384) (xy 325.395517 -404.264944) (xy 325.341569 -404.257183)
			(xy 325.289275 -404.241824) (xy 325.239698 -404.21918) (xy 325.193849 -404.189711) (xy 325.15266 -404.154017)
			(xy 325.11697 -404.112825) (xy 325.087505 -404.066974) (xy 325.064864 -404.017395) (xy 325.04951 -403.9651)
			(xy 325.041754 -403.911152) (xy 323.604097 -403.911152) (xy 323.596343 -403.96509) (xy 323.58099 -404.017379)
			(xy 323.558352 -404.066951) (xy 323.52889 -404.112798) (xy 323.493204 -404.153984) (xy 323.45202 -404.189674)
			(xy 323.406176 -404.219139) (xy 323.356605 -404.24178) (xy 323.304317 -404.257137) (xy 323.250376 -404.264896)
			(xy 323.223128 -404.265384) (xy 322.359528 -404.265384) (xy 322.332272 -404.264971) (xy 322.278315 -404.257217)
			(xy 322.22601 -404.241862) (xy 322.176423 -404.21922) (xy 322.130564 -404.189751) (xy 322.089365 -404.154055)
			(xy 322.053666 -404.112859) (xy 322.024194 -404.067001) (xy 322.001548 -404.017416) (xy 321.986189 -403.965113)
			(xy 321.978431 -403.911156) (xy 320.54092 -403.911156) (xy 320.533164 -403.9651) (xy 320.517808 -404.017396)
			(xy 320.495166 -404.066974) (xy 320.465699 -404.112824) (xy 320.430006 -404.154015) (xy 320.388815 -404.189706)
			(xy 320.342963 -404.219172) (xy 320.293385 -404.241812) (xy 320.241089 -404.257166) (xy 320.18714 -404.264922)
			(xy 320.159888 -404.265384) (xy 319.296288 -404.265384) (xy 319.269036 -404.264945) (xy 319.215086 -404.257187)
			(xy 319.162789 -404.24183) (xy 319.11321 -404.219187) (xy 319.067359 -404.189718) (xy 319.026167 -404.154024)
			(xy 318.990475 -404.112832) (xy 318.961008 -404.066979) (xy 318.938366 -404.0174) (xy 318.92301 -403.965102)
			(xy 318.915254 -403.911152) (xy 317.477597 -403.911152) (xy 317.469843 -403.965087) (xy 317.454491 -404.017375)
			(xy 317.431855 -404.066946) (xy 317.402395 -404.112791) (xy 317.366711 -404.153977) (xy 317.325529 -404.189667)
			(xy 317.279688 -404.219132) (xy 317.23012 -404.241775) (xy 317.177834 -404.257133) (xy 317.123895 -404.264895)
			(xy 317.096648 -404.265384) (xy 316.233048 -404.265384) (xy 316.205791 -404.264972) (xy 316.151832 -404.25722)
			(xy 316.099525 -404.241868) (xy 316.049935 -404.219226) (xy 316.004073 -404.189758) (xy 315.962872 -404.154062)
			(xy 315.927171 -404.112865) (xy 315.897697 -404.067007) (xy 315.875049 -404.01742) (xy 315.85969 -403.965115)
			(xy 315.851931 -403.911157) (xy 314.414397 -403.911157) (xy 314.406642 -403.965093) (xy 314.391288 -404.017383)
			(xy 314.368649 -404.066957) (xy 314.339186 -404.112804) (xy 314.303497 -404.153991) (xy 314.26231 -404.189681)
			(xy 314.216464 -404.219145) (xy 314.166891 -404.241785) (xy 314.114601 -404.25714) (xy 314.060657 -404.264897)
			(xy 314.033408 -404.265384) (xy 313.169808 -404.265384) (xy 313.142553 -404.26497) (xy 313.088598 -404.257213)
			(xy 313.036296 -404.241857) (xy 312.986711 -404.219213) (xy 312.940854 -404.189744) (xy 312.899658 -404.154048)
			(xy 312.863961 -404.112852) (xy 312.834491 -404.066996) (xy 312.811846 -404.017412) (xy 312.796489 -403.96511)
			(xy 312.788731 -403.911155) (xy 311.351221 -403.911155) (xy 311.343463 -403.965103) (xy 311.328107 -404.0174)
			(xy 311.305463 -404.066979) (xy 311.275994 -404.112831) (xy 311.240299 -404.154022) (xy 311.199105 -404.189713)
			(xy 311.153251 -404.219179) (xy 311.10367 -404.241818) (xy 311.051372 -404.25717) (xy 310.997421 -404.264923)
			(xy 310.970168 -404.265384) (xy 310.106568 -404.265384) (xy 310.079317 -404.264944) (xy 310.025369 -404.257183)
			(xy 309.973075 -404.241824) (xy 309.923498 -404.21918) (xy 309.877649 -404.189711) (xy 309.83646 -404.154017)
			(xy 309.80077 -404.112825) (xy 309.771305 -404.066974) (xy 309.748664 -404.017395) (xy 309.73331 -403.9651)
			(xy 309.725554 -403.911152) (xy 308.287897 -403.911152) (xy 308.280143 -403.96509) (xy 308.26479 -404.017379)
			(xy 308.242152 -404.066951) (xy 308.21269 -404.112798) (xy 308.177004 -404.153984) (xy 308.13582 -404.189674)
			(xy 308.089976 -404.219139) (xy 308.040405 -404.24178) (xy 307.988117 -404.257137) (xy 307.934176 -404.264896)
			(xy 307.906928 -404.265384) (xy 307.043328 -404.265384) (xy 307.016072 -404.264971) (xy 306.962115 -404.257217)
			(xy 306.90981 -404.241862) (xy 306.860223 -404.21922) (xy 306.814364 -404.189751) (xy 306.773165 -404.154055)
			(xy 306.737466 -404.112859) (xy 306.707994 -404.067001) (xy 306.685348 -404.017416) (xy 306.669989 -403.965113)
			(xy 306.662231 -403.911156) (xy 305.22472 -403.911156) (xy 305.216964 -403.9651) (xy 305.201608 -404.017396)
			(xy 305.178966 -404.066974) (xy 305.149499 -404.112824) (xy 305.113806 -404.154015) (xy 305.072615 -404.189706)
			(xy 305.026763 -404.219172) (xy 304.977185 -404.241812) (xy 304.924889 -404.257166) (xy 304.87094 -404.264922)
			(xy 304.843688 -404.265384) (xy 303.980088 -404.265384) (xy 303.952836 -404.264945) (xy 303.898886 -404.257187)
			(xy 303.846589 -404.24183) (xy 303.79701 -404.219187) (xy 303.751159 -404.189718) (xy 303.709967 -404.154024)
			(xy 303.674275 -404.112832) (xy 303.644808 -404.066979) (xy 303.622166 -404.0174) (xy 303.60681 -403.965102)
			(xy 303.599054 -403.911152) (xy 298.836897 -403.911152) (xy 298.840074 -403.920931) (xy 298.852049 -403.983712)
			(xy 298.856063 -404.0475) (xy 298.852049 -404.111288) (xy 298.840074 -404.174069) (xy 298.820324 -404.234855)
			(xy 298.793112 -404.292686) (xy 298.758866 -404.346651) (xy 298.718128 -404.395898) (xy 298.671538 -404.439652)
			(xy 298.619832 -404.477221) (xy 298.563825 -404.508014) (xy 298.504401 -404.531545) (xy 298.442496 -404.547442)
			(xy 298.379087 -404.555456) (xy 298.34713 -404.55596) (xy 298.346876 -404.55596) (xy 298.315131 -404.555422)
			(xy 298.252136 -404.547497) (xy 298.190616 -404.531797) (xy 298.131527 -404.508566) (xy 298.075787 -404.478166)
			(xy 298.024261 -404.441069) (xy 298.000674 -404.419816) (xy 297.993411 -404.413632) (xy 297.975661 -404.406681)
			(xy 297.956599 -404.406681) (xy 297.938849 -404.413632) (xy 297.931586 -404.419816) (xy 297.908028 -404.441107)
			(xy 297.856512 -404.478235) (xy 297.800771 -404.508654) (xy 297.741674 -404.531889) (xy 297.680142 -404.547579)
			(xy 297.617135 -404.555478) (xy 297.585384 -404.55596) (xy 297.58513 -404.55596) (xy 297.553163 -404.555577)
			(xy 297.489734 -404.547567) (xy 297.427809 -404.531671) (xy 297.368364 -404.508138) (xy 297.312338 -404.47734)
			(xy 297.260613 -404.439763) (xy 297.214007 -404.395999) (xy 297.173253 -404.346739) (xy 297.138995 -404.292759)
			(xy 297.111773 -404.234911) (xy 297.092015 -404.174108) (xy 297.080035 -404.111307) (xy 297.07602 -404.0475)
			(xy 296.316063 -404.0475) (xy 296.312049 -404.111288) (xy 296.300074 -404.174069) (xy 296.280324 -404.234855)
			(xy 296.253112 -404.292686) (xy 296.218866 -404.346651) (xy 296.178128 -404.395898) (xy 296.131538 -404.439652)
			(xy 296.079832 -404.477221) (xy 296.023825 -404.508014) (xy 295.964401 -404.531545) (xy 295.902496 -404.547442)
			(xy 295.839087 -404.555456) (xy 295.80713 -404.55596) (xy 295.806876 -404.55596) (xy 295.775131 -404.555422)
			(xy 295.712136 -404.547497) (xy 295.650616 -404.531797) (xy 295.591527 -404.508566) (xy 295.535787 -404.478166)
			(xy 295.484261 -404.441069) (xy 295.460674 -404.419816) (xy 295.453411 -404.413632) (xy 295.435661 -404.406681)
			(xy 295.416599 -404.406681) (xy 295.398849 -404.413632) (xy 295.391586 -404.419816) (xy 295.368028 -404.441107)
			(xy 295.316512 -404.478235) (xy 295.260771 -404.508654) (xy 295.201674 -404.531889) (xy 295.140142 -404.547579)
			(xy 295.077135 -404.555478) (xy 295.045384 -404.55596) (xy 295.04513 -404.55596) (xy 295.013163 -404.555577)
			(xy 294.949734 -404.547567) (xy 294.887809 -404.531671) (xy 294.828364 -404.508138) (xy 294.772338 -404.47734)
			(xy 294.720613 -404.439763) (xy 294.674007 -404.395999) (xy 294.633253 -404.346739) (xy 294.598995 -404.292759)
			(xy 294.571773 -404.234911) (xy 294.552015 -404.174108) (xy 294.540035 -404.111307) (xy 294.53602 -404.0475)
			(xy 293.926484 -404.0475) (xy 293.92247 -404.111293) (xy 293.910493 -404.174079) (xy 293.890741 -404.23487)
			(xy 293.863525 -404.292705) (xy 293.829276 -404.346674) (xy 293.788532 -404.395924) (xy 293.741937 -404.439679)
			(xy 293.690226 -404.47725) (xy 293.634213 -404.508043) (xy 293.574783 -404.531573) (xy 293.512872 -404.547468)
			(xy 293.449457 -404.555479) (xy 293.417498 -404.55596) (xy 293.417244 -404.55596) (xy 293.385498 -404.555442)
			(xy 293.322502 -404.547512) (xy 293.260982 -404.531809) (xy 293.201894 -404.508575) (xy 293.146154 -404.478171)
			(xy 293.094629 -404.44107) (xy 293.071042 -404.419816) (xy 293.063779 -404.413632) (xy 293.046029 -404.406681)
			(xy 293.026967 -404.406681) (xy 293.009217 -404.413632) (xy 293.001954 -404.419816) (xy 292.978367 -404.441074)
			(xy 292.926858 -404.478206) (xy 292.871123 -404.50863) (xy 292.812032 -404.531871) (xy 292.750504 -404.547567)
			(xy 292.687501 -404.555474) (xy 292.655752 -404.55596) (xy 292.655498 -404.55596) (xy 292.623534 -404.555554)
			(xy 292.56011 -404.547542) (xy 292.498191 -404.531643) (xy 292.438752 -404.50811) (xy 292.382731 -404.477312)
			(xy 292.331013 -404.439736) (xy 292.284411 -404.395974) (xy 292.243662 -404.346717) (xy 292.209408 -404.29274)
			(xy 292.182189 -404.234897) (xy 292.162434 -404.174098) (xy 292.150455 -404.111302) (xy 292.146441 -404.0475)
			(xy 291.386484 -404.0475) (xy 291.38247 -404.111293) (xy 291.370493 -404.174079) (xy 291.350741 -404.23487)
			(xy 291.323525 -404.292705) (xy 291.289276 -404.346674) (xy 291.248532 -404.395924) (xy 291.201937 -404.439679)
			(xy 291.150226 -404.47725) (xy 291.094213 -404.508043) (xy 291.034783 -404.531573) (xy 290.972872 -404.547468)
			(xy 290.909457 -404.555479) (xy 290.877498 -404.55596) (xy 290.877244 -404.55596) (xy 290.845498 -404.555442)
			(xy 290.782502 -404.547512) (xy 290.720982 -404.531809) (xy 290.661894 -404.508575) (xy 290.606154 -404.478171)
			(xy 290.554629 -404.44107) (xy 290.531042 -404.419816) (xy 290.523779 -404.413632) (xy 290.506029 -404.406681)
			(xy 290.486967 -404.406681) (xy 290.469217 -404.413632) (xy 290.461954 -404.419816) (xy 290.438367 -404.441074)
			(xy 290.386858 -404.478206) (xy 290.331123 -404.50863) (xy 290.272032 -404.531871) (xy 290.210504 -404.547567)
			(xy 290.147501 -404.555474) (xy 290.115752 -404.55596) (xy 290.115498 -404.55596) (xy 290.083534 -404.555554)
			(xy 290.02011 -404.547542) (xy 289.958191 -404.531643) (xy 289.898752 -404.50811) (xy 289.842731 -404.477312)
			(xy 289.791013 -404.439736) (xy 289.744411 -404.395974) (xy 289.703662 -404.346717) (xy 289.669408 -404.29274)
			(xy 289.642189 -404.234897) (xy 289.622434 -404.174098) (xy 289.610455 -404.111302) (xy 289.606441 -404.0475)
			(xy 288.846484 -404.0475) (xy 288.84247 -404.111293) (xy 288.830493 -404.174079) (xy 288.810741 -404.23487)
			(xy 288.783525 -404.292705) (xy 288.749276 -404.346674) (xy 288.708532 -404.395924) (xy 288.661937 -404.439679)
			(xy 288.610226 -404.47725) (xy 288.554213 -404.508043) (xy 288.494783 -404.531573) (xy 288.432872 -404.547468)
			(xy 288.369457 -404.555479) (xy 288.337498 -404.55596) (xy 288.337244 -404.55596) (xy 288.305498 -404.555442)
			(xy 288.242502 -404.547512) (xy 288.180982 -404.531809) (xy 288.121894 -404.508575) (xy 288.066154 -404.478171)
			(xy 288.014629 -404.44107) (xy 287.991042 -404.419816) (xy 287.983779 -404.413632) (xy 287.966029 -404.406681)
			(xy 287.946967 -404.406681) (xy 287.929217 -404.413632) (xy 287.921954 -404.419816) (xy 287.898367 -404.441074)
			(xy 287.846858 -404.478206) (xy 287.791123 -404.50863) (xy 287.732032 -404.531871) (xy 287.670504 -404.547567)
			(xy 287.607501 -404.555474) (xy 287.575752 -404.55596) (xy 287.575498 -404.55596) (xy 287.543534 -404.555554)
			(xy 287.48011 -404.547542) (xy 287.418191 -404.531643) (xy 287.358752 -404.50811) (xy 287.302731 -404.477312)
			(xy 287.251013 -404.439736) (xy 287.204411 -404.395974) (xy 287.163662 -404.346717) (xy 287.129408 -404.29274)
			(xy 287.102189 -404.234897) (xy 287.082434 -404.174098) (xy 287.070455 -404.111302) (xy 287.066441 -404.0475)
			(xy 281.686508 -404.0475) (xy 281.686508 -405.908764) (xy 281.686046 -405.933715) (xy 281.678225 -405.982999)
			(xy 281.6628 -406.030457) (xy 281.64015 -406.074922) (xy 281.610832 -406.115303) (xy 281.593544 -406.1333)
			(xy 281.262328 -406.464516) (xy 281.244327 -406.4818) (xy 281.203952 -406.511124) (xy 281.159488 -406.533773)
			(xy 281.112029 -406.549188) (xy 281.062742 -406.556992) (xy 281.037792 -406.55748) (xy 278.18334 -406.55748)
			(xy 278.180546 -406.557734) (xy 278.171247 -406.558785) (xy 278.152566 -406.559928) (xy 278.143208 -406.56002)
			(xy 275.351748 -406.56002) (xy 275.326798 -406.559547) (xy 275.277514 -406.551728) (xy 275.230056 -406.536305)
			(xy 275.185591 -406.513658) (xy 275.145209 -406.484343) (xy 275.127212 -406.467056) (xy 275.08835 -406.428194)
			(xy 275.077488 -406.4181) (xy 275.051415 -406.404014) (xy 275.022395 -406.398003) (xy 274.992872 -406.400573)
			(xy 274.965328 -406.411507) (xy 274.94208 -406.429886) (xy 274.925085 -406.454164) (xy 274.919948 -406.468072)
			(xy 274.906846 -406.505801) (xy 274.873042 -406.578165) (xy 274.831055 -406.646108) (xy 274.781453 -406.70871)
			(xy 274.753578 -406.737312) (xy 274.459335 -407.031749) (xy 304.945298 -407.031749) (xy 304.945298 -406.977251)
			(xy 304.953054 -406.923307) (xy 304.968408 -406.871016) (xy 304.991047 -406.821442) (xy 305.02051 -406.775595)
			(xy 305.056199 -406.734407) (xy 305.097385 -406.698718) (xy 305.143232 -406.669252) (xy 305.192805 -406.646612)
			(xy 305.245095 -406.631257) (xy 305.299039 -406.623499) (xy 305.326288 -406.623012) (xy 306.189888 -406.623012)
			(xy 306.217143 -406.623434) (xy 306.271098 -406.63119) (xy 306.3234 -406.646546) (xy 306.372984 -406.669189)
			(xy 306.418841 -406.698658) (xy 306.460038 -406.734354) (xy 306.495735 -406.775549) (xy 306.525205 -406.821405)
			(xy 306.54785 -406.870989) (xy 306.563207 -406.92329) (xy 306.570965 -406.977245) (xy 306.570965 -407.031753)
			(xy 308.008475 -407.031753) (xy 308.008475 -406.977247) (xy 308.016233 -406.923297) (xy 308.031589 -406.870999)
			(xy 308.054233 -406.82142) (xy 308.083702 -406.775568) (xy 308.119397 -406.734377) (xy 308.16059 -406.698685)
			(xy 308.206445 -406.669219) (xy 308.256026 -406.64658) (xy 308.308324 -406.631227) (xy 308.362275 -406.623473)
			(xy 308.389528 -406.623012) (xy 309.253128 -406.623012) (xy 309.280379 -406.62346) (xy 309.334327 -406.63122)
			(xy 309.386621 -406.646578) (xy 309.436197 -406.669222) (xy 309.482047 -406.698691) (xy 309.523236 -406.734384)
			(xy 309.558926 -406.775576) (xy 309.588391 -406.821427) (xy 309.611032 -406.871005) (xy 309.626386 -406.923301)
			(xy 309.634142 -406.977249) (xy 309.634142 -407.031748) (xy 311.071798 -407.031748) (xy 311.071798 -406.977252)
			(xy 311.079553 -406.92331) (xy 311.094906 -406.87102) (xy 311.117544 -406.821448) (xy 311.147005 -406.775601)
			(xy 311.182692 -406.734414) (xy 311.223876 -406.698725) (xy 311.26972 -406.669259) (xy 311.31929 -406.646617)
			(xy 311.371578 -406.63126) (xy 311.42552 -406.6235) (xy 311.452768 -406.623012) (xy 312.316368 -406.623012)
			(xy 312.343624 -406.623433) (xy 312.397581 -406.631186) (xy 312.449886 -406.64654) (xy 312.499472 -406.669182)
			(xy 312.545332 -406.698651) (xy 312.586531 -406.734347) (xy 312.62223 -406.775542) (xy 312.651702 -406.821399)
			(xy 312.674348 -406.870984) (xy 312.689707 -406.923288) (xy 312.697465 -406.977244) (xy 312.697465 -407.031752)
			(xy 314.134975 -407.031752) (xy 314.134975 -406.977248) (xy 314.142732 -406.923299) (xy 314.158088 -406.871004)
			(xy 314.18073 -406.821426) (xy 314.210197 -406.775575) (xy 314.245889 -406.734384) (xy 314.287081 -406.698692)
			(xy 314.332933 -406.669226) (xy 314.382511 -406.646585) (xy 314.434807 -406.63123) (xy 314.488756 -406.623475)
			(xy 314.516008 -406.623012) (xy 315.379608 -406.623012) (xy 315.40686 -406.623458) (xy 315.46081 -406.631216)
			(xy 315.513107 -406.646573) (xy 315.562685 -406.669216) (xy 315.608537 -406.698684) (xy 315.649729 -406.734377)
			(xy 315.685421 -406.775569) (xy 315.714888 -406.821422) (xy 315.73753 -406.871001) (xy 315.752885 -406.923298)
			(xy 315.760642 -406.977248) (xy 315.760642 -407.031752) (xy 315.760642 -407.031754) (xy 317.198175 -407.031754)
			(xy 317.198175 -406.977246) (xy 317.205933 -406.923294) (xy 317.221291 -406.870995) (xy 317.243936 -406.821414)
			(xy 317.273407 -406.775561) (xy 317.309104 -406.73437) (xy 317.3503 -406.698678) (xy 317.396157 -406.669213)
			(xy 317.44574 -406.646574) (xy 317.498041 -406.631223) (xy 317.551994 -406.623472) (xy 317.579248 -406.623012)
			(xy 318.442848 -406.623012) (xy 318.470098 -406.623461) (xy 318.524044 -406.631224) (xy 318.576336 -406.646584)
			(xy 318.625909 -406.669229) (xy 318.671756 -406.698698) (xy 318.712943 -406.734391) (xy 318.748631 -406.775582)
			(xy 318.778094 -406.821433) (xy 318.800733 -406.87101) (xy 318.816087 -406.923303) (xy 318.823842 -406.97725)
			(xy 318.823842 -407.031749) (xy 320.261498 -407.031749) (xy 320.261498 -406.977251) (xy 320.269254 -406.923307)
			(xy 320.284608 -406.871016) (xy 320.307247 -406.821442) (xy 320.33671 -406.775595) (xy 320.372399 -406.734407)
			(xy 320.413585 -406.698718) (xy 320.459432 -406.669252) (xy 320.509005 -406.646612) (xy 320.561295 -406.631257)
			(xy 320.615239 -406.623499) (xy 320.642488 -406.623012) (xy 321.506088 -406.623012) (xy 321.533343 -406.623434)
			(xy 321.587298 -406.63119) (xy 321.6396 -406.646546) (xy 321.689184 -406.669189) (xy 321.735041 -406.698658)
			(xy 321.776238 -406.734354) (xy 321.811935 -406.775549) (xy 321.841405 -406.821405) (xy 321.86405 -406.870989)
			(xy 321.879407 -406.92329) (xy 321.887165 -406.977245) (xy 321.887165 -407.031753) (xy 323.324675 -407.031753)
			(xy 323.324675 -406.977247) (xy 323.332433 -406.923297) (xy 323.347789 -406.870999) (xy 323.370433 -406.82142)
			(xy 323.399902 -406.775568) (xy 323.435597 -406.734377) (xy 323.47679 -406.698685) (xy 323.522645 -406.669219)
			(xy 323.572226 -406.64658) (xy 323.624524 -406.631227) (xy 323.678475 -406.623473) (xy 323.705728 -406.623012)
			(xy 324.569328 -406.623012) (xy 324.596579 -406.62346) (xy 324.650527 -406.63122) (xy 324.702821 -406.646578)
			(xy 324.752397 -406.669222) (xy 324.798247 -406.698691) (xy 324.839436 -406.734384) (xy 324.875126 -406.775576)
			(xy 324.904591 -406.821427) (xy 324.927232 -406.871005) (xy 324.942586 -406.923301) (xy 324.950342 -406.977249)
			(xy 324.950342 -407.031748) (xy 326.387998 -407.031748) (xy 326.387998 -406.977252) (xy 326.395753 -406.92331)
			(xy 326.411106 -406.87102) (xy 326.433744 -406.821448) (xy 326.463205 -406.775601) (xy 326.498892 -406.734414)
			(xy 326.540076 -406.698725) (xy 326.58592 -406.669259) (xy 326.63549 -406.646617) (xy 326.687778 -406.63126)
			(xy 326.74172 -406.6235) (xy 326.768968 -406.623012) (xy 327.632568 -406.623012) (xy 327.659824 -406.623433)
			(xy 327.713781 -406.631186) (xy 327.766086 -406.64654) (xy 327.815672 -406.669182) (xy 327.861532 -406.698651)
			(xy 327.902731 -406.734347) (xy 327.93843 -406.775542) (xy 327.967902 -406.821399) (xy 327.990548 -406.870984)
			(xy 328.005907 -406.923288) (xy 328.013665 -406.977244) (xy 328.013665 -407.031752) (xy 329.451175 -407.031752)
			(xy 329.451175 -406.977248) (xy 329.458932 -406.923299) (xy 329.474288 -406.871004) (xy 329.49693 -406.821426)
			(xy 329.526397 -406.775575) (xy 329.562089 -406.734384) (xy 329.603281 -406.698692) (xy 329.649133 -406.669226)
			(xy 329.698711 -406.646585) (xy 329.751007 -406.63123) (xy 329.804956 -406.623475) (xy 329.832208 -406.623012)
			(xy 330.695808 -406.623012) (xy 330.72306 -406.623458) (xy 330.77701 -406.631216) (xy 330.829307 -406.646573)
			(xy 330.878885 -406.669216) (xy 330.924737 -406.698684) (xy 330.965929 -406.734377) (xy 331.001621 -406.775569)
			(xy 331.031088 -406.821422) (xy 331.05373 -406.871001) (xy 331.069085 -406.923298) (xy 331.076842 -406.977248)
			(xy 331.076842 -407.031752) (xy 331.076842 -407.031754) (xy 332.514375 -407.031754) (xy 332.514375 -406.977246)
			(xy 332.522133 -406.923294) (xy 332.537491 -406.870995) (xy 332.560136 -406.821414) (xy 332.589607 -406.775561)
			(xy 332.625304 -406.73437) (xy 332.6665 -406.698678) (xy 332.712357 -406.669213) (xy 332.76194 -406.646574)
			(xy 332.814241 -406.631223) (xy 332.868194 -406.623472) (xy 332.895448 -406.623012) (xy 333.759048 -406.623012)
			(xy 333.786298 -406.623461) (xy 333.840244 -406.631224) (xy 333.892536 -406.646584) (xy 333.942109 -406.669229)
			(xy 333.987956 -406.698698) (xy 334.029143 -406.734391) (xy 334.064831 -406.775582) (xy 334.094294 -406.821433)
			(xy 334.116933 -406.87101) (xy 334.132287 -406.923303) (xy 334.140042 -406.97725) (xy 334.140042 -407.031749)
			(xy 335.577698 -407.031749) (xy 335.577698 -406.977251) (xy 335.585454 -406.923307) (xy 335.600808 -406.871016)
			(xy 335.623447 -406.821442) (xy 335.65291 -406.775595) (xy 335.688599 -406.734407) (xy 335.729785 -406.698718)
			(xy 335.775632 -406.669252) (xy 335.825205 -406.646612) (xy 335.877495 -406.631257) (xy 335.931439 -406.623499)
			(xy 335.958688 -406.623012) (xy 336.822288 -406.623012) (xy 336.849543 -406.623434) (xy 336.903498 -406.63119)
			(xy 336.9558 -406.646546) (xy 337.005384 -406.669189) (xy 337.051241 -406.698658) (xy 337.092438 -406.734354)
			(xy 337.128135 -406.775549) (xy 337.157605 -406.821405) (xy 337.18025 -406.870989) (xy 337.195607 -406.92329)
			(xy 337.203365 -406.977245) (xy 337.203365 -407.031753) (xy 338.640875 -407.031753) (xy 338.640875 -406.977247)
			(xy 338.648633 -406.923297) (xy 338.663989 -406.870999) (xy 338.686633 -406.82142) (xy 338.716102 -406.775568)
			(xy 338.751797 -406.734377) (xy 338.79299 -406.698685) (xy 338.838845 -406.669219) (xy 338.888426 -406.64658)
			(xy 338.940724 -406.631227) (xy 338.994675 -406.623473) (xy 339.021928 -406.623012) (xy 339.885528 -406.623012)
			(xy 339.912779 -406.62346) (xy 339.966727 -406.63122) (xy 340.019021 -406.646578) (xy 340.068597 -406.669222)
			(xy 340.114447 -406.698691) (xy 340.155636 -406.734384) (xy 340.191326 -406.775576) (xy 340.220791 -406.821427)
			(xy 340.243432 -406.871005) (xy 340.258786 -406.923301) (xy 340.266542 -406.977249) (xy 340.266542 -407.031748)
			(xy 341.704198 -407.031748) (xy 341.704198 -406.977252) (xy 341.711953 -406.92331) (xy 341.727306 -406.87102)
			(xy 341.749944 -406.821448) (xy 341.779405 -406.775601) (xy 341.815092 -406.734414) (xy 341.856276 -406.698725)
			(xy 341.90212 -406.669259) (xy 341.95169 -406.646617) (xy 342.003978 -406.63126) (xy 342.05792 -406.6235)
			(xy 342.085168 -406.623012) (xy 342.948768 -406.623012) (xy 342.976024 -406.623433) (xy 343.029981 -406.631186)
			(xy 343.082286 -406.64654) (xy 343.131872 -406.669182) (xy 343.177732 -406.698651) (xy 343.218931 -406.734347)
			(xy 343.25463 -406.775542) (xy 343.284102 -406.821399) (xy 343.306748 -406.870984) (xy 343.322107 -406.923288)
			(xy 343.329865 -406.977244) (xy 343.329865 -407.031752) (xy 344.767375 -407.031752) (xy 344.767375 -406.977248)
			(xy 344.775132 -406.923299) (xy 344.790488 -406.871004) (xy 344.81313 -406.821426) (xy 344.842597 -406.775575)
			(xy 344.878289 -406.734384) (xy 344.919481 -406.698692) (xy 344.965333 -406.669226) (xy 345.014911 -406.646585)
			(xy 345.067207 -406.63123) (xy 345.121156 -406.623475) (xy 345.148408 -406.623012) (xy 346.012008 -406.623012)
			(xy 346.03926 -406.623458) (xy 346.09321 -406.631216) (xy 346.145507 -406.646573) (xy 346.195085 -406.669216)
			(xy 346.240937 -406.698684) (xy 346.282129 -406.734377) (xy 346.317821 -406.775569) (xy 346.347288 -406.821422)
			(xy 346.36993 -406.871001) (xy 346.385285 -406.923298) (xy 346.393042 -406.977248) (xy 346.393042 -407.031752)
			(xy 346.393042 -407.031754) (xy 347.830575 -407.031754) (xy 347.830575 -406.977246) (xy 347.838333 -406.923294)
			(xy 347.853691 -406.870995) (xy 347.876336 -406.821414) (xy 347.905807 -406.775561) (xy 347.941504 -406.73437)
			(xy 347.9827 -406.698678) (xy 348.028557 -406.669213) (xy 348.07814 -406.646574) (xy 348.130441 -406.631223)
			(xy 348.184394 -406.623472) (xy 348.211648 -406.623012) (xy 349.075248 -406.623012) (xy 349.102498 -406.623461)
			(xy 349.156444 -406.631224) (xy 349.208736 -406.646584) (xy 349.258309 -406.669229) (xy 349.304156 -406.698698)
			(xy 349.345343 -406.734391) (xy 349.381031 -406.775582) (xy 349.410494 -406.821433) (xy 349.433133 -406.87101)
			(xy 349.448487 -406.923303) (xy 349.456242 -406.97725) (xy 349.456242 -407.031749) (xy 350.893898 -407.031749)
			(xy 350.893898 -406.977251) (xy 350.901654 -406.923307) (xy 350.917008 -406.871016) (xy 350.939647 -406.821442)
			(xy 350.96911 -406.775595) (xy 351.004799 -406.734407) (xy 351.045985 -406.698718) (xy 351.091832 -406.669252)
			(xy 351.141405 -406.646612) (xy 351.193695 -406.631257) (xy 351.247639 -406.623499) (xy 351.274888 -406.623012)
			(xy 352.138488 -406.623012) (xy 352.165743 -406.623434) (xy 352.219698 -406.63119) (xy 352.272 -406.646546)
			(xy 352.321584 -406.669189) (xy 352.367441 -406.698658) (xy 352.408638 -406.734354) (xy 352.444335 -406.775549)
			(xy 352.473805 -406.821405) (xy 352.49645 -406.870989) (xy 352.511807 -406.92329) (xy 352.519565 -406.977245)
			(xy 352.519565 -407.031753) (xy 372.388075 -407.031753) (xy 372.388075 -406.977247) (xy 372.395833 -406.923296)
			(xy 372.411189 -406.870999) (xy 372.433833 -406.821419) (xy 372.463302 -406.775567) (xy 372.498997 -406.734376)
			(xy 372.540191 -406.698684) (xy 372.586046 -406.669219) (xy 372.635627 -406.646579) (xy 372.687926 -406.631226)
			(xy 372.741877 -406.623473) (xy 372.76913 -406.623012) (xy 373.63273 -406.623012) (xy 373.659981 -406.62346)
			(xy 373.713929 -406.63122) (xy 373.766222 -406.646579) (xy 373.815799 -406.669223) (xy 373.861648 -406.698691)
			(xy 373.902836 -406.734385) (xy 373.938527 -406.775576) (xy 373.967992 -406.821428) (xy 373.990632 -406.871006)
			(xy 374.005986 -406.923301) (xy 374.013742 -406.977249) (xy 374.013742 -407.031748) (xy 375.451398 -407.031748)
			(xy 375.451398 -406.977252) (xy 375.459153 -406.923309) (xy 375.474506 -406.87102) (xy 375.497144 -406.821447)
			(xy 375.526606 -406.775601) (xy 375.562292 -406.734414) (xy 375.603477 -406.698724) (xy 375.649321 -406.669258)
			(xy 375.698892 -406.646617) (xy 375.75118 -406.63126) (xy 375.805122 -406.6235) (xy 375.83237 -406.623012)
			(xy 376.69597 -406.623012) (xy 376.723226 -406.623433) (xy 376.777183 -406.631187) (xy 376.829487 -406.646541)
			(xy 376.879074 -406.669183) (xy 376.924933 -406.698652) (xy 376.966131 -406.734347) (xy 377.00183 -406.775543)
			(xy 377.031303 -406.8214) (xy 377.053948 -406.870985) (xy 377.069307 -406.923288) (xy 377.077065 -406.977244)
			(xy 377.077065 -407.031752) (xy 378.514575 -407.031752) (xy 378.514575 -406.977248) (xy 378.522332 -406.923299)
			(xy 378.537688 -406.871003) (xy 378.56033 -406.821425) (xy 378.589797 -406.775574) (xy 378.62549 -406.734383)
			(xy 378.666682 -406.698691) (xy 378.712534 -406.669225) (xy 378.762113 -406.646584) (xy 378.814409 -406.63123)
			(xy 378.868358 -406.623475) (xy 378.89561 -406.623012) (xy 379.75921 -406.623012) (xy 379.786462 -406.623459)
			(xy 379.840412 -406.631217) (xy 379.892708 -406.646573) (xy 379.942287 -406.669216) (xy 379.988138 -406.698684)
			(xy 380.029329 -406.734378) (xy 380.065022 -406.77557) (xy 380.094489 -406.821422) (xy 380.11713 -406.871001)
			(xy 380.132486 -406.923298) (xy 380.140242 -406.977248) (xy 380.140242 -407.031748) (xy 381.577898 -407.031748)
			(xy 381.577898 -406.977252) (xy 381.585653 -406.923312) (xy 381.601005 -406.871024) (xy 381.623641 -406.821453)
			(xy 381.653101 -406.775607) (xy 381.688785 -406.734421) (xy 381.729967 -406.698731) (xy 381.775809 -406.669265)
			(xy 381.825377 -406.646622) (xy 381.877663 -406.631264) (xy 381.931603 -406.623502) (xy 381.95885 -406.623012)
			(xy 382.82245 -406.623012) (xy 382.849707 -406.623431) (xy 382.903666 -406.631183) (xy 382.955973 -406.646536)
			(xy 383.005562 -406.669176) (xy 383.051423 -406.698645) (xy 383.092624 -406.73434) (xy 383.128325 -406.775536)
			(xy 383.1578 -406.821394) (xy 383.180447 -406.870981) (xy 383.195806 -406.923285) (xy 383.203565 -406.977243)
			(xy 383.203565 -407.031749) (xy 384.641098 -407.031749) (xy 384.641098 -406.977251) (xy 384.648854 -406.923307)
			(xy 384.664208 -406.871016) (xy 384.686847 -406.821442) (xy 384.716311 -406.775594) (xy 384.751999 -406.734406)
			(xy 384.793186 -406.698717) (xy 384.839033 -406.669252) (xy 384.888606 -406.646611) (xy 384.940897 -406.631256)
			(xy 384.994841 -406.623499) (xy 385.02209 -406.623012) (xy 385.88569 -406.623012) (xy 385.912945 -406.623434)
			(xy 385.9669 -406.63119) (xy 386.019202 -406.646546) (xy 386.068786 -406.66919) (xy 386.114642 -406.698659)
			(xy 386.155838 -406.734354) (xy 386.191535 -406.77555) (xy 386.221006 -406.821406) (xy 386.24365 -406.870989)
			(xy 386.259007 -406.923291) (xy 386.266765 -406.977245) (xy 386.266765 -407.031753) (xy 387.704275 -407.031753)
			(xy 387.704275 -406.977247) (xy 387.712033 -406.923296) (xy 387.727389 -406.870999) (xy 387.750033 -406.821419)
			(xy 387.779502 -406.775567) (xy 387.815197 -406.734376) (xy 387.856391 -406.698684) (xy 387.902246 -406.669219)
			(xy 387.951827 -406.646579) (xy 388.004126 -406.631226) (xy 388.058077 -406.623473) (xy 388.08533 -406.623012)
			(xy 388.94893 -406.623012) (xy 388.976181 -406.62346) (xy 389.030129 -406.63122) (xy 389.082422 -406.646579)
			(xy 389.131999 -406.669223) (xy 389.177848 -406.698691) (xy 389.219036 -406.734385) (xy 389.254727 -406.775576)
			(xy 389.284192 -406.821428) (xy 389.306832 -406.871006) (xy 389.322186 -406.923301) (xy 389.329942 -406.977249)
			(xy 389.329942 -407.031748) (xy 390.767598 -407.031748) (xy 390.767598 -406.977252) (xy 390.775353 -406.923309)
			(xy 390.790706 -406.87102) (xy 390.813344 -406.821447) (xy 390.842806 -406.775601) (xy 390.878492 -406.734414)
			(xy 390.919677 -406.698724) (xy 390.965521 -406.669258) (xy 391.015092 -406.646617) (xy 391.06738 -406.63126)
			(xy 391.121322 -406.6235) (xy 391.14857 -406.623012) (xy 392.01217 -406.623012) (xy 392.039426 -406.623433)
			(xy 392.093383 -406.631187) (xy 392.145687 -406.646541) (xy 392.195274 -406.669183) (xy 392.241133 -406.698652)
			(xy 392.282331 -406.734347) (xy 392.31803 -406.775543) (xy 392.347503 -406.8214) (xy 392.370148 -406.870985)
			(xy 392.385507 -406.923288) (xy 392.393265 -406.977244) (xy 392.393265 -407.031752) (xy 393.830775 -407.031752)
			(xy 393.830775 -406.977248) (xy 393.838532 -406.923299) (xy 393.853888 -406.871003) (xy 393.87653 -406.821425)
			(xy 393.905997 -406.775574) (xy 393.94169 -406.734383) (xy 393.982882 -406.698691) (xy 394.028734 -406.669225)
			(xy 394.078313 -406.646584) (xy 394.130609 -406.63123) (xy 394.184558 -406.623475) (xy 394.21181 -406.623012)
			(xy 395.07541 -406.623012) (xy 395.102662 -406.623459) (xy 395.156612 -406.631217) (xy 395.208908 -406.646573)
			(xy 395.258487 -406.669216) (xy 395.304338 -406.698684) (xy 395.345529 -406.734378) (xy 395.381222 -406.77557)
			(xy 395.410689 -406.821422) (xy 395.43333 -406.871001) (xy 395.448686 -406.923298) (xy 395.456442 -406.977248)
			(xy 395.456442 -407.031748) (xy 396.894098 -407.031748) (xy 396.894098 -406.977252) (xy 396.901853 -406.923312)
			(xy 396.917205 -406.871024) (xy 396.939841 -406.821453) (xy 396.969301 -406.775607) (xy 397.004985 -406.734421)
			(xy 397.046167 -406.698731) (xy 397.092009 -406.669265) (xy 397.141577 -406.646622) (xy 397.193863 -406.631264)
			(xy 397.247803 -406.623502) (xy 397.27505 -406.623012) (xy 398.13865 -406.623012) (xy 398.165907 -406.623431)
			(xy 398.219866 -406.631183) (xy 398.272173 -406.646536) (xy 398.321762 -406.669176) (xy 398.367623 -406.698645)
			(xy 398.408824 -406.73434) (xy 398.444525 -406.775536) (xy 398.474 -406.821394) (xy 398.496647 -406.870981)
			(xy 398.512006 -406.923285) (xy 398.519765 -406.977243) (xy 398.519765 -407.031749) (xy 399.957298 -407.031749)
			(xy 399.957298 -406.977251) (xy 399.965054 -406.923307) (xy 399.980408 -406.871016) (xy 400.003047 -406.821442)
			(xy 400.032511 -406.775594) (xy 400.068199 -406.734406) (xy 400.109386 -406.698717) (xy 400.155233 -406.669252)
			(xy 400.204806 -406.646611) (xy 400.257097 -406.631256) (xy 400.311041 -406.623499) (xy 400.33829 -406.623012)
			(xy 401.20189 -406.623012) (xy 401.229145 -406.623434) (xy 401.2831 -406.63119) (xy 401.335402 -406.646546)
			(xy 401.384986 -406.66919) (xy 401.430842 -406.698659) (xy 401.472038 -406.734354) (xy 401.507735 -406.77555)
			(xy 401.537206 -406.821406) (xy 401.55985 -406.870989) (xy 401.575207 -406.923291) (xy 401.582965 -406.977245)
			(xy 401.582965 -407.031753) (xy 403.020475 -407.031753) (xy 403.020475 -406.977247) (xy 403.028233 -406.923296)
			(xy 403.043589 -406.870999) (xy 403.066233 -406.821419) (xy 403.095702 -406.775567) (xy 403.131397 -406.734376)
			(xy 403.172591 -406.698684) (xy 403.218446 -406.669219) (xy 403.268027 -406.646579) (xy 403.320326 -406.631226)
			(xy 403.374277 -406.623473) (xy 403.40153 -406.623012) (xy 404.26513 -406.623012) (xy 404.292381 -406.62346)
			(xy 404.346329 -406.63122) (xy 404.398622 -406.646579) (xy 404.448199 -406.669223) (xy 404.494048 -406.698691)
			(xy 404.535236 -406.734385) (xy 404.570927 -406.775576) (xy 404.600392 -406.821428) (xy 404.623032 -406.871006)
			(xy 404.638386 -406.923301) (xy 404.646142 -406.977249) (xy 404.646142 -407.031748) (xy 406.083798 -407.031748)
			(xy 406.083798 -406.977252) (xy 406.091553 -406.923309) (xy 406.106906 -406.87102) (xy 406.129544 -406.821447)
			(xy 406.159006 -406.775601) (xy 406.194692 -406.734414) (xy 406.235877 -406.698724) (xy 406.281721 -406.669258)
			(xy 406.331292 -406.646617) (xy 406.38358 -406.63126) (xy 406.437522 -406.6235) (xy 406.46477 -406.623012)
			(xy 407.32837 -406.623012) (xy 407.355626 -406.623433) (xy 407.409583 -406.631187) (xy 407.461887 -406.646541)
			(xy 407.511474 -406.669183) (xy 407.557333 -406.698652) (xy 407.598531 -406.734347) (xy 407.63423 -406.775543)
			(xy 407.663703 -406.8214) (xy 407.686348 -406.870985) (xy 407.701707 -406.923288) (xy 407.709465 -406.977244)
			(xy 407.709465 -407.031752) (xy 409.146975 -407.031752) (xy 409.146975 -406.977248) (xy 409.154732 -406.923299)
			(xy 409.170088 -406.871003) (xy 409.19273 -406.821425) (xy 409.222197 -406.775574) (xy 409.25789 -406.734383)
			(xy 409.299082 -406.698691) (xy 409.344934 -406.669225) (xy 409.394513 -406.646584) (xy 409.446809 -406.63123)
			(xy 409.500758 -406.623475) (xy 409.52801 -406.623012) (xy 410.39161 -406.623012) (xy 410.418862 -406.623459)
			(xy 410.472812 -406.631217) (xy 410.525108 -406.646573) (xy 410.574687 -406.669216) (xy 410.620538 -406.698684)
			(xy 410.661729 -406.734378) (xy 410.697422 -406.77557) (xy 410.726889 -406.821422) (xy 410.74953 -406.871001)
			(xy 410.764886 -406.923298) (xy 410.772642 -406.977248) (xy 410.772642 -407.031748) (xy 412.210298 -407.031748)
			(xy 412.210298 -406.977252) (xy 412.218053 -406.923312) (xy 412.233405 -406.871024) (xy 412.256041 -406.821453)
			(xy 412.285501 -406.775607) (xy 412.321185 -406.734421) (xy 412.362367 -406.698731) (xy 412.408209 -406.669265)
			(xy 412.457777 -406.646622) (xy 412.510063 -406.631264) (xy 412.564003 -406.623502) (xy 412.59125 -406.623012)
			(xy 413.45485 -406.623012) (xy 413.482107 -406.623431) (xy 413.536066 -406.631183) (xy 413.588373 -406.646536)
			(xy 413.637962 -406.669176) (xy 413.683823 -406.698645) (xy 413.725024 -406.73434) (xy 413.760725 -406.775536)
			(xy 413.7902 -406.821394) (xy 413.812847 -406.870981) (xy 413.828206 -406.923285) (xy 413.835965 -406.977243)
			(xy 413.835965 -407.031749) (xy 415.273498 -407.031749) (xy 415.273498 -406.977251) (xy 415.281254 -406.923307)
			(xy 415.296608 -406.871016) (xy 415.319247 -406.821442) (xy 415.348711 -406.775594) (xy 415.384399 -406.734406)
			(xy 415.425586 -406.698717) (xy 415.471433 -406.669252) (xy 415.521006 -406.646611) (xy 415.573297 -406.631256)
			(xy 415.627241 -406.623499) (xy 415.65449 -406.623012) (xy 416.51809 -406.623012) (xy 416.545345 -406.623434)
			(xy 416.5993 -406.63119) (xy 416.651602 -406.646546) (xy 416.701186 -406.66919) (xy 416.747042 -406.698659)
			(xy 416.788238 -406.734354) (xy 416.823935 -406.77555) (xy 416.853406 -406.821406) (xy 416.87605 -406.870989)
			(xy 416.891407 -406.923291) (xy 416.899165 -406.977245) (xy 416.899165 -407.031753) (xy 418.336675 -407.031753)
			(xy 418.336675 -406.977247) (xy 418.344433 -406.923296) (xy 418.359789 -406.870999) (xy 418.382433 -406.821419)
			(xy 418.411902 -406.775567) (xy 418.447597 -406.734376) (xy 418.488791 -406.698684) (xy 418.534646 -406.669219)
			(xy 418.584227 -406.646579) (xy 418.636526 -406.631226) (xy 418.690477 -406.623473) (xy 418.71773 -406.623012)
			(xy 419.58133 -406.623012) (xy 419.608581 -406.62346) (xy 419.662529 -406.63122) (xy 419.714822 -406.646579)
			(xy 419.764399 -406.669223) (xy 419.810248 -406.698691) (xy 419.851436 -406.734385) (xy 419.887127 -406.775576)
			(xy 419.916592 -406.821428) (xy 419.939232 -406.871006) (xy 419.954586 -406.923301) (xy 419.962342 -406.977249)
			(xy 419.962342 -407.031751) (xy 419.954586 -407.085699) (xy 419.939232 -407.137994) (xy 419.916592 -407.187572)
			(xy 419.887127 -407.233424) (xy 419.851436 -407.274615) (xy 419.810248 -407.310309) (xy 419.764399 -407.339777)
			(xy 419.714822 -407.362421) (xy 419.662529 -407.37778) (xy 419.608581 -407.38554) (xy 419.58133 -407.386028)
			(xy 418.71773 -407.386028) (xy 418.690477 -407.385527) (xy 418.636526 -407.377774) (xy 418.584227 -407.362421)
			(xy 418.534646 -407.339781) (xy 418.488791 -407.310316) (xy 418.447597 -407.274624) (xy 418.411902 -407.233433)
			(xy 418.382433 -407.187581) (xy 418.359789 -407.138001) (xy 418.344433 -407.085704) (xy 418.336675 -407.031753)
			(xy 416.899165 -407.031753) (xy 416.899165 -407.031755) (xy 416.891407 -407.085709) (xy 416.87605 -407.138011)
			(xy 416.853406 -407.187594) (xy 416.823935 -407.23345) (xy 416.788238 -407.274646) (xy 416.747042 -407.310341)
			(xy 416.701186 -407.33981) (xy 416.651602 -407.362454) (xy 416.5993 -407.37781) (xy 416.545345 -407.385566)
			(xy 416.51809 -407.386028) (xy 415.65449 -407.386028) (xy 415.627241 -407.385501) (xy 415.573297 -407.377744)
			(xy 415.521006 -407.362389) (xy 415.471433 -407.339748) (xy 415.425586 -407.310283) (xy 415.384399 -407.274594)
			(xy 415.348711 -407.233406) (xy 415.319247 -407.187558) (xy 415.296608 -407.137984) (xy 415.281254 -407.085693)
			(xy 415.273498 -407.031749) (xy 413.835965 -407.031749) (xy 413.835965 -407.031757) (xy 413.828206 -407.085715)
			(xy 413.812847 -407.138019) (xy 413.7902 -407.187606) (xy 413.760725 -407.233464) (xy 413.725024 -407.27466)
			(xy 413.683823 -407.310355) (xy 413.637962 -407.339824) (xy 413.588373 -407.362464) (xy 413.536066 -407.377817)
			(xy 413.482107 -407.385569) (xy 413.45485 -407.386028) (xy 412.59125 -407.386028) (xy 412.564003 -407.385498)
			(xy 412.510063 -407.377736) (xy 412.457777 -407.362378) (xy 412.408209 -407.339735) (xy 412.362367 -407.310269)
			(xy 412.321185 -407.274579) (xy 412.285501 -407.233393) (xy 412.256041 -407.187547) (xy 412.233405 -407.137976)
			(xy 412.218053 -407.085688) (xy 412.210298 -407.031748) (xy 410.772642 -407.031748) (xy 410.772642 -407.031752)
			(xy 410.764886 -407.085702) (xy 410.74953 -407.137999) (xy 410.726889 -407.187578) (xy 410.697422 -407.23343)
			(xy 410.661729 -407.274622) (xy 410.620538 -407.310316) (xy 410.574687 -407.339784) (xy 410.525108 -407.362427)
			(xy 410.472812 -407.377783) (xy 410.418862 -407.385541) (xy 410.39161 -407.386028) (xy 409.52801 -407.386028)
			(xy 409.500758 -407.385525) (xy 409.446809 -407.37777) (xy 409.394513 -407.362416) (xy 409.344934 -407.339775)
			(xy 409.299082 -407.310309) (xy 409.25789 -407.274617) (xy 409.222197 -407.233426) (xy 409.19273 -407.187575)
			(xy 409.170088 -407.137997) (xy 409.154732 -407.085701) (xy 409.146975 -407.031752) (xy 407.709465 -407.031752)
			(xy 407.709465 -407.031756) (xy 407.701707 -407.085712) (xy 407.686348 -407.138015) (xy 407.663703 -407.1876)
			(xy 407.63423 -407.233457) (xy 407.598531 -407.274653) (xy 407.557333 -407.310348) (xy 407.511474 -407.339817)
			(xy 407.461887 -407.362459) (xy 407.409583 -407.377813) (xy 407.355626 -407.385567) (xy 407.32837 -407.386028)
			(xy 406.46477 -407.386028) (xy 406.437522 -407.3855) (xy 406.38358 -407.37774) (xy 406.331292 -407.362383)
			(xy 406.281721 -407.339742) (xy 406.235877 -407.310276) (xy 406.194692 -407.274586) (xy 406.159006 -407.233399)
			(xy 406.129544 -407.187553) (xy 406.106906 -407.13798) (xy 406.091553 -407.085691) (xy 406.083798 -407.031748)
			(xy 404.646142 -407.031748) (xy 404.646142 -407.031751) (xy 404.638386 -407.085699) (xy 404.623032 -407.137994)
			(xy 404.600392 -407.187572) (xy 404.570927 -407.233424) (xy 404.535236 -407.274615) (xy 404.494048 -407.310309)
			(xy 404.448199 -407.339777) (xy 404.398622 -407.362421) (xy 404.346329 -407.37778) (xy 404.292381 -407.38554)
			(xy 404.26513 -407.386028) (xy 403.40153 -407.386028) (xy 403.374277 -407.385527) (xy 403.320326 -407.377774)
			(xy 403.268027 -407.362421) (xy 403.218446 -407.339781) (xy 403.172591 -407.310316) (xy 403.131397 -407.274624)
			(xy 403.095702 -407.233433) (xy 403.066233 -407.187581) (xy 403.043589 -407.138001) (xy 403.028233 -407.085704)
			(xy 403.020475 -407.031753) (xy 401.582965 -407.031753) (xy 401.582965 -407.031755) (xy 401.575207 -407.085709)
			(xy 401.55985 -407.138011) (xy 401.537206 -407.187594) (xy 401.507735 -407.23345) (xy 401.472038 -407.274646)
			(xy 401.430842 -407.310341) (xy 401.384986 -407.33981) (xy 401.335402 -407.362454) (xy 401.2831 -407.37781)
			(xy 401.229145 -407.385566) (xy 401.20189 -407.386028) (xy 400.33829 -407.386028) (xy 400.311041 -407.385501)
			(xy 400.257097 -407.377744) (xy 400.204806 -407.362389) (xy 400.155233 -407.339748) (xy 400.109386 -407.310283)
			(xy 400.068199 -407.274594) (xy 400.032511 -407.233406) (xy 400.003047 -407.187558) (xy 399.980408 -407.137984)
			(xy 399.965054 -407.085693) (xy 399.957298 -407.031749) (xy 398.519765 -407.031749) (xy 398.519765 -407.031757)
			(xy 398.512006 -407.085715) (xy 398.496647 -407.138019) (xy 398.474 -407.187606) (xy 398.444525 -407.233464)
			(xy 398.408824 -407.27466) (xy 398.367623 -407.310355) (xy 398.321762 -407.339824) (xy 398.272173 -407.362464)
			(xy 398.219866 -407.377817) (xy 398.165907 -407.385569) (xy 398.13865 -407.386028) (xy 397.27505 -407.386028)
			(xy 397.247803 -407.385498) (xy 397.193863 -407.377736) (xy 397.141577 -407.362378) (xy 397.092009 -407.339735)
			(xy 397.046167 -407.310269) (xy 397.004985 -407.274579) (xy 396.969301 -407.233393) (xy 396.939841 -407.187547)
			(xy 396.917205 -407.137976) (xy 396.901853 -407.085688) (xy 396.894098 -407.031748) (xy 395.456442 -407.031748)
			(xy 395.456442 -407.031752) (xy 395.448686 -407.085702) (xy 395.43333 -407.137999) (xy 395.410689 -407.187578)
			(xy 395.381222 -407.23343) (xy 395.345529 -407.274622) (xy 395.304338 -407.310316) (xy 395.258487 -407.339784)
			(xy 395.208908 -407.362427) (xy 395.156612 -407.377783) (xy 395.102662 -407.385541) (xy 395.07541 -407.386028)
			(xy 394.21181 -407.386028) (xy 394.184558 -407.385525) (xy 394.130609 -407.37777) (xy 394.078313 -407.362416)
			(xy 394.028734 -407.339775) (xy 393.982882 -407.310309) (xy 393.94169 -407.274617) (xy 393.905997 -407.233426)
			(xy 393.87653 -407.187575) (xy 393.853888 -407.137997) (xy 393.838532 -407.085701) (xy 393.830775 -407.031752)
			(xy 392.393265 -407.031752) (xy 392.393265 -407.031756) (xy 392.385507 -407.085712) (xy 392.370148 -407.138015)
			(xy 392.347503 -407.1876) (xy 392.31803 -407.233457) (xy 392.282331 -407.274653) (xy 392.241133 -407.310348)
			(xy 392.195274 -407.339817) (xy 392.145687 -407.362459) (xy 392.093383 -407.377813) (xy 392.039426 -407.385567)
			(xy 392.01217 -407.386028) (xy 391.14857 -407.386028) (xy 391.121322 -407.3855) (xy 391.06738 -407.37774)
			(xy 391.015092 -407.362383) (xy 390.965521 -407.339742) (xy 390.919677 -407.310276) (xy 390.878492 -407.274586)
			(xy 390.842806 -407.233399) (xy 390.813344 -407.187553) (xy 390.790706 -407.13798) (xy 390.775353 -407.085691)
			(xy 390.767598 -407.031748) (xy 389.329942 -407.031748) (xy 389.329942 -407.031751) (xy 389.322186 -407.085699)
			(xy 389.306832 -407.137994) (xy 389.284192 -407.187572) (xy 389.254727 -407.233424) (xy 389.219036 -407.274615)
			(xy 389.177848 -407.310309) (xy 389.131999 -407.339777) (xy 389.082422 -407.362421) (xy 389.030129 -407.37778)
			(xy 388.976181 -407.38554) (xy 388.94893 -407.386028) (xy 388.08533 -407.386028) (xy 388.058077 -407.385527)
			(xy 388.004126 -407.377774) (xy 387.951827 -407.362421) (xy 387.902246 -407.339781) (xy 387.856391 -407.310316)
			(xy 387.815197 -407.274624) (xy 387.779502 -407.233433) (xy 387.750033 -407.187581) (xy 387.727389 -407.138001)
			(xy 387.712033 -407.085704) (xy 387.704275 -407.031753) (xy 386.266765 -407.031753) (xy 386.266765 -407.031755)
			(xy 386.259007 -407.085709) (xy 386.24365 -407.138011) (xy 386.221006 -407.187594) (xy 386.191535 -407.23345)
			(xy 386.155838 -407.274646) (xy 386.114642 -407.310341) (xy 386.068786 -407.33981) (xy 386.019202 -407.362454)
			(xy 385.9669 -407.37781) (xy 385.912945 -407.385566) (xy 385.88569 -407.386028) (xy 385.02209 -407.386028)
			(xy 384.994841 -407.385501) (xy 384.940897 -407.377744) (xy 384.888606 -407.362389) (xy 384.839033 -407.339748)
			(xy 384.793186 -407.310283) (xy 384.751999 -407.274594) (xy 384.716311 -407.233406) (xy 384.686847 -407.187558)
			(xy 384.664208 -407.137984) (xy 384.648854 -407.085693) (xy 384.641098 -407.031749) (xy 383.203565 -407.031749)
			(xy 383.203565 -407.031757) (xy 383.195806 -407.085715) (xy 383.180447 -407.138019) (xy 383.1578 -407.187606)
			(xy 383.128325 -407.233464) (xy 383.092624 -407.27466) (xy 383.051423 -407.310355) (xy 383.005562 -407.339824)
			(xy 382.955973 -407.362464) (xy 382.903666 -407.377817) (xy 382.849707 -407.385569) (xy 382.82245 -407.386028)
			(xy 381.95885 -407.386028) (xy 381.931603 -407.385498) (xy 381.877663 -407.377736) (xy 381.825377 -407.362378)
			(xy 381.775809 -407.339735) (xy 381.729967 -407.310269) (xy 381.688785 -407.274579) (xy 381.653101 -407.233393)
			(xy 381.623641 -407.187547) (xy 381.601005 -407.137976) (xy 381.585653 -407.085688) (xy 381.577898 -407.031748)
			(xy 380.140242 -407.031748) (xy 380.140242 -407.031752) (xy 380.132486 -407.085702) (xy 380.11713 -407.137999)
			(xy 380.094489 -407.187578) (xy 380.065022 -407.23343) (xy 380.029329 -407.274622) (xy 379.988138 -407.310316)
			(xy 379.942287 -407.339784) (xy 379.892708 -407.362427) (xy 379.840412 -407.377783) (xy 379.786462 -407.385541)
			(xy 379.75921 -407.386028) (xy 378.89561 -407.386028) (xy 378.868358 -407.385525) (xy 378.814409 -407.37777)
			(xy 378.762113 -407.362416) (xy 378.712534 -407.339775) (xy 378.666682 -407.310309) (xy 378.62549 -407.274617)
			(xy 378.589797 -407.233426) (xy 378.56033 -407.187575) (xy 378.537688 -407.137997) (xy 378.522332 -407.085701)
			(xy 378.514575 -407.031752) (xy 377.077065 -407.031752) (xy 377.077065 -407.031756) (xy 377.069307 -407.085712)
			(xy 377.053948 -407.138015) (xy 377.031303 -407.1876) (xy 377.00183 -407.233457) (xy 376.966131 -407.274653)
			(xy 376.924933 -407.310348) (xy 376.879074 -407.339817) (xy 376.829487 -407.362459) (xy 376.777183 -407.377813)
			(xy 376.723226 -407.385567) (xy 376.69597 -407.386028) (xy 375.83237 -407.386028) (xy 375.805122 -407.3855)
			(xy 375.75118 -407.37774) (xy 375.698892 -407.362383) (xy 375.649321 -407.339742) (xy 375.603477 -407.310276)
			(xy 375.562292 -407.274586) (xy 375.526606 -407.233399) (xy 375.497144 -407.187553) (xy 375.474506 -407.13798)
			(xy 375.459153 -407.085691) (xy 375.451398 -407.031748) (xy 374.013742 -407.031748) (xy 374.013742 -407.031751)
			(xy 374.005986 -407.085699) (xy 373.990632 -407.137994) (xy 373.967992 -407.187572) (xy 373.938527 -407.233424)
			(xy 373.902836 -407.274615) (xy 373.861648 -407.310309) (xy 373.815799 -407.339777) (xy 373.766222 -407.362421)
			(xy 373.713929 -407.37778) (xy 373.659981 -407.38554) (xy 373.63273 -407.386028) (xy 372.76913 -407.386028)
			(xy 372.741877 -407.385527) (xy 372.687926 -407.377774) (xy 372.635627 -407.362421) (xy 372.586046 -407.339781)
			(xy 372.540191 -407.310316) (xy 372.498997 -407.274624) (xy 372.463302 -407.233433) (xy 372.433833 -407.187581)
			(xy 372.411189 -407.138001) (xy 372.395833 -407.085704) (xy 372.388075 -407.031753) (xy 352.519565 -407.031753)
			(xy 352.519565 -407.031755) (xy 352.511807 -407.08571) (xy 352.49645 -407.138011) (xy 352.473805 -407.187595)
			(xy 352.444335 -407.233451) (xy 352.408638 -407.274646) (xy 352.367441 -407.310342) (xy 352.321584 -407.339811)
			(xy 352.272 -407.362454) (xy 352.219698 -407.37781) (xy 352.165743 -407.385566) (xy 352.138488 -407.386028)
			(xy 351.274888 -407.386028) (xy 351.247639 -407.385501) (xy 351.193695 -407.377743) (xy 351.141405 -407.362388)
			(xy 351.091832 -407.339748) (xy 351.045985 -407.310282) (xy 351.004799 -407.274593) (xy 350.96911 -407.233405)
			(xy 350.939647 -407.187558) (xy 350.917008 -407.137984) (xy 350.901654 -407.085693) (xy 350.893898 -407.031749)
			(xy 349.456242 -407.031749) (xy 349.456242 -407.03175) (xy 349.448487 -407.085697) (xy 349.433133 -407.137991)
			(xy 349.410494 -407.187567) (xy 349.381031 -407.233418) (xy 349.345343 -407.274609) (xy 349.304156 -407.310302)
			(xy 349.258309 -407.339771) (xy 349.208736 -407.362416) (xy 349.156444 -407.377776) (xy 349.102498 -407.385539)
			(xy 349.075248 -407.386028) (xy 348.211648 -407.386028) (xy 348.184394 -407.385528) (xy 348.130441 -407.377777)
			(xy 348.07814 -407.362426) (xy 348.028557 -407.339787) (xy 347.9827 -407.310322) (xy 347.941504 -407.27463)
			(xy 347.905807 -407.233439) (xy 347.876336 -407.187586) (xy 347.853691 -407.138005) (xy 347.838333 -407.085706)
			(xy 347.830575 -407.031754) (xy 346.393042 -407.031754) (xy 346.385285 -407.085702) (xy 346.36993 -407.137999)
			(xy 346.347288 -407.187578) (xy 346.317821 -407.233431) (xy 346.282129 -407.274623) (xy 346.240937 -407.310316)
			(xy 346.195085 -407.339784) (xy 346.145507 -407.362427) (xy 346.09321 -407.377784) (xy 346.03926 -407.385542)
			(xy 346.012008 -407.386028) (xy 345.148408 -407.386028) (xy 345.121156 -407.385525) (xy 345.067207 -407.37777)
			(xy 345.014911 -407.362415) (xy 344.965333 -407.339774) (xy 344.919481 -407.310308) (xy 344.878289 -407.274616)
			(xy 344.842597 -407.233425) (xy 344.81313 -407.187574) (xy 344.790488 -407.137996) (xy 344.775132 -407.085701)
			(xy 344.767375 -407.031752) (xy 343.329865 -407.031752) (xy 343.329865 -407.031756) (xy 343.322107 -407.085712)
			(xy 343.306748 -407.138016) (xy 343.284102 -407.187601) (xy 343.25463 -407.233458) (xy 343.218931 -407.274653)
			(xy 343.177732 -407.310349) (xy 343.131872 -407.339818) (xy 343.082286 -407.36246) (xy 343.029981 -407.377814)
			(xy 342.976024 -407.385567) (xy 342.948768 -407.386028) (xy 342.085168 -407.386028) (xy 342.05792 -407.3855)
			(xy 342.003978 -407.37774) (xy 341.95169 -407.362383) (xy 341.90212 -407.339741) (xy 341.856276 -407.310275)
			(xy 341.815092 -407.274586) (xy 341.779405 -407.233399) (xy 341.749944 -407.187552) (xy 341.727306 -407.13798)
			(xy 341.711953 -407.08569) (xy 341.704198 -407.031748) (xy 340.266542 -407.031748) (xy 340.266542 -407.031751)
			(xy 340.258786 -407.0857) (xy 340.243432 -407.137995) (xy 340.220791 -407.187573) (xy 340.191326 -407.233424)
			(xy 340.155636 -407.274616) (xy 340.114447 -407.310309) (xy 340.068597 -407.339778) (xy 340.019021 -407.362422)
			(xy 339.966727 -407.37778) (xy 339.912779 -407.38554) (xy 339.885528 -407.386028) (xy 339.021928 -407.386028)
			(xy 338.994675 -407.385527) (xy 338.940724 -407.377773) (xy 338.888426 -407.36242) (xy 338.838845 -407.339781)
			(xy 338.79299 -407.310315) (xy 338.751797 -407.274623) (xy 338.716102 -407.233432) (xy 338.686633 -407.18758)
			(xy 338.663989 -407.138001) (xy 338.648633 -407.085703) (xy 338.640875 -407.031753) (xy 337.203365 -407.031753)
			(xy 337.203365 -407.031755) (xy 337.195607 -407.08571) (xy 337.18025 -407.138011) (xy 337.157605 -407.187595)
			(xy 337.128135 -407.233451) (xy 337.092438 -407.274646) (xy 337.051241 -407.310342) (xy 337.005384 -407.339811)
			(xy 336.9558 -407.362454) (xy 336.903498 -407.37781) (xy 336.849543 -407.385566) (xy 336.822288 -407.386028)
			(xy 335.958688 -407.386028) (xy 335.931439 -407.385501) (xy 335.877495 -407.377743) (xy 335.825205 -407.362388)
			(xy 335.775632 -407.339748) (xy 335.729785 -407.310282) (xy 335.688599 -407.274593) (xy 335.65291 -407.233405)
			(xy 335.623447 -407.187558) (xy 335.600808 -407.137984) (xy 335.585454 -407.085693) (xy 335.577698 -407.031749)
			(xy 334.140042 -407.031749) (xy 334.140042 -407.03175) (xy 334.132287 -407.085697) (xy 334.116933 -407.137991)
			(xy 334.094294 -407.187567) (xy 334.064831 -407.233418) (xy 334.029143 -407.274609) (xy 333.987956 -407.310302)
			(xy 333.942109 -407.339771) (xy 333.892536 -407.362416) (xy 333.840244 -407.377776) (xy 333.786298 -407.385539)
			(xy 333.759048 -407.386028) (xy 332.895448 -407.386028) (xy 332.868194 -407.385528) (xy 332.814241 -407.377777)
			(xy 332.76194 -407.362426) (xy 332.712357 -407.339787) (xy 332.6665 -407.310322) (xy 332.625304 -407.27463)
			(xy 332.589607 -407.233439) (xy 332.560136 -407.187586) (xy 332.537491 -407.138005) (xy 332.522133 -407.085706)
			(xy 332.514375 -407.031754) (xy 331.076842 -407.031754) (xy 331.069085 -407.085702) (xy 331.05373 -407.137999)
			(xy 331.031088 -407.187578) (xy 331.001621 -407.233431) (xy 330.965929 -407.274623) (xy 330.924737 -407.310316)
			(xy 330.878885 -407.339784) (xy 330.829307 -407.362427) (xy 330.77701 -407.377784) (xy 330.72306 -407.385542)
			(xy 330.695808 -407.386028) (xy 329.832208 -407.386028) (xy 329.804956 -407.385525) (xy 329.751007 -407.37777)
			(xy 329.698711 -407.362415) (xy 329.649133 -407.339774) (xy 329.603281 -407.310308) (xy 329.562089 -407.274616)
			(xy 329.526397 -407.233425) (xy 329.49693 -407.187574) (xy 329.474288 -407.137996) (xy 329.458932 -407.085701)
			(xy 329.451175 -407.031752) (xy 328.013665 -407.031752) (xy 328.013665 -407.031756) (xy 328.005907 -407.085712)
			(xy 327.990548 -407.138016) (xy 327.967902 -407.187601) (xy 327.93843 -407.233458) (xy 327.902731 -407.274653)
			(xy 327.861532 -407.310349) (xy 327.815672 -407.339818) (xy 327.766086 -407.36246) (xy 327.713781 -407.377814)
			(xy 327.659824 -407.385567) (xy 327.632568 -407.386028) (xy 326.768968 -407.386028) (xy 326.74172 -407.3855)
			(xy 326.687778 -407.37774) (xy 326.63549 -407.362383) (xy 326.58592 -407.339741) (xy 326.540076 -407.310275)
			(xy 326.498892 -407.274586) (xy 326.463205 -407.233399) (xy 326.433744 -407.187552) (xy 326.411106 -407.13798)
			(xy 326.395753 -407.08569) (xy 326.387998 -407.031748) (xy 324.950342 -407.031748) (xy 324.950342 -407.031751)
			(xy 324.942586 -407.0857) (xy 324.927232 -407.137995) (xy 324.904591 -407.187573) (xy 324.875126 -407.233424)
			(xy 324.839436 -407.274616) (xy 324.798247 -407.310309) (xy 324.752397 -407.339778) (xy 324.702821 -407.362422)
			(xy 324.650527 -407.37778) (xy 324.596579 -407.38554) (xy 324.569328 -407.386028) (xy 323.705728 -407.386028)
			(xy 323.678475 -407.385527) (xy 323.624524 -407.377773) (xy 323.572226 -407.36242) (xy 323.522645 -407.339781)
			(xy 323.47679 -407.310315) (xy 323.435597 -407.274623) (xy 323.399902 -407.233432) (xy 323.370433 -407.18758)
			(xy 323.347789 -407.138001) (xy 323.332433 -407.085703) (xy 323.324675 -407.031753) (xy 321.887165 -407.031753)
			(xy 321.887165 -407.031755) (xy 321.879407 -407.08571) (xy 321.86405 -407.138011) (xy 321.841405 -407.187595)
			(xy 321.811935 -407.233451) (xy 321.776238 -407.274646) (xy 321.735041 -407.310342) (xy 321.689184 -407.339811)
			(xy 321.6396 -407.362454) (xy 321.587298 -407.37781) (xy 321.533343 -407.385566) (xy 321.506088 -407.386028)
			(xy 320.642488 -407.386028) (xy 320.615239 -407.385501) (xy 320.561295 -407.377743) (xy 320.509005 -407.362388)
			(xy 320.459432 -407.339748) (xy 320.413585 -407.310282) (xy 320.372399 -407.274593) (xy 320.33671 -407.233405)
			(xy 320.307247 -407.187558) (xy 320.284608 -407.137984) (xy 320.269254 -407.085693) (xy 320.261498 -407.031749)
			(xy 318.823842 -407.031749) (xy 318.823842 -407.03175) (xy 318.816087 -407.085697) (xy 318.800733 -407.137991)
			(xy 318.778094 -407.187567) (xy 318.748631 -407.233418) (xy 318.712943 -407.274609) (xy 318.671756 -407.310302)
			(xy 318.625909 -407.339771) (xy 318.576336 -407.362416) (xy 318.524044 -407.377776) (xy 318.470098 -407.385539)
			(xy 318.442848 -407.386028) (xy 317.579248 -407.386028) (xy 317.551994 -407.385528) (xy 317.498041 -407.377777)
			(xy 317.44574 -407.362426) (xy 317.396157 -407.339787) (xy 317.3503 -407.310322) (xy 317.309104 -407.27463)
			(xy 317.273407 -407.233439) (xy 317.243936 -407.187586) (xy 317.221291 -407.138005) (xy 317.205933 -407.085706)
			(xy 317.198175 -407.031754) (xy 315.760642 -407.031754) (xy 315.752885 -407.085702) (xy 315.73753 -407.137999)
			(xy 315.714888 -407.187578) (xy 315.685421 -407.233431) (xy 315.649729 -407.274623) (xy 315.608537 -407.310316)
			(xy 315.562685 -407.339784) (xy 315.513107 -407.362427) (xy 315.46081 -407.377784) (xy 315.40686 -407.385542)
			(xy 315.379608 -407.386028) (xy 314.516008 -407.386028) (xy 314.488756 -407.385525) (xy 314.434807 -407.37777)
			(xy 314.382511 -407.362415) (xy 314.332933 -407.339774) (xy 314.287081 -407.310308) (xy 314.245889 -407.274616)
			(xy 314.210197 -407.233425) (xy 314.18073 -407.187574) (xy 314.158088 -407.137996) (xy 314.142732 -407.085701)
			(xy 314.134975 -407.031752) (xy 312.697465 -407.031752) (xy 312.697465 -407.031756) (xy 312.689707 -407.085712)
			(xy 312.674348 -407.138016) (xy 312.651702 -407.187601) (xy 312.62223 -407.233458) (xy 312.586531 -407.274653)
			(xy 312.545332 -407.310349) (xy 312.499472 -407.339818) (xy 312.449886 -407.36246) (xy 312.397581 -407.377814)
			(xy 312.343624 -407.385567) (xy 312.316368 -407.386028) (xy 311.452768 -407.386028) (xy 311.42552 -407.3855)
			(xy 311.371578 -407.37774) (xy 311.31929 -407.362383) (xy 311.26972 -407.339741) (xy 311.223876 -407.310275)
			(xy 311.182692 -407.274586) (xy 311.147005 -407.233399) (xy 311.117544 -407.187552) (xy 311.094906 -407.13798)
			(xy 311.079553 -407.08569) (xy 311.071798 -407.031748) (xy 309.634142 -407.031748) (xy 309.634142 -407.031751)
			(xy 309.626386 -407.0857) (xy 309.611032 -407.137995) (xy 309.588391 -407.187573) (xy 309.558926 -407.233424)
			(xy 309.523236 -407.274616) (xy 309.482047 -407.310309) (xy 309.436197 -407.339778) (xy 309.386621 -407.362422)
			(xy 309.334327 -407.37778) (xy 309.280379 -407.38554) (xy 309.253128 -407.386028) (xy 308.389528 -407.386028)
			(xy 308.362275 -407.385527) (xy 308.308324 -407.377773) (xy 308.256026 -407.36242) (xy 308.206445 -407.339781)
			(xy 308.16059 -407.310315) (xy 308.119397 -407.274623) (xy 308.083702 -407.233432) (xy 308.054233 -407.18758)
			(xy 308.031589 -407.138001) (xy 308.016233 -407.085703) (xy 308.008475 -407.031753) (xy 306.570965 -407.031753)
			(xy 306.570965 -407.031755) (xy 306.563207 -407.08571) (xy 306.54785 -407.138011) (xy 306.525205 -407.187595)
			(xy 306.495735 -407.233451) (xy 306.460038 -407.274646) (xy 306.418841 -407.310342) (xy 306.372984 -407.339811)
			(xy 306.3234 -407.362454) (xy 306.271098 -407.37781) (xy 306.217143 -407.385566) (xy 306.189888 -407.386028)
			(xy 305.326288 -407.386028) (xy 305.299039 -407.385501) (xy 305.245095 -407.377743) (xy 305.192805 -407.362388)
			(xy 305.143232 -407.339748) (xy 305.097385 -407.310282) (xy 305.056199 -407.274593) (xy 305.02051 -407.233405)
			(xy 304.991047 -407.187558) (xy 304.968408 -407.137984) (xy 304.953054 -407.085693) (xy 304.945298 -407.031749)
			(xy 274.459335 -407.031749) (xy 274.369276 -407.121868) (xy 274.369276 -407.203148) (xy 274.602448 -407.43632)
			(xy 280.100532 -407.43632) (xy 280.125481 -407.436823) (xy 280.174763 -407.444637) (xy 280.222219 -407.460054)
			(xy 280.266685 -407.482694) (xy 280.307069 -407.512001) (xy 280.325068 -407.529284) (xy 280.739596 -407.943812)
			(xy 280.756896 -407.961798) (xy 280.786219 -408.002177) (xy 280.808865 -408.046645) (xy 280.824276 -408.094108)
			(xy 280.832075 -408.143397) (xy 280.83256 -408.168348) (xy 280.83256 -410.057453) (xy 304.945246 -410.057453)
			(xy 304.945246 -410.002947) (xy 304.953003 -409.948996) (xy 304.968358 -409.896698) (xy 304.991001 -409.847117)
			(xy 305.020468 -409.801263) (xy 305.056162 -409.76007) (xy 305.097354 -409.724375) (xy 305.143207 -409.694906)
			(xy 305.192786 -409.672263) (xy 305.245084 -409.656905) (xy 305.299035 -409.649147) (xy 305.326288 -409.64866)
			(xy 306.189888 -409.64866) (xy 306.217139 -409.649186) (xy 306.271087 -409.656941) (xy 306.323382 -409.672295)
			(xy 306.372959 -409.694935) (xy 306.41881 -409.7244) (xy 306.460001 -409.760091) (xy 306.495693 -409.80128)
			(xy 306.525159 -409.84713) (xy 306.547801 -409.896707) (xy 306.563156 -409.949001) (xy 306.570913 -410.002949)
			(xy 306.570913 -410.057451) (xy 306.570912 -410.057456) (xy 308.008423 -410.057456) (xy 308.008423 -410.002944)
			(xy 308.016181 -409.948986) (xy 308.03154 -409.896681) (xy 308.054187 -409.847095) (xy 308.08366 -409.801236)
			(xy 308.119359 -409.76004) (xy 308.160559 -409.724343) (xy 308.206419 -409.694873) (xy 308.256007 -409.67223)
			(xy 308.308313 -409.656875) (xy 308.362272 -409.649121) (xy 308.389528 -409.64866) (xy 309.253128 -409.64866)
			(xy 309.280376 -409.649212) (xy 309.334316 -409.656971) (xy 309.386603 -409.672327) (xy 309.436172 -409.694968)
			(xy 309.482015 -409.724433) (xy 309.523199 -409.760121) (xy 309.558884 -409.801307) (xy 309.588345 -409.847152)
			(xy 309.610982 -409.896724) (xy 309.626335 -409.949012) (xy 309.63409 -410.002952) (xy 309.63409 -410.057448)
			(xy 309.634089 -410.057452) (xy 311.071746 -410.057452) (xy 311.071746 -410.002948) (xy 311.079502 -409.948998)
			(xy 311.094857 -409.896702) (xy 311.117498 -409.847123) (xy 311.146963 -409.80127) (xy 311.182654 -409.760077)
			(xy 311.223844 -409.724383) (xy 311.269695 -409.694913) (xy 311.319272 -409.672268) (xy 311.371567 -409.656909)
			(xy 311.425516 -409.649148) (xy 311.452768 -409.64866) (xy 312.316368 -409.64866) (xy 312.34362 -409.649185)
			(xy 312.39757 -409.656938) (xy 312.449867 -409.67229) (xy 312.499447 -409.694928) (xy 312.545301 -409.724393)
			(xy 312.586494 -409.760084) (xy 312.622188 -409.801274) (xy 312.651656 -409.847125) (xy 312.674299 -409.896703)
			(xy 312.689655 -409.948999) (xy 312.697413 -410.002948) (xy 312.697413 -410.057452) (xy 312.697412 -410.057456)
			(xy 314.134923 -410.057456) (xy 314.134923 -410.002944) (xy 314.142681 -409.948988) (xy 314.158039 -409.896685)
			(xy 314.180684 -409.8471) (xy 314.210155 -409.801243) (xy 314.245852 -409.760047) (xy 314.287049 -409.72435)
			(xy 314.332907 -409.69488) (xy 314.382493 -409.672236) (xy 314.434796 -409.656879) (xy 314.488752 -409.649122)
			(xy 314.516008 -409.64866) (xy 315.379608 -409.64866) (xy 315.406857 -409.649211) (xy 315.460799 -409.656968)
			(xy 315.513088 -409.672322) (xy 315.56266 -409.694962) (xy 315.608506 -409.724426) (xy 315.649691 -409.760114)
			(xy 315.685379 -409.801301) (xy 315.714842 -409.847147) (xy 315.737481 -409.896719) (xy 315.752834 -409.949009)
			(xy 315.76059 -410.002951) (xy 315.76059 -410.057449) (xy 315.760589 -410.057457) (xy 317.198123 -410.057457)
			(xy 317.198123 -410.002943) (xy 317.205882 -409.948983) (xy 317.221242 -409.896677) (xy 317.24389 -409.847089)
			(xy 317.273365 -409.80123) (xy 317.309066 -409.760033) (xy 317.350268 -409.724336) (xy 317.396131 -409.694867)
			(xy 317.445722 -409.672225) (xy 317.49803 -409.656872) (xy 317.551991 -409.64912) (xy 317.579248 -409.64866)
			(xy 318.442848 -409.64866) (xy 318.470095 -409.649213) (xy 318.524033 -409.656975) (xy 318.576317 -409.672333)
			(xy 318.625884 -409.694975) (xy 318.671725 -409.72444) (xy 318.712906 -409.760128) (xy 318.748589 -409.801314)
			(xy 318.778048 -409.847158) (xy 318.800684 -409.896728) (xy 318.816035 -409.949014) (xy 318.82379 -410.002953)
			(xy 318.82379 -410.057447) (xy 318.823789 -410.057453) (xy 320.261446 -410.057453) (xy 320.261446 -410.002947)
			(xy 320.269203 -409.948996) (xy 320.284558 -409.896698) (xy 320.307201 -409.847117) (xy 320.336668 -409.801263)
			(xy 320.372362 -409.76007) (xy 320.413554 -409.724375) (xy 320.459407 -409.694906) (xy 320.508986 -409.672263)
			(xy 320.561284 -409.656905) (xy 320.615235 -409.649147) (xy 320.642488 -409.64866) (xy 321.506088 -409.64866)
			(xy 321.533339 -409.649186) (xy 321.587287 -409.656941) (xy 321.639582 -409.672295) (xy 321.689159 -409.694935)
			(xy 321.73501 -409.7244) (xy 321.776201 -409.760091) (xy 321.811893 -409.80128) (xy 321.841359 -409.84713)
			(xy 321.864001 -409.896707) (xy 321.879356 -409.949001) (xy 321.887113 -410.002949) (xy 321.887113 -410.057451)
			(xy 321.887112 -410.057456) (xy 323.324623 -410.057456) (xy 323.324623 -410.002944) (xy 323.332381 -409.948986)
			(xy 323.34774 -409.896681) (xy 323.370387 -409.847095) (xy 323.39986 -409.801236) (xy 323.435559 -409.76004)
			(xy 323.476759 -409.724343) (xy 323.522619 -409.694873) (xy 323.572207 -409.67223) (xy 323.624513 -409.656875)
			(xy 323.678472 -409.649121) (xy 323.705728 -409.64866) (xy 324.569328 -409.64866) (xy 324.596576 -409.649212)
			(xy 324.650516 -409.656971) (xy 324.702803 -409.672327) (xy 324.752372 -409.694968) (xy 324.798215 -409.724433)
			(xy 324.839399 -409.760121) (xy 324.875084 -409.801307) (xy 324.904545 -409.847152) (xy 324.927182 -409.896724)
			(xy 324.942535 -409.949012) (xy 324.95029 -410.002952) (xy 324.95029 -410.057448) (xy 324.950289 -410.057452)
			(xy 326.387946 -410.057452) (xy 326.387946 -410.002948) (xy 326.395702 -409.948998) (xy 326.411057 -409.896702)
			(xy 326.433698 -409.847123) (xy 326.463163 -409.80127) (xy 326.498854 -409.760077) (xy 326.540044 -409.724383)
			(xy 326.585895 -409.694913) (xy 326.635472 -409.672268) (xy 326.687767 -409.656909) (xy 326.741716 -409.649148)
			(xy 326.768968 -409.64866) (xy 327.632568 -409.64866) (xy 327.65982 -409.649185) (xy 327.71377 -409.656938)
			(xy 327.766067 -409.67229) (xy 327.815647 -409.694928) (xy 327.861501 -409.724393) (xy 327.902694 -409.760084)
			(xy 327.938388 -409.801274) (xy 327.967856 -409.847125) (xy 327.990499 -409.896703) (xy 328.005855 -409.948999)
			(xy 328.013613 -410.002948) (xy 328.013613 -410.057452) (xy 328.013612 -410.057456) (xy 329.451123 -410.057456)
			(xy 329.451123 -410.002944) (xy 329.458881 -409.948988) (xy 329.474239 -409.896685) (xy 329.496884 -409.8471)
			(xy 329.526355 -409.801243) (xy 329.562052 -409.760047) (xy 329.603249 -409.72435) (xy 329.649107 -409.69488)
			(xy 329.698693 -409.672236) (xy 329.750996 -409.656879) (xy 329.804952 -409.649122) (xy 329.832208 -409.64866)
			(xy 330.695808 -409.64866) (xy 330.723057 -409.649211) (xy 330.776999 -409.656968) (xy 330.829288 -409.672322)
			(xy 330.87886 -409.694962) (xy 330.924706 -409.724426) (xy 330.965891 -409.760114) (xy 331.001579 -409.801301)
			(xy 331.031042 -409.847147) (xy 331.053681 -409.896719) (xy 331.069034 -409.949009) (xy 331.07679 -410.002951)
			(xy 331.07679 -410.057449) (xy 331.076789 -410.057457) (xy 332.514323 -410.057457) (xy 332.514323 -410.002943)
			(xy 332.522082 -409.948983) (xy 332.537442 -409.896677) (xy 332.56009 -409.847089) (xy 332.589565 -409.80123)
			(xy 332.625266 -409.760033) (xy 332.666468 -409.724336) (xy 332.712331 -409.694867) (xy 332.761922 -409.672225)
			(xy 332.81423 -409.656872) (xy 332.868191 -409.64912) (xy 332.895448 -409.64866) (xy 333.759048 -409.64866)
			(xy 333.786295 -409.649213) (xy 333.840233 -409.656975) (xy 333.892517 -409.672333) (xy 333.942084 -409.694975)
			(xy 333.987925 -409.72444) (xy 334.029106 -409.760128) (xy 334.064789 -409.801314) (xy 334.094248 -409.847158)
			(xy 334.116884 -409.896728) (xy 334.132235 -409.949014) (xy 334.13999 -410.002953) (xy 334.13999 -410.057447)
			(xy 334.139989 -410.057453) (xy 335.577646 -410.057453) (xy 335.577646 -410.002947) (xy 335.585403 -409.948996)
			(xy 335.600758 -409.896698) (xy 335.623401 -409.847117) (xy 335.652868 -409.801263) (xy 335.688562 -409.76007)
			(xy 335.729754 -409.724375) (xy 335.775607 -409.694906) (xy 335.825186 -409.672263) (xy 335.877484 -409.656905)
			(xy 335.931435 -409.649147) (xy 335.958688 -409.64866) (xy 336.822288 -409.64866) (xy 336.849539 -409.649186)
			(xy 336.903487 -409.656941) (xy 336.955782 -409.672295) (xy 337.005359 -409.694935) (xy 337.05121 -409.7244)
			(xy 337.092401 -409.760091) (xy 337.128093 -409.80128) (xy 337.157559 -409.84713) (xy 337.180201 -409.896707)
			(xy 337.195556 -409.949001) (xy 337.203313 -410.002949) (xy 337.203313 -410.057451) (xy 337.203312 -410.057456)
			(xy 338.640823 -410.057456) (xy 338.640823 -410.002944) (xy 338.648581 -409.948986) (xy 338.66394 -409.896681)
			(xy 338.686587 -409.847095) (xy 338.71606 -409.801236) (xy 338.751759 -409.76004) (xy 338.792959 -409.724343)
			(xy 338.838819 -409.694873) (xy 338.888407 -409.67223) (xy 338.940713 -409.656875) (xy 338.994672 -409.649121)
			(xy 339.021928 -409.64866) (xy 339.885528 -409.64866) (xy 339.912776 -409.649212) (xy 339.966716 -409.656971)
			(xy 340.019003 -409.672327) (xy 340.068572 -409.694968) (xy 340.114415 -409.724433) (xy 340.155599 -409.760121)
			(xy 340.191284 -409.801307) (xy 340.220745 -409.847152) (xy 340.243382 -409.896724) (xy 340.258735 -409.949012)
			(xy 340.26649 -410.002952) (xy 340.26649 -410.057448) (xy 340.266489 -410.057452) (xy 341.704146 -410.057452)
			(xy 341.704146 -410.002948) (xy 341.711902 -409.948998) (xy 341.727257 -409.896702) (xy 341.749898 -409.847123)
			(xy 341.779363 -409.80127) (xy 341.815054 -409.760077) (xy 341.856244 -409.724383) (xy 341.902095 -409.694913)
			(xy 341.951672 -409.672268) (xy 342.003967 -409.656909) (xy 342.057916 -409.649148) (xy 342.085168 -409.64866)
			(xy 342.948768 -409.64866) (xy 342.97602 -409.649185) (xy 343.02997 -409.656938) (xy 343.082267 -409.67229)
			(xy 343.131847 -409.694928) (xy 343.177701 -409.724393) (xy 343.218894 -409.760084) (xy 343.254588 -409.801274)
			(xy 343.284056 -409.847125) (xy 343.306699 -409.896703) (xy 343.322055 -409.948999) (xy 343.329813 -410.002948)
			(xy 343.329813 -410.057452) (xy 343.329812 -410.057456) (xy 344.767323 -410.057456) (xy 344.767323 -410.002944)
			(xy 344.775081 -409.948988) (xy 344.790439 -409.896685) (xy 344.813084 -409.8471) (xy 344.842555 -409.801243)
			(xy 344.878252 -409.760047) (xy 344.919449 -409.72435) (xy 344.965307 -409.69488) (xy 345.014893 -409.672236)
			(xy 345.067196 -409.656879) (xy 345.121152 -409.649122) (xy 345.148408 -409.64866) (xy 346.012008 -409.64866)
			(xy 346.039257 -409.649211) (xy 346.093199 -409.656968) (xy 346.145488 -409.672322) (xy 346.19506 -409.694962)
			(xy 346.240906 -409.724426) (xy 346.282091 -409.760114) (xy 346.317779 -409.801301) (xy 346.347242 -409.847147)
			(xy 346.369881 -409.896719) (xy 346.385234 -409.949009) (xy 346.39299 -410.002951) (xy 346.39299 -410.057449)
			(xy 346.392989 -410.057457) (xy 347.830523 -410.057457) (xy 347.830523 -410.002943) (xy 347.838282 -409.948983)
			(xy 347.853642 -409.896677) (xy 347.87629 -409.847089) (xy 347.905765 -409.80123) (xy 347.941466 -409.760033)
			(xy 347.982668 -409.724336) (xy 348.028531 -409.694867) (xy 348.078122 -409.672225) (xy 348.13043 -409.656872)
			(xy 348.184391 -409.64912) (xy 348.211648 -409.64866) (xy 349.075248 -409.64866) (xy 349.102495 -409.649213)
			(xy 349.156433 -409.656975) (xy 349.208717 -409.672333) (xy 349.258284 -409.694975) (xy 349.304125 -409.72444)
			(xy 349.345306 -409.760128) (xy 349.380989 -409.801314) (xy 349.410448 -409.847158) (xy 349.433084 -409.896728)
			(xy 349.448435 -409.949014) (xy 349.45619 -410.002953) (xy 349.45619 -410.057447) (xy 349.456189 -410.057453)
			(xy 350.893846 -410.057453) (xy 350.893846 -410.002947) (xy 350.901603 -409.948996) (xy 350.916958 -409.896698)
			(xy 350.939601 -409.847117) (xy 350.969068 -409.801263) (xy 351.004762 -409.76007) (xy 351.045954 -409.724375)
			(xy 351.091807 -409.694906) (xy 351.141386 -409.672263) (xy 351.193684 -409.656905) (xy 351.247635 -409.649147)
			(xy 351.274888 -409.64866) (xy 352.138488 -409.64866) (xy 352.165739 -409.649186) (xy 352.219687 -409.656941)
			(xy 352.271982 -409.672295) (xy 352.321559 -409.694935) (xy 352.36741 -409.7244) (xy 352.408601 -409.760091)
			(xy 352.444293 -409.80128) (xy 352.473759 -409.84713) (xy 352.496401 -409.896707) (xy 352.511756 -409.949001)
			(xy 352.519513 -410.002949) (xy 352.519513 -410.057451) (xy 352.519512 -410.057457) (xy 372.388023 -410.057457)
			(xy 372.388023 -410.002943) (xy 372.395781 -409.948985) (xy 372.41114 -409.896681) (xy 372.433787 -409.847094)
			(xy 372.46326 -409.801236) (xy 372.49896 -409.760039) (xy 372.54016 -409.724342) (xy 372.586021 -409.694872)
			(xy 372.635609 -409.67223) (xy 372.687915 -409.656875) (xy 372.741873 -409.649121) (xy 372.76913 -409.64866)
			(xy 373.63273 -409.64866) (xy 373.659978 -409.649212) (xy 373.713917 -409.656972) (xy 373.766204 -409.672328)
			(xy 373.815773 -409.694969) (xy 373.861616 -409.724434) (xy 373.902799 -409.760122) (xy 373.938484 -409.801308)
			(xy 373.967945 -409.847153) (xy 373.990583 -409.896724) (xy 374.005935 -409.949012) (xy 374.01369 -410.002952)
			(xy 374.01369 -410.057448) (xy 374.013689 -410.057452) (xy 375.451346 -410.057452) (xy 375.451346 -410.002948)
			(xy 375.459102 -409.948998) (xy 375.474457 -409.896701) (xy 375.497098 -409.847122) (xy 375.526564 -409.801269)
			(xy 375.562255 -409.760076) (xy 375.603445 -409.724382) (xy 375.649296 -409.694912) (xy 375.698873 -409.672268)
			(xy 375.751169 -409.656909) (xy 375.805118 -409.649148) (xy 375.83237 -409.64866) (xy 376.69597 -409.64866)
			(xy 376.723222 -409.649185) (xy 376.777172 -409.656938) (xy 376.829469 -409.67229) (xy 376.879048 -409.694929)
			(xy 376.924901 -409.724394) (xy 376.966094 -409.760084) (xy 377.001788 -409.801274) (xy 377.031257 -409.847125)
			(xy 377.053899 -409.896703) (xy 377.069256 -409.948999) (xy 377.077013 -410.002948) (xy 377.077013 -410.057452)
			(xy 377.077012 -410.057456) (xy 378.514523 -410.057456) (xy 378.514523 -410.002944) (xy 378.522281 -409.948988)
			(xy 378.537639 -409.896685) (xy 378.560284 -409.8471) (xy 378.589755 -409.801242) (xy 378.625453 -409.760046)
			(xy 378.66665 -409.724349) (xy 378.712509 -409.694879) (xy 378.762094 -409.672235) (xy 378.814398 -409.656879)
			(xy 378.868354 -409.649122) (xy 378.89561 -409.64866) (xy 379.75921 -409.64866) (xy 379.786458 -409.649211)
			(xy 379.840401 -409.656968) (xy 379.89269 -409.672323) (xy 379.942261 -409.694962) (xy 379.988107 -409.724426)
			(xy 380.029292 -409.760115) (xy 380.06498 -409.801301) (xy 380.094442 -409.847147) (xy 380.117081 -409.89672)
			(xy 380.132434 -409.949009) (xy 380.14019 -410.002952) (xy 380.14019 -410.057448) (xy 380.14019 -410.057451)
			(xy 381.577846 -410.057451) (xy 381.577846 -410.002949) (xy 381.585602 -409.949001) (xy 381.600955 -409.896706)
			(xy 381.623595 -409.847128) (xy 381.653059 -409.801276) (xy 381.688748 -409.760083) (xy 381.729936 -409.724389)
			(xy 381.775784 -409.694919) (xy 381.825359 -409.672273) (xy 381.877652 -409.656912) (xy 381.931599 -409.649149)
			(xy 381.95885 -409.64866) (xy 382.82245 -409.64866) (xy 382.849703 -409.649184) (xy 382.903655 -409.656934)
			(xy 382.955954 -409.672285) (xy 383.005536 -409.694923) (xy 383.051392 -409.724387) (xy 383.092587 -409.760077)
			(xy 383.128283 -409.801268) (xy 383.157753 -409.84712) (xy 383.180398 -409.896699) (xy 383.195755 -409.948996)
			(xy 383.203513 -410.002947) (xy 383.203513 -410.057453) (xy 384.641046 -410.057453) (xy 384.641046 -410.002947)
			(xy 384.648803 -409.948996) (xy 384.664159 -409.896697) (xy 384.686801 -409.847117) (xy 384.716269 -409.801263)
			(xy 384.751962 -409.760069) (xy 384.793155 -409.724375) (xy 384.839008 -409.694906) (xy 384.888588 -409.672262)
			(xy 384.940886 -409.656905) (xy 384.994837 -409.649147) (xy 385.02209 -409.64866) (xy 385.88569 -409.64866)
			(xy 385.912941 -409.649187) (xy 385.966889 -409.656942) (xy 386.019183 -409.672296) (xy 386.06876 -409.694936)
			(xy 386.114611 -409.724401) (xy 386.155801 -409.760092) (xy 386.191493 -409.801281) (xy 386.22096 -409.847131)
			(xy 386.243601 -409.896707) (xy 386.258956 -409.949002) (xy 386.266713 -410.002949) (xy 386.266713 -410.057451)
			(xy 386.266712 -410.057457) (xy 387.704223 -410.057457) (xy 387.704223 -410.002943) (xy 387.711981 -409.948985)
			(xy 387.72734 -409.896681) (xy 387.749987 -409.847094) (xy 387.77946 -409.801236) (xy 387.81516 -409.760039)
			(xy 387.85636 -409.724342) (xy 387.902221 -409.694872) (xy 387.951809 -409.67223) (xy 388.004115 -409.656875)
			(xy 388.058073 -409.649121) (xy 388.08533 -409.64866) (xy 388.94893 -409.64866) (xy 388.976178 -409.649212)
			(xy 389.030117 -409.656972) (xy 389.082404 -409.672328) (xy 389.131973 -409.694969) (xy 389.177816 -409.724434)
			(xy 389.218999 -409.760122) (xy 389.254684 -409.801308) (xy 389.284145 -409.847153) (xy 389.306783 -409.896724)
			(xy 389.322135 -409.949012) (xy 389.32989 -410.002952) (xy 389.32989 -410.057448) (xy 389.329889 -410.057452)
			(xy 390.767546 -410.057452) (xy 390.767546 -410.002948) (xy 390.775302 -409.948998) (xy 390.790657 -409.896701)
			(xy 390.813298 -409.847122) (xy 390.842764 -409.801269) (xy 390.878455 -409.760076) (xy 390.919645 -409.724382)
			(xy 390.965496 -409.694912) (xy 391.015073 -409.672268) (xy 391.067369 -409.656909) (xy 391.121318 -409.649148)
			(xy 391.14857 -409.64866) (xy 392.01217 -409.64866) (xy 392.039422 -409.649185) (xy 392.093372 -409.656938)
			(xy 392.145669 -409.67229) (xy 392.195248 -409.694929) (xy 392.241101 -409.724394) (xy 392.282294 -409.760084)
			(xy 392.317988 -409.801274) (xy 392.347457 -409.847125) (xy 392.370099 -409.896703) (xy 392.385456 -409.948999)
			(xy 392.393213 -410.002948) (xy 392.393213 -410.057452) (xy 392.393212 -410.057456) (xy 393.830723 -410.057456)
			(xy 393.830723 -410.002944) (xy 393.838481 -409.948988) (xy 393.853839 -409.896685) (xy 393.876484 -409.8471)
			(xy 393.905955 -409.801242) (xy 393.941653 -409.760046) (xy 393.98285 -409.724349) (xy 394.028709 -409.694879)
			(xy 394.078294 -409.672235) (xy 394.130598 -409.656879) (xy 394.184554 -409.649122) (xy 394.21181 -409.64866)
			(xy 395.07541 -409.64866) (xy 395.102658 -409.649211) (xy 395.156601 -409.656968) (xy 395.20889 -409.672323)
			(xy 395.258461 -409.694962) (xy 395.304307 -409.724426) (xy 395.345492 -409.760115) (xy 395.38118 -409.801301)
			(xy 395.410642 -409.847147) (xy 395.433281 -409.89672) (xy 395.448634 -409.949009) (xy 395.45639 -410.002952)
			(xy 395.45639 -410.057448) (xy 395.45639 -410.057451) (xy 396.894046 -410.057451) (xy 396.894046 -410.002949)
			(xy 396.901802 -409.949001) (xy 396.917155 -409.896706) (xy 396.939795 -409.847128) (xy 396.969259 -409.801276)
			(xy 397.004948 -409.760083) (xy 397.046136 -409.724389) (xy 397.091984 -409.694919) (xy 397.141559 -409.672273)
			(xy 397.193852 -409.656912) (xy 397.247799 -409.649149) (xy 397.27505 -409.64866) (xy 398.13865 -409.64866)
			(xy 398.165903 -409.649184) (xy 398.219855 -409.656934) (xy 398.272154 -409.672285) (xy 398.321736 -409.694923)
			(xy 398.367592 -409.724387) (xy 398.408787 -409.760077) (xy 398.444483 -409.801268) (xy 398.473953 -409.84712)
			(xy 398.496598 -409.896699) (xy 398.511955 -409.948996) (xy 398.519713 -410.002947) (xy 398.519713 -410.057453)
			(xy 399.957246 -410.057453) (xy 399.957246 -410.002947) (xy 399.965003 -409.948996) (xy 399.980359 -409.896697)
			(xy 400.003001 -409.847117) (xy 400.032469 -409.801263) (xy 400.068162 -409.760069) (xy 400.109355 -409.724375)
			(xy 400.155208 -409.694906) (xy 400.204788 -409.672262) (xy 400.257086 -409.656905) (xy 400.311037 -409.649147)
			(xy 400.33829 -409.64866) (xy 401.20189 -409.64866) (xy 401.229141 -409.649187) (xy 401.283089 -409.656942)
			(xy 401.335383 -409.672296) (xy 401.38496 -409.694936) (xy 401.430811 -409.724401) (xy 401.472001 -409.760092)
			(xy 401.507693 -409.801281) (xy 401.53716 -409.847131) (xy 401.559801 -409.896707) (xy 401.575156 -409.949002)
			(xy 401.582913 -410.002949) (xy 401.582913 -410.057451) (xy 401.582912 -410.057457) (xy 403.020423 -410.057457)
			(xy 403.020423 -410.002943) (xy 403.028181 -409.948985) (xy 403.04354 -409.896681) (xy 403.066187 -409.847094)
			(xy 403.09566 -409.801236) (xy 403.13136 -409.760039) (xy 403.17256 -409.724342) (xy 403.218421 -409.694872)
			(xy 403.268009 -409.67223) (xy 403.320315 -409.656875) (xy 403.374273 -409.649121) (xy 403.40153 -409.64866)
			(xy 404.26513 -409.64866) (xy 404.292378 -409.649212) (xy 404.346317 -409.656972) (xy 404.398604 -409.672328)
			(xy 404.448173 -409.694969) (xy 404.494016 -409.724434) (xy 404.535199 -409.760122) (xy 404.570884 -409.801308)
			(xy 404.600345 -409.847153) (xy 404.622983 -409.896724) (xy 404.638335 -409.949012) (xy 404.64609 -410.002952)
			(xy 404.64609 -410.057448) (xy 404.646089 -410.057452) (xy 406.083746 -410.057452) (xy 406.083746 -410.002948)
			(xy 406.091502 -409.948998) (xy 406.106857 -409.896701) (xy 406.129498 -409.847122) (xy 406.158964 -409.801269)
			(xy 406.194655 -409.760076) (xy 406.235845 -409.724382) (xy 406.281696 -409.694912) (xy 406.331273 -409.672268)
			(xy 406.383569 -409.656909) (xy 406.437518 -409.649148) (xy 406.46477 -409.64866) (xy 407.32837 -409.64866)
			(xy 407.355622 -409.649185) (xy 407.409572 -409.656938) (xy 407.461869 -409.67229) (xy 407.511448 -409.694929)
			(xy 407.557301 -409.724394) (xy 407.598494 -409.760084) (xy 407.634188 -409.801274) (xy 407.663657 -409.847125)
			(xy 407.686299 -409.896703) (xy 407.701656 -409.948999) (xy 407.709413 -410.002948) (xy 407.709413 -410.057452)
			(xy 407.709412 -410.057456) (xy 409.146923 -410.057456) (xy 409.146923 -410.002944) (xy 409.154681 -409.948988)
			(xy 409.170039 -409.896685) (xy 409.192684 -409.8471) (xy 409.222155 -409.801242) (xy 409.257853 -409.760046)
			(xy 409.29905 -409.724349) (xy 409.344909 -409.694879) (xy 409.394494 -409.672235) (xy 409.446798 -409.656879)
			(xy 409.500754 -409.649122) (xy 409.52801 -409.64866) (xy 410.39161 -409.64866) (xy 410.418858 -409.649211)
			(xy 410.472801 -409.656968) (xy 410.52509 -409.672323) (xy 410.574661 -409.694962) (xy 410.620507 -409.724426)
			(xy 410.661692 -409.760115) (xy 410.69738 -409.801301) (xy 410.726842 -409.847147) (xy 410.749481 -409.89672)
			(xy 410.764834 -409.949009) (xy 410.77259 -410.002952) (xy 410.77259 -410.057448) (xy 410.77259 -410.057451)
			(xy 412.210246 -410.057451) (xy 412.210246 -410.002949) (xy 412.218002 -409.949001) (xy 412.233355 -409.896706)
			(xy 412.255995 -409.847128) (xy 412.285459 -409.801276) (xy 412.321148 -409.760083) (xy 412.362336 -409.724389)
			(xy 412.408184 -409.694919) (xy 412.457759 -409.672273) (xy 412.510052 -409.656912) (xy 412.563999 -409.649149)
			(xy 412.59125 -409.64866) (xy 413.45485 -409.64866) (xy 413.482103 -409.649184) (xy 413.536055 -409.656934)
			(xy 413.588354 -409.672285) (xy 413.637936 -409.694923) (xy 413.683792 -409.724387) (xy 413.724987 -409.760077)
			(xy 413.760683 -409.801268) (xy 413.790153 -409.84712) (xy 413.812798 -409.896699) (xy 413.828155 -409.948996)
			(xy 413.835913 -410.002947) (xy 413.835913 -410.057453) (xy 415.273446 -410.057453) (xy 415.273446 -410.002947)
			(xy 415.281203 -409.948996) (xy 415.296559 -409.896697) (xy 415.319201 -409.847117) (xy 415.348669 -409.801263)
			(xy 415.384362 -409.760069) (xy 415.425555 -409.724375) (xy 415.471408 -409.694906) (xy 415.520988 -409.672262)
			(xy 415.573286 -409.656905) (xy 415.627237 -409.649147) (xy 415.65449 -409.64866) (xy 416.51809 -409.64866)
			(xy 416.545341 -409.649187) (xy 416.599289 -409.656942) (xy 416.651583 -409.672296) (xy 416.70116 -409.694936)
			(xy 416.747011 -409.724401) (xy 416.788201 -409.760092) (xy 416.823893 -409.801281) (xy 416.85336 -409.847131)
			(xy 416.876001 -409.896707) (xy 416.891356 -409.949002) (xy 416.899113 -410.002949) (xy 416.899113 -410.057451)
			(xy 416.899112 -410.057457) (xy 418.336623 -410.057457) (xy 418.336623 -410.002943) (xy 418.344381 -409.948985)
			(xy 418.35974 -409.896681) (xy 418.382387 -409.847094) (xy 418.41186 -409.801236) (xy 418.44756 -409.760039)
			(xy 418.48876 -409.724342) (xy 418.534621 -409.694872) (xy 418.584209 -409.67223) (xy 418.636515 -409.656875)
			(xy 418.690473 -409.649121) (xy 418.71773 -409.64866) (xy 419.58133 -409.64866) (xy 419.608578 -409.649212)
			(xy 419.662517 -409.656972) (xy 419.714804 -409.672328) (xy 419.764373 -409.694969) (xy 419.810216 -409.724434)
			(xy 419.851399 -409.760122) (xy 419.887084 -409.801308) (xy 419.916545 -409.847153) (xy 419.939183 -409.896724)
			(xy 419.954535 -409.949012) (xy 419.96229 -410.002952) (xy 419.96229 -410.057448) (xy 419.954535 -410.111388)
			(xy 419.939183 -410.163676) (xy 419.916545 -410.213247) (xy 419.887084 -410.259092) (xy 419.851399 -410.300278)
			(xy 419.810216 -410.335966) (xy 419.764373 -410.365431) (xy 419.714804 -410.388072) (xy 419.662517 -410.403428)
			(xy 419.608578 -410.411188) (xy 419.58133 -410.411676) (xy 418.71773 -410.411676) (xy 418.690473 -410.411279)
			(xy 418.636515 -410.403525) (xy 418.584209 -410.38817) (xy 418.534621 -410.365528) (xy 418.48876 -410.336058)
			(xy 418.44756 -410.300361) (xy 418.41186 -410.259164) (xy 418.382387 -410.213306) (xy 418.35974 -410.163719)
			(xy 418.344381 -410.111415) (xy 418.336623 -410.057457) (xy 416.899112 -410.057457) (xy 416.891356 -410.111398)
			(xy 416.876001 -410.163693) (xy 416.85336 -410.213269) (xy 416.823893 -410.259119) (xy 416.788201 -410.300308)
			(xy 416.747011 -410.335999) (xy 416.70116 -410.365464) (xy 416.651583 -410.388104) (xy 416.599289 -410.403458)
			(xy 416.545341 -410.411213) (xy 416.51809 -410.411676) (xy 415.65449 -410.411676) (xy 415.627237 -410.411253)
			(xy 415.573286 -410.403495) (xy 415.520988 -410.388138) (xy 415.471408 -410.365494) (xy 415.425555 -410.336025)
			(xy 415.384362 -410.300331) (xy 415.348669 -410.259137) (xy 415.319201 -410.213283) (xy 415.296559 -410.163703)
			(xy 415.281203 -410.111404) (xy 415.273446 -410.057453) (xy 413.835913 -410.057453) (xy 413.828155 -410.111404)
			(xy 413.812798 -410.163701) (xy 413.790153 -410.21328) (xy 413.760683 -410.259132) (xy 413.724987 -410.300323)
			(xy 413.683792 -410.336013) (xy 413.637936 -410.365477) (xy 413.588354 -410.388115) (xy 413.536055 -410.403466)
			(xy 413.482103 -410.411216) (xy 413.45485 -410.411676) (xy 412.59125 -410.411676) (xy 412.563999 -410.411251)
			(xy 412.510052 -410.403488) (xy 412.457759 -410.388127) (xy 412.408184 -410.365481) (xy 412.362336 -410.336011)
			(xy 412.321148 -410.300317) (xy 412.285459 -410.259124) (xy 412.255995 -410.213272) (xy 412.233355 -410.163694)
			(xy 412.218002 -410.111399) (xy 412.210246 -410.057451) (xy 410.77259 -410.057451) (xy 410.764834 -410.111391)
			(xy 410.749481 -410.16368) (xy 410.726842 -410.213253) (xy 410.69738 -410.259099) (xy 410.661692 -410.300285)
			(xy 410.620507 -410.335974) (xy 410.574661 -410.365438) (xy 410.52509 -410.388077) (xy 410.472801 -410.403432)
			(xy 410.418858 -410.411189) (xy 410.39161 -410.411676) (xy 409.52801 -410.411676) (xy 409.500754 -410.411278)
			(xy 409.446798 -410.403521) (xy 409.394494 -410.388165) (xy 409.344909 -410.365521) (xy 409.29905 -410.336051)
			(xy 409.257853 -410.300354) (xy 409.222155 -410.259158) (xy 409.192684 -410.2133) (xy 409.170039 -410.163715)
			(xy 409.154681 -410.111412) (xy 409.146923 -410.057456) (xy 407.709412 -410.057456) (xy 407.701656 -410.111401)
			(xy 407.686299 -410.163697) (xy 407.663657 -410.213275) (xy 407.634188 -410.259126) (xy 407.598494 -410.300316)
			(xy 407.557301 -410.336006) (xy 407.511448 -410.365471) (xy 407.461869 -410.38811) (xy 407.409572 -410.403462)
			(xy 407.355622 -410.411215) (xy 407.32837 -410.411676) (xy 406.46477 -410.411676) (xy 406.437518 -410.411252)
			(xy 406.383569 -410.403491) (xy 406.331273 -410.388132) (xy 406.281696 -410.365488) (xy 406.235845 -410.336018)
			(xy 406.194655 -410.300324) (xy 406.158964 -410.259131) (xy 406.129498 -410.213278) (xy 406.106857 -410.163699)
			(xy 406.091502 -410.111402) (xy 406.083746 -410.057452) (xy 404.646089 -410.057452) (xy 404.638335 -410.111388)
			(xy 404.622983 -410.163676) (xy 404.600345 -410.213247) (xy 404.570884 -410.259092) (xy 404.535199 -410.300278)
			(xy 404.494016 -410.335966) (xy 404.448173 -410.365431) (xy 404.398604 -410.388072) (xy 404.346317 -410.403428)
			(xy 404.292378 -410.411188) (xy 404.26513 -410.411676) (xy 403.40153 -410.411676) (xy 403.374273 -410.411279)
			(xy 403.320315 -410.403525) (xy 403.268009 -410.38817) (xy 403.218421 -410.365528) (xy 403.17256 -410.336058)
			(xy 403.13136 -410.300361) (xy 403.09566 -410.259164) (xy 403.066187 -410.213306) (xy 403.04354 -410.163719)
			(xy 403.028181 -410.111415) (xy 403.020423 -410.057457) (xy 401.582912 -410.057457) (xy 401.575156 -410.111398)
			(xy 401.559801 -410.163693) (xy 401.53716 -410.213269) (xy 401.507693 -410.259119) (xy 401.472001 -410.300308)
			(xy 401.430811 -410.335999) (xy 401.38496 -410.365464) (xy 401.335383 -410.388104) (xy 401.283089 -410.403458)
			(xy 401.229141 -410.411213) (xy 401.20189 -410.411676) (xy 400.33829 -410.411676) (xy 400.311037 -410.411253)
			(xy 400.257086 -410.403495) (xy 400.204788 -410.388138) (xy 400.155208 -410.365494) (xy 400.109355 -410.336025)
			(xy 400.068162 -410.300331) (xy 400.032469 -410.259137) (xy 400.003001 -410.213283) (xy 399.980359 -410.163703)
			(xy 399.965003 -410.111404) (xy 399.957246 -410.057453) (xy 398.519713 -410.057453) (xy 398.511955 -410.111404)
			(xy 398.496598 -410.163701) (xy 398.473953 -410.21328) (xy 398.444483 -410.259132) (xy 398.408787 -410.300323)
			(xy 398.367592 -410.336013) (xy 398.321736 -410.365477) (xy 398.272154 -410.388115) (xy 398.219855 -410.403466)
			(xy 398.165903 -410.411216) (xy 398.13865 -410.411676) (xy 397.27505 -410.411676) (xy 397.247799 -410.411251)
			(xy 397.193852 -410.403488) (xy 397.141559 -410.388127) (xy 397.091984 -410.365481) (xy 397.046136 -410.336011)
			(xy 397.004948 -410.300317) (xy 396.969259 -410.259124) (xy 396.939795 -410.213272) (xy 396.917155 -410.163694)
			(xy 396.901802 -410.111399) (xy 396.894046 -410.057451) (xy 395.45639 -410.057451) (xy 395.448634 -410.111391)
			(xy 395.433281 -410.16368) (xy 395.410642 -410.213253) (xy 395.38118 -410.259099) (xy 395.345492 -410.300285)
			(xy 395.304307 -410.335974) (xy 395.258461 -410.365438) (xy 395.20889 -410.388077) (xy 395.156601 -410.403432)
			(xy 395.102658 -410.411189) (xy 395.07541 -410.411676) (xy 394.21181 -410.411676) (xy 394.184554 -410.411278)
			(xy 394.130598 -410.403521) (xy 394.078294 -410.388165) (xy 394.028709 -410.365521) (xy 393.98285 -410.336051)
			(xy 393.941653 -410.300354) (xy 393.905955 -410.259158) (xy 393.876484 -410.2133) (xy 393.853839 -410.163715)
			(xy 393.838481 -410.111412) (xy 393.830723 -410.057456) (xy 392.393212 -410.057456) (xy 392.385456 -410.111401)
			(xy 392.370099 -410.163697) (xy 392.347457 -410.213275) (xy 392.317988 -410.259126) (xy 392.282294 -410.300316)
			(xy 392.241101 -410.336006) (xy 392.195248 -410.365471) (xy 392.145669 -410.38811) (xy 392.093372 -410.403462)
			(xy 392.039422 -410.411215) (xy 392.01217 -410.411676) (xy 391.14857 -410.411676) (xy 391.121318 -410.411252)
			(xy 391.067369 -410.403491) (xy 391.015073 -410.388132) (xy 390.965496 -410.365488) (xy 390.919645 -410.336018)
			(xy 390.878455 -410.300324) (xy 390.842764 -410.259131) (xy 390.813298 -410.213278) (xy 390.790657 -410.163699)
			(xy 390.775302 -410.111402) (xy 390.767546 -410.057452) (xy 389.329889 -410.057452) (xy 389.322135 -410.111388)
			(xy 389.306783 -410.163676) (xy 389.284145 -410.213247) (xy 389.254684 -410.259092) (xy 389.218999 -410.300278)
			(xy 389.177816 -410.335966) (xy 389.131973 -410.365431) (xy 389.082404 -410.388072) (xy 389.030117 -410.403428)
			(xy 388.976178 -410.411188) (xy 388.94893 -410.411676) (xy 388.08533 -410.411676) (xy 388.058073 -410.411279)
			(xy 388.004115 -410.403525) (xy 387.951809 -410.38817) (xy 387.902221 -410.365528) (xy 387.85636 -410.336058)
			(xy 387.81516 -410.300361) (xy 387.77946 -410.259164) (xy 387.749987 -410.213306) (xy 387.72734 -410.163719)
			(xy 387.711981 -410.111415) (xy 387.704223 -410.057457) (xy 386.266712 -410.057457) (xy 386.258956 -410.111398)
			(xy 386.243601 -410.163693) (xy 386.22096 -410.213269) (xy 386.191493 -410.259119) (xy 386.155801 -410.300308)
			(xy 386.114611 -410.335999) (xy 386.06876 -410.365464) (xy 386.019183 -410.388104) (xy 385.966889 -410.403458)
			(xy 385.912941 -410.411213) (xy 385.88569 -410.411676) (xy 385.02209 -410.411676) (xy 384.994837 -410.411253)
			(xy 384.940886 -410.403495) (xy 384.888588 -410.388138) (xy 384.839008 -410.365494) (xy 384.793155 -410.336025)
			(xy 384.751962 -410.300331) (xy 384.716269 -410.259137) (xy 384.686801 -410.213283) (xy 384.664159 -410.163703)
			(xy 384.648803 -410.111404) (xy 384.641046 -410.057453) (xy 383.203513 -410.057453) (xy 383.195755 -410.111404)
			(xy 383.180398 -410.163701) (xy 383.157753 -410.21328) (xy 383.128283 -410.259132) (xy 383.092587 -410.300323)
			(xy 383.051392 -410.336013) (xy 383.005536 -410.365477) (xy 382.955954 -410.388115) (xy 382.903655 -410.403466)
			(xy 382.849703 -410.411216) (xy 382.82245 -410.411676) (xy 381.95885 -410.411676) (xy 381.931599 -410.411251)
			(xy 381.877652 -410.403488) (xy 381.825359 -410.388127) (xy 381.775784 -410.365481) (xy 381.729936 -410.336011)
			(xy 381.688748 -410.300317) (xy 381.653059 -410.259124) (xy 381.623595 -410.213272) (xy 381.600955 -410.163694)
			(xy 381.585602 -410.111399) (xy 381.577846 -410.057451) (xy 380.14019 -410.057451) (xy 380.132434 -410.111391)
			(xy 380.117081 -410.16368) (xy 380.094442 -410.213253) (xy 380.06498 -410.259099) (xy 380.029292 -410.300285)
			(xy 379.988107 -410.335974) (xy 379.942261 -410.365438) (xy 379.89269 -410.388077) (xy 379.840401 -410.403432)
			(xy 379.786458 -410.411189) (xy 379.75921 -410.411676) (xy 378.89561 -410.411676) (xy 378.868354 -410.411278)
			(xy 378.814398 -410.403521) (xy 378.762094 -410.388165) (xy 378.712509 -410.365521) (xy 378.66665 -410.336051)
			(xy 378.625453 -410.300354) (xy 378.589755 -410.259158) (xy 378.560284 -410.2133) (xy 378.537639 -410.163715)
			(xy 378.522281 -410.111412) (xy 378.514523 -410.057456) (xy 377.077012 -410.057456) (xy 377.069256 -410.111401)
			(xy 377.053899 -410.163697) (xy 377.031257 -410.213275) (xy 377.001788 -410.259126) (xy 376.966094 -410.300316)
			(xy 376.924901 -410.336006) (xy 376.879048 -410.365471) (xy 376.829469 -410.38811) (xy 376.777172 -410.403462)
			(xy 376.723222 -410.411215) (xy 376.69597 -410.411676) (xy 375.83237 -410.411676) (xy 375.805118 -410.411252)
			(xy 375.751169 -410.403491) (xy 375.698873 -410.388132) (xy 375.649296 -410.365488) (xy 375.603445 -410.336018)
			(xy 375.562255 -410.300324) (xy 375.526564 -410.259131) (xy 375.497098 -410.213278) (xy 375.474457 -410.163699)
			(xy 375.459102 -410.111402) (xy 375.451346 -410.057452) (xy 374.013689 -410.057452) (xy 374.005935 -410.111388)
			(xy 373.990583 -410.163676) (xy 373.967945 -410.213247) (xy 373.938484 -410.259092) (xy 373.902799 -410.300278)
			(xy 373.861616 -410.335966) (xy 373.815773 -410.365431) (xy 373.766204 -410.388072) (xy 373.713917 -410.403428)
			(xy 373.659978 -410.411188) (xy 373.63273 -410.411676) (xy 372.76913 -410.411676) (xy 372.741873 -410.411279)
			(xy 372.687915 -410.403525) (xy 372.635609 -410.38817) (xy 372.586021 -410.365528) (xy 372.54016 -410.336058)
			(xy 372.49896 -410.300361) (xy 372.46326 -410.259164) (xy 372.433787 -410.213306) (xy 372.41114 -410.163719)
			(xy 372.395781 -410.111415) (xy 372.388023 -410.057457) (xy 352.519512 -410.057457) (xy 352.511756 -410.111399)
			(xy 352.496401 -410.163693) (xy 352.473759 -410.21327) (xy 352.444293 -410.25912) (xy 352.408601 -410.300309)
			(xy 352.36741 -410.336) (xy 352.321559 -410.365465) (xy 352.271982 -410.388105) (xy 352.219687 -410.403459)
			(xy 352.165739 -410.411214) (xy 352.138488 -410.411676) (xy 351.274888 -410.411676) (xy 351.247635 -410.411253)
			(xy 351.193684 -410.403495) (xy 351.141386 -410.388137) (xy 351.091807 -410.365494) (xy 351.045954 -410.336025)
			(xy 351.004762 -410.30033) (xy 350.969068 -410.259137) (xy 350.939601 -410.213283) (xy 350.916958 -410.163702)
			(xy 350.901603 -410.111404) (xy 350.893846 -410.057453) (xy 349.456189 -410.057453) (xy 349.448435 -410.111386)
			(xy 349.433084 -410.163672) (xy 349.410448 -410.213242) (xy 349.380989 -410.259086) (xy 349.345306 -410.300272)
			(xy 349.304125 -410.33596) (xy 349.258284 -410.365425) (xy 349.208717 -410.388067) (xy 349.156433 -410.403425)
			(xy 349.102495 -410.411187) (xy 349.075248 -410.411676) (xy 348.211648 -410.411676) (xy 348.184391 -410.41128)
			(xy 348.13043 -410.403528) (xy 348.078122 -410.388175) (xy 348.028531 -410.365533) (xy 347.982668 -410.336064)
			(xy 347.941466 -410.300367) (xy 347.905765 -410.25917) (xy 347.87629 -410.213311) (xy 347.853642 -410.163723)
			(xy 347.838282 -410.111417) (xy 347.830523 -410.057457) (xy 346.392989 -410.057457) (xy 346.385234 -410.111391)
			(xy 346.369881 -410.163681) (xy 346.347242 -410.213253) (xy 346.317779 -410.259099) (xy 346.282091 -410.300286)
			(xy 346.240906 -410.335974) (xy 346.19506 -410.365438) (xy 346.145488 -410.388078) (xy 346.093199 -410.403432)
			(xy 346.039257 -410.411189) (xy 346.012008 -410.411676) (xy 345.148408 -410.411676) (xy 345.121152 -410.411278)
			(xy 345.067196 -410.403521) (xy 345.014893 -410.388164) (xy 344.965307 -410.36552) (xy 344.919449 -410.33605)
			(xy 344.878252 -410.300353) (xy 344.842555 -410.259157) (xy 344.813084 -410.2133) (xy 344.790439 -410.163715)
			(xy 344.775081 -410.111412) (xy 344.767323 -410.057456) (xy 343.329812 -410.057456) (xy 343.322055 -410.111401)
			(xy 343.306699 -410.163697) (xy 343.284056 -410.213275) (xy 343.254588 -410.259126) (xy 343.218894 -410.300316)
			(xy 343.177701 -410.336007) (xy 343.131847 -410.365472) (xy 343.082267 -410.38811) (xy 343.02997 -410.403462)
			(xy 342.97602 -410.411215) (xy 342.948768 -410.411676) (xy 342.085168 -410.411676) (xy 342.057916 -410.411252)
			(xy 342.003967 -410.403491) (xy 341.951672 -410.388132) (xy 341.902095 -410.365487) (xy 341.856244 -410.336017)
			(xy 341.815054 -410.300323) (xy 341.779363 -410.25913) (xy 341.749898 -410.213277) (xy 341.727257 -410.163698)
			(xy 341.711902 -410.111402) (xy 341.704146 -410.057452) (xy 340.266489 -410.057452) (xy 340.258735 -410.111388)
			(xy 340.243382 -410.163676) (xy 340.220745 -410.213248) (xy 340.191284 -410.259093) (xy 340.155599 -410.300279)
			(xy 340.114415 -410.335967) (xy 340.068572 -410.365432) (xy 340.019003 -410.388073) (xy 339.966716 -410.403429)
			(xy 339.912776 -410.411188) (xy 339.885528 -410.411676) (xy 339.021928 -410.411676) (xy 338.994672 -410.411279)
			(xy 338.940713 -410.403525) (xy 338.888407 -410.38817) (xy 338.838819 -410.365527) (xy 338.792959 -410.336057)
			(xy 338.751759 -410.30036) (xy 338.71606 -410.259164) (xy 338.686587 -410.213305) (xy 338.66394 -410.163719)
			(xy 338.648581 -410.111414) (xy 338.640823 -410.057456) (xy 337.203312 -410.057456) (xy 337.195556 -410.111399)
			(xy 337.180201 -410.163693) (xy 337.157559 -410.21327) (xy 337.128093 -410.25912) (xy 337.092401 -410.300309)
			(xy 337.05121 -410.336) (xy 337.005359 -410.365465) (xy 336.955782 -410.388105) (xy 336.903487 -410.403459)
			(xy 336.849539 -410.411214) (xy 336.822288 -410.411676) (xy 335.958688 -410.411676) (xy 335.931435 -410.411253)
			(xy 335.877484 -410.403495) (xy 335.825186 -410.388137) (xy 335.775607 -410.365494) (xy 335.729754 -410.336025)
			(xy 335.688562 -410.30033) (xy 335.652868 -410.259137) (xy 335.623401 -410.213283) (xy 335.600758 -410.163702)
			(xy 335.585403 -410.111404) (xy 335.577646 -410.057453) (xy 334.139989 -410.057453) (xy 334.132235 -410.111386)
			(xy 334.116884 -410.163672) (xy 334.094248 -410.213242) (xy 334.064789 -410.259086) (xy 334.029106 -410.300272)
			(xy 333.987925 -410.33596) (xy 333.942084 -410.365425) (xy 333.892517 -410.388067) (xy 333.840233 -410.403425)
			(xy 333.786295 -410.411187) (xy 333.759048 -410.411676) (xy 332.895448 -410.411676) (xy 332.868191 -410.41128)
			(xy 332.81423 -410.403528) (xy 332.761922 -410.388175) (xy 332.712331 -410.365533) (xy 332.666468 -410.336064)
			(xy 332.625266 -410.300367) (xy 332.589565 -410.25917) (xy 332.56009 -410.213311) (xy 332.537442 -410.163723)
			(xy 332.522082 -410.111417) (xy 332.514323 -410.057457) (xy 331.076789 -410.057457) (xy 331.069034 -410.111391)
			(xy 331.053681 -410.163681) (xy 331.031042 -410.213253) (xy 331.001579 -410.259099) (xy 330.965891 -410.300286)
			(xy 330.924706 -410.335974) (xy 330.87886 -410.365438) (xy 330.829288 -410.388078) (xy 330.776999 -410.403432)
			(xy 330.723057 -410.411189) (xy 330.695808 -410.411676) (xy 329.832208 -410.411676) (xy 329.804952 -410.411278)
			(xy 329.750996 -410.403521) (xy 329.698693 -410.388164) (xy 329.649107 -410.36552) (xy 329.603249 -410.33605)
			(xy 329.562052 -410.300353) (xy 329.526355 -410.259157) (xy 329.496884 -410.2133) (xy 329.474239 -410.163715)
			(xy 329.458881 -410.111412) (xy 329.451123 -410.057456) (xy 328.013612 -410.057456) (xy 328.005855 -410.111401)
			(xy 327.990499 -410.163697) (xy 327.967856 -410.213275) (xy 327.938388 -410.259126) (xy 327.902694 -410.300316)
			(xy 327.861501 -410.336007) (xy 327.815647 -410.365472) (xy 327.766067 -410.38811) (xy 327.71377 -410.403462)
			(xy 327.65982 -410.411215) (xy 327.632568 -410.411676) (xy 326.768968 -410.411676) (xy 326.741716 -410.411252)
			(xy 326.687767 -410.403491) (xy 326.635472 -410.388132) (xy 326.585895 -410.365487) (xy 326.540044 -410.336017)
			(xy 326.498854 -410.300323) (xy 326.463163 -410.25913) (xy 326.433698 -410.213277) (xy 326.411057 -410.163698)
			(xy 326.395702 -410.111402) (xy 326.387946 -410.057452) (xy 324.950289 -410.057452) (xy 324.942535 -410.111388)
			(xy 324.927182 -410.163676) (xy 324.904545 -410.213248) (xy 324.875084 -410.259093) (xy 324.839399 -410.300279)
			(xy 324.798215 -410.335967) (xy 324.752372 -410.365432) (xy 324.702803 -410.388073) (xy 324.650516 -410.403429)
			(xy 324.596576 -410.411188) (xy 324.569328 -410.411676) (xy 323.705728 -410.411676) (xy 323.678472 -410.411279)
			(xy 323.624513 -410.403525) (xy 323.572207 -410.38817) (xy 323.522619 -410.365527) (xy 323.476759 -410.336057)
			(xy 323.435559 -410.30036) (xy 323.39986 -410.259164) (xy 323.370387 -410.213305) (xy 323.34774 -410.163719)
			(xy 323.332381 -410.111414) (xy 323.324623 -410.057456) (xy 321.887112 -410.057456) (xy 321.879356 -410.111399)
			(xy 321.864001 -410.163693) (xy 321.841359 -410.21327) (xy 321.811893 -410.25912) (xy 321.776201 -410.300309)
			(xy 321.73501 -410.336) (xy 321.689159 -410.365465) (xy 321.639582 -410.388105) (xy 321.587287 -410.403459)
			(xy 321.533339 -410.411214) (xy 321.506088 -410.411676) (xy 320.642488 -410.411676) (xy 320.615235 -410.411253)
			(xy 320.561284 -410.403495) (xy 320.508986 -410.388137) (xy 320.459407 -410.365494) (xy 320.413554 -410.336025)
			(xy 320.372362 -410.30033) (xy 320.336668 -410.259137) (xy 320.307201 -410.213283) (xy 320.284558 -410.163702)
			(xy 320.269203 -410.111404) (xy 320.261446 -410.057453) (xy 318.823789 -410.057453) (xy 318.816035 -410.111386)
			(xy 318.800684 -410.163672) (xy 318.778048 -410.213242) (xy 318.748589 -410.259086) (xy 318.712906 -410.300272)
			(xy 318.671725 -410.33596) (xy 318.625884 -410.365425) (xy 318.576317 -410.388067) (xy 318.524033 -410.403425)
			(xy 318.470095 -410.411187) (xy 318.442848 -410.411676) (xy 317.579248 -410.411676) (xy 317.551991 -410.41128)
			(xy 317.49803 -410.403528) (xy 317.445722 -410.388175) (xy 317.396131 -410.365533) (xy 317.350268 -410.336064)
			(xy 317.309066 -410.300367) (xy 317.273365 -410.25917) (xy 317.24389 -410.213311) (xy 317.221242 -410.163723)
			(xy 317.205882 -410.111417) (xy 317.198123 -410.057457) (xy 315.760589 -410.057457) (xy 315.752834 -410.111391)
			(xy 315.737481 -410.163681) (xy 315.714842 -410.213253) (xy 315.685379 -410.259099) (xy 315.649691 -410.300286)
			(xy 315.608506 -410.335974) (xy 315.56266 -410.365438) (xy 315.513088 -410.388078) (xy 315.460799 -410.403432)
			(xy 315.406857 -410.411189) (xy 315.379608 -410.411676) (xy 314.516008 -410.411676) (xy 314.488752 -410.411278)
			(xy 314.434796 -410.403521) (xy 314.382493 -410.388164) (xy 314.332907 -410.36552) (xy 314.287049 -410.33605)
			(xy 314.245852 -410.300353) (xy 314.210155 -410.259157) (xy 314.180684 -410.2133) (xy 314.158039 -410.163715)
			(xy 314.142681 -410.111412) (xy 314.134923 -410.057456) (xy 312.697412 -410.057456) (xy 312.689655 -410.111401)
			(xy 312.674299 -410.163697) (xy 312.651656 -410.213275) (xy 312.622188 -410.259126) (xy 312.586494 -410.300316)
			(xy 312.545301 -410.336007) (xy 312.499447 -410.365472) (xy 312.449867 -410.38811) (xy 312.39757 -410.403462)
			(xy 312.34362 -410.411215) (xy 312.316368 -410.411676) (xy 311.452768 -410.411676) (xy 311.425516 -410.411252)
			(xy 311.371567 -410.403491) (xy 311.319272 -410.388132) (xy 311.269695 -410.365487) (xy 311.223844 -410.336017)
			(xy 311.182654 -410.300323) (xy 311.146963 -410.25913) (xy 311.117498 -410.213277) (xy 311.094857 -410.163698)
			(xy 311.079502 -410.111402) (xy 311.071746 -410.057452) (xy 309.634089 -410.057452) (xy 309.626335 -410.111388)
			(xy 309.610982 -410.163676) (xy 309.588345 -410.213248) (xy 309.558884 -410.259093) (xy 309.523199 -410.300279)
			(xy 309.482015 -410.335967) (xy 309.436172 -410.365432) (xy 309.386603 -410.388073) (xy 309.334316 -410.403429)
			(xy 309.280376 -410.411188) (xy 309.253128 -410.411676) (xy 308.389528 -410.411676) (xy 308.362272 -410.411279)
			(xy 308.308313 -410.403525) (xy 308.256007 -410.38817) (xy 308.206419 -410.365527) (xy 308.160559 -410.336057)
			(xy 308.119359 -410.30036) (xy 308.08366 -410.259164) (xy 308.054187 -410.213305) (xy 308.03154 -410.163719)
			(xy 308.016181 -410.111414) (xy 308.008423 -410.057456) (xy 306.570912 -410.057456) (xy 306.563156 -410.111399)
			(xy 306.547801 -410.163693) (xy 306.525159 -410.21327) (xy 306.495693 -410.25912) (xy 306.460001 -410.300309)
			(xy 306.41881 -410.336) (xy 306.372959 -410.365465) (xy 306.323382 -410.388105) (xy 306.271087 -410.403459)
			(xy 306.217139 -410.411214) (xy 306.189888 -410.411676) (xy 305.326288 -410.411676) (xy 305.299035 -410.411253)
			(xy 305.245084 -410.403495) (xy 305.192786 -410.388137) (xy 305.143207 -410.365494) (xy 305.097354 -410.336025)
			(xy 305.056162 -410.30033) (xy 305.020468 -410.259137) (xy 304.991001 -410.213283) (xy 304.968358 -410.163702)
			(xy 304.953003 -410.111404) (xy 304.945246 -410.057453) (xy 280.83256 -410.057453) (xy 280.83256 -415.172652)
			(xy 280.832075 -415.197601) (xy 280.824257 -415.246884) (xy 280.808837 -415.294341) (xy 280.786193 -415.338807)
			(xy 280.756881 -415.37919) (xy 280.739596 -415.397188) (xy 280.152348 -415.984436) (xy 280.134386 -416.001764)
			(xy 280.094003 -416.03109) (xy 280.04953 -416.053738) (xy 280.002061 -416.069148) (xy 279.952766 -416.076943)
			(xy 279.927812 -416.0774) (xy 275.815552 -416.0774) (xy 270.724376 -421.168576) (xy 270.706392 -421.185878)
			(xy 270.666013 -421.215201) (xy 270.621545 -421.237847) (xy 270.574081 -421.253259) (xy 270.524791 -421.261055)
			(xy 270.49984 -421.26154) (xy 233.361992 -421.26154) (xy 231.01554 -423.607992) (xy 231.01554 -424.804386)
			(xy 357.679233 -424.804386) (xy 357.679233 -424.675246) (xy 357.687183 -424.546351) (xy 357.703053 -424.418191)
			(xy 357.726782 -424.29125) (xy 357.758281 -424.166011) (xy 357.79743 -424.042948) (xy 357.844081 -423.922529)
			(xy 357.898056 -423.80521) (xy 357.959151 -423.691436) (xy 358.027134 -423.581639) (xy 358.101748 -423.476236)
			(xy 358.182709 -423.375626) (xy 358.269709 -423.280191) (xy 358.36242 -423.190292) (xy 358.46049 -423.106271)
			(xy 358.563545 -423.028447) (xy 358.671196 -422.957115) (xy 358.783035 -422.892545) (xy 358.898636 -422.834983)
			(xy 359.017561 -422.784646) (xy 359.13936 -422.741726) (xy 359.26357 -422.706385) (xy 359.389719 -422.678758)
			(xy 359.517331 -422.658949) (xy 359.64592 -422.647033) (xy 359.774998 -422.643057) (xy 359.904076 -422.647033)
			(xy 360.032665 -422.658949) (xy 360.160277 -422.678758) (xy 360.286426 -422.706385) (xy 360.410636 -422.741726)
			(xy 360.532435 -422.784646) (xy 360.65136 -422.834983) (xy 360.766961 -422.892545) (xy 360.8788 -422.957115)
			(xy 360.986451 -423.028447) (xy 361.089506 -423.106271) (xy 361.187576 -423.190292) (xy 361.280287 -423.280191)
			(xy 361.367287 -423.375626) (xy 361.448248 -423.476236) (xy 361.522862 -423.581639) (xy 361.590845 -423.691436)
			(xy 361.65194 -423.80521) (xy 361.705915 -423.922529) (xy 361.752566 -424.042948) (xy 361.791715 -424.166011)
			(xy 361.823214 -424.29125) (xy 361.846943 -424.418191) (xy 361.853367 -424.470068) (xy 421.270176 -424.470068)
			(xy 421.270176 -417.770056) (xy 421.270681 -417.664527) (xy 421.278765 -417.453623) (xy 421.294922 -417.243184)
			(xy 421.319127 -417.033518) (xy 421.351345 -416.824934) (xy 421.391528 -416.617736) (xy 421.439619 -416.412229)
			(xy 421.495545 -416.208716) (xy 421.559226 -416.007493) (xy 421.630567 -415.808858) (xy 421.709464 -415.613101)
			(xy 421.795802 -415.420509) (xy 421.889452 -415.231366) (xy 421.990279 -415.045949) (xy 422.098134 -414.864529)
			(xy 422.212858 -414.687374) (xy 422.334284 -414.514743) (xy 422.462233 -414.34689) (xy 422.596517 -414.184061)
			(xy 422.73694 -414.026495) (xy 422.883295 -413.874423) (xy 423.035367 -413.728068) (xy 423.192933 -413.587645)
			(xy 423.355762 -413.453361) (xy 423.523615 -413.325412) (xy 423.696246 -413.203986) (xy 423.873401 -413.089262)
			(xy 424.054821 -412.981407) (xy 424.240238 -412.88058) (xy 424.429381 -412.78693) (xy 424.621973 -412.700592)
			(xy 424.81773 -412.621695) (xy 425.016365 -412.550354) (xy 425.217588 -412.486673) (xy 425.421101 -412.430747)
			(xy 425.626608 -412.382656) (xy 425.833806 -412.342473) (xy 426.04239 -412.310255) (xy 426.252056 -412.28605)
			(xy 426.462495 -412.269893) (xy 426.673399 -412.261809) (xy 426.884457 -412.261809) (xy 427.095361 -412.269893)
			(xy 427.3058 -412.28605) (xy 427.515466 -412.310255) (xy 427.72405 -412.342473) (xy 427.931248 -412.382656)
			(xy 428.136755 -412.430747) (xy 428.340268 -412.486673) (xy 428.541491 -412.550354) (xy 428.740126 -412.621695)
			(xy 428.935883 -412.700592) (xy 429.128475 -412.78693) (xy 429.317618 -412.88058) (xy 429.503035 -412.981407)
			(xy 429.684455 -413.089262) (xy 429.86161 -413.203986) (xy 430.034241 -413.325412) (xy 430.202094 -413.453361)
			(xy 430.364923 -413.587645) (xy 430.522489 -413.728068) (xy 430.674561 -413.874423) (xy 430.820916 -414.026495)
			(xy 430.961339 -414.184061) (xy 431.095623 -414.34689) (xy 431.223572 -414.514743) (xy 431.344998 -414.687374)
			(xy 431.459722 -414.864529) (xy 431.567577 -415.045949) (xy 431.668404 -415.231366) (xy 431.762054 -415.420509)
			(xy 431.848392 -415.613101) (xy 431.927289 -415.808858) (xy 431.99863 -416.007493) (xy 432.062311 -416.208716)
			(xy 432.118237 -416.412229) (xy 432.166328 -416.617736) (xy 432.206511 -416.824934) (xy 432.238729 -417.033518)
			(xy 432.262934 -417.243184) (xy 432.279091 -417.453623) (xy 432.287175 -417.664527) (xy 432.28768 -417.770056)
			(xy 432.28768 -424.470068) (xy 432.287175 -424.575597) (xy 432.279091 -424.786501) (xy 432.262934 -424.99694)
			(xy 432.238729 -425.206606) (xy 432.206511 -425.41519) (xy 432.166328 -425.622388) (xy 432.118237 -425.827895)
			(xy 432.062311 -426.031408) (xy 431.99863 -426.232631) (xy 431.927289 -426.431266) (xy 431.848392 -426.627023)
			(xy 431.762054 -426.819615) (xy 431.668404 -427.008758) (xy 431.567577 -427.194175) (xy 431.459722 -427.375595)
			(xy 431.344998 -427.55275) (xy 431.223572 -427.725381) (xy 431.095623 -427.893234) (xy 430.961339 -428.056063)
			(xy 430.820916 -428.213629) (xy 430.674561 -428.365701) (xy 430.522489 -428.512056) (xy 430.364923 -428.652479)
			(xy 430.202094 -428.786763) (xy 430.034241 -428.914712) (xy 429.86161 -429.036138) (xy 429.684455 -429.150862)
			(xy 429.503035 -429.258717) (xy 429.317618 -429.359544) (xy 429.128475 -429.453194) (xy 428.935883 -429.539532)
			(xy 428.740126 -429.618429) (xy 428.541491 -429.68977) (xy 428.340268 -429.753451) (xy 428.136755 -429.809377)
			(xy 427.931248 -429.857468) (xy 427.72405 -429.897651) (xy 427.515466 -429.929869) (xy 427.3058 -429.954074)
			(xy 427.095361 -429.970231) (xy 426.884457 -429.978315) (xy 426.673399 -429.978315) (xy 426.462495 -429.970231)
			(xy 426.252056 -429.954074) (xy 426.04239 -429.929869) (xy 425.833806 -429.897651) (xy 425.626608 -429.857468)
			(xy 425.421101 -429.809377) (xy 425.217588 -429.753451) (xy 425.016365 -429.68977) (xy 424.81773 -429.618429)
			(xy 424.621973 -429.539532) (xy 424.429381 -429.453194) (xy 424.240238 -429.359544) (xy 424.054821 -429.258717)
			(xy 423.873401 -429.150862) (xy 423.696246 -429.036138) (xy 423.523615 -428.914712) (xy 423.355762 -428.786763)
			(xy 423.192933 -428.652479) (xy 423.035367 -428.512056) (xy 422.883295 -428.365701) (xy 422.73694 -428.213629)
			(xy 422.596517 -428.056063) (xy 422.462233 -427.893234) (xy 422.334284 -427.725381) (xy 422.212858 -427.55275)
			(xy 422.098134 -427.375595) (xy 421.990279 -427.194175) (xy 421.889452 -427.008758) (xy 421.795802 -426.819615)
			(xy 421.709464 -426.627023) (xy 421.630567 -426.431266) (xy 421.559226 -426.232631) (xy 421.495545 -426.031408)
			(xy 421.439619 -425.827895) (xy 421.391528 -425.622388) (xy 421.351345 -425.41519) (xy 421.319127 -425.206606)
			(xy 421.294922 -424.99694) (xy 421.278765 -424.786501) (xy 421.270681 -424.575597) (xy 421.270176 -424.470068)
			(xy 361.853367 -424.470068) (xy 361.862813 -424.546351) (xy 361.870763 -424.675246) (xy 361.87126 -424.739816)
			(xy 361.870763 -424.804386) (xy 361.862813 -424.933281) (xy 361.846943 -425.061441) (xy 361.823214 -425.188382)
			(xy 361.791715 -425.313621) (xy 361.752566 -425.436684) (xy 361.705915 -425.557103) (xy 361.65194 -425.674422)
			(xy 361.590845 -425.788196) (xy 361.522862 -425.897993) (xy 361.448248 -426.003396) (xy 361.367287 -426.104006)
			(xy 361.280287 -426.199441) (xy 361.187576 -426.28934) (xy 361.089506 -426.373361) (xy 360.986451 -426.451185)
			(xy 360.8788 -426.522517) (xy 360.766961 -426.587087) (xy 360.65136 -426.644649) (xy 360.532435 -426.694986)
			(xy 360.410636 -426.737906) (xy 360.286426 -426.773247) (xy 360.160277 -426.800874) (xy 360.032665 -426.820683)
			(xy 359.904076 -426.832599) (xy 359.774998 -426.836576) (xy 359.64592 -426.832599) (xy 359.517331 -426.820683)
			(xy 359.389719 -426.800874) (xy 359.26357 -426.773247) (xy 359.13936 -426.737906) (xy 359.017561 -426.694986)
			(xy 358.898636 -426.644649) (xy 358.783035 -426.587087) (xy 358.671196 -426.522517) (xy 358.563545 -426.451185)
			(xy 358.46049 -426.373361) (xy 358.36242 -426.28934) (xy 358.269709 -426.199441) (xy 358.182709 -426.104006)
			(xy 358.101748 -426.003396) (xy 358.027134 -425.897993) (xy 357.959151 -425.788196) (xy 357.898056 -425.674422)
			(xy 357.844081 -425.557103) (xy 357.79743 -425.436684) (xy 357.758281 -425.313621) (xy 357.726782 -425.188382)
			(xy 357.703053 -425.061441) (xy 357.687183 -424.933281) (xy 357.679233 -424.804386) (xy 231.01554 -424.804386)
			(xy 231.01554 -427.289976) (xy 314.138056 -427.289976) (xy 314.13817 -427.274891) (xy 314.139948 -427.244772)
			(xy 314.141612 -427.229778) (xy 314.141612 -426.150024) (xy 314.139943 -426.135031) (xy 314.138165 -426.104912)
			(xy 314.138056 -426.089826) (xy 314.138166 -426.07474) (xy 314.139947 -426.044622) (xy 314.141612 -426.029628)
			(xy 314.141612 -425.419012) (xy 314.142023 -425.406928) (xy 314.14949 -425.383942) (xy 314.163696 -425.36439)
			(xy 314.183249 -425.350186) (xy 314.206236 -425.342722) (xy 314.21832 -425.342304) (xy 315.15812 -425.342304)
			(xy 315.170197 -425.342748) (xy 315.193167 -425.350217) (xy 315.212704 -425.364419) (xy 315.226898 -425.383962)
			(xy 315.234357 -425.406935) (xy 315.234828 -425.419012) (xy 315.234828 -427.960536) (xy 315.234367 -427.97261)
			(xy 315.226897 -427.995576) (xy 315.212699 -428.01511) (xy 315.193161 -428.029304) (xy 315.170195 -428.036769)
			(xy 315.15812 -428.037244) (xy 314.21832 -428.037244) (xy 314.20625 -428.036719) (xy 314.18329 -428.029267)
			(xy 314.163755 -428.015085) (xy 314.149559 -427.995561) (xy 314.142089 -427.972606) (xy 314.141612 -427.960536)
			(xy 314.141612 -427.350174) (xy 314.139948 -427.33518) (xy 314.138166 -427.305062) (xy 314.138056 -427.289976)
			(xy 231.01554 -427.289976) (xy 231.01554 -428.28972) (xy 316.138052 -428.28972) (xy 316.138162 -428.274634)
			(xy 316.139943 -428.244516) (xy 316.141608 -428.229522) (xy 316.141608 -427.150022) (xy 316.139939 -427.135029)
			(xy 316.138161 -427.10491) (xy 316.138052 -427.089824) (xy 316.138162 -427.074738) (xy 316.139943 -427.04462)
			(xy 316.141608 -427.029626) (xy 316.141608 -426.41901) (xy 316.142115 -426.406924) (xy 316.149565 -426.383929)
			(xy 316.163743 -426.364352) (xy 316.183266 -426.3501) (xy 316.206232 -426.342562) (xy 316.218316 -426.342048)
			(xy 317.158116 -426.342048) (xy 317.170221 -426.342502) (xy 317.193239 -426.349999) (xy 317.212808 -426.364253)
			(xy 317.227004 -426.383863) (xy 317.234433 -426.406904) (xy 317.234824 -426.41901) (xy 317.234824 -427.289976)
			(xy 318.138048 -427.289976) (xy 318.138162 -427.274891) (xy 318.13994 -427.244772) (xy 318.141604 -427.229778)
			(xy 318.141604 -426.150024) (xy 318.139935 -426.135031) (xy 318.138157 -426.104912) (xy 318.138048 -426.089826)
			(xy 318.138158 -426.07474) (xy 318.139939 -426.044622) (xy 318.141604 -426.029628) (xy 318.141604 -425.419012)
			(xy 318.142023 -425.406929) (xy 318.149489 -425.383944) (xy 318.163693 -425.364393) (xy 318.183244 -425.350189)
			(xy 318.206229 -425.342723) (xy 318.218312 -425.342304) (xy 319.158112 -425.342304) (xy 319.170188 -425.342754)
			(xy 319.193158 -425.350222) (xy 319.212696 -425.364421) (xy 319.226889 -425.383964) (xy 319.234349 -425.406935)
			(xy 319.23482 -425.419012) (xy 319.23482 -427.960536) (xy 319.234367 -427.972611) (xy 319.226896 -427.995578)
			(xy 319.212696 -428.015113) (xy 319.193156 -428.029307) (xy 319.170187 -428.036771) (xy 319.158112 -428.037244)
			(xy 318.218312 -428.037244) (xy 318.206242 -428.036726) (xy 318.183281 -428.029271) (xy 318.163747 -428.015087)
			(xy 318.149551 -427.995562) (xy 318.142081 -427.972606) (xy 318.141604 -427.960536) (xy 318.141604 -427.350174)
			(xy 318.13994 -427.33518) (xy 318.138158 -427.305062) (xy 318.138048 -427.289976) (xy 317.234824 -427.289976)
			(xy 317.234824 -428.28972) (xy 320.138044 -428.28972) (xy 320.138154 -428.274634) (xy 320.139935 -428.244516)
			(xy 320.1416 -428.229522) (xy 320.1416 -427.150022) (xy 320.139931 -427.135029) (xy 320.138153 -427.10491)
			(xy 320.138044 -427.089824) (xy 320.138154 -427.074738) (xy 320.139935 -427.04462) (xy 320.1416 -427.029626)
			(xy 320.1416 -426.41901) (xy 320.142115 -426.406925) (xy 320.149564 -426.383931) (xy 320.16374 -426.364355)
			(xy 320.183261 -426.350103) (xy 320.206225 -426.342563) (xy 320.218308 -426.342048) (xy 321.158108 -426.342048)
			(xy 321.170212 -426.342509) (xy 321.193231 -426.350004) (xy 321.212799 -426.364256) (xy 321.226996 -426.383865)
			(xy 321.234425 -426.406905) (xy 321.234816 -426.41901) (xy 321.234816 -427.289976) (xy 322.13804 -427.289976)
			(xy 322.138155 -427.274891) (xy 322.139932 -427.244772) (xy 322.141596 -427.229778) (xy 322.141596 -426.150024)
			(xy 322.139927 -426.135031) (xy 322.138149 -426.104912) (xy 322.13804 -426.089826) (xy 322.13815 -426.07474)
			(xy 322.139931 -426.044622) (xy 322.141596 -426.029628) (xy 322.141596 -425.419012) (xy 322.142023 -425.40693)
			(xy 322.149488 -425.383947) (xy 322.16369 -425.364396) (xy 322.183239 -425.350191) (xy 322.206222 -425.342724)
			(xy 322.218304 -425.342304) (xy 323.158104 -425.342304) (xy 323.170188 -425.342709) (xy 323.193173 -425.350179)
			(xy 323.212724 -425.364387) (xy 323.226928 -425.383941) (xy 323.234393 -425.406928) (xy 323.234812 -425.419012)
			(xy 323.234812 -427.960536) (xy 323.234367 -427.972612) (xy 323.226895 -427.99558) (xy 323.212693 -428.015116)
			(xy 323.193151 -428.029309) (xy 323.17018 -428.036772) (xy 323.158104 -428.037244) (xy 322.218304 -428.037244)
			(xy 322.206233 -428.036733) (xy 322.183272 -428.029276) (xy 322.163738 -428.01509) (xy 322.149542 -427.995564)
			(xy 322.142073 -427.972607) (xy 322.141596 -427.960536) (xy 322.141596 -427.350174) (xy 322.139932 -427.33518)
			(xy 322.13815 -427.305062) (xy 322.13804 -427.289976) (xy 321.234816 -427.289976) (xy 321.234816 -428.28972)
			(xy 324.138036 -428.28972) (xy 324.138148 -428.274634) (xy 324.139929 -428.244516) (xy 324.141592 -428.229522)
			(xy 324.141592 -427.150022) (xy 324.139923 -427.135029) (xy 324.138145 -427.10491) (xy 324.138036 -427.089824)
			(xy 324.138148 -427.074738) (xy 324.139929 -427.04462) (xy 324.141592 -427.029626) (xy 324.141592 -426.41901)
			(xy 324.142115 -426.406926) (xy 324.149563 -426.383934) (xy 324.163737 -426.364358) (xy 324.183256 -426.350105)
			(xy 324.206218 -426.342564) (xy 324.2183 -426.342048) (xy 325.1581 -426.342048) (xy 325.170204 -426.342515)
			(xy 325.193222 -426.350009) (xy 325.212791 -426.364259) (xy 325.226987 -426.383866) (xy 325.234417 -426.406905)
			(xy 325.234808 -426.41901) (xy 325.234808 -427.289976) (xy 326.138032 -427.289976) (xy 326.138149 -427.274891)
			(xy 326.139927 -427.244772) (xy 326.141588 -427.229778) (xy 326.141588 -426.150024) (xy 326.139919 -426.135031)
			(xy 326.138141 -426.104912) (xy 326.138032 -426.089826) (xy 326.138144 -426.07474) (xy 326.139925 -426.044622)
			(xy 326.141588 -426.029628) (xy 326.141588 -425.419012) (xy 326.142023 -425.40693) (xy 326.149487 -425.383949)
			(xy 326.163687 -425.364399) (xy 326.183234 -425.350194) (xy 326.206214 -425.342726) (xy 326.218296 -425.342304)
			(xy 327.158096 -425.342304) (xy 327.17018 -425.342716) (xy 327.193164 -425.350184) (xy 327.212716 -425.36439)
			(xy 327.22692 -425.383943) (xy 327.234385 -425.406928) (xy 327.234804 -425.419012) (xy 327.234804 -427.960536)
			(xy 327.234367 -427.972613) (xy 327.226894 -427.995582) (xy 327.21269 -428.015119) (xy 327.193146 -428.029312)
			(xy 327.170173 -428.036773) (xy 327.158096 -428.037244) (xy 326.218296 -428.037244) (xy 326.206225 -428.03674)
			(xy 326.183264 -428.02928) (xy 326.16373 -428.015093) (xy 326.149534 -427.995565) (xy 326.142065 -427.972607)
			(xy 326.141588 -427.960536) (xy 326.141588 -427.350174) (xy 326.139924 -427.33518) (xy 326.138142 -427.305062)
			(xy 326.138032 -427.289976) (xy 325.234808 -427.289976) (xy 325.234808 -428.28972) (xy 328.138028 -428.28972)
			(xy 328.13814 -428.274634) (xy 328.139921 -428.244516) (xy 328.141584 -428.229522) (xy 328.141584 -427.150022)
			(xy 328.139915 -427.135029) (xy 328.138137 -427.10491) (xy 328.138028 -427.089824) (xy 328.13814 -427.074738)
			(xy 328.139921 -427.04462) (xy 328.141584 -427.029626) (xy 328.141584 -426.41901) (xy 328.142017 -426.406917)
			(xy 328.149476 -426.383909) (xy 328.16367 -426.364325) (xy 328.183214 -426.350076) (xy 328.2062 -426.342551)
			(xy 328.218292 -426.342048) (xy 329.158092 -426.342048) (xy 329.170195 -426.342522) (xy 329.193214 -426.350013)
			(xy 329.212782 -426.364262) (xy 329.226979 -426.383868) (xy 329.234409 -426.406906) (xy 329.2348 -426.41901)
			(xy 329.2348 -427.289976) (xy 331.138022 -427.289976) (xy 331.138113 -427.275402) (xy 331.139767 -427.246301)
			(xy 331.141324 -427.23181) (xy 331.141324 -426.147992) (xy 331.139781 -426.1335) (xy 331.138128 -426.1044)
			(xy 331.138022 -426.089826) (xy 331.138117 -426.075252) (xy 331.139769 -426.046151) (xy 331.141324 -426.03166)
			(xy 331.141324 -425.419012) (xy 331.141727 -425.406901) (xy 331.149226 -425.38387) (xy 331.16349 -425.364295)
			(xy 331.183116 -425.350101) (xy 331.206174 -425.342684) (xy 331.218286 -425.342304) (xy 332.158086 -425.342304)
			(xy 332.170171 -425.342819) (xy 332.193165 -425.350267) (xy 332.212742 -425.364443) (xy 332.226995 -425.383964)
			(xy 332.234533 -425.406929) (xy 332.235048 -425.419012) (xy 332.235048 -427.960536) (xy 332.234615 -427.972642)
			(xy 332.227111 -427.995662) (xy 332.212852 -428.01523) (xy 332.193238 -428.029426) (xy 332.170193 -428.036854)
			(xy 332.158086 -428.037244) (xy 331.218286 -428.037244) (xy 331.206194 -428.036804) (xy 331.18319 -428.029342)
			(xy 331.163609 -428.015149) (xy 331.14936 -427.995609) (xy 331.141831 -427.972627) (xy 331.141324 -427.960536)
			(xy 331.141324 -427.348142) (xy 331.139777 -427.33365) (xy 331.138127 -427.30455) (xy 331.138022 -427.289976)
			(xy 329.2348 -427.289976) (xy 329.2348 -428.28972) (xy 333.138018 -428.28972) (xy 333.138113 -428.275146)
			(xy 333.139764 -428.246045) (xy 333.14132 -428.231554) (xy 333.14132 -427.14799) (xy 333.139777 -427.133498)
			(xy 333.138124 -427.104398) (xy 333.138018 -427.089824) (xy 333.138113 -427.07525) (xy 333.139765 -427.046149)
			(xy 333.14132 -427.031658) (xy 333.14132 -426.41901) (xy 333.14182 -426.406898) (xy 333.149302 -426.383858)
			(xy 333.163538 -426.364258) (xy 333.183133 -426.350015) (xy 333.20617 -426.342525) (xy 333.218282 -426.342048)
			(xy 334.158082 -426.342048) (xy 334.170205 -426.342475) (xy 334.193265 -426.349964) (xy 334.212881 -426.364213)
			(xy 334.227132 -426.383828) (xy 334.234623 -426.406887) (xy 334.235044 -426.41901) (xy 334.235044 -427.289976)
			(xy 335.138014 -427.289976) (xy 335.138104 -427.275402) (xy 335.139759 -427.246301) (xy 335.141316 -427.23181)
			(xy 335.141316 -426.147992) (xy 335.139773 -426.1335) (xy 335.13812 -426.1044) (xy 335.138014 -426.089826)
			(xy 335.138109 -426.075252) (xy 335.13976 -426.046151) (xy 335.141316 -426.03166) (xy 335.141316 -425.419012)
			(xy 335.141727 -425.406902) (xy 335.149225 -425.383873) (xy 335.163487 -425.364298) (xy 335.183111 -425.350104)
			(xy 335.206167 -425.342685) (xy 335.218278 -425.342304) (xy 336.158078 -425.342304) (xy 336.170163 -425.342825)
			(xy 336.193157 -425.350272) (xy 336.212734 -425.364446) (xy 336.226986 -425.383966) (xy 336.234525 -425.406929)
			(xy 336.23504 -425.419012) (xy 336.23504 -427.960536) (xy 336.234615 -427.972643) (xy 336.22711 -427.995664)
			(xy 336.21285 -428.015233) (xy 336.193233 -428.029428) (xy 336.170186 -428.036855) (xy 336.158078 -428.037244)
			(xy 335.218278 -428.037244) (xy 335.206186 -428.036811) (xy 335.183182 -428.029347) (xy 335.163601 -428.015152)
			(xy 335.149351 -427.99561) (xy 335.141823 -427.972627) (xy 335.141316 -427.960536) (xy 335.141316 -427.348142)
			(xy 335.139769 -427.33365) (xy 335.138119 -427.30455) (xy 335.138014 -427.289976) (xy 334.235044 -427.289976)
			(xy 334.235044 -428.28972) (xy 337.13801 -428.28972) (xy 337.138104 -428.275146) (xy 337.139756 -428.246045)
			(xy 337.141312 -428.231554) (xy 337.141312 -427.14799) (xy 337.139769 -427.133498) (xy 337.138116 -427.104398)
			(xy 337.13801 -427.089824) (xy 337.138104 -427.07525) (xy 337.139756 -427.046149) (xy 337.141312 -427.031658)
			(xy 337.141312 -426.41901) (xy 337.14182 -426.406899) (xy 337.149301 -426.38386) (xy 337.163535 -426.36426)
			(xy 337.183128 -426.350018) (xy 337.206163 -426.342526) (xy 337.218274 -426.342048) (xy 338.158074 -426.342048)
			(xy 338.170196 -426.342482) (xy 338.193256 -426.349969) (xy 338.212872 -426.364216) (xy 338.227124 -426.38383)
			(xy 338.234615 -426.406888) (xy 338.235036 -426.41901) (xy 338.235036 -427.289976) (xy 339.138006 -427.289976)
			(xy 339.138096 -427.275402) (xy 339.139751 -427.246301) (xy 339.141308 -427.23181) (xy 339.141308 -426.147992)
			(xy 339.139765 -426.1335) (xy 339.138112 -426.1044) (xy 339.138006 -426.089826) (xy 339.138101 -426.075252)
			(xy 339.139752 -426.046151) (xy 339.141308 -426.03166) (xy 339.141308 -425.419012) (xy 339.141727 -425.406903)
			(xy 339.149224 -425.383875) (xy 339.163485 -425.364301) (xy 339.183106 -425.350106) (xy 339.20616 -425.342687)
			(xy 339.21827 -425.342304) (xy 340.15807 -425.342304) (xy 340.170154 -425.342832) (xy 340.193148 -425.350276)
			(xy 340.212725 -425.364448) (xy 340.226978 -425.383967) (xy 340.234517 -425.40693) (xy 340.235032 -425.419012)
			(xy 340.235032 -427.960536) (xy 340.234615 -427.972644) (xy 340.227109 -427.995667) (xy 340.212847 -428.015236)
			(xy 340.193228 -428.029431) (xy 340.170179 -428.036856) (xy 340.15807 -428.037244) (xy 339.21827 -428.037244)
			(xy 339.206177 -428.036818) (xy 339.183173 -428.029351) (xy 339.163592 -428.015154) (xy 339.149343 -427.995612)
			(xy 339.141815 -427.972627) (xy 339.141308 -427.960536) (xy 339.141308 -427.348142) (xy 339.139761 -427.33365)
			(xy 339.138111 -427.30455) (xy 339.138006 -427.289976) (xy 338.235036 -427.289976) (xy 338.235036 -428.28972)
			(xy 341.138002 -428.28972) (xy 341.138096 -428.275146) (xy 341.139748 -428.246045) (xy 341.141304 -428.231554)
			(xy 341.141304 -427.14799) (xy 341.139761 -427.133498) (xy 341.138108 -427.104398) (xy 341.138002 -427.089824)
			(xy 341.138096 -427.07525) (xy 341.139748 -427.046149) (xy 341.141304 -427.031658) (xy 341.141304 -426.41901)
			(xy 341.14182 -426.406899) (xy 341.1493 -426.383862) (xy 341.163532 -426.364263) (xy 341.183123 -426.35002)
			(xy 341.206156 -426.342527) (xy 341.218266 -426.342048) (xy 342.158066 -426.342048) (xy 342.170188 -426.342489)
			(xy 342.193247 -426.349973) (xy 342.212864 -426.364219) (xy 342.227116 -426.383831) (xy 342.234607 -426.406888)
			(xy 342.235028 -426.41901) (xy 342.235028 -427.289976) (xy 343.137998 -427.289976) (xy 343.138088 -427.275402)
			(xy 343.139743 -427.246301) (xy 343.1413 -427.23181) (xy 343.1413 -426.147992) (xy 343.139757 -426.1335)
			(xy 343.138104 -426.1044) (xy 343.137998 -426.089826) (xy 343.138093 -426.075252) (xy 343.139744 -426.046151)
			(xy 343.1413 -426.03166) (xy 343.1413 -425.419012) (xy 343.141727 -425.406904) (xy 343.149223 -425.383877)
			(xy 343.163482 -425.364304) (xy 343.183101 -425.350109) (xy 343.206152 -425.342688) (xy 343.218262 -425.342304)
			(xy 344.158062 -425.342304) (xy 344.170146 -425.342839) (xy 344.193139 -425.350281) (xy 344.212717 -425.364451)
			(xy 344.22697 -425.383968) (xy 344.234509 -425.40693) (xy 344.235024 -425.419012) (xy 344.235024 -427.960536)
			(xy 344.234615 -427.972644) (xy 344.227108 -427.995669) (xy 344.212844 -428.015239) (xy 344.193223 -428.029433)
			(xy 344.170172 -428.036857) (xy 344.158062 -428.037244) (xy 343.218262 -428.037244) (xy 343.206169 -428.036825)
			(xy 343.183164 -428.029356) (xy 343.163584 -428.015157) (xy 343.149335 -427.995613) (xy 343.141807 -427.972628)
			(xy 343.1413 -427.960536) (xy 343.1413 -427.348142) (xy 343.139753 -427.33365) (xy 343.138103 -427.30455)
			(xy 343.137998 -427.289976) (xy 342.235028 -427.289976) (xy 342.235028 -428.28972) (xy 345.137994 -428.28972)
			(xy 345.138088 -428.275146) (xy 345.13974 -428.246045) (xy 345.141296 -428.231554) (xy 345.141296 -427.14799)
			(xy 345.139753 -427.133498) (xy 345.1381 -427.104398) (xy 345.137994 -427.089824) (xy 345.138088 -427.07525)
			(xy 345.13974 -427.046149) (xy 345.141296 -427.031658) (xy 345.141296 -426.41901) (xy 345.14182 -426.4069)
			(xy 345.149299 -426.383864) (xy 345.163529 -426.364266) (xy 345.183118 -426.350023) (xy 345.206148 -426.342528)
			(xy 345.218258 -426.342048) (xy 346.158058 -426.342048) (xy 346.17018 -426.342496) (xy 346.193239 -426.349978)
			(xy 346.212855 -426.364222) (xy 346.227108 -426.383833) (xy 346.234599 -426.406889) (xy 346.23502 -426.41901)
			(xy 346.23502 -427.289976) (xy 381.237998 -427.289976) (xy 381.238088 -427.275402) (xy 381.239743 -427.246301)
			(xy 381.2413 -427.23181) (xy 381.2413 -426.147992) (xy 381.239757 -426.1335) (xy 381.238104 -426.1044)
			(xy 381.237998 -426.089826) (xy 381.238093 -426.075252) (xy 381.239744 -426.046151) (xy 381.2413 -426.03166)
			(xy 381.2413 -425.419012) (xy 381.241727 -425.406904) (xy 381.249223 -425.383877) (xy 381.263482 -425.364304)
			(xy 381.283101 -425.350109) (xy 381.306152 -425.342688) (xy 381.318262 -425.342304) (xy 382.258062 -425.342304)
			(xy 382.270146 -425.342839) (xy 382.293139 -425.350281) (xy 382.312717 -425.364451) (xy 382.32697 -425.383968)
			(xy 382.334509 -425.40693) (xy 382.335024 -425.419012) (xy 382.335024 -427.960536) (xy 382.334615 -427.972644)
			(xy 382.327108 -427.995669) (xy 382.312844 -428.015239) (xy 382.293223 -428.029433) (xy 382.270172 -428.036857)
			(xy 382.258062 -428.037244) (xy 381.318262 -428.037244) (xy 381.306169 -428.036825) (xy 381.283164 -428.029356)
			(xy 381.263584 -428.015157) (xy 381.249335 -427.995613) (xy 381.241807 -427.972628) (xy 381.2413 -427.960536)
			(xy 381.2413 -427.348142) (xy 381.239753 -427.33365) (xy 381.238103 -427.30455) (xy 381.237998 -427.289976)
			(xy 346.23502 -427.289976) (xy 346.23502 -428.960534) (xy 346.234669 -428.972663) (xy 346.227162 -428.99573)
			(xy 346.212894 -429.015348) (xy 346.193262 -429.029597) (xy 346.170187 -429.03708) (xy 346.158058 -429.037496)
			(xy 345.218258 -429.037496) (xy 345.206145 -429.037025) (xy 345.183106 -429.02953) (xy 345.163508 -429.015287)
			(xy 345.149266 -428.995687) (xy 345.141774 -428.972647) (xy 345.141296 -428.960534) (xy 345.141296 -428.347886)
			(xy 345.139753 -428.333394) (xy 345.1381 -428.304294) (xy 345.137994 -428.28972) (xy 342.235028 -428.28972)
			(xy 342.235028 -428.960534) (xy 342.234617 -428.972654) (xy 342.227116 -428.995704) (xy 342.21286 -429.015308)
			(xy 342.193243 -429.029547) (xy 342.170186 -429.037027) (xy 342.158066 -429.037496) (xy 341.218266 -429.037496)
			(xy 341.206153 -429.037018) (xy 341.183114 -429.029525) (xy 341.163516 -429.015284) (xy 341.149275 -428.995686)
			(xy 341.141782 -428.972647) (xy 341.141304 -428.960534) (xy 341.141304 -428.347886) (xy 341.139761 -428.333394)
			(xy 341.138108 -428.304294) (xy 341.138002 -428.28972) (xy 338.235036 -428.28972) (xy 338.235036 -428.960534)
			(xy 338.234617 -428.972653) (xy 338.227117 -428.995702) (xy 338.212862 -429.015305) (xy 338.193248 -429.029545)
			(xy 338.170193 -429.037026) (xy 338.158074 -429.037496) (xy 337.218274 -429.037496) (xy 337.206161 -429.037011)
			(xy 337.183123 -429.029521) (xy 337.163525 -429.015281) (xy 337.149283 -428.995684) (xy 337.14179 -428.972646)
			(xy 337.141312 -428.960534) (xy 337.141312 -428.347886) (xy 337.139769 -428.333394) (xy 337.138116 -428.304294)
			(xy 337.13801 -428.28972) (xy 334.235044 -428.28972) (xy 334.235044 -428.960534) (xy 334.234617 -428.972652)
			(xy 334.227118 -428.9957) (xy 334.212865 -429.015302) (xy 334.193253 -429.029542) (xy 334.1702 -429.037025)
			(xy 334.158082 -429.037496) (xy 333.218282 -429.037496) (xy 333.20617 -429.037004) (xy 333.183132 -429.029516)
			(xy 333.163533 -429.015278) (xy 333.149291 -428.995683) (xy 333.141798 -428.972646) (xy 333.14132 -428.960534)
			(xy 333.14132 -428.347886) (xy 333.139777 -428.333394) (xy 333.138124 -428.304294) (xy 333.138018 -428.28972)
			(xy 329.2348 -428.28972) (xy 329.2348 -428.960534) (xy 329.234322 -428.972621) (xy 329.226861 -428.995616)
			(xy 329.212676 -429.015192) (xy 329.193148 -429.029443) (xy 329.170178 -429.036981) (xy 329.158092 -429.037496)
			(xy 328.218292 -429.037496) (xy 328.206182 -429.037091) (xy 328.183154 -429.029588) (xy 328.163581 -429.015324)
			(xy 328.149386 -428.9957) (xy 328.141967 -428.972645) (xy 328.141584 -428.960534) (xy 328.141584 -428.349918)
			(xy 328.139915 -428.334925) (xy 328.138137 -428.304806) (xy 328.138028 -428.28972) (xy 325.234808 -428.28972)
			(xy 325.234808 -428.960534) (xy 325.234323 -428.972621) (xy 325.226862 -428.995614) (xy 325.212679 -429.01519)
			(xy 325.193153 -429.029441) (xy 325.170185 -429.03698) (xy 325.1581 -429.037496) (xy 324.2183 -429.037496)
			(xy 324.206191 -429.037084) (xy 324.183163 -429.029584) (xy 324.163589 -429.015321) (xy 324.149395 -428.995699)
			(xy 324.141975 -428.972645) (xy 324.141592 -428.960534) (xy 324.141592 -428.349918) (xy 324.139923 -428.334925)
			(xy 324.138145 -428.304806) (xy 324.138036 -428.28972) (xy 321.234816 -428.28972) (xy 321.234816 -428.960534)
			(xy 321.234421 -428.97263) (xy 321.226949 -428.995639) (xy 321.212746 -429.015222) (xy 321.193195 -429.02947)
			(xy 321.170203 -429.036993) (xy 321.158108 -429.037496) (xy 320.218308 -429.037496) (xy 320.206199 -429.037077)
			(xy 320.183171 -429.029579) (xy 320.163598 -429.015319) (xy 320.149403 -428.995697) (xy 320.141983 -428.972644)
			(xy 320.1416 -428.960534) (xy 320.1416 -428.349918) (xy 320.139931 -428.334925) (xy 320.138153 -428.304806)
			(xy 320.138044 -428.28972) (xy 317.234824 -428.28972) (xy 317.234824 -428.960534) (xy 317.234421 -428.972629)
			(xy 317.226951 -428.995637) (xy 317.212749 -429.015219) (xy 317.1932 -429.029467) (xy 317.17021 -429.036992)
			(xy 317.158116 -429.037496) (xy 316.218316 -429.037496) (xy 316.206208 -429.03707) (xy 316.18318 -429.029574)
			(xy 316.163607 -429.015315) (xy 316.149412 -428.995695) (xy 316.141991 -428.972644) (xy 316.141608 -428.960534)
			(xy 316.141608 -428.349918) (xy 316.139939 -428.334925) (xy 316.138161 -428.304806) (xy 316.138052 -428.28972)
			(xy 231.01554 -428.28972) (xy 231.01554 -433.130695) (xy 266.885917 -433.130695) (xy 266.885917 -432.953425)
			(xy 266.89387 -432.776334) (xy 266.909761 -432.599778) (xy 266.933556 -432.424113) (xy 266.965209 -432.249692)
			(xy 267.004655 -432.076867) (xy 267.051815 -431.905986) (xy 267.106594 -431.737392) (xy 267.168882 -431.571427)
			(xy 267.238554 -431.408422) (xy 267.315468 -431.248708) (xy 267.399471 -431.092605) (xy 267.490392 -430.940428)
			(xy 267.588049 -430.792484) (xy 267.692246 -430.64907) (xy 267.802772 -430.510475) (xy 267.919404 -430.376978)
			(xy 268.041909 -430.248849) (xy 268.170038 -430.126344) (xy 268.303535 -430.009712) (xy 268.44213 -429.899186)
			(xy 268.585544 -429.794989) (xy 268.733488 -429.697332) (xy 268.885665 -429.606411) (xy 269.041768 -429.522408)
			(xy 269.201482 -429.445494) (xy 269.364487 -429.375822) (xy 269.530452 -429.313534) (xy 269.699046 -429.258755)
			(xy 269.869927 -429.211595) (xy 270.042752 -429.172149) (xy 270.217173 -429.140496) (xy 270.392838 -429.116701)
			(xy 270.569394 -429.10081) (xy 270.746485 -429.092857) (xy 270.923755 -429.092857) (xy 271.100846 -429.10081)
			(xy 271.277402 -429.116701) (xy 271.453067 -429.140496) (xy 271.627488 -429.172149) (xy 271.800313 -429.211595)
			(xy 271.971194 -429.258755) (xy 272.139788 -429.313534) (xy 272.305753 -429.375822) (xy 272.468758 -429.445494)
			(xy 272.628472 -429.522408) (xy 272.784575 -429.606411) (xy 272.936752 -429.697332) (xy 273.084696 -429.794989)
			(xy 273.22811 -429.899186) (xy 273.366705 -430.009712) (xy 273.500202 -430.126344) (xy 273.628331 -430.248849)
			(xy 273.750836 -430.376978) (xy 273.867468 -430.510475) (xy 273.977994 -430.64907) (xy 274.082191 -430.792484)
			(xy 274.146507 -430.889918) (xy 314.138056 -430.889918) (xy 314.138165 -430.874832) (xy 314.139947 -430.844714)
			(xy 314.141612 -430.82972) (xy 314.141612 -429.749966) (xy 314.139947 -429.734972) (xy 314.138166 -429.704854)
			(xy 314.138056 -429.689768) (xy 314.13817 -429.674682) (xy 314.139948 -429.644564) (xy 314.141612 -429.62957)
			(xy 314.141612 -429.018954) (xy 314.142068 -429.006865) (xy 314.149534 -428.983867) (xy 314.163724 -428.964291)
			(xy 314.183258 -428.950041) (xy 314.206232 -428.942505) (xy 314.21832 -428.941992) (xy 315.15812 -428.941992)
			(xy 315.170229 -428.942399) (xy 315.193256 -428.949903) (xy 315.212828 -428.964167) (xy 315.227022 -428.98379)
			(xy 315.234444 -429.006843) (xy 315.234828 -429.018954) (xy 315.234828 -431.560478) (xy 315.234373 -431.57257)
			(xy 315.226919 -431.595575) (xy 315.21273 -431.615158) (xy 315.193192 -431.629408) (xy 315.17021 -431.636935)
			(xy 315.15812 -431.63744) (xy 314.21832 -431.63744) (xy 314.206216 -431.636967) (xy 314.183196 -431.629478)
			(xy 314.163627 -431.61523) (xy 314.14943 -431.595622) (xy 314.142001 -431.572583) (xy 314.141612 -431.560478)
			(xy 314.141612 -430.950116) (xy 314.139943 -430.935123) (xy 314.138165 -430.905004) (xy 314.138056 -430.889918)
			(xy 274.146507 -430.889918) (xy 274.179848 -430.940428) (xy 274.270769 -431.092605) (xy 274.354772 -431.248708)
			(xy 274.431686 -431.408422) (xy 274.501358 -431.571427) (xy 274.563646 -431.737392) (xy 274.613204 -431.889916)
			(xy 316.138052 -431.889916) (xy 316.138161 -431.87483) (xy 316.139943 -431.844712) (xy 316.141608 -431.829718)
			(xy 316.141608 -430.749964) (xy 316.139943 -430.73497) (xy 316.138162 -430.704852) (xy 316.138052 -430.689766)
			(xy 316.138166 -430.67468) (xy 316.139944 -430.644562) (xy 316.141608 -430.629568) (xy 316.141608 -430.018952)
			(xy 316.142023 -430.006873) (xy 316.149501 -429.983902) (xy 316.16371 -429.964364) (xy 316.183259 -429.950172)
			(xy 316.206237 -429.942713) (xy 316.218316 -429.942244) (xy 317.158116 -429.942244) (xy 317.170187 -429.94275)
			(xy 317.193146 -429.950211) (xy 317.212679 -429.964399) (xy 317.226874 -429.983925) (xy 317.234345 -430.006882)
			(xy 317.234824 -430.018952) (xy 317.234824 -430.889918) (xy 318.138048 -430.889918) (xy 318.138157 -430.874832)
			(xy 318.139939 -430.844714) (xy 318.141604 -430.82972) (xy 318.141604 -429.749966) (xy 318.139939 -429.734972)
			(xy 318.138158 -429.704854) (xy 318.138048 -429.689768) (xy 318.138162 -429.674682) (xy 318.13994 -429.644564)
			(xy 318.141604 -429.62957) (xy 318.141604 -429.018954) (xy 318.142067 -429.006866) (xy 318.149532 -428.98387)
			(xy 318.163721 -428.964293) (xy 318.183253 -428.950043) (xy 318.206225 -428.942506) (xy 318.218312 -428.941992)
			(xy 319.158112 -428.941992) (xy 319.170221 -428.942406) (xy 319.193247 -428.949908) (xy 319.212819 -428.96417)
			(xy 319.227014 -428.983792) (xy 319.234436 -429.006844) (xy 319.23482 -429.018954) (xy 319.23482 -431.560478)
			(xy 319.234373 -431.57257) (xy 319.226918 -431.595577) (xy 319.212727 -431.615161) (xy 319.193187 -431.629411)
			(xy 319.170203 -431.636936) (xy 319.158112 -431.63744) (xy 318.218312 -431.63744) (xy 318.206208 -431.636974)
			(xy 318.183188 -431.629483) (xy 318.163618 -431.615232) (xy 318.149422 -431.595624) (xy 318.141993 -431.572583)
			(xy 318.141604 -431.560478) (xy 318.141604 -430.950116) (xy 318.139935 -430.935123) (xy 318.138157 -430.905004)
			(xy 318.138048 -430.889918) (xy 317.234824 -430.889918) (xy 317.234824 -431.889916) (xy 320.138044 -431.889916)
			(xy 320.138153 -431.87483) (xy 320.139935 -431.844712) (xy 320.1416 -431.829718) (xy 320.1416 -430.749964)
			(xy 320.139935 -430.73497) (xy 320.138154 -430.704852) (xy 320.138044 -430.689766) (xy 320.138158 -430.67468)
			(xy 320.139936 -430.644562) (xy 320.1416 -430.629568) (xy 320.1416 -430.018952) (xy 320.142023 -430.006874)
			(xy 320.1495 -429.983904) (xy 320.163707 -429.964367) (xy 320.183254 -429.950174) (xy 320.20623 -429.942714)
			(xy 320.218308 -429.942244) (xy 321.158108 -429.942244) (xy 321.170178 -429.942757) (xy 321.193137 -429.950216)
			(xy 321.21267 -429.964401) (xy 321.226866 -429.983927) (xy 321.234337 -430.006882) (xy 321.234816 -430.018952)
			(xy 321.234816 -430.889918) (xy 322.13804 -430.889918) (xy 322.138151 -430.874832) (xy 322.139933 -430.844714)
			(xy 322.141596 -430.82972) (xy 322.141596 -429.749966) (xy 322.139931 -429.734972) (xy 322.13815 -429.704854)
			(xy 322.13804 -429.689768) (xy 322.138154 -429.674682) (xy 322.139932 -429.644564) (xy 322.141596 -429.62957)
			(xy 322.141596 -429.018954) (xy 322.142067 -429.006866) (xy 322.149531 -428.983872) (xy 322.163718 -428.964296)
			(xy 322.183248 -428.950046) (xy 322.206218 -428.942507) (xy 322.218304 -428.941992) (xy 323.158104 -428.941992)
			(xy 323.170212 -428.942413) (xy 323.193238 -428.949912) (xy 323.212811 -428.964173) (xy 323.227006 -428.983793)
			(xy 323.234428 -429.006844) (xy 323.234812 -429.018954) (xy 323.234812 -431.560478) (xy 323.234373 -431.572571)
			(xy 323.226916 -431.595579) (xy 323.212724 -431.615164) (xy 323.193182 -431.629413) (xy 323.170196 -431.636937)
			(xy 323.158104 -431.63744) (xy 322.218304 -431.63744) (xy 322.206199 -431.636981) (xy 322.183179 -431.629488)
			(xy 322.163609 -431.615236) (xy 322.149413 -431.595625) (xy 322.141985 -431.572584) (xy 322.141596 -431.560478)
			(xy 322.141596 -430.950116) (xy 322.139927 -430.935123) (xy 322.138149 -430.905004) (xy 322.13804 -430.889918)
			(xy 321.234816 -430.889918) (xy 321.234816 -431.889916) (xy 324.138036 -431.889916) (xy 324.138147 -431.87483)
			(xy 324.139929 -431.844712) (xy 324.141592 -431.829718) (xy 324.141592 -430.749964) (xy 324.139927 -430.73497)
			(xy 324.138146 -430.704852) (xy 324.138036 -430.689766) (xy 324.138152 -430.674681) (xy 324.13993 -430.644562)
			(xy 324.141592 -430.629568) (xy 324.141592 -430.018952) (xy 324.142023 -430.006875) (xy 324.149499 -429.983906)
			(xy 324.163704 -429.96437) (xy 324.183249 -429.950177) (xy 324.206223 -429.942716) (xy 324.2183 -429.942244)
			(xy 325.1581 -429.942244) (xy 325.17017 -429.942764) (xy 325.193129 -429.95022) (xy 325.212662 -429.964404)
			(xy 325.226858 -429.983928) (xy 325.234329 -430.006883) (xy 325.234808 -430.018952) (xy 325.234808 -430.889918)
			(xy 326.138032 -430.889918) (xy 326.138143 -430.874832) (xy 326.139925 -430.844714) (xy 326.141588 -430.82972)
			(xy 326.141588 -429.749966) (xy 326.139923 -429.734972) (xy 326.138142 -429.704854) (xy 326.138032 -429.689768)
			(xy 326.138148 -429.674683) (xy 326.139926 -429.644564) (xy 326.141588 -429.62957) (xy 326.141588 -429.018954)
			(xy 326.141969 -429.006857) (xy 326.149444 -428.983847) (xy 326.163651 -428.964264) (xy 326.183205 -428.950016)
			(xy 326.2062 -428.942494) (xy 326.218296 -428.941992) (xy 327.158096 -428.941992) (xy 327.170204 -428.942419)
			(xy 327.19323 -428.949917) (xy 327.212802 -428.964176) (xy 327.226997 -428.983795) (xy 327.23442 -429.006845)
			(xy 327.234804 -429.018954) (xy 327.234804 -431.560478) (xy 327.234275 -431.572562) (xy 327.226829 -431.595555)
			(xy 327.212657 -431.615131) (xy 327.19314 -431.629384) (xy 327.170178 -431.636924) (xy 327.158096 -431.63744)
			(xy 326.218296 -431.63744) (xy 326.206191 -431.636988) (xy 326.18317 -431.629492) (xy 326.163601 -431.615238)
			(xy 326.149405 -431.595627) (xy 326.141977 -431.572584) (xy 326.141588 -431.560478) (xy 326.141588 -430.950116)
			(xy 326.139919 -430.935123) (xy 326.138141 -430.905004) (xy 326.138032 -430.889918) (xy 325.234808 -430.889918)
			(xy 325.234808 -431.889916) (xy 328.138028 -431.889916) (xy 328.138139 -431.87483) (xy 328.139921 -431.844712)
			(xy 328.141584 -431.829718) (xy 328.141584 -430.749964) (xy 328.139919 -430.73497) (xy 328.138138 -430.704852)
			(xy 328.138028 -430.689766) (xy 328.138144 -430.674681) (xy 328.139922 -430.644562) (xy 328.141584 -430.629568)
			(xy 328.141584 -430.018952) (xy 328.142023 -430.006876) (xy 328.149498 -429.983908) (xy 328.163701 -429.964373)
			(xy 328.183244 -429.95018) (xy 328.206215 -429.942717) (xy 328.218292 -429.942244) (xy 329.158092 -429.942244)
			(xy 329.170161 -429.94277) (xy 329.19312 -429.950225) (xy 329.212653 -429.964407) (xy 329.22685 -429.98393)
			(xy 329.234321 -430.006883) (xy 329.2348 -430.018952) (xy 329.2348 -430.889918) (xy 331.138022 -430.889918)
			(xy 331.138116 -430.875344) (xy 331.139768 -430.846243) (xy 331.141324 -430.831752) (xy 331.141324 -429.747934)
			(xy 331.139776 -429.733442) (xy 331.138126 -429.704342) (xy 331.138022 -429.689768) (xy 331.138121 -429.675194)
			(xy 331.13977 -429.646093) (xy 331.141324 -429.631602) (xy 331.141324 -429.018954) (xy 331.141772 -429.006838)
			(xy 331.14927 -428.983796) (xy 331.163519 -428.964196) (xy 331.183125 -428.949956) (xy 331.20617 -428.942467)
			(xy 331.218286 -428.941992) (xy 332.158086 -428.941992) (xy 332.170195 -428.942523) (xy 332.19323 -428.950001)
			(xy 332.212828 -428.964229) (xy 332.227072 -428.983816) (xy 332.234568 -429.006845) (xy 332.235048 -429.018954)
			(xy 332.235048 -431.560478) (xy 332.234621 -431.572601) (xy 332.227133 -431.595662) (xy 332.212884 -431.615278)
			(xy 332.193269 -431.62953) (xy 332.170209 -431.63702) (xy 332.158086 -431.63744) (xy 331.218286 -431.63744)
			(xy 331.20616 -431.637051) (xy 331.183097 -431.629553) (xy 331.163481 -431.615294) (xy 331.149231 -431.59567)
			(xy 331.141743 -431.572604) (xy 331.141324 -431.560478) (xy 331.141324 -430.948084) (xy 331.139781 -430.933592)
			(xy 331.138128 -430.904492) (xy 331.138022 -430.889918) (xy 329.2348 -430.889918) (xy 329.2348 -431.889916)
			(xy 333.138018 -431.889916) (xy 333.138112 -431.875342) (xy 333.139764 -431.846241) (xy 333.14132 -431.83175)
			(xy 333.14132 -430.747932) (xy 333.139772 -430.73344) (xy 333.138122 -430.70434) (xy 333.138018 -430.689766)
			(xy 333.138117 -430.675192) (xy 333.139766 -430.646091) (xy 333.14132 -430.6316) (xy 333.14132 -430.018952)
			(xy 333.141676 -430.006839) (xy 333.149191 -429.983806) (xy 333.163467 -429.964232) (xy 333.183103 -429.95004)
			(xy 333.206167 -429.942624) (xy 333.218282 -429.942244) (xy 334.158082 -429.942244) (xy 334.170171 -429.942723)
			(xy 334.193172 -429.950175) (xy 334.212752 -429.964358) (xy 334.227003 -429.98389) (xy 334.234535 -430.006865)
			(xy 334.235044 -430.018952) (xy 334.235044 -430.889918) (xy 335.138014 -430.889918) (xy 335.138108 -430.875344)
			(xy 335.13976 -430.846243) (xy 335.141316 -430.831752) (xy 335.141316 -429.747934) (xy 335.139768 -429.733442)
			(xy 335.138118 -429.704342) (xy 335.138014 -429.689768) (xy 335.138112 -429.675194) (xy 335.139762 -429.646093)
			(xy 335.141316 -429.631602) (xy 335.141316 -429.018954) (xy 335.141772 -429.006839) (xy 335.149269 -428.983798)
			(xy 335.163516 -428.964199) (xy 335.18312 -428.949958) (xy 335.206163 -428.942468) (xy 335.218278 -428.941992)
			(xy 336.158078 -428.941992) (xy 336.170187 -428.94253) (xy 336.193222 -428.950005) (xy 336.21282 -428.964232)
			(xy 336.227064 -428.983817) (xy 336.234559 -429.006846) (xy 336.23504 -429.018954) (xy 336.23504 -431.560478)
			(xy 336.234621 -431.572602) (xy 336.227132 -431.595664) (xy 336.212881 -431.615281) (xy 336.193264 -431.629532)
			(xy 336.170202 -431.637021) (xy 336.158078 -431.63744) (xy 335.218278 -431.63744) (xy 335.20616 -431.637007)
			(xy 335.183112 -431.629511) (xy 335.163509 -431.61526) (xy 335.149269 -431.595648) (xy 335.141786 -431.572596)
			(xy 335.141316 -431.560478) (xy 335.141316 -430.948084) (xy 335.139773 -430.933592) (xy 335.13812 -430.904492)
			(xy 335.138014 -430.889918) (xy 334.235044 -430.889918) (xy 334.235044 -431.889916) (xy 337.13801 -431.889916)
			(xy 337.138104 -431.875342) (xy 337.139756 -431.846241) (xy 337.141312 -431.83175) (xy 337.141312 -430.747932)
			(xy 337.139764 -430.73344) (xy 337.138114 -430.70434) (xy 337.13801 -430.689766) (xy 337.138108 -430.675192)
			(xy 337.139757 -430.646091) (xy 337.141312 -430.6316) (xy 337.141312 -430.018952) (xy 337.141676 -430.006839)
			(xy 337.14919 -429.983809) (xy 337.163465 -429.964235) (xy 337.183098 -429.950043) (xy 337.20616 -429.942625)
			(xy 337.218274 -429.942244) (xy 338.158074 -429.942244) (xy 338.170163 -429.94273) (xy 338.193163 -429.95018)
			(xy 338.212744 -429.964361) (xy 338.226995 -429.983891) (xy 338.234527 -430.006865) (xy 338.235036 -430.018952)
			(xy 338.235036 -430.889918) (xy 339.138006 -430.889918) (xy 339.1381 -430.875344) (xy 339.139752 -430.846243)
			(xy 339.141308 -430.831752) (xy 339.141308 -429.747934) (xy 339.13976 -429.733442) (xy 339.13811 -429.704342)
			(xy 339.138006 -429.689768) (xy 339.138104 -429.675194) (xy 339.139754 -429.646093) (xy 339.141308 -429.631602)
			(xy 339.141308 -429.018954) (xy 339.141772 -429.00684) (xy 339.149268 -428.9838) (xy 339.163513 -428.964202)
			(xy 339.183115 -428.949961) (xy 339.206156 -428.94247) (xy 339.21827 -428.941992) (xy 340.15807 -428.941992)
			(xy 340.170178 -428.942537) (xy 340.193213 -428.95001) (xy 340.212811 -428.964235) (xy 340.227055 -428.983819)
			(xy 340.234551 -429.006846) (xy 340.235032 -429.018954) (xy 340.235032 -431.560478) (xy 340.234621 -431.572603)
			(xy 340.227131 -431.595666) (xy 340.212878 -431.615284) (xy 340.193259 -431.629535) (xy 340.170195 -431.637022)
			(xy 340.15807 -431.63744) (xy 339.21827 -431.63744) (xy 339.206152 -431.637014) (xy 339.183104 -431.629515)
			(xy 339.163501 -431.615262) (xy 339.149261 -431.59565) (xy 339.141778 -431.572597) (xy 339.141308 -431.560478)
			(xy 339.141308 -430.948084) (xy 339.139764 -430.933592) (xy 339.138112 -430.904492) (xy 339.138006 -430.889918)
			(xy 338.235036 -430.889918) (xy 338.235036 -431.889916) (xy 341.138002 -431.889916) (xy 341.138096 -431.875342)
			(xy 341.139748 -431.846241) (xy 341.141304 -431.83175) (xy 341.141304 -430.747932) (xy 341.139756 -430.73344)
			(xy 341.138106 -430.70434) (xy 341.138002 -430.689766) (xy 341.1381 -430.675192) (xy 341.13975 -430.646091)
			(xy 341.141304 -430.6316) (xy 341.141304 -430.018952) (xy 341.141676 -430.00684) (xy 341.149189 -429.983811)
			(xy 341.163462 -429.964238) (xy 341.183093 -429.950045) (xy 341.206153 -429.942626) (xy 341.218266 -429.942244)
			(xy 342.158066 -429.942244) (xy 342.170154 -429.942736) (xy 342.193154 -429.950184) (xy 342.212735 -429.964364)
			(xy 342.226987 -429.983893) (xy 342.234519 -430.006866) (xy 342.235028 -430.018952) (xy 342.235028 -430.889918)
			(xy 343.137998 -430.889918) (xy 343.138092 -430.875344) (xy 343.139744 -430.846243) (xy 343.1413 -430.831752)
			(xy 343.1413 -429.747934) (xy 343.139752 -429.733442) (xy 343.138102 -429.704342) (xy 343.137998 -429.689768)
			(xy 343.138096 -429.675194) (xy 343.139746 -429.646093) (xy 343.1413 -429.631602) (xy 343.1413 -429.018954)
			(xy 343.141772 -429.006841) (xy 343.149267 -428.983803) (xy 343.163511 -428.964205) (xy 343.18311 -428.949964)
			(xy 343.206149 -428.942471) (xy 343.218262 -428.941992) (xy 344.158062 -428.941992) (xy 344.17017 -428.942543)
			(xy 344.193204 -428.950015) (xy 344.212803 -428.964238) (xy 344.227047 -428.98382) (xy 344.234543 -429.006847)
			(xy 344.235024 -429.018954) (xy 344.235024 -431.560478) (xy 344.234621 -431.572603) (xy 344.22713 -431.595668)
			(xy 344.212875 -431.615287) (xy 344.193254 -431.629537) (xy 344.170187 -431.637023) (xy 344.158062 -431.63744)
			(xy 343.218262 -431.63744) (xy 343.206143 -431.63702) (xy 343.183095 -431.62952) (xy 343.163492 -431.615265)
			(xy 343.149253 -431.595651) (xy 343.14177 -431.572597) (xy 343.1413 -431.560478) (xy 343.1413 -430.948084)
			(xy 343.139756 -430.933592) (xy 343.138104 -430.904492) (xy 343.137998 -430.889918) (xy 342.235028 -430.889918)
			(xy 342.235028 -431.889916) (xy 345.137994 -431.889916) (xy 345.138088 -431.875342) (xy 345.13974 -431.846241)
			(xy 345.141296 -431.83175) (xy 345.141296 -430.747932) (xy 345.139748 -430.73344) (xy 345.138098 -430.70434)
			(xy 345.137994 -430.689766) (xy 345.138092 -430.675192) (xy 345.139742 -430.646091) (xy 345.141296 -430.6316)
			(xy 345.141296 -430.018952) (xy 345.141676 -430.006841) (xy 345.149188 -429.983813) (xy 345.163459 -429.964241)
			(xy 345.183088 -429.950048) (xy 345.206145 -429.942628) (xy 345.218258 -429.942244) (xy 346.158058 -429.942244)
			(xy 346.170146 -429.942743) (xy 346.193146 -429.950189) (xy 346.212727 -429.964367) (xy 346.226979 -429.983894)
			(xy 346.234511 -430.006866) (xy 346.23502 -430.018952) (xy 346.23502 -431.359818) (xy 356.154736 -431.359818)
			(xy 356.155234 -431.274938) (xy 356.163191 -431.105365) (xy 356.179087 -430.936351) (xy 356.202888 -430.768268)
			(xy 356.234542 -430.601485) (xy 356.273978 -430.436369) (xy 356.32111 -430.273284) (xy 356.375834 -430.112586)
			(xy 356.438031 -429.954631) (xy 356.507563 -429.799764) (xy 356.584278 -429.648327) (xy 356.668006 -429.500651)
			(xy 356.758564 -429.357063) (xy 356.855753 -429.217877) (xy 356.95936 -429.0834) (xy 357.069155 -428.953927)
			(xy 357.184899 -428.829742) (xy 357.306336 -428.711119) (xy 357.4332 -428.598318) (xy 357.565211 -428.491588)
			(xy 357.702081 -428.391163) (xy 357.843506 -428.297264) (xy 357.989178 -428.210096) (xy 358.138776 -428.129853)
			(xy 358.29197 -428.056709) (xy 358.448424 -427.990827) (xy 358.607794 -427.93235) (xy 358.76973 -427.881408)
			(xy 358.933876 -427.838112) (xy 359.099871 -427.802557) (xy 359.26735 -427.774822) (xy 359.435945 -427.754968)
			(xy 359.605285 -427.743038) (xy 359.774998 -427.739059) (xy 359.944711 -427.743038) (xy 360.114051 -427.754968)
			(xy 360.282646 -427.774822) (xy 360.450125 -427.802557) (xy 360.61612 -427.838112) (xy 360.780266 -427.881408)
			(xy 360.942202 -427.93235) (xy 361.101572 -427.990827) (xy 361.258026 -428.056709) (xy 361.41122 -428.129853)
			(xy 361.560818 -428.210096) (xy 361.693883 -428.28972) (xy 383.237994 -428.28972) (xy 383.238088 -428.275146)
			(xy 383.23974 -428.246045) (xy 383.241296 -428.231554) (xy 383.241296 -427.14799) (xy 383.239753 -427.133498)
			(xy 383.2381 -427.104398) (xy 383.237994 -427.089824) (xy 383.238088 -427.07525) (xy 383.23974 -427.046149)
			(xy 383.241296 -427.031658) (xy 383.241296 -426.41901) (xy 383.24182 -426.4069) (xy 383.249299 -426.383864)
			(xy 383.263529 -426.364266) (xy 383.283118 -426.350023) (xy 383.306148 -426.342528) (xy 383.318258 -426.342048)
			(xy 384.258058 -426.342048) (xy 384.27018 -426.342496) (xy 384.293239 -426.349978) (xy 384.312855 -426.364222)
			(xy 384.327108 -426.383833) (xy 384.334599 -426.406889) (xy 384.33502 -426.41901) (xy 384.33502 -427.289976)
			(xy 385.23799 -427.289976) (xy 385.23808 -427.275402) (xy 385.239735 -427.246301) (xy 385.241292 -427.23181)
			(xy 385.241292 -426.147992) (xy 385.239749 -426.1335) (xy 385.238096 -426.1044) (xy 385.23799 -426.089826)
			(xy 385.238085 -426.075252) (xy 385.239736 -426.046151) (xy 385.241292 -426.03166) (xy 385.241292 -425.419012)
			(xy 385.241727 -425.406905) (xy 385.249222 -425.383879) (xy 385.263479 -425.364307) (xy 385.283096 -425.350111)
			(xy 385.306145 -425.342689) (xy 385.318254 -425.342304) (xy 386.258054 -425.342304) (xy 386.270138 -425.342846)
			(xy 386.293131 -425.350286) (xy 386.312708 -425.364454) (xy 386.326962 -425.38397) (xy 386.334501 -425.40693)
			(xy 386.335016 -425.419012) (xy 386.335016 -427.960536) (xy 386.334615 -427.972645) (xy 386.327107 -427.995671)
			(xy 386.312841 -428.015242) (xy 386.293218 -428.029436) (xy 386.270165 -428.036859) (xy 386.258054 -428.037244)
			(xy 385.318254 -428.037244) (xy 385.30616 -428.036832) (xy 385.283156 -428.02936) (xy 385.263575 -428.01516)
			(xy 385.249327 -427.995615) (xy 385.241799 -427.972628) (xy 385.241292 -427.960536) (xy 385.241292 -427.348142)
			(xy 385.239745 -427.33365) (xy 385.238095 -427.30455) (xy 385.23799 -427.289976) (xy 384.33502 -427.289976)
			(xy 384.33502 -428.28972) (xy 387.237986 -428.28972) (xy 387.23808 -428.275146) (xy 387.239732 -428.246045)
			(xy 387.241288 -428.231554) (xy 387.241288 -427.14799) (xy 387.239745 -427.133498) (xy 387.238092 -427.104398)
			(xy 387.237986 -427.089824) (xy 387.238081 -427.07525) (xy 387.239732 -427.046149) (xy 387.241288 -427.031658)
			(xy 387.241288 -426.41901) (xy 387.24182 -426.406901) (xy 387.249298 -426.383867) (xy 387.263526 -426.364269)
			(xy 387.283113 -426.350025) (xy 387.306141 -426.342529) (xy 387.31825 -426.342048) (xy 388.25805 -426.342048)
			(xy 388.270168 -426.342469) (xy 388.293215 -426.349972) (xy 388.312816 -426.364226) (xy 388.327056 -426.383839)
			(xy 388.33454 -426.406891) (xy 388.335012 -426.41901) (xy 388.335012 -427.289976) (xy 389.237982 -427.289976)
			(xy 389.238072 -427.275402) (xy 389.239727 -427.246301) (xy 389.241284 -427.23181) (xy 389.241284 -426.147992)
			(xy 389.239741 -426.1335) (xy 389.238088 -426.1044) (xy 389.237982 -426.089826) (xy 389.238077 -426.075252)
			(xy 389.239728 -426.046151) (xy 389.241284 -426.03166) (xy 389.241284 -425.419012) (xy 389.241727 -425.406905)
			(xy 389.249221 -425.383881) (xy 389.263476 -425.364309) (xy 389.283091 -425.350114) (xy 389.306138 -425.34269)
			(xy 389.318246 -425.342304) (xy 390.258046 -425.342304) (xy 390.270134 -425.342767) (xy 390.29313 -425.350232)
			(xy 390.312707 -425.364421) (xy 390.326957 -425.383953) (xy 390.334494 -425.406925) (xy 390.335008 -425.419012)
			(xy 390.335008 -427.960536) (xy 390.334614 -427.972646) (xy 390.327106 -427.995673) (xy 390.312838 -428.015245)
			(xy 390.293213 -428.029438) (xy 390.270157 -428.03686) (xy 390.258046 -428.037244) (xy 389.318246 -428.037244)
			(xy 389.306157 -428.036753) (xy 389.283155 -428.029307) (xy 389.263573 -428.015127) (xy 389.249322 -427.995597)
			(xy 389.241791 -427.972623) (xy 389.241284 -427.960536) (xy 389.241284 -427.348142) (xy 389.239737 -427.33365)
			(xy 389.238087 -427.30455) (xy 389.237982 -427.289976) (xy 388.335012 -427.289976) (xy 388.335012 -428.28972)
			(xy 391.237978 -428.28972) (xy 391.238072 -428.275146) (xy 391.239724 -428.246045) (xy 391.24128 -428.231554)
			(xy 391.24128 -427.14799) (xy 391.239737 -427.133498) (xy 391.238084 -427.104398) (xy 391.237978 -427.089824)
			(xy 391.238073 -427.07525) (xy 391.239724 -427.046149) (xy 391.24128 -427.031658) (xy 391.24128 -426.41901)
			(xy 391.241669 -426.406884) (xy 391.249164 -426.383818) (xy 391.263422 -426.364199) (xy 391.283047 -426.349949)
			(xy 391.306115 -426.342464) (xy 391.318242 -426.342048) (xy 392.258042 -426.342048) (xy 392.27016 -426.342476)
			(xy 392.293206 -426.349976) (xy 392.312808 -426.364229) (xy 392.327048 -426.383841) (xy 392.334532 -426.406892)
			(xy 392.335004 -426.41901) (xy 392.335004 -427.289976) (xy 393.237974 -427.289976) (xy 393.238064 -427.275402)
			(xy 393.239719 -427.246301) (xy 393.241276 -427.23181) (xy 393.241276 -426.147992) (xy 393.239733 -426.1335)
			(xy 393.23808 -426.1044) (xy 393.237974 -426.089826) (xy 393.238069 -426.075252) (xy 393.23972 -426.046151)
			(xy 393.241276 -426.03166) (xy 393.241276 -425.419012) (xy 393.241726 -425.406906) (xy 393.24922 -425.383883)
			(xy 393.263473 -425.364312) (xy 393.283086 -425.350116) (xy 393.306131 -425.342691) (xy 393.318238 -425.342304)
			(xy 394.258038 -425.342304) (xy 394.270126 -425.342774) (xy 394.293122 -425.350237) (xy 394.312698 -425.364424)
			(xy 394.326949 -425.383954) (xy 394.334486 -425.406926) (xy 394.335 -425.419012) (xy 394.335 -427.960536)
			(xy 394.334614 -427.972647) (xy 394.327105 -427.995675) (xy 394.312835 -428.015248) (xy 394.293208 -428.029441)
			(xy 394.27015 -428.036861) (xy 394.258038 -428.037244) (xy 393.318238 -428.037244) (xy 393.306149 -428.03676)
			(xy 393.283147 -428.029312) (xy 393.263565 -428.01513) (xy 393.249314 -427.995599) (xy 393.241783 -427.972623)
			(xy 393.241276 -427.960536) (xy 393.241276 -427.348142) (xy 393.239729 -427.33365) (xy 393.238079 -427.30455)
			(xy 393.237974 -427.289976) (xy 392.335004 -427.289976) (xy 392.335004 -428.28972) (xy 395.23797 -428.28972)
			(xy 395.238064 -428.275146) (xy 395.239716 -428.246045) (xy 395.241272 -428.231554) (xy 395.241272 -427.14799)
			(xy 395.239729 -427.133498) (xy 395.238076 -427.104398) (xy 395.23797 -427.089824) (xy 395.238065 -427.07525)
			(xy 395.239716 -427.046149) (xy 395.241272 -427.031658) (xy 395.241272 -426.41901) (xy 395.241669 -426.406884)
			(xy 395.249163 -426.38382) (xy 395.263419 -426.364202) (xy 395.283042 -426.349952) (xy 395.306108 -426.342465)
			(xy 395.318234 -426.342048) (xy 396.258034 -426.342048) (xy 396.270151 -426.342483) (xy 396.293197 -426.349981)
			(xy 396.312799 -426.364232) (xy 396.327039 -426.383842) (xy 396.334524 -426.406892) (xy 396.334996 -426.41901)
			(xy 396.334996 -427.289976) (xy 398.237964 -427.289976) (xy 398.238078 -427.274891) (xy 398.239856 -427.244772)
			(xy 398.24152 -427.229778) (xy 398.24152 -426.150024) (xy 398.239851 -426.135031) (xy 398.238073 -426.104912)
			(xy 398.237964 -426.089826) (xy 398.238074 -426.07474) (xy 398.239855 -426.044622) (xy 398.24152 -426.029628)
			(xy 398.24152 -425.419012) (xy 398.241924 -425.406927) (xy 398.249391 -425.38394) (xy 398.263599 -425.364387)
			(xy 398.283154 -425.350184) (xy 398.306143 -425.342721) (xy 398.318228 -425.342304) (xy 399.258028 -425.342304)
			(xy 399.270105 -425.34274) (xy 399.293075 -425.350212) (xy 399.312613 -425.364415) (xy 399.326806 -425.38396)
			(xy 399.334266 -425.406935) (xy 399.334736 -425.419012) (xy 399.334736 -427.960536) (xy 399.334267 -427.97261)
			(xy 399.326798 -427.995573) (xy 399.312602 -428.015107) (xy 399.293066 -428.029302) (xy 399.270102 -428.036768)
			(xy 399.258028 -428.037244) (xy 398.318228 -428.037244) (xy 398.306158 -428.036713) (xy 398.283198 -428.029262)
			(xy 398.263664 -428.015082) (xy 398.249467 -427.995559) (xy 398.241997 -427.972605) (xy 398.24152 -427.960536)
			(xy 398.24152 -427.350174) (xy 398.239856 -427.33518) (xy 398.238074 -427.305062) (xy 398.237964 -427.289976)
			(xy 396.334996 -427.289976) (xy 396.334996 -428.28972) (xy 400.23796 -428.28972) (xy 400.238069 -428.274634)
			(xy 400.239851 -428.244516) (xy 400.241516 -428.229522) (xy 400.241516 -427.150022) (xy 400.239847 -427.135029)
			(xy 400.238069 -427.10491) (xy 400.23796 -427.089824) (xy 400.23807 -427.074738) (xy 400.239851 -427.04462)
			(xy 400.241516 -427.029626) (xy 400.241516 -426.41901) (xy 400.242016 -426.406923) (xy 400.249467 -426.383927)
			(xy 400.263646 -426.364349) (xy 400.283171 -426.350097) (xy 400.306139 -426.342561) (xy 400.318224 -426.342048)
			(xy 401.258024 -426.342048) (xy 401.270129 -426.342495) (xy 401.293148 -426.349995) (xy 401.312716 -426.36425)
			(xy 401.326912 -426.383862) (xy 401.334341 -426.406904) (xy 401.334732 -426.41901) (xy 401.334732 -427.289976)
			(xy 402.237956 -427.289976) (xy 402.23807 -427.274891) (xy 402.239848 -427.244772) (xy 402.241512 -427.229778)
			(xy 402.241512 -426.150024) (xy 402.239843 -426.135031) (xy 402.238065 -426.104912) (xy 402.237956 -426.089826)
			(xy 402.238066 -426.07474) (xy 402.239847 -426.044622) (xy 402.241512 -426.029628) (xy 402.241512 -425.419012)
			(xy 402.241923 -425.406928) (xy 402.24939 -425.383942) (xy 402.263596 -425.36439) (xy 402.283149 -425.350186)
			(xy 402.306136 -425.342722) (xy 402.31822 -425.342304) (xy 403.25802 -425.342304) (xy 403.270097 -425.342748)
			(xy 403.293067 -425.350217) (xy 403.312604 -425.364419) (xy 403.326798 -425.383962) (xy 403.334257 -425.406935)
			(xy 403.334728 -425.419012) (xy 403.334728 -427.960536) (xy 403.334267 -427.97261) (xy 403.326797 -427.995576)
			(xy 403.312599 -428.01511) (xy 403.293061 -428.029304) (xy 403.270095 -428.036769) (xy 403.25802 -428.037244)
			(xy 402.31822 -428.037244) (xy 402.30615 -428.036719) (xy 402.28319 -428.029267) (xy 402.263655 -428.015085)
			(xy 402.249459 -427.995561) (xy 402.241989 -427.972606) (xy 402.241512 -427.960536) (xy 402.241512 -427.350174)
			(xy 402.239848 -427.33518) (xy 402.238066 -427.305062) (xy 402.237956 -427.289976) (xy 401.334732 -427.289976)
			(xy 401.334732 -428.28972) (xy 404.237952 -428.28972) (xy 404.238062 -428.274634) (xy 404.239843 -428.244516)
			(xy 404.241508 -428.229522) (xy 404.241508 -427.150022) (xy 404.239839 -427.135029) (xy 404.238061 -427.10491)
			(xy 404.237952 -427.089824) (xy 404.238062 -427.074738) (xy 404.239843 -427.04462) (xy 404.241508 -427.029626)
			(xy 404.241508 -426.41901) (xy 404.242015 -426.406924) (xy 404.249465 -426.383929) (xy 404.263643 -426.364352)
			(xy 404.283166 -426.3501) (xy 404.306132 -426.342562) (xy 404.318216 -426.342048) (xy 405.258016 -426.342048)
			(xy 405.270121 -426.342502) (xy 405.293139 -426.349999) (xy 405.312708 -426.364253) (xy 405.326904 -426.383863)
			(xy 405.334333 -426.406904) (xy 405.334724 -426.41901) (xy 405.334724 -427.289976) (xy 406.237948 -427.289976)
			(xy 406.238062 -427.274891) (xy 406.23984 -427.244772) (xy 406.241504 -427.229778) (xy 406.241504 -426.150024)
			(xy 406.239835 -426.135031) (xy 406.238057 -426.104912) (xy 406.237948 -426.089826) (xy 406.238058 -426.07474)
			(xy 406.239839 -426.044622) (xy 406.241504 -426.029628) (xy 406.241504 -425.419012) (xy 406.241923 -425.406929)
			(xy 406.249389 -425.383944) (xy 406.263593 -425.364393) (xy 406.283144 -425.350189) (xy 406.306129 -425.342723)
			(xy 406.318212 -425.342304) (xy 407.258012 -425.342304) (xy 407.270088 -425.342754) (xy 407.293058 -425.350222)
			(xy 407.312596 -425.364421) (xy 407.326789 -425.383964) (xy 407.334249 -425.406935) (xy 407.33472 -425.419012)
			(xy 407.33472 -427.960536) (xy 407.334267 -427.972611) (xy 407.326796 -427.995578) (xy 407.312596 -428.015113)
			(xy 407.293056 -428.029307) (xy 407.270087 -428.036771) (xy 407.258012 -428.037244) (xy 406.318212 -428.037244)
			(xy 406.306142 -428.036726) (xy 406.283181 -428.029271) (xy 406.263647 -428.015087) (xy 406.249451 -427.995562)
			(xy 406.241981 -427.972606) (xy 406.241504 -427.960536) (xy 406.241504 -427.350174) (xy 406.23984 -427.33518)
			(xy 406.238058 -427.305062) (xy 406.237948 -427.289976) (xy 405.334724 -427.289976) (xy 405.334724 -428.28972)
			(xy 408.237944 -428.28972) (xy 408.238054 -428.274634) (xy 408.239835 -428.244516) (xy 408.2415 -428.229522)
			(xy 408.2415 -427.150022) (xy 408.239831 -427.135029) (xy 408.238053 -427.10491) (xy 408.237944 -427.089824)
			(xy 408.238054 -427.074738) (xy 408.239835 -427.04462) (xy 408.2415 -427.029626) (xy 408.2415 -426.41901)
			(xy 408.242015 -426.406925) (xy 408.249464 -426.383931) (xy 408.26364 -426.364355) (xy 408.283161 -426.350103)
			(xy 408.306125 -426.342563) (xy 408.318208 -426.342048) (xy 409.258008 -426.342048) (xy 409.270112 -426.342509)
			(xy 409.293131 -426.350004) (xy 409.312699 -426.364256) (xy 409.326896 -426.383865) (xy 409.334325 -426.406905)
			(xy 409.334716 -426.41901) (xy 409.334716 -427.289976) (xy 410.23794 -427.289976) (xy 410.238055 -427.274891)
			(xy 410.239832 -427.244772) (xy 410.241496 -427.229778) (xy 410.241496 -426.150024) (xy 410.239827 -426.135031)
			(xy 410.238049 -426.104912) (xy 410.23794 -426.089826) (xy 410.23805 -426.07474) (xy 410.239831 -426.044622)
			(xy 410.241496 -426.029628) (xy 410.241496 -425.419012) (xy 410.241923 -425.40693) (xy 410.249388 -425.383947)
			(xy 410.26359 -425.364396) (xy 410.283139 -425.350191) (xy 410.306122 -425.342724) (xy 410.318204 -425.342304)
			(xy 411.258004 -425.342304) (xy 411.270088 -425.342709) (xy 411.293073 -425.350179) (xy 411.312624 -425.364387)
			(xy 411.326828 -425.383941) (xy 411.334293 -425.406928) (xy 411.334712 -425.419012) (xy 411.334712 -427.960536)
			(xy 411.334267 -427.972612) (xy 411.326795 -427.99558) (xy 411.312593 -428.015116) (xy 411.293051 -428.029309)
			(xy 411.27008 -428.036772) (xy 411.258004 -428.037244) (xy 410.318204 -428.037244) (xy 410.306133 -428.036733)
			(xy 410.283172 -428.029276) (xy 410.263638 -428.01509) (xy 410.249442 -427.995564) (xy 410.241973 -427.972607)
			(xy 410.241496 -427.960536) (xy 410.241496 -427.350174) (xy 410.239832 -427.33518) (xy 410.23805 -427.305062)
			(xy 410.23794 -427.289976) (xy 409.334716 -427.289976) (xy 409.334716 -428.28972) (xy 412.237936 -428.28972)
			(xy 412.238048 -428.274634) (xy 412.239829 -428.244516) (xy 412.241492 -428.229522) (xy 412.241492 -427.150022)
			(xy 412.239823 -427.135029) (xy 412.238045 -427.10491) (xy 412.237936 -427.089824) (xy 412.238048 -427.074738)
			(xy 412.239829 -427.04462) (xy 412.241492 -427.029626) (xy 412.241492 -426.41901) (xy 412.242015 -426.406926)
			(xy 412.249463 -426.383934) (xy 412.263637 -426.364358) (xy 412.283156 -426.350105) (xy 412.306118 -426.342564)
			(xy 412.3182 -426.342048) (xy 413.258 -426.342048) (xy 413.270104 -426.342515) (xy 413.293122 -426.350009)
			(xy 413.312691 -426.364259) (xy 413.326887 -426.383866) (xy 413.334317 -426.406905) (xy 413.334708 -426.41901)
			(xy 413.334708 -428.960534) (xy 413.334223 -428.972621) (xy 413.326762 -428.995614) (xy 413.312579 -429.01519)
			(xy 413.293053 -429.029441) (xy 413.270085 -429.03698) (xy 413.258 -429.037496) (xy 412.3182 -429.037496)
			(xy 412.306091 -429.037084) (xy 412.283063 -429.029584) (xy 412.263489 -429.015321) (xy 412.249295 -428.995699)
			(xy 412.241875 -428.972645) (xy 412.241492 -428.960534) (xy 412.241492 -428.349918) (xy 412.239823 -428.334925)
			(xy 412.238045 -428.304806) (xy 412.237936 -428.28972) (xy 409.334716 -428.28972) (xy 409.334716 -428.960534)
			(xy 409.334321 -428.97263) (xy 409.326849 -428.995639) (xy 409.312646 -429.015222) (xy 409.293095 -429.02947)
			(xy 409.270103 -429.036993) (xy 409.258008 -429.037496) (xy 408.318208 -429.037496) (xy 408.306099 -429.037077)
			(xy 408.283071 -429.029579) (xy 408.263498 -429.015319) (xy 408.249303 -428.995697) (xy 408.241883 -428.972644)
			(xy 408.2415 -428.960534) (xy 408.2415 -428.349918) (xy 408.239831 -428.334925) (xy 408.238053 -428.304806)
			(xy 408.237944 -428.28972) (xy 405.334724 -428.28972) (xy 405.334724 -428.960534) (xy 405.334321 -428.972629)
			(xy 405.326851 -428.995637) (xy 405.312649 -429.015219) (xy 405.2931 -429.029467) (xy 405.27011 -429.036992)
			(xy 405.258016 -429.037496) (xy 404.318216 -429.037496) (xy 404.306108 -429.03707) (xy 404.28308 -429.029574)
			(xy 404.263507 -429.015315) (xy 404.249312 -428.995695) (xy 404.241891 -428.972644) (xy 404.241508 -428.960534)
			(xy 404.241508 -428.349918) (xy 404.239839 -428.334925) (xy 404.238061 -428.304806) (xy 404.237952 -428.28972)
			(xy 401.334732 -428.28972) (xy 401.334732 -428.960534) (xy 401.334321 -428.972628) (xy 401.326852 -428.995635)
			(xy 401.312652 -429.015216) (xy 401.293105 -429.029465) (xy 401.270117 -429.036991) (xy 401.258024 -429.037496)
			(xy 400.318224 -429.037496) (xy 400.306116 -429.037063) (xy 400.283089 -429.02957) (xy 400.263515 -429.015313)
			(xy 400.24932 -428.995694) (xy 400.241899 -428.972643) (xy 400.241516 -428.960534) (xy 400.241516 -428.349918)
			(xy 400.239847 -428.334925) (xy 400.238069 -428.304806) (xy 400.23796 -428.28972) (xy 396.334996 -428.28972)
			(xy 396.334996 -428.960534) (xy 396.334518 -428.972647) (xy 396.327025 -428.995686) (xy 396.312784 -429.015284)
			(xy 396.293186 -429.029525) (xy 396.270147 -429.037018) (xy 396.258034 -429.037496) (xy 395.318234 -429.037496)
			(xy 395.306125 -429.03696) (xy 395.283088 -429.029486) (xy 395.263489 -429.01526) (xy 395.249245 -428.995673)
			(xy 395.241751 -428.972643) (xy 395.241272 -428.960534) (xy 395.241272 -428.347886) (xy 395.239729 -428.333394)
			(xy 395.238076 -428.304294) (xy 395.23797 -428.28972) (xy 392.335004 -428.28972) (xy 392.335004 -428.960534)
			(xy 392.334518 -428.972646) (xy 392.327027 -428.995683) (xy 392.312787 -429.015281) (xy 392.293191 -429.029523)
			(xy 392.270154 -429.037017) (xy 392.258042 -429.037496) (xy 391.318242 -429.037496) (xy 391.306125 -429.037005)
			(xy 391.283073 -429.029528) (xy 391.26346 -429.015294) (xy 391.249206 -428.995695) (xy 391.241707 -428.972651)
			(xy 391.24128 -428.960534) (xy 391.24128 -428.347886) (xy 391.239737 -428.333394) (xy 391.238084 -428.304294)
			(xy 391.237978 -428.28972) (xy 388.335012 -428.28972) (xy 388.335012 -428.960534) (xy 388.334518 -428.972645)
			(xy 388.327028 -428.995681) (xy 388.31279 -429.015278) (xy 388.293196 -429.02952) (xy 388.270161 -429.037016)
			(xy 388.25805 -429.037496) (xy 387.31825 -429.037496) (xy 387.306136 -429.037031) (xy 387.283097 -429.029535)
			(xy 387.263499 -429.015289) (xy 387.249258 -428.995689) (xy 387.241766 -428.972648) (xy 387.241288 -428.960534)
			(xy 387.241288 -428.347886) (xy 387.239745 -428.333394) (xy 387.238092 -428.304294) (xy 387.237986 -428.28972)
			(xy 384.33502 -428.28972) (xy 384.33502 -428.960534) (xy 384.334669 -428.972663) (xy 384.327162 -428.99573)
			(xy 384.312894 -429.015348) (xy 384.293262 -429.029597) (xy 384.270187 -429.03708) (xy 384.258058 -429.037496)
			(xy 383.318258 -429.037496) (xy 383.306145 -429.037025) (xy 383.283106 -429.02953) (xy 383.263508 -429.015287)
			(xy 383.249266 -428.995687) (xy 383.241774 -428.972647) (xy 383.241296 -428.960534) (xy 383.241296 -428.347886)
			(xy 383.239753 -428.333394) (xy 383.2381 -428.304294) (xy 383.237994 -428.28972) (xy 361.693883 -428.28972)
			(xy 361.70649 -428.297264) (xy 361.847915 -428.391163) (xy 361.984785 -428.491588) (xy 362.116796 -428.598318)
			(xy 362.24366 -428.711119) (xy 362.365097 -428.829742) (xy 362.480841 -428.953927) (xy 362.590636 -429.0834)
			(xy 362.694243 -429.217877) (xy 362.791432 -429.357063) (xy 362.88199 -429.500651) (xy 362.965718 -429.648327)
			(xy 363.042433 -429.799764) (xy 363.111965 -429.954631) (xy 363.174162 -430.112586) (xy 363.228886 -430.273284)
			(xy 363.276018 -430.436369) (xy 363.315454 -430.601485) (xy 363.347108 -430.768268) (xy 363.364334 -430.889918)
			(xy 381.237998 -430.889918) (xy 381.238092 -430.875344) (xy 381.239744 -430.846243) (xy 381.2413 -430.831752)
			(xy 381.2413 -429.747934) (xy 381.239752 -429.733442) (xy 381.238102 -429.704342) (xy 381.237998 -429.689768)
			(xy 381.238096 -429.675194) (xy 381.239746 -429.646093) (xy 381.2413 -429.631602) (xy 381.2413 -429.018954)
			(xy 381.241772 -429.006841) (xy 381.249267 -428.983803) (xy 381.263511 -428.964205) (xy 381.28311 -428.949964)
			(xy 381.306149 -428.942471) (xy 381.318262 -428.941992) (xy 382.258062 -428.941992) (xy 382.27017 -428.942543)
			(xy 382.293204 -428.950015) (xy 382.312803 -428.964238) (xy 382.327047 -428.98382) (xy 382.334543 -429.006847)
			(xy 382.335024 -429.018954) (xy 382.335024 -431.560478) (xy 382.334621 -431.572603) (xy 382.32713 -431.595668)
			(xy 382.312875 -431.615287) (xy 382.293254 -431.629537) (xy 382.270187 -431.637023) (xy 382.258062 -431.63744)
			(xy 381.318262 -431.63744) (xy 381.306143 -431.63702) (xy 381.283095 -431.62952) (xy 381.263492 -431.615265)
			(xy 381.249253 -431.595651) (xy 381.24177 -431.572597) (xy 381.2413 -431.560478) (xy 381.2413 -430.948084)
			(xy 381.239756 -430.933592) (xy 381.238104 -430.904492) (xy 381.237998 -430.889918) (xy 363.364334 -430.889918)
			(xy 363.370909 -430.936351) (xy 363.386805 -431.105365) (xy 363.394762 -431.274938) (xy 363.39526 -431.359818)
			(xy 363.39483 -431.445421) (xy 363.38674 -431.616436) (xy 363.370574 -431.786877) (xy 363.355859 -431.889916)
			(xy 383.237994 -431.889916) (xy 383.238088 -431.875342) (xy 383.23974 -431.846241) (xy 383.241296 -431.83175)
			(xy 383.241296 -430.747932) (xy 383.239748 -430.73344) (xy 383.238098 -430.70434) (xy 383.237994 -430.689766)
			(xy 383.238092 -430.675192) (xy 383.239742 -430.646091) (xy 383.241296 -430.6316) (xy 383.241296 -430.018952)
			(xy 383.241676 -430.006841) (xy 383.249188 -429.983813) (xy 383.263459 -429.964241) (xy 383.283088 -429.950048)
			(xy 383.306145 -429.942628) (xy 383.318258 -429.942244) (xy 384.258058 -429.942244) (xy 384.270146 -429.942743)
			(xy 384.293146 -429.950189) (xy 384.312727 -429.964367) (xy 384.326979 -429.983894) (xy 384.334511 -430.006866)
			(xy 384.33502 -430.018952) (xy 384.33502 -430.889918) (xy 385.23799 -430.889918) (xy 385.238084 -430.875344)
			(xy 385.239736 -430.846243) (xy 385.241292 -430.831752) (xy 385.241292 -429.747934) (xy 385.239745 -429.733442)
			(xy 385.238094 -429.704342) (xy 385.23799 -429.689768) (xy 385.238088 -429.675194) (xy 385.239738 -429.646093)
			(xy 385.241292 -429.631602) (xy 385.241292 -429.018954) (xy 385.241772 -429.006842) (xy 385.249266 -428.983805)
			(xy 385.263508 -428.964208) (xy 385.283105 -428.949966) (xy 385.306142 -428.942472) (xy 385.318254 -428.941992)
			(xy 386.258054 -428.941992) (xy 386.270162 -428.94255) (xy 386.293196 -428.950019) (xy 386.312794 -428.96424)
			(xy 386.327039 -428.983822) (xy 386.334535 -429.006847) (xy 386.335016 -429.018954) (xy 386.335016 -431.560478)
			(xy 386.334621 -431.572604) (xy 386.327129 -431.59567) (xy 386.312872 -431.61529) (xy 386.293249 -431.62954)
			(xy 386.27018 -431.637024) (xy 386.258054 -431.63744) (xy 385.318254 -431.63744) (xy 385.306135 -431.637027)
			(xy 385.283086 -431.629525) (xy 385.263484 -431.615268) (xy 385.249244 -431.595653) (xy 385.241762 -431.572598)
			(xy 385.241292 -431.560478) (xy 385.241292 -430.948084) (xy 385.239749 -430.933592) (xy 385.238096 -430.904492)
			(xy 385.23799 -430.889918) (xy 384.33502 -430.889918) (xy 384.33502 -431.889916) (xy 387.237986 -431.889916)
			(xy 387.23808 -431.875342) (xy 387.239732 -431.846241) (xy 387.241288 -431.83175) (xy 387.241288 -430.747932)
			(xy 387.23974 -430.73344) (xy 387.23809 -430.70434) (xy 387.237986 -430.689766) (xy 387.238084 -430.675192)
			(xy 387.239734 -430.646091) (xy 387.241288 -430.6316) (xy 387.241288 -430.018952) (xy 387.241675 -430.006842)
			(xy 387.249187 -429.983815) (xy 387.263456 -429.964244) (xy 387.283083 -429.95005) (xy 387.306138 -429.942629)
			(xy 387.31825 -429.942244) (xy 388.25805 -429.942244) (xy 388.270137 -429.94275) (xy 388.293137 -429.950193)
			(xy 388.312718 -429.96437) (xy 388.32697 -429.983896) (xy 388.334503 -430.006866) (xy 388.335012 -430.018952)
			(xy 388.335012 -430.889918) (xy 389.237982 -430.889918) (xy 389.238076 -430.875344) (xy 389.239728 -430.846243)
			(xy 389.241284 -430.831752) (xy 389.241284 -429.747934) (xy 389.239737 -429.733442) (xy 389.238086 -429.704342)
			(xy 389.237982 -429.689768) (xy 389.23808 -429.675194) (xy 389.23973 -429.646093) (xy 389.241284 -429.631602)
			(xy 389.241284 -429.018954) (xy 389.241673 -429.006832) (xy 389.249179 -428.98378) (xy 389.26344 -428.964175)
			(xy 389.283062 -428.949937) (xy 389.306124 -428.942459) (xy 389.318246 -428.941992) (xy 390.258046 -428.941992)
			(xy 390.270158 -428.942472) (xy 390.293195 -428.949966) (xy 390.312792 -428.964208) (xy 390.327034 -428.983805)
			(xy 390.334528 -429.006842) (xy 390.335008 -429.018954) (xy 390.335008 -431.560478) (xy 390.33447 -431.572587)
			(xy 390.326995 -431.595622) (xy 390.312768 -431.61522) (xy 390.293183 -431.629464) (xy 390.270154 -431.636959)
			(xy 390.258046 -431.63744) (xy 389.318246 -431.63744) (xy 389.306123 -431.637001) (xy 389.283062 -431.629518)
			(xy 389.263445 -431.615273) (xy 389.249193 -431.595659) (xy 389.241703 -431.5726) (xy 389.241284 -431.560478)
			(xy 389.241284 -430.948084) (xy 389.239741 -430.933592) (xy 389.238088 -430.904492) (xy 389.237982 -430.889918)
			(xy 388.335012 -430.889918) (xy 388.335012 -431.889916) (xy 391.237978 -431.889916) (xy 391.238072 -431.875342)
			(xy 391.239724 -431.846241) (xy 391.24128 -431.83175) (xy 391.24128 -430.747932) (xy 391.239732 -430.73344)
			(xy 391.238082 -430.70434) (xy 391.237978 -430.689766) (xy 391.238076 -430.675192) (xy 391.239726 -430.646091)
			(xy 391.24128 -430.6316) (xy 391.24128 -430.018952) (xy 391.241675 -430.006843) (xy 391.249186 -429.983817)
			(xy 391.263453 -429.964247) (xy 391.283077 -429.950053) (xy 391.306131 -429.94263) (xy 391.318242 -429.942244)
			(xy 392.258042 -429.942244) (xy 392.270134 -429.942672) (xy 392.293137 -429.95014) (xy 392.312716 -429.964337)
			(xy 392.326965 -429.983879) (xy 392.334496 -430.006861) (xy 392.335004 -430.018952) (xy 392.335004 -430.889918)
			(xy 393.237974 -430.889918) (xy 393.238068 -430.875344) (xy 393.23972 -430.846243) (xy 393.241276 -430.831752)
			(xy 393.241276 -429.747934) (xy 393.239729 -429.733442) (xy 393.238078 -429.704342) (xy 393.237974 -429.689768)
			(xy 393.238072 -429.675194) (xy 393.239722 -429.646093) (xy 393.241276 -429.631602) (xy 393.241276 -429.018954)
			(xy 393.241673 -429.006833) (xy 393.249178 -428.983782) (xy 393.263438 -428.964178) (xy 393.283057 -428.949939)
			(xy 393.306117 -428.94246) (xy 393.318238 -428.941992) (xy 394.258038 -428.941992) (xy 394.27015 -428.942479)
			(xy 394.293187 -428.949971) (xy 394.312784 -428.964211) (xy 394.327026 -428.983806) (xy 394.33452 -429.006842)
			(xy 394.335 -429.018954) (xy 394.335 -431.560478) (xy 394.33447 -431.572588) (xy 394.326994 -431.595624)
			(xy 394.312765 -431.615223) (xy 394.293177 -431.629466) (xy 394.270147 -431.636961) (xy 394.258038 -431.63744)
			(xy 393.318238 -431.63744) (xy 393.306115 -431.637007) (xy 393.283054 -431.629523) (xy 393.263436 -431.615275)
			(xy 393.249184 -431.595661) (xy 393.241695 -431.572601) (xy 393.241276 -431.560478) (xy 393.241276 -430.948084)
			(xy 393.239733 -430.933592) (xy 393.23808 -430.904492) (xy 393.237974 -430.889918) (xy 392.335004 -430.889918)
			(xy 392.335004 -431.889916) (xy 395.23797 -431.889916) (xy 395.238064 -431.875342) (xy 395.239716 -431.846241)
			(xy 395.241272 -431.83175) (xy 395.241272 -430.747932) (xy 395.239724 -430.73344) (xy 395.238074 -430.70434)
			(xy 395.23797 -430.689766) (xy 395.238068 -430.675192) (xy 395.239718 -430.646091) (xy 395.241272 -430.6316)
			(xy 395.241272 -430.018952) (xy 395.241675 -430.006843) (xy 395.249184 -429.983819) (xy 395.26345 -429.96425)
			(xy 395.283072 -429.950056) (xy 395.306124 -429.942631) (xy 395.318234 -429.942244) (xy 396.258034 -429.942244)
			(xy 396.270126 -429.942678) (xy 396.293128 -429.950145) (xy 396.312708 -429.96434) (xy 396.326957 -429.98388)
			(xy 396.334488 -430.006862) (xy 396.334996 -430.018952) (xy 396.334996 -430.889918) (xy 398.237964 -430.889918)
			(xy 398.238073 -430.874832) (xy 398.239855 -430.844714) (xy 398.24152 -430.82972) (xy 398.24152 -429.749966)
			(xy 398.239855 -429.734972) (xy 398.238074 -429.704854) (xy 398.237964 -429.689768) (xy 398.238078 -429.674682)
			(xy 398.239856 -429.644564) (xy 398.24152 -429.62957) (xy 398.24152 -429.018954) (xy 398.241968 -429.006864)
			(xy 398.249435 -428.983865) (xy 398.263627 -428.964288) (xy 398.283163 -428.950038) (xy 398.306139 -428.942504)
			(xy 398.318228 -428.941992) (xy 399.258028 -428.941992) (xy 399.270138 -428.942392) (xy 399.293164 -428.949899)
			(xy 399.312736 -428.964165) (xy 399.32693 -428.983789) (xy 399.334352 -429.006843) (xy 399.334736 -429.018954)
			(xy 399.334736 -431.560478) (xy 399.334273 -431.572569) (xy 399.32682 -431.595573) (xy 399.312633 -431.615155)
			(xy 399.293097 -431.629405) (xy 399.270117 -431.636934) (xy 399.258028 -431.63744) (xy 398.318228 -431.63744)
			(xy 398.306125 -431.63696) (xy 398.283105 -431.629473) (xy 398.263535 -431.615227) (xy 398.249338 -431.595621)
			(xy 398.241909 -431.572582) (xy 398.24152 -431.560478) (xy 398.24152 -430.950116) (xy 398.239851 -430.935123)
			(xy 398.238073 -430.905004) (xy 398.237964 -430.889918) (xy 396.334996 -430.889918) (xy 396.334996 -431.889916)
			(xy 400.23796 -431.889916) (xy 400.238069 -431.87483) (xy 400.239851 -431.844712) (xy 400.241516 -431.829718)
			(xy 400.241516 -430.749964) (xy 400.239851 -430.73497) (xy 400.23807 -430.704852) (xy 400.23796 -430.689766)
			(xy 400.238074 -430.67468) (xy 400.239852 -430.644562) (xy 400.241516 -430.629568) (xy 400.241516 -430.018952)
			(xy 400.241924 -430.006873) (xy 400.249402 -429.9839) (xy 400.263613 -429.964361) (xy 400.283164 -429.950169)
			(xy 400.306144 -429.942712) (xy 400.318224 -429.942244) (xy 401.258024 -429.942244) (xy 401.270095 -429.942743)
			(xy 401.293055 -429.950206) (xy 401.312587 -429.964396) (xy 401.326783 -429.983924) (xy 401.334253 -430.006881)
			(xy 401.334732 -430.018952) (xy 401.334732 -430.889918) (xy 402.237956 -430.889918) (xy 402.238065 -430.874832)
			(xy 402.239847 -430.844714) (xy 402.241512 -430.82972) (xy 402.241512 -429.749966) (xy 402.239847 -429.734972)
			(xy 402.238066 -429.704854) (xy 402.237956 -429.689768) (xy 402.23807 -429.674682) (xy 402.239848 -429.644564)
			(xy 402.241512 -429.62957) (xy 402.241512 -429.018954) (xy 402.241968 -429.006865) (xy 402.249434 -428.983867)
			(xy 402.263624 -428.964291) (xy 402.283158 -428.950041) (xy 402.306132 -428.942505) (xy 402.31822 -428.941992)
			(xy 403.25802 -428.941992) (xy 403.270129 -428.942399) (xy 403.293156 -428.949903) (xy 403.312728 -428.964167)
			(xy 403.326922 -428.98379) (xy 403.334344 -429.006843) (xy 403.334728 -429.018954) (xy 403.334728 -431.560478)
			(xy 403.334273 -431.57257) (xy 403.326819 -431.595575) (xy 403.31263 -431.615158) (xy 403.293092 -431.629408)
			(xy 403.27011 -431.636935) (xy 403.25802 -431.63744) (xy 402.31822 -431.63744) (xy 402.306116 -431.636967)
			(xy 402.283096 -431.629478) (xy 402.263527 -431.61523) (xy 402.24933 -431.595622) (xy 402.241901 -431.572583)
			(xy 402.241512 -431.560478) (xy 402.241512 -430.950116) (xy 402.239843 -430.935123) (xy 402.238065 -430.905004)
			(xy 402.237956 -430.889918) (xy 401.334732 -430.889918) (xy 401.334732 -431.889916) (xy 404.237952 -431.889916)
			(xy 404.238061 -431.87483) (xy 404.239843 -431.844712) (xy 404.241508 -431.829718) (xy 404.241508 -430.749964)
			(xy 404.239843 -430.73497) (xy 404.238062 -430.704852) (xy 404.237952 -430.689766) (xy 404.238066 -430.67468)
			(xy 404.239844 -430.644562) (xy 404.241508 -430.629568) (xy 404.241508 -430.018952) (xy 404.241923 -430.006873)
			(xy 404.249401 -429.983902) (xy 404.26361 -429.964364) (xy 404.283159 -429.950172) (xy 404.306137 -429.942713)
			(xy 404.318216 -429.942244) (xy 405.258016 -429.942244) (xy 405.270087 -429.94275) (xy 405.293046 -429.950211)
			(xy 405.312579 -429.964399) (xy 405.326774 -429.983925) (xy 405.334245 -430.006882) (xy 405.334724 -430.018952)
			(xy 405.334724 -430.889918) (xy 406.237948 -430.889918) (xy 406.238057 -430.874832) (xy 406.239839 -430.844714)
			(xy 406.241504 -430.82972) (xy 406.241504 -429.749966) (xy 406.239839 -429.734972) (xy 406.238058 -429.704854)
			(xy 406.237948 -429.689768) (xy 406.238062 -429.674682) (xy 406.23984 -429.644564) (xy 406.241504 -429.62957)
			(xy 406.241504 -429.018954) (xy 406.241967 -429.006866) (xy 406.249432 -428.98387) (xy 406.263621 -428.964293)
			(xy 406.283153 -428.950043) (xy 406.306125 -428.942506) (xy 406.318212 -428.941992) (xy 407.258012 -428.941992)
			(xy 407.270121 -428.942406) (xy 407.293147 -428.949908) (xy 407.312719 -428.96417) (xy 407.326914 -428.983792)
			(xy 407.334336 -429.006844) (xy 407.33472 -429.018954) (xy 407.33472 -431.560478) (xy 407.334273 -431.57257)
			(xy 407.326818 -431.595577) (xy 407.312627 -431.615161) (xy 407.293087 -431.629411) (xy 407.270103 -431.636936)
			(xy 407.258012 -431.63744) (xy 406.318212 -431.63744) (xy 406.306108 -431.636974) (xy 406.283088 -431.629483)
			(xy 406.263518 -431.615232) (xy 406.249322 -431.595624) (xy 406.241893 -431.572583) (xy 406.241504 -431.560478)
			(xy 406.241504 -430.950116) (xy 406.239835 -430.935123) (xy 406.238057 -430.905004) (xy 406.237948 -430.889918)
			(xy 405.334724 -430.889918) (xy 405.334724 -431.889916) (xy 408.237944 -431.889916) (xy 408.238053 -431.87483)
			(xy 408.239835 -431.844712) (xy 408.2415 -431.829718) (xy 408.2415 -430.749964) (xy 408.239835 -430.73497)
			(xy 408.238054 -430.704852) (xy 408.237944 -430.689766) (xy 408.238058 -430.67468) (xy 408.239836 -430.644562)
			(xy 408.2415 -430.629568) (xy 408.2415 -430.018952) (xy 408.241923 -430.006874) (xy 408.2494 -429.983904)
			(xy 408.263607 -429.964367) (xy 408.283154 -429.950174) (xy 408.30613 -429.942714) (xy 408.318208 -429.942244)
			(xy 409.258008 -429.942244) (xy 409.270078 -429.942757) (xy 409.293037 -429.950216) (xy 409.31257 -429.964401)
			(xy 409.326766 -429.983927) (xy 409.334237 -430.006882) (xy 409.334716 -430.018952) (xy 409.334716 -430.889918)
			(xy 410.23794 -430.889918) (xy 410.238051 -430.874832) (xy 410.239833 -430.844714) (xy 410.241496 -430.82972)
			(xy 410.241496 -429.749966) (xy 410.239831 -429.734972) (xy 410.23805 -429.704854) (xy 410.23794 -429.689768)
			(xy 410.238054 -429.674682) (xy 410.239832 -429.644564) (xy 410.241496 -429.62957) (xy 410.241496 -429.018954)
			(xy 410.241967 -429.006866) (xy 410.249431 -428.983872) (xy 410.263618 -428.964296) (xy 410.283148 -428.950046)
			(xy 410.306118 -428.942507) (xy 410.318204 -428.941992) (xy 411.258004 -428.941992) (xy 411.270112 -428.942413)
			(xy 411.293138 -428.949912) (xy 411.312711 -428.964173) (xy 411.326906 -428.983793) (xy 411.334328 -429.006844)
			(xy 411.334712 -429.018954) (xy 411.334712 -431.560478) (xy 411.334273 -431.572571) (xy 411.326816 -431.595579)
			(xy 411.312624 -431.615164) (xy 411.293082 -431.629413) (xy 411.270096 -431.636937) (xy 411.258004 -431.63744)
			(xy 410.318204 -431.63744) (xy 410.306099 -431.636981) (xy 410.283079 -431.629488) (xy 410.263509 -431.615236)
			(xy 410.249313 -431.595625) (xy 410.241885 -431.572584) (xy 410.241496 -431.560478) (xy 410.241496 -430.950116)
			(xy 410.239827 -430.935123) (xy 410.238049 -430.905004) (xy 410.23794 -430.889918) (xy 409.334716 -430.889918)
			(xy 409.334716 -431.889916) (xy 412.237936 -431.889916) (xy 412.238047 -431.87483) (xy 412.239829 -431.844712)
			(xy 412.241492 -431.829718) (xy 412.241492 -430.749964) (xy 412.239827 -430.73497) (xy 412.238046 -430.704852)
			(xy 412.237936 -430.689766) (xy 412.238052 -430.674681) (xy 412.23983 -430.644562) (xy 412.241492 -430.629568)
			(xy 412.241492 -430.018952) (xy 412.241923 -430.006875) (xy 412.249399 -429.983906) (xy 412.263604 -429.96437)
			(xy 412.283149 -429.950177) (xy 412.306123 -429.942716) (xy 412.3182 -429.942244) (xy 413.258 -429.942244)
			(xy 413.27007 -429.942764) (xy 413.293029 -429.95022) (xy 413.312562 -429.964404) (xy 413.326758 -429.983928)
			(xy 413.334229 -430.006883) (xy 413.334708 -430.018952) (xy 413.334708 -432.560476) (xy 413.334267 -432.572557)
			(xy 413.326806 -432.595539) (xy 413.312607 -432.61509) (xy 413.293061 -432.629295) (xy 413.270081 -432.636763)
			(xy 413.258 -432.637184) (xy 412.3182 -432.637184) (xy 412.306115 -432.636787) (xy 412.283128 -432.629317)
			(xy 412.263576 -432.615107) (xy 412.249372 -432.59555) (xy 412.241909 -432.572561) (xy 412.241492 -432.560476)
			(xy 412.241492 -431.950114) (xy 412.239822 -431.935121) (xy 412.238045 -431.905002) (xy 412.237936 -431.889916)
			(xy 409.334716 -431.889916) (xy 409.334716 -432.560476) (xy 409.334267 -432.572557) (xy 409.326807 -432.595537)
			(xy 409.31261 -432.615087) (xy 409.293066 -432.629292) (xy 409.270088 -432.636762) (xy 409.258008 -432.637184)
			(xy 408.318208 -432.637184) (xy 408.306123 -432.63678) (xy 408.283137 -432.629312) (xy 408.263584 -432.615105)
			(xy 408.249381 -432.595549) (xy 408.241917 -432.572561) (xy 408.2415 -432.560476) (xy 408.2415 -431.950114)
			(xy 408.23983 -431.935121) (xy 408.238053 -431.905002) (xy 408.237944 -431.889916) (xy 405.334724 -431.889916)
			(xy 405.334724 -432.560476) (xy 405.334267 -432.572556) (xy 405.326808 -432.595535) (xy 405.312613 -432.615084)
			(xy 405.293071 -432.62929) (xy 405.270096 -432.636761) (xy 405.258016 -432.637184) (xy 404.318216 -432.637184)
			(xy 404.306132 -432.636773) (xy 404.283146 -432.629307) (xy 404.263593 -432.615101) (xy 404.249389 -432.595547)
			(xy 404.241926 -432.57256) (xy 404.241508 -432.560476) (xy 404.241508 -431.950114) (xy 404.239838 -431.935121)
			(xy 404.238061 -431.905002) (xy 404.237952 -431.889916) (xy 401.334732 -431.889916) (xy 401.334732 -432.560476)
			(xy 401.334216 -432.572547) (xy 401.326763 -432.595509) (xy 401.312579 -432.615045) (xy 401.293052 -432.629241)
			(xy 401.270095 -432.636708) (xy 401.258024 -432.637184) (xy 400.318224 -432.637184) (xy 400.30614 -432.636766)
			(xy 400.283154 -432.629303) (xy 400.263601 -432.615099) (xy 400.249397 -432.595546) (xy 400.241934 -432.57256)
			(xy 400.241516 -432.560476) (xy 400.241516 -431.950114) (xy 400.239846 -431.935121) (xy 400.238069 -431.905002)
			(xy 400.23796 -431.889916) (xy 396.334996 -431.889916) (xy 396.334996 -432.560476) (xy 396.334563 -432.572584)
			(xy 396.32707 -432.595611) (xy 396.312813 -432.615185) (xy 396.293194 -432.62938) (xy 396.270143 -432.636801)
			(xy 396.258034 -432.637184) (xy 395.318234 -432.637184) (xy 395.306149 -432.636664) (xy 395.283153 -432.62922)
			(xy 395.263575 -432.615046) (xy 395.249322 -432.595525) (xy 395.241785 -432.572559) (xy 395.241272 -432.560476)
			(xy 395.241272 -431.948082) (xy 395.239729 -431.93359) (xy 395.238076 -431.90449) (xy 395.23797 -431.889916)
			(xy 392.335004 -431.889916) (xy 392.335004 -432.560476) (xy 392.334563 -432.572583) (xy 392.327071 -432.595609)
			(xy 392.312815 -432.615182) (xy 392.293199 -432.629378) (xy 392.27015 -432.6368) (xy 392.258042 -432.637184)
			(xy 391.318242 -432.637184) (xy 391.306157 -432.636657) (xy 391.283162 -432.629215) (xy 391.263583 -432.615043)
			(xy 391.24933 -432.595523) (xy 391.241793 -432.572559) (xy 391.24128 -432.560476) (xy 391.24128 -431.948082)
			(xy 391.239737 -431.93359) (xy 391.238084 -431.90449) (xy 391.237978 -431.889916) (xy 388.335012 -431.889916)
			(xy 388.335012 -432.560476) (xy 388.334563 -432.572582) (xy 388.327072 -432.595607) (xy 388.312818 -432.615179)
			(xy 388.293204 -432.629375) (xy 388.270158 -432.636799) (xy 388.25805 -432.637184) (xy 387.31825 -432.637184)
			(xy 387.306165 -432.636651) (xy 387.28317 -432.62921) (xy 387.263592 -432.61504) (xy 387.249339 -432.595522)
			(xy 387.241801 -432.572559) (xy 387.241288 -432.560476) (xy 387.241288 -431.948082) (xy 387.239745 -431.93359)
			(xy 387.238092 -431.90449) (xy 387.237986 -431.889916) (xy 384.33502 -431.889916) (xy 384.33502 -432.560476)
			(xy 384.334563 -432.572582) (xy 384.327073 -432.595605) (xy 384.312821 -432.615176) (xy 384.293209 -432.629373)
			(xy 384.270165 -432.636797) (xy 384.258058 -432.637184) (xy 383.318258 -432.637184) (xy 383.306169 -432.636729)
			(xy 383.283171 -432.629264) (xy 383.263593 -432.615073) (xy 383.249343 -432.595539) (xy 383.241808 -432.572564)
			(xy 383.241296 -432.560476) (xy 383.241296 -431.948082) (xy 383.239753 -431.93359) (xy 383.2381 -431.90449)
			(xy 383.237994 -431.889916) (xy 363.355859 -431.889916) (xy 363.346369 -431.956363) (xy 363.314178 -432.124516)
			(xy 363.274074 -432.290959) (xy 363.226145 -432.455319) (xy 363.170501 -432.61723) (xy 363.107264 -432.776329)
			(xy 363.036576 -432.932261) (xy 362.958595 -433.084677) (xy 362.873496 -433.233236) (xy 362.781469 -433.377605)
			(xy 362.68272 -433.517463) (xy 362.577469 -433.652495) (xy 362.465953 -433.782401) (xy 362.348419 -433.90689)
			(xy 362.225132 -434.025683) (xy 362.096367 -434.138515) (xy 361.962411 -434.245133) (xy 361.823565 -434.345299)
			(xy 361.680139 -434.438789) (xy 361.593049 -434.48986) (xy 381.237998 -434.48986) (xy 381.238096 -434.475286)
			(xy 381.239745 -434.446185) (xy 381.2413 -434.431694) (xy 381.2413 -433.34813) (xy 381.239752 -433.333638)
			(xy 381.238102 -433.304538) (xy 381.237998 -433.289964) (xy 381.238096 -433.27539) (xy 381.239745 -433.246289)
			(xy 381.2413 -433.231798) (xy 381.2413 -432.618896) (xy 381.241713 -432.606787) (xy 381.249213 -432.583759)
			(xy 381.263476 -432.564186) (xy 381.283098 -432.549992) (xy 381.306152 -432.542571) (xy 381.318262 -432.542188)
			(xy 382.258062 -432.542188) (xy 382.270154 -432.542641) (xy 382.293162 -432.550093) (xy 382.312747 -432.564281)
			(xy 382.326997 -432.583821) (xy 382.334521 -432.606805) (xy 382.335024 -432.618896) (xy 382.335024 -435.16042)
			(xy 382.334601 -435.172528) (xy 382.327099 -435.195551) (xy 382.312838 -435.215122) (xy 382.29322 -435.229317)
			(xy 382.270171 -435.236741) (xy 382.258062 -435.237128) (xy 381.318262 -435.237128) (xy 381.306167 -435.236724)
			(xy 381.28316 -435.229253) (xy 381.263578 -435.215052) (xy 381.24933 -435.195503) (xy 381.241804 -435.172514)
			(xy 381.2413 -435.16042) (xy 381.2413 -434.548026) (xy 381.239752 -434.533534) (xy 381.238102 -434.504434)
			(xy 381.237998 -434.48986) (xy 361.593049 -434.48986) (xy 361.532453 -434.525394) (xy 361.380838 -434.60492)
			(xy 361.225633 -434.67719) (xy 361.146598 -434.710078) (xy 361.132966 -434.716266) (xy 361.109724 -434.735103)
			(xy 361.092944 -434.759873) (xy 361.084069 -434.788444) (xy 361.083862 -434.818361) (xy 361.092341 -434.847052)
			(xy 361.108777 -434.872051) (xy 361.119928 -434.882036) (xy 361.169374 -434.924045) (xy 361.263563 -435.013299)
			(xy 361.352051 -435.108208) (xy 361.434498 -435.208409) (xy 361.510589 -435.313518) (xy 361.580032 -435.423133)
			(xy 361.616728 -435.489858) (xy 383.237994 -435.489858) (xy 383.238091 -435.475284) (xy 383.239741 -435.446183)
			(xy 383.241296 -435.431692) (xy 383.241296 -434.348128) (xy 383.239748 -434.333636) (xy 383.238098 -434.304536)
			(xy 383.237994 -434.289962) (xy 383.238092 -434.275388) (xy 383.239741 -434.246287) (xy 383.241296 -434.231796)
			(xy 383.241296 -433.618894) (xy 383.241806 -433.606783) (xy 383.24929 -433.583747) (xy 383.263524 -433.564149)
			(xy 383.283115 -433.549906) (xy 383.306148 -433.542412) (xy 383.318258 -433.541932) (xy 384.258058 -433.541932)
			(xy 384.270178 -433.542396) (xy 384.293234 -433.549876) (xy 384.31285 -433.564116) (xy 384.327103 -433.583722)
			(xy 384.334597 -433.606774) (xy 384.33502 -433.618894) (xy 384.33502 -434.48986) (xy 385.23799 -434.48986)
			(xy 385.238088 -434.475286) (xy 385.239737 -434.446185) (xy 385.241292 -434.431694) (xy 385.241292 -433.34813)
			(xy 385.239744 -433.333638) (xy 385.238094 -433.304538) (xy 385.23799 -433.289964) (xy 385.238088 -433.27539)
			(xy 385.239737 -433.246289) (xy 385.241292 -433.231798) (xy 385.241292 -432.618896) (xy 385.241713 -432.606788)
			(xy 385.249212 -432.583762) (xy 385.263473 -432.564189) (xy 385.283093 -432.549994) (xy 385.306144 -432.542572)
			(xy 385.318254 -432.542188) (xy 386.258054 -432.542188) (xy 386.270146 -432.542647) (xy 386.293153 -432.550097)
			(xy 386.312738 -432.564284) (xy 386.326988 -432.583823) (xy 386.334513 -432.606806) (xy 386.335016 -432.618896)
			(xy 386.335016 -435.16042) (xy 386.334601 -435.172528) (xy 386.327098 -435.195554) (xy 386.312836 -435.215125)
			(xy 386.293215 -435.229319) (xy 386.270164 -435.236743) (xy 386.258054 -435.237128) (xy 385.318254 -435.237128)
			(xy 385.306159 -435.236731) (xy 385.283151 -435.229258) (xy 385.263569 -435.215054) (xy 385.249322 -435.195505)
			(xy 385.241796 -435.172514) (xy 385.241292 -435.16042) (xy 385.241292 -434.548026) (xy 385.239744 -434.533534)
			(xy 385.238094 -434.504434) (xy 385.23799 -434.48986) (xy 384.33502 -434.48986) (xy 384.33502 -435.489858)
			(xy 387.237986 -435.489858) (xy 387.238083 -435.475284) (xy 387.239733 -435.446183) (xy 387.241288 -435.431692)
			(xy 387.241288 -434.348128) (xy 387.23974 -434.333636) (xy 387.23809 -434.304536) (xy 387.237986 -434.289962)
			(xy 387.238084 -434.275388) (xy 387.239733 -434.246287) (xy 387.241288 -434.231796) (xy 387.241288 -433.618894)
			(xy 387.241806 -433.606784) (xy 387.249289 -433.583749) (xy 387.263521 -433.564152) (xy 387.28311 -433.549909)
			(xy 387.30614 -433.542413) (xy 387.31825 -433.541932) (xy 388.25805 -433.541932) (xy 388.270167 -433.542369)
			(xy 388.29321 -433.549869) (xy 388.312811 -433.564121) (xy 388.327051 -433.583729) (xy 388.334538 -433.606777)
			(xy 388.335012 -433.618894) (xy 388.335012 -434.48986) (xy 389.237982 -434.48986) (xy 389.23808 -434.475286)
			(xy 389.239729 -434.446185) (xy 389.241284 -434.431694) (xy 389.241284 -433.34813) (xy 389.239736 -433.333638)
			(xy 389.238086 -433.304538) (xy 389.237982 -433.289964) (xy 389.23808 -433.27539) (xy 389.23973 -433.246289)
			(xy 389.241284 -433.231798) (xy 389.241284 -432.618896) (xy 389.241713 -432.606789) (xy 389.249211 -432.583764)
			(xy 389.26347 -432.564192) (xy 389.283088 -432.549997) (xy 389.306137 -432.542573) (xy 389.318246 -432.542188)
			(xy 390.258046 -432.542188) (xy 390.270143 -432.542569) (xy 390.293153 -432.550044) (xy 390.312736 -432.564251)
			(xy 390.326984 -432.583805) (xy 390.334506 -432.6068) (xy 390.335008 -432.618896) (xy 390.335008 -435.16042)
			(xy 390.334601 -435.172529) (xy 390.327097 -435.195556) (xy 390.312833 -435.215128) (xy 390.29321 -435.229322)
			(xy 390.270157 -435.236744) (xy 390.258046 -435.237128) (xy 389.318246 -435.237128) (xy 389.306156 -435.236653)
			(xy 389.283151 -435.229205) (xy 389.263568 -435.215022) (xy 389.249317 -435.195487) (xy 389.241789 -435.172509)
			(xy 389.241284 -435.16042) (xy 389.241284 -434.548026) (xy 389.239736 -434.533534) (xy 389.238086 -434.504434)
			(xy 389.237982 -434.48986) (xy 388.335012 -434.48986) (xy 388.335012 -435.489858) (xy 391.237978 -435.489858)
			(xy 391.238076 -435.475284) (xy 391.239725 -435.446183) (xy 391.24128 -435.431692) (xy 391.24128 -434.348128)
			(xy 391.239732 -434.333636) (xy 391.238082 -434.304536) (xy 391.237978 -434.289962) (xy 391.238076 -434.275388)
			(xy 391.239725 -434.246287) (xy 391.24128 -434.231796) (xy 391.24128 -433.618894) (xy 391.241656 -433.606767)
			(xy 391.249155 -433.583701) (xy 391.263416 -433.564082) (xy 391.283044 -433.549833) (xy 391.306115 -433.542348)
			(xy 391.318242 -433.541932) (xy 392.258042 -433.541932) (xy 392.270158 -433.542376) (xy 392.293202 -433.549874)
			(xy 392.312802 -433.564123) (xy 392.327043 -433.583731) (xy 392.33453 -433.606778) (xy 392.335004 -433.618894)
			(xy 392.335004 -434.48986) (xy 393.237974 -434.48986) (xy 393.238072 -434.475286) (xy 393.239721 -434.446185)
			(xy 393.241276 -434.431694) (xy 393.241276 -433.34813) (xy 393.239728 -433.333638) (xy 393.238078 -433.304538)
			(xy 393.237974 -433.289964) (xy 393.238072 -433.27539) (xy 393.239722 -433.246289) (xy 393.241276 -433.231798)
			(xy 393.241276 -432.618896) (xy 393.241712 -432.606789) (xy 393.24921 -432.583766) (xy 393.263467 -432.564195)
			(xy 393.283083 -432.55) (xy 393.30613 -432.542575) (xy 393.318238 -432.542188) (xy 394.258038 -432.542188)
			(xy 394.270134 -432.542576) (xy 394.293144 -432.550049) (xy 394.312728 -432.564254) (xy 394.326975 -432.583807)
			(xy 394.334498 -432.606801) (xy 394.335 -432.618896) (xy 394.335 -435.16042) (xy 394.334601 -435.17253)
			(xy 394.327096 -435.195558) (xy 394.31283 -435.215131) (xy 394.293205 -435.229325) (xy 394.270149 -435.236745)
			(xy 394.258038 -435.237128) (xy 393.318238 -435.237128) (xy 393.306147 -435.23666) (xy 393.283142 -435.22921)
			(xy 393.263559 -435.215024) (xy 393.249308 -435.195489) (xy 393.241781 -435.172509) (xy 393.241276 -435.16042)
			(xy 393.241276 -434.548026) (xy 393.239728 -434.533534) (xy 393.238078 -434.504434) (xy 393.237974 -434.48986)
			(xy 392.335004 -434.48986) (xy 392.335004 -435.489858) (xy 395.23797 -435.489858) (xy 395.238068 -435.475284)
			(xy 395.239717 -435.446183) (xy 395.241272 -435.431692) (xy 395.241272 -434.348128) (xy 395.239724 -434.333636)
			(xy 395.238074 -434.304536) (xy 395.23797 -434.289962) (xy 395.238068 -434.275388) (xy 395.239717 -434.246287)
			(xy 395.241272 -434.231796) (xy 395.241272 -433.618894) (xy 395.241656 -433.606768) (xy 395.249154 -433.583703)
			(xy 395.263413 -433.564085) (xy 395.283039 -433.549835) (xy 395.306107 -433.542349) (xy 395.318234 -433.541932)
			(xy 396.258034 -433.541932) (xy 396.27015 -433.542383) (xy 396.293193 -433.549878) (xy 396.312794 -433.564126)
			(xy 396.327034 -433.583732) (xy 396.334522 -433.606778) (xy 396.334996 -433.618894) (xy 396.334996 -434.48986)
			(xy 398.237964 -434.48986) (xy 398.238077 -434.474774) (xy 398.239856 -434.444656) (xy 398.24152 -434.429662)
			(xy 398.24152 -433.350162) (xy 398.239855 -433.335168) (xy 398.238074 -433.30505) (xy 398.237964 -433.289964)
			(xy 398.238077 -433.274878) (xy 398.239856 -433.24476) (xy 398.24152 -433.229766) (xy 398.24152 -432.618896)
			(xy 398.241909 -432.60681) (xy 398.249382 -432.583823) (xy 398.263593 -432.56427) (xy 398.283151 -432.550067)
			(xy 398.306142 -432.542604) (xy 398.318228 -432.542188) (xy 399.258028 -432.542188) (xy 399.270104 -432.54264)
			(xy 399.293071 -432.55011) (xy 399.312607 -432.56431) (xy 399.326801 -432.58385) (xy 399.334264 -432.60682)
			(xy 399.334736 -432.618896) (xy 399.334736 -435.16042) (xy 399.334253 -435.172493) (xy 399.326788 -435.195456)
			(xy 399.312596 -435.21499) (xy 399.293063 -435.229185) (xy 399.270101 -435.236652) (xy 399.258028 -435.237128)
			(xy 398.318228 -435.237128) (xy 398.306149 -435.236664) (xy 398.28317 -435.229206) (xy 398.263621 -435.215013)
			(xy 398.249416 -435.195473) (xy 398.241944 -435.172499) (xy 398.24152 -435.16042) (xy 398.24152 -434.550058)
			(xy 398.239854 -434.535064) (xy 398.238074 -434.504946) (xy 398.237964 -434.48986) (xy 396.334996 -434.48986)
			(xy 396.334996 -435.489858) (xy 400.23796 -435.489858) (xy 400.238073 -435.474772) (xy 400.239852 -435.444654)
			(xy 400.241516 -435.42966) (xy 400.241516 -434.35016) (xy 400.239851 -434.335166) (xy 400.23807 -434.305048)
			(xy 400.23796 -434.289962) (xy 400.238073 -434.274876) (xy 400.239852 -434.244758) (xy 400.241516 -434.229764)
			(xy 400.241516 -433.618894) (xy 400.242002 -433.606807) (xy 400.249457 -433.58381) (xy 400.26364 -433.564232)
			(xy 400.283168 -433.549981) (xy 400.306138 -433.542445) (xy 400.318224 -433.541932) (xy 401.258024 -433.541932)
			(xy 401.270137 -433.542296) (xy 401.293171 -433.549806) (xy 401.312746 -433.56408) (xy 401.326939 -433.583715)
			(xy 401.334353 -433.606779) (xy 401.334732 -433.618894) (xy 401.334732 -434.48986) (xy 402.237956 -434.48986)
			(xy 402.238069 -434.474774) (xy 402.239848 -434.444656) (xy 402.241512 -434.429662) (xy 402.241512 -433.350162)
			(xy 402.239847 -433.335168) (xy 402.238066 -433.30505) (xy 402.237956 -433.289964) (xy 402.238069 -433.274878)
			(xy 402.239848 -433.24476) (xy 402.241512 -433.229766) (xy 402.241512 -432.618896) (xy 402.241909 -432.606811)
			(xy 402.24938 -432.583825) (xy 402.26359 -432.564273) (xy 402.283146 -432.550069) (xy 402.306135 -432.542606)
			(xy 402.31822 -432.542188) (xy 403.25802 -432.542188) (xy 403.270095 -432.542647) (xy 403.293062 -432.550115)
			(xy 403.312599 -432.564313) (xy 403.326793 -432.583852) (xy 403.334255 -432.606821) (xy 403.334728 -432.618896)
			(xy 403.334728 -435.16042) (xy 403.334253 -435.172494) (xy 403.326787 -435.195458) (xy 403.312593 -435.214993)
			(xy 403.293058 -435.229187) (xy 403.270094 -435.236653) (xy 403.25802 -435.237128) (xy 402.31822 -435.237128)
			(xy 402.306148 -435.236619) (xy 402.283185 -435.229165) (xy 402.26365 -435.214979) (xy 402.249454 -435.195451)
			(xy 402.241987 -435.172491) (xy 402.241512 -435.16042) (xy 402.241512 -434.550058) (xy 402.239846 -434.535064)
			(xy 402.238066 -434.504946) (xy 402.237956 -434.48986) (xy 401.334732 -434.48986) (xy 401.334732 -435.489858)
			(xy 404.237952 -435.489858) (xy 404.238065 -435.474772) (xy 404.239844 -435.444654) (xy 404.241508 -435.42966)
			(xy 404.241508 -434.35016) (xy 404.239843 -434.335166) (xy 404.238062 -434.305048) (xy 404.237952 -434.289962)
			(xy 404.238065 -434.274876) (xy 404.239844 -434.244758) (xy 404.241508 -434.229764) (xy 404.241508 -433.618894)
			(xy 404.242002 -433.606807) (xy 404.249456 -433.583812) (xy 404.263637 -433.564235) (xy 404.283163 -433.549984)
			(xy 404.306131 -433.542446) (xy 404.318216 -433.541932) (xy 405.258016 -433.541932) (xy 405.270129 -433.542303)
			(xy 405.293162 -433.549811) (xy 405.312738 -433.564083) (xy 405.326931 -433.583716) (xy 405.334345 -433.606779)
			(xy 405.334724 -433.618894) (xy 405.334724 -434.48986) (xy 406.237948 -434.48986) (xy 406.238061 -434.474774)
			(xy 406.23984 -434.444656) (xy 406.241504 -434.429662) (xy 406.241504 -433.350162) (xy 406.239839 -433.335168)
			(xy 406.238058 -433.30505) (xy 406.237948 -433.289964) (xy 406.238061 -433.274878) (xy 406.23984 -433.24476)
			(xy 406.241504 -433.229766) (xy 406.241504 -432.618896) (xy 406.241909 -432.606812) (xy 406.249379 -432.583827)
			(xy 406.263587 -432.564276) (xy 406.283141 -432.550072) (xy 406.306128 -432.542607) (xy 406.318212 -432.542188)
			(xy 407.258012 -432.542188) (xy 407.270087 -432.542654) (xy 407.293054 -432.550119) (xy 407.31259 -432.564316)
			(xy 407.326784 -432.583854) (xy 407.334247 -432.606821) (xy 407.33472 -432.618896) (xy 407.33472 -435.16042)
			(xy 407.334253 -435.172494) (xy 407.326786 -435.19546) (xy 407.31259 -435.214996) (xy 407.293053 -435.22919)
			(xy 407.270086 -435.236654) (xy 407.258012 -435.237128) (xy 406.318212 -435.237128) (xy 406.30614 -435.236626)
			(xy 406.283177 -435.229169) (xy 406.263641 -435.214982) (xy 406.249446 -435.195452) (xy 406.241979 -435.172492)
			(xy 406.241504 -435.16042) (xy 406.241504 -434.550058) (xy 406.239838 -434.535064) (xy 406.238058 -434.504946)
			(xy 406.237948 -434.48986) (xy 405.334724 -434.48986) (xy 405.334724 -435.489858) (xy 408.237944 -435.489858)
			(xy 408.238057 -435.474772) (xy 408.239836 -435.444654) (xy 408.2415 -435.42966) (xy 408.2415 -434.35016)
			(xy 408.239834 -434.335166) (xy 408.238054 -434.305048) (xy 408.237944 -434.289962) (xy 408.238057 -434.274876)
			(xy 408.239836 -434.244758) (xy 408.2415 -434.229764) (xy 408.2415 -433.618894) (xy 408.242002 -433.606808)
			(xy 408.249455 -433.583814) (xy 408.263634 -433.564238) (xy 408.283158 -433.549986) (xy 408.306124 -433.542447)
			(xy 408.318208 -433.541932) (xy 409.258008 -433.541932) (xy 409.270121 -433.54231) (xy 409.293154 -433.549815)
			(xy 409.312729 -433.564086) (xy 409.326923 -433.583717) (xy 409.334337 -433.60678) (xy 409.334716 -433.618894)
			(xy 409.334716 -434.48986) (xy 410.23794 -434.48986) (xy 410.238053 -434.474774) (xy 410.239832 -434.444656)
			(xy 410.241496 -434.429662) (xy 410.241496 -433.350162) (xy 410.239831 -433.335168) (xy 410.23805 -433.30505)
			(xy 410.23794 -433.289964) (xy 410.238053 -433.274878) (xy 410.239832 -433.24476) (xy 410.241496 -433.229766)
			(xy 410.241496 -432.618896) (xy 410.241961 -432.606821) (xy 410.249425 -432.583853) (xy 410.263621 -432.564316)
			(xy 410.28316 -432.550121) (xy 410.306129 -432.54266) (xy 410.318204 -432.542188) (xy 411.258004 -432.542188)
			(xy 411.270078 -432.542661) (xy 411.293045 -432.550124) (xy 411.312582 -432.564318) (xy 411.326776 -432.583855)
			(xy 411.334239 -432.606822) (xy 411.334712 -432.618896) (xy 411.334712 -435.16042) (xy 411.334253 -435.172495)
			(xy 411.326785 -435.195462) (xy 411.312587 -435.214999) (xy 411.293048 -435.229193) (xy 411.270079 -435.236655)
			(xy 411.258004 -435.237128) (xy 410.318204 -435.237128) (xy 410.306132 -435.236633) (xy 410.283168 -435.229174)
			(xy 410.263633 -435.214984) (xy 410.249437 -435.195454) (xy 410.241971 -435.172492) (xy 410.241496 -435.16042)
			(xy 410.241496 -434.550058) (xy 410.23983 -434.535064) (xy 410.23805 -434.504946) (xy 410.23794 -434.48986)
			(xy 409.334716 -434.48986) (xy 409.334716 -435.489858) (xy 412.237936 -435.489858) (xy 412.238051 -435.474773)
			(xy 412.23983 -435.444654) (xy 412.241492 -435.42966) (xy 412.241492 -434.35016) (xy 412.239826 -434.335166)
			(xy 412.238046 -434.305048) (xy 412.237936 -434.289962) (xy 412.238051 -434.274877) (xy 412.23983 -434.244758)
			(xy 412.241492 -434.229764) (xy 412.241492 -433.618894) (xy 412.242002 -433.606809) (xy 412.249454 -433.583816)
			(xy 412.263631 -433.564241) (xy 412.283153 -433.549989) (xy 412.306117 -433.542448) (xy 412.3182 -433.541932)
			(xy 413.258 -433.541932) (xy 413.270112 -433.542317) (xy 413.293145 -433.54982) (xy 413.312721 -433.564088)
			(xy 413.326914 -433.583719) (xy 413.334329 -433.60678) (xy 413.334708 -433.618894) (xy 413.334708 -436.160418)
			(xy 413.334209 -436.172504) (xy 413.326753 -436.195497) (xy 413.312573 -436.215072) (xy 413.29305 -436.229324)
			(xy 413.270084 -436.236864) (xy 413.258 -436.23738) (xy 412.3182 -436.23738) (xy 412.306089 -436.236984)
			(xy 412.283058 -436.229482) (xy 412.263483 -436.215216) (xy 412.24929 -436.195589) (xy 412.241872 -436.17253)
			(xy 412.241492 -436.160418) (xy 412.241492 -435.550056) (xy 412.239826 -435.535062) (xy 412.238046 -435.504944)
			(xy 412.237936 -435.489858) (xy 409.334716 -435.489858) (xy 409.334716 -436.160418) (xy 409.334307 -436.172513)
			(xy 409.32684 -436.195522) (xy 409.31264 -436.215105) (xy 409.293092 -436.229353) (xy 409.270102 -436.236877)
			(xy 409.258008 -436.23738) (xy 408.318208 -436.23738) (xy 408.306098 -436.236977) (xy 408.283067 -436.229477)
			(xy 408.263492 -436.215213) (xy 408.249298 -436.195587) (xy 408.24188 -436.17253) (xy 408.2415 -436.160418)
			(xy 408.2415 -435.550056) (xy 408.239834 -435.535062) (xy 408.238054 -435.504944) (xy 408.237944 -435.489858)
			(xy 405.334724 -435.489858) (xy 405.334724 -436.160418) (xy 405.334307 -436.172512) (xy 405.326841 -436.195519)
			(xy 405.312643 -436.215102) (xy 405.293097 -436.229351) (xy 405.270109 -436.236876) (xy 405.258016 -436.23738)
			(xy 404.318216 -436.23738) (xy 404.306106 -436.23697) (xy 404.283076 -436.229472) (xy 404.263501 -436.21521)
			(xy 404.249306 -436.195585) (xy 404.241889 -436.172529) (xy 404.241508 -436.160418) (xy 404.241508 -435.550056)
			(xy 404.239842 -435.535062) (xy 404.238062 -435.504944) (xy 404.237952 -435.489858) (xy 401.334732 -435.489858)
			(xy 401.334732 -436.160418) (xy 401.334308 -436.172511) (xy 401.326843 -436.195517) (xy 401.312646 -436.215099)
			(xy 401.293102 -436.229348) (xy 401.270116 -436.236875) (xy 401.258024 -436.23738) (xy 400.318224 -436.23738)
			(xy 400.306114 -436.236963) (xy 400.283085 -436.229468) (xy 400.263509 -436.215207) (xy 400.249315 -436.195584)
			(xy 400.241897 -436.172529) (xy 400.241516 -436.160418) (xy 400.241516 -435.550056) (xy 400.23985 -435.535062)
			(xy 400.23807 -435.504944) (xy 400.23796 -435.489858) (xy 396.334996 -435.489858) (xy 396.334996 -436.160418)
			(xy 396.334504 -436.17253) (xy 396.327016 -436.195568) (xy 396.312778 -436.215167) (xy 396.293183 -436.229409)
			(xy 396.270146 -436.236902) (xy 396.258034 -436.23738) (xy 395.318234 -436.23738) (xy 395.306115 -436.236911)
			(xy 395.28306 -436.229431) (xy 395.263446 -436.215191) (xy 395.249193 -436.195587) (xy 395.241697 -436.172537)
			(xy 395.241272 -436.160418) (xy 395.241272 -435.548024) (xy 395.239724 -435.533532) (xy 395.238074 -435.504432)
			(xy 395.23797 -435.489858) (xy 392.335004 -435.489858) (xy 392.335004 -436.160418) (xy 392.334504 -436.172529)
			(xy 392.327017 -436.195566) (xy 392.312781 -436.215164) (xy 392.293188 -436.229406) (xy 392.270153 -436.236901)
			(xy 392.258042 -436.23738) (xy 391.318242 -436.23738) (xy 391.306123 -436.236905) (xy 391.283069 -436.229426)
			(xy 391.263455 -436.215188) (xy 391.249201 -436.195585) (xy 391.241705 -436.172536) (xy 391.24128 -436.160418)
			(xy 391.24128 -435.548024) (xy 391.239732 -435.533532) (xy 391.238082 -435.504432) (xy 391.237978 -435.489858)
			(xy 388.335012 -435.489858) (xy 388.335012 -436.160418) (xy 388.334505 -436.172529) (xy 388.327018 -436.195564)
			(xy 388.312784 -436.215161) (xy 388.293193 -436.229404) (xy 388.27016 -436.2369) (xy 388.25805 -436.23738)
			(xy 387.31825 -436.23738) (xy 387.306135 -436.236931) (xy 387.283093 -436.229432) (xy 387.263493 -436.215184)
			(xy 387.249253 -436.195578) (xy 387.241764 -436.172534) (xy 387.241288 -436.160418) (xy 387.241288 -435.548024)
			(xy 387.23974 -435.533532) (xy 387.23809 -435.504432) (xy 387.237986 -435.489858) (xy 384.33502 -435.489858)
			(xy 384.33502 -436.160418) (xy 384.334654 -436.172546) (xy 384.327152 -436.195612) (xy 384.312888 -436.215231)
			(xy 384.293258 -436.22948) (xy 384.270186 -436.236964) (xy 384.258058 -436.23738) (xy 383.318258 -436.23738)
			(xy 383.306143 -436.236924) (xy 383.283101 -436.229428) (xy 383.263502 -436.215181) (xy 383.249261 -436.195577)
			(xy 383.241772 -436.172533) (xy 383.241296 -436.160418) (xy 383.241296 -435.548024) (xy 383.239748 -435.533532)
			(xy 383.238098 -435.504432) (xy 383.237994 -435.489858) (xy 361.616728 -435.489858) (xy 361.642562 -435.536833)
			(xy 361.697938 -435.654184) (xy 361.74595 -435.774736) (xy 361.786412 -435.898026) (xy 361.81917 -436.023584)
			(xy 361.844098 -436.150927) (xy 361.861101 -436.279569) (xy 361.870114 -436.409016) (xy 361.871103 -436.538773)
			(xy 361.864062 -436.668342) (xy 361.849021 -436.797228) (xy 361.826035 -436.924936) (xy 361.795194 -437.050978)
			(xy 361.756614 -437.174871) (xy 361.710445 -437.29614) (xy 361.656862 -437.41432) (xy 361.596072 -437.52896)
			(xy 361.528306 -437.63962) (xy 361.453825 -437.745876) (xy 361.372914 -437.847321) (xy 361.285882 -437.943567)
			(xy 361.193064 -438.034245) (xy 361.128666 -438.089802) (xy 381.237998 -438.089802) (xy 381.238091 -438.075228)
			(xy 381.239744 -438.046127) (xy 381.2413 -438.031636) (xy 381.2413 -436.948072) (xy 381.239755 -436.93358)
			(xy 381.238103 -436.90448) (xy 381.237998 -436.889906) (xy 381.238091 -436.875332) (xy 381.239744 -436.846231)
			(xy 381.2413 -436.83174) (xy 381.2413 -436.219092) (xy 381.241709 -436.206983) (xy 381.249211 -436.183955)
			(xy 381.263474 -436.164382) (xy 381.283097 -436.150188) (xy 381.306151 -436.142767) (xy 381.318262 -436.142384)
			(xy 382.258062 -436.142384) (xy 382.270154 -436.142841) (xy 382.293161 -436.150292) (xy 382.312745 -436.16448)
			(xy 382.326995 -436.184019) (xy 382.334521 -436.207002) (xy 382.335024 -436.219092) (xy 382.335024 -438.760616)
			(xy 382.334598 -438.772723) (xy 382.327097 -438.795747) (xy 382.312837 -438.815318) (xy 382.293219 -438.829513)
			(xy 382.270171 -438.836937) (xy 382.258062 -438.837324) (xy 381.318262 -438.837324) (xy 381.306167 -438.836924)
			(xy 381.283159 -438.829453) (xy 381.263577 -438.81525) (xy 381.249329 -438.795701) (xy 381.241804 -438.77271)
			(xy 381.2413 -438.760616) (xy 381.2413 -438.147968) (xy 381.239755 -438.133476) (xy 381.238103 -438.104376)
			(xy 381.237998 -438.089802) (xy 361.128666 -438.089802) (xy 361.094814 -438.119007) (xy 360.991508 -438.19753)
			(xy 360.883543 -438.269512) (xy 360.771333 -438.334677) (xy 360.655306 -438.392776) (xy 360.535907 -438.443587)
			(xy 360.413594 -438.486915) (xy 360.288835 -438.522593) (xy 360.162108 -438.550485) (xy 360.033898 -438.570485)
			(xy 359.904696 -438.582516) (xy 359.774998 -438.586531) (xy 359.6453 -438.582516) (xy 359.516098 -438.570485)
			(xy 359.387888 -438.550485) (xy 359.261161 -438.522593) (xy 359.136402 -438.486915) (xy 359.014089 -438.443587)
			(xy 358.89469 -438.392776) (xy 358.778663 -438.334677) (xy 358.666453 -438.269512) (xy 358.558488 -438.19753)
			(xy 358.455182 -438.119007) (xy 358.356932 -438.034245) (xy 358.264114 -437.943567) (xy 358.177082 -437.847321)
			(xy 358.096171 -437.745876) (xy 358.02169 -437.63962) (xy 357.953924 -437.52896) (xy 357.893134 -437.41432)
			(xy 357.839551 -437.29614) (xy 357.793382 -437.174871) (xy 357.754802 -437.050978) (xy 357.723961 -436.924936)
			(xy 357.700975 -436.797228) (xy 357.685934 -436.668342) (xy 357.678893 -436.538773) (xy 357.679882 -436.409016)
			(xy 357.688895 -436.279569) (xy 357.705898 -436.150927) (xy 357.730826 -436.023584) (xy 357.763584 -435.898026)
			(xy 357.804046 -435.774736) (xy 357.852058 -435.654184) (xy 357.907434 -435.536833) (xy 357.969964 -435.423133)
			(xy 358.039407 -435.313518) (xy 358.115498 -435.208409) (xy 358.197945 -435.108208) (xy 358.286433 -435.013299)
			(xy 358.380622 -434.924045) (xy 358.430068 -434.882036) (xy 358.441235 -434.872067) (xy 358.457661 -434.847056)
			(xy 358.466134 -434.818358) (xy 358.465926 -434.788437) (xy 358.457055 -434.759859) (xy 358.440283 -434.735079)
			(xy 358.417049 -434.716224) (xy 358.403398 -434.710078) (xy 358.324356 -434.677212) (xy 358.169157 -434.604934)
			(xy 358.017549 -434.5254) (xy 357.869871 -434.438788) (xy 357.726451 -434.345291) (xy 357.587612 -434.24512)
			(xy 357.453663 -434.138498) (xy 357.324904 -434.025662) (xy 357.201623 -433.906867) (xy 357.084096 -433.782376)
			(xy 356.972584 -433.652469) (xy 356.867339 -433.517435) (xy 356.768594 -433.377578) (xy 356.676571 -433.233209)
			(xy 356.591476 -433.084651) (xy 356.513498 -432.932237) (xy 356.442812 -432.776307) (xy 356.379576 -432.61721)
			(xy 356.323932 -432.455301) (xy 356.276004 -432.290943) (xy 356.235899 -432.124503) (xy 356.203706 -431.956354)
			(xy 356.179498 -431.78687) (xy 356.163329 -431.616432) (xy 356.155235 -431.44542) (xy 356.154736 -431.359818)
			(xy 346.23502 -431.359818) (xy 346.23502 -432.560476) (xy 346.234563 -432.572582) (xy 346.227073 -432.595605)
			(xy 346.212821 -432.615176) (xy 346.193209 -432.629373) (xy 346.170165 -432.636797) (xy 346.158058 -432.637184)
			(xy 345.218258 -432.637184) (xy 345.206169 -432.636729) (xy 345.183171 -432.629264) (xy 345.163593 -432.615073)
			(xy 345.149343 -432.595539) (xy 345.141808 -432.572564) (xy 345.141296 -432.560476) (xy 345.141296 -431.948082)
			(xy 345.139753 -431.93359) (xy 345.1381 -431.90449) (xy 345.137994 -431.889916) (xy 342.235028 -431.889916)
			(xy 342.235028 -432.560476) (xy 342.234563 -432.572581) (xy 342.227074 -432.595602) (xy 342.212824 -432.615174)
			(xy 342.193214 -432.62937) (xy 342.170172 -432.636796) (xy 342.158066 -432.637184) (xy 341.218266 -432.637184)
			(xy 341.206177 -432.636722) (xy 341.183179 -432.629259) (xy 341.163602 -432.61507) (xy 341.149352 -432.595538)
			(xy 341.141816 -432.572563) (xy 341.141304 -432.560476) (xy 341.141304 -431.948082) (xy 341.13976 -431.93359)
			(xy 341.138108 -431.90449) (xy 341.138002 -431.889916) (xy 338.235036 -431.889916) (xy 338.235036 -432.560476)
			(xy 338.234564 -432.57258) (xy 338.227075 -432.5956) (xy 338.212827 -432.615171) (xy 338.193219 -432.629367)
			(xy 338.170179 -432.636795) (xy 338.158074 -432.637184) (xy 337.218274 -432.637184) (xy 337.206185 -432.636715)
			(xy 337.183188 -432.629254) (xy 337.163611 -432.615067) (xy 337.14936 -432.595536) (xy 337.141824 -432.572563)
			(xy 337.141312 -432.560476) (xy 337.141312 -431.948082) (xy 337.139768 -431.93359) (xy 337.138116 -431.90449)
			(xy 337.13801 -431.889916) (xy 334.235044 -431.889916) (xy 334.235044 -432.560476) (xy 334.234564 -432.572579)
			(xy 334.227076 -432.595598) (xy 334.21283 -432.615168) (xy 334.193224 -432.629365) (xy 334.170186 -432.636794)
			(xy 334.158082 -432.637184) (xy 333.218282 -432.637184) (xy 333.206194 -432.636709) (xy 333.183197 -432.62925)
			(xy 333.163619 -432.615065) (xy 333.149368 -432.595535) (xy 333.141832 -432.572563) (xy 333.14132 -432.560476)
			(xy 333.14132 -431.948082) (xy 333.139776 -431.93359) (xy 333.138124 -431.90449) (xy 333.138018 -431.889916)
			(xy 329.2348 -431.889916) (xy 329.2348 -432.560476) (xy 329.234367 -432.572558) (xy 329.226905 -432.595542)
			(xy 329.212704 -432.615093) (xy 329.193156 -432.629297) (xy 329.170174 -432.636764) (xy 329.158092 -432.637184)
			(xy 328.218292 -432.637184) (xy 328.206206 -432.636794) (xy 328.183219 -432.629321) (xy 328.163667 -432.61511)
			(xy 328.149464 -432.595552) (xy 328.142001 -432.572562) (xy 328.141584 -432.560476) (xy 328.141584 -431.950114)
			(xy 328.139914 -431.935121) (xy 328.138137 -431.905002) (xy 328.138028 -431.889916) (xy 325.234808 -431.889916)
			(xy 325.234808 -432.560476) (xy 325.234367 -432.572557) (xy 325.226906 -432.595539) (xy 325.212707 -432.61509)
			(xy 325.193161 -432.629295) (xy 325.170181 -432.636763) (xy 325.1581 -432.637184) (xy 324.2183 -432.637184)
			(xy 324.206215 -432.636787) (xy 324.183228 -432.629317) (xy 324.163676 -432.615107) (xy 324.149472 -432.59555)
			(xy 324.142009 -432.572561) (xy 324.141592 -432.560476) (xy 324.141592 -431.950114) (xy 324.139922 -431.935121)
			(xy 324.138145 -431.905002) (xy 324.138036 -431.889916) (xy 321.234816 -431.889916) (xy 321.234816 -432.560476)
			(xy 321.234367 -432.572557) (xy 321.226907 -432.595537) (xy 321.21271 -432.615087) (xy 321.193166 -432.629292)
			(xy 321.170188 -432.636762) (xy 321.158108 -432.637184) (xy 320.218308 -432.637184) (xy 320.206223 -432.63678)
			(xy 320.183237 -432.629312) (xy 320.163684 -432.615105) (xy 320.149481 -432.595549) (xy 320.142017 -432.572561)
			(xy 320.1416 -432.560476) (xy 320.1416 -431.950114) (xy 320.13993 -431.935121) (xy 320.138153 -431.905002)
			(xy 320.138044 -431.889916) (xy 317.234824 -431.889916) (xy 317.234824 -432.560476) (xy 317.234367 -432.572556)
			(xy 317.226908 -432.595535) (xy 317.212713 -432.615084) (xy 317.193171 -432.62929) (xy 317.170196 -432.636761)
			(xy 317.158116 -432.637184) (xy 316.218316 -432.637184) (xy 316.206232 -432.636773) (xy 316.183246 -432.629307)
			(xy 316.163693 -432.615101) (xy 316.149489 -432.595547) (xy 316.142026 -432.57256) (xy 316.141608 -432.560476)
			(xy 316.141608 -431.950114) (xy 316.139938 -431.935121) (xy 316.138161 -431.905002) (xy 316.138052 -431.889916)
			(xy 274.613204 -431.889916) (xy 274.618425 -431.905986) (xy 274.665585 -432.076867) (xy 274.705031 -432.249692)
			(xy 274.736684 -432.424113) (xy 274.760479 -432.599778) (xy 274.77637 -432.776334) (xy 274.784323 -432.953425)
			(xy 274.78482 -433.04206) (xy 274.784323 -433.130695) (xy 274.77637 -433.307786) (xy 274.760479 -433.484342)
			(xy 274.736684 -433.660007) (xy 274.705031 -433.834428) (xy 274.665585 -434.007253) (xy 274.618425 -434.178134)
			(xy 274.563646 -434.346728) (xy 274.509927 -434.48986) (xy 314.138056 -434.48986) (xy 314.138169 -434.474774)
			(xy 314.139948 -434.444656) (xy 314.141612 -434.429662) (xy 314.141612 -433.350162) (xy 314.139947 -433.335168)
			(xy 314.138166 -433.30505) (xy 314.138056 -433.289964) (xy 314.138169 -433.274878) (xy 314.139948 -433.24476)
			(xy 314.141612 -433.229766) (xy 314.141612 -432.618896) (xy 314.142009 -432.606811) (xy 314.14948 -432.583825)
			(xy 314.16369 -432.564273) (xy 314.183246 -432.550069) (xy 314.206235 -432.542606) (xy 314.21832 -432.542188)
			(xy 315.15812 -432.542188) (xy 315.170195 -432.542647) (xy 315.193162 -432.550115) (xy 315.212699 -432.564313)
			(xy 315.226893 -432.583852) (xy 315.234355 -432.606821) (xy 315.234828 -432.618896) (xy 315.234828 -435.16042)
			(xy 315.234353 -435.172494) (xy 315.226887 -435.195458) (xy 315.212693 -435.214993) (xy 315.193158 -435.229187)
			(xy 315.170194 -435.236653) (xy 315.15812 -435.237128) (xy 314.21832 -435.237128) (xy 314.206248 -435.236619)
			(xy 314.183285 -435.229165) (xy 314.16375 -435.214979) (xy 314.149554 -435.195451) (xy 314.142087 -435.172491)
			(xy 314.141612 -435.16042) (xy 314.141612 -434.550058) (xy 314.139946 -434.535064) (xy 314.138166 -434.504946)
			(xy 314.138056 -434.48986) (xy 274.509927 -434.48986) (xy 274.501358 -434.512693) (xy 274.431686 -434.675698)
			(xy 274.354772 -434.835412) (xy 274.270769 -434.991515) (xy 274.179848 -435.143692) (xy 274.082191 -435.291636)
			(xy 273.977994 -435.43505) (xy 273.934286 -435.489858) (xy 316.138052 -435.489858) (xy 316.138165 -435.474772)
			(xy 316.139944 -435.444654) (xy 316.141608 -435.42966) (xy 316.141608 -434.35016) (xy 316.139943 -434.335166)
			(xy 316.138162 -434.305048) (xy 316.138052 -434.289962) (xy 316.138165 -434.274876) (xy 316.139944 -434.244758)
			(xy 316.141608 -434.229764) (xy 316.141608 -433.618894) (xy 316.142102 -433.606807) (xy 316.149556 -433.583812)
			(xy 316.163737 -433.564235) (xy 316.183263 -433.549984) (xy 316.206231 -433.542446) (xy 316.218316 -433.541932)
			(xy 317.158116 -433.541932) (xy 317.170229 -433.542303) (xy 317.193262 -433.549811) (xy 317.212838 -433.564083)
			(xy 317.227031 -433.583716) (xy 317.234445 -433.606779) (xy 317.234824 -433.618894) (xy 317.234824 -434.48986)
			(xy 318.138048 -434.48986) (xy 318.138161 -434.474774) (xy 318.13994 -434.444656) (xy 318.141604 -434.429662)
			(xy 318.141604 -433.350162) (xy 318.139939 -433.335168) (xy 318.138158 -433.30505) (xy 318.138048 -433.289964)
			(xy 318.138161 -433.274878) (xy 318.13994 -433.24476) (xy 318.141604 -433.229766) (xy 318.141604 -432.618896)
			(xy 318.142009 -432.606812) (xy 318.149479 -432.583827) (xy 318.163687 -432.564276) (xy 318.183241 -432.550072)
			(xy 318.206228 -432.542607) (xy 318.218312 -432.542188) (xy 319.158112 -432.542188) (xy 319.170187 -432.542654)
			(xy 319.193154 -432.550119) (xy 319.21269 -432.564316) (xy 319.226884 -432.583854) (xy 319.234347 -432.606821)
			(xy 319.23482 -432.618896) (xy 319.23482 -435.16042) (xy 319.234353 -435.172494) (xy 319.226886 -435.19546)
			(xy 319.21269 -435.214996) (xy 319.193153 -435.22919) (xy 319.170186 -435.236654) (xy 319.158112 -435.237128)
			(xy 318.218312 -435.237128) (xy 318.20624 -435.236626) (xy 318.183277 -435.229169) (xy 318.163741 -435.214982)
			(xy 318.149546 -435.195452) (xy 318.142079 -435.172492) (xy 318.141604 -435.16042) (xy 318.141604 -434.550058)
			(xy 318.139938 -434.535064) (xy 318.138158 -434.504946) (xy 318.138048 -434.48986) (xy 317.234824 -434.48986)
			(xy 317.234824 -435.489858) (xy 320.138044 -435.489858) (xy 320.138157 -435.474772) (xy 320.139936 -435.444654)
			(xy 320.1416 -435.42966) (xy 320.1416 -434.35016) (xy 320.139934 -434.335166) (xy 320.138154 -434.305048)
			(xy 320.138044 -434.289962) (xy 320.138157 -434.274876) (xy 320.139936 -434.244758) (xy 320.1416 -434.229764)
			(xy 320.1416 -433.618894) (xy 320.142102 -433.606808) (xy 320.149555 -433.583814) (xy 320.163734 -433.564238)
			(xy 320.183258 -433.549986) (xy 320.206224 -433.542447) (xy 320.218308 -433.541932) (xy 321.158108 -433.541932)
			(xy 321.170221 -433.54231) (xy 321.193254 -433.549815) (xy 321.212829 -433.564086) (xy 321.227023 -433.583717)
			(xy 321.234437 -433.60678) (xy 321.234816 -433.618894) (xy 321.234816 -434.48986) (xy 322.13804 -434.48986)
			(xy 322.138153 -434.474774) (xy 322.139932 -434.444656) (xy 322.141596 -434.429662) (xy 322.141596 -433.350162)
			(xy 322.139931 -433.335168) (xy 322.13815 -433.30505) (xy 322.13804 -433.289964) (xy 322.138153 -433.274878)
			(xy 322.139932 -433.24476) (xy 322.141596 -433.229766) (xy 322.141596 -432.618896) (xy 322.142061 -432.606821)
			(xy 322.149525 -432.583853) (xy 322.163721 -432.564316) (xy 322.18326 -432.550121) (xy 322.206229 -432.54266)
			(xy 322.218304 -432.542188) (xy 323.158104 -432.542188) (xy 323.170178 -432.542661) (xy 323.193145 -432.550124)
			(xy 323.212682 -432.564318) (xy 323.226876 -432.583855) (xy 323.234339 -432.606822) (xy 323.234812 -432.618896)
			(xy 323.234812 -435.16042) (xy 323.234353 -435.172495) (xy 323.226885 -435.195462) (xy 323.212687 -435.214999)
			(xy 323.193148 -435.229193) (xy 323.170179 -435.236655) (xy 323.158104 -435.237128) (xy 322.218304 -435.237128)
			(xy 322.206232 -435.236633) (xy 322.183268 -435.229174) (xy 322.163733 -435.214984) (xy 322.149537 -435.195454)
			(xy 322.142071 -435.172492) (xy 322.141596 -435.16042) (xy 322.141596 -434.550058) (xy 322.13993 -434.535064)
			(xy 322.13815 -434.504946) (xy 322.13804 -434.48986) (xy 321.234816 -434.48986) (xy 321.234816 -435.489858)
			(xy 324.138036 -435.489858) (xy 324.138151 -435.474773) (xy 324.13993 -435.444654) (xy 324.141592 -435.42966)
			(xy 324.141592 -434.35016) (xy 324.139926 -434.335166) (xy 324.138146 -434.305048) (xy 324.138036 -434.289962)
			(xy 324.138151 -434.274877) (xy 324.13993 -434.244758) (xy 324.141592 -434.229764) (xy 324.141592 -433.618894)
			(xy 324.142102 -433.606809) (xy 324.149554 -433.583816) (xy 324.163731 -433.564241) (xy 324.183253 -433.549989)
			(xy 324.206217 -433.542448) (xy 324.2183 -433.541932) (xy 325.1581 -433.541932) (xy 325.170212 -433.542317)
			(xy 325.193245 -433.54982) (xy 325.212821 -433.564088) (xy 325.227014 -433.583719) (xy 325.234429 -433.60678)
			(xy 325.234808 -433.618894) (xy 325.234808 -434.48986) (xy 326.138032 -434.48986) (xy 326.138147 -434.474775)
			(xy 326.139926 -434.444656) (xy 326.141588 -434.429662) (xy 326.141588 -433.350162) (xy 326.139923 -433.335168)
			(xy 326.138142 -433.30505) (xy 326.138032 -433.289964) (xy 326.138148 -433.274879) (xy 326.139926 -433.24476)
			(xy 326.141588 -433.229766) (xy 326.141588 -432.618896) (xy 326.142061 -432.606822) (xy 326.149524 -432.583855)
			(xy 326.163718 -432.564318) (xy 326.183255 -432.550124) (xy 326.206222 -432.542661) (xy 326.218296 -432.542188)
			(xy 327.158096 -432.542188) (xy 327.17017 -432.542668) (xy 327.193136 -432.550129) (xy 327.212673 -432.564321)
			(xy 327.226868 -432.583857) (xy 327.234331 -432.606822) (xy 327.234804 -432.618896) (xy 327.234804 -435.16042)
			(xy 327.234353 -435.172496) (xy 327.226884 -435.195464) (xy 327.212684 -435.215001) (xy 327.193143 -435.229195)
			(xy 327.170172 -435.236656) (xy 327.158096 -435.237128) (xy 326.218296 -435.237128) (xy 326.206223 -435.236639)
			(xy 326.183259 -435.229178) (xy 326.163724 -435.214987) (xy 326.149529 -435.195455) (xy 326.142063 -435.172493)
			(xy 326.141588 -435.16042) (xy 326.141588 -434.550058) (xy 326.139922 -434.535064) (xy 326.138142 -434.504946)
			(xy 326.138032 -434.48986) (xy 325.234808 -434.48986) (xy 325.234808 -435.489858) (xy 328.138028 -435.489858)
			(xy 328.138143 -435.474773) (xy 328.139922 -435.444654) (xy 328.141584 -435.42966) (xy 328.141584 -434.35016)
			(xy 328.139918 -434.335166) (xy 328.138138 -434.305048) (xy 328.138028 -434.289962) (xy 328.138143 -434.274877)
			(xy 328.139922 -434.244758) (xy 328.141584 -434.229764) (xy 328.141584 -433.618894) (xy 328.142003 -433.6068)
			(xy 328.149467 -433.583792) (xy 328.163664 -433.564208) (xy 328.183211 -433.549959) (xy 328.206199 -433.542435)
			(xy 328.218292 -433.541932) (xy 329.158092 -433.541932) (xy 329.170204 -433.542323) (xy 329.193236 -433.549824)
			(xy 329.212812 -433.564091) (xy 329.227006 -433.58372) (xy 329.234421 -433.606781) (xy 329.2348 -433.618894)
			(xy 329.2348 -434.48986) (xy 331.138022 -434.48986) (xy 331.13812 -434.475286) (xy 331.13977 -434.446185)
			(xy 331.141324 -434.431694) (xy 331.141324 -433.34813) (xy 331.139776 -433.333638) (xy 331.138126 -433.304538)
			(xy 331.138022 -433.289964) (xy 331.13812 -433.27539) (xy 331.13977 -433.246289) (xy 331.141324 -433.231798)
			(xy 331.141324 -432.618896) (xy 331.141713 -432.606785) (xy 331.149217 -432.583753) (xy 331.163484 -432.564178)
			(xy 331.183113 -432.549984) (xy 331.206173 -432.542568) (xy 331.218286 -432.542188) (xy 332.158086 -432.542188)
			(xy 332.17018 -432.54262) (xy 332.193188 -432.550079) (xy 332.212772 -432.564273) (xy 332.227021 -432.583817)
			(xy 332.234545 -432.606804) (xy 332.235048 -432.618896) (xy 332.235048 -435.16042) (xy 332.234601 -435.172525)
			(xy 332.227102 -435.195545) (xy 332.212847 -435.215113) (xy 332.193235 -435.229309) (xy 332.170192 -435.236738)
			(xy 332.158086 -435.237128) (xy 331.218286 -435.237128) (xy 331.206192 -435.236704) (xy 331.183186 -435.22924)
			(xy 331.163603 -435.215043) (xy 331.149354 -435.195499) (xy 331.141828 -435.172512) (xy 331.141324 -435.16042)
			(xy 331.141324 -434.548026) (xy 331.139776 -434.533534) (xy 331.138126 -434.504434) (xy 331.138022 -434.48986)
			(xy 329.2348 -434.48986) (xy 329.2348 -435.489858) (xy 333.138018 -435.489858) (xy 333.138116 -435.475284)
			(xy 333.139766 -435.446183) (xy 333.14132 -435.431692) (xy 333.14132 -434.348128) (xy 333.139772 -434.333636)
			(xy 333.138122 -434.304536) (xy 333.138018 -434.289962) (xy 333.138116 -434.275388) (xy 333.139766 -434.246287)
			(xy 333.14132 -434.231796) (xy 333.14132 -433.618894) (xy 333.141807 -433.606781) (xy 333.149293 -433.583741)
			(xy 333.163532 -433.564141) (xy 333.18313 -433.549899) (xy 333.206169 -433.542408) (xy 333.218282 -433.541932)
			(xy 334.158082 -433.541932) (xy 334.170203 -433.542375) (xy 334.19326 -433.549862) (xy 334.212875 -433.564108)
			(xy 334.227127 -433.583718) (xy 334.234621 -433.606773) (xy 334.235044 -433.618894) (xy 334.235044 -434.48986)
			(xy 335.138014 -434.48986) (xy 335.138111 -434.475286) (xy 335.139761 -434.446185) (xy 335.141316 -434.431694)
			(xy 335.141316 -433.34813) (xy 335.139768 -433.333638) (xy 335.138118 -433.304538) (xy 335.138014 -433.289964)
			(xy 335.138112 -433.27539) (xy 335.139761 -433.246289) (xy 335.141316 -433.231798) (xy 335.141316 -432.618896)
			(xy 335.141713 -432.606785) (xy 335.149215 -432.583755) (xy 335.163481 -432.564181) (xy 335.183108 -432.549987)
			(xy 335.206166 -432.542569) (xy 335.218278 -432.542188) (xy 336.158078 -432.542188) (xy 336.170171 -432.542627)
			(xy 336.193179 -432.550084) (xy 336.212764 -432.564276) (xy 336.227013 -432.583818) (xy 336.234537 -432.606804)
			(xy 336.23504 -432.618896) (xy 336.23504 -435.16042) (xy 336.234601 -435.172526) (xy 336.227101 -435.195547)
			(xy 336.212844 -435.215116) (xy 336.19323 -435.229312) (xy 336.170185 -435.236739) (xy 336.158078 -435.237128)
			(xy 335.218278 -435.237128) (xy 335.206184 -435.236711) (xy 335.183177 -435.229244) (xy 335.163595 -435.215046)
			(xy 335.149346 -435.1955) (xy 335.14182 -435.172513) (xy 335.141316 -435.16042) (xy 335.141316 -434.548026)
			(xy 335.139768 -434.533534) (xy 335.138118 -434.504434) (xy 335.138014 -434.48986) (xy 334.235044 -434.48986)
			(xy 334.235044 -435.489858) (xy 337.13801 -435.489858) (xy 337.138107 -435.475284) (xy 337.139757 -435.446183)
			(xy 337.141312 -435.431692) (xy 337.141312 -434.348128) (xy 337.139764 -434.333636) (xy 337.138114 -434.304536)
			(xy 337.13801 -434.289962) (xy 337.138108 -434.275388) (xy 337.139757 -434.246287) (xy 337.141312 -434.231796)
			(xy 337.141312 -433.618894) (xy 337.141806 -433.606782) (xy 337.149292 -433.583743) (xy 337.163529 -433.564143)
			(xy 337.183125 -433.549901) (xy 337.206162 -433.54241) (xy 337.218274 -433.541932) (xy 338.158074 -433.541932)
			(xy 338.170195 -433.542382) (xy 338.193252 -433.549866) (xy 338.212867 -433.56411) (xy 338.227119 -433.58372)
			(xy 338.234613 -433.606773) (xy 338.235036 -433.618894) (xy 338.235036 -434.48986) (xy 339.138006 -434.48986)
			(xy 339.138104 -434.475286) (xy 339.139753 -434.446185) (xy 339.141308 -434.431694) (xy 339.141308 -433.34813)
			(xy 339.13976 -433.333638) (xy 339.13811 -433.304538) (xy 339.138006 -433.289964) (xy 339.138104 -433.27539)
			(xy 339.139753 -433.246289) (xy 339.141308 -433.231798) (xy 339.141308 -432.618896) (xy 339.141713 -432.606786)
			(xy 339.149214 -432.583757) (xy 339.163479 -432.564184) (xy 339.183103 -432.549989) (xy 339.206159 -432.54257)
			(xy 339.21827 -432.542188) (xy 340.15807 -432.542188) (xy 340.170163 -432.542634) (xy 340.19317 -432.550088)
			(xy 340.212755 -432.564278) (xy 340.227005 -432.58382) (xy 340.234529 -432.606805) (xy 340.235032 -432.618896)
			(xy 340.235032 -435.16042) (xy 340.234601 -435.172527) (xy 340.2271 -435.195549) (xy 340.212841 -435.215119)
			(xy 340.193225 -435.229314) (xy 340.170178 -435.23674) (xy 340.15807 -435.237128) (xy 339.21827 -435.237128)
			(xy 339.206176 -435.236718) (xy 339.183169 -435.229249) (xy 339.163586 -435.215049) (xy 339.149338 -435.195502)
			(xy 339.141812 -435.172513) (xy 339.141308 -435.16042) (xy 339.141308 -434.548026) (xy 339.13976 -434.533534)
			(xy 339.13811 -434.504434) (xy 339.138006 -434.48986) (xy 338.235036 -434.48986) (xy 338.235036 -435.489858)
			(xy 341.138002 -435.489858) (xy 341.138099 -435.475284) (xy 341.139749 -435.446183) (xy 341.141304 -435.431692)
			(xy 341.141304 -434.348128) (xy 341.139756 -434.333636) (xy 341.138106 -434.304536) (xy 341.138002 -434.289962)
			(xy 341.1381 -434.275388) (xy 341.139749 -434.246287) (xy 341.141304 -434.231796) (xy 341.141304 -433.618894)
			(xy 341.141806 -433.606783) (xy 341.149291 -433.583745) (xy 341.163526 -433.564146) (xy 341.18312 -433.549904)
			(xy 341.206155 -433.542411) (xy 341.218266 -433.541932) (xy 342.158066 -433.541932) (xy 342.170186 -433.542389)
			(xy 342.193243 -433.549871) (xy 342.212858 -433.564113) (xy 342.227111 -433.583721) (xy 342.234605 -433.606774)
			(xy 342.235028 -433.618894) (xy 342.235028 -434.48986) (xy 343.137998 -434.48986) (xy 343.138096 -434.475286)
			(xy 343.139745 -434.446185) (xy 343.1413 -434.431694) (xy 343.1413 -433.34813) (xy 343.139752 -433.333638)
			(xy 343.138102 -433.304538) (xy 343.137998 -433.289964) (xy 343.138096 -433.27539) (xy 343.139745 -433.246289)
			(xy 343.1413 -433.231798) (xy 343.1413 -432.618896) (xy 343.141713 -432.606787) (xy 343.149213 -432.583759)
			(xy 343.163476 -432.564186) (xy 343.183098 -432.549992) (xy 343.206152 -432.542571) (xy 343.218262 -432.542188)
			(xy 344.158062 -432.542188) (xy 344.170154 -432.542641) (xy 344.193162 -432.550093) (xy 344.212747 -432.564281)
			(xy 344.226997 -432.583821) (xy 344.234521 -432.606805) (xy 344.235024 -432.618896) (xy 344.235024 -435.16042)
			(xy 344.234601 -435.172528) (xy 344.227099 -435.195551) (xy 344.212838 -435.215122) (xy 344.19322 -435.229317)
			(xy 344.170171 -435.236741) (xy 344.158062 -435.237128) (xy 343.218262 -435.237128) (xy 343.206167 -435.236724)
			(xy 343.18316 -435.229253) (xy 343.163578 -435.215052) (xy 343.14933 -435.195503) (xy 343.141804 -435.172514)
			(xy 343.1413 -435.16042) (xy 343.1413 -434.548026) (xy 343.139752 -434.533534) (xy 343.138102 -434.504434)
			(xy 343.137998 -434.48986) (xy 342.235028 -434.48986) (xy 342.235028 -435.489858) (xy 345.137994 -435.489858)
			(xy 345.138091 -435.475284) (xy 345.139741 -435.446183) (xy 345.141296 -435.431692) (xy 345.141296 -434.348128)
			(xy 345.139748 -434.333636) (xy 345.138098 -434.304536) (xy 345.137994 -434.289962) (xy 345.138092 -434.275388)
			(xy 345.139741 -434.246287) (xy 345.141296 -434.231796) (xy 345.141296 -433.618894) (xy 345.141806 -433.606783)
			(xy 345.14929 -433.583747) (xy 345.163524 -433.564149) (xy 345.183115 -433.549906) (xy 345.206148 -433.542412)
			(xy 345.218258 -433.541932) (xy 346.158058 -433.541932) (xy 346.170178 -433.542396) (xy 346.193234 -433.549876)
			(xy 346.21285 -433.564116) (xy 346.227103 -433.583722) (xy 346.234597 -433.606774) (xy 346.23502 -433.618894)
			(xy 346.23502 -436.160418) (xy 346.234654 -436.172546) (xy 346.227152 -436.195612) (xy 346.212888 -436.215231)
			(xy 346.193258 -436.22948) (xy 346.170186 -436.236964) (xy 346.158058 -436.23738) (xy 345.218258 -436.23738)
			(xy 345.206143 -436.236924) (xy 345.183101 -436.229428) (xy 345.163502 -436.215181) (xy 345.149261 -436.195577)
			(xy 345.141772 -436.172533) (xy 345.141296 -436.160418) (xy 345.141296 -435.548024) (xy 345.139748 -435.533532)
			(xy 345.138098 -435.504432) (xy 345.137994 -435.489858) (xy 342.235028 -435.489858) (xy 342.235028 -436.160418)
			(xy 342.234655 -436.172545) (xy 342.227153 -436.19561) (xy 342.212891 -436.215228) (xy 342.193264 -436.229477)
			(xy 342.170193 -436.236963) (xy 342.158066 -436.23738) (xy 341.218266 -436.23738) (xy 341.206151 -436.236918)
			(xy 341.18311 -436.229423) (xy 341.16351 -436.215178) (xy 341.149269 -436.195576) (xy 341.14178 -436.172533)
			(xy 341.141304 -436.160418) (xy 341.141304 -435.548024) (xy 341.139755 -435.533532) (xy 341.138106 -435.504432)
			(xy 341.138002 -435.489858) (xy 338.235036 -435.489858) (xy 338.235036 -436.160418) (xy 338.234655 -436.172544)
			(xy 338.227154 -436.195608) (xy 338.212894 -436.215225) (xy 338.193269 -436.229474) (xy 338.1702 -436.236962)
			(xy 338.158074 -436.23738) (xy 337.218274 -436.23738) (xy 337.20616 -436.236911) (xy 337.183119 -436.229419)
			(xy 337.163519 -436.215175) (xy 337.149278 -436.195574) (xy 337.141788 -436.172532) (xy 337.141312 -436.160418)
			(xy 337.141312 -435.548024) (xy 337.139763 -435.533532) (xy 337.138114 -435.504432) (xy 337.13801 -435.489858)
			(xy 334.235044 -435.489858) (xy 334.235044 -436.160418) (xy 334.234604 -436.172535) (xy 334.227109 -436.195582)
			(xy 334.21286 -436.215185) (xy 334.19325 -436.229426) (xy 334.1702 -436.236909) (xy 334.158082 -436.23738)
			(xy 333.218282 -436.23738) (xy 333.206168 -436.236904) (xy 333.183127 -436.229414) (xy 333.163528 -436.215172)
			(xy 333.149286 -436.195573) (xy 333.141796 -436.172532) (xy 333.14132 -436.160418) (xy 333.14132 -435.548024)
			(xy 333.139771 -435.533532) (xy 333.138122 -435.504432) (xy 333.138018 -435.489858) (xy 329.2348 -435.489858)
			(xy 329.2348 -436.160418) (xy 329.234309 -436.172505) (xy 329.226852 -436.195499) (xy 329.21267 -436.215075)
			(xy 329.193145 -436.229327) (xy 329.170177 -436.236865) (xy 329.158092 -436.23738) (xy 328.218292 -436.23738)
			(xy 328.206181 -436.23699) (xy 328.18315 -436.229486) (xy 328.163575 -436.215219) (xy 328.149381 -436.19559)
			(xy 328.141964 -436.172531) (xy 328.141584 -436.160418) (xy 328.141584 -435.550056) (xy 328.139918 -435.535062)
			(xy 328.138138 -435.504944) (xy 328.138028 -435.489858) (xy 325.234808 -435.489858) (xy 325.234808 -436.160418)
			(xy 325.234309 -436.172504) (xy 325.226853 -436.195497) (xy 325.212673 -436.215072) (xy 325.19315 -436.229324)
			(xy 325.170184 -436.236864) (xy 325.1581 -436.23738) (xy 324.2183 -436.23738) (xy 324.206189 -436.236984)
			(xy 324.183158 -436.229482) (xy 324.163583 -436.215216) (xy 324.14939 -436.195589) (xy 324.141972 -436.17253)
			(xy 324.141592 -436.160418) (xy 324.141592 -435.550056) (xy 324.139926 -435.535062) (xy 324.138146 -435.504944)
			(xy 324.138036 -435.489858) (xy 321.234816 -435.489858) (xy 321.234816 -436.160418) (xy 321.234407 -436.172513)
			(xy 321.22694 -436.195522) (xy 321.21274 -436.215105) (xy 321.193192 -436.229353) (xy 321.170202 -436.236877)
			(xy 321.158108 -436.23738) (xy 320.218308 -436.23738) (xy 320.206198 -436.236977) (xy 320.183167 -436.229477)
			(xy 320.163592 -436.215213) (xy 320.149398 -436.195587) (xy 320.14198 -436.17253) (xy 320.1416 -436.160418)
			(xy 320.1416 -435.550056) (xy 320.139934 -435.535062) (xy 320.138154 -435.504944) (xy 320.138044 -435.489858)
			(xy 317.234824 -435.489858) (xy 317.234824 -436.160418) (xy 317.234407 -436.172512) (xy 317.226941 -436.195519)
			(xy 317.212743 -436.215102) (xy 317.193197 -436.229351) (xy 317.170209 -436.236876) (xy 317.158116 -436.23738)
			(xy 316.218316 -436.23738) (xy 316.206206 -436.23697) (xy 316.183176 -436.229472) (xy 316.163601 -436.21521)
			(xy 316.149406 -436.195585) (xy 316.141989 -436.172529) (xy 316.141608 -436.160418) (xy 316.141608 -435.550056)
			(xy 316.139942 -435.535062) (xy 316.138162 -435.504944) (xy 316.138052 -435.489858) (xy 273.934286 -435.489858)
			(xy 273.867468 -435.573645) (xy 273.750836 -435.707142) (xy 273.628331 -435.835271) (xy 273.500202 -435.957776)
			(xy 273.366705 -436.074408) (xy 273.22811 -436.184934) (xy 273.084696 -436.289131) (xy 272.936752 -436.386788)
			(xy 272.784575 -436.477709) (xy 272.628472 -436.561712) (xy 272.468758 -436.638626) (xy 272.305753 -436.708298)
			(xy 272.139788 -436.770586) (xy 271.971194 -436.825365) (xy 271.800313 -436.872525) (xy 271.627488 -436.911971)
			(xy 271.453067 -436.943624) (xy 271.277402 -436.967419) (xy 271.100846 -436.98331) (xy 270.923755 -436.991263)
			(xy 270.746485 -436.991263) (xy 270.569394 -436.98331) (xy 270.392838 -436.967419) (xy 270.217173 -436.943624)
			(xy 270.042752 -436.911971) (xy 269.869927 -436.872525) (xy 269.699046 -436.825365) (xy 269.530452 -436.770586)
			(xy 269.364487 -436.708298) (xy 269.201482 -436.638626) (xy 269.041768 -436.561712) (xy 268.885665 -436.477709)
			(xy 268.733488 -436.386788) (xy 268.585544 -436.289131) (xy 268.44213 -436.184934) (xy 268.303535 -436.074408)
			(xy 268.170038 -435.957776) (xy 268.041909 -435.835271) (xy 267.919404 -435.707142) (xy 267.802772 -435.573645)
			(xy 267.692246 -435.43505) (xy 267.588049 -435.291636) (xy 267.490392 -435.143692) (xy 267.399471 -434.991515)
			(xy 267.315468 -434.835412) (xy 267.238554 -434.675698) (xy 267.168882 -434.512693) (xy 267.106594 -434.346728)
			(xy 267.051815 -434.178134) (xy 267.004655 -434.007253) (xy 266.965209 -433.834428) (xy 266.933556 -433.660007)
			(xy 266.909761 -433.484342) (xy 266.89387 -433.307786) (xy 266.885917 -433.130695) (xy 231.01554 -433.130695)
			(xy 231.01554 -435.063392) (xy 231.015024 -435.08834) (xy 231.007214 -435.137622) (xy 230.991802 -435.185079)
			(xy 230.969165 -435.229545) (xy 230.939859 -435.269929) (xy 230.922576 -435.287928) (xy 229.133908 -437.076596)
			(xy 229.115913 -437.093886) (xy 229.075537 -437.12321) (xy 229.031071 -437.145858) (xy 228.98361 -437.161272)
			(xy 228.934323 -437.169073) (xy 228.909372 -437.16956) (xy 207.503268 -437.16956) (xy 207.478319 -437.169063)
			(xy 207.429037 -437.161248) (xy 207.38158 -437.14583) (xy 207.337114 -437.123189) (xy 207.296731 -437.09388)
			(xy 207.278732 -437.076596) (xy 205.949804 -435.747668) (xy 205.932495 -435.72969) (xy 205.903173 -435.68931)
			(xy 205.880529 -435.64484) (xy 205.865119 -435.597375) (xy 205.857324 -435.548084) (xy 205.85684 -435.523132)
			(xy 205.85684 -429.817784) (xy 197.285356 -421.2463) (xy 192.73774 -421.2463) (xy 192.712789 -421.245838)
			(xy 192.663505 -421.238017) (xy 192.616047 -421.222592) (xy 192.571582 -421.199943) (xy 192.531201 -421.170625)
			(xy 192.513204 -421.153336) (xy 184.781952 -413.422084) (xy 184.764639 -413.404108) (xy 184.735311 -413.363729)
			(xy 184.712661 -413.319259) (xy 184.697247 -413.271794) (xy 184.689448 -413.222501) (xy 184.688988 -413.197548)
			(xy 184.688988 -408.491182) (xy 184.68948 -408.466233) (xy 184.697294 -408.416949) (xy 184.712712 -408.369492)
			(xy 184.735355 -408.325026) (xy 184.764667 -408.284644) (xy 184.781952 -408.266646) (xy 184.892188 -408.15641)
			(xy 184.892188 -407.290778) (xy 184.874462 -407.269826) (xy 184.844586 -407.223792) (xy 184.821621 -407.173948)
			(xy 184.806044 -407.121325) (xy 184.798176 -407.067012) (xy 184.7977 -407.039572) (xy 184.798716 -407.01341)
			(xy 184.80024 -406.99055) (xy 184.654952 -406.845262) (xy 184.637629 -406.827296) (xy 184.608302 -406.786914)
			(xy 184.585654 -406.742442) (xy 184.570242 -406.694974) (xy 184.562446 -406.64568) (xy 184.561988 -406.620726)
			(xy 16.741648 -406.620726) (xy 16.741648 -407.035508) (xy 16.741601 -407.038147) (xy 34.34512 -407.038147)
			(xy 34.34512 -406.986133) (xy 34.353257 -406.934759) (xy 34.36933 -406.885291) (xy 34.392944 -406.838946)
			(xy 34.423518 -406.796865) (xy 34.460297 -406.760086) (xy 34.502378 -406.729512) (xy 34.548723 -406.705898)
			(xy 34.598191 -406.689825) (xy 34.649565 -406.681688) (xy 34.701579 -406.681688) (xy 34.752953 -406.689825)
			(xy 34.802421 -406.705898) (xy 34.848766 -406.729512) (xy 34.890847 -406.760086) (xy 34.927626 -406.796865)
			(xy 34.9582 -406.838946) (xy 34.981814 -406.885291) (xy 34.997887 -406.934759) (xy 35.006024 -406.986133)
			(xy 35.006534 -407.01214) (xy 35.006024 -407.038147) (xy 34.997887 -407.089521) (xy 34.981814 -407.138989)
			(xy 34.9582 -407.185334) (xy 34.927626 -407.227415) (xy 34.927509 -407.227532) (xy 35.858958 -407.227532)
			(xy 35.859212 -407.227532) (xy 35.859212 -406.9207) (xy 35.86038 -406.90633) (xy 35.869962 -406.879149)
			(xy 35.886927 -406.855851) (xy 35.909853 -406.838386) (xy 35.93682 -406.828218) (xy 35.95116 -406.82672)
			(xy 37.020754 -406.82672) (xy 37.033132 -406.827356) (xy 37.057024 -406.833922) (xy 37.07859 -406.846122)
			(xy 37.08781 -406.854406) (xy 37.097184 -406.864098) (xy 37.110898 -406.8873) (xy 37.117928 -406.913318)
			(xy 37.11829 -406.926796) (xy 37.118036 -406.926796) (xy 37.118036 -407.031753) (xy 48.944975 -407.031753)
			(xy 48.944975 -406.977247) (xy 48.952733 -406.923295) (xy 48.96809 -406.870997) (xy 48.990734 -406.821417)
			(xy 49.020204 -406.775565) (xy 49.0559 -406.734373) (xy 49.097095 -406.698681) (xy 49.142951 -406.669216)
			(xy 49.192533 -406.646577) (xy 49.244833 -406.631225) (xy 49.298785 -406.623473) (xy 49.326038 -406.623012)
			(xy 50.189638 -406.623012) (xy 50.216889 -406.62346) (xy 50.270835 -406.631222) (xy 50.323128 -406.646581)
			(xy 50.372703 -406.669225) (xy 50.418551 -406.698694) (xy 50.459739 -406.734388) (xy 50.495428 -406.775579)
			(xy 50.524893 -406.82143) (xy 50.547532 -406.871007) (xy 50.562886 -406.923302) (xy 50.570642 -406.977249)
			(xy 50.570642 -407.031749) (xy 52.008298 -407.031749) (xy 52.008298 -406.977251) (xy 52.016054 -406.923308)
			(xy 52.031407 -406.871018) (xy 52.054045 -406.821445) (xy 52.083508 -406.775598) (xy 52.119195 -406.734411)
			(xy 52.16038 -406.698721) (xy 52.206226 -406.669256) (xy 52.255797 -406.646615) (xy 52.308087 -406.631258)
			(xy 52.362029 -406.6235) (xy 52.389278 -406.623012) (xy 53.252878 -406.623012) (xy 53.280133 -406.623433)
			(xy 53.33409 -406.631188) (xy 53.386393 -406.646543) (xy 53.435978 -406.669186) (xy 53.481837 -406.698655)
			(xy 53.523034 -406.73435) (xy 53.558732 -406.775546) (xy 53.588204 -406.821402) (xy 53.610849 -406.870987)
			(xy 53.626207 -406.923289) (xy 53.633965 -406.977245) (xy 53.633965 -407.031752) (xy 55.071475 -407.031752)
			(xy 55.071475 -406.977248) (xy 55.079232 -406.923298) (xy 55.094589 -406.871002) (xy 55.117231 -406.821423)
			(xy 55.146699 -406.775571) (xy 55.182393 -406.73438) (xy 55.223586 -406.698688) (xy 55.269439 -406.669222)
			(xy 55.319018 -406.646582) (xy 55.371316 -406.631229) (xy 55.425266 -406.623474) (xy 55.452518 -406.623012)
			(xy 56.316118 -406.623012) (xy 56.34337 -406.623459) (xy 56.397318 -406.631218) (xy 56.449614 -406.646576)
			(xy 56.499191 -406.669219) (xy 56.545042 -406.698687) (xy 56.586232 -406.734381) (xy 56.621924 -406.775573)
			(xy 56.65139 -406.821424) (xy 56.674031 -406.871003) (xy 56.689386 -406.923299) (xy 56.697142 -406.977248)
			(xy 56.697142 -407.031748) (xy 58.134798 -407.031748) (xy 58.134798 -406.977252) (xy 58.142553 -406.923311)
			(xy 58.157905 -406.871022) (xy 58.180542 -406.821451) (xy 58.210003 -406.775605) (xy 58.245688 -406.734418)
			(xy 58.286871 -406.698728) (xy 58.332714 -406.669262) (xy 58.382283 -406.64662) (xy 58.43457 -406.631262)
			(xy 58.48851 -406.623501) (xy 58.515758 -406.623012) (xy 59.379358 -406.623012) (xy 59.406614 -406.623432)
			(xy 59.460573 -406.631185) (xy 59.512878 -406.646538) (xy 59.562466 -406.669179) (xy 59.608327 -406.698648)
			(xy 59.649527 -406.734343) (xy 59.685227 -406.775539) (xy 59.714701 -406.821397) (xy 59.737348 -406.870982)
			(xy 59.752707 -406.923286) (xy 59.760465 -406.977244) (xy 59.760465 -407.03175) (xy 61.197998 -407.03175)
			(xy 61.197998 -406.97725) (xy 61.205754 -406.923306) (xy 61.221108 -406.871014) (xy 61.243748 -406.821439)
			(xy 61.273213 -406.775592) (xy 61.308902 -406.734404) (xy 61.35009 -406.698714) (xy 61.395938 -406.669249)
			(xy 61.445512 -406.646609) (xy 61.497804 -406.631255) (xy 61.551748 -406.623498) (xy 61.578998 -406.623012)
			(xy 62.442598 -406.623012) (xy 62.469852 -406.623435) (xy 62.523806 -406.631192) (xy 62.576107 -406.646549)
			(xy 62.62569 -406.669192) (xy 62.671546 -406.698662) (xy 62.712741 -406.734357) (xy 62.748437 -406.775552)
			(xy 62.777907 -406.821408) (xy 62.800551 -406.870991) (xy 62.815908 -406.923292) (xy 62.823665 -406.977246)
			(xy 62.823665 -407.031753) (xy 64.261175 -407.031753) (xy 64.261175 -406.977247) (xy 64.268933 -406.923295)
			(xy 64.28429 -406.870997) (xy 64.306934 -406.821417) (xy 64.336404 -406.775565) (xy 64.3721 -406.734373)
			(xy 64.413295 -406.698681) (xy 64.459151 -406.669216) (xy 64.508733 -406.646577) (xy 64.561033 -406.631225)
			(xy 64.614985 -406.623473) (xy 64.642238 -406.623012) (xy 65.505838 -406.623012) (xy 65.533089 -406.62346)
			(xy 65.587035 -406.631222) (xy 65.639328 -406.646581) (xy 65.688903 -406.669225) (xy 65.734751 -406.698694)
			(xy 65.775939 -406.734388) (xy 65.811628 -406.775579) (xy 65.841093 -406.82143) (xy 65.863732 -406.871007)
			(xy 65.879086 -406.923302) (xy 65.886842 -406.977249) (xy 65.886842 -407.031749) (xy 67.324498 -407.031749)
			(xy 67.324498 -406.977251) (xy 67.332254 -406.923308) (xy 67.347607 -406.871018) (xy 67.370245 -406.821445)
			(xy 67.399708 -406.775598) (xy 67.435395 -406.734411) (xy 67.47658 -406.698721) (xy 67.522426 -406.669256)
			(xy 67.571997 -406.646615) (xy 67.624287 -406.631258) (xy 67.678229 -406.6235) (xy 67.705478 -406.623012)
			(xy 68.569078 -406.623012) (xy 68.596333 -406.623433) (xy 68.65029 -406.631188) (xy 68.702593 -406.646543)
			(xy 68.752178 -406.669186) (xy 68.798037 -406.698655) (xy 68.839234 -406.73435) (xy 68.874932 -406.775546)
			(xy 68.904404 -406.821402) (xy 68.927049 -406.870987) (xy 68.942407 -406.923289) (xy 68.950165 -406.977245)
			(xy 68.950165 -407.031752) (xy 70.387675 -407.031752) (xy 70.387675 -406.977248) (xy 70.395432 -406.923298)
			(xy 70.410789 -406.871002) (xy 70.433431 -406.821423) (xy 70.462899 -406.775571) (xy 70.498593 -406.73438)
			(xy 70.539786 -406.698688) (xy 70.585639 -406.669222) (xy 70.635218 -406.646582) (xy 70.687516 -406.631229)
			(xy 70.741466 -406.623474) (xy 70.768718 -406.623012) (xy 71.632318 -406.623012) (xy 71.65957 -406.623459)
			(xy 71.713518 -406.631218) (xy 71.765814 -406.646576) (xy 71.815391 -406.669219) (xy 71.861242 -406.698687)
			(xy 71.902432 -406.734381) (xy 71.938124 -406.775573) (xy 71.96759 -406.821424) (xy 71.990231 -406.871003)
			(xy 72.005586 -406.923299) (xy 72.013342 -406.977248) (xy 72.013342 -407.031748) (xy 73.450998 -407.031748)
			(xy 73.450998 -406.977252) (xy 73.458753 -406.923311) (xy 73.474105 -406.871022) (xy 73.496742 -406.821451)
			(xy 73.526203 -406.775605) (xy 73.561888 -406.734418) (xy 73.603071 -406.698728) (xy 73.648914 -406.669262)
			(xy 73.698483 -406.64662) (xy 73.75077 -406.631262) (xy 73.80471 -406.623501) (xy 73.831958 -406.623012)
			(xy 74.695558 -406.623012) (xy 74.722814 -406.623432) (xy 74.776773 -406.631185) (xy 74.829078 -406.646538)
			(xy 74.878666 -406.669179) (xy 74.924527 -406.698648) (xy 74.965727 -406.734343) (xy 75.001427 -406.775539)
			(xy 75.030901 -406.821397) (xy 75.053548 -406.870982) (xy 75.068907 -406.923286) (xy 75.076665 -406.977244)
			(xy 75.076665 -407.03175) (xy 76.514198 -407.03175) (xy 76.514198 -406.97725) (xy 76.521954 -406.923306)
			(xy 76.537308 -406.871014) (xy 76.559948 -406.821439) (xy 76.589413 -406.775592) (xy 76.625102 -406.734404)
			(xy 76.66629 -406.698714) (xy 76.712138 -406.669249) (xy 76.761712 -406.646609) (xy 76.814004 -406.631255)
			(xy 76.867948 -406.623498) (xy 76.895198 -406.623012) (xy 77.758798 -406.623012) (xy 77.786052 -406.623435)
			(xy 77.840006 -406.631192) (xy 77.892307 -406.646549) (xy 77.94189 -406.669192) (xy 77.987746 -406.698662)
			(xy 78.028941 -406.734357) (xy 78.064637 -406.775552) (xy 78.094107 -406.821408) (xy 78.116751 -406.870991)
			(xy 78.132108 -406.923292) (xy 78.139865 -406.977246) (xy 78.139865 -407.031753) (xy 79.577375 -407.031753)
			(xy 79.577375 -406.977247) (xy 79.585133 -406.923295) (xy 79.60049 -406.870997) (xy 79.623134 -406.821417)
			(xy 79.652604 -406.775565) (xy 79.6883 -406.734373) (xy 79.729495 -406.698681) (xy 79.775351 -406.669216)
			(xy 79.824933 -406.646577) (xy 79.877233 -406.631225) (xy 79.931185 -406.623473) (xy 79.958438 -406.623012)
			(xy 80.822038 -406.623012) (xy 80.849289 -406.62346) (xy 80.903235 -406.631222) (xy 80.955528 -406.646581)
			(xy 81.005103 -406.669225) (xy 81.050951 -406.698694) (xy 81.092139 -406.734388) (xy 81.127828 -406.775579)
			(xy 81.157293 -406.82143) (xy 81.179932 -406.871007) (xy 81.195286 -406.923302) (xy 81.203042 -406.977249)
			(xy 81.203042 -407.031749) (xy 82.640698 -407.031749) (xy 82.640698 -406.977251) (xy 82.648454 -406.923308)
			(xy 82.663807 -406.871018) (xy 82.686445 -406.821445) (xy 82.715908 -406.775598) (xy 82.751595 -406.734411)
			(xy 82.79278 -406.698721) (xy 82.838626 -406.669256) (xy 82.888197 -406.646615) (xy 82.940487 -406.631258)
			(xy 82.994429 -406.6235) (xy 83.021678 -406.623012) (xy 83.885278 -406.623012) (xy 83.912533 -406.623433)
			(xy 83.96649 -406.631188) (xy 84.018793 -406.646543) (xy 84.068378 -406.669186) (xy 84.114237 -406.698655)
			(xy 84.155434 -406.73435) (xy 84.191132 -406.775546) (xy 84.220604 -406.821402) (xy 84.243249 -406.870987)
			(xy 84.258607 -406.923289) (xy 84.266365 -406.977245) (xy 84.266365 -407.031752) (xy 85.703875 -407.031752)
			(xy 85.703875 -406.977248) (xy 85.711632 -406.923298) (xy 85.726989 -406.871002) (xy 85.749631 -406.821423)
			(xy 85.779099 -406.775571) (xy 85.814793 -406.73438) (xy 85.855986 -406.698688) (xy 85.901839 -406.669222)
			(xy 85.951418 -406.646582) (xy 86.003716 -406.631229) (xy 86.057666 -406.623474) (xy 86.084918 -406.623012)
			(xy 86.948518 -406.623012) (xy 86.97577 -406.623459) (xy 87.029718 -406.631218) (xy 87.082014 -406.646576)
			(xy 87.131591 -406.669219) (xy 87.177442 -406.698687) (xy 87.218632 -406.734381) (xy 87.254324 -406.775573)
			(xy 87.28379 -406.821424) (xy 87.306431 -406.871003) (xy 87.321786 -406.923299) (xy 87.329542 -406.977248)
			(xy 87.329542 -407.031748) (xy 88.767198 -407.031748) (xy 88.767198 -406.977252) (xy 88.774953 -406.923311)
			(xy 88.790305 -406.871022) (xy 88.812942 -406.821451) (xy 88.842403 -406.775605) (xy 88.878088 -406.734418)
			(xy 88.919271 -406.698728) (xy 88.965114 -406.669262) (xy 89.014683 -406.64662) (xy 89.06697 -406.631262)
			(xy 89.12091 -406.623501) (xy 89.148158 -406.623012) (xy 90.011758 -406.623012) (xy 90.039014 -406.623432)
			(xy 90.092973 -406.631185) (xy 90.145278 -406.646538) (xy 90.194866 -406.669179) (xy 90.240727 -406.698648)
			(xy 90.281927 -406.734343) (xy 90.317627 -406.775539) (xy 90.347101 -406.821397) (xy 90.369748 -406.870982)
			(xy 90.385107 -406.923286) (xy 90.392865 -406.977244) (xy 90.392865 -407.03175) (xy 91.830398 -407.03175)
			(xy 91.830398 -406.97725) (xy 91.838154 -406.923306) (xy 91.853508 -406.871014) (xy 91.876148 -406.821439)
			(xy 91.905613 -406.775592) (xy 91.941302 -406.734404) (xy 91.98249 -406.698714) (xy 92.028338 -406.669249)
			(xy 92.077912 -406.646609) (xy 92.130204 -406.631255) (xy 92.184148 -406.623498) (xy 92.211398 -406.623012)
			(xy 93.074998 -406.623012) (xy 93.102252 -406.623435) (xy 93.156206 -406.631192) (xy 93.208507 -406.646549)
			(xy 93.25809 -406.669192) (xy 93.303946 -406.698662) (xy 93.345141 -406.734357) (xy 93.380837 -406.775552)
			(xy 93.410307 -406.821408) (xy 93.432951 -406.870991) (xy 93.448308 -406.923292) (xy 93.456065 -406.977246)
			(xy 93.456065 -407.031753) (xy 94.893575 -407.031753) (xy 94.893575 -406.977247) (xy 94.901333 -406.923295)
			(xy 94.91669 -406.870997) (xy 94.939334 -406.821417) (xy 94.968804 -406.775565) (xy 95.0045 -406.734373)
			(xy 95.045695 -406.698681) (xy 95.091551 -406.669216) (xy 95.141133 -406.646577) (xy 95.193433 -406.631225)
			(xy 95.247385 -406.623473) (xy 95.274638 -406.623012) (xy 96.138238 -406.623012) (xy 96.165489 -406.62346)
			(xy 96.219435 -406.631222) (xy 96.271728 -406.646581) (xy 96.321303 -406.669225) (xy 96.367151 -406.698694)
			(xy 96.408339 -406.734388) (xy 96.444028 -406.775579) (xy 96.473493 -406.82143) (xy 96.496132 -406.871007)
			(xy 96.511486 -406.923302) (xy 96.519242 -406.977249) (xy 96.519242 -407.031751) (xy 96.511486 -407.085698)
			(xy 96.496132 -407.137993) (xy 96.495694 -407.138953) (xy 106.243063 -407.138953) (xy 106.243063 -407.084447)
			(xy 106.250821 -407.030495) (xy 106.266177 -406.978197) (xy 106.288821 -406.928617) (xy 106.31829 -406.882763)
			(xy 106.353985 -406.841571) (xy 106.395179 -406.805878) (xy 106.441034 -406.776411) (xy 106.490616 -406.75377)
			(xy 106.542915 -406.738416) (xy 106.596867 -406.730662) (xy 106.62412 -406.7302) (xy 107.48772 -406.7302)
			(xy 107.514971 -406.730671) (xy 107.568918 -406.73843) (xy 107.621211 -406.753787) (xy 107.670787 -406.77643)
			(xy 107.716636 -406.805898) (xy 107.757824 -406.84159) (xy 107.793514 -406.88278) (xy 107.82298 -406.928631)
			(xy 107.84562 -406.978208) (xy 107.860974 -407.030502) (xy 107.861153 -407.031748) (xy 121.120198 -407.031748)
			(xy 121.120198 -406.977252) (xy 121.127953 -406.923312) (xy 121.143305 -406.871023) (xy 121.165942 -406.821452)
			(xy 121.195402 -406.775606) (xy 121.231087 -406.734419) (xy 121.272269 -406.69873) (xy 121.318111 -406.669264)
			(xy 121.36768 -406.646621) (xy 121.419967 -406.631263) (xy 121.473906 -406.623501) (xy 121.501154 -406.623012)
			(xy 122.364754 -406.623012) (xy 122.39201 -406.623432) (xy 122.445969 -406.631184) (xy 122.498275 -406.646537)
			(xy 122.547864 -406.669178) (xy 122.593725 -406.698646) (xy 122.634926 -406.734342) (xy 122.670626 -406.775538)
			(xy 122.7001 -406.821396) (xy 122.722747 -406.870981) (xy 122.738106 -406.923286) (xy 122.745865 -406.977244)
			(xy 122.745865 -407.03175) (xy 124.183398 -407.03175) (xy 124.183398 -406.97725) (xy 124.191154 -406.923306)
			(xy 124.206508 -406.871015) (xy 124.229148 -406.821441) (xy 124.258612 -406.775593) (xy 124.294301 -406.734405)
			(xy 124.335488 -406.698715) (xy 124.381335 -406.669251) (xy 124.430909 -406.64661) (xy 124.4832 -406.631255)
			(xy 124.537144 -406.623499) (xy 124.564394 -406.623012) (xy 125.427994 -406.623012) (xy 125.455249 -406.623434)
			(xy 125.509203 -406.631191) (xy 125.561504 -406.646548) (xy 125.611088 -406.669191) (xy 125.656944 -406.69866)
			(xy 125.69814 -406.734356) (xy 125.733836 -406.775551) (xy 125.763306 -406.821407) (xy 125.78595 -406.87099)
			(xy 125.801308 -406.923291) (xy 125.809065 -406.977245) (xy 125.809065 -407.031753) (xy 127.246575 -407.031753)
			(xy 127.246575 -406.977247) (xy 127.254333 -406.923296) (xy 127.26969 -406.870998) (xy 127.292334 -406.821418)
			(xy 127.321803 -406.775566) (xy 127.357499 -406.734375) (xy 127.398693 -406.698683) (xy 127.444548 -406.669217)
			(xy 127.49413 -406.646578) (xy 127.546429 -406.631226) (xy 127.600381 -406.623473) (xy 127.627634 -406.623012)
			(xy 128.491234 -406.623012) (xy 128.518485 -406.62346) (xy 128.572432 -406.631221) (xy 128.624725 -406.64658)
			(xy 128.674301 -406.669224) (xy 128.720149 -406.698693) (xy 128.761338 -406.734386) (xy 128.797028 -406.775578)
			(xy 128.826492 -406.821429) (xy 128.849132 -406.871007) (xy 128.864486 -406.923301) (xy 128.872242 -406.977249)
			(xy 128.872242 -407.031749) (xy 130.309898 -407.031749) (xy 130.309898 -406.977251) (xy 130.317654 -406.923309)
			(xy 130.333007 -406.871019) (xy 130.355645 -406.821446) (xy 130.385107 -406.775599) (xy 130.420794 -406.734412)
			(xy 130.461979 -406.698722) (xy 130.507823 -406.669257) (xy 130.557395 -406.646616) (xy 130.609683 -406.631259)
			(xy 130.663625 -406.6235) (xy 130.690874 -406.623012) (xy 131.554474 -406.623012) (xy 131.58173 -406.623433)
			(xy 131.635686 -406.631187) (xy 131.68799 -406.646542) (xy 131.737576 -406.669184) (xy 131.783435 -406.698653)
			(xy 131.824633 -406.734349) (xy 131.860331 -406.775544) (xy 131.889803 -406.821401) (xy 131.912449 -406.870986)
			(xy 131.927807 -406.923288) (xy 131.935565 -406.977245) (xy 131.935565 -407.031752) (xy 133.373075 -407.031752)
			(xy 133.373075 -406.977248) (xy 133.380832 -406.923299) (xy 133.396188 -406.871002) (xy 133.418831 -406.821424)
			(xy 133.448298 -406.775573) (xy 133.483992 -406.734382) (xy 133.525184 -406.69869) (xy 133.571036 -406.669224)
			(xy 133.620616 -406.646583) (xy 133.672912 -406.631229) (xy 133.726862 -406.623474) (xy 133.754114 -406.623012)
			(xy 134.617714 -406.623012) (xy 134.644966 -406.623459) (xy 134.698915 -406.631217) (xy 134.751211 -406.646574)
			(xy 134.800789 -406.669218) (xy 134.84664 -406.698686) (xy 134.887831 -406.734379) (xy 134.923523 -406.775571)
			(xy 134.952989 -406.821423) (xy 134.97563 -406.871002) (xy 134.990986 -406.923299) (xy 134.998742 -406.977248)
			(xy 134.998742 -407.031748) (xy 136.436398 -407.031748) (xy 136.436398 -406.977252) (xy 136.444153 -406.923312)
			(xy 136.459505 -406.871023) (xy 136.482142 -406.821452) (xy 136.511602 -406.775606) (xy 136.547287 -406.734419)
			(xy 136.588469 -406.69873) (xy 136.634311 -406.669264) (xy 136.68388 -406.646621) (xy 136.736167 -406.631263)
			(xy 136.790106 -406.623501) (xy 136.817354 -406.623012) (xy 137.680954 -406.623012) (xy 137.70821 -406.623432)
			(xy 137.762169 -406.631184) (xy 137.814475 -406.646537) (xy 137.864064 -406.669178) (xy 137.909925 -406.698646)
			(xy 137.951126 -406.734342) (xy 137.986826 -406.775538) (xy 138.0163 -406.821396) (xy 138.038947 -406.870981)
			(xy 138.054306 -406.923286) (xy 138.062065 -406.977244) (xy 138.062065 -407.03175) (xy 139.499598 -407.03175)
			(xy 139.499598 -406.97725) (xy 139.507354 -406.923306) (xy 139.522708 -406.871015) (xy 139.545348 -406.821441)
			(xy 139.574812 -406.775593) (xy 139.610501 -406.734405) (xy 139.651688 -406.698715) (xy 139.697535 -406.669251)
			(xy 139.747109 -406.64661) (xy 139.7994 -406.631255) (xy 139.853344 -406.623499) (xy 139.880594 -406.623012)
			(xy 140.744194 -406.623012) (xy 140.771449 -406.623434) (xy 140.825403 -406.631191) (xy 140.877704 -406.646548)
			(xy 140.927288 -406.669191) (xy 140.973144 -406.69866) (xy 141.01434 -406.734356) (xy 141.050036 -406.775551)
			(xy 141.079506 -406.821407) (xy 141.10215 -406.87099) (xy 141.117508 -406.923291) (xy 141.125265 -406.977245)
			(xy 141.125265 -407.031753) (xy 142.562775 -407.031753) (xy 142.562775 -406.977247) (xy 142.570533 -406.923296)
			(xy 142.58589 -406.870998) (xy 142.608534 -406.821418) (xy 142.638003 -406.775566) (xy 142.673699 -406.734375)
			(xy 142.714893 -406.698683) (xy 142.760748 -406.669217) (xy 142.81033 -406.646578) (xy 142.862629 -406.631226)
			(xy 142.916581 -406.623473) (xy 142.943834 -406.623012) (xy 143.807434 -406.623012) (xy 143.834685 -406.62346)
			(xy 143.888632 -406.631221) (xy 143.940925 -406.64658) (xy 143.990501 -406.669224) (xy 144.036349 -406.698693)
			(xy 144.077538 -406.734386) (xy 144.113228 -406.775578) (xy 144.142692 -406.821429) (xy 144.165332 -406.871007)
			(xy 144.180686 -406.923301) (xy 144.188442 -406.977249) (xy 144.188442 -407.031749) (xy 145.626098 -407.031749)
			(xy 145.626098 -406.977251) (xy 145.633854 -406.923309) (xy 145.649207 -406.871019) (xy 145.671845 -406.821446)
			(xy 145.701307 -406.775599) (xy 145.736994 -406.734412) (xy 145.778179 -406.698722) (xy 145.824023 -406.669257)
			(xy 145.873595 -406.646616) (xy 145.925883 -406.631259) (xy 145.979825 -406.6235) (xy 146.007074 -406.623012)
			(xy 146.870674 -406.623012) (xy 146.89793 -406.623433) (xy 146.951886 -406.631187) (xy 147.00419 -406.646542)
			(xy 147.053776 -406.669184) (xy 147.099635 -406.698653) (xy 147.140833 -406.734349) (xy 147.176531 -406.775544)
			(xy 147.206003 -406.821401) (xy 147.228649 -406.870986) (xy 147.244007 -406.923288) (xy 147.251765 -406.977245)
			(xy 147.251765 -407.031752) (xy 148.689275 -407.031752) (xy 148.689275 -406.977248) (xy 148.697032 -406.923299)
			(xy 148.712388 -406.871002) (xy 148.735031 -406.821424) (xy 148.764498 -406.775573) (xy 148.800192 -406.734382)
			(xy 148.841384 -406.69869) (xy 148.887236 -406.669224) (xy 148.936816 -406.646583) (xy 148.989112 -406.631229)
			(xy 149.043062 -406.623474) (xy 149.070314 -406.623012) (xy 149.933914 -406.623012) (xy 149.961166 -406.623459)
			(xy 150.015115 -406.631217) (xy 150.067411 -406.646574) (xy 150.116989 -406.669218) (xy 150.16284 -406.698686)
			(xy 150.204031 -406.734379) (xy 150.239723 -406.775571) (xy 150.269189 -406.821423) (xy 150.29183 -406.871002)
			(xy 150.307186 -406.923299) (xy 150.314942 -406.977248) (xy 150.314942 -407.031748) (xy 151.752598 -407.031748)
			(xy 151.752598 -406.977252) (xy 151.760353 -406.923312) (xy 151.775705 -406.871023) (xy 151.798342 -406.821452)
			(xy 151.827802 -406.775606) (xy 151.863487 -406.734419) (xy 151.904669 -406.69873) (xy 151.950511 -406.669264)
			(xy 152.00008 -406.646621) (xy 152.052367 -406.631263) (xy 152.106306 -406.623501) (xy 152.133554 -406.623012)
			(xy 152.997154 -406.623012) (xy 153.02441 -406.623432) (xy 153.078369 -406.631184) (xy 153.130675 -406.646537)
			(xy 153.180264 -406.669178) (xy 153.226125 -406.698646) (xy 153.267326 -406.734342) (xy 153.303026 -406.775538)
			(xy 153.3325 -406.821396) (xy 153.355147 -406.870981) (xy 153.370506 -406.923286) (xy 153.378265 -406.977244)
			(xy 153.378265 -407.03175) (xy 154.815798 -407.03175) (xy 154.815798 -406.97725) (xy 154.823554 -406.923306)
			(xy 154.838908 -406.871015) (xy 154.861548 -406.821441) (xy 154.891012 -406.775593) (xy 154.926701 -406.734405)
			(xy 154.967888 -406.698715) (xy 155.013735 -406.669251) (xy 155.063309 -406.64661) (xy 155.1156 -406.631255)
			(xy 155.169544 -406.623499) (xy 155.196794 -406.623012) (xy 156.060394 -406.623012) (xy 156.087649 -406.623434)
			(xy 156.141603 -406.631191) (xy 156.193904 -406.646548) (xy 156.243488 -406.669191) (xy 156.289344 -406.69866)
			(xy 156.33054 -406.734356) (xy 156.366236 -406.775551) (xy 156.395706 -406.821407) (xy 156.41835 -406.87099)
			(xy 156.433708 -406.923291) (xy 156.441465 -406.977245) (xy 156.441465 -407.031753) (xy 157.878975 -407.031753)
			(xy 157.878975 -406.977247) (xy 157.886733 -406.923296) (xy 157.90209 -406.870998) (xy 157.924734 -406.821418)
			(xy 157.954203 -406.775566) (xy 157.989899 -406.734375) (xy 158.031093 -406.698683) (xy 158.076948 -406.669217)
			(xy 158.12653 -406.646578) (xy 158.178829 -406.631226) (xy 158.232781 -406.623473) (xy 158.260034 -406.623012)
			(xy 159.123634 -406.623012) (xy 159.150885 -406.62346) (xy 159.204832 -406.631221) (xy 159.257125 -406.64658)
			(xy 159.306701 -406.669224) (xy 159.352549 -406.698693) (xy 159.393738 -406.734386) (xy 159.429428 -406.775578)
			(xy 159.458892 -406.821429) (xy 159.481532 -406.871007) (xy 159.496886 -406.923301) (xy 159.504642 -406.977249)
			(xy 159.504642 -407.031749) (xy 160.942298 -407.031749) (xy 160.942298 -406.977251) (xy 160.950054 -406.923309)
			(xy 160.965407 -406.871019) (xy 160.988045 -406.821446) (xy 161.017507 -406.775599) (xy 161.053194 -406.734412)
			(xy 161.094379 -406.698722) (xy 161.140223 -406.669257) (xy 161.189795 -406.646616) (xy 161.242083 -406.631259)
			(xy 161.296025 -406.6235) (xy 161.323274 -406.623012) (xy 162.186874 -406.623012) (xy 162.21413 -406.623433)
			(xy 162.268086 -406.631187) (xy 162.32039 -406.646542) (xy 162.369976 -406.669184) (xy 162.415835 -406.698653)
			(xy 162.457033 -406.734349) (xy 162.492731 -406.775544) (xy 162.522203 -406.821401) (xy 162.544849 -406.870986)
			(xy 162.560207 -406.923288) (xy 162.567965 -406.977245) (xy 162.567965 -407.031752) (xy 164.005475 -407.031752)
			(xy 164.005475 -406.977248) (xy 164.013232 -406.923299) (xy 164.028588 -406.871002) (xy 164.051231 -406.821424)
			(xy 164.080698 -406.775573) (xy 164.116392 -406.734382) (xy 164.157584 -406.69869) (xy 164.203436 -406.669224)
			(xy 164.253016 -406.646583) (xy 164.305312 -406.631229) (xy 164.359262 -406.623474) (xy 164.386514 -406.623012)
			(xy 165.250114 -406.623012) (xy 165.277366 -406.623459) (xy 165.331315 -406.631217) (xy 165.383611 -406.646574)
			(xy 165.433189 -406.669218) (xy 165.47904 -406.698686) (xy 165.520231 -406.734379) (xy 165.555923 -406.775571)
			(xy 165.585389 -406.821423) (xy 165.60803 -406.871002) (xy 165.623386 -406.923299) (xy 165.631142 -406.977248)
			(xy 165.631142 -407.031748) (xy 167.068798 -407.031748) (xy 167.068798 -406.977252) (xy 167.076553 -406.923312)
			(xy 167.091905 -406.871023) (xy 167.114542 -406.821452) (xy 167.144002 -406.775606) (xy 167.179687 -406.734419)
			(xy 167.220869 -406.69873) (xy 167.266711 -406.669264) (xy 167.31628 -406.646621) (xy 167.368567 -406.631263)
			(xy 167.422506 -406.623501) (xy 167.449754 -406.623012) (xy 168.313354 -406.623012) (xy 168.34061 -406.623432)
			(xy 168.394569 -406.631184) (xy 168.446875 -406.646537) (xy 168.496464 -406.669178) (xy 168.542325 -406.698646)
			(xy 168.583526 -406.734342) (xy 168.619226 -406.775538) (xy 168.6487 -406.821396) (xy 168.671347 -406.870981)
			(xy 168.686706 -406.923286) (xy 168.694465 -406.977244) (xy 168.694465 -407.031756) (xy 168.686706 -407.085714)
			(xy 168.671347 -407.138019) (xy 168.6487 -407.187604) (xy 168.619226 -407.233462) (xy 168.583526 -407.274658)
			(xy 168.542325 -407.310354) (xy 168.496464 -407.339822) (xy 168.446875 -407.362463) (xy 168.394569 -407.377816)
			(xy 168.34061 -407.385568) (xy 168.313354 -407.386028) (xy 167.449754 -407.386028) (xy 167.422506 -407.385499)
			(xy 167.368567 -407.377737) (xy 167.31628 -407.362379) (xy 167.266711 -407.339736) (xy 167.220869 -407.31027)
			(xy 167.179687 -407.274581) (xy 167.144002 -407.233394) (xy 167.114542 -407.187548) (xy 167.091905 -407.137977)
			(xy 167.076553 -407.085688) (xy 167.068798 -407.031748) (xy 165.631142 -407.031748) (xy 165.631142 -407.031752)
			(xy 165.623386 -407.085701) (xy 165.60803 -407.137998) (xy 165.585389 -407.187577) (xy 165.555923 -407.233429)
			(xy 165.520231 -407.274621) (xy 165.47904 -407.310314) (xy 165.433189 -407.339782) (xy 165.383611 -407.362426)
			(xy 165.331315 -407.377783) (xy 165.277366 -407.385541) (xy 165.250114 -407.386028) (xy 164.386514 -407.386028)
			(xy 164.359262 -407.385526) (xy 164.305312 -407.377771) (xy 164.253016 -407.362417) (xy 164.203436 -407.339776)
			(xy 164.157584 -407.31031) (xy 164.116392 -407.274618) (xy 164.080698 -407.233427) (xy 164.051231 -407.187576)
			(xy 164.028588 -407.137998) (xy 164.013232 -407.085701) (xy 164.005475 -407.031752) (xy 162.567965 -407.031752)
			(xy 162.567965 -407.031755) (xy 162.560207 -407.085712) (xy 162.544849 -407.138014) (xy 162.522203 -407.187599)
			(xy 162.492731 -407.233456) (xy 162.457033 -407.274651) (xy 162.415835 -407.310347) (xy 162.369976 -407.339816)
			(xy 162.32039 -407.362458) (xy 162.268086 -407.377813) (xy 162.21413 -407.385567) (xy 162.186874 -407.386028)
			(xy 161.323274 -407.386028) (xy 161.296025 -407.3855) (xy 161.242083 -407.377741) (xy 161.189795 -407.362384)
			(xy 161.140223 -407.339743) (xy 161.094379 -407.310278) (xy 161.053194 -407.274588) (xy 161.017507 -407.233401)
			(xy 160.988045 -407.187554) (xy 160.965407 -407.137981) (xy 160.950054 -407.085691) (xy 160.942298 -407.031749)
			(xy 159.504642 -407.031749) (xy 159.504642 -407.031751) (xy 159.496886 -407.085699) (xy 159.481532 -407.137993)
			(xy 159.458892 -407.187571) (xy 159.429428 -407.233422) (xy 159.393738 -407.274614) (xy 159.352549 -407.310307)
			(xy 159.306701 -407.339776) (xy 159.257125 -407.36242) (xy 159.204832 -407.377779) (xy 159.150885 -407.38554)
			(xy 159.123634 -407.386028) (xy 158.260034 -407.386028) (xy 158.232781 -407.385527) (xy 158.178829 -407.377774)
			(xy 158.12653 -407.362422) (xy 158.076948 -407.339783) (xy 158.031093 -407.310317) (xy 157.989899 -407.274625)
			(xy 157.954203 -407.233434) (xy 157.924734 -407.187582) (xy 157.90209 -407.138002) (xy 157.886733 -407.085704)
			(xy 157.878975 -407.031753) (xy 156.441465 -407.031753) (xy 156.441465 -407.031755) (xy 156.433708 -407.085709)
			(xy 156.41835 -407.13801) (xy 156.395706 -407.187593) (xy 156.366236 -407.233449) (xy 156.33054 -407.274644)
			(xy 156.289344 -407.31034) (xy 156.243488 -407.339809) (xy 156.193904 -407.362452) (xy 156.141603 -407.377809)
			(xy 156.087649 -407.385566) (xy 156.060394 -407.386028) (xy 155.196794 -407.386028) (xy 155.169544 -407.385501)
			(xy 155.1156 -407.377745) (xy 155.063309 -407.36239) (xy 155.013735 -407.339749) (xy 154.967888 -407.310285)
			(xy 154.926701 -407.274595) (xy 154.891012 -407.233407) (xy 154.861548 -407.187559) (xy 154.838908 -407.137985)
			(xy 154.823554 -407.085694) (xy 154.815798 -407.03175) (xy 153.378265 -407.03175) (xy 153.378265 -407.031756)
			(xy 153.370506 -407.085714) (xy 153.355147 -407.138019) (xy 153.3325 -407.187604) (xy 153.303026 -407.233462)
			(xy 153.267326 -407.274658) (xy 153.226125 -407.310354) (xy 153.180264 -407.339822) (xy 153.130675 -407.362463)
			(xy 153.078369 -407.377816) (xy 153.02441 -407.385568) (xy 152.997154 -407.386028) (xy 152.133554 -407.386028)
			(xy 152.106306 -407.385499) (xy 152.052367 -407.377737) (xy 152.00008 -407.362379) (xy 151.950511 -407.339736)
			(xy 151.904669 -407.31027) (xy 151.863487 -407.274581) (xy 151.827802 -407.233394) (xy 151.798342 -407.187548)
			(xy 151.775705 -407.137977) (xy 151.760353 -407.085688) (xy 151.752598 -407.031748) (xy 150.314942 -407.031748)
			(xy 150.314942 -407.031752) (xy 150.307186 -407.085701) (xy 150.29183 -407.137998) (xy 150.269189 -407.187577)
			(xy 150.239723 -407.233429) (xy 150.204031 -407.274621) (xy 150.16284 -407.310314) (xy 150.116989 -407.339782)
			(xy 150.067411 -407.362426) (xy 150.015115 -407.377783) (xy 149.961166 -407.385541) (xy 149.933914 -407.386028)
			(xy 149.070314 -407.386028) (xy 149.043062 -407.385526) (xy 148.989112 -407.377771) (xy 148.936816 -407.362417)
			(xy 148.887236 -407.339776) (xy 148.841384 -407.31031) (xy 148.800192 -407.274618) (xy 148.764498 -407.233427)
			(xy 148.735031 -407.187576) (xy 148.712388 -407.137998) (xy 148.697032 -407.085701) (xy 148.689275 -407.031752)
			(xy 147.251765 -407.031752) (xy 147.251765 -407.031755) (xy 147.244007 -407.085712) (xy 147.228649 -407.138014)
			(xy 147.206003 -407.187599) (xy 147.176531 -407.233456) (xy 147.140833 -407.274651) (xy 147.099635 -407.310347)
			(xy 147.053776 -407.339816) (xy 147.00419 -407.362458) (xy 146.951886 -407.377813) (xy 146.89793 -407.385567)
			(xy 146.870674 -407.386028) (xy 146.007074 -407.386028) (xy 145.979825 -407.3855) (xy 145.925883 -407.377741)
			(xy 145.873595 -407.362384) (xy 145.824023 -407.339743) (xy 145.778179 -407.310278) (xy 145.736994 -407.274588)
			(xy 145.701307 -407.233401) (xy 145.671845 -407.187554) (xy 145.649207 -407.137981) (xy 145.633854 -407.085691)
			(xy 145.626098 -407.031749) (xy 144.188442 -407.031749) (xy 144.188442 -407.031751) (xy 144.180686 -407.085699)
			(xy 144.165332 -407.137993) (xy 144.142692 -407.187571) (xy 144.113228 -407.233422) (xy 144.077538 -407.274614)
			(xy 144.036349 -407.310307) (xy 143.990501 -407.339776) (xy 143.940925 -407.36242) (xy 143.888632 -407.377779)
			(xy 143.834685 -407.38554) (xy 143.807434 -407.386028) (xy 142.943834 -407.386028) (xy 142.916581 -407.385527)
			(xy 142.862629 -407.377774) (xy 142.81033 -407.362422) (xy 142.760748 -407.339783) (xy 142.714893 -407.310317)
			(xy 142.673699 -407.274625) (xy 142.638003 -407.233434) (xy 142.608534 -407.187582) (xy 142.58589 -407.138002)
			(xy 142.570533 -407.085704) (xy 142.562775 -407.031753) (xy 141.125265 -407.031753) (xy 141.125265 -407.031755)
			(xy 141.117508 -407.085709) (xy 141.10215 -407.13801) (xy 141.079506 -407.187593) (xy 141.050036 -407.233449)
			(xy 141.01434 -407.274644) (xy 140.973144 -407.31034) (xy 140.927288 -407.339809) (xy 140.877704 -407.362452)
			(xy 140.825403 -407.377809) (xy 140.771449 -407.385566) (xy 140.744194 -407.386028) (xy 139.880594 -407.386028)
			(xy 139.853344 -407.385501) (xy 139.7994 -407.377745) (xy 139.747109 -407.36239) (xy 139.697535 -407.339749)
			(xy 139.651688 -407.310285) (xy 139.610501 -407.274595) (xy 139.574812 -407.233407) (xy 139.545348 -407.187559)
			(xy 139.522708 -407.137985) (xy 139.507354 -407.085694) (xy 139.499598 -407.03175) (xy 138.062065 -407.03175)
			(xy 138.062065 -407.031756) (xy 138.054306 -407.085714) (xy 138.038947 -407.138019) (xy 138.0163 -407.187604)
			(xy 137.986826 -407.233462) (xy 137.951126 -407.274658) (xy 137.909925 -407.310354) (xy 137.864064 -407.339822)
			(xy 137.814475 -407.362463) (xy 137.762169 -407.377816) (xy 137.70821 -407.385568) (xy 137.680954 -407.386028)
			(xy 136.817354 -407.386028) (xy 136.790106 -407.385499) (xy 136.736167 -407.377737) (xy 136.68388 -407.362379)
			(xy 136.634311 -407.339736) (xy 136.588469 -407.31027) (xy 136.547287 -407.274581) (xy 136.511602 -407.233394)
			(xy 136.482142 -407.187548) (xy 136.459505 -407.137977) (xy 136.444153 -407.085688) (xy 136.436398 -407.031748)
			(xy 134.998742 -407.031748) (xy 134.998742 -407.031752) (xy 134.990986 -407.085701) (xy 134.97563 -407.137998)
			(xy 134.952989 -407.187577) (xy 134.923523 -407.233429) (xy 134.887831 -407.274621) (xy 134.84664 -407.310314)
			(xy 134.800789 -407.339782) (xy 134.751211 -407.362426) (xy 134.698915 -407.377783) (xy 134.644966 -407.385541)
			(xy 134.617714 -407.386028) (xy 133.754114 -407.386028) (xy 133.726862 -407.385526) (xy 133.672912 -407.377771)
			(xy 133.620616 -407.362417) (xy 133.571036 -407.339776) (xy 133.525184 -407.31031) (xy 133.483992 -407.274618)
			(xy 133.448298 -407.233427) (xy 133.418831 -407.187576) (xy 133.396188 -407.137998) (xy 133.380832 -407.085701)
			(xy 133.373075 -407.031752) (xy 131.935565 -407.031752) (xy 131.935565 -407.031755) (xy 131.927807 -407.085712)
			(xy 131.912449 -407.138014) (xy 131.889803 -407.187599) (xy 131.860331 -407.233456) (xy 131.824633 -407.274651)
			(xy 131.783435 -407.310347) (xy 131.737576 -407.339816) (xy 131.68799 -407.362458) (xy 131.635686 -407.377813)
			(xy 131.58173 -407.385567) (xy 131.554474 -407.386028) (xy 130.690874 -407.386028) (xy 130.663625 -407.3855)
			(xy 130.609683 -407.377741) (xy 130.557395 -407.362384) (xy 130.507823 -407.339743) (xy 130.461979 -407.310278)
			(xy 130.420794 -407.274588) (xy 130.385107 -407.233401) (xy 130.355645 -407.187554) (xy 130.333007 -407.137981)
			(xy 130.317654 -407.085691) (xy 130.309898 -407.031749) (xy 128.872242 -407.031749) (xy 128.872242 -407.031751)
			(xy 128.864486 -407.085699) (xy 128.849132 -407.137993) (xy 128.826492 -407.187571) (xy 128.797028 -407.233422)
			(xy 128.761338 -407.274614) (xy 128.720149 -407.310307) (xy 128.674301 -407.339776) (xy 128.624725 -407.36242)
			(xy 128.572432 -407.377779) (xy 128.518485 -407.38554) (xy 128.491234 -407.386028) (xy 127.627634 -407.386028)
			(xy 127.600381 -407.385527) (xy 127.546429 -407.377774) (xy 127.49413 -407.362422) (xy 127.444548 -407.339783)
			(xy 127.398693 -407.310317) (xy 127.357499 -407.274625) (xy 127.321803 -407.233434) (xy 127.292334 -407.187582)
			(xy 127.26969 -407.138002) (xy 127.254333 -407.085704) (xy 127.246575 -407.031753) (xy 125.809065 -407.031753)
			(xy 125.809065 -407.031755) (xy 125.801308 -407.085709) (xy 125.78595 -407.13801) (xy 125.763306 -407.187593)
			(xy 125.733836 -407.233449) (xy 125.69814 -407.274644) (xy 125.656944 -407.31034) (xy 125.611088 -407.339809)
			(xy 125.561504 -407.362452) (xy 125.509203 -407.377809) (xy 125.455249 -407.385566) (xy 125.427994 -407.386028)
			(xy 124.564394 -407.386028) (xy 124.537144 -407.385501) (xy 124.4832 -407.377745) (xy 124.430909 -407.36239)
			(xy 124.381335 -407.339749) (xy 124.335488 -407.310285) (xy 124.294301 -407.274595) (xy 124.258612 -407.233407)
			(xy 124.229148 -407.187559) (xy 124.206508 -407.137985) (xy 124.191154 -407.085694) (xy 124.183398 -407.03175)
			(xy 122.745865 -407.03175) (xy 122.745865 -407.031756) (xy 122.738106 -407.085714) (xy 122.722747 -407.138019)
			(xy 122.7001 -407.187604) (xy 122.670626 -407.233462) (xy 122.634926 -407.274658) (xy 122.593725 -407.310354)
			(xy 122.547864 -407.339822) (xy 122.498275 -407.362463) (xy 122.445969 -407.377816) (xy 122.39201 -407.385568)
			(xy 122.364754 -407.386028) (xy 121.501154 -407.386028) (xy 121.473906 -407.385499) (xy 121.419967 -407.377737)
			(xy 121.36768 -407.362379) (xy 121.318111 -407.339736) (xy 121.272269 -407.31027) (xy 121.231087 -407.274581)
			(xy 121.195402 -407.233394) (xy 121.165942 -407.187548) (xy 121.143305 -407.137977) (xy 121.127953 -407.085688)
			(xy 121.120198 -407.031748) (xy 107.861153 -407.031748) (xy 107.86873 -407.084449) (xy 107.86873 -407.138951)
			(xy 107.860974 -407.192898) (xy 107.84562 -407.245192) (xy 107.822979 -407.294769) (xy 107.793514 -407.34062)
			(xy 107.757824 -407.38181) (xy 107.716636 -407.417502) (xy 107.670787 -407.44697) (xy 107.621211 -407.469613)
			(xy 107.568918 -407.48497) (xy 107.514971 -407.492729) (xy 107.48772 -407.493216) (xy 106.62412 -407.493216)
			(xy 106.596867 -407.492738) (xy 106.542915 -407.484984) (xy 106.490616 -407.46963) (xy 106.441034 -407.446989)
			(xy 106.395179 -407.417522) (xy 106.353985 -407.381829) (xy 106.31829 -407.340637) (xy 106.288821 -407.294783)
			(xy 106.266177 -407.245203) (xy 106.250821 -407.192905) (xy 106.243063 -407.138953) (xy 96.495694 -407.138953)
			(xy 96.473493 -407.18757) (xy 96.444028 -407.233421) (xy 96.408339 -407.274612) (xy 96.367151 -407.310306)
			(xy 96.321303 -407.339775) (xy 96.271728 -407.362419) (xy 96.219435 -407.377778) (xy 96.165489 -407.38554)
			(xy 96.138238 -407.386028) (xy 95.274638 -407.386028) (xy 95.247385 -407.385527) (xy 95.193433 -407.377775)
			(xy 95.141133 -407.362423) (xy 95.091551 -407.339784) (xy 95.045695 -407.310319) (xy 95.0045 -407.274627)
			(xy 94.968804 -407.233435) (xy 94.939334 -407.187583) (xy 94.91669 -407.138003) (xy 94.901333 -407.085705)
			(xy 94.893575 -407.031753) (xy 93.456065 -407.031753) (xy 93.456065 -407.031754) (xy 93.448308 -407.085708)
			(xy 93.432951 -407.138009) (xy 93.410307 -407.187592) (xy 93.380837 -407.233448) (xy 93.345141 -407.274643)
			(xy 93.303946 -407.310338) (xy 93.25809 -407.339808) (xy 93.208507 -407.362451) (xy 93.156206 -407.377808)
			(xy 93.102252 -407.385565) (xy 93.074998 -407.386028) (xy 92.211398 -407.386028) (xy 92.184148 -407.385502)
			(xy 92.130204 -407.377745) (xy 92.077912 -407.362391) (xy 92.028338 -407.339751) (xy 91.98249 -407.310286)
			(xy 91.941302 -407.274596) (xy 91.905613 -407.233408) (xy 91.876148 -407.187561) (xy 91.853508 -407.137986)
			(xy 91.838154 -407.085694) (xy 91.830398 -407.03175) (xy 90.392865 -407.03175) (xy 90.392865 -407.031756)
			(xy 90.385107 -407.085714) (xy 90.369748 -407.138018) (xy 90.347101 -407.187603) (xy 90.317627 -407.233461)
			(xy 90.281927 -407.274657) (xy 90.240727 -407.310352) (xy 90.194866 -407.339821) (xy 90.145278 -407.362462)
			(xy 90.092973 -407.377815) (xy 90.039014 -407.385568) (xy 90.011758 -407.386028) (xy 89.148158 -407.386028)
			(xy 89.12091 -407.385499) (xy 89.06697 -407.377738) (xy 89.014683 -407.36238) (xy 88.965114 -407.339738)
			(xy 88.919271 -407.310272) (xy 88.878088 -407.274582) (xy 88.842403 -407.233395) (xy 88.812942 -407.187549)
			(xy 88.790305 -407.137978) (xy 88.774953 -407.085689) (xy 88.767198 -407.031748) (xy 87.329542 -407.031748)
			(xy 87.329542 -407.031752) (xy 87.321786 -407.085701) (xy 87.306431 -407.137997) (xy 87.28379 -407.187576)
			(xy 87.254324 -407.233427) (xy 87.218632 -407.274619) (xy 87.177442 -407.310313) (xy 87.131591 -407.339781)
			(xy 87.082014 -407.362424) (xy 87.029718 -407.377782) (xy 86.97577 -407.385541) (xy 86.948518 -407.386028)
			(xy 86.084918 -407.386028) (xy 86.057666 -407.385526) (xy 86.003716 -407.377771) (xy 85.951418 -407.362418)
			(xy 85.901839 -407.339778) (xy 85.855986 -407.310312) (xy 85.814793 -407.27462) (xy 85.779099 -407.233429)
			(xy 85.749631 -407.187577) (xy 85.726989 -407.137998) (xy 85.711632 -407.085702) (xy 85.703875 -407.031752)
			(xy 84.266365 -407.031752) (xy 84.266365 -407.031755) (xy 84.258607 -407.085711) (xy 84.243249 -407.138013)
			(xy 84.220604 -407.187598) (xy 84.191132 -407.233454) (xy 84.155434 -407.27465) (xy 84.114237 -407.310345)
			(xy 84.068378 -407.339814) (xy 84.018793 -407.362457) (xy 83.96649 -407.377812) (xy 83.912533 -407.385567)
			(xy 83.885278 -407.386028) (xy 83.021678 -407.386028) (xy 82.994429 -407.3855) (xy 82.940487 -407.377742)
			(xy 82.888197 -407.362385) (xy 82.838626 -407.339744) (xy 82.79278 -407.310279) (xy 82.751595 -407.274589)
			(xy 82.715908 -407.233402) (xy 82.686445 -407.187555) (xy 82.663807 -407.137982) (xy 82.648454 -407.085692)
			(xy 82.640698 -407.031749) (xy 81.203042 -407.031749) (xy 81.203042 -407.031751) (xy 81.195286 -407.085698)
			(xy 81.179932 -407.137993) (xy 81.157293 -407.18757) (xy 81.127828 -407.233421) (xy 81.092139 -407.274612)
			(xy 81.050951 -407.310306) (xy 81.005103 -407.339775) (xy 80.955528 -407.362419) (xy 80.903235 -407.377778)
			(xy 80.849289 -407.38554) (xy 80.822038 -407.386028) (xy 79.958438 -407.386028) (xy 79.931185 -407.385527)
			(xy 79.877233 -407.377775) (xy 79.824933 -407.362423) (xy 79.775351 -407.339784) (xy 79.729495 -407.310319)
			(xy 79.6883 -407.274627) (xy 79.652604 -407.233435) (xy 79.623134 -407.187583) (xy 79.60049 -407.138003)
			(xy 79.585133 -407.085705) (xy 79.577375 -407.031753) (xy 78.139865 -407.031753) (xy 78.139865 -407.031754)
			(xy 78.132108 -407.085708) (xy 78.116751 -407.138009) (xy 78.094107 -407.187592) (xy 78.064637 -407.233448)
			(xy 78.028941 -407.274643) (xy 77.987746 -407.310338) (xy 77.94189 -407.339808) (xy 77.892307 -407.362451)
			(xy 77.840006 -407.377808) (xy 77.786052 -407.385565) (xy 77.758798 -407.386028) (xy 76.895198 -407.386028)
			(xy 76.867948 -407.385502) (xy 76.814004 -407.377745) (xy 76.761712 -407.362391) (xy 76.712138 -407.339751)
			(xy 76.66629 -407.310286) (xy 76.625102 -407.274596) (xy 76.589413 -407.233408) (xy 76.559948 -407.187561)
			(xy 76.537308 -407.137986) (xy 76.521954 -407.085694) (xy 76.514198 -407.03175) (xy 75.076665 -407.03175)
			(xy 75.076665 -407.031756) (xy 75.068907 -407.085714) (xy 75.053548 -407.138018) (xy 75.030901 -407.187603)
			(xy 75.001427 -407.233461) (xy 74.965727 -407.274657) (xy 74.924527 -407.310352) (xy 74.878666 -407.339821)
			(xy 74.829078 -407.362462) (xy 74.776773 -407.377815) (xy 74.722814 -407.385568) (xy 74.695558 -407.386028)
			(xy 73.831958 -407.386028) (xy 73.80471 -407.385499) (xy 73.75077 -407.377738) (xy 73.698483 -407.36238)
			(xy 73.648914 -407.339738) (xy 73.603071 -407.310272) (xy 73.561888 -407.274582) (xy 73.526203 -407.233395)
			(xy 73.496742 -407.187549) (xy 73.474105 -407.137978) (xy 73.458753 -407.085689) (xy 73.450998 -407.031748)
			(xy 72.013342 -407.031748) (xy 72.013342 -407.031752) (xy 72.005586 -407.085701) (xy 71.990231 -407.137997)
			(xy 71.96759 -407.187576) (xy 71.938124 -407.233427) (xy 71.902432 -407.274619) (xy 71.861242 -407.310313)
			(xy 71.815391 -407.339781) (xy 71.765814 -407.362424) (xy 71.713518 -407.377782) (xy 71.65957 -407.385541)
			(xy 71.632318 -407.386028) (xy 70.768718 -407.386028) (xy 70.741466 -407.385526) (xy 70.687516 -407.377771)
			(xy 70.635218 -407.362418) (xy 70.585639 -407.339778) (xy 70.539786 -407.310312) (xy 70.498593 -407.27462)
			(xy 70.462899 -407.233429) (xy 70.433431 -407.187577) (xy 70.410789 -407.137998) (xy 70.395432 -407.085702)
			(xy 70.387675 -407.031752) (xy 68.950165 -407.031752) (xy 68.950165 -407.031755) (xy 68.942407 -407.085711)
			(xy 68.927049 -407.138013) (xy 68.904404 -407.187598) (xy 68.874932 -407.233454) (xy 68.839234 -407.27465)
			(xy 68.798037 -407.310345) (xy 68.752178 -407.339814) (xy 68.702593 -407.362457) (xy 68.65029 -407.377812)
			(xy 68.596333 -407.385567) (xy 68.569078 -407.386028) (xy 67.705478 -407.386028) (xy 67.678229 -407.3855)
			(xy 67.624287 -407.377742) (xy 67.571997 -407.362385) (xy 67.522426 -407.339744) (xy 67.47658 -407.310279)
			(xy 67.435395 -407.274589) (xy 67.399708 -407.233402) (xy 67.370245 -407.187555) (xy 67.347607 -407.137982)
			(xy 67.332254 -407.085692) (xy 67.324498 -407.031749) (xy 65.886842 -407.031749) (xy 65.886842 -407.031751)
			(xy 65.879086 -407.085698) (xy 65.863732 -407.137993) (xy 65.841093 -407.18757) (xy 65.811628 -407.233421)
			(xy 65.775939 -407.274612) (xy 65.734751 -407.310306) (xy 65.688903 -407.339775) (xy 65.639328 -407.362419)
			(xy 65.587035 -407.377778) (xy 65.533089 -407.38554) (xy 65.505838 -407.386028) (xy 64.642238 -407.386028)
			(xy 64.614985 -407.385527) (xy 64.561033 -407.377775) (xy 64.508733 -407.362423) (xy 64.459151 -407.339784)
			(xy 64.413295 -407.310319) (xy 64.3721 -407.274627) (xy 64.336404 -407.233435) (xy 64.306934 -407.187583)
			(xy 64.28429 -407.138003) (xy 64.268933 -407.085705) (xy 64.261175 -407.031753) (xy 62.823665 -407.031753)
			(xy 62.823665 -407.031754) (xy 62.815908 -407.085708) (xy 62.800551 -407.138009) (xy 62.777907 -407.187592)
			(xy 62.748437 -407.233448) (xy 62.712741 -407.274643) (xy 62.671546 -407.310338) (xy 62.62569 -407.339808)
			(xy 62.576107 -407.362451) (xy 62.523806 -407.377808) (xy 62.469852 -407.385565) (xy 62.442598 -407.386028)
			(xy 61.578998 -407.386028) (xy 61.551748 -407.385502) (xy 61.497804 -407.377745) (xy 61.445512 -407.362391)
			(xy 61.395938 -407.339751) (xy 61.35009 -407.310286) (xy 61.308902 -407.274596) (xy 61.273213 -407.233408)
			(xy 61.243748 -407.187561) (xy 61.221108 -407.137986) (xy 61.205754 -407.085694) (xy 61.197998 -407.03175)
			(xy 59.760465 -407.03175) (xy 59.760465 -407.031756) (xy 59.752707 -407.085714) (xy 59.737348 -407.138018)
			(xy 59.714701 -407.187603) (xy 59.685227 -407.233461) (xy 59.649527 -407.274657) (xy 59.608327 -407.310352)
			(xy 59.562466 -407.339821) (xy 59.512878 -407.362462) (xy 59.460573 -407.377815) (xy 59.406614 -407.385568)
			(xy 59.379358 -407.386028) (xy 58.515758 -407.386028) (xy 58.48851 -407.385499) (xy 58.43457 -407.377738)
			(xy 58.382283 -407.36238) (xy 58.332714 -407.339738) (xy 58.286871 -407.310272) (xy 58.245688 -407.274582)
			(xy 58.210003 -407.233395) (xy 58.180542 -407.187549) (xy 58.157905 -407.137978) (xy 58.142553 -407.085689)
			(xy 58.134798 -407.031748) (xy 56.697142 -407.031748) (xy 56.697142 -407.031752) (xy 56.689386 -407.085701)
			(xy 56.674031 -407.137997) (xy 56.65139 -407.187576) (xy 56.621924 -407.233427) (xy 56.586232 -407.274619)
			(xy 56.545042 -407.310313) (xy 56.499191 -407.339781) (xy 56.449614 -407.362424) (xy 56.397318 -407.377782)
			(xy 56.34337 -407.385541) (xy 56.316118 -407.386028) (xy 55.452518 -407.386028) (xy 55.425266 -407.385526)
			(xy 55.371316 -407.377771) (xy 55.319018 -407.362418) (xy 55.269439 -407.339778) (xy 55.223586 -407.310312)
			(xy 55.182393 -407.27462) (xy 55.146699 -407.233429) (xy 55.117231 -407.187577) (xy 55.094589 -407.137998)
			(xy 55.079232 -407.085702) (xy 55.071475 -407.031752) (xy 53.633965 -407.031752) (xy 53.633965 -407.031755)
			(xy 53.626207 -407.085711) (xy 53.610849 -407.138013) (xy 53.588204 -407.187598) (xy 53.558732 -407.233454)
			(xy 53.523034 -407.27465) (xy 53.481837 -407.310345) (xy 53.435978 -407.339814) (xy 53.386393 -407.362457)
			(xy 53.33409 -407.377812) (xy 53.280133 -407.385567) (xy 53.252878 -407.386028) (xy 52.389278 -407.386028)
			(xy 52.362029 -407.3855) (xy 52.308087 -407.377742) (xy 52.255797 -407.362385) (xy 52.206226 -407.339744)
			(xy 52.16038 -407.310279) (xy 52.119195 -407.274589) (xy 52.083508 -407.233402) (xy 52.054045 -407.187555)
			(xy 52.031407 -407.137982) (xy 52.016054 -407.085692) (xy 52.008298 -407.031749) (xy 50.570642 -407.031749)
			(xy 50.570642 -407.031751) (xy 50.562886 -407.085698) (xy 50.547532 -407.137993) (xy 50.524893 -407.18757)
			(xy 50.495428 -407.233421) (xy 50.459739 -407.274612) (xy 50.418551 -407.310306) (xy 50.372703 -407.339775)
			(xy 50.323128 -407.362419) (xy 50.270835 -407.377778) (xy 50.216889 -407.38554) (xy 50.189638 -407.386028)
			(xy 49.326038 -407.386028) (xy 49.298785 -407.385527) (xy 49.244833 -407.377775) (xy 49.192533 -407.362423)
			(xy 49.142951 -407.339784) (xy 49.097095 -407.310319) (xy 49.0559 -407.274627) (xy 49.020204 -407.233435)
			(xy 48.990734 -407.187583) (xy 48.96809 -407.138003) (xy 48.952733 -407.085705) (xy 48.944975 -407.031753)
			(xy 37.118036 -407.031753) (xy 37.118036 -407.233628) (xy 37.1169 -407.247345) (xy 37.108079 -407.273406)
			(xy 37.092455 -407.296052) (xy 37.071224 -407.31355) (xy 37.046011 -407.324562) (xy 37.032438 -407.326846)
			(xy 37.025834 -407.327608) (xy 35.956494 -407.327608) (xy 35.944119 -407.326938) (xy 35.920228 -407.320386)
			(xy 35.89866 -407.308199) (xy 35.889438 -407.299922) (xy 35.880022 -407.290268) (xy 35.866323 -407.267047)
			(xy 35.859309 -407.241015) (xy 35.858958 -407.227532) (xy 34.927509 -407.227532) (xy 34.890847 -407.264194)
			(xy 34.848766 -407.294768) (xy 34.802421 -407.318382) (xy 34.752953 -407.334455) (xy 34.701579 -407.342592)
			(xy 34.649565 -407.342592) (xy 34.598191 -407.334455) (xy 34.548723 -407.318382) (xy 34.502378 -407.294768)
			(xy 34.460297 -407.264194) (xy 34.423518 -407.227415) (xy 34.392944 -407.185334) (xy 34.36933 -407.138989)
			(xy 34.353257 -407.089521) (xy 34.34512 -407.038147) (xy 16.741601 -407.038147) (xy 16.741162 -407.062759)
			(xy 16.733406 -407.116707) (xy 16.718051 -407.169002) (xy 16.695409 -407.218579) (xy 16.665943 -407.264429)
			(xy 16.630252 -407.30562) (xy 16.589061 -407.341311) (xy 16.543211 -407.370777) (xy 16.493634 -407.393419)
			(xy 16.441339 -407.408774) (xy 16.387391 -407.41653) (xy 16.332889 -407.41653) (xy 16.278941 -407.408774)
			(xy 16.226646 -407.393419) (xy 16.177069 -407.370777) (xy 16.131219 -407.341311) (xy 16.090028 -407.30562)
			(xy 16.054337 -407.264429) (xy 16.024871 -407.218579) (xy 16.002229 -407.169002) (xy 15.986874 -407.116707)
			(xy 15.979118 -407.062759) (xy 15.978632 -407.035508) (xy 5.555234 -407.035508) (xy 6.274054 -407.754328)
			(xy 6.323476 -407.804436) (xy 6.417282 -407.909377) (xy 6.505056 -408.019414) (xy 6.586523 -408.134198)
			(xy 6.661426 -408.25337) (xy 6.729529 -408.376554) (xy 6.790618 -408.503362) (xy 6.844501 -408.633397)
			(xy 6.891008 -408.766247) (xy 6.929993 -408.901497) (xy 6.961334 -409.03872) (xy 6.984932 -409.177484)
			(xy 7.000712 -409.317352) (xy 7.008625 -409.457886) (xy 7.00913 -409.528264) (xy 7.00913 -410.057457)
			(xy 48.944923 -410.057457) (xy 48.944923 -410.002943) (xy 48.952682 -409.948984) (xy 48.968041 -409.896679)
			(xy 48.990688 -409.847092) (xy 49.020162 -409.801233) (xy 49.055863 -409.760036) (xy 49.097064 -409.724339)
			(xy 49.142925 -409.69487) (xy 49.192515 -409.672228) (xy 49.244821 -409.656874) (xy 49.298781 -409.64912)
			(xy 49.326038 -409.64866) (xy 50.189638 -409.64866) (xy 50.216885 -409.649213) (xy 50.270824 -409.656973)
			(xy 50.32311 -409.67233) (xy 50.372678 -409.694972) (xy 50.41852 -409.724436) (xy 50.459702 -409.760125)
			(xy 50.495386 -409.801311) (xy 50.524847 -409.847155) (xy 50.547483 -409.896726) (xy 50.562835 -409.949013)
			(xy 50.57059 -410.002953) (xy 50.57059 -410.057447) (xy 50.570589 -410.057453) (xy 52.008246 -410.057453)
			(xy 52.008246 -410.002947) (xy 52.016002 -409.948997) (xy 52.031358 -409.8967) (xy 52.053999 -409.84712)
			(xy 52.083466 -409.801267) (xy 52.119158 -409.760074) (xy 52.160349 -409.724379) (xy 52.206201 -409.69491)
			(xy 52.255779 -409.672265) (xy 52.308076 -409.656907) (xy 52.362025 -409.649147) (xy 52.389278 -409.64866)
			(xy 53.252878 -409.64866) (xy 53.28013 -409.649186) (xy 53.334078 -409.65694) (xy 53.386374 -409.672292)
			(xy 53.435953 -409.694932) (xy 53.481805 -409.724397) (xy 53.522997 -409.760087) (xy 53.55869 -409.801277)
			(xy 53.588158 -409.847127) (xy 53.6108 -409.896705) (xy 53.626156 -409.949) (xy 53.633913 -410.002948)
			(xy 53.633913 -410.057452) (xy 53.633912 -410.057456) (xy 55.071423 -410.057456) (xy 55.071423 -410.002944)
			(xy 55.079181 -409.948987) (xy 55.094539 -409.896683) (xy 55.117185 -409.847098) (xy 55.146657 -409.80124)
			(xy 55.182356 -409.760043) (xy 55.223554 -409.724346) (xy 55.269413 -409.694876) (xy 55.319 -409.672233)
			(xy 55.371305 -409.656877) (xy 55.425262 -409.649122) (xy 55.452518 -409.64866) (xy 56.316118 -409.64866)
			(xy 56.343366 -409.649211) (xy 56.397307 -409.656969) (xy 56.449595 -409.672325) (xy 56.499166 -409.694965)
			(xy 56.54501 -409.724429) (xy 56.586195 -409.760118) (xy 56.621882 -409.801304) (xy 56.651344 -409.84715)
			(xy 56.673982 -409.896721) (xy 56.689334 -409.94901) (xy 56.69709 -410.002952) (xy 56.69709 -410.057448)
			(xy 56.697089 -410.057452) (xy 58.134746 -410.057452) (xy 58.134746 -410.002948) (xy 58.142502 -409.949)
			(xy 58.157856 -409.896704) (xy 58.180496 -409.847125) (xy 58.209961 -409.801273) (xy 58.245651 -409.760081)
			(xy 58.28684 -409.724386) (xy 58.332689 -409.694916) (xy 58.382265 -409.672271) (xy 58.434559 -409.656911)
			(xy 58.488506 -409.649149) (xy 58.515758 -409.64866) (xy 59.379358 -409.64866) (xy 59.406611 -409.649184)
			(xy 59.460561 -409.656936) (xy 59.51286 -409.672287) (xy 59.562441 -409.694925) (xy 59.608296 -409.72439)
			(xy 59.64949 -409.76008) (xy 59.685185 -409.801271) (xy 59.714655 -409.847122) (xy 59.737298 -409.896701)
			(xy 59.752655 -409.948997) (xy 59.760413 -410.002948) (xy 59.760413 -410.057452) (xy 59.760413 -410.057453)
			(xy 61.197946 -410.057453) (xy 61.197946 -410.002947) (xy 61.205703 -409.948994) (xy 61.221059 -409.896695)
			(xy 61.243702 -409.847114) (xy 61.273171 -409.80126) (xy 61.308865 -409.760066) (xy 61.350059 -409.724372)
			(xy 61.395913 -409.694903) (xy 61.445494 -409.67226) (xy 61.497793 -409.656903) (xy 61.551745 -409.649146)
			(xy 61.578998 -409.64866) (xy 62.442598 -409.64866) (xy 62.469849 -409.649187) (xy 62.523795 -409.656943)
			(xy 62.576089 -409.672298) (xy 62.625665 -409.694938) (xy 62.671515 -409.724404) (xy 62.712704 -409.760094)
			(xy 62.748395 -409.801284) (xy 62.777861 -409.847133) (xy 62.800502 -409.896709) (xy 62.815856 -409.949003)
			(xy 62.823613 -410.002949) (xy 62.823613 -410.057451) (xy 62.823612 -410.057457) (xy 64.261123 -410.057457)
			(xy 64.261123 -410.002943) (xy 64.268882 -409.948984) (xy 64.284241 -409.896679) (xy 64.306888 -409.847092)
			(xy 64.336362 -409.801233) (xy 64.372063 -409.760036) (xy 64.413264 -409.724339) (xy 64.459125 -409.69487)
			(xy 64.508715 -409.672228) (xy 64.561021 -409.656874) (xy 64.614981 -409.64912) (xy 64.642238 -409.64866)
			(xy 65.505838 -409.64866) (xy 65.533085 -409.649213) (xy 65.587024 -409.656973) (xy 65.63931 -409.67233)
			(xy 65.688878 -409.694972) (xy 65.73472 -409.724436) (xy 65.775902 -409.760125) (xy 65.811586 -409.801311)
			(xy 65.841047 -409.847155) (xy 65.863683 -409.896726) (xy 65.879035 -409.949013) (xy 65.88679 -410.002953)
			(xy 65.88679 -410.057447) (xy 65.886789 -410.057453) (xy 67.324446 -410.057453) (xy 67.324446 -410.002947)
			(xy 67.332202 -409.948997) (xy 67.347558 -409.8967) (xy 67.370199 -409.84712) (xy 67.399666 -409.801267)
			(xy 67.435358 -409.760074) (xy 67.476549 -409.724379) (xy 67.522401 -409.69491) (xy 67.571979 -409.672265)
			(xy 67.624276 -409.656907) (xy 67.678225 -409.649147) (xy 67.705478 -409.64866) (xy 68.569078 -409.64866)
			(xy 68.59633 -409.649186) (xy 68.650278 -409.65694) (xy 68.702574 -409.672292) (xy 68.752153 -409.694932)
			(xy 68.798005 -409.724397) (xy 68.839197 -409.760087) (xy 68.87489 -409.801277) (xy 68.904358 -409.847127)
			(xy 68.927 -409.896705) (xy 68.942356 -409.949) (xy 68.950113 -410.002948) (xy 68.950113 -410.057452)
			(xy 68.950112 -410.057456) (xy 70.387623 -410.057456) (xy 70.387623 -410.002944) (xy 70.395381 -409.948987)
			(xy 70.410739 -409.896683) (xy 70.433385 -409.847098) (xy 70.462857 -409.80124) (xy 70.498556 -409.760043)
			(xy 70.539754 -409.724346) (xy 70.585613 -409.694876) (xy 70.6352 -409.672233) (xy 70.687505 -409.656877)
			(xy 70.741462 -409.649122) (xy 70.768718 -409.64866) (xy 71.632318 -409.64866) (xy 71.659566 -409.649211)
			(xy 71.713507 -409.656969) (xy 71.765795 -409.672325) (xy 71.815366 -409.694965) (xy 71.86121 -409.724429)
			(xy 71.902395 -409.760118) (xy 71.938082 -409.801304) (xy 71.967544 -409.84715) (xy 71.990182 -409.896721)
			(xy 72.005534 -409.94901) (xy 72.01329 -410.002952) (xy 72.01329 -410.057448) (xy 72.013289 -410.057452)
			(xy 73.450946 -410.057452) (xy 73.450946 -410.002948) (xy 73.458702 -409.949) (xy 73.474056 -409.896704)
			(xy 73.496696 -409.847125) (xy 73.526161 -409.801273) (xy 73.561851 -409.760081) (xy 73.60304 -409.724386)
			(xy 73.648889 -409.694916) (xy 73.698465 -409.672271) (xy 73.750759 -409.656911) (xy 73.804706 -409.649149)
			(xy 73.831958 -409.64866) (xy 74.695558 -409.64866) (xy 74.722811 -409.649184) (xy 74.776761 -409.656936)
			(xy 74.82906 -409.672287) (xy 74.878641 -409.694925) (xy 74.924496 -409.72439) (xy 74.96569 -409.76008)
			(xy 75.001385 -409.801271) (xy 75.030855 -409.847122) (xy 75.053498 -409.896701) (xy 75.068855 -409.948997)
			(xy 75.076613 -410.002948) (xy 75.076613 -410.057452) (xy 75.076613 -410.057453) (xy 76.514146 -410.057453)
			(xy 76.514146 -410.002947) (xy 76.521903 -409.948994) (xy 76.537259 -409.896695) (xy 76.559902 -409.847114)
			(xy 76.589371 -409.80126) (xy 76.625065 -409.760066) (xy 76.666259 -409.724372) (xy 76.712113 -409.694903)
			(xy 76.761694 -409.67226) (xy 76.813993 -409.656903) (xy 76.867945 -409.649146) (xy 76.895198 -409.64866)
			(xy 77.758798 -409.64866) (xy 77.786049 -409.649187) (xy 77.839995 -409.656943) (xy 77.892289 -409.672298)
			(xy 77.941865 -409.694938) (xy 77.987715 -409.724404) (xy 78.028904 -409.760094) (xy 78.064595 -409.801284)
			(xy 78.094061 -409.847133) (xy 78.116702 -409.896709) (xy 78.132056 -409.949003) (xy 78.139813 -410.002949)
			(xy 78.139813 -410.057451) (xy 78.139812 -410.057457) (xy 79.577323 -410.057457) (xy 79.577323 -410.002943)
			(xy 79.585082 -409.948984) (xy 79.600441 -409.896679) (xy 79.623088 -409.847092) (xy 79.652562 -409.801233)
			(xy 79.688263 -409.760036) (xy 79.729464 -409.724339) (xy 79.775325 -409.69487) (xy 79.824915 -409.672228)
			(xy 79.877221 -409.656874) (xy 79.931181 -409.64912) (xy 79.958438 -409.64866) (xy 80.822038 -409.64866)
			(xy 80.849285 -409.649213) (xy 80.903224 -409.656973) (xy 80.95551 -409.67233) (xy 81.005078 -409.694972)
			(xy 81.05092 -409.724436) (xy 81.092102 -409.760125) (xy 81.127786 -409.801311) (xy 81.157247 -409.847155)
			(xy 81.179883 -409.896726) (xy 81.195235 -409.949013) (xy 81.20299 -410.002953) (xy 81.20299 -410.057447)
			(xy 81.202989 -410.057453) (xy 82.640646 -410.057453) (xy 82.640646 -410.002947) (xy 82.648402 -409.948997)
			(xy 82.663758 -409.8967) (xy 82.686399 -409.84712) (xy 82.715866 -409.801267) (xy 82.751558 -409.760074)
			(xy 82.792749 -409.724379) (xy 82.838601 -409.69491) (xy 82.888179 -409.672265) (xy 82.940476 -409.656907)
			(xy 82.994425 -409.649147) (xy 83.021678 -409.64866) (xy 83.885278 -409.64866) (xy 83.91253 -409.649186)
			(xy 83.966478 -409.65694) (xy 84.018774 -409.672292) (xy 84.068353 -409.694932) (xy 84.114205 -409.724397)
			(xy 84.155397 -409.760087) (xy 84.19109 -409.801277) (xy 84.220558 -409.847127) (xy 84.2432 -409.896705)
			(xy 84.258556 -409.949) (xy 84.266313 -410.002948) (xy 84.266313 -410.057452) (xy 84.266312 -410.057456)
			(xy 85.703823 -410.057456) (xy 85.703823 -410.002944) (xy 85.711581 -409.948987) (xy 85.726939 -409.896683)
			(xy 85.749585 -409.847098) (xy 85.779057 -409.80124) (xy 85.814756 -409.760043) (xy 85.855954 -409.724346)
			(xy 85.901813 -409.694876) (xy 85.9514 -409.672233) (xy 86.003705 -409.656877) (xy 86.057662 -409.649122)
			(xy 86.084918 -409.64866) (xy 86.948518 -409.64866) (xy 86.975766 -409.649211) (xy 87.029707 -409.656969)
			(xy 87.081995 -409.672325) (xy 87.131566 -409.694965) (xy 87.17741 -409.724429) (xy 87.218595 -409.760118)
			(xy 87.254282 -409.801304) (xy 87.283744 -409.84715) (xy 87.306382 -409.896721) (xy 87.321734 -409.94901)
			(xy 87.32949 -410.002952) (xy 87.32949 -410.057448) (xy 87.329489 -410.057452) (xy 88.767146 -410.057452)
			(xy 88.767146 -410.002948) (xy 88.774902 -409.949) (xy 88.790256 -409.896704) (xy 88.812896 -409.847125)
			(xy 88.842361 -409.801273) (xy 88.878051 -409.760081) (xy 88.91924 -409.724386) (xy 88.965089 -409.694916)
			(xy 89.014665 -409.672271) (xy 89.066959 -409.656911) (xy 89.120906 -409.649149) (xy 89.148158 -409.64866)
			(xy 90.011758 -409.64866) (xy 90.039011 -409.649184) (xy 90.092961 -409.656936) (xy 90.14526 -409.672287)
			(xy 90.194841 -409.694925) (xy 90.240696 -409.72439) (xy 90.28189 -409.76008) (xy 90.317585 -409.801271)
			(xy 90.347055 -409.847122) (xy 90.369698 -409.896701) (xy 90.385055 -409.948997) (xy 90.392813 -410.002948)
			(xy 90.392813 -410.057452) (xy 90.392813 -410.057453) (xy 91.830346 -410.057453) (xy 91.830346 -410.002947)
			(xy 91.838103 -409.948994) (xy 91.853459 -409.896695) (xy 91.876102 -409.847114) (xy 91.905571 -409.80126)
			(xy 91.941265 -409.760066) (xy 91.982459 -409.724372) (xy 92.028313 -409.694903) (xy 92.077894 -409.67226)
			(xy 92.130193 -409.656903) (xy 92.184145 -409.649146) (xy 92.211398 -409.64866) (xy 93.074998 -409.64866)
			(xy 93.102249 -409.649187) (xy 93.156195 -409.656943) (xy 93.208489 -409.672298) (xy 93.258065 -409.694938)
			(xy 93.303915 -409.724404) (xy 93.345104 -409.760094) (xy 93.380795 -409.801284) (xy 93.410261 -409.847133)
			(xy 93.432902 -409.896709) (xy 93.448256 -409.949003) (xy 93.456013 -410.002949) (xy 93.456013 -410.057451)
			(xy 93.456012 -410.057457) (xy 94.893523 -410.057457) (xy 94.893523 -410.002943) (xy 94.901282 -409.948984)
			(xy 94.916641 -409.896679) (xy 94.939288 -409.847092) (xy 94.968762 -409.801233) (xy 95.004463 -409.760036)
			(xy 95.045664 -409.724339) (xy 95.091525 -409.69487) (xy 95.141115 -409.672228) (xy 95.193421 -409.656874)
			(xy 95.247381 -409.64912) (xy 95.274638 -409.64866) (xy 96.138238 -409.64866) (xy 96.165485 -409.649213)
			(xy 96.219424 -409.656973) (xy 96.27171 -409.67233) (xy 96.321278 -409.694972) (xy 96.36712 -409.724436)
			(xy 96.408302 -409.760125) (xy 96.443986 -409.801311) (xy 96.473447 -409.847155) (xy 96.496083 -409.896726)
			(xy 96.511435 -409.949013) (xy 96.51919 -410.002953) (xy 96.51919 -410.057447) (xy 96.519189 -410.057451)
			(xy 121.120146 -410.057451) (xy 121.120146 -410.002949) (xy 121.127902 -409.949) (xy 121.143256 -409.896705)
			(xy 121.165895 -409.847127) (xy 121.19536 -409.801275) (xy 121.231049 -409.760082) (xy 121.272238 -409.724388)
			(xy 121.318086 -409.694918) (xy 121.367662 -409.672272) (xy 121.419955 -409.656911) (xy 121.473903 -409.649149)
			(xy 121.501154 -409.64866) (xy 122.364754 -409.64866) (xy 122.392007 -409.649184) (xy 122.445958 -409.656935)
			(xy 122.498257 -409.672286) (xy 122.547839 -409.694924) (xy 122.593694 -409.724388) (xy 122.634889 -409.760079)
			(xy 122.670584 -409.801269) (xy 122.700054 -409.847121) (xy 122.722698 -409.8967) (xy 122.738055 -409.948997)
			(xy 122.745813 -410.002947) (xy 122.745813 -410.057453) (xy 124.183346 -410.057453) (xy 124.183346 -410.002947)
			(xy 124.191103 -409.948995) (xy 124.206459 -409.896696) (xy 124.229102 -409.847115) (xy 124.25857 -409.801261)
			(xy 124.294264 -409.760068) (xy 124.335457 -409.724373) (xy 124.38131 -409.694904) (xy 124.430891 -409.672261)
			(xy 124.483189 -409.656904) (xy 124.537141 -409.649146) (xy 124.564394 -409.64866) (xy 125.427994 -409.64866)
			(xy 125.455245 -409.649187) (xy 125.509192 -409.656942) (xy 125.561486 -409.672297) (xy 125.611063 -409.694937)
			(xy 125.656913 -409.724402) (xy 125.698103 -409.760093) (xy 125.733794 -409.801282) (xy 125.76326 -409.847132)
			(xy 125.785901 -409.896708) (xy 125.801256 -409.949002) (xy 125.809013 -410.002949) (xy 125.809013 -410.057451)
			(xy 125.809012 -410.057457) (xy 127.246523 -410.057457) (xy 127.246523 -410.002943) (xy 127.254282 -409.948985)
			(xy 127.269641 -409.89668) (xy 127.292287 -409.847093) (xy 127.321761 -409.801235) (xy 127.357462 -409.760037)
			(xy 127.398662 -409.724341) (xy 127.444523 -409.694871) (xy 127.494112 -409.672229) (xy 127.546418 -409.656874)
			(xy 127.600377 -409.649121) (xy 127.627634 -409.64866) (xy 128.491234 -409.64866) (xy 128.518481 -409.649213)
			(xy 128.572421 -409.656972) (xy 128.624707 -409.672329) (xy 128.674276 -409.69497) (xy 128.720118 -409.724435)
			(xy 128.761301 -409.760123) (xy 128.796985 -409.801309) (xy 128.826446 -409.847154) (xy 128.849083 -409.896725)
			(xy 128.864435 -409.949012) (xy 128.87219 -410.002953) (xy 128.87219 -410.057447) (xy 128.872189 -410.057452)
			(xy 130.309846 -410.057452) (xy 130.309846 -410.002948) (xy 130.317602 -409.948998) (xy 130.332957 -409.896701)
			(xy 130.355599 -409.847121) (xy 130.385065 -409.801268) (xy 130.420757 -409.760075) (xy 130.461947 -409.72438)
			(xy 130.507798 -409.694911) (xy 130.557376 -409.672266) (xy 130.609672 -409.656908) (xy 130.663622 -409.649148)
			(xy 130.690874 -409.64866) (xy 131.554474 -409.64866) (xy 131.581726 -409.649185) (xy 131.635675 -409.656939)
			(xy 131.687972 -409.672291) (xy 131.737551 -409.69493) (xy 131.783403 -409.724395) (xy 131.824596 -409.760086)
			(xy 131.860289 -409.801276) (xy 131.889757 -409.847126) (xy 131.9124 -409.896704) (xy 131.927756 -409.949)
			(xy 131.935513 -410.002948) (xy 131.935513 -410.057452) (xy 131.935512 -410.057456) (xy 133.373023 -410.057456)
			(xy 133.373023 -410.002944) (xy 133.380781 -409.948987) (xy 133.396139 -409.896684) (xy 133.418784 -409.847099)
			(xy 133.448256 -409.801241) (xy 133.483954 -409.760045) (xy 133.525152 -409.724348) (xy 133.571011 -409.694878)
			(xy 133.620597 -409.672234) (xy 133.672901 -409.656878) (xy 133.726858 -409.649122) (xy 133.754114 -409.64866)
			(xy 134.617714 -409.64866) (xy 134.644962 -409.649211) (xy 134.698904 -409.656969) (xy 134.751193 -409.672324)
			(xy 134.800764 -409.694964) (xy 134.846609 -409.724428) (xy 134.887794 -409.760116) (xy 134.923481 -409.801303)
			(xy 134.952943 -409.847149) (xy 134.975581 -409.896721) (xy 134.990934 -409.94901) (xy 134.99869 -410.002952)
			(xy 134.99869 -410.057448) (xy 134.99869 -410.057451) (xy 136.436346 -410.057451) (xy 136.436346 -410.002949)
			(xy 136.444102 -409.949) (xy 136.459456 -409.896705) (xy 136.482095 -409.847127) (xy 136.51156 -409.801275)
			(xy 136.547249 -409.760082) (xy 136.588438 -409.724388) (xy 136.634286 -409.694918) (xy 136.683862 -409.672272)
			(xy 136.736155 -409.656911) (xy 136.790103 -409.649149) (xy 136.817354 -409.64866) (xy 137.680954 -409.64866)
			(xy 137.708207 -409.649184) (xy 137.762158 -409.656935) (xy 137.814457 -409.672286) (xy 137.864039 -409.694924)
			(xy 137.909894 -409.724388) (xy 137.951089 -409.760079) (xy 137.986784 -409.801269) (xy 138.016254 -409.847121)
			(xy 138.038898 -409.8967) (xy 138.054255 -409.948997) (xy 138.062013 -410.002947) (xy 138.062013 -410.057453)
			(xy 139.499546 -410.057453) (xy 139.499546 -410.002947) (xy 139.507303 -409.948995) (xy 139.522659 -409.896696)
			(xy 139.545302 -409.847115) (xy 139.57477 -409.801261) (xy 139.610464 -409.760068) (xy 139.651657 -409.724373)
			(xy 139.69751 -409.694904) (xy 139.747091 -409.672261) (xy 139.799389 -409.656904) (xy 139.853341 -409.649146)
			(xy 139.880594 -409.64866) (xy 140.744194 -409.64866) (xy 140.771445 -409.649187) (xy 140.825392 -409.656942)
			(xy 140.877686 -409.672297) (xy 140.927263 -409.694937) (xy 140.973113 -409.724402) (xy 141.014303 -409.760093)
			(xy 141.049994 -409.801282) (xy 141.07946 -409.847132) (xy 141.102101 -409.896708) (xy 141.117456 -409.949002)
			(xy 141.125213 -410.002949) (xy 141.125213 -410.057451) (xy 141.125212 -410.057457) (xy 142.562723 -410.057457)
			(xy 142.562723 -410.002943) (xy 142.570482 -409.948985) (xy 142.585841 -409.89668) (xy 142.608487 -409.847093)
			(xy 142.637961 -409.801235) (xy 142.673662 -409.760037) (xy 142.714862 -409.724341) (xy 142.760723 -409.694871)
			(xy 142.810312 -409.672229) (xy 142.862618 -409.656874) (xy 142.916577 -409.649121) (xy 142.943834 -409.64866)
			(xy 143.807434 -409.64866) (xy 143.834681 -409.649213) (xy 143.888621 -409.656972) (xy 143.940907 -409.672329)
			(xy 143.990476 -409.69497) (xy 144.036318 -409.724435) (xy 144.077501 -409.760123) (xy 144.113185 -409.801309)
			(xy 144.142646 -409.847154) (xy 144.165283 -409.896725) (xy 144.180635 -409.949012) (xy 144.18839 -410.002953)
			(xy 144.18839 -410.057447) (xy 144.188389 -410.057452) (xy 145.626046 -410.057452) (xy 145.626046 -410.002948)
			(xy 145.633802 -409.948998) (xy 145.649157 -409.896701) (xy 145.671799 -409.847121) (xy 145.701265 -409.801268)
			(xy 145.736957 -409.760075) (xy 145.778147 -409.72438) (xy 145.823998 -409.694911) (xy 145.873576 -409.672266)
			(xy 145.925872 -409.656908) (xy 145.979822 -409.649148) (xy 146.007074 -409.64866) (xy 146.870674 -409.64866)
			(xy 146.897926 -409.649185) (xy 146.951875 -409.656939) (xy 147.004172 -409.672291) (xy 147.053751 -409.69493)
			(xy 147.099603 -409.724395) (xy 147.140796 -409.760086) (xy 147.176489 -409.801276) (xy 147.205957 -409.847126)
			(xy 147.2286 -409.896704) (xy 147.243956 -409.949) (xy 147.251713 -410.002948) (xy 147.251713 -410.057452)
			(xy 147.251712 -410.057456) (xy 148.689223 -410.057456) (xy 148.689223 -410.002944) (xy 148.696981 -409.948987)
			(xy 148.712339 -409.896684) (xy 148.734984 -409.847099) (xy 148.764456 -409.801241) (xy 148.800154 -409.760045)
			(xy 148.841352 -409.724348) (xy 148.887211 -409.694878) (xy 148.936797 -409.672234) (xy 148.989101 -409.656878)
			(xy 149.043058 -409.649122) (xy 149.070314 -409.64866) (xy 149.933914 -409.64866) (xy 149.961162 -409.649211)
			(xy 150.015104 -409.656969) (xy 150.067393 -409.672324) (xy 150.116964 -409.694964) (xy 150.162809 -409.724428)
			(xy 150.203994 -409.760116) (xy 150.239681 -409.801303) (xy 150.269143 -409.847149) (xy 150.291781 -409.896721)
			(xy 150.307134 -409.94901) (xy 150.31489 -410.002952) (xy 150.31489 -410.057448) (xy 150.31489 -410.057451)
			(xy 151.752546 -410.057451) (xy 151.752546 -410.002949) (xy 151.760302 -409.949) (xy 151.775656 -409.896705)
			(xy 151.798295 -409.847127) (xy 151.82776 -409.801275) (xy 151.863449 -409.760082) (xy 151.904638 -409.724388)
			(xy 151.950486 -409.694918) (xy 152.000062 -409.672272) (xy 152.052355 -409.656911) (xy 152.106303 -409.649149)
			(xy 152.133554 -409.64866) (xy 152.997154 -409.64866) (xy 153.024407 -409.649184) (xy 153.078358 -409.656935)
			(xy 153.130657 -409.672286) (xy 153.180239 -409.694924) (xy 153.226094 -409.724388) (xy 153.267289 -409.760079)
			(xy 153.302984 -409.801269) (xy 153.332454 -409.847121) (xy 153.355098 -409.8967) (xy 153.370455 -409.948997)
			(xy 153.378213 -410.002947) (xy 153.378213 -410.057453) (xy 154.815746 -410.057453) (xy 154.815746 -410.002947)
			(xy 154.823503 -409.948995) (xy 154.838859 -409.896696) (xy 154.861502 -409.847115) (xy 154.89097 -409.801261)
			(xy 154.926664 -409.760068) (xy 154.967857 -409.724373) (xy 155.01371 -409.694904) (xy 155.063291 -409.672261)
			(xy 155.115589 -409.656904) (xy 155.169541 -409.649146) (xy 155.196794 -409.64866) (xy 156.060394 -409.64866)
			(xy 156.087645 -409.649187) (xy 156.141592 -409.656942) (xy 156.193886 -409.672297) (xy 156.243463 -409.694937)
			(xy 156.289313 -409.724402) (xy 156.330503 -409.760093) (xy 156.366194 -409.801282) (xy 156.39566 -409.847132)
			(xy 156.418301 -409.896708) (xy 156.433656 -409.949002) (xy 156.441413 -410.002949) (xy 156.441413 -410.057451)
			(xy 156.441412 -410.057457) (xy 157.878923 -410.057457) (xy 157.878923 -410.002943) (xy 157.886682 -409.948985)
			(xy 157.902041 -409.89668) (xy 157.924687 -409.847093) (xy 157.954161 -409.801235) (xy 157.989862 -409.760037)
			(xy 158.031062 -409.724341) (xy 158.076923 -409.694871) (xy 158.126512 -409.672229) (xy 158.178818 -409.656874)
			(xy 158.232777 -409.649121) (xy 158.260034 -409.64866) (xy 159.123634 -409.64866) (xy 159.150881 -409.649213)
			(xy 159.204821 -409.656972) (xy 159.257107 -409.672329) (xy 159.306676 -409.69497) (xy 159.352518 -409.724435)
			(xy 159.393701 -409.760123) (xy 159.429385 -409.801309) (xy 159.458846 -409.847154) (xy 159.481483 -409.896725)
			(xy 159.496835 -409.949012) (xy 159.50459 -410.002953) (xy 159.50459 -410.057447) (xy 159.504589 -410.057452)
			(xy 160.942246 -410.057452) (xy 160.942246 -410.002948) (xy 160.950002 -409.948998) (xy 160.965357 -409.896701)
			(xy 160.987999 -409.847121) (xy 161.017465 -409.801268) (xy 161.053157 -409.760075) (xy 161.094347 -409.72438)
			(xy 161.140198 -409.694911) (xy 161.189776 -409.672266) (xy 161.242072 -409.656908) (xy 161.296022 -409.649148)
			(xy 161.323274 -409.64866) (xy 162.186874 -409.64866) (xy 162.214126 -409.649185) (xy 162.268075 -409.656939)
			(xy 162.320372 -409.672291) (xy 162.369951 -409.69493) (xy 162.415803 -409.724395) (xy 162.456996 -409.760086)
			(xy 162.492689 -409.801276) (xy 162.522157 -409.847126) (xy 162.5448 -409.896704) (xy 162.560156 -409.949)
			(xy 162.567913 -410.002948) (xy 162.567913 -410.057452) (xy 162.567912 -410.057456) (xy 164.005423 -410.057456)
			(xy 164.005423 -410.002944) (xy 164.013181 -409.948987) (xy 164.028539 -409.896684) (xy 164.051184 -409.847099)
			(xy 164.080656 -409.801241) (xy 164.116354 -409.760045) (xy 164.157552 -409.724348) (xy 164.203411 -409.694878)
			(xy 164.252997 -409.672234) (xy 164.305301 -409.656878) (xy 164.359258 -409.649122) (xy 164.386514 -409.64866)
			(xy 165.250114 -409.64866) (xy 165.277362 -409.649211) (xy 165.331304 -409.656969) (xy 165.383593 -409.672324)
			(xy 165.433164 -409.694964) (xy 165.479009 -409.724428) (xy 165.520194 -409.760116) (xy 165.555881 -409.801303)
			(xy 165.585343 -409.847149) (xy 165.607981 -409.896721) (xy 165.623334 -409.94901) (xy 165.63109 -410.002952)
			(xy 165.63109 -410.057448) (xy 165.63109 -410.057451) (xy 167.068746 -410.057451) (xy 167.068746 -410.002949)
			(xy 167.076502 -409.949) (xy 167.091856 -409.896705) (xy 167.114495 -409.847127) (xy 167.14396 -409.801275)
			(xy 167.179649 -409.760082) (xy 167.220838 -409.724388) (xy 167.266686 -409.694918) (xy 167.316262 -409.672272)
			(xy 167.368555 -409.656911) (xy 167.422503 -409.649149) (xy 167.449754 -409.64866) (xy 168.313354 -409.64866)
			(xy 168.340607 -409.649184) (xy 168.394558 -409.656935) (xy 168.446857 -409.672286) (xy 168.496439 -409.694924)
			(xy 168.542294 -409.724388) (xy 168.583489 -409.760079) (xy 168.619184 -409.801269) (xy 168.648654 -409.847121)
			(xy 168.671298 -409.8967) (xy 168.686655 -409.948997) (xy 168.694413 -410.002947) (xy 168.694413 -410.057453)
			(xy 168.686655 -410.111403) (xy 168.671298 -410.1637) (xy 168.648654 -410.213279) (xy 168.619184 -410.259131)
			(xy 168.583489 -410.300321) (xy 168.542294 -410.336012) (xy 168.496439 -410.365476) (xy 168.446857 -410.388114)
			(xy 168.394558 -410.403465) (xy 168.340607 -410.411216) (xy 168.313354 -410.411676) (xy 167.449754 -410.411676)
			(xy 167.422503 -410.411251) (xy 167.368555 -410.403489) (xy 167.316262 -410.388128) (xy 167.266686 -410.365482)
			(xy 167.220838 -410.336012) (xy 167.179649 -410.300318) (xy 167.14396 -410.259125) (xy 167.114495 -410.213273)
			(xy 167.091856 -410.163695) (xy 167.076502 -410.1114) (xy 167.068746 -410.057451) (xy 165.63109 -410.057451)
			(xy 165.623334 -410.11139) (xy 165.607981 -410.163679) (xy 165.585343 -410.213251) (xy 165.555881 -410.259097)
			(xy 165.520194 -410.300284) (xy 165.479009 -410.335972) (xy 165.433164 -410.365436) (xy 165.383593 -410.388076)
			(xy 165.331304 -410.403431) (xy 165.277362 -410.411189) (xy 165.250114 -410.411676) (xy 164.386514 -410.411676)
			(xy 164.359258 -410.411278) (xy 164.305301 -410.403522) (xy 164.252997 -410.388166) (xy 164.203411 -410.365522)
			(xy 164.157552 -410.336052) (xy 164.116354 -410.300355) (xy 164.080656 -410.259159) (xy 164.051184 -410.213301)
			(xy 164.028539 -410.163716) (xy 164.013181 -410.111413) (xy 164.005423 -410.057456) (xy 162.567912 -410.057456)
			(xy 162.560156 -410.1114) (xy 162.5448 -410.163696) (xy 162.522157 -410.213274) (xy 162.492689 -410.259124)
			(xy 162.456996 -410.300314) (xy 162.415803 -410.336005) (xy 162.369951 -410.36547) (xy 162.320372 -410.388109)
			(xy 162.268075 -410.403461) (xy 162.214126 -410.411215) (xy 162.186874 -410.411676) (xy 161.323274 -410.411676)
			(xy 161.296022 -410.411252) (xy 161.242072 -410.403492) (xy 161.189776 -410.388134) (xy 161.140198 -410.365489)
			(xy 161.094347 -410.33602) (xy 161.053157 -410.300325) (xy 161.017465 -410.259132) (xy 160.987999 -410.213279)
			(xy 160.965357 -410.163699) (xy 160.950002 -410.111402) (xy 160.942246 -410.057452) (xy 159.504589 -410.057452)
			(xy 159.496835 -410.111388) (xy 159.481483 -410.163675) (xy 159.458846 -410.213246) (xy 159.429385 -410.259091)
			(xy 159.393701 -410.300277) (xy 159.352518 -410.335965) (xy 159.306676 -410.36543) (xy 159.257107 -410.388071)
			(xy 159.204821 -410.403428) (xy 159.150881 -410.411187) (xy 159.123634 -410.411676) (xy 158.260034 -410.411676)
			(xy 158.232777 -410.411279) (xy 158.178818 -410.403526) (xy 158.126512 -410.388171) (xy 158.076923 -410.365529)
			(xy 158.031062 -410.336059) (xy 157.989862 -410.300363) (xy 157.954161 -410.259165) (xy 157.924687 -410.213307)
			(xy 157.902041 -410.16372) (xy 157.886682 -410.111415) (xy 157.878923 -410.057457) (xy 156.441412 -410.057457)
			(xy 156.433656 -410.111398) (xy 156.418301 -410.163692) (xy 156.39566 -410.213268) (xy 156.366194 -410.259118)
			(xy 156.330503 -410.300307) (xy 156.289313 -410.335998) (xy 156.243463 -410.365463) (xy 156.193886 -410.388103)
			(xy 156.141592 -410.403458) (xy 156.087645 -410.411213) (xy 156.060394 -410.411676) (xy 155.196794 -410.411676)
			(xy 155.169541 -410.411254) (xy 155.115589 -410.403496) (xy 155.063291 -410.388139) (xy 155.01371 -410.365496)
			(xy 154.967857 -410.336027) (xy 154.926664 -410.300332) (xy 154.89097 -410.259139) (xy 154.861502 -410.213285)
			(xy 154.838859 -410.163704) (xy 154.823503 -410.111405) (xy 154.815746 -410.057453) (xy 153.378213 -410.057453)
			(xy 153.370455 -410.111403) (xy 153.355098 -410.1637) (xy 153.332454 -410.213279) (xy 153.302984 -410.259131)
			(xy 153.267289 -410.300321) (xy 153.226094 -410.336012) (xy 153.180239 -410.365476) (xy 153.130657 -410.388114)
			(xy 153.078358 -410.403465) (xy 153.024407 -410.411216) (xy 152.997154 -410.411676) (xy 152.133554 -410.411676)
			(xy 152.106303 -410.411251) (xy 152.052355 -410.403489) (xy 152.000062 -410.388128) (xy 151.950486 -410.365482)
			(xy 151.904638 -410.336012) (xy 151.863449 -410.300318) (xy 151.82776 -410.259125) (xy 151.798295 -410.213273)
			(xy 151.775656 -410.163695) (xy 151.760302 -410.1114) (xy 151.752546 -410.057451) (xy 150.31489 -410.057451)
			(xy 150.307134 -410.11139) (xy 150.291781 -410.163679) (xy 150.269143 -410.213251) (xy 150.239681 -410.259097)
			(xy 150.203994 -410.300284) (xy 150.162809 -410.335972) (xy 150.116964 -410.365436) (xy 150.067393 -410.388076)
			(xy 150.015104 -410.403431) (xy 149.961162 -410.411189) (xy 149.933914 -410.411676) (xy 149.070314 -410.411676)
			(xy 149.043058 -410.411278) (xy 148.989101 -410.403522) (xy 148.936797 -410.388166) (xy 148.887211 -410.365522)
			(xy 148.841352 -410.336052) (xy 148.800154 -410.300355) (xy 148.764456 -410.259159) (xy 148.734984 -410.213301)
			(xy 148.712339 -410.163716) (xy 148.696981 -410.111413) (xy 148.689223 -410.057456) (xy 147.251712 -410.057456)
			(xy 147.243956 -410.1114) (xy 147.2286 -410.163696) (xy 147.205957 -410.213274) (xy 147.176489 -410.259124)
			(xy 147.140796 -410.300314) (xy 147.099603 -410.336005) (xy 147.053751 -410.36547) (xy 147.004172 -410.388109)
			(xy 146.951875 -410.403461) (xy 146.897926 -410.411215) (xy 146.870674 -410.411676) (xy 146.007074 -410.411676)
			(xy 145.979822 -410.411252) (xy 145.925872 -410.403492) (xy 145.873576 -410.388134) (xy 145.823998 -410.365489)
			(xy 145.778147 -410.33602) (xy 145.736957 -410.300325) (xy 145.701265 -410.259132) (xy 145.671799 -410.213279)
			(xy 145.649157 -410.163699) (xy 145.633802 -410.111402) (xy 145.626046 -410.057452) (xy 144.188389 -410.057452)
			(xy 144.180635 -410.111388) (xy 144.165283 -410.163675) (xy 144.142646 -410.213246) (xy 144.113185 -410.259091)
			(xy 144.077501 -410.300277) (xy 144.036318 -410.335965) (xy 143.990476 -410.36543) (xy 143.940907 -410.388071)
			(xy 143.888621 -410.403428) (xy 143.834681 -410.411187) (xy 143.807434 -410.411676) (xy 142.943834 -410.411676)
			(xy 142.916577 -410.411279) (xy 142.862618 -410.403526) (xy 142.810312 -410.388171) (xy 142.760723 -410.365529)
			(xy 142.714862 -410.336059) (xy 142.673662 -410.300363) (xy 142.637961 -410.259165) (xy 142.608487 -410.213307)
			(xy 142.585841 -410.16372) (xy 142.570482 -410.111415) (xy 142.562723 -410.057457) (xy 141.125212 -410.057457)
			(xy 141.117456 -410.111398) (xy 141.102101 -410.163692) (xy 141.07946 -410.213268) (xy 141.049994 -410.259118)
			(xy 141.014303 -410.300307) (xy 140.973113 -410.335998) (xy 140.927263 -410.365463) (xy 140.877686 -410.388103)
			(xy 140.825392 -410.403458) (xy 140.771445 -410.411213) (xy 140.744194 -410.411676) (xy 139.880594 -410.411676)
			(xy 139.853341 -410.411254) (xy 139.799389 -410.403496) (xy 139.747091 -410.388139) (xy 139.69751 -410.365496)
			(xy 139.651657 -410.336027) (xy 139.610464 -410.300332) (xy 139.57477 -410.259139) (xy 139.545302 -410.213285)
			(xy 139.522659 -410.163704) (xy 139.507303 -410.111405) (xy 139.499546 -410.057453) (xy 138.062013 -410.057453)
			(xy 138.054255 -410.111403) (xy 138.038898 -410.1637) (xy 138.016254 -410.213279) (xy 137.986784 -410.259131)
			(xy 137.951089 -410.300321) (xy 137.909894 -410.336012) (xy 137.864039 -410.365476) (xy 137.814457 -410.388114)
			(xy 137.762158 -410.403465) (xy 137.708207 -410.411216) (xy 137.680954 -410.411676) (xy 136.817354 -410.411676)
			(xy 136.790103 -410.411251) (xy 136.736155 -410.403489) (xy 136.683862 -410.388128) (xy 136.634286 -410.365482)
			(xy 136.588438 -410.336012) (xy 136.547249 -410.300318) (xy 136.51156 -410.259125) (xy 136.482095 -410.213273)
			(xy 136.459456 -410.163695) (xy 136.444102 -410.1114) (xy 136.436346 -410.057451) (xy 134.99869 -410.057451)
			(xy 134.990934 -410.11139) (xy 134.975581 -410.163679) (xy 134.952943 -410.213251) (xy 134.923481 -410.259097)
			(xy 134.887794 -410.300284) (xy 134.846609 -410.335972) (xy 134.800764 -410.365436) (xy 134.751193 -410.388076)
			(xy 134.698904 -410.403431) (xy 134.644962 -410.411189) (xy 134.617714 -410.411676) (xy 133.754114 -410.411676)
			(xy 133.726858 -410.411278) (xy 133.672901 -410.403522) (xy 133.620597 -410.388166) (xy 133.571011 -410.365522)
			(xy 133.525152 -410.336052) (xy 133.483954 -410.300355) (xy 133.448256 -410.259159) (xy 133.418784 -410.213301)
			(xy 133.396139 -410.163716) (xy 133.380781 -410.111413) (xy 133.373023 -410.057456) (xy 131.935512 -410.057456)
			(xy 131.927756 -410.1114) (xy 131.9124 -410.163696) (xy 131.889757 -410.213274) (xy 131.860289 -410.259124)
			(xy 131.824596 -410.300314) (xy 131.783403 -410.336005) (xy 131.737551 -410.36547) (xy 131.687972 -410.388109)
			(xy 131.635675 -410.403461) (xy 131.581726 -410.411215) (xy 131.554474 -410.411676) (xy 130.690874 -410.411676)
			(xy 130.663622 -410.411252) (xy 130.609672 -410.403492) (xy 130.557376 -410.388134) (xy 130.507798 -410.365489)
			(xy 130.461947 -410.33602) (xy 130.420757 -410.300325) (xy 130.385065 -410.259132) (xy 130.355599 -410.213279)
			(xy 130.332957 -410.163699) (xy 130.317602 -410.111402) (xy 130.309846 -410.057452) (xy 128.872189 -410.057452)
			(xy 128.864435 -410.111388) (xy 128.849083 -410.163675) (xy 128.826446 -410.213246) (xy 128.796985 -410.259091)
			(xy 128.761301 -410.300277) (xy 128.720118 -410.335965) (xy 128.674276 -410.36543) (xy 128.624707 -410.388071)
			(xy 128.572421 -410.403428) (xy 128.518481 -410.411187) (xy 128.491234 -410.411676) (xy 127.627634 -410.411676)
			(xy 127.600377 -410.411279) (xy 127.546418 -410.403526) (xy 127.494112 -410.388171) (xy 127.444523 -410.365529)
			(xy 127.398662 -410.336059) (xy 127.357462 -410.300363) (xy 127.321761 -410.259165) (xy 127.292287 -410.213307)
			(xy 127.269641 -410.16372) (xy 127.254282 -410.111415) (xy 127.246523 -410.057457) (xy 125.809012 -410.057457)
			(xy 125.801256 -410.111398) (xy 125.785901 -410.163692) (xy 125.76326 -410.213268) (xy 125.733794 -410.259118)
			(xy 125.698103 -410.300307) (xy 125.656913 -410.335998) (xy 125.611063 -410.365463) (xy 125.561486 -410.388103)
			(xy 125.509192 -410.403458) (xy 125.455245 -410.411213) (xy 125.427994 -410.411676) (xy 124.564394 -410.411676)
			(xy 124.537141 -410.411254) (xy 124.483189 -410.403496) (xy 124.430891 -410.388139) (xy 124.38131 -410.365496)
			(xy 124.335457 -410.336027) (xy 124.294264 -410.300332) (xy 124.25857 -410.259139) (xy 124.229102 -410.213285)
			(xy 124.206459 -410.163704) (xy 124.191103 -410.111405) (xy 124.183346 -410.057453) (xy 122.745813 -410.057453)
			(xy 122.738055 -410.111403) (xy 122.722698 -410.1637) (xy 122.700054 -410.213279) (xy 122.670584 -410.259131)
			(xy 122.634889 -410.300321) (xy 122.593694 -410.336012) (xy 122.547839 -410.365476) (xy 122.498257 -410.388114)
			(xy 122.445958 -410.403465) (xy 122.392007 -410.411216) (xy 122.364754 -410.411676) (xy 121.501154 -410.411676)
			(xy 121.473903 -410.411251) (xy 121.419955 -410.403489) (xy 121.367662 -410.388128) (xy 121.318086 -410.365482)
			(xy 121.272238 -410.336012) (xy 121.231049 -410.300318) (xy 121.19536 -410.259125) (xy 121.165895 -410.213273)
			(xy 121.143256 -410.163695) (xy 121.127902 -410.1114) (xy 121.120146 -410.057451) (xy 96.519189 -410.057451)
			(xy 96.511435 -410.111387) (xy 96.496083 -410.163674) (xy 96.473447 -410.213245) (xy 96.443986 -410.259089)
			(xy 96.408302 -410.300275) (xy 96.36712 -410.335964) (xy 96.321278 -410.365428) (xy 96.27171 -410.38807)
			(xy 96.219424 -410.403427) (xy 96.165485 -410.411187) (xy 96.138238 -410.411676) (xy 95.274638 -410.411676)
			(xy 95.247381 -410.41128) (xy 95.193421 -410.403526) (xy 95.141115 -410.388172) (xy 95.091525 -410.36553)
			(xy 95.045664 -410.336061) (xy 95.004463 -410.300364) (xy 94.968762 -410.259167) (xy 94.939288 -410.213308)
			(xy 94.916641 -410.163721) (xy 94.901282 -410.111416) (xy 94.893523 -410.057457) (xy 93.456012 -410.057457)
			(xy 93.448256 -410.111397) (xy 93.432902 -410.163691) (xy 93.410261 -410.213267) (xy 93.380795 -410.259116)
			(xy 93.345104 -410.300306) (xy 93.303915 -410.335996) (xy 93.258065 -410.365462) (xy 93.208489 -410.388102)
			(xy 93.156195 -410.403457) (xy 93.102249 -410.411213) (xy 93.074998 -410.411676) (xy 92.211398 -410.411676)
			(xy 92.184145 -410.411254) (xy 92.130193 -410.403497) (xy 92.077894 -410.38814) (xy 92.028313 -410.365497)
			(xy 91.982459 -410.336028) (xy 91.941265 -410.300334) (xy 91.905571 -410.25914) (xy 91.876102 -410.213286)
			(xy 91.853459 -410.163705) (xy 91.838103 -410.111406) (xy 91.830346 -410.057453) (xy 90.392813 -410.057453)
			(xy 90.385055 -410.111403) (xy 90.369698 -410.163699) (xy 90.347055 -410.213278) (xy 90.317585 -410.259129)
			(xy 90.28189 -410.30032) (xy 90.240696 -410.33601) (xy 90.194841 -410.365475) (xy 90.14526 -410.388113)
			(xy 90.092961 -410.403464) (xy 90.039011 -410.411216) (xy 90.011758 -410.411676) (xy 89.148158 -410.411676)
			(xy 89.120906 -410.411251) (xy 89.066959 -410.403489) (xy 89.014665 -410.388129) (xy 88.965089 -410.365484)
			(xy 88.91924 -410.336014) (xy 88.878051 -410.300319) (xy 88.842361 -410.259127) (xy 88.812896 -410.213275)
			(xy 88.790256 -410.163696) (xy 88.774902 -410.1114) (xy 88.767146 -410.057452) (xy 87.329489 -410.057452)
			(xy 87.321734 -410.11139) (xy 87.306382 -410.163679) (xy 87.283744 -410.21325) (xy 87.254282 -410.259096)
			(xy 87.218595 -410.300282) (xy 87.17741 -410.335971) (xy 87.131566 -410.365435) (xy 87.081995 -410.388075)
			(xy 87.029707 -410.403431) (xy 86.975766 -410.411189) (xy 86.948518 -410.411676) (xy 86.084918 -410.411676)
			(xy 86.057662 -410.411278) (xy 86.003705 -410.403523) (xy 85.9514 -410.388167) (xy 85.901813 -410.365524)
			(xy 85.855954 -410.336054) (xy 85.814756 -410.300357) (xy 85.779057 -410.25916) (xy 85.749585 -410.213302)
			(xy 85.726939 -410.163717) (xy 85.711581 -410.111413) (xy 85.703823 -410.057456) (xy 84.266312 -410.057456)
			(xy 84.258556 -410.1114) (xy 84.2432 -410.163695) (xy 84.220558 -410.213273) (xy 84.19109 -410.259123)
			(xy 84.155397 -410.300313) (xy 84.114205 -410.336003) (xy 84.068353 -410.365468) (xy 84.018774 -410.388108)
			(xy 83.966478 -410.40346) (xy 83.91253 -410.411214) (xy 83.885278 -410.411676) (xy 83.021678 -410.411676)
			(xy 82.994425 -410.411253) (xy 82.940476 -410.403493) (xy 82.888179 -410.388135) (xy 82.838601 -410.36549)
			(xy 82.792749 -410.336021) (xy 82.751558 -410.300326) (xy 82.715866 -410.259133) (xy 82.686399 -410.21328)
			(xy 82.663758 -410.1637) (xy 82.648402 -410.111403) (xy 82.640646 -410.057453) (xy 81.202989 -410.057453)
			(xy 81.195235 -410.111387) (xy 81.179883 -410.163674) (xy 81.157247 -410.213245) (xy 81.127786 -410.259089)
			(xy 81.092102 -410.300275) (xy 81.05092 -410.335964) (xy 81.005078 -410.365428) (xy 80.95551 -410.38807)
			(xy 80.903224 -410.403427) (xy 80.849285 -410.411187) (xy 80.822038 -410.411676) (xy 79.958438 -410.411676)
			(xy 79.931181 -410.41128) (xy 79.877221 -410.403526) (xy 79.824915 -410.388172) (xy 79.775325 -410.36553)
			(xy 79.729464 -410.336061) (xy 79.688263 -410.300364) (xy 79.652562 -410.259167) (xy 79.623088 -410.213308)
			(xy 79.600441 -410.163721) (xy 79.585082 -410.111416) (xy 79.577323 -410.057457) (xy 78.139812 -410.057457)
			(xy 78.132056 -410.111397) (xy 78.116702 -410.163691) (xy 78.094061 -410.213267) (xy 78.064595 -410.259116)
			(xy 78.028904 -410.300306) (xy 77.987715 -410.335996) (xy 77.941865 -410.365462) (xy 77.892289 -410.388102)
			(xy 77.839995 -410.403457) (xy 77.786049 -410.411213) (xy 77.758798 -410.411676) (xy 76.895198 -410.411676)
			(xy 76.867945 -410.411254) (xy 76.813993 -410.403497) (xy 76.761694 -410.38814) (xy 76.712113 -410.365497)
			(xy 76.666259 -410.336028) (xy 76.625065 -410.300334) (xy 76.589371 -410.25914) (xy 76.559902 -410.213286)
			(xy 76.537259 -410.163705) (xy 76.521903 -410.111406) (xy 76.514146 -410.057453) (xy 75.076613 -410.057453)
			(xy 75.068855 -410.111403) (xy 75.053498 -410.163699) (xy 75.030855 -410.213278) (xy 75.001385 -410.259129)
			(xy 74.96569 -410.30032) (xy 74.924496 -410.33601) (xy 74.878641 -410.365475) (xy 74.82906 -410.388113)
			(xy 74.776761 -410.403464) (xy 74.722811 -410.411216) (xy 74.695558 -410.411676) (xy 73.831958 -410.411676)
			(xy 73.804706 -410.411251) (xy 73.750759 -410.403489) (xy 73.698465 -410.388129) (xy 73.648889 -410.365484)
			(xy 73.60304 -410.336014) (xy 73.561851 -410.300319) (xy 73.526161 -410.259127) (xy 73.496696 -410.213275)
			(xy 73.474056 -410.163696) (xy 73.458702 -410.1114) (xy 73.450946 -410.057452) (xy 72.013289 -410.057452)
			(xy 72.005534 -410.11139) (xy 71.990182 -410.163679) (xy 71.967544 -410.21325) (xy 71.938082 -410.259096)
			(xy 71.902395 -410.300282) (xy 71.86121 -410.335971) (xy 71.815366 -410.365435) (xy 71.765795 -410.388075)
			(xy 71.713507 -410.403431) (xy 71.659566 -410.411189) (xy 71.632318 -410.411676) (xy 70.768718 -410.411676)
			(xy 70.741462 -410.411278) (xy 70.687505 -410.403523) (xy 70.6352 -410.388167) (xy 70.585613 -410.365524)
			(xy 70.539754 -410.336054) (xy 70.498556 -410.300357) (xy 70.462857 -410.25916) (xy 70.433385 -410.213302)
			(xy 70.410739 -410.163717) (xy 70.395381 -410.111413) (xy 70.387623 -410.057456) (xy 68.950112 -410.057456)
			(xy 68.942356 -410.1114) (xy 68.927 -410.163695) (xy 68.904358 -410.213273) (xy 68.87489 -410.259123)
			(xy 68.839197 -410.300313) (xy 68.798005 -410.336003) (xy 68.752153 -410.365468) (xy 68.702574 -410.388108)
			(xy 68.650278 -410.40346) (xy 68.59633 -410.411214) (xy 68.569078 -410.411676) (xy 67.705478 -410.411676)
			(xy 67.678225 -410.411253) (xy 67.624276 -410.403493) (xy 67.571979 -410.388135) (xy 67.522401 -410.36549)
			(xy 67.476549 -410.336021) (xy 67.435358 -410.300326) (xy 67.399666 -410.259133) (xy 67.370199 -410.21328)
			(xy 67.347558 -410.1637) (xy 67.332202 -410.111403) (xy 67.324446 -410.057453) (xy 65.886789 -410.057453)
			(xy 65.879035 -410.111387) (xy 65.863683 -410.163674) (xy 65.841047 -410.213245) (xy 65.811586 -410.259089)
			(xy 65.775902 -410.300275) (xy 65.73472 -410.335964) (xy 65.688878 -410.365428) (xy 65.63931 -410.38807)
			(xy 65.587024 -410.403427) (xy 65.533085 -410.411187) (xy 65.505838 -410.411676) (xy 64.642238 -410.411676)
			(xy 64.614981 -410.41128) (xy 64.561021 -410.403526) (xy 64.508715 -410.388172) (xy 64.459125 -410.36553)
			(xy 64.413264 -410.336061) (xy 64.372063 -410.300364) (xy 64.336362 -410.259167) (xy 64.306888 -410.213308)
			(xy 64.284241 -410.163721) (xy 64.268882 -410.111416) (xy 64.261123 -410.057457) (xy 62.823612 -410.057457)
			(xy 62.815856 -410.111397) (xy 62.800502 -410.163691) (xy 62.777861 -410.213267) (xy 62.748395 -410.259116)
			(xy 62.712704 -410.300306) (xy 62.671515 -410.335996) (xy 62.625665 -410.365462) (xy 62.576089 -410.388102)
			(xy 62.523795 -410.403457) (xy 62.469849 -410.411213) (xy 62.442598 -410.411676) (xy 61.578998 -410.411676)
			(xy 61.551745 -410.411254) (xy 61.497793 -410.403497) (xy 61.445494 -410.38814) (xy 61.395913 -410.365497)
			(xy 61.350059 -410.336028) (xy 61.308865 -410.300334) (xy 61.273171 -410.25914) (xy 61.243702 -410.213286)
			(xy 61.221059 -410.163705) (xy 61.205703 -410.111406) (xy 61.197946 -410.057453) (xy 59.760413 -410.057453)
			(xy 59.752655 -410.111403) (xy 59.737298 -410.163699) (xy 59.714655 -410.213278) (xy 59.685185 -410.259129)
			(xy 59.64949 -410.30032) (xy 59.608296 -410.33601) (xy 59.562441 -410.365475) (xy 59.51286 -410.388113)
			(xy 59.460561 -410.403464) (xy 59.406611 -410.411216) (xy 59.379358 -410.411676) (xy 58.515758 -410.411676)
			(xy 58.488506 -410.411251) (xy 58.434559 -410.403489) (xy 58.382265 -410.388129) (xy 58.332689 -410.365484)
			(xy 58.28684 -410.336014) (xy 58.245651 -410.300319) (xy 58.209961 -410.259127) (xy 58.180496 -410.213275)
			(xy 58.157856 -410.163696) (xy 58.142502 -410.1114) (xy 58.134746 -410.057452) (xy 56.697089 -410.057452)
			(xy 56.689334 -410.11139) (xy 56.673982 -410.163679) (xy 56.651344 -410.21325) (xy 56.621882 -410.259096)
			(xy 56.586195 -410.300282) (xy 56.54501 -410.335971) (xy 56.499166 -410.365435) (xy 56.449595 -410.388075)
			(xy 56.397307 -410.403431) (xy 56.343366 -410.411189) (xy 56.316118 -410.411676) (xy 55.452518 -410.411676)
			(xy 55.425262 -410.411278) (xy 55.371305 -410.403523) (xy 55.319 -410.388167) (xy 55.269413 -410.365524)
			(xy 55.223554 -410.336054) (xy 55.182356 -410.300357) (xy 55.146657 -410.25916) (xy 55.117185 -410.213302)
			(xy 55.094539 -410.163717) (xy 55.079181 -410.111413) (xy 55.071423 -410.057456) (xy 53.633912 -410.057456)
			(xy 53.626156 -410.1114) (xy 53.6108 -410.163695) (xy 53.588158 -410.213273) (xy 53.55869 -410.259123)
			(xy 53.522997 -410.300313) (xy 53.481805 -410.336003) (xy 53.435953 -410.365468) (xy 53.386374 -410.388108)
			(xy 53.334078 -410.40346) (xy 53.28013 -410.411214) (xy 53.252878 -410.411676) (xy 52.389278 -410.411676)
			(xy 52.362025 -410.411253) (xy 52.308076 -410.403493) (xy 52.255779 -410.388135) (xy 52.206201 -410.36549)
			(xy 52.160349 -410.336021) (xy 52.119158 -410.300326) (xy 52.083466 -410.259133) (xy 52.053999 -410.21328)
			(xy 52.031358 -410.1637) (xy 52.016002 -410.111403) (xy 52.008246 -410.057453) (xy 50.570589 -410.057453)
			(xy 50.562835 -410.111387) (xy 50.547483 -410.163674) (xy 50.524847 -410.213245) (xy 50.495386 -410.259089)
			(xy 50.459702 -410.300275) (xy 50.41852 -410.335964) (xy 50.372678 -410.365428) (xy 50.32311 -410.38807)
			(xy 50.270824 -410.403427) (xy 50.216885 -410.411187) (xy 50.189638 -410.411676) (xy 49.326038 -410.411676)
			(xy 49.298781 -410.41128) (xy 49.244821 -410.403526) (xy 49.192515 -410.388172) (xy 49.142925 -410.36553)
			(xy 49.097064 -410.336061) (xy 49.055863 -410.300364) (xy 49.020162 -410.259167) (xy 48.990688 -410.213308)
			(xy 48.968041 -410.163721) (xy 48.952682 -410.111416) (xy 48.944923 -410.057457) (xy 7.00913 -410.057457)
			(xy 7.00913 -411.241049) (xy 101.876886 -411.241049) (xy 101.876886 -411.186551) (xy 101.884641 -411.132608)
			(xy 101.899994 -411.080318) (xy 101.922631 -411.030744) (xy 101.952093 -410.984897) (xy 101.98778 -410.943708)
			(xy 102.028964 -410.908017) (xy 102.074809 -410.878551) (xy 102.12438 -410.855908) (xy 102.176669 -410.840549)
			(xy 102.230611 -410.832788) (xy 102.25786 -410.8323) (xy 103.12146 -410.8323) (xy 103.148715 -410.832745)
			(xy 103.202672 -410.840497) (xy 103.254975 -410.85585) (xy 103.304562 -410.878491) (xy 103.350421 -410.907958)
			(xy 103.391619 -410.943653) (xy 103.427318 -410.984847) (xy 103.45679 -411.030703) (xy 103.479436 -411.080287)
			(xy 103.494794 -411.132589) (xy 103.502553 -411.186545) (xy 103.502553 -411.241055) (xy 103.494794 -411.295011)
			(xy 103.479436 -411.347313) (xy 103.45679 -411.396897) (xy 103.427318 -411.442753) (xy 103.391619 -411.483947)
			(xy 103.350421 -411.519642) (xy 103.304562 -411.549109) (xy 103.254975 -411.57175) (xy 103.202672 -411.587103)
			(xy 103.148715 -411.594855) (xy 103.12146 -411.595316) (xy 102.25786 -411.595316) (xy 102.230611 -411.594812)
			(xy 102.176669 -411.587051) (xy 102.12438 -411.571692) (xy 102.074809 -411.549049) (xy 102.028964 -411.519583)
			(xy 101.98778 -411.483892) (xy 101.952093 -411.442703) (xy 101.922631 -411.396856) (xy 101.899994 -411.347282)
			(xy 101.884641 -411.294992) (xy 101.876886 -411.241049) (xy 7.00913 -411.241049) (xy 7.00913 -424.470068)
			(xy 39.528496 -424.470068) (xy 39.528496 -417.770056) (xy 39.529001 -417.664532) (xy 39.537085 -417.453638)
			(xy 39.553241 -417.243209) (xy 39.577444 -417.033552) (xy 39.609661 -416.824977) (xy 39.649843 -416.617789)
			(xy 39.697931 -416.412292) (xy 39.753855 -416.208788) (xy 39.817532 -416.007575) (xy 39.88887 -415.808948)
			(xy 39.967764 -415.6132) (xy 40.054097 -415.420618) (xy 40.147744 -415.231483) (xy 40.248566 -415.046074)
			(xy 40.356416 -414.864663) (xy 40.471135 -414.687516) (xy 40.592555 -414.514894) (xy 40.720498 -414.347048)
			(xy 40.854776 -414.184226) (xy 40.995192 -414.026667) (xy 41.14154 -413.874602) (xy 41.293605 -413.728254)
			(xy 41.451164 -413.587838) (xy 41.613986 -413.45356) (xy 41.781832 -413.325617) (xy 41.954454 -413.204197)
			(xy 42.131601 -413.089478) (xy 42.313012 -412.981628) (xy 42.498421 -412.880806) (xy 42.687556 -412.787159)
			(xy 42.880138 -412.700826) (xy 43.075886 -412.621932) (xy 43.274513 -412.550594) (xy 43.475726 -412.486917)
			(xy 43.67923 -412.430993) (xy 43.884727 -412.382905) (xy 44.091915 -412.342723) (xy 44.30049 -412.310506)
			(xy 44.510147 -412.286303) (xy 44.720576 -412.270147) (xy 44.93147 -412.262063) (xy 45.142518 -412.262063)
			(xy 45.353412 -412.270147) (xy 45.563841 -412.286303) (xy 45.773498 -412.310506) (xy 45.982073 -412.342723)
			(xy 46.189261 -412.382905) (xy 46.394758 -412.430993) (xy 46.598262 -412.486917) (xy 46.799475 -412.550594)
			(xy 46.998102 -412.621932) (xy 47.19385 -412.700826) (xy 47.386432 -412.787159) (xy 47.575567 -412.880806)
			(xy 47.760976 -412.981628) (xy 47.942387 -413.089478) (xy 48.119534 -413.204197) (xy 48.292156 -413.325617)
			(xy 48.460002 -413.45356) (xy 48.622824 -413.587838) (xy 48.649451 -413.611568) (xy 104.877616 -413.611568)
			(xy 104.877616 -412.747968) (xy 104.878102 -412.720717) (xy 104.885858 -412.666769) (xy 104.901213 -412.614474)
			(xy 104.923855 -412.564897) (xy 104.953321 -412.519047) (xy 104.989012 -412.477856) (xy 105.030203 -412.442165)
			(xy 105.076053 -412.412699) (xy 105.12563 -412.390057) (xy 105.177925 -412.374702) (xy 105.231873 -412.366946)
			(xy 105.286375 -412.366946) (xy 105.340323 -412.374702) (xy 105.392618 -412.390057) (xy 105.442195 -412.412699)
			(xy 105.488045 -412.442165) (xy 105.529236 -412.477856) (xy 105.564927 -412.519047) (xy 105.594393 -412.564897)
			(xy 105.617035 -412.614474) (xy 105.63239 -412.666769) (xy 105.640146 -412.720717) (xy 105.640632 -412.747968)
			(xy 105.640632 -413.611568) (xy 105.640146 -413.638819) (xy 105.63239 -413.692767) (xy 105.617035 -413.745062)
			(xy 105.594393 -413.794639) (xy 105.584722 -413.809688) (xy 116.689632 -413.809688) (xy 116.689632 -412.946088)
			(xy 116.690118 -412.918837) (xy 116.697874 -412.864889) (xy 116.713229 -412.812594) (xy 116.735871 -412.763017)
			(xy 116.765337 -412.717167) (xy 116.801028 -412.675976) (xy 116.842219 -412.640285) (xy 116.888069 -412.610819)
			(xy 116.937646 -412.588177) (xy 116.989941 -412.572822) (xy 117.043889 -412.565066) (xy 117.098391 -412.565066)
			(xy 117.152339 -412.572822) (xy 117.204634 -412.588177) (xy 117.254211 -412.610819) (xy 117.300061 -412.640285)
			(xy 117.341252 -412.675976) (xy 117.376943 -412.717167) (xy 117.406409 -412.763017) (xy 117.429051 -412.812594)
			(xy 117.444406 -412.864889) (xy 117.452162 -412.918837) (xy 117.452648 -412.946088) (xy 117.452648 -413.809688)
			(xy 117.452162 -413.836939) (xy 117.444406 -413.890887) (xy 117.429051 -413.943182) (xy 117.406409 -413.992759)
			(xy 117.376943 -414.038609) (xy 117.341252 -414.0798) (xy 117.300061 -414.115491) (xy 117.254211 -414.144957)
			(xy 117.204634 -414.167599) (xy 117.152339 -414.182954) (xy 117.098391 -414.19071) (xy 117.043889 -414.19071)
			(xy 116.989941 -414.182954) (xy 116.937646 -414.167599) (xy 116.888069 -414.144957) (xy 116.842219 -414.115491)
			(xy 116.801028 -414.0798) (xy 116.765337 -414.038609) (xy 116.735871 -413.992759) (xy 116.713229 -413.943182)
			(xy 116.697874 -413.890887) (xy 116.690118 -413.836939) (xy 116.689632 -413.809688) (xy 105.584722 -413.809688)
			(xy 105.564927 -413.840489) (xy 105.529236 -413.88168) (xy 105.488045 -413.917371) (xy 105.442195 -413.946837)
			(xy 105.392618 -413.969479) (xy 105.340323 -413.984834) (xy 105.286375 -413.99259) (xy 105.231873 -413.99259)
			(xy 105.177925 -413.984834) (xy 105.12563 -413.969479) (xy 105.076053 -413.946837) (xy 105.030203 -413.917371)
			(xy 104.989012 -413.88168) (xy 104.953321 -413.840489) (xy 104.923855 -413.794639) (xy 104.901213 -413.745062)
			(xy 104.885858 -413.692767) (xy 104.878102 -413.638819) (xy 104.877616 -413.611568) (xy 48.649451 -413.611568)
			(xy 48.780383 -413.728254) (xy 48.932448 -413.874602) (xy 49.078796 -414.026667) (xy 49.219212 -414.184226)
			(xy 49.35349 -414.347048) (xy 49.481433 -414.514894) (xy 49.602853 -414.687516) (xy 49.717572 -414.864663)
			(xy 49.825422 -415.046074) (xy 49.926244 -415.231483) (xy 50.019891 -415.420618) (xy 50.106224 -415.6132)
			(xy 50.133819 -415.681668) (xy 100.559616 -415.681668) (xy 100.559616 -414.818068) (xy 100.560102 -414.790817)
			(xy 100.567858 -414.736869) (xy 100.583213 -414.684574) (xy 100.605855 -414.634997) (xy 100.635321 -414.589147)
			(xy 100.671012 -414.547956) (xy 100.712203 -414.512265) (xy 100.758053 -414.482799) (xy 100.80763 -414.460157)
			(xy 100.859925 -414.444802) (xy 100.913873 -414.437046) (xy 100.968375 -414.437046) (xy 101.022323 -414.444802)
			(xy 101.074618 -414.460157) (xy 101.124195 -414.482799) (xy 101.170045 -414.512265) (xy 101.211236 -414.547956)
			(xy 101.246927 -414.589147) (xy 101.276393 -414.634997) (xy 101.299035 -414.684574) (xy 101.31439 -414.736869)
			(xy 101.322146 -414.790817) (xy 101.322632 -414.818068) (xy 101.322632 -415.681668) (xy 101.322146 -415.708919)
			(xy 101.31439 -415.762867) (xy 101.299035 -415.815162) (xy 101.276393 -415.864739) (xy 101.246927 -415.910589)
			(xy 101.211236 -415.95178) (xy 101.170045 -415.987471) (xy 101.124195 -416.016937) (xy 101.074618 -416.039579)
			(xy 101.022323 -416.054934) (xy 100.968375 -416.06269) (xy 100.913873 -416.06269) (xy 100.859925 -416.054934)
			(xy 100.80763 -416.039579) (xy 100.758053 -416.016937) (xy 100.712203 -415.987471) (xy 100.671012 -415.95178)
			(xy 100.635321 -415.910589) (xy 100.605855 -415.864739) (xy 100.583213 -415.815162) (xy 100.567858 -415.762867)
			(xy 100.560102 -415.708919) (xy 100.559616 -415.681668) (xy 50.133819 -415.681668) (xy 50.185118 -415.808948)
			(xy 50.256456 -416.007575) (xy 50.320133 -416.208788) (xy 50.376057 -416.412292) (xy 50.424145 -416.617789)
			(xy 50.464327 -416.824977) (xy 50.496544 -417.033552) (xy 50.520747 -417.243209) (xy 50.536903 -417.453638)
			(xy 50.544987 -417.664532) (xy 50.545492 -417.770056) (xy 50.545492 -420.089838) (xy 58.13806 -420.089838)
			(xy 58.138171 -420.074752) (xy 58.139951 -420.044634) (xy 58.141616 -420.02964) (xy 58.141616 -418.95014)
			(xy 58.139949 -418.935146) (xy 58.138169 -418.905028) (xy 58.13806 -418.889942) (xy 58.138171 -418.874856)
			(xy 58.139951 -418.844738) (xy 58.141616 -418.829744) (xy 58.141616 -418.218874) (xy 58.142085 -418.206785)
			(xy 58.149546 -418.183788) (xy 58.163733 -418.164211) (xy 58.183264 -418.14996) (xy 58.206237 -418.142424)
			(xy 58.218324 -418.141912) (xy 59.158124 -418.141912) (xy 59.170235 -418.142296) (xy 59.193265 -418.149803)
			(xy 59.212839 -418.164073) (xy 59.227033 -418.183702) (xy 59.234451 -418.206761) (xy 59.234832 -418.218874)
			(xy 59.234832 -420.760398) (xy 59.23439 -420.77249) (xy 59.226931 -420.795495) (xy 59.212739 -420.815078)
			(xy 59.193198 -420.829327) (xy 59.170215 -420.836854) (xy 59.158124 -420.83736) (xy 58.218324 -420.83736)
			(xy 58.206212 -420.836963) (xy 58.183179 -420.829465) (xy 58.163602 -420.8152) (xy 58.149408 -420.795571)
			(xy 58.141994 -420.772511) (xy 58.141616 -420.760398) (xy 58.141616 -420.150036) (xy 58.139948 -420.135042)
			(xy 58.138169 -420.104924) (xy 58.13806 -420.089838) (xy 50.545492 -420.089838) (xy 50.545492 -421.089836)
			(xy 60.138056 -421.089836) (xy 60.138167 -421.07475) (xy 60.139947 -421.044632) (xy 60.141612 -421.029638)
			(xy 60.141612 -419.950138) (xy 60.139945 -419.935144) (xy 60.138165 -419.905026) (xy 60.138056 -419.88994)
			(xy 60.138167 -419.874854) (xy 60.139947 -419.844736) (xy 60.141612 -419.829742) (xy 60.141612 -419.218872)
			(xy 60.14204 -419.206794) (xy 60.149513 -419.183822) (xy 60.163718 -419.164284) (xy 60.183265 -419.150091)
			(xy 60.206242 -419.142633) (xy 60.21832 -419.142164) (xy 61.15812 -419.142164) (xy 61.170193 -419.142647)
			(xy 61.193156 -419.150112) (xy 61.21269 -419.164304) (xy 61.226885 -419.183837) (xy 61.234352 -419.206799)
			(xy 61.234828 -419.218872) (xy 61.234828 -421.089836) (xy 68.13804 -421.089836) (xy 68.138151 -421.07475)
			(xy 68.139931 -421.044632) (xy 68.141596 -421.029638) (xy 68.141596 -419.950138) (xy 68.139929 -419.935144)
			(xy 68.138149 -419.905026) (xy 68.13804 -419.88994) (xy 68.138151 -419.874854) (xy 68.139931 -419.844736)
			(xy 68.141596 -419.829742) (xy 68.141596 -419.218872) (xy 68.14204 -419.206796) (xy 68.149511 -419.183827)
			(xy 68.163712 -419.16429) (xy 68.183255 -419.150096) (xy 68.206227 -419.142635) (xy 68.218304 -419.142164)
			(xy 69.158104 -419.142164) (xy 69.170176 -419.14266) (xy 69.193139 -419.150121) (xy 69.212673 -419.16431)
			(xy 69.226868 -419.18384) (xy 69.234336 -419.2068) (xy 69.234812 -419.218872) (xy 69.234812 -420.089838)
			(xy 70.138036 -420.089838) (xy 70.138149 -420.074753) (xy 70.139929 -420.044634) (xy 70.141592 -420.02964)
			(xy 70.141592 -418.95014) (xy 70.139925 -418.935146) (xy 70.138145 -418.905028) (xy 70.138036 -418.889942)
			(xy 70.13815 -418.874857) (xy 70.139929 -418.844738) (xy 70.141592 -418.829744) (xy 70.141592 -418.218874)
			(xy 70.142084 -418.206788) (xy 70.149542 -418.183794) (xy 70.163724 -418.164219) (xy 70.183249 -418.149968)
			(xy 70.206216 -418.142428) (xy 70.2183 -418.141912) (xy 71.1581 -418.141912) (xy 71.17021 -418.142316)
			(xy 71.193239 -418.149817) (xy 71.212814 -418.164081) (xy 71.227008 -418.183706) (xy 71.234426 -418.206762)
			(xy 71.234808 -418.218874) (xy 71.234808 -420.760398) (xy 71.234292 -420.772483) (xy 71.226841 -420.795475)
			(xy 71.212666 -420.815051) (xy 71.193146 -420.829303) (xy 71.170183 -420.836844) (xy 71.1581 -420.83736)
			(xy 70.2183 -420.83736) (xy 70.206187 -420.836983) (xy 70.183153 -420.829479) (xy 70.163576 -420.815209)
			(xy 70.149383 -420.795576) (xy 70.14197 -420.772512) (xy 70.141592 -420.760398) (xy 70.141592 -420.150036)
			(xy 70.139924 -420.135042) (xy 70.138145 -420.104924) (xy 70.138036 -420.089838) (xy 69.234812 -420.089838)
			(xy 69.234812 -421.089836) (xy 72.138032 -421.089836) (xy 72.138145 -421.074751) (xy 72.139925 -421.044632)
			(xy 72.141588 -421.029638) (xy 72.141588 -419.950138) (xy 72.13992 -419.935144) (xy 72.138141 -419.905026)
			(xy 72.138032 -419.88994) (xy 72.138145 -419.874855) (xy 72.139925 -419.844736) (xy 72.141588 -419.829742)
			(xy 72.141588 -419.218872) (xy 72.14204 -419.206796) (xy 72.14951 -419.183829) (xy 72.16371 -419.164293)
			(xy 72.18325 -419.150099) (xy 72.20622 -419.142636) (xy 72.218296 -419.142164) (xy 73.158096 -419.142164)
			(xy 73.170168 -419.142667) (xy 73.19313 -419.150125) (xy 73.212665 -419.164313) (xy 73.22686 -419.183841)
			(xy 73.234328 -419.206801) (xy 73.234804 -419.218872) (xy 73.234804 -419.702852) (xy 110.957342 -419.702852)
			(xy 110.957342 -419.648348) (xy 110.965098 -419.594399) (xy 110.980453 -419.542102) (xy 111.003093 -419.492523)
			(xy 111.032558 -419.44667) (xy 111.068249 -419.405477) (xy 111.109438 -419.369782) (xy 111.155288 -419.340312)
			(xy 111.204865 -419.317667) (xy 111.25716 -419.302306) (xy 111.311108 -419.294545) (xy 111.33836 -419.294056)
			(xy 112.20196 -419.294056) (xy 112.229212 -419.294589) (xy 112.283162 -419.30234) (xy 112.33546 -419.317691)
			(xy 112.385041 -419.340329) (xy 112.430894 -419.369793) (xy 112.472088 -419.405484) (xy 112.507783 -419.446674)
			(xy 112.537251 -419.492524) (xy 112.559895 -419.542102) (xy 112.575251 -419.594399) (xy 112.583009 -419.648348)
			(xy 112.583009 -419.702852) (xy 112.575251 -419.756801) (xy 112.559895 -419.809098) (xy 112.537251 -419.858676)
			(xy 112.507783 -419.904526) (xy 112.472088 -419.945716) (xy 112.430894 -419.981407) (xy 112.385041 -420.010871)
			(xy 112.33546 -420.033509) (xy 112.283162 -420.04886) (xy 112.229212 -420.056611) (xy 112.20196 -420.057072)
			(xy 111.33836 -420.057072) (xy 111.311108 -420.056655) (xy 111.25716 -420.048894) (xy 111.204865 -420.033533)
			(xy 111.155288 -420.010888) (xy 111.109438 -419.981418) (xy 111.068249 -419.945723) (xy 111.032558 -419.90453)
			(xy 111.003093 -419.858677) (xy 110.980453 -419.809098) (xy 110.965098 -419.756801) (xy 110.957342 -419.702852)
			(xy 73.234804 -419.702852) (xy 73.234804 -421.760396) (xy 73.234384 -421.772479) (xy 73.226917 -421.795462)
			(xy 73.212713 -421.815013) (xy 73.193162 -421.829217) (xy 73.170179 -421.836684) (xy 73.158096 -421.837104)
			(xy 72.218296 -421.837104) (xy 72.206221 -421.836639) (xy 72.183253 -421.829175) (xy 72.163716 -421.814979)
			(xy 72.149521 -421.79544) (xy 72.14206 -421.772471) (xy 72.141588 -421.760396) (xy 72.141588 -421.150034)
			(xy 72.13992 -421.13504) (xy 72.138141 -421.104922) (xy 72.138032 -421.089836) (xy 69.234812 -421.089836)
			(xy 69.234812 -421.760396) (xy 69.234332 -421.77247) (xy 69.226871 -421.795436) (xy 69.212679 -421.814973)
			(xy 69.193143 -421.829168) (xy 69.170178 -421.836631) (xy 69.158104 -421.837104) (xy 68.218304 -421.837104)
			(xy 68.206221 -421.836684) (xy 68.183238 -421.829217) (xy 68.163687 -421.815013) (xy 68.149483 -421.795462)
			(xy 68.142016 -421.772479) (xy 68.141596 -421.760396) (xy 68.141596 -421.150034) (xy 68.139928 -421.13504)
			(xy 68.138149 -421.104922) (xy 68.13804 -421.089836) (xy 61.234828 -421.089836) (xy 61.234828 -421.760396)
			(xy 61.234333 -421.772468) (xy 61.226874 -421.795432) (xy 61.212684 -421.814967) (xy 61.193154 -421.829163)
			(xy 61.170192 -421.836629) (xy 61.15812 -421.837104) (xy 60.21832 -421.837104) (xy 60.206238 -421.83667)
			(xy 60.183255 -421.829208) (xy 60.163704 -421.815007) (xy 60.1495 -421.795459) (xy 60.142032 -421.772478)
			(xy 60.141612 -421.760396) (xy 60.141612 -421.150034) (xy 60.139944 -421.13504) (xy 60.138165 -421.104922)
			(xy 60.138056 -421.089836) (xy 50.545492 -421.089836) (xy 50.545492 -423.68978) (xy 58.13806 -423.68978)
			(xy 58.138175 -423.674695) (xy 58.139953 -423.644576) (xy 58.141616 -423.629582) (xy 58.141616 -422.550082)
			(xy 58.139952 -422.535088) (xy 58.138171 -422.50497) (xy 58.13806 -422.489884) (xy 58.138175 -422.474799)
			(xy 58.139953 -422.44468) (xy 58.141616 -422.429686) (xy 58.141616 -421.81907) (xy 58.142081 -421.806981)
			(xy 58.149543 -421.783984) (xy 58.163731 -421.764406) (xy 58.183263 -421.750156) (xy 58.206237 -421.74262)
			(xy 58.218324 -421.742108) (xy 59.158124 -421.742108) (xy 59.170235 -421.742496) (xy 59.193264 -421.750003)
			(xy 59.212838 -421.764272) (xy 59.227031 -421.783899) (xy 59.23445 -421.806958) (xy 59.234832 -421.81907)
			(xy 59.234832 -423.68978) (xy 62.138052 -423.68978) (xy 62.138167 -423.674695) (xy 62.139945 -423.644576)
			(xy 62.141608 -423.629582) (xy 62.141608 -422.550082) (xy 62.139944 -422.535088) (xy 62.138163 -422.50497)
			(xy 62.138052 -422.489884) (xy 62.138167 -422.474799) (xy 62.139945 -422.44468) (xy 62.141608 -422.429686)
			(xy 62.141608 -421.81907) (xy 62.142081 -421.806982) (xy 62.149542 -421.783986) (xy 62.163728 -421.764409)
			(xy 62.183258 -421.750158) (xy 62.20623 -421.742621) (xy 62.218316 -421.742108) (xy 63.158116 -421.742108)
			(xy 63.170227 -421.742503) (xy 63.193256 -421.750008) (xy 63.212829 -421.764274) (xy 63.227023 -421.783901)
			(xy 63.234442 -421.806958) (xy 63.234824 -421.81907) (xy 63.234824 -424.360594) (xy 63.234387 -424.372687)
			(xy 63.226927 -424.395693) (xy 63.212734 -424.415276) (xy 63.193192 -424.429526) (xy 63.170207 -424.437051)
			(xy 63.158116 -424.437556) (xy 62.218316 -424.437556) (xy 62.206214 -424.437071) (xy 62.183196 -424.429582)
			(xy 62.163628 -424.415337) (xy 62.149431 -424.395733) (xy 62.142 -424.372697) (xy 62.141608 -424.360594)
			(xy 62.141608 -423.749978) (xy 62.139944 -423.734984) (xy 62.138162 -423.704866) (xy 62.138052 -423.68978)
			(xy 59.234832 -423.68978) (xy 59.234832 -424.360594) (xy 59.234387 -424.372686) (xy 59.226928 -424.395691)
			(xy 59.212737 -424.415274) (xy 59.193197 -424.429523) (xy 59.170215 -424.43705) (xy 59.158124 -424.437556)
			(xy 58.218324 -424.437556) (xy 58.206222 -424.437064) (xy 58.183205 -424.429578) (xy 58.163637 -424.415334)
			(xy 58.149439 -424.395732) (xy 58.142008 -424.372697) (xy 58.141616 -424.360594) (xy 58.141616 -423.749978)
			(xy 58.139952 -423.734984) (xy 58.13817 -423.704866) (xy 58.13806 -423.68978) (xy 50.545492 -423.68978)
			(xy 50.545492 -424.470068) (xy 50.544987 -424.575592) (xy 50.54061 -424.689778) (xy 64.138048 -424.689778)
			(xy 64.138163 -424.674693) (xy 64.139941 -424.644574) (xy 64.141604 -424.62958) (xy 64.141604 -423.55008)
			(xy 64.13994 -423.535086) (xy 64.138158 -423.504968) (xy 64.138048 -423.489882) (xy 64.138163 -423.474797)
			(xy 64.139941 -423.444678) (xy 64.141604 -423.429684) (xy 64.141604 -422.819068) (xy 64.142037 -422.806991)
			(xy 64.14951 -422.78402) (xy 64.163714 -422.764483) (xy 64.18326 -422.75029) (xy 64.206234 -422.74283)
			(xy 64.218312 -422.74236) (xy 65.158112 -422.74236) (xy 65.170184 -422.742854) (xy 65.193146 -422.750316)
			(xy 65.21268 -422.764506) (xy 65.226875 -422.784036) (xy 65.234343 -422.806996) (xy 65.23482 -422.819068)
			(xy 65.23482 -424.689778) (xy 68.13804 -424.689778) (xy 68.138155 -424.674693) (xy 68.139933 -424.644574)
			(xy 68.141596 -424.62958) (xy 68.141596 -423.55008) (xy 68.139932 -423.535086) (xy 68.13815 -423.504968)
			(xy 68.13804 -423.489882) (xy 68.138155 -423.474797) (xy 68.139933 -423.444678) (xy 68.141596 -423.429684)
			(xy 68.141596 -422.819068) (xy 68.142037 -422.806991) (xy 68.149509 -422.784022) (xy 68.163711 -422.764485)
			(xy 68.183255 -422.750292) (xy 68.206227 -422.742831) (xy 68.218304 -422.74236) (xy 69.158104 -422.74236)
			(xy 69.170176 -422.74286) (xy 69.193137 -422.75032) (xy 69.212672 -422.764508) (xy 69.226867 -422.784037)
			(xy 69.234335 -422.806997) (xy 69.234812 -422.819068) (xy 69.234812 -423.68978) (xy 70.138036 -423.68978)
			(xy 70.138153 -423.674695) (xy 70.139931 -423.644576) (xy 70.141592 -423.629582) (xy 70.141592 -422.550082)
			(xy 70.139928 -422.535088) (xy 70.138147 -422.50497) (xy 70.138036 -422.489884) (xy 70.138153 -422.474799)
			(xy 70.139931 -422.44468) (xy 70.141592 -422.429686) (xy 70.141592 -421.81907) (xy 70.142081 -421.806984)
			(xy 70.14954 -421.78399) (xy 70.163723 -421.764415) (xy 70.183248 -421.750163) (xy 70.206215 -421.742624)
			(xy 70.2183 -421.742108) (xy 71.1581 -421.742108) (xy 71.17021 -421.742516) (xy 71.193238 -421.750017)
			(xy 71.212812 -421.76428) (xy 71.227007 -421.783904) (xy 71.234426 -421.806959) (xy 71.234808 -421.81907)
			(xy 71.234808 -424.360594) (xy 71.234288 -424.372678) (xy 71.226839 -424.395671) (xy 71.212664 -424.415247)
			(xy 71.193145 -424.429499) (xy 71.170183 -424.43704) (xy 71.1581 -424.437556) (xy 70.2183 -424.437556)
			(xy 70.206197 -424.437085) (xy 70.183179 -424.429592) (xy 70.163611 -424.415343) (xy 70.149414 -424.395736)
			(xy 70.141983 -424.372698) (xy 70.141592 -424.360594) (xy 70.141592 -423.749978) (xy 70.139928 -423.734984)
			(xy 70.138146 -423.704866) (xy 70.138036 -423.68978) (xy 69.234812 -423.68978) (xy 69.234812 -424.689778)
			(xy 72.138032 -424.689778) (xy 72.138149 -424.674693) (xy 72.139927 -424.644574) (xy 72.141588 -424.62958)
			(xy 72.141588 -423.55008) (xy 72.139924 -423.535086) (xy 72.138142 -423.504968) (xy 72.138032 -423.489882)
			(xy 72.138149 -423.474797) (xy 72.139927 -423.444678) (xy 72.141588 -423.429684) (xy 72.141588 -422.819068)
			(xy 72.142037 -422.806992) (xy 72.149508 -422.784025) (xy 72.163708 -422.764488) (xy 72.18325 -422.750295)
			(xy 72.20622 -422.742832) (xy 72.218296 -422.74236) (xy 73.158096 -422.74236) (xy 73.170167 -422.742867)
			(xy 73.193129 -422.750325) (xy 73.212663 -422.764511) (xy 73.226859 -422.784039) (xy 73.234327 -422.806997)
			(xy 73.234804 -422.819068) (xy 73.234804 -424.80464) (xy 109.929157 -424.80464) (xy 109.929157 -424.6755)
			(xy 109.937107 -424.546605) (xy 109.952977 -424.418445) (xy 109.976706 -424.291504) (xy 110.008205 -424.166265)
			(xy 110.047354 -424.043202) (xy 110.094005 -423.922783) (xy 110.14798 -423.805464) (xy 110.209075 -423.69169)
			(xy 110.277058 -423.581893) (xy 110.351672 -423.47649) (xy 110.432633 -423.37588) (xy 110.519633 -423.280445)
			(xy 110.612344 -423.190546) (xy 110.710414 -423.106525) (xy 110.813469 -423.028701) (xy 110.92112 -422.957369)
			(xy 111.032959 -422.892799) (xy 111.14856 -422.835237) (xy 111.267485 -422.7849) (xy 111.389284 -422.74198)
			(xy 111.513494 -422.706639) (xy 111.639643 -422.679012) (xy 111.767255 -422.659203) (xy 111.895844 -422.647287)
			(xy 112.024922 -422.643311) (xy 112.154 -422.647287) (xy 112.282589 -422.659203) (xy 112.410201 -422.679012)
			(xy 112.53635 -422.706639) (xy 112.66056 -422.74198) (xy 112.782359 -422.7849) (xy 112.901284 -422.835237)
			(xy 113.016885 -422.892799) (xy 113.128724 -422.957369) (xy 113.236375 -423.028701) (xy 113.33943 -423.106525)
			(xy 113.4375 -423.190546) (xy 113.530211 -423.280445) (xy 113.617211 -423.37588) (xy 113.698172 -423.47649)
			(xy 113.772786 -423.581893) (xy 113.840769 -423.69169) (xy 113.901864 -423.805464) (xy 113.955839 -423.922783)
			(xy 114.00249 -424.043202) (xy 114.041639 -424.166265) (xy 114.073138 -424.291504) (xy 114.096867 -424.418445)
			(xy 114.112737 -424.546605) (xy 114.120687 -424.6755) (xy 114.121184 -424.74007) (xy 114.120687 -424.80464)
			(xy 114.112737 -424.933535) (xy 114.096867 -425.061695) (xy 114.073138 -425.188636) (xy 114.041639 -425.313875)
			(xy 114.00249 -425.436938) (xy 113.955839 -425.557357) (xy 113.901864 -425.674676) (xy 113.840769 -425.78845)
			(xy 113.772786 -425.898247) (xy 113.698172 -426.00365) (xy 113.617211 -426.10426) (xy 113.530211 -426.199695)
			(xy 113.4375 -426.289594) (xy 113.33943 -426.373615) (xy 113.236375 -426.451439) (xy 113.128724 -426.522771)
			(xy 113.016885 -426.587341) (xy 112.901284 -426.644903) (xy 112.782359 -426.69524) (xy 112.66056 -426.73816)
			(xy 112.53635 -426.773501) (xy 112.410201 -426.801128) (xy 112.282589 -426.820937) (xy 112.154 -426.832853)
			(xy 112.024922 -426.83683) (xy 111.895844 -426.832853) (xy 111.767255 -426.820937) (xy 111.639643 -426.801128)
			(xy 111.513494 -426.773501) (xy 111.389284 -426.73816) (xy 111.267485 -426.69524) (xy 111.14856 -426.644903)
			(xy 111.032959 -426.587341) (xy 110.92112 -426.522771) (xy 110.813469 -426.451439) (xy 110.710414 -426.373615)
			(xy 110.612344 -426.289594) (xy 110.519633 -426.199695) (xy 110.432633 -426.10426) (xy 110.351672 -426.00365)
			(xy 110.277058 -425.898247) (xy 110.209075 -425.78845) (xy 110.14798 -425.674676) (xy 110.094005 -425.557357)
			(xy 110.047354 -425.436938) (xy 110.008205 -425.313875) (xy 109.976706 -425.188636) (xy 109.952977 -425.061695)
			(xy 109.937107 -424.933535) (xy 109.929157 -424.80464) (xy 73.234804 -424.80464) (xy 73.234804 -425.360592)
			(xy 73.234381 -425.372675) (xy 73.226915 -425.395658) (xy 73.212712 -425.415209) (xy 73.193162 -425.429413)
			(xy 73.170179 -425.43688) (xy 73.158096 -425.4373) (xy 72.218296 -425.4373) (xy 72.206212 -425.436891)
			(xy 72.183228 -425.429421) (xy 72.163677 -425.415214) (xy 72.149473 -425.395661) (xy 72.142007 -425.372676)
			(xy 72.141588 -425.360592) (xy 72.141588 -424.749976) (xy 72.139924 -424.734982) (xy 72.138142 -424.704864)
			(xy 72.138032 -424.689778) (xy 69.234812 -424.689778) (xy 69.234812 -425.360592) (xy 69.234381 -425.372674)
			(xy 69.226916 -425.395656) (xy 69.212714 -425.415206) (xy 69.193167 -425.429411) (xy 69.170186 -425.436879)
			(xy 69.158104 -425.4373) (xy 68.218304 -425.4373) (xy 68.206221 -425.436884) (xy 68.183237 -425.429417)
			(xy 68.163686 -425.415212) (xy 68.149482 -425.39566) (xy 68.142015 -425.372675) (xy 68.141596 -425.360592)
			(xy 68.141596 -424.749976) (xy 68.139932 -424.734982) (xy 68.13815 -424.704864) (xy 68.13804 -424.689778)
			(xy 65.23482 -424.689778) (xy 65.23482 -425.360592) (xy 65.234329 -425.372665) (xy 65.22687 -425.39563)
			(xy 65.21268 -425.415166) (xy 65.193148 -425.429361) (xy 65.170185 -425.436826) (xy 65.158112 -425.4373)
			(xy 64.218312 -425.4373) (xy 64.206229 -425.436877) (xy 64.183246 -425.429412) (xy 64.163694 -425.415208)
			(xy 64.14949 -425.395658) (xy 64.142024 -425.372675) (xy 64.141604 -425.360592) (xy 64.141604 -424.749976)
			(xy 64.13994 -424.734982) (xy 64.138158 -424.704864) (xy 64.138048 -424.689778) (xy 50.54061 -424.689778)
			(xy 50.536903 -424.786486) (xy 50.520747 -424.996915) (xy 50.496544 -425.206572) (xy 50.464327 -425.415147)
			(xy 50.424145 -425.622335) (xy 50.376057 -425.827832) (xy 50.320133 -426.031336) (xy 50.256456 -426.232549)
			(xy 50.185118 -426.431176) (xy 50.106224 -426.626924) (xy 50.019891 -426.819506) (xy 49.926244 -427.008641)
			(xy 49.825422 -427.19405) (xy 49.768393 -427.289976) (xy 58.13806 -427.289976) (xy 58.138174 -427.274891)
			(xy 58.139952 -427.244772) (xy 58.141616 -427.229778) (xy 58.141616 -426.150024) (xy 58.139947 -426.135031)
			(xy 58.138169 -426.104912) (xy 58.13806 -426.089826) (xy 58.13817 -426.07474) (xy 58.139951 -426.044622)
			(xy 58.141616 -426.029628) (xy 58.141616 -425.419012) (xy 58.142023 -425.406928) (xy 58.149491 -425.383941)
			(xy 58.163697 -425.364389) (xy 58.183252 -425.350185) (xy 58.206239 -425.342722) (xy 58.218324 -425.342304)
			(xy 59.158124 -425.342304) (xy 59.170201 -425.342744) (xy 59.193171 -425.350215) (xy 59.212709 -425.364417)
			(xy 59.226902 -425.383961) (xy 59.234361 -425.406935) (xy 59.234832 -425.419012) (xy 59.234832 -427.960536)
			(xy 59.234367 -427.97261) (xy 59.226898 -427.995574) (xy 59.2127 -428.015109) (xy 59.193164 -428.029303)
			(xy 59.170198 -428.036769) (xy 59.158124 -428.037244) (xy 58.218324 -428.037244) (xy 58.206254 -428.036716)
			(xy 58.183294 -428.029264) (xy 58.16376 -428.015083) (xy 58.149563 -427.99556) (xy 58.142093 -427.972605)
			(xy 58.141616 -427.960536) (xy 58.141616 -427.350174) (xy 58.139952 -427.33518) (xy 58.13817 -427.305062)
			(xy 58.13806 -427.289976) (xy 49.768393 -427.289976) (xy 49.717572 -427.375461) (xy 49.602853 -427.552608)
			(xy 49.481433 -427.72523) (xy 49.35349 -427.893076) (xy 49.219212 -428.055898) (xy 49.078796 -428.213457)
			(xy 49.0054 -428.28972) (xy 60.138056 -428.28972) (xy 60.138166 -428.274634) (xy 60.139947 -428.244516)
			(xy 60.141612 -428.229522) (xy 60.141612 -427.150022) (xy 60.139943 -427.135029) (xy 60.138165 -427.10491)
			(xy 60.138056 -427.089824) (xy 60.138166 -427.074738) (xy 60.139947 -427.04462) (xy 60.141612 -427.029626)
			(xy 60.141612 -426.41901) (xy 60.142115 -426.406924) (xy 60.149566 -426.383928) (xy 60.163744 -426.364351)
			(xy 60.183268 -426.350099) (xy 60.206236 -426.342562) (xy 60.21832 -426.342048) (xy 61.15812 -426.342048)
			(xy 61.170225 -426.342499) (xy 61.193244 -426.349997) (xy 61.212812 -426.364252) (xy 61.227008 -426.383863)
			(xy 61.234437 -426.406904) (xy 61.234828 -426.41901) (xy 61.234828 -427.289976) (xy 62.138052 -427.289976)
			(xy 62.138166 -427.274891) (xy 62.139944 -427.244772) (xy 62.141608 -427.229778) (xy 62.141608 -426.150024)
			(xy 62.139939 -426.135031) (xy 62.138161 -426.104912) (xy 62.138052 -426.089826) (xy 62.138162 -426.07474)
			(xy 62.139943 -426.044622) (xy 62.141608 -426.029628) (xy 62.141608 -425.419012) (xy 62.142023 -425.406928)
			(xy 62.149489 -425.383943) (xy 62.163694 -425.364392) (xy 62.183247 -425.350188) (xy 62.206232 -425.342723)
			(xy 62.218316 -425.342304) (xy 63.158116 -425.342304) (xy 63.170193 -425.342751) (xy 63.193162 -425.350219)
			(xy 63.2127 -425.36442) (xy 63.226894 -425.383963) (xy 63.234353 -425.406935) (xy 63.234824 -425.419012)
			(xy 63.234824 -427.960536) (xy 63.234367 -427.972611) (xy 63.226896 -427.995577) (xy 63.212697 -428.015112)
			(xy 63.193159 -428.029306) (xy 63.170191 -428.03677) (xy 63.158116 -428.037244) (xy 62.218316 -428.037244)
			(xy 62.206246 -428.036723) (xy 62.183285 -428.029269) (xy 62.163751 -428.015086) (xy 62.149555 -427.995561)
			(xy 62.142085 -427.972606) (xy 62.141608 -427.960536) (xy 62.141608 -427.350174) (xy 62.139944 -427.33518)
			(xy 62.138162 -427.305062) (xy 62.138052 -427.289976) (xy 61.234828 -427.289976) (xy 61.234828 -428.28972)
			(xy 64.138048 -428.28972) (xy 64.138158 -428.274634) (xy 64.139939 -428.244516) (xy 64.141604 -428.229522)
			(xy 64.141604 -427.150022) (xy 64.139935 -427.135029) (xy 64.138157 -427.10491) (xy 64.138048 -427.089824)
			(xy 64.138158 -427.074738) (xy 64.139939 -427.04462) (xy 64.141604 -427.029626) (xy 64.141604 -426.41901)
			(xy 64.142115 -426.406925) (xy 64.149565 -426.38393) (xy 64.163741 -426.364353) (xy 64.183263 -426.350101)
			(xy 64.206228 -426.342563) (xy 64.218312 -426.342048) (xy 65.158112 -426.342048) (xy 65.170216 -426.342505)
			(xy 65.193235 -426.350002) (xy 65.212804 -426.364255) (xy 65.227 -426.383864) (xy 65.234429 -426.406905)
			(xy 65.23482 -426.41901) (xy 65.23482 -427.289976) (xy 66.138044 -427.289976) (xy 66.138159 -427.274891)
			(xy 66.139936 -427.244772) (xy 66.1416 -427.229778) (xy 66.1416 -426.150024) (xy 66.139931 -426.135031)
			(xy 66.138153 -426.104912) (xy 66.138044 -426.089826) (xy 66.138154 -426.07474) (xy 66.139935 -426.044622)
			(xy 66.1416 -426.029628) (xy 66.1416 -425.419012) (xy 66.142023 -425.406929) (xy 66.149488 -425.383946)
			(xy 66.163692 -425.364394) (xy 66.183242 -425.35019) (xy 66.206225 -425.342724) (xy 66.218308 -425.342304)
			(xy 67.158108 -425.342304) (xy 67.170192 -425.342706) (xy 67.193177 -425.350177) (xy 67.212729 -425.364386)
			(xy 67.226932 -425.383941) (xy 67.234397 -425.406928) (xy 67.234816 -425.419012) (xy 67.234816 -427.960536)
			(xy 67.234367 -427.972612) (xy 67.226895 -427.995579) (xy 67.212695 -428.015115) (xy 67.193154 -428.029308)
			(xy 67.170184 -428.036771) (xy 67.158108 -428.037244) (xy 66.218308 -428.037244) (xy 66.206237 -428.03673)
			(xy 66.183277 -428.029274) (xy 66.163743 -428.015089) (xy 66.149547 -427.995563) (xy 66.142077 -427.972606)
			(xy 66.1416 -427.960536) (xy 66.1416 -427.350174) (xy 66.139936 -427.33518) (xy 66.138154 -427.305062)
			(xy 66.138044 -427.289976) (xy 65.23482 -427.289976) (xy 65.23482 -428.28972) (xy 68.13804 -428.28972)
			(xy 68.138152 -428.274634) (xy 68.139933 -428.244516) (xy 68.141596 -428.229522) (xy 68.141596 -427.150022)
			(xy 68.139927 -427.135029) (xy 68.138149 -427.10491) (xy 68.13804 -427.089824) (xy 68.13815 -427.074738)
			(xy 68.139931 -427.04462) (xy 68.141596 -427.029626) (xy 68.141596 -426.41901) (xy 68.142115 -426.406925)
			(xy 68.149564 -426.383932) (xy 68.163739 -426.364356) (xy 68.183258 -426.350104) (xy 68.206221 -426.342564)
			(xy 68.218304 -426.342048) (xy 69.158104 -426.342048) (xy 69.170208 -426.342512) (xy 69.193227 -426.350006)
			(xy 69.212795 -426.364257) (xy 69.226991 -426.383866) (xy 69.234421 -426.406905) (xy 69.234812 -426.41901)
			(xy 69.234812 -427.289976) (xy 70.138036 -427.289976) (xy 70.138153 -427.274891) (xy 70.13993 -427.244772)
			(xy 70.141592 -427.229778) (xy 70.141592 -426.150024) (xy 70.139923 -426.135031) (xy 70.138145 -426.104912)
			(xy 70.138036 -426.089826) (xy 70.138148 -426.07474) (xy 70.139929 -426.044622) (xy 70.141592 -426.029628)
			(xy 70.141592 -425.419012) (xy 70.142023 -425.40693) (xy 70.149487 -425.383948) (xy 70.163689 -425.364397)
			(xy 70.183237 -425.350193) (xy 70.206218 -425.342725) (xy 70.2183 -425.342304) (xy 71.1581 -425.342304)
			(xy 71.170184 -425.342713) (xy 71.193169 -425.350182) (xy 71.21272 -425.364388) (xy 71.226924 -425.383942)
			(xy 71.234389 -425.406928) (xy 71.234808 -425.419012) (xy 71.234808 -427.960536) (xy 71.234367 -427.972612)
			(xy 71.226894 -427.995581) (xy 71.212692 -428.015117) (xy 71.193149 -428.029311) (xy 71.170177 -428.036772)
			(xy 71.1581 -428.037244) (xy 70.2183 -428.037244) (xy 70.206229 -428.036736) (xy 70.183268 -428.029278)
			(xy 70.163734 -428.015092) (xy 70.149538 -427.995564) (xy 70.142069 -427.972607) (xy 70.141592 -427.960536)
			(xy 70.141592 -427.350174) (xy 70.139928 -427.33518) (xy 70.138146 -427.305062) (xy 70.138036 -427.289976)
			(xy 69.234812 -427.289976) (xy 69.234812 -428.28972) (xy 72.138032 -428.28972) (xy 72.138144 -428.274634)
			(xy 72.139925 -428.244516) (xy 72.141588 -428.229522) (xy 72.141588 -427.150022) (xy 72.139919 -427.135029)
			(xy 72.138141 -427.10491) (xy 72.138032 -427.089824) (xy 72.138144 -427.074738) (xy 72.139925 -427.04462)
			(xy 72.141588 -427.029626) (xy 72.141588 -426.41901) (xy 72.142017 -426.406916) (xy 72.149477 -426.383908)
			(xy 72.163671 -426.364324) (xy 72.183216 -426.350075) (xy 72.206204 -426.342551) (xy 72.218296 -426.342048)
			(xy 73.158096 -426.342048) (xy 73.170199 -426.342519) (xy 73.193218 -426.350011) (xy 73.212787 -426.36426)
			(xy 73.226983 -426.383867) (xy 73.234413 -426.406905) (xy 73.234804 -426.41901) (xy 73.234804 -427.289976)
			(xy 75.138026 -427.289976) (xy 75.138117 -427.275402) (xy 75.139771 -427.246301) (xy 75.141328 -427.23181)
			(xy 75.141328 -426.147992) (xy 75.139785 -426.1335) (xy 75.138132 -426.1044) (xy 75.138026 -426.089826)
			(xy 75.138121 -426.075252) (xy 75.139773 -426.046151) (xy 75.141328 -426.03166) (xy 75.141328 -425.419012)
			(xy 75.141727 -425.406901) (xy 75.149227 -425.383869) (xy 75.163492 -425.364294) (xy 75.183119 -425.3501)
			(xy 75.206178 -425.342684) (xy 75.21829 -425.342304) (xy 76.15809 -425.342304) (xy 76.170175 -425.342815)
			(xy 76.19317 -425.350265) (xy 76.212747 -425.364441) (xy 76.226999 -425.383963) (xy 76.234537 -425.406928)
			(xy 76.235052 -425.419012) (xy 76.235052 -427.960536) (xy 76.234615 -427.972642) (xy 76.227112 -427.995661)
			(xy 76.212854 -428.015229) (xy 76.19324 -428.029424) (xy 76.170197 -428.036854) (xy 76.15809 -428.037244)
			(xy 75.21829 -428.037244) (xy 75.206198 -428.036801) (xy 75.183195 -428.029339) (xy 75.163614 -428.015147)
			(xy 75.149364 -427.995608) (xy 75.141835 -427.972626) (xy 75.141328 -427.960536) (xy 75.141328 -427.348142)
			(xy 75.139781 -427.33365) (xy 75.138131 -427.30455) (xy 75.138026 -427.289976) (xy 73.234804 -427.289976)
			(xy 73.234804 -428.28972) (xy 77.138022 -428.28972) (xy 77.138117 -428.275146) (xy 77.139768 -428.246045)
			(xy 77.141324 -428.231554) (xy 77.141324 -427.14799) (xy 77.139781 -427.133498) (xy 77.138128 -427.104398)
			(xy 77.138022 -427.089824) (xy 77.138117 -427.07525) (xy 77.139769 -427.046149) (xy 77.141324 -427.031658)
			(xy 77.141324 -426.41901) (xy 77.14182 -426.406897) (xy 77.149303 -426.383857) (xy 77.163539 -426.364256)
			(xy 77.183135 -426.350014) (xy 77.206174 -426.342524) (xy 77.218286 -426.342048) (xy 78.158086 -426.342048)
			(xy 78.170209 -426.342472) (xy 78.193269 -426.349962) (xy 78.212885 -426.364212) (xy 78.227136 -426.383827)
			(xy 78.234627 -426.406887) (xy 78.235048 -426.41901) (xy 78.235048 -427.289976) (xy 79.138018 -427.289976)
			(xy 79.138109 -427.275402) (xy 79.139763 -427.246301) (xy 79.14132 -427.23181) (xy 79.14132 -426.147992)
			(xy 79.139777 -426.1335) (xy 79.138124 -426.1044) (xy 79.138018 -426.089826) (xy 79.138113 -426.075252)
			(xy 79.139765 -426.046151) (xy 79.14132 -426.03166) (xy 79.14132 -425.419012) (xy 79.141727 -425.406902)
			(xy 79.149226 -425.383872) (xy 79.163489 -425.364297) (xy 79.183114 -425.350102) (xy 79.20617 -425.342685)
			(xy 79.218282 -425.342304) (xy 80.158082 -425.342304) (xy 80.170167 -425.342822) (xy 80.193161 -425.35027)
			(xy 80.212738 -425.364444) (xy 80.226991 -425.383965) (xy 80.234529 -425.406929) (xy 80.235044 -425.419012)
			(xy 80.235044 -427.960536) (xy 80.234615 -427.972642) (xy 80.227111 -427.995663) (xy 80.212851 -428.015232)
			(xy 80.193235 -428.029427) (xy 80.17019 -428.036855) (xy 80.158082 -428.037244) (xy 79.218282 -428.037244)
			(xy 79.20619 -428.036808) (xy 79.183186 -428.029344) (xy 79.163605 -428.01515) (xy 79.149355 -427.995609)
			(xy 79.141827 -427.972627) (xy 79.14132 -427.960536) (xy 79.14132 -427.348142) (xy 79.139773 -427.33365)
			(xy 79.138123 -427.30455) (xy 79.138018 -427.289976) (xy 78.235048 -427.289976) (xy 78.235048 -428.28972)
			(xy 81.138014 -428.28972) (xy 81.138108 -428.275146) (xy 81.13976 -428.246045) (xy 81.141316 -428.231554)
			(xy 81.141316 -427.14799) (xy 81.139773 -427.133498) (xy 81.13812 -427.104398) (xy 81.138014 -427.089824)
			(xy 81.138108 -427.07525) (xy 81.13976 -427.046149) (xy 81.141316 -427.031658) (xy 81.141316 -426.41901)
			(xy 81.14182 -426.406898) (xy 81.149302 -426.383859) (xy 81.163536 -426.364259) (xy 81.18313 -426.350016)
			(xy 81.206166 -426.342525) (xy 81.218278 -426.342048) (xy 82.158078 -426.342048) (xy 82.170201 -426.342479)
			(xy 82.19326 -426.349966) (xy 82.212877 -426.364215) (xy 82.227128 -426.383829) (xy 82.234619 -426.406887)
			(xy 82.23504 -426.41901) (xy 82.23504 -427.289976) (xy 83.13801 -427.289976) (xy 83.1381 -427.275402)
			(xy 83.139755 -427.246301) (xy 83.141312 -427.23181) (xy 83.141312 -426.147992) (xy 83.139769 -426.1335)
			(xy 83.138116 -426.1044) (xy 83.13801 -426.089826) (xy 83.138105 -426.075252) (xy 83.139756 -426.046151)
			(xy 83.141312 -426.03166) (xy 83.141312 -425.419012) (xy 83.141727 -425.406903) (xy 83.149224 -425.383874)
			(xy 83.163486 -425.364299) (xy 83.183109 -425.350105) (xy 83.206163 -425.342686) (xy 83.218274 -425.342304)
			(xy 84.158074 -425.342304) (xy 84.170159 -425.342829) (xy 84.193152 -425.350274) (xy 84.21273 -425.364447)
			(xy 84.226982 -425.383966) (xy 84.234521 -425.406929) (xy 84.235036 -425.419012) (xy 84.235036 -427.960536)
			(xy 84.234615 -427.972643) (xy 84.22711 -427.995665) (xy 84.212848 -428.015235) (xy 84.19323 -428.029429)
			(xy 84.170183 -428.036856) (xy 84.158074 -428.037244) (xy 83.218274 -428.037244) (xy 83.206181 -428.036815)
			(xy 83.183177 -428.029349) (xy 83.163596 -428.015153) (xy 83.149347 -427.995611) (xy 83.141819 -427.972627)
			(xy 83.141312 -427.960536) (xy 83.141312 -427.348142) (xy 83.139765 -427.33365) (xy 83.138115 -427.30455)
			(xy 83.13801 -427.289976) (xy 82.23504 -427.289976) (xy 82.23504 -428.28972) (xy 85.138006 -428.28972)
			(xy 85.1381 -428.275146) (xy 85.139752 -428.246045) (xy 85.141308 -428.231554) (xy 85.141308 -427.14799)
			(xy 85.139765 -427.133498) (xy 85.138112 -427.104398) (xy 85.138006 -427.089824) (xy 85.1381 -427.07525)
			(xy 85.139752 -427.046149) (xy 85.141308 -427.031658) (xy 85.141308 -426.41901) (xy 85.14182 -426.406899)
			(xy 85.149301 -426.383861) (xy 85.163533 -426.364262) (xy 85.183125 -426.350019) (xy 85.206159 -426.342526)
			(xy 85.21827 -426.342048) (xy 86.15807 -426.342048) (xy 86.170192 -426.342486) (xy 86.193252 -426.349971)
			(xy 86.212868 -426.364218) (xy 86.22712 -426.38383) (xy 86.234611 -426.406888) (xy 86.235032 -426.41901)
			(xy 86.235032 -427.289976) (xy 87.138002 -427.289976) (xy 87.138092 -427.275402) (xy 87.139747 -427.246301)
			(xy 87.141304 -427.23181) (xy 87.141304 -426.147992) (xy 87.139761 -426.1335) (xy 87.138108 -426.1044)
			(xy 87.138002 -426.089826) (xy 87.138097 -426.075252) (xy 87.139748 -426.046151) (xy 87.141304 -426.03166)
			(xy 87.141304 -425.419012) (xy 87.141727 -425.406903) (xy 87.149223 -425.383876) (xy 87.163483 -425.364302)
			(xy 87.183104 -425.350107) (xy 87.206156 -425.342687) (xy 87.218266 -425.342304) (xy 88.158066 -425.342304)
			(xy 88.17015 -425.342836) (xy 88.193144 -425.350279) (xy 88.212721 -425.36445) (xy 88.226974 -425.383968)
			(xy 88.234513 -425.40693) (xy 88.235028 -425.419012) (xy 88.235028 -427.960536) (xy 88.234615 -427.972644)
			(xy 88.227109 -427.995668) (xy 88.212845 -428.015238) (xy 88.193225 -428.029432) (xy 88.170175 -428.036857)
			(xy 88.158066 -428.037244) (xy 87.218266 -428.037244) (xy 87.206173 -428.036821) (xy 87.183169 -428.029353)
			(xy 87.163588 -428.015156) (xy 87.149339 -427.995612) (xy 87.141811 -427.972628) (xy 87.141304 -427.960536)
			(xy 87.141304 -427.348142) (xy 87.139757 -427.33365) (xy 87.138107 -427.30455) (xy 87.138002 -427.289976)
			(xy 86.235032 -427.289976) (xy 86.235032 -428.28972) (xy 89.137998 -428.28972) (xy 89.138092 -428.275146)
			(xy 89.139744 -428.246045) (xy 89.1413 -428.231554) (xy 89.1413 -427.14799) (xy 89.139757 -427.133498)
			(xy 89.138104 -427.104398) (xy 89.137998 -427.089824) (xy 89.138092 -427.07525) (xy 89.139744 -427.046149)
			(xy 89.1413 -427.031658) (xy 89.1413 -426.41901) (xy 89.14182 -426.4069) (xy 89.1493 -426.383863)
			(xy 89.163531 -426.364265) (xy 89.18312 -426.350022) (xy 89.206152 -426.342527) (xy 89.218262 -426.342048)
			(xy 90.158062 -426.342048) (xy 90.170184 -426.342492) (xy 90.193243 -426.349975) (xy 90.21286 -426.36422)
			(xy 90.227112 -426.383832) (xy 90.234603 -426.406888) (xy 90.235024 -426.41901) (xy 90.235024 -427.289976)
			(xy 125.238002 -427.289976) (xy 125.238092 -427.275402) (xy 125.239747 -427.246301) (xy 125.241304 -427.23181)
			(xy 125.241304 -426.147992) (xy 125.239761 -426.1335) (xy 125.238108 -426.1044) (xy 125.238002 -426.089826)
			(xy 125.238097 -426.075252) (xy 125.239748 -426.046151) (xy 125.241304 -426.03166) (xy 125.241304 -425.419012)
			(xy 125.241727 -425.406903) (xy 125.249223 -425.383876) (xy 125.263483 -425.364302) (xy 125.283104 -425.350107)
			(xy 125.306156 -425.342687) (xy 125.318266 -425.342304) (xy 126.258066 -425.342304) (xy 126.27015 -425.342836)
			(xy 126.293144 -425.350279) (xy 126.312721 -425.36445) (xy 126.326974 -425.383968) (xy 126.334513 -425.40693)
			(xy 126.335028 -425.419012) (xy 126.335028 -427.960536) (xy 126.334615 -427.972644) (xy 126.327109 -427.995668)
			(xy 126.312845 -428.015238) (xy 126.293225 -428.029432) (xy 126.270175 -428.036857) (xy 126.258066 -428.037244)
			(xy 125.318266 -428.037244) (xy 125.306173 -428.036821) (xy 125.283169 -428.029353) (xy 125.263588 -428.015156)
			(xy 125.249339 -427.995612) (xy 125.241811 -427.972628) (xy 125.241304 -427.960536) (xy 125.241304 -427.348142)
			(xy 125.239757 -427.33365) (xy 125.238107 -427.30455) (xy 125.238002 -427.289976) (xy 90.235024 -427.289976)
			(xy 90.235024 -428.960534) (xy 90.234669 -428.972662) (xy 90.227162 -428.995729) (xy 90.212895 -429.015347)
			(xy 90.193264 -429.029595) (xy 90.170191 -429.03708) (xy 90.158062 -429.037496) (xy 89.218262 -429.037496)
			(xy 89.206149 -429.037021) (xy 89.18311 -429.029528) (xy 89.163512 -429.015285) (xy 89.14927 -428.995686)
			(xy 89.141778 -428.972647) (xy 89.1413 -428.960534) (xy 89.1413 -428.347886) (xy 89.139757 -428.333394)
			(xy 89.138104 -428.304294) (xy 89.137998 -428.28972) (xy 86.235032 -428.28972) (xy 86.235032 -428.960534)
			(xy 86.234617 -428.972653) (xy 86.227117 -428.995703) (xy 86.212861 -429.015307) (xy 86.193245 -429.029546)
			(xy 86.17019 -429.037027) (xy 86.15807 -429.037496) (xy 85.21827 -429.037496) (xy 85.206157 -429.037014)
			(xy 85.183119 -429.029523) (xy 85.16352 -429.015282) (xy 85.149279 -428.995685) (xy 85.141786 -428.972647)
			(xy 85.141308 -428.960534) (xy 85.141308 -428.347886) (xy 85.139765 -428.333394) (xy 85.138112 -428.304294)
			(xy 85.138006 -428.28972) (xy 82.23504 -428.28972) (xy 82.23504 -428.960534) (xy 82.234617 -428.972653)
			(xy 82.227118 -428.995701) (xy 82.212864 -429.015304) (xy 82.19325 -429.029543) (xy 82.170197 -429.037026)
			(xy 82.158078 -429.037496) (xy 81.218278 -429.037496) (xy 81.206166 -429.037008) (xy 81.183127 -429.029519)
			(xy 81.163529 -429.01528) (xy 81.149287 -428.995683) (xy 81.141794 -428.972646) (xy 81.141316 -428.960534)
			(xy 81.141316 -428.347886) (xy 81.139773 -428.333394) (xy 81.13812 -428.304294) (xy 81.138014 -428.28972)
			(xy 78.235048 -428.28972) (xy 78.235048 -428.960534) (xy 78.234617 -428.972652) (xy 78.227119 -428.995698)
			(xy 78.212867 -429.015301) (xy 78.193255 -429.029541) (xy 78.170204 -429.037025) (xy 78.158086 -429.037496)
			(xy 77.218286 -429.037496) (xy 77.206174 -429.037001) (xy 77.183136 -429.029514) (xy 77.163537 -429.015277)
			(xy 77.149295 -428.995682) (xy 77.141802 -428.972646) (xy 77.141324 -428.960534) (xy 77.141324 -428.347886)
			(xy 77.139781 -428.333394) (xy 77.138128 -428.304294) (xy 77.138022 -428.28972) (xy 73.234804 -428.28972)
			(xy 73.234804 -428.960534) (xy 73.234323 -428.972621) (xy 73.226862 -428.995615) (xy 73.212677 -429.015191)
			(xy 73.19315 -429.029442) (xy 73.170181 -429.036981) (xy 73.158096 -429.037496) (xy 72.218296 -429.037496)
			(xy 72.206187 -429.037087) (xy 72.183158 -429.029586) (xy 72.163585 -429.015323) (xy 72.149391 -428.995699)
			(xy 72.141971 -428.972645) (xy 72.141588 -428.960534) (xy 72.141588 -428.349918) (xy 72.139919 -428.334925)
			(xy 72.138141 -428.304806) (xy 72.138032 -428.28972) (xy 69.234812 -428.28972) (xy 69.234812 -428.960534)
			(xy 69.234421 -428.97263) (xy 69.226949 -428.99564) (xy 69.212744 -429.015223) (xy 69.193192 -429.029471)
			(xy 69.170199 -429.036994) (xy 69.158104 -429.037496) (xy 68.218304 -429.037496) (xy 68.206195 -429.03708)
			(xy 68.183167 -429.029582) (xy 68.163593 -429.01532) (xy 68.149399 -428.995698) (xy 68.141979 -428.972644)
			(xy 68.141596 -428.960534) (xy 68.141596 -428.349918) (xy 68.139927 -428.334925) (xy 68.138149 -428.304806)
			(xy 68.13804 -428.28972) (xy 65.23482 -428.28972) (xy 65.23482 -428.960534) (xy 65.234421 -428.972629)
			(xy 65.22695 -428.995638) (xy 65.212747 -429.015221) (xy 65.193197 -429.029469) (xy 65.170206 -429.036993)
			(xy 65.158112 -429.037496) (xy 64.218312 -429.037496) (xy 64.206203 -429.037073) (xy 64.183176 -429.029577)
			(xy 64.163602 -429.015317) (xy 64.149407 -428.995696) (xy 64.141987 -428.972644) (xy 64.141604 -428.960534)
			(xy 64.141604 -428.349918) (xy 64.139935 -428.334925) (xy 64.138157 -428.304806) (xy 64.138048 -428.28972)
			(xy 61.234828 -428.28972) (xy 61.234828 -428.960534) (xy 61.234421 -428.972629) (xy 61.226951 -428.995636)
			(xy 61.21275 -429.015218) (xy 61.193202 -429.029466) (xy 61.170213 -429.036992) (xy 61.15812 -429.037496)
			(xy 60.21832 -429.037496) (xy 60.206212 -429.037066) (xy 60.183185 -429.029572) (xy 60.163611 -429.015314)
			(xy 60.149416 -428.995695) (xy 60.141995 -428.972643) (xy 60.141612 -428.960534) (xy 60.141612 -428.349918)
			(xy 60.139943 -428.334925) (xy 60.138165 -428.304806) (xy 60.138056 -428.28972) (xy 49.0054 -428.28972)
			(xy 48.932448 -428.365522) (xy 48.780383 -428.51187) (xy 48.622824 -428.652286) (xy 48.460002 -428.786564)
			(xy 48.292156 -428.914507) (xy 48.119534 -429.035927) (xy 47.942387 -429.150646) (xy 47.760976 -429.258496)
			(xy 47.575567 -429.359318) (xy 47.386432 -429.452965) (xy 47.19385 -429.539298) (xy 46.998102 -429.618192)
			(xy 46.799475 -429.68953) (xy 46.598262 -429.753207) (xy 46.394758 -429.809131) (xy 46.189261 -429.857219)
			(xy 45.982073 -429.897401) (xy 45.773498 -429.929618) (xy 45.563841 -429.953821) (xy 45.353412 -429.969977)
			(xy 45.142518 -429.978061) (xy 44.93147 -429.978061) (xy 44.720576 -429.969977) (xy 44.510147 -429.953821)
			(xy 44.30049 -429.929618) (xy 44.091915 -429.897401) (xy 43.884727 -429.857219) (xy 43.67923 -429.809131)
			(xy 43.475726 -429.753207) (xy 43.274513 -429.68953) (xy 43.075886 -429.618192) (xy 42.880138 -429.539298)
			(xy 42.687556 -429.452965) (xy 42.498421 -429.359318) (xy 42.313012 -429.258496) (xy 42.131601 -429.150646)
			(xy 41.954454 -429.035927) (xy 41.781832 -428.914507) (xy 41.613986 -428.786564) (xy 41.451164 -428.652286)
			(xy 41.293605 -428.51187) (xy 41.14154 -428.365522) (xy 40.995192 -428.213457) (xy 40.854776 -428.055898)
			(xy 40.720498 -427.893076) (xy 40.592555 -427.72523) (xy 40.471135 -427.552608) (xy 40.356416 -427.375461)
			(xy 40.248566 -427.19405) (xy 40.147744 -427.008641) (xy 40.054097 -426.819506) (xy 39.967764 -426.626924)
			(xy 39.88887 -426.431176) (xy 39.817532 -426.232549) (xy 39.753855 -426.031336) (xy 39.697931 -425.827832)
			(xy 39.649843 -425.622335) (xy 39.609661 -425.415147) (xy 39.577444 -425.206572) (xy 39.553241 -424.996915)
			(xy 39.537085 -424.786486) (xy 39.529001 -424.575592) (xy 39.528496 -424.470068) (xy 7.00913 -424.470068)
			(xy 7.00913 -430.889918) (xy 58.13806 -430.889918) (xy 58.138169 -430.874832) (xy 58.139951 -430.844714)
			(xy 58.141616 -430.82972) (xy 58.141616 -429.749966) (xy 58.139951 -429.734972) (xy 58.13817 -429.704854)
			(xy 58.13806 -429.689768) (xy 58.138174 -429.674682) (xy 58.139952 -429.644564) (xy 58.141616 -429.62957)
			(xy 58.141616 -429.018954) (xy 58.142068 -429.006864) (xy 58.149534 -428.983866) (xy 58.163726 -428.964289)
			(xy 58.18326 -428.950039) (xy 58.206236 -428.942504) (xy 58.218324 -428.941992) (xy 59.158124 -428.941992)
			(xy 59.170233 -428.942396) (xy 59.19326 -428.949901) (xy 59.212832 -428.964166) (xy 59.227026 -428.983789)
			(xy 59.234448 -429.006843) (xy 59.234832 -429.018954) (xy 59.234832 -431.560478) (xy 59.234373 -431.572569)
			(xy 59.226919 -431.595574) (xy 59.212732 -431.615156) (xy 59.193194 -431.629407) (xy 59.170214 -431.636934)
			(xy 59.158124 -431.63744) (xy 58.218324 -431.63744) (xy 58.20622 -431.636964) (xy 58.183201 -431.629476)
			(xy 58.163631 -431.615228) (xy 58.149434 -431.595622) (xy 58.142005 -431.572583) (xy 58.141616 -431.560478)
			(xy 58.141616 -430.950116) (xy 58.139947 -430.935123) (xy 58.138169 -430.905004) (xy 58.13806 -430.889918)
			(xy 7.00913 -430.889918) (xy 7.00913 -431.889916) (xy 60.138056 -431.889916) (xy 60.138165 -431.87483)
			(xy 60.139947 -431.844712) (xy 60.141612 -431.829718) (xy 60.141612 -430.749964) (xy 60.139947 -430.73497)
			(xy 60.138166 -430.704852) (xy 60.138056 -430.689766) (xy 60.13817 -430.67468) (xy 60.139948 -430.644562)
			(xy 60.141612 -430.629568) (xy 60.141612 -430.018952) (xy 60.142024 -430.006873) (xy 60.149502 -429.983901)
			(xy 60.163711 -429.964363) (xy 60.183262 -429.950171) (xy 60.206241 -429.942713) (xy 60.21832 -429.942244)
			(xy 61.15812 -429.942244) (xy 61.170191 -429.942747) (xy 61.19315 -429.950209) (xy 61.212683 -429.964397)
			(xy 61.226878 -429.983924) (xy 61.234349 -430.006881) (xy 61.234828 -430.018952) (xy 61.234828 -430.889918)
			(xy 62.138052 -430.889918) (xy 62.138161 -430.874832) (xy 62.139943 -430.844714) (xy 62.141608 -430.82972)
			(xy 62.141608 -429.749966) (xy 62.139943 -429.734972) (xy 62.138162 -429.704854) (xy 62.138052 -429.689768)
			(xy 62.138166 -429.674682) (xy 62.139944 -429.644564) (xy 62.141608 -429.62957) (xy 62.141608 -429.018954)
			(xy 62.142068 -429.006865) (xy 62.149533 -428.983868) (xy 62.163723 -428.964292) (xy 62.183255 -428.950042)
			(xy 62.206229 -428.942505) (xy 62.218316 -428.941992) (xy 63.158116 -428.941992) (xy 63.170225 -428.942402)
			(xy 63.193251 -428.949905) (xy 63.212824 -428.964169) (xy 63.227018 -428.983791) (xy 63.23444 -429.006844)
			(xy 63.234824 -429.018954) (xy 63.234824 -431.560478) (xy 63.234373 -431.57257) (xy 63.226918 -431.595576)
			(xy 63.212729 -431.615159) (xy 63.193189 -431.629409) (xy 63.170206 -431.636935) (xy 63.158116 -431.63744)
			(xy 62.218316 -431.63744) (xy 62.206212 -431.63697) (xy 62.183192 -431.62948) (xy 62.163622 -431.615231)
			(xy 62.149426 -431.595623) (xy 62.141997 -431.572583) (xy 62.141608 -431.560478) (xy 62.141608 -430.950116)
			(xy 62.139939 -430.935123) (xy 62.138161 -430.905004) (xy 62.138052 -430.889918) (xy 61.234828 -430.889918)
			(xy 61.234828 -431.889916) (xy 64.138048 -431.889916) (xy 64.138157 -431.87483) (xy 64.139939 -431.844712)
			(xy 64.141604 -431.829718) (xy 64.141604 -430.749964) (xy 64.139939 -430.73497) (xy 64.138158 -430.704852)
			(xy 64.138048 -430.689766) (xy 64.138162 -430.67468) (xy 64.13994 -430.644562) (xy 64.141604 -430.629568)
			(xy 64.141604 -430.018952) (xy 64.142023 -430.006874) (xy 64.149501 -429.983903) (xy 64.163708 -429.964366)
			(xy 64.183257 -429.950173) (xy 64.206233 -429.942714) (xy 64.218312 -429.942244) (xy 65.158112 -429.942244)
			(xy 65.170182 -429.942753) (xy 65.193142 -429.950213) (xy 65.212674 -429.9644) (xy 65.22687 -429.983926)
			(xy 65.234341 -430.006882) (xy 65.23482 -430.018952) (xy 65.23482 -430.889918) (xy 66.138044 -430.889918)
			(xy 66.138153 -430.874832) (xy 66.139935 -430.844714) (xy 66.1416 -430.82972) (xy 66.1416 -429.749966)
			(xy 66.139935 -429.734972) (xy 66.138154 -429.704854) (xy 66.138044 -429.689768) (xy 66.138158 -429.674682)
			(xy 66.139936 -429.644564) (xy 66.1416 -429.62957) (xy 66.1416 -429.018954) (xy 66.142067 -429.006866)
			(xy 66.149532 -428.983871) (xy 66.16372 -428.964295) (xy 66.18325 -428.950044) (xy 66.206222 -428.942507)
			(xy 66.218308 -428.941992) (xy 67.158108 -428.941992) (xy 67.170217 -428.942409) (xy 67.193243 -428.94991)
			(xy 67.212815 -428.964172) (xy 67.22701 -428.983792) (xy 67.234432 -429.006844) (xy 67.234816 -429.018954)
			(xy 67.234816 -431.560478) (xy 67.234373 -431.572571) (xy 67.226917 -431.595578) (xy 67.212726 -431.615162)
			(xy 67.193184 -431.629412) (xy 67.170199 -431.636937) (xy 67.158108 -431.63744) (xy 66.218308 -431.63744)
			(xy 66.206204 -431.636978) (xy 66.183183 -431.629485) (xy 66.163613 -431.615234) (xy 66.149417 -431.595625)
			(xy 66.141989 -431.572584) (xy 66.1416 -431.560478) (xy 66.1416 -430.950116) (xy 66.139931 -430.935123)
			(xy 66.138153 -430.905004) (xy 66.138044 -430.889918) (xy 65.23482 -430.889918) (xy 65.23482 -431.889916)
			(xy 68.13804 -431.889916) (xy 68.138151 -431.87483) (xy 68.139933 -431.844712) (xy 68.141596 -431.829718)
			(xy 68.141596 -430.749964) (xy 68.139931 -430.73497) (xy 68.13815 -430.704852) (xy 68.13804 -430.689766)
			(xy 68.138154 -430.67468) (xy 68.139932 -430.644562) (xy 68.141596 -430.629568) (xy 68.141596 -430.018952)
			(xy 68.142023 -430.006875) (xy 68.149499 -429.983905) (xy 68.163705 -429.964368) (xy 68.183252 -429.950176)
			(xy 68.206226 -429.942715) (xy 68.218304 -429.942244) (xy 69.158104 -429.942244) (xy 69.170174 -429.94276)
			(xy 69.193133 -429.950218) (xy 69.212666 -429.964403) (xy 69.226862 -429.983927) (xy 69.234333 -430.006882)
			(xy 69.234812 -430.018952) (xy 69.234812 -430.889918) (xy 70.138036 -430.889918) (xy 70.138147 -430.874832)
			(xy 70.139929 -430.844714) (xy 70.141592 -430.82972) (xy 70.141592 -429.749966) (xy 70.139927 -429.734972)
			(xy 70.138146 -429.704854) (xy 70.138036 -429.689768) (xy 70.138152 -429.674683) (xy 70.13993 -429.644564)
			(xy 70.141592 -429.62957) (xy 70.141592 -429.018954) (xy 70.142067 -429.006867) (xy 70.149531 -428.983873)
			(xy 70.163717 -428.964298) (xy 70.183245 -428.950047) (xy 70.206214 -428.942508) (xy 70.2183 -428.941992)
			(xy 71.1581 -428.941992) (xy 71.170208 -428.942416) (xy 71.193234 -428.949914) (xy 71.212807 -428.964174)
			(xy 71.227001 -428.983794) (xy 71.234424 -429.006845) (xy 71.234808 -429.018954) (xy 71.234808 -431.560478)
			(xy 71.234275 -431.572562) (xy 71.22683 -431.595553) (xy 71.212659 -431.61513) (xy 71.193142 -431.629383)
			(xy 71.170182 -431.636924) (xy 71.1581 -431.63744) (xy 70.2183 -431.63744) (xy 70.206195 -431.636984)
			(xy 70.183175 -431.62949) (xy 70.163605 -431.615237) (xy 70.149409 -431.595626) (xy 70.141981 -431.572584)
			(xy 70.141592 -431.560478) (xy 70.141592 -430.950116) (xy 70.139923 -430.935123) (xy 70.138145 -430.905004)
			(xy 70.138036 -430.889918) (xy 69.234812 -430.889918) (xy 69.234812 -431.889916) (xy 72.138032 -431.889916)
			(xy 72.138143 -431.87483) (xy 72.139925 -431.844712) (xy 72.141588 -431.829718) (xy 72.141588 -430.749964)
			(xy 72.139923 -430.73497) (xy 72.138142 -430.704852) (xy 72.138032 -430.689766) (xy 72.138148 -430.674681)
			(xy 72.139926 -430.644562) (xy 72.141588 -430.629568) (xy 72.141588 -430.018952) (xy 72.142023 -430.006875)
			(xy 72.149498 -429.983907) (xy 72.163703 -429.964371) (xy 72.183247 -429.950178) (xy 72.206219 -429.942716)
			(xy 72.218296 -429.942244) (xy 73.158096 -429.942244) (xy 73.170166 -429.942767) (xy 73.193124 -429.950222)
			(xy 73.212657 -429.964406) (xy 73.226854 -429.983929) (xy 73.234325 -430.006883) (xy 73.234804 -430.018952)
			(xy 73.234804 -430.889918) (xy 75.138026 -430.889918) (xy 75.13812 -430.875344) (xy 75.139772 -430.846243)
			(xy 75.141328 -430.831752) (xy 75.141328 -429.747934) (xy 75.13978 -429.733442) (xy 75.13813 -429.704342)
			(xy 75.138026 -429.689768) (xy 75.138125 -429.675194) (xy 75.139774 -429.646093) (xy 75.141328 -429.631602)
			(xy 75.141328 -429.018954) (xy 75.141772 -429.006838) (xy 75.149271 -428.983795) (xy 75.163521 -428.964195)
			(xy 75.183127 -428.949955) (xy 75.206174 -428.942467) (xy 75.21829 -428.941992) (xy 76.15809 -428.941992)
			(xy 76.170199 -428.94252) (xy 76.193235 -428.949999) (xy 76.212832 -428.964228) (xy 76.227076 -428.983815)
			(xy 76.234572 -429.006845) (xy 76.235052 -429.018954) (xy 76.235052 -431.560478) (xy 76.234621 -431.572601)
			(xy 76.227134 -431.59566) (xy 76.212885 -431.615277) (xy 76.193271 -431.629528) (xy 76.170213 -431.637019)
			(xy 76.15809 -431.63744) (xy 75.21829 -431.63744) (xy 75.206165 -431.637048) (xy 75.183102 -431.62955)
			(xy 75.163485 -431.615292) (xy 75.149235 -431.59567) (xy 75.141747 -431.572604) (xy 75.141328 -431.560478)
			(xy 75.141328 -430.948084) (xy 75.139785 -430.933592) (xy 75.138132 -430.904492) (xy 75.138026 -430.889918)
			(xy 73.234804 -430.889918) (xy 73.234804 -431.889916) (xy 77.138022 -431.889916) (xy 77.138116 -431.875342)
			(xy 77.139768 -431.846241) (xy 77.141324 -431.83175) (xy 77.141324 -430.747932) (xy 77.139776 -430.73344)
			(xy 77.138126 -430.70434) (xy 77.138022 -430.689766) (xy 77.138121 -430.675192) (xy 77.13977 -430.646091)
			(xy 77.141324 -430.6316) (xy 77.141324 -430.018952) (xy 77.141676 -430.006838) (xy 77.149191 -429.983805)
			(xy 77.163469 -429.964231) (xy 77.183105 -429.950039) (xy 77.20617 -429.942624) (xy 77.218286 -429.942244)
			(xy 78.158086 -429.942244) (xy 78.170175 -429.942719) (xy 78.193176 -429.950173) (xy 78.212757 -429.964357)
			(xy 78.227007 -429.983889) (xy 78.234539 -430.006864) (xy 78.235048 -430.018952) (xy 78.235048 -430.889918)
			(xy 79.138018 -430.889918) (xy 79.138112 -430.875344) (xy 79.139764 -430.846243) (xy 79.14132 -430.831752)
			(xy 79.14132 -429.747934) (xy 79.139772 -429.733442) (xy 79.138122 -429.704342) (xy 79.138018 -429.689768)
			(xy 79.138117 -429.675194) (xy 79.139766 -429.646093) (xy 79.14132 -429.631602) (xy 79.14132 -429.018954)
			(xy 79.141772 -429.006839) (xy 79.14927 -428.983797) (xy 79.163518 -428.964198) (xy 79.183122 -428.949957)
			(xy 79.206167 -428.942468) (xy 79.218282 -428.941992) (xy 80.158082 -428.941992) (xy 80.170191 -428.942526)
			(xy 80.193226 -428.950003) (xy 80.212824 -428.964231) (xy 80.227068 -428.983817) (xy 80.234563 -429.006845)
			(xy 80.235044 -429.018954) (xy 80.235044 -431.560478) (xy 80.234621 -431.572601) (xy 80.227133 -431.595663)
			(xy 80.212882 -431.61528) (xy 80.193266 -431.629531) (xy 80.170205 -431.63702) (xy 80.158082 -431.63744)
			(xy 79.218282 -431.63744) (xy 79.206156 -431.637055) (xy 79.183093 -431.629555) (xy 79.163476 -431.615295)
			(xy 79.149227 -431.595671) (xy 79.141739 -431.572604) (xy 79.14132 -431.560478) (xy 79.14132 -430.948084)
			(xy 79.139777 -430.933592) (xy 79.138124 -430.904492) (xy 79.138018 -430.889918) (xy 78.235048 -430.889918)
			(xy 78.235048 -431.889916) (xy 81.138014 -431.889916) (xy 81.138108 -431.875342) (xy 81.13976 -431.846241)
			(xy 81.141316 -431.83175) (xy 81.141316 -430.747932) (xy 81.139768 -430.73344) (xy 81.138118 -430.70434)
			(xy 81.138014 -430.689766) (xy 81.138112 -430.675192) (xy 81.139761 -430.646091) (xy 81.141316 -430.6316)
			(xy 81.141316 -430.018952) (xy 81.141676 -430.006839) (xy 81.14919 -429.983807) (xy 81.163466 -429.964234)
			(xy 81.1831 -429.950041) (xy 81.206163 -429.942625) (xy 81.218278 -429.942244) (xy 82.158078 -429.942244)
			(xy 82.170167 -429.942726) (xy 82.193167 -429.950177) (xy 82.212748 -429.96436) (xy 82.226999 -429.983891)
			(xy 82.234531 -430.006865) (xy 82.23504 -430.018952) (xy 82.23504 -430.889918) (xy 83.13801 -430.889918)
			(xy 83.138104 -430.875344) (xy 83.139756 -430.846243) (xy 83.141312 -430.831752) (xy 83.141312 -429.747934)
			(xy 83.139764 -429.733442) (xy 83.138114 -429.704342) (xy 83.13801 -429.689768) (xy 83.138108 -429.675194)
			(xy 83.139758 -429.646093) (xy 83.141312 -429.631602) (xy 83.141312 -429.018954) (xy 83.141772 -429.00684)
			(xy 83.149269 -428.983799) (xy 83.163515 -428.964201) (xy 83.183117 -428.94996) (xy 83.20616 -428.942469)
			(xy 83.218274 -428.941992) (xy 84.158074 -428.941992) (xy 84.170183 -428.942533) (xy 84.193217 -428.950008)
			(xy 84.212815 -428.964233) (xy 84.227059 -428.983818) (xy 84.234555 -429.006846) (xy 84.235036 -429.018954)
			(xy 84.235036 -431.560478) (xy 84.234621 -431.572602) (xy 84.227132 -431.595665) (xy 84.21288 -431.615282)
			(xy 84.193261 -431.629533) (xy 84.170198 -431.637022) (xy 84.158074 -431.63744) (xy 83.218274 -431.63744)
			(xy 83.206156 -431.63701) (xy 83.183108 -431.629513) (xy 83.163505 -431.615261) (xy 83.149265 -431.595649)
			(xy 83.141782 -431.572596) (xy 83.141312 -431.560478) (xy 83.141312 -430.948084) (xy 83.139769 -430.933592)
			(xy 83.138116 -430.904492) (xy 83.13801 -430.889918) (xy 82.23504 -430.889918) (xy 82.23504 -431.889916)
			(xy 85.138006 -431.889916) (xy 85.1381 -431.875342) (xy 85.139752 -431.846241) (xy 85.141308 -431.83175)
			(xy 85.141308 -430.747932) (xy 85.13976 -430.73344) (xy 85.13811 -430.70434) (xy 85.138006 -430.689766)
			(xy 85.138104 -430.675192) (xy 85.139753 -430.646091) (xy 85.141308 -430.6316) (xy 85.141308 -430.018952)
			(xy 85.141676 -430.00684) (xy 85.149189 -429.98381) (xy 85.163463 -429.964237) (xy 85.183095 -429.950044)
			(xy 85.206156 -429.942626) (xy 85.21827 -429.942244) (xy 86.15807 -429.942244) (xy 86.170158 -429.942733)
			(xy 86.193159 -429.950182) (xy 86.212739 -429.964363) (xy 86.226991 -429.983892) (xy 86.234523 -430.006865)
			(xy 86.235032 -430.018952) (xy 86.235032 -430.889918) (xy 87.138002 -430.889918) (xy 87.138096 -430.875344)
			(xy 87.139748 -430.846243) (xy 87.141304 -430.831752) (xy 87.141304 -429.747934) (xy 87.139756 -429.733442)
			(xy 87.138106 -429.704342) (xy 87.138002 -429.689768) (xy 87.1381 -429.675194) (xy 87.13975 -429.646093)
			(xy 87.141304 -429.631602) (xy 87.141304 -429.018954) (xy 87.141772 -429.00684) (xy 87.149268 -428.983801)
			(xy 87.163512 -428.964203) (xy 87.183112 -428.949962) (xy 87.206152 -428.94247) (xy 87.218266 -428.941992)
			(xy 88.158066 -428.941992) (xy 88.170174 -428.94254) (xy 88.193209 -428.950012) (xy 88.212807 -428.964236)
			(xy 88.227051 -428.98382) (xy 88.234547 -429.006846) (xy 88.235028 -429.018954) (xy 88.235028 -431.560478)
			(xy 88.234621 -431.572603) (xy 88.22713 -431.595667) (xy 88.212877 -431.615285) (xy 88.193256 -431.629536)
			(xy 88.170191 -431.637023) (xy 88.158066 -431.63744) (xy 87.218266 -431.63744) (xy 87.206147 -431.637017)
			(xy 87.183099 -431.629518) (xy 87.163496 -431.615264) (xy 87.149257 -431.59565) (xy 87.141774 -431.572597)
			(xy 87.141304 -431.560478) (xy 87.141304 -430.948084) (xy 87.13976 -430.933592) (xy 87.138108 -430.904492)
			(xy 87.138002 -430.889918) (xy 86.235032 -430.889918) (xy 86.235032 -431.889916) (xy 89.137998 -431.889916)
			(xy 89.138092 -431.875342) (xy 89.139744 -431.846241) (xy 89.1413 -431.83175) (xy 89.1413 -430.747932)
			(xy 89.139752 -430.73344) (xy 89.138102 -430.70434) (xy 89.137998 -430.689766) (xy 89.138096 -430.675192)
			(xy 89.139746 -430.646091) (xy 89.1413 -430.6316) (xy 89.1413 -430.018952) (xy 89.141676 -430.006841)
			(xy 89.149188 -429.983812) (xy 89.16346 -429.96424) (xy 89.18309 -429.950047) (xy 89.206149 -429.942627)
			(xy 89.218262 -429.942244) (xy 90.158062 -429.942244) (xy 90.17015 -429.94274) (xy 90.19315 -429.950187)
			(xy 90.212731 -429.964366) (xy 90.226983 -429.983894) (xy 90.234515 -430.006866) (xy 90.235024 -430.018952)
			(xy 90.235024 -431.360072) (xy 108.40466 -431.360072) (xy 108.405158 -431.275192) (xy 108.413115 -431.105619)
			(xy 108.429011 -430.936605) (xy 108.452812 -430.768522) (xy 108.484466 -430.601739) (xy 108.523902 -430.436623)
			(xy 108.571034 -430.273538) (xy 108.625758 -430.11284) (xy 108.687955 -429.954885) (xy 108.757487 -429.800018)
			(xy 108.834202 -429.648581) (xy 108.91793 -429.500905) (xy 109.008488 -429.357317) (xy 109.105677 -429.218131)
			(xy 109.209284 -429.083654) (xy 109.319079 -428.954181) (xy 109.434823 -428.829996) (xy 109.55626 -428.711373)
			(xy 109.683124 -428.598572) (xy 109.815135 -428.491842) (xy 109.952005 -428.391417) (xy 110.09343 -428.297518)
			(xy 110.239102 -428.21035) (xy 110.3887 -428.130107) (xy 110.541894 -428.056963) (xy 110.698348 -427.991081)
			(xy 110.857718 -427.932604) (xy 111.019654 -427.881662) (xy 111.1838 -427.838366) (xy 111.349795 -427.802811)
			(xy 111.517274 -427.775076) (xy 111.685869 -427.755222) (xy 111.855209 -427.743292) (xy 112.024922 -427.739313)
			(xy 112.194635 -427.743292) (xy 112.363975 -427.755222) (xy 112.53257 -427.775076) (xy 112.700049 -427.802811)
			(xy 112.866044 -427.838366) (xy 113.03019 -427.881662) (xy 113.192126 -427.932604) (xy 113.351496 -427.991081)
			(xy 113.50795 -428.056963) (xy 113.661144 -428.130107) (xy 113.810742 -428.21035) (xy 113.943382 -428.28972)
			(xy 127.237998 -428.28972) (xy 127.238092 -428.275146) (xy 127.239744 -428.246045) (xy 127.2413 -428.231554)
			(xy 127.2413 -427.14799) (xy 127.239757 -427.133498) (xy 127.238104 -427.104398) (xy 127.237998 -427.089824)
			(xy 127.238092 -427.07525) (xy 127.239744 -427.046149) (xy 127.2413 -427.031658) (xy 127.2413 -426.41901)
			(xy 127.24182 -426.4069) (xy 127.2493 -426.383863) (xy 127.263531 -426.364265) (xy 127.28312 -426.350022)
			(xy 127.306152 -426.342527) (xy 127.318262 -426.342048) (xy 128.258062 -426.342048) (xy 128.270184 -426.342492)
			(xy 128.293243 -426.349975) (xy 128.31286 -426.36422) (xy 128.327112 -426.383832) (xy 128.334603 -426.406888)
			(xy 128.335024 -426.41901) (xy 128.335024 -427.289976) (xy 129.237994 -427.289976) (xy 129.238084 -427.275402)
			(xy 129.239739 -427.246301) (xy 129.241296 -427.23181) (xy 129.241296 -426.147992) (xy 129.239753 -426.1335)
			(xy 129.2381 -426.1044) (xy 129.237994 -426.089826) (xy 129.238089 -426.075252) (xy 129.23974 -426.046151)
			(xy 129.241296 -426.03166) (xy 129.241296 -425.419012) (xy 129.241727 -425.406904) (xy 129.249222 -425.383878)
			(xy 129.26348 -425.364305) (xy 129.283099 -425.35011) (xy 129.306149 -425.342688) (xy 129.318258 -425.342304)
			(xy 130.258058 -425.342304) (xy 130.270142 -425.342842) (xy 130.293135 -425.350283) (xy 130.312713 -425.364453)
			(xy 130.326966 -425.383969) (xy 130.334505 -425.40693) (xy 130.33502 -425.419012) (xy 130.33502 -427.960536)
			(xy 130.334615 -427.972645) (xy 130.327108 -427.99567) (xy 130.312843 -428.01524) (xy 130.29322 -428.029435)
			(xy 130.270168 -428.036858) (xy 130.258058 -428.037244) (xy 129.318258 -428.037244) (xy 129.306165 -428.036828)
			(xy 129.28316 -428.029358) (xy 129.263579 -428.015159) (xy 129.249331 -427.995614) (xy 129.241803 -427.972628)
			(xy 129.241296 -427.960536) (xy 129.241296 -427.348142) (xy 129.239749 -427.33365) (xy 129.238099 -427.30455)
			(xy 129.237994 -427.289976) (xy 128.335024 -427.289976) (xy 128.335024 -428.28972) (xy 131.23799 -428.28972)
			(xy 131.238084 -428.275146) (xy 131.239736 -428.246045) (xy 131.241292 -428.231554) (xy 131.241292 -427.14799)
			(xy 131.239749 -427.133498) (xy 131.238096 -427.104398) (xy 131.23799 -427.089824) (xy 131.238085 -427.07525)
			(xy 131.239736 -427.046149) (xy 131.241292 -427.031658) (xy 131.241292 -426.41901) (xy 131.24182 -426.406901)
			(xy 131.249299 -426.383865) (xy 131.263528 -426.364268) (xy 131.283115 -426.350024) (xy 131.306145 -426.342528)
			(xy 131.318254 -426.342048) (xy 132.258054 -426.342048) (xy 132.270175 -426.342499) (xy 132.293234 -426.34998)
			(xy 132.312851 -426.364223) (xy 132.327104 -426.383833) (xy 132.334595 -426.406889) (xy 132.335016 -426.41901)
			(xy 132.335016 -427.289976) (xy 133.237986 -427.289976) (xy 133.238076 -427.275402) (xy 133.239731 -427.246301)
			(xy 133.241288 -427.23181) (xy 133.241288 -426.147992) (xy 133.239745 -426.1335) (xy 133.238092 -426.1044)
			(xy 133.237986 -426.089826) (xy 133.238081 -426.075252) (xy 133.239732 -426.046151) (xy 133.241288 -426.03166)
			(xy 133.241288 -425.419012) (xy 133.241727 -425.406905) (xy 133.249221 -425.38388) (xy 133.263477 -425.364308)
			(xy 133.283094 -425.350113) (xy 133.306142 -425.342689) (xy 133.31825 -425.342304) (xy 134.25805 -425.342304)
			(xy 134.270133 -425.342849) (xy 134.293126 -425.350288) (xy 134.312704 -425.364455) (xy 134.326958 -425.383971)
			(xy 134.334497 -425.406931) (xy 134.335012 -425.419012) (xy 134.335012 -427.960536) (xy 134.334614 -427.972646)
			(xy 134.327107 -427.995672) (xy 134.31284 -428.015243) (xy 134.293215 -428.029437) (xy 134.270161 -428.036859)
			(xy 134.25805 -428.037244) (xy 133.31825 -428.037244) (xy 133.306161 -428.03675) (xy 133.28316 -428.029305)
			(xy 133.263578 -428.015126) (xy 133.249326 -427.995597) (xy 133.241795 -427.972623) (xy 133.241288 -427.960536)
			(xy 133.241288 -427.348142) (xy 133.239741 -427.33365) (xy 133.238091 -427.30455) (xy 133.237986 -427.289976)
			(xy 132.335016 -427.289976) (xy 132.335016 -428.28972) (xy 135.237982 -428.28972) (xy 135.238076 -428.275146)
			(xy 135.239728 -428.246045) (xy 135.241284 -428.231554) (xy 135.241284 -427.14799) (xy 135.239741 -427.133498)
			(xy 135.238088 -427.104398) (xy 135.237982 -427.089824) (xy 135.238077 -427.07525) (xy 135.239728 -427.046149)
			(xy 135.241284 -427.031658) (xy 135.241284 -426.41901) (xy 135.241669 -426.406883) (xy 135.249164 -426.383817)
			(xy 135.263423 -426.364198) (xy 135.283049 -426.349948) (xy 135.306119 -426.342464) (xy 135.318246 -426.342048)
			(xy 136.258046 -426.342048) (xy 136.270164 -426.342473) (xy 136.29321 -426.349974) (xy 136.312812 -426.364228)
			(xy 136.327052 -426.38384) (xy 136.334536 -426.406892) (xy 136.335008 -426.41901) (xy 136.335008 -427.289976)
			(xy 137.237978 -427.289976) (xy 137.238068 -427.275402) (xy 137.239723 -427.246301) (xy 137.24128 -427.23181)
			(xy 137.24128 -426.147992) (xy 137.239737 -426.1335) (xy 137.238084 -426.1044) (xy 137.237978 -426.089826)
			(xy 137.238073 -426.075252) (xy 137.239724 -426.046151) (xy 137.24128 -426.03166) (xy 137.24128 -425.419012)
			(xy 137.241727 -425.406906) (xy 137.24922 -425.383882) (xy 137.263475 -425.364311) (xy 137.283089 -425.350115)
			(xy 137.306135 -425.342691) (xy 137.318242 -425.342304) (xy 138.258042 -425.342304) (xy 138.27013 -425.342771)
			(xy 138.293126 -425.350235) (xy 138.312702 -425.364423) (xy 138.326953 -425.383953) (xy 138.33449 -425.406925)
			(xy 138.335004 -425.419012) (xy 138.335004 -427.960536) (xy 138.334614 -427.972646) (xy 138.327106 -427.995674)
			(xy 138.312837 -428.015246) (xy 138.29321 -428.02944) (xy 138.270154 -428.03686) (xy 138.258042 -428.037244)
			(xy 137.318242 -428.037244) (xy 137.306153 -428.036757) (xy 137.283151 -428.029309) (xy 137.263569 -428.015129)
			(xy 137.249318 -427.995598) (xy 137.241787 -427.972623) (xy 137.24128 -427.960536) (xy 137.24128 -427.348142)
			(xy 137.239733 -427.33365) (xy 137.238083 -427.30455) (xy 137.237978 -427.289976) (xy 136.335008 -427.289976)
			(xy 136.335008 -428.28972) (xy 139.237974 -428.28972) (xy 139.238068 -428.275146) (xy 139.23972 -428.246045)
			(xy 139.241276 -428.231554) (xy 139.241276 -427.14799) (xy 139.239733 -427.133498) (xy 139.23808 -427.104398)
			(xy 139.237974 -427.089824) (xy 139.238069 -427.07525) (xy 139.23972 -427.046149) (xy 139.241276 -427.031658)
			(xy 139.241276 -426.41901) (xy 139.241669 -426.406884) (xy 139.249163 -426.383819) (xy 139.26342 -426.364201)
			(xy 139.283044 -426.34995) (xy 139.306112 -426.342465) (xy 139.318238 -426.342048) (xy 140.258038 -426.342048)
			(xy 140.270156 -426.342479) (xy 140.293202 -426.349978) (xy 140.312804 -426.36423) (xy 140.327044 -426.383841)
			(xy 140.334528 -426.406892) (xy 140.335 -426.41901) (xy 140.335 -427.289976) (xy 142.237968 -427.289976)
			(xy 142.238082 -427.274891) (xy 142.23986 -427.244772) (xy 142.241524 -427.229778) (xy 142.241524 -426.150024)
			(xy 142.239855 -426.135031) (xy 142.238077 -426.104912) (xy 142.237968 -426.089826) (xy 142.238078 -426.07474)
			(xy 142.239859 -426.044622) (xy 142.241524 -426.029628) (xy 142.241524 -425.419012) (xy 142.241924 -425.406927)
			(xy 142.249392 -425.383939) (xy 142.2636 -425.364386) (xy 142.283157 -425.350183) (xy 142.306147 -425.34272)
			(xy 142.318232 -425.342304) (xy 143.258032 -425.342304) (xy 143.270109 -425.342737) (xy 143.29308 -425.35021)
			(xy 143.312617 -425.364414) (xy 143.32681 -425.38396) (xy 143.33427 -425.406934) (xy 143.33474 -425.419012)
			(xy 143.33474 -427.960536) (xy 143.334267 -427.972609) (xy 143.326799 -427.995572) (xy 143.312603 -428.015106)
			(xy 143.293069 -428.0293) (xy 143.270105 -428.036768) (xy 143.258032 -428.037244) (xy 142.318232 -428.037244)
			(xy 142.306163 -428.036709) (xy 142.283203 -428.02926) (xy 142.263668 -428.01508) (xy 142.249471 -427.995558)
			(xy 142.242001 -427.972605) (xy 142.241524 -427.960536) (xy 142.241524 -427.350174) (xy 142.23986 -427.33518)
			(xy 142.238078 -427.305062) (xy 142.237968 -427.289976) (xy 140.335 -427.289976) (xy 140.335 -428.28972)
			(xy 144.237964 -428.28972) (xy 144.238073 -428.274634) (xy 144.239855 -428.244516) (xy 144.24152 -428.229522)
			(xy 144.24152 -427.150022) (xy 144.239851 -427.135029) (xy 144.238073 -427.10491) (xy 144.237964 -427.089824)
			(xy 144.238074 -427.074738) (xy 144.239855 -427.04462) (xy 144.24152 -427.029626) (xy 144.24152 -426.41901)
			(xy 144.242016 -426.406923) (xy 144.249467 -426.383926) (xy 144.263647 -426.364348) (xy 144.283173 -426.350096)
			(xy 144.306143 -426.34256) (xy 144.318228 -426.342048) (xy 145.258028 -426.342048) (xy 145.270133 -426.342492)
			(xy 145.293152 -426.349993) (xy 145.312721 -426.364249) (xy 145.326916 -426.383861) (xy 145.334345 -426.406904)
			(xy 145.334736 -426.41901) (xy 145.334736 -427.289976) (xy 146.23796 -427.289976) (xy 146.238074 -427.274891)
			(xy 146.239852 -427.244772) (xy 146.241516 -427.229778) (xy 146.241516 -426.150024) (xy 146.239847 -426.135031)
			(xy 146.238069 -426.104912) (xy 146.23796 -426.089826) (xy 146.23807 -426.07474) (xy 146.239851 -426.044622)
			(xy 146.241516 -426.029628) (xy 146.241516 -425.419012) (xy 146.241923 -425.406928) (xy 146.249391 -425.383941)
			(xy 146.263597 -425.364389) (xy 146.283152 -425.350185) (xy 146.306139 -425.342722) (xy 146.318224 -425.342304)
			(xy 147.258024 -425.342304) (xy 147.270101 -425.342744) (xy 147.293071 -425.350215) (xy 147.312609 -425.364417)
			(xy 147.326802 -425.383961) (xy 147.334261 -425.406935) (xy 147.334732 -425.419012) (xy 147.334732 -427.960536)
			(xy 147.334267 -427.97261) (xy 147.326798 -427.995574) (xy 147.3126 -428.015109) (xy 147.293064 -428.029303)
			(xy 147.270098 -428.036769) (xy 147.258024 -428.037244) (xy 146.318224 -428.037244) (xy 146.306154 -428.036716)
			(xy 146.283194 -428.029264) (xy 146.26366 -428.015083) (xy 146.249463 -427.99556) (xy 146.241993 -427.972605)
			(xy 146.241516 -427.960536) (xy 146.241516 -427.350174) (xy 146.239852 -427.33518) (xy 146.23807 -427.305062)
			(xy 146.23796 -427.289976) (xy 145.334736 -427.289976) (xy 145.334736 -428.28972) (xy 148.237956 -428.28972)
			(xy 148.238066 -428.274634) (xy 148.239847 -428.244516) (xy 148.241512 -428.229522) (xy 148.241512 -427.150022)
			(xy 148.239843 -427.135029) (xy 148.238065 -427.10491) (xy 148.237956 -427.089824) (xy 148.238066 -427.074738)
			(xy 148.239847 -427.04462) (xy 148.241512 -427.029626) (xy 148.241512 -426.41901) (xy 148.242015 -426.406924)
			(xy 148.249466 -426.383928) (xy 148.263644 -426.364351) (xy 148.283168 -426.350099) (xy 148.306136 -426.342562)
			(xy 148.31822 -426.342048) (xy 149.25802 -426.342048) (xy 149.270125 -426.342499) (xy 149.293144 -426.349997)
			(xy 149.312712 -426.364252) (xy 149.326908 -426.383863) (xy 149.334337 -426.406904) (xy 149.334728 -426.41901)
			(xy 149.334728 -427.289976) (xy 150.237952 -427.289976) (xy 150.238066 -427.274891) (xy 150.239844 -427.244772)
			(xy 150.241508 -427.229778) (xy 150.241508 -426.150024) (xy 150.239839 -426.135031) (xy 150.238061 -426.104912)
			(xy 150.237952 -426.089826) (xy 150.238062 -426.07474) (xy 150.239843 -426.044622) (xy 150.241508 -426.029628)
			(xy 150.241508 -425.419012) (xy 150.241923 -425.406928) (xy 150.249389 -425.383943) (xy 150.263594 -425.364392)
			(xy 150.283147 -425.350188) (xy 150.306132 -425.342723) (xy 150.318216 -425.342304) (xy 151.258016 -425.342304)
			(xy 151.270093 -425.342751) (xy 151.293062 -425.350219) (xy 151.3126 -425.36442) (xy 151.326794 -425.383963)
			(xy 151.334253 -425.406935) (xy 151.334724 -425.419012) (xy 151.334724 -427.960536) (xy 151.334267 -427.972611)
			(xy 151.326796 -427.995577) (xy 151.312597 -428.015112) (xy 151.293059 -428.029306) (xy 151.270091 -428.03677)
			(xy 151.258016 -428.037244) (xy 150.318216 -428.037244) (xy 150.306146 -428.036723) (xy 150.283185 -428.029269)
			(xy 150.263651 -428.015086) (xy 150.249455 -427.995561) (xy 150.241985 -427.972606) (xy 150.241508 -427.960536)
			(xy 150.241508 -427.350174) (xy 150.239844 -427.33518) (xy 150.238062 -427.305062) (xy 150.237952 -427.289976)
			(xy 149.334728 -427.289976) (xy 149.334728 -428.28972) (xy 152.237948 -428.28972) (xy 152.238058 -428.274634)
			(xy 152.239839 -428.244516) (xy 152.241504 -428.229522) (xy 152.241504 -427.150022) (xy 152.239835 -427.135029)
			(xy 152.238057 -427.10491) (xy 152.237948 -427.089824) (xy 152.238058 -427.074738) (xy 152.239839 -427.04462)
			(xy 152.241504 -427.029626) (xy 152.241504 -426.41901) (xy 152.242015 -426.406925) (xy 152.249465 -426.38393)
			(xy 152.263641 -426.364353) (xy 152.283163 -426.350101) (xy 152.306128 -426.342563) (xy 152.318212 -426.342048)
			(xy 153.258012 -426.342048) (xy 153.270116 -426.342505) (xy 153.293135 -426.350002) (xy 153.312704 -426.364255)
			(xy 153.3269 -426.383864) (xy 153.334329 -426.406905) (xy 153.33472 -426.41901) (xy 153.33472 -427.289976)
			(xy 154.237944 -427.289976) (xy 154.238059 -427.274891) (xy 154.239836 -427.244772) (xy 154.2415 -427.229778)
			(xy 154.2415 -426.150024) (xy 154.239831 -426.135031) (xy 154.238053 -426.104912) (xy 154.237944 -426.089826)
			(xy 154.238054 -426.07474) (xy 154.239835 -426.044622) (xy 154.2415 -426.029628) (xy 154.2415 -425.419012)
			(xy 154.241923 -425.406929) (xy 154.249388 -425.383946) (xy 154.263592 -425.364394) (xy 154.283142 -425.35019)
			(xy 154.306125 -425.342724) (xy 154.318208 -425.342304) (xy 155.258008 -425.342304) (xy 155.270092 -425.342706)
			(xy 155.293077 -425.350177) (xy 155.312629 -425.364386) (xy 155.326832 -425.383941) (xy 155.334297 -425.406928)
			(xy 155.334716 -425.419012) (xy 155.334716 -427.960536) (xy 155.334267 -427.972612) (xy 155.326795 -427.995579)
			(xy 155.312595 -428.015115) (xy 155.293054 -428.029308) (xy 155.270084 -428.036771) (xy 155.258008 -428.037244)
			(xy 154.318208 -428.037244) (xy 154.306137 -428.03673) (xy 154.283177 -428.029274) (xy 154.263643 -428.015089)
			(xy 154.249447 -427.995563) (xy 154.241977 -427.972606) (xy 154.2415 -427.960536) (xy 154.2415 -427.350174)
			(xy 154.239836 -427.33518) (xy 154.238054 -427.305062) (xy 154.237944 -427.289976) (xy 153.33472 -427.289976)
			(xy 153.33472 -428.28972) (xy 156.23794 -428.28972) (xy 156.238052 -428.274634) (xy 156.239833 -428.244516)
			(xy 156.241496 -428.229522) (xy 156.241496 -427.150022) (xy 156.239827 -427.135029) (xy 156.238049 -427.10491)
			(xy 156.23794 -427.089824) (xy 156.23805 -427.074738) (xy 156.239831 -427.04462) (xy 156.241496 -427.029626)
			(xy 156.241496 -426.41901) (xy 156.242015 -426.406925) (xy 156.249464 -426.383932) (xy 156.263639 -426.364356)
			(xy 156.283158 -426.350104) (xy 156.306121 -426.342564) (xy 156.318204 -426.342048) (xy 157.258004 -426.342048)
			(xy 157.270108 -426.342512) (xy 157.293127 -426.350006) (xy 157.312695 -426.364257) (xy 157.326891 -426.383866)
			(xy 157.334321 -426.406905) (xy 157.334712 -426.41901) (xy 157.334712 -428.960534) (xy 157.334321 -428.97263)
			(xy 157.326849 -428.99564) (xy 157.312644 -429.015223) (xy 157.293092 -429.029471) (xy 157.270099 -429.036994)
			(xy 157.258004 -429.037496) (xy 156.318204 -429.037496) (xy 156.306095 -429.03708) (xy 156.283067 -429.029582)
			(xy 156.263493 -429.01532) (xy 156.249299 -428.995698) (xy 156.241879 -428.972644) (xy 156.241496 -428.960534)
			(xy 156.241496 -428.349918) (xy 156.239827 -428.334925) (xy 156.238049 -428.304806) (xy 156.23794 -428.28972)
			(xy 153.33472 -428.28972) (xy 153.33472 -428.960534) (xy 153.334321 -428.972629) (xy 153.32685 -428.995638)
			(xy 153.312647 -429.015221) (xy 153.293097 -429.029469) (xy 153.270106 -429.036993) (xy 153.258012 -429.037496)
			(xy 152.318212 -429.037496) (xy 152.306103 -429.037073) (xy 152.283076 -429.029577) (xy 152.263502 -429.015317)
			(xy 152.249307 -428.995696) (xy 152.241887 -428.972644) (xy 152.241504 -428.960534) (xy 152.241504 -428.349918)
			(xy 152.239835 -428.334925) (xy 152.238057 -428.304806) (xy 152.237948 -428.28972) (xy 149.334728 -428.28972)
			(xy 149.334728 -428.960534) (xy 149.334321 -428.972629) (xy 149.326851 -428.995636) (xy 149.31265 -429.015218)
			(xy 149.293102 -429.029466) (xy 149.270113 -429.036992) (xy 149.25802 -429.037496) (xy 148.31822 -429.037496)
			(xy 148.306112 -429.037066) (xy 148.283085 -429.029572) (xy 148.263511 -429.015314) (xy 148.249316 -428.995695)
			(xy 148.241895 -428.972643) (xy 148.241512 -428.960534) (xy 148.241512 -428.349918) (xy 148.239843 -428.334925)
			(xy 148.238065 -428.304806) (xy 148.237956 -428.28972) (xy 145.334736 -428.28972) (xy 145.334736 -428.960534)
			(xy 145.334321 -428.972628) (xy 145.326852 -428.995634) (xy 145.312653 -429.015215) (xy 145.293107 -429.029464)
			(xy 145.27012 -429.03699) (xy 145.258028 -429.037496) (xy 144.318228 -429.037496) (xy 144.30612 -429.03706)
			(xy 144.283093 -429.029567) (xy 144.263519 -429.015311) (xy 144.249324 -428.995693) (xy 144.241903 -428.972643)
			(xy 144.24152 -428.960534) (xy 144.24152 -428.349918) (xy 144.239851 -428.334925) (xy 144.238073 -428.304806)
			(xy 144.237964 -428.28972) (xy 140.335 -428.28972) (xy 140.335 -428.960534) (xy 140.334518 -428.972647)
			(xy 140.327026 -428.995684) (xy 140.312785 -429.015282) (xy 140.293188 -429.029524) (xy 140.270151 -429.037017)
			(xy 140.258038 -429.037496) (xy 139.318238 -429.037496) (xy 139.306121 -429.037008) (xy 139.283069 -429.029531)
			(xy 139.263456 -429.015295) (xy 139.249202 -428.995696) (xy 139.241703 -428.972651) (xy 139.241276 -428.960534)
			(xy 139.241276 -428.347886) (xy 139.239733 -428.333394) (xy 139.23808 -428.304294) (xy 139.237974 -428.28972)
			(xy 136.335008 -428.28972) (xy 136.335008 -428.960534) (xy 136.334518 -428.972646) (xy 136.327027 -428.995682)
			(xy 136.312788 -429.01528) (xy 136.293193 -429.029522) (xy 136.270158 -429.037016) (xy 136.258046 -429.037496)
			(xy 135.318246 -429.037496) (xy 135.306129 -429.037002) (xy 135.283077 -429.029526) (xy 135.263464 -429.015292)
			(xy 135.249211 -428.995694) (xy 135.241711 -428.972651) (xy 135.241284 -428.960534) (xy 135.241284 -428.347886)
			(xy 135.239741 -428.333394) (xy 135.238088 -428.304294) (xy 135.237982 -428.28972) (xy 132.335016 -428.28972)
			(xy 132.335016 -428.960534) (xy 132.334668 -428.972663) (xy 132.327161 -428.995731) (xy 132.312892 -429.015349)
			(xy 132.293259 -429.029598) (xy 132.270184 -429.037081) (xy 132.258054 -429.037496) (xy 131.318254 -429.037496)
			(xy 131.30614 -429.037028) (xy 131.283101 -429.029532) (xy 131.263503 -429.015288) (xy 131.249262 -428.995688)
			(xy 131.24177 -428.972648) (xy 131.241292 -428.960534) (xy 131.241292 -428.347886) (xy 131.239749 -428.333394)
			(xy 131.238096 -428.304294) (xy 131.23799 -428.28972) (xy 128.335024 -428.28972) (xy 128.335024 -428.960534)
			(xy 128.334669 -428.972662) (xy 128.327162 -428.995729) (xy 128.312895 -429.015347) (xy 128.293264 -429.029595)
			(xy 128.270191 -429.03708) (xy 128.258062 -429.037496) (xy 127.318262 -429.037496) (xy 127.306149 -429.037021)
			(xy 127.28311 -429.029528) (xy 127.263512 -429.015285) (xy 127.24927 -428.995686) (xy 127.241778 -428.972647)
			(xy 127.2413 -428.960534) (xy 127.2413 -428.347886) (xy 127.239757 -428.333394) (xy 127.238104 -428.304294)
			(xy 127.237998 -428.28972) (xy 113.943382 -428.28972) (xy 113.956414 -428.297518) (xy 114.097839 -428.391417)
			(xy 114.234709 -428.491842) (xy 114.36672 -428.598572) (xy 114.493584 -428.711373) (xy 114.615021 -428.829996)
			(xy 114.730765 -428.954181) (xy 114.84056 -429.083654) (xy 114.944167 -429.218131) (xy 115.041356 -429.357317)
			(xy 115.131914 -429.500905) (xy 115.215642 -429.648581) (xy 115.292357 -429.800018) (xy 115.361889 -429.954885)
			(xy 115.424086 -430.11284) (xy 115.47881 -430.273538) (xy 115.525942 -430.436623) (xy 115.565378 -430.601739)
			(xy 115.597032 -430.768522) (xy 115.614222 -430.889918) (xy 125.238002 -430.889918) (xy 125.238096 -430.875344)
			(xy 125.239748 -430.846243) (xy 125.241304 -430.831752) (xy 125.241304 -429.747934) (xy 125.239756 -429.733442)
			(xy 125.238106 -429.704342) (xy 125.238002 -429.689768) (xy 125.2381 -429.675194) (xy 125.23975 -429.646093)
			(xy 125.241304 -429.631602) (xy 125.241304 -429.018954) (xy 125.241772 -429.00684) (xy 125.249268 -428.983801)
			(xy 125.263512 -428.964203) (xy 125.283112 -428.949962) (xy 125.306152 -428.94247) (xy 125.318266 -428.941992)
			(xy 126.258066 -428.941992) (xy 126.270174 -428.94254) (xy 126.293209 -428.950012) (xy 126.312807 -428.964236)
			(xy 126.327051 -428.98382) (xy 126.334547 -429.006846) (xy 126.335028 -429.018954) (xy 126.335028 -431.560478)
			(xy 126.334621 -431.572603) (xy 126.32713 -431.595667) (xy 126.312877 -431.615285) (xy 126.293256 -431.629536)
			(xy 126.270191 -431.637023) (xy 126.258066 -431.63744) (xy 125.318266 -431.63744) (xy 125.306147 -431.637017)
			(xy 125.283099 -431.629518) (xy 125.263496 -431.615264) (xy 125.249257 -431.59565) (xy 125.241774 -431.572597)
			(xy 125.241304 -431.560478) (xy 125.241304 -430.948084) (xy 125.23976 -430.933592) (xy 125.238108 -430.904492)
			(xy 125.238002 -430.889918) (xy 115.614222 -430.889918) (xy 115.620833 -430.936605) (xy 115.636729 -431.105619)
			(xy 115.644686 -431.275192) (xy 115.645184 -431.360072) (xy 115.644698 -431.445674) (xy 115.63661 -431.616688)
			(xy 115.620446 -431.787128) (xy 115.605768 -431.889916) (xy 127.237998 -431.889916) (xy 127.238092 -431.875342)
			(xy 127.239744 -431.846241) (xy 127.2413 -431.83175) (xy 127.2413 -430.747932) (xy 127.239752 -430.73344)
			(xy 127.238102 -430.70434) (xy 127.237998 -430.689766) (xy 127.238096 -430.675192) (xy 127.239746 -430.646091)
			(xy 127.2413 -430.6316) (xy 127.2413 -430.018952) (xy 127.241676 -430.006841) (xy 127.249188 -429.983812)
			(xy 127.26346 -429.96424) (xy 127.28309 -429.950047) (xy 127.306149 -429.942627) (xy 127.318262 -429.942244)
			(xy 128.258062 -429.942244) (xy 128.27015 -429.94274) (xy 128.29315 -429.950187) (xy 128.312731 -429.964366)
			(xy 128.326983 -429.983894) (xy 128.334515 -430.006866) (xy 128.335024 -430.018952) (xy 128.335024 -430.889918)
			(xy 129.237994 -430.889918) (xy 129.238088 -430.875344) (xy 129.23974 -430.846243) (xy 129.241296 -430.831752)
			(xy 129.241296 -429.747934) (xy 129.239749 -429.733442) (xy 129.238098 -429.704342) (xy 129.237994 -429.689768)
			(xy 129.238092 -429.675194) (xy 129.239742 -429.646093) (xy 129.241296 -429.631602) (xy 129.241296 -429.018954)
			(xy 129.241772 -429.006841) (xy 129.249267 -428.983804) (xy 129.263509 -428.964206) (xy 129.283107 -428.949965)
			(xy 129.306145 -428.942471) (xy 129.318258 -428.941992) (xy 130.258058 -428.941992) (xy 130.270166 -428.942547)
			(xy 130.2932 -428.950017) (xy 130.312798 -428.964239) (xy 130.327043 -428.983821) (xy 130.334539 -429.006847)
			(xy 130.33502 -429.018954) (xy 130.33502 -431.560478) (xy 130.334621 -431.572604) (xy 130.327129 -431.595669)
			(xy 130.312874 -431.615288) (xy 130.293251 -431.629538) (xy 130.270184 -431.637024) (xy 130.258058 -431.63744)
			(xy 129.318258 -431.63744) (xy 129.306139 -431.637024) (xy 129.283091 -431.629522) (xy 129.263488 -431.615267)
			(xy 129.249248 -431.595652) (xy 129.241766 -431.572597) (xy 129.241296 -431.560478) (xy 129.241296 -430.948084)
			(xy 129.239753 -430.933592) (xy 129.2381 -430.904492) (xy 129.237994 -430.889918) (xy 128.335024 -430.889918)
			(xy 128.335024 -431.889916) (xy 131.23799 -431.889916) (xy 131.238084 -431.875342) (xy 131.239736 -431.846241)
			(xy 131.241292 -431.83175) (xy 131.241292 -430.747932) (xy 131.239744 -430.73344) (xy 131.238094 -430.70434)
			(xy 131.23799 -430.689766) (xy 131.238088 -430.675192) (xy 131.239738 -430.646091) (xy 131.241292 -430.6316)
			(xy 131.241292 -430.018952) (xy 131.241675 -430.006841) (xy 131.249187 -429.983814) (xy 131.263458 -429.964242)
			(xy 131.283085 -429.950049) (xy 131.306142 -429.942628) (xy 131.318254 -429.942244) (xy 132.258054 -429.942244)
			(xy 132.270142 -429.942747) (xy 132.293141 -429.950191) (xy 132.312722 -429.964368) (xy 132.326974 -429.983895)
			(xy 132.334507 -430.006866) (xy 132.335016 -430.018952) (xy 132.335016 -430.889918) (xy 133.237986 -430.889918)
			(xy 133.23808 -430.875344) (xy 133.239732 -430.846243) (xy 133.241288 -430.831752) (xy 133.241288 -429.747934)
			(xy 133.239741 -429.733442) (xy 133.23809 -429.704342) (xy 133.237986 -429.689768) (xy 133.238084 -429.675194)
			(xy 133.239734 -429.646093) (xy 133.241288 -429.631602) (xy 133.241288 -429.018954) (xy 133.241772 -429.006842)
			(xy 133.249266 -428.983806) (xy 133.263506 -428.964209) (xy 133.283102 -428.949967) (xy 133.306138 -428.942472)
			(xy 133.31825 -428.941992) (xy 134.25805 -428.941992) (xy 134.270163 -428.942468) (xy 134.2932 -428.949964)
			(xy 134.312797 -428.964206) (xy 134.327038 -428.983804) (xy 134.334532 -429.006841) (xy 134.335012 -429.018954)
			(xy 134.335012 -431.560478) (xy 134.33447 -431.572586) (xy 134.326995 -431.59562) (xy 134.312769 -431.615218)
			(xy 134.293185 -431.629462) (xy 134.270158 -431.636959) (xy 134.25805 -431.63744) (xy 133.31825 -431.63744)
			(xy 133.306131 -431.63703) (xy 133.283082 -431.629527) (xy 133.263479 -431.615269) (xy 133.24924 -431.595653)
			(xy 133.241758 -431.572598) (xy 133.241288 -431.560478) (xy 133.241288 -430.948084) (xy 133.239745 -430.933592)
			(xy 133.238092 -430.904492) (xy 133.237986 -430.889918) (xy 132.335016 -430.889918) (xy 132.335016 -431.889916)
			(xy 135.237982 -431.889916) (xy 135.238076 -431.875342) (xy 135.239728 -431.846241) (xy 135.241284 -431.83175)
			(xy 135.241284 -430.747932) (xy 135.239736 -430.73344) (xy 135.238086 -430.70434) (xy 135.237982 -430.689766)
			(xy 135.23808 -430.675192) (xy 135.23973 -430.646091) (xy 135.241284 -430.6316) (xy 135.241284 -430.018952)
			(xy 135.241675 -430.006842) (xy 135.249186 -429.983816) (xy 135.263455 -429.964245) (xy 135.28308 -429.950052)
			(xy 135.306135 -429.942629) (xy 135.318246 -429.942244) (xy 136.258046 -429.942244) (xy 136.270138 -429.942668)
			(xy 136.293141 -429.950138) (xy 136.312721 -429.964336) (xy 136.32697 -429.983878) (xy 136.3345 -430.006861)
			(xy 136.335008 -430.018952) (xy 136.335008 -430.889918) (xy 137.237978 -430.889918) (xy 137.238072 -430.875344)
			(xy 137.239724 -430.846243) (xy 137.24128 -430.831752) (xy 137.24128 -429.747934) (xy 137.239733 -429.733442)
			(xy 137.238082 -429.704342) (xy 137.237978 -429.689768) (xy 137.238076 -429.675194) (xy 137.239726 -429.646093)
			(xy 137.24128 -429.631602) (xy 137.24128 -429.018954) (xy 137.241673 -429.006833) (xy 137.249178 -428.983781)
			(xy 137.263439 -428.964176) (xy 137.28306 -428.949938) (xy 137.30612 -428.942459) (xy 137.318242 -428.941992)
			(xy 138.258042 -428.941992) (xy 138.270154 -428.942475) (xy 138.293191 -428.949968) (xy 138.312788 -428.964209)
			(xy 138.32703 -428.983805) (xy 138.334524 -429.006842) (xy 138.335004 -429.018954) (xy 138.335004 -431.560478)
			(xy 138.33447 -431.572587) (xy 138.326994 -431.595623) (xy 138.312767 -431.615221) (xy 138.29318 -431.629465)
			(xy 138.270151 -431.63696) (xy 138.258042 -431.63744) (xy 137.318242 -431.63744) (xy 137.306119 -431.637004)
			(xy 137.283058 -431.629521) (xy 137.26344 -431.615274) (xy 137.249188 -431.59566) (xy 137.241699 -431.572601)
			(xy 137.24128 -431.560478) (xy 137.24128 -430.948084) (xy 137.239737 -430.933592) (xy 137.238084 -430.904492)
			(xy 137.237978 -430.889918) (xy 136.335008 -430.889918) (xy 136.335008 -431.889916) (xy 139.237974 -431.889916)
			(xy 139.238068 -431.875342) (xy 139.23972 -431.846241) (xy 139.241276 -431.83175) (xy 139.241276 -430.747932)
			(xy 139.239728 -430.73344) (xy 139.238078 -430.70434) (xy 139.237974 -430.689766) (xy 139.238072 -430.675192)
			(xy 139.239722 -430.646091) (xy 139.241276 -430.6316) (xy 139.241276 -430.018952) (xy 139.241675 -430.006843)
			(xy 139.249185 -429.983818) (xy 139.263452 -429.964248) (xy 139.283075 -429.950054) (xy 139.306128 -429.94263)
			(xy 139.318238 -429.942244) (xy 140.258038 -429.942244) (xy 140.27013 -429.942675) (xy 140.293133 -429.950143)
			(xy 140.312712 -429.964338) (xy 140.326961 -429.983879) (xy 140.334492 -430.006861) (xy 140.335 -430.018952)
			(xy 140.335 -430.889918) (xy 142.237968 -430.889918) (xy 142.238077 -430.874832) (xy 142.239859 -430.844714)
			(xy 142.241524 -430.82972) (xy 142.241524 -429.749966) (xy 142.239859 -429.734972) (xy 142.238078 -429.704854)
			(xy 142.237968 -429.689768) (xy 142.238082 -429.674682) (xy 142.23986 -429.644564) (xy 142.241524 -429.62957)
			(xy 142.241524 -429.018954) (xy 142.241968 -429.006864) (xy 142.249435 -428.983864) (xy 142.263628 -428.964286)
			(xy 142.283165 -428.950037) (xy 142.306143 -428.942503) (xy 142.318232 -428.941992) (xy 143.258032 -428.941992)
			(xy 143.270142 -428.942389) (xy 143.293169 -428.949896) (xy 143.312741 -428.964163) (xy 143.326934 -428.983788)
			(xy 143.334356 -429.006843) (xy 143.33474 -429.018954) (xy 143.33474 -431.560478) (xy 143.334273 -431.572568)
			(xy 143.32682 -431.595572) (xy 143.312634 -431.615154) (xy 143.293099 -431.629404) (xy 143.270121 -431.636933)
			(xy 143.258032 -431.63744) (xy 142.318232 -431.63744) (xy 142.306129 -431.636957) (xy 142.283109 -431.629471)
			(xy 142.263539 -431.615225) (xy 142.249342 -431.59562) (xy 142.241913 -431.572582) (xy 142.241524 -431.560478)
			(xy 142.241524 -430.950116) (xy 142.239855 -430.935123) (xy 142.238077 -430.905004) (xy 142.237968 -430.889918)
			(xy 140.335 -430.889918) (xy 140.335 -431.889916) (xy 144.237964 -431.889916) (xy 144.238073 -431.87483)
			(xy 144.239855 -431.844712) (xy 144.24152 -431.829718) (xy 144.24152 -430.749964) (xy 144.239855 -430.73497)
			(xy 144.238074 -430.704852) (xy 144.237964 -430.689766) (xy 144.238078 -430.67468) (xy 144.239856 -430.644562)
			(xy 144.24152 -430.629568) (xy 144.24152 -430.018952) (xy 144.241924 -430.006872) (xy 144.249403 -429.983899)
			(xy 144.263614 -429.96436) (xy 144.283167 -429.950168) (xy 144.306148 -429.942712) (xy 144.318228 -429.942244)
			(xy 145.258028 -429.942244) (xy 145.270099 -429.942739) (xy 145.293059 -429.950204) (xy 145.312592 -429.964394)
			(xy 145.326787 -429.983923) (xy 145.334258 -430.006881) (xy 145.334736 -430.018952) (xy 145.334736 -430.889918)
			(xy 146.23796 -430.889918) (xy 146.238069 -430.874832) (xy 146.239851 -430.844714) (xy 146.241516 -430.82972)
			(xy 146.241516 -429.749966) (xy 146.239851 -429.734972) (xy 146.23807 -429.704854) (xy 146.23796 -429.689768)
			(xy 146.238074 -429.674682) (xy 146.239852 -429.644564) (xy 146.241516 -429.62957) (xy 146.241516 -429.018954)
			(xy 146.241968 -429.006864) (xy 146.249434 -428.983866) (xy 146.263626 -428.964289) (xy 146.28316 -428.950039)
			(xy 146.306136 -428.942504) (xy 146.318224 -428.941992) (xy 147.258024 -428.941992) (xy 147.270133 -428.942396)
			(xy 147.29316 -428.949901) (xy 147.312732 -428.964166) (xy 147.326926 -428.983789) (xy 147.334348 -429.006843)
			(xy 147.334732 -429.018954) (xy 147.334732 -431.560478) (xy 147.334273 -431.572569) (xy 147.326819 -431.595574)
			(xy 147.312632 -431.615156) (xy 147.293094 -431.629407) (xy 147.270114 -431.636934) (xy 147.258024 -431.63744)
			(xy 146.318224 -431.63744) (xy 146.30612 -431.636964) (xy 146.283101 -431.629476) (xy 146.263531 -431.615228)
			(xy 146.249334 -431.595622) (xy 146.241905 -431.572583) (xy 146.241516 -431.560478) (xy 146.241516 -430.950116)
			(xy 146.239847 -430.935123) (xy 146.238069 -430.905004) (xy 146.23796 -430.889918) (xy 145.334736 -430.889918)
			(xy 145.334736 -431.889916) (xy 148.237956 -431.889916) (xy 148.238065 -431.87483) (xy 148.239847 -431.844712)
			(xy 148.241512 -431.829718) (xy 148.241512 -430.749964) (xy 148.239847 -430.73497) (xy 148.238066 -430.704852)
			(xy 148.237956 -430.689766) (xy 148.23807 -430.67468) (xy 148.239848 -430.644562) (xy 148.241512 -430.629568)
			(xy 148.241512 -430.018952) (xy 148.241924 -430.006873) (xy 148.249402 -429.983901) (xy 148.263611 -429.964363)
			(xy 148.283162 -429.950171) (xy 148.306141 -429.942713) (xy 148.31822 -429.942244) (xy 149.25802 -429.942244)
			(xy 149.270091 -429.942747) (xy 149.29305 -429.950209) (xy 149.312583 -429.964397) (xy 149.326778 -429.983924)
			(xy 149.334249 -430.006881) (xy 149.334728 -430.018952) (xy 149.334728 -430.889918) (xy 150.237952 -430.889918)
			(xy 150.238061 -430.874832) (xy 150.239843 -430.844714) (xy 150.241508 -430.82972) (xy 150.241508 -429.749966)
			(xy 150.239843 -429.734972) (xy 150.238062 -429.704854) (xy 150.237952 -429.689768) (xy 150.238066 -429.674682)
			(xy 150.239844 -429.644564) (xy 150.241508 -429.62957) (xy 150.241508 -429.018954) (xy 150.241968 -429.006865)
			(xy 150.249433 -428.983868) (xy 150.263623 -428.964292) (xy 150.283155 -428.950042) (xy 150.306129 -428.942505)
			(xy 150.318216 -428.941992) (xy 151.258016 -428.941992) (xy 151.270125 -428.942402) (xy 151.293151 -428.949905)
			(xy 151.312724 -428.964169) (xy 151.326918 -428.983791) (xy 151.33434 -429.006844) (xy 151.334724 -429.018954)
			(xy 151.334724 -431.560478) (xy 151.334273 -431.57257) (xy 151.326818 -431.595576) (xy 151.312629 -431.615159)
			(xy 151.293089 -431.629409) (xy 151.270106 -431.636935) (xy 151.258016 -431.63744) (xy 150.318216 -431.63744)
			(xy 150.306112 -431.63697) (xy 150.283092 -431.62948) (xy 150.263522 -431.615231) (xy 150.249326 -431.595623)
			(xy 150.241897 -431.572583) (xy 150.241508 -431.560478) (xy 150.241508 -430.950116) (xy 150.239839 -430.935123)
			(xy 150.238061 -430.905004) (xy 150.237952 -430.889918) (xy 149.334728 -430.889918) (xy 149.334728 -431.889916)
			(xy 152.237948 -431.889916) (xy 152.238057 -431.87483) (xy 152.239839 -431.844712) (xy 152.241504 -431.829718)
			(xy 152.241504 -430.749964) (xy 152.239839 -430.73497) (xy 152.238058 -430.704852) (xy 152.237948 -430.689766)
			(xy 152.238062 -430.67468) (xy 152.23984 -430.644562) (xy 152.241504 -430.629568) (xy 152.241504 -430.018952)
			(xy 152.241923 -430.006874) (xy 152.249401 -429.983903) (xy 152.263608 -429.964366) (xy 152.283157 -429.950173)
			(xy 152.306133 -429.942714) (xy 152.318212 -429.942244) (xy 153.258012 -429.942244) (xy 153.270082 -429.942753)
			(xy 153.293042 -429.950213) (xy 153.312574 -429.9644) (xy 153.32677 -429.983926) (xy 153.334241 -430.006882)
			(xy 153.33472 -430.018952) (xy 153.33472 -430.889918) (xy 154.237944 -430.889918) (xy 154.238053 -430.874832)
			(xy 154.239835 -430.844714) (xy 154.2415 -430.82972) (xy 154.2415 -429.749966) (xy 154.239835 -429.734972)
			(xy 154.238054 -429.704854) (xy 154.237944 -429.689768) (xy 154.238058 -429.674682) (xy 154.239836 -429.644564)
			(xy 154.2415 -429.62957) (xy 154.2415 -429.018954) (xy 154.241967 -429.006866) (xy 154.249432 -428.983871)
			(xy 154.26362 -428.964295) (xy 154.28315 -428.950044) (xy 154.306122 -428.942507) (xy 154.318208 -428.941992)
			(xy 155.258008 -428.941992) (xy 155.270117 -428.942409) (xy 155.293143 -428.94991) (xy 155.312715 -428.964172)
			(xy 155.32691 -428.983792) (xy 155.334332 -429.006844) (xy 155.334716 -429.018954) (xy 155.334716 -431.560478)
			(xy 155.334273 -431.572571) (xy 155.326817 -431.595578) (xy 155.312626 -431.615162) (xy 155.293084 -431.629412)
			(xy 155.270099 -431.636937) (xy 155.258008 -431.63744) (xy 154.318208 -431.63744) (xy 154.306104 -431.636978)
			(xy 154.283083 -431.629485) (xy 154.263513 -431.615234) (xy 154.249317 -431.595625) (xy 154.241889 -431.572584)
			(xy 154.2415 -431.560478) (xy 154.2415 -430.950116) (xy 154.239831 -430.935123) (xy 154.238053 -430.905004)
			(xy 154.237944 -430.889918) (xy 153.33472 -430.889918) (xy 153.33472 -431.889916) (xy 156.23794 -431.889916)
			(xy 156.238051 -431.87483) (xy 156.239833 -431.844712) (xy 156.241496 -431.829718) (xy 156.241496 -430.749964)
			(xy 156.239831 -430.73497) (xy 156.23805 -430.704852) (xy 156.23794 -430.689766) (xy 156.238054 -430.67468)
			(xy 156.239832 -430.644562) (xy 156.241496 -430.629568) (xy 156.241496 -430.018952) (xy 156.241923 -430.006875)
			(xy 156.249399 -429.983905) (xy 156.263605 -429.964368) (xy 156.283152 -429.950176) (xy 156.306126 -429.942715)
			(xy 156.318204 -429.942244) (xy 157.258004 -429.942244) (xy 157.270074 -429.94276) (xy 157.293033 -429.950218)
			(xy 157.312566 -429.964403) (xy 157.326762 -429.983927) (xy 157.334233 -430.006882) (xy 157.334712 -430.018952)
			(xy 157.334712 -432.560476) (xy 157.334267 -432.572557) (xy 157.326806 -432.595538) (xy 157.312609 -432.615089)
			(xy 157.293063 -432.629294) (xy 157.270085 -432.636762) (xy 157.258004 -432.637184) (xy 156.318204 -432.637184)
			(xy 156.306119 -432.636784) (xy 156.283132 -432.629314) (xy 156.26358 -432.615106) (xy 156.249376 -432.59555)
			(xy 156.241913 -432.572561) (xy 156.241496 -432.560476) (xy 156.241496 -431.950114) (xy 156.239826 -431.935121)
			(xy 156.238049 -431.905002) (xy 156.23794 -431.889916) (xy 153.33472 -431.889916) (xy 153.33472 -432.560476)
			(xy 153.334267 -432.572556) (xy 153.326807 -432.595536) (xy 153.312611 -432.615086) (xy 153.293068 -432.629291)
			(xy 153.270092 -432.636761) (xy 153.258012 -432.637184) (xy 152.318212 -432.637184) (xy 152.306128 -432.636777)
			(xy 152.283141 -432.629309) (xy 152.263589 -432.615103) (xy 152.249385 -432.595548) (xy 152.241922 -432.572561)
			(xy 152.241504 -432.560476) (xy 152.241504 -431.950114) (xy 152.239834 -431.935121) (xy 152.238057 -431.905002)
			(xy 152.237948 -431.889916) (xy 149.334728 -431.889916) (xy 149.334728 -432.560476) (xy 149.334267 -432.572555)
			(xy 149.326809 -432.595534) (xy 149.312614 -432.615083) (xy 149.293073 -432.629288) (xy 149.270099 -432.63676)
			(xy 149.25802 -432.637184) (xy 148.31822 -432.637184) (xy 148.306136 -432.63677) (xy 148.28315 -432.629305)
			(xy 148.263597 -432.6151) (xy 148.249393 -432.595547) (xy 148.24193 -432.57256) (xy 148.241512 -432.560476)
			(xy 148.241512 -431.950114) (xy 148.239842 -431.935121) (xy 148.238065 -431.905002) (xy 148.237956 -431.889916)
			(xy 145.334736 -431.889916) (xy 145.334736 -432.560476) (xy 145.334216 -432.572547) (xy 145.326763 -432.595508)
			(xy 145.31258 -432.615043) (xy 145.293055 -432.62924) (xy 145.270098 -432.636708) (xy 145.258028 -432.637184)
			(xy 144.318228 -432.637184) (xy 144.306144 -432.636763) (xy 144.283159 -432.6293) (xy 144.263606 -432.615097)
			(xy 144.249402 -432.595545) (xy 144.241938 -432.57256) (xy 144.24152 -432.560476) (xy 144.24152 -431.950114)
			(xy 144.23985 -431.935121) (xy 144.238073 -431.905002) (xy 144.237964 -431.889916) (xy 140.335 -431.889916)
			(xy 140.335 -432.560476) (xy 140.334563 -432.572584) (xy 140.32707 -432.59561) (xy 140.312814 -432.615184)
			(xy 140.293196 -432.629379) (xy 140.270147 -432.6368) (xy 140.258038 -432.637184) (xy 139.318238 -432.637184)
			(xy 139.306153 -432.636661) (xy 139.283157 -432.629217) (xy 139.263579 -432.615044) (xy 139.249326 -432.595524)
			(xy 139.241789 -432.572559) (xy 139.241276 -432.560476) (xy 139.241276 -431.948082) (xy 139.239733 -431.93359)
			(xy 139.23808 -431.90449) (xy 139.237974 -431.889916) (xy 136.335008 -431.889916) (xy 136.335008 -432.560476)
			(xy 136.334563 -432.572583) (xy 136.327071 -432.595608) (xy 136.312817 -432.615181) (xy 136.293201 -432.629376)
			(xy 136.270154 -432.636799) (xy 136.258046 -432.637184) (xy 135.318246 -432.637184) (xy 135.306161 -432.636654)
			(xy 135.283166 -432.629213) (xy 135.263587 -432.615042) (xy 135.249334 -432.595522) (xy 135.241797 -432.572559)
			(xy 135.241284 -432.560476) (xy 135.241284 -431.948082) (xy 135.239741 -431.93359) (xy 135.238088 -431.90449)
			(xy 135.237982 -431.889916) (xy 132.335016 -431.889916) (xy 132.335016 -432.560476) (xy 132.334563 -432.572582)
			(xy 132.327072 -432.595606) (xy 132.31282 -432.615178) (xy 132.293206 -432.629374) (xy 132.270161 -432.636798)
			(xy 132.258054 -432.637184) (xy 131.318254 -432.637184) (xy 131.306164 -432.636732) (xy 131.283166 -432.629266)
			(xy 131.263589 -432.615074) (xy 131.249339 -432.59554) (xy 131.241804 -432.572564) (xy 131.241292 -432.560476)
			(xy 131.241292 -431.948082) (xy 131.239749 -431.93359) (xy 131.238096 -431.90449) (xy 131.23799 -431.889916)
			(xy 128.335024 -431.889916) (xy 128.335024 -432.560476) (xy 128.334563 -432.572581) (xy 128.327074 -432.595604)
			(xy 128.312823 -432.615175) (xy 128.293212 -432.629371) (xy 128.270168 -432.636797) (xy 128.258062 -432.637184)
			(xy 127.318262 -432.637184) (xy 127.306173 -432.636726) (xy 127.283175 -432.629261) (xy 127.263598 -432.615072)
			(xy 127.249348 -432.595538) (xy 127.241812 -432.572564) (xy 127.2413 -432.560476) (xy 127.2413 -431.948082)
			(xy 127.239756 -431.93359) (xy 127.238104 -431.90449) (xy 127.237998 -431.889916) (xy 115.605768 -431.889916)
			(xy 115.596243 -431.956613) (xy 115.564055 -432.124765) (xy 115.523953 -432.291207) (xy 115.476027 -432.455567)
			(xy 115.420385 -432.617477) (xy 115.35715 -432.776576) (xy 115.286464 -432.932508) (xy 115.208486 -433.084923)
			(xy 115.12339 -433.233482) (xy 115.031365 -433.377851) (xy 114.932619 -433.517709) (xy 114.82737 -433.652742)
			(xy 114.715856 -433.782648) (xy 114.598325 -433.907137) (xy 114.47504 -434.02593) (xy 114.346277 -434.138763)
			(xy 114.212324 -434.245381) (xy 114.07348 -434.345548) (xy 113.930056 -434.439039) (xy 113.843394 -434.48986)
			(xy 125.238002 -434.48986) (xy 125.2381 -434.475286) (xy 125.239749 -434.446185) (xy 125.241304 -434.431694)
			(xy 125.241304 -433.34813) (xy 125.239756 -433.333638) (xy 125.238106 -433.304538) (xy 125.238002 -433.289964)
			(xy 125.2381 -433.27539) (xy 125.239749 -433.246289) (xy 125.241304 -433.231798) (xy 125.241304 -432.618896)
			(xy 125.241713 -432.606787) (xy 125.249214 -432.583758) (xy 125.263477 -432.564185) (xy 125.283101 -432.549991)
			(xy 125.306155 -432.542571) (xy 125.318266 -432.542188) (xy 126.258066 -432.542188) (xy 126.270159 -432.542637)
			(xy 126.293166 -432.55009) (xy 126.312751 -432.56428) (xy 126.327001 -432.583821) (xy 126.334525 -432.606805)
			(xy 126.335028 -432.618896) (xy 126.335028 -435.16042) (xy 126.334601 -435.172527) (xy 126.3271 -435.19555)
			(xy 126.31284 -435.215121) (xy 126.293222 -435.229316) (xy 126.270174 -435.236741) (xy 126.258066 -435.237128)
			(xy 125.318266 -435.237128) (xy 125.306171 -435.236721) (xy 125.283164 -435.229251) (xy 125.263582 -435.21505)
			(xy 125.249334 -435.195502) (xy 125.241808 -435.172513) (xy 125.241304 -435.16042) (xy 125.241304 -434.548026)
			(xy 125.239756 -434.533534) (xy 125.238106 -434.504434) (xy 125.238002 -434.48986) (xy 113.843394 -434.48986)
			(xy 113.782372 -434.525645) (xy 113.630759 -434.605172) (xy 113.475556 -434.677443) (xy 113.396522 -434.710332)
			(xy 113.382851 -434.716444) (xy 113.359598 -434.735293) (xy 113.342813 -434.760077) (xy 113.333939 -434.788665)
			(xy 113.333741 -434.818598) (xy 113.342235 -434.847301) (xy 113.358691 -434.872305) (xy 113.369852 -434.88229)
			(xy 113.419298 -434.924299) (xy 113.513487 -435.013553) (xy 113.601975 -435.108462) (xy 113.684422 -435.208663)
			(xy 113.760513 -435.313772) (xy 113.829956 -435.423387) (xy 113.866512 -435.489858) (xy 127.237998 -435.489858)
			(xy 127.238095 -435.475284) (xy 127.239745 -435.446183) (xy 127.2413 -435.431692) (xy 127.2413 -434.348128)
			(xy 127.239752 -434.333636) (xy 127.238102 -434.304536) (xy 127.237998 -434.289962) (xy 127.238096 -434.275388)
			(xy 127.239745 -434.246287) (xy 127.2413 -434.231796) (xy 127.2413 -433.618894) (xy 127.241806 -433.606783)
			(xy 127.24929 -433.583746) (xy 127.263525 -433.564148) (xy 127.283117 -433.549905) (xy 127.306151 -433.542411)
			(xy 127.318262 -433.541932) (xy 128.258062 -433.541932) (xy 128.270182 -433.542392) (xy 128.293239 -433.549873)
			(xy 128.312854 -433.564115) (xy 128.327107 -433.583722) (xy 128.334601 -433.606774) (xy 128.335024 -433.618894)
			(xy 128.335024 -434.48986) (xy 129.237994 -434.48986) (xy 129.238092 -434.475286) (xy 129.239741 -434.446185)
			(xy 129.241296 -434.431694) (xy 129.241296 -433.34813) (xy 129.239748 -433.333638) (xy 129.238098 -433.304538)
			(xy 129.237994 -433.289964) (xy 129.238092 -433.27539) (xy 129.239741 -433.246289) (xy 129.241296 -433.231798)
			(xy 129.241296 -432.618896) (xy 129.241713 -432.606787) (xy 129.249213 -432.583761) (xy 129.263474 -432.564188)
			(xy 129.283096 -432.549993) (xy 129.306148 -432.542572) (xy 129.318258 -432.542188) (xy 130.258058 -432.542188)
			(xy 130.27015 -432.542644) (xy 130.293158 -432.550095) (xy 130.312742 -432.564283) (xy 130.326993 -432.583822)
			(xy 130.334517 -432.606805) (xy 130.33502 -432.618896) (xy 130.33502 -435.16042) (xy 130.334601 -435.172528)
			(xy 130.327099 -435.195552) (xy 130.312837 -435.215123) (xy 130.293217 -435.229318) (xy 130.270167 -435.236742)
			(xy 130.258058 -435.237128) (xy 129.318258 -435.237128) (xy 129.306163 -435.236728) (xy 129.283156 -435.229256)
			(xy 129.263574 -435.215053) (xy 129.249326 -435.195504) (xy 129.2418 -435.172514) (xy 129.241296 -435.16042)
			(xy 129.241296 -434.548026) (xy 129.239748 -434.533534) (xy 129.238098 -434.504434) (xy 129.237994 -434.48986)
			(xy 128.335024 -434.48986) (xy 128.335024 -435.489858) (xy 131.23799 -435.489858) (xy 131.238087 -435.475284)
			(xy 131.239737 -435.446183) (xy 131.241292 -435.431692) (xy 131.241292 -434.348128) (xy 131.239744 -434.333636)
			(xy 131.238094 -434.304536) (xy 131.23799 -434.289962) (xy 131.238088 -434.275388) (xy 131.239737 -434.246287)
			(xy 131.241292 -434.231796) (xy 131.241292 -433.618894) (xy 131.241806 -433.606784) (xy 131.249289 -433.583748)
			(xy 131.263522 -433.564151) (xy 131.283112 -433.549908) (xy 131.306144 -433.542412) (xy 131.318254 -433.541932)
			(xy 132.258054 -433.541932) (xy 132.270174 -433.542399) (xy 132.29323 -433.549878) (xy 132.312846 -433.564117)
			(xy 132.327098 -433.583723) (xy 132.334593 -433.606775) (xy 132.335016 -433.618894) (xy 132.335016 -434.48986)
			(xy 133.237986 -434.48986) (xy 133.238084 -434.475286) (xy 133.239733 -434.446185) (xy 133.241288 -434.431694)
			(xy 133.241288 -433.34813) (xy 133.23974 -433.333638) (xy 133.23809 -433.304538) (xy 133.237986 -433.289964)
			(xy 133.238084 -433.27539) (xy 133.239733 -433.246289) (xy 133.241288 -433.231798) (xy 133.241288 -432.618896)
			(xy 133.241713 -432.606788) (xy 133.249212 -432.583763) (xy 133.263472 -432.564191) (xy 133.283091 -432.549996)
			(xy 133.306141 -432.542573) (xy 133.31825 -432.542188) (xy 134.25805 -432.542188) (xy 134.270142 -432.542651)
			(xy 134.293149 -432.5501) (xy 134.312734 -432.564285) (xy 134.326984 -432.583823) (xy 134.334509 -432.606806)
			(xy 134.335012 -432.618896) (xy 134.335012 -435.16042) (xy 134.334601 -435.172529) (xy 134.327097 -435.195555)
			(xy 134.312834 -435.215126) (xy 134.293212 -435.229321) (xy 134.27016 -435.236743) (xy 134.25805 -435.237128)
			(xy 133.31825 -435.237128) (xy 133.30616 -435.23665) (xy 133.283155 -435.229203) (xy 133.263572 -435.21502)
			(xy 133.249321 -435.195487) (xy 133.241793 -435.172508) (xy 133.241288 -435.16042) (xy 133.241288 -434.548026)
			(xy 133.23974 -434.533534) (xy 133.23809 -434.504434) (xy 133.237986 -434.48986) (xy 132.335016 -434.48986)
			(xy 132.335016 -435.489858) (xy 135.237982 -435.489858) (xy 135.238079 -435.475284) (xy 135.239729 -435.446183)
			(xy 135.241284 -435.431692) (xy 135.241284 -434.348128) (xy 135.239736 -434.333636) (xy 135.238086 -434.304536)
			(xy 135.237982 -434.289962) (xy 135.23808 -434.275388) (xy 135.239729 -434.246287) (xy 135.241284 -434.231796)
			(xy 135.241284 -433.618894) (xy 135.241656 -433.606766) (xy 135.249155 -433.5837) (xy 135.263418 -433.564081)
			(xy 135.283046 -433.549831) (xy 135.306118 -433.542348) (xy 135.318246 -433.541932) (xy 136.258046 -433.541932)
			(xy 136.270162 -433.542372) (xy 136.293206 -433.549872) (xy 136.312807 -433.564122) (xy 136.327047 -433.58373)
			(xy 136.334534 -433.606777) (xy 136.335008 -433.618894) (xy 136.335008 -434.48986) (xy 137.237978 -434.48986)
			(xy 137.238076 -434.475286) (xy 137.239725 -434.446185) (xy 137.24128 -434.431694) (xy 137.24128 -433.34813)
			(xy 137.239732 -433.333638) (xy 137.238082 -433.304538) (xy 137.237978 -433.289964) (xy 137.238076 -433.27539)
			(xy 137.239726 -433.246289) (xy 137.24128 -433.231798) (xy 137.24128 -432.618896) (xy 137.241712 -432.606789)
			(xy 137.249211 -432.583765) (xy 137.263469 -432.564194) (xy 137.283086 -432.549998) (xy 137.306134 -432.542574)
			(xy 137.318242 -432.542188) (xy 138.258042 -432.542188) (xy 138.270139 -432.542572) (xy 138.293149 -432.550047)
			(xy 138.312732 -432.564253) (xy 138.326979 -432.583806) (xy 138.334502 -432.606801) (xy 138.335004 -432.618896)
			(xy 138.335004 -435.16042) (xy 138.334601 -435.17253) (xy 138.327096 -435.195557) (xy 138.312831 -435.215129)
			(xy 138.293207 -435.229323) (xy 138.270153 -435.236744) (xy 138.258042 -435.237128) (xy 137.318242 -435.237128)
			(xy 137.306151 -435.236656) (xy 137.283147 -435.229207) (xy 137.263563 -435.215023) (xy 137.249313 -435.195488)
			(xy 137.241785 -435.172509) (xy 137.24128 -435.16042) (xy 137.24128 -434.548026) (xy 137.239732 -434.533534)
			(xy 137.238082 -434.504434) (xy 137.237978 -434.48986) (xy 136.335008 -434.48986) (xy 136.335008 -435.489858)
			(xy 139.237974 -435.489858) (xy 139.238072 -435.475284) (xy 139.239721 -435.446183) (xy 139.241276 -435.431692)
			(xy 139.241276 -434.348128) (xy 139.239728 -434.333636) (xy 139.238078 -434.304536) (xy 139.237974 -434.289962)
			(xy 139.238072 -434.275388) (xy 139.239721 -434.246287) (xy 139.241276 -434.231796) (xy 139.241276 -433.618894)
			(xy 139.241656 -433.606767) (xy 139.249154 -433.583702) (xy 139.263415 -433.564084) (xy 139.283041 -433.549834)
			(xy 139.306111 -433.542349) (xy 139.318238 -433.541932) (xy 140.258038 -433.541932) (xy 140.270154 -433.542379)
			(xy 140.293197 -433.549876) (xy 140.312798 -433.564125) (xy 140.327038 -433.583731) (xy 140.334526 -433.606778)
			(xy 140.335 -433.618894) (xy 140.335 -434.48986) (xy 142.237968 -434.48986) (xy 142.238081 -434.474774)
			(xy 142.23986 -434.444656) (xy 142.241524 -434.429662) (xy 142.241524 -433.350162) (xy 142.239859 -433.335168)
			(xy 142.238078 -433.30505) (xy 142.237968 -433.289964) (xy 142.238081 -433.274878) (xy 142.23986 -433.24476)
			(xy 142.241524 -433.229766) (xy 142.241524 -432.618896) (xy 142.24191 -432.60681) (xy 142.249382 -432.583822)
			(xy 142.263594 -432.564268) (xy 142.283154 -432.550066) (xy 142.306146 -432.542604) (xy 142.318232 -432.542188)
			(xy 143.258032 -432.542188) (xy 143.270108 -432.542637) (xy 143.293075 -432.550108) (xy 143.312612 -432.564308)
			(xy 143.326805 -432.58385) (xy 143.334268 -432.60682) (xy 143.33474 -432.618896) (xy 143.33474 -435.16042)
			(xy 143.334253 -435.172492) (xy 143.326789 -435.195455) (xy 143.312597 -435.214989) (xy 143.293065 -435.229184)
			(xy 143.270104 -435.236651) (xy 143.258032 -435.237128) (xy 142.318232 -435.237128) (xy 142.306153 -435.23666)
			(xy 142.283175 -435.229204) (xy 142.263626 -435.215011) (xy 142.24942 -435.195472) (xy 142.241948 -435.172499)
			(xy 142.241524 -435.16042) (xy 142.241524 -434.550058) (xy 142.239858 -434.535064) (xy 142.238078 -434.504946)
			(xy 142.237968 -434.48986) (xy 140.335 -434.48986) (xy 140.335 -435.489858) (xy 144.237964 -435.489858)
			(xy 144.238077 -435.474772) (xy 144.239856 -435.444654) (xy 144.24152 -435.42966) (xy 144.24152 -434.35016)
			(xy 144.239855 -434.335166) (xy 144.238074 -434.305048) (xy 144.237964 -434.289962) (xy 144.238077 -434.274876)
			(xy 144.239856 -434.244758) (xy 144.24152 -434.229764) (xy 144.24152 -433.618894) (xy 144.242002 -433.606806)
			(xy 144.249458 -433.583809) (xy 144.263641 -433.564231) (xy 144.28317 -433.54998) (xy 144.306142 -433.542444)
			(xy 144.318228 -433.541932) (xy 145.258028 -433.541932) (xy 145.270142 -433.542293) (xy 145.293175 -433.549804)
			(xy 145.312751 -433.564079) (xy 145.326943 -433.583714) (xy 145.334357 -433.606779) (xy 145.334736 -433.618894)
			(xy 145.334736 -434.48986) (xy 146.23796 -434.48986) (xy 146.238073 -434.474774) (xy 146.239852 -434.444656)
			(xy 146.241516 -434.429662) (xy 146.241516 -433.350162) (xy 146.239851 -433.335168) (xy 146.23807 -433.30505)
			(xy 146.23796 -433.289964) (xy 146.238073 -433.274878) (xy 146.239852 -433.24476) (xy 146.241516 -433.229766)
			(xy 146.241516 -432.618896) (xy 146.241909 -432.606811) (xy 146.249381 -432.583824) (xy 146.263591 -432.564271)
			(xy 146.283149 -432.550068) (xy 146.306138 -432.542605) (xy 146.318224 -432.542188) (xy 147.258024 -432.542188)
			(xy 147.270099 -432.542644) (xy 147.293067 -432.550113) (xy 147.312603 -432.564311) (xy 147.326797 -432.583851)
			(xy 147.334259 -432.606821) (xy 147.334732 -432.618896) (xy 147.334732 -435.16042) (xy 147.334253 -435.172493)
			(xy 147.326788 -435.195457) (xy 147.312594 -435.214991) (xy 147.29306 -435.229186) (xy 147.270097 -435.236652)
			(xy 147.258024 -435.237128) (xy 146.318224 -435.237128) (xy 146.306145 -435.236667) (xy 146.283166 -435.229209)
			(xy 146.263617 -435.215014) (xy 146.249412 -435.195473) (xy 146.24194 -435.172499) (xy 146.241516 -435.16042)
			(xy 146.241516 -434.550058) (xy 146.23985 -434.535064) (xy 146.23807 -434.504946) (xy 146.23796 -434.48986)
			(xy 145.334736 -434.48986) (xy 145.334736 -435.489858) (xy 148.237956 -435.489858) (xy 148.238069 -435.474772)
			(xy 148.239848 -435.444654) (xy 148.241512 -435.42966) (xy 148.241512 -434.35016) (xy 148.239847 -434.335166)
			(xy 148.238066 -434.305048) (xy 148.237956 -434.289962) (xy 148.238069 -434.274876) (xy 148.239848 -434.244758)
			(xy 148.241512 -434.229764) (xy 148.241512 -433.618894) (xy 148.242002 -433.606807) (xy 148.249457 -433.583811)
			(xy 148.263639 -433.564234) (xy 148.283165 -433.549982) (xy 148.306135 -433.542445) (xy 148.31822 -433.541932)
			(xy 149.25802 -433.541932) (xy 149.270133 -433.5423) (xy 149.293167 -433.549808) (xy 149.312742 -433.564081)
			(xy 149.326935 -433.583715) (xy 149.334349 -433.606779) (xy 149.334728 -433.618894) (xy 149.334728 -434.48986)
			(xy 150.237952 -434.48986) (xy 150.238065 -434.474774) (xy 150.239844 -434.444656) (xy 150.241508 -434.429662)
			(xy 150.241508 -433.350162) (xy 150.239843 -433.335168) (xy 150.238062 -433.30505) (xy 150.237952 -433.289964)
			(xy 150.238065 -433.274878) (xy 150.239844 -433.24476) (xy 150.241508 -433.229766) (xy 150.241508 -432.618896)
			(xy 150.241909 -432.606811) (xy 150.24938 -432.583826) (xy 150.263588 -432.564274) (xy 150.283144 -432.550071)
			(xy 150.306131 -432.542606) (xy 150.318216 -432.542188) (xy 151.258016 -432.542188) (xy 151.270091 -432.542651)
			(xy 151.293058 -432.550117) (xy 151.312594 -432.564314) (xy 151.326788 -432.583853) (xy 151.334251 -432.606821)
			(xy 151.334724 -432.618896) (xy 151.334724 -435.16042) (xy 151.334253 -435.172494) (xy 151.326787 -435.195459)
			(xy 151.312591 -435.214994) (xy 151.293055 -435.229189) (xy 151.27009 -435.236654) (xy 151.258016 -435.237128)
			(xy 150.318216 -435.237128) (xy 150.306144 -435.236622) (xy 150.283181 -435.229167) (xy 150.263645 -435.21498)
			(xy 150.24945 -435.195451) (xy 150.241983 -435.172492) (xy 150.241508 -435.16042) (xy 150.241508 -434.550058)
			(xy 150.239842 -434.535064) (xy 150.238062 -434.504946) (xy 150.237952 -434.48986) (xy 149.334728 -434.48986)
			(xy 149.334728 -435.489858) (xy 152.237948 -435.489858) (xy 152.238061 -435.474772) (xy 152.23984 -435.444654)
			(xy 152.241504 -435.42966) (xy 152.241504 -434.35016) (xy 152.239838 -434.335166) (xy 152.238058 -434.305048)
			(xy 152.237948 -434.289962) (xy 152.238061 -434.274876) (xy 152.23984 -434.244758) (xy 152.241504 -434.229764)
			(xy 152.241504 -433.618894) (xy 152.242002 -433.606808) (xy 152.249456 -433.583813) (xy 152.263636 -433.564236)
			(xy 152.28316 -433.549985) (xy 152.306128 -433.542447) (xy 152.318212 -433.541932) (xy 153.258012 -433.541932)
			(xy 153.270125 -433.542306) (xy 153.293158 -433.549813) (xy 153.312734 -433.564084) (xy 153.326927 -433.583717)
			(xy 153.334341 -433.60678) (xy 153.33472 -433.618894) (xy 153.33472 -434.48986) (xy 154.237944 -434.48986)
			(xy 154.238057 -434.474774) (xy 154.239836 -434.444656) (xy 154.2415 -434.429662) (xy 154.2415 -433.350162)
			(xy 154.239835 -433.335168) (xy 154.238054 -433.30505) (xy 154.237944 -433.289964) (xy 154.238057 -433.274878)
			(xy 154.239836 -433.24476) (xy 154.2415 -433.229766) (xy 154.2415 -432.618896) (xy 154.241909 -432.606812)
			(xy 154.249379 -432.583828) (xy 154.263586 -432.564277) (xy 154.283139 -432.550073) (xy 154.306124 -432.542607)
			(xy 154.318208 -432.542188) (xy 155.258008 -432.542188) (xy 155.270083 -432.542657) (xy 155.293049 -432.550122)
			(xy 155.312586 -432.564317) (xy 155.32678 -432.583854) (xy 155.334243 -432.606821) (xy 155.334716 -432.618896)
			(xy 155.334716 -433.130695) (xy 197.035917 -433.130695) (xy 197.035917 -432.953425) (xy 197.04387 -432.776334)
			(xy 197.059761 -432.599778) (xy 197.083556 -432.424113) (xy 197.115209 -432.249692) (xy 197.154655 -432.076867)
			(xy 197.201815 -431.905986) (xy 197.256594 -431.737392) (xy 197.318882 -431.571427) (xy 197.388554 -431.408422)
			(xy 197.465468 -431.248708) (xy 197.549471 -431.092605) (xy 197.640392 -430.940428) (xy 197.738049 -430.792484)
			(xy 197.842246 -430.64907) (xy 197.952772 -430.510475) (xy 198.069404 -430.376978) (xy 198.191909 -430.248849)
			(xy 198.320038 -430.126344) (xy 198.453535 -430.009712) (xy 198.59213 -429.899186) (xy 198.735544 -429.794989)
			(xy 198.883488 -429.697332) (xy 199.035665 -429.606411) (xy 199.191768 -429.522408) (xy 199.351482 -429.445494)
			(xy 199.514487 -429.375822) (xy 199.680452 -429.313534) (xy 199.849046 -429.258755) (xy 200.019927 -429.211595)
			(xy 200.192752 -429.172149) (xy 200.367173 -429.140496) (xy 200.542838 -429.116701) (xy 200.719394 -429.10081)
			(xy 200.896485 -429.092857) (xy 201.073755 -429.092857) (xy 201.250846 -429.10081) (xy 201.427402 -429.116701)
			(xy 201.603067 -429.140496) (xy 201.777488 -429.172149) (xy 201.950313 -429.211595) (xy 202.121194 -429.258755)
			(xy 202.289788 -429.313534) (xy 202.455753 -429.375822) (xy 202.618758 -429.445494) (xy 202.778472 -429.522408)
			(xy 202.934575 -429.606411) (xy 203.086752 -429.697332) (xy 203.234696 -429.794989) (xy 203.37811 -429.899186)
			(xy 203.516705 -430.009712) (xy 203.650202 -430.126344) (xy 203.778331 -430.248849) (xy 203.900836 -430.376978)
			(xy 204.017468 -430.510475) (xy 204.127994 -430.64907) (xy 204.232191 -430.792484) (xy 204.329848 -430.940428)
			(xy 204.420769 -431.092605) (xy 204.504772 -431.248708) (xy 204.581686 -431.408422) (xy 204.651358 -431.571427)
			(xy 204.713646 -431.737392) (xy 204.768425 -431.905986) (xy 204.815585 -432.076867) (xy 204.855031 -432.249692)
			(xy 204.886684 -432.424113) (xy 204.910479 -432.599778) (xy 204.92637 -432.776334) (xy 204.934323 -432.953425)
			(xy 204.93482 -433.04206) (xy 204.934323 -433.130695) (xy 204.92637 -433.307786) (xy 204.910479 -433.484342)
			(xy 204.886684 -433.660007) (xy 204.855031 -433.834428) (xy 204.815585 -434.007253) (xy 204.768425 -434.178134)
			(xy 204.713646 -434.346728) (xy 204.651358 -434.512693) (xy 204.581686 -434.675698) (xy 204.504772 -434.835412)
			(xy 204.420769 -434.991515) (xy 204.329848 -435.143692) (xy 204.232191 -435.291636) (xy 204.127994 -435.43505)
			(xy 204.017468 -435.573645) (xy 203.900836 -435.707142) (xy 203.778331 -435.835271) (xy 203.650202 -435.957776)
			(xy 203.516705 -436.074408) (xy 203.37811 -436.184934) (xy 203.234696 -436.289131) (xy 203.086752 -436.386788)
			(xy 202.934575 -436.477709) (xy 202.778472 -436.561712) (xy 202.618758 -436.638626) (xy 202.455753 -436.708298)
			(xy 202.289788 -436.770586) (xy 202.121194 -436.825365) (xy 201.950313 -436.872525) (xy 201.777488 -436.911971)
			(xy 201.603067 -436.943624) (xy 201.427402 -436.967419) (xy 201.250846 -436.98331) (xy 201.073755 -436.991263)
			(xy 200.896485 -436.991263) (xy 200.719394 -436.98331) (xy 200.542838 -436.967419) (xy 200.367173 -436.943624)
			(xy 200.192752 -436.911971) (xy 200.019927 -436.872525) (xy 199.849046 -436.825365) (xy 199.680452 -436.770586)
			(xy 199.514487 -436.708298) (xy 199.351482 -436.638626) (xy 199.191768 -436.561712) (xy 199.035665 -436.477709)
			(xy 198.883488 -436.386788) (xy 198.735544 -436.289131) (xy 198.59213 -436.184934) (xy 198.453535 -436.074408)
			(xy 198.320038 -435.957776) (xy 198.191909 -435.835271) (xy 198.069404 -435.707142) (xy 197.952772 -435.573645)
			(xy 197.842246 -435.43505) (xy 197.738049 -435.291636) (xy 197.640392 -435.143692) (xy 197.549471 -434.991515)
			(xy 197.465468 -434.835412) (xy 197.388554 -434.675698) (xy 197.318882 -434.512693) (xy 197.256594 -434.346728)
			(xy 197.201815 -434.178134) (xy 197.154655 -434.007253) (xy 197.115209 -433.834428) (xy 197.083556 -433.660007)
			(xy 197.059761 -433.484342) (xy 197.04387 -433.307786) (xy 197.035917 -433.130695) (xy 155.334716 -433.130695)
			(xy 155.334716 -435.16042) (xy 155.334253 -435.172495) (xy 155.326786 -435.195461) (xy 155.312589 -435.214997)
			(xy 155.29305 -435.229191) (xy 155.270083 -435.236655) (xy 155.258008 -435.237128) (xy 154.318208 -435.237128)
			(xy 154.306136 -435.236629) (xy 154.283172 -435.229171) (xy 154.263637 -435.214983) (xy 154.249441 -435.195453)
			(xy 154.241975 -435.172492) (xy 154.2415 -435.16042) (xy 154.2415 -434.550058) (xy 154.239834 -434.535064)
			(xy 154.238054 -434.504946) (xy 154.237944 -434.48986) (xy 153.33472 -434.48986) (xy 153.33472 -435.489858)
			(xy 156.23794 -435.489858) (xy 156.238053 -435.474772) (xy 156.239832 -435.444654) (xy 156.241496 -435.42966)
			(xy 156.241496 -434.35016) (xy 156.23983 -434.335166) (xy 156.23805 -434.305048) (xy 156.23794 -434.289962)
			(xy 156.238053 -434.274876) (xy 156.239832 -434.244758) (xy 156.241496 -434.229764) (xy 156.241496 -433.618894)
			(xy 156.242002 -433.606809) (xy 156.249455 -433.583815) (xy 156.263633 -433.564239) (xy 156.283155 -433.549987)
			(xy 156.30612 -433.542448) (xy 156.318204 -433.541932) (xy 157.258004 -433.541932) (xy 157.270116 -433.542313)
			(xy 157.293149 -433.549818) (xy 157.312725 -433.564087) (xy 157.326918 -433.583718) (xy 157.334333 -433.60678)
			(xy 157.334712 -433.618894) (xy 157.334712 -436.160418) (xy 157.334307 -436.172513) (xy 157.32684 -436.195523)
			(xy 157.312639 -436.215106) (xy 157.293089 -436.229355) (xy 157.270098 -436.236878) (xy 157.258004 -436.23738)
			(xy 156.318204 -436.23738) (xy 156.306093 -436.23698) (xy 156.283063 -436.229479) (xy 156.263488 -436.215214)
			(xy 156.249294 -436.195588) (xy 156.241876 -436.17253) (xy 156.241496 -436.160418) (xy 156.241496 -435.550056)
			(xy 156.23983 -435.535062) (xy 156.23805 -435.504944) (xy 156.23794 -435.489858) (xy 153.33472 -435.489858)
			(xy 153.33472 -436.160418) (xy 153.334307 -436.172513) (xy 153.326841 -436.195521) (xy 153.312642 -436.215104)
			(xy 153.293094 -436.229352) (xy 153.270105 -436.236877) (xy 153.258012 -436.23738) (xy 152.318212 -436.23738)
			(xy 152.306102 -436.236973) (xy 152.283072 -436.229474) (xy 152.263497 -436.215211) (xy 152.249302 -436.195586)
			(xy 152.241885 -436.17253) (xy 152.241504 -436.160418) (xy 152.241504 -435.550056) (xy 152.239838 -435.535062)
			(xy 152.238058 -435.504944) (xy 152.237948 -435.489858) (xy 149.334728 -435.489858) (xy 149.334728 -436.160418)
			(xy 149.334308 -436.172512) (xy 149.326842 -436.195518) (xy 149.312645 -436.215101) (xy 149.293099 -436.22935)
			(xy 149.270112 -436.236876) (xy 149.25802 -436.23738) (xy 148.31822 -436.23738) (xy 148.30611 -436.236966)
			(xy 148.28308 -436.22947) (xy 148.263505 -436.215208) (xy 148.249311 -436.195585) (xy 148.241893 -436.172529)
			(xy 148.241512 -436.160418) (xy 148.241512 -435.550056) (xy 148.239846 -435.535062) (xy 148.238066 -435.504944)
			(xy 148.237956 -435.489858) (xy 145.334736 -435.489858) (xy 145.334736 -436.160418) (xy 145.334308 -436.172511)
			(xy 145.326843 -436.195516) (xy 145.312647 -436.215098) (xy 145.293104 -436.229347) (xy 145.27012 -436.236874)
			(xy 145.258028 -436.23738) (xy 144.318228 -436.23738) (xy 144.306119 -436.236959) (xy 144.283089 -436.229465)
			(xy 144.263514 -436.215206) (xy 144.249319 -436.195583) (xy 144.241901 -436.172529) (xy 144.24152 -436.160418)
			(xy 144.24152 -435.550056) (xy 144.239854 -435.535062) (xy 144.238074 -435.504944) (xy 144.237964 -435.489858)
			(xy 140.335 -435.489858) (xy 140.335 -436.160418) (xy 140.334504 -436.17253) (xy 140.327017 -436.195567)
			(xy 140.31278 -436.215165) (xy 140.293185 -436.229408) (xy 140.27015 -436.236901) (xy 140.258038 -436.23738)
			(xy 139.318238 -436.23738) (xy 139.306119 -436.236908) (xy 139.283064 -436.229428) (xy 139.26345 -436.21519)
			(xy 139.249197 -436.195586) (xy 139.241701 -436.172537) (xy 139.241276 -436.160418) (xy 139.241276 -435.548024)
			(xy 139.239728 -435.533532) (xy 139.238078 -435.504432) (xy 139.237974 -435.489858) (xy 136.335008 -435.489858)
			(xy 136.335008 -436.160418) (xy 136.334505 -436.172529) (xy 136.327018 -436.195565) (xy 136.312782 -436.215163)
			(xy 136.29319 -436.229405) (xy 136.270157 -436.2369) (xy 136.258046 -436.23738) (xy 135.318246 -436.23738)
			(xy 135.306127 -436.236901) (xy 135.283073 -436.229424) (xy 135.263459 -436.215187) (xy 135.249205 -436.195584)
			(xy 135.241709 -436.172536) (xy 135.241284 -436.160418) (xy 135.241284 -435.548024) (xy 135.239736 -435.533532)
			(xy 135.238086 -435.504432) (xy 135.237982 -435.489858) (xy 132.335016 -435.489858) (xy 132.335016 -436.160418)
			(xy 132.334654 -436.172546) (xy 132.327152 -436.195613) (xy 132.312886 -436.215232) (xy 132.293256 -436.229481)
			(xy 132.270183 -436.236965) (xy 132.258054 -436.23738) (xy 131.318254 -436.23738) (xy 131.306139 -436.236928)
			(xy 131.283097 -436.22943) (xy 131.263498 -436.215182) (xy 131.249257 -436.195578) (xy 131.241768 -436.172533)
			(xy 131.241292 -436.160418) (xy 131.241292 -435.548024) (xy 131.239744 -435.533532) (xy 131.238094 -435.504432)
			(xy 131.23799 -435.489858) (xy 128.335024 -435.489858) (xy 128.335024 -436.160418) (xy 128.334655 -436.172545)
			(xy 128.327153 -436.195611) (xy 128.312889 -436.215229) (xy 128.293261 -436.229478) (xy 128.27019 -436.236963)
			(xy 128.258062 -436.23738) (xy 127.318262 -436.23738) (xy 127.306147 -436.236921) (xy 127.283106 -436.229425)
			(xy 127.263506 -436.21518) (xy 127.249265 -436.195576) (xy 127.241776 -436.172533) (xy 127.2413 -436.160418)
			(xy 127.2413 -435.548024) (xy 127.239751 -435.533532) (xy 127.238102 -435.504432) (xy 127.237998 -435.489858)
			(xy 113.866512 -435.489858) (xy 113.892486 -435.537087) (xy 113.947862 -435.654438) (xy 113.995874 -435.77499)
			(xy 114.036336 -435.89828) (xy 114.069094 -436.023838) (xy 114.094022 -436.151181) (xy 114.111025 -436.279823)
			(xy 114.120038 -436.40927) (xy 114.121027 -436.539027) (xy 114.113986 -436.668596) (xy 114.098945 -436.797482)
			(xy 114.075959 -436.92519) (xy 114.045118 -437.051232) (xy 114.006538 -437.175125) (xy 113.960369 -437.296394)
			(xy 113.906786 -437.414574) (xy 113.845996 -437.529214) (xy 113.77823 -437.639874) (xy 113.703749 -437.74613)
			(xy 113.622838 -437.847575) (xy 113.535806 -437.943821) (xy 113.442988 -438.034499) (xy 113.378885 -438.089802)
			(xy 125.238002 -438.089802) (xy 125.238095 -438.075228) (xy 125.239748 -438.046127) (xy 125.241304 -438.031636)
			(xy 125.241304 -436.948072) (xy 125.239759 -436.93358) (xy 125.238107 -436.90448) (xy 125.238002 -436.889906)
			(xy 125.238095 -436.875332) (xy 125.239748 -436.846231) (xy 125.241304 -436.83174) (xy 125.241304 -436.219092)
			(xy 125.241709 -436.206982) (xy 125.249212 -436.183954) (xy 125.263476 -436.164381) (xy 125.2831 -436.150186)
			(xy 125.306155 -436.142767) (xy 125.318266 -436.142384) (xy 126.258066 -436.142384) (xy 126.270158 -436.142837)
			(xy 126.293165 -436.15029) (xy 126.312749 -436.164478) (xy 126.327 -436.184018) (xy 126.334525 -436.207001)
			(xy 126.335028 -436.219092) (xy 126.335028 -438.760616) (xy 126.334598 -438.772723) (xy 126.327097 -438.795746)
			(xy 126.312838 -438.815316) (xy 126.293222 -438.829511) (xy 126.270174 -438.836937) (xy 126.258066 -438.837324)
			(xy 125.318266 -438.837324) (xy 125.306171 -438.836921) (xy 125.283163 -438.829451) (xy 125.263581 -438.815249)
			(xy 125.249333 -438.7957) (xy 125.241808 -438.77271) (xy 125.241304 -438.760616) (xy 125.241304 -438.147968)
			(xy 125.239759 -438.133476) (xy 125.238107 -438.104376) (xy 125.238002 -438.089802) (xy 113.378885 -438.089802)
			(xy 113.344738 -438.119261) (xy 113.241432 -438.197784) (xy 113.133467 -438.269766) (xy 113.021257 -438.334931)
			(xy 112.90523 -438.39303) (xy 112.785831 -438.443841) (xy 112.663518 -438.487169) (xy 112.538759 -438.522847)
			(xy 112.412032 -438.550739) (xy 112.283822 -438.570739) (xy 112.15462 -438.58277) (xy 112.024922 -438.586785)
			(xy 111.895224 -438.58277) (xy 111.766022 -438.570739) (xy 111.637812 -438.550739) (xy 111.511085 -438.522847)
			(xy 111.386326 -438.487169) (xy 111.264013 -438.443841) (xy 111.144614 -438.39303) (xy 111.028587 -438.334931)
			(xy 110.916377 -438.269766) (xy 110.808412 -438.197784) (xy 110.705106 -438.119261) (xy 110.606856 -438.034499)
			(xy 110.514038 -437.943821) (xy 110.427006 -437.847575) (xy 110.346095 -437.74613) (xy 110.271614 -437.639874)
			(xy 110.203848 -437.529214) (xy 110.143058 -437.414574) (xy 110.089475 -437.296394) (xy 110.043306 -437.175125)
			(xy 110.004726 -437.051232) (xy 109.973885 -436.92519) (xy 109.950899 -436.797482) (xy 109.935858 -436.668596)
			(xy 109.928817 -436.539027) (xy 109.929806 -436.40927) (xy 109.938819 -436.279823) (xy 109.955822 -436.151181)
			(xy 109.98075 -436.023838) (xy 110.013508 -435.89828) (xy 110.05397 -435.77499) (xy 110.101982 -435.654438)
			(xy 110.157358 -435.537087) (xy 110.219888 -435.423387) (xy 110.289331 -435.313772) (xy 110.365422 -435.208663)
			(xy 110.447869 -435.108462) (xy 110.536357 -435.013553) (xy 110.630546 -434.924299) (xy 110.679992 -434.88229)
			(xy 110.691093 -434.872254) (xy 110.707515 -434.847259) (xy 110.71599 -434.818578) (xy 110.71579 -434.788672)
			(xy 110.706933 -434.760107) (xy 110.690178 -434.735334) (xy 110.666963 -434.71648) (xy 110.653322 -434.710332)
			(xy 110.574304 -434.677407) (xy 110.419107 -434.605131) (xy 110.267499 -434.5256) (xy 110.119821 -434.438991)
			(xy 109.976402 -434.345497) (xy 109.837562 -434.245328) (xy 109.703613 -434.138709) (xy 109.574854 -434.025876)
			(xy 109.451573 -433.907083) (xy 109.334045 -433.782595) (xy 109.222533 -433.65269) (xy 109.117287 -433.517659)
			(xy 109.018541 -433.377804) (xy 108.926517 -433.233438) (xy 108.84142 -433.084883) (xy 108.763441 -432.932471)
			(xy 108.692754 -432.776543) (xy 108.629516 -432.617449) (xy 108.57387 -432.455542) (xy 108.52594 -432.291187)
			(xy 108.485833 -432.124749) (xy 108.453638 -431.956601) (xy 108.429428 -431.78712) (xy 108.413257 -431.616683)
			(xy 108.405161 -431.445673) (xy 108.40466 -431.360072) (xy 90.235024 -431.360072) (xy 90.235024 -432.560476)
			(xy 90.234563 -432.572581) (xy 90.227074 -432.595604) (xy 90.212823 -432.615175) (xy 90.193212 -432.629371)
			(xy 90.170168 -432.636797) (xy 90.158062 -432.637184) (xy 89.218262 -432.637184) (xy 89.206173 -432.636726)
			(xy 89.183175 -432.629261) (xy 89.163598 -432.615072) (xy 89.149348 -432.595538) (xy 89.141812 -432.572564)
			(xy 89.1413 -432.560476) (xy 89.1413 -431.948082) (xy 89.139756 -431.93359) (xy 89.138104 -431.90449)
			(xy 89.137998 -431.889916) (xy 86.235032 -431.889916) (xy 86.235032 -432.560476) (xy 86.234563 -432.57258)
			(xy 86.227075 -432.595601) (xy 86.212825 -432.615172) (xy 86.193217 -432.629369) (xy 86.170175 -432.636796)
			(xy 86.15807 -432.637184) (xy 85.21827 -432.637184) (xy 85.206181 -432.636719) (xy 85.183184 -432.629257)
			(xy 85.163606 -432.615069) (xy 85.149356 -432.595537) (xy 85.14182 -432.572563) (xy 85.141308 -432.560476)
			(xy 85.141308 -431.948082) (xy 85.139764 -431.93359) (xy 85.138112 -431.90449) (xy 85.138006 -431.889916)
			(xy 82.23504 -431.889916) (xy 82.23504 -432.560476) (xy 82.234564 -432.57258) (xy 82.227076 -432.595599)
			(xy 82.212828 -432.615169) (xy 82.193222 -432.629366) (xy 82.170183 -432.636795) (xy 82.158078 -432.637184)
			(xy 81.218278 -432.637184) (xy 81.20619 -432.636712) (xy 81.183192 -432.629252) (xy 81.163615 -432.615066)
			(xy 81.149364 -432.595535) (xy 81.141828 -432.572563) (xy 81.141316 -432.560476) (xy 81.141316 -431.948082)
			(xy 81.139772 -431.93359) (xy 81.13812 -431.90449) (xy 81.138014 -431.889916) (xy 78.235048 -431.889916)
			(xy 78.235048 -432.560476) (xy 78.234564 -432.572579) (xy 78.227077 -432.595597) (xy 78.212831 -432.615166)
			(xy 78.193227 -432.629364) (xy 78.17019 -432.636793) (xy 78.158086 -432.637184) (xy 77.218286 -432.637184)
			(xy 77.206198 -432.636705) (xy 77.183201 -432.629248) (xy 77.163623 -432.615063) (xy 77.149372 -432.595534)
			(xy 77.141836 -432.572562) (xy 77.141324 -432.560476) (xy 77.141324 -431.948082) (xy 77.13978 -431.93359)
			(xy 77.138128 -431.90449) (xy 77.138022 -431.889916) (xy 73.234804 -431.889916) (xy 73.234804 -432.560476)
			(xy 73.234367 -432.572558) (xy 73.226905 -432.59554) (xy 73.212706 -432.615091) (xy 73.193158 -432.629296)
			(xy 73.170178 -432.636764) (xy 73.158096 -432.637184) (xy 72.218296 -432.637184) (xy 72.206211 -432.636791)
			(xy 72.183224 -432.629319) (xy 72.163671 -432.615109) (xy 72.149468 -432.595551) (xy 72.142005 -432.572562)
			(xy 72.141588 -432.560476) (xy 72.141588 -431.950114) (xy 72.139918 -431.935121) (xy 72.138141 -431.905002)
			(xy 72.138032 -431.889916) (xy 69.234812 -431.889916) (xy 69.234812 -432.560476) (xy 69.234367 -432.572557)
			(xy 69.226906 -432.595538) (xy 69.212709 -432.615089) (xy 69.193163 -432.629294) (xy 69.170185 -432.636762)
			(xy 69.158104 -432.637184) (xy 68.218304 -432.637184) (xy 68.206219 -432.636784) (xy 68.183232 -432.629314)
			(xy 68.16368 -432.615106) (xy 68.149476 -432.59555) (xy 68.142013 -432.572561) (xy 68.141596 -432.560476)
			(xy 68.141596 -431.950114) (xy 68.139926 -431.935121) (xy 68.138149 -431.905002) (xy 68.13804 -431.889916)
			(xy 65.23482 -431.889916) (xy 65.23482 -432.560476) (xy 65.234367 -432.572556) (xy 65.226907 -432.595536)
			(xy 65.212711 -432.615086) (xy 65.193168 -432.629291) (xy 65.170192 -432.636761) (xy 65.158112 -432.637184)
			(xy 64.218312 -432.637184) (xy 64.206228 -432.636777) (xy 64.183241 -432.629309) (xy 64.163689 -432.615103)
			(xy 64.149485 -432.595548) (xy 64.142022 -432.572561) (xy 64.141604 -432.560476) (xy 64.141604 -431.950114)
			(xy 64.139934 -431.935121) (xy 64.138157 -431.905002) (xy 64.138048 -431.889916) (xy 61.234828 -431.889916)
			(xy 61.234828 -432.560476) (xy 61.234367 -432.572555) (xy 61.226909 -432.595534) (xy 61.212714 -432.615083)
			(xy 61.193173 -432.629288) (xy 61.170199 -432.63676) (xy 61.15812 -432.637184) (xy 60.21832 -432.637184)
			(xy 60.206236 -432.63677) (xy 60.18325 -432.629305) (xy 60.163697 -432.6151) (xy 60.149493 -432.595547)
			(xy 60.14203 -432.57256) (xy 60.141612 -432.560476) (xy 60.141612 -431.950114) (xy 60.139942 -431.935121)
			(xy 60.138165 -431.905002) (xy 60.138056 -431.889916) (xy 7.00913 -431.889916) (xy 7.00913 -434.48986)
			(xy 58.13806 -434.48986) (xy 58.138173 -434.474774) (xy 58.139952 -434.444656) (xy 58.141616 -434.429662)
			(xy 58.141616 -433.350162) (xy 58.139951 -433.335168) (xy 58.13817 -433.30505) (xy 58.13806 -433.289964)
			(xy 58.138173 -433.274878) (xy 58.139952 -433.24476) (xy 58.141616 -433.229766) (xy 58.141616 -432.618896)
			(xy 58.142009 -432.606811) (xy 58.149481 -432.583824) (xy 58.163691 -432.564271) (xy 58.183249 -432.550068)
			(xy 58.206238 -432.542605) (xy 58.218324 -432.542188) (xy 59.158124 -432.542188) (xy 59.170199 -432.542644)
			(xy 59.193167 -432.550113) (xy 59.212703 -432.564311) (xy 59.226897 -432.583851) (xy 59.234359 -432.606821)
			(xy 59.234832 -432.618896) (xy 59.234832 -435.16042) (xy 59.234353 -435.172493) (xy 59.226888 -435.195457)
			(xy 59.212694 -435.214991) (xy 59.19316 -435.229186) (xy 59.170197 -435.236652) (xy 59.158124 -435.237128)
			(xy 58.218324 -435.237128) (xy 58.206245 -435.236667) (xy 58.183266 -435.229209) (xy 58.163717 -435.215014)
			(xy 58.149512 -435.195473) (xy 58.14204 -435.172499) (xy 58.141616 -435.16042) (xy 58.141616 -434.550058)
			(xy 58.13995 -434.535064) (xy 58.13817 -434.504946) (xy 58.13806 -434.48986) (xy 7.00913 -434.48986)
			(xy 7.00913 -435.489858) (xy 60.138056 -435.489858) (xy 60.138169 -435.474772) (xy 60.139948 -435.444654)
			(xy 60.141612 -435.42966) (xy 60.141612 -434.35016) (xy 60.139947 -434.335166) (xy 60.138166 -434.305048)
			(xy 60.138056 -434.289962) (xy 60.138169 -434.274876) (xy 60.139948 -434.244758) (xy 60.141612 -434.229764)
			(xy 60.141612 -433.618894) (xy 60.142102 -433.606807) (xy 60.149557 -433.583811) (xy 60.163739 -433.564234)
			(xy 60.183265 -433.549982) (xy 60.206235 -433.542445) (xy 60.21832 -433.541932) (xy 61.15812 -433.541932)
			(xy 61.170233 -433.5423) (xy 61.193267 -433.549808) (xy 61.212842 -433.564081) (xy 61.227035 -433.583715)
			(xy 61.234449 -433.606779) (xy 61.234828 -433.618894) (xy 61.234828 -434.48986) (xy 62.138052 -434.48986)
			(xy 62.138165 -434.474774) (xy 62.139944 -434.444656) (xy 62.141608 -434.429662) (xy 62.141608 -433.350162)
			(xy 62.139943 -433.335168) (xy 62.138162 -433.30505) (xy 62.138052 -433.289964) (xy 62.138165 -433.274878)
			(xy 62.139944 -433.24476) (xy 62.141608 -433.229766) (xy 62.141608 -432.618896) (xy 62.142009 -432.606811)
			(xy 62.14948 -432.583826) (xy 62.163688 -432.564274) (xy 62.183244 -432.550071) (xy 62.206231 -432.542606)
			(xy 62.218316 -432.542188) (xy 63.158116 -432.542188) (xy 63.170191 -432.542651) (xy 63.193158 -432.550117)
			(xy 63.212694 -432.564314) (xy 63.226888 -432.583853) (xy 63.234351 -432.606821) (xy 63.234824 -432.618896)
			(xy 63.234824 -435.16042) (xy 63.234353 -435.172494) (xy 63.226887 -435.195459) (xy 63.212691 -435.214994)
			(xy 63.193155 -435.229189) (xy 63.17019 -435.236654) (xy 63.158116 -435.237128) (xy 62.218316 -435.237128)
			(xy 62.206244 -435.236622) (xy 62.183281 -435.229167) (xy 62.163745 -435.21498) (xy 62.14955 -435.195451)
			(xy 62.142083 -435.172492) (xy 62.141608 -435.16042) (xy 62.141608 -434.550058) (xy 62.139942 -434.535064)
			(xy 62.138162 -434.504946) (xy 62.138052 -434.48986) (xy 61.234828 -434.48986) (xy 61.234828 -435.489858)
			(xy 64.138048 -435.489858) (xy 64.138161 -435.474772) (xy 64.13994 -435.444654) (xy 64.141604 -435.42966)
			(xy 64.141604 -434.35016) (xy 64.139938 -434.335166) (xy 64.138158 -434.305048) (xy 64.138048 -434.289962)
			(xy 64.138161 -434.274876) (xy 64.13994 -434.244758) (xy 64.141604 -434.229764) (xy 64.141604 -433.618894)
			(xy 64.142102 -433.606808) (xy 64.149556 -433.583813) (xy 64.163736 -433.564236) (xy 64.18326 -433.549985)
			(xy 64.206228 -433.542447) (xy 64.218312 -433.541932) (xy 65.158112 -433.541932) (xy 65.170225 -433.542306)
			(xy 65.193258 -433.549813) (xy 65.212834 -433.564084) (xy 65.227027 -433.583717) (xy 65.234441 -433.60678)
			(xy 65.23482 -433.618894) (xy 65.23482 -434.48986) (xy 66.138044 -434.48986) (xy 66.138157 -434.474774)
			(xy 66.139936 -434.444656) (xy 66.1416 -434.429662) (xy 66.1416 -433.350162) (xy 66.139935 -433.335168)
			(xy 66.138154 -433.30505) (xy 66.138044 -433.289964) (xy 66.138157 -433.274878) (xy 66.139936 -433.24476)
			(xy 66.1416 -433.229766) (xy 66.1416 -432.618896) (xy 66.142009 -432.606812) (xy 66.149479 -432.583828)
			(xy 66.163686 -432.564277) (xy 66.183239 -432.550073) (xy 66.206224 -432.542607) (xy 66.218308 -432.542188)
			(xy 67.158108 -432.542188) (xy 67.170183 -432.542657) (xy 67.193149 -432.550122) (xy 67.212686 -432.564317)
			(xy 67.22688 -432.583854) (xy 67.234343 -432.606821) (xy 67.234816 -432.618896) (xy 67.234816 -435.16042)
			(xy 67.234353 -435.172495) (xy 67.226886 -435.195461) (xy 67.212689 -435.214997) (xy 67.19315 -435.229191)
			(xy 67.170183 -435.236655) (xy 67.158108 -435.237128) (xy 66.218308 -435.237128) (xy 66.206236 -435.236629)
			(xy 66.183272 -435.229171) (xy 66.163737 -435.214983) (xy 66.149541 -435.195453) (xy 66.142075 -435.172492)
			(xy 66.1416 -435.16042) (xy 66.1416 -434.550058) (xy 66.139934 -434.535064) (xy 66.138154 -434.504946)
			(xy 66.138044 -434.48986) (xy 65.23482 -434.48986) (xy 65.23482 -435.489858) (xy 68.13804 -435.489858)
			(xy 68.138153 -435.474772) (xy 68.139932 -435.444654) (xy 68.141596 -435.42966) (xy 68.141596 -434.35016)
			(xy 68.13993 -434.335166) (xy 68.13815 -434.305048) (xy 68.13804 -434.289962) (xy 68.138153 -434.274876)
			(xy 68.139932 -434.244758) (xy 68.141596 -434.229764) (xy 68.141596 -433.618894) (xy 68.142102 -433.606809)
			(xy 68.149555 -433.583815) (xy 68.163733 -433.564239) (xy 68.183255 -433.549987) (xy 68.20622 -433.542448)
			(xy 68.218304 -433.541932) (xy 69.158104 -433.541932) (xy 69.170216 -433.542313) (xy 69.193249 -433.549818)
			(xy 69.212825 -433.564087) (xy 69.227018 -433.583718) (xy 69.234433 -433.60678) (xy 69.234812 -433.618894)
			(xy 69.234812 -434.48986) (xy 70.138036 -434.48986) (xy 70.138151 -434.474775) (xy 70.13993 -434.444656)
			(xy 70.141592 -434.429662) (xy 70.141592 -433.350162) (xy 70.139927 -433.335168) (xy 70.138146 -433.30505)
			(xy 70.138036 -433.289964) (xy 70.138152 -433.274879) (xy 70.13993 -433.24476) (xy 70.141592 -433.229766)
			(xy 70.141592 -432.618896) (xy 70.142061 -432.606821) (xy 70.149524 -432.583854) (xy 70.16372 -432.564317)
			(xy 70.183258 -432.550123) (xy 70.206225 -432.54266) (xy 70.2183 -432.542188) (xy 71.1581 -432.542188)
			(xy 71.170174 -432.542664) (xy 71.193141 -432.550126) (xy 71.212677 -432.56432) (xy 71.226872 -432.583856)
			(xy 71.234335 -432.606822) (xy 71.234808 -432.618896) (xy 71.234808 -435.16042) (xy 71.234353 -435.172496)
			(xy 71.226885 -435.195463) (xy 71.212686 -435.215) (xy 71.193145 -435.229194) (xy 71.170176 -435.236656)
			(xy 71.1581 -435.237128) (xy 70.2183 -435.237128) (xy 70.206227 -435.236636) (xy 70.183264 -435.229176)
			(xy 70.163728 -435.214986) (xy 70.149533 -435.195454) (xy 70.142067 -435.172492) (xy 70.141592 -435.16042)
			(xy 70.141592 -434.550058) (xy 70.139926 -434.535064) (xy 70.138146 -434.504946) (xy 70.138036 -434.48986)
			(xy 69.234812 -434.48986) (xy 69.234812 -435.489858) (xy 72.138032 -435.489858) (xy 72.138147 -435.474773)
			(xy 72.139926 -435.444654) (xy 72.141588 -435.42966) (xy 72.141588 -434.35016) (xy 72.139922 -434.335166)
			(xy 72.138142 -434.305048) (xy 72.138032 -434.289962) (xy 72.138147 -434.274877) (xy 72.139926 -434.244758)
			(xy 72.141588 -434.229764) (xy 72.141588 -433.618894) (xy 72.142003 -433.606799) (xy 72.149468 -433.583791)
			(xy 72.163666 -433.564207) (xy 72.183213 -433.549958) (xy 72.206203 -433.542435) (xy 72.218296 -433.541932)
			(xy 73.158096 -433.541932) (xy 73.170208 -433.54232) (xy 73.193241 -433.549822) (xy 73.212817 -433.56409)
			(xy 73.22701 -433.58372) (xy 73.234425 -433.606781) (xy 73.234804 -433.618894) (xy 73.234804 -434.48986)
			(xy 75.138026 -434.48986) (xy 75.138124 -434.475286) (xy 75.139774 -434.446185) (xy 75.141328 -434.431694)
			(xy 75.141328 -433.34813) (xy 75.13978 -433.333638) (xy 75.13813 -433.304538) (xy 75.138026 -433.289964)
			(xy 75.138124 -433.27539) (xy 75.139774 -433.246289) (xy 75.141328 -433.231798) (xy 75.141328 -432.618896)
			(xy 75.141713 -432.606784) (xy 75.149217 -432.583752) (xy 75.163486 -432.564176) (xy 75.183116 -432.549983)
			(xy 75.206177 -432.542567) (xy 75.21829 -432.542188) (xy 76.15809 -432.542188) (xy 76.170184 -432.542617)
			(xy 76.193192 -432.550077) (xy 76.212776 -432.564271) (xy 76.227025 -432.583816) (xy 76.234549 -432.606804)
			(xy 76.235052 -432.618896) (xy 76.235052 -435.16042) (xy 76.234601 -435.172525) (xy 76.227103 -435.195544)
			(xy 76.212848 -435.215112) (xy 76.193237 -435.229308) (xy 76.170196 -435.236737) (xy 76.15809 -435.237128)
			(xy 75.21829 -435.237128) (xy 75.206197 -435.2367) (xy 75.183191 -435.229237) (xy 75.163608 -435.215041)
			(xy 75.149359 -435.195498) (xy 75.141833 -435.172512) (xy 75.141328 -435.16042) (xy 75.141328 -434.548026)
			(xy 75.13978 -434.533534) (xy 75.13813 -434.504434) (xy 75.138026 -434.48986) (xy 73.234804 -434.48986)
			(xy 73.234804 -435.489858) (xy 77.138022 -435.489858) (xy 77.13812 -435.475284) (xy 77.13977 -435.446183)
			(xy 77.141324 -435.431692) (xy 77.141324 -434.348128) (xy 77.139776 -434.333636) (xy 77.138126 -434.304536)
			(xy 77.138022 -434.289962) (xy 77.13812 -434.275388) (xy 77.13977 -434.246287) (xy 77.141324 -434.231796)
			(xy 77.141324 -433.618894) (xy 77.141807 -433.606781) (xy 77.149294 -433.58374) (xy 77.163534 -433.564139)
			(xy 77.183132 -433.549897) (xy 77.206173 -433.542408) (xy 77.218286 -433.541932) (xy 78.158086 -433.541932)
			(xy 78.170207 -433.542372) (xy 78.193265 -433.54986) (xy 78.21288 -433.564106) (xy 78.227131 -433.583717)
			(xy 78.234625 -433.606773) (xy 78.235048 -433.618894) (xy 78.235048 -434.48986) (xy 79.138018 -434.48986)
			(xy 79.138116 -434.475286) (xy 79.139766 -434.446185) (xy 79.14132 -434.431694) (xy 79.14132 -433.34813)
			(xy 79.139772 -433.333638) (xy 79.138122 -433.304538) (xy 79.138018 -433.289964) (xy 79.138116 -433.27539)
			(xy 79.139766 -433.246289) (xy 79.14132 -433.231798) (xy 79.14132 -432.618896) (xy 79.141713 -432.606785)
			(xy 79.149216 -432.583754) (xy 79.163483 -432.564179) (xy 79.183111 -432.549985) (xy 79.206169 -432.542568)
			(xy 79.218282 -432.542188) (xy 80.158082 -432.542188) (xy 80.170175 -432.542624) (xy 80.193183 -432.550081)
			(xy 80.212768 -432.564274) (xy 80.227017 -432.583818) (xy 80.234541 -432.606804) (xy 80.235044 -432.618896)
			(xy 80.235044 -435.16042) (xy 80.234601 -435.172526) (xy 80.227102 -435.195546) (xy 80.212845 -435.215115)
			(xy 80.193232 -435.22931) (xy 80.170189 -435.236739) (xy 80.158082 -435.237128) (xy 79.218282 -435.237128)
			(xy 79.206188 -435.236708) (xy 79.183182 -435.229242) (xy 79.163599 -435.215045) (xy 79.14935 -435.195499)
			(xy 79.141824 -435.172512) (xy 79.14132 -435.16042) (xy 79.14132 -434.548026) (xy 79.139772 -434.533534)
			(xy 79.138122 -434.504434) (xy 79.138018 -434.48986) (xy 78.235048 -434.48986) (xy 78.235048 -435.489858)
			(xy 81.138014 -435.489858) (xy 81.138111 -435.475284) (xy 81.139761 -435.446183) (xy 81.141316 -435.431692)
			(xy 81.141316 -434.348128) (xy 81.139768 -434.333636) (xy 81.138118 -434.304536) (xy 81.138014 -434.289962)
			(xy 81.138112 -434.275388) (xy 81.139761 -434.246287) (xy 81.141316 -434.231796) (xy 81.141316 -433.618894)
			(xy 81.141807 -433.606781) (xy 81.149293 -433.583742) (xy 81.163531 -433.564142) (xy 81.183127 -433.5499)
			(xy 81.206165 -433.542409) (xy 81.218278 -433.541932) (xy 82.158078 -433.541932) (xy 82.170199 -433.542379)
			(xy 82.193256 -433.549864) (xy 82.212871 -433.564109) (xy 82.227123 -433.583719) (xy 82.234617 -433.606773)
			(xy 82.23504 -433.618894) (xy 82.23504 -434.48986) (xy 83.13801 -434.48986) (xy 83.138107 -434.475286)
			(xy 83.139757 -434.446185) (xy 83.141312 -434.431694) (xy 83.141312 -433.34813) (xy 83.139764 -433.333638)
			(xy 83.138114 -433.304538) (xy 83.13801 -433.289964) (xy 83.138108 -433.27539) (xy 83.139757 -433.246289)
			(xy 83.141312 -433.231798) (xy 83.141312 -432.618896) (xy 83.141713 -432.606786) (xy 83.149215 -432.583756)
			(xy 83.16348 -432.564182) (xy 83.183106 -432.549988) (xy 83.206162 -432.542569) (xy 83.218274 -432.542188)
			(xy 84.158074 -432.542188) (xy 84.170167 -432.54263) (xy 84.193175 -432.550086) (xy 84.212759 -432.564277)
			(xy 84.227009 -432.583819) (xy 84.234533 -432.606804) (xy 84.235036 -432.618896) (xy 84.235036 -435.16042)
			(xy 84.234601 -435.172526) (xy 84.227101 -435.195548) (xy 84.212843 -435.215118) (xy 84.193227 -435.229313)
			(xy 84.170182 -435.23674) (xy 84.158074 -435.237128) (xy 83.218274 -435.237128) (xy 83.20618 -435.236714)
			(xy 83.183173 -435.229247) (xy 83.163591 -435.215047) (xy 83.149342 -435.195501) (xy 83.141816 -435.172513)
			(xy 83.141312 -435.16042) (xy 83.141312 -434.548026) (xy 83.139764 -434.533534) (xy 83.138114 -434.504434)
			(xy 83.13801 -434.48986) (xy 82.23504 -434.48986) (xy 82.23504 -435.489858) (xy 85.138006 -435.489858)
			(xy 85.138103 -435.475284) (xy 85.139753 -435.446183) (xy 85.141308 -435.431692) (xy 85.141308 -434.348128)
			(xy 85.13976 -434.333636) (xy 85.13811 -434.304536) (xy 85.138006 -434.289962) (xy 85.138104 -434.275388)
			(xy 85.139753 -434.246287) (xy 85.141308 -434.231796) (xy 85.141308 -433.618894) (xy 85.141806 -433.606782)
			(xy 85.149292 -433.583744) (xy 85.163528 -433.564145) (xy 85.183122 -433.549903) (xy 85.206158 -433.54241)
			(xy 85.21827 -433.541932) (xy 86.15807 -433.541932) (xy 86.170191 -433.542385) (xy 86.193247 -433.549869)
			(xy 86.212863 -433.564112) (xy 86.227115 -433.58372) (xy 86.234609 -433.606774) (xy 86.235032 -433.618894)
			(xy 86.235032 -434.48986) (xy 87.138002 -434.48986) (xy 87.1381 -434.475286) (xy 87.139749 -434.446185)
			(xy 87.141304 -434.431694) (xy 87.141304 -433.34813) (xy 87.139756 -433.333638) (xy 87.138106 -433.304538)
			(xy 87.138002 -433.289964) (xy 87.1381 -433.27539) (xy 87.139749 -433.246289) (xy 87.141304 -433.231798)
			(xy 87.141304 -432.618896) (xy 87.141713 -432.606787) (xy 87.149214 -432.583758) (xy 87.163477 -432.564185)
			(xy 87.183101 -432.549991) (xy 87.206155 -432.542571) (xy 87.218266 -432.542188) (xy 88.158066 -432.542188)
			(xy 88.170159 -432.542637) (xy 88.193166 -432.55009) (xy 88.212751 -432.56428) (xy 88.227001 -432.583821)
			(xy 88.234525 -432.606805) (xy 88.235028 -432.618896) (xy 88.235028 -435.16042) (xy 88.234601 -435.172527)
			(xy 88.2271 -435.19555) (xy 88.21284 -435.215121) (xy 88.193222 -435.229316) (xy 88.170174 -435.236741)
			(xy 88.158066 -435.237128) (xy 87.218266 -435.237128) (xy 87.206171 -435.236721) (xy 87.183164 -435.229251)
			(xy 87.163582 -435.21505) (xy 87.149334 -435.195502) (xy 87.141808 -435.172513) (xy 87.141304 -435.16042)
			(xy 87.141304 -434.548026) (xy 87.139756 -434.533534) (xy 87.138106 -434.504434) (xy 87.138002 -434.48986)
			(xy 86.235032 -434.48986) (xy 86.235032 -435.489858) (xy 89.137998 -435.489858) (xy 89.138095 -435.475284)
			(xy 89.139745 -435.446183) (xy 89.1413 -435.431692) (xy 89.1413 -434.348128) (xy 89.139752 -434.333636)
			(xy 89.138102 -434.304536) (xy 89.137998 -434.289962) (xy 89.138096 -434.275388) (xy 89.139745 -434.246287)
			(xy 89.1413 -434.231796) (xy 89.1413 -433.618894) (xy 89.141806 -433.606783) (xy 89.14929 -433.583746)
			(xy 89.163525 -433.564148) (xy 89.183117 -433.549905) (xy 89.206151 -433.542411) (xy 89.218262 -433.541932)
			(xy 90.158062 -433.541932) (xy 90.170182 -433.542392) (xy 90.193239 -433.549873) (xy 90.212854 -433.564115)
			(xy 90.227107 -433.583722) (xy 90.234601 -433.606774) (xy 90.235024 -433.618894) (xy 90.235024 -436.160418)
			(xy 90.234655 -436.172545) (xy 90.227153 -436.195611) (xy 90.212889 -436.215229) (xy 90.193261 -436.229478)
			(xy 90.17019 -436.236963) (xy 90.158062 -436.23738) (xy 89.218262 -436.23738) (xy 89.206147 -436.236921)
			(xy 89.183106 -436.229425) (xy 89.163506 -436.21518) (xy 89.149265 -436.195576) (xy 89.141776 -436.172533)
			(xy 89.1413 -436.160418) (xy 89.1413 -435.548024) (xy 89.139751 -435.533532) (xy 89.138102 -435.504432)
			(xy 89.137998 -435.489858) (xy 86.235032 -435.489858) (xy 86.235032 -436.160418) (xy 86.234655 -436.172545)
			(xy 86.227154 -436.195609) (xy 86.212892 -436.215226) (xy 86.193266 -436.229476) (xy 86.170197 -436.236962)
			(xy 86.15807 -436.23738) (xy 85.21827 -436.23738) (xy 85.206156 -436.236914) (xy 85.183114 -436.229421)
			(xy 85.163515 -436.215177) (xy 85.149274 -436.195575) (xy 85.141784 -436.172532) (xy 85.141308 -436.160418)
			(xy 85.141308 -435.548024) (xy 85.139759 -435.533532) (xy 85.13811 -435.504432) (xy 85.138006 -435.489858)
			(xy 82.23504 -435.489858) (xy 82.23504 -436.160418) (xy 82.234655 -436.172544) (xy 82.227155 -436.195607)
			(xy 82.212895 -436.215224) (xy 82.193271 -436.229473) (xy 82.170204 -436.236961) (xy 82.158078 -436.23738)
			(xy 81.218278 -436.23738) (xy 81.206164 -436.236907) (xy 81.183123 -436.229416) (xy 81.163523 -436.215174)
			(xy 81.149282 -436.195573) (xy 81.141792 -436.172532) (xy 81.141316 -436.160418) (xy 81.141316 -435.548024)
			(xy 81.139767 -435.533532) (xy 81.138118 -435.504432) (xy 81.138014 -435.489858) (xy 78.235048 -435.489858)
			(xy 78.235048 -436.160418) (xy 78.234604 -436.172535) (xy 78.22711 -436.195581) (xy 78.212861 -436.215184)
			(xy 78.193252 -436.229424) (xy 78.170203 -436.236909) (xy 78.158086 -436.23738) (xy 77.218286 -436.23738)
			(xy 77.206172 -436.236901) (xy 77.183132 -436.229412) (xy 77.163532 -436.215171) (xy 77.14929 -436.195572)
			(xy 77.1418 -436.172531) (xy 77.141324 -436.160418) (xy 77.141324 -435.548024) (xy 77.139775 -435.533532)
			(xy 77.138126 -435.504432) (xy 77.138022 -435.489858) (xy 73.234804 -435.489858) (xy 73.234804 -436.160418)
			(xy 73.234309 -436.172504) (xy 73.226853 -436.195498) (xy 73.212672 -436.215074) (xy 73.193147 -436.229325)
			(xy 73.17018 -436.236865) (xy 73.158096 -436.23738) (xy 72.218296 -436.23738) (xy 72.206185 -436.236987)
			(xy 72.183154 -436.229484) (xy 72.163579 -436.215217) (xy 72.149385 -436.195589) (xy 72.141968 -436.172531)
			(xy 72.141588 -436.160418) (xy 72.141588 -435.550056) (xy 72.139922 -435.535062) (xy 72.138142 -435.504944)
			(xy 72.138032 -435.489858) (xy 69.234812 -435.489858) (xy 69.234812 -436.160418) (xy 69.234407 -436.172513)
			(xy 69.22694 -436.195523) (xy 69.212739 -436.215106) (xy 69.193189 -436.229355) (xy 69.170198 -436.236878)
			(xy 69.158104 -436.23738) (xy 68.218304 -436.23738) (xy 68.206193 -436.23698) (xy 68.183163 -436.229479)
			(xy 68.163588 -436.215214) (xy 68.149394 -436.195588) (xy 68.141976 -436.17253) (xy 68.141596 -436.160418)
			(xy 68.141596 -435.550056) (xy 68.13993 -435.535062) (xy 68.13815 -435.504944) (xy 68.13804 -435.489858)
			(xy 65.23482 -435.489858) (xy 65.23482 -436.160418) (xy 65.234407 -436.172513) (xy 65.226941 -436.195521)
			(xy 65.212742 -436.215104) (xy 65.193194 -436.229352) (xy 65.170205 -436.236877) (xy 65.158112 -436.23738)
			(xy 64.218312 -436.23738) (xy 64.206202 -436.236973) (xy 64.183172 -436.229474) (xy 64.163597 -436.215211)
			(xy 64.149402 -436.195586) (xy 64.141985 -436.17253) (xy 64.141604 -436.160418) (xy 64.141604 -435.550056)
			(xy 64.139938 -435.535062) (xy 64.138158 -435.504944) (xy 64.138048 -435.489858) (xy 61.234828 -435.489858)
			(xy 61.234828 -436.160418) (xy 61.234408 -436.172512) (xy 61.226942 -436.195518) (xy 61.212745 -436.215101)
			(xy 61.193199 -436.22935) (xy 61.170212 -436.236876) (xy 61.15812 -436.23738) (xy 60.21832 -436.23738)
			(xy 60.20621 -436.236966) (xy 60.18318 -436.22947) (xy 60.163605 -436.215208) (xy 60.149411 -436.195585)
			(xy 60.141993 -436.172529) (xy 60.141612 -436.160418) (xy 60.141612 -435.550056) (xy 60.139946 -435.535062)
			(xy 60.138166 -435.504944) (xy 60.138056 -435.489858) (xy 7.00913 -435.489858) (xy 7.00913 -438.089802)
			(xy 58.13806 -438.089802) (xy 58.138177 -438.074717) (xy 58.139953 -438.044598) (xy 58.141616 -438.029604)
			(xy 58.141616 -436.950104) (xy 58.139946 -436.935111) (xy 58.138168 -436.904992) (xy 58.13806 -436.889906)
			(xy 58.138168 -436.87482) (xy 58.13995 -436.844702) (xy 58.141616 -436.829708) (xy 58.141616 -436.219092)
			(xy 58.142006 -436.207006) (xy 58.149479 -436.184019) (xy 58.16369 -436.164467) (xy 58.183248 -436.150264)
			(xy 58.206238 -436.142801) (xy 58.218324 -436.142384) (xy 59.158124 -436.142384) (xy 59.170199 -436.142844)
			(xy 59.193166 -436.150312) (xy 59.212701 -436.16451) (xy 59.226895 -436.184049) (xy 59.234359 -436.207017)
			(xy 59.234832 -436.219092) (xy 59.234832 -438.760616) (xy 59.23435 -438.772689) (xy 59.226886 -438.795653)
			(xy 59.212693 -438.815187) (xy 59.19316 -438.829382) (xy 59.170197 -438.836848) (xy 59.158124 -438.837324)
			(xy 58.218324 -438.837324) (xy 58.206244 -438.836867) (xy 58.183265 -438.829408) (xy 58.163716 -438.815213)
			(xy 58.14951 -438.795671) (xy 58.142039 -438.772696) (xy 58.141616 -438.760616) (xy 58.141616 -438.15)
			(xy 58.139945 -438.135007) (xy 58.138168 -438.104888) (xy 58.13806 -438.089802) (xy 7.00913 -438.089802)
			(xy 7.00913 -439.0898) (xy 60.138056 -439.0898) (xy 60.138173 -439.074715) (xy 60.139949 -439.044596)
			(xy 60.141612 -439.029602) (xy 60.141612 -437.950102) (xy 60.139941 -437.935109) (xy 60.138164 -437.90499)
			(xy 60.138056 -437.889904) (xy 60.138173 -437.874819) (xy 60.139949 -437.8447) (xy 60.141612 -437.829706)
			(xy 60.141612 -437.21909) (xy 60.142099 -437.207003) (xy 60.149555 -437.184007) (xy 60.163737 -437.164429)
			(xy 60.183265 -437.150178) (xy 60.206234 -437.142641) (xy 60.21832 -437.142128) (xy 61.15812 -437.142128)
			(xy 61.170233 -437.1425) (xy 61.193265 -437.150008) (xy 61.212841 -437.16428) (xy 61.227034 -437.183913)
			(xy 61.234449 -437.206976) (xy 61.234828 -437.21909) (xy 61.234828 -438.089802) (xy 62.138052 -438.089802)
			(xy 62.138169 -438.074717) (xy 62.139945 -438.044598) (xy 62.141608 -438.029604) (xy 62.141608 -436.950104)
			(xy 62.139938 -436.935111) (xy 62.13816 -436.904992) (xy 62.138052 -436.889906) (xy 62.13816 -436.87482)
			(xy 62.139942 -436.844702) (xy 62.141608 -436.829708) (xy 62.141608 -436.219092) (xy 62.142006 -436.207007)
			(xy 62.149478 -436.184021) (xy 62.163687 -436.16447) (xy 62.183243 -436.150267) (xy 62.206231 -436.142802)
			(xy 62.218316 -436.142384) (xy 63.158116 -436.142384) (xy 63.170191 -436.142851) (xy 63.193157 -436.150317)
			(xy 63.212693 -436.164513) (xy 63.226887 -436.18405) (xy 63.234351 -436.207017) (xy 63.234824 -436.219092)
			(xy 63.234824 -438.760616) (xy 63.23435 -438.77269) (xy 63.226885 -438.795655) (xy 63.21269 -438.81519)
			(xy 63.193155 -438.829385) (xy 63.17019 -438.83685) (xy 63.158116 -438.837324) (xy 62.218316 -438.837324)
			(xy 62.206244 -438.836822) (xy 62.18328 -438.829366) (xy 62.163744 -438.815179) (xy 62.149548 -438.795649)
			(xy 62.142083 -438.772688) (xy 62.141608 -438.760616) (xy 62.141608 -438.15) (xy 62.139937 -438.135007)
			(xy 62.13816 -438.104888) (xy 62.138052 -438.089802) (xy 61.234828 -438.089802) (xy 61.234828 -439.0898)
			(xy 64.138048 -439.0898) (xy 64.138165 -439.074715) (xy 64.139941 -439.044596) (xy 64.141604 -439.029602)
			(xy 64.141604 -437.950102) (xy 64.139933 -437.935109) (xy 64.138156 -437.90499) (xy 64.138048 -437.889904)
			(xy 64.138165 -437.874819) (xy 64.139941 -437.8447) (xy 64.141604 -437.829706) (xy 64.141604 -437.21909)
			(xy 64.142098 -437.207004) (xy 64.149553 -437.184009) (xy 64.163734 -437.164432) (xy 64.18326 -437.150181)
			(xy 64.206227 -437.142643) (xy 64.218312 -437.142128) (xy 65.158112 -437.142128) (xy 65.170224 -437.142506)
			(xy 65.193257 -437.150012) (xy 65.212832 -437.164283) (xy 65.227025 -437.183914) (xy 65.234441 -437.206976)
			(xy 65.23482 -437.21909) (xy 65.23482 -438.089802) (xy 66.138044 -438.089802) (xy 66.138161 -438.074717)
			(xy 66.139937 -438.044598) (xy 66.1416 -438.029604) (xy 66.1416 -436.950104) (xy 66.13993 -436.935111)
			(xy 66.138152 -436.904992) (xy 66.138044 -436.889906) (xy 66.138152 -436.87482) (xy 66.139934 -436.844702)
			(xy 66.1416 -436.829708) (xy 66.1416 -436.219092) (xy 66.142058 -436.207016) (xy 66.149523 -436.184047)
			(xy 66.163721 -436.16451) (xy 66.183262 -436.150316) (xy 66.206232 -436.142855) (xy 66.218308 -436.142384)
			(xy 67.158108 -436.142384) (xy 67.170182 -436.142857) (xy 67.193148 -436.150321) (xy 67.212684 -436.164516)
			(xy 67.226879 -436.184052) (xy 67.234343 -436.207018) (xy 67.234816 -436.219092) (xy 67.234816 -438.760616)
			(xy 67.234349 -438.772691) (xy 67.226883 -438.795657) (xy 67.212687 -438.815193) (xy 67.19315 -438.829387)
			(xy 67.170183 -438.836851) (xy 67.158108 -438.837324) (xy 66.218308 -438.837324) (xy 66.206235 -438.836829)
			(xy 66.183271 -438.829371) (xy 66.163735 -438.815182) (xy 66.14954 -438.79565) (xy 66.142075 -438.772688)
			(xy 66.1416 -438.760616) (xy 66.1416 -438.15) (xy 66.139929 -438.135007) (xy 66.138152 -438.104888)
			(xy 66.138044 -438.089802) (xy 65.23482 -438.089802) (xy 65.23482 -439.0898) (xy 68.13804 -439.0898)
			(xy 68.138157 -439.074715) (xy 68.139933 -439.044596) (xy 68.141596 -439.029602) (xy 68.141596 -437.950102)
			(xy 68.139925 -437.935109) (xy 68.138148 -437.90499) (xy 68.13804 -437.889904) (xy 68.138157 -437.874819)
			(xy 68.139933 -437.8447) (xy 68.141596 -437.829706) (xy 68.141596 -437.21909) (xy 68.142098 -437.207004)
			(xy 68.149552 -437.184011) (xy 68.163731 -437.164435) (xy 68.183255 -437.150183) (xy 68.20622 -437.142644)
			(xy 68.218304 -437.142128) (xy 69.158104 -437.142128) (xy 69.170216 -437.142513) (xy 69.193248 -437.150017)
			(xy 69.212824 -437.164286) (xy 69.227017 -437.183916) (xy 69.234433 -437.206977) (xy 69.234812 -437.21909)
			(xy 69.234812 -438.089802) (xy 70.138036 -438.089802) (xy 70.138153 -438.074717) (xy 70.139929 -438.044598)
			(xy 70.141592 -438.029604) (xy 70.141592 -436.950104) (xy 70.139922 -436.935111) (xy 70.138144 -436.904992)
			(xy 70.138036 -436.889906) (xy 70.138146 -436.87482) (xy 70.139928 -436.844702) (xy 70.141592 -436.829708)
			(xy 70.141592 -436.219092) (xy 70.142058 -436.207017) (xy 70.149522 -436.18405) (xy 70.163718 -436.164513)
			(xy 70.183257 -436.150319) (xy 70.206225 -436.142856) (xy 70.2183 -436.142384) (xy 71.1581 -436.142384)
			(xy 71.170174 -436.142864) (xy 71.19314 -436.150326) (xy 71.212676 -436.164518) (xy 71.226871 -436.184053)
			(xy 71.234335 -436.207018) (xy 71.234808 -436.219092) (xy 71.234808 -438.760616) (xy 71.234349 -438.772691)
			(xy 71.226882 -438.795659) (xy 71.212684 -438.815196) (xy 71.193145 -438.82939) (xy 71.170175 -438.836852)
			(xy 71.1581 -438.837324) (xy 70.2183 -438.837324) (xy 70.206227 -438.836836) (xy 70.183263 -438.829375)
			(xy 70.163727 -438.815184) (xy 70.149532 -438.795652) (xy 70.142067 -438.772689) (xy 70.141592 -438.760616)
			(xy 70.141592 -438.15) (xy 70.139921 -438.135007) (xy 70.138144 -438.104888) (xy 70.138036 -438.089802)
			(xy 69.234812 -438.089802) (xy 69.234812 -439.0898) (xy 72.138032 -439.0898) (xy 72.138151 -439.074715)
			(xy 72.139927 -439.044596) (xy 72.141588 -439.029602) (xy 72.141588 -437.950102) (xy 72.139917 -437.935109)
			(xy 72.13814 -437.90499) (xy 72.138032 -437.889904) (xy 72.138151 -437.874819) (xy 72.139927 -437.8447)
			(xy 72.141588 -437.829706) (xy 72.141588 -437.21909) (xy 72.142 -437.206995) (xy 72.149465 -437.183986)
			(xy 72.163664 -437.164402) (xy 72.183212 -437.150154) (xy 72.206202 -437.142631) (xy 72.218296 -437.142128)
			(xy 73.158096 -437.142128) (xy 73.170207 -437.14252) (xy 73.193239 -437.150022) (xy 73.212815 -437.164288)
			(xy 73.227009 -437.183917) (xy 73.234425 -437.206977) (xy 73.234804 -437.21909) (xy 73.234804 -438.089802)
			(xy 75.138026 -438.089802) (xy 75.138119 -438.075228) (xy 75.139772 -438.046127) (xy 75.141328 -438.031636)
			(xy 75.141328 -436.948072) (xy 75.139784 -436.93358) (xy 75.138131 -436.90448) (xy 75.138026 -436.889906)
			(xy 75.138119 -436.875332) (xy 75.139772 -436.846231) (xy 75.141328 -436.83174) (xy 75.141328 -436.219092)
			(xy 75.14171 -436.20698) (xy 75.149215 -436.183948) (xy 75.163484 -436.164372) (xy 75.183115 -436.150179)
			(xy 75.206176 -436.142763) (xy 75.21829 -436.142384) (xy 76.15809 -436.142384) (xy 76.170183 -436.142817)
			(xy 76.193191 -436.150276) (xy 76.212775 -436.16447) (xy 76.227024 -436.184014) (xy 76.234549 -436.207)
			(xy 76.235052 -436.219092) (xy 76.235052 -438.760616) (xy 76.234598 -438.772721) (xy 76.227101 -438.795739)
			(xy 76.212847 -438.815308) (xy 76.193237 -438.829504) (xy 76.170196 -438.836933) (xy 76.15809 -438.837324)
			(xy 75.21829 -438.837324) (xy 75.206196 -438.8369) (xy 75.183189 -438.829436) (xy 75.163607 -438.81524)
			(xy 75.149358 -438.795695) (xy 75.141832 -438.772708) (xy 75.141328 -438.760616) (xy 75.141328 -438.147968)
			(xy 75.139783 -438.133476) (xy 75.138131 -438.104376) (xy 75.138026 -438.089802) (xy 73.234804 -438.089802)
			(xy 73.234804 -439.0898) (xy 77.138022 -439.0898) (xy 77.138115 -439.075226) (xy 77.139768 -439.046125)
			(xy 77.141324 -439.031634) (xy 77.141324 -437.94807) (xy 77.139779 -437.933578) (xy 77.138127 -437.904478)
			(xy 77.138022 -437.889904) (xy 77.138115 -437.87533) (xy 77.139768 -437.846229) (xy 77.141324 -437.831738)
			(xy 77.141324 -437.21909) (xy 77.141803 -437.206976) (xy 77.149291 -437.183935) (xy 77.163532 -437.164335)
			(xy 77.183132 -437.150093) (xy 77.206172 -437.142604) (xy 77.218286 -437.142128) (xy 78.158086 -437.142128)
			(xy 78.170207 -437.142572) (xy 78.193264 -437.150059) (xy 78.212878 -437.164305) (xy 78.22713 -437.183915)
			(xy 78.234624 -437.206969) (xy 78.235048 -437.21909) (xy 78.235048 -438.089802) (xy 79.138018 -438.089802)
			(xy 79.138111 -438.075228) (xy 79.139764 -438.046127) (xy 79.14132 -438.031636) (xy 79.14132 -436.948072)
			(xy 79.139776 -436.93358) (xy 79.138123 -436.90448) (xy 79.138018 -436.889906) (xy 79.138111 -436.875332)
			(xy 79.139764 -436.846231) (xy 79.14132 -436.83174) (xy 79.14132 -436.219092) (xy 79.14171 -436.206981)
			(xy 79.149214 -436.18395) (xy 79.163481 -436.164375) (xy 79.18311 -436.150181) (xy 79.206169 -436.142764)
			(xy 79.218282 -436.142384) (xy 80.158082 -436.142384) (xy 80.170175 -436.142824) (xy 80.193182 -436.150281)
			(xy 80.212766 -436.164473) (xy 80.227016 -436.184015) (xy 80.234541 -436.207) (xy 80.235044 -436.219092)
			(xy 80.235044 -438.760616) (xy 80.234598 -438.772721) (xy 80.227099 -438.795742) (xy 80.212844 -438.815311)
			(xy 80.193232 -438.829506) (xy 80.170189 -438.836935) (xy 80.158082 -438.837324) (xy 79.218282 -438.837324)
			(xy 79.206188 -438.836907) (xy 79.183181 -438.829441) (xy 79.163598 -438.815243) (xy 79.149349 -438.795697)
			(xy 79.141824 -438.772709) (xy 79.14132 -438.760616) (xy 79.14132 -438.147968) (xy 79.139775 -438.133476)
			(xy 79.138123 -438.104376) (xy 79.138018 -438.089802) (xy 78.235048 -438.089802) (xy 78.235048 -439.0898)
			(xy 81.138014 -439.0898) (xy 81.138106 -439.075226) (xy 81.13976 -439.046125) (xy 81.141316 -439.031634)
			(xy 81.141316 -437.94807) (xy 81.139771 -437.933578) (xy 81.138119 -437.904478) (xy 81.138014 -437.889904)
			(xy 81.138107 -437.87533) (xy 81.13976 -437.846229) (xy 81.141316 -437.831738) (xy 81.141316 -437.21909)
			(xy 81.141803 -437.206977) (xy 81.14929 -437.183937) (xy 81.163529 -437.164338) (xy 81.183127 -437.150096)
			(xy 81.206165 -437.142605) (xy 81.218278 -437.142128) (xy 82.158078 -437.142128) (xy 82.170199 -437.142579)
			(xy 82.193255 -437.150064) (xy 82.21287 -437.164308) (xy 82.227122 -437.183916) (xy 82.234616 -437.20697)
			(xy 82.23504 -437.21909) (xy 82.23504 -438.089802) (xy 83.13801 -438.089802) (xy 83.138103 -438.075228)
			(xy 83.139756 -438.046127) (xy 83.141312 -438.031636) (xy 83.141312 -436.948072) (xy 83.139767 -436.93358)
			(xy 83.138115 -436.90448) (xy 83.13801 -436.889906) (xy 83.138103 -436.875332) (xy 83.139756 -436.846231)
			(xy 83.141312 -436.83174) (xy 83.141312 -436.219092) (xy 83.14171 -436.206981) (xy 83.149213 -436.183952)
			(xy 83.163479 -436.164378) (xy 83.183105 -436.150184) (xy 83.206162 -436.142765) (xy 83.218274 -436.142384)
			(xy 84.158074 -436.142384) (xy 84.170167 -436.14283) (xy 84.193174 -436.150285) (xy 84.212758 -436.164476)
			(xy 84.227008 -436.184017) (xy 84.234533 -436.207001) (xy 84.235036 -436.219092) (xy 84.235036 -438.760616)
			(xy 84.234598 -438.772722) (xy 84.227098 -438.795744) (xy 84.212841 -438.815313) (xy 84.193227 -438.829509)
			(xy 84.170181 -438.836936) (xy 84.158074 -438.837324) (xy 83.218274 -438.837324) (xy 83.206179 -438.836914)
			(xy 83.183172 -438.829446) (xy 83.163589 -438.815246) (xy 83.149341 -438.795698) (xy 83.141816 -438.772709)
			(xy 83.141312 -438.760616) (xy 83.141312 -438.147968) (xy 83.139767 -438.133476) (xy 83.138115 -438.104376)
			(xy 83.13801 -438.089802) (xy 82.23504 -438.089802) (xy 82.23504 -439.0898) (xy 85.138006 -439.0898)
			(xy 85.138098 -439.075226) (xy 85.139752 -439.046125) (xy 85.141308 -439.031634) (xy 85.141308 -437.94807)
			(xy 85.139763 -437.933578) (xy 85.138111 -437.904478) (xy 85.138006 -437.889904) (xy 85.138099 -437.87533)
			(xy 85.139752 -437.846229) (xy 85.141308 -437.831738) (xy 85.141308 -437.21909) (xy 85.141803 -437.206978)
			(xy 85.149289 -437.18394) (xy 85.163526 -437.164341) (xy 85.183122 -437.150098) (xy 85.206158 -437.142606)
			(xy 85.21827 -437.142128) (xy 86.15807 -437.142128) (xy 86.17019 -437.142585) (xy 86.193246 -437.150068)
			(xy 86.212861 -437.16431) (xy 86.227114 -437.183918) (xy 86.234608 -437.20697) (xy 86.235032 -437.21909)
			(xy 86.235032 -438.089802) (xy 87.138002 -438.089802) (xy 87.138095 -438.075228) (xy 87.139748 -438.046127)
			(xy 87.141304 -438.031636) (xy 87.141304 -436.948072) (xy 87.139759 -436.93358) (xy 87.138107 -436.90448)
			(xy 87.138002 -436.889906) (xy 87.138095 -436.875332) (xy 87.139748 -436.846231) (xy 87.141304 -436.83174)
			(xy 87.141304 -436.219092) (xy 87.141709 -436.206982) (xy 87.149212 -436.183954) (xy 87.163476 -436.164381)
			(xy 87.1831 -436.150186) (xy 87.206155 -436.142767) (xy 87.218266 -436.142384) (xy 88.158066 -436.142384)
			(xy 88.170158 -436.142837) (xy 88.193165 -436.15029) (xy 88.212749 -436.164478) (xy 88.227 -436.184018)
			(xy 88.234525 -436.207001) (xy 88.235028 -436.219092) (xy 88.235028 -438.760616) (xy 88.234598 -438.772723)
			(xy 88.227097 -438.795746) (xy 88.212838 -438.815316) (xy 88.193222 -438.829511) (xy 88.170174 -438.836937)
			(xy 88.158066 -438.837324) (xy 87.218266 -438.837324) (xy 87.206171 -438.836921) (xy 87.183163 -438.829451)
			(xy 87.163581 -438.815249) (xy 87.149333 -438.7957) (xy 87.141808 -438.77271) (xy 87.141304 -438.760616)
			(xy 87.141304 -438.147968) (xy 87.139759 -438.133476) (xy 87.138107 -438.104376) (xy 87.138002 -438.089802)
			(xy 86.235032 -438.089802) (xy 86.235032 -439.0898) (xy 89.137998 -439.0898) (xy 89.13809 -439.075226)
			(xy 89.139744 -439.046125) (xy 89.1413 -439.031634) (xy 89.1413 -437.94807) (xy 89.139755 -437.933578)
			(xy 89.138103 -437.904478) (xy 89.137998 -437.889904) (xy 89.138091 -437.87533) (xy 89.139744 -437.846229)
			(xy 89.1413 -437.831738) (xy 89.1413 -437.21909) (xy 89.141803 -437.206979) (xy 89.149288 -437.183942)
			(xy 89.163524 -437.164343) (xy 89.183117 -437.150101) (xy 89.206151 -437.142607) (xy 89.218262 -437.142128)
			(xy 90.158062 -437.142128) (xy 90.170182 -437.142592) (xy 90.193238 -437.150073) (xy 90.212853 -437.164313)
			(xy 90.227105 -437.183919) (xy 90.2346 -437.20697) (xy 90.235024 -437.21909) (xy 90.235024 -439.0898)
			(xy 127.237998 -439.0898) (xy 127.23809 -439.075226) (xy 127.239744 -439.046125) (xy 127.2413 -439.031634)
			(xy 127.2413 -437.94807) (xy 127.239755 -437.933578) (xy 127.238103 -437.904478) (xy 127.237998 -437.889904)
			(xy 127.238091 -437.87533) (xy 127.239744 -437.846229) (xy 127.2413 -437.831738) (xy 127.2413 -437.21909)
			(xy 127.241803 -437.206979) (xy 127.249288 -437.183942) (xy 127.263524 -437.164343) (xy 127.283117 -437.150101)
			(xy 127.306151 -437.142607) (xy 127.318262 -437.142128) (xy 128.258062 -437.142128) (xy 128.270182 -437.142592)
			(xy 128.293238 -437.150073) (xy 128.312853 -437.164313) (xy 128.327105 -437.183919) (xy 128.3346 -437.20697)
			(xy 128.335024 -437.21909) (xy 128.335024 -438.089802) (xy 129.237994 -438.089802) (xy 129.238087 -438.075228)
			(xy 129.23974 -438.046127) (xy 129.241296 -438.031636) (xy 129.241296 -436.948072) (xy 129.239752 -436.93358)
			(xy 129.238099 -436.90448) (xy 129.237994 -436.889906) (xy 129.238087 -436.875332) (xy 129.23974 -436.846231)
			(xy 129.241296 -436.83174) (xy 129.241296 -436.219092) (xy 129.241709 -436.206983) (xy 129.24921 -436.183956)
			(xy 129.263473 -436.164384) (xy 129.283095 -436.150189) (xy 129.306148 -436.142768) (xy 129.318258 -436.142384)
			(xy 130.258058 -436.142384) (xy 130.27015 -436.142844) (xy 130.293156 -436.150294) (xy 130.312741 -436.164481)
			(xy 130.326991 -436.184019) (xy 130.334516 -436.207002) (xy 130.33502 -436.219092) (xy 130.33502 -438.760616)
			(xy 130.334598 -438.772724) (xy 130.327096 -438.795748) (xy 130.312836 -438.815319) (xy 130.293217 -438.829514)
			(xy 130.270167 -438.836938) (xy 130.258058 -438.837324) (xy 129.318258 -438.837324) (xy 129.306163 -438.836928)
			(xy 129.283155 -438.829455) (xy 129.263572 -438.815252) (xy 129.249324 -438.795701) (xy 129.2418 -438.77271)
			(xy 129.241296 -438.760616) (xy 129.241296 -438.147968) (xy 129.239751 -438.133476) (xy 129.238099 -438.104376)
			(xy 129.237994 -438.089802) (xy 128.335024 -438.089802) (xy 128.335024 -439.0898) (xy 131.23799 -439.0898)
			(xy 131.238082 -439.075226) (xy 131.239736 -439.046125) (xy 131.241292 -439.031634) (xy 131.241292 -437.94807)
			(xy 131.239748 -437.933578) (xy 131.238095 -437.904478) (xy 131.23799 -437.889904) (xy 131.238083 -437.87533)
			(xy 131.239736 -437.846229) (xy 131.241292 -437.831738) (xy 131.241292 -437.21909) (xy 131.241803 -437.20698)
			(xy 131.249287 -437.183944) (xy 131.263521 -437.164346) (xy 131.283112 -437.150104) (xy 131.306144 -437.142608)
			(xy 131.318254 -437.142128) (xy 132.258054 -437.142128) (xy 132.270173 -437.142599) (xy 132.293229 -437.150077)
			(xy 132.312844 -437.164316) (xy 132.327097 -437.183921) (xy 132.334592 -437.206971) (xy 132.335016 -437.21909)
			(xy 132.335016 -438.089802) (xy 133.237986 -438.089802) (xy 133.238079 -438.075228) (xy 133.239732 -438.046127)
			(xy 133.241288 -438.031636) (xy 133.241288 -436.948072) (xy 133.239744 -436.93358) (xy 133.238091 -436.90448)
			(xy 133.237986 -436.889906) (xy 133.238079 -436.875332) (xy 133.239732 -436.846231) (xy 133.241288 -436.83174)
			(xy 133.241288 -436.219092) (xy 133.241709 -436.206984) (xy 133.249209 -436.183958) (xy 133.26347 -436.164386)
			(xy 133.28309 -436.150192) (xy 133.306141 -436.142769) (xy 133.31825 -436.142384) (xy 134.25805 -436.142384)
			(xy 134.270141 -436.142851) (xy 134.293148 -436.150299) (xy 134.312732 -436.164484) (xy 134.326983 -436.184021)
			(xy 134.334508 -436.207002) (xy 134.335012 -436.219092) (xy 134.335012 -438.760616) (xy 134.334598 -438.772725)
			(xy 134.327095 -438.79575) (xy 134.312833 -438.815322) (xy 134.293212 -438.829517) (xy 134.27016 -438.836939)
			(xy 134.25805 -438.837324) (xy 133.31825 -438.837324) (xy 133.306159 -438.836849) (xy 133.283154 -438.829402)
			(xy 133.26357 -438.815219) (xy 133.249319 -438.795684) (xy 133.241793 -438.772705) (xy 133.241288 -438.760616)
			(xy 133.241288 -438.147968) (xy 133.239743 -438.133476) (xy 133.238091 -438.104376) (xy 133.237986 -438.089802)
			(xy 132.335016 -438.089802) (xy 132.335016 -439.0898) (xy 135.237982 -439.0898) (xy 135.238075 -439.075226)
			(xy 135.239728 -439.046125) (xy 135.241284 -439.031634) (xy 135.241284 -437.94807) (xy 135.23974 -437.933578)
			(xy 135.238087 -437.904478) (xy 135.237982 -437.889904) (xy 135.238075 -437.87533) (xy 135.239728 -437.846229)
			(xy 135.241284 -437.831738) (xy 135.241284 -437.21909) (xy 135.241652 -437.206962) (xy 135.249153 -437.183895)
			(xy 135.263416 -437.164276) (xy 135.283045 -437.150027) (xy 135.306118 -437.142544) (xy 135.318246 -437.142128)
			(xy 136.258046 -437.142128) (xy 136.270162 -437.142572) (xy 136.293205 -437.150071) (xy 136.312805 -437.164321)
			(xy 136.327045 -437.183927) (xy 136.334533 -437.206974) (xy 136.335008 -437.21909) (xy 136.335008 -438.089802)
			(xy 137.237978 -438.089802) (xy 137.238071 -438.075228) (xy 137.239724 -438.046127) (xy 137.24128 -438.031636)
			(xy 137.24128 -436.948072) (xy 137.239736 -436.93358) (xy 137.238083 -436.90448) (xy 137.237978 -436.889906)
			(xy 137.238071 -436.875332) (xy 137.239724 -436.846231) (xy 137.24128 -436.83174) (xy 137.24128 -436.219092)
			(xy 137.241709 -436.206985) (xy 137.249208 -436.183961) (xy 137.263467 -436.164389) (xy 137.283085 -436.150194)
			(xy 137.306133 -436.14277) (xy 137.318242 -436.142384) (xy 138.258042 -436.142384) (xy 138.270138 -436.142772)
			(xy 138.293148 -436.150246) (xy 138.312731 -436.164451) (xy 138.326978 -436.184004) (xy 138.334501 -436.206997)
			(xy 138.335004 -436.219092) (xy 138.335004 -438.760616) (xy 138.334597 -438.772725) (xy 138.327094 -438.795752)
			(xy 138.31283 -438.815325) (xy 138.293207 -438.829519) (xy 138.270153 -438.83694) (xy 138.258042 -438.837324)
			(xy 137.318242 -438.837324) (xy 137.306151 -438.836856) (xy 137.283146 -438.829407) (xy 137.263562 -438.815222)
			(xy 137.249311 -438.795686) (xy 137.241785 -438.772705) (xy 137.24128 -438.760616) (xy 137.24128 -438.147968)
			(xy 137.239735 -438.133476) (xy 137.238083 -438.104376) (xy 137.237978 -438.089802) (xy 136.335008 -438.089802)
			(xy 136.335008 -439.0898) (xy 139.237974 -439.0898) (xy 139.238067 -439.075226) (xy 139.23972 -439.046125)
			(xy 139.241276 -439.031634) (xy 139.241276 -437.94807) (xy 139.239732 -437.933578) (xy 139.238079 -437.904478)
			(xy 139.237974 -437.889904) (xy 139.238067 -437.87533) (xy 139.23972 -437.846229) (xy 139.241276 -437.831738)
			(xy 139.241276 -437.21909) (xy 139.241652 -437.206963) (xy 139.249152 -437.183897) (xy 139.263413 -437.164279)
			(xy 139.28304 -437.15003) (xy 139.306111 -437.142545) (xy 139.318238 -437.142128) (xy 140.258038 -437.142128)
			(xy 140.270154 -437.142579) (xy 140.293196 -437.150076) (xy 140.312797 -437.164323) (xy 140.327037 -437.183929)
			(xy 140.334525 -437.206974) (xy 140.335 -437.21909) (xy 140.335 -438.089802) (xy 142.237968 -438.089802)
			(xy 142.238085 -438.074717) (xy 142.239861 -438.044598) (xy 142.241524 -438.029604) (xy 142.241524 -436.950104)
			(xy 142.239854 -436.935111) (xy 142.238076 -436.904992) (xy 142.237968 -436.889906) (xy 142.238076 -436.87482)
			(xy 142.239858 -436.844702) (xy 142.241524 -436.829708) (xy 142.241524 -436.219092) (xy 142.241906 -436.207006)
			(xy 142.24938 -436.184017) (xy 142.263593 -436.164464) (xy 142.283153 -436.150262) (xy 142.306145 -436.1428)
			(xy 142.318232 -436.142384) (xy 143.258032 -436.142384) (xy 143.270107 -436.142837) (xy 143.293074 -436.150307)
			(xy 143.31261 -436.164507) (xy 143.326804 -436.184047) (xy 143.334267 -436.207016) (xy 143.33474 -436.219092)
			(xy 143.33474 -438.760616) (xy 143.33425 -438.772688) (xy 143.326787 -438.79565) (xy 143.312596 -438.815184)
			(xy 143.293065 -438.829379) (xy 143.270104 -438.836847) (xy 143.258032 -438.837324) (xy 142.318232 -438.837324)
			(xy 142.306153 -438.83686) (xy 142.283174 -438.829403) (xy 142.263624 -438.81521) (xy 142.249418 -438.795669)
			(xy 142.241947 -438.772695) (xy 142.241524 -438.760616) (xy 142.241524 -438.15) (xy 142.239853 -438.135007)
			(xy 142.238076 -438.104888) (xy 142.237968 -438.089802) (xy 140.335 -438.089802) (xy 140.335 -439.0898)
			(xy 144.237964 -439.0898) (xy 144.23808 -439.074715) (xy 144.239857 -439.044596) (xy 144.24152 -439.029602)
			(xy 144.24152 -437.950102) (xy 144.239849 -437.935109) (xy 144.238072 -437.90499) (xy 144.237964 -437.889904)
			(xy 144.238081 -437.874819) (xy 144.239857 -437.8447) (xy 144.24152 -437.829706) (xy 144.24152 -437.21909)
			(xy 144.241999 -437.207002) (xy 144.249456 -437.184004) (xy 144.26364 -437.164426) (xy 144.28317 -437.150176)
			(xy 144.306142 -437.14264) (xy 144.318228 -437.142128) (xy 145.258028 -437.142128) (xy 145.270141 -437.142493)
			(xy 145.293174 -437.150003) (xy 145.312749 -437.164277) (xy 145.326942 -437.183911) (xy 145.334357 -437.206975)
			(xy 145.334736 -437.21909) (xy 145.334736 -438.089802) (xy 146.23796 -438.089802) (xy 146.238077 -438.074717)
			(xy 146.239853 -438.044598) (xy 146.241516 -438.029604) (xy 146.241516 -436.950104) (xy 146.239846 -436.935111)
			(xy 146.238068 -436.904992) (xy 146.23796 -436.889906) (xy 146.238068 -436.87482) (xy 146.23985 -436.844702)
			(xy 146.241516 -436.829708) (xy 146.241516 -436.219092) (xy 146.241906 -436.207006) (xy 146.249379 -436.184019)
			(xy 146.26359 -436.164467) (xy 146.283148 -436.150264) (xy 146.306138 -436.142801) (xy 146.318224 -436.142384)
			(xy 147.258024 -436.142384) (xy 147.270099 -436.142844) (xy 147.293066 -436.150312) (xy 147.312601 -436.16451)
			(xy 147.326795 -436.184049) (xy 147.334259 -436.207017) (xy 147.334732 -436.219092) (xy 147.334732 -438.760616)
			(xy 147.33425 -438.772689) (xy 147.326786 -438.795653) (xy 147.312593 -438.815187) (xy 147.29306 -438.829382)
			(xy 147.270097 -438.836848) (xy 147.258024 -438.837324) (xy 146.318224 -438.837324) (xy 146.306144 -438.836867)
			(xy 146.283165 -438.829408) (xy 146.263616 -438.815213) (xy 146.24941 -438.795671) (xy 146.241939 -438.772696)
			(xy 146.241516 -438.760616) (xy 146.241516 -438.15) (xy 146.239845 -438.135007) (xy 146.238068 -438.104888)
			(xy 146.23796 -438.089802) (xy 145.334736 -438.089802) (xy 145.334736 -439.0898) (xy 148.237956 -439.0898)
			(xy 148.238073 -439.074715) (xy 148.239849 -439.044596) (xy 148.241512 -439.029602) (xy 148.241512 -437.950102)
			(xy 148.239841 -437.935109) (xy 148.238064 -437.90499) (xy 148.237956 -437.889904) (xy 148.238073 -437.874819)
			(xy 148.239849 -437.8447) (xy 148.241512 -437.829706) (xy 148.241512 -437.21909) (xy 148.241999 -437.207003)
			(xy 148.249455 -437.184007) (xy 148.263637 -437.164429) (xy 148.283165 -437.150178) (xy 148.306134 -437.142641)
			(xy 148.31822 -437.142128) (xy 149.25802 -437.142128) (xy 149.270133 -437.1425) (xy 149.293165 -437.150008)
			(xy 149.312741 -437.16428) (xy 149.326934 -437.183913) (xy 149.334349 -437.206976) (xy 149.334728 -437.21909)
			(xy 149.334728 -438.089802) (xy 150.237952 -438.089802) (xy 150.238069 -438.074717) (xy 150.239845 -438.044598)
			(xy 150.241508 -438.029604) (xy 150.241508 -436.950104) (xy 150.239838 -436.935111) (xy 150.23806 -436.904992)
			(xy 150.237952 -436.889906) (xy 150.23806 -436.87482) (xy 150.239842 -436.844702) (xy 150.241508 -436.829708)
			(xy 150.241508 -436.219092) (xy 150.241906 -436.207007) (xy 150.249378 -436.184021) (xy 150.263587 -436.16447)
			(xy 150.283143 -436.150267) (xy 150.306131 -436.142802) (xy 150.318216 -436.142384) (xy 151.258016 -436.142384)
			(xy 151.270091 -436.142851) (xy 151.293057 -436.150317) (xy 151.312593 -436.164513) (xy 151.326787 -436.18405)
			(xy 151.334251 -436.207017) (xy 151.334724 -436.219092) (xy 151.334724 -438.760616) (xy 151.33425 -438.77269)
			(xy 151.326785 -438.795655) (xy 151.31259 -438.81519) (xy 151.293055 -438.829385) (xy 151.27009 -438.83685)
			(xy 151.258016 -438.837324) (xy 150.318216 -438.837324) (xy 150.306144 -438.836822) (xy 150.28318 -438.829366)
			(xy 150.263644 -438.815179) (xy 150.249448 -438.795649) (xy 150.241983 -438.772688) (xy 150.241508 -438.760616)
			(xy 150.241508 -438.15) (xy 150.239837 -438.135007) (xy 150.23806 -438.104888) (xy 150.237952 -438.089802)
			(xy 149.334728 -438.089802) (xy 149.334728 -439.0898) (xy 152.237948 -439.0898) (xy 152.238065 -439.074715)
			(xy 152.239841 -439.044596) (xy 152.241504 -439.029602) (xy 152.241504 -437.950102) (xy 152.239833 -437.935109)
			(xy 152.238056 -437.90499) (xy 152.237948 -437.889904) (xy 152.238065 -437.874819) (xy 152.239841 -437.8447)
			(xy 152.241504 -437.829706) (xy 152.241504 -437.21909) (xy 152.241998 -437.207004) (xy 152.249453 -437.184009)
			(xy 152.263634 -437.164432) (xy 152.28316 -437.150181) (xy 152.306127 -437.142643) (xy 152.318212 -437.142128)
			(xy 153.258012 -437.142128) (xy 153.270124 -437.142506) (xy 153.293157 -437.150012) (xy 153.312732 -437.164283)
			(xy 153.326925 -437.183914) (xy 153.334341 -437.206976) (xy 153.33472 -437.21909) (xy 153.33472 -438.089802)
			(xy 154.237944 -438.089802) (xy 154.238061 -438.074717) (xy 154.239837 -438.044598) (xy 154.2415 -438.029604)
			(xy 154.2415 -436.950104) (xy 154.23983 -436.935111) (xy 154.238052 -436.904992) (xy 154.237944 -436.889906)
			(xy 154.238052 -436.87482) (xy 154.239834 -436.844702) (xy 154.2415 -436.829708) (xy 154.2415 -436.219092)
			(xy 154.241958 -436.207016) (xy 154.249423 -436.184047) (xy 154.263621 -436.16451) (xy 154.283162 -436.150316)
			(xy 154.306132 -436.142855) (xy 154.318208 -436.142384) (xy 155.258008 -436.142384) (xy 155.270082 -436.142857)
			(xy 155.293048 -436.150321) (xy 155.312584 -436.164516) (xy 155.326779 -436.184052) (xy 155.334243 -436.207018)
			(xy 155.334716 -436.219092) (xy 155.334716 -438.760616) (xy 155.334249 -438.772691) (xy 155.326783 -438.795657)
			(xy 155.312587 -438.815193) (xy 155.29305 -438.829387) (xy 155.270083 -438.836851) (xy 155.258008 -438.837324)
			(xy 154.318208 -438.837324) (xy 154.306135 -438.836829) (xy 154.283171 -438.829371) (xy 154.263635 -438.815182)
			(xy 154.24944 -438.79565) (xy 154.241975 -438.772688) (xy 154.2415 -438.760616) (xy 154.2415 -438.15)
			(xy 154.239829 -438.135007) (xy 154.238052 -438.104888) (xy 154.237944 -438.089802) (xy 153.33472 -438.089802)
			(xy 153.33472 -439.0898) (xy 156.23794 -439.0898) (xy 156.238057 -439.074715) (xy 156.239833 -439.044596)
			(xy 156.241496 -439.029602) (xy 156.241496 -437.950102) (xy 156.239825 -437.935109) (xy 156.238048 -437.90499)
			(xy 156.23794 -437.889904) (xy 156.238057 -437.874819) (xy 156.239833 -437.8447) (xy 156.241496 -437.829706)
			(xy 156.241496 -437.21909) (xy 156.241998 -437.207004) (xy 156.249452 -437.184011) (xy 156.263631 -437.164435)
			(xy 156.283155 -437.150183) (xy 156.30612 -437.142644) (xy 156.318204 -437.142128) (xy 157.258004 -437.142128)
			(xy 157.270116 -437.142513) (xy 157.293148 -437.150017) (xy 157.312724 -437.164286) (xy 157.326917 -437.183916)
			(xy 157.334333 -437.206977) (xy 157.334712 -437.21909) (xy 157.334712 -438.089802) (xy 314.138056 -438.089802)
			(xy 314.138173 -438.074717) (xy 314.139949 -438.044598) (xy 314.141612 -438.029604) (xy 314.141612 -436.950104)
			(xy 314.139942 -436.935111) (xy 314.138164 -436.904992) (xy 314.138056 -436.889906) (xy 314.138164 -436.87482)
			(xy 314.139946 -436.844702) (xy 314.141612 -436.829708) (xy 314.141612 -436.219092) (xy 314.142006 -436.207007)
			(xy 314.149478 -436.18402) (xy 314.163688 -436.164469) (xy 314.183246 -436.150265) (xy 314.206235 -436.142802)
			(xy 314.21832 -436.142384) (xy 315.15812 -436.142384) (xy 315.170195 -436.142847) (xy 315.193161 -436.150314)
			(xy 315.212697 -436.164511) (xy 315.226891 -436.18405) (xy 315.234355 -436.207017) (xy 315.234828 -436.219092)
			(xy 315.234828 -438.760616) (xy 315.23435 -438.772689) (xy 315.226885 -438.795654) (xy 315.212691 -438.815189)
			(xy 315.193157 -438.829383) (xy 315.170193 -438.836849) (xy 315.15812 -438.837324) (xy 314.21832 -438.837324)
			(xy 314.20624 -438.83687) (xy 314.183261 -438.82941) (xy 314.163711 -438.815214) (xy 314.149506 -438.795672)
			(xy 314.142035 -438.772696) (xy 314.141612 -438.760616) (xy 314.141612 -438.15) (xy 314.139941 -438.135007)
			(xy 314.138164 -438.104888) (xy 314.138056 -438.089802) (xy 157.334712 -438.089802) (xy 157.334712 -439.0898)
			(xy 316.138052 -439.0898) (xy 316.138169 -439.074715) (xy 316.139945 -439.044596) (xy 316.141608 -439.029602)
			(xy 316.141608 -437.950102) (xy 316.139937 -437.935109) (xy 316.13816 -437.90499) (xy 316.138052 -437.889904)
			(xy 316.138169 -437.874819) (xy 316.139945 -437.8447) (xy 316.141608 -437.829706) (xy 316.141608 -437.21909)
			(xy 316.142098 -437.207003) (xy 316.149554 -437.184008) (xy 316.163736 -437.164431) (xy 316.183262 -437.150179)
			(xy 316.206231 -437.142642) (xy 316.218316 -437.142128) (xy 317.158116 -437.142128) (xy 317.170229 -437.142503)
			(xy 317.193261 -437.15001) (xy 317.212836 -437.164281) (xy 317.227029 -437.183914) (xy 317.234445 -437.206976)
			(xy 317.234824 -437.21909) (xy 317.234824 -438.089802) (xy 318.138048 -438.089802) (xy 318.138165 -438.074717)
			(xy 318.139941 -438.044598) (xy 318.141604 -438.029604) (xy 318.141604 -436.950104) (xy 318.139934 -436.935111)
			(xy 318.138156 -436.904992) (xy 318.138048 -436.889906) (xy 318.138156 -436.87482) (xy 318.139938 -436.844702)
			(xy 318.141604 -436.829708) (xy 318.141604 -436.219092) (xy 318.142006 -436.207008) (xy 318.149477 -436.184023)
			(xy 318.163686 -436.164471) (xy 318.183241 -436.150268) (xy 318.206228 -436.142803) (xy 318.218312 -436.142384)
			(xy 319.158112 -436.142384) (xy 319.170186 -436.142854) (xy 319.193153 -436.150319) (xy 319.212689 -436.164514)
			(xy 319.226883 -436.184051) (xy 319.234347 -436.207018) (xy 319.23482 -436.219092) (xy 319.23482 -438.760616)
			(xy 319.234349 -438.77269) (xy 319.226884 -438.795656) (xy 319.212689 -438.815191) (xy 319.193152 -438.829386)
			(xy 319.170186 -438.83685) (xy 319.158112 -438.837324) (xy 318.218312 -438.837324) (xy 318.20624 -438.836826)
			(xy 318.183276 -438.829369) (xy 318.16374 -438.81518) (xy 318.149544 -438.79565) (xy 318.142079 -438.772688)
			(xy 318.141604 -438.760616) (xy 318.141604 -438.15) (xy 318.139933 -438.135007) (xy 318.138156 -438.104888)
			(xy 318.138048 -438.089802) (xy 317.234824 -438.089802) (xy 317.234824 -439.0898) (xy 320.138044 -439.0898)
			(xy 320.138161 -439.074715) (xy 320.139937 -439.044596) (xy 320.1416 -439.029602) (xy 320.1416 -437.950102)
			(xy 320.139929 -437.935109) (xy 320.138152 -437.90499) (xy 320.138044 -437.889904) (xy 320.138161 -437.874819)
			(xy 320.139937 -437.8447) (xy 320.1416 -437.829706) (xy 320.1416 -437.21909) (xy 320.142098 -437.207004)
			(xy 320.149553 -437.18401) (xy 320.163733 -437.164434) (xy 320.183257 -437.150182) (xy 320.206224 -437.142643)
			(xy 320.218308 -437.142128) (xy 321.158108 -437.142128) (xy 321.17022 -437.14251) (xy 321.193252 -437.150015)
			(xy 321.212828 -437.164284) (xy 321.227021 -437.183915) (xy 321.234437 -437.206976) (xy 321.234816 -437.21909)
			(xy 321.234816 -438.089802) (xy 322.13804 -438.089802) (xy 322.138157 -438.074717) (xy 322.139933 -438.044598)
			(xy 322.141596 -438.029604) (xy 322.141596 -436.950104) (xy 322.139926 -436.935111) (xy 322.138148 -436.904992)
			(xy 322.13804 -436.889906) (xy 322.13815 -436.87482) (xy 322.139932 -436.844702) (xy 322.141596 -436.829708)
			(xy 322.141596 -436.219092) (xy 322.142058 -436.207017) (xy 322.149523 -436.184049) (xy 322.16372 -436.164511)
			(xy 322.183259 -436.150317) (xy 322.206229 -436.142856) (xy 322.218304 -436.142384) (xy 323.158104 -436.142384)
			(xy 323.170178 -436.142861) (xy 323.193144 -436.150323) (xy 323.21268 -436.164517) (xy 323.226875 -436.184053)
			(xy 323.234339 -436.207018) (xy 323.234812 -436.219092) (xy 323.234812 -438.760616) (xy 323.234349 -438.772691)
			(xy 323.226883 -438.795658) (xy 323.212686 -438.815194) (xy 323.193147 -438.829388) (xy 323.170179 -438.836851)
			(xy 323.158104 -438.837324) (xy 322.218304 -438.837324) (xy 322.206231 -438.836833) (xy 322.183267 -438.829373)
			(xy 322.163731 -438.815183) (xy 322.149536 -438.795651) (xy 322.142071 -438.772689) (xy 322.141596 -438.760616)
			(xy 322.141596 -438.15) (xy 322.139925 -438.135007) (xy 322.138148 -438.104888) (xy 322.13804 -438.089802)
			(xy 321.234816 -438.089802) (xy 321.234816 -439.0898) (xy 324.138036 -439.0898) (xy 324.138153 -439.074715)
			(xy 324.139929 -439.044596) (xy 324.141592 -439.029602) (xy 324.141592 -437.950102) (xy 324.139921 -437.935109)
			(xy 324.138144 -437.90499) (xy 324.138036 -437.889904) (xy 324.138153 -437.874819) (xy 324.139929 -437.8447)
			(xy 324.141592 -437.829706) (xy 324.141592 -437.21909) (xy 324.142098 -437.207005) (xy 324.149552 -437.184012)
			(xy 324.16373 -437.164436) (xy 324.183252 -437.150184) (xy 324.206217 -437.142644) (xy 324.2183 -437.142128)
			(xy 325.1581 -437.142128) (xy 325.170212 -437.142516) (xy 325.193244 -437.150019) (xy 325.212819 -437.164287)
			(xy 325.227013 -437.183916) (xy 325.234429 -437.206977) (xy 325.234808 -437.21909) (xy 325.234808 -438.089802)
			(xy 326.138032 -438.089802) (xy 326.138151 -438.074717) (xy 326.139927 -438.044598) (xy 326.141588 -438.029604)
			(xy 326.141588 -436.950104) (xy 326.139917 -436.935111) (xy 326.13814 -436.904992) (xy 326.138032 -436.889906)
			(xy 326.138142 -436.87482) (xy 326.139924 -436.844702) (xy 326.141588 -436.829708) (xy 326.141588 -436.219092)
			(xy 326.142057 -436.207017) (xy 326.149522 -436.184051) (xy 326.163717 -436.164514) (xy 326.183254 -436.15032)
			(xy 326.206221 -436.142857) (xy 326.218296 -436.142384) (xy 327.158096 -436.142384) (xy 327.17017 -436.142868)
			(xy 327.193135 -436.150328) (xy 327.212672 -436.16452) (xy 327.226867 -436.184054) (xy 327.234331 -436.207019)
			(xy 327.234804 -436.219092) (xy 327.234804 -438.760616) (xy 327.234349 -438.772692) (xy 327.226882 -438.79566)
			(xy 327.212683 -438.815197) (xy 327.193142 -438.829391) (xy 327.170172 -438.836852) (xy 327.158096 -438.837324)
			(xy 326.218296 -438.837324) (xy 326.206223 -438.836839) (xy 326.183258 -438.829378) (xy 326.163723 -438.815186)
			(xy 326.149528 -438.795652) (xy 326.142063 -438.772689) (xy 326.141588 -438.760616) (xy 326.141588 -438.15)
			(xy 326.139917 -438.135007) (xy 326.13814 -438.104888) (xy 326.138032 -438.089802) (xy 325.234808 -438.089802)
			(xy 325.234808 -439.0898) (xy 328.138028 -439.0898) (xy 328.138147 -439.074715) (xy 328.139923 -439.044596)
			(xy 328.141584 -439.029602) (xy 328.141584 -437.950102) (xy 328.139913 -437.935109) (xy 328.138136 -437.90499)
			(xy 328.138028 -437.889904) (xy 328.138147 -437.874819) (xy 328.139923 -437.8447) (xy 328.141584 -437.829706)
			(xy 328.141584 -437.21909) (xy 328.142 -437.206996) (xy 328.149465 -437.183987) (xy 328.163663 -437.164404)
			(xy 328.18321 -437.150155) (xy 328.206199 -437.142631) (xy 328.218292 -437.142128) (xy 329.158092 -437.142128)
			(xy 329.170203 -437.142523) (xy 329.193235 -437.150024) (xy 329.212811 -437.16429) (xy 329.227005 -437.183918)
			(xy 329.234421 -437.206977) (xy 329.2348 -437.21909) (xy 329.2348 -438.089802) (xy 331.138022 -438.089802)
			(xy 331.138115 -438.075228) (xy 331.139768 -438.046127) (xy 331.141324 -438.031636) (xy 331.141324 -436.948072)
			(xy 331.13978 -436.93358) (xy 331.138127 -436.90448) (xy 331.138022 -436.889906) (xy 331.138115 -436.875332)
			(xy 331.139768 -436.846231) (xy 331.141324 -436.83174) (xy 331.141324 -436.219092) (xy 331.14171 -436.20698)
			(xy 331.149214 -436.183949) (xy 331.163483 -436.164374) (xy 331.183112 -436.15018) (xy 331.206173 -436.142764)
			(xy 331.218286 -436.142384) (xy 332.158086 -436.142384) (xy 332.170179 -436.14282) (xy 332.193187 -436.150278)
			(xy 332.212771 -436.164471) (xy 332.22702 -436.184014) (xy 332.234545 -436.207) (xy 332.235048 -436.219092)
			(xy 332.235048 -438.760616) (xy 332.234598 -438.772721) (xy 332.2271 -438.795741) (xy 332.212845 -438.815309)
			(xy 332.193234 -438.829505) (xy 332.170192 -438.836934) (xy 332.158086 -438.837324) (xy 331.218286 -438.837324)
			(xy 331.206192 -438.836904) (xy 331.183185 -438.829439) (xy 331.163602 -438.815242) (xy 331.149353 -438.795696)
			(xy 331.141828 -438.772709) (xy 331.141324 -438.760616) (xy 331.141324 -438.147968) (xy 331.139779 -438.133476)
			(xy 331.138127 -438.104376) (xy 331.138022 -438.089802) (xy 329.2348 -438.089802) (xy 329.2348 -439.0898)
			(xy 333.138018 -439.0898) (xy 333.138111 -439.075226) (xy 333.139764 -439.046125) (xy 333.14132 -439.031634)
			(xy 333.14132 -437.94807) (xy 333.139775 -437.933578) (xy 333.138123 -437.904478) (xy 333.138018 -437.889904)
			(xy 333.138111 -437.87533) (xy 333.139764 -437.846229) (xy 333.14132 -437.831738) (xy 333.14132 -437.21909)
			(xy 333.141803 -437.206977) (xy 333.149291 -437.183936) (xy 333.163531 -437.164336) (xy 333.183129 -437.150095)
			(xy 333.206169 -437.142604) (xy 333.218282 -437.142128) (xy 334.158082 -437.142128) (xy 334.170203 -437.142575)
			(xy 334.193259 -437.150061) (xy 334.212874 -437.164306) (xy 334.227126 -437.183916) (xy 334.23462 -437.206969)
			(xy 334.235044 -437.21909) (xy 334.235044 -438.089802) (xy 335.138014 -438.089802) (xy 335.138106 -438.075228)
			(xy 335.13976 -438.046127) (xy 335.141316 -438.031636) (xy 335.141316 -436.948072) (xy 335.139772 -436.93358)
			(xy 335.138119 -436.90448) (xy 335.138014 -436.889906) (xy 335.138107 -436.875332) (xy 335.13976 -436.846231)
			(xy 335.141316 -436.83174) (xy 335.141316 -436.219092) (xy 335.14171 -436.206981) (xy 335.149213 -436.183951)
			(xy 335.16348 -436.164376) (xy 335.183107 -436.150183) (xy 335.206166 -436.142765) (xy 335.218278 -436.142384)
			(xy 336.158078 -436.142384) (xy 336.170171 -436.142827) (xy 336.193178 -436.150283) (xy 336.212762 -436.164474)
			(xy 336.227012 -436.184016) (xy 336.234537 -436.207001) (xy 336.23504 -436.219092) (xy 336.23504 -438.760616)
			(xy 336.234598 -438.772722) (xy 336.227099 -438.795743) (xy 336.212843 -438.815312) (xy 336.193229 -438.829508)
			(xy 336.170185 -438.836935) (xy 336.158078 -438.837324) (xy 335.218278 -438.837324) (xy 335.206184 -438.836911)
			(xy 335.183176 -438.829444) (xy 335.163594 -438.815245) (xy 335.149345 -438.795698) (xy 335.14182 -438.772709)
			(xy 335.141316 -438.760616) (xy 335.141316 -438.147968) (xy 335.139771 -438.133476) (xy 335.138119 -438.104376)
			(xy 335.138014 -438.089802) (xy 334.235044 -438.089802) (xy 334.235044 -439.0898) (xy 337.13801 -439.0898)
			(xy 337.138102 -439.075226) (xy 337.139756 -439.046125) (xy 337.141312 -439.031634) (xy 337.141312 -437.94807)
			(xy 337.139767 -437.933578) (xy 337.138115 -437.904478) (xy 337.13801 -437.889904) (xy 337.138103 -437.87533)
			(xy 337.139756 -437.846229) (xy 337.141312 -437.831738) (xy 337.141312 -437.21909) (xy 337.141803 -437.206978)
			(xy 337.14929 -437.183938) (xy 337.163528 -437.164339) (xy 337.183124 -437.150097) (xy 337.206162 -437.142606)
			(xy 337.218274 -437.142128) (xy 338.158074 -437.142128) (xy 338.170194 -437.142582) (xy 338.193251 -437.150066)
			(xy 338.212865 -437.164309) (xy 338.227118 -437.183917) (xy 338.234612 -437.20697) (xy 338.235036 -437.21909)
			(xy 338.235036 -438.089802) (xy 339.138006 -438.089802) (xy 339.138099 -438.075228) (xy 339.139752 -438.046127)
			(xy 339.141308 -438.031636) (xy 339.141308 -436.948072) (xy 339.139763 -436.93358) (xy 339.138111 -436.90448)
			(xy 339.138006 -436.889906) (xy 339.138099 -436.875332) (xy 339.139752 -436.846231) (xy 339.141308 -436.83174)
			(xy 339.141308 -436.219092) (xy 339.141709 -436.206982) (xy 339.149212 -436.183953) (xy 339.163477 -436.164379)
			(xy 339.183102 -436.150185) (xy 339.206158 -436.142766) (xy 339.21827 -436.142384) (xy 340.15807 -436.142384)
			(xy 340.170162 -436.142834) (xy 340.193169 -436.150288) (xy 340.212754 -436.164477) (xy 340.227004 -436.184017)
			(xy 340.234529 -436.207001) (xy 340.235032 -436.219092) (xy 340.235032 -438.760616) (xy 340.234598 -438.772723)
			(xy 340.227098 -438.795745) (xy 340.21284 -438.815315) (xy 340.193224 -438.82951) (xy 340.170178 -438.836936)
			(xy 340.15807 -438.837324) (xy 339.21827 -438.837324) (xy 339.206175 -438.836918) (xy 339.183168 -438.829448)
			(xy 339.163585 -438.815247) (xy 339.149337 -438.795699) (xy 339.141812 -438.77271) (xy 339.141308 -438.760616)
			(xy 339.141308 -438.147968) (xy 339.139763 -438.133476) (xy 339.138111 -438.104376) (xy 339.138006 -438.089802)
			(xy 338.235036 -438.089802) (xy 338.235036 -439.0898) (xy 341.138002 -439.0898) (xy 341.138094 -439.075226)
			(xy 341.139748 -439.046125) (xy 341.141304 -439.031634) (xy 341.141304 -437.94807) (xy 341.139759 -437.933578)
			(xy 341.138107 -437.904478) (xy 341.138002 -437.889904) (xy 341.138095 -437.87533) (xy 341.139748 -437.846229)
			(xy 341.141304 -437.831738) (xy 341.141304 -437.21909) (xy 341.141803 -437.206978) (xy 341.149289 -437.183941)
			(xy 341.163525 -437.164342) (xy 341.183119 -437.1501) (xy 341.206154 -437.142607) (xy 341.218266 -437.142128)
			(xy 342.158066 -437.142128) (xy 342.170186 -437.142589) (xy 342.193242 -437.15007) (xy 342.212857 -437.164312)
			(xy 342.22711 -437.183918) (xy 342.234604 -437.20697) (xy 342.235028 -437.21909) (xy 342.235028 -438.089802)
			(xy 343.137998 -438.089802) (xy 343.138091 -438.075228) (xy 343.139744 -438.046127) (xy 343.1413 -438.031636)
			(xy 343.1413 -436.948072) (xy 343.139755 -436.93358) (xy 343.138103 -436.90448) (xy 343.137998 -436.889906)
			(xy 343.138091 -436.875332) (xy 343.139744 -436.846231) (xy 343.1413 -436.83174) (xy 343.1413 -436.219092)
			(xy 343.141709 -436.206983) (xy 343.149211 -436.183955) (xy 343.163474 -436.164382) (xy 343.183097 -436.150188)
			(xy 343.206151 -436.142767) (xy 343.218262 -436.142384) (xy 344.158062 -436.142384) (xy 344.170154 -436.142841)
			(xy 344.193161 -436.150292) (xy 344.212745 -436.16448) (xy 344.226995 -436.184019) (xy 344.234521 -436.207002)
			(xy 344.235024 -436.219092) (xy 344.235024 -438.760616) (xy 344.234598 -438.772723) (xy 344.227097 -438.795747)
			(xy 344.212837 -438.815318) (xy 344.193219 -438.829513) (xy 344.170171 -438.836937) (xy 344.158062 -438.837324)
			(xy 343.218262 -438.837324) (xy 343.206167 -438.836924) (xy 343.183159 -438.829453) (xy 343.163577 -438.81525)
			(xy 343.149329 -438.795701) (xy 343.141804 -438.77271) (xy 343.1413 -438.760616) (xy 343.1413 -438.147968)
			(xy 343.139755 -438.133476) (xy 343.138103 -438.104376) (xy 343.137998 -438.089802) (xy 342.235028 -438.089802)
			(xy 342.235028 -439.0898) (xy 345.137994 -439.0898) (xy 345.138086 -439.075226) (xy 345.13974 -439.046125)
			(xy 345.141296 -439.031634) (xy 345.141296 -437.94807) (xy 345.139752 -437.933578) (xy 345.138099 -437.904478)
			(xy 345.137994 -437.889904) (xy 345.138087 -437.87533) (xy 345.13974 -437.846229) (xy 345.141296 -437.831738)
			(xy 345.141296 -437.21909) (xy 345.141803 -437.206979) (xy 345.149288 -437.183943) (xy 345.163522 -437.164345)
			(xy 345.183114 -437.150102) (xy 345.206147 -437.142608) (xy 345.218258 -437.142128) (xy 346.158058 -437.142128)
			(xy 346.170178 -437.142595) (xy 346.193233 -437.150075) (xy 346.212848 -437.164315) (xy 346.227101 -437.18392)
			(xy 346.234596 -437.206971) (xy 346.23502 -437.21909) (xy 346.23502 -439.0898) (xy 383.237994 -439.0898)
			(xy 383.238086 -439.075226) (xy 383.23974 -439.046125) (xy 383.241296 -439.031634) (xy 383.241296 -437.94807)
			(xy 383.239752 -437.933578) (xy 383.238099 -437.904478) (xy 383.237994 -437.889904) (xy 383.238087 -437.87533)
			(xy 383.23974 -437.846229) (xy 383.241296 -437.831738) (xy 383.241296 -437.21909) (xy 383.241803 -437.206979)
			(xy 383.249288 -437.183943) (xy 383.263522 -437.164345) (xy 383.283114 -437.150102) (xy 383.306147 -437.142608)
			(xy 383.318258 -437.142128) (xy 384.258058 -437.142128) (xy 384.270178 -437.142595) (xy 384.293233 -437.150075)
			(xy 384.312848 -437.164315) (xy 384.327101 -437.18392) (xy 384.334596 -437.206971) (xy 384.33502 -437.21909)
			(xy 384.33502 -438.089802) (xy 385.23799 -438.089802) (xy 385.238083 -438.075228) (xy 385.239736 -438.046127)
			(xy 385.241292 -438.031636) (xy 385.241292 -436.948072) (xy 385.239748 -436.93358) (xy 385.238095 -436.90448)
			(xy 385.23799 -436.889906) (xy 385.238083 -436.875332) (xy 385.239736 -436.846231) (xy 385.241292 -436.83174)
			(xy 385.241292 -436.219092) (xy 385.241709 -436.206983) (xy 385.24921 -436.183957) (xy 385.263472 -436.164385)
			(xy 385.283092 -436.15019) (xy 385.306144 -436.142768) (xy 385.318254 -436.142384) (xy 386.258054 -436.142384)
			(xy 386.270146 -436.142847) (xy 386.293152 -436.150297) (xy 386.312737 -436.164483) (xy 386.326987 -436.18402)
			(xy 386.334512 -436.207002) (xy 386.335016 -436.219092) (xy 386.335016 -438.760616) (xy 386.334598 -438.772724)
			(xy 386.327096 -438.795749) (xy 386.312834 -438.815321) (xy 386.293214 -438.829515) (xy 386.270163 -438.836939)
			(xy 386.258054 -438.837324) (xy 385.318254 -438.837324) (xy 385.306158 -438.836931) (xy 385.28315 -438.829457)
			(xy 385.263568 -438.815253) (xy 385.24932 -438.795702) (xy 385.241796 -438.77271) (xy 385.241292 -438.760616)
			(xy 385.241292 -438.147968) (xy 385.239747 -438.133476) (xy 385.238095 -438.104376) (xy 385.23799 -438.089802)
			(xy 384.33502 -438.089802) (xy 384.33502 -439.0898) (xy 387.237986 -439.0898) (xy 387.238078 -439.075226)
			(xy 387.239732 -439.046125) (xy 387.241288 -439.031634) (xy 387.241288 -437.94807) (xy 387.239744 -437.933578)
			(xy 387.238091 -437.904478) (xy 387.237986 -437.889904) (xy 387.238079 -437.87533) (xy 387.239732 -437.846229)
			(xy 387.241288 -437.831738) (xy 387.241288 -437.21909) (xy 387.241803 -437.20698) (xy 387.249287 -437.183945)
			(xy 387.263519 -437.164348) (xy 387.283109 -437.150105) (xy 387.30614 -437.142609) (xy 387.31825 -437.142128)
			(xy 388.25805 -437.142128) (xy 388.270166 -437.142569) (xy 388.293209 -437.150069) (xy 388.312809 -437.164319)
			(xy 388.32705 -437.183927) (xy 388.334537 -437.206974) (xy 388.335012 -437.21909) (xy 388.335012 -438.089802)
			(xy 389.237982 -438.089802) (xy 389.238075 -438.075228) (xy 389.239728 -438.046127) (xy 389.241284 -438.031636)
			(xy 389.241284 -436.948072) (xy 389.23974 -436.93358) (xy 389.238087 -436.90448) (xy 389.237982 -436.889906)
			(xy 389.238075 -436.875332) (xy 389.239728 -436.846231) (xy 389.241284 -436.83174) (xy 389.241284 -436.219092)
			(xy 389.241709 -436.206984) (xy 389.249209 -436.183959) (xy 389.263469 -436.164388) (xy 389.283087 -436.150193)
			(xy 389.306137 -436.142769) (xy 389.318246 -436.142384) (xy 390.258046 -436.142384) (xy 390.270142 -436.142769)
			(xy 390.293152 -436.150244) (xy 390.312735 -436.16445) (xy 390.326982 -436.184003) (xy 390.334505 -436.206997)
			(xy 390.335008 -436.219092) (xy 390.335008 -438.760616) (xy 390.334598 -438.772725) (xy 390.327095 -438.795751)
			(xy 390.312831 -438.815324) (xy 390.293209 -438.829518) (xy 390.270156 -438.83694) (xy 390.258046 -438.837324)
			(xy 389.318246 -438.837324) (xy 389.306155 -438.836853) (xy 389.28315 -438.829404) (xy 389.263566 -438.81522)
			(xy 389.249315 -438.795685) (xy 389.241789 -438.772705) (xy 389.241284 -438.760616) (xy 389.241284 -438.147968)
			(xy 389.239739 -438.133476) (xy 389.238087 -438.104376) (xy 389.237982 -438.089802) (xy 388.335012 -438.089802)
			(xy 388.335012 -439.0898) (xy 391.237978 -439.0898) (xy 391.238071 -439.075226) (xy 391.239724 -439.046125)
			(xy 391.24128 -439.031634) (xy 391.24128 -437.94807) (xy 391.239736 -437.933578) (xy 391.238083 -437.904478)
			(xy 391.237978 -437.889904) (xy 391.238071 -437.87533) (xy 391.239724 -437.846229) (xy 391.24128 -437.831738)
			(xy 391.24128 -437.21909) (xy 391.241652 -437.206963) (xy 391.249152 -437.183896) (xy 391.263415 -437.164278)
			(xy 391.283043 -437.150029) (xy 391.306114 -437.142544) (xy 391.318242 -437.142128) (xy 392.258042 -437.142128)
			(xy 392.270158 -437.142576) (xy 392.293201 -437.150073) (xy 392.312801 -437.164322) (xy 392.327041 -437.183928)
			(xy 392.334529 -437.206974) (xy 392.335004 -437.21909) (xy 392.335004 -438.089802) (xy 393.237974 -438.089802)
			(xy 393.238067 -438.075228) (xy 393.23972 -438.046127) (xy 393.241276 -438.031636) (xy 393.241276 -436.948072)
			(xy 393.239732 -436.93358) (xy 393.238079 -436.90448) (xy 393.237974 -436.889906) (xy 393.238067 -436.875332)
			(xy 393.23972 -436.846231) (xy 393.241276 -436.83174) (xy 393.241276 -436.219092) (xy 393.241709 -436.206985)
			(xy 393.249208 -436.183962) (xy 393.263466 -436.164391) (xy 393.283082 -436.150195) (xy 393.30613 -436.142771)
			(xy 393.318238 -436.142384) (xy 394.258038 -436.142384) (xy 394.270134 -436.142776) (xy 394.293143 -436.150248)
			(xy 394.312726 -436.164453) (xy 394.326974 -436.184004) (xy 394.334497 -436.206997) (xy 394.335 -436.219092)
			(xy 394.335 -438.760616) (xy 394.334597 -438.772726) (xy 394.327094 -438.795754) (xy 394.312828 -438.815326)
			(xy 394.293204 -438.82952) (xy 394.270149 -438.836941) (xy 394.258038 -438.837324) (xy 393.318238 -438.837324)
			(xy 393.306147 -438.83686) (xy 393.283141 -438.829409) (xy 393.263558 -438.815223) (xy 393.249307 -438.795686)
			(xy 393.241781 -438.772706) (xy 393.241276 -438.760616) (xy 393.241276 -438.147968) (xy 393.239731 -438.133476)
			(xy 393.238079 -438.104376) (xy 393.237974 -438.089802) (xy 392.335004 -438.089802) (xy 392.335004 -439.0898)
			(xy 395.23797 -439.0898) (xy 395.238063 -439.075226) (xy 395.239716 -439.046125) (xy 395.241272 -439.031634)
			(xy 395.241272 -437.94807) (xy 395.239728 -437.933578) (xy 395.238075 -437.904478) (xy 395.23797 -437.889904)
			(xy 395.238063 -437.87533) (xy 395.239716 -437.846229) (xy 395.241272 -437.831738) (xy 395.241272 -437.21909)
			(xy 395.241652 -437.206963) (xy 395.249151 -437.183898) (xy 395.263412 -437.164281) (xy 395.283038 -437.150031)
			(xy 395.306107 -437.142545) (xy 395.318234 -437.142128) (xy 396.258034 -437.142128) (xy 396.270149 -437.142583)
			(xy 396.293192 -437.150078) (xy 396.312792 -437.164325) (xy 396.327033 -437.18393) (xy 396.334521 -437.206975)
			(xy 396.334996 -437.21909) (xy 396.334996 -438.089802) (xy 398.237964 -438.089802) (xy 398.238081 -438.074717)
			(xy 398.239857 -438.044598) (xy 398.24152 -438.029604) (xy 398.24152 -436.950104) (xy 398.23985 -436.935111)
			(xy 398.238072 -436.904992) (xy 398.237964 -436.889906) (xy 398.238072 -436.87482) (xy 398.239854 -436.844702)
			(xy 398.24152 -436.829708) (xy 398.24152 -436.219092) (xy 398.241906 -436.207006) (xy 398.249379 -436.184018)
			(xy 398.263591 -436.164466) (xy 398.283151 -436.150263) (xy 398.306142 -436.1428) (xy 398.318228 -436.142384)
			(xy 399.258028 -436.142384) (xy 399.270103 -436.14284) (xy 399.29307 -436.150309) (xy 399.312606 -436.164508)
			(xy 399.3268 -436.184048) (xy 399.334263 -436.207017) (xy 399.334736 -436.219092) (xy 399.334736 -438.760616)
			(xy 399.33425 -438.772689) (xy 399.326786 -438.795651) (xy 399.312594 -438.815186) (xy 399.293062 -438.829381)
			(xy 399.270101 -438.836848) (xy 399.258028 -438.837324) (xy 398.318228 -438.837324) (xy 398.306148 -438.836864)
			(xy 398.283169 -438.829406) (xy 398.26362 -438.815211) (xy 398.249414 -438.79567) (xy 398.241943 -438.772695)
			(xy 398.24152 -438.760616) (xy 398.24152 -438.15) (xy 398.239849 -438.135007) (xy 398.238072 -438.104888)
			(xy 398.237964 -438.089802) (xy 396.334996 -438.089802) (xy 396.334996 -439.0898) (xy 400.23796 -439.0898)
			(xy 400.238077 -439.074715) (xy 400.239853 -439.044596) (xy 400.241516 -439.029602) (xy 400.241516 -437.950102)
			(xy 400.239845 -437.935109) (xy 400.238068 -437.90499) (xy 400.23796 -437.889904) (xy 400.238077 -437.874819)
			(xy 400.239853 -437.8447) (xy 400.241516 -437.829706) (xy 400.241516 -437.21909) (xy 400.241999 -437.207002)
			(xy 400.249455 -437.184006) (xy 400.263639 -437.164428) (xy 400.283167 -437.150177) (xy 400.306138 -437.142641)
			(xy 400.318224 -437.142128) (xy 401.258024 -437.142128) (xy 401.270137 -437.142496) (xy 401.29317 -437.150006)
			(xy 401.312745 -437.164279) (xy 401.326938 -437.183912) (xy 401.334353 -437.206975) (xy 401.334732 -437.21909)
			(xy 401.334732 -438.089802) (xy 402.237956 -438.089802) (xy 402.238073 -438.074717) (xy 402.239849 -438.044598)
			(xy 402.241512 -438.029604) (xy 402.241512 -436.950104) (xy 402.239842 -436.935111) (xy 402.238064 -436.904992)
			(xy 402.237956 -436.889906) (xy 402.238064 -436.87482) (xy 402.239846 -436.844702) (xy 402.241512 -436.829708)
			(xy 402.241512 -436.219092) (xy 402.241906 -436.207007) (xy 402.249378 -436.18402) (xy 402.263588 -436.164469)
			(xy 402.283146 -436.150265) (xy 402.306135 -436.142802) (xy 402.31822 -436.142384) (xy 403.25802 -436.142384)
			(xy 403.270095 -436.142847) (xy 403.293061 -436.150314) (xy 403.312597 -436.164511) (xy 403.326791 -436.18405)
			(xy 403.334255 -436.207017) (xy 403.334728 -436.219092) (xy 403.334728 -438.760616) (xy 403.33425 -438.772689)
			(xy 403.326785 -438.795654) (xy 403.312591 -438.815189) (xy 403.293057 -438.829383) (xy 403.270093 -438.836849)
			(xy 403.25802 -438.837324) (xy 402.31822 -438.837324) (xy 402.30614 -438.83687) (xy 402.283161 -438.82941)
			(xy 402.263611 -438.815214) (xy 402.249406 -438.795672) (xy 402.241935 -438.772696) (xy 402.241512 -438.760616)
			(xy 402.241512 -438.15) (xy 402.239841 -438.135007) (xy 402.238064 -438.104888) (xy 402.237956 -438.089802)
			(xy 401.334732 -438.089802) (xy 401.334732 -439.0898) (xy 404.237952 -439.0898) (xy 404.238069 -439.074715)
			(xy 404.239845 -439.044596) (xy 404.241508 -439.029602) (xy 404.241508 -437.950102) (xy 404.239837 -437.935109)
			(xy 404.23806 -437.90499) (xy 404.237952 -437.889904) (xy 404.238069 -437.874819) (xy 404.239845 -437.8447)
			(xy 404.241508 -437.829706) (xy 404.241508 -437.21909) (xy 404.241998 -437.207003) (xy 404.249454 -437.184008)
			(xy 404.263636 -437.164431) (xy 404.283162 -437.150179) (xy 404.306131 -437.142642) (xy 404.318216 -437.142128)
			(xy 405.258016 -437.142128) (xy 405.270129 -437.142503) (xy 405.293161 -437.15001) (xy 405.312736 -437.164281)
			(xy 405.326929 -437.183914) (xy 405.334345 -437.206976) (xy 405.334724 -437.21909) (xy 405.334724 -438.089802)
			(xy 406.237948 -438.089802) (xy 406.238065 -438.074717) (xy 406.239841 -438.044598) (xy 406.241504 -438.029604)
			(xy 406.241504 -436.950104) (xy 406.239834 -436.935111) (xy 406.238056 -436.904992) (xy 406.237948 -436.889906)
			(xy 406.238056 -436.87482) (xy 406.239838 -436.844702) (xy 406.241504 -436.829708) (xy 406.241504 -436.219092)
			(xy 406.241906 -436.207008) (xy 406.249377 -436.184023) (xy 406.263586 -436.164471) (xy 406.283141 -436.150268)
			(xy 406.306128 -436.142803) (xy 406.318212 -436.142384) (xy 407.258012 -436.142384) (xy 407.270086 -436.142854)
			(xy 407.293053 -436.150319) (xy 407.312589 -436.164514) (xy 407.326783 -436.184051) (xy 407.334247 -436.207018)
			(xy 407.33472 -436.219092) (xy 407.33472 -438.760616) (xy 407.334249 -438.77269) (xy 407.326784 -438.795656)
			(xy 407.312589 -438.815191) (xy 407.293052 -438.829386) (xy 407.270086 -438.83685) (xy 407.258012 -438.837324)
			(xy 406.318212 -438.837324) (xy 406.30614 -438.836826) (xy 406.283176 -438.829369) (xy 406.26364 -438.81518)
			(xy 406.249444 -438.79565) (xy 406.241979 -438.772688) (xy 406.241504 -438.760616) (xy 406.241504 -438.15)
			(xy 406.239833 -438.135007) (xy 406.238056 -438.104888) (xy 406.237948 -438.089802) (xy 405.334724 -438.089802)
			(xy 405.334724 -439.0898) (xy 408.237944 -439.0898) (xy 408.238061 -439.074715) (xy 408.239837 -439.044596)
			(xy 408.2415 -439.029602) (xy 408.2415 -437.950102) (xy 408.239829 -437.935109) (xy 408.238052 -437.90499)
			(xy 408.237944 -437.889904) (xy 408.238061 -437.874819) (xy 408.239837 -437.8447) (xy 408.2415 -437.829706)
			(xy 408.2415 -437.21909) (xy 408.241998 -437.207004) (xy 408.249453 -437.18401) (xy 408.263633 -437.164434)
			(xy 408.283157 -437.150182) (xy 408.306124 -437.142643) (xy 408.318208 -437.142128) (xy 409.258008 -437.142128)
			(xy 409.27012 -437.14251) (xy 409.293152 -437.150015) (xy 409.312728 -437.164284) (xy 409.326921 -437.183915)
			(xy 409.334337 -437.206976) (xy 409.334716 -437.21909) (xy 409.334716 -438.089802) (xy 410.23794 -438.089802)
			(xy 410.238057 -438.074717) (xy 410.239833 -438.044598) (xy 410.241496 -438.029604) (xy 410.241496 -436.950104)
			(xy 410.239826 -436.935111) (xy 410.238048 -436.904992) (xy 410.23794 -436.889906) (xy 410.23805 -436.87482)
			(xy 410.239832 -436.844702) (xy 410.241496 -436.829708) (xy 410.241496 -436.219092) (xy 410.241958 -436.207017)
			(xy 410.249423 -436.184049) (xy 410.26362 -436.164511) (xy 410.283159 -436.150317) (xy 410.306129 -436.142856)
			(xy 410.318204 -436.142384) (xy 411.258004 -436.142384) (xy 411.270078 -436.142861) (xy 411.293044 -436.150323)
			(xy 411.31258 -436.164517) (xy 411.326775 -436.184053) (xy 411.334239 -436.207018) (xy 411.334712 -436.219092)
			(xy 411.334712 -438.760616) (xy 411.334249 -438.772691) (xy 411.326783 -438.795658) (xy 411.312586 -438.815194)
			(xy 411.293047 -438.829388) (xy 411.270079 -438.836851) (xy 411.258004 -438.837324) (xy 410.318204 -438.837324)
			(xy 410.306131 -438.836833) (xy 410.283167 -438.829373) (xy 410.263631 -438.815183) (xy 410.249436 -438.795651)
			(xy 410.241971 -438.772689) (xy 410.241496 -438.760616) (xy 410.241496 -438.15) (xy 410.239825 -438.135007)
			(xy 410.238048 -438.104888) (xy 410.23794 -438.089802) (xy 409.334716 -438.089802) (xy 409.334716 -439.0898)
			(xy 412.237936 -439.0898) (xy 412.238053 -439.074715) (xy 412.239829 -439.044596) (xy 412.241492 -439.029602)
			(xy 412.241492 -437.950102) (xy 412.239821 -437.935109) (xy 412.238044 -437.90499) (xy 412.237936 -437.889904)
			(xy 412.238053 -437.874819) (xy 412.239829 -437.8447) (xy 412.241492 -437.829706) (xy 412.241492 -437.21909)
			(xy 412.241998 -437.207005) (xy 412.249452 -437.184012) (xy 412.26363 -437.164436) (xy 412.283152 -437.150184)
			(xy 412.306117 -437.142644) (xy 412.3182 -437.142128) (xy 413.258 -437.142128) (xy 413.270112 -437.142516)
			(xy 413.293144 -437.150019) (xy 413.312719 -437.164287) (xy 413.326913 -437.183916) (xy 413.334329 -437.206977)
			(xy 413.334708 -437.21909) (xy 413.334708 -439.760614) (xy 413.334206 -439.7727) (xy 413.326751 -439.795693)
			(xy 413.312572 -439.815268) (xy 413.293049 -439.82952) (xy 413.270084 -439.83706) (xy 413.258 -439.837576)
			(xy 412.3182 -439.837576) (xy 412.306089 -439.837184) (xy 412.283057 -439.829681) (xy 412.263482 -439.815414)
			(xy 412.249288 -439.795786) (xy 412.241872 -439.772727) (xy 412.241492 -439.760614) (xy 412.241492 -439.149998)
			(xy 412.239821 -439.135005) (xy 412.238044 -439.104886) (xy 412.237936 -439.0898) (xy 409.334716 -439.0898)
			(xy 409.334716 -439.760614) (xy 409.334304 -439.772709) (xy 409.326838 -439.795717) (xy 409.312639 -439.815301)
			(xy 409.293091 -439.829549) (xy 409.270101 -439.837073) (xy 409.258008 -439.837576) (xy 408.318208 -439.837576)
			(xy 408.306097 -439.837177) (xy 408.283066 -439.829677) (xy 408.263491 -439.815412) (xy 408.249296 -439.795785)
			(xy 408.24188 -439.772726) (xy 408.2415 -439.760614) (xy 408.2415 -439.149998) (xy 408.239829 -439.135005)
			(xy 408.238052 -439.104886) (xy 408.237944 -439.0898) (xy 405.334724 -439.0898) (xy 405.334724 -439.760614)
			(xy 405.334304 -439.772708) (xy 405.326839 -439.795715) (xy 405.312642 -439.815298) (xy 405.293096 -439.829547)
			(xy 405.270109 -439.837072) (xy 405.258016 -439.837576) (xy 404.318216 -439.837576) (xy 404.306106 -439.83717)
			(xy 404.283075 -439.829672) (xy 404.263499 -439.815408) (xy 404.249305 -439.795783) (xy 404.241888 -439.772726)
			(xy 404.241508 -439.760614) (xy 404.241508 -439.149998) (xy 404.239837 -439.135005) (xy 404.23806 -439.104886)
			(xy 404.237952 -439.0898) (xy 401.334732 -439.0898) (xy 401.334732 -439.760614) (xy 401.334304 -439.772707)
			(xy 401.32684 -439.795713) (xy 401.312645 -439.815295) (xy 401.293101 -439.829544) (xy 401.270116 -439.837071)
			(xy 401.258024 -439.837576) (xy 400.318224 -439.837576) (xy 400.306114 -439.837163) (xy 400.283083 -439.829667)
			(xy 400.263508 -439.815406) (xy 400.249313 -439.795781) (xy 400.241896 -439.772725) (xy 400.241516 -439.760614)
			(xy 400.241516 -439.149998) (xy 400.239845 -439.135005) (xy 400.238068 -439.104886) (xy 400.23796 -439.0898)
			(xy 396.334996 -439.0898) (xy 396.334996 -439.760614) (xy 396.334501 -439.772726) (xy 396.327014 -439.795764)
			(xy 396.312777 -439.815363) (xy 396.293182 -439.829605) (xy 396.270146 -439.837098) (xy 396.258034 -439.837576)
			(xy 395.318234 -439.837576) (xy 395.306114 -439.837111) (xy 395.283059 -439.82963) (xy 395.263445 -439.81539)
			(xy 395.249192 -439.795784) (xy 395.241696 -439.772733) (xy 395.241272 -439.760614) (xy 395.241272 -439.147966)
			(xy 395.239727 -439.133474) (xy 395.238075 -439.104374) (xy 395.23797 -439.0898) (xy 392.335004 -439.0898)
			(xy 392.335004 -439.760614) (xy 392.334501 -439.772725) (xy 392.327015 -439.795762) (xy 392.31278 -439.81536)
			(xy 392.293187 -439.829602) (xy 392.270153 -439.837097) (xy 392.258042 -439.837576) (xy 391.318242 -439.837576)
			(xy 391.306123 -439.837105) (xy 391.283068 -439.829626) (xy 391.263453 -439.815387) (xy 391.2492 -439.795783)
			(xy 391.241704 -439.772733) (xy 391.24128 -439.760614) (xy 391.24128 -439.147966) (xy 391.239735 -439.133474)
			(xy 391.238083 -439.104374) (xy 391.237978 -439.0898) (xy 388.335012 -439.0898) (xy 388.335012 -439.760614)
			(xy 388.334501 -439.772724) (xy 388.327016 -439.79576) (xy 388.312782 -439.815357) (xy 388.293192 -439.8296)
			(xy 388.27016 -439.837096) (xy 388.25805 -439.837576) (xy 387.31825 -439.837576) (xy 387.306134 -439.837131)
			(xy 387.283092 -439.829632) (xy 387.263492 -439.815382) (xy 387.249252 -439.795776) (xy 387.241763 -439.77273)
			(xy 387.241288 -439.760614) (xy 387.241288 -439.147966) (xy 387.239743 -439.133474) (xy 387.238091 -439.104374)
			(xy 387.237986 -439.0898) (xy 384.33502 -439.0898) (xy 384.33502 -439.760614) (xy 384.334651 -439.772742)
			(xy 384.32715 -439.795808) (xy 384.312886 -439.815426) (xy 384.293258 -439.829675) (xy 384.270186 -439.83716)
			(xy 384.258058 -439.837576) (xy 383.318258 -439.837576) (xy 383.306143 -439.837124) (xy 383.2831 -439.829627)
			(xy 383.263501 -439.815379) (xy 383.24926 -439.795774) (xy 383.241771 -439.77273) (xy 383.241296 -439.760614)
			(xy 383.241296 -439.147966) (xy 383.239751 -439.133474) (xy 383.238099 -439.104374) (xy 383.237994 -439.0898)
			(xy 346.23502 -439.0898) (xy 346.23502 -439.760614) (xy 346.234651 -439.772742) (xy 346.22715 -439.795808)
			(xy 346.212886 -439.815426) (xy 346.193258 -439.829675) (xy 346.170186 -439.83716) (xy 346.158058 -439.837576)
			(xy 345.218258 -439.837576) (xy 345.206143 -439.837124) (xy 345.1831 -439.829627) (xy 345.163501 -439.815379)
			(xy 345.14926 -439.795774) (xy 345.141771 -439.77273) (xy 345.141296 -439.760614) (xy 345.141296 -439.147966)
			(xy 345.139751 -439.133474) (xy 345.138099 -439.104374) (xy 345.137994 -439.0898) (xy 342.235028 -439.0898)
			(xy 342.235028 -439.760614) (xy 342.234651 -439.772741) (xy 342.227151 -439.795806) (xy 342.212889 -439.815424)
			(xy 342.193263 -439.829673) (xy 342.170193 -439.837159) (xy 342.158066 -439.837576) (xy 341.218266 -439.837576)
			(xy 341.206151 -439.837118) (xy 341.183109 -439.829623) (xy 341.163509 -439.815377) (xy 341.149268 -439.795773)
			(xy 341.141779 -439.772729) (xy 341.141304 -439.760614) (xy 341.141304 -439.147966) (xy 341.139759 -439.133474)
			(xy 341.138107 -439.104374) (xy 341.138002 -439.0898) (xy 338.235036 -439.0898) (xy 338.235036 -439.760614)
			(xy 338.234651 -439.77274) (xy 338.227152 -439.795804) (xy 338.212892 -439.815421) (xy 338.193268 -439.82967)
			(xy 338.1702 -439.837158) (xy 338.158074 -439.837576) (xy 337.218274 -439.837576) (xy 337.206159 -439.837111)
			(xy 337.183118 -439.829618) (xy 337.163518 -439.815374) (xy 337.149276 -439.795772) (xy 337.141787 -439.772729)
			(xy 337.141312 -439.760614) (xy 337.141312 -439.147966) (xy 337.139767 -439.133474) (xy 337.138115 -439.104374)
			(xy 337.13801 -439.0898) (xy 334.235044 -439.0898) (xy 334.235044 -439.760614) (xy 334.234651 -439.772739)
			(xy 334.227153 -439.795802) (xy 334.212895 -439.815418) (xy 334.193273 -439.829668) (xy 334.170207 -439.837157)
			(xy 334.158082 -439.837576) (xy 333.218282 -439.837576) (xy 333.206168 -439.837104) (xy 333.183126 -439.829614)
			(xy 333.163526 -439.815371) (xy 333.149285 -439.79577) (xy 333.141795 -439.772728) (xy 333.14132 -439.760614)
			(xy 333.14132 -439.147966) (xy 333.139775 -439.133474) (xy 333.138123 -439.104374) (xy 333.138018 -439.0898)
			(xy 329.2348 -439.0898) (xy 329.2348 -439.760614) (xy 329.234306 -439.7727) (xy 329.22685 -439.795695)
			(xy 329.212669 -439.815271) (xy 329.193144 -439.829523) (xy 329.170177 -439.837061) (xy 329.158092 -439.837576)
			(xy 328.218292 -439.837576) (xy 328.20618 -439.83719) (xy 328.183149 -439.829686) (xy 328.163574 -439.815417)
			(xy 328.14938 -439.795788) (xy 328.141964 -439.772727) (xy 328.141584 -439.760614) (xy 328.141584 -439.149998)
			(xy 328.139913 -439.135005) (xy 328.138136 -439.104886) (xy 328.138028 -439.0898) (xy 325.234808 -439.0898)
			(xy 325.234808 -439.760614) (xy 325.234306 -439.7727) (xy 325.226851 -439.795693) (xy 325.212672 -439.815268)
			(xy 325.193149 -439.82952) (xy 325.170184 -439.83706) (xy 325.1581 -439.837576) (xy 324.2183 -439.837576)
			(xy 324.206189 -439.837184) (xy 324.183157 -439.829681) (xy 324.163582 -439.815414) (xy 324.149388 -439.795786)
			(xy 324.141972 -439.772727) (xy 324.141592 -439.760614) (xy 324.141592 -439.149998) (xy 324.139921 -439.135005)
			(xy 324.138144 -439.104886) (xy 324.138036 -439.0898) (xy 321.234816 -439.0898) (xy 321.234816 -439.760614)
			(xy 321.234404 -439.772709) (xy 321.226938 -439.795717) (xy 321.212739 -439.815301) (xy 321.193191 -439.829549)
			(xy 321.170201 -439.837073) (xy 321.158108 -439.837576) (xy 320.218308 -439.837576) (xy 320.206197 -439.837177)
			(xy 320.183166 -439.829677) (xy 320.163591 -439.815412) (xy 320.149396 -439.795785) (xy 320.14198 -439.772726)
			(xy 320.1416 -439.760614) (xy 320.1416 -439.149998) (xy 320.139929 -439.135005) (xy 320.138152 -439.104886)
			(xy 320.138044 -439.0898) (xy 317.234824 -439.0898) (xy 317.234824 -439.760614) (xy 317.234404 -439.772708)
			(xy 317.226939 -439.795715) (xy 317.212742 -439.815298) (xy 317.193196 -439.829547) (xy 317.170209 -439.837072)
			(xy 317.158116 -439.837576) (xy 316.218316 -439.837576) (xy 316.206206 -439.83717) (xy 316.183175 -439.829672)
			(xy 316.163599 -439.815408) (xy 316.149405 -439.795783) (xy 316.141988 -439.772726) (xy 316.141608 -439.760614)
			(xy 316.141608 -439.149998) (xy 316.139937 -439.135005) (xy 316.13816 -439.104886) (xy 316.138052 -439.0898)
			(xy 157.334712 -439.0898) (xy 157.334712 -439.760614) (xy 157.334304 -439.772709) (xy 157.326838 -439.795718)
			(xy 157.312637 -439.815302) (xy 157.293089 -439.829551) (xy 157.270098 -439.837074) (xy 157.258004 -439.837576)
			(xy 156.318204 -439.837576) (xy 156.306093 -439.83718) (xy 156.283062 -439.829679) (xy 156.263486 -439.815413)
			(xy 156.249292 -439.795785) (xy 156.241876 -439.772727) (xy 156.241496 -439.760614) (xy 156.241496 -439.149998)
			(xy 156.239825 -439.135005) (xy 156.238048 -439.104886) (xy 156.23794 -439.0898) (xy 153.33472 -439.0898)
			(xy 153.33472 -439.760614) (xy 153.334304 -439.772708) (xy 153.326839 -439.795716) (xy 153.31264 -439.815299)
			(xy 153.293094 -439.829548) (xy 153.270105 -439.837073) (xy 153.258012 -439.837576) (xy 152.318212 -439.837576)
			(xy 152.306101 -439.837173) (xy 152.28307 -439.829674) (xy 152.263495 -439.81541) (xy 152.249301 -439.795784)
			(xy 152.241884 -439.772726) (xy 152.241504 -439.760614) (xy 152.241504 -439.149998) (xy 152.239833 -439.135005)
			(xy 152.238056 -439.104886) (xy 152.237948 -439.0898) (xy 149.334728 -439.0898) (xy 149.334728 -439.760614)
			(xy 149.334304 -439.772708) (xy 149.32684 -439.795714) (xy 149.312643 -439.815297) (xy 149.293099 -439.829546)
			(xy 149.270112 -439.837072) (xy 149.25802 -439.837576) (xy 148.31822 -439.837576) (xy 148.30611 -439.837166)
			(xy 148.283079 -439.829669) (xy 148.263504 -439.815407) (xy 148.249309 -439.795782) (xy 148.241892 -439.772726)
			(xy 148.241512 -439.760614) (xy 148.241512 -439.149998) (xy 148.239841 -439.135005) (xy 148.238064 -439.104886)
			(xy 148.237956 -439.0898) (xy 145.334736 -439.0898) (xy 145.334736 -439.760614) (xy 145.334304 -439.772707)
			(xy 145.326841 -439.795712) (xy 145.312646 -439.815294) (xy 145.293104 -439.829543) (xy 145.270119 -439.83707)
			(xy 145.258028 -439.837576) (xy 144.318228 -439.837576) (xy 144.306118 -439.837159) (xy 144.283088 -439.829665)
			(xy 144.263512 -439.815404) (xy 144.249317 -439.795781) (xy 144.2419 -439.772725) (xy 144.24152 -439.760614)
			(xy 144.24152 -439.149998) (xy 144.239849 -439.135005) (xy 144.238072 -439.104886) (xy 144.237964 -439.0898)
			(xy 140.335 -439.0898) (xy 140.335 -439.760614) (xy 140.334501 -439.772726) (xy 140.327015 -439.795763)
			(xy 140.312778 -439.815361) (xy 140.293184 -439.829604) (xy 140.270149 -439.837097) (xy 140.258038 -439.837576)
			(xy 139.318238 -439.837576) (xy 139.306119 -439.837108) (xy 139.283063 -439.829628) (xy 139.263449 -439.815388)
			(xy 139.249196 -439.795783) (xy 139.2417 -439.772733) (xy 139.241276 -439.760614) (xy 139.241276 -439.147966)
			(xy 139.239731 -439.133474) (xy 139.238079 -439.104374) (xy 139.237974 -439.0898) (xy 136.335008 -439.0898)
			(xy 136.335008 -439.760614) (xy 136.334501 -439.772725) (xy 136.327016 -439.795761) (xy 136.312781 -439.815358)
			(xy 136.293189 -439.829601) (xy 136.270157 -439.837096) (xy 136.258046 -439.837576) (xy 135.318246 -439.837576)
			(xy 135.306127 -439.837101) (xy 135.283072 -439.829623) (xy 135.263457 -439.815385) (xy 135.249204 -439.795782)
			(xy 135.241708 -439.772733) (xy 135.241284 -439.760614) (xy 135.241284 -439.147966) (xy 135.239739 -439.133474)
			(xy 135.238087 -439.104374) (xy 135.237982 -439.0898) (xy 132.335016 -439.0898) (xy 132.335016 -439.760614)
			(xy 132.334651 -439.772742) (xy 132.327149 -439.795809) (xy 132.312885 -439.815428) (xy 132.293255 -439.829677)
			(xy 132.270182 -439.83716) (xy 132.258054 -439.837576) (xy 131.318254 -439.837576) (xy 131.306138 -439.837128)
			(xy 131.283096 -439.82963) (xy 131.263496 -439.815381) (xy 131.249256 -439.795775) (xy 131.241767 -439.77273)
			(xy 131.241292 -439.760614) (xy 131.241292 -439.147966) (xy 131.239747 -439.133474) (xy 131.238095 -439.104374)
			(xy 131.23799 -439.0898) (xy 128.335024 -439.0898) (xy 128.335024 -439.760614) (xy 128.334651 -439.772741)
			(xy 128.32715 -439.795807) (xy 128.312888 -439.815425) (xy 128.29326 -439.829674) (xy 128.27019 -439.837159)
			(xy 128.258062 -439.837576) (xy 127.318262 -439.837576) (xy 127.306147 -439.837121) (xy 127.283105 -439.829625)
			(xy 127.263505 -439.815378) (xy 127.249264 -439.795774) (xy 127.241775 -439.772729) (xy 127.2413 -439.760614)
			(xy 127.2413 -439.147966) (xy 127.239755 -439.133474) (xy 127.238103 -439.104374) (xy 127.237998 -439.0898)
			(xy 90.235024 -439.0898) (xy 90.235024 -439.760614) (xy 90.234651 -439.772741) (xy 90.22715 -439.795807)
			(xy 90.212888 -439.815425) (xy 90.19326 -439.829674) (xy 90.17019 -439.837159) (xy 90.158062 -439.837576)
			(xy 89.218262 -439.837576) (xy 89.206147 -439.837121) (xy 89.183105 -439.829625) (xy 89.163505 -439.815378)
			(xy 89.149264 -439.795774) (xy 89.141775 -439.772729) (xy 89.1413 -439.760614) (xy 89.1413 -439.147966)
			(xy 89.139755 -439.133474) (xy 89.138103 -439.104374) (xy 89.137998 -439.0898) (xy 86.235032 -439.0898)
			(xy 86.235032 -439.760614) (xy 86.234651 -439.77274) (xy 86.227152 -439.795805) (xy 86.212891 -439.815422)
			(xy 86.193265 -439.829672) (xy 86.170197 -439.837158) (xy 86.15807 -439.837576) (xy 85.21827 -439.837576)
			(xy 85.206155 -439.837114) (xy 85.183113 -439.82962) (xy 85.163513 -439.815375) (xy 85.149272 -439.795772)
			(xy 85.141783 -439.772729) (xy 85.141308 -439.760614) (xy 85.141308 -439.147966) (xy 85.139763 -439.133474)
			(xy 85.138111 -439.104374) (xy 85.138006 -439.0898) (xy 82.23504 -439.0898) (xy 82.23504 -439.760614)
			(xy 82.234651 -439.77274) (xy 82.227153 -439.795803) (xy 82.212894 -439.815419) (xy 82.19327 -439.829669)
			(xy 82.170204 -439.837157) (xy 82.158078 -439.837576) (xy 81.218278 -439.837576) (xy 81.206164 -439.837107)
			(xy 81.183122 -439.829616) (xy 81.163522 -439.815372) (xy 81.149281 -439.795771) (xy 81.141791 -439.772728)
			(xy 81.141316 -439.760614) (xy 81.141316 -439.147966) (xy 81.139771 -439.133474) (xy 81.138119 -439.104374)
			(xy 81.138014 -439.0898) (xy 78.235048 -439.0898) (xy 78.235048 -439.760614) (xy 78.2346 -439.772731)
			(xy 78.227107 -439.795777) (xy 78.21286 -439.81538) (xy 78.193252 -439.82962) (xy 78.170203 -439.837105)
			(xy 78.158086 -439.837576) (xy 77.218286 -439.837576) (xy 77.206172 -439.837101) (xy 77.183131 -439.829611)
			(xy 77.16353 -439.81537) (xy 77.149289 -439.795769) (xy 77.141799 -439.772728) (xy 77.141324 -439.760614)
			(xy 77.141324 -439.147966) (xy 77.139779 -439.133474) (xy 77.138127 -439.104374) (xy 77.138022 -439.0898)
			(xy 73.234804 -439.0898) (xy 73.234804 -439.760614) (xy 73.234306 -439.7727) (xy 73.22685 -439.795694)
			(xy 73.21267 -439.81527) (xy 73.193146 -439.829521) (xy 73.17018 -439.837061) (xy 73.158096 -439.837576)
			(xy 72.218296 -439.837576) (xy 72.206185 -439.837187) (xy 72.183153 -439.829683) (xy 72.163578 -439.815416)
			(xy 72.149384 -439.795787) (xy 72.141968 -439.772727) (xy 72.141588 -439.760614) (xy 72.141588 -439.149998)
			(xy 72.139917 -439.135005) (xy 72.13814 -439.104886) (xy 72.138032 -439.0898) (xy 69.234812 -439.0898)
			(xy 69.234812 -439.760614) (xy 69.234404 -439.772709) (xy 69.226938 -439.795718) (xy 69.212737 -439.815302)
			(xy 69.193189 -439.829551) (xy 69.170198 -439.837074) (xy 69.158104 -439.837576) (xy 68.218304 -439.837576)
			(xy 68.206193 -439.83718) (xy 68.183162 -439.829679) (xy 68.163586 -439.815413) (xy 68.149392 -439.795785)
			(xy 68.141976 -439.772727) (xy 68.141596 -439.760614) (xy 68.141596 -439.149998) (xy 68.139925 -439.135005)
			(xy 68.138148 -439.104886) (xy 68.13804 -439.0898) (xy 65.23482 -439.0898) (xy 65.23482 -439.760614)
			(xy 65.234404 -439.772708) (xy 65.226939 -439.795716) (xy 65.21274 -439.815299) (xy 65.193194 -439.829548)
			(xy 65.170205 -439.837073) (xy 65.158112 -439.837576) (xy 64.218312 -439.837576) (xy 64.206201 -439.837173)
			(xy 64.18317 -439.829674) (xy 64.163595 -439.81541) (xy 64.149401 -439.795784) (xy 64.141984 -439.772726)
			(xy 64.141604 -439.760614) (xy 64.141604 -439.149998) (xy 64.139933 -439.135005) (xy 64.138156 -439.104886)
			(xy 64.138048 -439.0898) (xy 61.234828 -439.0898) (xy 61.234828 -439.760614) (xy 61.234404 -439.772708)
			(xy 61.22694 -439.795714) (xy 61.212743 -439.815297) (xy 61.193199 -439.829546) (xy 61.170212 -439.837072)
			(xy 61.15812 -439.837576) (xy 60.21832 -439.837576) (xy 60.20621 -439.837166) (xy 60.183179 -439.829669)
			(xy 60.163604 -439.815407) (xy 60.149409 -439.795782) (xy 60.141992 -439.772726) (xy 60.141612 -439.760614)
			(xy 60.141612 -439.149998) (xy 60.139941 -439.135005) (xy 60.138164 -439.104886) (xy 60.138056 -439.0898)
			(xy 7.00913 -439.0898) (xy 7.00913 -439.989976) (xy 7.009638 -440.045746) (xy 7.017973 -440.156973)
			(xy 7.034597 -440.267266) (xy 7.059417 -440.376009) (xy 7.092293 -440.482593) (xy 7.133043 -440.586422)
			(xy 7.181438 -440.686915) (xy 7.237207 -440.783511) (xy 7.300039 -440.87567) (xy 7.369583 -440.962874)
			(xy 7.445449 -441.044639) (xy 7.527212 -441.120505) (xy 7.614417 -441.190048) (xy 7.706575 -441.252881)
			(xy 7.803171 -441.30865) (xy 7.903664 -441.357045) (xy 8.007493 -441.397795) (xy 8.114077 -441.430672)
			(xy 8.22282 -441.455492) (xy 8.333113 -441.472116) (xy 8.44434 -441.480451) (xy 8.50011 -441.480956)
			(xy 194.495928 -441.480956)
		)
		(stroke
			(width 0)
			(type solid)
		)
		(fill yes)
		(layer "In16.Cu")
		(net "GND")
	)
	(gr_line
		(start 184.879488 -406.620726)
		(end 185.209688 -406.950926)
		(stroke
			(width 0.635)
			(type default)
		)
		(layer "In16.Cu")
	)
	(gr_line
		(start 184.879488 -400.685254)
		(end 184.879488 -406.620726)
		(stroke
			(width 0.635)
			(type default)
		)
		(layer "In16.Cu")
	)
	(gr_line
		(start 185.006488 -413.197548)
		(end 185.006488 -408.491182)
		(stroke
			(width 0.635)
			(type default)
		)
		(layer "In16.Cu")
	)
	(gr_line
		(start 185.209688 -408.287982)
		(end 185.006488 -408.491182)
		(stroke
			(width 0.635)
			(type default)
		)
		(layer "In16.Cu")
	)
	(gr_line
		(start 185.209688 -406.950926)
		(end 185.209688 -408.287982)
		(stroke
			(width 0.635)
			(type default)
		)
		(layer "In16.Cu")
	)
	(gr_line
		(start 188.73343 -400.685254)
		(end 184.879488 -400.685254)
		(stroke
			(width 0.635)
			(type default)
		)
		(layer "In16.Cu")
	)
	(gr_line
		(start 188.93536 -403.657054)
		(end 188.93536 -400.890232)
		(stroke
			(width 0.635)
			(type default)
		)
		(layer "In16.Cu")
	)
	(gr_line
		(start 188.93536 -400.890232)
		(end 188.73343 -400.685254)
		(stroke
			(width 0.635)
			(type default)
		)
		(layer "In16.Cu")
	)
	(gr_line
		(start 189.11316 -403.834854)
		(end 188.93536 -403.657054)
		(stroke
			(width 0.635)
			(type default)
		)
		(layer "In16.Cu")
	)
	(gr_line
		(start 189.46876 -403.834854)
		(end 189.11316 -403.834854)
		(stroke
			(width 0.635)
			(type default)
		)
		(layer "In16.Cu")
	)
	(gr_line
		(start 189.680088 -404.477982)
		(end 189.680088 -404.046182)
		(stroke
			(width 0.635)
			(type default)
		)
		(layer "In16.Cu")
	)
	(gr_line
		(start 189.680088 -404.046182)
		(end 189.46876 -403.834854)
		(stroke
			(width 0.635)
			(type default)
		)
		(layer "In16.Cu")
	)
	(gr_line
		(start 190.870332 -405.66848)
		(end 189.680088 -404.477982)
		(stroke
			(width 0.635)
			(type default)
		)
		(layer "In16.Cu")
	)
	(gr_line
		(start 192.73774 -420.9288)
		(end 185.006488 -413.197548)
		(stroke
			(width 0.635)
			(type default)
		)
		(layer "In16.Cu")
	)
	(gr_line
		(start 196.969888 -405.66848)
		(end 190.870332 -405.66848)
		(stroke
			(width 0.635)
			(type default)
		)
		(layer "In16.Cu")
	)
	(gr_line
		(start 197.416928 -420.9288)
		(end 192.73774 -420.9288)
		(stroke
			(width 0.635)
			(type default)
		)
		(layer "In16.Cu")
	)
	(gr_line
		(start 198.15048 -404.487888)
		(end 196.969888 -405.66848)
		(stroke
			(width 0.635)
			(type default)
		)
		(layer "In16.Cu")
	)
	(gr_line
		(start 198.15048 -400.893788)
		(end 198.15048 -404.487888)
		(stroke
			(width 0.635)
			(type default)
		)
		(layer "In16.Cu")
	)
	(gr_line
		(start 198.341488 -400.70278)
		(end 198.15048 -400.893788)
		(stroke
			(width 0.635)
			(type default)
		)
		(layer "In16.Cu")
	)
	(gr_line
		(start 201.995532 -400.70278)
		(end 198.341488 -400.70278)
		(stroke
			(width 0.635)
			(type default)
		)
		(layer "In16.Cu")
	)
	(gr_line
		(start 202.19416 -404.462488)
		(end 202.19416 -400.901408)
		(stroke
			(width 0.635)
			(type default)
		)
		(layer "In16.Cu")
	)
	(gr_line
		(start 202.19416 -400.901408)
		(end 201.995532 -400.70278)
		(stroke
			(width 0.635)
			(type default)
		)
		(layer "In16.Cu")
	)
	(gr_line
		(start 202.380088 -407.607008)
		(end 202.380088 -404.648416)
		(stroke
			(width 0.635)
			(type default)
		)
		(layer "In16.Cu")
	)
	(gr_line
		(start 202.380088 -404.648416)
		(end 202.19416 -404.462488)
		(stroke
			(width 0.635)
			(type default)
		)
		(layer "In16.Cu")
	)
	(gr_line
		(start 204.16012 -409.38704)
		(end 202.380088 -407.607008)
		(stroke
			(width 0.635)
			(type default)
		)
		(layer "In16.Cu")
	)
	(gr_line
		(start 206.17434 -435.523132)
		(end 206.17434 -429.686212)
		(stroke
			(width 0.635)
			(type default)
		)
		(layer "In16.Cu")
	)
	(gr_line
		(start 206.17434 -429.686212)
		(end 197.416928 -420.9288)
		(stroke
			(width 0.635)
			(type default)
		)
		(layer "In16.Cu")
	)
	(gr_line
		(start 206.545688 -409.38704)
		(end 204.16012 -409.38704)
		(stroke
			(width 0.635)
			(type default)
		)
		(layer "In16.Cu")
	)
	(gr_line
		(start 207.503268 -436.85206)
		(end 206.17434 -435.523132)
		(stroke
			(width 0.635)
			(type default)
		)
		(layer "In16.Cu")
	)
	(gr_line
		(start 207.503268 -436.85206)
		(end 228.909372 -436.85206)
		(stroke
			(width 0.635)
			(type default)
		)
		(layer "In16.Cu")
	)
	(gr_line
		(start 208.628488 -407.30424)
		(end 206.545688 -409.38704)
		(stroke
			(width 0.635)
			(type default)
		)
		(layer "In16.Cu")
	)
	(gr_line
		(start 208.628488 -404.642828)
		(end 208.628488 -407.30424)
		(stroke
			(width 0.635)
			(type default)
		)
		(layer "In16.Cu")
	)
	(gr_line
		(start 208.81848 -404.452836)
		(end 208.628488 -404.642828)
		(stroke
			(width 0.635)
			(type default)
		)
		(layer "In16.Cu")
	)
	(gr_line
		(start 208.81848 -400.893788)
		(end 208.81848 -404.452836)
		(stroke
			(width 0.635)
			(type default)
		)
		(layer "In16.Cu")
	)
	(gr_line
		(start 209.009488 -400.70278)
		(end 208.81848 -400.893788)
		(stroke
			(width 0.635)
			(type default)
		)
		(layer "In16.Cu")
	)
	(gr_line
		(start 212.668612 -400.70278)
		(end 209.009488 -400.70278)
		(stroke
			(width 0.635)
			(type default)
		)
		(layer "In16.Cu")
	)
	(gr_line
		(start 212.85962 -404.485348)
		(end 212.85962 -400.893788)
		(stroke
			(width 0.635)
			(type default)
		)
		(layer "In16.Cu")
	)
	(gr_line
		(start 212.85962 -400.893788)
		(end 212.668612 -400.70278)
		(stroke
			(width 0.635)
			(type default)
		)
		(layer "In16.Cu")
	)
	(gr_line
		(start 213.03742 -407.525728)
		(end 213.03742 -404.663148)
		(stroke
			(width 0.635)
			(type default)
		)
		(layer "In16.Cu")
	)
	(gr_line
		(start 213.03742 -404.663148)
		(end 212.85962 -404.485348)
		(stroke
			(width 0.635)
			(type default)
		)
		(layer "In16.Cu")
	)
	(gr_line
		(start 214.794592 -409.2829)
		(end 213.03742 -407.525728)
		(stroke
			(width 0.635)
			(type default)
		)
		(layer "In16.Cu")
	)
	(gr_line
		(start 217.272616 -409.2829)
		(end 214.794592 -409.2829)
		(stroke
			(width 0.635)
			(type default)
		)
		(layer "In16.Cu")
	)
	(gr_line
		(start 219.296488 -407.259028)
		(end 217.272616 -409.2829)
		(stroke
			(width 0.635)
			(type default)
		)
		(layer "In16.Cu")
	)
	(gr_line
		(start 219.296488 -404.673308)
		(end 219.296488 -407.259028)
		(stroke
			(width 0.635)
			(type default)
		)
		(layer "In16.Cu")
	)
	(gr_line
		(start 219.47886 -404.490936)
		(end 219.296488 -404.673308)
		(stroke
			(width 0.635)
			(type default)
		)
		(layer "In16.Cu")
	)
	(gr_line
		(start 219.47886 -400.906488)
		(end 219.47886 -404.490936)
		(stroke
			(width 0.635)
			(type default)
		)
		(layer "In16.Cu")
	)
	(gr_line
		(start 219.682568 -400.70278)
		(end 219.47886 -400.906488)
		(stroke
			(width 0.635)
			(type default)
		)
		(layer "In16.Cu")
	)
	(gr_line
		(start 223.323912 -400.70278)
		(end 219.682568 -400.70278)
		(stroke
			(width 0.635)
			(type default)
		)
		(layer "In16.Cu")
	)
	(gr_line
		(start 223.53524 -404.47976)
		(end 223.53524 -400.914108)
		(stroke
			(width 0.635)
			(type default)
		)
		(layer "In16.Cu")
	)
	(gr_line
		(start 223.53524 -400.914108)
		(end 223.323912 -400.70278)
		(stroke
			(width 0.635)
			(type default)
		)
		(layer "In16.Cu")
	)
	(gr_line
		(start 223.716088 -407.403808)
		(end 223.716088 -404.660608)
		(stroke
			(width 0.635)
			(type default)
		)
		(layer "In16.Cu")
	)
	(gr_line
		(start 223.716088 -404.660608)
		(end 223.53524 -404.47976)
		(stroke
			(width 0.635)
			(type default)
		)
		(layer "In16.Cu")
	)
	(gr_line
		(start 225.70694 -409.39466)
		(end 223.716088 -407.403808)
		(stroke
			(width 0.635)
			(type default)
		)
		(layer "In16.Cu")
	)
	(gr_line
		(start 227.935028 -409.39466)
		(end 225.70694 -409.39466)
		(stroke
			(width 0.635)
			(type default)
		)
		(layer "In16.Cu")
	)
	(gr_line
		(start 228.909372 -436.85206)
		(end 230.69804 -435.063392)
		(stroke
			(width 0.635)
			(type default)
		)
		(layer "In16.Cu")
	)
	(gr_line
		(start 229.939088 -407.3906)
		(end 227.935028 -409.39466)
		(stroke
			(width 0.635)
			(type default)
		)
		(layer "In16.Cu")
	)
	(gr_line
		(start 229.939088 -404.678388)
		(end 229.939088 -407.3906)
		(stroke
			(width 0.635)
			(type default)
		)
		(layer "In16.Cu")
	)
	(gr_line
		(start 230.14432 -404.473156)
		(end 229.939088 -404.678388)
		(stroke
			(width 0.635)
			(type default)
		)
		(layer "In16.Cu")
	)
	(gr_line
		(start 230.14432 -400.901408)
		(end 230.14432 -404.473156)
		(stroke
			(width 0.635)
			(type default)
		)
		(layer "In16.Cu")
	)
	(gr_line
		(start 230.345488 -400.70024)
		(end 230.14432 -400.901408)
		(stroke
			(width 0.635)
			(type default)
		)
		(layer "In16.Cu")
	)
	(gr_line
		(start 230.69804 -435.063392)
		(end 230.69804 -423.4688)
		(stroke
			(width 0.635)
			(type default)
		)
		(layer "In16.Cu")
	)
	(gr_line
		(start 230.69804 -423.4688)
		(end 233.20756 -420.95928)
		(stroke
			(width 0.635)
			(type default)
		)
		(layer "In16.Cu")
	)
	(gr_line
		(start 233.23042 -420.94404)
		(end 270.49984 -420.94404)
		(stroke
			(width 0.635)
			(type default)
		)
		(layer "In16.Cu")
	)
	(gr_line
		(start 233.996992 -400.70024)
		(end 230.345488 -400.70024)
		(stroke
			(width 0.635)
			(type default)
		)
		(layer "In16.Cu")
	)
	(gr_line
		(start 234.19816 -404.477728)
		(end 234.19816 -400.901408)
		(stroke
			(width 0.635)
			(type default)
		)
		(layer "In16.Cu")
	)
	(gr_line
		(start 234.19816 -400.901408)
		(end 233.996992 -400.70024)
		(stroke
			(width 0.635)
			(type default)
		)
		(layer "In16.Cu")
	)
	(gr_line
		(start 235.520992 -405.80056)
		(end 234.19816 -404.477728)
		(stroke
			(width 0.635)
			(type default)
		)
		(layer "In16.Cu")
	)
	(gr_line
		(start 237.746032 -405.80056)
		(end 235.520992 -405.80056)
		(stroke
			(width 0.635)
			(type default)
		)
		(layer "In16.Cu")
	)
	(gr_line
		(start 237.746032 -405.80056)
		(end 239.699292 -407.75382)
		(stroke
			(width 0.635)
			(type default)
		)
		(layer "In16.Cu")
	)
	(gr_line
		(start 239.10036 -406.737312)
		(end 238.682784 -406.737312)
		(stroke
			(width 0.635)
			(type default)
		)
		(layer "In16.Cu")
	)
	(gr_line
		(start 239.3315 -406.506172)
		(end 239.10036 -406.737312)
		(stroke
			(width 0.635)
			(type default)
		)
		(layer "In16.Cu")
	)
	(gr_arc
		(start 239.3315 -406.506172)
		(mid 239.359619 -406.647264)
		(end 239.439704 -406.766776)
		(stroke
			(width 0.635)
			(type default)
		)
		(layer "In16.Cu")
	)
	(gr_line
		(start 239.3315 -397.839946)
		(end 239.3315 -406.506172)
		(stroke
			(width 0.635)
			(type default)
		)
		(layer "In16.Cu")
	)
	(gr_line
		(start 239.387634 -397.701516)
		(end 239.3315 -397.839946)
		(stroke
			(width 0.635)
			(type default)
		)
		(layer "In16.Cu")
	)
	(gr_line
		(start 239.439704 -406.766776)
		(end 239.663224 -406.990296)
		(stroke
			(width 0.635)
			(type default)
		)
		(layer "In16.Cu")
	)
	(gr_line
		(start 239.441482 -397.649446)
		(end 239.387634 -397.701516)
		(stroke
			(width 0.635)
			(type default)
		)
		(layer "In16.Cu")
	)
	(gr_arc
		(start 239.663224 -406.990296)
		(mid 239.782747 -407.070378)
		(end 239.923828 -407.0985)
		(stroke
			(width 0.635)
			(type default)
		)
		(layer "In16.Cu")
	)
	(gr_line
		(start 239.699292 -407.759408)
		(end 239.699292 -407.75382)
		(stroke
			(width 0.635)
			(type default)
		)
		(layer "In16.Cu")
	)
	(gr_line
		(start 239.699292 -407.75382)
		(end 240.057432 -407.39568)
		(stroke
			(width 0.635)
			(type default)
		)
		(layer "In16.Cu")
	)
	(gr_line
		(start 239.917224 -397.173704)
		(end 239.441482 -397.649446)
		(stroke
			(width 0.635)
			(type default)
		)
		(layer "In16.Cu")
	)
	(gr_line
		(start 239.923828 -407.0985)
		(end 273.791172 -407.0985)
		(stroke
			(width 0.635)
			(type default)
		)
		(layer "In16.Cu")
	)
	(gr_line
		(start 240.057432 -407.39568)
		(end 273.646392 -407.39568)
		(stroke
			(width 0.635)
			(type default)
		)
		(layer "In16.Cu")
	)
	(gr_arc
		(start 240.177828 -397.0655)
		(mid 240.036774 -397.093687)
		(end 239.917224 -397.173704)
		(stroke
			(width 0.635)
			(type default)
		)
		(layer "In16.Cu")
	)
	(gr_line
		(start 265.38936 -420.89832)
		(end 266.3317 -419.95598)
		(stroke
			(width 0.635)
			(type default)
		)
		(layer "In16.Cu")
	)
	(gr_line
		(start 266.3317 -419.95598)
		(end 266.3317 -416.65398)
		(stroke
			(width 0.635)
			(type default)
		)
		(layer "In16.Cu")
	)
	(gr_line
		(start 266.3317 -416.65398)
		(end 267.22578 -415.7599)
		(stroke
			(width 0.635)
			(type default)
		)
		(layer "In16.Cu")
	)
	(gr_line
		(start 267.22578 -415.7599)
		(end 275.68398 -415.7599)
		(stroke
			(width 0.635)
			(type default)
		)
		(layer "In16.Cu")
	)
	(gr_line
		(start 270.47698 -420.58844)
		(end 266.27074 -420.58844)
		(stroke
			(width 0.635)
			(type default)
		)
		(layer "In16.Cu")
	)
	(gr_line
		(start 270.49984 -420.94404)
		(end 275.68398 -415.7599)
		(stroke
			(width 0.635)
			(type default)
		)
		(layer "In16.Cu")
	)
	(gr_line
		(start 270.7005 -420.1668)
		(end 266.49426 -420.1668)
		(stroke
			(width 0.635)
			(type default)
		)
		(layer "In16.Cu")
	)
	(gr_line
		(start 270.7005 -419.71976)
		(end 266.49426 -419.71976)
		(stroke
			(width 0.635)
			(type default)
		)
		(layer "In16.Cu")
	)
	(gr_line
		(start 270.7132 -419.24732)
		(end 266.50696 -419.24732)
		(stroke
			(width 0.635)
			(type default)
		)
		(layer "In16.Cu")
	)
	(gr_line
		(start 270.7386 -418.80028)
		(end 266.53236 -418.80028)
		(stroke
			(width 0.635)
			(type default)
		)
		(layer "In16.Cu")
	)
	(gr_line
		(start 270.74876 -418.31768)
		(end 266.54252 -418.31768)
		(stroke
			(width 0.635)
			(type default)
		)
		(layer "In16.Cu")
	)
	(gr_line
		(start 270.78686 -417.79698)
		(end 266.58062 -417.79698)
		(stroke
			(width 0.635)
			(type default)
		)
		(layer "In16.Cu")
	)
	(gr_line
		(start 270.93672 -417.27374)
		(end 266.73048 -417.27374)
		(stroke
			(width 0.635)
			(type default)
		)
		(layer "In16.Cu")
	)
	(gr_line
		(start 271.06118 -416.8648)
		(end 266.85494 -416.8648)
		(stroke
			(width 0.635)
			(type default)
		)
		(layer "In16.Cu")
	)
	(gr_line
		(start 271.2847 -419.91788)
		(end 267.07846 -419.91788)
		(stroke
			(width 0.635)
			(type default)
		)
		(layer "In16.Cu")
	)
	(gr_line
		(start 271.35836 -416.52952)
		(end 267.15212 -416.52952)
		(stroke
			(width 0.635)
			(type default)
		)
		(layer "In16.Cu")
	)
	(gr_line
		(start 271.39646 -419.70706)
		(end 267.19022 -419.70706)
		(stroke
			(width 0.635)
			(type default)
		)
		(layer "In16.Cu")
	)
	(gr_line
		(start 271.59458 -416.24504)
		(end 267.38834 -416.24504)
		(stroke
			(width 0.635)
			(type default)
		)
		(layer "In16.Cu")
	)
	(gr_line
		(start 271.8054 -419.35908)
		(end 267.59916 -419.35908)
		(stroke
			(width 0.635)
			(type default)
		)
		(layer "In16.Cu")
	)
	(gr_line
		(start 272.23974 -418.91204)
		(end 268.0335 -418.91204)
		(stroke
			(width 0.635)
			(type default)
		)
		(layer "In16.Cu")
	)
	(gr_line
		(start 272.46326 -418.5285)
		(end 268.25702 -418.5285)
		(stroke
			(width 0.635)
			(type default)
		)
		(layer "In16.Cu")
	)
	(gr_line
		(start 272.98396 -418.20592)
		(end 268.77772 -418.20592)
		(stroke
			(width 0.635)
			(type default)
		)
		(layer "In16.Cu")
	)
	(gr_line
		(start 273.29384 -417.77158)
		(end 269.0876 -417.77158)
		(stroke
			(width 0.635)
			(type default)
		)
		(layer "In16.Cu")
	)
	(gr_line
		(start 273.60626 -417.50996)
		(end 269.40002 -417.50996)
		(stroke
			(width 0.635)
			(type default)
		)
		(layer "In16.Cu")
	)
	(gr_line
		(start 273.646392 -407.39568)
		(end 274.051776 -406.990296)
		(stroke
			(width 0.635)
			(type default)
		)
		(layer "In16.Cu")
	)
	(gr_arc
		(start 273.791172 -407.0985)
		(mid 273.932264 -407.070381)
		(end 274.051776 -406.990296)
		(stroke
			(width 0.635)
			(type default)
		)
		(layer "In16.Cu")
	)
	(gr_line
		(start 273.90344 -417.16198)
		(end 269.6972 -417.16198)
		(stroke
			(width 0.635)
			(type default)
		)
		(layer "In16.Cu")
	)
	(gr_line
		(start 274.051776 -407.33472)
		(end 274.470876 -407.75382)
		(stroke
			(width 0.635)
			(type default)
		)
		(layer "In16.Cu")
	)
	(gr_line
		(start 274.051776 -406.990296)
		(end 274.051776 -407.33472)
		(stroke
			(width 0.635)
			(type default)
		)
		(layer "In16.Cu")
	)
	(gr_line
		(start 274.051776 -406.990296)
		(end 274.529296 -406.512776)
		(stroke
			(width 0.635)
			(type default)
		)
		(layer "In16.Cu")
	)
	(gr_line
		(start 274.117054 -397.0655)
		(end 240.177828 -397.0655)
		(stroke
			(width 0.635)
			(type default)
		)
		(layer "In16.Cu")
	)
	(gr_line
		(start 274.22602 -416.8394)
		(end 270.01978 -416.8394)
		(stroke
			(width 0.635)
			(type default)
		)
		(layer "In16.Cu")
	)
	(gr_line
		(start 274.255484 -397.121634)
		(end 274.117054 -397.0655)
		(stroke
			(width 0.635)
			(type default)
		)
		(layer "In16.Cu")
	)
	(gr_line
		(start 274.307554 -397.175482)
		(end 274.255484 -397.121634)
		(stroke
			(width 0.635)
			(type default)
		)
		(layer "In16.Cu")
	)
	(gr_arc
		(start 274.529296 -406.512776)
		(mid 274.609378 -406.393253)
		(end 274.6375 -406.252172)
		(stroke
			(width 0.635)
			(type default)
		)
		(layer "In16.Cu")
	)
	(gr_line
		(start 274.529296 -397.397224)
		(end 274.307554 -397.175482)
		(stroke
			(width 0.635)
			(type default)
		)
		(layer "In16.Cu")
	)
	(gr_line
		(start 274.5359 -416.45586)
		(end 270.32966 -416.45586)
		(stroke
			(width 0.635)
			(type default)
		)
		(layer "In16.Cu")
	)
	(gr_line
		(start 274.6375 -406.252172)
		(end 274.6375 -397.657828)
		(stroke
			(width 0.635)
			(type default)
		)
		(layer "In16.Cu")
	)
	(gr_arc
		(start 274.6375 -397.657828)
		(mid 274.609313 -397.516774)
		(end 274.529296 -397.397224)
		(stroke
			(width 0.635)
			(type default)
		)
		(layer "In16.Cu")
	)
	(gr_line
		(start 274.85848 -416.08248)
		(end 270.65224 -416.08248)
		(stroke
			(width 0.635)
			(type default)
		)
		(layer "In16.Cu")
	)
	(gr_line
		(start 275.0693 -405.960072)
		(end 275.351748 -406.24252)
		(stroke
			(width 0.635)
			(type default)
		)
		(layer "In16.Cu")
	)
	(gr_line
		(start 275.0693 -397.505428)
		(end 275.0693 -405.960072)
		(stroke
			(width 0.635)
			(type default)
		)
		(layer "In16.Cu")
	)
	(gr_line
		(start 275.351748 -406.24252)
		(end 278.143208 -406.24252)
		(stroke
			(width 0.635)
			(type default)
		)
		(layer "In16.Cu")
	)
	(gr_line
		(start 275.509228 -397.0655)
		(end 275.0693 -397.505428)
		(stroke
			(width 0.635)
			(type default)
		)
		(layer "In16.Cu")
	)
	(gr_line
		(start 275.68398 -415.77006)
		(end 275.68398 -415.7599)
		(stroke
			(width 0.635)
			(type default)
		)
		(layer "In16.Cu")
	)
	(gr_line
		(start 275.68398 -415.7599)
		(end 279.927812 -415.7599)
		(stroke
			(width 0.635)
			(type default)
		)
		(layer "In16.Cu")
	)
	(gr_line
		(start 278.143208 -406.24252)
		(end 278.145748 -406.23998)
		(stroke
			(width 0.635)
			(type default)
		)
		(layer "In16.Cu")
	)
	(gr_line
		(start 278.145748 -406.23998)
		(end 281.037792 -406.23998)
		(stroke
			(width 0.635)
			(type default)
		)
		(layer "In16.Cu")
	)
	(gr_line
		(start 279.927812 -415.7599)
		(end 280.51506 -415.172652)
		(stroke
			(width 0.635)
			(type default)
		)
		(layer "In16.Cu")
	)
	(gr_line
		(start 280.100532 -407.75382)
		(end 239.699292 -407.75382)
		(stroke
			(width 0.635)
			(type default)
		)
		(layer "In16.Cu")
	)
	(gr_line
		(start 280.51506 -415.172652)
		(end 280.51506 -408.168348)
		(stroke
			(width 0.635)
			(type default)
		)
		(layer "In16.Cu")
	)
	(gr_line
		(start 280.51506 -408.168348)
		(end 280.100532 -407.75382)
		(stroke
			(width 0.635)
			(type default)
		)
		(layer "In16.Cu")
	)
	(gr_line
		(start 280.83764 -397.0655)
		(end 275.509228 -397.0655)
		(stroke
			(width 0.635)
			(type default)
		)
		(layer "In16.Cu")
	)
	(gr_line
		(start 281.037792 -406.23998)
		(end 281.369008 -405.908764)
		(stroke
			(width 0.635)
			(type default)
		)
		(layer "In16.Cu")
	)
	(gr_line
		(start 281.369008 -405.908764)
		(end 281.369008 -397.596868)
		(stroke
			(width 0.635)
			(type default)
		)
		(layer "In16.Cu")
	)
	(gr_line
		(start 281.369008 -397.596868)
		(end 280.83764 -397.0655)
		(stroke
			(width 0.635)
			(type default)
		)
		(layer "In16.Cu")
	)
	(segment
		(start 473.482162 -95.619824)
		(end 473.605606 -96.321372)
		(width 0.1016)
		(layer "In15.Cu")
		(net "TDR_DIFF_85_NECK_IN6_DP")
	)
	(segment
		(start 478.66427 -91.748102)
		(end 478.795842 -91.840812)
		(width 0.1016)
		(layer "In15.Cu")
		(net "TDR_DIFF_85_NECK_IN6_DP")
	)
	(segment
		(start 483.99319 -107.408218)
		(end 483.826312 -107.645962)
		(width 0.1016)
		(layer "In15.Cu")
		(net "TDR_DIFF_85_NECK_IN6_DP")
	)
	(segment
		(start 473.601796 -114.6683)
		(end 473.723462 -114.753898)
		(width 0.1016)
		(layer "In15.Cu")
		(net "TDR_DIFF_85_NECK_IN6_DP")
	)
	(segment
		(start 483.994206 -103.738934)
		(end 483.827328 -103.976424)
		(width 0.1016)
		(layer "In15.Cu")
		(net "TDR_DIFF_85_NECK_IN6_DP")
	)
	(segment
		(start 473.683838 -111.087408)
		(end 483.452678 -109.365034)
		(width 0.1016)
		(layer "In15.Cu")
		(net "TDR_DIFF_85_NECK_IN6_DP")
	)
	(segment
		(start 483.481634 -105.690924)
		(end 483.719886 -105.857802)
		(width 0.1016)
		(layer "In15.Cu")
		(net "TDR_DIFF_85_NECK_IN6_DP")
	)
	(segment
		(start 473.353384 -113.264188)
		(end 473.601034 -114.667792)
		(width 0.1016)
		(layer "In15.Cu")
		(net "TDR_DIFF_85_NECK_IN6_DP")
	)
	(segment
		(start 473.714572 -107.41279)
		(end 483.481634 -105.690924)
		(width 0.1016)
		(layer "In15.Cu")
		(net "TDR_DIFF_85_NECK_IN6_DP")
	)
	(segment
		(start 483.452678 -109.365034)
		(end 483.690676 -109.531912)
		(width 0.1016)
		(layer "In15.Cu")
		(net "TDR_DIFF_85_NECK_IN6_DP")
	)
	(segment
		(start 473.438474 -98.469958)
		(end 473.356178 -98.587052)
		(width 0.1016)
		(layer "In15.Cu")
		(net "TDR_DIFF_85_NECK_IN6_DP")
	)
	(segment
		(start 483.746556 -94.845632)
		(end 484.01986 -96.396048)
		(width 0.1016)
		(layer "In15.Cu")
		(net "TDR_DIFF_85_NECK_IN6_DP")
	)
	(segment
		(start 473.322904 -102.262178)
		(end 473.570554 -103.665782)
		(width 0.1016)
		(layer "In15.Cu")
		(net "TDR_DIFF_85_NECK_IN6_DP")
	)
	(segment
		(start 483.508304 -94.678754)
		(end 483.746556 -94.845632)
		(width 0.1016)
		(layer "In15.Cu")
		(net "TDR_DIFF_85_NECK_IN6_DP")
	)
	(segment
		(start 484.01986 -96.396048)
		(end 483.852982 -96.633792)
		(width 0.1016)
		(layer "In15.Cu")
		(net "TDR_DIFF_85_NECK_IN6_DP")
	)
	(segment
		(start 484.018082 -92.654374)
		(end 483.794562 -92.974922)
		(width 0.1016)
		(layer "In15.Cu")
		(net "TDR_DIFF_85_NECK_IN6_DP")
	)
	(segment
		(start 483.827328 -103.976424)
		(end 473.432124 -105.809288)
		(width 0.1016)
		(layer "In15.Cu")
		(net "TDR_DIFF_85_NECK_IN6_DP")
	)
	(segment
		(start 473.357956 -94.917768)
		(end 473.481908 -95.619824)
		(width 0.1016)
		(layer "In15.Cu")
		(net "TDR_DIFF_85_NECK_IN6_DP")
	)
	(segment
		(start 473.597224 -107.33024)
		(end 473.714572 -107.41279)
		(width 0.1016)
		(layer "In15.Cu")
		(net "TDR_DIFF_85_NECK_IN6_DP")
	)
	(segment
		(start 478.79127 -90.156792)
		(end 478.66427 -90.283792)
		(width 0.1016)
		(layer "In15.Cu")
		(net "TDR_DIFF_85_NECK_IN6_DP")
	)
	(segment
		(start 473.603828 -99.990656)
		(end 473.72143 -100.073206)
		(width 0.1016)
		(layer "In15.Cu")
		(net "TDR_DIFF_85_NECK_IN6_DP")
	)
	(segment
		(start 478.658936 -116.453158)
		(end 478.76587 -116.560092)
		(width 0.1016)
		(layer "In15.Cu")
		(net "TDR_DIFF_85_NECK_IN6_DP")
	)
	(segment
		(start 473.601034 -114.667792)
		(end 473.601796 -114.6683)
		(width 0.1016)
		(layer "In15.Cu")
		(net "TDR_DIFF_85_NECK_IN6_DP")
	)
	(segment
		(start 483.720902 -102.188518)
		(end 483.994206 -103.738934)
		(width 0.1016)
		(layer "In15.Cu")
		(net "TDR_DIFF_85_NECK_IN6_DP")
	)
	(segment
		(start 473.435934 -113.14684)
		(end 473.353384 -113.264188)
		(width 0.1016)
		(layer "In15.Cu")
		(net "TDR_DIFF_85_NECK_IN6_DP")
	)
	(segment
		(start 483.719886 -105.857802)
		(end 483.99319 -107.408218)
		(width 0.1016)
		(layer "In15.Cu")
		(net "TDR_DIFF_85_NECK_IN6_DP")
	)
	(segment
		(start 483.826312 -107.645962)
		(end 473.40139 -109.483906)
		(width 0.1016)
		(layer "In15.Cu")
		(net "TDR_DIFF_85_NECK_IN6_DP")
	)
	(segment
		(start 473.56649 -111.004858)
		(end 473.683838 -111.087408)
		(width 0.1016)
		(layer "In15.Cu")
		(net "TDR_DIFF_85_NECK_IN6_DP")
	)
	(segment
		(start 473.31884 -109.601254)
		(end 473.56649 -111.004858)
		(width 0.1016)
		(layer "In15.Cu")
		(net "TDR_DIFF_85_NECK_IN6_DP")
	)
	(segment
		(start 483.76967 -91.24442)
		(end 484.018082 -92.654374)
		(width 0.1016)
		(layer "In15.Cu")
		(net "TDR_DIFF_85_NECK_IN6_DP")
	)
	(segment
		(start 483.482396 -102.02164)
		(end 483.720902 -102.188518)
		(width 0.1016)
		(layer "In15.Cu")
		(net "TDR_DIFF_85_NECK_IN6_DP")
	)
	(segment
		(start 478.795842 -91.840812)
		(end 483.449884 -91.019884)
		(width 0.1016)
		(layer "In15.Cu")
		(net "TDR_DIFF_85_NECK_IN6_DP")
	)
	(segment
		(start 473.40139 -109.483906)
		(end 473.31884 -109.601254)
		(width 0.1016)
		(layer "In15.Cu")
		(net "TDR_DIFF_85_NECK_IN6_DP")
	)
	(segment
		(start 473.722954 -96.403922)
		(end 483.508304 -94.678754)
		(width 0.1016)
		(layer "In15.Cu")
		(net "TDR_DIFF_85_NECK_IN6_DP")
	)
	(segment
		(start 483.695756 -98.523552)
		(end 483.96906 -100.073968)
		(width 0.1016)
		(layer "In15.Cu")
		(net "TDR_DIFF_85_NECK_IN6_DP")
	)
	(segment
		(start 473.356178 -98.587052)
		(end 473.603828 -99.990656)
		(width 0.1016)
		(layer "In15.Cu")
		(net "TDR_DIFF_85_NECK_IN6_DP")
	)
	(segment
		(start 473.440506 -94.80042)
		(end 473.357956 -94.917768)
		(width 0.1016)
		(layer "In15.Cu")
		(net "TDR_DIFF_85_NECK_IN6_DP")
	)
	(segment
		(start 479.84537 -90.156792)
		(end 478.79127 -90.156792)
		(width 0.1016)
		(layer "In15.Cu")
		(net "TDR_DIFF_85_NECK_IN6_DP")
	)
	(segment
		(start 483.690676 -109.531912)
		(end 483.96398 -111.082328)
		(width 0.1016)
		(layer "In15.Cu")
		(net "TDR_DIFF_85_NECK_IN6_DP")
	)
	(segment
		(start 473.405454 -102.14483)
		(end 473.322904 -102.262178)
		(width 0.1016)
		(layer "In15.Cu")
		(net "TDR_DIFF_85_NECK_IN6_DP")
	)
	(segment
		(start 483.852982 -96.633792)
		(end 473.438474 -98.469958)
		(width 0.1016)
		(layer "In15.Cu")
		(net "TDR_DIFF_85_NECK_IN6_DP")
	)
	(segment
		(start 483.449884 -91.019884)
		(end 483.76967 -91.24442)
		(width 0.1016)
		(layer "In15.Cu")
		(net "TDR_DIFF_85_NECK_IN6_DP")
	)
	(segment
		(start 483.794562 -92.974922)
		(end 473.440506 -94.80042)
		(width 0.1016)
		(layer "In15.Cu")
		(net "TDR_DIFF_85_NECK_IN6_DP")
	)
	(segment
		(start 478.76587 -116.560092)
		(end 479.84537 -116.560092)
		(width 0.1016)
		(layer "In15.Cu")
		(net "TDR_DIFF_85_NECK_IN6_DP")
	)
	(segment
		(start 473.687902 -103.748332)
		(end 483.482396 -102.02164)
		(width 0.1016)
		(layer "In15.Cu")
		(net "TDR_DIFF_85_NECK_IN6_DP")
	)
	(segment
		(start 473.349574 -105.926636)
		(end 473.597224 -107.33024)
		(width 0.1016)
		(layer "In15.Cu")
		(net "TDR_DIFF_85_NECK_IN6_DP")
	)
	(segment
		(start 483.797102 -111.320072)
		(end 473.435934 -113.14684)
		(width 0.1016)
		(layer "In15.Cu")
		(net "TDR_DIFF_85_NECK_IN6_DP")
	)
	(segment
		(start 473.605606 -96.321372)
		(end 473.722954 -96.403922)
		(width 0.1016)
		(layer "In15.Cu")
		(net "TDR_DIFF_85_NECK_IN6_DP")
	)
	(segment
		(start 473.570554 -103.665782)
		(end 473.687902 -103.748332)
		(width 0.1016)
		(layer "In15.Cu")
		(net "TDR_DIFF_85_NECK_IN6_DP")
	)
	(segment
		(start 473.723462 -114.753898)
		(end 478.427542 -113.924334)
		(width 0.1016)
		(layer "In15.Cu")
		(net "TDR_DIFF_85_NECK_IN6_DP")
	)
	(segment
		(start 483.457504 -98.356674)
		(end 483.695756 -98.523552)
		(width 0.1016)
		(layer "In15.Cu")
		(net "TDR_DIFF_85_NECK_IN6_DP")
	)
	(segment
		(start 473.481908 -95.619824)
		(end 473.482162 -95.619824)
		(width 0.1016)
		(layer "In15.Cu")
		(net "TDR_DIFF_85_NECK_IN6_DP")
	)
	(segment
		(start 473.432124 -105.809288)
		(end 473.349574 -105.926636)
		(width 0.1016)
		(layer "In15.Cu")
		(net "TDR_DIFF_85_NECK_IN6_DP")
	)
	(segment
		(start 478.66427 -90.283792)
		(end 478.66427 -91.748102)
		(width 0.1016)
		(layer "In15.Cu")
		(net "TDR_DIFF_85_NECK_IN6_DP")
	)
	(segment
		(start 483.96906 -100.073968)
		(end 483.802182 -100.311966)
		(width 0.1016)
		(layer "In15.Cu")
		(net "TDR_DIFF_85_NECK_IN6_DP")
	)
	(segment
		(start 478.427542 -113.924334)
		(end 478.658936 -114.15522)
		(width 0.1016)
		(layer "In15.Cu")
		(net "TDR_DIFF_85_NECK_IN6_DP")
	)
	(segment
		(start 473.72143 -100.073206)
		(end 483.457504 -98.356674)
		(width 0.1016)
		(layer "In15.Cu")
		(net "TDR_DIFF_85_NECK_IN6_DP")
	)
	(segment
		(start 478.658936 -114.15522)
		(end 478.658936 -116.453158)
		(width 0.1016)
		(layer "In15.Cu")
		(net "TDR_DIFF_85_NECK_IN6_DP")
	)
	(segment
		(start 483.802182 -100.311966)
		(end 473.405454 -102.14483)
		(width 0.1016)
		(layer "In15.Cu")
		(net "TDR_DIFF_85_NECK_IN6_DP")
	)
	(segment
		(start 483.96398 -111.082328)
		(end 483.797102 -111.320072)
		(width 0.1016)
		(layer "In15.Cu")
		(net "TDR_DIFF_85_NECK_IN6_DP")
	)
	(segment
		(start 483.557326 -105.961434)
		(end 483.804976 -107.366308)
		(width 0.1016)
		(layer "In15.Cu")
		(net "TDR_DIFF_85_NECK_IN6_DN")
	)
	(segment
		(start 473.681552 -114.941858)
		(end 478.367344 -114.115596)
		(width 0.1016)
		(layer "In15.Cu")
		(net "TDR_DIFF_85_NECK_IN6_DN")
	)
	(segment
		(start 473.641928 -111.275368)
		(end 483.411022 -109.552994)
		(width 0.1016)
		(layer "In15.Cu")
		(net "TDR_DIFF_85_NECK_IN6_DN")
	)
	(segment
		(start 478.38487 -116.560092)
		(end 477.30537 -116.560092)
		(width 0.1016)
		(layer "In15.Cu")
		(net "TDR_DIFF_85_NECK_IN6_DN")
	)
	(segment
		(start 483.558342 -102.29215)
		(end 483.806246 -103.697024)
		(width 0.1016)
		(layer "In15.Cu")
		(net "TDR_DIFF_85_NECK_IN6_DN")
	)
	(segment
		(start 478.48647 -91.840558)
		(end 478.753932 -92.028772)
		(width 0.1016)
		(layer "In15.Cu")
		(net "TDR_DIFF_85_NECK_IN6_DN")
	)
	(segment
		(start 478.38487 -90.156792)
		(end 478.48647 -90.258392)
		(width 0.1016)
		(layer "In15.Cu")
		(net "TDR_DIFF_85_NECK_IN6_DN")
	)
	(segment
		(start 473.434664 -107.433618)
		(end 473.672662 -107.60075)
		(width 0.1016)
		(layer "In15.Cu")
		(net "TDR_DIFF_85_NECK_IN6_DN")
	)
	(segment
		(start 473.134944 -102.220268)
		(end 473.407994 -103.76916)
		(width 0.1016)
		(layer "In15.Cu")
		(net "TDR_DIFF_85_NECK_IN6_DN")
	)
	(segment
		(start 473.672662 -107.60075)
		(end 483.439978 -105.878884)
		(width 0.1016)
		(layer "In15.Cu")
		(net "TDR_DIFF_85_NECK_IN6_DN")
	)
	(segment
		(start 473.499434 -114.813842)
		(end 473.681552 -114.941858)
		(width 0.1016)
		(layer "In15.Cu")
		(net "TDR_DIFF_85_NECK_IN6_DN")
	)
	(segment
		(start 473.168218 -98.545142)
		(end 473.441268 -100.094034)
		(width 0.1016)
		(layer "In15.Cu")
		(net "TDR_DIFF_85_NECK_IN6_DN")
	)
	(segment
		(start 473.328746 -105.646728)
		(end 473.161614 -105.884726)
		(width 0.1016)
		(layer "In15.Cu")
		(net "TDR_DIFF_85_NECK_IN6_DN")
	)
	(segment
		(start 483.749604 -96.471232)
		(end 473.335096 -98.307398)
		(width 0.1016)
		(layer "In15.Cu")
		(net "TDR_DIFF_85_NECK_IN6_DN")
	)
	(segment
		(start 483.466648 -94.866714)
		(end 483.583996 -94.949264)
		(width 0.1016)
		(layer "In15.Cu")
		(net "TDR_DIFF_85_NECK_IN6_DN")
	)
	(segment
		(start 473.169996 -94.876112)
		(end 473.443046 -96.42475)
		(width 0.1016)
		(layer "In15.Cu")
		(net "TDR_DIFF_85_NECK_IN6_DN")
	)
	(segment
		(start 473.40393 -111.108236)
		(end 473.641928 -111.275368)
		(width 0.1016)
		(layer "In15.Cu")
		(net "TDR_DIFF_85_NECK_IN6_DN")
	)
	(segment
		(start 483.583996 -94.949264)
		(end 483.831646 -96.354138)
		(width 0.1016)
		(layer "In15.Cu")
		(net "TDR_DIFF_85_NECK_IN6_DN")
	)
	(segment
		(start 478.481136 -114.229134)
		(end 478.481136 -116.463826)
		(width 0.1016)
		(layer "In15.Cu")
		(net "TDR_DIFF_85_NECK_IN6_DN")
	)
	(segment
		(start 473.67952 -100.26142)
		(end 483.415848 -98.544634)
		(width 0.1016)
		(layer "In15.Cu")
		(net "TDR_DIFF_85_NECK_IN6_DN")
	)
	(segment
		(start 473.681044 -96.591882)
		(end 483.466648 -94.866714)
		(width 0.1016)
		(layer "In15.Cu")
		(net "TDR_DIFF_85_NECK_IN6_DN")
	)
	(segment
		(start 473.302076 -101.98227)
		(end 473.134944 -102.220268)
		(width 0.1016)
		(layer "In15.Cu")
		(net "TDR_DIFF_85_NECK_IN6_DN")
	)
	(segment
		(start 483.775766 -111.040418)
		(end 483.693724 -111.157512)
		(width 0.1016)
		(layer "In15.Cu")
		(net "TDR_DIFF_85_NECK_IN6_DN")
	)
	(segment
		(start 483.806246 -103.697024)
		(end 483.72395 -103.813864)
		(width 0.1016)
		(layer "In15.Cu")
		(net "TDR_DIFF_85_NECK_IN6_DN")
	)
	(segment
		(start 483.804976 -107.366308)
		(end 483.722934 -107.483402)
		(width 0.1016)
		(layer "In15.Cu")
		(net "TDR_DIFF_85_NECK_IN6_DN")
	)
	(segment
		(start 483.60711 -91.347798)
		(end 483.830122 -92.612972)
		(width 0.1016)
		(layer "In15.Cu")
		(net "TDR_DIFF_85_NECK_IN6_DN")
	)
	(segment
		(start 473.336874 -94.63786)
		(end 473.169996 -94.876112)
		(width 0.1016)
		(layer "In15.Cu")
		(net "TDR_DIFF_85_NECK_IN6_DN")
	)
	(segment
		(start 473.438474 -114.771424)
		(end 473.49918 -114.814096)
		(width 0.1016)
		(layer "In15.Cu")
		(net "TDR_DIFF_85_NECK_IN6_DN")
	)
	(segment
		(start 473.165424 -113.222278)
		(end 473.438474 -114.771424)
		(width 0.1016)
		(layer "In15.Cu")
		(net "TDR_DIFF_85_NECK_IN6_DN")
	)
	(segment
		(start 483.69093 -92.812616)
		(end 473.336874 -94.63786)
		(width 0.1016)
		(layer "In15.Cu")
		(net "TDR_DIFF_85_NECK_IN6_DN")
	)
	(segment
		(start 483.7811 -100.032312)
		(end 483.698804 -100.149406)
		(width 0.1016)
		(layer "In15.Cu")
		(net "TDR_DIFF_85_NECK_IN6_DN")
	)
	(segment
		(start 473.161614 -105.884726)
		(end 473.434664 -107.433618)
		(width 0.1016)
		(layer "In15.Cu")
		(net "TDR_DIFF_85_NECK_IN6_DN")
	)
	(segment
		(start 478.753932 -92.028772)
		(end 483.407974 -91.208098)
		(width 0.1016)
		(layer "In15.Cu")
		(net "TDR_DIFF_85_NECK_IN6_DN")
	)
	(segment
		(start 473.49918 -114.814096)
		(end 473.499434 -114.813842)
		(width 0.1016)
		(layer "In15.Cu")
		(net "TDR_DIFF_85_NECK_IN6_DN")
	)
	(segment
		(start 483.533196 -98.627184)
		(end 483.7811 -100.032312)
		(width 0.1016)
		(layer "In15.Cu")
		(net "TDR_DIFF_85_NECK_IN6_DN")
	)
	(segment
		(start 483.698804 -100.149406)
		(end 473.302076 -101.98227)
		(width 0.1016)
		(layer "In15.Cu")
		(net "TDR_DIFF_85_NECK_IN6_DN")
	)
	(segment
		(start 483.528116 -109.63529)
		(end 483.775766 -111.040418)
		(width 0.1016)
		(layer "In15.Cu")
		(net "TDR_DIFF_85_NECK_IN6_DN")
	)
	(segment
		(start 473.332556 -112.98428)
		(end 473.165424 -113.222278)
		(width 0.1016)
		(layer "In15.Cu")
		(net "TDR_DIFF_85_NECK_IN6_DN")
	)
	(segment
		(start 483.72395 -103.813864)
		(end 473.328746 -105.646728)
		(width 0.1016)
		(layer "In15.Cu")
		(net "TDR_DIFF_85_NECK_IN6_DN")
	)
	(segment
		(start 473.407994 -103.76916)
		(end 473.645992 -103.936292)
		(width 0.1016)
		(layer "In15.Cu")
		(net "TDR_DIFF_85_NECK_IN6_DN")
	)
	(segment
		(start 478.48647 -90.258392)
		(end 478.48647 -91.840558)
		(width 0.1016)
		(layer "In15.Cu")
		(net "TDR_DIFF_85_NECK_IN6_DN")
	)
	(segment
		(start 483.44074 -102.2096)
		(end 483.558342 -102.29215)
		(width 0.1016)
		(layer "In15.Cu")
		(net "TDR_DIFF_85_NECK_IN6_DN")
	)
	(segment
		(start 473.443046 -96.42475)
		(end 473.681044 -96.591882)
		(width 0.1016)
		(layer "In15.Cu")
		(net "TDR_DIFF_85_NECK_IN6_DN")
	)
	(segment
		(start 483.415848 -98.544634)
		(end 483.533196 -98.627184)
		(width 0.1016)
		(layer "In15.Cu")
		(net "TDR_DIFF_85_NECK_IN6_DN")
	)
	(segment
		(start 483.407974 -91.208098)
		(end 483.60711 -91.347798)
		(width 0.1016)
		(layer "In15.Cu")
		(net "TDR_DIFF_85_NECK_IN6_DN")
	)
	(segment
		(start 483.722934 -107.483402)
		(end 473.298012 -109.321346)
		(width 0.1016)
		(layer "In15.Cu")
		(net "TDR_DIFF_85_NECK_IN6_DN")
	)
	(segment
		(start 483.831646 -96.354138)
		(end 483.749604 -96.471232)
		(width 0.1016)
		(layer "In15.Cu")
		(net "TDR_DIFF_85_NECK_IN6_DN")
	)
	(segment
		(start 473.298012 -109.321346)
		(end 473.13088 -109.559344)
		(width 0.1016)
		(layer "In15.Cu")
		(net "TDR_DIFF_85_NECK_IN6_DN")
	)
	(segment
		(start 473.645992 -103.936292)
		(end 483.44074 -102.2096)
		(width 0.1016)
		(layer "In15.Cu")
		(net "TDR_DIFF_85_NECK_IN6_DN")
	)
	(segment
		(start 473.335096 -98.307398)
		(end 473.168218 -98.545142)
		(width 0.1016)
		(layer "In15.Cu")
		(net "TDR_DIFF_85_NECK_IN6_DN")
	)
	(segment
		(start 478.367344 -114.115596)
		(end 478.481136 -114.229134)
		(width 0.1016)
		(layer "In15.Cu")
		(net "TDR_DIFF_85_NECK_IN6_DN")
	)
	(segment
		(start 483.411022 -109.552994)
		(end 483.528116 -109.63529)
		(width 0.1016)
		(layer "In15.Cu")
		(net "TDR_DIFF_85_NECK_IN6_DN")
	)
	(segment
		(start 473.13088 -109.559344)
		(end 473.40393 -111.108236)
		(width 0.1016)
		(layer "In15.Cu")
		(net "TDR_DIFF_85_NECK_IN6_DN")
	)
	(segment
		(start 483.439978 -105.878884)
		(end 483.557326 -105.961434)
		(width 0.1016)
		(layer "In15.Cu")
		(net "TDR_DIFF_85_NECK_IN6_DN")
	)
	(segment
		(start 478.481136 -116.463826)
		(end 478.38487 -116.560092)
		(width 0.1016)
		(layer "In15.Cu")
		(net "TDR_DIFF_85_NECK_IN6_DN")
	)
	(segment
		(start 473.441268 -100.094034)
		(end 473.67952 -100.26142)
		(width 0.1016)
		(layer "In15.Cu")
		(net "TDR_DIFF_85_NECK_IN6_DN")
	)
	(segment
		(start 477.30537 -90.156792)
		(end 478.38487 -90.156792)
		(width 0.1016)
		(layer "In15.Cu")
		(net "TDR_DIFF_85_NECK_IN6_DN")
	)
	(segment
		(start 483.693724 -111.157512)
		(end 473.332556 -112.98428)
		(width 0.1016)
		(layer "In15.Cu")
		(net "TDR_DIFF_85_NECK_IN6_DN")
	)
	(segment
		(start 483.830122 -92.612972)
		(end 483.69093 -92.812616)
		(width 0.1016)
		(layer "In15.Cu")
		(net "TDR_DIFF_85_NECK_IN6_DN")
	)
	(segment
		(start 473.672662 -170.56735)
		(end 483.439978 -168.845484)
		(width 0.1016)
		(layer "In13.Cu")
		(net "TDR_DIFF_85_NECK_IN5_DP")
	)
	(segment
		(start 483.533196 -161.593784)
		(end 483.7811 -162.998912)
		(width 0.1016)
		(layer "In13.Cu")
		(net "TDR_DIFF_85_NECK_IN5_DP")
	)
	(segment
		(start 483.693724 -174.124112)
		(end 473.332556 -175.95088)
		(width 0.1016)
		(layer "In13.Cu")
		(net "TDR_DIFF_85_NECK_IN5_DP")
	)
	(segment
		(start 478.48647 -154.807158)
		(end 478.753932 -154.995372)
		(width 0.1016)
		(layer "In13.Cu")
		(net "TDR_DIFF_85_NECK_IN5_DP")
	)
	(segment
		(start 483.804976 -170.332908)
		(end 483.722934 -170.450002)
		(width 0.1016)
		(layer "In13.Cu")
		(net "TDR_DIFF_85_NECK_IN5_DP")
	)
	(segment
		(start 473.13088 -172.525944)
		(end 473.40393 -174.074836)
		(width 0.1016)
		(layer "In13.Cu")
		(net "TDR_DIFF_85_NECK_IN5_DP")
	)
	(segment
		(start 483.583996 -157.915864)
		(end 483.831646 -159.320738)
		(width 0.1016)
		(layer "In13.Cu")
		(net "TDR_DIFF_85_NECK_IN5_DP")
	)
	(segment
		(start 473.165424 -176.188878)
		(end 473.438474 -177.738024)
		(width 0.1016)
		(layer "In13.Cu")
		(net "TDR_DIFF_85_NECK_IN5_DP")
	)
	(segment
		(start 483.557326 -168.928034)
		(end 483.804976 -170.332908)
		(width 0.1016)
		(layer "In13.Cu")
		(net "TDR_DIFF_85_NECK_IN5_DP")
	)
	(segment
		(start 473.134944 -165.186868)
		(end 473.407994 -166.73576)
		(width 0.1016)
		(layer "In13.Cu")
		(net "TDR_DIFF_85_NECK_IN5_DP")
	)
	(segment
		(start 483.44074 -165.1762)
		(end 483.558342 -165.25875)
		(width 0.1016)
		(layer "In13.Cu")
		(net "TDR_DIFF_85_NECK_IN5_DP")
	)
	(segment
		(start 473.49918 -177.780696)
		(end 473.499434 -177.780442)
		(width 0.1016)
		(layer "In13.Cu")
		(net "TDR_DIFF_85_NECK_IN5_DP")
	)
	(segment
		(start 473.499434 -177.780442)
		(end 473.681552 -177.908458)
		(width 0.1016)
		(layer "In13.Cu")
		(net "TDR_DIFF_85_NECK_IN5_DP")
	)
	(segment
		(start 473.335096 -161.273998)
		(end 473.168218 -161.511742)
		(width 0.1016)
		(layer "In13.Cu")
		(net "TDR_DIFF_85_NECK_IN5_DP")
	)
	(segment
		(start 483.466648 -157.833314)
		(end 483.583996 -157.915864)
		(width 0.1016)
		(layer "In13.Cu")
		(net "TDR_DIFF_85_NECK_IN5_DP")
	)
	(segment
		(start 473.298012 -172.287946)
		(end 473.13088 -172.525944)
		(width 0.1016)
		(layer "In13.Cu")
		(net "TDR_DIFF_85_NECK_IN5_DP")
	)
	(segment
		(start 478.481136 -177.195734)
		(end 478.481136 -179.430426)
		(width 0.1016)
		(layer "In13.Cu")
		(net "TDR_DIFF_85_NECK_IN5_DP")
	)
	(segment
		(start 473.328746 -168.613328)
		(end 473.161614 -168.851326)
		(width 0.1016)
		(layer "In13.Cu")
		(net "TDR_DIFF_85_NECK_IN5_DP")
	)
	(segment
		(start 473.332556 -175.95088)
		(end 473.165424 -176.188878)
		(width 0.1016)
		(layer "In13.Cu")
		(net "TDR_DIFF_85_NECK_IN5_DP")
	)
	(segment
		(start 478.38487 -179.526692)
		(end 477.30537 -179.526692)
		(width 0.1016)
		(layer "In13.Cu")
		(net "TDR_DIFF_85_NECK_IN5_DP")
	)
	(segment
		(start 483.407974 -154.174698)
		(end 483.60711 -154.314398)
		(width 0.1016)
		(layer "In13.Cu")
		(net "TDR_DIFF_85_NECK_IN5_DP")
	)
	(segment
		(start 473.434664 -170.400218)
		(end 473.672662 -170.56735)
		(width 0.1016)
		(layer "In13.Cu")
		(net "TDR_DIFF_85_NECK_IN5_DP")
	)
	(segment
		(start 473.161614 -168.851326)
		(end 473.434664 -170.400218)
		(width 0.1016)
		(layer "In13.Cu")
		(net "TDR_DIFF_85_NECK_IN5_DP")
	)
	(segment
		(start 483.806246 -166.663624)
		(end 483.72395 -166.780464)
		(width 0.1016)
		(layer "In13.Cu")
		(net "TDR_DIFF_85_NECK_IN5_DP")
	)
	(segment
		(start 478.367344 -177.082196)
		(end 478.481136 -177.195734)
		(width 0.1016)
		(layer "In13.Cu")
		(net "TDR_DIFF_85_NECK_IN5_DP")
	)
	(segment
		(start 478.753932 -154.995372)
		(end 483.407974 -154.174698)
		(width 0.1016)
		(layer "In13.Cu")
		(net "TDR_DIFF_85_NECK_IN5_DP")
	)
	(segment
		(start 483.415848 -161.511234)
		(end 483.533196 -161.593784)
		(width 0.1016)
		(layer "In13.Cu")
		(net "TDR_DIFF_85_NECK_IN5_DP")
	)
	(segment
		(start 483.558342 -165.25875)
		(end 483.806246 -166.663624)
		(width 0.1016)
		(layer "In13.Cu")
		(net "TDR_DIFF_85_NECK_IN5_DP")
	)
	(segment
		(start 483.528116 -172.60189)
		(end 483.775766 -174.007018)
		(width 0.1016)
		(layer "In13.Cu")
		(net "TDR_DIFF_85_NECK_IN5_DP")
	)
	(segment
		(start 473.169996 -157.842712)
		(end 473.443046 -159.39135)
		(width 0.1016)
		(layer "In13.Cu")
		(net "TDR_DIFF_85_NECK_IN5_DP")
	)
	(segment
		(start 473.67952 -163.22802)
		(end 483.415848 -161.511234)
		(width 0.1016)
		(layer "In13.Cu")
		(net "TDR_DIFF_85_NECK_IN5_DP")
	)
	(segment
		(start 483.72395 -166.780464)
		(end 473.328746 -168.613328)
		(width 0.1016)
		(layer "In13.Cu")
		(net "TDR_DIFF_85_NECK_IN5_DP")
	)
	(segment
		(start 473.40393 -174.074836)
		(end 473.641928 -174.241968)
		(width 0.1016)
		(layer "In13.Cu")
		(net "TDR_DIFF_85_NECK_IN5_DP")
	)
	(segment
		(start 477.30537 -153.123392)
		(end 478.38487 -153.123392)
		(width 0.1016)
		(layer "In13.Cu")
		(net "TDR_DIFF_85_NECK_IN5_DP")
	)
	(segment
		(start 473.681044 -159.558482)
		(end 483.466648 -157.833314)
		(width 0.1016)
		(layer "In13.Cu")
		(net "TDR_DIFF_85_NECK_IN5_DP")
	)
	(segment
		(start 473.681552 -177.908458)
		(end 478.367344 -177.082196)
		(width 0.1016)
		(layer "In13.Cu")
		(net "TDR_DIFF_85_NECK_IN5_DP")
	)
	(segment
		(start 473.438474 -177.738024)
		(end 473.49918 -177.780696)
		(width 0.1016)
		(layer "In13.Cu")
		(net "TDR_DIFF_85_NECK_IN5_DP")
	)
	(segment
		(start 483.749604 -159.437832)
		(end 473.335096 -161.273998)
		(width 0.1016)
		(layer "In13.Cu")
		(net "TDR_DIFF_85_NECK_IN5_DP")
	)
	(segment
		(start 483.831646 -159.320738)
		(end 483.749604 -159.437832)
		(width 0.1016)
		(layer "In13.Cu")
		(net "TDR_DIFF_85_NECK_IN5_DP")
	)
	(segment
		(start 473.443046 -159.39135)
		(end 473.681044 -159.558482)
		(width 0.1016)
		(layer "In13.Cu")
		(net "TDR_DIFF_85_NECK_IN5_DP")
	)
	(segment
		(start 483.69093 -155.779216)
		(end 473.336874 -157.60446)
		(width 0.1016)
		(layer "In13.Cu")
		(net "TDR_DIFF_85_NECK_IN5_DP")
	)
	(segment
		(start 478.481136 -179.430426)
		(end 478.38487 -179.526692)
		(width 0.1016)
		(layer "In13.Cu")
		(net "TDR_DIFF_85_NECK_IN5_DP")
	)
	(segment
		(start 483.775766 -174.007018)
		(end 483.693724 -174.124112)
		(width 0.1016)
		(layer "In13.Cu")
		(net "TDR_DIFF_85_NECK_IN5_DP")
	)
	(segment
		(start 473.441268 -163.060634)
		(end 473.67952 -163.22802)
		(width 0.1016)
		(layer "In13.Cu")
		(net "TDR_DIFF_85_NECK_IN5_DP")
	)
	(segment
		(start 483.722934 -170.450002)
		(end 473.298012 -172.287946)
		(width 0.1016)
		(layer "In13.Cu")
		(net "TDR_DIFF_85_NECK_IN5_DP")
	)
	(segment
		(start 473.302076 -164.94887)
		(end 473.134944 -165.186868)
		(width 0.1016)
		(layer "In13.Cu")
		(net "TDR_DIFF_85_NECK_IN5_DP")
	)
	(segment
		(start 483.439978 -168.845484)
		(end 483.557326 -168.928034)
		(width 0.1016)
		(layer "In13.Cu")
		(net "TDR_DIFF_85_NECK_IN5_DP")
	)
	(segment
		(start 478.48647 -153.224992)
		(end 478.48647 -154.807158)
		(width 0.1016)
		(layer "In13.Cu")
		(net "TDR_DIFF_85_NECK_IN5_DP")
	)
	(segment
		(start 483.60711 -154.314398)
		(end 483.830122 -155.579572)
		(width 0.1016)
		(layer "In13.Cu")
		(net "TDR_DIFF_85_NECK_IN5_DP")
	)
	(segment
		(start 483.830122 -155.579572)
		(end 483.69093 -155.779216)
		(width 0.1016)
		(layer "In13.Cu")
		(net "TDR_DIFF_85_NECK_IN5_DP")
	)
	(segment
		(start 483.411022 -172.519594)
		(end 483.528116 -172.60189)
		(width 0.1016)
		(layer "In13.Cu")
		(net "TDR_DIFF_85_NECK_IN5_DP")
	)
	(segment
		(start 478.38487 -153.123392)
		(end 478.48647 -153.224992)
		(width 0.1016)
		(layer "In13.Cu")
		(net "TDR_DIFF_85_NECK_IN5_DP")
	)
	(segment
		(start 473.645992 -166.902892)
		(end 483.44074 -165.1762)
		(width 0.1016)
		(layer "In13.Cu")
		(net "TDR_DIFF_85_NECK_IN5_DP")
	)
	(segment
		(start 483.7811 -162.998912)
		(end 483.698804 -163.116006)
		(width 0.1016)
		(layer "In13.Cu")
		(net "TDR_DIFF_85_NECK_IN5_DP")
	)
	(segment
		(start 473.641928 -174.241968)
		(end 483.411022 -172.519594)
		(width 0.1016)
		(layer "In13.Cu")
		(net "TDR_DIFF_85_NECK_IN5_DP")
	)
	(segment
		(start 473.168218 -161.511742)
		(end 473.441268 -163.060634)
		(width 0.1016)
		(layer "In13.Cu")
		(net "TDR_DIFF_85_NECK_IN5_DP")
	)
	(segment
		(start 473.336874 -157.60446)
		(end 473.169996 -157.842712)
		(width 0.1016)
		(layer "In13.Cu")
		(net "TDR_DIFF_85_NECK_IN5_DP")
	)
	(segment
		(start 473.407994 -166.73576)
		(end 473.645992 -166.902892)
		(width 0.1016)
		(layer "In13.Cu")
		(net "TDR_DIFF_85_NECK_IN5_DP")
	)
	(segment
		(start 483.698804 -163.116006)
		(end 473.302076 -164.94887)
		(width 0.1016)
		(layer "In13.Cu")
		(net "TDR_DIFF_85_NECK_IN5_DP")
	)
	(segment
		(start 483.797102 -174.286672)
		(end 473.435934 -176.11344)
		(width 0.1016)
		(layer "In13.Cu")
		(net "TDR_DIFF_85_NECK_IN5_DN")
	)
	(segment
		(start 483.76967 -154.21102)
		(end 484.018082 -155.620974)
		(width 0.1016)
		(layer "In13.Cu")
		(net "TDR_DIFF_85_NECK_IN5_DN")
	)
	(segment
		(start 478.658936 -179.419758)
		(end 478.76587 -179.526692)
		(width 0.1016)
		(layer "In13.Cu")
		(net "TDR_DIFF_85_NECK_IN5_DN")
	)
	(segment
		(start 483.852982 -159.600392)
		(end 473.438474 -161.436558)
		(width 0.1016)
		(layer "In13.Cu")
		(net "TDR_DIFF_85_NECK_IN5_DN")
	)
	(segment
		(start 473.570554 -166.632382)
		(end 473.687902 -166.714932)
		(width 0.1016)
		(layer "In13.Cu")
		(net "TDR_DIFF_85_NECK_IN5_DN")
	)
	(segment
		(start 478.658936 -177.12182)
		(end 478.658936 -179.419758)
		(width 0.1016)
		(layer "In13.Cu")
		(net "TDR_DIFF_85_NECK_IN5_DN")
	)
	(segment
		(start 473.597224 -170.29684)
		(end 473.714572 -170.37939)
		(width 0.1016)
		(layer "In13.Cu")
		(net "TDR_DIFF_85_NECK_IN5_DN")
	)
	(segment
		(start 483.826312 -170.612562)
		(end 473.40139 -172.450506)
		(width 0.1016)
		(layer "In13.Cu")
		(net "TDR_DIFF_85_NECK_IN5_DN")
	)
	(segment
		(start 479.84537 -153.123392)
		(end 478.79127 -153.123392)
		(width 0.1016)
		(layer "In13.Cu")
		(net "TDR_DIFF_85_NECK_IN5_DN")
	)
	(segment
		(start 473.438474 -161.436558)
		(end 473.356178 -161.553652)
		(width 0.1016)
		(layer "In13.Cu")
		(net "TDR_DIFF_85_NECK_IN5_DN")
	)
	(segment
		(start 483.508304 -157.645354)
		(end 483.746556 -157.812232)
		(width 0.1016)
		(layer "In13.Cu")
		(net "TDR_DIFF_85_NECK_IN5_DN")
	)
	(segment
		(start 478.79127 -153.123392)
		(end 478.66427 -153.250392)
		(width 0.1016)
		(layer "In13.Cu")
		(net "TDR_DIFF_85_NECK_IN5_DN")
	)
	(segment
		(start 478.795842 -154.807412)
		(end 483.449884 -153.986484)
		(width 0.1016)
		(layer "In13.Cu")
		(net "TDR_DIFF_85_NECK_IN5_DN")
	)
	(segment
		(start 473.405454 -165.11143)
		(end 473.322904 -165.228778)
		(width 0.1016)
		(layer "In13.Cu")
		(net "TDR_DIFF_85_NECK_IN5_DN")
	)
	(segment
		(start 483.482396 -164.98824)
		(end 483.720902 -165.155118)
		(width 0.1016)
		(layer "In13.Cu")
		(net "TDR_DIFF_85_NECK_IN5_DN")
	)
	(segment
		(start 483.452678 -172.331634)
		(end 483.690676 -172.498512)
		(width 0.1016)
		(layer "In13.Cu")
		(net "TDR_DIFF_85_NECK_IN5_DN")
	)
	(segment
		(start 483.457504 -161.323274)
		(end 483.695756 -161.490152)
		(width 0.1016)
		(layer "In13.Cu")
		(net "TDR_DIFF_85_NECK_IN5_DN")
	)
	(segment
		(start 473.40139 -172.450506)
		(end 473.31884 -172.567854)
		(width 0.1016)
		(layer "In13.Cu")
		(net "TDR_DIFF_85_NECK_IN5_DN")
	)
	(segment
		(start 478.66427 -154.714702)
		(end 478.795842 -154.807412)
		(width 0.1016)
		(layer "In13.Cu")
		(net "TDR_DIFF_85_NECK_IN5_DN")
	)
	(segment
		(start 483.96398 -174.048928)
		(end 483.797102 -174.286672)
		(width 0.1016)
		(layer "In13.Cu")
		(net "TDR_DIFF_85_NECK_IN5_DN")
	)
	(segment
		(start 473.605606 -159.287972)
		(end 473.722954 -159.370522)
		(width 0.1016)
		(layer "In13.Cu")
		(net "TDR_DIFF_85_NECK_IN5_DN")
	)
	(segment
		(start 483.695756 -161.490152)
		(end 483.96906 -163.040568)
		(width 0.1016)
		(layer "In13.Cu")
		(net "TDR_DIFF_85_NECK_IN5_DN")
	)
	(segment
		(start 473.349574 -168.893236)
		(end 473.597224 -170.29684)
		(width 0.1016)
		(layer "In13.Cu")
		(net "TDR_DIFF_85_NECK_IN5_DN")
	)
	(segment
		(start 473.714572 -170.37939)
		(end 483.481634 -168.657524)
		(width 0.1016)
		(layer "In13.Cu")
		(net "TDR_DIFF_85_NECK_IN5_DN")
	)
	(segment
		(start 473.687902 -166.714932)
		(end 483.482396 -164.98824)
		(width 0.1016)
		(layer "In13.Cu")
		(net "TDR_DIFF_85_NECK_IN5_DN")
	)
	(segment
		(start 473.722954 -159.370522)
		(end 483.508304 -157.645354)
		(width 0.1016)
		(layer "In13.Cu")
		(net "TDR_DIFF_85_NECK_IN5_DN")
	)
	(segment
		(start 484.018082 -155.620974)
		(end 483.794562 -155.941522)
		(width 0.1016)
		(layer "In13.Cu")
		(net "TDR_DIFF_85_NECK_IN5_DN")
	)
	(segment
		(start 473.481908 -158.586424)
		(end 473.482162 -158.586424)
		(width 0.1016)
		(layer "In13.Cu")
		(net "TDR_DIFF_85_NECK_IN5_DN")
	)
	(segment
		(start 473.482162 -158.586424)
		(end 473.605606 -159.287972)
		(width 0.1016)
		(layer "In13.Cu")
		(net "TDR_DIFF_85_NECK_IN5_DN")
	)
	(segment
		(start 483.481634 -168.657524)
		(end 483.719886 -168.824402)
		(width 0.1016)
		(layer "In13.Cu")
		(net "TDR_DIFF_85_NECK_IN5_DN")
	)
	(segment
		(start 483.720902 -165.155118)
		(end 483.994206 -166.705534)
		(width 0.1016)
		(layer "In13.Cu")
		(net "TDR_DIFF_85_NECK_IN5_DN")
	)
	(segment
		(start 473.353384 -176.230788)
		(end 473.601034 -177.634392)
		(width 0.1016)
		(layer "In13.Cu")
		(net "TDR_DIFF_85_NECK_IN5_DN")
	)
	(segment
		(start 483.690676 -172.498512)
		(end 483.96398 -174.048928)
		(width 0.1016)
		(layer "In13.Cu")
		(net "TDR_DIFF_85_NECK_IN5_DN")
	)
	(segment
		(start 478.66427 -153.250392)
		(end 478.66427 -154.714702)
		(width 0.1016)
		(layer "In13.Cu")
		(net "TDR_DIFF_85_NECK_IN5_DN")
	)
	(segment
		(start 483.802182 -163.278566)
		(end 473.405454 -165.11143)
		(width 0.1016)
		(layer "In13.Cu")
		(net "TDR_DIFF_85_NECK_IN5_DN")
	)
	(segment
		(start 473.356178 -161.553652)
		(end 473.603828 -162.957256)
		(width 0.1016)
		(layer "In13.Cu")
		(net "TDR_DIFF_85_NECK_IN5_DN")
	)
	(segment
		(start 483.794562 -155.941522)
		(end 473.440506 -157.76702)
		(width 0.1016)
		(layer "In13.Cu")
		(net "TDR_DIFF_85_NECK_IN5_DN")
	)
	(segment
		(start 478.427542 -176.890934)
		(end 478.658936 -177.12182)
		(width 0.1016)
		(layer "In13.Cu")
		(net "TDR_DIFF_85_NECK_IN5_DN")
	)
	(segment
		(start 473.432124 -168.775888)
		(end 473.349574 -168.893236)
		(width 0.1016)
		(layer "In13.Cu")
		(net "TDR_DIFF_85_NECK_IN5_DN")
	)
	(segment
		(start 473.72143 -163.039806)
		(end 483.457504 -161.323274)
		(width 0.1016)
		(layer "In13.Cu")
		(net "TDR_DIFF_85_NECK_IN5_DN")
	)
	(segment
		(start 473.603828 -162.957256)
		(end 473.72143 -163.039806)
		(width 0.1016)
		(layer "In13.Cu")
		(net "TDR_DIFF_85_NECK_IN5_DN")
	)
	(segment
		(start 478.76587 -179.526692)
		(end 479.84537 -179.526692)
		(width 0.1016)
		(layer "In13.Cu")
		(net "TDR_DIFF_85_NECK_IN5_DN")
	)
	(segment
		(start 473.601034 -177.634392)
		(end 473.601796 -177.6349)
		(width 0.1016)
		(layer "In13.Cu")
		(net "TDR_DIFF_85_NECK_IN5_DN")
	)
	(segment
		(start 473.357956 -157.884368)
		(end 473.481908 -158.586424)
		(width 0.1016)
		(layer "In13.Cu")
		(net "TDR_DIFF_85_NECK_IN5_DN")
	)
	(segment
		(start 473.435934 -176.11344)
		(end 473.353384 -176.230788)
		(width 0.1016)
		(layer "In13.Cu")
		(net "TDR_DIFF_85_NECK_IN5_DN")
	)
	(segment
		(start 483.994206 -166.705534)
		(end 483.827328 -166.943024)
		(width 0.1016)
		(layer "In13.Cu")
		(net "TDR_DIFF_85_NECK_IN5_DN")
	)
	(segment
		(start 473.723462 -177.720498)
		(end 478.427542 -176.890934)
		(width 0.1016)
		(layer "In13.Cu")
		(net "TDR_DIFF_85_NECK_IN5_DN")
	)
	(segment
		(start 484.01986 -159.362648)
		(end 483.852982 -159.600392)
		(width 0.1016)
		(layer "In13.Cu")
		(net "TDR_DIFF_85_NECK_IN5_DN")
	)
	(segment
		(start 473.31884 -172.567854)
		(end 473.56649 -173.971458)
		(width 0.1016)
		(layer "In13.Cu")
		(net "TDR_DIFF_85_NECK_IN5_DN")
	)
	(segment
		(start 483.746556 -157.812232)
		(end 484.01986 -159.362648)
		(width 0.1016)
		(layer "In13.Cu")
		(net "TDR_DIFF_85_NECK_IN5_DN")
	)
	(segment
		(start 483.99319 -170.374818)
		(end 483.826312 -170.612562)
		(width 0.1016)
		(layer "In13.Cu")
		(net "TDR_DIFF_85_NECK_IN5_DN")
	)
	(segment
		(start 473.683838 -174.054008)
		(end 483.452678 -172.331634)
		(width 0.1016)
		(layer "In13.Cu")
		(net "TDR_DIFF_85_NECK_IN5_DN")
	)
	(segment
		(start 483.719886 -168.824402)
		(end 483.99319 -170.374818)
		(width 0.1016)
		(layer "In13.Cu")
		(net "TDR_DIFF_85_NECK_IN5_DN")
	)
	(segment
		(start 483.827328 -166.943024)
		(end 473.432124 -168.775888)
		(width 0.1016)
		(layer "In13.Cu")
		(net "TDR_DIFF_85_NECK_IN5_DN")
	)
	(segment
		(start 473.322904 -165.228778)
		(end 473.570554 -166.632382)
		(width 0.1016)
		(layer "In13.Cu")
		(net "TDR_DIFF_85_NECK_IN5_DN")
	)
	(segment
		(start 483.96906 -163.040568)
		(end 483.802182 -163.278566)
		(width 0.1016)
		(layer "In13.Cu")
		(net "TDR_DIFF_85_NECK_IN5_DN")
	)
	(segment
		(start 483.449884 -153.986484)
		(end 483.76967 -154.21102)
		(width 0.1016)
		(layer "In13.Cu")
		(net "TDR_DIFF_85_NECK_IN5_DN")
	)
	(segment
		(start 473.56649 -173.971458)
		(end 473.683838 -174.054008)
		(width 0.1016)
		(layer "In13.Cu")
		(net "TDR_DIFF_85_NECK_IN5_DN")
	)
	(segment
		(start 473.440506 -157.76702)
		(end 473.357956 -157.884368)
		(width 0.1016)
		(layer "In13.Cu")
		(net "TDR_DIFF_85_NECK_IN5_DN")
	)
	(segment
		(start 473.601796 -177.6349)
		(end 473.723462 -177.720498)
		(width 0.1016)
		(layer "In13.Cu")
		(net "TDR_DIFF_85_NECK_IN5_DN")
	)
	(segment
		(start 479.087434 -190.856362)
		(end 488.872784 -189.131194)
		(width 0.1016)
		(layer "In11.Cu")
		(net "TDR_DIFF_85_NECK_IN4_DP")
	)
	(segment
		(start 489.191808 -198.428864)
		(end 478.796604 -200.261728)
		(width 0.1016)
		(layer "In11.Cu")
		(net "TDR_DIFF_85_NECK_IN4_DP")
	)
	(segment
		(start 484.02875 -186.200542)
		(end 484.160322 -186.293252)
		(width 0.1016)
		(layer "In11.Cu")
		(net "TDR_DIFF_85_NECK_IN4_DP")
	)
	(segment
		(start 489.38434 -190.848488)
		(end 489.217462 -191.086232)
		(width 0.1016)
		(layer "In11.Cu")
		(net "TDR_DIFF_85_NECK_IN4_DP")
	)
	(segment
		(start 484.160322 -186.293252)
		(end 488.814364 -185.472324)
		(width 0.1016)
		(layer "In11.Cu")
		(net "TDR_DIFF_85_NECK_IN4_DP")
	)
	(segment
		(start 489.085382 -196.640958)
		(end 489.358686 -198.191374)
		(width 0.1016)
		(layer "In11.Cu")
		(net "TDR_DIFF_85_NECK_IN4_DP")
	)
	(segment
		(start 489.166662 -194.764406)
		(end 478.769934 -196.59727)
		(width 0.1016)
		(layer "In11.Cu")
		(net "TDR_DIFF_85_NECK_IN4_DP")
	)
	(segment
		(start 489.217462 -191.086232)
		(end 478.802954 -192.922398)
		(width 0.1016)
		(layer "In11.Cu")
		(net "TDR_DIFF_85_NECK_IN4_DP")
	)
	(segment
		(start 478.769934 -196.59727)
		(end 478.687384 -196.714618)
		(width 0.1016)
		(layer "In11.Cu")
		(net "TDR_DIFF_85_NECK_IN4_DP")
	)
	(segment
		(start 489.111036 -189.298072)
		(end 489.38434 -190.848488)
		(width 0.1016)
		(layer "In11.Cu")
		(net "TDR_DIFF_85_NECK_IN4_DP")
	)
	(segment
		(start 488.846114 -200.143364)
		(end 489.084366 -200.310242)
		(width 0.1016)
		(layer "In11.Cu")
		(net "TDR_DIFF_85_NECK_IN4_DP")
	)
	(segment
		(start 489.382562 -187.106814)
		(end 489.159042 -187.427362)
		(width 0.1016)
		(layer "In11.Cu")
		(net "TDR_DIFF_85_NECK_IN4_DP")
	)
	(segment
		(start 478.720658 -193.039492)
		(end 478.968308 -194.443096)
		(width 0.1016)
		(layer "In11.Cu")
		(net "TDR_DIFF_85_NECK_IN4_DP")
	)
	(segment
		(start 489.161582 -205.772512)
		(end 478.800414 -207.59928)
		(width 0.1016)
		(layer "In11.Cu")
		(net "TDR_DIFF_85_NECK_IN4_DP")
	)
	(segment
		(start 478.687384 -196.714618)
		(end 478.935034 -198.118222)
		(width 0.1016)
		(layer "In11.Cu")
		(net "TDR_DIFF_85_NECK_IN4_DP")
	)
	(segment
		(start 484.023416 -210.905598)
		(end 484.13035 -211.012532)
		(width 0.1016)
		(layer "In11.Cu")
		(net "TDR_DIFF_85_NECK_IN4_DP")
	)
	(segment
		(start 478.846642 -190.072264)
		(end 478.970086 -190.773812)
		(width 0.1016)
		(layer "In11.Cu")
		(net "TDR_DIFF_85_NECK_IN4_DP")
	)
	(segment
		(start 485.20985 -184.609232)
		(end 484.15575 -184.609232)
		(width 0.1016)
		(layer "In11.Cu")
		(net "TDR_DIFF_85_NECK_IN4_DP")
	)
	(segment
		(start 478.68332 -204.053694)
		(end 478.93097 -205.457298)
		(width 0.1016)
		(layer "In11.Cu")
		(net "TDR_DIFF_85_NECK_IN4_DP")
	)
	(segment
		(start 478.800414 -207.59928)
		(end 478.717864 -207.716628)
		(width 0.1016)
		(layer "In11.Cu")
		(net "TDR_DIFF_85_NECK_IN4_DP")
	)
	(segment
		(start 489.358686 -198.191374)
		(end 489.191808 -198.428864)
		(width 0.1016)
		(layer "In11.Cu")
		(net "TDR_DIFF_85_NECK_IN4_DP")
	)
	(segment
		(start 478.935034 -198.118222)
		(end 479.052382 -198.200772)
		(width 0.1016)
		(layer "In11.Cu")
		(net "TDR_DIFF_85_NECK_IN4_DP")
	)
	(segment
		(start 488.846876 -196.47408)
		(end 489.085382 -196.640958)
		(width 0.1016)
		(layer "In11.Cu")
		(net "TDR_DIFF_85_NECK_IN4_DP")
	)
	(segment
		(start 478.961704 -201.78268)
		(end 479.079052 -201.86523)
		(width 0.1016)
		(layer "In11.Cu")
		(net "TDR_DIFF_85_NECK_IN4_DP")
	)
	(segment
		(start 488.872784 -189.131194)
		(end 489.111036 -189.298072)
		(width 0.1016)
		(layer "In11.Cu")
		(net "TDR_DIFF_85_NECK_IN4_DP")
	)
	(segment
		(start 484.02875 -184.736232)
		(end 484.02875 -186.200542)
		(width 0.1016)
		(layer "In11.Cu")
		(net "TDR_DIFF_85_NECK_IN4_DP")
	)
	(segment
		(start 478.846388 -190.072264)
		(end 478.846642 -190.072264)
		(width 0.1016)
		(layer "In11.Cu")
		(net "TDR_DIFF_85_NECK_IN4_DP")
	)
	(segment
		(start 478.970086 -190.773812)
		(end 479.087434 -190.856362)
		(width 0.1016)
		(layer "In11.Cu")
		(net "TDR_DIFF_85_NECK_IN4_DP")
	)
	(segment
		(start 479.052382 -198.200772)
		(end 488.846876 -196.47408)
		(width 0.1016)
		(layer "In11.Cu")
		(net "TDR_DIFF_85_NECK_IN4_DP")
	)
	(segment
		(start 484.15575 -184.609232)
		(end 484.02875 -184.736232)
		(width 0.1016)
		(layer "In11.Cu")
		(net "TDR_DIFF_85_NECK_IN4_DP")
	)
	(segment
		(start 484.13035 -211.012532)
		(end 485.20985 -211.012532)
		(width 0.1016)
		(layer "In11.Cu")
		(net "TDR_DIFF_85_NECK_IN4_DP")
	)
	(segment
		(start 479.087942 -209.206338)
		(end 483.792022 -208.376774)
		(width 0.1016)
		(layer "In11.Cu")
		(net "TDR_DIFF_85_NECK_IN4_DP")
	)
	(segment
		(start 484.023416 -208.60766)
		(end 484.023416 -210.905598)
		(width 0.1016)
		(layer "In11.Cu")
		(net "TDR_DIFF_85_NECK_IN4_DP")
	)
	(segment
		(start 489.35767 -201.860658)
		(end 489.190792 -202.098402)
		(width 0.1016)
		(layer "In11.Cu")
		(net "TDR_DIFF_85_NECK_IN4_DP")
	)
	(segment
		(start 478.717864 -207.716628)
		(end 478.965514 -209.120232)
		(width 0.1016)
		(layer "In11.Cu")
		(net "TDR_DIFF_85_NECK_IN4_DP")
	)
	(segment
		(start 478.76587 -203.936346)
		(end 478.68332 -204.053694)
		(width 0.1016)
		(layer "In11.Cu")
		(net "TDR_DIFF_85_NECK_IN4_DP")
	)
	(segment
		(start 479.08591 -194.525646)
		(end 488.821984 -192.809114)
		(width 0.1016)
		(layer "In11.Cu")
		(net "TDR_DIFF_85_NECK_IN4_DP")
	)
	(segment
		(start 488.817158 -203.817474)
		(end 489.055156 -203.984352)
		(width 0.1016)
		(layer "In11.Cu")
		(net "TDR_DIFF_85_NECK_IN4_DP")
	)
	(segment
		(start 489.060236 -192.975992)
		(end 489.33354 -194.526408)
		(width 0.1016)
		(layer "In11.Cu")
		(net "TDR_DIFF_85_NECK_IN4_DP")
	)
	(segment
		(start 478.804986 -189.25286)
		(end 478.722436 -189.370208)
		(width 0.1016)
		(layer "In11.Cu")
		(net "TDR_DIFF_85_NECK_IN4_DP")
	)
	(segment
		(start 478.965514 -209.120232)
		(end 478.966276 -209.12074)
		(width 0.1016)
		(layer "In11.Cu")
		(net "TDR_DIFF_85_NECK_IN4_DP")
	)
	(segment
		(start 488.814364 -185.472324)
		(end 489.13415 -185.69686)
		(width 0.1016)
		(layer "In11.Cu")
		(net "TDR_DIFF_85_NECK_IN4_DP")
	)
	(segment
		(start 483.792022 -208.376774)
		(end 484.023416 -208.60766)
		(width 0.1016)
		(layer "In11.Cu")
		(net "TDR_DIFF_85_NECK_IN4_DP")
	)
	(segment
		(start 489.084366 -200.310242)
		(end 489.35767 -201.860658)
		(width 0.1016)
		(layer "In11.Cu")
		(net "TDR_DIFF_85_NECK_IN4_DP")
	)
	(segment
		(start 478.722436 -189.370208)
		(end 478.846388 -190.072264)
		(width 0.1016)
		(layer "In11.Cu")
		(net "TDR_DIFF_85_NECK_IN4_DP")
	)
	(segment
		(start 488.821984 -192.809114)
		(end 489.060236 -192.975992)
		(width 0.1016)
		(layer "In11.Cu")
		(net "TDR_DIFF_85_NECK_IN4_DP")
	)
	(segment
		(start 489.33354 -194.526408)
		(end 489.166662 -194.764406)
		(width 0.1016)
		(layer "In11.Cu")
		(net "TDR_DIFF_85_NECK_IN4_DP")
	)
	(segment
		(start 489.055156 -203.984352)
		(end 489.32846 -205.534768)
		(width 0.1016)
		(layer "In11.Cu")
		(net "TDR_DIFF_85_NECK_IN4_DP")
	)
	(segment
		(start 479.079052 -201.86523)
		(end 488.846114 -200.143364)
		(width 0.1016)
		(layer "In11.Cu")
		(net "TDR_DIFF_85_NECK_IN4_DP")
	)
	(segment
		(start 489.190792 -202.098402)
		(end 478.76587 -203.936346)
		(width 0.1016)
		(layer "In11.Cu")
		(net "TDR_DIFF_85_NECK_IN4_DP")
	)
	(segment
		(start 489.13415 -185.69686)
		(end 489.382562 -187.106814)
		(width 0.1016)
		(layer "In11.Cu")
		(net "TDR_DIFF_85_NECK_IN4_DP")
	)
	(segment
		(start 489.159042 -187.427362)
		(end 478.804986 -189.25286)
		(width 0.1016)
		(layer "In11.Cu")
		(net "TDR_DIFF_85_NECK_IN4_DP")
	)
	(segment
		(start 478.968308 -194.443096)
		(end 479.08591 -194.525646)
		(width 0.1016)
		(layer "In11.Cu")
		(net "TDR_DIFF_85_NECK_IN4_DP")
	)
	(segment
		(start 478.802954 -192.922398)
		(end 478.720658 -193.039492)
		(width 0.1016)
		(layer "In11.Cu")
		(net "TDR_DIFF_85_NECK_IN4_DP")
	)
	(segment
		(start 478.966276 -209.12074)
		(end 479.087942 -209.206338)
		(width 0.1016)
		(layer "In11.Cu")
		(net "TDR_DIFF_85_NECK_IN4_DP")
	)
	(segment
		(start 489.32846 -205.534768)
		(end 489.161582 -205.772512)
		(width 0.1016)
		(layer "In11.Cu")
		(net "TDR_DIFF_85_NECK_IN4_DP")
	)
	(segment
		(start 478.796604 -200.261728)
		(end 478.714054 -200.379076)
		(width 0.1016)
		(layer "In11.Cu")
		(net "TDR_DIFF_85_NECK_IN4_DP")
	)
	(segment
		(start 478.93097 -205.457298)
		(end 479.048318 -205.539848)
		(width 0.1016)
		(layer "In11.Cu")
		(net "TDR_DIFF_85_NECK_IN4_DP")
	)
	(segment
		(start 479.048318 -205.539848)
		(end 488.817158 -203.817474)
		(width 0.1016)
		(layer "In11.Cu")
		(net "TDR_DIFF_85_NECK_IN4_DP")
	)
	(segment
		(start 478.714054 -200.379076)
		(end 478.961704 -201.78268)
		(width 0.1016)
		(layer "In11.Cu")
		(net "TDR_DIFF_85_NECK_IN4_DP")
	)
	(segment
		(start 478.666556 -196.43471)
		(end 478.499424 -196.672708)
		(width 0.1016)
		(layer "In11.Cu")
		(net "TDR_DIFF_85_NECK_IN4_DN")
	)
	(segment
		(start 478.49536 -204.011784)
		(end 478.76841 -205.560676)
		(width 0.1016)
		(layer "In11.Cu")
		(net "TDR_DIFF_85_NECK_IN4_DN")
	)
	(segment
		(start 483.731824 -208.568036)
		(end 483.845616 -208.681574)
		(width 0.1016)
		(layer "In11.Cu")
		(net "TDR_DIFF_85_NECK_IN4_DN")
	)
	(segment
		(start 478.662492 -203.773786)
		(end 478.49536 -204.011784)
		(width 0.1016)
		(layer "In11.Cu")
		(net "TDR_DIFF_85_NECK_IN4_DN")
	)
	(segment
		(start 489.169456 -201.818748)
		(end 489.087414 -201.935842)
		(width 0.1016)
		(layer "In11.Cu")
		(net "TDR_DIFF_85_NECK_IN4_DN")
	)
	(segment
		(start 489.14558 -194.484752)
		(end 489.063284 -194.601846)
		(width 0.1016)
		(layer "In11.Cu")
		(net "TDR_DIFF_85_NECK_IN4_DN")
	)
	(segment
		(start 483.74935 -184.609232)
		(end 483.85095 -184.710832)
		(width 0.1016)
		(layer "In11.Cu")
		(net "TDR_DIFF_85_NECK_IN4_DN")
	)
	(segment
		(start 489.08843 -198.266304)
		(end 478.693226 -200.099168)
		(width 0.1016)
		(layer "In11.Cu")
		(net "TDR_DIFF_85_NECK_IN4_DN")
	)
	(segment
		(start 479.045524 -191.044322)
		(end 488.831128 -189.319154)
		(width 0.1016)
		(layer "In11.Cu")
		(net "TDR_DIFF_85_NECK_IN4_DN")
	)
	(segment
		(start 488.804458 -200.331324)
		(end 488.921806 -200.413874)
		(width 0.1016)
		(layer "In11.Cu")
		(net "TDR_DIFF_85_NECK_IN4_DN")
	)
	(segment
		(start 488.948476 -189.401704)
		(end 489.196126 -190.806578)
		(width 0.1016)
		(layer "In11.Cu")
		(net "TDR_DIFF_85_NECK_IN4_DN")
	)
	(segment
		(start 478.529904 -207.674718)
		(end 478.802954 -209.223864)
		(width 0.1016)
		(layer "In11.Cu")
		(net "TDR_DIFF_85_NECK_IN4_DN")
	)
	(segment
		(start 479.046032 -209.394298)
		(end 483.731824 -208.568036)
		(width 0.1016)
		(layer "In11.Cu")
		(net "TDR_DIFF_85_NECK_IN4_DN")
	)
	(segment
		(start 488.921806 -200.413874)
		(end 489.169456 -201.818748)
		(width 0.1016)
		(layer "In11.Cu")
		(net "TDR_DIFF_85_NECK_IN4_DN")
	)
	(segment
		(start 478.86366 -209.266536)
		(end 478.863914 -209.266282)
		(width 0.1016)
		(layer "In11.Cu")
		(net "TDR_DIFF_85_NECK_IN4_DN")
	)
	(segment
		(start 489.114084 -190.923672)
		(end 478.699576 -192.759838)
		(width 0.1016)
		(layer "In11.Cu")
		(net "TDR_DIFF_85_NECK_IN4_DN")
	)
	(segment
		(start 478.701354 -189.0903)
		(end 478.534476 -189.328552)
		(width 0.1016)
		(layer "In11.Cu")
		(net "TDR_DIFF_85_NECK_IN4_DN")
	)
	(segment
		(start 488.892596 -204.08773)
		(end 489.140246 -205.492858)
		(width 0.1016)
		(layer "In11.Cu")
		(net "TDR_DIFF_85_NECK_IN4_DN")
	)
	(segment
		(start 489.087414 -201.935842)
		(end 478.662492 -203.773786)
		(width 0.1016)
		(layer "In11.Cu")
		(net "TDR_DIFF_85_NECK_IN4_DN")
	)
	(segment
		(start 478.802954 -209.223864)
		(end 478.86366 -209.266536)
		(width 0.1016)
		(layer "In11.Cu")
		(net "TDR_DIFF_85_NECK_IN4_DN")
	)
	(segment
		(start 478.863914 -209.266282)
		(end 479.046032 -209.394298)
		(width 0.1016)
		(layer "In11.Cu")
		(net "TDR_DIFF_85_NECK_IN4_DN")
	)
	(segment
		(start 488.80522 -196.66204)
		(end 488.922822 -196.74459)
		(width 0.1016)
		(layer "In11.Cu")
		(net "TDR_DIFF_85_NECK_IN4_DN")
	)
	(segment
		(start 478.697036 -207.43672)
		(end 478.529904 -207.674718)
		(width 0.1016)
		(layer "In11.Cu")
		(net "TDR_DIFF_85_NECK_IN4_DN")
	)
	(segment
		(start 483.85095 -184.710832)
		(end 483.85095 -186.292998)
		(width 0.1016)
		(layer "In11.Cu")
		(net "TDR_DIFF_85_NECK_IN4_DN")
	)
	(segment
		(start 488.831128 -189.319154)
		(end 488.948476 -189.401704)
		(width 0.1016)
		(layer "In11.Cu")
		(net "TDR_DIFF_85_NECK_IN4_DN")
	)
	(segment
		(start 489.194602 -187.065412)
		(end 489.05541 -187.265056)
		(width 0.1016)
		(layer "In11.Cu")
		(net "TDR_DIFF_85_NECK_IN4_DN")
	)
	(segment
		(start 483.845616 -210.916266)
		(end 483.74935 -211.012532)
		(width 0.1016)
		(layer "In11.Cu")
		(net "TDR_DIFF_85_NECK_IN4_DN")
	)
	(segment
		(start 478.526094 -200.337166)
		(end 478.799144 -201.886058)
		(width 0.1016)
		(layer "In11.Cu")
		(net "TDR_DIFF_85_NECK_IN4_DN")
	)
	(segment
		(start 479.044 -194.71386)
		(end 488.780328 -192.997074)
		(width 0.1016)
		(layer "In11.Cu")
		(net "TDR_DIFF_85_NECK_IN4_DN")
	)
	(segment
		(start 483.85095 -186.292998)
		(end 484.118412 -186.481212)
		(width 0.1016)
		(layer "In11.Cu")
		(net "TDR_DIFF_85_NECK_IN4_DN")
	)
	(segment
		(start 478.772474 -198.2216)
		(end 479.010472 -198.388732)
		(width 0.1016)
		(layer "In11.Cu")
		(net "TDR_DIFF_85_NECK_IN4_DN")
	)
	(segment
		(start 478.532698 -192.997582)
		(end 478.805748 -194.546474)
		(width 0.1016)
		(layer "In11.Cu")
		(net "TDR_DIFF_85_NECK_IN4_DN")
	)
	(segment
		(start 478.799144 -201.886058)
		(end 479.037142 -202.05319)
		(width 0.1016)
		(layer "In11.Cu")
		(net "TDR_DIFF_85_NECK_IN4_DN")
	)
	(segment
		(start 478.76841 -205.560676)
		(end 479.006408 -205.727808)
		(width 0.1016)
		(layer "In11.Cu")
		(net "TDR_DIFF_85_NECK_IN4_DN")
	)
	(segment
		(start 489.05541 -187.265056)
		(end 478.701354 -189.0903)
		(width 0.1016)
		(layer "In11.Cu")
		(net "TDR_DIFF_85_NECK_IN4_DN")
	)
	(segment
		(start 489.170726 -198.149464)
		(end 489.08843 -198.266304)
		(width 0.1016)
		(layer "In11.Cu")
		(net "TDR_DIFF_85_NECK_IN4_DN")
	)
	(segment
		(start 478.807526 -190.87719)
		(end 479.045524 -191.044322)
		(width 0.1016)
		(layer "In11.Cu")
		(net "TDR_DIFF_85_NECK_IN4_DN")
	)
	(segment
		(start 478.534476 -189.328552)
		(end 478.807526 -190.87719)
		(width 0.1016)
		(layer "In11.Cu")
		(net "TDR_DIFF_85_NECK_IN4_DN")
	)
	(segment
		(start 489.058204 -205.609952)
		(end 478.697036 -207.43672)
		(width 0.1016)
		(layer "In11.Cu")
		(net "TDR_DIFF_85_NECK_IN4_DN")
	)
	(segment
		(start 478.699576 -192.759838)
		(end 478.532698 -192.997582)
		(width 0.1016)
		(layer "In11.Cu")
		(net "TDR_DIFF_85_NECK_IN4_DN")
	)
	(segment
		(start 488.922822 -196.74459)
		(end 489.170726 -198.149464)
		(width 0.1016)
		(layer "In11.Cu")
		(net "TDR_DIFF_85_NECK_IN4_DN")
	)
	(segment
		(start 482.66985 -184.609232)
		(end 483.74935 -184.609232)
		(width 0.1016)
		(layer "In11.Cu")
		(net "TDR_DIFF_85_NECK_IN4_DN")
	)
	(segment
		(start 483.845616 -208.681574)
		(end 483.845616 -210.916266)
		(width 0.1016)
		(layer "In11.Cu")
		(net "TDR_DIFF_85_NECK_IN4_DN")
	)
	(segment
		(start 488.97159 -185.800238)
		(end 489.194602 -187.065412)
		(width 0.1016)
		(layer "In11.Cu")
		(net "TDR_DIFF_85_NECK_IN4_DN")
	)
	(segment
		(start 479.006408 -205.727808)
		(end 488.775502 -204.005434)
		(width 0.1016)
		(layer "In11.Cu")
		(net "TDR_DIFF_85_NECK_IN4_DN")
	)
	(segment
		(start 483.74935 -211.012532)
		(end 482.66985 -211.012532)
		(width 0.1016)
		(layer "In11.Cu")
		(net "TDR_DIFF_85_NECK_IN4_DN")
	)
	(segment
		(start 478.693226 -200.099168)
		(end 478.526094 -200.337166)
		(width 0.1016)
		(layer "In11.Cu")
		(net "TDR_DIFF_85_NECK_IN4_DN")
	)
	(segment
		(start 478.805748 -194.546474)
		(end 479.044 -194.71386)
		(width 0.1016)
		(layer "In11.Cu")
		(net "TDR_DIFF_85_NECK_IN4_DN")
	)
	(segment
		(start 488.772454 -185.660538)
		(end 488.97159 -185.800238)
		(width 0.1016)
		(layer "In11.Cu")
		(net "TDR_DIFF_85_NECK_IN4_DN")
	)
	(segment
		(start 489.063284 -194.601846)
		(end 478.666556 -196.43471)
		(width 0.1016)
		(layer "In11.Cu")
		(net "TDR_DIFF_85_NECK_IN4_DN")
	)
	(segment
		(start 489.196126 -190.806578)
		(end 489.114084 -190.923672)
		(width 0.1016)
		(layer "In11.Cu")
		(net "TDR_DIFF_85_NECK_IN4_DN")
	)
	(segment
		(start 479.037142 -202.05319)
		(end 488.804458 -200.331324)
		(width 0.1016)
		(layer "In11.Cu")
		(net "TDR_DIFF_85_NECK_IN4_DN")
	)
	(segment
		(start 489.140246 -205.492858)
		(end 489.058204 -205.609952)
		(width 0.1016)
		(layer "In11.Cu")
		(net "TDR_DIFF_85_NECK_IN4_DN")
	)
	(segment
		(start 478.499424 -196.672708)
		(end 478.772474 -198.2216)
		(width 0.1016)
		(layer "In11.Cu")
		(net "TDR_DIFF_85_NECK_IN4_DN")
	)
	(segment
		(start 479.010472 -198.388732)
		(end 488.80522 -196.66204)
		(width 0.1016)
		(layer "In11.Cu")
		(net "TDR_DIFF_85_NECK_IN4_DN")
	)
	(segment
		(start 484.118412 -186.481212)
		(end 488.772454 -185.660538)
		(width 0.1016)
		(layer "In11.Cu")
		(net "TDR_DIFF_85_NECK_IN4_DN")
	)
	(segment
		(start 488.780328 -192.997074)
		(end 488.897676 -193.079624)
		(width 0.1016)
		(layer "In11.Cu")
		(net "TDR_DIFF_85_NECK_IN4_DN")
	)
	(segment
		(start 488.775502 -204.005434)
		(end 488.892596 -204.08773)
		(width 0.1016)
		(layer "In11.Cu")
		(net "TDR_DIFF_85_NECK_IN4_DN")
	)
	(segment
		(start 488.897676 -193.079624)
		(end 489.14558 -194.484752)
		(width 0.1016)
		(layer "In11.Cu")
		(net "TDR_DIFF_85_NECK_IN4_DN")
	)
	(segment
		(start 473.482162 -127.103124)
		(end 473.605606 -127.804672)
		(width 0.1016)
		(layer "In6.Cu")
		(net "TDR_DIFF_85_NECK_IN3_DP")
	)
	(segment
		(start 473.597224 -138.81354)
		(end 473.714572 -138.89609)
		(width 0.1016)
		(layer "In6.Cu")
		(net "TDR_DIFF_85_NECK_IN3_DP")
	)
	(segment
		(start 473.723462 -146.237198)
		(end 478.427542 -145.407634)
		(width 0.1016)
		(layer "In6.Cu")
		(net "TDR_DIFF_85_NECK_IN3_DP")
	)
	(segment
		(start 473.357956 -126.401068)
		(end 473.481908 -127.103124)
		(width 0.1016)
		(layer "In6.Cu")
		(net "TDR_DIFF_85_NECK_IN3_DP")
	)
	(segment
		(start 473.683838 -142.570708)
		(end 483.452678 -140.848334)
		(width 0.1016)
		(layer "In6.Cu")
		(net "TDR_DIFF_85_NECK_IN3_DP")
	)
	(segment
		(start 478.795842 -123.324112)
		(end 483.449884 -122.503184)
		(width 0.1016)
		(layer "In6.Cu")
		(net "TDR_DIFF_85_NECK_IN3_DP")
	)
	(segment
		(start 473.601796 -146.1516)
		(end 473.723462 -146.237198)
		(width 0.1016)
		(layer "In6.Cu")
		(net "TDR_DIFF_85_NECK_IN3_DP")
	)
	(segment
		(start 473.72143 -131.556506)
		(end 483.457504 -129.839974)
		(width 0.1016)
		(layer "In6.Cu")
		(net "TDR_DIFF_85_NECK_IN3_DP")
	)
	(segment
		(start 483.99319 -138.891518)
		(end 483.826312 -139.129262)
		(width 0.1016)
		(layer "In6.Cu")
		(net "TDR_DIFF_85_NECK_IN3_DP")
	)
	(segment
		(start 473.356178 -130.070352)
		(end 473.603828 -131.473956)
		(width 0.1016)
		(layer "In6.Cu")
		(net "TDR_DIFF_85_NECK_IN3_DP")
	)
	(segment
		(start 483.481634 -137.174224)
		(end 483.719886 -137.341102)
		(width 0.1016)
		(layer "In6.Cu")
		(net "TDR_DIFF_85_NECK_IN3_DP")
	)
	(segment
		(start 478.427542 -145.407634)
		(end 478.658936 -145.63852)
		(width 0.1016)
		(layer "In6.Cu")
		(net "TDR_DIFF_85_NECK_IN3_DP")
	)
	(segment
		(start 473.687902 -135.231632)
		(end 483.482396 -133.50494)
		(width 0.1016)
		(layer "In6.Cu")
		(net "TDR_DIFF_85_NECK_IN3_DP")
	)
	(segment
		(start 473.714572 -138.89609)
		(end 483.481634 -137.174224)
		(width 0.1016)
		(layer "In6.Cu")
		(net "TDR_DIFF_85_NECK_IN3_DP")
	)
	(segment
		(start 483.802182 -131.795266)
		(end 473.405454 -133.62813)
		(width 0.1016)
		(layer "In6.Cu")
		(net "TDR_DIFF_85_NECK_IN3_DP")
	)
	(segment
		(start 473.56649 -142.488158)
		(end 473.683838 -142.570708)
		(width 0.1016)
		(layer "In6.Cu")
		(net "TDR_DIFF_85_NECK_IN3_DP")
	)
	(segment
		(start 473.722954 -127.887222)
		(end 483.508304 -126.162054)
		(width 0.1016)
		(layer "In6.Cu")
		(net "TDR_DIFF_85_NECK_IN3_DP")
	)
	(segment
		(start 473.349574 -137.409936)
		(end 473.597224 -138.81354)
		(width 0.1016)
		(layer "In6.Cu")
		(net "TDR_DIFF_85_NECK_IN3_DP")
	)
	(segment
		(start 473.570554 -135.149082)
		(end 473.687902 -135.231632)
		(width 0.1016)
		(layer "In6.Cu")
		(net "TDR_DIFF_85_NECK_IN3_DP")
	)
	(segment
		(start 483.720902 -133.671818)
		(end 483.994206 -135.222234)
		(width 0.1016)
		(layer "In6.Cu")
		(net "TDR_DIFF_85_NECK_IN3_DP")
	)
	(segment
		(start 483.794562 -124.458222)
		(end 473.440506 -126.28372)
		(width 0.1016)
		(layer "In6.Cu")
		(net "TDR_DIFF_85_NECK_IN3_DP")
	)
	(segment
		(start 483.482396 -133.50494)
		(end 483.720902 -133.671818)
		(width 0.1016)
		(layer "In6.Cu")
		(net "TDR_DIFF_85_NECK_IN3_DP")
	)
	(segment
		(start 483.827328 -135.459724)
		(end 473.432124 -137.292588)
		(width 0.1016)
		(layer "In6.Cu")
		(net "TDR_DIFF_85_NECK_IN3_DP")
	)
	(segment
		(start 473.40139 -140.967206)
		(end 473.31884 -141.084554)
		(width 0.1016)
		(layer "In6.Cu")
		(net "TDR_DIFF_85_NECK_IN3_DP")
	)
	(segment
		(start 473.435934 -144.63014)
		(end 473.353384 -144.747488)
		(width 0.1016)
		(layer "In6.Cu")
		(net "TDR_DIFF_85_NECK_IN3_DP")
	)
	(segment
		(start 473.481908 -127.103124)
		(end 473.482162 -127.103124)
		(width 0.1016)
		(layer "In6.Cu")
		(net "TDR_DIFF_85_NECK_IN3_DP")
	)
	(segment
		(start 483.452678 -140.848334)
		(end 483.690676 -141.015212)
		(width 0.1016)
		(layer "In6.Cu")
		(net "TDR_DIFF_85_NECK_IN3_DP")
	)
	(segment
		(start 483.96398 -142.565628)
		(end 483.797102 -142.803372)
		(width 0.1016)
		(layer "In6.Cu")
		(net "TDR_DIFF_85_NECK_IN3_DP")
	)
	(segment
		(start 473.603828 -131.473956)
		(end 473.72143 -131.556506)
		(width 0.1016)
		(layer "In6.Cu")
		(net "TDR_DIFF_85_NECK_IN3_DP")
	)
	(segment
		(start 473.440506 -126.28372)
		(end 473.357956 -126.401068)
		(width 0.1016)
		(layer "In6.Cu")
		(net "TDR_DIFF_85_NECK_IN3_DP")
	)
	(segment
		(start 483.719886 -137.341102)
		(end 483.99319 -138.891518)
		(width 0.1016)
		(layer "In6.Cu")
		(net "TDR_DIFF_85_NECK_IN3_DP")
	)
	(segment
		(start 483.457504 -129.839974)
		(end 483.695756 -130.006852)
		(width 0.1016)
		(layer "In6.Cu")
		(net "TDR_DIFF_85_NECK_IN3_DP")
	)
	(segment
		(start 473.405454 -133.62813)
		(end 473.322904 -133.745478)
		(width 0.1016)
		(layer "In6.Cu")
		(net "TDR_DIFF_85_NECK_IN3_DP")
	)
	(segment
		(start 473.601034 -146.151092)
		(end 473.601796 -146.1516)
		(width 0.1016)
		(layer "In6.Cu")
		(net "TDR_DIFF_85_NECK_IN3_DP")
	)
	(segment
		(start 483.826312 -139.129262)
		(end 473.40139 -140.967206)
		(width 0.1016)
		(layer "In6.Cu")
		(net "TDR_DIFF_85_NECK_IN3_DP")
	)
	(segment
		(start 478.658936 -145.63852)
		(end 478.658936 -147.936458)
		(width 0.1016)
		(layer "In6.Cu")
		(net "TDR_DIFF_85_NECK_IN3_DP")
	)
	(segment
		(start 473.605606 -127.804672)
		(end 473.722954 -127.887222)
		(width 0.1016)
		(layer "In6.Cu")
		(net "TDR_DIFF_85_NECK_IN3_DP")
	)
	(segment
		(start 483.852982 -128.117092)
		(end 473.438474 -129.953258)
		(width 0.1016)
		(layer "In6.Cu")
		(net "TDR_DIFF_85_NECK_IN3_DP")
	)
	(segment
		(start 473.438474 -129.953258)
		(end 473.356178 -130.070352)
		(width 0.1016)
		(layer "In6.Cu")
		(net "TDR_DIFF_85_NECK_IN3_DP")
	)
	(segment
		(start 478.66427 -121.767092)
		(end 478.66427 -123.231402)
		(width 0.1016)
		(layer "In6.Cu")
		(net "TDR_DIFF_85_NECK_IN3_DP")
	)
	(segment
		(start 483.508304 -126.162054)
		(end 483.746556 -126.328932)
		(width 0.1016)
		(layer "In6.Cu")
		(net "TDR_DIFF_85_NECK_IN3_DP")
	)
	(segment
		(start 483.695756 -130.006852)
		(end 483.96906 -131.557268)
		(width 0.1016)
		(layer "In6.Cu")
		(net "TDR_DIFF_85_NECK_IN3_DP")
	)
	(segment
		(start 483.449884 -122.503184)
		(end 483.76967 -122.72772)
		(width 0.1016)
		(layer "In6.Cu")
		(net "TDR_DIFF_85_NECK_IN3_DP")
	)
	(segment
		(start 483.797102 -142.803372)
		(end 473.435934 -144.63014)
		(width 0.1016)
		(layer "In6.Cu")
		(net "TDR_DIFF_85_NECK_IN3_DP")
	)
	(segment
		(start 473.353384 -144.747488)
		(end 473.601034 -146.151092)
		(width 0.1016)
		(layer "In6.Cu")
		(net "TDR_DIFF_85_NECK_IN3_DP")
	)
	(segment
		(start 473.322904 -133.745478)
		(end 473.570554 -135.149082)
		(width 0.1016)
		(layer "In6.Cu")
		(net "TDR_DIFF_85_NECK_IN3_DP")
	)
	(segment
		(start 483.690676 -141.015212)
		(end 483.96398 -142.565628)
		(width 0.1016)
		(layer "In6.Cu")
		(net "TDR_DIFF_85_NECK_IN3_DP")
	)
	(segment
		(start 478.79127 -121.640092)
		(end 478.66427 -121.767092)
		(width 0.1016)
		(layer "In6.Cu")
		(net "TDR_DIFF_85_NECK_IN3_DP")
	)
	(segment
		(start 473.432124 -137.292588)
		(end 473.349574 -137.409936)
		(width 0.1016)
		(layer "In6.Cu")
		(net "TDR_DIFF_85_NECK_IN3_DP")
	)
	(segment
		(start 483.76967 -122.72772)
		(end 484.018082 -124.137674)
		(width 0.1016)
		(layer "In6.Cu")
		(net "TDR_DIFF_85_NECK_IN3_DP")
	)
	(segment
		(start 483.746556 -126.328932)
		(end 484.01986 -127.879348)
		(width 0.1016)
		(layer "In6.Cu")
		(net "TDR_DIFF_85_NECK_IN3_DP")
	)
	(segment
		(start 478.76587 -148.043392)
		(end 479.84537 -148.043392)
		(width 0.1016)
		(layer "In6.Cu")
		(net "TDR_DIFF_85_NECK_IN3_DP")
	)
	(segment
		(start 478.658936 -147.936458)
		(end 478.76587 -148.043392)
		(width 0.1016)
		(layer "In6.Cu")
		(net "TDR_DIFF_85_NECK_IN3_DP")
	)
	(segment
		(start 483.994206 -135.222234)
		(end 483.827328 -135.459724)
		(width 0.1016)
		(layer "In6.Cu")
		(net "TDR_DIFF_85_NECK_IN3_DP")
	)
	(segment
		(start 484.018082 -124.137674)
		(end 483.794562 -124.458222)
		(width 0.1016)
		(layer "In6.Cu")
		(net "TDR_DIFF_85_NECK_IN3_DP")
	)
	(segment
		(start 478.66427 -123.231402)
		(end 478.795842 -123.324112)
		(width 0.1016)
		(layer "In6.Cu")
		(net "TDR_DIFF_85_NECK_IN3_DP")
	)
	(segment
		(start 484.01986 -127.879348)
		(end 483.852982 -128.117092)
		(width 0.1016)
		(layer "In6.Cu")
		(net "TDR_DIFF_85_NECK_IN3_DP")
	)
	(segment
		(start 473.31884 -141.084554)
		(end 473.56649 -142.488158)
		(width 0.1016)
		(layer "In6.Cu")
		(net "TDR_DIFF_85_NECK_IN3_DP")
	)
	(segment
		(start 479.84537 -121.640092)
		(end 478.79127 -121.640092)
		(width 0.1016)
		(layer "In6.Cu")
		(net "TDR_DIFF_85_NECK_IN3_DP")
	)
	(segment
		(start 483.96906 -131.557268)
		(end 483.802182 -131.795266)
		(width 0.1016)
		(layer "In6.Cu")
		(net "TDR_DIFF_85_NECK_IN3_DP")
	)
	(segment
		(start 483.44074 -133.6929)
		(end 483.558342 -133.77545)
		(width 0.1016)
		(layer "In6.Cu")
		(net "TDR_DIFF_85_NECK_IN3_DN")
	)
	(segment
		(start 483.831646 -127.837438)
		(end 483.749604 -127.954532)
		(width 0.1016)
		(layer "In6.Cu")
		(net "TDR_DIFF_85_NECK_IN3_DN")
	)
	(segment
		(start 478.481136 -147.947126)
		(end 478.38487 -148.043392)
		(width 0.1016)
		(layer "In6.Cu")
		(net "TDR_DIFF_85_NECK_IN3_DN")
	)
	(segment
		(start 477.30537 -121.640092)
		(end 478.38487 -121.640092)
		(width 0.1016)
		(layer "In6.Cu")
		(net "TDR_DIFF_85_NECK_IN3_DN")
	)
	(segment
		(start 473.169996 -126.359412)
		(end 473.443046 -127.90805)
		(width 0.1016)
		(layer "In6.Cu")
		(net "TDR_DIFF_85_NECK_IN3_DN")
	)
	(segment
		(start 483.583996 -126.432564)
		(end 483.831646 -127.837438)
		(width 0.1016)
		(layer "In6.Cu")
		(net "TDR_DIFF_85_NECK_IN3_DN")
	)
	(segment
		(start 473.641928 -142.758668)
		(end 483.411022 -141.036294)
		(width 0.1016)
		(layer "In6.Cu")
		(net "TDR_DIFF_85_NECK_IN3_DN")
	)
	(segment
		(start 483.72395 -135.297164)
		(end 473.328746 -137.130028)
		(width 0.1016)
		(layer "In6.Cu")
		(net "TDR_DIFF_85_NECK_IN3_DN")
	)
	(segment
		(start 483.415848 -130.027934)
		(end 483.533196 -130.110484)
		(width 0.1016)
		(layer "In6.Cu")
		(net "TDR_DIFF_85_NECK_IN3_DN")
	)
	(segment
		(start 473.407994 -135.25246)
		(end 473.645992 -135.419592)
		(width 0.1016)
		(layer "In6.Cu")
		(net "TDR_DIFF_85_NECK_IN3_DN")
	)
	(segment
		(start 473.328746 -137.130028)
		(end 473.161614 -137.368026)
		(width 0.1016)
		(layer "In6.Cu")
		(net "TDR_DIFF_85_NECK_IN3_DN")
	)
	(segment
		(start 483.557326 -137.444734)
		(end 483.804976 -138.849608)
		(width 0.1016)
		(layer "In6.Cu")
		(net "TDR_DIFF_85_NECK_IN3_DN")
	)
	(segment
		(start 473.443046 -127.90805)
		(end 473.681044 -128.075182)
		(width 0.1016)
		(layer "In6.Cu")
		(net "TDR_DIFF_85_NECK_IN3_DN")
	)
	(segment
		(start 483.693724 -142.640812)
		(end 473.332556 -144.46758)
		(width 0.1016)
		(layer "In6.Cu")
		(net "TDR_DIFF_85_NECK_IN3_DN")
	)
	(segment
		(start 473.645992 -135.419592)
		(end 483.44074 -133.6929)
		(width 0.1016)
		(layer "In6.Cu")
		(net "TDR_DIFF_85_NECK_IN3_DN")
	)
	(segment
		(start 478.38487 -148.043392)
		(end 477.30537 -148.043392)
		(width 0.1016)
		(layer "In6.Cu")
		(net "TDR_DIFF_85_NECK_IN3_DN")
	)
	(segment
		(start 478.753932 -123.512072)
		(end 483.407974 -122.691398)
		(width 0.1016)
		(layer "In6.Cu")
		(net "TDR_DIFF_85_NECK_IN3_DN")
	)
	(segment
		(start 473.134944 -133.703568)
		(end 473.407994 -135.25246)
		(width 0.1016)
		(layer "In6.Cu")
		(net "TDR_DIFF_85_NECK_IN3_DN")
	)
	(segment
		(start 483.69093 -124.295916)
		(end 473.336874 -126.12116)
		(width 0.1016)
		(layer "In6.Cu")
		(net "TDR_DIFF_85_NECK_IN3_DN")
	)
	(segment
		(start 478.481136 -145.712434)
		(end 478.481136 -147.947126)
		(width 0.1016)
		(layer "In6.Cu")
		(net "TDR_DIFF_85_NECK_IN3_DN")
	)
	(segment
		(start 473.681552 -146.425158)
		(end 478.367344 -145.598896)
		(width 0.1016)
		(layer "In6.Cu")
		(net "TDR_DIFF_85_NECK_IN3_DN")
	)
	(segment
		(start 483.806246 -135.180324)
		(end 483.72395 -135.297164)
		(width 0.1016)
		(layer "In6.Cu")
		(net "TDR_DIFF_85_NECK_IN3_DN")
	)
	(segment
		(start 473.332556 -144.46758)
		(end 473.165424 -144.705578)
		(width 0.1016)
		(layer "In6.Cu")
		(net "TDR_DIFF_85_NECK_IN3_DN")
	)
	(segment
		(start 473.165424 -144.705578)
		(end 473.438474 -146.254724)
		(width 0.1016)
		(layer "In6.Cu")
		(net "TDR_DIFF_85_NECK_IN3_DN")
	)
	(segment
		(start 473.336874 -126.12116)
		(end 473.169996 -126.359412)
		(width 0.1016)
		(layer "In6.Cu")
		(net "TDR_DIFF_85_NECK_IN3_DN")
	)
	(segment
		(start 483.830122 -124.096272)
		(end 483.69093 -124.295916)
		(width 0.1016)
		(layer "In6.Cu")
		(net "TDR_DIFF_85_NECK_IN3_DN")
	)
	(segment
		(start 473.168218 -130.028442)
		(end 473.441268 -131.577334)
		(width 0.1016)
		(layer "In6.Cu")
		(net "TDR_DIFF_85_NECK_IN3_DN")
	)
	(segment
		(start 483.804976 -138.849608)
		(end 483.722934 -138.966702)
		(width 0.1016)
		(layer "In6.Cu")
		(net "TDR_DIFF_85_NECK_IN3_DN")
	)
	(segment
		(start 483.749604 -127.954532)
		(end 473.335096 -129.790698)
		(width 0.1016)
		(layer "In6.Cu")
		(net "TDR_DIFF_85_NECK_IN3_DN")
	)
	(segment
		(start 473.13088 -141.042644)
		(end 473.40393 -142.591536)
		(width 0.1016)
		(layer "In6.Cu")
		(net "TDR_DIFF_85_NECK_IN3_DN")
	)
	(segment
		(start 483.528116 -141.11859)
		(end 483.775766 -142.523718)
		(width 0.1016)
		(layer "In6.Cu")
		(net "TDR_DIFF_85_NECK_IN3_DN")
	)
	(segment
		(start 473.40393 -142.591536)
		(end 473.641928 -142.758668)
		(width 0.1016)
		(layer "In6.Cu")
		(net "TDR_DIFF_85_NECK_IN3_DN")
	)
	(segment
		(start 473.672662 -139.08405)
		(end 483.439978 -137.362184)
		(width 0.1016)
		(layer "In6.Cu")
		(net "TDR_DIFF_85_NECK_IN3_DN")
	)
	(segment
		(start 483.7811 -131.515612)
		(end 483.698804 -131.632706)
		(width 0.1016)
		(layer "In6.Cu")
		(net "TDR_DIFF_85_NECK_IN3_DN")
	)
	(segment
		(start 473.302076 -133.46557)
		(end 473.134944 -133.703568)
		(width 0.1016)
		(layer "In6.Cu")
		(net "TDR_DIFF_85_NECK_IN3_DN")
	)
	(segment
		(start 473.298012 -140.804646)
		(end 473.13088 -141.042644)
		(width 0.1016)
		(layer "In6.Cu")
		(net "TDR_DIFF_85_NECK_IN3_DN")
	)
	(segment
		(start 483.411022 -141.036294)
		(end 483.528116 -141.11859)
		(width 0.1016)
		(layer "In6.Cu")
		(net "TDR_DIFF_85_NECK_IN3_DN")
	)
	(segment
		(start 473.681044 -128.075182)
		(end 483.466648 -126.350014)
		(width 0.1016)
		(layer "In6.Cu")
		(net "TDR_DIFF_85_NECK_IN3_DN")
	)
	(segment
		(start 473.441268 -131.577334)
		(end 473.67952 -131.74472)
		(width 0.1016)
		(layer "In6.Cu")
		(net "TDR_DIFF_85_NECK_IN3_DN")
	)
	(segment
		(start 483.466648 -126.350014)
		(end 483.583996 -126.432564)
		(width 0.1016)
		(layer "In6.Cu")
		(net "TDR_DIFF_85_NECK_IN3_DN")
	)
	(segment
		(start 473.499434 -146.297142)
		(end 473.681552 -146.425158)
		(width 0.1016)
		(layer "In6.Cu")
		(net "TDR_DIFF_85_NECK_IN3_DN")
	)
	(segment
		(start 483.533196 -130.110484)
		(end 483.7811 -131.515612)
		(width 0.1016)
		(layer "In6.Cu")
		(net "TDR_DIFF_85_NECK_IN3_DN")
	)
	(segment
		(start 473.438474 -146.254724)
		(end 473.49918 -146.297396)
		(width 0.1016)
		(layer "In6.Cu")
		(net "TDR_DIFF_85_NECK_IN3_DN")
	)
	(segment
		(start 478.48647 -121.741692)
		(end 478.48647 -123.323858)
		(width 0.1016)
		(layer "In6.Cu")
		(net "TDR_DIFF_85_NECK_IN3_DN")
	)
	(segment
		(start 483.722934 -138.966702)
		(end 473.298012 -140.804646)
		(width 0.1016)
		(layer "In6.Cu")
		(net "TDR_DIFF_85_NECK_IN3_DN")
	)
	(segment
		(start 473.434664 -138.916918)
		(end 473.672662 -139.08405)
		(width 0.1016)
		(layer "In6.Cu")
		(net "TDR_DIFF_85_NECK_IN3_DN")
	)
	(segment
		(start 483.698804 -131.632706)
		(end 473.302076 -133.46557)
		(width 0.1016)
		(layer "In6.Cu")
		(net "TDR_DIFF_85_NECK_IN3_DN")
	)
	(segment
		(start 478.38487 -121.640092)
		(end 478.48647 -121.741692)
		(width 0.1016)
		(layer "In6.Cu")
		(net "TDR_DIFF_85_NECK_IN3_DN")
	)
	(segment
		(start 473.67952 -131.74472)
		(end 483.415848 -130.027934)
		(width 0.1016)
		(layer "In6.Cu")
		(net "TDR_DIFF_85_NECK_IN3_DN")
	)
	(segment
		(start 483.558342 -133.77545)
		(end 483.806246 -135.180324)
		(width 0.1016)
		(layer "In6.Cu")
		(net "TDR_DIFF_85_NECK_IN3_DN")
	)
	(segment
		(start 483.775766 -142.523718)
		(end 483.693724 -142.640812)
		(width 0.1016)
		(layer "In6.Cu")
		(net "TDR_DIFF_85_NECK_IN3_DN")
	)
	(segment
		(start 483.439978 -137.362184)
		(end 483.557326 -137.444734)
		(width 0.1016)
		(layer "In6.Cu")
		(net "TDR_DIFF_85_NECK_IN3_DN")
	)
	(segment
		(start 473.49918 -146.297396)
		(end 473.499434 -146.297142)
		(width 0.1016)
		(layer "In6.Cu")
		(net "TDR_DIFF_85_NECK_IN3_DN")
	)
	(segment
		(start 473.161614 -137.368026)
		(end 473.434664 -138.916918)
		(width 0.1016)
		(layer "In6.Cu")
		(net "TDR_DIFF_85_NECK_IN3_DN")
	)
	(segment
		(start 478.48647 -123.323858)
		(end 478.753932 -123.512072)
		(width 0.1016)
		(layer "In6.Cu")
		(net "TDR_DIFF_85_NECK_IN3_DN")
	)
	(segment
		(start 473.335096 -129.790698)
		(end 473.168218 -130.028442)
		(width 0.1016)
		(layer "In6.Cu")
		(net "TDR_DIFF_85_NECK_IN3_DN")
	)
	(segment
		(start 483.60711 -122.831098)
		(end 483.830122 -124.096272)
		(width 0.1016)
		(layer "In6.Cu")
		(net "TDR_DIFF_85_NECK_IN3_DN")
	)
	(segment
		(start 483.407974 -122.691398)
		(end 483.60711 -122.831098)
		(width 0.1016)
		(layer "In6.Cu")
		(net "TDR_DIFF_85_NECK_IN3_DN")
	)
	(segment
		(start 478.367344 -145.598896)
		(end 478.481136 -145.712434)
		(width 0.1016)
		(layer "In6.Cu")
		(net "TDR_DIFF_85_NECK_IN3_DN")
	)
	(segment
		(start 483.60711 -185.797698)
		(end 483.830122 -187.062872)
		(width 0.1016)
		(layer "In4.Cu")
		(net "TDR_DIFF_85_NECK_IN2_DP")
	)
	(segment
		(start 483.407974 -185.657998)
		(end 483.60711 -185.797698)
		(width 0.1016)
		(layer "In4.Cu")
		(net "TDR_DIFF_85_NECK_IN2_DP")
	)
	(segment
		(start 473.681044 -191.041782)
		(end 483.466648 -189.316614)
		(width 0.1016)
		(layer "In4.Cu")
		(net "TDR_DIFF_85_NECK_IN2_DP")
	)
	(segment
		(start 478.753932 -186.478672)
		(end 483.407974 -185.657998)
		(width 0.1016)
		(layer "In4.Cu")
		(net "TDR_DIFF_85_NECK_IN2_DP")
	)
	(segment
		(start 483.698804 -194.599306)
		(end 473.302076 -196.43217)
		(width 0.1016)
		(layer "In4.Cu")
		(net "TDR_DIFF_85_NECK_IN2_DP")
	)
	(segment
		(start 483.415848 -192.994534)
		(end 483.533196 -193.077084)
		(width 0.1016)
		(layer "In4.Cu")
		(net "TDR_DIFF_85_NECK_IN2_DP")
	)
	(segment
		(start 473.49918 -209.263996)
		(end 473.499434 -209.263742)
		(width 0.1016)
		(layer "In4.Cu")
		(net "TDR_DIFF_85_NECK_IN2_DP")
	)
	(segment
		(start 473.443046 -190.87465)
		(end 473.681044 -191.041782)
		(width 0.1016)
		(layer "In4.Cu")
		(net "TDR_DIFF_85_NECK_IN2_DP")
	)
	(segment
		(start 473.407994 -198.21906)
		(end 473.645992 -198.386192)
		(width 0.1016)
		(layer "In4.Cu")
		(net "TDR_DIFF_85_NECK_IN2_DP")
	)
	(segment
		(start 478.481136 -210.913726)
		(end 478.38487 -211.009992)
		(width 0.1016)
		(layer "In4.Cu")
		(net "TDR_DIFF_85_NECK_IN2_DP")
	)
	(segment
		(start 473.13088 -204.009244)
		(end 473.40393 -205.558136)
		(width 0.1016)
		(layer "In4.Cu")
		(net "TDR_DIFF_85_NECK_IN2_DP")
	)
	(segment
		(start 483.439978 -200.328784)
		(end 483.557326 -200.411334)
		(width 0.1016)
		(layer "In4.Cu")
		(net "TDR_DIFF_85_NECK_IN2_DP")
	)
	(segment
		(start 483.7811 -194.482212)
		(end 483.698804 -194.599306)
		(width 0.1016)
		(layer "In4.Cu")
		(net "TDR_DIFF_85_NECK_IN2_DP")
	)
	(segment
		(start 483.72395 -198.263764)
		(end 473.328746 -200.096628)
		(width 0.1016)
		(layer "In4.Cu")
		(net "TDR_DIFF_85_NECK_IN2_DP")
	)
	(segment
		(start 473.298012 -203.771246)
		(end 473.13088 -204.009244)
		(width 0.1016)
		(layer "In4.Cu")
		(net "TDR_DIFF_85_NECK_IN2_DP")
	)
	(segment
		(start 473.67952 -194.71132)
		(end 483.415848 -192.994534)
		(width 0.1016)
		(layer "In4.Cu")
		(net "TDR_DIFF_85_NECK_IN2_DP")
	)
	(segment
		(start 483.44074 -196.6595)
		(end 483.558342 -196.74205)
		(width 0.1016)
		(layer "In4.Cu")
		(net "TDR_DIFF_85_NECK_IN2_DP")
	)
	(segment
		(start 473.40393 -205.558136)
		(end 473.641928 -205.725268)
		(width 0.1016)
		(layer "In4.Cu")
		(net "TDR_DIFF_85_NECK_IN2_DP")
	)
	(segment
		(start 483.557326 -200.411334)
		(end 483.804976 -201.816208)
		(width 0.1016)
		(layer "In4.Cu")
		(net "TDR_DIFF_85_NECK_IN2_DP")
	)
	(segment
		(start 483.831646 -190.804038)
		(end 483.749604 -190.921132)
		(width 0.1016)
		(layer "In4.Cu")
		(net "TDR_DIFF_85_NECK_IN2_DP")
	)
	(segment
		(start 473.335096 -192.757298)
		(end 473.168218 -192.995042)
		(width 0.1016)
		(layer "In4.Cu")
		(net "TDR_DIFF_85_NECK_IN2_DP")
	)
	(segment
		(start 483.583996 -189.399164)
		(end 483.831646 -190.804038)
		(width 0.1016)
		(layer "In4.Cu")
		(net "TDR_DIFF_85_NECK_IN2_DP")
	)
	(segment
		(start 473.641928 -205.725268)
		(end 483.411022 -204.002894)
		(width 0.1016)
		(layer "In4.Cu")
		(net "TDR_DIFF_85_NECK_IN2_DP")
	)
	(segment
		(start 483.528116 -204.08519)
		(end 483.775766 -205.490318)
		(width 0.1016)
		(layer "In4.Cu")
		(net "TDR_DIFF_85_NECK_IN2_DP")
	)
	(segment
		(start 478.367344 -208.565496)
		(end 478.481136 -208.679034)
		(width 0.1016)
		(layer "In4.Cu")
		(net "TDR_DIFF_85_NECK_IN2_DP")
	)
	(segment
		(start 483.775766 -205.490318)
		(end 483.693724 -205.607412)
		(width 0.1016)
		(layer "In4.Cu")
		(net "TDR_DIFF_85_NECK_IN2_DP")
	)
	(segment
		(start 473.165424 -207.672178)
		(end 473.438474 -209.221324)
		(width 0.1016)
		(layer "In4.Cu")
		(net "TDR_DIFF_85_NECK_IN2_DP")
	)
	(segment
		(start 473.336874 -189.08776)
		(end 473.169996 -189.326012)
		(width 0.1016)
		(layer "In4.Cu")
		(net "TDR_DIFF_85_NECK_IN2_DP")
	)
	(segment
		(start 473.328746 -200.096628)
		(end 473.161614 -200.334626)
		(width 0.1016)
		(layer "In4.Cu")
		(net "TDR_DIFF_85_NECK_IN2_DP")
	)
	(segment
		(start 473.441268 -194.543934)
		(end 473.67952 -194.71132)
		(width 0.1016)
		(layer "In4.Cu")
		(net "TDR_DIFF_85_NECK_IN2_DP")
	)
	(segment
		(start 478.38487 -184.606692)
		(end 478.48647 -184.708292)
		(width 0.1016)
		(layer "In4.Cu")
		(net "TDR_DIFF_85_NECK_IN2_DP")
	)
	(segment
		(start 473.168218 -192.995042)
		(end 473.441268 -194.543934)
		(width 0.1016)
		(layer "In4.Cu")
		(net "TDR_DIFF_85_NECK_IN2_DP")
	)
	(segment
		(start 473.645992 -198.386192)
		(end 483.44074 -196.6595)
		(width 0.1016)
		(layer "In4.Cu")
		(net "TDR_DIFF_85_NECK_IN2_DP")
	)
	(segment
		(start 483.411022 -204.002894)
		(end 483.528116 -204.08519)
		(width 0.1016)
		(layer "In4.Cu")
		(net "TDR_DIFF_85_NECK_IN2_DP")
	)
	(segment
		(start 473.134944 -196.670168)
		(end 473.407994 -198.21906)
		(width 0.1016)
		(layer "In4.Cu")
		(net "TDR_DIFF_85_NECK_IN2_DP")
	)
	(segment
		(start 473.161614 -200.334626)
		(end 473.434664 -201.883518)
		(width 0.1016)
		(layer "In4.Cu")
		(net "TDR_DIFF_85_NECK_IN2_DP")
	)
	(segment
		(start 483.830122 -187.062872)
		(end 483.69093 -187.262516)
		(width 0.1016)
		(layer "In4.Cu")
		(net "TDR_DIFF_85_NECK_IN2_DP")
	)
	(segment
		(start 473.438474 -209.221324)
		(end 473.49918 -209.263996)
		(width 0.1016)
		(layer "In4.Cu")
		(net "TDR_DIFF_85_NECK_IN2_DP")
	)
	(segment
		(start 473.434664 -201.883518)
		(end 473.672662 -202.05065)
		(width 0.1016)
		(layer "In4.Cu")
		(net "TDR_DIFF_85_NECK_IN2_DP")
	)
	(segment
		(start 483.693724 -205.607412)
		(end 473.332556 -207.43418)
		(width 0.1016)
		(layer "In4.Cu")
		(net "TDR_DIFF_85_NECK_IN2_DP")
	)
	(segment
		(start 473.169996 -189.326012)
		(end 473.443046 -190.87465)
		(width 0.1016)
		(layer "In4.Cu")
		(net "TDR_DIFF_85_NECK_IN2_DP")
	)
	(segment
		(start 478.48647 -184.708292)
		(end 478.48647 -186.290458)
		(width 0.1016)
		(layer "In4.Cu")
		(net "TDR_DIFF_85_NECK_IN2_DP")
	)
	(segment
		(start 473.672662 -202.05065)
		(end 483.439978 -200.328784)
		(width 0.1016)
		(layer "In4.Cu")
		(net "TDR_DIFF_85_NECK_IN2_DP")
	)
	(segment
		(start 483.804976 -201.816208)
		(end 483.722934 -201.933302)
		(width 0.1016)
		(layer "In4.Cu")
		(net "TDR_DIFF_85_NECK_IN2_DP")
	)
	(segment
		(start 473.681552 -209.391758)
		(end 478.367344 -208.565496)
		(width 0.1016)
		(layer "In4.Cu")
		(net "TDR_DIFF_85_NECK_IN2_DP")
	)
	(segment
		(start 473.332556 -207.43418)
		(end 473.165424 -207.672178)
		(width 0.1016)
		(layer "In4.Cu")
		(net "TDR_DIFF_85_NECK_IN2_DP")
	)
	(segment
		(start 483.558342 -196.74205)
		(end 483.806246 -198.146924)
		(width 0.1016)
		(layer "In4.Cu")
		(net "TDR_DIFF_85_NECK_IN2_DP")
	)
	(segment
		(start 473.302076 -196.43217)
		(end 473.134944 -196.670168)
		(width 0.1016)
		(layer "In4.Cu")
		(net "TDR_DIFF_85_NECK_IN2_DP")
	)
	(segment
		(start 483.533196 -193.077084)
		(end 483.7811 -194.482212)
		(width 0.1016)
		(layer "In4.Cu")
		(net "TDR_DIFF_85_NECK_IN2_DP")
	)
	(segment
		(start 477.30537 -184.606692)
		(end 478.38487 -184.606692)
		(width 0.1016)
		(layer "In4.Cu")
		(net "TDR_DIFF_85_NECK_IN2_DP")
	)
	(segment
		(start 473.499434 -209.263742)
		(end 473.681552 -209.391758)
		(width 0.1016)
		(layer "In4.Cu")
		(net "TDR_DIFF_85_NECK_IN2_DP")
	)
	(segment
		(start 483.749604 -190.921132)
		(end 473.335096 -192.757298)
		(width 0.1016)
		(layer "In4.Cu")
		(net "TDR_DIFF_85_NECK_IN2_DP")
	)
	(segment
		(start 483.722934 -201.933302)
		(end 473.298012 -203.771246)
		(width 0.1016)
		(layer "In4.Cu")
		(net "TDR_DIFF_85_NECK_IN2_DP")
	)
	(segment
		(start 483.69093 -187.262516)
		(end 473.336874 -189.08776)
		(width 0.1016)
		(layer "In4.Cu")
		(net "TDR_DIFF_85_NECK_IN2_DP")
	)
	(segment
		(start 478.38487 -211.009992)
		(end 477.30537 -211.009992)
		(width 0.1016)
		(layer "In4.Cu")
		(net "TDR_DIFF_85_NECK_IN2_DP")
	)
	(segment
		(start 478.48647 -186.290458)
		(end 478.753932 -186.478672)
		(width 0.1016)
		(layer "In4.Cu")
		(net "TDR_DIFF_85_NECK_IN2_DP")
	)
	(segment
		(start 483.466648 -189.316614)
		(end 483.583996 -189.399164)
		(width 0.1016)
		(layer "In4.Cu")
		(net "TDR_DIFF_85_NECK_IN2_DP")
	)
	(segment
		(start 478.481136 -208.679034)
		(end 478.481136 -210.913726)
		(width 0.1016)
		(layer "In4.Cu")
		(net "TDR_DIFF_85_NECK_IN2_DP")
	)
	(segment
		(start 483.806246 -198.146924)
		(end 483.72395 -198.263764)
		(width 0.1016)
		(layer "In4.Cu")
		(net "TDR_DIFF_85_NECK_IN2_DP")
	)
	(segment
		(start 483.690676 -203.981812)
		(end 483.96398 -205.532228)
		(width 0.1016)
		(layer "In4.Cu")
		(net "TDR_DIFF_85_NECK_IN2_DN")
	)
	(segment
		(start 473.72143 -194.523106)
		(end 483.457504 -192.806574)
		(width 0.1016)
		(layer "In4.Cu")
		(net "TDR_DIFF_85_NECK_IN2_DN")
	)
	(segment
		(start 473.723462 -209.203798)
		(end 478.427542 -208.374234)
		(width 0.1016)
		(layer "In4.Cu")
		(net "TDR_DIFF_85_NECK_IN2_DN")
	)
	(segment
		(start 483.99319 -201.858118)
		(end 483.826312 -202.095862)
		(width 0.1016)
		(layer "In4.Cu")
		(net "TDR_DIFF_85_NECK_IN2_DN")
	)
	(segment
		(start 483.508304 -189.128654)
		(end 483.746556 -189.295532)
		(width 0.1016)
		(layer "In4.Cu")
		(net "TDR_DIFF_85_NECK_IN2_DN")
	)
	(segment
		(start 473.322904 -196.712078)
		(end 473.570554 -198.115682)
		(width 0.1016)
		(layer "In4.Cu")
		(net "TDR_DIFF_85_NECK_IN2_DN")
	)
	(segment
		(start 483.96906 -194.523868)
		(end 483.802182 -194.761866)
		(width 0.1016)
		(layer "In4.Cu")
		(net "TDR_DIFF_85_NECK_IN2_DN")
	)
	(segment
		(start 473.601796 -209.1182)
		(end 473.723462 -209.203798)
		(width 0.1016)
		(layer "In4.Cu")
		(net "TDR_DIFF_85_NECK_IN2_DN")
	)
	(segment
		(start 483.746556 -189.295532)
		(end 484.01986 -190.845948)
		(width 0.1016)
		(layer "In4.Cu")
		(net "TDR_DIFF_85_NECK_IN2_DN")
	)
	(segment
		(start 473.687902 -198.198232)
		(end 483.482396 -196.47154)
		(width 0.1016)
		(layer "In4.Cu")
		(net "TDR_DIFF_85_NECK_IN2_DN")
	)
	(segment
		(start 473.357956 -189.367668)
		(end 473.481908 -190.069724)
		(width 0.1016)
		(layer "In4.Cu")
		(net "TDR_DIFF_85_NECK_IN2_DN")
	)
	(segment
		(start 483.457504 -192.806574)
		(end 483.695756 -192.973452)
		(width 0.1016)
		(layer "In4.Cu")
		(net "TDR_DIFF_85_NECK_IN2_DN")
	)
	(segment
		(start 473.481908 -190.069724)
		(end 473.482162 -190.069724)
		(width 0.1016)
		(layer "In4.Cu")
		(net "TDR_DIFF_85_NECK_IN2_DN")
	)
	(segment
		(start 483.852982 -191.083692)
		(end 473.438474 -192.919858)
		(width 0.1016)
		(layer "In4.Cu")
		(net "TDR_DIFF_85_NECK_IN2_DN")
	)
	(segment
		(start 478.66427 -186.198002)
		(end 478.795842 -186.290712)
		(width 0.1016)
		(layer "In4.Cu")
		(net "TDR_DIFF_85_NECK_IN2_DN")
	)
	(segment
		(start 483.96398 -205.532228)
		(end 483.797102 -205.769972)
		(width 0.1016)
		(layer "In4.Cu")
		(net "TDR_DIFF_85_NECK_IN2_DN")
	)
	(segment
		(start 478.658936 -208.60512)
		(end 478.658936 -210.903058)
		(width 0.1016)
		(layer "In4.Cu")
		(net "TDR_DIFF_85_NECK_IN2_DN")
	)
	(segment
		(start 473.722954 -190.853822)
		(end 483.508304 -189.128654)
		(width 0.1016)
		(layer "In4.Cu")
		(net "TDR_DIFF_85_NECK_IN2_DN")
	)
	(segment
		(start 478.427542 -208.374234)
		(end 478.658936 -208.60512)
		(width 0.1016)
		(layer "In4.Cu")
		(net "TDR_DIFF_85_NECK_IN2_DN")
	)
	(segment
		(start 483.719886 -200.307702)
		(end 483.99319 -201.858118)
		(width 0.1016)
		(layer "In4.Cu")
		(net "TDR_DIFF_85_NECK_IN2_DN")
	)
	(segment
		(start 483.482396 -196.47154)
		(end 483.720902 -196.638418)
		(width 0.1016)
		(layer "In4.Cu")
		(net "TDR_DIFF_85_NECK_IN2_DN")
	)
	(segment
		(start 483.826312 -202.095862)
		(end 473.40139 -203.933806)
		(width 0.1016)
		(layer "In4.Cu")
		(net "TDR_DIFF_85_NECK_IN2_DN")
	)
	(segment
		(start 483.797102 -205.769972)
		(end 473.435934 -207.59674)
		(width 0.1016)
		(layer "In4.Cu")
		(net "TDR_DIFF_85_NECK_IN2_DN")
	)
	(segment
		(start 484.018082 -187.104274)
		(end 483.794562 -187.424822)
		(width 0.1016)
		(layer "In4.Cu")
		(net "TDR_DIFF_85_NECK_IN2_DN")
	)
	(segment
		(start 478.66427 -184.733692)
		(end 478.66427 -186.198002)
		(width 0.1016)
		(layer "In4.Cu")
		(net "TDR_DIFF_85_NECK_IN2_DN")
	)
	(segment
		(start 473.683838 -205.537308)
		(end 483.452678 -203.814934)
		(width 0.1016)
		(layer "In4.Cu")
		(net "TDR_DIFF_85_NECK_IN2_DN")
	)
	(segment
		(start 478.76587 -211.009992)
		(end 479.84537 -211.009992)
		(width 0.1016)
		(layer "In4.Cu")
		(net "TDR_DIFF_85_NECK_IN2_DN")
	)
	(segment
		(start 483.449884 -185.469784)
		(end 483.76967 -185.69432)
		(width 0.1016)
		(layer "In4.Cu")
		(net "TDR_DIFF_85_NECK_IN2_DN")
	)
	(segment
		(start 473.353384 -207.714088)
		(end 473.601034 -209.117692)
		(width 0.1016)
		(layer "In4.Cu")
		(net "TDR_DIFF_85_NECK_IN2_DN")
	)
	(segment
		(start 473.40139 -203.933806)
		(end 473.31884 -204.051154)
		(width 0.1016)
		(layer "In4.Cu")
		(net "TDR_DIFF_85_NECK_IN2_DN")
	)
	(segment
		(start 478.658936 -210.903058)
		(end 478.76587 -211.009992)
		(width 0.1016)
		(layer "In4.Cu")
		(net "TDR_DIFF_85_NECK_IN2_DN")
	)
	(segment
		(start 483.76967 -185.69432)
		(end 484.018082 -187.104274)
		(width 0.1016)
		(layer "In4.Cu")
		(net "TDR_DIFF_85_NECK_IN2_DN")
	)
	(segment
		(start 473.601034 -209.117692)
		(end 473.601796 -209.1182)
		(width 0.1016)
		(layer "In4.Cu")
		(net "TDR_DIFF_85_NECK_IN2_DN")
	)
	(segment
		(start 483.481634 -200.140824)
		(end 483.719886 -200.307702)
		(width 0.1016)
		(layer "In4.Cu")
		(net "TDR_DIFF_85_NECK_IN2_DN")
	)
	(segment
		(start 478.795842 -186.290712)
		(end 483.449884 -185.469784)
		(width 0.1016)
		(layer "In4.Cu")
		(net "TDR_DIFF_85_NECK_IN2_DN")
	)
	(segment
		(start 483.794562 -187.424822)
		(end 473.440506 -189.25032)
		(width 0.1016)
		(layer "In4.Cu")
		(net "TDR_DIFF_85_NECK_IN2_DN")
	)
	(segment
		(start 473.435934 -207.59674)
		(end 473.353384 -207.714088)
		(width 0.1016)
		(layer "In4.Cu")
		(net "TDR_DIFF_85_NECK_IN2_DN")
	)
	(segment
		(start 473.356178 -193.036952)
		(end 473.603828 -194.440556)
		(width 0.1016)
		(layer "In4.Cu")
		(net "TDR_DIFF_85_NECK_IN2_DN")
	)
	(segment
		(start 483.452678 -203.814934)
		(end 483.690676 -203.981812)
		(width 0.1016)
		(layer "In4.Cu")
		(net "TDR_DIFF_85_NECK_IN2_DN")
	)
	(segment
		(start 473.440506 -189.25032)
		(end 473.357956 -189.367668)
		(width 0.1016)
		(layer "In4.Cu")
		(net "TDR_DIFF_85_NECK_IN2_DN")
	)
	(segment
		(start 483.695756 -192.973452)
		(end 483.96906 -194.523868)
		(width 0.1016)
		(layer "In4.Cu")
		(net "TDR_DIFF_85_NECK_IN2_DN")
	)
	(segment
		(start 473.438474 -192.919858)
		(end 473.356178 -193.036952)
		(width 0.1016)
		(layer "In4.Cu")
		(net "TDR_DIFF_85_NECK_IN2_DN")
	)
	(segment
		(start 473.603828 -194.440556)
		(end 473.72143 -194.523106)
		(width 0.1016)
		(layer "In4.Cu")
		(net "TDR_DIFF_85_NECK_IN2_DN")
	)
	(segment
		(start 483.802182 -194.761866)
		(end 473.405454 -196.59473)
		(width 0.1016)
		(layer "In4.Cu")
		(net "TDR_DIFF_85_NECK_IN2_DN")
	)
	(segment
		(start 473.570554 -198.115682)
		(end 473.687902 -198.198232)
		(width 0.1016)
		(layer "In4.Cu")
		(net "TDR_DIFF_85_NECK_IN2_DN")
	)
	(segment
		(start 478.79127 -184.606692)
		(end 478.66427 -184.733692)
		(width 0.1016)
		(layer "In4.Cu")
		(net "TDR_DIFF_85_NECK_IN2_DN")
	)
	(segment
		(start 484.01986 -190.845948)
		(end 483.852982 -191.083692)
		(width 0.1016)
		(layer "In4.Cu")
		(net "TDR_DIFF_85_NECK_IN2_DN")
	)
	(segment
		(start 483.994206 -198.188834)
		(end 483.827328 -198.426324)
		(width 0.1016)
		(layer "In4.Cu")
		(net "TDR_DIFF_85_NECK_IN2_DN")
	)
	(segment
		(start 473.605606 -190.771272)
		(end 473.722954 -190.853822)
		(width 0.1016)
		(layer "In4.Cu")
		(net "TDR_DIFF_85_NECK_IN2_DN")
	)
	(segment
		(start 473.597224 -201.78014)
		(end 473.714572 -201.86269)
		(width 0.1016)
		(layer "In4.Cu")
		(net "TDR_DIFF_85_NECK_IN2_DN")
	)
	(segment
		(start 483.720902 -196.638418)
		(end 483.994206 -198.188834)
		(width 0.1016)
		(layer "In4.Cu")
		(net "TDR_DIFF_85_NECK_IN2_DN")
	)
	(segment
		(start 473.349574 -200.376536)
		(end 473.597224 -201.78014)
		(width 0.1016)
		(layer "In4.Cu")
		(net "TDR_DIFF_85_NECK_IN2_DN")
	)
	(segment
		(start 473.432124 -200.259188)
		(end 473.349574 -200.376536)
		(width 0.1016)
		(layer "In4.Cu")
		(net "TDR_DIFF_85_NECK_IN2_DN")
	)
	(segment
		(start 473.482162 -190.069724)
		(end 473.605606 -190.771272)
		(width 0.1016)
		(layer "In4.Cu")
		(net "TDR_DIFF_85_NECK_IN2_DN")
	)
	(segment
		(start 473.405454 -196.59473)
		(end 473.322904 -196.712078)
		(width 0.1016)
		(layer "In4.Cu")
		(net "TDR_DIFF_85_NECK_IN2_DN")
	)
	(segment
		(start 473.714572 -201.86269)
		(end 483.481634 -200.140824)
		(width 0.1016)
		(layer "In4.Cu")
		(net "TDR_DIFF_85_NECK_IN2_DN")
	)
	(segment
		(start 479.84537 -184.606692)
		(end 478.79127 -184.606692)
		(width 0.1016)
		(layer "In4.Cu")
		(net "TDR_DIFF_85_NECK_IN2_DN")
	)
	(segment
		(start 483.827328 -198.426324)
		(end 473.432124 -200.259188)
		(width 0.1016)
		(layer "In4.Cu")
		(net "TDR_DIFF_85_NECK_IN2_DN")
	)
	(segment
		(start 473.31884 -204.051154)
		(end 473.56649 -205.454758)
		(width 0.1016)
		(layer "In4.Cu")
		(net "TDR_DIFF_85_NECK_IN2_DN")
	)
	(segment
		(start 473.56649 -205.454758)
		(end 473.683838 -205.537308)
		(width 0.1016)
		(layer "In4.Cu")
		(net "TDR_DIFF_85_NECK_IN2_DN")
	)
	(segment
		(start 489.140246 -236.976158)
		(end 489.058204 -237.093252)
		(width 0.1016)
		(layer "In2.Cu")
		(net "TDR_DIFF_85_NECK_IN1_DP")
	)
	(segment
		(start 488.775502 -235.488734)
		(end 488.892596 -235.57103)
		(width 0.1016)
		(layer "In2.Cu")
		(net "TDR_DIFF_85_NECK_IN1_DP")
	)
	(segment
		(start 483.731824 -240.051336)
		(end 483.845616 -240.164874)
		(width 0.1016)
		(layer "In2.Cu")
		(net "TDR_DIFF_85_NECK_IN1_DP")
	)
	(segment
		(start 484.118412 -217.964512)
		(end 488.772454 -217.143838)
		(width 0.1016)
		(layer "In2.Cu")
		(net "TDR_DIFF_85_NECK_IN1_DP")
	)
	(segment
		(start 478.805748 -226.029774)
		(end 479.044 -226.19716)
		(width 0.1016)
		(layer "In2.Cu")
		(net "TDR_DIFF_85_NECK_IN1_DP")
	)
	(segment
		(start 478.529904 -239.158018)
		(end 478.802954 -240.707164)
		(width 0.1016)
		(layer "In2.Cu")
		(net "TDR_DIFF_85_NECK_IN1_DP")
	)
	(segment
		(start 489.058204 -237.093252)
		(end 478.697036 -238.92002)
		(width 0.1016)
		(layer "In2.Cu")
		(net "TDR_DIFF_85_NECK_IN1_DP")
	)
	(segment
		(start 488.80522 -228.14534)
		(end 488.922822 -228.22789)
		(width 0.1016)
		(layer "In2.Cu")
		(net "TDR_DIFF_85_NECK_IN1_DP")
	)
	(segment
		(start 479.045524 -222.527622)
		(end 488.831128 -220.802454)
		(width 0.1016)
		(layer "In2.Cu")
		(net "TDR_DIFF_85_NECK_IN1_DP")
	)
	(segment
		(start 489.114084 -222.406972)
		(end 478.699576 -224.243138)
		(width 0.1016)
		(layer "In2.Cu")
		(net "TDR_DIFF_85_NECK_IN1_DP")
	)
	(segment
		(start 489.05541 -218.748356)
		(end 478.701354 -220.5736)
		(width 0.1016)
		(layer "In2.Cu")
		(net "TDR_DIFF_85_NECK_IN1_DP")
	)
	(segment
		(start 478.532698 -224.480882)
		(end 478.805748 -226.029774)
		(width 0.1016)
		(layer "In2.Cu")
		(net "TDR_DIFF_85_NECK_IN1_DP")
	)
	(segment
		(start 488.804458 -231.814624)
		(end 488.921806 -231.897174)
		(width 0.1016)
		(layer "In2.Cu")
		(net "TDR_DIFF_85_NECK_IN1_DP")
	)
	(segment
		(start 489.087414 -233.419142)
		(end 478.662492 -235.257086)
		(width 0.1016)
		(layer "In2.Cu")
		(net "TDR_DIFF_85_NECK_IN1_DP")
	)
	(segment
		(start 489.196126 -222.289878)
		(end 489.114084 -222.406972)
		(width 0.1016)
		(layer "In2.Cu")
		(net "TDR_DIFF_85_NECK_IN1_DP")
	)
	(segment
		(start 478.534476 -220.811852)
		(end 478.807526 -222.36049)
		(width 0.1016)
		(layer "In2.Cu")
		(net "TDR_DIFF_85_NECK_IN1_DP")
	)
	(segment
		(start 478.76841 -237.043976)
		(end 479.006408 -237.211108)
		(width 0.1016)
		(layer "In2.Cu")
		(net "TDR_DIFF_85_NECK_IN1_DP")
	)
	(segment
		(start 478.526094 -231.820466)
		(end 478.799144 -233.369358)
		(width 0.1016)
		(layer "In2.Cu")
		(net "TDR_DIFF_85_NECK_IN1_DP")
	)
	(segment
		(start 478.701354 -220.5736)
		(end 478.534476 -220.811852)
		(width 0.1016)
		(layer "In2.Cu")
		(net "TDR_DIFF_85_NECK_IN1_DP")
	)
	(segment
		(start 483.845616 -240.164874)
		(end 483.845616 -242.399566)
		(width 0.1016)
		(layer "In2.Cu")
		(net "TDR_DIFF_85_NECK_IN1_DP")
	)
	(segment
		(start 488.97159 -217.283538)
		(end 489.194602 -218.548712)
		(width 0.1016)
		(layer "In2.Cu")
		(net "TDR_DIFF_85_NECK_IN1_DP")
	)
	(segment
		(start 483.845616 -242.399566)
		(end 483.74935 -242.495832)
		(width 0.1016)
		(layer "In2.Cu")
		(net "TDR_DIFF_85_NECK_IN1_DP")
	)
	(segment
		(start 482.66985 -216.092532)
		(end 483.74935 -216.092532)
		(width 0.1016)
		(layer "In2.Cu")
		(net "TDR_DIFF_85_NECK_IN1_DP")
	)
	(segment
		(start 489.170726 -229.632764)
		(end 489.08843 -229.749604)
		(width 0.1016)
		(layer "In2.Cu")
		(net "TDR_DIFF_85_NECK_IN1_DP")
	)
	(segment
		(start 478.807526 -222.36049)
		(end 479.045524 -222.527622)
		(width 0.1016)
		(layer "In2.Cu")
		(net "TDR_DIFF_85_NECK_IN1_DP")
	)
	(segment
		(start 488.897676 -224.562924)
		(end 489.14558 -225.968052)
		(width 0.1016)
		(layer "In2.Cu")
		(net "TDR_DIFF_85_NECK_IN1_DP")
	)
	(segment
		(start 478.499424 -228.156008)
		(end 478.772474 -229.7049)
		(width 0.1016)
		(layer "In2.Cu")
		(net "TDR_DIFF_85_NECK_IN1_DP")
	)
	(segment
		(start 488.892596 -235.57103)
		(end 489.140246 -236.976158)
		(width 0.1016)
		(layer "In2.Cu")
		(net "TDR_DIFF_85_NECK_IN1_DP")
	)
	(segment
		(start 489.063284 -226.085146)
		(end 478.666556 -227.91801)
		(width 0.1016)
		(layer "In2.Cu")
		(net "TDR_DIFF_85_NECK_IN1_DP")
	)
	(segment
		(start 489.169456 -233.302048)
		(end 489.087414 -233.419142)
		(width 0.1016)
		(layer "In2.Cu")
		(net "TDR_DIFF_85_NECK_IN1_DP")
	)
	(segment
		(start 479.044 -226.19716)
		(end 488.780328 -224.480374)
		(width 0.1016)
		(layer "In2.Cu")
		(net "TDR_DIFF_85_NECK_IN1_DP")
	)
	(segment
		(start 478.666556 -227.91801)
		(end 478.499424 -228.156008)
		(width 0.1016)
		(layer "In2.Cu")
		(net "TDR_DIFF_85_NECK_IN1_DP")
	)
	(segment
		(start 478.802954 -240.707164)
		(end 478.86366 -240.749836)
		(width 0.1016)
		(layer "In2.Cu")
		(net "TDR_DIFF_85_NECK_IN1_DP")
	)
	(segment
		(start 489.14558 -225.968052)
		(end 489.063284 -226.085146)
		(width 0.1016)
		(layer "In2.Cu")
		(net "TDR_DIFF_85_NECK_IN1_DP")
	)
	(segment
		(start 488.780328 -224.480374)
		(end 488.897676 -224.562924)
		(width 0.1016)
		(layer "In2.Cu")
		(net "TDR_DIFF_85_NECK_IN1_DP")
	)
	(segment
		(start 483.74935 -242.495832)
		(end 482.66985 -242.495832)
		(width 0.1016)
		(layer "In2.Cu")
		(net "TDR_DIFF_85_NECK_IN1_DP")
	)
	(segment
		(start 489.194602 -218.548712)
		(end 489.05541 -218.748356)
		(width 0.1016)
		(layer "In2.Cu")
		(net "TDR_DIFF_85_NECK_IN1_DP")
	)
	(segment
		(start 478.772474 -229.7049)
		(end 479.010472 -229.872032)
		(width 0.1016)
		(layer "In2.Cu")
		(net "TDR_DIFF_85_NECK_IN1_DP")
	)
	(segment
		(start 479.006408 -237.211108)
		(end 488.775502 -235.488734)
		(width 0.1016)
		(layer "In2.Cu")
		(net "TDR_DIFF_85_NECK_IN1_DP")
	)
	(segment
		(start 483.85095 -217.776298)
		(end 484.118412 -217.964512)
		(width 0.1016)
		(layer "In2.Cu")
		(net "TDR_DIFF_85_NECK_IN1_DP")
	)
	(segment
		(start 488.922822 -228.22789)
		(end 489.170726 -229.632764)
		(width 0.1016)
		(layer "In2.Cu")
		(net "TDR_DIFF_85_NECK_IN1_DP")
	)
	(segment
		(start 488.831128 -220.802454)
		(end 488.948476 -220.885004)
		(width 0.1016)
		(layer "In2.Cu")
		(net "TDR_DIFF_85_NECK_IN1_DP")
	)
	(segment
		(start 478.49536 -235.495084)
		(end 478.76841 -237.043976)
		(width 0.1016)
		(layer "In2.Cu")
		(net "TDR_DIFF_85_NECK_IN1_DP")
	)
	(segment
		(start 483.74935 -216.092532)
		(end 483.85095 -216.194132)
		(width 0.1016)
		(layer "In2.Cu")
		(net "TDR_DIFF_85_NECK_IN1_DP")
	)
	(segment
		(start 479.046032 -240.877598)
		(end 483.731824 -240.051336)
		(width 0.1016)
		(layer "In2.Cu")
		(net "TDR_DIFF_85_NECK_IN1_DP")
	)
	(segment
		(start 489.08843 -229.749604)
		(end 478.693226 -231.582468)
		(width 0.1016)
		(layer "In2.Cu")
		(net "TDR_DIFF_85_NECK_IN1_DP")
	)
	(segment
		(start 478.86366 -240.749836)
		(end 478.863914 -240.749582)
		(width 0.1016)
		(layer "In2.Cu")
		(net "TDR_DIFF_85_NECK_IN1_DP")
	)
	(segment
		(start 479.010472 -229.872032)
		(end 488.80522 -228.14534)
		(width 0.1016)
		(layer "In2.Cu")
		(net "TDR_DIFF_85_NECK_IN1_DP")
	)
	(segment
		(start 488.772454 -217.143838)
		(end 488.97159 -217.283538)
		(width 0.1016)
		(layer "In2.Cu")
		(net "TDR_DIFF_85_NECK_IN1_DP")
	)
	(segment
		(start 478.662492 -235.257086)
		(end 478.49536 -235.495084)
		(width 0.1016)
		(layer "In2.Cu")
		(net "TDR_DIFF_85_NECK_IN1_DP")
	)
	(segment
		(start 478.697036 -238.92002)
		(end 478.529904 -239.158018)
		(width 0.1016)
		(layer "In2.Cu")
		(net "TDR_DIFF_85_NECK_IN1_DP")
	)
	(segment
		(start 478.693226 -231.582468)
		(end 478.526094 -231.820466)
		(width 0.1016)
		(layer "In2.Cu")
		(net "TDR_DIFF_85_NECK_IN1_DP")
	)
	(segment
		(start 483.85095 -216.194132)
		(end 483.85095 -217.776298)
		(width 0.1016)
		(layer "In2.Cu")
		(net "TDR_DIFF_85_NECK_IN1_DP")
	)
	(segment
		(start 488.948476 -220.885004)
		(end 489.196126 -222.289878)
		(width 0.1016)
		(layer "In2.Cu")
		(net "TDR_DIFF_85_NECK_IN1_DP")
	)
	(segment
		(start 478.799144 -233.369358)
		(end 479.037142 -233.53649)
		(width 0.1016)
		(layer "In2.Cu")
		(net "TDR_DIFF_85_NECK_IN1_DP")
	)
	(segment
		(start 478.699576 -224.243138)
		(end 478.532698 -224.480882)
		(width 0.1016)
		(layer "In2.Cu")
		(net "TDR_DIFF_85_NECK_IN1_DP")
	)
	(segment
		(start 488.921806 -231.897174)
		(end 489.169456 -233.302048)
		(width 0.1016)
		(layer "In2.Cu")
		(net "TDR_DIFF_85_NECK_IN1_DP")
	)
	(segment
		(start 479.037142 -233.53649)
		(end 488.804458 -231.814624)
		(width 0.1016)
		(layer "In2.Cu")
		(net "TDR_DIFF_85_NECK_IN1_DP")
	)
	(segment
		(start 478.863914 -240.749582)
		(end 479.046032 -240.877598)
		(width 0.1016)
		(layer "In2.Cu")
		(net "TDR_DIFF_85_NECK_IN1_DP")
	)
	(segment
		(start 489.060236 -224.459292)
		(end 489.33354 -226.009708)
		(width 0.1016)
		(layer "In2.Cu")
		(net "TDR_DIFF_85_NECK_IN1_DN")
	)
	(segment
		(start 478.68332 -235.536994)
		(end 478.93097 -236.940598)
		(width 0.1016)
		(layer "In2.Cu")
		(net "TDR_DIFF_85_NECK_IN1_DN")
	)
	(segment
		(start 483.792022 -239.860074)
		(end 484.023416 -240.09096)
		(width 0.1016)
		(layer "In2.Cu")
		(net "TDR_DIFF_85_NECK_IN1_DN")
	)
	(segment
		(start 478.966276 -240.60404)
		(end 479.087942 -240.689638)
		(width 0.1016)
		(layer "In2.Cu")
		(net "TDR_DIFF_85_NECK_IN1_DN")
	)
	(segment
		(start 489.35767 -233.343958)
		(end 489.190792 -233.581702)
		(width 0.1016)
		(layer "In2.Cu")
		(net "TDR_DIFF_85_NECK_IN1_DN")
	)
	(segment
		(start 489.13415 -217.18016)
		(end 489.382562 -218.590114)
		(width 0.1016)
		(layer "In2.Cu")
		(net "TDR_DIFF_85_NECK_IN1_DN")
	)
	(segment
		(start 484.15575 -216.092532)
		(end 484.02875 -216.219532)
		(width 0.1016)
		(layer "In2.Cu")
		(net "TDR_DIFF_85_NECK_IN1_DN")
	)
	(segment
		(start 478.720658 -224.522792)
		(end 478.968308 -225.926396)
		(width 0.1016)
		(layer "In2.Cu")
		(net "TDR_DIFF_85_NECK_IN1_DN")
	)
	(segment
		(start 488.817158 -235.300774)
		(end 489.055156 -235.467652)
		(width 0.1016)
		(layer "In2.Cu")
		(net "TDR_DIFF_85_NECK_IN1_DN")
	)
	(segment
		(start 488.814364 -216.955624)
		(end 489.13415 -217.18016)
		(width 0.1016)
		(layer "In2.Cu")
		(net "TDR_DIFF_85_NECK_IN1_DN")
	)
	(segment
		(start 478.846388 -221.555564)
		(end 478.846642 -221.555564)
		(width 0.1016)
		(layer "In2.Cu")
		(net "TDR_DIFF_85_NECK_IN1_DN")
	)
	(segment
		(start 489.217462 -222.569532)
		(end 478.802954 -224.405698)
		(width 0.1016)
		(layer "In2.Cu")
		(net "TDR_DIFF_85_NECK_IN1_DN")
	)
	(segment
		(start 489.159042 -218.910662)
		(end 478.804986 -220.73616)
		(width 0.1016)
		(layer "In2.Cu")
		(net "TDR_DIFF_85_NECK_IN1_DN")
	)
	(segment
		(start 485.20985 -216.092532)
		(end 484.15575 -216.092532)
		(width 0.1016)
		(layer "In2.Cu")
		(net "TDR_DIFF_85_NECK_IN1_DN")
	)
	(segment
		(start 484.023416 -240.09096)
		(end 484.023416 -242.388898)
		(width 0.1016)
		(layer "In2.Cu")
		(net "TDR_DIFF_85_NECK_IN1_DN")
	)
	(segment
		(start 478.965514 -240.603532)
		(end 478.966276 -240.60404)
		(width 0.1016)
		(layer "In2.Cu")
		(net "TDR_DIFF_85_NECK_IN1_DN")
	)
	(segment
		(start 489.33354 -226.009708)
		(end 489.166662 -226.247706)
		(width 0.1016)
		(layer "In2.Cu")
		(net "TDR_DIFF_85_NECK_IN1_DN")
	)
	(segment
		(start 478.935034 -229.601522)
		(end 479.052382 -229.684072)
		(width 0.1016)
		(layer "In2.Cu")
		(net "TDR_DIFF_85_NECK_IN1_DN")
	)
	(segment
		(start 479.087942 -240.689638)
		(end 483.792022 -239.860074)
		(width 0.1016)
		(layer "In2.Cu")
		(net "TDR_DIFF_85_NECK_IN1_DN")
	)
	(segment
		(start 479.052382 -229.684072)
		(end 488.846876 -227.95738)
		(width 0.1016)
		(layer "In2.Cu")
		(net "TDR_DIFF_85_NECK_IN1_DN")
	)
	(segment
		(start 478.804986 -220.73616)
		(end 478.722436 -220.853508)
		(width 0.1016)
		(layer "In2.Cu")
		(net "TDR_DIFF_85_NECK_IN1_DN")
	)
	(segment
		(start 478.722436 -220.853508)
		(end 478.846388 -221.555564)
		(width 0.1016)
		(layer "In2.Cu")
		(net "TDR_DIFF_85_NECK_IN1_DN")
	)
	(segment
		(start 478.93097 -236.940598)
		(end 479.048318 -237.023148)
		(width 0.1016)
		(layer "In2.Cu")
		(net "TDR_DIFF_85_NECK_IN1_DN")
	)
	(segment
		(start 478.796604 -231.745028)
		(end 478.714054 -231.862376)
		(width 0.1016)
		(layer "In2.Cu")
		(net "TDR_DIFF_85_NECK_IN1_DN")
	)
	(segment
		(start 478.961704 -233.26598)
		(end 479.079052 -233.34853)
		(width 0.1016)
		(layer "In2.Cu")
		(net "TDR_DIFF_85_NECK_IN1_DN")
	)
	(segment
		(start 478.687384 -228.197918)
		(end 478.935034 -229.601522)
		(width 0.1016)
		(layer "In2.Cu")
		(net "TDR_DIFF_85_NECK_IN1_DN")
	)
	(segment
		(start 484.023416 -242.388898)
		(end 484.13035 -242.495832)
		(width 0.1016)
		(layer "In2.Cu")
		(net "TDR_DIFF_85_NECK_IN1_DN")
	)
	(segment
		(start 478.846642 -221.555564)
		(end 478.970086 -222.257112)
		(width 0.1016)
		(layer "In2.Cu")
		(net "TDR_DIFF_85_NECK_IN1_DN")
	)
	(segment
		(start 478.76587 -235.419646)
		(end 478.68332 -235.536994)
		(width 0.1016)
		(layer "In2.Cu")
		(net "TDR_DIFF_85_NECK_IN1_DN")
	)
	(segment
		(start 484.02875 -217.683842)
		(end 484.160322 -217.776552)
		(width 0.1016)
		(layer "In2.Cu")
		(net "TDR_DIFF_85_NECK_IN1_DN")
	)
	(segment
		(start 478.800414 -239.08258)
		(end 478.717864 -239.199928)
		(width 0.1016)
		(layer "In2.Cu")
		(net "TDR_DIFF_85_NECK_IN1_DN")
	)
	(segment
		(start 479.087434 -222.339662)
		(end 488.872784 -220.614494)
		(width 0.1016)
		(layer "In2.Cu")
		(net "TDR_DIFF_85_NECK_IN1_DN")
	)
	(segment
		(start 488.821984 -224.292414)
		(end 489.060236 -224.459292)
		(width 0.1016)
		(layer "In2.Cu")
		(net "TDR_DIFF_85_NECK_IN1_DN")
	)
	(segment
		(start 489.191808 -229.912164)
		(end 478.796604 -231.745028)
		(width 0.1016)
		(layer "In2.Cu")
		(net "TDR_DIFF_85_NECK_IN1_DN")
	)
	(segment
		(start 488.846876 -227.95738)
		(end 489.085382 -228.124258)
		(width 0.1016)
		(layer "In2.Cu")
		(net "TDR_DIFF_85_NECK_IN1_DN")
	)
	(segment
		(start 478.717864 -239.199928)
		(end 478.965514 -240.603532)
		(width 0.1016)
		(layer "In2.Cu")
		(net "TDR_DIFF_85_NECK_IN1_DN")
	)
	(segment
		(start 479.048318 -237.023148)
		(end 488.817158 -235.300774)
		(width 0.1016)
		(layer "In2.Cu")
		(net "TDR_DIFF_85_NECK_IN1_DN")
	)
	(segment
		(start 489.382562 -218.590114)
		(end 489.159042 -218.910662)
		(width 0.1016)
		(layer "In2.Cu")
		(net "TDR_DIFF_85_NECK_IN1_DN")
	)
	(segment
		(start 489.358686 -229.674674)
		(end 489.191808 -229.912164)
		(width 0.1016)
		(layer "In2.Cu")
		(net "TDR_DIFF_85_NECK_IN1_DN")
	)
	(segment
		(start 489.161582 -237.255812)
		(end 478.800414 -239.08258)
		(width 0.1016)
		(layer "In2.Cu")
		(net "TDR_DIFF_85_NECK_IN1_DN")
	)
	(segment
		(start 489.085382 -228.124258)
		(end 489.358686 -229.674674)
		(width 0.1016)
		(layer "In2.Cu")
		(net "TDR_DIFF_85_NECK_IN1_DN")
	)
	(segment
		(start 478.970086 -222.257112)
		(end 479.087434 -222.339662)
		(width 0.1016)
		(layer "In2.Cu")
		(net "TDR_DIFF_85_NECK_IN1_DN")
	)
	(segment
		(start 488.846114 -231.626664)
		(end 489.084366 -231.793542)
		(width 0.1016)
		(layer "In2.Cu")
		(net "TDR_DIFF_85_NECK_IN1_DN")
	)
	(segment
		(start 484.160322 -217.776552)
		(end 488.814364 -216.955624)
		(width 0.1016)
		(layer "In2.Cu")
		(net "TDR_DIFF_85_NECK_IN1_DN")
	)
	(segment
		(start 479.08591 -226.008946)
		(end 488.821984 -224.292414)
		(width 0.1016)
		(layer "In2.Cu")
		(net "TDR_DIFF_85_NECK_IN1_DN")
	)
	(segment
		(start 489.32846 -237.018068)
		(end 489.161582 -237.255812)
		(width 0.1016)
		(layer "In2.Cu")
		(net "TDR_DIFF_85_NECK_IN1_DN")
	)
	(segment
		(start 489.084366 -231.793542)
		(end 489.35767 -233.343958)
		(width 0.1016)
		(layer "In2.Cu")
		(net "TDR_DIFF_85_NECK_IN1_DN")
	)
	(segment
		(start 478.802954 -224.405698)
		(end 478.720658 -224.522792)
		(width 0.1016)
		(layer "In2.Cu")
		(net "TDR_DIFF_85_NECK_IN1_DN")
	)
	(segment
		(start 484.02875 -216.219532)
		(end 484.02875 -217.683842)
		(width 0.1016)
		(layer "In2.Cu")
		(net "TDR_DIFF_85_NECK_IN1_DN")
	)
	(segment
		(start 478.714054 -231.862376)
		(end 478.961704 -233.26598)
		(width 0.1016)
		(layer "In2.Cu")
		(net "TDR_DIFF_85_NECK_IN1_DN")
	)
	(segment
		(start 479.079052 -233.34853)
		(end 488.846114 -231.626664)
		(width 0.1016)
		(layer "In2.Cu")
		(net "TDR_DIFF_85_NECK_IN1_DN")
	)
	(segment
		(start 489.055156 -235.467652)
		(end 489.32846 -237.018068)
		(width 0.1016)
		(layer "In2.Cu")
		(net "TDR_DIFF_85_NECK_IN1_DN")
	)
	(segment
		(start 478.968308 -225.926396)
		(end 479.08591 -226.008946)
		(width 0.1016)
		(layer "In2.Cu")
		(net "TDR_DIFF_85_NECK_IN1_DN")
	)
	(segment
		(start 484.13035 -242.495832)
		(end 485.20985 -242.495832)
		(width 0.1016)
		(layer "In2.Cu")
		(net "TDR_DIFF_85_NECK_IN1_DN")
	)
	(segment
		(start 489.111036 -220.781372)
		(end 489.38434 -222.331788)
		(width 0.1016)
		(layer "In2.Cu")
		(net "TDR_DIFF_85_NECK_IN1_DN")
	)
	(segment
		(start 489.166662 -226.247706)
		(end 478.769934 -228.08057)
		(width 0.1016)
		(layer "In2.Cu")
		(net "TDR_DIFF_85_NECK_IN1_DN")
	)
	(segment
		(start 489.38434 -222.331788)
		(end 489.217462 -222.569532)
		(width 0.1016)
		(layer "In2.Cu")
		(net "TDR_DIFF_85_NECK_IN1_DN")
	)
	(segment
		(start 478.769934 -228.08057)
		(end 478.687384 -228.197918)
		(width 0.1016)
		(layer "In2.Cu")
		(net "TDR_DIFF_85_NECK_IN1_DN")
	)
	(segment
		(start 489.190792 -233.581702)
		(end 478.76587 -235.419646)
		(width 0.1016)
		(layer "In2.Cu")
		(net "TDR_DIFF_85_NECK_IN1_DN")
	)
	(segment
		(start 488.872784 -220.614494)
		(end 489.111036 -220.781372)
		(width 0.1016)
		(layer "In2.Cu")
		(net "TDR_DIFF_85_NECK_IN1_DN")
	)
	(segment
		(start 139.34694 -13.600176)
		(end 139.34694 -12.213082)
		(width 0.12954)
		(layer "F.Cu")
		(net "FM_BMC_INTRUDER_N")
	)
	(segment
		(start 139.34694 -12.213082)
		(end 139.346686 -12.212828)
		(width 0.12954)
		(layer "F.Cu")
		(net "FM_BMC_INTRUDER_N")
	)
	(via
		(at 139.346686 -12.212828)
		(size 0.508)
		(drill 0.254)
		(layers "F.Cu" "B.Cu")
		(net "FM_BMC_INTRUDER_N")
	)
	(segment
		(start 139.346686 -9.762998)
		(end 139.346686 -12.212828)
		(width 0.12954)
		(layer "B.Cu")
		(net "FM_BMC_INTRUDER_N")
	)
	(segment
		(start 278.55672 -423.48404)
		(end 278.474678 -423.401998)
		(width 0.381)
		(layer "F.Cu")
		(net "U369_VDD")
	)
	(segment
		(start 279.00757 -425.69638)
		(end 279.00757 -425.3738)
		(width 0.381)
		(layer "F.Cu")
		(net "U369_VDD")
	)
	(segment
		(start 279.43175 -424.94962)
		(end 279.43175 -424.69562)
		(width 0.381)
		(layer "F.Cu")
		(net "U369_VDD")
	)
	(segment
		(start 278.474678 -423.401998)
		(end 278.474678 -421.96131)
		(width 0.381)
		(layer "F.Cu")
		(net "U369_VDD")
	)
	(segment
		(start 279.43175 -424.35907)
		(end 278.55672 -423.48404)
		(width 0.381)
		(layer "F.Cu")
		(net "U369_VDD")
	)
	(segment
		(start 279.00757 -425.3738)
		(end 279.43175 -424.94962)
		(width 0.381)
		(layer "F.Cu")
		(net "U369_VDD")
	)
	(segment
		(start 279.00757 -425.69638)
		(end 279.00757 -426.68698)
		(width 0.381)
		(layer "F.Cu")
		(net "U369_VDD")
	)
	(segment
		(start 279.43175 -424.69562)
		(end 279.43175 -424.35907)
		(width 0.381)
		(layer "F.Cu")
		(net "U369_VDD")
	)
	(via
		(at 278.55672 -423.48404)
		(size 0.762)
		(drill 0.381)
		(layers "F.Cu" "B.Cu")
		(net "U369_VDD")
	)
	(segment
		(start 217.73896 -99.79152)
		(end 218.343734 -100.396294)
		(width 0.381)
		(layer "F.Cu")
		(net "U206_VDD")
	)
	(segment
		(start 216.661492 -99.79152)
		(end 217.73896 -99.79152)
		(width 0.381)
		(layer "F.Cu")
		(net "U206_VDD")
	)
	(segment
		(start 219.687394 -101.24948)
		(end 219.687394 -100.23348)
		(width 0.381)
		(layer "F.Cu")
		(net "U206_VDD")
	)
	(segment
		(start 219.687394 -99.21748)
		(end 219.687394 -100.23348)
		(width 0.381)
		(layer "F.Cu")
		(net "U206_VDD")
	)
	(segment
		(start 219.687394 -101.24948)
		(end 219.19692 -101.24948)
		(width 0.381)
		(layer "F.Cu")
		(net "U206_VDD")
	)
	(segment
		(start 219.19692 -101.24948)
		(end 218.343734 -100.396294)
		(width 0.381)
		(layer "F.Cu")
		(net "U206_VDD")
	)
	(via
		(at 218.343734 -100.396294)
		(size 0.762)
		(drill 0.381)
		(layers "F.Cu" "B.Cu")
		(net "U206_VDD")
	)
	(segment
		(start 210.960208 -104.96804)
		(end 210.960208 -103.95204)
		(width 0.381)
		(layer "F.Cu")
		(net "U205_VDD")
	)
	(segment
		(start 210.960208 -102.93604)
		(end 210.960208 -103.95204)
		(width 0.381)
		(layer "F.Cu")
		(net "U205_VDD")
	)
	(segment
		(start 211.77504 -104.96804)
		(end 212.41004 -104.33304)
		(width 0.381)
		(layer "F.Cu")
		(net "U205_VDD")
	)
	(segment
		(start 213.98738 -104.33304)
		(end 212.41004 -104.33304)
		(width 0.381)
		(layer "F.Cu")
		(net "U205_VDD")
	)
	(segment
		(start 210.960208 -104.96804)
		(end 211.77504 -104.96804)
		(width 0.381)
		(layer "F.Cu")
		(net "U205_VDD")
	)
	(via
		(at 212.41004 -104.33304)
		(size 0.762)
		(drill 0.381)
		(layers "F.Cu" "B.Cu")
		(net "U205_VDD")
	)
	(segment
		(start 210.1342 -111.353854)
		(end 210.44916 -111.668814)
		(width 0.12954)
		(layer "F.Cu")
		(net "UV_P2V5_COMP")
	)
	(segment
		(start 210.1342 -109.6772)
		(end 210.1342 -111.353854)
		(width 0.12954)
		(layer "F.Cu")
		(net "UV_P2V5_COMP")
	)
	(segment
		(start 211.1248 -109.0422)
		(end 211.2518 -109.1692)
		(width 0.12954)
		(layer "F.Cu")
		(net "UV_P2V5_COMP")
	)
	(segment
		(start 210.44916 -113.35004)
		(end 210.312 -113.4872)
		(width 0.12954)
		(layer "F.Cu")
		(net "UV_P2V5_COMP")
	)
	(segment
		(start 209.7278 -113.4872)
		(end 209.53095 -113.68405)
		(width 0.12954)
		(layer "F.Cu")
		(net "UV_P2V5_COMP")
	)
	(segment
		(start 209.53095 -113.68405)
		(end 209.53095 -114.0968)
		(width 0.12954)
		(layer "F.Cu")
		(net "UV_P2V5_COMP")
	)
	(segment
		(start 211.2518 -110.019084)
		(end 211.3788 -110.146084)
		(width 0.12954)
		(layer "F.Cu")
		(net "UV_P2V5_COMP")
	)
	(segment
		(start 210.44916 -111.668814)
		(end 210.44916 -112.61471)
		(width 0.12954)
		(layer "F.Cu")
		(net "UV_P2V5_COMP")
	)
	(segment
		(start 210.7692 -109.0422)
		(end 210.1342 -109.6772)
		(width 0.12954)
		(layer "F.Cu")
		(net "UV_P2V5_COMP")
	)
	(segment
		(start 210.312 -113.4872)
		(end 209.7278 -113.4872)
		(width 0.12954)
		(layer "F.Cu")
		(net "UV_P2V5_COMP")
	)
	(segment
		(start 208.50225 -114.0968)
		(end 209.53095 -114.0968)
		(width 0.12954)
		(layer "F.Cu")
		(net "UV_P2V5_COMP")
	)
	(segment
		(start 212.20684 -109.99216)
		(end 212.20684 -109.26699)
		(width 0.12954)
		(layer "F.Cu")
		(net "UV_P2V5_COMP")
	)
	(segment
		(start 211.3788 -110.146084)
		(end 212.052916 -110.146084)
		(width 0.12954)
		(layer "F.Cu")
		(net "UV_P2V5_COMP")
	)
	(segment
		(start 212.052916 -110.146084)
		(end 212.20684 -109.99216)
		(width 0.12954)
		(layer "F.Cu")
		(net "UV_P2V5_COMP")
	)
	(segment
		(start 211.2518 -109.1692)
		(end 211.2518 -110.019084)
		(width 0.12954)
		(layer "F.Cu")
		(net "UV_P2V5_COMP")
	)
	(segment
		(start 210.7692 -109.0422)
		(end 211.1248 -109.0422)
		(width 0.12954)
		(layer "F.Cu")
		(net "UV_P2V5_COMP")
	)
	(segment
		(start 210.44916 -112.61471)
		(end 210.44916 -113.35004)
		(width 0.12954)
		(layer "F.Cu")
		(net "UV_P2V5_COMP")
	)
	(via
		(at 210.7692 -109.0422)
		(size 0.762)
		(drill 0.381)
		(layers "F.Cu" "B.Cu")
		(net "UV_P2V5_COMP")
	)
	(segment
		(start 202.19924 -96.09836)
		(end 202.19924 -94.56801)
		(width 0.12954)
		(layer "F.Cu")
		(net "UV_ADR_P2V5_COMP")
	)
	(segment
		(start 200.44156 -95.16491)
		(end 200.44156 -96.65716)
		(width 0.12954)
		(layer "F.Cu")
		(net "UV_ADR_P2V5_COMP")
	)
	(segment
		(start 201.8284 -93.48216)
		(end 202.19924 -93.853)
		(width 0.12954)
		(layer "F.Cu")
		(net "UV_ADR_P2V5_COMP")
	)
	(segment
		(start 201.64044 -96.65716)
		(end 202.19924 -96.09836)
		(width 0.12954)
		(layer "F.Cu")
		(net "UV_ADR_P2V5_COMP")
	)
	(segment
		(start 201.8284 -93.03385)
		(end 202.7936 -93.03385)
		(width 0.12954)
		(layer "F.Cu")
		(net "UV_ADR_P2V5_COMP")
	)
	(segment
		(start 202.19924 -93.853)
		(end 202.19924 -94.56801)
		(width 0.12954)
		(layer "F.Cu")
		(net "UV_ADR_P2V5_COMP")
	)
	(segment
		(start 201.8284 -93.03385)
		(end 201.8284 -93.48216)
		(width 0.12954)
		(layer "F.Cu")
		(net "UV_ADR_P2V5_COMP")
	)
	(segment
		(start 200.44156 -96.65716)
		(end 201.64044 -96.65716)
		(width 0.12954)
		(layer "F.Cu")
		(net "UV_ADR_P2V5_COMP")
	)
	(via
		(at 200.44156 -96.65716)
		(size 0.762)
		(drill 0.381)
		(layers "F.Cu" "B.Cu")
		(net "UV_ADR_P2V5_COMP")
	)
	(segment
		(start 44.064428 -101.872034)
		(end 43.636184 -101.44379)
		(width 0.12954)
		(layer "F.Cu")
		(net "SMB_SEN_MAM_3V3AUX_SDA")
	)
	(segment
		(start 20.70227 -113.633758)
		(end 22.191472 -113.633758)
		(width 0.12954)
		(layer "F.Cu")
		(net "SMB_SEN_MAM_3V3AUX_SDA")
	)
	(segment
		(start 22.191472 -113.633758)
		(end 22.409404 -113.415826)
		(width 0.12954)
		(layer "F.Cu")
		(net "SMB_SEN_MAM_3V3AUX_SDA")
	)
	(segment
		(start 43.636184 -101.44379)
		(end 42.29862 -101.44379)
		(width 0.12954)
		(layer "F.Cu")
		(net "SMB_SEN_MAM_3V3AUX_SDA")
	)
	(segment
		(start 44.699428 -101.872034)
		(end 44.064428 -101.872034)
		(width 0.12954)
		(layer "F.Cu")
		(net "SMB_SEN_MAM_3V3AUX_SDA")
	)
	(segment
		(start 44.699428 -101.872034)
		(end 46.18863 -101.872034)
		(width 0.12954)
		(layer "F.Cu")
		(net "SMB_SEN_MAM_3V3AUX_SDA")
	)
	(via
		(at 20.70227 -113.633758)
		(size 0.508)
		(drill 0.254)
		(layers "F.Cu" "B.Cu")
		(net "SMB_SEN_MAM_3V3AUX_SDA")
	)
	(via
		(at 32.54883 -115.245388)
		(size 0.6604)
		(drill 0.3302)
		(layers "F.Cu" "B.Cu")
		(net "SMB_SEN_MAM_3V3AUX_SDA")
	)
	(via
		(at 44.699428 -101.872034)
		(size 0.762)
		(drill 0.381)
		(layers "F.Cu" "B.Cu")
		(net "SMB_SEN_MAM_3V3AUX_SDA")
	)
	(via
		(at 46.18863 -101.872034)
		(size 0.508)
		(drill 0.254)
		(layers "F.Cu" "B.Cu")
		(net "SMB_SEN_MAM_3V3AUX_SDA")
	)
	(segment
		(start 35.651186 -114.419888)
		(end 35.521646 -114.290348)
		(width 0.12954)
		(layer "B.Cu")
		(net "SMB_SEN_MAM_3V3AUX_SDA")
	)
	(segment
		(start 36.796726 -114.290348)
		(end 36.418266 -114.290348)
		(width 0.12954)
		(layer "B.Cu")
		(net "SMB_SEN_MAM_3V3AUX_SDA")
	)
	(segment
		(start 38.071806 -114.290348)
		(end 37.693346 -114.290348)
		(width 0.12954)
		(layer "B.Cu")
		(net "SMB_SEN_MAM_3V3AUX_SDA")
	)
	(segment
		(start 36.926266 -115.115848)
		(end 36.926266 -114.419888)
		(width 0.12954)
		(layer "B.Cu")
		(net "SMB_SEN_MAM_3V3AUX_SDA")
	)
	(segment
		(start 44.407836 -103.652828)
		(end 43.33748 -103.652828)
		(width 0.12954)
		(layer "B.Cu")
		(net "SMB_SEN_MAM_3V3AUX_SDA")
	)
	(segment
		(start 36.418266 -114.290348)
		(end 36.288726 -114.419888)
		(width 0.12954)
		(layer "B.Cu")
		(net "SMB_SEN_MAM_3V3AUX_SDA")
	)
	(segment
		(start 36.159186 -115.245388)
		(end 35.780726 -115.245388)
		(width 0.12954)
		(layer "B.Cu")
		(net "SMB_SEN_MAM_3V3AUX_SDA")
	)
	(segment
		(start 35.013646 -114.419888)
		(end 35.013646 -115.115848)
		(width 0.12954)
		(layer "B.Cu")
		(net "SMB_SEN_MAM_3V3AUX_SDA")
	)
	(segment
		(start 21.71319 -113.633758)
		(end 23.32482 -115.245388)
		(width 0.12954)
		(layer "B.Cu")
		(net "SMB_SEN_MAM_3V3AUX_SDA")
	)
	(segment
		(start 35.521646 -114.290348)
		(end 35.143186 -114.290348)
		(width 0.12954)
		(layer "B.Cu")
		(net "SMB_SEN_MAM_3V3AUX_SDA")
	)
	(segment
		(start 43.33748 -103.652828)
		(end 42.93616 -104.054148)
		(width 0.12954)
		(layer "B.Cu")
		(net "SMB_SEN_MAM_3V3AUX_SDA")
	)
	(segment
		(start 37.563806 -115.115848)
		(end 37.434266 -115.245388)
		(width 0.12954)
		(layer "B.Cu")
		(net "SMB_SEN_MAM_3V3AUX_SDA")
	)
	(segment
		(start 35.143186 -114.290348)
		(end 35.013646 -114.419888)
		(width 0.12954)
		(layer "B.Cu")
		(net "SMB_SEN_MAM_3V3AUX_SDA")
	)
	(segment
		(start 38.201346 -114.419888)
		(end 38.071806 -114.290348)
		(width 0.12954)
		(layer "B.Cu")
		(net "SMB_SEN_MAM_3V3AUX_SDA")
	)
	(segment
		(start 38.201346 -115.115848)
		(end 38.201346 -114.419888)
		(width 0.12954)
		(layer "B.Cu")
		(net "SMB_SEN_MAM_3V3AUX_SDA")
	)
	(segment
		(start 35.651186 -115.115848)
		(end 35.651186 -114.419888)
		(width 0.12954)
		(layer "B.Cu")
		(net "SMB_SEN_MAM_3V3AUX_SDA")
	)
	(segment
		(start 37.434266 -115.245388)
		(end 37.055806 -115.245388)
		(width 0.12954)
		(layer "B.Cu")
		(net "SMB_SEN_MAM_3V3AUX_SDA")
	)
	(segment
		(start 37.693346 -114.290348)
		(end 37.563806 -114.419888)
		(width 0.12954)
		(layer "B.Cu")
		(net "SMB_SEN_MAM_3V3AUX_SDA")
	)
	(segment
		(start 40.67302 -115.245388)
		(end 38.330886 -115.245388)
		(width 0.12954)
		(layer "B.Cu")
		(net "SMB_SEN_MAM_3V3AUX_SDA")
	)
	(segment
		(start 42.93616 -112.982248)
		(end 40.67302 -115.245388)
		(width 0.12954)
		(layer "B.Cu")
		(net "SMB_SEN_MAM_3V3AUX_SDA")
	)
	(segment
		(start 42.93616 -104.054148)
		(end 42.93616 -112.982248)
		(width 0.12954)
		(layer "B.Cu")
		(net "SMB_SEN_MAM_3V3AUX_SDA")
	)
	(segment
		(start 34.884106 -115.245388)
		(end 32.54883 -115.245388)
		(width 0.12954)
		(layer "B.Cu")
		(net "SMB_SEN_MAM_3V3AUX_SDA")
	)
	(segment
		(start 37.055806 -115.245388)
		(end 36.926266 -115.115848)
		(width 0.12954)
		(layer "B.Cu")
		(net "SMB_SEN_MAM_3V3AUX_SDA")
	)
	(segment
		(start 46.18863 -101.872034)
		(end 44.407836 -103.652828)
		(width 0.12954)
		(layer "B.Cu")
		(net "SMB_SEN_MAM_3V3AUX_SDA")
	)
	(segment
		(start 20.70227 -113.633758)
		(end 21.71319 -113.633758)
		(width 0.12954)
		(layer "B.Cu")
		(net "SMB_SEN_MAM_3V3AUX_SDA")
	)
	(segment
		(start 36.288726 -114.419888)
		(end 36.288726 -115.115848)
		(width 0.12954)
		(layer "B.Cu")
		(net "SMB_SEN_MAM_3V3AUX_SDA")
	)
	(segment
		(start 35.013646 -115.115848)
		(end 34.884106 -115.245388)
		(width 0.12954)
		(layer "B.Cu")
		(net "SMB_SEN_MAM_3V3AUX_SDA")
	)
	(segment
		(start 23.32482 -115.245388)
		(end 32.54883 -115.245388)
		(width 0.12954)
		(layer "B.Cu")
		(net "SMB_SEN_MAM_3V3AUX_SDA")
	)
	(segment
		(start 38.330886 -115.245388)
		(end 38.201346 -115.115848)
		(width 0.12954)
		(layer "B.Cu")
		(net "SMB_SEN_MAM_3V3AUX_SDA")
	)
	(segment
		(start 35.780726 -115.245388)
		(end 35.651186 -115.115848)
		(width 0.12954)
		(layer "B.Cu")
		(net "SMB_SEN_MAM_3V3AUX_SDA")
	)
	(segment
		(start 36.288726 -115.115848)
		(end 36.159186 -115.245388)
		(width 0.12954)
		(layer "B.Cu")
		(net "SMB_SEN_MAM_3V3AUX_SDA")
	)
	(segment
		(start 37.563806 -114.419888)
		(end 37.563806 -115.115848)
		(width 0.12954)
		(layer "B.Cu")
		(net "SMB_SEN_MAM_3V3AUX_SDA")
	)
	(segment
		(start 36.926266 -114.419888)
		(end 36.796726 -114.290348)
		(width 0.12954)
		(layer "B.Cu")
		(net "SMB_SEN_MAM_3V3AUX_SDA")
	)
	(segment
		(start 43.222672 -100.80879)
		(end 42.29862 -100.80879)
		(width 0.12954)
		(layer "F.Cu")
		(net "SMB_SEN_MAM_3V3AUX_SCL")
	)
	(segment
		(start 44.064428 -100.729034)
		(end 43.302428 -100.729034)
		(width 0.12954)
		(layer "F.Cu")
		(net "SMB_SEN_MAM_3V3AUX_SCL")
	)
	(segment
		(start 44.064428 -100.729034)
		(end 45.30725 -100.729034)
		(width 0.12954)
		(layer "F.Cu")
		(net "SMB_SEN_MAM_3V3AUX_SCL")
	)
	(segment
		(start 39.82847 -121.980452)
		(end 37.890196 -121.980452)
		(width 0.12954)
		(layer "F.Cu")
		(net "SMB_SEN_MAM_3V3AUX_SCL")
	)
	(segment
		(start 43.848528 -115.34013)
		(end 41.316402 -115.34013)
		(width 0.12954)
		(layer "F.Cu")
		(net "SMB_SEN_MAM_3V3AUX_SCL")
	)
	(segment
		(start 41.189402 -115.46713)
		(end 41.189402 -120.61952)
		(width 0.12954)
		(layer "F.Cu")
		(net "SMB_SEN_MAM_3V3AUX_SCL")
	)
	(segment
		(start 43.302428 -100.729034)
		(end 43.222672 -100.80879)
		(width 0.12954)
		(layer "F.Cu")
		(net "SMB_SEN_MAM_3V3AUX_SCL")
	)
	(segment
		(start 41.316402 -115.34013)
		(end 41.189402 -115.46713)
		(width 0.12954)
		(layer "F.Cu")
		(net "SMB_SEN_MAM_3V3AUX_SCL")
	)
	(segment
		(start 41.189402 -120.61952)
		(end 39.82847 -121.980452)
		(width 0.12954)
		(layer "F.Cu")
		(net "SMB_SEN_MAM_3V3AUX_SCL")
	)
	(via
		(at 43.848528 -115.34013)
		(size 0.508)
		(drill 0.254)
		(layers "F.Cu" "B.Cu")
		(net "SMB_SEN_MAM_3V3AUX_SCL")
	)
	(via
		(at 44.064428 -100.729034)
		(size 0.762)
		(drill 0.381)
		(layers "F.Cu" "B.Cu")
		(net "SMB_SEN_MAM_3V3AUX_SCL")
	)
	(via
		(at 45.30725 -100.729034)
		(size 0.508)
		(drill 0.254)
		(layers "F.Cu" "B.Cu")
		(net "SMB_SEN_MAM_3V3AUX_SCL")
	)
	(segment
		(start 48.210978 -98.854006)
		(end 47.700692 -99.364292)
		(width 0.12954)
		(layer "B.Cu")
		(net "SMB_SEN_MAM_3V3AUX_SCL")
	)
	(segment
		(start 45.30725 -100.419662)
		(end 45.30725 -100.729034)
		(width 0.12954)
		(layer "B.Cu")
		(net "SMB_SEN_MAM_3V3AUX_SCL")
	)
	(segment
		(start 43.848528 -115.34013)
		(end 44.45889 -114.729768)
		(width 0.12954)
		(layer "B.Cu")
		(net "SMB_SEN_MAM_3V3AUX_SCL")
	)
	(segment
		(start 44.45889 -114.729768)
		(end 44.45889 -106.433874)
		(width 0.12954)
		(layer "B.Cu")
		(net "SMB_SEN_MAM_3V3AUX_SCL")
	)
	(segment
		(start 47.700692 -99.364292)
		(end 46.36262 -99.364292)
		(width 0.12954)
		(layer "B.Cu")
		(net "SMB_SEN_MAM_3V3AUX_SCL")
	)
	(segment
		(start 50.486818 -99.564444)
		(end 49.77638 -98.854006)
		(width 0.12954)
		(layer "B.Cu")
		(net "SMB_SEN_MAM_3V3AUX_SCL")
	)
	(segment
		(start 44.45889 -106.433874)
		(end 45.038264 -105.8545)
		(width 0.12954)
		(layer "B.Cu")
		(net "SMB_SEN_MAM_3V3AUX_SCL")
	)
	(segment
		(start 49.77638 -98.854006)
		(end 48.210978 -98.854006)
		(width 0.12954)
		(layer "B.Cu")
		(net "SMB_SEN_MAM_3V3AUX_SCL")
	)
	(segment
		(start 46.36262 -99.364292)
		(end 45.30725 -100.419662)
		(width 0.12954)
		(layer "B.Cu")
		(net "SMB_SEN_MAM_3V3AUX_SCL")
	)
	(segment
		(start 50.486818 -104.419908)
		(end 50.486818 -99.564444)
		(width 0.12954)
		(layer "B.Cu")
		(net "SMB_SEN_MAM_3V3AUX_SCL")
	)
	(segment
		(start 49.052226 -105.8545)
		(end 50.486818 -104.419908)
		(width 0.12954)
		(layer "B.Cu")
		(net "SMB_SEN_MAM_3V3AUX_SCL")
	)
	(segment
		(start 45.038264 -105.8545)
		(end 49.052226 -105.8545)
		(width 0.12954)
		(layer "B.Cu")
		(net "SMB_SEN_MAM_3V3AUX_SCL")
	)
	(segment
		(start 243.880386 -135.730996)
		(end 243.880386 -137.217658)
		(width 0.12954)
		(layer "F.Cu")
		(net "SMB_HOST_3V3AUX_PLD_SDA")
	)
	(segment
		(start 243.880386 -137.217658)
		(end 243.753386 -137.344658)
		(width 0.12954)
		(layer "F.Cu")
		(net "SMB_HOST_3V3AUX_PLD_SDA")
	)
	(segment
		(start 170.955716 -112.175544)
		(end 170.555666 -112.575594)
		(width 0.12954)
		(layer "F.Cu")
		(net "SMB_HOST_3V3AUX_PLD_SDA")
	)
	(segment
		(start 243.675154 -135.525764)
		(end 243.880386 -135.730996)
		(width 0.12954)
		(layer "F.Cu")
		(net "SMB_HOST_3V3AUX_PLD_SDA")
	)
	(segment
		(start 243.753386 -137.344658)
		(end 243.445284 -137.344658)
		(width 0.12954)
		(layer "F.Cu")
		(net "SMB_HOST_3V3AUX_PLD_SDA")
	)
	(via
		(at 170.555666 -112.575594)
		(size 0.4572)
		(drill 0.254)
		(layers "F.Cu" "B.Cu")
		(net "SMB_HOST_3V3AUX_PLD_SDA")
	)
	(via
		(at 155.142438 -136.532112)
		(size 0.508)
		(drill 0.254)
		(layers "F.Cu" "B.Cu")
		(net "SMB_HOST_3V3AUX_PLD_SDA")
	)
	(via
		(at 243.675154 -135.525764)
		(size 0.508)
		(drill 0.254)
		(layers "F.Cu" "B.Cu")
		(net "SMB_HOST_3V3AUX_PLD_SDA")
	)
	(segment
		(start 155.142438 -136.532112)
		(end 155.142438 -135.662162)
		(width 0.12954)
		(layer "B.Cu")
		(net "SMB_HOST_3V3AUX_PLD_SDA")
	)
	(segment
		(start 156.303472 -120.8532)
		(end 155.12034 -120.8532)
		(width 0.12954)
		(layer "B.Cu")
		(net "SMB_HOST_3V3AUX_PLD_SDA")
	)
	(segment
		(start 170.17746 -112.9538)
		(end 170.555666 -112.575594)
		(width 0.12954)
		(layer "B.Cu")
		(net "SMB_HOST_3V3AUX_PLD_SDA")
	)
	(segment
		(start 158.315914 -110.94974)
		(end 159.782764 -111.5568)
		(width 0.12954)
		(layer "B.Cu")
		(net "SMB_HOST_3V3AUX_PLD_SDA")
	)
	(segment
		(start 154.561794 -117.858794)
		(end 154.561794 -110.715806)
		(width 0.12954)
		(layer "B.Cu")
		(net "SMB_HOST_3V3AUX_PLD_SDA")
	)
	(segment
		(start 154.561794 -110.715806)
		(end 154.916632 -110.360968)
		(width 0.12954)
		(layer "B.Cu")
		(net "SMB_HOST_3V3AUX_PLD_SDA")
	)
	(segment
		(start 167.72255 -112.9538)
		(end 170.17746 -112.9538)
		(width 0.12954)
		(layer "B.Cu")
		(net "SMB_HOST_3V3AUX_PLD_SDA")
	)
	(segment
		(start 167.44315 -112.6744)
		(end 167.72255 -112.9538)
		(width 0.12954)
		(layer "B.Cu")
		(net "SMB_HOST_3V3AUX_PLD_SDA")
	)
	(segment
		(start 155.142438 -135.662162)
		(end 157.7086 -133.096)
		(width 0.12954)
		(layer "B.Cu")
		(net "SMB_HOST_3V3AUX_PLD_SDA")
	)
	(segment
		(start 154.60091 -120.33377)
		(end 154.60091 -119.51589)
		(width 0.12954)
		(layer "B.Cu")
		(net "SMB_HOST_3V3AUX_PLD_SDA")
	)
	(segment
		(start 157.7086 -133.096)
		(end 157.7086 -129.2098)
		(width 0.12954)
		(layer "B.Cu")
		(net "SMB_HOST_3V3AUX_PLD_SDA")
	)
	(segment
		(start 154.916632 -110.360968)
		(end 157.727142 -110.360968)
		(width 0.12954)
		(layer "B.Cu")
		(net "SMB_HOST_3V3AUX_PLD_SDA")
	)
	(segment
		(start 156.591 -121.140728)
		(end 156.303472 -120.8532)
		(width 0.12954)
		(layer "B.Cu")
		(net "SMB_HOST_3V3AUX_PLD_SDA")
	)
	(segment
		(start 156.591 -128.0922)
		(end 156.591 -121.140728)
		(width 0.12954)
		(layer "B.Cu")
		(net "SMB_HOST_3V3AUX_PLD_SDA")
	)
	(segment
		(start 154.9146 -118.2116)
		(end 154.561794 -117.858794)
		(width 0.12954)
		(layer "B.Cu")
		(net "SMB_HOST_3V3AUX_PLD_SDA")
	)
	(segment
		(start 161.299398 -112.6744)
		(end 167.44315 -112.6744)
		(width 0.12954)
		(layer "B.Cu")
		(net "SMB_HOST_3V3AUX_PLD_SDA")
	)
	(segment
		(start 160.181798 -111.5568)
		(end 161.299398 -112.6744)
		(width 0.12954)
		(layer "B.Cu")
		(net "SMB_HOST_3V3AUX_PLD_SDA")
	)
	(segment
		(start 157.727142 -110.360968)
		(end 158.315914 -110.94974)
		(width 0.12954)
		(layer "B.Cu")
		(net "SMB_HOST_3V3AUX_PLD_SDA")
	)
	(segment
		(start 154.9146 -119.2022)
		(end 154.9146 -118.2116)
		(width 0.12954)
		(layer "B.Cu")
		(net "SMB_HOST_3V3AUX_PLD_SDA")
	)
	(segment
		(start 155.12034 -120.8532)
		(end 154.60091 -120.33377)
		(width 0.12954)
		(layer "B.Cu")
		(net "SMB_HOST_3V3AUX_PLD_SDA")
	)
	(segment
		(start 159.782764 -111.5568)
		(end 160.181798 -111.5568)
		(width 0.12954)
		(layer "B.Cu")
		(net "SMB_HOST_3V3AUX_PLD_SDA")
	)
	(segment
		(start 157.7086 -129.2098)
		(end 156.591 -128.0922)
		(width 0.12954)
		(layer "B.Cu")
		(net "SMB_HOST_3V3AUX_PLD_SDA")
	)
	(segment
		(start 154.60091 -119.51589)
		(end 154.9146 -119.2022)
		(width 0.12954)
		(layer "B.Cu")
		(net "SMB_HOST_3V3AUX_PLD_SDA")
	)
	(segment
		(start 225.718878 -132.447792)
		(end 223.217232 -132.447792)
		(width 0.127)
		(layer "In15.Cu")
		(net "SMB_HOST_3V3AUX_PLD_SDA")
	)
	(segment
		(start 194.196716 -137.488422)
		(end 179.241704 -137.488422)
		(width 0.127)
		(layer "In15.Cu")
		(net "SMB_HOST_3V3AUX_PLD_SDA")
	)
	(segment
		(start 155.879546 -135.795004)
		(end 155.142438 -136.532112)
		(width 0.127)
		(layer "In15.Cu")
		(net "SMB_HOST_3V3AUX_PLD_SDA")
	)
	(segment
		(start 227.114608 -133.843522)
		(end 225.718878 -132.447792)
		(width 0.127)
		(layer "In15.Cu")
		(net "SMB_HOST_3V3AUX_PLD_SDA")
	)
	(segment
		(start 194.965066 -138.256772)
		(end 194.196716 -137.488422)
		(width 0.127)
		(layer "In15.Cu")
		(net "SMB_HOST_3V3AUX_PLD_SDA")
	)
	(segment
		(start 178.887882 -137.1346)
		(end 158.85414 -137.1346)
		(width 0.127)
		(layer "In15.Cu")
		(net "SMB_HOST_3V3AUX_PLD_SDA")
	)
	(segment
		(start 210.134454 -138.256772)
		(end 194.965066 -138.256772)
		(width 0.127)
		(layer "In15.Cu")
		(net "SMB_HOST_3V3AUX_PLD_SDA")
	)
	(segment
		(start 219.808806 -135.856218)
		(end 212.535008 -135.856218)
		(width 0.127)
		(layer "In15.Cu")
		(net "SMB_HOST_3V3AUX_PLD_SDA")
	)
	(segment
		(start 231.051608 -133.843522)
		(end 227.114608 -133.843522)
		(width 0.127)
		(layer "In15.Cu")
		(net "SMB_HOST_3V3AUX_PLD_SDA")
	)
	(segment
		(start 223.217232 -132.447792)
		(end 219.808806 -135.856218)
		(width 0.127)
		(layer "In15.Cu")
		(net "SMB_HOST_3V3AUX_PLD_SDA")
	)
	(segment
		(start 179.241704 -137.488422)
		(end 178.887882 -137.1346)
		(width 0.127)
		(layer "In15.Cu")
		(net "SMB_HOST_3V3AUX_PLD_SDA")
	)
	(segment
		(start 157.514544 -135.795004)
		(end 155.879546 -135.795004)
		(width 0.127)
		(layer "In15.Cu")
		(net "SMB_HOST_3V3AUX_PLD_SDA")
	)
	(segment
		(start 158.85414 -137.1346)
		(end 157.514544 -135.795004)
		(width 0.127)
		(layer "In15.Cu")
		(net "SMB_HOST_3V3AUX_PLD_SDA")
	)
	(segment
		(start 234.046776 -136.83869)
		(end 231.051608 -133.843522)
		(width 0.127)
		(layer "In15.Cu")
		(net "SMB_HOST_3V3AUX_PLD_SDA")
	)
	(segment
		(start 212.535008 -135.856218)
		(end 210.134454 -138.256772)
		(width 0.127)
		(layer "In15.Cu")
		(net "SMB_HOST_3V3AUX_PLD_SDA")
	)
	(segment
		(start 242.362228 -136.83869)
		(end 234.046776 -136.83869)
		(width 0.127)
		(layer "In15.Cu")
		(net "SMB_HOST_3V3AUX_PLD_SDA")
	)
	(segment
		(start 243.675154 -135.525764)
		(end 242.362228 -136.83869)
		(width 0.127)
		(layer "In15.Cu")
		(net "SMB_HOST_3V3AUX_PLD_SDA")
	)
	(segment
		(start 243.445538 -136.348724)
		(end 243.1288 -136.031986)
		(width 0.12954)
		(layer "F.Cu")
		(net "SMB_HOST_3V3AUX_PLD_SCL")
	)
	(segment
		(start 242.955826 -135.057134)
		(end 242.955572 -135.018018)
		(width 0.12954)
		(layer "F.Cu")
		(net "SMB_HOST_3V3AUX_PLD_SCL")
	)
	(segment
		(start 243.1288 -136.031986)
		(end 243.1288 -135.230108)
		(width 0.12954)
		(layer "F.Cu")
		(net "SMB_HOST_3V3AUX_PLD_SCL")
	)
	(segment
		(start 170.155616 -112.175544)
		(end 169.589958 -112.175544)
		(width 0.12954)
		(layer "F.Cu")
		(net "SMB_HOST_3V3AUX_PLD_SCL")
	)
	(segment
		(start 243.1288 -135.230108)
		(end 242.955826 -135.057134)
		(width 0.12954)
		(layer "F.Cu")
		(net "SMB_HOST_3V3AUX_PLD_SCL")
	)
	(via
		(at 154.261312 -136.520174)
		(size 0.508)
		(drill 0.254)
		(layers "F.Cu" "B.Cu")
		(net "SMB_HOST_3V3AUX_PLD_SCL")
	)
	(via
		(at 169.589958 -112.175544)
		(size 0.4572)
		(drill 0.254)
		(layers "F.Cu" "B.Cu")
		(net "SMB_HOST_3V3AUX_PLD_SCL")
	)
	(via
		(at 242.955572 -135.018018)
		(size 0.508)
		(drill 0.254)
		(layers "F.Cu" "B.Cu")
		(net "SMB_HOST_3V3AUX_PLD_SCL")
	)
	(segment
		(start 158.496 -110.5154)
		(end 160.3756 -110.5154)
		(width 0.12954)
		(layer "B.Cu")
		(net "SMB_HOST_3V3AUX_PLD_SCL")
	)
	(segment
		(start 156.131006 -128.282954)
		(end 156.131006 -122.480832)
		(width 0.12954)
		(layer "B.Cu")
		(net "SMB_HOST_3V3AUX_PLD_SCL")
	)
	(segment
		(start 162.052 -112.1918)
		(end 169.573702 -112.1918)
		(width 0.12954)
		(layer "B.Cu")
		(net "SMB_HOST_3V3AUX_PLD_SCL")
	)
	(segment
		(start 154.261312 -136.520174)
		(end 154.261312 -135.89254)
		(width 0.12954)
		(layer "B.Cu")
		(net "SMB_HOST_3V3AUX_PLD_SCL")
	)
	(segment
		(start 154.454606 -118.402354)
		(end 154.1018 -118.049548)
		(width 0.12954)
		(layer "B.Cu")
		(net "SMB_HOST_3V3AUX_PLD_SCL")
	)
	(segment
		(start 169.573702 -112.1918)
		(end 169.589958 -112.175544)
		(width 0.12954)
		(layer "B.Cu")
		(net "SMB_HOST_3V3AUX_PLD_SCL")
	)
	(segment
		(start 157.907228 -109.926628)
		(end 158.496 -110.5154)
		(width 0.12954)
		(layer "B.Cu")
		(net "SMB_HOST_3V3AUX_PLD_SCL")
	)
	(segment
		(start 154.700224 -109.926628)
		(end 157.907228 -109.926628)
		(width 0.12954)
		(layer "B.Cu")
		(net "SMB_HOST_3V3AUX_PLD_SCL")
	)
	(segment
		(start 154.1018 -110.525052)
		(end 154.700224 -109.926628)
		(width 0.12954)
		(layer "B.Cu")
		(net "SMB_HOST_3V3AUX_PLD_SCL")
	)
	(segment
		(start 157.248606 -132.905246)
		(end 157.248606 -129.400554)
		(width 0.12954)
		(layer "B.Cu")
		(net "SMB_HOST_3V3AUX_PLD_SCL")
	)
	(segment
		(start 157.248606 -129.400554)
		(end 156.131006 -128.282954)
		(width 0.12954)
		(layer "B.Cu")
		(net "SMB_HOST_3V3AUX_PLD_SCL")
	)
	(segment
		(start 154.261312 -135.89254)
		(end 157.248606 -132.905246)
		(width 0.12954)
		(layer "B.Cu")
		(net "SMB_HOST_3V3AUX_PLD_SCL")
	)
	(segment
		(start 154.048206 -119.417846)
		(end 154.454606 -119.011446)
		(width 0.12954)
		(layer "B.Cu")
		(net "SMB_HOST_3V3AUX_PLD_SCL")
	)
	(segment
		(start 154.048206 -120.398032)
		(end 154.048206 -119.417846)
		(width 0.12954)
		(layer "B.Cu")
		(net "SMB_HOST_3V3AUX_PLD_SCL")
	)
	(segment
		(start 160.3756 -110.5154)
		(end 162.052 -112.1918)
		(width 0.12954)
		(layer "B.Cu")
		(net "SMB_HOST_3V3AUX_PLD_SCL")
	)
	(segment
		(start 154.1018 -118.049548)
		(end 154.1018 -110.525052)
		(width 0.12954)
		(layer "B.Cu")
		(net "SMB_HOST_3V3AUX_PLD_SCL")
	)
	(segment
		(start 154.454606 -119.011446)
		(end 154.454606 -118.402354)
		(width 0.12954)
		(layer "B.Cu")
		(net "SMB_HOST_3V3AUX_PLD_SCL")
	)
	(segment
		(start 156.131006 -122.480832)
		(end 154.048206 -120.398032)
		(width 0.12954)
		(layer "B.Cu")
		(net "SMB_HOST_3V3AUX_PLD_SCL")
	)
	(segment
		(start 234.225846 -136.40689)
		(end 231.230678 -133.411722)
		(width 0.127)
		(layer "In15.Cu")
		(net "SMB_HOST_3V3AUX_PLD_SCL")
	)
	(segment
		(start 195.144136 -137.824972)
		(end 194.375786 -137.056622)
		(width 0.127)
		(layer "In15.Cu")
		(net "SMB_HOST_3V3AUX_PLD_SCL")
	)
	(segment
		(start 212.355938 -135.424418)
		(end 209.955384 -137.824972)
		(width 0.127)
		(layer "In15.Cu")
		(net "SMB_HOST_3V3AUX_PLD_SCL")
	)
	(segment
		(start 157.955742 -135.343138)
		(end 155.438348 -135.343138)
		(width 0.127)
		(layer "In15.Cu")
		(net "SMB_HOST_3V3AUX_PLD_SCL")
	)
	(segment
		(start 179.420774 -137.056622)
		(end 179.066952 -136.7028)
		(width 0.127)
		(layer "In15.Cu")
		(net "SMB_HOST_3V3AUX_PLD_SCL")
	)
	(segment
		(start 225.897948 -132.015992)
		(end 223.038162 -132.015992)
		(width 0.127)
		(layer "In15.Cu")
		(net "SMB_HOST_3V3AUX_PLD_SCL")
	)
	(segment
		(start 159.315404 -136.7028)
		(end 157.955742 -135.343138)
		(width 0.127)
		(layer "In15.Cu")
		(net "SMB_HOST_3V3AUX_PLD_SCL")
	)
	(segment
		(start 194.375786 -137.056622)
		(end 179.420774 -137.056622)
		(width 0.127)
		(layer "In15.Cu")
		(net "SMB_HOST_3V3AUX_PLD_SCL")
	)
	(segment
		(start 231.230678 -133.411722)
		(end 227.293678 -133.411722)
		(width 0.127)
		(layer "In15.Cu")
		(net "SMB_HOST_3V3AUX_PLD_SCL")
	)
	(segment
		(start 223.038162 -132.015992)
		(end 219.629736 -135.424418)
		(width 0.127)
		(layer "In15.Cu")
		(net "SMB_HOST_3V3AUX_PLD_SCL")
	)
	(segment
		(start 227.293678 -133.411722)
		(end 225.897948 -132.015992)
		(width 0.127)
		(layer "In15.Cu")
		(net "SMB_HOST_3V3AUX_PLD_SCL")
	)
	(segment
		(start 179.066952 -136.7028)
		(end 159.315404 -136.7028)
		(width 0.127)
		(layer "In15.Cu")
		(net "SMB_HOST_3V3AUX_PLD_SCL")
	)
	(segment
		(start 155.438348 -135.343138)
		(end 154.261312 -136.520174)
		(width 0.127)
		(layer "In15.Cu")
		(net "SMB_HOST_3V3AUX_PLD_SCL")
	)
	(segment
		(start 219.629736 -135.424418)
		(end 212.355938 -135.424418)
		(width 0.127)
		(layer "In15.Cu")
		(net "SMB_HOST_3V3AUX_PLD_SCL")
	)
	(segment
		(start 240.949734 -136.40689)
		(end 234.225846 -136.40689)
		(width 0.127)
		(layer "In15.Cu")
		(net "SMB_HOST_3V3AUX_PLD_SCL")
	)
	(segment
		(start 242.955572 -135.018018)
		(end 242.338606 -135.018018)
		(width 0.127)
		(layer "In15.Cu")
		(net "SMB_HOST_3V3AUX_PLD_SCL")
	)
	(segment
		(start 209.955384 -137.824972)
		(end 195.144136 -137.824972)
		(width 0.127)
		(layer "In15.Cu")
		(net "SMB_HOST_3V3AUX_PLD_SCL")
	)
	(segment
		(start 242.338606 -135.018018)
		(end 240.949734 -136.40689)
		(width 0.127)
		(layer "In15.Cu")
		(net "SMB_HOST_3V3AUX_PLD_SCL")
	)
	(segment
		(start 305.5747 -25.5905)
		(end 305.74996 -25.41524)
		(width 0.12954)
		(layer "F.Cu")
		(net "PWRGD_DSW_PWROK_TRIGGER")
	)
	(segment
		(start 304.38725 -25.8064)
		(end 304.38725 -24.7396)
		(width 0.12954)
		(layer "F.Cu")
		(net "PWRGD_DSW_PWROK_TRIGGER")
	)
	(segment
		(start 305.74996 -25.41524)
		(end 307.05679 -25.41524)
		(width 0.12954)
		(layer "F.Cu")
		(net "PWRGD_DSW_PWROK_TRIGGER")
	)
	(segment
		(start 304.38725 -24.7396)
		(end 304.38725 -23.6728)
		(width 0.12954)
		(layer "F.Cu")
		(net "PWRGD_DSW_PWROK_TRIGGER")
	)
	(segment
		(start 304.38725 -23.6728)
		(end 304.38725 -22.606)
		(width 0.12954)
		(layer "F.Cu")
		(net "PWRGD_DSW_PWROK_TRIGGER")
	)
	(segment
		(start 304.38725 -25.8064)
		(end 305.3588 -25.8064)
		(width 0.12954)
		(layer "F.Cu")
		(net "PWRGD_DSW_PWROK_TRIGGER")
	)
	(segment
		(start 305.3588 -25.8064)
		(end 305.5747 -25.5905)
		(width 0.12954)
		(layer "F.Cu")
		(net "PWRGD_DSW_PWROK_TRIGGER")
	)
	(via
		(at 305.5747 -25.5905)
		(size 0.762)
		(drill 0.381)
		(layers "F.Cu" "B.Cu")
		(net "PWRGD_DSW_PWROK_TRIGGER")
	)
	(segment
		(start 309.75681 -25.41524)
		(end 311.59831 -25.41524)
		(width 0.12954)
		(layer "F.Cu")
		(net "PWRGD_DSW_PWROK_R5")
	)
	(segment
		(start 311.4294 -24.9936)
		(end 312.01995 -24.9936)
		(width 0.12954)
		(layer "F.Cu")
		(net "PWRGD_DSW_PWROK_R5")
	)
	(segment
		(start 311.1754 -23.241)
		(end 311.1754 -24.7396)
		(width 0.12954)
		(layer "F.Cu")
		(net "PWRGD_DSW_PWROK_R5")
	)
	(segment
		(start 311.59831 -25.41524)
		(end 312.01995 -24.9936)
		(width 0.12954)
		(layer "F.Cu")
		(net "PWRGD_DSW_PWROK_R5")
	)
	(segment
		(start 302.97755 -26.416)
		(end 303.58715 -25.8064)
		(width 0.12954)
		(layer "F.Cu")
		(net "PWRGD_DSW_PWROK_R5")
	)
	(segment
		(start 311.1754 -24.7396)
		(end 311.4294 -24.9936)
		(width 0.12954)
		(layer "F.Cu")
		(net "PWRGD_DSW_PWROK_R5")
	)
	(segment
		(start 301.0916 -26.416)
		(end 302.97755 -26.416)
		(width 0.12954)
		(layer "F.Cu")
		(net "PWRGD_DSW_PWROK_R5")
	)
	(via
		(at 301.0916 -26.416)
		(size 0.508)
		(drill 0.254)
		(layers "F.Cu" "B.Cu")
		(net "PWRGD_DSW_PWROK_R5")
	)
	(via
		(at 311.1754 -23.241)
		(size 0.508)
		(drill 0.254)
		(layers "F.Cu" "B.Cu")
		(net "PWRGD_DSW_PWROK_R5")
	)
	(segment
		(start 303.6824 -22.3266)
		(end 300.2534 -25.7556)
		(width 0.12954)
		(layer "B.Cu")
		(net "PWRGD_DSW_PWROK_R5")
	)
	(segment
		(start 300.5074 -26.416)
		(end 301.0916 -26.416)
		(width 0.12954)
		(layer "B.Cu")
		(net "PWRGD_DSW_PWROK_R5")
	)
	(segment
		(start 311.1754 -23.241)
		(end 310.261 -22.3266)
		(width 0.12954)
		(layer "B.Cu")
		(net "PWRGD_DSW_PWROK_R5")
	)
	(segment
		(start 300.2534 -26.162)
		(end 300.5074 -26.416)
		(width 0.12954)
		(layer "B.Cu")
		(net "PWRGD_DSW_PWROK_R5")
	)
	(segment
		(start 300.2534 -25.7556)
		(end 300.2534 -26.162)
		(width 0.12954)
		(layer "B.Cu")
		(net "PWRGD_DSW_PWROK_R5")
	)
	(segment
		(start 310.261 -22.3266)
		(end 303.6824 -22.3266)
		(width 0.12954)
		(layer "B.Cu")
		(net "PWRGD_DSW_PWROK_R5")
	)
	(segment
		(start 18.8214 -411.6578)
		(end 18.034 -412.4452)
		(width 0.12954)
		(layer "F.Cu")
		(net "PRSNT_SWB_ISO_R1_N")
	)
	(segment
		(start 18.290032 -413.539686)
		(end 18.034 -413.283654)
		(width 0.12954)
		(layer "F.Cu")
		(net "PRSNT_SWB_ISO_R1_N")
	)
	(segment
		(start 18.290032 -414.277302)
		(end 18.290032 -413.539686)
		(width 0.12954)
		(layer "F.Cu")
		(net "PRSNT_SWB_ISO_R1_N")
	)
	(segment
		(start 18.034 -413.283654)
		(end 18.034 -412.4452)
		(width 0.12954)
		(layer "F.Cu")
		(net "PRSNT_SWB_ISO_R1_N")
	)
	(segment
		(start 18.8214 -411.19425)
		(end 18.8214 -411.6578)
		(width 0.12954)
		(layer "F.Cu")
		(net "PRSNT_SWB_ISO_R1_N")
	)
	(via
		(at 18.034 -412.4452)
		(size 0.762)
		(drill 0.381)
		(layers "F.Cu" "B.Cu")
		(net "PRSNT_SWB_ISO_R1_N")
	)
	(segment
		(start 96.4438 -392.3538)
		(end 96.4438 -390.4488)
		(width 0.12954)
		(layer "F.Cu")
		(net "PRSNT_SWB_ISO_N")
	)
	(segment
		(start 217.4748 -318.262)
		(end 223.9772 -311.7596)
		(width 0.12954)
		(layer "F.Cu")
		(net "PRSNT_SWB_ISO_N")
	)
	(segment
		(start 93.599 -390.3218)
		(end 92.456 -389.1788)
		(width 0.12954)
		(layer "F.Cu")
		(net "PRSNT_SWB_ISO_N")
	)
	(segment
		(start 185.219848 -135.0518)
		(end 185.219848 -134.362952)
		(width 0.12954)
		(layer "F.Cu")
		(net "PRSNT_SWB_ISO_N")
	)
	(segment
		(start 92.456 -384.429)
		(end 94.0816 -382.8034)
		(width 0.12954)
		(layer "F.Cu")
		(net "PRSNT_SWB_ISO_N")
	)
	(segment
		(start 96.012 -392.7856)
		(end 96.4438 -392.3538)
		(width 0.12954)
		(layer "F.Cu")
		(net "PRSNT_SWB_ISO_N")
	)
	(segment
		(start 105.22585 -407.07945)
		(end 105.22585 -407.289)
		(width 0.12954)
		(layer "F.Cu")
		(net "PRSNT_SWB_ISO_N")
	)
	(segment
		(start 105.22585 -408.2796)
		(end 105.22585 -407.289)
		(width 0.12954)
		(layer "F.Cu")
		(net "PRSNT_SWB_ISO_N")
	)
	(segment
		(start 196.1642 -347.7514)
		(end 217.4748 -326.4408)
		(width 0.12954)
		(layer "F.Cu")
		(net "PRSNT_SWB_ISO_N")
	)
	(segment
		(start 223.9772 -239.9792)
		(end 220.345 -236.347)
		(width 0.12954)
		(layer "F.Cu")
		(net "PRSNT_SWB_ISO_N")
	)
	(segment
		(start 92.456 -389.1788)
		(end 92.456 -384.429)
		(width 0.12954)
		(layer "F.Cu")
		(net "PRSNT_SWB_ISO_N")
	)
	(segment
		(start 174.486062 -380.830074)
		(end 176.493424 -379.630432)
		(width 0.12954)
		(layer "F.Cu")
		(net "PRSNT_SWB_ISO_N")
	)
	(segment
		(start 176.493424 -379.630432)
		(end 196.1642 -359.959656)
		(width 0.12954)
		(layer "F.Cu")
		(net "PRSNT_SWB_ISO_N")
	)
	(segment
		(start 223.9772 -311.7596)
		(end 223.9772 -239.9792)
		(width 0.12954)
		(layer "F.Cu")
		(net "PRSNT_SWB_ISO_N")
	)
	(segment
		(start 104.8004 -406.654)
		(end 105.22585 -407.07945)
		(width 0.12954)
		(layer "F.Cu")
		(net "PRSNT_SWB_ISO_N")
	)
	(segment
		(start 106.41584 -408.036014)
		(end 105.469436 -408.036014)
		(width 0.12954)
		(layer "F.Cu")
		(net "PRSNT_SWB_ISO_N")
	)
	(segment
		(start 159.6009 -382.8034)
		(end 168.680638 -382.14554)
		(width 0.12954)
		(layer "F.Cu")
		(net "PRSNT_SWB_ISO_N")
	)
	(segment
		(start 196.1642 -359.959656)
		(end 196.1642 -347.7514)
		(width 0.12954)
		(layer "F.Cu")
		(net "PRSNT_SWB_ISO_N")
	)
	(segment
		(start 18.8214 -410.39415)
		(end 18.8214 -409.7782)
		(width 0.12954)
		(layer "F.Cu")
		(net "PRSNT_SWB_ISO_N")
	)
	(segment
		(start 220.345 -198.3994)
		(end 219.6338 -197.6882)
		(width 0.12954)
		(layer "F.Cu")
		(net "PRSNT_SWB_ISO_N")
	)
	(segment
		(start 96.4438 -390.4488)
		(end 96.3168 -390.3218)
		(width 0.12954)
		(layer "F.Cu")
		(net "PRSNT_SWB_ISO_N")
	)
	(segment
		(start 94.0816 -382.8034)
		(end 159.6009 -382.8034)
		(width 0.12954)
		(layer "F.Cu")
		(net "PRSNT_SWB_ISO_N")
	)
	(segment
		(start 185.493152 -134.089648)
		(end 186.733942 -134.089648)
		(width 0.12954)
		(layer "F.Cu")
		(net "PRSNT_SWB_ISO_N")
	)
	(segment
		(start 217.4748 -326.4408)
		(end 217.4748 -318.262)
		(width 0.12954)
		(layer "F.Cu")
		(net "PRSNT_SWB_ISO_N")
	)
	(segment
		(start 105.469436 -408.036014)
		(end 105.22585 -408.2796)
		(width 0.12954)
		(layer "F.Cu")
		(net "PRSNT_SWB_ISO_N")
	)
	(segment
		(start 168.680638 -382.14554)
		(end 174.486062 -380.830074)
		(width 0.12954)
		(layer "F.Cu")
		(net "PRSNT_SWB_ISO_N")
	)
	(segment
		(start 220.345 -236.347)
		(end 220.345 -198.3994)
		(width 0.12954)
		(layer "F.Cu")
		(net "PRSNT_SWB_ISO_N")
	)
	(segment
		(start 185.219848 -134.362952)
		(end 185.493152 -134.089648)
		(width 0.12954)
		(layer "F.Cu")
		(net "PRSNT_SWB_ISO_N")
	)
	(segment
		(start 96.3168 -390.3218)
		(end 93.599 -390.3218)
		(width 0.12954)
		(layer "F.Cu")
		(net "PRSNT_SWB_ISO_N")
	)
	(via
		(at 96.012 -392.7856)
		(size 0.508)
		(drill 0.254)
		(layers "F.Cu" "B.Cu")
		(net "PRSNT_SWB_ISO_N")
	)
	(via
		(at 219.6338 -197.6882)
		(size 0.508)
		(drill 0.254)
		(layers "F.Cu" "B.Cu")
		(net "PRSNT_SWB_ISO_N")
	)
	(via
		(at 205.2574 -129.5146)
		(size 0.508)
		(drill 0.254)
		(layers "F.Cu" "B.Cu")
		(net "PRSNT_SWB_ISO_N")
	)
	(via
		(at 18.8214 -409.7782)
		(size 0.508)
		(drill 0.254)
		(layers "F.Cu" "B.Cu")
		(net "PRSNT_SWB_ISO_N")
	)
	(via
		(at 185.219848 -135.0518)
		(size 0.508)
		(drill 0.254)
		(layers "F.Cu" "B.Cu")
		(net "PRSNT_SWB_ISO_N")
	)
	(via
		(at 104.8004 -406.654)
		(size 0.508)
		(drill 0.254)
		(layers "F.Cu" "B.Cu")
		(net "PRSNT_SWB_ISO_N")
	)
	(segment
		(start 219.6338 -151.3332)
		(end 219.6338 -184.1246)
		(width 0.127)
		(layer "In2.Cu")
		(net "PRSNT_SWB_ISO_N")
	)
	(segment
		(start 96.012 -392.7856)
		(end 96.012 -394.5636)
		(width 0.127)
		(layer "In2.Cu")
		(net "PRSNT_SWB_ISO_N")
	)
	(segment
		(start 103.1748 -407.1112)
		(end 103.632 -406.654)
		(width 0.127)
		(layer "In2.Cu")
		(net "PRSNT_SWB_ISO_N")
	)
	(segment
		(start 205.4352 -135.433054)
		(end 216.6112 -146.609054)
		(width 0.127)
		(layer "In2.Cu")
		(net "PRSNT_SWB_ISO_N")
	)
	(segment
		(start 103.632 -406.654)
		(end 104.8004 -406.654)
		(width 0.127)
		(layer "In2.Cu")
		(net "PRSNT_SWB_ISO_N")
	)
	(segment
		(start 205.2574 -129.5146)
		(end 205.4352 -129.6924)
		(width 0.127)
		(layer "In2.Cu")
		(net "PRSNT_SWB_ISO_N")
	)
	(segment
		(start 216.6112 -146.609054)
		(end 216.6112 -149.1488)
		(width 0.127)
		(layer "In2.Cu")
		(net "PRSNT_SWB_ISO_N")
	)
	(segment
		(start 219.6338 -184.1246)
		(end 218.059 -185.6994)
		(width 0.127)
		(layer "In2.Cu")
		(net "PRSNT_SWB_ISO_N")
	)
	(segment
		(start 205.4352 -129.6924)
		(end 205.4352 -135.433054)
		(width 0.127)
		(layer "In2.Cu")
		(net "PRSNT_SWB_ISO_N")
	)
	(segment
		(start 219.6338 -191.897)
		(end 219.6338 -197.6882)
		(width 0.127)
		(layer "In2.Cu")
		(net "PRSNT_SWB_ISO_N")
	)
	(segment
		(start 217.5764 -150.114)
		(end 218.4146 -150.114)
		(width 0.127)
		(layer "In2.Cu")
		(net "PRSNT_SWB_ISO_N")
	)
	(segment
		(start 218.059 -185.6994)
		(end 218.059 -188.1378)
		(width 0.127)
		(layer "In2.Cu")
		(net "PRSNT_SWB_ISO_N")
	)
	(segment
		(start 220.1672 -191.3636)
		(end 219.6338 -191.897)
		(width 0.127)
		(layer "In2.Cu")
		(net "PRSNT_SWB_ISO_N")
	)
	(segment
		(start 97.3582 -403.4536)
		(end 101.0158 -407.1112)
		(width 0.127)
		(layer "In2.Cu")
		(net "PRSNT_SWB_ISO_N")
	)
	(segment
		(start 96.012 -394.5636)
		(end 97.3582 -395.9098)
		(width 0.127)
		(layer "In2.Cu")
		(net "PRSNT_SWB_ISO_N")
	)
	(segment
		(start 218.059 -188.1378)
		(end 220.1672 -190.246)
		(width 0.127)
		(layer "In2.Cu")
		(net "PRSNT_SWB_ISO_N")
	)
	(segment
		(start 216.6112 -149.1488)
		(end 217.5764 -150.114)
		(width 0.127)
		(layer "In2.Cu")
		(net "PRSNT_SWB_ISO_N")
	)
	(segment
		(start 220.1672 -190.246)
		(end 220.1672 -191.3636)
		(width 0.127)
		(layer "In2.Cu")
		(net "PRSNT_SWB_ISO_N")
	)
	(segment
		(start 97.3582 -395.9098)
		(end 97.3582 -403.4536)
		(width 0.127)
		(layer "In2.Cu")
		(net "PRSNT_SWB_ISO_N")
	)
	(segment
		(start 101.0158 -407.1112)
		(end 103.1748 -407.1112)
		(width 0.127)
		(layer "In2.Cu")
		(net "PRSNT_SWB_ISO_N")
	)
	(segment
		(start 218.4146 -150.114)
		(end 219.6338 -151.3332)
		(width 0.127)
		(layer "In2.Cu")
		(net "PRSNT_SWB_ISO_N")
	)
	(segment
		(start 185.219848 -134.108952)
		(end 185.6486 -133.6802)
		(width 0.127)
		(layer "In4.Cu")
		(net "PRSNT_SWB_ISO_N")
	)
	(segment
		(start 194.9958 -131.3942)
		(end 195.707 -131.3942)
		(width 0.127)
		(layer "In4.Cu")
		(net "PRSNT_SWB_ISO_N")
	)
	(segment
		(start 191.6684 -132.0292)
		(end 191.9732 -132.334)
		(width 0.127)
		(layer "In4.Cu")
		(net "PRSNT_SWB_ISO_N")
	)
	(segment
		(start 209.3468 -129.1082)
		(end 208.4324 -129.1082)
		(width 0.127)
		(layer "In4.Cu")
		(net "PRSNT_SWB_ISO_N")
	)
	(segment
		(start 209.7024 -133.8326)
		(end 209.7024 -129.4638)
		(width 0.127)
		(layer "In4.Cu")
		(net "PRSNT_SWB_ISO_N")
	)
	(segment
		(start 191.9732 -132.334)
		(end 194.056 -132.334)
		(width 0.127)
		(layer "In4.Cu")
		(net "PRSNT_SWB_ISO_N")
	)
	(segment
		(start 185.6486 -133.6802)
		(end 186.6646 -133.6802)
		(width 0.127)
		(layer "In4.Cu")
		(net "PRSNT_SWB_ISO_N")
	)
	(segment
		(start 209.1182 -134.4168)
		(end 209.7024 -133.8326)
		(width 0.127)
		(layer "In4.Cu")
		(net "PRSNT_SWB_ISO_N")
	)
	(segment
		(start 195.707 -131.3942)
		(end 198.7296 -134.4168)
		(width 0.127)
		(layer "In4.Cu")
		(net "PRSNT_SWB_ISO_N")
	)
	(segment
		(start 194.056 -132.334)
		(end 194.9958 -131.3942)
		(width 0.127)
		(layer "In4.Cu")
		(net "PRSNT_SWB_ISO_N")
	)
	(segment
		(start 187.3758 -132.969)
		(end 187.3758 -132.1562)
		(width 0.127)
		(layer "In4.Cu")
		(net "PRSNT_SWB_ISO_N")
	)
	(segment
		(start 185.219848 -135.0518)
		(end 185.219848 -134.108952)
		(width 0.127)
		(layer "In4.Cu")
		(net "PRSNT_SWB_ISO_N")
	)
	(segment
		(start 198.7296 -134.4168)
		(end 209.1182 -134.4168)
		(width 0.127)
		(layer "In4.Cu")
		(net "PRSNT_SWB_ISO_N")
	)
	(segment
		(start 186.6646 -133.6802)
		(end 187.3758 -132.969)
		(width 0.127)
		(layer "In4.Cu")
		(net "PRSNT_SWB_ISO_N")
	)
	(segment
		(start 187.3758 -132.1562)
		(end 187.5028 -132.0292)
		(width 0.127)
		(layer "In4.Cu")
		(net "PRSNT_SWB_ISO_N")
	)
	(segment
		(start 208.026 -129.5146)
		(end 205.2574 -129.5146)
		(width 0.127)
		(layer "In4.Cu")
		(net "PRSNT_SWB_ISO_N")
	)
	(segment
		(start 209.7024 -129.4638)
		(end 209.3468 -129.1082)
		(width 0.127)
		(layer "In4.Cu")
		(net "PRSNT_SWB_ISO_N")
	)
	(segment
		(start 187.5028 -132.0292)
		(end 191.6684 -132.0292)
		(width 0.127)
		(layer "In4.Cu")
		(net "PRSNT_SWB_ISO_N")
	)
	(segment
		(start 208.4324 -129.1082)
		(end 208.026 -129.5146)
		(width 0.127)
		(layer "In4.Cu")
		(net "PRSNT_SWB_ISO_N")
	)
	(segment
		(start 42.1386 -401.599654)
		(end 42.1386 -402.613114)
		(width 0.127)
		(layer "In11.Cu")
		(net "PRSNT_SWB_ISO_N")
	)
	(segment
		(start 49.911 -394.1064)
		(end 48.9712 -394.1064)
		(width 0.127)
		(layer "In11.Cu")
		(net "PRSNT_SWB_ISO_N")
	)
	(segment
		(start 45.8216 -396.133574)
		(end 44.0436 -397.911574)
		(width 0.127)
		(layer "In11.Cu")
		(net "PRSNT_SWB_ISO_N")
	)
	(segment
		(start 22.0218 -407.416)
		(end 19.6596 -409.7782)
		(width 0.127)
		(layer "In11.Cu")
		(net "PRSNT_SWB_ISO_N")
	)
	(segment
		(start 50.4698 -394.6652)
		(end 49.911 -394.1064)
		(width 0.127)
		(layer "In11.Cu")
		(net "PRSNT_SWB_ISO_N")
	)
	(segment
		(start 95.504 -394.6652)
		(end 50.4698 -394.6652)
		(width 0.127)
		(layer "In11.Cu")
		(net "PRSNT_SWB_ISO_N")
	)
	(segment
		(start 44.0436 -397.911574)
		(end 44.0436 -399.694654)
		(width 0.127)
		(layer "In11.Cu")
		(net "PRSNT_SWB_ISO_N")
	)
	(segment
		(start 96.012 -394.1572)
		(end 95.504 -394.6652)
		(width 0.127)
		(layer "In11.Cu")
		(net "PRSNT_SWB_ISO_N")
	)
	(segment
		(start 42.1386 -402.613114)
		(end 36.700714 -408.051)
		(width 0.127)
		(layer "In11.Cu")
		(net "PRSNT_SWB_ISO_N")
	)
	(segment
		(start 48.9712 -394.1064)
		(end 47.6758 -392.811)
		(width 0.127)
		(layer "In11.Cu")
		(net "PRSNT_SWB_ISO_N")
	)
	(segment
		(start 47.6758 -392.811)
		(end 46.9646 -392.811)
		(width 0.127)
		(layer "In11.Cu")
		(net "PRSNT_SWB_ISO_N")
	)
	(segment
		(start 24.3586 -407.416)
		(end 22.0218 -407.416)
		(width 0.127)
		(layer "In11.Cu")
		(net "PRSNT_SWB_ISO_N")
	)
	(segment
		(start 24.9682 -406.8064)
		(end 24.3586 -407.416)
		(width 0.127)
		(layer "In11.Cu")
		(net "PRSNT_SWB_ISO_N")
	)
	(segment
		(start 29.5656 -408.051)
		(end 28.321 -406.8064)
		(width 0.127)
		(layer "In11.Cu")
		(net "PRSNT_SWB_ISO_N")
	)
	(segment
		(start 19.6596 -409.7782)
		(end 18.8214 -409.7782)
		(width 0.127)
		(layer "In11.Cu")
		(net "PRSNT_SWB_ISO_N")
	)
	(segment
		(start 46.9646 -392.811)
		(end 45.8216 -393.954)
		(width 0.127)
		(layer "In11.Cu")
		(net "PRSNT_SWB_ISO_N")
	)
	(segment
		(start 45.8216 -393.954)
		(end 45.8216 -396.133574)
		(width 0.127)
		(layer "In11.Cu")
		(net "PRSNT_SWB_ISO_N")
	)
	(segment
		(start 36.700714 -408.051)
		(end 29.5656 -408.051)
		(width 0.127)
		(layer "In11.Cu")
		(net "PRSNT_SWB_ISO_N")
	)
	(segment
		(start 28.321 -406.8064)
		(end 24.9682 -406.8064)
		(width 0.127)
		(layer "In11.Cu")
		(net "PRSNT_SWB_ISO_N")
	)
	(segment
		(start 96.012 -392.7856)
		(end 96.012 -394.1572)
		(width 0.127)
		(layer "In11.Cu")
		(net "PRSNT_SWB_ISO_N")
	)
	(segment
		(start 44.0436 -399.694654)
		(end 42.1386 -401.599654)
		(width 0.127)
		(layer "In11.Cu")
		(net "PRSNT_SWB_ISO_N")
	)
	(segment
		(start 106.5784 -409.9306)
		(end 106.33075 -410.17825)
		(width 0.12954)
		(layer "F.Cu")
		(net "PRSNT_SWB")
	)
	(segment
		(start 108.31576 -409.335986)
		(end 108.2802 -409.371546)
		(width 0.12954)
		(layer "F.Cu")
		(net "PRSNT_SWB")
	)
	(segment
		(start 109.433614 -409.335986)
		(end 109.601 -409.1686)
		(width 0.12954)
		(layer "F.Cu")
		(net "PRSNT_SWB")
	)
	(segment
		(start 108.331508 -408.670252)
		(end 108.31576 -408.686)
		(width 0.12954)
		(layer "F.Cu")
		(net "PRSNT_SWB")
	)
	(segment
		(start 108.2802 -409.371546)
		(end 108.2802 -409.7782)
		(width 0.12954)
		(layer "F.Cu")
		(net "PRSNT_SWB")
	)
	(segment
		(start 109.601 -409.1686)
		(end 109.601 -409.0162)
		(width 0.12954)
		(layer "F.Cu")
		(net "PRSNT_SWB")
	)
	(segment
		(start 109.601 -409.0162)
		(end 109.601 -408.8384)
		(width 0.12954)
		(layer "F.Cu")
		(net "PRSNT_SWB")
	)
	(segment
		(start 108.31576 -409.335986)
		(end 109.433614 -409.335986)
		(width 0.12954)
		(layer "F.Cu")
		(net "PRSNT_SWB")
	)
	(segment
		(start 108.1278 -409.9306)
		(end 106.5784 -409.9306)
		(width 0.12954)
		(layer "F.Cu")
		(net "PRSNT_SWB")
	)
	(segment
		(start 109.432852 -408.670252)
		(end 108.331508 -408.670252)
		(width 0.12954)
		(layer "F.Cu")
		(net "PRSNT_SWB")
	)
	(segment
		(start 108.2802 -409.7782)
		(end 108.1278 -409.9306)
		(width 0.12954)
		(layer "F.Cu")
		(net "PRSNT_SWB")
	)
	(segment
		(start 106.33075 -410.17825)
		(end 106.33075 -410.6164)
		(width 0.12954)
		(layer "F.Cu")
		(net "PRSNT_SWB")
	)
	(segment
		(start 109.601 -408.8384)
		(end 109.432852 -408.670252)
		(width 0.12954)
		(layer "F.Cu")
		(net "PRSNT_SWB")
	)
	(via
		(at 109.601 -409.0162)
		(size 0.762)
		(drill 0.381)
		(layers "F.Cu" "B.Cu")
		(net "PRSNT_SWB")
	)
	(segment
		(start 356.205536 -404.433786)
		(end 356.205282 -404.43404)
		(width 0.12954)
		(layer "F.Cu")
		(net "PRSNT_CABLE_SWB_B2_N")
	)
	(segment
		(start 356.205536 -403.933914)
		(end 356.205536 -404.433786)
		(width 0.12954)
		(layer "F.Cu")
		(net "PRSNT_CABLE_SWB_B2_N")
	)
	(segment
		(start 356.205282 -404.852632)
		(end 356.22865 -404.876)
		(width 0.12954)
		(layer "F.Cu")
		(net "PRSNT_CABLE_SWB_B2_N")
	)
	(segment
		(start 356.205282 -404.43404)
		(end 356.205282 -404.852632)
		(width 0.12954)
		(layer "F.Cu")
		(net "PRSNT_CABLE_SWB_B2_N")
	)
	(segment
		(start 352.1964 -416.9156)
		(end 353.6188 -415.4932)
		(width 0.12954)
		(layer "F.Cu")
		(net "PRSNT_CABLE_SWB_B2_N")
	)
	(segment
		(start 354.1014 -405.3586)
		(end 355.72065 -405.3586)
		(width 0.12954)
		(layer "F.Cu")
		(net "PRSNT_CABLE_SWB_B2_N")
	)
	(segment
		(start 355.72065 -405.3586)
		(end 356.20325 -404.876)
		(width 0.12954)
		(layer "F.Cu")
		(net "PRSNT_CABLE_SWB_B2_N")
	)
	(segment
		(start 357.69804 -402.844)
		(end 357.2256 -402.844)
		(width 0.12954)
		(layer "F.Cu")
		(net "PRSNT_CABLE_SWB_B2_N")
	)
	(segment
		(start 356.20325 -404.876)
		(end 356.22865 -404.876)
		(width 0.12954)
		(layer "F.Cu")
		(net "PRSNT_CABLE_SWB_B2_N")
	)
	(segment
		(start 353.6188 -405.8412)
		(end 354.1014 -405.3586)
		(width 0.12954)
		(layer "F.Cu")
		(net "PRSNT_CABLE_SWB_B2_N")
	)
	(segment
		(start 356.997 -403.0726)
		(end 356.997 -403.733)
		(width 0.12954)
		(layer "F.Cu")
		(net "PRSNT_CABLE_SWB_B2_N")
	)
	(segment
		(start 356.22865 -403.9108)
		(end 356.205536 -403.933914)
		(width 0.12954)
		(layer "F.Cu")
		(net "PRSNT_CABLE_SWB_B2_N")
	)
	(segment
		(start 356.8192 -403.9108)
		(end 356.22865 -403.9108)
		(width 0.12954)
		(layer "F.Cu")
		(net "PRSNT_CABLE_SWB_B2_N")
	)
	(segment
		(start 353.6188 -415.4932)
		(end 353.6188 -405.8412)
		(width 0.12954)
		(layer "F.Cu")
		(net "PRSNT_CABLE_SWB_B2_N")
	)
	(segment
		(start 356.997 -403.733)
		(end 356.8192 -403.9108)
		(width 0.12954)
		(layer "F.Cu")
		(net "PRSNT_CABLE_SWB_B2_N")
	)
	(segment
		(start 357.2256 -402.844)
		(end 356.997 -403.0726)
		(width 0.12954)
		(layer "F.Cu")
		(net "PRSNT_CABLE_SWB_B2_N")
	)
	(via
		(at 352.1964 -416.9156)
		(size 0.508)
		(drill 0.254)
		(layers "F.Cu" "B.Cu")
		(net "PRSNT_CABLE_SWB_B2_N")
	)
	(via
		(at 333.650082 -421.758364)
		(size 0.6604)
		(drill 0.3302)
		(layers "F.Cu" "B.Cu")
		(net "PRSNT_CABLE_SWB_B2_N")
	)
	(segment
		(start 334.5434 -419.3794)
		(end 333.650082 -420.272718)
		(width 0.12954)
		(layer "B.Cu")
		(net "PRSNT_CABLE_SWB_B2_N")
	)
	(segment
		(start 352.7298 -418.4142)
		(end 351.7646 -419.3794)
		(width 0.12954)
		(layer "B.Cu")
		(net "PRSNT_CABLE_SWB_B2_N")
	)
	(segment
		(start 352.1964 -416.9156)
		(end 352.7298 -417.449)
		(width 0.12954)
		(layer "B.Cu")
		(net "PRSNT_CABLE_SWB_B2_N")
	)
	(segment
		(start 333.650082 -424.689778)
		(end 333.650082 -421.758364)
		(width 0.12954)
		(layer "B.Cu")
		(net "PRSNT_CABLE_SWB_B2_N")
	)
	(segment
		(start 352.7298 -417.449)
		(end 352.7298 -418.4142)
		(width 0.12954)
		(layer "B.Cu")
		(net "PRSNT_CABLE_SWB_B2_N")
	)
	(segment
		(start 333.650082 -420.272718)
		(end 333.650082 -421.758364)
		(width 0.12954)
		(layer "B.Cu")
		(net "PRSNT_CABLE_SWB_B2_N")
	)
	(segment
		(start 351.7646 -419.3794)
		(end 334.5434 -419.3794)
		(width 0.12954)
		(layer "B.Cu")
		(net "PRSNT_CABLE_SWB_B2_N")
	)
	(segment
		(start 20.23999 -413.3596)
		(end 20.36699 -413.2326)
		(width 0.12954)
		(layer "F.Cu")
		(net "PRSNT_CABLE_SWB_B2_ISO_R_N")
	)
	(segment
		(start 20.36699 -413.2326)
		(end 20.7264 -413.2326)
		(width 0.12954)
		(layer "F.Cu")
		(net "PRSNT_CABLE_SWB_B2_ISO_R_N")
	)
	(segment
		(start 21.5138 -412.4452)
		(end 21.844 -412.4452)
		(width 0.12954)
		(layer "F.Cu")
		(net "PRSNT_CABLE_SWB_B2_ISO_R_N")
	)
	(segment
		(start 21.7932 -411.6832)
		(end 21.7932 -411.19425)
		(width 0.12954)
		(layer "F.Cu")
		(net "PRSNT_CABLE_SWB_B2_ISO_R_N")
	)
	(segment
		(start 21.844 -411.734)
		(end 21.7932 -411.6832)
		(width 0.12954)
		(layer "F.Cu")
		(net "PRSNT_CABLE_SWB_B2_ISO_R_N")
	)
	(segment
		(start 21.844 -412.4452)
		(end 21.844 -411.734)
		(width 0.12954)
		(layer "F.Cu")
		(net "PRSNT_CABLE_SWB_B2_ISO_R_N")
	)
	(segment
		(start 20.7264 -413.2326)
		(end 21.5138 -412.4452)
		(width 0.12954)
		(layer "F.Cu")
		(net "PRSNT_CABLE_SWB_B2_ISO_R_N")
	)
	(segment
		(start 20.23999 -414.277302)
		(end 20.23999 -413.3596)
		(width 0.12954)
		(layer "F.Cu")
		(net "PRSNT_CABLE_SWB_B2_ISO_R_N")
	)
	(via
		(at 21.844 -412.4452)
		(size 0.762)
		(drill 0.381)
		(layers "F.Cu" "B.Cu")
		(net "PRSNT_CABLE_SWB_B2_ISO_R_N")
	)
	(segment
		(start 356.22865 -402.9456)
		(end 356.22865 -401.955)
		(width 0.12954)
		(layer "F.Cu")
		(net "PRSNT_CABLE_SWB_B2_ISO_N")
	)
	(segment
		(start 353.822 -403.6822)
		(end 354.076 -403.4282)
		(width 0.12954)
		(layer "F.Cu")
		(net "PRSNT_CABLE_SWB_B2_ISO_N")
	)
	(segment
		(start 356.22865 -403.33295)
		(end 356.22865 -402.9456)
		(width 0.12954)
		(layer "F.Cu")
		(net "PRSNT_CABLE_SWB_B2_ISO_N")
	)
	(segment
		(start 357.236014 -402.194014)
		(end 356.997 -401.955)
		(width 0.12954)
		(layer "F.Cu")
		(net "PRSNT_CABLE_SWB_B2_ISO_N")
	)
	(segment
		(start 357.69804 -402.194014)
		(end 357.236014 -402.194014)
		(width 0.12954)
		(layer "F.Cu")
		(net "PRSNT_CABLE_SWB_B2_ISO_N")
	)
	(segment
		(start 356.1334 -403.4282)
		(end 356.22865 -403.33295)
		(width 0.12954)
		(layer "F.Cu")
		(net "PRSNT_CABLE_SWB_B2_ISO_N")
	)
	(segment
		(start 354.076 -403.4282)
		(end 356.1334 -403.4282)
		(width 0.12954)
		(layer "F.Cu")
		(net "PRSNT_CABLE_SWB_B2_ISO_N")
	)
	(segment
		(start 353.822 -403.9362)
		(end 353.822 -403.6822)
		(width 0.12954)
		(layer "F.Cu")
		(net "PRSNT_CABLE_SWB_B2_ISO_N")
	)
	(segment
		(start 356.997 -401.955)
		(end 356.22865 -401.955)
		(width 0.12954)
		(layer "F.Cu")
		(net "PRSNT_CABLE_SWB_B2_ISO_N")
	)
	(segment
		(start 21.7932 -410.39415)
		(end 21.7932 -409.7782)
		(width 0.12954)
		(layer "F.Cu")
		(net "PRSNT_CABLE_SWB_B2_ISO_N")
	)
	(via
		(at 169.3418 -403.479)
		(size 0.508)
		(drill 0.254)
		(layers "F.Cu" "B.Cu")
		(net "PRSNT_CABLE_SWB_B2_ISO_N")
	)
	(via
		(at 97.536 -392.811)
		(size 0.508)
		(drill 0.254)
		(layers "F.Cu" "B.Cu")
		(net "PRSNT_CABLE_SWB_B2_ISO_N")
	)
	(via
		(at 353.822 -403.9362)
		(size 0.508)
		(drill 0.254)
		(layers "F.Cu" "B.Cu")
		(net "PRSNT_CABLE_SWB_B2_ISO_N")
	)
	(via
		(at 21.7932 -409.7782)
		(size 0.508)
		(drill 0.254)
		(layers "F.Cu" "B.Cu")
		(net "PRSNT_CABLE_SWB_B2_ISO_N")
	)
	(via
		(at 284.3022 -437.9214)
		(size 0.508)
		(drill 0.254)
		(layers "F.Cu" "B.Cu")
		(net "PRSNT_CABLE_SWB_B2_ISO_N")
	)
	(segment
		(start 170.0022 -402.8186)
		(end 170.0022 -400.115532)
		(width 0.12954)
		(layer "B.Cu")
		(net "PRSNT_CABLE_SWB_B2_ISO_N")
	)
	(segment
		(start 116.680234 -395.1478)
		(end 113.9698 -395.1478)
		(width 0.12954)
		(layer "B.Cu")
		(net "PRSNT_CABLE_SWB_B2_ISO_N")
	)
	(segment
		(start 120.820434 -398.3228)
		(end 119.448834 -396.9512)
		(width 0.12954)
		(layer "B.Cu")
		(net "PRSNT_CABLE_SWB_B2_ISO_N")
	)
	(segment
		(start 119.448834 -396.9512)
		(end 118.483634 -396.9512)
		(width 0.12954)
		(layer "B.Cu")
		(net "PRSNT_CABLE_SWB_B2_ISO_N")
	)
	(segment
		(start 101.2698 -394.335)
		(end 99.06 -394.335)
		(width 0.12954)
		(layer "B.Cu")
		(net "PRSNT_CABLE_SWB_B2_ISO_N")
	)
	(segment
		(start 118.483634 -396.9512)
		(end 116.680234 -395.1478)
		(width 0.12954)
		(layer "B.Cu")
		(net "PRSNT_CABLE_SWB_B2_ISO_N")
	)
	(segment
		(start 107.8992 -395.097)
		(end 106.2228 -393.4206)
		(width 0.12954)
		(layer "B.Cu")
		(net "PRSNT_CABLE_SWB_B2_ISO_N")
	)
	(segment
		(start 111.887 -395.097)
		(end 107.8992 -395.097)
		(width 0.12954)
		(layer "B.Cu")
		(net "PRSNT_CABLE_SWB_B2_ISO_N")
	)
	(segment
		(start 106.2228 -393.4206)
		(end 102.1842 -393.4206)
		(width 0.12954)
		(layer "B.Cu")
		(net "PRSNT_CABLE_SWB_B2_ISO_N")
	)
	(segment
		(start 102.1842 -393.4206)
		(end 101.2698 -394.335)
		(width 0.12954)
		(layer "B.Cu")
		(net "PRSNT_CABLE_SWB_B2_ISO_N")
	)
	(segment
		(start 170.0022 -400.115532)
		(end 168.209468 -398.3228)
		(width 0.12954)
		(layer "B.Cu")
		(net "PRSNT_CABLE_SWB_B2_ISO_N")
	)
	(segment
		(start 99.06 -394.335)
		(end 97.536 -392.811)
		(width 0.12954)
		(layer "B.Cu")
		(net "PRSNT_CABLE_SWB_B2_ISO_N")
	)
	(segment
		(start 113.9698 -395.1478)
		(end 113.4364 -394.6144)
		(width 0.12954)
		(layer "B.Cu")
		(net "PRSNT_CABLE_SWB_B2_ISO_N")
	)
	(segment
		(start 112.3696 -394.6144)
		(end 111.887 -395.097)
		(width 0.12954)
		(layer "B.Cu")
		(net "PRSNT_CABLE_SWB_B2_ISO_N")
	)
	(segment
		(start 168.209468 -398.3228)
		(end 120.820434 -398.3228)
		(width 0.12954)
		(layer "B.Cu")
		(net "PRSNT_CABLE_SWB_B2_ISO_N")
	)
	(segment
		(start 113.4364 -394.6144)
		(end 112.3696 -394.6144)
		(width 0.12954)
		(layer "B.Cu")
		(net "PRSNT_CABLE_SWB_B2_ISO_N")
	)
	(segment
		(start 169.3418 -403.479)
		(end 170.0022 -402.8186)
		(width 0.12954)
		(layer "B.Cu")
		(net "PRSNT_CABLE_SWB_B2_ISO_N")
	)
	(segment
		(start 303.824894 -402.1074)
		(end 352.053906 -402.1074)
		(width 0.127)
		(layer "In6.Cu")
		(net "PRSNT_CABLE_SWB_B2_ISO_N")
	)
	(segment
		(start 302.6664 -414.1978)
		(end 302.6664 -403.265894)
		(width 0.127)
		(layer "In6.Cu")
		(net "PRSNT_CABLE_SWB_B2_ISO_N")
	)
	(segment
		(start 309.7784 -425.1706)
		(end 303.4919 -418.8841)
		(width 0.127)
		(layer "In6.Cu")
		(net "PRSNT_CABLE_SWB_B2_ISO_N")
	)
	(segment
		(start 292.862 -425.0944)
		(end 305.6636 -425.0944)
		(width 0.127)
		(layer "In6.Cu")
		(net "PRSNT_CABLE_SWB_B2_ISO_N")
	)
	(segment
		(start 303.4919 -415.0233)
		(end 302.6664 -414.1978)
		(width 0.127)
		(layer "In6.Cu")
		(net "PRSNT_CABLE_SWB_B2_ISO_N")
	)
	(segment
		(start 286.2326 -426.5676)
		(end 291.3888 -426.5676)
		(width 0.127)
		(layer "In6.Cu")
		(net "PRSNT_CABLE_SWB_B2_ISO_N")
	)
	(segment
		(start 284.947614 -437.275986)
		(end 284.947614 -427.852586)
		(width 0.127)
		(layer "In6.Cu")
		(net "PRSNT_CABLE_SWB_B2_ISO_N")
	)
	(segment
		(start 302.6664 -403.265894)
		(end 303.824894 -402.1074)
		(width 0.127)
		(layer "In6.Cu")
		(net "PRSNT_CABLE_SWB_B2_ISO_N")
	)
	(segment
		(start 291.3888 -426.5676)
		(end 292.862 -425.0944)
		(width 0.127)
		(layer "In6.Cu")
		(net "PRSNT_CABLE_SWB_B2_ISO_N")
	)
	(segment
		(start 352.053906 -402.1074)
		(end 353.822 -403.875494)
		(width 0.127)
		(layer "In6.Cu")
		(net "PRSNT_CABLE_SWB_B2_ISO_N")
	)
	(segment
		(start 353.822 -403.875494)
		(end 353.822 -403.9362)
		(width 0.127)
		(layer "In6.Cu")
		(net "PRSNT_CABLE_SWB_B2_ISO_N")
	)
	(segment
		(start 284.3022 -437.9214)
		(end 284.947614 -437.275986)
		(width 0.127)
		(layer "In6.Cu")
		(net "PRSNT_CABLE_SWB_B2_ISO_N")
	)
	(segment
		(start 284.947614 -427.852586)
		(end 286.2326 -426.5676)
		(width 0.127)
		(layer "In6.Cu")
		(net "PRSNT_CABLE_SWB_B2_ISO_N")
	)
	(segment
		(start 309.7784 -428.0408)
		(end 309.7784 -425.1706)
		(width 0.127)
		(layer "In6.Cu")
		(net "PRSNT_CABLE_SWB_B2_ISO_N")
	)
	(segment
		(start 305.6636 -425.0944)
		(end 308.9402 -428.371)
		(width 0.127)
		(layer "In6.Cu")
		(net "PRSNT_CABLE_SWB_B2_ISO_N")
	)
	(segment
		(start 308.9402 -428.371)
		(end 309.4482 -428.371)
		(width 0.127)
		(layer "In6.Cu")
		(net "PRSNT_CABLE_SWB_B2_ISO_N")
	)
	(segment
		(start 303.4919 -418.8841)
		(end 303.4919 -415.0233)
		(width 0.127)
		(layer "In6.Cu")
		(net "PRSNT_CABLE_SWB_B2_ISO_N")
	)
	(segment
		(start 309.4482 -428.371)
		(end 309.7784 -428.0408)
		(width 0.127)
		(layer "In6.Cu")
		(net "PRSNT_CABLE_SWB_B2_ISO_N")
	)
	(segment
		(start 37.3634 -408.9146)
		(end 22.3774 -408.9146)
		(width 0.127)
		(layer "In11.Cu")
		(net "PRSNT_CABLE_SWB_B2_ISO_N")
	)
	(segment
		(start 44.8056 -398.1196)
		(end 44.8056 -401.4724)
		(width 0.127)
		(layer "In11.Cu")
		(net "PRSNT_CABLE_SWB_B2_ISO_N")
	)
	(segment
		(start 97.536 -392.811)
		(end 97.536 -393.962636)
		(width 0.127)
		(layer "In11.Cu")
		(net "PRSNT_CABLE_SWB_B2_ISO_N")
	)
	(segment
		(start 22.3774 -408.9146)
		(end 21.7932 -409.4988)
		(width 0.127)
		(layer "In11.Cu")
		(net "PRSNT_CABLE_SWB_B2_ISO_N")
	)
	(segment
		(start 49.9618 -395.6558)
		(end 49.3522 -395.0462)
		(width 0.127)
		(layer "In11.Cu")
		(net "PRSNT_CABLE_SWB_B2_ISO_N")
	)
	(segment
		(start 95.842836 -395.6558)
		(end 49.9618 -395.6558)
		(width 0.127)
		(layer "In11.Cu")
		(net "PRSNT_CABLE_SWB_B2_ISO_N")
	)
	(segment
		(start 44.8056 -401.4724)
		(end 37.3634 -408.9146)
		(width 0.127)
		(layer "In11.Cu")
		(net "PRSNT_CABLE_SWB_B2_ISO_N")
	)
	(segment
		(start 49.3522 -395.0462)
		(end 47.020226 -395.0462)
		(width 0.127)
		(layer "In11.Cu")
		(net "PRSNT_CABLE_SWB_B2_ISO_N")
	)
	(segment
		(start 46.5074 -395.559026)
		(end 46.5074 -396.4178)
		(width 0.127)
		(layer "In11.Cu")
		(net "PRSNT_CABLE_SWB_B2_ISO_N")
	)
	(segment
		(start 21.7932 -409.4988)
		(end 21.7932 -409.7782)
		(width 0.127)
		(layer "In11.Cu")
		(net "PRSNT_CABLE_SWB_B2_ISO_N")
	)
	(segment
		(start 47.020226 -395.0462)
		(end 46.5074 -395.559026)
		(width 0.127)
		(layer "In11.Cu")
		(net "PRSNT_CABLE_SWB_B2_ISO_N")
	)
	(segment
		(start 97.536 -393.962636)
		(end 95.842836 -395.6558)
		(width 0.127)
		(layer "In11.Cu")
		(net "PRSNT_CABLE_SWB_B2_ISO_N")
	)
	(segment
		(start 46.5074 -396.4178)
		(end 44.8056 -398.1196)
		(width 0.127)
		(layer "In11.Cu")
		(net "PRSNT_CABLE_SWB_B2_ISO_N")
	)
	(segment
		(start 180.36032 -419.7096)
		(end 176.897284 -419.7096)
		(width 0.127)
		(layer "In13.Cu")
		(net "PRSNT_CABLE_SWB_B2_ISO_N")
	)
	(segment
		(start 277.661116 -438.4294)
		(end 198.336916 -438.4294)
		(width 0.127)
		(layer "In13.Cu")
		(net "PRSNT_CABLE_SWB_B2_ISO_N")
	)
	(segment
		(start 187.2742 -426.62348)
		(end 180.36032 -419.7096)
		(width 0.127)
		(layer "In13.Cu")
		(net "PRSNT_CABLE_SWB_B2_ISO_N")
	)
	(segment
		(start 278.829516 -439.5978)
		(end 277.661116 -438.4294)
		(width 0.127)
		(layer "In13.Cu")
		(net "PRSNT_CABLE_SWB_B2_ISO_N")
	)
	(segment
		(start 175.474884 -421.132)
		(end 174.384716 -421.132)
		(width 0.127)
		(layer "In13.Cu")
		(net "PRSNT_CABLE_SWB_B2_ISO_N")
	)
	(segment
		(start 170.18 -413.752284)
		(end 170.18 -411.290516)
		(width 0.127)
		(layer "In13.Cu")
		(net "PRSNT_CABLE_SWB_B2_ISO_N")
	)
	(segment
		(start 198.336916 -438.4294)
		(end 187.2742 -427.366684)
		(width 0.127)
		(layer "In13.Cu")
		(net "PRSNT_CABLE_SWB_B2_ISO_N")
	)
	(segment
		(start 170.18 -411.290516)
		(end 170.8658 -410.604716)
		(width 0.127)
		(layer "In13.Cu")
		(net "PRSNT_CABLE_SWB_B2_ISO_N")
	)
	(segment
		(start 173.3042 -420.051484)
		(end 173.3042 -416.876484)
		(width 0.127)
		(layer "In13.Cu")
		(net "PRSNT_CABLE_SWB_B2_ISO_N")
	)
	(segment
		(start 187.2742 -427.366684)
		(end 187.2742 -426.62348)
		(width 0.127)
		(layer "In13.Cu")
		(net "PRSNT_CABLE_SWB_B2_ISO_N")
	)
	(segment
		(start 170.8658 -405.003)
		(end 169.3418 -403.479)
		(width 0.127)
		(layer "In13.Cu")
		(net "PRSNT_CABLE_SWB_B2_ISO_N")
	)
	(segment
		(start 174.384716 -421.132)
		(end 173.3042 -420.051484)
		(width 0.127)
		(layer "In13.Cu")
		(net "PRSNT_CABLE_SWB_B2_ISO_N")
	)
	(segment
		(start 284.3022 -437.9214)
		(end 283.464 -437.9214)
		(width 0.127)
		(layer "In13.Cu")
		(net "PRSNT_CABLE_SWB_B2_ISO_N")
	)
	(segment
		(start 281.7876 -439.5978)
		(end 278.829516 -439.5978)
		(width 0.127)
		(layer "In13.Cu")
		(net "PRSNT_CABLE_SWB_B2_ISO_N")
	)
	(segment
		(start 173.3042 -416.876484)
		(end 170.18 -413.752284)
		(width 0.127)
		(layer "In13.Cu")
		(net "PRSNT_CABLE_SWB_B2_ISO_N")
	)
	(segment
		(start 170.8658 -410.604716)
		(end 170.8658 -405.003)
		(width 0.127)
		(layer "In13.Cu")
		(net "PRSNT_CABLE_SWB_B2_ISO_N")
	)
	(segment
		(start 176.897284 -419.7096)
		(end 175.474884 -421.132)
		(width 0.127)
		(layer "In13.Cu")
		(net "PRSNT_CABLE_SWB_B2_ISO_N")
	)
	(segment
		(start 283.464 -437.9214)
		(end 281.7876 -439.5978)
		(width 0.127)
		(layer "In13.Cu")
		(net "PRSNT_CABLE_SWB_B2_ISO_N")
	)
	(segment
		(start 359.59796 -403.493986)
		(end 359.59796 -403.97684)
		(width 0.12954)
		(layer "F.Cu")
		(net "PRSNT_CABLE_SWB_B2")
	)
	(segment
		(start 358.993186 -403.364446)
		(end 359.122726 -403.493986)
		(width 0.12954)
		(layer "F.Cu")
		(net "PRSNT_CABLE_SWB_B2")
	)
	(segment
		(start 359.4608 -404.114)
		(end 358.2162 -404.114)
		(width 0.12954)
		(layer "F.Cu")
		(net "PRSNT_CABLE_SWB_B2")
	)
	(segment
		(start 359.59796 -403.97684)
		(end 359.4608 -404.114)
		(width 0.12954)
		(layer "F.Cu")
		(net "PRSNT_CABLE_SWB_B2")
	)
	(segment
		(start 357.9368 -404.7744)
		(end 358.008682 -404.846282)
		(width 0.12954)
		(layer "F.Cu")
		(net "PRSNT_CABLE_SWB_B2")
	)
	(segment
		(start 358.008682 -404.846282)
		(end 358.601772 -404.846282)
		(width 0.12954)
		(layer "F.Cu")
		(net "PRSNT_CABLE_SWB_B2")
	)
	(segment
		(start 359.097326 -402.844)
		(end 358.993186 -402.94814)
		(width 0.12954)
		(layer "F.Cu")
		(net "PRSNT_CABLE_SWB_B2")
	)
	(segment
		(start 358.601772 -404.846282)
		(end 358.648254 -404.7998)
		(width 0.12954)
		(layer "F.Cu")
		(net "PRSNT_CABLE_SWB_B2")
	)
	(segment
		(start 358.993186 -402.94814)
		(end 358.993186 -403.364446)
		(width 0.12954)
		(layer "F.Cu")
		(net "PRSNT_CABLE_SWB_B2")
	)
	(segment
		(start 359.59796 -402.844)
		(end 359.097326 -402.844)
		(width 0.12954)
		(layer "F.Cu")
		(net "PRSNT_CABLE_SWB_B2")
	)
	(segment
		(start 358.648254 -404.7998)
		(end 359.36555 -404.7998)
		(width 0.12954)
		(layer "F.Cu")
		(net "PRSNT_CABLE_SWB_B2")
	)
	(segment
		(start 359.122726 -403.493986)
		(end 359.59796 -403.493986)
		(width 0.12954)
		(layer "F.Cu")
		(net "PRSNT_CABLE_SWB_B2")
	)
	(segment
		(start 357.9368 -404.3934)
		(end 357.9368 -404.7744)
		(width 0.12954)
		(layer "F.Cu")
		(net "PRSNT_CABLE_SWB_B2")
	)
	(segment
		(start 358.2162 -404.114)
		(end 357.9368 -404.3934)
		(width 0.12954)
		(layer "F.Cu")
		(net "PRSNT_CABLE_SWB_B2")
	)
	(via
		(at 358.008682 -404.846282)
		(size 0.762)
		(drill 0.381)
		(layers "F.Cu" "B.Cu")
		(net "PRSNT_CABLE_SWB_B2")
	)
	(segment
		(start 367.3094 -408.1272)
		(end 366.76965 -408.1272)
		(width 0.12954)
		(layer "F.Cu")
		(net "PRSNT_CABLE_SWB_B1_N")
	)
	(segment
		(start 367.7666 -407.67)
		(end 367.3094 -408.1272)
		(width 0.12954)
		(layer "F.Cu")
		(net "PRSNT_CABLE_SWB_B1_N")
	)
	(segment
		(start 372.1608 -412.0896)
		(end 368.4016 -412.0896)
		(width 0.12954)
		(layer "F.Cu")
		(net "PRSNT_CABLE_SWB_B1_N")
	)
	(segment
		(start 368.31524 -407.67)
		(end 367.7666 -407.67)
		(width 0.12954)
		(layer "F.Cu")
		(net "PRSNT_CABLE_SWB_B1_N")
	)
	(segment
		(start 372.3894 -411.861)
		(end 372.1608 -412.0896)
		(width 0.12954)
		(layer "F.Cu")
		(net "PRSNT_CABLE_SWB_B1_N")
	)
	(segment
		(start 368.4016 -412.0896)
		(end 366.76965 -410.45765)
		(width 0.12954)
		(layer "F.Cu")
		(net "PRSNT_CABLE_SWB_B1_N")
	)
	(segment
		(start 366.76965 -410.45765)
		(end 366.76965 -409.194)
		(width 0.12954)
		(layer "F.Cu")
		(net "PRSNT_CABLE_SWB_B1_N")
	)
	(segment
		(start 366.76965 -409.194)
		(end 366.76965 -408.1272)
		(width 0.12954)
		(layer "F.Cu")
		(net "PRSNT_CABLE_SWB_B1_N")
	)
	(segment
		(start 376.1232 -412.6992)
		(end 375.285 -411.861)
		(width 0.12954)
		(layer "F.Cu")
		(net "PRSNT_CABLE_SWB_B1_N")
	)
	(segment
		(start 376.1232 -422.5544)
		(end 376.1232 -412.6992)
		(width 0.12954)
		(layer "F.Cu")
		(net "PRSNT_CABLE_SWB_B1_N")
	)
	(segment
		(start 375.285 -411.861)
		(end 372.3894 -411.861)
		(width 0.12954)
		(layer "F.Cu")
		(net "PRSNT_CABLE_SWB_B1_N")
	)
	(via
		(at 379.3998 -423.1386)
		(size 0.6604)
		(drill 0.3302)
		(layers "F.Cu" "B.Cu")
		(net "PRSNT_CABLE_SWB_B1_N")
	)
	(via
		(at 376.1232 -422.5544)
		(size 0.508)
		(drill 0.254)
		(layers "F.Cu" "B.Cu")
		(net "PRSNT_CABLE_SWB_B1_N")
	)
	(segment
		(start 381.750062 -440.489848)
		(end 380.972314 -440.489848)
		(width 0.12954)
		(layer "B.Cu")
		(net "PRSNT_CABLE_SWB_B1_N")
	)
	(segment
		(start 380.455932 -439.973466)
		(end 380.455932 -424.194732)
		(width 0.12954)
		(layer "B.Cu")
		(net "PRSNT_CABLE_SWB_B1_N")
	)
	(segment
		(start 380.455932 -424.194732)
		(end 379.3998 -423.1386)
		(width 0.12954)
		(layer "B.Cu")
		(net "PRSNT_CABLE_SWB_B1_N")
	)
	(segment
		(start 379.3998 -423.1386)
		(end 378.8156 -422.5544)
		(width 0.12954)
		(layer "B.Cu")
		(net "PRSNT_CABLE_SWB_B1_N")
	)
	(segment
		(start 380.972314 -440.489848)
		(end 380.455932 -439.973466)
		(width 0.12954)
		(layer "B.Cu")
		(net "PRSNT_CABLE_SWB_B1_N")
	)
	(segment
		(start 378.8156 -422.5544)
		(end 376.1232 -422.5544)
		(width 0.12954)
		(layer "B.Cu")
		(net "PRSNT_CABLE_SWB_B1_N")
	)
	(segment
		(start 23.6474 -420.2684)
		(end 23.9522 -420.5732)
		(width 0.12954)
		(layer "F.Cu")
		(net "PRSNT_CABLE_SWB_B1_ISO_R_N")
	)
	(segment
		(start 21.971 -421.198548)
		(end 22.2504 -420.919148)
		(width 0.12954)
		(layer "F.Cu")
		(net "PRSNT_CABLE_SWB_B1_ISO_R_N")
	)
	(segment
		(start 23.9522 -420.5732)
		(end 24.49195 -420.5732)
		(width 0.12954)
		(layer "F.Cu")
		(net "PRSNT_CABLE_SWB_B1_ISO_R_N")
	)
	(segment
		(start 20.23999 -420.686738)
		(end 20.7518 -421.198548)
		(width 0.12954)
		(layer "F.Cu")
		(net "PRSNT_CABLE_SWB_B1_ISO_R_N")
	)
	(segment
		(start 22.2504 -420.512748)
		(end 22.494748 -420.2684)
		(width 0.12954)
		(layer "F.Cu")
		(net "PRSNT_CABLE_SWB_B1_ISO_R_N")
	)
	(segment
		(start 22.2504 -420.919148)
		(end 22.2504 -420.512748)
		(width 0.12954)
		(layer "F.Cu")
		(net "PRSNT_CABLE_SWB_B1_ISO_R_N")
	)
	(segment
		(start 20.23999 -420.12743)
		(end 20.23999 -420.686738)
		(width 0.12954)
		(layer "F.Cu")
		(net "PRSNT_CABLE_SWB_B1_ISO_R_N")
	)
	(segment
		(start 22.494748 -420.2684)
		(end 23.6474 -420.2684)
		(width 0.12954)
		(layer "F.Cu")
		(net "PRSNT_CABLE_SWB_B1_ISO_R_N")
	)
	(segment
		(start 20.7518 -421.198548)
		(end 21.971 -421.198548)
		(width 0.12954)
		(layer "F.Cu")
		(net "PRSNT_CABLE_SWB_B1_ISO_R_N")
	)
	(via
		(at 22.2504 -420.512748)
		(size 0.762)
		(drill 0.381)
		(layers "F.Cu" "B.Cu")
		(net "PRSNT_CABLE_SWB_B1_ISO_R_N")
	)
	(segment
		(start 88.621108 -418.211)
		(end 77.452982 -418.211)
		(width 0.12954)
		(layer "F.Cu")
		(net "PRSNT_CABLE_SWB_B1_ISO_N")
	)
	(segment
		(start 38.227 -427.7106)
		(end 36.957 -426.4406)
		(width 0.12954)
		(layer "F.Cu")
		(net "PRSNT_CABLE_SWB_B1_ISO_N")
	)
	(segment
		(start 36.957 -424.053)
		(end 33.4772 -420.5732)
		(width 0.12954)
		(layer "F.Cu")
		(net "PRSNT_CABLE_SWB_B1_ISO_N")
	)
	(segment
		(start 54.9656 -415.3408)
		(end 53.580284 -415.3408)
		(width 0.12954)
		(layer "F.Cu")
		(net "PRSNT_CABLE_SWB_B1_ISO_N")
	)
	(segment
		(start 33.4772 -420.5732)
		(end 26.543 -420.5732)
		(width 0.12954)
		(layer "F.Cu")
		(net "PRSNT_CABLE_SWB_B1_ISO_N")
	)
	(segment
		(start 91.3384 -420.928292)
		(end 88.621108 -418.211)
		(width 0.12954)
		(layer "F.Cu")
		(net "PRSNT_CABLE_SWB_B1_ISO_N")
	)
	(segment
		(start 366.76965 -405.9936)
		(end 366.76965 -407.0604)
		(width 0.12954)
		(layer "F.Cu")
		(net "PRSNT_CABLE_SWB_B1_ISO_N")
	)
	(segment
		(start 91.3384 -425.170092)
		(end 91.3384 -420.928292)
		(width 0.12954)
		(layer "F.Cu")
		(net "PRSNT_CABLE_SWB_B1_ISO_N")
	)
	(segment
		(start 26.543 -420.5732)
		(end 25.29205 -420.5732)
		(width 0.12954)
		(layer "F.Cu")
		(net "PRSNT_CABLE_SWB_B1_ISO_N")
	)
	(segment
		(start 51.7144 -426.934884)
		(end 47.789084 -430.8602)
		(width 0.12954)
		(layer "F.Cu")
		(net "PRSNT_CABLE_SWB_B1_ISO_N")
	)
	(segment
		(start 51.7144 -417.206684)
		(end 51.7144 -426.934884)
		(width 0.12954)
		(layer "F.Cu")
		(net "PRSNT_CABLE_SWB_B1_ISO_N")
	)
	(segment
		(start 41.642284 -430.8602)
		(end 40.677084 -431.8254)
		(width 0.12954)
		(layer "F.Cu")
		(net "PRSNT_CABLE_SWB_B1_ISO_N")
	)
	(segment
		(start 93.624908 -427.4566)
		(end 91.3384 -425.170092)
		(width 0.12954)
		(layer "F.Cu")
		(net "PRSNT_CABLE_SWB_B1_ISO_N")
	)
	(segment
		(start 93.8022 -427.4566)
		(end 93.624908 -427.4566)
		(width 0.12954)
		(layer "F.Cu")
		(net "PRSNT_CABLE_SWB_B1_ISO_N")
	)
	(segment
		(start 47.789084 -430.8602)
		(end 41.642284 -430.8602)
		(width 0.12954)
		(layer "F.Cu")
		(net "PRSNT_CABLE_SWB_B1_ISO_N")
	)
	(segment
		(start 56.642 -413.6644)
		(end 54.9656 -415.3408)
		(width 0.12954)
		(layer "F.Cu")
		(net "PRSNT_CABLE_SWB_B1_ISO_N")
	)
	(segment
		(start 368.31524 -407.020014)
		(end 366.810036 -407.020014)
		(width 0.12954)
		(layer "F.Cu")
		(net "PRSNT_CABLE_SWB_B1_ISO_N")
	)
	(segment
		(start 72.906382 -413.6644)
		(end 56.642 -413.6644)
		(width 0.12954)
		(layer "F.Cu")
		(net "PRSNT_CABLE_SWB_B1_ISO_N")
	)
	(segment
		(start 39.243 -431.8254)
		(end 38.227 -430.8094)
		(width 0.12954)
		(layer "F.Cu")
		(net "PRSNT_CABLE_SWB_B1_ISO_N")
	)
	(segment
		(start 77.452982 -418.211)
		(end 72.906382 -413.6644)
		(width 0.12954)
		(layer "F.Cu")
		(net "PRSNT_CABLE_SWB_B1_ISO_N")
	)
	(segment
		(start 36.957 -426.4406)
		(end 36.957 -424.053)
		(width 0.12954)
		(layer "F.Cu")
		(net "PRSNT_CABLE_SWB_B1_ISO_N")
	)
	(segment
		(start 40.677084 -431.8254)
		(end 39.243 -431.8254)
		(width 0.12954)
		(layer "F.Cu")
		(net "PRSNT_CABLE_SWB_B1_ISO_N")
	)
	(segment
		(start 366.76965 -405.9936)
		(end 367.4618 -405.9936)
		(width 0.12954)
		(layer "F.Cu")
		(net "PRSNT_CABLE_SWB_B1_ISO_N")
	)
	(segment
		(start 366.810036 -407.020014)
		(end 366.76965 -407.0604)
		(width 0.12954)
		(layer "F.Cu")
		(net "PRSNT_CABLE_SWB_B1_ISO_N")
	)
	(segment
		(start 38.227 -430.8094)
		(end 38.227 -427.7106)
		(width 0.12954)
		(layer "F.Cu")
		(net "PRSNT_CABLE_SWB_B1_ISO_N")
	)
	(segment
		(start 53.580284 -415.3408)
		(end 51.7144 -417.206684)
		(width 0.12954)
		(layer "F.Cu")
		(net "PRSNT_CABLE_SWB_B1_ISO_N")
	)
	(via
		(at 304.6476 -413.4612)
		(size 0.508)
		(drill 0.254)
		(layers "F.Cu" "B.Cu")
		(net "PRSNT_CABLE_SWB_B1_ISO_N")
	)
	(via
		(at 26.543 -420.5732)
		(size 0.762)
		(drill 0.381)
		(layers "F.Cu" "B.Cu")
		(net "PRSNT_CABLE_SWB_B1_ISO_N")
	)
	(via
		(at 93.8022 -427.4566)
		(size 0.508)
		(drill 0.254)
		(layers "F.Cu" "B.Cu")
		(net "PRSNT_CABLE_SWB_B1_ISO_N")
	)
	(via
		(at 172.4406 -404.5204)
		(size 0.508)
		(drill 0.254)
		(layers "F.Cu" "B.Cu")
		(net "PRSNT_CABLE_SWB_B1_ISO_N")
	)
	(via
		(at 367.4618 -405.9936)
		(size 0.508)
		(drill 0.254)
		(layers "F.Cu" "B.Cu")
		(net "PRSNT_CABLE_SWB_B1_ISO_N")
	)
	(segment
		(start 363.8042 -409.1178)
		(end 364.5408 -409.8544)
		(width 0.12954)
		(layer "B.Cu")
		(net "PRSNT_CABLE_SWB_B1_ISO_N")
	)
	(segment
		(start 356.6414 -409.1178)
		(end 363.8042 -409.1178)
		(width 0.12954)
		(layer "B.Cu")
		(net "PRSNT_CABLE_SWB_B1_ISO_N")
	)
	(segment
		(start 304.6476 -413.4612)
		(end 306.6796 -411.4292)
		(width 0.12954)
		(layer "B.Cu")
		(net "PRSNT_CABLE_SWB_B1_ISO_N")
	)
	(segment
		(start 354.33 -411.4292)
		(end 356.6414 -409.1178)
		(width 0.12954)
		(layer "B.Cu")
		(net "PRSNT_CABLE_SWB_B1_ISO_N")
	)
	(segment
		(start 364.5408 -409.8544)
		(end 366.0648 -409.8544)
		(width 0.12954)
		(layer "B.Cu")
		(net "PRSNT_CABLE_SWB_B1_ISO_N")
	)
	(segment
		(start 367.4618 -408.4574)
		(end 367.4618 -405.9936)
		(width 0.12954)
		(layer "B.Cu")
		(net "PRSNT_CABLE_SWB_B1_ISO_N")
	)
	(segment
		(start 306.6796 -411.4292)
		(end 354.33 -411.4292)
		(width 0.12954)
		(layer "B.Cu")
		(net "PRSNT_CABLE_SWB_B1_ISO_N")
	)
	(segment
		(start 366.0648 -409.8544)
		(end 367.4618 -408.4574)
		(width 0.12954)
		(layer "B.Cu")
		(net "PRSNT_CABLE_SWB_B1_ISO_N")
	)
	(segment
		(start 173.049946 -403.326854)
		(end 172.0088 -403.326854)
		(width 0.127)
		(layer "In4.Cu")
		(net "PRSNT_CABLE_SWB_B1_ISO_N")
	)
	(segment
		(start 183.667908 -381.694182)
		(end 177.080418 -388.281672)
		(width 0.127)
		(layer "In4.Cu")
		(net "PRSNT_CABLE_SWB_B1_ISO_N")
	)
	(segment
		(start 173.7614 -398.738598)
		(end 173.7614 -402.6154)
		(width 0.127)
		(layer "In4.Cu")
		(net "PRSNT_CABLE_SWB_B1_ISO_N")
	)
	(segment
		(start 177.080418 -395.41958)
		(end 173.7614 -398.738598)
		(width 0.127)
		(layer "In4.Cu")
		(net "PRSNT_CABLE_SWB_B1_ISO_N")
	)
	(segment
		(start 282.448 -415.1122)
		(end 282.2194 -414.8836)
		(width 0.127)
		(layer "In4.Cu")
		(net "PRSNT_CABLE_SWB_B1_ISO_N")
	)
	(segment
		(start 292.4302 -409.9052)
		(end 294.445436 -407.889964)
		(width 0.127)
		(layer "In4.Cu")
		(net "PRSNT_CABLE_SWB_B1_ISO_N")
	)
	(segment
		(start 267.733018 -385.131818)
		(end 264.126472 -385.131818)
		(width 0.127)
		(layer "In4.Cu")
		(net "PRSNT_CABLE_SWB_B1_ISO_N")
	)
	(segment
		(start 177.080418 -388.281672)
		(end 177.080418 -395.41958)
		(width 0.127)
		(layer "In4.Cu")
		(net "PRSNT_CABLE_SWB_B1_ISO_N")
	)
	(segment
		(start 285.980632 -398.35582)
		(end 282.1432 -394.518388)
		(width 0.127)
		(layer "In4.Cu")
		(net "PRSNT_CABLE_SWB_B1_ISO_N")
	)
	(segment
		(start 282.1432 -392.218926)
		(end 277.426674 -387.5024)
		(width 0.127)
		(layer "In4.Cu")
		(net "PRSNT_CABLE_SWB_B1_ISO_N")
	)
	(segment
		(start 282.2194 -411.5816)
		(end 282.8798 -410.9212)
		(width 0.127)
		(layer "In4.Cu")
		(net "PRSNT_CABLE_SWB_B1_ISO_N")
	)
	(segment
		(start 293.83482 -398.35582)
		(end 285.980632 -398.35582)
		(width 0.127)
		(layer "In4.Cu")
		(net "PRSNT_CABLE_SWB_B1_ISO_N")
	)
	(segment
		(start 172.0088 -403.326854)
		(end 171.8818 -403.453854)
		(width 0.127)
		(layer "In4.Cu")
		(net "PRSNT_CABLE_SWB_B1_ISO_N")
	)
	(segment
		(start 270.1036 -387.5024)
		(end 267.733018 -385.131818)
		(width 0.127)
		(layer "In4.Cu")
		(net "PRSNT_CABLE_SWB_B1_ISO_N")
	)
	(segment
		(start 292.2524 -416.052)
		(end 291.3126 -415.1122)
		(width 0.127)
		(layer "In4.Cu")
		(net "PRSNT_CABLE_SWB_B1_ISO_N")
	)
	(segment
		(start 294.445436 -407.889964)
		(end 294.445436 -398.966436)
		(width 0.127)
		(layer "In4.Cu")
		(net "PRSNT_CABLE_SWB_B1_ISO_N")
	)
	(segment
		(start 173.7614 -402.6154)
		(end 173.049946 -403.326854)
		(width 0.127)
		(layer "In4.Cu")
		(net "PRSNT_CABLE_SWB_B1_ISO_N")
	)
	(segment
		(start 304.6476 -413.4612)
		(end 302.0568 -416.052)
		(width 0.127)
		(layer "In4.Cu")
		(net "PRSNT_CABLE_SWB_B1_ISO_N")
	)
	(segment
		(start 260.688836 -381.694182)
		(end 183.667908 -381.694182)
		(width 0.127)
		(layer "In4.Cu")
		(net "PRSNT_CABLE_SWB_B1_ISO_N")
	)
	(segment
		(start 277.426674 -387.5024)
		(end 270.1036 -387.5024)
		(width 0.127)
		(layer "In4.Cu")
		(net "PRSNT_CABLE_SWB_B1_ISO_N")
	)
	(segment
		(start 302.0568 -416.052)
		(end 292.2524 -416.052)
		(width 0.127)
		(layer "In4.Cu")
		(net "PRSNT_CABLE_SWB_B1_ISO_N")
	)
	(segment
		(start 291.3126 -415.1122)
		(end 282.448 -415.1122)
		(width 0.127)
		(layer "In4.Cu")
		(net "PRSNT_CABLE_SWB_B1_ISO_N")
	)
	(segment
		(start 294.445436 -398.966436)
		(end 293.83482 -398.35582)
		(width 0.127)
		(layer "In4.Cu")
		(net "PRSNT_CABLE_SWB_B1_ISO_N")
	)
	(segment
		(start 172.1358 -404.5204)
		(end 172.4406 -404.5204)
		(width 0.127)
		(layer "In4.Cu")
		(net "PRSNT_CABLE_SWB_B1_ISO_N")
	)
	(segment
		(start 282.1432 -394.518388)
		(end 282.1432 -392.218926)
		(width 0.127)
		(layer "In4.Cu")
		(net "PRSNT_CABLE_SWB_B1_ISO_N")
	)
	(segment
		(start 282.2194 -414.8836)
		(end 282.2194 -411.5816)
		(width 0.127)
		(layer "In4.Cu")
		(net "PRSNT_CABLE_SWB_B1_ISO_N")
	)
	(segment
		(start 288.6456 -409.9052)
		(end 292.4302 -409.9052)
		(width 0.127)
		(layer "In4.Cu")
		(net "PRSNT_CABLE_SWB_B1_ISO_N")
	)
	(segment
		(start 171.8818 -404.2664)
		(end 172.1358 -404.5204)
		(width 0.127)
		(layer "In4.Cu")
		(net "PRSNT_CABLE_SWB_B1_ISO_N")
	)
	(segment
		(start 282.8798 -410.9212)
		(end 287.6296 -410.9212)
		(width 0.127)
		(layer "In4.Cu")
		(net "PRSNT_CABLE_SWB_B1_ISO_N")
	)
	(segment
		(start 171.8818 -403.453854)
		(end 171.8818 -404.2664)
		(width 0.127)
		(layer "In4.Cu")
		(net "PRSNT_CABLE_SWB_B1_ISO_N")
	)
	(segment
		(start 287.6296 -410.9212)
		(end 288.6456 -409.9052)
		(width 0.127)
		(layer "In4.Cu")
		(net "PRSNT_CABLE_SWB_B1_ISO_N")
	)
	(segment
		(start 264.126472 -385.131818)
		(end 260.688836 -381.694182)
		(width 0.127)
		(layer "In4.Cu")
		(net "PRSNT_CABLE_SWB_B1_ISO_N")
	)
	(segment
		(start 97.3328 -426.2882)
		(end 95.758 -427.863)
		(width 0.127)
		(layer "In6.Cu")
		(net "PRSNT_CABLE_SWB_B1_ISO_N")
	)
	(segment
		(start 119.74322 -416.43427)
		(end 119.74322 -417.16198)
		(width 0.127)
		(layer "In6.Cu")
		(net "PRSNT_CABLE_SWB_B1_ISO_N")
	)
	(segment
		(start 170.815 -404.5204)
		(end 170.2816 -405.0538)
		(width 0.127)
		(layer "In6.Cu")
		(net "PRSNT_CABLE_SWB_B1_ISO_N")
	)
	(segment
		(start 95.758 -427.863)
		(end 94.2086 -427.863)
		(width 0.127)
		(layer "In6.Cu")
		(net "PRSNT_CABLE_SWB_B1_ISO_N")
	)
	(segment
		(start 106.696002 -426.2882)
		(end 97.3328 -426.2882)
		(width 0.127)
		(layer "In6.Cu")
		(net "PRSNT_CABLE_SWB_B1_ISO_N")
	)
	(segment
		(start 119.2276 -409.9306)
		(end 119.2276 -415.91865)
		(width 0.127)
		(layer "In6.Cu")
		(net "PRSNT_CABLE_SWB_B1_ISO_N")
	)
	(segment
		(start 170.2816 -407.294588)
		(end 169.093388 -408.4828)
		(width 0.127)
		(layer "In6.Cu")
		(net "PRSNT_CABLE_SWB_B1_ISO_N")
	)
	(segment
		(start 107.9246 -420.5732)
		(end 107.9246 -425.059602)
		(width 0.127)
		(layer "In6.Cu")
		(net "PRSNT_CABLE_SWB_B1_ISO_N")
	)
	(segment
		(start 119.74322 -417.16198)
		(end 116.5606 -420.3446)
		(width 0.127)
		(layer "In6.Cu")
		(net "PRSNT_CABLE_SWB_B1_ISO_N")
	)
	(segment
		(start 116.5606 -420.3446)
		(end 108.1532 -420.3446)
		(width 0.127)
		(layer "In6.Cu")
		(net "PRSNT_CABLE_SWB_B1_ISO_N")
	)
	(segment
		(start 94.2086 -427.863)
		(end 93.8022 -427.4566)
		(width 0.127)
		(layer "In6.Cu")
		(net "PRSNT_CABLE_SWB_B1_ISO_N")
	)
	(segment
		(start 119.2276 -415.91865)
		(end 119.74322 -416.43427)
		(width 0.127)
		(layer "In6.Cu")
		(net "PRSNT_CABLE_SWB_B1_ISO_N")
	)
	(segment
		(start 172.4406 -404.5204)
		(end 170.815 -404.5204)
		(width 0.127)
		(layer "In6.Cu")
		(net "PRSNT_CABLE_SWB_B1_ISO_N")
	)
	(segment
		(start 108.1532 -420.3446)
		(end 107.9246 -420.5732)
		(width 0.127)
		(layer "In6.Cu")
		(net "PRSNT_CABLE_SWB_B1_ISO_N")
	)
	(segment
		(start 120.6754 -408.4828)
		(end 119.2276 -409.9306)
		(width 0.127)
		(layer "In6.Cu")
		(net "PRSNT_CABLE_SWB_B1_ISO_N")
	)
	(segment
		(start 169.093388 -408.4828)
		(end 120.6754 -408.4828)
		(width 0.127)
		(layer "In6.Cu")
		(net "PRSNT_CABLE_SWB_B1_ISO_N")
	)
	(segment
		(start 107.9246 -425.059602)
		(end 106.696002 -426.2882)
		(width 0.127)
		(layer "In6.Cu")
		(net "PRSNT_CABLE_SWB_B1_ISO_N")
	)
	(segment
		(start 170.2816 -405.0538)
		(end 170.2816 -407.294588)
		(width 0.127)
		(layer "In6.Cu")
		(net "PRSNT_CABLE_SWB_B1_ISO_N")
	)
	(segment
		(start 371.362986 -408.319986)
		(end 370.21516 -408.319986)
		(width 0.12954)
		(layer "F.Cu")
		(net "PRSNT_CABLE_SWB_B1")
	)
	(segment
		(start 371.454934 -408.411934)
		(end 371.362986 -408.319986)
		(width 0.12954)
		(layer "F.Cu")
		(net "PRSNT_CABLE_SWB_B1")
	)
	(segment
		(start 371.454934 -408.8892)
		(end 371.454934 -408.411934)
		(width 0.12954)
		(layer "F.Cu")
		(net "PRSNT_CABLE_SWB_B1")
	)
	(segment
		(start 370.21516 -409.6512)
		(end 371.2972 -409.6512)
		(width 0.12954)
		(layer "F.Cu")
		(net "PRSNT_CABLE_SWB_B1")
	)
	(segment
		(start 371.2972 -409.6512)
		(end 371.454934 -409.493466)
		(width 0.12954)
		(layer "F.Cu")
		(net "PRSNT_CABLE_SWB_B1")
	)
	(segment
		(start 370.21516 -408.319986)
		(end 370.21516 -407.67)
		(width 0.12954)
		(layer "F.Cu")
		(net "PRSNT_CABLE_SWB_B1")
	)
	(segment
		(start 371.454934 -409.493466)
		(end 371.454934 -408.8892)
		(width 0.12954)
		(layer "F.Cu")
		(net "PRSNT_CABLE_SWB_B1")
	)
	(via
		(at 371.454934 -408.8892)
		(size 0.762)
		(drill 0.381)
		(layers "F.Cu" "B.Cu")
		(net "PRSNT_CABLE_SWB_B1")
	)
	(segment
		(start 20.2184 -412.4452)
		(end 20.574 -412.4452)
		(width 0.12954)
		(layer "F.Cu")
		(net "PRSNT_CABLE_GPU_B3_ISO_R1_N")
	)
	(segment
		(start 20.8026 -412.2166)
		(end 20.574 -412.4452)
		(width 0.12954)
		(layer "F.Cu")
		(net "PRSNT_CABLE_GPU_B3_ISO_R1_N")
	)
	(segment
		(start 19.590004 -414.277302)
		(end 19.590004 -413.073596)
		(width 0.12954)
		(layer "F.Cu")
		(net "PRSNT_CABLE_GPU_B3_ISO_R1_N")
	)
	(segment
		(start 19.590004 -413.073596)
		(end 20.2184 -412.4452)
		(width 0.12954)
		(layer "F.Cu")
		(net "PRSNT_CABLE_GPU_B3_ISO_R1_N")
	)
	(segment
		(start 20.8026 -411.19425)
		(end 20.8026 -412.2166)
		(width 0.12954)
		(layer "F.Cu")
		(net "PRSNT_CABLE_GPU_B3_ISO_R1_N")
	)
	(via
		(at 20.574 -412.4452)
		(size 0.762)
		(drill 0.381)
		(layers "F.Cu" "B.Cu")
		(net "PRSNT_CABLE_GPU_B3_ISO_R1_N")
	)
	(segment
		(start 300.833282 -421.193722)
		(end 300.833282 -419.73627)
		(width 0.12954)
		(layer "F.Cu")
		(net "PRSNT_CABLE_GPU_B3_ISO_N")
	)
	(segment
		(start 301.45482 -419.42766)
		(end 301.98695 -418.89553)
		(width 0.12954)
		(layer "F.Cu")
		(net "PRSNT_CABLE_GPU_B3_ISO_N")
	)
	(segment
		(start 301.190406 -423.05605)
		(end 301.190406 -422.610026)
		(width 0.12954)
		(layer "F.Cu")
		(net "PRSNT_CABLE_GPU_B3_ISO_N")
	)
	(segment
		(start 301.98695 -418.89553)
		(end 301.98695 -417.50234)
		(width 0.12954)
		(layer "F.Cu")
		(net "PRSNT_CABLE_GPU_B3_ISO_N")
	)
	(segment
		(start 301.141892 -419.42766)
		(end 301.45482 -419.42766)
		(width 0.12954)
		(layer "F.Cu")
		(net "PRSNT_CABLE_GPU_B3_ISO_N")
	)
	(segment
		(start 301.45482 -421.81526)
		(end 300.833282 -421.193722)
		(width 0.12954)
		(layer "F.Cu")
		(net "PRSNT_CABLE_GPU_B3_ISO_N")
	)
	(segment
		(start 201.40041 -112.994948)
		(end 202.01128 -112.994948)
		(width 0.12954)
		(layer "F.Cu")
		(net "PRSNT_CABLE_GPU_B3_ISO_N")
	)
	(segment
		(start 301.70501 -417.2204)
		(end 301.244 -417.2204)
		(width 0.12954)
		(layer "F.Cu")
		(net "PRSNT_CABLE_GPU_B3_ISO_N")
	)
	(segment
		(start 301.98695 -417.50234)
		(end 301.70501 -417.2204)
		(width 0.12954)
		(layer "F.Cu")
		(net "PRSNT_CABLE_GPU_B3_ISO_N")
	)
	(segment
		(start 300.833282 -419.73627)
		(end 301.141892 -419.42766)
		(width 0.12954)
		(layer "F.Cu")
		(net "PRSNT_CABLE_GPU_B3_ISO_N")
	)
	(segment
		(start 301.244 -417.2204)
		(end 301.244 -416.56)
		(width 0.12954)
		(layer "F.Cu")
		(net "PRSNT_CABLE_GPU_B3_ISO_N")
	)
	(segment
		(start 301.190406 -422.610026)
		(end 301.45482 -422.345612)
		(width 0.12954)
		(layer "F.Cu")
		(net "PRSNT_CABLE_GPU_B3_ISO_N")
	)
	(segment
		(start 20.8026 -410.39415)
		(end 20.8026 -409.7782)
		(width 0.12954)
		(layer "F.Cu")
		(net "PRSNT_CABLE_GPU_B3_ISO_N")
	)
	(segment
		(start 301.45482 -422.345612)
		(end 301.45482 -421.81526)
		(width 0.12954)
		(layer "F.Cu")
		(net "PRSNT_CABLE_GPU_B3_ISO_N")
	)
	(via
		(at 283.0322 -437.5658)
		(size 0.508)
		(drill 0.254)
		(layers "F.Cu" "B.Cu")
		(net "PRSNT_CABLE_GPU_B3_ISO_N")
	)
	(via
		(at 300.833282 -419.73627)
		(size 0.508)
		(drill 0.254)
		(layers "F.Cu" "B.Cu")
		(net "PRSNT_CABLE_GPU_B3_ISO_N")
	)
	(via
		(at 20.8026 -409.7782)
		(size 0.508)
		(drill 0.254)
		(layers "F.Cu" "B.Cu")
		(net "PRSNT_CABLE_GPU_B3_ISO_N")
	)
	(via
		(at 96.774 -392.811)
		(size 0.508)
		(drill 0.254)
		(layers "F.Cu" "B.Cu")
		(net "PRSNT_CABLE_GPU_B3_ISO_N")
	)
	(via
		(at 169.3164 -402.5646)
		(size 0.508)
		(drill 0.254)
		(layers "F.Cu" "B.Cu")
		(net "PRSNT_CABLE_GPU_B3_ISO_N")
	)
	(via
		(at 211.35086 -340.832948)
		(size 0.508)
		(drill 0.254)
		(layers "F.Cu" "B.Cu")
		(net "PRSNT_CABLE_GPU_B3_ISO_N")
	)
	(via
		(at 301.244 -416.56)
		(size 0.508)
		(drill 0.254)
		(layers "F.Cu" "B.Cu")
		(net "PRSNT_CABLE_GPU_B3_ISO_N")
	)
	(via
		(at 202.01128 -112.994948)
		(size 0.508)
		(drill 0.254)
		(layers "F.Cu" "B.Cu")
		(net "PRSNT_CABLE_GPU_B3_ISO_N")
	)
	(segment
		(start 299.757592 -418.66058)
		(end 294.3606 -418.66058)
		(width 0.12954)
		(layer "B.Cu")
		(net "PRSNT_CABLE_GPU_B3_ISO_N")
	)
	(segment
		(start 281.54122 -386.70738)
		(end 280.97734 -386.70738)
		(width 0.12954)
		(layer "B.Cu")
		(net "PRSNT_CABLE_GPU_B3_ISO_N")
	)
	(segment
		(start 241.146076 -340.832948)
		(end 211.35086 -340.832948)
		(width 0.12954)
		(layer "B.Cu")
		(net "PRSNT_CABLE_GPU_B3_ISO_N")
	)
	(segment
		(start 285.230062 -406.907492)
		(end 285.230062 -395.948408)
		(width 0.12954)
		(layer "B.Cu")
		(net "PRSNT_CABLE_GPU_B3_ISO_N")
	)
	(segment
		(start 288.21507 -409.8925)
		(end 285.230062 -406.907492)
		(width 0.12954)
		(layer "B.Cu")
		(net "PRSNT_CABLE_GPU_B3_ISO_N")
	)
	(segment
		(start 293.98468 -418.28466)
		(end 293.98468 -417.78174)
		(width 0.12954)
		(layer "B.Cu")
		(net "PRSNT_CABLE_GPU_B3_ISO_N")
	)
	(segment
		(start 168.5798 -399.23212)
		(end 168.05148 -398.7038)
		(width 0.12954)
		(layer "B.Cu")
		(net "PRSNT_CABLE_GPU_B3_ISO_N")
	)
	(segment
		(start 253.038356 -352.725228)
		(end 241.146076 -340.832948)
		(width 0.12954)
		(layer "B.Cu")
		(net "PRSNT_CABLE_GPU_B3_ISO_N")
	)
	(segment
		(start 293.98468 -417.78174)
		(end 292.04666 -415.84372)
		(width 0.12954)
		(layer "B.Cu")
		(net "PRSNT_CABLE_GPU_B3_ISO_N")
	)
	(segment
		(start 284.137862 -394.856208)
		(end 284.137862 -389.304022)
		(width 0.12954)
		(layer "B.Cu")
		(net "PRSNT_CABLE_GPU_B3_ISO_N")
	)
	(segment
		(start 112.649 -396.367)
		(end 106.7054 -396.367)
		(width 0.12954)
		(layer "B.Cu")
		(net "PRSNT_CABLE_GPU_B3_ISO_N")
	)
	(segment
		(start 105.212134 -394.873734)
		(end 98.836734 -394.873734)
		(width 0.12954)
		(layer "B.Cu")
		(net "PRSNT_CABLE_GPU_B3_ISO_N")
	)
	(segment
		(start 285.230062 -395.948408)
		(end 284.137862 -394.856208)
		(width 0.12954)
		(layer "B.Cu")
		(net "PRSNT_CABLE_GPU_B3_ISO_N")
	)
	(segment
		(start 168.5798 -401.828)
		(end 168.5798 -399.23212)
		(width 0.12954)
		(layer "B.Cu")
		(net "PRSNT_CABLE_GPU_B3_ISO_N")
	)
	(segment
		(start 106.7054 -396.367)
		(end 105.212134 -394.873734)
		(width 0.12954)
		(layer "B.Cu")
		(net "PRSNT_CABLE_GPU_B3_ISO_N")
	)
	(segment
		(start 292.04666 -415.84372)
		(end 292.04666 -410.60116)
		(width 0.12954)
		(layer "B.Cu")
		(net "PRSNT_CABLE_GPU_B3_ISO_N")
	)
	(segment
		(start 266.27074 -372.00078)
		(end 266.27074 -358.208072)
		(width 0.12954)
		(layer "B.Cu")
		(net "PRSNT_CABLE_GPU_B3_ISO_N")
	)
	(segment
		(start 280.97734 -386.70738)
		(end 266.27074 -372.00078)
		(width 0.12954)
		(layer "B.Cu")
		(net "PRSNT_CABLE_GPU_B3_ISO_N")
	)
	(segment
		(start 300.833282 -419.73627)
		(end 299.757592 -418.66058)
		(width 0.12954)
		(layer "B.Cu")
		(net "PRSNT_CABLE_GPU_B3_ISO_N")
	)
	(segment
		(start 116.495068 -395.691868)
		(end 113.324132 -395.691868)
		(width 0.12954)
		(layer "B.Cu")
		(net "PRSNT_CABLE_GPU_B3_ISO_N")
	)
	(segment
		(start 119.2022 -397.3576)
		(end 118.1608 -397.3576)
		(width 0.12954)
		(layer "B.Cu")
		(net "PRSNT_CABLE_GPU_B3_ISO_N")
	)
	(segment
		(start 292.04666 -410.60116)
		(end 291.338 -409.8925)
		(width 0.12954)
		(layer "B.Cu")
		(net "PRSNT_CABLE_GPU_B3_ISO_N")
	)
	(segment
		(start 118.1608 -397.3576)
		(end 116.495068 -395.691868)
		(width 0.12954)
		(layer "B.Cu")
		(net "PRSNT_CABLE_GPU_B3_ISO_N")
	)
	(segment
		(start 294.3606 -418.66058)
		(end 293.98468 -418.28466)
		(width 0.12954)
		(layer "B.Cu")
		(net "PRSNT_CABLE_GPU_B3_ISO_N")
	)
	(segment
		(start 169.3164 -402.5646)
		(end 168.5798 -401.828)
		(width 0.12954)
		(layer "B.Cu")
		(net "PRSNT_CABLE_GPU_B3_ISO_N")
	)
	(segment
		(start 120.5484 -398.7038)
		(end 119.2022 -397.3576)
		(width 0.12954)
		(layer "B.Cu")
		(net "PRSNT_CABLE_GPU_B3_ISO_N")
	)
	(segment
		(start 284.137862 -389.304022)
		(end 281.54122 -386.70738)
		(width 0.12954)
		(layer "B.Cu")
		(net "PRSNT_CABLE_GPU_B3_ISO_N")
	)
	(segment
		(start 266.27074 -358.208072)
		(end 260.787896 -352.725228)
		(width 0.12954)
		(layer "B.Cu")
		(net "PRSNT_CABLE_GPU_B3_ISO_N")
	)
	(segment
		(start 168.05148 -398.7038)
		(end 120.5484 -398.7038)
		(width 0.12954)
		(layer "B.Cu")
		(net "PRSNT_CABLE_GPU_B3_ISO_N")
	)
	(segment
		(start 98.836734 -394.873734)
		(end 96.774 -392.811)
		(width 0.12954)
		(layer "B.Cu")
		(net "PRSNT_CABLE_GPU_B3_ISO_N")
	)
	(segment
		(start 260.787896 -352.725228)
		(end 253.038356 -352.725228)
		(width 0.12954)
		(layer "B.Cu")
		(net "PRSNT_CABLE_GPU_B3_ISO_N")
	)
	(segment
		(start 291.338 -409.8925)
		(end 288.21507 -409.8925)
		(width 0.12954)
		(layer "B.Cu")
		(net "PRSNT_CABLE_GPU_B3_ISO_N")
	)
	(segment
		(start 113.324132 -395.691868)
		(end 112.649 -396.367)
		(width 0.12954)
		(layer "B.Cu")
		(net "PRSNT_CABLE_GPU_B3_ISO_N")
	)
	(segment
		(start 211.35086 -340.832948)
		(end 212.301074 -340.832948)
		(width 0.127)
		(layer "In2.Cu")
		(net "PRSNT_CABLE_GPU_B3_ISO_N")
	)
	(segment
		(start 207.899 -112.5728)
		(end 205.2066 -112.5728)
		(width 0.127)
		(layer "In2.Cu")
		(net "PRSNT_CABLE_GPU_B3_ISO_N")
	)
	(segment
		(start 205.2066 -112.5728)
		(end 204.41158 -113.36782)
		(width 0.127)
		(layer "In2.Cu")
		(net "PRSNT_CABLE_GPU_B3_ISO_N")
	)
	(segment
		(start 210.7438 -115.4176)
		(end 207.899 -112.5728)
		(width 0.127)
		(layer "In2.Cu")
		(net "PRSNT_CABLE_GPU_B3_ISO_N")
	)
	(segment
		(start 212.301074 -340.832948)
		(end 222.97898 -330.155042)
		(width 0.127)
		(layer "In2.Cu")
		(net "PRSNT_CABLE_GPU_B3_ISO_N")
	)
	(segment
		(start 214.68334 -124.6378)
		(end 213.106 -123.06046)
		(width 0.127)
		(layer "In2.Cu")
		(net "PRSNT_CABLE_GPU_B3_ISO_N")
	)
	(segment
		(start 213.106 -118.7958)
		(end 210.7438 -116.4336)
		(width 0.127)
		(layer "In2.Cu")
		(net "PRSNT_CABLE_GPU_B3_ISO_N")
	)
	(segment
		(start 202.384152 -113.36782)
		(end 202.01128 -112.994948)
		(width 0.127)
		(layer "In2.Cu")
		(net "PRSNT_CABLE_GPU_B3_ISO_N")
	)
	(segment
		(start 222.97898 -330.155042)
		(end 222.97898 -236.177328)
		(width 0.127)
		(layer "In2.Cu")
		(net "PRSNT_CABLE_GPU_B3_ISO_N")
	)
	(segment
		(start 210.7438 -116.4336)
		(end 210.7438 -115.4176)
		(width 0.127)
		(layer "In2.Cu")
		(net "PRSNT_CABLE_GPU_B3_ISO_N")
	)
	(segment
		(start 225.61296 -190.330074)
		(end 223.82734 -188.544454)
		(width 0.127)
		(layer "In2.Cu")
		(net "PRSNT_CABLE_GPU_B3_ISO_N")
	)
	(segment
		(start 223.82734 -147.200874)
		(end 214.68334 -138.056874)
		(width 0.127)
		(layer "In2.Cu")
		(net "PRSNT_CABLE_GPU_B3_ISO_N")
	)
	(segment
		(start 204.41158 -113.36782)
		(end 202.384152 -113.36782)
		(width 0.127)
		(layer "In2.Cu")
		(net "PRSNT_CABLE_GPU_B3_ISO_N")
	)
	(segment
		(start 213.106 -123.06046)
		(end 213.106 -118.7958)
		(width 0.127)
		(layer "In2.Cu")
		(net "PRSNT_CABLE_GPU_B3_ISO_N")
	)
	(segment
		(start 214.68334 -138.056874)
		(end 214.68334 -124.6378)
		(width 0.127)
		(layer "In2.Cu")
		(net "PRSNT_CABLE_GPU_B3_ISO_N")
	)
	(segment
		(start 225.61296 -233.543348)
		(end 225.61296 -190.330074)
		(width 0.127)
		(layer "In2.Cu")
		(net "PRSNT_CABLE_GPU_B3_ISO_N")
	)
	(segment
		(start 222.97898 -236.177328)
		(end 225.61296 -233.543348)
		(width 0.127)
		(layer "In2.Cu")
		(net "PRSNT_CABLE_GPU_B3_ISO_N")
	)
	(segment
		(start 223.82734 -188.544454)
		(end 223.82734 -147.200874)
		(width 0.127)
		(layer "In2.Cu")
		(net "PRSNT_CABLE_GPU_B3_ISO_N")
	)
	(segment
		(start 283.0322 -437.5658)
		(end 284.506924 -436.091076)
		(width 0.127)
		(layer "In4.Cu")
		(net "PRSNT_CABLE_GPU_B3_ISO_N")
	)
	(segment
		(start 284.506924 -436.091076)
		(end 284.506924 -428.44339)
		(width 0.127)
		(layer "In4.Cu")
		(net "PRSNT_CABLE_GPU_B3_ISO_N")
	)
	(segment
		(start 284.506924 -428.44339)
		(end 284.401514 -428.33798)
		(width 0.127)
		(layer "In4.Cu")
		(net "PRSNT_CABLE_GPU_B3_ISO_N")
	)
	(segment
		(start 300.8122 -420.6494)
		(end 300.8122 -419.757352)
		(width 0.127)
		(layer "In4.Cu")
		(net "PRSNT_CABLE_GPU_B3_ISO_N")
	)
	(segment
		(start 293.4208 -422.3766)
		(end 294.6146 -421.1828)
		(width 0.127)
		(layer "In4.Cu")
		(net "PRSNT_CABLE_GPU_B3_ISO_N")
	)
	(segment
		(start 284.401514 -427.433486)
		(end 285.1912 -426.6438)
		(width 0.127)
		(layer "In4.Cu")
		(net "PRSNT_CABLE_GPU_B3_ISO_N")
	)
	(segment
		(start 294.6146 -421.1828)
		(end 300.2788 -421.1828)
		(width 0.127)
		(layer "In4.Cu")
		(net "PRSNT_CABLE_GPU_B3_ISO_N")
	)
	(segment
		(start 291.4396 -426.6438)
		(end 293.4208 -424.6626)
		(width 0.127)
		(layer "In4.Cu")
		(net "PRSNT_CABLE_GPU_B3_ISO_N")
	)
	(segment
		(start 293.4208 -424.6626)
		(end 293.4208 -422.3766)
		(width 0.127)
		(layer "In4.Cu")
		(net "PRSNT_CABLE_GPU_B3_ISO_N")
	)
	(segment
		(start 300.8122 -419.757352)
		(end 300.833282 -419.73627)
		(width 0.127)
		(layer "In4.Cu")
		(net "PRSNT_CABLE_GPU_B3_ISO_N")
	)
	(segment
		(start 300.2788 -421.1828)
		(end 300.8122 -420.6494)
		(width 0.127)
		(layer "In4.Cu")
		(net "PRSNT_CABLE_GPU_B3_ISO_N")
	)
	(segment
		(start 285.1912 -426.6438)
		(end 291.4396 -426.6438)
		(width 0.127)
		(layer "In4.Cu")
		(net "PRSNT_CABLE_GPU_B3_ISO_N")
	)
	(segment
		(start 284.401514 -428.33798)
		(end 284.401514 -427.433486)
		(width 0.127)
		(layer "In4.Cu")
		(net "PRSNT_CABLE_GPU_B3_ISO_N")
	)
	(segment
		(start 44.4246 -397.99768)
		(end 44.4246 -399.9738)
		(width 0.127)
		(layer "In11.Cu")
		(net "PRSNT_CABLE_GPU_B3_ISO_N")
	)
	(segment
		(start 96.774 -392.811)
		(end 96.774 -394.113766)
		(width 0.127)
		(layer "In11.Cu")
		(net "PRSNT_CABLE_GPU_B3_ISO_N")
	)
	(segment
		(start 95.714566 -395.1732)
		(end 50.266346 -395.1732)
		(width 0.127)
		(layer "In11.Cu")
		(net "PRSNT_CABLE_GPU_B3_ISO_N")
	)
	(segment
		(start 46.8376 -393.827)
		(end 46.1518 -394.5128)
		(width 0.127)
		(layer "In11.Cu")
		(net "PRSNT_CABLE_GPU_B3_ISO_N")
	)
	(segment
		(start 42.7736 -402.816568)
		(end 37.031168 -408.559)
		(width 0.127)
		(layer "In11.Cu")
		(net "PRSNT_CABLE_GPU_B3_ISO_N")
	)
	(segment
		(start 47.879 -393.827)
		(end 46.8376 -393.827)
		(width 0.127)
		(layer "In11.Cu")
		(net "PRSNT_CABLE_GPU_B3_ISO_N")
	)
	(segment
		(start 21.6408 -408.559)
		(end 20.8026 -409.3972)
		(width 0.127)
		(layer "In11.Cu")
		(net "PRSNT_CABLE_GPU_B3_ISO_N")
	)
	(segment
		(start 46.1518 -394.5128)
		(end 46.1518 -396.27048)
		(width 0.127)
		(layer "In11.Cu")
		(net "PRSNT_CABLE_GPU_B3_ISO_N")
	)
	(segment
		(start 49.707546 -394.6144)
		(end 48.6664 -394.6144)
		(width 0.127)
		(layer "In11.Cu")
		(net "PRSNT_CABLE_GPU_B3_ISO_N")
	)
	(segment
		(start 50.266346 -395.1732)
		(end 49.707546 -394.6144)
		(width 0.127)
		(layer "In11.Cu")
		(net "PRSNT_CABLE_GPU_B3_ISO_N")
	)
	(segment
		(start 96.774 -394.113766)
		(end 95.714566 -395.1732)
		(width 0.127)
		(layer "In11.Cu")
		(net "PRSNT_CABLE_GPU_B3_ISO_N")
	)
	(segment
		(start 42.7736 -401.6248)
		(end 42.7736 -402.816568)
		(width 0.127)
		(layer "In11.Cu")
		(net "PRSNT_CABLE_GPU_B3_ISO_N")
	)
	(segment
		(start 20.8026 -409.3972)
		(end 20.8026 -409.7782)
		(width 0.127)
		(layer "In11.Cu")
		(net "PRSNT_CABLE_GPU_B3_ISO_N")
	)
	(segment
		(start 44.4246 -399.9738)
		(end 42.7736 -401.6248)
		(width 0.127)
		(layer "In11.Cu")
		(net "PRSNT_CABLE_GPU_B3_ISO_N")
	)
	(segment
		(start 48.6664 -394.6144)
		(end 47.879 -393.827)
		(width 0.127)
		(layer "In11.Cu")
		(net "PRSNT_CABLE_GPU_B3_ISO_N")
	)
	(segment
		(start 46.1518 -396.27048)
		(end 44.4246 -397.99768)
		(width 0.127)
		(layer "In11.Cu")
		(net "PRSNT_CABLE_GPU_B3_ISO_N")
	)
	(segment
		(start 37.031168 -408.559)
		(end 21.6408 -408.559)
		(width 0.127)
		(layer "In11.Cu")
		(net "PRSNT_CABLE_GPU_B3_ISO_N")
	)
	(segment
		(start 171.323 -410.7942)
		(end 171.323 -404.5712)
		(width 0.127)
		(layer "In13.Cu")
		(net "PRSNT_CABLE_GPU_B3_ISO_N")
	)
	(segment
		(start 198.5264 -437.9722)
		(end 187.7314 -427.1772)
		(width 0.127)
		(layer "In13.Cu")
		(net "PRSNT_CABLE_GPU_B3_ISO_N")
	)
	(segment
		(start 173.7614 -419.862)
		(end 173.7614 -416.687)
		(width 0.127)
		(layer "In13.Cu")
		(net "PRSNT_CABLE_GPU_B3_ISO_N")
	)
	(segment
		(start 176.7078 -419.2524)
		(end 175.2854 -420.6748)
		(width 0.127)
		(layer "In13.Cu")
		(net "PRSNT_CABLE_GPU_B3_ISO_N")
	)
	(segment
		(start 277.8506 -437.9722)
		(end 198.5264 -437.9722)
		(width 0.127)
		(layer "In13.Cu")
		(net "PRSNT_CABLE_GPU_B3_ISO_N")
	)
	(segment
		(start 180.40604 -419.2524)
		(end 176.7078 -419.2524)
		(width 0.127)
		(layer "In13.Cu")
		(net "PRSNT_CABLE_GPU_B3_ISO_N")
	)
	(segment
		(start 187.7314 -427.1772)
		(end 187.7314 -426.57776)
		(width 0.127)
		(layer "In13.Cu")
		(net "PRSNT_CABLE_GPU_B3_ISO_N")
	)
	(segment
		(start 187.7314 -426.57776)
		(end 180.40604 -419.2524)
		(width 0.127)
		(layer "In13.Cu")
		(net "PRSNT_CABLE_GPU_B3_ISO_N")
	)
	(segment
		(start 170.6372 -411.48)
		(end 171.323 -410.7942)
		(width 0.127)
		(layer "In13.Cu")
		(net "PRSNT_CABLE_GPU_B3_ISO_N")
	)
	(segment
		(start 174.5742 -420.6748)
		(end 173.7614 -419.862)
		(width 0.127)
		(layer "In13.Cu")
		(net "PRSNT_CABLE_GPU_B3_ISO_N")
	)
	(segment
		(start 281.4574 -439.1406)
		(end 279.019 -439.1406)
		(width 0.127)
		(layer "In13.Cu")
		(net "PRSNT_CABLE_GPU_B3_ISO_N")
	)
	(segment
		(start 171.323 -404.5712)
		(end 169.3164 -402.5646)
		(width 0.127)
		(layer "In13.Cu")
		(net "PRSNT_CABLE_GPU_B3_ISO_N")
	)
	(segment
		(start 279.019 -439.1406)
		(end 277.8506 -437.9722)
		(width 0.127)
		(layer "In13.Cu")
		(net "PRSNT_CABLE_GPU_B3_ISO_N")
	)
	(segment
		(start 175.2854 -420.6748)
		(end 174.5742 -420.6748)
		(width 0.127)
		(layer "In13.Cu")
		(net "PRSNT_CABLE_GPU_B3_ISO_N")
	)
	(segment
		(start 173.7614 -416.687)
		(end 170.6372 -413.5628)
		(width 0.127)
		(layer "In13.Cu")
		(net "PRSNT_CABLE_GPU_B3_ISO_N")
	)
	(segment
		(start 170.6372 -413.5628)
		(end 170.6372 -411.48)
		(width 0.127)
		(layer "In13.Cu")
		(net "PRSNT_CABLE_GPU_B3_ISO_N")
	)
	(segment
		(start 283.0322 -437.5658)
		(end 281.4574 -439.1406)
		(width 0.127)
		(layer "In13.Cu")
		(net "PRSNT_CABLE_GPU_B3_ISO_N")
	)
	(segment
		(start 357.3526 -411.0482)
		(end 360.0958 -411.0482)
		(width 0.12954)
		(layer "F.Cu")
		(net "PRSNT_CABLE_GPU_A3_N")
	)
	(segment
		(start 355.3714 -412.1912)
		(end 356.2096 -412.1912)
		(width 0.12954)
		(layer "F.Cu")
		(net "PRSNT_CABLE_GPU_A3_N")
	)
	(segment
		(start 363.6264 -412.8262)
		(end 363.7915 -412.9913)
		(width 0.12954)
		(layer "F.Cu")
		(net "PRSNT_CABLE_GPU_A3_N")
	)
	(segment
		(start 360.0958 -411.0482)
		(end 360.807 -411.7594)
		(width 0.12954)
		(layer "F.Cu")
		(net "PRSNT_CABLE_GPU_A3_N")
	)
	(segment
		(start 356.2096 -412.1912)
		(end 357.3526 -411.0482)
		(width 0.12954)
		(layer "F.Cu")
		(net "PRSNT_CABLE_GPU_A3_N")
	)
	(segment
		(start 364.43285 -412.9913)
		(end 364.80115 -412.623)
		(width 0.12954)
		(layer "F.Cu")
		(net "PRSNT_CABLE_GPU_A3_N")
	)
	(segment
		(start 352.298 -418.0078)
		(end 355.0666 -415.2392)
		(width 0.12954)
		(layer "F.Cu")
		(net "PRSNT_CABLE_GPU_A3_N")
	)
	(segment
		(start 360.807 -411.7594)
		(end 362.712 -411.7594)
		(width 0.12954)
		(layer "F.Cu")
		(net "PRSNT_CABLE_GPU_A3_N")
	)
	(segment
		(start 364.80115 -412.623)
		(end 364.80115 -411.5562)
		(width 0.12954)
		(layer "F.Cu")
		(net "PRSNT_CABLE_GPU_A3_N")
	)
	(segment
		(start 355.0666 -412.496)
		(end 355.3714 -412.1912)
		(width 0.12954)
		(layer "F.Cu")
		(net "PRSNT_CABLE_GPU_A3_N")
	)
	(segment
		(start 352.0948 -418.0078)
		(end 352.298 -418.0078)
		(width 0.12954)
		(layer "F.Cu")
		(net "PRSNT_CABLE_GPU_A3_N")
	)
	(segment
		(start 362.9152 -411.5562)
		(end 364.80115 -411.5562)
		(width 0.12954)
		(layer "F.Cu")
		(net "PRSNT_CABLE_GPU_A3_N")
	)
	(segment
		(start 362.3945 -412.9913)
		(end 363.4613 -412.9913)
		(width 0.12954)
		(layer "F.Cu")
		(net "PRSNT_CABLE_GPU_A3_N")
	)
	(segment
		(start 363.7915 -412.9913)
		(end 364.43285 -412.9913)
		(width 0.12954)
		(layer "F.Cu")
		(net "PRSNT_CABLE_GPU_A3_N")
	)
	(segment
		(start 363.4613 -412.9913)
		(end 363.6264 -412.8262)
		(width 0.12954)
		(layer "F.Cu")
		(net "PRSNT_CABLE_GPU_A3_N")
	)
	(segment
		(start 362.712 -411.7594)
		(end 362.9152 -411.5562)
		(width 0.12954)
		(layer "F.Cu")
		(net "PRSNT_CABLE_GPU_A3_N")
	)
	(segment
		(start 355.0666 -415.2392)
		(end 355.0666 -412.496)
		(width 0.12954)
		(layer "F.Cu")
		(net "PRSNT_CABLE_GPU_A3_N")
	)
	(via
		(at 363.6264 -412.8262)
		(size 0.762)
		(drill 0.381)
		(layers "F.Cu" "B.Cu")
		(net "PRSNT_CABLE_GPU_A3_N")
	)
	(via
		(at 352.0948 -418.0078)
		(size 0.508)
		(drill 0.254)
		(layers "F.Cu" "B.Cu")
		(net "PRSNT_CABLE_GPU_A3_N")
	)
	(via
		(at 329.42022 -421.77208)
		(size 0.6604)
		(drill 0.3302)
		(layers "F.Cu" "B.Cu")
		(net "PRSNT_CABLE_GPU_A3_N")
	)
	(segment
		(start 351.1677 -418.9349)
		(end 332.2701 -418.9349)
		(width 0.12954)
		(layer "B.Cu")
		(net "PRSNT_CABLE_GPU_A3_N")
	)
	(segment
		(start 332.2701 -418.9349)
		(end 329.43292 -421.77208)
		(width 0.12954)
		(layer "B.Cu")
		(net "PRSNT_CABLE_GPU_A3_N")
	)
	(segment
		(start 352.0948 -418.0078)
		(end 351.1677 -418.9349)
		(width 0.12954)
		(layer "B.Cu")
		(net "PRSNT_CABLE_GPU_A3_N")
	)
	(segment
		(start 328.650092 -424.689778)
		(end 328.650092 -422.542208)
		(width 0.12954)
		(layer "B.Cu")
		(net "PRSNT_CABLE_GPU_A3_N")
	)
	(segment
		(start 329.43292 -421.77208)
		(end 329.42022 -421.77208)
		(width 0.12954)
		(layer "B.Cu")
		(net "PRSNT_CABLE_GPU_A3_N")
	)
	(segment
		(start 328.650092 -422.542208)
		(end 329.42022 -421.77208)
		(width 0.12954)
		(layer "B.Cu")
		(net "PRSNT_CABLE_GPU_A3_N")
	)
	(segment
		(start 15.959582 -422.97858)
		(end 16.33982 -422.598342)
		(width 0.12954)
		(layer "F.Cu")
		(net "PRSNT_CABLE_GPU_A3_ISO_R_N")
	)
	(segment
		(start 15.959582 -424.518836)
		(end 15.959582 -422.97858)
		(width 0.12954)
		(layer "F.Cu")
		(net "PRSNT_CABLE_GPU_A3_ISO_R_N")
	)
	(segment
		(start 15.494 -424.984418)
		(end 15.959582 -424.518836)
		(width 0.12954)
		(layer "F.Cu")
		(net "PRSNT_CABLE_GPU_A3_ISO_R_N")
	)
	(segment
		(start 16.33982 -422.598342)
		(end 16.33982 -420.12743)
		(width 0.12954)
		(layer "F.Cu")
		(net "PRSNT_CABLE_GPU_A3_ISO_R_N")
	)
	(segment
		(start 15.494 -425.73575)
		(end 15.494 -424.984418)
		(width 0.12954)
		(layer "F.Cu")
		(net "PRSNT_CABLE_GPU_A3_ISO_R_N")
	)
	(via
		(at 15.959582 -424.518836)
		(size 0.762)
		(drill 0.381)
		(layers "F.Cu" "B.Cu")
		(net "PRSNT_CABLE_GPU_A3_ISO_R_N")
	)
	(segment
		(start 364.0328 -413.6898)
		(end 363.6264 -414.0962)
		(width 0.12954)
		(layer "F.Cu")
		(net "PRSNT_CABLE_GPU_A3_ISO_N")
	)
	(segment
		(start 355.727 -418.0078)
		(end 364.109 -418.0078)
		(width 0.12954)
		(layer "F.Cu")
		(net "PRSNT_CABLE_GPU_A3_ISO_N")
	)
	(segment
		(start 363.171486 -413.641286)
		(end 363.6264 -414.0962)
		(width 0.12954)
		(layer "F.Cu")
		(net "PRSNT_CABLE_GPU_A3_ISO_N")
	)
	(segment
		(start 362.3945 -413.641286)
		(end 363.171486 -413.641286)
		(width 0.12954)
		(layer "F.Cu")
		(net "PRSNT_CABLE_GPU_A3_ISO_N")
	)
	(segment
		(start 364.80115 -413.6898)
		(end 364.80115 -414.7566)
		(width 0.12954)
		(layer "F.Cu")
		(net "PRSNT_CABLE_GPU_A3_ISO_N")
	)
	(segment
		(start 364.80115 -417.31565)
		(end 364.80115 -414.7566)
		(width 0.12954)
		(layer "F.Cu")
		(net "PRSNT_CABLE_GPU_A3_ISO_N")
	)
	(segment
		(start 15.494 -426.53585)
		(end 14.81455 -426.53585)
		(width 0.12954)
		(layer "F.Cu")
		(net "PRSNT_CABLE_GPU_A3_ISO_N")
	)
	(segment
		(start 364.80115 -413.6898)
		(end 364.0328 -413.6898)
		(width 0.12954)
		(layer "F.Cu")
		(net "PRSNT_CABLE_GPU_A3_ISO_N")
	)
	(segment
		(start 364.109 -418.0078)
		(end 364.80115 -417.31565)
		(width 0.12954)
		(layer "F.Cu")
		(net "PRSNT_CABLE_GPU_A3_ISO_N")
	)
	(segment
		(start 354.8126 -417.0934)
		(end 355.727 -418.0078)
		(width 0.12954)
		(layer "F.Cu")
		(net "PRSNT_CABLE_GPU_A3_ISO_N")
	)
	(via
		(at 363.6264 -414.0962)
		(size 0.762)
		(drill 0.381)
		(layers "F.Cu" "B.Cu")
		(net "PRSNT_CABLE_GPU_A3_ISO_N")
	)
	(via
		(at 96.9772 -391.0584)
		(size 0.508)
		(drill 0.254)
		(layers "F.Cu" "B.Cu")
		(net "PRSNT_CABLE_GPU_A3_ISO_N")
	)
	(via
		(at 14.81455 -426.53585)
		(size 0.508)
		(drill 0.254)
		(layers "F.Cu" "B.Cu")
		(net "PRSNT_CABLE_GPU_A3_ISO_N")
	)
	(via
		(at 169.3418 -404.3426)
		(size 0.508)
		(drill 0.254)
		(layers "F.Cu" "B.Cu")
		(net "PRSNT_CABLE_GPU_A3_ISO_N")
	)
	(via
		(at 354.8126 -417.0934)
		(size 0.508)
		(drill 0.254)
		(layers "F.Cu" "B.Cu")
		(net "PRSNT_CABLE_GPU_A3_ISO_N")
	)
	(via
		(at 284.2768 -438.7088)
		(size 0.508)
		(drill 0.254)
		(layers "F.Cu" "B.Cu")
		(net "PRSNT_CABLE_GPU_A3_ISO_N")
	)
	(segment
		(start 114.1222 -394.6398)
		(end 113.7412 -394.2588)
		(width 0.12954)
		(layer "B.Cu")
		(net "PRSNT_CABLE_GPU_A3_ISO_N")
	)
	(segment
		(start 170.5102 -399.904966)
		(end 168.420034 -397.8148)
		(width 0.12954)
		(layer "B.Cu")
		(net "PRSNT_CABLE_GPU_A3_ISO_N")
	)
	(segment
		(start 98.974148 -393.055348)
		(end 96.9772 -391.0584)
		(width 0.12954)
		(layer "B.Cu")
		(net "PRSNT_CABLE_GPU_A3_ISO_N")
	)
	(segment
		(start 121.031 -397.8148)
		(end 119.6594 -396.4432)
		(width 0.12954)
		(layer "B.Cu")
		(net "PRSNT_CABLE_GPU_A3_ISO_N")
	)
	(segment
		(start 168.420034 -397.8148)
		(end 121.031 -397.8148)
		(width 0.12954)
		(layer "B.Cu")
		(net "PRSNT_CABLE_GPU_A3_ISO_N")
	)
	(segment
		(start 116.8908 -394.6398)
		(end 114.1222 -394.6398)
		(width 0.12954)
		(layer "B.Cu")
		(net "PRSNT_CABLE_GPU_A3_ISO_N")
	)
	(segment
		(start 119.6594 -396.4432)
		(end 118.6942 -396.4432)
		(width 0.12954)
		(layer "B.Cu")
		(net "PRSNT_CABLE_GPU_A3_ISO_N")
	)
	(segment
		(start 111.649002 -393.055348)
		(end 98.974148 -393.055348)
		(width 0.12954)
		(layer "B.Cu")
		(net "PRSNT_CABLE_GPU_A3_ISO_N")
	)
	(segment
		(start 170.5102 -403.417024)
		(end 170.5102 -399.904966)
		(width 0.12954)
		(layer "B.Cu")
		(net "PRSNT_CABLE_GPU_A3_ISO_N")
	)
	(segment
		(start 169.584624 -404.3426)
		(end 170.5102 -403.417024)
		(width 0.12954)
		(layer "B.Cu")
		(net "PRSNT_CABLE_GPU_A3_ISO_N")
	)
	(segment
		(start 118.6942 -396.4432)
		(end 116.8908 -394.6398)
		(width 0.12954)
		(layer "B.Cu")
		(net "PRSNT_CABLE_GPU_A3_ISO_N")
	)
	(segment
		(start 112.852454 -394.2588)
		(end 111.649002 -393.055348)
		(width 0.12954)
		(layer "B.Cu")
		(net "PRSNT_CABLE_GPU_A3_ISO_N")
	)
	(segment
		(start 113.7412 -394.2588)
		(end 112.852454 -394.2588)
		(width 0.12954)
		(layer "B.Cu")
		(net "PRSNT_CABLE_GPU_A3_ISO_N")
	)
	(segment
		(start 169.3418 -404.3426)
		(end 169.584624 -404.3426)
		(width 0.12954)
		(layer "B.Cu")
		(net "PRSNT_CABLE_GPU_A3_ISO_N")
	)
	(segment
		(start 351.917 -402.4376)
		(end 352.9076 -403.4282)
		(width 0.127)
		(layer "In6.Cu")
		(net "PRSNT_CABLE_GPU_A3_ISO_N")
	)
	(segment
		(start 310.1848 -424.941746)
		(end 304.7238 -419.480746)
		(width 0.127)
		(layer "In6.Cu")
		(net "PRSNT_CABLE_GPU_A3_ISO_N")
	)
	(segment
		(start 302.9966 -403.4028)
		(end 303.9618 -402.4376)
		(width 0.127)
		(layer "In6.Cu")
		(net "PRSNT_CABLE_GPU_A3_ISO_N")
	)
	(segment
		(start 353.8474 -405.1808)
		(end 353.8474 -416.1282)
		(width 0.127)
		(layer "In6.Cu")
		(net "PRSNT_CABLE_GPU_A3_ISO_N")
	)
	(segment
		(start 353.8474 -416.1282)
		(end 354.8126 -417.0934)
		(width 0.127)
		(layer "In6.Cu")
		(net "PRSNT_CABLE_GPU_A3_ISO_N")
	)
	(segment
		(start 291.561266 -427.106334)
		(end 292.989 -425.6786)
		(width 0.127)
		(layer "In6.Cu")
		(net "PRSNT_CABLE_GPU_A3_ISO_N")
	)
	(segment
		(start 285.486348 -437.499252)
		(end 285.486348 -428.075852)
		(width 0.127)
		(layer "In6.Cu")
		(net "PRSNT_CABLE_GPU_A3_ISO_N")
	)
	(segment
		(start 292.989 -425.6786)
		(end 305.5874 -425.6786)
		(width 0.127)
		(layer "In6.Cu")
		(net "PRSNT_CABLE_GPU_A3_ISO_N")
	)
	(segment
		(start 310.1848 -428.1932)
		(end 310.1848 -424.941746)
		(width 0.127)
		(layer "In6.Cu")
		(net "PRSNT_CABLE_GPU_A3_ISO_N")
	)
	(segment
		(start 352.9076 -403.4282)
		(end 352.9076 -404.241)
		(width 0.127)
		(layer "In6.Cu")
		(net "PRSNT_CABLE_GPU_A3_ISO_N")
	)
	(segment
		(start 308.737 -428.8282)
		(end 309.5498 -428.8282)
		(width 0.127)
		(layer "In6.Cu")
		(net "PRSNT_CABLE_GPU_A3_ISO_N")
	)
	(segment
		(start 304.7238 -419.480746)
		(end 304.7238 -415.4932)
		(width 0.127)
		(layer "In6.Cu")
		(net "PRSNT_CABLE_GPU_A3_ISO_N")
	)
	(segment
		(start 309.5498 -428.8282)
		(end 310.1848 -428.1932)
		(width 0.127)
		(layer "In6.Cu")
		(net "PRSNT_CABLE_GPU_A3_ISO_N")
	)
	(segment
		(start 352.9076 -404.241)
		(end 353.8474 -405.1808)
		(width 0.127)
		(layer "In6.Cu")
		(net "PRSNT_CABLE_GPU_A3_ISO_N")
	)
	(segment
		(start 284.2768 -438.7088)
		(end 285.486348 -437.499252)
		(width 0.127)
		(layer "In6.Cu")
		(net "PRSNT_CABLE_GPU_A3_ISO_N")
	)
	(segment
		(start 286.455866 -427.106334)
		(end 291.561266 -427.106334)
		(width 0.127)
		(layer "In6.Cu")
		(net "PRSNT_CABLE_GPU_A3_ISO_N")
	)
	(segment
		(start 305.5874 -425.6786)
		(end 308.737 -428.8282)
		(width 0.127)
		(layer "In6.Cu")
		(net "PRSNT_CABLE_GPU_A3_ISO_N")
	)
	(segment
		(start 303.9618 -402.4376)
		(end 351.917 -402.4376)
		(width 0.127)
		(layer "In6.Cu")
		(net "PRSNT_CABLE_GPU_A3_ISO_N")
	)
	(segment
		(start 285.486348 -428.075852)
		(end 286.455866 -427.106334)
		(width 0.127)
		(layer "In6.Cu")
		(net "PRSNT_CABLE_GPU_A3_ISO_N")
	)
	(segment
		(start 304.7238 -415.4932)
		(end 302.9966 -413.766)
		(width 0.127)
		(layer "In6.Cu")
		(net "PRSNT_CABLE_GPU_A3_ISO_N")
	)
	(segment
		(start 302.9966 -413.766)
		(end 302.9966 -403.4028)
		(width 0.127)
		(layer "In6.Cu")
		(net "PRSNT_CABLE_GPU_A3_ISO_N")
	)
	(segment
		(start 26.6192 -425.3484)
		(end 23.5966 -425.3484)
		(width 0.127)
		(layer "In11.Cu")
		(net "PRSNT_CABLE_GPU_A3_ISO_N")
	)
	(segment
		(start 16.49095 -426.53585)
		(end 14.81455 -426.53585)
		(width 0.127)
		(layer "In11.Cu")
		(net "PRSNT_CABLE_GPU_A3_ISO_N")
	)
	(segment
		(start 29.3116 -409.4226)
		(end 27.4066 -411.3276)
		(width 0.127)
		(layer "In11.Cu")
		(net "PRSNT_CABLE_GPU_A3_ISO_N")
	)
	(segment
		(start 47.5234 -396.0622)
		(end 45.3898 -398.1958)
		(width 0.127)
		(layer "In11.Cu")
		(net "PRSNT_CABLE_GPU_A3_ISO_N")
	)
	(segment
		(start 42.291 -404.7998)
		(end 37.6682 -409.4226)
		(width 0.127)
		(layer "In11.Cu")
		(net "PRSNT_CABLE_GPU_A3_ISO_N")
	)
	(segment
		(start 45.3898 -398.1958)
		(end 45.3898 -402.961094)
		(width 0.127)
		(layer "In11.Cu")
		(net "PRSNT_CABLE_GPU_A3_ISO_N")
	)
	(segment
		(start 43.551094 -404.7998)
		(end 42.291 -404.7998)
		(width 0.127)
		(layer "In11.Cu")
		(net "PRSNT_CABLE_GPU_A3_ISO_N")
	)
	(segment
		(start 22.7076 -426.2374)
		(end 20.4978 -426.2374)
		(width 0.127)
		(layer "In11.Cu")
		(net "PRSNT_CABLE_GPU_A3_ISO_N")
	)
	(segment
		(start 23.5966 -425.3484)
		(end 22.7076 -426.2374)
		(width 0.127)
		(layer "In11.Cu")
		(net "PRSNT_CABLE_GPU_A3_ISO_N")
	)
	(segment
		(start 27.4066 -411.3276)
		(end 27.4066 -424.561)
		(width 0.127)
		(layer "In11.Cu")
		(net "PRSNT_CABLE_GPU_A3_ISO_N")
	)
	(segment
		(start 20.4978 -426.2374)
		(end 20.0152 -425.7548)
		(width 0.127)
		(layer "In11.Cu")
		(net "PRSNT_CABLE_GPU_A3_ISO_N")
	)
	(segment
		(start 45.3898 -402.961094)
		(end 43.551094 -404.7998)
		(width 0.127)
		(layer "In11.Cu")
		(net "PRSNT_CABLE_GPU_A3_ISO_N")
	)
	(segment
		(start 98.171 -393.9032)
		(end 96.012 -396.0622)
		(width 0.127)
		(layer "In11.Cu")
		(net "PRSNT_CABLE_GPU_A3_ISO_N")
	)
	(segment
		(start 20.0152 -425.7548)
		(end 17.272 -425.7548)
		(width 0.127)
		(layer "In11.Cu")
		(net "PRSNT_CABLE_GPU_A3_ISO_N")
	)
	(segment
		(start 27.4066 -424.561)
		(end 26.6192 -425.3484)
		(width 0.127)
		(layer "In11.Cu")
		(net "PRSNT_CABLE_GPU_A3_ISO_N")
	)
	(segment
		(start 98.171 -392.5824)
		(end 98.171 -393.9032)
		(width 0.127)
		(layer "In11.Cu")
		(net "PRSNT_CABLE_GPU_A3_ISO_N")
	)
	(segment
		(start 17.272 -425.7548)
		(end 16.49095 -426.53585)
		(width 0.127)
		(layer "In11.Cu")
		(net "PRSNT_CABLE_GPU_A3_ISO_N")
	)
	(segment
		(start 96.9772 -391.3886)
		(end 98.171 -392.5824)
		(width 0.127)
		(layer "In11.Cu")
		(net "PRSNT_CABLE_GPU_A3_ISO_N")
	)
	(segment
		(start 37.6682 -409.4226)
		(end 29.3116 -409.4226)
		(width 0.127)
		(layer "In11.Cu")
		(net "PRSNT_CABLE_GPU_A3_ISO_N")
	)
	(segment
		(start 96.012 -396.0622)
		(end 47.5234 -396.0622)
		(width 0.127)
		(layer "In11.Cu")
		(net "PRSNT_CABLE_GPU_A3_ISO_N")
	)
	(segment
		(start 96.9772 -391.0584)
		(end 96.9772 -391.3886)
		(width 0.127)
		(layer "In11.Cu")
		(net "PRSNT_CABLE_GPU_A3_ISO_N")
	)
	(segment
		(start 282.054808 -439.990992)
		(end 283.337 -438.7088)
		(width 0.127)
		(layer "In13.Cu")
		(net "PRSNT_CABLE_GPU_A3_ISO_N")
	)
	(segment
		(start 283.337 -438.7088)
		(end 284.2768 -438.7088)
		(width 0.127)
		(layer "In13.Cu")
		(net "PRSNT_CABLE_GPU_A3_ISO_N")
	)
	(segment
		(start 169.786808 -411.127448)
		(end 169.786808 -413.915352)
		(width 0.127)
		(layer "In13.Cu")
		(net "PRSNT_CABLE_GPU_A3_ISO_N")
	)
	(segment
		(start 180.281072 -420.102792)
		(end 185.357008 -425.178728)
		(width 0.127)
		(layer "In13.Cu")
		(net "PRSNT_CABLE_GPU_A3_ISO_N")
	)
	(segment
		(start 169.786808 -413.915352)
		(end 172.911008 -417.039552)
		(width 0.127)
		(layer "In13.Cu")
		(net "PRSNT_CABLE_GPU_A3_ISO_N")
	)
	(segment
		(start 185.357008 -425.178728)
		(end 185.357008 -426.005752)
		(width 0.127)
		(layer "In13.Cu")
		(net "PRSNT_CABLE_GPU_A3_ISO_N")
	)
	(segment
		(start 172.911008 -417.039552)
		(end 172.911008 -420.214552)
		(width 0.127)
		(layer "In13.Cu")
		(net "PRSNT_CABLE_GPU_A3_ISO_N")
	)
	(segment
		(start 177.060352 -420.102792)
		(end 180.281072 -420.102792)
		(width 0.127)
		(layer "In13.Cu")
		(net "PRSNT_CABLE_GPU_A3_ISO_N")
	)
	(segment
		(start 172.911008 -420.214552)
		(end 174.221648 -421.525192)
		(width 0.127)
		(layer "In13.Cu")
		(net "PRSNT_CABLE_GPU_A3_ISO_N")
	)
	(segment
		(start 170.472608 -410.441648)
		(end 169.786808 -411.127448)
		(width 0.127)
		(layer "In13.Cu")
		(net "PRSNT_CABLE_GPU_A3_ISO_N")
	)
	(segment
		(start 278.666448 -439.990992)
		(end 282.054808 -439.990992)
		(width 0.127)
		(layer "In13.Cu")
		(net "PRSNT_CABLE_GPU_A3_ISO_N")
	)
	(segment
		(start 175.637952 -421.525192)
		(end 177.060352 -420.102792)
		(width 0.127)
		(layer "In13.Cu")
		(net "PRSNT_CABLE_GPU_A3_ISO_N")
	)
	(segment
		(start 169.3418 -404.3426)
		(end 170.472608 -405.473408)
		(width 0.127)
		(layer "In13.Cu")
		(net "PRSNT_CABLE_GPU_A3_ISO_N")
	)
	(segment
		(start 198.173848 -438.822592)
		(end 277.498048 -438.822592)
		(width 0.127)
		(layer "In13.Cu")
		(net "PRSNT_CABLE_GPU_A3_ISO_N")
	)
	(segment
		(start 277.498048 -438.822592)
		(end 278.666448 -439.990992)
		(width 0.127)
		(layer "In13.Cu")
		(net "PRSNT_CABLE_GPU_A3_ISO_N")
	)
	(segment
		(start 185.357008 -426.005752)
		(end 198.173848 -438.822592)
		(width 0.127)
		(layer "In13.Cu")
		(net "PRSNT_CABLE_GPU_A3_ISO_N")
	)
	(segment
		(start 170.472608 -405.473408)
		(end 170.472608 -410.441648)
		(width 0.127)
		(layer "In13.Cu")
		(net "PRSNT_CABLE_GPU_A3_ISO_N")
	)
	(segment
		(start 174.221648 -421.525192)
		(end 175.637952 -421.525192)
		(width 0.127)
		(layer "In13.Cu")
		(net "PRSNT_CABLE_GPU_A3_ISO_N")
	)
	(segment
		(start 359.7148 -413.3088)
		(end 359.2576 -413.3088)
		(width 0.12954)
		(layer "F.Cu")
		(net "PRSNT_CABLE_GPU_A3")
	)
	(segment
		(start 360.49458 -412.9913)
		(end 360.0323 -412.9913)
		(width 0.12954)
		(layer "F.Cu")
		(net "PRSNT_CABLE_GPU_A3")
	)
	(segment
		(start 360.49458 -412.341314)
		(end 360.49458 -412.9913)
		(width 0.12954)
		(layer "F.Cu")
		(net "PRSNT_CABLE_GPU_A3")
	)
	(segment
		(start 359.1687 -413.2199)
		(end 359.1687 -412.0388)
		(width 0.12954)
		(layer "F.Cu")
		(net "PRSNT_CABLE_GPU_A3")
	)
	(segment
		(start 359.2576 -413.3088)
		(end 359.1687 -413.2199)
		(width 0.12954)
		(layer "F.Cu")
		(net "PRSNT_CABLE_GPU_A3")
	)
	(segment
		(start 360.0323 -412.9913)
		(end 359.7148 -413.3088)
		(width 0.12954)
		(layer "F.Cu")
		(net "PRSNT_CABLE_GPU_A3")
	)
	(via
		(at 359.2576 -413.3088)
		(size 0.762)
		(drill 0.381)
		(layers "F.Cu" "B.Cu")
		(net "PRSNT_CABLE_GPU_A3")
	)
	(segment
		(start 21.1582 -420.766748)
		(end 20.989798 -420.598346)
		(width 0.12954)
		(layer "F.Cu")
		(net "PRSNT_CABLE_GPU_A2_ISO_R1_N")
	)
	(segment
		(start 24.49195 -419.5572)
		(end 23.123652 -419.5572)
		(width 0.12954)
		(layer "F.Cu")
		(net "PRSNT_CABLE_GPU_A2_ISO_R1_N")
	)
	(segment
		(start 21.6408 -420.080948)
		(end 21.6408 -420.639748)
		(width 0.12954)
		(layer "F.Cu")
		(net "PRSNT_CABLE_GPU_A2_ISO_R1_N")
	)
	(segment
		(start 21.6408 -420.639748)
		(end 21.5138 -420.766748)
		(width 0.12954)
		(layer "F.Cu")
		(net "PRSNT_CABLE_GPU_A2_ISO_R1_N")
	)
	(segment
		(start 21.5138 -420.766748)
		(end 21.1582 -420.766748)
		(width 0.12954)
		(layer "F.Cu")
		(net "PRSNT_CABLE_GPU_A2_ISO_R1_N")
	)
	(segment
		(start 20.989798 -420.598346)
		(end 20.989798 -420.12743)
		(width 0.12954)
		(layer "F.Cu")
		(net "PRSNT_CABLE_GPU_A2_ISO_R1_N")
	)
	(segment
		(start 22.4028 -419.318948)
		(end 21.6408 -420.080948)
		(width 0.12954)
		(layer "F.Cu")
		(net "PRSNT_CABLE_GPU_A2_ISO_R1_N")
	)
	(segment
		(start 23.123652 -419.5572)
		(end 22.8854 -419.318948)
		(width 0.12954)
		(layer "F.Cu")
		(net "PRSNT_CABLE_GPU_A2_ISO_R1_N")
	)
	(segment
		(start 22.8854 -419.318948)
		(end 22.4028 -419.318948)
		(width 0.12954)
		(layer "F.Cu")
		(net "PRSNT_CABLE_GPU_A2_ISO_R1_N")
	)
	(via
		(at 22.8854 -419.318948)
		(size 0.762)
		(drill 0.381)
		(layers "F.Cu" "B.Cu")
		(net "PRSNT_CABLE_GPU_A2_ISO_R1_N")
	)
	(segment
		(start 33.110678 -419.5572)
		(end 29.7434 -419.5572)
		(width 0.12954)
		(layer "F.Cu")
		(net "PRSNT_CABLE_GPU_A2_ISO_N")
	)
	(segment
		(start 37.2872 -426.197522)
		(end 37.2872 -423.733722)
		(width 0.12954)
		(layer "F.Cu")
		(net "PRSNT_CABLE_GPU_A2_ISO_N")
	)
	(segment
		(start 93.4212 -426.8216)
		(end 91.6432 -425.0436)
		(width 0.12954)
		(layer "F.Cu")
		(net "PRSNT_CABLE_GPU_A2_ISO_N")
	)
	(segment
		(start 205.33741 -114.264948)
		(end 205.95844 -114.264948)
		(width 0.12954)
		(layer "F.Cu")
		(net "PRSNT_CABLE_GPU_A2_ISO_N")
	)
	(segment
		(start 91.6432 -420.8018)
		(end 88.7476 -417.9062)
		(width 0.12954)
		(layer "F.Cu")
		(net "PRSNT_CABLE_GPU_A2_ISO_N")
	)
	(segment
		(start 51.2572 -417.0172)
		(end 51.2572 -426.7454)
		(width 0.12954)
		(layer "F.Cu")
		(net "PRSNT_CABLE_GPU_A2_ISO_N")
	)
	(segment
		(start 306.213002 -431.37836)
		(end 306.521612 -431.06975)
		(width 0.12954)
		(layer "F.Cu")
		(net "PRSNT_CABLE_GPU_A2_ISO_N")
	)
	(segment
		(start 306.83454 -433.987702)
		(end 306.83454 -433.45735)
		(width 0.12954)
		(layer "F.Cu")
		(net "PRSNT_CABLE_GPU_A2_ISO_N")
	)
	(segment
		(start 306.521612 -431.06975)
		(end 306.83454 -431.06975)
		(width 0.12954)
		(layer "F.Cu")
		(net "PRSNT_CABLE_GPU_A2_ISO_N")
	)
	(segment
		(start 39.384478 -431.3682)
		(end 38.6334 -430.617122)
		(width 0.12954)
		(layer "F.Cu")
		(net "PRSNT_CABLE_GPU_A2_ISO_N")
	)
	(segment
		(start 306.62372 -428.86249)
		(end 306.62372 -428.16272)
		(width 0.12954)
		(layer "F.Cu")
		(net "PRSNT_CABLE_GPU_A2_ISO_N")
	)
	(segment
		(start 93.8022 -426.8216)
		(end 93.4212 -426.8216)
		(width 0.12954)
		(layer "F.Cu")
		(net "PRSNT_CABLE_GPU_A2_ISO_N")
	)
	(segment
		(start 47.5996 -430.403)
		(end 41.4528 -430.403)
		(width 0.12954)
		(layer "F.Cu")
		(net "PRSNT_CABLE_GPU_A2_ISO_N")
	)
	(segment
		(start 91.6432 -425.0436)
		(end 91.6432 -420.8018)
		(width 0.12954)
		(layer "F.Cu")
		(net "PRSNT_CABLE_GPU_A2_ISO_N")
	)
	(segment
		(start 307.10505 -428.86249)
		(end 306.62372 -428.86249)
		(width 0.12954)
		(layer "F.Cu")
		(net "PRSNT_CABLE_GPU_A2_ISO_N")
	)
	(segment
		(start 38.6334 -430.617122)
		(end 38.6334 -427.543722)
		(width 0.12954)
		(layer "F.Cu")
		(net "PRSNT_CABLE_GPU_A2_ISO_N")
	)
	(segment
		(start 51.2572 -426.7454)
		(end 47.5996 -430.403)
		(width 0.12954)
		(layer "F.Cu")
		(net "PRSNT_CABLE_GPU_A2_ISO_N")
	)
	(segment
		(start 306.83454 -433.45735)
		(end 306.213002 -432.835812)
		(width 0.12954)
		(layer "F.Cu")
		(net "PRSNT_CABLE_GPU_A2_ISO_N")
	)
	(segment
		(start 40.4876 -431.3682)
		(end 39.384478 -431.3682)
		(width 0.12954)
		(layer "F.Cu")
		(net "PRSNT_CABLE_GPU_A2_ISO_N")
	)
	(segment
		(start 29.7434 -419.5572)
		(end 25.29205 -419.5572)
		(width 0.12954)
		(layer "F.Cu")
		(net "PRSNT_CABLE_GPU_A2_ISO_N")
	)
	(segment
		(start 307.39461 -430.50968)
		(end 307.39461 -429.15205)
		(width 0.12954)
		(layer "F.Cu")
		(net "PRSNT_CABLE_GPU_A2_ISO_N")
	)
	(segment
		(start 306.570126 -434.69814)
		(end 306.570126 -434.252116)
		(width 0.12954)
		(layer "F.Cu")
		(net "PRSNT_CABLE_GPU_A2_ISO_N")
	)
	(segment
		(start 306.213002 -432.835812)
		(end 306.213002 -431.37836)
		(width 0.12954)
		(layer "F.Cu")
		(net "PRSNT_CABLE_GPU_A2_ISO_N")
	)
	(segment
		(start 41.4528 -430.403)
		(end 40.4876 -431.3682)
		(width 0.12954)
		(layer "F.Cu")
		(net "PRSNT_CABLE_GPU_A2_ISO_N")
	)
	(segment
		(start 88.7476 -417.9062)
		(end 77.546962 -417.9062)
		(width 0.12954)
		(layer "F.Cu")
		(net "PRSNT_CABLE_GPU_A2_ISO_N")
	)
	(segment
		(start 54.5592 -414.8836)
		(end 53.3908 -414.8836)
		(width 0.12954)
		(layer "F.Cu")
		(net "PRSNT_CABLE_GPU_A2_ISO_N")
	)
	(segment
		(start 306.570126 -434.252116)
		(end 306.83454 -433.987702)
		(width 0.12954)
		(layer "F.Cu")
		(net "PRSNT_CABLE_GPU_A2_ISO_N")
	)
	(segment
		(start 38.6334 -427.543722)
		(end 37.2872 -426.197522)
		(width 0.12954)
		(layer "F.Cu")
		(net "PRSNT_CABLE_GPU_A2_ISO_N")
	)
	(segment
		(start 307.39461 -429.15205)
		(end 307.10505 -428.86249)
		(width 0.12954)
		(layer "F.Cu")
		(net "PRSNT_CABLE_GPU_A2_ISO_N")
	)
	(segment
		(start 53.3908 -414.8836)
		(end 51.2572 -417.0172)
		(width 0.12954)
		(layer "F.Cu")
		(net "PRSNT_CABLE_GPU_A2_ISO_N")
	)
	(segment
		(start 72.974962 -413.3342)
		(end 56.1086 -413.3342)
		(width 0.12954)
		(layer "F.Cu")
		(net "PRSNT_CABLE_GPU_A2_ISO_N")
	)
	(segment
		(start 77.546962 -417.9062)
		(end 72.974962 -413.3342)
		(width 0.12954)
		(layer "F.Cu")
		(net "PRSNT_CABLE_GPU_A2_ISO_N")
	)
	(segment
		(start 56.1086 -413.3342)
		(end 54.5592 -414.8836)
		(width 0.12954)
		(layer "F.Cu")
		(net "PRSNT_CABLE_GPU_A2_ISO_N")
	)
	(segment
		(start 306.83454 -431.06975)
		(end 307.39461 -430.50968)
		(width 0.12954)
		(layer "F.Cu")
		(net "PRSNT_CABLE_GPU_A2_ISO_N")
	)
	(segment
		(start 37.2872 -423.733722)
		(end 33.110678 -419.5572)
		(width 0.12954)
		(layer "F.Cu")
		(net "PRSNT_CABLE_GPU_A2_ISO_N")
	)
	(via
		(at 211.35086 -339.562948)
		(size 0.508)
		(drill 0.254)
		(layers "F.Cu" "B.Cu")
		(net "PRSNT_CABLE_GPU_A2_ISO_N")
	)
	(via
		(at 306.62372 -428.16272)
		(size 0.508)
		(drill 0.254)
		(layers "F.Cu" "B.Cu")
		(net "PRSNT_CABLE_GPU_A2_ISO_N")
	)
	(via
		(at 93.8022 -426.8216)
		(size 0.508)
		(drill 0.254)
		(layers "F.Cu" "B.Cu")
		(net "PRSNT_CABLE_GPU_A2_ISO_N")
	)
	(via
		(at 205.95844 -114.264948)
		(size 0.508)
		(drill 0.254)
		(layers "F.Cu" "B.Cu")
		(net "PRSNT_CABLE_GPU_A2_ISO_N")
	)
	(via
		(at 29.7434 -419.5572)
		(size 0.762)
		(drill 0.381)
		(layers "F.Cu" "B.Cu")
		(net "PRSNT_CABLE_GPU_A2_ISO_N")
	)
	(via
		(at 172.4406 -403.8092)
		(size 0.508)
		(drill 0.254)
		(layers "F.Cu" "B.Cu")
		(net "PRSNT_CABLE_GPU_A2_ISO_N")
	)
	(via
		(at 306.213002 -431.37836)
		(size 0.508)
		(drill 0.254)
		(layers "F.Cu" "B.Cu")
		(net "PRSNT_CABLE_GPU_A2_ISO_N")
	)
	(segment
		(start 287.144206 -405.31161)
		(end 286.053022 -404.220426)
		(width 0.12954)
		(layer "B.Cu")
		(net "PRSNT_CABLE_GPU_A2_ISO_N")
	)
	(segment
		(start 310.46166 -429.88992)
		(end 310.46166 -428.308262)
		(width 0.12954)
		(layer "B.Cu")
		(net "PRSNT_CABLE_GPU_A2_ISO_N")
	)
	(segment
		(start 306.845462 -430.7459)
		(end 309.60568 -430.7459)
		(width 0.12954)
		(layer "B.Cu")
		(net "PRSNT_CABLE_GPU_A2_ISO_N")
	)
	(segment
		(start 310.46166 -428.308262)
		(end 309.22468 -427.071282)
		(width 0.12954)
		(layer "B.Cu")
		(net "PRSNT_CABLE_GPU_A2_ISO_N")
	)
	(segment
		(start 280.29281 -384.65125)
		(end 267.54074 -371.89918)
		(width 0.12954)
		(layer "B.Cu")
		(net "PRSNT_CABLE_GPU_A2_ISO_N")
	)
	(segment
		(start 286.053022 -404.220426)
		(end 286.053022 -395.628368)
		(width 0.12954)
		(layer "B.Cu")
		(net "PRSNT_CABLE_GPU_A2_ISO_N")
	)
	(segment
		(start 285.062422 -394.637768)
		(end 285.062422 -386.870702)
		(width 0.12954)
		(layer "B.Cu")
		(net "PRSNT_CABLE_GPU_A2_ISO_N")
	)
	(segment
		(start 296.147998 -405.31161)
		(end 287.144206 -405.31161)
		(width 0.12954)
		(layer "B.Cu")
		(net "PRSNT_CABLE_GPU_A2_ISO_N")
	)
	(segment
		(start 309.22468 -427.071282)
		(end 309.22468 -421.37584)
		(width 0.12954)
		(layer "B.Cu")
		(net "PRSNT_CABLE_GPU_A2_ISO_N")
	)
	(segment
		(start 253.564644 -351.455228)
		(end 241.672364 -339.562948)
		(width 0.12954)
		(layer "B.Cu")
		(net "PRSNT_CABLE_GPU_A2_ISO_N")
	)
	(segment
		(start 309.60568 -430.7459)
		(end 310.46166 -429.88992)
		(width 0.12954)
		(layer "B.Cu")
		(net "PRSNT_CABLE_GPU_A2_ISO_N")
	)
	(segment
		(start 241.672364 -339.562948)
		(end 211.35086 -339.562948)
		(width 0.12954)
		(layer "B.Cu")
		(net "PRSNT_CABLE_GPU_A2_ISO_N")
	)
	(segment
		(start 309.22468 -421.37584)
		(end 303.35474 -415.5059)
		(width 0.12954)
		(layer "B.Cu")
		(net "PRSNT_CABLE_GPU_A2_ISO_N")
	)
	(segment
		(start 299.7962 -414.74644)
		(end 299.7962 -410.001974)
		(width 0.12954)
		(layer "B.Cu")
		(net "PRSNT_CABLE_GPU_A2_ISO_N")
	)
	(segment
		(start 303.35474 -415.5059)
		(end 300.55566 -415.5059)
		(width 0.12954)
		(layer "B.Cu")
		(net "PRSNT_CABLE_GPU_A2_ISO_N")
	)
	(segment
		(start 299.7962 -410.001974)
		(end 297.643042 -407.848816)
		(width 0.12954)
		(layer "B.Cu")
		(net "PRSNT_CABLE_GPU_A2_ISO_N")
	)
	(segment
		(start 285.062422 -386.870702)
		(end 282.84297 -384.65125)
		(width 0.12954)
		(layer "B.Cu")
		(net "PRSNT_CABLE_GPU_A2_ISO_N")
	)
	(segment
		(start 306.213002 -431.37836)
		(end 306.845462 -430.7459)
		(width 0.12954)
		(layer "B.Cu")
		(net "PRSNT_CABLE_GPU_A2_ISO_N")
	)
	(segment
		(start 297.643042 -407.848816)
		(end 297.643042 -406.806654)
		(width 0.12954)
		(layer "B.Cu")
		(net "PRSNT_CABLE_GPU_A2_ISO_N")
	)
	(segment
		(start 267.54074 -371.89918)
		(end 267.54074 -357.681784)
		(width 0.12954)
		(layer "B.Cu")
		(net "PRSNT_CABLE_GPU_A2_ISO_N")
	)
	(segment
		(start 282.84297 -384.65125)
		(end 280.29281 -384.65125)
		(width 0.12954)
		(layer "B.Cu")
		(net "PRSNT_CABLE_GPU_A2_ISO_N")
	)
	(segment
		(start 297.643042 -406.806654)
		(end 296.147998 -405.31161)
		(width 0.12954)
		(layer "B.Cu")
		(net "PRSNT_CABLE_GPU_A2_ISO_N")
	)
	(segment
		(start 300.55566 -415.5059)
		(end 299.7962 -414.74644)
		(width 0.12954)
		(layer "B.Cu")
		(net "PRSNT_CABLE_GPU_A2_ISO_N")
	)
	(segment
		(start 261.314184 -351.455228)
		(end 253.564644 -351.455228)
		(width 0.12954)
		(layer "B.Cu")
		(net "PRSNT_CABLE_GPU_A2_ISO_N")
	)
	(segment
		(start 286.053022 -395.628368)
		(end 285.062422 -394.637768)
		(width 0.12954)
		(layer "B.Cu")
		(net "PRSNT_CABLE_GPU_A2_ISO_N")
	)
	(segment
		(start 267.54074 -357.681784)
		(end 261.314184 -351.455228)
		(width 0.12954)
		(layer "B.Cu")
		(net "PRSNT_CABLE_GPU_A2_ISO_N")
	)
	(segment
		(start 224.62998 -190.55207)
		(end 224.62998 -216.572846)
		(width 0.127)
		(layer "In2.Cu")
		(net "PRSNT_CABLE_GPU_A2_ISO_N")
	)
	(segment
		(start 209.677 -115.5446)
		(end 209.677 -117.105176)
		(width 0.127)
		(layer "In2.Cu")
		(net "PRSNT_CABLE_GPU_A2_ISO_N")
	)
	(segment
		(start 221.996 -329.779122)
		(end 212.212174 -339.562948)
		(width 0.127)
		(layer "In2.Cu")
		(net "PRSNT_CABLE_GPU_A2_ISO_N")
	)
	(segment
		(start 212.34146 -137.10539)
		(end 222.84436 -147.60829)
		(width 0.127)
		(layer "In2.Cu")
		(net "PRSNT_CABLE_GPU_A2_ISO_N")
	)
	(segment
		(start 207.2132 -113.9952)
		(end 208.1276 -113.9952)
		(width 0.127)
		(layer "In2.Cu")
		(net "PRSNT_CABLE_GPU_A2_ISO_N")
	)
	(segment
		(start 222.84436 -147.60829)
		(end 222.84436 -188.76645)
		(width 0.127)
		(layer "In2.Cu")
		(net "PRSNT_CABLE_GPU_A2_ISO_N")
	)
	(segment
		(start 212.34146 -119.769636)
		(end 212.34146 -128.519428)
		(width 0.127)
		(layer "In2.Cu")
		(net "PRSNT_CABLE_GPU_A2_ISO_N")
	)
	(segment
		(start 212.34146 -132.41274)
		(end 212.34146 -137.10539)
		(width 0.127)
		(layer "In2.Cu")
		(net "PRSNT_CABLE_GPU_A2_ISO_N")
	)
	(segment
		(start 212.212174 -339.562948)
		(end 211.35086 -339.562948)
		(width 0.127)
		(layer "In2.Cu")
		(net "PRSNT_CABLE_GPU_A2_ISO_N")
	)
	(segment
		(start 213.0933 -129.271268)
		(end 213.0933 -131.6609)
		(width 0.127)
		(layer "In2.Cu")
		(net "PRSNT_CABLE_GPU_A2_ISO_N")
	)
	(segment
		(start 212.34146 -128.519428)
		(end 213.0933 -129.271268)
		(width 0.127)
		(layer "In2.Cu")
		(net "PRSNT_CABLE_GPU_A2_ISO_N")
	)
	(segment
		(start 208.1276 -113.9952)
		(end 209.677 -115.5446)
		(width 0.127)
		(layer "In2.Cu")
		(net "PRSNT_CABLE_GPU_A2_ISO_N")
	)
	(segment
		(start 224.62998 -216.572846)
		(end 221.996 -219.206826)
		(width 0.127)
		(layer "In2.Cu")
		(net "PRSNT_CABLE_GPU_A2_ISO_N")
	)
	(segment
		(start 222.84436 -188.76645)
		(end 224.62998 -190.55207)
		(width 0.127)
		(layer "In2.Cu")
		(net "PRSNT_CABLE_GPU_A2_ISO_N")
	)
	(segment
		(start 205.95844 -114.264948)
		(end 206.943452 -114.264948)
		(width 0.127)
		(layer "In2.Cu")
		(net "PRSNT_CABLE_GPU_A2_ISO_N")
	)
	(segment
		(start 206.943452 -114.264948)
		(end 207.2132 -113.9952)
		(width 0.127)
		(layer "In2.Cu")
		(net "PRSNT_CABLE_GPU_A2_ISO_N")
	)
	(segment
		(start 221.996 -219.206826)
		(end 221.996 -329.779122)
		(width 0.127)
		(layer "In2.Cu")
		(net "PRSNT_CABLE_GPU_A2_ISO_N")
	)
	(segment
		(start 213.0933 -131.6609)
		(end 212.34146 -132.41274)
		(width 0.127)
		(layer "In2.Cu")
		(net "PRSNT_CABLE_GPU_A2_ISO_N")
	)
	(segment
		(start 209.677 -117.105176)
		(end 212.34146 -119.769636)
		(width 0.127)
		(layer "In2.Cu")
		(net "PRSNT_CABLE_GPU_A2_ISO_N")
	)
	(segment
		(start 277.354284 -387.951218)
		(end 281.694382 -392.291316)
		(width 0.127)
		(layer "In4.Cu")
		(net "PRSNT_CABLE_GPU_A2_ISO_N")
	)
	(segment
		(start 304.2158 -427.355)
		(end 305.02352 -428.16272)
		(width 0.127)
		(layer "In4.Cu")
		(net "PRSNT_CABLE_GPU_A2_ISO_N")
	)
	(segment
		(start 263.940544 -385.580636)
		(end 267.54709 -385.580636)
		(width 0.127)
		(layer "In4.Cu")
		(net "PRSNT_CABLE_GPU_A2_ISO_N")
	)
	(segment
		(start 281.694382 -394.704316)
		(end 285.794704 -398.804638)
		(width 0.127)
		(layer "In4.Cu")
		(net "PRSNT_CABLE_GPU_A2_ISO_N")
	)
	(segment
		(start 285.794704 -398.804638)
		(end 293.445438 -398.804638)
		(width 0.127)
		(layer "In4.Cu")
		(net "PRSNT_CABLE_GPU_A2_ISO_N")
	)
	(segment
		(start 177.529236 -388.4676)
		(end 183.853836 -382.143)
		(width 0.127)
		(layer "In4.Cu")
		(net "PRSNT_CABLE_GPU_A2_ISO_N")
	)
	(segment
		(start 294.259 -418.8714)
		(end 303.403 -418.8714)
		(width 0.127)
		(layer "In4.Cu")
		(net "PRSNT_CABLE_GPU_A2_ISO_N")
	)
	(segment
		(start 291.0078 -415.6202)
		(end 294.259 -418.8714)
		(width 0.127)
		(layer "In4.Cu")
		(net "PRSNT_CABLE_GPU_A2_ISO_N")
	)
	(segment
		(start 174.1678 -402.7424)
		(end 174.1678 -398.907)
		(width 0.127)
		(layer "In4.Cu")
		(net "PRSNT_CABLE_GPU_A2_ISO_N")
	)
	(segment
		(start 294.006778 -399.365978)
		(end 294.006778 -407.668222)
		(width 0.127)
		(layer "In4.Cu")
		(net "PRSNT_CABLE_GPU_A2_ISO_N")
	)
	(segment
		(start 173.101 -403.8092)
		(end 174.1678 -402.7424)
		(width 0.127)
		(layer "In4.Cu")
		(net "PRSNT_CABLE_GPU_A2_ISO_N")
	)
	(segment
		(start 305.0794 -423.9768)
		(end 304.2158 -424.8404)
		(width 0.127)
		(layer "In4.Cu")
		(net "PRSNT_CABLE_GPU_A2_ISO_N")
	)
	(segment
		(start 293.445438 -398.804638)
		(end 294.006778 -399.365978)
		(width 0.127)
		(layer "In4.Cu")
		(net "PRSNT_CABLE_GPU_A2_ISO_N")
	)
	(segment
		(start 305.0794 -420.5478)
		(end 305.0794 -423.9768)
		(width 0.127)
		(layer "In4.Cu")
		(net "PRSNT_CABLE_GPU_A2_ISO_N")
	)
	(segment
		(start 183.853836 -382.143)
		(end 260.502908 -382.143)
		(width 0.127)
		(layer "In4.Cu")
		(net "PRSNT_CABLE_GPU_A2_ISO_N")
	)
	(segment
		(start 281.4574 -415.1122)
		(end 281.9654 -415.6202)
		(width 0.127)
		(layer "In4.Cu")
		(net "PRSNT_CABLE_GPU_A2_ISO_N")
	)
	(segment
		(start 172.4406 -403.8092)
		(end 173.101 -403.8092)
		(width 0.127)
		(layer "In4.Cu")
		(net "PRSNT_CABLE_GPU_A2_ISO_N")
	)
	(segment
		(start 292.2524 -409.4226)
		(end 282.448 -409.4226)
		(width 0.127)
		(layer "In4.Cu")
		(net "PRSNT_CABLE_GPU_A2_ISO_N")
	)
	(segment
		(start 282.448 -409.4226)
		(end 281.4574 -410.4132)
		(width 0.127)
		(layer "In4.Cu")
		(net "PRSNT_CABLE_GPU_A2_ISO_N")
	)
	(segment
		(start 281.9654 -415.6202)
		(end 291.0078 -415.6202)
		(width 0.127)
		(layer "In4.Cu")
		(net "PRSNT_CABLE_GPU_A2_ISO_N")
	)
	(segment
		(start 294.006778 -407.668222)
		(end 292.2524 -409.4226)
		(width 0.127)
		(layer "In4.Cu")
		(net "PRSNT_CABLE_GPU_A2_ISO_N")
	)
	(segment
		(start 305.02352 -428.16272)
		(end 306.62372 -428.16272)
		(width 0.127)
		(layer "In4.Cu")
		(net "PRSNT_CABLE_GPU_A2_ISO_N")
	)
	(segment
		(start 269.917672 -387.951218)
		(end 277.354284 -387.951218)
		(width 0.127)
		(layer "In4.Cu")
		(net "PRSNT_CABLE_GPU_A2_ISO_N")
	)
	(segment
		(start 267.54709 -385.580636)
		(end 269.917672 -387.951218)
		(width 0.127)
		(layer "In4.Cu")
		(net "PRSNT_CABLE_GPU_A2_ISO_N")
	)
	(segment
		(start 260.502908 -382.143)
		(end 263.940544 -385.580636)
		(width 0.127)
		(layer "In4.Cu")
		(net "PRSNT_CABLE_GPU_A2_ISO_N")
	)
	(segment
		(start 281.694382 -392.291316)
		(end 281.694382 -394.704316)
		(width 0.127)
		(layer "In4.Cu")
		(net "PRSNT_CABLE_GPU_A2_ISO_N")
	)
	(segment
		(start 174.1678 -398.907)
		(end 177.529236 -395.545564)
		(width 0.127)
		(layer "In4.Cu")
		(net "PRSNT_CABLE_GPU_A2_ISO_N")
	)
	(segment
		(start 303.403 -418.8714)
		(end 305.0794 -420.5478)
		(width 0.127)
		(layer "In4.Cu")
		(net "PRSNT_CABLE_GPU_A2_ISO_N")
	)
	(segment
		(start 281.4574 -410.4132)
		(end 281.4574 -415.1122)
		(width 0.127)
		(layer "In4.Cu")
		(net "PRSNT_CABLE_GPU_A2_ISO_N")
	)
	(segment
		(start 177.529236 -395.545564)
		(end 177.529236 -388.4676)
		(width 0.127)
		(layer "In4.Cu")
		(net "PRSNT_CABLE_GPU_A2_ISO_N")
	)
	(segment
		(start 304.2158 -424.8404)
		(end 304.2158 -427.355)
		(width 0.127)
		(layer "In4.Cu")
		(net "PRSNT_CABLE_GPU_A2_ISO_N")
	)
	(segment
		(start 168.9354 -408.1018)
		(end 120.2944 -408.1018)
		(width 0.127)
		(layer "In6.Cu")
		(net "PRSNT_CABLE_GPU_A2_ISO_N")
	)
	(segment
		(start 107.5182 -424.8912)
		(end 106.5276 -425.8818)
		(width 0.127)
		(layer "In6.Cu")
		(net "PRSNT_CABLE_GPU_A2_ISO_N")
	)
	(segment
		(start 96.2914 -425.8818)
		(end 95.3516 -426.8216)
		(width 0.127)
		(layer "In6.Cu")
		(net "PRSNT_CABLE_GPU_A2_ISO_N")
	)
	(segment
		(start 120.2944 -408.1018)
		(end 118.6942 -409.702)
		(width 0.127)
		(layer "In6.Cu")
		(net "PRSNT_CABLE_GPU_A2_ISO_N")
	)
	(segment
		(start 114.3 -419.9636)
		(end 112.8014 -418.465)
		(width 0.127)
		(layer "In6.Cu")
		(net "PRSNT_CABLE_GPU_A2_ISO_N")
	)
	(segment
		(start 169.9006 -404.7236)
		(end 169.9006 -407.1366)
		(width 0.127)
		(layer "In6.Cu")
		(net "PRSNT_CABLE_GPU_A2_ISO_N")
	)
	(segment
		(start 172.4406 -403.8092)
		(end 170.815 -403.8092)
		(width 0.127)
		(layer "In6.Cu")
		(net "PRSNT_CABLE_GPU_A2_ISO_N")
	)
	(segment
		(start 106.5276 -425.8818)
		(end 96.2914 -425.8818)
		(width 0.127)
		(layer "In6.Cu")
		(net "PRSNT_CABLE_GPU_A2_ISO_N")
	)
	(segment
		(start 118.6942 -409.702)
		(end 118.6942 -417.449)
		(width 0.127)
		(layer "In6.Cu")
		(net "PRSNT_CABLE_GPU_A2_ISO_N")
	)
	(segment
		(start 95.3516 -426.8216)
		(end 93.8022 -426.8216)
		(width 0.127)
		(layer "In6.Cu")
		(net "PRSNT_CABLE_GPU_A2_ISO_N")
	)
	(segment
		(start 118.6942 -417.449)
		(end 116.1796 -419.9636)
		(width 0.127)
		(layer "In6.Cu")
		(net "PRSNT_CABLE_GPU_A2_ISO_N")
	)
	(segment
		(start 169.9006 -407.1366)
		(end 168.9354 -408.1018)
		(width 0.127)
		(layer "In6.Cu")
		(net "PRSNT_CABLE_GPU_A2_ISO_N")
	)
	(segment
		(start 116.1796 -419.9636)
		(end 114.3 -419.9636)
		(width 0.127)
		(layer "In6.Cu")
		(net "PRSNT_CABLE_GPU_A2_ISO_N")
	)
	(segment
		(start 107.5182 -420.1922)
		(end 107.5182 -424.8912)
		(width 0.127)
		(layer "In6.Cu")
		(net "PRSNT_CABLE_GPU_A2_ISO_N")
	)
	(segment
		(start 109.2454 -418.465)
		(end 107.5182 -420.1922)
		(width 0.127)
		(layer "In6.Cu")
		(net "PRSNT_CABLE_GPU_A2_ISO_N")
	)
	(segment
		(start 112.8014 -418.465)
		(end 109.2454 -418.465)
		(width 0.127)
		(layer "In6.Cu")
		(net "PRSNT_CABLE_GPU_A2_ISO_N")
	)
	(segment
		(start 170.815 -403.8092)
		(end 169.9006 -404.7236)
		(width 0.127)
		(layer "In6.Cu")
		(net "PRSNT_CABLE_GPU_A2_ISO_N")
	)
	(segment
		(start 16.721582 -421.10406)
		(end 16.989806 -420.835836)
		(width 0.12954)
		(layer "F.Cu")
		(net "PRSNT_CABLE_GPU_A1_ISO_R1_N")
	)
	(segment
		(start 16.51 -425.297854)
		(end 16.51 -425.73575)
		(width 0.12954)
		(layer "F.Cu")
		(net "PRSNT_CABLE_GPU_A1_ISO_R1_N")
	)
	(segment
		(start 16.637 -423.353484)
		(end 16.637 -425.170854)
		(width 0.12954)
		(layer "F.Cu")
		(net "PRSNT_CABLE_GPU_A1_ISO_R1_N")
	)
	(segment
		(start 16.532352 -423.248836)
		(end 16.637 -423.353484)
		(width 0.12954)
		(layer "F.Cu")
		(net "PRSNT_CABLE_GPU_A1_ISO_R1_N")
	)
	(segment
		(start 16.637 -425.170854)
		(end 16.51 -425.297854)
		(width 0.12954)
		(layer "F.Cu")
		(net "PRSNT_CABLE_GPU_A1_ISO_R1_N")
	)
	(segment
		(start 16.989806 -420.835836)
		(end 16.989806 -420.12743)
		(width 0.12954)
		(layer "F.Cu")
		(net "PRSNT_CABLE_GPU_A1_ISO_R1_N")
	)
	(segment
		(start 16.532352 -423.248836)
		(end 16.721582 -423.059606)
		(width 0.12954)
		(layer "F.Cu")
		(net "PRSNT_CABLE_GPU_A1_ISO_R1_N")
	)
	(segment
		(start 16.721582 -423.059606)
		(end 16.721582 -421.10406)
		(width 0.12954)
		(layer "F.Cu")
		(net "PRSNT_CABLE_GPU_A1_ISO_R1_N")
	)
	(via
		(at 16.532352 -423.248836)
		(size 0.762)
		(drill 0.381)
		(layers "F.Cu" "B.Cu")
		(net "PRSNT_CABLE_GPU_A1_ISO_R1_N")
	)
	(segment
		(start 295.86682 -422.345612)
		(end 295.86682 -421.81526)
		(width 0.12954)
		(layer "F.Cu")
		(net "PRSNT_CABLE_GPU_A1_ISO_N")
	)
	(segment
		(start 295.245282 -419.73627)
		(end 295.553892 -419.42766)
		(width 0.12954)
		(layer "F.Cu")
		(net "PRSNT_CABLE_GPU_A1_ISO_N")
	)
	(segment
		(start 296.06367 -417.2204)
		(end 295.656 -417.2204)
		(width 0.12954)
		(layer "F.Cu")
		(net "PRSNT_CABLE_GPU_A1_ISO_N")
	)
	(segment
		(start 201.40041 -116.804948)
		(end 202.01128 -116.804948)
		(width 0.12954)
		(layer "F.Cu")
		(net "PRSNT_CABLE_GPU_A1_ISO_N")
	)
	(segment
		(start 296.42689 -418.86759)
		(end 296.42689 -417.58362)
		(width 0.12954)
		(layer "F.Cu")
		(net "PRSNT_CABLE_GPU_A1_ISO_N")
	)
	(segment
		(start 295.602406 -423.05605)
		(end 295.602406 -422.610026)
		(width 0.12954)
		(layer "F.Cu")
		(net "PRSNT_CABLE_GPU_A1_ISO_N")
	)
	(segment
		(start 295.783 -427.609)
		(end 296.164 -427.228)
		(width 0.12954)
		(layer "F.Cu")
		(net "PRSNT_CABLE_GPU_A1_ISO_N")
	)
	(segment
		(start 294.0558 -426.9994)
		(end 294.6654 -427.609)
		(width 0.12954)
		(layer "F.Cu")
		(net "PRSNT_CABLE_GPU_A1_ISO_N")
	)
	(segment
		(start 296.164 -427.228)
		(end 296.164 -424.0784)
		(width 0.12954)
		(layer "F.Cu")
		(net "PRSNT_CABLE_GPU_A1_ISO_N")
	)
	(segment
		(start 16.51 -426.53585)
		(end 16.51 -427.2026)
		(width 0.12954)
		(layer "F.Cu")
		(net "PRSNT_CABLE_GPU_A1_ISO_N")
	)
	(segment
		(start 294.6654 -427.609)
		(end 295.783 -427.609)
		(width 0.12954)
		(layer "F.Cu")
		(net "PRSNT_CABLE_GPU_A1_ISO_N")
	)
	(segment
		(start 295.553892 -419.42766)
		(end 295.86682 -419.42766)
		(width 0.12954)
		(layer "F.Cu")
		(net "PRSNT_CABLE_GPU_A1_ISO_N")
	)
	(segment
		(start 295.86682 -421.81526)
		(end 295.245282 -421.193722)
		(width 0.12954)
		(layer "F.Cu")
		(net "PRSNT_CABLE_GPU_A1_ISO_N")
	)
	(segment
		(start 296.164 -424.0784)
		(end 295.602406 -423.516806)
		(width 0.12954)
		(layer "F.Cu")
		(net "PRSNT_CABLE_GPU_A1_ISO_N")
	)
	(segment
		(start 295.86682 -419.42766)
		(end 296.42689 -418.86759)
		(width 0.12954)
		(layer "F.Cu")
		(net "PRSNT_CABLE_GPU_A1_ISO_N")
	)
	(segment
		(start 295.245282 -421.193722)
		(end 295.245282 -419.73627)
		(width 0.12954)
		(layer "F.Cu")
		(net "PRSNT_CABLE_GPU_A1_ISO_N")
	)
	(segment
		(start 296.42689 -417.58362)
		(end 296.06367 -417.2204)
		(width 0.12954)
		(layer "F.Cu")
		(net "PRSNT_CABLE_GPU_A1_ISO_N")
	)
	(segment
		(start 295.602406 -422.610026)
		(end 295.86682 -422.345612)
		(width 0.12954)
		(layer "F.Cu")
		(net "PRSNT_CABLE_GPU_A1_ISO_N")
	)
	(segment
		(start 295.602406 -423.516806)
		(end 295.602406 -423.05605)
		(width 0.12954)
		(layer "F.Cu")
		(net "PRSNT_CABLE_GPU_A1_ISO_N")
	)
	(via
		(at 209.82686 -337.657948)
		(size 0.508)
		(drill 0.254)
		(layers "F.Cu" "B.Cu")
		(net "PRSNT_CABLE_GPU_A1_ISO_N")
	)
	(via
		(at 97.8154 -391.0838)
		(size 0.508)
		(drill 0.254)
		(layers "F.Cu" "B.Cu")
		(net "PRSNT_CABLE_GPU_A1_ISO_N")
	)
	(via
		(at 169.3418 -405.257)
		(size 0.508)
		(drill 0.254)
		(layers "F.Cu" "B.Cu")
		(net "PRSNT_CABLE_GPU_A1_ISO_N")
	)
	(via
		(at 202.01128 -116.804948)
		(size 0.508)
		(drill 0.254)
		(layers "F.Cu" "B.Cu")
		(net "PRSNT_CABLE_GPU_A1_ISO_N")
	)
	(via
		(at 294.0558 -426.9994)
		(size 0.508)
		(drill 0.254)
		(layers "F.Cu" "B.Cu")
		(net "PRSNT_CABLE_GPU_A1_ISO_N")
	)
	(via
		(at 295.245282 -419.73627)
		(size 0.508)
		(drill 0.254)
		(layers "F.Cu" "B.Cu")
		(net "PRSNT_CABLE_GPU_A1_ISO_N")
	)
	(via
		(at 16.51 -427.2026)
		(size 0.508)
		(drill 0.254)
		(layers "F.Cu" "B.Cu")
		(net "PRSNT_CABLE_GPU_A1_ISO_N")
	)
	(via
		(at 284.2768 -439.4962)
		(size 0.508)
		(drill 0.254)
		(layers "F.Cu" "B.Cu")
		(net "PRSNT_CABLE_GPU_A1_ISO_N")
	)
	(segment
		(start 168.6306 -397.3068)
		(end 121.9454 -397.3068)
		(width 0.12954)
		(layer "B.Cu")
		(net "PRSNT_CABLE_GPU_A1_ISO_N")
	)
	(segment
		(start 293.259256 -417.983924)
		(end 288.82594 -413.550608)
		(width 0.12954)
		(layer "B.Cu")
		(net "PRSNT_CABLE_GPU_A1_ISO_N")
	)
	(segment
		(start 284.5054 -407.47315)
		(end 284.5054 -396.1892)
		(width 0.12954)
		(layer "B.Cu")
		(net "PRSNT_CABLE_GPU_A1_ISO_N")
	)
	(segment
		(start 278.33828 -385.80314)
		(end 264.72134 -372.1862)
		(width 0.12954)
		(layer "B.Cu")
		(net "PRSNT_CABLE_GPU_A1_ISO_N")
	)
	(segment
		(start 209.07502 -338.409788)
		(end 209.82686 -337.657948)
		(width 0.12954)
		(layer "B.Cu")
		(net "PRSNT_CABLE_GPU_A1_ISO_N")
	)
	(segment
		(start 284.5054 -396.1892)
		(end 283.225494 -394.909294)
		(width 0.12954)
		(layer "B.Cu")
		(net "PRSNT_CABLE_GPU_A1_ISO_N")
	)
	(segment
		(start 169.671746 -405.257)
		(end 171.0182 -403.910546)
		(width 0.12954)
		(layer "B.Cu")
		(net "PRSNT_CABLE_GPU_A1_ISO_N")
	)
	(segment
		(start 240.50752 -341.950548)
		(end 209.43316 -341.950548)
		(width 0.12954)
		(layer "B.Cu")
		(net "PRSNT_CABLE_GPU_A1_ISO_N")
	)
	(segment
		(start 288.82594 -411.79369)
		(end 284.5054 -407.47315)
		(width 0.12954)
		(layer "B.Cu")
		(net "PRSNT_CABLE_GPU_A1_ISO_N")
	)
	(segment
		(start 294.2336 -419.76548)
		(end 293.259256 -418.791136)
		(width 0.12954)
		(layer "B.Cu")
		(net "PRSNT_CABLE_GPU_A1_ISO_N")
	)
	(segment
		(start 288.82594 -413.550608)
		(end 288.82594 -411.79369)
		(width 0.12954)
		(layer "B.Cu")
		(net "PRSNT_CABLE_GPU_A1_ISO_N")
	)
	(segment
		(start 295.216072 -419.76548)
		(end 294.2336 -419.76548)
		(width 0.12954)
		(layer "B.Cu")
		(net "PRSNT_CABLE_GPU_A1_ISO_N")
	)
	(segment
		(start 264.72134 -372.1862)
		(end 264.72134 -358.341168)
		(width 0.12954)
		(layer "B.Cu")
		(net "PRSNT_CABLE_GPU_A1_ISO_N")
	)
	(segment
		(start 295.245282 -419.73627)
		(end 295.216072 -419.76548)
		(width 0.12954)
		(layer "B.Cu")
		(net "PRSNT_CABLE_GPU_A1_ISO_N")
	)
	(segment
		(start 283.225494 -394.909294)
		(end 283.225494 -391.3378)
		(width 0.12954)
		(layer "B.Cu")
		(net "PRSNT_CABLE_GPU_A1_ISO_N")
	)
	(segment
		(start 111.886746 -392.4808)
		(end 99.2124 -392.4808)
		(width 0.12954)
		(layer "B.Cu")
		(net "PRSNT_CABLE_GPU_A1_ISO_N")
	)
	(segment
		(start 171.0182 -399.6944)
		(end 168.6306 -397.3068)
		(width 0.12954)
		(layer "B.Cu")
		(net "PRSNT_CABLE_GPU_A1_ISO_N")
	)
	(segment
		(start 278.33828 -386.450586)
		(end 278.33828 -385.80314)
		(width 0.12954)
		(layer "B.Cu")
		(net "PRSNT_CABLE_GPU_A1_ISO_N")
	)
	(segment
		(start 260.22046 -353.840288)
		(end 252.39726 -353.840288)
		(width 0.12954)
		(layer "B.Cu")
		(net "PRSNT_CABLE_GPU_A1_ISO_N")
	)
	(segment
		(start 121.9454 -397.3068)
		(end 118.8212 -394.1826)
		(width 0.12954)
		(layer "B.Cu")
		(net "PRSNT_CABLE_GPU_A1_ISO_N")
	)
	(segment
		(start 112.826546 -393.4206)
		(end 111.886746 -392.4808)
		(width 0.12954)
		(layer "B.Cu")
		(net "PRSNT_CABLE_GPU_A1_ISO_N")
	)
	(segment
		(start 209.43316 -341.950548)
		(end 209.07502 -341.592408)
		(width 0.12954)
		(layer "B.Cu")
		(net "PRSNT_CABLE_GPU_A1_ISO_N")
	)
	(segment
		(start 99.2124 -392.4808)
		(end 97.8154 -391.0838)
		(width 0.12954)
		(layer "B.Cu")
		(net "PRSNT_CABLE_GPU_A1_ISO_N")
	)
	(segment
		(start 118.8212 -394.1826)
		(end 116.592096 -394.1826)
		(width 0.12954)
		(layer "B.Cu")
		(net "PRSNT_CABLE_GPU_A1_ISO_N")
	)
	(segment
		(start 115.830096 -393.4206)
		(end 112.826546 -393.4206)
		(width 0.12954)
		(layer "B.Cu")
		(net "PRSNT_CABLE_GPU_A1_ISO_N")
	)
	(segment
		(start 209.07502 -341.592408)
		(end 209.07502 -338.409788)
		(width 0.12954)
		(layer "B.Cu")
		(net "PRSNT_CABLE_GPU_A1_ISO_N")
	)
	(segment
		(start 293.259256 -418.791136)
		(end 293.259256 -417.983924)
		(width 0.12954)
		(layer "B.Cu")
		(net "PRSNT_CABLE_GPU_A1_ISO_N")
	)
	(segment
		(start 252.39726 -353.840288)
		(end 240.50752 -341.950548)
		(width 0.12954)
		(layer "B.Cu")
		(net "PRSNT_CABLE_GPU_A1_ISO_N")
	)
	(segment
		(start 171.0182 -403.910546)
		(end 171.0182 -399.6944)
		(width 0.12954)
		(layer "B.Cu")
		(net "PRSNT_CABLE_GPU_A1_ISO_N")
	)
	(segment
		(start 264.72134 -358.341168)
		(end 260.22046 -353.840288)
		(width 0.12954)
		(layer "B.Cu")
		(net "PRSNT_CABLE_GPU_A1_ISO_N")
	)
	(segment
		(start 116.592096 -394.1826)
		(end 115.830096 -393.4206)
		(width 0.12954)
		(layer "B.Cu")
		(net "PRSNT_CABLE_GPU_A1_ISO_N")
	)
	(segment
		(start 169.3418 -405.257)
		(end 169.671746 -405.257)
		(width 0.12954)
		(layer "B.Cu")
		(net "PRSNT_CABLE_GPU_A1_ISO_N")
	)
	(segment
		(start 283.225494 -391.3378)
		(end 278.33828 -386.450586)
		(width 0.12954)
		(layer "B.Cu")
		(net "PRSNT_CABLE_GPU_A1_ISO_N")
	)
	(segment
		(start 208.3816 -117.48643)
		(end 207.113378 -116.218208)
		(width 0.127)
		(layer "In2.Cu")
		(net "PRSNT_CABLE_GPU_A1_ISO_N")
	)
	(segment
		(start 220.5863 -328.937874)
		(end 220.5863 -218.622626)
		(width 0.127)
		(layer "In2.Cu")
		(net "PRSNT_CABLE_GPU_A1_ISO_N")
	)
	(segment
		(start 221.43466 -189.23635)
		(end 221.43466 -148.19249)
		(width 0.127)
		(layer "In2.Cu")
		(net "PRSNT_CABLE_GPU_A1_ISO_N")
	)
	(segment
		(start 223.22028 -191.02197)
		(end 221.43466 -189.23635)
		(width 0.127)
		(layer "In2.Cu")
		(net "PRSNT_CABLE_GPU_A1_ISO_N")
	)
	(segment
		(start 209.82686 -337.657948)
		(end 211.866226 -337.657948)
		(width 0.127)
		(layer "In2.Cu")
		(net "PRSNT_CABLE_GPU_A1_ISO_N")
	)
	(segment
		(start 203.0603 -116.804948)
		(end 202.01128 -116.804948)
		(width 0.127)
		(layer "In2.Cu")
		(net "PRSNT_CABLE_GPU_A1_ISO_N")
	)
	(segment
		(start 209.26298 -128.491488)
		(end 209.26298 -123.259088)
		(width 0.127)
		(layer "In2.Cu")
		(net "PRSNT_CABLE_GPU_A1_ISO_N")
	)
	(segment
		(start 211.866226 -337.657948)
		(end 220.5863 -328.937874)
		(width 0.127)
		(layer "In2.Cu")
		(net "PRSNT_CABLE_GPU_A1_ISO_N")
	)
	(segment
		(start 207.113378 -116.218208)
		(end 203.64704 -116.218208)
		(width 0.127)
		(layer "In2.Cu")
		(net "PRSNT_CABLE_GPU_A1_ISO_N")
	)
	(segment
		(start 208.3816 -122.377708)
		(end 208.3816 -117.48643)
		(width 0.127)
		(layer "In2.Cu")
		(net "PRSNT_CABLE_GPU_A1_ISO_N")
	)
	(segment
		(start 209.69478 -136.45261)
		(end 209.69478 -128.923288)
		(width 0.127)
		(layer "In2.Cu")
		(net "PRSNT_CABLE_GPU_A1_ISO_N")
	)
	(segment
		(start 221.43466 -148.19249)
		(end 209.69478 -136.45261)
		(width 0.127)
		(layer "In2.Cu")
		(net "PRSNT_CABLE_GPU_A1_ISO_N")
	)
	(segment
		(start 209.69478 -128.923288)
		(end 209.26298 -128.491488)
		(width 0.127)
		(layer "In2.Cu")
		(net "PRSNT_CABLE_GPU_A1_ISO_N")
	)
	(segment
		(start 209.26298 -123.259088)
		(end 208.3816 -122.377708)
		(width 0.127)
		(layer "In2.Cu")
		(net "PRSNT_CABLE_GPU_A1_ISO_N")
	)
	(segment
		(start 223.22028 -215.988646)
		(end 223.22028 -191.02197)
		(width 0.127)
		(layer "In2.Cu")
		(net "PRSNT_CABLE_GPU_A1_ISO_N")
	)
	(segment
		(start 203.64704 -116.218208)
		(end 203.0603 -116.804948)
		(width 0.127)
		(layer "In2.Cu")
		(net "PRSNT_CABLE_GPU_A1_ISO_N")
	)
	(segment
		(start 220.5863 -218.622626)
		(end 223.22028 -215.988646)
		(width 0.127)
		(layer "In2.Cu")
		(net "PRSNT_CABLE_GPU_A1_ISO_N")
	)
	(segment
		(start 283.6418 -439.4962)
		(end 284.2768 -439.4962)
		(width 0.127)
		(layer "In4.Cu")
		(net "PRSNT_CABLE_GPU_A1_ISO_N")
	)
	(segment
		(start 294.0558 -426.9994)
		(end 293.7256 -427.3296)
		(width 0.127)
		(layer "In4.Cu")
		(net "PRSNT_CABLE_GPU_A1_ISO_N")
	)
	(segment
		(start 284.879796 -428.326804)
		(end 284.879796 -436.632604)
		(width 0.127)
		(layer "In4.Cu")
		(net "PRSNT_CABLE_GPU_A1_ISO_N")
	)
	(segment
		(start 284.879796 -436.632604)
		(end 283.3878 -438.1246)
		(width 0.127)
		(layer "In4.Cu")
		(net "PRSNT_CABLE_GPU_A1_ISO_N")
	)
	(segment
		(start 283.3878 -438.1246)
		(end 283.3878 -439.2422)
		(width 0.127)
		(layer "In4.Cu")
		(net "PRSNT_CABLE_GPU_A1_ISO_N")
	)
	(segment
		(start 293.7256 -427.3296)
		(end 285.877 -427.3296)
		(width 0.127)
		(layer "In4.Cu")
		(net "PRSNT_CABLE_GPU_A1_ISO_N")
	)
	(segment
		(start 283.3878 -439.2422)
		(end 283.6418 -439.4962)
		(width 0.127)
		(layer "In4.Cu")
		(net "PRSNT_CABLE_GPU_A1_ISO_N")
	)
	(segment
		(start 285.877 -427.3296)
		(end 284.879796 -428.326804)
		(width 0.127)
		(layer "In4.Cu")
		(net "PRSNT_CABLE_GPU_A1_ISO_N")
	)
	(segment
		(start 21.082 -427.2026)
		(end 16.51 -427.2026)
		(width 0.127)
		(layer "In11.Cu")
		(net "PRSNT_CABLE_GPU_A1_ISO_N")
	)
	(segment
		(start 38.050216 -409.853638)
		(end 29.490162 -409.853638)
		(width 0.127)
		(layer "In11.Cu")
		(net "PRSNT_CABLE_GPU_A1_ISO_N")
	)
	(segment
		(start 27.9146 -425.577)
		(end 26.7716 -426.72)
		(width 0.127)
		(layer "In11.Cu")
		(net "PRSNT_CABLE_GPU_A1_ISO_N")
	)
	(segment
		(start 45.7962 -403.4028)
		(end 43.7896 -405.4094)
		(width 0.127)
		(layer "In11.Cu")
		(net "PRSNT_CABLE_GPU_A1_ISO_N")
	)
	(segment
		(start 97.8154 -391.541)
		(end 98.5774 -392.303)
		(width 0.127)
		(layer "In11.Cu")
		(net "PRSNT_CABLE_GPU_A1_ISO_N")
	)
	(segment
		(start 26.7716 -426.72)
		(end 21.5646 -426.72)
		(width 0.127)
		(layer "In11.Cu")
		(net "PRSNT_CABLE_GPU_A1_ISO_N")
	)
	(segment
		(start 98.5774 -392.303)
		(end 98.5774 -394.1064)
		(width 0.127)
		(layer "In11.Cu")
		(net "PRSNT_CABLE_GPU_A1_ISO_N")
	)
	(segment
		(start 97.8154 -391.0838)
		(end 97.8154 -391.541)
		(width 0.127)
		(layer "In11.Cu")
		(net "PRSNT_CABLE_GPU_A1_ISO_N")
	)
	(segment
		(start 96.190562 -396.493238)
		(end 47.651162 -396.493238)
		(width 0.127)
		(layer "In11.Cu")
		(net "PRSNT_CABLE_GPU_A1_ISO_N")
	)
	(segment
		(start 27.9146 -411.4292)
		(end 27.9146 -425.577)
		(width 0.127)
		(layer "In11.Cu")
		(net "PRSNT_CABLE_GPU_A1_ISO_N")
	)
	(segment
		(start 21.5646 -426.72)
		(end 21.082 -427.2026)
		(width 0.127)
		(layer "In11.Cu")
		(net "PRSNT_CABLE_GPU_A1_ISO_N")
	)
	(segment
		(start 43.7896 -405.4094)
		(end 42.494454 -405.4094)
		(width 0.127)
		(layer "In11.Cu")
		(net "PRSNT_CABLE_GPU_A1_ISO_N")
	)
	(segment
		(start 45.7962 -398.3482)
		(end 45.7962 -403.4028)
		(width 0.127)
		(layer "In11.Cu")
		(net "PRSNT_CABLE_GPU_A1_ISO_N")
	)
	(segment
		(start 47.651162 -396.493238)
		(end 45.7962 -398.3482)
		(width 0.127)
		(layer "In11.Cu")
		(net "PRSNT_CABLE_GPU_A1_ISO_N")
	)
	(segment
		(start 29.490162 -409.853638)
		(end 27.9146 -411.4292)
		(width 0.127)
		(layer "In11.Cu")
		(net "PRSNT_CABLE_GPU_A1_ISO_N")
	)
	(segment
		(start 98.5774 -394.1064)
		(end 96.190562 -396.493238)
		(width 0.127)
		(layer "In11.Cu")
		(net "PRSNT_CABLE_GPU_A1_ISO_N")
	)
	(segment
		(start 42.494454 -405.4094)
		(end 38.050216 -409.853638)
		(width 0.127)
		(layer "In11.Cu")
		(net "PRSNT_CABLE_GPU_A1_ISO_N")
	)
	(segment
		(start 184.912 -425.2341)
		(end 180.2257 -420.5478)
		(width 0.127)
		(layer "In13.Cu")
		(net "PRSNT_CABLE_GPU_A1_ISO_N")
	)
	(segment
		(start 169.3418 -414.099756)
		(end 169.3418 -410.943044)
		(width 0.127)
		(layer "In13.Cu")
		(net "PRSNT_CABLE_GPU_A1_ISO_N")
	)
	(segment
		(start 283.1846 -439.4962)
		(end 282.2448 -440.436)
		(width 0.127)
		(layer "In13.Cu")
		(net "PRSNT_CABLE_GPU_A1_ISO_N")
	)
	(segment
		(start 170.0276 -405.9428)
		(end 169.3418 -405.257)
		(width 0.127)
		(layer "In13.Cu")
		(net "PRSNT_CABLE_GPU_A1_ISO_N")
	)
	(segment
		(start 197.989444 -439.2676)
		(end 184.912 -426.190156)
		(width 0.127)
		(layer "In13.Cu")
		(net "PRSNT_CABLE_GPU_A1_ISO_N")
	)
	(segment
		(start 175.822356 -421.9702)
		(end 174.037244 -421.9702)
		(width 0.127)
		(layer "In13.Cu")
		(net "PRSNT_CABLE_GPU_A1_ISO_N")
	)
	(segment
		(start 177.244756 -420.5478)
		(end 175.822356 -421.9702)
		(width 0.127)
		(layer "In13.Cu")
		(net "PRSNT_CABLE_GPU_A1_ISO_N")
	)
	(segment
		(start 282.2448 -440.436)
		(end 278.482044 -440.436)
		(width 0.127)
		(layer "In13.Cu")
		(net "PRSNT_CABLE_GPU_A1_ISO_N")
	)
	(segment
		(start 277.313644 -439.2676)
		(end 197.989444 -439.2676)
		(width 0.127)
		(layer "In13.Cu")
		(net "PRSNT_CABLE_GPU_A1_ISO_N")
	)
	(segment
		(start 174.037244 -421.9702)
		(end 172.466 -420.398956)
		(width 0.127)
		(layer "In13.Cu")
		(net "PRSNT_CABLE_GPU_A1_ISO_N")
	)
	(segment
		(start 278.482044 -440.436)
		(end 277.313644 -439.2676)
		(width 0.127)
		(layer "In13.Cu")
		(net "PRSNT_CABLE_GPU_A1_ISO_N")
	)
	(segment
		(start 284.2768 -439.4962)
		(end 283.1846 -439.4962)
		(width 0.127)
		(layer "In13.Cu")
		(net "PRSNT_CABLE_GPU_A1_ISO_N")
	)
	(segment
		(start 172.466 -417.223956)
		(end 169.3418 -414.099756)
		(width 0.127)
		(layer "In13.Cu")
		(net "PRSNT_CABLE_GPU_A1_ISO_N")
	)
	(segment
		(start 172.466 -420.398956)
		(end 172.466 -417.223956)
		(width 0.127)
		(layer "In13.Cu")
		(net "PRSNT_CABLE_GPU_A1_ISO_N")
	)
	(segment
		(start 170.0276 -410.257244)
		(end 170.0276 -405.9428)
		(width 0.127)
		(layer "In13.Cu")
		(net "PRSNT_CABLE_GPU_A1_ISO_N")
	)
	(segment
		(start 184.912 -426.190156)
		(end 184.912 -425.2341)
		(width 0.127)
		(layer "In13.Cu")
		(net "PRSNT_CABLE_GPU_A1_ISO_N")
	)
	(segment
		(start 169.3418 -410.943044)
		(end 170.0276 -410.257244)
		(width 0.127)
		(layer "In13.Cu")
		(net "PRSNT_CABLE_GPU_A1_ISO_N")
	)
	(segment
		(start 180.2257 -420.5478)
		(end 177.244756 -420.5478)
		(width 0.127)
		(layer "In13.Cu")
		(net "PRSNT_CABLE_GPU_A1_ISO_N")
	)
	(segment
		(start 170.82008 -30.87624)
		(end 170.82008 -31.40456)
		(width 0.12954)
		(layer "F.Cu")
		(net "P12V_SCM_FLTB_N")
	)
	(segment
		(start 171.249848 -31.834328)
		(end 173.130464 -31.834328)
		(width 0.12954)
		(layer "F.Cu")
		(net "P12V_SCM_FLTB_N")
	)
	(segment
		(start 170.82008 -31.40456)
		(end 171.249848 -31.834328)
		(width 0.12954)
		(layer "F.Cu")
		(net "P12V_SCM_FLTB_N")
	)
	(segment
		(start 173.130464 -31.834328)
		(end 173.616112 -31.34868)
		(width 0.12954)
		(layer "F.Cu")
		(net "P12V_SCM_FLTB_N")
	)
	(via
		(at 170.82008 -30.87624)
		(size 0.762)
		(drill 0.381)
		(layers "F.Cu" "B.Cu")
		(net "P12V_SCM_FLTB_N")
	)
	(segment
		(start 194.08902 -28.72867)
		(end 194.08902 -27.63266)
		(width 0.12954)
		(layer "F.Cu")
		(net "P12V_SCM_FAULT_R_N")
	)
	(segment
		(start 193.98996 -27.29738)
		(end 193.089022 -26.396442)
		(width 0.12954)
		(layer "F.Cu")
		(net "P12V_SCM_FAULT_R_N")
	)
	(segment
		(start 205.994 -68.1482)
		(end 205.994 -68.326)
		(width 0.12954)
		(layer "F.Cu")
		(net "P12V_SCM_FAULT_R_N")
	)
	(segment
		(start 205.994 -68.326)
		(end 204.978 -69.342)
		(width 0.12954)
		(layer "F.Cu")
		(net "P12V_SCM_FAULT_R_N")
	)
	(segment
		(start 194.08902 -27.63266)
		(end 193.98996 -27.5336)
		(width 0.12954)
		(layer "F.Cu")
		(net "P12V_SCM_FAULT_R_N")
	)
	(segment
		(start 194.08902 -28.72867)
		(end 193.46799 -28.72867)
		(width 0.12954)
		(layer "F.Cu")
		(net "P12V_SCM_FAULT_R_N")
	)
	(segment
		(start 204.978 -69.342)
		(end 204.1652 -69.342)
		(width 0.12954)
		(layer "F.Cu")
		(net "P12V_SCM_FAULT_R_N")
	)
	(segment
		(start 202.438 -73.787)
		(end 189.0014 -73.787)
		(width 0.12954)
		(layer "F.Cu")
		(net "P12V_SCM_FAULT_R_N")
	)
	(segment
		(start 193.98996 -27.5336)
		(end 193.98996 -27.29738)
		(width 0.12954)
		(layer "F.Cu")
		(net "P12V_SCM_FAULT_R_N")
	)
	(segment
		(start 208.199736 -67.853306)
		(end 206.288894 -67.853306)
		(width 0.12954)
		(layer "F.Cu")
		(net "P12V_SCM_FAULT_R_N")
	)
	(segment
		(start 204.1652 -69.342)
		(end 204.0382 -69.469)
		(width 0.12954)
		(layer "F.Cu")
		(net "P12V_SCM_FAULT_R_N")
	)
	(segment
		(start 204.0382 -72.1868)
		(end 202.438 -73.787)
		(width 0.12954)
		(layer "F.Cu")
		(net "P12V_SCM_FAULT_R_N")
	)
	(segment
		(start 189.7888 -64.389)
		(end 189.7888 -63.881)
		(width 0.12954)
		(layer "F.Cu")
		(net "P12V_SCM_FAULT_R_N")
	)
	(segment
		(start 172.816012 -31.34868)
		(end 171.77512 -31.34868)
		(width 0.12954)
		(layer "F.Cu")
		(net "P12V_SCM_FAULT_R_N")
	)
	(segment
		(start 171.59224 -31.1658)
		(end 171.59224 -29.74848)
		(width 0.12954)
		(layer "F.Cu")
		(net "P12V_SCM_FAULT_R_N")
	)
	(segment
		(start 187.833 -66.3448)
		(end 189.7888 -64.389)
		(width 0.12954)
		(layer "F.Cu")
		(net "P12V_SCM_FAULT_R_N")
	)
	(segment
		(start 187.833 -72.6186)
		(end 187.833 -66.3448)
		(width 0.12954)
		(layer "F.Cu")
		(net "P12V_SCM_FAULT_R_N")
	)
	(segment
		(start 193.089022 -26.396442)
		(end 193.089022 -26.365962)
		(width 0.12954)
		(layer "F.Cu")
		(net "P12V_SCM_FAULT_R_N")
	)
	(segment
		(start 206.288894 -67.853306)
		(end 205.994 -68.1482)
		(width 0.12954)
		(layer "F.Cu")
		(net "P12V_SCM_FAULT_R_N")
	)
	(segment
		(start 193.46799 -28.72867)
		(end 193.13906 -28.39974)
		(width 0.12954)
		(layer "F.Cu")
		(net "P12V_SCM_FAULT_R_N")
	)
	(segment
		(start 189.0014 -73.787)
		(end 187.833 -72.6186)
		(width 0.12954)
		(layer "F.Cu")
		(net "P12V_SCM_FAULT_R_N")
	)
	(segment
		(start 204.0382 -69.469)
		(end 204.0382 -72.1868)
		(width 0.12954)
		(layer "F.Cu")
		(net "P12V_SCM_FAULT_R_N")
	)
	(segment
		(start 171.77512 -31.34868)
		(end 171.59224 -31.1658)
		(width 0.12954)
		(layer "F.Cu")
		(net "P12V_SCM_FAULT_R_N")
	)
	(via
		(at 193.13906 -28.39974)
		(size 0.508)
		(drill 0.254)
		(layers "F.Cu" "B.Cu")
		(net "P12V_SCM_FAULT_R_N")
	)
	(via
		(at 193.98996 -27.5336)
		(size 0.762)
		(drill 0.381)
		(layers "F.Cu" "B.Cu")
		(net "P12V_SCM_FAULT_R_N")
	)
	(via
		(at 187.6044 -34.6964)
		(size 0.508)
		(drill 0.254)
		(layers "F.Cu" "B.Cu")
		(net "P12V_SCM_FAULT_R_N")
	)
	(via
		(at 171.59224 -29.74848)
		(size 0.508)
		(drill 0.254)
		(layers "F.Cu" "B.Cu")
		(net "P12V_SCM_FAULT_R_N")
	)
	(via
		(at 189.7888 -63.881)
		(size 0.508)
		(drill 0.254)
		(layers "F.Cu" "B.Cu")
		(net "P12V_SCM_FAULT_R_N")
	)
	(segment
		(start 187.5028 -34.798)
		(end 187.5028 -37.719)
		(width 0.127)
		(layer "In2.Cu")
		(net "P12V_SCM_FAULT_R_N")
	)
	(segment
		(start 187.5028 -37.719)
		(end 187.9854 -38.2016)
		(width 0.127)
		(layer "In2.Cu")
		(net "P12V_SCM_FAULT_R_N")
	)
	(segment
		(start 187.9854 -38.2016)
		(end 187.9854 -44.1198)
		(width 0.127)
		(layer "In2.Cu")
		(net "P12V_SCM_FAULT_R_N")
	)
	(segment
		(start 187.6044 -34.6964)
		(end 187.5028 -34.798)
		(width 0.127)
		(layer "In2.Cu")
		(net "P12V_SCM_FAULT_R_N")
	)
	(segment
		(start 187.9854 -44.1198)
		(end 189.7888 -45.9232)
		(width 0.127)
		(layer "In2.Cu")
		(net "P12V_SCM_FAULT_R_N")
	)
	(segment
		(start 189.7888 -45.9232)
		(end 189.7888 -63.881)
		(width 0.127)
		(layer "In2.Cu")
		(net "P12V_SCM_FAULT_R_N")
	)
	(segment
		(start 187.02782 -35.27298)
		(end 183.54802 -35.27298)
		(width 0.127)
		(layer "In4.Cu")
		(net "P12V_SCM_FAULT_R_N")
	)
	(segment
		(start 182.92318 -35.89782)
		(end 175.33112 -35.89782)
		(width 0.127)
		(layer "In4.Cu")
		(net "P12V_SCM_FAULT_R_N")
	)
	(segment
		(start 187.6044 -34.6964)
		(end 187.02782 -35.27298)
		(width 0.127)
		(layer "In4.Cu")
		(net "P12V_SCM_FAULT_R_N")
	)
	(segment
		(start 171.59224 -32.15894)
		(end 171.59224 -29.74848)
		(width 0.127)
		(layer "In4.Cu")
		(net "P12V_SCM_FAULT_R_N")
	)
	(segment
		(start 175.33112 -35.89782)
		(end 171.59224 -32.15894)
		(width 0.127)
		(layer "In4.Cu")
		(net "P12V_SCM_FAULT_R_N")
	)
	(segment
		(start 183.54802 -35.27298)
		(end 182.92318 -35.89782)
		(width 0.127)
		(layer "In4.Cu")
		(net "P12V_SCM_FAULT_R_N")
	)
	(segment
		(start 193.89598 -28.39974)
		(end 193.13906 -28.39974)
		(width 0.127)
		(layer "In11.Cu")
		(net "P12V_SCM_FAULT_R_N")
	)
	(segment
		(start 195.24218 -29.74594)
		(end 193.89598 -28.39974)
		(width 0.127)
		(layer "In11.Cu")
		(net "P12V_SCM_FAULT_R_N")
	)
	(segment
		(start 195.24218 -34.05378)
		(end 195.24218 -29.74594)
		(width 0.127)
		(layer "In11.Cu")
		(net "P12V_SCM_FAULT_R_N")
	)
	(segment
		(start 193.76136 -35.5346)
		(end 195.24218 -34.05378)
		(width 0.127)
		(layer "In11.Cu")
		(net "P12V_SCM_FAULT_R_N")
	)
	(segment
		(start 187.6044 -34.6964)
		(end 188.4426 -35.5346)
		(width 0.127)
		(layer "In11.Cu")
		(net "P12V_SCM_FAULT_R_N")
	)
	(segment
		(start 188.4426 -35.5346)
		(end 193.76136 -35.5346)
		(width 0.127)
		(layer "In11.Cu")
		(net "P12V_SCM_FAULT_R_N")
	)
	(segment
		(start 191.539876 -25.393396)
		(end 192.29832 -26.15184)
		(width 0.12954)
		(layer "F.Cu")
		(net "P12V_SCM_FAULT_N")
	)
	(segment
		(start 192.29832 -26.15184)
		(end 192.29832 -28.93314)
		(width 0.12954)
		(layer "F.Cu")
		(net "P12V_SCM_FAULT_N")
	)
	(segment
		(start 192.89395 -29.52877)
		(end 192.8749 -29.50972)
		(width 0.12954)
		(layer "F.Cu")
		(net "P12V_SCM_FAULT_N")
	)
	(segment
		(start 191.238886 -25.393396)
		(end 191.539876 -25.393396)
		(width 0.12954)
		(layer "F.Cu")
		(net "P12V_SCM_FAULT_N")
	)
	(segment
		(start 194.08902 -29.52877)
		(end 192.89395 -29.52877)
		(width 0.12954)
		(layer "F.Cu")
		(net "P12V_SCM_FAULT_N")
	)
	(segment
		(start 192.29832 -28.93314)
		(end 192.8749 -29.50972)
		(width 0.12954)
		(layer "F.Cu")
		(net "P12V_SCM_FAULT_N")
	)
	(via
		(at 192.8749 -29.50972)
		(size 0.762)
		(drill 0.381)
		(layers "F.Cu" "B.Cu")
		(net "P12V_SCM_FAULT_N")
	)
	(segment
		(start 214.10676 -109.26699)
		(end 214.10676 -108.49864)
		(width 0.12954)
		(layer "F.Cu")
		(net "P12V_AUX_UV_TRIGGER")
	)
	(segment
		(start 212.4202 -107.81665)
		(end 213.4108 -107.81665)
		(width 0.12954)
		(layer "F.Cu")
		(net "P12V_AUX_UV_TRIGGER")
	)
	(segment
		(start 215.6206 -110.0836)
		(end 214.249 -110.0836)
		(width 0.12954)
		(layer "F.Cu")
		(net "P12V_AUX_UV_TRIGGER")
	)
	(segment
		(start 214.249 -110.0836)
		(end 214.10676 -109.94136)
		(width 0.12954)
		(layer "F.Cu")
		(net "P12V_AUX_UV_TRIGGER")
	)
	(segment
		(start 214.4268 -108.1786)
		(end 214.4268 -107.81665)
		(width 0.12954)
		(layer "F.Cu")
		(net "P12V_AUX_UV_TRIGGER")
	)
	(segment
		(start 214.10676 -108.49864)
		(end 214.4268 -108.1786)
		(width 0.12954)
		(layer "F.Cu")
		(net "P12V_AUX_UV_TRIGGER")
	)
	(segment
		(start 215.646 -110.109)
		(end 215.6206 -110.0836)
		(width 0.12954)
		(layer "F.Cu")
		(net "P12V_AUX_UV_TRIGGER")
	)
	(segment
		(start 215.646 -111.28375)
		(end 215.646 -110.109)
		(width 0.12954)
		(layer "F.Cu")
		(net "P12V_AUX_UV_TRIGGER")
	)
	(segment
		(start 213.4108 -107.81665)
		(end 214.4268 -107.81665)
		(width 0.12954)
		(layer "F.Cu")
		(net "P12V_AUX_UV_TRIGGER")
	)
	(segment
		(start 214.10676 -109.94136)
		(end 214.10676 -109.26699)
		(width 0.12954)
		(layer "F.Cu")
		(net "P12V_AUX_UV_TRIGGER")
	)
	(via
		(at 215.6206 -110.0836)
		(size 0.762)
		(drill 0.381)
		(layers "F.Cu" "B.Cu")
		(net "P12V_AUX_UV_TRIGGER")
	)
	(segment
		(start 204.97165 -98.7552)
		(end 203.6572 -98.7552)
		(width 0.12954)
		(layer "F.Cu")
		(net "P12V_AUX_UV_ADR_TRIGGER")
	)
	(segment
		(start 203.1238 -96.8502)
		(end 203.1238 -98.298)
		(width 0.12954)
		(layer "F.Cu")
		(net "P12V_AUX_UV_ADR_TRIGGER")
	)
	(segment
		(start 203.7588 -93.03385)
		(end 204.724 -93.03385)
		(width 0.12954)
		(layer "F.Cu")
		(net "P12V_AUX_UV_ADR_TRIGGER")
	)
	(segment
		(start 204.724 -93.03385)
		(end 205.6892 -93.03385)
		(width 0.12954)
		(layer "F.Cu")
		(net "P12V_AUX_UV_ADR_TRIGGER")
	)
	(segment
		(start 205.6384 -98.08845)
		(end 204.97165 -98.7552)
		(width 0.12954)
		(layer "F.Cu")
		(net "P12V_AUX_UV_ADR_TRIGGER")
	)
	(segment
		(start 204.09916 -94.56801)
		(end 204.09916 -95.87484)
		(width 0.12954)
		(layer "F.Cu")
		(net "P12V_AUX_UV_ADR_TRIGGER")
	)
	(segment
		(start 203.1238 -98.298)
		(end 203.581 -98.7552)
		(width 0.12954)
		(layer "F.Cu")
		(net "P12V_AUX_UV_ADR_TRIGGER")
	)
	(segment
		(start 203.581 -98.7552)
		(end 203.6572 -98.7552)
		(width 0.12954)
		(layer "F.Cu")
		(net "P12V_AUX_UV_ADR_TRIGGER")
	)
	(segment
		(start 204.09916 -94.56801)
		(end 204.09916 -93.73616)
		(width 0.12954)
		(layer "F.Cu")
		(net "P12V_AUX_UV_ADR_TRIGGER")
	)
	(segment
		(start 203.7588 -93.3958)
		(end 203.7588 -93.03385)
		(width 0.12954)
		(layer "F.Cu")
		(net "P12V_AUX_UV_ADR_TRIGGER")
	)
	(segment
		(start 204.09916 -95.87484)
		(end 203.1238 -96.8502)
		(width 0.12954)
		(layer "F.Cu")
		(net "P12V_AUX_UV_ADR_TRIGGER")
	)
	(segment
		(start 204.09916 -93.73616)
		(end 203.7588 -93.3958)
		(width 0.12954)
		(layer "F.Cu")
		(net "P12V_AUX_UV_ADR_TRIGGER")
	)
	(via
		(at 203.6572 -98.7552)
		(size 0.762)
		(drill 0.381)
		(layers "F.Cu" "B.Cu")
		(net "P12V_AUX_UV_ADR_TRIGGER")
	)
	(segment
		(start 181.80812 -411.60827)
		(end 180.79212 -411.60827)
		(width 0.12954)
		(layer "F.Cu")
		(net "OC_P2V5_COMP")
	)
	(segment
		(start 185.68416 -419.1762)
		(end 185.49874 -418.99078)
		(width 0.12954)
		(layer "F.Cu")
		(net "OC_P2V5_COMP")
	)
	(segment
		(start 182.50662 -412.89986)
		(end 181.80812 -412.20136)
		(width 0.12954)
		(layer "F.Cu")
		(net "OC_P2V5_COMP")
	)
	(segment
		(start 183.39054 -415.16554)
		(end 182.50662 -414.28162)
		(width 0.12954)
		(layer "F.Cu")
		(net "OC_P2V5_COMP")
	)
	(segment
		(start 182.50662 -413.41421)
		(end 182.50662 -412.89986)
		(width 0.12954)
		(layer "F.Cu")
		(net "OC_P2V5_COMP")
	)
	(segment
		(start 182.7149 -422.04132)
		(end 182.98414 -422.31056)
		(width 0.12954)
		(layer "F.Cu")
		(net "OC_P2V5_COMP")
	)
	(segment
		(start 185.3946 -422.31056)
		(end 185.68416 -422.021)
		(width 0.12954)
		(layer "F.Cu")
		(net "OC_P2V5_COMP")
	)
	(segment
		(start 183.91632 -416.98164)
		(end 183.39054 -416.45586)
		(width 0.12954)
		(layer "F.Cu")
		(net "OC_P2V5_COMP")
	)
	(segment
		(start 185.68416 -419.84422)
		(end 185.68416 -419.1762)
		(width 0.12954)
		(layer "F.Cu")
		(net "OC_P2V5_COMP")
	)
	(segment
		(start 183.91632 -418.6809)
		(end 183.91632 -416.98164)
		(width 0.12954)
		(layer "F.Cu")
		(net "OC_P2V5_COMP")
	)
	(segment
		(start 185.68416 -422.021)
		(end 185.68416 -419.84422)
		(width 0.12954)
		(layer "F.Cu")
		(net "OC_P2V5_COMP")
	)
	(segment
		(start 182.50662 -414.28162)
		(end 182.50662 -413.41421)
		(width 0.12954)
		(layer "F.Cu")
		(net "OC_P2V5_COMP")
	)
	(segment
		(start 181.80812 -412.20136)
		(end 181.80812 -411.60827)
		(width 0.12954)
		(layer "F.Cu")
		(net "OC_P2V5_COMP")
	)
	(segment
		(start 184.2262 -418.99078)
		(end 183.91632 -418.6809)
		(width 0.12954)
		(layer "F.Cu")
		(net "OC_P2V5_COMP")
	)
	(segment
		(start 182.98414 -422.31056)
		(end 185.3946 -422.31056)
		(width 0.12954)
		(layer "F.Cu")
		(net "OC_P2V5_COMP")
	)
	(segment
		(start 183.39054 -416.45586)
		(end 183.39054 -415.16554)
		(width 0.12954)
		(layer "F.Cu")
		(net "OC_P2V5_COMP")
	)
	(segment
		(start 185.49874 -418.99078)
		(end 184.2262 -418.99078)
		(width 0.12954)
		(layer "F.Cu")
		(net "OC_P2V5_COMP")
	)
	(segment
		(start 182.7149 -421.40251)
		(end 182.7149 -422.04132)
		(width 0.12954)
		(layer "F.Cu")
		(net "OC_P2V5_COMP")
	)
	(via
		(at 185.68416 -419.84422)
		(size 0.762)
		(drill 0.381)
		(layers "F.Cu" "B.Cu")
		(net "OC_P2V5_COMP")
	)
	(segment
		(start 144.295368 -113.463324)
		(end 145.06194 -113.463324)
		(width 0.12954)
		(layer "F.Cu")
		(net "OCP_V3_2_AUX_PWR_PLD_EN_R")
	)
	(segment
		(start 136.78535 -113.384584)
		(end 136.78535 -112.363504)
		(width 0.12954)
		(layer "F.Cu")
		(net "OCP_V3_2_AUX_PWR_PLD_EN_R")
	)
	(segment
		(start 136.78535 -112.03813)
		(end 136.78535 -112.363504)
		(width 0.12954)
		(layer "F.Cu")
		(net "OCP_V3_2_AUX_PWR_PLD_EN_R")
	)
	(segment
		(start 138.303 -113.384584)
		(end 137.98296 -113.064544)
		(width 0.12954)
		(layer "F.Cu")
		(net "OCP_V3_2_AUX_PWR_PLD_EN_R")
	)
	(segment
		(start 137.10539 -113.064544)
		(end 136.78535 -113.384584)
		(width 0.12954)
		(layer "F.Cu")
		(net "OCP_V3_2_AUX_PWR_PLD_EN_R")
	)
	(segment
		(start 137.98296 -113.064544)
		(end 137.10539 -113.064544)
		(width 0.12954)
		(layer "F.Cu")
		(net "OCP_V3_2_AUX_PWR_PLD_EN_R")
	)
	(segment
		(start 139.36218 -113.384584)
		(end 138.303 -113.384584)
		(width 0.12954)
		(layer "F.Cu")
		(net "OCP_V3_2_AUX_PWR_PLD_EN_R")
	)
	(segment
		(start 137.88898 -111.33328)
		(end 137.4902 -111.33328)
		(width 0.12954)
		(layer "F.Cu")
		(net "OCP_V3_2_AUX_PWR_PLD_EN_R")
	)
	(segment
		(start 137.4902 -111.33328)
		(end 136.78535 -112.03813)
		(width 0.12954)
		(layer "F.Cu")
		(net "OCP_V3_2_AUX_PWR_PLD_EN_R")
	)
	(via
		(at 137.88898 -111.33328)
		(size 0.508)
		(drill 0.254)
		(layers "F.Cu" "B.Cu")
		(net "OCP_V3_2_AUX_PWR_PLD_EN_R")
	)
	(via
		(at 137.98296 -113.064544)
		(size 0.762)
		(drill 0.381)
		(layers "F.Cu" "B.Cu")
		(net "OCP_V3_2_AUX_PWR_PLD_EN_R")
	)
	(via
		(at 145.06194 -113.463324)
		(size 0.508)
		(drill 0.254)
		(layers "F.Cu" "B.Cu")
		(net "OCP_V3_2_AUX_PWR_PLD_EN_R")
	)
	(segment
		(start 141.7828 -111.68634)
		(end 141.42974 -111.33328)
		(width 0.127)
		(layer "In6.Cu")
		(net "OCP_V3_2_AUX_PWR_PLD_EN_R")
	)
	(segment
		(start 143.9164 -111.68634)
		(end 141.7828 -111.68634)
		(width 0.127)
		(layer "In6.Cu")
		(net "OCP_V3_2_AUX_PWR_PLD_EN_R")
	)
	(segment
		(start 141.42974 -111.33328)
		(end 137.88898 -111.33328)
		(width 0.127)
		(layer "In6.Cu")
		(net "OCP_V3_2_AUX_PWR_PLD_EN_R")
	)
	(segment
		(start 145.06194 -113.463324)
		(end 144.10944 -112.510824)
		(width 0.127)
		(layer "In6.Cu")
		(net "OCP_V3_2_AUX_PWR_PLD_EN_R")
	)
	(segment
		(start 144.10944 -111.87938)
		(end 143.9164 -111.68634)
		(width 0.127)
		(layer "In6.Cu")
		(net "OCP_V3_2_AUX_PWR_PLD_EN_R")
	)
	(segment
		(start 144.10944 -112.510824)
		(end 144.10944 -111.87938)
		(width 0.127)
		(layer "In6.Cu")
		(net "OCP_V3_2_AUX_PWR_PLD_EN_R")
	)
	(segment
		(start 172.555662 -108.975398)
		(end 172.155612 -108.575348)
		(width 0.12954)
		(layer "F.Cu")
		(net "OCP_V3_2_AUX_PWR_PLD_EN")
	)
	(segment
		(start 135.98525 -112.363504)
		(end 135.2931 -112.363504)
		(width 0.12954)
		(layer "F.Cu")
		(net "OCP_V3_2_AUX_PWR_PLD_EN")
	)
	(via
		(at 172.155612 -108.575348)
		(size 0.4572)
		(drill 0.254)
		(layers "F.Cu" "B.Cu")
		(net "OCP_V3_2_AUX_PWR_PLD_EN")
	)
	(via
		(at 135.2931 -112.363504)
		(size 0.508)
		(drill 0.254)
		(layers "F.Cu" "B.Cu")
		(net "OCP_V3_2_AUX_PWR_PLD_EN")
	)
	(segment
		(start 161.1122 -108.077)
		(end 161.1122 -109.3724)
		(width 0.127)
		(layer "In6.Cu")
		(net "OCP_V3_2_AUX_PWR_PLD_EN")
	)
	(segment
		(start 146.05508 -108.44276)
		(end 131.17322 -108.44276)
		(width 0.127)
		(layer "In6.Cu")
		(net "OCP_V3_2_AUX_PWR_PLD_EN")
	)
	(segment
		(start 160.2994 -110.1852)
		(end 152.27046 -110.1852)
		(width 0.127)
		(layer "In6.Cu")
		(net "OCP_V3_2_AUX_PWR_PLD_EN")
	)
	(segment
		(start 152.27046 -110.1852)
		(end 151.02332 -108.93806)
		(width 0.127)
		(layer "In6.Cu")
		(net "OCP_V3_2_AUX_PWR_PLD_EN")
	)
	(segment
		(start 128.77292 -111.38408)
		(end 129.752344 -112.363504)
		(width 0.127)
		(layer "In6.Cu")
		(net "OCP_V3_2_AUX_PWR_PLD_EN")
	)
	(segment
		(start 146.55038 -108.93806)
		(end 146.05508 -108.44276)
		(width 0.127)
		(layer "In6.Cu")
		(net "OCP_V3_2_AUX_PWR_PLD_EN")
	)
	(segment
		(start 167.2336 -107.696)
		(end 161.4932 -107.696)
		(width 0.127)
		(layer "In6.Cu")
		(net "OCP_V3_2_AUX_PWR_PLD_EN")
	)
	(segment
		(start 172.155612 -108.3056)
		(end 172.028612 -108.1786)
		(width 0.127)
		(layer "In6.Cu")
		(net "OCP_V3_2_AUX_PWR_PLD_EN")
	)
	(segment
		(start 161.1122 -109.3724)
		(end 160.2994 -110.1852)
		(width 0.127)
		(layer "In6.Cu")
		(net "OCP_V3_2_AUX_PWR_PLD_EN")
	)
	(segment
		(start 167.6654 -108.1278)
		(end 167.2336 -107.696)
		(width 0.127)
		(layer "In6.Cu")
		(net "OCP_V3_2_AUX_PWR_PLD_EN")
	)
	(segment
		(start 131.17322 -108.44276)
		(end 128.77292 -110.84306)
		(width 0.127)
		(layer "In6.Cu")
		(net "OCP_V3_2_AUX_PWR_PLD_EN")
	)
	(segment
		(start 170.865546 -108.1278)
		(end 167.6654 -108.1278)
		(width 0.127)
		(layer "In6.Cu")
		(net "OCP_V3_2_AUX_PWR_PLD_EN")
	)
	(segment
		(start 128.77292 -110.84306)
		(end 128.77292 -111.38408)
		(width 0.127)
		(layer "In6.Cu")
		(net "OCP_V3_2_AUX_PWR_PLD_EN")
	)
	(segment
		(start 129.752344 -112.363504)
		(end 135.2931 -112.363504)
		(width 0.127)
		(layer "In6.Cu")
		(net "OCP_V3_2_AUX_PWR_PLD_EN")
	)
	(segment
		(start 161.4932 -107.696)
		(end 161.1122 -108.077)
		(width 0.127)
		(layer "In6.Cu")
		(net "OCP_V3_2_AUX_PWR_PLD_EN")
	)
	(segment
		(start 172.028612 -108.1786)
		(end 170.916346 -108.1786)
		(width 0.127)
		(layer "In6.Cu")
		(net "OCP_V3_2_AUX_PWR_PLD_EN")
	)
	(segment
		(start 151.02332 -108.93806)
		(end 146.55038 -108.93806)
		(width 0.127)
		(layer "In6.Cu")
		(net "OCP_V3_2_AUX_PWR_PLD_EN")
	)
	(segment
		(start 172.155612 -108.575348)
		(end 172.155612 -108.3056)
		(width 0.127)
		(layer "In6.Cu")
		(net "OCP_V3_2_AUX_PWR_PLD_EN")
	)
	(segment
		(start 170.916346 -108.1786)
		(end 170.865546 -108.1278)
		(width 0.127)
		(layer "In6.Cu")
		(net "OCP_V3_2_AUX_PWR_PLD_EN")
	)
	(segment
		(start 143.495268 -113.927128)
		(end 143.495268 -113.463324)
		(width 0.12954)
		(layer "F.Cu")
		(net "OCP_V3_2_AUX_PWR_EN_R2")
	)
	(segment
		(start 144.65046 -111.1504)
		(end 145.36928 -111.1504)
		(width 0.12954)
		(layer "F.Cu")
		(net "OCP_V3_2_AUX_PWR_EN_R2")
	)
	(segment
		(start 135.98525 -115.38458)
		(end 135.2931 -115.38458)
		(width 0.12954)
		(layer "F.Cu")
		(net "OCP_V3_2_AUX_PWR_EN_R2")
	)
	(segment
		(start 145.628614 -111.409734)
		(end 145.628614 -113.992406)
		(width 0.12954)
		(layer "F.Cu")
		(net "OCP_V3_2_AUX_PWR_EN_R2")
	)
	(segment
		(start 143.50111 -113.457482)
		(end 143.495268 -113.463324)
		(width 0.12954)
		(layer "F.Cu")
		(net "OCP_V3_2_AUX_PWR_EN_R2")
	)
	(segment
		(start 145.36928 -111.1504)
		(end 145.628614 -111.409734)
		(width 0.12954)
		(layer "F.Cu")
		(net "OCP_V3_2_AUX_PWR_EN_R2")
	)
	(segment
		(start 141.761972 -112.434624)
		(end 143.50111 -112.434624)
		(width 0.12954)
		(layer "F.Cu")
		(net "OCP_V3_2_AUX_PWR_EN_R2")
	)
	(segment
		(start 143.65224 -114.0841)
		(end 143.495268 -113.927128)
		(width 0.12954)
		(layer "F.Cu")
		(net "OCP_V3_2_AUX_PWR_EN_R2")
	)
	(segment
		(start 145.53692 -114.0841)
		(end 143.65224 -114.0841)
		(width 0.12954)
		(layer "F.Cu")
		(net "OCP_V3_2_AUX_PWR_EN_R2")
	)
	(segment
		(start 145.628614 -113.992406)
		(end 145.53692 -114.0841)
		(width 0.12954)
		(layer "F.Cu")
		(net "OCP_V3_2_AUX_PWR_EN_R2")
	)
	(segment
		(start 143.50111 -112.434624)
		(end 143.50111 -113.457482)
		(width 0.12954)
		(layer "F.Cu")
		(net "OCP_V3_2_AUX_PWR_EN_R2")
	)
	(via
		(at 144.65046 -111.1504)
		(size 0.508)
		(drill 0.254)
		(layers "F.Cu" "B.Cu")
		(net "OCP_V3_2_AUX_PWR_EN_R2")
	)
	(via
		(at 135.2931 -115.38458)
		(size 0.508)
		(drill 0.254)
		(layers "F.Cu" "B.Cu")
		(net "OCP_V3_2_AUX_PWR_EN_R2")
	)
	(segment
		(start 141.72438 -110.9726)
		(end 141.18336 -110.43158)
		(width 0.127)
		(layer "In6.Cu")
		(net "OCP_V3_2_AUX_PWR_EN_R2")
	)
	(segment
		(start 136.38022 -114.29746)
		(end 135.2931 -115.38458)
		(width 0.127)
		(layer "In6.Cu")
		(net "OCP_V3_2_AUX_PWR_EN_R2")
	)
	(segment
		(start 144.65046 -111.1504)
		(end 144.47266 -110.9726)
		(width 0.127)
		(layer "In6.Cu")
		(net "OCP_V3_2_AUX_PWR_EN_R2")
	)
	(segment
		(start 144.47266 -110.9726)
		(end 141.72438 -110.9726)
		(width 0.127)
		(layer "In6.Cu")
		(net "OCP_V3_2_AUX_PWR_EN_R2")
	)
	(segment
		(start 136.38022 -111.34852)
		(end 136.38022 -114.29746)
		(width 0.127)
		(layer "In6.Cu")
		(net "OCP_V3_2_AUX_PWR_EN_R2")
	)
	(segment
		(start 141.18336 -110.43158)
		(end 137.29716 -110.43158)
		(width 0.127)
		(layer "In6.Cu")
		(net "OCP_V3_2_AUX_PWR_EN_R2")
	)
	(segment
		(start 137.29716 -110.43158)
		(end 136.38022 -111.34852)
		(width 0.127)
		(layer "In6.Cu")
		(net "OCP_V3_2_AUX_PWR_EN_R2")
	)
	(segment
		(start 440.38012 -100.67163)
		(end 440.38012 -102.119176)
		(width 0.12954)
		(layer "F.Cu")
		(net "OCP_SFF_AUX_PWR_PLD_EN_R")
	)
	(segment
		(start 442.76518 -101.71684)
		(end 442.76518 -102.92715)
		(width 0.12954)
		(layer "F.Cu")
		(net "OCP_SFF_AUX_PWR_PLD_EN_R")
	)
	(segment
		(start 442.19114 -102.66172)
		(end 442.19114 -101.84384)
		(width 0.12954)
		(layer "F.Cu")
		(net "OCP_SFF_AUX_PWR_PLD_EN_R")
	)
	(segment
		(start 440.38012 -102.119176)
		(end 440.358276 -102.14102)
		(width 0.12954)
		(layer "F.Cu")
		(net "OCP_SFF_AUX_PWR_PLD_EN_R")
	)
	(segment
		(start 442.31814 -101.71684)
		(end 442.76518 -101.71684)
		(width 0.12954)
		(layer "F.Cu")
		(net "OCP_SFF_AUX_PWR_PLD_EN_R")
	)
	(segment
		(start 440.43219 -102.92715)
		(end 441.92571 -102.92715)
		(width 0.12954)
		(layer "F.Cu")
		(net "OCP_SFF_AUX_PWR_PLD_EN_R")
	)
	(segment
		(start 441.92571 -102.92715)
		(end 442.19114 -102.66172)
		(width 0.12954)
		(layer "F.Cu")
		(net "OCP_SFF_AUX_PWR_PLD_EN_R")
	)
	(segment
		(start 440.358276 -102.14102)
		(end 440.358276 -102.853236)
		(width 0.12954)
		(layer "F.Cu")
		(net "OCP_SFF_AUX_PWR_PLD_EN_R")
	)
	(segment
		(start 440.38012 -100.67163)
		(end 441.36564 -100.67163)
		(width 0.12954)
		(layer "F.Cu")
		(net "OCP_SFF_AUX_PWR_PLD_EN_R")
	)
	(segment
		(start 442.19114 -101.84384)
		(end 442.31814 -101.71684)
		(width 0.12954)
		(layer "F.Cu")
		(net "OCP_SFF_AUX_PWR_PLD_EN_R")
	)
	(segment
		(start 440.358276 -102.853236)
		(end 440.43219 -102.92715)
		(width 0.12954)
		(layer "F.Cu")
		(net "OCP_SFF_AUX_PWR_PLD_EN_R")
	)
	(via
		(at 442.76518 -101.71684)
		(size 0.762)
		(drill 0.381)
		(layers "F.Cu" "B.Cu")
		(net "OCP_SFF_AUX_PWR_PLD_EN_R")
	)
	(segment
		(start 441.36564 -99.87153)
		(end 441.36564 -99.21748)
		(width 0.12954)
		(layer "F.Cu")
		(net "OCP_SFF_AUX_PWR_PLD_EN")
	)
	(segment
		(start 173.355762 -109.775498)
		(end 172.955712 -109.375448)
		(width 0.12954)
		(layer "F.Cu")
		(net "OCP_SFF_AUX_PWR_PLD_EN")
	)
	(via
		(at 202.6666 -90.1192)
		(size 0.508)
		(drill 0.254)
		(layers "F.Cu" "B.Cu")
		(net "OCP_SFF_AUX_PWR_PLD_EN")
	)
	(via
		(at 186.1058 -89.281)
		(size 0.508)
		(drill 0.254)
		(layers "F.Cu" "B.Cu")
		(net "OCP_SFF_AUX_PWR_PLD_EN")
	)
	(via
		(at 172.955712 -109.375448)
		(size 0.4572)
		(drill 0.254)
		(layers "F.Cu" "B.Cu")
		(net "OCP_SFF_AUX_PWR_PLD_EN")
	)
	(via
		(at 276.77364 -103.77424)
		(size 0.508)
		(drill 0.254)
		(layers "F.Cu" "B.Cu")
		(net "OCP_SFF_AUX_PWR_PLD_EN")
	)
	(via
		(at 441.36564 -99.21748)
		(size 0.508)
		(drill 0.254)
		(layers "F.Cu" "B.Cu")
		(net "OCP_SFF_AUX_PWR_PLD_EN")
	)
	(segment
		(start 440.93638 -98.05162)
		(end 441.36564 -98.48088)
		(width 0.127)
		(layer "In4.Cu")
		(net "OCP_SFF_AUX_PWR_PLD_EN")
	)
	(segment
		(start 437.5785 -97.86874)
		(end 437.76138 -98.05162)
		(width 0.127)
		(layer "In4.Cu")
		(net "OCP_SFF_AUX_PWR_PLD_EN")
	)
	(segment
		(start 277.35784 -104.35844)
		(end 366.27816 -104.35844)
		(width 0.127)
		(layer "In4.Cu")
		(net "OCP_SFF_AUX_PWR_PLD_EN")
	)
	(segment
		(start 368.9096 -102.9335)
		(end 369.40744 -102.43566)
		(width 0.127)
		(layer "In4.Cu")
		(net "OCP_SFF_AUX_PWR_PLD_EN")
	)
	(segment
		(start 276.77364 -103.77424)
		(end 277.35784 -104.35844)
		(width 0.127)
		(layer "In4.Cu")
		(net "OCP_SFF_AUX_PWR_PLD_EN")
	)
	(segment
		(start 435.9275 -95.21952)
		(end 437.5785 -96.87052)
		(width 0.127)
		(layer "In4.Cu")
		(net "OCP_SFF_AUX_PWR_PLD_EN")
	)
	(segment
		(start 437.5785 -96.87052)
		(end 437.5785 -97.86874)
		(width 0.127)
		(layer "In4.Cu")
		(net "OCP_SFF_AUX_PWR_PLD_EN")
	)
	(segment
		(start 437.76138 -98.05162)
		(end 440.93638 -98.05162)
		(width 0.127)
		(layer "In4.Cu")
		(net "OCP_SFF_AUX_PWR_PLD_EN")
	)
	(segment
		(start 376.39498 -103.8733)
		(end 377.73356 -102.53472)
		(width 0.127)
		(layer "In4.Cu")
		(net "OCP_SFF_AUX_PWR_PLD_EN")
	)
	(segment
		(start 369.40744 -102.43566)
		(end 373.67718 -102.43566)
		(width 0.127)
		(layer "In4.Cu")
		(net "OCP_SFF_AUX_PWR_PLD_EN")
	)
	(segment
		(start 373.67718 -102.43566)
		(end 375.11482 -103.8733)
		(width 0.127)
		(layer "In4.Cu")
		(net "OCP_SFF_AUX_PWR_PLD_EN")
	)
	(segment
		(start 392.20648 -95.21952)
		(end 435.9275 -95.21952)
		(width 0.127)
		(layer "In4.Cu")
		(net "OCP_SFF_AUX_PWR_PLD_EN")
	)
	(segment
		(start 367.7031 -102.9335)
		(end 368.9096 -102.9335)
		(width 0.127)
		(layer "In4.Cu")
		(net "OCP_SFF_AUX_PWR_PLD_EN")
	)
	(segment
		(start 384.89128 -102.53472)
		(end 392.20648 -95.21952)
		(width 0.127)
		(layer "In4.Cu")
		(net "OCP_SFF_AUX_PWR_PLD_EN")
	)
	(segment
		(start 377.73356 -102.53472)
		(end 384.89128 -102.53472)
		(width 0.127)
		(layer "In4.Cu")
		(net "OCP_SFF_AUX_PWR_PLD_EN")
	)
	(segment
		(start 441.36564 -98.48088)
		(end 441.36564 -99.21748)
		(width 0.127)
		(layer "In4.Cu")
		(net "OCP_SFF_AUX_PWR_PLD_EN")
	)
	(segment
		(start 366.27816 -104.35844)
		(end 367.7031 -102.9335)
		(width 0.127)
		(layer "In4.Cu")
		(net "OCP_SFF_AUX_PWR_PLD_EN")
	)
	(segment
		(start 375.11482 -103.8733)
		(end 376.39498 -103.8733)
		(width 0.127)
		(layer "In4.Cu")
		(net "OCP_SFF_AUX_PWR_PLD_EN")
	)
	(segment
		(start 187.9854 -88.519)
		(end 188.7474 -89.281)
		(width 0.127)
		(layer "In6.Cu")
		(net "OCP_SFF_AUX_PWR_PLD_EN")
	)
	(segment
		(start 186.1058 -89.281)
		(end 186.1058 -88.7984)
		(width 0.127)
		(layer "In6.Cu")
		(net "OCP_SFF_AUX_PWR_PLD_EN")
	)
	(segment
		(start 202.6666 -89.7382)
		(end 202.6666 -90.1192)
		(width 0.127)
		(layer "In6.Cu")
		(net "OCP_SFF_AUX_PWR_PLD_EN")
	)
	(segment
		(start 186.1058 -88.7984)
		(end 186.3852 -88.519)
		(width 0.127)
		(layer "In6.Cu")
		(net "OCP_SFF_AUX_PWR_PLD_EN")
	)
	(segment
		(start 186.3852 -88.519)
		(end 187.9854 -88.519)
		(width 0.127)
		(layer "In6.Cu")
		(net "OCP_SFF_AUX_PWR_PLD_EN")
	)
	(segment
		(start 188.7474 -89.281)
		(end 202.2094 -89.281)
		(width 0.127)
		(layer "In6.Cu")
		(net "OCP_SFF_AUX_PWR_PLD_EN")
	)
	(segment
		(start 202.2094 -89.281)
		(end 202.6666 -89.7382)
		(width 0.127)
		(layer "In6.Cu")
		(net "OCP_SFF_AUX_PWR_PLD_EN")
	)
	(segment
		(start 197.13448 -97.60712)
		(end 197.13448 -104.94264)
		(width 0.127)
		(layer "In13.Cu")
		(net "OCP_SFF_AUX_PWR_PLD_EN")
	)
	(segment
		(start 252.2093 -108.5723)
		(end 253.57582 -108.5723)
		(width 0.127)
		(layer "In13.Cu")
		(net "OCP_SFF_AUX_PWR_PLD_EN")
	)
	(segment
		(start 212.84692 -107.96016)
		(end 228.89972 -107.96016)
		(width 0.127)
		(layer "In13.Cu")
		(net "OCP_SFF_AUX_PWR_PLD_EN")
	)
	(segment
		(start 200.71588 -106.426)
		(end 211.31276 -106.426)
		(width 0.127)
		(layer "In13.Cu")
		(net "OCP_SFF_AUX_PWR_PLD_EN")
	)
	(segment
		(start 172.562774 -98.242374)
		(end 172.562774 -109.062774)
		(width 0.127)
		(layer "In13.Cu")
		(net "OCP_SFF_AUX_PWR_PLD_EN")
	)
	(segment
		(start 182.782464 -88.743536)
		(end 181.229 -90.297)
		(width 0.127)
		(layer "In13.Cu")
		(net "OCP_SFF_AUX_PWR_PLD_EN")
	)
	(segment
		(start 173.66107 -93.0148)
		(end 171.7294 -94.94647)
		(width 0.127)
		(layer "In13.Cu")
		(net "OCP_SFF_AUX_PWR_PLD_EN")
	)
	(segment
		(start 197.7898 -105.59796)
		(end 199.88784 -105.59796)
		(width 0.127)
		(layer "In13.Cu")
		(net "OCP_SFF_AUX_PWR_PLD_EN")
	)
	(segment
		(start 274.91182 -103.77424)
		(end 276.77364 -103.77424)
		(width 0.127)
		(layer "In13.Cu")
		(net "OCP_SFF_AUX_PWR_PLD_EN")
	)
	(segment
		(start 186.1058 -89.281)
		(end 185.568336 -88.743536)
		(width 0.127)
		(layer "In13.Cu")
		(net "OCP_SFF_AUX_PWR_PLD_EN")
	)
	(segment
		(start 249.80646 -105.25506)
		(end 250.6726 -106.1212)
		(width 0.127)
		(layer "In13.Cu")
		(net "OCP_SFF_AUX_PWR_PLD_EN")
	)
	(segment
		(start 202.6666 -90.1192)
		(end 202.6666 -90.678)
		(width 0.127)
		(layer "In13.Cu")
		(net "OCP_SFF_AUX_PWR_PLD_EN")
	)
	(segment
		(start 269.64386 -103.30434)
		(end 274.44192 -103.30434)
		(width 0.127)
		(layer "In13.Cu")
		(net "OCP_SFF_AUX_PWR_PLD_EN")
	)
	(segment
		(start 246.43334 -103.83266)
		(end 247.85574 -105.25506)
		(width 0.127)
		(layer "In13.Cu")
		(net "OCP_SFF_AUX_PWR_PLD_EN")
	)
	(segment
		(start 181.229 -92.4814)
		(end 180.6956 -93.0148)
		(width 0.127)
		(layer "In13.Cu")
		(net "OCP_SFF_AUX_PWR_PLD_EN")
	)
	(segment
		(start 199.88784 -105.59796)
		(end 200.71588 -106.426)
		(width 0.127)
		(layer "In13.Cu")
		(net "OCP_SFF_AUX_PWR_PLD_EN")
	)
	(segment
		(start 171.7294 -97.409)
		(end 172.562774 -98.242374)
		(width 0.127)
		(layer "In13.Cu")
		(net "OCP_SFF_AUX_PWR_PLD_EN")
	)
	(segment
		(start 228.89972 -107.96016)
		(end 233.02722 -103.83266)
		(width 0.127)
		(layer "In13.Cu")
		(net "OCP_SFF_AUX_PWR_PLD_EN")
	)
	(segment
		(start 202.6666 -90.678)
		(end 202.2348 -91.1098)
		(width 0.127)
		(layer "In13.Cu")
		(net "OCP_SFF_AUX_PWR_PLD_EN")
	)
	(segment
		(start 211.31276 -106.426)
		(end 212.84692 -107.96016)
		(width 0.127)
		(layer "In13.Cu")
		(net "OCP_SFF_AUX_PWR_PLD_EN")
	)
	(segment
		(start 202.2348 -91.1098)
		(end 201.1172 -91.1098)
		(width 0.127)
		(layer "In13.Cu")
		(net "OCP_SFF_AUX_PWR_PLD_EN")
	)
	(segment
		(start 247.85574 -105.25506)
		(end 249.80646 -105.25506)
		(width 0.127)
		(layer "In13.Cu")
		(net "OCP_SFF_AUX_PWR_PLD_EN")
	)
	(segment
		(start 255.62306 -110.61954)
		(end 262.32866 -110.61954)
		(width 0.127)
		(layer "In13.Cu")
		(net "OCP_SFF_AUX_PWR_PLD_EN")
	)
	(segment
		(start 181.229 -90.297)
		(end 181.229 -92.4814)
		(width 0.127)
		(layer "In13.Cu")
		(net "OCP_SFF_AUX_PWR_PLD_EN")
	)
	(segment
		(start 274.44192 -103.30434)
		(end 274.91182 -103.77424)
		(width 0.127)
		(layer "In13.Cu")
		(net "OCP_SFF_AUX_PWR_PLD_EN")
	)
	(segment
		(start 200.0504 -92.1766)
		(end 200.0504 -94.6912)
		(width 0.127)
		(layer "In13.Cu")
		(net "OCP_SFF_AUX_PWR_PLD_EN")
	)
	(segment
		(start 250.6726 -107.0356)
		(end 252.2093 -108.5723)
		(width 0.127)
		(layer "In13.Cu")
		(net "OCP_SFF_AUX_PWR_PLD_EN")
	)
	(segment
		(start 262.32866 -110.61954)
		(end 269.64386 -103.30434)
		(width 0.127)
		(layer "In13.Cu")
		(net "OCP_SFF_AUX_PWR_PLD_EN")
	)
	(segment
		(start 172.875448 -109.375448)
		(end 172.955712 -109.375448)
		(width 0.127)
		(layer "In13.Cu")
		(net "OCP_SFF_AUX_PWR_PLD_EN")
	)
	(segment
		(start 201.1172 -91.1098)
		(end 200.0504 -92.1766)
		(width 0.127)
		(layer "In13.Cu")
		(net "OCP_SFF_AUX_PWR_PLD_EN")
	)
	(segment
		(start 171.7294 -94.94647)
		(end 171.7294 -97.409)
		(width 0.127)
		(layer "In13.Cu")
		(net "OCP_SFF_AUX_PWR_PLD_EN")
	)
	(segment
		(start 200.0504 -94.6912)
		(end 197.13448 -97.60712)
		(width 0.127)
		(layer "In13.Cu")
		(net "OCP_SFF_AUX_PWR_PLD_EN")
	)
	(segment
		(start 233.02722 -103.83266)
		(end 246.43334 -103.83266)
		(width 0.127)
		(layer "In13.Cu")
		(net "OCP_SFF_AUX_PWR_PLD_EN")
	)
	(segment
		(start 172.562774 -109.062774)
		(end 172.875448 -109.375448)
		(width 0.127)
		(layer "In13.Cu")
		(net "OCP_SFF_AUX_PWR_PLD_EN")
	)
	(segment
		(start 250.6726 -106.1212)
		(end 250.6726 -107.0356)
		(width 0.127)
		(layer "In13.Cu")
		(net "OCP_SFF_AUX_PWR_PLD_EN")
	)
	(segment
		(start 180.6956 -93.0148)
		(end 173.66107 -93.0148)
		(width 0.127)
		(layer "In13.Cu")
		(net "OCP_SFF_AUX_PWR_PLD_EN")
	)
	(segment
		(start 197.13448 -104.94264)
		(end 197.7898 -105.59796)
		(width 0.127)
		(layer "In13.Cu")
		(net "OCP_SFF_AUX_PWR_PLD_EN")
	)
	(segment
		(start 185.568336 -88.743536)
		(end 182.782464 -88.743536)
		(width 0.127)
		(layer "In13.Cu")
		(net "OCP_SFF_AUX_PWR_PLD_EN")
	)
	(segment
		(start 253.57582 -108.5723)
		(end 255.62306 -110.61954)
		(width 0.127)
		(layer "In13.Cu")
		(net "OCP_SFF_AUX_PWR_PLD_EN")
	)
	(segment
		(start 442.708538 -104.984042)
		(end 442.76518 -104.9274)
		(width 0.12954)
		(layer "F.Cu")
		(net "OCP_SFF_AUX_PWR_EN_R2")
	)
	(segment
		(start 441.308236 -105.283)
		(end 441.308236 -104.540812)
		(width 0.12954)
		(layer "F.Cu")
		(net "OCP_SFF_AUX_PWR_EN_R2")
	)
	(segment
		(start 441.52566 -105.500424)
		(end 441.308236 -105.283)
		(width 0.12954)
		(layer "F.Cu")
		(net "OCP_SFF_AUX_PWR_EN_R2")
	)
	(segment
		(start 440.50966 -105.98531)
		(end 441.52566 -105.98531)
		(width 0.12954)
		(layer "F.Cu")
		(net "OCP_SFF_AUX_PWR_EN_R2")
	)
	(segment
		(start 441.52566 -105.98531)
		(end 441.52566 -105.500424)
		(width 0.12954)
		(layer "F.Cu")
		(net "OCP_SFF_AUX_PWR_EN_R2")
	)
	(segment
		(start 442.035692 -104.540812)
		(end 442.53023 -105.03535)
		(width 0.12954)
		(layer "F.Cu")
		(net "OCP_SFF_AUX_PWR_EN_R2")
	)
	(segment
		(start 442.53023 -105.03535)
		(end 442.65723 -105.03535)
		(width 0.12954)
		(layer "F.Cu")
		(net "OCP_SFF_AUX_PWR_EN_R2")
	)
	(segment
		(start 441.308236 -104.540812)
		(end 442.035692 -104.540812)
		(width 0.12954)
		(layer "F.Cu")
		(net "OCP_SFF_AUX_PWR_EN_R2")
	)
	(segment
		(start 442.76518 -104.9274)
		(end 442.76518 -103.72725)
		(width 0.12954)
		(layer "F.Cu")
		(net "OCP_SFF_AUX_PWR_EN_R2")
	)
	(segment
		(start 442.65723 -105.03535)
		(end 442.708538 -104.984042)
		(width 0.12954)
		(layer "F.Cu")
		(net "OCP_SFF_AUX_PWR_EN_R2")
	)
	(via
		(at 442.708538 -104.984042)
		(size 0.762)
		(drill 0.381)
		(layers "F.Cu" "B.Cu")
		(net "OCP_SFF_AUX_PWR_EN_R2")
	)
	(segment
		(start 210.693 -121.1072)
		(end 211.349336 -121.1072)
		(width 0.12954)
		(layer "F.Cu")
		(net "NC_UXX_2Y")
	)
	(segment
		(start 210.0834 -121.7168)
		(end 210.693 -121.1072)
		(width 0.12954)
		(layer "F.Cu")
		(net "NC_UXX_2Y")
	)
	(via
		(at 210.0834 -121.7168)
		(size 0.762)
		(drill 0.381)
		(layers "F.Cu" "B.Cu")
		(net "NC_UXX_2Y")
	)
	(segment
		(start 206.9592 -67.20332)
		(end 205.433422 -67.20332)
		(width 0.12954)
		(layer "F.Cu")
		(net "LED_P12V_SCM_FAULT_D2")
	)
	(segment
		(start 208.199736 -67.20332)
		(end 206.9592 -67.20332)
		(width 0.12954)
		(layer "F.Cu")
		(net "LED_P12V_SCM_FAULT_D2")
	)
	(via
		(at 206.9592 -67.20332)
		(size 0.762)
		(drill 0.381)
		(layers "F.Cu" "B.Cu")
		(net "LED_P12V_SCM_FAULT_D2")
	)
	(segment
		(start 209.494882 -68.411344)
		(end 209.58683 -68.503292)
		(width 0.12954)
		(layer "F.Cu")
		(net "LED_P12V_SCM_FAULT_D1")
	)
	(segment
		(start 209.58683 -68.503292)
		(end 210.099656 -68.503292)
		(width 0.12954)
		(layer "F.Cu")
		(net "LED_P12V_SCM_FAULT_D1")
	)
	(segment
		(start 210.099656 -67.853306)
		(end 210.0961 -67.856862)
		(width 0.12954)
		(layer "F.Cu")
		(net "LED_P12V_SCM_FAULT_D1")
	)
	(segment
		(start 210.0961 -67.856862)
		(end 209.6262 -67.856862)
		(width 0.12954)
		(layer "F.Cu")
		(net "LED_P12V_SCM_FAULT_D1")
	)
	(segment
		(start 209.6262 -67.856862)
		(end 209.494882 -67.98818)
		(width 0.12954)
		(layer "F.Cu")
		(net "LED_P12V_SCM_FAULT_D1")
	)
	(segment
		(start 210.099656 -67.853306)
		(end 211.455 -67.853306)
		(width 0.12954)
		(layer "F.Cu")
		(net "LED_P12V_SCM_FAULT_D1")
	)
	(segment
		(start 209.494882 -67.98818)
		(end 209.494882 -68.411344)
		(width 0.12954)
		(layer "F.Cu")
		(net "LED_P12V_SCM_FAULT_D1")
	)
	(segment
		(start 202.3872 -67.7672)
		(end 203.1492 -68.5292)
		(width 0.12954)
		(layer "F.Cu")
		(net "LED_P12V_SCM_FAULT")
	)
	(segment
		(start 202.3872 -67.7672)
		(end 202.3872 -67.3354)
		(width 0.12954)
		(layer "F.Cu")
		(net "LED_P12V_SCM_FAULT")
	)
	(segment
		(start 202.51928 -67.20332)
		(end 203.933298 -67.20332)
		(width 0.12954)
		(layer "F.Cu")
		(net "LED_P12V_SCM_FAULT")
	)
	(segment
		(start 203.1492 -68.5292)
		(end 203.933298 -68.5292)
		(width 0.12954)
		(layer "F.Cu")
		(net "LED_P12V_SCM_FAULT")
	)
	(segment
		(start 202.3872 -67.3354)
		(end 202.51928 -67.20332)
		(width 0.12954)
		(layer "F.Cu")
		(net "LED_P12V_SCM_FAULT")
	)
	(via
		(at 202.3872 -67.7672)
		(size 0.762)
		(drill 0.381)
		(layers "F.Cu" "B.Cu")
		(net "LED_P12V_SCM_FAULT")
	)
	(via
		(at 194.769994 -422.078404)
		(size 0.6604)
		(drill 0.3302)
		(layers "F.Cu" "B.Cu")
		(net "LED_P12V_PSU_R3")
	)
	(segment
		(start 193.708528 -422.838626)
		(end 193.71818 -422.848278)
		(width 0.12954)
		(layer "B.Cu")
		(net "LED_P12V_PSU_R3")
	)
	(segment
		(start 193.708528 -422.430448)
		(end 193.708528 -422.838626)
		(width 0.12954)
		(layer "B.Cu")
		(net "LED_P12V_PSU_R3")
	)
	(segment
		(start 195.243704 -422.826688)
		(end 195.243704 -422.552114)
		(width 0.12954)
		(layer "B.Cu")
		(net "LED_P12V_PSU_R3")
	)
	(segment
		(start 195.253356 -423.256964)
		(end 195.253356 -422.83634)
		(width 0.12954)
		(layer "B.Cu")
		(net "LED_P12V_PSU_R3")
	)
	(segment
		(start 194.060572 -422.078404)
		(end 193.708528 -422.430448)
		(width 0.12954)
		(layer "B.Cu")
		(net "LED_P12V_PSU_R3")
	)
	(segment
		(start 193.71818 -422.848278)
		(end 193.71818 -423.269156)
		(width 0.12954)
		(layer "B.Cu")
		(net "LED_P12V_PSU_R3")
	)
	(segment
		(start 195.253356 -422.83634)
		(end 195.243704 -422.826688)
		(width 0.12954)
		(layer "B.Cu")
		(net "LED_P12V_PSU_R3")
	)
	(segment
		(start 194.769994 -422.078404)
		(end 194.060572 -422.078404)
		(width 0.12954)
		(layer "B.Cu")
		(net "LED_P12V_PSU_R3")
	)
	(segment
		(start 195.243704 -422.552114)
		(end 194.769994 -422.078404)
		(width 0.12954)
		(layer "B.Cu")
		(net "LED_P12V_PSU_R3")
	)
	(via
		(at 194.054476 -425.371514)
		(size 0.6604)
		(drill 0.3302)
		(layers "F.Cu" "B.Cu")
		(net "LED_P12V_PSU_R2")
	)
	(segment
		(start 193.71818 -424.48988)
		(end 193.71818 -424.069256)
		(width 0.12954)
		(layer "B.Cu")
		(net "LED_P12V_PSU_R2")
	)
	(segment
		(start 193.613786 -425.371514)
		(end 192.724532 -424.48226)
		(width 0.12954)
		(layer "B.Cu")
		(net "LED_P12V_PSU_R2")
	)
	(segment
		(start 194.054476 -424.826176)
		(end 193.71818 -424.48988)
		(width 0.12954)
		(layer "B.Cu")
		(net "LED_P12V_PSU_R2")
	)
	(segment
		(start 194.054476 -425.371514)
		(end 193.613786 -425.371514)
		(width 0.12954)
		(layer "B.Cu")
		(net "LED_P12V_PSU_R2")
	)
	(segment
		(start 194.054476 -425.371514)
		(end 194.054476 -424.826176)
		(width 0.12954)
		(layer "B.Cu")
		(net "LED_P12V_PSU_R2")
	)
	(segment
		(start 192.724532 -424.48226)
		(end 192.724532 -424.057064)
		(width 0.12954)
		(layer "B.Cu")
		(net "LED_P12V_PSU_R2")
	)
	(segment
		(start 49.934622 -59.688222)
		(end 51.45786 -61.21146)
		(width 0.12954)
		(layer "F.Cu")
		(net "LED_P12V_PSU_R1")
	)
	(segment
		(start 93.6244 -391.9728)
		(end 90.6272 -388.9756)
		(width 0.12954)
		(layer "F.Cu")
		(net "LED_P12V_PSU_R1")
	)
	(segment
		(start 56.60517 -94.635574)
		(end 38.949376 -94.635574)
		(width 0.12954)
		(layer "F.Cu")
		(net "LED_P12V_PSU_R1")
	)
	(segment
		(start 3.527552 -111.794798)
		(end 12.2936 -120.560846)
		(width 0.12954)
		(layer "F.Cu")
		(net "LED_P12V_PSU_R1")
	)
	(segment
		(start 90.6272 -388.9756)
		(end 90.6272 -384.2004)
		(width 0.12954)
		(layer "F.Cu")
		(net "LED_P12V_PSU_R1")
	)
	(segment
		(start 42.880534 -59.688222)
		(end 46.041564 -59.688222)
		(width 0.12954)
		(layer "F.Cu")
		(net "LED_P12V_PSU_R1")
	)
	(segment
		(start 88.8492 -382.4224)
		(end 39.0144 -382.4224)
		(width 0.12954)
		(layer "F.Cu")
		(net "LED_P12V_PSU_R1")
	)
	(segment
		(start 66.447924 -95.734124)
		(end 66.447924 -100.496116)
		(width 0.12954)
		(layer "F.Cu")
		(net "LED_P12V_PSU_R1")
	)
	(segment
		(start 90.6272 -384.2004)
		(end 88.8492 -382.4224)
		(width 0.12954)
		(layer "F.Cu")
		(net "LED_P12V_PSU_R1")
	)
	(segment
		(start 42.233596 -58.655712)
		(end 42.233596 -59.041284)
		(width 0.12954)
		(layer "F.Cu")
		(net "LED_P12V_PSU_R1")
	)
	(segment
		(start 66.447924 -100.496116)
		(end 65.62598 -101.31806)
		(width 0.12954)
		(layer "F.Cu")
		(net "LED_P12V_PSU_R1")
	)
	(segment
		(start 38.949376 -94.635574)
		(end 25.376378 -81.062576)
		(width 0.12954)
		(layer "F.Cu")
		(net "LED_P12V_PSU_R1")
	)
	(segment
		(start 51.45786 -80.74406)
		(end 66.447924 -95.734124)
		(width 0.12954)
		(layer "F.Cu")
		(net "LED_P12V_PSU_R1")
	)
	(segment
		(start 51.45786 -61.21146)
		(end 51.45786 -80.74406)
		(width 0.12954)
		(layer "F.Cu")
		(net "LED_P12V_PSU_R1")
	)
	(segment
		(start 3.527552 -83.876388)
		(end 3.527552 -111.794798)
		(width 0.12954)
		(layer "F.Cu")
		(net "LED_P12V_PSU_R1")
	)
	(segment
		(start 65.62598 -101.31806)
		(end 63.287656 -101.31806)
		(width 0.12954)
		(layer "F.Cu")
		(net "LED_P12V_PSU_R1")
	)
	(segment
		(start 46.041564 -59.688222)
		(end 49.934622 -59.688222)
		(width 0.12954)
		(layer "F.Cu")
		(net "LED_P12V_PSU_R1")
	)
	(segment
		(start 63.287656 -101.31806)
		(end 56.60517 -94.635574)
		(width 0.12954)
		(layer "F.Cu")
		(net "LED_P12V_PSU_R1")
	)
	(segment
		(start 12.2936 -120.560846)
		(end 12.2936 -148.844)
		(width 0.12954)
		(layer "F.Cu")
		(net "LED_P12V_PSU_R1")
	)
	(segment
		(start 42.233596 -59.041284)
		(end 42.880534 -59.688222)
		(width 0.12954)
		(layer "F.Cu")
		(net "LED_P12V_PSU_R1")
	)
	(segment
		(start 6.341364 -81.062576)
		(end 3.527552 -83.876388)
		(width 0.12954)
		(layer "F.Cu")
		(net "LED_P12V_PSU_R1")
	)
	(segment
		(start 25.376378 -81.062576)
		(end 6.341364 -81.062576)
		(width 0.12954)
		(layer "F.Cu")
		(net "LED_P12V_PSU_R1")
	)
	(via
		(at 46.041564 -59.688222)
		(size 0.762)
		(drill 0.381)
		(layers "F.Cu" "B.Cu")
		(net "LED_P12V_PSU_R1")
	)
	(via
		(at 193.475864 -421.943276)
		(size 0.508)
		(drill 0.254)
		(layers "F.Cu" "B.Cu")
		(net "LED_P12V_PSU_R1")
	)
	(via
		(at 39.0144 -382.4224)
		(size 0.508)
		(drill 0.254)
		(layers "F.Cu" "B.Cu")
		(net "LED_P12V_PSU_R1")
	)
	(via
		(at 15.113 -187.6298)
		(size 0.508)
		(drill 0.254)
		(layers "F.Cu" "B.Cu")
		(net "LED_P12V_PSU_R1")
	)
	(via
		(at 116.8908 -403.8346)
		(size 0.508)
		(drill 0.254)
		(layers "F.Cu" "B.Cu")
		(net "LED_P12V_PSU_R1")
	)
	(via
		(at 12.2936 -148.844)
		(size 0.508)
		(drill 0.254)
		(layers "F.Cu" "B.Cu")
		(net "LED_P12V_PSU_R1")
	)
	(via
		(at 93.6244 -391.9728)
		(size 0.508)
		(drill 0.254)
		(layers "F.Cu" "B.Cu")
		(net "LED_P12V_PSU_R1")
	)
	(segment
		(start 93.6244 -394.8176)
		(end 95.25 -396.4432)
		(width 0.12954)
		(layer "B.Cu")
		(net "LED_P12V_PSU_R1")
	)
	(segment
		(start 15.113 -187.6298)
		(end 14.7574 -187.2742)
		(width 0.12954)
		(layer "B.Cu")
		(net "LED_P12V_PSU_R1")
	)
	(segment
		(start 17.7292 -163.2712)
		(end 17.7292 -156.2862)
		(width 0.12954)
		(layer "B.Cu")
		(net "LED_P12V_PSU_R1")
	)
	(segment
		(start 6.27507 -166.92753)
		(end 14.07287 -166.92753)
		(width 0.12954)
		(layer "B.Cu")
		(net "LED_P12V_PSU_R1")
	)
	(segment
		(start 14.7574 -187.2742)
		(end 14.7574 -183.72836)
		(width 0.12954)
		(layer "B.Cu")
		(net "LED_P12V_PSU_R1")
	)
	(segment
		(start 12.2936 -152.146)
		(end 12.2936 -148.844)
		(width 0.12954)
		(layer "B.Cu")
		(net "LED_P12V_PSU_R1")
	)
	(segment
		(start 15.113 -154.9654)
		(end 12.2936 -152.146)
		(width 0.12954)
		(layer "B.Cu")
		(net "LED_P12V_PSU_R1")
	)
	(segment
		(start 192.996566 -421.943276)
		(end 192.71488 -422.224962)
		(width 0.12954)
		(layer "B.Cu")
		(net "LED_P12V_PSU_R1")
	)
	(segment
		(start 193.475864 -421.943276)
		(end 192.996566 -421.943276)
		(width 0.12954)
		(layer "B.Cu")
		(net "LED_P12V_PSU_R1")
	)
	(segment
		(start 5.13969 -168.06291)
		(end 6.27507 -166.92753)
		(width 0.12954)
		(layer "B.Cu")
		(net "LED_P12V_PSU_R1")
	)
	(segment
		(start 14.7574 -183.72836)
		(end 5.13969 -174.11065)
		(width 0.12954)
		(layer "B.Cu")
		(net "LED_P12V_PSU_R1")
	)
	(segment
		(start 192.71488 -422.224962)
		(end 192.71488 -422.826688)
		(width 0.12954)
		(layer "B.Cu")
		(net "LED_P12V_PSU_R1")
	)
	(segment
		(start 192.71488 -422.826688)
		(end 192.724532 -422.83634)
		(width 0.12954)
		(layer "B.Cu")
		(net "LED_P12V_PSU_R1")
	)
	(segment
		(start 93.6244 -391.9728)
		(end 93.6244 -394.8176)
		(width 0.12954)
		(layer "B.Cu")
		(net "LED_P12V_PSU_R1")
	)
	(segment
		(start 97.536 -396.4432)
		(end 101.981 -400.8882)
		(width 0.12954)
		(layer "B.Cu")
		(net "LED_P12V_PSU_R1")
	)
	(segment
		(start 16.4084 -154.9654)
		(end 15.113 -154.9654)
		(width 0.12954)
		(layer "B.Cu")
		(net "LED_P12V_PSU_R1")
	)
	(segment
		(start 5.13969 -174.11065)
		(end 5.13969 -168.06291)
		(width 0.12954)
		(layer "B.Cu")
		(net "LED_P12V_PSU_R1")
	)
	(segment
		(start 101.981 -400.8882)
		(end 104.8004 -400.8882)
		(width 0.12954)
		(layer "B.Cu")
		(net "LED_P12V_PSU_R1")
	)
	(segment
		(start 95.25 -396.4432)
		(end 97.536 -396.4432)
		(width 0.12954)
		(layer "B.Cu")
		(net "LED_P12V_PSU_R1")
	)
	(segment
		(start 17.7292 -156.2862)
		(end 16.4084 -154.9654)
		(width 0.12954)
		(layer "B.Cu")
		(net "LED_P12V_PSU_R1")
	)
	(segment
		(start 104.8004 -400.8882)
		(end 107.7468 -403.8346)
		(width 0.12954)
		(layer "B.Cu")
		(net "LED_P12V_PSU_R1")
	)
	(segment
		(start 14.07287 -166.92753)
		(end 17.7292 -163.2712)
		(width 0.12954)
		(layer "B.Cu")
		(net "LED_P12V_PSU_R1")
	)
	(segment
		(start 107.7468 -403.8346)
		(end 116.8908 -403.8346)
		(width 0.12954)
		(layer "B.Cu")
		(net "LED_P12V_PSU_R1")
	)
	(segment
		(start 192.724532 -422.83634)
		(end 192.724532 -423.256964)
		(width 0.12954)
		(layer "B.Cu")
		(net "LED_P12V_PSU_R1")
	)
	(segment
		(start 37.7444 -374.777)
		(end 32.385 -369.4176)
		(width 0.12954)
		(layer "In2.Cu")
		(net "LED_P12V_PSU_R1")
	)
	(segment
		(start 16.1798 -190.5)
		(end 15.113 -189.4332)
		(width 0.12954)
		(layer "In2.Cu")
		(net "LED_P12V_PSU_R1")
	)
	(segment
		(start 37.7444 -379.984)
		(end 37.7444 -374.777)
		(width 0.12954)
		(layer "In2.Cu")
		(net "LED_P12V_PSU_R1")
	)
	(segment
		(start 32.385 -369.4176)
		(end 32.385 -329.8698)
		(width 0.12954)
		(layer "In2.Cu")
		(net "LED_P12V_PSU_R1")
	)
	(segment
		(start 24.6634 -194.6656)
		(end 23.2664 -194.6656)
		(width 0.12954)
		(layer "In2.Cu")
		(net "LED_P12V_PSU_R1")
	)
	(segment
		(start 26.9748 -325.8312)
		(end 25.3238 -324.1802)
		(width 0.12954)
		(layer "In2.Cu")
		(net "LED_P12V_PSU_R1")
	)
	(segment
		(start 19.2278 -190.5)
		(end 16.1798 -190.5)
		(width 0.12954)
		(layer "In2.Cu")
		(net "LED_P12V_PSU_R1")
	)
	(segment
		(start 25.0698 -195.072)
		(end 24.6634 -194.6656)
		(width 0.12954)
		(layer "In2.Cu")
		(net "LED_P12V_PSU_R1")
	)
	(segment
		(start 20.4216 -193.7766)
		(end 20.0152 -193.3702)
		(width 0.12954)
		(layer "In2.Cu")
		(net "LED_P12V_PSU_R1")
	)
	(segment
		(start 39.0144 -382.4224)
		(end 39.0144 -381.254)
		(width 0.12954)
		(layer "In2.Cu")
		(net "LED_P12V_PSU_R1")
	)
	(segment
		(start 22.3774 -193.7766)
		(end 20.4216 -193.7766)
		(width 0.12954)
		(layer "In2.Cu")
		(net "LED_P12V_PSU_R1")
	)
	(segment
		(start 23.0124 -255.8288)
		(end 23.0124 -253.8222)
		(width 0.12954)
		(layer "In2.Cu")
		(net "LED_P12V_PSU_R1")
	)
	(segment
		(start 32.385 -329.8698)
		(end 28.3464 -325.8312)
		(width 0.12954)
		(layer "In2.Cu")
		(net "LED_P12V_PSU_R1")
	)
	(segment
		(start 15.113 -189.4332)
		(end 15.113 -187.6298)
		(width 0.12954)
		(layer "In2.Cu")
		(net "LED_P12V_PSU_R1")
	)
	(segment
		(start 25.3238 -324.1802)
		(end 25.3238 -258.1402)
		(width 0.12954)
		(layer "In2.Cu")
		(net "LED_P12V_PSU_R1")
	)
	(segment
		(start 23.2664 -194.6656)
		(end 22.3774 -193.7766)
		(width 0.12954)
		(layer "In2.Cu")
		(net "LED_P12V_PSU_R1")
	)
	(segment
		(start 23.0124 -253.8222)
		(end 23.5712 -253.2634)
		(width 0.12954)
		(layer "In2.Cu")
		(net "LED_P12V_PSU_R1")
	)
	(segment
		(start 23.5712 -253.2634)
		(end 24.003 -253.2634)
		(width 0.12954)
		(layer "In2.Cu")
		(net "LED_P12V_PSU_R1")
	)
	(segment
		(start 20.0152 -191.2874)
		(end 19.2278 -190.5)
		(width 0.12954)
		(layer "In2.Cu")
		(net "LED_P12V_PSU_R1")
	)
	(segment
		(start 25.3238 -258.1402)
		(end 23.0124 -255.8288)
		(width 0.12954)
		(layer "In2.Cu")
		(net "LED_P12V_PSU_R1")
	)
	(segment
		(start 25.0698 -252.1966)
		(end 25.0698 -195.072)
		(width 0.12954)
		(layer "In2.Cu")
		(net "LED_P12V_PSU_R1")
	)
	(segment
		(start 20.0152 -193.3702)
		(end 20.0152 -191.2874)
		(width 0.12954)
		(layer "In2.Cu")
		(net "LED_P12V_PSU_R1")
	)
	(segment
		(start 39.0144 -381.254)
		(end 37.7444 -379.984)
		(width 0.12954)
		(layer "In2.Cu")
		(net "LED_P12V_PSU_R1")
	)
	(segment
		(start 28.3464 -325.8312)
		(end 26.9748 -325.8312)
		(width 0.12954)
		(layer "In2.Cu")
		(net "LED_P12V_PSU_R1")
	)
	(segment
		(start 24.003 -253.2634)
		(end 25.0698 -252.1966)
		(width 0.12954)
		(layer "In2.Cu")
		(net "LED_P12V_PSU_R1")
	)
	(segment
		(start 193.475864 -421.943276)
		(end 193.475864 -421.634158)
		(width 0.12954)
		(layer "In6.Cu")
		(net "LED_P12V_PSU_R1")
	)
	(segment
		(start 168.0972 -398.8562)
		(end 120.523 -398.8562)
		(width 0.12954)
		(layer "In6.Cu")
		(net "LED_P12V_PSU_R1")
	)
	(segment
		(start 169.645076 -400.404076)
		(end 168.0972 -398.8562)
		(width 0.12954)
		(layer "In6.Cu")
		(net "LED_P12V_PSU_R1")
	)
	(segment
		(start 174.445422 -399.702782)
		(end 173.744128 -400.404076)
		(width 0.12954)
		(layer "In6.Cu")
		(net "LED_P12V_PSU_R1")
	)
	(segment
		(start 118.745 -400.6342)
		(end 118.745 -403.2758)
		(width 0.12954)
		(layer "In6.Cu")
		(net "LED_P12V_PSU_R1")
	)
	(segment
		(start 120.523 -398.8562)
		(end 118.745 -400.6342)
		(width 0.12954)
		(layer "In6.Cu")
		(net "LED_P12V_PSU_R1")
	)
	(segment
		(start 173.744128 -400.404076)
		(end 169.645076 -400.404076)
		(width 0.12954)
		(layer "In6.Cu")
		(net "LED_P12V_PSU_R1")
	)
	(segment
		(start 178.950366 -413.097726)
		(end 177.038 -411.18536)
		(width 0.12954)
		(layer "In6.Cu")
		(net "LED_P12V_PSU_R1")
	)
	(segment
		(start 188.911992 -413.097726)
		(end 178.950366 -413.097726)
		(width 0.12954)
		(layer "In6.Cu")
		(net "LED_P12V_PSU_R1")
	)
	(segment
		(start 177.038 -400.685)
		(end 176.055782 -399.702782)
		(width 0.12954)
		(layer "In6.Cu")
		(net "LED_P12V_PSU_R1")
	)
	(segment
		(start 191.538352 -415.724086)
		(end 188.911992 -413.097726)
		(width 0.12954)
		(layer "In6.Cu")
		(net "LED_P12V_PSU_R1")
	)
	(segment
		(start 193.475864 -421.634158)
		(end 191.538352 -419.696646)
		(width 0.12954)
		(layer "In6.Cu")
		(net "LED_P12V_PSU_R1")
	)
	(segment
		(start 177.038 -411.18536)
		(end 177.038 -400.685)
		(width 0.12954)
		(layer "In6.Cu")
		(net "LED_P12V_PSU_R1")
	)
	(segment
		(start 191.538352 -419.696646)
		(end 191.538352 -415.724086)
		(width 0.12954)
		(layer "In6.Cu")
		(net "LED_P12V_PSU_R1")
	)
	(segment
		(start 118.745 -403.2758)
		(end 118.1862 -403.8346)
		(width 0.12954)
		(layer "In6.Cu")
		(net "LED_P12V_PSU_R1")
	)
	(segment
		(start 118.1862 -403.8346)
		(end 116.8908 -403.8346)
		(width 0.12954)
		(layer "In6.Cu")
		(net "LED_P12V_PSU_R1")
	)
	(segment
		(start 176.055782 -399.702782)
		(end 174.445422 -399.702782)
		(width 0.12954)
		(layer "In6.Cu")
		(net "LED_P12V_PSU_R1")
	)
	(segment
		(start 369.54206 -72.7456)
		(end 369.7478 -72.95134)
		(width 0.12954)
		(layer "F.Cu")
		(net "LED_P12V_AUX_R3")
	)
	(segment
		(start 368.7318 -72.9742)
		(end 368.9604 -72.7456)
		(width 0.12954)
		(layer "F.Cu")
		(net "LED_P12V_AUX_R3")
	)
	(segment
		(start 369.2906 -72.7456)
		(end 369.54206 -72.7456)
		(width 0.12954)
		(layer "F.Cu")
		(net "LED_P12V_AUX_R3")
	)
	(segment
		(start 368.7318 -73.94575)
		(end 368.7318 -72.9742)
		(width 0.12954)
		(layer "F.Cu")
		(net "LED_P12V_AUX_R3")
	)
	(segment
		(start 369.7478 -73.92035)
		(end 369.7224 -73.94575)
		(width 0.12954)
		(layer "F.Cu")
		(net "LED_P12V_AUX_R3")
	)
	(segment
		(start 369.7478 -72.95134)
		(end 369.7478 -73.92035)
		(width 0.12954)
		(layer "F.Cu")
		(net "LED_P12V_AUX_R3")
	)
	(segment
		(start 368.9604 -72.7456)
		(end 369.2906 -72.7456)
		(width 0.12954)
		(layer "F.Cu")
		(net "LED_P12V_AUX_R3")
	)
	(via
		(at 369.2906 -72.7456)
		(size 0.762)
		(drill 0.381)
		(layers "F.Cu" "B.Cu")
		(net "LED_P12V_AUX_R3")
	)
	(segment
		(start 368.7318 -75.836018)
		(end 368.6048 -75.963018)
		(width 0.12954)
		(layer "F.Cu")
		(net "LED_P12V_AUX_R2")
	)
	(segment
		(start 368.7318 -74.74585)
		(end 368.7318 -75.836018)
		(width 0.12954)
		(layer "F.Cu")
		(net "LED_P12V_AUX_R2")
	)
	(segment
		(start 367.8682 -75.963018)
		(end 367.7412 -75.836018)
		(width 0.12954)
		(layer "F.Cu")
		(net "LED_P12V_AUX_R2")
	)
	(segment
		(start 368.6048 -75.963018)
		(end 368.2238 -75.963018)
		(width 0.12954)
		(layer "F.Cu")
		(net "LED_P12V_AUX_R2")
	)
	(segment
		(start 367.7412 -75.836018)
		(end 367.7412 -74.74585)
		(width 0.12954)
		(layer "F.Cu")
		(net "LED_P12V_AUX_R2")
	)
	(segment
		(start 368.2238 -75.963018)
		(end 367.8682 -75.963018)
		(width 0.12954)
		(layer "F.Cu")
		(net "LED_P12V_AUX_R2")
	)
	(via
		(at 368.2238 -75.963018)
		(size 0.762)
		(drill 0.381)
		(layers "F.Cu" "B.Cu")
		(net "LED_P12V_AUX_R2")
	)
	(segment
		(start 367.5888 -73.558654)
		(end 367.7412 -73.711054)
		(width 0.12954)
		(layer "F.Cu")
		(net "LED_P12V_AUX_R1")
	)
	(segment
		(start 368.28222 -71.42226)
		(end 368.28222 -72.05218)
		(width 0.12954)
		(layer "F.Cu")
		(net "LED_P12V_AUX_R1")
	)
	(segment
		(start 368.28222 -72.05218)
		(end 367.5888 -72.7456)
		(width 0.12954)
		(layer "F.Cu")
		(net "LED_P12V_AUX_R1")
	)
	(segment
		(start 367.7412 -73.711054)
		(end 367.7412 -73.94575)
		(width 0.12954)
		(layer "F.Cu")
		(net "LED_P12V_AUX_R1")
	)
	(segment
		(start 367.5888 -72.7456)
		(end 367.5888 -73.558654)
		(width 0.12954)
		(layer "F.Cu")
		(net "LED_P12V_AUX_R1")
	)
	(via
		(at 367.5888 -72.7456)
		(size 0.762)
		(drill 0.381)
		(layers "F.Cu" "B.Cu")
		(net "LED_P12V_AUX_R1")
	)
	(segment
		(start 215.0618 -111.887)
		(end 215.0618 -111.1504)
		(width 0.12954)
		(layer "F.Cu")
		(net "IRQ_UV_DETECT_R2_N")
	)
	(segment
		(start 207.7466 -112.014)
		(end 207.7466 -109.7534)
		(width 0.12954)
		(layer "F.Cu")
		(net "IRQ_UV_DETECT_R2_N")
	)
	(segment
		(start 209.931 -109.22)
		(end 209.931 -108.694474)
		(width 0.12954)
		(layer "F.Cu")
		(net "IRQ_UV_DETECT_R2_N")
	)
	(segment
		(start 207.1624 -112.5982)
		(end 207.7466 -112.014)
		(width 0.12954)
		(layer "F.Cu")
		(net "IRQ_UV_DETECT_R2_N")
	)
	(segment
		(start 214.503 -113.2586)
		(end 214.10676 -112.86236)
		(width 0.12954)
		(layer "F.Cu")
		(net "IRQ_UV_DETECT_R2_N")
	)
	(segment
		(start 214.10676 -111.19104)
		(end 214.10676 -111.96701)
		(width 0.12954)
		(layer "F.Cu")
		(net "IRQ_UV_DETECT_R2_N")
	)
	(segment
		(start 210.3882 -108.237274)
		(end 210.3882 -107.81665)
		(width 0.12954)
		(layer "F.Cu")
		(net "IRQ_UV_DETECT_R2_N")
	)
	(segment
		(start 214.10676 -112.86236)
		(end 214.10676 -111.96701)
		(width 0.12954)
		(layer "F.Cu")
		(net "IRQ_UV_DETECT_R2_N")
	)
	(segment
		(start 209.7024 -115.4176)
		(end 207.5688 -115.4176)
		(width 0.12954)
		(layer "F.Cu")
		(net "IRQ_UV_DETECT_R2_N")
	)
	(segment
		(start 215.0618 -111.1504)
		(end 214.884 -110.9726)
		(width 0.12954)
		(layer "F.Cu")
		(net "IRQ_UV_DETECT_R2_N")
	)
	(segment
		(start 214.884 -110.9726)
		(end 214.3252 -110.9726)
		(width 0.12954)
		(layer "F.Cu")
		(net "IRQ_UV_DETECT_R2_N")
	)
	(segment
		(start 207.1624 -115.0112)
		(end 207.1624 -112.5982)
		(width 0.12954)
		(layer "F.Cu")
		(net "IRQ_UV_DETECT_R2_N")
	)
	(segment
		(start 215.25865 -112.08385)
		(end 215.0618 -111.887)
		(width 0.12954)
		(layer "F.Cu")
		(net "IRQ_UV_DETECT_R2_N")
	)
	(segment
		(start 207.7466 -109.7534)
		(end 208.1276 -109.3724)
		(width 0.12954)
		(layer "F.Cu")
		(net "IRQ_UV_DETECT_R2_N")
	)
	(segment
		(start 213.1314 -115.062)
		(end 210.058 -115.062)
		(width 0.12954)
		(layer "F.Cu")
		(net "IRQ_UV_DETECT_R2_N")
	)
	(segment
		(start 210.058 -115.062)
		(end 209.7024 -115.4176)
		(width 0.12954)
		(layer "F.Cu")
		(net "IRQ_UV_DETECT_R2_N")
	)
	(segment
		(start 214.503 -113.5634)
		(end 214.503 -113.6904)
		(width 0.12954)
		(layer "F.Cu")
		(net "IRQ_UV_DETECT_R2_N")
	)
	(segment
		(start 215.646 -112.08385)
		(end 215.25865 -112.08385)
		(width 0.12954)
		(layer "F.Cu")
		(net "IRQ_UV_DETECT_R2_N")
	)
	(segment
		(start 208.1276 -109.3724)
		(end 209.7786 -109.3724)
		(width 0.12954)
		(layer "F.Cu")
		(net "IRQ_UV_DETECT_R2_N")
	)
	(segment
		(start 214.503 -113.5634)
		(end 214.503 -113.2586)
		(width 0.12954)
		(layer "F.Cu")
		(net "IRQ_UV_DETECT_R2_N")
	)
	(segment
		(start 214.3252 -110.9726)
		(end 214.10676 -111.19104)
		(width 0.12954)
		(layer "F.Cu")
		(net "IRQ_UV_DETECT_R2_N")
	)
	(segment
		(start 207.5688 -115.4176)
		(end 207.1624 -115.0112)
		(width 0.12954)
		(layer "F.Cu")
		(net "IRQ_UV_DETECT_R2_N")
	)
	(segment
		(start 214.503 -113.6904)
		(end 213.1314 -115.062)
		(width 0.12954)
		(layer "F.Cu")
		(net "IRQ_UV_DETECT_R2_N")
	)
	(segment
		(start 209.7786 -109.3724)
		(end 209.931 -109.22)
		(width 0.12954)
		(layer "F.Cu")
		(net "IRQ_UV_DETECT_R2_N")
	)
	(segment
		(start 209.931 -108.694474)
		(end 210.3882 -108.237274)
		(width 0.12954)
		(layer "F.Cu")
		(net "IRQ_UV_DETECT_R2_N")
	)
	(via
		(at 214.503 -113.5634)
		(size 0.762)
		(drill 0.381)
		(layers "F.Cu" "B.Cu")
		(net "IRQ_UV_DETECT_R2_N")
	)
	(segment
		(start 180.555646 -119.375428)
		(end 180.955696 -119.775478)
		(width 0.12954)
		(layer "F.Cu")
		(net "IRQ_PVCCIN_CPU1_VRHOT_R_N")
	)
	(via
		(at 146.67738 -128.420368)
		(size 0.508)
		(drill 0.254)
		(layers "F.Cu" "B.Cu")
		(net "IRQ_PVCCIN_CPU1_VRHOT_R_N")
	)
	(via
		(at 38.72738 -125.827282)
		(size 0.508)
		(drill 0.254)
		(layers "F.Cu" "B.Cu")
		(net "IRQ_PVCCIN_CPU1_VRHOT_R_N")
	)
	(via
		(at 180.955696 -119.775478)
		(size 0.4572)
		(drill 0.254)
		(layers "F.Cu" "B.Cu")
		(net "IRQ_PVCCIN_CPU1_VRHOT_R_N")
	)
	(via
		(at 68.434458 -351.000822)
		(size 0.6604)
		(drill 0.3302)
		(layers "F.Cu" "B.Cu")
		(net "IRQ_PVCCIN_CPU1_VRHOT_R_N")
	)
	(segment
		(start 68.379848 -350.946212)
		(end 68.434458 -351.000822)
		(width 0.12954)
		(layer "B.Cu")
		(net "IRQ_PVCCIN_CPU1_VRHOT_R_N")
	)
	(segment
		(start 30.983936 -122.70359)
		(end 30.43174 -123.255786)
		(width 0.12954)
		(layer "B.Cu")
		(net "IRQ_PVCCIN_CPU1_VRHOT_R_N")
	)
	(segment
		(start 27.983434 -122.319288)
		(end 24.56434 -122.319288)
		(width 0.12954)
		(layer "B.Cu")
		(net "IRQ_PVCCIN_CPU1_VRHOT_R_N")
	)
	(segment
		(start 14.96568 -335.676748)
		(end 34.80308 -335.676748)
		(width 0.12954)
		(layer "B.Cu")
		(net "IRQ_PVCCIN_CPU1_VRHOT_R_N")
	)
	(segment
		(start 39.45128 -331.028548)
		(end 66.087244 -331.028548)
		(width 0.12954)
		(layer "B.Cu")
		(net "IRQ_PVCCIN_CPU1_VRHOT_R_N")
	)
	(segment
		(start 102.85603 -359.287318)
		(end 103.245666 -359.676954)
		(width 0.12954)
		(layer "B.Cu")
		(net "IRQ_PVCCIN_CPU1_VRHOT_R_N")
	)
	(segment
		(start 28.279852 -122.615706)
		(end 27.983434 -122.319288)
		(width 0.12954)
		(layer "B.Cu")
		(net "IRQ_PVCCIN_CPU1_VRHOT_R_N")
	)
	(segment
		(start 35.931856 -122.70359)
		(end 30.983936 -122.70359)
		(width 0.12954)
		(layer "B.Cu")
		(net "IRQ_PVCCIN_CPU1_VRHOT_R_N")
	)
	(segment
		(start 14.27988 -334.990948)
		(end 14.96568 -335.676748)
		(width 0.12954)
		(layer "B.Cu")
		(net "IRQ_PVCCIN_CPU1_VRHOT_R_N")
	)
	(segment
		(start 38.72738 -125.499114)
		(end 35.931856 -122.70359)
		(width 0.12954)
		(layer "B.Cu")
		(net "IRQ_PVCCIN_CPU1_VRHOT_R_N")
	)
	(segment
		(start 7.32028 -148.326348)
		(end 3.396996 -152.249632)
		(width 0.12954)
		(layer "B.Cu")
		(net "IRQ_PVCCIN_CPU1_VRHOT_R_N")
	)
	(segment
		(start 80.375506 -362.94187)
		(end 96.267778 -362.94187)
		(width 0.12954)
		(layer "B.Cu")
		(net "IRQ_PVCCIN_CPU1_VRHOT_R_N")
	)
	(segment
		(start 97.79762 -361.412028)
		(end 102.565454 -361.412028)
		(width 0.12954)
		(layer "B.Cu")
		(net "IRQ_PVCCIN_CPU1_VRHOT_R_N")
	)
	(segment
		(start 24.56434 -122.319288)
		(end 7.32028 -139.563348)
		(width 0.12954)
		(layer "B.Cu")
		(net "IRQ_PVCCIN_CPU1_VRHOT_R_N")
	)
	(segment
		(start 103.245666 -360.731816)
		(end 103.245666 -360.296968)
		(width 0.12954)
		(layer "B.Cu")
		(net "IRQ_PVCCIN_CPU1_VRHOT_R_N")
	)
	(segment
		(start 38.72738 -125.827282)
		(end 38.72738 -125.499114)
		(width 0.12954)
		(layer "B.Cu")
		(net "IRQ_PVCCIN_CPU1_VRHOT_R_N")
	)
	(segment
		(start 66.087244 -331.028548)
		(end 68.379848 -333.321152)
		(width 0.12954)
		(layer "B.Cu")
		(net "IRQ_PVCCIN_CPU1_VRHOT_R_N")
	)
	(segment
		(start 30.266132 -124.683266)
		(end 28.452318 -124.683266)
		(width 0.12954)
		(layer "B.Cu")
		(net "IRQ_PVCCIN_CPU1_VRHOT_R_N")
	)
	(segment
		(start 102.85603 -359.070148)
		(end 102.85603 -359.287318)
		(width 0.12954)
		(layer "B.Cu")
		(net "IRQ_PVCCIN_CPU1_VRHOT_R_N")
	)
	(segment
		(start 28.452318 -124.683266)
		(end 28.279852 -124.5108)
		(width 0.12954)
		(layer "B.Cu")
		(net "IRQ_PVCCIN_CPU1_VRHOT_R_N")
	)
	(segment
		(start 102.565454 -361.412028)
		(end 103.245666 -360.731816)
		(width 0.12954)
		(layer "B.Cu")
		(net "IRQ_PVCCIN_CPU1_VRHOT_R_N")
	)
	(segment
		(start 7.06628 -334.990948)
		(end 14.27988 -334.990948)
		(width 0.12954)
		(layer "B.Cu")
		(net "IRQ_PVCCIN_CPU1_VRHOT_R_N")
	)
	(segment
		(start 103.245666 -359.676954)
		(end 103.245666 -360.296968)
		(width 0.12954)
		(layer "B.Cu")
		(net "IRQ_PVCCIN_CPU1_VRHOT_R_N")
	)
	(segment
		(start 28.279852 -124.5108)
		(end 28.279852 -122.615706)
		(width 0.12954)
		(layer "B.Cu")
		(net "IRQ_PVCCIN_CPU1_VRHOT_R_N")
	)
	(segment
		(start 68.379848 -333.321152)
		(end 68.379848 -350.946212)
		(width 0.12954)
		(layer "B.Cu")
		(net "IRQ_PVCCIN_CPU1_VRHOT_R_N")
	)
	(segment
		(start 7.32028 -139.563348)
		(end 7.32028 -148.326348)
		(width 0.12954)
		(layer "B.Cu")
		(net "IRQ_PVCCIN_CPU1_VRHOT_R_N")
	)
	(segment
		(start 3.396996 -193.991992)
		(end 4.90728 -195.502276)
		(width 0.12954)
		(layer "B.Cu")
		(net "IRQ_PVCCIN_CPU1_VRHOT_R_N")
	)
	(segment
		(start 4.90728 -195.502276)
		(end 4.90728 -332.831948)
		(width 0.12954)
		(layer "B.Cu")
		(net "IRQ_PVCCIN_CPU1_VRHOT_R_N")
	)
	(segment
		(start 4.90728 -332.831948)
		(end 7.06628 -334.990948)
		(width 0.12954)
		(layer "B.Cu")
		(net "IRQ_PVCCIN_CPU1_VRHOT_R_N")
	)
	(segment
		(start 96.267778 -362.94187)
		(end 97.79762 -361.412028)
		(width 0.12954)
		(layer "B.Cu")
		(net "IRQ_PVCCIN_CPU1_VRHOT_R_N")
	)
	(segment
		(start 3.396996 -152.249632)
		(end 3.396996 -193.991992)
		(width 0.12954)
		(layer "B.Cu")
		(net "IRQ_PVCCIN_CPU1_VRHOT_R_N")
	)
	(segment
		(start 34.80308 -335.676748)
		(end 39.45128 -331.028548)
		(width 0.12954)
		(layer "B.Cu")
		(net "IRQ_PVCCIN_CPU1_VRHOT_R_N")
	)
	(segment
		(start 30.43174 -124.517658)
		(end 30.266132 -124.683266)
		(width 0.12954)
		(layer "B.Cu")
		(net "IRQ_PVCCIN_CPU1_VRHOT_R_N")
	)
	(segment
		(start 30.43174 -123.255786)
		(end 30.43174 -124.517658)
		(width 0.12954)
		(layer "B.Cu")
		(net "IRQ_PVCCIN_CPU1_VRHOT_R_N")
	)
	(segment
		(start 68.434458 -351.000822)
		(end 80.375506 -362.94187)
		(width 0.12954)
		(layer "B.Cu")
		(net "IRQ_PVCCIN_CPU1_VRHOT_R_N")
	)
	(segment
		(start 131.110736 -118.561612)
		(end 110.783624 -118.561612)
		(width 0.127)
		(layer "In13.Cu")
		(net "IRQ_PVCCIN_CPU1_VRHOT_R_N")
	)
	(segment
		(start 132.297932 -119.748808)
		(end 131.110736 -118.561612)
		(width 0.127)
		(layer "In13.Cu")
		(net "IRQ_PVCCIN_CPU1_VRHOT_R_N")
	)
	(segment
		(start 146.67738 -128.420368)
		(end 146.67738 -126.997968)
		(width 0.127)
		(layer "In13.Cu")
		(net "IRQ_PVCCIN_CPU1_VRHOT_R_N")
	)
	(segment
		(start 110.783624 -118.561612)
		(end 105.650284 -123.694952)
		(width 0.127)
		(layer "In13.Cu")
		(net "IRQ_PVCCIN_CPU1_VRHOT_R_N")
	)
	(segment
		(start 40.85971 -123.694952)
		(end 38.72738 -125.827282)
		(width 0.127)
		(layer "In13.Cu")
		(net "IRQ_PVCCIN_CPU1_VRHOT_R_N")
	)
	(segment
		(start 146.67738 -126.997968)
		(end 139.42822 -119.748808)
		(width 0.127)
		(layer "In13.Cu")
		(net "IRQ_PVCCIN_CPU1_VRHOT_R_N")
	)
	(segment
		(start 139.42822 -119.748808)
		(end 132.297932 -119.748808)
		(width 0.127)
		(layer "In13.Cu")
		(net "IRQ_PVCCIN_CPU1_VRHOT_R_N")
	)
	(segment
		(start 105.650284 -123.694952)
		(end 40.85971 -123.694952)
		(width 0.127)
		(layer "In13.Cu")
		(net "IRQ_PVCCIN_CPU1_VRHOT_R_N")
	)
	(segment
		(start 166.532052 -130.2258)
		(end 171.3738 -130.2258)
		(width 0.127)
		(layer "In15.Cu")
		(net "IRQ_PVCCIN_CPU1_VRHOT_R_N")
	)
	(segment
		(start 164.4396 -130.3274)
		(end 164.881052 -129.885948)
		(width 0.127)
		(layer "In15.Cu")
		(net "IRQ_PVCCIN_CPU1_VRHOT_R_N")
	)
	(segment
		(start 166.1922 -129.885948)
		(end 166.532052 -130.2258)
		(width 0.127)
		(layer "In15.Cu")
		(net "IRQ_PVCCIN_CPU1_VRHOT_R_N")
	)
	(segment
		(start 176.6316 -127.0762)
		(end 177.464974 -126.242826)
		(width 0.127)
		(layer "In15.Cu")
		(net "IRQ_PVCCIN_CPU1_VRHOT_R_N")
	)
	(segment
		(start 162.899852 -130.3274)
		(end 164.4396 -130.3274)
		(width 0.127)
		(layer "In15.Cu")
		(net "IRQ_PVCCIN_CPU1_VRHOT_R_N")
	)
	(segment
		(start 172.7454 -127.0762)
		(end 176.6316 -127.0762)
		(width 0.127)
		(layer "In15.Cu")
		(net "IRQ_PVCCIN_CPU1_VRHOT_R_N")
	)
	(segment
		(start 177.464974 -121.737374)
		(end 179.0319 -120.170448)
		(width 0.127)
		(layer "In15.Cu")
		(net "IRQ_PVCCIN_CPU1_VRHOT_R_N")
	)
	(segment
		(start 177.464974 -126.242826)
		(end 177.464974 -121.737374)
		(width 0.127)
		(layer "In15.Cu")
		(net "IRQ_PVCCIN_CPU1_VRHOT_R_N")
	)
	(segment
		(start 171.3738 -130.2258)
		(end 172.1612 -129.4384)
		(width 0.127)
		(layer "In15.Cu")
		(net "IRQ_PVCCIN_CPU1_VRHOT_R_N")
	)
	(segment
		(start 172.1612 -129.4384)
		(end 172.1612 -127.6604)
		(width 0.127)
		(layer "In15.Cu")
		(net "IRQ_PVCCIN_CPU1_VRHOT_R_N")
	)
	(segment
		(start 147.63496 -129.377948)
		(end 152.89022 -129.377948)
		(width 0.127)
		(layer "In15.Cu")
		(net "IRQ_PVCCIN_CPU1_VRHOT_R_N")
	)
	(segment
		(start 172.1612 -127.6604)
		(end 172.7454 -127.0762)
		(width 0.127)
		(layer "In15.Cu")
		(net "IRQ_PVCCIN_CPU1_VRHOT_R_N")
	)
	(segment
		(start 152.89022 -129.377948)
		(end 153.51252 -128.755648)
		(width 0.127)
		(layer "In15.Cu")
		(net "IRQ_PVCCIN_CPU1_VRHOT_R_N")
	)
	(segment
		(start 155.247848 -128.755648)
		(end 156.5656 -130.0734)
		(width 0.127)
		(layer "In15.Cu")
		(net "IRQ_PVCCIN_CPU1_VRHOT_R_N")
	)
	(segment
		(start 180.560726 -120.170448)
		(end 180.955696 -119.775478)
		(width 0.127)
		(layer "In15.Cu")
		(net "IRQ_PVCCIN_CPU1_VRHOT_R_N")
	)
	(segment
		(start 146.67738 -128.420368)
		(end 147.63496 -129.377948)
		(width 0.127)
		(layer "In15.Cu")
		(net "IRQ_PVCCIN_CPU1_VRHOT_R_N")
	)
	(segment
		(start 156.5656 -130.0734)
		(end 162.645852 -130.0734)
		(width 0.127)
		(layer "In15.Cu")
		(net "IRQ_PVCCIN_CPU1_VRHOT_R_N")
	)
	(segment
		(start 179.0319 -120.170448)
		(end 180.560726 -120.170448)
		(width 0.127)
		(layer "In15.Cu")
		(net "IRQ_PVCCIN_CPU1_VRHOT_R_N")
	)
	(segment
		(start 162.645852 -130.0734)
		(end 162.899852 -130.3274)
		(width 0.127)
		(layer "In15.Cu")
		(net "IRQ_PVCCIN_CPU1_VRHOT_R_N")
	)
	(segment
		(start 153.51252 -128.755648)
		(end 155.247848 -128.755648)
		(width 0.127)
		(layer "In15.Cu")
		(net "IRQ_PVCCIN_CPU1_VRHOT_R_N")
	)
	(segment
		(start 164.881052 -129.885948)
		(end 166.1922 -129.885948)
		(width 0.127)
		(layer "In15.Cu")
		(net "IRQ_PVCCIN_CPU1_VRHOT_R_N")
	)
	(segment
		(start 351.72269 -359.402888)
		(end 351.589848 -359.53573)
		(width 0.12954)
		(layer "F.Cu")
		(net "IRQ_PVCCIN_CPU0_VRHOT_R_N")
	)
	(segment
		(start 182.155592 -120.975374)
		(end 182.555642 -121.375424)
		(width 0.12954)
		(layer "F.Cu")
		(net "IRQ_PVCCIN_CPU0_VRHOT_R_N")
	)
	(segment
		(start 352.066098 -359.402888)
		(end 351.72269 -359.402888)
		(width 0.12954)
		(layer "F.Cu")
		(net "IRQ_PVCCIN_CPU0_VRHOT_R_N")
	)
	(segment
		(start 352.315272 -359.153714)
		(end 352.066098 -359.402888)
		(width 0.12954)
		(layer "F.Cu")
		(net "IRQ_PVCCIN_CPU0_VRHOT_R_N")
	)
	(via
		(at 182.555642 -121.375424)
		(size 0.4572)
		(drill 0.254)
		(layers "F.Cu" "B.Cu")
		(net "IRQ_PVCCIN_CPU0_VRHOT_R_N")
	)
	(via
		(at 352.315272 -359.153714)
		(size 0.508)
		(drill 0.254)
		(layers "F.Cu" "B.Cu")
		(net "IRQ_PVCCIN_CPU0_VRHOT_R_N")
	)
	(via
		(at 426.90288 -377.713748)
		(size 0.508)
		(drill 0.254)
		(layers "F.Cu" "B.Cu")
		(net "IRQ_PVCCIN_CPU0_VRHOT_R_N")
	)
	(via
		(at 435.89194 -135.288528)
		(size 0.508)
		(drill 0.254)
		(layers "F.Cu" "B.Cu")
		(net "IRQ_PVCCIN_CPU0_VRHOT_R_N")
	)
	(segment
		(start 352.315272 -359.153714)
		(end 351.718626 -359.153714)
		(width 0.12954)
		(layer "B.Cu")
		(net "IRQ_PVCCIN_CPU0_VRHOT_R_N")
	)
	(segment
		(start 351.718626 -359.153714)
		(end 351.66808 -359.103168)
		(width 0.12954)
		(layer "B.Cu")
		(net "IRQ_PVCCIN_CPU0_VRHOT_R_N")
	)
	(segment
		(start 426.90288 -377.713748)
		(end 432.025044 -377.713748)
		(width 0.127)
		(layer "In4.Cu")
		(net "IRQ_PVCCIN_CPU0_VRHOT_R_N")
	)
	(segment
		(start 435.151276 -374.587516)
		(end 435.151276 -363.213904)
		(width 0.127)
		(layer "In4.Cu")
		(net "IRQ_PVCCIN_CPU0_VRHOT_R_N")
	)
	(segment
		(start 435.151276 -363.213904)
		(end 465.46262 -332.90256)
		(width 0.127)
		(layer "In4.Cu")
		(net "IRQ_PVCCIN_CPU0_VRHOT_R_N")
	)
	(segment
		(start 432.025044 -377.713748)
		(end 435.151276 -374.587516)
		(width 0.127)
		(layer "In4.Cu")
		(net "IRQ_PVCCIN_CPU0_VRHOT_R_N")
	)
	(segment
		(start 453.60336 -162.954208)
		(end 453.60336 -138.532108)
		(width 0.127)
		(layer "In4.Cu")
		(net "IRQ_PVCCIN_CPU0_VRHOT_R_N")
	)
	(segment
		(start 450.35978 -135.288528)
		(end 435.89194 -135.288528)
		(width 0.127)
		(layer "In4.Cu")
		(net "IRQ_PVCCIN_CPU0_VRHOT_R_N")
	)
	(segment
		(start 465.46262 -174.813468)
		(end 453.60336 -162.954208)
		(width 0.127)
		(layer "In4.Cu")
		(net "IRQ_PVCCIN_CPU0_VRHOT_R_N")
	)
	(segment
		(start 465.46262 -332.90256)
		(end 465.46262 -174.813468)
		(width 0.127)
		(layer "In4.Cu")
		(net "IRQ_PVCCIN_CPU0_VRHOT_R_N")
	)
	(segment
		(start 453.60336 -138.532108)
		(end 450.35978 -135.288528)
		(width 0.127)
		(layer "In4.Cu")
		(net "IRQ_PVCCIN_CPU0_VRHOT_R_N")
	)
	(segment
		(start 354.646738 -369.10645)
		(end 366.645698 -381.10541)
		(width 0.127)
		(layer "In6.Cu")
		(net "IRQ_PVCCIN_CPU0_VRHOT_R_N")
	)
	(segment
		(start 352.49612 -362.212128)
		(end 353.582478 -363.298486)
		(width 0.127)
		(layer "In6.Cu")
		(net "IRQ_PVCCIN_CPU0_VRHOT_R_N")
	)
	(segment
		(start 394.750798 -383.32029)
		(end 405.18588 -383.32029)
		(width 0.127)
		(layer "In6.Cu")
		(net "IRQ_PVCCIN_CPU0_VRHOT_R_N")
	)
	(segment
		(start 352.49612 -361.488228)
		(end 352.49612 -362.212128)
		(width 0.127)
		(layer "In6.Cu")
		(net "IRQ_PVCCIN_CPU0_VRHOT_R_N")
	)
	(segment
		(start 353.582478 -363.298486)
		(end 353.582478 -365.79429)
		(width 0.127)
		(layer "In6.Cu")
		(net "IRQ_PVCCIN_CPU0_VRHOT_R_N")
	)
	(segment
		(start 353.331018 -359.33761)
		(end 353.331018 -360.65333)
		(width 0.127)
		(layer "In6.Cu")
		(net "IRQ_PVCCIN_CPU0_VRHOT_R_N")
	)
	(segment
		(start 392.535918 -381.10541)
		(end 394.750798 -383.32029)
		(width 0.127)
		(layer "In6.Cu")
		(net "IRQ_PVCCIN_CPU0_VRHOT_R_N")
	)
	(segment
		(start 366.645698 -381.10541)
		(end 392.535918 -381.10541)
		(width 0.127)
		(layer "In6.Cu")
		(net "IRQ_PVCCIN_CPU0_VRHOT_R_N")
	)
	(segment
		(start 409.941522 -378.564648)
		(end 405.18588 -383.32029)
		(width 0.127)
		(layer "In6.Cu")
		(net "IRQ_PVCCIN_CPU0_VRHOT_R_N")
	)
	(segment
		(start 426.90288 -377.713748)
		(end 426.05198 -378.564648)
		(width 0.127)
		(layer "In6.Cu")
		(net "IRQ_PVCCIN_CPU0_VRHOT_R_N")
	)
	(segment
		(start 353.147122 -359.153714)
		(end 353.331018 -359.33761)
		(width 0.127)
		(layer "In6.Cu")
		(net "IRQ_PVCCIN_CPU0_VRHOT_R_N")
	)
	(segment
		(start 354.646738 -366.85855)
		(end 354.646738 -369.10645)
		(width 0.127)
		(layer "In6.Cu")
		(net "IRQ_PVCCIN_CPU0_VRHOT_R_N")
	)
	(segment
		(start 352.315272 -359.153714)
		(end 353.147122 -359.153714)
		(width 0.127)
		(layer "In6.Cu")
		(net "IRQ_PVCCIN_CPU0_VRHOT_R_N")
	)
	(segment
		(start 353.582478 -365.79429)
		(end 354.646738 -366.85855)
		(width 0.127)
		(layer "In6.Cu")
		(net "IRQ_PVCCIN_CPU0_VRHOT_R_N")
	)
	(segment
		(start 426.05198 -378.564648)
		(end 409.941522 -378.564648)
		(width 0.127)
		(layer "In6.Cu")
		(net "IRQ_PVCCIN_CPU0_VRHOT_R_N")
	)
	(segment
		(start 353.331018 -360.65333)
		(end 352.49612 -361.488228)
		(width 0.127)
		(layer "In6.Cu")
		(net "IRQ_PVCCIN_CPU0_VRHOT_R_N")
	)
	(segment
		(start 249.19432 -126.815088)
		(end 251.34316 -124.666248)
		(width 0.127)
		(layer "In15.Cu")
		(net "IRQ_PVCCIN_CPU0_VRHOT_R_N")
	)
	(segment
		(start 194.027552 -130.149854)
		(end 194.246246 -130.368548)
		(width 0.127)
		(layer "In15.Cu")
		(net "IRQ_PVCCIN_CPU0_VRHOT_R_N")
	)
	(segment
		(start 187.19038 -126.604522)
		(end 189.328298 -126.604522)
		(width 0.127)
		(layer "In15.Cu")
		(net "IRQ_PVCCIN_CPU0_VRHOT_R_N")
	)
	(segment
		(start 198.77786 -129.553208)
		(end 200.377806 -129.553208)
		(width 0.127)
		(layer "In15.Cu")
		(net "IRQ_PVCCIN_CPU0_VRHOT_R_N")
	)
	(segment
		(start 189.328298 -126.604522)
		(end 192.87363 -130.149854)
		(width 0.127)
		(layer "In15.Cu")
		(net "IRQ_PVCCIN_CPU0_VRHOT_R_N")
	)
	(segment
		(start 232.05948 -123.256548)
		(end 232.50398 -123.701048)
		(width 0.127)
		(layer "In15.Cu")
		(net "IRQ_PVCCIN_CPU0_VRHOT_R_N")
	)
	(segment
		(start 182.555642 -121.375424)
		(end 182.555642 -121.969784)
		(width 0.127)
		(layer "In15.Cu")
		(net "IRQ_PVCCIN_CPU0_VRHOT_R_N")
	)
	(segment
		(start 242.6589 -124.920248)
		(end 244.55374 -126.815088)
		(width 0.127)
		(layer "In15.Cu")
		(net "IRQ_PVCCIN_CPU0_VRHOT_R_N")
	)
	(segment
		(start 194.246246 -130.368548)
		(end 197.96252 -130.368548)
		(width 0.127)
		(layer "In15.Cu")
		(net "IRQ_PVCCIN_CPU0_VRHOT_R_N")
	)
	(segment
		(start 205.45298 -128.146048)
		(end 205.89748 -128.590548)
		(width 0.127)
		(layer "In15.Cu")
		(net "IRQ_PVCCIN_CPU0_VRHOT_R_N")
	)
	(segment
		(start 229.29088 -123.256548)
		(end 232.05948 -123.256548)
		(width 0.127)
		(layer "In15.Cu")
		(net "IRQ_PVCCIN_CPU0_VRHOT_R_N")
	)
	(segment
		(start 433.91074 -131.793488)
		(end 433.91074 -133.307328)
		(width 0.127)
		(layer "In15.Cu")
		(net "IRQ_PVCCIN_CPU0_VRHOT_R_N")
	)
	(segment
		(start 227.62718 -124.564648)
		(end 227.98278 -124.564648)
		(width 0.127)
		(layer "In15.Cu")
		(net "IRQ_PVCCIN_CPU0_VRHOT_R_N")
	)
	(segment
		(start 201.784966 -128.146048)
		(end 205.45298 -128.146048)
		(width 0.127)
		(layer "In15.Cu")
		(net "IRQ_PVCCIN_CPU0_VRHOT_R_N")
	)
	(segment
		(start 213.383114 -128.902714)
		(end 215.876886 -128.902714)
		(width 0.127)
		(layer "In15.Cu")
		(net "IRQ_PVCCIN_CPU0_VRHOT_R_N")
	)
	(segment
		(start 251.34316 -124.666248)
		(end 410.99994 -124.666248)
		(width 0.127)
		(layer "In15.Cu")
		(net "IRQ_PVCCIN_CPU0_VRHOT_R_N")
	)
	(segment
		(start 225.232214 -126.379478)
		(end 225.81235 -126.379478)
		(width 0.127)
		(layer "In15.Cu")
		(net "IRQ_PVCCIN_CPU0_VRHOT_R_N")
	)
	(segment
		(start 232.50398 -123.701048)
		(end 237.39602 -123.701048)
		(width 0.127)
		(layer "In15.Cu")
		(net "IRQ_PVCCIN_CPU0_VRHOT_R_N")
	)
	(segment
		(start 220.1164 -124.6632)
		(end 223.515936 -124.6632)
		(width 0.127)
		(layer "In15.Cu")
		(net "IRQ_PVCCIN_CPU0_VRHOT_R_N")
	)
	(segment
		(start 213.070948 -128.590548)
		(end 213.383114 -128.902714)
		(width 0.127)
		(layer "In15.Cu")
		(net "IRQ_PVCCIN_CPU0_VRHOT_R_N")
	)
	(segment
		(start 244.55374 -126.815088)
		(end 249.19432 -126.815088)
		(width 0.127)
		(layer "In15.Cu")
		(net "IRQ_PVCCIN_CPU0_VRHOT_R_N")
	)
	(segment
		(start 200.377806 -129.553208)
		(end 201.784966 -128.146048)
		(width 0.127)
		(layer "In15.Cu")
		(net "IRQ_PVCCIN_CPU0_VRHOT_R_N")
	)
	(segment
		(start 227.98278 -124.564648)
		(end 229.29088 -123.256548)
		(width 0.127)
		(layer "In15.Cu")
		(net "IRQ_PVCCIN_CPU0_VRHOT_R_N")
	)
	(segment
		(start 431.4444 -129.327148)
		(end 433.91074 -131.793488)
		(width 0.127)
		(layer "In15.Cu")
		(net "IRQ_PVCCIN_CPU0_VRHOT_R_N")
	)
	(segment
		(start 410.99994 -124.666248)
		(end 415.66084 -129.327148)
		(width 0.127)
		(layer "In15.Cu")
		(net "IRQ_PVCCIN_CPU0_VRHOT_R_N")
	)
	(segment
		(start 237.39602 -123.701048)
		(end 238.61522 -124.920248)
		(width 0.127)
		(layer "In15.Cu")
		(net "IRQ_PVCCIN_CPU0_VRHOT_R_N")
	)
	(segment
		(start 197.96252 -130.368548)
		(end 198.77786 -129.553208)
		(width 0.127)
		(layer "In15.Cu")
		(net "IRQ_PVCCIN_CPU0_VRHOT_R_N")
	)
	(segment
		(start 215.876886 -128.902714)
		(end 220.1164 -124.6632)
		(width 0.127)
		(layer "In15.Cu")
		(net "IRQ_PVCCIN_CPU0_VRHOT_R_N")
	)
	(segment
		(start 433.91074 -133.307328)
		(end 435.89194 -135.288528)
		(width 0.127)
		(layer "In15.Cu")
		(net "IRQ_PVCCIN_CPU0_VRHOT_R_N")
	)
	(segment
		(start 205.89748 -128.590548)
		(end 213.070948 -128.590548)
		(width 0.127)
		(layer "In15.Cu")
		(net "IRQ_PVCCIN_CPU0_VRHOT_R_N")
	)
	(segment
		(start 182.555642 -121.969784)
		(end 187.19038 -126.604522)
		(width 0.127)
		(layer "In15.Cu")
		(net "IRQ_PVCCIN_CPU0_VRHOT_R_N")
	)
	(segment
		(start 415.66084 -129.327148)
		(end 431.4444 -129.327148)
		(width 0.127)
		(layer "In15.Cu")
		(net "IRQ_PVCCIN_CPU0_VRHOT_R_N")
	)
	(segment
		(start 192.87363 -130.149854)
		(end 194.027552 -130.149854)
		(width 0.127)
		(layer "In15.Cu")
		(net "IRQ_PVCCIN_CPU0_VRHOT_R_N")
	)
	(segment
		(start 238.61522 -124.920248)
		(end 242.6589 -124.920248)
		(width 0.127)
		(layer "In15.Cu")
		(net "IRQ_PVCCIN_CPU0_VRHOT_R_N")
	)
	(segment
		(start 223.515936 -124.6632)
		(end 225.232214 -126.379478)
		(width 0.127)
		(layer "In15.Cu")
		(net "IRQ_PVCCIN_CPU0_VRHOT_R_N")
	)
	(segment
		(start 225.81235 -126.379478)
		(end 227.62718 -124.564648)
		(width 0.127)
		(layer "In15.Cu")
		(net "IRQ_PVCCIN_CPU0_VRHOT_R_N")
	)
	(segment
		(start 52.8828 -125.35154)
		(end 46.08576 -125.35154)
		(width 0.12954)
		(layer "F.Cu")
		(net "IRQ_PVCCFA_CPU1_VRHOT_R_N")
	)
	(segment
		(start 176.937924 -122.423428)
		(end 176.937924 -125.616462)
		(width 0.12954)
		(layer "F.Cu")
		(net "IRQ_PVCCFA_CPU1_VRHOT_R_N")
	)
	(segment
		(start 38.72738 -127.708152)
		(end 38.23335 -128.202182)
		(width 0.12954)
		(layer "F.Cu")
		(net "IRQ_PVCCFA_CPU1_VRHOT_R_N")
	)
	(segment
		(start 39.764208 -127.708152)
		(end 38.72738 -127.708152)
		(width 0.12954)
		(layer "F.Cu")
		(net "IRQ_PVCCFA_CPU1_VRHOT_R_N")
	)
	(segment
		(start 37.804598 -128.202182)
		(end 37.347398 -128.659382)
		(width 0.12954)
		(layer "F.Cu")
		(net "IRQ_PVCCFA_CPU1_VRHOT_R_N")
	)
	(segment
		(start 176.555654 -121.775474)
		(end 176.555654 -122.041158)
		(width 0.12954)
		(layer "F.Cu")
		(net "IRQ_PVCCFA_CPU1_VRHOT_R_N")
	)
	(segment
		(start 176.595278 -126.981204)
		(end 176.595278 -127.977138)
		(width 0.12954)
		(layer "F.Cu")
		(net "IRQ_PVCCFA_CPU1_VRHOT_R_N")
	)
	(segment
		(start 41.28262 -126.18974)
		(end 39.764208 -127.708152)
		(width 0.12954)
		(layer "F.Cu")
		(net "IRQ_PVCCFA_CPU1_VRHOT_R_N")
	)
	(segment
		(start 176.937924 -125.616462)
		(end 177.10658 -125.785118)
		(width 0.12954)
		(layer "F.Cu")
		(net "IRQ_PVCCFA_CPU1_VRHOT_R_N")
	)
	(segment
		(start 177.10658 -126.469902)
		(end 176.595278 -126.981204)
		(width 0.12954)
		(layer "F.Cu")
		(net "IRQ_PVCCFA_CPU1_VRHOT_R_N")
	)
	(segment
		(start 45.24756 -126.18974)
		(end 41.28262 -126.18974)
		(width 0.12954)
		(layer "F.Cu")
		(net "IRQ_PVCCFA_CPU1_VRHOT_R_N")
	)
	(segment
		(start 176.555654 -122.041158)
		(end 176.937924 -122.423428)
		(width 0.12954)
		(layer "F.Cu")
		(net "IRQ_PVCCFA_CPU1_VRHOT_R_N")
	)
	(segment
		(start 177.10658 -125.785118)
		(end 177.10658 -126.469902)
		(width 0.12954)
		(layer "F.Cu")
		(net "IRQ_PVCCFA_CPU1_VRHOT_R_N")
	)
	(segment
		(start 46.08576 -125.35154)
		(end 45.24756 -126.18974)
		(width 0.12954)
		(layer "F.Cu")
		(net "IRQ_PVCCFA_CPU1_VRHOT_R_N")
	)
	(segment
		(start 38.23335 -128.202182)
		(end 37.804598 -128.202182)
		(width 0.12954)
		(layer "F.Cu")
		(net "IRQ_PVCCFA_CPU1_VRHOT_R_N")
	)
	(via
		(at 159.18688 -122.65152)
		(size 0.508)
		(drill 0.254)
		(layers "F.Cu" "B.Cu")
		(net "IRQ_PVCCFA_CPU1_VRHOT_R_N")
	)
	(via
		(at 176.595278 -127.977138)
		(size 0.508)
		(drill 0.254)
		(layers "F.Cu" "B.Cu")
		(net "IRQ_PVCCFA_CPU1_VRHOT_R_N")
	)
	(via
		(at 176.595278 -126.981204)
		(size 0.762)
		(drill 0.381)
		(layers "F.Cu" "B.Cu")
		(net "IRQ_PVCCFA_CPU1_VRHOT_R_N")
	)
	(via
		(at 52.8828 -125.35154)
		(size 0.508)
		(drill 0.254)
		(layers "F.Cu" "B.Cu")
		(net "IRQ_PVCCFA_CPU1_VRHOT_R_N")
	)
	(segment
		(start 160.6931 -135.29056)
		(end 159.18688 -133.78434)
		(width 0.12954)
		(layer "B.Cu")
		(net "IRQ_PVCCFA_CPU1_VRHOT_R_N")
	)
	(segment
		(start 169.45356 -134.60222)
		(end 168.76522 -135.29056)
		(width 0.12954)
		(layer "B.Cu")
		(net "IRQ_PVCCFA_CPU1_VRHOT_R_N")
	)
	(segment
		(start 168.76522 -135.29056)
		(end 160.6931 -135.29056)
		(width 0.12954)
		(layer "B.Cu")
		(net "IRQ_PVCCFA_CPU1_VRHOT_R_N")
	)
	(segment
		(start 175.35652 -126.73838)
		(end 171.58462 -126.73838)
		(width 0.12954)
		(layer "B.Cu")
		(net "IRQ_PVCCFA_CPU1_VRHOT_R_N")
	)
	(segment
		(start 176.595278 -127.977138)
		(end 175.35652 -126.73838)
		(width 0.12954)
		(layer "B.Cu")
		(net "IRQ_PVCCFA_CPU1_VRHOT_R_N")
	)
	(segment
		(start 169.85996 -132.1562)
		(end 169.45356 -132.5626)
		(width 0.12954)
		(layer "B.Cu")
		(net "IRQ_PVCCFA_CPU1_VRHOT_R_N")
	)
	(segment
		(start 169.45356 -132.5626)
		(end 169.45356 -134.60222)
		(width 0.12954)
		(layer "B.Cu")
		(net "IRQ_PVCCFA_CPU1_VRHOT_R_N")
	)
	(segment
		(start 170.83532 -130.04038)
		(end 169.85996 -131.01574)
		(width 0.12954)
		(layer "B.Cu")
		(net "IRQ_PVCCFA_CPU1_VRHOT_R_N")
	)
	(segment
		(start 170.83532 -127.48768)
		(end 170.83532 -130.04038)
		(width 0.12954)
		(layer "B.Cu")
		(net "IRQ_PVCCFA_CPU1_VRHOT_R_N")
	)
	(segment
		(start 171.58462 -126.73838)
		(end 170.83532 -127.48768)
		(width 0.12954)
		(layer "B.Cu")
		(net "IRQ_PVCCFA_CPU1_VRHOT_R_N")
	)
	(segment
		(start 169.85996 -131.01574)
		(end 169.85996 -132.1562)
		(width 0.12954)
		(layer "B.Cu")
		(net "IRQ_PVCCFA_CPU1_VRHOT_R_N")
	)
	(segment
		(start 159.18688 -133.78434)
		(end 159.18688 -122.65152)
		(width 0.12954)
		(layer "B.Cu")
		(net "IRQ_PVCCFA_CPU1_VRHOT_R_N")
	)
	(segment
		(start 148.74748 -120.73128)
		(end 148.34108 -120.73128)
		(width 0.127)
		(layer "In6.Cu")
		(net "IRQ_PVCCFA_CPU1_VRHOT_R_N")
	)
	(segment
		(start 97.4471 -123.32716)
		(end 95.42272 -125.35154)
		(width 0.127)
		(layer "In6.Cu")
		(net "IRQ_PVCCFA_CPU1_VRHOT_R_N")
	)
	(segment
		(start 137.32002 -123.88088)
		(end 134.61238 -121.17324)
		(width 0.127)
		(layer "In6.Cu")
		(net "IRQ_PVCCFA_CPU1_VRHOT_R_N")
	)
	(segment
		(start 106.31932 -123.32716)
		(end 97.4471 -123.32716)
		(width 0.127)
		(layer "In6.Cu")
		(net "IRQ_PVCCFA_CPU1_VRHOT_R_N")
	)
	(segment
		(start 147.69592 -121.37644)
		(end 147.69592 -122.04446)
		(width 0.127)
		(layer "In6.Cu")
		(net "IRQ_PVCCFA_CPU1_VRHOT_R_N")
	)
	(segment
		(start 158.64586 -123.19254)
		(end 154.0129 -123.19254)
		(width 0.127)
		(layer "In6.Cu")
		(net "IRQ_PVCCFA_CPU1_VRHOT_R_N")
	)
	(segment
		(start 133.0071 -118.32336)
		(end 128.59512 -118.32336)
		(width 0.127)
		(layer "In6.Cu")
		(net "IRQ_PVCCFA_CPU1_VRHOT_R_N")
	)
	(segment
		(start 134.61238 -121.17324)
		(end 134.61238 -119.92864)
		(width 0.127)
		(layer "In6.Cu")
		(net "IRQ_PVCCFA_CPU1_VRHOT_R_N")
	)
	(segment
		(start 153.41092 -122.59056)
		(end 150.60676 -122.59056)
		(width 0.127)
		(layer "In6.Cu")
		(net "IRQ_PVCCFA_CPU1_VRHOT_R_N")
	)
	(segment
		(start 154.0129 -123.19254)
		(end 153.41092 -122.59056)
		(width 0.127)
		(layer "In6.Cu")
		(net "IRQ_PVCCFA_CPU1_VRHOT_R_N")
	)
	(segment
		(start 95.42272 -125.35154)
		(end 52.8828 -125.35154)
		(width 0.127)
		(layer "In6.Cu")
		(net "IRQ_PVCCFA_CPU1_VRHOT_R_N")
	)
	(segment
		(start 112.00638 -117.6401)
		(end 106.31932 -123.32716)
		(width 0.127)
		(layer "In6.Cu")
		(net "IRQ_PVCCFA_CPU1_VRHOT_R_N")
	)
	(segment
		(start 150.60676 -122.59056)
		(end 148.74748 -120.73128)
		(width 0.127)
		(layer "In6.Cu")
		(net "IRQ_PVCCFA_CPU1_VRHOT_R_N")
	)
	(segment
		(start 148.34108 -120.73128)
		(end 147.69592 -121.37644)
		(width 0.127)
		(layer "In6.Cu")
		(net "IRQ_PVCCFA_CPU1_VRHOT_R_N")
	)
	(segment
		(start 145.8595 -123.88088)
		(end 137.32002 -123.88088)
		(width 0.127)
		(layer "In6.Cu")
		(net "IRQ_PVCCFA_CPU1_VRHOT_R_N")
	)
	(segment
		(start 159.18688 -122.65152)
		(end 158.64586 -123.19254)
		(width 0.127)
		(layer "In6.Cu")
		(net "IRQ_PVCCFA_CPU1_VRHOT_R_N")
	)
	(segment
		(start 147.69592 -122.04446)
		(end 145.8595 -123.88088)
		(width 0.127)
		(layer "In6.Cu")
		(net "IRQ_PVCCFA_CPU1_VRHOT_R_N")
	)
	(segment
		(start 128.59512 -118.32336)
		(end 127.91186 -117.6401)
		(width 0.127)
		(layer "In6.Cu")
		(net "IRQ_PVCCFA_CPU1_VRHOT_R_N")
	)
	(segment
		(start 127.91186 -117.6401)
		(end 112.00638 -117.6401)
		(width 0.127)
		(layer "In6.Cu")
		(net "IRQ_PVCCFA_CPU1_VRHOT_R_N")
	)
	(segment
		(start 134.61238 -119.92864)
		(end 133.0071 -118.32336)
		(width 0.127)
		(layer "In6.Cu")
		(net "IRQ_PVCCFA_CPU1_VRHOT_R_N")
	)
	(segment
		(start 435.0258 -130.556)
		(end 435.0258 -132.8674)
		(width 0.12954)
		(layer "F.Cu")
		(net "IRQ_PVCCFA_CPU0_VRHOT_R_N")
	)
	(segment
		(start 434.318918 -129.849118)
		(end 435.0258 -130.556)
		(width 0.12954)
		(layer "F.Cu")
		(net "IRQ_PVCCFA_CPU0_VRHOT_R_N")
	)
	(segment
		(start 432.93284 -135.029702)
		(end 432.791616 -135.029702)
		(width 0.12954)
		(layer "F.Cu")
		(net "IRQ_PVCCFA_CPU0_VRHOT_R_N")
	)
	(segment
		(start 435.0258 -132.8674)
		(end 432.93284 -134.96036)
		(width 0.12954)
		(layer "F.Cu")
		(net "IRQ_PVCCFA_CPU0_VRHOT_R_N")
	)
	(segment
		(start 431.79111 -136.030208)
		(end 431.32756 -136.030208)
		(width 0.12954)
		(layer "F.Cu")
		(net "IRQ_PVCCFA_CPU0_VRHOT_R_N")
	)
	(segment
		(start 334.5434 -140.6906)
		(end 334.5434 -137.3632)
		(width 0.12954)
		(layer "F.Cu")
		(net "IRQ_PVCCFA_CPU0_VRHOT_R_N")
	)
	(segment
		(start 339.4964 -132.4102)
		(end 410.2354 -132.4102)
		(width 0.12954)
		(layer "F.Cu")
		(net "IRQ_PVCCFA_CPU0_VRHOT_R_N")
	)
	(segment
		(start 413.0548 -129.5908)
		(end 431.9524 -129.5908)
		(width 0.12954)
		(layer "F.Cu")
		(net "IRQ_PVCCFA_CPU0_VRHOT_R_N")
	)
	(segment
		(start 431.000154 -135.702802)
		(end 431.000154 -135.510778)
		(width 0.12954)
		(layer "F.Cu")
		(net "IRQ_PVCCFA_CPU0_VRHOT_R_N")
	)
	(segment
		(start 431.32756 -136.030208)
		(end 431.000154 -135.702802)
		(width 0.12954)
		(layer "F.Cu")
		(net "IRQ_PVCCFA_CPU0_VRHOT_R_N")
	)
	(segment
		(start 334.5434 -137.3632)
		(end 339.4964 -132.4102)
		(width 0.12954)
		(layer "F.Cu")
		(net "IRQ_PVCCFA_CPU0_VRHOT_R_N")
	)
	(segment
		(start 410.2354 -132.4102)
		(end 413.0548 -129.5908)
		(width 0.12954)
		(layer "F.Cu")
		(net "IRQ_PVCCFA_CPU0_VRHOT_R_N")
	)
	(segment
		(start 431.9524 -129.5908)
		(end 432.210718 -129.849118)
		(width 0.12954)
		(layer "F.Cu")
		(net "IRQ_PVCCFA_CPU0_VRHOT_R_N")
	)
	(segment
		(start 432.210718 -129.849118)
		(end 434.318918 -129.849118)
		(width 0.12954)
		(layer "F.Cu")
		(net "IRQ_PVCCFA_CPU0_VRHOT_R_N")
	)
	(segment
		(start 176.555654 -120.975374)
		(end 176.155604 -121.375424)
		(width 0.12954)
		(layer "F.Cu")
		(net "IRQ_PVCCFA_CPU0_VRHOT_R_N")
	)
	(segment
		(start 432.93284 -134.96036)
		(end 432.93284 -135.029702)
		(width 0.12954)
		(layer "F.Cu")
		(net "IRQ_PVCCFA_CPU0_VRHOT_R_N")
	)
	(segment
		(start 432.791616 -135.029702)
		(end 431.79111 -136.030208)
		(width 0.12954)
		(layer "F.Cu")
		(net "IRQ_PVCCFA_CPU0_VRHOT_R_N")
	)
	(via
		(at 160.782 -129.2098)
		(size 0.508)
		(drill 0.254)
		(layers "F.Cu" "B.Cu")
		(net "IRQ_PVCCFA_CPU0_VRHOT_R_N")
	)
	(via
		(at 250.5456 -127.8128)
		(size 0.508)
		(drill 0.254)
		(layers "F.Cu" "B.Cu")
		(net "IRQ_PVCCFA_CPU0_VRHOT_R_N")
	)
	(via
		(at 334.5434 -140.6906)
		(size 0.508)
		(drill 0.254)
		(layers "F.Cu" "B.Cu")
		(net "IRQ_PVCCFA_CPU0_VRHOT_R_N")
	)
	(via
		(at 176.155604 -121.375424)
		(size 0.4572)
		(drill 0.254)
		(layers "F.Cu" "B.Cu")
		(net "IRQ_PVCCFA_CPU0_VRHOT_R_N")
	)
	(via
		(at 158.242 -138.9126)
		(size 0.508)
		(drill 0.254)
		(layers "F.Cu" "B.Cu")
		(net "IRQ_PVCCFA_CPU0_VRHOT_R_N")
	)
	(segment
		(start 250.5456 -127.8128)
		(end 256.1082 -127.8128)
		(width 0.12954)
		(layer "B.Cu")
		(net "IRQ_PVCCFA_CPU0_VRHOT_R_N")
	)
	(segment
		(start 277.7744 -126.238)
		(end 280.6446 -129.1082)
		(width 0.12954)
		(layer "B.Cu")
		(net "IRQ_PVCCFA_CPU0_VRHOT_R_N")
	)
	(segment
		(start 257.683 -126.238)
		(end 277.7744 -126.238)
		(width 0.12954)
		(layer "B.Cu")
		(net "IRQ_PVCCFA_CPU0_VRHOT_R_N")
	)
	(segment
		(start 256.1082 -127.8128)
		(end 257.683 -126.238)
		(width 0.12954)
		(layer "B.Cu")
		(net "IRQ_PVCCFA_CPU0_VRHOT_R_N")
	)
	(segment
		(start 280.6446 -129.1082)
		(end 304.2666 -129.1082)
		(width 0.12954)
		(layer "B.Cu")
		(net "IRQ_PVCCFA_CPU0_VRHOT_R_N")
	)
	(segment
		(start 318.196214 -134.7978)
		(end 332.422754 -140.6906)
		(width 0.12954)
		(layer "B.Cu")
		(net "IRQ_PVCCFA_CPU0_VRHOT_R_N")
	)
	(segment
		(start 309.9562 -134.7978)
		(end 318.196214 -134.7978)
		(width 0.12954)
		(layer "B.Cu")
		(net "IRQ_PVCCFA_CPU0_VRHOT_R_N")
	)
	(segment
		(start 304.2666 -129.1082)
		(end 309.9562 -134.7978)
		(width 0.12954)
		(layer "B.Cu")
		(net "IRQ_PVCCFA_CPU0_VRHOT_R_N")
	)
	(segment
		(start 332.422754 -140.6906)
		(end 334.5434 -140.6906)
		(width 0.12954)
		(layer "B.Cu")
		(net "IRQ_PVCCFA_CPU0_VRHOT_R_N")
	)
	(segment
		(start 160.782 -129.2098)
		(end 160.2232 -128.651)
		(width 0.127)
		(layer "In11.Cu")
		(net "IRQ_PVCCFA_CPU0_VRHOT_R_N")
	)
	(segment
		(start 160.2232 -128.651)
		(end 159.5374 -128.651)
		(width 0.127)
		(layer "In11.Cu")
		(net "IRQ_PVCCFA_CPU0_VRHOT_R_N")
	)
	(segment
		(start 159.5374 -128.651)
		(end 158.242 -129.9464)
		(width 0.127)
		(layer "In11.Cu")
		(net "IRQ_PVCCFA_CPU0_VRHOT_R_N")
	)
	(segment
		(start 158.242 -129.9464)
		(end 158.242 -138.9126)
		(width 0.127)
		(layer "In11.Cu")
		(net "IRQ_PVCCFA_CPU0_VRHOT_R_N")
	)
	(segment
		(start 210.6168 -140.081)
		(end 213.2584 -137.4394)
		(width 0.127)
		(layer "In15.Cu")
		(net "IRQ_PVCCFA_CPU0_VRHOT_R_N")
	)
	(segment
		(start 176.911 -123.3932)
		(end 176.911 -122.3264)
		(width 0.127)
		(layer "In15.Cu")
		(net "IRQ_PVCCFA_CPU0_VRHOT_R_N")
	)
	(segment
		(start 233.756708 -137.511028)
		(end 247.12295 -137.511028)
		(width 0.127)
		(layer "In15.Cu")
		(net "IRQ_PVCCFA_CPU0_VRHOT_R_N")
	)
	(segment
		(start 168.8338 -129.8448)
		(end 169.2656 -129.413)
		(width 0.127)
		(layer "In15.Cu")
		(net "IRQ_PVCCFA_CPU0_VRHOT_R_N")
	)
	(segment
		(start 221.4118 -137.4394)
		(end 224.45726 -134.39394)
		(width 0.127)
		(layer "In15.Cu")
		(net "IRQ_PVCCFA_CPU0_VRHOT_R_N")
	)
	(segment
		(start 166.2938 -129.2098)
		(end 166.9288 -129.8448)
		(width 0.127)
		(layer "In15.Cu")
		(net "IRQ_PVCCFA_CPU0_VRHOT_R_N")
	)
	(segment
		(start 250.855734 -128.122934)
		(end 250.5456 -127.8128)
		(width 0.127)
		(layer "In15.Cu")
		(net "IRQ_PVCCFA_CPU0_VRHOT_R_N")
	)
	(segment
		(start 164.719 -129.2098)
		(end 166.2938 -129.2098)
		(width 0.127)
		(layer "In15.Cu")
		(net "IRQ_PVCCFA_CPU0_VRHOT_R_N")
	)
	(segment
		(start 175.133 -124.1806)
		(end 176.1236 -124.1806)
		(width 0.127)
		(layer "In15.Cu")
		(net "IRQ_PVCCFA_CPU0_VRHOT_R_N")
	)
	(segment
		(start 176.155604 -121.571004)
		(end 176.155604 -121.375424)
		(width 0.127)
		(layer "In15.Cu")
		(net "IRQ_PVCCFA_CPU0_VRHOT_R_N")
	)
	(segment
		(start 166.9288 -129.8448)
		(end 168.8338 -129.8448)
		(width 0.127)
		(layer "In15.Cu")
		(net "IRQ_PVCCFA_CPU0_VRHOT_R_N")
	)
	(segment
		(start 170.2308 -129.413)
		(end 170.8404 -128.8034)
		(width 0.127)
		(layer "In15.Cu")
		(net "IRQ_PVCCFA_CPU0_VRHOT_R_N")
	)
	(segment
		(start 224.45726 -134.39394)
		(end 230.63962 -134.39394)
		(width 0.127)
		(layer "In15.Cu")
		(net "IRQ_PVCCFA_CPU0_VRHOT_R_N")
	)
	(segment
		(start 230.63962 -134.39394)
		(end 233.756708 -137.511028)
		(width 0.127)
		(layer "In15.Cu")
		(net "IRQ_PVCCFA_CPU0_VRHOT_R_N")
	)
	(segment
		(start 213.2584 -137.4394)
		(end 221.4118 -137.4394)
		(width 0.127)
		(layer "In15.Cu")
		(net "IRQ_PVCCFA_CPU0_VRHOT_R_N")
	)
	(segment
		(start 162.9918 -129.7686)
		(end 164.1602 -129.7686)
		(width 0.127)
		(layer "In15.Cu")
		(net "IRQ_PVCCFA_CPU0_VRHOT_R_N")
	)
	(segment
		(start 158.242 -138.9126)
		(end 158.496 -139.1666)
		(width 0.127)
		(layer "In15.Cu")
		(net "IRQ_PVCCFA_CPU0_VRHOT_R_N")
	)
	(segment
		(start 170.8404 -127.0762)
		(end 172.6692 -125.2474)
		(width 0.127)
		(layer "In15.Cu")
		(net "IRQ_PVCCFA_CPU0_VRHOT_R_N")
	)
	(segment
		(start 176.1236 -124.1806)
		(end 176.911 -123.3932)
		(width 0.127)
		(layer "In15.Cu")
		(net "IRQ_PVCCFA_CPU0_VRHOT_R_N")
	)
	(segment
		(start 176.911 -122.3264)
		(end 176.155604 -121.571004)
		(width 0.127)
		(layer "In15.Cu")
		(net "IRQ_PVCCFA_CPU0_VRHOT_R_N")
	)
	(segment
		(start 194.0306 -140.081)
		(end 210.6168 -140.081)
		(width 0.127)
		(layer "In15.Cu")
		(net "IRQ_PVCCFA_CPU0_VRHOT_R_N")
	)
	(segment
		(start 170.8404 -128.8034)
		(end 170.8404 -127.0762)
		(width 0.127)
		(layer "In15.Cu")
		(net "IRQ_PVCCFA_CPU0_VRHOT_R_N")
	)
	(segment
		(start 248.545858 -132.307076)
		(end 250.855734 -129.9972)
		(width 0.127)
		(layer "In15.Cu")
		(net "IRQ_PVCCFA_CPU0_VRHOT_R_N")
	)
	(segment
		(start 174.0662 -125.2474)
		(end 175.133 -124.1806)
		(width 0.127)
		(layer "In15.Cu")
		(net "IRQ_PVCCFA_CPU0_VRHOT_R_N")
	)
	(segment
		(start 169.2656 -129.413)
		(end 170.2308 -129.413)
		(width 0.127)
		(layer "In15.Cu")
		(net "IRQ_PVCCFA_CPU0_VRHOT_R_N")
	)
	(segment
		(start 164.1602 -129.7686)
		(end 164.719 -129.2098)
		(width 0.127)
		(layer "In15.Cu")
		(net "IRQ_PVCCFA_CPU0_VRHOT_R_N")
	)
	(segment
		(start 158.496 -139.1666)
		(end 193.1162 -139.1666)
		(width 0.127)
		(layer "In15.Cu")
		(net "IRQ_PVCCFA_CPU0_VRHOT_R_N")
	)
	(segment
		(start 162.433 -129.2098)
		(end 162.9918 -129.7686)
		(width 0.127)
		(layer "In15.Cu")
		(net "IRQ_PVCCFA_CPU0_VRHOT_R_N")
	)
	(segment
		(start 160.782 -129.2098)
		(end 162.433 -129.2098)
		(width 0.127)
		(layer "In15.Cu")
		(net "IRQ_PVCCFA_CPU0_VRHOT_R_N")
	)
	(segment
		(start 193.1162 -139.1666)
		(end 194.0306 -140.081)
		(width 0.127)
		(layer "In15.Cu")
		(net "IRQ_PVCCFA_CPU0_VRHOT_R_N")
	)
	(segment
		(start 247.12295 -137.511028)
		(end 248.545858 -136.08812)
		(width 0.127)
		(layer "In15.Cu")
		(net "IRQ_PVCCFA_CPU0_VRHOT_R_N")
	)
	(segment
		(start 250.855734 -129.9972)
		(end 250.855734 -128.122934)
		(width 0.127)
		(layer "In15.Cu")
		(net "IRQ_PVCCFA_CPU0_VRHOT_R_N")
	)
	(segment
		(start 248.545858 -136.08812)
		(end 248.545858 -132.307076)
		(width 0.127)
		(layer "In15.Cu")
		(net "IRQ_PVCCFA_CPU0_VRHOT_R_N")
	)
	(segment
		(start 172.6692 -125.2474)
		(end 174.0662 -125.2474)
		(width 0.127)
		(layer "In15.Cu")
		(net "IRQ_PVCCFA_CPU0_VRHOT_R_N")
	)
	(segment
		(start 183.54802 -419.87343)
		(end 183.54802 -420.55796)
		(width 0.12954)
		(layer "F.Cu")
		(net "HSC_OC_VOL")
	)
	(segment
		(start 182.58282 -419.87343)
		(end 183.54802 -419.87343)
		(width 0.12954)
		(layer "F.Cu")
		(net "HSC_OC_VOL")
	)
	(segment
		(start 182.668672 -409.452064)
		(end 182.2958 -409.824936)
		(width 0.12954)
		(layer "F.Cu")
		(net "HSC_OC_VOL")
	)
	(segment
		(start 182.40883 -411.60573)
		(end 182.82158 -411.60573)
		(width 0.12954)
		(layer "F.Cu")
		(net "HSC_OC_VOL")
	)
	(segment
		(start 184.40654 -413.41421)
		(end 184.40654 -412.16199)
		(width 0.12954)
		(layer "F.Cu")
		(net "HSC_OC_VOL")
	)
	(segment
		(start 182.2958 -409.824936)
		(end 182.2958 -411.4927)
		(width 0.12954)
		(layer "F.Cu")
		(net "HSC_OC_VOL")
	)
	(segment
		(start 182.82158 -411.60573)
		(end 183.85028 -411.60573)
		(width 0.12954)
		(layer "F.Cu")
		(net "HSC_OC_VOL")
	)
	(segment
		(start 182.2958 -411.4927)
		(end 182.40883 -411.60573)
		(width 0.12954)
		(layer "F.Cu")
		(net "HSC_OC_VOL")
	)
	(segment
		(start 184.40654 -412.16199)
		(end 183.85028 -411.60573)
		(width 0.12954)
		(layer "F.Cu")
		(net "HSC_OC_VOL")
	)
	(via
		(at 183.54802 -420.55796)
		(size 0.508)
		(drill 0.254)
		(layers "F.Cu" "B.Cu")
		(net "HSC_OC_VOL")
	)
	(via
		(at 182.668672 -409.452064)
		(size 0.508)
		(drill 0.254)
		(layers "F.Cu" "B.Cu")
		(net "HSC_OC_VOL")
	)
	(segment
		(start 183.54802 -419.12794)
		(end 183.54802 -420.55796)
		(width 0.12954)
		(layer "B.Cu")
		(net "HSC_OC_VOL")
	)
	(segment
		(start 182.31104 -413.63392)
		(end 184.0357 -415.35858)
		(width 0.12954)
		(layer "B.Cu")
		(net "HSC_OC_VOL")
	)
	(segment
		(start 182.668672 -409.452064)
		(end 182.31104 -409.809696)
		(width 0.12954)
		(layer "B.Cu")
		(net "HSC_OC_VOL")
	)
	(segment
		(start 182.31104 -409.809696)
		(end 182.31104 -413.63392)
		(width 0.12954)
		(layer "B.Cu")
		(net "HSC_OC_VOL")
	)
	(segment
		(start 184.0357 -418.64026)
		(end 183.54802 -419.12794)
		(width 0.12954)
		(layer "B.Cu")
		(net "HSC_OC_VOL")
	)
	(segment
		(start 184.0357 -415.35858)
		(end 184.0357 -418.64026)
		(width 0.12954)
		(layer "B.Cu")
		(net "HSC_OC_VOL")
	)
	(segment
		(start 184.40654 -417.48837)
		(end 184.58688 -417.66871)
		(width 0.12954)
		(layer "F.Cu")
		(net "HSC_D_OC_R2")
	)
	(segment
		(start 185.91784 -415.06394)
		(end 184.86374 -415.06394)
		(width 0.12954)
		(layer "F.Cu")
		(net "HSC_D_OC_R2")
	)
	(segment
		(start 183.85028 -410.80563)
		(end 183.87441 -410.80563)
		(width 0.12954)
		(layer "F.Cu")
		(net "HSC_D_OC_R2")
	)
	(segment
		(start 183.87441 -410.80563)
		(end 184.93486 -411.86608)
		(width 0.12954)
		(layer "F.Cu")
		(net "HSC_D_OC_R2")
	)
	(segment
		(start 184.93486 -411.86608)
		(end 184.93486 -414.08096)
		(width 0.12954)
		(layer "F.Cu")
		(net "HSC_D_OC_R2")
	)
	(segment
		(start 184.40654 -415.52114)
		(end 184.40654 -416.11423)
		(width 0.12954)
		(layer "F.Cu")
		(net "HSC_D_OC_R2")
	)
	(segment
		(start 184.86374 -415.06394)
		(end 184.40654 -415.52114)
		(width 0.12954)
		(layer "F.Cu")
		(net "HSC_D_OC_R2")
	)
	(segment
		(start 184.93486 -414.08096)
		(end 185.91784 -415.06394)
		(width 0.12954)
		(layer "F.Cu")
		(net "HSC_D_OC_R2")
	)
	(segment
		(start 184.40654 -416.11423)
		(end 184.40654 -417.48837)
		(width 0.12954)
		(layer "F.Cu")
		(net "HSC_D_OC_R2")
	)
	(via
		(at 185.91784 -415.06394)
		(size 0.762)
		(drill 0.381)
		(layers "F.Cu" "B.Cu")
		(net "HSC_D_OC_R2")
	)
	(segment
		(start 174.506636 -29.437584)
		(end 174.499524 -29.430472)
		(width 0.12954)
		(layer "F.Cu")
		(net "HP_LVC3_SCM_HSC_PWRGD_R")
	)
	(segment
		(start 174.499524 -29.430472)
		(end 173.616112 -29.430472)
		(width 0.12954)
		(layer "F.Cu")
		(net "HP_LVC3_SCM_HSC_PWRGD_R")
	)
	(segment
		(start 175.294036 -29.437584)
		(end 174.506636 -29.437584)
		(width 0.12954)
		(layer "F.Cu")
		(net "HP_LVC3_SCM_HSC_PWRGD_R")
	)
	(via
		(at 174.506636 -29.437584)
		(size 0.508)
		(drill 0.254)
		(layers "F.Cu" "B.Cu")
		(net "HP_LVC3_SCM_HSC_PWRGD_R")
	)
	(segment
		(start 173.73219 -30.21203)
		(end 174.506636 -29.437584)
		(width 0.12954)
		(layer "B.Cu")
		(net "HP_LVC3_SCM_HSC_PWRGD_R")
	)
	(segment
		(start 173.33976 -30.21203)
		(end 173.73219 -30.21203)
		(width 0.12954)
		(layer "B.Cu")
		(net "HP_LVC3_SCM_HSC_PWRGD_R")
	)
	(segment
		(start 178.1556 -108.175552)
		(end 177.75555 -107.775502)
		(width 0.12954)
		(layer "F.Cu")
		(net "HP_LVC3_SCM_HSC_PWRGD_PLD")
	)
	(segment
		(start 185.7756 -94.3102)
		(end 185.7756 -95.25)
		(width 0.12954)
		(layer "F.Cu")
		(net "HP_LVC3_SCM_HSC_PWRGD_PLD")
	)
	(via
		(at 177.75555 -107.775502)
		(size 0.4572)
		(drill 0.254)
		(layers "F.Cu" "B.Cu")
		(net "HP_LVC3_SCM_HSC_PWRGD_PLD")
	)
	(via
		(at 185.7756 -95.25)
		(size 0.508)
		(drill 0.254)
		(layers "F.Cu" "B.Cu")
		(net "HP_LVC3_SCM_HSC_PWRGD_PLD")
	)
	(segment
		(start 185.7756 -95.3516)
		(end 185.4454 -95.6818)
		(width 0.127)
		(layer "In11.Cu")
		(net "HP_LVC3_SCM_HSC_PWRGD_PLD")
	)
	(segment
		(start 178.9938 -105.0036)
		(end 178.9938 -105.537)
		(width 0.127)
		(layer "In11.Cu")
		(net "HP_LVC3_SCM_HSC_PWRGD_PLD")
	)
	(segment
		(start 178.0794 -94.5388)
		(end 177.4698 -95.1484)
		(width 0.127)
		(layer "In11.Cu")
		(net "HP_LVC3_SCM_HSC_PWRGD_PLD")
	)
	(segment
		(start 178.435 -104.4448)
		(end 178.9938 -105.0036)
		(width 0.127)
		(layer "In11.Cu")
		(net "HP_LVC3_SCM_HSC_PWRGD_PLD")
	)
	(segment
		(start 178.435 -100.904294)
		(end 178.435 -104.4448)
		(width 0.127)
		(layer "In11.Cu")
		(net "HP_LVC3_SCM_HSC_PWRGD_PLD")
	)
	(segment
		(start 177.4698 -95.1484)
		(end 177.4698 -95.6056)
		(width 0.127)
		(layer "In11.Cu")
		(net "HP_LVC3_SCM_HSC_PWRGD_PLD")
	)
	(segment
		(start 183.3372 -95.6818)
		(end 182.1942 -94.5388)
		(width 0.127)
		(layer "In11.Cu")
		(net "HP_LVC3_SCM_HSC_PWRGD_PLD")
	)
	(segment
		(start 178.0794 -107.1372)
		(end 177.75555 -107.46105)
		(width 0.127)
		(layer "In11.Cu")
		(net "HP_LVC3_SCM_HSC_PWRGD_PLD")
	)
	(segment
		(start 178.8033 -96.9391)
		(end 178.8033 -100.535994)
		(width 0.127)
		(layer "In11.Cu")
		(net "HP_LVC3_SCM_HSC_PWRGD_PLD")
	)
	(segment
		(start 182.1942 -94.5388)
		(end 178.0794 -94.5388)
		(width 0.127)
		(layer "In11.Cu")
		(net "HP_LVC3_SCM_HSC_PWRGD_PLD")
	)
	(segment
		(start 178.0794 -106.4514)
		(end 178.0794 -107.1372)
		(width 0.127)
		(layer "In11.Cu")
		(net "HP_LVC3_SCM_HSC_PWRGD_PLD")
	)
	(segment
		(start 177.75555 -107.46105)
		(end 177.75555 -107.775502)
		(width 0.127)
		(layer "In11.Cu")
		(net "HP_LVC3_SCM_HSC_PWRGD_PLD")
	)
	(segment
		(start 178.8033 -100.535994)
		(end 178.435 -100.904294)
		(width 0.127)
		(layer "In11.Cu")
		(net "HP_LVC3_SCM_HSC_PWRGD_PLD")
	)
	(segment
		(start 185.7756 -95.25)
		(end 185.7756 -95.3516)
		(width 0.127)
		(layer "In11.Cu")
		(net "HP_LVC3_SCM_HSC_PWRGD_PLD")
	)
	(segment
		(start 178.9938 -105.537)
		(end 178.0794 -106.4514)
		(width 0.127)
		(layer "In11.Cu")
		(net "HP_LVC3_SCM_HSC_PWRGD_PLD")
	)
	(segment
		(start 177.4698 -95.6056)
		(end 178.8033 -96.9391)
		(width 0.127)
		(layer "In11.Cu")
		(net "HP_LVC3_SCM_HSC_PWRGD_PLD")
	)
	(segment
		(start 185.4454 -95.6818)
		(end 183.3372 -95.6818)
		(width 0.127)
		(layer "In11.Cu")
		(net "HP_LVC3_SCM_HSC_PWRGD_PLD")
	)
	(segment
		(start 192.544954 -23.691342)
		(end 193.089022 -23.691342)
		(width 0.12954)
		(layer "F.Cu")
		(net "HP_LVC3_SCM_HSC_PWRGD")
	)
	(segment
		(start 193.089022 -22.694392)
		(end 193.089022 -23.691342)
		(width 0.12954)
		(layer "F.Cu")
		(net "HP_LVC3_SCM_HSC_PWRGD")
	)
	(segment
		(start 185.7756 -93.5101)
		(end 185.7756 -92.837)
		(width 0.12954)
		(layer "F.Cu")
		(net "HP_LVC3_SCM_HSC_PWRGD")
	)
	(segment
		(start 192.36436 -23.510748)
		(end 192.544954 -23.691342)
		(width 0.12954)
		(layer "F.Cu")
		(net "HP_LVC3_SCM_HSC_PWRGD")
	)
	(via
		(at 192.36436 -23.510748)
		(size 0.508)
		(drill 0.254)
		(layers "F.Cu" "B.Cu")
		(net "HP_LVC3_SCM_HSC_PWRGD")
	)
	(via
		(at 185.7756 -92.837)
		(size 0.508)
		(drill 0.254)
		(layers "F.Cu" "B.Cu")
		(net "HP_LVC3_SCM_HSC_PWRGD")
	)
	(via
		(at 172.15866 -26.63952)
		(size 0.508)
		(drill 0.254)
		(layers "F.Cu" "B.Cu")
		(net "HP_LVC3_SCM_HSC_PWRGD")
	)
	(via
		(at 169.7482 -33.6296)
		(size 0.508)
		(drill 0.254)
		(layers "F.Cu" "B.Cu")
		(net "HP_LVC3_SCM_HSC_PWRGD")
	)
	(via
		(at 174.50562 -28.72486)
		(size 0.508)
		(drill 0.254)
		(layers "F.Cu" "B.Cu")
		(net "HP_LVC3_SCM_HSC_PWRGD")
	)
	(segment
		(start 174.02683 -28.72486)
		(end 173.33976 -29.41193)
		(width 0.12954)
		(layer "B.Cu")
		(net "HP_LVC3_SCM_HSC_PWRGD")
	)
	(segment
		(start 172.15866 -27.08148)
		(end 173.33976 -28.26258)
		(width 0.12954)
		(layer "B.Cu")
		(net "HP_LVC3_SCM_HSC_PWRGD")
	)
	(segment
		(start 173.33976 -28.26258)
		(end 173.33976 -29.41193)
		(width 0.12954)
		(layer "B.Cu")
		(net "HP_LVC3_SCM_HSC_PWRGD")
	)
	(segment
		(start 172.15866 -26.63952)
		(end 172.15866 -27.08148)
		(width 0.12954)
		(layer "B.Cu")
		(net "HP_LVC3_SCM_HSC_PWRGD")
	)
	(segment
		(start 174.50562 -28.72486)
		(end 174.02683 -28.72486)
		(width 0.12954)
		(layer "B.Cu")
		(net "HP_LVC3_SCM_HSC_PWRGD")
	)
	(segment
		(start 185.293 -55.1942)
		(end 185.7756 -54.7116)
		(width 0.127)
		(layer "In2.Cu")
		(net "HP_LVC3_SCM_HSC_PWRGD")
	)
	(segment
		(start 173.9138 -36.9824)
		(end 170.561 -33.6296)
		(width 0.127)
		(layer "In2.Cu")
		(net "HP_LVC3_SCM_HSC_PWRGD")
	)
	(segment
		(start 185.7756 -46.2534)
		(end 182.1688 -42.6466)
		(width 0.127)
		(layer "In2.Cu")
		(net "HP_LVC3_SCM_HSC_PWRGD")
	)
	(segment
		(start 185.7756 -54.7116)
		(end 185.7756 -46.2534)
		(width 0.127)
		(layer "In2.Cu")
		(net "HP_LVC3_SCM_HSC_PWRGD")
	)
	(segment
		(start 180.721 -58.166)
		(end 181.2544 -57.6326)
		(width 0.127)
		(layer "In2.Cu")
		(net "HP_LVC3_SCM_HSC_PWRGD")
	)
	(segment
		(start 170.561 -33.6296)
		(end 169.7482 -33.6296)
		(width 0.127)
		(layer "In2.Cu")
		(net "HP_LVC3_SCM_HSC_PWRGD")
	)
	(segment
		(start 182.1688 -42.6466)
		(end 180.5178 -42.6466)
		(width 0.127)
		(layer "In2.Cu")
		(net "HP_LVC3_SCM_HSC_PWRGD")
	)
	(segment
		(start 182.1434 -87.122)
		(end 174.8282 -87.122)
		(width 0.127)
		(layer "In2.Cu")
		(net "HP_LVC3_SCM_HSC_PWRGD")
	)
	(segment
		(start 181.2544 -57.6326)
		(end 181.2544 -55.6514)
		(width 0.127)
		(layer "In2.Cu")
		(net "HP_LVC3_SCM_HSC_PWRGD")
	)
	(segment
		(start 180.5178 -42.6466)
		(end 174.8536 -36.9824)
		(width 0.127)
		(layer "In2.Cu")
		(net "HP_LVC3_SCM_HSC_PWRGD")
	)
	(segment
		(start 181.2544 -55.6514)
		(end 181.7116 -55.1942)
		(width 0.127)
		(layer "In2.Cu")
		(net "HP_LVC3_SCM_HSC_PWRGD")
	)
	(segment
		(start 169.8244 -62.5856)
		(end 174.244 -58.166)
		(width 0.127)
		(layer "In2.Cu")
		(net "HP_LVC3_SCM_HSC_PWRGD")
	)
	(segment
		(start 174.8282 -87.122)
		(end 169.8244 -82.1182)
		(width 0.127)
		(layer "In2.Cu")
		(net "HP_LVC3_SCM_HSC_PWRGD")
	)
	(segment
		(start 185.7756 -92.837)
		(end 185.7756 -90.7542)
		(width 0.127)
		(layer "In2.Cu")
		(net "HP_LVC3_SCM_HSC_PWRGD")
	)
	(segment
		(start 181.7116 -55.1942)
		(end 185.293 -55.1942)
		(width 0.127)
		(layer "In2.Cu")
		(net "HP_LVC3_SCM_HSC_PWRGD")
	)
	(segment
		(start 174.8536 -36.9824)
		(end 173.9138 -36.9824)
		(width 0.127)
		(layer "In2.Cu")
		(net "HP_LVC3_SCM_HSC_PWRGD")
	)
	(segment
		(start 174.244 -58.166)
		(end 180.721 -58.166)
		(width 0.127)
		(layer "In2.Cu")
		(net "HP_LVC3_SCM_HSC_PWRGD")
	)
	(segment
		(start 169.8244 -82.1182)
		(end 169.8244 -62.5856)
		(width 0.127)
		(layer "In2.Cu")
		(net "HP_LVC3_SCM_HSC_PWRGD")
	)
	(segment
		(start 185.7756 -90.7542)
		(end 182.1434 -87.122)
		(width 0.127)
		(layer "In2.Cu")
		(net "HP_LVC3_SCM_HSC_PWRGD")
	)
	(segment
		(start 172.25518 -23.32736)
		(end 171.50588 -24.07666)
		(width 0.127)
		(layer "In11.Cu")
		(net "HP_LVC3_SCM_HSC_PWRGD")
	)
	(segment
		(start 181.77256 -23.32736)
		(end 172.25518 -23.32736)
		(width 0.127)
		(layer "In11.Cu")
		(net "HP_LVC3_SCM_HSC_PWRGD")
	)
	(segment
		(start 183.19242 -21.9075)
		(end 181.77256 -23.32736)
		(width 0.127)
		(layer "In11.Cu")
		(net "HP_LVC3_SCM_HSC_PWRGD")
	)
	(segment
		(start 190.761112 -21.9075)
		(end 183.19242 -21.9075)
		(width 0.127)
		(layer "In11.Cu")
		(net "HP_LVC3_SCM_HSC_PWRGD")
	)
	(segment
		(start 171.50588 -25.98674)
		(end 172.15866 -26.63952)
		(width 0.127)
		(layer "In11.Cu")
		(net "HP_LVC3_SCM_HSC_PWRGD")
	)
	(segment
		(start 171.50588 -24.07666)
		(end 171.50588 -25.98674)
		(width 0.127)
		(layer "In11.Cu")
		(net "HP_LVC3_SCM_HSC_PWRGD")
	)
	(segment
		(start 192.36436 -23.510748)
		(end 190.761112 -21.9075)
		(width 0.127)
		(layer "In11.Cu")
		(net "HP_LVC3_SCM_HSC_PWRGD")
	)
	(segment
		(start 172.15866 -26.63952)
		(end 170.51528 -26.63952)
		(width 0.127)
		(layer "In15.Cu")
		(net "HP_LVC3_SCM_HSC_PWRGD")
	)
	(segment
		(start 170.51528 -26.63952)
		(end 169.7482 -27.4066)
		(width 0.127)
		(layer "In15.Cu")
		(net "HP_LVC3_SCM_HSC_PWRGD")
	)
	(segment
		(start 169.7482 -27.4066)
		(end 169.7482 -33.6296)
		(width 0.127)
		(layer "In15.Cu")
		(net "HP_LVC3_SCM_HSC_PWRGD")
	)
	(segment
		(start 139.36218 -114.334544)
		(end 137.98296 -114.334544)
		(width 0.12954)
		(layer "F.Cu")
		(net "HP_LVC3_OCP_V3_2_PWRGD_R2")
	)
	(segment
		(start 136.834626 -114.334544)
		(end 136.78535 -114.38382)
		(width 0.12954)
		(layer "F.Cu")
		(net "HP_LVC3_OCP_V3_2_PWRGD_R2")
	)
	(segment
		(start 136.78535 -114.38382)
		(end 136.78535 -115.38458)
		(width 0.12954)
		(layer "F.Cu")
		(net "HP_LVC3_OCP_V3_2_PWRGD_R2")
	)
	(segment
		(start 137.98296 -114.334544)
		(end 136.834626 -114.334544)
		(width 0.12954)
		(layer "F.Cu")
		(net "HP_LVC3_OCP_V3_2_PWRGD_R2")
	)
	(via
		(at 137.98296 -114.334544)
		(size 0.762)
		(drill 0.381)
		(layers "F.Cu" "B.Cu")
		(net "HP_LVC3_OCP_V3_2_PWRGD_R2")
	)
	(segment
		(start 39.4716 -93.726)
		(end 60.198 -93.726)
		(width 0.12954)
		(layer "F.Cu")
		(net "HP_LVC3_OCP_V3_2_PRSNT2_PLD_N")
	)
	(segment
		(start 33.8328 -68.8848)
		(end 34.1376 -69.1896)
		(width 0.12954)
		(layer "F.Cu")
		(net "HP_LVC3_OCP_V3_2_PRSNT2_PLD_N")
	)
	(segment
		(start 34.1376 -77.5716)
		(end 38.862 -82.296)
		(width 0.12954)
		(layer "F.Cu")
		(net "HP_LVC3_OCP_V3_2_PRSNT2_PLD_N")
	)
	(segment
		(start 30.18028 -69.7992)
		(end 31.45155 -69.7992)
		(width 0.12954)
		(layer "F.Cu")
		(net "HP_LVC3_OCP_V3_2_PRSNT2_PLD_N")
	)
	(segment
		(start 31.45155 -69.13245)
		(end 31.6992 -68.8848)
		(width 0.12954)
		(layer "F.Cu")
		(net "HP_LVC3_OCP_V3_2_PRSNT2_PLD_N")
	)
	(segment
		(start 60.198 -93.726)
		(end 64.008 -97.536)
		(width 0.12954)
		(layer "F.Cu")
		(net "HP_LVC3_OCP_V3_2_PRSNT2_PLD_N")
	)
	(segment
		(start 31.45155 -69.7992)
		(end 31.45155 -69.13245)
		(width 0.12954)
		(layer "F.Cu")
		(net "HP_LVC3_OCP_V3_2_PRSNT2_PLD_N")
	)
	(segment
		(start 31.6992 -68.8848)
		(end 33.8328 -68.8848)
		(width 0.12954)
		(layer "F.Cu")
		(net "HP_LVC3_OCP_V3_2_PRSNT2_PLD_N")
	)
	(segment
		(start 34.1376 -69.1896)
		(end 34.1376 -77.5716)
		(width 0.12954)
		(layer "F.Cu")
		(net "HP_LVC3_OCP_V3_2_PRSNT2_PLD_N")
	)
	(segment
		(start 64.008 -97.536)
		(end 64.008 -100.4316)
		(width 0.12954)
		(layer "F.Cu")
		(net "HP_LVC3_OCP_V3_2_PRSNT2_PLD_N")
	)
	(segment
		(start 38.862 -82.296)
		(end 38.862 -93.1164)
		(width 0.12954)
		(layer "F.Cu")
		(net "HP_LVC3_OCP_V3_2_PRSNT2_PLD_N")
	)
	(segment
		(start 177.355754 -106.575352)
		(end 176.955704 -106.175302)
		(width 0.12954)
		(layer "F.Cu")
		(net "HP_LVC3_OCP_V3_2_PRSNT2_PLD_N")
	)
	(segment
		(start 38.862 -93.1164)
		(end 39.4716 -93.726)
		(width 0.12954)
		(layer "F.Cu")
		(net "HP_LVC3_OCP_V3_2_PRSNT2_PLD_N")
	)
	(segment
		(start 28.978098 -69.7992)
		(end 30.18028 -69.7992)
		(width 0.12954)
		(layer "F.Cu")
		(net "HP_LVC3_OCP_V3_2_PRSNT2_PLD_N")
	)
	(via
		(at 30.18028 -69.7992)
		(size 0.762)
		(drill 0.381)
		(layers "F.Cu" "B.Cu")
		(net "HP_LVC3_OCP_V3_2_PRSNT2_PLD_N")
	)
	(via
		(at 176.955704 -106.175302)
		(size 0.4572)
		(drill 0.254)
		(layers "F.Cu" "B.Cu")
		(net "HP_LVC3_OCP_V3_2_PRSNT2_PLD_N")
	)
	(via
		(at 64.008 -100.4316)
		(size 0.508)
		(drill 0.254)
		(layers "F.Cu" "B.Cu")
		(net "HP_LVC3_OCP_V3_2_PRSNT2_PLD_N")
	)
	(segment
		(start 78.9432 -88.392)
		(end 66.9036 -100.4316)
		(width 0.127)
		(layer "In6.Cu")
		(net "HP_LVC3_OCP_V3_2_PRSNT2_PLD_N")
	)
	(segment
		(start 141.1224 -92.2274)
		(end 112.4966 -92.2274)
		(width 0.127)
		(layer "In6.Cu")
		(net "HP_LVC3_OCP_V3_2_PRSNT2_PLD_N")
	)
	(segment
		(start 147.2692 -96.2406)
		(end 145.1356 -96.2406)
		(width 0.127)
		(layer "In6.Cu")
		(net "HP_LVC3_OCP_V3_2_PRSNT2_PLD_N")
	)
	(segment
		(start 155.3464 -97.1296)
		(end 148.1582 -97.1296)
		(width 0.127)
		(layer "In6.Cu")
		(net "HP_LVC3_OCP_V3_2_PRSNT2_PLD_N")
	)
	(segment
		(start 112.4966 -92.2274)
		(end 111.7346 -91.4654)
		(width 0.127)
		(layer "In6.Cu")
		(net "HP_LVC3_OCP_V3_2_PRSNT2_PLD_N")
	)
	(segment
		(start 170.6499 -99.1616)
		(end 168.265348 -96.777048)
		(width 0.127)
		(layer "In6.Cu")
		(net "HP_LVC3_OCP_V3_2_PRSNT2_PLD_N")
	)
	(segment
		(start 175.15205 -100.005388)
		(end 174.05731 -100.005388)
		(width 0.127)
		(layer "In6.Cu")
		(net "HP_LVC3_OCP_V3_2_PRSNT2_PLD_N")
	)
	(segment
		(start 175.655732 -100.5078)
		(end 175.654462 -100.5078)
		(width 0.127)
		(layer "In6.Cu")
		(net "HP_LVC3_OCP_V3_2_PRSNT2_PLD_N")
	)
	(segment
		(start 177.5714 -104.5972)
		(end 177.5714 -101.124258)
		(width 0.127)
		(layer "In6.Cu")
		(net "HP_LVC3_OCP_V3_2_PRSNT2_PLD_N")
	)
	(segment
		(start 175.884332 -100.7364)
		(end 175.655732 -100.5078)
		(width 0.127)
		(layer "In6.Cu")
		(net "HP_LVC3_OCP_V3_2_PRSNT2_PLD_N")
	)
	(segment
		(start 177.5714 -101.124258)
		(end 177.183542 -100.7364)
		(width 0.127)
		(layer "In6.Cu")
		(net "HP_LVC3_OCP_V3_2_PRSNT2_PLD_N")
	)
	(segment
		(start 145.1356 -96.2406)
		(end 141.1224 -92.2274)
		(width 0.127)
		(layer "In6.Cu")
		(net "HP_LVC3_OCP_V3_2_PRSNT2_PLD_N")
	)
	(segment
		(start 104.7242 -88.392)
		(end 78.9432 -88.392)
		(width 0.127)
		(layer "In6.Cu")
		(net "HP_LVC3_OCP_V3_2_PRSNT2_PLD_N")
	)
	(segment
		(start 148.1582 -97.1296)
		(end 147.2692 -96.2406)
		(width 0.127)
		(layer "In6.Cu")
		(net "HP_LVC3_OCP_V3_2_PRSNT2_PLD_N")
	)
	(segment
		(start 176.955704 -105.212896)
		(end 177.5714 -104.5972)
		(width 0.127)
		(layer "In6.Cu")
		(net "HP_LVC3_OCP_V3_2_PRSNT2_PLD_N")
	)
	(segment
		(start 107.7976 -91.4654)
		(end 104.7242 -88.392)
		(width 0.127)
		(layer "In6.Cu")
		(net "HP_LVC3_OCP_V3_2_PRSNT2_PLD_N")
	)
	(segment
		(start 111.7346 -91.4654)
		(end 107.7976 -91.4654)
		(width 0.127)
		(layer "In6.Cu")
		(net "HP_LVC3_OCP_V3_2_PRSNT2_PLD_N")
	)
	(segment
		(start 175.654462 -100.5078)
		(end 175.15205 -100.005388)
		(width 0.127)
		(layer "In6.Cu")
		(net "HP_LVC3_OCP_V3_2_PRSNT2_PLD_N")
	)
	(segment
		(start 168.265348 -96.777048)
		(end 155.698952 -96.777048)
		(width 0.127)
		(layer "In6.Cu")
		(net "HP_LVC3_OCP_V3_2_PRSNT2_PLD_N")
	)
	(segment
		(start 155.698952 -96.777048)
		(end 155.3464 -97.1296)
		(width 0.127)
		(layer "In6.Cu")
		(net "HP_LVC3_OCP_V3_2_PRSNT2_PLD_N")
	)
	(segment
		(start 172.020484 -99.1616)
		(end 170.6499 -99.1616)
		(width 0.127)
		(layer "In6.Cu")
		(net "HP_LVC3_OCP_V3_2_PRSNT2_PLD_N")
	)
	(segment
		(start 174.05731 -100.005388)
		(end 172.020484 -99.1616)
		(width 0.127)
		(layer "In6.Cu")
		(net "HP_LVC3_OCP_V3_2_PRSNT2_PLD_N")
	)
	(segment
		(start 66.9036 -100.4316)
		(end 64.008 -100.4316)
		(width 0.127)
		(layer "In6.Cu")
		(net "HP_LVC3_OCP_V3_2_PRSNT2_PLD_N")
	)
	(segment
		(start 176.955704 -106.175302)
		(end 176.955704 -105.212896)
		(width 0.127)
		(layer "In6.Cu")
		(net "HP_LVC3_OCP_V3_2_PRSNT2_PLD_N")
	)
	(segment
		(start 177.183542 -100.7364)
		(end 175.884332 -100.7364)
		(width 0.127)
		(layer "In6.Cu")
		(net "HP_LVC3_OCP_V3_2_PRSNT2_PLD_N")
	)
	(segment
		(start 184.658 -94.3102)
		(end 184.658 -95.0214)
		(width 0.12954)
		(layer "F.Cu")
		(net "HP_LVC3_OCP_V3_2_FUSE_PWRGD")
	)
	(segment
		(start 177.355754 -108.175552)
		(end 176.955704 -107.775502)
		(width 0.12954)
		(layer "F.Cu")
		(net "HP_LVC3_OCP_V3_2_FUSE_PWRGD")
	)
	(via
		(at 184.658 -95.0214)
		(size 0.508)
		(drill 0.254)
		(layers "F.Cu" "B.Cu")
		(net "HP_LVC3_OCP_V3_2_FUSE_PWRGD")
	)
	(via
		(at 176.955704 -107.775502)
		(size 0.4572)
		(drill 0.254)
		(layers "F.Cu" "B.Cu")
		(net "HP_LVC3_OCP_V3_2_FUSE_PWRGD")
	)
	(segment
		(start 177.2158 -104.3686)
		(end 177.2158 -105.6894)
		(width 0.127)
		(layer "In11.Cu")
		(net "HP_LVC3_OCP_V3_2_FUSE_PWRGD")
	)
	(segment
		(start 184.658 -95.0214)
		(end 184.3024 -95.0214)
		(width 0.127)
		(layer "In11.Cu")
		(net "HP_LVC3_OCP_V3_2_FUSE_PWRGD")
	)
	(segment
		(start 184.3024 -95.0214)
		(end 182.8038 -93.5228)
		(width 0.127)
		(layer "In11.Cu")
		(net "HP_LVC3_OCP_V3_2_FUSE_PWRGD")
	)
	(segment
		(start 178.1429 -97.3963)
		(end 178.1429 -100.262182)
		(width 0.127)
		(layer "In11.Cu")
		(net "HP_LVC3_OCP_V3_2_FUSE_PWRGD")
	)
	(segment
		(start 174.8536 -95.5548)
		(end 175.4886 -96.1898)
		(width 0.127)
		(layer "In11.Cu")
		(net "HP_LVC3_OCP_V3_2_FUSE_PWRGD")
	)
	(segment
		(start 176.955704 -107.702096)
		(end 176.955704 -107.775502)
		(width 0.127)
		(layer "In11.Cu")
		(net "HP_LVC3_OCP_V3_2_FUSE_PWRGD")
	)
	(segment
		(start 177.5968 -103.9876)
		(end 177.2158 -104.3686)
		(width 0.127)
		(layer "In11.Cu")
		(net "HP_LVC3_OCP_V3_2_FUSE_PWRGD")
	)
	(segment
		(start 182.8038 -93.5228)
		(end 176.5046 -93.5228)
		(width 0.127)
		(layer "In11.Cu")
		(net "HP_LVC3_OCP_V3_2_FUSE_PWRGD")
	)
	(segment
		(start 175.4886 -96.1898)
		(end 176.9364 -96.1898)
		(width 0.127)
		(layer "In11.Cu")
		(net "HP_LVC3_OCP_V3_2_FUSE_PWRGD")
	)
	(segment
		(start 174.8536 -95.1738)
		(end 174.8536 -95.5548)
		(width 0.127)
		(layer "In11.Cu")
		(net "HP_LVC3_OCP_V3_2_FUSE_PWRGD")
	)
	(segment
		(start 177.5968 -100.808282)
		(end 177.5968 -103.9876)
		(width 0.127)
		(layer "In11.Cu")
		(net "HP_LVC3_OCP_V3_2_FUSE_PWRGD")
	)
	(segment
		(start 176.9364 -96.1898)
		(end 178.1429 -97.3963)
		(width 0.127)
		(layer "In11.Cu")
		(net "HP_LVC3_OCP_V3_2_FUSE_PWRGD")
	)
	(segment
		(start 177.5714 -107.0864)
		(end 176.955704 -107.702096)
		(width 0.127)
		(layer "In11.Cu")
		(net "HP_LVC3_OCP_V3_2_FUSE_PWRGD")
	)
	(segment
		(start 177.5714 -106.045)
		(end 177.5714 -107.0864)
		(width 0.127)
		(layer "In11.Cu")
		(net "HP_LVC3_OCP_V3_2_FUSE_PWRGD")
	)
	(segment
		(start 178.1429 -100.262182)
		(end 177.5968 -100.808282)
		(width 0.127)
		(layer "In11.Cu")
		(net "HP_LVC3_OCP_V3_2_FUSE_PWRGD")
	)
	(segment
		(start 177.2158 -105.6894)
		(end 177.5714 -106.045)
		(width 0.127)
		(layer "In11.Cu")
		(net "HP_LVC3_OCP_V3_2_FUSE_PWRGD")
	)
	(segment
		(start 176.5046 -93.5228)
		(end 174.8536 -95.1738)
		(width 0.127)
		(layer "In11.Cu")
		(net "HP_LVC3_OCP_V3_2_FUSE_PWRGD")
	)
	(segment
		(start 441.52566 -108.25988)
		(end 441.2234 -108.56214)
		(width 0.12954)
		(layer "F.Cu")
		(net "HP_LVC3_OCP_V3_1_PWRGD_R2")
	)
	(segment
		(start 441.2234 -108.56214)
		(end 439.7121 -108.56214)
		(width 0.12954)
		(layer "F.Cu")
		(net "HP_LVC3_OCP_V3_1_PWRGD_R2")
	)
	(segment
		(start 438.18302 -102.5017)
		(end 438.5437 -102.14102)
		(width 0.12954)
		(layer "F.Cu")
		(net "HP_LVC3_OCP_V3_1_PWRGD_R2")
	)
	(segment
		(start 438.5437 -102.14102)
		(end 439.408316 -102.14102)
		(width 0.12954)
		(layer "F.Cu")
		(net "HP_LVC3_OCP_V3_1_PWRGD_R2")
	)
	(segment
		(start 438.18302 -108.10748)
		(end 438.18302 -102.5017)
		(width 0.12954)
		(layer "F.Cu")
		(net "HP_LVC3_OCP_V3_1_PWRGD_R2")
	)
	(segment
		(start 439.408316 -100.708206)
		(end 439.37174 -100.67163)
		(width 0.12954)
		(layer "F.Cu")
		(net "HP_LVC3_OCP_V3_1_PWRGD_R2")
	)
	(segment
		(start 439.7121 -108.56214)
		(end 438.63768 -108.56214)
		(width 0.12954)
		(layer "F.Cu")
		(net "HP_LVC3_OCP_V3_1_PWRGD_R2")
	)
	(segment
		(start 438.63768 -108.56214)
		(end 438.18302 -108.10748)
		(width 0.12954)
		(layer "F.Cu")
		(net "HP_LVC3_OCP_V3_1_PWRGD_R2")
	)
	(segment
		(start 441.52566 -106.78541)
		(end 441.52566 -108.25988)
		(width 0.12954)
		(layer "F.Cu")
		(net "HP_LVC3_OCP_V3_1_PWRGD_R2")
	)
	(segment
		(start 439.408316 -102.14102)
		(end 439.408316 -100.708206)
		(width 0.12954)
		(layer "F.Cu")
		(net "HP_LVC3_OCP_V3_1_PWRGD_R2")
	)
	(via
		(at 439.7121 -108.56214)
		(size 0.762)
		(drill 0.381)
		(layers "F.Cu" "B.Cu")
		(net "HP_LVC3_OCP_V3_1_PWRGD_R2")
	)
	(segment
		(start 461.193896 -106.027728)
		(end 461.193896 -105.011728)
		(width 0.12954)
		(layer "F.Cu")
		(net "HP_LVC3_OCP_V3_1_PRSNT2_PLD_N")
	)
	(segment
		(start 461.193896 -106.027728)
		(end 459.941168 -106.027728)
		(width 0.12954)
		(layer "F.Cu")
		(net "HP_LVC3_OCP_V3_1_PRSNT2_PLD_N")
	)
	(segment
		(start 177.355754 -107.375452)
		(end 176.955704 -106.975402)
		(width 0.12954)
		(layer "F.Cu")
		(net "HP_LVC3_OCP_V3_1_PRSNT2_PLD_N")
	)
	(via
		(at 276.16912 -110.600998)
		(size 0.508)
		(drill 0.254)
		(layers "F.Cu" "B.Cu")
		(net "HP_LVC3_OCP_V3_1_PRSNT2_PLD_N")
	)
	(via
		(at 176.955704 -106.975402)
		(size 0.4572)
		(drill 0.254)
		(layers "F.Cu" "B.Cu")
		(net "HP_LVC3_OCP_V3_1_PRSNT2_PLD_N")
	)
	(via
		(at 459.941168 -106.027728)
		(size 0.508)
		(drill 0.254)
		(layers "F.Cu" "B.Cu")
		(net "HP_LVC3_OCP_V3_1_PRSNT2_PLD_N")
	)
	(via
		(at 195.30314 -102.42804)
		(size 0.508)
		(drill 0.254)
		(layers "F.Cu" "B.Cu")
		(net "HP_LVC3_OCP_V3_1_PRSNT2_PLD_N")
	)
	(segment
		(start 180.570886 -108.968286)
		(end 178.578002 -106.975402)
		(width 0.127)
		(layer "In2.Cu")
		(net "HP_LVC3_OCP_V3_1_PRSNT2_PLD_N")
	)
	(segment
		(start 186.720988 -108.966)
		(end 186.7154 -108.966)
		(width 0.127)
		(layer "In2.Cu")
		(net "HP_LVC3_OCP_V3_1_PRSNT2_PLD_N")
	)
	(segment
		(start 186.713114 -108.968286)
		(end 180.570886 -108.968286)
		(width 0.127)
		(layer "In2.Cu")
		(net "HP_LVC3_OCP_V3_1_PRSNT2_PLD_N")
	)
	(segment
		(start 192.98158 -104.7496)
		(end 190.937388 -104.7496)
		(width 0.127)
		(layer "In2.Cu")
		(net "HP_LVC3_OCP_V3_1_PRSNT2_PLD_N")
	)
	(segment
		(start 195.30314 -102.42804)
		(end 192.98158 -104.7496)
		(width 0.127)
		(layer "In2.Cu")
		(net "HP_LVC3_OCP_V3_1_PRSNT2_PLD_N")
	)
	(segment
		(start 178.578002 -106.975402)
		(end 176.955704 -106.975402)
		(width 0.127)
		(layer "In2.Cu")
		(net "HP_LVC3_OCP_V3_1_PRSNT2_PLD_N")
	)
	(segment
		(start 186.7154 -108.966)
		(end 186.713114 -108.968286)
		(width 0.127)
		(layer "In2.Cu")
		(net "HP_LVC3_OCP_V3_1_PRSNT2_PLD_N")
	)
	(segment
		(start 190.937388 -104.7496)
		(end 186.720988 -108.966)
		(width 0.127)
		(layer "In2.Cu")
		(net "HP_LVC3_OCP_V3_1_PRSNT2_PLD_N")
	)
	(segment
		(start 370.29898 -109.20222)
		(end 371.17782 -108.32338)
		(width 0.127)
		(layer "In4.Cu")
		(net "HP_LVC3_OCP_V3_1_PRSNT2_PLD_N")
	)
	(segment
		(start 361.57662 -109.51718)
		(end 361.89158 -109.20222)
		(width 0.127)
		(layer "In4.Cu")
		(net "HP_LVC3_OCP_V3_1_PRSNT2_PLD_N")
	)
	(segment
		(start 375.11736 -108.32338)
		(end 376.1359 -109.34192)
		(width 0.127)
		(layer "In4.Cu")
		(net "HP_LVC3_OCP_V3_1_PRSNT2_PLD_N")
	)
	(segment
		(start 446.60058 -105.5878)
		(end 455.97318 -105.5878)
		(width 0.127)
		(layer "In4.Cu")
		(net "HP_LVC3_OCP_V3_1_PRSNT2_PLD_N")
	)
	(segment
		(start 276.16912 -109.28858)
		(end 277.59152 -107.86618)
		(width 0.127)
		(layer "In4.Cu")
		(net "HP_LVC3_OCP_V3_1_PRSNT2_PLD_N")
	)
	(segment
		(start 438.05856 -114.12982)
		(end 446.60058 -105.5878)
		(width 0.127)
		(layer "In4.Cu")
		(net "HP_LVC3_OCP_V3_1_PRSNT2_PLD_N")
	)
	(segment
		(start 361.89158 -109.20222)
		(end 370.29898 -109.20222)
		(width 0.127)
		(layer "In4.Cu")
		(net "HP_LVC3_OCP_V3_1_PRSNT2_PLD_N")
	)
	(segment
		(start 376.1359 -109.34192)
		(end 379.35408 -109.34192)
		(width 0.127)
		(layer "In4.Cu")
		(net "HP_LVC3_OCP_V3_1_PRSNT2_PLD_N")
	)
	(segment
		(start 379.35408 -109.34192)
		(end 380.55296 -108.14304)
		(width 0.127)
		(layer "In4.Cu")
		(net "HP_LVC3_OCP_V3_1_PRSNT2_PLD_N")
	)
	(segment
		(start 407.86558 -108.14304)
		(end 413.85236 -114.12982)
		(width 0.127)
		(layer "In4.Cu")
		(net "HP_LVC3_OCP_V3_1_PRSNT2_PLD_N")
	)
	(segment
		(start 337.25104 -107.86618)
		(end 338.90204 -109.51718)
		(width 0.127)
		(layer "In4.Cu")
		(net "HP_LVC3_OCP_V3_1_PRSNT2_PLD_N")
	)
	(segment
		(start 276.16912 -110.600998)
		(end 276.16912 -109.28858)
		(width 0.127)
		(layer "In4.Cu")
		(net "HP_LVC3_OCP_V3_1_PRSNT2_PLD_N")
	)
	(segment
		(start 277.59152 -107.86618)
		(end 337.25104 -107.86618)
		(width 0.127)
		(layer "In4.Cu")
		(net "HP_LVC3_OCP_V3_1_PRSNT2_PLD_N")
	)
	(segment
		(start 455.97318 -105.5878)
		(end 456.413108 -106.027728)
		(width 0.127)
		(layer "In4.Cu")
		(net "HP_LVC3_OCP_V3_1_PRSNT2_PLD_N")
	)
	(segment
		(start 371.17782 -108.32338)
		(end 375.11736 -108.32338)
		(width 0.127)
		(layer "In4.Cu")
		(net "HP_LVC3_OCP_V3_1_PRSNT2_PLD_N")
	)
	(segment
		(start 456.413108 -106.027728)
		(end 459.941168 -106.027728)
		(width 0.127)
		(layer "In4.Cu")
		(net "HP_LVC3_OCP_V3_1_PRSNT2_PLD_N")
	)
	(segment
		(start 380.55296 -108.14304)
		(end 407.86558 -108.14304)
		(width 0.127)
		(layer "In4.Cu")
		(net "HP_LVC3_OCP_V3_1_PRSNT2_PLD_N")
	)
	(segment
		(start 338.90204 -109.51718)
		(end 361.57662 -109.51718)
		(width 0.127)
		(layer "In4.Cu")
		(net "HP_LVC3_OCP_V3_1_PRSNT2_PLD_N")
	)
	(segment
		(start 413.85236 -114.12982)
		(end 438.05856 -114.12982)
		(width 0.127)
		(layer "In4.Cu")
		(net "HP_LVC3_OCP_V3_1_PRSNT2_PLD_N")
	)
	(segment
		(start 249.26544 -110.44428)
		(end 249.26544 -107.52328)
		(width 0.127)
		(layer "In13.Cu")
		(net "HP_LVC3_OCP_V3_1_PRSNT2_PLD_N")
	)
	(segment
		(start 249.01906 -106.02976)
		(end 247.74144 -106.02976)
		(width 0.127)
		(layer "In13.Cu")
		(net "HP_LVC3_OCP_V3_1_PRSNT2_PLD_N")
	)
	(segment
		(start 202.44308 -107.13974)
		(end 202.20178 -106.89844)
		(width 0.127)
		(layer "In13.Cu")
		(net "HP_LVC3_OCP_V3_1_PRSNT2_PLD_N")
	)
	(segment
		(start 245.9101 -104.19842)
		(end 233.62412 -104.19842)
		(width 0.127)
		(layer "In13.Cu")
		(net "HP_LVC3_OCP_V3_1_PRSNT2_PLD_N")
	)
	(segment
		(start 202.20178 -106.89844)
		(end 198.00824 -106.89844)
		(width 0.127)
		(layer "In13.Cu")
		(net "HP_LVC3_OCP_V3_1_PRSNT2_PLD_N")
	)
	(segment
		(start 249.52706 -106.53776)
		(end 249.01906 -106.02976)
		(width 0.127)
		(layer "In13.Cu")
		(net "HP_LVC3_OCP_V3_1_PRSNT2_PLD_N")
	)
	(segment
		(start 233.62412 -104.19842)
		(end 229.132892 -108.689648)
		(width 0.127)
		(layer "In13.Cu")
		(net "HP_LVC3_OCP_V3_1_PRSNT2_PLD_N")
	)
	(segment
		(start 198.00824 -106.89844)
		(end 195.30314 -104.19334)
		(width 0.127)
		(layer "In13.Cu")
		(net "HP_LVC3_OCP_V3_1_PRSNT2_PLD_N")
	)
	(segment
		(start 216.279984 -109.0676)
		(end 210.00974 -109.0676)
		(width 0.127)
		(layer "In13.Cu")
		(net "HP_LVC3_OCP_V3_1_PRSNT2_PLD_N")
	)
	(segment
		(start 276.16912 -105.6132)
		(end 274.29714 -103.74122)
		(width 0.127)
		(layer "In13.Cu")
		(net "HP_LVC3_OCP_V3_1_PRSNT2_PLD_N")
	)
	(segment
		(start 276.16912 -110.600998)
		(end 276.16912 -105.6132)
		(width 0.127)
		(layer "In13.Cu")
		(net "HP_LVC3_OCP_V3_1_PRSNT2_PLD_N")
	)
	(segment
		(start 216.657936 -108.689648)
		(end 216.279984 -109.0676)
		(width 0.127)
		(layer "In13.Cu")
		(net "HP_LVC3_OCP_V3_1_PRSNT2_PLD_N")
	)
	(segment
		(start 208.08188 -107.13974)
		(end 202.44308 -107.13974)
		(width 0.127)
		(layer "In13.Cu")
		(net "HP_LVC3_OCP_V3_1_PRSNT2_PLD_N")
	)
	(segment
		(start 195.30314 -104.19334)
		(end 195.30314 -102.42804)
		(width 0.127)
		(layer "In13.Cu")
		(net "HP_LVC3_OCP_V3_1_PRSNT2_PLD_N")
	)
	(segment
		(start 210.00974 -109.0676)
		(end 208.08188 -107.13974)
		(width 0.127)
		(layer "In13.Cu")
		(net "HP_LVC3_OCP_V3_1_PRSNT2_PLD_N")
	)
	(segment
		(start 229.132892 -108.689648)
		(end 216.657936 -108.689648)
		(width 0.127)
		(layer "In13.Cu")
		(net "HP_LVC3_OCP_V3_1_PRSNT2_PLD_N")
	)
	(segment
		(start 274.29714 -103.74122)
		(end 270.00962 -103.74122)
		(width 0.127)
		(layer "In13.Cu")
		(net "HP_LVC3_OCP_V3_1_PRSNT2_PLD_N")
	)
	(segment
		(start 249.52706 -107.26166)
		(end 249.52706 -106.53776)
		(width 0.127)
		(layer "In13.Cu")
		(net "HP_LVC3_OCP_V3_1_PRSNT2_PLD_N")
	)
	(segment
		(start 262.70204 -111.0488)
		(end 249.86996 -111.0488)
		(width 0.127)
		(layer "In13.Cu")
		(net "HP_LVC3_OCP_V3_1_PRSNT2_PLD_N")
	)
	(segment
		(start 270.00962 -103.74122)
		(end 262.70204 -111.0488)
		(width 0.127)
		(layer "In13.Cu")
		(net "HP_LVC3_OCP_V3_1_PRSNT2_PLD_N")
	)
	(segment
		(start 247.74144 -106.02976)
		(end 245.9101 -104.19842)
		(width 0.127)
		(layer "In13.Cu")
		(net "HP_LVC3_OCP_V3_1_PRSNT2_PLD_N")
	)
	(segment
		(start 249.26544 -107.52328)
		(end 249.52706 -107.26166)
		(width 0.127)
		(layer "In13.Cu")
		(net "HP_LVC3_OCP_V3_1_PRSNT2_PLD_N")
	)
	(segment
		(start 249.86996 -111.0488)
		(end 249.26544 -110.44428)
		(width 0.127)
		(layer "In13.Cu")
		(net "HP_LVC3_OCP_V3_1_PRSNT2_PLD_N")
	)
	(segment
		(start 178.1556 -109.775498)
		(end 177.75555 -109.375448)
		(width 0.12954)
		(layer "F.Cu")
		(net "HP_LVC3_OCP_V3_1_FUSE_PWRGD")
	)
	(segment
		(start 186.8932 -94.3102)
		(end 186.8932 -95.25)
		(width 0.12954)
		(layer "F.Cu")
		(net "HP_LVC3_OCP_V3_1_FUSE_PWRGD")
	)
	(via
		(at 177.75555 -109.375448)
		(size 0.4572)
		(drill 0.254)
		(layers "F.Cu" "B.Cu")
		(net "HP_LVC3_OCP_V3_1_FUSE_PWRGD")
	)
	(via
		(at 186.8932 -95.25)
		(size 0.508)
		(drill 0.254)
		(layers "F.Cu" "B.Cu")
		(net "HP_LVC3_OCP_V3_1_FUSE_PWRGD")
	)
	(segment
		(start 179.8574 -107.273598)
		(end 179.8574 -102.5652)
		(width 0.127)
		(layer "In11.Cu")
		(net "HP_LVC3_OCP_V3_1_FUSE_PWRGD")
	)
	(segment
		(start 179.0192 -94.869)
		(end 181.9402 -94.869)
		(width 0.127)
		(layer "In11.Cu")
		(net "HP_LVC3_OCP_V3_1_FUSE_PWRGD")
	)
	(segment
		(start 179.1335 -95.9993)
		(end 178.7398 -95.6056)
		(width 0.127)
		(layer "In11.Cu")
		(net "HP_LVC3_OCP_V3_1_FUSE_PWRGD")
	)
	(segment
		(start 178.7398 -95.6056)
		(end 178.7398 -95.1484)
		(width 0.127)
		(layer "In11.Cu")
		(net "HP_LVC3_OCP_V3_1_FUSE_PWRGD")
	)
	(segment
		(start 178.7398 -95.1484)
		(end 179.0192 -94.869)
		(width 0.127)
		(layer "In11.Cu")
		(net "HP_LVC3_OCP_V3_1_FUSE_PWRGD")
	)
	(segment
		(start 186.0296 -96.1136)
		(end 186.8932 -95.25)
		(width 0.127)
		(layer "In11.Cu")
		(net "HP_LVC3_OCP_V3_1_FUSE_PWRGD")
	)
	(segment
		(start 179.8574 -102.5652)
		(end 179.1335 -101.8413)
		(width 0.127)
		(layer "In11.Cu")
		(net "HP_LVC3_OCP_V3_1_FUSE_PWRGD")
	)
	(segment
		(start 179.1335 -101.8413)
		(end 179.1335 -95.9993)
		(width 0.127)
		(layer "In11.Cu")
		(net "HP_LVC3_OCP_V3_1_FUSE_PWRGD")
	)
	(segment
		(start 183.1848 -96.1136)
		(end 186.0296 -96.1136)
		(width 0.127)
		(layer "In11.Cu")
		(net "HP_LVC3_OCP_V3_1_FUSE_PWRGD")
	)
	(segment
		(start 177.75555 -109.375448)
		(end 179.8574 -107.273598)
		(width 0.127)
		(layer "In11.Cu")
		(net "HP_LVC3_OCP_V3_1_FUSE_PWRGD")
	)
	(segment
		(start 181.9402 -94.869)
		(end 183.1848 -96.1136)
		(width 0.127)
		(layer "In11.Cu")
		(net "HP_LVC3_OCP_V3_1_FUSE_PWRGD")
	)
	(segment
		(start 177.355754 -105.775506)
		(end 177.755804 -105.375456)
		(width 0.12954)
		(layer "F.Cu")
		(net "HP_LVC3_E1S_0_HSC_PWRGD_PLD")
	)
	(segment
		(start 183.515 -94.3102)
		(end 183.515 -95.0214)
		(width 0.12954)
		(layer "F.Cu")
		(net "HP_LVC3_E1S_0_HSC_PWRGD_PLD")
	)
	(via
		(at 177.755804 -105.375456)
		(size 0.4572)
		(drill 0.254)
		(layers "F.Cu" "B.Cu")
		(net "HP_LVC3_E1S_0_HSC_PWRGD_PLD")
	)
	(via
		(at 183.515 -95.0214)
		(size 0.508)
		(drill 0.254)
		(layers "F.Cu" "B.Cu")
		(net "HP_LVC3_E1S_0_HSC_PWRGD_PLD")
	)
	(segment
		(start 176.1744 -95.1992)
		(end 176.1744 -95.7072)
		(width 0.127)
		(layer "In11.Cu")
		(net "HP_LVC3_E1S_0_HSC_PWRGD_PLD")
	)
	(segment
		(start 177.1904 -95.8596)
		(end 178.4731 -97.1423)
		(width 0.127)
		(layer "In11.Cu")
		(net "HP_LVC3_E1S_0_HSC_PWRGD_PLD")
	)
	(segment
		(start 176.1744 -95.7072)
		(end 176.3268 -95.8596)
		(width 0.127)
		(layer "In11.Cu")
		(net "HP_LVC3_E1S_0_HSC_PWRGD_PLD")
	)
	(segment
		(start 178.0032 -100.868988)
		(end 178.0032 -104.14)
		(width 0.127)
		(layer "In11.Cu")
		(net "HP_LVC3_E1S_0_HSC_PWRGD_PLD")
	)
	(segment
		(start 178.0032 -104.14)
		(end 177.755804 -104.387396)
		(width 0.127)
		(layer "In11.Cu")
		(net "HP_LVC3_E1S_0_HSC_PWRGD_PLD")
	)
	(segment
		(start 177.3682 -94.0054)
		(end 176.1744 -95.1992)
		(width 0.127)
		(layer "In11.Cu")
		(net "HP_LVC3_E1S_0_HSC_PWRGD_PLD")
	)
	(segment
		(start 177.755804 -104.387396)
		(end 177.755804 -105.375456)
		(width 0.127)
		(layer "In11.Cu")
		(net "HP_LVC3_E1S_0_HSC_PWRGD_PLD")
	)
	(segment
		(start 183.515 -95.0214)
		(end 182.499 -94.0054)
		(width 0.127)
		(layer "In11.Cu")
		(net "HP_LVC3_E1S_0_HSC_PWRGD_PLD")
	)
	(segment
		(start 178.4731 -100.399088)
		(end 178.0032 -100.868988)
		(width 0.127)
		(layer "In11.Cu")
		(net "HP_LVC3_E1S_0_HSC_PWRGD_PLD")
	)
	(segment
		(start 178.4731 -97.1423)
		(end 178.4731 -100.399088)
		(width 0.127)
		(layer "In11.Cu")
		(net "HP_LVC3_E1S_0_HSC_PWRGD_PLD")
	)
	(segment
		(start 182.499 -94.0054)
		(end 177.3682 -94.0054)
		(width 0.127)
		(layer "In11.Cu")
		(net "HP_LVC3_E1S_0_HSC_PWRGD_PLD")
	)
	(segment
		(start 176.3268 -95.8596)
		(end 177.1904 -95.8596)
		(width 0.127)
		(layer "In11.Cu")
		(net "HP_LVC3_E1S_0_HSC_PWRGD_PLD")
	)
	(segment
		(start 192.63106 -75.0062)
		(end 192.63106 -75.0443)
		(width 0.12954)
		(layer "F.Cu")
		(net "HP_E1S_0_P3V3_PWRGD_PLD")
	)
	(segment
		(start 191.80556 -74.1807)
		(end 192.63106 -75.0062)
		(width 0.12954)
		(layer "F.Cu")
		(net "HP_E1S_0_P3V3_PWRGD_PLD")
	)
	(segment
		(start 188.98362 -97.34804)
		(end 190.754 -95.57766)
		(width 0.12954)
		(layer "F.Cu")
		(net "HP_E1S_0_P3V3_PWRGD_PLD")
	)
	(segment
		(start 188.38418 -88.07704)
		(end 188.38418 -75.11034)
		(width 0.12954)
		(layer "F.Cu")
		(net "HP_E1S_0_P3V3_PWRGD_PLD")
	)
	(segment
		(start 190.754 -95.57766)
		(end 190.754 -90.44686)
		(width 0.12954)
		(layer "F.Cu")
		(net "HP_E1S_0_P3V3_PWRGD_PLD")
	)
	(segment
		(start 189.0522 -91.948)
		(end 189.0522 -95.3516)
		(width 0.12954)
		(layer "F.Cu")
		(net "HP_E1S_0_P3V3_PWRGD_PLD")
	)
	(segment
		(start 217.47226 -49.73066)
		(end 217.47226 -48.30699)
		(width 0.12954)
		(layer "F.Cu")
		(net "HP_E1S_0_P3V3_PWRGD_PLD")
	)
	(segment
		(start 180.1368 -91.2876)
		(end 180.5178 -91.6686)
		(width 0.12954)
		(layer "F.Cu")
		(net "HP_E1S_0_P3V3_PWRGD_PLD")
	)
	(segment
		(start 188.32322 -97.34804)
		(end 188.98362 -97.34804)
		(width 0.12954)
		(layer "F.Cu")
		(net "HP_E1S_0_P3V3_PWRGD_PLD")
	)
	(segment
		(start 180.5178 -91.6686)
		(end 188.7728 -91.6686)
		(width 0.12954)
		(layer "F.Cu")
		(net "HP_E1S_0_P3V3_PWRGD_PLD")
	)
	(segment
		(start 177.464974 -104.975406)
		(end 178.2191 -104.22128)
		(width 0.12954)
		(layer "F.Cu")
		(net "HP_E1S_0_P3V3_PWRGD_PLD")
	)
	(segment
		(start 178.58486 -95.4532)
		(end 178.58486 -91.51874)
		(width 0.12954)
		(layer "F.Cu")
		(net "HP_E1S_0_P3V3_PWRGD_PLD")
	)
	(segment
		(start 179.05984 -98.35896)
		(end 179.05984 -95.92818)
		(width 0.12954)
		(layer "F.Cu")
		(net "HP_E1S_0_P3V3_PWRGD_PLD")
	)
	(segment
		(start 218.4527 -50.7111)
		(end 217.47226 -49.73066)
		(width 0.12954)
		(layer "F.Cu")
		(net "HP_E1S_0_P3V3_PWRGD_PLD")
	)
	(segment
		(start 218.4527 -54.68874)
		(end 218.4527 -50.7111)
		(width 0.12954)
		(layer "F.Cu")
		(net "HP_E1S_0_P3V3_PWRGD_PLD")
	)
	(segment
		(start 187.9854 -96.4184)
		(end 187.9854 -97.01022)
		(width 0.12954)
		(layer "F.Cu")
		(net "HP_E1S_0_P3V3_PWRGD_PLD")
	)
	(segment
		(start 178.816 -91.2876)
		(end 180.1368 -91.2876)
		(width 0.12954)
		(layer "F.Cu")
		(net "HP_E1S_0_P3V3_PWRGD_PLD")
	)
	(segment
		(start 178.2191 -100.46716)
		(end 178.73726 -99.949)
		(width 0.12954)
		(layer "F.Cu")
		(net "HP_E1S_0_P3V3_PWRGD_PLD")
	)
	(segment
		(start 188.38418 -75.11034)
		(end 189.31382 -74.1807)
		(width 0.12954)
		(layer "F.Cu")
		(net "HP_E1S_0_P3V3_PWRGD_PLD")
	)
	(segment
		(start 179.05984 -95.92818)
		(end 178.58486 -95.4532)
		(width 0.12954)
		(layer "F.Cu")
		(net "HP_E1S_0_P3V3_PWRGD_PLD")
	)
	(segment
		(start 190.754 -90.44686)
		(end 188.38418 -88.07704)
		(width 0.12954)
		(layer "F.Cu")
		(net "HP_E1S_0_P3V3_PWRGD_PLD")
	)
	(segment
		(start 178.2191 -104.22128)
		(end 178.2191 -100.46716)
		(width 0.12954)
		(layer "F.Cu")
		(net "HP_E1S_0_P3V3_PWRGD_PLD")
	)
	(segment
		(start 188.7728 -91.6686)
		(end 189.0522 -91.948)
		(width 0.12954)
		(layer "F.Cu")
		(net "HP_E1S_0_P3V3_PWRGD_PLD")
	)
	(segment
		(start 189.31382 -74.1807)
		(end 191.80556 -74.1807)
		(width 0.12954)
		(layer "F.Cu")
		(net "HP_E1S_0_P3V3_PWRGD_PLD")
	)
	(segment
		(start 189.0522 -95.3516)
		(end 187.9854 -96.4184)
		(width 0.12954)
		(layer "F.Cu")
		(net "HP_E1S_0_P3V3_PWRGD_PLD")
	)
	(segment
		(start 177.355754 -104.975406)
		(end 177.464974 -104.975406)
		(width 0.12954)
		(layer "F.Cu")
		(net "HP_E1S_0_P3V3_PWRGD_PLD")
	)
	(segment
		(start 178.58486 -91.51874)
		(end 178.816 -91.2876)
		(width 0.12954)
		(layer "F.Cu")
		(net "HP_E1S_0_P3V3_PWRGD_PLD")
	)
	(segment
		(start 178.73726 -99.949)
		(end 178.73726 -98.68154)
		(width 0.12954)
		(layer "F.Cu")
		(net "HP_E1S_0_P3V3_PWRGD_PLD")
	)
	(segment
		(start 178.73726 -98.68154)
		(end 179.05984 -98.35896)
		(width 0.12954)
		(layer "F.Cu")
		(net "HP_E1S_0_P3V3_PWRGD_PLD")
	)
	(segment
		(start 187.9854 -97.01022)
		(end 188.32322 -97.34804)
		(width 0.12954)
		(layer "F.Cu")
		(net "HP_E1S_0_P3V3_PWRGD_PLD")
	)
	(via
		(at 218.4527 -54.68874)
		(size 0.508)
		(drill 0.254)
		(layers "F.Cu" "B.Cu")
		(net "HP_E1S_0_P3V3_PWRGD_PLD")
	)
	(via
		(at 192.63106 -75.0443)
		(size 0.508)
		(drill 0.254)
		(layers "F.Cu" "B.Cu")
		(net "HP_E1S_0_P3V3_PWRGD_PLD")
	)
	(segment
		(start 209.97418 -81.92262)
		(end 221.61754 -81.92262)
		(width 0.127)
		(layer "In6.Cu")
		(net "HP_E1S_0_P3V3_PWRGD_PLD")
	)
	(segment
		(start 193.58356 -75.9968)
		(end 196.80936 -75.9968)
		(width 0.127)
		(layer "In6.Cu")
		(net "HP_E1S_0_P3V3_PWRGD_PLD")
	)
	(segment
		(start 196.80936 -75.9968)
		(end 197.28942 -76.47686)
		(width 0.127)
		(layer "In6.Cu")
		(net "HP_E1S_0_P3V3_PWRGD_PLD")
	)
	(segment
		(start 202.80376 -77.93228)
		(end 204.85862 -79.98714)
		(width 0.127)
		(layer "In6.Cu")
		(net "HP_E1S_0_P3V3_PWRGD_PLD")
	)
	(segment
		(start 228.38664 -75.15352)
		(end 228.38664 -65.3415)
		(width 0.127)
		(layer "In6.Cu")
		(net "HP_E1S_0_P3V3_PWRGD_PLD")
	)
	(segment
		(start 228.38664 -65.3415)
		(end 218.4527 -55.40756)
		(width 0.127)
		(layer "In6.Cu")
		(net "HP_E1S_0_P3V3_PWRGD_PLD")
	)
	(segment
		(start 221.61754 -81.92262)
		(end 228.38664 -75.15352)
		(width 0.127)
		(layer "In6.Cu")
		(net "HP_E1S_0_P3V3_PWRGD_PLD")
	)
	(segment
		(start 204.85862 -79.98714)
		(end 208.0387 -79.98714)
		(width 0.127)
		(layer "In6.Cu")
		(net "HP_E1S_0_P3V3_PWRGD_PLD")
	)
	(segment
		(start 200.14692 -77.93228)
		(end 202.80376 -77.93228)
		(width 0.127)
		(layer "In6.Cu")
		(net "HP_E1S_0_P3V3_PWRGD_PLD")
	)
	(segment
		(start 192.63106 -75.0443)
		(end 193.58356 -75.9968)
		(width 0.127)
		(layer "In6.Cu")
		(net "HP_E1S_0_P3V3_PWRGD_PLD")
	)
	(segment
		(start 208.0387 -79.98714)
		(end 209.97418 -81.92262)
		(width 0.127)
		(layer "In6.Cu")
		(net "HP_E1S_0_P3V3_PWRGD_PLD")
	)
	(segment
		(start 218.4527 -55.40756)
		(end 218.4527 -54.68874)
		(width 0.127)
		(layer "In6.Cu")
		(net "HP_E1S_0_P3V3_PWRGD_PLD")
	)
	(segment
		(start 197.28942 -76.47686)
		(end 198.6915 -76.47686)
		(width 0.127)
		(layer "In6.Cu")
		(net "HP_E1S_0_P3V3_PWRGD_PLD")
	)
	(segment
		(start 198.6915 -76.47686)
		(end 200.14692 -77.93228)
		(width 0.127)
		(layer "In6.Cu")
		(net "HP_E1S_0_P3V3_PWRGD_PLD")
	)
	(segment
		(start 218.2622 -46.6344)
		(end 217.92184 -46.29404)
		(width 0.12954)
		(layer "F.Cu")
		(net "HP_E1S_0_P3V3_PWRGD")
	)
	(segment
		(start 219.006928 -46.6344)
		(end 218.2622 -46.6344)
		(width 0.12954)
		(layer "F.Cu")
		(net "HP_E1S_0_P3V3_PWRGD")
	)
	(segment
		(start 217.92184 -46.29404)
		(end 217.53322 -46.29404)
		(width 0.12954)
		(layer "F.Cu")
		(net "HP_E1S_0_P3V3_PWRGD")
	)
	(segment
		(start 217.47226 -46.355)
		(end 217.47226 -47.50689)
		(width 0.12954)
		(layer "F.Cu")
		(net "HP_E1S_0_P3V3_PWRGD")
	)
	(segment
		(start 217.53322 -46.29404)
		(end 217.47226 -46.355)
		(width 0.12954)
		(layer "F.Cu")
		(net "HP_E1S_0_P3V3_PWRGD")
	)
	(via
		(at 217.53322 -46.29404)
		(size 0.762)
		(drill 0.381)
		(layers "F.Cu" "B.Cu")
		(net "HP_E1S_0_P3V3_PWRGD")
	)
	(segment
		(start 18.940018 -414.277302)
		(end 18.940018 -412.809182)
		(width 0.12954)
		(layer "F.Cu")
		(net "GPU_PRSNT_N_ISO_R1")
	)
	(segment
		(start 19.812 -411.19425)
		(end 19.812 -411.9372)
		(width 0.12954)
		(layer "F.Cu")
		(net "GPU_PRSNT_N_ISO_R1")
	)
	(segment
		(start 18.940018 -412.809182)
		(end 19.304 -412.4452)
		(width 0.12954)
		(layer "F.Cu")
		(net "GPU_PRSNT_N_ISO_R1")
	)
	(segment
		(start 19.812 -411.9372)
		(end 19.304 -412.4452)
		(width 0.12954)
		(layer "F.Cu")
		(net "GPU_PRSNT_N_ISO_R1")
	)
	(via
		(at 19.304 -412.4452)
		(size 0.762)
		(drill 0.381)
		(layers "F.Cu" "B.Cu")
		(net "GPU_PRSNT_N_ISO_R1")
	)
	(segment
		(start 206.1464 -96.0628)
		(end 206.39786 -96.0628)
		(width 0.12954)
		(layer "F.Cu")
		(net "FM_UV_ADR_TRIGGER_N_R2")
	)
	(segment
		(start 205.6384 -97.28835)
		(end 205.6384 -96.26854)
		(width 0.12954)
		(layer "F.Cu")
		(net "FM_UV_ADR_TRIGGER_N_R2")
	)
	(segment
		(start 204.09916 -97.26803)
		(end 205.61808 -97.26803)
		(width 0.12954)
		(layer "F.Cu")
		(net "FM_UV_ADR_TRIGGER_N_R2")
	)
	(segment
		(start 206.39786 -96.0628)
		(end 206.7052 -96.37014)
		(width 0.12954)
		(layer "F.Cu")
		(net "FM_UV_ADR_TRIGGER_N_R2")
	)
	(segment
		(start 205.6384 -96.26854)
		(end 205.84414 -96.0628)
		(width 0.12954)
		(layer "F.Cu")
		(net "FM_UV_ADR_TRIGGER_N_R2")
	)
	(segment
		(start 205.84414 -96.0628)
		(end 206.1464 -96.0628)
		(width 0.12954)
		(layer "F.Cu")
		(net "FM_UV_ADR_TRIGGER_N_R2")
	)
	(segment
		(start 206.7052 -96.37014)
		(end 206.7052 -97.28835)
		(width 0.12954)
		(layer "F.Cu")
		(net "FM_UV_ADR_TRIGGER_N_R2")
	)
	(segment
		(start 205.61808 -97.26803)
		(end 205.6384 -97.28835)
		(width 0.12954)
		(layer "F.Cu")
		(net "FM_UV_ADR_TRIGGER_N_R2")
	)
	(via
		(at 206.1464 -96.0628)
		(size 0.762)
		(drill 0.381)
		(layers "F.Cu" "B.Cu")
		(net "FM_UV_ADR_TRIGGER_N_R2")
	)
	(segment
		(start 361.36072 -402.54555)
		(end 361.36072 -401.8534)
		(width 0.12954)
		(layer "F.Cu")
		(net "FM_PDB_BUF_EN_R")
	)
	(segment
		(start 182.564532 -425.831)
		(end 182.564532 -425.1452)
		(width 0.12954)
		(layer "F.Cu")
		(net "FM_PDB_BUF_EN_R")
	)
	(segment
		(start 245.03888 -165.674548)
		(end 245.52148 -165.191948)
		(width 0.12954)
		(layer "F.Cu")
		(net "FM_PDB_BUF_EN_R")
	)
	(segment
		(start 245.52148 -165.191948)
		(end 245.52148 -160.292796)
		(width 0.12954)
		(layer "F.Cu")
		(net "FM_PDB_BUF_EN_R")
	)
	(segment
		(start 240.032032 -154.803348)
		(end 207.018128 -154.803348)
		(width 0.12954)
		(layer "F.Cu")
		(net "FM_PDB_BUF_EN_R")
	)
	(segment
		(start 186.84748 -156.809948)
		(end 186.84748 -155.920948)
		(width 0.12954)
		(layer "F.Cu")
		(net "FM_PDB_BUF_EN_R")
	)
	(segment
		(start 194.334384 -122.900948)
		(end 194.408044 -122.827288)
		(width 0.12954)
		(layer "F.Cu")
		(net "FM_PDB_BUF_EN_R")
	)
	(segment
		(start 207.018128 -154.803348)
		(end 200.241408 -161.580068)
		(width 0.12954)
		(layer "F.Cu")
		(net "FM_PDB_BUF_EN_R")
	)
	(segment
		(start 245.52148 -160.292796)
		(end 240.032032 -154.803348)
		(width 0.12954)
		(layer "F.Cu")
		(net "FM_PDB_BUF_EN_R")
	)
	(segment
		(start 181.535832 -426.8216)
		(end 182.564532 -426.8216)
		(width 0.12954)
		(layer "F.Cu")
		(net "FM_PDB_BUF_EN_R")
	)
	(segment
		(start 191.6176 -161.580068)
		(end 186.84748 -156.809948)
		(width 0.12954)
		(layer "F.Cu")
		(net "FM_PDB_BUF_EN_R")
	)
	(segment
		(start 193.78041 -122.900948)
		(end 194.334384 -122.900948)
		(width 0.12954)
		(layer "F.Cu")
		(net "FM_PDB_BUF_EN_R")
	)
	(segment
		(start 200.241408 -161.580068)
		(end 191.6176 -161.580068)
		(width 0.12954)
		(layer "F.Cu")
		(net "FM_PDB_BUF_EN_R")
	)
	(segment
		(start 182.564532 -426.8216)
		(end 182.564532 -425.831)
		(width 0.12954)
		(layer "F.Cu")
		(net "FM_PDB_BUF_EN_R")
	)
	(segment
		(start 244.78488 -165.674548)
		(end 245.03888 -165.674548)
		(width 0.12954)
		(layer "F.Cu")
		(net "FM_PDB_BUF_EN_R")
	)
	(via
		(at 186.84748 -155.920948)
		(size 0.508)
		(drill 0.254)
		(layers "F.Cu" "B.Cu")
		(net "FM_PDB_BUF_EN_R")
	)
	(via
		(at 244.78488 -165.674548)
		(size 0.508)
		(drill 0.254)
		(layers "F.Cu" "B.Cu")
		(net "FM_PDB_BUF_EN_R")
	)
	(via
		(at 182.564532 -425.1452)
		(size 0.508)
		(drill 0.254)
		(layers "F.Cu" "B.Cu")
		(net "FM_PDB_BUF_EN_R")
	)
	(via
		(at 300.56328 -405.65832)
		(size 0.508)
		(drill 0.254)
		(layers "F.Cu" "B.Cu")
		(net "FM_PDB_BUF_EN_R")
	)
	(via
		(at 194.408044 -122.827288)
		(size 0.508)
		(drill 0.254)
		(layers "F.Cu" "B.Cu")
		(net "FM_PDB_BUF_EN_R")
	)
	(via
		(at 361.36072 -401.8534)
		(size 0.508)
		(drill 0.254)
		(layers "F.Cu" "B.Cu")
		(net "FM_PDB_BUF_EN_R")
	)
	(via
		(at 352.24466 -397.15694)
		(size 0.508)
		(drill 0.254)
		(layers "F.Cu" "B.Cu")
		(net "FM_PDB_BUF_EN_R")
	)
	(segment
		(start 199.713596 -373.24538)
		(end 216.321894 -373.24538)
		(width 0.127)
		(layer "In2.Cu")
		(net "FM_PDB_BUF_EN_R")
	)
	(segment
		(start 225.88728 -363.679994)
		(end 225.88728 -345.984068)
		(width 0.127)
		(layer "In2.Cu")
		(net "FM_PDB_BUF_EN_R")
	)
	(segment
		(start 175.96358 -419.58768)
		(end 178.67122 -416.88004)
		(width 0.127)
		(layer "In2.Cu")
		(net "FM_PDB_BUF_EN_R")
	)
	(segment
		(start 179.742338 -408.633422)
		(end 179.742338 -393.216638)
		(width 0.127)
		(layer "In2.Cu")
		(net "FM_PDB_BUF_EN_R")
	)
	(segment
		(start 179.742338 -393.216638)
		(end 199.713596 -373.24538)
		(width 0.127)
		(layer "In2.Cu")
		(net "FM_PDB_BUF_EN_R")
	)
	(segment
		(start 178.67122 -409.70454)
		(end 179.742338 -408.633422)
		(width 0.127)
		(layer "In2.Cu")
		(net "FM_PDB_BUF_EN_R")
	)
	(segment
		(start 243.89588 -164.32276)
		(end 243.57076 -164.64788)
		(width 0.127)
		(layer "In2.Cu")
		(net "FM_PDB_BUF_EN_R")
	)
	(segment
		(start 243.57076 -164.64788)
		(end 243.57076 -165.4302)
		(width 0.127)
		(layer "In2.Cu")
		(net "FM_PDB_BUF_EN_R")
	)
	(segment
		(start 182.564532 -425.1452)
		(end 179.48021 -425.1452)
		(width 0.127)
		(layer "In2.Cu")
		(net "FM_PDB_BUF_EN_R")
	)
	(segment
		(start 216.321894 -373.24538)
		(end 225.88728 -363.679994)
		(width 0.127)
		(layer "In2.Cu")
		(net "FM_PDB_BUF_EN_R")
	)
	(segment
		(start 244.61216 -163.89858)
		(end 244.18798 -164.32276)
		(width 0.127)
		(layer "In2.Cu")
		(net "FM_PDB_BUF_EN_R")
	)
	(segment
		(start 245.537228 -163.89858)
		(end 244.61216 -163.89858)
		(width 0.127)
		(layer "In2.Cu")
		(net "FM_PDB_BUF_EN_R")
	)
	(segment
		(start 243.57076 -165.4302)
		(end 243.815108 -165.674548)
		(width 0.127)
		(layer "In2.Cu")
		(net "FM_PDB_BUF_EN_R")
	)
	(segment
		(start 175.96358 -423.13098)
		(end 175.96358 -419.58768)
		(width 0.127)
		(layer "In2.Cu")
		(net "FM_PDB_BUF_EN_R")
	)
	(segment
		(start 177.0634 -424.2308)
		(end 175.96358 -423.13098)
		(width 0.127)
		(layer "In2.Cu")
		(net "FM_PDB_BUF_EN_R")
	)
	(segment
		(start 178.67122 -416.88004)
		(end 178.67122 -409.70454)
		(width 0.127)
		(layer "In2.Cu")
		(net "FM_PDB_BUF_EN_R")
	)
	(segment
		(start 179.48021 -425.1452)
		(end 178.56581 -424.2308)
		(width 0.127)
		(layer "In2.Cu")
		(net "FM_PDB_BUF_EN_R")
	)
	(segment
		(start 249.01906 -239.518952)
		(end 249.01906 -167.380412)
		(width 0.127)
		(layer "In2.Cu")
		(net "FM_PDB_BUF_EN_R")
	)
	(segment
		(start 249.7582 -240.258092)
		(end 249.01906 -239.518952)
		(width 0.127)
		(layer "In2.Cu")
		(net "FM_PDB_BUF_EN_R")
	)
	(segment
		(start 249.01906 -167.380412)
		(end 245.537228 -163.89858)
		(width 0.127)
		(layer "In2.Cu")
		(net "FM_PDB_BUF_EN_R")
	)
	(segment
		(start 178.56581 -424.2308)
		(end 177.0634 -424.2308)
		(width 0.127)
		(layer "In2.Cu")
		(net "FM_PDB_BUF_EN_R")
	)
	(segment
		(start 243.815108 -165.674548)
		(end 244.78488 -165.674548)
		(width 0.127)
		(layer "In2.Cu")
		(net "FM_PDB_BUF_EN_R")
	)
	(segment
		(start 249.7582 -322.113148)
		(end 249.7582 -240.258092)
		(width 0.127)
		(layer "In2.Cu")
		(net "FM_PDB_BUF_EN_R")
	)
	(segment
		(start 225.88728 -345.984068)
		(end 249.7582 -322.113148)
		(width 0.127)
		(layer "In2.Cu")
		(net "FM_PDB_BUF_EN_R")
	)
	(segment
		(start 244.18798 -164.32276)
		(end 243.89588 -164.32276)
		(width 0.127)
		(layer "In2.Cu")
		(net "FM_PDB_BUF_EN_R")
	)
	(segment
		(start 306.295552 -396.55496)
		(end 351.64268 -396.55496)
		(width 0.127)
		(layer "In6.Cu")
		(net "FM_PDB_BUF_EN_R")
	)
	(segment
		(start 299.45584 -398.32534)
		(end 300.15434 -397.62684)
		(width 0.127)
		(layer "In6.Cu")
		(net "FM_PDB_BUF_EN_R")
	)
	(segment
		(start 300.56328 -405.65832)
		(end 299.45584 -404.55088)
		(width 0.127)
		(layer "In6.Cu")
		(net "FM_PDB_BUF_EN_R")
	)
	(segment
		(start 351.64268 -396.55496)
		(end 352.24466 -397.15694)
		(width 0.127)
		(layer "In6.Cu")
		(net "FM_PDB_BUF_EN_R")
	)
	(segment
		(start 300.15434 -397.62684)
		(end 305.223672 -397.62684)
		(width 0.127)
		(layer "In6.Cu")
		(net "FM_PDB_BUF_EN_R")
	)
	(segment
		(start 305.223672 -397.62684)
		(end 306.295552 -396.55496)
		(width 0.127)
		(layer "In6.Cu")
		(net "FM_PDB_BUF_EN_R")
	)
	(segment
		(start 299.45584 -404.55088)
		(end 299.45584 -398.32534)
		(width 0.127)
		(layer "In6.Cu")
		(net "FM_PDB_BUF_EN_R")
	)
	(segment
		(start 194.056 -130.98018)
		(end 194.056 -132.664708)
		(width 0.127)
		(layer "In11.Cu")
		(net "FM_PDB_BUF_EN_R")
	)
	(segment
		(start 300.2026 -409.744418)
		(end 299.104812 -410.842206)
		(width 0.127)
		(layer "In11.Cu")
		(net "FM_PDB_BUF_EN_R")
	)
	(segment
		(start 194.408044 -122.827288)
		(end 193.421 -123.814332)
		(width 0.127)
		(layer "In11.Cu")
		(net "FM_PDB_BUF_EN_R")
	)
	(segment
		(start 194.056 -132.664708)
		(end 193.47688 -133.243828)
		(width 0.127)
		(layer "In11.Cu")
		(net "FM_PDB_BUF_EN_R")
	)
	(segment
		(start 276.61108 -434.943504)
		(end 273.043904 -438.51068)
		(width 0.127)
		(layer "In11.Cu")
		(net "FM_PDB_BUF_EN_R")
	)
	(segment
		(start 198.6915 -438.51068)
		(end 190.15202 -429.9712)
		(width 0.127)
		(layer "In11.Cu")
		(net "FM_PDB_BUF_EN_R")
	)
	(segment
		(start 276.61108 -431.316384)
		(end 276.61108 -434.943504)
		(width 0.127)
		(layer "In11.Cu")
		(net "FM_PDB_BUF_EN_R")
	)
	(segment
		(start 193.47688 -139.664948)
		(end 187.92444 -145.217388)
		(width 0.127)
		(layer "In11.Cu")
		(net "FM_PDB_BUF_EN_R")
	)
	(segment
		(start 186.10072 -422.29024)
		(end 186.10072 -423.13098)
		(width 0.127)
		(layer "In11.Cu")
		(net "FM_PDB_BUF_EN_R")
	)
	(segment
		(start 186.10072 -423.13098)
		(end 187.12434 -424.1546)
		(width 0.127)
		(layer "In11.Cu")
		(net "FM_PDB_BUF_EN_R")
	)
	(segment
		(start 299.104812 -412.448502)
		(end 296.44086 -415.112454)
		(width 0.127)
		(layer "In11.Cu")
		(net "FM_PDB_BUF_EN_R")
	)
	(segment
		(start 186.4741 -421.91686)
		(end 186.10072 -422.29024)
		(width 0.127)
		(layer "In11.Cu")
		(net "FM_PDB_BUF_EN_R")
	)
	(segment
		(start 187.12434 -424.1546)
		(end 187.12434 -425.05376)
		(width 0.127)
		(layer "In11.Cu")
		(net "FM_PDB_BUF_EN_R")
	)
	(segment
		(start 273.043904 -438.51068)
		(end 198.6915 -438.51068)
		(width 0.127)
		(layer "In11.Cu")
		(net "FM_PDB_BUF_EN_R")
	)
	(segment
		(start 185.78068 -153.044144)
		(end 185.78068 -154.854148)
		(width 0.127)
		(layer "In11.Cu")
		(net "FM_PDB_BUF_EN_R")
	)
	(segment
		(start 296.44086 -419.53688)
		(end 296.872914 -419.968934)
		(width 0.127)
		(layer "In11.Cu")
		(net "FM_PDB_BUF_EN_R")
	)
	(segment
		(start 279.247854 -428.67961)
		(end 276.61108 -431.316384)
		(width 0.127)
		(layer "In11.Cu")
		(net "FM_PDB_BUF_EN_R")
	)
	(segment
		(start 193.421 -130.34518)
		(end 194.056 -130.98018)
		(width 0.127)
		(layer "In11.Cu")
		(net "FM_PDB_BUF_EN_R")
	)
	(segment
		(start 185.78068 -154.854148)
		(end 186.84748 -155.920948)
		(width 0.127)
		(layer "In11.Cu")
		(net "FM_PDB_BUF_EN_R")
	)
	(segment
		(start 190.15202 -422.36644)
		(end 189.70244 -421.91686)
		(width 0.127)
		(layer "In11.Cu")
		(net "FM_PDB_BUF_EN_R")
	)
	(segment
		(start 300.56328 -405.65832)
		(end 300.2026 -406.019)
		(width 0.127)
		(layer "In11.Cu")
		(net "FM_PDB_BUF_EN_R")
	)
	(segment
		(start 299.104812 -410.842206)
		(end 299.104812 -412.448502)
		(width 0.127)
		(layer "In11.Cu")
		(net "FM_PDB_BUF_EN_R")
	)
	(segment
		(start 190.15202 -429.9712)
		(end 190.15202 -422.36644)
		(width 0.127)
		(layer "In11.Cu")
		(net "FM_PDB_BUF_EN_R")
	)
	(segment
		(start 193.421 -123.814332)
		(end 193.421 -130.34518)
		(width 0.127)
		(layer "In11.Cu")
		(net "FM_PDB_BUF_EN_R")
	)
	(segment
		(start 296.872914 -419.968934)
		(end 296.872914 -427.507146)
		(width 0.127)
		(layer "In11.Cu")
		(net "FM_PDB_BUF_EN_R")
	)
	(segment
		(start 189.70244 -421.91686)
		(end 186.4741 -421.91686)
		(width 0.127)
		(layer "In11.Cu")
		(net "FM_PDB_BUF_EN_R")
	)
	(segment
		(start 295.70045 -428.67961)
		(end 279.247854 -428.67961)
		(width 0.127)
		(layer "In11.Cu")
		(net "FM_PDB_BUF_EN_R")
	)
	(segment
		(start 187.92444 -150.900384)
		(end 185.78068 -153.044144)
		(width 0.127)
		(layer "In11.Cu")
		(net "FM_PDB_BUF_EN_R")
	)
	(segment
		(start 193.47688 -133.243828)
		(end 193.47688 -139.664948)
		(width 0.127)
		(layer "In11.Cu")
		(net "FM_PDB_BUF_EN_R")
	)
	(segment
		(start 300.2026 -406.019)
		(end 300.2026 -409.744418)
		(width 0.127)
		(layer "In11.Cu")
		(net "FM_PDB_BUF_EN_R")
	)
	(segment
		(start 296.872914 -427.507146)
		(end 295.70045 -428.67961)
		(width 0.127)
		(layer "In11.Cu")
		(net "FM_PDB_BUF_EN_R")
	)
	(segment
		(start 187.0329 -425.1452)
		(end 182.564532 -425.1452)
		(width 0.127)
		(layer "In11.Cu")
		(net "FM_PDB_BUF_EN_R")
	)
	(segment
		(start 187.92444 -145.217388)
		(end 187.92444 -150.900384)
		(width 0.127)
		(layer "In11.Cu")
		(net "FM_PDB_BUF_EN_R")
	)
	(segment
		(start 296.44086 -415.112454)
		(end 296.44086 -419.53688)
		(width 0.127)
		(layer "In11.Cu")
		(net "FM_PDB_BUF_EN_R")
	)
	(segment
		(start 187.12434 -425.05376)
		(end 187.0329 -425.1452)
		(width 0.127)
		(layer "In11.Cu")
		(net "FM_PDB_BUF_EN_R")
	)
	(segment
		(start 355.713792 -400.8882)
		(end 355.006656 -400.181064)
		(width 0.127)
		(layer "In13.Cu")
		(net "FM_PDB_BUF_EN_R")
	)
	(segment
		(start 352.46056 -396.94104)
		(end 352.24466 -397.15694)
		(width 0.127)
		(layer "In13.Cu")
		(net "FM_PDB_BUF_EN_R")
	)
	(segment
		(start 360.39552 -400.8882)
		(end 355.713792 -400.8882)
		(width 0.127)
		(layer "In13.Cu")
		(net "FM_PDB_BUF_EN_R")
	)
	(segment
		(start 355.006656 -400.181064)
		(end 355.006656 -398.397476)
		(width 0.127)
		(layer "In13.Cu")
		(net "FM_PDB_BUF_EN_R")
	)
	(segment
		(start 353.55022 -396.94104)
		(end 352.46056 -396.94104)
		(width 0.127)
		(layer "In13.Cu")
		(net "FM_PDB_BUF_EN_R")
	)
	(segment
		(start 361.36072 -401.8534)
		(end 360.39552 -400.8882)
		(width 0.127)
		(layer "In13.Cu")
		(net "FM_PDB_BUF_EN_R")
	)
	(segment
		(start 355.006656 -398.397476)
		(end 353.55022 -396.94104)
		(width 0.127)
		(layer "In13.Cu")
		(net "FM_PDB_BUF_EN_R")
	)
	(segment
		(start 183.755538 -117.775482)
		(end 184.155588 -118.175532)
		(width 0.12954)
		(layer "F.Cu")
		(net "FM_PDB_BUF_EN")
	)
	(segment
		(start 192.98031 -122.900948)
		(end 192.338452 -122.900948)
		(width 0.12954)
		(layer "F.Cu")
		(net "FM_PDB_BUF_EN")
	)
	(via
		(at 192.338452 -122.900948)
		(size 0.508)
		(drill 0.254)
		(layers "F.Cu" "B.Cu")
		(net "FM_PDB_BUF_EN")
	)
	(via
		(at 184.155588 -118.175532)
		(size 0.4572)
		(drill 0.254)
		(layers "F.Cu" "B.Cu")
		(net "FM_PDB_BUF_EN")
	)
	(segment
		(start 191.60871 -122.900948)
		(end 192.338452 -122.900948)
		(width 0.127)
		(layer "In15.Cu")
		(net "FM_PDB_BUF_EN")
	)
	(segment
		(start 184.399936 -118.175532)
		(end 184.792874 -118.56847)
		(width 0.127)
		(layer "In15.Cu")
		(net "FM_PDB_BUF_EN")
	)
	(segment
		(start 186.704478 -118.56847)
		(end 187.6806 -118.972838)
		(width 0.127)
		(layer "In15.Cu")
		(net "FM_PDB_BUF_EN")
	)
	(segment
		(start 187.6806 -118.972838)
		(end 191.60871 -122.900948)
		(width 0.127)
		(layer "In15.Cu")
		(net "FM_PDB_BUF_EN")
	)
	(segment
		(start 184.155588 -118.175532)
		(end 184.399936 -118.175532)
		(width 0.127)
		(layer "In15.Cu")
		(net "FM_PDB_BUF_EN")
	)
	(segment
		(start 184.792874 -118.56847)
		(end 186.704478 -118.56847)
		(width 0.127)
		(layer "In15.Cu")
		(net "FM_PDB_BUF_EN")
	)
	(segment
		(start 295.33342 -95.8469)
		(end 292.68674 -98.49358)
		(width 0.12954)
		(layer "F.Cu")
		(net "FM_PCH_BMC_RST_R_N")
	)
	(segment
		(start 214.25916 -117.3988)
		(end 212.60816 -115.7478)
		(width 0.12954)
		(layer "F.Cu")
		(net "FM_PCH_BMC_RST_R_N")
	)
	(segment
		(start 275.33854 -98.49358)
		(end 274.42922 -99.4029)
		(width 0.12954)
		(layer "F.Cu")
		(net "FM_PCH_BMC_RST_R_N")
	)
	(segment
		(start 310.1975 -95.8469)
		(end 295.33342 -95.8469)
		(width 0.12954)
		(layer "F.Cu")
		(net "FM_PCH_BMC_RST_R_N")
	)
	(segment
		(start 205.39583 -113.0554)
		(end 205.39583 -112.02924)
		(width 0.12954)
		(layer "F.Cu")
		(net "FM_PCH_BMC_RST_R_N")
	)
	(segment
		(start 206.4512 -115.3668)
		(end 206.4512 -113.0046)
		(width 0.12954)
		(layer "F.Cu")
		(net "FM_PCH_BMC_RST_R_N")
	)
	(segment
		(start 323.231256 -52.652422)
		(end 323.623686 -52.259992)
		(width 0.0889)
		(layer "F.Cu")
		(net "FM_PCH_BMC_RST_R_N")
	)
	(segment
		(start 206.4512 -113.0046)
		(end 205.47584 -112.02924)
		(width 0.12954)
		(layer "F.Cu")
		(net "FM_PCH_BMC_RST_R_N")
	)
	(segment
		(start 323.623686 -52.259992)
		(end 326.686418 -52.259992)
		(width 0.0889)
		(layer "F.Cu")
		(net "FM_PCH_BMC_RST_R_N")
	)
	(segment
		(start 321.03695 -53.345588)
		(end 321.39763 -53.706268)
		(width 0.12954)
		(layer "F.Cu")
		(net "FM_PCH_BMC_RST_R_N")
	)
	(segment
		(start 209.8548 -116.2304)
		(end 207.3148 -116.2304)
		(width 0.12954)
		(layer "F.Cu")
		(net "FM_PCH_BMC_RST_R_N")
	)
	(segment
		(start 210.3374 -115.7478)
		(end 209.8548 -116.2304)
		(width 0.12954)
		(layer "F.Cu")
		(net "FM_PCH_BMC_RST_R_N")
	)
	(segment
		(start 292.68674 -98.49358)
		(end 275.33854 -98.49358)
		(width 0.12954)
		(layer "F.Cu")
		(net "FM_PCH_BMC_RST_R_N")
	)
	(segment
		(start 216.83218 -117.3988)
		(end 214.25916 -117.3988)
		(width 0.12954)
		(layer "F.Cu")
		(net "FM_PCH_BMC_RST_R_N")
	)
	(segment
		(start 322.321682 -53.706268)
		(end 322.831206 -53.196744)
		(width 0.12954)
		(layer "F.Cu")
		(net "FM_PCH_BMC_RST_R_N")
	)
	(segment
		(start 236.83976 -111.90732)
		(end 227.33508 -111.90732)
		(width 0.12954)
		(layer "F.Cu")
		(net "FM_PCH_BMC_RST_R_N")
	)
	(segment
		(start 212.60816 -115.7478)
		(end 210.3374 -115.7478)
		(width 0.12954)
		(layer "F.Cu")
		(net "FM_PCH_BMC_RST_R_N")
	)
	(segment
		(start 327.147174 -51.95189)
		(end 327.41489 -51.95189)
		(width 0.0889)
		(layer "F.Cu")
		(net "FM_PCH_BMC_RST_R_N")
	)
	(segment
		(start 205.47584 -112.02924)
		(end 205.39583 -112.02924)
		(width 0.12954)
		(layer "F.Cu")
		(net "FM_PCH_BMC_RST_R_N")
	)
	(segment
		(start 263.46912 -113.03762)
		(end 237.97006 -113.03762)
		(width 0.12954)
		(layer "F.Cu")
		(net "FM_PCH_BMC_RST_R_N")
	)
	(segment
		(start 326.686418 -52.259992)
		(end 327.147174 -51.95189)
		(width 0.0889)
		(layer "F.Cu")
		(net "FM_PCH_BMC_RST_R_N")
	)
	(segment
		(start 237.97006 -113.03762)
		(end 236.83976 -111.90732)
		(width 0.12954)
		(layer "F.Cu")
		(net "FM_PCH_BMC_RST_R_N")
	)
	(segment
		(start 224.85604 -114.38636)
		(end 222.95866 -114.38636)
		(width 0.12954)
		(layer "F.Cu")
		(net "FM_PCH_BMC_RST_R_N")
	)
	(segment
		(start 322.831206 -53.052472)
		(end 323.231256 -52.652422)
		(width 0.12954)
		(layer "F.Cu")
		(net "FM_PCH_BMC_RST_R_N")
	)
	(segment
		(start 207.3148 -116.2304)
		(end 206.4512 -115.3668)
		(width 0.12954)
		(layer "F.Cu")
		(net "FM_PCH_BMC_RST_R_N")
	)
	(segment
		(start 221.84106 -115.50396)
		(end 218.72702 -115.50396)
		(width 0.12954)
		(layer "F.Cu")
		(net "FM_PCH_BMC_RST_R_N")
	)
	(segment
		(start 322.831206 -53.196744)
		(end 322.831206 -53.052472)
		(width 0.12954)
		(layer "F.Cu")
		(net "FM_PCH_BMC_RST_R_N")
	)
	(segment
		(start 320.398902 -53.345588)
		(end 321.03695 -53.345588)
		(width 0.12954)
		(layer "F.Cu")
		(net "FM_PCH_BMC_RST_R_N")
	)
	(segment
		(start 274.42922 -99.4029)
		(end 274.42922 -102.07752)
		(width 0.12954)
		(layer "F.Cu")
		(net "FM_PCH_BMC_RST_R_N")
	)
	(segment
		(start 310.9722 -96.6216)
		(end 310.1975 -95.8469)
		(width 0.12954)
		(layer "F.Cu")
		(net "FM_PCH_BMC_RST_R_N")
	)
	(segment
		(start 321.39763 -53.706268)
		(end 322.321682 -53.706268)
		(width 0.12954)
		(layer "F.Cu")
		(net "FM_PCH_BMC_RST_R_N")
	)
	(segment
		(start 274.42922 -102.07752)
		(end 263.46912 -113.03762)
		(width 0.12954)
		(layer "F.Cu")
		(net "FM_PCH_BMC_RST_R_N")
	)
	(segment
		(start 319.964562 -53.291232)
		(end 320.344546 -53.291232)
		(width 0.12954)
		(layer "F.Cu")
		(net "FM_PCH_BMC_RST_R_N")
	)
	(segment
		(start 320.344546 -53.291232)
		(end 320.398902 -53.345588)
		(width 0.12954)
		(layer "F.Cu")
		(net "FM_PCH_BMC_RST_R_N")
	)
	(segment
		(start 218.72702 -115.50396)
		(end 216.83218 -117.3988)
		(width 0.12954)
		(layer "F.Cu")
		(net "FM_PCH_BMC_RST_R_N")
	)
	(segment
		(start 227.33508 -111.90732)
		(end 224.85604 -114.38636)
		(width 0.12954)
		(layer "F.Cu")
		(net "FM_PCH_BMC_RST_R_N")
	)
	(segment
		(start 222.95866 -114.38636)
		(end 221.84106 -115.50396)
		(width 0.12954)
		(layer "F.Cu")
		(net "FM_PCH_BMC_RST_R_N")
	)
	(via
		(at 319.964562 -53.291232)
		(size 0.508)
		(drill 0.254)
		(layers "F.Cu" "B.Cu")
		(net "FM_PCH_BMC_RST_R_N")
	)
	(via
		(at 307.5686 -67.3862)
		(size 0.508)
		(drill 0.254)
		(layers "F.Cu" "B.Cu")
		(net "FM_PCH_BMC_RST_R_N")
	)
	(via
		(at 310.9722 -96.6216)
		(size 0.508)
		(drill 0.254)
		(layers "F.Cu" "B.Cu")
		(net "FM_PCH_BMC_RST_R_N")
	)
	(segment
		(start 309.3466 -73.9902)
		(end 309.3466 -75.7174)
		(width 0.127)
		(layer "In2.Cu")
		(net "FM_PCH_BMC_RST_R_N")
	)
	(segment
		(start 309.3466 -75.7174)
		(end 310.9722 -77.343)
		(width 0.127)
		(layer "In2.Cu")
		(net "FM_PCH_BMC_RST_R_N")
	)
	(segment
		(start 308.4322 -68.6054)
		(end 308.4322 -73.0758)
		(width 0.127)
		(layer "In2.Cu")
		(net "FM_PCH_BMC_RST_R_N")
	)
	(segment
		(start 308.4322 -73.0758)
		(end 309.3466 -73.9902)
		(width 0.127)
		(layer "In2.Cu")
		(net "FM_PCH_BMC_RST_R_N")
	)
	(segment
		(start 307.5686 -67.7418)
		(end 308.4322 -68.6054)
		(width 0.127)
		(layer "In2.Cu")
		(net "FM_PCH_BMC_RST_R_N")
	)
	(segment
		(start 310.9722 -77.343)
		(end 310.9722 -96.6216)
		(width 0.127)
		(layer "In2.Cu")
		(net "FM_PCH_BMC_RST_R_N")
	)
	(segment
		(start 307.5686 -67.3862)
		(end 307.5686 -67.7418)
		(width 0.127)
		(layer "In2.Cu")
		(net "FM_PCH_BMC_RST_R_N")
	)
	(segment
		(start 310.896 -61.4172)
		(end 314.714128 -61.4172)
		(width 0.127)
		(layer "In6.Cu")
		(net "FM_PCH_BMC_RST_R_N")
	)
	(segment
		(start 317.79972 -60.310268)
		(end 317.79972 -55.474108)
		(width 0.127)
		(layer "In6.Cu")
		(net "FM_PCH_BMC_RST_R_N")
	)
	(segment
		(start 319.964562 -53.309266)
		(end 319.964562 -53.291232)
		(width 0.127)
		(layer "In6.Cu")
		(net "FM_PCH_BMC_RST_R_N")
	)
	(segment
		(start 317.30442 -60.805568)
		(end 317.79972 -60.310268)
		(width 0.127)
		(layer "In6.Cu")
		(net "FM_PCH_BMC_RST_R_N")
	)
	(segment
		(start 310.5658 -64.389)
		(end 310.5658 -61.7474)
		(width 0.127)
		(layer "In6.Cu")
		(net "FM_PCH_BMC_RST_R_N")
	)
	(segment
		(start 317.79972 -55.474108)
		(end 319.964562 -53.309266)
		(width 0.127)
		(layer "In6.Cu")
		(net "FM_PCH_BMC_RST_R_N")
	)
	(segment
		(start 315.32576 -60.805568)
		(end 317.30442 -60.805568)
		(width 0.127)
		(layer "In6.Cu")
		(net "FM_PCH_BMC_RST_R_N")
	)
	(segment
		(start 310.5658 -61.7474)
		(end 310.896 -61.4172)
		(width 0.127)
		(layer "In6.Cu")
		(net "FM_PCH_BMC_RST_R_N")
	)
	(segment
		(start 307.5686 -67.3862)
		(end 310.5658 -64.389)
		(width 0.127)
		(layer "In6.Cu")
		(net "FM_PCH_BMC_RST_R_N")
	)
	(segment
		(start 314.714128 -61.4172)
		(end 315.32576 -60.805568)
		(width 0.127)
		(layer "In6.Cu")
		(net "FM_PCH_BMC_RST_R_N")
	)
	(segment
		(start 185.355738 -112.175544)
		(end 185.755788 -111.775494)
		(width 0.12954)
		(layer "F.Cu")
		(net "FM_PCH_BMC_RST_N")
	)
	(segment
		(start 203.6445 -112.85982)
		(end 203.84008 -113.0554)
		(width 0.12954)
		(layer "F.Cu")
		(net "FM_PCH_BMC_RST_N")
	)
	(segment
		(start 203.84008 -113.0554)
		(end 204.59573 -113.0554)
		(width 0.12954)
		(layer "F.Cu")
		(net "FM_PCH_BMC_RST_N")
	)
	(via
		(at 203.6445 -112.85982)
		(size 0.508)
		(drill 0.254)
		(layers "F.Cu" "B.Cu")
		(net "FM_PCH_BMC_RST_N")
	)
	(via
		(at 185.755788 -111.775494)
		(size 0.4572)
		(drill 0.254)
		(layers "F.Cu" "B.Cu")
		(net "FM_PCH_BMC_RST_N")
	)
	(segment
		(start 197.616826 -110.28172)
		(end 197.436994 -110.101888)
		(width 0.127)
		(layer "In6.Cu")
		(net "FM_PCH_BMC_RST_N")
	)
	(segment
		(start 187.332366 -111.775494)
		(end 185.755788 -111.775494)
		(width 0.127)
		(layer "In6.Cu")
		(net "FM_PCH_BMC_RST_N")
	)
	(segment
		(start 192.569592 -110.101888)
		(end 191.28486 -111.38662)
		(width 0.127)
		(layer "In6.Cu")
		(net "FM_PCH_BMC_RST_N")
	)
	(segment
		(start 202.61072 -112.85982)
		(end 202.11288 -112.36198)
		(width 0.127)
		(layer "In6.Cu")
		(net "FM_PCH_BMC_RST_N")
	)
	(segment
		(start 199.3392 -112.10036)
		(end 199.3392 -111.089694)
		(width 0.127)
		(layer "In6.Cu")
		(net "FM_PCH_BMC_RST_N")
	)
	(segment
		(start 191.28486 -111.38662)
		(end 187.72124 -111.38662)
		(width 0.127)
		(layer "In6.Cu")
		(net "FM_PCH_BMC_RST_N")
	)
	(segment
		(start 197.436994 -110.101888)
		(end 192.569592 -110.101888)
		(width 0.127)
		(layer "In6.Cu")
		(net "FM_PCH_BMC_RST_N")
	)
	(segment
		(start 202.11288 -112.36198)
		(end 199.60082 -112.36198)
		(width 0.127)
		(layer "In6.Cu")
		(net "FM_PCH_BMC_RST_N")
	)
	(segment
		(start 203.6445 -112.85982)
		(end 202.61072 -112.85982)
		(width 0.127)
		(layer "In6.Cu")
		(net "FM_PCH_BMC_RST_N")
	)
	(segment
		(start 199.3392 -111.089694)
		(end 198.531226 -110.28172)
		(width 0.127)
		(layer "In6.Cu")
		(net "FM_PCH_BMC_RST_N")
	)
	(segment
		(start 198.531226 -110.28172)
		(end 197.616826 -110.28172)
		(width 0.127)
		(layer "In6.Cu")
		(net "FM_PCH_BMC_RST_N")
	)
	(segment
		(start 187.72124 -111.38662)
		(end 187.332366 -111.775494)
		(width 0.127)
		(layer "In6.Cu")
		(net "FM_PCH_BMC_RST_N")
	)
	(segment
		(start 199.60082 -112.36198)
		(end 199.3392 -112.10036)
		(width 0.127)
		(layer "In6.Cu")
		(net "FM_PCH_BMC_RST_N")
	)
	(segment
		(start 151.23541 -62.61481)
		(end 150.76678 -62.14618)
		(width 0.12954)
		(layer "F.Cu")
		(net "FM_AC_PWR_BTN_R_N")
	)
	(segment
		(start 150.99538 -23.94458)
		(end 150.99538 -23.60168)
		(width 0.12954)
		(layer "F.Cu")
		(net "FM_AC_PWR_BTN_R_N")
	)
	(segment
		(start 130.30073 -33.82391)
		(end 131.98094 -32.1437)
		(width 0.12954)
		(layer "F.Cu")
		(net "FM_AC_PWR_BTN_R_N")
	)
	(segment
		(start 150.99538 -23.60168)
		(end 150.68296 -23.28926)
		(width 0.12954)
		(layer "F.Cu")
		(net "FM_AC_PWR_BTN_R_N")
	)
	(segment
		(start 140.9319 -58.04154)
		(end 139.1666 -58.04154)
		(width 0.12954)
		(layer "F.Cu")
		(net "FM_AC_PWR_BTN_R_N")
	)
	(segment
		(start 146.61388 -28.44546)
		(end 149.00148 -28.44546)
		(width 0.12954)
		(layer "F.Cu")
		(net "FM_AC_PWR_BTN_R_N")
	)
	(segment
		(start 216.52865 -121.1326)
		(end 217.2208 -121.1326)
		(width 0.12954)
		(layer "F.Cu")
		(net "FM_AC_PWR_BTN_R_N")
	)
	(segment
		(start 131.98094 -32.1437)
		(end 138.08202 -32.1437)
		(width 0.12954)
		(layer "F.Cu")
		(net "FM_AC_PWR_BTN_R_N")
	)
	(segment
		(start 138.50874 -31.71698)
		(end 140.71854 -31.71698)
		(width 0.12954)
		(layer "F.Cu")
		(net "FM_AC_PWR_BTN_R_N")
	)
	(segment
		(start 130.30073 -45.25391)
		(end 130.30073 -33.82391)
		(width 0.12954)
		(layer "F.Cu")
		(net "FM_AC_PWR_BTN_R_N")
	)
	(segment
		(start 216.52865 -120.142)
		(end 216.52865 -121.1326)
		(width 0.12954)
		(layer "F.Cu")
		(net "FM_AC_PWR_BTN_R_N")
	)
	(segment
		(start 141.54912 -30.8864)
		(end 144.17294 -30.8864)
		(width 0.12954)
		(layer "F.Cu")
		(net "FM_AC_PWR_BTN_R_N")
	)
	(segment
		(start 145.03654 -62.14618)
		(end 140.9319 -58.04154)
		(width 0.12954)
		(layer "F.Cu")
		(net "FM_AC_PWR_BTN_R_N")
	)
	(segment
		(start 144.17294 -30.8864)
		(end 146.61388 -28.44546)
		(width 0.12954)
		(layer "F.Cu")
		(net "FM_AC_PWR_BTN_R_N")
	)
	(segment
		(start 139.1666 -58.04154)
		(end 138.96594 -57.84088)
		(width 0.12954)
		(layer "F.Cu")
		(net "FM_AC_PWR_BTN_R_N")
	)
	(segment
		(start 138.96594 -53.91912)
		(end 130.30073 -45.25391)
		(width 0.12954)
		(layer "F.Cu")
		(net "FM_AC_PWR_BTN_R_N")
	)
	(segment
		(start 140.71854 -31.71698)
		(end 141.54912 -30.8864)
		(width 0.12954)
		(layer "F.Cu")
		(net "FM_AC_PWR_BTN_R_N")
	)
	(segment
		(start 211.04098 -121.92254)
		(end 216.43086 -121.92254)
		(width 0.12954)
		(layer "F.Cu")
		(net "FM_AC_PWR_BTN_R_N")
	)
	(segment
		(start 149.00148 -28.44546)
		(end 151.54148 -25.90546)
		(width 0.12954)
		(layer "F.Cu")
		(net "FM_AC_PWR_BTN_R_N")
	)
	(segment
		(start 150.68296 -23.28926)
		(end 150.68296 -23.13813)
		(width 0.12954)
		(layer "F.Cu")
		(net "FM_AC_PWR_BTN_R_N")
	)
	(segment
		(start 151.54148 -24.49068)
		(end 150.99538 -23.94458)
		(width 0.12954)
		(layer "F.Cu")
		(net "FM_AC_PWR_BTN_R_N")
	)
	(segment
		(start 216.52865 -119.1514)
		(end 216.52865 -120.142)
		(width 0.12954)
		(layer "F.Cu")
		(net "FM_AC_PWR_BTN_R_N")
	)
	(segment
		(start 138.08202 -32.1437)
		(end 138.50874 -31.71698)
		(width 0.12954)
		(layer "F.Cu")
		(net "FM_AC_PWR_BTN_R_N")
	)
	(segment
		(start 150.76678 -62.14618)
		(end 145.03654 -62.14618)
		(width 0.12954)
		(layer "F.Cu")
		(net "FM_AC_PWR_BTN_R_N")
	)
	(segment
		(start 216.43086 -121.92254)
		(end 217.2208 -121.1326)
		(width 0.12954)
		(layer "F.Cu")
		(net "FM_AC_PWR_BTN_R_N")
	)
	(segment
		(start 138.96594 -57.84088)
		(end 138.96594 -53.91912)
		(width 0.12954)
		(layer "F.Cu")
		(net "FM_AC_PWR_BTN_R_N")
	)
	(segment
		(start 151.54148 -25.90546)
		(end 151.54148 -24.49068)
		(width 0.12954)
		(layer "F.Cu")
		(net "FM_AC_PWR_BTN_R_N")
	)
	(via
		(at 282.88615 -388.85749)
		(size 0.508)
		(drill 0.254)
		(layers "F.Cu" "B.Cu")
		(net "FM_AC_PWR_BTN_R_N")
	)
	(via
		(at 151.23541 -62.61481)
		(size 0.508)
		(drill 0.254)
		(layers "F.Cu" "B.Cu")
		(net "FM_AC_PWR_BTN_R_N")
	)
	(via
		(at 233.549952 -421.826182)
		(size 0.6604)
		(drill 0.254)
		(layers "F.Cu" "B.Cu")
		(net "FM_AC_PWR_BTN_R_N")
	)
	(via
		(at 245.8085 -349.62084)
		(size 0.508)
		(drill 0.254)
		(layers "F.Cu" "B.Cu")
		(net "FM_AC_PWR_BTN_R_N")
	)
	(via
		(at 217.2208 -121.1326)
		(size 0.508)
		(drill 0.254)
		(layers "F.Cu" "B.Cu")
		(net "FM_AC_PWR_BTN_R_N")
	)
	(via
		(at 211.04098 -121.92254)
		(size 0.508)
		(drill 0.254)
		(layers "F.Cu" "B.Cu")
		(net "FM_AC_PWR_BTN_R_N")
	)
	(segment
		(start 232.918508 -422.190926)
		(end 233.185208 -422.190926)
		(width 0.12954)
		(layer "B.Cu")
		(net "FM_AC_PWR_BTN_R_N")
	)
	(segment
		(start 233.185208 -422.190926)
		(end 233.549952 -421.826182)
		(width 0.12954)
		(layer "B.Cu")
		(net "FM_AC_PWR_BTN_R_N")
	)
	(segment
		(start 232.497884 -422.61155)
		(end 232.918508 -422.190926)
		(width 0.12954)
		(layer "B.Cu")
		(net "FM_AC_PWR_BTN_R_N")
	)
	(segment
		(start 232.283 -422.61155)
		(end 232.497884 -422.61155)
		(width 0.12954)
		(layer "B.Cu")
		(net "FM_AC_PWR_BTN_R_N")
	)
	(segment
		(start 267.295376 -388.85749)
		(end 282.88615 -388.85749)
		(width 0.127)
		(layer "In2.Cu")
		(net "FM_AC_PWR_BTN_R_N")
	)
	(segment
		(start 245.8085 -367.370614)
		(end 267.295376 -388.85749)
		(width 0.127)
		(layer "In2.Cu")
		(net "FM_AC_PWR_BTN_R_N")
	)
	(segment
		(start 245.8085 -349.62084)
		(end 245.8085 -367.370614)
		(width 0.127)
		(layer "In2.Cu")
		(net "FM_AC_PWR_BTN_R_N")
	)
	(segment
		(start 151.23541 -62.61481)
		(end 159.24911 -62.61481)
		(width 0.127)
		(layer "In4.Cu")
		(net "FM_AC_PWR_BTN_R_N")
	)
	(segment
		(start 210.25612 -122.7074)
		(end 211.04098 -121.92254)
		(width 0.127)
		(layer "In4.Cu")
		(net "FM_AC_PWR_BTN_R_N")
	)
	(segment
		(start 197.6247 -98.88728)
		(end 198.7804 -98.88728)
		(width 0.127)
		(layer "In4.Cu")
		(net "FM_AC_PWR_BTN_R_N")
	)
	(segment
		(start 200.98258 -104.61498)
		(end 205.19771 -108.83011)
		(width 0.127)
		(layer "In4.Cu")
		(net "FM_AC_PWR_BTN_R_N")
	)
	(segment
		(start 206.4639 -114.09934)
		(end 206.4639 -119.56542)
		(width 0.127)
		(layer "In4.Cu")
		(net "FM_AC_PWR_BTN_R_N")
	)
	(segment
		(start 192.23482 -93.4974)
		(end 197.6247 -98.88728)
		(width 0.127)
		(layer "In4.Cu")
		(net "FM_AC_PWR_BTN_R_N")
	)
	(segment
		(start 205.07452 -120.19026)
		(end 205.07452 -121.68124)
		(width 0.127)
		(layer "In4.Cu")
		(net "FM_AC_PWR_BTN_R_N")
	)
	(segment
		(start 189.5729 -79.81188)
		(end 189.5729 -78.4098)
		(width 0.127)
		(layer "In4.Cu")
		(net "FM_AC_PWR_BTN_R_N")
	)
	(segment
		(start 205.19771 -108.83011)
		(end 205.19771 -112.83315)
		(width 0.127)
		(layer "In4.Cu")
		(net "FM_AC_PWR_BTN_R_N")
	)
	(segment
		(start 205.07452 -121.68124)
		(end 206.10068 -122.7074)
		(width 0.127)
		(layer "In4.Cu")
		(net "FM_AC_PWR_BTN_R_N")
	)
	(segment
		(start 198.7804 -98.88728)
		(end 200.98258 -101.08946)
		(width 0.127)
		(layer "In4.Cu")
		(net "FM_AC_PWR_BTN_R_N")
	)
	(segment
		(start 189.87262 -78.11008)
		(end 190.40348 -78.11008)
		(width 0.127)
		(layer "In4.Cu")
		(net "FM_AC_PWR_BTN_R_N")
	)
	(segment
		(start 159.24911 -62.61481)
		(end 160.65754 -64.02324)
		(width 0.127)
		(layer "In4.Cu")
		(net "FM_AC_PWR_BTN_R_N")
	)
	(segment
		(start 200.98258 -101.08946)
		(end 200.98258 -104.61498)
		(width 0.127)
		(layer "In4.Cu")
		(net "FM_AC_PWR_BTN_R_N")
	)
	(segment
		(start 190.40348 -78.11008)
		(end 190.71336 -78.41996)
		(width 0.127)
		(layer "In4.Cu")
		(net "FM_AC_PWR_BTN_R_N")
	)
	(segment
		(start 205.19771 -112.83315)
		(end 206.4639 -114.09934)
		(width 0.127)
		(layer "In4.Cu")
		(net "FM_AC_PWR_BTN_R_N")
	)
	(segment
		(start 206.10068 -122.7074)
		(end 210.25612 -122.7074)
		(width 0.127)
		(layer "In4.Cu")
		(net "FM_AC_PWR_BTN_R_N")
	)
	(segment
		(start 206.00924 -120.02008)
		(end 205.2447 -120.02008)
		(width 0.127)
		(layer "In4.Cu")
		(net "FM_AC_PWR_BTN_R_N")
	)
	(segment
		(start 206.4639 -119.56542)
		(end 206.00924 -120.02008)
		(width 0.127)
		(layer "In4.Cu")
		(net "FM_AC_PWR_BTN_R_N")
	)
	(segment
		(start 190.71336 -78.41996)
		(end 190.71336 -83.08086)
		(width 0.127)
		(layer "In4.Cu")
		(net "FM_AC_PWR_BTN_R_N")
	)
	(segment
		(start 176.480216 -81.15427)
		(end 188.23051 -81.15427)
		(width 0.127)
		(layer "In4.Cu")
		(net "FM_AC_PWR_BTN_R_N")
	)
	(segment
		(start 160.65754 -64.02324)
		(end 160.65754 -65.331594)
		(width 0.127)
		(layer "In4.Cu")
		(net "FM_AC_PWR_BTN_R_N")
	)
	(segment
		(start 190.71336 -83.08086)
		(end 192.23482 -84.60232)
		(width 0.127)
		(layer "In4.Cu")
		(net "FM_AC_PWR_BTN_R_N")
	)
	(segment
		(start 160.65754 -65.331594)
		(end 176.480216 -81.15427)
		(width 0.127)
		(layer "In4.Cu")
		(net "FM_AC_PWR_BTN_R_N")
	)
	(segment
		(start 192.23482 -84.60232)
		(end 192.23482 -93.4974)
		(width 0.127)
		(layer "In4.Cu")
		(net "FM_AC_PWR_BTN_R_N")
	)
	(segment
		(start 188.23051 -81.15427)
		(end 189.5729 -79.81188)
		(width 0.127)
		(layer "In4.Cu")
		(net "FM_AC_PWR_BTN_R_N")
	)
	(segment
		(start 189.5729 -78.4098)
		(end 189.87262 -78.11008)
		(width 0.127)
		(layer "In4.Cu")
		(net "FM_AC_PWR_BTN_R_N")
	)
	(segment
		(start 205.2447 -120.02008)
		(end 205.07452 -120.19026)
		(width 0.127)
		(layer "In4.Cu")
		(net "FM_AC_PWR_BTN_R_N")
	)
	(segment
		(start 286.2707 -408.92222)
		(end 286.2707 -395.2113)
		(width 0.127)
		(layer "In11.Cu")
		(net "FM_AC_PWR_BTN_R_N")
	)
	(segment
		(start 246.10568 -203.61402)
		(end 246.10568 -172.42282)
		(width 0.127)
		(layer "In11.Cu")
		(net "FM_AC_PWR_BTN_R_N")
	)
	(segment
		(start 285.1277 -391.09904)
		(end 282.88615 -388.85749)
		(width 0.127)
		(layer "In11.Cu")
		(net "FM_AC_PWR_BTN_R_N")
	)
	(segment
		(start 233.549952 -421.826182)
		(end 233.549952 -422.73982)
		(width 0.127)
		(layer "In11.Cu")
		(net "FM_AC_PWR_BTN_R_N")
	)
	(segment
		(start 246.10568 -172.42282)
		(end 242.3414 -168.65854)
		(width 0.127)
		(layer "In11.Cu")
		(net "FM_AC_PWR_BTN_R_N")
	)
	(segment
		(start 235.966 -264.00252)
		(end 234.04576 -262.08228)
		(width 0.127)
		(layer "In11.Cu")
		(net "FM_AC_PWR_BTN_R_N")
	)
	(segment
		(start 233.676952 -422.86682)
		(end 241.19586 -422.86682)
		(width 0.127)
		(layer "In11.Cu")
		(net "FM_AC_PWR_BTN_R_N")
	)
	(segment
		(start 234.04576 -262.08228)
		(end 234.04576 -256.26314)
		(width 0.127)
		(layer "In11.Cu")
		(net "FM_AC_PWR_BTN_R_N")
	)
	(segment
		(start 242.3414 -168.65854)
		(end 242.3414 -158.97098)
		(width 0.127)
		(layer "In11.Cu")
		(net "FM_AC_PWR_BTN_R_N")
	)
	(segment
		(start 242.6208 -421.44188)
		(end 271.53616 -421.44188)
		(width 0.127)
		(layer "In11.Cu")
		(net "FM_AC_PWR_BTN_R_N")
	)
	(segment
		(start 245.8085 -349.62084)
		(end 244.6655 -348.47784)
		(width 0.127)
		(layer "In11.Cu")
		(net "FM_AC_PWR_BTN_R_N")
	)
	(segment
		(start 285.1277 -394.0683)
		(end 285.1277 -391.09904)
		(width 0.127)
		(layer "In11.Cu")
		(net "FM_AC_PWR_BTN_R_N")
	)
	(segment
		(start 231.70642 -246.47398)
		(end 233.45902 -244.72138)
		(width 0.127)
		(layer "In11.Cu")
		(net "FM_AC_PWR_BTN_R_N")
	)
	(segment
		(start 279.62098 -416.8013)
		(end 280.9621 -415.46018)
		(width 0.127)
		(layer "In11.Cu")
		(net "FM_AC_PWR_BTN_R_N")
	)
	(segment
		(start 283.25826 -409.46578)
		(end 285.72714 -409.46578)
		(width 0.127)
		(layer "In11.Cu")
		(net "FM_AC_PWR_BTN_R_N")
	)
	(segment
		(start 245.83644 -203.90358)
		(end 245.83644 -203.88326)
		(width 0.127)
		(layer "In11.Cu")
		(net "FM_AC_PWR_BTN_R_N")
	)
	(segment
		(start 233.549952 -422.73982)
		(end 233.676952 -422.86682)
		(width 0.127)
		(layer "In11.Cu")
		(net "FM_AC_PWR_BTN_R_N")
	)
	(segment
		(start 280.9621 -415.46018)
		(end 280.9621 -411.76194)
		(width 0.127)
		(layer "In11.Cu")
		(net "FM_AC_PWR_BTN_R_N")
	)
	(segment
		(start 280.9621 -411.76194)
		(end 283.25826 -409.46578)
		(width 0.127)
		(layer "In11.Cu")
		(net "FM_AC_PWR_BTN_R_N")
	)
	(segment
		(start 217.2208 -125.65634)
		(end 217.2208 -121.1326)
		(width 0.127)
		(layer "In11.Cu")
		(net "FM_AC_PWR_BTN_R_N")
	)
	(segment
		(start 244.6655 -268.65072)
		(end 240.0173 -264.00252)
		(width 0.127)
		(layer "In11.Cu")
		(net "FM_AC_PWR_BTN_R_N")
	)
	(segment
		(start 233.45902 -244.72138)
		(end 233.45902 -216.281)
		(width 0.127)
		(layer "In11.Cu")
		(net "FM_AC_PWR_BTN_R_N")
	)
	(segment
		(start 241.19586 -422.86682)
		(end 242.6208 -421.44188)
		(width 0.127)
		(layer "In11.Cu")
		(net "FM_AC_PWR_BTN_R_N")
	)
	(segment
		(start 231.70642 -253.9238)
		(end 231.70642 -246.47398)
		(width 0.127)
		(layer "In11.Cu")
		(net "FM_AC_PWR_BTN_R_N")
	)
	(segment
		(start 244.6655 -348.47784)
		(end 244.6655 -268.65072)
		(width 0.127)
		(layer "In11.Cu")
		(net "FM_AC_PWR_BTN_R_N")
	)
	(segment
		(start 240.0173 -264.00252)
		(end 235.966 -264.00252)
		(width 0.127)
		(layer "In11.Cu")
		(net "FM_AC_PWR_BTN_R_N")
	)
	(segment
		(start 277.5839 -416.8013)
		(end 279.62098 -416.8013)
		(width 0.127)
		(layer "In11.Cu")
		(net "FM_AC_PWR_BTN_R_N")
	)
	(segment
		(start 233.45902 -216.281)
		(end 245.83644 -203.90358)
		(width 0.127)
		(layer "In11.Cu")
		(net "FM_AC_PWR_BTN_R_N")
	)
	(segment
		(start 271.53616 -421.44188)
		(end 275.463 -417.51504)
		(width 0.127)
		(layer "In11.Cu")
		(net "FM_AC_PWR_BTN_R_N")
	)
	(segment
		(start 286.2707 -395.2113)
		(end 285.1277 -394.0683)
		(width 0.127)
		(layer "In11.Cu")
		(net "FM_AC_PWR_BTN_R_N")
	)
	(segment
		(start 245.83644 -203.88326)
		(end 246.10568 -203.61402)
		(width 0.127)
		(layer "In11.Cu")
		(net "FM_AC_PWR_BTN_R_N")
	)
	(segment
		(start 234.04576 -256.26314)
		(end 231.70642 -253.9238)
		(width 0.127)
		(layer "In11.Cu")
		(net "FM_AC_PWR_BTN_R_N")
	)
	(segment
		(start 275.463 -417.51504)
		(end 276.87016 -417.51504)
		(width 0.127)
		(layer "In11.Cu")
		(net "FM_AC_PWR_BTN_R_N")
	)
	(segment
		(start 276.87016 -417.51504)
		(end 277.5839 -416.8013)
		(width 0.127)
		(layer "In11.Cu")
		(net "FM_AC_PWR_BTN_R_N")
	)
	(segment
		(start 219.1893 -135.81888)
		(end 219.1893 -130.04292)
		(width 0.127)
		(layer "In11.Cu")
		(net "FM_AC_PWR_BTN_R_N")
	)
	(segment
		(start 219.1893 -130.04292)
		(end 217.9447 -128.79832)
		(width 0.127)
		(layer "In11.Cu")
		(net "FM_AC_PWR_BTN_R_N")
	)
	(segment
		(start 217.9447 -126.38024)
		(end 217.2208 -125.65634)
		(width 0.127)
		(layer "In11.Cu")
		(net "FM_AC_PWR_BTN_R_N")
	)
	(segment
		(start 285.72714 -409.46578)
		(end 286.2707 -408.92222)
		(width 0.127)
		(layer "In11.Cu")
		(net "FM_AC_PWR_BTN_R_N")
	)
	(segment
		(start 217.9447 -128.79832)
		(end 217.9447 -126.38024)
		(width 0.127)
		(layer "In11.Cu")
		(net "FM_AC_PWR_BTN_R_N")
	)
	(segment
		(start 242.3414 -158.97098)
		(end 219.1893 -135.81888)
		(width 0.127)
		(layer "In11.Cu")
		(net "FM_AC_PWR_BTN_R_N")
	)
	(segment
		(start 214.278972 -119.807228)
		(end 214.4522 -119.634)
		(width 0.12954)
		(layer "F.Cu")
		(net "FM_AC_PWR_BTN_PLD_N")
	)
	(segment
		(start 214.5284 -119.1514)
		(end 215.72855 -119.1514)
		(width 0.12954)
		(layer "F.Cu")
		(net "FM_AC_PWR_BTN_PLD_N")
	)
	(segment
		(start 214.52078 -119.15902)
		(end 214.5284 -119.1514)
		(width 0.12954)
		(layer "F.Cu")
		(net "FM_AC_PWR_BTN_PLD_N")
	)
	(segment
		(start 213.249256 -119.807228)
		(end 214.278972 -119.807228)
		(width 0.12954)
		(layer "F.Cu")
		(net "FM_AC_PWR_BTN_PLD_N")
	)
	(segment
		(start 214.4522 -119.2276)
		(end 214.52078 -119.15902)
		(width 0.12954)
		(layer "F.Cu")
		(net "FM_AC_PWR_BTN_PLD_N")
	)
	(segment
		(start 214.4522 -119.634)
		(end 214.4522 -119.2276)
		(width 0.12954)
		(layer "F.Cu")
		(net "FM_AC_PWR_BTN_PLD_N")
	)
	(via
		(at 214.52078 -119.15902)
		(size 0.762)
		(drill 0.381)
		(layers "F.Cu" "B.Cu")
		(net "FM_AC_PWR_BTN_PLD_N")
	)
	(segment
		(start 211.349336 -119.807228)
		(end 210.0834 -119.807228)
		(width 0.12954)
		(layer "F.Cu")
		(net "FM_AC_PWR_BTN_PLD_ISO_R_N")
	)
	(segment
		(start 210.011772 -119.807228)
		(end 209.7024 -120.1166)
		(width 0.12954)
		(layer "F.Cu")
		(net "FM_AC_PWR_BTN_PLD_ISO_R_N")
	)
	(segment
		(start 210.0834 -119.807228)
		(end 210.011772 -119.807228)
		(width 0.12954)
		(layer "F.Cu")
		(net "FM_AC_PWR_BTN_PLD_ISO_R_N")
	)
	(segment
		(start 209.7024 -120.1166)
		(end 208.89341 -120.1166)
		(width 0.12954)
		(layer "F.Cu")
		(net "FM_AC_PWR_BTN_PLD_ISO_R_N")
	)
	(via
		(at 210.0834 -119.807228)
		(size 0.762)
		(drill 0.381)
		(layers "F.Cu" "B.Cu")
		(net "FM_AC_PWR_BTN_PLD_ISO_R_N")
	)
	(segment
		(start 182.155592 -116.975382)
		(end 182.555642 -117.375432)
		(width 0.12954)
		(layer "F.Cu")
		(net "FM_AC_PWR_BTN_PLD_ISO_N")
	)
	(segment
		(start 208.09331 -120.1166)
		(end 208.09331 -119.1006)
		(width 0.12954)
		(layer "F.Cu")
		(net "FM_AC_PWR_BTN_PLD_ISO_N")
	)
	(segment
		(start 208.09331 -120.1166)
		(end 207.3656 -120.1166)
		(width 0.12954)
		(layer "F.Cu")
		(net "FM_AC_PWR_BTN_PLD_ISO_N")
	)
	(via
		(at 182.555642 -117.375432)
		(size 0.4572)
		(drill 0.254)
		(layers "F.Cu" "B.Cu")
		(net "FM_AC_PWR_BTN_PLD_ISO_N")
	)
	(via
		(at 207.3656 -120.1166)
		(size 0.508)
		(drill 0.254)
		(layers "F.Cu" "B.Cu")
		(net "FM_AC_PWR_BTN_PLD_ISO_N")
	)
	(segment
		(start 198.17461 -119.98198)
		(end 200.30948 -119.98198)
		(width 0.127)
		(layer "In6.Cu")
		(net "FM_AC_PWR_BTN_PLD_ISO_N")
	)
	(segment
		(start 184.7342 -117.77472)
		(end 189.66942 -117.77472)
		(width 0.127)
		(layer "In6.Cu")
		(net "FM_AC_PWR_BTN_PLD_ISO_N")
	)
	(segment
		(start 182.613808 -117.375432)
		(end 182.94858 -117.04066)
		(width 0.127)
		(layer "In6.Cu")
		(net "FM_AC_PWR_BTN_PLD_ISO_N")
	)
	(segment
		(start 182.94858 -116.412772)
		(end 183.192928 -116.168424)
		(width 0.127)
		(layer "In6.Cu")
		(net "FM_AC_PWR_BTN_PLD_ISO_N")
	)
	(segment
		(start 183.192928 -116.168424)
		(end 184.314084 -116.168424)
		(width 0.127)
		(layer "In6.Cu")
		(net "FM_AC_PWR_BTN_PLD_ISO_N")
	)
	(segment
		(start 189.66942 -117.77472)
		(end 191.60998 -119.71528)
		(width 0.127)
		(layer "In6.Cu")
		(net "FM_AC_PWR_BTN_PLD_ISO_N")
	)
	(segment
		(start 184.314084 -116.168424)
		(end 184.55132 -116.40566)
		(width 0.127)
		(layer "In6.Cu")
		(net "FM_AC_PWR_BTN_PLD_ISO_N")
	)
	(segment
		(start 182.555642 -117.375432)
		(end 182.613808 -117.375432)
		(width 0.127)
		(layer "In6.Cu")
		(net "FM_AC_PWR_BTN_PLD_ISO_N")
	)
	(segment
		(start 193.52006 -120.15724)
		(end 197.99935 -120.15724)
		(width 0.127)
		(layer "In6.Cu")
		(net "FM_AC_PWR_BTN_PLD_ISO_N")
	)
	(segment
		(start 182.94858 -117.04066)
		(end 182.94858 -116.412772)
		(width 0.127)
		(layer "In6.Cu")
		(net "FM_AC_PWR_BTN_PLD_ISO_N")
	)
	(segment
		(start 197.99935 -120.15724)
		(end 198.17461 -119.98198)
		(width 0.127)
		(layer "In6.Cu")
		(net "FM_AC_PWR_BTN_PLD_ISO_N")
	)
	(segment
		(start 184.55132 -116.40566)
		(end 184.55132 -117.59184)
		(width 0.127)
		(layer "In6.Cu")
		(net "FM_AC_PWR_BTN_PLD_ISO_N")
	)
	(segment
		(start 203.65212 -121.1326)
		(end 206.3496 -121.1326)
		(width 0.127)
		(layer "In6.Cu")
		(net "FM_AC_PWR_BTN_PLD_ISO_N")
	)
	(segment
		(start 203.45781 -120.93829)
		(end 203.65212 -121.1326)
		(width 0.127)
		(layer "In6.Cu")
		(net "FM_AC_PWR_BTN_PLD_ISO_N")
	)
	(segment
		(start 200.472548 -120.145048)
		(end 203.138278 -120.145048)
		(width 0.127)
		(layer "In6.Cu")
		(net "FM_AC_PWR_BTN_PLD_ISO_N")
	)
	(segment
		(start 206.3496 -121.1326)
		(end 207.3656 -120.1166)
		(width 0.127)
		(layer "In6.Cu")
		(net "FM_AC_PWR_BTN_PLD_ISO_N")
	)
	(segment
		(start 203.45781 -120.46458)
		(end 203.45781 -120.93829)
		(width 0.127)
		(layer "In6.Cu")
		(net "FM_AC_PWR_BTN_PLD_ISO_N")
	)
	(segment
		(start 203.138278 -120.145048)
		(end 203.45781 -120.46458)
		(width 0.127)
		(layer "In6.Cu")
		(net "FM_AC_PWR_BTN_PLD_ISO_N")
	)
	(segment
		(start 193.0781 -119.71528)
		(end 193.52006 -120.15724)
		(width 0.127)
		(layer "In6.Cu")
		(net "FM_AC_PWR_BTN_PLD_ISO_N")
	)
	(segment
		(start 191.60998 -119.71528)
		(end 193.0781 -119.71528)
		(width 0.127)
		(layer "In6.Cu")
		(net "FM_AC_PWR_BTN_PLD_ISO_N")
	)
	(segment
		(start 200.30948 -119.98198)
		(end 200.472548 -120.145048)
		(width 0.127)
		(layer "In6.Cu")
		(net "FM_AC_PWR_BTN_PLD_ISO_N")
	)
	(segment
		(start 184.55132 -117.59184)
		(end 184.7342 -117.77472)
		(width 0.127)
		(layer "In6.Cu")
		(net "FM_AC_PWR_BTN_PLD_ISO_N")
	)
	(via
		(at 232.283 -424.5356)
		(size 0.508)
		(drill 0.254)
		(layers "F.Cu" "B.Cu")
		(net "FM_AC_PWR_BTN_PDB_N")
	)
	(segment
		(start 232.283 -423.41165)
		(end 233.2482 -423.41165)
		(width 0.12954)
		(layer "B.Cu")
		(net "FM_AC_PWR_BTN_PDB_N")
	)
	(segment
		(start 232.283 -423.41165)
		(end 232.283 -424.5356)
		(width 0.12954)
		(layer "B.Cu")
		(net "FM_AC_PWR_BTN_PDB_N")
	)
	(segment
		(start 234.2642 -424.0022)
		(end 232.8164 -424.0022)
		(width 0.127)
		(layer "In2.Cu")
		(net "FM_AC_PWR_BTN_PDB_N")
	)
	(segment
		(start 232.8164 -424.0022)
		(end 232.283 -424.5356)
		(width 0.127)
		(layer "In2.Cu")
		(net "FM_AC_PWR_BTN_PDB_N")
	)
	(segment
		(start 234.6071 -434.27904)
		(end 234.6071 -424.3451)
		(width 0.127)
		(layer "In2.Cu")
		(net "FM_AC_PWR_BTN_PDB_N")
	)
	(segment
		(start 234.6071 -424.3451)
		(end 234.2642 -424.0022)
		(width 0.127)
		(layer "In2.Cu")
		(net "FM_AC_PWR_BTN_PDB_N")
	)
	(segment
		(start 235.91012 -435.58206)
		(end 234.6071 -434.27904)
		(width 0.127)
		(layer "In2.Cu")
		(net "FM_AC_PWR_BTN_PDB_N")
	)
	(segment
		(start 150.68296 -20.8407)
		(end 150.68296 -22.33803)
		(width 0.12954)
		(layer "F.Cu")
		(net "FM_AC_PWR_BTN_N")
	)
	(segment
		(start 150.43531 -19.750278)
		(end 150.43531 -20.59305)
		(width 0.12954)
		(layer "F.Cu")
		(net "FM_AC_PWR_BTN_N")
	)
	(segment
		(start 150.85695 -19.328638)
		(end 150.43531 -19.750278)
		(width 0.12954)
		(layer "F.Cu")
		(net "FM_AC_PWR_BTN_N")
	)
	(segment
		(start 150.43531 -20.59305)
		(end 150.68296 -20.8407)
		(width 0.12954)
		(layer "F.Cu")
		(net "FM_AC_PWR_BTN_N")
	)
	(segment
		(start 150.85695 -16.550132)
		(end 150.85695 -19.328638)
		(width 0.12954)
		(layer "F.Cu")
		(net "FM_AC_PWR_BTN_N")
	)
	(via
		(at 150.43531 -19.750278)
		(size 0.762)
		(drill 0.381)
		(layers "F.Cu" "B.Cu")
		(net "FM_AC_PWR_BTN_N")
	)
	(segment
		(start 178.1556 -108.975398)
		(end 177.75555 -108.575348)
		(width 0.12954)
		(layer "F.Cu")
		(net "E1S_0_CLK_OE_N")
	)
	(via
		(at 304.02022 -32.17926)
		(size 0.6604)
		(drill 0.3302)
		(layers "F.Cu" "B.Cu")
		(net "E1S_0_CLK_OE_N")
	)
	(via
		(at 295.06926 -95.02394)
		(size 0.508)
		(drill 0.254)
		(layers "F.Cu" "B.Cu")
		(net "E1S_0_CLK_OE_N")
	)
	(via
		(at 177.75555 -108.575348)
		(size 0.4572)
		(drill 0.254)
		(layers "F.Cu" "B.Cu")
		(net "E1S_0_CLK_OE_N")
	)
	(via
		(at 296.85234 -44.85386)
		(size 0.508)
		(drill 0.254)
		(layers "F.Cu" "B.Cu")
		(net "E1S_0_CLK_OE_N")
	)
	(segment
		(start 295.7322 -36.26612)
		(end 299.81906 -32.17926)
		(width 0.12954)
		(layer "B.Cu")
		(net "E1S_0_CLK_OE_N")
	)
	(segment
		(start 296.85234 -44.85386)
		(end 295.7322 -43.73372)
		(width 0.12954)
		(layer "B.Cu")
		(net "E1S_0_CLK_OE_N")
	)
	(segment
		(start 307.07584 -33.83026)
		(end 307.07584 -32.5247)
		(width 0.12954)
		(layer "B.Cu")
		(net "E1S_0_CLK_OE_N")
	)
	(segment
		(start 295.7322 -43.73372)
		(end 295.7322 -36.26612)
		(width 0.12954)
		(layer "B.Cu")
		(net "E1S_0_CLK_OE_N")
	)
	(segment
		(start 307.43398 -34.1884)
		(end 307.07584 -33.83026)
		(width 0.12954)
		(layer "B.Cu")
		(net "E1S_0_CLK_OE_N")
	)
	(segment
		(start 307.07584 -32.5247)
		(end 306.7304 -32.17926)
		(width 0.12954)
		(layer "B.Cu")
		(net "E1S_0_CLK_OE_N")
	)
	(segment
		(start 306.7304 -32.17926)
		(end 304.02022 -32.17926)
		(width 0.12954)
		(layer "B.Cu")
		(net "E1S_0_CLK_OE_N")
	)
	(segment
		(start 309.15737 -34.18078)
		(end 309.14975 -34.1884)
		(width 0.12954)
		(layer "B.Cu")
		(net "E1S_0_CLK_OE_N")
	)
	(segment
		(start 299.81906 -32.17926)
		(end 304.02022 -32.17926)
		(width 0.12954)
		(layer "B.Cu")
		(net "E1S_0_CLK_OE_N")
	)
	(segment
		(start 309.14975 -34.1884)
		(end 307.43398 -34.1884)
		(width 0.12954)
		(layer "B.Cu")
		(net "E1S_0_CLK_OE_N")
	)
	(segment
		(start 309.15737 -33.22574)
		(end 309.15737 -34.18078)
		(width 0.12954)
		(layer "B.Cu")
		(net "E1S_0_CLK_OE_N")
	)
	(segment
		(start 299.80382 -75.28814)
		(end 301.29734 -73.79462)
		(width 0.127)
		(layer "In2.Cu")
		(net "E1S_0_CLK_OE_N")
	)
	(segment
		(start 297.1292 -53.52796)
		(end 297.1292 -45.14342)
		(width 0.127)
		(layer "In2.Cu")
		(net "E1S_0_CLK_OE_N")
	)
	(segment
		(start 292.88994 -85.13572)
		(end 298.7929 -79.23276)
		(width 0.127)
		(layer "In2.Cu")
		(net "E1S_0_CLK_OE_N")
	)
	(segment
		(start 297.1292 -45.14342)
		(end 296.85234 -44.86656)
		(width 0.127)
		(layer "In2.Cu")
		(net "E1S_0_CLK_OE_N")
	)
	(segment
		(start 295.06926 -95.02394)
		(end 292.88994 -92.84462)
		(width 0.127)
		(layer "In2.Cu")
		(net "E1S_0_CLK_OE_N")
	)
	(segment
		(start 298.64812 -55.04688)
		(end 297.1292 -53.52796)
		(width 0.127)
		(layer "In2.Cu")
		(net "E1S_0_CLK_OE_N")
	)
	(segment
		(start 298.7929 -77.72908)
		(end 299.80382 -75.28814)
		(width 0.127)
		(layer "In2.Cu")
		(net "E1S_0_CLK_OE_N")
	)
	(segment
		(start 296.85234 -44.86656)
		(end 296.85234 -44.85386)
		(width 0.127)
		(layer "In2.Cu")
		(net "E1S_0_CLK_OE_N")
	)
	(segment
		(start 298.7929 -79.23276)
		(end 298.7929 -77.72908)
		(width 0.127)
		(layer "In2.Cu")
		(net "E1S_0_CLK_OE_N")
	)
	(segment
		(start 298.64812 -61.16828)
		(end 298.64812 -55.04688)
		(width 0.127)
		(layer "In2.Cu")
		(net "E1S_0_CLK_OE_N")
	)
	(segment
		(start 301.29734 -63.8175)
		(end 298.64812 -61.16828)
		(width 0.127)
		(layer "In2.Cu")
		(net "E1S_0_CLK_OE_N")
	)
	(segment
		(start 301.29734 -73.79462)
		(end 301.29734 -63.8175)
		(width 0.127)
		(layer "In2.Cu")
		(net "E1S_0_CLK_OE_N")
	)
	(segment
		(start 292.88994 -92.84462)
		(end 292.88994 -85.13572)
		(width 0.127)
		(layer "In2.Cu")
		(net "E1S_0_CLK_OE_N")
	)
	(segment
		(start 189.0268 -93.929454)
		(end 193.853054 -89.1032)
		(width 0.127)
		(layer "In13.Cu")
		(net "E1S_0_CLK_OE_N")
	)
	(segment
		(start 189.0268 -95.3262)
		(end 189.0268 -93.929454)
		(width 0.127)
		(layer "In13.Cu")
		(net "E1S_0_CLK_OE_N")
	)
	(segment
		(start 188.1124 -96.2406)
		(end 189.0268 -95.3262)
		(width 0.127)
		(layer "In13.Cu")
		(net "E1S_0_CLK_OE_N")
	)
	(segment
		(start 179.9336 -104.8512)
		(end 179.9336 -102.108)
		(width 0.127)
		(layer "In13.Cu")
		(net "E1S_0_CLK_OE_N")
	)
	(segment
		(start 254.14478 -88.82888)
		(end 276.10562 -88.82888)
		(width 0.127)
		(layer "In13.Cu")
		(net "E1S_0_CLK_OE_N")
	)
	(segment
		(start 204.122782 -89.676732)
		(end 205.796134 -89.676732)
		(width 0.127)
		(layer "In13.Cu")
		(net "E1S_0_CLK_OE_N")
	)
	(segment
		(start 220.24086 -93.78188)
		(end 242.99926 -93.78188)
		(width 0.127)
		(layer "In13.Cu")
		(net "E1S_0_CLK_OE_N")
	)
	(segment
		(start 251.74448 -91.22918)
		(end 254.14478 -88.82888)
		(width 0.127)
		(layer "In13.Cu")
		(net "E1S_0_CLK_OE_N")
	)
	(segment
		(start 242.99926 -93.78188)
		(end 245.55196 -91.22918)
		(width 0.127)
		(layer "In13.Cu")
		(net "E1S_0_CLK_OE_N")
	)
	(segment
		(start 193.853054 -89.1032)
		(end 203.54925 -89.1032)
		(width 0.127)
		(layer "In13.Cu")
		(net "E1S_0_CLK_OE_N")
	)
	(segment
		(start 185.6232 -98.7552)
		(end 185.6232 -98.4758)
		(width 0.127)
		(layer "In13.Cu")
		(net "E1S_0_CLK_OE_N")
	)
	(segment
		(start 184.746392 -99.632008)
		(end 185.6232 -98.7552)
		(width 0.127)
		(layer "In13.Cu")
		(net "E1S_0_CLK_OE_N")
	)
	(segment
		(start 293.4208 -95.39732)
		(end 294.40632 -95.39732)
		(width 0.127)
		(layer "In13.Cu")
		(net "E1S_0_CLK_OE_N")
	)
	(segment
		(start 178.6128 -108.2802)
		(end 178.6128 -106.172)
		(width 0.127)
		(layer "In13.Cu")
		(net "E1S_0_CLK_OE_N")
	)
	(segment
		(start 185.6232 -98.4758)
		(end 186.0042 -98.0948)
		(width 0.127)
		(layer "In13.Cu")
		(net "E1S_0_CLK_OE_N")
	)
	(segment
		(start 181.3814 -100.6602)
		(end 182.245 -100.6602)
		(width 0.127)
		(layer "In13.Cu")
		(net "E1S_0_CLK_OE_N")
	)
	(segment
		(start 177.75555 -108.575348)
		(end 178.317652 -108.575348)
		(width 0.127)
		(layer "In13.Cu")
		(net "E1S_0_CLK_OE_N")
	)
	(segment
		(start 245.55196 -91.22918)
		(end 251.74448 -91.22918)
		(width 0.127)
		(layer "In13.Cu")
		(net "E1S_0_CLK_OE_N")
	)
	(segment
		(start 205.796134 -89.676732)
		(end 206.369666 -89.1032)
		(width 0.127)
		(layer "In13.Cu")
		(net "E1S_0_CLK_OE_N")
	)
	(segment
		(start 206.369666 -89.1032)
		(end 215.56218 -89.1032)
		(width 0.127)
		(layer "In13.Cu")
		(net "E1S_0_CLK_OE_N")
	)
	(segment
		(start 281.95016 -94.67342)
		(end 292.6969 -94.67342)
		(width 0.127)
		(layer "In13.Cu")
		(net "E1S_0_CLK_OE_N")
	)
	(segment
		(start 178.317652 -108.575348)
		(end 178.6128 -108.2802)
		(width 0.127)
		(layer "In13.Cu")
		(net "E1S_0_CLK_OE_N")
	)
	(segment
		(start 294.7797 -95.02394)
		(end 295.06926 -95.02394)
		(width 0.127)
		(layer "In13.Cu")
		(net "E1S_0_CLK_OE_N")
	)
	(segment
		(start 187.706 -98.0948)
		(end 188.1124 -97.6884)
		(width 0.127)
		(layer "In13.Cu")
		(net "E1S_0_CLK_OE_N")
	)
	(segment
		(start 292.6969 -94.67342)
		(end 293.4208 -95.39732)
		(width 0.127)
		(layer "In13.Cu")
		(net "E1S_0_CLK_OE_N")
	)
	(segment
		(start 294.40632 -95.39732)
		(end 294.7797 -95.02394)
		(width 0.127)
		(layer "In13.Cu")
		(net "E1S_0_CLK_OE_N")
	)
	(segment
		(start 188.1124 -97.6884)
		(end 188.1124 -96.2406)
		(width 0.127)
		(layer "In13.Cu")
		(net "E1S_0_CLK_OE_N")
	)
	(segment
		(start 182.245 -100.6602)
		(end 183.273192 -99.632008)
		(width 0.127)
		(layer "In13.Cu")
		(net "E1S_0_CLK_OE_N")
	)
	(segment
		(start 215.56218 -89.1032)
		(end 220.24086 -93.78188)
		(width 0.127)
		(layer "In13.Cu")
		(net "E1S_0_CLK_OE_N")
	)
	(segment
		(start 178.6128 -106.172)
		(end 179.9336 -104.8512)
		(width 0.127)
		(layer "In13.Cu")
		(net "E1S_0_CLK_OE_N")
	)
	(segment
		(start 186.0042 -98.0948)
		(end 187.706 -98.0948)
		(width 0.127)
		(layer "In13.Cu")
		(net "E1S_0_CLK_OE_N")
	)
	(segment
		(start 276.10562 -88.82888)
		(end 281.95016 -94.67342)
		(width 0.127)
		(layer "In13.Cu")
		(net "E1S_0_CLK_OE_N")
	)
	(segment
		(start 179.9336 -102.108)
		(end 181.3814 -100.6602)
		(width 0.127)
		(layer "In13.Cu")
		(net "E1S_0_CLK_OE_N")
	)
	(segment
		(start 203.54925 -89.1032)
		(end 204.122782 -89.676732)
		(width 0.127)
		(layer "In13.Cu")
		(net "E1S_0_CLK_OE_N")
	)
	(segment
		(start 183.273192 -99.632008)
		(end 184.746392 -99.632008)
		(width 0.127)
		(layer "In13.Cu")
		(net "E1S_0_CLK_OE_N")
	)
	(segment
		(start 308.737 -23.0886)
		(end 308.97195 -23.32355)
		(width 0.12954)
		(layer "F.Cu")
		(net "DSW_PWROK_P2V5_COMP")
	)
	(segment
		(start 307.79085 -24.47925)
		(end 308.229 -24.9174)
		(width 0.12954)
		(layer "F.Cu")
		(net "DSW_PWROK_P2V5_COMP")
	)
	(segment
		(start 307.99024 -27.31516)
		(end 307.05679 -27.31516)
		(width 0.12954)
		(layer "F.Cu")
		(net "DSW_PWROK_P2V5_COMP")
	)
	(segment
		(start 305.7398 -22.9108)
		(end 305.9176 -23.0886)
		(width 0.12954)
		(layer "F.Cu")
		(net "DSW_PWROK_P2V5_COMP")
	)
	(segment
		(start 305.93538 -22.13356)
		(end 305.7398 -22.32914)
		(width 0.12954)
		(layer "F.Cu")
		(net "DSW_PWROK_P2V5_COMP")
	)
	(segment
		(start 307.79085 -23.7744)
		(end 308.97195 -23.7744)
		(width 0.12954)
		(layer "F.Cu")
		(net "DSW_PWROK_P2V5_COMP")
	)
	(segment
		(start 305.7398 -22.32914)
		(end 305.7398 -22.7076)
		(width 0.12954)
		(layer "F.Cu")
		(net "DSW_PWROK_P2V5_COMP")
	)
	(segment
		(start 307.79085 -23.7744)
		(end 307.79085 -24.47925)
		(width 0.12954)
		(layer "F.Cu")
		(net "DSW_PWROK_P2V5_COMP")
	)
	(segment
		(start 307.27269 -22.13356)
		(end 305.93538 -22.13356)
		(width 0.12954)
		(layer "F.Cu")
		(net "DSW_PWROK_P2V5_COMP")
	)
	(segment
		(start 305.7398 -22.7076)
		(end 305.7398 -22.9108)
		(width 0.12954)
		(layer "F.Cu")
		(net "DSW_PWROK_P2V5_COMP")
	)
	(segment
		(start 308.229 -27.0764)
		(end 307.99024 -27.31516)
		(width 0.12954)
		(layer "F.Cu")
		(net "DSW_PWROK_P2V5_COMP")
	)
	(segment
		(start 305.9176 -23.0886)
		(end 308.737 -23.0886)
		(width 0.12954)
		(layer "F.Cu")
		(net "DSW_PWROK_P2V5_COMP")
	)
	(segment
		(start 308.229 -24.9174)
		(end 308.229 -27.0764)
		(width 0.12954)
		(layer "F.Cu")
		(net "DSW_PWROK_P2V5_COMP")
	)
	(segment
		(start 308.97195 -23.32355)
		(end 308.97195 -23.7744)
		(width 0.12954)
		(layer "F.Cu")
		(net "DSW_PWROK_P2V5_COMP")
	)
	(via
		(at 305.7398 -22.7076)
		(size 0.762)
		(drill 0.381)
		(layers "F.Cu" "B.Cu")
		(net "DSW_PWROK_P2V5_COMP")
	)
	(segment
		(start 22.756876 -174.113952)
		(end 23.74011 -174.113952)
		(width 0.254)
		(layer "F.Cu")
		(net "PVNN_MAIN_CPU1_FB_RC")
	)
	(segment
		(start 25.98674 -174.117)
		(end 27.18054 -174.117)
		(width 0.254)
		(layer "F.Cu")
		(net "PVNN_MAIN_CPU1_FB_RC")
	)
	(segment
		(start 24.779986 -174.117)
		(end 25.98674 -174.117)
		(width 0.254)
		(layer "F.Cu")
		(net "PVNN_MAIN_CPU1_FB_RC")
	)
	(segment
		(start 22.756876 -174.113952)
		(end 22.754082 -174.116746)
		(width 0.254)
		(layer "F.Cu")
		(net "PVNN_MAIN_CPU1_FB_RC")
	)
	(segment
		(start 24.777446 -174.11446)
		(end 24.757126 -174.13478)
		(width 0.254)
		(layer "F.Cu")
		(net "PVNN_MAIN_CPU1_FB_RC")
	)
	(segment
		(start 24.777446 -174.11446)
		(end 24.779986 -174.117)
		(width 0.254)
		(layer "F.Cu")
		(net "PVNN_MAIN_CPU1_FB_RC")
	)
	(segment
		(start 24.757126 -174.13478)
		(end 23.760938 -174.13478)
		(width 0.254)
		(layer "F.Cu")
		(net "PVNN_MAIN_CPU1_FB_RC")
	)
	(segment
		(start 27.18054 -174.117)
		(end 27.18308 -174.11446)
		(width 0.254)
		(layer "F.Cu")
		(net "PVNN_MAIN_CPU1_FB_RC")
	)
	(segment
		(start 22.754082 -174.116746)
		(end 22.754082 -175.423576)
		(width 0.254)
		(layer "F.Cu")
		(net "PVNN_MAIN_CPU1_FB_RC")
	)
	(segment
		(start 23.74011 -174.113952)
		(end 23.760938 -174.13478)
		(width 0.254)
		(layer "F.Cu")
		(net "PVNN_MAIN_CPU1_FB_RC")
	)
	(via
		(at 25.98674 -174.117)
		(size 0.762)
		(drill 0.381)
		(layers "F.Cu" "B.Cu")
		(net "PVNN_MAIN_CPU1_FB_RC")
	)
	(segment
		(start 436.34152 -174.67072)
		(end 435.85892 -174.67072)
		(width 0.254)
		(layer "F.Cu")
		(net "PVNN_MAIN_CPU0_FB_RC")
	)
	(segment
		(start 435.142386 -174.8028)
		(end 435.136544 -174.796958)
		(width 0.254)
		(layer "F.Cu")
		(net "PVNN_MAIN_CPU0_FB_RC")
	)
	(segment
		(start 432.81473 -175.69942)
		(end 432.81473 -174.78502)
		(width 0.254)
		(layer "F.Cu")
		(net "PVNN_MAIN_CPU0_FB_RC")
	)
	(segment
		(start 437.53532 -174.805594)
		(end 437.15432 -174.805594)
		(width 0.254)
		(layer "F.Cu")
		(net "PVNN_MAIN_CPU0_FB_RC")
	)
	(segment
		(start 437.019446 -174.67072)
		(end 436.34152 -174.67072)
		(width 0.254)
		(layer "F.Cu")
		(net "PVNN_MAIN_CPU0_FB_RC")
	)
	(segment
		(start 433.757832 -174.71517)
		(end 433.83962 -174.796958)
		(width 0.254)
		(layer "F.Cu")
		(net "PVNN_MAIN_CPU0_FB_RC")
	)
	(segment
		(start 435.136544 -174.796958)
		(end 433.83962 -174.796958)
		(width 0.254)
		(layer "F.Cu")
		(net "PVNN_MAIN_CPU0_FB_RC")
	)
	(segment
		(start 437.15432 -174.805594)
		(end 437.019446 -174.67072)
		(width 0.254)
		(layer "F.Cu")
		(net "PVNN_MAIN_CPU0_FB_RC")
	)
	(segment
		(start 435.85892 -174.67072)
		(end 435.72684 -174.8028)
		(width 0.254)
		(layer "F.Cu")
		(net "PVNN_MAIN_CPU0_FB_RC")
	)
	(segment
		(start 432.88458 -174.71517)
		(end 433.757832 -174.71517)
		(width 0.254)
		(layer "F.Cu")
		(net "PVNN_MAIN_CPU0_FB_RC")
	)
	(segment
		(start 435.72684 -174.8028)
		(end 435.142386 -174.8028)
		(width 0.254)
		(layer "F.Cu")
		(net "PVNN_MAIN_CPU0_FB_RC")
	)
	(segment
		(start 432.81473 -174.78502)
		(end 432.88458 -174.71517)
		(width 0.254)
		(layer "F.Cu")
		(net "PVNN_MAIN_CPU0_FB_RC")
	)
	(via
		(at 436.34152 -174.67072)
		(size 0.762)
		(drill 0.381)
		(layers "F.Cu" "B.Cu")
		(net "PVNN_MAIN_CPU0_FB_RC")
	)
	(via
		(at 434.746146 -50.121566)
		(size 0.6604)
		(drill 0.3302)
		(layers "F.Cu" "B.Cu")
		(net "PWRGD_P5V_N")
	)
	(segment
		(start 435.39664 -48.24222)
		(end 435.518306 -48.363886)
		(width 0.12954)
		(layer "B.Cu")
		(net "PWRGD_P5V_N")
	)
	(segment
		(start 435.518306 -48.363886)
		(end 435.518306 -48.9331)
		(width 0.12954)
		(layer "B.Cu")
		(net "PWRGD_P5V_N")
	)
	(segment
		(start 434.86832 -48.41748)
		(end 435.04358 -48.24222)
		(width 0.12954)
		(layer "B.Cu")
		(net "PWRGD_P5V_N")
	)
	(segment
		(start 434.86832 -49.974246)
		(end 434.746146 -50.09642)
		(width 0.12954)
		(layer "B.Cu")
		(net "PWRGD_P5V_N")
	)
	(segment
		(start 434.86832 -48.9331)
		(end 434.86832 -48.41748)
		(width 0.12954)
		(layer "B.Cu")
		(net "PWRGD_P5V_N")
	)
	(segment
		(start 434.86832 -48.9331)
		(end 434.86832 -49.974246)
		(width 0.12954)
		(layer "B.Cu")
		(net "PWRGD_P5V_N")
	)
	(segment
		(start 434.746146 -50.09642)
		(end 434.746146 -50.121566)
		(width 0.12954)
		(layer "B.Cu")
		(net "PWRGD_P5V_N")
	)
	(segment
		(start 435.04358 -48.24222)
		(end 435.39664 -48.24222)
		(width 0.12954)
		(layer "B.Cu")
		(net "PWRGD_P5V_N")
	)
	(segment
		(start 434.746146 -50.09642)
		(end 434.113686 -50.72888)
		(width 0.12954)
		(layer "B.Cu")
		(net "PWRGD_P5V_N")
	)
	(segment
		(start 434.113686 -50.72888)
		(end 433.61483 -50.72888)
		(width 0.12954)
		(layer "B.Cu")
		(net "PWRGD_P5V_N")
	)
	(segment
		(start 434.583586 -53.36032)
		(end 433.618386 -53.36032)
		(width 0.12954)
		(layer "F.Cu")
		(net "PWRGD_P5V_ISO_R")
	)
	(via
		(at 433.618386 -53.36032)
		(size 0.508)
		(drill 0.254)
		(layers "F.Cu" "B.Cu")
		(net "PWRGD_P5V_ISO_R")
	)
	(via
		(at 431.73396 -52.60086)
		(size 0.6604)
		(drill 0.3302)
		(layers "F.Cu" "B.Cu")
		(net "PWRGD_P5V_ISO_R")
	)
	(segment
		(start 430.65446 -51.65979)
		(end 430.42205 -51.42738)
		(width 0.12954)
		(layer "B.Cu")
		(net "PWRGD_P5V_ISO_R")
	)
	(segment
		(start 433.61864 -52.64785)
		(end 433.61864 -53.360066)
		(width 0.12954)
		(layer "B.Cu")
		(net "PWRGD_P5V_ISO_R")
	)
	(segment
		(start 433.61864 -52.64785)
		(end 431.78095 -52.64785)
		(width 0.12954)
		(layer "B.Cu")
		(net "PWRGD_P5V_ISO_R")
	)
	(segment
		(start 433.61864 -53.360066)
		(end 433.618386 -53.36032)
		(width 0.12954)
		(layer "B.Cu")
		(net "PWRGD_P5V_ISO_R")
	)
	(segment
		(start 430.42205 -51.42738)
		(end 430.42713 -51.4223)
		(width 0.12954)
		(layer "B.Cu")
		(net "PWRGD_P5V_ISO_R")
	)
	(segment
		(start 431.73396 -52.60086)
		(end 430.81956 -52.60086)
		(width 0.12954)
		(layer "B.Cu")
		(net "PWRGD_P5V_ISO_R")
	)
	(segment
		(start 430.65446 -52.43576)
		(end 430.65446 -51.65979)
		(width 0.12954)
		(layer "B.Cu")
		(net "PWRGD_P5V_ISO_R")
	)
	(segment
		(start 430.42713 -51.4223)
		(end 430.42713 -50.37582)
		(width 0.12954)
		(layer "B.Cu")
		(net "PWRGD_P5V_ISO_R")
	)
	(segment
		(start 431.78095 -52.64785)
		(end 431.73396 -52.60086)
		(width 0.12954)
		(layer "B.Cu")
		(net "PWRGD_P5V_ISO_R")
	)
	(segment
		(start 430.81956 -52.60086)
		(end 430.65446 -52.43576)
		(width 0.12954)
		(layer "B.Cu")
		(net "PWRGD_P5V_ISO_R")
	)
	(via
		(at 432.568604 -48.004222)
		(size 0.6604)
		(drill 0.3302)
		(layers "F.Cu" "B.Cu")
		(net "PWRGD_P5V_ISO")
	)
	(segment
		(start 431.22723 -49.345596)
		(end 431.22723 -50.37582)
		(width 0.12954)
		(layer "B.Cu")
		(net "PWRGD_P5V_ISO")
	)
	(segment
		(start 432.568604 -48.004222)
		(end 431.22723 -49.345596)
		(width 0.12954)
		(layer "B.Cu")
		(net "PWRGD_P5V_ISO")
	)
	(segment
		(start 433.539646 -47.03318)
		(end 432.568604 -48.004222)
		(width 0.12954)
		(layer "B.Cu")
		(net "PWRGD_P5V_ISO")
	)
	(segment
		(start 434.218334 -47.03318)
		(end 433.539646 -47.03318)
		(width 0.12954)
		(layer "B.Cu")
		(net "PWRGD_P5V_ISO")
	)
	(segment
		(start 419.71722 -49.97958)
		(end 419.92931 -49.76749)
		(width 0.12954)
		(layer "F.Cu")
		(net "PWRGD_P3V3_R1")
	)
	(segment
		(start 421.73398 -49.76749)
		(end 421.73398 -50.356008)
		(width 0.12954)
		(layer "F.Cu")
		(net "PWRGD_P3V3_R1")
	)
	(segment
		(start 418.69106 -51.47691)
		(end 418.6936 -51.47437)
		(width 0.12954)
		(layer "F.Cu")
		(net "PWRGD_P3V3_R1")
	)
	(segment
		(start 418.6936 -51.47437)
		(end 418.71519 -51.45278)
		(width 0.12954)
		(layer "F.Cu")
		(net "PWRGD_P3V3_R1")
	)
	(segment
		(start 418.71519 -51.45278)
		(end 419.39718 -51.45278)
		(width 0.12954)
		(layer "F.Cu")
		(net "PWRGD_P3V3_R1")
	)
	(segment
		(start 419.71722 -51.13274)
		(end 419.71722 -49.97958)
		(width 0.12954)
		(layer "F.Cu")
		(net "PWRGD_P3V3_R1")
	)
	(segment
		(start 419.39718 -51.45278)
		(end 419.71722 -51.13274)
		(width 0.12954)
		(layer "F.Cu")
		(net "PWRGD_P3V3_R1")
	)
	(segment
		(start 421.73398 -50.356008)
		(end 420.873428 -51.21656)
		(width 0.12954)
		(layer "F.Cu")
		(net "PWRGD_P3V3_R1")
	)
	(segment
		(start 417.66744 -51.47691)
		(end 418.69106 -51.47691)
		(width 0.12954)
		(layer "F.Cu")
		(net "PWRGD_P3V3_R1")
	)
	(segment
		(start 420.3446 -49.76749)
		(end 421.73398 -49.76749)
		(width 0.12954)
		(layer "F.Cu")
		(net "PWRGD_P3V3_R1")
	)
	(segment
		(start 419.92931 -49.76749)
		(end 420.3446 -49.76749)
		(width 0.12954)
		(layer "F.Cu")
		(net "PWRGD_P3V3_R1")
	)
	(via
		(at 420.3446 -49.76749)
		(size 0.762)
		(drill 0.381)
		(layers "F.Cu" "B.Cu")
		(net "PWRGD_P3V3_R1")
	)
	(segment
		(start 295.656 -412.93288)
		(end 295.029636 -412.93288)
		(width 0.12954)
		(layer "F.Cu")
		(net "TP_HSC_TYPE_ADC_ALERT")
	)
	(segment
		(start 295.656 -412.93288)
		(end 296.032936 -412.555944)
		(width 0.12954)
		(layer "F.Cu")
		(net "TP_HSC_TYPE_ADC_ALERT")
	)
	(segment
		(start 294.902636 -413.05988)
		(end 294.445944 -413.05988)
		(width 0.12954)
		(layer "F.Cu")
		(net "TP_HSC_TYPE_ADC_ALERT")
	)
	(segment
		(start 296.032936 -412.555944)
		(end 296.968926 -412.555944)
		(width 0.12954)
		(layer "F.Cu")
		(net "TP_HSC_TYPE_ADC_ALERT")
	)
	(segment
		(start 295.029636 -412.93288)
		(end 294.902636 -413.05988)
		(width 0.12954)
		(layer "F.Cu")
		(net "TP_HSC_TYPE_ADC_ALERT")
	)
	(via
		(at 295.656 -412.93288)
		(size 0.762)
		(drill 0.381)
		(layers "F.Cu" "B.Cu")
		(net "TP_HSC_TYPE_ADC_ALERT")
	)
	(segment
		(start 302.909986 -405.08809)
		(end 302.909986 -386.869686)
		(width 0.12954)
		(layer "F.Cu")
		(net "SMB_SML1_PMBUS_HSC_MODULE_SDA")
	)
	(segment
		(start 300.7868 -407.0858)
		(end 300.912276 -407.0858)
		(width 0.12954)
		(layer "F.Cu")
		(net "SMB_SML1_PMBUS_HSC_MODULE_SDA")
	)
	(segment
		(start 301.26432 -386.11556)
		(end 300.74362 -385.59486)
		(width 0.12954)
		(layer "F.Cu")
		(net "SMB_SML1_PMBUS_HSC_MODULE_SDA")
	)
	(segment
		(start 302.15586 -386.11556)
		(end 301.26432 -386.11556)
		(width 0.12954)
		(layer "F.Cu")
		(net "SMB_SML1_PMBUS_HSC_MODULE_SDA")
	)
	(segment
		(start 302.909986 -386.869686)
		(end 302.15586 -386.11556)
		(width 0.12954)
		(layer "F.Cu")
		(net "SMB_SML1_PMBUS_HSC_MODULE_SDA")
	)
	(segment
		(start 290.479988 -386.623052)
		(end 290.479988 -388.349998)
		(width 0.12954)
		(layer "F.Cu")
		(net "SMB_SML1_PMBUS_HSC_MODULE_SDA")
	)
	(segment
		(start 291.50818 -385.59486)
		(end 290.479988 -386.623052)
		(width 0.12954)
		(layer "F.Cu")
		(net "SMB_SML1_PMBUS_HSC_MODULE_SDA")
	)
	(segment
		(start 300.74362 -385.59486)
		(end 291.50818 -385.59486)
		(width 0.12954)
		(layer "F.Cu")
		(net "SMB_SML1_PMBUS_HSC_MODULE_SDA")
	)
	(segment
		(start 300.912276 -407.0858)
		(end 302.909986 -405.08809)
		(width 0.12954)
		(layer "F.Cu")
		(net "SMB_SML1_PMBUS_HSC_MODULE_SDA")
	)
	(via
		(at 300.7868 -407.0858)
		(size 0.508)
		(drill 0.254)
		(layers "F.Cu" "B.Cu")
		(net "SMB_SML1_PMBUS_HSC_MODULE_SDA")
	)
	(via
		(at 282.9941 -435.794404)
		(size 0.508)
		(drill 0.254)
		(layers "F.Cu" "B.Cu")
		(net "SMB_SML1_PMBUS_HSC_MODULE_SDA")
	)
	(via
		(at 179.201064 -411.555184)
		(size 0.508)
		(drill 0.254)
		(layers "F.Cu" "B.Cu")
		(net "SMB_SML1_PMBUS_HSC_MODULE_SDA")
	)
	(segment
		(start 179.201064 -411.555184)
		(end 178.699668 -411.053788)
		(width 0.12954)
		(layer "B.Cu")
		(net "SMB_SML1_PMBUS_HSC_MODULE_SDA")
	)
	(segment
		(start 178.699668 -411.053788)
		(end 178.699668 -408.502358)
		(width 0.12954)
		(layer "B.Cu")
		(net "SMB_SML1_PMBUS_HSC_MODULE_SDA")
	)
	(segment
		(start 179.345082 -407.856944)
		(end 179.87645 -407.856944)
		(width 0.12954)
		(layer "B.Cu")
		(net "SMB_SML1_PMBUS_HSC_MODULE_SDA")
	)
	(segment
		(start 178.699668 -408.502358)
		(end 179.345082 -407.856944)
		(width 0.12954)
		(layer "B.Cu")
		(net "SMB_SML1_PMBUS_HSC_MODULE_SDA")
	)
	(segment
		(start 191.418464 -432.357784)
		(end 191.418464 -418.66947)
		(width 0.127)
		(layer "In4.Cu")
		(net "SMB_SML1_PMBUS_HSC_MODULE_SDA")
	)
	(segment
		(start 180.46446 -411.74797)
		(end 179.39385 -411.74797)
		(width 0.127)
		(layer "In4.Cu")
		(net "SMB_SML1_PMBUS_HSC_MODULE_SDA")
	)
	(segment
		(start 191.418464 -418.66947)
		(end 186.178698 -413.429704)
		(width 0.127)
		(layer "In4.Cu")
		(net "SMB_SML1_PMBUS_HSC_MODULE_SDA")
	)
	(segment
		(start 279.39238 -434.99278)
		(end 276.406102 -437.979058)
		(width 0.127)
		(layer "In4.Cu")
		(net "SMB_SML1_PMBUS_HSC_MODULE_SDA")
	)
	(segment
		(start 186.178698 -413.429704)
		(end 183.448452 -413.429704)
		(width 0.127)
		(layer "In4.Cu")
		(net "SMB_SML1_PMBUS_HSC_MODULE_SDA")
	)
	(segment
		(start 183.448452 -413.429704)
		(end 182.167276 -412.148528)
		(width 0.127)
		(layer "In4.Cu")
		(net "SMB_SML1_PMBUS_HSC_MODULE_SDA")
	)
	(segment
		(start 281.955748 -435.768496)
		(end 282.968192 -435.768496)
		(width 0.127)
		(layer "In4.Cu")
		(net "SMB_SML1_PMBUS_HSC_MODULE_SDA")
	)
	(segment
		(start 282.968192 -435.768496)
		(end 282.9941 -435.794404)
		(width 0.127)
		(layer "In4.Cu")
		(net "SMB_SML1_PMBUS_HSC_MODULE_SDA")
	)
	(segment
		(start 197.039738 -437.979058)
		(end 191.418464 -432.357784)
		(width 0.127)
		(layer "In4.Cu")
		(net "SMB_SML1_PMBUS_HSC_MODULE_SDA")
	)
	(segment
		(start 276.406102 -437.979058)
		(end 197.039738 -437.979058)
		(width 0.127)
		(layer "In4.Cu")
		(net "SMB_SML1_PMBUS_HSC_MODULE_SDA")
	)
	(segment
		(start 179.39385 -411.74797)
		(end 179.201064 -411.555184)
		(width 0.127)
		(layer "In4.Cu")
		(net "SMB_SML1_PMBUS_HSC_MODULE_SDA")
	)
	(segment
		(start 281.180032 -434.99278)
		(end 281.955748 -435.768496)
		(width 0.127)
		(layer "In4.Cu")
		(net "SMB_SML1_PMBUS_HSC_MODULE_SDA")
	)
	(segment
		(start 279.39238 -434.99278)
		(end 281.180032 -434.99278)
		(width 0.127)
		(layer "In4.Cu")
		(net "SMB_SML1_PMBUS_HSC_MODULE_SDA")
	)
	(segment
		(start 180.865018 -412.148528)
		(end 180.46446 -411.74797)
		(width 0.127)
		(layer "In4.Cu")
		(net "SMB_SML1_PMBUS_HSC_MODULE_SDA")
	)
	(segment
		(start 182.167276 -412.148528)
		(end 180.865018 -412.148528)
		(width 0.127)
		(layer "In4.Cu")
		(net "SMB_SML1_PMBUS_HSC_MODULE_SDA")
	)
	(segment
		(start 285.2928 -425.2722)
		(end 284.127448 -426.437552)
		(width 0.127)
		(layer "In6.Cu")
		(net "SMB_SML1_PMBUS_HSC_MODULE_SDA")
	)
	(segment
		(start 296.250868 -407.633932)
		(end 294.005 -409.8798)
		(width 0.127)
		(layer "In6.Cu")
		(net "SMB_SML1_PMBUS_HSC_MODULE_SDA")
	)
	(segment
		(start 284.127448 -426.437552)
		(end 284.127448 -426.944282)
		(width 0.127)
		(layer "In6.Cu")
		(net "SMB_SML1_PMBUS_HSC_MODULE_SDA")
	)
	(segment
		(start 293.40048 -417.86048)
		(end 293.40048 -422.0718)
		(width 0.127)
		(layer "In6.Cu")
		(net "SMB_SML1_PMBUS_HSC_MODULE_SDA")
	)
	(segment
		(start 296.250868 -407.254202)
		(end 296.250868 -407.633932)
		(width 0.127)
		(layer "In6.Cu")
		(net "SMB_SML1_PMBUS_HSC_MODULE_SDA")
	)
	(segment
		(start 300.59757 -407.0858)
		(end 299.46219 -405.95042)
		(width 0.127)
		(layer "In6.Cu")
		(net "SMB_SML1_PMBUS_HSC_MODULE_SDA")
	)
	(segment
		(start 293.40048 -422.0718)
		(end 290.20008 -425.2722)
		(width 0.127)
		(layer "In6.Cu")
		(net "SMB_SML1_PMBUS_HSC_MODULE_SDA")
	)
	(segment
		(start 284.127448 -426.944282)
		(end 284.058614 -427.013116)
		(width 0.127)
		(layer "In6.Cu")
		(net "SMB_SML1_PMBUS_HSC_MODULE_SDA")
	)
	(segment
		(start 294.005 -409.8798)
		(end 291.95268 -409.8798)
		(width 0.127)
		(layer "In6.Cu")
		(net "SMB_SML1_PMBUS_HSC_MODULE_SDA")
	)
	(segment
		(start 290.42868 -411.4038)
		(end 290.42868 -414.88868)
		(width 0.127)
		(layer "In6.Cu")
		(net "SMB_SML1_PMBUS_HSC_MODULE_SDA")
	)
	(segment
		(start 290.42868 -414.88868)
		(end 293.40048 -417.86048)
		(width 0.127)
		(layer "In6.Cu")
		(net "SMB_SML1_PMBUS_HSC_MODULE_SDA")
	)
	(segment
		(start 283.468572 -435.794404)
		(end 282.9941 -435.794404)
		(width 0.127)
		(layer "In6.Cu")
		(net "SMB_SML1_PMBUS_HSC_MODULE_SDA")
	)
	(segment
		(start 300.7868 -407.0858)
		(end 300.59757 -407.0858)
		(width 0.127)
		(layer "In6.Cu")
		(net "SMB_SML1_PMBUS_HSC_MODULE_SDA")
	)
	(segment
		(start 290.20008 -425.2722)
		(end 285.2928 -425.2722)
		(width 0.127)
		(layer "In6.Cu")
		(net "SMB_SML1_PMBUS_HSC_MODULE_SDA")
	)
	(segment
		(start 299.46219 -405.95042)
		(end 297.55465 -405.95042)
		(width 0.127)
		(layer "In6.Cu")
		(net "SMB_SML1_PMBUS_HSC_MODULE_SDA")
	)
	(segment
		(start 291.95268 -409.8798)
		(end 290.42868 -411.4038)
		(width 0.127)
		(layer "In6.Cu")
		(net "SMB_SML1_PMBUS_HSC_MODULE_SDA")
	)
	(segment
		(start 297.55465 -405.95042)
		(end 296.250868 -407.254202)
		(width 0.127)
		(layer "In6.Cu")
		(net "SMB_SML1_PMBUS_HSC_MODULE_SDA")
	)
	(segment
		(start 284.058614 -427.013116)
		(end 284.058614 -435.204362)
		(width 0.127)
		(layer "In6.Cu")
		(net "SMB_SML1_PMBUS_HSC_MODULE_SDA")
	)
	(segment
		(start 284.058614 -435.204362)
		(end 283.468572 -435.794404)
		(width 0.127)
		(layer "In6.Cu")
		(net "SMB_SML1_PMBUS_HSC_MODULE_SDA")
	)
	(segment
		(start 301.61738 -387.21538)
		(end 300.53788 -386.13588)
		(width 0.12954)
		(layer "F.Cu")
		(net "SMB_SML1_PMBUS_HSC_MODULE_SCL")
	)
	(segment
		(start 291.479986 -386.613654)
		(end 291.479986 -388.349998)
		(width 0.12954)
		(layer "F.Cu")
		(net "SMB_SML1_PMBUS_HSC_MODULE_SCL")
	)
	(segment
		(start 302.4378 -387.555994)
		(end 302.097186 -387.21538)
		(width 0.12954)
		(layer "F.Cu")
		(net "SMB_SML1_PMBUS_HSC_MODULE_SCL")
	)
	(segment
		(start 302.4378 -404.7236)
		(end 302.4378 -387.555994)
		(width 0.12954)
		(layer "F.Cu")
		(net "SMB_SML1_PMBUS_HSC_MODULE_SCL")
	)
	(segment
		(start 300.53788 -386.13588)
		(end 291.95776 -386.13588)
		(width 0.12954)
		(layer "F.Cu")
		(net "SMB_SML1_PMBUS_HSC_MODULE_SCL")
	)
	(segment
		(start 291.95776 -386.13588)
		(end 291.479986 -386.613654)
		(width 0.12954)
		(layer "F.Cu")
		(net "SMB_SML1_PMBUS_HSC_MODULE_SCL")
	)
	(segment
		(start 302.097186 -387.21538)
		(end 301.61738 -387.21538)
		(width 0.12954)
		(layer "F.Cu")
		(net "SMB_SML1_PMBUS_HSC_MODULE_SCL")
	)
	(segment
		(start 300.7868 -406.3746)
		(end 302.4378 -404.7236)
		(width 0.12954)
		(layer "F.Cu")
		(net "SMB_SML1_PMBUS_HSC_MODULE_SCL")
	)
	(via
		(at 182.038752 -408.95397)
		(size 0.508)
		(drill 0.254)
		(layers "F.Cu" "B.Cu")
		(net "SMB_SML1_PMBUS_HSC_MODULE_SCL")
	)
	(via
		(at 300.7868 -406.3746)
		(size 0.508)
		(drill 0.254)
		(layers "F.Cu" "B.Cu")
		(net "SMB_SML1_PMBUS_HSC_MODULE_SCL")
	)
	(via
		(at 282.108402 -436.674006)
		(size 0.508)
		(drill 0.254)
		(layers "F.Cu" "B.Cu")
		(net "SMB_SML1_PMBUS_HSC_MODULE_SCL")
	)
	(segment
		(start 181.915308 -408.259534)
		(end 181.915308 -408.830526)
		(width 0.12954)
		(layer "B.Cu")
		(net "SMB_SML1_PMBUS_HSC_MODULE_SCL")
	)
	(segment
		(start 181.915308 -408.830526)
		(end 182.038752 -408.95397)
		(width 0.12954)
		(layer "B.Cu")
		(net "SMB_SML1_PMBUS_HSC_MODULE_SCL")
	)
	(segment
		(start 183.262016 -413.885634)
		(end 182.135272 -412.75889)
		(width 0.127)
		(layer "In4.Cu")
		(net "SMB_SML1_PMBUS_HSC_MODULE_SCL")
	)
	(segment
		(start 278.514302 -438.410858)
		(end 196.828918 -438.410858)
		(width 0.127)
		(layer "In4.Cu")
		(net "SMB_SML1_PMBUS_HSC_MODULE_SCL")
	)
	(segment
		(start 190.1571 -431.73904)
		(end 190.1571 -418.124386)
		(width 0.127)
		(layer "In4.Cu")
		(net "SMB_SML1_PMBUS_HSC_MODULE_SCL")
	)
	(segment
		(start 281.249628 -437.53278)
		(end 282.108402 -436.674006)
		(width 0.127)
		(layer "In4.Cu")
		(net "SMB_SML1_PMBUS_HSC_MODULE_SCL")
	)
	(segment
		(start 190.1571 -418.124386)
		(end 185.918348 -413.885634)
		(width 0.127)
		(layer "In4.Cu")
		(net "SMB_SML1_PMBUS_HSC_MODULE_SCL")
	)
	(segment
		(start 178.641502 -411.916626)
		(end 178.641502 -409.45562)
		(width 0.127)
		(layer "In4.Cu")
		(net "SMB_SML1_PMBUS_HSC_MODULE_SCL")
	)
	(segment
		(start 179.143152 -408.95397)
		(end 182.038752 -408.95397)
		(width 0.127)
		(layer "In4.Cu")
		(net "SMB_SML1_PMBUS_HSC_MODULE_SCL")
	)
	(segment
		(start 182.135272 -412.75889)
		(end 179.483766 -412.75889)
		(width 0.127)
		(layer "In4.Cu")
		(net "SMB_SML1_PMBUS_HSC_MODULE_SCL")
	)
	(segment
		(start 279.39238 -437.53278)
		(end 278.514302 -438.410858)
		(width 0.127)
		(layer "In4.Cu")
		(net "SMB_SML1_PMBUS_HSC_MODULE_SCL")
	)
	(segment
		(start 185.918348 -413.885634)
		(end 183.262016 -413.885634)
		(width 0.127)
		(layer "In4.Cu")
		(net "SMB_SML1_PMBUS_HSC_MODULE_SCL")
	)
	(segment
		(start 279.39238 -437.53278)
		(end 281.249628 -437.53278)
		(width 0.127)
		(layer "In4.Cu")
		(net "SMB_SML1_PMBUS_HSC_MODULE_SCL")
	)
	(segment
		(start 178.641502 -409.45562)
		(end 179.143152 -408.95397)
		(width 0.127)
		(layer "In4.Cu")
		(net "SMB_SML1_PMBUS_HSC_MODULE_SCL")
	)
	(segment
		(start 179.483766 -412.75889)
		(end 178.641502 -411.916626)
		(width 0.127)
		(layer "In4.Cu")
		(net "SMB_SML1_PMBUS_HSC_MODULE_SCL")
	)
	(segment
		(start 196.828918 -438.410858)
		(end 190.1571 -431.73904)
		(width 0.127)
		(layer "In4.Cu")
		(net "SMB_SML1_PMBUS_HSC_MODULE_SCL")
	)
	(segment
		(start 282.108402 -435.812438)
		(end 282.993846 -434.926994)
		(width 0.127)
		(layer "In6.Cu")
		(net "SMB_SML1_PMBUS_HSC_MODULE_SCL")
	)
	(segment
		(start 299.64126 -405.51862)
		(end 300.49724 -406.3746)
		(width 0.127)
		(layer "In6.Cu")
		(net "SMB_SML1_PMBUS_HSC_MODULE_SCL")
	)
	(segment
		(start 292.86962 -418.080444)
		(end 289.89782 -415.108644)
		(width 0.127)
		(layer "In6.Cu")
		(net "SMB_SML1_PMBUS_HSC_MODULE_SCL")
	)
	(segment
		(start 285.115 -424.6626)
		(end 290.02482 -424.6626)
		(width 0.127)
		(layer "In6.Cu")
		(net "SMB_SML1_PMBUS_HSC_MODULE_SCL")
	)
	(segment
		(start 295.819068 -407.075132)
		(end 297.37558 -405.51862)
		(width 0.127)
		(layer "In6.Cu")
		(net "SMB_SML1_PMBUS_HSC_MODULE_SCL")
	)
	(segment
		(start 292.86962 -421.8178)
		(end 292.86962 -418.080444)
		(width 0.127)
		(layer "In6.Cu")
		(net "SMB_SML1_PMBUS_HSC_MODULE_SCL")
	)
	(segment
		(start 291.6809 -409.448)
		(end 293.82593 -409.448)
		(width 0.127)
		(layer "In6.Cu")
		(net "SMB_SML1_PMBUS_HSC_MODULE_SCL")
	)
	(segment
		(start 295.819068 -407.454862)
		(end 295.819068 -407.075132)
		(width 0.127)
		(layer "In6.Cu")
		(net "SMB_SML1_PMBUS_HSC_MODULE_SCL")
	)
	(segment
		(start 282.993846 -434.926994)
		(end 282.993846 -426.783754)
		(width 0.127)
		(layer "In6.Cu")
		(net "SMB_SML1_PMBUS_HSC_MODULE_SCL")
	)
	(segment
		(start 300.49724 -406.3746)
		(end 300.7868 -406.3746)
		(width 0.127)
		(layer "In6.Cu")
		(net "SMB_SML1_PMBUS_HSC_MODULE_SCL")
	)
	(segment
		(start 293.82593 -409.448)
		(end 295.819068 -407.454862)
		(width 0.127)
		(layer "In6.Cu")
		(net "SMB_SML1_PMBUS_HSC_MODULE_SCL")
	)
	(segment
		(start 297.37558 -405.51862)
		(end 299.64126 -405.51862)
		(width 0.127)
		(layer "In6.Cu")
		(net "SMB_SML1_PMBUS_HSC_MODULE_SCL")
	)
	(segment
		(start 282.993846 -426.783754)
		(end 285.115 -424.6626)
		(width 0.127)
		(layer "In6.Cu")
		(net "SMB_SML1_PMBUS_HSC_MODULE_SCL")
	)
	(segment
		(start 289.89782 -415.108644)
		(end 289.89782 -411.23108)
		(width 0.127)
		(layer "In6.Cu")
		(net "SMB_SML1_PMBUS_HSC_MODULE_SCL")
	)
	(segment
		(start 289.89782 -411.23108)
		(end 291.6809 -409.448)
		(width 0.127)
		(layer "In6.Cu")
		(net "SMB_SML1_PMBUS_HSC_MODULE_SCL")
	)
	(segment
		(start 282.108402 -436.674006)
		(end 282.108402 -435.812438)
		(width 0.127)
		(layer "In6.Cu")
		(net "SMB_SML1_PMBUS_HSC_MODULE_SCL")
	)
	(segment
		(start 290.02482 -424.6626)
		(end 292.86962 -421.8178)
		(width 0.127)
		(layer "In6.Cu")
		(net "SMB_SML1_PMBUS_HSC_MODULE_SCL")
	)
	(segment
		(start 295.15308 -412.07436)
		(end 294.445944 -412.07436)
		(width 0.12954)
		(layer "F.Cu")
		(net "SMB_HSC_TYPE_ADC_SDA")
	)
	(segment
		(start 296.968926 -412.055818)
		(end 296.150538 -412.055818)
		(width 0.12954)
		(layer "F.Cu")
		(net "SMB_HSC_TYPE_ADC_SDA")
	)
	(segment
		(start 295.64838 -411.6324)
		(end 295.59504 -411.6324)
		(width 0.12954)
		(layer "F.Cu")
		(net "SMB_HSC_TYPE_ADC_SDA")
	)
	(segment
		(start 296.150538 -412.055818)
		(end 295.72712 -411.6324)
		(width 0.12954)
		(layer "F.Cu")
		(net "SMB_HSC_TYPE_ADC_SDA")
	)
	(segment
		(start 295.72712 -411.6324)
		(end 295.64838 -411.6324)
		(width 0.12954)
		(layer "F.Cu")
		(net "SMB_HSC_TYPE_ADC_SDA")
	)
	(segment
		(start 295.59504 -411.6324)
		(end 295.15308 -412.07436)
		(width 0.12954)
		(layer "F.Cu")
		(net "SMB_HSC_TYPE_ADC_SDA")
	)
	(via
		(at 295.64838 -411.6324)
		(size 0.762)
		(drill 0.254)
		(layers "F.Cu" "B.Cu")
		(net "SMB_HSC_TYPE_ADC_SDA")
	)
	(segment
		(start 295.64838 -411.6324)
		(end 294.71874 -412.56204)
		(width 0.12954)
		(layer "B.Cu")
		(net "SMB_HSC_TYPE_ADC_SDA")
	)
	(segment
		(start 294.71874 -412.56204)
		(end 294.71874 -413.55899)
		(width 0.12954)
		(layer "B.Cu")
		(net "SMB_HSC_TYPE_ADC_SDA")
	)
	(segment
		(start 299.45076 -410.26842)
		(end 301.08652 -410.26842)
		(width 0.12954)
		(layer "F.Cu")
		(net "SMB_HSC_TYPE_ADC_SCL")
	)
	(segment
		(start 298.8691 -410.85008)
		(end 299.45076 -410.26842)
		(width 0.12954)
		(layer "F.Cu")
		(net "SMB_HSC_TYPE_ADC_SCL")
	)
	(segment
		(start 301.08652 -410.26842)
		(end 301.44466 -409.91028)
		(width 0.12954)
		(layer "F.Cu")
		(net "SMB_HSC_TYPE_ADC_SCL")
	)
	(segment
		(start 297.618912 -411.405832)
		(end 297.618912 -411.079188)
		(width 0.12954)
		(layer "F.Cu")
		(net "SMB_HSC_TYPE_ADC_SCL")
	)
	(segment
		(start 297.618912 -411.079188)
		(end 297.84802 -410.85008)
		(width 0.12954)
		(layer "F.Cu")
		(net "SMB_HSC_TYPE_ADC_SCL")
	)
	(segment
		(start 301.22622 -409.69184)
		(end 301.44466 -409.91028)
		(width 0.12954)
		(layer "F.Cu")
		(net "SMB_HSC_TYPE_ADC_SCL")
	)
	(segment
		(start 300.265084 -409.69184)
		(end 301.22622 -409.69184)
		(width 0.12954)
		(layer "F.Cu")
		(net "SMB_HSC_TYPE_ADC_SCL")
	)
	(segment
		(start 297.84802 -410.85008)
		(end 298.8691 -410.85008)
		(width 0.12954)
		(layer "F.Cu")
		(net "SMB_HSC_TYPE_ADC_SCL")
	)
	(via
		(at 301.44466 -409.91028)
		(size 0.762)
		(drill 0.381)
		(layers "F.Cu" "B.Cu")
		(net "SMB_HSC_TYPE_ADC_SCL")
	)
	(segment
		(start 153.50744 -114.83848)
		(end 153.50744 -115.116356)
		(width 0.12954)
		(layer "F.Cu")
		(net "RST_SRST_PLD_BMC_R_N")
	)
	(segment
		(start 153.50744 -115.116356)
		(end 153.155396 -115.4684)
		(width 0.12954)
		(layer "F.Cu")
		(net "RST_SRST_PLD_BMC_R_N")
	)
	(segment
		(start 174.155608 -116.175536)
		(end 173.755558 -116.575586)
		(width 0.12954)
		(layer "F.Cu")
		(net "RST_SRST_PLD_BMC_R_N")
	)
	(via
		(at 153.50744 -114.83848)
		(size 0.508)
		(drill 0.254)
		(layers "F.Cu" "B.Cu")
		(net "RST_SRST_PLD_BMC_R_N")
	)
	(via
		(at 173.755558 -116.575586)
		(size 0.4572)
		(drill 0.254)
		(layers "F.Cu" "B.Cu")
		(net "RST_SRST_PLD_BMC_R_N")
	)
	(segment
		(start 160.02 -119.4308)
		(end 161.26714 -118.18366)
		(width 0.127)
		(layer "In13.Cu")
		(net "RST_SRST_PLD_BMC_R_N")
	)
	(segment
		(start 161.26714 -118.18366)
		(end 163.83254 -118.18366)
		(width 0.127)
		(layer "In13.Cu")
		(net "RST_SRST_PLD_BMC_R_N")
	)
	(segment
		(start 154.32024 -115.65128)
		(end 156.53766 -115.65128)
		(width 0.127)
		(layer "In13.Cu")
		(net "RST_SRST_PLD_BMC_R_N")
	)
	(segment
		(start 153.50744 -114.83848)
		(end 154.32024 -115.65128)
		(width 0.127)
		(layer "In13.Cu")
		(net "RST_SRST_PLD_BMC_R_N")
	)
	(segment
		(start 165.0365 -119.38762)
		(end 167.31488 -119.38762)
		(width 0.127)
		(layer "In13.Cu")
		(net "RST_SRST_PLD_BMC_R_N")
	)
	(segment
		(start 157.78988 -119.4308)
		(end 160.02 -119.4308)
		(width 0.127)
		(layer "In13.Cu")
		(net "RST_SRST_PLD_BMC_R_N")
	)
	(segment
		(start 156.81833 -118.45925)
		(end 157.78988 -119.4308)
		(width 0.127)
		(layer "In13.Cu")
		(net "RST_SRST_PLD_BMC_R_N")
	)
	(segment
		(start 171.591224 -118.85168)
		(end 171.872402 -118.570502)
		(width 0.127)
		(layer "In13.Cu")
		(net "RST_SRST_PLD_BMC_R_N")
	)
	(segment
		(start 156.53766 -115.65128)
		(end 156.81833 -115.93195)
		(width 0.127)
		(layer "In13.Cu")
		(net "RST_SRST_PLD_BMC_R_N")
	)
	(segment
		(start 156.81833 -115.93195)
		(end 156.81833 -118.45925)
		(width 0.127)
		(layer "In13.Cu")
		(net "RST_SRST_PLD_BMC_R_N")
	)
	(segment
		(start 167.31488 -119.38762)
		(end 167.85082 -118.85168)
		(width 0.127)
		(layer "In13.Cu")
		(net "RST_SRST_PLD_BMC_R_N")
	)
	(segment
		(start 171.872402 -118.570502)
		(end 172.571918 -118.570502)
		(width 0.127)
		(layer "In13.Cu")
		(net "RST_SRST_PLD_BMC_R_N")
	)
	(segment
		(start 167.85082 -118.85168)
		(end 171.591224 -118.85168)
		(width 0.127)
		(layer "In13.Cu")
		(net "RST_SRST_PLD_BMC_R_N")
	)
	(segment
		(start 172.571918 -118.570502)
		(end 173.755558 -117.386862)
		(width 0.127)
		(layer "In13.Cu")
		(net "RST_SRST_PLD_BMC_R_N")
	)
	(segment
		(start 173.755558 -117.386862)
		(end 173.755558 -116.575586)
		(width 0.127)
		(layer "In13.Cu")
		(net "RST_SRST_PLD_BMC_R_N")
	)
	(segment
		(start 163.83254 -118.18366)
		(end 165.0365 -119.38762)
		(width 0.127)
		(layer "In13.Cu")
		(net "RST_SRST_PLD_BMC_R_N")
	)
	(segment
		(start 149.23262 -107.36834)
		(end 149.23262 -112.06226)
		(width 0.12954)
		(layer "F.Cu")
		(net "RST_SRST_PLD_BMC_N")
	)
	(segment
		(start 151.22652 -105.83164)
		(end 150.76932 -105.83164)
		(width 0.12954)
		(layer "F.Cu")
		(net "RST_SRST_PLD_BMC_N")
	)
	(segment
		(start 149.23262 -112.06226)
		(end 152.355296 -115.184936)
		(width 0.12954)
		(layer "F.Cu")
		(net "RST_SRST_PLD_BMC_N")
	)
	(segment
		(start 185.062114 -16.550132)
		(end 185.062114 -18.27784)
		(width 0.12954)
		(layer "F.Cu")
		(net "RST_SRST_PLD_BMC_N")
	)
	(segment
		(start 150.76932 -105.83164)
		(end 149.23262 -107.36834)
		(width 0.12954)
		(layer "F.Cu")
		(net "RST_SRST_PLD_BMC_N")
	)
	(segment
		(start 152.355296 -115.184936)
		(end 152.355296 -115.4684)
		(width 0.12954)
		(layer "F.Cu")
		(net "RST_SRST_PLD_BMC_N")
	)
	(via
		(at 142.865094 -69.128894)
		(size 0.508)
		(drill 0.254)
		(layers "F.Cu" "B.Cu")
		(net "RST_SRST_PLD_BMC_N")
	)
	(via
		(at 185.062114 -18.27784)
		(size 0.508)
		(drill 0.254)
		(layers "F.Cu" "B.Cu")
		(net "RST_SRST_PLD_BMC_N")
	)
	(via
		(at 151.22652 -105.83164)
		(size 0.508)
		(drill 0.254)
		(layers "F.Cu" "B.Cu")
		(net "RST_SRST_PLD_BMC_N")
	)
	(segment
		(start 146.88693 -92.61221)
		(end 146.88693 -83.65363)
		(width 0.127)
		(layer "In2.Cu")
		(net "RST_SRST_PLD_BMC_N")
	)
	(segment
		(start 142.865094 -75.542394)
		(end 142.865094 -69.128894)
		(width 0.127)
		(layer "In2.Cu")
		(net "RST_SRST_PLD_BMC_N")
	)
	(segment
		(start 151.22652 -105.83164)
		(end 151.22652 -96.9518)
		(width 0.127)
		(layer "In2.Cu")
		(net "RST_SRST_PLD_BMC_N")
	)
	(segment
		(start 143.30426 -80.07096)
		(end 143.30426 -75.98156)
		(width 0.127)
		(layer "In2.Cu")
		(net "RST_SRST_PLD_BMC_N")
	)
	(segment
		(start 146.88693 -83.65363)
		(end 143.30426 -80.07096)
		(width 0.127)
		(layer "In2.Cu")
		(net "RST_SRST_PLD_BMC_N")
	)
	(segment
		(start 143.30426 -75.98156)
		(end 142.865094 -75.542394)
		(width 0.127)
		(layer "In2.Cu")
		(net "RST_SRST_PLD_BMC_N")
	)
	(segment
		(start 151.22652 -96.9518)
		(end 146.88693 -92.61221)
		(width 0.127)
		(layer "In2.Cu")
		(net "RST_SRST_PLD_BMC_N")
	)
	(segment
		(start 168.59758 -8.3693)
		(end 177.6222 -8.3693)
		(width 0.127)
		(layer "In15.Cu")
		(net "RST_SRST_PLD_BMC_N")
	)
	(segment
		(start 164.70122 -27.4193)
		(end 163.40328 -26.12136)
		(width 0.127)
		(layer "In15.Cu")
		(net "RST_SRST_PLD_BMC_N")
	)
	(segment
		(start 152.02916 -56.2991)
		(end 154.32786 -56.2991)
		(width 0.127)
		(layer "In15.Cu")
		(net "RST_SRST_PLD_BMC_N")
	)
	(segment
		(start 149.68982 -61.699394)
		(end 149.68982 -58.63844)
		(width 0.127)
		(layer "In15.Cu")
		(net "RST_SRST_PLD_BMC_N")
	)
	(segment
		(start 162.97148 -20.7391)
		(end 162.97148 -17.63522)
		(width 0.127)
		(layer "In15.Cu")
		(net "RST_SRST_PLD_BMC_N")
	)
	(segment
		(start 161.2646 -49.36236)
		(end 161.2646 -47.58436)
		(width 0.127)
		(layer "In15.Cu")
		(net "RST_SRST_PLD_BMC_N")
	)
	(segment
		(start 154.32786 -56.2991)
		(end 161.2646 -49.36236)
		(width 0.127)
		(layer "In15.Cu")
		(net "RST_SRST_PLD_BMC_N")
	)
	(segment
		(start 165.61816 -14.98854)
		(end 165.61816 -11.34872)
		(width 0.127)
		(layer "In15.Cu")
		(net "RST_SRST_PLD_BMC_N")
	)
	(segment
		(start 184.00522 -13.08862)
		(end 183.4388 -13.65504)
		(width 0.127)
		(layer "In15.Cu")
		(net "RST_SRST_PLD_BMC_N")
	)
	(segment
		(start 163.40328 -26.12136)
		(end 163.40328 -21.1709)
		(width 0.127)
		(layer "In15.Cu")
		(net "RST_SRST_PLD_BMC_N")
	)
	(segment
		(start 162.97148 -17.63522)
		(end 165.61816 -14.98854)
		(width 0.127)
		(layer "In15.Cu")
		(net "RST_SRST_PLD_BMC_N")
	)
	(segment
		(start 183.4388 -13.65504)
		(end 183.4388 -14.93012)
		(width 0.127)
		(layer "In15.Cu")
		(net "RST_SRST_PLD_BMC_N")
	)
	(segment
		(start 161.2646 -47.58436)
		(end 164.70122 -44.14774)
		(width 0.127)
		(layer "In15.Cu")
		(net "RST_SRST_PLD_BMC_N")
	)
	(segment
		(start 142.865094 -69.128894)
		(end 142.865094 -68.52412)
		(width 0.127)
		(layer "In15.Cu")
		(net "RST_SRST_PLD_BMC_N")
	)
	(segment
		(start 183.4388 -14.93012)
		(end 185.11774 -16.60906)
		(width 0.127)
		(layer "In15.Cu")
		(net "RST_SRST_PLD_BMC_N")
	)
	(segment
		(start 164.70122 -44.14774)
		(end 164.70122 -27.4193)
		(width 0.127)
		(layer "In15.Cu")
		(net "RST_SRST_PLD_BMC_N")
	)
	(segment
		(start 184.00522 -11.6459)
		(end 184.00522 -13.08862)
		(width 0.127)
		(layer "In15.Cu")
		(net "RST_SRST_PLD_BMC_N")
	)
	(segment
		(start 163.40328 -21.1709)
		(end 162.97148 -20.7391)
		(width 0.127)
		(layer "In15.Cu")
		(net "RST_SRST_PLD_BMC_N")
	)
	(segment
		(start 165.61816 -11.34872)
		(end 168.59758 -8.3693)
		(width 0.127)
		(layer "In15.Cu")
		(net "RST_SRST_PLD_BMC_N")
	)
	(segment
		(start 179.88026 -10.62736)
		(end 182.98668 -10.62736)
		(width 0.127)
		(layer "In15.Cu")
		(net "RST_SRST_PLD_BMC_N")
	)
	(segment
		(start 182.98668 -10.62736)
		(end 184.00522 -11.6459)
		(width 0.127)
		(layer "In15.Cu")
		(net "RST_SRST_PLD_BMC_N")
	)
	(segment
		(start 177.6222 -8.3693)
		(end 179.88026 -10.62736)
		(width 0.127)
		(layer "In15.Cu")
		(net "RST_SRST_PLD_BMC_N")
	)
	(segment
		(start 185.11774 -16.60906)
		(end 185.11774 -18.242788)
		(width 0.127)
		(layer "In15.Cu")
		(net "RST_SRST_PLD_BMC_N")
	)
	(segment
		(start 142.865094 -68.52412)
		(end 149.68982 -61.699394)
		(width 0.127)
		(layer "In15.Cu")
		(net "RST_SRST_PLD_BMC_N")
	)
	(segment
		(start 185.082688 -18.27784)
		(end 185.062114 -18.27784)
		(width 0.127)
		(layer "In15.Cu")
		(net "RST_SRST_PLD_BMC_N")
	)
	(segment
		(start 149.68982 -58.63844)
		(end 152.02916 -56.2991)
		(width 0.127)
		(layer "In15.Cu")
		(net "RST_SRST_PLD_BMC_N")
	)
	(segment
		(start 185.11774 -18.242788)
		(end 185.082688 -18.27784)
		(width 0.127)
		(layer "In15.Cu")
		(net "RST_SRST_PLD_BMC_N")
	)
	(segment
		(start 41.859962 -392.180318)
		(end 42.383202 -392.180318)
		(width 0.10668)
		(layer "F.Cu")
		(net "PD_P2E_BUF2_ENSMB")
	)
	(segment
		(start 43.117516 -391.792206)
		(end 45.276516 -391.792206)
		(width 0.10668)
		(layer "F.Cu")
		(net "PD_P2E_BUF2_ENSMB")
	)
	(segment
		(start 45.276516 -391.792206)
		(end 45.667422 -392.183112)
		(width 0.10668)
		(layer "F.Cu")
		(net "PD_P2E_BUF2_ENSMB")
	)
	(segment
		(start 42.771314 -391.792206)
		(end 43.117516 -391.792206)
		(width 0.10668)
		(layer "F.Cu")
		(net "PD_P2E_BUF2_ENSMB")
	)
	(segment
		(start 42.383202 -392.180318)
		(end 42.771314 -391.792206)
		(width 0.10668)
		(layer "F.Cu")
		(net "PD_P2E_BUF2_ENSMB")
	)
	(via
		(at 43.117516 -391.792206)
		(size 0.762)
		(drill 0.381)
		(layers "F.Cu" "B.Cu")
		(net "PD_P2E_BUF2_ENSMB")
	)
	(segment
		(start 41.209976 -390.353296)
		(end 41.08958 -390.2329)
		(width 0.13208)
		(layer "F.Cu")
		(net "P2E_MB_BMC_TX_C_R2_DP<0>")
	)
	(segment
		(start 19.212052 -384.231896)
		(end 19.71294 -383.730246)
		(width 0.13208)
		(layer "F.Cu")
		(net "P2E_MB_BMC_TX_C_R2_DP<0>")
	)
	(segment
		(start 41.837864 -388.970012)
		(end 42.40022 -387.612382)
		(width 0.13208)
		(layer "F.Cu")
		(net "P2E_MB_BMC_TX_C_R2_DP<0>")
	)
	(segment
		(start 41.209976 -390.530334)
		(end 41.209976 -390.353296)
		(width 0.13208)
		(layer "F.Cu")
		(net "P2E_MB_BMC_TX_C_R2_DP<0>")
	)
	(segment
		(start 19.71294 -383.209038)
		(end 19.397726 -382.893824)
		(width 0.13208)
		(layer "F.Cu")
		(net "P2E_MB_BMC_TX_C_R2_DP<0>")
	)
	(segment
		(start 42.40022 -385.875276)
		(end 42.69994 -385.575556)
		(width 0.13208)
		(layer "F.Cu")
		(net "P2E_MB_BMC_TX_C_R2_DP<0>")
	)
	(segment
		(start 19.71294 -383.730246)
		(end 19.71294 -383.209038)
		(width 0.13208)
		(layer "F.Cu")
		(net "P2E_MB_BMC_TX_C_R2_DP<0>")
	)
	(segment
		(start 42.40022 -387.612382)
		(end 42.40022 -385.875276)
		(width 0.13208)
		(layer "F.Cu")
		(net "P2E_MB_BMC_TX_C_R2_DP<0>")
	)
	(segment
		(start 19.19859 -384.665474)
		(end 19.19859 -384.245358)
		(width 0.13208)
		(layer "F.Cu")
		(net "P2E_MB_BMC_TX_C_R2_DP<0>")
	)
	(segment
		(start 41.08958 -389.718296)
		(end 41.837864 -388.970012)
		(width 0.13208)
		(layer "F.Cu")
		(net "P2E_MB_BMC_TX_C_R2_DP<0>")
	)
	(segment
		(start 41.08958 -390.2329)
		(end 41.08958 -389.718296)
		(width 0.13208)
		(layer "F.Cu")
		(net "P2E_MB_BMC_TX_C_R2_DP<0>")
	)
	(segment
		(start 19.19859 -384.245358)
		(end 19.212052 -384.231896)
		(width 0.13208)
		(layer "F.Cu")
		(net "P2E_MB_BMC_TX_C_R2_DP<0>")
	)
	(segment
		(start 40.43426 -383.666238)
		(end 34.88817 -382.563116)
		(width 0.14732)
		(layer "In15.Cu")
		(net "P2E_MB_BMC_TX_C_R2_DP<0>")
	)
	(segment
		(start 21.197824 -380.7714)
		(end 19.692366 -382.276858)
		(width 0.14732)
		(layer "In15.Cu")
		(net "P2E_MB_BMC_TX_C_R2_DP<0>")
	)
	(segment
		(start 34.88817 -382.562862)
		(end 26.881074 -380.970028)
		(width 0.14732)
		(layer "In15.Cu")
		(net "P2E_MB_BMC_TX_C_R2_DP<0>")
	)
	(segment
		(start 41.891458 -384.444494)
		(end 40.43426 -383.666238)
		(width 0.14732)
		(layer "In15.Cu")
		(net "P2E_MB_BMC_TX_C_R2_DP<0>")
	)
	(segment
		(start 42.4053 -385.280916)
		(end 42.4053 -384.95859)
		(width 0.14732)
		(layer "In15.Cu")
		(net "P2E_MB_BMC_TX_C_R2_DP<0>")
	)
	(segment
		(start 19.692366 -382.599184)
		(end 19.397726 -382.893824)
		(width 0.14732)
		(layer "In15.Cu")
		(net "P2E_MB_BMC_TX_C_R2_DP<0>")
	)
	(segment
		(start 42.4053 -384.95859)
		(end 41.891458 -384.444494)
		(width 0.14732)
		(layer "In15.Cu")
		(net "P2E_MB_BMC_TX_C_R2_DP<0>")
	)
	(segment
		(start 42.69994 -385.575556)
		(end 42.4053 -385.280916)
		(width 0.14732)
		(layer "In15.Cu")
		(net "P2E_MB_BMC_TX_C_R2_DP<0>")
	)
	(segment
		(start 25.88133 -380.7714)
		(end 21.197824 -380.7714)
		(width 0.14732)
		(layer "In15.Cu")
		(net "P2E_MB_BMC_TX_C_R2_DP<0>")
	)
	(segment
		(start 26.88082 -380.969774)
		(end 25.88133 -380.7714)
		(width 0.14732)
		(layer "In15.Cu")
		(net "P2E_MB_BMC_TX_C_R2_DP<0>")
	)
	(segment
		(start 26.881074 -380.970028)
		(end 26.88082 -380.969774)
		(width 0.14732)
		(layer "In15.Cu")
		(net "P2E_MB_BMC_TX_C_R2_DP<0>")
	)
	(segment
		(start 34.88817 -382.563116)
		(end 34.88817 -382.562862)
		(width 0.14732)
		(layer "In15.Cu")
		(net "P2E_MB_BMC_TX_C_R2_DP<0>")
	)
	(segment
		(start 19.692366 -382.276858)
		(end 19.692366 -382.599184)
		(width 0.14732)
		(layer "In15.Cu")
		(net "P2E_MB_BMC_TX_C_R2_DP<0>")
	)
	(segment
		(start 41.83634 -385.575556)
		(end 42.14114 -385.880356)
		(width 0.13208)
		(layer "F.Cu")
		(net "P2E_MB_BMC_TX_C_R2_DN<0>")
	)
	(segment
		(start 40.710104 -390.345676)
		(end 40.710104 -390.530334)
		(width 0.13208)
		(layer "F.Cu")
		(net "P2E_MB_BMC_TX_C_R2_DN<0>")
	)
	(segment
		(start 19.97202 -383.707386)
		(end 19.97202 -383.18313)
		(width 0.13208)
		(layer "F.Cu")
		(net "P2E_MB_BMC_TX_C_R2_DN<0>")
	)
	(segment
		(start 20.485608 -384.221482)
		(end 19.97202 -383.707386)
		(width 0.13208)
		(layer "F.Cu")
		(net "P2E_MB_BMC_TX_C_R2_DN<0>")
	)
	(segment
		(start 42.14114 -385.880356)
		(end 42.14114 -387.56082)
		(width 0.13208)
		(layer "F.Cu")
		(net "P2E_MB_BMC_TX_C_R2_DN<0>")
	)
	(segment
		(start 42.14114 -387.56082)
		(end 41.618154 -388.8232)
		(width 0.13208)
		(layer "F.Cu")
		(net "P2E_MB_BMC_TX_C_R2_DN<0>")
	)
	(segment
		(start 19.97202 -383.18313)
		(end 20.261326 -382.893824)
		(width 0.13208)
		(layer "F.Cu")
		(net "P2E_MB_BMC_TX_C_R2_DN<0>")
	)
	(segment
		(start 40.8305 -389.610854)
		(end 40.8305 -390.22528)
		(width 0.13208)
		(layer "F.Cu")
		(net "P2E_MB_BMC_TX_C_R2_DN<0>")
	)
	(segment
		(start 41.618154 -388.8232)
		(end 40.8305 -389.610854)
		(width 0.13208)
		(layer "F.Cu")
		(net "P2E_MB_BMC_TX_C_R2_DN<0>")
	)
	(segment
		(start 40.8305 -390.22528)
		(end 40.710104 -390.345676)
		(width 0.13208)
		(layer "F.Cu")
		(net "P2E_MB_BMC_TX_C_R2_DN<0>")
	)
	(segment
		(start 20.485608 -384.666744)
		(end 20.485608 -384.221482)
		(width 0.13208)
		(layer "F.Cu")
		(net "P2E_MB_BMC_TX_C_R2_DN<0>")
	)
	(segment
		(start 30.77718 -382.149604)
		(end 30.681422 -382.00584)
		(width 0.14732)
		(layer "In15.Cu")
		(net "P2E_MB_BMC_TX_C_R2_DN<0>")
	)
	(segment
		(start 21.311616 -381.04572)
		(end 20.749768 -381.607568)
		(width 0.14732)
		(layer "In15.Cu")
		(net "P2E_MB_BMC_TX_C_R2_DN<0>")
	)
	(segment
		(start 28.433268 -381.68326)
		(end 28.33751 -381.539496)
		(width 0.14732)
		(layer "In15.Cu")
		(net "P2E_MB_BMC_TX_C_R2_DN<0>")
	)
	(segment
		(start 34.17189 -382.700276)
		(end 33.748472 -382.616202)
		(width 0.14732)
		(layer "In15.Cu")
		(net "P2E_MB_BMC_TX_C_R2_DN<0>")
	)
	(segment
		(start 22.040596 -381.16764)
		(end 21.608796 -381.16764)
		(width 0.14732)
		(layer "In15.Cu")
		(net "P2E_MB_BMC_TX_C_R2_DN<0>")
	)
	(segment
		(start 21.486876 -381.04572)
		(end 21.311616 -381.04572)
		(width 0.14732)
		(layer "In15.Cu")
		(net "P2E_MB_BMC_TX_C_R2_DN<0>")
	)
	(segment
		(start 33.748472 -382.616202)
		(end 33.605216 -382.71196)
		(width 0.14732)
		(layer "In15.Cu")
		(net "P2E_MB_BMC_TX_C_R2_DN<0>")
	)
	(segment
		(start 19.966686 -382.39065)
		(end 19.966686 -382.599184)
		(width 0.14732)
		(layer "In15.Cu")
		(net "P2E_MB_BMC_TX_C_R2_DN<0>")
	)
	(segment
		(start 20.749768 -381.607568)
		(end 20.749768 -381.77978)
		(width 0.14732)
		(layer "In15.Cu")
		(net "P2E_MB_BMC_TX_C_R2_DN<0>")
	)
	(segment
		(start 20.749768 -381.77978)
		(end 20.444206 -382.085342)
		(width 0.14732)
		(layer "In15.Cu")
		(net "P2E_MB_BMC_TX_C_R2_DN<0>")
	)
	(segment
		(start 28.33751 -381.539496)
		(end 27.914092 -381.455422)
		(width 0.14732)
		(layer "In15.Cu")
		(net "P2E_MB_BMC_TX_C_R2_DN<0>")
	)
	(segment
		(start 31.76778 -382.221994)
		(end 31.344362 -382.13792)
		(width 0.14732)
		(layer "In15.Cu")
		(net "P2E_MB_BMC_TX_C_R2_DN<0>")
	)
	(segment
		(start 33.085532 -382.484122)
		(end 32.43072 -382.354074)
		(width 0.14732)
		(layer "In15.Cu")
		(net "P2E_MB_BMC_TX_C_R2_DN<0>")
	)
	(segment
		(start 19.966686 -382.599184)
		(end 20.261326 -382.893824)
		(width 0.14732)
		(layer "In15.Cu")
		(net "P2E_MB_BMC_TX_C_R2_DN<0>")
	)
	(segment
		(start 33.605216 -382.71196)
		(end 33.181544 -382.627886)
		(width 0.14732)
		(layer "In15.Cu")
		(net "P2E_MB_BMC_TX_C_R2_DN<0>")
	)
	(segment
		(start 29.519626 -381.899414)
		(end 29.423868 -381.75565)
		(width 0.14732)
		(layer "In15.Cu")
		(net "P2E_MB_BMC_TX_C_R2_DN<0>")
	)
	(segment
		(start 42.13098 -385.280916)
		(end 42.13098 -385.072382)
		(width 0.14732)
		(layer "In15.Cu")
		(net "P2E_MB_BMC_TX_C_R2_DN<0>")
	)
	(segment
		(start 31.344362 -382.13792)
		(end 31.201106 -382.233678)
		(width 0.14732)
		(layer "In15.Cu")
		(net "P2E_MB_BMC_TX_C_R2_DN<0>")
	)
	(segment
		(start 41.726104 -384.667506)
		(end 40.340788 -383.92735)
		(width 0.14732)
		(layer "In15.Cu")
		(net "P2E_MB_BMC_TX_C_R2_DN<0>")
	)
	(segment
		(start 31.201106 -382.233678)
		(end 30.77718 -382.149604)
		(width 0.14732)
		(layer "In15.Cu")
		(net "P2E_MB_BMC_TX_C_R2_DN<0>")
	)
	(segment
		(start 32.28721 -382.449832)
		(end 31.863538 -382.365758)
		(width 0.14732)
		(layer "In15.Cu")
		(net "P2E_MB_BMC_TX_C_R2_DN<0>")
	)
	(segment
		(start 30.086808 -381.88773)
		(end 29.943298 -381.983488)
		(width 0.14732)
		(layer "In15.Cu")
		(net "P2E_MB_BMC_TX_C_R2_DN<0>")
	)
	(segment
		(start 42.13098 -385.072382)
		(end 41.726104 -384.667506)
		(width 0.14732)
		(layer "In15.Cu")
		(net "P2E_MB_BMC_TX_C_R2_DN<0>")
	)
	(segment
		(start 40.340788 -383.92735)
		(end 34.83483 -382.832356)
		(width 0.14732)
		(layer "In15.Cu")
		(net "P2E_MB_BMC_TX_C_R2_DN<0>")
	)
	(segment
		(start 31.863538 -382.365758)
		(end 31.76778 -382.221994)
		(width 0.14732)
		(layer "In15.Cu")
		(net "P2E_MB_BMC_TX_C_R2_DN<0>")
	)
	(segment
		(start 25.854152 -381.04572)
		(end 22.162516 -381.04572)
		(width 0.14732)
		(layer "In15.Cu")
		(net "P2E_MB_BMC_TX_C_R2_DN<0>")
	)
	(segment
		(start 41.83634 -385.575556)
		(end 42.13098 -385.280916)
		(width 0.14732)
		(layer "In15.Cu")
		(net "P2E_MB_BMC_TX_C_R2_DN<0>")
	)
	(segment
		(start 33.181544 -382.627886)
		(end 33.085532 -382.484122)
		(width 0.14732)
		(layer "In15.Cu")
		(net "P2E_MB_BMC_TX_C_R2_DN<0>")
	)
	(segment
		(start 29.943298 -381.983488)
		(end 29.519626 -381.899414)
		(width 0.14732)
		(layer "In15.Cu")
		(net "P2E_MB_BMC_TX_C_R2_DN<0>")
	)
	(segment
		(start 34.267648 -382.84404)
		(end 34.17189 -382.700276)
		(width 0.14732)
		(layer "In15.Cu")
		(net "P2E_MB_BMC_TX_C_R2_DN<0>")
	)
	(segment
		(start 28.85694 -381.767334)
		(end 28.433268 -381.68326)
		(width 0.14732)
		(layer "In15.Cu")
		(net "P2E_MB_BMC_TX_C_R2_DN<0>")
	)
	(segment
		(start 26.923238 -381.382778)
		(end 26.82748 -381.239014)
		(width 0.14732)
		(layer "In15.Cu")
		(net "P2E_MB_BMC_TX_C_R2_DN<0>")
	)
	(segment
		(start 34.83483 -382.832356)
		(end 34.69132 -382.928114)
		(width 0.14732)
		(layer "In15.Cu")
		(net "P2E_MB_BMC_TX_C_R2_DN<0>")
	)
	(segment
		(start 21.608796 -381.16764)
		(end 21.486876 -381.04572)
		(width 0.14732)
		(layer "In15.Cu")
		(net "P2E_MB_BMC_TX_C_R2_DN<0>")
	)
	(segment
		(start 27.914092 -381.455422)
		(end 27.913838 -381.455168)
		(width 0.14732)
		(layer "In15.Cu")
		(net "P2E_MB_BMC_TX_C_R2_DN<0>")
	)
	(segment
		(start 34.69132 -382.928114)
		(end 34.267648 -382.84404)
		(width 0.14732)
		(layer "In15.Cu")
		(net "P2E_MB_BMC_TX_C_R2_DN<0>")
	)
	(segment
		(start 27.913838 -381.455168)
		(end 27.49042 -381.371094)
		(width 0.14732)
		(layer "In15.Cu")
		(net "P2E_MB_BMC_TX_C_R2_DN<0>")
	)
	(segment
		(start 29.423868 -381.75565)
		(end 29.00045 -381.671576)
		(width 0.14732)
		(layer "In15.Cu")
		(net "P2E_MB_BMC_TX_C_R2_DN<0>")
	)
	(segment
		(start 32.43072 -382.354074)
		(end 32.28721 -382.449832)
		(width 0.14732)
		(layer "In15.Cu")
		(net "P2E_MB_BMC_TX_C_R2_DN<0>")
	)
	(segment
		(start 26.82748 -381.239014)
		(end 25.854152 -381.04572)
		(width 0.14732)
		(layer "In15.Cu")
		(net "P2E_MB_BMC_TX_C_R2_DN<0>")
	)
	(segment
		(start 20.271994 -382.085342)
		(end 19.966686 -382.39065)
		(width 0.14732)
		(layer "In15.Cu")
		(net "P2E_MB_BMC_TX_C_R2_DN<0>")
	)
	(segment
		(start 27.49042 -381.371094)
		(end 27.34691 -381.466852)
		(width 0.14732)
		(layer "In15.Cu")
		(net "P2E_MB_BMC_TX_C_R2_DN<0>")
	)
	(segment
		(start 22.162516 -381.04572)
		(end 22.040596 -381.16764)
		(width 0.14732)
		(layer "In15.Cu")
		(net "P2E_MB_BMC_TX_C_R2_DN<0>")
	)
	(segment
		(start 29.00045 -381.671576)
		(end 28.85694 -381.767334)
		(width 0.14732)
		(layer "In15.Cu")
		(net "P2E_MB_BMC_TX_C_R2_DN<0>")
	)
	(segment
		(start 20.444206 -382.085342)
		(end 20.271994 -382.085342)
		(width 0.14732)
		(layer "In15.Cu")
		(net "P2E_MB_BMC_TX_C_R2_DN<0>")
	)
	(segment
		(start 27.34691 -381.466852)
		(end 26.923238 -381.382778)
		(width 0.14732)
		(layer "In15.Cu")
		(net "P2E_MB_BMC_TX_C_R2_DN<0>")
	)
	(segment
		(start 30.681422 -382.00584)
		(end 30.086808 -381.88773)
		(width 0.14732)
		(layer "In15.Cu")
		(net "P2E_MB_BMC_TX_C_R2_DN<0>")
	)
	(segment
		(start 20.513548 -389.150098)
		(end 20.513548 -389.425942)
		(width 0.13208)
		(layer "F.Cu")
		(net "P2E_MB_BMC_TX_C_R1_DP<0>")
	)
	(segment
		(start 20.58416 -388.33552)
		(end 20.58416 -389.079486)
		(width 0.13208)
		(layer "F.Cu")
		(net "P2E_MB_BMC_TX_C_R1_DP<0>")
	)
	(segment
		(start 20.58416 -389.079486)
		(end 20.513548 -389.150098)
		(width 0.13208)
		(layer "F.Cu")
		(net "P2E_MB_BMC_TX_C_R1_DP<0>")
	)
	(segment
		(start 19.19859 -386.443728)
		(end 19.721322 -386.96646)
		(width 0.13208)
		(layer "F.Cu")
		(net "P2E_MB_BMC_TX_C_R1_DP<0>")
	)
	(segment
		(start 19.721322 -386.96646)
		(end 19.721322 -387.472682)
		(width 0.13208)
		(layer "F.Cu")
		(net "P2E_MB_BMC_TX_C_R1_DP<0>")
	)
	(segment
		(start 19.721322 -387.472682)
		(end 20.58416 -388.33552)
		(width 0.13208)
		(layer "F.Cu")
		(net "P2E_MB_BMC_TX_C_R1_DP<0>")
	)
	(segment
		(start 19.19859 -386.265674)
		(end 19.19859 -386.443728)
		(width 0.13208)
		(layer "F.Cu")
		(net "P2E_MB_BMC_TX_C_R1_DP<0>")
	)
	(segment
		(start 20.84324 -388.228078)
		(end 20.84324 -389.084566)
		(width 0.13208)
		(layer "F.Cu")
		(net "P2E_MB_BMC_TX_C_R1_DN<0>")
	)
	(segment
		(start 20.485608 -386.461254)
		(end 19.980402 -386.96646)
		(width 0.13208)
		(layer "F.Cu")
		(net "P2E_MB_BMC_TX_C_R1_DN<0>")
	)
	(segment
		(start 19.980402 -386.96646)
		(end 19.980402 -387.36524)
		(width 0.13208)
		(layer "F.Cu")
		(net "P2E_MB_BMC_TX_C_R1_DN<0>")
	)
	(segment
		(start 20.485608 -386.266944)
		(end 20.485608 -386.461254)
		(width 0.13208)
		(layer "F.Cu")
		(net "P2E_MB_BMC_TX_C_R1_DN<0>")
	)
	(segment
		(start 19.980402 -387.36524)
		(end 20.84324 -388.228078)
		(width 0.13208)
		(layer "F.Cu")
		(net "P2E_MB_BMC_TX_C_R1_DN<0>")
	)
	(segment
		(start 20.913598 -389.154924)
		(end 20.913598 -389.425942)
		(width 0.13208)
		(layer "F.Cu")
		(net "P2E_MB_BMC_TX_C_R1_DN<0>")
	)
	(segment
		(start 20.84324 -389.084566)
		(end 20.913598 -389.154924)
		(width 0.13208)
		(layer "F.Cu")
		(net "P2E_MB_BMC_TX_C_R1_DN<0>")
	)
	(segment
		(start 41.209976 -394.509244)
		(end 41.209976 -394.330174)
		(width 0.13208)
		(layer "F.Cu")
		(net "P2E_MB_BMC_TX_BUF2_DP<0>")
	)
	(segment
		(start 19.153632 -399.113756)
		(end 18.851372 -399.416016)
		(width 0.13208)
		(layer "F.Cu")
		(net "P2E_MB_BMC_TX_BUF2_DP<0>")
	)
	(segment
		(start 43.349164 -398.771872)
		(end 43.07332 -398.496028)
		(width 0.13208)
		(layer "F.Cu")
		(net "P2E_MB_BMC_TX_BUF2_DP<0>")
	)
	(segment
		(start 41.08958 -394.62964)
		(end 41.209976 -394.509244)
		(width 0.13208)
		(layer "F.Cu")
		(net "P2E_MB_BMC_TX_BUF2_DP<0>")
	)
	(segment
		(start 43.07332 -397.537178)
		(end 42.563796 -396.307056)
		(width 0.13208)
		(layer "F.Cu")
		(net "P2E_MB_BMC_TX_BUF2_DP<0>")
	)
	(segment
		(start 19.153632 -398.81937)
		(end 19.153632 -399.113756)
		(width 0.13208)
		(layer "F.Cu")
		(net "P2E_MB_BMC_TX_BUF2_DP<0>")
	)
	(segment
		(start 18.640806 -397.575786)
		(end 19.15668 -398.09166)
		(width 0.13208)
		(layer "F.Cu")
		(net "P2E_MB_BMC_TX_BUF2_DP<0>")
	)
	(segment
		(start 42.563796 -396.307056)
		(end 41.08958 -394.83284)
		(width 0.13208)
		(layer "F.Cu")
		(net "P2E_MB_BMC_TX_BUF2_DP<0>")
	)
	(segment
		(start 43.07332 -398.496028)
		(end 43.07332 -397.537178)
		(width 0.13208)
		(layer "F.Cu")
		(net "P2E_MB_BMC_TX_BUF2_DP<0>")
	)
	(segment
		(start 18.640806 -397.210788)
		(end 18.640806 -397.575786)
		(width 0.13208)
		(layer "F.Cu")
		(net "P2E_MB_BMC_TX_BUF2_DP<0>")
	)
	(segment
		(start 19.15668 -398.816322)
		(end 19.153632 -398.81937)
		(width 0.13208)
		(layer "F.Cu")
		(net "P2E_MB_BMC_TX_BUF2_DP<0>")
	)
	(segment
		(start 41.08958 -394.83284)
		(end 41.08958 -394.62964)
		(width 0.13208)
		(layer "F.Cu")
		(net "P2E_MB_BMC_TX_BUF2_DP<0>")
	)
	(segment
		(start 19.15668 -398.09166)
		(end 19.15668 -398.816322)
		(width 0.13208)
		(layer "F.Cu")
		(net "P2E_MB_BMC_TX_BUF2_DP<0>")
	)
	(segment
		(start 29.398468 -399.06702)
		(end 33.077912 -397.54302)
		(width 0.14732)
		(layer "In11.Cu")
		(net "P2E_MB_BMC_TX_BUF2_DP<0>")
	)
	(segment
		(start 43.054524 -398.154906)
		(end 43.054524 -398.477232)
		(width 0.14732)
		(layer "In11.Cu")
		(net "P2E_MB_BMC_TX_BUF2_DP<0>")
	)
	(segment
		(start 42.442638 -397.54302)
		(end 43.054524 -398.154906)
		(width 0.14732)
		(layer "In11.Cu")
		(net "P2E_MB_BMC_TX_BUF2_DP<0>")
	)
	(segment
		(start 19.146012 -398.404588)
		(end 19.6342 -397.9164)
		(width 0.14732)
		(layer "In11.Cu")
		(net "P2E_MB_BMC_TX_BUF2_DP<0>")
	)
	(segment
		(start 18.851372 -399.416016)
		(end 19.146012 -399.121376)
		(width 0.14732)
		(layer "In11.Cu")
		(net "P2E_MB_BMC_TX_BUF2_DP<0>")
	)
	(segment
		(start 33.077912 -397.54302)
		(end 42.442638 -397.54302)
		(width 0.14732)
		(layer "In11.Cu")
		(net "P2E_MB_BMC_TX_BUF2_DP<0>")
	)
	(segment
		(start 19.6342 -397.9164)
		(end 20.31238 -397.9164)
		(width 0.14732)
		(layer "In11.Cu")
		(net "P2E_MB_BMC_TX_BUF2_DP<0>")
	)
	(segment
		(start 21.428202 -398.59585)
		(end 22.565868 -399.06702)
		(width 0.14732)
		(layer "In11.Cu")
		(net "P2E_MB_BMC_TX_BUF2_DP<0>")
	)
	(segment
		(start 43.054524 -398.477232)
		(end 43.349164 -398.771872)
		(width 0.14732)
		(layer "In11.Cu")
		(net "P2E_MB_BMC_TX_BUF2_DP<0>")
	)
	(segment
		(start 20.31238 -397.9164)
		(end 21.057108 -398.224756)
		(width 0.14732)
		(layer "In11.Cu")
		(net "P2E_MB_BMC_TX_BUF2_DP<0>")
	)
	(segment
		(start 22.565868 -399.06702)
		(end 29.398468 -399.06702)
		(width 0.14732)
		(layer "In11.Cu")
		(net "P2E_MB_BMC_TX_BUF2_DP<0>")
	)
	(segment
		(start 21.057108 -398.224756)
		(end 21.428202 -398.59585)
		(width 0.14732)
		(layer "In11.Cu")
		(net "P2E_MB_BMC_TX_BUF2_DP<0>")
	)
	(segment
		(start 19.146012 -399.121376)
		(end 19.146012 -398.404588)
		(width 0.14732)
		(layer "In11.Cu")
		(net "P2E_MB_BMC_TX_BUF2_DP<0>")
	)
	(segment
		(start 19.412712 -399.113756)
		(end 19.714972 -399.416016)
		(width 0.13208)
		(layer "F.Cu")
		(net "P2E_MB_BMC_TX_BUF2_DN<0>")
	)
	(segment
		(start 19.927824 -397.212058)
		(end 19.927824 -397.620236)
		(width 0.13208)
		(layer "F.Cu")
		(net "P2E_MB_BMC_TX_BUF2_DN<0>")
	)
	(segment
		(start 40.8305 -394.940282)
		(end 40.8305 -394.63218)
		(width 0.13208)
		(layer "F.Cu")
		(net "P2E_MB_BMC_TX_BUF2_DN<0>")
	)
	(segment
		(start 19.412712 -398.926812)
		(end 19.412712 -399.113756)
		(width 0.13208)
		(layer "F.Cu")
		(net "P2E_MB_BMC_TX_BUF2_DN<0>")
	)
	(segment
		(start 40.710104 -394.511784)
		(end 40.710104 -394.330174)
		(width 0.13208)
		(layer "F.Cu")
		(net "P2E_MB_BMC_TX_BUF2_DN<0>")
	)
	(segment
		(start 19.41576 -398.923764)
		(end 19.412712 -398.926812)
		(width 0.13208)
		(layer "F.Cu")
		(net "P2E_MB_BMC_TX_BUF2_DN<0>")
	)
	(segment
		(start 42.81424 -397.58874)
		(end 42.344086 -396.453868)
		(width 0.13208)
		(layer "F.Cu")
		(net "P2E_MB_BMC_TX_BUF2_DN<0>")
	)
	(segment
		(start 42.485564 -398.771872)
		(end 42.81424 -398.443196)
		(width 0.13208)
		(layer "F.Cu")
		(net "P2E_MB_BMC_TX_BUF2_DN<0>")
	)
	(segment
		(start 19.927824 -397.620236)
		(end 19.41576 -398.1323)
		(width 0.13208)
		(layer "F.Cu")
		(net "P2E_MB_BMC_TX_BUF2_DN<0>")
	)
	(segment
		(start 40.8305 -394.63218)
		(end 40.710104 -394.511784)
		(width 0.13208)
		(layer "F.Cu")
		(net "P2E_MB_BMC_TX_BUF2_DN<0>")
	)
	(segment
		(start 19.41576 -398.1323)
		(end 19.41576 -398.923764)
		(width 0.13208)
		(layer "F.Cu")
		(net "P2E_MB_BMC_TX_BUF2_DN<0>")
	)
	(segment
		(start 42.344086 -396.453868)
		(end 40.8305 -394.940282)
		(width 0.13208)
		(layer "F.Cu")
		(net "P2E_MB_BMC_TX_BUF2_DN<0>")
	)
	(segment
		(start 42.81424 -398.443196)
		(end 42.81424 -397.58874)
		(width 0.13208)
		(layer "F.Cu")
		(net "P2E_MB_BMC_TX_BUF2_DN<0>")
	)
	(segment
		(start 36.7538 -397.81734)
		(end 39.06266 -397.81734)
		(width 0.14732)
		(layer "In11.Cu")
		(net "P2E_MB_BMC_TX_BUF2_DN<0>")
	)
	(segment
		(start 19.420332 -398.51838)
		(end 19.747992 -398.19072)
		(width 0.14732)
		(layer "In11.Cu")
		(net "P2E_MB_BMC_TX_BUF2_DN<0>")
	)
	(segment
		(start 39.7383 -397.81734)
		(end 40.31488 -397.81734)
		(width 0.14732)
		(layer "In11.Cu")
		(net "P2E_MB_BMC_TX_BUF2_DN<0>")
	)
	(segment
		(start 28.18384 -399.34134)
		(end 28.30576 -399.46326)
		(width 0.14732)
		(layer "In11.Cu")
		(net "P2E_MB_BMC_TX_BUF2_DN<0>")
	)
	(segment
		(start 30.871414 -398.754092)
		(end 31.030672 -398.819878)
		(width 0.14732)
		(layer "In11.Cu")
		(net "P2E_MB_BMC_TX_BUF2_DN<0>")
	)
	(segment
		(start 32.659066 -398.145508)
		(end 32.725106 -397.985996)
		(width 0.14732)
		(layer "In11.Cu")
		(net "P2E_MB_BMC_TX_BUF2_DN<0>")
	)
	(segment
		(start 40.99052 -397.81734)
		(end 41.42232 -397.81734)
		(width 0.14732)
		(layer "In11.Cu")
		(net "P2E_MB_BMC_TX_BUF2_DN<0>")
	)
	(segment
		(start 22.511258 -399.34134)
		(end 28.18384 -399.34134)
		(width 0.14732)
		(layer "In11.Cu")
		(net "P2E_MB_BMC_TX_BUF2_DN<0>")
	)
	(segment
		(start 40.31488 -397.81734)
		(end 40.4368 -397.93926)
		(width 0.14732)
		(layer "In11.Cu")
		(net "P2E_MB_BMC_TX_BUF2_DN<0>")
	)
	(segment
		(start 32.10052 -398.244822)
		(end 32.259778 -398.310862)
		(width 0.14732)
		(layer "In11.Cu")
		(net "P2E_MB_BMC_TX_BUF2_DN<0>")
	)
	(segment
		(start 41.42232 -397.81734)
		(end 41.54424 -397.93926)
		(width 0.14732)
		(layer "In11.Cu")
		(net "P2E_MB_BMC_TX_BUF2_DN<0>")
	)
	(segment
		(start 36.63188 -397.93926)
		(end 36.7538 -397.81734)
		(width 0.14732)
		(layer "In11.Cu")
		(net "P2E_MB_BMC_TX_BUF2_DN<0>")
	)
	(segment
		(start 42.780204 -398.477232)
		(end 42.485564 -398.771872)
		(width 0.14732)
		(layer "In11.Cu")
		(net "P2E_MB_BMC_TX_BUF2_DN<0>")
	)
	(segment
		(start 34.74212 -397.81734)
		(end 34.86404 -397.93926)
		(width 0.14732)
		(layer "In11.Cu")
		(net "P2E_MB_BMC_TX_BUF2_DN<0>")
	)
	(segment
		(start 33.7566 -397.93926)
		(end 34.1884 -397.93926)
		(width 0.14732)
		(layer "In11.Cu")
		(net "P2E_MB_BMC_TX_BUF2_DN<0>")
	)
	(segment
		(start 21.272754 -398.828514)
		(end 22.511258 -399.34134)
		(width 0.14732)
		(layer "In11.Cu")
		(net "P2E_MB_BMC_TX_BUF2_DN<0>")
	)
	(segment
		(start 31.030672 -398.819878)
		(end 31.42996 -398.654778)
		(width 0.14732)
		(layer "In11.Cu")
		(net "P2E_MB_BMC_TX_BUF2_DN<0>")
	)
	(segment
		(start 40.4368 -397.93926)
		(end 40.8686 -397.93926)
		(width 0.14732)
		(layer "In11.Cu")
		(net "P2E_MB_BMC_TX_BUF2_DN<0>")
	)
	(segment
		(start 39.18458 -397.93926)
		(end 39.61638 -397.93926)
		(width 0.14732)
		(layer "In11.Cu")
		(net "P2E_MB_BMC_TX_BUF2_DN<0>")
	)
	(segment
		(start 42.328846 -397.81734)
		(end 42.780204 -398.268698)
		(width 0.14732)
		(layer "In11.Cu")
		(net "P2E_MB_BMC_TX_BUF2_DN<0>")
	)
	(segment
		(start 35.29584 -397.93926)
		(end 35.41776 -397.81734)
		(width 0.14732)
		(layer "In11.Cu")
		(net "P2E_MB_BMC_TX_BUF2_DN<0>")
	)
	(segment
		(start 28.73756 -399.46326)
		(end 28.85948 -399.34134)
		(width 0.14732)
		(layer "In11.Cu")
		(net "P2E_MB_BMC_TX_BUF2_DN<0>")
	)
	(segment
		(start 19.747992 -398.19072)
		(end 20.25777 -398.19072)
		(width 0.14732)
		(layer "In11.Cu")
		(net "P2E_MB_BMC_TX_BUF2_DN<0>")
	)
	(segment
		(start 39.06266 -397.81734)
		(end 39.18458 -397.93926)
		(width 0.14732)
		(layer "In11.Cu")
		(net "P2E_MB_BMC_TX_BUF2_DN<0>")
	)
	(segment
		(start 40.8686 -397.93926)
		(end 40.99052 -397.81734)
		(width 0.14732)
		(layer "In11.Cu")
		(net "P2E_MB_BMC_TX_BUF2_DN<0>")
	)
	(segment
		(start 19.714972 -399.416016)
		(end 19.420332 -399.121376)
		(width 0.14732)
		(layer "In11.Cu")
		(net "P2E_MB_BMC_TX_BUF2_DN<0>")
	)
	(segment
		(start 20.25777 -398.19072)
		(end 20.90166 -398.45742)
		(width 0.14732)
		(layer "In11.Cu")
		(net "P2E_MB_BMC_TX_BUF2_DN<0>")
	)
	(segment
		(start 32.725106 -397.985996)
		(end 33.132522 -397.81734)
		(width 0.14732)
		(layer "In11.Cu")
		(net "P2E_MB_BMC_TX_BUF2_DN<0>")
	)
	(segment
		(start 28.30576 -399.46326)
		(end 28.73756 -399.46326)
		(width 0.14732)
		(layer "In11.Cu")
		(net "P2E_MB_BMC_TX_BUF2_DN<0>")
	)
	(segment
		(start 31.495746 -398.495266)
		(end 32.10052 -398.244822)
		(width 0.14732)
		(layer "In11.Cu")
		(net "P2E_MB_BMC_TX_BUF2_DN<0>")
	)
	(segment
		(start 34.1884 -397.93926)
		(end 34.31032 -397.81734)
		(width 0.14732)
		(layer "In11.Cu")
		(net "P2E_MB_BMC_TX_BUF2_DN<0>")
	)
	(segment
		(start 33.132522 -397.81734)
		(end 33.63468 -397.81734)
		(width 0.14732)
		(layer "In11.Cu")
		(net "P2E_MB_BMC_TX_BUF2_DN<0>")
	)
	(segment
		(start 19.420332 -399.121376)
		(end 19.420332 -398.51838)
		(width 0.14732)
		(layer "In11.Cu")
		(net "P2E_MB_BMC_TX_BUF2_DN<0>")
	)
	(segment
		(start 34.86404 -397.93926)
		(end 35.29584 -397.93926)
		(width 0.14732)
		(layer "In11.Cu")
		(net "P2E_MB_BMC_TX_BUF2_DN<0>")
	)
	(segment
		(start 42.09796 -397.81734)
		(end 42.328846 -397.81734)
		(width 0.14732)
		(layer "In11.Cu")
		(net "P2E_MB_BMC_TX_BUF2_DN<0>")
	)
	(segment
		(start 42.780204 -398.268698)
		(end 42.780204 -398.477232)
		(width 0.14732)
		(layer "In11.Cu")
		(net "P2E_MB_BMC_TX_BUF2_DN<0>")
	)
	(segment
		(start 35.41776 -397.81734)
		(end 36.07816 -397.81734)
		(width 0.14732)
		(layer "In11.Cu")
		(net "P2E_MB_BMC_TX_BUF2_DN<0>")
	)
	(segment
		(start 39.61638 -397.93926)
		(end 39.7383 -397.81734)
		(width 0.14732)
		(layer "In11.Cu")
		(net "P2E_MB_BMC_TX_BUF2_DN<0>")
	)
	(segment
		(start 41.54424 -397.93926)
		(end 41.97604 -397.93926)
		(width 0.14732)
		(layer "In11.Cu")
		(net "P2E_MB_BMC_TX_BUF2_DN<0>")
	)
	(segment
		(start 20.90166 -398.45742)
		(end 21.272754 -398.828514)
		(width 0.14732)
		(layer "In11.Cu")
		(net "P2E_MB_BMC_TX_BUF2_DN<0>")
	)
	(segment
		(start 31.42996 -398.654778)
		(end 31.495746 -398.495266)
		(width 0.14732)
		(layer "In11.Cu")
		(net "P2E_MB_BMC_TX_BUF2_DN<0>")
	)
	(segment
		(start 33.63468 -397.81734)
		(end 33.7566 -397.93926)
		(width 0.14732)
		(layer "In11.Cu")
		(net "P2E_MB_BMC_TX_BUF2_DN<0>")
	)
	(segment
		(start 29.453078 -399.34134)
		(end 30.871414 -398.754092)
		(width 0.14732)
		(layer "In11.Cu")
		(net "P2E_MB_BMC_TX_BUF2_DN<0>")
	)
	(segment
		(start 34.31032 -397.81734)
		(end 34.74212 -397.81734)
		(width 0.14732)
		(layer "In11.Cu")
		(net "P2E_MB_BMC_TX_BUF2_DN<0>")
	)
	(segment
		(start 36.07816 -397.81734)
		(end 36.20008 -397.93926)
		(width 0.14732)
		(layer "In11.Cu")
		(net "P2E_MB_BMC_TX_BUF2_DN<0>")
	)
	(segment
		(start 28.85948 -399.34134)
		(end 29.453078 -399.34134)
		(width 0.14732)
		(layer "In11.Cu")
		(net "P2E_MB_BMC_TX_BUF2_DN<0>")
	)
	(segment
		(start 32.259778 -398.310862)
		(end 32.659066 -398.145508)
		(width 0.14732)
		(layer "In11.Cu")
		(net "P2E_MB_BMC_TX_BUF2_DN<0>")
	)
	(segment
		(start 36.20008 -397.93926)
		(end 36.63188 -397.93926)
		(width 0.14732)
		(layer "In11.Cu")
		(net "P2E_MB_BMC_TX_BUF2_DN<0>")
	)
	(segment
		(start 41.97604 -397.93926)
		(end 42.09796 -397.81734)
		(width 0.14732)
		(layer "In11.Cu")
		(net "P2E_MB_BMC_TX_BUF2_DN<0>")
	)
	(segment
		(start 25.9715 -398.088612)
		(end 25.9715 -398.343374)
		(width 0.13208)
		(layer "F.Cu")
		(net "P2E_MB_BMC_RX_R2_DP<0>")
	)
	(segment
		(start 37.7317 -398.364202)
		(end 37.7317 -396.365222)
		(width 0.13208)
		(layer "F.Cu")
		(net "P2E_MB_BMC_RX_R2_DP<0>")
	)
	(segment
		(start 26.533094 -399.887186)
		(end 26.533094 -400.129756)
		(width 0.13208)
		(layer "F.Cu")
		(net "P2E_MB_BMC_RX_R2_DP<0>")
	)
	(segment
		(start 37.7317 -396.365222)
		(end 39.089584 -395.007338)
		(width 0.13208)
		(layer "F.Cu")
		(net "P2E_MB_BMC_RX_R2_DP<0>")
	)
	(segment
		(start 38.026848 -398.65935)
		(end 37.7317 -398.364202)
		(width 0.13208)
		(layer "F.Cu")
		(net "P2E_MB_BMC_RX_R2_DP<0>")
	)
	(segment
		(start 25.5397 -398.775174)
		(end 25.5397 -398.893792)
		(width 0.13208)
		(layer "F.Cu")
		(net "P2E_MB_BMC_RX_R2_DP<0>")
	)
	(segment
		(start 39.20998 -394.51788)
		(end 39.20998 -394.330174)
		(width 0.13208)
		(layer "F.Cu")
		(net "P2E_MB_BMC_RX_R2_DP<0>")
	)
	(segment
		(start 25.9715 -398.343374)
		(end 25.5397 -398.775174)
		(width 0.13208)
		(layer "F.Cu")
		(net "P2E_MB_BMC_RX_R2_DP<0>")
	)
	(segment
		(start 25.5397 -398.893792)
		(end 26.533094 -399.887186)
		(width 0.13208)
		(layer "F.Cu")
		(net "P2E_MB_BMC_RX_R2_DP<0>")
	)
	(segment
		(start 39.089584 -394.638276)
		(end 39.20998 -394.51788)
		(width 0.13208)
		(layer "F.Cu")
		(net "P2E_MB_BMC_RX_R2_DP<0>")
	)
	(segment
		(start 26.533094 -400.129756)
		(end 26.835354 -400.432016)
		(width 0.13208)
		(layer "F.Cu")
		(net "P2E_MB_BMC_RX_R2_DP<0>")
	)
	(segment
		(start 39.089584 -395.007338)
		(end 39.089584 -394.638276)
		(width 0.13208)
		(layer "F.Cu")
		(net "P2E_MB_BMC_RX_R2_DP<0>")
	)
	(segment
		(start 32.994092 -399.29054)
		(end 27.179016 -399.29054)
		(width 0.14732)
		(layer "In15.Cu")
		(net "P2E_MB_BMC_RX_R2_DP<0>")
	)
	(segment
		(start 35.34283 -400.26336)
		(end 32.994092 -399.29054)
		(width 0.14732)
		(layer "In15.Cu")
		(net "P2E_MB_BMC_RX_R2_DP<0>")
	)
	(segment
		(start 37.20338 -400.26336)
		(end 35.34283 -400.26336)
		(width 0.14732)
		(layer "In15.Cu")
		(net "P2E_MB_BMC_RX_R2_DP<0>")
	)
	(segment
		(start 38.026848 -398.65935)
		(end 37.732208 -398.95399)
		(width 0.14732)
		(layer "In15.Cu")
		(net "P2E_MB_BMC_RX_R2_DP<0>")
	)
	(segment
		(start 27.179016 -399.29054)
		(end 26.540714 -399.928842)
		(width 0.14732)
		(layer "In15.Cu")
		(net "P2E_MB_BMC_RX_R2_DP<0>")
	)
	(segment
		(start 26.540714 -399.928842)
		(end 26.540714 -400.137376)
		(width 0.14732)
		(layer "In15.Cu")
		(net "P2E_MB_BMC_RX_R2_DP<0>")
	)
	(segment
		(start 37.732208 -398.95399)
		(end 37.732208 -399.734532)
		(width 0.14732)
		(layer "In15.Cu")
		(net "P2E_MB_BMC_RX_R2_DP<0>")
	)
	(segment
		(start 37.732208 -399.734532)
		(end 37.20338 -400.26336)
		(width 0.14732)
		(layer "In15.Cu")
		(net "P2E_MB_BMC_RX_R2_DP<0>")
	)
	(segment
		(start 26.540714 -400.137376)
		(end 26.835354 -400.432016)
		(width 0.14732)
		(layer "In15.Cu")
		(net "P2E_MB_BMC_RX_R2_DP<0>")
	)
	(segment
		(start 25.28062 -399.001234)
		(end 26.274014 -399.994628)
		(width 0.13208)
		(layer "F.Cu")
		(net "P2E_MB_BMC_RX_R2_DN<0>")
	)
	(segment
		(start 24.684482 -398.087342)
		(end 24.684482 -398.287748)
		(width 0.13208)
		(layer "F.Cu")
		(net "P2E_MB_BMC_RX_R2_DN<0>")
	)
	(segment
		(start 38.830504 -394.628624)
		(end 38.710108 -394.508228)
		(width 0.13208)
		(layer "F.Cu")
		(net "P2E_MB_BMC_RX_R2_DN<0>")
	)
	(segment
		(start 37.47262 -396.25778)
		(end 38.830504 -394.899896)
		(width 0.13208)
		(layer "F.Cu")
		(net "P2E_MB_BMC_RX_R2_DN<0>")
	)
	(segment
		(start 37.163248 -398.65935)
		(end 37.47262 -398.349978)
		(width 0.13208)
		(layer "F.Cu")
		(net "P2E_MB_BMC_RX_R2_DN<0>")
	)
	(segment
		(start 38.710108 -394.508228)
		(end 38.710108 -394.330174)
		(width 0.13208)
		(layer "F.Cu")
		(net "P2E_MB_BMC_RX_R2_DN<0>")
	)
	(segment
		(start 25.28062 -398.883886)
		(end 25.28062 -399.001234)
		(width 0.13208)
		(layer "F.Cu")
		(net "P2E_MB_BMC_RX_R2_DN<0>")
	)
	(segment
		(start 37.47262 -398.349978)
		(end 37.47262 -396.25778)
		(width 0.13208)
		(layer "F.Cu")
		(net "P2E_MB_BMC_RX_R2_DN<0>")
	)
	(segment
		(start 26.274014 -399.994628)
		(end 26.274014 -400.129756)
		(width 0.13208)
		(layer "F.Cu")
		(net "P2E_MB_BMC_RX_R2_DN<0>")
	)
	(segment
		(start 24.684482 -398.287748)
		(end 25.28062 -398.883886)
		(width 0.13208)
		(layer "F.Cu")
		(net "P2E_MB_BMC_RX_R2_DN<0>")
	)
	(segment
		(start 38.830504 -394.899896)
		(end 38.830504 -394.628624)
		(width 0.13208)
		(layer "F.Cu")
		(net "P2E_MB_BMC_RX_R2_DN<0>")
	)
	(segment
		(start 26.274014 -400.129756)
		(end 25.971754 -400.432016)
		(width 0.13208)
		(layer "F.Cu")
		(net "P2E_MB_BMC_RX_R2_DN<0>")
	)
	(segment
		(start 37.089588 -399.98904)
		(end 35.39744 -399.98904)
		(width 0.14732)
		(layer "In15.Cu")
		(net "P2E_MB_BMC_RX_R2_DN<0>")
	)
	(segment
		(start 37.457888 -398.95399)
		(end 37.457888 -399.62074)
		(width 0.14732)
		(layer "In15.Cu")
		(net "P2E_MB_BMC_RX_R2_DN<0>")
	)
	(segment
		(start 26.266394 -400.137376)
		(end 25.971754 -400.432016)
		(width 0.14732)
		(layer "In15.Cu")
		(net "P2E_MB_BMC_RX_R2_DN<0>")
	)
	(segment
		(start 35.39744 -399.98904)
		(end 33.048702 -399.01622)
		(width 0.14732)
		(layer "In15.Cu")
		(net "P2E_MB_BMC_RX_R2_DN<0>")
	)
	(segment
		(start 37.163248 -398.65935)
		(end 37.457888 -398.95399)
		(width 0.14732)
		(layer "In15.Cu")
		(net "P2E_MB_BMC_RX_R2_DN<0>")
	)
	(segment
		(start 37.457888 -399.62074)
		(end 37.089588 -399.98904)
		(width 0.14732)
		(layer "In15.Cu")
		(net "P2E_MB_BMC_RX_R2_DN<0>")
	)
	(segment
		(start 33.048702 -399.01622)
		(end 27.065224 -399.01622)
		(width 0.14732)
		(layer "In15.Cu")
		(net "P2E_MB_BMC_RX_R2_DN<0>")
	)
	(segment
		(start 26.266394 -399.81505)
		(end 26.266394 -400.137376)
		(width 0.14732)
		(layer "In15.Cu")
		(net "P2E_MB_BMC_RX_R2_DN<0>")
	)
	(segment
		(start 27.065224 -399.01622)
		(end 26.266394 -399.81505)
		(width 0.14732)
		(layer "In15.Cu")
		(net "P2E_MB_BMC_RX_R2_DN<0>")
	)
	(segment
		(start 25.9715 -395.986508)
		(end 25.959816 -395.974824)
		(width 0.13208)
		(layer "F.Cu")
		(net "P2E_MB_BMC_RX_R1_DP<0>")
	)
	(segment
		(start 25.959816 -395.974824)
		(end 25.50922 -395.523212)
		(width 0.13208)
		(layer "F.Cu")
		(net "P2E_MB_BMC_RX_R1_DP<0>")
	)
	(segment
		(start 25.50922 -395.235938)
		(end 23.243286 -392.970004)
		(width 0.13208)
		(layer "F.Cu")
		(net "P2E_MB_BMC_RX_R1_DP<0>")
	)
	(segment
		(start 25.50922 -395.523212)
		(end 25.50922 -395.235938)
		(width 0.13208)
		(layer "F.Cu")
		(net "P2E_MB_BMC_RX_R1_DP<0>")
	)
	(segment
		(start 23.313644 -392.485372)
		(end 23.313644 -391.92581)
		(width 0.13208)
		(layer "F.Cu")
		(net "P2E_MB_BMC_RX_R1_DP<0>")
	)
	(segment
		(start 23.243286 -392.55573)
		(end 23.313644 -392.485372)
		(width 0.13208)
		(layer "F.Cu")
		(net "P2E_MB_BMC_RX_R1_DP<0>")
	)
	(segment
		(start 25.9715 -396.488412)
		(end 25.9715 -395.986508)
		(width 0.13208)
		(layer "F.Cu")
		(net "P2E_MB_BMC_RX_R1_DP<0>")
	)
	(segment
		(start 23.243286 -392.970004)
		(end 23.243286 -392.55573)
		(width 0.13208)
		(layer "F.Cu")
		(net "P2E_MB_BMC_RX_R1_DP<0>")
	)
	(segment
		(start 22.913594 -392.485118)
		(end 22.913594 -391.92581)
		(width 0.13208)
		(layer "F.Cu")
		(net "P2E_MB_BMC_RX_R1_DN<0>")
	)
	(segment
		(start 24.684482 -396.078456)
		(end 25.25014 -395.512036)
		(width 0.13208)
		(layer "F.Cu")
		(net "P2E_MB_BMC_RX_R1_DN<0>")
	)
	(segment
		(start 22.984206 -392.55573)
		(end 22.913594 -392.485118)
		(width 0.13208)
		(layer "F.Cu")
		(net "P2E_MB_BMC_RX_R1_DN<0>")
	)
	(segment
		(start 22.984206 -393.077446)
		(end 22.984206 -392.55573)
		(width 0.13208)
		(layer "F.Cu")
		(net "P2E_MB_BMC_RX_R1_DN<0>")
	)
	(segment
		(start 25.25014 -395.34338)
		(end 22.984206 -393.077446)
		(width 0.13208)
		(layer "F.Cu")
		(net "P2E_MB_BMC_RX_R1_DN<0>")
	)
	(segment
		(start 25.25014 -395.512036)
		(end 25.25014 -395.34338)
		(width 0.13208)
		(layer "F.Cu")
		(net "P2E_MB_BMC_RX_R1_DN<0>")
	)
	(segment
		(start 24.684482 -396.487142)
		(end 24.684482 -396.078456)
		(width 0.13208)
		(layer "F.Cu")
		(net "P2E_MB_BMC_RX_R1_DN<0>")
	)
	(segment
		(start 39.20998 -390.35228)
		(end 39.20998 -390.530334)
		(width 0.13208)
		(layer "F.Cu")
		(net "P2E_MB_BMC_RX_BUF2_C_DP<0>")
	)
	(segment
		(start 37.527992 -387.27507)
		(end 37.982398 -388.372096)
		(width 0.13208)
		(layer "F.Cu")
		(net "P2E_MB_BMC_RX_BUF2_C_DP<0>")
	)
	(segment
		(start 37.982398 -388.372096)
		(end 39.089584 -389.479282)
		(width 0.13208)
		(layer "F.Cu")
		(net "P2E_MB_BMC_RX_BUF2_C_DP<0>")
	)
	(segment
		(start 23.767034 -384.578098)
		(end 23.767034 -384.261614)
		(width 0.13208)
		(layer "F.Cu")
		(net "P2E_MB_BMC_RX_BUF2_C_DP<0>")
	)
	(segment
		(start 39.089584 -389.479282)
		(end 39.089584 -390.231884)
		(width 0.13208)
		(layer "F.Cu")
		(net "P2E_MB_BMC_RX_BUF2_C_DP<0>")
	)
	(segment
		(start 23.767034 -384.261614)
		(end 23.234396 -383.728976)
		(width 0.13208)
		(layer "F.Cu")
		(net "P2E_MB_BMC_RX_BUF2_C_DP<0>")
	)
	(segment
		(start 23.234396 -383.728976)
		(end 23.234396 -383.235454)
		(width 0.13208)
		(layer "F.Cu")
		(net "P2E_MB_BMC_RX_BUF2_C_DP<0>")
	)
	(segment
		(start 37.527992 -385.715256)
		(end 37.527992 -387.27507)
		(width 0.13208)
		(layer "F.Cu")
		(net "P2E_MB_BMC_RX_BUF2_C_DP<0>")
	)
	(segment
		(start 37.830252 -385.412996)
		(end 37.527992 -385.715256)
		(width 0.13208)
		(layer "F.Cu")
		(net "P2E_MB_BMC_RX_BUF2_C_DP<0>")
	)
	(segment
		(start 39.089584 -390.231884)
		(end 39.20998 -390.35228)
		(width 0.13208)
		(layer "F.Cu")
		(net "P2E_MB_BMC_RX_BUF2_C_DP<0>")
	)
	(segment
		(start 23.234396 -383.235454)
		(end 23.536656 -382.933194)
		(width 0.13208)
		(layer "F.Cu")
		(net "P2E_MB_BMC_RX_BUF2_C_DP<0>")
	)
	(segment
		(start 23.242016 -382.497076)
		(end 23.456392 -382.2827)
		(width 0.14732)
		(layer "In15.Cu")
		(net "P2E_MB_BMC_RX_BUF2_C_DP<0>")
	)
	(segment
		(start 23.536656 -382.933194)
		(end 23.242016 -382.638554)
		(width 0.14732)
		(layer "In15.Cu")
		(net "P2E_MB_BMC_RX_BUF2_C_DP<0>")
	)
	(segment
		(start 24.43988 -382.2827)
		(end 27.761692 -383.658618)
		(width 0.14732)
		(layer "In15.Cu")
		(net "P2E_MB_BMC_RX_BUF2_C_DP<0>")
	)
	(segment
		(start 27.761692 -383.658618)
		(end 28.623768 -383.658618)
		(width 0.14732)
		(layer "In15.Cu")
		(net "P2E_MB_BMC_RX_BUF2_C_DP<0>")
	)
	(segment
		(start 23.456392 -382.2827)
		(end 24.43988 -382.2827)
		(width 0.14732)
		(layer "In15.Cu")
		(net "P2E_MB_BMC_RX_BUF2_C_DP<0>")
	)
	(segment
		(start 37.535612 -386.029962)
		(end 37.535612 -385.707636)
		(width 0.14732)
		(layer "In15.Cu")
		(net "P2E_MB_BMC_RX_BUF2_C_DP<0>")
	)
	(segment
		(start 28.623768 -383.658618)
		(end 35.37712 -386.45592)
		(width 0.14732)
		(layer "In15.Cu")
		(net "P2E_MB_BMC_RX_BUF2_C_DP<0>")
	)
	(segment
		(start 37.535612 -385.707636)
		(end 37.830252 -385.412996)
		(width 0.14732)
		(layer "In15.Cu")
		(net "P2E_MB_BMC_RX_BUF2_C_DP<0>")
	)
	(segment
		(start 37.109654 -386.45592)
		(end 37.535612 -386.029962)
		(width 0.14732)
		(layer "In15.Cu")
		(net "P2E_MB_BMC_RX_BUF2_C_DP<0>")
	)
	(segment
		(start 35.37712 -386.45592)
		(end 37.109654 -386.45592)
		(width 0.14732)
		(layer "In15.Cu")
		(net "P2E_MB_BMC_RX_BUF2_C_DP<0>")
	)
	(segment
		(start 23.242016 -382.638554)
		(end 23.242016 -382.497076)
		(width 0.14732)
		(layer "In15.Cu")
		(net "P2E_MB_BMC_RX_BUF2_C_DP<0>")
	)
	(segment
		(start 22.460204 -384.24993)
		(end 22.975316 -383.734818)
		(width 0.13208)
		(layer "F.Cu")
		(net "P2E_MB_BMC_RX_BUF2_C_DN<0>")
	)
	(segment
		(start 36.966652 -385.412996)
		(end 37.268912 -385.715256)
		(width 0.13208)
		(layer "F.Cu")
		(net "P2E_MB_BMC_RX_BUF2_C_DN<0>")
	)
	(segment
		(start 38.830504 -389.586724)
		(end 38.830504 -390.244076)
		(width 0.13208)
		(layer "F.Cu")
		(net "P2E_MB_BMC_RX_BUF2_C_DN<0>")
	)
	(segment
		(start 22.975316 -383.235454)
		(end 22.673056 -382.933194)
		(width 0.13208)
		(layer "F.Cu")
		(net "P2E_MB_BMC_RX_BUF2_C_DN<0>")
	)
	(segment
		(start 38.710108 -390.364472)
		(end 38.710108 -390.530334)
		(width 0.13208)
		(layer "F.Cu")
		(net "P2E_MB_BMC_RX_BUF2_C_DN<0>")
	)
	(segment
		(start 22.460204 -384.578098)
		(end 22.460204 -384.24993)
		(width 0.13208)
		(layer "F.Cu")
		(net "P2E_MB_BMC_RX_BUF2_C_DN<0>")
	)
	(segment
		(start 37.268912 -385.715256)
		(end 37.268912 -387.326632)
		(width 0.13208)
		(layer "F.Cu")
		(net "P2E_MB_BMC_RX_BUF2_C_DN<0>")
	)
	(segment
		(start 37.268912 -387.326632)
		(end 37.762688 -388.518908)
		(width 0.13208)
		(layer "F.Cu")
		(net "P2E_MB_BMC_RX_BUF2_C_DN<0>")
	)
	(segment
		(start 37.762688 -388.518908)
		(end 38.830504 -389.586724)
		(width 0.13208)
		(layer "F.Cu")
		(net "P2E_MB_BMC_RX_BUF2_C_DN<0>")
	)
	(segment
		(start 22.975316 -383.734818)
		(end 22.975316 -383.235454)
		(width 0.13208)
		(layer "F.Cu")
		(net "P2E_MB_BMC_RX_BUF2_C_DN<0>")
	)
	(segment
		(start 38.830504 -390.244076)
		(end 38.710108 -390.364472)
		(width 0.13208)
		(layer "F.Cu")
		(net "P2E_MB_BMC_RX_BUF2_C_DN<0>")
	)
	(segment
		(start 22.673056 -382.933194)
		(end 22.967696 -382.638554)
		(width 0.14732)
		(layer "In15.Cu")
		(net "P2E_MB_BMC_RX_BUF2_C_DN<0>")
	)
	(segment
		(start 24.49449 -382.00838)
		(end 27.816302 -383.384298)
		(width 0.14732)
		(layer "In15.Cu")
		(net "P2E_MB_BMC_RX_BUF2_C_DN<0>")
	)
	(segment
		(start 36.995862 -386.1816)
		(end 37.261292 -385.91617)
		(width 0.14732)
		(layer "In15.Cu")
		(net "P2E_MB_BMC_RX_BUF2_C_DN<0>")
	)
	(segment
		(start 27.816302 -383.384298)
		(end 28.678378 -383.384298)
		(width 0.14732)
		(layer "In15.Cu")
		(net "P2E_MB_BMC_RX_BUF2_C_DN<0>")
	)
	(segment
		(start 23.3426 -382.00838)
		(end 24.49449 -382.00838)
		(width 0.14732)
		(layer "In15.Cu")
		(net "P2E_MB_BMC_RX_BUF2_C_DN<0>")
	)
	(segment
		(start 37.261292 -385.91617)
		(end 37.261292 -385.707636)
		(width 0.14732)
		(layer "In15.Cu")
		(net "P2E_MB_BMC_RX_BUF2_C_DN<0>")
	)
	(segment
		(start 28.678378 -383.384298)
		(end 35.43173 -386.1816)
		(width 0.14732)
		(layer "In15.Cu")
		(net "P2E_MB_BMC_RX_BUF2_C_DN<0>")
	)
	(segment
		(start 22.967696 -382.638554)
		(end 22.967696 -382.383284)
		(width 0.14732)
		(layer "In15.Cu")
		(net "P2E_MB_BMC_RX_BUF2_C_DN<0>")
	)
	(segment
		(start 37.261292 -385.707636)
		(end 36.966652 -385.412996)
		(width 0.14732)
		(layer "In15.Cu")
		(net "P2E_MB_BMC_RX_BUF2_C_DN<0>")
	)
	(segment
		(start 35.43173 -386.1816)
		(end 36.995862 -386.1816)
		(width 0.14732)
		(layer "In15.Cu")
		(net "P2E_MB_BMC_RX_BUF2_C_DN<0>")
	)
	(segment
		(start 22.967696 -382.383284)
		(end 23.3426 -382.00838)
		(width 0.14732)
		(layer "In15.Cu")
		(net "P2E_MB_BMC_RX_BUF2_C_DN<0>")
	)
	(segment
		(start 40.209978 -387.818122)
		(end 40.209978 -388.95782)
		(width 0.10668)
		(layer "F.Cu")
		(net "P2E_BUF2_VDD")
	)
	(segment
		(start 40.209978 -388.95782)
		(end 40.209978 -390.530334)
		(width 0.10668)
		(layer "F.Cu")
		(net "P2E_BUF2_VDD")
	)
	(segment
		(start 40.27678 -387.75132)
		(end 40.209978 -387.818122)
		(width 0.10668)
		(layer "F.Cu")
		(net "P2E_BUF2_VDD")
	)
	(segment
		(start 40.266366 -387.740906)
		(end 40.27678 -387.75132)
		(width 0.10668)
		(layer "F.Cu")
		(net "P2E_BUF2_VDD")
	)
	(segment
		(start 39.710106 -389.370316)
		(end 39.263574 -388.923784)
		(width 0.10668)
		(layer "F.Cu")
		(net "P2E_BUF2_VDD")
	)
	(segment
		(start 39.263574 -387.740906)
		(end 40.266366 -387.740906)
		(width 0.10668)
		(layer "F.Cu")
		(net "P2E_BUF2_VDD")
	)
	(segment
		(start 39.263574 -388.923784)
		(end 39.263574 -387.740906)
		(width 0.10668)
		(layer "F.Cu")
		(net "P2E_BUF2_VDD")
	)
	(segment
		(start 39.710106 -390.530334)
		(end 39.710106 -389.370316)
		(width 0.10668)
		(layer "F.Cu")
		(net "P2E_BUF2_VDD")
	)
	(via
		(at 40.209978 -388.95782)
		(size 0.762)
		(drill 0.381)
		(layers "F.Cu" "B.Cu")
		(net "P2E_BUF2_VDD")
	)
	(via
		(at 278.206708 -402.7551)
		(size 0.508)
		(drill 0.254)
		(layers "F.Cu" "B.Cu")
		(net "P12V_MAIN_R_0")
	)
	(via
		(at 280.40584 -403.9362)
		(size 0.6604)
		(drill 0.3302)
		(layers "F.Cu" "B.Cu")
		(net "P12V_MAIN_R_0")
	)
	(via
		(at 280.645108 -403.01164)
		(size 0.762)
		(drill 0.381)
		(layers "F.Cu" "B.Cu")
		(net "P12V_MAIN_R_0")
	)
	(via
		(at 280.40584 -400.3802)
		(size 0.6604)
		(drill 0.3302)
		(layers "F.Cu" "B.Cu")
		(net "P12V_MAIN_R_0")
	)
	(via
		(at 280.40584 -402.1582)
		(size 0.6604)
		(drill 0.3302)
		(layers "F.Cu" "B.Cu")
		(net "P12V_MAIN_R_0")
	)
	(via
		(at 276.682708 -402.7551)
		(size 0.508)
		(drill 0.254)
		(layers "F.Cu" "B.Cu")
		(net "P12V_MAIN_R_0")
	)
	(via
		(at 277.444708 -402.7551)
		(size 0.508)
		(drill 0.254)
		(layers "F.Cu" "B.Cu")
		(net "P12V_MAIN_R_0")
	)
	(via
		(at 278.968708 -402.7551)
		(size 0.508)
		(drill 0.254)
		(layers "F.Cu" "B.Cu")
		(net "P12V_MAIN_R_0")
	)
	(via
		(at 251.202952 -399.60296)
		(size 0.508)
		(drill 0.254)
		(layers "F.Cu" "B.Cu")
		(net "P12V_MAIN_R")
	)
	(via
		(at 263.07288 -400.36496)
		(size 0.508)
		(drill 0.254)
		(layers "F.Cu" "B.Cu")
		(net "P12V_MAIN_R")
	)
	(via
		(at 269.903448 -402.84654)
		(size 0.508)
		(drill 0.254)
		(layers "F.Cu" "B.Cu")
		(net "P12V_MAIN_R")
	)
	(via
		(at 261.097268 -402.86686)
		(size 0.508)
		(drill 0.254)
		(layers "F.Cu" "B.Cu")
		(net "P12V_MAIN_R")
	)
	(via
		(at 259.573268 -402.86686)
		(size 0.508)
		(drill 0.254)
		(layers "F.Cu" "B.Cu")
		(net "P12V_MAIN_R")
	)
	(via
		(at 269.007844 -401.12696)
		(size 0.508)
		(drill 0.254)
		(layers "F.Cu" "B.Cu")
		(net "P12V_MAIN_R")
	)
	(via
		(at 270.665448 -402.84654)
		(size 0.508)
		(drill 0.254)
		(layers "F.Cu" "B.Cu")
		(net "P12V_MAIN_R")
	)
	(via
		(at 246.342408 -402.82368)
		(size 0.508)
		(drill 0.254)
		(layers "F.Cu" "B.Cu")
		(net "P12V_MAIN_R")
	)
	(via
		(at 260.335268 -402.86686)
		(size 0.508)
		(drill 0.254)
		(layers "F.Cu" "B.Cu")
		(net "P12V_MAIN_R")
	)
	(via
		(at 251.658628 -402.82368)
		(size 0.508)
		(drill 0.254)
		(layers "F.Cu" "B.Cu")
		(net "P12V_MAIN_R")
	)
	(via
		(at 245.580408 -402.82368)
		(size 0.508)
		(drill 0.254)
		(layers "F.Cu" "B.Cu")
		(net "P12V_MAIN_R")
	)
	(via
		(at 261.859268 -402.86686)
		(size 0.508)
		(drill 0.254)
		(layers "F.Cu" "B.Cu")
		(net "P12V_MAIN_R")
	)
	(via
		(at 253.182628 -402.82368)
		(size 0.508)
		(drill 0.254)
		(layers "F.Cu" "B.Cu")
		(net "P12V_MAIN_R")
	)
	(via
		(at 245.267988 -401.12696)
		(size 0.508)
		(drill 0.254)
		(layers "F.Cu" "B.Cu")
		(net "P12V_MAIN_R")
	)
	(via
		(at 263.07288 -399.60296)
		(size 0.508)
		(drill 0.254)
		(layers "F.Cu" "B.Cu")
		(net "P12V_MAIN_R")
	)
	(via
		(at 253.944628 -402.82368)
		(size 0.508)
		(drill 0.254)
		(layers "F.Cu" "B.Cu")
		(net "P12V_MAIN_R")
	)
	(via
		(at 244.818408 -402.82368)
		(size 0.508)
		(drill 0.254)
		(layers "F.Cu" "B.Cu")
		(net "P12V_MAIN_R")
	)
	(via
		(at 254.706628 -402.82368)
		(size 0.508)
		(drill 0.254)
		(layers "F.Cu" "B.Cu")
		(net "P12V_MAIN_R")
	)
	(via
		(at 245.267988 -399.60296)
		(size 0.508)
		(drill 0.254)
		(layers "F.Cu" "B.Cu")
		(net "P12V_MAIN_R")
	)
	(via
		(at 257.137916 -400.36496)
		(size 0.508)
		(drill 0.254)
		(layers "F.Cu" "B.Cu")
		(net "P12V_MAIN_R")
	)
	(via
		(at 245.267988 -400.36496)
		(size 0.508)
		(drill 0.254)
		(layers "F.Cu" "B.Cu")
		(net "P12V_MAIN_R")
	)
	(via
		(at 243.294408 -402.82368)
		(size 0.508)
		(drill 0.254)
		(layers "F.Cu" "B.Cu")
		(net "P12V_MAIN_R")
	)
	(via
		(at 252.420628 -402.82368)
		(size 0.508)
		(drill 0.254)
		(layers "F.Cu" "B.Cu")
		(net "P12V_MAIN_R")
	)
	(via
		(at 244.056408 -402.82368)
		(size 0.508)
		(drill 0.254)
		(layers "F.Cu" "B.Cu")
		(net "P12V_MAIN_R")
	)
	(via
		(at 269.007844 -400.36496)
		(size 0.508)
		(drill 0.254)
		(layers "F.Cu" "B.Cu")
		(net "P12V_MAIN_R")
	)
	(via
		(at 269.007844 -399.60296)
		(size 0.508)
		(drill 0.254)
		(layers "F.Cu" "B.Cu")
		(net "P12V_MAIN_R")
	)
	(via
		(at 263.07288 -401.12696)
		(size 0.508)
		(drill 0.254)
		(layers "F.Cu" "B.Cu")
		(net "P12V_MAIN_R")
	)
	(via
		(at 268.379448 -402.84654)
		(size 0.508)
		(drill 0.254)
		(layers "F.Cu" "B.Cu")
		(net "P12V_MAIN_R")
	)
	(via
		(at 257.137916 -401.12696)
		(size 0.508)
		(drill 0.254)
		(layers "F.Cu" "B.Cu")
		(net "P12V_MAIN_R")
	)
	(via
		(at 251.202952 -401.12696)
		(size 0.508)
		(drill 0.254)
		(layers "F.Cu" "B.Cu")
		(net "P12V_MAIN_R")
	)
	(via
		(at 251.202952 -400.36496)
		(size 0.508)
		(drill 0.254)
		(layers "F.Cu" "B.Cu")
		(net "P12V_MAIN_R")
	)
	(via
		(at 262.621268 -402.86686)
		(size 0.508)
		(drill 0.254)
		(layers "F.Cu" "B.Cu")
		(net "P12V_MAIN_R")
	)
	(via
		(at 267.617448 -402.84654)
		(size 0.508)
		(drill 0.254)
		(layers "F.Cu" "B.Cu")
		(net "P12V_MAIN_R")
	)
	(via
		(at 273.837908 -403.06244)
		(size 0.762)
		(drill 0.381)
		(layers "F.Cu" "B.Cu")
		(net "P12V_MAIN_R")
	)
	(via
		(at 269.141448 -402.84654)
		(size 0.508)
		(drill 0.254)
		(layers "F.Cu" "B.Cu")
		(net "P12V_MAIN_R")
	)
	(via
		(at 257.137916 -399.60296)
		(size 0.508)
		(drill 0.254)
		(layers "F.Cu" "B.Cu")
		(net "P12V_MAIN_R")
	)
	(segment
		(start 287.71342 -405.79802)
		(end 287.32988 -406.18156)
		(width 0.12954)
		(layer "F.Cu")
		(net "P12V_HSC_T_CRIT_R_N")
	)
	(segment
		(start 292.19652 -406.21712)
		(end 291.11194 -405.13254)
		(width 0.12954)
		(layer "F.Cu")
		(net "P12V_HSC_T_CRIT_R_N")
	)
	(segment
		(start 288.53765 -405.60879)
		(end 288.53765 -405.79802)
		(width 0.12954)
		(layer "F.Cu")
		(net "P12V_HSC_T_CRIT_R_N")
	)
	(segment
		(start 291.11194 -405.13254)
		(end 289.0139 -405.13254)
		(width 0.12954)
		(layer "F.Cu")
		(net "P12V_HSC_T_CRIT_R_N")
	)
	(segment
		(start 170.955716 -120.175528)
		(end 170.555666 -120.575578)
		(width 0.12954)
		(layer "F.Cu")
		(net "P12V_HSC_T_CRIT_R_N")
	)
	(segment
		(start 287.32988 -406.18156)
		(end 287.96234 -406.81402)
		(width 0.12954)
		(layer "F.Cu")
		(net "P12V_HSC_T_CRIT_R_N")
	)
	(segment
		(start 287.96234 -406.81402)
		(end 288.53765 -406.81402)
		(width 0.12954)
		(layer "F.Cu")
		(net "P12V_HSC_T_CRIT_R_N")
	)
	(segment
		(start 289.0139 -405.13254)
		(end 288.53765 -405.60879)
		(width 0.12954)
		(layer "F.Cu")
		(net "P12V_HSC_T_CRIT_R_N")
	)
	(segment
		(start 288.53765 -405.79802)
		(end 287.71342 -405.79802)
		(width 0.12954)
		(layer "F.Cu")
		(net "P12V_HSC_T_CRIT_R_N")
	)
	(segment
		(start 292.19652 -407.05786)
		(end 292.19652 -406.21712)
		(width 0.12954)
		(layer "F.Cu")
		(net "P12V_HSC_T_CRIT_R_N")
	)
	(via
		(at 170.555666 -120.575578)
		(size 0.4572)
		(drill 0.254)
		(layers "F.Cu" "B.Cu")
		(net "P12V_HSC_T_CRIT_R_N")
	)
	(via
		(at 162.59302 -131.53898)
		(size 0.508)
		(drill 0.254)
		(layers "F.Cu" "B.Cu")
		(net "P12V_HSC_T_CRIT_R_N")
	)
	(via
		(at 287.32988 -406.18156)
		(size 0.762)
		(drill 0.381)
		(layers "F.Cu" "B.Cu")
		(net "P12V_HSC_T_CRIT_R_N")
	)
	(via
		(at 292.19652 -407.05786)
		(size 0.508)
		(drill 0.254)
		(layers "F.Cu" "B.Cu")
		(net "P12V_HSC_T_CRIT_R_N")
	)
	(via
		(at 178.49596 -150.88108)
		(size 0.508)
		(drill 0.254)
		(layers "F.Cu" "B.Cu")
		(net "P12V_HSC_T_CRIT_R_N")
	)
	(via
		(at 255.93294 -328.94016)
		(size 0.508)
		(drill 0.254)
		(layers "F.Cu" "B.Cu")
		(net "P12V_HSC_T_CRIT_R_N")
	)
	(via
		(at 268.27226 -132.27304)
		(size 0.508)
		(drill 0.254)
		(layers "F.Cu" "B.Cu")
		(net "P12V_HSC_T_CRIT_R_N")
	)
	(segment
		(start 162.7378 -130.4798)
		(end 163.59378 -129.62382)
		(width 0.12954)
		(layer "B.Cu")
		(net "P12V_HSC_T_CRIT_R_N")
	)
	(segment
		(start 163.59378 -129.62382)
		(end 168.80332 -129.62382)
		(width 0.12954)
		(layer "B.Cu")
		(net "P12V_HSC_T_CRIT_R_N")
	)
	(segment
		(start 162.59302 -131.53898)
		(end 162.59302 -131.067556)
		(width 0.12954)
		(layer "B.Cu")
		(net "P12V_HSC_T_CRIT_R_N")
	)
	(segment
		(start 170.9547 -120.97512)
		(end 170.555666 -120.576086)
		(width 0.12954)
		(layer "B.Cu")
		(net "P12V_HSC_T_CRIT_R_N")
	)
	(segment
		(start 169.14114 -126.690882)
		(end 172.55998 -123.272042)
		(width 0.12954)
		(layer "B.Cu")
		(net "P12V_HSC_T_CRIT_R_N")
	)
	(segment
		(start 172.55998 -121.11736)
		(end 172.41774 -120.97512)
		(width 0.12954)
		(layer "B.Cu")
		(net "P12V_HSC_T_CRIT_R_N")
	)
	(segment
		(start 169.14114 -129.286)
		(end 169.14114 -126.690882)
		(width 0.12954)
		(layer "B.Cu")
		(net "P12V_HSC_T_CRIT_R_N")
	)
	(segment
		(start 172.41774 -120.97512)
		(end 170.9547 -120.97512)
		(width 0.12954)
		(layer "B.Cu")
		(net "P12V_HSC_T_CRIT_R_N")
	)
	(segment
		(start 168.80332 -129.62382)
		(end 169.14114 -129.286)
		(width 0.12954)
		(layer "B.Cu")
		(net "P12V_HSC_T_CRIT_R_N")
	)
	(segment
		(start 172.55998 -123.272042)
		(end 172.55998 -121.11736)
		(width 0.12954)
		(layer "B.Cu")
		(net "P12V_HSC_T_CRIT_R_N")
	)
	(segment
		(start 162.7378 -130.922776)
		(end 162.7378 -130.4798)
		(width 0.12954)
		(layer "B.Cu")
		(net "P12V_HSC_T_CRIT_R_N")
	)
	(segment
		(start 170.555666 -120.576086)
		(end 170.555666 -120.575578)
		(width 0.12954)
		(layer "B.Cu")
		(net "P12V_HSC_T_CRIT_R_N")
	)
	(segment
		(start 162.59302 -131.067556)
		(end 162.7378 -130.922776)
		(width 0.12954)
		(layer "B.Cu")
		(net "P12V_HSC_T_CRIT_R_N")
	)
	(segment
		(start 297.49242 -390.05002)
		(end 298.62272 -391.18032)
		(width 0.127)
		(layer "In2.Cu")
		(net "P12V_HSC_T_CRIT_R_N")
	)
	(segment
		(start 162.59302 -134.347204)
		(end 162.59302 -131.53898)
		(width 0.127)
		(layer "In2.Cu")
		(net "P12V_HSC_T_CRIT_R_N")
	)
	(segment
		(start 292.55466 -407.416)
		(end 292.19652 -407.05786)
		(width 0.127)
		(layer "In2.Cu")
		(net "P12V_HSC_T_CRIT_R_N")
	)
	(segment
		(start 270.46682 -387.25602)
		(end 271.74444 -387.25602)
		(width 0.127)
		(layer "In2.Cu")
		(net "P12V_HSC_T_CRIT_R_N")
	)
	(segment
		(start 296.96156 -384.68808)
		(end 298.52112 -386.24764)
		(width 0.127)
		(layer "In2.Cu")
		(net "P12V_HSC_T_CRIT_R_N")
	)
	(segment
		(start 299.90034 -400.6215)
		(end 299.90034 -403.32406)
		(width 0.127)
		(layer "In2.Cu")
		(net "P12V_HSC_T_CRIT_R_N")
	)
	(segment
		(start 268.84376 -360.446828)
		(end 268.84376 -385.63296)
		(width 0.127)
		(layer "In2.Cu")
		(net "P12V_HSC_T_CRIT_R_N")
	)
	(segment
		(start 254.7366 -330.1365)
		(end 254.7366 -346.339668)
		(width 0.127)
		(layer "In2.Cu")
		(net "P12V_HSC_T_CRIT_R_N")
	)
	(segment
		(start 298.52112 -386.24764)
		(end 298.52112 -387.67512)
		(width 0.127)
		(layer "In2.Cu")
		(net "P12V_HSC_T_CRIT_R_N")
	)
	(segment
		(start 271.74444 -387.25602)
		(end 273.36496 -385.6355)
		(width 0.127)
		(layer "In2.Cu")
		(net "P12V_HSC_T_CRIT_R_N")
	)
	(segment
		(start 280.29662 -384.68808)
		(end 296.96156 -384.68808)
		(width 0.127)
		(layer "In2.Cu")
		(net "P12V_HSC_T_CRIT_R_N")
	)
	(segment
		(start 254.7366 -346.339668)
		(end 268.84376 -360.446828)
		(width 0.127)
		(layer "In2.Cu")
		(net "P12V_HSC_T_CRIT_R_N")
	)
	(segment
		(start 298.62272 -391.18032)
		(end 298.62272 -399.34388)
		(width 0.127)
		(layer "In2.Cu")
		(net "P12V_HSC_T_CRIT_R_N")
	)
	(segment
		(start 297.49242 -388.70382)
		(end 297.49242 -390.05002)
		(width 0.127)
		(layer "In2.Cu")
		(net "P12V_HSC_T_CRIT_R_N")
	)
	(segment
		(start 273.36496 -385.6355)
		(end 279.3492 -385.6355)
		(width 0.127)
		(layer "In2.Cu")
		(net "P12V_HSC_T_CRIT_R_N")
	)
	(segment
		(start 298.52112 -387.67512)
		(end 297.49242 -388.70382)
		(width 0.127)
		(layer "In2.Cu")
		(net "P12V_HSC_T_CRIT_R_N")
	)
	(segment
		(start 295.8084 -407.416)
		(end 292.55466 -407.416)
		(width 0.127)
		(layer "In2.Cu")
		(net "P12V_HSC_T_CRIT_R_N")
	)
	(segment
		(start 279.3492 -385.6355)
		(end 280.29662 -384.68808)
		(width 0.127)
		(layer "In2.Cu")
		(net "P12V_HSC_T_CRIT_R_N")
	)
	(segment
		(start 298.62272 -399.34388)
		(end 299.90034 -400.6215)
		(width 0.127)
		(layer "In2.Cu")
		(net "P12V_HSC_T_CRIT_R_N")
	)
	(segment
		(start 255.93294 -328.94016)
		(end 254.7366 -330.1365)
		(width 0.127)
		(layer "In2.Cu")
		(net "P12V_HSC_T_CRIT_R_N")
	)
	(segment
		(start 299.90034 -403.32406)
		(end 295.8084 -407.416)
		(width 0.127)
		(layer "In2.Cu")
		(net "P12V_HSC_T_CRIT_R_N")
	)
	(segment
		(start 178.49596 -150.250144)
		(end 162.59302 -134.347204)
		(width 0.127)
		(layer "In2.Cu")
		(net "P12V_HSC_T_CRIT_R_N")
	)
	(segment
		(start 268.84376 -385.63296)
		(end 270.46682 -387.25602)
		(width 0.127)
		(layer "In2.Cu")
		(net "P12V_HSC_T_CRIT_R_N")
	)
	(segment
		(start 178.49596 -150.88108)
		(end 178.49596 -150.250144)
		(width 0.127)
		(layer "In2.Cu")
		(net "P12V_HSC_T_CRIT_R_N")
	)
	(segment
		(start 268.27226 -134.436104)
		(end 268.27226 -132.27304)
		(width 0.127)
		(layer "In11.Cu")
		(net "P12V_HSC_T_CRIT_R_N")
	)
	(segment
		(start 252.50648 -150.201884)
		(end 268.27226 -134.436104)
		(width 0.127)
		(layer "In11.Cu")
		(net "P12V_HSC_T_CRIT_R_N")
	)
	(segment
		(start 255.93294 -328.94016)
		(end 255.93294 -323.472556)
		(width 0.127)
		(layer "In11.Cu")
		(net "P12V_HSC_T_CRIT_R_N")
	)
	(segment
		(start 252.50648 -192.850516)
		(end 252.50648 -150.201884)
		(width 0.127)
		(layer "In11.Cu")
		(net "P12V_HSC_T_CRIT_R_N")
	)
	(segment
		(start 253.86284 -321.402456)
		(end 253.86284 -194.206876)
		(width 0.127)
		(layer "In11.Cu")
		(net "P12V_HSC_T_CRIT_R_N")
	)
	(segment
		(start 253.86284 -194.206876)
		(end 252.50648 -192.850516)
		(width 0.127)
		(layer "In11.Cu")
		(net "P12V_HSC_T_CRIT_R_N")
	)
	(segment
		(start 255.93294 -323.472556)
		(end 253.86284 -321.402456)
		(width 0.127)
		(layer "In11.Cu")
		(net "P12V_HSC_T_CRIT_R_N")
	)
	(segment
		(start 267.019024 -134.13994)
		(end 265.065764 -134.13994)
		(width 0.127)
		(layer "In15.Cu")
		(net "P12V_HSC_T_CRIT_R_N")
	)
	(segment
		(start 268.27226 -132.886704)
		(end 267.019024 -134.13994)
		(width 0.127)
		(layer "In15.Cu")
		(net "P12V_HSC_T_CRIT_R_N")
	)
	(segment
		(start 216.252044 -149.606)
		(end 203.884784 -161.97326)
		(width 0.127)
		(layer "In15.Cu")
		(net "P12V_HSC_T_CRIT_R_N")
	)
	(segment
		(start 226.780344 -142.13586)
		(end 219.310204 -149.606)
		(width 0.127)
		(layer "In15.Cu")
		(net "P12V_HSC_T_CRIT_R_N")
	)
	(segment
		(start 253.404624 -137.48258)
		(end 248.751344 -142.13586)
		(width 0.127)
		(layer "In15.Cu")
		(net "P12V_HSC_T_CRIT_R_N")
	)
	(segment
		(start 178.49596 -153.422604)
		(end 178.49596 -150.88108)
		(width 0.127)
		(layer "In15.Cu")
		(net "P12V_HSC_T_CRIT_R_N")
	)
	(segment
		(start 248.751344 -142.13586)
		(end 226.780344 -142.13586)
		(width 0.127)
		(layer "In15.Cu")
		(net "P12V_HSC_T_CRIT_R_N")
	)
	(segment
		(start 265.065764 -134.13994)
		(end 261.723124 -137.48258)
		(width 0.127)
		(layer "In15.Cu")
		(net "P12V_HSC_T_CRIT_R_N")
	)
	(segment
		(start 203.884784 -161.97326)
		(end 187.046616 -161.97326)
		(width 0.127)
		(layer "In15.Cu")
		(net "P12V_HSC_T_CRIT_R_N")
	)
	(segment
		(start 261.723124 -137.48258)
		(end 253.404624 -137.48258)
		(width 0.127)
		(layer "In15.Cu")
		(net "P12V_HSC_T_CRIT_R_N")
	)
	(segment
		(start 268.27226 -132.27304)
		(end 268.27226 -132.886704)
		(width 0.127)
		(layer "In15.Cu")
		(net "P12V_HSC_T_CRIT_R_N")
	)
	(segment
		(start 219.310204 -149.606)
		(end 216.252044 -149.606)
		(width 0.127)
		(layer "In15.Cu")
		(net "P12V_HSC_T_CRIT_R_N")
	)
	(segment
		(start 187.046616 -161.97326)
		(end 178.49596 -153.422604)
		(width 0.127)
		(layer "In15.Cu")
		(net "P12V_HSC_T_CRIT_R_N")
	)
	(segment
		(start 289.33775 -406.81402)
		(end 289.33775 -407.08707)
		(width 0.12954)
		(layer "F.Cu")
		(net "P12V_HSC_T_CRIT_N")
	)
	(segment
		(start 289.33775 -407.08707)
		(end 289.7505 -407.49982)
		(width 0.12954)
		(layer "F.Cu")
		(net "P12V_HSC_T_CRIT_N")
	)
	(segment
		(start 289.7505 -407.49982)
		(end 290.050474 -407.799794)
		(width 0.12954)
		(layer "F.Cu")
		(net "P12V_HSC_T_CRIT_N")
	)
	(segment
		(start 290.050474 -407.799794)
		(end 290.91509 -407.799794)
		(width 0.12954)
		(layer "F.Cu")
		(net "P12V_HSC_T_CRIT_N")
	)
	(via
		(at 289.7505 -407.49982)
		(size 0.508)
		(drill 0.254)
		(layers "F.Cu" "B.Cu")
		(net "P12V_HSC_T_CRIT_N")
	)
	(segment
		(start 296.78884 -409.10002)
		(end 295.615106 -409.10002)
		(width 0.12954)
		(layer "F.Cu")
		(net "P12V_HSC_TEMP_SDA")
	)
	(segment
		(start 297.6753 -408.72156)
		(end 297.04284 -409.35402)
		(width 0.12954)
		(layer "F.Cu")
		(net "P12V_HSC_TEMP_SDA")
	)
	(segment
		(start 297.04284 -409.35402)
		(end 296.78884 -409.10002)
		(width 0.12954)
		(layer "F.Cu")
		(net "P12V_HSC_TEMP_SDA")
	)
	(segment
		(start 297.75531 -408.72156)
		(end 297.6753 -408.72156)
		(width 0.12954)
		(layer "F.Cu")
		(net "P12V_HSC_TEMP_SDA")
	)
	(segment
		(start 297.76547 -408.7114)
		(end 297.75531 -408.72156)
		(width 0.12954)
		(layer "F.Cu")
		(net "P12V_HSC_TEMP_SDA")
	)
	(via
		(at 297.04284 -409.35402)
		(size 0.508)
		(drill 0.254)
		(layers "F.Cu" "B.Cu")
		(net "P12V_HSC_TEMP_SDA")
	)
	(segment
		(start 297.3705 -410.29636)
		(end 297.04284 -410.62402)
		(width 0.12954)
		(layer "F.Cu")
		(net "P12V_HSC_TEMP_SCL")
	)
	(segment
		(start 297.73499 -409.69184)
		(end 297.73499 -409.713176)
		(width 0.12954)
		(layer "F.Cu")
		(net "P12V_HSC_TEMP_SCL")
	)
	(segment
		(start 297.04284 -410.62402)
		(end 296.168826 -409.750006)
		(width 0.12954)
		(layer "F.Cu")
		(net "P12V_HSC_TEMP_SCL")
	)
	(segment
		(start 297.3705 -410.077666)
		(end 297.3705 -410.29636)
		(width 0.12954)
		(layer "F.Cu")
		(net "P12V_HSC_TEMP_SCL")
	)
	(segment
		(start 296.168826 -409.750006)
		(end 295.615106 -409.750006)
		(width 0.12954)
		(layer "F.Cu")
		(net "P12V_HSC_TEMP_SCL")
	)
	(segment
		(start 297.73499 -409.713176)
		(end 297.3705 -410.077666)
		(width 0.12954)
		(layer "F.Cu")
		(net "P12V_HSC_TEMP_SCL")
	)
	(via
		(at 297.04284 -410.62402)
		(size 0.508)
		(drill 0.254)
		(layers "F.Cu" "B.Cu")
		(net "P12V_HSC_TEMP_SCL")
	)
	(segment
		(start 283.94787 -409.24226)
		(end 282.93568 -409.24226)
		(width 0.254)
		(layer "F.Cu")
		(net "P12V_HSC_TEMP_R")
	)
	(segment
		(start 281.329638 -409.26004)
		(end 281.96286 -409.26004)
		(width 0.254)
		(layer "F.Cu")
		(net "P12V_HSC_TEMP_R")
	)
	(segment
		(start 282.30576 -399.14322)
		(end 283.32176 -400.15922)
		(width 0.254)
		(layer "F.Cu")
		(net "P12V_HSC_TEMP_R")
	)
	(segment
		(start 281.96286 -409.26004)
		(end 282.44038 -409.73756)
		(width 0.254)
		(layer "F.Cu")
		(net "P12V_HSC_TEMP_R")
	)
	(segment
		(start 282.30576 -397.92402)
		(end 282.30576 -399.14322)
		(width 0.254)
		(layer "F.Cu")
		(net "P12V_HSC_TEMP_R")
	)
	(segment
		(start 283.32176 -400.15922)
		(end 284.10916 -400.94662)
		(width 0.254)
		(layer "F.Cu")
		(net "P12V_HSC_TEMP_R")
	)
	(segment
		(start 284.23489 -409.52928)
		(end 283.94787 -409.24226)
		(width 0.254)
		(layer "F.Cu")
		(net "P12V_HSC_TEMP_R")
	)
	(segment
		(start 282.93568 -409.24226)
		(end 282.44038 -409.73756)
		(width 0.254)
		(layer "F.Cu")
		(net "P12V_HSC_TEMP_R")
	)
	(segment
		(start 284.10916 -400.94662)
		(end 284.10916 -404.321264)
		(width 0.254)
		(layer "F.Cu")
		(net "P12V_HSC_TEMP_R")
	)
	(segment
		(start 284.10916 -404.321264)
		(end 280.93162 -407.498804)
		(width 0.254)
		(layer "F.Cu")
		(net "P12V_HSC_TEMP_R")
	)
	(segment
		(start 280.93162 -407.498804)
		(end 280.93162 -408.862022)
		(width 0.254)
		(layer "F.Cu")
		(net "P12V_HSC_TEMP_R")
	)
	(segment
		(start 280.93162 -408.862022)
		(end 281.329638 -409.26004)
		(width 0.254)
		(layer "F.Cu")
		(net "P12V_HSC_TEMP_R")
	)
	(via
		(at 282.44038 -409.73756)
		(size 0.762)
		(drill 0.381)
		(layers "F.Cu" "B.Cu")
		(net "P12V_HSC_TEMP_R")
	)
	(segment
		(start 281.33802 -407.667206)
		(end 281.33802 -408.69362)
		(width 0.254)
		(layer "F.Cu")
		(net "P12V_HSC_TEMP_E")
	)
	(segment
		(start 281.33802 -408.69362)
		(end 281.49804 -408.85364)
		(width 0.254)
		(layer "F.Cu")
		(net "P12V_HSC_TEMP_E")
	)
	(segment
		(start 284.51556 -404.489666)
		(end 281.33802 -407.667206)
		(width 0.254)
		(layer "F.Cu")
		(net "P12V_HSC_TEMP_E")
	)
	(segment
		(start 284.22727 -408.53868)
		(end 283.90469 -408.86126)
		(width 0.254)
		(layer "F.Cu")
		(net "P12V_HSC_TEMP_E")
	)
	(segment
		(start 281.9527 -408.85364)
		(end 282.44038 -408.36596)
		(width 0.254)
		(layer "F.Cu")
		(net "P12V_HSC_TEMP_E")
	)
	(segment
		(start 282.93568 -408.86126)
		(end 282.44038 -408.36596)
		(width 0.254)
		(layer "F.Cu")
		(net "P12V_HSC_TEMP_E")
	)
	(segment
		(start 283.90469 -408.86126)
		(end 282.93568 -408.86126)
		(width 0.254)
		(layer "F.Cu")
		(net "P12V_HSC_TEMP_E")
	)
	(segment
		(start 281.49804 -408.85364)
		(end 281.9527 -408.85364)
		(width 0.254)
		(layer "F.Cu")
		(net "P12V_HSC_TEMP_E")
	)
	(segment
		(start 284.51556 -398.10182)
		(end 284.51556 -404.489666)
		(width 0.254)
		(layer "F.Cu")
		(net "P12V_HSC_TEMP_E")
	)
	(segment
		(start 284.33776 -397.92402)
		(end 284.51556 -398.10182)
		(width 0.254)
		(layer "F.Cu")
		(net "P12V_HSC_TEMP_E")
	)
	(via
		(at 282.44038 -408.36596)
		(size 0.762)
		(drill 0.381)
		(layers "F.Cu" "B.Cu")
		(net "P12V_HSC_TEMP_E")
	)
	(segment
		(start 287.83788 -408.02306)
		(end 288.42462 -408.6098)
		(width 0.254)
		(layer "F.Cu")
		(net "P12V_HSC_TEMP_D-")
	)
	(segment
		(start 287.29178 -408.56916)
		(end 287.83788 -408.02306)
		(width 0.254)
		(layer "F.Cu")
		(net "P12V_HSC_TEMP_D-")
	)
	(segment
		(start 285.35503 -408.86634)
		(end 285.02737 -408.53868)
		(width 0.254)
		(layer "F.Cu")
		(net "P12V_HSC_TEMP_D-")
	)
	(segment
		(start 289.18662 -408.1145)
		(end 289.61334 -408.54122)
		(width 0.254)
		(layer "F.Cu")
		(net "P12V_HSC_TEMP_D-")
	)
	(segment
		(start 285.92526 -408.86634)
		(end 285.35503 -408.86634)
		(width 0.254)
		(layer "F.Cu")
		(net "P12V_HSC_TEMP_D-")
	)
	(segment
		(start 286.24276 -407.98242)
		(end 286.24276 -408.54884)
		(width 0.254)
		(layer "F.Cu")
		(net "P12V_HSC_TEMP_D-")
	)
	(segment
		(start 288.42462 -408.6098)
		(end 288.69132 -408.6098)
		(width 0.254)
		(layer "F.Cu")
		(net "P12V_HSC_TEMP_D-")
	)
	(segment
		(start 290.243514 -408.54122)
		(end 290.334954 -408.44978)
		(width 0.254)
		(layer "F.Cu")
		(net "P12V_HSC_TEMP_D-")
	)
	(segment
		(start 286.24276 -408.54884)
		(end 285.92526 -408.86634)
		(width 0.254)
		(layer "F.Cu")
		(net "P12V_HSC_TEMP_D-")
	)
	(segment
		(start 289.61334 -408.54122)
		(end 290.243514 -408.54122)
		(width 0.254)
		(layer "F.Cu")
		(net "P12V_HSC_TEMP_D-")
	)
	(segment
		(start 288.69132 -408.6098)
		(end 289.18662 -408.1145)
		(width 0.254)
		(layer "F.Cu")
		(net "P12V_HSC_TEMP_D-")
	)
	(segment
		(start 290.334954 -408.44978)
		(end 290.91509 -408.44978)
		(width 0.254)
		(layer "F.Cu")
		(net "P12V_HSC_TEMP_D-")
	)
	(segment
		(start 286.8295 -408.56916)
		(end 287.29178 -408.56916)
		(width 0.254)
		(layer "F.Cu")
		(net "P12V_HSC_TEMP_D-")
	)
	(segment
		(start 286.24276 -407.98242)
		(end 286.8295 -408.56916)
		(width 0.254)
		(layer "F.Cu")
		(net "P12V_HSC_TEMP_D-")
	)
	(via
		(at 289.18662 -408.1145)
		(size 0.762)
		(drill 0.381)
		(layers "F.Cu" "B.Cu")
		(net "P12V_HSC_TEMP_D-")
	)
	(via
		(at 286.24276 -407.98242)
		(size 0.762)
		(drill 0.381)
		(layers "F.Cu" "B.Cu")
		(net "P12V_HSC_TEMP_D-")
	)
	(segment
		(start 288.69132 -408.9908)
		(end 289.18662 -409.4861)
		(width 0.254)
		(layer "F.Cu")
		(net "P12V_HSC_TEMP_D+")
	)
	(segment
		(start 289.7505 -408.92222)
		(end 290.164266 -408.92222)
		(width 0.254)
		(layer "F.Cu")
		(net "P12V_HSC_TEMP_D+")
	)
	(segment
		(start 290.164266 -408.92222)
		(end 290.342066 -409.10002)
		(width 0.254)
		(layer "F.Cu")
		(net "P12V_HSC_TEMP_D+")
	)
	(segment
		(start 286.24276 -409.45562)
		(end 286.03448 -409.24734)
		(width 0.254)
		(layer "F.Cu")
		(net "P12V_HSC_TEMP_D+")
	)
	(segment
		(start 286.24276 -409.45562)
		(end 286.74822 -408.95016)
		(width 0.254)
		(layer "F.Cu")
		(net "P12V_HSC_TEMP_D+")
	)
	(segment
		(start 287.29178 -408.95016)
		(end 287.83788 -409.49626)
		(width 0.254)
		(layer "F.Cu")
		(net "P12V_HSC_TEMP_D+")
	)
	(segment
		(start 288.34334 -408.9908)
		(end 288.69132 -408.9908)
		(width 0.254)
		(layer "F.Cu")
		(net "P12V_HSC_TEMP_D+")
	)
	(segment
		(start 285.29153 -409.24734)
		(end 285.03499 -409.50388)
		(width 0.254)
		(layer "F.Cu")
		(net "P12V_HSC_TEMP_D+")
	)
	(segment
		(start 285.03499 -409.50388)
		(end 285.03499 -409.52928)
		(width 0.254)
		(layer "F.Cu")
		(net "P12V_HSC_TEMP_D+")
	)
	(segment
		(start 289.18662 -409.4861)
		(end 289.7505 -408.92222)
		(width 0.254)
		(layer "F.Cu")
		(net "P12V_HSC_TEMP_D+")
	)
	(segment
		(start 287.83788 -409.49626)
		(end 288.34334 -408.9908)
		(width 0.254)
		(layer "F.Cu")
		(net "P12V_HSC_TEMP_D+")
	)
	(segment
		(start 286.74822 -408.95016)
		(end 287.29178 -408.95016)
		(width 0.254)
		(layer "F.Cu")
		(net "P12V_HSC_TEMP_D+")
	)
	(segment
		(start 290.342066 -409.10002)
		(end 290.91509 -409.10002)
		(width 0.254)
		(layer "F.Cu")
		(net "P12V_HSC_TEMP_D+")
	)
	(segment
		(start 286.03448 -409.24734)
		(end 285.29153 -409.24734)
		(width 0.254)
		(layer "F.Cu")
		(net "P12V_HSC_TEMP_D+")
	)
	(via
		(at 289.18662 -409.4861)
		(size 0.762)
		(drill 0.381)
		(layers "F.Cu" "B.Cu")
		(net "P12V_HSC_TEMP_D+")
	)
	(via
		(at 286.24276 -409.45562)
		(size 0.762)
		(drill 0.381)
		(layers "F.Cu" "B.Cu")
		(net "P12V_HSC_TEMP_D+")
	)
	(segment
		(start 299.24756 -406.6794)
		(end 298.56557 -406.6794)
		(width 0.12954)
		(layer "F.Cu")
		(net "P12V_HSC_TEMP_ALERT_R_N")
	)
	(segment
		(start 169.5069 -119.55272)
		(end 169.684192 -119.375428)
		(width 0.12954)
		(layer "F.Cu")
		(net "P12V_HSC_TEMP_ALERT_R_N")
	)
	(segment
		(start 169.684192 -119.375428)
		(end 170.155616 -119.375428)
		(width 0.12954)
		(layer "F.Cu")
		(net "P12V_HSC_TEMP_ALERT_R_N")
	)
	(segment
		(start 298.56557 -407.6954)
		(end 298.56557 -406.6794)
		(width 0.12954)
		(layer "F.Cu")
		(net "P12V_HSC_TEMP_ALERT_R_N")
	)
	(via
		(at 299.24756 -406.6794)
		(size 0.508)
		(drill 0.254)
		(layers "F.Cu" "B.Cu")
		(net "P12V_HSC_TEMP_ALERT_R_N")
	)
	(via
		(at 267.63726 -132.27304)
		(size 0.508)
		(drill 0.254)
		(layers "F.Cu" "B.Cu")
		(net "P12V_HSC_TEMP_ALERT_R_N")
	)
	(via
		(at 255.9304 -329.7555)
		(size 0.508)
		(drill 0.254)
		(layers "F.Cu" "B.Cu")
		(net "P12V_HSC_TEMP_ALERT_R_N")
	)
	(via
		(at 169.5069 -119.55272)
		(size 0.4572)
		(drill 0.254)
		(layers "F.Cu" "B.Cu")
		(net "P12V_HSC_TEMP_ALERT_R_N")
	)
	(via
		(at 163.22802 -131.53898)
		(size 0.508)
		(drill 0.254)
		(layers "F.Cu" "B.Cu")
		(net "P12V_HSC_TEMP_ALERT_R_N")
	)
	(via
		(at 179.13096 -150.88108)
		(size 0.508)
		(drill 0.254)
		(layers "F.Cu" "B.Cu")
		(net "P12V_HSC_TEMP_ALERT_R_N")
	)
	(segment
		(start 169.9387 -119.12092)
		(end 169.5069 -119.55272)
		(width 0.12954)
		(layer "B.Cu")
		(net "P12V_HSC_TEMP_ALERT_R_N")
	)
	(segment
		(start 173.24578 -119.37238)
		(end 171.819824 -119.37238)
		(width 0.12954)
		(layer "B.Cu")
		(net "P12V_HSC_TEMP_ALERT_R_N")
	)
	(segment
		(start 169.00652 -130.11404)
		(end 169.63136 -129.4892)
		(width 0.12954)
		(layer "B.Cu")
		(net "P12V_HSC_TEMP_ALERT_R_N")
	)
	(segment
		(start 169.63136 -127.32512)
		(end 173.355 -123.60148)
		(width 0.12954)
		(layer "B.Cu")
		(net "P12V_HSC_TEMP_ALERT_R_N")
	)
	(segment
		(start 163.22802 -130.683)
		(end 163.79698 -130.11404)
		(width 0.12954)
		(layer "B.Cu")
		(net "P12V_HSC_TEMP_ALERT_R_N")
	)
	(segment
		(start 173.355 -123.60148)
		(end 173.355 -119.4816)
		(width 0.12954)
		(layer "B.Cu")
		(net "P12V_HSC_TEMP_ALERT_R_N")
	)
	(segment
		(start 171.568364 -119.12092)
		(end 169.9387 -119.12092)
		(width 0.12954)
		(layer "B.Cu")
		(net "P12V_HSC_TEMP_ALERT_R_N")
	)
	(segment
		(start 169.63136 -129.4892)
		(end 169.63136 -127.32512)
		(width 0.12954)
		(layer "B.Cu")
		(net "P12V_HSC_TEMP_ALERT_R_N")
	)
	(segment
		(start 173.355 -119.4816)
		(end 173.24578 -119.37238)
		(width 0.12954)
		(layer "B.Cu")
		(net "P12V_HSC_TEMP_ALERT_R_N")
	)
	(segment
		(start 163.79698 -130.11404)
		(end 169.00652 -130.11404)
		(width 0.12954)
		(layer "B.Cu")
		(net "P12V_HSC_TEMP_ALERT_R_N")
	)
	(segment
		(start 171.819824 -119.37238)
		(end 171.568364 -119.12092)
		(width 0.12954)
		(layer "B.Cu")
		(net "P12V_HSC_TEMP_ALERT_R_N")
	)
	(segment
		(start 163.22802 -131.53898)
		(end 163.22802 -130.683)
		(width 0.12954)
		(layer "B.Cu")
		(net "P12V_HSC_TEMP_ALERT_R_N")
	)
	(segment
		(start 299.230288 -391.842752)
		(end 299.65142 -391.42162)
		(width 0.127)
		(layer "In2.Cu")
		(net "P12V_HSC_TEMP_ALERT_R_N")
	)
	(segment
		(start 278.91486 -385.09956)
		(end 271.73682 -385.09956)
		(width 0.127)
		(layer "In2.Cu")
		(net "P12V_HSC_TEMP_ALERT_R_N")
	)
	(segment
		(start 255.31572 -346.040964)
		(end 255.31572 -330.37018)
		(width 0.127)
		(layer "In2.Cu")
		(net "P12V_HSC_TEMP_ALERT_R_N")
	)
	(segment
		(start 302.50384 -406.63876)
		(end 301.80788 -405.9428)
		(width 0.127)
		(layer "In2.Cu")
		(net "P12V_HSC_TEMP_ALERT_R_N")
	)
	(segment
		(start 269.41526 -360.140504)
		(end 255.31572 -346.040964)
		(width 0.127)
		(layer "In2.Cu")
		(net "P12V_HSC_TEMP_ALERT_R_N")
	)
	(segment
		(start 301.87646 -408.72156)
		(end 302.50384 -408.09418)
		(width 0.127)
		(layer "In2.Cu")
		(net "P12V_HSC_TEMP_ALERT_R_N")
	)
	(segment
		(start 299.24756 -406.6794)
		(end 299.24756 -407.894536)
		(width 0.127)
		(layer "In2.Cu")
		(net "P12V_HSC_TEMP_ALERT_R_N")
	)
	(segment
		(start 299.1231 -387.33476)
		(end 299.1231 -386.17144)
		(width 0.127)
		(layer "In2.Cu")
		(net "P12V_HSC_TEMP_ALERT_R_N")
	)
	(segment
		(start 300.074584 -408.72156)
		(end 301.87646 -408.72156)
		(width 0.127)
		(layer "In2.Cu")
		(net "P12V_HSC_TEMP_ALERT_R_N")
	)
	(segment
		(start 163.22802 -134.08406)
		(end 163.22802 -131.53898)
		(width 0.127)
		(layer "In2.Cu")
		(net "P12V_HSC_TEMP_ALERT_R_N")
	)
	(segment
		(start 179.13096 -149.987)
		(end 163.22802 -134.08406)
		(width 0.127)
		(layer "In2.Cu")
		(net "P12V_HSC_TEMP_ALERT_R_N")
	)
	(segment
		(start 299.230288 -399.245328)
		(end 299.230288 -391.842752)
		(width 0.127)
		(layer "In2.Cu")
		(net "P12V_HSC_TEMP_ALERT_R_N")
	)
	(segment
		(start 301.80788 -401.82292)
		(end 299.230288 -399.245328)
		(width 0.127)
		(layer "In2.Cu")
		(net "P12V_HSC_TEMP_ALERT_R_N")
	)
	(segment
		(start 299.65142 -391.42162)
		(end 299.65142 -387.86308)
		(width 0.127)
		(layer "In2.Cu")
		(net "P12V_HSC_TEMP_ALERT_R_N")
	)
	(segment
		(start 299.1231 -386.17144)
		(end 297.16984 -384.21818)
		(width 0.127)
		(layer "In2.Cu")
		(net "P12V_HSC_TEMP_ALERT_R_N")
	)
	(segment
		(start 279.79624 -384.21818)
		(end 278.91486 -385.09956)
		(width 0.127)
		(layer "In2.Cu")
		(net "P12V_HSC_TEMP_ALERT_R_N")
	)
	(segment
		(start 299.24756 -407.894536)
		(end 300.074584 -408.72156)
		(width 0.127)
		(layer "In2.Cu")
		(net "P12V_HSC_TEMP_ALERT_R_N")
	)
	(segment
		(start 271.73682 -385.09956)
		(end 269.41526 -382.778)
		(width 0.127)
		(layer "In2.Cu")
		(net "P12V_HSC_TEMP_ALERT_R_N")
	)
	(segment
		(start 255.31572 -330.37018)
		(end 255.9304 -329.7555)
		(width 0.127)
		(layer "In2.Cu")
		(net "P12V_HSC_TEMP_ALERT_R_N")
	)
	(segment
		(start 297.16984 -384.21818)
		(end 279.79624 -384.21818)
		(width 0.127)
		(layer "In2.Cu")
		(net "P12V_HSC_TEMP_ALERT_R_N")
	)
	(segment
		(start 299.65142 -387.86308)
		(end 299.1231 -387.33476)
		(width 0.127)
		(layer "In2.Cu")
		(net "P12V_HSC_TEMP_ALERT_R_N")
	)
	(segment
		(start 302.50384 -408.09418)
		(end 302.50384 -406.63876)
		(width 0.127)
		(layer "In2.Cu")
		(net "P12V_HSC_TEMP_ALERT_R_N")
	)
	(segment
		(start 269.41526 -382.778)
		(end 269.41526 -360.140504)
		(width 0.127)
		(layer "In2.Cu")
		(net "P12V_HSC_TEMP_ALERT_R_N")
	)
	(segment
		(start 179.13096 -150.88108)
		(end 179.13096 -149.987)
		(width 0.127)
		(layer "In2.Cu")
		(net "P12V_HSC_TEMP_ALERT_R_N")
	)
	(segment
		(start 301.80788 -405.9428)
		(end 301.80788 -401.82292)
		(width 0.127)
		(layer "In2.Cu")
		(net "P12V_HSC_TEMP_ALERT_R_N")
	)
	(segment
		(start 251.87148 -149.93874)
		(end 267.63726 -134.17296)
		(width 0.127)
		(layer "In11.Cu")
		(net "P12V_HSC_TEMP_ALERT_R_N")
	)
	(segment
		(start 255.29794 -329.12304)
		(end 255.29794 -323.7357)
		(width 0.127)
		(layer "In11.Cu")
		(net "P12V_HSC_TEMP_ALERT_R_N")
	)
	(segment
		(start 255.9304 -329.7555)
		(end 255.29794 -329.12304)
		(width 0.127)
		(layer "In11.Cu")
		(net "P12V_HSC_TEMP_ALERT_R_N")
	)
	(segment
		(start 251.87148 -193.11366)
		(end 251.87148 -149.93874)
		(width 0.127)
		(layer "In11.Cu")
		(net "P12V_HSC_TEMP_ALERT_R_N")
	)
	(segment
		(start 253.31928 -321.75704)
		(end 253.31928 -194.56146)
		(width 0.127)
		(layer "In11.Cu")
		(net "P12V_HSC_TEMP_ALERT_R_N")
	)
	(segment
		(start 255.29794 -323.7357)
		(end 253.31928 -321.75704)
		(width 0.127)
		(layer "In11.Cu")
		(net "P12V_HSC_TEMP_ALERT_R_N")
	)
	(segment
		(start 253.31928 -194.56146)
		(end 251.87148 -193.11366)
		(width 0.127)
		(layer "In11.Cu")
		(net "P12V_HSC_TEMP_ALERT_R_N")
	)
	(segment
		(start 267.63726 -134.17296)
		(end 267.63726 -132.27304)
		(width 0.127)
		(layer "In11.Cu")
		(net "P12V_HSC_TEMP_ALERT_R_N")
	)
	(segment
		(start 264.80262 -133.50494)
		(end 261.45998 -136.84758)
		(width 0.127)
		(layer "In15.Cu")
		(net "P12V_HSC_TEMP_ALERT_R_N")
	)
	(segment
		(start 266.75588 -133.50494)
		(end 264.80262 -133.50494)
		(width 0.127)
		(layer "In15.Cu")
		(net "P12V_HSC_TEMP_ALERT_R_N")
	)
	(segment
		(start 267.63726 -132.62356)
		(end 266.75588 -133.50494)
		(width 0.127)
		(layer "In15.Cu")
		(net "P12V_HSC_TEMP_ALERT_R_N")
	)
	(segment
		(start 261.45998 -136.84758)
		(end 253.14148 -136.84758)
		(width 0.127)
		(layer "In15.Cu")
		(net "P12V_HSC_TEMP_ALERT_R_N")
	)
	(segment
		(start 179.13096 -153.15946)
		(end 179.13096 -150.88108)
		(width 0.127)
		(layer "In15.Cu")
		(net "P12V_HSC_TEMP_ALERT_R_N")
	)
	(segment
		(start 267.63726 -132.27304)
		(end 267.63726 -132.62356)
		(width 0.127)
		(layer "In15.Cu")
		(net "P12V_HSC_TEMP_ALERT_R_N")
	)
	(segment
		(start 219.04706 -148.971)
		(end 215.9889 -148.971)
		(width 0.127)
		(layer "In15.Cu")
		(net "P12V_HSC_TEMP_ALERT_R_N")
	)
	(segment
		(start 203.62164 -161.33826)
		(end 187.30976 -161.33826)
		(width 0.127)
		(layer "In15.Cu")
		(net "P12V_HSC_TEMP_ALERT_R_N")
	)
	(segment
		(start 253.14148 -136.84758)
		(end 248.4882 -141.50086)
		(width 0.127)
		(layer "In15.Cu")
		(net "P12V_HSC_TEMP_ALERT_R_N")
	)
	(segment
		(start 248.4882 -141.50086)
		(end 226.5172 -141.50086)
		(width 0.127)
		(layer "In15.Cu")
		(net "P12V_HSC_TEMP_ALERT_R_N")
	)
	(segment
		(start 187.30976 -161.33826)
		(end 179.13096 -153.15946)
		(width 0.127)
		(layer "In15.Cu")
		(net "P12V_HSC_TEMP_ALERT_R_N")
	)
	(segment
		(start 215.9889 -148.971)
		(end 203.62164 -161.33826)
		(width 0.127)
		(layer "In15.Cu")
		(net "P12V_HSC_TEMP_ALERT_R_N")
	)
	(segment
		(start 226.5172 -141.50086)
		(end 219.04706 -148.971)
		(width 0.127)
		(layer "In15.Cu")
		(net "P12V_HSC_TEMP_ALERT_R_N")
	)
	(segment
		(start 296.67708 -408.44978)
		(end 295.615106 -408.44978)
		(width 0.12954)
		(layer "F.Cu")
		(net "P12V_HSC_TEMP_ALERT_N")
	)
	(segment
		(start 297.04284 -408.08402)
		(end 296.67708 -408.44978)
		(width 0.12954)
		(layer "F.Cu")
		(net "P12V_HSC_TEMP_ALERT_N")
	)
	(segment
		(start 297.76547 -407.6954)
		(end 297.75531 -407.70556)
		(width 0.12954)
		(layer "F.Cu")
		(net "P12V_HSC_TEMP_ALERT_N")
	)
	(segment
		(start 297.75531 -407.70556)
		(end 297.4213 -407.70556)
		(width 0.12954)
		(layer "F.Cu")
		(net "P12V_HSC_TEMP_ALERT_N")
	)
	(segment
		(start 297.4213 -407.70556)
		(end 297.04284 -408.08402)
		(width 0.12954)
		(layer "F.Cu")
		(net "P12V_HSC_TEMP_ALERT_N")
	)
	(via
		(at 297.04284 -408.08402)
		(size 0.508)
		(drill 0.254)
		(layers "F.Cu" "B.Cu")
		(net "P12V_HSC_TEMP_ALERT_N")
	)
	(segment
		(start 260.806692 -408.192732)
		(end 260.806692 -407.797)
		(width 0.254)
		(layer "F.Cu")
		(net "P12V_HSC_SENSE2_R4_P")
	)
	(segment
		(start 260.806692 -407.797)
		(end 260.425692 -407.416)
		(width 0.254)
		(layer "F.Cu")
		(net "P12V_HSC_SENSE2_R4_P")
	)
	(via
		(at 260.425692 -407.416)
		(size 0.508)
		(drill 0.254)
		(layers "F.Cu" "B.Cu")
		(net "P12V_HSC_SENSE2_R4_P")
	)
	(via
		(at 293.417498 -402.015452)
		(size 0.508)
		(drill 0.254)
		(layers "F.Cu" "B.Cu")
		(net "P12V_HSC_SENSE2_R4_P")
	)
	(segment
		(start 293.417498 -401.526502)
		(end 293.417498 -402.015452)
		(width 0.254)
		(layer "B.Cu")
		(net "P12V_HSC_SENSE2_R4_P")
	)
	(segment
		(start 293.417498 -402.504402)
		(end 293.417498 -402.015452)
		(width 0.254)
		(layer "B.Cu")
		(net "P12V_HSC_SENSE2_R4_P")
	)
	(segment
		(start 293.544498 -401.399502)
		(end 293.417498 -401.526502)
		(width 0.254)
		(layer "B.Cu")
		(net "P12V_HSC_SENSE2_R4_P")
	)
	(segment
		(start 293.544498 -402.631402)
		(end 293.417498 -402.504402)
		(width 0.254)
		(layer "B.Cu")
		(net "P12V_HSC_SENSE2_R4_P")
	)
	(segment
		(start 291.338 -398.87398)
		(end 291.99078 -399.52676)
		(width 0.254)
		(layer "In13.Cu")
		(net "P12V_HSC_SENSE2_R4_P")
	)
	(segment
		(start 260.616192 -407.2255)
		(end 260.616192 -406.606756)
		(width 0.254)
		(layer "In13.Cu")
		(net "P12V_HSC_SENSE2_R4_P")
	)
	(segment
		(start 291.99078 -399.52676)
		(end 291.99078 -400.22018)
		(width 0.254)
		(layer "In13.Cu")
		(net "P12V_HSC_SENSE2_R4_P")
	)
	(segment
		(start 260.616192 -406.606756)
		(end 261.257288 -405.96566)
		(width 0.254)
		(layer "In13.Cu")
		(net "P12V_HSC_SENSE2_R4_P")
	)
	(segment
		(start 261.257288 -405.96566)
		(end 280.865072 -405.96566)
		(width 0.254)
		(layer "In13.Cu")
		(net "P12V_HSC_SENSE2_R4_P")
	)
	(segment
		(start 293.226998 -401.456398)
		(end 293.226998 -401.824952)
		(width 0.254)
		(layer "In13.Cu")
		(net "P12V_HSC_SENSE2_R4_P")
	)
	(segment
		(start 260.425692 -407.416)
		(end 260.616192 -407.2255)
		(width 0.254)
		(layer "In13.Cu")
		(net "P12V_HSC_SENSE2_R4_P")
	)
	(segment
		(start 287.956752 -398.87398)
		(end 291.338 -398.87398)
		(width 0.254)
		(layer "In13.Cu")
		(net "P12V_HSC_SENSE2_R4_P")
	)
	(segment
		(start 291.99078 -400.22018)
		(end 293.226998 -401.456398)
		(width 0.254)
		(layer "In13.Cu")
		(net "P12V_HSC_SENSE2_R4_P")
	)
	(segment
		(start 293.226998 -401.824952)
		(end 293.417498 -402.015452)
		(width 0.254)
		(layer "In13.Cu")
		(net "P12V_HSC_SENSE2_R4_P")
	)
	(segment
		(start 280.865072 -405.96566)
		(end 287.956752 -398.87398)
		(width 0.254)
		(layer "In13.Cu")
		(net "P12V_HSC_SENSE2_R4_P")
	)
	(segment
		(start 260.806692 -407.035)
		(end 261.187692 -407.416)
		(width 0.254)
		(layer "F.Cu")
		(net "P12V_HSC_SENSE2_R4_N")
	)
	(segment
		(start 260.806692 -406.639268)
		(end 260.806692 -407.035)
		(width 0.254)
		(layer "F.Cu")
		(net "P12V_HSC_SENSE2_R4_N")
	)
	(via
		(at 292.655498 -402.015452)
		(size 0.762)
		(drill 0.254)
		(layers "F.Cu" "B.Cu")
		(net "P12V_HSC_SENSE2_R4_N")
	)
	(via
		(at 261.187692 -407.416)
		(size 0.508)
		(drill 0.254)
		(layers "F.Cu" "B.Cu")
		(net "P12V_HSC_SENSE2_R4_N")
	)
	(segment
		(start 292.528498 -402.631402)
		(end 292.655498 -402.504402)
		(width 0.254)
		(layer "B.Cu")
		(net "P12V_HSC_SENSE2_R4_N")
	)
	(segment
		(start 292.655498 -401.526502)
		(end 292.655498 -402.015452)
		(width 0.254)
		(layer "B.Cu")
		(net "P12V_HSC_SENSE2_R4_N")
	)
	(segment
		(start 292.655498 -402.504402)
		(end 292.655498 -402.015452)
		(width 0.254)
		(layer "B.Cu")
		(net "P12V_HSC_SENSE2_R4_N")
	)
	(segment
		(start 292.528498 -401.399502)
		(end 292.655498 -401.526502)
		(width 0.254)
		(layer "B.Cu")
		(net "P12V_HSC_SENSE2_R4_N")
	)
	(segment
		(start 260.997192 -406.764744)
		(end 261.415276 -406.34666)
		(width 0.254)
		(layer "In13.Cu")
		(net "P12V_HSC_SENSE2_R4_N")
	)
	(segment
		(start 292.845998 -401.824952)
		(end 292.655498 -402.015452)
		(width 0.254)
		(layer "In13.Cu")
		(net "P12V_HSC_SENSE2_R4_N")
	)
	(segment
		(start 288.11474 -399.25498)
		(end 291.180012 -399.25498)
		(width 0.254)
		(layer "In13.Cu")
		(net "P12V_HSC_SENSE2_R4_N")
	)
	(segment
		(start 281.02306 -406.34666)
		(end 288.11474 -399.25498)
		(width 0.254)
		(layer "In13.Cu")
		(net "P12V_HSC_SENSE2_R4_N")
	)
	(segment
		(start 291.180012 -399.25498)
		(end 291.60978 -399.684748)
		(width 0.254)
		(layer "In13.Cu")
		(net "P12V_HSC_SENSE2_R4_N")
	)
	(segment
		(start 291.60978 -399.684748)
		(end 291.60978 -400.378168)
		(width 0.254)
		(layer "In13.Cu")
		(net "P12V_HSC_SENSE2_R4_N")
	)
	(segment
		(start 260.997192 -407.2255)
		(end 260.997192 -406.764744)
		(width 0.254)
		(layer "In13.Cu")
		(net "P12V_HSC_SENSE2_R4_N")
	)
	(segment
		(start 292.845998 -401.614386)
		(end 292.845998 -401.824952)
		(width 0.254)
		(layer "In13.Cu")
		(net "P12V_HSC_SENSE2_R4_N")
	)
	(segment
		(start 261.415276 -406.34666)
		(end 281.02306 -406.34666)
		(width 0.254)
		(layer "In13.Cu")
		(net "P12V_HSC_SENSE2_R4_N")
	)
	(segment
		(start 291.60978 -400.378168)
		(end 292.845998 -401.614386)
		(width 0.254)
		(layer "In13.Cu")
		(net "P12V_HSC_SENSE2_R4_N")
	)
	(segment
		(start 261.187692 -407.416)
		(end 260.997192 -407.2255)
		(width 0.254)
		(layer "In13.Cu")
		(net "P12V_HSC_SENSE2_R4_N")
	)
	(segment
		(start 252.780292 -408.192732)
		(end 252.780292 -407.797)
		(width 0.254)
		(layer "F.Cu")
		(net "P12V_HSC_SENSE2_R3_P")
	)
	(segment
		(start 252.780292 -407.797)
		(end 252.399292 -407.416)
		(width 0.254)
		(layer "F.Cu")
		(net "P12V_HSC_SENSE2_R3_P")
	)
	(via
		(at 252.399292 -407.416)
		(size 0.508)
		(drill 0.254)
		(layers "F.Cu" "B.Cu")
		(net "P12V_HSC_SENSE2_R3_P")
	)
	(via
		(at 295.80713 -402.015452)
		(size 0.508)
		(drill 0.254)
		(layers "F.Cu" "B.Cu")
		(net "P12V_HSC_SENSE2_R3_P")
	)
	(segment
		(start 295.93413 -401.399502)
		(end 295.80713 -401.526502)
		(width 0.254)
		(layer "B.Cu")
		(net "P12V_HSC_SENSE2_R3_P")
	)
	(segment
		(start 295.93413 -402.631402)
		(end 295.80713 -402.504402)
		(width 0.254)
		(layer "B.Cu")
		(net "P12V_HSC_SENSE2_R3_P")
	)
	(segment
		(start 295.80713 -401.526502)
		(end 295.80713 -402.015452)
		(width 0.254)
		(layer "B.Cu")
		(net "P12V_HSC_SENSE2_R3_P")
	)
	(segment
		(start 295.80713 -402.504402)
		(end 295.80713 -402.015452)
		(width 0.254)
		(layer "B.Cu")
		(net "P12V_HSC_SENSE2_R3_P")
	)
	(segment
		(start 254.006096 -404.821644)
		(end 280.390854 -404.821644)
		(width 0.254)
		(layer "In13.Cu")
		(net "P12V_HSC_SENSE2_R3_P")
	)
	(segment
		(start 294.44442 -398.85112)
		(end 294.44442 -400.18462)
		(width 0.254)
		(layer "In13.Cu")
		(net "P12V_HSC_SENSE2_R3_P")
	)
	(segment
		(start 287.482534 -397.729964)
		(end 293.323264 -397.729964)
		(width 0.254)
		(layer "In13.Cu")
		(net "P12V_HSC_SENSE2_R3_P")
	)
	(segment
		(start 252.399292 -407.416)
		(end 252.589792 -407.2255)
		(width 0.254)
		(layer "In13.Cu")
		(net "P12V_HSC_SENSE2_R3_P")
	)
	(segment
		(start 293.323264 -397.729964)
		(end 294.44442 -398.85112)
		(width 0.254)
		(layer "In13.Cu")
		(net "P12V_HSC_SENSE2_R3_P")
	)
	(segment
		(start 295.61663 -401.824952)
		(end 295.80713 -402.015452)
		(width 0.254)
		(layer "In13.Cu")
		(net "P12V_HSC_SENSE2_R3_P")
	)
	(segment
		(start 252.589792 -407.2255)
		(end 252.589792 -406.237948)
		(width 0.254)
		(layer "In13.Cu")
		(net "P12V_HSC_SENSE2_R3_P")
	)
	(segment
		(start 280.390854 -404.821644)
		(end 287.482534 -397.729964)
		(width 0.254)
		(layer "In13.Cu")
		(net "P12V_HSC_SENSE2_R3_P")
	)
	(segment
		(start 252.589792 -406.237948)
		(end 254.006096 -404.821644)
		(width 0.254)
		(layer "In13.Cu")
		(net "P12V_HSC_SENSE2_R3_P")
	)
	(segment
		(start 294.44442 -400.18462)
		(end 295.61663 -401.35683)
		(width 0.254)
		(layer "In13.Cu")
		(net "P12V_HSC_SENSE2_R3_P")
	)
	(segment
		(start 295.61663 -401.35683)
		(end 295.61663 -401.824952)
		(width 0.254)
		(layer "In13.Cu")
		(net "P12V_HSC_SENSE2_R3_P")
	)
	(segment
		(start 252.780292 -406.639268)
		(end 252.780292 -407.035)
		(width 0.254)
		(layer "F.Cu")
		(net "P12V_HSC_SENSE2_R3_N")
	)
	(segment
		(start 252.780292 -407.035)
		(end 253.161292 -407.416)
		(width 0.254)
		(layer "F.Cu")
		(net "P12V_HSC_SENSE2_R3_N")
	)
	(via
		(at 253.161292 -407.416)
		(size 0.508)
		(drill 0.254)
		(layers "F.Cu" "B.Cu")
		(net "P12V_HSC_SENSE2_R3_N")
	)
	(via
		(at 295.04513 -402.015452)
		(size 0.762)
		(drill 0.254)
		(layers "F.Cu" "B.Cu")
		(net "P12V_HSC_SENSE2_R3_N")
	)
	(segment
		(start 295.04513 -401.526502)
		(end 295.04513 -402.015452)
		(width 0.254)
		(layer "B.Cu")
		(net "P12V_HSC_SENSE2_R3_N")
	)
	(segment
		(start 295.04513 -402.504402)
		(end 295.04513 -402.015452)
		(width 0.254)
		(layer "B.Cu")
		(net "P12V_HSC_SENSE2_R3_N")
	)
	(segment
		(start 294.91813 -401.399502)
		(end 295.04513 -401.526502)
		(width 0.254)
		(layer "B.Cu")
		(net "P12V_HSC_SENSE2_R3_N")
	)
	(segment
		(start 294.91813 -402.631402)
		(end 295.04513 -402.504402)
		(width 0.254)
		(layer "B.Cu")
		(net "P12V_HSC_SENSE2_R3_N")
	)
	(segment
		(start 280.548842 -405.202644)
		(end 287.640522 -398.110964)
		(width 0.254)
		(layer "In13.Cu")
		(net "P12V_HSC_SENSE2_R3_N")
	)
	(segment
		(start 287.640522 -398.110964)
		(end 293.165276 -398.110964)
		(width 0.254)
		(layer "In13.Cu")
		(net "P12V_HSC_SENSE2_R3_N")
	)
	(segment
		(start 252.970792 -407.2255)
		(end 252.970792 -406.395936)
		(width 0.254)
		(layer "In13.Cu")
		(net "P12V_HSC_SENSE2_R3_N")
	)
	(segment
		(start 294.06342 -399.009108)
		(end 294.06342 -400.342608)
		(width 0.254)
		(layer "In13.Cu")
		(net "P12V_HSC_SENSE2_R3_N")
	)
	(segment
		(start 295.23563 -401.824952)
		(end 295.04513 -402.015452)
		(width 0.254)
		(layer "In13.Cu")
		(net "P12V_HSC_SENSE2_R3_N")
	)
	(segment
		(start 253.161292 -407.416)
		(end 252.970792 -407.2255)
		(width 0.254)
		(layer "In13.Cu")
		(net "P12V_HSC_SENSE2_R3_N")
	)
	(segment
		(start 252.970792 -406.395936)
		(end 254.164084 -405.202644)
		(width 0.254)
		(layer "In13.Cu")
		(net "P12V_HSC_SENSE2_R3_N")
	)
	(segment
		(start 254.164084 -405.202644)
		(end 280.548842 -405.202644)
		(width 0.254)
		(layer "In13.Cu")
		(net "P12V_HSC_SENSE2_R3_N")
	)
	(segment
		(start 295.23563 -401.514818)
		(end 295.23563 -401.824952)
		(width 0.254)
		(layer "In13.Cu")
		(net "P12V_HSC_SENSE2_R3_N")
	)
	(segment
		(start 294.06342 -400.342608)
		(end 295.23563 -401.514818)
		(width 0.254)
		(layer "In13.Cu")
		(net "P12V_HSC_SENSE2_R3_N")
	)
	(segment
		(start 293.165276 -398.110964)
		(end 294.06342 -399.009108)
		(width 0.254)
		(layer "In13.Cu")
		(net "P12V_HSC_SENSE2_R3_N")
	)
	(segment
		(start 268.833092 -408.192732)
		(end 268.833092 -407.797)
		(width 0.254)
		(layer "F.Cu")
		(net "P12V_HSC_SENSE2_R2_P")
	)
	(segment
		(start 268.833092 -407.797)
		(end 268.452092 -407.416)
		(width 0.254)
		(layer "F.Cu")
		(net "P12V_HSC_SENSE2_R2_P")
	)
	(via
		(at 290.877498 -402.015452)
		(size 0.508)
		(drill 0.254)
		(layers "F.Cu" "B.Cu")
		(net "P12V_HSC_SENSE2_R2_P")
	)
	(via
		(at 268.452092 -407.416)
		(size 0.508)
		(drill 0.254)
		(layers "F.Cu" "B.Cu")
		(net "P12V_HSC_SENSE2_R2_P")
	)
	(segment
		(start 290.877498 -401.526502)
		(end 290.877498 -402.015452)
		(width 0.254)
		(layer "B.Cu")
		(net "P12V_HSC_SENSE2_R2_P")
	)
	(segment
		(start 291.004498 -401.399502)
		(end 290.877498 -401.526502)
		(width 0.254)
		(layer "B.Cu")
		(net "P12V_HSC_SENSE2_R2_P")
	)
	(segment
		(start 291.004498 -402.631402)
		(end 290.877498 -402.504402)
		(width 0.254)
		(layer "B.Cu")
		(net "P12V_HSC_SENSE2_R2_P")
	)
	(segment
		(start 290.877498 -402.504402)
		(end 290.877498 -402.015452)
		(width 0.254)
		(layer "B.Cu")
		(net "P12V_HSC_SENSE2_R2_P")
	)
	(segment
		(start 268.642592 -407.2255)
		(end 268.452092 -407.416)
		(width 0.254)
		(layer "In4.Cu")
		(net "P12V_HSC_SENSE2_R2_P")
	)
	(segment
		(start 268.642592 -405.990806)
		(end 268.642592 -407.2255)
		(width 0.254)
		(layer "In4.Cu")
		(net "P12V_HSC_SENSE2_R2_P")
	)
	(segment
		(start 275.027898 -399.6055)
		(end 268.642592 -405.990806)
		(width 0.254)
		(layer "In4.Cu")
		(net "P12V_HSC_SENSE2_R2_P")
	)
	(segment
		(start 290.680394 -401.818348)
		(end 290.680394 -401.406614)
		(width 0.254)
		(layer "In4.Cu")
		(net "P12V_HSC_SENSE2_R2_P")
	)
	(segment
		(start 290.680394 -401.406614)
		(end 288.87928 -399.6055)
		(width 0.254)
		(layer "In4.Cu")
		(net "P12V_HSC_SENSE2_R2_P")
	)
	(segment
		(start 288.87928 -399.6055)
		(end 275.027898 -399.6055)
		(width 0.254)
		(layer "In4.Cu")
		(net "P12V_HSC_SENSE2_R2_P")
	)
	(segment
		(start 290.877498 -402.015452)
		(end 290.680394 -401.818348)
		(width 0.254)
		(layer "In4.Cu")
		(net "P12V_HSC_SENSE2_R2_P")
	)
	(segment
		(start 268.833092 -407.035)
		(end 269.214092 -407.416)
		(width 0.254)
		(layer "F.Cu")
		(net "P12V_HSC_SENSE2_R2_N")
	)
	(segment
		(start 268.833092 -406.639268)
		(end 268.833092 -407.035)
		(width 0.254)
		(layer "F.Cu")
		(net "P12V_HSC_SENSE2_R2_N")
	)
	(via
		(at 290.115498 -402.015452)
		(size 0.762)
		(drill 0.254)
		(layers "F.Cu" "B.Cu")
		(net "P12V_HSC_SENSE2_R2_N")
	)
	(via
		(at 269.214092 -407.416)
		(size 0.508)
		(drill 0.254)
		(layers "F.Cu" "B.Cu")
		(net "P12V_HSC_SENSE2_R2_N")
	)
	(segment
		(start 289.988498 -402.631402)
		(end 290.115498 -402.504402)
		(width 0.254)
		(layer "B.Cu")
		(net "P12V_HSC_SENSE2_R2_N")
	)
	(segment
		(start 290.115498 -401.526502)
		(end 290.115498 -402.015452)
		(width 0.254)
		(layer "B.Cu")
		(net "P12V_HSC_SENSE2_R2_N")
	)
	(segment
		(start 289.988498 -401.399502)
		(end 290.115498 -401.526502)
		(width 0.254)
		(layer "B.Cu")
		(net "P12V_HSC_SENSE2_R2_N")
	)
	(segment
		(start 290.115498 -402.504402)
		(end 290.115498 -402.015452)
		(width 0.254)
		(layer "B.Cu")
		(net "P12V_HSC_SENSE2_R2_N")
	)
	(segment
		(start 269.023592 -407.2255)
		(end 269.023592 -406.148794)
		(width 0.254)
		(layer "In4.Cu")
		(net "P12V_HSC_SENSE2_R2_N")
	)
	(segment
		(start 269.023592 -406.148794)
		(end 275.185886 -399.9865)
		(width 0.254)
		(layer "In4.Cu")
		(net "P12V_HSC_SENSE2_R2_N")
	)
	(segment
		(start 290.299394 -401.564602)
		(end 290.299394 -401.831556)
		(width 0.254)
		(layer "In4.Cu")
		(net "P12V_HSC_SENSE2_R2_N")
	)
	(segment
		(start 288.721292 -399.9865)
		(end 290.299394 -401.564602)
		(width 0.254)
		(layer "In4.Cu")
		(net "P12V_HSC_SENSE2_R2_N")
	)
	(segment
		(start 269.214092 -407.416)
		(end 269.023592 -407.2255)
		(width 0.254)
		(layer "In4.Cu")
		(net "P12V_HSC_SENSE2_R2_N")
	)
	(segment
		(start 275.185886 -399.9865)
		(end 288.721292 -399.9865)
		(width 0.254)
		(layer "In4.Cu")
		(net "P12V_HSC_SENSE2_R2_N")
	)
	(segment
		(start 290.299394 -401.831556)
		(end 290.115498 -402.015452)
		(width 0.254)
		(layer "In4.Cu")
		(net "P12V_HSC_SENSE2_R2_N")
	)
	(segment
		(start 244.750844 -407.792936)
		(end 244.369844 -407.411936)
		(width 0.254)
		(layer "F.Cu")
		(net "P12V_HSC_SENSE2_R1_P")
	)
	(segment
		(start 244.750844 -408.188668)
		(end 244.750844 -407.792936)
		(width 0.254)
		(layer "F.Cu")
		(net "P12V_HSC_SENSE2_R1_P")
	)
	(via
		(at 244.369844 -407.411936)
		(size 0.508)
		(drill 0.254)
		(layers "F.Cu" "B.Cu")
		(net "P12V_HSC_SENSE2_R1_P")
	)
	(via
		(at 298.34713 -402.015452)
		(size 0.508)
		(drill 0.254)
		(layers "F.Cu" "B.Cu")
		(net "P12V_HSC_SENSE2_R1_P")
	)
	(segment
		(start 298.47413 -401.399502)
		(end 298.34713 -401.526502)
		(width 0.254)
		(layer "B.Cu")
		(net "P12V_HSC_SENSE2_R1_P")
	)
	(segment
		(start 298.34713 -401.526502)
		(end 298.34713 -402.015452)
		(width 0.254)
		(layer "B.Cu")
		(net "P12V_HSC_SENSE2_R1_P")
	)
	(segment
		(start 298.34713 -402.504402)
		(end 298.34713 -402.015452)
		(width 0.254)
		(layer "B.Cu")
		(net "P12V_HSC_SENSE2_R1_P")
	)
	(segment
		(start 298.47413 -402.631402)
		(end 298.34713 -402.504402)
		(width 0.254)
		(layer "B.Cu")
		(net "P12V_HSC_SENSE2_R1_P")
	)
	(segment
		(start 244.369844 -407.411936)
		(end 244.560344 -407.221436)
		(width 0.254)
		(layer "In13.Cu")
		(net "P12V_HSC_SENSE2_R1_P")
	)
	(segment
		(start 294.80256 -396.4178)
		(end 296.88028 -398.49552)
		(width 0.254)
		(layer "In13.Cu")
		(net "P12V_HSC_SENSE2_R1_P")
	)
	(segment
		(start 244.560344 -407.221436)
		(end 244.560344 -406.357836)
		(width 0.254)
		(layer "In13.Cu")
		(net "P12V_HSC_SENSE2_R1_P")
	)
	(segment
		(start 296.88028 -398.49552)
		(end 296.88028 -400.1389)
		(width 0.254)
		(layer "In13.Cu")
		(net "P12V_HSC_SENSE2_R1_P")
	)
	(segment
		(start 296.88028 -400.1389)
		(end 298.15663 -401.41525)
		(width 0.254)
		(layer "In13.Cu")
		(net "P12V_HSC_SENSE2_R1_P")
	)
	(segment
		(start 244.560344 -406.357836)
		(end 247.4087 -403.50948)
		(width 0.254)
		(layer "In13.Cu")
		(net "P12V_HSC_SENSE2_R1_P")
	)
	(segment
		(start 279.84704 -403.50948)
		(end 286.93872 -396.4178)
		(width 0.254)
		(layer "In13.Cu")
		(net "P12V_HSC_SENSE2_R1_P")
	)
	(segment
		(start 286.93872 -396.4178)
		(end 294.80256 -396.4178)
		(width 0.254)
		(layer "In13.Cu")
		(net "P12V_HSC_SENSE2_R1_P")
	)
	(segment
		(start 247.4087 -403.50948)
		(end 279.84704 -403.50948)
		(width 0.254)
		(layer "In13.Cu")
		(net "P12V_HSC_SENSE2_R1_P")
	)
	(segment
		(start 298.15663 -401.824952)
		(end 298.34713 -402.015452)
		(width 0.254)
		(layer "In13.Cu")
		(net "P12V_HSC_SENSE2_R1_P")
	)
	(segment
		(start 298.15663 -401.41525)
		(end 298.15663 -401.824952)
		(width 0.254)
		(layer "In13.Cu")
		(net "P12V_HSC_SENSE2_R1_P")
	)
	(segment
		(start 244.750844 -406.635204)
		(end 244.750844 -407.030936)
		(width 0.254)
		(layer "F.Cu")
		(net "P12V_HSC_SENSE2_R1_N")
	)
	(segment
		(start 244.750844 -407.030936)
		(end 245.131844 -407.411936)
		(width 0.254)
		(layer "F.Cu")
		(net "P12V_HSC_SENSE2_R1_N")
	)
	(via
		(at 245.131844 -407.411936)
		(size 0.508)
		(drill 0.254)
		(layers "F.Cu" "B.Cu")
		(net "P12V_HSC_SENSE2_R1_N")
	)
	(via
		(at 297.58513 -402.015452)
		(size 0.762)
		(drill 0.254)
		(layers "F.Cu" "B.Cu")
		(net "P12V_HSC_SENSE2_R1_N")
	)
	(segment
		(start 297.58513 -401.526502)
		(end 297.58513 -402.015452)
		(width 0.254)
		(layer "B.Cu")
		(net "P12V_HSC_SENSE2_R1_N")
	)
	(segment
		(start 297.45813 -401.399502)
		(end 297.58513 -401.526502)
		(width 0.254)
		(layer "B.Cu")
		(net "P12V_HSC_SENSE2_R1_N")
	)
	(segment
		(start 297.58513 -402.504402)
		(end 297.58513 -402.015452)
		(width 0.254)
		(layer "B.Cu")
		(net "P12V_HSC_SENSE2_R1_N")
	)
	(segment
		(start 297.45813 -402.631402)
		(end 297.58513 -402.504402)
		(width 0.254)
		(layer "B.Cu")
		(net "P12V_HSC_SENSE2_R1_N")
	)
	(segment
		(start 287.096708 -396.7988)
		(end 294.644572 -396.7988)
		(width 0.254)
		(layer "In13.Cu")
		(net "P12V_HSC_SENSE2_R1_N")
	)
	(segment
		(start 297.77563 -401.573238)
		(end 297.77563 -401.824952)
		(width 0.254)
		(layer "In13.Cu")
		(net "P12V_HSC_SENSE2_R1_N")
	)
	(segment
		(start 280.005028 -403.89048)
		(end 287.096708 -396.7988)
		(width 0.254)
		(layer "In13.Cu")
		(net "P12V_HSC_SENSE2_R1_N")
	)
	(segment
		(start 244.941344 -407.221436)
		(end 244.941344 -406.515824)
		(width 0.254)
		(layer "In13.Cu")
		(net "P12V_HSC_SENSE2_R1_N")
	)
	(segment
		(start 244.941344 -406.515824)
		(end 247.566688 -403.89048)
		(width 0.254)
		(layer "In13.Cu")
		(net "P12V_HSC_SENSE2_R1_N")
	)
	(segment
		(start 296.49928 -398.653508)
		(end 296.49928 -400.296888)
		(width 0.254)
		(layer "In13.Cu")
		(net "P12V_HSC_SENSE2_R1_N")
	)
	(segment
		(start 247.566688 -403.89048)
		(end 280.005028 -403.89048)
		(width 0.254)
		(layer "In13.Cu")
		(net "P12V_HSC_SENSE2_R1_N")
	)
	(segment
		(start 245.131844 -407.411936)
		(end 244.941344 -407.221436)
		(width 0.254)
		(layer "In13.Cu")
		(net "P12V_HSC_SENSE2_R1_N")
	)
	(segment
		(start 296.49928 -400.296888)
		(end 297.77563 -401.573238)
		(width 0.254)
		(layer "In13.Cu")
		(net "P12V_HSC_SENSE2_R1_N")
	)
	(segment
		(start 297.77563 -401.824952)
		(end 297.58513 -402.015452)
		(width 0.254)
		(layer "In13.Cu")
		(net "P12V_HSC_SENSE2_R1_N")
	)
	(segment
		(start 294.644572 -396.7988)
		(end 296.49928 -398.653508)
		(width 0.254)
		(layer "In13.Cu")
		(net "P12V_HSC_SENSE2_R1_N")
	)
	(segment
		(start 294.980106 -392.569954)
		(end 294.980106 -393.776454)
		(width 0.254)
		(layer "F.Cu")
		(net "P12V_HSC_SENSE2_P")
	)
	(via
		(at 294.980106 -393.776454)
		(size 0.508)
		(drill 0.254)
		(layers "F.Cu" "B.Cu")
		(net "P12V_HSC_SENSE2_P")
	)
	(via
		(at 290.877498 -399.983452)
		(size 0.508)
		(drill 0.254)
		(layers "F.Cu" "B.Cu")
		(net "P12V_HSC_SENSE2_P")
	)
	(via
		(at 295.80713 -399.983452)
		(size 0.508)
		(drill 0.254)
		(layers "F.Cu" "B.Cu")
		(net "P12V_HSC_SENSE2_P")
	)
	(via
		(at 293.417498 -399.983452)
		(size 0.508)
		(drill 0.254)
		(layers "F.Cu" "B.Cu")
		(net "P12V_HSC_SENSE2_P")
	)
	(via
		(at 298.34713 -399.983452)
		(size 0.508)
		(drill 0.254)
		(layers "F.Cu" "B.Cu")
		(net "P12V_HSC_SENSE2_P")
	)
	(segment
		(start 293.544498 -400.599402)
		(end 293.544498 -400.110452)
		(width 0.254)
		(layer "B.Cu")
		(net "P12V_HSC_SENSE2_P")
	)
	(segment
		(start 293.544498 -400.110452)
		(end 293.417498 -399.983452)
		(width 0.254)
		(layer "B.Cu")
		(net "P12V_HSC_SENSE2_P")
	)
	(segment
		(start 298.47413 -400.599402)
		(end 298.34713 -400.472402)
		(width 0.254)
		(layer "B.Cu")
		(net "P12V_HSC_SENSE2_P")
	)
	(segment
		(start 298.34713 -400.472402)
		(end 298.34713 -399.983452)
		(width 0.254)
		(layer "B.Cu")
		(net "P12V_HSC_SENSE2_P")
	)
	(segment
		(start 291.004498 -400.599402)
		(end 291.004498 -400.110452)
		(width 0.254)
		(layer "B.Cu")
		(net "P12V_HSC_SENSE2_P")
	)
	(segment
		(start 291.004498 -400.110452)
		(end 290.877498 -399.983452)
		(width 0.254)
		(layer "B.Cu")
		(net "P12V_HSC_SENSE2_P")
	)
	(segment
		(start 295.80713 -400.472402)
		(end 295.80713 -399.983452)
		(width 0.254)
		(layer "B.Cu")
		(net "P12V_HSC_SENSE2_P")
	)
	(segment
		(start 295.93413 -400.599402)
		(end 295.80713 -400.472402)
		(width 0.254)
		(layer "B.Cu")
		(net "P12V_HSC_SENSE2_P")
	)
	(segment
		(start 290.686998 -398.423638)
		(end 294.66413 -394.446506)
		(width 0.254)
		(layer "In2.Cu")
		(net "P12V_HSC_SENSE2_P")
	)
	(segment
		(start 290.877498 -399.983452)
		(end 290.686998 -399.792952)
		(width 0.254)
		(layer "In2.Cu")
		(net "P12V_HSC_SENSE2_P")
	)
	(segment
		(start 290.686998 -399.792952)
		(end 290.686998 -398.423638)
		(width 0.254)
		(layer "In2.Cu")
		(net "P12V_HSC_SENSE2_P")
	)
	(segment
		(start 294.66413 -394.092684)
		(end 294.980106 -393.776454)
		(width 0.254)
		(layer "In2.Cu")
		(net "P12V_HSC_SENSE2_P")
	)
	(segment
		(start 294.66413 -394.446506)
		(end 294.66413 -394.092684)
		(width 0.254)
		(layer "In2.Cu")
		(net "P12V_HSC_SENSE2_P")
	)
	(segment
		(start 294.086788 -396.411704)
		(end 294.086788 -395.023848)
		(width 0.254)
		(layer "In6.Cu")
		(net "P12V_HSC_SENSE2_P")
	)
	(segment
		(start 293.226998 -399.792952)
		(end 293.226998 -397.271494)
		(width 0.254)
		(layer "In6.Cu")
		(net "P12V_HSC_SENSE2_P")
	)
	(segment
		(start 293.417498 -399.983452)
		(end 293.226998 -399.792952)
		(width 0.254)
		(layer "In6.Cu")
		(net "P12V_HSC_SENSE2_P")
	)
	(segment
		(start 293.226998 -397.271494)
		(end 294.086788 -396.411704)
		(width 0.254)
		(layer "In6.Cu")
		(net "P12V_HSC_SENSE2_P")
	)
	(segment
		(start 294.67048 -394.440156)
		(end 294.67048 -394.08608)
		(width 0.254)
		(layer "In6.Cu")
		(net "P12V_HSC_SENSE2_P")
	)
	(segment
		(start 294.67048 -394.08608)
		(end 294.980106 -393.776454)
		(width 0.254)
		(layer "In6.Cu")
		(net "P12V_HSC_SENSE2_P")
	)
	(segment
		(start 294.086788 -395.023848)
		(end 294.67048 -394.440156)
		(width 0.254)
		(layer "In6.Cu")
		(net "P12V_HSC_SENSE2_P")
	)
	(segment
		(start 295.80713 -399.983452)
		(end 295.61663 -399.792952)
		(width 0.254)
		(layer "In11.Cu")
		(net "P12V_HSC_SENSE2_P")
	)
	(segment
		(start 294.67048 -394.440156)
		(end 294.67048 -394.08608)
		(width 0.254)
		(layer "In11.Cu")
		(net "P12V_HSC_SENSE2_P")
	)
	(segment
		(start 294.383206 -394.72743)
		(end 294.67048 -394.440156)
		(width 0.254)
		(layer "In11.Cu")
		(net "P12V_HSC_SENSE2_P")
	)
	(segment
		(start 295.61663 -399.792952)
		(end 295.61663 -398.454372)
		(width 0.254)
		(layer "In11.Cu")
		(net "P12V_HSC_SENSE2_P")
	)
	(segment
		(start 294.383206 -397.220948)
		(end 294.383206 -394.72743)
		(width 0.254)
		(layer "In11.Cu")
		(net "P12V_HSC_SENSE2_P")
	)
	(segment
		(start 294.67048 -394.08608)
		(end 294.980106 -393.776454)
		(width 0.254)
		(layer "In11.Cu")
		(net "P12V_HSC_SENSE2_P")
	)
	(segment
		(start 295.61663 -398.454372)
		(end 294.383206 -397.220948)
		(width 0.254)
		(layer "In11.Cu")
		(net "P12V_HSC_SENSE2_P")
	)
	(segment
		(start 298.15536 -397.026892)
		(end 295.918128 -394.78966)
		(width 0.254)
		(layer "In13.Cu")
		(net "P12V_HSC_SENSE2_P")
	)
	(segment
		(start 298.15536 -399.791682)
		(end 298.15536 -397.026892)
		(width 0.254)
		(layer "In13.Cu")
		(net "P12V_HSC_SENSE2_P")
	)
	(segment
		(start 294.670734 -394.085826)
		(end 294.980106 -393.776454)
		(width 0.254)
		(layer "In13.Cu")
		(net "P12V_HSC_SENSE2_P")
	)
	(segment
		(start 298.34713 -399.983452)
		(end 298.15536 -399.791682)
		(width 0.254)
		(layer "In13.Cu")
		(net "P12V_HSC_SENSE2_P")
	)
	(segment
		(start 294.670734 -394.445236)
		(end 294.670734 -394.085826)
		(width 0.254)
		(layer "In13.Cu")
		(net "P12V_HSC_SENSE2_P")
	)
	(segment
		(start 295.918128 -394.78966)
		(end 295.015158 -394.78966)
		(width 0.254)
		(layer "In13.Cu")
		(net "P12V_HSC_SENSE2_P")
	)
	(segment
		(start 295.015158 -394.78966)
		(end 294.670734 -394.445236)
		(width 0.254)
		(layer "In13.Cu")
		(net "P12V_HSC_SENSE2_P")
	)
	(segment
		(start 293.980108 -392.569954)
		(end 293.980108 -393.776454)
		(width 0.254)
		(layer "F.Cu")
		(net "P12V_HSC_SENSE2_N")
	)
	(via
		(at 297.58513 -399.983452)
		(size 0.508)
		(drill 0.254)
		(layers "F.Cu" "B.Cu")
		(net "P12V_HSC_SENSE2_N")
	)
	(via
		(at 290.115498 -399.983452)
		(size 0.508)
		(drill 0.254)
		(layers "F.Cu" "B.Cu")
		(net "P12V_HSC_SENSE2_N")
	)
	(via
		(at 292.655498 -399.983452)
		(size 0.508)
		(drill 0.254)
		(layers "F.Cu" "B.Cu")
		(net "P12V_HSC_SENSE2_N")
	)
	(via
		(at 295.04513 -399.983452)
		(size 0.762)
		(drill 0.254)
		(layers "F.Cu" "B.Cu")
		(net "P12V_HSC_SENSE2_N")
	)
	(via
		(at 293.980108 -393.776454)
		(size 0.508)
		(drill 0.254)
		(layers "F.Cu" "B.Cu")
		(net "P12V_HSC_SENSE2_N")
	)
	(segment
		(start 292.528498 -400.110452)
		(end 292.655498 -399.983452)
		(width 0.254)
		(layer "B.Cu")
		(net "P12V_HSC_SENSE2_N")
	)
	(segment
		(start 297.45813 -400.599402)
		(end 297.45813 -400.110452)
		(width 0.254)
		(layer "B.Cu")
		(net "P12V_HSC_SENSE2_N")
	)
	(segment
		(start 294.91813 -400.599402)
		(end 294.91813 -400.110452)
		(width 0.254)
		(layer "B.Cu")
		(net "P12V_HSC_SENSE2_N")
	)
	(segment
		(start 289.988498 -400.599402)
		(end 289.988498 -400.110452)
		(width 0.254)
		(layer "B.Cu")
		(net "P12V_HSC_SENSE2_N")
	)
	(segment
		(start 297.45813 -400.110452)
		(end 297.58513 -399.983452)
		(width 0.254)
		(layer "B.Cu")
		(net "P12V_HSC_SENSE2_N")
	)
	(segment
		(start 294.91813 -400.110452)
		(end 295.04513 -399.983452)
		(width 0.254)
		(layer "B.Cu")
		(net "P12V_HSC_SENSE2_N")
	)
	(segment
		(start 289.988498 -400.110452)
		(end 290.115498 -399.983452)
		(width 0.254)
		(layer "B.Cu")
		(net "P12V_HSC_SENSE2_N")
	)
	(segment
		(start 292.528498 -400.599402)
		(end 292.528498 -400.110452)
		(width 0.254)
		(layer "B.Cu")
		(net "P12V_HSC_SENSE2_N")
	)
	(segment
		(start 290.305998 -399.792952)
		(end 290.305998 -398.26565)
		(width 0.254)
		(layer "In2.Cu")
		(net "P12V_HSC_SENSE2_N")
	)
	(segment
		(start 294.28313 -394.079476)
		(end 293.980108 -393.776454)
		(width 0.254)
		(layer "In2.Cu")
		(net "P12V_HSC_SENSE2_N")
	)
	(segment
		(start 294.28313 -394.288518)
		(end 294.28313 -394.079476)
		(width 0.254)
		(layer "In2.Cu")
		(net "P12V_HSC_SENSE2_N")
	)
	(segment
		(start 290.305998 -398.26565)
		(end 294.28313 -394.288518)
		(width 0.254)
		(layer "In2.Cu")
		(net "P12V_HSC_SENSE2_N")
	)
	(segment
		(start 290.115498 -399.983452)
		(end 290.305998 -399.792952)
		(width 0.254)
		(layer "In2.Cu")
		(net "P12V_HSC_SENSE2_N")
	)
	(segment
		(start 292.845998 -397.113506)
		(end 293.705788 -396.253716)
		(width 0.254)
		(layer "In6.Cu")
		(net "P12V_HSC_SENSE2_N")
	)
	(segment
		(start 292.845998 -399.792952)
		(end 292.845998 -397.113506)
		(width 0.254)
		(layer "In6.Cu")
		(net "P12V_HSC_SENSE2_N")
	)
	(segment
		(start 293.705788 -394.86586)
		(end 294.28948 -394.282168)
		(width 0.254)
		(layer "In6.Cu")
		(net "P12V_HSC_SENSE2_N")
	)
	(segment
		(start 294.28948 -394.085826)
		(end 293.980108 -393.776454)
		(width 0.254)
		(layer "In6.Cu")
		(net "P12V_HSC_SENSE2_N")
	)
	(segment
		(start 293.705788 -396.253716)
		(end 293.705788 -394.86586)
		(width 0.254)
		(layer "In6.Cu")
		(net "P12V_HSC_SENSE2_N")
	)
	(segment
		(start 292.655498 -399.983452)
		(end 292.845998 -399.792952)
		(width 0.254)
		(layer "In6.Cu")
		(net "P12V_HSC_SENSE2_N")
	)
	(segment
		(start 294.28948 -394.282168)
		(end 294.28948 -394.085826)
		(width 0.254)
		(layer "In6.Cu")
		(net "P12V_HSC_SENSE2_N")
	)
	(segment
		(start 294.28948 -394.282168)
		(end 294.28948 -394.085826)
		(width 0.254)
		(layer "In11.Cu")
		(net "P12V_HSC_SENSE2_N")
	)
	(segment
		(start 295.23563 -399.792952)
		(end 295.23563 -398.61236)
		(width 0.254)
		(layer "In11.Cu")
		(net "P12V_HSC_SENSE2_N")
	)
	(segment
		(start 294.002206 -397.378936)
		(end 294.002206 -394.569442)
		(width 0.254)
		(layer "In11.Cu")
		(net "P12V_HSC_SENSE2_N")
	)
	(segment
		(start 294.28948 -394.085826)
		(end 293.980108 -393.776454)
		(width 0.254)
		(layer "In11.Cu")
		(net "P12V_HSC_SENSE2_N")
	)
	(segment
		(start 294.002206 -394.569442)
		(end 294.28948 -394.282168)
		(width 0.254)
		(layer "In11.Cu")
		(net "P12V_HSC_SENSE2_N")
	)
	(segment
		(start 295.23563 -398.61236)
		(end 294.002206 -397.378936)
		(width 0.254)
		(layer "In11.Cu")
		(net "P12V_HSC_SENSE2_N")
	)
	(segment
		(start 295.04513 -399.983452)
		(end 295.23563 -399.792952)
		(width 0.254)
		(layer "In11.Cu")
		(net "P12V_HSC_SENSE2_N")
	)
	(segment
		(start 294.289734 -394.08608)
		(end 293.980108 -393.776454)
		(width 0.254)
		(layer "In13.Cu")
		(net "P12V_HSC_SENSE2_N")
	)
	(segment
		(start 297.77436 -397.18488)
		(end 295.76014 -395.17066)
		(width 0.254)
		(layer "In13.Cu")
		(net "P12V_HSC_SENSE2_N")
	)
	(segment
		(start 294.85717 -395.17066)
		(end 294.289734 -394.603224)
		(width 0.254)
		(layer "In13.Cu")
		(net "P12V_HSC_SENSE2_N")
	)
	(segment
		(start 297.77436 -399.794222)
		(end 297.77436 -397.18488)
		(width 0.254)
		(layer "In13.Cu")
		(net "P12V_HSC_SENSE2_N")
	)
	(segment
		(start 295.76014 -395.17066)
		(end 294.85717 -395.17066)
		(width 0.254)
		(layer "In13.Cu")
		(net "P12V_HSC_SENSE2_N")
	)
	(segment
		(start 297.58513 -399.983452)
		(end 297.77436 -399.794222)
		(width 0.254)
		(layer "In13.Cu")
		(net "P12V_HSC_SENSE2_N")
	)
	(segment
		(start 294.289734 -394.603224)
		(end 294.289734 -394.08608)
		(width 0.254)
		(layer "In13.Cu")
		(net "P12V_HSC_SENSE2_N")
	)
	(segment
		(start 288.146998 -400.698208)
		(end 291.962078 -396.883128)
		(width 0.254)
		(layer "F.Cu")
		(net "P12V_HSC_SENSE1_P")
	)
	(segment
		(start 288.146998 -401.824952)
		(end 288.146998 -400.698208)
		(width 0.254)
		(layer "F.Cu")
		(net "P12V_HSC_SENSE1_P")
	)
	(segment
		(start 295.276524 -396.883128)
		(end 296.670476 -395.489176)
		(width 0.254)
		(layer "F.Cu")
		(net "P12V_HSC_SENSE1_P")
	)
	(segment
		(start 296.980102 -393.776454)
		(end 296.980102 -392.569954)
		(width 0.254)
		(layer "F.Cu")
		(net "P12V_HSC_SENSE1_P")
	)
	(segment
		(start 296.670476 -394.08608)
		(end 296.980102 -393.776454)
		(width 0.254)
		(layer "F.Cu")
		(net "P12V_HSC_SENSE1_P")
	)
	(segment
		(start 288.337498 -402.015452)
		(end 288.146998 -401.824952)
		(width 0.254)
		(layer "F.Cu")
		(net "P12V_HSC_SENSE1_P")
	)
	(segment
		(start 296.670476 -395.489176)
		(end 296.670476 -394.08608)
		(width 0.254)
		(layer "F.Cu")
		(net "P12V_HSC_SENSE1_P")
	)
	(segment
		(start 277.859744 -407.782776)
		(end 277.478744 -407.401776)
		(width 0.254)
		(layer "F.Cu")
		(net "P12V_HSC_SENSE1_P")
	)
	(segment
		(start 291.962078 -396.883128)
		(end 295.276524 -396.883128)
		(width 0.254)
		(layer "F.Cu")
		(net "P12V_HSC_SENSE1_P")
	)
	(segment
		(start 277.859744 -410.101796)
		(end 277.859744 -407.782776)
		(width 0.254)
		(layer "F.Cu")
		(net "P12V_HSC_SENSE1_P")
	)
	(via
		(at 288.337498 -402.015452)
		(size 0.508)
		(drill 0.254)
		(layers "F.Cu" "B.Cu")
		(net "P12V_HSC_SENSE1_P")
	)
	(via
		(at 296.980102 -393.776454)
		(size 0.508)
		(drill 0.254)
		(layers "F.Cu" "B.Cu")
		(net "P12V_HSC_SENSE1_P")
	)
	(via
		(at 277.478744 -407.401776)
		(size 0.508)
		(drill 0.254)
		(layers "F.Cu" "B.Cu")
		(net "P12V_HSC_SENSE1_P")
	)
	(segment
		(start 288.28238 -402.07057)
		(end 288.337498 -402.015452)
		(width 0.254)
		(layer "B.Cu")
		(net "P12V_HSC_SENSE1_P")
	)
	(segment
		(start 288.464498 -402.631402)
		(end 288.28238 -402.449284)
		(width 0.254)
		(layer "B.Cu")
		(net "P12V_HSC_SENSE1_P")
	)
	(segment
		(start 288.28238 -402.449284)
		(end 288.28238 -402.07057)
		(width 0.254)
		(layer "B.Cu")
		(net "P12V_HSC_SENSE1_P")
	)
	(segment
		(start 277.669244 -406.107392)
		(end 283.043376 -400.73326)
		(width 0.254)
		(layer "In4.Cu")
		(net "P12V_HSC_SENSE1_P")
	)
	(segment
		(start 277.478744 -407.401776)
		(end 277.669244 -407.211276)
		(width 0.254)
		(layer "In4.Cu")
		(net "P12V_HSC_SENSE1_P")
	)
	(segment
		(start 288.146998 -401.824952)
		(end 288.337498 -402.015452)
		(width 0.254)
		(layer "In4.Cu")
		(net "P12V_HSC_SENSE1_P")
	)
	(segment
		(start 288.146998 -401.195032)
		(end 288.146998 -401.824952)
		(width 0.254)
		(layer "In4.Cu")
		(net "P12V_HSC_SENSE1_P")
	)
	(segment
		(start 277.669244 -407.211276)
		(end 277.669244 -406.107392)
		(width 0.254)
		(layer "In4.Cu")
		(net "P12V_HSC_SENSE1_P")
	)
	(segment
		(start 283.043376 -400.73326)
		(end 287.685226 -400.73326)
		(width 0.254)
		(layer "In4.Cu")
		(net "P12V_HSC_SENSE1_P")
	)
	(segment
		(start 287.685226 -400.73326)
		(end 288.146998 -401.195032)
		(width 0.254)
		(layer "In4.Cu")
		(net "P12V_HSC_SENSE1_P")
	)
	(segment
		(start 287.575498 -402.015452)
		(end 287.765998 -401.824952)
		(width 0.254)
		(layer "F.Cu")
		(net "P12V_HSC_SENSE1_N")
	)
	(segment
		(start 295.980104 -393.776454)
		(end 295.980104 -392.569954)
		(width 0.254)
		(layer "F.Cu")
		(net "P12V_HSC_SENSE1_N")
	)
	(segment
		(start 277.859744 -407.018744)
		(end 278.24176 -407.40076)
		(width 0.254)
		(layer "F.Cu")
		(net "P12V_HSC_SENSE1_N")
	)
	(segment
		(start 277.859744 -404.701756)
		(end 277.859744 -407.018744)
		(width 0.254)
		(layer "F.Cu")
		(net "P12V_HSC_SENSE1_N")
	)
	(segment
		(start 287.765998 -400.54022)
		(end 291.80409 -396.502128)
		(width 0.254)
		(layer "F.Cu")
		(net "P12V_HSC_SENSE1_N")
	)
	(segment
		(start 287.765998 -401.824952)
		(end 287.765998 -400.54022)
		(width 0.254)
		(layer "F.Cu")
		(net "P12V_HSC_SENSE1_N")
	)
	(segment
		(start 291.80409 -396.502128)
		(end 295.118536 -396.502128)
		(width 0.254)
		(layer "F.Cu")
		(net "P12V_HSC_SENSE1_N")
	)
	(segment
		(start 295.118536 -396.502128)
		(end 296.289476 -395.331188)
		(width 0.254)
		(layer "F.Cu")
		(net "P12V_HSC_SENSE1_N")
	)
	(segment
		(start 296.289476 -394.085826)
		(end 295.980104 -393.776454)
		(width 0.254)
		(layer "F.Cu")
		(net "P12V_HSC_SENSE1_N")
	)
	(segment
		(start 278.24176 -407.40076)
		(end 278.240744 -407.401776)
		(width 0.254)
		(layer "F.Cu")
		(net "P12V_HSC_SENSE1_N")
	)
	(segment
		(start 296.289476 -395.331188)
		(end 296.289476 -394.085826)
		(width 0.254)
		(layer "F.Cu")
		(net "P12V_HSC_SENSE1_N")
	)
	(via
		(at 287.575498 -402.015452)
		(size 0.6604)
		(drill 0.254)
		(layers "F.Cu" "B.Cu")
		(net "P12V_HSC_SENSE1_N")
	)
	(via
		(at 295.980104 -393.776454)
		(size 0.508)
		(drill 0.254)
		(layers "F.Cu" "B.Cu")
		(net "P12V_HSC_SENSE1_N")
	)
	(via
		(at 278.240744 -407.401776)
		(size 0.508)
		(drill 0.254)
		(layers "F.Cu" "B.Cu")
		(net "P12V_HSC_SENSE1_N")
	)
	(segment
		(start 287.67024 -402.40966)
		(end 287.448498 -402.631402)
		(width 0.254)
		(layer "B.Cu")
		(net "P12V_HSC_SENSE1_N")
	)
	(segment
		(start 287.67024 -402.110194)
		(end 287.67024 -402.40966)
		(width 0.254)
		(layer "B.Cu")
		(net "P12V_HSC_SENSE1_N")
	)
	(segment
		(start 287.575498 -402.015452)
		(end 287.67024 -402.110194)
		(width 0.254)
		(layer "B.Cu")
		(net "P12V_HSC_SENSE1_N")
	)
	(segment
		(start 287.575498 -402.015452)
		(end 287.765998 -401.824952)
		(width 0.254)
		(layer "In4.Cu")
		(net "P12V_HSC_SENSE1_N")
	)
	(segment
		(start 287.765998 -401.824952)
		(end 287.765998 -401.35302)
		(width 0.254)
		(layer "In4.Cu")
		(net "P12V_HSC_SENSE1_N")
	)
	(segment
		(start 278.050244 -406.26538)
		(end 278.050244 -407.211276)
		(width 0.254)
		(layer "In4.Cu")
		(net "P12V_HSC_SENSE1_N")
	)
	(segment
		(start 278.050244 -407.211276)
		(end 278.240744 -407.401776)
		(width 0.254)
		(layer "In4.Cu")
		(net "P12V_HSC_SENSE1_N")
	)
	(segment
		(start 283.201364 -401.11426)
		(end 278.050244 -406.26538)
		(width 0.254)
		(layer "In4.Cu")
		(net "P12V_HSC_SENSE1_N")
	)
	(segment
		(start 287.765998 -401.35302)
		(end 287.527238 -401.11426)
		(width 0.254)
		(layer "In4.Cu")
		(net "P12V_HSC_SENSE1_N")
	)
	(segment
		(start 287.527238 -401.11426)
		(end 283.201364 -401.11426)
		(width 0.254)
		(layer "In4.Cu")
		(net "P12V_HSC_SENSE1_N")
	)
	(via
		(at 246.432578 -396.933674)
		(size 0.7112)
		(drill 0.3556)
		(layers "F.Cu" "B.Cu")
		(net "P12V_HSC_GATE_RC")
	)
	(via
		(at 250.00458 -394.808456)
		(size 0.508)
		(drill 0.254)
		(layers "F.Cu" "B.Cu")
		(net "P12V_HSC_GATE_G6")
	)
	(via
		(at 244.069616 -394.808456)
		(size 0.508)
		(drill 0.254)
		(layers "F.Cu" "B.Cu")
		(net "P12V_HSC_GATE_G5")
	)
	(via
		(at 273.744436 -394.808456)
		(size 0.508)
		(drill 0.254)
		(layers "F.Cu" "B.Cu")
		(net "P12V_HSC_GATE_G4")
	)
	(via
		(at 267.809472 -394.808456)
		(size 0.508)
		(drill 0.254)
		(layers "F.Cu" "B.Cu")
		(net "P12V_HSC_GATE_G3")
	)
	(via
		(at 261.874508 -394.808456)
		(size 0.508)
		(drill 0.254)
		(layers "F.Cu" "B.Cu")
		(net "P12V_HSC_GATE_G2")
	)
	(via
		(at 255.939544 -394.808456)
		(size 0.508)
		(drill 0.254)
		(layers "F.Cu" "B.Cu")
		(net "P12V_HSC_GATE_G1")
	)
	(via
		(at 245.339616 -394.808456)
		(size 0.508)
		(drill 0.254)
		(layers "F.Cu" "B.Cu")
		(net "P12V_HSC_GATE2")
	)
	(via
		(at 269.079472 -394.808456)
		(size 0.508)
		(drill 0.254)
		(layers "F.Cu" "B.Cu")
		(net "P12V_HSC_GATE2")
	)
	(via
		(at 251.27458 -394.808456)
		(size 0.508)
		(drill 0.254)
		(layers "F.Cu" "B.Cu")
		(net "P12V_HSC_GATE2")
	)
	(via
		(at 289.980116 -393.776454)
		(size 0.508)
		(drill 0.254)
		(layers "F.Cu" "B.Cu")
		(net "P12V_HSC_GATE2")
	)
	(via
		(at 275.014436 -394.808456)
		(size 0.508)
		(drill 0.254)
		(layers "F.Cu" "B.Cu")
		(net "P12V_HSC_GATE2")
	)
	(via
		(at 263.144508 -394.808456)
		(size 0.508)
		(drill 0.254)
		(layers "F.Cu" "B.Cu")
		(net "P12V_HSC_GATE2")
	)
	(via
		(at 257.209544 -394.808456)
		(size 0.508)
		(drill 0.254)
		(layers "F.Cu" "B.Cu")
		(net "P12V_HSC_GATE2")
	)
	(via
		(at 289.98926 -394.44168)
		(size 0.508)
		(drill 0.254)
		(layers "F.Cu" "B.Cu")
		(net "P12V_HSC_GATE2")
	)
	(via
		(at 290.93414 -391.32256)
		(size 0.508)
		(drill 0.254)
		(layers "F.Cu" "B.Cu")
		(net "P12V_HSC_GATE1")
	)
	(via
		(at 290.33724 -390.74852)
		(size 0.508)
		(drill 0.254)
		(layers "F.Cu" "B.Cu")
		(net "P12V_HSC_GATE1")
	)
	(via
		(at 280.6065 -393.533884)
		(size 0.508)
		(drill 0.254)
		(layers "F.Cu" "B.Cu")
		(net "P12V_HSC_GATE1")
	)
	(segment
		(start 288.0614 -404.61819)
		(end 287.726628 -404.952962)
		(width 0.254)
		(layer "F.Cu")
		(net "P12V_HSC_ADC_P")
	)
	(segment
		(start 292.289738 -394.406882)
		(end 292.289738 -394.08608)
		(width 0.254)
		(layer "F.Cu")
		(net "P12V_HSC_ADC_P")
	)
	(segment
		(start 291.980112 -393.776454)
		(end 291.980112 -392.569954)
		(width 0.254)
		(layer "F.Cu")
		(net "P12V_HSC_ADC_P")
	)
	(segment
		(start 288.337498 -404.047452)
		(end 288.0614 -404.32355)
		(width 0.254)
		(layer "F.Cu")
		(net "P12V_HSC_ADC_P")
	)
	(segment
		(start 287.726628 -404.952962)
		(end 287.05302 -404.952962)
		(width 0.254)
		(layer "F.Cu")
		(net "P12V_HSC_ADC_P")
	)
	(segment
		(start 287.05302 -404.952962)
		(end 286.390588 -404.29053)
		(width 0.254)
		(layer "F.Cu")
		(net "P12V_HSC_ADC_P")
	)
	(segment
		(start 292.289738 -394.08608)
		(end 291.980112 -393.776454)
		(width 0.254)
		(layer "F.Cu")
		(net "P12V_HSC_ADC_P")
	)
	(segment
		(start 286.390588 -404.29053)
		(end 286.390588 -400.306032)
		(width 0.254)
		(layer "F.Cu")
		(net "P12V_HSC_ADC_P")
	)
	(segment
		(start 286.390588 -400.306032)
		(end 292.289738 -394.406882)
		(width 0.254)
		(layer "F.Cu")
		(net "P12V_HSC_ADC_P")
	)
	(segment
		(start 288.0614 -404.32355)
		(end 288.0614 -404.61819)
		(width 0.254)
		(layer "F.Cu")
		(net "P12V_HSC_ADC_P")
	)
	(via
		(at 288.337498 -404.047452)
		(size 0.508)
		(drill 0.254)
		(layers "F.Cu" "B.Cu")
		(net "P12V_HSC_ADC_P")
	)
	(via
		(at 295.80713 -404.047452)
		(size 0.508)
		(drill 0.254)
		(layers "F.Cu" "B.Cu")
		(net "P12V_HSC_ADC_P")
	)
	(via
		(at 290.877498 -404.047452)
		(size 0.508)
		(drill 0.254)
		(layers "F.Cu" "B.Cu")
		(net "P12V_HSC_ADC_P")
	)
	(via
		(at 291.980112 -393.776454)
		(size 0.508)
		(drill 0.254)
		(layers "F.Cu" "B.Cu")
		(net "P12V_HSC_ADC_P")
	)
	(via
		(at 293.417498 -404.047452)
		(size 0.508)
		(drill 0.254)
		(layers "F.Cu" "B.Cu")
		(net "P12V_HSC_ADC_P")
	)
	(via
		(at 298.34713 -404.047452)
		(size 0.762)
		(drill 0.254)
		(layers "F.Cu" "B.Cu")
		(net "P12V_HSC_ADC_P")
	)
	(segment
		(start 293.544498 -403.431502)
		(end 293.544498 -403.920452)
		(width 0.254)
		(layer "B.Cu")
		(net "P12V_HSC_ADC_P")
	)
	(segment
		(start 291.004498 -403.920452)
		(end 290.877498 -404.047452)
		(width 0.254)
		(layer "B.Cu")
		(net "P12V_HSC_ADC_P")
	)
	(segment
		(start 288.464498 -403.431502)
		(end 288.464498 -403.920452)
		(width 0.254)
		(layer "B.Cu")
		(net "P12V_HSC_ADC_P")
	)
	(segment
		(start 298.47413 -403.431502)
		(end 298.47413 -403.920452)
		(width 0.254)
		(layer "B.Cu")
		(net "P12V_HSC_ADC_P")
	)
	(segment
		(start 298.47413 -403.920452)
		(end 298.34713 -404.047452)
		(width 0.254)
		(layer "B.Cu")
		(net "P12V_HSC_ADC_P")
	)
	(segment
		(start 295.93413 -403.431502)
		(end 295.93413 -403.920452)
		(width 0.254)
		(layer "B.Cu")
		(net "P12V_HSC_ADC_P")
	)
	(segment
		(start 291.004498 -403.431502)
		(end 291.004498 -403.920452)
		(width 0.254)
		(layer "B.Cu")
		(net "P12V_HSC_ADC_P")
	)
	(segment
		(start 293.544498 -403.920452)
		(end 293.417498 -404.047452)
		(width 0.254)
		(layer "B.Cu")
		(net "P12V_HSC_ADC_P")
	)
	(segment
		(start 295.93413 -403.920452)
		(end 295.80713 -404.047452)
		(width 0.254)
		(layer "B.Cu")
		(net "P12V_HSC_ADC_P")
	)
	(segment
		(start 288.464498 -403.920452)
		(end 288.337498 -404.047452)
		(width 0.254)
		(layer "B.Cu")
		(net "P12V_HSC_ADC_P")
	)
	(segment
		(start 289.047428 -397.6878)
		(end 292.289738 -394.44549)
		(width 0.254)
		(layer "In2.Cu")
		(net "P12V_HSC_ADC_P")
	)
	(segment
		(start 289.5346 -405.232362)
		(end 289.047428 -404.74519)
		(width 0.254)
		(layer "In2.Cu")
		(net "P12V_HSC_ADC_P")
	)
	(segment
		(start 290.686998 -404.237952)
		(end 290.686998 -404.75535)
		(width 0.254)
		(layer "In2.Cu")
		(net "P12V_HSC_ADC_P")
	)
	(segment
		(start 292.289738 -394.44549)
		(end 292.289738 -394.08608)
		(width 0.254)
		(layer "In2.Cu")
		(net "P12V_HSC_ADC_P")
	)
	(segment
		(start 290.209986 -405.232362)
		(end 289.5346 -405.232362)
		(width 0.254)
		(layer "In2.Cu")
		(net "P12V_HSC_ADC_P")
	)
	(segment
		(start 290.877498 -404.047452)
		(end 290.686998 -404.237952)
		(width 0.254)
		(layer "In2.Cu")
		(net "P12V_HSC_ADC_P")
	)
	(segment
		(start 292.289738 -394.08608)
		(end 291.980112 -393.776454)
		(width 0.254)
		(layer "In2.Cu")
		(net "P12V_HSC_ADC_P")
	)
	(segment
		(start 290.686998 -404.75535)
		(end 290.209986 -405.232362)
		(width 0.254)
		(layer "In2.Cu")
		(net "P12V_HSC_ADC_P")
	)
	(segment
		(start 289.047428 -404.74519)
		(end 289.047428 -397.6878)
		(width 0.254)
		(layer "In2.Cu")
		(net "P12V_HSC_ADC_P")
	)
	(segment
		(start 292.289738 -394.08608)
		(end 291.980112 -393.776454)
		(width 0.254)
		(layer "In6.Cu")
		(net "P12V_HSC_ADC_P")
	)
	(segment
		(start 293.417498 -404.047452)
		(end 293.226998 -404.237952)
		(width 0.254)
		(layer "In6.Cu")
		(net "P12V_HSC_ADC_P")
	)
	(segment
		(start 292.749986 -405.232362)
		(end 292.0746 -405.232362)
		(width 0.254)
		(layer "In6.Cu")
		(net "P12V_HSC_ADC_P")
	)
	(segment
		(start 291.597588 -404.75535)
		(end 291.597588 -396.136114)
		(width 0.254)
		(layer "In6.Cu")
		(net "P12V_HSC_ADC_P")
	)
	(segment
		(start 291.597588 -396.136114)
		(end 292.289738 -395.443964)
		(width 0.254)
		(layer "In6.Cu")
		(net "P12V_HSC_ADC_P")
	)
	(segment
		(start 292.0746 -405.232362)
		(end 291.597588 -404.75535)
		(width 0.254)
		(layer "In6.Cu")
		(net "P12V_HSC_ADC_P")
	)
	(segment
		(start 293.226998 -404.237952)
		(end 293.226998 -404.75535)
		(width 0.254)
		(layer "In6.Cu")
		(net "P12V_HSC_ADC_P")
	)
	(segment
		(start 292.289738 -395.443964)
		(end 292.289738 -394.08608)
		(width 0.254)
		(layer "In6.Cu")
		(net "P12V_HSC_ADC_P")
	)
	(segment
		(start 293.226998 -404.75535)
		(end 292.749986 -405.232362)
		(width 0.254)
		(layer "In6.Cu")
		(net "P12V_HSC_ADC_P")
	)
	(segment
		(start 294.464232 -405.232362)
		(end 293.98722 -404.75535)
		(width 0.254)
		(layer "In11.Cu")
		(net "P12V_HSC_ADC_P")
	)
	(segment
		(start 293.98722 -399.24228)
		(end 292.289484 -397.544544)
		(width 0.254)
		(layer "In11.Cu")
		(net "P12V_HSC_ADC_P")
	)
	(segment
		(start 295.61663 -404.237952)
		(end 295.61663 -404.75535)
		(width 0.254)
		(layer "In11.Cu")
		(net "P12V_HSC_ADC_P")
	)
	(segment
		(start 292.289484 -397.544544)
		(end 292.289484 -394.085826)
		(width 0.254)
		(layer "In11.Cu")
		(net "P12V_HSC_ADC_P")
	)
	(segment
		(start 295.139618 -405.232362)
		(end 294.464232 -405.232362)
		(width 0.254)
		(layer "In11.Cu")
		(net "P12V_HSC_ADC_P")
	)
	(segment
		(start 295.80713 -404.047452)
		(end 295.61663 -404.237952)
		(width 0.254)
		(layer "In11.Cu")
		(net "P12V_HSC_ADC_P")
	)
	(segment
		(start 292.289484 -394.085826)
		(end 291.980112 -393.776454)
		(width 0.254)
		(layer "In11.Cu")
		(net "P12V_HSC_ADC_P")
	)
	(segment
		(start 295.61663 -404.75535)
		(end 295.139618 -405.232362)
		(width 0.254)
		(layer "In11.Cu")
		(net "P12V_HSC_ADC_P")
	)
	(segment
		(start 293.98722 -404.75535)
		(end 293.98722 -399.24228)
		(width 0.254)
		(layer "In11.Cu")
		(net "P12V_HSC_ADC_P")
	)
	(segment
		(start 299.937932 -397.31569)
		(end 299.937932 -402.35251)
		(width 0.254)
		(layer "In13.Cu")
		(net "P12V_HSC_ADC_P")
	)
	(segment
		(start 299.433488 -391.865104)
		(end 300.71949 -393.151106)
		(width 0.254)
		(layer "In13.Cu")
		(net "P12V_HSC_ADC_P")
	)
	(segment
		(start 300.71949 -396.534132)
		(end 299.937932 -397.31569)
		(width 0.254)
		(layer "In13.Cu")
		(net "P12V_HSC_ADC_P")
	)
	(segment
		(start 298.15663 -403.856952)
		(end 298.34713 -404.047452)
		(width 0.254)
		(layer "In13.Cu")
		(net "P12V_HSC_ADC_P")
	)
	(segment
		(start 292.289738 -392.278108)
		(end 292.702742 -391.865104)
		(width 0.254)
		(layer "In13.Cu")
		(net "P12V_HSC_ADC_P")
	)
	(segment
		(start 292.289738 -393.466828)
		(end 292.289738 -392.278108)
		(width 0.254)
		(layer "In13.Cu")
		(net "P12V_HSC_ADC_P")
	)
	(segment
		(start 299.0469 -403.243542)
		(end 298.41063 -403.243542)
		(width 0.254)
		(layer "In13.Cu")
		(net "P12V_HSC_ADC_P")
	)
	(segment
		(start 300.71949 -393.151106)
		(end 300.71949 -396.534132)
		(width 0.254)
		(layer "In13.Cu")
		(net "P12V_HSC_ADC_P")
	)
	(segment
		(start 291.980112 -393.776454)
		(end 292.289738 -393.466828)
		(width 0.254)
		(layer "In13.Cu")
		(net "P12V_HSC_ADC_P")
	)
	(segment
		(start 299.937932 -402.35251)
		(end 299.0469 -403.243542)
		(width 0.254)
		(layer "In13.Cu")
		(net "P12V_HSC_ADC_P")
	)
	(segment
		(start 298.15663 -403.497542)
		(end 298.15663 -403.856952)
		(width 0.254)
		(layer "In13.Cu")
		(net "P12V_HSC_ADC_P")
	)
	(segment
		(start 292.702742 -391.865104)
		(end 299.433488 -391.865104)
		(width 0.254)
		(layer "In13.Cu")
		(net "P12V_HSC_ADC_P")
	)
	(segment
		(start 298.41063 -403.243542)
		(end 298.15663 -403.497542)
		(width 0.254)
		(layer "In13.Cu")
		(net "P12V_HSC_ADC_P")
	)
	(segment
		(start 292.670738 -394.56487)
		(end 292.670738 -394.085826)
		(width 0.254)
		(layer "F.Cu")
		(net "P12V_HSC_ADC_N")
	)
	(segment
		(start 287.6804 -404.460202)
		(end 287.56864 -404.571962)
		(width 0.254)
		(layer "F.Cu")
		(net "P12V_HSC_ADC_N")
	)
	(segment
		(start 292.670738 -394.085826)
		(end 292.98011 -393.776454)
		(width 0.254)
		(layer "F.Cu")
		(net "P12V_HSC_ADC_N")
	)
	(segment
		(start 287.575498 -404.047452)
		(end 287.6804 -404.152354)
		(width 0.254)
		(layer "F.Cu")
		(net "P12V_HSC_ADC_N")
	)
	(segment
		(start 286.771588 -400.46402)
		(end 292.670738 -394.56487)
		(width 0.254)
		(layer "F.Cu")
		(net "P12V_HSC_ADC_N")
	)
	(segment
		(start 287.56864 -404.571962)
		(end 287.211008 -404.571962)
		(width 0.254)
		(layer "F.Cu")
		(net "P12V_HSC_ADC_N")
	)
	(segment
		(start 287.6804 -404.152354)
		(end 287.6804 -404.460202)
		(width 0.254)
		(layer "F.Cu")
		(net "P12V_HSC_ADC_N")
	)
	(segment
		(start 287.211008 -404.571962)
		(end 286.771588 -404.132542)
		(width 0.254)
		(layer "F.Cu")
		(net "P12V_HSC_ADC_N")
	)
	(segment
		(start 286.771588 -404.132542)
		(end 286.771588 -400.46402)
		(width 0.254)
		(layer "F.Cu")
		(net "P12V_HSC_ADC_N")
	)
	(segment
		(start 292.98011 -393.776454)
		(end 292.98011 -392.569954)
		(width 0.254)
		(layer "F.Cu")
		(net "P12V_HSC_ADC_N")
	)
	(via
		(at 292.98011 -393.776454)
		(size 0.508)
		(drill 0.254)
		(layers "F.Cu" "B.Cu")
		(net "P12V_HSC_ADC_N")
	)
	(via
		(at 287.575498 -404.047452)
		(size 0.508)
		(drill 0.254)
		(layers "F.Cu" "B.Cu")
		(net "P12V_HSC_ADC_N")
	)
	(via
		(at 295.04513 -404.047452)
		(size 0.508)
		(drill 0.254)
		(layers "F.Cu" "B.Cu")
		(net "P12V_HSC_ADC_N")
	)
	(via
		(at 292.655498 -404.047452)
		(size 0.508)
		(drill 0.254)
		(layers "F.Cu" "B.Cu")
		(net "P12V_HSC_ADC_N")
	)
	(via
		(at 297.58513 -404.047452)
		(size 0.508)
		(drill 0.254)
		(layers "F.Cu" "B.Cu")
		(net "P12V_HSC_ADC_N")
	)
	(via
		(at 290.115498 -404.047452)
		(size 0.508)
		(drill 0.254)
		(layers "F.Cu" "B.Cu")
		(net "P12V_HSC_ADC_N")
	)
	(segment
		(start 289.988498 -403.431502)
		(end 289.988498 -403.920452)
		(width 0.254)
		(layer "B.Cu")
		(net "P12V_HSC_ADC_N")
	)
	(segment
		(start 289.988498 -403.920452)
		(end 290.115498 -404.047452)
		(width 0.254)
		(layer "B.Cu")
		(net "P12V_HSC_ADC_N")
	)
	(segment
		(start 297.45813 -403.920452)
		(end 297.58513 -404.047452)
		(width 0.254)
		(layer "B.Cu")
		(net "P12V_HSC_ADC_N")
	)
	(segment
		(start 292.528498 -403.920452)
		(end 292.655498 -404.047452)
		(width 0.254)
		(layer "B.Cu")
		(net "P12V_HSC_ADC_N")
	)
	(segment
		(start 287.448498 -403.920452)
		(end 287.575498 -404.047452)
		(width 0.254)
		(layer "B.Cu")
		(net "P12V_HSC_ADC_N")
	)
	(segment
		(start 297.45813 -403.431502)
		(end 297.45813 -403.920452)
		(width 0.254)
		(layer "B.Cu")
		(net "P12V_HSC_ADC_N")
	)
	(segment
		(start 292.528498 -403.431502)
		(end 292.528498 -403.920452)
		(width 0.254)
		(layer "B.Cu")
		(net "P12V_HSC_ADC_N")
	)
	(segment
		(start 287.448498 -403.431502)
		(end 287.448498 -403.920452)
		(width 0.254)
		(layer "B.Cu")
		(net "P12V_HSC_ADC_N")
	)
	(segment
		(start 294.91813 -403.431502)
		(end 294.91813 -403.920452)
		(width 0.254)
		(layer "B.Cu")
		(net "P12V_HSC_ADC_N")
	)
	(segment
		(start 294.91813 -403.920452)
		(end 295.04513 -404.047452)
		(width 0.254)
		(layer "B.Cu")
		(net "P12V_HSC_ADC_N")
	)
	(segment
		(start 290.115498 -404.047452)
		(end 290.305998 -404.237952)
		(width 0.254)
		(layer "In2.Cu")
		(net "P12V_HSC_ADC_N")
	)
	(segment
		(start 292.670738 -394.085826)
		(end 292.98011 -393.776454)
		(width 0.254)
		(layer "In2.Cu")
		(net "P12V_HSC_ADC_N")
	)
	(segment
		(start 290.305998 -404.237952)
		(end 290.305998 -404.597362)
		(width 0.254)
		(layer "In2.Cu")
		(net "P12V_HSC_ADC_N")
	)
	(segment
		(start 292.670738 -394.603478)
		(end 292.670738 -394.085826)
		(width 0.254)
		(layer "In2.Cu")
		(net "P12V_HSC_ADC_N")
	)
	(segment
		(start 289.428428 -404.587202)
		(end 289.428428 -397.845788)
		(width 0.254)
		(layer "In2.Cu")
		(net "P12V_HSC_ADC_N")
	)
	(segment
		(start 290.305998 -404.597362)
		(end 290.051998 -404.851362)
		(width 0.254)
		(layer "In2.Cu")
		(net "P12V_HSC_ADC_N")
	)
	(segment
		(start 290.051998 -404.851362)
		(end 289.692588 -404.851362)
		(width 0.254)
		(layer "In2.Cu")
		(net "P12V_HSC_ADC_N")
	)
	(segment
		(start 289.692588 -404.851362)
		(end 289.428428 -404.587202)
		(width 0.254)
		(layer "In2.Cu")
		(net "P12V_HSC_ADC_N")
	)
	(segment
		(start 289.428428 -397.845788)
		(end 292.670738 -394.603478)
		(width 0.254)
		(layer "In2.Cu")
		(net "P12V_HSC_ADC_N")
	)
	(segment
		(start 292.232588 -404.851362)
		(end 291.978588 -404.597362)
		(width 0.254)
		(layer "In6.Cu")
		(net "P12V_HSC_ADC_N")
	)
	(segment
		(start 292.670738 -394.085826)
		(end 292.98011 -393.776454)
		(width 0.254)
		(layer "In6.Cu")
		(net "P12V_HSC_ADC_N")
	)
	(segment
		(start 292.591998 -404.851362)
		(end 292.232588 -404.851362)
		(width 0.254)
		(layer "In6.Cu")
		(net "P12V_HSC_ADC_N")
	)
	(segment
		(start 292.670738 -395.601952)
		(end 292.670738 -394.085826)
		(width 0.254)
		(layer "In6.Cu")
		(net "P12V_HSC_ADC_N")
	)
	(segment
		(start 291.978588 -396.294102)
		(end 292.670738 -395.601952)
		(width 0.254)
		(layer "In6.Cu")
		(net "P12V_HSC_ADC_N")
	)
	(segment
		(start 292.845998 -404.237952)
		(end 292.845998 -404.597362)
		(width 0.254)
		(layer "In6.Cu")
		(net "P12V_HSC_ADC_N")
	)
	(segment
		(start 292.655498 -404.047452)
		(end 292.845998 -404.237952)
		(width 0.254)
		(layer "In6.Cu")
		(net "P12V_HSC_ADC_N")
	)
	(segment
		(start 291.978588 -404.597362)
		(end 291.978588 -396.294102)
		(width 0.254)
		(layer "In6.Cu")
		(net "P12V_HSC_ADC_N")
	)
	(segment
		(start 292.845998 -404.597362)
		(end 292.591998 -404.851362)
		(width 0.254)
		(layer "In6.Cu")
		(net "P12V_HSC_ADC_N")
	)
	(segment
		(start 294.62222 -404.851362)
		(end 294.36822 -404.597362)
		(width 0.254)
		(layer "In11.Cu")
		(net "P12V_HSC_ADC_N")
	)
	(segment
		(start 295.23563 -404.237952)
		(end 295.23563 -404.597362)
		(width 0.254)
		(layer "In11.Cu")
		(net "P12V_HSC_ADC_N")
	)
	(segment
		(start 292.670484 -397.386556)
		(end 292.670484 -394.08608)
		(width 0.254)
		(layer "In11.Cu")
		(net "P12V_HSC_ADC_N")
	)
	(segment
		(start 294.36822 -399.084292)
		(end 292.670484 -397.386556)
		(width 0.254)
		(layer "In11.Cu")
		(net "P12V_HSC_ADC_N")
	)
	(segment
		(start 295.23563 -404.597362)
		(end 294.98163 -404.851362)
		(width 0.254)
		(layer "In11.Cu")
		(net "P12V_HSC_ADC_N")
	)
	(segment
		(start 294.36822 -404.597362)
		(end 294.36822 -399.084292)
		(width 0.254)
		(layer "In11.Cu")
		(net "P12V_HSC_ADC_N")
	)
	(segment
		(start 292.670484 -394.08608)
		(end 292.98011 -393.776454)
		(width 0.254)
		(layer "In11.Cu")
		(net "P12V_HSC_ADC_N")
	)
	(segment
		(start 294.98163 -404.851362)
		(end 294.62222 -404.851362)
		(width 0.254)
		(layer "In11.Cu")
		(net "P12V_HSC_ADC_N")
	)
	(segment
		(start 295.04513 -404.047452)
		(end 295.23563 -404.237952)
		(width 0.254)
		(layer "In11.Cu")
		(net "P12V_HSC_ADC_N")
	)
	(segment
		(start 297.77563 -403.339554)
		(end 297.77563 -403.856952)
		(width 0.254)
		(layer "In13.Cu")
		(net "P12V_HSC_ADC_N")
	)
	(segment
		(start 300.33849 -396.376144)
		(end 299.556932 -397.157702)
		(width 0.254)
		(layer "In13.Cu")
		(net "P12V_HSC_ADC_N")
	)
	(segment
		(start 292.670738 -392.436096)
		(end 292.86073 -392.246104)
		(width 0.254)
		(layer "In13.Cu")
		(net "P12V_HSC_ADC_N")
	)
	(segment
		(start 298.252642 -402.862542)
		(end 297.77563 -403.339554)
		(width 0.254)
		(layer "In13.Cu")
		(net "P12V_HSC_ADC_N")
	)
	(segment
		(start 292.98011 -393.776454)
		(end 292.670738 -393.467082)
		(width 0.254)
		(layer "In13.Cu")
		(net "P12V_HSC_ADC_N")
	)
	(segment
		(start 300.33849 -393.309094)
		(end 300.33849 -396.376144)
		(width 0.254)
		(layer "In13.Cu")
		(net "P12V_HSC_ADC_N")
	)
	(segment
		(start 299.556932 -402.194522)
		(end 298.888912 -402.862542)
		(width 0.254)
		(layer "In13.Cu")
		(net "P12V_HSC_ADC_N")
	)
	(segment
		(start 292.86073 -392.246104)
		(end 299.2755 -392.246104)
		(width 0.254)
		(layer "In13.Cu")
		(net "P12V_HSC_ADC_N")
	)
	(segment
		(start 297.77563 -403.856952)
		(end 297.58513 -404.047452)
		(width 0.254)
		(layer "In13.Cu")
		(net "P12V_HSC_ADC_N")
	)
	(segment
		(start 298.888912 -402.862542)
		(end 298.252642 -402.862542)
		(width 0.254)
		(layer "In13.Cu")
		(net "P12V_HSC_ADC_N")
	)
	(segment
		(start 299.2755 -392.246104)
		(end 300.33849 -393.309094)
		(width 0.254)
		(layer "In13.Cu")
		(net "P12V_HSC_ADC_N")
	)
	(segment
		(start 299.556932 -397.157702)
		(end 299.556932 -402.194522)
		(width 0.254)
		(layer "In13.Cu")
		(net "P12V_HSC_ADC_N")
	)
	(segment
		(start 292.670738 -393.467082)
		(end 292.670738 -392.436096)
		(width 0.254)
		(layer "In13.Cu")
		(net "P12V_HSC_ADC_N")
	)
	(segment
		(start 38.060122 -393.680188)
		(end 37.634164 -393.680188)
		(width 0.10668)
		(layer "F.Cu")
		(net "NC_RES")
	)
	(segment
		(start 37.634164 -393.680188)
		(end 36.292536 -395.021816)
		(width 0.10668)
		(layer "F.Cu")
		(net "NC_RES")
	)
	(via
		(at 36.292536 -395.021816)
		(size 0.762)
		(drill 0.381)
		(layers "F.Cu" "B.Cu")
		(net "NC_RES")
	)
	(segment
		(start 182.955692 -116.975382)
		(end 183.355742 -117.375432)
		(width 0.12954)
		(layer "F.Cu")
		(net "NC_FPGA_PB43D")
	)
	(via
		(at 203.2 -363.4994)
		(size 0.508)
		(drill 0.254)
		(layers "F.Cu" "B.Cu")
		(net "NC_FPGA_PB43D")
	)
	(via
		(at 123.49734 -393.18184)
		(size 0.508)
		(drill 0.254)
		(layers "F.Cu" "B.Cu")
		(net "NC_FPGA_PB43D")
	)
	(via
		(at 183.355742 -117.375432)
		(size 0.4572)
		(drill 0.254)
		(layers "F.Cu" "B.Cu")
		(net "NC_FPGA_PB43D")
	)
	(via
		(at 210.62442 -148.024088)
		(size 0.508)
		(drill 0.254)
		(layers "F.Cu" "B.Cu")
		(net "NC_FPGA_PB43D")
	)
	(segment
		(start 198.467472 -364.495588)
		(end 202.203812 -364.495588)
		(width 0.12954)
		(layer "B.Cu")
		(net "NC_FPGA_PB43D")
	)
	(segment
		(start 127.5207 -388.447788)
		(end 174.515272 -388.447788)
		(width 0.12954)
		(layer "B.Cu")
		(net "NC_FPGA_PB43D")
	)
	(segment
		(start 174.515272 -388.447788)
		(end 198.467472 -364.495588)
		(width 0.12954)
		(layer "B.Cu")
		(net "NC_FPGA_PB43D")
	)
	(segment
		(start 123.405138 -392.56335)
		(end 127.5207 -388.447788)
		(width 0.12954)
		(layer "B.Cu")
		(net "NC_FPGA_PB43D")
	)
	(segment
		(start 123.49734 -393.18184)
		(end 123.405138 -393.089638)
		(width 0.12954)
		(layer "B.Cu")
		(net "NC_FPGA_PB43D")
	)
	(segment
		(start 202.203812 -364.495588)
		(end 203.2 -363.4994)
		(width 0.12954)
		(layer "B.Cu")
		(net "NC_FPGA_PB43D")
	)
	(segment
		(start 123.405138 -393.089638)
		(end 123.405138 -392.56335)
		(width 0.12954)
		(layer "B.Cu")
		(net "NC_FPGA_PB43D")
	)
	(segment
		(start 185.94959 -119.376698)
		(end 187.10402 -120.531128)
		(width 0.127)
		(layer "In2.Cu")
		(net "NC_FPGA_PB43D")
	)
	(segment
		(start 184.5564 -119.205248)
		(end 184.72785 -119.376698)
		(width 0.127)
		(layer "In2.Cu")
		(net "NC_FPGA_PB43D")
	)
	(segment
		(start 183.93664 -118.58244)
		(end 184.350152 -118.58244)
		(width 0.127)
		(layer "In2.Cu")
		(net "NC_FPGA_PB43D")
	)
	(segment
		(start 210.62442 -146.64182)
		(end 210.62442 -148.024088)
		(width 0.127)
		(layer "In2.Cu")
		(net "NC_FPGA_PB43D")
	)
	(segment
		(start 187.10402 -121.290588)
		(end 190.32728 -124.513848)
		(width 0.127)
		(layer "In2.Cu")
		(net "NC_FPGA_PB43D")
	)
	(segment
		(start 190.32728 -124.513848)
		(end 190.32728 -126.34468)
		(width 0.127)
		(layer "In2.Cu")
		(net "NC_FPGA_PB43D")
	)
	(segment
		(start 184.350152 -118.58244)
		(end 184.5564 -118.788688)
		(width 0.127)
		(layer "In2.Cu")
		(net "NC_FPGA_PB43D")
	)
	(segment
		(start 183.355742 -117.375432)
		(end 183.355742 -117.58803)
		(width 0.127)
		(layer "In2.Cu")
		(net "NC_FPGA_PB43D")
	)
	(segment
		(start 183.75884 -117.991128)
		(end 183.75884 -118.40464)
		(width 0.127)
		(layer "In2.Cu")
		(net "NC_FPGA_PB43D")
	)
	(segment
		(start 184.5564 -118.788688)
		(end 184.5564 -119.205248)
		(width 0.127)
		(layer "In2.Cu")
		(net "NC_FPGA_PB43D")
	)
	(segment
		(start 184.72785 -119.376698)
		(end 185.94959 -119.376698)
		(width 0.127)
		(layer "In2.Cu")
		(net "NC_FPGA_PB43D")
	)
	(segment
		(start 187.10402 -120.531128)
		(end 187.10402 -121.290588)
		(width 0.127)
		(layer "In2.Cu")
		(net "NC_FPGA_PB43D")
	)
	(segment
		(start 190.32728 -126.34468)
		(end 210.62442 -146.64182)
		(width 0.127)
		(layer "In2.Cu")
		(net "NC_FPGA_PB43D")
	)
	(segment
		(start 183.75884 -118.40464)
		(end 183.93664 -118.58244)
		(width 0.127)
		(layer "In2.Cu")
		(net "NC_FPGA_PB43D")
	)
	(segment
		(start 183.355742 -117.58803)
		(end 183.75884 -117.991128)
		(width 0.127)
		(layer "In2.Cu")
		(net "NC_FPGA_PB43D")
	)
	(segment
		(start 233.925364 -204.034644)
		(end 233.925364 -214.156544)
		(width 0.127)
		(layer "In11.Cu")
		(net "NC_FPGA_PB43D")
	)
	(segment
		(start 212.52942 -159.459168)
		(end 213.60892 -160.538668)
		(width 0.127)
		(layer "In11.Cu")
		(net "NC_FPGA_PB43D")
	)
	(segment
		(start 212.52942 -149.682708)
		(end 212.52942 -159.459168)
		(width 0.127)
		(layer "In11.Cu")
		(net "NC_FPGA_PB43D")
	)
	(segment
		(start 203.74102 -362.95838)
		(end 203.2 -363.4994)
		(width 0.127)
		(layer "In11.Cu")
		(net "NC_FPGA_PB43D")
	)
	(segment
		(start 230.7717 -266.611608)
		(end 222.42272 -274.960588)
		(width 0.127)
		(layer "In11.Cu")
		(net "NC_FPGA_PB43D")
	)
	(segment
		(start 219.52204 -344.541348)
		(end 203.74102 -360.322368)
		(width 0.127)
		(layer "In11.Cu")
		(net "NC_FPGA_PB43D")
	)
	(segment
		(start 222.42272 -274.960588)
		(end 222.42272 -280.985468)
		(width 0.127)
		(layer "In11.Cu")
		(net "NC_FPGA_PB43D")
	)
	(segment
		(start 231.04348 -265.29665)
		(end 231.04348 -265.686286)
		(width 0.127)
		(layer "In11.Cu")
		(net "NC_FPGA_PB43D")
	)
	(segment
		(start 210.62442 -148.024088)
		(end 210.8708 -148.024088)
		(width 0.127)
		(layer "In11.Cu")
		(net "NC_FPGA_PB43D")
	)
	(segment
		(start 226.538028 -196.647308)
		(end 233.925364 -204.034644)
		(width 0.127)
		(layer "In11.Cu")
		(net "NC_FPGA_PB43D")
	)
	(segment
		(start 231.04348 -265.686286)
		(end 230.7717 -265.958066)
		(width 0.127)
		(layer "In11.Cu")
		(net "NC_FPGA_PB43D")
	)
	(segment
		(start 219.52204 -283.886148)
		(end 219.52204 -344.541348)
		(width 0.127)
		(layer "In11.Cu")
		(net "NC_FPGA_PB43D")
	)
	(segment
		(start 203.74102 -360.322368)
		(end 203.74102 -362.95838)
		(width 0.127)
		(layer "In11.Cu")
		(net "NC_FPGA_PB43D")
	)
	(segment
		(start 213.629494 -160.538668)
		(end 226.538028 -173.447202)
		(width 0.127)
		(layer "In11.Cu")
		(net "NC_FPGA_PB43D")
	)
	(segment
		(start 230.7717 -265.958066)
		(end 230.7717 -266.611608)
		(width 0.127)
		(layer "In11.Cu")
		(net "NC_FPGA_PB43D")
	)
	(segment
		(start 210.8708 -148.024088)
		(end 212.52942 -149.682708)
		(width 0.127)
		(layer "In11.Cu")
		(net "NC_FPGA_PB43D")
	)
	(segment
		(start 213.60892 -160.538668)
		(end 213.629494 -160.538668)
		(width 0.127)
		(layer "In11.Cu")
		(net "NC_FPGA_PB43D")
	)
	(segment
		(start 222.42272 -280.985468)
		(end 219.52204 -283.886148)
		(width 0.127)
		(layer "In11.Cu")
		(net "NC_FPGA_PB43D")
	)
	(segment
		(start 230.7717 -265.02487)
		(end 231.04348 -265.29665)
		(width 0.127)
		(layer "In11.Cu")
		(net "NC_FPGA_PB43D")
	)
	(segment
		(start 226.538028 -173.447202)
		(end 226.538028 -196.647308)
		(width 0.127)
		(layer "In11.Cu")
		(net "NC_FPGA_PB43D")
	)
	(segment
		(start 233.925364 -214.156544)
		(end 230.7717 -217.310208)
		(width 0.127)
		(layer "In11.Cu")
		(net "NC_FPGA_PB43D")
	)
	(segment
		(start 230.7717 -217.310208)
		(end 230.7717 -265.02487)
		(width 0.127)
		(layer "In11.Cu")
		(net "NC_FPGA_PB43D")
	)
	(via
		(at 279.8064 -394.808456)
		(size 0.508)
		(drill 0.254)
		(layers "F.Cu" "B.Cu")
		(net "MB0_CM_GATE_G0")
	)
	(segment
		(start 295.5925 -415.036)
		(end 294.476424 -415.036)
		(width 0.12954)
		(layer "F.Cu")
		(net "HSC_TYPE_ADC_A1")
	)
	(segment
		(start 295.9354 -414.37814)
		(end 295.9354 -414.8963)
		(width 0.12954)
		(layer "F.Cu")
		(net "HSC_TYPE_ADC_A1")
	)
	(segment
		(start 296.968926 -413.555942)
		(end 296.757598 -413.555942)
		(width 0.12954)
		(layer "F.Cu")
		(net "HSC_TYPE_ADC_A1")
	)
	(segment
		(start 294.476424 -415.036)
		(end 294.445944 -415.00552)
		(width 0.12954)
		(layer "F.Cu")
		(net "HSC_TYPE_ADC_A1")
	)
	(segment
		(start 296.757598 -413.555942)
		(end 295.9354 -414.37814)
		(width 0.12954)
		(layer "F.Cu")
		(net "HSC_TYPE_ADC_A1")
	)
	(segment
		(start 295.9354 -414.8963)
		(end 295.7322 -414.8963)
		(width 0.12954)
		(layer "F.Cu")
		(net "HSC_TYPE_ADC_A1")
	)
	(segment
		(start 295.7322 -414.8963)
		(end 295.5925 -415.036)
		(width 0.12954)
		(layer "F.Cu")
		(net "HSC_TYPE_ADC_A1")
	)
	(via
		(at 295.9354 -414.8963)
		(size 0.762)
		(drill 0.381)
		(layers "F.Cu" "B.Cu")
		(net "HSC_TYPE_ADC_A1")
	)
	(segment
		(start 295.54678 -414.04286)
		(end 295.86682 -413.72282)
		(width 0.12954)
		(layer "F.Cu")
		(net "HSC_TYPE_ADC_A0")
	)
	(segment
		(start 296.533824 -413.055816)
		(end 296.968926 -413.055816)
		(width 0.12954)
		(layer "F.Cu")
		(net "HSC_TYPE_ADC_A0")
	)
	(segment
		(start 295.86682 -413.72282)
		(end 296.533824 -413.055816)
		(width 0.12954)
		(layer "F.Cu")
		(net "HSC_TYPE_ADC_A0")
	)
	(segment
		(start 294.445944 -414.04286)
		(end 295.54678 -414.04286)
		(width 0.12954)
		(layer "F.Cu")
		(net "HSC_TYPE_ADC_A0")
	)
	(via
		(at 295.86682 -413.72282)
		(size 0.508)
		(drill 0.254)
		(layers "F.Cu" "B.Cu")
		(net "HSC_TYPE_ADC_A0")
	)
	(segment
		(start 295.23055 -414.35909)
		(end 294.71874 -414.35909)
		(width 0.12954)
		(layer "B.Cu")
		(net "HSC_TYPE_ADC_A0")
	)
	(segment
		(start 295.86682 -413.72282)
		(end 295.23055 -414.35909)
		(width 0.12954)
		(layer "B.Cu")
		(net "HSC_TYPE_ADC_A0")
	)
	(segment
		(start 300.99762 -412.66364)
		(end 300.99762 -413.356044)
		(width 0.254)
		(layer "F.Cu")
		(net "HSC_TYPE_ADC")
	)
	(segment
		(start 300.331632 -413.055816)
		(end 300.63186 -413.356044)
		(width 0.254)
		(layer "F.Cu")
		(net "HSC_TYPE_ADC")
	)
	(segment
		(start 299.769022 -413.055816)
		(end 300.331632 -413.055816)
		(width 0.2286)
		(layer "F.Cu")
		(net "HSC_TYPE_ADC")
	)
	(segment
		(start 292.480238 -388.349998)
		(end 292.480238 -387.143498)
		(width 0.254)
		(layer "F.Cu")
		(net "HSC_TYPE_ADC")
	)
	(segment
		(start 300.63186 -413.356044)
		(end 300.99762 -413.356044)
		(width 0.254)
		(layer "F.Cu")
		(net "HSC_TYPE_ADC")
	)
	(via
		(at 292.480238 -387.143498)
		(size 0.508)
		(drill 0.254)
		(layers "F.Cu" "B.Cu")
		(net "HSC_TYPE_ADC")
	)
	(via
		(at 300.99762 -412.66364)
		(size 0.508)
		(drill 0.254)
		(layers "F.Cu" "B.Cu")
		(net "HSC_TYPE_ADC")
	)
	(segment
		(start 302.7426 -385.64312)
		(end 301.92472 -384.82524)
		(width 0.254)
		(layer "In13.Cu")
		(net "HSC_TYPE_ADC")
	)
	(segment
		(start 302.00346 -412.66364)
		(end 302.7426 -411.9245)
		(width 0.254)
		(layer "In13.Cu")
		(net "HSC_TYPE_ADC")
	)
	(segment
		(start 294.798496 -384.82524)
		(end 292.480238 -387.143498)
		(width 0.254)
		(layer "In13.Cu")
		(net "HSC_TYPE_ADC")
	)
	(segment
		(start 300.99762 -412.66364)
		(end 302.00346 -412.66364)
		(width 0.254)
		(layer "In13.Cu")
		(net "HSC_TYPE_ADC")
	)
	(segment
		(start 302.7426 -411.9245)
		(end 302.7426 -385.64312)
		(width 0.254)
		(layer "In13.Cu")
		(net "HSC_TYPE_ADC")
	)
	(segment
		(start 301.92472 -384.82524)
		(end 294.798496 -384.82524)
		(width 0.254)
		(layer "In13.Cu")
		(net "HSC_TYPE_ADC")
	)
	(segment
		(start 183.68645 -419.07333)
		(end 183.54802 -419.07333)
		(width 0.12954)
		(layer "F.Cu")
		(net "HSC_CSOUT")
	)
	(segment
		(start 184.33034 -419.71722)
		(end 183.68645 -419.07333)
		(width 0.12954)
		(layer "F.Cu")
		(net "HSC_CSOUT")
	)
	(segment
		(start 184.60974 -419.71722)
		(end 184.33034 -419.71722)
		(width 0.12954)
		(layer "F.Cu")
		(net "HSC_CSOUT")
	)
	(segment
		(start 293.479982 -388.349998)
		(end 293.479982 -387.143498)
		(width 0.10668)
		(layer "F.Cu")
		(net "HSC_CSOUT")
	)
	(segment
		(start 280.278078 -416.88385)
		(end 281.04592 -416.88385)
		(width 0.12954)
		(layer "F.Cu")
		(net "HSC_CSOUT")
	)
	(segment
		(start 282.546044 -424.158664)
		(end 281.758898 -424.94581)
		(width 0.12954)
		(layer "F.Cu")
		(net "HSC_CSOUT")
	)
	(segment
		(start 282.72994 -423.73042)
		(end 282.73756 -423.73804)
		(width 0.12954)
		(layer "F.Cu")
		(net "HSC_CSOUT")
	)
	(segment
		(start 282.72994 -423.28084)
		(end 282.72994 -423.73042)
		(width 0.12954)
		(layer "F.Cu")
		(net "HSC_CSOUT")
	)
	(segment
		(start 282.73756 -424.158664)
		(end 282.546044 -424.158664)
		(width 0.12954)
		(layer "F.Cu")
		(net "HSC_CSOUT")
	)
	(segment
		(start 277.7744 -427.27626)
		(end 277.33752 -426.83938)
		(width 0.12954)
		(layer "F.Cu")
		(net "HSC_CSOUT")
	)
	(segment
		(start 281.758898 -425.681902)
		(end 280.16454 -427.27626)
		(width 0.12954)
		(layer "F.Cu")
		(net "HSC_CSOUT")
	)
	(segment
		(start 281.758898 -424.94581)
		(end 281.758898 -425.681902)
		(width 0.12954)
		(layer "F.Cu")
		(net "HSC_CSOUT")
	)
	(segment
		(start 280.16454 -427.27626)
		(end 277.7744 -427.27626)
		(width 0.12954)
		(layer "F.Cu")
		(net "HSC_CSOUT")
	)
	(segment
		(start 277.33752 -426.83938)
		(end 277.33752 -425.12488)
		(width 0.12954)
		(layer "F.Cu")
		(net "HSC_CSOUT")
	)
	(segment
		(start 282.73756 -423.73804)
		(end 282.73756 -424.158664)
		(width 0.12954)
		(layer "F.Cu")
		(net "HSC_CSOUT")
	)
	(via
		(at 282.72994 -423.28084)
		(size 0.508)
		(drill 0.254)
		(layers "F.Cu" "B.Cu")
		(net "HSC_CSOUT")
	)
	(via
		(at 281.04592 -416.88385)
		(size 0.508)
		(drill 0.254)
		(layers "F.Cu" "B.Cu")
		(net "HSC_CSOUT")
	)
	(via
		(at 277.33752 -425.12488)
		(size 0.508)
		(drill 0.254)
		(layers "F.Cu" "B.Cu")
		(net "HSC_CSOUT")
	)
	(via
		(at 184.60974 -419.71722)
		(size 0.508)
		(drill 0.254)
		(layers "F.Cu" "B.Cu")
		(net "HSC_CSOUT")
	)
	(via
		(at 293.479982 -387.143498)
		(size 0.508)
		(drill 0.254)
		(layers "F.Cu" "B.Cu")
		(net "HSC_CSOUT")
	)
	(segment
		(start 231.78008 -426.86986)
		(end 231.78008 -435.97576)
		(width 0.127)
		(layer "In6.Cu")
		(net "HSC_CSOUT")
	)
	(segment
		(start 190.31966 -421.27932)
		(end 186.3471 -421.27932)
		(width 0.127)
		(layer "In6.Cu")
		(net "HSC_CSOUT")
	)
	(segment
		(start 231.78008 -435.97576)
		(end 230.54564 -437.2102)
		(width 0.127)
		(layer "In6.Cu")
		(net "HSC_CSOUT")
	)
	(segment
		(start 242.35156 -421.73906)
		(end 240.30686 -423.78376)
		(width 0.127)
		(layer "In6.Cu")
		(net "HSC_CSOUT")
	)
	(segment
		(start 199.3392 -437.2102)
		(end 192.84315 -430.71415)
		(width 0.127)
		(layer "In6.Cu")
		(net "HSC_CSOUT")
	)
	(segment
		(start 239.37976 -426.17644)
		(end 232.4735 -426.17644)
		(width 0.127)
		(layer "In6.Cu")
		(net "HSC_CSOUT")
	)
	(segment
		(start 299.72 -392.093196)
		(end 299.07484 -392.738356)
		(width 0.127)
		(layer "In6.Cu")
		(net "HSC_CSOUT")
	)
	(segment
		(start 278.89962 -424.79214)
		(end 278.56688 -425.12488)
		(width 0.127)
		(layer "In6.Cu")
		(net "HSC_CSOUT")
	)
	(segment
		(start 298.54398 -405.06396)
		(end 296.783252 -405.06396)
		(width 0.127)
		(layer "In6.Cu")
		(net "HSC_CSOUT")
	)
	(segment
		(start 291.33038 -409.01112)
		(end 288.2646 -412.0769)
		(width 0.127)
		(layer "In6.Cu")
		(net "HSC_CSOUT")
	)
	(segment
		(start 240.30686 -425.24934)
		(end 239.37976 -426.17644)
		(width 0.127)
		(layer "In6.Cu")
		(net "HSC_CSOUT")
	)
	(segment
		(start 230.54564 -437.2102)
		(end 199.3392 -437.2102)
		(width 0.127)
		(layer "In6.Cu")
		(net "HSC_CSOUT")
	)
	(segment
		(start 193.48196 -424.44162)
		(end 190.31966 -421.27932)
		(width 0.127)
		(layer "In6.Cu")
		(net "HSC_CSOUT")
	)
	(segment
		(start 299.07484 -392.738356)
		(end 299.07484 -404.5331)
		(width 0.127)
		(layer "In6.Cu")
		(net "HSC_CSOUT")
	)
	(segment
		(start 277.33752 -425.12488)
		(end 277.02256 -425.12488)
		(width 0.127)
		(layer "In6.Cu")
		(net "HSC_CSOUT")
	)
	(segment
		(start 296.783252 -405.06396)
		(end 296.399712 -405.4475)
		(width 0.127)
		(layer "In6.Cu")
		(net "HSC_CSOUT")
	)
	(segment
		(start 192.84315 -429.42891)
		(end 193.48196 -428.7901)
		(width 0.127)
		(layer "In6.Cu")
		(net "HSC_CSOUT")
	)
	(segment
		(start 288.2646 -412.0769)
		(end 288.2646 -413.29356)
		(width 0.127)
		(layer "In6.Cu")
		(net "HSC_CSOUT")
	)
	(segment
		(start 288.2646 -413.29356)
		(end 282.72994 -418.82822)
		(width 0.127)
		(layer "In6.Cu")
		(net "HSC_CSOUT")
	)
	(segment
		(start 278.56688 -425.12488)
		(end 277.33752 -425.12488)
		(width 0.127)
		(layer "In6.Cu")
		(net "HSC_CSOUT")
	)
	(segment
		(start 240.30686 -423.78376)
		(end 240.30686 -425.24934)
		(width 0.127)
		(layer "In6.Cu")
		(net "HSC_CSOUT")
	)
	(segment
		(start 282.72994 -418.82822)
		(end 282.72994 -423.28084)
		(width 0.127)
		(layer "In6.Cu")
		(net "HSC_CSOUT")
	)
	(segment
		(start 299.72 -388.08152)
		(end 299.72 -392.093196)
		(width 0.127)
		(layer "In6.Cu")
		(net "HSC_CSOUT")
	)
	(segment
		(start 232.4735 -426.17644)
		(end 231.78008 -426.86986)
		(width 0.127)
		(layer "In6.Cu")
		(net "HSC_CSOUT")
	)
	(segment
		(start 294.26916 -386.35432)
		(end 297.9928 -386.35432)
		(width 0.127)
		(layer "In6.Cu")
		(net "HSC_CSOUT")
	)
	(segment
		(start 293.479982 -387.143498)
		(end 294.26916 -386.35432)
		(width 0.127)
		(layer "In6.Cu")
		(net "HSC_CSOUT")
	)
	(segment
		(start 273.63674 -421.73906)
		(end 242.35156 -421.73906)
		(width 0.127)
		(layer "In6.Cu")
		(net "HSC_CSOUT")
	)
	(segment
		(start 186.3471 -421.27932)
		(end 184.785 -419.71722)
		(width 0.127)
		(layer "In6.Cu")
		(net "HSC_CSOUT")
	)
	(segment
		(start 192.84315 -430.71415)
		(end 192.84315 -429.42891)
		(width 0.127)
		(layer "In6.Cu")
		(net "HSC_CSOUT")
	)
	(segment
		(start 296.085006 -405.4475)
		(end 292.521386 -409.01112)
		(width 0.127)
		(layer "In6.Cu")
		(net "HSC_CSOUT")
	)
	(segment
		(start 299.07484 -404.5331)
		(end 298.54398 -405.06396)
		(width 0.127)
		(layer "In6.Cu")
		(net "HSC_CSOUT")
	)
	(segment
		(start 297.9928 -386.35432)
		(end 299.72 -388.08152)
		(width 0.127)
		(layer "In6.Cu")
		(net "HSC_CSOUT")
	)
	(segment
		(start 184.785 -419.71722)
		(end 184.60974 -419.71722)
		(width 0.127)
		(layer "In6.Cu")
		(net "HSC_CSOUT")
	)
	(segment
		(start 292.521386 -409.01112)
		(end 291.33038 -409.01112)
		(width 0.127)
		(layer "In6.Cu")
		(net "HSC_CSOUT")
	)
	(segment
		(start 193.48196 -428.7901)
		(end 193.48196 -424.44162)
		(width 0.127)
		(layer "In6.Cu")
		(net "HSC_CSOUT")
	)
	(segment
		(start 277.02256 -425.12488)
		(end 273.63674 -421.73906)
		(width 0.127)
		(layer "In6.Cu")
		(net "HSC_CSOUT")
	)
	(segment
		(start 296.399712 -405.4475)
		(end 296.085006 -405.4475)
		(width 0.127)
		(layer "In6.Cu")
		(net "HSC_CSOUT")
	)
	(segment
		(start 278.89962 -419.03015)
		(end 278.89962 -424.79214)
		(width 0.127)
		(layer "In6.Cu")
		(net "HSC_CSOUT")
	)
	(segment
		(start 281.04592 -416.88385)
		(end 278.89962 -419.03015)
		(width 0.127)
		(layer "In6.Cu")
		(net "HSC_CSOUT")
	)
	(segment
		(start 42.25417 -393.680188)
		(end 44.273978 -395.699996)
		(width 0.10668)
		(layer "F.Cu")
		(net "FM_P2E_EN2_N")
	)
	(segment
		(start 41.859962 -393.680188)
		(end 42.25417 -393.680188)
		(width 0.10668)
		(layer "F.Cu")
		(net "FM_P2E_EN2_N")
	)
	(segment
		(start 44.466256 -395.699996)
		(end 45.685456 -395.699996)
		(width 0.10668)
		(layer "F.Cu")
		(net "FM_P2E_EN2_N")
	)
	(segment
		(start 44.273978 -395.699996)
		(end 44.466256 -395.699996)
		(width 0.10668)
		(layer "F.Cu")
		(net "FM_P2E_EN2_N")
	)
	(via
		(at 44.466256 -395.699996)
		(size 0.762)
		(drill 0.381)
		(layers "F.Cu" "B.Cu")
		(net "FM_P2E_EN2_N")
	)
	(segment
		(start 30.545024 -390.943084)
		(end 33.156144 -390.943084)
		(width 0.10668)
		(layer "F.Cu")
		(net "FM_P2E_BUF2_VOD_SEL")
	)
	(segment
		(start 33.893252 -391.680192)
		(end 35.368738 -391.680192)
		(width 0.10668)
		(layer "F.Cu")
		(net "FM_P2E_BUF2_VOD_SEL")
	)
	(segment
		(start 30.33014 -391.157968)
		(end 30.545024 -390.943084)
		(width 0.10668)
		(layer "F.Cu")
		(net "FM_P2E_BUF2_VOD_SEL")
	)
	(segment
		(start 33.156144 -390.943084)
		(end 33.849056 -391.635996)
		(width 0.10668)
		(layer "F.Cu")
		(net "FM_P2E_BUF2_VOD_SEL")
	)
	(segment
		(start 35.368738 -391.680192)
		(end 38.060122 -391.680192)
		(width 0.10668)
		(layer "F.Cu")
		(net "FM_P2E_BUF2_VOD_SEL")
	)
	(segment
		(start 30.33014 -391.65149)
		(end 30.33014 -391.157968)
		(width 0.10668)
		(layer "F.Cu")
		(net "FM_P2E_BUF2_VOD_SEL")
	)
	(segment
		(start 33.849056 -391.635996)
		(end 33.893252 -391.680192)
		(width 0.10668)
		(layer "F.Cu")
		(net "FM_P2E_BUF2_VOD_SEL")
	)
	(via
		(at 35.368738 -391.680192)
		(size 0.762)
		(drill 0.381)
		(layers "F.Cu" "B.Cu")
		(net "FM_P2E_BUF2_VOD_SEL")
	)
	(segment
		(start 46.382178 -395.126718)
		(end 45.685456 -394.429996)
		(width 0.10668)
		(layer "F.Cu")
		(net "FM_P2E_BUF2_VODB_DB")
	)
	(segment
		(start 41.859962 -393.180316)
		(end 42.890948 -393.180316)
		(width 0.10668)
		(layer "F.Cu")
		(net "FM_P2E_BUF2_VODB_DB")
	)
	(segment
		(start 43.846242 -394.13561)
		(end 44.18711 -394.476478)
		(width 0.10668)
		(layer "F.Cu")
		(net "FM_P2E_BUF2_VODB_DB")
	)
	(segment
		(start 42.890948 -393.180316)
		(end 43.846242 -394.13561)
		(width 0.10668)
		(layer "F.Cu")
		(net "FM_P2E_BUF2_VODB_DB")
	)
	(segment
		(start 48.244506 -395.126718)
		(end 46.382178 -395.126718)
		(width 0.10668)
		(layer "F.Cu")
		(net "FM_P2E_BUF2_VODB_DB")
	)
	(segment
		(start 45.638974 -394.476478)
		(end 45.685456 -394.429996)
		(width 0.10668)
		(layer "F.Cu")
		(net "FM_P2E_BUF2_VODB_DB")
	)
	(segment
		(start 44.18711 -394.476478)
		(end 45.638974 -394.476478)
		(width 0.10668)
		(layer "F.Cu")
		(net "FM_P2E_BUF2_VODB_DB")
	)
	(segment
		(start 48.924464 -394.44676)
		(end 48.244506 -395.126718)
		(width 0.10668)
		(layer "F.Cu")
		(net "FM_P2E_BUF2_VODB_DB")
	)
	(via
		(at 43.846242 -394.13561)
		(size 0.762)
		(drill 0.381)
		(layers "F.Cu" "B.Cu")
		(net "FM_P2E_BUF2_VODB_DB")
	)
	(segment
		(start 44.480734 -392.68019)
		(end 45.052488 -392.68019)
		(width 0.10668)
		(layer "F.Cu")
		(net "FM_P2E_BUF2_VODA_DB")
	)
	(segment
		(start 41.859962 -392.68019)
		(end 44.480734 -392.68019)
		(width 0.10668)
		(layer "F.Cu")
		(net "FM_P2E_BUF2_VODA_DB")
	)
	(segment
		(start 48.507142 -393.784328)
		(end 46.156626 -393.784328)
		(width 0.10668)
		(layer "F.Cu")
		(net "FM_P2E_BUF2_VODA_DB")
	)
	(segment
		(start 48.947832 -393.30122)
		(end 48.947832 -393.343638)
		(width 0.10668)
		(layer "F.Cu")
		(net "FM_P2E_BUF2_VODA_DB")
	)
	(segment
		(start 48.947832 -393.343638)
		(end 48.507142 -393.784328)
		(width 0.10668)
		(layer "F.Cu")
		(net "FM_P2E_BUF2_VODA_DB")
	)
	(segment
		(start 46.156626 -393.784328)
		(end 45.687742 -393.315444)
		(width 0.10668)
		(layer "F.Cu")
		(net "FM_P2E_BUF2_VODA_DB")
	)
	(segment
		(start 45.052488 -392.68019)
		(end 45.687742 -393.315444)
		(width 0.10668)
		(layer "F.Cu")
		(net "FM_P2E_BUF2_VODA_DB")
	)
	(via
		(at 44.480734 -392.68019)
		(size 0.762)
		(drill 0.381)
		(layers "F.Cu" "B.Cu")
		(net "FM_P2E_BUF2_VODA_DB")
	)
	(segment
		(start 30.348174 -393.198858)
		(end 30.348174 -393.045442)
		(width 0.10668)
		(layer "F.Cu")
		(net "FM_P2E_BUF2_SD_TH")
	)
	(segment
		(start 34.122614 -393.42568)
		(end 35.421062 -393.42568)
		(width 0.10668)
		(layer "F.Cu")
		(net "FM_P2E_BUF2_SD_TH")
	)
	(segment
		(start 37.653468 -393.180316)
		(end 38.060122 -393.180316)
		(width 0.10668)
		(layer "F.Cu")
		(net "FM_P2E_BUF2_SD_TH")
	)
	(segment
		(start 35.421062 -393.42568)
		(end 37.408104 -393.42568)
		(width 0.10668)
		(layer "F.Cu")
		(net "FM_P2E_BUF2_SD_TH")
	)
	(segment
		(start 33.872424 -393.17549)
		(end 34.122614 -393.42568)
		(width 0.10668)
		(layer "F.Cu")
		(net "FM_P2E_BUF2_SD_TH")
	)
	(segment
		(start 33.264856 -392.567922)
		(end 33.872424 -393.17549)
		(width 0.10668)
		(layer "F.Cu")
		(net "FM_P2E_BUF2_SD_TH")
	)
	(segment
		(start 37.408104 -393.42568)
		(end 37.653468 -393.180316)
		(width 0.10668)
		(layer "F.Cu")
		(net "FM_P2E_BUF2_SD_TH")
	)
	(segment
		(start 30.348174 -393.045442)
		(end 30.825694 -392.567922)
		(width 0.10668)
		(layer "F.Cu")
		(net "FM_P2E_BUF2_SD_TH")
	)
	(segment
		(start 30.825694 -392.567922)
		(end 33.264856 -392.567922)
		(width 0.10668)
		(layer "F.Cu")
		(net "FM_P2E_BUF2_SD_TH")
	)
	(via
		(at 35.421062 -393.42568)
		(size 0.762)
		(drill 0.381)
		(layers "F.Cu" "B.Cu")
		(net "FM_P2E_BUF2_SD_TH")
	)
	(segment
		(start 30.304232 -390.084818)
		(end 30.304232 -389.579612)
		(width 0.10668)
		(layer "F.Cu")
		(net "FM_P2E_BUF2_RXDET")
	)
	(segment
		(start 33.03143 -389.328152)
		(end 33.810448 -390.10717)
		(width 0.10668)
		(layer "F.Cu")
		(net "FM_P2E_BUF2_RXDET")
	)
	(segment
		(start 30.555692 -389.328152)
		(end 33.03143 -389.328152)
		(width 0.10668)
		(layer "F.Cu")
		(net "FM_P2E_BUF2_RXDET")
	)
	(segment
		(start 30.304232 -389.579612)
		(end 30.555692 -389.328152)
		(width 0.10668)
		(layer "F.Cu")
		(net "FM_P2E_BUF2_RXDET")
	)
	(segment
		(start 33.810448 -390.10717)
		(end 33.828482 -390.125204)
		(width 0.10668)
		(layer "F.Cu")
		(net "FM_P2E_BUF2_RXDET")
	)
	(segment
		(start 35.253422 -390.125204)
		(end 35.68319 -390.125204)
		(width 0.10668)
		(layer "F.Cu")
		(net "FM_P2E_BUF2_RXDET")
	)
	(segment
		(start 36.738306 -391.18032)
		(end 38.060122 -391.18032)
		(width 0.10668)
		(layer "F.Cu")
		(net "FM_P2E_BUF2_RXDET")
	)
	(segment
		(start 33.828482 -390.125204)
		(end 35.253422 -390.125204)
		(width 0.10668)
		(layer "F.Cu")
		(net "FM_P2E_BUF2_RXDET")
	)
	(segment
		(start 35.68319 -390.125204)
		(end 36.738306 -391.18032)
		(width 0.10668)
		(layer "F.Cu")
		(net "FM_P2E_BUF2_RXDET")
	)
	(via
		(at 35.253422 -390.125204)
		(size 0.762)
		(drill 0.381)
		(layers "F.Cu" "B.Cu")
		(net "FM_P2E_BUF2_RXDET")
	)
	(segment
		(start 46.011592 -391.63498)
		(end 45.693584 -391.316972)
		(width 0.10668)
		(layer "F.Cu")
		(net "FM_P2E_BUF2_EQB1")
	)
	(segment
		(start 42.149522 -391.680192)
		(end 42.708576 -391.121138)
		(width 0.10668)
		(layer "F.Cu")
		(net "FM_P2E_BUF2_EQB1")
	)
	(segment
		(start 41.859962 -391.680192)
		(end 42.149522 -391.680192)
		(width 0.10668)
		(layer "F.Cu")
		(net "FM_P2E_BUF2_EQB1")
	)
	(segment
		(start 48.418496 -391.63498)
		(end 46.011592 -391.63498)
		(width 0.10668)
		(layer "F.Cu")
		(net "FM_P2E_BUF2_EQB1")
	)
	(segment
		(start 44.323254 -391.121138)
		(end 45.662088 -391.121138)
		(width 0.10668)
		(layer "F.Cu")
		(net "FM_P2E_BUF2_EQB1")
	)
	(segment
		(start 45.693584 -391.316972)
		(end 45.693584 -391.089642)
		(width 0.10668)
		(layer "F.Cu")
		(net "FM_P2E_BUF2_EQB1")
	)
	(segment
		(start 42.708576 -391.121138)
		(end 44.323254 -391.121138)
		(width 0.10668)
		(layer "F.Cu")
		(net "FM_P2E_BUF2_EQB1")
	)
	(segment
		(start 48.975264 -391.078212)
		(end 48.418496 -391.63498)
		(width 0.10668)
		(layer "F.Cu")
		(net "FM_P2E_BUF2_EQB1")
	)
	(segment
		(start 45.662088 -391.121138)
		(end 45.693584 -391.089642)
		(width 0.10668)
		(layer "F.Cu")
		(net "FM_P2E_BUF2_EQB1")
	)
	(via
		(at 44.323254 -391.121138)
		(size 0.762)
		(drill 0.381)
		(layers "F.Cu" "B.Cu")
		(net "FM_P2E_BUF2_EQB1")
	)
	(segment
		(start 48.400208 -390.5758)
		(end 45.990764 -390.5758)
		(width 0.10668)
		(layer "F.Cu")
		(net "FM_P2E_BUF2_EQB0")
	)
	(segment
		(start 45.990764 -390.5758)
		(end 45.696378 -390.281414)
		(width 0.10668)
		(layer "F.Cu")
		(net "FM_P2E_BUF2_EQB0")
	)
	(segment
		(start 45.614844 -389.925814)
		(end 45.696378 -390.007348)
		(width 0.10668)
		(layer "F.Cu")
		(net "FM_P2E_BUF2_EQB0")
	)
	(segment
		(start 45.696378 -390.281414)
		(end 45.696378 -390.007348)
		(width 0.10668)
		(layer "F.Cu")
		(net "FM_P2E_BUF2_EQB0")
	)
	(segment
		(start 42.114724 -391.18032)
		(end 43.36923 -389.925814)
		(width 0.10668)
		(layer "F.Cu")
		(net "FM_P2E_BUF2_EQB0")
	)
	(segment
		(start 43.57878 -389.925814)
		(end 45.614844 -389.925814)
		(width 0.10668)
		(layer "F.Cu")
		(net "FM_P2E_BUF2_EQB0")
	)
	(segment
		(start 41.859962 -391.18032)
		(end 42.114724 -391.18032)
		(width 0.10668)
		(layer "F.Cu")
		(net "FM_P2E_BUF2_EQB0")
	)
	(segment
		(start 48.99025 -389.985758)
		(end 48.400208 -390.5758)
		(width 0.10668)
		(layer "F.Cu")
		(net "FM_P2E_BUF2_EQB0")
	)
	(segment
		(start 43.36923 -389.925814)
		(end 43.57878 -389.925814)
		(width 0.10668)
		(layer "F.Cu")
		(net "FM_P2E_BUF2_EQB0")
	)
	(via
		(at 43.57878 -389.925814)
		(size 0.762)
		(drill 0.381)
		(layers "F.Cu" "B.Cu")
		(net "FM_P2E_BUF2_EQB0")
	)
	(segment
		(start 40.587676 -395.676882)
		(end 40.209978 -395.299184)
		(width 0.10668)
		(layer "F.Cu")
		(net "FM_P2E_BUF2_EQA1")
	)
	(segment
		(start 41.075102 -397.668496)
		(end 40.413178 -397.006572)
		(width 0.10668)
		(layer "F.Cu")
		(net "FM_P2E_BUF2_EQA1")
	)
	(segment
		(start 40.968422 -399.753836)
		(end 41.075102 -399.647156)
		(width 0.10668)
		(layer "F.Cu")
		(net "FM_P2E_BUF2_EQA1")
	)
	(segment
		(start 40.587676 -396.832074)
		(end 40.587676 -395.792452)
		(width 0.10668)
		(layer "F.Cu")
		(net "FM_P2E_BUF2_EQA1")
	)
	(segment
		(start 41.075102 -399.647156)
		(end 41.075102 -397.668496)
		(width 0.10668)
		(layer "F.Cu")
		(net "FM_P2E_BUF2_EQA1")
	)
	(segment
		(start 40.413178 -397.006572)
		(end 40.587676 -396.832074)
		(width 0.10668)
		(layer "F.Cu")
		(net "FM_P2E_BUF2_EQA1")
	)
	(segment
		(start 40.587676 -395.792452)
		(end 40.587676 -395.676882)
		(width 0.10668)
		(layer "F.Cu")
		(net "FM_P2E_BUF2_EQA1")
	)
	(segment
		(start 40.389556 -399.753836)
		(end 40.968422 -399.753836)
		(width 0.10668)
		(layer "F.Cu")
		(net "FM_P2E_BUF2_EQA1")
	)
	(segment
		(start 40.209978 -395.299184)
		(end 40.209978 -394.330174)
		(width 0.10668)
		(layer "F.Cu")
		(net "FM_P2E_BUF2_EQA1")
	)
	(via
		(at 40.587676 -395.792452)
		(size 0.762)
		(drill 0.381)
		(layers "F.Cu" "B.Cu")
		(net "FM_P2E_BUF2_EQA1")
	)
	(segment
		(start 38.894258 -398.975834)
		(end 38.894258 -397.525494)
		(width 0.10668)
		(layer "F.Cu")
		(net "FM_P2E_BUF2_EQA0")
	)
	(segment
		(start 39.710106 -395.351508)
		(end 39.28999 -395.771624)
		(width 0.10668)
		(layer "F.Cu")
		(net "FM_P2E_BUF2_EQA0")
	)
	(segment
		(start 39.710106 -394.330174)
		(end 39.710106 -395.351508)
		(width 0.10668)
		(layer "F.Cu")
		(net "FM_P2E_BUF2_EQA0")
	)
	(segment
		(start 39.28999 -396.919958)
		(end 39.394892 -397.02486)
		(width 0.10668)
		(layer "F.Cu")
		(net "FM_P2E_BUF2_EQA0")
	)
	(segment
		(start 38.894258 -397.525494)
		(end 39.394892 -397.02486)
		(width 0.10668)
		(layer "F.Cu")
		(net "FM_P2E_BUF2_EQA0")
	)
	(segment
		(start 39.26332 -399.344896)
		(end 38.894258 -398.975834)
		(width 0.10668)
		(layer "F.Cu")
		(net "FM_P2E_BUF2_EQA0")
	)
	(segment
		(start 39.28999 -395.771624)
		(end 39.28999 -396.919958)
		(width 0.10668)
		(layer "F.Cu")
		(net "FM_P2E_BUF2_EQA0")
	)
	(segment
		(start 39.26332 -399.753836)
		(end 39.26332 -399.344896)
		(width 0.10668)
		(layer "F.Cu")
		(net "FM_P2E_BUF2_EQA0")
	)
	(via
		(at 39.28999 -395.771624)
		(size 0.762)
		(drill 0.381)
		(layers "F.Cu" "B.Cu")
		(net "FM_P2E_BUF2_EQA0")
	)
	(segment
		(start 186.44997 -418.46881)
		(end 185.59272 -418.46881)
		(width 0.12954)
		(layer "F.Cu")
		(net "A_HSC_LOW_GATE")
	)
	(segment
		(start 278.02205 -417.68395)
		(end 277.230078 -417.68395)
		(width 0.12954)
		(layer "F.Cu")
		(net "A_HSC_LOW_GATE")
	)
	(segment
		(start 184.58688 -418.46881)
		(end 185.59272 -418.46881)
		(width 0.12954)
		(layer "F.Cu")
		(net "A_HSC_LOW_GATE")
	)
	(segment
		(start 275.436076 -418.466016)
		(end 275.436076 -419.15334)
		(width 0.12954)
		(layer "F.Cu")
		(net "A_HSC_LOW_GATE")
	)
	(segment
		(start 277.524718 -418.181282)
		(end 278.02205 -417.68395)
		(width 0.12954)
		(layer "F.Cu")
		(net "A_HSC_LOW_GATE")
	)
	(segment
		(start 275.960078 -418.629338)
		(end 275.960078 -417.6903)
		(width 0.12954)
		(layer "F.Cu")
		(net "A_HSC_LOW_GATE")
	)
	(segment
		(start 277.524718 -419.26129)
		(end 277.524718 -418.181282)
		(width 0.12954)
		(layer "F.Cu")
		(net "A_HSC_LOW_GATE")
	)
	(segment
		(start 275.966428 -417.68395)
		(end 277.230078 -417.68395)
		(width 0.12954)
		(layer "F.Cu")
		(net "A_HSC_LOW_GATE")
	)
	(segment
		(start 275.336 -418.36594)
		(end 275.436076 -418.466016)
		(width 0.12954)
		(layer "F.Cu")
		(net "A_HSC_LOW_GATE")
	)
	(segment
		(start 186.7662 -418.78504)
		(end 186.44997 -418.46881)
		(width 0.12954)
		(layer "F.Cu")
		(net "A_HSC_LOW_GATE")
	)
	(segment
		(start 275.960078 -417.6903)
		(end 275.966428 -417.68395)
		(width 0.12954)
		(layer "F.Cu")
		(net "A_HSC_LOW_GATE")
	)
	(segment
		(start 275.436076 -419.15334)
		(end 275.960078 -418.629338)
		(width 0.12954)
		(layer "F.Cu")
		(net "A_HSC_LOW_GATE")
	)
	(segment
		(start 278.02205 -417.68395)
		(end 278.246078 -417.68395)
		(width 0.12954)
		(layer "F.Cu")
		(net "A_HSC_LOW_GATE")
	)
	(via
		(at 275.336 -418.36594)
		(size 0.508)
		(drill 0.254)
		(layers "F.Cu" "B.Cu")
		(net "A_HSC_LOW_GATE")
	)
	(via
		(at 186.7662 -418.78504)
		(size 0.508)
		(drill 0.254)
		(layers "F.Cu" "B.Cu")
		(net "A_HSC_LOW_GATE")
	)
	(via
		(at 275.960078 -417.6903)
		(size 0.762)
		(drill 0.381)
		(layers "F.Cu" "B.Cu")
		(net "A_HSC_LOW_GATE")
	)
	(segment
		(start 192.70726 -431.0888)
		(end 192.70726 -429.83658)
		(width 0.127)
		(layer "In11.Cu")
		(net "A_HSC_LOW_GATE")
	)
	(segment
		(start 192.70726 -429.83658)
		(end 193.80708 -428.73676)
		(width 0.127)
		(layer "In11.Cu")
		(net "A_HSC_LOW_GATE")
	)
	(segment
		(start 239.522 -437.51246)
		(end 199.13092 -437.51246)
		(width 0.127)
		(layer "In11.Cu")
		(net "A_HSC_LOW_GATE")
	)
	(segment
		(start 193.80708 -425.63288)
		(end 192.80378 -424.62958)
		(width 0.127)
		(layer "In11.Cu")
		(net "A_HSC_LOW_GATE")
	)
	(segment
		(start 189.2554 -418.78504)
		(end 186.7662 -418.78504)
		(width 0.127)
		(layer "In11.Cu")
		(net "A_HSC_LOW_GATE")
	)
	(segment
		(start 243.03482 -421.78986)
		(end 239.90554 -424.91914)
		(width 0.127)
		(layer "In11.Cu")
		(net "A_HSC_LOW_GATE")
	)
	(segment
		(start 239.90554 -424.91914)
		(end 239.90554 -437.12892)
		(width 0.127)
		(layer "In11.Cu")
		(net "A_HSC_LOW_GATE")
	)
	(segment
		(start 271.91208 -421.78986)
		(end 243.03482 -421.78986)
		(width 0.127)
		(layer "In11.Cu")
		(net "A_HSC_LOW_GATE")
	)
	(segment
		(start 192.80378 -422.33342)
		(end 189.2554 -418.78504)
		(width 0.127)
		(layer "In11.Cu")
		(net "A_HSC_LOW_GATE")
	)
	(segment
		(start 239.90554 -437.12892)
		(end 239.522 -437.51246)
		(width 0.127)
		(layer "In11.Cu")
		(net "A_HSC_LOW_GATE")
	)
	(segment
		(start 193.80708 -428.73676)
		(end 193.80708 -425.63288)
		(width 0.127)
		(layer "In11.Cu")
		(net "A_HSC_LOW_GATE")
	)
	(segment
		(start 199.13092 -437.51246)
		(end 192.70726 -431.0888)
		(width 0.127)
		(layer "In11.Cu")
		(net "A_HSC_LOW_GATE")
	)
	(segment
		(start 275.336 -418.36594)
		(end 271.91208 -421.78986)
		(width 0.127)
		(layer "In11.Cu")
		(net "A_HSC_LOW_GATE")
	)
	(segment
		(start 192.80378 -424.62958)
		(end 192.80378 -422.33342)
		(width 0.127)
		(layer "In11.Cu")
		(net "A_HSC_LOW_GATE")
	)
	(segment
		(start 272.68424 -422.6433)
		(end 273.401028 -422.6433)
		(width 0.12954)
		(layer "F.Cu")
		(net "A_HSC_LOW_DRAIN")
	)
	(segment
		(start 272.277078 -421.5003)
		(end 272.27276 -421.504618)
		(width 0.12954)
		(layer "F.Cu")
		(net "A_HSC_LOW_DRAIN")
	)
	(segment
		(start 272.27276 -420.57066)
		(end 272.74012 -420.1033)
		(width 0.12954)
		(layer "F.Cu")
		(net "A_HSC_LOW_DRAIN")
	)
	(segment
		(start 272.277078 -421.5003)
		(end 272.27276 -421.495982)
		(width 0.12954)
		(layer "F.Cu")
		(net "A_HSC_LOW_DRAIN")
	)
	(segment
		(start 272.27276 -422.23182)
		(end 272.68424 -422.6433)
		(width 0.12954)
		(layer "F.Cu")
		(net "A_HSC_LOW_DRAIN")
	)
	(segment
		(start 272.27276 -421.495982)
		(end 272.27276 -420.57066)
		(width 0.12954)
		(layer "F.Cu")
		(net "A_HSC_LOW_DRAIN")
	)
	(segment
		(start 272.27276 -421.504618)
		(end 272.27276 -422.23182)
		(width 0.12954)
		(layer "F.Cu")
		(net "A_HSC_LOW_DRAIN")
	)
	(segment
		(start 272.74012 -420.1033)
		(end 273.43608 -420.1033)
		(width 0.12954)
		(layer "F.Cu")
		(net "A_HSC_LOW_DRAIN")
	)
	(via
		(at 272.277078 -421.5003)
		(size 0.762)
		(drill 0.381)
		(layers "F.Cu" "B.Cu")
		(net "A_HSC_LOW_DRAIN")
	)
	(segment
		(start 280.811478 -417.86429)
		(end 280.811478 -418.9095)
		(width 0.12954)
		(layer "F.Cu")
		(net "A_HSC_LOW")
	)
	(segment
		(start 280.278078 -417.68395)
		(end 280.631138 -417.68395)
		(width 0.12954)
		(layer "F.Cu")
		(net "A_HSC_LOW")
	)
	(segment
		(start 279.262078 -417.68395)
		(end 280.278078 -417.68395)
		(width 0.12954)
		(layer "F.Cu")
		(net "A_HSC_LOW")
	)
	(segment
		(start 279.424638 -419.26129)
		(end 279.424638 -419.05174)
		(width 0.12954)
		(layer "F.Cu")
		(net "A_HSC_LOW")
	)
	(segment
		(start 280.631138 -417.68395)
		(end 280.811478 -417.86429)
		(width 0.12954)
		(layer "F.Cu")
		(net "A_HSC_LOW")
	)
	(segment
		(start 279.566878 -418.9095)
		(end 280.811478 -418.9095)
		(width 0.12954)
		(layer "F.Cu")
		(net "A_HSC_LOW")
	)
	(segment
		(start 279.424638 -419.05174)
		(end 279.566878 -418.9095)
		(width 0.12954)
		(layer "F.Cu")
		(net "A_HSC_LOW")
	)
	(via
		(at 280.811478 -418.9095)
		(size 0.762)
		(drill 0.381)
		(layers "F.Cu" "B.Cu")
		(net "A_HSC_LOW")
	)
	(segment
		(start 280.786078 -424.14825)
		(end 280.809446 -424.171618)
		(width 0.12954)
		(layer "F.Cu")
		(net "A_HSC_HIGH")
	)
	(segment
		(start 279.977088 -421.96131)
		(end 280.786078 -422.7703)
		(width 0.12954)
		(layer "F.Cu")
		(net "A_HSC_HIGH")
	)
	(segment
		(start 280.809446 -424.171618)
		(end 281.314144 -424.171618)
		(width 0.12954)
		(layer "F.Cu")
		(net "A_HSC_HIGH")
	)
	(segment
		(start 280.786078 -422.7703)
		(end 280.786078 -424.14825)
		(width 0.12954)
		(layer "F.Cu")
		(net "A_HSC_HIGH")
	)
	(segment
		(start 281.314144 -424.171618)
		(end 281.316938 -424.168824)
		(width 0.12954)
		(layer "F.Cu")
		(net "A_HSC_HIGH")
	)
	(segment
		(start 279.424638 -421.96131)
		(end 279.977088 -421.96131)
		(width 0.12954)
		(layer "F.Cu")
		(net "A_HSC_HIGH")
	)
	(segment
		(start 281.735784 -424.168824)
		(end 281.758898 -424.14571)
		(width 0.12954)
		(layer "F.Cu")
		(net "A_HSC_HIGH")
	)
	(segment
		(start 281.316938 -424.168824)
		(end 281.735784 -424.168824)
		(width 0.12954)
		(layer "F.Cu")
		(net "A_HSC_HIGH")
	)
	(via
		(at 280.786078 -422.7703)
		(size 0.762)
		(drill 0.381)
		(layers "F.Cu" "B.Cu")
		(net "A_HSC_HIGH")
	)
	(segment
		(start 140.793724 -45.703236)
		(end 140.156692 -45.066204)
		(width 0.12954)
		(layer "F.Cu")
		(net "NC_Q95_S2")
	)
	(segment
		(start 139.026138 -45.066204)
		(end 138.67638 -45.415962)
		(width 0.12954)
		(layer "F.Cu")
		(net "NC_Q95_S2")
	)
	(segment
		(start 140.156692 -45.066204)
		(end 139.026138 -45.066204)
		(width 0.12954)
		(layer "F.Cu")
		(net "NC_Q95_S2")
	)
	(segment
		(start 138.67638 -45.415962)
		(end 137.02284 -45.415962)
		(width 0.12954)
		(layer "F.Cu")
		(net "NC_Q95_S2")
	)
	(via
		(at 140.793724 -45.703236)
		(size 0.762)
		(drill 0.381)
		(layers "F.Cu" "B.Cu")
		(net "NC_Q95_S2")
	)
	(segment
		(start 137.02284 -46.065948)
		(end 139.161012 -46.065948)
		(width 0.12954)
		(layer "F.Cu")
		(net "NC_Q95_G2")
	)
	(segment
		(start 139.161012 -46.065948)
		(end 139.523724 -45.703236)
		(width 0.12954)
		(layer "F.Cu")
		(net "NC_Q95_G2")
	)
	(via
		(at 139.523724 -45.703236)
		(size 0.762)
		(drill 0.381)
		(layers "F.Cu" "B.Cu")
		(net "NC_Q95_G2")
	)
	(segment
		(start 135.12292 -45.415962)
		(end 133.78942 -45.415962)
		(width 0.12954)
		(layer "F.Cu")
		(net "NC_Q95_D2")
	)
	(via
		(at 133.78942 -45.415962)
		(size 0.762)
		(drill 0.381)
		(layers "F.Cu" "B.Cu")
		(net "NC_Q95_D2")
	)
	(segment
		(start 130.455162 -27.915362)
		(end 129.821178 -27.281378)
		(width 0.13208)
		(layer "B.Cu")
		(net "USB3_PCH_RX_C_DP<4>")
	)
	(segment
		(start 131.053332 -27.915362)
		(end 130.455162 -27.915362)
		(width 0.13208)
		(layer "B.Cu")
		(net "USB3_PCH_RX_C_DP<4>")
	)
	(segment
		(start 129.249424 -27.326844)
		(end 129.065782 -27.326844)
		(width 0.12954)
		(layer "B.Cu")
		(net "USB3_PCH_RX_C_DP<4>")
	)
	(segment
		(start 129.29489 -27.281378)
		(end 129.249424 -27.326844)
		(width 0.12954)
		(layer "B.Cu")
		(net "USB3_PCH_RX_C_DP<4>")
	)
	(segment
		(start 131.34721 -28.20924)
		(end 131.053332 -27.915362)
		(width 0.13208)
		(layer "B.Cu")
		(net "USB3_PCH_RX_C_DP<4>")
	)
	(segment
		(start 129.821178 -27.281378)
		(end 129.29489 -27.281378)
		(width 0.13208)
		(layer "B.Cu")
		(net "USB3_PCH_RX_C_DP<4>")
	)
	(segment
		(start 129.249424 -26.976832)
		(end 129.065782 -26.976832)
		(width 0.12954)
		(layer "B.Cu")
		(net "USB3_PCH_RX_C_DN<4>")
	)
	(segment
		(start 131.34721 -27.3177)
		(end 131.008628 -27.656282)
		(width 0.13208)
		(layer "B.Cu")
		(net "USB3_PCH_RX_C_DN<4>")
	)
	(segment
		(start 129.92862 -27.022298)
		(end 129.29489 -27.022298)
		(width 0.13208)
		(layer "B.Cu")
		(net "USB3_PCH_RX_C_DN<4>")
	)
	(segment
		(start 130.562604 -27.656282)
		(end 129.92862 -27.022298)
		(width 0.13208)
		(layer "B.Cu")
		(net "USB3_PCH_RX_C_DN<4>")
	)
	(segment
		(start 131.008628 -27.656282)
		(end 130.562604 -27.656282)
		(width 0.13208)
		(layer "B.Cu")
		(net "USB3_PCH_RX_C_DN<4>")
	)
	(segment
		(start 129.29489 -27.022298)
		(end 129.249424 -26.976832)
		(width 0.12954)
		(layer "B.Cu")
		(net "USB3_PCH_RX_C_DN<4>")
	)
	(segment
		(start 119.634 -55.321962)
		(end 118.4402 -55.321962)
		(width 0.12954)
		(layer "F.Cu")
		(net "JTAG_BMC_TMS_R")
	)
	(segment
		(start 143.36395 -25.110948)
		(end 142.494 -25.110948)
		(width 0.12954)
		(layer "F.Cu")
		(net "JTAG_BMC_TMS_R")
	)
	(via
		(at 142.494 -25.110948)
		(size 0.508)
		(drill 0.254)
		(layers "F.Cu" "B.Cu")
		(net "JTAG_BMC_TMS_R")
	)
	(via
		(at 118.4402 -55.321962)
		(size 0.508)
		(drill 0.254)
		(layers "F.Cu" "B.Cu")
		(net "JTAG_BMC_TMS_R")
	)
	(via
		(at 141.540992 -50.522886)
		(size 0.508)
		(drill 0.254)
		(layers "F.Cu" "B.Cu")
		(net "JTAG_BMC_TMS_R")
	)
	(segment
		(start 141.351 -32.858202)
		(end 142.01013 -33.517332)
		(width 0.127)
		(layer "In2.Cu")
		(net "JTAG_BMC_TMS_R")
	)
	(segment
		(start 141.351 -25.618694)
		(end 141.351 -32.858202)
		(width 0.127)
		(layer "In2.Cu")
		(net "JTAG_BMC_TMS_R")
	)
	(segment
		(start 142.01013 -50.053748)
		(end 141.540992 -50.522886)
		(width 0.127)
		(layer "In2.Cu")
		(net "JTAG_BMC_TMS_R")
	)
	(segment
		(start 142.494 -25.110948)
		(end 141.858746 -25.110948)
		(width 0.127)
		(layer "In2.Cu")
		(net "JTAG_BMC_TMS_R")
	)
	(segment
		(start 142.01013 -33.517332)
		(end 142.01013 -50.053748)
		(width 0.127)
		(layer "In2.Cu")
		(net "JTAG_BMC_TMS_R")
	)
	(segment
		(start 141.858746 -25.110948)
		(end 141.351 -25.618694)
		(width 0.127)
		(layer "In2.Cu")
		(net "JTAG_BMC_TMS_R")
	)
	(segment
		(start 118.4402 -55.321962)
		(end 120.932194 -52.829968)
		(width 0.127)
		(layer "In6.Cu")
		(net "JTAG_BMC_TMS_R")
	)
	(segment
		(start 120.932194 -52.829968)
		(end 139.23391 -52.829968)
		(width 0.127)
		(layer "In6.Cu")
		(net "JTAG_BMC_TMS_R")
	)
	(segment
		(start 139.23391 -52.829968)
		(end 141.540992 -50.522886)
		(width 0.127)
		(layer "In6.Cu")
		(net "JTAG_BMC_TMS_R")
	)
	(segment
		(start 127.7874 -56.621934)
		(end 125.476 -56.621934)
		(width 0.12954)
		(layer "F.Cu")
		(net "JTAG_BMC_TDO_R")
	)
	(segment
		(start 128.75895 -56.733948)
		(end 127.899414 -56.733948)
		(width 0.12954)
		(layer "F.Cu")
		(net "JTAG_BMC_TDO_R")
	)
	(segment
		(start 127.899414 -56.733948)
		(end 127.7874 -56.621934)
		(width 0.12954)
		(layer "F.Cu")
		(net "JTAG_BMC_TDO_R")
	)
	(via
		(at 127.7874 -56.621934)
		(size 0.508)
		(drill 0.254)
		(layers "F.Cu" "B.Cu")
		(net "JTAG_BMC_TDO_R")
	)
	(segment
		(start 125.476 -54.671976)
		(end 127.7874 -54.671976)
		(width 0.12954)
		(layer "F.Cu")
		(net "JTAG_BMC_TDI_R")
	)
	(segment
		(start 143.36395 -26.126948)
		(end 141.986 -26.126948)
		(width 0.12954)
		(layer "F.Cu")
		(net "JTAG_BMC_TDI_R")
	)
	(via
		(at 127.7874 -54.671976)
		(size 0.508)
		(drill 0.254)
		(layers "F.Cu" "B.Cu")
		(net "JTAG_BMC_TDI_R")
	)
	(via
		(at 142.0876 -51.095148)
		(size 0.508)
		(drill 0.254)
		(layers "F.Cu" "B.Cu")
		(net "JTAG_BMC_TDI_R")
	)
	(via
		(at 141.986 -26.126948)
		(size 0.508)
		(drill 0.254)
		(layers "F.Cu" "B.Cu")
		(net "JTAG_BMC_TDI_R")
	)
	(segment
		(start 142.44193 -32.551878)
		(end 141.986 -32.095948)
		(width 0.127)
		(layer "In2.Cu")
		(net "JTAG_BMC_TDI_R")
	)
	(segment
		(start 141.986 -32.095948)
		(end 141.986 -26.126948)
		(width 0.127)
		(layer "In2.Cu")
		(net "JTAG_BMC_TDI_R")
	)
	(segment
		(start 142.44193 -50.740818)
		(end 142.44193 -32.551878)
		(width 0.127)
		(layer "In2.Cu")
		(net "JTAG_BMC_TDI_R")
	)
	(segment
		(start 142.0876 -51.095148)
		(end 142.44193 -50.740818)
		(width 0.127)
		(layer "In2.Cu")
		(net "JTAG_BMC_TDI_R")
	)
	(segment
		(start 138.7348 -54.447948)
		(end 142.0876 -51.095148)
		(width 0.127)
		(layer "In6.Cu")
		(net "JTAG_BMC_TDI_R")
	)
	(segment
		(start 128.011428 -54.447948)
		(end 138.7348 -54.447948)
		(width 0.127)
		(layer "In6.Cu")
		(net "JTAG_BMC_TDI_R")
	)
	(segment
		(start 127.7874 -54.671976)
		(end 128.011428 -54.447948)
		(width 0.127)
		(layer "In6.Cu")
		(net "JTAG_BMC_TDI_R")
	)
	(segment
		(start 119.634 -57.27192)
		(end 118.4402 -57.27192)
		(width 0.12954)
		(layer "F.Cu")
		(net "JTAG_BMC_TCK_R")
	)
	(via
		(at 148.9964 -15.392908)
		(size 0.508)
		(drill 0.254)
		(layers "F.Cu" "B.Cu")
		(net "JTAG_BMC_TCK_R")
	)
	(via
		(at 118.4402 -57.27192)
		(size 0.508)
		(drill 0.254)
		(layers "F.Cu" "B.Cu")
		(net "JTAG_BMC_TCK_R")
	)
	(via
		(at 140.937488 -49.94529)
		(size 0.508)
		(drill 0.254)
		(layers "F.Cu" "B.Cu")
		(net "JTAG_BMC_TCK_R")
	)
	(segment
		(start 149.8854 -15.223998)
		(end 149.16531 -15.223998)
		(width 0.12954)
		(layer "B.Cu")
		(net "JTAG_BMC_TCK_R")
	)
	(segment
		(start 149.16531 -15.223998)
		(end 148.9964 -15.392908)
		(width 0.12954)
		(layer "B.Cu")
		(net "JTAG_BMC_TCK_R")
	)
	(segment
		(start 114.935 -57.622948)
		(end 114.3 -56.987948)
		(width 0.127)
		(layer "In6.Cu")
		(net "JTAG_BMC_TCK_R")
	)
	(segment
		(start 115.943126 -52.169568)
		(end 138.71321 -52.169568)
		(width 0.127)
		(layer "In6.Cu")
		(net "JTAG_BMC_TCK_R")
	)
	(segment
		(start 118.4402 -57.27192)
		(end 118.089172 -57.622948)
		(width 0.127)
		(layer "In6.Cu")
		(net "JTAG_BMC_TCK_R")
	)
	(segment
		(start 138.71321 -52.169568)
		(end 140.937488 -49.94529)
		(width 0.127)
		(layer "In6.Cu")
		(net "JTAG_BMC_TCK_R")
	)
	(segment
		(start 118.089172 -57.622948)
		(end 114.935 -57.622948)
		(width 0.127)
		(layer "In6.Cu")
		(net "JTAG_BMC_TCK_R")
	)
	(segment
		(start 114.3 -56.987948)
		(end 114.3 -53.812694)
		(width 0.127)
		(layer "In6.Cu")
		(net "JTAG_BMC_TCK_R")
	)
	(segment
		(start 114.3 -53.812694)
		(end 115.943126 -52.169568)
		(width 0.127)
		(layer "In6.Cu")
		(net "JTAG_BMC_TCK_R")
	)
	(segment
		(start 149.733 -23.586948)
		(end 149.733 -27.752548)
		(width 0.127)
		(layer "In15.Cu")
		(net "JTAG_BMC_TCK_R")
	)
	(segment
		(start 150.6982 -22.621748)
		(end 149.733 -23.586948)
		(width 0.127)
		(layer "In15.Cu")
		(net "JTAG_BMC_TCK_R")
	)
	(segment
		(start 154.290268 -46.96968)
		(end 153.1112 -48.148748)
		(width 0.127)
		(layer "In15.Cu")
		(net "JTAG_BMC_TCK_R")
	)
	(segment
		(start 153.3652 -31.384748)
		(end 155.067 -31.384748)
		(width 0.127)
		(layer "In15.Cu")
		(net "JTAG_BMC_TCK_R")
	)
	(segment
		(start 160.995106 -46.96968)
		(end 154.290268 -46.96968)
		(width 0.127)
		(layer "In15.Cu")
		(net "JTAG_BMC_TCK_R")
	)
	(segment
		(start 149.733 -27.752548)
		(end 153.3652 -31.384748)
		(width 0.127)
		(layer "In15.Cu")
		(net "JTAG_BMC_TCK_R")
	)
	(segment
		(start 150.6982 -17.033748)
		(end 150.6982 -22.621748)
		(width 0.127)
		(layer "In15.Cu")
		(net "JTAG_BMC_TCK_R")
	)
	(segment
		(start 147.9042 -48.148748)
		(end 147.193 -47.437548)
		(width 0.127)
		(layer "In15.Cu")
		(net "JTAG_BMC_TCK_R")
	)
	(segment
		(start 147.193 -47.437548)
		(end 143.44523 -47.437548)
		(width 0.127)
		(layer "In15.Cu")
		(net "JTAG_BMC_TCK_R")
	)
	(segment
		(start 155.067 -31.384748)
		(end 164.1348 -40.452548)
		(width 0.127)
		(layer "In15.Cu")
		(net "JTAG_BMC_TCK_R")
	)
	(segment
		(start 164.1348 -40.452548)
		(end 164.1348 -43.829986)
		(width 0.127)
		(layer "In15.Cu")
		(net "JTAG_BMC_TCK_R")
	)
	(segment
		(start 143.44523 -47.437548)
		(end 140.937488 -49.94529)
		(width 0.127)
		(layer "In15.Cu")
		(net "JTAG_BMC_TCK_R")
	)
	(segment
		(start 149.05736 -15.392908)
		(end 150.6982 -17.033748)
		(width 0.127)
		(layer "In15.Cu")
		(net "JTAG_BMC_TCK_R")
	)
	(segment
		(start 148.9964 -15.392908)
		(end 149.05736 -15.392908)
		(width 0.127)
		(layer "In15.Cu")
		(net "JTAG_BMC_TCK_R")
	)
	(segment
		(start 153.1112 -48.148748)
		(end 147.9042 -48.148748)
		(width 0.127)
		(layer "In15.Cu")
		(net "JTAG_BMC_TCK_R")
	)
	(segment
		(start 164.1348 -43.829986)
		(end 160.995106 -46.96968)
		(width 0.127)
		(layer "In15.Cu")
		(net "JTAG_BMC_TCK_R")
	)
	(segment
		(start 119.634 -54.671976)
		(end 117.3226 -54.671976)
		(width 0.12954)
		(layer "F.Cu")
		(net "JTAG_BMC_SW_TMS_R")
	)
	(segment
		(start 117.3226 -54.671976)
		(end 116.844572 -54.193948)
		(width 0.12954)
		(layer "F.Cu")
		(net "JTAG_BMC_SW_TMS_R")
	)
	(segment
		(start 116.844572 -54.193948)
		(end 116.35105 -54.193948)
		(width 0.12954)
		(layer "F.Cu")
		(net "JTAG_BMC_SW_TMS_R")
	)
	(via
		(at 117.3226 -54.671976)
		(size 0.508)
		(drill 0.254)
		(layers "F.Cu" "B.Cu")
		(net "JTAG_BMC_SW_TMS_R")
	)
	(segment
		(start 125.476 -55.971948)
		(end 126.6698 -55.971948)
		(width 0.12954)
		(layer "F.Cu")
		(net "JTAG_BMC_SW_TDO_R")
	)
	(segment
		(start 124.26569 -79.649828)
		(end 123.62434 -79.649828)
		(width 0.12954)
		(layer "F.Cu")
		(net "JTAG_BMC_SW_TDO_R")
	)
	(via
		(at 126.6698 -55.971948)
		(size 0.508)
		(drill 0.254)
		(layers "F.Cu" "B.Cu")
		(net "JTAG_BMC_SW_TDO_R")
	)
	(via
		(at 123.62434 -79.649828)
		(size 0.508)
		(drill 0.254)
		(layers "F.Cu" "B.Cu")
		(net "JTAG_BMC_SW_TDO_R")
	)
	(segment
		(start 128.3716 -63.363348)
		(end 128.3716 -76.985368)
		(width 0.127)
		(layer "In11.Cu")
		(net "JTAG_BMC_SW_TDO_R")
	)
	(segment
		(start 129.667 -57.427368)
		(end 129.667 -62.067948)
		(width 0.127)
		(layer "In11.Cu")
		(net "JTAG_BMC_SW_TDO_R")
	)
	(segment
		(start 125.70714 -79.649828)
		(end 123.62434 -79.649828)
		(width 0.127)
		(layer "In11.Cu")
		(net "JTAG_BMC_SW_TDO_R")
	)
	(segment
		(start 128.21158 -55.971948)
		(end 129.667 -57.427368)
		(width 0.127)
		(layer "In11.Cu")
		(net "JTAG_BMC_SW_TDO_R")
	)
	(segment
		(start 128.3716 -76.985368)
		(end 125.70714 -79.649828)
		(width 0.127)
		(layer "In11.Cu")
		(net "JTAG_BMC_SW_TDO_R")
	)
	(segment
		(start 126.6698 -55.971948)
		(end 128.21158 -55.971948)
		(width 0.127)
		(layer "In11.Cu")
		(net "JTAG_BMC_SW_TDO_R")
	)
	(segment
		(start 129.667 -62.067948)
		(end 128.3716 -63.363348)
		(width 0.127)
		(layer "In11.Cu")
		(net "JTAG_BMC_SW_TDO_R")
	)
	(segment
		(start 125.476 -54.02199)
		(end 126.6698 -54.02199)
		(width 0.12954)
		(layer "F.Cu")
		(net "JTAG_BMC_SW_TDI_R")
	)
	(segment
		(start 126.6698 -54.02199)
		(end 127.386842 -53.304948)
		(width 0.12954)
		(layer "F.Cu")
		(net "JTAG_BMC_SW_TDI_R")
	)
	(segment
		(start 127.386842 -53.304948)
		(end 128.75895 -53.304948)
		(width 0.12954)
		(layer "F.Cu")
		(net "JTAG_BMC_SW_TDI_R")
	)
	(via
		(at 126.6698 -54.02199)
		(size 0.508)
		(drill 0.254)
		(layers "F.Cu" "B.Cu")
		(net "JTAG_BMC_SW_TDI_R")
	)
	(segment
		(start 117.3226 -56.621934)
		(end 117.180614 -56.479948)
		(width 0.12954)
		(layer "F.Cu")
		(net "JTAG_BMC_SW_TCK_R")
	)
	(segment
		(start 119.634 -56.621934)
		(end 117.3226 -56.621934)
		(width 0.12954)
		(layer "F.Cu")
		(net "JTAG_BMC_SW_TCK_R")
	)
	(segment
		(start 117.180614 -56.479948)
		(end 116.35105 -56.479948)
		(width 0.12954)
		(layer "F.Cu")
		(net "JTAG_BMC_SW_TCK_R")
	)
	(via
		(at 117.3226 -56.621934)
		(size 0.508)
		(drill 0.254)
		(layers "F.Cu" "B.Cu")
		(net "JTAG_BMC_SW_TCK_R")
	)
	(segment
		(start 120.269 -62.575948)
		(end 120.269 -60.435998)
		(width 0.12954)
		(layer "F.Cu")
		(net "PU_JTAG_SW_PU")
	)
	(segment
		(start 115.55095 -54.193948)
		(end 114.935 -54.193948)
		(width 0.12954)
		(layer "F.Cu")
		(net "JTAG_BMC_SW_TMS")
	)
	(segment
		(start 117.800882 -76.99883)
		(end 118.063772 -76.99883)
		(width 0.12954)
		(layer "F.Cu")
		(net "JTAG_BMC_SW_TMS")
	)
	(segment
		(start 117.280944 -76.478892)
		(end 117.800882 -76.99883)
		(width 0.12954)
		(layer "F.Cu")
		(net "JTAG_BMC_SW_TMS")
	)
	(via
		(at 114.935 -54.193948)
		(size 0.508)
		(drill 0.254)
		(layers "F.Cu" "B.Cu")
		(net "JTAG_BMC_SW_TMS")
	)
	(via
		(at 117.280944 -76.478892)
		(size 0.508)
		(drill 0.254)
		(layers "F.Cu" "B.Cu")
		(net "JTAG_BMC_SW_TMS")
	)
	(segment
		(start 114.37366 -58.382408)
		(end 114.37366 -54.755288)
		(width 0.127)
		(layer "In11.Cu")
		(net "JTAG_BMC_SW_TMS")
	)
	(segment
		(start 115.6462 -59.654948)
		(end 114.37366 -58.382408)
		(width 0.127)
		(layer "In11.Cu")
		(net "JTAG_BMC_SW_TMS")
	)
	(segment
		(start 114.37366 -54.755288)
		(end 114.935 -54.193948)
		(width 0.127)
		(layer "In11.Cu")
		(net "JTAG_BMC_SW_TMS")
	)
	(segment
		(start 115.6462 -72.761348)
		(end 115.6462 -59.654948)
		(width 0.127)
		(layer "In11.Cu")
		(net "JTAG_BMC_SW_TMS")
	)
	(segment
		(start 117.280944 -74.396092)
		(end 115.6462 -72.761348)
		(width 0.127)
		(layer "In11.Cu")
		(net "JTAG_BMC_SW_TMS")
	)
	(segment
		(start 117.280944 -76.478892)
		(end 117.280944 -74.396092)
		(width 0.127)
		(layer "In11.Cu")
		(net "JTAG_BMC_SW_TMS")
	)
	(segment
		(start 126.259082 -78.321154)
		(end 126.547372 -78.321154)
		(width 0.12954)
		(layer "F.Cu")
		(net "JTAG_BMC_SW_TDO")
	)
	(segment
		(start 125.739144 -78.841092)
		(end 126.259082 -78.321154)
		(width 0.12954)
		(layer "F.Cu")
		(net "JTAG_BMC_SW_TDO")
	)
	(segment
		(start 125.739144 -78.976474)
		(end 125.739144 -78.841092)
		(width 0.12954)
		(layer "F.Cu")
		(net "JTAG_BMC_SW_TDO")
	)
	(segment
		(start 125.06579 -79.649828)
		(end 125.739144 -78.976474)
		(width 0.12954)
		(layer "F.Cu")
		(net "JTAG_BMC_SW_TDO")
	)
	(via
		(at 125.739144 -78.841092)
		(size 0.508)
		(drill 0.254)
		(layers "F.Cu" "B.Cu")
		(net "JTAG_BMC_SW_TDO")
	)
	(segment
		(start 126.284482 -76.82103)
		(end 126.547372 -76.82103)
		(width 0.12954)
		(layer "F.Cu")
		(net "JTAG_BMC_SW_TDI")
	)
	(segment
		(start 129.55905 -53.304948)
		(end 130.175 -53.304948)
		(width 0.12954)
		(layer "F.Cu")
		(net "JTAG_BMC_SW_TDI")
	)
	(segment
		(start 125.764544 -76.301092)
		(end 126.284482 -76.82103)
		(width 0.12954)
		(layer "F.Cu")
		(net "JTAG_BMC_SW_TDI")
	)
	(via
		(at 130.175 -53.304948)
		(size 0.508)
		(drill 0.254)
		(layers "F.Cu" "B.Cu")
		(net "JTAG_BMC_SW_TDI")
	)
	(via
		(at 125.764544 -76.301092)
		(size 0.508)
		(drill 0.254)
		(layers "F.Cu" "B.Cu")
		(net "JTAG_BMC_SW_TDI")
	)
	(segment
		(start 125.94336 -53.680868)
		(end 126.31928 -53.304948)
		(width 0.127)
		(layer "In11.Cu")
		(net "JTAG_BMC_SW_TDI")
	)
	(segment
		(start 127.6096 -66.004948)
		(end 127.6096 -62.195202)
		(width 0.127)
		(layer "In11.Cu")
		(net "JTAG_BMC_SW_TDI")
	)
	(segment
		(start 126.31928 -53.304948)
		(end 130.175 -53.304948)
		(width 0.127)
		(layer "In11.Cu")
		(net "JTAG_BMC_SW_TDI")
	)
	(segment
		(start 127.6096 -62.195202)
		(end 125.94336 -60.528962)
		(width 0.127)
		(layer "In11.Cu")
		(net "JTAG_BMC_SW_TDI")
	)
	(segment
		(start 125.94336 -60.528962)
		(end 125.94336 -53.680868)
		(width 0.127)
		(layer "In11.Cu")
		(net "JTAG_BMC_SW_TDI")
	)
	(segment
		(start 125.764544 -76.301092)
		(end 125.764544 -67.850004)
		(width 0.127)
		(layer "In11.Cu")
		(net "JTAG_BMC_SW_TDI")
	)
	(segment
		(start 125.764544 -67.850004)
		(end 127.6096 -66.004948)
		(width 0.127)
		(layer "In11.Cu")
		(net "JTAG_BMC_SW_TDI")
	)
	(segment
		(start 115.55095 -56.479948)
		(end 114.935 -56.479948)
		(width 0.12954)
		(layer "F.Cu")
		(net "JTAG_BMC_SW_TCK")
	)
	(segment
		(start 117.652292 -78.622144)
		(end 117.775482 -78.498954)
		(width 0.12954)
		(layer "F.Cu")
		(net "JTAG_BMC_SW_TCK")
	)
	(segment
		(start 117.652292 -79.143098)
		(end 117.652292 -78.622144)
		(width 0.12954)
		(layer "F.Cu")
		(net "JTAG_BMC_SW_TCK")
	)
	(segment
		(start 117.775482 -78.498954)
		(end 118.063772 -78.498954)
		(width 0.12954)
		(layer "F.Cu")
		(net "JTAG_BMC_SW_TCK")
	)
	(via
		(at 117.652292 -79.143098)
		(size 0.508)
		(drill 0.254)
		(layers "F.Cu" "B.Cu")
		(net "JTAG_BMC_SW_TCK")
	)
	(via
		(at 114.935 -56.479948)
		(size 0.508)
		(drill 0.254)
		(layers "F.Cu" "B.Cu")
		(net "JTAG_BMC_SW_TCK")
	)
	(segment
		(start 118.0846 -69.281548)
		(end 117.3226 -68.519548)
		(width 0.127)
		(layer "In11.Cu")
		(net "JTAG_BMC_SW_TCK")
	)
	(segment
		(start 118.0846 -73.269348)
		(end 118.0846 -69.281548)
		(width 0.127)
		(layer "In11.Cu")
		(net "JTAG_BMC_SW_TCK")
	)
	(segment
		(start 117.3226 -68.519548)
		(end 117.3226 -58.867548)
		(width 0.127)
		(layer "In11.Cu")
		(net "JTAG_BMC_SW_TCK")
	)
	(segment
		(start 117.652292 -78.622144)
		(end 118.9228 -77.351636)
		(width 0.127)
		(layer "In11.Cu")
		(net "JTAG_BMC_SW_TCK")
	)
	(segment
		(start 118.9228 -77.351636)
		(end 118.9228 -74.107548)
		(width 0.127)
		(layer "In11.Cu")
		(net "JTAG_BMC_SW_TCK")
	)
	(segment
		(start 118.9228 -74.107548)
		(end 118.0846 -73.269348)
		(width 0.127)
		(layer "In11.Cu")
		(net "JTAG_BMC_SW_TCK")
	)
	(segment
		(start 117.652292 -79.143098)
		(end 117.652292 -78.622144)
		(width 0.127)
		(layer "In11.Cu")
		(net "JTAG_BMC_SW_TCK")
	)
	(segment
		(start 117.3226 -58.867548)
		(end 114.935 -56.479948)
		(width 0.127)
		(layer "In11.Cu")
		(net "JTAG_BMC_SW_TCK")
	)
	(segment
		(start 118.954042 -57.921906)
		(end 118.745 -58.130948)
		(width 0.12954)
		(layer "F.Cu")
		(net "JTAG_BMC_SW_R_OE")
	)
	(segment
		(start 118.745 -58.130948)
		(end 118.745 -58.384948)
		(width 0.12954)
		(layer "F.Cu")
		(net "JTAG_BMC_SW_R_OE")
	)
	(segment
		(start 129.159 -59.146948)
		(end 129.159 -57.902348)
		(width 0.12954)
		(layer "F.Cu")
		(net "JTAG_BMC_SW_R_OE")
	)
	(segment
		(start 118.999 -58.638948)
		(end 121.157746 -58.638948)
		(width 0.12954)
		(layer "F.Cu")
		(net "JTAG_BMC_SW_R_OE")
	)
	(segment
		(start 122.154696 -59.635898)
		(end 122.809 -59.635898)
		(width 0.12954)
		(layer "F.Cu")
		(net "JTAG_BMC_SW_R_OE")
	)
	(segment
		(start 120.604788 -57.921906)
		(end 119.634 -57.921906)
		(width 0.12954)
		(layer "F.Cu")
		(net "JTAG_BMC_SW_R_OE")
	)
	(segment
		(start 129.159 -57.902348)
		(end 128.528572 -57.27192)
		(width 0.12954)
		(layer "F.Cu")
		(net "JTAG_BMC_SW_R_OE")
	)
	(segment
		(start 120.904 -57.622694)
		(end 120.604788 -57.921906)
		(width 0.12954)
		(layer "F.Cu")
		(net "JTAG_BMC_SW_R_OE")
	)
	(segment
		(start 124.439172 -57.27192)
		(end 125.476 -57.27192)
		(width 0.12954)
		(layer "F.Cu")
		(net "JTAG_BMC_SW_R_OE")
	)
	(segment
		(start 124.1298 -55.794402)
		(end 124.1298 -56.962548)
		(width 0.12954)
		(layer "F.Cu")
		(net "JTAG_BMC_SW_R_OE")
	)
	(segment
		(start 125.476 -55.321962)
		(end 124.60224 -55.321962)
		(width 0.12954)
		(layer "F.Cu")
		(net "JTAG_BMC_SW_R_OE")
	)
	(segment
		(start 122.809 -59.635898)
		(end 128.67005 -59.635898)
		(width 0.12954)
		(layer "F.Cu")
		(net "JTAG_BMC_SW_R_OE")
	)
	(segment
		(start 124.1298 -56.962548)
		(end 124.439172 -57.27192)
		(width 0.12954)
		(layer "F.Cu")
		(net "JTAG_BMC_SW_R_OE")
	)
	(segment
		(start 118.745 -58.384948)
		(end 118.999 -58.638948)
		(width 0.12954)
		(layer "F.Cu")
		(net "JTAG_BMC_SW_R_OE")
	)
	(segment
		(start 120.904 -56.352948)
		(end 120.904 -57.622694)
		(width 0.12954)
		(layer "F.Cu")
		(net "JTAG_BMC_SW_R_OE")
	)
	(segment
		(start 121.157746 -58.638948)
		(end 122.154696 -59.635898)
		(width 0.12954)
		(layer "F.Cu")
		(net "JTAG_BMC_SW_R_OE")
	)
	(segment
		(start 119.634 -55.971948)
		(end 120.523 -55.971948)
		(width 0.12954)
		(layer "F.Cu")
		(net "JTAG_BMC_SW_R_OE")
	)
	(segment
		(start 119.634 -57.921906)
		(end 118.954042 -57.921906)
		(width 0.12954)
		(layer "F.Cu")
		(net "JTAG_BMC_SW_R_OE")
	)
	(segment
		(start 128.67005 -59.635898)
		(end 129.159 -59.146948)
		(width 0.12954)
		(layer "F.Cu")
		(net "JTAG_BMC_SW_R_OE")
	)
	(segment
		(start 120.523 -55.971948)
		(end 120.904 -56.352948)
		(width 0.12954)
		(layer "F.Cu")
		(net "JTAG_BMC_SW_R_OE")
	)
	(segment
		(start 128.528572 -57.27192)
		(end 125.476 -57.27192)
		(width 0.12954)
		(layer "F.Cu")
		(net "JTAG_BMC_SW_R_OE")
	)
	(segment
		(start 124.60224 -55.321962)
		(end 124.1298 -55.794402)
		(width 0.12954)
		(layer "F.Cu")
		(net "JTAG_BMC_SW_R_OE")
	)
	(via
		(at 129.159 -59.146948)
		(size 0.508)
		(drill 0.254)
		(layers "F.Cu" "B.Cu")
		(net "JTAG_BMC_SW_R_OE")
	)
	(segment
		(start 165.5064 -121.961148)
		(end 162.49396 -121.961148)
		(width 0.12954)
		(layer "F.Cu")
		(net "JTAG_BMC_SW_PLD_OE")
	)
	(segment
		(start 169.396156 -121.38152)
		(end 169.026078 -121.751598)
		(width 0.12954)
		(layer "F.Cu")
		(net "JTAG_BMC_SW_PLD_OE")
	)
	(segment
		(start 162.414712 -122.040396)
		(end 161.85896 -122.596148)
		(width 0.12954)
		(layer "F.Cu")
		(net "JTAG_BMC_SW_PLD_OE")
	)
	(segment
		(start 171.755562 -118.575328)
		(end 171.3738 -118.95709)
		(width 0.12954)
		(layer "F.Cu")
		(net "JTAG_BMC_SW_PLD_OE")
	)
	(segment
		(start 165.71595 -121.751598)
		(end 165.5064 -121.961148)
		(width 0.12954)
		(layer "F.Cu")
		(net "JTAG_BMC_SW_PLD_OE")
	)
	(segment
		(start 169.026078 -121.751598)
		(end 165.71595 -121.751598)
		(width 0.12954)
		(layer "F.Cu")
		(net "JTAG_BMC_SW_PLD_OE")
	)
	(segment
		(start 162.49396 -121.961148)
		(end 162.414712 -122.040396)
		(width 0.12954)
		(layer "F.Cu")
		(net "JTAG_BMC_SW_PLD_OE")
	)
	(segment
		(start 161.85896 -122.596148)
		(end 161.23285 -122.596148)
		(width 0.12954)
		(layer "F.Cu")
		(net "JTAG_BMC_SW_PLD_OE")
	)
	(segment
		(start 171.3738 -121.1072)
		(end 171.09948 -121.38152)
		(width 0.12954)
		(layer "F.Cu")
		(net "JTAG_BMC_SW_PLD_OE")
	)
	(segment
		(start 171.09948 -121.38152)
		(end 169.396156 -121.38152)
		(width 0.12954)
		(layer "F.Cu")
		(net "JTAG_BMC_SW_PLD_OE")
	)
	(segment
		(start 171.3738 -118.95709)
		(end 171.3738 -121.1072)
		(width 0.12954)
		(layer "F.Cu")
		(net "JTAG_BMC_SW_PLD_OE")
	)
	(via
		(at 162.414712 -122.040396)
		(size 0.762)
		(drill 0.381)
		(layers "F.Cu" "B.Cu")
		(net "JTAG_BMC_SW_PLD_OE")
	)
	(segment
		(start 148.7043 -115.395248)
		(end 151.2824 -117.973348)
		(width 0.12954)
		(layer "F.Cu")
		(net "JTAG_BMC_SW_OE")
	)
	(segment
		(start 158.03118 -122.46864)
		(end 158.77286 -123.21032)
		(width 0.12954)
		(layer "F.Cu")
		(net "JTAG_BMC_SW_OE")
	)
	(segment
		(start 154.3685 -122.46864)
		(end 158.03118 -122.46864)
		(width 0.12954)
		(layer "F.Cu")
		(net "JTAG_BMC_SW_OE")
	)
	(segment
		(start 145.9992 -81.905348)
		(end 147.193 -81.905348)
		(width 0.12954)
		(layer "F.Cu")
		(net "JTAG_BMC_SW_OE")
	)
	(segment
		(start 155.1686 -95.519748)
		(end 154.484832 -96.203516)
		(width 0.12954)
		(layer "F.Cu")
		(net "JTAG_BMC_SW_OE")
	)
	(segment
		(start 127.5969 -60.435998)
		(end 127.61595 -60.416948)
		(width 0.12954)
		(layer "F.Cu")
		(net "JTAG_BMC_SW_OE")
	)
	(segment
		(start 160.0327 -123.21032)
		(end 160.43275 -122.81027)
		(width 0.12954)
		(layer "F.Cu")
		(net "JTAG_BMC_SW_OE")
	)
	(segment
		(start 147.193 -81.905348)
		(end 155.1686 -89.880948)
		(width 0.12954)
		(layer "F.Cu")
		(net "JTAG_BMC_SW_OE")
	)
	(segment
		(start 148.7043 -106.532426)
		(end 148.7043 -115.395248)
		(width 0.12954)
		(layer "F.Cu")
		(net "JTAG_BMC_SW_OE")
	)
	(segment
		(start 122.809 -60.435998)
		(end 122.809 -62.575948)
		(width 0.12954)
		(layer "F.Cu")
		(net "JTAG_BMC_SW_OE")
	)
	(segment
		(start 122.809 -60.435998)
		(end 127.5969 -60.435998)
		(width 0.12954)
		(layer "F.Cu")
		(net "JTAG_BMC_SW_OE")
	)
	(segment
		(start 127.61595 -60.416948)
		(end 127.61595 -61.432948)
		(width 0.12954)
		(layer "F.Cu")
		(net "JTAG_BMC_SW_OE")
	)
	(segment
		(start 151.2824 -122.418348)
		(end 151.9682 -123.104148)
		(width 0.12954)
		(layer "F.Cu")
		(net "JTAG_BMC_SW_OE")
	)
	(segment
		(start 153.732992 -123.104148)
		(end 154.3685 -122.46864)
		(width 0.12954)
		(layer "F.Cu")
		(net "JTAG_BMC_SW_OE")
	)
	(segment
		(start 158.77286 -123.21032)
		(end 160.0327 -123.21032)
		(width 0.12954)
		(layer "F.Cu")
		(net "JTAG_BMC_SW_OE")
	)
	(segment
		(start 154.484832 -100.751894)
		(end 148.7043 -106.532426)
		(width 0.12954)
		(layer "F.Cu")
		(net "JTAG_BMC_SW_OE")
	)
	(segment
		(start 154.484832 -96.203516)
		(end 154.484832 -100.751894)
		(width 0.12954)
		(layer "F.Cu")
		(net "JTAG_BMC_SW_OE")
	)
	(segment
		(start 151.9682 -123.104148)
		(end 153.732992 -123.104148)
		(width 0.12954)
		(layer "F.Cu")
		(net "JTAG_BMC_SW_OE")
	)
	(segment
		(start 155.1686 -89.880948)
		(end 155.1686 -95.519748)
		(width 0.12954)
		(layer "F.Cu")
		(net "JTAG_BMC_SW_OE")
	)
	(segment
		(start 151.2824 -117.973348)
		(end 151.2824 -122.418348)
		(width 0.12954)
		(layer "F.Cu")
		(net "JTAG_BMC_SW_OE")
	)
	(segment
		(start 160.43275 -122.81027)
		(end 160.43275 -122.596148)
		(width 0.12954)
		(layer "F.Cu")
		(net "JTAG_BMC_SW_OE")
	)
	(via
		(at 145.9992 -81.905348)
		(size 0.508)
		(drill 0.254)
		(layers "F.Cu" "B.Cu")
		(net "JTAG_BMC_SW_OE")
	)
	(segment
		(start 122.809 -62.575948)
		(end 122.809 -64.023748)
		(width 0.127)
		(layer "In4.Cu")
		(net "JTAG_BMC_SW_OE")
	)
	(segment
		(start 141.480286 -76.599034)
		(end 145.9992 -81.117948)
		(width 0.127)
		(layer "In4.Cu")
		(net "JTAG_BMC_SW_OE")
	)
	(segment
		(start 126.858776 -65.014348)
		(end 136.545574 -68.161154)
		(width 0.127)
		(layer "In4.Cu")
		(net "JTAG_BMC_SW_OE")
	)
	(segment
		(start 145.9992 -81.117948)
		(end 145.9992 -81.905348)
		(width 0.127)
		(layer "In4.Cu")
		(net "JTAG_BMC_SW_OE")
	)
	(segment
		(start 122.809 -64.023748)
		(end 123.7996 -65.014348)
		(width 0.127)
		(layer "In4.Cu")
		(net "JTAG_BMC_SW_OE")
	)
	(segment
		(start 138.43 -69.23532)
		(end 141.480286 -76.599034)
		(width 0.127)
		(layer "In4.Cu")
		(net "JTAG_BMC_SW_OE")
	)
	(segment
		(start 137.928604 -68.733924)
		(end 138.43 -69.23532)
		(width 0.127)
		(layer "In4.Cu")
		(net "JTAG_BMC_SW_OE")
	)
	(segment
		(start 136.545574 -68.161154)
		(end 137.928604 -68.733924)
		(width 0.127)
		(layer "In4.Cu")
		(net "JTAG_BMC_SW_OE")
	)
	(segment
		(start 123.7996 -65.014348)
		(end 126.858776 -65.014348)
		(width 0.127)
		(layer "In4.Cu")
		(net "JTAG_BMC_SW_OE")
	)
	(segment
		(start 134.547102 -18.236946)
		(end 134.26186 -18.522188)
		(width 0.12954)
		(layer "F.Cu")
		(net "TP_PCIE_HPM_TXP<1>")
	)
	(segment
		(start 134.547102 -16.550132)
		(end 134.547102 -18.236946)
		(width 0.12954)
		(layer "F.Cu")
		(net "TP_PCIE_HPM_TXP<1>")
	)
	(via
		(at 141.93266 -84.288884)
		(size 0.508)
		(drill 0.254)
		(layers "F.Cu" "B.Cu")
		(net "TP_PCIE_HPM_TXP<1>")
	)
	(via
		(at 175.34382 -127.89662)
		(size 0.508)
		(drill 0.254)
		(layers "F.Cu" "B.Cu")
		(net "TP_PCIE_HPM_TXP<1>")
	)
	(via
		(at 134.26186 -18.522188)
		(size 0.508)
		(drill 0.254)
		(layers "F.Cu" "B.Cu")
		(net "TP_PCIE_HPM_TXP<1>")
	)
	(via
		(at 142.40256 -137.315702)
		(size 0.508)
		(drill 0.254)
		(layers "F.Cu" "B.Cu")
		(net "TP_PCIE_HPM_TXP<1>")
	)
	(via
		(at 134.949692 -72.20712)
		(size 0.508)
		(drill 0.254)
		(layers "F.Cu" "B.Cu")
		(net "TP_PCIE_HPM_TXP<1>")
	)
	(segment
		(start 175.965358 -128.518158)
		(end 175.34382 -127.89662)
		(width 0.12954)
		(layer "B.Cu")
		(net "TP_PCIE_HPM_TXP<1>")
	)
	(segment
		(start 142.40256 -137.315702)
		(end 155.355544 -137.315702)
		(width 0.12954)
		(layer "B.Cu")
		(net "TP_PCIE_HPM_TXP<1>")
	)
	(segment
		(start 175.965358 -132.973826)
		(end 175.965358 -128.518158)
		(width 0.12954)
		(layer "B.Cu")
		(net "TP_PCIE_HPM_TXP<1>")
	)
	(segment
		(start 174.502572 -135.797036)
		(end 174.502572 -134.436612)
		(width 0.12954)
		(layer "B.Cu")
		(net "TP_PCIE_HPM_TXP<1>")
	)
	(segment
		(start 155.355544 -137.315702)
		(end 157.889702 -139.84986)
		(width 0.12954)
		(layer "B.Cu")
		(net "TP_PCIE_HPM_TXP<1>")
	)
	(segment
		(start 174.502572 -134.436612)
		(end 175.965358 -132.973826)
		(width 0.12954)
		(layer "B.Cu")
		(net "TP_PCIE_HPM_TXP<1>")
	)
	(segment
		(start 157.889702 -139.84986)
		(end 170.449748 -139.84986)
		(width 0.12954)
		(layer "B.Cu")
		(net "TP_PCIE_HPM_TXP<1>")
	)
	(segment
		(start 170.449748 -139.84986)
		(end 174.502572 -135.797036)
		(width 0.12954)
		(layer "B.Cu")
		(net "TP_PCIE_HPM_TXP<1>")
	)
	(segment
		(start 136.75233 -61.886846)
		(end 136.0424 -61.176916)
		(width 0.127)
		(layer "In2.Cu")
		(net "TP_PCIE_HPM_TXP<1>")
	)
	(segment
		(start 136.0424 -61.176916)
		(end 136.0424 -50.30851)
		(width 0.127)
		(layer "In2.Cu")
		(net "TP_PCIE_HPM_TXP<1>")
	)
	(segment
		(start 137.661396 -48.689514)
		(end 137.661396 -38.879272)
		(width 0.127)
		(layer "In2.Cu")
		(net "TP_PCIE_HPM_TXP<1>")
	)
	(segment
		(start 145.952972 -107.387644)
		(end 145.952972 -100.947474)
		(width 0.127)
		(layer "In2.Cu")
		(net "TP_PCIE_HPM_TXP<1>")
	)
	(segment
		(start 142.14348 -84.851748)
		(end 141.93266 -84.640928)
		(width 0.127)
		(layer "In2.Cu")
		(net "TP_PCIE_HPM_TXP<1>")
	)
	(segment
		(start 134.26186 -18.521934)
		(end 134.26186 -18.522188)
		(width 0.127)
		(layer "In2.Cu")
		(net "TP_PCIE_HPM_TXP<1>")
	)
	(segment
		(start 141.93266 -84.640928)
		(end 141.93266 -84.288884)
		(width 0.127)
		(layer "In2.Cu")
		(net "TP_PCIE_HPM_TXP<1>")
	)
	(segment
		(start 136.75233 -66.55562)
		(end 136.75233 -61.886846)
		(width 0.127)
		(layer "In2.Cu")
		(net "TP_PCIE_HPM_TXP<1>")
	)
	(segment
		(start 135.574024 -19.834098)
		(end 134.26186 -18.521934)
		(width 0.127)
		(layer "In2.Cu")
		(net "TP_PCIE_HPM_TXP<1>")
	)
	(segment
		(start 135.439404 -72.20712)
		(end 135.928608 -71.717916)
		(width 0.127)
		(layer "In2.Cu")
		(net "TP_PCIE_HPM_TXP<1>")
	)
	(segment
		(start 135.928608 -71.717916)
		(end 135.928608 -67.379342)
		(width 0.127)
		(layer "In2.Cu")
		(net "TP_PCIE_HPM_TXP<1>")
	)
	(segment
		(start 142.40256 -137.315702)
		(end 142.40256 -110.938056)
		(width 0.127)
		(layer "In2.Cu")
		(net "TP_PCIE_HPM_TXP<1>")
	)
	(segment
		(start 137.661396 -38.879272)
		(end 135.574024 -36.7919)
		(width 0.127)
		(layer "In2.Cu")
		(net "TP_PCIE_HPM_TXP<1>")
	)
	(segment
		(start 136.0424 -50.30851)
		(end 137.661396 -48.689514)
		(width 0.127)
		(layer "In2.Cu")
		(net "TP_PCIE_HPM_TXP<1>")
	)
	(segment
		(start 142.14348 -97.137982)
		(end 142.14348 -84.851748)
		(width 0.127)
		(layer "In2.Cu")
		(net "TP_PCIE_HPM_TXP<1>")
	)
	(segment
		(start 135.928608 -67.379342)
		(end 136.75233 -66.55562)
		(width 0.127)
		(layer "In2.Cu")
		(net "TP_PCIE_HPM_TXP<1>")
	)
	(segment
		(start 134.949692 -72.20712)
		(end 135.439404 -72.20712)
		(width 0.127)
		(layer "In2.Cu")
		(net "TP_PCIE_HPM_TXP<1>")
	)
	(segment
		(start 142.40256 -110.938056)
		(end 145.952972 -107.387644)
		(width 0.127)
		(layer "In2.Cu")
		(net "TP_PCIE_HPM_TXP<1>")
	)
	(segment
		(start 145.952972 -100.947474)
		(end 142.14348 -97.137982)
		(width 0.127)
		(layer "In2.Cu")
		(net "TP_PCIE_HPM_TXP<1>")
	)
	(segment
		(start 135.574024 -36.7919)
		(end 135.574024 -19.834098)
		(width 0.127)
		(layer "In2.Cu")
		(net "TP_PCIE_HPM_TXP<1>")
	)
	(segment
		(start 141.766798 -77.13091)
		(end 136.843008 -72.20712)
		(width 0.127)
		(layer "In11.Cu")
		(net "TP_PCIE_HPM_TXP<1>")
	)
	(segment
		(start 141.93266 -84.288884)
		(end 141.93266 -84.034884)
		(width 0.127)
		(layer "In11.Cu")
		(net "TP_PCIE_HPM_TXP<1>")
	)
	(segment
		(start 141.93266 -84.034884)
		(end 141.766798 -83.869022)
		(width 0.127)
		(layer "In11.Cu")
		(net "TP_PCIE_HPM_TXP<1>")
	)
	(segment
		(start 141.766798 -83.869022)
		(end 141.766798 -77.13091)
		(width 0.127)
		(layer "In11.Cu")
		(net "TP_PCIE_HPM_TXP<1>")
	)
	(segment
		(start 136.843008 -72.20712)
		(end 134.949692 -72.20712)
		(width 0.127)
		(layer "In11.Cu")
		(net "TP_PCIE_HPM_TXP<1>")
	)
	(segment
		(start 133.9469 -16.550132)
		(end 133.9469 -17.643348)
		(width 0.12954)
		(layer "F.Cu")
		(net "TP_PCIE_HPM_TXN<1>")
	)
	(segment
		(start 133.99008 -17.686528)
		(end 133.99008 -17.686782)
		(width 0.12954)
		(layer "F.Cu")
		(net "TP_PCIE_HPM_TXN<1>")
	)
	(segment
		(start 133.9469 -17.643348)
		(end 133.99008 -17.686528)
		(width 0.12954)
		(layer "F.Cu")
		(net "TP_PCIE_HPM_TXN<1>")
	)
	(via
		(at 142.56766 -84.288884)
		(size 0.508)
		(drill 0.254)
		(layers "F.Cu" "B.Cu")
		(net "TP_PCIE_HPM_TXN<1>")
	)
	(via
		(at 136.58088 -70.665848)
		(size 0.762)
		(drill 0.254)
		(layers "F.Cu" "B.Cu")
		(net "TP_PCIE_HPM_TXN<1>")
	)
	(via
		(at 143.1798 -136.773158)
		(size 0.508)
		(drill 0.254)
		(layers "F.Cu" "B.Cu")
		(net "TP_PCIE_HPM_TXN<1>")
	)
	(via
		(at 133.99008 -17.686782)
		(size 0.508)
		(drill 0.254)
		(layers "F.Cu" "B.Cu")
		(net "TP_PCIE_HPM_TXN<1>")
	)
	(segment
		(start 138.059922 -48.854614)
		(end 136.440926 -50.47361)
		(width 0.127)
		(layer "In2.Cu")
		(net "TP_PCIE_HPM_TXN<1>")
	)
	(segment
		(start 143.1798 -136.773158)
		(end 143.1798 -136.545574)
		(width 0.127)
		(layer "In2.Cu")
		(net "TP_PCIE_HPM_TXN<1>")
	)
	(segment
		(start 133.99008 -17.686782)
		(end 133.990334 -17.686528)
		(width 0.127)
		(layer "In2.Cu")
		(net "TP_PCIE_HPM_TXN<1>")
	)
	(segment
		(start 143.1798 -136.545574)
		(end 142.774924 -136.140698)
		(width 0.127)
		(layer "In2.Cu")
		(net "TP_PCIE_HPM_TXN<1>")
	)
	(segment
		(start 136.327134 -67.544442)
		(end 136.327134 -70.412102)
		(width 0.127)
		(layer "In2.Cu")
		(net "TP_PCIE_HPM_TXN<1>")
	)
	(segment
		(start 134.181596 -17.686528)
		(end 135.97255 -19.477482)
		(width 0.127)
		(layer "In2.Cu")
		(net "TP_PCIE_HPM_TXN<1>")
	)
	(segment
		(start 138.059922 -38.714172)
		(end 138.059922 -48.854614)
		(width 0.127)
		(layer "In2.Cu")
		(net "TP_PCIE_HPM_TXN<1>")
	)
	(segment
		(start 137.150856 -61.721746)
		(end 137.150856 -66.72072)
		(width 0.127)
		(layer "In2.Cu")
		(net "TP_PCIE_HPM_TXN<1>")
	)
	(segment
		(start 142.56766 -97.035366)
		(end 142.56766 -84.288884)
		(width 0.127)
		(layer "In2.Cu")
		(net "TP_PCIE_HPM_TXN<1>")
	)
	(segment
		(start 136.440926 -61.011816)
		(end 137.150856 -61.721746)
		(width 0.127)
		(layer "In2.Cu")
		(net "TP_PCIE_HPM_TXN<1>")
	)
	(segment
		(start 136.440926 -50.47361)
		(end 136.440926 -61.011816)
		(width 0.127)
		(layer "In2.Cu")
		(net "TP_PCIE_HPM_TXN<1>")
	)
	(segment
		(start 137.150856 -66.72072)
		(end 136.327134 -67.544442)
		(width 0.127)
		(layer "In2.Cu")
		(net "TP_PCIE_HPM_TXN<1>")
	)
	(segment
		(start 136.327134 -70.412102)
		(end 136.58088 -70.665848)
		(width 0.127)
		(layer "In2.Cu")
		(net "TP_PCIE_HPM_TXN<1>")
	)
	(segment
		(start 146.325336 -100.793042)
		(end 142.56766 -97.035366)
		(width 0.127)
		(layer "In2.Cu")
		(net "TP_PCIE_HPM_TXN<1>")
	)
	(segment
		(start 133.990334 -17.686528)
		(end 134.181596 -17.686528)
		(width 0.127)
		(layer "In2.Cu")
		(net "TP_PCIE_HPM_TXN<1>")
	)
	(segment
		(start 135.97255 -19.477482)
		(end 135.97255 -36.6268)
		(width 0.127)
		(layer "In2.Cu")
		(net "TP_PCIE_HPM_TXN<1>")
	)
	(segment
		(start 146.325336 -107.542076)
		(end 146.325336 -100.793042)
		(width 0.127)
		(layer "In2.Cu")
		(net "TP_PCIE_HPM_TXN<1>")
	)
	(segment
		(start 135.97255 -36.6268)
		(end 138.059922 -38.714172)
		(width 0.127)
		(layer "In2.Cu")
		(net "TP_PCIE_HPM_TXN<1>")
	)
	(segment
		(start 142.774924 -111.092488)
		(end 146.325336 -107.542076)
		(width 0.127)
		(layer "In2.Cu")
		(net "TP_PCIE_HPM_TXN<1>")
	)
	(segment
		(start 142.774924 -136.140698)
		(end 142.774924 -111.092488)
		(width 0.127)
		(layer "In2.Cu")
		(net "TP_PCIE_HPM_TXN<1>")
	)
	(segment
		(start 142.14983 -76.917296)
		(end 136.58088 -71.348346)
		(width 0.127)
		(layer "In11.Cu")
		(net "TP_PCIE_HPM_TXN<1>")
	)
	(segment
		(start 136.58088 -71.348346)
		(end 136.58088 -70.665848)
		(width 0.127)
		(layer "In11.Cu")
		(net "TP_PCIE_HPM_TXN<1>")
	)
	(segment
		(start 142.56766 -81.823306)
		(end 142.14983 -81.405476)
		(width 0.127)
		(layer "In11.Cu")
		(net "TP_PCIE_HPM_TXN<1>")
	)
	(segment
		(start 142.56766 -84.288884)
		(end 142.56766 -81.823306)
		(width 0.127)
		(layer "In11.Cu")
		(net "TP_PCIE_HPM_TXN<1>")
	)
	(segment
		(start 142.14983 -81.405476)
		(end 142.14983 -76.917296)
		(width 0.127)
		(layer "In11.Cu")
		(net "TP_PCIE_HPM_TXN<1>")
	)
	(segment
		(start 22.51837 -428.401988)
		(end 22.51837 -427.503844)
		(width 0.12954)
		(layer "F.Cu")
		(net "RST_PERST_SWB_N")
	)
	(segment
		(start 21.856954 -427.500034)
		(end 21.85162 -427.505368)
		(width 0.12954)
		(layer "F.Cu")
		(net "RST_PERST_SWB_N")
	)
	(segment
		(start 22.52218 -427.500034)
		(end 21.856954 -427.500034)
		(width 0.12954)
		(layer "F.Cu")
		(net "RST_PERST_SWB_N")
	)
	(segment
		(start 22.51837 -427.503844)
		(end 22.52218 -427.500034)
		(width 0.12954)
		(layer "F.Cu")
		(net "RST_PERST_SWB_N")
	)
	(segment
		(start 184.555638 -119.375428)
		(end 184.955688 -119.775478)
		(width 0.12954)
		(layer "F.Cu")
		(net "RST_PERST_SWB_N")
	)
	(via
		(at 22.48408 -377.058428)
		(size 0.508)
		(drill 0.254)
		(layers "F.Cu" "B.Cu")
		(net "RST_PERST_SWB_N")
	)
	(via
		(at 184.955688 -119.775478)
		(size 0.4572)
		(drill 0.254)
		(layers "F.Cu" "B.Cu")
		(net "RST_PERST_SWB_N")
	)
	(via
		(at 146.61388 -114.163348)
		(size 0.508)
		(drill 0.254)
		(layers "F.Cu" "B.Cu")
		(net "RST_PERST_SWB_N")
	)
	(via
		(at 18.9357 -123.904248)
		(size 0.508)
		(drill 0.254)
		(layers "F.Cu" "B.Cu")
		(net "RST_PERST_SWB_N")
	)
	(via
		(at 21.85162 -427.505368)
		(size 0.508)
		(drill 0.254)
		(layers "F.Cu" "B.Cu")
		(net "RST_PERST_SWB_N")
	)
	(segment
		(start 10.45464 -413.563308)
		(end 21.85162 -424.960288)
		(width 0.12954)
		(layer "B.Cu")
		(net "RST_PERST_SWB_N")
	)
	(segment
		(start 8.586216 -377.73864)
		(end 5.35686 -380.967996)
		(width 0.12954)
		(layer "B.Cu")
		(net "RST_PERST_SWB_N")
	)
	(segment
		(start 10.45464 -407.417524)
		(end 10.45464 -413.563308)
		(width 0.12954)
		(layer "B.Cu")
		(net "RST_PERST_SWB_N")
	)
	(segment
		(start 21.803868 -377.73864)
		(end 8.586216 -377.73864)
		(width 0.12954)
		(layer "B.Cu")
		(net "RST_PERST_SWB_N")
	)
	(segment
		(start 5.35686 -380.967996)
		(end 5.35686 -402.319744)
		(width 0.12954)
		(layer "B.Cu")
		(net "RST_PERST_SWB_N")
	)
	(segment
		(start 5.35686 -402.319744)
		(end 10.45464 -407.417524)
		(width 0.12954)
		(layer "B.Cu")
		(net "RST_PERST_SWB_N")
	)
	(segment
		(start 22.48408 -377.058428)
		(end 21.803868 -377.73864)
		(width 0.12954)
		(layer "B.Cu")
		(net "RST_PERST_SWB_N")
	)
	(segment
		(start 21.85162 -424.960288)
		(end 21.85162 -427.505368)
		(width 0.12954)
		(layer "B.Cu")
		(net "RST_PERST_SWB_N")
	)
	(segment
		(start 163.588192 -112.230408)
		(end 160.78454 -112.230408)
		(width 0.127)
		(layer "In4.Cu")
		(net "RST_PERST_SWB_N")
	)
	(segment
		(start 172.786548 -118.57482)
		(end 169.455592 -118.57482)
		(width 0.127)
		(layer "In4.Cu")
		(net "RST_PERST_SWB_N")
	)
	(segment
		(start 184.304432 -118.56847)
		(end 183.992774 -118.56847)
		(width 0.127)
		(layer "In4.Cu")
		(net "RST_PERST_SWB_N")
	)
	(segment
		(start 183.76265 -118.338346)
		(end 183.76265 -118.026688)
		(width 0.127)
		(layer "In4.Cu")
		(net "RST_PERST_SWB_N")
	)
	(segment
		(start 183.76265 -118.026688)
		(end 183.518556 -117.782594)
		(width 0.127)
		(layer "In4.Cu")
		(net "RST_PERST_SWB_N")
	)
	(segment
		(start 174.829724 -116.968778)
		(end 174.39259 -116.968778)
		(width 0.127)
		(layer "In4.Cu")
		(net "RST_PERST_SWB_N")
	)
	(segment
		(start 181.99862 -116.972588)
		(end 181.57952 -116.972588)
		(width 0.127)
		(layer "In4.Cu")
		(net "RST_PERST_SWB_N")
	)
	(segment
		(start 181.57952 -116.972588)
		(end 181.356 -116.749068)
		(width 0.127)
		(layer "In4.Cu")
		(net "RST_PERST_SWB_N")
	)
	(segment
		(start 181.356 -116.749068)
		(end 181.356 -116.416328)
		(width 0.127)
		(layer "In4.Cu")
		(net "RST_PERST_SWB_N")
	)
	(segment
		(start 174.950374 -116.410994)
		(end 174.950374 -116.848128)
		(width 0.127)
		(layer "In4.Cu")
		(net "RST_PERST_SWB_N")
	)
	(segment
		(start 182.151274 -117.59438)
		(end 182.151274 -117.125242)
		(width 0.127)
		(layer "In4.Cu")
		(net "RST_PERST_SWB_N")
	)
	(segment
		(start 169.02176 -113.508028)
		(end 167.20058 -111.686848)
		(width 0.127)
		(layer "In4.Cu")
		(net "RST_PERST_SWB_N")
	)
	(segment
		(start 164.131752 -111.686848)
		(end 163.588192 -112.230408)
		(width 0.127)
		(layer "In4.Cu")
		(net "RST_PERST_SWB_N")
	)
	(segment
		(start 183.992774 -118.56847)
		(end 183.76265 -118.338346)
		(width 0.127)
		(layer "In4.Cu")
		(net "RST_PERST_SWB_N")
	)
	(segment
		(start 155.037028 -113.066068)
		(end 154.140408 -112.169448)
		(width 0.127)
		(layer "In4.Cu")
		(net "RST_PERST_SWB_N")
	)
	(segment
		(start 175.18634 -116.175028)
		(end 174.950374 -116.410994)
		(width 0.127)
		(layer "In4.Cu")
		(net "RST_PERST_SWB_N")
	)
	(segment
		(start 174.39259 -116.968778)
		(end 172.786548 -118.57482)
		(width 0.127)
		(layer "In4.Cu")
		(net "RST_PERST_SWB_N")
	)
	(segment
		(start 182.151274 -117.125242)
		(end 181.99862 -116.972588)
		(width 0.127)
		(layer "In4.Cu")
		(net "RST_PERST_SWB_N")
	)
	(segment
		(start 148.60778 -112.169448)
		(end 146.61388 -114.163348)
		(width 0.127)
		(layer "In4.Cu")
		(net "RST_PERST_SWB_N")
	)
	(segment
		(start 183.518556 -117.782594)
		(end 182.339488 -117.782594)
		(width 0.127)
		(layer "In4.Cu")
		(net "RST_PERST_SWB_N")
	)
	(segment
		(start 184.955688 -119.775478)
		(end 184.548526 -119.368316)
		(width 0.127)
		(layer "In4.Cu")
		(net "RST_PERST_SWB_N")
	)
	(segment
		(start 169.455592 -118.57482)
		(end 169.02176 -118.140988)
		(width 0.127)
		(layer "In4.Cu")
		(net "RST_PERST_SWB_N")
	)
	(segment
		(start 167.20058 -111.686848)
		(end 164.131752 -111.686848)
		(width 0.127)
		(layer "In4.Cu")
		(net "RST_PERST_SWB_N")
	)
	(segment
		(start 181.356 -116.416328)
		(end 181.1147 -116.175028)
		(width 0.127)
		(layer "In4.Cu")
		(net "RST_PERST_SWB_N")
	)
	(segment
		(start 184.548526 -118.812564)
		(end 184.304432 -118.56847)
		(width 0.127)
		(layer "In4.Cu")
		(net "RST_PERST_SWB_N")
	)
	(segment
		(start 181.1147 -116.175028)
		(end 175.18634 -116.175028)
		(width 0.127)
		(layer "In4.Cu")
		(net "RST_PERST_SWB_N")
	)
	(segment
		(start 154.140408 -112.169448)
		(end 148.60778 -112.169448)
		(width 0.127)
		(layer "In4.Cu")
		(net "RST_PERST_SWB_N")
	)
	(segment
		(start 174.950374 -116.848128)
		(end 174.829724 -116.968778)
		(width 0.127)
		(layer "In4.Cu")
		(net "RST_PERST_SWB_N")
	)
	(segment
		(start 184.548526 -119.368316)
		(end 184.548526 -118.812564)
		(width 0.127)
		(layer "In4.Cu")
		(net "RST_PERST_SWB_N")
	)
	(segment
		(start 156.585666 -113.066068)
		(end 155.037028 -113.066068)
		(width 0.127)
		(layer "In4.Cu")
		(net "RST_PERST_SWB_N")
	)
	(segment
		(start 182.339488 -117.782594)
		(end 182.151274 -117.59438)
		(width 0.127)
		(layer "In4.Cu")
		(net "RST_PERST_SWB_N")
	)
	(segment
		(start 160.50006 -111.945928)
		(end 157.705806 -111.945928)
		(width 0.127)
		(layer "In4.Cu")
		(net "RST_PERST_SWB_N")
	)
	(segment
		(start 169.02176 -118.140988)
		(end 169.02176 -113.508028)
		(width 0.127)
		(layer "In4.Cu")
		(net "RST_PERST_SWB_N")
	)
	(segment
		(start 157.705806 -111.945928)
		(end 156.585666 -113.066068)
		(width 0.127)
		(layer "In4.Cu")
		(net "RST_PERST_SWB_N")
	)
	(segment
		(start 160.78454 -112.230408)
		(end 160.50006 -111.945928)
		(width 0.127)
		(layer "In4.Cu")
		(net "RST_PERST_SWB_N")
	)
	(segment
		(start 106.9594 -119.167148)
		(end 110.4392 -115.687348)
		(width 0.127)
		(layer "In6.Cu")
		(net "RST_PERST_SWB_N")
	)
	(segment
		(start 110.4392 -115.687348)
		(end 131.498848 -115.687348)
		(width 0.127)
		(layer "In6.Cu")
		(net "RST_PERST_SWB_N")
	)
	(segment
		(start 98.9076 -119.167148)
		(end 106.9594 -119.167148)
		(width 0.127)
		(layer "In6.Cu")
		(net "RST_PERST_SWB_N")
	)
	(segment
		(start 97.7138 -120.360948)
		(end 98.9076 -119.167148)
		(width 0.127)
		(layer "In6.Cu")
		(net "RST_PERST_SWB_N")
	)
	(segment
		(start 131.99872 -116.18722)
		(end 137.345928 -116.18722)
		(width 0.127)
		(layer "In6.Cu")
		(net "RST_PERST_SWB_N")
	)
	(segment
		(start 64.7446 -121.580148)
		(end 65.9638 -120.360948)
		(width 0.127)
		(layer "In6.Cu")
		(net "RST_PERST_SWB_N")
	)
	(segment
		(start 48.82134 -121.580148)
		(end 64.7446 -121.580148)
		(width 0.127)
		(layer "In6.Cu")
		(net "RST_PERST_SWB_N")
	)
	(segment
		(start 139.3698 -114.163348)
		(end 146.61388 -114.163348)
		(width 0.127)
		(layer "In6.Cu")
		(net "RST_PERST_SWB_N")
	)
	(segment
		(start 22.86 -118.455948)
		(end 29.10967 -118.455948)
		(width 0.127)
		(layer "In6.Cu")
		(net "RST_PERST_SWB_N")
	)
	(segment
		(start 137.345928 -116.18722)
		(end 139.3698 -114.163348)
		(width 0.127)
		(layer "In6.Cu")
		(net "RST_PERST_SWB_N")
	)
	(segment
		(start 29.10967 -118.455948)
		(end 30.48127 -117.084348)
		(width 0.127)
		(layer "In6.Cu")
		(net "RST_PERST_SWB_N")
	)
	(segment
		(start 44.32554 -117.084348)
		(end 48.82134 -121.580148)
		(width 0.127)
		(layer "In6.Cu")
		(net "RST_PERST_SWB_N")
	)
	(segment
		(start 18.9357 -122.380248)
		(end 22.86 -118.455948)
		(width 0.127)
		(layer "In6.Cu")
		(net "RST_PERST_SWB_N")
	)
	(segment
		(start 18.9357 -123.904248)
		(end 18.9357 -122.380248)
		(width 0.127)
		(layer "In6.Cu")
		(net "RST_PERST_SWB_N")
	)
	(segment
		(start 131.498848 -115.687348)
		(end 131.99872 -116.18722)
		(width 0.127)
		(layer "In6.Cu")
		(net "RST_PERST_SWB_N")
	)
	(segment
		(start 30.48127 -117.084348)
		(end 44.32554 -117.084348)
		(width 0.127)
		(layer "In6.Cu")
		(net "RST_PERST_SWB_N")
	)
	(segment
		(start 65.9638 -120.360948)
		(end 97.7138 -120.360948)
		(width 0.127)
		(layer "In6.Cu")
		(net "RST_PERST_SWB_N")
	)
	(segment
		(start 8.7884 -196.764148)
		(end 9.7282 -195.824348)
		(width 0.127)
		(layer "In13.Cu")
		(net "RST_PERST_SWB_N")
	)
	(segment
		(start 22.35454 -348.160848)
		(end 8.2042 -334.010508)
		(width 0.127)
		(layer "In13.Cu")
		(net "RST_PERST_SWB_N")
	)
	(segment
		(start 9.7282 -195.824348)
		(end 9.7282 -190.998348)
		(width 0.127)
		(layer "In13.Cu")
		(net "RST_PERST_SWB_N")
	)
	(segment
		(start 8.2042 -334.010508)
		(end 8.2042 -326.739758)
		(width 0.127)
		(layer "In13.Cu")
		(net "RST_PERST_SWB_N")
	)
	(segment
		(start 18.415 -154.549348)
		(end 16.7386 -152.872948)
		(width 0.127)
		(layer "In13.Cu")
		(net "RST_PERST_SWB_N")
	)
	(segment
		(start 8.1788 -173.599348)
		(end 18.415 -163.363148)
		(width 0.127)
		(layer "In13.Cu")
		(net "RST_PERST_SWB_N")
	)
	(segment
		(start 8.7884 -255.408938)
		(end 8.2042 -254.824738)
		(width 0.127)
		(layer "In13.Cu")
		(net "RST_PERST_SWB_N")
	)
	(segment
		(start 22.35454 -376.928888)
		(end 22.35454 -348.160848)
		(width 0.127)
		(layer "In13.Cu")
		(net "RST_PERST_SWB_N")
	)
	(segment
		(start 16.7386 -126.101348)
		(end 18.9357 -123.904248)
		(width 0.127)
		(layer "In13.Cu")
		(net "RST_PERST_SWB_N")
	)
	(segment
		(start 8.2042 -326.739758)
		(end 10.5156 -324.428358)
		(width 0.127)
		(layer "In13.Cu")
		(net "RST_PERST_SWB_N")
	)
	(segment
		(start 18.415 -163.363148)
		(end 18.415 -154.549348)
		(width 0.127)
		(layer "In13.Cu")
		(net "RST_PERST_SWB_N")
	)
	(segment
		(start 8.1788 -189.448948)
		(end 8.1788 -173.599348)
		(width 0.127)
		(layer "In13.Cu")
		(net "RST_PERST_SWB_N")
	)
	(segment
		(start 8.7884 -319.848738)
		(end 8.7884 -255.408938)
		(width 0.127)
		(layer "In13.Cu")
		(net "RST_PERST_SWB_N")
	)
	(segment
		(start 22.48408 -377.058428)
		(end 22.35454 -376.928888)
		(width 0.127)
		(layer "In13.Cu")
		(net "RST_PERST_SWB_N")
	)
	(segment
		(start 10.5156 -321.575938)
		(end 8.7884 -319.848738)
		(width 0.127)
		(layer "In13.Cu")
		(net "RST_PERST_SWB_N")
	)
	(segment
		(start 8.2042 -254.824738)
		(end 8.2042 -253.660148)
		(width 0.127)
		(layer "In13.Cu")
		(net "RST_PERST_SWB_N")
	)
	(segment
		(start 8.2042 -253.660148)
		(end 8.7884 -253.075948)
		(width 0.127)
		(layer "In13.Cu")
		(net "RST_PERST_SWB_N")
	)
	(segment
		(start 16.7386 -152.872948)
		(end 16.7386 -126.101348)
		(width 0.127)
		(layer "In13.Cu")
		(net "RST_PERST_SWB_N")
	)
	(segment
		(start 8.7884 -253.075948)
		(end 8.7884 -196.764148)
		(width 0.127)
		(layer "In13.Cu")
		(net "RST_PERST_SWB_N")
	)
	(segment
		(start 10.5156 -324.428358)
		(end 10.5156 -321.575938)
		(width 0.127)
		(layer "In13.Cu")
		(net "RST_PERST_SWB_N")
	)
	(segment
		(start 9.7282 -190.998348)
		(end 8.1788 -189.448948)
		(width 0.127)
		(layer "In13.Cu")
		(net "RST_PERST_SWB_N")
	)
	(segment
		(start 116.519706 -91.699842)
		(end 116.519706 -92.583762)
		(width 0.12954)
		(layer "F.Cu")
		(net "H_CPU_CATERR_LVC2_BMC_R_N")
	)
	(segment
		(start 117.0432 -91.176348)
		(end 116.519706 -91.699842)
		(width 0.12954)
		(layer "F.Cu")
		(net "H_CPU_CATERR_LVC2_BMC_R_N")
	)
	(via
		(at 117.0432 -95.341948)
		(size 0.6604)
		(drill 0.3302)
		(layers "F.Cu" "B.Cu")
		(net "H_CPU_CATERR_LVC2_BMC_R_N")
	)
	(via
		(at 117.0432 -91.176348)
		(size 0.508)
		(drill 0.254)
		(layers "F.Cu" "B.Cu")
		(net "H_CPU_CATERR_LVC2_BMC_R_N")
	)
	(segment
		(start 117.0432 -96.516698)
		(end 117.0432 -95.341948)
		(width 0.12954)
		(layer "B.Cu")
		(net "H_CPU_CATERR_LVC2_BMC_R_N")
	)
	(segment
		(start 117.0432 -95.341948)
		(end 117.0432 -91.176348)
		(width 0.12954)
		(layer "B.Cu")
		(net "H_CPU_CATERR_LVC2_BMC_R_N")
	)
	(segment
		(start 183.86171 -15.848838)
		(end 184.3278 -15.382748)
		(width 0.12954)
		(layer "F.Cu")
		(net "H_CPU_CATERR_LVC2_BMC_N")
	)
	(segment
		(start 183.861964 -16.549878)
		(end 183.86171 -16.549624)
		(width 0.12954)
		(layer "F.Cu")
		(net "H_CPU_CATERR_LVC2_BMC_N")
	)
	(segment
		(start 184.3278 -15.382748)
		(end 184.8358 -15.382748)
		(width 0.12954)
		(layer "F.Cu")
		(net "H_CPU_CATERR_LVC2_BMC_N")
	)
	(segment
		(start 183.861964 -16.550132)
		(end 183.861964 -16.549878)
		(width 0.12954)
		(layer "F.Cu")
		(net "H_CPU_CATERR_LVC2_BMC_N")
	)
	(segment
		(start 183.86171 -16.549624)
		(end 183.86171 -15.848838)
		(width 0.12954)
		(layer "F.Cu")
		(net "H_CPU_CATERR_LVC2_BMC_N")
	)
	(via
		(at 117.729 -97.424748)
		(size 0.508)
		(drill 0.254)
		(layers "F.Cu" "B.Cu")
		(net "H_CPU_CATERR_LVC2_BMC_N")
	)
	(via
		(at 131.74218 -55.674768)
		(size 0.508)
		(drill 0.254)
		(layers "F.Cu" "B.Cu")
		(net "H_CPU_CATERR_LVC2_BMC_N")
	)
	(via
		(at 124.39142 -19.337528)
		(size 0.508)
		(drill 0.254)
		(layers "F.Cu" "B.Cu")
		(net "H_CPU_CATERR_LVC2_BMC_N")
	)
	(via
		(at 184.8358 -15.382748)
		(size 0.508)
		(drill 0.254)
		(layers "F.Cu" "B.Cu")
		(net "H_CPU_CATERR_LVC2_BMC_N")
	)
	(segment
		(start 117.62105 -97.316798)
		(end 117.729 -97.424748)
		(width 0.12954)
		(layer "B.Cu")
		(net "H_CPU_CATERR_LVC2_BMC_N")
	)
	(segment
		(start 117.0432 -97.316798)
		(end 117.62105 -97.316798)
		(width 0.12954)
		(layer "B.Cu")
		(net "H_CPU_CATERR_LVC2_BMC_N")
	)
	(segment
		(start 131.74218 -53.221128)
		(end 130.2258 -51.704748)
		(width 0.127)
		(layer "In2.Cu")
		(net "H_CPU_CATERR_LVC2_BMC_N")
	)
	(segment
		(start 131.74218 -55.674768)
		(end 131.74218 -53.221128)
		(width 0.127)
		(layer "In2.Cu")
		(net "H_CPU_CATERR_LVC2_BMC_N")
	)
	(segment
		(start 124.39142 -35.179508)
		(end 124.39142 -19.337528)
		(width 0.127)
		(layer "In2.Cu")
		(net "H_CPU_CATERR_LVC2_BMC_N")
	)
	(segment
		(start 130.2258 -41.013888)
		(end 124.39142 -35.179508)
		(width 0.127)
		(layer "In2.Cu")
		(net "H_CPU_CATERR_LVC2_BMC_N")
	)
	(segment
		(start 130.2258 -51.704748)
		(end 130.2258 -41.013888)
		(width 0.127)
		(layer "In2.Cu")
		(net "H_CPU_CATERR_LVC2_BMC_N")
	)
	(segment
		(start 130.79984 -56.617108)
		(end 130.79984 -77.224128)
		(width 0.127)
		(layer "In11.Cu")
		(net "H_CPU_CATERR_LVC2_BMC_N")
	)
	(segment
		(start 136.10082 -82.525108)
		(end 136.10082 -88.897968)
		(width 0.127)
		(layer "In11.Cu")
		(net "H_CPU_CATERR_LVC2_BMC_N")
	)
	(segment
		(start 130.79984 -77.224128)
		(end 136.10082 -82.525108)
		(width 0.127)
		(layer "In11.Cu")
		(net "H_CPU_CATERR_LVC2_BMC_N")
	)
	(segment
		(start 131.74218 -55.674768)
		(end 130.79984 -56.617108)
		(width 0.127)
		(layer "In11.Cu")
		(net "H_CPU_CATERR_LVC2_BMC_N")
	)
	(segment
		(start 129.00406 -95.994728)
		(end 119.15902 -95.994728)
		(width 0.127)
		(layer "In11.Cu")
		(net "H_CPU_CATERR_LVC2_BMC_N")
	)
	(segment
		(start 136.10082 -88.897968)
		(end 129.00406 -95.994728)
		(width 0.127)
		(layer "In11.Cu")
		(net "H_CPU_CATERR_LVC2_BMC_N")
	)
	(segment
		(start 119.15902 -95.994728)
		(end 117.729 -97.424748)
		(width 0.127)
		(layer "In11.Cu")
		(net "H_CPU_CATERR_LVC2_BMC_N")
	)
	(segment
		(start 141.02842 -14.463268)
		(end 149.1107 -14.463268)
		(width 0.127)
		(layer "In15.Cu")
		(net "H_CPU_CATERR_LVC2_BMC_N")
	)
	(segment
		(start 150.08352 -13.490448)
		(end 164.23894 -13.490448)
		(width 0.127)
		(layer "In15.Cu")
		(net "H_CPU_CATERR_LVC2_BMC_N")
	)
	(segment
		(start 184.6707 -15.217648)
		(end 184.8358 -15.382748)
		(width 0.127)
		(layer "In15.Cu")
		(net "H_CPU_CATERR_LVC2_BMC_N")
	)
	(segment
		(start 183.479948 -10.267188)
		(end 184.6707 -11.45794)
		(width 0.127)
		(layer "In15.Cu")
		(net "H_CPU_CATERR_LVC2_BMC_N")
	)
	(segment
		(start 129.31394 -16.868648)
		(end 138.62304 -16.868648)
		(width 0.127)
		(layer "In15.Cu")
		(net "H_CPU_CATERR_LVC2_BMC_N")
	)
	(segment
		(start 126.84506 -19.337528)
		(end 129.31394 -16.868648)
		(width 0.127)
		(layer "In15.Cu")
		(net "H_CPU_CATERR_LVC2_BMC_N")
	)
	(segment
		(start 180.14696 -10.267188)
		(end 183.479948 -10.267188)
		(width 0.127)
		(layer "In15.Cu")
		(net "H_CPU_CATERR_LVC2_BMC_N")
	)
	(segment
		(start 165.28796 -11.029188)
		(end 168.4909 -7.826248)
		(width 0.127)
		(layer "In15.Cu")
		(net "H_CPU_CATERR_LVC2_BMC_N")
	)
	(segment
		(start 177.70602 -7.826248)
		(end 180.14696 -10.267188)
		(width 0.127)
		(layer "In15.Cu")
		(net "H_CPU_CATERR_LVC2_BMC_N")
	)
	(segment
		(start 149.1107 -14.463268)
		(end 150.08352 -13.490448)
		(width 0.127)
		(layer "In15.Cu")
		(net "H_CPU_CATERR_LVC2_BMC_N")
	)
	(segment
		(start 184.6707 -11.45794)
		(end 184.6707 -15.217648)
		(width 0.127)
		(layer "In15.Cu")
		(net "H_CPU_CATERR_LVC2_BMC_N")
	)
	(segment
		(start 164.23894 -13.490448)
		(end 165.28796 -12.441428)
		(width 0.127)
		(layer "In15.Cu")
		(net "H_CPU_CATERR_LVC2_BMC_N")
	)
	(segment
		(start 165.28796 -12.441428)
		(end 165.28796 -11.029188)
		(width 0.127)
		(layer "In15.Cu")
		(net "H_CPU_CATERR_LVC2_BMC_N")
	)
	(segment
		(start 124.39142 -19.337528)
		(end 126.84506 -19.337528)
		(width 0.127)
		(layer "In15.Cu")
		(net "H_CPU_CATERR_LVC2_BMC_N")
	)
	(segment
		(start 138.62304 -16.868648)
		(end 141.02842 -14.463268)
		(width 0.127)
		(layer "In15.Cu")
		(net "H_CPU_CATERR_LVC2_BMC_N")
	)
	(segment
		(start 168.4909 -7.826248)
		(end 177.70602 -7.826248)
		(width 0.127)
		(layer "In15.Cu")
		(net "H_CPU_CATERR_LVC2_BMC_N")
	)
	(via
		(at 155.1178 -123.27128)
		(size 0.762)
		(drill 0.381)
		(layers "F.Cu" "B.Cu")
		(net "VR_P5V_EN_D")
	)
	(segment
		(start 134.547102 -14.896338)
		(end 134.547102 -13.600176)
		(width 0.12954)
		(layer "F.Cu")
		(net "TP_PCIE_HPM_RXP<1>")
	)
	(segment
		(start 134.385812 -15.057628)
		(end 134.547102 -14.896338)
		(width 0.12954)
		(layer "F.Cu")
		(net "TP_PCIE_HPM_RXP<1>")
	)
	(via
		(at 134.385812 -15.057628)
		(size 0.508)
		(drill 0.254)
		(layers "F.Cu" "B.Cu")
		(net "TP_PCIE_HPM_RXP<1>")
	)
	(segment
		(start 133.090412 -15.004796)
		(end 133.547612 -15.004796)
		(width 0.12954)
		(layer "F.Cu")
		(net "TP_PCIE_HPM_RXN<1>")
	)
	(segment
		(start 133.547612 -15.004796)
		(end 133.9469 -14.605508)
		(width 0.12954)
		(layer "F.Cu")
		(net "TP_PCIE_HPM_RXN<1>")
	)
	(segment
		(start 133.9469 -14.605508)
		(end 133.9469 -13.600176)
		(width 0.12954)
		(layer "F.Cu")
		(net "TP_PCIE_HPM_RXN<1>")
	)
	(via
		(at 133.090412 -15.004796)
		(size 0.508)
		(drill 0.254)
		(layers "F.Cu" "B.Cu")
		(net "TP_PCIE_HPM_RXN<1>")
	)
	(segment
		(start 144.74698 -13.600176)
		(end 144.74698 -12.27328)
		(width 0.12954)
		(layer "F.Cu")
		(net "TP_HPM_STBY_EN")
	)
	(segment
		(start 144.74698 -12.27328)
		(end 144.832832 -12.187428)
		(width 0.12954)
		(layer "F.Cu")
		(net "TP_HPM_STBY_EN")
	)
	(via
		(at 144.832832 -12.187428)
		(size 0.508)
		(drill 0.254)
		(layers "F.Cu" "B.Cu")
		(net "TP_HPM_STBY_EN")
	)
	(segment
		(start 203.52258 -157.508448)
		(end 202.43038 -157.508448)
		(width 0.12954)
		(layer "F.Cu")
		(net "SMB_BMC_SWB_EN")
	)
	(segment
		(start 356.244144 -400.328638)
		(end 357.294942 -400.328638)
		(width 0.12954)
		(layer "F.Cu")
		(net "SMB_BMC_SWB_EN")
	)
	(segment
		(start 246.08028 -160.061148)
		(end 240.26368 -154.244548)
		(width 0.12954)
		(layer "F.Cu")
		(net "SMB_BMC_SWB_EN")
	)
	(segment
		(start 206.78648 -154.244548)
		(end 203.52258 -157.508448)
		(width 0.12954)
		(layer "F.Cu")
		(net "SMB_BMC_SWB_EN")
	)
	(segment
		(start 357.294942 -400.328638)
		(end 357.320342 -400.354038)
		(width 0.12954)
		(layer "F.Cu")
		(net "SMB_BMC_SWB_EN")
	)
	(segment
		(start 244.78488 -166.944548)
		(end 244.78488 -166.792148)
		(width 0.12954)
		(layer "F.Cu")
		(net "SMB_BMC_SWB_EN")
	)
	(segment
		(start 170.155616 -107.375452)
		(end 169.755566 -106.975402)
		(width 0.12954)
		(layer "F.Cu")
		(net "SMB_BMC_SWB_EN")
	)
	(segment
		(start 355.131878 -400.328638)
		(end 356.244144 -400.328638)
		(width 0.12954)
		(layer "F.Cu")
		(net "SMB_BMC_SWB_EN")
	)
	(segment
		(start 240.26368 -154.244548)
		(end 206.78648 -154.244548)
		(width 0.12954)
		(layer "F.Cu")
		(net "SMB_BMC_SWB_EN")
	)
	(segment
		(start 202.43038 -157.508448)
		(end 201.85888 -156.936948)
		(width 0.12954)
		(layer "F.Cu")
		(net "SMB_BMC_SWB_EN")
	)
	(segment
		(start 244.78488 -166.792148)
		(end 246.08028 -165.496748)
		(width 0.12954)
		(layer "F.Cu")
		(net "SMB_BMC_SWB_EN")
	)
	(segment
		(start 165.941502 -431.487326)
		(end 165.15715 -431.487326)
		(width 0.12954)
		(layer "F.Cu")
		(net "SMB_BMC_SWB_EN")
	)
	(segment
		(start 165.96868 -431.460148)
		(end 165.941502 -431.487326)
		(width 0.12954)
		(layer "F.Cu")
		(net "SMB_BMC_SWB_EN")
	)
	(segment
		(start 246.08028 -165.496748)
		(end 246.08028 -160.061148)
		(width 0.12954)
		(layer "F.Cu")
		(net "SMB_BMC_SWB_EN")
	)
	(via
		(at 165.96868 -431.460148)
		(size 0.508)
		(drill 0.254)
		(layers "F.Cu" "B.Cu")
		(net "SMB_BMC_SWB_EN")
	)
	(via
		(at 356.244144 -400.328638)
		(size 0.508)
		(drill 0.254)
		(layers "F.Cu" "B.Cu")
		(net "SMB_BMC_SWB_EN")
	)
	(via
		(at 201.85888 -156.936948)
		(size 0.508)
		(drill 0.254)
		(layers "F.Cu" "B.Cu")
		(net "SMB_BMC_SWB_EN")
	)
	(via
		(at 175.774604 -401.44446)
		(size 0.508)
		(drill 0.254)
		(layers "F.Cu" "B.Cu")
		(net "SMB_BMC_SWB_EN")
	)
	(via
		(at 169.755566 -106.975402)
		(size 0.4572)
		(drill 0.254)
		(layers "F.Cu" "B.Cu")
		(net "SMB_BMC_SWB_EN")
	)
	(via
		(at 303.40554 -397.021304)
		(size 0.508)
		(drill 0.254)
		(layers "F.Cu" "B.Cu")
		(net "SMB_BMC_SWB_EN")
	)
	(via
		(at 244.78488 -166.944548)
		(size 0.508)
		(drill 0.254)
		(layers "F.Cu" "B.Cu")
		(net "SMB_BMC_SWB_EN")
	)
	(via
		(at 191.57188 -134.737348)
		(size 0.508)
		(drill 0.254)
		(layers "F.Cu" "B.Cu")
		(net "SMB_BMC_SWB_EN")
	)
	(via
		(at 202.62088 -108.816648)
		(size 0.508)
		(drill 0.254)
		(layers "F.Cu" "B.Cu")
		(net "SMB_BMC_SWB_EN")
	)
	(segment
		(start 191.57188 -133.187948)
		(end 191.57188 -134.737348)
		(width 0.12954)
		(layer "B.Cu")
		(net "SMB_BMC_SWB_EN")
	)
	(segment
		(start 202.391518 -109.04601)
		(end 202.391518 -110.59033)
		(width 0.12954)
		(layer "B.Cu")
		(net "SMB_BMC_SWB_EN")
	)
	(segment
		(start 192.33388 -132.425948)
		(end 191.57188 -133.187948)
		(width 0.12954)
		(layer "B.Cu")
		(net "SMB_BMC_SWB_EN")
	)
	(segment
		(start 198.17334 -129.324608)
		(end 195.072 -132.425948)
		(width 0.12954)
		(layer "B.Cu")
		(net "SMB_BMC_SWB_EN")
	)
	(segment
		(start 202.391518 -110.59033)
		(end 201.0664 -111.915448)
		(width 0.12954)
		(layer "B.Cu")
		(net "SMB_BMC_SWB_EN")
	)
	(segment
		(start 195.072 -132.425948)
		(end 192.33388 -132.425948)
		(width 0.12954)
		(layer "B.Cu")
		(net "SMB_BMC_SWB_EN")
	)
	(segment
		(start 201.0664 -124.760228)
		(end 198.17334 -127.653288)
		(width 0.12954)
		(layer "B.Cu")
		(net "SMB_BMC_SWB_EN")
	)
	(segment
		(start 201.0664 -111.915448)
		(end 201.0664 -124.760228)
		(width 0.12954)
		(layer "B.Cu")
		(net "SMB_BMC_SWB_EN")
	)
	(segment
		(start 198.17334 -127.653288)
		(end 198.17334 -129.324608)
		(width 0.12954)
		(layer "B.Cu")
		(net "SMB_BMC_SWB_EN")
	)
	(segment
		(start 202.62088 -108.816648)
		(end 202.391518 -109.04601)
		(width 0.12954)
		(layer "B.Cu")
		(net "SMB_BMC_SWB_EN")
	)
	(segment
		(start 198.52894 -106.845608)
		(end 199.81418 -108.130848)
		(width 0.127)
		(layer "In2.Cu")
		(net "SMB_BMC_SWB_EN")
	)
	(segment
		(start 191.57188 -135.010652)
		(end 191.57188 -134.737348)
		(width 0.127)
		(layer "In2.Cu")
		(net "SMB_BMC_SWB_EN")
	)
	(segment
		(start 247.59666 -241.022378)
		(end 247.59666 -168.904158)
		(width 0.127)
		(layer "In2.Cu")
		(net "SMB_BMC_SWB_EN")
	)
	(segment
		(start 202.86218 -149.583648)
		(end 202.13828 -148.859748)
		(width 0.127)
		(layer "In2.Cu")
		(net "SMB_BMC_SWB_EN")
	)
	(segment
		(start 173.355 -105.123488)
		(end 173.355 -105.578148)
		(width 0.127)
		(layer "In2.Cu")
		(net "SMB_BMC_SWB_EN")
	)
	(segment
		(start 170.95724 -105.164128)
		(end 171.27728 -104.844088)
		(width 0.127)
		(layer "In2.Cu")
		(net "SMB_BMC_SWB_EN")
	)
	(segment
		(start 173.0756 -104.844088)
		(end 173.355 -105.123488)
		(width 0.127)
		(layer "In2.Cu")
		(net "SMB_BMC_SWB_EN")
	)
	(segment
		(start 202.13828 -145.577052)
		(end 191.57188 -135.010652)
		(width 0.127)
		(layer "In2.Cu")
		(net "SMB_BMC_SWB_EN")
	)
	(segment
		(start 180.7591 -110.576868)
		(end 186.4868 -110.576868)
		(width 0.127)
		(layer "In2.Cu")
		(net "SMB_BMC_SWB_EN")
	)
	(segment
		(start 186.4868 -110.576868)
		(end 190.21806 -106.845608)
		(width 0.127)
		(layer "In2.Cu")
		(net "SMB_BMC_SWB_EN")
	)
	(segment
		(start 171.27728 -104.844088)
		(end 173.0756 -104.844088)
		(width 0.127)
		(layer "In2.Cu")
		(net "SMB_BMC_SWB_EN")
	)
	(segment
		(start 177.1269 -392.289792)
		(end 198.675752 -370.74094)
		(width 0.127)
		(layer "In2.Cu")
		(net "SMB_BMC_SWB_EN")
	)
	(segment
		(start 223.39808 -344.993214)
		(end 247.8278 -320.563494)
		(width 0.127)
		(layer "In2.Cu")
		(net "SMB_BMC_SWB_EN")
	)
	(segment
		(start 180.56098 -110.378748)
		(end 180.7591 -110.576868)
		(width 0.127)
		(layer "In2.Cu")
		(net "SMB_BMC_SWB_EN")
	)
	(segment
		(start 173.5582 -105.781348)
		(end 173.9646 -105.781348)
		(width 0.127)
		(layer "In2.Cu")
		(net "SMB_BMC_SWB_EN")
	)
	(segment
		(start 169.755566 -106.975402)
		(end 170.95724 -105.773728)
		(width 0.127)
		(layer "In2.Cu")
		(net "SMB_BMC_SWB_EN")
	)
	(segment
		(start 247.8278 -241.253518)
		(end 247.59666 -241.022378)
		(width 0.127)
		(layer "In2.Cu")
		(net "SMB_BMC_SWB_EN")
	)
	(segment
		(start 201.55408 -154.472132)
		(end 203.38288 -152.643332)
		(width 0.127)
		(layer "In2.Cu")
		(net "SMB_BMC_SWB_EN")
	)
	(segment
		(start 199.81418 -108.130848)
		(end 201.93508 -108.130848)
		(width 0.127)
		(layer "In2.Cu")
		(net "SMB_BMC_SWB_EN")
	)
	(segment
		(start 198.675752 -370.74094)
		(end 215.28405 -370.74094)
		(width 0.127)
		(layer "In2.Cu")
		(net "SMB_BMC_SWB_EN")
	)
	(segment
		(start 176.367694 -108.168948)
		(end 176.562766 -108.36402)
		(width 0.127)
		(layer "In2.Cu")
		(net "SMB_BMC_SWB_EN")
	)
	(segment
		(start 223.39808 -362.62691)
		(end 223.39808 -344.993214)
		(width 0.127)
		(layer "In2.Cu")
		(net "SMB_BMC_SWB_EN")
	)
	(segment
		(start 176.786286 -108.968286)
		(end 179.559458 -108.968286)
		(width 0.127)
		(layer "In2.Cu")
		(net "SMB_BMC_SWB_EN")
	)
	(segment
		(start 201.93508 -108.130848)
		(end 202.62088 -108.816648)
		(width 0.127)
		(layer "In2.Cu")
		(net "SMB_BMC_SWB_EN")
	)
	(segment
		(start 173.9646 -105.781348)
		(end 174.9552 -106.771948)
		(width 0.127)
		(layer "In2.Cu")
		(net "SMB_BMC_SWB_EN")
	)
	(segment
		(start 245.63705 -166.944548)
		(end 244.78488 -166.944548)
		(width 0.127)
		(layer "In2.Cu")
		(net "SMB_BMC_SWB_EN")
	)
	(segment
		(start 175.133 -108.168948)
		(end 176.367694 -108.168948)
		(width 0.127)
		(layer "In2.Cu")
		(net "SMB_BMC_SWB_EN")
	)
	(segment
		(start 202.86218 -150.828248)
		(end 202.86218 -149.583648)
		(width 0.127)
		(layer "In2.Cu")
		(net "SMB_BMC_SWB_EN")
	)
	(segment
		(start 202.13828 -148.859748)
		(end 202.13828 -145.577052)
		(width 0.127)
		(layer "In2.Cu")
		(net "SMB_BMC_SWB_EN")
	)
	(segment
		(start 180.56098 -109.969808)
		(end 180.56098 -110.378748)
		(width 0.127)
		(layer "In2.Cu")
		(net "SMB_BMC_SWB_EN")
	)
	(segment
		(start 203.38288 -152.643332)
		(end 203.38288 -151.348948)
		(width 0.127)
		(layer "In2.Cu")
		(net "SMB_BMC_SWB_EN")
	)
	(segment
		(start 247.59666 -168.904158)
		(end 245.63705 -166.944548)
		(width 0.127)
		(layer "In2.Cu")
		(net "SMB_BMC_SWB_EN")
	)
	(segment
		(start 174.9552 -106.771948)
		(end 174.9552 -107.991148)
		(width 0.127)
		(layer "In2.Cu")
		(net "SMB_BMC_SWB_EN")
	)
	(segment
		(start 175.774604 -401.44446)
		(end 175.774604 -399.57121)
		(width 0.127)
		(layer "In2.Cu")
		(net "SMB_BMC_SWB_EN")
	)
	(segment
		(start 201.85888 -156.936948)
		(end 201.55408 -156.632148)
		(width 0.127)
		(layer "In2.Cu")
		(net "SMB_BMC_SWB_EN")
	)
	(segment
		(start 201.55408 -156.632148)
		(end 201.55408 -154.472132)
		(width 0.127)
		(layer "In2.Cu")
		(net "SMB_BMC_SWB_EN")
	)
	(segment
		(start 179.559458 -108.968286)
		(end 180.56098 -109.969808)
		(width 0.127)
		(layer "In2.Cu")
		(net "SMB_BMC_SWB_EN")
	)
	(segment
		(start 215.28405 -370.74094)
		(end 223.39808 -362.62691)
		(width 0.127)
		(layer "In2.Cu")
		(net "SMB_BMC_SWB_EN")
	)
	(segment
		(start 174.9552 -107.991148)
		(end 175.133 -108.168948)
		(width 0.127)
		(layer "In2.Cu")
		(net "SMB_BMC_SWB_EN")
	)
	(segment
		(start 247.8278 -320.563494)
		(end 247.8278 -241.253518)
		(width 0.127)
		(layer "In2.Cu")
		(net "SMB_BMC_SWB_EN")
	)
	(segment
		(start 176.562766 -108.36402)
		(end 176.562766 -108.744766)
		(width 0.127)
		(layer "In2.Cu")
		(net "SMB_BMC_SWB_EN")
	)
	(segment
		(start 190.21806 -106.845608)
		(end 198.52894 -106.845608)
		(width 0.127)
		(layer "In2.Cu")
		(net "SMB_BMC_SWB_EN")
	)
	(segment
		(start 175.774604 -399.57121)
		(end 177.1269 -396.30604)
		(width 0.127)
		(layer "In2.Cu")
		(net "SMB_BMC_SWB_EN")
	)
	(segment
		(start 170.95724 -105.773728)
		(end 170.95724 -105.164128)
		(width 0.127)
		(layer "In2.Cu")
		(net "SMB_BMC_SWB_EN")
	)
	(segment
		(start 176.562766 -108.744766)
		(end 176.786286 -108.968286)
		(width 0.127)
		(layer "In2.Cu")
		(net "SMB_BMC_SWB_EN")
	)
	(segment
		(start 203.38288 -151.348948)
		(end 202.86218 -150.828248)
		(width 0.127)
		(layer "In2.Cu")
		(net "SMB_BMC_SWB_EN")
	)
	(segment
		(start 173.355 -105.578148)
		(end 173.5582 -105.781348)
		(width 0.127)
		(layer "In2.Cu")
		(net "SMB_BMC_SWB_EN")
	)
	(segment
		(start 177.1269 -396.30604)
		(end 177.1269 -392.289792)
		(width 0.127)
		(layer "In2.Cu")
		(net "SMB_BMC_SWB_EN")
	)
	(segment
		(start 285.3436 -439.6486)
		(end 285.3436 -431.392584)
		(width 0.127)
		(layer "In4.Cu")
		(net "SMB_BMC_SWB_EN")
	)
	(segment
		(start 185.859928 -430.22774)
		(end 194.937888 -439.3057)
		(width 0.127)
		(layer "In4.Cu")
		(net "SMB_BMC_SWB_EN")
	)
	(segment
		(start 164.97554 -431.460148)
		(end 165.96868 -431.460148)
		(width 0.127)
		(layer "In4.Cu")
		(net "SMB_BMC_SWB_EN")
	)
	(segment
		(start 173.60519 -407.72207)
		(end 171.92752 -409.39974)
		(width 0.127)
		(layer "In4.Cu")
		(net "SMB_BMC_SWB_EN")
	)
	(segment
		(start 277.255986 -439.3057)
		(end 278.259286 -440.309)
		(width 0.127)
		(layer "In4.Cu")
		(net "SMB_BMC_SWB_EN")
	)
	(segment
		(start 305.435 -418.973)
		(end 305.816 -418.592)
		(width 0.127)
		(layer "In4.Cu")
		(net "SMB_BMC_SWB_EN")
	)
	(segment
		(start 306.0954 -425.6532)
		(end 306.0954 -420.7002)
		(width 0.127)
		(layer "In4.Cu")
		(net "SMB_BMC_SWB_EN")
	)
	(segment
		(start 167.201088 -430.22774)
		(end 185.859928 -430.22774)
		(width 0.127)
		(layer "In4.Cu")
		(net "SMB_BMC_SWB_EN")
	)
	(segment
		(start 173.60519 -406.41143)
		(end 173.60519 -407.72207)
		(width 0.127)
		(layer "In4.Cu")
		(net "SMB_BMC_SWB_EN")
	)
	(segment
		(start 175.774604 -401.44446)
		(end 175.774604 -404.242016)
		(width 0.127)
		(layer "In4.Cu")
		(net "SMB_BMC_SWB_EN")
	)
	(segment
		(start 163.53028 -430.014888)
		(end 164.97554 -431.460148)
		(width 0.127)
		(layer "In4.Cu")
		(net "SMB_BMC_SWB_EN")
	)
	(segment
		(start 163.53028 -423.321988)
		(end 163.53028 -430.014888)
		(width 0.127)
		(layer "In4.Cu")
		(net "SMB_BMC_SWB_EN")
	)
	(segment
		(start 288.606484 -428.1297)
		(end 299.8089 -428.1297)
		(width 0.127)
		(layer "In4.Cu")
		(net "SMB_BMC_SWB_EN")
	)
	(segment
		(start 307.34 -426.8978)
		(end 306.0954 -425.6532)
		(width 0.127)
		(layer "In4.Cu")
		(net "SMB_BMC_SWB_EN")
	)
	(segment
		(start 167.07104 -417.13404)
		(end 167.07104 -419.781228)
		(width 0.127)
		(layer "In4.Cu")
		(net "SMB_BMC_SWB_EN")
	)
	(segment
		(start 306.8066 -430.4538)
		(end 307.34 -429.9204)
		(width 0.127)
		(layer "In4.Cu")
		(net "SMB_BMC_SWB_EN")
	)
	(segment
		(start 305.435 -420.0398)
		(end 305.435 -418.973)
		(width 0.127)
		(layer "In4.Cu")
		(net "SMB_BMC_SWB_EN")
	)
	(segment
		(start 167.07104 -419.781228)
		(end 163.53028 -423.321988)
		(width 0.127)
		(layer "In4.Cu")
		(net "SMB_BMC_SWB_EN")
	)
	(segment
		(start 305.816 -413.3088)
		(end 305.3334 -412.8262)
		(width 0.127)
		(layer "In4.Cu")
		(net "SMB_BMC_SWB_EN")
	)
	(segment
		(start 169.56278 -411.38856)
		(end 169.56278 -414.6423)
		(width 0.127)
		(layer "In4.Cu")
		(net "SMB_BMC_SWB_EN")
	)
	(segment
		(start 285.3436 -431.392584)
		(end 288.606484 -428.1297)
		(width 0.127)
		(layer "In4.Cu")
		(net "SMB_BMC_SWB_EN")
	)
	(segment
		(start 302.95342 -398.660112)
		(end 303.40554 -398.207992)
		(width 0.127)
		(layer "In4.Cu")
		(net "SMB_BMC_SWB_EN")
	)
	(segment
		(start 171.92752 -409.39974)
		(end 171.5516 -409.39974)
		(width 0.127)
		(layer "In4.Cu")
		(net "SMB_BMC_SWB_EN")
	)
	(segment
		(start 194.937888 -439.3057)
		(end 277.255986 -439.3057)
		(width 0.127)
		(layer "In4.Cu")
		(net "SMB_BMC_SWB_EN")
	)
	(segment
		(start 304.0126 -412.8262)
		(end 302.95342 -411.76702)
		(width 0.127)
		(layer "In4.Cu")
		(net "SMB_BMC_SWB_EN")
	)
	(segment
		(start 307.34 -429.9204)
		(end 307.34 -426.8978)
		(width 0.127)
		(layer "In4.Cu")
		(net "SMB_BMC_SWB_EN")
	)
	(segment
		(start 299.8089 -428.1297)
		(end 302.133 -430.4538)
		(width 0.127)
		(layer "In4.Cu")
		(net "SMB_BMC_SWB_EN")
	)
	(segment
		(start 165.96868 -431.460148)
		(end 167.201088 -430.22774)
		(width 0.127)
		(layer "In4.Cu")
		(net "SMB_BMC_SWB_EN")
	)
	(segment
		(start 169.56278 -414.6423)
		(end 167.07104 -417.13404)
		(width 0.127)
		(layer "In4.Cu")
		(net "SMB_BMC_SWB_EN")
	)
	(segment
		(start 305.816 -418.592)
		(end 305.816 -413.3088)
		(width 0.127)
		(layer "In4.Cu")
		(net "SMB_BMC_SWB_EN")
	)
	(segment
		(start 171.5516 -409.39974)
		(end 169.56278 -411.38856)
		(width 0.127)
		(layer "In4.Cu")
		(net "SMB_BMC_SWB_EN")
	)
	(segment
		(start 303.40554 -398.207992)
		(end 303.40554 -397.021304)
		(width 0.127)
		(layer "In4.Cu")
		(net "SMB_BMC_SWB_EN")
	)
	(segment
		(start 175.774604 -404.242016)
		(end 173.60519 -406.41143)
		(width 0.127)
		(layer "In4.Cu")
		(net "SMB_BMC_SWB_EN")
	)
	(segment
		(start 302.95342 -411.76702)
		(end 302.95342 -398.660112)
		(width 0.127)
		(layer "In4.Cu")
		(net "SMB_BMC_SWB_EN")
	)
	(segment
		(start 302.133 -430.4538)
		(end 306.8066 -430.4538)
		(width 0.127)
		(layer "In4.Cu")
		(net "SMB_BMC_SWB_EN")
	)
	(segment
		(start 306.0954 -420.7002)
		(end 305.435 -420.0398)
		(width 0.127)
		(layer "In4.Cu")
		(net "SMB_BMC_SWB_EN")
	)
	(segment
		(start 284.6832 -440.309)
		(end 285.3436 -439.6486)
		(width 0.127)
		(layer "In4.Cu")
		(net "SMB_BMC_SWB_EN")
	)
	(segment
		(start 305.3334 -412.8262)
		(end 304.0126 -412.8262)
		(width 0.127)
		(layer "In4.Cu")
		(net "SMB_BMC_SWB_EN")
	)
	(segment
		(start 278.259286 -440.309)
		(end 284.6832 -440.309)
		(width 0.127)
		(layer "In4.Cu")
		(net "SMB_BMC_SWB_EN")
	)
	(segment
		(start 354.71608 -397.03756)
		(end 354.71608 -399.31848)
		(width 0.127)
		(layer "In6.Cu")
		(net "SMB_BMC_SWB_EN")
	)
	(segment
		(start 304.10912 -395.94282)
		(end 353.62134 -395.94282)
		(width 0.127)
		(layer "In6.Cu")
		(net "SMB_BMC_SWB_EN")
	)
	(segment
		(start 353.62134 -395.94282)
		(end 354.71608 -397.03756)
		(width 0.127)
		(layer "In6.Cu")
		(net "SMB_BMC_SWB_EN")
	)
	(segment
		(start 303.40554 -397.021304)
		(end 303.40554 -396.6464)
		(width 0.127)
		(layer "In6.Cu")
		(net "SMB_BMC_SWB_EN")
	)
	(segment
		(start 303.40554 -396.6464)
		(end 304.10912 -395.94282)
		(width 0.127)
		(layer "In6.Cu")
		(net "SMB_BMC_SWB_EN")
	)
	(segment
		(start 355.726238 -400.328638)
		(end 356.244144 -400.328638)
		(width 0.127)
		(layer "In6.Cu")
		(net "SMB_BMC_SWB_EN")
	)
	(segment
		(start 354.71608 -399.31848)
		(end 355.726238 -400.328638)
		(width 0.127)
		(layer "In6.Cu")
		(net "SMB_BMC_SWB_EN")
	)
	(segment
		(start 45.248068 -437.792368)
		(end 45.248068 -437.045608)
		(width 0.12954)
		(layer "F.Cu")
		(net "SMB_BMC_GPU_EN")
	)
	(segment
		(start 39.40683 -435.955948)
		(end 39.40683 -435.233318)
		(width 0.12954)
		(layer "F.Cu")
		(net "SMB_BMC_GPU_EN")
	)
	(segment
		(start 174.955708 -110.575344)
		(end 174.555658 -110.175294)
		(width 0.12954)
		(layer "F.Cu")
		(net "SMB_BMC_GPU_EN")
	)
	(via
		(at 174.555658 -110.175294)
		(size 0.4572)
		(drill 0.254)
		(layers "F.Cu" "B.Cu")
		(net "SMB_BMC_GPU_EN")
	)
	(via
		(at 45.248068 -437.045608)
		(size 0.508)
		(drill 0.254)
		(layers "F.Cu" "B.Cu")
		(net "SMB_BMC_GPU_EN")
	)
	(via
		(at 150.4696 -121.707148)
		(size 0.508)
		(drill 0.254)
		(layers "F.Cu" "B.Cu")
		(net "SMB_BMC_GPU_EN")
	)
	(via
		(at 39.40683 -435.233318)
		(size 0.508)
		(drill 0.254)
		(layers "F.Cu" "B.Cu")
		(net "SMB_BMC_GPU_EN")
	)
	(via
		(at 151.60752 -135.842248)
		(size 0.508)
		(drill 0.254)
		(layers "F.Cu" "B.Cu")
		(net "SMB_BMC_GPU_EN")
	)
	(via
		(at 22.48408 -379.725428)
		(size 0.508)
		(drill 0.254)
		(layers "F.Cu" "B.Cu")
		(net "SMB_BMC_GPU_EN")
	)
	(segment
		(start 17.95018 -418.475668)
		(end 25.02916 -418.475668)
		(width 0.12954)
		(layer "B.Cu")
		(net "SMB_BMC_GPU_EN")
	)
	(segment
		(start 39.3954 -435.244748)
		(end 39.40683 -435.233318)
		(width 0.12954)
		(layer "B.Cu")
		(net "SMB_BMC_GPU_EN")
	)
	(segment
		(start 153.6192 -117.0178)
		(end 153.6192 -117.5766)
		(width 0.12954)
		(layer "B.Cu")
		(net "SMB_BMC_GPU_EN")
	)
	(segment
		(start 22.48408 -379.725428)
		(end 22.186392 -379.42774)
		(width 0.12954)
		(layer "B.Cu")
		(net "SMB_BMC_GPU_EN")
	)
	(segment
		(start 152.4 -114.6048)
		(end 152.4 -115.7986)
		(width 0.12954)
		(layer "B.Cu")
		(net "SMB_BMC_GPU_EN")
	)
	(segment
		(start 160.56991 -110.049818)
		(end 158.750254 -110.049818)
		(width 0.12954)
		(layer "B.Cu")
		(net "SMB_BMC_GPU_EN")
	)
	(segment
		(start 27.69362 -433.527708)
		(end 29.1338 -434.967888)
		(width 0.12954)
		(layer "B.Cu")
		(net "SMB_BMC_GPU_EN")
	)
	(segment
		(start 38.43274 -434.259228)
		(end 39.40683 -435.233318)
		(width 0.12954)
		(layer "B.Cu")
		(net "SMB_BMC_GPU_EN")
	)
	(segment
		(start 158.750254 -110.049818)
		(end 158.192724 -109.492288)
		(width 0.12954)
		(layer "B.Cu")
		(net "SMB_BMC_GPU_EN")
	)
	(segment
		(start 161.39922 -110.879128)
		(end 160.56991 -110.049818)
		(width 0.12954)
		(layer "B.Cu")
		(net "SMB_BMC_GPU_EN")
	)
	(segment
		(start 45.248068 -437.045608)
		(end 45.101256 -437.045608)
		(width 0.12954)
		(layer "B.Cu")
		(net "SMB_BMC_GPU_EN")
	)
	(segment
		(start 152.9588 -119.923052)
		(end 155.51277 -122.477022)
		(width 0.12954)
		(layer "B.Cu")
		(net "SMB_BMC_GPU_EN")
	)
	(segment
		(start 174.555658 -110.175294)
		(end 174.159164 -110.571788)
		(width 0.12954)
		(layer "B.Cu")
		(net "SMB_BMC_GPU_EN")
	)
	(segment
		(start 7.04596 -381.66802)
		(end 7.04596 -401.61972)
		(width 0.12954)
		(layer "B.Cu")
		(net "SMB_BMC_GPU_EN")
	)
	(segment
		(start 169.43324 -110.571788)
		(end 169.1259 -110.879128)
		(width 0.12954)
		(layer "B.Cu")
		(net "SMB_BMC_GPU_EN")
	)
	(segment
		(start 156.72562 -132.654548)
		(end 153.53792 -135.842248)
		(width 0.12954)
		(layer "B.Cu")
		(net "SMB_BMC_GPU_EN")
	)
	(segment
		(start 169.1259 -110.879128)
		(end 161.39922 -110.879128)
		(width 0.12954)
		(layer "B.Cu")
		(net "SMB_BMC_GPU_EN")
	)
	(segment
		(start 27.69362 -421.140128)
		(end 27.69362 -433.527708)
		(width 0.12954)
		(layer "B.Cu")
		(net "SMB_BMC_GPU_EN")
	)
	(segment
		(start 22.186392 -379.42774)
		(end 9.28624 -379.42774)
		(width 0.12954)
		(layer "B.Cu")
		(net "SMB_BMC_GPU_EN")
	)
	(segment
		(start 9.28624 -379.42774)
		(end 7.04596 -381.66802)
		(width 0.12954)
		(layer "B.Cu")
		(net "SMB_BMC_GPU_EN")
	)
	(segment
		(start 12.14374 -406.7175)
		(end 12.14374 -412.669228)
		(width 0.12954)
		(layer "B.Cu")
		(net "SMB_BMC_GPU_EN")
	)
	(segment
		(start 155.51277 -128.471422)
		(end 156.72562 -129.684272)
		(width 0.12954)
		(layer "B.Cu")
		(net "SMB_BMC_GPU_EN")
	)
	(segment
		(start 36.1188 -434.259228)
		(end 38.43274 -434.259228)
		(width 0.12954)
		(layer "B.Cu")
		(net "SMB_BMC_GPU_EN")
	)
	(segment
		(start 152.4 -115.7986)
		(end 153.6192 -117.0178)
		(width 0.12954)
		(layer "B.Cu")
		(net "SMB_BMC_GPU_EN")
	)
	(segment
		(start 156.72562 -129.684272)
		(end 156.72562 -132.654548)
		(width 0.12954)
		(layer "B.Cu")
		(net "SMB_BMC_GPU_EN")
	)
	(segment
		(start 29.1338 -434.967888)
		(end 35.41014 -434.967888)
		(width 0.12954)
		(layer "B.Cu")
		(net "SMB_BMC_GPU_EN")
	)
	(segment
		(start 152.9588 -118.237)
		(end 152.9588 -119.923052)
		(width 0.12954)
		(layer "B.Cu")
		(net "SMB_BMC_GPU_EN")
	)
	(segment
		(start 39.663624 -435.490112)
		(end 39.40683 -435.233318)
		(width 0.12954)
		(layer "B.Cu")
		(net "SMB_BMC_GPU_EN")
	)
	(segment
		(start 39.3954 -436.246778)
		(end 39.3954 -435.244748)
		(width 0.12954)
		(layer "B.Cu")
		(net "SMB_BMC_GPU_EN")
	)
	(segment
		(start 153.53792 -135.842248)
		(end 151.60752 -135.842248)
		(width 0.12954)
		(layer "B.Cu")
		(net "SMB_BMC_GPU_EN")
	)
	(segment
		(start 7.04596 -401.61972)
		(end 12.14374 -406.7175)
		(width 0.12954)
		(layer "B.Cu")
		(net "SMB_BMC_GPU_EN")
	)
	(segment
		(start 25.02916 -418.475668)
		(end 27.69362 -421.140128)
		(width 0.12954)
		(layer "B.Cu")
		(net "SMB_BMC_GPU_EN")
	)
	(segment
		(start 153.1366 -110.875826)
		(end 153.1366 -113.8682)
		(width 0.12954)
		(layer "B.Cu")
		(net "SMB_BMC_GPU_EN")
	)
	(segment
		(start 12.14374 -412.669228)
		(end 17.95018 -418.475668)
		(width 0.12954)
		(layer "B.Cu")
		(net "SMB_BMC_GPU_EN")
	)
	(segment
		(start 45.101256 -437.045608)
		(end 43.54576 -435.490112)
		(width 0.12954)
		(layer "B.Cu")
		(net "SMB_BMC_GPU_EN")
	)
	(segment
		(start 154.520138 -109.492288)
		(end 153.1366 -110.875826)
		(width 0.12954)
		(layer "B.Cu")
		(net "SMB_BMC_GPU_EN")
	)
	(segment
		(start 153.6192 -117.5766)
		(end 152.9588 -118.237)
		(width 0.12954)
		(layer "B.Cu")
		(net "SMB_BMC_GPU_EN")
	)
	(segment
		(start 158.192724 -109.492288)
		(end 154.520138 -109.492288)
		(width 0.12954)
		(layer "B.Cu")
		(net "SMB_BMC_GPU_EN")
	)
	(segment
		(start 153.1366 -113.8682)
		(end 152.4 -114.6048)
		(width 0.12954)
		(layer "B.Cu")
		(net "SMB_BMC_GPU_EN")
	)
	(segment
		(start 174.159164 -110.571788)
		(end 169.43324 -110.571788)
		(width 0.12954)
		(layer "B.Cu")
		(net "SMB_BMC_GPU_EN")
	)
	(segment
		(start 155.51277 -122.477022)
		(end 155.51277 -128.471422)
		(width 0.12954)
		(layer "B.Cu")
		(net "SMB_BMC_GPU_EN")
	)
	(segment
		(start 35.41014 -434.967888)
		(end 36.1188 -434.259228)
		(width 0.12954)
		(layer "B.Cu")
		(net "SMB_BMC_GPU_EN")
	)
	(segment
		(start 43.54576 -435.490112)
		(end 39.663624 -435.490112)
		(width 0.12954)
		(layer "B.Cu")
		(net "SMB_BMC_GPU_EN")
	)
	(segment
		(start 150.1648 -123.789948)
		(end 150.1648 -126.456948)
		(width 0.127)
		(layer "In11.Cu")
		(net "SMB_BMC_GPU_EN")
	)
	(segment
		(start 148.7932 -127.828548)
		(end 148.7932 -133.027928)
		(width 0.127)
		(layer "In11.Cu")
		(net "SMB_BMC_GPU_EN")
	)
	(segment
		(start 150.1648 -126.456948)
		(end 148.7932 -127.828548)
		(width 0.127)
		(layer "In11.Cu")
		(net "SMB_BMC_GPU_EN")
	)
	(segment
		(start 150.4696 -123.485148)
		(end 150.1648 -123.789948)
		(width 0.127)
		(layer "In11.Cu")
		(net "SMB_BMC_GPU_EN")
	)
	(segment
		(start 148.7932 -133.027928)
		(end 151.60752 -135.842248)
		(width 0.127)
		(layer "In11.Cu")
		(net "SMB_BMC_GPU_EN")
	)
	(segment
		(start 150.4696 -121.707148)
		(end 150.4696 -123.485148)
		(width 0.127)
		(layer "In11.Cu")
		(net "SMB_BMC_GPU_EN")
	)
	(segment
		(start 103.43515 -118.506748)
		(end 106.07675 -115.865148)
		(width 0.127)
		(layer "In13.Cu")
		(net "SMB_BMC_GPU_EN")
	)
	(segment
		(start 7.493 -255.946148)
		(end 6.9088 -255.361948)
		(width 0.127)
		(layer "In13.Cu")
		(net "SMB_BMC_GPU_EN")
	)
	(segment
		(start 7.493 -252.538738)
		(end 7.493 -195.058538)
		(width 0.127)
		(layer "In13.Cu")
		(net "SMB_BMC_GPU_EN")
	)
	(segment
		(start 7.493 -195.058538)
		(end 8.382 -194.169538)
		(width 0.127)
		(layer "In13.Cu")
		(net "SMB_BMC_GPU_EN")
	)
	(segment
		(start 49.151286 -118.509288)
		(end 50.215546 -119.573548)
		(width 0.127)
		(layer "In13.Cu")
		(net "SMB_BMC_GPU_EN")
	)
	(segment
		(start 21.05914 -348.698058)
		(end 6.9088 -334.547718)
		(width 0.127)
		(layer "In13.Cu")
		(net "SMB_BMC_GPU_EN")
	)
	(segment
		(start 21.12645 -118.509288)
		(end 49.151286 -118.509288)
		(width 0.127)
		(layer "In13.Cu")
		(net "SMB_BMC_GPU_EN")
	)
	(segment
		(start 22.48408 -379.725428)
		(end 21.05914 -378.300488)
		(width 0.127)
		(layer "In13.Cu")
		(net "SMB_BMC_GPU_EN")
	)
	(segment
		(start 15.4432 -153.410158)
		(end 15.4432 -124.192538)
		(width 0.127)
		(layer "In13.Cu")
		(net "SMB_BMC_GPU_EN")
	)
	(segment
		(start 15.4432 -124.192538)
		(end 21.12645 -118.509288)
		(width 0.127)
		(layer "In13.Cu")
		(net "SMB_BMC_GPU_EN")
	)
	(segment
		(start 6.9088 -253.122938)
		(end 7.493 -252.538738)
		(width 0.127)
		(layer "In13.Cu")
		(net "SMB_BMC_GPU_EN")
	)
	(segment
		(start 50.215546 -119.573548)
		(end 94.23527 -119.573548)
		(width 0.127)
		(layer "In13.Cu")
		(net "SMB_BMC_GPU_EN")
	)
	(segment
		(start 132.42798 -115.839748)
		(end 132.739384 -116.151152)
		(width 0.127)
		(layer "In13.Cu")
		(net "SMB_BMC_GPU_EN")
	)
	(segment
		(start 131.37261 -115.839748)
		(end 132.42798 -115.839748)
		(width 0.127)
		(layer "In13.Cu")
		(net "SMB_BMC_GPU_EN")
	)
	(segment
		(start 106.07675 -115.865148)
		(end 126.98095 -115.865148)
		(width 0.127)
		(layer "In13.Cu")
		(net "SMB_BMC_GPU_EN")
	)
	(segment
		(start 9.2202 -323.891148)
		(end 9.2202 -322.113148)
		(width 0.127)
		(layer "In13.Cu")
		(net "SMB_BMC_GPU_EN")
	)
	(segment
		(start 8.382 -194.169538)
		(end 8.382 -191.484758)
		(width 0.127)
		(layer "In13.Cu")
		(net "SMB_BMC_GPU_EN")
	)
	(segment
		(start 132.739384 -116.151152)
		(end 137.901934 -116.151152)
		(width 0.127)
		(layer "In13.Cu")
		(net "SMB_BMC_GPU_EN")
	)
	(segment
		(start 126.98095 -115.865148)
		(end 127.56515 -115.280948)
		(width 0.127)
		(layer "In13.Cu")
		(net "SMB_BMC_GPU_EN")
	)
	(segment
		(start 17.1196 -155.086558)
		(end 15.4432 -153.410158)
		(width 0.127)
		(layer "In13.Cu")
		(net "SMB_BMC_GPU_EN")
	)
	(segment
		(start 6.9088 -334.547718)
		(end 6.9088 -326.202548)
		(width 0.127)
		(layer "In13.Cu")
		(net "SMB_BMC_GPU_EN")
	)
	(segment
		(start 95.30207 -118.506748)
		(end 103.43515 -118.506748)
		(width 0.127)
		(layer "In13.Cu")
		(net "SMB_BMC_GPU_EN")
	)
	(segment
		(start 8.382 -191.484758)
		(end 6.8834 -189.986158)
		(width 0.127)
		(layer "In13.Cu")
		(net "SMB_BMC_GPU_EN")
	)
	(segment
		(start 140.526008 -116.691156)
		(end 144.2974 -120.462548)
		(width 0.127)
		(layer "In13.Cu")
		(net "SMB_BMC_GPU_EN")
	)
	(segment
		(start 127.56515 -115.280948)
		(end 130.81381 -115.280948)
		(width 0.127)
		(layer "In13.Cu")
		(net "SMB_BMC_GPU_EN")
	)
	(segment
		(start 137.901934 -116.151152)
		(end 138.441938 -116.691156)
		(width 0.127)
		(layer "In13.Cu")
		(net "SMB_BMC_GPU_EN")
	)
	(segment
		(start 6.9088 -326.202548)
		(end 9.2202 -323.891148)
		(width 0.127)
		(layer "In13.Cu")
		(net "SMB_BMC_GPU_EN")
	)
	(segment
		(start 9.2202 -322.113148)
		(end 7.493 -320.385948)
		(width 0.127)
		(layer "In13.Cu")
		(net "SMB_BMC_GPU_EN")
	)
	(segment
		(start 6.9088 -255.361948)
		(end 6.9088 -253.122938)
		(width 0.127)
		(layer "In13.Cu")
		(net "SMB_BMC_GPU_EN")
	)
	(segment
		(start 138.441938 -116.691156)
		(end 140.526008 -116.691156)
		(width 0.127)
		(layer "In13.Cu")
		(net "SMB_BMC_GPU_EN")
	)
	(segment
		(start 7.493 -320.385948)
		(end 7.493 -255.946148)
		(width 0.127)
		(layer "In13.Cu")
		(net "SMB_BMC_GPU_EN")
	)
	(segment
		(start 94.23527 -119.573548)
		(end 95.30207 -118.506748)
		(width 0.127)
		(layer "In13.Cu")
		(net "SMB_BMC_GPU_EN")
	)
	(segment
		(start 6.8834 -173.062138)
		(end 17.1196 -162.825938)
		(width 0.127)
		(layer "In13.Cu")
		(net "SMB_BMC_GPU_EN")
	)
	(segment
		(start 144.2974 -120.462548)
		(end 149.225 -120.462548)
		(width 0.127)
		(layer "In13.Cu")
		(net "SMB_BMC_GPU_EN")
	)
	(segment
		(start 17.1196 -162.825938)
		(end 17.1196 -155.086558)
		(width 0.127)
		(layer "In13.Cu")
		(net "SMB_BMC_GPU_EN")
	)
	(segment
		(start 6.8834 -189.986158)
		(end 6.8834 -173.062138)
		(width 0.127)
		(layer "In13.Cu")
		(net "SMB_BMC_GPU_EN")
	)
	(segment
		(start 149.225 -120.462548)
		(end 150.4696 -121.707148)
		(width 0.127)
		(layer "In13.Cu")
		(net "SMB_BMC_GPU_EN")
	)
	(segment
		(start 21.05914 -378.300488)
		(end 21.05914 -348.698058)
		(width 0.127)
		(layer "In13.Cu")
		(net "SMB_BMC_GPU_EN")
	)
	(segment
		(start 130.81381 -115.280948)
		(end 131.37261 -115.839748)
		(width 0.127)
		(layer "In13.Cu")
		(net "SMB_BMC_GPU_EN")
	)
	(segment
		(start 149.03704 -129.967482)
		(end 149.03704 -130.632962)
		(width 0.12954)
		(layer "F.Cu")
		(net "PWRGD_PS_PWROK_PLD_N")
	)
	(segment
		(start 147.84705 -130.647948)
		(end 147.84705 -129.625598)
		(width 0.12954)
		(layer "F.Cu")
		(net "PWRGD_PS_PWROK_PLD_N")
	)
	(segment
		(start 149.03704 -130.632962)
		(end 149.464014 -130.632962)
		(width 0.12954)
		(layer "F.Cu")
		(net "PWRGD_PS_PWROK_PLD_N")
	)
	(segment
		(start 149.606 -130.774948)
		(end 149.606 -131.155948)
		(width 0.12954)
		(layer "F.Cu")
		(net "PWRGD_PS_PWROK_PLD_N")
	)
	(segment
		(start 148.1201 -129.352548)
		(end 148.422106 -129.352548)
		(width 0.12954)
		(layer "F.Cu")
		(net "PWRGD_PS_PWROK_PLD_N")
	)
	(segment
		(start 149.479 -131.282948)
		(end 149.03704 -131.282948)
		(width 0.12954)
		(layer "F.Cu")
		(net "PWRGD_PS_PWROK_PLD_N")
	)
	(segment
		(start 149.606 -131.155948)
		(end 149.479 -131.282948)
		(width 0.12954)
		(layer "F.Cu")
		(net "PWRGD_PS_PWROK_PLD_N")
	)
	(segment
		(start 149.464014 -130.632962)
		(end 149.606 -130.774948)
		(width 0.12954)
		(layer "F.Cu")
		(net "PWRGD_PS_PWROK_PLD_N")
	)
	(segment
		(start 148.422106 -129.352548)
		(end 149.03704 -129.967482)
		(width 0.12954)
		(layer "F.Cu")
		(net "PWRGD_PS_PWROK_PLD_N")
	)
	(segment
		(start 147.84705 -129.625598)
		(end 148.1201 -129.352548)
		(width 0.12954)
		(layer "F.Cu")
		(net "PWRGD_PS_PWROK_PLD_N")
	)
	(via
		(at 148.1201 -129.352548)
		(size 0.762)
		(drill 0.381)
		(layers "F.Cu" "B.Cu")
		(net "PWRGD_PS_PWROK_PLD_N")
	)
	(segment
		(start 174.117 -135.219948)
		(end 174.117 -133.060694)
		(width 0.12954)
		(layer "F.Cu")
		(net "PWRGD_PS_PWROK_PLD_ISO")
	)
	(segment
		(start 174.117 -133.060694)
		(end 172.77588 -131.719574)
		(width 0.12954)
		(layer "F.Cu")
		(net "PWRGD_PS_PWROK_PLD_ISO")
	)
	(segment
		(start 155.702 -135.981948)
		(end 173.355 -135.981948)
		(width 0.12954)
		(layer "F.Cu")
		(net "PWRGD_PS_PWROK_PLD_ISO")
	)
	(segment
		(start 172.77588 -131.719574)
		(end 172.77588 -130.666998)
		(width 0.12954)
		(layer "F.Cu")
		(net "PWRGD_PS_PWROK_PLD_ISO")
	)
	(segment
		(start 151.02205 -133.314948)
		(end 152.3746 -133.314948)
		(width 0.12954)
		(layer "F.Cu")
		(net "PWRGD_PS_PWROK_PLD_ISO")
	)
	(segment
		(start 153.035 -133.314948)
		(end 155.702 -135.981948)
		(width 0.12954)
		(layer "F.Cu")
		(net "PWRGD_PS_PWROK_PLD_ISO")
	)
	(segment
		(start 150.93696 -131.932934)
		(end 150.93696 -133.229858)
		(width 0.12954)
		(layer "F.Cu")
		(net "PWRGD_PS_PWROK_PLD_ISO")
	)
	(segment
		(start 150.93696 -133.229858)
		(end 151.02205 -133.314948)
		(width 0.12954)
		(layer "F.Cu")
		(net "PWRGD_PS_PWROK_PLD_ISO")
	)
	(segment
		(start 152.3746 -133.314948)
		(end 153.035 -133.314948)
		(width 0.12954)
		(layer "F.Cu")
		(net "PWRGD_PS_PWROK_PLD_ISO")
	)
	(segment
		(start 173.355 -135.981948)
		(end 174.117 -135.219948)
		(width 0.12954)
		(layer "F.Cu")
		(net "PWRGD_PS_PWROK_PLD_ISO")
	)
	(via
		(at 152.3746 -133.314948)
		(size 0.762)
		(drill 0.381)
		(layers "F.Cu" "B.Cu")
		(net "PWRGD_PS_PWROK_PLD_ISO")
	)
	(segment
		(start 126.635002 -154.195018)
		(end 126.635002 -156.35986)
		(width 0.12954)
		(layer "F.Cu")
		(net "PU_FORCE_PWRON")
	)
	(segment
		(start 126.635002 -156.35986)
		(end 126.64059 -156.365448)
		(width 0.12954)
		(layer "F.Cu")
		(net "PU_FORCE_PWRON")
	)
	(segment
		(start 131.715002 -156.39542)
		(end 131.71805 -156.398468)
		(width 0.12954)
		(layer "F.Cu")
		(net "PD_FORCE_PWRON")
	)
	(segment
		(start 131.715002 -154.195018)
		(end 131.715002 -156.39542)
		(width 0.12954)
		(layer "F.Cu")
		(net "PD_FORCE_PWRON")
	)
	(segment
		(start 83.4898 -35.251898)
		(end 82.858864 -35.251898)
		(width 0.12954)
		(layer "F.Cu")
		(net "OCP_V3_2_P3V3_PWRGD")
	)
	(via
		(at 81.34858 -50.917348)
		(size 0.508)
		(drill 0.254)
		(layers "F.Cu" "B.Cu")
		(net "OCP_V3_2_P3V3_PWRGD")
	)
	(via
		(at 82.858864 -35.251898)
		(size 0.508)
		(drill 0.254)
		(layers "F.Cu" "B.Cu")
		(net "OCP_V3_2_P3V3_PWRGD")
	)
	(segment
		(start 81.34858 -52.082446)
		(end 81.34858 -50.917348)
		(width 0.12954)
		(layer "B.Cu")
		(net "OCP_V3_2_P3V3_PWRGD")
	)
	(segment
		(start 80.35163 -52.082446)
		(end 81.34858 -52.082446)
		(width 0.12954)
		(layer "B.Cu")
		(net "OCP_V3_2_P3V3_PWRGD")
	)
	(segment
		(start 81.34858 -50.917348)
		(end 80.8736 -50.442368)
		(width 0.127)
		(layer "In2.Cu")
		(net "OCP_V3_2_P3V3_PWRGD")
	)
	(segment
		(start 80.8736 -50.442368)
		(end 80.8736 -37.237162)
		(width 0.127)
		(layer "In2.Cu")
		(net "OCP_V3_2_P3V3_PWRGD")
	)
	(segment
		(start 80.8736 -37.237162)
		(end 82.858864 -35.251898)
		(width 0.127)
		(layer "In2.Cu")
		(net "OCP_V3_2_P3V3_PWRGD")
	)
	(segment
		(start 390.03605 -30.825948)
		(end 390.03605 -30.190948)
		(width 0.12954)
		(layer "F.Cu")
		(net "OCP_V3_1_P3V3_PWRGD")
	)
	(segment
		(start 429.876966 -101.97719)
		(end 428.880016 -101.97719)
		(width 0.12954)
		(layer "F.Cu")
		(net "OCP_V3_1_P3V3_PWRGD")
	)
	(segment
		(start 429.876966 -102.61219)
		(end 429.876966 -101.97719)
		(width 0.12954)
		(layer "F.Cu")
		(net "OCP_V3_1_P3V3_PWRGD")
	)
	(via
		(at 390.03605 -30.190948)
		(size 0.508)
		(drill 0.254)
		(layers "F.Cu" "B.Cu")
		(net "OCP_V3_1_P3V3_PWRGD")
	)
	(via
		(at 429.876966 -102.61219)
		(size 0.508)
		(drill 0.254)
		(layers "F.Cu" "B.Cu")
		(net "OCP_V3_1_P3V3_PWRGD")
	)
	(segment
		(start 428.293784 -101.029008)
		(end 418.12718 -101.029008)
		(width 0.127)
		(layer "In13.Cu")
		(net "OCP_V3_1_P3V3_PWRGD")
	)
	(segment
		(start 414.44672 -23.652988)
		(end 412.8897 -22.095968)
		(width 0.127)
		(layer "In13.Cu")
		(net "OCP_V3_1_P3V3_PWRGD")
	)
	(segment
		(start 390.03605 -29.473398)
		(end 390.03605 -30.190948)
		(width 0.127)
		(layer "In13.Cu")
		(net "OCP_V3_1_P3V3_PWRGD")
	)
	(segment
		(start 429.876966 -102.61219)
		(end 428.293784 -101.029008)
		(width 0.127)
		(layer "In13.Cu")
		(net "OCP_V3_1_P3V3_PWRGD")
	)
	(segment
		(start 394.29944 -22.095968)
		(end 390.66724 -25.728168)
		(width 0.127)
		(layer "In13.Cu")
		(net "OCP_V3_1_P3V3_PWRGD")
	)
	(segment
		(start 390.66724 -28.842208)
		(end 390.03605 -29.473398)
		(width 0.127)
		(layer "In13.Cu")
		(net "OCP_V3_1_P3V3_PWRGD")
	)
	(segment
		(start 416.47618 -99.378008)
		(end 416.47618 -52.906168)
		(width 0.127)
		(layer "In13.Cu")
		(net "OCP_V3_1_P3V3_PWRGD")
	)
	(segment
		(start 418.12718 -101.029008)
		(end 416.47618 -99.378008)
		(width 0.127)
		(layer "In13.Cu")
		(net "OCP_V3_1_P3V3_PWRGD")
	)
	(segment
		(start 414.44672 -50.876708)
		(end 414.44672 -23.652988)
		(width 0.127)
		(layer "In13.Cu")
		(net "OCP_V3_1_P3V3_PWRGD")
	)
	(segment
		(start 412.8897 -22.095968)
		(end 394.29944 -22.095968)
		(width 0.127)
		(layer "In13.Cu")
		(net "OCP_V3_1_P3V3_PWRGD")
	)
	(segment
		(start 390.66724 -25.728168)
		(end 390.66724 -28.842208)
		(width 0.127)
		(layer "In13.Cu")
		(net "OCP_V3_1_P3V3_PWRGD")
	)
	(segment
		(start 416.47618 -52.906168)
		(end 414.44672 -50.876708)
		(width 0.127)
		(layer "In13.Cu")
		(net "OCP_V3_1_P3V3_PWRGD")
	)
	(segment
		(start 178.1556 -116.975382)
		(end 177.75555 -117.375432)
		(width 0.12954)
		(layer "F.Cu")
		(net "NC_FPGA_PR14B")
	)
	(via
		(at 177.75555 -117.375432)
		(size 0.4572)
		(drill 0.254)
		(layers "F.Cu" "B.Cu")
		(net "NC_FPGA_PR14B")
	)
	(via
		(at 175.31588 -125.955298)
		(size 0.508)
		(drill 0.254)
		(layers "F.Cu" "B.Cu")
		(net "NC_FPGA_PR14B")
	)
	(segment
		(start 177.35296 -117.968014)
		(end 177.35296 -121.671588)
		(width 0.127)
		(layer "In2.Cu")
		(net "NC_FPGA_PR14B")
	)
	(segment
		(start 175.9712 -125.299978)
		(end 175.31588 -125.955298)
		(width 0.127)
		(layer "In2.Cu")
		(net "NC_FPGA_PR14B")
	)
	(segment
		(start 177.35296 -121.671588)
		(end 176.9618 -122.062748)
		(width 0.127)
		(layer "In2.Cu")
		(net "NC_FPGA_PR14B")
	)
	(segment
		(start 177.75555 -117.375432)
		(end 177.75555 -117.565424)
		(width 0.127)
		(layer "In2.Cu")
		(net "NC_FPGA_PR14B")
	)
	(segment
		(start 175.9712 -124.097288)
		(end 175.9712 -125.299978)
		(width 0.127)
		(layer "In2.Cu")
		(net "NC_FPGA_PR14B")
	)
	(segment
		(start 177.75555 -117.565424)
		(end 177.35296 -117.968014)
		(width 0.127)
		(layer "In2.Cu")
		(net "NC_FPGA_PR14B")
	)
	(segment
		(start 176.9618 -122.062748)
		(end 176.9618 -123.106688)
		(width 0.127)
		(layer "In2.Cu")
		(net "NC_FPGA_PR14B")
	)
	(segment
		(start 176.9618 -123.106688)
		(end 175.9712 -124.097288)
		(width 0.127)
		(layer "In2.Cu")
		(net "NC_FPGA_PR14B")
	)
	(segment
		(start 178.1556 -117.775482)
		(end 177.75555 -118.175532)
		(width 0.12954)
		(layer "F.Cu")
		(net "NC_FPGA_PR14A")
	)
	(via
		(at 176.58588 -125.955298)
		(size 0.508)
		(drill 0.254)
		(layers "F.Cu" "B.Cu")
		(net "NC_FPGA_PR14A")
	)
	(via
		(at 177.75555 -118.175532)
		(size 0.4572)
		(drill 0.254)
		(layers "F.Cu" "B.Cu")
		(net "NC_FPGA_PR14A")
	)
	(segment
		(start 177.015648 -123.555506)
		(end 177.015648 -125.52553)
		(width 0.127)
		(layer "In2.Cu")
		(net "NC_FPGA_PR14A")
	)
	(segment
		(start 177.015648 -125.52553)
		(end 176.58588 -125.955298)
		(width 0.127)
		(layer "In2.Cu")
		(net "NC_FPGA_PR14A")
	)
	(segment
		(start 177.75555 -118.175532)
		(end 178.16068 -118.580662)
		(width 0.127)
		(layer "In2.Cu")
		(net "NC_FPGA_PR14A")
	)
	(segment
		(start 178.16068 -120.780048)
		(end 177.68316 -121.257568)
		(width 0.127)
		(layer "In2.Cu")
		(net "NC_FPGA_PR14A")
	)
	(segment
		(start 177.32502 -123.246134)
		(end 177.015648 -123.555506)
		(width 0.127)
		(layer "In2.Cu")
		(net "NC_FPGA_PR14A")
	)
	(segment
		(start 177.68316 -122.095768)
		(end 177.32502 -122.453908)
		(width 0.127)
		(layer "In2.Cu")
		(net "NC_FPGA_PR14A")
	)
	(segment
		(start 177.68316 -121.257568)
		(end 177.68316 -122.095768)
		(width 0.127)
		(layer "In2.Cu")
		(net "NC_FPGA_PR14A")
	)
	(segment
		(start 177.32502 -122.453908)
		(end 177.32502 -123.246134)
		(width 0.127)
		(layer "In2.Cu")
		(net "NC_FPGA_PR14A")
	)
	(segment
		(start 178.16068 -118.580662)
		(end 178.16068 -120.780048)
		(width 0.127)
		(layer "In2.Cu")
		(net "NC_FPGA_PR14A")
	)
	(segment
		(start 186.155584 -116.175536)
		(end 186.555634 -116.575586)
		(width 0.12954)
		(layer "F.Cu")
		(net "NC_FPGA_PB35B")
	)
	(via
		(at 186.555634 -116.575586)
		(size 0.4572)
		(drill 0.254)
		(layers "F.Cu" "B.Cu")
		(net "NC_FPGA_PB35B")
	)
	(via
		(at 206.37754 -123.551188)
		(size 0.508)
		(drill 0.254)
		(layers "F.Cu" "B.Cu")
		(net "NC_FPGA_PB35B")
	)
	(segment
		(start 187.84316 -117.279674)
		(end 187.881514 -117.318028)
		(width 0.127)
		(layer "In15.Cu")
		(net "NC_FPGA_PB35B")
	)
	(segment
		(start 205.7527 -122.926348)
		(end 206.37754 -123.551188)
		(width 0.127)
		(layer "In15.Cu")
		(net "NC_FPGA_PB35B")
	)
	(segment
		(start 195.73748 -123.180348)
		(end 198.944992 -123.180348)
		(width 0.127)
		(layer "In15.Cu")
		(net "NC_FPGA_PB35B")
	)
	(segment
		(start 194.195192 -122.354848)
		(end 194.91198 -122.354848)
		(width 0.127)
		(layer "In15.Cu")
		(net "NC_FPGA_PB35B")
	)
	(segment
		(start 186.555634 -116.575586)
		(end 186.846972 -116.866924)
		(width 0.127)
		(layer "In15.Cu")
		(net "NC_FPGA_PB35B")
	)
	(segment
		(start 192.490344 -120.65)
		(end 194.195192 -122.354848)
		(width 0.127)
		(layer "In15.Cu")
		(net "NC_FPGA_PB35B")
	)
	(segment
		(start 187.93587 -117.318028)
		(end 188.107574 -117.389148)
		(width 0.127)
		(layer "In15.Cu")
		(net "NC_FPGA_PB35B")
	)
	(segment
		(start 188.107574 -117.389148)
		(end 188.6712 -117.389148)
		(width 0.127)
		(layer "In15.Cu")
		(net "NC_FPGA_PB35B")
	)
	(segment
		(start 188.6712 -117.389148)
		(end 191.932052 -120.65)
		(width 0.127)
		(layer "In15.Cu")
		(net "NC_FPGA_PB35B")
	)
	(segment
		(start 199.503792 -123.739148)
		(end 202.024488 -123.739148)
		(width 0.127)
		(layer "In15.Cu")
		(net "NC_FPGA_PB35B")
	)
	(segment
		(start 198.944992 -123.180348)
		(end 199.503792 -123.739148)
		(width 0.127)
		(layer "In15.Cu")
		(net "NC_FPGA_PB35B")
	)
	(segment
		(start 202.024488 -123.739148)
		(end 202.837288 -122.926348)
		(width 0.127)
		(layer "In15.Cu")
		(net "NC_FPGA_PB35B")
	)
	(segment
		(start 191.932052 -120.65)
		(end 192.490344 -120.65)
		(width 0.127)
		(layer "In15.Cu")
		(net "NC_FPGA_PB35B")
	)
	(segment
		(start 186.846972 -116.866924)
		(end 187.84316 -117.279674)
		(width 0.127)
		(layer "In15.Cu")
		(net "NC_FPGA_PB35B")
	)
	(segment
		(start 202.837288 -122.926348)
		(end 205.7527 -122.926348)
		(width 0.127)
		(layer "In15.Cu")
		(net "NC_FPGA_PB35B")
	)
	(segment
		(start 194.91198 -122.354848)
		(end 195.73748 -123.180348)
		(width 0.127)
		(layer "In15.Cu")
		(net "NC_FPGA_PB35B")
	)
	(segment
		(start 187.881514 -117.318028)
		(end 187.93587 -117.318028)
		(width 0.127)
		(layer "In15.Cu")
		(net "NC_FPGA_PB35B")
	)
	(segment
		(start 193.4718 -131.480814)
		(end 193.4718 -130.819398)
		(width 0.12954)
		(layer "F.Cu")
		(net "LED_HDD_ACTIVITY_B_PLD_N")
	)
	(segment
		(start 186.155584 -121.775474)
		(end 186.555634 -122.175524)
		(width 0.12954)
		(layer "F.Cu")
		(net "LED_HDD_ACTIVITY_B_PLD_N")
	)
	(segment
		(start 193.47434 -131.483354)
		(end 193.4718 -131.480814)
		(width 0.12954)
		(layer "F.Cu")
		(net "LED_HDD_ACTIVITY_B_PLD_N")
	)
	(via
		(at 193.47434 -131.483354)
		(size 0.508)
		(drill 0.254)
		(layers "F.Cu" "B.Cu")
		(net "LED_HDD_ACTIVITY_B_PLD_N")
	)
	(via
		(at 186.555634 -122.175524)
		(size 0.4572)
		(drill 0.254)
		(layers "F.Cu" "B.Cu")
		(net "LED_HDD_ACTIVITY_B_PLD_N")
	)
	(segment
		(start 189.66688 -126.973076)
		(end 189.66688 -125.369828)
		(width 0.127)
		(layer "In2.Cu")
		(net "LED_HDD_ACTIVITY_B_PLD_N")
	)
	(segment
		(start 187.96 -123.662948)
		(end 187.452 -123.662948)
		(width 0.127)
		(layer "In2.Cu")
		(net "LED_HDD_ACTIVITY_B_PLD_N")
	)
	(segment
		(start 187.452 -123.662948)
		(end 186.555634 -122.766582)
		(width 0.127)
		(layer "In2.Cu")
		(net "LED_HDD_ACTIVITY_B_PLD_N")
	)
	(segment
		(start 186.555634 -122.766582)
		(end 186.555634 -122.175524)
		(width 0.127)
		(layer "In2.Cu")
		(net "LED_HDD_ACTIVITY_B_PLD_N")
	)
	(segment
		(start 190.5 -128.509014)
		(end 190.5 -127.806196)
		(width 0.127)
		(layer "In2.Cu")
		(net "LED_HDD_ACTIVITY_B_PLD_N")
	)
	(segment
		(start 190.5 -127.806196)
		(end 189.66688 -126.973076)
		(width 0.127)
		(layer "In2.Cu")
		(net "LED_HDD_ACTIVITY_B_PLD_N")
	)
	(segment
		(start 189.66688 -125.369828)
		(end 187.96 -123.662948)
		(width 0.127)
		(layer "In2.Cu")
		(net "LED_HDD_ACTIVITY_B_PLD_N")
	)
	(segment
		(start 193.47434 -131.483354)
		(end 190.5 -128.509014)
		(width 0.127)
		(layer "In2.Cu")
		(net "LED_HDD_ACTIVITY_B_PLD_N")
	)
	(segment
		(start 85.715856 -35.618166)
		(end 85.50275 -35.831272)
		(width 0.12954)
		(layer "F.Cu")
		(net "HP_OCP_V3_2_RST_R")
	)
	(segment
		(start 84.5058 -36.051998)
		(end 84.723224 -36.051998)
		(width 0.12954)
		(layer "F.Cu")
		(net "HP_OCP_V3_2_RST_R")
	)
	(segment
		(start 85.19922 -34.818828)
		(end 85.715856 -34.818828)
		(width 0.12954)
		(layer "F.Cu")
		(net "HP_OCP_V3_2_RST_R")
	)
	(segment
		(start 85.50275 -35.831272)
		(end 85.50275 -36.032948)
		(width 0.12954)
		(layer "F.Cu")
		(net "HP_OCP_V3_2_RST_R")
	)
	(segment
		(start 85.03412 -34.983928)
		(end 85.19922 -34.818828)
		(width 0.12954)
		(layer "F.Cu")
		(net "HP_OCP_V3_2_RST_R")
	)
	(segment
		(start 84.723224 -36.051998)
		(end 85.03412 -35.741102)
		(width 0.12954)
		(layer "F.Cu")
		(net "HP_OCP_V3_2_RST_R")
	)
	(segment
		(start 83.50504 -36.067238)
		(end 83.4898 -36.051998)
		(width 0.12954)
		(layer "F.Cu")
		(net "HP_OCP_V3_2_RST_R")
	)
	(segment
		(start 85.715856 -34.818828)
		(end 85.715856 -35.618166)
		(width 0.12954)
		(layer "F.Cu")
		(net "HP_OCP_V3_2_RST_R")
	)
	(segment
		(start 83.4898 -36.051998)
		(end 84.5058 -36.051998)
		(width 0.12954)
		(layer "F.Cu")
		(net "HP_OCP_V3_2_RST_R")
	)
	(segment
		(start 83.50504 -37.500052)
		(end 83.50504 -36.067238)
		(width 0.12954)
		(layer "F.Cu")
		(net "HP_OCP_V3_2_RST_R")
	)
	(segment
		(start 85.03412 -35.741102)
		(end 85.03412 -34.983928)
		(width 0.12954)
		(layer "F.Cu")
		(net "HP_OCP_V3_2_RST_R")
	)
	(via
		(at 85.715856 -34.818828)
		(size 0.762)
		(drill 0.381)
		(layers "F.Cu" "B.Cu")
		(net "HP_OCP_V3_2_RST_R")
	)
	(segment
		(start 83.78825 -34.534348)
		(end 84.5058 -35.251898)
		(width 0.12954)
		(layer "F.Cu")
		(net "HP_OCP_V3_2_RST")
	)
	(segment
		(start 81.030064 -39.643812)
		(end 80.4926 -39.106348)
		(width 0.12954)
		(layer "F.Cu")
		(net "HP_OCP_V3_2_RST")
	)
	(segment
		(start 80.4926 -39.106348)
		(end 80.4926 -35.550348)
		(width 0.12954)
		(layer "F.Cu")
		(net "HP_OCP_V3_2_RST")
	)
	(segment
		(start 80.4926 -35.550348)
		(end 81.5086 -34.534348)
		(width 0.12954)
		(layer "F.Cu")
		(net "HP_OCP_V3_2_RST")
	)
	(segment
		(start 81.5086 -34.534348)
		(end 83.78825 -34.534348)
		(width 0.12954)
		(layer "F.Cu")
		(net "HP_OCP_V3_2_RST")
	)
	(segment
		(start 81.618582 -39.643812)
		(end 81.030064 -39.643812)
		(width 0.12954)
		(layer "F.Cu")
		(net "HP_OCP_V3_2_RST")
	)
	(via
		(at 80.4926 -35.550348)
		(size 0.762)
		(drill 0.381)
		(layers "F.Cu" "B.Cu")
		(net "HP_OCP_V3_2_RST")
	)
	(segment
		(start 388.493 -31.018988)
		(end 389.04291 -31.018988)
		(width 0.12954)
		(layer "F.Cu")
		(net "HP_OCP_V3_1_RST_R")
	)
	(segment
		(start 389.04291 -31.018988)
		(end 389.23595 -30.825948)
		(width 0.12954)
		(layer "F.Cu")
		(net "HP_OCP_V3_1_RST_R")
	)
	(segment
		(start 387.660896 -31.018988)
		(end 388.493 -31.018988)
		(width 0.12954)
		(layer "F.Cu")
		(net "HP_OCP_V3_1_RST_R")
	)
	(segment
		(start 389.23595 -31.841948)
		(end 389.23595 -30.825948)
		(width 0.12954)
		(layer "F.Cu")
		(net "HP_OCP_V3_1_RST_R")
	)
	(via
		(at 388.493 -31.018988)
		(size 0.508)
		(drill 0.254)
		(layers "F.Cu" "B.Cu")
		(net "HP_OCP_V3_1_RST_R")
	)
	(segment
		(start 389.19404 -31.018988)
		(end 389.636 -31.460948)
		(width 0.12954)
		(layer "B.Cu")
		(net "HP_OCP_V3_1_RST_R")
	)
	(segment
		(start 388.493 -31.018988)
		(end 389.19404 -31.018988)
		(width 0.12954)
		(layer "B.Cu")
		(net "HP_OCP_V3_1_RST_R")
	)
	(segment
		(start 389.636 -31.460948)
		(end 389.636 -32.203898)
		(width 0.12954)
		(layer "B.Cu")
		(net "HP_OCP_V3_1_RST_R")
	)
	(segment
		(start 390.03605 -32.330898)
		(end 390.03605 -31.841948)
		(width 0.12954)
		(layer "F.Cu")
		(net "HP_OCP_V3_1_RST")
	)
	(segment
		(start 389.255 -33.111948)
		(end 390.03605 -32.330898)
		(width 0.12954)
		(layer "F.Cu")
		(net "HP_OCP_V3_1_RST")
	)
	(segment
		(start 389.67537 -33.532318)
		(end 389.255 -33.111948)
		(width 0.12954)
		(layer "F.Cu")
		(net "HP_OCP_V3_1_RST")
	)
	(segment
		(start 389.67537 -34.581084)
		(end 389.67537 -33.532318)
		(width 0.12954)
		(layer "F.Cu")
		(net "HP_OCP_V3_1_RST")
	)
	(via
		(at 389.255 -33.111948)
		(size 0.762)
		(drill 0.381)
		(layers "F.Cu" "B.Cu")
		(net "HP_OCP_V3_1_RST")
	)
	(segment
		(start 184.658 -93.5101)
		(end 184.658 -92.837)
		(width 0.12954)
		(layer "F.Cu")
		(net "HP_LVC3_OCP_V3_2_PWRGD_R")
	)
	(segment
		(start 89.12098 -52.39004)
		(end 87.14105 -50.41011)
		(width 0.12954)
		(layer "F.Cu")
		(net "HP_LVC3_OCP_V3_2_PWRGD_R")
	)
	(segment
		(start 135.98525 -114.38382)
		(end 135.2931 -114.38382)
		(width 0.12954)
		(layer "F.Cu")
		(net "HP_LVC3_OCP_V3_2_PWRGD_R")
	)
	(segment
		(start 87.14105 -41.112948)
		(end 87.14105 -39.755318)
		(width 0.12954)
		(layer "F.Cu")
		(net "HP_LVC3_OCP_V3_2_PWRGD_R")
	)
	(segment
		(start 88.360504 -39.609268)
		(end 86.995 -39.609268)
		(width 0.12954)
		(layer "F.Cu")
		(net "HP_LVC3_OCP_V3_2_PWRGD_R")
	)
	(segment
		(start 90.84564 -80.9879)
		(end 89.12098 -79.26324)
		(width 0.12954)
		(layer "F.Cu")
		(net "HP_LVC3_OCP_V3_2_PWRGD_R")
	)
	(segment
		(start 87.14105 -39.755318)
		(end 86.995 -39.609268)
		(width 0.12954)
		(layer "F.Cu")
		(net "HP_LVC3_OCP_V3_2_PWRGD_R")
	)
	(segment
		(start 87.14105 -50.41011)
		(end 87.14105 -41.112948)
		(width 0.12954)
		(layer "F.Cu")
		(net "HP_LVC3_OCP_V3_2_PWRGD_R")
	)
	(segment
		(start 89.12098 -79.26324)
		(end 89.12098 -52.39004)
		(width 0.12954)
		(layer "F.Cu")
		(net "HP_LVC3_OCP_V3_2_PWRGD_R")
	)
	(via
		(at 125.0061 -85.54974)
		(size 0.508)
		(drill 0.254)
		(layers "F.Cu" "B.Cu")
		(net "HP_LVC3_OCP_V3_2_PWRGD_R")
	)
	(via
		(at 86.995 -39.609268)
		(size 0.762)
		(drill 0.381)
		(layers "F.Cu" "B.Cu")
		(net "HP_LVC3_OCP_V3_2_PWRGD_R")
	)
	(via
		(at 90.84564 -80.9879)
		(size 0.508)
		(drill 0.254)
		(layers "F.Cu" "B.Cu")
		(net "HP_LVC3_OCP_V3_2_PWRGD_R")
	)
	(via
		(at 135.2931 -114.38382)
		(size 0.508)
		(drill 0.254)
		(layers "F.Cu" "B.Cu")
		(net "HP_LVC3_OCP_V3_2_PWRGD_R")
	)
	(via
		(at 184.658 -92.837)
		(size 0.508)
		(drill 0.254)
		(layers "F.Cu" "B.Cu")
		(net "HP_LVC3_OCP_V3_2_PWRGD_R")
	)
	(segment
		(start 134.67588 -102.11562)
		(end 134.67588 -113.9698)
		(width 0.127)
		(layer "In2.Cu")
		(net "HP_LVC3_OCP_V3_2_PWRGD_R")
	)
	(segment
		(start 132.70992 -100.14966)
		(end 134.67588 -102.11562)
		(width 0.127)
		(layer "In2.Cu")
		(net "HP_LVC3_OCP_V3_2_PWRGD_R")
	)
	(segment
		(start 134.67588 -113.9698)
		(end 135.0899 -114.38382)
		(width 0.127)
		(layer "In2.Cu")
		(net "HP_LVC3_OCP_V3_2_PWRGD_R")
	)
	(segment
		(start 135.0899 -114.38382)
		(end 135.2931 -114.38382)
		(width 0.127)
		(layer "In2.Cu")
		(net "HP_LVC3_OCP_V3_2_PWRGD_R")
	)
	(segment
		(start 125.0061 -85.54974)
		(end 126.63424 -85.54974)
		(width 0.127)
		(layer "In2.Cu")
		(net "HP_LVC3_OCP_V3_2_PWRGD_R")
	)
	(segment
		(start 132.08 -94.89694)
		(end 132.70992 -95.52686)
		(width 0.127)
		(layer "In2.Cu")
		(net "HP_LVC3_OCP_V3_2_PWRGD_R")
	)
	(segment
		(start 132.70992 -95.52686)
		(end 132.70992 -100.14966)
		(width 0.127)
		(layer "In2.Cu")
		(net "HP_LVC3_OCP_V3_2_PWRGD_R")
	)
	(segment
		(start 126.63424 -85.54974)
		(end 132.08 -90.9955)
		(width 0.127)
		(layer "In2.Cu")
		(net "HP_LVC3_OCP_V3_2_PWRGD_R")
	)
	(segment
		(start 132.08 -90.9955)
		(end 132.08 -94.89694)
		(width 0.127)
		(layer "In2.Cu")
		(net "HP_LVC3_OCP_V3_2_PWRGD_R")
	)
	(segment
		(start 109.8804 -86.3981)
		(end 110.89386 -85.38464)
		(width 0.127)
		(layer "In4.Cu")
		(net "HP_LVC3_OCP_V3_2_PWRGD_R")
	)
	(segment
		(start 90.84564 -80.9879)
		(end 91.1606 -80.9879)
		(width 0.127)
		(layer "In4.Cu")
		(net "HP_LVC3_OCP_V3_2_PWRGD_R")
	)
	(segment
		(start 124.841 -85.38464)
		(end 125.0061 -85.54974)
		(width 0.127)
		(layer "In4.Cu")
		(net "HP_LVC3_OCP_V3_2_PWRGD_R")
	)
	(segment
		(start 91.1606 -80.9879)
		(end 96.5708 -86.3981)
		(width 0.127)
		(layer "In4.Cu")
		(net "HP_LVC3_OCP_V3_2_PWRGD_R")
	)
	(segment
		(start 96.5708 -86.3981)
		(end 109.8804 -86.3981)
		(width 0.127)
		(layer "In4.Cu")
		(net "HP_LVC3_OCP_V3_2_PWRGD_R")
	)
	(segment
		(start 110.89386 -85.38464)
		(end 124.841 -85.38464)
		(width 0.127)
		(layer "In4.Cu")
		(net "HP_LVC3_OCP_V3_2_PWRGD_R")
	)
	(segment
		(start 129.794254 -80.2894)
		(end 125.0061 -85.077554)
		(width 0.127)
		(layer "In15.Cu")
		(net "HP_LVC3_OCP_V3_2_PWRGD_R")
	)
	(segment
		(start 169.3037 -91.7575)
		(end 155.4353 -91.7575)
		(width 0.127)
		(layer "In15.Cu")
		(net "HP_LVC3_OCP_V3_2_PWRGD_R")
	)
	(segment
		(start 184.658 -92.837)
		(end 184.658 -92.6338)
		(width 0.127)
		(layer "In15.Cu")
		(net "HP_LVC3_OCP_V3_2_PWRGD_R")
	)
	(segment
		(start 151.6634 -86.9696)
		(end 150.5204 -85.8266)
		(width 0.127)
		(layer "In15.Cu")
		(net "HP_LVC3_OCP_V3_2_PWRGD_R")
	)
	(segment
		(start 155.4353 -91.7575)
		(end 151.6634 -87.9856)
		(width 0.127)
		(layer "In15.Cu")
		(net "HP_LVC3_OCP_V3_2_PWRGD_R")
	)
	(segment
		(start 184.2008 -92.1766)
		(end 183.0578 -92.1766)
		(width 0.127)
		(layer "In15.Cu")
		(net "HP_LVC3_OCP_V3_2_PWRGD_R")
	)
	(segment
		(start 170.5864 -90.4748)
		(end 169.3037 -91.7575)
		(width 0.127)
		(layer "In15.Cu")
		(net "HP_LVC3_OCP_V3_2_PWRGD_R")
	)
	(segment
		(start 125.0061 -85.077554)
		(end 125.0061 -85.54974)
		(width 0.127)
		(layer "In15.Cu")
		(net "HP_LVC3_OCP_V3_2_PWRGD_R")
	)
	(segment
		(start 146.939 -81.788)
		(end 145.4404 -80.2894)
		(width 0.127)
		(layer "In15.Cu")
		(net "HP_LVC3_OCP_V3_2_PWRGD_R")
	)
	(segment
		(start 150.5204 -85.8266)
		(end 149.4536 -85.8266)
		(width 0.127)
		(layer "In15.Cu")
		(net "HP_LVC3_OCP_V3_2_PWRGD_R")
	)
	(segment
		(start 181.356 -90.4748)
		(end 170.5864 -90.4748)
		(width 0.127)
		(layer "In15.Cu")
		(net "HP_LVC3_OCP_V3_2_PWRGD_R")
	)
	(segment
		(start 184.658 -92.6338)
		(end 184.2008 -92.1766)
		(width 0.127)
		(layer "In15.Cu")
		(net "HP_LVC3_OCP_V3_2_PWRGD_R")
	)
	(segment
		(start 145.4404 -80.2894)
		(end 129.794254 -80.2894)
		(width 0.127)
		(layer "In15.Cu")
		(net "HP_LVC3_OCP_V3_2_PWRGD_R")
	)
	(segment
		(start 149.4536 -85.8266)
		(end 146.939 -83.312)
		(width 0.127)
		(layer "In15.Cu")
		(net "HP_LVC3_OCP_V3_2_PWRGD_R")
	)
	(segment
		(start 151.6634 -87.9856)
		(end 151.6634 -86.9696)
		(width 0.127)
		(layer "In15.Cu")
		(net "HP_LVC3_OCP_V3_2_PWRGD_R")
	)
	(segment
		(start 146.939 -83.312)
		(end 146.939 -81.788)
		(width 0.127)
		(layer "In15.Cu")
		(net "HP_LVC3_OCP_V3_2_PWRGD_R")
	)
	(segment
		(start 183.0578 -92.1766)
		(end 181.356 -90.4748)
		(width 0.127)
		(layer "In15.Cu")
		(net "HP_LVC3_OCP_V3_2_PWRGD_R")
	)
	(segment
		(start 82.706718 -18.742152)
		(end 82.221324 -18.742152)
		(width 0.12954)
		(layer "F.Cu")
		(net "HP_LVC3_OCP_V3_2_P12V_PWRGD")
	)
	(segment
		(start 82.706718 -18.742152)
		(end 82.706718 -17.745202)
		(width 0.12954)
		(layer "F.Cu")
		(net "HP_LVC3_OCP_V3_2_P12V_PWRGD")
	)
	(segment
		(start 65.272412 -28.389834)
		(end 64.485012 -28.389834)
		(width 0.12954)
		(layer "F.Cu")
		(net "HP_LVC3_OCP_V3_2_P12V_PWRGD")
	)
	(segment
		(start 84.455 -37.500052)
		(end 84.455 -38.287452)
		(width 0.12954)
		(layer "F.Cu")
		(net "HP_LVC3_OCP_V3_2_P12V_PWRGD")
	)
	(segment
		(start 192.53962 -128.623822)
		(end 191.284606 -127.368808)
		(width 0.12954)
		(layer "F.Cu")
		(net "HP_LVC3_OCP_V3_2_P12V_PWRGD")
	)
	(segment
		(start 64.485012 -28.389834)
		(end 63.6016 -28.389834)
		(width 0.12954)
		(layer "F.Cu")
		(net "HP_LVC3_OCP_V3_2_P12V_PWRGD")
	)
	(segment
		(start 192.1891 -133.622288)
		(end 192.53962 -133.271768)
		(width 0.12954)
		(layer "F.Cu")
		(net "HP_LVC3_OCP_V3_2_P12V_PWRGD")
	)
	(segment
		(start 63.6016 -28.389834)
		(end 63.594488 -28.382722)
		(width 0.12954)
		(layer "F.Cu")
		(net "HP_LVC3_OCP_V3_2_P12V_PWRGD")
	)
	(segment
		(start 192.53962 -133.271768)
		(end 192.53962 -128.623822)
		(width 0.12954)
		(layer "F.Cu")
		(net "HP_LVC3_OCP_V3_2_P12V_PWRGD")
	)
	(segment
		(start 82.221324 -18.742152)
		(end 82.05216 -18.572988)
		(width 0.12954)
		(layer "F.Cu")
		(net "HP_LVC3_OCP_V3_2_P12V_PWRGD")
	)
	(via
		(at 100.57892 -37.661088)
		(size 0.508)
		(drill 0.254)
		(layers "F.Cu" "B.Cu")
		(net "HP_LVC3_OCP_V3_2_P12V_PWRGD")
	)
	(via
		(at 82.05216 -18.572988)
		(size 0.508)
		(drill 0.254)
		(layers "F.Cu" "B.Cu")
		(net "HP_LVC3_OCP_V3_2_P12V_PWRGD")
	)
	(via
		(at 192.1891 -133.622288)
		(size 0.508)
		(drill 0.254)
		(layers "F.Cu" "B.Cu")
		(net "HP_LVC3_OCP_V3_2_P12V_PWRGD")
	)
	(via
		(at 138.73734 -131.989068)
		(size 0.508)
		(drill 0.254)
		(layers "F.Cu" "B.Cu")
		(net "HP_LVC3_OCP_V3_2_P12V_PWRGD")
	)
	(via
		(at 64.485012 -28.389834)
		(size 0.508)
		(drill 0.254)
		(layers "F.Cu" "B.Cu")
		(net "HP_LVC3_OCP_V3_2_P12V_PWRGD")
	)
	(via
		(at 84.455 -38.287452)
		(size 0.508)
		(drill 0.254)
		(layers "F.Cu" "B.Cu")
		(net "HP_LVC3_OCP_V3_2_P12V_PWRGD")
	)
	(segment
		(start 112.86744 -51.130708)
		(end 113.48212 -51.745388)
		(width 0.127)
		(layer "In2.Cu")
		(net "HP_LVC3_OCP_V3_2_P12V_PWRGD")
	)
	(segment
		(start 112.86744 -47.437548)
		(end 112.86744 -51.130708)
		(width 0.127)
		(layer "In2.Cu")
		(net "HP_LVC3_OCP_V3_2_P12V_PWRGD")
	)
	(segment
		(start 139.64666 -105.649268)
		(end 138.73734 -106.558588)
		(width 0.127)
		(layer "In2.Cu")
		(net "HP_LVC3_OCP_V3_2_P12V_PWRGD")
	)
	(segment
		(start 114.81816 -74.242168)
		(end 114.81816 -78.524608)
		(width 0.127)
		(layer "In2.Cu")
		(net "HP_LVC3_OCP_V3_2_P12V_PWRGD")
	)
	(segment
		(start 113.48212 -51.745388)
		(end 113.48212 -67.988688)
		(width 0.127)
		(layer "In2.Cu")
		(net "HP_LVC3_OCP_V3_2_P12V_PWRGD")
	)
	(segment
		(start 115.34902 -73.711308)
		(end 114.81816 -74.242168)
		(width 0.127)
		(layer "In2.Cu")
		(net "HP_LVC3_OCP_V3_2_P12V_PWRGD")
	)
	(segment
		(start 138.73734 -106.558588)
		(end 138.73734 -131.989068)
		(width 0.127)
		(layer "In2.Cu")
		(net "HP_LVC3_OCP_V3_2_P12V_PWRGD")
	)
	(segment
		(start 133.98754 -83.6295)
		(end 138.12266 -87.76462)
		(width 0.127)
		(layer "In2.Cu")
		(net "HP_LVC3_OCP_V3_2_P12V_PWRGD")
	)
	(segment
		(start 138.12266 -87.76462)
		(end 138.12266 -103.251508)
		(width 0.127)
		(layer "In2.Cu")
		(net "HP_LVC3_OCP_V3_2_P12V_PWRGD")
	)
	(segment
		(start 119.923052 -83.6295)
		(end 133.98754 -83.6295)
		(width 0.127)
		(layer "In2.Cu")
		(net "HP_LVC3_OCP_V3_2_P12V_PWRGD")
	)
	(segment
		(start 100.57892 -37.661088)
		(end 103.09098 -37.661088)
		(width 0.127)
		(layer "In2.Cu")
		(net "HP_LVC3_OCP_V3_2_P12V_PWRGD")
	)
	(segment
		(start 138.12266 -103.251508)
		(end 139.64666 -104.775508)
		(width 0.127)
		(layer "In2.Cu")
		(net "HP_LVC3_OCP_V3_2_P12V_PWRGD")
	)
	(segment
		(start 103.09098 -37.661088)
		(end 112.86744 -47.437548)
		(width 0.127)
		(layer "In2.Cu")
		(net "HP_LVC3_OCP_V3_2_P12V_PWRGD")
	)
	(segment
		(start 113.48212 -67.988688)
		(end 115.34902 -69.855588)
		(width 0.127)
		(layer "In2.Cu")
		(net "HP_LVC3_OCP_V3_2_P12V_PWRGD")
	)
	(segment
		(start 114.81816 -78.524608)
		(end 119.923052 -83.6295)
		(width 0.127)
		(layer "In2.Cu")
		(net "HP_LVC3_OCP_V3_2_P12V_PWRGD")
	)
	(segment
		(start 115.34902 -69.855588)
		(end 115.34902 -73.711308)
		(width 0.127)
		(layer "In2.Cu")
		(net "HP_LVC3_OCP_V3_2_P12V_PWRGD")
	)
	(segment
		(start 139.64666 -104.775508)
		(end 139.64666 -105.649268)
		(width 0.127)
		(layer "In2.Cu")
		(net "HP_LVC3_OCP_V3_2_P12V_PWRGD")
	)
	(segment
		(start 80.889602 -33.727136)
		(end 68.019168 -33.727136)
		(width 0.127)
		(layer "In4.Cu")
		(net "HP_LVC3_OCP_V3_2_P12V_PWRGD")
	)
	(segment
		(start 68.019168 -33.727136)
		(end 65.85712 -31.565088)
		(width 0.127)
		(layer "In4.Cu")
		(net "HP_LVC3_OCP_V3_2_P12V_PWRGD")
	)
	(segment
		(start 65.27038 -28.389834)
		(end 64.485012 -28.389834)
		(width 0.127)
		(layer "In4.Cu")
		(net "HP_LVC3_OCP_V3_2_P12V_PWRGD")
	)
	(segment
		(start 65.85712 -31.565088)
		(end 65.85712 -28.976574)
		(width 0.127)
		(layer "In4.Cu")
		(net "HP_LVC3_OCP_V3_2_P12V_PWRGD")
	)
	(segment
		(start 65.85712 -28.976574)
		(end 65.27038 -28.389834)
		(width 0.127)
		(layer "In4.Cu")
		(net "HP_LVC3_OCP_V3_2_P12V_PWRGD")
	)
	(segment
		(start 83.04784 -31.568898)
		(end 80.889602 -33.727136)
		(width 0.127)
		(layer "In4.Cu")
		(net "HP_LVC3_OCP_V3_2_P12V_PWRGD")
	)
	(segment
		(start 83.04784 -19.568668)
		(end 83.04784 -31.568898)
		(width 0.127)
		(layer "In4.Cu")
		(net "HP_LVC3_OCP_V3_2_P12V_PWRGD")
	)
	(segment
		(start 82.05216 -18.572988)
		(end 83.04784 -19.568668)
		(width 0.127)
		(layer "In4.Cu")
		(net "HP_LVC3_OCP_V3_2_P12V_PWRGD")
	)
	(segment
		(start 191.8716 -133.304788)
		(end 192.1891 -133.622288)
		(width 0.127)
		(layer "In6.Cu")
		(net "HP_LVC3_OCP_V3_2_P12V_PWRGD")
	)
	(segment
		(start 138.73734 -131.989068)
		(end 140.8684 -134.120128)
		(width 0.127)
		(layer "In6.Cu")
		(net "HP_LVC3_OCP_V3_2_P12V_PWRGD")
	)
	(segment
		(start 184.58434 -133.652768)
		(end 187.62472 -133.652768)
		(width 0.127)
		(layer "In6.Cu")
		(net "HP_LVC3_OCP_V3_2_P12V_PWRGD")
	)
	(segment
		(start 181.99481 -133.923278)
		(end 184.31383 -133.923278)
		(width 0.127)
		(layer "In6.Cu")
		(net "HP_LVC3_OCP_V3_2_P12V_PWRGD")
	)
	(segment
		(start 168.3893 -133.518148)
		(end 168.86174 -133.518148)
		(width 0.127)
		(layer "In6.Cu")
		(net "HP_LVC3_OCP_V3_2_P12V_PWRGD")
	)
	(segment
		(start 167.93464 -133.063488)
		(end 168.3893 -133.518148)
		(width 0.127)
		(layer "In6.Cu")
		(net "HP_LVC3_OCP_V3_2_P12V_PWRGD")
	)
	(segment
		(start 161.85896 -134.120128)
		(end 162.9156 -133.063488)
		(width 0.127)
		(layer "In6.Cu")
		(net "HP_LVC3_OCP_V3_2_P12V_PWRGD")
	)
	(segment
		(start 140.8684 -134.120128)
		(end 161.85896 -134.120128)
		(width 0.127)
		(layer "In6.Cu")
		(net "HP_LVC3_OCP_V3_2_P12V_PWRGD")
	)
	(segment
		(start 162.9156 -133.063488)
		(end 167.93464 -133.063488)
		(width 0.127)
		(layer "In6.Cu")
		(net "HP_LVC3_OCP_V3_2_P12V_PWRGD")
	)
	(segment
		(start 187.9727 -133.304788)
		(end 191.8716 -133.304788)
		(width 0.127)
		(layer "In6.Cu")
		(net "HP_LVC3_OCP_V3_2_P12V_PWRGD")
	)
	(segment
		(start 169.02684 -133.353048)
		(end 181.42458 -133.353048)
		(width 0.127)
		(layer "In6.Cu")
		(net "HP_LVC3_OCP_V3_2_P12V_PWRGD")
	)
	(segment
		(start 184.31383 -133.923278)
		(end 184.58434 -133.652768)
		(width 0.127)
		(layer "In6.Cu")
		(net "HP_LVC3_OCP_V3_2_P12V_PWRGD")
	)
	(segment
		(start 181.42458 -133.353048)
		(end 181.99481 -133.923278)
		(width 0.127)
		(layer "In6.Cu")
		(net "HP_LVC3_OCP_V3_2_P12V_PWRGD")
	)
	(segment
		(start 168.86174 -133.518148)
		(end 169.02684 -133.353048)
		(width 0.127)
		(layer "In6.Cu")
		(net "HP_LVC3_OCP_V3_2_P12V_PWRGD")
	)
	(segment
		(start 187.62472 -133.652768)
		(end 187.9727 -133.304788)
		(width 0.127)
		(layer "In6.Cu")
		(net "HP_LVC3_OCP_V3_2_P12V_PWRGD")
	)
	(segment
		(start 84.5312 -21.052028)
		(end 82.05216 -18.572988)
		(width 0.127)
		(layer "In13.Cu")
		(net "HP_LVC3_OCP_V3_2_P12V_PWRGD")
	)
	(segment
		(start 84.455 -38.287452)
		(end 84.5312 -38.211252)
		(width 0.127)
		(layer "In13.Cu")
		(net "HP_LVC3_OCP_V3_2_P12V_PWRGD")
	)
	(segment
		(start 84.5312 -38.211252)
		(end 84.5312 -21.052028)
		(width 0.127)
		(layer "In13.Cu")
		(net "HP_LVC3_OCP_V3_2_P12V_PWRGD")
	)
	(segment
		(start 88.9762 -37.201348)
		(end 87.9094 -38.268148)
		(width 0.127)
		(layer "In15.Cu")
		(net "HP_LVC3_OCP_V3_2_P12V_PWRGD")
	)
	(segment
		(start 85.109304 -37.633148)
		(end 84.455 -38.287452)
		(width 0.127)
		(layer "In15.Cu")
		(net "HP_LVC3_OCP_V3_2_P12V_PWRGD")
	)
	(segment
		(start 100.11918 -37.201348)
		(end 88.9762 -37.201348)
		(width 0.127)
		(layer "In15.Cu")
		(net "HP_LVC3_OCP_V3_2_P12V_PWRGD")
	)
	(segment
		(start 87.122 -38.268148)
		(end 86.487 -37.633148)
		(width 0.127)
		(layer "In15.Cu")
		(net "HP_LVC3_OCP_V3_2_P12V_PWRGD")
	)
	(segment
		(start 87.9094 -38.268148)
		(end 87.122 -38.268148)
		(width 0.127)
		(layer "In15.Cu")
		(net "HP_LVC3_OCP_V3_2_P12V_PWRGD")
	)
	(segment
		(start 100.57892 -37.661088)
		(end 100.11918 -37.201348)
		(width 0.127)
		(layer "In15.Cu")
		(net "HP_LVC3_OCP_V3_2_P12V_PWRGD")
	)
	(segment
		(start 86.487 -37.633148)
		(end 85.109304 -37.633148)
		(width 0.127)
		(layer "In15.Cu")
		(net "HP_LVC3_OCP_V3_2_P12V_PWRGD")
	)
	(segment
		(start 186.8932 -93.5101)
		(end 186.8932 -92.837)
		(width 0.12954)
		(layer "F.Cu")
		(net "HP_LVC3_OCP_V3_1_PWRGD_R")
	)
	(segment
		(start 385.71805 -34.585148)
		(end 385.71805 -35.220148)
		(width 0.12954)
		(layer "F.Cu")
		(net "HP_LVC3_OCP_V3_1_PWRGD_R")
	)
	(segment
		(start 439.37174 -99.87153)
		(end 439.37174 -99.21748)
		(width 0.12954)
		(layer "F.Cu")
		(net "HP_LVC3_OCP_V3_1_PWRGD_R")
	)
	(segment
		(start 391.769854 -35.118802)
		(end 391.769854 -35.956494)
		(width 0.12954)
		(layer "F.Cu")
		(net "HP_LVC3_OCP_V3_1_PWRGD_R")
	)
	(via
		(at 434.7718 -35.6108)
		(size 0.508)
		(drill 0.254)
		(layers "F.Cu" "B.Cu")
		(net "HP_LVC3_OCP_V3_1_PWRGD_R")
	)
	(via
		(at 385.71805 -35.220148)
		(size 0.508)
		(drill 0.254)
		(layers "F.Cu" "B.Cu")
		(net "HP_LVC3_OCP_V3_1_PWRGD_R")
	)
	(via
		(at 439.37174 -99.21748)
		(size 0.508)
		(drill 0.254)
		(layers "F.Cu" "B.Cu")
		(net "HP_LVC3_OCP_V3_1_PWRGD_R")
	)
	(via
		(at 391.769854 -35.956494)
		(size 0.508)
		(drill 0.254)
		(layers "F.Cu" "B.Cu")
		(net "HP_LVC3_OCP_V3_1_PWRGD_R")
	)
	(via
		(at 186.8932 -92.837)
		(size 0.508)
		(drill 0.254)
		(layers "F.Cu" "B.Cu")
		(net "HP_LVC3_OCP_V3_1_PWRGD_R")
	)
	(via
		(at 256.4892 -87.3252)
		(size 0.508)
		(drill 0.254)
		(layers "F.Cu" "B.Cu")
		(net "HP_LVC3_OCP_V3_1_PWRGD_R")
	)
	(segment
		(start 368.7318 -75.5904)
		(end 369.4938 -74.8284)
		(width 0.12954)
		(layer "B.Cu")
		(net "HP_LVC3_OCP_V3_1_PWRGD_R")
	)
	(segment
		(start 381.254 -68.834)
		(end 391.7188 -58.3692)
		(width 0.12954)
		(layer "B.Cu")
		(net "HP_LVC3_OCP_V3_1_PWRGD_R")
	)
	(segment
		(start 371.6528 -68.834)
		(end 381.254 -68.834)
		(width 0.12954)
		(layer "B.Cu")
		(net "HP_LVC3_OCP_V3_1_PWRGD_R")
	)
	(segment
		(start 369.4938 -71.6534)
		(end 370.332 -70.8152)
		(width 0.12954)
		(layer "B.Cu")
		(net "HP_LVC3_OCP_V3_1_PWRGD_R")
	)
	(segment
		(start 385.71805 -38.01745)
		(end 385.71805 -35.220148)
		(width 0.12954)
		(layer "B.Cu")
		(net "HP_LVC3_OCP_V3_1_PWRGD_R")
	)
	(segment
		(start 256.4892 -87.3252)
		(end 256.7686 -87.0458)
		(width 0.12954)
		(layer "B.Cu")
		(net "HP_LVC3_OCP_V3_1_PWRGD_R")
	)
	(segment
		(start 354.5332 -94.361)
		(end 368.7318 -80.1624)
		(width 0.12954)
		(layer "B.Cu")
		(net "HP_LVC3_OCP_V3_1_PWRGD_R")
	)
	(segment
		(start 393.98956 -38.1762)
		(end 432.2826 -38.1762)
		(width 0.12954)
		(layer "B.Cu")
		(net "HP_LVC3_OCP_V3_1_PWRGD_R")
	)
	(segment
		(start 285.3182 -97.6122)
		(end 308.356 -97.6122)
		(width 0.12954)
		(layer "B.Cu")
		(net "HP_LVC3_OCP_V3_1_PWRGD_R")
	)
	(segment
		(start 391.7188 -48.4124)
		(end 390.9568 -47.6504)
		(width 0.12954)
		(layer "B.Cu")
		(net "HP_LVC3_OCP_V3_1_PWRGD_R")
	)
	(segment
		(start 432.2826 -38.1762)
		(end 434.7718 -35.687)
		(width 0.12954)
		(layer "B.Cu")
		(net "HP_LVC3_OCP_V3_1_PWRGD_R")
	)
	(segment
		(start 370.332 -70.1548)
		(end 371.6528 -68.834)
		(width 0.12954)
		(layer "B.Cu")
		(net "HP_LVC3_OCP_V3_1_PWRGD_R")
	)
	(segment
		(start 330.9874 -93.5736)
		(end 331.7748 -94.361)
		(width 0.12954)
		(layer "B.Cu")
		(net "HP_LVC3_OCP_V3_1_PWRGD_R")
	)
	(segment
		(start 391.769854 -35.956494)
		(end 393.98956 -38.1762)
		(width 0.12954)
		(layer "B.Cu")
		(net "HP_LVC3_OCP_V3_1_PWRGD_R")
	)
	(segment
		(start 308.356 -97.6122)
		(end 312.3946 -93.5736)
		(width 0.12954)
		(layer "B.Cu")
		(net "HP_LVC3_OCP_V3_1_PWRGD_R")
	)
	(segment
		(start 274.7518 -87.0458)
		(end 285.3182 -97.6122)
		(width 0.12954)
		(layer "B.Cu")
		(net "HP_LVC3_OCP_V3_1_PWRGD_R")
	)
	(segment
		(start 369.4938 -74.8284)
		(end 369.4938 -71.6534)
		(width 0.12954)
		(layer "B.Cu")
		(net "HP_LVC3_OCP_V3_1_PWRGD_R")
	)
	(segment
		(start 368.7318 -80.1624)
		(end 368.7318 -75.5904)
		(width 0.12954)
		(layer "B.Cu")
		(net "HP_LVC3_OCP_V3_1_PWRGD_R")
	)
	(segment
		(start 390.9568 -47.6504)
		(end 390.9568 -43.2562)
		(width 0.12954)
		(layer "B.Cu")
		(net "HP_LVC3_OCP_V3_1_PWRGD_R")
	)
	(segment
		(start 434.7718 -35.687)
		(end 434.7718 -35.6108)
		(width 0.12954)
		(layer "B.Cu")
		(net "HP_LVC3_OCP_V3_1_PWRGD_R")
	)
	(segment
		(start 312.3946 -93.5736)
		(end 330.9874 -93.5736)
		(width 0.12954)
		(layer "B.Cu")
		(net "HP_LVC3_OCP_V3_1_PWRGD_R")
	)
	(segment
		(start 370.332 -70.8152)
		(end 370.332 -70.1548)
		(width 0.12954)
		(layer "B.Cu")
		(net "HP_LVC3_OCP_V3_1_PWRGD_R")
	)
	(segment
		(start 390.9568 -43.2562)
		(end 385.71805 -38.01745)
		(width 0.12954)
		(layer "B.Cu")
		(net "HP_LVC3_OCP_V3_1_PWRGD_R")
	)
	(segment
		(start 331.7748 -94.361)
		(end 354.5332 -94.361)
		(width 0.12954)
		(layer "B.Cu")
		(net "HP_LVC3_OCP_V3_1_PWRGD_R")
	)
	(segment
		(start 256.7686 -87.0458)
		(end 274.7518 -87.0458)
		(width 0.12954)
		(layer "B.Cu")
		(net "HP_LVC3_OCP_V3_1_PWRGD_R")
	)
	(segment
		(start 391.7188 -58.3692)
		(end 391.7188 -48.4124)
		(width 0.12954)
		(layer "B.Cu")
		(net "HP_LVC3_OCP_V3_1_PWRGD_R")
	)
	(segment
		(start 434.7718 -35.6108)
		(end 435.737 -35.6108)
		(width 0.127)
		(layer "In2.Cu")
		(net "HP_LVC3_OCP_V3_1_PWRGD_R")
	)
	(segment
		(start 438.17032 -47.87392)
		(end 438.17032 -58.863738)
		(width 0.127)
		(layer "In2.Cu")
		(net "HP_LVC3_OCP_V3_1_PWRGD_R")
	)
	(segment
		(start 436.9054 -38.27526)
		(end 437.91632 -39.28618)
		(width 0.127)
		(layer "In2.Cu")
		(net "HP_LVC3_OCP_V3_1_PWRGD_R")
	)
	(segment
		(start 435.84114 -95.33382)
		(end 437.5912 -97.08388)
		(width 0.127)
		(layer "In2.Cu")
		(net "HP_LVC3_OCP_V3_1_PWRGD_R")
	)
	(segment
		(start 434.31968 -79.86776)
		(end 428.33036 -85.85708)
		(width 0.127)
		(layer "In2.Cu")
		(net "HP_LVC3_OCP_V3_1_PWRGD_R")
	)
	(segment
		(start 435.737 -35.6108)
		(end 436.9054 -36.7792)
		(width 0.127)
		(layer "In2.Cu")
		(net "HP_LVC3_OCP_V3_1_PWRGD_R")
	)
	(segment
		(start 428.33036 -85.85708)
		(end 428.33036 -94.93504)
		(width 0.127)
		(layer "In2.Cu")
		(net "HP_LVC3_OCP_V3_1_PWRGD_R")
	)
	(segment
		(start 436.79364 -47.05096)
		(end 437.261 -47.51832)
		(width 0.127)
		(layer "In2.Cu")
		(net "HP_LVC3_OCP_V3_1_PWRGD_R")
	)
	(segment
		(start 437.91632 -39.28618)
		(end 437.91632 -42.25798)
		(width 0.127)
		(layer "In2.Cu")
		(net "HP_LVC3_OCP_V3_1_PWRGD_R")
	)
	(segment
		(start 428.33036 -94.93504)
		(end 428.72914 -95.33382)
		(width 0.127)
		(layer "In2.Cu")
		(net "HP_LVC3_OCP_V3_1_PWRGD_R")
	)
	(segment
		(start 437.261 -47.51832)
		(end 437.81472 -47.51832)
		(width 0.127)
		(layer "In2.Cu")
		(net "HP_LVC3_OCP_V3_1_PWRGD_R")
	)
	(segment
		(start 437.5912 -98.8187)
		(end 437.98998 -99.21748)
		(width 0.127)
		(layer "In2.Cu")
		(net "HP_LVC3_OCP_V3_1_PWRGD_R")
	)
	(segment
		(start 437.81472 -47.51832)
		(end 438.17032 -47.87392)
		(width 0.127)
		(layer "In2.Cu")
		(net "HP_LVC3_OCP_V3_1_PWRGD_R")
	)
	(segment
		(start 437.91632 -42.25798)
		(end 436.79364 -43.38066)
		(width 0.127)
		(layer "In2.Cu")
		(net "HP_LVC3_OCP_V3_1_PWRGD_R")
	)
	(segment
		(start 434.31968 -62.78372)
		(end 434.31968 -79.86776)
		(width 0.127)
		(layer "In2.Cu")
		(net "HP_LVC3_OCP_V3_1_PWRGD_R")
	)
	(segment
		(start 436.9054 -36.7792)
		(end 436.9054 -38.27526)
		(width 0.127)
		(layer "In2.Cu")
		(net "HP_LVC3_OCP_V3_1_PWRGD_R")
	)
	(segment
		(start 437.5912 -97.08388)
		(end 437.5912 -98.8187)
		(width 0.127)
		(layer "In2.Cu")
		(net "HP_LVC3_OCP_V3_1_PWRGD_R")
	)
	(segment
		(start 437.98998 -99.21748)
		(end 439.37174 -99.21748)
		(width 0.127)
		(layer "In2.Cu")
		(net "HP_LVC3_OCP_V3_1_PWRGD_R")
	)
	(segment
		(start 438.10936 -58.99404)
		(end 434.31968 -62.78372)
		(width 0.127)
		(layer "In2.Cu")
		(net "HP_LVC3_OCP_V3_1_PWRGD_R")
	)
	(segment
		(start 438.10936 -58.924698)
		(end 438.10936 -58.99404)
		(width 0.127)
		(layer "In2.Cu")
		(net "HP_LVC3_OCP_V3_1_PWRGD_R")
	)
	(segment
		(start 438.17032 -58.863738)
		(end 438.10936 -58.924698)
		(width 0.127)
		(layer "In2.Cu")
		(net "HP_LVC3_OCP_V3_1_PWRGD_R")
	)
	(segment
		(start 428.72914 -95.33382)
		(end 435.84114 -95.33382)
		(width 0.127)
		(layer "In2.Cu")
		(net "HP_LVC3_OCP_V3_1_PWRGD_R")
	)
	(segment
		(start 436.79364 -43.38066)
		(end 436.79364 -47.05096)
		(width 0.127)
		(layer "In2.Cu")
		(net "HP_LVC3_OCP_V3_1_PWRGD_R")
	)
	(segment
		(start 204.5208 -94.2086)
		(end 206.3242 -96.012)
		(width 0.127)
		(layer "In11.Cu")
		(net "HP_LVC3_OCP_V3_1_PWRGD_R")
	)
	(segment
		(start 189.4332 -92.837)
		(end 190.1698 -93.5736)
		(width 0.127)
		(layer "In11.Cu")
		(net "HP_LVC3_OCP_V3_1_PWRGD_R")
	)
	(segment
		(start 193.802 -94.488)
		(end 198.3232 -94.488)
		(width 0.127)
		(layer "In11.Cu")
		(net "HP_LVC3_OCP_V3_1_PWRGD_R")
	)
	(segment
		(start 198.6026 -94.2086)
		(end 204.5208 -94.2086)
		(width 0.127)
		(layer "In11.Cu")
		(net "HP_LVC3_OCP_V3_1_PWRGD_R")
	)
	(segment
		(start 239.2172 -90.1954)
		(end 245.6688 -83.7438)
		(width 0.127)
		(layer "In11.Cu")
		(net "HP_LVC3_OCP_V3_1_PWRGD_R")
	)
	(segment
		(start 192.8876 -93.5736)
		(end 193.802 -94.488)
		(width 0.127)
		(layer "In11.Cu")
		(net "HP_LVC3_OCP_V3_1_PWRGD_R")
	)
	(segment
		(start 213.5124 -95.1992)
		(end 218.5162 -90.1954)
		(width 0.127)
		(layer "In11.Cu")
		(net "HP_LVC3_OCP_V3_1_PWRGD_R")
	)
	(segment
		(start 218.5162 -90.1954)
		(end 239.2172 -90.1954)
		(width 0.127)
		(layer "In11.Cu")
		(net "HP_LVC3_OCP_V3_1_PWRGD_R")
	)
	(segment
		(start 255.4224 -83.7438)
		(end 256.4892 -84.8106)
		(width 0.127)
		(layer "In11.Cu")
		(net "HP_LVC3_OCP_V3_1_PWRGD_R")
	)
	(segment
		(start 256.4892 -84.8106)
		(end 256.4892 -87.3252)
		(width 0.127)
		(layer "In11.Cu")
		(net "HP_LVC3_OCP_V3_1_PWRGD_R")
	)
	(segment
		(start 245.6688 -83.7438)
		(end 255.4224 -83.7438)
		(width 0.127)
		(layer "In11.Cu")
		(net "HP_LVC3_OCP_V3_1_PWRGD_R")
	)
	(segment
		(start 206.3242 -96.012)
		(end 207.1116 -96.012)
		(width 0.127)
		(layer "In11.Cu")
		(net "HP_LVC3_OCP_V3_1_PWRGD_R")
	)
	(segment
		(start 190.1698 -93.5736)
		(end 192.8876 -93.5736)
		(width 0.127)
		(layer "In11.Cu")
		(net "HP_LVC3_OCP_V3_1_PWRGD_R")
	)
	(segment
		(start 186.8932 -92.837)
		(end 189.4332 -92.837)
		(width 0.127)
		(layer "In11.Cu")
		(net "HP_LVC3_OCP_V3_1_PWRGD_R")
	)
	(segment
		(start 207.1116 -96.012)
		(end 207.9244 -95.1992)
		(width 0.127)
		(layer "In11.Cu")
		(net "HP_LVC3_OCP_V3_1_PWRGD_R")
	)
	(segment
		(start 198.3232 -94.488)
		(end 198.6026 -94.2086)
		(width 0.127)
		(layer "In11.Cu")
		(net "HP_LVC3_OCP_V3_1_PWRGD_R")
	)
	(segment
		(start 207.9244 -95.1992)
		(end 213.5124 -95.1992)
		(width 0.127)
		(layer "In11.Cu")
		(net "HP_LVC3_OCP_V3_1_PWRGD_R")
	)
	(segment
		(start 385.94665 -34.991548)
		(end 390.804908 -34.991548)
		(width 0.127)
		(layer "In15.Cu")
		(net "HP_LVC3_OCP_V3_1_PWRGD_R")
	)
	(segment
		(start 390.804908 -34.991548)
		(end 391.769854 -35.956494)
		(width 0.127)
		(layer "In15.Cu")
		(net "HP_LVC3_OCP_V3_1_PWRGD_R")
	)
	(segment
		(start 385.71805 -35.220148)
		(end 385.94665 -34.991548)
		(width 0.127)
		(layer "In15.Cu")
		(net "HP_LVC3_OCP_V3_1_PWRGD_R")
	)
	(segment
		(start 387.660896 -31.968948)
		(end 388.493 -31.968948)
		(width 0.12954)
		(layer "F.Cu")
		(net "HP_LVC3_OCP_V3_1_P12V_PWRGD")
	)
	(segment
		(start 190.291466 -128.013714)
		(end 190.291466 -127.363728)
		(width 0.12954)
		(layer "F.Cu")
		(net "HP_LVC3_OCP_V3_1_P12V_PWRGD")
	)
	(segment
		(start 439.158634 -28.668218)
		(end 438.275222 -28.668218)
		(width 0.12954)
		(layer "F.Cu")
		(net "HP_LVC3_OCP_V3_1_P12V_PWRGD")
	)
	(segment
		(start 439.953146 -28.67533)
		(end 439.165746 -28.67533)
		(width 0.12954)
		(layer "F.Cu")
		(net "HP_LVC3_OCP_V3_1_P12V_PWRGD")
	)
	(segment
		(start 454.212452 -19.027648)
		(end 454.847452 -19.027648)
		(width 0.12954)
		(layer "F.Cu")
		(net "HP_LVC3_OCP_V3_1_P12V_PWRGD")
	)
	(segment
		(start 439.165746 -28.67533)
		(end 439.158634 -28.668218)
		(width 0.12954)
		(layer "F.Cu")
		(net "HP_LVC3_OCP_V3_1_P12V_PWRGD")
	)
	(segment
		(start 191.41694 -130.691128)
		(end 191.41694 -129.139188)
		(width 0.12954)
		(layer "F.Cu")
		(net "HP_LVC3_OCP_V3_1_P12V_PWRGD")
	)
	(segment
		(start 191.41694 -129.139188)
		(end 190.291466 -128.013714)
		(width 0.12954)
		(layer "F.Cu")
		(net "HP_LVC3_OCP_V3_1_P12V_PWRGD")
	)
	(segment
		(start 454.847452 -19.027648)
		(end 454.847452 -18.030698)
		(width 0.12954)
		(layer "F.Cu")
		(net "HP_LVC3_OCP_V3_1_P12V_PWRGD")
	)
	(segment
		(start 192.00876 -131.282948)
		(end 191.41694 -130.691128)
		(width 0.12954)
		(layer "F.Cu")
		(net "HP_LVC3_OCP_V3_1_P12V_PWRGD")
	)
	(via
		(at 192.00876 -131.282948)
		(size 0.508)
		(drill 0.254)
		(layers "F.Cu" "B.Cu")
		(net "HP_LVC3_OCP_V3_1_P12V_PWRGD")
	)
	(via
		(at 388.493 -31.968948)
		(size 0.508)
		(drill 0.254)
		(layers "F.Cu" "B.Cu")
		(net "HP_LVC3_OCP_V3_1_P12V_PWRGD")
	)
	(via
		(at 454.212452 -19.027648)
		(size 0.508)
		(drill 0.254)
		(layers "F.Cu" "B.Cu")
		(net "HP_LVC3_OCP_V3_1_P12V_PWRGD")
	)
	(via
		(at 439.165746 -28.67533)
		(size 0.508)
		(drill 0.254)
		(layers "F.Cu" "B.Cu")
		(net "HP_LVC3_OCP_V3_1_P12V_PWRGD")
	)
	(via
		(at 353.38004 -128.798828)
		(size 0.508)
		(drill 0.254)
		(layers "F.Cu" "B.Cu")
		(net "HP_LVC3_OCP_V3_1_P12V_PWRGD")
	)
	(segment
		(start 431.32248 -29.124148)
		(end 435.31028 -29.124148)
		(width 0.12954)
		(layer "B.Cu")
		(net "HP_LVC3_OCP_V3_1_P12V_PWRGD")
	)
	(segment
		(start 387.73608 -31.212028)
		(end 387.73608 -30.145228)
		(width 0.12954)
		(layer "B.Cu")
		(net "HP_LVC3_OCP_V3_1_P12V_PWRGD")
	)
	(segment
		(start 426.62348 -27.396948)
		(end 429.59528 -27.396948)
		(width 0.12954)
		(layer "B.Cu")
		(net "HP_LVC3_OCP_V3_1_P12V_PWRGD")
	)
	(segment
		(start 436.47868 -27.955748)
		(end 438.446164 -27.955748)
		(width 0.12954)
		(layer "B.Cu")
		(net "HP_LVC3_OCP_V3_1_P12V_PWRGD")
	)
	(segment
		(start 388.366 -29.515308)
		(end 391.1346 -29.515308)
		(width 0.12954)
		(layer "B.Cu")
		(net "HP_LVC3_OCP_V3_1_P12V_PWRGD")
	)
	(segment
		(start 392.15314 -30.533848)
		(end 423.48658 -30.533848)
		(width 0.12954)
		(layer "B.Cu")
		(net "HP_LVC3_OCP_V3_1_P12V_PWRGD")
	)
	(segment
		(start 429.59528 -27.396948)
		(end 431.32248 -29.124148)
		(width 0.12954)
		(layer "B.Cu")
		(net "HP_LVC3_OCP_V3_1_P12V_PWRGD")
	)
	(segment
		(start 435.31028 -29.124148)
		(end 436.47868 -27.955748)
		(width 0.12954)
		(layer "B.Cu")
		(net "HP_LVC3_OCP_V3_1_P12V_PWRGD")
	)
	(segment
		(start 391.1346 -29.515308)
		(end 392.15314 -30.533848)
		(width 0.12954)
		(layer "B.Cu")
		(net "HP_LVC3_OCP_V3_1_P12V_PWRGD")
	)
	(segment
		(start 388.493 -31.968948)
		(end 387.73608 -31.212028)
		(width 0.12954)
		(layer "B.Cu")
		(net "HP_LVC3_OCP_V3_1_P12V_PWRGD")
	)
	(segment
		(start 423.48658 -30.533848)
		(end 426.62348 -27.396948)
		(width 0.12954)
		(layer "B.Cu")
		(net "HP_LVC3_OCP_V3_1_P12V_PWRGD")
	)
	(segment
		(start 438.446164 -27.955748)
		(end 439.165746 -28.67533)
		(width 0.12954)
		(layer "B.Cu")
		(net "HP_LVC3_OCP_V3_1_P12V_PWRGD")
	)
	(segment
		(start 387.73608 -30.145228)
		(end 388.366 -29.515308)
		(width 0.12954)
		(layer "B.Cu")
		(net "HP_LVC3_OCP_V3_1_P12V_PWRGD")
	)
	(segment
		(start 389.85952 -33.335468)
		(end 388.493 -31.968948)
		(width 0.127)
		(layer "In2.Cu")
		(net "HP_LVC3_OCP_V3_1_P12V_PWRGD")
	)
	(segment
		(start 376.1486 -112.916208)
		(end 376.1486 -111.719868)
		(width 0.127)
		(layer "In2.Cu")
		(net "HP_LVC3_OCP_V3_1_P12V_PWRGD")
	)
	(segment
		(start 392.10361 -72.018398)
		(end 392.10361 -49.707038)
		(width 0.127)
		(layer "In2.Cu")
		(net "HP_LVC3_OCP_V3_1_P12V_PWRGD")
	)
	(segment
		(start 372.14048 -116.924328)
		(end 376.1486 -112.916208)
		(width 0.127)
		(layer "In2.Cu")
		(net "HP_LVC3_OCP_V3_1_P12V_PWRGD")
	)
	(segment
		(start 367.27638 -116.924328)
		(end 372.14048 -116.924328)
		(width 0.127)
		(layer "In2.Cu")
		(net "HP_LVC3_OCP_V3_1_P12V_PWRGD")
	)
	(segment
		(start 394.41374 -81.628488)
		(end 394.41374 -74.328528)
		(width 0.127)
		(layer "In2.Cu")
		(net "HP_LVC3_OCP_V3_1_P12V_PWRGD")
	)
	(segment
		(start 394.41374 -74.328528)
		(end 392.10361 -72.018398)
		(width 0.127)
		(layer "In2.Cu")
		(net "HP_LVC3_OCP_V3_1_P12V_PWRGD")
	)
	(segment
		(start 355.40188 -128.798828)
		(end 367.27638 -116.924328)
		(width 0.127)
		(layer "In2.Cu")
		(net "HP_LVC3_OCP_V3_1_P12V_PWRGD")
	)
	(segment
		(start 391.43686 -49.040288)
		(end 391.43686 -38.039548)
		(width 0.127)
		(layer "In2.Cu")
		(net "HP_LVC3_OCP_V3_1_P12V_PWRGD")
	)
	(segment
		(start 389.85952 -36.462208)
		(end 389.85952 -33.335468)
		(width 0.127)
		(layer "In2.Cu")
		(net "HP_LVC3_OCP_V3_1_P12V_PWRGD")
	)
	(segment
		(start 379.98908 -105.547668)
		(end 382.8669 -102.669848)
		(width 0.127)
		(layer "In2.Cu")
		(net "HP_LVC3_OCP_V3_1_P12V_PWRGD")
	)
	(segment
		(start 391.43686 -38.039548)
		(end 389.85952 -36.462208)
		(width 0.127)
		(layer "In2.Cu")
		(net "HP_LVC3_OCP_V3_1_P12V_PWRGD")
	)
	(segment
		(start 382.8669 -102.669848)
		(end 382.8669 -93.175328)
		(width 0.127)
		(layer "In2.Cu")
		(net "HP_LVC3_OCP_V3_1_P12V_PWRGD")
	)
	(segment
		(start 379.33884 -108.529628)
		(end 379.33884 -107.500928)
		(width 0.127)
		(layer "In2.Cu")
		(net "HP_LVC3_OCP_V3_1_P12V_PWRGD")
	)
	(segment
		(start 353.38004 -128.798828)
		(end 355.40188 -128.798828)
		(width 0.127)
		(layer "In2.Cu")
		(net "HP_LVC3_OCP_V3_1_P12V_PWRGD")
	)
	(segment
		(start 376.1486 -111.719868)
		(end 379.33884 -108.529628)
		(width 0.127)
		(layer "In2.Cu")
		(net "HP_LVC3_OCP_V3_1_P12V_PWRGD")
	)
	(segment
		(start 379.33884 -107.500928)
		(end 379.98908 -106.850688)
		(width 0.127)
		(layer "In2.Cu")
		(net "HP_LVC3_OCP_V3_1_P12V_PWRGD")
	)
	(segment
		(start 392.10361 -49.707038)
		(end 391.43686 -49.040288)
		(width 0.127)
		(layer "In2.Cu")
		(net "HP_LVC3_OCP_V3_1_P12V_PWRGD")
	)
	(segment
		(start 379.98908 -106.850688)
		(end 379.98908 -105.547668)
		(width 0.127)
		(layer "In2.Cu")
		(net "HP_LVC3_OCP_V3_1_P12V_PWRGD")
	)
	(segment
		(start 382.8669 -93.175328)
		(end 394.41374 -81.628488)
		(width 0.127)
		(layer "In2.Cu")
		(net "HP_LVC3_OCP_V3_1_P12V_PWRGD")
	)
	(segment
		(start 440.44108 -27.399996)
		(end 439.165746 -28.67533)
		(width 0.127)
		(layer "In4.Cu")
		(net "HP_LVC3_OCP_V3_1_P12V_PWRGD")
	)
	(segment
		(start 454.212452 -19.027648)
		(end 452.218552 -17.033748)
		(width 0.127)
		(layer "In4.Cu")
		(net "HP_LVC3_OCP_V3_1_P12V_PWRGD")
	)
	(segment
		(start 449.96608 -16.271748)
		(end 442.86932 -16.271748)
		(width 0.127)
		(layer "In4.Cu")
		(net "HP_LVC3_OCP_V3_1_P12V_PWRGD")
	)
	(segment
		(start 452.218552 -17.033748)
		(end 450.72808 -17.033748)
		(width 0.127)
		(layer "In4.Cu")
		(net "HP_LVC3_OCP_V3_1_P12V_PWRGD")
	)
	(segment
		(start 442.86932 -16.271748)
		(end 440.44108 -18.699988)
		(width 0.127)
		(layer "In4.Cu")
		(net "HP_LVC3_OCP_V3_1_P12V_PWRGD")
	)
	(segment
		(start 440.44108 -18.699988)
		(end 440.44108 -27.399996)
		(width 0.127)
		(layer "In4.Cu")
		(net "HP_LVC3_OCP_V3_1_P12V_PWRGD")
	)
	(segment
		(start 450.72808 -17.033748)
		(end 449.96608 -16.271748)
		(width 0.127)
		(layer "In4.Cu")
		(net "HP_LVC3_OCP_V3_1_P12V_PWRGD")
	)
	(segment
		(start 197.845934 -132.044948)
		(end 192.77076 -132.044948)
		(width 0.127)
		(layer "In13.Cu")
		(net "HP_LVC3_OCP_V3_1_P12V_PWRGD")
	)
	(segment
		(start 334.79232 -136.731248)
		(end 208.20126 -136.731248)
		(width 0.127)
		(layer "In13.Cu")
		(net "HP_LVC3_OCP_V3_1_P12V_PWRGD")
	)
	(segment
		(start 348.2213 -133.957568)
		(end 337.566 -133.957568)
		(width 0.127)
		(layer "In13.Cu")
		(net "HP_LVC3_OCP_V3_1_P12V_PWRGD")
	)
	(segment
		(start 192.77076 -132.044948)
		(end 192.00876 -131.282948)
		(width 0.127)
		(layer "In13.Cu")
		(net "HP_LVC3_OCP_V3_1_P12V_PWRGD")
	)
	(segment
		(start 353.38004 -128.798828)
		(end 348.2213 -133.957568)
		(width 0.127)
		(layer "In13.Cu")
		(net "HP_LVC3_OCP_V3_1_P12V_PWRGD")
	)
	(segment
		(start 202.552554 -131.082542)
		(end 198.80834 -131.082542)
		(width 0.127)
		(layer "In13.Cu")
		(net "HP_LVC3_OCP_V3_1_P12V_PWRGD")
	)
	(segment
		(start 198.80834 -131.082542)
		(end 197.845934 -132.044948)
		(width 0.127)
		(layer "In13.Cu")
		(net "HP_LVC3_OCP_V3_1_P12V_PWRGD")
	)
	(segment
		(start 208.20126 -136.731248)
		(end 202.552554 -131.082542)
		(width 0.127)
		(layer "In13.Cu")
		(net "HP_LVC3_OCP_V3_1_P12V_PWRGD")
	)
	(segment
		(start 337.566 -133.957568)
		(end 334.79232 -136.731248)
		(width 0.127)
		(layer "In13.Cu")
		(net "HP_LVC3_OCP_V3_1_P12V_PWRGD")
	)
	(segment
		(start 184.555638 -120.175528)
		(end 184.955688 -120.575578)
		(width 0.12954)
		(layer "F.Cu")
		(net "FM_PCH_SPKR_R")
	)
	(segment
		(start 198.8312 -127.828548)
		(end 198.8312 -128.393698)
		(width 0.12954)
		(layer "F.Cu")
		(net "FM_PCH_SPKR_R")
	)
	(segment
		(start 199.0344 -127.625348)
		(end 198.8312 -127.828548)
		(width 0.12954)
		(layer "F.Cu")
		(net "FM_PCH_SPKR_R")
	)
	(via
		(at 184.955688 -120.575578)
		(size 0.4572)
		(drill 0.254)
		(layers "F.Cu" "B.Cu")
		(net "FM_PCH_SPKR_R")
	)
	(via
		(at 199.0344 -127.625348)
		(size 0.508)
		(drill 0.254)
		(layers "F.Cu" "B.Cu")
		(net "FM_PCH_SPKR_R")
	)
	(segment
		(start 194.142614 -128.041908)
		(end 192.687194 -126.586488)
		(width 0.127)
		(layer "In15.Cu")
		(net "FM_PCH_SPKR_R")
	)
	(segment
		(start 191.99225 -126.586488)
		(end 191.717168 -126.311406)
		(width 0.127)
		(layer "In15.Cu")
		(net "FM_PCH_SPKR_R")
	)
	(segment
		(start 195.77812 -128.194308)
		(end 195.04914 -128.194308)
		(width 0.127)
		(layer "In15.Cu")
		(net "FM_PCH_SPKR_R")
	)
	(segment
		(start 191.717168 -125.433582)
		(end 190.538354 -124.254768)
		(width 0.127)
		(layer "In15.Cu")
		(net "FM_PCH_SPKR_R")
	)
	(segment
		(start 198.55434 -128.105408)
		(end 195.86702 -128.105408)
		(width 0.127)
		(layer "In15.Cu")
		(net "FM_PCH_SPKR_R")
	)
	(segment
		(start 191.717168 -126.311406)
		(end 191.717168 -125.433582)
		(width 0.127)
		(layer "In15.Cu")
		(net "FM_PCH_SPKR_R")
	)
	(segment
		(start 192.687194 -126.586488)
		(end 191.99225 -126.586488)
		(width 0.127)
		(layer "In15.Cu")
		(net "FM_PCH_SPKR_R")
	)
	(segment
		(start 195.04914 -128.194308)
		(end 194.89674 -128.041908)
		(width 0.127)
		(layer "In15.Cu")
		(net "FM_PCH_SPKR_R")
	)
	(segment
		(start 185.84672 -122.570748)
		(end 185.84672 -122.050302)
		(width 0.127)
		(layer "In15.Cu")
		(net "FM_PCH_SPKR_R")
	)
	(segment
		(start 185.84672 -122.050302)
		(end 185.35142 -121.555002)
		(width 0.127)
		(layer "In15.Cu")
		(net "FM_PCH_SPKR_R")
	)
	(segment
		(start 195.86702 -128.105408)
		(end 195.77812 -128.194308)
		(width 0.127)
		(layer "In15.Cu")
		(net "FM_PCH_SPKR_R")
	)
	(segment
		(start 187.53074 -124.254768)
		(end 185.84672 -122.570748)
		(width 0.127)
		(layer "In15.Cu")
		(net "FM_PCH_SPKR_R")
	)
	(segment
		(start 199.0344 -127.625348)
		(end 198.55434 -128.105408)
		(width 0.127)
		(layer "In15.Cu")
		(net "FM_PCH_SPKR_R")
	)
	(segment
		(start 185.35142 -120.97131)
		(end 184.955688 -120.575578)
		(width 0.127)
		(layer "In15.Cu")
		(net "FM_PCH_SPKR_R")
	)
	(segment
		(start 185.35142 -121.555002)
		(end 185.35142 -120.97131)
		(width 0.127)
		(layer "In15.Cu")
		(net "FM_PCH_SPKR_R")
	)
	(segment
		(start 194.89674 -128.041908)
		(end 194.142614 -128.041908)
		(width 0.127)
		(layer "In15.Cu")
		(net "FM_PCH_SPKR_R")
	)
	(segment
		(start 190.538354 -124.254768)
		(end 187.53074 -124.254768)
		(width 0.127)
		(layer "In15.Cu")
		(net "FM_PCH_SPKR_R")
	)
	(segment
		(start 194.056 -90.660728)
		(end 194.056 -92.401898)
		(width 0.12954)
		(layer "F.Cu")
		(net "E1S_0_LED_ACT_R_N")
	)
	(segment
		(start 194.31 -90.406728)
		(end 194.056 -90.660728)
		(width 0.12954)
		(layer "F.Cu")
		(net "E1S_0_LED_ACT_R_N")
	)
	(segment
		(start 194.31 -90.134948)
		(end 194.31 -90.406728)
		(width 0.12954)
		(layer "F.Cu")
		(net "E1S_0_LED_ACT_R_N")
	)
	(segment
		(start 182.955692 -118.575328)
		(end 183.355742 -118.975378)
		(width 0.12954)
		(layer "F.Cu")
		(net "E1S_0_LED_ACT_R_N")
	)
	(via
		(at 183.355742 -118.975378)
		(size 0.4572)
		(drill 0.254)
		(layers "F.Cu" "B.Cu")
		(net "E1S_0_LED_ACT_R_N")
	)
	(via
		(at 194.31 -90.134948)
		(size 0.762)
		(drill 0.254)
		(layers "F.Cu" "B.Cu")
		(net "E1S_0_LED_ACT_R_N")
	)
	(segment
		(start 190.6524 -94.064328)
		(end 190.6524 -97.926398)
		(width 0.127)
		(layer "In13.Cu")
		(net "E1S_0_LED_ACT_R_N")
	)
	(segment
		(start 182.9562 -118.575836)
		(end 183.355742 -118.975378)
		(width 0.127)
		(layer "In13.Cu")
		(net "E1S_0_LED_ACT_R_N")
	)
	(segment
		(start 194.31 -90.406728)
		(end 190.6524 -94.064328)
		(width 0.127)
		(layer "In13.Cu")
		(net "E1S_0_LED_ACT_R_N")
	)
	(segment
		(start 194.31 -90.134948)
		(end 194.31 -90.406728)
		(width 0.127)
		(layer "In13.Cu")
		(net "E1S_0_LED_ACT_R_N")
	)
	(segment
		(start 185.862214 -100.152708)
		(end 184.88406 -101.130862)
		(width 0.127)
		(layer "In13.Cu")
		(net "E1S_0_LED_ACT_R_N")
	)
	(segment
		(start 190.10757 -98.471228)
		(end 188.956696 -98.471228)
		(width 0.127)
		(layer "In13.Cu")
		(net "E1S_0_LED_ACT_R_N")
	)
	(segment
		(start 184.88406 -101.130862)
		(end 184.88406 -103.259128)
		(width 0.127)
		(layer "In13.Cu")
		(net "E1S_0_LED_ACT_R_N")
	)
	(segment
		(start 182.9562 -105.186988)
		(end 182.9562 -118.575836)
		(width 0.127)
		(layer "In13.Cu")
		(net "E1S_0_LED_ACT_R_N")
	)
	(segment
		(start 187.275216 -100.152708)
		(end 185.862214 -100.152708)
		(width 0.127)
		(layer "In13.Cu")
		(net "E1S_0_LED_ACT_R_N")
	)
	(segment
		(start 190.6524 -97.926398)
		(end 190.10757 -98.471228)
		(width 0.127)
		(layer "In13.Cu")
		(net "E1S_0_LED_ACT_R_N")
	)
	(segment
		(start 184.88406 -103.259128)
		(end 182.9562 -105.186988)
		(width 0.127)
		(layer "In13.Cu")
		(net "E1S_0_LED_ACT_R_N")
	)
	(segment
		(start 188.956696 -98.471228)
		(end 187.275216 -100.152708)
		(width 0.127)
		(layer "In13.Cu")
		(net "E1S_0_LED_ACT_R_N")
	)
	(segment
		(start 220.252036 -96.41967)
		(end 219.75445 -95.922084)
		(width 0.12954)
		(layer "F.Cu")
		(net "A_P12V_STBY_FPH_GATE")
	)
	(segment
		(start 212.91296 -97.053908)
		(end 214.291926 -97.053908)
		(width 0.12954)
		(layer "F.Cu")
		(net "A_P12V_STBY_FPH_GATE")
	)
	(segment
		(start 219.26296 -102.255574)
		(end 218.37396 -101.366574)
		(width 0.12954)
		(layer "F.Cu")
		(net "A_P12V_STBY_FPH_GATE")
	)
	(segment
		(start 219.75445 -94.751398)
		(end 219.202 -94.198948)
		(width 0.12954)
		(layer "F.Cu")
		(net "A_P12V_STBY_FPH_GATE")
	)
	(segment
		(start 213.522306 -93.782642)
		(end 212.344 -94.960948)
		(width 0.12954)
		(layer "F.Cu")
		(net "A_P12V_STBY_FPH_GATE")
	)
	(segment
		(start 215.111076 -94.426024)
		(end 214.467694 -93.782642)
		(width 0.12954)
		(layer "F.Cu")
		(net "A_P12V_STBY_FPH_GATE")
	)
	(segment
		(start 219.687394 -102.255574)
		(end 220.25356 -102.82174)
		(width 0.12954)
		(layer "F.Cu")
		(net "A_P12V_STBY_FPH_GATE")
	)
	(segment
		(start 222.758 -102.67696)
		(end 222.758 -97.754948)
		(width 0.12954)
		(layer "F.Cu")
		(net "A_P12V_STBY_FPH_GATE")
	)
	(segment
		(start 219.202 -94.198948)
		(end 217.493088 -94.198948)
		(width 0.12954)
		(layer "F.Cu")
		(net "A_P12V_STBY_FPH_GATE")
	)
	(segment
		(start 212.344 -94.960948)
		(end 212.344 -96.484948)
		(width 0.12954)
		(layer "F.Cu")
		(net "A_P12V_STBY_FPH_GATE")
	)
	(segment
		(start 214.467694 -93.782642)
		(end 213.522306 -93.782642)
		(width 0.12954)
		(layer "F.Cu")
		(net "A_P12V_STBY_FPH_GATE")
	)
	(segment
		(start 222.61322 -102.82174)
		(end 222.758 -102.67696)
		(width 0.12954)
		(layer "F.Cu")
		(net "A_P12V_STBY_FPH_GATE")
	)
	(segment
		(start 217.748866 -100.74148)
		(end 218.37396 -101.366574)
		(width 0.12954)
		(layer "F.Cu")
		(net "A_P12V_STBY_FPH_GATE")
	)
	(segment
		(start 219.687394 -102.255574)
		(end 219.26296 -102.255574)
		(width 0.12954)
		(layer "F.Cu")
		(net "A_P12V_STBY_FPH_GATE")
	)
	(segment
		(start 216.661492 -100.74148)
		(end 217.748866 -100.74148)
		(width 0.12954)
		(layer "F.Cu")
		(net "A_P12V_STBY_FPH_GATE")
	)
	(segment
		(start 219.75445 -95.922084)
		(end 219.75445 -94.751398)
		(width 0.12954)
		(layer "F.Cu")
		(net "A_P12V_STBY_FPH_GATE")
	)
	(segment
		(start 212.344 -96.484948)
		(end 212.91296 -97.053908)
		(width 0.12954)
		(layer "F.Cu")
		(net "A_P12V_STBY_FPH_GATE")
	)
	(segment
		(start 217.266012 -94.426024)
		(end 215.111076 -94.426024)
		(width 0.12954)
		(layer "F.Cu")
		(net "A_P12V_STBY_FPH_GATE")
	)
	(segment
		(start 217.493088 -94.198948)
		(end 217.266012 -94.426024)
		(width 0.12954)
		(layer "F.Cu")
		(net "A_P12V_STBY_FPH_GATE")
	)
	(segment
		(start 221.422722 -96.41967)
		(end 220.252036 -96.41967)
		(width 0.12954)
		(layer "F.Cu")
		(net "A_P12V_STBY_FPH_GATE")
	)
	(segment
		(start 220.25356 -102.82174)
		(end 222.61322 -102.82174)
		(width 0.12954)
		(layer "F.Cu")
		(net "A_P12V_STBY_FPH_GATE")
	)
	(segment
		(start 222.758 -97.754948)
		(end 221.422722 -96.41967)
		(width 0.12954)
		(layer "F.Cu")
		(net "A_P12V_STBY_FPH_GATE")
	)
	(via
		(at 218.37396 -101.366574)
		(size 0.508)
		(drill 0.254)
		(layers "F.Cu" "B.Cu")
		(net "A_P12V_STBY_FPH_GATE")
	)
	(segment
		(start 87.303102 -32.070548)
		(end 88.309958 -32.070548)
		(width 0.12954)
		(layer "F.Cu")
		(net "CLK_50M_NCSI_OCP_V3_2_ISO_R")
	)
	(segment
		(start 86.311994 -32.416496)
		(end 86.311994 -32.068008)
		(width 0.12954)
		(layer "F.Cu")
		(net "CLK_50M_NCSI_OCP_V3_2_ISO_R")
	)
	(segment
		(start 87.157306 -32.285432)
		(end 87.157306 -32.216344)
		(width 0.12954)
		(layer "F.Cu")
		(net "CLK_50M_NCSI_OCP_V3_2_ISO_R")
	)
	(segment
		(start 86.15553 -33.287208)
		(end 87.157306 -32.285432)
		(width 0.12954)
		(layer "F.Cu")
		(net "CLK_50M_NCSI_OCP_V3_2_ISO_R")
	)
	(segment
		(start 87.157306 -32.216344)
		(end 87.303102 -32.070548)
		(width 0.12954)
		(layer "F.Cu")
		(net "CLK_50M_NCSI_OCP_V3_2_ISO_R")
	)
	(segment
		(start 86.15553 -32.57296)
		(end 86.311994 -32.416496)
		(width 0.12954)
		(layer "F.Cu")
		(net "CLK_50M_NCSI_OCP_V3_2_ISO_R")
	)
	(segment
		(start 86.15553 -33.287208)
		(end 86.15553 -32.57296)
		(width 0.12954)
		(layer "F.Cu")
		(net "CLK_50M_NCSI_OCP_V3_2_ISO_R")
	)
	(via
		(at 86.15553 -33.287208)
		(size 0.762)
		(drill 0.381)
		(layers "F.Cu" "B.Cu")
		(net "CLK_50M_NCSI_OCP_V3_2_ISO_R")
	)
	(segment
		(start 373.144542 -16.271748)
		(end 372.454424 -16.271748)
		(width 0.12954)
		(layer "F.Cu")
		(net "CLK_50M_NCSI_OCP_SFF_ISO_R")
	)
	(segment
		(start 373.631968 -16.34617)
		(end 373.218964 -16.34617)
		(width 0.12954)
		(layer "F.Cu")
		(net "CLK_50M_NCSI_OCP_SFF_ISO_R")
	)
	(segment
		(start 373.218964 -16.34617)
		(end 373.144542 -16.271748)
		(width 0.12954)
		(layer "F.Cu")
		(net "CLK_50M_NCSI_OCP_SFF_ISO_R")
	)
	(segment
		(start 372.454424 -16.271748)
		(end 370.845842 -16.271748)
		(width 0.12954)
		(layer "F.Cu")
		(net "CLK_50M_NCSI_OCP_SFF_ISO_R")
	)
	(via
		(at 372.454424 -16.271748)
		(size 0.762)
		(drill 0.381)
		(layers "F.Cu" "B.Cu")
		(net "CLK_50M_NCSI_OCP_SFF_ISO_R")
	)
	(segment
		(start 191.135 -125.923548)
		(end 191.284606 -126.073154)
		(width 0.12954)
		(layer "F.Cu")
		(net "HP_LVC3_OCP_V3_2_HSC_PWRGD_PLD_")
	)
	(segment
		(start 191.284606 -126.073154)
		(end 191.284606 -126.568708)
		(width 0.12954)
		(layer "F.Cu")
		(net "HP_LVC3_OCP_V3_2_HSC_PWRGD_PLD_")
	)
	(segment
		(start 182.955692 -120.175528)
		(end 183.355742 -120.575578)
		(width 0.12954)
		(layer "F.Cu")
		(net "HP_LVC3_OCP_V3_2_HSC_PWRGD_PLD_")
	)
	(via
		(at 183.355742 -120.575578)
		(size 0.4572)
		(drill 0.254)
		(layers "F.Cu" "B.Cu")
		(net "HP_LVC3_OCP_V3_2_HSC_PWRGD_PLD_")
	)
	(via
		(at 191.135 -125.923548)
		(size 0.508)
		(drill 0.254)
		(layers "F.Cu" "B.Cu")
		(net "HP_LVC3_OCP_V3_2_HSC_PWRGD_PLD_")
	)
	(segment
		(start 182.9562 -120.97512)
		(end 183.355742 -120.575578)
		(width 0.127)
		(layer "In6.Cu")
		(net "HP_LVC3_OCP_V3_2_HSC_PWRGD_PLD_")
	)
	(segment
		(start 182.9562 -121.656348)
		(end 182.9562 -120.97512)
		(width 0.127)
		(layer "In6.Cu")
		(net "HP_LVC3_OCP_V3_2_HSC_PWRGD_PLD_")
	)
	(segment
		(start 191.135 -125.923548)
		(end 190.8302 -125.923548)
		(width 0.127)
		(layer "In6.Cu")
		(net "HP_LVC3_OCP_V3_2_HSC_PWRGD_PLD_")
	)
	(segment
		(start 185.2676 -123.967748)
		(end 182.9562 -121.656348)
		(width 0.127)
		(layer "In6.Cu")
		(net "HP_LVC3_OCP_V3_2_HSC_PWRGD_PLD_")
	)
	(segment
		(start 190.8302 -125.923548)
		(end 188.8744 -123.967748)
		(width 0.127)
		(layer "In6.Cu")
		(net "HP_LVC3_OCP_V3_2_HSC_PWRGD_PLD_")
	)
	(segment
		(start 188.8744 -123.967748)
		(end 185.2676 -123.967748)
		(width 0.127)
		(layer "In6.Cu")
		(net "HP_LVC3_OCP_V3_2_HSC_PWRGD_PLD_")
	)
	(segment
		(start 185.6359 -122.055636)
		(end 185.355738 -121.775474)
		(width 0.12954)
		(layer "F.Cu")
		(net "HP_LVC3_OCP_V3_1_HSC_PWRGD_PLD_")
	)
	(segment
		(start 188.001656 -125.013974)
		(end 189.046612 -125.013974)
		(width 0.12954)
		(layer "F.Cu")
		(net "HP_LVC3_OCP_V3_1_HSC_PWRGD_PLD_")
	)
	(segment
		(start 185.6359 -122.852688)
		(end 185.6359 -122.055636)
		(width 0.12954)
		(layer "F.Cu")
		(net "HP_LVC3_OCP_V3_1_HSC_PWRGD_PLD_")
	)
	(segment
		(start 187.46978 -125.433582)
		(end 187.46978 -124.686568)
		(width 0.12954)
		(layer "F.Cu")
		(net "HP_LVC3_OCP_V3_1_HSC_PWRGD_PLD_")
	)
	(segment
		(start 190.291466 -126.258828)
		(end 190.291466 -126.563628)
		(width 0.12954)
		(layer "F.Cu")
		(net "HP_LVC3_OCP_V3_1_HSC_PWRGD_PLD_")
	)
	(segment
		(start 187.46978 -125.433582)
		(end 187.582048 -125.433582)
		(width 0.12954)
		(layer "F.Cu")
		(net "HP_LVC3_OCP_V3_1_HSC_PWRGD_PLD_")
	)
	(segment
		(start 187.46978 -124.686568)
		(end 185.6359 -122.852688)
		(width 0.12954)
		(layer "F.Cu")
		(net "HP_LVC3_OCP_V3_1_HSC_PWRGD_PLD_")
	)
	(segment
		(start 187.582048 -125.433582)
		(end 188.001656 -125.013974)
		(width 0.12954)
		(layer "F.Cu")
		(net "HP_LVC3_OCP_V3_1_HSC_PWRGD_PLD_")
	)
	(segment
		(start 189.046612 -125.013974)
		(end 190.291466 -126.258828)
		(width 0.12954)
		(layer "F.Cu")
		(net "HP_LVC3_OCP_V3_1_HSC_PWRGD_PLD_")
	)
	(via
		(at 187.46978 -125.433582)
		(size 0.762)
		(drill 0.381)
		(layers "F.Cu" "B.Cu")
		(net "HP_LVC3_OCP_V3_1_HSC_PWRGD_PLD_")
	)
	(segment
		(start 173.30928 -96.8248)
		(end 172.2247 -95.74022)
		(width 0.12954)
		(layer "F.Cu")
		(net "FM_BOARD_BMC_SKU_ID4")
	)
	(segment
		(start 172.339762 -93.938598)
		(end 172.8724 -93.938598)
		(width 0.12954)
		(layer "F.Cu")
		(net "FM_BOARD_BMC_SKU_ID4")
	)
	(segment
		(start 175.755554 -108.175552)
		(end 175.355504 -107.775502)
		(width 0.12954)
		(layer "F.Cu")
		(net "FM_BOARD_BMC_SKU_ID4")
	)
	(segment
		(start 173.609 -96.8248)
		(end 173.30928 -96.8248)
		(width 0.12954)
		(layer "F.Cu")
		(net "FM_BOARD_BMC_SKU_ID4")
	)
	(segment
		(start 172.2247 -94.05366)
		(end 172.339762 -93.938598)
		(width 0.12954)
		(layer "F.Cu")
		(net "FM_BOARD_BMC_SKU_ID4")
	)
	(segment
		(start 172.2247 -95.74022)
		(end 172.2247 -94.05366)
		(width 0.12954)
		(layer "F.Cu")
		(net "FM_BOARD_BMC_SKU_ID4")
	)
	(via
		(at 173.609 -96.8248)
		(size 0.762)
		(drill 0.254)
		(layers "F.Cu" "B.Cu")
		(net "FM_BOARD_BMC_SKU_ID4")
	)
	(via
		(at 175.355504 -107.775502)
		(size 0.4572)
		(drill 0.254)
		(layers "F.Cu" "B.Cu")
		(net "FM_BOARD_BMC_SKU_ID4")
	)
	(segment
		(start 173.892718 -96.8248)
		(end 174.603918 -97.536)
		(width 0.127)
		(layer "In13.Cu")
		(net "FM_BOARD_BMC_SKU_ID4")
	)
	(segment
		(start 173.609 -96.8248)
		(end 173.892718 -96.8248)
		(width 0.127)
		(layer "In13.Cu")
		(net "FM_BOARD_BMC_SKU_ID4")
	)
	(segment
		(start 174.96282 -104.358948)
		(end 175.75276 -105.148888)
		(width 0.127)
		(layer "In13.Cu")
		(net "FM_BOARD_BMC_SKU_ID4")
	)
	(segment
		(start 175.38954 -101.158548)
		(end 175.38954 -101.862128)
		(width 0.127)
		(layer "In13.Cu")
		(net "FM_BOARD_BMC_SKU_ID4")
	)
	(segment
		(start 175.75276 -107.378246)
		(end 175.355504 -107.775502)
		(width 0.127)
		(layer "In13.Cu")
		(net "FM_BOARD_BMC_SKU_ID4")
	)
	(segment
		(start 175.9966 -97.536)
		(end 177.4063 -98.9457)
		(width 0.127)
		(layer "In13.Cu")
		(net "FM_BOARD_BMC_SKU_ID4")
	)
	(segment
		(start 175.75276 -105.148888)
		(end 175.75276 -107.378246)
		(width 0.127)
		(layer "In13.Cu")
		(net "FM_BOARD_BMC_SKU_ID4")
	)
	(segment
		(start 174.603918 -97.536)
		(end 175.9966 -97.536)
		(width 0.127)
		(layer "In13.Cu")
		(net "FM_BOARD_BMC_SKU_ID4")
	)
	(segment
		(start 177.4063 -98.9457)
		(end 177.4063 -99.141788)
		(width 0.127)
		(layer "In13.Cu")
		(net "FM_BOARD_BMC_SKU_ID4")
	)
	(segment
		(start 175.38954 -101.862128)
		(end 174.96282 -102.288848)
		(width 0.127)
		(layer "In13.Cu")
		(net "FM_BOARD_BMC_SKU_ID4")
	)
	(segment
		(start 177.4063 -99.141788)
		(end 175.38954 -101.158548)
		(width 0.127)
		(layer "In13.Cu")
		(net "FM_BOARD_BMC_SKU_ID4")
	)
	(segment
		(start 174.96282 -102.288848)
		(end 174.96282 -104.358948)
		(width 0.127)
		(layer "In13.Cu")
		(net "FM_BOARD_BMC_SKU_ID4")
	)
	(segment
		(start 179.9082 -93.252798)
		(end 179.9082 -92.2528)
		(width 0.12954)
		(layer "F.Cu")
		(net "FM_BOARD_BMC_SKU_ID3")
	)
	(segment
		(start 179.451 -91.7956)
		(end 179.2478 -91.7956)
		(width 0.12954)
		(layer "F.Cu")
		(net "FM_BOARD_BMC_SKU_ID3")
	)
	(segment
		(start 179.9082 -92.2528)
		(end 179.451 -91.7956)
		(width 0.12954)
		(layer "F.Cu")
		(net "FM_BOARD_BMC_SKU_ID3")
	)
	(segment
		(start 176.555654 -108.175552)
		(end 176.155604 -107.775502)
		(width 0.12954)
		(layer "F.Cu")
		(net "FM_BOARD_BMC_SKU_ID3")
	)
	(segment
		(start 179.2224 -93.938598)
		(end 179.9082 -93.252798)
		(width 0.12954)
		(layer "F.Cu")
		(net "FM_BOARD_BMC_SKU_ID3")
	)
	(via
		(at 176.155604 -107.775502)
		(size 0.4572)
		(drill 0.254)
		(layers "F.Cu" "B.Cu")
		(net "FM_BOARD_BMC_SKU_ID3")
	)
	(via
		(at 179.2478 -91.7956)
		(size 0.508)
		(drill 0.254)
		(layers "F.Cu" "B.Cu")
		(net "FM_BOARD_BMC_SKU_ID3")
	)
	(segment
		(start 175.762666 -107.284266)
		(end 175.762666 -105.12552)
		(width 0.127)
		(layer "In11.Cu")
		(net "FM_BOARD_BMC_SKU_ID3")
	)
	(segment
		(start 172.8724 -96.2152)
		(end 172.3898 -95.7326)
		(width 0.127)
		(layer "In11.Cu")
		(net "FM_BOARD_BMC_SKU_ID3")
	)
	(segment
		(start 173.355 -93.2434)
		(end 173.355 -92.202254)
		(width 0.127)
		(layer "In11.Cu")
		(net "FM_BOARD_BMC_SKU_ID3")
	)
	(segment
		(start 177.4825 -99.98837)
		(end 177.4825 -98.359976)
		(width 0.127)
		(layer "In11.Cu")
		(net "FM_BOARD_BMC_SKU_ID3")
	)
	(segment
		(start 176.155604 -107.677204)
		(end 175.762666 -107.284266)
		(width 0.127)
		(layer "In11.Cu")
		(net "FM_BOARD_BMC_SKU_ID3")
	)
	(segment
		(start 174.3456 -96.2152)
		(end 172.8724 -96.2152)
		(width 0.127)
		(layer "In11.Cu")
		(net "FM_BOARD_BMC_SKU_ID3")
	)
	(segment
		(start 175.387 -104.749854)
		(end 175.387 -102.08387)
		(width 0.127)
		(layer "In11.Cu")
		(net "FM_BOARD_BMC_SKU_ID3")
	)
	(segment
		(start 173.355 -92.202254)
		(end 173.761654 -91.7956)
		(width 0.127)
		(layer "In11.Cu")
		(net "FM_BOARD_BMC_SKU_ID3")
	)
	(segment
		(start 177.4825 -98.359976)
		(end 175.972724 -96.8502)
		(width 0.127)
		(layer "In11.Cu")
		(net "FM_BOARD_BMC_SKU_ID3")
	)
	(segment
		(start 172.3898 -94.2086)
		(end 173.355 -93.2434)
		(width 0.127)
		(layer "In11.Cu")
		(net "FM_BOARD_BMC_SKU_ID3")
	)
	(segment
		(start 173.761654 -91.7956)
		(end 179.2478 -91.7956)
		(width 0.127)
		(layer "In11.Cu")
		(net "FM_BOARD_BMC_SKU_ID3")
	)
	(segment
		(start 172.3898 -95.7326)
		(end 172.3898 -94.2086)
		(width 0.127)
		(layer "In11.Cu")
		(net "FM_BOARD_BMC_SKU_ID3")
	)
	(segment
		(start 176.155604 -107.775502)
		(end 176.155604 -107.677204)
		(width 0.127)
		(layer "In11.Cu")
		(net "FM_BOARD_BMC_SKU_ID3")
	)
	(segment
		(start 175.762666 -105.12552)
		(end 175.387 -104.749854)
		(width 0.127)
		(layer "In11.Cu")
		(net "FM_BOARD_BMC_SKU_ID3")
	)
	(segment
		(start 174.9806 -96.8502)
		(end 174.3456 -96.2152)
		(width 0.127)
		(layer "In11.Cu")
		(net "FM_BOARD_BMC_SKU_ID3")
	)
	(segment
		(start 175.387 -102.08387)
		(end 177.4825 -99.98837)
		(width 0.127)
		(layer "In11.Cu")
		(net "FM_BOARD_BMC_SKU_ID3")
	)
	(segment
		(start 175.972724 -96.8502)
		(end 174.9806 -96.8502)
		(width 0.127)
		(layer "In11.Cu")
		(net "FM_BOARD_BMC_SKU_ID3")
	)
	(segment
		(start 173.580298 -93.938598)
		(end 173.5074 -93.8657)
		(width 0.12954)
		(layer "F.Cu")
		(net "FM_BOARD_BMC_SKU_ID2")
	)
	(segment
		(start 174.1424 -93.938598)
		(end 173.580298 -93.938598)
		(width 0.12954)
		(layer "F.Cu")
		(net "FM_BOARD_BMC_SKU_ID2")
	)
	(segment
		(start 176.555654 -107.375452)
		(end 176.155604 -106.975402)
		(width 0.12954)
		(layer "F.Cu")
		(net "FM_BOARD_BMC_SKU_ID2")
	)
	(via
		(at 173.5074 -93.8657)
		(size 0.508)
		(drill 0.254)
		(layers "F.Cu" "B.Cu")
		(net "FM_BOARD_BMC_SKU_ID2")
	)
	(via
		(at 176.155604 -106.975402)
		(size 0.4572)
		(drill 0.254)
		(layers "F.Cu" "B.Cu")
		(net "FM_BOARD_BMC_SKU_ID2")
	)
	(segment
		(start 176.53 -102.173786)
		(end 176.11598 -101.759766)
		(width 0.127)
		(layer "In2.Cu")
		(net "FM_BOARD_BMC_SKU_ID2")
	)
	(segment
		(start 176.11598 -101.759766)
		(end 176.11598 -100.36302)
		(width 0.127)
		(layer "In2.Cu")
		(net "FM_BOARD_BMC_SKU_ID2")
	)
	(segment
		(start 176.0982 -94.732094)
		(end 175.280066 -93.91396)
		(width 0.127)
		(layer "In2.Cu")
		(net "FM_BOARD_BMC_SKU_ID2")
	)
	(segment
		(start 177.419 -96.871028)
		(end 176.0982 -95.550228)
		(width 0.127)
		(layer "In2.Cu")
		(net "FM_BOARD_BMC_SKU_ID2")
	)
	(segment
		(start 176.11598 -100.36302)
		(end 177.419 -99.06)
		(width 0.127)
		(layer "In2.Cu")
		(net "FM_BOARD_BMC_SKU_ID2")
	)
	(segment
		(start 176.53 -103.072946)
		(end 176.53 -102.173786)
		(width 0.127)
		(layer "In2.Cu")
		(net "FM_BOARD_BMC_SKU_ID2")
	)
	(segment
		(start 176.155604 -103.447342)
		(end 176.53 -103.072946)
		(width 0.127)
		(layer "In2.Cu")
		(net "FM_BOARD_BMC_SKU_ID2")
	)
	(segment
		(start 175.280066 -93.91396)
		(end 173.55566 -93.91396)
		(width 0.127)
		(layer "In2.Cu")
		(net "FM_BOARD_BMC_SKU_ID2")
	)
	(segment
		(start 173.55566 -93.91396)
		(end 173.5074 -93.8657)
		(width 0.127)
		(layer "In2.Cu")
		(net "FM_BOARD_BMC_SKU_ID2")
	)
	(segment
		(start 177.419 -99.06)
		(end 177.419 -96.871028)
		(width 0.127)
		(layer "In2.Cu")
		(net "FM_BOARD_BMC_SKU_ID2")
	)
	(segment
		(start 176.0982 -95.550228)
		(end 176.0982 -94.732094)
		(width 0.127)
		(layer "In2.Cu")
		(net "FM_BOARD_BMC_SKU_ID2")
	)
	(segment
		(start 176.155604 -106.975402)
		(end 176.155604 -103.447342)
		(width 0.127)
		(layer "In2.Cu")
		(net "FM_BOARD_BMC_SKU_ID2")
	)
	(segment
		(start 177.46726 -98.533712)
		(end 177.46726 -99.192588)
		(width 0.12954)
		(layer "F.Cu")
		(net "FM_BOARD_BMC_SKU_ID1")
	)
	(segment
		(start 176.57572 -102.91064)
		(end 176.149 -103.33736)
		(width 0.12954)
		(layer "F.Cu")
		(net "FM_BOARD_BMC_SKU_ID1")
	)
	(segment
		(start 175.4124 -93.938598)
		(end 174.884842 -93.938598)
		(width 0.12954)
		(layer "F.Cu")
		(net "FM_BOARD_BMC_SKU_ID1")
	)
	(segment
		(start 177.46726 -99.192588)
		(end 177.27422 -99.385628)
		(width 0.12954)
		(layer "F.Cu")
		(net "FM_BOARD_BMC_SKU_ID1")
	)
	(segment
		(start 175.38192 -96.26346)
		(end 176.78654 -96.26346)
		(width 0.12954)
		(layer "F.Cu")
		(net "FM_BOARD_BMC_SKU_ID1")
	)
	(segment
		(start 174.79264 -95.67418)
		(end 175.38192 -96.26346)
		(width 0.12954)
		(layer "F.Cu")
		(net "FM_BOARD_BMC_SKU_ID1")
	)
	(segment
		(start 176.149 -106.168698)
		(end 176.555654 -106.575352)
		(width 0.12954)
		(layer "F.Cu")
		(net "FM_BOARD_BMC_SKU_ID1")
	)
	(segment
		(start 176.78654 -96.26346)
		(end 177.23358 -96.7105)
		(width 0.12954)
		(layer "F.Cu")
		(net "FM_BOARD_BMC_SKU_ID1")
	)
	(segment
		(start 177.23358 -96.7105)
		(end 177.23358 -98.300032)
		(width 0.12954)
		(layer "F.Cu")
		(net "FM_BOARD_BMC_SKU_ID1")
	)
	(segment
		(start 176.57572 -102.3874)
		(end 176.57572 -102.91064)
		(width 0.12954)
		(layer "F.Cu")
		(net "FM_BOARD_BMC_SKU_ID1")
	)
	(segment
		(start 177.23358 -98.300032)
		(end 177.46726 -98.533712)
		(width 0.12954)
		(layer "F.Cu")
		(net "FM_BOARD_BMC_SKU_ID1")
	)
	(segment
		(start 177.1777 -99.482148)
		(end 177.1777 -101.78542)
		(width 0.12954)
		(layer "F.Cu")
		(net "FM_BOARD_BMC_SKU_ID1")
	)
	(segment
		(start 174.884842 -93.938598)
		(end 174.79264 -94.0308)
		(width 0.12954)
		(layer "F.Cu")
		(net "FM_BOARD_BMC_SKU_ID1")
	)
	(segment
		(start 176.149 -103.33736)
		(end 176.149 -106.168698)
		(width 0.12954)
		(layer "F.Cu")
		(net "FM_BOARD_BMC_SKU_ID1")
	)
	(segment
		(start 177.27422 -99.385628)
		(end 177.1777 -99.482148)
		(width 0.12954)
		(layer "F.Cu")
		(net "FM_BOARD_BMC_SKU_ID1")
	)
	(segment
		(start 174.79264 -94.0308)
		(end 174.79264 -95.67418)
		(width 0.12954)
		(layer "F.Cu")
		(net "FM_BOARD_BMC_SKU_ID1")
	)
	(segment
		(start 177.1777 -101.78542)
		(end 176.57572 -102.3874)
		(width 0.12954)
		(layer "F.Cu")
		(net "FM_BOARD_BMC_SKU_ID1")
	)
	(via
		(at 177.27422 -99.385628)
		(size 0.762)
		(drill 0.381)
		(layers "F.Cu" "B.Cu")
		(net "FM_BOARD_BMC_SKU_ID1")
	)
	(segment
		(start 177.2412 -94.12478)
		(end 177.427382 -93.938598)
		(width 0.12954)
		(layer "F.Cu")
		(net "FM_BOARD_BMC_SKU_ID0")
	)
	(segment
		(start 177.85842 -104.032812)
		(end 177.85842 -104.046528)
		(width 0.12954)
		(layer "F.Cu")
		(net "FM_BOARD_BMC_SKU_ID0")
	)
	(segment
		(start 177.2158 -104.485948)
		(end 176.9364 -104.765348)
		(width 0.12954)
		(layer "F.Cu")
		(net "FM_BOARD_BMC_SKU_ID0")
	)
	(segment
		(start 178.130708 -96.01073)
		(end 177.88763 -96.01073)
		(width 0.12954)
		(layer "F.Cu")
		(net "FM_BOARD_BMC_SKU_ID0")
	)
	(segment
		(start 177.87112 -99.997768)
		(end 177.87112 -104.020112)
		(width 0.12954)
		(layer "F.Cu")
		(net "FM_BOARD_BMC_SKU_ID0")
	)
	(segment
		(start 178.48707 -96.367092)
		(end 178.130708 -96.01073)
		(width 0.12954)
		(layer "F.Cu")
		(net "FM_BOARD_BMC_SKU_ID0")
	)
	(segment
		(start 178.48707 -96.367092)
		(end 178.48707 -98.26117)
		(width 0.12954)
		(layer "F.Cu")
		(net "FM_BOARD_BMC_SKU_ID0")
	)
	(segment
		(start 178.12893 -98.61931)
		(end 178.12893 -99.739958)
		(width 0.12954)
		(layer "F.Cu")
		(net "FM_BOARD_BMC_SKU_ID0")
	)
	(segment
		(start 176.9364 -104.765348)
		(end 176.9364 -105.39476)
		(width 0.12954)
		(layer "F.Cu")
		(net "FM_BOARD_BMC_SKU_ID0")
	)
	(segment
		(start 177.87112 -104.020112)
		(end 177.85842 -104.032812)
		(width 0.12954)
		(layer "F.Cu")
		(net "FM_BOARD_BMC_SKU_ID0")
	)
	(segment
		(start 178.48707 -98.26117)
		(end 178.12893 -98.61931)
		(width 0.12954)
		(layer "F.Cu")
		(net "FM_BOARD_BMC_SKU_ID0")
	)
	(segment
		(start 176.9364 -105.39476)
		(end 176.555654 -105.775506)
		(width 0.12954)
		(layer "F.Cu")
		(net "FM_BOARD_BMC_SKU_ID0")
	)
	(segment
		(start 177.2412 -95.3643)
		(end 177.2412 -94.12478)
		(width 0.12954)
		(layer "F.Cu")
		(net "FM_BOARD_BMC_SKU_ID0")
	)
	(segment
		(start 177.427382 -93.938598)
		(end 177.9524 -93.938598)
		(width 0.12954)
		(layer "F.Cu")
		(net "FM_BOARD_BMC_SKU_ID0")
	)
	(segment
		(start 177.88763 -96.01073)
		(end 177.2412 -95.3643)
		(width 0.12954)
		(layer "F.Cu")
		(net "FM_BOARD_BMC_SKU_ID0")
	)
	(segment
		(start 178.12893 -99.739958)
		(end 177.87112 -99.997768)
		(width 0.12954)
		(layer "F.Cu")
		(net "FM_BOARD_BMC_SKU_ID0")
	)
	(segment
		(start 177.419 -104.485948)
		(end 177.2158 -104.485948)
		(width 0.12954)
		(layer "F.Cu")
		(net "FM_BOARD_BMC_SKU_ID0")
	)
	(segment
		(start 177.85842 -104.046528)
		(end 177.419 -104.485948)
		(width 0.12954)
		(layer "F.Cu")
		(net "FM_BOARD_BMC_SKU_ID0")
	)
	(via
		(at 178.48707 -96.367092)
		(size 0.762)
		(drill 0.381)
		(layers "F.Cu" "B.Cu")
		(net "FM_BOARD_BMC_SKU_ID0")
	)
	(segment
		(start 177.58918 -103.909368)
		(end 177.58918 -99.880928)
		(width 0.12954)
		(layer "F.Cu")
		(net "FAB_BMC_REV_ID2")
	)
	(segment
		(start 177.84699 -96.59493)
		(end 177.15992 -95.90786)
		(width 0.12954)
		(layer "F.Cu")
		(net "FAB_BMC_REV_ID2")
	)
	(segment
		(start 177.0634 -104.206548)
		(end 177.292 -104.206548)
		(width 0.12954)
		(layer "F.Cu")
		(net "FAB_BMC_REV_ID2")
	)
	(segment
		(start 176.190402 -93.938598)
		(end 176.6824 -93.938598)
		(width 0.12954)
		(layer "F.Cu")
		(net "FAB_BMC_REV_ID2")
	)
	(segment
		(start 177.58918 -99.880928)
		(end 177.84699 -99.623118)
		(width 0.12954)
		(layer "F.Cu")
		(net "FAB_BMC_REV_ID2")
	)
	(segment
		(start 177.84699 -97.79254)
		(end 177.84699 -96.59493)
		(width 0.12954)
		(layer "F.Cu")
		(net "FAB_BMC_REV_ID2")
	)
	(segment
		(start 176.06772 -95.4913)
		(end 176.06772 -94.06128)
		(width 0.12954)
		(layer "F.Cu")
		(net "FAB_BMC_REV_ID2")
	)
	(segment
		(start 176.06772 -94.06128)
		(end 176.190402 -93.938598)
		(width 0.12954)
		(layer "F.Cu")
		(net "FAB_BMC_REV_ID2")
	)
	(segment
		(start 176.555654 -104.975406)
		(end 176.555654 -104.714294)
		(width 0.12954)
		(layer "F.Cu")
		(net "FAB_BMC_REV_ID2")
	)
	(segment
		(start 177.84699 -99.623118)
		(end 177.84699 -97.79254)
		(width 0.12954)
		(layer "F.Cu")
		(net "FAB_BMC_REV_ID2")
	)
	(segment
		(start 177.15992 -95.90786)
		(end 176.48428 -95.90786)
		(width 0.12954)
		(layer "F.Cu")
		(net "FAB_BMC_REV_ID2")
	)
	(segment
		(start 177.292 -104.206548)
		(end 177.58918 -103.909368)
		(width 0.12954)
		(layer "F.Cu")
		(net "FAB_BMC_REV_ID2")
	)
	(segment
		(start 176.48428 -95.90786)
		(end 176.06772 -95.4913)
		(width 0.12954)
		(layer "F.Cu")
		(net "FAB_BMC_REV_ID2")
	)
	(segment
		(start 176.555654 -104.714294)
		(end 177.0634 -104.206548)
		(width 0.12954)
		(layer "F.Cu")
		(net "FAB_BMC_REV_ID2")
	)
	(via
		(at 177.84699 -97.79254)
		(size 0.762)
		(drill 0.381)
		(layers "F.Cu" "B.Cu")
		(net "FAB_BMC_REV_ID2")
	)
	(segment
		(start 181.7624 -93.938598)
		(end 182.299356 -93.938598)
		(width 0.12954)
		(layer "F.Cu")
		(net "FAB_BMC_REV_ID1")
	)
	(segment
		(start 182.299356 -92.4306)
		(end 181.7624 -92.4306)
		(width 0.12954)
		(layer "F.Cu")
		(net "FAB_BMC_REV_ID1")
	)
	(segment
		(start 182.299356 -93.938598)
		(end 182.426356 -93.811598)
		(width 0.12954)
		(layer "F.Cu")
		(net "FAB_BMC_REV_ID1")
	)
	(segment
		(start 177.355754 -109.775498)
		(end 176.955704 -109.375448)
		(width 0.12954)
		(layer "F.Cu")
		(net "FAB_BMC_REV_ID1")
	)
	(segment
		(start 182.426356 -92.5576)
		(end 182.299356 -92.4306)
		(width 0.12954)
		(layer "F.Cu")
		(net "FAB_BMC_REV_ID1")
	)
	(segment
		(start 182.426356 -93.811598)
		(end 182.426356 -92.5576)
		(width 0.12954)
		(layer "F.Cu")
		(net "FAB_BMC_REV_ID1")
	)
	(via
		(at 181.7624 -92.4306)
		(size 0.508)
		(drill 0.254)
		(layers "F.Cu" "B.Cu")
		(net "FAB_BMC_REV_ID1")
	)
	(via
		(at 176.955704 -109.375448)
		(size 0.4572)
		(drill 0.254)
		(layers "F.Cu" "B.Cu")
		(net "FAB_BMC_REV_ID1")
	)
	(segment
		(start 177.8127 -100.125276)
		(end 177.0888 -100.849176)
		(width 0.127)
		(layer "In11.Cu")
		(net "FAB_BMC_REV_ID1")
	)
	(segment
		(start 175.351694 -96.52)
		(end 176.1236 -96.52)
		(width 0.127)
		(layer "In11.Cu")
		(net "FAB_BMC_REV_ID1")
	)
	(segment
		(start 176.955704 -109.315504)
		(end 176.955704 -109.375448)
		(width 0.127)
		(layer "In11.Cu")
		(net "FAB_BMC_REV_ID1")
	)
	(segment
		(start 177.8127 -98.2091)
		(end 177.8127 -100.125276)
		(width 0.127)
		(layer "In11.Cu")
		(net "FAB_BMC_REV_ID1")
	)
	(segment
		(start 174.716694 -95.885)
		(end 175.351694 -96.52)
		(width 0.127)
		(layer "In11.Cu")
		(net "FAB_BMC_REV_ID1")
	)
	(segment
		(start 173.482 -95.6056)
		(end 173.7614 -95.885)
		(width 0.127)
		(layer "In11.Cu")
		(net "FAB_BMC_REV_ID1")
	)
	(segment
		(start 176.5046 -102.3366)
		(end 176.5046 -102.9716)
		(width 0.127)
		(layer "In11.Cu")
		(net "FAB_BMC_REV_ID1")
	)
	(segment
		(start 181.7624 -92.4306)
		(end 181.1528 -93.0402)
		(width 0.127)
		(layer "In11.Cu")
		(net "FAB_BMC_REV_ID1")
	)
	(segment
		(start 176.5554 -106.6546)
		(end 176.5554 -108.9152)
		(width 0.127)
		(layer "In11.Cu")
		(net "FAB_BMC_REV_ID1")
	)
	(segment
		(start 176.5046 -102.9716)
		(end 176.2252 -103.251)
		(width 0.127)
		(layer "In11.Cu")
		(net "FAB_BMC_REV_ID1")
	)
	(segment
		(start 176.2252 -106.3244)
		(end 176.5554 -106.6546)
		(width 0.127)
		(layer "In11.Cu")
		(net "FAB_BMC_REV_ID1")
	)
	(segment
		(start 173.7614 -95.885)
		(end 174.716694 -95.885)
		(width 0.127)
		(layer "In11.Cu")
		(net "FAB_BMC_REV_ID1")
	)
	(segment
		(start 177.0888 -100.849176)
		(end 177.0888 -101.7524)
		(width 0.127)
		(layer "In11.Cu")
		(net "FAB_BMC_REV_ID1")
	)
	(segment
		(start 175.514 -93.0402)
		(end 173.482 -95.0722)
		(width 0.127)
		(layer "In11.Cu")
		(net "FAB_BMC_REV_ID1")
	)
	(segment
		(start 181.1528 -93.0402)
		(end 175.514 -93.0402)
		(width 0.127)
		(layer "In11.Cu")
		(net "FAB_BMC_REV_ID1")
	)
	(segment
		(start 176.2252 -103.251)
		(end 176.2252 -106.3244)
		(width 0.127)
		(layer "In11.Cu")
		(net "FAB_BMC_REV_ID1")
	)
	(segment
		(start 177.0888 -101.7524)
		(end 176.5046 -102.3366)
		(width 0.127)
		(layer "In11.Cu")
		(net "FAB_BMC_REV_ID1")
	)
	(segment
		(start 173.482 -95.0722)
		(end 173.482 -95.6056)
		(width 0.127)
		(layer "In11.Cu")
		(net "FAB_BMC_REV_ID1")
	)
	(segment
		(start 176.1236 -96.52)
		(end 177.8127 -98.2091)
		(width 0.127)
		(layer "In11.Cu")
		(net "FAB_BMC_REV_ID1")
	)
	(segment
		(start 176.5554 -108.9152)
		(end 176.955704 -109.315504)
		(width 0.127)
		(layer "In11.Cu")
		(net "FAB_BMC_REV_ID1")
	)
	(segment
		(start 180.581554 -95.58274)
		(end 179.673504 -95.58274)
		(width 0.12954)
		(layer "F.Cu")
		(net "FAB_BMC_REV_ID0")
	)
	(segment
		(start 179.42814 -95.828104)
		(end 179.42814 -98.78314)
		(width 0.12954)
		(layer "F.Cu")
		(net "FAB_BMC_REV_ID0")
	)
	(segment
		(start 181.0258 -94.471998)
		(end 181.0258 -95.138494)
		(width 0.12954)
		(layer "F.Cu")
		(net "FAB_BMC_REV_ID0")
	)
	(segment
		(start 177.355754 -108.975398)
		(end 176.955704 -108.575348)
		(width 0.12954)
		(layer "F.Cu")
		(net "FAB_BMC_REV_ID0")
	)
	(segment
		(start 179.9336 -99.568)
		(end 179.6796 -99.822)
		(width 0.12954)
		(layer "F.Cu")
		(net "FAB_BMC_REV_ID0")
	)
	(segment
		(start 179.42814 -98.78314)
		(end 179.9336 -99.2886)
		(width 0.12954)
		(layer "F.Cu")
		(net "FAB_BMC_REV_ID0")
	)
	(segment
		(start 179.673504 -95.58274)
		(end 179.42814 -95.828104)
		(width 0.12954)
		(layer "F.Cu")
		(net "FAB_BMC_REV_ID0")
	)
	(segment
		(start 180.4924 -93.938598)
		(end 181.0258 -94.471998)
		(width 0.12954)
		(layer "F.Cu")
		(net "FAB_BMC_REV_ID0")
	)
	(segment
		(start 181.0258 -95.138494)
		(end 180.581554 -95.58274)
		(width 0.12954)
		(layer "F.Cu")
		(net "FAB_BMC_REV_ID0")
	)
	(segment
		(start 179.9336 -99.2886)
		(end 179.9336 -99.568)
		(width 0.12954)
		(layer "F.Cu")
		(net "FAB_BMC_REV_ID0")
	)
	(segment
		(start 179.6796 -99.822)
		(end 179.6796 -100.6348)
		(width 0.12954)
		(layer "F.Cu")
		(net "FAB_BMC_REV_ID0")
	)
	(via
		(at 176.955704 -108.575348)
		(size 0.4572)
		(drill 0.254)
		(layers "F.Cu" "B.Cu")
		(net "FAB_BMC_REV_ID0")
	)
	(via
		(at 179.9336 -99.568)
		(size 0.762)
		(drill 0.381)
		(layers "F.Cu" "B.Cu")
		(net "FAB_BMC_REV_ID0")
	)
	(via
		(at 179.6796 -100.6348)
		(size 0.508)
		(drill 0.254)
		(layers "F.Cu" "B.Cu")
		(net "FAB_BMC_REV_ID0")
	)
	(segment
		(start 178.1556 -105.6386)
		(end 177.362612 -106.431588)
		(width 0.127)
		(layer "In6.Cu")
		(net "FAB_BMC_REV_ID0")
	)
	(segment
		(start 178.1556 -101.1174)
		(end 178.1556 -105.6386)
		(width 0.127)
		(layer "In6.Cu")
		(net "FAB_BMC_REV_ID0")
	)
	(segment
		(start 178.6382 -100.6348)
		(end 178.1556 -101.1174)
		(width 0.127)
		(layer "In6.Cu")
		(net "FAB_BMC_REV_ID0")
	)
	(segment
		(start 177.362612 -106.431588)
		(end 177.362612 -108.16844)
		(width 0.127)
		(layer "In6.Cu")
		(net "FAB_BMC_REV_ID0")
	)
	(segment
		(start 179.6796 -100.6348)
		(end 178.6382 -100.6348)
		(width 0.127)
		(layer "In6.Cu")
		(net "FAB_BMC_REV_ID0")
	)
	(segment
		(start 177.362612 -108.16844)
		(end 176.955704 -108.575348)
		(width 0.127)
		(layer "In6.Cu")
		(net "FAB_BMC_REV_ID0")
	)
	(segment
		(start 40.227504 -106.015282)
		(end 40.227504 -105.006902)
		(width 0.12954)
		(layer "F.Cu")
		(net "P1V581_PDB_ADC")
	)
	(segment
		(start 38.830758 -104.52862)
		(end 38.830758 -104.069642)
		(width 0.12954)
		(layer "F.Cu")
		(net "P1V581_PDB_ADC")
	)
	(segment
		(start 38.967918 -104.993948)
		(end 38.830758 -104.856788)
		(width 0.12954)
		(layer "F.Cu")
		(net "P1V581_PDB_ADC")
	)
	(segment
		(start 38.830758 -104.069642)
		(end 38.922452 -103.977948)
		(width 0.12954)
		(layer "F.Cu")
		(net "P1V581_PDB_ADC")
	)
	(segment
		(start 38.922452 -103.977948)
		(end 40.21455 -103.977948)
		(width 0.12954)
		(layer "F.Cu")
		(net "P1V581_PDB_ADC")
	)
	(segment
		(start 38.830758 -104.856788)
		(end 38.830758 -104.52862)
		(width 0.12954)
		(layer "F.Cu")
		(net "P1V581_PDB_ADC")
	)
	(segment
		(start 40.227504 -105.006902)
		(end 40.21455 -104.993948)
		(width 0.12954)
		(layer "F.Cu")
		(net "P1V581_PDB_ADC")
	)
	(segment
		(start 40.21455 -104.993948)
		(end 38.967918 -104.993948)
		(width 0.12954)
		(layer "F.Cu")
		(net "P1V581_PDB_ADC")
	)
	(via
		(at 38.830758 -104.52862)
		(size 0.762)
		(drill 0.381)
		(layers "F.Cu" "B.Cu")
		(net "P1V581_PDB_ADC")
	)
	(segment
		(start 86.311994 -30.779974)
		(end 86.47176 -30.620208)
		(width 0.12954)
		(layer "F.Cu")
		(net "CLK_50M_NCSI_OCP_V3_2_ISO")
	)
	(segment
		(start 70.261988 -7.636256)
		(end 69.88048 -7.254748)
		(width 0.12954)
		(layer "F.Cu")
		(net "CLK_50M_NCSI_OCP_V3_2_ISO")
	)
	(segment
		(start 86.311994 -31.267908)
		(end 86.311994 -30.779974)
		(width 0.12954)
		(layer "F.Cu")
		(net "CLK_50M_NCSI_OCP_V3_2_ISO")
	)
	(segment
		(start 70.261988 -8.320024)
		(end 70.261988 -7.636256)
		(width 0.12954)
		(layer "F.Cu")
		(net "CLK_50M_NCSI_OCP_V3_2_ISO")
	)
	(via
		(at 69.88048 -7.254748)
		(size 0.508)
		(drill 0.254)
		(layers "F.Cu" "B.Cu")
		(net "CLK_50M_NCSI_OCP_V3_2_ISO")
	)
	(via
		(at 86.47176 -30.620208)
		(size 0.508)
		(drill 0.254)
		(layers "F.Cu" "B.Cu")
		(net "CLK_50M_NCSI_OCP_V3_2_ISO")
	)
	(segment
		(start 85.32876 -29.477208)
		(end 85.32876 -19.317208)
		(width 0.127)
		(layer "In6.Cu")
		(net "CLK_50M_NCSI_OCP_V3_2_ISO")
	)
	(segment
		(start 85.32876 -19.317208)
		(end 82.3849 -16.373348)
		(width 0.127)
		(layer "In6.Cu")
		(net "CLK_50M_NCSI_OCP_V3_2_ISO")
	)
	(segment
		(start 69.88048 -10.988548)
		(end 69.88048 -7.254748)
		(width 0.127)
		(layer "In6.Cu")
		(net "CLK_50M_NCSI_OCP_V3_2_ISO")
	)
	(segment
		(start 69.4563 -11.412728)
		(end 69.88048 -10.988548)
		(width 0.127)
		(layer "In6.Cu")
		(net "CLK_50M_NCSI_OCP_V3_2_ISO")
	)
	(segment
		(start 79.62138 -14.712188)
		(end 70.88632 -14.712188)
		(width 0.127)
		(layer "In6.Cu")
		(net "CLK_50M_NCSI_OCP_V3_2_ISO")
	)
	(segment
		(start 86.47176 -30.620208)
		(end 85.32876 -29.477208)
		(width 0.127)
		(layer "In6.Cu")
		(net "CLK_50M_NCSI_OCP_V3_2_ISO")
	)
	(segment
		(start 70.88632 -14.712188)
		(end 69.4563 -13.282168)
		(width 0.127)
		(layer "In6.Cu")
		(net "CLK_50M_NCSI_OCP_V3_2_ISO")
	)
	(segment
		(start 82.3849 -16.373348)
		(end 81.28254 -16.373348)
		(width 0.127)
		(layer "In6.Cu")
		(net "CLK_50M_NCSI_OCP_V3_2_ISO")
	)
	(segment
		(start 69.4563 -13.282168)
		(end 69.4563 -11.412728)
		(width 0.127)
		(layer "In6.Cu")
		(net "CLK_50M_NCSI_OCP_V3_2_ISO")
	)
	(segment
		(start 81.28254 -16.373348)
		(end 79.62138 -14.712188)
		(width 0.127)
		(layer "In6.Cu")
		(net "CLK_50M_NCSI_OCP_V3_2_ISO")
	)
	(segment
		(start 374.432068 -15.688818)
		(end 374.432068 -16.34617)
		(width 0.12954)
		(layer "F.Cu")
		(net "CLK_50M_NCSI_OCP_SFF_ISO")
	)
	(segment
		(start 444.761874 -6.855714)
		(end 446.35928 -5.258308)
		(width 0.12954)
		(layer "F.Cu")
		(net "CLK_50M_NCSI_OCP_SFF_ISO")
	)
	(segment
		(start 444.761874 -8.320024)
		(end 444.761874 -6.855714)
		(width 0.12954)
		(layer "F.Cu")
		(net "CLK_50M_NCSI_OCP_SFF_ISO")
	)
	(segment
		(start 446.35928 -5.258308)
		(end 446.35928 -4.031488)
		(width 0.12954)
		(layer "F.Cu")
		(net "CLK_50M_NCSI_OCP_SFF_ISO")
	)
	(via
		(at 446.35928 -4.031488)
		(size 0.508)
		(drill 0.254)
		(layers "F.Cu" "B.Cu")
		(net "CLK_50M_NCSI_OCP_SFF_ISO")
	)
	(via
		(at 374.432068 -15.688818)
		(size 0.508)
		(drill 0.254)
		(layers "F.Cu" "B.Cu")
		(net "CLK_50M_NCSI_OCP_SFF_ISO")
	)
	(segment
		(start 437.404764 -4.816348)
		(end 443.71768 -4.816348)
		(width 0.127)
		(layer "In4.Cu")
		(net "CLK_50M_NCSI_OCP_SFF_ISO")
	)
	(segment
		(start 444.8937 -3.640328)
		(end 445.96812 -3.640328)
		(width 0.127)
		(layer "In4.Cu")
		(net "CLK_50M_NCSI_OCP_SFF_ISO")
	)
	(segment
		(start 422.7195 -6.712458)
		(end 422.7195 -6.128258)
		(width 0.127)
		(layer "In4.Cu")
		(net "CLK_50M_NCSI_OCP_SFF_ISO")
	)
	(segment
		(start 445.96812 -3.640328)
		(end 446.35928 -4.031488)
		(width 0.127)
		(layer "In4.Cu")
		(net "CLK_50M_NCSI_OCP_SFF_ISO")
	)
	(segment
		(start 374.432068 -15.688818)
		(end 374.509538 -15.611348)
		(width 0.127)
		(layer "In4.Cu")
		(net "CLK_50M_NCSI_OCP_SFF_ISO")
	)
	(segment
		(start 435.575964 -2.987548)
		(end 437.404764 -4.816348)
		(width 0.127)
		(layer "In4.Cu")
		(net "CLK_50M_NCSI_OCP_SFF_ISO")
	)
	(segment
		(start 374.509538 -15.611348)
		(end 385.29641 -15.611348)
		(width 0.127)
		(layer "In4.Cu")
		(net "CLK_50M_NCSI_OCP_SFF_ISO")
	)
	(segment
		(start 420.98341 -8.448548)
		(end 422.7195 -6.712458)
		(width 0.127)
		(layer "In4.Cu")
		(net "CLK_50M_NCSI_OCP_SFF_ISO")
	)
	(segment
		(start 392.45921 -8.448548)
		(end 420.98341 -8.448548)
		(width 0.127)
		(layer "In4.Cu")
		(net "CLK_50M_NCSI_OCP_SFF_ISO")
	)
	(segment
		(start 385.29641 -15.611348)
		(end 392.45921 -8.448548)
		(width 0.127)
		(layer "In4.Cu")
		(net "CLK_50M_NCSI_OCP_SFF_ISO")
	)
	(segment
		(start 425.86021 -2.987548)
		(end 435.575964 -2.987548)
		(width 0.127)
		(layer "In4.Cu")
		(net "CLK_50M_NCSI_OCP_SFF_ISO")
	)
	(segment
		(start 443.71768 -4.816348)
		(end 444.8937 -3.640328)
		(width 0.127)
		(layer "In4.Cu")
		(net "CLK_50M_NCSI_OCP_SFF_ISO")
	)
	(segment
		(start 422.7195 -6.128258)
		(end 425.86021 -2.987548)
		(width 0.127)
		(layer "In4.Cu")
		(net "CLK_50M_NCSI_OCP_SFF_ISO")
	)
	(segment
		(start 361.061 -415.889948)
		(end 360.934 -416.016948)
		(width 0.12954)
		(layer "F.Cu")
		(net "SWB_HSC_PWRGD_N")
	)
	(segment
		(start 361.075986 -416.539934)
		(end 361.50296 -416.539934)
		(width 0.12954)
		(layer "F.Cu")
		(net "SWB_HSC_PWRGD_N")
	)
	(segment
		(start 362.218986 -416.539934)
		(end 361.50296 -416.539934)
		(width 0.12954)
		(layer "F.Cu")
		(net "SWB_HSC_PWRGD_N")
	)
	(segment
		(start 362.839 -417.159948)
		(end 362.218986 -416.539934)
		(width 0.12954)
		(layer "F.Cu")
		(net "SWB_HSC_PWRGD_N")
	)
	(segment
		(start 362.81995 -415.889948)
		(end 362.839 -415.908998)
		(width 0.12954)
		(layer "F.Cu")
		(net "SWB_HSC_PWRGD_N")
	)
	(segment
		(start 360.934 -416.016948)
		(end 360.934 -416.397948)
		(width 0.12954)
		(layer "F.Cu")
		(net "SWB_HSC_PWRGD_N")
	)
	(segment
		(start 362.839 -415.908998)
		(end 362.839 -417.159948)
		(width 0.12954)
		(layer "F.Cu")
		(net "SWB_HSC_PWRGD_N")
	)
	(segment
		(start 361.50296 -415.889948)
		(end 361.061 -415.889948)
		(width 0.12954)
		(layer "F.Cu")
		(net "SWB_HSC_PWRGD_N")
	)
	(segment
		(start 360.934 -416.397948)
		(end 361.075986 -416.539934)
		(width 0.12954)
		(layer "F.Cu")
		(net "SWB_HSC_PWRGD_N")
	)
	(via
		(at 362.839 -417.159948)
		(size 0.762)
		(drill 0.381)
		(layers "F.Cu" "B.Cu")
		(net "SWB_HSC_PWRGD_N")
	)
	(segment
		(start 184.555638 -118.575328)
		(end 184.955688 -118.975378)
		(width 0.12954)
		(layer "F.Cu")
		(net "SWB_HSC_PWRGD_ISO_R")
	)
	(segment
		(start 356.21595 -413.095948)
		(end 355.6 -413.095948)
		(width 0.12954)
		(layer "F.Cu")
		(net "SWB_HSC_PWRGD_ISO_R")
	)
	(via
		(at 230.57358 -265.491468)
		(size 0.508)
		(drill 0.254)
		(layers "F.Cu" "B.Cu")
		(net "SWB_HSC_PWRGD_ISO_R")
	)
	(via
		(at 355.6 -413.095948)
		(size 0.508)
		(drill 0.254)
		(layers "F.Cu" "B.Cu")
		(net "SWB_HSC_PWRGD_ISO_R")
	)
	(via
		(at 184.955688 -118.975378)
		(size 0.4572)
		(drill 0.254)
		(layers "F.Cu" "B.Cu")
		(net "SWB_HSC_PWRGD_ISO_R")
	)
	(segment
		(start 358.104948 -410.591)
		(end 368.689128 -410.591)
		(width 0.12954)
		(layer "B.Cu")
		(net "SWB_HSC_PWRGD_ISO_R")
	)
	(segment
		(start 359.73004 -396.339568)
		(end 357.03002 -393.639548)
		(width 0.12954)
		(layer "B.Cu")
		(net "SWB_HSC_PWRGD_ISO_R")
	)
	(segment
		(start 270.83004 -357.070914)
		(end 223.11614 -309.357014)
		(width 0.12954)
		(layer "B.Cu")
		(net "SWB_HSC_PWRGD_ISO_R")
	)
	(segment
		(start 270.83004 -372.961408)
		(end 270.83004 -357.070914)
		(width 0.12954)
		(layer "B.Cu")
		(net "SWB_HSC_PWRGD_ISO_R")
	)
	(segment
		(start 281.022044 -383.153412)
		(end 270.83004 -372.961408)
		(width 0.12954)
		(layer "B.Cu")
		(net "SWB_HSC_PWRGD_ISO_R")
	)
	(segment
		(start 368.62512 -398.620488)
		(end 367.20526 -397.200628)
		(width 0.12954)
		(layer "B.Cu")
		(net "SWB_HSC_PWRGD_ISO_R")
	)
	(segment
		(start 360.52506 -396.339568)
		(end 359.73004 -396.339568)
		(width 0.12954)
		(layer "B.Cu")
		(net "SWB_HSC_PWRGD_ISO_R")
	)
	(segment
		(start 357.03002 -393.639548)
		(end 357.03002 -391.742168)
		(width 0.12954)
		(layer "B.Cu")
		(net "SWB_HSC_PWRGD_ISO_R")
	)
	(segment
		(start 223.11614 -272.948908)
		(end 230.57358 -265.491468)
		(width 0.12954)
		(layer "B.Cu")
		(net "SWB_HSC_PWRGD_ISO_R")
	)
	(segment
		(start 368.62512 -403.771608)
		(end 368.62512 -398.620488)
		(width 0.12954)
		(layer "B.Cu")
		(net "SWB_HSC_PWRGD_ISO_R")
	)
	(segment
		(start 369.55476 -404.701248)
		(end 368.62512 -403.771608)
		(width 0.12954)
		(layer "B.Cu")
		(net "SWB_HSC_PWRGD_ISO_R")
	)
	(segment
		(start 361.38612 -397.200628)
		(end 360.52506 -396.339568)
		(width 0.12954)
		(layer "B.Cu")
		(net "SWB_HSC_PWRGD_ISO_R")
	)
	(segment
		(start 369.7224 -404.828248)
		(end 369.5954 -404.701248)
		(width 0.12954)
		(layer "B.Cu")
		(net "SWB_HSC_PWRGD_ISO_R")
	)
	(segment
		(start 223.11614 -309.357014)
		(end 223.11614 -272.948908)
		(width 0.12954)
		(layer "B.Cu")
		(net "SWB_HSC_PWRGD_ISO_R")
	)
	(segment
		(start 367.20526 -397.200628)
		(end 361.38612 -397.200628)
		(width 0.12954)
		(layer "B.Cu")
		(net "SWB_HSC_PWRGD_ISO_R")
	)
	(segment
		(start 355.6 -413.095948)
		(end 358.104948 -410.591)
		(width 0.12954)
		(layer "B.Cu")
		(net "SWB_HSC_PWRGD_ISO_R")
	)
	(segment
		(start 348.441264 -383.153412)
		(end 281.022044 -383.153412)
		(width 0.12954)
		(layer "B.Cu")
		(net "SWB_HSC_PWRGD_ISO_R")
	)
	(segment
		(start 357.03002 -391.742168)
		(end 348.441264 -383.153412)
		(width 0.12954)
		(layer "B.Cu")
		(net "SWB_HSC_PWRGD_ISO_R")
	)
	(segment
		(start 369.5954 -404.701248)
		(end 369.55476 -404.701248)
		(width 0.12954)
		(layer "B.Cu")
		(net "SWB_HSC_PWRGD_ISO_R")
	)
	(segment
		(start 368.689128 -410.591)
		(end 369.7224 -409.557728)
		(width 0.12954)
		(layer "B.Cu")
		(net "SWB_HSC_PWRGD_ISO_R")
	)
	(segment
		(start 369.7224 -409.557728)
		(end 369.7224 -404.828248)
		(width 0.12954)
		(layer "B.Cu")
		(net "SWB_HSC_PWRGD_ISO_R")
	)
	(segment
		(start 185.360818 -119.380508)
		(end 185.930794 -119.380508)
		(width 0.127)
		(layer "In11.Cu")
		(net "SWB_HSC_PWRGD_ISO_R")
	)
	(segment
		(start 194.34048 -190.696088)
		(end 194.65544 -191.011048)
		(width 0.127)
		(layer "In11.Cu")
		(net "SWB_HSC_PWRGD_ISO_R")
	)
	(segment
		(start 216.30386 -192.540128)
		(end 216.30386 -193.413888)
		(width 0.127)
		(layer "In11.Cu")
		(net "SWB_HSC_PWRGD_ISO_R")
	)
	(segment
		(start 186.18708 -119.636794)
		(end 186.18708 -121.544588)
		(width 0.127)
		(layer "In11.Cu")
		(net "SWB_HSC_PWRGD_ISO_R")
	)
	(segment
		(start 214.650828 -190.887096)
		(end 216.30386 -192.540128)
		(width 0.127)
		(layer "In11.Cu")
		(net "SWB_HSC_PWRGD_ISO_R")
	)
	(segment
		(start 216.30386 -193.413888)
		(end 230.35768 -207.467708)
		(width 0.127)
		(layer "In11.Cu")
		(net "SWB_HSC_PWRGD_ISO_R")
	)
	(segment
		(start 184.6707 -134.6327)
		(end 184.6707 -139.362688)
		(width 0.127)
		(layer "In11.Cu")
		(net "SWB_HSC_PWRGD_ISO_R")
	)
	(segment
		(start 182.53456 -141.498828)
		(end 182.53456 -148.910548)
		(width 0.127)
		(layer "In11.Cu")
		(net "SWB_HSC_PWRGD_ISO_R")
	)
	(segment
		(start 187.13196 -190.696088)
		(end 194.34048 -190.696088)
		(width 0.127)
		(layer "In11.Cu")
		(net "SWB_HSC_PWRGD_ISO_R")
	)
	(segment
		(start 182.12562 -149.319488)
		(end 182.12562 -159.301942)
		(width 0.127)
		(layer "In11.Cu")
		(net "SWB_HSC_PWRGD_ISO_R")
	)
	(segment
		(start 184.66816 -131.392168)
		(end 185.98642 -132.710428)
		(width 0.127)
		(layer "In11.Cu")
		(net "SWB_HSC_PWRGD_ISO_R")
	)
	(segment
		(start 184.6707 -139.362688)
		(end 182.53456 -141.498828)
		(width 0.127)
		(layer "In11.Cu")
		(net "SWB_HSC_PWRGD_ISO_R")
	)
	(segment
		(start 182.53456 -148.910548)
		(end 182.12562 -149.319488)
		(width 0.127)
		(layer "In11.Cu")
		(net "SWB_HSC_PWRGD_ISO_R")
	)
	(segment
		(start 186.2074 -188.247528)
		(end 186.2074 -189.771528)
		(width 0.127)
		(layer "In11.Cu")
		(net "SWB_HSC_PWRGD_ISO_R")
	)
	(segment
		(start 208.04886 -191.011048)
		(end 208.172812 -190.887096)
		(width 0.127)
		(layer "In11.Cu")
		(net "SWB_HSC_PWRGD_ISO_R")
	)
	(segment
		(start 185.98642 -132.710428)
		(end 185.98642 -133.31698)
		(width 0.127)
		(layer "In11.Cu")
		(net "SWB_HSC_PWRGD_ISO_R")
	)
	(segment
		(start 184.7977 -186.837828)
		(end 186.2074 -188.247528)
		(width 0.127)
		(layer "In11.Cu")
		(net "SWB_HSC_PWRGD_ISO_R")
	)
	(segment
		(start 186.18708 -121.544588)
		(end 185.77052 -121.961148)
		(width 0.127)
		(layer "In11.Cu")
		(net "SWB_HSC_PWRGD_ISO_R")
	)
	(segment
		(start 230.35768 -207.467708)
		(end 230.35768 -265.275568)
		(width 0.127)
		(layer "In11.Cu")
		(net "SWB_HSC_PWRGD_ISO_R")
	)
	(segment
		(start 182.12562 -159.301942)
		(end 184.7977 -161.974022)
		(width 0.127)
		(layer "In11.Cu")
		(net "SWB_HSC_PWRGD_ISO_R")
	)
	(segment
		(start 184.955688 -118.975378)
		(end 185.360818 -119.380508)
		(width 0.127)
		(layer "In11.Cu")
		(net "SWB_HSC_PWRGD_ISO_R")
	)
	(segment
		(start 186.2074 -189.771528)
		(end 187.13196 -190.696088)
		(width 0.127)
		(layer "In11.Cu")
		(net "SWB_HSC_PWRGD_ISO_R")
	)
	(segment
		(start 184.7977 -161.974022)
		(end 184.7977 -186.837828)
		(width 0.127)
		(layer "In11.Cu")
		(net "SWB_HSC_PWRGD_ISO_R")
	)
	(segment
		(start 230.35768 -265.275568)
		(end 230.57358 -265.491468)
		(width 0.127)
		(layer "In11.Cu")
		(net "SWB_HSC_PWRGD_ISO_R")
	)
	(segment
		(start 185.930794 -119.380508)
		(end 186.18708 -119.636794)
		(width 0.127)
		(layer "In11.Cu")
		(net "SWB_HSC_PWRGD_ISO_R")
	)
	(segment
		(start 208.172812 -190.887096)
		(end 214.650828 -190.887096)
		(width 0.127)
		(layer "In11.Cu")
		(net "SWB_HSC_PWRGD_ISO_R")
	)
	(segment
		(start 185.77052 -121.961148)
		(end 185.77052 -126.159768)
		(width 0.127)
		(layer "In11.Cu")
		(net "SWB_HSC_PWRGD_ISO_R")
	)
	(segment
		(start 194.65544 -191.011048)
		(end 208.04886 -191.011048)
		(width 0.127)
		(layer "In11.Cu")
		(net "SWB_HSC_PWRGD_ISO_R")
	)
	(segment
		(start 185.77052 -126.159768)
		(end 184.66816 -127.262128)
		(width 0.127)
		(layer "In11.Cu")
		(net "SWB_HSC_PWRGD_ISO_R")
	)
	(segment
		(start 185.98642 -133.31698)
		(end 184.6707 -134.6327)
		(width 0.127)
		(layer "In11.Cu")
		(net "SWB_HSC_PWRGD_ISO_R")
	)
	(segment
		(start 184.66816 -127.262128)
		(end 184.66816 -131.392168)
		(width 0.127)
		(layer "In11.Cu")
		(net "SWB_HSC_PWRGD_ISO_R")
	)
	(segment
		(start 358.267 -415.000948)
		(end 358.506014 -415.239962)
		(width 0.12954)
		(layer "F.Cu")
		(net "SWB_HSC_PWRGD_ISO")
	)
	(segment
		(start 358.506014 -415.239962)
		(end 359.60304 -415.239962)
		(width 0.12954)
		(layer "F.Cu")
		(net "SWB_HSC_PWRGD_ISO")
	)
	(segment
		(start 357.01605 -415.127948)
		(end 357.01605 -414.111948)
		(width 0.12954)
		(layer "F.Cu")
		(net "SWB_HSC_PWRGD_ISO")
	)
	(segment
		(start 358.267 -415.000948)
		(end 358.14 -415.127948)
		(width 0.12954)
		(layer "F.Cu")
		(net "SWB_HSC_PWRGD_ISO")
	)
	(segment
		(start 358.14 -415.127948)
		(end 357.01605 -415.127948)
		(width 0.12954)
		(layer "F.Cu")
		(net "SWB_HSC_PWRGD_ISO")
	)
	(segment
		(start 357.01605 -413.095948)
		(end 357.01605 -414.111948)
		(width 0.12954)
		(layer "F.Cu")
		(net "SWB_HSC_PWRGD_ISO")
	)
	(via
		(at 358.267 -415.000948)
		(size 0.762)
		(drill 0.381)
		(layers "F.Cu" "B.Cu")
		(net "SWB_HSC_PWRGD_ISO")
	)
	(segment
		(start 357.01605 -416.143948)
		(end 358.14 -416.143948)
		(width 0.12954)
		(layer "F.Cu")
		(net "SWB_HSC_PWRGD")
	)
	(segment
		(start 357.01605 -417.159948)
		(end 357.01605 -416.143948)
		(width 0.12954)
		(layer "F.Cu")
		(net "SWB_HSC_PWRGD")
	)
	(segment
		(start 359.60304 -415.889948)
		(end 358.648 -415.889948)
		(width 0.12954)
		(layer "F.Cu")
		(net "SWB_HSC_PWRGD")
	)
	(segment
		(start 358.14 -416.143948)
		(end 358.267 -416.270948)
		(width 0.12954)
		(layer "F.Cu")
		(net "SWB_HSC_PWRGD")
	)
	(segment
		(start 358.648 -415.889948)
		(end 358.267 -416.270948)
		(width 0.12954)
		(layer "F.Cu")
		(net "SWB_HSC_PWRGD")
	)
	(via
		(at 358.267 -416.270948)
		(size 0.508)
		(drill 0.254)
		(layers "F.Cu" "B.Cu")
		(net "SWB_HSC_PWRGD")
	)
	(segment
		(start 359.1433 -415.394648)
		(end 359.1433 -411.206188)
		(width 0.127)
		(layer "In2.Cu")
		(net "SWB_HSC_PWRGD")
	)
	(segment
		(start 353.89312 -410.794708)
		(end 342.85428 -421.833548)
		(width 0.127)
		(layer "In2.Cu")
		(net "SWB_HSC_PWRGD")
	)
	(segment
		(start 342.85428 -421.833548)
		(end 342.85428 -439.694066)
		(width 0.127)
		(layer "In2.Cu")
		(net "SWB_HSC_PWRGD")
	)
	(segment
		(start 359.1433 -411.206188)
		(end 358.73182 -410.794708)
		(width 0.127)
		(layer "In2.Cu")
		(net "SWB_HSC_PWRGD")
	)
	(segment
		(start 358.267 -416.270948)
		(end 359.1433 -415.394648)
		(width 0.127)
		(layer "In2.Cu")
		(net "SWB_HSC_PWRGD")
	)
	(segment
		(start 342.85428 -439.694066)
		(end 343.650062 -440.489848)
		(width 0.127)
		(layer "In2.Cu")
		(net "SWB_HSC_PWRGD")
	)
	(segment
		(start 358.73182 -410.794708)
		(end 353.89312 -410.794708)
		(width 0.127)
		(layer "In2.Cu")
		(net "SWB_HSC_PWRGD")
	)
	(segment
		(start 326.31507 -52.952396)
		(end 326.584818 -52.952396)
		(width 0.0889)
		(layer "F.Cu")
		(net "PD_GPP_I_14")
	)
	(segment
		(start 324.377304 -52.894992)
		(end 326.257666 -52.894992)
		(width 0.0889)
		(layer "F.Cu")
		(net "PD_GPP_I_14")
	)
	(segment
		(start 324.034658 -53.237638)
		(end 324.377304 -52.894992)
		(width 0.0889)
		(layer "F.Cu")
		(net "PD_GPP_I_14")
	)
	(segment
		(start 314.43549 -62.060328)
		(end 315.087 -62.060328)
		(width 0.12954)
		(layer "F.Cu")
		(net "PD_GPP_I_14")
	)
	(segment
		(start 326.257666 -52.894992)
		(end 326.31507 -52.952396)
		(width 0.0889)
		(layer "F.Cu")
		(net "PD_GPP_I_14")
	)
	(via
		(at 324.034658 -53.237638)
		(size 0.508)
		(drill 0.254)
		(layers "F.Cu" "B.Cu")
		(net "PD_GPP_I_14")
	)
	(via
		(at 315.087 -62.060328)
		(size 0.508)
		(drill 0.254)
		(layers "F.Cu" "B.Cu")
		(net "PD_GPP_I_14")
	)
	(segment
		(start 324.034658 -53.237638)
		(end 323.459348 -53.812948)
		(width 0.127)
		(layer "In6.Cu")
		(net "PD_GPP_I_14")
	)
	(segment
		(start 323.459348 -53.812948)
		(end 322.86448 -53.812948)
		(width 0.127)
		(layer "In6.Cu")
		(net "PD_GPP_I_14")
	)
	(segment
		(start 319.76568 -57.445148)
		(end 319.76568 -62.060328)
		(width 0.127)
		(layer "In6.Cu")
		(net "PD_GPP_I_14")
	)
	(segment
		(start 318.94526 -62.311788)
		(end 318.6938 -62.060328)
		(width 0.127)
		(layer "In6.Cu")
		(net "PD_GPP_I_14")
	)
	(segment
		(start 319.51422 -62.311788)
		(end 318.94526 -62.311788)
		(width 0.127)
		(layer "In6.Cu")
		(net "PD_GPP_I_14")
	)
	(segment
		(start 322.86448 -53.812948)
		(end 322.12788 -54.549548)
		(width 0.127)
		(layer "In6.Cu")
		(net "PD_GPP_I_14")
	)
	(segment
		(start 319.76568 -62.060328)
		(end 319.51422 -62.311788)
		(width 0.127)
		(layer "In6.Cu")
		(net "PD_GPP_I_14")
	)
	(segment
		(start 322.12788 -55.082948)
		(end 319.76568 -57.445148)
		(width 0.127)
		(layer "In6.Cu")
		(net "PD_GPP_I_14")
	)
	(segment
		(start 322.12788 -54.549548)
		(end 322.12788 -55.082948)
		(width 0.127)
		(layer "In6.Cu")
		(net "PD_GPP_I_14")
	)
	(segment
		(start 318.6938 -62.060328)
		(end 315.087 -62.060328)
		(width 0.127)
		(layer "In6.Cu")
		(net "PD_GPP_I_14")
	)
	(segment
		(start 326.082152 -53.452522)
		(end 326.999854 -53.452522)
		(width 0.0889)
		(layer "F.Cu")
		(net "PD_GPP_I_13")
	)
	(segment
		(start 323.365622 -54.346348)
		(end 323.857112 -54.346348)
		(width 0.0889)
		(layer "F.Cu")
		(net "PD_GPP_I_13")
	)
	(segment
		(start 314.43549 -63.076328)
		(end 315.087 -63.076328)
		(width 0.12954)
		(layer "F.Cu")
		(net "PD_GPP_I_13")
	)
	(segment
		(start 323.857112 -54.346348)
		(end 324.793356 -53.402992)
		(width 0.0889)
		(layer "F.Cu")
		(net "PD_GPP_I_13")
	)
	(segment
		(start 324.793356 -53.402992)
		(end 326.032622 -53.402992)
		(width 0.0889)
		(layer "F.Cu")
		(net "PD_GPP_I_13")
	)
	(segment
		(start 326.032622 -53.402992)
		(end 326.082152 -53.452522)
		(width 0.0889)
		(layer "F.Cu")
		(net "PD_GPP_I_13")
	)
	(via
		(at 315.087 -63.076328)
		(size 0.508)
		(drill 0.254)
		(layers "F.Cu" "B.Cu")
		(net "PD_GPP_I_13")
	)
	(via
		(at 323.365622 -54.346348)
		(size 0.508)
		(drill 0.254)
		(layers "F.Cu" "B.Cu")
		(net "PD_GPP_I_13")
	)
	(segment
		(start 317.3349 -62.677548)
		(end 315.48578 -62.677548)
		(width 0.127)
		(layer "In6.Cu")
		(net "PD_GPP_I_13")
	)
	(segment
		(start 315.48578 -62.677548)
		(end 315.087 -63.076328)
		(width 0.127)
		(layer "In6.Cu")
		(net "PD_GPP_I_13")
	)
	(segment
		(start 318.17564 -63.518288)
		(end 317.3349 -62.677548)
		(width 0.127)
		(layer "In6.Cu")
		(net "PD_GPP_I_13")
	)
	(segment
		(start 323.365622 -54.346348)
		(end 323.619114 -54.59984)
		(width 0.127)
		(layer "In6.Cu")
		(net "PD_GPP_I_13")
	)
	(segment
		(start 320.09588 -60.924948)
		(end 320.09588 -63.017908)
		(width 0.127)
		(layer "In6.Cu")
		(net "PD_GPP_I_13")
	)
	(segment
		(start 319.5955 -63.518288)
		(end 318.17564 -63.518288)
		(width 0.127)
		(layer "In6.Cu")
		(net "PD_GPP_I_13")
	)
	(segment
		(start 323.619114 -54.59984)
		(end 323.619114 -57.401714)
		(width 0.127)
		(layer "In6.Cu")
		(net "PD_GPP_I_13")
	)
	(segment
		(start 320.09588 -63.017908)
		(end 319.5955 -63.518288)
		(width 0.127)
		(layer "In6.Cu")
		(net "PD_GPP_I_13")
	)
	(segment
		(start 323.619114 -57.401714)
		(end 320.09588 -60.924948)
		(width 0.127)
		(layer "In6.Cu")
		(net "PD_GPP_I_13")
	)
	(segment
		(start 172.69714 -407.58872)
		(end 172.69714 -408.99334)
		(width 0.12954)
		(layer "F.Cu")
		(net "HGX_DETECT_N_R")
	)
	(segment
		(start 160.31972 -416.740848)
		(end 124.71654 -416.740848)
		(width 0.12954)
		(layer "F.Cu")
		(net "HGX_DETECT_N_R")
	)
	(segment
		(start 172.69714 -408.99334)
		(end 168.54424 -413.14624)
		(width 0.12954)
		(layer "F.Cu")
		(net "HGX_DETECT_N_R")
	)
	(segment
		(start 168.54424 -413.14624)
		(end 163.914328 -413.14624)
		(width 0.12954)
		(layer "F.Cu")
		(net "HGX_DETECT_N_R")
	)
	(segment
		(start 124.71654 -416.740848)
		(end 124.37364 -416.397948)
		(width 0.12954)
		(layer "F.Cu")
		(net "HGX_DETECT_N_R")
	)
	(segment
		(start 188.08446 -120.175528)
		(end 186.955684 -120.175528)
		(width 0.12954)
		(layer "F.Cu")
		(net "HGX_DETECT_N_R")
	)
	(segment
		(start 119.37238 -416.728148)
		(end 119.27332 -416.629088)
		(width 0.12954)
		(layer "F.Cu")
		(net "HGX_DETECT_N_R")
	)
	(segment
		(start 123.26874 -416.397948)
		(end 122.93854 -416.728148)
		(width 0.12954)
		(layer "F.Cu")
		(net "HGX_DETECT_N_R")
	)
	(segment
		(start 163.914328 -413.14624)
		(end 160.31972 -416.740848)
		(width 0.12954)
		(layer "F.Cu")
		(net "HGX_DETECT_N_R")
	)
	(segment
		(start 188.14796 -120.239028)
		(end 188.08446 -120.175528)
		(width 0.12954)
		(layer "F.Cu")
		(net "HGX_DETECT_N_R")
	)
	(segment
		(start 122.93854 -416.728148)
		(end 119.37238 -416.728148)
		(width 0.12954)
		(layer "F.Cu")
		(net "HGX_DETECT_N_R")
	)
	(segment
		(start 188.14796 -120.350788)
		(end 188.14796 -120.239028)
		(width 0.12954)
		(layer "F.Cu")
		(net "HGX_DETECT_N_R")
	)
	(segment
		(start 172.53458 -407.42616)
		(end 172.69714 -407.58872)
		(width 0.12954)
		(layer "F.Cu")
		(net "HGX_DETECT_N_R")
	)
	(segment
		(start 124.37364 -416.397948)
		(end 123.26874 -416.397948)
		(width 0.12954)
		(layer "F.Cu")
		(net "HGX_DETECT_N_R")
	)
	(via
		(at 119.27332 -416.629088)
		(size 0.508)
		(drill 0.254)
		(layers "F.Cu" "B.Cu")
		(net "HGX_DETECT_N_R")
	)
	(via
		(at 188.14796 -120.350788)
		(size 0.508)
		(drill 0.254)
		(layers "F.Cu" "B.Cu")
		(net "HGX_DETECT_N_R")
	)
	(via
		(at 200.98004 -352.720148)
		(size 0.508)
		(drill 0.254)
		(layers "F.Cu" "B.Cu")
		(net "HGX_DETECT_N_R")
	)
	(via
		(at 211.61248 -188.821568)
		(size 0.508)
		(drill 0.254)
		(layers "F.Cu" "B.Cu")
		(net "HGX_DETECT_N_R")
	)
	(via
		(at 172.53458 -407.42616)
		(size 0.508)
		(drill 0.254)
		(layers "F.Cu" "B.Cu")
		(net "HGX_DETECT_N_R")
	)
	(via
		(at 203.00442 -123.424188)
		(size 0.508)
		(drill 0.254)
		(layers "F.Cu" "B.Cu")
		(net "HGX_DETECT_N_R")
	)
	(segment
		(start 219.62618 -192.052448)
		(end 220.2942 -192.720468)
		(width 0.12954)
		(layer "B.Cu")
		(net "HGX_DETECT_N_R")
	)
	(segment
		(start 212.20684 -190.355728)
		(end 214.82558 -190.355728)
		(width 0.12954)
		(layer "B.Cu")
		(net "HGX_DETECT_N_R")
	)
	(segment
		(start 228.854 -238.219488)
		(end 220.26118 -246.812308)
		(width 0.12954)
		(layer "B.Cu")
		(net "HGX_DETECT_N_R")
	)
	(segment
		(start 220.26118 -246.812308)
		(end 220.26118 -332.534768)
		(width 0.12954)
		(layer "B.Cu")
		(net "HGX_DETECT_N_R")
	)
	(segment
		(start 108.19892 -420.434008)
		(end 115.4684 -420.434008)
		(width 0.12954)
		(layer "B.Cu")
		(net "HGX_DETECT_N_R")
	)
	(segment
		(start 200.98004 -342.501728)
		(end 200.98004 -352.720148)
		(width 0.12954)
		(layer "B.Cu")
		(net "HGX_DETECT_N_R")
	)
	(segment
		(start 101.86543 -422.546018)
		(end 102.11308 -422.298368)
		(width 0.12954)
		(layer "B.Cu")
		(net "HGX_DETECT_N_R")
	)
	(segment
		(start 102.11308 -422.298368)
		(end 106.33456 -422.298368)
		(width 0.12954)
		(layer "B.Cu")
		(net "HGX_DETECT_N_R")
	)
	(segment
		(start 214.82558 -190.355728)
		(end 216.5223 -192.052448)
		(width 0.12954)
		(layer "B.Cu")
		(net "HGX_DETECT_N_R")
	)
	(segment
		(start 218.23934 -334.556608)
		(end 208.92516 -334.556608)
		(width 0.12954)
		(layer "B.Cu")
		(net "HGX_DETECT_N_R")
	)
	(segment
		(start 99.53752 -422.546018)
		(end 101.86543 -422.546018)
		(width 0.12954)
		(layer "B.Cu")
		(net "HGX_DETECT_N_R")
	)
	(segment
		(start 220.2942 -192.720468)
		(end 220.2942 -195.862448)
		(width 0.12954)
		(layer "B.Cu")
		(net "HGX_DETECT_N_R")
	)
	(segment
		(start 220.26118 -332.534768)
		(end 218.23934 -334.556608)
		(width 0.12954)
		(layer "B.Cu")
		(net "HGX_DETECT_N_R")
	)
	(segment
		(start 208.92516 -334.556608)
		(end 200.98004 -342.501728)
		(width 0.12954)
		(layer "B.Cu")
		(net "HGX_DETECT_N_R")
	)
	(segment
		(start 106.33456 -422.298368)
		(end 108.19892 -420.434008)
		(width 0.12954)
		(layer "B.Cu")
		(net "HGX_DETECT_N_R")
	)
	(segment
		(start 220.2942 -195.862448)
		(end 228.854 -204.422248)
		(width 0.12954)
		(layer "B.Cu")
		(net "HGX_DETECT_N_R")
	)
	(segment
		(start 115.4684 -420.434008)
		(end 119.27332 -416.629088)
		(width 0.12954)
		(layer "B.Cu")
		(net "HGX_DETECT_N_R")
	)
	(segment
		(start 211.61248 -189.761368)
		(end 212.20684 -190.355728)
		(width 0.12954)
		(layer "B.Cu")
		(net "HGX_DETECT_N_R")
	)
	(segment
		(start 228.854 -204.422248)
		(end 228.854 -238.219488)
		(width 0.12954)
		(layer "B.Cu")
		(net "HGX_DETECT_N_R")
	)
	(segment
		(start 211.61248 -188.821568)
		(end 211.61248 -189.761368)
		(width 0.12954)
		(layer "B.Cu")
		(net "HGX_DETECT_N_R")
	)
	(segment
		(start 216.5223 -192.052448)
		(end 219.62618 -192.052448)
		(width 0.12954)
		(layer "B.Cu")
		(net "HGX_DETECT_N_R")
	)
	(segment
		(start 216.2683 -146.8501)
		(end 216.2683 -160.368488)
		(width 0.127)
		(layer "In2.Cu")
		(net "HGX_DETECT_N_R")
	)
	(segment
		(start 203.00442 -128.842008)
		(end 204.67828 -130.515868)
		(width 0.127)
		(layer "In2.Cu")
		(net "HGX_DETECT_N_R")
	)
	(segment
		(start 215.09482 -185.339228)
		(end 211.61248 -188.821568)
		(width 0.127)
		(layer "In2.Cu")
		(net "HGX_DETECT_N_R")
	)
	(segment
		(start 204.67828 -135.26008)
		(end 216.2683 -146.8501)
		(width 0.127)
		(layer "In2.Cu")
		(net "HGX_DETECT_N_R")
	)
	(segment
		(start 203.00442 -123.424188)
		(end 203.00442 -128.842008)
		(width 0.127)
		(layer "In2.Cu")
		(net "HGX_DETECT_N_R")
	)
	(segment
		(start 215.09482 -161.541968)
		(end 215.09482 -185.339228)
		(width 0.127)
		(layer "In2.Cu")
		(net "HGX_DETECT_N_R")
	)
	(segment
		(start 216.2683 -160.368488)
		(end 215.09482 -161.541968)
		(width 0.127)
		(layer "In2.Cu")
		(net "HGX_DETECT_N_R")
	)
	(segment
		(start 204.67828 -130.515868)
		(end 204.67828 -135.26008)
		(width 0.127)
		(layer "In2.Cu")
		(net "HGX_DETECT_N_R")
	)
	(segment
		(start 195.113148 -121.798588)
		(end 201.89444 -121.798588)
		(width 0.127)
		(layer "In4.Cu")
		(net "HGX_DETECT_N_R")
	)
	(segment
		(start 188.14796 -120.350788)
		(end 189.09538 -121.298208)
		(width 0.127)
		(layer "In4.Cu")
		(net "HGX_DETECT_N_R")
	)
	(segment
		(start 200.98004 -357.1875)
		(end 200.98004 -352.720148)
		(width 0.127)
		(layer "In4.Cu")
		(net "HGX_DETECT_N_R")
	)
	(segment
		(start 173.87316 -386.06222)
		(end 183.06034 -376.87504)
		(width 0.127)
		(layer "In4.Cu")
		(net "HGX_DETECT_N_R")
	)
	(segment
		(start 170.3578 -396.97914)
		(end 173.87316 -393.46378)
		(width 0.127)
		(layer "In4.Cu")
		(net "HGX_DETECT_N_R")
	)
	(segment
		(start 173.87316 -393.46378)
		(end 173.87316 -386.06222)
		(width 0.127)
		(layer "In4.Cu")
		(net "HGX_DETECT_N_R")
	)
	(segment
		(start 194.612768 -121.298208)
		(end 195.113148 -121.798588)
		(width 0.127)
		(layer "In4.Cu")
		(net "HGX_DETECT_N_R")
	)
	(segment
		(start 189.09538 -121.298208)
		(end 194.612768 -121.298208)
		(width 0.127)
		(layer "In4.Cu")
		(net "HGX_DETECT_N_R")
	)
	(segment
		(start 170.3578 -405.24938)
		(end 170.3578 -396.97914)
		(width 0.127)
		(layer "In4.Cu")
		(net "HGX_DETECT_N_R")
	)
	(segment
		(start 196.68998 -369.52936)
		(end 196.68998 -361.47756)
		(width 0.127)
		(layer "In4.Cu")
		(net "HGX_DETECT_N_R")
	)
	(segment
		(start 201.89444 -121.798588)
		(end 203.00442 -122.908568)
		(width 0.127)
		(layer "In4.Cu")
		(net "HGX_DETECT_N_R")
	)
	(segment
		(start 196.68998 -361.47756)
		(end 200.98004 -357.1875)
		(width 0.127)
		(layer "In4.Cu")
		(net "HGX_DETECT_N_R")
	)
	(segment
		(start 203.00442 -122.908568)
		(end 203.00442 -123.424188)
		(width 0.127)
		(layer "In4.Cu")
		(net "HGX_DETECT_N_R")
	)
	(segment
		(start 189.3443 -376.87504)
		(end 196.68998 -369.52936)
		(width 0.127)
		(layer "In4.Cu")
		(net "HGX_DETECT_N_R")
	)
	(segment
		(start 172.53458 -407.42616)
		(end 170.3578 -405.24938)
		(width 0.127)
		(layer "In4.Cu")
		(net "HGX_DETECT_N_R")
	)
	(segment
		(start 183.06034 -376.87504)
		(end 189.3443 -376.87504)
		(width 0.127)
		(layer "In4.Cu")
		(net "HGX_DETECT_N_R")
	)
	(segment
		(start 94.943168 -426.2374)
		(end 93.599 -426.2374)
		(width 0.12954)
		(layer "F.Cu")
		(net "HGX_DETECT_N_ISO")
	)
	(segment
		(start 55.626 -412.9786)
		(end 54.294532 -414.310068)
		(width 0.12954)
		(layer "F.Cu")
		(net "HGX_DETECT_N_ISO")
	)
	(segment
		(start 97.08388 -406.73528)
		(end 97.9678 -407.6192)
		(width 0.12954)
		(layer "F.Cu")
		(net "HGX_DETECT_N_ISO")
	)
	(segment
		(start 88.83396 -417.58616)
		(end 77.625702 -417.58616)
		(width 0.12954)
		(layer "F.Cu")
		(net "HGX_DETECT_N_ISO")
	)
	(segment
		(start 73.017888 -412.9786)
		(end 55.626 -412.9786)
		(width 0.12954)
		(layer "F.Cu")
		(net "HGX_DETECT_N_ISO")
	)
	(segment
		(start 92.0242 -424.6626)
		(end 92.0242 -420.7764)
		(width 0.12954)
		(layer "F.Cu")
		(net "HGX_DETECT_N_ISO")
	)
	(segment
		(start 92.0242 -420.7764)
		(end 88.83396 -417.58616)
		(width 0.12954)
		(layer "F.Cu")
		(net "HGX_DETECT_N_ISO")
	)
	(segment
		(start 73.091548 -413.05226)
		(end 73.017888 -412.9786)
		(width 0.12954)
		(layer "F.Cu")
		(net "HGX_DETECT_N_ISO")
	)
	(segment
		(start 44.905422 -401.167346)
		(end 44.026074 -401.167346)
		(width 0.12954)
		(layer "F.Cu")
		(net "HGX_DETECT_N_ISO")
	)
	(segment
		(start 73.091802 -413.05226)
		(end 73.091548 -413.05226)
		(width 0.12954)
		(layer "F.Cu")
		(net "HGX_DETECT_N_ISO")
	)
	(segment
		(start 97.9678 -407.6192)
		(end 97.9678 -408.7876)
		(width 0.12954)
		(layer "F.Cu")
		(net "HGX_DETECT_N_ISO")
	)
	(segment
		(start 97.9678 -410.464)
		(end 95.163132 -413.268668)
		(width 0.12954)
		(layer "F.Cu")
		(net "HGX_DETECT_N_ISO")
	)
	(segment
		(start 77.625702 -417.58616)
		(end 73.091802 -413.05226)
		(width 0.12954)
		(layer "F.Cu")
		(net "HGX_DETECT_N_ISO")
	)
	(segment
		(start 95.35922 -425.821348)
		(end 94.943168 -426.2374)
		(width 0.12954)
		(layer "F.Cu")
		(net "HGX_DETECT_N_ISO")
	)
	(segment
		(start 95.163132 -413.268668)
		(end 94.856046 -413.268668)
		(width 0.12954)
		(layer "F.Cu")
		(net "HGX_DETECT_N_ISO")
	)
	(segment
		(start 97.9678 -408.7876)
		(end 97.9678 -410.464)
		(width 0.12954)
		(layer "F.Cu")
		(net "HGX_DETECT_N_ISO")
	)
	(segment
		(start 97.08388 -404.33498)
		(end 97.08388 -406.73528)
		(width 0.12954)
		(layer "F.Cu")
		(net "HGX_DETECT_N_ISO")
	)
	(segment
		(start 54.294532 -414.310068)
		(end 53.29428 -414.310068)
		(width 0.12954)
		(layer "F.Cu")
		(net "HGX_DETECT_N_ISO")
	)
	(segment
		(start 93.599 -426.2374)
		(end 92.0242 -424.6626)
		(width 0.12954)
		(layer "F.Cu")
		(net "HGX_DETECT_N_ISO")
	)
	(via
		(at 53.29428 -414.310068)
		(size 0.508)
		(drill 0.254)
		(layers "F.Cu" "B.Cu")
		(net "HGX_DETECT_N_ISO")
	)
	(via
		(at 95.35922 -425.821348)
		(size 0.508)
		(drill 0.254)
		(layers "F.Cu" "B.Cu")
		(net "HGX_DETECT_N_ISO")
	)
	(via
		(at 44.026074 -401.167346)
		(size 0.508)
		(drill 0.254)
		(layers "F.Cu" "B.Cu")
		(net "HGX_DETECT_N_ISO")
	)
	(via
		(at 97.9678 -408.7876)
		(size 0.762)
		(drill 0.381)
		(layers "F.Cu" "B.Cu")
		(net "HGX_DETECT_N_ISO")
	)
	(via
		(at 97.08388 -404.33498)
		(size 0.508)
		(drill 0.254)
		(layers "F.Cu" "B.Cu")
		(net "HGX_DETECT_N_ISO")
	)
	(segment
		(start 61.8236 -440.002168)
		(end 61.8236 -416.611308)
		(width 0.12954)
		(layer "B.Cu")
		(net "HGX_DETECT_N_ISO")
	)
	(segment
		(start 97.48266 -421.756078)
		(end 97.46996 -421.743378)
		(width 0.12954)
		(layer "B.Cu")
		(net "HGX_DETECT_N_ISO")
	)
	(segment
		(start 96.56064 -423.344848)
		(end 96.56064 -422.478708)
		(width 0.12954)
		(layer "B.Cu")
		(net "HGX_DETECT_N_ISO")
	)
	(segment
		(start 95.35922 -425.821348)
		(end 95.35922 -424.546268)
		(width 0.12954)
		(layer "B.Cu")
		(net "HGX_DETECT_N_ISO")
	)
	(segment
		(start 62.31128 -440.489848)
		(end 61.8236 -440.002168)
		(width 0.12954)
		(layer "B.Cu")
		(net "HGX_DETECT_N_ISO")
	)
	(segment
		(start 98.50374 -421.756078)
		(end 97.48266 -421.756078)
		(width 0.12954)
		(layer "B.Cu")
		(net "HGX_DETECT_N_ISO")
	)
	(segment
		(start 59.52236 -414.310068)
		(end 53.29428 -414.310068)
		(width 0.12954)
		(layer "B.Cu")
		(net "HGX_DETECT_N_ISO")
	)
	(segment
		(start 95.35922 -424.546268)
		(end 96.56064 -423.344848)
		(width 0.12954)
		(layer "B.Cu")
		(net "HGX_DETECT_N_ISO")
	)
	(segment
		(start 61.8236 -416.611308)
		(end 59.52236 -414.310068)
		(width 0.12954)
		(layer "B.Cu")
		(net "HGX_DETECT_N_ISO")
	)
	(segment
		(start 62.650116 -440.489848)
		(end 62.31128 -440.489848)
		(width 0.12954)
		(layer "B.Cu")
		(net "HGX_DETECT_N_ISO")
	)
	(segment
		(start 96.56064 -422.478708)
		(end 97.29597 -421.743378)
		(width 0.12954)
		(layer "B.Cu")
		(net "HGX_DETECT_N_ISO")
	)
	(segment
		(start 97.29597 -421.743378)
		(end 97.46996 -421.743378)
		(width 0.12954)
		(layer "B.Cu")
		(net "HGX_DETECT_N_ISO")
	)
	(segment
		(start 96.8756 -416.540188)
		(end 97.45472 -417.119308)
		(width 0.127)
		(layer "In13.Cu")
		(net "HGX_DETECT_N_ISO")
	)
	(segment
		(start 96.8756 -413.454088)
		(end 96.8756 -416.540188)
		(width 0.127)
		(layer "In13.Cu")
		(net "HGX_DETECT_N_ISO")
	)
	(segment
		(start 97.45472 -417.119308)
		(end 97.45472 -421.820848)
		(width 0.127)
		(layer "In13.Cu")
		(net "HGX_DETECT_N_ISO")
	)
	(segment
		(start 97.08388 -405.87168)
		(end 98.14052 -406.92832)
		(width 0.127)
		(layer "In13.Cu")
		(net "HGX_DETECT_N_ISO")
	)
	(segment
		(start 95.35922 -423.916348)
		(end 95.35922 -425.821348)
		(width 0.127)
		(layer "In13.Cu")
		(net "HGX_DETECT_N_ISO")
	)
	(segment
		(start 97.45472 -421.820848)
		(end 95.35922 -423.916348)
		(width 0.127)
		(layer "In13.Cu")
		(net "HGX_DETECT_N_ISO")
	)
	(segment
		(start 97.08388 -404.33498)
		(end 97.08388 -405.87168)
		(width 0.127)
		(layer "In13.Cu")
		(net "HGX_DETECT_N_ISO")
	)
	(segment
		(start 98.14052 -412.189168)
		(end 96.8756 -413.454088)
		(width 0.127)
		(layer "In13.Cu")
		(net "HGX_DETECT_N_ISO")
	)
	(segment
		(start 98.14052 -406.92832)
		(end 98.14052 -412.189168)
		(width 0.127)
		(layer "In13.Cu")
		(net "HGX_DETECT_N_ISO")
	)
	(segment
		(start 72.43318 -405.077168)
		(end 72.82942 -405.473408)
		(width 0.127)
		(layer "In15.Cu")
		(net "HGX_DETECT_N_ISO")
	)
	(segment
		(start 97.08388 -404.54326)
		(end 97.08388 -404.33498)
		(width 0.127)
		(layer "In15.Cu")
		(net "HGX_DETECT_N_ISO")
	)
	(segment
		(start 45.747178 -401.167346)
		(end 46.54296 -401.963128)
		(width 0.127)
		(layer "In15.Cu")
		(net "HGX_DETECT_N_ISO")
	)
	(segment
		(start 96.153732 -405.473408)
		(end 97.08388 -404.54326)
		(width 0.127)
		(layer "In15.Cu")
		(net "HGX_DETECT_N_ISO")
	)
	(segment
		(start 44.026074 -401.167346)
		(end 45.747178 -401.167346)
		(width 0.127)
		(layer "In15.Cu")
		(net "HGX_DETECT_N_ISO")
	)
	(segment
		(start 46.54296 -404.589488)
		(end 47.03064 -405.077168)
		(width 0.127)
		(layer "In15.Cu")
		(net "HGX_DETECT_N_ISO")
	)
	(segment
		(start 72.82942 -405.473408)
		(end 96.153732 -405.473408)
		(width 0.127)
		(layer "In15.Cu")
		(net "HGX_DETECT_N_ISO")
	)
	(segment
		(start 47.03064 -405.077168)
		(end 72.43318 -405.077168)
		(width 0.127)
		(layer "In15.Cu")
		(net "HGX_DETECT_N_ISO")
	)
	(segment
		(start 46.54296 -401.963128)
		(end 46.54296 -404.589488)
		(width 0.127)
		(layer "In15.Cu")
		(net "HGX_DETECT_N_ISO")
	)
	(segment
		(start 97.73285 -413.273748)
		(end 97.73285 -412.173928)
		(width 0.12954)
		(layer "F.Cu")
		(net "HGX_DETECT_N")
	)
	(segment
		(start 99.74834 -410.45638)
		(end 98.81616 -410.45638)
		(width 0.12954)
		(layer "F.Cu")
		(net "HGX_DETECT_N")
	)
	(segment
		(start 97.73285 -412.173928)
		(end 97.73031 -412.171388)
		(width 0.12954)
		(layer "F.Cu")
		(net "HGX_DETECT_N")
	)
	(segment
		(start 100.16744 -410.56052)
		(end 99.85248 -410.56052)
		(width 0.12954)
		(layer "F.Cu")
		(net "HGX_DETECT_N")
	)
	(segment
		(start 98.81616 -410.45638)
		(end 97.73031 -411.54223)
		(width 0.12954)
		(layer "F.Cu")
		(net "HGX_DETECT_N")
	)
	(segment
		(start 97.73031 -411.54223)
		(end 97.73031 -412.171388)
		(width 0.12954)
		(layer "F.Cu")
		(net "HGX_DETECT_N")
	)
	(segment
		(start 94.20606 -413.479488)
		(end 94.48546 -413.758888)
		(width 0.12954)
		(layer "F.Cu")
		(net "HGX_DETECT_N")
	)
	(segment
		(start 94.48546 -413.758888)
		(end 97.24771 -413.758888)
		(width 0.12954)
		(layer "F.Cu")
		(net "HGX_DETECT_N")
	)
	(segment
		(start 97.24771 -413.758888)
		(end 97.73285 -413.273748)
		(width 0.12954)
		(layer "F.Cu")
		(net "HGX_DETECT_N")
	)
	(segment
		(start 99.85248 -410.56052)
		(end 99.74834 -410.45638)
		(width 0.12954)
		(layer "F.Cu")
		(net "HGX_DETECT_N")
	)
	(segment
		(start 94.20606 -413.268668)
		(end 94.20606 -413.479488)
		(width 0.12954)
		(layer "F.Cu")
		(net "HGX_DETECT_N")
	)
	(via
		(at 100.16744 -410.56052)
		(size 0.508)
		(drill 0.254)
		(layers "F.Cu" "B.Cu")
		(net "HGX_DETECT_N")
	)
	(segment
		(start 100.37318 -416.72256)
		(end 100.37318 -421.2971)
		(width 0.12954)
		(layer "B.Cu")
		(net "HGX_DETECT_N")
	)
	(segment
		(start 100.37318 -412.46552)
		(end 99.54768 -413.29102)
		(width 0.12954)
		(layer "B.Cu")
		(net "HGX_DETECT_N")
	)
	(segment
		(start 99.54768 -415.89706)
		(end 100.37318 -416.72256)
		(width 0.12954)
		(layer "B.Cu")
		(net "HGX_DETECT_N")
	)
	(segment
		(start 100.37318 -421.2971)
		(end 99.924362 -421.745918)
		(width 0.12954)
		(layer "B.Cu")
		(net "HGX_DETECT_N")
	)
	(segment
		(start 100.16744 -410.56052)
		(end 100.37318 -410.76626)
		(width 0.12954)
		(layer "B.Cu")
		(net "HGX_DETECT_N")
	)
	(segment
		(start 99.924362 -421.745918)
		(end 99.53752 -421.745918)
		(width 0.12954)
		(layer "B.Cu")
		(net "HGX_DETECT_N")
	)
	(segment
		(start 100.37318 -410.76626)
		(end 100.37318 -412.46552)
		(width 0.12954)
		(layer "B.Cu")
		(net "HGX_DETECT_N")
	)
	(segment
		(start 99.54768 -413.29102)
		(end 99.54768 -415.89706)
		(width 0.12954)
		(layer "B.Cu")
		(net "HGX_DETECT_N")
	)
	(segment
		(start 185.355738 -119.375428)
		(end 185.755788 -119.775478)
		(width 0.12954)
		(layer "F.Cu")
		(net "SWB_HSC_EN_R")
	)
	(segment
		(start 354.41255 -408.818588)
		(end 354.41255 -408.142948)
		(width 0.12954)
		(layer "F.Cu")
		(net "SWB_HSC_EN_R")
	)
	(via
		(at 207.87868 -341.462868)
		(size 0.508)
		(drill 0.254)
		(layers "F.Cu" "B.Cu")
		(net "SWB_HSC_EN_R")
	)
	(via
		(at 272.79854 -383.7051)
		(size 0.508)
		(drill 0.254)
		(layers "F.Cu" "B.Cu")
		(net "SWB_HSC_EN_R")
	)
	(via
		(at 205.61554 -123.474988)
		(size 0.508)
		(drill 0.254)
		(layers "F.Cu" "B.Cu")
		(net "SWB_HSC_EN_R")
	)
	(via
		(at 185.755788 -119.775478)
		(size 0.4572)
		(drill 0.254)
		(layers "F.Cu" "B.Cu")
		(net "SWB_HSC_EN_R")
	)
	(via
		(at 354.41255 -408.142948)
		(size 0.508)
		(drill 0.254)
		(layers "F.Cu" "B.Cu")
		(net "SWB_HSC_EN_R")
	)
	(segment
		(start 271.54124 -382.4478)
		(end 271.54124 -382.039368)
		(width 0.12954)
		(layer "B.Cu")
		(net "SWB_HSC_EN_R")
	)
	(segment
		(start 263.9695 -374.467628)
		(end 263.9695 -358.607868)
		(width 0.12954)
		(layer "B.Cu")
		(net "SWB_HSC_EN_R")
	)
	(segment
		(start 252.2474 -354.625148)
		(end 240.25606 -342.633808)
		(width 0.12954)
		(layer "B.Cu")
		(net "SWB_HSC_EN_R")
	)
	(segment
		(start 271.54124 -382.039368)
		(end 263.9695 -374.467628)
		(width 0.12954)
		(layer "B.Cu")
		(net "SWB_HSC_EN_R")
	)
	(segment
		(start 272.79854 -383.7051)
		(end 271.54124 -382.4478)
		(width 0.12954)
		(layer "B.Cu")
		(net "SWB_HSC_EN_R")
	)
	(segment
		(start 259.98678 -354.625148)
		(end 252.2474 -354.625148)
		(width 0.12954)
		(layer "B.Cu")
		(net "SWB_HSC_EN_R")
	)
	(segment
		(start 263.9695 -358.607868)
		(end 259.98678 -354.625148)
		(width 0.12954)
		(layer "B.Cu")
		(net "SWB_HSC_EN_R")
	)
	(segment
		(start 207.87868 -341.959692)
		(end 207.87868 -341.462868)
		(width 0.12954)
		(layer "B.Cu")
		(net "SWB_HSC_EN_R")
	)
	(segment
		(start 208.552796 -342.633808)
		(end 207.87868 -341.959692)
		(width 0.12954)
		(layer "B.Cu")
		(net "SWB_HSC_EN_R")
	)
	(segment
		(start 240.25606 -342.633808)
		(end 208.552796 -342.633808)
		(width 0.12954)
		(layer "B.Cu")
		(net "SWB_HSC_EN_R")
	)
	(segment
		(start 220.41358 -215.65362)
		(end 220.41358 -194.511168)
		(width 0.127)
		(layer "In2.Cu")
		(net "SWB_HSC_EN_R")
	)
	(segment
		(start 309.187088 -415.666428)
		(end 348.44228 -415.666428)
		(width 0.127)
		(layer "In2.Cu")
		(net "SWB_HSC_EN_R")
	)
	(segment
		(start 348.44228 -415.666428)
		(end 353.7966 -410.312108)
		(width 0.127)
		(layer "In2.Cu")
		(net "SWB_HSC_EN_R")
	)
	(segment
		(start 220.63964 -190.194946)
		(end 218.49588 -188.051186)
		(width 0.127)
		(layer "In2.Cu")
		(net "SWB_HSC_EN_R")
	)
	(segment
		(start 300.97476 -386.36194)
		(end 300.97476 -397.3576)
		(width 0.127)
		(layer "In2.Cu")
		(net "SWB_HSC_EN_R")
	)
	(segment
		(start 302.60036 -405.384)
		(end 303.50968 -406.29332)
		(width 0.127)
		(layer "In2.Cu")
		(net "SWB_HSC_EN_R")
	)
	(segment
		(start 218.49588 -188.051186)
		(end 218.49588 -186.04611)
		(width 0.127)
		(layer "In2.Cu")
		(net "SWB_HSC_EN_R")
	)
	(segment
		(start 275.9456 -383.04216)
		(end 297.65498 -383.04216)
		(width 0.127)
		(layer "In2.Cu")
		(net "SWB_HSC_EN_R")
	)
	(segment
		(start 218.603322 -149.736048)
		(end 217.828622 -149.736048)
		(width 0.127)
		(layer "In2.Cu")
		(net "SWB_HSC_EN_R")
	)
	(segment
		(start 297.65498 -383.04216)
		(end 300.97476 -386.36194)
		(width 0.127)
		(layer "In2.Cu")
		(net "SWB_HSC_EN_R")
	)
	(segment
		(start 218.49588 -186.04611)
		(end 220.16974 -184.37225)
		(width 0.127)
		(layer "In2.Cu")
		(net "SWB_HSC_EN_R")
	)
	(segment
		(start 353.7966 -410.312108)
		(end 353.7966 -409.265628)
		(width 0.127)
		(layer "In2.Cu")
		(net "SWB_HSC_EN_R")
	)
	(segment
		(start 219.16644 -327.151746)
		(end 219.16644 -216.90076)
		(width 0.127)
		(layer "In2.Cu")
		(net "SWB_HSC_EN_R")
	)
	(segment
		(start 353.79914 -408.756358)
		(end 354.41255 -408.142948)
		(width 0.127)
		(layer "In2.Cu")
		(net "SWB_HSC_EN_R")
	)
	(segment
		(start 216.95918 -146.075908)
		(end 206.31658 -135.433308)
		(width 0.127)
		(layer "In2.Cu")
		(net "SWB_HSC_EN_R")
	)
	(segment
		(start 220.16974 -184.37225)
		(end 220.16974 -151.302466)
		(width 0.127)
		(layer "In2.Cu")
		(net "SWB_HSC_EN_R")
	)
	(segment
		(start 302.60036 -398.9832)
		(end 302.60036 -405.384)
		(width 0.127)
		(layer "In2.Cu")
		(net "SWB_HSC_EN_R")
	)
	(segment
		(start 303.50968 -406.29332)
		(end 303.50968 -409.98902)
		(width 0.127)
		(layer "In2.Cu")
		(net "SWB_HSC_EN_R")
	)
	(segment
		(start 275.28266 -383.7051)
		(end 275.9456 -383.04216)
		(width 0.127)
		(layer "In2.Cu")
		(net "SWB_HSC_EN_R")
	)
	(segment
		(start 216.95918 -148.866606)
		(end 216.95918 -146.075908)
		(width 0.127)
		(layer "In2.Cu")
		(net "SWB_HSC_EN_R")
	)
	(segment
		(start 300.97476 -397.3576)
		(end 302.60036 -398.9832)
		(width 0.127)
		(layer "In2.Cu")
		(net "SWB_HSC_EN_R")
	)
	(segment
		(start 353.7966 -409.265628)
		(end 353.79914 -409.263088)
		(width 0.127)
		(layer "In2.Cu")
		(net "SWB_HSC_EN_R")
	)
	(segment
		(start 272.79854 -383.7051)
		(end 275.28266 -383.7051)
		(width 0.127)
		(layer "In2.Cu")
		(net "SWB_HSC_EN_R")
	)
	(segment
		(start 207.87868 -341.462868)
		(end 207.87868 -337.967066)
		(width 0.127)
		(layer "In2.Cu")
		(net "SWB_HSC_EN_R")
	)
	(segment
		(start 206.31658 -124.493528)
		(end 205.61554 -123.792488)
		(width 0.127)
		(layer "In2.Cu")
		(net "SWB_HSC_EN_R")
	)
	(segment
		(start 303.50968 -409.98902)
		(end 309.187088 -415.666428)
		(width 0.127)
		(layer "In2.Cu")
		(net "SWB_HSC_EN_R")
	)
	(segment
		(start 217.828622 -149.736048)
		(end 216.95918 -148.866606)
		(width 0.127)
		(layer "In2.Cu")
		(net "SWB_HSC_EN_R")
	)
	(segment
		(start 209.417158 -336.428588)
		(end 209.889598 -336.428588)
		(width 0.127)
		(layer "In2.Cu")
		(net "SWB_HSC_EN_R")
	)
	(segment
		(start 353.79914 -409.263088)
		(end 353.79914 -408.756358)
		(width 0.127)
		(layer "In2.Cu")
		(net "SWB_HSC_EN_R")
	)
	(segment
		(start 220.16974 -151.302466)
		(end 218.603322 -149.736048)
		(width 0.127)
		(layer "In2.Cu")
		(net "SWB_HSC_EN_R")
	)
	(segment
		(start 220.41358 -194.511168)
		(end 220.63964 -194.285108)
		(width 0.127)
		(layer "In2.Cu")
		(net "SWB_HSC_EN_R")
	)
	(segment
		(start 206.31658 -135.433308)
		(end 206.31658 -124.493528)
		(width 0.127)
		(layer "In2.Cu")
		(net "SWB_HSC_EN_R")
	)
	(segment
		(start 207.87868 -337.967066)
		(end 209.417158 -336.428588)
		(width 0.127)
		(layer "In2.Cu")
		(net "SWB_HSC_EN_R")
	)
	(segment
		(start 220.63964 -194.285108)
		(end 220.63964 -190.194946)
		(width 0.127)
		(layer "In2.Cu")
		(net "SWB_HSC_EN_R")
	)
	(segment
		(start 209.889598 -336.428588)
		(end 219.16644 -327.151746)
		(width 0.127)
		(layer "In2.Cu")
		(net "SWB_HSC_EN_R")
	)
	(segment
		(start 205.61554 -123.792488)
		(end 205.61554 -123.474988)
		(width 0.127)
		(layer "In2.Cu")
		(net "SWB_HSC_EN_R")
	)
	(segment
		(start 219.16644 -216.90076)
		(end 220.41358 -215.65362)
		(width 0.127)
		(layer "In2.Cu")
		(net "SWB_HSC_EN_R")
	)
	(segment
		(start 203.15555 -121.24436)
		(end 203.755752 -121.24436)
		(width 0.127)
		(layer "In4.Cu")
		(net "SWB_HSC_EN_R")
	)
	(segment
		(start 192.09766 -119.776748)
		(end 194.619372 -119.776748)
		(width 0.127)
		(layer "In4.Cu")
		(net "SWB_HSC_EN_R")
	)
	(segment
		(start 205.61554 -123.104148)
		(end 205.61554 -123.474988)
		(width 0.127)
		(layer "In4.Cu")
		(net "SWB_HSC_EN_R")
	)
	(segment
		(start 194.619372 -119.776748)
		(end 195.980812 -121.138188)
		(width 0.127)
		(layer "In4.Cu")
		(net "SWB_HSC_EN_R")
	)
	(segment
		(start 187.21832 -119.324628)
		(end 191.64554 -119.324628)
		(width 0.127)
		(layer "In4.Cu")
		(net "SWB_HSC_EN_R")
	)
	(segment
		(start 185.755788 -119.775478)
		(end 186.76747 -119.775478)
		(width 0.127)
		(layer "In4.Cu")
		(net "SWB_HSC_EN_R")
	)
	(segment
		(start 191.64554 -119.324628)
		(end 192.09766 -119.776748)
		(width 0.127)
		(layer "In4.Cu")
		(net "SWB_HSC_EN_R")
	)
	(segment
		(start 186.76747 -119.775478)
		(end 187.21832 -119.324628)
		(width 0.127)
		(layer "In4.Cu")
		(net "SWB_HSC_EN_R")
	)
	(segment
		(start 203.755752 -121.24436)
		(end 205.61554 -123.104148)
		(width 0.127)
		(layer "In4.Cu")
		(net "SWB_HSC_EN_R")
	)
	(segment
		(start 195.980812 -121.138188)
		(end 203.049378 -121.138188)
		(width 0.127)
		(layer "In4.Cu")
		(net "SWB_HSC_EN_R")
	)
	(segment
		(start 203.049378 -121.138188)
		(end 203.15555 -121.24436)
		(width 0.127)
		(layer "In4.Cu")
		(net "SWB_HSC_EN_R")
	)
	(segment
		(start 361.74553 -409.649168)
		(end 361.74045 -409.654248)
		(width 0.12954)
		(layer "F.Cu")
		(net "SWB_HSC_EN_BUF_R")
	)
	(segment
		(start 361.73029 -410.700728)
		(end 361.74045 -410.690568)
		(width 0.12954)
		(layer "F.Cu")
		(net "SWB_HSC_EN_BUF_R")
	)
	(segment
		(start 361.74045 -410.690568)
		(end 361.74045 -409.654248)
		(width 0.12954)
		(layer "F.Cu")
		(net "SWB_HSC_EN_BUF_R")
	)
	(segment
		(start 360.98861 -409.301188)
		(end 361.74553 -408.544268)
		(width 0.12954)
		(layer "F.Cu")
		(net "SWB_HSC_EN_BUF_R")
	)
	(segment
		(start 359.59542 -407.883614)
		(end 359.59542 -409.301188)
		(width 0.12954)
		(layer "F.Cu")
		(net "SWB_HSC_EN_BUF_R")
	)
	(segment
		(start 359.59542 -409.301188)
		(end 360.98861 -409.301188)
		(width 0.12954)
		(layer "F.Cu")
		(net "SWB_HSC_EN_BUF_R")
	)
	(segment
		(start 361.74553 -408.544268)
		(end 361.74553 -409.649168)
		(width 0.12954)
		(layer "F.Cu")
		(net "SWB_HSC_EN_BUF_R")
	)
	(via
		(at 359.59542 -409.301188)
		(size 0.762)
		(drill 0.381)
		(layers "F.Cu" "B.Cu")
		(net "SWB_HSC_EN_BUF_R")
	)
	(segment
		(start 355.9302 -411.458918)
		(end 356.823518 -410.5656)
		(width 0.12954)
		(layer "F.Cu")
		(net "SWB_HSC_EN_BUF")
	)
	(segment
		(start 360.5022 -410.5656)
		(end 361.194096 -411.257496)
		(width 0.12954)
		(layer "F.Cu")
		(net "SWB_HSC_EN_BUF")
	)
	(segment
		(start 361.194096 -411.257496)
		(end 362.413042 -411.257496)
		(width 0.12954)
		(layer "F.Cu")
		(net "SWB_HSC_EN_BUF")
	)
	(segment
		(start 356.823518 -410.5656)
		(end 360.5022 -410.5656)
		(width 0.12954)
		(layer "F.Cu")
		(net "SWB_HSC_EN_BUF")
	)
	(segment
		(start 362.53039 -411.140148)
		(end 362.53039 -410.700728)
		(width 0.12954)
		(layer "F.Cu")
		(net "SWB_HSC_EN_BUF")
	)
	(segment
		(start 362.413042 -411.257496)
		(end 362.53039 -411.140148)
		(width 0.12954)
		(layer "F.Cu")
		(net "SWB_HSC_EN_BUF")
	)
	(via
		(at 355.9302 -411.458918)
		(size 0.508)
		(drill 0.254)
		(layers "F.Cu" "B.Cu")
		(net "SWB_HSC_EN_BUF")
	)
	(segment
		(start 353.83597 -411.458918)
		(end 348.57944 -416.715448)
		(width 0.127)
		(layer "In2.Cu")
		(net "SWB_HSC_EN_BUF")
	)
	(segment
		(start 348.57944 -418.859208)
		(end 345.6305 -421.808148)
		(width 0.127)
		(layer "In2.Cu")
		(net "SWB_HSC_EN_BUF")
	)
	(segment
		(start 345.6305 -424.67022)
		(end 345.650058 -424.689778)
		(width 0.127)
		(layer "In2.Cu")
		(net "SWB_HSC_EN_BUF")
	)
	(segment
		(start 355.9302 -411.458918)
		(end 353.83597 -411.458918)
		(width 0.127)
		(layer "In2.Cu")
		(net "SWB_HSC_EN_BUF")
	)
	(segment
		(start 348.57944 -416.715448)
		(end 348.57944 -418.859208)
		(width 0.127)
		(layer "In2.Cu")
		(net "SWB_HSC_EN_BUF")
	)
	(segment
		(start 345.6305 -421.808148)
		(end 345.6305 -424.67022)
		(width 0.127)
		(layer "In2.Cu")
		(net "SWB_HSC_EN_BUF")
	)
	(segment
		(start 355.21265 -408.818588)
		(end 355.2698 -408.761438)
		(width 0.12954)
		(layer "F.Cu")
		(net "SWB_HSC_EN")
	)
	(segment
		(start 355.2698 -408.761438)
		(end 355.2698 -407.252678)
		(width 0.12954)
		(layer "F.Cu")
		(net "SWB_HSC_EN")
	)
	(segment
		(start 355.21265 -408.818588)
		(end 356.08768 -408.818588)
		(width 0.12954)
		(layer "F.Cu")
		(net "SWB_HSC_EN")
	)
	(segment
		(start 356.4255 -408.480768)
		(end 357.022654 -407.883614)
		(width 0.12954)
		(layer "F.Cu")
		(net "SWB_HSC_EN")
	)
	(segment
		(start 357.022654 -407.883614)
		(end 357.6955 -407.883614)
		(width 0.12954)
		(layer "F.Cu")
		(net "SWB_HSC_EN")
	)
	(segment
		(start 356.28072 -407.250138)
		(end 355.27234 -407.250138)
		(width 0.12954)
		(layer "F.Cu")
		(net "SWB_HSC_EN")
	)
	(segment
		(start 356.08768 -408.818588)
		(end 356.4255 -408.480768)
		(width 0.12954)
		(layer "F.Cu")
		(net "SWB_HSC_EN")
	)
	(segment
		(start 355.27234 -407.250138)
		(end 355.2698 -407.252678)
		(width 0.12954)
		(layer "F.Cu")
		(net "SWB_HSC_EN")
	)
	(via
		(at 356.4255 -408.480768)
		(size 0.762)
		(drill 0.381)
		(layers "F.Cu" "B.Cu")
		(net "SWB_HSC_EN")
	)
	(segment
		(start 259.179568 -132.543804)
		(end 259.421376 -132.301996)
		(width 0.12954)
		(layer "F.Cu")
		(net "SMB_HOST_CLK_BUF_ISO_3V3AUX_S_2")
	)
	(segment
		(start 263.95299 -133.410198)
		(end 263.51738 -133.845808)
		(width 0.12954)
		(layer "F.Cu")
		(net "SMB_HOST_CLK_BUF_ISO_3V3AUX_S_2")
	)
	(segment
		(start 263.95299 -133.005068)
		(end 264.56894 -132.389118)
		(width 0.12954)
		(layer "F.Cu")
		(net "SMB_HOST_CLK_BUF_ISO_3V3AUX_S_2")
	)
	(segment
		(start 265.929872 -130.861816)
		(end 266.493244 -130.861816)
		(width 0.12954)
		(layer "F.Cu")
		(net "SMB_HOST_CLK_BUF_ISO_3V3AUX_S_2")
	)
	(segment
		(start 259.969 -133.845808)
		(end 259.179568 -133.056376)
		(width 0.12954)
		(layer "F.Cu")
		(net "SMB_HOST_CLK_BUF_ISO_3V3AUX_S_2")
	)
	(segment
		(start 263.51738 -133.845808)
		(end 259.969 -133.845808)
		(width 0.12954)
		(layer "F.Cu")
		(net "SMB_HOST_CLK_BUF_ISO_3V3AUX_S_2")
	)
	(segment
		(start 264.56894 -132.389118)
		(end 264.56894 -132.222748)
		(width 0.12954)
		(layer "F.Cu")
		(net "SMB_HOST_CLK_BUF_ISO_3V3AUX_S_2")
	)
	(segment
		(start 264.56894 -132.222748)
		(end 265.929872 -130.861816)
		(width 0.12954)
		(layer "F.Cu")
		(net "SMB_HOST_CLK_BUF_ISO_3V3AUX_S_2")
	)
	(segment
		(start 263.95299 -133.005068)
		(end 263.95299 -133.410198)
		(width 0.12954)
		(layer "F.Cu")
		(net "SMB_HOST_CLK_BUF_ISO_3V3AUX_S_2")
	)
	(segment
		(start 259.179568 -133.056376)
		(end 259.179568 -132.543804)
		(width 0.12954)
		(layer "F.Cu")
		(net "SMB_HOST_CLK_BUF_ISO_3V3AUX_S_2")
	)
	(segment
		(start 259.421376 -132.301996)
		(end 259.421376 -131.502912)
		(width 0.12954)
		(layer "F.Cu")
		(net "SMB_HOST_CLK_BUF_ISO_3V3AUX_S_2")
	)
	(via
		(at 259.179568 -132.543804)
		(size 0.508)
		(drill 0.254)
		(layers "F.Cu" "B.Cu")
		(net "SMB_HOST_CLK_BUF_ISO_3V3AUX_S_2")
	)
	(segment
		(start 260.698488 -131.470908)
		(end 262.765794 -131.470908)
		(width 0.12954)
		(layer "F.Cu")
		(net "SMB_HOST_CLK_BUF_ISO_3V3AUX_S_1")
	)
	(segment
		(start 264.05967 -131.303268)
		(end 264.05967 -130.602228)
		(width 0.12954)
		(layer "F.Cu")
		(net "SMB_HOST_CLK_BUF_ISO_3V3AUX_S_1")
	)
	(segment
		(start 263.68502 -131.677918)
		(end 264.05967 -131.303268)
		(width 0.12954)
		(layer "F.Cu")
		(net "SMB_HOST_CLK_BUF_ISO_3V3AUX_S_1")
	)
	(segment
		(start 262.972804 -131.677918)
		(end 263.68502 -131.677918)
		(width 0.12954)
		(layer "F.Cu")
		(net "SMB_HOST_CLK_BUF_ISO_3V3AUX_S_1")
	)
	(segment
		(start 264.450322 -130.211576)
		(end 264.05967 -130.602228)
		(width 0.12954)
		(layer "F.Cu")
		(net "SMB_HOST_CLK_BUF_ISO_3V3AUX_S_1")
	)
	(segment
		(start 266.493244 -130.211576)
		(end 264.450322 -130.211576)
		(width 0.12954)
		(layer "F.Cu")
		(net "SMB_HOST_CLK_BUF_ISO_3V3AUX_S_1")
	)
	(segment
		(start 259.421376 -130.193796)
		(end 260.698488 -131.470908)
		(width 0.12954)
		(layer "F.Cu")
		(net "SMB_HOST_CLK_BUF_ISO_3V3AUX_S_1")
	)
	(segment
		(start 262.765794 -131.470908)
		(end 262.972804 -131.677918)
		(width 0.12954)
		(layer "F.Cu")
		(net "SMB_HOST_CLK_BUF_ISO_3V3AUX_S_1")
	)
	(via
		(at 263.68502 -131.677918)
		(size 0.508)
		(drill 0.254)
		(layers "F.Cu" "B.Cu")
		(net "SMB_HOST_CLK_BUF_ISO_3V3AUX_S_1")
	)
	(segment
		(start 93.9546 -414.6804)
		(end 94.20606 -414.93186)
		(width 0.12954)
		(layer "F.Cu")
		(net "HGX_DETECT")
	)
	(segment
		(start 94.767654 -416.433)
		(end 93.726 -416.433)
		(width 0.12954)
		(layer "F.Cu")
		(net "HGX_DETECT")
	)
	(segment
		(start 93.556074 -416.263074)
		(end 93.556074 -415.168588)
		(width 0.12954)
		(layer "F.Cu")
		(net "HGX_DETECT")
	)
	(segment
		(start 95.123 -417.283138)
		(end 95.123 -416.788346)
		(width 0.12954)
		(layer "F.Cu")
		(net "HGX_DETECT")
	)
	(segment
		(start 94.20606 -414.93186)
		(end 94.20606 -415.168588)
		(width 0.12954)
		(layer "F.Cu")
		(net "HGX_DETECT")
	)
	(segment
		(start 93.556074 -415.168588)
		(end 93.556074 -414.776666)
		(width 0.12954)
		(layer "F.Cu")
		(net "HGX_DETECT")
	)
	(segment
		(start 95.123 -416.788346)
		(end 94.767654 -416.433)
		(width 0.12954)
		(layer "F.Cu")
		(net "HGX_DETECT")
	)
	(segment
		(start 93.726 -416.433)
		(end 93.556074 -416.263074)
		(width 0.12954)
		(layer "F.Cu")
		(net "HGX_DETECT")
	)
	(segment
		(start 93.556074 -414.776666)
		(end 93.65234 -414.6804)
		(width 0.12954)
		(layer "F.Cu")
		(net "HGX_DETECT")
	)
	(segment
		(start 93.65234 -414.6804)
		(end 93.9546 -414.6804)
		(width 0.12954)
		(layer "F.Cu")
		(net "HGX_DETECT")
	)
	(via
		(at 93.726 -416.433)
		(size 0.762)
		(drill 0.381)
		(layers "F.Cu" "B.Cu")
		(net "HGX_DETECT")
	)
	(via
		(at 177.5206 -34.488628)
		(size 0.6604)
		(drill 0.3302)
		(layers "F.Cu" "B.Cu")
		(net "P12V_SCM_ISET_R")
	)
	(segment
		(start 178.04384 -33.344358)
		(end 178.04384 -33.965388)
		(width 0.12954)
		(layer "B.Cu")
		(net "P12V_SCM_ISET_R")
	)
	(segment
		(start 177.5206 -34.488628)
		(end 176.97704 -33.945068)
		(width 0.12954)
		(layer "B.Cu")
		(net "P12V_SCM_ISET_R")
	)
	(segment
		(start 176.97704 -33.945068)
		(end 176.97704 -33.351978)
		(width 0.12954)
		(layer "B.Cu")
		(net "P12V_SCM_ISET_R")
	)
	(segment
		(start 178.04384 -33.965388)
		(end 177.5206 -34.488628)
		(width 0.12954)
		(layer "B.Cu")
		(net "P12V_SCM_ISET_R")
	)
	(via
		(at 258.40944 -50.573686)
		(size 0.6604)
		(drill 0.3302)
		(layers "F.Cu" "B.Cu")
		(net "P12V_E1S_ISET_0_R")
	)
	(segment
		(start 258.97459 -50.008536)
		(end 258.40944 -50.573686)
		(width 0.12954)
		(layer "B.Cu")
		(net "P12V_E1S_ISET_0_R")
	)
	(segment
		(start 258.03987 -50.204116)
		(end 258.03987 -49.430686)
		(width 0.12954)
		(layer "B.Cu")
		(net "P12V_E1S_ISET_0_R")
	)
	(segment
		(start 258.97459 -49.430686)
		(end 258.97459 -50.008536)
		(width 0.12954)
		(layer "B.Cu")
		(net "P12V_E1S_ISET_0_R")
	)
	(segment
		(start 258.40944 -50.573686)
		(end 258.03987 -50.204116)
		(width 0.12954)
		(layer "B.Cu")
		(net "P12V_E1S_ISET_0_R")
	)
	(segment
		(start 362.3056 -405.9682)
		(end 359.72242 -405.9682)
		(width 0.12954)
		(layer "F.Cu")
		(net "NC_U316_2Y")
	)
	(segment
		(start 359.59542 -406.0952)
		(end 359.59542 -406.583642)
		(width 0.12954)
		(layer "F.Cu")
		(net "NC_U316_2Y")
	)
	(segment
		(start 362.8898 -406.5524)
		(end 362.3056 -405.9682)
		(width 0.12954)
		(layer "F.Cu")
		(net "NC_U316_2Y")
	)
	(segment
		(start 359.72242 -405.9682)
		(end 359.59542 -406.0952)
		(width 0.12954)
		(layer "F.Cu")
		(net "NC_U316_2Y")
	)
	(via
		(at 362.8898 -406.5524)
		(size 0.762)
		(drill 0.381)
		(layers "F.Cu" "B.Cu")
		(net "NC_U316_2Y")
	)
	(segment
		(start 290.804346 -413.6009)
		(end 291.330126 -413.07512)
		(width 0.12954)
		(layer "F.Cu")
		(net "HPDB_HSC_PWRGD_N")
	)
	(segment
		(start 290.065968 -412.996126)
		(end 290.065968 -413.504634)
		(width 0.12954)
		(layer "F.Cu")
		(net "HPDB_HSC_PWRGD_N")
	)
	(segment
		(start 290.065968 -412.996126)
		(end 290.065968 -412.34614)
		(width 0.12954)
		(layer "F.Cu")
		(net "HPDB_HSC_PWRGD_N")
	)
	(segment
		(start 290.804346 -414.243012)
		(end 290.804346 -413.6009)
		(width 0.12954)
		(layer "F.Cu")
		(net "HPDB_HSC_PWRGD_N")
	)
	(segment
		(start 290.065968 -413.504634)
		(end 290.804346 -414.243012)
		(width 0.12954)
		(layer "F.Cu")
		(net "HPDB_HSC_PWRGD_N")
	)
	(segment
		(start 291.330126 -413.07512)
		(end 291.873178 -413.07512)
		(width 0.12954)
		(layer "F.Cu")
		(net "HPDB_HSC_PWRGD_N")
	)
	(via
		(at 290.804346 -414.243012)
		(size 0.762)
		(drill 0.381)
		(layers "F.Cu" "B.Cu")
		(net "HPDB_HSC_PWRGD_N")
	)
	(segment
		(start 186.155584 -120.175528)
		(end 185.755534 -120.575578)
		(width 0.12954)
		(layer "F.Cu")
		(net "HPDB_HSC_PWRGD_ISO_R")
	)
	(segment
		(start 283.413708 -410.89453)
		(end 283.413708 -410.21254)
		(width 0.12954)
		(layer "F.Cu")
		(net "HPDB_HSC_PWRGD_ISO_R")
	)
	(via
		(at 204.34554 -123.474988)
		(size 0.508)
		(drill 0.254)
		(layers "F.Cu" "B.Cu")
		(net "HPDB_HSC_PWRGD_ISO_R")
	)
	(via
		(at 185.755534 -120.575578)
		(size 0.4572)
		(drill 0.254)
		(layers "F.Cu" "B.Cu")
		(net "HPDB_HSC_PWRGD_ISO_R")
	)
	(via
		(at 208.51368 -341.462868)
		(size 0.508)
		(drill 0.254)
		(layers "F.Cu" "B.Cu")
		(net "HPDB_HSC_PWRGD_ISO_R")
	)
	(via
		(at 283.413708 -410.21254)
		(size 0.508)
		(drill 0.254)
		(layers "F.Cu" "B.Cu")
		(net "HPDB_HSC_PWRGD_ISO_R")
	)
	(segment
		(start 260.11632 -354.312728)
		(end 252.37694 -354.312728)
		(width 0.12954)
		(layer "B.Cu")
		(net "HPDB_HSC_PWRGD_ISO_R")
	)
	(segment
		(start 264.28192 -358.478328)
		(end 260.11632 -354.312728)
		(width 0.12954)
		(layer "B.Cu")
		(net "HPDB_HSC_PWRGD_ISO_R")
	)
	(segment
		(start 240.3856 -342.321388)
		(end 209.13852 -342.321388)
		(width 0.12954)
		(layer "B.Cu")
		(net "HPDB_HSC_PWRGD_ISO_R")
	)
	(segment
		(start 209.13852 -342.321388)
		(end 208.51368 -341.696548)
		(width 0.12954)
		(layer "B.Cu")
		(net "HPDB_HSC_PWRGD_ISO_R")
	)
	(segment
		(start 284.1498 -409.476448)
		(end 284.1498 -396.240254)
		(width 0.12954)
		(layer "B.Cu")
		(net "HPDB_HSC_PWRGD_ISO_R")
	)
	(segment
		(start 277.80996 -386.68706)
		(end 277.80996 -386.30352)
		(width 0.12954)
		(layer "B.Cu")
		(net "HPDB_HSC_PWRGD_ISO_R")
	)
	(segment
		(start 277.80996 -386.30352)
		(end 264.28192 -372.77548)
		(width 0.12954)
		(layer "B.Cu")
		(net "HPDB_HSC_PWRGD_ISO_R")
	)
	(segment
		(start 283.413708 -410.21254)
		(end 284.1498 -409.476448)
		(width 0.12954)
		(layer "B.Cu")
		(net "HPDB_HSC_PWRGD_ISO_R")
	)
	(segment
		(start 284.1498 -396.240254)
		(end 282.921202 -395.011656)
		(width 0.12954)
		(layer "B.Cu")
		(net "HPDB_HSC_PWRGD_ISO_R")
	)
	(segment
		(start 252.37694 -354.312728)
		(end 240.3856 -342.321388)
		(width 0.12954)
		(layer "B.Cu")
		(net "HPDB_HSC_PWRGD_ISO_R")
	)
	(segment
		(start 208.51368 -341.696548)
		(end 208.51368 -341.462868)
		(width 0.12954)
		(layer "B.Cu")
		(net "HPDB_HSC_PWRGD_ISO_R")
	)
	(segment
		(start 282.921202 -395.011656)
		(end 282.921202 -391.798302)
		(width 0.12954)
		(layer "B.Cu")
		(net "HPDB_HSC_PWRGD_ISO_R")
	)
	(segment
		(start 282.921202 -391.798302)
		(end 277.80996 -386.68706)
		(width 0.12954)
		(layer "B.Cu")
		(net "HPDB_HSC_PWRGD_ISO_R")
	)
	(segment
		(start 264.28192 -372.77548)
		(end 264.28192 -358.478328)
		(width 0.12954)
		(layer "B.Cu")
		(net "HPDB_HSC_PWRGD_ISO_R")
	)
	(segment
		(start 207.09382 -123.276868)
		(end 206.69758 -122.880628)
		(width 0.127)
		(layer "In2.Cu")
		(net "HPDB_HSC_PWRGD_ISO_R")
	)
	(segment
		(start 221.0054 -194.600068)
		(end 221.0054 -190.043308)
		(width 0.127)
		(layer "In2.Cu")
		(net "HPDB_HSC_PWRGD_ISO_R")
	)
	(segment
		(start 218.86164 -186.197748)
		(end 220.5355 -184.523888)
		(width 0.127)
		(layer "In2.Cu")
		(net "HPDB_HSC_PWRGD_ISO_R")
	)
	(segment
		(start 204.34554 -123.134628)
		(end 204.34554 -123.474988)
		(width 0.127)
		(layer "In2.Cu")
		(net "HPDB_HSC_PWRGD_ISO_R")
	)
	(segment
		(start 220.5355 -151.150828)
		(end 218.75496 -149.370288)
		(width 0.127)
		(layer "In2.Cu")
		(net "HPDB_HSC_PWRGD_ISO_R")
	)
	(segment
		(start 206.68234 -128.158748)
		(end 207.4418 -127.399288)
		(width 0.127)
		(layer "In2.Cu")
		(net "HPDB_HSC_PWRGD_ISO_R")
	)
	(segment
		(start 208.51368 -341.462868)
		(end 208.51368 -337.860132)
		(width 0.127)
		(layer "In2.Cu")
		(net "HPDB_HSC_PWRGD_ISO_R")
	)
	(segment
		(start 220.86316 -194.742308)
		(end 221.0054 -194.600068)
		(width 0.127)
		(layer "In2.Cu")
		(net "HPDB_HSC_PWRGD_ISO_R")
	)
	(segment
		(start 221.0054 -190.043308)
		(end 218.86164 -187.899548)
		(width 0.127)
		(layer "In2.Cu")
		(net "HPDB_HSC_PWRGD_ISO_R")
	)
	(segment
		(start 210.044284 -336.801968)
		(end 219.53982 -327.306432)
		(width 0.127)
		(layer "In2.Cu")
		(net "HPDB_HSC_PWRGD_ISO_R")
	)
	(segment
		(start 207.09382 -126.152148)
		(end 207.09382 -123.276868)
		(width 0.127)
		(layer "In2.Cu")
		(net "HPDB_HSC_PWRGD_ISO_R")
	)
	(segment
		(start 207.4418 -127.399288)
		(end 207.4418 -126.500128)
		(width 0.127)
		(layer "In2.Cu")
		(net "HPDB_HSC_PWRGD_ISO_R")
	)
	(segment
		(start 204.59954 -122.880628)
		(end 204.34554 -123.134628)
		(width 0.127)
		(layer "In2.Cu")
		(net "HPDB_HSC_PWRGD_ISO_R")
	)
	(segment
		(start 217.32494 -148.714968)
		(end 217.32494 -145.92427)
		(width 0.127)
		(layer "In2.Cu")
		(net "HPDB_HSC_PWRGD_ISO_R")
	)
	(segment
		(start 206.68234 -135.28167)
		(end 206.68234 -128.158748)
		(width 0.127)
		(layer "In2.Cu")
		(net "HPDB_HSC_PWRGD_ISO_R")
	)
	(segment
		(start 217.32494 -145.92427)
		(end 206.68234 -135.28167)
		(width 0.127)
		(layer "In2.Cu")
		(net "HPDB_HSC_PWRGD_ISO_R")
	)
	(segment
		(start 206.69758 -122.880628)
		(end 204.59954 -122.880628)
		(width 0.127)
		(layer "In2.Cu")
		(net "HPDB_HSC_PWRGD_ISO_R")
	)
	(segment
		(start 209.571844 -336.801968)
		(end 210.044284 -336.801968)
		(width 0.127)
		(layer "In2.Cu")
		(net "HPDB_HSC_PWRGD_ISO_R")
	)
	(segment
		(start 218.86164 -187.899548)
		(end 218.86164 -186.197748)
		(width 0.127)
		(layer "In2.Cu")
		(net "HPDB_HSC_PWRGD_ISO_R")
	)
	(segment
		(start 219.53982 -217.465402)
		(end 220.86316 -216.142062)
		(width 0.127)
		(layer "In2.Cu")
		(net "HPDB_HSC_PWRGD_ISO_R")
	)
	(segment
		(start 208.51368 -337.860132)
		(end 209.571844 -336.801968)
		(width 0.127)
		(layer "In2.Cu")
		(net "HPDB_HSC_PWRGD_ISO_R")
	)
	(segment
		(start 207.4418 -126.500128)
		(end 207.09382 -126.152148)
		(width 0.127)
		(layer "In2.Cu")
		(net "HPDB_HSC_PWRGD_ISO_R")
	)
	(segment
		(start 220.86316 -216.142062)
		(end 220.86316 -194.742308)
		(width 0.127)
		(layer "In2.Cu")
		(net "HPDB_HSC_PWRGD_ISO_R")
	)
	(segment
		(start 217.98026 -149.370288)
		(end 217.32494 -148.714968)
		(width 0.127)
		(layer "In2.Cu")
		(net "HPDB_HSC_PWRGD_ISO_R")
	)
	(segment
		(start 218.75496 -149.370288)
		(end 217.98026 -149.370288)
		(width 0.127)
		(layer "In2.Cu")
		(net "HPDB_HSC_PWRGD_ISO_R")
	)
	(segment
		(start 220.5355 -184.523888)
		(end 220.5355 -151.150828)
		(width 0.127)
		(layer "In2.Cu")
		(net "HPDB_HSC_PWRGD_ISO_R")
	)
	(segment
		(start 219.53982 -327.306432)
		(end 219.53982 -217.465402)
		(width 0.127)
		(layer "In2.Cu")
		(net "HPDB_HSC_PWRGD_ISO_R")
	)
	(segment
		(start 195.843652 -121.468388)
		(end 202.912472 -121.468388)
		(width 0.127)
		(layer "In4.Cu")
		(net "HPDB_HSC_PWRGD_ISO_R")
	)
	(segment
		(start 194.482212 -120.106948)
		(end 195.843652 -121.468388)
		(width 0.127)
		(layer "In4.Cu")
		(net "HPDB_HSC_PWRGD_ISO_R")
	)
	(segment
		(start 202.912472 -121.468388)
		(end 204.484986 -123.040902)
		(width 0.127)
		(layer "In4.Cu")
		(net "HPDB_HSC_PWRGD_ISO_R")
	)
	(segment
		(start 187.97524 -119.822468)
		(end 191.3509 -119.822468)
		(width 0.127)
		(layer "In4.Cu")
		(net "HPDB_HSC_PWRGD_ISO_R")
	)
	(segment
		(start 204.484986 -123.040902)
		(end 204.484986 -123.335542)
		(width 0.127)
		(layer "In4.Cu")
		(net "HPDB_HSC_PWRGD_ISO_R")
	)
	(segment
		(start 187.22213 -120.575578)
		(end 187.97524 -119.822468)
		(width 0.127)
		(layer "In4.Cu")
		(net "HPDB_HSC_PWRGD_ISO_R")
	)
	(segment
		(start 185.755534 -120.575578)
		(end 187.22213 -120.575578)
		(width 0.127)
		(layer "In4.Cu")
		(net "HPDB_HSC_PWRGD_ISO_R")
	)
	(segment
		(start 191.3509 -119.822468)
		(end 191.63538 -120.106948)
		(width 0.127)
		(layer "In4.Cu")
		(net "HPDB_HSC_PWRGD_ISO_R")
	)
	(segment
		(start 204.484986 -123.335542)
		(end 204.34554 -123.474988)
		(width 0.127)
		(layer "In4.Cu")
		(net "HPDB_HSC_PWRGD_ISO_R")
	)
	(segment
		(start 191.63538 -120.106948)
		(end 194.482212 -120.106948)
		(width 0.127)
		(layer "In4.Cu")
		(net "HPDB_HSC_PWRGD_ISO_R")
	)
	(segment
		(start 285.714948 -411.68955)
		(end 285.721552 -411.696154)
		(width 0.12954)
		(layer "F.Cu")
		(net "HPDB_HSC_PWRGD_ISO")
	)
	(segment
		(start 285.721552 -411.696154)
		(end 286.92348 -411.696154)
		(width 0.12954)
		(layer "F.Cu")
		(net "HPDB_HSC_PWRGD_ISO")
	)
	(segment
		(start 284.602428 -411.68955)
		(end 284.599888 -411.69209)
		(width 0.12954)
		(layer "F.Cu")
		(net "HPDB_HSC_PWRGD_ISO")
	)
	(segment
		(start 285.714948 -411.68955)
		(end 284.602428 -411.68955)
		(width 0.12954)
		(layer "F.Cu")
		(net "HPDB_HSC_PWRGD_ISO")
	)
	(segment
		(start 284.599888 -411.69209)
		(end 283.416248 -411.69209)
		(width 0.12954)
		(layer "F.Cu")
		(net "HPDB_HSC_PWRGD_ISO")
	)
	(segment
		(start 286.92348 -411.696154)
		(end 288.166048 -411.696154)
		(width 0.12954)
		(layer "F.Cu")
		(net "HPDB_HSC_PWRGD_ISO")
	)
	(segment
		(start 283.416248 -411.69209)
		(end 283.413708 -411.69463)
		(width 0.12954)
		(layer "F.Cu")
		(net "HPDB_HSC_PWRGD_ISO")
	)
	(via
		(at 286.92348 -411.696154)
		(size 0.762)
		(drill 0.381)
		(layers "F.Cu" "B.Cu")
		(net "HPDB_HSC_PWRGD_ISO")
	)
	(segment
		(start 284.560518 -412.86684)
		(end 284.589728 -412.83763)
		(width 0.12954)
		(layer "F.Cu")
		(net "HPDB_HSC_PWRGD")
	)
	(segment
		(start 285.713678 -412.85922)
		(end 285.689548 -412.83509)
		(width 0.12954)
		(layer "F.Cu")
		(net "HPDB_HSC_PWRGD")
	)
	(segment
		(start 286.974788 -412.34614)
		(end 286.461708 -412.85922)
		(width 0.12954)
		(layer "F.Cu")
		(net "HPDB_HSC_PWRGD")
	)
	(segment
		(start 288.166048 -412.34614)
		(end 286.974788 -412.34614)
		(width 0.12954)
		(layer "F.Cu")
		(net "HPDB_HSC_PWRGD")
	)
	(segment
		(start 286.461708 -412.85922)
		(end 285.713678 -412.85922)
		(width 0.12954)
		(layer "F.Cu")
		(net "HPDB_HSC_PWRGD")
	)
	(segment
		(start 285.687008 -412.83763)
		(end 284.589728 -412.83763)
		(width 0.12954)
		(layer "F.Cu")
		(net "HPDB_HSC_PWRGD")
	)
	(segment
		(start 285.689548 -412.83509)
		(end 285.687008 -412.83763)
		(width 0.12954)
		(layer "F.Cu")
		(net "HPDB_HSC_PWRGD")
	)
	(segment
		(start 283.764228 -412.86684)
		(end 284.560518 -412.86684)
		(width 0.12954)
		(layer "F.Cu")
		(net "HPDB_HSC_PWRGD")
	)
	(via
		(at 236.214666 -421.983408)
		(size 0.508)
		(drill 0.254)
		(layers "F.Cu" "B.Cu")
		(net "HPDB_HSC_PWRGD")
	)
	(via
		(at 283.764228 -412.86684)
		(size 0.508)
		(drill 0.254)
		(layers "F.Cu" "B.Cu")
		(net "HPDB_HSC_PWRGD")
	)
	(segment
		(start 236.214666 -422.601898)
		(end 236.214666 -421.983408)
		(width 0.12954)
		(layer "B.Cu")
		(net "HPDB_HSC_PWRGD")
	)
	(segment
		(start 280.30297 -420.55923)
		(end 277.70455 -420.55923)
		(width 0.127)
		(layer "In2.Cu")
		(net "HPDB_HSC_PWRGD")
	)
	(segment
		(start 237.69828 -425.20108)
		(end 236.214666 -423.717466)
		(width 0.127)
		(layer "In2.Cu")
		(net "HPDB_HSC_PWRGD")
	)
	(segment
		(start 239.63122 -425.20108)
		(end 237.69828 -425.20108)
		(width 0.127)
		(layer "In2.Cu")
		(net "HPDB_HSC_PWRGD")
	)
	(segment
		(start 277.70455 -420.55923)
		(end 273.59356 -424.67022)
		(width 0.127)
		(layer "In2.Cu")
		(net "HPDB_HSC_PWRGD")
	)
	(segment
		(start 283.764228 -412.86684)
		(end 284.31236 -412.86684)
		(width 0.127)
		(layer "In2.Cu")
		(net "HPDB_HSC_PWRGD")
	)
	(segment
		(start 284.31236 -412.86684)
		(end 284.43936 -412.99384)
		(width 0.127)
		(layer "In2.Cu")
		(net "HPDB_HSC_PWRGD")
	)
	(segment
		(start 273.59356 -424.67022)
		(end 240.16208 -424.67022)
		(width 0.127)
		(layer "In2.Cu")
		(net "HPDB_HSC_PWRGD")
	)
	(segment
		(start 240.16208 -424.67022)
		(end 239.63122 -425.20108)
		(width 0.127)
		(layer "In2.Cu")
		(net "HPDB_HSC_PWRGD")
	)
	(segment
		(start 236.214666 -423.717466)
		(end 236.214666 -421.983408)
		(width 0.127)
		(layer "In2.Cu")
		(net "HPDB_HSC_PWRGD")
	)
	(segment
		(start 284.43936 -416.42284)
		(end 280.30297 -420.55923)
		(width 0.127)
		(layer "In2.Cu")
		(net "HPDB_HSC_PWRGD")
	)
	(segment
		(start 284.43936 -412.99384)
		(end 284.43936 -416.42284)
		(width 0.127)
		(layer "In2.Cu")
		(net "HPDB_HSC_PWRGD")
	)
	(segment
		(start 177.61458 -404.071328)
		(end 177.61458 -407.128218)
		(width 0.12954)
		(layer "F.Cu")
		(net "SMB_SML1_PMBUS_HSC_SDA_R3")
	)
	(segment
		(start 172.59554 -399.052288)
		(end 177.61458 -404.071328)
		(width 0.12954)
		(layer "F.Cu")
		(net "SMB_SML1_PMBUS_HSC_SDA_R3")
	)
	(segment
		(start 172.369734 -399.052288)
		(end 172.59554 -399.052288)
		(width 0.12954)
		(layer "F.Cu")
		(net "SMB_SML1_PMBUS_HSC_SDA_R3")
	)
	(segment
		(start 7.82193 -54.955948)
		(end 7.82193 -54.192932)
		(width 0.12954)
		(layer "F.Cu")
		(net "SMB_SML1_PMBUS_HSC_SDA_R3")
	)
	(segment
		(start 177.61458 -407.128218)
		(end 178.69027 -408.203908)
		(width 0.12954)
		(layer "F.Cu")
		(net "SMB_SML1_PMBUS_HSC_SDA_R3")
	)
	(via
		(at 47.5996 -398.305528)
		(size 0.508)
		(drill 0.254)
		(layers "F.Cu" "B.Cu")
		(net "SMB_SML1_PMBUS_HSC_SDA_R3")
	)
	(via
		(at 7.82193 -54.192932)
		(size 0.508)
		(drill 0.254)
		(layers "F.Cu" "B.Cu")
		(net "SMB_SML1_PMBUS_HSC_SDA_R3")
	)
	(via
		(at 6.731 -171.668948)
		(size 0.508)
		(drill 0.254)
		(layers "F.Cu" "B.Cu")
		(net "SMB_SML1_PMBUS_HSC_SDA_R3")
	)
	(via
		(at 172.369734 -399.052288)
		(size 0.508)
		(drill 0.254)
		(layers "F.Cu" "B.Cu")
		(net "SMB_SML1_PMBUS_HSC_SDA_R3")
	)
	(segment
		(start 50.104548 -398.3736)
		(end 51.943 -396.535148)
		(width 0.127)
		(layer "In6.Cu")
		(net "SMB_SML1_PMBUS_HSC_SDA_R3")
	)
	(segment
		(start 51.943 -389.601202)
		(end 29.718 -367.376202)
		(width 0.127)
		(layer "In6.Cu")
		(net "SMB_SML1_PMBUS_HSC_SDA_R3")
	)
	(segment
		(start 6.2992 -322.789042)
		(end 6.2992 -256.749042)
		(width 0.127)
		(layer "In6.Cu")
		(net "SMB_SML1_PMBUS_HSC_SDA_R3")
	)
	(segment
		(start 29.718 -367.376202)
		(end 29.718 -330.673202)
		(width 0.127)
		(layer "In6.Cu")
		(net "SMB_SML1_PMBUS_HSC_SDA_R3")
	)
	(segment
		(start 47.667672 -398.3736)
		(end 50.104548 -398.3736)
		(width 0.127)
		(layer "In6.Cu")
		(net "SMB_SML1_PMBUS_HSC_SDA_R3")
	)
	(segment
		(start 47.5996 -398.305528)
		(end 47.667672 -398.3736)
		(width 0.127)
		(layer "In6.Cu")
		(net "SMB_SML1_PMBUS_HSC_SDA_R3")
	)
	(segment
		(start 10.845546 -324.881748)
		(end 8.391906 -324.881748)
		(width 0.127)
		(layer "In6.Cu")
		(net "SMB_SML1_PMBUS_HSC_SDA_R3")
	)
	(segment
		(start 8.391906 -324.881748)
		(end 6.2992 -322.789042)
		(width 0.127)
		(layer "In6.Cu")
		(net "SMB_SML1_PMBUS_HSC_SDA_R3")
	)
	(segment
		(start 14.858746 -328.894948)
		(end 10.845546 -324.881748)
		(width 0.127)
		(layer "In6.Cu")
		(net "SMB_SML1_PMBUS_HSC_SDA_R3")
	)
	(segment
		(start 3.777742 -254.227584)
		(end 3.777742 -174.622206)
		(width 0.127)
		(layer "In6.Cu")
		(net "SMB_SML1_PMBUS_HSC_SDA_R3")
	)
	(segment
		(start 29.718 -330.673202)
		(end 27.939746 -328.894948)
		(width 0.127)
		(layer "In6.Cu")
		(net "SMB_SML1_PMBUS_HSC_SDA_R3")
	)
	(segment
		(start 6.2992 -256.749042)
		(end 3.777742 -254.227584)
		(width 0.127)
		(layer "In6.Cu")
		(net "SMB_SML1_PMBUS_HSC_SDA_R3")
	)
	(segment
		(start 27.939746 -328.894948)
		(end 14.858746 -328.894948)
		(width 0.127)
		(layer "In6.Cu")
		(net "SMB_SML1_PMBUS_HSC_SDA_R3")
	)
	(segment
		(start 3.777742 -174.622206)
		(end 6.731 -171.668948)
		(width 0.127)
		(layer "In6.Cu")
		(net "SMB_SML1_PMBUS_HSC_SDA_R3")
	)
	(segment
		(start 51.943 -396.535148)
		(end 51.943 -389.601202)
		(width 0.127)
		(layer "In6.Cu")
		(net "SMB_SML1_PMBUS_HSC_SDA_R3")
	)
	(segment
		(start 100.08362 -397.383508)
		(end 100.03282 -397.434308)
		(width 0.127)
		(layer "In11.Cu")
		(net "SMB_SML1_PMBUS_HSC_SDA_R3")
	)
	(segment
		(start 5.208016 -54.192932)
		(end 4.35102 -55.049928)
		(width 0.127)
		(layer "In11.Cu")
		(net "SMB_SML1_PMBUS_HSC_SDA_R3")
	)
	(segment
		(start 4.826 -107.787948)
		(end 3.81 -108.803948)
		(width 0.127)
		(layer "In11.Cu")
		(net "SMB_SML1_PMBUS_HSC_SDA_R3")
	)
	(segment
		(start 100.03282 -397.434308)
		(end 97.789492 -397.434308)
		(width 0.127)
		(layer "In11.Cu")
		(net "SMB_SML1_PMBUS_HSC_SDA_R3")
	)
	(segment
		(start 163.039806 -397.708628)
		(end 116.65966 -397.708628)
		(width 0.127)
		(layer "In11.Cu")
		(net "SMB_SML1_PMBUS_HSC_SDA_R3")
	)
	(segment
		(start 4.35102 -55.049928)
		(end 4.35102 -104.441752)
		(width 0.127)
		(layer "In11.Cu")
		(net "SMB_SML1_PMBUS_HSC_SDA_R3")
	)
	(segment
		(start 116.26342 -398.104868)
		(end 111.639096 -398.104868)
		(width 0.127)
		(layer "In11.Cu")
		(net "SMB_SML1_PMBUS_HSC_SDA_R3")
	)
	(segment
		(start 6.14934 -171.668948)
		(end 6.731 -171.668948)
		(width 0.127)
		(layer "In11.Cu")
		(net "SMB_SML1_PMBUS_HSC_SDA_R3")
	)
	(segment
		(start 116.65966 -397.708628)
		(end 116.26342 -398.104868)
		(width 0.127)
		(layer "In11.Cu")
		(net "SMB_SML1_PMBUS_HSC_SDA_R3")
	)
	(segment
		(start 170.772328 -398.661128)
		(end 163.992306 -398.661128)
		(width 0.127)
		(layer "In11.Cu")
		(net "SMB_SML1_PMBUS_HSC_SDA_R3")
	)
	(segment
		(start 171.163488 -399.052288)
		(end 170.772328 -398.661128)
		(width 0.127)
		(layer "In11.Cu")
		(net "SMB_SML1_PMBUS_HSC_SDA_R3")
	)
	(segment
		(start 110.917736 -397.383508)
		(end 100.08362 -397.383508)
		(width 0.127)
		(layer "In11.Cu")
		(net "SMB_SML1_PMBUS_HSC_SDA_R3")
	)
	(segment
		(start 47.95266 -398.658588)
		(end 47.5996 -398.305528)
		(width 0.127)
		(layer "In11.Cu")
		(net "SMB_SML1_PMBUS_HSC_SDA_R3")
	)
	(segment
		(start 163.992306 -398.661128)
		(end 163.039806 -397.708628)
		(width 0.127)
		(layer "In11.Cu")
		(net "SMB_SML1_PMBUS_HSC_SDA_R3")
	)
	(segment
		(start 3.81 -169.329608)
		(end 6.14934 -171.668948)
		(width 0.127)
		(layer "In11.Cu")
		(net "SMB_SML1_PMBUS_HSC_SDA_R3")
	)
	(segment
		(start 3.81 -108.803948)
		(end 3.81 -169.329608)
		(width 0.127)
		(layer "In11.Cu")
		(net "SMB_SML1_PMBUS_HSC_SDA_R3")
	)
	(segment
		(start 97.789492 -397.434308)
		(end 96.565212 -398.658588)
		(width 0.127)
		(layer "In11.Cu")
		(net "SMB_SML1_PMBUS_HSC_SDA_R3")
	)
	(segment
		(start 4.826 -104.916732)
		(end 4.826 -107.787948)
		(width 0.127)
		(layer "In11.Cu")
		(net "SMB_SML1_PMBUS_HSC_SDA_R3")
	)
	(segment
		(start 4.35102 -104.441752)
		(end 4.826 -104.916732)
		(width 0.127)
		(layer "In11.Cu")
		(net "SMB_SML1_PMBUS_HSC_SDA_R3")
	)
	(segment
		(start 7.82193 -54.192932)
		(end 5.208016 -54.192932)
		(width 0.127)
		(layer "In11.Cu")
		(net "SMB_SML1_PMBUS_HSC_SDA_R3")
	)
	(segment
		(start 172.369734 -399.052288)
		(end 171.163488 -399.052288)
		(width 0.127)
		(layer "In11.Cu")
		(net "SMB_SML1_PMBUS_HSC_SDA_R3")
	)
	(segment
		(start 96.565212 -398.658588)
		(end 47.95266 -398.658588)
		(width 0.127)
		(layer "In11.Cu")
		(net "SMB_SML1_PMBUS_HSC_SDA_R3")
	)
	(segment
		(start 111.639096 -398.104868)
		(end 110.917736 -397.383508)
		(width 0.127)
		(layer "In11.Cu")
		(net "SMB_SML1_PMBUS_HSC_SDA_R3")
	)
	(segment
		(start 177.14976 -405.06015)
		(end 177.14976 -407.659078)
		(width 0.12954)
		(layer "F.Cu")
		(net "SMB_SML1_PMBUS_HSC_SCL_R3")
	)
	(segment
		(start 174.891954 -403.606508)
		(end 175.696118 -403.606508)
		(width 0.12954)
		(layer "F.Cu")
		(net "SMB_SML1_PMBUS_HSC_SCL_R3")
	)
	(segment
		(start 7.82193 -56.987948)
		(end 7.82193 -57.750964)
		(width 0.12954)
		(layer "F.Cu")
		(net "SMB_SML1_PMBUS_HSC_SCL_R3")
	)
	(segment
		(start 172.369226 -401.08378)
		(end 174.891954 -403.606508)
		(width 0.12954)
		(layer "F.Cu")
		(net "SMB_SML1_PMBUS_HSC_SCL_R3")
	)
	(segment
		(start 177.14976 -407.659078)
		(end 178.69027 -409.199588)
		(width 0.12954)
		(layer "F.Cu")
		(net "SMB_SML1_PMBUS_HSC_SCL_R3")
	)
	(segment
		(start 175.696118 -403.606508)
		(end 177.14976 -405.06015)
		(width 0.12954)
		(layer "F.Cu")
		(net "SMB_SML1_PMBUS_HSC_SCL_R3")
	)
	(via
		(at 172.369226 -401.08378)
		(size 0.508)
		(drill 0.254)
		(layers "F.Cu" "B.Cu")
		(net "SMB_SML1_PMBUS_HSC_SCL_R3")
	)
	(via
		(at 6.731 -170.906948)
		(size 0.508)
		(drill 0.254)
		(layers "F.Cu" "B.Cu")
		(net "SMB_SML1_PMBUS_HSC_SCL_R3")
	)
	(via
		(at 7.82193 -57.750964)
		(size 0.508)
		(drill 0.254)
		(layers "F.Cu" "B.Cu")
		(net "SMB_SML1_PMBUS_HSC_SCL_R3")
	)
	(via
		(at 48.1584 -397.8402)
		(size 0.508)
		(drill 0.254)
		(layers "F.Cu" "B.Cu")
		(net "SMB_SML1_PMBUS_HSC_SCL_R3")
	)
	(segment
		(start 3.34137 -174.296578)
		(end 6.731 -170.906948)
		(width 0.127)
		(layer "In6.Cu")
		(net "SMB_SML1_PMBUS_HSC_SCL_R3")
	)
	(segment
		(start 5.842 -323.306948)
		(end 5.842 -257.012948)
		(width 0.127)
		(layer "In6.Cu")
		(net "SMB_SML1_PMBUS_HSC_SCL_R3")
	)
	(segment
		(start 3.34137 -254.512318)
		(end 3.34137 -174.296578)
		(width 0.127)
		(layer "In6.Cu")
		(net "SMB_SML1_PMBUS_HSC_SCL_R3")
	)
	(segment
		(start 29.21 -367.502948)
		(end 29.21 -330.926948)
		(width 0.127)
		(layer "In6.Cu")
		(net "SMB_SML1_PMBUS_HSC_SCL_R3")
	)
	(segment
		(start 48.1584 -397.8402)
		(end 48.595788 -397.8402)
		(width 0.127)
		(layer "In6.Cu")
		(net "SMB_SML1_PMBUS_HSC_SCL_R3")
	)
	(segment
		(start 29.21 -330.926948)
		(end 27.686 -329.402948)
		(width 0.127)
		(layer "In6.Cu")
		(net "SMB_SML1_PMBUS_HSC_SCL_R3")
	)
	(segment
		(start 10.795 -325.465948)
		(end 8.001 -325.465948)
		(width 0.127)
		(layer "In6.Cu")
		(net "SMB_SML1_PMBUS_HSC_SCL_R3")
	)
	(segment
		(start 8.001 -325.465948)
		(end 5.842 -323.306948)
		(width 0.127)
		(layer "In6.Cu")
		(net "SMB_SML1_PMBUS_HSC_SCL_R3")
	)
	(segment
		(start 51.435 -389.727948)
		(end 29.21 -367.502948)
		(width 0.127)
		(layer "In6.Cu")
		(net "SMB_SML1_PMBUS_HSC_SCL_R3")
	)
	(segment
		(start 51.435 -395.000988)
		(end 51.435 -389.727948)
		(width 0.127)
		(layer "In6.Cu")
		(net "SMB_SML1_PMBUS_HSC_SCL_R3")
	)
	(segment
		(start 14.732 -329.402948)
		(end 10.795 -325.465948)
		(width 0.127)
		(layer "In6.Cu")
		(net "SMB_SML1_PMBUS_HSC_SCL_R3")
	)
	(segment
		(start 5.842 -257.012948)
		(end 3.34137 -254.512318)
		(width 0.127)
		(layer "In6.Cu")
		(net "SMB_SML1_PMBUS_HSC_SCL_R3")
	)
	(segment
		(start 48.595788 -397.8402)
		(end 51.435 -395.000988)
		(width 0.127)
		(layer "In6.Cu")
		(net "SMB_SML1_PMBUS_HSC_SCL_R3")
	)
	(segment
		(start 27.686 -329.402948)
		(end 14.732 -329.402948)
		(width 0.127)
		(layer "In6.Cu")
		(net "SMB_SML1_PMBUS_HSC_SCL_R3")
	)
	(segment
		(start 164.158676 -398.216628)
		(end 163.218876 -397.276828)
		(width 0.127)
		(layer "In11.Cu")
		(net "SMB_SML1_PMBUS_HSC_SCL_R3")
	)
	(segment
		(start 48.421798 -398.103598)
		(end 48.1584 -397.8402)
		(width 0.127)
		(layer "In11.Cu")
		(net "SMB_SML1_PMBUS_HSC_SCL_R3")
	)
	(segment
		(start 163.218876 -397.276828)
		(end 117.33022 -397.276828)
		(width 0.127)
		(layer "In11.Cu")
		(net "SMB_SML1_PMBUS_HSC_SCL_R3")
	)
	(segment
		(start 96.485202 -398.103598)
		(end 48.421798 -398.103598)
		(width 0.127)
		(layer "In11.Cu")
		(net "SMB_SML1_PMBUS_HSC_SCL_R3")
	)
	(segment
		(start 111.096806 -396.951708)
		(end 97.637092 -396.951708)
		(width 0.127)
		(layer "In11.Cu")
		(net "SMB_SML1_PMBUS_HSC_SCL_R3")
	)
	(segment
		(start 5.998464 -170.906948)
		(end 6.731 -170.906948)
		(width 0.127)
		(layer "In11.Cu")
		(net "SMB_SML1_PMBUS_HSC_SCL_R3")
	)
	(segment
		(start 4.2418 -108.983018)
		(end 4.2418 -169.150284)
		(width 0.127)
		(layer "In11.Cu")
		(net "SMB_SML1_PMBUS_HSC_SCL_R3")
	)
	(segment
		(start 111.818166 -397.673068)
		(end 111.096806 -396.951708)
		(width 0.127)
		(layer "In11.Cu")
		(net "SMB_SML1_PMBUS_HSC_SCL_R3")
	)
	(segment
		(start 173.18228 -398.923764)
		(end 172.713396 -398.45488)
		(width 0.127)
		(layer "In11.Cu")
		(net "SMB_SML1_PMBUS_HSC_SCL_R3")
	)
	(segment
		(start 173.18228 -400.270726)
		(end 173.18228 -398.923764)
		(width 0.127)
		(layer "In11.Cu")
		(net "SMB_SML1_PMBUS_HSC_SCL_R3")
	)
	(segment
		(start 172.369226 -401.08378)
		(end 173.18228 -400.270726)
		(width 0.127)
		(layer "In11.Cu")
		(net "SMB_SML1_PMBUS_HSC_SCL_R3")
	)
	(segment
		(start 117.33022 -397.276828)
		(end 117.02542 -396.972028)
		(width 0.127)
		(layer "In11.Cu")
		(net "SMB_SML1_PMBUS_HSC_SCL_R3")
	)
	(segment
		(start 172.713396 -398.45488)
		(end 171.62272 -398.45488)
		(width 0.127)
		(layer "In11.Cu")
		(net "SMB_SML1_PMBUS_HSC_SCL_R3")
	)
	(segment
		(start 171.62272 -398.45488)
		(end 171.384468 -398.216628)
		(width 0.127)
		(layer "In11.Cu")
		(net "SMB_SML1_PMBUS_HSC_SCL_R3")
	)
	(segment
		(start 5.2578 -104.737662)
		(end 5.2578 -107.967018)
		(width 0.127)
		(layer "In11.Cu")
		(net "SMB_SML1_PMBUS_HSC_SCL_R3")
	)
	(segment
		(start 4.2418 -169.150284)
		(end 5.998464 -170.906948)
		(width 0.127)
		(layer "In11.Cu")
		(net "SMB_SML1_PMBUS_HSC_SCL_R3")
	)
	(segment
		(start 6.18109 -57.750964)
		(end 4.78282 -59.149234)
		(width 0.127)
		(layer "In11.Cu")
		(net "SMB_SML1_PMBUS_HSC_SCL_R3")
	)
	(segment
		(start 117.02542 -396.972028)
		(end 114.543586 -396.972028)
		(width 0.127)
		(layer "In11.Cu")
		(net "SMB_SML1_PMBUS_HSC_SCL_R3")
	)
	(segment
		(start 171.384468 -398.216628)
		(end 164.158676 -398.216628)
		(width 0.127)
		(layer "In11.Cu")
		(net "SMB_SML1_PMBUS_HSC_SCL_R3")
	)
	(segment
		(start 5.2578 -107.967018)
		(end 4.2418 -108.983018)
		(width 0.127)
		(layer "In11.Cu")
		(net "SMB_SML1_PMBUS_HSC_SCL_R3")
	)
	(segment
		(start 114.543586 -396.972028)
		(end 113.842546 -397.673068)
		(width 0.127)
		(layer "In11.Cu")
		(net "SMB_SML1_PMBUS_HSC_SCL_R3")
	)
	(segment
		(start 113.842546 -397.673068)
		(end 111.818166 -397.673068)
		(width 0.127)
		(layer "In11.Cu")
		(net "SMB_SML1_PMBUS_HSC_SCL_R3")
	)
	(segment
		(start 97.637092 -396.951708)
		(end 96.485202 -398.103598)
		(width 0.127)
		(layer "In11.Cu")
		(net "SMB_SML1_PMBUS_HSC_SCL_R3")
	)
	(segment
		(start 4.78282 -104.262682)
		(end 5.2578 -104.737662)
		(width 0.127)
		(layer "In11.Cu")
		(net "SMB_SML1_PMBUS_HSC_SCL_R3")
	)
	(segment
		(start 7.82193 -57.750964)
		(end 6.18109 -57.750964)
		(width 0.127)
		(layer "In11.Cu")
		(net "SMB_SML1_PMBUS_HSC_SCL_R3")
	)
	(segment
		(start 4.78282 -59.149234)
		(end 4.78282 -104.262682)
		(width 0.127)
		(layer "In11.Cu")
		(net "SMB_SML1_PMBUS_HSC_SCL_R3")
	)
	(segment
		(start 123.53798 -66.789808)
		(end 123.897644 -67.149472)
		(width 0.12954)
		(layer "F.Cu")
		(net "TP_PLD_CONN_P4")
	)
	(segment
		(start 123.897644 -70.187566)
		(end 124.46 -70.749922)
		(width 0.12954)
		(layer "F.Cu")
		(net "TP_PLD_CONN_P4")
	)
	(segment
		(start 123.897644 -67.149472)
		(end 123.897644 -70.187566)
		(width 0.12954)
		(layer "F.Cu")
		(net "TP_PLD_CONN_P4")
	)
	(via
		(at 123.53798 -66.789808)
		(size 0.762)
		(drill 0.381)
		(layers "F.Cu" "B.Cu")
		(net "TP_PLD_CONN_P4")
	)
	(segment
		(start 170.955716 -121.775474)
		(end 170.555666 -122.175524)
		(width 0.12954)
		(layer "F.Cu")
		(net "NC_FPGA_PT44B")
	)
	(via
		(at 170.555666 -122.175524)
		(size 0.4572)
		(drill 0.254)
		(layers "F.Cu" "B.Cu")
		(net "NC_FPGA_PT44B")
	)
	(segment
		(start 166.71036 -120.975374)
		(end 166.511478 -121.174256)
		(width 0.12954)
		(layer "F.Cu")
		(net "NC_FPGA_PT44A")
	)
	(segment
		(start 170.155616 -120.975374)
		(end 166.71036 -120.975374)
		(width 0.12954)
		(layer "F.Cu")
		(net "NC_FPGA_PT44A")
	)
	(via
		(at 166.511478 -121.174256)
		(size 0.762)
		(drill 0.381)
		(layers "F.Cu" "B.Cu")
		(net "NC_FPGA_PT44A")
	)
	(segment
		(start 174.955708 -116.175536)
		(end 174.555658 -116.575586)
		(width 0.12954)
		(layer "F.Cu")
		(net "NC_FPGA_PT42D")
	)
	(via
		(at 174.555658 -116.575586)
		(size 0.4572)
		(drill 0.254)
		(layers "F.Cu" "B.Cu")
		(net "NC_FPGA_PT42D")
	)
	(segment
		(start 172.555662 -118.575328)
		(end 172.155612 -118.975378)
		(width 0.12954)
		(layer "F.Cu")
		(net "NC_FPGA_PT41D")
	)
	(via
		(at 172.155612 -118.975378)
		(size 0.4572)
		(drill 0.254)
		(layers "F.Cu" "B.Cu")
		(net "NC_FPGA_PT41D")
	)
	(segment
		(start 177.355754 -119.375428)
		(end 176.955704 -119.775478)
		(width 0.12954)
		(layer "F.Cu")
		(net "NC_FPGA_PR13A")
	)
	(via
		(at 176.955704 -119.775478)
		(size 0.4572)
		(drill 0.254)
		(layers "F.Cu" "B.Cu")
		(net "NC_FPGA_PR13A")
	)
	(segment
		(start 184.555638 -108.175552)
		(end 184.955688 -107.775502)
		(width 0.12954)
		(layer "F.Cu")
		(net "NC_FPGA_PB7D")
	)
	(via
		(at 184.955688 -107.775502)
		(size 0.4572)
		(drill 0.254)
		(layers "F.Cu" "B.Cu")
		(net "NC_FPGA_PB7D")
	)
	(segment
		(start 187.292488 -121.363232)
		(end 189.223142 -123.293886)
		(width 0.12954)
		(layer "F.Cu")
		(net "NC_FPGA_PB46B")
	)
	(segment
		(start 196.212714 -127.639572)
		(end 196.212714 -128.054354)
		(width 0.12954)
		(layer "F.Cu")
		(net "NC_FPGA_PB46B")
	)
	(segment
		(start 189.223142 -123.293886)
		(end 189.956186 -123.293886)
		(width 0.12954)
		(layer "F.Cu")
		(net "NC_FPGA_PB46B")
	)
	(segment
		(start 191.70777 -126.228602)
		(end 191.859916 -126.595886)
		(width 0.12954)
		(layer "F.Cu")
		(net "NC_FPGA_PB46B")
	)
	(segment
		(start 195.884546 -128.382522)
		(end 195.884546 -133.22554)
		(width 0.12954)
		(layer "F.Cu")
		(net "NC_FPGA_PB46B")
	)
	(segment
		(start 186.155584 -120.975374)
		(end 186.543442 -121.363232)
		(width 0.12954)
		(layer "F.Cu")
		(net "NC_FPGA_PB46B")
	)
	(segment
		(start 195.470018 -126.896876)
		(end 196.212714 -127.639572)
		(width 0.12954)
		(layer "F.Cu")
		(net "NC_FPGA_PB46B")
	)
	(segment
		(start 186.543442 -121.363232)
		(end 187.292488 -121.363232)
		(width 0.12954)
		(layer "F.Cu")
		(net "NC_FPGA_PB46B")
	)
	(segment
		(start 195.884546 -133.22554)
		(end 195.57619 -133.533896)
		(width 0.12954)
		(layer "F.Cu")
		(net "NC_FPGA_PB46B")
	)
	(segment
		(start 191.859916 -126.595886)
		(end 192.160906 -126.896876)
		(width 0.12954)
		(layer "F.Cu")
		(net "NC_FPGA_PB46B")
	)
	(segment
		(start 189.956186 -123.293886)
		(end 191.70777 -125.04547)
		(width 0.12954)
		(layer "F.Cu")
		(net "NC_FPGA_PB46B")
	)
	(segment
		(start 196.212714 -128.054354)
		(end 195.884546 -128.382522)
		(width 0.12954)
		(layer "F.Cu")
		(net "NC_FPGA_PB46B")
	)
	(segment
		(start 191.70777 -125.04547)
		(end 191.70777 -126.228602)
		(width 0.12954)
		(layer "F.Cu")
		(net "NC_FPGA_PB46B")
	)
	(segment
		(start 192.160906 -126.896876)
		(end 195.470018 -126.896876)
		(width 0.12954)
		(layer "F.Cu")
		(net "NC_FPGA_PB46B")
	)
	(via
		(at 195.57619 -133.533896)
		(size 0.762)
		(drill 0.381)
		(layers "F.Cu" "B.Cu")
		(net "NC_FPGA_PB46B")
	)
	(segment
		(start 326.875902 -41.745408)
		(end 327.14946 -41.745408)
		(width 0.0889)
		(layer "F.Cu")
		(net "SMB_SML1_PMBUS_3V3AUX_PCH_SDA_1")
	)
	(segment
		(start 327.14946 -41.745408)
		(end 327.295256 -41.619424)
		(width 0.0889)
		(layer "F.Cu")
		(net "SMB_SML1_PMBUS_3V3AUX_PCH_SDA_1")
	)
	(segment
		(start 326.296274 -41.701212)
		(end 326.533764 -41.654222)
		(width 0.0889)
		(layer "F.Cu")
		(net "SMB_SML1_PMBUS_3V3AUX_PCH_SDA_1")
	)
	(segment
		(start 310.727598 -31.22803)
		(end 312.583322 -31.22803)
		(width 0.12954)
		(layer "F.Cu")
		(net "SMB_SML1_PMBUS_3V3AUX_PCH_SDA_1")
	)
	(segment
		(start 316.76721 -34.250122)
		(end 318.485266 -35.968178)
		(width 0.12954)
		(layer "F.Cu")
		(net "SMB_SML1_PMBUS_3V3AUX_PCH_SDA_1")
	)
	(segment
		(start 310.105552 -31.850076)
		(end 310.727598 -31.22803)
		(width 0.12954)
		(layer "F.Cu")
		(net "SMB_SML1_PMBUS_3V3AUX_PCH_SDA_1")
	)
	(segment
		(start 327.467722 -41.446958)
		(end 327.829926 -41.446958)
		(width 0.0889)
		(layer "F.Cu")
		(net "SMB_SML1_PMBUS_3V3AUX_PCH_SDA_1")
	)
	(segment
		(start 289.022282 -33.115504)
		(end 293.268908 -37.36213)
		(width 0.12954)
		(layer "F.Cu")
		(net "SMB_SML1_PMBUS_3V3AUX_PCH_SDA_1")
	)
	(segment
		(start 312.583322 -31.22803)
		(end 313.266074 -31.910782)
		(width 0.12954)
		(layer "F.Cu")
		(net "SMB_SML1_PMBUS_3V3AUX_PCH_SDA_1")
	)
	(segment
		(start 326.754998 -41.66489)
		(end 326.875902 -41.745408)
		(width 0.0889)
		(layer "F.Cu")
		(net "SMB_SML1_PMBUS_3V3AUX_PCH_SDA_1")
	)
	(segment
		(start 323.172836 -39.332408)
		(end 323.416676 -39.576248)
		(width 0.0889)
		(layer "F.Cu")
		(net "SMB_SML1_PMBUS_3V3AUX_PCH_SDA_1")
	)
	(segment
		(start 304.27168 -37.36213)
		(end 305.193954 -36.439856)
		(width 0.12954)
		(layer "F.Cu")
		(net "SMB_SML1_PMBUS_3V3AUX_PCH_SDA_1")
	)
	(segment
		(start 323.416676 -39.576248)
		(end 323.604636 -39.576248)
		(width 0.0889)
		(layer "F.Cu")
		(net "SMB_SML1_PMBUS_3V3AUX_PCH_SDA_1")
	)
	(segment
		(start 327.295256 -41.619424)
		(end 327.467722 -41.446958)
		(width 0.0889)
		(layer "F.Cu")
		(net "SMB_SML1_PMBUS_3V3AUX_PCH_SDA_1")
	)
	(segment
		(start 306.22367 -31.850076)
		(end 310.105552 -31.850076)
		(width 0.12954)
		(layer "F.Cu")
		(net "SMB_SML1_PMBUS_3V3AUX_PCH_SDA_1")
	)
	(segment
		(start 326.533764 -41.654222)
		(end 326.754998 -41.66489)
		(width 0.0889)
		(layer "F.Cu")
		(net "SMB_SML1_PMBUS_3V3AUX_PCH_SDA_1")
	)
	(segment
		(start 325.7296 -41.701212)
		(end 326.296274 -41.701212)
		(width 0.0889)
		(layer "F.Cu")
		(net "SMB_SML1_PMBUS_3V3AUX_PCH_SDA_1")
	)
	(segment
		(start 279.56002 -33.115504)
		(end 289.022282 -33.115504)
		(width 0.12954)
		(layer "F.Cu")
		(net "SMB_SML1_PMBUS_3V3AUX_PCH_SDA_1")
	)
	(segment
		(start 305.193954 -36.439856)
		(end 305.193954 -32.879792)
		(width 0.12954)
		(layer "F.Cu")
		(net "SMB_SML1_PMBUS_3V3AUX_PCH_SDA_1")
	)
	(segment
		(start 313.266074 -31.910782)
		(end 316.76721 -34.250122)
		(width 0.12954)
		(layer "F.Cu")
		(net "SMB_SML1_PMBUS_3V3AUX_PCH_SDA_1")
	)
	(segment
		(start 323.604636 -39.576248)
		(end 325.7296 -41.701212)
		(width 0.0889)
		(layer "F.Cu")
		(net "SMB_SML1_PMBUS_3V3AUX_PCH_SDA_1")
	)
	(segment
		(start 318.485266 -35.968178)
		(end 319.242948 -35.968178)
		(width 0.12954)
		(layer "F.Cu")
		(net "SMB_SML1_PMBUS_3V3AUX_PCH_SDA_1")
	)
	(segment
		(start 319.242948 -35.968178)
		(end 321.555618 -38.280848)
		(width 0.12954)
		(layer "F.Cu")
		(net "SMB_SML1_PMBUS_3V3AUX_PCH_SDA_1")
	)
	(segment
		(start 293.268908 -37.36213)
		(end 304.27168 -37.36213)
		(width 0.12954)
		(layer "F.Cu")
		(net "SMB_SML1_PMBUS_3V3AUX_PCH_SDA_1")
	)
	(segment
		(start 305.193954 -32.879792)
		(end 306.22367 -31.850076)
		(width 0.12954)
		(layer "F.Cu")
		(net "SMB_SML1_PMBUS_3V3AUX_PCH_SDA_1")
	)
	(segment
		(start 321.555618 -38.280848)
		(end 322.121276 -38.280848)
		(width 0.12954)
		(layer "F.Cu")
		(net "SMB_SML1_PMBUS_3V3AUX_PCH_SDA_1")
	)
	(segment
		(start 322.121276 -38.280848)
		(end 323.172836 -39.332408)
		(width 0.12954)
		(layer "F.Cu")
		(net "SMB_SML1_PMBUS_3V3AUX_PCH_SDA_1")
	)
	(via
		(at 279.56002 -33.115504)
		(size 0.508)
		(drill 0.254)
		(layers "F.Cu" "B.Cu")
		(net "SMB_SML1_PMBUS_3V3AUX_PCH_SDA_1")
	)
	(via
		(at 178.562 -21.554948)
		(size 0.508)
		(drill 0.254)
		(layers "F.Cu" "B.Cu")
		(net "SMB_SML1_PMBUS_3V3AUX_PCH_SDA_1")
	)
	(segment
		(start 178.562 -21.554948)
		(end 178.47056 -21.463508)
		(width 0.12954)
		(layer "B.Cu")
		(net "SMB_SML1_PMBUS_3V3AUX_PCH_SDA_1")
	)
	(segment
		(start 178.47056 -21.463508)
		(end 178.47056 -20.141438)
		(width 0.12954)
		(layer "B.Cu")
		(net "SMB_SML1_PMBUS_3V3AUX_PCH_SDA_1")
	)
	(segment
		(start 178.47056 -20.141438)
		(end 178.689 -19.922998)
		(width 0.12954)
		(layer "B.Cu")
		(net "SMB_SML1_PMBUS_3V3AUX_PCH_SDA_1")
	)
	(segment
		(start 179.764436 -21.689568)
		(end 179.376324 -21.301456)
		(width 0.127)
		(layer "In13.Cu")
		(net "SMB_SML1_PMBUS_3V3AUX_PCH_SDA_1")
	)
	(segment
		(start 231.709468 -45.277024)
		(end 231.709468 -44.769024)
		(width 0.127)
		(layer "In13.Cu")
		(net "SMB_SML1_PMBUS_3V3AUX_PCH_SDA_1")
	)
	(segment
		(start 219.45092 -35.785552)
		(end 219.45092 -32.045148)
		(width 0.127)
		(layer "In13.Cu")
		(net "SMB_SML1_PMBUS_3V3AUX_PCH_SDA_1")
	)
	(segment
		(start 266.923266 -36.700968)
		(end 266.923266 -42.793158)
		(width 0.127)
		(layer "In13.Cu")
		(net "SMB_SML1_PMBUS_3V3AUX_PCH_SDA_1")
	)
	(segment
		(start 267.26896 -36.355274)
		(end 266.923266 -36.700968)
		(width 0.127)
		(layer "In13.Cu")
		(net "SMB_SML1_PMBUS_3V3AUX_PCH_SDA_1")
	)
	(segment
		(start 277.108666 -34.260282)
		(end 276.1996 -35.169348)
		(width 0.127)
		(layer "In13.Cu")
		(net "SMB_SML1_PMBUS_3V3AUX_PCH_SDA_1")
	)
	(segment
		(start 193.1162 -23.205948)
		(end 191.8462 -21.935948)
		(width 0.127)
		(layer "In13.Cu")
		(net "SMB_SML1_PMBUS_3V3AUX_PCH_SDA_1")
	)
	(segment
		(start 223.990916 -40.325548)
		(end 219.45092 -35.785552)
		(width 0.127)
		(layer "In13.Cu")
		(net "SMB_SML1_PMBUS_3V3AUX_PCH_SDA_1")
	)
	(segment
		(start 251.804932 -42.25798)
		(end 250.536964 -43.525948)
		(width 0.127)
		(layer "In13.Cu")
		(net "SMB_SML1_PMBUS_3V3AUX_PCH_SDA_1")
	)
	(segment
		(start 270.8148 -35.169348)
		(end 269.628874 -36.355274)
		(width 0.127)
		(layer "In13.Cu")
		(net "SMB_SML1_PMBUS_3V3AUX_PCH_SDA_1")
	)
	(segment
		(start 219.45092 -32.045148)
		(end 217.87612 -30.470348)
		(width 0.127)
		(layer "In13.Cu")
		(net "SMB_SML1_PMBUS_3V3AUX_PCH_SDA_1")
	)
	(segment
		(start 254.525018 -42.601642)
		(end 253.15926 -42.601642)
		(width 0.127)
		(layer "In13.Cu")
		(net "SMB_SML1_PMBUS_3V3AUX_PCH_SDA_1")
	)
	(segment
		(start 232.295446 -47.335948)
		(end 231.709468 -46.74997)
		(width 0.127)
		(layer "In13.Cu")
		(net "SMB_SML1_PMBUS_3V3AUX_PCH_SDA_1")
	)
	(segment
		(start 203.718414 -30.470348)
		(end 202.283822 -31.90494)
		(width 0.127)
		(layer "In13.Cu")
		(net "SMB_SML1_PMBUS_3V3AUX_PCH_SDA_1")
	)
	(segment
		(start 231.709468 -46.293024)
		(end 231.836468 -46.166024)
		(width 0.127)
		(layer "In13.Cu")
		(net "SMB_SML1_PMBUS_3V3AUX_PCH_SDA_1")
	)
	(segment
		(start 232.61828 -44.515024)
		(end 232.61828 -44.007024)
		(width 0.127)
		(layer "In13.Cu")
		(net "SMB_SML1_PMBUS_3V3AUX_PCH_SDA_1")
	)
	(segment
		(start 231.709468 -43.753024)
		(end 231.709468 -41.879012)
		(width 0.127)
		(layer "In13.Cu")
		(net "SMB_SML1_PMBUS_3V3AUX_PCH_SDA_1")
	)
	(segment
		(start 250.536964 -43.525948)
		(end 248.2088 -43.525948)
		(width 0.127)
		(layer "In13.Cu")
		(net "SMB_SML1_PMBUS_3V3AUX_PCH_SDA_1")
	)
	(segment
		(start 231.836468 -44.642024)
		(end 232.49128 -44.642024)
		(width 0.127)
		(layer "In13.Cu")
		(net "SMB_SML1_PMBUS_3V3AUX_PCH_SDA_1")
	)
	(segment
		(start 232.61828 -44.007024)
		(end 232.49128 -43.880024)
		(width 0.127)
		(layer "In13.Cu")
		(net "SMB_SML1_PMBUS_3V3AUX_PCH_SDA_1")
	)
	(segment
		(start 261.2263 -43.259248)
		(end 260.225032 -42.25798)
		(width 0.127)
		(layer "In13.Cu")
		(net "SMB_SML1_PMBUS_3V3AUX_PCH_SDA_1")
	)
	(segment
		(start 202.283822 -31.90494)
		(end 198.665592 -31.90494)
		(width 0.127)
		(layer "In13.Cu")
		(net "SMB_SML1_PMBUS_3V3AUX_PCH_SDA_1")
	)
	(segment
		(start 193.1162 -26.355548)
		(end 193.1162 -23.205948)
		(width 0.127)
		(layer "In13.Cu")
		(net "SMB_SML1_PMBUS_3V3AUX_PCH_SDA_1")
	)
	(segment
		(start 184.404 -21.173948)
		(end 182.01132 -21.173948)
		(width 0.127)
		(layer "In13.Cu")
		(net "SMB_SML1_PMBUS_3V3AUX_PCH_SDA_1")
	)
	(segment
		(start 268.28115 -36.355274)
		(end 267.26896 -36.355274)
		(width 0.127)
		(layer "In13.Cu")
		(net "SMB_SML1_PMBUS_3V3AUX_PCH_SDA_1")
	)
	(segment
		(start 254.86868 -42.25798)
		(end 254.525018 -42.601642)
		(width 0.127)
		(layer "In13.Cu")
		(net "SMB_SML1_PMBUS_3V3AUX_PCH_SDA_1")
	)
	(segment
		(start 232.49128 -43.880024)
		(end 231.836468 -43.880024)
		(width 0.127)
		(layer "In13.Cu")
		(net "SMB_SML1_PMBUS_3V3AUX_PCH_SDA_1")
	)
	(segment
		(start 233.956098 -47.335948)
		(end 232.295446 -47.335948)
		(width 0.127)
		(layer "In13.Cu")
		(net "SMB_SML1_PMBUS_3V3AUX_PCH_SDA_1")
	)
	(segment
		(start 185.166 -21.935948)
		(end 184.404 -21.173948)
		(width 0.127)
		(layer "In13.Cu")
		(net "SMB_SML1_PMBUS_3V3AUX_PCH_SDA_1")
	)
	(segment
		(start 231.836468 -46.166024)
		(end 232.49128 -46.166024)
		(width 0.127)
		(layer "In13.Cu")
		(net "SMB_SML1_PMBUS_3V3AUX_PCH_SDA_1")
	)
	(segment
		(start 198.665592 -31.90494)
		(end 193.1162 -26.355548)
		(width 0.127)
		(layer "In13.Cu")
		(net "SMB_SML1_PMBUS_3V3AUX_PCH_SDA_1")
	)
	(segment
		(start 179.376324 -21.301456)
		(end 178.815492 -21.301456)
		(width 0.127)
		(layer "In13.Cu")
		(net "SMB_SML1_PMBUS_3V3AUX_PCH_SDA_1")
	)
	(segment
		(start 245.97614 -45.758608)
		(end 235.533438 -45.758608)
		(width 0.127)
		(layer "In13.Cu")
		(net "SMB_SML1_PMBUS_3V3AUX_PCH_SDA_1")
	)
	(segment
		(start 231.709468 -46.74997)
		(end 231.709468 -46.293024)
		(width 0.127)
		(layer "In13.Cu")
		(net "SMB_SML1_PMBUS_3V3AUX_PCH_SDA_1")
	)
	(segment
		(start 231.709468 -44.769024)
		(end 231.836468 -44.642024)
		(width 0.127)
		(layer "In13.Cu")
		(net "SMB_SML1_PMBUS_3V3AUX_PCH_SDA_1")
	)
	(segment
		(start 278.415242 -34.260282)
		(end 277.108666 -34.260282)
		(width 0.127)
		(layer "In13.Cu")
		(net "SMB_SML1_PMBUS_3V3AUX_PCH_SDA_1")
	)
	(segment
		(start 231.836468 -45.404024)
		(end 231.709468 -45.277024)
		(width 0.127)
		(layer "In13.Cu")
		(net "SMB_SML1_PMBUS_3V3AUX_PCH_SDA_1")
	)
	(segment
		(start 231.836468 -43.880024)
		(end 231.709468 -43.753024)
		(width 0.127)
		(layer "In13.Cu")
		(net "SMB_SML1_PMBUS_3V3AUX_PCH_SDA_1")
	)
	(segment
		(start 269.628874 -36.355274)
		(end 268.28115 -36.355274)
		(width 0.127)
		(layer "In13.Cu")
		(net "SMB_SML1_PMBUS_3V3AUX_PCH_SDA_1")
	)
	(segment
		(start 217.87612 -30.470348)
		(end 203.718414 -30.470348)
		(width 0.127)
		(layer "In13.Cu")
		(net "SMB_SML1_PMBUS_3V3AUX_PCH_SDA_1")
	)
	(segment
		(start 232.61828 -45.531024)
		(end 232.49128 -45.404024)
		(width 0.127)
		(layer "In13.Cu")
		(net "SMB_SML1_PMBUS_3V3AUX_PCH_SDA_1")
	)
	(segment
		(start 231.709468 -41.879012)
		(end 230.156004 -40.325548)
		(width 0.127)
		(layer "In13.Cu")
		(net "SMB_SML1_PMBUS_3V3AUX_PCH_SDA_1")
	)
	(segment
		(start 266.923266 -42.793158)
		(end 266.457176 -43.259248)
		(width 0.127)
		(layer "In13.Cu")
		(net "SMB_SML1_PMBUS_3V3AUX_PCH_SDA_1")
	)
	(segment
		(start 191.8462 -21.935948)
		(end 185.166 -21.935948)
		(width 0.127)
		(layer "In13.Cu")
		(net "SMB_SML1_PMBUS_3V3AUX_PCH_SDA_1")
	)
	(segment
		(start 232.61828 -46.039024)
		(end 232.61828 -45.531024)
		(width 0.127)
		(layer "In13.Cu")
		(net "SMB_SML1_PMBUS_3V3AUX_PCH_SDA_1")
	)
	(segment
		(start 253.15926 -42.601642)
		(end 252.815598 -42.25798)
		(width 0.127)
		(layer "In13.Cu")
		(net "SMB_SML1_PMBUS_3V3AUX_PCH_SDA_1")
	)
	(segment
		(start 260.225032 -42.25798)
		(end 254.86868 -42.25798)
		(width 0.127)
		(layer "In13.Cu")
		(net "SMB_SML1_PMBUS_3V3AUX_PCH_SDA_1")
	)
	(segment
		(start 181.4957 -21.689568)
		(end 179.764436 -21.689568)
		(width 0.127)
		(layer "In13.Cu")
		(net "SMB_SML1_PMBUS_3V3AUX_PCH_SDA_1")
	)
	(segment
		(start 178.815492 -21.301456)
		(end 178.562 -21.554948)
		(width 0.127)
		(layer "In13.Cu")
		(net "SMB_SML1_PMBUS_3V3AUX_PCH_SDA_1")
	)
	(segment
		(start 232.49128 -44.642024)
		(end 232.61828 -44.515024)
		(width 0.127)
		(layer "In13.Cu")
		(net "SMB_SML1_PMBUS_3V3AUX_PCH_SDA_1")
	)
	(segment
		(start 252.815598 -42.25798)
		(end 251.804932 -42.25798)
		(width 0.127)
		(layer "In13.Cu")
		(net "SMB_SML1_PMBUS_3V3AUX_PCH_SDA_1")
	)
	(segment
		(start 276.1996 -35.169348)
		(end 270.8148 -35.169348)
		(width 0.127)
		(layer "In13.Cu")
		(net "SMB_SML1_PMBUS_3V3AUX_PCH_SDA_1")
	)
	(segment
		(start 266.457176 -43.259248)
		(end 261.2263 -43.259248)
		(width 0.127)
		(layer "In13.Cu")
		(net "SMB_SML1_PMBUS_3V3AUX_PCH_SDA_1")
	)
	(segment
		(start 232.49128 -45.404024)
		(end 231.836468 -45.404024)
		(width 0.127)
		(layer "In13.Cu")
		(net "SMB_SML1_PMBUS_3V3AUX_PCH_SDA_1")
	)
	(segment
		(start 248.2088 -43.525948)
		(end 245.97614 -45.758608)
		(width 0.127)
		(layer "In13.Cu")
		(net "SMB_SML1_PMBUS_3V3AUX_PCH_SDA_1")
	)
	(segment
		(start 279.56002 -33.115504)
		(end 278.415242 -34.260282)
		(width 0.127)
		(layer "In13.Cu")
		(net "SMB_SML1_PMBUS_3V3AUX_PCH_SDA_1")
	)
	(segment
		(start 182.01132 -21.173948)
		(end 181.4957 -21.689568)
		(width 0.127)
		(layer "In13.Cu")
		(net "SMB_SML1_PMBUS_3V3AUX_PCH_SDA_1")
	)
	(segment
		(start 232.49128 -46.166024)
		(end 232.61828 -46.039024)
		(width 0.127)
		(layer "In13.Cu")
		(net "SMB_SML1_PMBUS_3V3AUX_PCH_SDA_1")
	)
	(segment
		(start 235.533438 -45.758608)
		(end 233.956098 -47.335948)
		(width 0.127)
		(layer "In13.Cu")
		(net "SMB_SML1_PMBUS_3V3AUX_PCH_SDA_1")
	)
	(segment
		(start 230.156004 -40.325548)
		(end 223.990916 -40.325548)
		(width 0.127)
		(layer "In13.Cu")
		(net "SMB_SML1_PMBUS_3V3AUX_PCH_SDA_1")
	)
	(segment
		(start 315.768736 -39.050468)
		(end 316.010036 -38.809168)
		(width 0.12954)
		(layer "F.Cu")
		(net "SMB_SML1_PMBUS_3V3AUX_PCH_SCL_1")
	)
	(segment
		(start 290.031932 -35.469068)
		(end 290.21532 -35.469068)
		(width 0.12954)
		(layer "F.Cu")
		(net "SMB_SML1_PMBUS_3V3AUX_PCH_SCL_1")
	)
	(segment
		(start 285.402274 -33.828228)
		(end 285.531814 -33.957768)
		(width 0.12954)
		(layer "F.Cu")
		(net "SMB_SML1_PMBUS_3V3AUX_PCH_SCL_1")
	)
	(segment
		(start 320.438018 -41.847008)
		(end 321.008756 -42.083482)
		(width 0.12954)
		(layer "F.Cu")
		(net "SMB_SML1_PMBUS_3V3AUX_PCH_SCL_1")
	)
	(segment
		(start 282.473654 -34.709608)
		(end 282.603194 -34.839148)
		(width 0.12954)
		(layer "F.Cu")
		(net "SMB_SML1_PMBUS_3V3AUX_PCH_SCL_1")
	)
	(segment
		(start 284.767274 -33.957768)
		(end 284.896814 -33.828228)
		(width 0.12954)
		(layer "F.Cu")
		(net "SMB_SML1_PMBUS_3V3AUX_PCH_SCL_1")
	)
	(segment
		(start 306.92344 -37.963348)
		(end 307.43144 -38.471348)
		(width 0.12954)
		(layer "F.Cu")
		(net "SMB_SML1_PMBUS_3V3AUX_PCH_SCL_1")
	)
	(segment
		(start 288.57448 -33.828228)
		(end 289.491166 -34.744914)
		(width 0.12954)
		(layer "F.Cu")
		(net "SMB_SML1_PMBUS_3V3AUX_PCH_SCL_1")
	)
	(segment
		(start 283.108654 -34.839148)
		(end 283.238194 -34.709608)
		(width 0.12954)
		(layer "F.Cu")
		(net "SMB_SML1_PMBUS_3V3AUX_PCH_SCL_1")
	)
	(segment
		(start 282.344114 -33.828228)
		(end 282.473654 -33.957768)
		(width 0.12954)
		(layer "F.Cu")
		(net "SMB_SML1_PMBUS_3V3AUX_PCH_SCL_1")
	)
	(segment
		(start 322.928234 -43.434)
		(end 323.464682 -43.434)
		(width 0.0889)
		(layer "F.Cu")
		(net "SMB_SML1_PMBUS_3V3AUX_PCH_SCL_1")
	)
	(segment
		(start 284.896814 -33.828228)
		(end 285.402274 -33.828228)
		(width 0.12954)
		(layer "F.Cu")
		(net "SMB_SML1_PMBUS_3V3AUX_PCH_SCL_1")
	)
	(segment
		(start 289.026854 -35.392614)
		(end 289.026854 -35.576002)
		(width 0.12954)
		(layer "F.Cu")
		(net "SMB_SML1_PMBUS_3V3AUX_PCH_SCL_1")
	)
	(segment
		(start 283.238194 -34.709608)
		(end 283.238194 -33.957768)
		(width 0.12954)
		(layer "F.Cu")
		(net "SMB_SML1_PMBUS_3V3AUX_PCH_SCL_1")
	)
	(segment
		(start 314.130182 -38.38829)
		(end 314.79236 -39.050468)
		(width 0.12954)
		(layer "F.Cu")
		(net "SMB_SML1_PMBUS_3V3AUX_PCH_SCL_1")
	)
	(segment
		(start 283.238194 -33.957768)
		(end 283.367734 -33.828228)
		(width 0.12954)
		(layer "F.Cu")
		(net "SMB_SML1_PMBUS_3V3AUX_PCH_SCL_1")
	)
	(segment
		(start 286.166814 -34.839148)
		(end 286.296354 -34.709608)
		(width 0.12954)
		(layer "F.Cu")
		(net "SMB_SML1_PMBUS_3V3AUX_PCH_SCL_1")
	)
	(segment
		(start 307.43144 -38.471348)
		(end 310.7817 -38.471348)
		(width 0.12954)
		(layer "F.Cu")
		(net "SMB_SML1_PMBUS_3V3AUX_PCH_SCL_1")
	)
	(segment
		(start 310.93664 -38.316408)
		(end 312.523632 -38.316408)
		(width 0.12954)
		(layer "F.Cu")
		(net "SMB_SML1_PMBUS_3V3AUX_PCH_SCL_1")
	)
	(segment
		(start 292.7096 -37.963348)
		(end 306.92344 -37.963348)
		(width 0.12954)
		(layer "F.Cu")
		(net "SMB_SML1_PMBUS_3V3AUX_PCH_SCL_1")
	)
	(segment
		(start 312.523632 -38.316408)
		(end 312.595514 -38.38829)
		(width 0.12954)
		(layer "F.Cu")
		(net "SMB_SML1_PMBUS_3V3AUX_PCH_SCL_1")
	)
	(segment
		(start 289.56762 -35.93338)
		(end 290.031932 -35.469068)
		(width 0.12954)
		(layer "F.Cu")
		(net "SMB_SML1_PMBUS_3V3AUX_PCH_SCL_1")
	)
	(segment
		(start 284.002734 -33.957768)
		(end 284.002734 -34.709608)
		(width 0.12954)
		(layer "F.Cu")
		(net "SMB_SML1_PMBUS_3V3AUX_PCH_SCL_1")
	)
	(segment
		(start 282.473654 -33.957768)
		(end 282.473654 -34.709608)
		(width 0.12954)
		(layer "F.Cu")
		(net "SMB_SML1_PMBUS_3V3AUX_PCH_SCL_1")
	)
	(segment
		(start 284.767274 -34.709608)
		(end 284.767274 -33.957768)
		(width 0.12954)
		(layer "F.Cu")
		(net "SMB_SML1_PMBUS_3V3AUX_PCH_SCL_1")
	)
	(segment
		(start 284.132274 -34.839148)
		(end 284.637734 -34.839148)
		(width 0.12954)
		(layer "F.Cu")
		(net "SMB_SML1_PMBUS_3V3AUX_PCH_SCL_1")
	)
	(segment
		(start 280.90876 -33.828228)
		(end 282.344114 -33.828228)
		(width 0.12954)
		(layer "F.Cu")
		(net "SMB_SML1_PMBUS_3V3AUX_PCH_SCL_1")
	)
	(segment
		(start 285.531814 -34.709608)
		(end 285.661354 -34.839148)
		(width 0.12954)
		(layer "F.Cu")
		(net "SMB_SML1_PMBUS_3V3AUX_PCH_SCL_1")
	)
	(segment
		(start 310.7817 -38.471348)
		(end 310.93664 -38.316408)
		(width 0.12954)
		(layer "F.Cu")
		(net "SMB_SML1_PMBUS_3V3AUX_PCH_SCL_1")
	)
	(segment
		(start 322.575174 -43.287696)
		(end 322.928234 -43.434)
		(width 0.0889)
		(layer "F.Cu")
		(net "SMB_SML1_PMBUS_3V3AUX_PCH_SCL_1")
	)
	(segment
		(start 289.026854 -35.576002)
		(end 289.384232 -35.93338)
		(width 0.12954)
		(layer "F.Cu")
		(net "SMB_SML1_PMBUS_3V3AUX_PCH_SCL_1")
	)
	(segment
		(start 289.384232 -35.93338)
		(end 289.56762 -35.93338)
		(width 0.12954)
		(layer "F.Cu")
		(net "SMB_SML1_PMBUS_3V3AUX_PCH_SCL_1")
	)
	(segment
		(start 321.008756 -42.083482)
		(end 321.95643 -43.031156)
		(width 0.12954)
		(layer "F.Cu")
		(net "SMB_SML1_PMBUS_3V3AUX_PCH_SCL_1")
	)
	(segment
		(start 285.661354 -34.839148)
		(end 286.166814 -34.839148)
		(width 0.12954)
		(layer "F.Cu")
		(net "SMB_SML1_PMBUS_3V3AUX_PCH_SCL_1")
	)
	(segment
		(start 284.637734 -34.839148)
		(end 284.767274 -34.709608)
		(width 0.12954)
		(layer "F.Cu")
		(net "SMB_SML1_PMBUS_3V3AUX_PCH_SCL_1")
	)
	(segment
		(start 289.491166 -34.928302)
		(end 289.026854 -35.392614)
		(width 0.12954)
		(layer "F.Cu")
		(net "SMB_SML1_PMBUS_3V3AUX_PCH_SCL_1")
	)
	(segment
		(start 285.531814 -33.957768)
		(end 285.531814 -34.709608)
		(width 0.12954)
		(layer "F.Cu")
		(net "SMB_SML1_PMBUS_3V3AUX_PCH_SCL_1")
	)
	(segment
		(start 289.491166 -34.744914)
		(end 289.491166 -34.928302)
		(width 0.12954)
		(layer "F.Cu")
		(net "SMB_SML1_PMBUS_3V3AUX_PCH_SCL_1")
	)
	(segment
		(start 286.425894 -33.828228)
		(end 288.57448 -33.828228)
		(width 0.12954)
		(layer "F.Cu")
		(net "SMB_SML1_PMBUS_3V3AUX_PCH_SCL_1")
	)
	(segment
		(start 318.608202 -40.693848)
		(end 318.984122 -40.693848)
		(width 0.12954)
		(layer "F.Cu")
		(net "SMB_SML1_PMBUS_3V3AUX_PCH_SCL_1")
	)
	(segment
		(start 323.464682 -43.434)
		(end 323.958966 -43.928284)
		(width 0.0889)
		(layer "F.Cu")
		(net "SMB_SML1_PMBUS_3V3AUX_PCH_SCL_1")
	)
	(segment
		(start 316.723522 -38.809168)
		(end 318.608202 -40.693848)
		(width 0.12954)
		(layer "F.Cu")
		(net "SMB_SML1_PMBUS_3V3AUX_PCH_SCL_1")
	)
	(segment
		(start 314.79236 -39.050468)
		(end 315.768736 -39.050468)
		(width 0.12954)
		(layer "F.Cu")
		(net "SMB_SML1_PMBUS_3V3AUX_PCH_SCL_1")
	)
	(segment
		(start 319.924684 -41.63441)
		(end 320.438018 -41.847008)
		(width 0.12954)
		(layer "F.Cu")
		(net "SMB_SML1_PMBUS_3V3AUX_PCH_SCL_1")
	)
	(segment
		(start 284.002734 -34.709608)
		(end 284.132274 -34.839148)
		(width 0.12954)
		(layer "F.Cu")
		(net "SMB_SML1_PMBUS_3V3AUX_PCH_SCL_1")
	)
	(segment
		(start 323.958966 -43.928284)
		(end 326.565006 -43.928284)
		(width 0.0889)
		(layer "F.Cu")
		(net "SMB_SML1_PMBUS_3V3AUX_PCH_SCL_1")
	)
	(segment
		(start 290.21532 -35.469068)
		(end 292.7096 -37.963348)
		(width 0.12954)
		(layer "F.Cu")
		(net "SMB_SML1_PMBUS_3V3AUX_PCH_SCL_1")
	)
	(segment
		(start 318.984122 -40.693848)
		(end 319.924684 -41.63441)
		(width 0.12954)
		(layer "F.Cu")
		(net "SMB_SML1_PMBUS_3V3AUX_PCH_SCL_1")
	)
	(segment
		(start 286.296354 -33.957768)
		(end 286.425894 -33.828228)
		(width 0.12954)
		(layer "F.Cu")
		(net "SMB_SML1_PMBUS_3V3AUX_PCH_SCL_1")
	)
	(segment
		(start 321.95643 -43.031156)
		(end 322.564252 -43.283124)
		(width 0.12954)
		(layer "F.Cu")
		(net "SMB_SML1_PMBUS_3V3AUX_PCH_SCL_1")
	)
	(segment
		(start 326.565006 -43.928284)
		(end 326.584818 -43.948096)
		(width 0.0889)
		(layer "F.Cu")
		(net "SMB_SML1_PMBUS_3V3AUX_PCH_SCL_1")
	)
	(segment
		(start 282.603194 -34.839148)
		(end 283.108654 -34.839148)
		(width 0.12954)
		(layer "F.Cu")
		(net "SMB_SML1_PMBUS_3V3AUX_PCH_SCL_1")
	)
	(segment
		(start 280.81732 -33.736788)
		(end 280.90876 -33.828228)
		(width 0.12954)
		(layer "F.Cu")
		(net "SMB_SML1_PMBUS_3V3AUX_PCH_SCL_1")
	)
	(segment
		(start 316.010036 -38.809168)
		(end 316.723522 -38.809168)
		(width 0.12954)
		(layer "F.Cu")
		(net "SMB_SML1_PMBUS_3V3AUX_PCH_SCL_1")
	)
	(segment
		(start 322.564252 -43.283124)
		(end 322.575174 -43.287696)
		(width 0.12954)
		(layer "F.Cu")
		(net "SMB_SML1_PMBUS_3V3AUX_PCH_SCL_1")
	)
	(segment
		(start 312.595514 -38.38829)
		(end 314.130182 -38.38829)
		(width 0.12954)
		(layer "F.Cu")
		(net "SMB_SML1_PMBUS_3V3AUX_PCH_SCL_1")
	)
	(segment
		(start 283.873194 -33.828228)
		(end 284.002734 -33.957768)
		(width 0.12954)
		(layer "F.Cu")
		(net "SMB_SML1_PMBUS_3V3AUX_PCH_SCL_1")
	)
	(segment
		(start 283.367734 -33.828228)
		(end 283.873194 -33.828228)
		(width 0.12954)
		(layer "F.Cu")
		(net "SMB_SML1_PMBUS_3V3AUX_PCH_SCL_1")
	)
	(segment
		(start 286.296354 -34.709608)
		(end 286.296354 -33.957768)
		(width 0.12954)
		(layer "F.Cu")
		(net "SMB_SML1_PMBUS_3V3AUX_PCH_SCL_1")
	)
	(via
		(at 280.81732 -33.736788)
		(size 0.508)
		(drill 0.254)
		(layers "F.Cu" "B.Cu")
		(net "SMB_SML1_PMBUS_3V3AUX_PCH_SCL_1")
	)
	(via
		(at 179.16906 -21.791168)
		(size 0.508)
		(drill 0.254)
		(layers "F.Cu" "B.Cu")
		(net "SMB_SML1_PMBUS_3V3AUX_PCH_SCL_1")
	)
	(segment
		(start 179.16906 -21.791168)
		(end 179.16906 -20.458938)
		(width 0.12954)
		(layer "B.Cu")
		(net "SMB_SML1_PMBUS_3V3AUX_PCH_SCL_1")
	)
	(segment
		(start 179.16906 -20.458938)
		(end 179.705 -19.922998)
		(width 0.12954)
		(layer "B.Cu")
		(net "SMB_SML1_PMBUS_3V3AUX_PCH_SCL_1")
	)
	(segment
		(start 190.9191 -22.367748)
		(end 191.12484 -22.573488)
		(width 0.127)
		(layer "In13.Cu")
		(net "SMB_SML1_PMBUS_3V3AUX_PCH_SCL_1")
	)
	(segment
		(start 270.981678 -35.648138)
		(end 270.3576 -36.272216)
		(width 0.127)
		(layer "In13.Cu")
		(net "SMB_SML1_PMBUS_3V3AUX_PCH_SCL_1")
	)
	(segment
		(start 270.3576 -39.358824)
		(end 268.28115 -41.435274)
		(width 0.127)
		(layer "In13.Cu")
		(net "SMB_SML1_PMBUS_3V3AUX_PCH_SCL_1")
	)
	(segment
		(start 179.16906 -21.791168)
		(end 179.74564 -22.367748)
		(width 0.127)
		(layer "In13.Cu")
		(net "SMB_SML1_PMBUS_3V3AUX_PCH_SCL_1")
	)
	(segment
		(start 275.726398 -35.648138)
		(end 275.599398 -35.775138)
		(width 0.127)
		(layer "In13.Cu")
		(net "SMB_SML1_PMBUS_3V3AUX_PCH_SCL_1")
	)
	(segment
		(start 268.28115 -42.821098)
		(end 268.28115 -41.435274)
		(width 0.127)
		(layer "In13.Cu")
		(net "SMB_SML1_PMBUS_3V3AUX_PCH_SCL_1")
	)
	(segment
		(start 252.933454 -43.143678)
		(end 254.612648 -43.143678)
		(width 0.127)
		(layer "In13.Cu")
		(net "SMB_SML1_PMBUS_3V3AUX_PCH_SCL_1")
	)
	(segment
		(start 231.277668 -42.058336)
		(end 231.277668 -47.148496)
		(width 0.127)
		(layer "In13.Cu")
		(net "SMB_SML1_PMBUS_3V3AUX_PCH_SCL_1")
	)
	(segment
		(start 275.472398 -36.827968)
		(end 274.964398 -36.827968)
		(width 0.127)
		(layer "In13.Cu")
		(net "SMB_SML1_PMBUS_3V3AUX_PCH_SCL_1")
	)
	(segment
		(start 275.599398 -36.700968)
		(end 275.472398 -36.827968)
		(width 0.127)
		(layer "In13.Cu")
		(net "SMB_SML1_PMBUS_3V3AUX_PCH_SCL_1")
	)
	(segment
		(start 231.9401 -47.810928)
		(end 234.091988 -47.810928)
		(width 0.127)
		(layer "In13.Cu")
		(net "SMB_SML1_PMBUS_3V3AUX_PCH_SCL_1")
	)
	(segment
		(start 274.837398 -35.775138)
		(end 274.710398 -35.648138)
		(width 0.127)
		(layer "In13.Cu")
		(net "SMB_SML1_PMBUS_3V3AUX_PCH_SCL_1")
	)
	(segment
		(start 219.01912 -32.224218)
		(end 219.01912 -35.964876)
		(width 0.127)
		(layer "In13.Cu")
		(net "SMB_SML1_PMBUS_3V3AUX_PCH_SCL_1")
	)
	(segment
		(start 274.837398 -36.700968)
		(end 274.837398 -35.775138)
		(width 0.127)
		(layer "In13.Cu")
		(net "SMB_SML1_PMBUS_3V3AUX_PCH_SCL_1")
	)
	(segment
		(start 273.186398 -35.648138)
		(end 270.981678 -35.648138)
		(width 0.127)
		(layer "In13.Cu")
		(net "SMB_SML1_PMBUS_3V3AUX_PCH_SCL_1")
	)
	(segment
		(start 275.599398 -35.775138)
		(end 275.599398 -36.700968)
		(width 0.127)
		(layer "In13.Cu")
		(net "SMB_SML1_PMBUS_3V3AUX_PCH_SCL_1")
	)
	(segment
		(start 273.313398 -36.700968)
		(end 273.313398 -35.775138)
		(width 0.127)
		(layer "In13.Cu")
		(net "SMB_SML1_PMBUS_3V3AUX_PCH_SCL_1")
	)
	(segment
		(start 267.3604 -43.741848)
		(end 268.28115 -42.821098)
		(width 0.127)
		(layer "In13.Cu")
		(net "SMB_SML1_PMBUS_3V3AUX_PCH_SCL_1")
	)
	(segment
		(start 255.017778 -42.738548)
		(end 260.0452 -42.738548)
		(width 0.127)
		(layer "In13.Cu")
		(net "SMB_SML1_PMBUS_3V3AUX_PCH_SCL_1")
	)
	(segment
		(start 191.12484 -22.573488)
		(end 191.12484 -25.227788)
		(width 0.127)
		(layer "In13.Cu")
		(net "SMB_SML1_PMBUS_3V3AUX_PCH_SCL_1")
	)
	(segment
		(start 179.74564 -22.367748)
		(end 190.9191 -22.367748)
		(width 0.127)
		(layer "In13.Cu")
		(net "SMB_SML1_PMBUS_3V3AUX_PCH_SCL_1")
	)
	(segment
		(start 248.15546 -44.211748)
		(end 250.54814 -44.211748)
		(width 0.127)
		(layer "In13.Cu")
		(net "SMB_SML1_PMBUS_3V3AUX_PCH_SCL_1")
	)
	(segment
		(start 274.075398 -36.700968)
		(end 273.948398 -36.827968)
		(width 0.127)
		(layer "In13.Cu")
		(net "SMB_SML1_PMBUS_3V3AUX_PCH_SCL_1")
	)
	(segment
		(start 273.948398 -36.827968)
		(end 273.440398 -36.827968)
		(width 0.127)
		(layer "In13.Cu")
		(net "SMB_SML1_PMBUS_3V3AUX_PCH_SCL_1")
	)
	(segment
		(start 219.01912 -35.964876)
		(end 223.862392 -40.808148)
		(width 0.127)
		(layer "In13.Cu")
		(net "SMB_SML1_PMBUS_3V3AUX_PCH_SCL_1")
	)
	(segment
		(start 203.897484 -30.902148)
		(end 217.69705 -30.902148)
		(width 0.127)
		(layer "In13.Cu")
		(net "SMB_SML1_PMBUS_3V3AUX_PCH_SCL_1")
	)
	(segment
		(start 191.12484 -25.227788)
		(end 198.233792 -32.33674)
		(width 0.127)
		(layer "In13.Cu")
		(net "SMB_SML1_PMBUS_3V3AUX_PCH_SCL_1")
	)
	(segment
		(start 202.462892 -32.33674)
		(end 203.897484 -30.902148)
		(width 0.127)
		(layer "In13.Cu")
		(net "SMB_SML1_PMBUS_3V3AUX_PCH_SCL_1")
	)
	(segment
		(start 270.3576 -36.272216)
		(end 270.3576 -39.358824)
		(width 0.127)
		(layer "In13.Cu")
		(net "SMB_SML1_PMBUS_3V3AUX_PCH_SCL_1")
	)
	(segment
		(start 280.81732 -33.736788)
		(end 280.81732 -33.993836)
		(width 0.127)
		(layer "In13.Cu")
		(net "SMB_SML1_PMBUS_3V3AUX_PCH_SCL_1")
	)
	(segment
		(start 274.075398 -35.775138)
		(end 274.075398 -36.700968)
		(width 0.127)
		(layer "In13.Cu")
		(net "SMB_SML1_PMBUS_3V3AUX_PCH_SCL_1")
	)
	(segment
		(start 230.02748 -40.808148)
		(end 231.277668 -42.058336)
		(width 0.127)
		(layer "In13.Cu")
		(net "SMB_SML1_PMBUS_3V3AUX_PCH_SCL_1")
	)
	(segment
		(start 280.81732 -33.993836)
		(end 279.878282 -34.932874)
		(width 0.127)
		(layer "In13.Cu")
		(net "SMB_SML1_PMBUS_3V3AUX_PCH_SCL_1")
	)
	(segment
		(start 261.0485 -43.741848)
		(end 267.3604 -43.741848)
		(width 0.127)
		(layer "In13.Cu")
		(net "SMB_SML1_PMBUS_3V3AUX_PCH_SCL_1")
	)
	(segment
		(start 252.528324 -42.738548)
		(end 252.933454 -43.143678)
		(width 0.127)
		(layer "In13.Cu")
		(net "SMB_SML1_PMBUS_3V3AUX_PCH_SCL_1")
	)
	(segment
		(start 231.277668 -47.148496)
		(end 231.9401 -47.810928)
		(width 0.127)
		(layer "In13.Cu")
		(net "SMB_SML1_PMBUS_3V3AUX_PCH_SCL_1")
	)
	(segment
		(start 235.712508 -46.190408)
		(end 246.1768 -46.190408)
		(width 0.127)
		(layer "In13.Cu")
		(net "SMB_SML1_PMBUS_3V3AUX_PCH_SCL_1")
	)
	(segment
		(start 234.091988 -47.810928)
		(end 235.712508 -46.190408)
		(width 0.127)
		(layer "In13.Cu")
		(net "SMB_SML1_PMBUS_3V3AUX_PCH_SCL_1")
	)
	(segment
		(start 217.69705 -30.902148)
		(end 219.01912 -32.224218)
		(width 0.127)
		(layer "In13.Cu")
		(net "SMB_SML1_PMBUS_3V3AUX_PCH_SCL_1")
	)
	(segment
		(start 276.65807 -35.648138)
		(end 275.726398 -35.648138)
		(width 0.127)
		(layer "In13.Cu")
		(net "SMB_SML1_PMBUS_3V3AUX_PCH_SCL_1")
	)
	(segment
		(start 274.202398 -35.648138)
		(end 274.075398 -35.775138)
		(width 0.127)
		(layer "In13.Cu")
		(net "SMB_SML1_PMBUS_3V3AUX_PCH_SCL_1")
	)
	(segment
		(start 273.440398 -36.827968)
		(end 273.313398 -36.700968)
		(width 0.127)
		(layer "In13.Cu")
		(net "SMB_SML1_PMBUS_3V3AUX_PCH_SCL_1")
	)
	(segment
		(start 254.612648 -43.143678)
		(end 255.017778 -42.738548)
		(width 0.127)
		(layer "In13.Cu")
		(net "SMB_SML1_PMBUS_3V3AUX_PCH_SCL_1")
	)
	(segment
		(start 198.233792 -32.33674)
		(end 202.462892 -32.33674)
		(width 0.127)
		(layer "In13.Cu")
		(net "SMB_SML1_PMBUS_3V3AUX_PCH_SCL_1")
	)
	(segment
		(start 274.710398 -35.648138)
		(end 274.202398 -35.648138)
		(width 0.127)
		(layer "In13.Cu")
		(net "SMB_SML1_PMBUS_3V3AUX_PCH_SCL_1")
	)
	(segment
		(start 277.373334 -34.932874)
		(end 276.65807 -35.648138)
		(width 0.127)
		(layer "In13.Cu")
		(net "SMB_SML1_PMBUS_3V3AUX_PCH_SCL_1")
	)
	(segment
		(start 274.964398 -36.827968)
		(end 274.837398 -36.700968)
		(width 0.127)
		(layer "In13.Cu")
		(net "SMB_SML1_PMBUS_3V3AUX_PCH_SCL_1")
	)
	(segment
		(start 252.02134 -42.738548)
		(end 252.528324 -42.738548)
		(width 0.127)
		(layer "In13.Cu")
		(net "SMB_SML1_PMBUS_3V3AUX_PCH_SCL_1")
	)
	(segment
		(start 279.878282 -34.932874)
		(end 277.373334 -34.932874)
		(width 0.127)
		(layer "In13.Cu")
		(net "SMB_SML1_PMBUS_3V3AUX_PCH_SCL_1")
	)
	(segment
		(start 273.313398 -35.775138)
		(end 273.186398 -35.648138)
		(width 0.127)
		(layer "In13.Cu")
		(net "SMB_SML1_PMBUS_3V3AUX_PCH_SCL_1")
	)
	(segment
		(start 250.54814 -44.211748)
		(end 252.02134 -42.738548)
		(width 0.127)
		(layer "In13.Cu")
		(net "SMB_SML1_PMBUS_3V3AUX_PCH_SCL_1")
	)
	(segment
		(start 246.1768 -46.190408)
		(end 248.15546 -44.211748)
		(width 0.127)
		(layer "In13.Cu")
		(net "SMB_SML1_PMBUS_3V3AUX_PCH_SCL_1")
	)
	(segment
		(start 260.0452 -42.738548)
		(end 261.0485 -43.741848)
		(width 0.127)
		(layer "In13.Cu")
		(net "SMB_SML1_PMBUS_3V3AUX_PCH_SCL_1")
	)
	(segment
		(start 223.862392 -40.808148)
		(end 230.02748 -40.808148)
		(width 0.127)
		(layer "In13.Cu")
		(net "SMB_SML1_PMBUS_3V3AUX_PCH_SCL_1")
	)
	(segment
		(start 163.867084 -13.600176)
		(end 163.867084 -12.879832)
		(width 0.12954)
		(layer "F.Cu")
		(net "SMB_SML0_3V3AUX_SDA_R1")
	)
	(segment
		(start 163.867084 -12.879832)
		(end 162.8648 -11.877548)
		(width 0.12954)
		(layer "F.Cu")
		(net "SMB_SML0_3V3AUX_SDA_R1")
	)
	(via
		(at 162.8648 -11.877548)
		(size 0.508)
		(drill 0.254)
		(layers "F.Cu" "B.Cu")
		(net "SMB_SML0_3V3AUX_SDA_R1")
	)
	(segment
		(start 162.8648 -11.877548)
		(end 162.43935 -11.877548)
		(width 0.12954)
		(layer "B.Cu")
		(net "SMB_SML0_3V3AUX_SDA_R1")
	)
	(segment
		(start 162.43935 -11.877548)
		(end 161.29 -13.026898)
		(width 0.12954)
		(layer "B.Cu")
		(net "SMB_SML0_3V3AUX_SDA_R1")
	)
	(segment
		(start 164.467032 -11.781282)
		(end 164.451538 -11.765788)
		(width 0.12954)
		(layer "F.Cu")
		(net "SMB_SML0_3V3AUX_SCL_R1")
	)
	(segment
		(start 164.467032 -13.600176)
		(end 164.467032 -11.781282)
		(width 0.12954)
		(layer "F.Cu")
		(net "SMB_SML0_3V3AUX_SCL_R1")
	)
	(via
		(at 164.451538 -11.765788)
		(size 0.508)
		(drill 0.254)
		(layers "F.Cu" "B.Cu")
		(net "SMB_SML0_3V3AUX_SCL_R1")
	)
	(segment
		(start 164.451538 -11.765788)
		(end 163.966144 -11.765788)
		(width 0.12954)
		(layer "B.Cu")
		(net "SMB_SML0_3V3AUX_SCL_R1")
	)
	(segment
		(start 163.793932 -12.121388)
		(end 164.148262 -12.475718)
		(width 0.12954)
		(layer "B.Cu")
		(net "SMB_SML0_3V3AUX_SCL_R1")
	)
	(segment
		(start 163.966144 -11.765788)
		(end 163.793932 -11.938)
		(width 0.12954)
		(layer "B.Cu")
		(net "SMB_SML0_3V3AUX_SCL_R1")
	)
	(segment
		(start 163.793932 -11.938)
		(end 163.793932 -12.121388)
		(width 0.12954)
		(layer "B.Cu")
		(net "SMB_SML0_3V3AUX_SCL_R1")
	)
	(segment
		(start 162.997896 -12.734036)
		(end 162.705034 -13.026898)
		(width 0.12954)
		(layer "B.Cu")
		(net "SMB_SML0_3V3AUX_SCL_R1")
	)
	(segment
		(start 163.719002 -13.088366)
		(end 163.535614 -13.088366)
		(width 0.12954)
		(layer "B.Cu")
		(net "SMB_SML0_3V3AUX_SCL_R1")
	)
	(segment
		(start 163.181284 -12.734036)
		(end 162.997896 -12.734036)
		(width 0.12954)
		(layer "B.Cu")
		(net "SMB_SML0_3V3AUX_SCL_R1")
	)
	(segment
		(start 164.148262 -12.475718)
		(end 164.148262 -12.659106)
		(width 0.12954)
		(layer "B.Cu")
		(net "SMB_SML0_3V3AUX_SCL_R1")
	)
	(segment
		(start 162.705034 -13.026898)
		(end 162.306 -13.026898)
		(width 0.12954)
		(layer "B.Cu")
		(net "SMB_SML0_3V3AUX_SCL_R1")
	)
	(segment
		(start 163.535614 -13.088366)
		(end 163.181284 -12.734036)
		(width 0.12954)
		(layer "B.Cu")
		(net "SMB_SML0_3V3AUX_SCL_R1")
	)
	(segment
		(start 164.148262 -12.659106)
		(end 163.719002 -13.088366)
		(width 0.12954)
		(layer "B.Cu")
		(net "SMB_SML0_3V3AUX_SCL_R1")
	)
	(segment
		(start 402.231606 -50.637948)
		(end 403.58695 -50.637948)
		(width 0.12954)
		(layer "F.Cu")
		(net "SMB_HOST_3V3AUX_XDP_R_SDA")
	)
	(segment
		(start 400.619722 -52.249832)
		(end 401.91436 -50.955194)
		(width 0.12954)
		(layer "F.Cu")
		(net "SMB_HOST_3V3AUX_XDP_R_SDA")
	)
	(segment
		(start 401.91436 -50.955194)
		(end 402.231606 -50.637948)
		(width 0.12954)
		(layer "F.Cu")
		(net "SMB_HOST_3V3AUX_XDP_R_SDA")
	)
	(segment
		(start 397.765016 -52.249832)
		(end 400.619722 -52.249832)
		(width 0.12954)
		(layer "F.Cu")
		(net "SMB_HOST_3V3AUX_XDP_R_SDA")
	)
	(via
		(at 401.91436 -50.955194)
		(size 0.762)
		(drill 0.381)
		(layers "F.Cu" "B.Cu")
		(net "SMB_HOST_3V3AUX_XDP_R_SDA")
	)
	(segment
		(start 407.29662 -51.410108)
		(end 402.450554 -51.410108)
		(width 0.12954)
		(layer "F.Cu")
		(net "SMB_HOST_3V3AUX_XDP_R_SCL")
	)
	(segment
		(start 401.110704 -52.749958)
		(end 397.765016 -52.749958)
		(width 0.12954)
		(layer "F.Cu")
		(net "SMB_HOST_3V3AUX_XDP_R_SCL")
	)
	(segment
		(start 402.450554 -51.410108)
		(end 401.110704 -52.749958)
		(width 0.12954)
		(layer "F.Cu")
		(net "SMB_HOST_3V3AUX_XDP_R_SCL")
	)
	(via
		(at 274.028662 -92.447364)
		(size 0.508)
		(drill 0.254)
		(layers "F.Cu" "B.Cu")
		(net "SMB_HOST_3V3AUX_XDP_R_SCL")
	)
	(via
		(at 407.29662 -51.410108)
		(size 0.508)
		(drill 0.254)
		(layers "F.Cu" "B.Cu")
		(net "SMB_HOST_3V3AUX_XDP_R_SCL")
	)
	(via
		(at 273.51228 -120.368568)
		(size 0.508)
		(drill 0.254)
		(layers "F.Cu" "B.Cu")
		(net "SMB_HOST_3V3AUX_XDP_R_SCL")
	)
	(via
		(at 239.42294 -130.8989)
		(size 0.508)
		(drill 0.254)
		(layers "F.Cu" "B.Cu")
		(net "SMB_HOST_3V3AUX_XDP_R_SCL")
	)
	(via
		(at 399.388584 -78.6003)
		(size 0.508)
		(drill 0.254)
		(layers "F.Cu" "B.Cu")
		(net "SMB_HOST_3V3AUX_XDP_R_SCL")
	)
	(segment
		(start 383.63525 -97.153476)
		(end 383.63525 -108.207048)
		(width 0.12954)
		(layer "B.Cu")
		(net "SMB_HOST_3V3AUX_XDP_R_SCL")
	)
	(segment
		(start 370.280438 -110.988602)
		(end 366.214914 -110.988602)
		(width 0.12954)
		(layer "B.Cu")
		(net "SMB_HOST_3V3AUX_XDP_R_SCL")
	)
	(segment
		(start 392.494516 -88.29421)
		(end 383.63525 -97.153476)
		(width 0.12954)
		(layer "B.Cu")
		(net "SMB_HOST_3V3AUX_XDP_R_SCL")
	)
	(segment
		(start 239.136174 -132.108702)
		(end 238.75238 -132.108702)
		(width 0.12954)
		(layer "B.Cu")
		(net "SMB_HOST_3V3AUX_XDP_R_SCL")
	)
	(segment
		(start 239.42294 -130.8989)
		(end 239.42294 -131.20751)
		(width 0.12954)
		(layer "B.Cu")
		(net "SMB_HOST_3V3AUX_XDP_R_SCL")
	)
	(segment
		(start 239.343184 -131.608576)
		(end 239.136174 -132.108702)
		(width 0.12954)
		(layer "B.Cu")
		(net "SMB_HOST_3V3AUX_XDP_R_SCL")
	)
	(segment
		(start 380.20879 -111.633508)
		(end 370.925344 -111.633508)
		(width 0.12954)
		(layer "B.Cu")
		(net "SMB_HOST_3V3AUX_XDP_R_SCL")
	)
	(segment
		(start 355.380798 -100.154486)
		(end 284.423612 -100.154486)
		(width 0.12954)
		(layer "B.Cu")
		(net "SMB_HOST_3V3AUX_XDP_R_SCL")
	)
	(segment
		(start 274.028662 -92.337382)
		(end 274.028662 -92.447364)
		(width 0.12954)
		(layer "B.Cu")
		(net "SMB_HOST_3V3AUX_XDP_R_SCL")
	)
	(segment
		(start 370.925344 -111.633508)
		(end 370.280438 -110.988602)
		(width 0.12954)
		(layer "B.Cu")
		(net "SMB_HOST_3V3AUX_XDP_R_SCL")
	)
	(segment
		(start 399.388584 -78.6003)
		(end 398.842484 -78.6003)
		(width 0.12954)
		(layer "B.Cu")
		(net "SMB_HOST_3V3AUX_XDP_R_SCL")
	)
	(segment
		(start 239.42294 -131.20751)
		(end 239.343184 -131.608576)
		(width 0.12954)
		(layer "B.Cu")
		(net "SMB_HOST_3V3AUX_XDP_R_SCL")
	)
	(segment
		(start 366.214914 -110.988602)
		(end 355.380798 -100.154486)
		(width 0.12954)
		(layer "B.Cu")
		(net "SMB_HOST_3V3AUX_XDP_R_SCL")
	)
	(segment
		(start 284.423612 -100.154486)
		(end 276.140418 -91.871292)
		(width 0.12954)
		(layer "B.Cu")
		(net "SMB_HOST_3V3AUX_XDP_R_SCL")
	)
	(segment
		(start 274.494752 -91.871292)
		(end 274.028662 -92.337382)
		(width 0.12954)
		(layer "B.Cu")
		(net "SMB_HOST_3V3AUX_XDP_R_SCL")
	)
	(segment
		(start 276.140418 -91.871292)
		(end 274.494752 -91.871292)
		(width 0.12954)
		(layer "B.Cu")
		(net "SMB_HOST_3V3AUX_XDP_R_SCL")
	)
	(segment
		(start 383.63525 -108.207048)
		(end 380.20879 -111.633508)
		(width 0.12954)
		(layer "B.Cu")
		(net "SMB_HOST_3V3AUX_XDP_R_SCL")
	)
	(segment
		(start 392.494516 -84.948268)
		(end 392.494516 -88.29421)
		(width 0.12954)
		(layer "B.Cu")
		(net "SMB_HOST_3V3AUX_XDP_R_SCL")
	)
	(segment
		(start 398.842484 -78.6003)
		(end 392.494516 -84.948268)
		(width 0.12954)
		(layer "B.Cu")
		(net "SMB_HOST_3V3AUX_XDP_R_SCL")
	)
	(segment
		(start 275.0693 -93.488002)
		(end 274.028662 -92.447364)
		(width 0.127)
		(layer "In2.Cu")
		(net "SMB_HOST_3V3AUX_XDP_R_SCL")
	)
	(segment
		(start 273.51228 -120.368568)
		(end 273.51228 -112.342168)
		(width 0.127)
		(layer "In2.Cu")
		(net "SMB_HOST_3V3AUX_XDP_R_SCL")
	)
	(segment
		(start 275.0693 -104.591104)
		(end 275.0693 -93.488002)
		(width 0.127)
		(layer "In2.Cu")
		(net "SMB_HOST_3V3AUX_XDP_R_SCL")
	)
	(segment
		(start 273.51228 -112.342168)
		(end 272.96618 -111.796068)
		(width 0.127)
		(layer "In2.Cu")
		(net "SMB_HOST_3V3AUX_XDP_R_SCL")
	)
	(segment
		(start 272.96618 -106.694224)
		(end 275.0693 -104.591104)
		(width 0.127)
		(layer "In2.Cu")
		(net "SMB_HOST_3V3AUX_XDP_R_SCL")
	)
	(segment
		(start 272.96618 -111.796068)
		(end 272.96618 -106.694224)
		(width 0.127)
		(layer "In2.Cu")
		(net "SMB_HOST_3V3AUX_XDP_R_SCL")
	)
	(segment
		(start 239.519968 -130.8989)
		(end 239.68202 -130.736848)
		(width 0.127)
		(layer "In4.Cu")
		(net "SMB_HOST_3V3AUX_XDP_R_SCL")
	)
	(segment
		(start 239.9157 -127.356108)
		(end 239.9157 -123.337828)
		(width 0.127)
		(layer "In4.Cu")
		(net "SMB_HOST_3V3AUX_XDP_R_SCL")
	)
	(segment
		(start 271.85366 -120.378728)
		(end 272.51152 -119.720868)
		(width 0.127)
		(layer "In4.Cu")
		(net "SMB_HOST_3V3AUX_XDP_R_SCL")
	)
	(segment
		(start 239.9157 -123.337828)
		(end 242.8748 -120.378728)
		(width 0.127)
		(layer "In4.Cu")
		(net "SMB_HOST_3V3AUX_XDP_R_SCL")
	)
	(segment
		(start 272.51152 -119.720868)
		(end 273.2151 -119.720868)
		(width 0.127)
		(layer "In4.Cu")
		(net "SMB_HOST_3V3AUX_XDP_R_SCL")
	)
	(segment
		(start 242.8748 -120.378728)
		(end 271.85366 -120.378728)
		(width 0.127)
		(layer "In4.Cu")
		(net "SMB_HOST_3V3AUX_XDP_R_SCL")
	)
	(segment
		(start 273.2151 -119.720868)
		(end 273.51228 -120.018048)
		(width 0.127)
		(layer "In4.Cu")
		(net "SMB_HOST_3V3AUX_XDP_R_SCL")
	)
	(segment
		(start 239.42294 -130.8989)
		(end 239.519968 -130.8989)
		(width 0.127)
		(layer "In4.Cu")
		(net "SMB_HOST_3V3AUX_XDP_R_SCL")
	)
	(segment
		(start 239.68202 -130.736848)
		(end 239.68202 -127.589788)
		(width 0.127)
		(layer "In4.Cu")
		(net "SMB_HOST_3V3AUX_XDP_R_SCL")
	)
	(segment
		(start 239.68202 -127.589788)
		(end 239.9157 -127.356108)
		(width 0.127)
		(layer "In4.Cu")
		(net "SMB_HOST_3V3AUX_XDP_R_SCL")
	)
	(segment
		(start 273.51228 -120.018048)
		(end 273.51228 -120.368568)
		(width 0.127)
		(layer "In4.Cu")
		(net "SMB_HOST_3V3AUX_XDP_R_SCL")
	)
	(segment
		(start 408.704542 -53.52669)
		(end 408.831542 -53.65369)
		(width 0.127)
		(layer "In6.Cu")
		(net "SMB_HOST_3V3AUX_XDP_R_SCL")
	)
	(segment
		(start 408.704542 -52.81803)
		(end 408.704542 -53.52669)
		(width 0.127)
		(layer "In6.Cu")
		(net "SMB_HOST_3V3AUX_XDP_R_SCL")
	)
	(segment
		(start 398.455642 -72.925686)
		(end 398.455642 -77.667358)
		(width 0.127)
		(layer "In6.Cu")
		(net "SMB_HOST_3V3AUX_XDP_R_SCL")
	)
	(segment
		(start 407.096976 -65.753996)
		(end 405.627332 -65.753996)
		(width 0.127)
		(layer "In6.Cu")
		(net "SMB_HOST_3V3AUX_XDP_R_SCL")
	)
	(segment
		(start 405.627332 -65.753996)
		(end 398.455642 -72.925686)
		(width 0.127)
		(layer "In6.Cu")
		(net "SMB_HOST_3V3AUX_XDP_R_SCL")
	)
	(segment
		(start 408.831542 -53.65369)
		(end 408.831542 -64.01943)
		(width 0.127)
		(layer "In6.Cu")
		(net "SMB_HOST_3V3AUX_XDP_R_SCL")
	)
	(segment
		(start 398.455642 -77.667358)
		(end 399.388584 -78.6003)
		(width 0.127)
		(layer "In6.Cu")
		(net "SMB_HOST_3V3AUX_XDP_R_SCL")
	)
	(segment
		(start 408.831542 -64.01943)
		(end 407.096976 -65.753996)
		(width 0.127)
		(layer "In6.Cu")
		(net "SMB_HOST_3V3AUX_XDP_R_SCL")
	)
	(segment
		(start 407.29662 -51.410108)
		(end 408.704542 -52.81803)
		(width 0.127)
		(layer "In6.Cu")
		(net "SMB_HOST_3V3AUX_XDP_R_SCL")
	)
	(segment
		(start 8.55218 -48.986948)
		(end 5.989066 -48.986948)
		(width 0.12954)
		(layer "F.Cu")
		(net "SMB_HOST_3V3AUX_SDA_R5")
	)
	(segment
		(start 5.989066 -48.986948)
		(end 5.862066 -49.113948)
		(width 0.12954)
		(layer "F.Cu")
		(net "SMB_HOST_3V3AUX_SDA_R5")
	)
	(segment
		(start 9.25195 -48.986948)
		(end 8.55218 -48.986948)
		(width 0.12954)
		(layer "F.Cu")
		(net "SMB_HOST_3V3AUX_SDA_R5")
	)
	(segment
		(start 5.862066 -49.113948)
		(end 5.09905 -49.113948)
		(width 0.12954)
		(layer "F.Cu")
		(net "SMB_HOST_3V3AUX_SDA_R5")
	)
	(via
		(at 8.55218 -48.986948)
		(size 0.508)
		(drill 0.254)
		(layers "F.Cu" "B.Cu")
		(net "SMB_HOST_3V3AUX_SDA_R5")
	)
	(via
		(at 182.6514 -21.656548)
		(size 0.508)
		(drill 0.254)
		(layers "F.Cu" "B.Cu")
		(net "SMB_HOST_3V3AUX_SDA_R5")
	)
	(via
		(at 90.754962 -54.142386)
		(size 0.508)
		(drill 0.254)
		(layers "F.Cu" "B.Cu")
		(net "SMB_HOST_3V3AUX_SDA_R5")
	)
	(segment
		(start 182.64505 -21.650198)
		(end 182.64505 -20.970748)
		(width 0.12954)
		(layer "B.Cu")
		(net "SMB_HOST_3V3AUX_SDA_R5")
	)
	(segment
		(start 182.6514 -21.656548)
		(end 182.64505 -21.650198)
		(width 0.12954)
		(layer "B.Cu")
		(net "SMB_HOST_3V3AUX_SDA_R5")
	)
	(segment
		(start 106.7562 -56.911748)
		(end 110.109 -56.911748)
		(width 0.127)
		(layer "In4.Cu")
		(net "SMB_HOST_3V3AUX_SDA_R5")
	)
	(segment
		(start 163.3855 -22.875748)
		(end 164.3761 -21.885148)
		(width 0.127)
		(layer "In4.Cu")
		(net "SMB_HOST_3V3AUX_SDA_R5")
	)
	(segment
		(start 97.88398 -56.454548)
		(end 106.299 -56.454548)
		(width 0.127)
		(layer "In4.Cu")
		(net "SMB_HOST_3V3AUX_SDA_R5")
	)
	(segment
		(start 144.2974 -30.267148)
		(end 144.2974 -29.342334)
		(width 0.127)
		(layer "In4.Cu")
		(net "SMB_HOST_3V3AUX_SDA_R5")
	)
	(segment
		(start 140.22578 -33.431988)
		(end 140.85824 -33.431988)
		(width 0.127)
		(layer "In4.Cu")
		(net "SMB_HOST_3V3AUX_SDA_R5")
	)
	(segment
		(start 150.268686 -23.371048)
		(end 153.04008 -23.371048)
		(width 0.127)
		(layer "In4.Cu")
		(net "SMB_HOST_3V3AUX_SDA_R5")
	)
	(segment
		(start 90.754962 -54.142386)
		(end 94.538038 -54.142386)
		(width 0.127)
		(layer "In4.Cu")
		(net "SMB_HOST_3V3AUX_SDA_R5")
	)
	(segment
		(start 124.342906 -34.483548)
		(end 139.17422 -34.483548)
		(width 0.127)
		(layer "In4.Cu")
		(net "SMB_HOST_3V3AUX_SDA_R5")
	)
	(segment
		(start 171.5008 -18.151348)
		(end 172.34662 -17.305528)
		(width 0.127)
		(layer "In4.Cu")
		(net "SMB_HOST_3V3AUX_SDA_R5")
	)
	(segment
		(start 95.0214 -54.625748)
		(end 96.05518 -54.625748)
		(width 0.127)
		(layer "In4.Cu")
		(net "SMB_HOST_3V3AUX_SDA_R5")
	)
	(segment
		(start 172.34662 -17.305528)
		(end 178.6128 -17.305528)
		(width 0.127)
		(layer "In4.Cu")
		(net "SMB_HOST_3V3AUX_SDA_R5")
	)
	(segment
		(start 166.90594 -21.885148)
		(end 170.63974 -18.151348)
		(width 0.127)
		(layer "In4.Cu")
		(net "SMB_HOST_3V3AUX_SDA_R5")
	)
	(segment
		(start 143.71828 -30.846268)
		(end 144.2974 -30.267148)
		(width 0.127)
		(layer "In4.Cu")
		(net "SMB_HOST_3V3AUX_SDA_R5")
	)
	(segment
		(start 94.538038 -54.142386)
		(end 95.0214 -54.625748)
		(width 0.127)
		(layer "In4.Cu")
		(net "SMB_HOST_3V3AUX_SDA_R5")
	)
	(segment
		(start 153.04008 -23.371048)
		(end 153.53538 -22.875748)
		(width 0.127)
		(layer "In4.Cu")
		(net "SMB_HOST_3V3AUX_SDA_R5")
	)
	(segment
		(start 143.44396 -30.846268)
		(end 143.71828 -30.846268)
		(width 0.127)
		(layer "In4.Cu")
		(net "SMB_HOST_3V3AUX_SDA_R5")
	)
	(segment
		(start 110.109 -56.911748)
		(end 113.9952 -53.025548)
		(width 0.127)
		(layer "In4.Cu")
		(net "SMB_HOST_3V3AUX_SDA_R5")
	)
	(segment
		(start 180.24856 -18.941288)
		(end 183.35244 -18.941288)
		(width 0.127)
		(layer "In4.Cu")
		(net "SMB_HOST_3V3AUX_SDA_R5")
	)
	(segment
		(start 178.6128 -17.305528)
		(end 180.24856 -18.941288)
		(width 0.127)
		(layer "In4.Cu")
		(net "SMB_HOST_3V3AUX_SDA_R5")
	)
	(segment
		(start 113.9952 -44.831254)
		(end 124.342906 -34.483548)
		(width 0.127)
		(layer "In4.Cu")
		(net "SMB_HOST_3V3AUX_SDA_R5")
	)
	(segment
		(start 153.53538 -22.875748)
		(end 163.3855 -22.875748)
		(width 0.127)
		(layer "In4.Cu")
		(net "SMB_HOST_3V3AUX_SDA_R5")
	)
	(segment
		(start 139.17422 -34.483548)
		(end 140.22578 -33.431988)
		(width 0.127)
		(layer "In4.Cu")
		(net "SMB_HOST_3V3AUX_SDA_R5")
	)
	(segment
		(start 140.85824 -33.431988)
		(end 143.44396 -30.846268)
		(width 0.127)
		(layer "In4.Cu")
		(net "SMB_HOST_3V3AUX_SDA_R5")
	)
	(segment
		(start 183.96712 -19.555968)
		(end 183.96712 -20.340828)
		(width 0.127)
		(layer "In4.Cu")
		(net "SMB_HOST_3V3AUX_SDA_R5")
	)
	(segment
		(start 183.35244 -18.941288)
		(end 183.96712 -19.555968)
		(width 0.127)
		(layer "In4.Cu")
		(net "SMB_HOST_3V3AUX_SDA_R5")
	)
	(segment
		(start 183.96712 -20.340828)
		(end 182.6514 -21.656548)
		(width 0.127)
		(layer "In4.Cu")
		(net "SMB_HOST_3V3AUX_SDA_R5")
	)
	(segment
		(start 106.299 -56.454548)
		(end 106.7562 -56.911748)
		(width 0.127)
		(layer "In4.Cu")
		(net "SMB_HOST_3V3AUX_SDA_R5")
	)
	(segment
		(start 96.05518 -54.625748)
		(end 97.88398 -56.454548)
		(width 0.127)
		(layer "In4.Cu")
		(net "SMB_HOST_3V3AUX_SDA_R5")
	)
	(segment
		(start 113.9952 -53.025548)
		(end 113.9952 -44.831254)
		(width 0.127)
		(layer "In4.Cu")
		(net "SMB_HOST_3V3AUX_SDA_R5")
	)
	(segment
		(start 170.63974 -18.151348)
		(end 171.5008 -18.151348)
		(width 0.127)
		(layer "In4.Cu")
		(net "SMB_HOST_3V3AUX_SDA_R5")
	)
	(segment
		(start 144.2974 -29.342334)
		(end 150.268686 -23.371048)
		(width 0.127)
		(layer "In4.Cu")
		(net "SMB_HOST_3V3AUX_SDA_R5")
	)
	(segment
		(start 164.3761 -21.885148)
		(end 166.90594 -21.885148)
		(width 0.127)
		(layer "In4.Cu")
		(net "SMB_HOST_3V3AUX_SDA_R5")
	)
	(segment
		(start 4.95808 -54.763924)
		(end 7.92988 -51.792124)
		(width 0.127)
		(layer "In6.Cu")
		(net "SMB_HOST_3V3AUX_SDA_R5")
	)
	(segment
		(start 6.759194 -58.357262)
		(end 5.798566 -58.357262)
		(width 0.127)
		(layer "In6.Cu")
		(net "SMB_HOST_3V3AUX_SDA_R5")
	)
	(segment
		(start 88.062308 -54.142386)
		(end 81.84896 -47.929038)
		(width 0.127)
		(layer "In6.Cu")
		(net "SMB_HOST_3V3AUX_SDA_R5")
	)
	(segment
		(start 7.92988 -50.371248)
		(end 8.55218 -49.748948)
		(width 0.127)
		(layer "In6.Cu")
		(net "SMB_HOST_3V3AUX_SDA_R5")
	)
	(segment
		(start 76.73467 -47.929038)
		(end 72.38238 -43.576748)
		(width 0.127)
		(layer "In6.Cu")
		(net "SMB_HOST_3V3AUX_SDA_R5")
	)
	(segment
		(start 7.54888 -59.146948)
		(end 6.759194 -58.357262)
		(width 0.127)
		(layer "In6.Cu")
		(net "SMB_HOST_3V3AUX_SDA_R5")
	)
	(segment
		(start 8.325612 -62.408308)
		(end 7.54888 -61.631576)
		(width 0.127)
		(layer "In6.Cu")
		(net "SMB_HOST_3V3AUX_SDA_R5")
	)
	(segment
		(start 81.84896 -47.929038)
		(end 76.73467 -47.929038)
		(width 0.127)
		(layer "In6.Cu")
		(net "SMB_HOST_3V3AUX_SDA_R5")
	)
	(segment
		(start 26.774648 -51.008788)
		(end 19.713448 -58.069988)
		(width 0.127)
		(layer "In6.Cu")
		(net "SMB_HOST_3V3AUX_SDA_R5")
	)
	(segment
		(start 14.68882 -58.069988)
		(end 10.3505 -62.408308)
		(width 0.127)
		(layer "In6.Cu")
		(net "SMB_HOST_3V3AUX_SDA_R5")
	)
	(segment
		(start 72.38238 -43.576748)
		(end 67.69608 -43.576748)
		(width 0.127)
		(layer "In6.Cu")
		(net "SMB_HOST_3V3AUX_SDA_R5")
	)
	(segment
		(start 8.55218 -49.748948)
		(end 8.55218 -48.986948)
		(width 0.127)
		(layer "In6.Cu")
		(net "SMB_HOST_3V3AUX_SDA_R5")
	)
	(segment
		(start 7.54888 -61.631576)
		(end 7.54888 -59.146948)
		(width 0.127)
		(layer "In6.Cu")
		(net "SMB_HOST_3V3AUX_SDA_R5")
	)
	(segment
		(start 53.4416 -43.475148)
		(end 45.90796 -51.008788)
		(width 0.127)
		(layer "In6.Cu")
		(net "SMB_HOST_3V3AUX_SDA_R5")
	)
	(segment
		(start 7.92988 -51.792124)
		(end 7.92988 -50.371248)
		(width 0.127)
		(layer "In6.Cu")
		(net "SMB_HOST_3V3AUX_SDA_R5")
	)
	(segment
		(start 19.713448 -58.069988)
		(end 14.68882 -58.069988)
		(width 0.127)
		(layer "In6.Cu")
		(net "SMB_HOST_3V3AUX_SDA_R5")
	)
	(segment
		(start 90.754962 -54.142386)
		(end 88.062308 -54.142386)
		(width 0.127)
		(layer "In6.Cu")
		(net "SMB_HOST_3V3AUX_SDA_R5")
	)
	(segment
		(start 67.59448 -43.475148)
		(end 53.4416 -43.475148)
		(width 0.127)
		(layer "In6.Cu")
		(net "SMB_HOST_3V3AUX_SDA_R5")
	)
	(segment
		(start 4.95808 -57.516776)
		(end 4.95808 -54.763924)
		(width 0.127)
		(layer "In6.Cu")
		(net "SMB_HOST_3V3AUX_SDA_R5")
	)
	(segment
		(start 67.69608 -43.576748)
		(end 67.59448 -43.475148)
		(width 0.127)
		(layer "In6.Cu")
		(net "SMB_HOST_3V3AUX_SDA_R5")
	)
	(segment
		(start 10.3505 -62.408308)
		(end 8.325612 -62.408308)
		(width 0.127)
		(layer "In6.Cu")
		(net "SMB_HOST_3V3AUX_SDA_R5")
	)
	(segment
		(start 45.90796 -51.008788)
		(end 26.774648 -51.008788)
		(width 0.127)
		(layer "In6.Cu")
		(net "SMB_HOST_3V3AUX_SDA_R5")
	)
	(segment
		(start 5.798566 -58.357262)
		(end 4.95808 -57.516776)
		(width 0.127)
		(layer "In6.Cu")
		(net "SMB_HOST_3V3AUX_SDA_R5")
	)
	(segment
		(start 241.324892 -137.344658)
		(end 242.645184 -137.344658)
		(width 0.12954)
		(layer "F.Cu")
		(net "SMB_HOST_3V3AUX_SDA_R4")
	)
	(segment
		(start 212.234018 -92.951808)
		(end 208.96834 -92.951808)
		(width 0.12954)
		(layer "F.Cu")
		(net "SMB_HOST_3V3AUX_SDA_R4")
	)
	(segment
		(start 223.38284 -108.649262)
		(end 223.2533 -108.519722)
		(width 0.12954)
		(layer "F.Cu")
		(net "SMB_HOST_3V3AUX_SDA_R4")
	)
	(segment
		(start 223.2533 -109.385862)
		(end 223.38284 -109.256322)
		(width 0.12954)
		(layer "F.Cu")
		(net "SMB_HOST_3V3AUX_SDA_R4")
	)
	(segment
		(start 223.38284 -96.548956)
		(end 219.785692 -92.951808)
		(width 0.12954)
		(layer "F.Cu")
		(net "SMB_HOST_3V3AUX_SDA_R4")
	)
	(segment
		(start 238.618014 -68.19773)
		(end 235.820458 -68.19773)
		(width 0.12954)
		(layer "F.Cu")
		(net "SMB_HOST_3V3AUX_SDA_R4")
	)
	(segment
		(start 222.8215 -108.519722)
		(end 222.69196 -108.390182)
		(width 0.12954)
		(layer "F.Cu")
		(net "SMB_HOST_3V3AUX_SDA_R4")
	)
	(segment
		(start 217.701114 -92.951808)
		(end 217.571574 -93.081348)
		(width 0.12954)
		(layer "F.Cu")
		(net "SMB_HOST_3V3AUX_SDA_R4")
	)
	(segment
		(start 222.8215 -109.385862)
		(end 223.2533 -109.385862)
		(width 0.12954)
		(layer "F.Cu")
		(net "SMB_HOST_3V3AUX_SDA_R4")
	)
	(segment
		(start 223.38284 -110.970314)
		(end 223.38284 -110.381542)
		(width 0.12954)
		(layer "F.Cu")
		(net "SMB_HOST_3V3AUX_SDA_R4")
	)
	(segment
		(start 222.8215 -110.252002)
		(end 222.69196 -110.122462)
		(width 0.12954)
		(layer "F.Cu")
		(net "SMB_HOST_3V3AUX_SDA_R4")
	)
	(segment
		(start 404.904194 -49.009554)
		(end 404.38705 -49.526698)
		(width 0.12954)
		(layer "F.Cu")
		(net "SMB_HOST_3V3AUX_SDA_R4")
	)
	(segment
		(start 223.2533 -107.653582)
		(end 223.38284 -107.524042)
		(width 0.12954)
		(layer "F.Cu")
		(net "SMB_HOST_3V3AUX_SDA_R4")
	)
	(segment
		(start 226.07016 -83.337908)
		(end 225.2345 -84.173568)
		(width 0.12954)
		(layer "F.Cu")
		(net "SMB_HOST_3V3AUX_SDA_R4")
	)
	(segment
		(start 223.38284 -107.524042)
		(end 223.38284 -96.548956)
		(width 0.12954)
		(layer "F.Cu")
		(net "SMB_HOST_3V3AUX_SDA_R4")
	)
	(segment
		(start 214.42934 -115.799108)
		(end 216.39276 -115.799108)
		(width 0.12954)
		(layer "F.Cu")
		(net "SMB_HOST_3V3AUX_SDA_R4")
	)
	(segment
		(start 222.531686 -111.821468)
		(end 223.38284 -110.970314)
		(width 0.12954)
		(layer "F.Cu")
		(net "SMB_HOST_3V3AUX_SDA_R4")
	)
	(segment
		(start 222.69196 -107.783122)
		(end 222.8215 -107.653582)
		(width 0.12954)
		(layer "F.Cu")
		(net "SMB_HOST_3V3AUX_SDA_R4")
	)
	(segment
		(start 216.39276 -115.799108)
		(end 217.34526 -114.846608)
		(width 0.12954)
		(layer "F.Cu")
		(net "SMB_HOST_3V3AUX_SDA_R4")
	)
	(segment
		(start 245.334536 -61.481208)
		(end 238.618014 -68.19773)
		(width 0.12954)
		(layer "F.Cu")
		(net "SMB_HOST_3V3AUX_SDA_R4")
	)
	(segment
		(start 223.2533 -110.252002)
		(end 222.8215 -110.252002)
		(width 0.12954)
		(layer "F.Cu")
		(net "SMB_HOST_3V3AUX_SDA_R4")
	)
	(segment
		(start 217.442034 -93.594428)
		(end 216.834974 -93.594428)
		(width 0.12954)
		(layer "F.Cu")
		(net "SMB_HOST_3V3AUX_SDA_R4")
	)
	(segment
		(start 217.571574 -93.081348)
		(end 217.571574 -93.464888)
		(width 0.12954)
		(layer "F.Cu")
		(net "SMB_HOST_3V3AUX_SDA_R4")
	)
	(segment
		(start 212.811106 -92.37472)
		(end 212.234018 -92.951808)
		(width 0.12954)
		(layer "F.Cu")
		(net "SMB_HOST_3V3AUX_SDA_R4")
	)
	(segment
		(start 216.575894 -92.951808)
		(end 215.968834 -92.951808)
		(width 0.12954)
		(layer "F.Cu")
		(net "SMB_HOST_3V3AUX_SDA_R4")
	)
	(segment
		(start 215.839294 -93.464888)
		(end 215.709754 -93.594428)
		(width 0.12954)
		(layer "F.Cu")
		(net "SMB_HOST_3V3AUX_SDA_R4")
	)
	(segment
		(start 226.07016 -77.948028)
		(end 226.07016 -83.337908)
		(width 0.12954)
		(layer "F.Cu")
		(net "SMB_HOST_3V3AUX_SDA_R4")
	)
	(segment
		(start 222.69196 -109.515402)
		(end 222.8215 -109.385862)
		(width 0.12954)
		(layer "F.Cu")
		(net "SMB_HOST_3V3AUX_SDA_R4")
	)
	(segment
		(start 404.38705 -49.526698)
		(end 404.38705 -50.637948)
		(width 0.12954)
		(layer "F.Cu")
		(net "SMB_HOST_3V3AUX_SDA_R4")
	)
	(segment
		(start 225.2345 -85.423248)
		(end 226.45878 -86.647528)
		(width 0.12954)
		(layer "F.Cu")
		(net "SMB_HOST_3V3AUX_SDA_R4")
	)
	(segment
		(start 217.34526 -113.035842)
		(end 218.559634 -111.821468)
		(width 0.12954)
		(layer "F.Cu")
		(net "SMB_HOST_3V3AUX_SDA_R4")
	)
	(segment
		(start 217.571574 -93.464888)
		(end 217.442034 -93.594428)
		(width 0.12954)
		(layer "F.Cu")
		(net "SMB_HOST_3V3AUX_SDA_R4")
	)
	(segment
		(start 219.785692 -92.951808)
		(end 217.701114 -92.951808)
		(width 0.12954)
		(layer "F.Cu")
		(net "SMB_HOST_3V3AUX_SDA_R4")
	)
	(segment
		(start 240.89741 -135.715502)
		(end 240.89741 -136.917176)
		(width 0.12954)
		(layer "F.Cu")
		(net "SMB_HOST_3V3AUX_SDA_R4")
	)
	(segment
		(start 214.266526 -92.37472)
		(end 212.811106 -92.37472)
		(width 0.12954)
		(layer "F.Cu")
		(net "SMB_HOST_3V3AUX_SDA_R4")
	)
	(segment
		(start 216.705434 -93.464888)
		(end 216.705434 -93.081348)
		(width 0.12954)
		(layer "F.Cu")
		(net "SMB_HOST_3V3AUX_SDA_R4")
	)
	(segment
		(start 215.968834 -92.951808)
		(end 215.839294 -93.081348)
		(width 0.12954)
		(layer "F.Cu")
		(net "SMB_HOST_3V3AUX_SDA_R4")
	)
	(segment
		(start 240.89741 -136.917176)
		(end 241.324892 -137.344658)
		(width 0.12954)
		(layer "F.Cu")
		(net "SMB_HOST_3V3AUX_SDA_R4")
	)
	(segment
		(start 216.705434 -93.081348)
		(end 216.575894 -92.951808)
		(width 0.12954)
		(layer "F.Cu")
		(net "SMB_HOST_3V3AUX_SDA_R4")
	)
	(segment
		(start 245.334536 -61.480954)
		(end 245.334536 -61.481208)
		(width 0.12954)
		(layer "F.Cu")
		(net "SMB_HOST_3V3AUX_SDA_R4")
	)
	(segment
		(start 222.8215 -107.653582)
		(end 223.2533 -107.653582)
		(width 0.12954)
		(layer "F.Cu")
		(net "SMB_HOST_3V3AUX_SDA_R4")
	)
	(segment
		(start 217.34526 -114.846608)
		(end 217.34526 -113.035842)
		(width 0.12954)
		(layer "F.Cu")
		(net "SMB_HOST_3V3AUX_SDA_R4")
	)
	(segment
		(start 216.834974 -93.594428)
		(end 216.705434 -93.464888)
		(width 0.12954)
		(layer "F.Cu")
		(net "SMB_HOST_3V3AUX_SDA_R4")
	)
	(segment
		(start 407.351738 -49.009554)
		(end 404.904194 -49.009554)
		(width 0.12954)
		(layer "F.Cu")
		(net "SMB_HOST_3V3AUX_SDA_R4")
	)
	(segment
		(start 214.973154 -93.464888)
		(end 214.973154 -93.081348)
		(width 0.12954)
		(layer "F.Cu")
		(net "SMB_HOST_3V3AUX_SDA_R4")
	)
	(segment
		(start 218.559634 -111.821468)
		(end 222.531686 -111.821468)
		(width 0.12954)
		(layer "F.Cu")
		(net "SMB_HOST_3V3AUX_SDA_R4")
	)
	(segment
		(start 222.69196 -110.122462)
		(end 222.69196 -109.515402)
		(width 0.12954)
		(layer "F.Cu")
		(net "SMB_HOST_3V3AUX_SDA_R4")
	)
	(segment
		(start 214.973154 -93.081348)
		(end 214.266526 -92.37472)
		(width 0.12954)
		(layer "F.Cu")
		(net "SMB_HOST_3V3AUX_SDA_R4")
	)
	(segment
		(start 215.102694 -93.594428)
		(end 214.973154 -93.464888)
		(width 0.12954)
		(layer "F.Cu")
		(net "SMB_HOST_3V3AUX_SDA_R4")
	)
	(segment
		(start 223.2533 -108.519722)
		(end 222.8215 -108.519722)
		(width 0.12954)
		(layer "F.Cu")
		(net "SMB_HOST_3V3AUX_SDA_R4")
	)
	(segment
		(start 225.2345 -84.173568)
		(end 225.2345 -85.423248)
		(width 0.12954)
		(layer "F.Cu")
		(net "SMB_HOST_3V3AUX_SDA_R4")
	)
	(segment
		(start 215.709754 -93.594428)
		(end 215.102694 -93.594428)
		(width 0.12954)
		(layer "F.Cu")
		(net "SMB_HOST_3V3AUX_SDA_R4")
	)
	(segment
		(start 208.96834 -92.951808)
		(end 207.19034 -94.729808)
		(width 0.12954)
		(layer "F.Cu")
		(net "SMB_HOST_3V3AUX_SDA_R4")
	)
	(segment
		(start 235.820458 -68.19773)
		(end 226.07016 -77.948028)
		(width 0.12954)
		(layer "F.Cu")
		(net "SMB_HOST_3V3AUX_SDA_R4")
	)
	(segment
		(start 223.38284 -109.256322)
		(end 223.38284 -108.649262)
		(width 0.12954)
		(layer "F.Cu")
		(net "SMB_HOST_3V3AUX_SDA_R4")
	)
	(segment
		(start 223.38284 -110.381542)
		(end 223.2533 -110.252002)
		(width 0.12954)
		(layer "F.Cu")
		(net "SMB_HOST_3V3AUX_SDA_R4")
	)
	(segment
		(start 207.19034 -94.729808)
		(end 207.19034 -95.070168)
		(width 0.12954)
		(layer "F.Cu")
		(net "SMB_HOST_3V3AUX_SDA_R4")
	)
	(segment
		(start 222.69196 -108.390182)
		(end 222.69196 -107.783122)
		(width 0.12954)
		(layer "F.Cu")
		(net "SMB_HOST_3V3AUX_SDA_R4")
	)
	(segment
		(start 215.839294 -93.081348)
		(end 215.839294 -93.464888)
		(width 0.12954)
		(layer "F.Cu")
		(net "SMB_HOST_3V3AUX_SDA_R4")
	)
	(segment
		(start 226.45878 -86.647528)
		(end 227.72116 -86.647528)
		(width 0.12954)
		(layer "F.Cu")
		(net "SMB_HOST_3V3AUX_SDA_R4")
	)
	(via
		(at 239.20196 -130.282188)
		(size 0.508)
		(drill 0.254)
		(layers "F.Cu" "B.Cu")
		(net "SMB_HOST_3V3AUX_SDA_R4")
	)
	(via
		(at 240.89741 -135.715502)
		(size 0.508)
		(drill 0.254)
		(layers "F.Cu" "B.Cu")
		(net "SMB_HOST_3V3AUX_SDA_R4")
	)
	(via
		(at 227.72116 -86.647528)
		(size 0.508)
		(drill 0.254)
		(layers "F.Cu" "B.Cu")
		(net "SMB_HOST_3V3AUX_SDA_R4")
	)
	(via
		(at 399.604484 -77.8891)
		(size 0.508)
		(drill 0.254)
		(layers "F.Cu" "B.Cu")
		(net "SMB_HOST_3V3AUX_SDA_R4")
	)
	(via
		(at 207.19034 -95.070168)
		(size 0.508)
		(drill 0.254)
		(layers "F.Cu" "B.Cu")
		(net "SMB_HOST_3V3AUX_SDA_R4")
	)
	(via
		(at 273.393662 -92.447364)
		(size 0.508)
		(drill 0.254)
		(layers "F.Cu" "B.Cu")
		(net "SMB_HOST_3V3AUX_SDA_R4")
	)
	(via
		(at 245.334536 -61.480954)
		(size 0.508)
		(drill 0.254)
		(layers "F.Cu" "B.Cu")
		(net "SMB_HOST_3V3AUX_SDA_R4")
	)
	(via
		(at 274.14728 -120.368568)
		(size 0.508)
		(drill 0.254)
		(layers "F.Cu" "B.Cu")
		(net "SMB_HOST_3V3AUX_SDA_R4")
	)
	(via
		(at 407.351738 -49.009554)
		(size 0.508)
		(drill 0.254)
		(layers "F.Cu" "B.Cu")
		(net "SMB_HOST_3V3AUX_SDA_R4")
	)
	(via
		(at 214.42934 -115.799108)
		(size 0.508)
		(drill 0.254)
		(layers "F.Cu" "B.Cu")
		(net "SMB_HOST_3V3AUX_SDA_R4")
	)
	(segment
		(start 355.643942 -99.519486)
		(end 284.686756 -99.519486)
		(width 0.12954)
		(layer "B.Cu")
		(net "SMB_HOST_3V3AUX_SDA_R4")
	)
	(segment
		(start 244.324632 -56.250078)
		(end 236.630972 -56.250078)
		(width 0.12954)
		(layer "B.Cu")
		(net "SMB_HOST_3V3AUX_SDA_R4")
	)
	(segment
		(start 224.175828 -49.76495)
		(end 223.694752 -49.283874)
		(width 0.12954)
		(layer "B.Cu")
		(net "SMB_HOST_3V3AUX_SDA_R4")
	)
	(segment
		(start 186.296046 -38.811454)
		(end 184.481978 -36.997386)
		(width 0.12954)
		(layer "B.Cu")
		(net "SMB_HOST_3V3AUX_SDA_R4")
	)
	(segment
		(start 194.92595 -37.9476)
		(end 194.062096 -38.811454)
		(width 0.12954)
		(layer "B.Cu")
		(net "SMB_HOST_3V3AUX_SDA_R4")
	)
	(segment
		(start 184.481978 -36.997386)
		(end 184.481978 -34.89579)
		(width 0.12954)
		(layer "B.Cu")
		(net "SMB_HOST_3V3AUX_SDA_R4")
	)
	(segment
		(start 370.543582 -110.353602)
		(end 366.478058 -110.353602)
		(width 0.12954)
		(layer "B.Cu")
		(net "SMB_HOST_3V3AUX_SDA_R4")
	)
	(segment
		(start 383.00025 -107.943904)
		(end 379.963426 -110.980728)
		(width 0.12954)
		(layer "B.Cu")
		(net "SMB_HOST_3V3AUX_SDA_R4")
	)
	(segment
		(start 245.334536 -61.480954)
		(end 245.334536 -57.259982)
		(width 0.12954)
		(layer "B.Cu")
		(net "SMB_HOST_3V3AUX_SDA_R4")
	)
	(segment
		(start 371.170708 -110.980728)
		(end 370.543582 -110.353602)
		(width 0.12954)
		(layer "B.Cu")
		(net "SMB_HOST_3V3AUX_SDA_R4")
	)
	(segment
		(start 284.686756 -99.519486)
		(end 276.403562 -91.236292)
		(width 0.12954)
		(layer "B.Cu")
		(net "SMB_HOST_3V3AUX_SDA_R4")
	)
	(segment
		(start 391.859516 -88.031066)
		(end 383.00025 -96.890332)
		(width 0.12954)
		(layer "B.Cu")
		(net "SMB_HOST_3V3AUX_SDA_R4")
	)
	(segment
		(start 180.22316 -25.579832)
		(end 180.22316 -25.040082)
		(width 0.12954)
		(layer "B.Cu")
		(net "SMB_HOST_3V3AUX_SDA_R4")
	)
	(segment
		(start 399.604484 -77.8891)
		(end 398.65554 -77.8891)
		(width 0.12954)
		(layer "B.Cu")
		(net "SMB_HOST_3V3AUX_SDA_R4")
	)
	(segment
		(start 179.797964 -26.005028)
		(end 180.22316 -25.579832)
		(width 0.12954)
		(layer "B.Cu")
		(net "SMB_HOST_3V3AUX_SDA_R4")
	)
	(segment
		(start 238.910622 -129.99085)
		(end 238.161322 -129.99085)
		(width 0.12954)
		(layer "B.Cu")
		(net "SMB_HOST_3V3AUX_SDA_R4")
	)
	(segment
		(start 229.0953 -49.76495)
		(end 224.175828 -49.76495)
		(width 0.12954)
		(layer "B.Cu")
		(net "SMB_HOST_3V3AUX_SDA_R4")
	)
	(segment
		(start 198.244968 -39.895272)
		(end 196.297296 -37.9476)
		(width 0.12954)
		(layer "B.Cu")
		(net "SMB_HOST_3V3AUX_SDA_R4")
	)
	(segment
		(start 245.334536 -57.259982)
		(end 244.324632 -56.250078)
		(width 0.12954)
		(layer "B.Cu")
		(net "SMB_HOST_3V3AUX_SDA_R4")
	)
	(segment
		(start 273.393662 -92.074238)
		(end 273.393662 -92.447364)
		(width 0.12954)
		(layer "B.Cu")
		(net "SMB_HOST_3V3AUX_SDA_R4")
	)
	(segment
		(start 213.110826 -39.895272)
		(end 198.244968 -39.895272)
		(width 0.12954)
		(layer "B.Cu")
		(net "SMB_HOST_3V3AUX_SDA_R4")
	)
	(segment
		(start 183.02605 -33.833816)
		(end 179.797964 -30.60573)
		(width 0.12954)
		(layer "B.Cu")
		(net "SMB_HOST_3V3AUX_SDA_R4")
	)
	(segment
		(start 236.630972 -56.250078)
		(end 231.455468 -51.074574)
		(width 0.12954)
		(layer "B.Cu")
		(net "SMB_HOST_3V3AUX_SDA_R4")
	)
	(segment
		(start 383.00025 -96.890332)
		(end 383.00025 -107.943904)
		(width 0.12954)
		(layer "B.Cu")
		(net "SMB_HOST_3V3AUX_SDA_R4")
	)
	(segment
		(start 223.694752 -49.283874)
		(end 222.499428 -49.283874)
		(width 0.12954)
		(layer "B.Cu")
		(net "SMB_HOST_3V3AUX_SDA_R4")
	)
	(segment
		(start 231.455468 -51.074574)
		(end 230.404924 -51.074574)
		(width 0.12954)
		(layer "B.Cu")
		(net "SMB_HOST_3V3AUX_SDA_R4")
	)
	(segment
		(start 194.062096 -38.811454)
		(end 186.296046 -38.811454)
		(width 0.12954)
		(layer "B.Cu")
		(net "SMB_HOST_3V3AUX_SDA_R4")
	)
	(segment
		(start 196.297296 -37.9476)
		(end 194.92595 -37.9476)
		(width 0.12954)
		(layer "B.Cu")
		(net "SMB_HOST_3V3AUX_SDA_R4")
	)
	(segment
		(start 239.20196 -130.282188)
		(end 238.910622 -129.99085)
		(width 0.12954)
		(layer "B.Cu")
		(net "SMB_HOST_3V3AUX_SDA_R4")
	)
	(segment
		(start 184.481978 -34.89579)
		(end 183.420004 -33.833816)
		(width 0.12954)
		(layer "B.Cu")
		(net "SMB_HOST_3V3AUX_SDA_R4")
	)
	(segment
		(start 274.231608 -91.236292)
		(end 273.393662 -92.074238)
		(width 0.12954)
		(layer "B.Cu")
		(net "SMB_HOST_3V3AUX_SDA_R4")
	)
	(segment
		(start 391.859516 -84.685124)
		(end 391.859516 -88.031066)
		(width 0.12954)
		(layer "B.Cu")
		(net "SMB_HOST_3V3AUX_SDA_R4")
	)
	(segment
		(start 180.22316 -25.040082)
		(end 179.85994 -24.676862)
		(width 0.12954)
		(layer "B.Cu")
		(net "SMB_HOST_3V3AUX_SDA_R4")
	)
	(segment
		(start 379.963426 -110.980728)
		(end 371.170708 -110.980728)
		(width 0.12954)
		(layer "B.Cu")
		(net "SMB_HOST_3V3AUX_SDA_R4")
	)
	(segment
		(start 222.499428 -49.283874)
		(end 213.110826 -39.895272)
		(width 0.12954)
		(layer "B.Cu")
		(net "SMB_HOST_3V3AUX_SDA_R4")
	)
	(segment
		(start 398.65554 -77.8891)
		(end 391.859516 -84.685124)
		(width 0.12954)
		(layer "B.Cu")
		(net "SMB_HOST_3V3AUX_SDA_R4")
	)
	(segment
		(start 179.85994 -24.676862)
		(end 179.85994 -21.764498)
		(width 0.12954)
		(layer "B.Cu")
		(net "SMB_HOST_3V3AUX_SDA_R4")
	)
	(segment
		(start 183.420004 -33.833816)
		(end 183.02605 -33.833816)
		(width 0.12954)
		(layer "B.Cu")
		(net "SMB_HOST_3V3AUX_SDA_R4")
	)
	(segment
		(start 230.404924 -51.074574)
		(end 229.0953 -49.76495)
		(width 0.12954)
		(layer "B.Cu")
		(net "SMB_HOST_3V3AUX_SDA_R4")
	)
	(segment
		(start 366.478058 -110.353602)
		(end 355.643942 -99.519486)
		(width 0.12954)
		(layer "B.Cu")
		(net "SMB_HOST_3V3AUX_SDA_R4")
	)
	(segment
		(start 276.403562 -91.236292)
		(end 274.231608 -91.236292)
		(width 0.12954)
		(layer "B.Cu")
		(net "SMB_HOST_3V3AUX_SDA_R4")
	)
	(segment
		(start 179.797964 -30.60573)
		(end 179.797964 -26.005028)
		(width 0.12954)
		(layer "B.Cu")
		(net "SMB_HOST_3V3AUX_SDA_R4")
	)
	(segment
		(start 273.39798 -111.616744)
		(end 273.39798 -106.873548)
		(width 0.127)
		(layer "In2.Cu")
		(net "SMB_HOST_3V3AUX_SDA_R4")
	)
	(segment
		(start 274.14728 -112.366044)
		(end 273.39798 -111.616744)
		(width 0.127)
		(layer "In2.Cu")
		(net "SMB_HOST_3V3AUX_SDA_R4")
	)
	(segment
		(start 273.39798 -106.873548)
		(end 275.5011 -104.770428)
		(width 0.127)
		(layer "In2.Cu")
		(net "SMB_HOST_3V3AUX_SDA_R4")
	)
	(segment
		(start 275.5011 -92.210128)
		(end 274.86356 -91.572588)
		(width 0.127)
		(layer "In2.Cu")
		(net "SMB_HOST_3V3AUX_SDA_R4")
	)
	(segment
		(start 273.64944 -91.572588)
		(end 273.393662 -91.828366)
		(width 0.127)
		(layer "In2.Cu")
		(net "SMB_HOST_3V3AUX_SDA_R4")
	)
	(segment
		(start 274.14728 -120.368568)
		(end 274.14728 -112.366044)
		(width 0.127)
		(layer "In2.Cu")
		(net "SMB_HOST_3V3AUX_SDA_R4")
	)
	(segment
		(start 273.393662 -91.828366)
		(end 273.393662 -92.447364)
		(width 0.127)
		(layer "In2.Cu")
		(net "SMB_HOST_3V3AUX_SDA_R4")
	)
	(segment
		(start 275.5011 -104.770428)
		(end 275.5011 -92.210128)
		(width 0.127)
		(layer "In2.Cu")
		(net "SMB_HOST_3V3AUX_SDA_R4")
	)
	(segment
		(start 274.86356 -91.572588)
		(end 273.64944 -91.572588)
		(width 0.127)
		(layer "In2.Cu")
		(net "SMB_HOST_3V3AUX_SDA_R4")
	)
	(segment
		(start 271.674336 -119.946928)
		(end 242.695476 -119.946928)
		(width 0.127)
		(layer "In4.Cu")
		(net "SMB_HOST_3V3AUX_SDA_R4")
	)
	(segment
		(start 274.14728 -120.368568)
		(end 274.14728 -120.042178)
		(width 0.127)
		(layer "In4.Cu")
		(net "SMB_HOST_3V3AUX_SDA_R4")
	)
	(segment
		(start 273.37512 -119.270018)
		(end 272.351246 -119.270018)
		(width 0.127)
		(layer "In4.Cu")
		(net "SMB_HOST_3V3AUX_SDA_R4")
	)
	(segment
		(start 274.14728 -120.042178)
		(end 273.37512 -119.270018)
		(width 0.127)
		(layer "In4.Cu")
		(net "SMB_HOST_3V3AUX_SDA_R4")
	)
	(segment
		(start 239.20196 -127.353568)
		(end 239.20196 -130.282188)
		(width 0.127)
		(layer "In4.Cu")
		(net "SMB_HOST_3V3AUX_SDA_R4")
	)
	(segment
		(start 272.351246 -119.270018)
		(end 271.674336 -119.946928)
		(width 0.127)
		(layer "In4.Cu")
		(net "SMB_HOST_3V3AUX_SDA_R4")
	)
	(segment
		(start 239.4839 -123.158504)
		(end 239.4839 -127.071628)
		(width 0.127)
		(layer "In4.Cu")
		(net "SMB_HOST_3V3AUX_SDA_R4")
	)
	(segment
		(start 242.695476 -119.946928)
		(end 239.4839 -123.158504)
		(width 0.127)
		(layer "In4.Cu")
		(net "SMB_HOST_3V3AUX_SDA_R4")
	)
	(segment
		(start 239.4839 -127.071628)
		(end 239.20196 -127.353568)
		(width 0.127)
		(layer "In4.Cu")
		(net "SMB_HOST_3V3AUX_SDA_R4")
	)
	(segment
		(start 409.52293 -51.180746)
		(end 409.52293 -64.305942)
		(width 0.127)
		(layer "In6.Cu")
		(net "SMB_HOST_3V3AUX_SDA_R4")
	)
	(segment
		(start 399.14703 -77.431646)
		(end 399.604484 -77.8891)
		(width 0.127)
		(layer "In6.Cu")
		(net "SMB_HOST_3V3AUX_SDA_R4")
	)
	(segment
		(start 407.351738 -49.009554)
		(end 409.52293 -51.180746)
		(width 0.127)
		(layer "In6.Cu")
		(net "SMB_HOST_3V3AUX_SDA_R4")
	)
	(segment
		(start 409.52293 -64.305942)
		(end 407.383488 -66.445384)
		(width 0.127)
		(layer "In6.Cu")
		(net "SMB_HOST_3V3AUX_SDA_R4")
	)
	(segment
		(start 407.383488 -66.445384)
		(end 405.913844 -66.445384)
		(width 0.127)
		(layer "In6.Cu")
		(net "SMB_HOST_3V3AUX_SDA_R4")
	)
	(segment
		(start 405.913844 -66.445384)
		(end 399.14703 -73.212198)
		(width 0.127)
		(layer "In6.Cu")
		(net "SMB_HOST_3V3AUX_SDA_R4")
	)
	(segment
		(start 399.14703 -73.212198)
		(end 399.14703 -77.431646)
		(width 0.127)
		(layer "In6.Cu")
		(net "SMB_HOST_3V3AUX_SDA_R4")
	)
	(segment
		(start 222.862394 -117.584728)
		(end 222.758254 -117.480588)
		(width 0.127)
		(layer "In11.Cu")
		(net "SMB_HOST_3V3AUX_SDA_R4")
	)
	(segment
		(start 222.758254 -116.111528)
		(end 222.654114 -116.007388)
		(width 0.127)
		(layer "In11.Cu")
		(net "SMB_HOST_3V3AUX_SDA_R4")
	)
	(segment
		(start 220.921834 -116.111528)
		(end 220.921834 -117.480588)
		(width 0.127)
		(layer "In11.Cu")
		(net "SMB_HOST_3V3AUX_SDA_R4")
	)
	(segment
		(start 246.664734 -136.22655)
		(end 246.201946 -136.689338)
		(width 0.127)
		(layer "In11.Cu")
		(net "SMB_HOST_3V3AUX_SDA_R4")
	)
	(segment
		(start 239.20196 -130.282188)
		(end 240.66881 -130.282188)
		(width 0.127)
		(layer "In11.Cu")
		(net "SMB_HOST_3V3AUX_SDA_R4")
	)
	(segment
		(start 228.81844 -126.531624)
		(end 228.81844 -121.720864)
		(width 0.127)
		(layer "In11.Cu")
		(net "SMB_HOST_3V3AUX_SDA_R4")
	)
	(segment
		(start 220.309694 -116.111528)
		(end 220.205554 -116.007388)
		(width 0.127)
		(layer "In11.Cu")
		(net "SMB_HOST_3V3AUX_SDA_R4")
	)
	(segment
		(start 221.025974 -116.007388)
		(end 220.921834 -116.111528)
		(width 0.127)
		(layer "In11.Cu")
		(net "SMB_HOST_3V3AUX_SDA_R4")
	)
	(segment
		(start 230.31704 -128.030224)
		(end 228.81844 -126.531624)
		(width 0.127)
		(layer "In11.Cu")
		(net "SMB_HOST_3V3AUX_SDA_R4")
	)
	(segment
		(start 237.753144 -131.065524)
		(end 231.123236 -131.065524)
		(width 0.127)
		(layer "In11.Cu")
		(net "SMB_HOST_3V3AUX_SDA_R4")
	)
	(segment
		(start 209.22234 -94.059248)
		(end 209.34934 -94.186248)
		(width 0.127)
		(layer "In11.Cu")
		(net "SMB_HOST_3V3AUX_SDA_R4")
	)
	(segment
		(start 221.533974 -117.480588)
		(end 221.533974 -116.111528)
		(width 0.127)
		(layer "In11.Cu")
		(net "SMB_HOST_3V3AUX_SDA_R4")
	)
	(segment
		(start 213.798404 -94.059248)
		(end 221.210124 -86.647528)
		(width 0.127)
		(layer "In11.Cu")
		(net "SMB_HOST_3V3AUX_SDA_R4")
	)
	(segment
		(start 209.34934 -94.186248)
		(end 209.34934 -94.336108)
		(width 0.127)
		(layer "In11.Cu")
		(net "SMB_HOST_3V3AUX_SDA_R4")
	)
	(segment
		(start 222.250254 -116.007388)
		(end 222.146114 -116.111528)
		(width 0.127)
		(layer "In11.Cu")
		(net "SMB_HOST_3V3AUX_SDA_R4")
	)
	(segment
		(start 238.53648 -130.282188)
		(end 237.753144 -131.065524)
		(width 0.127)
		(layer "In11.Cu")
		(net "SMB_HOST_3V3AUX_SDA_R4")
	)
	(segment
		(start 209.34934 -94.336108)
		(end 209.47634 -94.463108)
		(width 0.127)
		(layer "In11.Cu")
		(net "SMB_HOST_3V3AUX_SDA_R4")
	)
	(segment
		(start 212.06714 -94.059248)
		(end 213.798404 -94.059248)
		(width 0.127)
		(layer "In11.Cu")
		(net "SMB_HOST_3V3AUX_SDA_R4")
	)
	(segment
		(start 241.86896 -136.689338)
		(end 240.89741 -135.717788)
		(width 0.127)
		(layer "In11.Cu")
		(net "SMB_HOST_3V3AUX_SDA_R4")
	)
	(segment
		(start 222.758254 -117.480588)
		(end 222.758254 -116.111528)
		(width 0.127)
		(layer "In11.Cu")
		(net "SMB_HOST_3V3AUX_SDA_R4")
	)
	(segment
		(start 220.817694 -117.584728)
		(end 220.413834 -117.584728)
		(width 0.127)
		(layer "In11.Cu")
		(net "SMB_HOST_3V3AUX_SDA_R4")
	)
	(segment
		(start 210.08594 -94.463108)
		(end 210.21294 -94.336108)
		(width 0.127)
		(layer "In11.Cu")
		(net "SMB_HOST_3V3AUX_SDA_R4")
	)
	(segment
		(start 216.21496 -117.584728)
		(end 214.42934 -115.799108)
		(width 0.127)
		(layer "In11.Cu")
		(net "SMB_HOST_3V3AUX_SDA_R4")
	)
	(segment
		(start 231.123236 -131.065524)
		(end 230.31704 -130.259328)
		(width 0.127)
		(layer "In11.Cu")
		(net "SMB_HOST_3V3AUX_SDA_R4")
	)
	(segment
		(start 210.33994 -94.059248)
		(end 210.94954 -94.059248)
		(width 0.127)
		(layer "In11.Cu")
		(net "SMB_HOST_3V3AUX_SDA_R4")
	)
	(segment
		(start 210.94954 -94.059248)
		(end 211.07654 -94.186248)
		(width 0.127)
		(layer "In11.Cu")
		(net "SMB_HOST_3V3AUX_SDA_R4")
	)
	(segment
		(start 211.94014 -94.336108)
		(end 211.94014 -94.186248)
		(width 0.127)
		(layer "In11.Cu")
		(net "SMB_HOST_3V3AUX_SDA_R4")
	)
	(segment
		(start 222.146114 -117.480588)
		(end 222.041974 -117.584728)
		(width 0.127)
		(layer "In11.Cu")
		(net "SMB_HOST_3V3AUX_SDA_R4")
	)
	(segment
		(start 211.07654 -94.336108)
		(end 211.20354 -94.463108)
		(width 0.127)
		(layer "In11.Cu")
		(net "SMB_HOST_3V3AUX_SDA_R4")
	)
	(segment
		(start 224.682304 -117.584728)
		(end 222.862394 -117.584728)
		(width 0.127)
		(layer "In11.Cu")
		(net "SMB_HOST_3V3AUX_SDA_R4")
	)
	(segment
		(start 222.654114 -116.007388)
		(end 222.250254 -116.007388)
		(width 0.127)
		(layer "In11.Cu")
		(net "SMB_HOST_3V3AUX_SDA_R4")
	)
	(segment
		(start 230.31704 -130.259328)
		(end 230.31704 -128.030224)
		(width 0.127)
		(layer "In11.Cu")
		(net "SMB_HOST_3V3AUX_SDA_R4")
	)
	(segment
		(start 246.664734 -134.554976)
		(end 246.664734 -136.22655)
		(width 0.127)
		(layer "In11.Cu")
		(net "SMB_HOST_3V3AUX_SDA_R4")
	)
	(segment
		(start 221.533974 -116.111528)
		(end 221.429834 -116.007388)
		(width 0.127)
		(layer "In11.Cu")
		(net "SMB_HOST_3V3AUX_SDA_R4")
	)
	(segment
		(start 220.309694 -117.480588)
		(end 220.309694 -116.111528)
		(width 0.127)
		(layer "In11.Cu")
		(net "SMB_HOST_3V3AUX_SDA_R4")
	)
	(segment
		(start 210.21294 -94.186248)
		(end 210.33994 -94.059248)
		(width 0.127)
		(layer "In11.Cu")
		(net "SMB_HOST_3V3AUX_SDA_R4")
	)
	(segment
		(start 207.704944 -94.059248)
		(end 209.22234 -94.059248)
		(width 0.127)
		(layer "In11.Cu")
		(net "SMB_HOST_3V3AUX_SDA_R4")
	)
	(segment
		(start 246.201946 -136.689338)
		(end 241.86896 -136.689338)
		(width 0.127)
		(layer "In11.Cu")
		(net "SMB_HOST_3V3AUX_SDA_R4")
	)
	(segment
		(start 220.921834 -117.480588)
		(end 220.817694 -117.584728)
		(width 0.127)
		(layer "In11.Cu")
		(net "SMB_HOST_3V3AUX_SDA_R4")
	)
	(segment
		(start 221.429834 -116.007388)
		(end 221.025974 -116.007388)
		(width 0.127)
		(layer "In11.Cu")
		(net "SMB_HOST_3V3AUX_SDA_R4")
	)
	(segment
		(start 219.801694 -116.007388)
		(end 219.697554 -116.111528)
		(width 0.127)
		(layer "In11.Cu")
		(net "SMB_HOST_3V3AUX_SDA_R4")
	)
	(segment
		(start 245.237508 -133.12775)
		(end 246.664734 -134.554976)
		(width 0.127)
		(layer "In11.Cu")
		(net "SMB_HOST_3V3AUX_SDA_R4")
	)
	(segment
		(start 219.697554 -116.111528)
		(end 219.697554 -117.480588)
		(width 0.127)
		(layer "In11.Cu")
		(net "SMB_HOST_3V3AUX_SDA_R4")
	)
	(segment
		(start 219.593414 -117.584728)
		(end 216.21496 -117.584728)
		(width 0.127)
		(layer "In11.Cu")
		(net "SMB_HOST_3V3AUX_SDA_R4")
	)
	(segment
		(start 228.81844 -121.720864)
		(end 224.682304 -117.584728)
		(width 0.127)
		(layer "In11.Cu")
		(net "SMB_HOST_3V3AUX_SDA_R4")
	)
	(segment
		(start 221.638114 -117.584728)
		(end 221.533974 -117.480588)
		(width 0.127)
		(layer "In11.Cu")
		(net "SMB_HOST_3V3AUX_SDA_R4")
	)
	(segment
		(start 211.94014 -94.186248)
		(end 212.06714 -94.059248)
		(width 0.127)
		(layer "In11.Cu")
		(net "SMB_HOST_3V3AUX_SDA_R4")
	)
	(segment
		(start 240.89741 -135.717788)
		(end 240.89741 -135.715502)
		(width 0.127)
		(layer "In11.Cu")
		(net "SMB_HOST_3V3AUX_SDA_R4")
	)
	(segment
		(start 219.697554 -117.480588)
		(end 219.593414 -117.584728)
		(width 0.127)
		(layer "In11.Cu")
		(net "SMB_HOST_3V3AUX_SDA_R4")
	)
	(segment
		(start 207.19034 -95.070168)
		(end 207.19034 -94.573852)
		(width 0.127)
		(layer "In11.Cu")
		(net "SMB_HOST_3V3AUX_SDA_R4")
	)
	(segment
		(start 240.66881 -130.282188)
		(end 243.514372 -133.12775)
		(width 0.127)
		(layer "In11.Cu")
		(net "SMB_HOST_3V3AUX_SDA_R4")
	)
	(segment
		(start 207.19034 -94.573852)
		(end 207.704944 -94.059248)
		(width 0.127)
		(layer "In11.Cu")
		(net "SMB_HOST_3V3AUX_SDA_R4")
	)
	(segment
		(start 220.205554 -116.007388)
		(end 219.801694 -116.007388)
		(width 0.127)
		(layer "In11.Cu")
		(net "SMB_HOST_3V3AUX_SDA_R4")
	)
	(segment
		(start 222.041974 -117.584728)
		(end 221.638114 -117.584728)
		(width 0.127)
		(layer "In11.Cu")
		(net "SMB_HOST_3V3AUX_SDA_R4")
	)
	(segment
		(start 221.210124 -86.647528)
		(end 227.72116 -86.647528)
		(width 0.127)
		(layer "In11.Cu")
		(net "SMB_HOST_3V3AUX_SDA_R4")
	)
	(segment
		(start 222.146114 -116.111528)
		(end 222.146114 -117.480588)
		(width 0.127)
		(layer "In11.Cu")
		(net "SMB_HOST_3V3AUX_SDA_R4")
	)
	(segment
		(start 243.514372 -133.12775)
		(end 245.237508 -133.12775)
		(width 0.127)
		(layer "In11.Cu")
		(net "SMB_HOST_3V3AUX_SDA_R4")
	)
	(segment
		(start 211.07654 -94.186248)
		(end 211.07654 -94.336108)
		(width 0.127)
		(layer "In11.Cu")
		(net "SMB_HOST_3V3AUX_SDA_R4")
	)
	(segment
		(start 211.81314 -94.463108)
		(end 211.94014 -94.336108)
		(width 0.127)
		(layer "In11.Cu")
		(net "SMB_HOST_3V3AUX_SDA_R4")
	)
	(segment
		(start 211.20354 -94.463108)
		(end 211.81314 -94.463108)
		(width 0.127)
		(layer "In11.Cu")
		(net "SMB_HOST_3V3AUX_SDA_R4")
	)
	(segment
		(start 239.20196 -130.282188)
		(end 238.53648 -130.282188)
		(width 0.127)
		(layer "In11.Cu")
		(net "SMB_HOST_3V3AUX_SDA_R4")
	)
	(segment
		(start 220.413834 -117.584728)
		(end 220.309694 -117.480588)
		(width 0.127)
		(layer "In11.Cu")
		(net "SMB_HOST_3V3AUX_SDA_R4")
	)
	(segment
		(start 209.47634 -94.463108)
		(end 210.08594 -94.463108)
		(width 0.127)
		(layer "In11.Cu")
		(net "SMB_HOST_3V3AUX_SDA_R4")
	)
	(segment
		(start 210.21294 -94.336108)
		(end 210.21294 -94.186248)
		(width 0.127)
		(layer "In11.Cu")
		(net "SMB_HOST_3V3AUX_SDA_R4")
	)
	(segment
		(start 5.862066 -50.891948)
		(end 5.09905 -50.891948)
		(width 0.12954)
		(layer "F.Cu")
		(net "SMB_HOST_3V3AUX_SCL_R5")
	)
	(segment
		(start 9.25195 -51.018948)
		(end 8.509 -51.018948)
		(width 0.12954)
		(layer "F.Cu")
		(net "SMB_HOST_3V3AUX_SCL_R5")
	)
	(segment
		(start 8.509 -51.018948)
		(end 5.989066 -51.018948)
		(width 0.12954)
		(layer "F.Cu")
		(net "SMB_HOST_3V3AUX_SCL_R5")
	)
	(segment
		(start 5.989066 -51.018948)
		(end 5.862066 -50.891948)
		(width 0.12954)
		(layer "F.Cu")
		(net "SMB_HOST_3V3AUX_SCL_R5")
	)
	(via
		(at 91.74226 -53.533548)
		(size 0.508)
		(drill 0.254)
		(layers "F.Cu" "B.Cu")
		(net "SMB_HOST_3V3AUX_SCL_R5")
	)
	(via
		(at 184.93486 -19.083528)
		(size 0.508)
		(drill 0.254)
		(layers "F.Cu" "B.Cu")
		(net "SMB_HOST_3V3AUX_SCL_R5")
	)
	(via
		(at 8.509 -51.018948)
		(size 0.508)
		(drill 0.254)
		(layers "F.Cu" "B.Cu")
		(net "SMB_HOST_3V3AUX_SCL_R5")
	)
	(segment
		(start 184.93486 -19.862038)
		(end 184.912 -19.884898)
		(width 0.12954)
		(layer "B.Cu")
		(net "SMB_HOST_3V3AUX_SCL_R5")
	)
	(segment
		(start 184.93486 -19.083528)
		(end 184.93486 -19.862038)
		(width 0.12954)
		(layer "B.Cu")
		(net "SMB_HOST_3V3AUX_SCL_R5")
	)
	(segment
		(start 91.74226 -53.533548)
		(end 97.71888 -53.533548)
		(width 0.127)
		(layer "In4.Cu")
		(net "SMB_HOST_3V3AUX_SCL_R5")
	)
	(segment
		(start 164.19068 -21.417788)
		(end 166.703248 -21.417788)
		(width 0.127)
		(layer "In4.Cu")
		(net "SMB_HOST_3V3AUX_SCL_R5")
	)
	(segment
		(start 113.538 -52.847748)
		(end 113.538 -44.674536)
		(width 0.127)
		(layer "In4.Cu")
		(net "SMB_HOST_3V3AUX_SCL_R5")
	)
	(segment
		(start 184.21223 -18.360898)
		(end 184.93486 -19.083528)
		(width 0.127)
		(layer "In4.Cu")
		(net "SMB_HOST_3V3AUX_SCL_R5")
	)
	(segment
		(start 171.22648 -17.668748)
		(end 172.02404 -16.871188)
		(width 0.127)
		(layer "In4.Cu")
		(net "SMB_HOST_3V3AUX_SCL_R5")
	)
	(segment
		(start 138.965432 -34.008568)
		(end 150.174452 -22.799548)
		(width 0.127)
		(layer "In4.Cu")
		(net "SMB_HOST_3V3AUX_SCL_R5")
	)
	(segment
		(start 180.365654 -18.360898)
		(end 184.21223 -18.360898)
		(width 0.127)
		(layer "In4.Cu")
		(net "SMB_HOST_3V3AUX_SCL_R5")
	)
	(segment
		(start 111.00816 -55.377588)
		(end 113.538 -52.847748)
		(width 0.127)
		(layer "In4.Cu")
		(net "SMB_HOST_3V3AUX_SCL_R5")
	)
	(segment
		(start 99.6696 -54.519068)
		(end 104.77246 -54.519068)
		(width 0.127)
		(layer "In4.Cu")
		(net "SMB_HOST_3V3AUX_SCL_R5")
	)
	(segment
		(start 178.875944 -16.871188)
		(end 180.365654 -18.360898)
		(width 0.127)
		(layer "In4.Cu")
		(net "SMB_HOST_3V3AUX_SCL_R5")
	)
	(segment
		(start 97.71888 -53.533548)
		(end 98.27768 -54.092348)
		(width 0.127)
		(layer "In4.Cu")
		(net "SMB_HOST_3V3AUX_SCL_R5")
	)
	(segment
		(start 152.88006 -22.799548)
		(end 153.24582 -22.433788)
		(width 0.127)
		(layer "In4.Cu")
		(net "SMB_HOST_3V3AUX_SCL_R5")
	)
	(segment
		(start 124.203968 -34.008568)
		(end 138.965432 -34.008568)
		(width 0.127)
		(layer "In4.Cu")
		(net "SMB_HOST_3V3AUX_SCL_R5")
	)
	(segment
		(start 166.703248 -21.417788)
		(end 170.452288 -17.668748)
		(width 0.127)
		(layer "In4.Cu")
		(net "SMB_HOST_3V3AUX_SCL_R5")
	)
	(segment
		(start 163.17468 -22.433788)
		(end 164.19068 -21.417788)
		(width 0.127)
		(layer "In4.Cu")
		(net "SMB_HOST_3V3AUX_SCL_R5")
	)
	(segment
		(start 98.27768 -54.092348)
		(end 99.24288 -54.092348)
		(width 0.127)
		(layer "In4.Cu")
		(net "SMB_HOST_3V3AUX_SCL_R5")
	)
	(segment
		(start 99.24288 -54.092348)
		(end 99.6696 -54.519068)
		(width 0.127)
		(layer "In4.Cu")
		(net "SMB_HOST_3V3AUX_SCL_R5")
	)
	(segment
		(start 153.24582 -22.433788)
		(end 163.17468 -22.433788)
		(width 0.127)
		(layer "In4.Cu")
		(net "SMB_HOST_3V3AUX_SCL_R5")
	)
	(segment
		(start 150.174452 -22.799548)
		(end 152.88006 -22.799548)
		(width 0.127)
		(layer "In4.Cu")
		(net "SMB_HOST_3V3AUX_SCL_R5")
	)
	(segment
		(start 104.77246 -54.519068)
		(end 105.63098 -55.377588)
		(width 0.127)
		(layer "In4.Cu")
		(net "SMB_HOST_3V3AUX_SCL_R5")
	)
	(segment
		(start 105.63098 -55.377588)
		(end 111.00816 -55.377588)
		(width 0.127)
		(layer "In4.Cu")
		(net "SMB_HOST_3V3AUX_SCL_R5")
	)
	(segment
		(start 170.452288 -17.668748)
		(end 171.22648 -17.668748)
		(width 0.127)
		(layer "In4.Cu")
		(net "SMB_HOST_3V3AUX_SCL_R5")
	)
	(segment
		(start 113.538 -44.674536)
		(end 124.203968 -34.008568)
		(width 0.127)
		(layer "In4.Cu")
		(net "SMB_HOST_3V3AUX_SCL_R5")
	)
	(segment
		(start 172.02404 -16.871188)
		(end 178.875944 -16.871188)
		(width 0.127)
		(layer "In4.Cu")
		(net "SMB_HOST_3V3AUX_SCL_R5")
	)
	(segment
		(start 67.79768 -43.017948)
		(end 67.89928 -43.119548)
		(width 0.127)
		(layer "In6.Cu")
		(net "SMB_HOST_3V3AUX_SCL_R5")
	)
	(segment
		(start 79.38008 -43.576748)
		(end 82.28076 -46.477428)
		(width 0.127)
		(layer "In6.Cu")
		(net "SMB_HOST_3V3AUX_SCL_R5")
	)
	(segment
		(start 19.52498 -57.615328)
		(end 26.58618 -50.554128)
		(width 0.127)
		(layer "In6.Cu")
		(net "SMB_HOST_3V3AUX_SCL_R5")
	)
	(segment
		(start 67.89928 -43.119548)
		(end 72.57796 -43.119548)
		(width 0.127)
		(layer "In6.Cu")
		(net "SMB_HOST_3V3AUX_SCL_R5")
	)
	(segment
		(start 82.28076 -46.477428)
		(end 82.28076 -47.749968)
		(width 0.127)
		(layer "In6.Cu")
		(net "SMB_HOST_3V3AUX_SCL_R5")
	)
	(segment
		(start 5.38988 -54.943248)
		(end 5.38988 -57.337452)
		(width 0.127)
		(layer "In6.Cu")
		(net "SMB_HOST_3V3AUX_SCL_R5")
	)
	(segment
		(start 53.076348 -43.017948)
		(end 67.79768 -43.017948)
		(width 0.127)
		(layer "In6.Cu")
		(net "SMB_HOST_3V3AUX_SCL_R5")
	)
	(segment
		(start 45.540168 -50.554128)
		(end 53.076348 -43.017948)
		(width 0.127)
		(layer "In6.Cu")
		(net "SMB_HOST_3V3AUX_SCL_R5")
	)
	(segment
		(start 82.28076 -47.749968)
		(end 88.06434 -53.533548)
		(width 0.127)
		(layer "In6.Cu")
		(net "SMB_HOST_3V3AUX_SCL_R5")
	)
	(segment
		(start 8.476996 -61.948568)
		(end 10.14476 -61.948568)
		(width 0.127)
		(layer "In6.Cu")
		(net "SMB_HOST_3V3AUX_SCL_R5")
	)
	(segment
		(start 7.178548 -57.7977)
		(end 8.05688 -58.676032)
		(width 0.127)
		(layer "In6.Cu")
		(net "SMB_HOST_3V3AUX_SCL_R5")
	)
	(segment
		(start 72.57796 -43.119548)
		(end 73.03516 -43.576748)
		(width 0.127)
		(layer "In6.Cu")
		(net "SMB_HOST_3V3AUX_SCL_R5")
	)
	(segment
		(start 8.509 -51.018948)
		(end 8.509 -51.824128)
		(width 0.127)
		(layer "In6.Cu")
		(net "SMB_HOST_3V3AUX_SCL_R5")
	)
	(segment
		(start 26.58618 -50.554128)
		(end 45.540168 -50.554128)
		(width 0.127)
		(layer "In6.Cu")
		(net "SMB_HOST_3V3AUX_SCL_R5")
	)
	(segment
		(start 5.850128 -57.7977)
		(end 7.178548 -57.7977)
		(width 0.127)
		(layer "In6.Cu")
		(net "SMB_HOST_3V3AUX_SCL_R5")
	)
	(segment
		(start 88.06434 -53.533548)
		(end 91.74226 -53.533548)
		(width 0.127)
		(layer "In6.Cu")
		(net "SMB_HOST_3V3AUX_SCL_R5")
	)
	(segment
		(start 14.478 -57.615328)
		(end 19.52498 -57.615328)
		(width 0.127)
		(layer "In6.Cu")
		(net "SMB_HOST_3V3AUX_SCL_R5")
	)
	(segment
		(start 8.05688 -61.528452)
		(end 8.476996 -61.948568)
		(width 0.127)
		(layer "In6.Cu")
		(net "SMB_HOST_3V3AUX_SCL_R5")
	)
	(segment
		(start 73.03516 -43.576748)
		(end 79.38008 -43.576748)
		(width 0.127)
		(layer "In6.Cu")
		(net "SMB_HOST_3V3AUX_SCL_R5")
	)
	(segment
		(start 8.05688 -58.676032)
		(end 8.05688 -61.528452)
		(width 0.127)
		(layer "In6.Cu")
		(net "SMB_HOST_3V3AUX_SCL_R5")
	)
	(segment
		(start 8.509 -51.824128)
		(end 5.38988 -54.943248)
		(width 0.127)
		(layer "In6.Cu")
		(net "SMB_HOST_3V3AUX_SCL_R5")
	)
	(segment
		(start 5.38988 -57.337452)
		(end 5.850128 -57.7977)
		(width 0.127)
		(layer "In6.Cu")
		(net "SMB_HOST_3V3AUX_SCL_R5")
	)
	(segment
		(start 10.14476 -61.948568)
		(end 14.478 -57.615328)
		(width 0.127)
		(layer "In6.Cu")
		(net "SMB_HOST_3V3AUX_SCL_R5")
	)
	(segment
		(start 242.645438 -136.348724)
		(end 242.645438 -135.589264)
		(width 0.12954)
		(layer "F.Cu")
		(net "SMB_HOST_3V3AUX_SCL_R4")
	)
	(segment
		(start 242.645438 -135.589264)
		(end 242.601242 -135.545068)
		(width 0.12954)
		(layer "F.Cu")
		(net "SMB_HOST_3V3AUX_SCL_R4")
	)
	(via
		(at 239.842294 -131.539234)
		(size 0.508)
		(drill 0.254)
		(layers "F.Cu" "B.Cu")
		(net "SMB_HOST_3V3AUX_SCL_R4")
	)
	(via
		(at 242.601242 -135.545068)
		(size 0.508)
		(drill 0.254)
		(layers "F.Cu" "B.Cu")
		(net "SMB_HOST_3V3AUX_SCL_R4")
	)
	(via
		(at 236.985048 -131.244594)
		(size 0.7112)
		(drill 0.3556)
		(layers "F.Cu" "B.Cu")
		(net "SMB_HOST_3V3AUX_SCL_R4")
	)
	(segment
		(start 239.201198 -132.908802)
		(end 238.75238 -132.908802)
		(width 0.12954)
		(layer "B.Cu")
		(net "SMB_HOST_3V3AUX_SCL_R4")
	)
	(segment
		(start 238.75238 -132.908802)
		(end 238.26597 -132.422392)
		(width 0.12954)
		(layer "B.Cu")
		(net "SMB_HOST_3V3AUX_SCL_R4")
	)
	(segment
		(start 238.26597 -132.422392)
		(end 237.80623 -132.422392)
		(width 0.12954)
		(layer "B.Cu")
		(net "SMB_HOST_3V3AUX_SCL_R4")
	)
	(segment
		(start 239.328198 -132.781548)
		(end 239.328198 -132.781802)
		(width 0.12954)
		(layer "B.Cu")
		(net "SMB_HOST_3V3AUX_SCL_R4")
	)
	(segment
		(start 239.842294 -131.539234)
		(end 239.328198 -132.781548)
		(width 0.12954)
		(layer "B.Cu")
		(net "SMB_HOST_3V3AUX_SCL_R4")
	)
	(segment
		(start 239.328198 -132.781802)
		(end 239.201198 -132.908802)
		(width 0.12954)
		(layer "B.Cu")
		(net "SMB_HOST_3V3AUX_SCL_R4")
	)
	(segment
		(start 236.36986 -130.629406)
		(end 236.985048 -131.244594)
		(width 0.12954)
		(layer "B.Cu")
		(net "SMB_HOST_3V3AUX_SCL_R4")
	)
	(segment
		(start 237.80623 -132.065776)
		(end 236.985048 -131.244594)
		(width 0.12954)
		(layer "B.Cu")
		(net "SMB_HOST_3V3AUX_SCL_R4")
	)
	(segment
		(start 237.80623 -132.422392)
		(end 237.80623 -132.065776)
		(width 0.12954)
		(layer "B.Cu")
		(net "SMB_HOST_3V3AUX_SCL_R4")
	)
	(segment
		(start 236.36986 -130.072892)
		(end 236.36986 -130.629406)
		(width 0.12954)
		(layer "B.Cu")
		(net "SMB_HOST_3V3AUX_SCL_R4")
	)
	(segment
		(start 237.586012 -133.103874)
		(end 241.369088 -133.103874)
		(width 0.127)
		(layer "In11.Cu")
		(net "SMB_HOST_3V3AUX_SCL_R4")
	)
	(segment
		(start 241.135408 -131.539234)
		(end 241.496088 -131.899914)
		(width 0.127)
		(layer "In11.Cu")
		(net "SMB_HOST_3V3AUX_SCL_R4")
	)
	(segment
		(start 241.496088 -133.230874)
		(end 241.496088 -135.160766)
		(width 0.127)
		(layer "In11.Cu")
		(net "SMB_HOST_3V3AUX_SCL_R4")
	)
	(segment
		(start 241.496088 -131.899914)
		(end 241.496088 -132.468874)
		(width 0.127)
		(layer "In11.Cu")
		(net "SMB_HOST_3V3AUX_SCL_R4")
	)
	(segment
		(start 241.496088 -132.468874)
		(end 241.369088 -132.595874)
		(width 0.127)
		(layer "In11.Cu")
		(net "SMB_HOST_3V3AUX_SCL_R4")
	)
	(segment
		(start 237.459012 -132.976874)
		(end 237.586012 -133.103874)
		(width 0.127)
		(layer "In11.Cu")
		(net "SMB_HOST_3V3AUX_SCL_R4")
	)
	(segment
		(start 239.842294 -131.539234)
		(end 241.135408 -131.539234)
		(width 0.127)
		(layer "In11.Cu")
		(net "SMB_HOST_3V3AUX_SCL_R4")
	)
	(segment
		(start 241.88039 -135.545068)
		(end 242.601242 -135.545068)
		(width 0.127)
		(layer "In11.Cu")
		(net "SMB_HOST_3V3AUX_SCL_R4")
	)
	(segment
		(start 241.369088 -132.595874)
		(end 237.586012 -132.595874)
		(width 0.127)
		(layer "In11.Cu")
		(net "SMB_HOST_3V3AUX_SCL_R4")
	)
	(segment
		(start 237.586012 -132.595874)
		(end 237.459012 -132.722874)
		(width 0.127)
		(layer "In11.Cu")
		(net "SMB_HOST_3V3AUX_SCL_R4")
	)
	(segment
		(start 241.369088 -133.103874)
		(end 241.496088 -133.230874)
		(width 0.127)
		(layer "In11.Cu")
		(net "SMB_HOST_3V3AUX_SCL_R4")
	)
	(segment
		(start 237.459012 -132.722874)
		(end 237.459012 -132.976874)
		(width 0.127)
		(layer "In11.Cu")
		(net "SMB_HOST_3V3AUX_SCL_R4")
	)
	(segment
		(start 241.496088 -135.160766)
		(end 241.88039 -135.545068)
		(width 0.127)
		(layer "In11.Cu")
		(net "SMB_HOST_3V3AUX_SCL_R4")
	)
	(segment
		(start 161.823654 -15.154148)
		(end 161.163 -15.814802)
		(width 0.12954)
		(layer "F.Cu")
		(net "SMB_1_PLD_3V3AUX_SDA_R3")
	)
	(segment
		(start 162.7378 -13.671042)
		(end 162.7378 -14.798802)
		(width 0.12954)
		(layer "F.Cu")
		(net "SMB_1_PLD_3V3AUX_SDA_R3")
	)
	(segment
		(start 162.7378 -14.798802)
		(end 162.382454 -15.154148)
		(width 0.12954)
		(layer "F.Cu")
		(net "SMB_1_PLD_3V3AUX_SDA_R3")
	)
	(segment
		(start 161.163 -18.649188)
		(end 161.163 -20.265898)
		(width 0.12954)
		(layer "F.Cu")
		(net "SMB_1_PLD_3V3AUX_SDA_R3")
	)
	(segment
		(start 161.163 -15.814802)
		(end 161.163 -18.649188)
		(width 0.12954)
		(layer "F.Cu")
		(net "SMB_1_PLD_3V3AUX_SDA_R3")
	)
	(segment
		(start 162.666934 -13.600176)
		(end 162.7378 -13.671042)
		(width 0.12954)
		(layer "F.Cu")
		(net "SMB_1_PLD_3V3AUX_SDA_R3")
	)
	(segment
		(start 162.382454 -15.154148)
		(end 161.823654 -15.154148)
		(width 0.12954)
		(layer "F.Cu")
		(net "SMB_1_PLD_3V3AUX_SDA_R3")
	)
	(via
		(at 161.163 -18.649188)
		(size 0.508)
		(drill 0.254)
		(layers "F.Cu" "B.Cu")
		(net "SMB_1_PLD_3V3AUX_SDA_R3")
	)
	(segment
		(start 163.267136 -13.600176)
		(end 163.267136 -15.061946)
		(width 0.12954)
		(layer "F.Cu")
		(net "SMB_1_PLD_3V3AUX_SCL_R3")
	)
	(segment
		(start 161.798 -17.308068)
		(end 161.798 -18.126202)
		(width 0.12954)
		(layer "F.Cu")
		(net "SMB_1_PLD_3V3AUX_SCL_R3")
	)
	(segment
		(start 163.267136 -15.061946)
		(end 162.694874 -15.634208)
		(width 0.12954)
		(layer "F.Cu")
		(net "SMB_1_PLD_3V3AUX_SCL_R3")
	)
	(segment
		(start 161.798 -18.126202)
		(end 162.179 -18.507202)
		(width 0.12954)
		(layer "F.Cu")
		(net "SMB_1_PLD_3V3AUX_SCL_R3")
	)
	(segment
		(start 161.798 -16.073882)
		(end 161.798 -17.308068)
		(width 0.12954)
		(layer "F.Cu")
		(net "SMB_1_PLD_3V3AUX_SCL_R3")
	)
	(segment
		(start 162.179 -18.507202)
		(end 162.179 -20.265898)
		(width 0.12954)
		(layer "F.Cu")
		(net "SMB_1_PLD_3V3AUX_SCL_R3")
	)
	(segment
		(start 162.694874 -15.634208)
		(end 162.237674 -15.634208)
		(width 0.12954)
		(layer "F.Cu")
		(net "SMB_1_PLD_3V3AUX_SCL_R3")
	)
	(segment
		(start 162.237674 -15.634208)
		(end 161.798 -16.073882)
		(width 0.12954)
		(layer "F.Cu")
		(net "SMB_1_PLD_3V3AUX_SCL_R3")
	)
	(via
		(at 161.798 -17.308068)
		(size 0.508)
		(drill 0.254)
		(layers "F.Cu" "B.Cu")
		(net "SMB_1_PLD_3V3AUX_SCL_R3")
	)
	(segment
		(start 109.89056 -415.158428)
		(end 109.89056 -415.733484)
		(width 0.12954)
		(layer "F.Cu")
		(net "NC_U314_NC2")
	)
	(segment
		(start 109.89056 -415.733484)
		(end 109.48289 -416.141154)
		(width 0.12954)
		(layer "F.Cu")
		(net "NC_U314_NC2")
	)
	(segment
		(start 109.48289 -416.141154)
		(end 109.48289 -417.030154)
		(width 0.12954)
		(layer "F.Cu")
		(net "NC_U314_NC2")
	)
	(via
		(at 109.48289 -417.030154)
		(size 0.762)
		(drill 0.381)
		(layers "F.Cu" "B.Cu")
		(net "NC_U314_NC2")
	)
	(segment
		(start 113.61928 -416.86988)
		(end 113.015522 -416.266122)
		(width 0.12954)
		(layer "F.Cu")
		(net "NC_U314_NC1")
	)
	(segment
		(start 113.51768 -417.64712)
		(end 113.61928 -417.54552)
		(width 0.12954)
		(layer "F.Cu")
		(net "NC_U314_NC1")
	)
	(segment
		(start 113.015522 -416.266122)
		(end 113.015522 -415.783268)
		(width 0.12954)
		(layer "F.Cu")
		(net "NC_U314_NC1")
	)
	(segment
		(start 113.61928 -417.54552)
		(end 113.61928 -416.86988)
		(width 0.12954)
		(layer "F.Cu")
		(net "NC_U314_NC1")
	)
	(via
		(at 113.51768 -417.64712)
		(size 0.762)
		(drill 0.381)
		(layers "F.Cu" "B.Cu")
		(net "NC_U314_NC1")
	)
	(segment
		(start 118.72722 -423.225468)
		(end 116.281708 -420.779956)
		(width 0.12954)
		(layer "F.Cu")
		(net "NC_U314_FBOUT_N")
	)
	(segment
		(start 115.34013 -415.698178)
		(end 114.80038 -415.158428)
		(width 0.12954)
		(layer "F.Cu")
		(net "NC_U314_FBOUT_N")
	)
	(segment
		(start 116.281708 -416.27806)
		(end 115.957604 -415.953956)
		(width 0.12954)
		(layer "F.Cu")
		(net "NC_U314_FBOUT_N")
	)
	(segment
		(start 116.281708 -420.779956)
		(end 116.281708 -416.27806)
		(width 0.12954)
		(layer "F.Cu")
		(net "NC_U314_FBOUT_N")
	)
	(segment
		(start 115.957604 -415.953956)
		(end 115.34013 -415.698178)
		(width 0.12954)
		(layer "F.Cu")
		(net "NC_U314_FBOUT_N")
	)
	(segment
		(start 114.80038 -415.158428)
		(end 114.64036 -415.158428)
		(width 0.12954)
		(layer "F.Cu")
		(net "NC_U314_FBOUT_N")
	)
	(via
		(at 118.72722 -423.225468)
		(size 0.762)
		(drill 0.381)
		(layers "F.Cu" "B.Cu")
		(net "NC_U314_FBOUT_N")
	)
	(segment
		(start 114.01552 -416.030156)
		(end 114.01552 -415.783268)
		(width 0.12954)
		(layer "F.Cu")
		(net "NC_U314_FBOUT")
	)
	(segment
		(start 118.004844 -423.441114)
		(end 115.943888 -421.380158)
		(width 0.12954)
		(layer "F.Cu")
		(net "NC_U314_FBOUT")
	)
	(segment
		(start 114.205004 -416.21964)
		(end 114.01552 -416.030156)
		(width 0.12954)
		(layer "F.Cu")
		(net "NC_U314_FBOUT")
	)
	(segment
		(start 115.673378 -416.21964)
		(end 114.205004 -416.21964)
		(width 0.12954)
		(layer "F.Cu")
		(net "NC_U314_FBOUT")
	)
	(segment
		(start 115.943888 -416.49015)
		(end 115.673378 -416.21964)
		(width 0.12954)
		(layer "F.Cu")
		(net "NC_U314_FBOUT")
	)
	(segment
		(start 115.943888 -421.380158)
		(end 115.943888 -416.49015)
		(width 0.12954)
		(layer "F.Cu")
		(net "NC_U314_FBOUT")
	)
	(segment
		(start 118.004844 -425.447714)
		(end 118.004844 -423.441114)
		(width 0.12954)
		(layer "F.Cu")
		(net "NC_U314_FBOUT")
	)
	(via
		(at 118.004844 -425.447714)
		(size 0.762)
		(drill 0.381)
		(layers "F.Cu" "B.Cu")
		(net "NC_U314_FBOUT")
	)
	(via
		(at 341.650066 -421.769032)
		(size 0.6604)
		(drill 0.3302)
		(layers "F.Cu" "B.Cu")
		(net "NC_J107_N6")
	)
	(segment
		(start 341.650066 -424.689778)
		(end 341.650066 -421.769032)
		(width 0.12954)
		(layer "B.Cu")
		(net "NC_J107_N6")
	)
	(segment
		(start 184.555638 -112.175544)
		(end 184.955688 -111.775494)
		(width 0.12954)
		(layer "F.Cu")
		(net "HSC_D_OC_R1")
	)
	(via
		(at 188.55944 -110.912148)
		(size 0.6604)
		(drill 0.3302)
		(layers "F.Cu" "B.Cu")
		(net "HSC_D_OC_R1")
	)
	(via
		(at 184.955688 -111.775494)
		(size 0.4572)
		(drill 0.254)
		(layers "F.Cu" "B.Cu")
		(net "HSC_D_OC_R1")
	)
	(segment
		(start 193.02222 -108.168948)
		(end 196.34073 -108.168948)
		(width 0.12954)
		(layer "B.Cu")
		(net "HSC_D_OC_R1")
	)
	(segment
		(start 188.55944 -110.912148)
		(end 190.27902 -110.912148)
		(width 0.12954)
		(layer "B.Cu")
		(net "HSC_D_OC_R1")
	)
	(segment
		(start 190.27902 -110.912148)
		(end 193.02222 -108.168948)
		(width 0.12954)
		(layer "B.Cu")
		(net "HSC_D_OC_R1")
	)
	(segment
		(start 187.9727 -110.912148)
		(end 188.55944 -110.912148)
		(width 0.12954)
		(layer "B.Cu")
		(net "HSC_D_OC_R1")
	)
	(segment
		(start 196.34073 -108.168948)
		(end 197.01383 -107.495848)
		(width 0.12954)
		(layer "B.Cu")
		(net "HSC_D_OC_R1")
	)
	(segment
		(start 184.955688 -111.775494)
		(end 185.357008 -112.176814)
		(width 0.12954)
		(layer "B.Cu")
		(net "HSC_D_OC_R1")
	)
	(segment
		(start 185.357008 -112.176814)
		(end 186.708034 -112.176814)
		(width 0.12954)
		(layer "B.Cu")
		(net "HSC_D_OC_R1")
	)
	(segment
		(start 186.708034 -112.176814)
		(end 187.9727 -110.912148)
		(width 0.12954)
		(layer "B.Cu")
		(net "HSC_D_OC_R1")
	)
	(via
		(at 213.994238 -2.788412)
		(size 0.508)
		(drill 0.254)
		(layers "F.Cu" "B.Cu")
		(net "DELTA_L_GND_1")
	)
	(via
		(at 327.09993 8.633206)
		(size 0.508)
		(drill 0.254)
		(layers "F.Cu" "B.Cu")
		(net "DELTA_L_GND_1")
	)
	(via
		(at 260.77926 1.300988)
		(size 0.508)
		(drill 0.254)
		(layers "F.Cu" "B.Cu")
		(net "DELTA_L_GND_1")
	)
	(via
		(at 327.09993 1.013206)
		(size 0.508)
		(drill 0.254)
		(layers "F.Cu" "B.Cu")
		(net "DELTA_L_GND_1")
	)
	(via
		(at 375.959116 3.553206)
		(size 0.508)
		(drill 0.254)
		(layers "F.Cu" "B.Cu")
		(net "DELTA_L_GND_1")
	)
	(via
		(at 251.44095 2.931922)
		(size 0.508)
		(drill 0.254)
		(layers "F.Cu" "B.Cu")
		(net "DELTA_L_GND_1")
	)
	(via
		(at 338.512404 -0.611124)
		(size 0.508)
		(drill 0.254)
		(layers "F.Cu" "B.Cu")
		(net "DELTA_L_GND_1")
	)
	(via
		(at 340.110826 6.723888)
		(size 0.508)
		(drill 0.254)
		(layers "F.Cu" "B.Cu")
		(net "DELTA_L_GND_1")
	)
	(via
		(at 250.607068 -3.090926)
		(size 0.508)
		(drill 0.254)
		(layers "F.Cu" "B.Cu")
		(net "DELTA_L_GND_1")
	)
	(via
		(at 338.516214 -1.249934)
		(size 0.508)
		(drill 0.254)
		(layers "F.Cu" "B.Cu")
		(net "DELTA_L_GND_1")
	)
	(via
		(at 259.945378 1.936242)
		(size 0.508)
		(drill 0.254)
		(layers "F.Cu" "B.Cu")
		(net "DELTA_L_GND_1")
	)
	(via
		(at 251.44095 -4.837176)
		(size 0.508)
		(drill 0.254)
		(layers "F.Cu" "B.Cu")
		(net "DELTA_L_GND_1")
	)
	(via
		(at 262.871966 2.294382)
		(size 0.508)
		(drill 0.254)
		(layers "F.Cu" "B.Cu")
		(net "DELTA_L_GND_1")
	)
	(via
		(at 378.885704 6.466078)
		(size 0.508)
		(drill 0.254)
		(layers "F.Cu" "B.Cu")
		(net "DELTA_L_GND_1")
	)
	(via
		(at 211.905342 -5.697728)
		(size 0.508)
		(drill 0.254)
		(layers "F.Cu" "B.Cu")
		(net "DELTA_L_GND_1")
	)
	(via
		(at 378.048012 6.462522)
		(size 0.508)
		(drill 0.254)
		(layers "F.Cu" "B.Cu")
		(net "DELTA_L_GND_1")
	)
	(via
		(at 259.945378 -5.705856)
		(size 0.508)
		(drill 0.254)
		(layers "F.Cu" "B.Cu")
		(net "DELTA_L_GND_1")
	)
	(via
		(at 250.603258 1.364996)
		(size 0.508)
		(drill 0.254)
		(layers "F.Cu" "B.Cu")
		(net "DELTA_L_GND_1")
	)
	(via
		(at 330.022708 9.652254)
		(size 0.508)
		(drill 0.254)
		(layers "F.Cu" "B.Cu")
		(net "DELTA_L_GND_1")
	)
	(via
		(at 327.09993 7.374382)
		(size 0.508)
		(drill 0.254)
		(layers "F.Cu" "B.Cu")
		(net "DELTA_L_GND_1")
	)
	(via
		(at 181.36362 3.827272)
		(size 0.508)
		(drill 0.254)
		(layers "F.Cu" "B.Cu")
		(net "DELTA_L_GND_1")
	)
	(via
		(at 250.607068 2.003806)
		(size 0.508)
		(drill 0.254)
		(layers "F.Cu" "B.Cu")
		(net "DELTA_L_GND_1")
	)
	(via
		(at 250.603258 6.459728)
		(size 0.508)
		(drill 0.254)
		(layers "F.Cu" "B.Cu")
		(net "DELTA_L_GND_1")
	)
	(via
		(at 181.35981 5.450078)
		(size 0.508)
		(drill 0.254)
		(layers "F.Cu" "B.Cu")
		(net "DELTA_L_GND_1")
	)
	(via
		(at 330.026518 -3.723386)
		(size 0.508)
		(drill 0.254)
		(layers "F.Cu" "B.Cu")
		(net "DELTA_L_GND_1")
	)
	(via
		(at 250.607068 -5.765292)
		(size 0.508)
		(drill 0.254)
		(layers "F.Cu" "B.Cu")
		(net "DELTA_L_GND_1")
	)
	(via
		(at 212.666072 -6.00837)
		(size 0.508)
		(drill 0.254)
		(layers "F.Cu" "B.Cu")
		(net "DELTA_L_GND_1")
	)
	(via
		(at 259.945378 -2.174494)
		(size 0.508)
		(drill 0.254)
		(layers "F.Cu" "B.Cu")
		(net "DELTA_L_GND_1")
	)
	(via
		(at 378.878084 -6.397752)
		(size 0.508)
		(drill 0.254)
		(layers "F.Cu" "B.Cu")
		(net "DELTA_L_GND_1")
	)
	(via
		(at 251.44095 -1.178814)
		(size 0.508)
		(drill 0.254)
		(layers "F.Cu" "B.Cu")
		(net "DELTA_L_GND_1")
	)
	(via
		(at 248.514362 2.291588)
		(size 0.508)
		(drill 0.254)
		(layers "F.Cu" "B.Cu")
		(net "DELTA_L_GND_1")
	)
	(via
		(at 329.188826 -4.837938)
		(size 0.508)
		(drill 0.254)
		(layers "F.Cu" "B.Cu")
		(net "DELTA_L_GND_1")
	)
	(via
		(at 378.881894 2.010156)
		(size 0.508)
		(drill 0.254)
		(layers "F.Cu" "B.Cu")
		(net "DELTA_L_GND_1")
	)
	(via
		(at 330.026518 0.38735)
		(size 0.508)
		(drill 0.254)
		(layers "F.Cu" "B.Cu")
		(net "DELTA_L_GND_1")
	)
	(via
		(at 338.512404 -3.15849)
		(size 0.508)
		(drill 0.254)
		(layers "F.Cu" "B.Cu")
		(net "DELTA_L_GND_1")
	)
	(via
		(at 375.959116 8.633206)
		(size 0.508)
		(drill 0.254)
		(layers "F.Cu" "B.Cu")
		(net "DELTA_L_GND_1")
	)
	(via
		(at 378.881894 -0.53721)
		(size 0.508)
		(drill 0.254)
		(layers "F.Cu" "B.Cu")
		(net "DELTA_L_GND_1")
	)
	(via
		(at 375.959116 7.374382)
		(size 0.508)
		(drill 0.254)
		(layers "F.Cu" "B.Cu")
		(net "DELTA_L_GND_1")
	)
	(via
		(at 249.842528 1.675638)
		(size 0.508)
		(drill 0.254)
		(layers "F.Cu" "B.Cu")
		(net "DELTA_L_GND_1")
	)
	(via
		(at 378.048012 1.36779)
		(size 0.508)
		(drill 0.254)
		(layers "F.Cu" "B.Cu")
		(net "DELTA_L_GND_1")
	)
	(via
		(at 213.994238 -1.529588)
		(size 0.508)
		(drill 0.254)
		(layers "F.Cu" "B.Cu")
		(net "DELTA_L_GND_1")
	)
	(via
		(at 339.350096 9.708896)
		(size 0.508)
		(drill 0.254)
		(layers "F.Cu" "B.Cu")
		(net "DELTA_L_GND_1")
	)
	(via
		(at 260.77926 -6.34111)
		(size 0.508)
		(drill 0.254)
		(layers "F.Cu" "B.Cu")
		(net "DELTA_L_GND_1")
	)
	(via
		(at 182.958232 6.706362)
		(size 0.508)
		(drill 0.254)
		(layers "F.Cu" "B.Cu")
		(net "DELTA_L_GND_1")
	)
	(via
		(at 330.026518 2.934716)
		(size 0.508)
		(drill 0.254)
		(layers "F.Cu" "B.Cu")
		(net "DELTA_L_GND_1")
	)
	(via
		(at 248.514362 4.831588)
		(size 0.508)
		(drill 0.254)
		(layers "F.Cu" "B.Cu")
		(net "DELTA_L_GND_1")
	)
	(via
		(at 339.350096 8.145526)
		(size 0.508)
		(drill 0.254)
		(layers "F.Cu" "B.Cu")
		(net "DELTA_L_GND_1")
	)
	(via
		(at 328.428096 -3.4163)
		(size 0.508)
		(drill 0.254)
		(layers "F.Cu" "B.Cu")
		(net "DELTA_L_GND_1")
	)
	(via
		(at 330.022708 7.104888)
		(size 0.508)
		(drill 0.254)
		(layers "F.Cu" "B.Cu")
		(net "DELTA_L_GND_1")
	)
	(via
		(at 211.901532 -1.241806)
		(size 0.508)
		(drill 0.254)
		(layers "F.Cu" "B.Cu")
		(net "DELTA_L_GND_1")
	)
	(via
		(at 259.949188 -6.344666)
		(size 0.508)
		(drill 0.254)
		(layers "F.Cu" "B.Cu")
		(net "DELTA_L_GND_1")
	)
	(via
		(at 339.346286 9.070086)
		(size 0.508)
		(drill 0.254)
		(layers "F.Cu" "B.Cu")
		(net "DELTA_L_GND_1")
	)
	(via
		(at 327.09993 3.553206)
		(size 0.508)
		(drill 0.254)
		(layers "F.Cu" "B.Cu")
		(net "DELTA_L_GND_1")
	)
	(via
		(at 251.43714 -3.08737)
		(size 0.508)
		(drill 0.254)
		(layers "F.Cu" "B.Cu")
		(net "DELTA_L_GND_1")
	)
	(via
		(at 339.350096 4.487164)
		(size 0.508)
		(drill 0.254)
		(layers "F.Cu" "B.Cu")
		(net "DELTA_L_GND_1")
	)
	(via
		(at 339.350096 -4.718304)
		(size 0.508)
		(drill 0.254)
		(layers "F.Cu" "B.Cu")
		(net "DELTA_L_GND_1")
	)
	(via
		(at 250.603258 3.912362)
		(size 0.508)
		(drill 0.254)
		(layers "F.Cu" "B.Cu")
		(net "DELTA_L_GND_1")
	)
	(via
		(at 328.428096 -0.868934)
		(size 0.508)
		(drill 0.254)
		(layers "F.Cu" "B.Cu")
		(net "DELTA_L_GND_1")
	)
	(via
		(at 330.026518 6.466078)
		(size 0.508)
		(drill 0.254)
		(layers "F.Cu" "B.Cu")
		(net "DELTA_L_GND_1")
	)
	(via
		(at 261.5438 1.629156)
		(size 0.508)
		(drill 0.254)
		(layers "F.Cu" "B.Cu")
		(net "DELTA_L_GND_1")
	)
	(via
		(at 259.949188 -1.249934)
		(size 0.508)
		(drill 0.254)
		(layers "F.Cu" "B.Cu")
		(net "DELTA_L_GND_1")
	)
	(via
		(at 262.871966 4.834382)
		(size 0.508)
		(drill 0.254)
		(layers "F.Cu" "B.Cu")
		(net "DELTA_L_GND_1")
	)
	(via
		(at 377.287282 1.678432)
		(size 0.508)
		(drill 0.254)
		(layers "F.Cu" "B.Cu")
		(net "DELTA_L_GND_1")
	)
	(via
		(at 182.197502 5.453634)
		(size 0.508)
		(drill 0.254)
		(layers "F.Cu" "B.Cu")
		(net "DELTA_L_GND_1")
	)
	(via
		(at 251.43714 -0.540004)
		(size 0.508)
		(drill 0.254)
		(layers "F.Cu" "B.Cu")
		(net "DELTA_L_GND_1")
	)
	(via
		(at 378.051822 -3.088132)
		(size 0.508)
		(drill 0.254)
		(layers "F.Cu" "B.Cu")
		(net "DELTA_L_GND_1")
	)
	(via
		(at 378.885704 8.029448)
		(size 0.508)
		(drill 0.254)
		(layers "F.Cu" "B.Cu")
		(net "DELTA_L_GND_1")
	)
	(via
		(at 338.512404 7.030974)
		(size 0.508)
		(drill 0.254)
		(layers "F.Cu" "B.Cu")
		(net "DELTA_L_GND_1")
	)
	(via
		(at 327.09993 -0.245618)
		(size 0.508)
		(drill 0.254)
		(layers "F.Cu" "B.Cu")
		(net "DELTA_L_GND_1")
	)
	(via
		(at 328.428096 9.32053)
		(size 0.508)
		(drill 0.254)
		(layers "F.Cu" "B.Cu")
		(net "DELTA_L_GND_1")
	)
	(via
		(at 330.018898 -6.397752)
		(size 0.508)
		(drill 0.254)
		(layers "F.Cu" "B.Cu")
		(net "DELTA_L_GND_1")
	)
	(via
		(at 341.438992 6.093206)
		(size 0.508)
		(drill 0.254)
		(layers "F.Cu" "B.Cu")
		(net "DELTA_L_GND_1")
	)
	(via
		(at 251.43333 -6.400546)
		(size 0.508)
		(drill 0.254)
		(layers "F.Cu" "B.Cu")
		(net "DELTA_L_GND_1")
	)
	(via
		(at 330.026518 9.013444)
		(size 0.508)
		(drill 0.254)
		(layers "F.Cu" "B.Cu")
		(net "DELTA_L_GND_1")
	)
	(via
		(at 261.5438 4.176522)
		(size 0.508)
		(drill 0.254)
		(layers "F.Cu" "B.Cu")
		(net "DELTA_L_GND_1")
	)
	(via
		(at 250.603258 2.928366)
		(size 0.508)
		(drill 0.254)
		(layers "F.Cu" "B.Cu")
		(net "DELTA_L_GND_1")
	)
	(via
		(at 330.022708 -5.758942)
		(size 0.508)
		(drill 0.254)
		(layers "F.Cu" "B.Cu")
		(net "DELTA_L_GND_1")
	)
	(via
		(at 375.959116 4.834382)
		(size 0.508)
		(drill 0.254)
		(layers "F.Cu" "B.Cu")
		(net "DELTA_L_GND_1")
	)
	(via
		(at 260.78307 -5.7023)
		(size 0.508)
		(drill 0.254)
		(layers "F.Cu" "B.Cu")
		(net "DELTA_L_GND_1")
	)
	(via
		(at 378.885704 -1.17602)
		(size 0.508)
		(drill 0.254)
		(layers "F.Cu" "B.Cu")
		(net "DELTA_L_GND_1")
	)
	(via
		(at 329.188826 8.025892)
		(size 0.508)
		(drill 0.254)
		(layers "F.Cu" "B.Cu")
		(net "DELTA_L_GND_1")
	)
	(via
		(at 260.77926 6.39572)
		(size 0.508)
		(drill 0.254)
		(layers "F.Cu" "B.Cu")
		(net "DELTA_L_GND_1")
	)
	(via
		(at 211.06765 -4.717288)
		(size 0.508)
		(drill 0.254)
		(layers "F.Cu" "B.Cu")
		(net "DELTA_L_GND_1")
	)
	(via
		(at 260.78307 -4.718304)
		(size 0.508)
		(drill 0.254)
		(layers "F.Cu" "B.Cu")
		(net "DELTA_L_GND_1")
	)
	(via
		(at 181.35981 1.918716)
		(size 0.508)
		(drill 0.254)
		(layers "F.Cu" "B.Cu")
		(net "DELTA_L_GND_1")
	)
	(via
		(at 211.905342 -3.150362)
		(size 0.508)
		(drill 0.254)
		(layers "F.Cu" "B.Cu")
		(net "DELTA_L_GND_1")
	)
	(via
		(at 341.438992 7.374382)
		(size 0.508)
		(drill 0.254)
		(layers "F.Cu" "B.Cu")
		(net "DELTA_L_GND_1")
	)
	(via
		(at 338.516214 3.844798)
		(size 0.508)
		(drill 0.254)
		(layers "F.Cu" "B.Cu")
		(net "DELTA_L_GND_1")
	)
	(via
		(at 251.44095 1.368552)
		(size 0.508)
		(drill 0.254)
		(layers "F.Cu" "B.Cu")
		(net "DELTA_L_GND_1")
	)
	(via
		(at 378.048012 -6.401308)
		(size 0.508)
		(drill 0.254)
		(layers "F.Cu" "B.Cu")
		(net "DELTA_L_GND_1")
	)
	(via
		(at 262.871966 7.374382)
		(size 0.508)
		(drill 0.254)
		(layers "F.Cu" "B.Cu")
		(net "DELTA_L_GND_1")
	)
	(via
		(at 328.428096 1.678432)
		(size 0.508)
		(drill 0.254)
		(layers "F.Cu" "B.Cu")
		(net "DELTA_L_GND_1")
	)
	(via
		(at 249.842528 -0.871728)
		(size 0.508)
		(drill 0.254)
		(layers "F.Cu" "B.Cu")
		(net "DELTA_L_GND_1")
	)
	(via
		(at 329.192636 -5.762498)
		(size 0.508)
		(drill 0.254)
		(layers "F.Cu" "B.Cu")
		(net "DELTA_L_GND_1")
	)
	(via
		(at 341.438992 2.294382)
		(size 0.508)
		(drill 0.254)
		(layers "F.Cu" "B.Cu")
		(net "DELTA_L_GND_1")
	)
	(via
		(at 338.512404 5.467604)
		(size 0.508)
		(drill 0.254)
		(layers "F.Cu" "B.Cu")
		(net "DELTA_L_GND_1")
	)
	(via
		(at 327.09993 6.093206)
		(size 0.508)
		(drill 0.254)
		(layers "F.Cu" "B.Cu")
		(net "DELTA_L_GND_1")
	)
	(via
		(at 211.901532 -3.789172)
		(size 0.508)
		(drill 0.254)
		(layers "F.Cu" "B.Cu")
		(net "DELTA_L_GND_1")
	)
	(via
		(at 259.949188 -3.7973)
		(size 0.508)
		(drill 0.254)
		(layers "F.Cu" "B.Cu")
		(net "DELTA_L_GND_1")
	)
	(via
		(at 248.514362 -5.328412)
		(size 0.508)
		(drill 0.254)
		(layers "F.Cu" "B.Cu")
		(net "DELTA_L_GND_1")
	)
	(via
		(at 251.43714 2.007362)
		(size 0.508)
		(drill 0.254)
		(layers "F.Cu" "B.Cu")
		(net "DELTA_L_GND_1")
	)
	(via
		(at 181.35981 4.466082)
		(size 0.508)
		(drill 0.254)
		(layers "F.Cu" "B.Cu")
		(net "DELTA_L_GND_1")
	)
	(via
		(at 261.5438 -3.465576)
		(size 0.508)
		(drill 0.254)
		(layers "F.Cu" "B.Cu")
		(net "DELTA_L_GND_1")
	)
	(via
		(at 211.07146 -1.245362)
		(size 0.508)
		(drill 0.254)
		(layers "F.Cu" "B.Cu")
		(net "DELTA_L_GND_1")
	)
	(via
		(at 181.35981 7.013448)
		(size 0.508)
		(drill 0.254)
		(layers "F.Cu" "B.Cu")
		(net "DELTA_L_GND_1")
	)
	(via
		(at 260.78307 8.145526)
		(size 0.508)
		(drill 0.254)
		(layers "F.Cu" "B.Cu")
		(net "DELTA_L_GND_1")
	)
	(via
		(at 338.516214 9.06653)
		(size 0.508)
		(drill 0.254)
		(layers "F.Cu" "B.Cu")
		(net "DELTA_L_GND_1")
	)
	(via
		(at 260.78307 -0.607568)
		(size 0.508)
		(drill 0.254)
		(layers "F.Cu" "B.Cu")
		(net "DELTA_L_GND_1")
	)
	(via
		(at 248.514362 3.550412)
		(size 0.508)
		(drill 0.254)
		(layers "F.Cu" "B.Cu")
		(net "DELTA_L_GND_1")
	)
	(via
		(at 330.022708 -3.084576)
		(size 0.508)
		(drill 0.254)
		(layers "F.Cu" "B.Cu")
		(net "DELTA_L_GND_1")
	)
	(via
		(at 261.5438 -6.012942)
		(size 0.508)
		(drill 0.254)
		(layers "F.Cu" "B.Cu")
		(net "DELTA_L_GND_1")
	)
	(via
		(at 377.287282 -3.4163)
		(size 0.508)
		(drill 0.254)
		(layers "F.Cu" "B.Cu")
		(net "DELTA_L_GND_1")
	)
	(via
		(at 260.78307 7.03453)
		(size 0.508)
		(drill 0.254)
		(layers "F.Cu" "B.Cu")
		(net "DELTA_L_GND_1")
	)
	(via
		(at 211.905342 -2.166366)
		(size 0.508)
		(drill 0.254)
		(layers "F.Cu" "B.Cu")
		(net "DELTA_L_GND_1")
	)
	(via
		(at 213.994238 -4.069588)
		(size 0.508)
		(drill 0.254)
		(layers "F.Cu" "B.Cu")
		(net "DELTA_L_GND_1")
	)
	(via
		(at 378.881894 7.104888)
		(size 0.508)
		(drill 0.254)
		(layers "F.Cu" "B.Cu")
		(net "DELTA_L_GND_1")
	)
	(via
		(at 330.026518 1.371346)
		(size 0.508)
		(drill 0.254)
		(layers "F.Cu" "B.Cu")
		(net "DELTA_L_GND_1")
	)
	(via
		(at 378.885704 9.013444)
		(size 0.508)
		(drill 0.254)
		(layers "F.Cu" "B.Cu")
		(net "DELTA_L_GND_1")
	)
	(via
		(at 249.842528 -3.419094)
		(size 0.508)
		(drill 0.254)
		(layers "F.Cu" "B.Cu")
		(net "DELTA_L_GND_1")
	)
	(via
		(at 378.885704 3.918712)
		(size 0.508)
		(drill 0.254)
		(layers "F.Cu" "B.Cu")
		(net "DELTA_L_GND_1")
	)
	(via
		(at 329.188826 -3.726942)
		(size 0.508)
		(drill 0.254)
		(layers "F.Cu" "B.Cu")
		(net "DELTA_L_GND_1")
	)
	(via
		(at 250.607068 7.098538)
		(size 0.508)
		(drill 0.254)
		(layers "F.Cu" "B.Cu")
		(net "DELTA_L_GND_1")
	)
	(via
		(at 329.192636 7.101332)
		(size 0.508)
		(drill 0.254)
		(layers "F.Cu" "B.Cu")
		(net "DELTA_L_GND_1")
	)
	(via
		(at 378.051822 9.648698)
		(size 0.508)
		(drill 0.254)
		(layers "F.Cu" "B.Cu")
		(net "DELTA_L_GND_1")
	)
	(via
		(at 338.516214 6.392164)
		(size 0.508)
		(drill 0.254)
		(layers "F.Cu" "B.Cu")
		(net "DELTA_L_GND_1")
	)
	(via
		(at 212.666072 -0.913638)
		(size 0.508)
		(drill 0.254)
		(layers "F.Cu" "B.Cu")
		(net "DELTA_L_GND_1")
	)
	(via
		(at 378.051822 4.553966)
		(size 0.508)
		(drill 0.254)
		(layers "F.Cu" "B.Cu")
		(net "DELTA_L_GND_1")
	)
	(via
		(at 211.905342 -4.713732)
		(size 0.508)
		(drill 0.254)
		(layers "F.Cu" "B.Cu")
		(net "DELTA_L_GND_1")
	)
	(via
		(at 378.048012 0.383794)
		(size 0.508)
		(drill 0.254)
		(layers "F.Cu" "B.Cu")
		(net "DELTA_L_GND_1")
	)
	(via
		(at 378.051822 7.101332)
		(size 0.508)
		(drill 0.254)
		(layers "F.Cu" "B.Cu")
		(net "DELTA_L_GND_1")
	)
	(via
		(at 378.885704 -3.723386)
		(size 0.508)
		(drill 0.254)
		(layers "F.Cu" "B.Cu")
		(net "DELTA_L_GND_1")
	)
	(via
		(at 181.36362 1.279906)
		(size 0.508)
		(drill 0.254)
		(layers "F.Cu" "B.Cu")
		(net "DELTA_L_GND_1")
	)
	(via
		(at 260.78307 0.376428)
		(size 0.508)
		(drill 0.254)
		(layers "F.Cu" "B.Cu")
		(net "DELTA_L_GND_1")
	)
	(via
		(at 251.44095 6.463284)
		(size 0.508)
		(drill 0.254)
		(layers "F.Cu" "B.Cu")
		(net "DELTA_L_GND_1")
	)
	(via
		(at 250.603258 -1.18237)
		(size 0.508)
		(drill 0.254)
		(layers "F.Cu" "B.Cu")
		(net "DELTA_L_GND_1")
	)
	(via
		(at 329.188826 9.009888)
		(size 0.508)
		(drill 0.254)
		(layers "F.Cu" "B.Cu")
		(net "DELTA_L_GND_1")
	)
	(via
		(at 329.188826 0.383794)
		(size 0.508)
		(drill 0.254)
		(layers "F.Cu" "B.Cu")
		(net "DELTA_L_GND_1")
	)
	(via
		(at 329.188826 6.462522)
		(size 0.508)
		(drill 0.254)
		(layers "F.Cu" "B.Cu")
		(net "DELTA_L_GND_1")
	)
	(via
		(at 341.438992 8.633206)
		(size 0.508)
		(drill 0.254)
		(layers "F.Cu" "B.Cu")
		(net "DELTA_L_GND_1")
	)
	(via
		(at 260.78307 -3.154934)
		(size 0.508)
		(drill 0.254)
		(layers "F.Cu" "B.Cu")
		(net "DELTA_L_GND_1")
	)
	(via
		(at 182.197502 7.017004)
		(size 0.508)
		(drill 0.254)
		(layers "F.Cu" "B.Cu")
		(net "DELTA_L_GND_1")
	)
	(via
		(at 211.06765 -2.169922)
		(size 0.508)
		(drill 0.254)
		(layers "F.Cu" "B.Cu")
		(net "DELTA_L_GND_1")
	)
	(via
		(at 341.438992 1.013206)
		(size 0.508)
		(drill 0.254)
		(layers "F.Cu" "B.Cu")
		(net "DELTA_L_GND_1")
	)
	(via
		(at 377.287282 -6.090666)
		(size 0.508)
		(drill 0.254)
		(layers "F.Cu" "B.Cu")
		(net "DELTA_L_GND_1")
	)
	(via
		(at 262.871966 8.633206)
		(size 0.508)
		(drill 0.254)
		(layers "F.Cu" "B.Cu")
		(net "DELTA_L_GND_1")
	)
	(via
		(at 260.78307 9.708896)
		(size 0.508)
		(drill 0.254)
		(layers "F.Cu" "B.Cu")
		(net "DELTA_L_GND_1")
	)
	(via
		(at 339.350096 -2.170938)
		(size 0.508)
		(drill 0.254)
		(layers "F.Cu" "B.Cu")
		(net "DELTA_L_GND_1")
	)
	(via
		(at 378.051822 2.0066)
		(size 0.508)
		(drill 0.254)
		(layers "F.Cu" "B.Cu")
		(net "DELTA_L_GND_1")
	)
	(via
		(at 211.905342 -0.602996)
		(size 0.508)
		(drill 0.254)
		(layers "F.Cu" "B.Cu")
		(net "DELTA_L_GND_1")
	)
	(via
		(at 378.885704 5.482082)
		(size 0.508)
		(drill 0.254)
		(layers "F.Cu" "B.Cu")
		(net "DELTA_L_GND_1")
	)
	(via
		(at 259.945378 0.372872)
		(size 0.508)
		(drill 0.254)
		(layers "F.Cu" "B.Cu")
		(net "DELTA_L_GND_1")
	)
	(via
		(at 248.514362 -4.069588)
		(size 0.508)
		(drill 0.254)
		(layers "F.Cu" "B.Cu")
		(net "DELTA_L_GND_1")
	)
	(via
		(at 250.607068 4.551172)
		(size 0.508)
		(drill 0.254)
		(layers "F.Cu" "B.Cu")
		(net "DELTA_L_GND_1")
	)
	(via
		(at 211.06765 -3.153918)
		(size 0.508)
		(drill 0.254)
		(layers "F.Cu" "B.Cu")
		(net "DELTA_L_GND_1")
	)
	(via
		(at 340.110826 4.176522)
		(size 0.508)
		(drill 0.254)
		(layers "F.Cu" "B.Cu")
		(net "DELTA_L_GND_1")
	)
	(via
		(at 251.44095 5.479288)
		(size 0.508)
		(drill 0.254)
		(layers "F.Cu" "B.Cu")
		(net "DELTA_L_GND_1")
	)
	(via
		(at 249.842528 6.77037)
		(size 0.508)
		(drill 0.254)
		(layers "F.Cu" "B.Cu")
		(net "DELTA_L_GND_1")
	)
	(via
		(at 339.346286 6.39572)
		(size 0.508)
		(drill 0.254)
		(layers "F.Cu" "B.Cu")
		(net "DELTA_L_GND_1")
	)
	(via
		(at 327.09993 4.834382)
		(size 0.508)
		(drill 0.254)
		(layers "F.Cu" "B.Cu")
		(net "DELTA_L_GND_1")
	)
	(via
		(at 339.350096 -0.607568)
		(size 0.508)
		(drill 0.254)
		(layers "F.Cu" "B.Cu")
		(net "DELTA_L_GND_1")
	)
	(via
		(at 340.110826 -6.012942)
		(size 0.508)
		(drill 0.254)
		(layers "F.Cu" "B.Cu")
		(net "DELTA_L_GND_1")
	)
	(via
		(at 341.438992 3.553206)
		(size 0.508)
		(drill 0.254)
		(layers "F.Cu" "B.Cu")
		(net "DELTA_L_GND_1")
	)
	(via
		(at 211.06765 -5.701284)
		(size 0.508)
		(drill 0.254)
		(layers "F.Cu" "B.Cu")
		(net "DELTA_L_GND_1")
	)
	(via
		(at 378.048012 -4.837938)
		(size 0.508)
		(drill 0.254)
		(layers "F.Cu" "B.Cu")
		(net "DELTA_L_GND_1")
	)
	(via
		(at 248.514362 6.090412)
		(size 0.508)
		(drill 0.254)
		(layers "F.Cu" "B.Cu")
		(net "DELTA_L_GND_1")
	)
	(via
		(at 182.193692 3.830828)
		(size 0.508)
		(drill 0.254)
		(layers "F.Cu" "B.Cu")
		(net "DELTA_L_GND_1")
	)
	(via
		(at 339.346286 -6.34111)
		(size 0.508)
		(drill 0.254)
		(layers "F.Cu" "B.Cu")
		(net "DELTA_L_GND_1")
	)
	(via
		(at 330.026518 5.482082)
		(size 0.508)
		(drill 0.254)
		(layers "F.Cu" "B.Cu")
		(net "DELTA_L_GND_1")
	)
	(via
		(at 259.949188 6.392164)
		(size 0.508)
		(drill 0.254)
		(layers "F.Cu" "B.Cu")
		(net "DELTA_L_GND_1")
	)
	(via
		(at 329.188826 -2.163572)
		(size 0.508)
		(drill 0.254)
		(layers "F.Cu" "B.Cu")
		(net "DELTA_L_GND_1")
	)
	(via
		(at 339.350096 7.03453)
		(size 0.508)
		(drill 0.254)
		(layers "F.Cu" "B.Cu")
		(net "DELTA_L_GND_1")
	)
	(via
		(at 330.026518 8.029448)
		(size 0.508)
		(drill 0.254)
		(layers "F.Cu" "B.Cu")
		(net "DELTA_L_GND_1")
	)
	(via
		(at 251.44095 -3.72618)
		(size 0.508)
		(drill 0.254)
		(layers "F.Cu" "B.Cu")
		(net "DELTA_L_GND_1")
	)
	(via
		(at 338.512404 -2.174494)
		(size 0.508)
		(drill 0.254)
		(layers "F.Cu" "B.Cu")
		(net "DELTA_L_GND_1")
	)
	(via
		(at 377.287282 4.225798)
		(size 0.508)
		(drill 0.254)
		(layers "F.Cu" "B.Cu")
		(net "DELTA_L_GND_1")
	)
	(via
		(at 211.07146 -6.340094)
		(size 0.508)
		(drill 0.254)
		(layers "F.Cu" "B.Cu")
		(net "DELTA_L_GND_1")
	)
	(via
		(at 340.110826 -3.465576)
		(size 0.508)
		(drill 0.254)
		(layers "F.Cu" "B.Cu")
		(net "DELTA_L_GND_1")
	)
	(via
		(at 181.35981 2.902712)
		(size 0.508)
		(drill 0.254)
		(layers "F.Cu" "B.Cu")
		(net "DELTA_L_GND_1")
	)
	(via
		(at 330.026518 3.918712)
		(size 0.508)
		(drill 0.254)
		(layers "F.Cu" "B.Cu")
		(net "DELTA_L_GND_1")
	)
	(via
		(at 338.516214 -3.7973)
		(size 0.508)
		(drill 0.254)
		(layers "F.Cu" "B.Cu")
		(net "DELTA_L_GND_1")
	)
	(via
		(at 182.193692 1.283462)
		(size 0.508)
		(drill 0.254)
		(layers "F.Cu" "B.Cu")
		(net "DELTA_L_GND_1")
	)
	(via
		(at 250.603258 5.475732)
		(size 0.508)
		(drill 0.254)
		(layers "F.Cu" "B.Cu")
		(net "DELTA_L_GND_1")
	)
	(via
		(at 260.77926 3.848354)
		(size 0.508)
		(drill 0.254)
		(layers "F.Cu" "B.Cu")
		(net "DELTA_L_GND_1")
	)
	(via
		(at 338.520024 9.70534)
		(size 0.508)
		(drill 0.254)
		(layers "F.Cu" "B.Cu")
		(net "DELTA_L_GND_1")
	)
	(via
		(at 262.871966 1.013206)
		(size 0.508)
		(drill 0.254)
		(layers "F.Cu" "B.Cu")
		(net "DELTA_L_GND_1")
	)
	(via
		(at 375.959116 2.294382)
		(size 0.508)
		(drill 0.254)
		(layers "F.Cu" "B.Cu")
		(net "DELTA_L_GND_1")
	)
	(via
		(at 377.287282 6.773164)
		(size 0.508)
		(drill 0.254)
		(layers "F.Cu" "B.Cu")
		(net "DELTA_L_GND_1")
	)
	(via
		(at 330.022708 2.010156)
		(size 0.508)
		(drill 0.254)
		(layers "F.Cu" "B.Cu")
		(net "DELTA_L_GND_1")
	)
	(via
		(at 260.78307 4.487164)
		(size 0.508)
		(drill 0.254)
		(layers "F.Cu" "B.Cu")
		(net "DELTA_L_GND_1")
	)
	(via
		(at 330.026518 -4.834382)
		(size 0.508)
		(drill 0.254)
		(layers "F.Cu" "B.Cu")
		(net "DELTA_L_GND_1")
	)
	(via
		(at 261.5438 -0.91821)
		(size 0.508)
		(drill 0.254)
		(layers "F.Cu" "B.Cu")
		(net "DELTA_L_GND_1")
	)
	(via
		(at 259.949188 1.297432)
		(size 0.508)
		(drill 0.254)
		(layers "F.Cu" "B.Cu")
		(net "DELTA_L_GND_1")
	)
	(via
		(at 339.350096 -3.154934)
		(size 0.508)
		(drill 0.254)
		(layers "F.Cu" "B.Cu")
		(net "DELTA_L_GND_1")
	)
	(via
		(at 378.048012 -3.726942)
		(size 0.508)
		(drill 0.254)
		(layers "F.Cu" "B.Cu")
		(net "DELTA_L_GND_1")
	)
	(via
		(at 339.346286 3.848354)
		(size 0.508)
		(drill 0.254)
		(layers "F.Cu" "B.Cu")
		(net "DELTA_L_GND_1")
	)
	(via
		(at 182.197502 1.922272)
		(size 0.508)
		(drill 0.254)
		(layers "F.Cu" "B.Cu")
		(net "DELTA_L_GND_1")
	)
	(via
		(at 250.603258 -3.729736)
		(size 0.508)
		(drill 0.254)
		(layers "F.Cu" "B.Cu")
		(net "DELTA_L_GND_1")
	)
	(via
		(at 328.428096 -6.090666)
		(size 0.508)
		(drill 0.254)
		(layers "F.Cu" "B.Cu")
		(net "DELTA_L_GND_1")
	)
	(via
		(at 330.026518 -1.17602)
		(size 0.508)
		(drill 0.254)
		(layers "F.Cu" "B.Cu")
		(net "DELTA_L_GND_1")
	)
	(via
		(at 329.188826 1.36779)
		(size 0.508)
		(drill 0.254)
		(layers "F.Cu" "B.Cu")
		(net "DELTA_L_GND_1")
	)
	(via
		(at 184.286398 3.550412)
		(size 0.508)
		(drill 0.254)
		(layers "F.Cu" "B.Cu")
		(net "DELTA_L_GND_1")
	)
	(via
		(at 260.77926 -1.246378)
		(size 0.508)
		(drill 0.254)
		(layers "F.Cu" "B.Cu")
		(net "DELTA_L_GND_1")
	)
	(via
		(at 260.78307 5.47116)
		(size 0.508)
		(drill 0.254)
		(layers "F.Cu" "B.Cu")
		(net "DELTA_L_GND_1")
	)
	(via
		(at 377.287282 9.32053)
		(size 0.508)
		(drill 0.254)
		(layers "F.Cu" "B.Cu")
		(net "DELTA_L_GND_1")
	)
	(via
		(at 378.051822 -5.762498)
		(size 0.508)
		(drill 0.254)
		(layers "F.Cu" "B.Cu")
		(net "DELTA_L_GND_1")
	)
	(via
		(at 330.022708 -0.53721)
		(size 0.508)
		(drill 0.254)
		(layers "F.Cu" "B.Cu")
		(net "DELTA_L_GND_1")
	)
	(via
		(at 260.77926 -3.793744)
		(size 0.508)
		(drill 0.254)
		(layers "F.Cu" "B.Cu")
		(net "DELTA_L_GND_1")
	)
	(via
		(at 259.945378 -3.15849)
		(size 0.508)
		(drill 0.254)
		(layers "F.Cu" "B.Cu")
		(net "DELTA_L_GND_1")
	)
	(via
		(at 338.512404 8.14197)
		(size 0.508)
		(drill 0.254)
		(layers "F.Cu" "B.Cu")
		(net "DELTA_L_GND_1")
	)
	(via
		(at 259.945378 -4.72186)
		(size 0.508)
		(drill 0.254)
		(layers "F.Cu" "B.Cu")
		(net "DELTA_L_GND_1")
	)
	(via
		(at 329.188826 -1.179576)
		(size 0.508)
		(drill 0.254)
		(layers "F.Cu" "B.Cu")
		(net "DELTA_L_GND_1")
	)
	(via
		(at 378.885704 -2.160016)
		(size 0.508)
		(drill 0.254)
		(layers "F.Cu" "B.Cu")
		(net "DELTA_L_GND_1")
	)
	(via
		(at 338.512404 -5.705856)
		(size 0.508)
		(drill 0.254)
		(layers "F.Cu" "B.Cu")
		(net "DELTA_L_GND_1")
	)
	(via
		(at 339.346286 -1.246378)
		(size 0.508)
		(drill 0.254)
		(layers "F.Cu" "B.Cu")
		(net "DELTA_L_GND_1")
	)
	(via
		(at 329.192636 2.0066)
		(size 0.508)
		(drill 0.254)
		(layers "F.Cu" "B.Cu")
		(net "DELTA_L_GND_1")
	)
	(via
		(at 338.512404 -4.72186)
		(size 0.508)
		(drill 0.254)
		(layers "F.Cu" "B.Cu")
		(net "DELTA_L_GND_1")
	)
	(via
		(at 375.959116 1.013206)
		(size 0.508)
		(drill 0.254)
		(layers "F.Cu" "B.Cu")
		(net "DELTA_L_GND_1")
	)
	(via
		(at 328.428096 6.773164)
		(size 0.508)
		(drill 0.254)
		(layers "F.Cu" "B.Cu")
		(net "DELTA_L_GND_1")
	)
	(via
		(at 378.881894 -5.758942)
		(size 0.508)
		(drill 0.254)
		(layers "F.Cu" "B.Cu")
		(net "DELTA_L_GND_1")
	)
	(via
		(at 182.193692 6.378194)
		(size 0.508)
		(drill 0.254)
		(layers "F.Cu" "B.Cu")
		(net "DELTA_L_GND_1")
	)
	(via
		(at 339.350096 2.923794)
		(size 0.508)
		(drill 0.254)
		(layers "F.Cu" "B.Cu")
		(net "DELTA_L_GND_1")
	)
	(via
		(at 338.512404 2.920238)
		(size 0.508)
		(drill 0.254)
		(layers "F.Cu" "B.Cu")
		(net "DELTA_L_GND_1")
	)
	(via
		(at 341.438992 4.834382)
		(size 0.508)
		(drill 0.254)
		(layers "F.Cu" "B.Cu")
		(net "DELTA_L_GND_1")
	)
	(via
		(at 378.881894 -3.084576)
		(size 0.508)
		(drill 0.254)
		(layers "F.Cu" "B.Cu")
		(net "DELTA_L_GND_1")
	)
	(via
		(at 378.048012 3.915156)
		(size 0.508)
		(drill 0.254)
		(layers "F.Cu" "B.Cu")
		(net "DELTA_L_GND_1")
	)
	(via
		(at 378.885704 0.38735)
		(size 0.508)
		(drill 0.254)
		(layers "F.Cu" "B.Cu")
		(net "DELTA_L_GND_1")
	)
	(via
		(at 250.603258 -6.404102)
		(size 0.508)
		(drill 0.254)
		(layers "F.Cu" "B.Cu")
		(net "DELTA_L_GND_1")
	)
	(via
		(at 259.949188 9.06653)
		(size 0.508)
		(drill 0.254)
		(layers "F.Cu" "B.Cu")
		(net "DELTA_L_GND_1")
	)
	(via
		(at 250.607068 -0.54356)
		(size 0.508)
		(drill 0.254)
		(layers "F.Cu" "B.Cu")
		(net "DELTA_L_GND_1")
	)
	(via
		(at 339.350096 1.939798)
		(size 0.508)
		(drill 0.254)
		(layers "F.Cu" "B.Cu")
		(net "DELTA_L_GND_1")
	)
	(via
		(at 182.197502 2.906268)
		(size 0.508)
		(drill 0.254)
		(layers "F.Cu" "B.Cu")
		(net "DELTA_L_GND_1")
	)
	(via
		(at 329.192636 -3.088132)
		(size 0.508)
		(drill 0.254)
		(layers "F.Cu" "B.Cu")
		(net "DELTA_L_GND_1")
	)
	(via
		(at 378.048012 -2.163572)
		(size 0.508)
		(drill 0.254)
		(layers "F.Cu" "B.Cu")
		(net "DELTA_L_GND_1")
	)
	(via
		(at 260.78307 2.923794)
		(size 0.508)
		(drill 0.254)
		(layers "F.Cu" "B.Cu")
		(net "DELTA_L_GND_1")
	)
	(via
		(at 181.36362 6.374638)
		(size 0.508)
		(drill 0.254)
		(layers "F.Cu" "B.Cu")
		(net "DELTA_L_GND_1")
	)
	(via
		(at 378.048012 8.025892)
		(size 0.508)
		(drill 0.254)
		(layers "F.Cu" "B.Cu")
		(net "DELTA_L_GND_1")
	)
	(via
		(at 378.048012 5.478526)
		(size 0.508)
		(drill 0.254)
		(layers "F.Cu" "B.Cu")
		(net "DELTA_L_GND_1")
	)
	(via
		(at 329.192636 4.553966)
		(size 0.508)
		(drill 0.254)
		(layers "F.Cu" "B.Cu")
		(net "DELTA_L_GND_1")
	)
	(via
		(at 259.945378 4.483608)
		(size 0.508)
		(drill 0.254)
		(layers "F.Cu" "B.Cu")
		(net "DELTA_L_GND_1")
	)
	(via
		(at 184.286398 6.090412)
		(size 0.508)
		(drill 0.254)
		(layers "F.Cu" "B.Cu")
		(net "DELTA_L_GND_1")
	)
	(via
		(at 330.026518 -2.160016)
		(size 0.508)
		(drill 0.254)
		(layers "F.Cu" "B.Cu")
		(net "DELTA_L_GND_1")
	)
	(via
		(at 339.350096 5.47116)
		(size 0.508)
		(drill 0.254)
		(layers "F.Cu" "B.Cu")
		(net "DELTA_L_GND_1")
	)
	(via
		(at 330.022708 4.557522)
		(size 0.508)
		(drill 0.254)
		(layers "F.Cu" "B.Cu")
		(net "DELTA_L_GND_1")
	)
	(via
		(at 378.881894 9.652254)
		(size 0.508)
		(drill 0.254)
		(layers "F.Cu" "B.Cu")
		(net "DELTA_L_GND_1")
	)
	(via
		(at 378.881894 4.557522)
		(size 0.508)
		(drill 0.254)
		(layers "F.Cu" "B.Cu")
		(net "DELTA_L_GND_1")
	)
	(via
		(at 261.5438 6.723888)
		(size 0.508)
		(drill 0.254)
		(layers "F.Cu" "B.Cu")
		(net "DELTA_L_GND_1")
	)
	(via
		(at 184.286398 2.291588)
		(size 0.508)
		(drill 0.254)
		(layers "F.Cu" "B.Cu")
		(net "DELTA_L_GND_1")
	)
	(via
		(at 329.192636 -0.540766)
		(size 0.508)
		(drill 0.254)
		(layers "F.Cu" "B.Cu")
		(net "DELTA_L_GND_1")
	)
	(via
		(at 262.871966 -0.245618)
		(size 0.508)
		(drill 0.254)
		(layers "F.Cu" "B.Cu")
		(net "DELTA_L_GND_1")
	)
	(via
		(at 182.958232 4.158996)
		(size 0.508)
		(drill 0.254)
		(layers "F.Cu" "B.Cu")
		(net "DELTA_L_GND_1")
	)
	(via
		(at 261.5438 9.398254)
		(size 0.508)
		(drill 0.254)
		(layers "F.Cu" "B.Cu")
		(net "DELTA_L_GND_1")
	)
	(via
		(at 251.44095 -2.16281)
		(size 0.508)
		(drill 0.254)
		(layers "F.Cu" "B.Cu")
		(net "DELTA_L_GND_1")
	)
	(via
		(at 339.350096 0.376428)
		(size 0.508)
		(drill 0.254)
		(layers "F.Cu" "B.Cu")
		(net "DELTA_L_GND_1")
	)
	(via
		(at 375.959116 -0.245618)
		(size 0.508)
		(drill 0.254)
		(layers "F.Cu" "B.Cu")
		(net "DELTA_L_GND_1")
	)
	(via
		(at 212.666072 -3.461004)
		(size 0.508)
		(drill 0.254)
		(layers "F.Cu" "B.Cu")
		(net "DELTA_L_GND_1")
	)
	(via
		(at 378.048012 2.93116)
		(size 0.508)
		(drill 0.254)
		(layers "F.Cu" "B.Cu")
		(net "DELTA_L_GND_1")
	)
	(via
		(at 340.110826 1.629156)
		(size 0.508)
		(drill 0.254)
		(layers "F.Cu" "B.Cu")
		(net "DELTA_L_GND_1")
	)
	(via
		(at 251.44095 3.915918)
		(size 0.508)
		(drill 0.254)
		(layers "F.Cu" "B.Cu")
		(net "DELTA_L_GND_1")
	)
	(via
		(at 213.994238 -5.328412)
		(size 0.508)
		(drill 0.254)
		(layers "F.Cu" "B.Cu")
		(net "DELTA_L_GND_1")
	)
	(via
		(at 329.192636 9.648698)
		(size 0.508)
		(drill 0.254)
		(layers "F.Cu" "B.Cu")
		(net "DELTA_L_GND_1")
	)
	(via
		(at 259.945378 8.14197)
		(size 0.508)
		(drill 0.254)
		(layers "F.Cu" "B.Cu")
		(net "DELTA_L_GND_1")
	)
	(via
		(at 328.428096 4.225798)
		(size 0.508)
		(drill 0.254)
		(layers "F.Cu" "B.Cu")
		(net "DELTA_L_GND_1")
	)
	(via
		(at 250.603258 -2.166366)
		(size 0.508)
		(drill 0.254)
		(layers "F.Cu" "B.Cu")
		(net "DELTA_L_GND_1")
	)
	(via
		(at 251.43714 -5.761736)
		(size 0.508)
		(drill 0.254)
		(layers "F.Cu" "B.Cu")
		(net "DELTA_L_GND_1")
	)
	(via
		(at 182.197502 4.469638)
		(size 0.508)
		(drill 0.254)
		(layers "F.Cu" "B.Cu")
		(net "DELTA_L_GND_1")
	)
	(via
		(at 251.43714 4.554728)
		(size 0.508)
		(drill 0.254)
		(layers "F.Cu" "B.Cu")
		(net "DELTA_L_GND_1")
	)
	(via
		(at 259.952998 9.70534)
		(size 0.508)
		(drill 0.254)
		(layers "F.Cu" "B.Cu")
		(net "DELTA_L_GND_1")
	)
	(via
		(at 378.048012 -1.179576)
		(size 0.508)
		(drill 0.254)
		(layers "F.Cu" "B.Cu")
		(net "DELTA_L_GND_1")
	)
	(via
		(at 262.871966 6.093206)
		(size 0.508)
		(drill 0.254)
		(layers "F.Cu" "B.Cu")
		(net "DELTA_L_GND_1")
	)
	(via
		(at 248.514362 -1.529588)
		(size 0.508)
		(drill 0.254)
		(layers "F.Cu" "B.Cu")
		(net "DELTA_L_GND_1")
	)
	(via
		(at 211.06765 -0.606552)
		(size 0.508)
		(drill 0.254)
		(layers "F.Cu" "B.Cu")
		(net "DELTA_L_GND_1")
	)
	(via
		(at 211.901532 -6.336538)
		(size 0.508)
		(drill 0.254)
		(layers "F.Cu" "B.Cu")
		(net "DELTA_L_GND_1")
	)
	(via
		(at 338.512404 4.483608)
		(size 0.508)
		(drill 0.254)
		(layers "F.Cu" "B.Cu")
		(net "DELTA_L_GND_1")
	)
	(via
		(at 329.188826 5.478526)
		(size 0.508)
		(drill 0.254)
		(layers "F.Cu" "B.Cu")
		(net "DELTA_L_GND_1")
	)
	(via
		(at 378.885704 -4.834382)
		(size 0.508)
		(drill 0.254)
		(layers "F.Cu" "B.Cu")
		(net "DELTA_L_GND_1")
	)
	(via
		(at 248.514362 -2.788412)
		(size 0.508)
		(drill 0.254)
		(layers "F.Cu" "B.Cu")
		(net "DELTA_L_GND_1")
	)
	(via
		(at 341.438992 -0.245618)
		(size 0.508)
		(drill 0.254)
		(layers "F.Cu" "B.Cu")
		(net "DELTA_L_GND_1")
	)
	(via
		(at 250.603258 -4.840732)
		(size 0.508)
		(drill 0.254)
		(layers "F.Cu" "B.Cu")
		(net "DELTA_L_GND_1")
	)
	(via
		(at 259.949188 3.844798)
		(size 0.508)
		(drill 0.254)
		(layers "F.Cu" "B.Cu")
		(net "DELTA_L_GND_1")
	)
	(via
		(at 260.78307 1.939798)
		(size 0.508)
		(drill 0.254)
		(layers "F.Cu" "B.Cu")
		(net "DELTA_L_GND_1")
	)
	(via
		(at 340.110826 -0.91821)
		(size 0.508)
		(drill 0.254)
		(layers "F.Cu" "B.Cu")
		(net "DELTA_L_GND_1")
	)
	(via
		(at 329.188826 2.93116)
		(size 0.508)
		(drill 0.254)
		(layers "F.Cu" "B.Cu")
		(net "DELTA_L_GND_1")
	)
	(via
		(at 327.09993 2.294382)
		(size 0.508)
		(drill 0.254)
		(layers "F.Cu" "B.Cu")
		(net "DELTA_L_GND_1")
	)
	(via
		(at 338.516214 1.297432)
		(size 0.508)
		(drill 0.254)
		(layers "F.Cu" "B.Cu")
		(net "DELTA_L_GND_1")
	)
	(via
		(at 329.188826 -6.401308)
		(size 0.508)
		(drill 0.254)
		(layers "F.Cu" "B.Cu")
		(net "DELTA_L_GND_1")
	)
	(via
		(at 338.516214 -6.344666)
		(size 0.508)
		(drill 0.254)
		(layers "F.Cu" "B.Cu")
		(net "DELTA_L_GND_1")
	)
	(via
		(at 340.110826 9.398254)
		(size 0.508)
		(drill 0.254)
		(layers "F.Cu" "B.Cu")
		(net "DELTA_L_GND_1")
	)
	(via
		(at 338.512404 1.936242)
		(size 0.508)
		(drill 0.254)
		(layers "F.Cu" "B.Cu")
		(net "DELTA_L_GND_1")
	)
	(via
		(at 260.78307 -2.170938)
		(size 0.508)
		(drill 0.254)
		(layers "F.Cu" "B.Cu")
		(net "DELTA_L_GND_1")
	)
	(via
		(at 184.286398 4.831588)
		(size 0.508)
		(drill 0.254)
		(layers "F.Cu" "B.Cu")
		(net "DELTA_L_GND_1")
	)
	(via
		(at 249.842528 4.223004)
		(size 0.508)
		(drill 0.254)
		(layers "F.Cu" "B.Cu")
		(net "DELTA_L_GND_1")
	)
	(via
		(at 211.07146 -3.792728)
		(size 0.508)
		(drill 0.254)
		(layers "F.Cu" "B.Cu")
		(net "DELTA_L_GND_1")
	)
	(via
		(at 262.871966 3.553206)
		(size 0.508)
		(drill 0.254)
		(layers "F.Cu" "B.Cu")
		(net "DELTA_L_GND_1")
	)
	(via
		(at 338.512404 0.372872)
		(size 0.508)
		(drill 0.254)
		(layers "F.Cu" "B.Cu")
		(net "DELTA_L_GND_1")
	)
	(via
		(at 260.77926 9.070086)
		(size 0.508)
		(drill 0.254)
		(layers "F.Cu" "B.Cu")
		(net "DELTA_L_GND_1")
	)
	(via
		(at 249.842528 -6.09346)
		(size 0.508)
		(drill 0.254)
		(layers "F.Cu" "B.Cu")
		(net "DELTA_L_GND_1")
	)
	(via
		(at 259.945378 7.030974)
		(size 0.508)
		(drill 0.254)
		(layers "F.Cu" "B.Cu")
		(net "DELTA_L_GND_1")
	)
	(via
		(at 339.346286 1.300988)
		(size 0.508)
		(drill 0.254)
		(layers "F.Cu" "B.Cu")
		(net "DELTA_L_GND_1")
	)
	(via
		(at 182.958232 1.61163)
		(size 0.508)
		(drill 0.254)
		(layers "F.Cu" "B.Cu")
		(net "DELTA_L_GND_1")
	)
	(via
		(at 251.43714 7.102094)
		(size 0.508)
		(drill 0.254)
		(layers "F.Cu" "B.Cu")
		(net "DELTA_L_GND_1")
	)
	(via
		(at 329.188826 3.915156)
		(size 0.508)
		(drill 0.254)
		(layers "F.Cu" "B.Cu")
		(net "DELTA_L_GND_1")
	)
	(via
		(at 377.287282 -0.868934)
		(size 0.508)
		(drill 0.254)
		(layers "F.Cu" "B.Cu")
		(net "DELTA_L_GND_1")
	)
	(via
		(at 339.346286 -3.793744)
		(size 0.508)
		(drill 0.254)
		(layers "F.Cu" "B.Cu")
		(net "DELTA_L_GND_1")
	)
	(via
		(at 259.945378 5.467604)
		(size 0.508)
		(drill 0.254)
		(layers "F.Cu" "B.Cu")
		(net "DELTA_L_GND_1")
	)
	(via
		(at 378.051822 -0.540766)
		(size 0.508)
		(drill 0.254)
		(layers "F.Cu" "B.Cu")
		(net "DELTA_L_GND_1")
	)
	(via
		(at 378.885704 2.934716)
		(size 0.508)
		(drill 0.254)
		(layers "F.Cu" "B.Cu")
		(net "DELTA_L_GND_1")
	)
	(via
		(at 378.885704 1.371346)
		(size 0.508)
		(drill 0.254)
		(layers "F.Cu" "B.Cu")
		(net "DELTA_L_GND_1")
	)
	(via
		(at 259.945378 2.920238)
		(size 0.508)
		(drill 0.254)
		(layers "F.Cu" "B.Cu")
		(net "DELTA_L_GND_1")
	)
	(via
		(at 375.959116 6.093206)
		(size 0.508)
		(drill 0.254)
		(layers "F.Cu" "B.Cu")
		(net "DELTA_L_GND_1")
	)
	(via
		(at 378.048012 9.009888)
		(size 0.508)
		(drill 0.254)
		(layers "F.Cu" "B.Cu")
		(net "DELTA_L_GND_1")
	)
	(via
		(at 259.945378 -0.611124)
		(size 0.508)
		(drill 0.254)
		(layers "F.Cu" "B.Cu")
		(net "DELTA_L_GND_1")
	)
	(via
		(at 339.350096 -5.7023)
		(size 0.508)
		(drill 0.254)
		(layers "F.Cu" "B.Cu")
		(net "DELTA_L_GND_1")
	)
	(segment
		(start 202.023472 -186.87542)
		(end 203.327 -188.178948)
		(width 0.12954)
		(layer "F.Cu")
		(net "CLK_SWB_BUF2_OE_N")
	)
	(segment
		(start 218.739212 -327.031096)
		(end 206.28102 -339.489288)
		(width 0.12954)
		(layer "F.Cu")
		(net "CLK_SWB_BUF2_OE_N")
	)
	(segment
		(start 194.289934 -188.49213)
		(end 194.289934 -187.95619)
		(width 0.12954)
		(layer "F.Cu")
		(net "CLK_SWB_BUF2_OE_N")
	)
	(segment
		(start 206.28102 -339.489288)
		(end 206.28102 -341.127588)
		(width 0.12954)
		(layer "F.Cu")
		(net "CLK_SWB_BUF2_OE_N")
	)
	(segment
		(start 225.308668 -312.228992)
		(end 218.739212 -318.798448)
		(width 0.12954)
		(layer "F.Cu")
		(net "CLK_SWB_BUF2_OE_N")
	)
	(segment
		(start 195.370704 -186.87542)
		(end 202.023472 -186.87542)
		(width 0.12954)
		(layer "F.Cu")
		(net "CLK_SWB_BUF2_OE_N")
	)
	(segment
		(start 218.739212 -318.798448)
		(end 218.739212 -327.031096)
		(width 0.12954)
		(layer "F.Cu")
		(net "CLK_SWB_BUF2_OE_N")
	)
	(segment
		(start 215.68918 -192.43294)
		(end 217.66022 -192.43294)
		(width 0.12954)
		(layer "F.Cu")
		(net "CLK_SWB_BUF2_OE_N")
	)
	(segment
		(start 196.946012 -127.635508)
		(end 197.10654 -127.796036)
		(width 0.12954)
		(layer "F.Cu")
		(net "CLK_SWB_BUF2_OE_N")
	)
	(segment
		(start 217.66022 -192.43294)
		(end 221.59087 -196.36359)
		(width 0.12954)
		(layer "F.Cu")
		(net "CLK_SWB_BUF2_OE_N")
	)
	(segment
		(start 197.10654 -134.114032)
		(end 196.630544 -134.590028)
		(width 0.12954)
		(layer "F.Cu")
		(net "CLK_SWB_BUF2_OE_N")
	)
	(segment
		(start 203.327 -188.178948)
		(end 203.327 -189.906148)
		(width 0.12954)
		(layer "F.Cu")
		(net "CLK_SWB_BUF2_OE_N")
	)
	(segment
		(start 225.308668 -239.592358)
		(end 225.308668 -312.228992)
		(width 0.12954)
		(layer "F.Cu")
		(net "CLK_SWB_BUF2_OE_N")
	)
	(segment
		(start 187.36945 -148.760688)
		(end 186.216036 -148.760688)
		(width 0.12954)
		(layer "F.Cu")
		(net "CLK_SWB_BUF2_OE_N")
	)
	(segment
		(start 214.9602 -191.70396)
		(end 215.68918 -192.43294)
		(width 0.12954)
		(layer "F.Cu")
		(net "CLK_SWB_BUF2_OE_N")
	)
	(segment
		(start 221.59087 -235.87456)
		(end 225.308668 -239.592358)
		(width 0.12954)
		(layer "F.Cu")
		(net "CLK_SWB_BUF2_OE_N")
	)
	(segment
		(start 197.10654 -127.796036)
		(end 197.10654 -134.114032)
		(width 0.12954)
		(layer "F.Cu")
		(net "CLK_SWB_BUF2_OE_N")
	)
	(segment
		(start 196.630544 -139.499594)
		(end 187.36945 -148.760688)
		(width 0.12954)
		(layer "F.Cu")
		(net "CLK_SWB_BUF2_OE_N")
	)
	(segment
		(start 193.78295 -126.405386)
		(end 195.71589 -126.405386)
		(width 0.12954)
		(layer "F.Cu")
		(net "CLK_SWB_BUF2_OE_N")
	)
	(segment
		(start 106.46537 -418.814758)
		(end 106.46537 -418.392864)
		(width 0.12954)
		(layer "F.Cu")
		(net "CLK_SWB_BUF2_OE_N")
	)
	(segment
		(start 194.289934 -187.95619)
		(end 195.370704 -186.87542)
		(width 0.12954)
		(layer "F.Cu")
		(net "CLK_SWB_BUF2_OE_N")
	)
	(segment
		(start 204.027278 -190.606426)
		(end 210.591654 -190.606426)
		(width 0.12954)
		(layer "F.Cu")
		(net "CLK_SWB_BUF2_OE_N")
	)
	(segment
		(start 106.16184 -419.118288)
		(end 106.46537 -418.814758)
		(width 0.12954)
		(layer "F.Cu")
		(net "CLK_SWB_BUF2_OE_N")
	)
	(segment
		(start 211.689188 -191.70396)
		(end 214.9602 -191.70396)
		(width 0.12954)
		(layer "F.Cu")
		(net "CLK_SWB_BUF2_OE_N")
	)
	(segment
		(start 196.630544 -134.590028)
		(end 196.630544 -139.499594)
		(width 0.12954)
		(layer "F.Cu")
		(net "CLK_SWB_BUF2_OE_N")
	)
	(segment
		(start 182.155592 -116.175536)
		(end 182.555642 -116.575586)
		(width 0.12954)
		(layer "F.Cu")
		(net "CLK_SWB_BUF2_OE_N")
	)
	(segment
		(start 210.591654 -190.606426)
		(end 211.689188 -191.70396)
		(width 0.12954)
		(layer "F.Cu")
		(net "CLK_SWB_BUF2_OE_N")
	)
	(segment
		(start 203.327 -189.906148)
		(end 204.027278 -190.606426)
		(width 0.12954)
		(layer "F.Cu")
		(net "CLK_SWB_BUF2_OE_N")
	)
	(segment
		(start 195.71589 -126.405386)
		(end 196.946012 -127.635508)
		(width 0.12954)
		(layer "F.Cu")
		(net "CLK_SWB_BUF2_OE_N")
	)
	(segment
		(start 221.59087 -196.36359)
		(end 221.59087 -235.87456)
		(width 0.12954)
		(layer "F.Cu")
		(net "CLK_SWB_BUF2_OE_N")
	)
	(via
		(at 194.289934 -188.49213)
		(size 0.508)
		(drill 0.254)
		(layers "F.Cu" "B.Cu")
		(net "CLK_SWB_BUF2_OE_N")
	)
	(via
		(at 122.135392 -393.22248)
		(size 0.508)
		(drill 0.254)
		(layers "F.Cu" "B.Cu")
		(net "CLK_SWB_BUF2_OE_N")
	)
	(via
		(at 206.28102 -341.127588)
		(size 0.508)
		(drill 0.254)
		(layers "F.Cu" "B.Cu")
		(net "CLK_SWB_BUF2_OE_N")
	)
	(via
		(at 182.555642 -116.575586)
		(size 0.4572)
		(drill 0.254)
		(layers "F.Cu" "B.Cu")
		(net "CLK_SWB_BUF2_OE_N")
	)
	(via
		(at 186.216036 -148.760688)
		(size 0.508)
		(drill 0.254)
		(layers "F.Cu" "B.Cu")
		(net "CLK_SWB_BUF2_OE_N")
	)
	(via
		(at 106.16184 -419.118288)
		(size 0.508)
		(drill 0.254)
		(layers "F.Cu" "B.Cu")
		(net "CLK_SWB_BUF2_OE_N")
	)
	(via
		(at 196.946012 -127.635508)
		(size 0.508)
		(drill 0.254)
		(layers "F.Cu" "B.Cu")
		(net "CLK_SWB_BUF2_OE_N")
	)
	(segment
		(start 122.135392 -391.949432)
		(end 122.135392 -393.22248)
		(width 0.12954)
		(layer "B.Cu")
		(net "CLK_SWB_BUF2_OE_N")
	)
	(segment
		(start 127.66421 -386.420614)
		(end 122.135392 -391.949432)
		(width 0.12954)
		(layer "B.Cu")
		(net "CLK_SWB_BUF2_OE_N")
	)
	(segment
		(start 206.28102 -341.127588)
		(end 206.28102 -354.751386)
		(width 0.12954)
		(layer "B.Cu")
		(net "CLK_SWB_BUF2_OE_N")
	)
	(segment
		(start 174.611792 -386.420614)
		(end 127.66421 -386.420614)
		(width 0.12954)
		(layer "B.Cu")
		(net "CLK_SWB_BUF2_OE_N")
	)
	(segment
		(start 206.28102 -354.751386)
		(end 174.611792 -386.420614)
		(width 0.12954)
		(layer "B.Cu")
		(net "CLK_SWB_BUF2_OE_N")
	)
	(segment
		(start 194.289934 -187.766706)
		(end 193.034158 -186.51093)
		(width 0.127)
		(layer "In2.Cu")
		(net "CLK_SWB_BUF2_OE_N")
	)
	(segment
		(start 187.091574 -186.51093)
		(end 183.684672 -183.104028)
		(width 0.127)
		(layer "In2.Cu")
		(net "CLK_SWB_BUF2_OE_N")
	)
	(segment
		(start 184.813702 -164.921692)
		(end 184.813702 -153.35377)
		(width 0.127)
		(layer "In2.Cu")
		(net "CLK_SWB_BUF2_OE_N")
	)
	(segment
		(start 183.684672 -183.104028)
		(end 183.684672 -166.050722)
		(width 0.127)
		(layer "In2.Cu")
		(net "CLK_SWB_BUF2_OE_N")
	)
	(segment
		(start 186.216036 -151.951436)
		(end 186.216036 -148.760688)
		(width 0.127)
		(layer "In2.Cu")
		(net "CLK_SWB_BUF2_OE_N")
	)
	(segment
		(start 193.034158 -186.51093)
		(end 187.091574 -186.51093)
		(width 0.127)
		(layer "In2.Cu")
		(net "CLK_SWB_BUF2_OE_N")
	)
	(segment
		(start 184.813702 -153.35377)
		(end 186.216036 -151.951436)
		(width 0.127)
		(layer "In2.Cu")
		(net "CLK_SWB_BUF2_OE_N")
	)
	(segment
		(start 194.289934 -188.49213)
		(end 194.289934 -187.766706)
		(width 0.127)
		(layer "In2.Cu")
		(net "CLK_SWB_BUF2_OE_N")
	)
	(segment
		(start 183.684672 -166.050722)
		(end 184.813702 -164.921692)
		(width 0.127)
		(layer "In2.Cu")
		(net "CLK_SWB_BUF2_OE_N")
	)
	(segment
		(start 115.266978 -399.863564)
		(end 114.403886 -400.726656)
		(width 0.127)
		(layer "In13.Cu")
		(net "CLK_SWB_BUF2_OE_N")
	)
	(segment
		(start 113.07572 -401.423886)
		(end 113.07572 -402.21408)
		(width 0.127)
		(layer "In13.Cu")
		(net "CLK_SWB_BUF2_OE_N")
	)
	(segment
		(start 106.16184 -414.32226)
		(end 106.16184 -419.118288)
		(width 0.127)
		(layer "In13.Cu")
		(net "CLK_SWB_BUF2_OE_N")
	)
	(segment
		(start 122.135392 -393.22248)
		(end 122.038872 -393.319)
		(width 0.127)
		(layer "In13.Cu")
		(net "CLK_SWB_BUF2_OE_N")
	)
	(segment
		(start 113.07572 -402.21408)
		(end 108.3818 -406.908)
		(width 0.127)
		(layer "In13.Cu")
		(net "CLK_SWB_BUF2_OE_N")
	)
	(segment
		(start 113.77295 -400.726656)
		(end 113.07572 -401.423886)
		(width 0.127)
		(layer "In13.Cu")
		(net "CLK_SWB_BUF2_OE_N")
	)
	(segment
		(start 122.038872 -393.319)
		(end 122.038872 -394.521182)
		(width 0.127)
		(layer "In13.Cu")
		(net "CLK_SWB_BUF2_OE_N")
	)
	(segment
		(start 108.3818 -412.1023)
		(end 106.16184 -414.32226)
		(width 0.127)
		(layer "In13.Cu")
		(net "CLK_SWB_BUF2_OE_N")
	)
	(segment
		(start 115.266978 -398.867376)
		(end 115.266978 -399.863564)
		(width 0.127)
		(layer "In13.Cu")
		(net "CLK_SWB_BUF2_OE_N")
	)
	(segment
		(start 119.849646 -396.710408)
		(end 117.423946 -396.710408)
		(width 0.127)
		(layer "In13.Cu")
		(net "CLK_SWB_BUF2_OE_N")
	)
	(segment
		(start 117.423946 -396.710408)
		(end 115.266978 -398.867376)
		(width 0.127)
		(layer "In13.Cu")
		(net "CLK_SWB_BUF2_OE_N")
	)
	(segment
		(start 122.038872 -394.521182)
		(end 119.849646 -396.710408)
		(width 0.127)
		(layer "In13.Cu")
		(net "CLK_SWB_BUF2_OE_N")
	)
	(segment
		(start 114.403886 -400.726656)
		(end 113.77295 -400.726656)
		(width 0.127)
		(layer "In13.Cu")
		(net "CLK_SWB_BUF2_OE_N")
	)
	(segment
		(start 108.3818 -406.908)
		(end 108.3818 -412.1023)
		(width 0.127)
		(layer "In13.Cu")
		(net "CLK_SWB_BUF2_OE_N")
	)
	(segment
		(start 182.95874 -118.364508)
		(end 183.1721 -118.577868)
		(width 0.127)
		(layer "In15.Cu")
		(net "CLK_SWB_BUF2_OE_N")
	)
	(segment
		(start 183.75376 -118.778528)
		(end 183.75376 -119.182388)
		(width 0.127)
		(layer "In15.Cu")
		(net "CLK_SWB_BUF2_OE_N")
	)
	(segment
		(start 183.95188 -119.380508)
		(end 184.34304 -119.380508)
		(width 0.127)
		(layer "In15.Cu")
		(net "CLK_SWB_BUF2_OE_N")
	)
	(segment
		(start 182.15356 -117.654578)
		(end 182.27421 -117.775228)
		(width 0.127)
		(layer "In15.Cu")
		(net "CLK_SWB_BUF2_OE_N")
	)
	(segment
		(start 183.75376 -119.182388)
		(end 183.95188 -119.380508)
		(width 0.127)
		(layer "In15.Cu")
		(net "CLK_SWB_BUF2_OE_N")
	)
	(segment
		(start 186.39028 -121.338848)
		(end 186.9567 -121.905268)
		(width 0.127)
		(layer "In15.Cu")
		(net "CLK_SWB_BUF2_OE_N")
	)
	(segment
		(start 183.5531 -118.577868)
		(end 183.75376 -118.778528)
		(width 0.127)
		(layer "In15.Cu")
		(net "CLK_SWB_BUF2_OE_N")
	)
	(segment
		(start 184.55132 -119.957088)
		(end 184.76976 -120.175528)
		(width 0.127)
		(layer "In15.Cu")
		(net "CLK_SWB_BUF2_OE_N")
	)
	(segment
		(start 186.9567 -121.905268)
		(end 186.9567 -122.352308)
		(width 0.127)
		(layer "In15.Cu")
		(net "CLK_SWB_BUF2_OE_N")
	)
	(segment
		(start 186.9567 -122.352308)
		(end 188.5188 -123.914408)
		(width 0.127)
		(layer "In15.Cu")
		(net "CLK_SWB_BUF2_OE_N")
	)
	(segment
		(start 182.73522 -117.775228)
		(end 182.95874 -117.998748)
		(width 0.127)
		(layer "In15.Cu")
		(net "CLK_SWB_BUF2_OE_N")
	)
	(segment
		(start 185.9407 -120.175528)
		(end 186.39028 -120.625108)
		(width 0.127)
		(layer "In15.Cu")
		(net "CLK_SWB_BUF2_OE_N")
	)
	(segment
		(start 182.555642 -116.575586)
		(end 182.434738 -116.575586)
		(width 0.127)
		(layer "In15.Cu")
		(net "CLK_SWB_BUF2_OE_N")
	)
	(segment
		(start 196.464682 -127.154178)
		(end 196.946012 -127.635508)
		(width 0.127)
		(layer "In15.Cu")
		(net "CLK_SWB_BUF2_OE_N")
	)
	(segment
		(start 182.434738 -116.575586)
		(end 182.15356 -116.856764)
		(width 0.127)
		(layer "In15.Cu")
		(net "CLK_SWB_BUF2_OE_N")
	)
	(segment
		(start 190.665354 -123.914408)
		(end 193.905124 -127.154178)
		(width 0.127)
		(layer "In15.Cu")
		(net "CLK_SWB_BUF2_OE_N")
	)
	(segment
		(start 184.76976 -120.175528)
		(end 185.9407 -120.175528)
		(width 0.127)
		(layer "In15.Cu")
		(net "CLK_SWB_BUF2_OE_N")
	)
	(segment
		(start 182.15356 -116.856764)
		(end 182.15356 -117.654578)
		(width 0.127)
		(layer "In15.Cu")
		(net "CLK_SWB_BUF2_OE_N")
	)
	(segment
		(start 184.55132 -119.588788)
		(end 184.55132 -119.957088)
		(width 0.127)
		(layer "In15.Cu")
		(net "CLK_SWB_BUF2_OE_N")
	)
	(segment
		(start 193.905124 -127.154178)
		(end 196.464682 -127.154178)
		(width 0.127)
		(layer "In15.Cu")
		(net "CLK_SWB_BUF2_OE_N")
	)
	(segment
		(start 184.34304 -119.380508)
		(end 184.55132 -119.588788)
		(width 0.127)
		(layer "In15.Cu")
		(net "CLK_SWB_BUF2_OE_N")
	)
	(segment
		(start 183.1721 -118.577868)
		(end 183.5531 -118.577868)
		(width 0.127)
		(layer "In15.Cu")
		(net "CLK_SWB_BUF2_OE_N")
	)
	(segment
		(start 182.27421 -117.775228)
		(end 182.73522 -117.775228)
		(width 0.127)
		(layer "In15.Cu")
		(net "CLK_SWB_BUF2_OE_N")
	)
	(segment
		(start 182.95874 -117.998748)
		(end 182.95874 -118.364508)
		(width 0.127)
		(layer "In15.Cu")
		(net "CLK_SWB_BUF2_OE_N")
	)
	(segment
		(start 186.39028 -120.625108)
		(end 186.39028 -121.338848)
		(width 0.127)
		(layer "In15.Cu")
		(net "CLK_SWB_BUF2_OE_N")
	)
	(segment
		(start 188.5188 -123.914408)
		(end 190.665354 -123.914408)
		(width 0.127)
		(layer "In15.Cu")
		(net "CLK_SWB_BUF2_OE_N")
	)
	(segment
		(start 210.47456 -190.888366)
		(end 211.572094 -191.9859)
		(width 0.12954)
		(layer "F.Cu")
		(net "CLK_GPU_2_OE_N")
	)
	(segment
		(start 214.4522 -191.9859)
		(end 215.18118 -192.71488)
		(width 0.12954)
		(layer "F.Cu")
		(net "CLK_GPU_2_OE_N")
	)
	(segment
		(start 211.572094 -191.9859)
		(end 214.4522 -191.9859)
		(width 0.12954)
		(layer "F.Cu")
		(net "CLK_GPU_2_OE_N")
	)
	(segment
		(start 105.78592 -411.582108)
		(end 106.31805 -411.582108)
		(width 0.12954)
		(layer "F.Cu")
		(net "CLK_GPU_2_OE_N")
	)
	(segment
		(start 193.891916 -133.097778)
		(end 193.891916 -139.599162)
		(width 0.12954)
		(layer "F.Cu")
		(net "CLK_GPU_2_OE_N")
	)
	(segment
		(start 201.837544 -187.324238)
		(end 202.878182 -188.364876)
		(width 0.12954)
		(layer "F.Cu")
		(net "CLK_GPU_2_OE_N")
	)
	(segment
		(start 221.142052 -196.313806)
		(end 221.142052 -236.060488)
		(width 0.12954)
		(layer "F.Cu")
		(net "CLK_GPU_2_OE_N")
	)
	(segment
		(start 218.290394 -326.845168)
		(end 205.53934 -339.596222)
		(width 0.12954)
		(layer "F.Cu")
		(net "CLK_GPU_2_OE_N")
	)
	(segment
		(start 218.290394 -318.61252)
		(end 218.290394 -326.845168)
		(width 0.12954)
		(layer "F.Cu")
		(net "CLK_GPU_2_OE_N")
	)
	(segment
		(start 215.18118 -192.71488)
		(end 217.543126 -192.71488)
		(width 0.12954)
		(layer "F.Cu")
		(net "CLK_GPU_2_OE_N")
	)
	(segment
		(start 224.85985 -239.778286)
		(end 224.85985 -312.043064)
		(width 0.12954)
		(layer "F.Cu")
		(net "CLK_GPU_2_OE_N")
	)
	(segment
		(start 193.891916 -139.599162)
		(end 187.747148 -145.74393)
		(width 0.12954)
		(layer "F.Cu")
		(net "CLK_GPU_2_OE_N")
	)
	(segment
		(start 203.674472 -190.888366)
		(end 210.47456 -190.888366)
		(width 0.12954)
		(layer "F.Cu")
		(net "CLK_GPU_2_OE_N")
	)
	(segment
		(start 224.85985 -312.043064)
		(end 218.290394 -318.61252)
		(width 0.12954)
		(layer "F.Cu")
		(net "CLK_GPU_2_OE_N")
	)
	(segment
		(start 195.51523 -131.474464)
		(end 193.891916 -133.097778)
		(width 0.12954)
		(layer "F.Cu")
		(net "CLK_GPU_2_OE_N")
	)
	(segment
		(start 194.924934 -188.49213)
		(end 194.924934 -188.150754)
		(width 0.12954)
		(layer "F.Cu")
		(net "CLK_GPU_2_OE_N")
	)
	(segment
		(start 187.747148 -145.74393)
		(end 187.747148 -146.938746)
		(width 0.12954)
		(layer "F.Cu")
		(net "CLK_GPU_2_OE_N")
	)
	(segment
		(start 205.53934 -339.596222)
		(end 205.53934 -341.137748)
		(width 0.12954)
		(layer "F.Cu")
		(net "CLK_GPU_2_OE_N")
	)
	(segment
		(start 186.71286 -147.973034)
		(end 186.211718 -147.973034)
		(width 0.12954)
		(layer "F.Cu")
		(net "CLK_GPU_2_OE_N")
	)
	(segment
		(start 202.878182 -190.092076)
		(end 203.674472 -190.888366)
		(width 0.12954)
		(layer "F.Cu")
		(net "CLK_GPU_2_OE_N")
	)
	(segment
		(start 217.543126 -192.71488)
		(end 221.142052 -196.313806)
		(width 0.12954)
		(layer "F.Cu")
		(net "CLK_GPU_2_OE_N")
	)
	(segment
		(start 187.747148 -146.938746)
		(end 186.71286 -147.973034)
		(width 0.12954)
		(layer "F.Cu")
		(net "CLK_GPU_2_OE_N")
	)
	(segment
		(start 185.355738 -118.575328)
		(end 185.755788 -118.975378)
		(width 0.12954)
		(layer "F.Cu")
		(net "CLK_GPU_2_OE_N")
	)
	(segment
		(start 195.51523 -127.6604)
		(end 195.51523 -131.474464)
		(width 0.12954)
		(layer "F.Cu")
		(net "CLK_GPU_2_OE_N")
	)
	(segment
		(start 221.142052 -236.060488)
		(end 224.85985 -239.778286)
		(width 0.12954)
		(layer "F.Cu")
		(net "CLK_GPU_2_OE_N")
	)
	(segment
		(start 105.66908 -411.698948)
		(end 105.78592 -411.582108)
		(width 0.12954)
		(layer "F.Cu")
		(net "CLK_GPU_2_OE_N")
	)
	(segment
		(start 195.75145 -187.324238)
		(end 201.837544 -187.324238)
		(width 0.12954)
		(layer "F.Cu")
		(net "CLK_GPU_2_OE_N")
	)
	(segment
		(start 202.878182 -188.364876)
		(end 202.878182 -190.092076)
		(width 0.12954)
		(layer "F.Cu")
		(net "CLK_GPU_2_OE_N")
	)
	(segment
		(start 194.924934 -188.150754)
		(end 195.75145 -187.324238)
		(width 0.12954)
		(layer "F.Cu")
		(net "CLK_GPU_2_OE_N")
	)
	(via
		(at 186.211718 -147.973034)
		(size 0.508)
		(drill 0.254)
		(layers "F.Cu" "B.Cu")
		(net "CLK_GPU_2_OE_N")
	)
	(via
		(at 185.755788 -118.975378)
		(size 0.4572)
		(drill 0.254)
		(layers "F.Cu" "B.Cu")
		(net "CLK_GPU_2_OE_N")
	)
	(via
		(at 194.924934 -188.49213)
		(size 0.508)
		(drill 0.254)
		(layers "F.Cu" "B.Cu")
		(net "CLK_GPU_2_OE_N")
	)
	(via
		(at 205.53934 -341.137748)
		(size 0.508)
		(drill 0.254)
		(layers "F.Cu" "B.Cu")
		(net "CLK_GPU_2_OE_N")
	)
	(via
		(at 121.403872 -393.222988)
		(size 0.508)
		(drill 0.254)
		(layers "F.Cu" "B.Cu")
		(net "CLK_GPU_2_OE_N")
	)
	(via
		(at 195.51523 -127.6604)
		(size 0.508)
		(drill 0.254)
		(layers "F.Cu" "B.Cu")
		(net "CLK_GPU_2_OE_N")
	)
	(via
		(at 105.66908 -411.698948)
		(size 0.508)
		(drill 0.254)
		(layers "F.Cu" "B.Cu")
		(net "CLK_GPU_2_OE_N")
	)
	(segment
		(start 195.108576 -124.656088)
		(end 195.365878 -124.91339)
		(width 0.12954)
		(layer "B.Cu")
		(net "CLK_GPU_2_OE_N")
	)
	(segment
		(start 192.405762 -124.160788)
		(end 192.901062 -124.656088)
		(width 0.12954)
		(layer "B.Cu")
		(net "CLK_GPU_2_OE_N")
	)
	(segment
		(start 121.403872 -391.782808)
		(end 121.403872 -393.222988)
		(width 0.12954)
		(layer "B.Cu")
		(net "CLK_GPU_2_OE_N")
	)
	(segment
		(start 194.890898 -126.405132)
		(end 193.784728 -126.405132)
		(width 0.12954)
		(layer "B.Cu")
		(net "CLK_GPU_2_OE_N")
	)
	(segment
		(start 194.842892 -126.988062)
		(end 194.367658 -126.988062)
		(width 0.12954)
		(layer "B.Cu")
		(net "CLK_GPU_2_OE_N")
	)
	(segment
		(start 186.35218 -119.57177)
		(end 186.35218 -120.248426)
		(width 0.12954)
		(layer "B.Cu")
		(net "CLK_GPU_2_OE_N")
	)
	(segment
		(start 205.53934 -354.594922)
		(end 174.348648 -385.785614)
		(width 0.12954)
		(layer "B.Cu")
		(net "CLK_GPU_2_OE_N")
	)
	(segment
		(start 127.401066 -385.785614)
		(end 121.403872 -391.782808)
		(width 0.12954)
		(layer "B.Cu")
		(net "CLK_GPU_2_OE_N")
	)
	(segment
		(start 174.348648 -385.785614)
		(end 127.401066 -385.785614)
		(width 0.12954)
		(layer "B.Cu")
		(net "CLK_GPU_2_OE_N")
	)
	(segment
		(start 190.264542 -124.160788)
		(end 192.405762 -124.160788)
		(width 0.12954)
		(layer "B.Cu")
		(net "CLK_GPU_2_OE_N")
	)
	(segment
		(start 205.53934 -341.137748)
		(end 205.53934 -354.594922)
		(width 0.12954)
		(layer "B.Cu")
		(net "CLK_GPU_2_OE_N")
	)
	(segment
		(start 192.901062 -124.656088)
		(end 195.108576 -124.656088)
		(width 0.12954)
		(layer "B.Cu")
		(net "CLK_GPU_2_OE_N")
	)
	(segment
		(start 185.755788 -118.975378)
		(end 186.35218 -119.57177)
		(width 0.12954)
		(layer "B.Cu")
		(net "CLK_GPU_2_OE_N")
	)
	(segment
		(start 195.365878 -124.91339)
		(end 195.365878 -125.930152)
		(width 0.12954)
		(layer "B.Cu")
		(net "CLK_GPU_2_OE_N")
	)
	(segment
		(start 195.51523 -127.6604)
		(end 194.842892 -126.988062)
		(width 0.12954)
		(layer "B.Cu")
		(net "CLK_GPU_2_OE_N")
	)
	(segment
		(start 195.365878 -125.930152)
		(end 194.890898 -126.405132)
		(width 0.12954)
		(layer "B.Cu")
		(net "CLK_GPU_2_OE_N")
	)
	(segment
		(start 194.367658 -126.988062)
		(end 193.784728 -126.405132)
		(width 0.12954)
		(layer "B.Cu")
		(net "CLK_GPU_2_OE_N")
	)
	(segment
		(start 186.35218 -120.248426)
		(end 190.264542 -124.160788)
		(width 0.12954)
		(layer "B.Cu")
		(net "CLK_GPU_2_OE_N")
	)
	(segment
		(start 186.687968 -148.44903)
		(end 186.211718 -147.97278)
		(width 0.127)
		(layer "In2.Cu")
		(net "CLK_GPU_2_OE_N")
	)
	(segment
		(start 186.687968 -152.147016)
		(end 186.687968 -148.44903)
		(width 0.127)
		(layer "In2.Cu")
		(net "CLK_GPU_2_OE_N")
	)
	(segment
		(start 187.287154 -186.038998)
		(end 184.156604 -182.908448)
		(width 0.127)
		(layer "In2.Cu")
		(net "CLK_GPU_2_OE_N")
	)
	(segment
		(start 194.924934 -187.734194)
		(end 193.229738 -186.038998)
		(width 0.127)
		(layer "In2.Cu")
		(net "CLK_GPU_2_OE_N")
	)
	(segment
		(start 185.285634 -165.117272)
		(end 185.285634 -153.54935)
		(width 0.127)
		(layer "In2.Cu")
		(net "CLK_GPU_2_OE_N")
	)
	(segment
		(start 186.211718 -147.97278)
		(end 186.211718 -147.973034)
		(width 0.127)
		(layer "In2.Cu")
		(net "CLK_GPU_2_OE_N")
	)
	(segment
		(start 185.285634 -153.54935)
		(end 186.687968 -152.147016)
		(width 0.127)
		(layer "In2.Cu")
		(net "CLK_GPU_2_OE_N")
	)
	(segment
		(start 184.156604 -182.908448)
		(end 184.156604 -166.246302)
		(width 0.127)
		(layer "In2.Cu")
		(net "CLK_GPU_2_OE_N")
	)
	(segment
		(start 184.156604 -166.246302)
		(end 185.285634 -165.117272)
		(width 0.127)
		(layer "In2.Cu")
		(net "CLK_GPU_2_OE_N")
	)
	(segment
		(start 194.924934 -188.49213)
		(end 194.924934 -187.734194)
		(width 0.127)
		(layer "In2.Cu")
		(net "CLK_GPU_2_OE_N")
	)
	(segment
		(start 193.229738 -186.038998)
		(end 187.287154 -186.038998)
		(width 0.127)
		(layer "In2.Cu")
		(net "CLK_GPU_2_OE_N")
	)
	(segment
		(start 121.403872 -393.222988)
		(end 121.403872 -394.622782)
		(width 0.127)
		(layer "In13.Cu")
		(net "CLK_GPU_2_OE_N")
	)
	(segment
		(start 110.9218 -403.402546)
		(end 108.483146 -405.8412)
		(width 0.127)
		(layer "In13.Cu")
		(net "CLK_GPU_2_OE_N")
	)
	(segment
		(start 110.9218 -398.54124)
		(end 110.9218 -403.402546)
		(width 0.127)
		(layer "In13.Cu")
		(net "CLK_GPU_2_OE_N")
	)
	(segment
		(start 116.943378 -396.278354)
		(end 115.134136 -398.087596)
		(width 0.127)
		(layer "In13.Cu")
		(net "CLK_GPU_2_OE_N")
	)
	(segment
		(start 105.8418 -411.526228)
		(end 105.66908 -411.698948)
		(width 0.127)
		(layer "In13.Cu")
		(net "CLK_GPU_2_OE_N")
	)
	(segment
		(start 111.375444 -398.087596)
		(end 110.9218 -398.54124)
		(width 0.127)
		(layer "In13.Cu")
		(net "CLK_GPU_2_OE_N")
	)
	(segment
		(start 115.134136 -398.087596)
		(end 111.375444 -398.087596)
		(width 0.127)
		(layer "In13.Cu")
		(net "CLK_GPU_2_OE_N")
	)
	(segment
		(start 121.403872 -394.622782)
		(end 119.7483 -396.278354)
		(width 0.127)
		(layer "In13.Cu")
		(net "CLK_GPU_2_OE_N")
	)
	(segment
		(start 119.7483 -396.278354)
		(end 116.943378 -396.278354)
		(width 0.127)
		(layer "In13.Cu")
		(net "CLK_GPU_2_OE_N")
	)
	(segment
		(start 105.969054 -405.8412)
		(end 105.8418 -405.968454)
		(width 0.127)
		(layer "In13.Cu")
		(net "CLK_GPU_2_OE_N")
	)
	(segment
		(start 105.8418 -405.968454)
		(end 105.8418 -411.526228)
		(width 0.127)
		(layer "In13.Cu")
		(net "CLK_GPU_2_OE_N")
	)
	(segment
		(start 108.483146 -405.8412)
		(end 105.969054 -405.8412)
		(width 0.127)
		(layer "In13.Cu")
		(net "CLK_GPU_2_OE_N")
	)
	(segment
		(start 186.155584 -118.575328)
		(end 186.555634 -118.975378)
		(width 0.12954)
		(layer "F.Cu")
		(net "CLK_GPU_1_OE_N")
	)
	(segment
		(start 106.46029 -417.362386)
		(end 104.763824 -419.058852)
		(width 0.12954)
		(layer "F.Cu")
		(net "CLK_GPU_1_OE_N")
	)
	(segment
		(start 193.493644 -132.861304)
		(end 193.493644 -139.434062)
		(width 0.12954)
		(layer "F.Cu")
		(net "CLK_GPU_1_OE_N")
	)
	(segment
		(start 194.51574 -131.839208)
		(end 193.493644 -132.861304)
		(width 0.12954)
		(layer "F.Cu")
		(net "CLK_GPU_1_OE_N")
	)
	(segment
		(start 210.414108 -191.226948)
		(end 211.455 -192.26784)
		(width 0.12954)
		(layer "F.Cu")
		(net "CLK_GPU_1_OE_N")
	)
	(segment
		(start 214.0966 -192.26784)
		(end 214.82558 -192.99682)
		(width 0.12954)
		(layer "F.Cu")
		(net "CLK_GPU_1_OE_N")
	)
	(segment
		(start 214.82558 -192.99682)
		(end 217.426286 -192.99682)
		(width 0.12954)
		(layer "F.Cu")
		(net "CLK_GPU_1_OE_N")
	)
	(segment
		(start 204.806042 -339.790532)
		(end 204.806042 -341.141304)
		(width 0.12954)
		(layer "F.Cu")
		(net "CLK_GPU_1_OE_N")
	)
	(segment
		(start 201.612754 -187.773056)
		(end 202.388978 -188.54928)
		(width 0.12954)
		(layer "F.Cu")
		(net "CLK_GPU_1_OE_N")
	)
	(segment
		(start 211.455 -192.26784)
		(end 214.0966 -192.26784)
		(width 0.12954)
		(layer "F.Cu")
		(net "CLK_GPU_1_OE_N")
	)
	(segment
		(start 193.493644 -139.434062)
		(end 187.348876 -145.57883)
		(width 0.12954)
		(layer "F.Cu")
		(net "CLK_GPU_1_OE_N")
	)
	(segment
		(start 220.761052 -236.218476)
		(end 224.47885 -239.936274)
		(width 0.12954)
		(layer "F.Cu")
		(net "CLK_GPU_1_OE_N")
	)
	(segment
		(start 202.388978 -188.54928)
		(end 202.388978 -190.27521)
		(width 0.12954)
		(layer "F.Cu")
		(net "CLK_GPU_1_OE_N")
	)
	(segment
		(start 217.426286 -192.99682)
		(end 220.761052 -196.331586)
		(width 0.12954)
		(layer "F.Cu")
		(net "CLK_GPU_1_OE_N")
	)
	(segment
		(start 203.340716 -191.226948)
		(end 210.414108 -191.226948)
		(width 0.12954)
		(layer "F.Cu")
		(net "CLK_GPU_1_OE_N")
	)
	(segment
		(start 217.909394 -318.454532)
		(end 217.909394 -326.68718)
		(width 0.12954)
		(layer "F.Cu")
		(net "CLK_GPU_1_OE_N")
	)
	(segment
		(start 220.761052 -196.331586)
		(end 220.761052 -236.218476)
		(width 0.12954)
		(layer "F.Cu")
		(net "CLK_GPU_1_OE_N")
	)
	(segment
		(start 224.47885 -311.885076)
		(end 217.909394 -318.454532)
		(width 0.12954)
		(layer "F.Cu")
		(net "CLK_GPU_1_OE_N")
	)
	(segment
		(start 224.47885 -239.936274)
		(end 224.47885 -311.885076)
		(width 0.12954)
		(layer "F.Cu")
		(net "CLK_GPU_1_OE_N")
	)
	(segment
		(start 187.348876 -146.773646)
		(end 186.784488 -147.338034)
		(width 0.12954)
		(layer "F.Cu")
		(net "CLK_GPU_1_OE_N")
	)
	(segment
		(start 202.388978 -190.27521)
		(end 203.340716 -191.226948)
		(width 0.12954)
		(layer "F.Cu")
		(net "CLK_GPU_1_OE_N")
	)
	(segment
		(start 194.51574 -128.610868)
		(end 194.51574 -131.839208)
		(width 0.12954)
		(layer "F.Cu")
		(net "CLK_GPU_1_OE_N")
	)
	(segment
		(start 195.559934 -188.49213)
		(end 196.279008 -187.773056)
		(width 0.12954)
		(layer "F.Cu")
		(net "CLK_GPU_1_OE_N")
	)
	(segment
		(start 186.784488 -147.338034)
		(end 186.211718 -147.338034)
		(width 0.12954)
		(layer "F.Cu")
		(net "CLK_GPU_1_OE_N")
	)
	(segment
		(start 196.279008 -187.773056)
		(end 201.612754 -187.773056)
		(width 0.12954)
		(layer "F.Cu")
		(net "CLK_GPU_1_OE_N")
	)
	(segment
		(start 217.909394 -326.68718)
		(end 204.806042 -339.790532)
		(width 0.12954)
		(layer "F.Cu")
		(net "CLK_GPU_1_OE_N")
	)
	(segment
		(start 187.348876 -145.57883)
		(end 187.348876 -146.773646)
		(width 0.12954)
		(layer "F.Cu")
		(net "CLK_GPU_1_OE_N")
	)
	(via
		(at 204.806042 -341.141304)
		(size 0.508)
		(drill 0.254)
		(layers "F.Cu" "B.Cu")
		(net "CLK_GPU_1_OE_N")
	)
	(via
		(at 194.51574 -128.610868)
		(size 0.508)
		(drill 0.254)
		(layers "F.Cu" "B.Cu")
		(net "CLK_GPU_1_OE_N")
	)
	(via
		(at 186.555634 -118.975378)
		(size 0.4572)
		(drill 0.254)
		(layers "F.Cu" "B.Cu")
		(net "CLK_GPU_1_OE_N")
	)
	(via
		(at 186.211718 -147.338034)
		(size 0.508)
		(drill 0.254)
		(layers "F.Cu" "B.Cu")
		(net "CLK_GPU_1_OE_N")
	)
	(via
		(at 104.763824 -419.058852)
		(size 0.508)
		(drill 0.254)
		(layers "F.Cu" "B.Cu")
		(net "CLK_GPU_1_OE_N")
	)
	(via
		(at 120.67794 -393.220448)
		(size 0.508)
		(drill 0.254)
		(layers "F.Cu" "B.Cu")
		(net "CLK_GPU_1_OE_N")
	)
	(via
		(at 195.559934 -188.49213)
		(size 0.508)
		(drill 0.254)
		(layers "F.Cu" "B.Cu")
		(net "CLK_GPU_1_OE_N")
	)
	(segment
		(start 190.27013 -123.4694)
		(end 194.456812 -123.4694)
		(width 0.12954)
		(layer "B.Cu")
		(net "CLK_GPU_1_OE_N")
	)
	(segment
		(start 196.08546 -125.098048)
		(end 196.08546 -127.912622)
		(width 0.12954)
		(layer "B.Cu")
		(net "CLK_GPU_1_OE_N")
	)
	(segment
		(start 194.456812 -123.4694)
		(end 196.08546 -125.098048)
		(width 0.12954)
		(layer "B.Cu")
		(net "CLK_GPU_1_OE_N")
	)
	(segment
		(start 195.387214 -128.610868)
		(end 194.51574 -128.610868)
		(width 0.12954)
		(layer "B.Cu")
		(net "CLK_GPU_1_OE_N")
	)
	(segment
		(start 204.806042 -341.141304)
		(end 204.806042 -354.430076)
		(width 0.12954)
		(layer "B.Cu")
		(net "CLK_GPU_1_OE_N")
	)
	(segment
		(start 196.08546 -127.912622)
		(end 195.387214 -128.610868)
		(width 0.12954)
		(layer "B.Cu")
		(net "CLK_GPU_1_OE_N")
	)
	(segment
		(start 186.7789 -119.97817)
		(end 190.27013 -123.4694)
		(width 0.12954)
		(layer "B.Cu")
		(net "CLK_GPU_1_OE_N")
	)
	(segment
		(start 194.51574 -127.689102)
		(end 194.51574 -128.610868)
		(width 0.12954)
		(layer "B.Cu")
		(net "CLK_GPU_1_OE_N")
	)
	(segment
		(start 174.085504 -385.150614)
		(end 127.137922 -385.150614)
		(width 0.12954)
		(layer "B.Cu")
		(net "CLK_GPU_1_OE_N")
	)
	(segment
		(start 186.555634 -118.975378)
		(end 186.7789 -119.198644)
		(width 0.12954)
		(layer "B.Cu")
		(net "CLK_GPU_1_OE_N")
	)
	(segment
		(start 204.806042 -354.430076)
		(end 174.085504 -385.150614)
		(width 0.12954)
		(layer "B.Cu")
		(net "CLK_GPU_1_OE_N")
	)
	(segment
		(start 127.137922 -385.150614)
		(end 120.67794 -391.610596)
		(width 0.12954)
		(layer "B.Cu")
		(net "CLK_GPU_1_OE_N")
	)
	(segment
		(start 186.7789 -119.198644)
		(end 186.7789 -119.97817)
		(width 0.12954)
		(layer "B.Cu")
		(net "CLK_GPU_1_OE_N")
	)
	(segment
		(start 194.248786 -127.422148)
		(end 194.51574 -127.689102)
		(width 0.12954)
		(layer "B.Cu")
		(net "CLK_GPU_1_OE_N")
	)
	(segment
		(start 193.78168 -127.422148)
		(end 194.248786 -127.422148)
		(width 0.12954)
		(layer "B.Cu")
		(net "CLK_GPU_1_OE_N")
	)
	(segment
		(start 120.67794 -391.610596)
		(end 120.67794 -393.220448)
		(width 0.12954)
		(layer "B.Cu")
		(net "CLK_GPU_1_OE_N")
	)
	(segment
		(start 193.377566 -185.68162)
		(end 187.435236 -185.68162)
		(width 0.127)
		(layer "In2.Cu")
		(net "CLK_GPU_1_OE_N")
	)
	(segment
		(start 195.559934 -187.863988)
		(end 193.377566 -185.68162)
		(width 0.127)
		(layer "In2.Cu")
		(net "CLK_GPU_1_OE_N")
	)
	(segment
		(start 195.559934 -188.49213)
		(end 195.559934 -187.863988)
		(width 0.127)
		(layer "In2.Cu")
		(net "CLK_GPU_1_OE_N")
	)
	(segment
		(start 187.045346 -152.295098)
		(end 187.045346 -148.079206)
		(width 0.127)
		(layer "In2.Cu")
		(net "CLK_GPU_1_OE_N")
	)
	(segment
		(start 185.643012 -153.697432)
		(end 187.045346 -152.295098)
		(width 0.127)
		(layer "In2.Cu")
		(net "CLK_GPU_1_OE_N")
	)
	(segment
		(start 187.045346 -148.079206)
		(end 186.304174 -147.338034)
		(width 0.127)
		(layer "In2.Cu")
		(net "CLK_GPU_1_OE_N")
	)
	(segment
		(start 187.435236 -185.68162)
		(end 184.513982 -182.760366)
		(width 0.127)
		(layer "In2.Cu")
		(net "CLK_GPU_1_OE_N")
	)
	(segment
		(start 186.304174 -147.338034)
		(end 186.211718 -147.338034)
		(width 0.127)
		(layer "In2.Cu")
		(net "CLK_GPU_1_OE_N")
	)
	(segment
		(start 184.513982 -182.760366)
		(end 184.513982 -166.394384)
		(width 0.127)
		(layer "In2.Cu")
		(net "CLK_GPU_1_OE_N")
	)
	(segment
		(start 185.643012 -165.265354)
		(end 185.643012 -153.697432)
		(width 0.127)
		(layer "In2.Cu")
		(net "CLK_GPU_1_OE_N")
	)
	(segment
		(start 184.513982 -166.394384)
		(end 185.643012 -165.265354)
		(width 0.127)
		(layer "In2.Cu")
		(net "CLK_GPU_1_OE_N")
	)
	(segment
		(start 116.475764 -394.452348)
		(end 119.539004 -394.452348)
		(width 0.127)
		(layer "In13.Cu")
		(net "CLK_GPU_1_OE_N")
	)
	(segment
		(start 119.539004 -394.452348)
		(end 120.67794 -393.313412)
		(width 0.127)
		(layer "In13.Cu")
		(net "CLK_GPU_1_OE_N")
	)
	(segment
		(start 114.79911 -396.129002)
		(end 116.475764 -394.452348)
		(width 0.127)
		(layer "In13.Cu")
		(net "CLK_GPU_1_OE_N")
	)
	(segment
		(start 104.763824 -419.058852)
		(end 104.763824 -415.102802)
		(width 0.127)
		(layer "In13.Cu")
		(net "CLK_GPU_1_OE_N")
	)
	(segment
		(start 105.3338 -411.08376)
		(end 105.3338 -405.586946)
		(width 0.127)
		(layer "In13.Cu")
		(net "CLK_GPU_1_OE_N")
	)
	(segment
		(start 104.126792 -412.290768)
		(end 105.3338 -411.08376)
		(width 0.127)
		(layer "In13.Cu")
		(net "CLK_GPU_1_OE_N")
	)
	(segment
		(start 109.58068 -404.099014)
		(end 109.58068 -397.397224)
		(width 0.127)
		(layer "In13.Cu")
		(net "CLK_GPU_1_OE_N")
	)
	(segment
		(start 104.126792 -414.46577)
		(end 104.126792 -412.290768)
		(width 0.127)
		(layer "In13.Cu")
		(net "CLK_GPU_1_OE_N")
	)
	(segment
		(start 105.3338 -405.586946)
		(end 105.583736 -405.33701)
		(width 0.127)
		(layer "In13.Cu")
		(net "CLK_GPU_1_OE_N")
	)
	(segment
		(start 105.583736 -405.33701)
		(end 108.342684 -405.33701)
		(width 0.127)
		(layer "In13.Cu")
		(net "CLK_GPU_1_OE_N")
	)
	(segment
		(start 108.342684 -405.33701)
		(end 109.58068 -404.099014)
		(width 0.127)
		(layer "In13.Cu")
		(net "CLK_GPU_1_OE_N")
	)
	(segment
		(start 120.67794 -393.313412)
		(end 120.67794 -393.220448)
		(width 0.127)
		(layer "In13.Cu")
		(net "CLK_GPU_1_OE_N")
	)
	(segment
		(start 109.58068 -397.397224)
		(end 110.848902 -396.129002)
		(width 0.127)
		(layer "In13.Cu")
		(net "CLK_GPU_1_OE_N")
	)
	(segment
		(start 110.848902 -396.129002)
		(end 114.79911 -396.129002)
		(width 0.127)
		(layer "In13.Cu")
		(net "CLK_GPU_1_OE_N")
	)
	(segment
		(start 104.763824 -415.102802)
		(end 104.126792 -414.46577)
		(width 0.127)
		(layer "In13.Cu")
		(net "CLK_GPU_1_OE_N")
	)
	(segment
		(start 249.0724 -89.52865)
		(end 249.0724 -89.923366)
		(width 0.12954)
		(layer "F.Cu")
		(net "XTAL_CLK_GEN1_25M_X1_R")
	)
	(segment
		(start 248.687336 -89.143586)
		(end 249.0724 -89.52865)
		(width 0.12954)
		(layer "F.Cu")
		(net "XTAL_CLK_GEN1_25M_X1_R")
	)
	(segment
		(start 248.412 -92.065348)
		(end 248.1834 -91.836748)
		(width 0.12954)
		(layer "F.Cu")
		(net "XTAL_CLK_GEN1_25M_X1_R")
	)
	(segment
		(start 248.8184 -92.065348)
		(end 248.412 -92.065348)
		(width 0.12954)
		(layer "F.Cu")
		(net "XTAL_CLK_GEN1_25M_X1_R")
	)
	(segment
		(start 248.1834 -90.812366)
		(end 248.340626 -90.65514)
		(width 0.12954)
		(layer "F.Cu")
		(net "XTAL_CLK_GEN1_25M_X1_R")
	)
	(segment
		(start 249.374406 -91.66479)
		(end 249.218958 -91.66479)
		(width 0.12954)
		(layer "F.Cu")
		(net "XTAL_CLK_GEN1_25M_X1_R")
	)
	(segment
		(start 249.0724 -89.923366)
		(end 248.340626 -90.65514)
		(width 0.12954)
		(layer "F.Cu")
		(net "XTAL_CLK_GEN1_25M_X1_R")
	)
	(segment
		(start 248.1834 -91.836748)
		(end 248.1834 -90.812366)
		(width 0.12954)
		(layer "F.Cu")
		(net "XTAL_CLK_GEN1_25M_X1_R")
	)
	(segment
		(start 249.218958 -91.66479)
		(end 248.8184 -92.065348)
		(width 0.12954)
		(layer "F.Cu")
		(net "XTAL_CLK_GEN1_25M_X1_R")
	)
	(via
		(at 248.412 -92.065348)
		(size 0.508)
		(drill 0.254)
		(layers "F.Cu" "B.Cu")
		(net "XTAL_CLK_GEN1_25M_X1_R")
	)
	(segment
		(start 251.046488 -301.112174)
		(end 251.176028 -300.982634)
		(width 0.12954)
		(layer "F.Cu")
		(net "SMB_HOST_CLK_BUF_ISO_3V3AUX_SDA")
	)
	(segment
		(start 197.390512 -369.047268)
		(end 217.144854 -369.047268)
		(width 0.12954)
		(layer "F.Cu")
		(net "SMB_HOST_CLK_BUF_ISO_3V3AUX_SDA")
	)
	(segment
		(start 251.046488 -299.837094)
		(end 251.176028 -299.707554)
		(width 0.12954)
		(layer "F.Cu")
		(net "SMB_HOST_CLK_BUF_ISO_3V3AUX_SDA")
	)
	(segment
		(start 120.49125 -415.276538)
		(end 120.54586 -415.331148)
		(width 0.12954)
		(layer "F.Cu")
		(net "SMB_HOST_CLK_BUF_ISO_3V3AUX_SDA")
	)
	(segment
		(start 251.176028 -300.982634)
		(end 251.176028 -300.604174)
		(width 0.12954)
		(layer "F.Cu")
		(net "SMB_HOST_CLK_BUF_ISO_3V3AUX_SDA")
	)
	(segment
		(start 251.176028 -299.707554)
		(end 251.176028 -194.709542)
		(width 0.12954)
		(layer "F.Cu")
		(net "SMB_HOST_CLK_BUF_ISO_3V3AUX_SDA")
	)
	(segment
		(start 251.176028 -300.604174)
		(end 251.046488 -300.474634)
		(width 0.12954)
		(layer "F.Cu")
		(net "SMB_HOST_CLK_BUF_ISO_3V3AUX_SDA")
	)
	(segment
		(start 158.24962 -415.331148)
		(end 161.704274 -411.876494)
		(width 0.12954)
		(layer "F.Cu")
		(net "SMB_HOST_CLK_BUF_ISO_3V3AUX_SDA")
	)
	(segment
		(start 250.82754 -301.112174)
		(end 251.046488 -301.112174)
		(width 0.12954)
		(layer "F.Cu")
		(net "SMB_HOST_CLK_BUF_ISO_3V3AUX_SDA")
	)
	(segment
		(start 250.82754 -300.474634)
		(end 250.698 -300.345094)
		(width 0.12954)
		(layer "F.Cu")
		(net "SMB_HOST_CLK_BUF_ISO_3V3AUX_SDA")
	)
	(segment
		(start 171.96308 -391.81024)
		(end 174.62754 -391.81024)
		(width 0.12954)
		(layer "F.Cu")
		(net "SMB_HOST_CLK_BUF_ISO_3V3AUX_SDA")
	)
	(segment
		(start 250.698 -301.241714)
		(end 250.82754 -301.112174)
		(width 0.12954)
		(layer "F.Cu")
		(net "SMB_HOST_CLK_BUF_ISO_3V3AUX_SDA")
	)
	(segment
		(start 261.836662 -132.597906)
		(end 261.836662 -133.001512)
		(width 0.12954)
		(layer "F.Cu")
		(net "SMB_HOST_CLK_BUF_ISO_3V3AUX_SDA")
	)
	(segment
		(start 250.698 -300.345094)
		(end 250.698 -299.966634)
		(width 0.12954)
		(layer "F.Cu")
		(net "SMB_HOST_CLK_BUF_ISO_3V3AUX_SDA")
	)
	(segment
		(start 251.046488 -301.749714)
		(end 250.82754 -301.749714)
		(width 0.12954)
		(layer "F.Cu")
		(net "SMB_HOST_CLK_BUF_ISO_3V3AUX_SDA")
	)
	(segment
		(start 170.01744 -410.1719)
		(end 170.01744 -393.75588)
		(width 0.12954)
		(layer "F.Cu")
		(net "SMB_HOST_CLK_BUF_ISO_3V3AUX_SDA")
	)
	(segment
		(start 168.312846 -411.876494)
		(end 170.01744 -410.1719)
		(width 0.12954)
		(layer "F.Cu")
		(net "SMB_HOST_CLK_BUF_ISO_3V3AUX_SDA")
	)
	(segment
		(start 251.176028 -194.709542)
		(end 254.26162 -191.62395)
		(width 0.12954)
		(layer "F.Cu")
		(net "SMB_HOST_CLK_BUF_ISO_3V3AUX_SDA")
	)
	(segment
		(start 251.176028 -301.879254)
		(end 251.046488 -301.749714)
		(width 0.12954)
		(layer "F.Cu")
		(net "SMB_HOST_CLK_BUF_ISO_3V3AUX_SDA")
	)
	(segment
		(start 254.26162 -191.62395)
		(end 254.821944 -191.62395)
		(width 0.12954)
		(layer "F.Cu")
		(net "SMB_HOST_CLK_BUF_ISO_3V3AUX_SDA")
	)
	(segment
		(start 261.840218 -133.005068)
		(end 261.836662 -133.001512)
		(width 0.12954)
		(layer "F.Cu")
		(net "SMB_HOST_CLK_BUF_ISO_3V3AUX_SDA")
	)
	(segment
		(start 262.39216 -132.042408)
		(end 261.836662 -132.597906)
		(width 0.12954)
		(layer "F.Cu")
		(net "SMB_HOST_CLK_BUF_ISO_3V3AUX_SDA")
	)
	(segment
		(start 251.046488 -300.474634)
		(end 250.82754 -300.474634)
		(width 0.12954)
		(layer "F.Cu")
		(net "SMB_HOST_CLK_BUF_ISO_3V3AUX_SDA")
	)
	(segment
		(start 224.639124 -361.552998)
		(end 224.639124 -330.969366)
		(width 0.12954)
		(layer "F.Cu")
		(net "SMB_HOST_CLK_BUF_ISO_3V3AUX_SDA")
	)
	(segment
		(start 217.144854 -369.047268)
		(end 224.639124 -361.552998)
		(width 0.12954)
		(layer "F.Cu")
		(net "SMB_HOST_CLK_BUF_ISO_3V3AUX_SDA")
	)
	(segment
		(start 254.821944 -191.62395)
		(end 255.364742 -191.081152)
		(width 0.12954)
		(layer "F.Cu")
		(net "SMB_HOST_CLK_BUF_ISO_3V3AUX_SDA")
	)
	(segment
		(start 170.01744 -393.75588)
		(end 171.96308 -391.81024)
		(width 0.12954)
		(layer "F.Cu")
		(net "SMB_HOST_CLK_BUF_ISO_3V3AUX_SDA")
	)
	(segment
		(start 251.176028 -304.432462)
		(end 251.176028 -301.879254)
		(width 0.12954)
		(layer "F.Cu")
		(net "SMB_HOST_CLK_BUF_ISO_3V3AUX_SDA")
	)
	(segment
		(start 250.82754 -299.837094)
		(end 251.046488 -299.837094)
		(width 0.12954)
		(layer "F.Cu")
		(net "SMB_HOST_CLK_BUF_ISO_3V3AUX_SDA")
	)
	(segment
		(start 263.15289 -133.005068)
		(end 261.840218 -133.005068)
		(width 0.12954)
		(layer "F.Cu")
		(net "SMB_HOST_CLK_BUF_ISO_3V3AUX_SDA")
	)
	(segment
		(start 224.639124 -330.969366)
		(end 251.176028 -304.432462)
		(width 0.12954)
		(layer "F.Cu")
		(net "SMB_HOST_CLK_BUF_ISO_3V3AUX_SDA")
	)
	(segment
		(start 255.364742 -191.081152)
		(end 255.364742 -190.201804)
		(width 0.12954)
		(layer "F.Cu")
		(net "SMB_HOST_CLK_BUF_ISO_3V3AUX_SDA")
	)
	(segment
		(start 161.704274 -411.876494)
		(end 168.312846 -411.876494)
		(width 0.12954)
		(layer "F.Cu")
		(net "SMB_HOST_CLK_BUF_ISO_3V3AUX_SDA")
	)
	(segment
		(start 250.698 -301.620174)
		(end 250.698 -301.241714)
		(width 0.12954)
		(layer "F.Cu")
		(net "SMB_HOST_CLK_BUF_ISO_3V3AUX_SDA")
	)
	(segment
		(start 250.82754 -301.749714)
		(end 250.698 -301.620174)
		(width 0.12954)
		(layer "F.Cu")
		(net "SMB_HOST_CLK_BUF_ISO_3V3AUX_SDA")
	)
	(segment
		(start 250.698 -299.966634)
		(end 250.82754 -299.837094)
		(width 0.12954)
		(layer "F.Cu")
		(net "SMB_HOST_CLK_BUF_ISO_3V3AUX_SDA")
	)
	(segment
		(start 174.62754 -391.81024)
		(end 197.390512 -369.047268)
		(width 0.12954)
		(layer "F.Cu")
		(net "SMB_HOST_CLK_BUF_ISO_3V3AUX_SDA")
	)
	(segment
		(start 120.54586 -415.331148)
		(end 158.24962 -415.331148)
		(width 0.12954)
		(layer "F.Cu")
		(net "SMB_HOST_CLK_BUF_ISO_3V3AUX_SDA")
	)
	(via
		(at 255.364742 -190.201804)
		(size 0.508)
		(drill 0.254)
		(layers "F.Cu" "B.Cu")
		(net "SMB_HOST_CLK_BUF_ISO_3V3AUX_SDA")
	)
	(via
		(at 262.39216 -132.042408)
		(size 0.508)
		(drill 0.254)
		(layers "F.Cu" "B.Cu")
		(net "SMB_HOST_CLK_BUF_ISO_3V3AUX_SDA")
	)
	(segment
		(start 252.349508 -127.81788)
		(end 252.349508 -152.339548)
		(width 0.127)
		(layer "In2.Cu")
		(net "SMB_HOST_CLK_BUF_ISO_3V3AUX_SDA")
	)
	(segment
		(start 262.39216 -132.042408)
		(end 262.84428 -131.590288)
		(width 0.127)
		(layer "In2.Cu")
		(net "SMB_HOST_CLK_BUF_ISO_3V3AUX_SDA")
	)
	(segment
		(start 259.19557 -125.335284)
		(end 254.832104 -125.335284)
		(width 0.127)
		(layer "In2.Cu")
		(net "SMB_HOST_CLK_BUF_ISO_3V3AUX_SDA")
	)
	(segment
		(start 255.364742 -155.354782)
		(end 255.364742 -190.201804)
		(width 0.127)
		(layer "In2.Cu")
		(net "SMB_HOST_CLK_BUF_ISO_3V3AUX_SDA")
	)
	(segment
		(start 262.84428 -128.983994)
		(end 259.19557 -125.335284)
		(width 0.127)
		(layer "In2.Cu")
		(net "SMB_HOST_CLK_BUF_ISO_3V3AUX_SDA")
	)
	(segment
		(start 252.349508 -152.339548)
		(end 255.364742 -155.354782)
		(width 0.127)
		(layer "In2.Cu")
		(net "SMB_HOST_CLK_BUF_ISO_3V3AUX_SDA")
	)
	(segment
		(start 262.84428 -131.590288)
		(end 262.84428 -128.983994)
		(width 0.127)
		(layer "In2.Cu")
		(net "SMB_HOST_CLK_BUF_ISO_3V3AUX_SDA")
	)
	(segment
		(start 254.832104 -125.335284)
		(end 252.349508 -127.81788)
		(width 0.127)
		(layer "In2.Cu")
		(net "SMB_HOST_CLK_BUF_ISO_3V3AUX_SDA")
	)
	(segment
		(start 262.450072 -129.190496)
		(end 262.450072 -128.365758)
		(width 0.12954)
		(layer "F.Cu")
		(net "SMB_HOST_CLK_BUF_ISO_3V3AUX_SCL")
	)
	(segment
		(start 263.258046 -130.600704)
		(end 263.25957 -130.602228)
		(width 0.12954)
		(layer "F.Cu")
		(net "SMB_HOST_CLK_BUF_ISO_3V3AUX_SCL")
	)
	(segment
		(start 261.836662 -129.803906)
		(end 262.16737 -129.473198)
		(width 0.12954)
		(layer "F.Cu")
		(net "SMB_HOST_CLK_BUF_ISO_3V3AUX_SCL")
	)
	(segment
		(start 261.836662 -130.600704)
		(end 263.258046 -130.600704)
		(width 0.12954)
		(layer "F.Cu")
		(net "SMB_HOST_CLK_BUF_ISO_3V3AUX_SCL")
	)
	(segment
		(start 261.836662 -130.600704)
		(end 261.836662 -129.803906)
		(width 0.12954)
		(layer "F.Cu")
		(net "SMB_HOST_CLK_BUF_ISO_3V3AUX_SCL")
	)
	(segment
		(start 262.16737 -129.473198)
		(end 262.450072 -129.190496)
		(width 0.12954)
		(layer "F.Cu")
		(net "SMB_HOST_CLK_BUF_ISO_3V3AUX_SCL")
	)
	(via
		(at 262.16737 -129.473198)
		(size 0.508)
		(drill 0.254)
		(layers "F.Cu" "B.Cu")
		(net "SMB_HOST_CLK_BUF_ISO_3V3AUX_SCL")
	)
	(segment
		(start 274.81022 -121.641108)
		(end 274.060412 -122.390916)
		(width 0.12954)
		(layer "F.Cu")
		(net "SMB_HOST_CLK_BUF_3V3AUX_SDA")
	)
	(segment
		(start 274.060412 -125.276356)
		(end 275.761958 -126.977902)
		(width 0.12954)
		(layer "F.Cu")
		(net "SMB_HOST_CLK_BUF_3V3AUX_SDA")
	)
	(segment
		(start 274.81022 -121.191528)
		(end 274.81022 -121.641108)
		(width 0.12954)
		(layer "F.Cu")
		(net "SMB_HOST_CLK_BUF_3V3AUX_SDA")
	)
	(segment
		(start 274.060412 -122.390916)
		(end 274.060412 -125.276356)
		(width 0.12954)
		(layer "F.Cu")
		(net "SMB_HOST_CLK_BUF_3V3AUX_SDA")
	)
	(segment
		(start 275.761958 -129.830576)
		(end 274.730718 -130.861816)
		(width 0.12954)
		(layer "F.Cu")
		(net "SMB_HOST_CLK_BUF_3V3AUX_SDA")
	)
	(segment
		(start 275.761958 -126.977902)
		(end 275.761958 -129.830576)
		(width 0.12954)
		(layer "F.Cu")
		(net "SMB_HOST_CLK_BUF_3V3AUX_SDA")
	)
	(segment
		(start 274.730718 -130.861816)
		(end 270.843248 -130.861816)
		(width 0.12954)
		(layer "F.Cu")
		(net "SMB_HOST_CLK_BUF_3V3AUX_SDA")
	)
	(via
		(at 274.81022 -121.191528)
		(size 0.508)
		(drill 0.254)
		(layers "F.Cu" "B.Cu")
		(net "SMB_HOST_CLK_BUF_3V3AUX_SDA")
	)
	(segment
		(start 239.615726 -127.849884)
		(end 239.615726 -128.270762)
		(width 0.12954)
		(layer "B.Cu")
		(net "SMB_HOST_CLK_BUF_3V3AUX_SDA")
	)
	(segment
		(start 242.39982 -125.06579)
		(end 239.615726 -127.849884)
		(width 0.12954)
		(layer "B.Cu")
		(net "SMB_HOST_CLK_BUF_3V3AUX_SDA")
	)
	(segment
		(start 274.81022 -121.635012)
		(end 272.725642 -123.71959)
		(width 0.12954)
		(layer "B.Cu")
		(net "SMB_HOST_CLK_BUF_3V3AUX_SDA")
	)
	(segment
		(start 272.725642 -123.71959)
		(end 249.893582 -123.71959)
		(width 0.12954)
		(layer "B.Cu")
		(net "SMB_HOST_CLK_BUF_3V3AUX_SDA")
	)
	(segment
		(start 274.81022 -121.191528)
		(end 274.81022 -121.635012)
		(width 0.12954)
		(layer "B.Cu")
		(net "SMB_HOST_CLK_BUF_3V3AUX_SDA")
	)
	(segment
		(start 249.893582 -123.71959)
		(end 248.547382 -125.06579)
		(width 0.12954)
		(layer "B.Cu")
		(net "SMB_HOST_CLK_BUF_3V3AUX_SDA")
	)
	(segment
		(start 248.547382 -125.06579)
		(end 242.39982 -125.06579)
		(width 0.12954)
		(layer "B.Cu")
		(net "SMB_HOST_CLK_BUF_3V3AUX_SDA")
	)
	(segment
		(start 272.669 -124.475494)
		(end 272.79854 -124.605034)
		(width 0.12954)
		(layer "F.Cu")
		(net "SMB_HOST_CLK_BUF_3V3AUX_SCL")
	)
	(segment
		(start 272.669 -124.097034)
		(end 272.669 -124.475494)
		(width 0.12954)
		(layer "F.Cu")
		(net "SMB_HOST_CLK_BUF_3V3AUX_SCL")
	)
	(segment
		(start 273.295872 -123.967494)
		(end 272.79854 -123.967494)
		(width 0.12954)
		(layer "F.Cu")
		(net "SMB_HOST_CLK_BUF_3V3AUX_SCL")
	)
	(segment
		(start 273.455892 -123.807474)
		(end 273.295872 -123.967494)
		(width 0.12954)
		(layer "F.Cu")
		(net "SMB_HOST_CLK_BUF_3V3AUX_SCL")
	)
	(segment
		(start 272.79854 -124.605034)
		(end 273.295872 -124.605034)
		(width 0.12954)
		(layer "F.Cu")
		(net "SMB_HOST_CLK_BUF_3V3AUX_SCL")
	)
	(segment
		(start 273.425412 -125.5395)
		(end 275.126958 -127.241046)
		(width 0.12954)
		(layer "F.Cu")
		(net "SMB_HOST_CLK_BUF_3V3AUX_SCL")
	)
	(segment
		(start 274.482814 -130.211576)
		(end 270.843248 -130.211576)
		(width 0.12954)
		(layer "F.Cu")
		(net "SMB_HOST_CLK_BUF_3V3AUX_SCL")
	)
	(segment
		(start 272.79854 -123.967494)
		(end 272.669 -124.097034)
		(width 0.12954)
		(layer "F.Cu")
		(net "SMB_HOST_CLK_BUF_3V3AUX_SCL")
	)
	(segment
		(start 273.425412 -124.734574)
		(end 273.425412 -125.5395)
		(width 0.12954)
		(layer "F.Cu")
		(net "SMB_HOST_CLK_BUF_3V3AUX_SCL")
	)
	(segment
		(start 275.126958 -127.241046)
		(end 275.126958 -129.567432)
		(width 0.12954)
		(layer "F.Cu")
		(net "SMB_HOST_CLK_BUF_3V3AUX_SCL")
	)
	(segment
		(start 273.295872 -124.605034)
		(end 273.425412 -124.734574)
		(width 0.12954)
		(layer "F.Cu")
		(net "SMB_HOST_CLK_BUF_3V3AUX_SCL")
	)
	(segment
		(start 273.455892 -121.180098)
		(end 273.455892 -123.807474)
		(width 0.12954)
		(layer "F.Cu")
		(net "SMB_HOST_CLK_BUF_3V3AUX_SCL")
	)
	(segment
		(start 275.126958 -129.567432)
		(end 274.482814 -130.211576)
		(width 0.12954)
		(layer "F.Cu")
		(net "SMB_HOST_CLK_BUF_3V3AUX_SCL")
	)
	(via
		(at 273.455892 -121.180098)
		(size 0.508)
		(drill 0.254)
		(layers "F.Cu" "B.Cu")
		(net "SMB_HOST_CLK_BUF_3V3AUX_SCL")
	)
	(segment
		(start 239.04829 -127.67183)
		(end 239.04829 -128.911604)
		(width 0.12954)
		(layer "B.Cu")
		(net "SMB_HOST_CLK_BUF_3V3AUX_SCL")
	)
	(segment
		(start 235.7374 -129.306828)
		(end 235.7374 -131.188968)
		(width 0.12954)
		(layer "B.Cu")
		(net "SMB_HOST_CLK_BUF_3V3AUX_SCL")
	)
	(segment
		(start 238.861346 -129.098548)
		(end 235.94568 -129.098548)
		(width 0.12954)
		(layer "B.Cu")
		(net "SMB_HOST_CLK_BUF_3V3AUX_SCL")
	)
	(segment
		(start 273.455892 -121.180098)
		(end 273.455892 -122.3645)
		(width 0.12954)
		(layer "B.Cu")
		(net "SMB_HOST_CLK_BUF_3V3AUX_SCL")
	)
	(segment
		(start 272.542508 -123.277884)
		(end 249.710448 -123.277884)
		(width 0.12954)
		(layer "B.Cu")
		(net "SMB_HOST_CLK_BUF_3V3AUX_SCL")
	)
	(segment
		(start 239.04829 -128.911604)
		(end 238.861346 -129.098548)
		(width 0.12954)
		(layer "B.Cu")
		(net "SMB_HOST_CLK_BUF_3V3AUX_SCL")
	)
	(segment
		(start 235.94568 -129.098548)
		(end 235.7374 -129.306828)
		(width 0.12954)
		(layer "B.Cu")
		(net "SMB_HOST_CLK_BUF_3V3AUX_SCL")
	)
	(segment
		(start 273.455892 -122.3645)
		(end 272.542508 -123.277884)
		(width 0.12954)
		(layer "B.Cu")
		(net "SMB_HOST_CLK_BUF_3V3AUX_SCL")
	)
	(segment
		(start 235.7374 -131.188968)
		(end 235.811822 -131.26339)
		(width 0.12954)
		(layer "B.Cu")
		(net "SMB_HOST_CLK_BUF_3V3AUX_SCL")
	)
	(segment
		(start 249.710448 -123.277884)
		(end 248.364248 -124.624084)
		(width 0.12954)
		(layer "B.Cu")
		(net "SMB_HOST_CLK_BUF_3V3AUX_SCL")
	)
	(segment
		(start 242.096036 -124.624084)
		(end 239.04829 -127.67183)
		(width 0.12954)
		(layer "B.Cu")
		(net "SMB_HOST_CLK_BUF_3V3AUX_SCL")
	)
	(segment
		(start 235.811822 -131.26339)
		(end 235.811822 -131.703064)
		(width 0.12954)
		(layer "B.Cu")
		(net "SMB_HOST_CLK_BUF_3V3AUX_SCL")
	)
	(segment
		(start 248.364248 -124.624084)
		(end 242.096036 -124.624084)
		(width 0.12954)
		(layer "B.Cu")
		(net "SMB_HOST_CLK_BUF_3V3AUX_SCL")
	)
	(segment
		(start 268.21638 -130.909568)
		(end 268.21638 -128.514348)
		(width 0.12954)
		(layer "F.Cu")
		(net "PU_CLK_BUF_ISO_EN")
	)
	(segment
		(start 265.596116 -127.572008)
		(end 265.573002 -127.548894)
		(width 0.12954)
		(layer "F.Cu")
		(net "PU_CLK_BUF_ISO_EN")
	)
	(segment
		(start 266.493244 -131.586732)
		(end 267.539216 -131.586732)
		(width 0.12954)
		(layer "F.Cu")
		(net "PU_CLK_BUF_ISO_EN")
	)
	(segment
		(start 268.21638 -128.514348)
		(end 267.56614 -127.864108)
		(width 0.12954)
		(layer "F.Cu")
		(net "PU_CLK_BUF_ISO_EN")
	)
	(segment
		(start 267.56614 -127.864108)
		(end 267.27404 -127.572008)
		(width 0.12954)
		(layer "F.Cu")
		(net "PU_CLK_BUF_ISO_EN")
	)
	(segment
		(start 267.27404 -127.572008)
		(end 265.596116 -127.572008)
		(width 0.12954)
		(layer "F.Cu")
		(net "PU_CLK_BUF_ISO_EN")
	)
	(segment
		(start 267.539216 -131.586732)
		(end 268.21638 -130.909568)
		(width 0.12954)
		(layer "F.Cu")
		(net "PU_CLK_BUF_ISO_EN")
	)
	(via
		(at 267.56614 -127.864108)
		(size 0.762)
		(drill 0.381)
		(layers "F.Cu" "B.Cu")
		(net "PU_CLK_BUF_ISO_EN")
	)
	(segment
		(start 240.8301 -248.915428)
		(end 240.60785 -248.915428)
		(width 0.12954)
		(layer "F.Cu")
		(net "CLK_GEN2_XTAL_IN_R")
	)
	(segment
		(start 242.86083 -249.173238)
		(end 241.28857 -249.173238)
		(width 0.12954)
		(layer "F.Cu")
		(net "CLK_GEN2_XTAL_IN_R")
	)
	(segment
		(start 239.7125 -249.739658)
		(end 240.53673 -248.915428)
		(width 0.12954)
		(layer "F.Cu")
		(net "CLK_GEN2_XTAL_IN_R")
	)
	(segment
		(start 240.53673 -248.915428)
		(end 240.60785 -248.915428)
		(width 0.12954)
		(layer "F.Cu")
		(net "CLK_GEN2_XTAL_IN_R")
	)
	(segment
		(start 243.72189 -248.312178)
		(end 242.86083 -249.173238)
		(width 0.12954)
		(layer "F.Cu")
		(net "CLK_GEN2_XTAL_IN_R")
	)
	(segment
		(start 241.28857 -249.173238)
		(end 241.18824 -249.273568)
		(width 0.12954)
		(layer "F.Cu")
		(net "CLK_GEN2_XTAL_IN_R")
	)
	(segment
		(start 243.72189 -248.2215)
		(end 243.72189 -248.312178)
		(width 0.12954)
		(layer "F.Cu")
		(net "CLK_GEN2_XTAL_IN_R")
	)
	(segment
		(start 241.18824 -249.273568)
		(end 240.8301 -248.915428)
		(width 0.12954)
		(layer "F.Cu")
		(net "CLK_GEN2_XTAL_IN_R")
	)
	(via
		(at 241.18824 -249.273568)
		(size 0.508)
		(drill 0.254)
		(layers "F.Cu" "B.Cu")
		(net "CLK_GEN2_XTAL_IN_R")
	)
	(via
		(at 107.3531 -419.87216)
		(size 0.6604)
		(drill 0.3302)
		(layers "F.Cu" "B.Cu")
		(net "P3V3_9ZXL045")
	)
	(segment
		(start 112.7252 -409.120848)
		(end 112.54994 -409.120848)
		(width 0.12954)
		(layer "F.Cu")
		(net "TP_CLK_100M_BUF_DIF3_DP")
	)
	(segment
		(start 111.515398 -410.15539)
		(end 111.515398 -411.033468)
		(width 0.12954)
		(layer "F.Cu")
		(net "TP_CLK_100M_BUF_DIF3_DP")
	)
	(segment
		(start 112.54994 -409.120848)
		(end 111.515398 -410.15539)
		(width 0.12954)
		(layer "F.Cu")
		(net "TP_CLK_100M_BUF_DIF3_DP")
	)
	(via
		(at 112.7252 -409.120848)
		(size 0.508)
		(drill 0.254)
		(layers "F.Cu" "B.Cu")
		(net "TP_CLK_100M_BUF_DIF3_DP")
	)
	(segment
		(start 112.015524 -410.080968)
		(end 112.015524 -411.033468)
		(width 0.12954)
		(layer "F.Cu")
		(net "TP_CLK_100M_BUF_DIF3_DN")
	)
	(segment
		(start 112.558576 -409.810458)
		(end 112.546384 -409.82265)
		(width 0.12954)
		(layer "F.Cu")
		(net "TP_CLK_100M_BUF_DIF3_DN")
	)
	(segment
		(start 112.546384 -409.82265)
		(end 112.080802 -410.01569)
		(width 0.12954)
		(layer "F.Cu")
		(net "TP_CLK_100M_BUF_DIF3_DN")
	)
	(segment
		(start 113.08715 -409.810458)
		(end 112.558576 -409.810458)
		(width 0.12954)
		(layer "F.Cu")
		(net "TP_CLK_100M_BUF_DIF3_DN")
	)
	(segment
		(start 112.080802 -410.01569)
		(end 112.015524 -410.080968)
		(width 0.12954)
		(layer "F.Cu")
		(net "TP_CLK_100M_BUF_DIF3_DN")
	)
	(via
		(at 113.08715 -409.810458)
		(size 0.762)
		(drill 0.381)
		(layers "F.Cu" "B.Cu")
		(net "TP_CLK_100M_BUF_DIF3_DN")
	)
	(segment
		(start 118.020084 -415.387028)
		(end 117.79123 -415.158174)
		(width 0.12954)
		(layer "F.Cu")
		(net "SMB_HOST_9ZXL045_3V3AUX_SDA")
	)
	(segment
		(start 119.69115 -415.276538)
		(end 119.58066 -415.387028)
		(width 0.12954)
		(layer "F.Cu")
		(net "SMB_HOST_9ZXL045_3V3AUX_SDA")
	)
	(segment
		(start 115.91544 -415.003488)
		(end 115.070382 -414.15843)
		(width 0.12954)
		(layer "F.Cu")
		(net "SMB_HOST_9ZXL045_3V3AUX_SDA")
	)
	(segment
		(start 116.28882 -415.158174)
		(end 115.91544 -415.003488)
		(width 0.12954)
		(layer "F.Cu")
		(net "SMB_HOST_9ZXL045_3V3AUX_SDA")
	)
	(segment
		(start 119.58066 -415.387028)
		(end 118.020084 -415.387028)
		(width 0.12954)
		(layer "F.Cu")
		(net "SMB_HOST_9ZXL045_3V3AUX_SDA")
	)
	(segment
		(start 116.580412 -415.158174)
		(end 116.28882 -415.158174)
		(width 0.12954)
		(layer "F.Cu")
		(net "SMB_HOST_9ZXL045_3V3AUX_SDA")
	)
	(segment
		(start 115.070382 -414.15843)
		(end 114.64036 -414.15843)
		(width 0.12954)
		(layer "F.Cu")
		(net "SMB_HOST_9ZXL045_3V3AUX_SDA")
	)
	(segment
		(start 117.79123 -415.158174)
		(end 116.580412 -415.158174)
		(width 0.12954)
		(layer "F.Cu")
		(net "SMB_HOST_9ZXL045_3V3AUX_SDA")
	)
	(via
		(at 116.580412 -415.158174)
		(size 0.508)
		(drill 0.254)
		(layers "F.Cu" "B.Cu")
		(net "SMB_HOST_9ZXL045_3V3AUX_SDA")
	)
	(segment
		(start 197.827392 -369.496848)
		(end 217.49258 -369.496848)
		(width 0.12954)
		(layer "F.Cu")
		(net "SMB_HOST_9ZXL045_3V3AUX_SCL")
	)
	(segment
		(start 117.689376 -415.955988)
		(end 121.3104 -415.955988)
		(width 0.12954)
		(layer "F.Cu")
		(net "SMB_HOST_9ZXL045_3V3AUX_SCL")
	)
	(segment
		(start 161.88436 -412.311088)
		(end 168.514268 -412.311088)
		(width 0.12954)
		(layer "F.Cu")
		(net "SMB_HOST_9ZXL045_3V3AUX_SCL")
	)
	(segment
		(start 121.3104 -415.955988)
		(end 121.48566 -415.780728)
		(width 0.12954)
		(layer "F.Cu")
		(net "SMB_HOST_9ZXL045_3V3AUX_SCL")
	)
	(segment
		(start 260.69798 -127.904748)
		(end 261.03707 -127.565658)
		(width 0.12954)
		(layer "F.Cu")
		(net "SMB_HOST_9ZXL045_3V3AUX_SCL")
	)
	(segment
		(start 251.62764 -194.89674)
		(end 254.448818 -192.075562)
		(width 0.12954)
		(layer "F.Cu")
		(net "SMB_HOST_9ZXL045_3V3AUX_SCL")
	)
	(segment
		(start 225.090736 -361.898692)
		(end 225.090736 -331.156564)
		(width 0.12954)
		(layer "F.Cu")
		(net "SMB_HOST_9ZXL045_3V3AUX_SCL")
	)
	(segment
		(start 255.009142 -192.075562)
		(end 255.999742 -191.084962)
		(width 0.12954)
		(layer "F.Cu")
		(net "SMB_HOST_9ZXL045_3V3AUX_SCL")
	)
	(segment
		(start 170.56608 -396.75816)
		(end 197.827392 -369.496848)
		(width 0.12954)
		(layer "F.Cu")
		(net "SMB_HOST_9ZXL045_3V3AUX_SCL")
	)
	(segment
		(start 117.689376 -415.955988)
		(end 117.05844 -415.955988)
		(width 0.12954)
		(layer "F.Cu")
		(net "SMB_HOST_9ZXL045_3V3AUX_SCL")
	)
	(segment
		(start 261.03707 -127.565658)
		(end 262.450072 -127.565658)
		(width 0.12954)
		(layer "F.Cu")
		(net "SMB_HOST_9ZXL045_3V3AUX_SCL")
	)
	(segment
		(start 117.05844 -415.955988)
		(end 115.558062 -415.33445)
		(width 0.12954)
		(layer "F.Cu")
		(net "SMB_HOST_9ZXL045_3V3AUX_SCL")
	)
	(segment
		(start 251.62764 -304.61966)
		(end 251.62764 -194.89674)
		(width 0.12954)
		(layer "F.Cu")
		(net "SMB_HOST_9ZXL045_3V3AUX_SCL")
	)
	(segment
		(start 254.448818 -192.075562)
		(end 255.009142 -192.075562)
		(width 0.12954)
		(layer "F.Cu")
		(net "SMB_HOST_9ZXL045_3V3AUX_SCL")
	)
	(segment
		(start 121.48566 -415.780728)
		(end 158.41472 -415.780728)
		(width 0.12954)
		(layer "F.Cu")
		(net "SMB_HOST_9ZXL045_3V3AUX_SCL")
	)
	(segment
		(start 158.41472 -415.780728)
		(end 161.88436 -412.311088)
		(width 0.12954)
		(layer "F.Cu")
		(net "SMB_HOST_9ZXL045_3V3AUX_SCL")
	)
	(segment
		(start 217.49258 -369.496848)
		(end 225.090736 -361.898692)
		(width 0.12954)
		(layer "F.Cu")
		(net "SMB_HOST_9ZXL045_3V3AUX_SCL")
	)
	(segment
		(start 115.558062 -415.33445)
		(end 114.881914 -414.658302)
		(width 0.12954)
		(layer "F.Cu")
		(net "SMB_HOST_9ZXL045_3V3AUX_SCL")
	)
	(segment
		(start 168.514268 -412.311088)
		(end 170.56608 -410.259276)
		(width 0.12954)
		(layer "F.Cu")
		(net "SMB_HOST_9ZXL045_3V3AUX_SCL")
	)
	(segment
		(start 255.999742 -191.084962)
		(end 255.999742 -190.201804)
		(width 0.12954)
		(layer "F.Cu")
		(net "SMB_HOST_9ZXL045_3V3AUX_SCL")
	)
	(segment
		(start 114.881914 -414.658302)
		(end 114.64036 -414.658302)
		(width 0.12954)
		(layer "F.Cu")
		(net "SMB_HOST_9ZXL045_3V3AUX_SCL")
	)
	(segment
		(start 225.090736 -331.156564)
		(end 251.62764 -304.61966)
		(width 0.12954)
		(layer "F.Cu")
		(net "SMB_HOST_9ZXL045_3V3AUX_SCL")
	)
	(segment
		(start 170.56608 -410.259276)
		(end 170.56608 -396.75816)
		(width 0.12954)
		(layer "F.Cu")
		(net "SMB_HOST_9ZXL045_3V3AUX_SCL")
	)
	(via
		(at 117.689376 -415.955988)
		(size 0.508)
		(drill 0.254)
		(layers "F.Cu" "B.Cu")
		(net "SMB_HOST_9ZXL045_3V3AUX_SCL")
	)
	(via
		(at 260.69798 -127.904748)
		(size 0.508)
		(drill 0.254)
		(layers "F.Cu" "B.Cu")
		(net "SMB_HOST_9ZXL045_3V3AUX_SCL")
	)
	(via
		(at 255.999742 -190.201804)
		(size 0.508)
		(drill 0.254)
		(layers "F.Cu" "B.Cu")
		(net "SMB_HOST_9ZXL045_3V3AUX_SCL")
	)
	(segment
		(start 253.111508 -136.964674)
		(end 252.984508 -137.091674)
		(width 0.127)
		(layer "In2.Cu")
		(net "SMB_HOST_9ZXL045_3V3AUX_SCL")
	)
	(segment
		(start 260.531864 -128.070864)
		(end 259.62991 -128.070864)
		(width 0.127)
		(layer "In2.Cu")
		(net "SMB_HOST_9ZXL045_3V3AUX_SCL")
	)
	(segment
		(start 253.873 -134.424674)
		(end 253.111508 -134.424674)
		(width 0.127)
		(layer "In2.Cu")
		(net "SMB_HOST_9ZXL045_3V3AUX_SCL")
	)
	(segment
		(start 254 -135.186674)
		(end 254 -135.567674)
		(width 0.127)
		(layer "In2.Cu")
		(net "SMB_HOST_9ZXL045_3V3AUX_SCL")
	)
	(segment
		(start 257.52933 -125.970284)
		(end 255.095248 -125.970284)
		(width 0.127)
		(layer "In2.Cu")
		(net "SMB_HOST_9ZXL045_3V3AUX_SCL")
	)
	(segment
		(start 253.111508 -133.789674)
		(end 253.873 -133.789674)
		(width 0.127)
		(layer "In2.Cu")
		(net "SMB_HOST_9ZXL045_3V3AUX_SCL")
	)
	(segment
		(start 260.69798 -127.904748)
		(end 260.531864 -128.070864)
		(width 0.127)
		(layer "In2.Cu")
		(net "SMB_HOST_9ZXL045_3V3AUX_SCL")
	)
	(segment
		(start 254 -136.456674)
		(end 254 -136.837674)
		(width 0.127)
		(layer "In2.Cu")
		(net "SMB_HOST_9ZXL045_3V3AUX_SCL")
	)
	(segment
		(start 252.984508 -134.932674)
		(end 253.111508 -135.059674)
		(width 0.127)
		(layer "In2.Cu")
		(net "SMB_HOST_9ZXL045_3V3AUX_SCL")
	)
	(segment
		(start 252.984508 -135.821674)
		(end 252.984508 -136.202674)
		(width 0.127)
		(layer "In2.Cu")
		(net "SMB_HOST_9ZXL045_3V3AUX_SCL")
	)
	(segment
		(start 253.873 -136.964674)
		(end 253.111508 -136.964674)
		(width 0.127)
		(layer "In2.Cu")
		(net "SMB_HOST_9ZXL045_3V3AUX_SCL")
	)
	(segment
		(start 252.984508 -137.091674)
		(end 252.984508 -152.076404)
		(width 0.127)
		(layer "In2.Cu")
		(net "SMB_HOST_9ZXL045_3V3AUX_SCL")
	)
	(segment
		(start 253.873 -136.329674)
		(end 254 -136.456674)
		(width 0.127)
		(layer "In2.Cu")
		(net "SMB_HOST_9ZXL045_3V3AUX_SCL")
	)
	(segment
		(start 255.095248 -125.970284)
		(end 252.984508 -128.081024)
		(width 0.127)
		(layer "In2.Cu")
		(net "SMB_HOST_9ZXL045_3V3AUX_SCL")
	)
	(segment
		(start 254 -134.297674)
		(end 253.873 -134.424674)
		(width 0.127)
		(layer "In2.Cu")
		(net "SMB_HOST_9ZXL045_3V3AUX_SCL")
	)
	(segment
		(start 253.111508 -135.694674)
		(end 252.984508 -135.821674)
		(width 0.127)
		(layer "In2.Cu")
		(net "SMB_HOST_9ZXL045_3V3AUX_SCL")
	)
	(segment
		(start 253.873 -135.694674)
		(end 253.111508 -135.694674)
		(width 0.127)
		(layer "In2.Cu")
		(net "SMB_HOST_9ZXL045_3V3AUX_SCL")
	)
	(segment
		(start 253.873 -135.059674)
		(end 254 -135.186674)
		(width 0.127)
		(layer "In2.Cu")
		(net "SMB_HOST_9ZXL045_3V3AUX_SCL")
	)
	(segment
		(start 259.62991 -128.070864)
		(end 257.52933 -125.970284)
		(width 0.127)
		(layer "In2.Cu")
		(net "SMB_HOST_9ZXL045_3V3AUX_SCL")
	)
	(segment
		(start 254 -136.837674)
		(end 253.873 -136.964674)
		(width 0.127)
		(layer "In2.Cu")
		(net "SMB_HOST_9ZXL045_3V3AUX_SCL")
	)
	(segment
		(start 252.984508 -128.081024)
		(end 252.984508 -133.662674)
		(width 0.127)
		(layer "In2.Cu")
		(net "SMB_HOST_9ZXL045_3V3AUX_SCL")
	)
	(segment
		(start 254 -133.916674)
		(end 254 -134.297674)
		(width 0.127)
		(layer "In2.Cu")
		(net "SMB_HOST_9ZXL045_3V3AUX_SCL")
	)
	(segment
		(start 252.984508 -134.551674)
		(end 252.984508 -134.932674)
		(width 0.127)
		(layer "In2.Cu")
		(net "SMB_HOST_9ZXL045_3V3AUX_SCL")
	)
	(segment
		(start 253.111508 -134.424674)
		(end 252.984508 -134.551674)
		(width 0.127)
		(layer "In2.Cu")
		(net "SMB_HOST_9ZXL045_3V3AUX_SCL")
	)
	(segment
		(start 253.111508 -136.329674)
		(end 253.873 -136.329674)
		(width 0.127)
		(layer "In2.Cu")
		(net "SMB_HOST_9ZXL045_3V3AUX_SCL")
	)
	(segment
		(start 253.111508 -135.059674)
		(end 253.873 -135.059674)
		(width 0.127)
		(layer "In2.Cu")
		(net "SMB_HOST_9ZXL045_3V3AUX_SCL")
	)
	(segment
		(start 252.984508 -152.076404)
		(end 255.999742 -155.091638)
		(width 0.127)
		(layer "In2.Cu")
		(net "SMB_HOST_9ZXL045_3V3AUX_SCL")
	)
	(segment
		(start 252.984508 -136.202674)
		(end 253.111508 -136.329674)
		(width 0.127)
		(layer "In2.Cu")
		(net "SMB_HOST_9ZXL045_3V3AUX_SCL")
	)
	(segment
		(start 253.873 -133.789674)
		(end 254 -133.916674)
		(width 0.127)
		(layer "In2.Cu")
		(net "SMB_HOST_9ZXL045_3V3AUX_SCL")
	)
	(segment
		(start 255.999742 -155.091638)
		(end 255.999742 -190.201804)
		(width 0.127)
		(layer "In2.Cu")
		(net "SMB_HOST_9ZXL045_3V3AUX_SCL")
	)
	(segment
		(start 252.984508 -133.662674)
		(end 253.111508 -133.789674)
		(width 0.127)
		(layer "In2.Cu")
		(net "SMB_HOST_9ZXL045_3V3AUX_SCL")
	)
	(segment
		(start 254 -135.567674)
		(end 253.873 -135.694674)
		(width 0.127)
		(layer "In2.Cu")
		(net "SMB_HOST_9ZXL045_3V3AUX_SCL")
	)
	(segment
		(start 115.512596 -412.158434)
		(end 114.64036 -412.158434)
		(width 0.2032)
		(layer "F.Cu")
		(net "P3V3_9ZXL045_VDDR")
	)
	(segment
		(start 115.742974 -412.112968)
		(end 115.558062 -412.112968)
		(width 0.2032)
		(layer "F.Cu")
		(net "P3V3_9ZXL045_VDDR")
	)
	(segment
		(start 115.558062 -412.112968)
		(end 115.512596 -412.158434)
		(width 0.2032)
		(layer "F.Cu")
		(net "P3V3_9ZXL045_VDDR")
	)
	(via
		(at 115.742974 -412.112968)
		(size 0.508)
		(drill 0.254)
		(layers "F.Cu" "B.Cu")
		(net "P3V3_9ZXL045_VDDR")
	)
	(via
		(at 110.617 -418.328348)
		(size 0.6604)
		(drill 0.3302)
		(layers "F.Cu" "B.Cu")
		(net "P3V3_9ZXL045_VDDR")
	)
	(segment
		(start 113.515394 -410.380434)
		(end 113.515394 -411.033468)
		(width 0.2032)
		(layer "F.Cu")
		(net "P3V3_9ZXL045_VDDA")
	)
	(segment
		(start 113.837974 -410.057854)
		(end 113.515394 -410.380434)
		(width 0.2032)
		(layer "F.Cu")
		(net "P3V3_9ZXL045_VDDA")
	)
	(via
		(at 113.837974 -410.057854)
		(size 0.508)
		(drill 0.254)
		(layers "F.Cu" "B.Cu")
		(net "P3V3_9ZXL045_VDDA")
	)
	(via
		(at 108.388912 -415.66973)
		(size 0.762)
		(drill 0.254)
		(layers "F.Cu" "B.Cu")
		(net "P3V3_9ZXL045_VDDA")
	)
	(segment
		(start 113.07445 -410.821378)
		(end 113.07445 -411.170628)
		(width 0.381)
		(layer "B.Cu")
		(net "P3V3_9ZXL045_VDDA")
	)
	(segment
		(start 113.07445 -411.170628)
		(end 112.9284 -411.316678)
		(width 0.381)
		(layer "B.Cu")
		(net "P3V3_9ZXL045_VDDA")
	)
	(segment
		(start 113.837974 -410.057854)
		(end 113.07445 -410.821378)
		(width 0.381)
		(layer "B.Cu")
		(net "P3V3_9ZXL045_VDDA")
	)
	(segment
		(start 113.01476 -416.83178)
		(end 112.515396 -416.332416)
		(width 0.2032)
		(layer "F.Cu")
		(net "P3V3_9ZXL045_VDD")
	)
	(segment
		(start 109.855 -409.910788)
		(end 110.5154 -410.571188)
		(width 0.2032)
		(layer "F.Cu")
		(net "P3V3_9ZXL045_VDD")
	)
	(segment
		(start 113.01476 -417.027868)
		(end 113.01476 -416.83178)
		(width 0.2032)
		(layer "F.Cu")
		(net "P3V3_9ZXL045_VDD")
	)
	(segment
		(start 112.515396 -411.033468)
		(end 112.515396 -410.36621)
		(width 0.2032)
		(layer "F.Cu")
		(net "P3V3_9ZXL045_VDD")
	)
	(segment
		(start 110.5154 -416.085528)
		(end 110.5154 -415.783268)
		(width 0.2032)
		(layer "F.Cu")
		(net "P3V3_9ZXL045_VDD")
	)
	(segment
		(start 110.5154 -410.571188)
		(end 110.5154 -411.033468)
		(width 0.2032)
		(layer "F.Cu")
		(net "P3V3_9ZXL045_VDD")
	)
	(segment
		(start 109.89056 -413.158432)
		(end 109.22381 -413.158432)
		(width 0.2032)
		(layer "F.Cu")
		(net "P3V3_9ZXL045_VDD")
	)
	(segment
		(start 110.15218 -416.448748)
		(end 110.5154 -416.085528)
		(width 0.2032)
		(layer "F.Cu")
		(net "P3V3_9ZXL045_VDD")
	)
	(segment
		(start 112.515396 -416.332416)
		(end 112.515396 -415.783268)
		(width 0.2032)
		(layer "F.Cu")
		(net "P3V3_9ZXL045_VDD")
	)
	(via
		(at 109.855 -409.910788)
		(size 0.508)
		(drill 0.254)
		(layers "F.Cu" "B.Cu")
		(net "P3V3_9ZXL045_VDD")
	)
	(via
		(at 109.22381 -413.158432)
		(size 0.508)
		(drill 0.254)
		(layers "F.Cu" "B.Cu")
		(net "P3V3_9ZXL045_VDD")
	)
	(via
		(at 112.515396 -410.36621)
		(size 0.508)
		(drill 0.254)
		(layers "F.Cu" "B.Cu")
		(net "P3V3_9ZXL045_VDD")
	)
	(via
		(at 113.01476 -417.027868)
		(size 0.508)
		(drill 0.254)
		(layers "F.Cu" "B.Cu")
		(net "P3V3_9ZXL045_VDD")
	)
	(via
		(at 110.15218 -416.448748)
		(size 0.508)
		(drill 0.254)
		(layers "F.Cu" "B.Cu")
		(net "P3V3_9ZXL045_VDD")
	)
	(segment
		(start 76.89088 -10.076942)
		(end 76.89088 -9.698228)
		(width 0.12954)
		(layer "F.Cu")
		(net "OCP_V3_2_MAIN_PWR_EN_R")
	)
	(segment
		(start 77.461872 -10.647934)
		(end 76.89088 -10.076942)
		(width 0.12954)
		(layer "F.Cu")
		(net "OCP_V3_2_MAIN_PWR_EN_R")
	)
	(segment
		(start 77.461872 -11.26998)
		(end 77.461872 -10.647934)
		(width 0.12954)
		(layer "F.Cu")
		(net "OCP_V3_2_MAIN_PWR_EN_R")
	)
	(via
		(at 76.89088 -9.698228)
		(size 0.508)
		(drill 0.254)
		(layers "F.Cu" "B.Cu")
		(net "OCP_V3_2_MAIN_PWR_EN_R")
	)
	(segment
		(start 76.89088 -10.867898)
		(end 76.89088 -9.698228)
		(width 0.12954)
		(layer "B.Cu")
		(net "OCP_V3_2_MAIN_PWR_EN_R")
	)
	(segment
		(start 451.961758 -11.26998)
		(end 451.961758 -12.867132)
		(width 0.12954)
		(layer "F.Cu")
		(net "OCP_SFF_MAIN_PWR_EN_R")
	)
	(segment
		(start 451.961758 -12.867132)
		(end 451.970394 -12.875768)
		(width 0.12954)
		(layer "F.Cu")
		(net "OCP_SFF_MAIN_PWR_EN_R")
	)
	(via
		(at 451.970394 -12.875768)
		(size 0.508)
		(drill 0.254)
		(layers "F.Cu" "B.Cu")
		(net "OCP_SFF_MAIN_PWR_EN_R")
	)
	(segment
		(start 451.970394 -12.875768)
		(end 453.892666 -12.875768)
		(width 0.12954)
		(layer "B.Cu")
		(net "OCP_SFF_MAIN_PWR_EN_R")
	)
	(segment
		(start 453.892666 -12.875768)
		(end 454.077324 -12.69111)
		(width 0.12954)
		(layer "B.Cu")
		(net "OCP_SFF_MAIN_PWR_EN_R")
	)
	(segment
		(start 169.13098 -110.221268)
		(end 169.18432 -110.167928)
		(width 0.12954)
		(layer "F.Cu")
		(net "OCP_SFF_CLK_OE_R_N")
	)
	(segment
		(start 169.18432 -110.167928)
		(end 171.35348 -110.167928)
		(width 0.12954)
		(layer "F.Cu")
		(net "OCP_SFF_CLK_OE_R_N")
	)
	(segment
		(start 171.35348 -110.167928)
		(end 171.755562 -110.57001)
		(width 0.12954)
		(layer "F.Cu")
		(net "OCP_SFF_CLK_OE_R_N")
	)
	(segment
		(start 171.755562 -110.57001)
		(end 171.755562 -110.575344)
		(width 0.12954)
		(layer "F.Cu")
		(net "OCP_SFF_CLK_OE_R_N")
	)
	(via
		(at 175.870108 -99.3775)
		(size 0.508)
		(drill 0.254)
		(layers "F.Cu" "B.Cu")
		(net "OCP_SFF_CLK_OE_R_N")
	)
	(via
		(at 169.13098 -110.221268)
		(size 0.508)
		(drill 0.254)
		(layers "F.Cu" "B.Cu")
		(net "OCP_SFF_CLK_OE_R_N")
	)
	(via
		(at 203.289408 -103.730806)
		(size 0.508)
		(drill 0.254)
		(layers "F.Cu" "B.Cu")
		(net "OCP_SFF_CLK_OE_R_N")
	)
	(via
		(at 218.71432 -116.774468)
		(size 0.508)
		(drill 0.254)
		(layers "F.Cu" "B.Cu")
		(net "OCP_SFF_CLK_OE_R_N")
	)
	(segment
		(start 193.977768 -99.3775)
		(end 194.07886 -99.276408)
		(width 0.12954)
		(layer "B.Cu")
		(net "OCP_SFF_CLK_OE_R_N")
	)
	(segment
		(start 194.07886 -99.276408)
		(end 198.49084 -99.276408)
		(width 0.12954)
		(layer "B.Cu")
		(net "OCP_SFF_CLK_OE_R_N")
	)
	(segment
		(start 218.71432 -116.774468)
		(end 219.722954 -115.765834)
		(width 0.12954)
		(layer "B.Cu")
		(net "OCP_SFF_CLK_OE_R_N")
	)
	(segment
		(start 199.26046 -101.503988)
		(end 201.487278 -103.730806)
		(width 0.12954)
		(layer "B.Cu")
		(net "OCP_SFF_CLK_OE_R_N")
	)
	(segment
		(start 229.33025 -116.367814)
		(end 229.33025 -117.560598)
		(width 0.12954)
		(layer "B.Cu")
		(net "OCP_SFF_CLK_OE_R_N")
	)
	(segment
		(start 175.870108 -99.3775)
		(end 193.977768 -99.3775)
		(width 0.12954)
		(layer "B.Cu")
		(net "OCP_SFF_CLK_OE_R_N")
	)
	(segment
		(start 228.72827 -115.765834)
		(end 229.33025 -116.367814)
		(width 0.12954)
		(layer "B.Cu")
		(net "OCP_SFF_CLK_OE_R_N")
	)
	(segment
		(start 201.487278 -103.730806)
		(end 203.289408 -103.730806)
		(width 0.12954)
		(layer "B.Cu")
		(net "OCP_SFF_CLK_OE_R_N")
	)
	(segment
		(start 198.49084 -99.276408)
		(end 199.26046 -100.046028)
		(width 0.12954)
		(layer "B.Cu")
		(net "OCP_SFF_CLK_OE_R_N")
	)
	(segment
		(start 219.722954 -115.765834)
		(end 228.72827 -115.765834)
		(width 0.12954)
		(layer "B.Cu")
		(net "OCP_SFF_CLK_OE_R_N")
	)
	(segment
		(start 199.26046 -100.046028)
		(end 199.26046 -101.503988)
		(width 0.12954)
		(layer "B.Cu")
		(net "OCP_SFF_CLK_OE_R_N")
	)
	(segment
		(start 212.29066 -110.46714)
		(end 211.33054 -110.46714)
		(width 0.127)
		(layer "In4.Cu")
		(net "OCP_SFF_CLK_OE_R_N")
	)
	(segment
		(start 205.53045 -105.971848)
		(end 203.289408 -103.730806)
		(width 0.127)
		(layer "In4.Cu")
		(net "OCP_SFF_CLK_OE_R_N")
	)
	(segment
		(start 211.33054 -110.46714)
		(end 206.835248 -105.971848)
		(width 0.127)
		(layer "In4.Cu")
		(net "OCP_SFF_CLK_OE_R_N")
	)
	(segment
		(start 218.597988 -116.774468)
		(end 212.29066 -110.46714)
		(width 0.127)
		(layer "In4.Cu")
		(net "OCP_SFF_CLK_OE_R_N")
	)
	(segment
		(start 206.835248 -105.971848)
		(end 205.53045 -105.971848)
		(width 0.127)
		(layer "In4.Cu")
		(net "OCP_SFF_CLK_OE_R_N")
	)
	(segment
		(start 218.71432 -116.774468)
		(end 218.597988 -116.774468)
		(width 0.127)
		(layer "In4.Cu")
		(net "OCP_SFF_CLK_OE_R_N")
	)
	(segment
		(start 175.290734 -99.956874)
		(end 173.030134 -99.956874)
		(width 0.127)
		(layer "In11.Cu")
		(net "OCP_SFF_CLK_OE_R_N")
	)
	(segment
		(start 172.339 -100.648008)
		(end 170.37558 -100.648008)
		(width 0.127)
		(layer "In11.Cu")
		(net "OCP_SFF_CLK_OE_R_N")
	)
	(segment
		(start 173.030134 -99.956874)
		(end 172.339 -100.648008)
		(width 0.127)
		(layer "In11.Cu")
		(net "OCP_SFF_CLK_OE_R_N")
	)
	(segment
		(start 170.37558 -100.648008)
		(end 169.13098 -101.892608)
		(width 0.127)
		(layer "In11.Cu")
		(net "OCP_SFF_CLK_OE_R_N")
	)
	(segment
		(start 169.13098 -101.892608)
		(end 169.13098 -110.221268)
		(width 0.127)
		(layer "In11.Cu")
		(net "OCP_SFF_CLK_OE_R_N")
	)
	(segment
		(start 175.870108 -99.3775)
		(end 175.290734 -99.956874)
		(width 0.127)
		(layer "In11.Cu")
		(net "OCP_SFF_CLK_OE_R_N")
	)
	(via
		(at 228.358446 -127.455168)
		(size 0.6604)
		(drill 0.3302)
		(layers "F.Cu" "B.Cu")
		(net "OCP_SFF_CLK_OE_N")
	)
	(segment
		(start 229.001828 -127.085852)
		(end 228.727762 -127.085852)
		(width 0.12954)
		(layer "B.Cu")
		(net "OCP_SFF_CLK_OE_N")
	)
	(segment
		(start 229.49027 -127.029718)
		(end 229.057962 -127.029718)
		(width 0.12954)
		(layer "B.Cu")
		(net "OCP_SFF_CLK_OE_N")
	)
	(segment
		(start 226.746308 -128.275588)
		(end 224.7646 -126.29388)
		(width 0.12954)
		(layer "B.Cu")
		(net "OCP_SFF_CLK_OE_N")
	)
	(segment
		(start 229.49027 -127.029718)
		(end 229.944168 -126.57582)
		(width 0.12954)
		(layer "B.Cu")
		(net "OCP_SFF_CLK_OE_N")
	)
	(segment
		(start 230.48468 -118.360698)
		(end 229.33025 -118.360698)
		(width 0.12954)
		(layer "B.Cu")
		(net "OCP_SFF_CLK_OE_N")
	)
	(segment
		(start 230.639112 -126.44882)
		(end 230.639112 -125.626368)
		(width 0.12954)
		(layer "B.Cu")
		(net "OCP_SFF_CLK_OE_N")
	)
	(segment
		(start 228.358446 -127.485902)
		(end 227.56876 -128.275588)
		(width 0.12954)
		(layer "B.Cu")
		(net "OCP_SFF_CLK_OE_N")
	)
	(segment
		(start 228.727762 -127.085852)
		(end 228.358446 -127.455168)
		(width 0.12954)
		(layer "B.Cu")
		(net "OCP_SFF_CLK_OE_N")
	)
	(segment
		(start 230.512112 -126.57582)
		(end 230.639112 -126.44882)
		(width 0.12954)
		(layer "B.Cu")
		(net "OCP_SFF_CLK_OE_N")
	)
	(segment
		(start 224.7646 -122.686064)
		(end 228.114098 -119.336566)
		(width 0.12954)
		(layer "B.Cu")
		(net "OCP_SFF_CLK_OE_N")
	)
	(segment
		(start 229.944168 -126.57582)
		(end 230.512112 -126.57582)
		(width 0.12954)
		(layer "B.Cu")
		(net "OCP_SFF_CLK_OE_N")
	)
	(segment
		(start 231.52608 -118.360698)
		(end 230.48468 -118.360698)
		(width 0.12954)
		(layer "B.Cu")
		(net "OCP_SFF_CLK_OE_N")
	)
	(segment
		(start 228.114098 -119.336566)
		(end 228.114098 -118.360698)
		(width 0.12954)
		(layer "B.Cu")
		(net "OCP_SFF_CLK_OE_N")
	)
	(segment
		(start 229.33025 -118.360698)
		(end 228.114098 -118.360698)
		(width 0.12954)
		(layer "B.Cu")
		(net "OCP_SFF_CLK_OE_N")
	)
	(segment
		(start 224.7646 -126.29388)
		(end 224.7646 -122.686064)
		(width 0.12954)
		(layer "B.Cu")
		(net "OCP_SFF_CLK_OE_N")
	)
	(segment
		(start 230.639112 -125.626368)
		(end 230.888286 -125.377194)
		(width 0.12954)
		(layer "B.Cu")
		(net "OCP_SFF_CLK_OE_N")
	)
	(segment
		(start 227.56876 -128.275588)
		(end 226.746308 -128.275588)
		(width 0.12954)
		(layer "B.Cu")
		(net "OCP_SFF_CLK_OE_N")
	)
	(segment
		(start 228.358446 -127.455168)
		(end 228.358446 -127.485902)
		(width 0.12954)
		(layer "B.Cu")
		(net "OCP_SFF_CLK_OE_N")
	)
	(segment
		(start 229.057962 -127.029718)
		(end 229.001828 -127.085852)
		(width 0.12954)
		(layer "B.Cu")
		(net "OCP_SFF_CLK_OE_N")
	)
	(segment
		(start 213.98738 -103.38308)
		(end 212.694012 -103.38308)
		(width 0.12954)
		(layer "F.Cu")
		(net "NC_U205_OUTB")
	)
	(segment
		(start 212.694012 -103.38308)
		(end 212.42782 -103.116888)
		(width 0.12954)
		(layer "F.Cu")
		(net "NC_U205_OUTB")
	)
	(via
		(at 212.42782 -103.116888)
		(size 0.762)
		(drill 0.381)
		(layers "F.Cu" "B.Cu")
		(net "NC_U205_OUTB")
	)
	(segment
		(start 213.98738 -105.283)
		(end 212.687408 -105.283)
		(width 0.12954)
		(layer "F.Cu")
		(net "NC_U205_INB-")
	)
	(segment
		(start 212.687408 -105.283)
		(end 212.41766 -105.552748)
		(width 0.12954)
		(layer "F.Cu")
		(net "NC_U205_INB-")
	)
	(via
		(at 212.41766 -105.552748)
		(size 0.762)
		(drill 0.381)
		(layers "F.Cu" "B.Cu")
		(net "NC_U205_INB-")
	)
	(segment
		(start 260.03377 -99.81311)
		(end 260.270244 -99.576636)
		(width 0.0889)
		(layer "F.Cu")
		(net "NC_CLK_CK440_MXCK8_DP")
	)
	(segment
		(start 262.018272 -100.027486)
		(end 263.1059 -100.027486)
		(width 0.12954)
		(layer "F.Cu")
		(net "NC_CLK_CK440_MXCK8_DP")
	)
	(segment
		(start 259.557774 -99.81311)
		(end 260.03377 -99.81311)
		(width 0.0889)
		(layer "F.Cu")
		(net "NC_CLK_CK440_MXCK8_DP")
	)
	(segment
		(start 263.1059 -100.027486)
		(end 263.311386 -99.822)
		(width 0.12954)
		(layer "F.Cu")
		(net "NC_CLK_CK440_MXCK8_DP")
	)
	(segment
		(start 261.62127 -100.027486)
		(end 262.018272 -100.027486)
		(width 0.0889)
		(layer "F.Cu")
		(net "NC_CLK_CK440_MXCK8_DP")
	)
	(segment
		(start 261.17042 -99.576636)
		(end 261.62127 -100.027486)
		(width 0.0889)
		(layer "F.Cu")
		(net "NC_CLK_CK440_MXCK8_DP")
	)
	(segment
		(start 260.270244 -99.576636)
		(end 261.17042 -99.576636)
		(width 0.0889)
		(layer "F.Cu")
		(net "NC_CLK_CK440_MXCK8_DP")
	)
	(via
		(at 263.311386 -99.822)
		(size 0.762)
		(drill 0.381)
		(layers "F.Cu" "B.Cu")
		(net "NC_CLK_CK440_MXCK8_DP")
	)
	(segment
		(start 259.557774 -99.313238)
		(end 261.314946 -99.313238)
		(width 0.0889)
		(layer "F.Cu")
		(net "NC_CLK_CK440_MXCK8_DN")
	)
	(segment
		(start 261.608062 -99.606354)
		(end 262.114284 -99.606354)
		(width 0.0889)
		(layer "F.Cu")
		(net "NC_CLK_CK440_MXCK8_DN")
	)
	(segment
		(start 262.257032 -99.606354)
		(end 263.311386 -98.552)
		(width 0.12954)
		(layer "F.Cu")
		(net "NC_CLK_CK440_MXCK8_DN")
	)
	(segment
		(start 262.114284 -99.606354)
		(end 262.257032 -99.606354)
		(width 0.12954)
		(layer "F.Cu")
		(net "NC_CLK_CK440_MXCK8_DN")
	)
	(segment
		(start 261.314946 -99.313238)
		(end 261.608062 -99.606354)
		(width 0.0889)
		(layer "F.Cu")
		(net "NC_CLK_CK440_MXCK8_DN")
	)
	(via
		(at 263.311386 -98.552)
		(size 0.762)
		(drill 0.381)
		(layers "F.Cu" "B.Cu")
		(net "NC_CLK_CK440_MXCK8_DN")
	)
	(segment
		(start 261.89305 -100.847906)
		(end 262.05307 -100.847906)
		(width 0.0889)
		(layer "F.Cu")
		(net "NC_CLK_CK440_MXCK7_DP")
	)
	(segment
		(start 263.214612 -100.847906)
		(end 263.65073 -101.284024)
		(width 0.12954)
		(layer "F.Cu")
		(net "NC_CLK_CK440_MXCK7_DP")
	)
	(segment
		(start 263.65073 -101.284024)
		(end 264.147808 -101.284024)
		(width 0.12954)
		(layer "F.Cu")
		(net "NC_CLK_CK440_MXCK7_DP")
	)
	(segment
		(start 259.918962 -100.813108)
		(end 260.101588 -100.995734)
		(width 0.0889)
		(layer "F.Cu")
		(net "NC_CLK_CK440_MXCK7_DP")
	)
	(segment
		(start 262.05307 -100.847906)
		(end 263.214612 -100.847906)
		(width 0.12954)
		(layer "F.Cu")
		(net "NC_CLK_CK440_MXCK7_DP")
	)
	(segment
		(start 261.745222 -100.995734)
		(end 261.89305 -100.847906)
		(width 0.0889)
		(layer "F.Cu")
		(net "NC_CLK_CK440_MXCK7_DP")
	)
	(segment
		(start 259.557774 -100.813108)
		(end 259.918962 -100.813108)
		(width 0.0889)
		(layer "F.Cu")
		(net "NC_CLK_CK440_MXCK7_DP")
	)
	(segment
		(start 260.101588 -100.995734)
		(end 261.745222 -100.995734)
		(width 0.0889)
		(layer "F.Cu")
		(net "NC_CLK_CK440_MXCK7_DP")
	)
	(via
		(at 264.147808 -101.284024)
		(size 0.762)
		(drill 0.381)
		(layers "F.Cu" "B.Cu")
		(net "NC_CLK_CK440_MXCK7_DP")
	)
	(segment
		(start 261.422896 -100.742496)
		(end 261.67715 -100.488242)
		(width 0.0889)
		(layer "F.Cu")
		(net "NC_CLK_CK440_MXCK7_DN")
	)
	(segment
		(start 260.437376 -100.742496)
		(end 261.422896 -100.742496)
		(width 0.0889)
		(layer "F.Cu")
		(net "NC_CLK_CK440_MXCK7_DN")
	)
	(segment
		(start 259.557774 -100.313236)
		(end 260.008116 -100.313236)
		(width 0.0889)
		(layer "F.Cu")
		(net "NC_CLK_CK440_MXCK7_DN")
	)
	(segment
		(start 261.67715 -100.488242)
		(end 262.012938 -100.488242)
		(width 0.0889)
		(layer "F.Cu")
		(net "NC_CLK_CK440_MXCK7_DN")
	)
	(segment
		(start 263.41705 -100.488242)
		(end 263.574022 -100.645214)
		(width 0.12954)
		(layer "F.Cu")
		(net "NC_CLK_CK440_MXCK7_DN")
	)
	(segment
		(start 265.020044 -101.284024)
		(end 265.417808 -101.284024)
		(width 0.12954)
		(layer "F.Cu")
		(net "NC_CLK_CK440_MXCK7_DN")
	)
	(segment
		(start 262.012938 -100.488242)
		(end 263.41705 -100.488242)
		(width 0.12954)
		(layer "F.Cu")
		(net "NC_CLK_CK440_MXCK7_DN")
	)
	(segment
		(start 260.008116 -100.313236)
		(end 260.437376 -100.742496)
		(width 0.0889)
		(layer "F.Cu")
		(net "NC_CLK_CK440_MXCK7_DN")
	)
	(segment
		(start 263.574022 -100.645214)
		(end 264.381234 -100.645214)
		(width 0.12954)
		(layer "F.Cu")
		(net "NC_CLK_CK440_MXCK7_DN")
	)
	(segment
		(start 264.381234 -100.645214)
		(end 265.020044 -101.284024)
		(width 0.12954)
		(layer "F.Cu")
		(net "NC_CLK_CK440_MXCK7_DN")
	)
	(via
		(at 265.417808 -101.284024)
		(size 0.762)
		(drill 0.381)
		(layers "F.Cu" "B.Cu")
		(net "NC_CLK_CK440_MXCK7_DN")
	)
	(segment
		(start 260.943852 -103.164132)
		(end 262.46582 -104.6861)
		(width 0.12954)
		(layer "F.Cu")
		(net "NC_CLK_CK440_MXCK5_DP")
	)
	(segment
		(start 259.79755 -102.813104)
		(end 260.148578 -103.164132)
		(width 0.12954)
		(layer "F.Cu")
		(net "NC_CLK_CK440_MXCK5_DP")
	)
	(segment
		(start 259.557774 -102.813104)
		(end 259.79755 -102.813104)
		(width 0.12954)
		(layer "F.Cu")
		(net "NC_CLK_CK440_MXCK5_DP")
	)
	(segment
		(start 260.148578 -103.164132)
		(end 260.943852 -103.164132)
		(width 0.12954)
		(layer "F.Cu")
		(net "NC_CLK_CK440_MXCK5_DP")
	)
	(segment
		(start 262.46582 -104.6861)
		(end 262.46582 -105.077768)
		(width 0.12954)
		(layer "F.Cu")
		(net "NC_CLK_CK440_MXCK5_DP")
	)
	(via
		(at 262.46582 -105.077768)
		(size 0.762)
		(drill 0.381)
		(layers "F.Cu" "B.Cu")
		(net "NC_CLK_CK440_MXCK5_DP")
	)
	(segment
		(start 259.796534 -102.313232)
		(end 260.348984 -102.865682)
		(width 0.12954)
		(layer "F.Cu")
		(net "NC_CLK_CK440_MXCK5_DN")
	)
	(segment
		(start 260.348984 -102.865682)
		(end 261.306056 -102.865682)
		(width 0.12954)
		(layer "F.Cu")
		(net "NC_CLK_CK440_MXCK5_DN")
	)
	(segment
		(start 261.306056 -102.865682)
		(end 263.518142 -105.077768)
		(width 0.12954)
		(layer "F.Cu")
		(net "NC_CLK_CK440_MXCK5_DN")
	)
	(segment
		(start 263.518142 -105.077768)
		(end 263.73582 -105.077768)
		(width 0.12954)
		(layer "F.Cu")
		(net "NC_CLK_CK440_MXCK5_DN")
	)
	(segment
		(start 259.557774 -102.313232)
		(end 259.796534 -102.313232)
		(width 0.12954)
		(layer "F.Cu")
		(net "NC_CLK_CK440_MXCK5_DN")
	)
	(via
		(at 263.73582 -105.077768)
		(size 0.762)
		(drill 0.381)
		(layers "F.Cu" "B.Cu")
		(net "NC_CLK_CK440_MXCK5_DN")
	)
	(segment
		(start 258.432808 -103.438198)
		(end 258.432808 -103.782368)
		(width 0.12954)
		(layer "F.Cu")
		(net "NC_CLK_CK440_MXCK4_DP")
	)
	(segment
		(start 258.432808 -103.782368)
		(end 258.721352 -104.070912)
		(width 0.12954)
		(layer "F.Cu")
		(net "NC_CLK_CK440_MXCK4_DP")
	)
	(segment
		(start 259.942838 -104.070912)
		(end 260.62051 -104.748584)
		(width 0.12954)
		(layer "F.Cu")
		(net "NC_CLK_CK440_MXCK4_DP")
	)
	(segment
		(start 260.62051 -104.748584)
		(end 260.62051 -106.425746)
		(width 0.12954)
		(layer "F.Cu")
		(net "NC_CLK_CK440_MXCK4_DP")
	)
	(segment
		(start 258.721352 -104.070912)
		(end 259.942838 -104.070912)
		(width 0.12954)
		(layer "F.Cu")
		(net "NC_CLK_CK440_MXCK4_DP")
	)
	(via
		(at 260.62051 -106.425746)
		(size 0.762)
		(drill 0.381)
		(layers "F.Cu" "B.Cu")
		(net "NC_CLK_CK440_MXCK4_DP")
	)
	(segment
		(start 258.93268 -103.438198)
		(end 258.93268 -103.643176)
		(width 0.12954)
		(layer "F.Cu")
		(net "NC_CLK_CK440_MXCK4_DN")
	)
	(segment
		(start 259.06222 -103.772716)
		(end 260.342888 -103.772716)
		(width 0.12954)
		(layer "F.Cu")
		(net "NC_CLK_CK440_MXCK4_DN")
	)
	(segment
		(start 261.19582 -104.625648)
		(end 261.19582 -105.077768)
		(width 0.12954)
		(layer "F.Cu")
		(net "NC_CLK_CK440_MXCK4_DN")
	)
	(segment
		(start 258.93268 -103.643176)
		(end 259.06222 -103.772716)
		(width 0.12954)
		(layer "F.Cu")
		(net "NC_CLK_CK440_MXCK4_DN")
	)
	(segment
		(start 260.342888 -103.772716)
		(end 261.19582 -104.625648)
		(width 0.12954)
		(layer "F.Cu")
		(net "NC_CLK_CK440_MXCK4_DN")
	)
	(via
		(at 261.19582 -105.077768)
		(size 0.762)
		(drill 0.381)
		(layers "F.Cu" "B.Cu")
		(net "NC_CLK_CK440_MXCK4_DN")
	)
	(segment
		(start 114.99342 -411.658308)
		(end 115.27282 -411.378908)
		(width 0.12954)
		(layer "F.Cu")
		(net "FM_9ZXL045_DEV_EN")
	)
	(segment
		(start 115.27282 -411.378908)
		(end 117.02034 -411.378908)
		(width 0.12954)
		(layer "F.Cu")
		(net "FM_9ZXL045_DEV_EN")
	)
	(segment
		(start 117.90934 -412.267908)
		(end 117.90934 -412.637478)
		(width 0.12954)
		(layer "F.Cu")
		(net "FM_9ZXL045_DEV_EN")
	)
	(segment
		(start 117.02034 -411.378908)
		(end 117.90934 -412.267908)
		(width 0.12954)
		(layer "F.Cu")
		(net "FM_9ZXL045_DEV_EN")
	)
	(segment
		(start 117.90934 -412.637478)
		(end 118.46179 -413.189928)
		(width 0.12954)
		(layer "F.Cu")
		(net "FM_9ZXL045_DEV_EN")
	)
	(segment
		(start 114.64036 -411.658308)
		(end 114.99342 -411.658308)
		(width 0.12954)
		(layer "F.Cu")
		(net "FM_9ZXL045_DEV_EN")
	)
	(via
		(at 117.02034 -411.378908)
		(size 0.762)
		(drill 0.381)
		(layers "F.Cu" "B.Cu")
		(net "FM_9ZXL045_DEV_EN")
	)
	(segment
		(start 112.18926 -408.628088)
		(end 113.500916 -408.628088)
		(width 0.12954)
		(layer "F.Cu")
		(net "FM_9ZXL045_3_OE_N")
	)
	(segment
		(start 111.02594 -409.791408)
		(end 111.442246 -409.375102)
		(width 0.12954)
		(layer "F.Cu")
		(net "FM_9ZXL045_3_OE_N")
	)
	(segment
		(start 111.015526 -411.033468)
		(end 111.02594 -411.023054)
		(width 0.12954)
		(layer "F.Cu")
		(net "FM_9ZXL045_3_OE_N")
	)
	(segment
		(start 111.442246 -409.375102)
		(end 112.18926 -408.628088)
		(width 0.12954)
		(layer "F.Cu")
		(net "FM_9ZXL045_3_OE_N")
	)
	(segment
		(start 113.500916 -408.628088)
		(end 114.30127 -409.428442)
		(width 0.12954)
		(layer "F.Cu")
		(net "FM_9ZXL045_3_OE_N")
	)
	(segment
		(start 111.02594 -411.023054)
		(end 111.02594 -409.791408)
		(width 0.12954)
		(layer "F.Cu")
		(net "FM_9ZXL045_3_OE_N")
	)
	(via
		(at 111.442246 -409.375102)
		(size 0.762)
		(drill 0.381)
		(layers "F.Cu" "B.Cu")
		(net "FM_9ZXL045_3_OE_N")
	)
	(segment
		(start 108.33354 -411.579568)
		(end 107.12069 -411.579568)
		(width 0.12954)
		(layer "F.Cu")
		(net "FM_9ZXL045_2_OE_N")
	)
	(segment
		(start 107.12069 -411.579568)
		(end 107.11815 -411.582108)
		(width 0.12954)
		(layer "F.Cu")
		(net "FM_9ZXL045_2_OE_N")
	)
	(segment
		(start 108.59262 -411.320488)
		(end 108.33354 -411.579568)
		(width 0.12954)
		(layer "F.Cu")
		(net "FM_9ZXL045_2_OE_N")
	)
	(segment
		(start 109.89056 -411.658308)
		(end 109.61878 -411.658308)
		(width 0.12954)
		(layer "F.Cu")
		(net "FM_9ZXL045_2_OE_N")
	)
	(segment
		(start 109.28096 -411.320488)
		(end 108.59262 -411.320488)
		(width 0.12954)
		(layer "F.Cu")
		(net "FM_9ZXL045_2_OE_N")
	)
	(segment
		(start 109.61878 -411.658308)
		(end 109.28096 -411.320488)
		(width 0.12954)
		(layer "F.Cu")
		(net "FM_9ZXL045_2_OE_N")
	)
	(via
		(at 108.33354 -411.579568)
		(size 0.762)
		(drill 0.381)
		(layers "F.Cu" "B.Cu")
		(net "FM_9ZXL045_2_OE_N")
	)
	(segment
		(start 108.449872 -418.090604)
		(end 108.449872 -416.576256)
		(width 0.12954)
		(layer "F.Cu")
		(net "FM_9ZXL045_1_OE_N")
	)
	(segment
		(start 107.988608 -418.090604)
		(end 108.449872 -418.090604)
		(width 0.12954)
		(layer "F.Cu")
		(net "FM_9ZXL045_1_OE_N")
	)
	(segment
		(start 109.31144 -415.018728)
		(end 109.671866 -414.658302)
		(width 0.12954)
		(layer "F.Cu")
		(net "FM_9ZXL045_1_OE_N")
	)
	(segment
		(start 109.671866 -414.658302)
		(end 109.89056 -414.658302)
		(width 0.12954)
		(layer "F.Cu")
		(net "FM_9ZXL045_1_OE_N")
	)
	(segment
		(start 107.26039 -417.362386)
		(end 107.988608 -418.090604)
		(width 0.12954)
		(layer "F.Cu")
		(net "FM_9ZXL045_1_OE_N")
	)
	(segment
		(start 109.31144 -415.714688)
		(end 109.31144 -415.018728)
		(width 0.12954)
		(layer "F.Cu")
		(net "FM_9ZXL045_1_OE_N")
	)
	(segment
		(start 108.449872 -416.576256)
		(end 109.31144 -415.714688)
		(width 0.12954)
		(layer "F.Cu")
		(net "FM_9ZXL045_1_OE_N")
	)
	(via
		(at 108.449872 -418.090604)
		(size 0.762)
		(drill 0.381)
		(layers "F.Cu" "B.Cu")
		(net "FM_9ZXL045_1_OE_N")
	)
	(segment
		(start 109.44098 -419.002718)
		(end 109.987334 -418.456364)
		(width 0.12954)
		(layer "F.Cu")
		(net "FM_9ZXL045_0_OE_N")
	)
	(segment
		(start 107.26547 -418.392864)
		(end 107.875324 -419.002718)
		(width 0.12954)
		(layer "F.Cu")
		(net "FM_9ZXL045_0_OE_N")
	)
	(segment
		(start 109.987334 -418.456364)
		(end 110.52937 -417.914328)
		(width 0.12954)
		(layer "F.Cu")
		(net "FM_9ZXL045_0_OE_N")
	)
	(segment
		(start 107.875324 -419.002718)
		(end 109.44098 -419.002718)
		(width 0.12954)
		(layer "F.Cu")
		(net "FM_9ZXL045_0_OE_N")
	)
	(segment
		(start 110.52937 -417.914328)
		(end 110.52937 -416.828478)
		(width 0.12954)
		(layer "F.Cu")
		(net "FM_9ZXL045_0_OE_N")
	)
	(segment
		(start 111.015526 -416.342322)
		(end 111.015526 -415.783268)
		(width 0.12954)
		(layer "F.Cu")
		(net "FM_9ZXL045_0_OE_N")
	)
	(segment
		(start 110.52937 -416.828478)
		(end 111.015526 -416.342322)
		(width 0.12954)
		(layer "F.Cu")
		(net "FM_9ZXL045_0_OE_N")
	)
	(via
		(at 109.987334 -418.456364)
		(size 0.762)
		(drill 0.381)
		(layers "F.Cu" "B.Cu")
		(net "FM_9ZXL045_0_OE_N")
	)
	(segment
		(start 119.70639 -414.384998)
		(end 120.07088 -414.749488)
		(width 0.12954)
		(layer "F.Cu")
		(net "CLK_9ZXL045_SADR0")
	)
	(segment
		(start 115.210336 -413.658304)
		(end 116.1923 -414.640268)
		(width 0.12954)
		(layer "F.Cu")
		(net "CLK_9ZXL045_SADR0")
	)
	(segment
		(start 119.70639 -414.274762)
		(end 119.70639 -414.384998)
		(width 0.12954)
		(layer "F.Cu")
		(net "CLK_9ZXL045_SADR0")
	)
	(segment
		(start 119.340884 -414.640268)
		(end 119.70639 -414.274762)
		(width 0.12954)
		(layer "F.Cu")
		(net "CLK_9ZXL045_SADR0")
	)
	(segment
		(start 118.237 -414.640268)
		(end 119.340884 -414.640268)
		(width 0.12954)
		(layer "F.Cu")
		(net "CLK_9ZXL045_SADR0")
	)
	(segment
		(start 116.1923 -414.640268)
		(end 118.237 -414.640268)
		(width 0.12954)
		(layer "F.Cu")
		(net "CLK_9ZXL045_SADR0")
	)
	(segment
		(start 120.07088 -414.749488)
		(end 122.743214 -414.749488)
		(width 0.12954)
		(layer "F.Cu")
		(net "CLK_9ZXL045_SADR0")
	)
	(segment
		(start 122.743214 -414.749488)
		(end 123.20905 -414.283652)
		(width 0.12954)
		(layer "F.Cu")
		(net "CLK_9ZXL045_SADR0")
	)
	(segment
		(start 114.64036 -413.658304)
		(end 115.210336 -413.658304)
		(width 0.12954)
		(layer "F.Cu")
		(net "CLK_9ZXL045_SADR0")
	)
	(via
		(at 118.237 -414.640268)
		(size 0.762)
		(drill 0.381)
		(layers "F.Cu" "B.Cu")
		(net "CLK_9ZXL045_SADR0")
	)
	(segment
		(start 114.36096 -410.690568)
		(end 114.01806 -411.033468)
		(width 0.12954)
		(layer "F.Cu")
		(net "CLK_9ZXL045_HIBW")
	)
	(segment
		(start 117.411754 -410.103828)
		(end 116.8146 -410.103828)
		(width 0.12954)
		(layer "F.Cu")
		(net "CLK_9ZXL045_HIBW")
	)
	(segment
		(start 118.43893 -411.131004)
		(end 117.411754 -410.103828)
		(width 0.12954)
		(layer "F.Cu")
		(net "CLK_9ZXL045_HIBW")
	)
	(segment
		(start 118.43893 -411.131004)
		(end 118.43893 -412.17469)
		(width 0.12954)
		(layer "F.Cu")
		(net "CLK_9ZXL045_HIBW")
	)
	(segment
		(start 114.01806 -411.033468)
		(end 114.01552 -411.033468)
		(width 0.12954)
		(layer "F.Cu")
		(net "CLK_9ZXL045_HIBW")
	)
	(segment
		(start 116.22786 -410.690568)
		(end 114.36096 -410.690568)
		(width 0.12954)
		(layer "F.Cu")
		(net "CLK_9ZXL045_HIBW")
	)
	(segment
		(start 116.8146 -410.103828)
		(end 116.22786 -410.690568)
		(width 0.12954)
		(layer "F.Cu")
		(net "CLK_9ZXL045_HIBW")
	)
	(via
		(at 116.8146 -410.103828)
		(size 0.762)
		(drill 0.381)
		(layers "F.Cu" "B.Cu")
		(net "CLK_9ZXL045_HIBW")
	)
	(segment
		(start 115.24742 -412.778702)
		(end 115.717066 -413.248348)
		(width 0.13208)
		(layer "F.Cu")
		(net "CLK_100M_GPU_SWB_REF_DP")
	)
	(segment
		(start 115.717066 -413.248348)
		(end 116.76888 -413.248348)
		(width 0.13208)
		(layer "F.Cu")
		(net "CLK_100M_GPU_SWB_REF_DP")
	)
	(segment
		(start 232.130092 -127.899922)
		(end 232.247948 -128.017778)
		(width 0.13208)
		(layer "F.Cu")
		(net "CLK_100M_GPU_SWB_REF_DP")
	)
	(segment
		(start 114.64036 -412.658306)
		(end 114.812318 -412.658306)
		(width 0.13208)
		(layer "F.Cu")
		(net "CLK_100M_GPU_SWB_REF_DP")
	)
	(segment
		(start 229.44963 -128.745488)
		(end 231.49687 -127.897382)
		(width 0.13208)
		(layer "F.Cu")
		(net "CLK_100M_GPU_SWB_REF_DP")
	)
	(segment
		(start 231.49687 -127.897382)
		(end 232.126282 -127.897382)
		(width 0.13208)
		(layer "F.Cu")
		(net "CLK_100M_GPU_SWB_REF_DP")
	)
	(segment
		(start 224.2693 -128.745488)
		(end 229.44963 -128.745488)
		(width 0.13208)
		(layer "F.Cu")
		(net "CLK_100M_GPU_SWB_REF_DP")
	)
	(segment
		(start 116.76888 -413.248348)
		(end 117.07114 -412.946088)
		(width 0.13208)
		(layer "F.Cu")
		(net "CLK_100M_GPU_SWB_REF_DP")
	)
	(segment
		(start 232.126282 -127.897382)
		(end 232.128822 -127.899922)
		(width 0.13208)
		(layer "F.Cu")
		(net "CLK_100M_GPU_SWB_REF_DP")
	)
	(segment
		(start 114.812318 -412.658306)
		(end 114.932714 -412.778702)
		(width 0.13208)
		(layer "F.Cu")
		(net "CLK_100M_GPU_SWB_REF_DP")
	)
	(segment
		(start 223.94672 -129.068068)
		(end 224.2693 -128.745488)
		(width 0.13208)
		(layer "F.Cu")
		(net "CLK_100M_GPU_SWB_REF_DP")
	)
	(segment
		(start 114.932714 -412.778702)
		(end 115.24742 -412.778702)
		(width 0.13208)
		(layer "F.Cu")
		(net "CLK_100M_GPU_SWB_REF_DP")
	)
	(segment
		(start 232.128822 -127.899922)
		(end 232.130092 -127.899922)
		(width 0.13208)
		(layer "F.Cu")
		(net "CLK_100M_GPU_SWB_REF_DP")
	)
	(via
		(at 223.94672 -129.068068)
		(size 0.508)
		(drill 0.254)
		(layers "F.Cu" "B.Cu")
		(net "CLK_100M_GPU_SWB_REF_DP")
	)
	(via
		(at 117.07114 -412.946088)
		(size 0.508)
		(drill 0.254)
		(layers "F.Cu" "B.Cu")
		(net "CLK_100M_GPU_SWB_REF_DP")
	)
	(segment
		(start 223.093026 -130.538982)
		(end 223.353376 -130.278632)
		(width 0.14732)
		(layer "In2.Cu")
		(net "CLK_100M_GPU_SWB_REF_DP")
	)
	(segment
		(start 227.7491 -334.237076)
		(end 227.7491 -252.941328)
		(width 0.14732)
		(layer "In2.Cu")
		(net "CLK_100M_GPU_SWB_REF_DP")
	)
	(segment
		(start 126.521972 -417.048188)
		(end 127.316992 -417.048188)
		(width 0.14732)
		(layer "In2.Cu")
		(net "CLK_100M_GPU_SWB_REF_DP")
	)
	(segment
		(start 117.07114 -412.946088)
		(end 117.42928 -413.304228)
		(width 0.14732)
		(layer "In2.Cu")
		(net "CLK_100M_GPU_SWB_REF_DP")
	)
	(segment
		(start 220.92158 -134.441438)
		(end 221.06636 -134.296658)
		(width 0.14732)
		(layer "In2.Cu")
		(net "CLK_100M_GPU_SWB_REF_DP")
	)
	(segment
		(start 224.2185 -129.701544)
		(end 224.471738 -129.448306)
		(width 0.14732)
		(layer "In2.Cu")
		(net "CLK_100M_GPU_SWB_REF_DP")
	)
	(segment
		(start 221.06636 -132.565902)
		(end 221.90202 -131.729988)
		(width 0.14732)
		(layer "In2.Cu")
		(net "CLK_100M_GPU_SWB_REF_DP")
	)
	(segment
		(start 127.964692 -417.048188)
		(end 128.332992 -417.048188)
		(width 0.14732)
		(layer "In2.Cu")
		(net "CLK_100M_GPU_SWB_REF_DP")
	)
	(segment
		(start 128.472692 -416.908488)
		(end 128.840992 -416.908488)
		(width 0.14732)
		(layer "In2.Cu")
		(net "CLK_100M_GPU_SWB_REF_DP")
	)
	(segment
		(start 127.316992 -417.048188)
		(end 127.456692 -416.908488)
		(width 0.14732)
		(layer "In2.Cu")
		(net "CLK_100M_GPU_SWB_REF_DP")
	)
	(segment
		(start 228.70668 -146.688302)
		(end 221.06636 -139.047982)
		(width 0.14732)
		(layer "In2.Cu")
		(net "CLK_100M_GPU_SWB_REF_DP")
	)
	(segment
		(start 127.456692 -416.908488)
		(end 127.824992 -416.908488)
		(width 0.14732)
		(layer "In2.Cu")
		(net "CLK_100M_GPU_SWB_REF_DP")
	)
	(segment
		(start 169.206926 -412.346902)
		(end 171.4119 -410.141928)
		(width 0.14732)
		(layer "In2.Cu")
		(net "CLK_100M_GPU_SWB_REF_DP")
	)
	(segment
		(start 171.4119 -410.141928)
		(end 171.4119 -395.9225)
		(width 0.14732)
		(layer "In2.Cu")
		(net "CLK_100M_GPU_SWB_REF_DP")
	)
	(segment
		(start 227.7491 -252.941328)
		(end 230.52532 -250.165108)
		(width 0.14732)
		(layer "In2.Cu")
		(net "CLK_100M_GPU_SWB_REF_DP")
	)
	(segment
		(start 222.627698 -130.799586)
		(end 222.888302 -130.538982)
		(width 0.14732)
		(layer "In2.Cu")
		(net "CLK_100M_GPU_SWB_REF_DP")
	)
	(segment
		(start 221.06636 -134.954518)
		(end 220.92158 -134.809738)
		(width 0.14732)
		(layer "In2.Cu")
		(net "CLK_100M_GPU_SWB_REF_DP")
	)
	(segment
		(start 221.06636 -133.928358)
		(end 220.92158 -133.783578)
		(width 0.14732)
		(layer "In2.Cu")
		(net "CLK_100M_GPU_SWB_REF_DP")
	)
	(segment
		(start 172.15612 -389.830056)
		(end 227.7491 -334.237076)
		(width 0.14732)
		(layer "In2.Cu")
		(net "CLK_100M_GPU_SWB_REF_DP")
	)
	(segment
		(start 127.824992 -416.908488)
		(end 127.964692 -417.048188)
		(width 0.14732)
		(layer "In2.Cu")
		(net "CLK_100M_GPU_SWB_REF_DP")
	)
	(segment
		(start 224.64776 -129.119122)
		(end 224.64776 -128.951228)
		(width 0.14732)
		(layer "In2.Cu")
		(net "CLK_100M_GPU_SWB_REF_DP")
	)
	(segment
		(start 222.627698 -131.00431)
		(end 222.627698 -130.799586)
		(width 0.14732)
		(layer "In2.Cu")
		(net "CLK_100M_GPU_SWB_REF_DP")
	)
	(segment
		(start 221.06636 -134.296658)
		(end 221.06636 -133.928358)
		(width 0.14732)
		(layer "In2.Cu")
		(net "CLK_100M_GPU_SWB_REF_DP")
	)
	(segment
		(start 222.888302 -130.538982)
		(end 223.093026 -130.538982)
		(width 0.14732)
		(layer "In2.Cu")
		(net "CLK_100M_GPU_SWB_REF_DP")
	)
	(segment
		(start 220.92158 -133.783578)
		(end 220.92158 -133.415278)
		(width 0.14732)
		(layer "In2.Cu")
		(net "CLK_100M_GPU_SWB_REF_DP")
	)
	(segment
		(start 224.46996 -128.773428)
		(end 224.24136 -128.773428)
		(width 0.14732)
		(layer "In2.Cu")
		(net "CLK_100M_GPU_SWB_REF_DP")
	)
	(segment
		(start 172.15612 -395.17828)
		(end 172.15612 -389.830056)
		(width 0.14732)
		(layer "In2.Cu")
		(net "CLK_100M_GPU_SWB_REF_DP")
	)
	(segment
		(start 222.162624 -131.26466)
		(end 222.367348 -131.26466)
		(width 0.14732)
		(layer "In2.Cu")
		(net "CLK_100M_GPU_SWB_REF_DP")
	)
	(segment
		(start 224.24136 -128.773428)
		(end 223.94672 -129.068068)
		(width 0.14732)
		(layer "In2.Cu")
		(net "CLK_100M_GPU_SWB_REF_DP")
	)
	(segment
		(start 221.06636 -139.047982)
		(end 221.06636 -134.954518)
		(width 0.14732)
		(layer "In2.Cu")
		(net "CLK_100M_GPU_SWB_REF_DP")
	)
	(segment
		(start 117.5512 -413.304228)
		(end 119.24284 -414.995868)
		(width 0.14732)
		(layer "In2.Cu")
		(net "CLK_100M_GPU_SWB_REF_DP")
	)
	(segment
		(start 171.4119 -395.9225)
		(end 172.15612 -395.17828)
		(width 0.14732)
		(layer "In2.Cu")
		(net "CLK_100M_GPU_SWB_REF_DP")
	)
	(segment
		(start 128.980692 -417.048188)
		(end 157.85719 -417.048188)
		(width 0.14732)
		(layer "In2.Cu")
		(net "CLK_100M_GPU_SWB_REF_DP")
	)
	(segment
		(start 228.70668 -212.7377)
		(end 228.70668 -146.688302)
		(width 0.14732)
		(layer "In2.Cu")
		(net "CLK_100M_GPU_SWB_REF_DP")
	)
	(segment
		(start 230.52532 -250.165108)
		(end 230.52532 -214.55634)
		(width 0.14732)
		(layer "In2.Cu")
		(net "CLK_100M_GPU_SWB_REF_DP")
	)
	(segment
		(start 221.90202 -131.525264)
		(end 222.162624 -131.26466)
		(width 0.14732)
		(layer "In2.Cu")
		(net "CLK_100M_GPU_SWB_REF_DP")
	)
	(segment
		(start 128.332992 -417.048188)
		(end 128.472692 -416.908488)
		(width 0.14732)
		(layer "In2.Cu")
		(net "CLK_100M_GPU_SWB_REF_DP")
	)
	(segment
		(start 220.92158 -133.415278)
		(end 221.06636 -133.270498)
		(width 0.14732)
		(layer "In2.Cu")
		(net "CLK_100M_GPU_SWB_REF_DP")
	)
	(segment
		(start 222.367348 -131.26466)
		(end 222.627698 -131.00431)
		(width 0.14732)
		(layer "In2.Cu")
		(net "CLK_100M_GPU_SWB_REF_DP")
	)
	(segment
		(start 119.24284 -414.995868)
		(end 124.469652 -414.995868)
		(width 0.14732)
		(layer "In2.Cu")
		(net "CLK_100M_GPU_SWB_REF_DP")
	)
	(segment
		(start 221.06636 -133.270498)
		(end 221.06636 -132.565902)
		(width 0.14732)
		(layer "In2.Cu")
		(net "CLK_100M_GPU_SWB_REF_DP")
	)
	(segment
		(start 221.90202 -131.729988)
		(end 221.90202 -131.525264)
		(width 0.14732)
		(layer "In2.Cu")
		(net "CLK_100M_GPU_SWB_REF_DP")
	)
	(segment
		(start 124.469652 -414.995868)
		(end 126.521972 -417.048188)
		(width 0.14732)
		(layer "In2.Cu")
		(net "CLK_100M_GPU_SWB_REF_DP")
	)
	(segment
		(start 157.85719 -417.048188)
		(end 169.206926 -412.346902)
		(width 0.14732)
		(layer "In2.Cu")
		(net "CLK_100M_GPU_SWB_REF_DP")
	)
	(segment
		(start 224.472246 -129.44729)
		(end 224.64776 -129.119122)
		(width 0.14732)
		(layer "In2.Cu")
		(net "CLK_100M_GPU_SWB_REF_DP")
	)
	(segment
		(start 128.840992 -416.908488)
		(end 128.980692 -417.048188)
		(width 0.14732)
		(layer "In2.Cu")
		(net "CLK_100M_GPU_SWB_REF_DP")
	)
	(segment
		(start 220.92158 -134.809738)
		(end 220.92158 -134.441438)
		(width 0.14732)
		(layer "In2.Cu")
		(net "CLK_100M_GPU_SWB_REF_DP")
	)
	(segment
		(start 224.64776 -128.951228)
		(end 224.46996 -128.773428)
		(width 0.14732)
		(layer "In2.Cu")
		(net "CLK_100M_GPU_SWB_REF_DP")
	)
	(segment
		(start 117.42928 -413.304228)
		(end 117.5512 -413.304228)
		(width 0.14732)
		(layer "In2.Cu")
		(net "CLK_100M_GPU_SWB_REF_DP")
	)
	(segment
		(start 224.471738 -129.448306)
		(end 224.472246 -129.44729)
		(width 0.14732)
		(layer "In2.Cu")
		(net "CLK_100M_GPU_SWB_REF_DP")
	)
	(segment
		(start 223.353376 -130.278632)
		(end 224.2185 -129.701544)
		(width 0.14732)
		(layer "In2.Cu")
		(net "CLK_100M_GPU_SWB_REF_DP")
	)
	(segment
		(start 230.52532 -214.55634)
		(end 228.70668 -212.7377)
		(width 0.14732)
		(layer "In2.Cu")
		(net "CLK_100M_GPU_SWB_REF_DP")
	)
	(segment
		(start 232.127552 -127.638302)
		(end 232.247948 -127.517906)
		(width 0.13208)
		(layer "F.Cu")
		(net "CLK_100M_GPU_SWB_REF_DN")
	)
	(segment
		(start 224.22866 -128.486408)
		(end 229.398068 -128.486408)
		(width 0.13208)
		(layer "F.Cu")
		(net "CLK_100M_GPU_SWB_REF_DN")
	)
	(segment
		(start 114.763296 -413.158432)
		(end 114.64036 -413.158432)
		(width 0.13208)
		(layer "F.Cu")
		(net "CLK_100M_GPU_SWB_REF_DN")
	)
	(segment
		(start 223.94672 -128.204468)
		(end 224.22866 -128.486408)
		(width 0.13208)
		(layer "F.Cu")
		(net "CLK_100M_GPU_SWB_REF_DN")
	)
	(segment
		(start 117.07114 -413.809688)
		(end 116.76888 -413.507428)
		(width 0.13208)
		(layer "F.Cu")
		(net "CLK_100M_GPU_SWB_REF_DN")
	)
	(segment
		(start 116.76888 -413.507428)
		(end 115.609624 -413.507428)
		(width 0.13208)
		(layer "F.Cu")
		(net "CLK_100M_GPU_SWB_REF_DN")
	)
	(segment
		(start 115.609624 -413.507428)
		(end 115.139978 -413.037782)
		(width 0.13208)
		(layer "F.Cu")
		(net "CLK_100M_GPU_SWB_REF_DN")
	)
	(segment
		(start 115.139978 -413.037782)
		(end 114.883946 -413.037782)
		(width 0.13208)
		(layer "F.Cu")
		(net "CLK_100M_GPU_SWB_REF_DN")
	)
	(segment
		(start 114.883946 -413.037782)
		(end 114.763296 -413.158432)
		(width 0.13208)
		(layer "F.Cu")
		(net "CLK_100M_GPU_SWB_REF_DN")
	)
	(segment
		(start 229.398068 -128.486408)
		(end 231.445308 -127.638302)
		(width 0.13208)
		(layer "F.Cu")
		(net "CLK_100M_GPU_SWB_REF_DN")
	)
	(segment
		(start 231.445308 -127.638302)
		(end 232.127552 -127.638302)
		(width 0.13208)
		(layer "F.Cu")
		(net "CLK_100M_GPU_SWB_REF_DN")
	)
	(via
		(at 223.94672 -128.204468)
		(size 0.508)
		(drill 0.254)
		(layers "F.Cu" "B.Cu")
		(net "CLK_100M_GPU_SWB_REF_DN")
	)
	(via
		(at 117.07114 -413.809688)
		(size 0.508)
		(drill 0.254)
		(layers "F.Cu" "B.Cu")
		(net "CLK_100M_GPU_SWB_REF_DN")
	)
	(segment
		(start 117.07114 -413.809688)
		(end 117.30228 -413.578548)
		(width 0.14732)
		(layer "In2.Cu")
		(net "CLK_100M_GPU_SWB_REF_DN")
	)
	(segment
		(start 224.92208 -129.187956)
		(end 224.92208 -128.837436)
		(width 0.14732)
		(layer "In2.Cu")
		(net "CLK_100M_GPU_SWB_REF_DN")
	)
	(segment
		(start 224.92208 -128.837436)
		(end 224.583752 -128.499108)
		(width 0.14732)
		(layer "In2.Cu")
		(net "CLK_100M_GPU_SWB_REF_DN")
	)
	(segment
		(start 221.34068 -138.93419)
		(end 221.34068 -132.679694)
		(width 0.14732)
		(layer "In2.Cu")
		(net "CLK_100M_GPU_SWB_REF_DN")
	)
	(segment
		(start 172.43044 -395.292072)
		(end 172.43044 -389.943848)
		(width 0.14732)
		(layer "In2.Cu")
		(net "CLK_100M_GPU_SWB_REF_DN")
	)
	(segment
		(start 117.437408 -413.578548)
		(end 119.129048 -415.270188)
		(width 0.14732)
		(layer "In2.Cu")
		(net "CLK_100M_GPU_SWB_REF_DN")
	)
	(segment
		(start 223.528382 -130.491992)
		(end 224.393506 -129.914904)
		(width 0.14732)
		(layer "In2.Cu")
		(net "CLK_100M_GPU_SWB_REF_DN")
	)
	(segment
		(start 119.129048 -415.270188)
		(end 124.35586 -415.270188)
		(width 0.14732)
		(layer "In2.Cu")
		(net "CLK_100M_GPU_SWB_REF_DN")
	)
	(segment
		(start 224.583752 -128.499108)
		(end 224.24136 -128.499108)
		(width 0.14732)
		(layer "In2.Cu")
		(net "CLK_100M_GPU_SWB_REF_DN")
	)
	(segment
		(start 228.02342 -334.350868)
		(end 228.02342 -253.05512)
		(width 0.14732)
		(layer "In2.Cu")
		(net "CLK_100M_GPU_SWB_REF_DN")
	)
	(segment
		(start 157.9118 -417.322508)
		(end 169.362374 -412.579566)
		(width 0.14732)
		(layer "In2.Cu")
		(net "CLK_100M_GPU_SWB_REF_DN")
	)
	(segment
		(start 228.02342 -253.05512)
		(end 230.79964 -250.2789)
		(width 0.14732)
		(layer "In2.Cu")
		(net "CLK_100M_GPU_SWB_REF_DN")
	)
	(segment
		(start 172.43044 -389.943848)
		(end 228.02342 -334.350868)
		(width 0.14732)
		(layer "In2.Cu")
		(net "CLK_100M_GPU_SWB_REF_DN")
	)
	(segment
		(start 224.695512 -129.612136)
		(end 224.695258 -129.612644)
		(width 0.14732)
		(layer "In2.Cu")
		(net "CLK_100M_GPU_SWB_REF_DN")
	)
	(segment
		(start 124.35586 -415.270188)
		(end 126.40818 -417.322508)
		(width 0.14732)
		(layer "In2.Cu")
		(net "CLK_100M_GPU_SWB_REF_DN")
	)
	(segment
		(start 224.24136 -128.499108)
		(end 223.94672 -128.204468)
		(width 0.14732)
		(layer "In2.Cu")
		(net "CLK_100M_GPU_SWB_REF_DN")
	)
	(segment
		(start 169.362374 -412.579566)
		(end 171.68622 -410.25572)
		(width 0.14732)
		(layer "In2.Cu")
		(net "CLK_100M_GPU_SWB_REF_DN")
	)
	(segment
		(start 221.34068 -132.679694)
		(end 223.528382 -130.491992)
		(width 0.14732)
		(layer "In2.Cu")
		(net "CLK_100M_GPU_SWB_REF_DN")
	)
	(segment
		(start 171.68622 -410.25572)
		(end 171.68622 -396.036292)
		(width 0.14732)
		(layer "In2.Cu")
		(net "CLK_100M_GPU_SWB_REF_DN")
	)
	(segment
		(start 126.40818 -417.322508)
		(end 157.9118 -417.322508)
		(width 0.14732)
		(layer "In2.Cu")
		(net "CLK_100M_GPU_SWB_REF_DN")
	)
	(segment
		(start 228.981 -146.57451)
		(end 221.34068 -138.93419)
		(width 0.14732)
		(layer "In2.Cu")
		(net "CLK_100M_GPU_SWB_REF_DN")
	)
	(segment
		(start 224.695258 -129.612644)
		(end 224.92208 -129.187956)
		(width 0.14732)
		(layer "In2.Cu")
		(net "CLK_100M_GPU_SWB_REF_DN")
	)
	(segment
		(start 230.79964 -214.442548)
		(end 228.981 -212.623908)
		(width 0.14732)
		(layer "In2.Cu")
		(net "CLK_100M_GPU_SWB_REF_DN")
	)
	(segment
		(start 224.393506 -129.914904)
		(end 224.695512 -129.612136)
		(width 0.14732)
		(layer "In2.Cu")
		(net "CLK_100M_GPU_SWB_REF_DN")
	)
	(segment
		(start 117.30228 -413.578548)
		(end 117.437408 -413.578548)
		(width 0.14732)
		(layer "In2.Cu")
		(net "CLK_100M_GPU_SWB_REF_DN")
	)
	(segment
		(start 171.68622 -396.036292)
		(end 172.43044 -395.292072)
		(width 0.14732)
		(layer "In2.Cu")
		(net "CLK_100M_GPU_SWB_REF_DN")
	)
	(segment
		(start 228.981 -212.623908)
		(end 228.981 -146.57451)
		(width 0.14732)
		(layer "In2.Cu")
		(net "CLK_100M_GPU_SWB_REF_DN")
	)
	(segment
		(start 230.79964 -250.2789)
		(end 230.79964 -214.442548)
		(width 0.14732)
		(layer "In2.Cu")
		(net "CLK_100M_GPU_SWB_REF_DN")
	)
	(segment
		(start 151.75992 -36.807648)
		(end 152.09393 -37.141658)
		(width 0.12954)
		(layer "F.Cu")
		(net "USB_HUB_2_XTAL_OUT")
	)
	(segment
		(start 150.94458 -36.807648)
		(end 151.75992 -36.807648)
		(width 0.12954)
		(layer "F.Cu")
		(net "USB_HUB_2_XTAL_OUT")
	)
	(segment
		(start 152.17648 -37.059108)
		(end 153.040588 -37.059108)
		(width 0.12954)
		(layer "F.Cu")
		(net "USB_HUB_2_XTAL_OUT")
	)
	(segment
		(start 150.697946 -37.054282)
		(end 150.94458 -36.807648)
		(width 0.12954)
		(layer "F.Cu")
		(net "USB_HUB_2_XTAL_OUT")
	)
	(segment
		(start 153.771854 -37.790374)
		(end 154.723084 -37.790374)
		(width 0.12954)
		(layer "F.Cu")
		(net "USB_HUB_2_XTAL_OUT")
	)
	(segment
		(start 152.09393 -37.141658)
		(end 152.17648 -37.059108)
		(width 0.12954)
		(layer "F.Cu")
		(net "USB_HUB_2_XTAL_OUT")
	)
	(segment
		(start 153.166826 -37.185346)
		(end 153.771854 -37.790374)
		(width 0.12954)
		(layer "F.Cu")
		(net "USB_HUB_2_XTAL_OUT")
	)
	(segment
		(start 153.040588 -37.059108)
		(end 153.166826 -37.185346)
		(width 0.12954)
		(layer "F.Cu")
		(net "USB_HUB_2_XTAL_OUT")
	)
	(via
		(at 153.166826 -37.185346)
		(size 0.508)
		(drill 0.254)
		(layers "F.Cu" "B.Cu")
		(net "USB_HUB_2_XTAL_OUT")
	)
	(segment
		(start 151.95296 -38.052248)
		(end 150.00986 -38.052248)
		(width 0.12954)
		(layer "F.Cu")
		(net "USB_HUB_2_XTAL_IN")
	)
	(segment
		(start 152.075896 -38.175184)
		(end 152.26792 -38.367208)
		(width 0.12954)
		(layer "F.Cu")
		(net "USB_HUB_2_XTAL_IN")
	)
	(segment
		(start 152.075896 -38.175184)
		(end 151.95296 -38.052248)
		(width 0.12954)
		(layer "F.Cu")
		(net "USB_HUB_2_XTAL_IN")
	)
	(segment
		(start 153.449782 -38.290246)
		(end 154.723084 -38.290246)
		(width 0.12954)
		(layer "F.Cu")
		(net "USB_HUB_2_XTAL_IN")
	)
	(segment
		(start 153.37282 -38.367208)
		(end 153.449782 -38.290246)
		(width 0.12954)
		(layer "F.Cu")
		(net "USB_HUB_2_XTAL_IN")
	)
	(segment
		(start 150.00986 -38.052248)
		(end 149.397974 -38.664134)
		(width 0.12954)
		(layer "F.Cu")
		(net "USB_HUB_2_XTAL_IN")
	)
	(segment
		(start 149.397974 -38.664134)
		(end 149.397974 -38.75405)
		(width 0.12954)
		(layer "F.Cu")
		(net "USB_HUB_2_XTAL_IN")
	)
	(segment
		(start 152.26792 -38.367208)
		(end 153.05532 -38.367208)
		(width 0.12954)
		(layer "F.Cu")
		(net "USB_HUB_2_XTAL_IN")
	)
	(segment
		(start 153.05532 -38.367208)
		(end 153.37282 -38.367208)
		(width 0.12954)
		(layer "F.Cu")
		(net "USB_HUB_2_XTAL_IN")
	)
	(via
		(at 153.05532 -38.367208)
		(size 0.508)
		(drill 0.254)
		(layers "F.Cu" "B.Cu")
		(net "USB_HUB_2_XTAL_IN")
	)
	(segment
		(start 157.135576 -34.545778)
		(end 156.845 -34.255202)
		(width 0.12954)
		(layer "F.Cu")
		(net "USB_HUB_2_TEST")
	)
	(segment
		(start 156.845 -32.984948)
		(end 157.08884 -32.741108)
		(width 0.12954)
		(layer "F.Cu")
		(net "USB_HUB_2_TEST")
	)
	(segment
		(start 157.135576 -35.377882)
		(end 157.135576 -34.545778)
		(width 0.12954)
		(layer "F.Cu")
		(net "USB_HUB_2_TEST")
	)
	(segment
		(start 156.845 -34.255202)
		(end 156.845 -32.984948)
		(width 0.12954)
		(layer "F.Cu")
		(net "USB_HUB_2_TEST")
	)
	(segment
		(start 157.08884 -32.741108)
		(end 157.08884 -31.741618)
		(width 0.12954)
		(layer "F.Cu")
		(net "USB_HUB_2_TEST")
	)
	(via
		(at 156.845 -32.984948)
		(size 0.762)
		(drill 0.381)
		(layers "F.Cu" "B.Cu")
		(net "USB_HUB_2_TEST")
	)
	(segment
		(start 153.411174 -40.203374)
		(end 153.106628 -40.50792)
		(width 0.12954)
		(layer "F.Cu")
		(net "USB_HUB_2_RREF")
	)
	(segment
		(start 154.32405 -39.290498)
		(end 153.411174 -40.203374)
		(width 0.12954)
		(layer "F.Cu")
		(net "USB_HUB_2_RREF")
	)
	(segment
		(start 154.723084 -39.290498)
		(end 154.32405 -39.290498)
		(width 0.12954)
		(layer "F.Cu")
		(net "USB_HUB_2_RREF")
	)
	(segment
		(start 153.106628 -40.50792)
		(end 152.22982 -40.50792)
		(width 0.12954)
		(layer "F.Cu")
		(net "USB_HUB_2_RREF")
	)
	(via
		(at 153.411174 -40.203374)
		(size 0.762)
		(drill 0.381)
		(layers "F.Cu" "B.Cu")
		(net "USB_HUB_2_RREF")
	)
	(segment
		(start 163.847526 -35.737546)
		(end 161.077402 -35.737546)
		(width 0.12954)
		(layer "F.Cu")
		(net "USB_HUB_2_PSELF")
	)
	(segment
		(start 163.847526 -35.737546)
		(end 163.851844 -35.733228)
		(width 0.12954)
		(layer "F.Cu")
		(net "USB_HUB_2_PSELF")
	)
	(segment
		(start 161.077402 -35.737546)
		(end 160.909 -35.905948)
		(width 0.12954)
		(layer "F.Cu")
		(net "USB_HUB_2_PSELF")
	)
	(segment
		(start 163.851844 -35.733228)
		(end 163.851844 -34.164524)
		(width 0.12954)
		(layer "F.Cu")
		(net "USB_HUB_2_PSELF")
	)
	(segment
		(start 160.524698 -36.29025)
		(end 159.548068 -36.29025)
		(width 0.12954)
		(layer "F.Cu")
		(net "USB_HUB_2_PSELF")
	)
	(segment
		(start 160.909 -35.905948)
		(end 160.524698 -36.29025)
		(width 0.12954)
		(layer "F.Cu")
		(net "USB_HUB_2_PSELF")
	)
	(via
		(at 160.909 -35.905948)
		(size 0.762)
		(drill 0.381)
		(layers "F.Cu" "B.Cu")
		(net "USB_HUB_2_PSELF")
	)
	(segment
		(start 159.548068 -36.790376)
		(end 162.555428 -36.790376)
		(width 0.12954)
		(layer "F.Cu")
		(net "USB_HUB_2_PGANG")
	)
	(segment
		(start 162.555428 -36.790376)
		(end 162.59048 -36.825428)
		(width 0.12954)
		(layer "F.Cu")
		(net "USB_HUB_2_PGANG")
	)
	(segment
		(start 162.59048 -36.825428)
		(end 163.847526 -36.825428)
		(width 0.12954)
		(layer "F.Cu")
		(net "USB_HUB_2_PGANG")
	)
	(via
		(at 162.555428 -36.790376)
		(size 0.762)
		(drill 0.381)
		(layers "F.Cu" "B.Cu")
		(net "USB_HUB_2_PGANG")
	)
	(segment
		(start 157.635448 -35.377882)
		(end 157.635448 -34.000948)
		(width 0.12954)
		(layer "F.Cu")
		(net "USB_HUB_2_OVCUR4")
	)
	(segment
		(start 158.138368 -33.498028)
		(end 158.138368 -31.741618)
		(width 0.12954)
		(layer "F.Cu")
		(net "USB_HUB_2_OVCUR4")
	)
	(segment
		(start 157.635448 -34.000948)
		(end 158.138368 -33.498028)
		(width 0.12954)
		(layer "F.Cu")
		(net "USB_HUB_2_OVCUR4")
	)
	(via
		(at 157.635448 -34.000948)
		(size 0.762)
		(drill 0.381)
		(layers "F.Cu" "B.Cu")
		(net "USB_HUB_2_OVCUR4")
	)
	(segment
		(start 159.181546 -32.984948)
		(end 159.181546 -33.442402)
		(width 0.12954)
		(layer "F.Cu")
		(net "USB_HUB_2_OVCUR3")
	)
	(segment
		(start 158.135574 -34.488374)
		(end 158.135574 -35.377882)
		(width 0.12954)
		(layer "F.Cu")
		(net "USB_HUB_2_OVCUR3")
	)
	(segment
		(start 159.181546 -31.741618)
		(end 159.181546 -32.984948)
		(width 0.12954)
		(layer "F.Cu")
		(net "USB_HUB_2_OVCUR3")
	)
	(segment
		(start 159.181546 -33.442402)
		(end 158.135574 -34.488374)
		(width 0.12954)
		(layer "F.Cu")
		(net "USB_HUB_2_OVCUR3")
	)
	(via
		(at 159.181546 -32.984948)
		(size 0.762)
		(drill 0.381)
		(layers "F.Cu" "B.Cu")
		(net "USB_HUB_2_OVCUR3")
	)
	(segment
		(start 161.419286 -38.067234)
		(end 163.847526 -38.067234)
		(width 0.12954)
		(layer "F.Cu")
		(net "USB_HUB_2_OVCUR2")
	)
	(segment
		(start 160.909 -37.556948)
		(end 161.419286 -38.067234)
		(width 0.12954)
		(layer "F.Cu")
		(net "USB_HUB_2_OVCUR2")
	)
	(segment
		(start 160.642554 -37.290502)
		(end 160.909 -37.556948)
		(width 0.12954)
		(layer "F.Cu")
		(net "USB_HUB_2_OVCUR2")
	)
	(segment
		(start 159.548068 -37.290502)
		(end 160.642554 -37.290502)
		(width 0.12954)
		(layer "F.Cu")
		(net "USB_HUB_2_OVCUR2")
	)
	(via
		(at 160.909 -37.556948)
		(size 0.762)
		(drill 0.381)
		(layers "F.Cu" "B.Cu")
		(net "USB_HUB_2_OVCUR2")
	)
	(segment
		(start 161.679382 -39.20363)
		(end 160.266126 -37.790374)
		(width 0.12954)
		(layer "F.Cu")
		(net "USB_HUB_2_OVCUR1")
	)
	(segment
		(start 163.847526 -39.20363)
		(end 162.56 -39.20363)
		(width 0.12954)
		(layer "F.Cu")
		(net "USB_HUB_2_OVCUR1")
	)
	(segment
		(start 160.266126 -37.790374)
		(end 159.548068 -37.790374)
		(width 0.12954)
		(layer "F.Cu")
		(net "USB_HUB_2_OVCUR1")
	)
	(segment
		(start 162.56 -39.20363)
		(end 161.679382 -39.20363)
		(width 0.12954)
		(layer "F.Cu")
		(net "USB_HUB_2_OVCUR1")
	)
	(via
		(at 162.56 -39.20363)
		(size 0.762)
		(drill 0.381)
		(layers "F.Cu" "B.Cu")
		(net "USB_HUB_2_OVCUR1")
	)
	(segment
		(start 159.258 -34.127948)
		(end 159.893 -34.127948)
		(width 0.12954)
		(layer "F.Cu")
		(net "USB_HUB_2_DVDD")
	)
	(segment
		(start 160.2359 -33.785048)
		(end 160.2359 -31.767272)
		(width 0.12954)
		(layer "F.Cu")
		(net "USB_HUB_2_DVDD")
	)
	(segment
		(start 158.6357 -34.750248)
		(end 159.258 -34.127948)
		(width 0.12954)
		(layer "F.Cu")
		(net "USB_HUB_2_DVDD")
	)
	(segment
		(start 158.6357 -35.377882)
		(end 158.6357 -34.750248)
		(width 0.12954)
		(layer "F.Cu")
		(net "USB_HUB_2_DVDD")
	)
	(segment
		(start 160.2359 -31.767272)
		(end 160.261554 -31.741618)
		(width 0.12954)
		(layer "F.Cu")
		(net "USB_HUB_2_DVDD")
	)
	(segment
		(start 159.893 -34.127948)
		(end 160.2359 -33.785048)
		(width 0.12954)
		(layer "F.Cu")
		(net "USB_HUB_2_DVDD")
	)
	(via
		(at 159.893 -34.127948)
		(size 0.762)
		(drill 0.381)
		(layers "F.Cu" "B.Cu")
		(net "USB_HUB_2_DVDD")
	)
	(segment
		(start 158.901384 -43.250104)
		(end 158.901384 -43.432476)
		(width 0.13208)
		(layer "F.Cu")
		(net "USB2_PCH_0_R_DP")
	)
	(segment
		(start 158.5214 -41.71442)
		(end 158.256224 -41.449244)
		(width 0.13208)
		(layer "F.Cu")
		(net "USB2_PCH_0_R_DP")
	)
	(segment
		(start 159.45612 -42.647616)
		(end 159.45612 -42.695368)
		(width 0.13208)
		(layer "F.Cu")
		(net "USB2_PCH_0_R_DP")
	)
	(segment
		(start 158.521654 -42.24909)
		(end 159.057594 -42.24909)
		(width 0.13208)
		(layer "F.Cu")
		(net "USB2_PCH_0_R_DP")
	)
	(segment
		(start 158.521654 -42.24909)
		(end 158.5214 -41.71442)
		(width 0.13208)
		(layer "F.Cu")
		(net "USB2_PCH_0_R_DP")
	)
	(segment
		(start 158.135574 -40.404796)
		(end 158.135574 -40.202866)
		(width 0.13208)
		(layer "F.Cu")
		(net "USB2_PCH_0_R_DP")
	)
	(segment
		(start 158.256224 -40.525446)
		(end 158.135574 -40.404796)
		(width 0.13208)
		(layer "F.Cu")
		(net "USB2_PCH_0_R_DP")
	)
	(segment
		(start 159.45612 -42.695368)
		(end 158.901384 -43.250104)
		(width 0.13208)
		(layer "F.Cu")
		(net "USB2_PCH_0_R_DP")
	)
	(segment
		(start 158.256224 -41.449244)
		(end 158.256224 -40.525446)
		(width 0.13208)
		(layer "F.Cu")
		(net "USB2_PCH_0_R_DP")
	)
	(segment
		(start 159.057594 -42.24909)
		(end 159.45612 -42.647616)
		(width 0.13208)
		(layer "F.Cu")
		(net "USB2_PCH_0_R_DP")
	)
	(via
		(at 158.521654 -42.24909)
		(size 0.762)
		(drill 0.381)
		(layers "F.Cu" "B.Cu")
		(net "USB2_PCH_0_R_DP")
	)
	(segment
		(start 158.704534 -41.531032)
		(end 158.515304 -41.341802)
		(width 0.13208)
		(layer "F.Cu")
		(net "USB2_PCH_0_R_DN")
	)
	(segment
		(start 159.239966 -41.530524)
		(end 159.239966 -42.066464)
		(width 0.13208)
		(layer "F.Cu")
		(net "USB2_PCH_0_R_DN")
	)
	(segment
		(start 158.704788 -41.531032)
		(end 158.704534 -41.531032)
		(width 0.13208)
		(layer "F.Cu")
		(net "USB2_PCH_0_R_DN")
	)
	(segment
		(start 159.24149 -42.066464)
		(end 159.7152 -42.540174)
		(width 0.13208)
		(layer "F.Cu")
		(net "USB2_PCH_0_R_DN")
	)
	(segment
		(start 158.515304 -41.341802)
		(end 158.515304 -40.557958)
		(width 0.13208)
		(layer "F.Cu")
		(net "USB2_PCH_0_R_DN")
	)
	(segment
		(start 158.705296 -41.530524)
		(end 158.704788 -41.531032)
		(width 0.13208)
		(layer "F.Cu")
		(net "USB2_PCH_0_R_DN")
	)
	(segment
		(start 159.7152 -42.697654)
		(end 160.28035 -43.262804)
		(width 0.13208)
		(layer "F.Cu")
		(net "USB2_PCH_0_R_DN")
	)
	(segment
		(start 160.28035 -43.262804)
		(end 160.28035 -43.432476)
		(width 0.13208)
		(layer "F.Cu")
		(net "USB2_PCH_0_R_DN")
	)
	(segment
		(start 159.7152 -42.540174)
		(end 159.7152 -42.697654)
		(width 0.13208)
		(layer "F.Cu")
		(net "USB2_PCH_0_R_DN")
	)
	(segment
		(start 158.6357 -40.437562)
		(end 158.6357 -40.202866)
		(width 0.13208)
		(layer "F.Cu")
		(net "USB2_PCH_0_R_DN")
	)
	(segment
		(start 159.239966 -41.530524)
		(end 158.705296 -41.530524)
		(width 0.13208)
		(layer "F.Cu")
		(net "USB2_PCH_0_R_DN")
	)
	(segment
		(start 159.239966 -42.066464)
		(end 159.24149 -42.066464)
		(width 0.13208)
		(layer "F.Cu")
		(net "USB2_PCH_0_R_DN")
	)
	(segment
		(start 158.515304 -40.557958)
		(end 158.6357 -40.437562)
		(width 0.13208)
		(layer "F.Cu")
		(net "USB2_PCH_0_R_DN")
	)
	(via
		(at 159.239966 -41.530524)
		(size 0.762)
		(drill 0.381)
		(layers "F.Cu" "B.Cu")
		(net "USB2_PCH_0_R_DN")
	)
	(segment
		(start 157.255972 -40.943276)
		(end 157.255972 -40.574214)
		(width 0.13208)
		(layer "F.Cu")
		(net "USB2_HUB_2_EXT_DP")
	)
	(segment
		(start 156.2481 -42.53865)
		(end 156.247846 -42.538396)
		(width 0.13208)
		(layer "F.Cu")
		(net "USB2_HUB_2_EXT_DP")
	)
	(segment
		(start 155.634944 -44.2468)
		(end 156.248608 -43.633136)
		(width 0.13208)
		(layer "F.Cu")
		(net "USB2_HUB_2_EXT_DP")
	)
	(segment
		(start 156.247846 -42.538396)
		(end 156.247846 -41.951402)
		(width 0.13208)
		(layer "F.Cu")
		(net "USB2_HUB_2_EXT_DP")
	)
	(segment
		(start 156.248608 -43.633136)
		(end 156.248608 -43.296332)
		(width 0.13208)
		(layer "F.Cu")
		(net "USB2_HUB_2_EXT_DP")
	)
	(segment
		(start 155.86964 -42.917364)
		(end 156.2481 -42.53865)
		(width 0.13208)
		(layer "F.Cu")
		(net "USB2_HUB_2_EXT_DP")
	)
	(segment
		(start 157.135576 -40.453818)
		(end 157.135576 -40.202866)
		(width 0.13208)
		(layer "F.Cu")
		(net "USB2_HUB_2_EXT_DP")
	)
	(segment
		(start 156.247846 -41.951402)
		(end 157.255972 -40.943276)
		(width 0.13208)
		(layer "F.Cu")
		(net "USB2_HUB_2_EXT_DP")
	)
	(segment
		(start 156.248608 -43.296332)
		(end 155.86964 -42.917364)
		(width 0.13208)
		(layer "F.Cu")
		(net "USB2_HUB_2_EXT_DP")
	)
	(segment
		(start 157.255972 -40.574214)
		(end 157.135576 -40.453818)
		(width 0.13208)
		(layer "F.Cu")
		(net "USB2_HUB_2_EXT_DP")
	)
	(via
		(at 155.86964 -42.917364)
		(size 0.762)
		(drill 0.381)
		(layers "F.Cu" "B.Cu")
		(net "USB2_HUB_2_EXT_DP")
	)
	(segment
		(start 156.506672 -43.296078)
		(end 156.88564 -42.91711)
		(width 0.13208)
		(layer "F.Cu")
		(net "USB2_HUB_2_EXT_DN")
	)
	(segment
		(start 157.061408 -44.204128)
		(end 156.506672 -43.649392)
		(width 0.13208)
		(layer "F.Cu")
		(net "USB2_HUB_2_EXT_DN")
	)
	(segment
		(start 156.506926 -42.53865)
		(end 156.506926 -42.058844)
		(width 0.13208)
		(layer "F.Cu")
		(net "USB2_HUB_2_EXT_DN")
	)
	(segment
		(start 156.506926 -42.058844)
		(end 157.515052 -41.050718)
		(width 0.13208)
		(layer "F.Cu")
		(net "USB2_HUB_2_EXT_DN")
	)
	(segment
		(start 157.635448 -40.467026)
		(end 157.635448 -40.202866)
		(width 0.13208)
		(layer "F.Cu")
		(net "USB2_HUB_2_EXT_DN")
	)
	(segment
		(start 157.061408 -44.262548)
		(end 157.061408 -44.204128)
		(width 0.13208)
		(layer "F.Cu")
		(net "USB2_HUB_2_EXT_DN")
	)
	(segment
		(start 156.506672 -43.649392)
		(end 156.506672 -43.296078)
		(width 0.13208)
		(layer "F.Cu")
		(net "USB2_HUB_2_EXT_DN")
	)
	(segment
		(start 156.88564 -42.91711)
		(end 156.506926 -42.53865)
		(width 0.13208)
		(layer "F.Cu")
		(net "USB2_HUB_2_EXT_DN")
	)
	(segment
		(start 157.515052 -40.587422)
		(end 157.635448 -40.467026)
		(width 0.13208)
		(layer "F.Cu")
		(net "USB2_HUB_2_EXT_DN")
	)
	(segment
		(start 157.515052 -41.050718)
		(end 157.515052 -40.587422)
		(width 0.13208)
		(layer "F.Cu")
		(net "USB2_HUB_2_EXT_DN")
	)
	(via
		(at 156.88564 -42.91711)
		(size 0.762)
		(drill 0.381)
		(layers "F.Cu" "B.Cu")
		(net "USB2_HUB_2_EXT_DN")
	)
	(segment
		(start 155.634944 -45.0469)
		(end 155.711144 -45.1231)
		(width 0.13208)
		(layer "F.Cu")
		(net "USB2_HUB_2_BUF_EXT_R_DP")
	)
	(segment
		(start 156.048456 -45.1231)
		(end 156.355288 -44.816268)
		(width 0.13208)
		(layer "F.Cu")
		(net "USB2_HUB_2_BUF_EXT_R_DP")
	)
	(segment
		(start 155.711144 -45.1231)
		(end 156.048456 -45.1231)
		(width 0.13208)
		(layer "F.Cu")
		(net "USB2_HUB_2_BUF_EXT_R_DP")
	)
	(via
		(at 156.355288 -44.816268)
		(size 0.508)
		(drill 0.254)
		(layers "F.Cu" "B.Cu")
		(net "USB2_HUB_2_BUF_EXT_R_DP")
	)
	(via
		(at 139.431268 -24.846534)
		(size 0.6604)
		(drill 0.3302)
		(layers "F.Cu" "B.Cu")
		(net "USB2_HUB_2_BUF_EXT_R_DP")
	)
	(segment
		(start 152.5143 -35.661092)
		(end 152.5143 -39.949374)
		(width 0.13208)
		(layer "B.Cu")
		(net "USB2_HUB_2_BUF_EXT_R_DP")
	)
	(segment
		(start 141.788642 -31.909766)
		(end 142.057882 -32.179006)
		(width 0.13208)
		(layer "B.Cu")
		(net "USB2_HUB_2_BUF_EXT_R_DP")
	)
	(segment
		(start 152.5143 -39.949374)
		(end 153.473658 -42.265346)
		(width 0.13208)
		(layer "B.Cu")
		(net "USB2_HUB_2_BUF_EXT_R_DP")
	)
	(segment
		(start 147.296886 -34.562288)
		(end 147.677886 -34.562288)
		(width 0.13208)
		(layer "B.Cu")
		(net "USB2_HUB_2_BUF_EXT_R_DP")
	)
	(segment
		(start 142.948914 -32.894016)
		(end 143.218662 -33.163764)
		(width 0.13208)
		(layer "B.Cu")
		(net "USB2_HUB_2_BUF_EXT_R_DP")
	)
	(segment
		(start 155.143708 -44.625006)
		(end 155.550362 -45.03166)
		(width 0.13208)
		(layer "B.Cu")
		(net "USB2_HUB_2_BUF_EXT_R_DP")
	)
	(segment
		(start 140.877798 -27.729434)
		(end 140.877798 -27.322526)
		(width 0.13208)
		(layer "B.Cu")
		(net "USB2_HUB_2_BUF_EXT_R_DP")
	)
	(segment
		(start 142.772892 -32.894016)
		(end 142.948914 -32.894016)
		(width 0.13208)
		(layer "B.Cu")
		(net "USB2_HUB_2_BUF_EXT_R_DP")
	)
	(segment
		(start 143.218662 -33.339786)
		(end 143.724122 -33.845246)
		(width 0.13208)
		(layer "B.Cu")
		(net "USB2_HUB_2_BUF_EXT_R_DP")
	)
	(segment
		(start 142.233904 -32.179006)
		(end 142.503652 -32.448754)
		(width 0.13208)
		(layer "B.Cu")
		(net "USB2_HUB_2_BUF_EXT_R_DP")
	)
	(segment
		(start 141.0843 -30.906974)
		(end 141.0843 -31.09595)
		(width 0.13208)
		(layer "B.Cu")
		(net "USB2_HUB_2_BUF_EXT_R_DP")
	)
	(segment
		(start 140.793724 -27.238452)
		(end 140.793724 -26.744168)
		(width 0.13208)
		(layer "B.Cu")
		(net "USB2_HUB_2_BUF_EXT_R_DP")
	)
	(segment
		(start 142.057882 -32.179006)
		(end 142.233904 -32.179006)
		(width 0.13208)
		(layer "B.Cu")
		(net "USB2_HUB_2_BUF_EXT_R_DP")
	)
	(segment
		(start 138.89609 -24.846534)
		(end 138.15568 -24.106124)
		(width 0.13208)
		(layer "B.Cu")
		(net "USB2_HUB_2_BUF_EXT_R_DP")
	)
	(segment
		(start 147.172426 -34.686748)
		(end 147.296886 -34.562288)
		(width 0.13208)
		(layer "B.Cu")
		(net "USB2_HUB_2_BUF_EXT_R_DP")
	)
	(segment
		(start 147.802346 -34.686748)
		(end 151.294338 -34.686748)
		(width 0.13208)
		(layer "B.Cu")
		(net "USB2_HUB_2_BUF_EXT_R_DP")
	)
	(segment
		(start 140.877798 -29.50591)
		(end 140.821156 -29.562552)
		(width 0.13208)
		(layer "B.Cu")
		(net "USB2_HUB_2_BUF_EXT_R_DP")
	)
	(segment
		(start 143.724122 -33.845246)
		(end 144.990566 -34.369756)
		(width 0.13208)
		(layer "B.Cu")
		(net "USB2_HUB_2_BUF_EXT_R_DP")
	)
	(segment
		(start 147.677886 -34.562288)
		(end 147.802346 -34.686748)
		(width 0.13208)
		(layer "B.Cu")
		(net "USB2_HUB_2_BUF_EXT_R_DP")
	)
	(segment
		(start 140.821156 -30.272228)
		(end 141.0843 -30.906974)
		(width 0.13208)
		(layer "B.Cu")
		(net "USB2_HUB_2_BUF_EXT_R_DP")
	)
	(segment
		(start 138.15568 -24.106124)
		(end 138.15568 -23.731728)
		(width 0.13208)
		(layer "B.Cu")
		(net "USB2_HUB_2_BUF_EXT_R_DP")
	)
	(segment
		(start 153.473658 -42.265346)
		(end 155.143708 -43.935396)
		(width 0.13208)
		(layer "B.Cu")
		(net "USB2_HUB_2_BUF_EXT_R_DP")
	)
	(segment
		(start 140.821156 -29.562552)
		(end 140.821156 -30.272228)
		(width 0.13208)
		(layer "B.Cu")
		(net "USB2_HUB_2_BUF_EXT_R_DP")
	)
	(segment
		(start 144.990566 -34.369756)
		(end 146.58213 -34.686748)
		(width 0.13208)
		(layer "B.Cu")
		(net "USB2_HUB_2_BUF_EXT_R_DP")
	)
	(segment
		(start 155.550362 -45.03166)
		(end 156.139896 -45.03166)
		(width 0.13208)
		(layer "B.Cu")
		(net "USB2_HUB_2_BUF_EXT_R_DP")
	)
	(segment
		(start 139.431268 -24.846534)
		(end 138.89609 -24.846534)
		(width 0.13208)
		(layer "B.Cu")
		(net "USB2_HUB_2_BUF_EXT_R_DP")
	)
	(segment
		(start 139.431268 -25.381712)
		(end 139.431268 -24.846534)
		(width 0.13208)
		(layer "B.Cu")
		(net "USB2_HUB_2_BUF_EXT_R_DP")
	)
	(segment
		(start 141.16177 -31.282894)
		(end 141.342872 -31.463996)
		(width 0.13208)
		(layer "B.Cu")
		(net "USB2_HUB_2_BUF_EXT_R_DP")
	)
	(segment
		(start 141.518894 -31.463996)
		(end 141.788642 -31.733744)
		(width 0.13208)
		(layer "B.Cu")
		(net "USB2_HUB_2_BUF_EXT_R_DP")
	)
	(segment
		(start 146.58213 -34.686748)
		(end 147.172426 -34.686748)
		(width 0.13208)
		(layer "B.Cu")
		(net "USB2_HUB_2_BUF_EXT_R_DP")
	)
	(segment
		(start 140.877798 -27.322526)
		(end 140.793724 -27.238452)
		(width 0.13208)
		(layer "B.Cu")
		(net "USB2_HUB_2_BUF_EXT_R_DP")
	)
	(segment
		(start 142.503652 -32.448754)
		(end 142.503652 -32.624776)
		(width 0.13208)
		(layer "B.Cu")
		(net "USB2_HUB_2_BUF_EXT_R_DP")
	)
	(segment
		(start 140.793724 -26.744168)
		(end 139.431268 -25.381712)
		(width 0.13208)
		(layer "B.Cu")
		(net "USB2_HUB_2_BUF_EXT_R_DP")
	)
	(segment
		(start 143.218662 -33.163764)
		(end 143.218662 -33.339786)
		(width 0.13208)
		(layer "B.Cu")
		(net "USB2_HUB_2_BUF_EXT_R_DP")
	)
	(segment
		(start 141.788642 -31.733744)
		(end 141.788642 -31.909766)
		(width 0.13208)
		(layer "B.Cu")
		(net "USB2_HUB_2_BUF_EXT_R_DP")
	)
	(segment
		(start 155.143708 -43.935396)
		(end 155.143708 -44.625006)
		(width 0.13208)
		(layer "B.Cu")
		(net "USB2_HUB_2_BUF_EXT_R_DP")
	)
	(segment
		(start 156.139896 -45.03166)
		(end 156.355288 -44.816268)
		(width 0.13208)
		(layer "B.Cu")
		(net "USB2_HUB_2_BUF_EXT_R_DP")
	)
	(segment
		(start 141.0843 -31.09595)
		(end 141.16177 -31.282894)
		(width 0.13208)
		(layer "B.Cu")
		(net "USB2_HUB_2_BUF_EXT_R_DP")
	)
	(segment
		(start 141.342872 -31.463996)
		(end 141.518894 -31.463996)
		(width 0.13208)
		(layer "B.Cu")
		(net "USB2_HUB_2_BUF_EXT_R_DP")
	)
	(segment
		(start 152.279858 -35.094926)
		(end 152.5143 -35.661092)
		(width 0.13208)
		(layer "B.Cu")
		(net "USB2_HUB_2_BUF_EXT_R_DP")
	)
	(segment
		(start 151.294338 -34.686748)
		(end 152.279858 -35.094926)
		(width 0.13208)
		(layer "B.Cu")
		(net "USB2_HUB_2_BUF_EXT_R_DP")
	)
	(segment
		(start 142.503652 -32.624776)
		(end 142.772892 -32.894016)
		(width 0.13208)
		(layer "B.Cu")
		(net "USB2_HUB_2_BUF_EXT_R_DP")
	)
	(segment
		(start 138.15568 -23.731728)
		(end 138.5443 -23.343108)
		(width 0.13208)
		(layer "B.Cu")
		(net "USB2_HUB_2_BUF_EXT_R_DP")
	)
	(segment
		(start 140.877798 -29.129482)
		(end 140.877798 -29.50591)
		(width 0.13208)
		(layer "B.Cu")
		(net "USB2_HUB_2_BUF_EXT_R_DP")
	)
	(segment
		(start 157.061408 -45.062648)
		(end 156.88183 -45.062648)
		(width 0.13208)
		(layer "F.Cu")
		(net "USB2_HUB_2_BUF_EXT_R_DN")
	)
	(segment
		(start 156.88183 -45.062648)
		(end 156.355542 -45.588936)
		(width 0.13208)
		(layer "F.Cu")
		(net "USB2_HUB_2_BUF_EXT_R_DN")
	)
	(via
		(at 156.355542 -45.588936)
		(size 0.508)
		(drill 0.254)
		(layers "F.Cu" "B.Cu")
		(net "USB2_HUB_2_BUF_EXT_R_DN")
	)
	(via
		(at 138.71194 -25.564338)
		(size 0.6604)
		(drill 0.3302)
		(layers "F.Cu" "B.Cu")
		(net "USB2_HUB_2_BUF_EXT_R_DN")
	)
	(segment
		(start 140.534644 -27.296364)
		(end 140.534644 -26.85161)
		(width 0.13208)
		(layer "B.Cu")
		(net "USB2_HUB_2_BUF_EXT_R_DN")
	)
	(segment
		(start 140.478002 -29.129482)
		(end 140.478002 -29.53639)
		(width 0.13208)
		(layer "B.Cu")
		(net "USB2_HUB_2_BUF_EXT_R_DN")
	)
	(segment
		(start 137.50798 -23.343108)
		(end 137.8966 -23.731728)
		(width 0.13208)
		(layer "B.Cu")
		(net "USB2_HUB_2_BUF_EXT_R_DN")
	)
	(segment
		(start 140.478002 -29.53639)
		(end 140.562076 -29.620464)
		(width 0.13208)
		(layer "B.Cu")
		(net "USB2_HUB_2_BUF_EXT_R_DN")
	)
	(segment
		(start 144.914874 -34.61893)
		(end 146.556476 -34.945828)
		(width 0.13208)
		(layer "B.Cu")
		(net "USB2_HUB_2_BUF_EXT_R_DN")
	)
	(segment
		(start 140.534644 -26.85161)
		(end 139.247372 -25.564338)
		(width 0.13208)
		(layer "B.Cu")
		(net "USB2_HUB_2_BUF_EXT_R_DN")
	)
	(segment
		(start 153.253948 -42.412158)
		(end 154.884628 -44.042838)
		(width 0.13208)
		(layer "B.Cu")
		(net "USB2_HUB_2_BUF_EXT_R_DN")
	)
	(segment
		(start 138.71194 -25.028906)
		(end 138.71194 -25.564338)
		(width 0.13208)
		(layer "B.Cu")
		(net "USB2_HUB_2_BUF_EXT_R_DN")
	)
	(segment
		(start 146.556476 -34.945828)
		(end 151.242776 -34.945828)
		(width 0.13208)
		(layer "B.Cu")
		(net "USB2_HUB_2_BUF_EXT_R_DN")
	)
	(segment
		(start 156.057346 -45.29074)
		(end 156.355542 -45.588936)
		(width 0.13208)
		(layer "B.Cu")
		(net "USB2_HUB_2_BUF_EXT_R_DN")
	)
	(segment
		(start 155.44292 -45.29074)
		(end 156.057346 -45.29074)
		(width 0.13208)
		(layer "B.Cu")
		(net "USB2_HUB_2_BUF_EXT_R_DN")
	)
	(segment
		(start 151.242776 -34.945828)
		(end 152.081484 -35.2933)
		(width 0.13208)
		(layer "B.Cu")
		(net "USB2_HUB_2_BUF_EXT_R_DN")
	)
	(segment
		(start 140.82522 -30.95879)
		(end 140.82522 -31.147512)
		(width 0.13208)
		(layer "B.Cu")
		(net "USB2_HUB_2_BUF_EXT_R_DN")
	)
	(segment
		(start 154.884628 -44.732448)
		(end 155.44292 -45.29074)
		(width 0.13208)
		(layer "B.Cu")
		(net "USB2_HUB_2_BUF_EXT_R_DN")
	)
	(segment
		(start 152.25522 -35.712654)
		(end 152.25522 -40.000936)
		(width 0.13208)
		(layer "B.Cu")
		(net "USB2_HUB_2_BUF_EXT_R_DN")
	)
	(segment
		(start 140.478002 -27.729434)
		(end 140.478002 -27.353006)
		(width 0.13208)
		(layer "B.Cu")
		(net "USB2_HUB_2_BUF_EXT_R_DN")
	)
	(segment
		(start 152.081484 -35.2933)
		(end 152.25522 -35.712654)
		(width 0.13208)
		(layer "B.Cu")
		(net "USB2_HUB_2_BUF_EXT_R_DN")
	)
	(segment
		(start 140.562076 -29.620464)
		(end 140.562076 -30.324044)
		(width 0.13208)
		(layer "B.Cu")
		(net "USB2_HUB_2_BUF_EXT_R_DN")
	)
	(segment
		(start 137.8966 -24.213566)
		(end 138.71194 -25.028906)
		(width 0.13208)
		(layer "B.Cu")
		(net "USB2_HUB_2_BUF_EXT_R_DN")
	)
	(segment
		(start 152.25522 -40.000936)
		(end 153.253948 -42.412158)
		(width 0.13208)
		(layer "B.Cu")
		(net "USB2_HUB_2_BUF_EXT_R_DN")
	)
	(segment
		(start 140.82522 -31.147512)
		(end 140.94206 -31.429706)
		(width 0.13208)
		(layer "B.Cu")
		(net "USB2_HUB_2_BUF_EXT_R_DN")
	)
	(segment
		(start 140.478002 -27.353006)
		(end 140.534644 -27.296364)
		(width 0.13208)
		(layer "B.Cu")
		(net "USB2_HUB_2_BUF_EXT_R_DN")
	)
	(segment
		(start 140.562076 -30.324044)
		(end 140.82522 -30.95879)
		(width 0.13208)
		(layer "B.Cu")
		(net "USB2_HUB_2_BUF_EXT_R_DN")
	)
	(segment
		(start 154.884628 -44.042838)
		(end 154.884628 -44.732448)
		(width 0.13208)
		(layer "B.Cu")
		(net "USB2_HUB_2_BUF_EXT_R_DN")
	)
	(segment
		(start 139.247372 -25.564338)
		(end 138.71194 -25.564338)
		(width 0.13208)
		(layer "B.Cu")
		(net "USB2_HUB_2_BUF_EXT_R_DN")
	)
	(segment
		(start 140.94206 -31.429706)
		(end 143.57731 -34.064956)
		(width 0.13208)
		(layer "B.Cu")
		(net "USB2_HUB_2_BUF_EXT_R_DN")
	)
	(segment
		(start 137.8966 -23.731728)
		(end 137.8966 -24.213566)
		(width 0.13208)
		(layer "B.Cu")
		(net "USB2_HUB_2_BUF_EXT_R_DN")
	)
	(segment
		(start 143.57731 -34.064956)
		(end 144.914874 -34.61893)
		(width 0.13208)
		(layer "B.Cu")
		(net "USB2_HUB_2_BUF_EXT_R_DN")
	)
	(segment
		(start 138.147044 -16.550132)
		(end 138.147044 -17.074388)
		(width 0.12954)
		(layer "F.Cu")
		(net "USB2_HUB_2_BUF_EXT_DP")
	)
	(segment
		(start 138.147044 -17.074388)
		(end 137.975848 -17.245584)
		(width 0.12954)
		(layer "F.Cu")
		(net "USB2_HUB_2_BUF_EXT_DP")
	)
	(segment
		(start 137.975848 -17.842484)
		(end 138.278108 -18.144744)
		(width 0.13208)
		(layer "F.Cu")
		(net "USB2_HUB_2_BUF_EXT_DP")
	)
	(segment
		(start 137.975848 -17.245584)
		(end 137.975848 -17.842484)
		(width 0.13208)
		(layer "F.Cu")
		(net "USB2_HUB_2_BUF_EXT_DP")
	)
	(via
		(at 138.278108 -18.144744)
		(size 0.508)
		(drill 0.254)
		(layers "F.Cu" "B.Cu")
		(net "USB2_HUB_2_BUF_EXT_DP")
	)
	(segment
		(start 138.14806 -21.201126)
		(end 137.975848 -21.028914)
		(width 0.13208)
		(layer "B.Cu")
		(net "USB2_HUB_2_BUF_EXT_DP")
	)
	(segment
		(start 137.975848 -21.028914)
		(end 137.975848 -18.447004)
		(width 0.13208)
		(layer "B.Cu")
		(net "USB2_HUB_2_BUF_EXT_DP")
	)
	(segment
		(start 138.5443 -22.543008)
		(end 138.14806 -22.146768)
		(width 0.13208)
		(layer "B.Cu")
		(net "USB2_HUB_2_BUF_EXT_DP")
	)
	(segment
		(start 137.975848 -18.447004)
		(end 138.278108 -18.144744)
		(width 0.13208)
		(layer "B.Cu")
		(net "USB2_HUB_2_BUF_EXT_DP")
	)
	(segment
		(start 138.14806 -22.146768)
		(end 138.14806 -21.201126)
		(width 0.13208)
		(layer "B.Cu")
		(net "USB2_HUB_2_BUF_EXT_DP")
	)
	(segment
		(start 137.716768 -17.258284)
		(end 137.716768 -17.842484)
		(width 0.13208)
		(layer "F.Cu")
		(net "USB2_HUB_2_BUF_EXT_DN")
	)
	(segment
		(start 137.547096 -17.088612)
		(end 137.716768 -17.258284)
		(width 0.12954)
		(layer "F.Cu")
		(net "USB2_HUB_2_BUF_EXT_DN")
	)
	(segment
		(start 137.716768 -17.842484)
		(end 137.414508 -18.144744)
		(width 0.13208)
		(layer "F.Cu")
		(net "USB2_HUB_2_BUF_EXT_DN")
	)
	(segment
		(start 137.547096 -16.550132)
		(end 137.547096 -17.088612)
		(width 0.12954)
		(layer "F.Cu")
		(net "USB2_HUB_2_BUF_EXT_DN")
	)
	(via
		(at 137.414508 -18.144744)
		(size 0.508)
		(drill 0.254)
		(layers "F.Cu" "B.Cu")
		(net "USB2_HUB_2_BUF_EXT_DN")
	)
	(segment
		(start 137.88898 -22.162008)
		(end 137.88898 -21.308568)
		(width 0.13208)
		(layer "B.Cu")
		(net "USB2_HUB_2_BUF_EXT_DN")
	)
	(segment
		(start 137.716768 -18.447004)
		(end 137.414508 -18.144744)
		(width 0.13208)
		(layer "B.Cu")
		(net "USB2_HUB_2_BUF_EXT_DN")
	)
	(segment
		(start 137.716768 -21.136356)
		(end 137.716768 -18.447004)
		(width 0.13208)
		(layer "B.Cu")
		(net "USB2_HUB_2_BUF_EXT_DN")
	)
	(segment
		(start 137.50798 -22.543008)
		(end 137.88898 -22.162008)
		(width 0.13208)
		(layer "B.Cu")
		(net "USB2_HUB_2_BUF_EXT_DN")
	)
	(segment
		(start 137.88898 -21.308568)
		(end 137.716768 -21.136356)
		(width 0.13208)
		(layer "B.Cu")
		(net "USB2_HUB_2_BUF_EXT_DN")
	)
	(segment
		(start 155.63596 -45.852588)
		(end 155.63596 -46.708568)
		(width 0.13208)
		(layer "F.Cu")
		(net "USB2_HOST_PCH_0_DP")
	)
	(segment
		(start 155.94838 -47.943008)
		(end 156.26842 -47.622968)
		(width 0.13208)
		(layer "F.Cu")
		(net "USB2_HOST_PCH_0_DP")
	)
	(segment
		(start 156.26842 -47.622968)
		(end 156.26842 -47.341028)
		(width 0.13208)
		(layer "F.Cu")
		(net "USB2_HOST_PCH_0_DP")
	)
	(segment
		(start 158.901384 -45.032676)
		(end 158.901384 -45.523912)
		(width 0.13208)
		(layer "F.Cu")
		(net "USB2_HOST_PCH_0_DP")
	)
	(segment
		(start 159.46882 -46.091348)
		(end 159.46882 -47.640748)
		(width 0.13208)
		(layer "F.Cu")
		(net "USB2_HOST_PCH_0_DP")
	)
	(segment
		(start 155.63596 -46.708568)
		(end 155.67914 -46.751748)
		(width 0.13208)
		(layer "F.Cu")
		(net "USB2_HOST_PCH_0_DP")
	)
	(segment
		(start 159.46882 -47.640748)
		(end 159.16656 -47.943008)
		(width 0.13208)
		(layer "F.Cu")
		(net "USB2_HOST_PCH_0_DP")
	)
	(segment
		(start 156.26842 -47.341028)
		(end 155.67914 -46.751748)
		(width 0.13208)
		(layer "F.Cu")
		(net "USB2_HOST_PCH_0_DP")
	)
	(segment
		(start 158.901384 -45.523912)
		(end 159.46882 -46.091348)
		(width 0.13208)
		(layer "F.Cu")
		(net "USB2_HOST_PCH_0_DP")
	)
	(segment
		(start 156.228034 -48.222662)
		(end 155.94838 -47.943008)
		(width 0.14732)
		(layer "In6.Cu")
		(net "USB2_HOST_PCH_0_DP")
	)
	(segment
		(start 158.61538 -47.216568)
		(end 158.40202 -47.429928)
		(width 0.14732)
		(layer "In6.Cu")
		(net "USB2_HOST_PCH_0_DP")
	)
	(segment
		(start 159.16656 -47.943008)
		(end 159.4612 -47.648368)
		(width 0.14732)
		(layer "In6.Cu")
		(net "USB2_HOST_PCH_0_DP")
	)
	(segment
		(start 158.40202 -47.429928)
		(end 158.40202 -48.525938)
		(width 0.14732)
		(layer "In6.Cu")
		(net "USB2_HOST_PCH_0_DP")
	)
	(segment
		(start 157.705806 -49.222152)
		(end 156.784548 -49.222152)
		(width 0.14732)
		(layer "In6.Cu")
		(net "USB2_HOST_PCH_0_DP")
	)
	(segment
		(start 159.237934 -47.216568)
		(end 158.61538 -47.216568)
		(width 0.14732)
		(layer "In6.Cu")
		(net "USB2_HOST_PCH_0_DP")
	)
	(segment
		(start 156.228034 -48.665638)
		(end 156.228034 -48.222662)
		(width 0.14732)
		(layer "In6.Cu")
		(net "USB2_HOST_PCH_0_DP")
	)
	(segment
		(start 159.4612 -47.648368)
		(end 159.4612 -47.439834)
		(width 0.14732)
		(layer "In6.Cu")
		(net "USB2_HOST_PCH_0_DP")
	)
	(segment
		(start 156.784548 -49.222152)
		(end 156.228034 -48.665638)
		(width 0.14732)
		(layer "In6.Cu")
		(net "USB2_HOST_PCH_0_DP")
	)
	(segment
		(start 158.40202 -48.525938)
		(end 157.705806 -49.222152)
		(width 0.14732)
		(layer "In6.Cu")
		(net "USB2_HOST_PCH_0_DP")
	)
	(segment
		(start 159.4612 -47.439834)
		(end 159.237934 -47.216568)
		(width 0.14732)
		(layer "In6.Cu")
		(net "USB2_HOST_PCH_0_DP")
	)
	(segment
		(start 159.7279 -47.640748)
		(end 160.03016 -47.943008)
		(width 0.13208)
		(layer "F.Cu")
		(net "USB2_HOST_PCH_0_DN")
	)
	(segment
		(start 156.5275 -47.245016)
		(end 157.030928 -46.741588)
		(width 0.13208)
		(layer "F.Cu")
		(net "USB2_HOST_PCH_0_DN")
	)
	(segment
		(start 160.28035 -45.538898)
		(end 159.7279 -46.091348)
		(width 0.13208)
		(layer "F.Cu")
		(net "USB2_HOST_PCH_0_DN")
	)
	(segment
		(start 157.061408 -46.711108)
		(end 157.030928 -46.741588)
		(width 0.13208)
		(layer "F.Cu")
		(net "USB2_HOST_PCH_0_DN")
	)
	(segment
		(start 159.7279 -46.091348)
		(end 159.7279 -47.640748)
		(width 0.13208)
		(layer "F.Cu")
		(net "USB2_HOST_PCH_0_DN")
	)
	(segment
		(start 156.5275 -47.658528)
		(end 156.5275 -47.245016)
		(width 0.13208)
		(layer "F.Cu")
		(net "USB2_HOST_PCH_0_DN")
	)
	(segment
		(start 156.81198 -47.943008)
		(end 156.5275 -47.658528)
		(width 0.13208)
		(layer "F.Cu")
		(net "USB2_HOST_PCH_0_DN")
	)
	(segment
		(start 157.061408 -45.862748)
		(end 157.061408 -46.711108)
		(width 0.13208)
		(layer "F.Cu")
		(net "USB2_HOST_PCH_0_DN")
	)
	(segment
		(start 160.28035 -45.032676)
		(end 160.28035 -45.538898)
		(width 0.13208)
		(layer "F.Cu")
		(net "USB2_HOST_PCH_0_DN")
	)
	(segment
		(start 158.501588 -46.942248)
		(end 158.1277 -47.316136)
		(width 0.14732)
		(layer "In6.Cu")
		(net "USB2_HOST_PCH_0_DN")
	)
	(segment
		(start 156.502354 -48.252634)
		(end 156.81198 -47.943008)
		(width 0.14732)
		(layer "In6.Cu")
		(net "USB2_HOST_PCH_0_DN")
	)
	(segment
		(start 157.592014 -48.947832)
		(end 156.89834 -48.947832)
		(width 0.14732)
		(layer "In6.Cu")
		(net "USB2_HOST_PCH_0_DN")
	)
	(segment
		(start 159.73552 -47.648368)
		(end 159.73552 -47.326042)
		(width 0.14732)
		(layer "In6.Cu")
		(net "USB2_HOST_PCH_0_DN")
	)
	(segment
		(start 156.502354 -48.551846)
		(end 156.502354 -48.252634)
		(width 0.14732)
		(layer "In6.Cu")
		(net "USB2_HOST_PCH_0_DN")
	)
	(segment
		(start 158.1277 -48.412146)
		(end 157.592014 -48.947832)
		(width 0.14732)
		(layer "In6.Cu")
		(net "USB2_HOST_PCH_0_DN")
	)
	(segment
		(start 160.03016 -47.943008)
		(end 159.73552 -47.648368)
		(width 0.14732)
		(layer "In6.Cu")
		(net "USB2_HOST_PCH_0_DN")
	)
	(segment
		(start 156.89834 -48.947832)
		(end 156.502354 -48.551846)
		(width 0.14732)
		(layer "In6.Cu")
		(net "USB2_HOST_PCH_0_DN")
	)
	(segment
		(start 159.351726 -46.942248)
		(end 158.501588 -46.942248)
		(width 0.14732)
		(layer "In6.Cu")
		(net "USB2_HOST_PCH_0_DN")
	)
	(segment
		(start 159.73552 -47.326042)
		(end 159.351726 -46.942248)
		(width 0.14732)
		(layer "In6.Cu")
		(net "USB2_HOST_PCH_0_DN")
	)
	(segment
		(start 158.1277 -47.316136)
		(end 158.1277 -48.412146)
		(width 0.14732)
		(layer "In6.Cu")
		(net "USB2_HOST_PCH_0_DN")
	)
	(via
		(at 141.9606 -30.216348)
		(size 0.6604)
		(drill 0.3302)
		(layers "F.Cu" "B.Cu")
		(net "TP_USB_HUB_2_TEST")
	)
	(segment
		(start 141.815058 -29.029406)
		(end 141.478 -29.029406)
		(width 0.12954)
		(layer "B.Cu")
		(net "TP_USB_HUB_2_TEST")
	)
	(segment
		(start 141.9606 -30.216348)
		(end 141.9606 -29.174948)
		(width 0.12954)
		(layer "B.Cu")
		(net "TP_USB_HUB_2_TEST")
	)
	(segment
		(start 141.9606 -29.174948)
		(end 141.815058 -29.029406)
		(width 0.12954)
		(layer "B.Cu")
		(net "TP_USB_HUB_2_TEST")
	)
	(via
		(at 138.7094 -26.965148)
		(size 0.6604)
		(drill 0.3302)
		(layers "F.Cu" "B.Cu")
		(net "TP_USB_HUB_2_ENA_HS")
	)
	(segment
		(start 138.7094 -26.965148)
		(end 139.573762 -27.82951)
		(width 0.12954)
		(layer "B.Cu")
		(net "TP_USB_HUB_2_ENA_HS")
	)
	(segment
		(start 139.573762 -27.82951)
		(end 139.8778 -27.82951)
		(width 0.12954)
		(layer "B.Cu")
		(net "TP_USB_HUB_2_ENA_HS")
	)
	(via
		(at 142.7988 -29.200348)
		(size 0.6604)
		(drill 0.3302)
		(layers "F.Cu" "B.Cu")
		(net "TP_USB_HUB_2_CD")
	)
	(segment
		(start 142.7988 -29.200348)
		(end 142.227808 -28.629356)
		(width 0.12954)
		(layer "B.Cu")
		(net "TP_USB_HUB_2_CD")
	)
	(segment
		(start 142.227808 -28.629356)
		(end 141.478 -28.629356)
		(width 0.12954)
		(layer "B.Cu")
		(net "TP_USB_HUB_2_CD")
	)
	(segment
		(start 11.0363 -416.077908)
		(end 16.56588 -416.077908)
		(width 0.12954)
		(layer "F.Cu")
		(net "TP_TCA9539_0_P0_3")
	)
	(segment
		(start 16.56588 -416.077908)
		(end 17.640046 -415.003742)
		(width 0.12954)
		(layer "F.Cu")
		(net "TP_TCA9539_0_P0_3")
	)
	(segment
		(start 17.640046 -415.003742)
		(end 17.640046 -414.277302)
		(width 0.12954)
		(layer "F.Cu")
		(net "TP_TCA9539_0_P0_3")
	)
	(via
		(at 11.0363 -416.077908)
		(size 0.762)
		(drill 0.381)
		(layers "F.Cu" "B.Cu")
		(net "TP_TCA9539_0_P0_3")
	)
	(segment
		(start 12.17676 -415.418016)
		(end 16.516858 -415.418016)
		(width 0.12954)
		(layer "F.Cu")
		(net "TP_TCA9539_0_P0_2")
	)
	(segment
		(start 16.516858 -415.418016)
		(end 16.989806 -414.945068)
		(width 0.12954)
		(layer "F.Cu")
		(net "TP_TCA9539_0_P0_2")
	)
	(segment
		(start 16.989806 -414.945068)
		(end 16.989806 -414.277302)
		(width 0.12954)
		(layer "F.Cu")
		(net "TP_TCA9539_0_P0_2")
	)
	(via
		(at 12.17676 -415.418016)
		(size 0.762)
		(drill 0.381)
		(layers "F.Cu" "B.Cu")
		(net "TP_TCA9539_0_P0_2")
	)
	(segment
		(start 156.635704 -34.680652)
		(end 155.956 -34.000948)
		(width 0.12954)
		(layer "F.Cu")
		(net "RST_USB_HUB_2_R_N")
	)
	(segment
		(start 153.944066 -31.741618)
		(end 152.978612 -31.741618)
		(width 0.12954)
		(layer "F.Cu")
		(net "RST_USB_HUB_2_R_N")
	)
	(segment
		(start 155.956 -34.000948)
		(end 155.956 -31.839154)
		(width 0.12954)
		(layer "F.Cu")
		(net "RST_USB_HUB_2_R_N")
	)
	(segment
		(start 154.966416 -31.741618)
		(end 156.053536 -31.741618)
		(width 0.12954)
		(layer "F.Cu")
		(net "RST_USB_HUB_2_R_N")
	)
	(segment
		(start 154.966416 -31.741618)
		(end 153.944066 -31.741618)
		(width 0.12954)
		(layer "F.Cu")
		(net "RST_USB_HUB_2_R_N")
	)
	(segment
		(start 156.635704 -35.377882)
		(end 156.635704 -34.680652)
		(width 0.12954)
		(layer "F.Cu")
		(net "RST_USB_HUB_2_R_N")
	)
	(segment
		(start 155.956 -31.839154)
		(end 156.053536 -31.741618)
		(width 0.12954)
		(layer "F.Cu")
		(net "RST_USB_HUB_2_R_N")
	)
	(via
		(at 155.956 -34.000948)
		(size 0.762)
		(drill 0.381)
		(layers "F.Cu" "B.Cu")
		(net "RST_USB_HUB_2_R_N")
	)
	(via
		(at 138.3538 -28.539948)
		(size 0.6604)
		(drill 0.3302)
		(layers "F.Cu" "B.Cu")
		(net "PD_USB_HUB_2_VREG")
	)
	(segment
		(start 137.06602 -28.539948)
		(end 137.0076 -28.598368)
		(width 0.12954)
		(layer "B.Cu")
		(net "PD_USB_HUB_2_VREG")
	)
	(segment
		(start 138.3538 -28.539948)
		(end 137.06602 -28.539948)
		(width 0.12954)
		(layer "B.Cu")
		(net "PD_USB_HUB_2_VREG")
	)
	(segment
		(start 138.443208 -28.629356)
		(end 138.3538 -28.539948)
		(width 0.12954)
		(layer "B.Cu")
		(net "PD_USB_HUB_2_VREG")
	)
	(segment
		(start 139.8778 -28.629356)
		(end 138.443208 -28.629356)
		(width 0.12954)
		(layer "B.Cu")
		(net "PD_USB_HUB_2_VREG")
	)
	(via
		(at 142.8242 -27.930348)
		(size 0.6604)
		(drill 0.3302)
		(layers "F.Cu" "B.Cu")
		(net "PD_USB_HUB_2_RSTN")
	)
	(segment
		(start 143.88338 -28.989528)
		(end 144.11706 -28.989528)
		(width 0.12954)
		(layer "B.Cu")
		(net "PD_USB_HUB_2_RSTN")
	)
	(segment
		(start 141.478 -28.22956)
		(end 142.524988 -28.22956)
		(width 0.12954)
		(layer "B.Cu")
		(net "PD_USB_HUB_2_RSTN")
	)
	(segment
		(start 142.524988 -28.22956)
		(end 142.8242 -27.930348)
		(width 0.12954)
		(layer "B.Cu")
		(net "PD_USB_HUB_2_RSTN")
	)
	(segment
		(start 142.8242 -27.930348)
		(end 143.88338 -28.989528)
		(width 0.12954)
		(layer "B.Cu")
		(net "PD_USB_HUB_2_RSTN")
	)
	(via
		(at 142.875 -26.660348)
		(size 0.6604)
		(drill 0.3302)
		(layers "F.Cu" "B.Cu")
		(net "PD_USB_HUB_2_EQ")
	)
	(segment
		(start 143.67764 -27.843988)
		(end 144.10182 -27.843988)
		(width 0.12954)
		(layer "B.Cu")
		(net "PD_USB_HUB_2_EQ")
	)
	(segment
		(start 142.875 -26.660348)
		(end 142.875 -27.041348)
		(width 0.12954)
		(layer "B.Cu")
		(net "PD_USB_HUB_2_EQ")
	)
	(segment
		(start 142.875 -27.041348)
		(end 143.67764 -27.843988)
		(width 0.12954)
		(layer "B.Cu")
		(net "PD_USB_HUB_2_EQ")
	)
	(segment
		(start 141.478 -27.82951)
		(end 141.705838 -27.82951)
		(width 0.12954)
		(layer "B.Cu")
		(net "PD_USB_HUB_2_EQ")
	)
	(segment
		(start 141.705838 -27.82951)
		(end 142.875 -26.660348)
		(width 0.12954)
		(layer "B.Cu")
		(net "PD_USB_HUB_2_EQ")
	)
	(segment
		(start 153.97226 -36.576508)
		(end 154.258518 -36.29025)
		(width 0.254)
		(layer "F.Cu")
		(net "P3V3_AUX_USB_HUB_2")
	)
	(segment
		(start 159.548068 -38.790372)
		(end 160.097724 -38.790372)
		(width 0.254)
		(layer "F.Cu")
		(net "P3V3_AUX_USB_HUB_2")
	)
	(segment
		(start 156.45638 -40.754808)
		(end 156.635704 -40.575484)
		(width 0.12954)
		(layer "F.Cu")
		(net "P3V3_AUX_USB_HUB_2")
	)
	(segment
		(start 154.115516 -38.790372)
		(end 154.723084 -38.790372)
		(width 0.254)
		(layer "F.Cu")
		(net "P3V3_AUX_USB_HUB_2")
	)
	(segment
		(start 160.261554 -30.941518)
		(end 160.261554 -30.272228)
		(width 0.381)
		(layer "F.Cu")
		(net "P3V3_AUX_USB_HUB_2")
	)
	(segment
		(start 154.258518 -36.29025)
		(end 154.723084 -36.29025)
		(width 0.254)
		(layer "F.Cu")
		(net "P3V3_AUX_USB_HUB_2")
	)
	(segment
		(start 156.45638 -41.026588)
		(end 156.45638 -40.754808)
		(width 0.12954)
		(layer "F.Cu")
		(net "P3V3_AUX_USB_HUB_2")
	)
	(segment
		(start 160.09747 -39.290498)
		(end 159.548068 -39.290498)
		(width 0.254)
		(layer "F.Cu")
		(net "P3V3_AUX_USB_HUB_2")
	)
	(segment
		(start 156.635704 -40.575484)
		(end 156.635704 -40.202866)
		(width 0.12954)
		(layer "F.Cu")
		(net "P3V3_AUX_USB_HUB_2")
	)
	(segment
		(start 160.34766 -39.040308)
		(end 160.09747 -39.290498)
		(width 0.254)
		(layer "F.Cu")
		(net "P3V3_AUX_USB_HUB_2")
	)
	(segment
		(start 153.93416 -38.971728)
		(end 154.115516 -38.790372)
		(width 0.254)
		(layer "F.Cu")
		(net "P3V3_AUX_USB_HUB_2")
	)
	(segment
		(start 160.097724 -38.790372)
		(end 160.34766 -39.040308)
		(width 0.254)
		(layer "F.Cu")
		(net "P3V3_AUX_USB_HUB_2")
	)
	(via
		(at 160.261554 -30.272228)
		(size 0.508)
		(drill 0.254)
		(layers "F.Cu" "B.Cu")
		(net "P3V3_AUX_USB_HUB_2")
	)
	(via
		(at 156.45638 -41.026588)
		(size 0.508)
		(drill 0.254)
		(layers "F.Cu" "B.Cu")
		(net "P3V3_AUX_USB_HUB_2")
	)
	(via
		(at 153.93416 -38.971728)
		(size 0.508)
		(drill 0.254)
		(layers "F.Cu" "B.Cu")
		(net "P3V3_AUX_USB_HUB_2")
	)
	(via
		(at 153.97226 -36.576508)
		(size 0.508)
		(drill 0.254)
		(layers "F.Cu" "B.Cu")
		(net "P3V3_AUX_USB_HUB_2")
	)
	(via
		(at 161.4424 -38.357048)
		(size 0.6604)
		(drill 0.3302)
		(layers "F.Cu" "B.Cu")
		(net "P3V3_AUX_USB_HUB_2")
	)
	(via
		(at 160.34766 -39.040308)
		(size 0.508)
		(drill 0.254)
		(layers "F.Cu" "B.Cu")
		(net "P3V3_AUX_USB_HUB_2")
	)
	(segment
		(start 160.34766 -39.040308)
		(end 160.261554 -38.954202)
		(width 0.381)
		(layer "In2.Cu")
		(net "P3V3_AUX_USB_HUB_2")
	)
	(segment
		(start 160.261554 -38.954202)
		(end 160.261554 -30.272228)
		(width 0.381)
		(layer "In2.Cu")
		(net "P3V3_AUX_USB_HUB_2")
	)
	(via
		(at 129.7686 -28.438348)
		(size 0.508)
		(drill 0.254)
		(layers "F.Cu" "B.Cu")
		(net "P3V3_AUX_USB_BUF")
	)
	(via
		(at 126.57582 -24.412448)
		(size 0.508)
		(drill 0.254)
		(layers "F.Cu" "B.Cu")
		(net "P3V3_AUX_USB_BUF")
	)
	(segment
		(start 126.57582 -24.412448)
		(end 126.74346 -24.412448)
		(width 0.12954)
		(layer "B.Cu")
		(net "P3V3_AUX_USB_BUF")
	)
	(segment
		(start 128.95834 -28.438348)
		(end 128.540764 -28.020772)
		(width 0.12954)
		(layer "B.Cu")
		(net "P3V3_AUX_USB_BUF")
	)
	(segment
		(start 128.540764 -28.020772)
		(end 128.540764 -27.50185)
		(width 0.12954)
		(layer "B.Cu")
		(net "P3V3_AUX_USB_BUF")
	)
	(segment
		(start 127.140716 -24.809704)
		(end 127.140716 -25.051766)
		(width 0.12954)
		(layer "B.Cu")
		(net "P3V3_AUX_USB_BUF")
	)
	(segment
		(start 126.74346 -24.412448)
		(end 127.140716 -24.809704)
		(width 0.12954)
		(layer "B.Cu")
		(net "P3V3_AUX_USB_BUF")
	)
	(segment
		(start 129.7686 -28.438348)
		(end 128.95834 -28.438348)
		(width 0.12954)
		(layer "B.Cu")
		(net "P3V3_AUX_USB_BUF")
	)
	(segment
		(start 189.25032 -425.287948)
		(end 187.85078 -425.287948)
		(width 0.254)
		(layer "F.Cu")
		(net "P12V_PSU_FUSE")
	)
	(segment
		(start 186.839352 -420.022528)
		(end 186.65952 -420.20236)
		(width 0.254)
		(layer "F.Cu")
		(net "P12V_PSU_FUSE")
	)
	(segment
		(start 187.34024 -422.75506)
		(end 186.94146 -423.15384)
		(width 0.254)
		(layer "F.Cu")
		(net "P12V_PSU_FUSE")
	)
	(segment
		(start 187.85078 -425.287948)
		(end 187.842652 -425.27982)
		(width 0.254)
		(layer "F.Cu")
		(net "P12V_PSU_FUSE")
	)
	(segment
		(start 187.325 -425.27982)
		(end 187.842652 -425.27982)
		(width 0.254)
		(layer "F.Cu")
		(net "P12V_PSU_FUSE")
	)
	(segment
		(start 186.94146 -423.15384)
		(end 186.94146 -424.89628)
		(width 0.254)
		(layer "F.Cu")
		(net "P12V_PSU_FUSE")
	)
	(segment
		(start 186.65952 -420.20236)
		(end 186.65952 -421.09898)
		(width 0.254)
		(layer "F.Cu")
		(net "P12V_PSU_FUSE")
	)
	(segment
		(start 188.17336 -420.51986)
		(end 187.676028 -420.022528)
		(width 0.254)
		(layer "F.Cu")
		(net "P12V_PSU_FUSE")
	)
	(segment
		(start 186.65952 -421.09898)
		(end 187.34024 -421.7797)
		(width 0.254)
		(layer "F.Cu")
		(net "P12V_PSU_FUSE")
	)
	(segment
		(start 187.34024 -421.7797)
		(end 187.34024 -422.75506)
		(width 0.254)
		(layer "F.Cu")
		(net "P12V_PSU_FUSE")
	)
	(segment
		(start 186.94146 -424.89628)
		(end 187.325 -425.27982)
		(width 0.254)
		(layer "F.Cu")
		(net "P12V_PSU_FUSE")
	)
	(segment
		(start 187.676028 -420.022528)
		(end 186.839352 -420.022528)
		(width 0.254)
		(layer "F.Cu")
		(net "P12V_PSU_FUSE")
	)
	(via
		(at 188.17336 -420.51986)
		(size 0.508)
		(drill 0.254)
		(layers "F.Cu" "B.Cu")
		(net "P12V_PSU_FUSE")
	)
	(segment
		(start 239.81156 -438.33034)
		(end 197.35546 -438.33034)
		(width 0.254)
		(layer "B.Cu")
		(net "P12V_PSU_FUSE")
	)
	(segment
		(start 190.74638 -422.40454)
		(end 188.8617 -420.51986)
		(width 0.254)
		(layer "B.Cu")
		(net "P12V_PSU_FUSE")
	)
	(segment
		(start 244.77726 -421.41394)
		(end 243.84 -422.3512)
		(width 0.254)
		(layer "B.Cu")
		(net "P12V_PSU_FUSE")
	)
	(segment
		(start 240.70818 -427.03242)
		(end 240.70818 -437.43372)
		(width 0.254)
		(layer "B.Cu")
		(net "P12V_PSU_FUSE")
	)
	(segment
		(start 240.70818 -437.43372)
		(end 239.81156 -438.33034)
		(width 0.254)
		(layer "B.Cu")
		(net "P12V_PSU_FUSE")
	)
	(segment
		(start 250.31192 -420.00932)
		(end 250.31192 -420.97198)
		(width 0.254)
		(layer "B.Cu")
		(net "P12V_PSU_FUSE")
	)
	(segment
		(start 250.31192 -420.97198)
		(end 249.86996 -421.41394)
		(width 0.254)
		(layer "B.Cu")
		(net "P12V_PSU_FUSE")
	)
	(segment
		(start 188.8617 -420.51986)
		(end 188.17336 -420.51986)
		(width 0.254)
		(layer "B.Cu")
		(net "P12V_PSU_FUSE")
	)
	(segment
		(start 190.74638 -423.39514)
		(end 190.74638 -422.40454)
		(width 0.254)
		(layer "B.Cu")
		(net "P12V_PSU_FUSE")
	)
	(segment
		(start 249.86996 -421.41394)
		(end 244.77726 -421.41394)
		(width 0.254)
		(layer "B.Cu")
		(net "P12V_PSU_FUSE")
	)
	(segment
		(start 189.81166 -430.78654)
		(end 189.81166 -424.32986)
		(width 0.254)
		(layer "B.Cu")
		(net "P12V_PSU_FUSE")
	)
	(segment
		(start 189.81166 -424.32986)
		(end 190.74638 -423.39514)
		(width 0.254)
		(layer "B.Cu")
		(net "P12V_PSU_FUSE")
	)
	(segment
		(start 243.84 -423.9006)
		(end 240.70818 -427.03242)
		(width 0.254)
		(layer "B.Cu")
		(net "P12V_PSU_FUSE")
	)
	(segment
		(start 243.84 -422.3512)
		(end 243.84 -423.9006)
		(width 0.254)
		(layer "B.Cu")
		(net "P12V_PSU_FUSE")
	)
	(segment
		(start 197.35546 -438.33034)
		(end 189.81166 -430.78654)
		(width 0.254)
		(layer "B.Cu")
		(net "P12V_PSU_FUSE")
	)
	(segment
		(start 161.279586 -39.984426)
		(end 161.279586 -39.29761)
		(width 0.12954)
		(layer "F.Cu")
		(net "NC_USB_HUB_2_SDA")
	)
	(segment
		(start 161.279586 -39.29761)
		(end 160.272222 -38.290246)
		(width 0.12954)
		(layer "F.Cu")
		(net "NC_USB_HUB_2_SDA")
	)
	(segment
		(start 160.272222 -38.290246)
		(end 159.548068 -38.290246)
		(width 0.12954)
		(layer "F.Cu")
		(net "NC_USB_HUB_2_SDA")
	)
	(segment
		(start 161.81197 -40.51681)
		(end 161.279586 -39.984426)
		(width 0.12954)
		(layer "F.Cu")
		(net "NC_USB_HUB_2_SDA")
	)
	(via
		(at 161.81197 -40.51681)
		(size 0.762)
		(drill 0.381)
		(layers "F.Cu" "B.Cu")
		(net "NC_USB_HUB_2_SDA")
	)
	(segment
		(start 155.49118 -34.425128)
		(end 156.135578 -35.069526)
		(width 0.12954)
		(layer "F.Cu")
		(net "NC_USB_HUB_2_DP4")
	)
	(segment
		(start 153.99004 -34.425128)
		(end 155.49118 -34.425128)
		(width 0.12954)
		(layer "F.Cu")
		(net "NC_USB_HUB_2_DP4")
	)
	(segment
		(start 156.135578 -35.069526)
		(end 156.135578 -35.377882)
		(width 0.12954)
		(layer "F.Cu")
		(net "NC_USB_HUB_2_DP4")
	)
	(segment
		(start 153.26614 -33.701228)
		(end 153.99004 -34.425128)
		(width 0.12954)
		(layer "F.Cu")
		(net "NC_USB_HUB_2_DP4")
	)
	(via
		(at 153.26614 -33.701228)
		(size 0.762)
		(drill 0.381)
		(layers "F.Cu" "B.Cu")
		(net "NC_USB_HUB_2_DP4")
	)
	(segment
		(start 153.80462 -42.393108)
		(end 153.80462 -44.83608)
		(width 0.12954)
		(layer "F.Cu")
		(net "NC_USB_HUB_2_DP2")
	)
	(segment
		(start 155.635452 -40.202866)
		(end 155.635452 -40.562276)
		(width 0.12954)
		(layer "F.Cu")
		(net "NC_USB_HUB_2_DP2")
	)
	(segment
		(start 155.635452 -40.562276)
		(end 153.80462 -42.393108)
		(width 0.12954)
		(layer "F.Cu")
		(net "NC_USB_HUB_2_DP2")
	)
	(segment
		(start 153.80462 -44.83608)
		(end 154.41676 -45.44822)
		(width 0.12954)
		(layer "F.Cu")
		(net "NC_USB_HUB_2_DP2")
	)
	(via
		(at 154.41676 -45.44822)
		(size 0.762)
		(drill 0.381)
		(layers "F.Cu" "B.Cu")
		(net "NC_USB_HUB_2_DP2")
	)
	(segment
		(start 153.69286 -34.935668)
		(end 155.366974 -34.935668)
		(width 0.12954)
		(layer "F.Cu")
		(net "NC_USB_HUB_2_DM4")
	)
	(segment
		(start 155.366974 -34.935668)
		(end 155.635452 -35.204146)
		(width 0.12954)
		(layer "F.Cu")
		(net "NC_USB_HUB_2_DM4")
	)
	(segment
		(start 155.635452 -35.204146)
		(end 155.635452 -35.377882)
		(width 0.12954)
		(layer "F.Cu")
		(net "NC_USB_HUB_2_DM4")
	)
	(via
		(at 153.69286 -34.935668)
		(size 0.762)
		(drill 0.381)
		(layers "F.Cu" "B.Cu")
		(net "NC_USB_HUB_2_DM4")
	)
	(segment
		(start 153.470356 -36.751006)
		(end 154.009852 -37.290502)
		(width 0.12954)
		(layer "F.Cu")
		(net "NC_USB_HUB_2_DM3")
	)
	(segment
		(start 154.009852 -37.290502)
		(end 154.723084 -37.290502)
		(width 0.12954)
		(layer "F.Cu")
		(net "NC_USB_HUB_2_DM3")
	)
	(segment
		(start 152.418034 -35.103308)
		(end 152.912826 -35.103308)
		(width 0.12954)
		(layer "F.Cu")
		(net "NC_USB_HUB_2_DM3")
	)
	(segment
		(start 153.470356 -35.660838)
		(end 153.470356 -36.751006)
		(width 0.12954)
		(layer "F.Cu")
		(net "NC_USB_HUB_2_DM3")
	)
	(segment
		(start 152.912826 -35.103308)
		(end 153.470356 -35.660838)
		(width 0.12954)
		(layer "F.Cu")
		(net "NC_USB_HUB_2_DM3")
	)
	(via
		(at 152.418034 -35.103308)
		(size 0.762)
		(drill 0.381)
		(layers "F.Cu" "B.Cu")
		(net "NC_USB_HUB_2_DM3")
	)
	(segment
		(start 156.135578 -40.638984)
		(end 156.135578 -40.202866)
		(width 0.12954)
		(layer "F.Cu")
		(net "NC_USB_HUB_2_DM2")
	)
	(segment
		(start 154.41676 -44.17822)
		(end 154.41676 -42.357802)
		(width 0.12954)
		(layer "F.Cu")
		(net "NC_USB_HUB_2_DM2")
	)
	(segment
		(start 154.41676 -42.357802)
		(end 156.135578 -40.638984)
		(width 0.12954)
		(layer "F.Cu")
		(net "NC_USB_HUB_2_DM2")
	)
	(via
		(at 154.41676 -44.17822)
		(size 0.762)
		(drill 0.381)
		(layers "F.Cu" "B.Cu")
		(net "NC_USB_HUB_2_DM2")
	)
	(segment
		(start 181.355746 -106.575352)
		(end 181.755796 -106.175302)
		(width 0.12954)
		(layer "F.Cu")
		(net "Net_441")
	)
	(via
		(at 181.755796 -106.175302)
		(size 0.4572)
		(drill 0.254)
		(layers "F.Cu" "B.Cu")
		(net "Net_441")
	)
	(segment
		(start 181.355746 -107.375452)
		(end 181.755796 -106.975402)
		(width 0.12954)
		(layer "F.Cu")
		(net "Net_443")
	)
	(via
		(at 181.755796 -106.975402)
		(size 0.4572)
		(drill 0.254)
		(layers "F.Cu" "B.Cu")
		(net "Net_443")
	)
	(segment
		(start 181.355746 -108.175552)
		(end 181.755796 -107.775502)
		(width 0.12954)
		(layer "F.Cu")
		(net "Net_444")
	)
	(via
		(at 181.755796 -107.775502)
		(size 0.4572)
		(drill 0.254)
		(layers "F.Cu" "B.Cu")
		(net "Net_444")
	)
	(segment
		(start 116.449094 -272.917158)
		(end 116.449094 -273.452844)
		(width 0.12954)
		(layer "F.Cu")
		(net "TP_PWRGD_S0_PWROK_CPU1_LVC1")
	)
	(segment
		(start 116.449094 -273.452844)
		(end 116.449348 -273.453098)
		(width 0.12954)
		(layer "F.Cu")
		(net "TP_PWRGD_S0_PWROK_CPU1_LVC1")
	)
	(via
		(at 156.128212 -266.861798)
		(size 0.6604)
		(drill 0.3302)
		(layers "F.Cu" "B.Cu")
		(net "TP_PWRGD_S0_PWROK_CPU1_LVC1")
	)
	(via
		(at 116.449348 -273.453098)
		(size 0.4572)
		(drill 0.2032)
		(layers "F.Cu" "B.Cu")
		(net "TP_PWRGD_S0_PWROK_CPU1_LVC1")
	)
	(segment
		(start 116.762022 -273.453098)
		(end 116.819426 -273.510502)
		(width 0.0889)
		(layer "B.Cu")
		(net "TP_PWRGD_S0_PWROK_CPU1_LVC1")
	)
	(segment
		(start 117.661182 -267.437616)
		(end 117.671596 -267.43152)
		(width 0.0889)
		(layer "B.Cu")
		(net "TP_PWRGD_S0_PWROK_CPU1_LVC1")
	)
	(segment
		(start 116.166392 -267.43152)
		(end 116.181124 -267.440156)
		(width 0.0889)
		(layer "B.Cu")
		(net "TP_PWRGD_S0_PWROK_CPU1_LVC1")
	)
	(segment
		(start 113.903506 -273.947636)
		(end 113.912396 -273.942556)
		(width 0.0889)
		(layer "B.Cu")
		(net "TP_PWRGD_S0_PWROK_CPU1_LVC1")
	)
	(segment
		(start 113.903506 -272.320004)
		(end 113.912396 -272.314924)
		(width 0.0889)
		(layer "B.Cu")
		(net "TP_PWRGD_S0_PWROK_CPU1_LVC1")
	)
	(segment
		(start 115.31346 -268.250416)
		(end 115.32235 -268.245336)
		(width 0.0889)
		(layer "B.Cu")
		(net "TP_PWRGD_S0_PWROK_CPU1_LVC1")
	)
	(segment
		(start 114.278918 -269.054326)
		(end 114.279172 -269.05458)
		(width 0.0889)
		(layer "B.Cu")
		(net "TP_PWRGD_S0_PWROK_CPU1_LVC1")
	)
	(segment
		(start 113.912396 -274.591272)
		(end 113.903506 -274.586192)
		(width 0.0889)
		(layer "B.Cu")
		(net "TP_PWRGD_S0_PWROK_CPU1_LVC1")
	)
	(segment
		(start 114.194844 -273.463004)
		(end 114.194844 -273.443192)
		(width 0.0889)
		(layer "B.Cu")
		(net "TP_PWRGD_S0_PWROK_CPU1_LVC1")
	)
	(segment
		(start 123.295664 -267.440156)
		(end 123.310396 -267.43152)
		(width 0.0889)
		(layer "B.Cu")
		(net "TP_PWRGD_S0_PWROK_CPU1_LVC1")
	)
	(segment
		(start 115.604544 -267.771372)
		(end 115.604544 -267.755878)
		(width 0.0889)
		(layer "B.Cu")
		(net "TP_PWRGD_S0_PWROK_CPU1_LVC1")
	)
	(segment
		(start 139.00277 -267.14069)
		(end 139.233402 -267.14069)
		(width 0.0889)
		(layer "B.Cu")
		(net "TP_PWRGD_S0_PWROK_CPU1_LVC1")
	)
	(segment
		(start 125.175264 -267.440156)
		(end 125.189996 -267.43152)
		(width 0.0889)
		(layer "B.Cu")
		(net "TP_PWRGD_S0_PWROK_CPU1_LVC1")
	)
	(segment
		(start 113.442496 -270.521938)
		(end 113.433606 -270.516858)
		(width 0.0889)
		(layer "B.Cu")
		(net "TP_PWRGD_S0_PWROK_CPU1_LVC1")
	)
	(segment
		(start 134.573264 -267.440156)
		(end 134.587996 -267.43152)
		(width 0.0889)
		(layer "B.Cu")
		(net "TP_PWRGD_S0_PWROK_CPU1_LVC1")
	)
	(segment
		(start 114.195098 -271.832832)
		(end 114.195098 -271.825212)
		(width 0.0889)
		(layer "B.Cu")
		(net "TP_PWRGD_S0_PWROK_CPU1_LVC1")
	)
	(segment
		(start 113.912396 -272.96364)
		(end 113.903506 -272.95856)
		(width 0.0889)
		(layer "B.Cu")
		(net "TP_PWRGD_S0_PWROK_CPU1_LVC1")
	)
	(segment
		(start 155.84932 -267.14069)
		(end 156.128212 -266.861798)
		(width 0.12954)
		(layer "B.Cu")
		(net "TP_PWRGD_S0_PWROK_CPU1_LVC1")
	)
	(segment
		(start 120.865646 -267.43152)
		(end 120.880378 -267.440156)
		(width 0.0889)
		(layer "B.Cu")
		(net "TP_PWRGD_S0_PWROK_CPU1_LVC1")
	)
	(segment
		(start 113.924588 -271.342866)
		(end 113.921032 -271.34058)
		(width 0.0889)
		(layer "B.Cu")
		(net "TP_PWRGD_S0_PWROK_CPU1_LVC1")
	)
	(segment
		(start 113.912396 -271.335754)
		(end 113.903506 -271.330674)
		(width 0.0889)
		(layer "B.Cu")
		(net "TP_PWRGD_S0_PWROK_CPU1_LVC1")
	)
	(segment
		(start 114.852196 -269.059152)
		(end 114.858292 -269.055596)
		(width 0.0889)
		(layer "B.Cu")
		(net "TP_PWRGD_S0_PWROK_CPU1_LVC1")
	)
	(segment
		(start 124.235464 -267.440156)
		(end 124.250196 -267.43152)
		(width 0.0889)
		(layer "B.Cu")
		(net "TP_PWRGD_S0_PWROK_CPU1_LVC1")
	)
	(segment
		(start 118.045992 -267.43152)
		(end 118.060724 -267.440156)
		(width 0.0889)
		(layer "B.Cu")
		(net "TP_PWRGD_S0_PWROK_CPU1_LVC1")
	)
	(segment
		(start 116.645436 -273.772376)
		(end 116.636546 -273.777456)
		(width 0.0889)
		(layer "B.Cu")
		(net "TP_PWRGD_S0_PWROK_CPU1_LVC1")
	)
	(segment
		(start 135.513064 -267.440156)
		(end 135.527796 -267.43152)
		(width 0.0889)
		(layer "B.Cu")
		(net "TP_PWRGD_S0_PWROK_CPU1_LVC1")
	)
	(segment
		(start 113.725198 -269.39113)
		(end 113.725198 -269.38351)
		(width 0.0889)
		(layer "B.Cu")
		(net "TP_PWRGD_S0_PWROK_CPU1_LVC1")
	)
	(segment
		(start 138.76274 -267.38072)
		(end 139.00277 -267.14069)
		(width 0.0889)
		(layer "B.Cu")
		(net "TP_PWRGD_S0_PWROK_CPU1_LVC1")
	)
	(segment
		(start 127.994664 -267.440156)
		(end 128.009396 -267.43152)
		(width 0.0889)
		(layer "B.Cu")
		(net "TP_PWRGD_S0_PWROK_CPU1_LVC1")
	)
	(segment
		(start 120.480836 -267.437616)
		(end 120.49125 -267.43152)
		(width 0.0889)
		(layer "B.Cu")
		(net "TP_PWRGD_S0_PWROK_CPU1_LVC1")
	)
	(segment
		(start 115.783106 -267.4366)
		(end 115.791996 -267.43152)
		(width 0.0889)
		(layer "B.Cu")
		(net "TP_PWRGD_S0_PWROK_CPU1_LVC1")
	)
	(segment
		(start 113.433606 -269.878302)
		(end 113.442496 -269.873222)
		(width 0.0889)
		(layer "B.Cu")
		(net "TP_PWRGD_S0_PWROK_CPU1_LVC1")
	)
	(segment
		(start 118.986046 -267.43152)
		(end 118.99646 -267.437616)
		(width 0.0889)
		(layer "B.Cu")
		(net "TP_PWRGD_S0_PWROK_CPU1_LVC1")
	)
	(segment
		(start 115.79225 -274.591272)
		(end 115.781836 -274.585176)
		(width 0.0889)
		(layer "B.Cu")
		(net "TP_PWRGD_S0_PWROK_CPU1_LVC1")
	)
	(segment
		(start 128.934464 -267.440156)
		(end 128.949196 -267.43152)
		(width 0.0889)
		(layer "B.Cu")
		(net "TP_PWRGD_S0_PWROK_CPU1_LVC1")
	)
	(segment
		(start 130.814064 -267.440156)
		(end 130.828796 -267.43152)
		(width 0.0889)
		(layer "B.Cu")
		(net "TP_PWRGD_S0_PWROK_CPU1_LVC1")
	)
	(segment
		(start 113.724944 -271.011396)
		(end 113.724944 -271.00149)
		(width 0.0889)
		(layer "B.Cu")
		(net "TP_PWRGD_S0_PWROK_CPU1_LVC1")
	)
	(segment
		(start 131.758436 -267.437616)
		(end 131.76885 -267.43152)
		(width 0.0889)
		(layer "B.Cu")
		(net "TP_PWRGD_S0_PWROK_CPU1_LVC1")
	)
	(segment
		(start 117.098064 -267.426694)
		(end 117.106446 -267.43152)
		(width 0.0889)
		(layer "B.Cu")
		(net "TP_PWRGD_S0_PWROK_CPU1_LVC1")
	)
	(segment
		(start 138.534394 -267.38072)
		(end 138.76274 -267.38072)
		(width 0.0889)
		(layer "B.Cu")
		(net "TP_PWRGD_S0_PWROK_CPU1_LVC1")
	)
	(segment
		(start 127.054864 -267.440156)
		(end 127.069596 -267.43152)
		(width 0.0889)
		(layer "B.Cu")
		(net "TP_PWRGD_S0_PWROK_CPU1_LVC1")
	)
	(segment
		(start 116.175536 -274.586192)
		(end 116.166646 -274.591272)
		(width 0.0889)
		(layer "B.Cu")
		(net "TP_PWRGD_S0_PWROK_CPU1_LVC1")
	)
	(segment
		(start 113.900204 -269.066264)
		(end 113.91265 -269.059152)
		(width 0.0889)
		(layer "B.Cu")
		(net "TP_PWRGD_S0_PWROK_CPU1_LVC1")
	)
	(segment
		(start 116.449348 -273.453098)
		(end 116.762022 -273.453098)
		(width 0.0889)
		(layer "B.Cu")
		(net "TP_PWRGD_S0_PWROK_CPU1_LVC1")
	)
	(segment
		(start 132.143246 -267.43152)
		(end 132.15366 -267.437616)
		(width 0.0889)
		(layer "B.Cu")
		(net "TP_PWRGD_S0_PWROK_CPU1_LVC1")
	)
	(segment
		(start 122.360182 -267.437616)
		(end 122.370596 -267.43152)
		(width 0.0889)
		(layer "B.Cu")
		(net "TP_PWRGD_S0_PWROK_CPU1_LVC1")
	)
	(segment
		(start 116.354098 -274.257008)
		(end 116.354098 -274.266914)
		(width 0.0889)
		(layer "B.Cu")
		(net "TP_PWRGD_S0_PWROK_CPU1_LVC1")
	)
	(segment
		(start 139.233402 -267.14069)
		(end 155.84932 -267.14069)
		(width 0.12954)
		(layer "B.Cu")
		(net "TP_PWRGD_S0_PWROK_CPU1_LVC1")
	)
	(segment
		(start 114.279172 -269.05458)
		(end 114.2873 -269.059152)
		(width 0.0889)
		(layer "B.Cu")
		(net "TP_PWRGD_S0_PWROK_CPU1_LVC1")
	)
	(segment
		(start 113.921032 -271.34058)
		(end 113.912396 -271.335754)
		(width 0.0889)
		(layer "B.Cu")
		(net "TP_PWRGD_S0_PWROK_CPU1_LVC1")
	)
	(segment
		(start 129.874264 -267.440156)
		(end 129.888996 -267.43152)
		(width 0.0889)
		(layer "B.Cu")
		(net "TP_PWRGD_S0_PWROK_CPU1_LVC1")
	)
	(segment
		(start 114.852196 -274.591272)
		(end 114.837464 -274.582636)
		(width 0.0889)
		(layer "B.Cu")
		(net "TP_PWRGD_S0_PWROK_CPU1_LVC1")
	)
	(segment
		(start 118.977664 -267.426694)
		(end 118.986046 -267.43152)
		(width 0.0889)
		(layer "B.Cu")
		(net "TP_PWRGD_S0_PWROK_CPU1_LVC1")
	)
	(arc
		(start 124.250196 -267.43152)
		(mid 124.437394 -267.381377)
		(end 124.624592 -267.43152)
		(width 0.0889)
		(layer "B.Cu")
		(net "TP_PWRGD_S0_PWROK_CPU1_LVC1")
	)
	(arc
		(start 134.962392 -267.43152)
		(mid 135.236591 -267.507355)
		(end 135.513064 -267.440156)
		(width 0.0889)
		(layer "B.Cu")
		(net "TP_PWRGD_S0_PWROK_CPU1_LVC1")
	)
	(arc
		(start 118.611396 -267.43152)
		(mid 118.793901 -267.381282)
		(end 118.977664 -267.426694)
		(width 0.0889)
		(layer "B.Cu")
		(net "TP_PWRGD_S0_PWROK_CPU1_LVC1")
	)
	(arc
		(start 118.060724 -267.440156)
		(mid 118.337165 -267.507322)
		(end 118.611396 -267.43152)
		(width 0.0889)
		(layer "B.Cu")
		(net "TP_PWRGD_S0_PWROK_CPU1_LVC1")
	)
	(arc
		(start 122.370596 -267.43152)
		(mid 122.557794 -267.381377)
		(end 122.744992 -267.43152)
		(width 0.0889)
		(layer "B.Cu")
		(net "TP_PWRGD_S0_PWROK_CPU1_LVC1")
	)
	(arc
		(start 125.189996 -267.43152)
		(mid 125.377194 -267.381377)
		(end 125.564392 -267.43152)
		(width 0.0889)
		(layer "B.Cu")
		(net "TP_PWRGD_S0_PWROK_CPU1_LVC1")
	)
	(arc
		(start 127.443992 -267.43152)
		(mid 127.718221 -267.507445)
		(end 127.994664 -267.440156)
		(width 0.0889)
		(layer "B.Cu")
		(net "TP_PWRGD_S0_PWROK_CPU1_LVC1")
	)
	(arc
		(start 126.129796 -267.43152)
		(mid 126.316994 -267.381377)
		(end 126.504192 -267.43152)
		(width 0.0889)
		(layer "B.Cu")
		(net "TP_PWRGD_S0_PWROK_CPU1_LVC1")
	)
	(arc
		(start 113.725198 -269.38351)
		(mid 113.771843 -269.20234)
		(end 113.900204 -269.066264)
		(width 0.0889)
		(layer "B.Cu")
		(net "TP_PWRGD_S0_PWROK_CPU1_LVC1")
	)
	(arc
		(start 113.903506 -274.586192)
		(mid 113.724909 -274.266914)
		(end 113.903506 -273.947636)
		(width 0.0889)
		(layer "B.Cu")
		(net "TP_PWRGD_S0_PWROK_CPU1_LVC1")
	)
	(arc
		(start 114.858292 -269.055596)
		(mid 115.060879 -268.849245)
		(end 115.134898 -268.569694)
		(width 0.0889)
		(layer "B.Cu")
		(net "TP_PWRGD_S0_PWROK_CPU1_LVC1")
	)
	(arc
		(start 115.604544 -267.755878)
		(mid 115.652223 -267.572978)
		(end 115.783106 -267.4366)
		(width 0.0889)
		(layer "B.Cu")
		(net "TP_PWRGD_S0_PWROK_CPU1_LVC1")
	)
	(arc
		(start 126.504192 -267.43152)
		(mid 126.778421 -267.507445)
		(end 127.054864 -267.440156)
		(width 0.0889)
		(layer "B.Cu")
		(net "TP_PWRGD_S0_PWROK_CPU1_LVC1")
	)
	(arc
		(start 114.194844 -273.443192)
		(mid 114.116733 -273.166243)
		(end 113.912396 -272.96364)
		(width 0.0889)
		(layer "B.Cu")
		(net "TP_PWRGD_S0_PWROK_CPU1_LVC1")
	)
	(arc
		(start 129.323592 -267.43152)
		(mid 129.597821 -267.507445)
		(end 129.874264 -267.440156)
		(width 0.0889)
		(layer "B.Cu")
		(net "TP_PWRGD_S0_PWROK_CPU1_LVC1")
	)
	(arc
		(start 115.134898 -268.569694)
		(mid 115.182577 -268.386794)
		(end 115.31346 -268.250416)
		(width 0.0889)
		(layer "B.Cu")
		(net "TP_PWRGD_S0_PWROK_CPU1_LVC1")
	)
	(arc
		(start 134.587996 -267.43152)
		(mid 134.775194 -267.381377)
		(end 134.962392 -267.43152)
		(width 0.0889)
		(layer "B.Cu")
		(net "TP_PWRGD_S0_PWROK_CPU1_LVC1")
	)
	(arc
		(start 114.2873 -269.059152)
		(mid 114.569748 -269.134801)
		(end 114.852196 -269.059152)
		(width 0.0889)
		(layer "B.Cu")
		(net "TP_PWRGD_S0_PWROK_CPU1_LVC1")
	)
	(arc
		(start 135.902192 -267.43152)
		(mid 136.184894 -267.507262)
		(end 136.467596 -267.43152)
		(width 0.0889)
		(layer "B.Cu")
		(net "TP_PWRGD_S0_PWROK_CPU1_LVC1")
	)
	(arc
		(start 134.022592 -267.43152)
		(mid 134.296821 -267.507445)
		(end 134.573264 -267.440156)
		(width 0.0889)
		(layer "B.Cu")
		(net "TP_PWRGD_S0_PWROK_CPU1_LVC1")
	)
	(arc
		(start 128.009396 -267.43152)
		(mid 128.196594 -267.381377)
		(end 128.383792 -267.43152)
		(width 0.0889)
		(layer "B.Cu")
		(net "TP_PWRGD_S0_PWROK_CPU1_LVC1")
	)
	(arc
		(start 113.91265 -269.059152)
		(mid 114.095155 -269.008914)
		(end 114.278918 -269.054326)
		(width 0.0889)
		(layer "B.Cu")
		(net "TP_PWRGD_S0_PWROK_CPU1_LVC1")
	)
	(arc
		(start 113.903506 -272.95856)
		(mid 113.724909 -272.639282)
		(end 113.903506 -272.320004)
		(width 0.0889)
		(layer "B.Cu")
		(net "TP_PWRGD_S0_PWROK_CPU1_LVC1")
	)
	(arc
		(start 138.347196 -267.43152)
		(mid 138.437452 -267.393798)
		(end 138.534394 -267.38072)
		(width 0.0889)
		(layer "B.Cu")
		(net "TP_PWRGD_S0_PWROK_CPU1_LVC1")
	)
	(arc
		(start 116.354098 -274.266914)
		(mid 116.306419 -274.449814)
		(end 116.175536 -274.586192)
		(width 0.0889)
		(layer "B.Cu")
		(net "TP_PWRGD_S0_PWROK_CPU1_LVC1")
	)
	(arc
		(start 116.181124 -267.440156)
		(mid 116.457565 -267.507322)
		(end 116.731796 -267.43152)
		(width 0.0889)
		(layer "B.Cu")
		(net "TP_PWRGD_S0_PWROK_CPU1_LVC1")
	)
	(arc
		(start 123.684792 -267.43152)
		(mid 123.959021 -267.507445)
		(end 124.235464 -267.440156)
		(width 0.0889)
		(layer "B.Cu")
		(net "TP_PWRGD_S0_PWROK_CPU1_LVC1")
	)
	(arc
		(start 131.76885 -267.43152)
		(mid 131.956048 -267.381377)
		(end 132.143246 -267.43152)
		(width 0.0889)
		(layer "B.Cu")
		(net "TP_PWRGD_S0_PWROK_CPU1_LVC1")
	)
	(arc
		(start 115.791996 -267.43152)
		(mid 115.979194 -267.381377)
		(end 116.166392 -267.43152)
		(width 0.0889)
		(layer "B.Cu")
		(net "TP_PWRGD_S0_PWROK_CPU1_LVC1")
	)
	(arc
		(start 123.310396 -267.43152)
		(mid 123.497594 -267.381377)
		(end 123.684792 -267.43152)
		(width 0.0889)
		(layer "B.Cu")
		(net "TP_PWRGD_S0_PWROK_CPU1_LVC1")
	)
	(arc
		(start 116.731796 -267.43152)
		(mid 116.914301 -267.381282)
		(end 117.098064 -267.426694)
		(width 0.0889)
		(layer "B.Cu")
		(net "TP_PWRGD_S0_PWROK_CPU1_LVC1")
	)
	(arc
		(start 114.837464 -274.582636)
		(mid 114.560989 -274.515316)
		(end 114.286792 -274.591272)
		(width 0.0889)
		(layer "B.Cu")
		(net "TP_PWRGD_S0_PWROK_CPU1_LVC1")
	)
	(arc
		(start 113.912396 -273.942556)
		(mid 114.116731 -273.739951)
		(end 114.194844 -273.463004)
		(width 0.0889)
		(layer "B.Cu")
		(net "TP_PWRGD_S0_PWROK_CPU1_LVC1")
	)
	(arc
		(start 120.49125 -267.43152)
		(mid 120.678448 -267.381377)
		(end 120.865646 -267.43152)
		(width 0.0889)
		(layer "B.Cu")
		(net "TP_PWRGD_S0_PWROK_CPU1_LVC1")
	)
	(arc
		(start 121.43105 -267.43152)
		(mid 121.618248 -267.381377)
		(end 121.805446 -267.43152)
		(width 0.0889)
		(layer "B.Cu")
		(net "TP_PWRGD_S0_PWROK_CPU1_LVC1")
	)
	(arc
		(start 113.724944 -271.00149)
		(mid 113.646833 -270.724541)
		(end 113.442496 -270.521938)
		(width 0.0889)
		(layer "B.Cu")
		(net "TP_PWRGD_S0_PWROK_CPU1_LVC1")
	)
	(arc
		(start 135.527796 -267.43152)
		(mid 135.714994 -267.381377)
		(end 135.902192 -267.43152)
		(width 0.0889)
		(layer "B.Cu")
		(net "TP_PWRGD_S0_PWROK_CPU1_LVC1")
	)
	(arc
		(start 125.564392 -267.43152)
		(mid 125.847094 -267.507262)
		(end 126.129796 -267.43152)
		(width 0.0889)
		(layer "B.Cu")
		(net "TP_PWRGD_S0_PWROK_CPU1_LVC1")
	)
	(arc
		(start 116.166646 -274.591272)
		(mid 115.979448 -274.641415)
		(end 115.79225 -274.591272)
		(width 0.0889)
		(layer "B.Cu")
		(net "TP_PWRGD_S0_PWROK_CPU1_LVC1")
	)
	(arc
		(start 115.32235 -268.245336)
		(mid 115.525173 -268.045105)
		(end 115.604544 -267.771372)
		(width 0.0889)
		(layer "B.Cu")
		(net "TP_PWRGD_S0_PWROK_CPU1_LVC1")
	)
	(arc
		(start 115.781836 -274.585176)
		(mid 115.503404 -274.51533)
		(end 115.226592 -274.591272)
		(width 0.0889)
		(layer "B.Cu")
		(net "TP_PWRGD_S0_PWROK_CPU1_LVC1")
	)
	(arc
		(start 113.433606 -270.516858)
		(mid 113.255009 -270.19758)
		(end 113.433606 -269.878302)
		(width 0.0889)
		(layer "B.Cu")
		(net "TP_PWRGD_S0_PWROK_CPU1_LVC1")
	)
	(arc
		(start 124.624592 -267.43152)
		(mid 124.898821 -267.507445)
		(end 125.175264 -267.440156)
		(width 0.0889)
		(layer "B.Cu")
		(net "TP_PWRGD_S0_PWROK_CPU1_LVC1")
	)
	(arc
		(start 136.841992 -267.43152)
		(mid 137.124694 -267.507262)
		(end 137.407396 -267.43152)
		(width 0.0889)
		(layer "B.Cu")
		(net "TP_PWRGD_S0_PWROK_CPU1_LVC1")
	)
	(arc
		(start 127.069596 -267.43152)
		(mid 127.256794 -267.381377)
		(end 127.443992 -267.43152)
		(width 0.0889)
		(layer "B.Cu")
		(net "TP_PWRGD_S0_PWROK_CPU1_LVC1")
	)
	(arc
		(start 114.286792 -274.591272)
		(mid 114.099594 -274.641415)
		(end 113.912396 -274.591272)
		(width 0.0889)
		(layer "B.Cu")
		(net "TP_PWRGD_S0_PWROK_CPU1_LVC1")
	)
	(arc
		(start 130.828796 -267.43152)
		(mid 131.015994 -267.381377)
		(end 131.203192 -267.43152)
		(width 0.0889)
		(layer "B.Cu")
		(net "TP_PWRGD_S0_PWROK_CPU1_LVC1")
	)
	(arc
		(start 137.407396 -267.43152)
		(mid 137.594594 -267.381377)
		(end 137.781792 -267.43152)
		(width 0.0889)
		(layer "B.Cu")
		(net "TP_PWRGD_S0_PWROK_CPU1_LVC1")
	)
	(arc
		(start 137.781792 -267.43152)
		(mid 138.064494 -267.507262)
		(end 138.347196 -267.43152)
		(width 0.0889)
		(layer "B.Cu")
		(net "TP_PWRGD_S0_PWROK_CPU1_LVC1")
	)
	(arc
		(start 113.903506 -271.330674)
		(mid 113.772592 -271.194314)
		(end 113.724944 -271.011396)
		(width 0.0889)
		(layer "B.Cu")
		(net "TP_PWRGD_S0_PWROK_CPU1_LVC1")
	)
	(arc
		(start 119.551196 -267.43152)
		(mid 119.738394 -267.381377)
		(end 119.925592 -267.43152)
		(width 0.0889)
		(layer "B.Cu")
		(net "TP_PWRGD_S0_PWROK_CPU1_LVC1")
	)
	(arc
		(start 113.912396 -272.314924)
		(mid 114.117468 -272.111245)
		(end 114.195098 -271.832832)
		(width 0.0889)
		(layer "B.Cu")
		(net "TP_PWRGD_S0_PWROK_CPU1_LVC1")
	)
	(arc
		(start 131.203192 -267.43152)
		(mid 131.480005 -267.507356)
		(end 131.758436 -267.437616)
		(width 0.0889)
		(layer "B.Cu")
		(net "TP_PWRGD_S0_PWROK_CPU1_LVC1")
	)
	(arc
		(start 117.671596 -267.43152)
		(mid 117.858794 -267.381377)
		(end 118.045992 -267.43152)
		(width 0.0889)
		(layer "B.Cu")
		(net "TP_PWRGD_S0_PWROK_CPU1_LVC1")
	)
	(arc
		(start 115.226592 -274.591272)
		(mid 115.039394 -274.641415)
		(end 114.852196 -274.591272)
		(width 0.0889)
		(layer "B.Cu")
		(net "TP_PWRGD_S0_PWROK_CPU1_LVC1")
	)
	(arc
		(start 116.636546 -273.777456)
		(mid 116.432211 -273.980061)
		(end 116.354098 -274.257008)
		(width 0.0889)
		(layer "B.Cu")
		(net "TP_PWRGD_S0_PWROK_CPU1_LVC1")
	)
	(arc
		(start 132.708396 -267.43152)
		(mid 132.895594 -267.381377)
		(end 133.082792 -267.43152)
		(width 0.0889)
		(layer "B.Cu")
		(net "TP_PWRGD_S0_PWROK_CPU1_LVC1")
	)
	(arc
		(start 128.383792 -267.43152)
		(mid 128.658021 -267.507445)
		(end 128.934464 -267.440156)
		(width 0.0889)
		(layer "B.Cu")
		(net "TP_PWRGD_S0_PWROK_CPU1_LVC1")
	)
	(arc
		(start 121.805446 -267.43152)
		(mid 122.082005 -267.507229)
		(end 122.360182 -267.437616)
		(width 0.0889)
		(layer "B.Cu")
		(net "TP_PWRGD_S0_PWROK_CPU1_LVC1")
	)
	(arc
		(start 119.925592 -267.43152)
		(mid 120.202405 -267.507356)
		(end 120.480836 -267.437616)
		(width 0.0889)
		(layer "B.Cu")
		(net "TP_PWRGD_S0_PWROK_CPU1_LVC1")
	)
	(arc
		(start 133.648196 -267.43152)
		(mid 133.835394 -267.381377)
		(end 134.022592 -267.43152)
		(width 0.0889)
		(layer "B.Cu")
		(net "TP_PWRGD_S0_PWROK_CPU1_LVC1")
	)
	(arc
		(start 116.819426 -273.510502)
		(mid 116.76127 -273.660615)
		(end 116.645436 -273.772376)
		(width 0.0889)
		(layer "B.Cu")
		(net "TP_PWRGD_S0_PWROK_CPU1_LVC1")
	)
	(arc
		(start 129.888996 -267.43152)
		(mid 130.076194 -267.381377)
		(end 130.263392 -267.43152)
		(width 0.0889)
		(layer "B.Cu")
		(net "TP_PWRGD_S0_PWROK_CPU1_LVC1")
	)
	(arc
		(start 136.467596 -267.43152)
		(mid 136.654794 -267.381377)
		(end 136.841992 -267.43152)
		(width 0.0889)
		(layer "B.Cu")
		(net "TP_PWRGD_S0_PWROK_CPU1_LVC1")
	)
	(arc
		(start 122.744992 -267.43152)
		(mid 123.019221 -267.507445)
		(end 123.295664 -267.440156)
		(width 0.0889)
		(layer "B.Cu")
		(net "TP_PWRGD_S0_PWROK_CPU1_LVC1")
	)
	(arc
		(start 120.880378 -267.440156)
		(mid 121.156819 -267.507322)
		(end 121.43105 -267.43152)
		(width 0.0889)
		(layer "B.Cu")
		(net "TP_PWRGD_S0_PWROK_CPU1_LVC1")
	)
	(arc
		(start 118.99646 -267.437616)
		(mid 119.274638 -267.507308)
		(end 119.551196 -267.43152)
		(width 0.0889)
		(layer "B.Cu")
		(net "TP_PWRGD_S0_PWROK_CPU1_LVC1")
	)
	(arc
		(start 117.106446 -267.43152)
		(mid 117.383005 -267.507229)
		(end 117.661182 -267.437616)
		(width 0.0889)
		(layer "B.Cu")
		(net "TP_PWRGD_S0_PWROK_CPU1_LVC1")
	)
	(arc
		(start 113.442496 -269.873222)
		(mid 113.647568 -269.669543)
		(end 113.725198 -269.39113)
		(width 0.0889)
		(layer "B.Cu")
		(net "TP_PWRGD_S0_PWROK_CPU1_LVC1")
	)
	(arc
		(start 133.082792 -267.43152)
		(mid 133.365494 -267.507262)
		(end 133.648196 -267.43152)
		(width 0.0889)
		(layer "B.Cu")
		(net "TP_PWRGD_S0_PWROK_CPU1_LVC1")
	)
	(arc
		(start 132.15366 -267.437616)
		(mid 132.431838 -267.507308)
		(end 132.708396 -267.43152)
		(width 0.0889)
		(layer "B.Cu")
		(net "TP_PWRGD_S0_PWROK_CPU1_LVC1")
	)
	(arc
		(start 128.949196 -267.43152)
		(mid 129.136394 -267.381377)
		(end 129.323592 -267.43152)
		(width 0.0889)
		(layer "B.Cu")
		(net "TP_PWRGD_S0_PWROK_CPU1_LVC1")
	)
	(arc
		(start 114.195098 -271.825212)
		(mid 114.122863 -271.548688)
		(end 113.924588 -271.342866)
		(width 0.0889)
		(layer "B.Cu")
		(net "TP_PWRGD_S0_PWROK_CPU1_LVC1")
	)
	(arc
		(start 130.263392 -267.43152)
		(mid 130.537621 -267.507445)
		(end 130.814064 -267.440156)
		(width 0.0889)
		(layer "B.Cu")
		(net "TP_PWRGD_S0_PWROK_CPU1_LVC1")
	)
	(segment
		(start 364.389162 -272.917158)
		(end 364.389416 -272.917158)
		(width 0.12954)
		(layer "F.Cu")
		(net "TP_PWRGD_S0_PWROK_CPU0_LVC1")
	)
	(segment
		(start 364.389416 -272.917158)
		(end 364.389416 -273.453098)
		(width 0.12954)
		(layer "F.Cu")
		(net "TP_PWRGD_S0_PWROK_CPU0_LVC1")
	)
	(via
		(at 364.389416 -273.453098)
		(size 0.4572)
		(drill 0.2032)
		(layers "F.Cu" "B.Cu")
		(net "TP_PWRGD_S0_PWROK_CPU0_LVC1")
	)
	(via
		(at 389.201152 -267.34643)
		(size 0.6604)
		(drill 0.3302)
		(layers "F.Cu" "B.Cu")
		(net "TP_PWRGD_S0_PWROK_CPU0_LVC1")
	)
	(segment
		(start 372.175532 -267.440156)
		(end 372.190264 -267.43152)
		(width 0.0889)
		(layer "B.Cu")
		(net "TP_PWRGD_S0_PWROK_CPU0_LVC1")
	)
	(segment
		(start 365.98606 -267.43152)
		(end 366.000792 -267.440156)
		(width 0.0889)
		(layer "B.Cu")
		(net "TP_PWRGD_S0_PWROK_CPU0_LVC1")
	)
	(segment
		(start 362.605066 -269.405608)
		(end 362.605066 -269.374874)
		(width 0.0889)
		(layer "B.Cu")
		(net "TP_PWRGD_S0_PWROK_CPU0_LVC1")
	)
	(segment
		(start 379.698504 -267.437616)
		(end 379.708918 -267.43152)
		(width 0.0889)
		(layer "B.Cu")
		(net "TP_PWRGD_S0_PWROK_CPU0_LVC1")
	)
	(segment
		(start 381.573532 -267.440156)
		(end 381.588264 -267.43152)
		(width 0.0889)
		(layer "B.Cu")
		(net "TP_PWRGD_S0_PWROK_CPU0_LVC1")
	)
	(segment
		(start 361.843574 -273.947636)
		(end 361.852464 -273.942556)
		(width 0.0889)
		(layer "B.Cu")
		(net "TP_PWRGD_S0_PWROK_CPU0_LVC1")
	)
	(segment
		(start 383.453132 -267.440156)
		(end 383.467864 -267.43152)
		(width 0.0889)
		(layer "B.Cu")
		(net "TP_PWRGD_S0_PWROK_CPU0_LVC1")
	)
	(segment
		(start 362.134912 -270.207486)
		(end 362.134912 -270.19758)
		(width 0.0889)
		(layer "B.Cu")
		(net "TP_PWRGD_S0_PWROK_CPU0_LVC1")
	)
	(segment
		(start 361.843574 -270.692118)
		(end 361.852464 -270.687038)
		(width 0.0889)
		(layer "B.Cu")
		(net "TP_PWRGD_S0_PWROK_CPU0_LVC1")
	)
	(segment
		(start 388.022338 -267.34643)
		(end 389.201152 -267.34643)
		(width 0.12954)
		(layer "B.Cu")
		(net "TP_PWRGD_S0_PWROK_CPU0_LVC1")
	)
	(segment
		(start 371.235732 -267.440156)
		(end 371.250464 -267.43152)
		(width 0.0889)
		(layer "B.Cu")
		(net "TP_PWRGD_S0_PWROK_CPU0_LVC1")
	)
	(segment
		(start 362.134912 -273.463004)
		(end 362.134912 -273.443192)
		(width 0.0889)
		(layer "B.Cu")
		(net "TP_PWRGD_S0_PWROK_CPU0_LVC1")
	)
	(segment
		(start 388.019798 -267.34897)
		(end 388.022338 -267.34643)
		(width 0.0889)
		(layer "B.Cu")
		(net "TP_PWRGD_S0_PWROK_CPU0_LVC1")
	)
	(segment
		(start 364.10646 -267.43152)
		(end 364.121192 -267.440156)
		(width 0.0889)
		(layer "B.Cu")
		(net "TP_PWRGD_S0_PWROK_CPU0_LVC1")
	)
	(segment
		(start 376.874532 -267.440156)
		(end 376.889264 -267.43152)
		(width 0.0889)
		(layer "B.Cu")
		(net "TP_PWRGD_S0_PWROK_CPU0_LVC1")
	)
	(segment
		(start 362.792264 -269.059152)
		(end 362.79836 -269.055596)
		(width 0.0889)
		(layer "B.Cu")
		(net "TP_PWRGD_S0_PWROK_CPU0_LVC1")
	)
	(segment
		(start 362.792264 -274.591272)
		(end 362.777532 -274.582636)
		(width 0.0889)
		(layer "B.Cu")
		(net "TP_PWRGD_S0_PWROK_CPU0_LVC1")
	)
	(segment
		(start 368.805714 -267.43152)
		(end 368.820446 -267.440156)
		(width 0.0889)
		(layer "B.Cu")
		(net "TP_PWRGD_S0_PWROK_CPU0_LVC1")
	)
	(segment
		(start 382.513332 -267.440156)
		(end 382.528064 -267.43152)
		(width 0.0889)
		(layer "B.Cu")
		(net "TP_PWRGD_S0_PWROK_CPU0_LVC1")
	)
	(segment
		(start 361.843574 -272.320004)
		(end 361.852464 -272.314924)
		(width 0.0889)
		(layer "B.Cu")
		(net "TP_PWRGD_S0_PWROK_CPU0_LVC1")
	)
	(segment
		(start 361.852464 -274.591272)
		(end 361.843574 -274.586192)
		(width 0.0889)
		(layer "B.Cu")
		(net "TP_PWRGD_S0_PWROK_CPU0_LVC1")
	)
	(segment
		(start 377.814332 -267.440156)
		(end 377.829064 -267.43152)
		(width 0.0889)
		(layer "B.Cu")
		(net "TP_PWRGD_S0_PWROK_CPU0_LVC1")
	)
	(segment
		(start 361.864656 -271.342866)
		(end 361.852464 -271.335754)
		(width 0.0889)
		(layer "B.Cu")
		(net "TP_PWRGD_S0_PWROK_CPU0_LVC1")
	)
	(segment
		(start 361.852464 -272.96364)
		(end 361.843574 -272.95856)
		(width 0.0889)
		(layer "B.Cu")
		(net "TP_PWRGD_S0_PWROK_CPU0_LVC1")
	)
	(segment
		(start 361.852464 -271.335754)
		(end 361.843574 -271.330674)
		(width 0.0889)
		(layer "B.Cu")
		(net "TP_PWRGD_S0_PWROK_CPU0_LVC1")
	)
	(segment
		(start 365.60125 -267.437616)
		(end 365.611664 -267.43152)
		(width 0.0889)
		(layer "B.Cu")
		(net "TP_PWRGD_S0_PWROK_CPU0_LVC1")
	)
	(segment
		(start 366.917732 -267.426694)
		(end 366.926114 -267.43152)
		(width 0.0889)
		(layer "B.Cu")
		(net "TP_PWRGD_S0_PWROK_CPU0_LVC1")
	)
	(segment
		(start 374.994932 -267.440156)
		(end 375.009664 -267.43152)
		(width 0.0889)
		(layer "B.Cu")
		(net "TP_PWRGD_S0_PWROK_CPU0_LVC1")
	)
	(segment
		(start 365.038132 -267.426694)
		(end 365.046514 -267.43152)
		(width 0.0889)
		(layer "B.Cu")
		(net "TP_PWRGD_S0_PWROK_CPU0_LVC1")
	)
	(segment
		(start 362.135166 -271.832832)
		(end 362.135166 -271.825212)
		(width 0.0889)
		(layer "B.Cu")
		(net "TP_PWRGD_S0_PWROK_CPU0_LVC1")
	)
	(segment
		(start 378.754132 -267.440156)
		(end 378.768864 -267.43152)
		(width 0.0889)
		(layer "B.Cu")
		(net "TP_PWRGD_S0_PWROK_CPU0_LVC1")
	)
	(segment
		(start 366.926114 -267.43152)
		(end 366.936528 -267.437616)
		(width 0.0889)
		(layer "B.Cu")
		(net "TP_PWRGD_S0_PWROK_CPU0_LVC1")
	)
	(segment
		(start 363.723174 -267.4366)
		(end 363.732064 -267.43152)
		(width 0.0889)
		(layer "B.Cu")
		(net "TP_PWRGD_S0_PWROK_CPU0_LVC1")
	)
	(segment
		(start 384.716274 -267.34897)
		(end 388.019798 -267.34897)
		(width 0.0889)
		(layer "B.Cu")
		(net "TP_PWRGD_S0_PWROK_CPU0_LVC1")
	)
	(segment
		(start 380.083314 -267.43152)
		(end 380.093728 -267.437616)
		(width 0.0889)
		(layer "B.Cu")
		(net "TP_PWRGD_S0_PWROK_CPU0_LVC1")
	)
	(segment
		(start 364.115604 -274.586192)
		(end 364.106714 -274.591272)
		(width 0.0889)
		(layer "B.Cu")
		(net "TP_PWRGD_S0_PWROK_CPU0_LVC1")
	)
	(segment
		(start 362.310172 -269.880334)
		(end 362.322618 -269.873222)
		(width 0.0889)
		(layer "B.Cu")
		(net "TP_PWRGD_S0_PWROK_CPU0_LVC1")
	)
	(segment
		(start 375.934732 -267.440156)
		(end 375.949464 -267.43152)
		(width 0.0889)
		(layer "B.Cu")
		(net "TP_PWRGD_S0_PWROK_CPU0_LVC1")
	)
	(segment
		(start 373.115332 -267.440156)
		(end 373.130064 -267.43152)
		(width 0.0889)
		(layer "B.Cu")
		(net "TP_PWRGD_S0_PWROK_CPU0_LVC1")
	)
	(segment
		(start 364.294166 -274.257008)
		(end 364.294166 -274.266914)
		(width 0.0889)
		(layer "B.Cu")
		(net "TP_PWRGD_S0_PWROK_CPU0_LVC1")
	)
	(segment
		(start 364.389416 -273.453098)
		(end 364.70209 -273.453098)
		(width 0.0889)
		(layer "B.Cu")
		(net "TP_PWRGD_S0_PWROK_CPU0_LVC1")
	)
	(segment
		(start 363.544612 -267.771372)
		(end 363.544612 -267.755878)
		(width 0.0889)
		(layer "B.Cu")
		(net "TP_PWRGD_S0_PWROK_CPU0_LVC1")
	)
	(segment
		(start 364.70209 -273.453098)
		(end 364.759494 -273.510502)
		(width 0.0889)
		(layer "B.Cu")
		(net "TP_PWRGD_S0_PWROK_CPU0_LVC1")
	)
	(segment
		(start 363.253528 -268.250416)
		(end 363.262418 -268.245336)
		(width 0.0889)
		(layer "B.Cu")
		(net "TP_PWRGD_S0_PWROK_CPU0_LVC1")
	)
	(segment
		(start 368.420904 -267.437616)
		(end 368.431318 -267.43152)
		(width 0.0889)
		(layer "B.Cu")
		(net "TP_PWRGD_S0_PWROK_CPU0_LVC1")
	)
	(segment
		(start 363.732318 -274.591272)
		(end 363.721904 -274.585176)
		(width 0.0889)
		(layer "B.Cu")
		(net "TP_PWRGD_S0_PWROK_CPU0_LVC1")
	)
	(segment
		(start 370.30025 -267.437616)
		(end 370.310664 -267.43152)
		(width 0.0889)
		(layer "B.Cu")
		(net "TP_PWRGD_S0_PWROK_CPU0_LVC1")
	)
	(segment
		(start 364.585504 -273.772376)
		(end 364.576614 -273.777456)
		(width 0.0889)
		(layer "B.Cu")
		(net "TP_PWRGD_S0_PWROK_CPU0_LVC1")
	)
	(arc
		(start 368.820446 -267.440156)
		(mid 369.096887 -267.507322)
		(end 369.371118 -267.43152)
		(width 0.0889)
		(layer "B.Cu")
		(net "TP_PWRGD_S0_PWROK_CPU0_LVC1")
	)
	(arc
		(start 364.106714 -274.591272)
		(mid 363.919516 -274.641415)
		(end 363.732318 -274.591272)
		(width 0.0889)
		(layer "B.Cu")
		(net "TP_PWRGD_S0_PWROK_CPU0_LVC1")
	)
	(arc
		(start 382.528064 -267.43152)
		(mid 382.715262 -267.381377)
		(end 382.90246 -267.43152)
		(width 0.0889)
		(layer "B.Cu")
		(net "TP_PWRGD_S0_PWROK_CPU0_LVC1")
	)
	(arc
		(start 363.074966 -268.569694)
		(mid 363.122645 -268.386794)
		(end 363.253528 -268.250416)
		(width 0.0889)
		(layer "B.Cu")
		(net "TP_PWRGD_S0_PWROK_CPU0_LVC1")
	)
	(arc
		(start 377.26366 -267.43152)
		(mid 377.537889 -267.507445)
		(end 377.814332 -267.440156)
		(width 0.0889)
		(layer "B.Cu")
		(net "TP_PWRGD_S0_PWROK_CPU0_LVC1")
	)
	(arc
		(start 362.134912 -270.19758)
		(mid 362.181649 -270.016374)
		(end 362.310172 -269.880334)
		(width 0.0889)
		(layer "B.Cu")
		(net "TP_PWRGD_S0_PWROK_CPU0_LVC1")
	)
	(arc
		(start 374.44426 -267.43152)
		(mid 374.718489 -267.507445)
		(end 374.994932 -267.440156)
		(width 0.0889)
		(layer "B.Cu")
		(net "TP_PWRGD_S0_PWROK_CPU0_LVC1")
	)
	(arc
		(start 383.467864 -267.43152)
		(mid 383.655062 -267.381377)
		(end 383.84226 -267.43152)
		(width 0.0889)
		(layer "B.Cu")
		(net "TP_PWRGD_S0_PWROK_CPU0_LVC1")
	)
	(arc
		(start 382.90246 -267.43152)
		(mid 383.176689 -267.507445)
		(end 383.453132 -267.440156)
		(width 0.0889)
		(layer "B.Cu")
		(net "TP_PWRGD_S0_PWROK_CPU0_LVC1")
	)
	(arc
		(start 364.294166 -274.266914)
		(mid 364.246487 -274.449814)
		(end 364.115604 -274.586192)
		(width 0.0889)
		(layer "B.Cu")
		(net "TP_PWRGD_S0_PWROK_CPU0_LVC1")
	)
	(arc
		(start 364.759494 -273.510502)
		(mid 364.701338 -273.660615)
		(end 364.585504 -273.772376)
		(width 0.0889)
		(layer "B.Cu")
		(net "TP_PWRGD_S0_PWROK_CPU0_LVC1")
	)
	(arc
		(start 367.491264 -267.43152)
		(mid 367.678462 -267.381377)
		(end 367.86566 -267.43152)
		(width 0.0889)
		(layer "B.Cu")
		(net "TP_PWRGD_S0_PWROK_CPU0_LVC1")
	)
	(arc
		(start 362.79836 -269.055596)
		(mid 363.000947 -268.849245)
		(end 363.074966 -268.569694)
		(width 0.0889)
		(layer "B.Cu")
		(net "TP_PWRGD_S0_PWROK_CPU0_LVC1")
	)
	(arc
		(start 381.02286 -267.43152)
		(mid 381.297089 -267.507445)
		(end 381.573532 -267.440156)
		(width 0.0889)
		(layer "B.Cu")
		(net "TP_PWRGD_S0_PWROK_CPU0_LVC1")
	)
	(arc
		(start 376.32386 -267.43152)
		(mid 376.598089 -267.507445)
		(end 376.874532 -267.440156)
		(width 0.0889)
		(layer "B.Cu")
		(net "TP_PWRGD_S0_PWROK_CPU0_LVC1")
	)
	(arc
		(start 367.86566 -267.43152)
		(mid 368.142473 -267.507356)
		(end 368.420904 -267.437616)
		(width 0.0889)
		(layer "B.Cu")
		(net "TP_PWRGD_S0_PWROK_CPU0_LVC1")
	)
	(arc
		(start 384.407664 -267.43152)
		(mid 384.556537 -267.369924)
		(end 384.716274 -267.34897)
		(width 0.0889)
		(layer "B.Cu")
		(net "TP_PWRGD_S0_PWROK_CPU0_LVC1")
	)
	(arc
		(start 379.708918 -267.43152)
		(mid 379.896116 -267.381377)
		(end 380.083314 -267.43152)
		(width 0.0889)
		(layer "B.Cu")
		(net "TP_PWRGD_S0_PWROK_CPU0_LVC1")
	)
	(arc
		(start 380.093728 -267.437616)
		(mid 380.371906 -267.507308)
		(end 380.648464 -267.43152)
		(width 0.0889)
		(layer "B.Cu")
		(net "TP_PWRGD_S0_PWROK_CPU0_LVC1")
	)
	(arc
		(start 376.889264 -267.43152)
		(mid 377.076462 -267.381377)
		(end 377.26366 -267.43152)
		(width 0.0889)
		(layer "B.Cu")
		(net "TP_PWRGD_S0_PWROK_CPU0_LVC1")
	)
	(arc
		(start 363.732064 -267.43152)
		(mid 363.919262 -267.381377)
		(end 364.10646 -267.43152)
		(width 0.0889)
		(layer "B.Cu")
		(net "TP_PWRGD_S0_PWROK_CPU0_LVC1")
	)
	(arc
		(start 369.745514 -267.43152)
		(mid 370.022073 -267.507229)
		(end 370.30025 -267.437616)
		(width 0.0889)
		(layer "B.Cu")
		(net "TP_PWRGD_S0_PWROK_CPU0_LVC1")
	)
	(arc
		(start 365.046514 -267.43152)
		(mid 365.323073 -267.507229)
		(end 365.60125 -267.437616)
		(width 0.0889)
		(layer "B.Cu")
		(net "TP_PWRGD_S0_PWROK_CPU0_LVC1")
	)
	(arc
		(start 362.777532 -274.582636)
		(mid 362.501057 -274.515316)
		(end 362.22686 -274.591272)
		(width 0.0889)
		(layer "B.Cu")
		(net "TP_PWRGD_S0_PWROK_CPU0_LVC1")
	)
	(arc
		(start 361.852464 -272.314924)
		(mid 362.057536 -272.111245)
		(end 362.135166 -271.832832)
		(width 0.0889)
		(layer "B.Cu")
		(net "TP_PWRGD_S0_PWROK_CPU0_LVC1")
	)
	(arc
		(start 363.544612 -267.755878)
		(mid 363.592291 -267.572978)
		(end 363.723174 -267.4366)
		(width 0.0889)
		(layer "B.Cu")
		(net "TP_PWRGD_S0_PWROK_CPU0_LVC1")
	)
	(arc
		(start 373.130064 -267.43152)
		(mid 373.317262 -267.381377)
		(end 373.50446 -267.43152)
		(width 0.0889)
		(layer "B.Cu")
		(net "TP_PWRGD_S0_PWROK_CPU0_LVC1")
	)
	(arc
		(start 378.20346 -267.43152)
		(mid 378.477689 -267.507445)
		(end 378.754132 -267.440156)
		(width 0.0889)
		(layer "B.Cu")
		(net "TP_PWRGD_S0_PWROK_CPU0_LVC1")
	)
	(arc
		(start 372.190264 -267.43152)
		(mid 372.377462 -267.381377)
		(end 372.56466 -267.43152)
		(width 0.0889)
		(layer "B.Cu")
		(net "TP_PWRGD_S0_PWROK_CPU0_LVC1")
	)
	(arc
		(start 369.371118 -267.43152)
		(mid 369.558316 -267.381377)
		(end 369.745514 -267.43152)
		(width 0.0889)
		(layer "B.Cu")
		(net "TP_PWRGD_S0_PWROK_CPU0_LVC1")
	)
	(arc
		(start 361.843574 -271.330674)
		(mid 361.664977 -271.011396)
		(end 361.843574 -270.692118)
		(width 0.0889)
		(layer "B.Cu")
		(net "TP_PWRGD_S0_PWROK_CPU0_LVC1")
	)
	(arc
		(start 361.852464 -270.687038)
		(mid 362.056799 -270.484433)
		(end 362.134912 -270.207486)
		(width 0.0889)
		(layer "B.Cu")
		(net "TP_PWRGD_S0_PWROK_CPU0_LVC1")
	)
	(arc
		(start 361.843574 -274.586192)
		(mid 361.664977 -274.266914)
		(end 361.843574 -273.947636)
		(width 0.0889)
		(layer "B.Cu")
		(net "TP_PWRGD_S0_PWROK_CPU0_LVC1")
	)
	(arc
		(start 362.134912 -273.443192)
		(mid 362.056801 -273.166243)
		(end 361.852464 -272.96364)
		(width 0.0889)
		(layer "B.Cu")
		(net "TP_PWRGD_S0_PWROK_CPU0_LVC1")
	)
	(arc
		(start 364.121192 -267.440156)
		(mid 364.397633 -267.507322)
		(end 364.671864 -267.43152)
		(width 0.0889)
		(layer "B.Cu")
		(net "TP_PWRGD_S0_PWROK_CPU0_LVC1")
	)
	(arc
		(start 380.648464 -267.43152)
		(mid 380.835662 -267.381377)
		(end 381.02286 -267.43152)
		(width 0.0889)
		(layer "B.Cu")
		(net "TP_PWRGD_S0_PWROK_CPU0_LVC1")
	)
	(arc
		(start 364.576614 -273.777456)
		(mid 364.372279 -273.980061)
		(end 364.294166 -274.257008)
		(width 0.0889)
		(layer "B.Cu")
		(net "TP_PWRGD_S0_PWROK_CPU0_LVC1")
	)
	(arc
		(start 371.62486 -267.43152)
		(mid 371.899089 -267.507445)
		(end 372.175532 -267.440156)
		(width 0.0889)
		(layer "B.Cu")
		(net "TP_PWRGD_S0_PWROK_CPU0_LVC1")
	)
	(arc
		(start 375.949464 -267.43152)
		(mid 376.136662 -267.381377)
		(end 376.32386 -267.43152)
		(width 0.0889)
		(layer "B.Cu")
		(net "TP_PWRGD_S0_PWROK_CPU0_LVC1")
	)
	(arc
		(start 377.829064 -267.43152)
		(mid 378.016262 -267.381377)
		(end 378.20346 -267.43152)
		(width 0.0889)
		(layer "B.Cu")
		(net "TP_PWRGD_S0_PWROK_CPU0_LVC1")
	)
	(arc
		(start 365.611664 -267.43152)
		(mid 365.798862 -267.381377)
		(end 365.98606 -267.43152)
		(width 0.0889)
		(layer "B.Cu")
		(net "TP_PWRGD_S0_PWROK_CPU0_LVC1")
	)
	(arc
		(start 381.588264 -267.43152)
		(mid 381.775462 -267.381377)
		(end 381.96266 -267.43152)
		(width 0.0889)
		(layer "B.Cu")
		(net "TP_PWRGD_S0_PWROK_CPU0_LVC1")
	)
	(arc
		(start 362.605066 -269.374874)
		(mid 362.657336 -269.192509)
		(end 362.792264 -269.059152)
		(width 0.0889)
		(layer "B.Cu")
		(net "TP_PWRGD_S0_PWROK_CPU0_LVC1")
	)
	(arc
		(start 362.322618 -269.873222)
		(mid 362.524074 -269.675797)
		(end 362.605066 -269.405608)
		(width 0.0889)
		(layer "B.Cu")
		(net "TP_PWRGD_S0_PWROK_CPU0_LVC1")
	)
	(arc
		(start 370.310664 -267.43152)
		(mid 370.497862 -267.381377)
		(end 370.68506 -267.43152)
		(width 0.0889)
		(layer "B.Cu")
		(net "TP_PWRGD_S0_PWROK_CPU0_LVC1")
	)
	(arc
		(start 361.852464 -273.942556)
		(mid 362.056799 -273.739951)
		(end 362.134912 -273.463004)
		(width 0.0889)
		(layer "B.Cu")
		(net "TP_PWRGD_S0_PWROK_CPU0_LVC1")
	)
	(arc
		(start 379.14326 -267.43152)
		(mid 379.420073 -267.507356)
		(end 379.698504 -267.437616)
		(width 0.0889)
		(layer "B.Cu")
		(net "TP_PWRGD_S0_PWROK_CPU0_LVC1")
	)
	(arc
		(start 363.262418 -268.245336)
		(mid 363.465241 -268.045105)
		(end 363.544612 -267.771372)
		(width 0.0889)
		(layer "B.Cu")
		(net "TP_PWRGD_S0_PWROK_CPU0_LVC1")
	)
	(arc
		(start 372.56466 -267.43152)
		(mid 372.838889 -267.507445)
		(end 373.115332 -267.440156)
		(width 0.0889)
		(layer "B.Cu")
		(net "TP_PWRGD_S0_PWROK_CPU0_LVC1")
	)
	(arc
		(start 362.22686 -274.591272)
		(mid 362.039662 -274.641415)
		(end 361.852464 -274.591272)
		(width 0.0889)
		(layer "B.Cu")
		(net "TP_PWRGD_S0_PWROK_CPU0_LVC1")
	)
	(arc
		(start 368.431318 -267.43152)
		(mid 368.618516 -267.381377)
		(end 368.805714 -267.43152)
		(width 0.0889)
		(layer "B.Cu")
		(net "TP_PWRGD_S0_PWROK_CPU0_LVC1")
	)
	(arc
		(start 364.671864 -267.43152)
		(mid 364.854369 -267.381282)
		(end 365.038132 -267.426694)
		(width 0.0889)
		(layer "B.Cu")
		(net "TP_PWRGD_S0_PWROK_CPU0_LVC1")
	)
	(arc
		(start 375.38406 -267.43152)
		(mid 375.658289 -267.507445)
		(end 375.934732 -267.440156)
		(width 0.0889)
		(layer "B.Cu")
		(net "TP_PWRGD_S0_PWROK_CPU0_LVC1")
	)
	(arc
		(start 375.009664 -267.43152)
		(mid 375.196862 -267.381377)
		(end 375.38406 -267.43152)
		(width 0.0889)
		(layer "B.Cu")
		(net "TP_PWRGD_S0_PWROK_CPU0_LVC1")
	)
	(arc
		(start 381.96266 -267.43152)
		(mid 382.236889 -267.507445)
		(end 382.513332 -267.440156)
		(width 0.0889)
		(layer "B.Cu")
		(net "TP_PWRGD_S0_PWROK_CPU0_LVC1")
	)
	(arc
		(start 361.843574 -272.95856)
		(mid 361.664977 -272.639282)
		(end 361.843574 -272.320004)
		(width 0.0889)
		(layer "B.Cu")
		(net "TP_PWRGD_S0_PWROK_CPU0_LVC1")
	)
	(arc
		(start 366.936528 -267.437616)
		(mid 367.214706 -267.507308)
		(end 367.491264 -267.43152)
		(width 0.0889)
		(layer "B.Cu")
		(net "TP_PWRGD_S0_PWROK_CPU0_LVC1")
	)
	(arc
		(start 362.135166 -271.825212)
		(mid 362.062931 -271.548688)
		(end 361.864656 -271.342866)
		(width 0.0889)
		(layer "B.Cu")
		(net "TP_PWRGD_S0_PWROK_CPU0_LVC1")
	)
	(arc
		(start 366.000792 -267.440156)
		(mid 366.277233 -267.507322)
		(end 366.551464 -267.43152)
		(width 0.0889)
		(layer "B.Cu")
		(net "TP_PWRGD_S0_PWROK_CPU0_LVC1")
	)
	(arc
		(start 371.250464 -267.43152)
		(mid 371.437662 -267.381377)
		(end 371.62486 -267.43152)
		(width 0.0889)
		(layer "B.Cu")
		(net "TP_PWRGD_S0_PWROK_CPU0_LVC1")
	)
	(arc
		(start 363.721904 -274.585176)
		(mid 363.443472 -274.51533)
		(end 363.16666 -274.591272)
		(width 0.0889)
		(layer "B.Cu")
		(net "TP_PWRGD_S0_PWROK_CPU0_LVC1")
	)
	(arc
		(start 378.768864 -267.43152)
		(mid 378.956062 -267.381377)
		(end 379.14326 -267.43152)
		(width 0.0889)
		(layer "B.Cu")
		(net "TP_PWRGD_S0_PWROK_CPU0_LVC1")
	)
	(arc
		(start 366.551464 -267.43152)
		(mid 366.733969 -267.381282)
		(end 366.917732 -267.426694)
		(width 0.0889)
		(layer "B.Cu")
		(net "TP_PWRGD_S0_PWROK_CPU0_LVC1")
	)
	(arc
		(start 363.16666 -274.591272)
		(mid 362.979462 -274.641415)
		(end 362.792264 -274.591272)
		(width 0.0889)
		(layer "B.Cu")
		(net "TP_PWRGD_S0_PWROK_CPU0_LVC1")
	)
	(arc
		(start 370.68506 -267.43152)
		(mid 370.959289 -267.507445)
		(end 371.235732 -267.440156)
		(width 0.0889)
		(layer "B.Cu")
		(net "TP_PWRGD_S0_PWROK_CPU0_LVC1")
	)
	(arc
		(start 374.069864 -267.43152)
		(mid 374.257062 -267.381377)
		(end 374.44426 -267.43152)
		(width 0.0889)
		(layer "B.Cu")
		(net "TP_PWRGD_S0_PWROK_CPU0_LVC1")
	)
	(arc
		(start 373.50446 -267.43152)
		(mid 373.787162 -267.507262)
		(end 374.069864 -267.43152)
		(width 0.0889)
		(layer "B.Cu")
		(net "TP_PWRGD_S0_PWROK_CPU0_LVC1")
	)
	(arc
		(start 383.84226 -267.43152)
		(mid 384.124962 -267.507262)
		(end 384.407664 -267.43152)
		(width 0.0889)
		(layer "B.Cu")
		(net "TP_PWRGD_S0_PWROK_CPU0_LVC1")
	)
	(segment
		(start 110.230666 -232.250488)
		(end 110.230666 -231.714548)
		(width 0.12954)
		(layer "F.Cu")
		(net "TP_CPU1_BR23")
	)
	(via
		(at 110.230666 -231.714548)
		(size 0.4572)
		(drill 0.2032)
		(layers "F.Cu" "B.Cu")
		(net "TP_CPU1_BR23")
	)
	(via
		(at 122.62612 -154.181048)
		(size 0.508)
		(drill 0.254)
		(layers "F.Cu" "B.Cu")
		(net "TP_CPU1_BR23")
	)
	(via
		(at 125.21438 -103.950008)
		(size 0.762)
		(drill 0.254)
		(layers "F.Cu" "B.Cu")
		(net "TP_CPU1_BR23")
	)
	(via
		(at 87.471758 -199.57415)
		(size 0.6604)
		(drill 0.3302)
		(layers "F.Cu" "B.Cu")
		(net "TP_CPU1_BR23")
	)
	(segment
		(start 97.730564 -223.085914)
		(end 97.745296 -223.077278)
		(width 0.0889)
		(layer "B.Cu")
		(net "TP_CPU1_BR23")
	)
	(segment
		(start 106.566716 -227.635054)
		(end 106.566716 -227.64496)
		(width 0.0889)
		(layer "B.Cu")
		(net "TP_CPU1_BR23")
	)
	(segment
		(start 87.471758 -200.91146)
		(end 85.209634 -203.173584)
		(width 0.12954)
		(layer "B.Cu")
		(net "TP_CPU1_BR23")
	)
	(segment
		(start 85.782658 -222.924878)
		(end 85.873082 -223.015302)
		(width 0.0889)
		(layer "B.Cu")
		(net "TP_CPU1_BR23")
	)
	(segment
		(start 107.685078 -229.592124)
		(end 107.693968 -229.597204)
		(width 0.0889)
		(layer "B.Cu")
		(net "TP_CPU1_BR23")
	)
	(segment
		(start 120.9294 -154.181048)
		(end 119.58574 -155.524708)
		(width 0.12954)
		(layer "B.Cu")
		(net "TP_CPU1_BR23")
	)
	(segment
		(start 88.324182 -223.09074)
		(end 88.332564 -223.085914)
		(width 0.0889)
		(layer "B.Cu")
		(net "TP_CPU1_BR23")
	)
	(segment
		(start 104.395778 -223.894904)
		(end 104.404668 -223.899984)
		(width 0.0889)
		(layer "B.Cu")
		(net "TP_CPU1_BR23")
	)
	(segment
		(start 101.489764 -223.085914)
		(end 101.504496 -223.077278)
		(width 0.0889)
		(layer "B.Cu")
		(net "TP_CPU1_BR23")
	)
	(segment
		(start 95.850964 -223.085914)
		(end 95.865696 -223.077278)
		(width 0.0889)
		(layer "B.Cu")
		(net "TP_CPU1_BR23")
	)
	(segment
		(start 85.209634 -207.373474)
		(end 82.582258 -210.00085)
		(width 0.12954)
		(layer "B.Cu")
		(net "TP_CPU1_BR23")
	)
	(segment
		(start 82.582258 -219.59443)
		(end 84.81441 -221.826582)
		(width 0.12954)
		(layer "B.Cu")
		(net "TP_CPU1_BR23")
	)
	(segment
		(start 109.088682 -230.402384)
		(end 109.103414 -230.41102)
		(width 0.0889)
		(layer "B.Cu")
		(net "TP_CPU1_BR23")
	)
	(segment
		(start 85.209634 -203.173584)
		(end 85.209634 -207.373474)
		(width 0.12954)
		(layer "B.Cu")
		(net "TP_CPU1_BR23")
	)
	(segment
		(start 105.805478 -226.336606)
		(end 105.814368 -226.341686)
		(width 0.0889)
		(layer "B.Cu")
		(net "TP_CPU1_BR23")
	)
	(segment
		(start 88.332564 -223.085914)
		(end 88.347296 -223.077278)
		(width 0.0889)
		(layer "B.Cu")
		(net "TP_CPU1_BR23")
	)
	(segment
		(start 87.471758 -191.87795)
		(end 87.471758 -199.57415)
		(width 0.12954)
		(layer "B.Cu")
		(net "TP_CPU1_BR23")
	)
	(segment
		(start 103.369364 -223.085914)
		(end 103.384096 -223.077278)
		(width 0.0889)
		(layer "B.Cu")
		(net "TP_CPU1_BR23")
	)
	(segment
		(start 85.782658 -222.661226)
		(end 85.782658 -222.924878)
		(width 0.0889)
		(layer "B.Cu")
		(net "TP_CPU1_BR23")
	)
	(segment
		(start 86.068154 -223.079818)
		(end 86.078568 -223.085914)
		(width 0.0889)
		(layer "B.Cu")
		(net "TP_CPU1_BR23")
	)
	(segment
		(start 104.217216 -223.561402)
		(end 104.217216 -223.575626)
		(width 0.0889)
		(layer "B.Cu")
		(net "TP_CPU1_BR23")
	)
	(segment
		(start 122.62612 -154.181048)
		(end 120.9294 -154.181048)
		(width 0.12954)
		(layer "B.Cu")
		(net "TP_CPU1_BR23")
	)
	(segment
		(start 104.687116 -224.379536)
		(end 104.687116 -224.389442)
		(width 0.0889)
		(layer "B.Cu")
		(net "TP_CPU1_BR23")
	)
	(segment
		(start 104.865678 -224.70872)
		(end 104.874568 -224.7138)
		(width 0.0889)
		(layer "B.Cu")
		(net "TP_CPU1_BR23")
	)
	(segment
		(start 84.81441 -221.826582)
		(end 84.948014 -221.826582)
		(width 0.0889)
		(layer "B.Cu")
		(net "TP_CPU1_BR23")
	)
	(segment
		(start 108.154724 -230.40594)
		(end 108.163614 -230.41102)
		(width 0.0889)
		(layer "B.Cu")
		(net "TP_CPU1_BR23")
	)
	(segment
		(start 105.814368 -226.341686)
		(end 105.820464 -226.345242)
		(width 0.0889)
		(layer "B.Cu")
		(net "TP_CPU1_BR23")
	)
	(segment
		(start 84.948014 -221.826582)
		(end 85.782658 -222.661226)
		(width 0.0889)
		(layer "B.Cu")
		(net "TP_CPU1_BR23")
	)
	(segment
		(start 109.359954 -155.524708)
		(end 87.86368 -177.020982)
		(width 0.12954)
		(layer "B.Cu")
		(net "TP_CPU1_BR23")
	)
	(segment
		(start 88.505284 -187.494418)
		(end 88.505284 -190.305182)
		(width 0.12954)
		(layer "B.Cu")
		(net "TP_CPU1_BR23")
	)
	(segment
		(start 109.385862 -230.884984)
		(end 109.385862 -230.909114)
		(width 0.0889)
		(layer "B.Cu")
		(net "TP_CPU1_BR23")
	)
	(segment
		(start 107.214924 -228.778308)
		(end 107.223814 -228.783388)
		(width 0.0889)
		(layer "B.Cu")
		(net "TP_CPU1_BR23")
	)
	(segment
		(start 107.036362 -228.436932)
		(end 107.036362 -228.45903)
		(width 0.0889)
		(layer "B.Cu")
		(net "TP_CPU1_BR23")
	)
	(segment
		(start 87.989918 -190.820548)
		(end 87.989918 -191.35979)
		(width 0.12954)
		(layer "B.Cu")
		(net "TP_CPU1_BR23")
	)
	(segment
		(start 99.610164 -223.085914)
		(end 99.624896 -223.077278)
		(width 0.0889)
		(layer "B.Cu")
		(net "TP_CPU1_BR23")
	)
	(segment
		(start 110.034578 -232.033826)
		(end 110.043468 -232.038906)
		(width 0.0889)
		(layer "B.Cu")
		(net "TP_CPU1_BR23")
	)
	(segment
		(start 105.335324 -225.522536)
		(end 105.344214 -225.527616)
		(width 0.0889)
		(layer "B.Cu")
		(net "TP_CPU1_BR23")
	)
	(segment
		(start 88.505284 -190.305182)
		(end 87.989918 -190.820548)
		(width 0.12954)
		(layer "B.Cu")
		(net "TP_CPU1_BR23")
	)
	(segment
		(start 87.86368 -177.020982)
		(end 87.86368 -186.852814)
		(width 0.12954)
		(layer "B.Cu")
		(net "TP_CPU1_BR23")
	)
	(segment
		(start 105.156762 -225.187764)
		(end 105.156762 -225.203258)
		(width 0.0889)
		(layer "B.Cu")
		(net "TP_CPU1_BR23")
	)
	(segment
		(start 110.38713 -231.985566)
		(end 110.230666 -231.714548)
		(width 0.0889)
		(layer "B.Cu")
		(net "TP_CPU1_BR23")
	)
	(segment
		(start 87.392764 -223.085914)
		(end 87.403178 -223.079818)
		(width 0.0889)
		(layer "B.Cu")
		(net "TP_CPU1_BR23")
	)
	(segment
		(start 106.745278 -227.964238)
		(end 106.754168 -227.969318)
		(width 0.0889)
		(layer "B.Cu")
		(net "TP_CPU1_BR23")
	)
	(segment
		(start 87.989918 -191.35979)
		(end 87.471758 -191.87795)
		(width 0.12954)
		(layer "B.Cu")
		(net "TP_CPU1_BR23")
	)
	(segment
		(start 119.58574 -155.524708)
		(end 109.359954 -155.524708)
		(width 0.12954)
		(layer "B.Cu")
		(net "TP_CPU1_BR23")
	)
	(segment
		(start 92.091764 -223.085914)
		(end 92.106496 -223.077278)
		(width 0.0889)
		(layer "B.Cu")
		(net "TP_CPU1_BR23")
	)
	(segment
		(start 106.275378 -227.150422)
		(end 106.284268 -227.155502)
		(width 0.0889)
		(layer "B.Cu")
		(net "TP_CPU1_BR23")
	)
	(segment
		(start 90.212164 -223.085914)
		(end 90.226896 -223.077278)
		(width 0.0889)
		(layer "B.Cu")
		(net "TP_CPU1_BR23")
	)
	(segment
		(start 109.57306 -231.224836)
		(end 109.581188 -231.229662)
		(width 0.0889)
		(layer "B.Cu")
		(net "TP_CPU1_BR23")
	)
	(segment
		(start 87.471758 -199.57415)
		(end 87.471758 -200.91146)
		(width 0.12954)
		(layer "B.Cu")
		(net "TP_CPU1_BR23")
	)
	(segment
		(start 105.626916 -226.003104)
		(end 105.626916 -226.017328)
		(width 0.0889)
		(layer "B.Cu")
		(net "TP_CPU1_BR23")
	)
	(segment
		(start 107.976162 -230.071168)
		(end 107.976162 -230.086662)
		(width 0.0889)
		(layer "B.Cu")
		(net "TP_CPU1_BR23")
	)
	(segment
		(start 110.366048 -232.063544)
		(end 110.38713 -231.985566)
		(width 0.0889)
		(layer "B.Cu")
		(net "TP_CPU1_BR23")
	)
	(segment
		(start 87.86368 -186.852814)
		(end 88.505284 -187.494418)
		(width 0.12954)
		(layer "B.Cu")
		(net "TP_CPU1_BR23")
	)
	(segment
		(start 82.582258 -210.00085)
		(end 82.582258 -219.59443)
		(width 0.12954)
		(layer "B.Cu")
		(net "TP_CPU1_BR23")
	)
	(segment
		(start 93.971364 -223.085914)
		(end 93.986096 -223.077278)
		(width 0.0889)
		(layer "B.Cu")
		(net "TP_CPU1_BR23")
	)
	(segment
		(start 107.223814 -228.783388)
		(end 107.22991 -228.786944)
		(width 0.0889)
		(layer "B.Cu")
		(net "TP_CPU1_BR23")
	)
	(arc
		(start 104.404668 -223.899984)
		(mid 104.609003 -224.102589)
		(end 104.687116 -224.379536)
		(width 0.0889)
		(layer "B.Cu")
		(net "TP_CPU1_BR23")
	)
	(arc
		(start 92.657168 -223.085914)
		(mid 92.844366 -223.136057)
		(end 93.031564 -223.085914)
		(width 0.0889)
		(layer "B.Cu")
		(net "TP_CPU1_BR23")
	)
	(arc
		(start 94.536768 -223.085914)
		(mid 94.723966 -223.136057)
		(end 94.911164 -223.085914)
		(width 0.0889)
		(layer "B.Cu")
		(net "TP_CPU1_BR23")
	)
	(arc
		(start 96.790764 -223.085914)
		(mid 97.073466 -223.010172)
		(end 97.356168 -223.085914)
		(width 0.0889)
		(layer "B.Cu")
		(net "TP_CPU1_BR23")
	)
	(arc
		(start 97.745296 -223.077278)
		(mid 98.021737 -223.010112)
		(end 98.295968 -223.085914)
		(width 0.0889)
		(layer "B.Cu")
		(net "TP_CPU1_BR23")
	)
	(arc
		(start 101.115368 -223.085914)
		(mid 101.302566 -223.136057)
		(end 101.489764 -223.085914)
		(width 0.0889)
		(layer "B.Cu")
		(net "TP_CPU1_BR23")
	)
	(arc
		(start 104.687116 -224.389442)
		(mid 104.734795 -224.572342)
		(end 104.865678 -224.70872)
		(width 0.0889)
		(layer "B.Cu")
		(net "TP_CPU1_BR23")
	)
	(arc
		(start 107.976162 -230.086662)
		(mid 108.023841 -230.269562)
		(end 108.154724 -230.40594)
		(width 0.0889)
		(layer "B.Cu")
		(net "TP_CPU1_BR23")
	)
	(arc
		(start 105.626916 -226.017328)
		(mid 105.674595 -226.200228)
		(end 105.805478 -226.336606)
		(width 0.0889)
		(layer "B.Cu")
		(net "TP_CPU1_BR23")
	)
	(arc
		(start 103.934768 -223.085914)
		(mid 104.138073 -223.28678)
		(end 104.217216 -223.561402)
		(width 0.0889)
		(layer "B.Cu")
		(net "TP_CPU1_BR23")
	)
	(arc
		(start 87.018368 -223.085914)
		(mid 87.205566 -223.136057)
		(end 87.392764 -223.085914)
		(width 0.0889)
		(layer "B.Cu")
		(net "TP_CPU1_BR23")
	)
	(arc
		(start 88.897968 -223.085914)
		(mid 89.085166 -223.136057)
		(end 89.272364 -223.085914)
		(width 0.0889)
		(layer "B.Cu")
		(net "TP_CPU1_BR23")
	)
	(arc
		(start 108.163614 -230.41102)
		(mid 108.350812 -230.461163)
		(end 108.53801 -230.41102)
		(width 0.0889)
		(layer "B.Cu")
		(net "TP_CPU1_BR23")
	)
	(arc
		(start 86.452964 -223.085914)
		(mid 86.735666 -223.010172)
		(end 87.018368 -223.085914)
		(width 0.0889)
		(layer "B.Cu")
		(net "TP_CPU1_BR23")
	)
	(arc
		(start 104.874568 -224.7138)
		(mid 105.077391 -224.914031)
		(end 105.156762 -225.187764)
		(width 0.0889)
		(layer "B.Cu")
		(net "TP_CPU1_BR23")
	)
	(arc
		(start 97.356168 -223.085914)
		(mid 97.543366 -223.136057)
		(end 97.730564 -223.085914)
		(width 0.0889)
		(layer "B.Cu")
		(net "TP_CPU1_BR23")
	)
	(arc
		(start 109.581188 -231.229662)
		(mid 109.782536 -231.435869)
		(end 109.856016 -231.714548)
		(width 0.0889)
		(layer "B.Cu")
		(net "TP_CPU1_BR23")
	)
	(arc
		(start 106.566716 -227.64496)
		(mid 106.614395 -227.82786)
		(end 106.745278 -227.964238)
		(width 0.0889)
		(layer "B.Cu")
		(net "TP_CPU1_BR23")
	)
	(arc
		(start 96.416368 -223.085914)
		(mid 96.603566 -223.136057)
		(end 96.790764 -223.085914)
		(width 0.0889)
		(layer "B.Cu")
		(net "TP_CPU1_BR23")
	)
	(arc
		(start 93.596968 -223.085914)
		(mid 93.784166 -223.136057)
		(end 93.971364 -223.085914)
		(width 0.0889)
		(layer "B.Cu")
		(net "TP_CPU1_BR23")
	)
	(arc
		(start 89.272364 -223.085914)
		(mid 89.555066 -223.010172)
		(end 89.837768 -223.085914)
		(width 0.0889)
		(layer "B.Cu")
		(net "TP_CPU1_BR23")
	)
	(arc
		(start 109.385862 -230.909114)
		(mid 109.438132 -231.091479)
		(end 109.57306 -231.224836)
		(width 0.0889)
		(layer "B.Cu")
		(net "TP_CPU1_BR23")
	)
	(arc
		(start 104.217216 -223.575626)
		(mid 104.264895 -223.758526)
		(end 104.395778 -223.894904)
		(width 0.0889)
		(layer "B.Cu")
		(net "TP_CPU1_BR23")
	)
	(arc
		(start 109.103414 -230.41102)
		(mid 109.306412 -230.611189)
		(end 109.385862 -230.884984)
		(width 0.0889)
		(layer "B.Cu")
		(net "TP_CPU1_BR23")
	)
	(arc
		(start 86.078568 -223.085914)
		(mid 86.265766 -223.136057)
		(end 86.452964 -223.085914)
		(width 0.0889)
		(layer "B.Cu")
		(net "TP_CPU1_BR23")
	)
	(arc
		(start 99.624896 -223.077278)
		(mid 99.901337 -223.010112)
		(end 100.175568 -223.085914)
		(width 0.0889)
		(layer "B.Cu")
		(net "TP_CPU1_BR23")
	)
	(arc
		(start 102.429564 -223.085914)
		(mid 102.712266 -223.010172)
		(end 102.994968 -223.085914)
		(width 0.0889)
		(layer "B.Cu")
		(net "TP_CPU1_BR23")
	)
	(arc
		(start 103.384096 -223.077278)
		(mid 103.660537 -223.010112)
		(end 103.934768 -223.085914)
		(width 0.0889)
		(layer "B.Cu")
		(net "TP_CPU1_BR23")
	)
	(arc
		(start 87.403178 -223.079818)
		(mid 87.68161 -223.010004)
		(end 87.958422 -223.085914)
		(width 0.0889)
		(layer "B.Cu")
		(net "TP_CPU1_BR23")
	)
	(arc
		(start 95.476568 -223.085914)
		(mid 95.663766 -223.136057)
		(end 95.850964 -223.085914)
		(width 0.0889)
		(layer "B.Cu")
		(net "TP_CPU1_BR23")
	)
	(arc
		(start 102.994968 -223.085914)
		(mid 103.182166 -223.136057)
		(end 103.369364 -223.085914)
		(width 0.0889)
		(layer "B.Cu")
		(net "TP_CPU1_BR23")
	)
	(arc
		(start 98.670364 -223.085914)
		(mid 98.953066 -223.010172)
		(end 99.235768 -223.085914)
		(width 0.0889)
		(layer "B.Cu")
		(net "TP_CPU1_BR23")
	)
	(arc
		(start 102.055168 -223.085914)
		(mid 102.242366 -223.136057)
		(end 102.429564 -223.085914)
		(width 0.0889)
		(layer "B.Cu")
		(net "TP_CPU1_BR23")
	)
	(arc
		(start 89.837768 -223.085914)
		(mid 90.024966 -223.136057)
		(end 90.212164 -223.085914)
		(width 0.0889)
		(layer "B.Cu")
		(net "TP_CPU1_BR23")
	)
	(arc
		(start 106.754168 -227.969318)
		(mid 106.95545 -228.166805)
		(end 107.036362 -228.436932)
		(width 0.0889)
		(layer "B.Cu")
		(net "TP_CPU1_BR23")
	)
	(arc
		(start 100.175568 -223.085914)
		(mid 100.362766 -223.136057)
		(end 100.549964 -223.085914)
		(width 0.0889)
		(layer "B.Cu")
		(net "TP_CPU1_BR23")
	)
	(arc
		(start 100.549964 -223.085914)
		(mid 100.832666 -223.010172)
		(end 101.115368 -223.085914)
		(width 0.0889)
		(layer "B.Cu")
		(net "TP_CPU1_BR23")
	)
	(arc
		(start 90.226896 -223.077278)
		(mid 90.503337 -223.010112)
		(end 90.777568 -223.085914)
		(width 0.0889)
		(layer "B.Cu")
		(net "TP_CPU1_BR23")
	)
	(arc
		(start 109.856016 -231.714548)
		(mid 109.903695 -231.897448)
		(end 110.034578 -232.033826)
		(width 0.0889)
		(layer "B.Cu")
		(net "TP_CPU1_BR23")
	)
	(arc
		(start 91.151964 -223.085914)
		(mid 91.434666 -223.010172)
		(end 91.717368 -223.085914)
		(width 0.0889)
		(layer "B.Cu")
		(net "TP_CPU1_BR23")
	)
	(arc
		(start 90.777568 -223.085914)
		(mid 90.964766 -223.136057)
		(end 91.151964 -223.085914)
		(width 0.0889)
		(layer "B.Cu")
		(net "TP_CPU1_BR23")
	)
	(arc
		(start 101.504496 -223.077278)
		(mid 101.780937 -223.010112)
		(end 102.055168 -223.085914)
		(width 0.0889)
		(layer "B.Cu")
		(net "TP_CPU1_BR23")
	)
	(arc
		(start 99.235768 -223.085914)
		(mid 99.422966 -223.136057)
		(end 99.610164 -223.085914)
		(width 0.0889)
		(layer "B.Cu")
		(net "TP_CPU1_BR23")
	)
	(arc
		(start 85.873082 -223.015302)
		(mid 85.973565 -223.038645)
		(end 86.068154 -223.079818)
		(width 0.0889)
		(layer "B.Cu")
		(net "TP_CPU1_BR23")
	)
	(arc
		(start 107.506516 -229.272846)
		(mid 107.554195 -229.455746)
		(end 107.685078 -229.592124)
		(width 0.0889)
		(layer "B.Cu")
		(net "TP_CPU1_BR23")
	)
	(arc
		(start 108.53801 -230.41102)
		(mid 108.812209 -230.335185)
		(end 109.088682 -230.402384)
		(width 0.0889)
		(layer "B.Cu")
		(net "TP_CPU1_BR23")
	)
	(arc
		(start 107.693968 -229.597204)
		(mid 107.896791 -229.797435)
		(end 107.976162 -230.071168)
		(width 0.0889)
		(layer "B.Cu")
		(net "TP_CPU1_BR23")
	)
	(arc
		(start 105.344214 -225.527616)
		(mid 105.547695 -225.72842)
		(end 105.626916 -226.003104)
		(width 0.0889)
		(layer "B.Cu")
		(net "TP_CPU1_BR23")
	)
	(arc
		(start 87.958422 -223.085914)
		(mid 88.140673 -223.136025)
		(end 88.324182 -223.09074)
		(width 0.0889)
		(layer "B.Cu")
		(net "TP_CPU1_BR23")
	)
	(arc
		(start 92.106496 -223.077278)
		(mid 92.382937 -223.010112)
		(end 92.657168 -223.085914)
		(width 0.0889)
		(layer "B.Cu")
		(net "TP_CPU1_BR23")
	)
	(arc
		(start 98.295968 -223.085914)
		(mid 98.483166 -223.136057)
		(end 98.670364 -223.085914)
		(width 0.0889)
		(layer "B.Cu")
		(net "TP_CPU1_BR23")
	)
	(arc
		(start 110.043468 -232.038906)
		(mid 110.201956 -232.087839)
		(end 110.366048 -232.063544)
		(width 0.0889)
		(layer "B.Cu")
		(net "TP_CPU1_BR23")
	)
	(arc
		(start 88.347296 -223.077278)
		(mid 88.623737 -223.010112)
		(end 88.897968 -223.085914)
		(width 0.0889)
		(layer "B.Cu")
		(net "TP_CPU1_BR23")
	)
	(arc
		(start 107.036362 -228.45903)
		(mid 107.084041 -228.64193)
		(end 107.214924 -228.778308)
		(width 0.0889)
		(layer "B.Cu")
		(net "TP_CPU1_BR23")
	)
	(arc
		(start 93.986096 -223.077278)
		(mid 94.262537 -223.010112)
		(end 94.536768 -223.085914)
		(width 0.0889)
		(layer "B.Cu")
		(net "TP_CPU1_BR23")
	)
	(arc
		(start 106.096816 -226.831144)
		(mid 106.144495 -227.014044)
		(end 106.275378 -227.150422)
		(width 0.0889)
		(layer "B.Cu")
		(net "TP_CPU1_BR23")
	)
	(arc
		(start 107.22991 -228.786944)
		(mid 107.432497 -228.993295)
		(end 107.506516 -229.272846)
		(width 0.0889)
		(layer "B.Cu")
		(net "TP_CPU1_BR23")
	)
	(arc
		(start 105.820464 -226.345242)
		(mid 106.022877 -226.551655)
		(end 106.096816 -226.831144)
		(width 0.0889)
		(layer "B.Cu")
		(net "TP_CPU1_BR23")
	)
	(arc
		(start 95.865696 -223.077278)
		(mid 96.142137 -223.010112)
		(end 96.416368 -223.085914)
		(width 0.0889)
		(layer "B.Cu")
		(net "TP_CPU1_BR23")
	)
	(arc
		(start 91.717368 -223.085914)
		(mid 91.904566 -223.136057)
		(end 92.091764 -223.085914)
		(width 0.0889)
		(layer "B.Cu")
		(net "TP_CPU1_BR23")
	)
	(arc
		(start 105.156762 -225.203258)
		(mid 105.204441 -225.386158)
		(end 105.335324 -225.522536)
		(width 0.0889)
		(layer "B.Cu")
		(net "TP_CPU1_BR23")
	)
	(arc
		(start 106.284268 -227.155502)
		(mid 106.488603 -227.358107)
		(end 106.566716 -227.635054)
		(width 0.0889)
		(layer "B.Cu")
		(net "TP_CPU1_BR23")
	)
	(arc
		(start 93.031564 -223.085914)
		(mid 93.314266 -223.010172)
		(end 93.596968 -223.085914)
		(width 0.0889)
		(layer "B.Cu")
		(net "TP_CPU1_BR23")
	)
	(arc
		(start 94.911164 -223.085914)
		(mid 95.193866 -223.010172)
		(end 95.476568 -223.085914)
		(width 0.0889)
		(layer "B.Cu")
		(net "TP_CPU1_BR23")
	)
	(segment
		(start 122.62612 -154.181048)
		(end 122.62612 -150.746968)
		(width 0.127)
		(layer "In2.Cu")
		(net "TP_CPU1_BR23")
	)
	(segment
		(start 123.52274 -123.327668)
		(end 123.52274 -122.123708)
		(width 0.127)
		(layer "In2.Cu")
		(net "TP_CPU1_BR23")
	)
	(segment
		(start 123.52274 -122.123708)
		(end 122.90044 -121.501408)
		(width 0.127)
		(layer "In2.Cu")
		(net "TP_CPU1_BR23")
	)
	(segment
		(start 122.62612 -150.746968)
		(end 124.63526 -148.737828)
		(width 0.127)
		(layer "In2.Cu")
		(net "TP_CPU1_BR23")
	)
	(segment
		(start 122.90044 -121.501408)
		(end 122.90044 -117.163088)
		(width 0.127)
		(layer "In2.Cu")
		(net "TP_CPU1_BR23")
	)
	(segment
		(start 123.00966 -139.885928)
		(end 123.00966 -123.840748)
		(width 0.127)
		(layer "In2.Cu")
		(net "TP_CPU1_BR23")
	)
	(segment
		(start 122.90044 -117.163088)
		(end 124.85878 -115.204748)
		(width 0.127)
		(layer "In2.Cu")
		(net "TP_CPU1_BR23")
	)
	(segment
		(start 124.63526 -148.737828)
		(end 124.63526 -141.511528)
		(width 0.127)
		(layer "In2.Cu")
		(net "TP_CPU1_BR23")
	)
	(segment
		(start 124.85878 -104.305608)
		(end 125.21438 -103.950008)
		(width 0.127)
		(layer "In2.Cu")
		(net "TP_CPU1_BR23")
	)
	(segment
		(start 124.63526 -141.511528)
		(end 123.00966 -139.885928)
		(width 0.127)
		(layer "In2.Cu")
		(net "TP_CPU1_BR23")
	)
	(segment
		(start 124.85878 -115.204748)
		(end 124.85878 -104.305608)
		(width 0.127)
		(layer "In2.Cu")
		(net "TP_CPU1_BR23")
	)
	(segment
		(start 123.00966 -123.840748)
		(end 123.52274 -123.327668)
		(width 0.127)
		(layer "In2.Cu")
		(net "TP_CPU1_BR23")
	)
	(segment
		(start 358.170734 -232.250488)
		(end 358.170734 -231.714548)
		(width 0.12954)
		(layer "F.Cu")
		(net "TP_CPU0_BR23")
	)
	(via
		(at 358.170734 -231.714548)
		(size 0.4572)
		(drill 0.2032)
		(layers "F.Cu" "B.Cu")
		(net "TP_CPU0_BR23")
	)
	(via
		(at 329.90282 -219.573094)
		(size 0.6604)
		(drill 0.3302)
		(layers "F.Cu" "B.Cu")
		(net "TP_CPU0_BR23")
	)
	(segment
		(start 353.760532 -226.345242)
		(end 353.754436 -226.341686)
		(width 0.0889)
		(layer "B.Cu")
		(net "TP_CPU0_BR23")
	)
	(segment
		(start 332.754478 -221.826582)
		(end 332.527656 -221.59976)
		(width 0.12954)
		(layer "B.Cu")
		(net "TP_CPU0_BR23")
	)
	(segment
		(start 358.170734 -231.714548)
		(end 357.75138 -231.494076)
		(width 0.0889)
		(layer "B.Cu")
		(net "TP_CPU0_BR23")
	)
	(segment
		(start 356.103682 -230.41102)
		(end 356.094792 -230.40594)
		(width 0.0889)
		(layer "B.Cu")
		(net "TP_CPU0_BR23")
	)
	(segment
		(start 357.32593 -230.909114)
		(end 357.32593 -230.884984)
		(width 0.0889)
		(layer "B.Cu")
		(net "TP_CPU0_BR23")
	)
	(segment
		(start 345.685364 -223.077278)
		(end 345.670632 -223.085914)
		(width 0.0889)
		(layer "B.Cu")
		(net "TP_CPU0_BR23")
	)
	(segment
		(start 338.166964 -223.077278)
		(end 338.152232 -223.085914)
		(width 0.0889)
		(layer "B.Cu")
		(net "TP_CPU0_BR23")
	)
	(segment
		(start 353.754436 -226.341686)
		(end 353.745546 -226.336606)
		(width 0.0889)
		(layer "B.Cu")
		(net "TP_CPU0_BR23")
	)
	(segment
		(start 352.627184 -224.389442)
		(end 352.627184 -224.379536)
		(width 0.0889)
		(layer "B.Cu")
		(net "TP_CPU0_BR23")
	)
	(segment
		(start 353.284282 -225.527616)
		(end 353.275392 -225.522536)
		(width 0.0889)
		(layer "B.Cu")
		(net "TP_CPU0_BR23")
	)
	(segment
		(start 334.018636 -223.085914)
		(end 334.008222 -223.079818)
		(width 0.0889)
		(layer "B.Cu")
		(net "TP_CPU0_BR23")
	)
	(segment
		(start 333.722726 -222.924878)
		(end 333.722726 -222.420434)
		(width 0.12954)
		(layer "B.Cu")
		(net "TP_CPU0_BR23")
	)
	(segment
		(start 347.564964 -223.077278)
		(end 347.550232 -223.085914)
		(width 0.0889)
		(layer "B.Cu")
		(net "TP_CPU0_BR23")
	)
	(segment
		(start 354.694236 -227.969318)
		(end 354.685346 -227.964238)
		(width 0.0889)
		(layer "B.Cu")
		(net "TP_CPU0_BR23")
	)
	(segment
		(start 333.722726 -222.420434)
		(end 333.128874 -221.826582)
		(width 0.12954)
		(layer "B.Cu")
		(net "TP_CPU0_BR23")
	)
	(segment
		(start 354.506784 -227.64496)
		(end 354.506784 -227.635054)
		(width 0.0889)
		(layer "B.Cu")
		(net "TP_CPU0_BR23")
	)
	(segment
		(start 340.046564 -223.077278)
		(end 340.031832 -223.085914)
		(width 0.0889)
		(layer "B.Cu")
		(net "TP_CPU0_BR23")
	)
	(segment
		(start 352.814636 -224.7138)
		(end 352.805746 -224.70872)
		(width 0.0889)
		(layer "B.Cu")
		(net "TP_CPU0_BR23")
	)
	(segment
		(start 341.926164 -223.077278)
		(end 341.911432 -223.085914)
		(width 0.0889)
		(layer "B.Cu")
		(net "TP_CPU0_BR23")
	)
	(segment
		(start 353.566984 -226.017328)
		(end 353.566984 -226.003104)
		(width 0.0889)
		(layer "B.Cu")
		(net "TP_CPU0_BR23")
	)
	(segment
		(start 354.224336 -227.155502)
		(end 354.215446 -227.150422)
		(width 0.0889)
		(layer "B.Cu")
		(net "TP_CPU0_BR23")
	)
	(segment
		(start 355.169978 -228.786944)
		(end 355.163882 -228.783388)
		(width 0.0889)
		(layer "B.Cu")
		(net "TP_CPU0_BR23")
	)
	(segment
		(start 351.324164 -223.077278)
		(end 351.309432 -223.085914)
		(width 0.0889)
		(layer "B.Cu")
		(net "TP_CPU0_BR23")
	)
	(segment
		(start 355.91623 -230.086662)
		(end 355.91623 -230.071168)
		(width 0.0889)
		(layer "B.Cu")
		(net "TP_CPU0_BR23")
	)
	(segment
		(start 336.272632 -223.085914)
		(end 336.26425 -223.09074)
		(width 0.0889)
		(layer "B.Cu")
		(net "TP_CPU0_BR23")
	)
	(segment
		(start 333.81315 -223.015302)
		(end 333.722726 -222.924878)
		(width 0.0889)
		(layer "B.Cu")
		(net "TP_CPU0_BR23")
	)
	(segment
		(start 352.344736 -223.899984)
		(end 352.335846 -223.894904)
		(width 0.0889)
		(layer "B.Cu")
		(net "TP_CPU0_BR23")
	)
	(segment
		(start 355.163882 -228.783388)
		(end 355.154992 -228.778308)
		(width 0.0889)
		(layer "B.Cu")
		(net "TP_CPU0_BR23")
	)
	(segment
		(start 336.287364 -223.077278)
		(end 336.272632 -223.085914)
		(width 0.0889)
		(layer "B.Cu")
		(net "TP_CPU0_BR23")
	)
	(segment
		(start 331.929486 -221.59976)
		(end 329.90282 -219.573094)
		(width 0.12954)
		(layer "B.Cu")
		(net "TP_CPU0_BR23")
	)
	(segment
		(start 357.521256 -231.229662)
		(end 357.513128 -231.224836)
		(width 0.0889)
		(layer "B.Cu")
		(net "TP_CPU0_BR23")
	)
	(segment
		(start 349.444564 -223.077278)
		(end 349.429832 -223.085914)
		(width 0.0889)
		(layer "B.Cu")
		(net "TP_CPU0_BR23")
	)
	(segment
		(start 357.043482 -230.41102)
		(end 357.02875 -230.402384)
		(width 0.0889)
		(layer "B.Cu")
		(net "TP_CPU0_BR23")
	)
	(segment
		(start 335.343246 -223.079818)
		(end 335.332832 -223.085914)
		(width 0.0889)
		(layer "B.Cu")
		(net "TP_CPU0_BR23")
	)
	(segment
		(start 332.527656 -221.59976)
		(end 331.929486 -221.59976)
		(width 0.12954)
		(layer "B.Cu")
		(net "TP_CPU0_BR23")
	)
	(segment
		(start 353.09683 -225.203258)
		(end 353.09683 -225.187764)
		(width 0.0889)
		(layer "B.Cu")
		(net "TP_CPU0_BR23")
	)
	(segment
		(start 333.128874 -221.826582)
		(end 332.754478 -221.826582)
		(width 0.12954)
		(layer "B.Cu")
		(net "TP_CPU0_BR23")
	)
	(segment
		(start 354.97643 -228.45903)
		(end 354.97643 -228.436932)
		(width 0.0889)
		(layer "B.Cu")
		(net "TP_CPU0_BR23")
	)
	(segment
		(start 355.634036 -229.597204)
		(end 355.625146 -229.592124)
		(width 0.0889)
		(layer "B.Cu")
		(net "TP_CPU0_BR23")
	)
	(segment
		(start 352.157284 -223.575626)
		(end 352.157284 -223.561402)
		(width 0.0889)
		(layer "B.Cu")
		(net "TP_CPU0_BR23")
	)
	(segment
		(start 343.805764 -223.077278)
		(end 343.791032 -223.085914)
		(width 0.0889)
		(layer "B.Cu")
		(net "TP_CPU0_BR23")
	)
	(arc
		(start 354.215446 -227.150422)
		(mid 354.084532 -227.014062)
		(end 354.036884 -226.831144)
		(width 0.0889)
		(layer "B.Cu")
		(net "TP_CPU0_BR23")
	)
	(arc
		(start 348.115636 -223.085914)
		(mid 347.841407 -223.009989)
		(end 347.564964 -223.077278)
		(width 0.0889)
		(layer "B.Cu")
		(net "TP_CPU0_BR23")
	)
	(arc
		(start 350.369632 -223.085914)
		(mid 350.182434 -223.136057)
		(end 349.995236 -223.085914)
		(width 0.0889)
		(layer "B.Cu")
		(net "TP_CPU0_BR23")
	)
	(arc
		(start 336.838036 -223.085914)
		(mid 336.563807 -223.009989)
		(end 336.287364 -223.077278)
		(width 0.0889)
		(layer "B.Cu")
		(net "TP_CPU0_BR23")
	)
	(arc
		(start 357.513128 -231.224836)
		(mid 357.378195 -231.091482)
		(end 357.32593 -230.909114)
		(width 0.0889)
		(layer "B.Cu")
		(net "TP_CPU0_BR23")
	)
	(arc
		(start 343.791032 -223.085914)
		(mid 343.603834 -223.136057)
		(end 343.416636 -223.085914)
		(width 0.0889)
		(layer "B.Cu")
		(net "TP_CPU0_BR23")
	)
	(arc
		(start 339.657436 -223.085914)
		(mid 339.374734 -223.010172)
		(end 339.092032 -223.085914)
		(width 0.0889)
		(layer "B.Cu")
		(net "TP_CPU0_BR23")
	)
	(arc
		(start 341.537036 -223.085914)
		(mid 341.254334 -223.010172)
		(end 340.971632 -223.085914)
		(width 0.0889)
		(layer "B.Cu")
		(net "TP_CPU0_BR23")
	)
	(arc
		(start 345.296236 -223.085914)
		(mid 345.013534 -223.010172)
		(end 344.730832 -223.085914)
		(width 0.0889)
		(layer "B.Cu")
		(net "TP_CPU0_BR23")
	)
	(arc
		(start 351.874836 -223.085914)
		(mid 351.600607 -223.009989)
		(end 351.324164 -223.077278)
		(width 0.0889)
		(layer "B.Cu")
		(net "TP_CPU0_BR23")
	)
	(arc
		(start 334.393032 -223.085914)
		(mid 334.205834 -223.136057)
		(end 334.018636 -223.085914)
		(width 0.0889)
		(layer "B.Cu")
		(net "TP_CPU0_BR23")
	)
	(arc
		(start 356.478078 -230.41102)
		(mid 356.29088 -230.461163)
		(end 356.103682 -230.41102)
		(width 0.0889)
		(layer "B.Cu")
		(net "TP_CPU0_BR23")
	)
	(arc
		(start 343.416636 -223.085914)
		(mid 343.133934 -223.010172)
		(end 342.851232 -223.085914)
		(width 0.0889)
		(layer "B.Cu")
		(net "TP_CPU0_BR23")
	)
	(arc
		(start 337.212432 -223.085914)
		(mid 337.025234 -223.136057)
		(end 336.838036 -223.085914)
		(width 0.0889)
		(layer "B.Cu")
		(net "TP_CPU0_BR23")
	)
	(arc
		(start 354.506784 -227.635054)
		(mid 354.428673 -227.358105)
		(end 354.224336 -227.155502)
		(width 0.0889)
		(layer "B.Cu")
		(net "TP_CPU0_BR23")
	)
	(arc
		(start 337.777836 -223.085914)
		(mid 337.495134 -223.010172)
		(end 337.212432 -223.085914)
		(width 0.0889)
		(layer "B.Cu")
		(net "TP_CPU0_BR23")
	)
	(arc
		(start 336.26425 -223.09074)
		(mid 336.080742 -223.136018)
		(end 335.89849 -223.085914)
		(width 0.0889)
		(layer "B.Cu")
		(net "TP_CPU0_BR23")
	)
	(arc
		(start 340.597236 -223.085914)
		(mid 340.323007 -223.009989)
		(end 340.046564 -223.077278)
		(width 0.0889)
		(layer "B.Cu")
		(net "TP_CPU0_BR23")
	)
	(arc
		(start 353.09683 -225.187764)
		(mid 353.01746 -224.91403)
		(end 352.814636 -224.7138)
		(width 0.0889)
		(layer "B.Cu")
		(net "TP_CPU0_BR23")
	)
	(arc
		(start 355.446584 -229.272846)
		(mid 355.372593 -228.99328)
		(end 355.169978 -228.786944)
		(width 0.0889)
		(layer "B.Cu")
		(net "TP_CPU0_BR23")
	)
	(arc
		(start 347.550232 -223.085914)
		(mid 347.363034 -223.136057)
		(end 347.175836 -223.085914)
		(width 0.0889)
		(layer "B.Cu")
		(net "TP_CPU0_BR23")
	)
	(arc
		(start 356.094792 -230.40594)
		(mid 355.963878 -230.26958)
		(end 355.91623 -230.086662)
		(width 0.0889)
		(layer "B.Cu")
		(net "TP_CPU0_BR23")
	)
	(arc
		(start 344.730832 -223.085914)
		(mid 344.543634 -223.136057)
		(end 344.356436 -223.085914)
		(width 0.0889)
		(layer "B.Cu")
		(net "TP_CPU0_BR23")
	)
	(arc
		(start 338.717636 -223.085914)
		(mid 338.443407 -223.009989)
		(end 338.166964 -223.077278)
		(width 0.0889)
		(layer "B.Cu")
		(net "TP_CPU0_BR23")
	)
	(arc
		(start 347.175836 -223.085914)
		(mid 346.893134 -223.010172)
		(end 346.610432 -223.085914)
		(width 0.0889)
		(layer "B.Cu")
		(net "TP_CPU0_BR23")
	)
	(arc
		(start 349.055436 -223.085914)
		(mid 348.772734 -223.010172)
		(end 348.490032 -223.085914)
		(width 0.0889)
		(layer "B.Cu")
		(net "TP_CPU0_BR23")
	)
	(arc
		(start 357.75138 -231.494076)
		(mid 357.657355 -231.343553)
		(end 357.521256 -231.229662)
		(width 0.0889)
		(layer "B.Cu")
		(net "TP_CPU0_BR23")
	)
	(arc
		(start 340.031832 -223.085914)
		(mid 339.844634 -223.136057)
		(end 339.657436 -223.085914)
		(width 0.0889)
		(layer "B.Cu")
		(net "TP_CPU0_BR23")
	)
	(arc
		(start 353.275392 -225.522536)
		(mid 353.144478 -225.386176)
		(end 353.09683 -225.203258)
		(width 0.0889)
		(layer "B.Cu")
		(net "TP_CPU0_BR23")
	)
	(arc
		(start 335.332832 -223.085914)
		(mid 335.145634 -223.136057)
		(end 334.958436 -223.085914)
		(width 0.0889)
		(layer "B.Cu")
		(net "TP_CPU0_BR23")
	)
	(arc
		(start 357.02875 -230.402384)
		(mid 356.752275 -230.335064)
		(end 356.478078 -230.41102)
		(width 0.0889)
		(layer "B.Cu")
		(net "TP_CPU0_BR23")
	)
	(arc
		(start 355.154992 -228.778308)
		(mid 355.024078 -228.641948)
		(end 354.97643 -228.45903)
		(width 0.0889)
		(layer "B.Cu")
		(net "TP_CPU0_BR23")
	)
	(arc
		(start 349.429832 -223.085914)
		(mid 349.242634 -223.136057)
		(end 349.055436 -223.085914)
		(width 0.0889)
		(layer "B.Cu")
		(net "TP_CPU0_BR23")
	)
	(arc
		(start 354.036884 -226.831144)
		(mid 353.962968 -226.551642)
		(end 353.760532 -226.345242)
		(width 0.0889)
		(layer "B.Cu")
		(net "TP_CPU0_BR23")
	)
	(arc
		(start 346.610432 -223.085914)
		(mid 346.423234 -223.136057)
		(end 346.236036 -223.085914)
		(width 0.0889)
		(layer "B.Cu")
		(net "TP_CPU0_BR23")
	)
	(arc
		(start 352.335846 -223.894904)
		(mid 352.204932 -223.758544)
		(end 352.157284 -223.575626)
		(width 0.0889)
		(layer "B.Cu")
		(net "TP_CPU0_BR23")
	)
	(arc
		(start 345.670632 -223.085914)
		(mid 345.483434 -223.136057)
		(end 345.296236 -223.085914)
		(width 0.0889)
		(layer "B.Cu")
		(net "TP_CPU0_BR23")
	)
	(arc
		(start 355.625146 -229.592124)
		(mid 355.494232 -229.455764)
		(end 355.446584 -229.272846)
		(width 0.0889)
		(layer "B.Cu")
		(net "TP_CPU0_BR23")
	)
	(arc
		(start 334.958436 -223.085914)
		(mid 334.675734 -223.010172)
		(end 334.393032 -223.085914)
		(width 0.0889)
		(layer "B.Cu")
		(net "TP_CPU0_BR23")
	)
	(arc
		(start 354.685346 -227.964238)
		(mid 354.554432 -227.827878)
		(end 354.506784 -227.64496)
		(width 0.0889)
		(layer "B.Cu")
		(net "TP_CPU0_BR23")
	)
	(arc
		(start 352.627184 -224.379536)
		(mid 352.549073 -224.102587)
		(end 352.344736 -223.899984)
		(width 0.0889)
		(layer "B.Cu")
		(net "TP_CPU0_BR23")
	)
	(arc
		(start 335.89849 -223.085914)
		(mid 335.621677 -223.010078)
		(end 335.343246 -223.079818)
		(width 0.0889)
		(layer "B.Cu")
		(net "TP_CPU0_BR23")
	)
	(arc
		(start 349.995236 -223.085914)
		(mid 349.721007 -223.009989)
		(end 349.444564 -223.077278)
		(width 0.0889)
		(layer "B.Cu")
		(net "TP_CPU0_BR23")
	)
	(arc
		(start 350.935036 -223.085914)
		(mid 350.652334 -223.010172)
		(end 350.369632 -223.085914)
		(width 0.0889)
		(layer "B.Cu")
		(net "TP_CPU0_BR23")
	)
	(arc
		(start 341.911432 -223.085914)
		(mid 341.724234 -223.136057)
		(end 341.537036 -223.085914)
		(width 0.0889)
		(layer "B.Cu")
		(net "TP_CPU0_BR23")
	)
	(arc
		(start 342.476836 -223.085914)
		(mid 342.202607 -223.009989)
		(end 341.926164 -223.077278)
		(width 0.0889)
		(layer "B.Cu")
		(net "TP_CPU0_BR23")
	)
	(arc
		(start 352.157284 -223.561402)
		(mid 352.078143 -223.286779)
		(end 351.874836 -223.085914)
		(width 0.0889)
		(layer "B.Cu")
		(net "TP_CPU0_BR23")
	)
	(arc
		(start 340.971632 -223.085914)
		(mid 340.784434 -223.136057)
		(end 340.597236 -223.085914)
		(width 0.0889)
		(layer "B.Cu")
		(net "TP_CPU0_BR23")
	)
	(arc
		(start 339.092032 -223.085914)
		(mid 338.904834 -223.136057)
		(end 338.717636 -223.085914)
		(width 0.0889)
		(layer "B.Cu")
		(net "TP_CPU0_BR23")
	)
	(arc
		(start 346.236036 -223.085914)
		(mid 345.961807 -223.009989)
		(end 345.685364 -223.077278)
		(width 0.0889)
		(layer "B.Cu")
		(net "TP_CPU0_BR23")
	)
	(arc
		(start 353.745546 -226.336606)
		(mid 353.614632 -226.200246)
		(end 353.566984 -226.017328)
		(width 0.0889)
		(layer "B.Cu")
		(net "TP_CPU0_BR23")
	)
	(arc
		(start 352.805746 -224.70872)
		(mid 352.674832 -224.57236)
		(end 352.627184 -224.389442)
		(width 0.0889)
		(layer "B.Cu")
		(net "TP_CPU0_BR23")
	)
	(arc
		(start 348.490032 -223.085914)
		(mid 348.302834 -223.136057)
		(end 348.115636 -223.085914)
		(width 0.0889)
		(layer "B.Cu")
		(net "TP_CPU0_BR23")
	)
	(arc
		(start 344.356436 -223.085914)
		(mid 344.082207 -223.009989)
		(end 343.805764 -223.077278)
		(width 0.0889)
		(layer "B.Cu")
		(net "TP_CPU0_BR23")
	)
	(arc
		(start 354.97643 -228.436932)
		(mid 354.895519 -228.166804)
		(end 354.694236 -227.969318)
		(width 0.0889)
		(layer "B.Cu")
		(net "TP_CPU0_BR23")
	)
	(arc
		(start 342.851232 -223.085914)
		(mid 342.664034 -223.136057)
		(end 342.476836 -223.085914)
		(width 0.0889)
		(layer "B.Cu")
		(net "TP_CPU0_BR23")
	)
	(arc
		(start 334.008222 -223.079818)
		(mid 333.913644 -223.038611)
		(end 333.81315 -223.015302)
		(width 0.0889)
		(layer "B.Cu")
		(net "TP_CPU0_BR23")
	)
	(arc
		(start 353.566984 -226.003104)
		(mid 353.487765 -225.728419)
		(end 353.284282 -225.527616)
		(width 0.0889)
		(layer "B.Cu")
		(net "TP_CPU0_BR23")
	)
	(arc
		(start 338.152232 -223.085914)
		(mid 337.965034 -223.136057)
		(end 337.777836 -223.085914)
		(width 0.0889)
		(layer "B.Cu")
		(net "TP_CPU0_BR23")
	)
	(arc
		(start 357.32593 -230.884984)
		(mid 357.246481 -230.611188)
		(end 357.043482 -230.41102)
		(width 0.0889)
		(layer "B.Cu")
		(net "TP_CPU0_BR23")
	)
	(arc
		(start 351.309432 -223.085914)
		(mid 351.122234 -223.136057)
		(end 350.935036 -223.085914)
		(width 0.0889)
		(layer "B.Cu")
		(net "TP_CPU0_BR23")
	)
	(arc
		(start 355.91623 -230.071168)
		(mid 355.83686 -229.797434)
		(end 355.634036 -229.597204)
		(width 0.0889)
		(layer "B.Cu")
		(net "TP_CPU0_BR23")
	)
	(segment
		(start 25.632156 -179.163726)
		(end 25.632156 -180.129688)
		(width 0.254)
		(layer "F.Cu")
		(net "SW_PVNN_MAIN_CPU1_BST_R")
	)
	(segment
		(start 25.636474 -179.159408)
		(end 25.632156 -179.163726)
		(width 0.254)
		(layer "F.Cu")
		(net "SW_PVNN_MAIN_CPU1_BST_R")
	)
	(segment
		(start 435.431692 -180.21681)
		(end 435.43728 -180.211222)
		(width 0.254)
		(layer "F.Cu")
		(net "SW_PVNN_MAIN_CPU0_BST_R")
	)
	(segment
		(start 435.431692 -180.73116)
		(end 435.431692 -180.21681)
		(width 0.254)
		(layer "F.Cu")
		(net "SW_PVNN_MAIN_CPU0_BST_R")
	)
	(segment
		(start 435.43728 -180.211222)
		(end 435.43728 -179.790598)
		(width 0.254)
		(layer "F.Cu")
		(net "SW_PVNN_MAIN_CPU0_BST_R")
	)
	(via
		(at 214.762842 -147.860004)
		(size 0.508)
		(drill 0.254)
		(layers "F.Cu" "B.Cu")
		(net "PWRGD_DRAMPWRGD_CPU1_GH_LVC1_R2")
	)
	(via
		(at 225.50374 -147.940268)
		(size 0.508)
		(drill 0.254)
		(layers "F.Cu" "B.Cu")
		(net "PWRGD_DRAMPWRGD_CPU1_GH_LVC1_R2")
	)
	(via
		(at 204.65288 -109.957108)
		(size 0.508)
		(drill 0.254)
		(layers "F.Cu" "B.Cu")
		(net "PWRGD_DRAMPWRGD_CPU1_GH_LVC1_R2")
	)
	(via
		(at 210.969098 -188.26607)
		(size 0.508)
		(drill 0.254)
		(layers "F.Cu" "B.Cu")
		(net "PWRGD_DRAMPWRGD_CPU1_GH_LVC1_R2")
	)
	(via
		(at 209.930238 -187.77077)
		(size 0.6604)
		(drill 0.3302)
		(layers "F.Cu" "B.Cu")
		(net "PWRGD_DRAMPWRGD_CPU1_GH_LVC1_R2")
	)
	(segment
		(start 170.824398 -193.42608)
		(end 170.673268 -193.57721)
		(width 0.12954)
		(layer "B.Cu")
		(net "PWRGD_DRAMPWRGD_CPU1_GH_LVC1_R2")
	)
	(segment
		(start 210.969098 -188.26607)
		(end 210.473798 -187.77077)
		(width 0.12954)
		(layer "B.Cu")
		(net "PWRGD_DRAMPWRGD_CPU1_GH_LVC1_R2")
	)
	(segment
		(start 172.737272 -191.707008)
		(end 171.0182 -193.42608)
		(width 0.12954)
		(layer "B.Cu")
		(net "PWRGD_DRAMPWRGD_CPU1_GH_LVC1_R2")
	)
	(segment
		(start 209.930238 -187.77077)
		(end 208.479898 -186.32043)
		(width 0.12954)
		(layer "B.Cu")
		(net "PWRGD_DRAMPWRGD_CPU1_GH_LVC1_R2")
	)
	(segment
		(start 175.165258 -186.32043)
		(end 172.737272 -188.748416)
		(width 0.12954)
		(layer "B.Cu")
		(net "PWRGD_DRAMPWRGD_CPU1_GH_LVC1_R2")
	)
	(segment
		(start 172.737272 -188.748416)
		(end 172.737272 -191.707008)
		(width 0.12954)
		(layer "B.Cu")
		(net "PWRGD_DRAMPWRGD_CPU1_GH_LVC1_R2")
	)
	(segment
		(start 171.0182 -193.42608)
		(end 170.824398 -193.42608)
		(width 0.12954)
		(layer "B.Cu")
		(net "PWRGD_DRAMPWRGD_CPU1_GH_LVC1_R2")
	)
	(segment
		(start 204.65288 -109.957108)
		(end 204.65288 -110.673388)
		(width 0.12954)
		(layer "B.Cu")
		(net "PWRGD_DRAMPWRGD_CPU1_GH_LVC1_R2")
	)
	(segment
		(start 208.479898 -186.32043)
		(end 175.165258 -186.32043)
		(width 0.12954)
		(layer "B.Cu")
		(net "PWRGD_DRAMPWRGD_CPU1_GH_LVC1_R2")
	)
	(segment
		(start 204.65288 -110.673388)
		(end 204.850492 -110.871)
		(width 0.12954)
		(layer "B.Cu")
		(net "PWRGD_DRAMPWRGD_CPU1_GH_LVC1_R2")
	)
	(segment
		(start 170.673268 -193.57721)
		(end 170.673268 -195.613528)
		(width 0.12954)
		(layer "B.Cu")
		(net "PWRGD_DRAMPWRGD_CPU1_GH_LVC1_R2")
	)
	(segment
		(start 204.850492 -110.871)
		(end 205.434438 -110.871)
		(width 0.12954)
		(layer "B.Cu")
		(net "PWRGD_DRAMPWRGD_CPU1_GH_LVC1_R2")
	)
	(segment
		(start 210.473798 -187.77077)
		(end 209.930238 -187.77077)
		(width 0.12954)
		(layer "B.Cu")
		(net "PWRGD_DRAMPWRGD_CPU1_GH_LVC1_R2")
	)
	(segment
		(start 215.081358 -155.53817)
		(end 215.081358 -160.81629)
		(width 0.127)
		(layer "In2.Cu")
		(net "PWRGD_DRAMPWRGD_CPU1_GH_LVC1_R2")
	)
	(segment
		(start 214.570818 -148.052028)
		(end 214.570818 -155.02763)
		(width 0.127)
		(layer "In2.Cu")
		(net "PWRGD_DRAMPWRGD_CPU1_GH_LVC1_R2")
	)
	(segment
		(start 216.5477 -129.88544)
		(end 215.98636 -130.44678)
		(width 0.127)
		(layer "In2.Cu")
		(net "PWRGD_DRAMPWRGD_CPU1_GH_LVC1_R2")
	)
	(segment
		(start 215.9889 -124.0663)
		(end 215.9889 -127.267208)
		(width 0.127)
		(layer "In2.Cu")
		(net "PWRGD_DRAMPWRGD_CPU1_GH_LVC1_R2")
	)
	(segment
		(start 215.98636 -130.44678)
		(end 215.98636 -137.444988)
		(width 0.127)
		(layer "In2.Cu")
		(net "PWRGD_DRAMPWRGD_CPU1_GH_LVC1_R2")
	)
	(segment
		(start 204.65288 -109.957108)
		(end 204.66812 -109.972348)
		(width 0.127)
		(layer "In2.Cu")
		(net "PWRGD_DRAMPWRGD_CPU1_GH_LVC1_R2")
	)
	(segment
		(start 215.6714 -114.3508)
		(end 215.6714 -123.7488)
		(width 0.127)
		(layer "In2.Cu")
		(net "PWRGD_DRAMPWRGD_CPU1_GH_LVC1_R2")
	)
	(segment
		(start 214.762842 -147.860004)
		(end 214.570818 -148.052028)
		(width 0.127)
		(layer "In2.Cu")
		(net "PWRGD_DRAMPWRGD_CPU1_GH_LVC1_R2")
	)
	(segment
		(start 215.9889 -127.267208)
		(end 216.5477 -127.826008)
		(width 0.127)
		(layer "In2.Cu")
		(net "PWRGD_DRAMPWRGD_CPU1_GH_LVC1_R2")
	)
	(segment
		(start 216.5477 -127.826008)
		(end 216.5477 -129.88544)
		(width 0.127)
		(layer "In2.Cu")
		(net "PWRGD_DRAMPWRGD_CPU1_GH_LVC1_R2")
	)
	(segment
		(start 214.570818 -155.02763)
		(end 215.081358 -155.53817)
		(width 0.127)
		(layer "In2.Cu")
		(net "PWRGD_DRAMPWRGD_CPU1_GH_LVC1_R2")
	)
	(segment
		(start 215.6714 -123.7488)
		(end 215.9889 -124.0663)
		(width 0.127)
		(layer "In2.Cu")
		(net "PWRGD_DRAMPWRGD_CPU1_GH_LVC1_R2")
	)
	(segment
		(start 211.292948 -109.972348)
		(end 215.6714 -114.3508)
		(width 0.127)
		(layer "In2.Cu")
		(net "PWRGD_DRAMPWRGD_CPU1_GH_LVC1_R2")
	)
	(segment
		(start 215.98636 -137.444988)
		(end 225.50374 -146.962368)
		(width 0.127)
		(layer "In2.Cu")
		(net "PWRGD_DRAMPWRGD_CPU1_GH_LVC1_R2")
	)
	(segment
		(start 214.626698 -161.27095)
		(end 214.626698 -184.60847)
		(width 0.127)
		(layer "In2.Cu")
		(net "PWRGD_DRAMPWRGD_CPU1_GH_LVC1_R2")
	)
	(segment
		(start 204.66812 -109.972348)
		(end 211.292948 -109.972348)
		(width 0.127)
		(layer "In2.Cu")
		(net "PWRGD_DRAMPWRGD_CPU1_GH_LVC1_R2")
	)
	(segment
		(start 215.081358 -160.81629)
		(end 214.626698 -161.27095)
		(width 0.127)
		(layer "In2.Cu")
		(net "PWRGD_DRAMPWRGD_CPU1_GH_LVC1_R2")
	)
	(segment
		(start 225.50374 -146.962368)
		(end 225.50374 -147.940268)
		(width 0.127)
		(layer "In2.Cu")
		(net "PWRGD_DRAMPWRGD_CPU1_GH_LVC1_R2")
	)
	(segment
		(start 214.626698 -184.60847)
		(end 210.969098 -188.26607)
		(width 0.127)
		(layer "In2.Cu")
		(net "PWRGD_DRAMPWRGD_CPU1_GH_LVC1_R2")
	)
	(segment
		(start 225.50374 -147.940268)
		(end 225.238564 -147.675092)
		(width 0.127)
		(layer "In13.Cu")
		(net "PWRGD_DRAMPWRGD_CPU1_GH_LVC1_R2")
	)
	(segment
		(start 225.238564 -147.675092)
		(end 214.947754 -147.675092)
		(width 0.127)
		(layer "In13.Cu")
		(net "PWRGD_DRAMPWRGD_CPU1_GH_LVC1_R2")
	)
	(segment
		(start 214.947754 -147.675092)
		(end 214.762842 -147.860004)
		(width 0.127)
		(layer "In13.Cu")
		(net "PWRGD_DRAMPWRGD_CPU1_GH_LVC1_R2")
	)
	(via
		(at 224.86874 -187.056268)
		(size 0.508)
		(drill 0.254)
		(layers "F.Cu" "B.Cu")
		(net "PWRGD_DRAMPWRGD_CPU1_EF_LVC1_R2")
	)
	(via
		(at 172.183298 -188.498734)
		(size 0.508)
		(drill 0.254)
		(layers "F.Cu" "B.Cu")
		(net "PWRGD_DRAMPWRGD_CPU1_EF_LVC1_R2")
	)
	(via
		(at 201.061828 -110.579408)
		(size 0.508)
		(drill 0.254)
		(layers "F.Cu" "B.Cu")
		(net "PWRGD_DRAMPWRGD_CPU1_EF_LVC1_R2")
	)
	(segment
		(start 169.506138 -193.41084)
		(end 169.506138 -193.951606)
		(width 0.12954)
		(layer "B.Cu")
		(net "PWRGD_DRAMPWRGD_CPU1_EF_LVC1_R2")
	)
	(segment
		(start 168.540938 -192.114424)
		(end 168.540938 -192.61074)
		(width 0.12954)
		(layer "B.Cu")
		(net "PWRGD_DRAMPWRGD_CPU1_EF_LVC1_R2")
	)
	(segment
		(start 169.341038 -193.41084)
		(end 169.506138 -193.41084)
		(width 0.12954)
		(layer "B.Cu")
		(net "PWRGD_DRAMPWRGD_CPU1_EF_LVC1_R2")
	)
	(segment
		(start 169.72788 -195.570348)
		(end 168.236646 -195.570348)
		(width 0.12954)
		(layer "B.Cu")
		(net "PWRGD_DRAMPWRGD_CPU1_EF_LVC1_R2")
	)
	(segment
		(start 168.15308 -196.611748)
		(end 168.27246 -196.731128)
		(width 0.12954)
		(layer "B.Cu")
		(net "PWRGD_DRAMPWRGD_CPU1_EF_LVC1_R2")
	)
	(segment
		(start 172.183298 -188.498734)
		(end 172.183298 -189.963044)
		(width 0.12954)
		(layer "B.Cu")
		(net "PWRGD_DRAMPWRGD_CPU1_EF_LVC1_R2")
	)
	(segment
		(start 168.670732 -191.98463)
		(end 168.540938 -192.114424)
		(width 0.12954)
		(layer "B.Cu")
		(net "PWRGD_DRAMPWRGD_CPU1_EF_LVC1_R2")
	)
	(segment
		(start 201.061828 -109.86897)
		(end 201.061828 -110.579408)
		(width 0.12954)
		(layer "B.Cu")
		(net "PWRGD_DRAMPWRGD_CPU1_EF_LVC1_R2")
	)
	(segment
		(start 170.161712 -191.98463)
		(end 168.670732 -191.98463)
		(width 0.12954)
		(layer "B.Cu")
		(net "PWRGD_DRAMPWRGD_CPU1_EF_LVC1_R2")
	)
	(segment
		(start 169.93108 -194.376548)
		(end 169.93108 -195.367148)
		(width 0.12954)
		(layer "B.Cu")
		(net "PWRGD_DRAMPWRGD_CPU1_EF_LVC1_R2")
	)
	(segment
		(start 168.540938 -192.61074)
		(end 169.341038 -193.41084)
		(width 0.12954)
		(layer "B.Cu")
		(net "PWRGD_DRAMPWRGD_CPU1_EF_LVC1_R2")
	)
	(segment
		(start 169.506138 -193.951606)
		(end 169.93108 -194.376548)
		(width 0.12954)
		(layer "B.Cu")
		(net "PWRGD_DRAMPWRGD_CPU1_EF_LVC1_R2")
	)
	(segment
		(start 172.183298 -189.963044)
		(end 170.161712 -191.98463)
		(width 0.12954)
		(layer "B.Cu")
		(net "PWRGD_DRAMPWRGD_CPU1_EF_LVC1_R2")
	)
	(segment
		(start 169.93108 -195.367148)
		(end 169.72788 -195.570348)
		(width 0.12954)
		(layer "B.Cu")
		(net "PWRGD_DRAMPWRGD_CPU1_EF_LVC1_R2")
	)
	(segment
		(start 168.27246 -196.731128)
		(end 168.742868 -196.731128)
		(width 0.12954)
		(layer "B.Cu")
		(net "PWRGD_DRAMPWRGD_CPU1_EF_LVC1_R2")
	)
	(segment
		(start 168.15308 -195.653914)
		(end 168.15308 -196.611748)
		(width 0.12954)
		(layer "B.Cu")
		(net "PWRGD_DRAMPWRGD_CPU1_EF_LVC1_R2")
	)
	(segment
		(start 168.236646 -195.570348)
		(end 168.15308 -195.653914)
		(width 0.12954)
		(layer "B.Cu")
		(net "PWRGD_DRAMPWRGD_CPU1_EF_LVC1_R2")
	)
	(segment
		(start 224.86874 -146.938238)
		(end 224.86874 -187.056268)
		(width 0.127)
		(layer "In2.Cu")
		(net "PWRGD_DRAMPWRGD_CPU1_EF_LVC1_R2")
	)
	(segment
		(start 215.51138 -127.442468)
		(end 216.10066 -128.031748)
		(width 0.127)
		(layer "In2.Cu")
		(net "PWRGD_DRAMPWRGD_CPU1_EF_LVC1_R2")
	)
	(segment
		(start 215.51138 -124.24918)
		(end 215.51138 -127.442468)
		(width 0.127)
		(layer "In2.Cu")
		(net "PWRGD_DRAMPWRGD_CPU1_EF_LVC1_R2")
	)
	(segment
		(start 201.061828 -110.579408)
		(end 201.343768 -110.861348)
		(width 0.127)
		(layer "In2.Cu")
		(net "PWRGD_DRAMPWRGD_CPU1_EF_LVC1_R2")
	)
	(segment
		(start 209.692748 -110.861348)
		(end 212.1662 -113.3348)
		(width 0.127)
		(layer "In2.Cu")
		(net "PWRGD_DRAMPWRGD_CPU1_EF_LVC1_R2")
	)
	(segment
		(start 201.343768 -110.861348)
		(end 209.692748 -110.861348)
		(width 0.127)
		(layer "In2.Cu")
		(net "PWRGD_DRAMPWRGD_CPU1_EF_LVC1_R2")
	)
	(segment
		(start 214.503 -117.5258)
		(end 214.503 -123.2408)
		(width 0.127)
		(layer "In2.Cu")
		(net "PWRGD_DRAMPWRGD_CPU1_EF_LVC1_R2")
	)
	(segment
		(start 215.56472 -130.24866)
		(end 215.56472 -137.634218)
		(width 0.127)
		(layer "In2.Cu")
		(net "PWRGD_DRAMPWRGD_CPU1_EF_LVC1_R2")
	)
	(segment
		(start 216.10066 -128.031748)
		(end 216.10066 -129.71272)
		(width 0.127)
		(layer "In2.Cu")
		(net "PWRGD_DRAMPWRGD_CPU1_EF_LVC1_R2")
	)
	(segment
		(start 212.1662 -115.189)
		(end 214.503 -117.5258)
		(width 0.127)
		(layer "In2.Cu")
		(net "PWRGD_DRAMPWRGD_CPU1_EF_LVC1_R2")
	)
	(segment
		(start 214.503 -123.2408)
		(end 215.51138 -124.24918)
		(width 0.127)
		(layer "In2.Cu")
		(net "PWRGD_DRAMPWRGD_CPU1_EF_LVC1_R2")
	)
	(segment
		(start 215.56472 -137.634218)
		(end 224.86874 -146.938238)
		(width 0.127)
		(layer "In2.Cu")
		(net "PWRGD_DRAMPWRGD_CPU1_EF_LVC1_R2")
	)
	(segment
		(start 212.1662 -113.3348)
		(end 212.1662 -115.189)
		(width 0.127)
		(layer "In2.Cu")
		(net "PWRGD_DRAMPWRGD_CPU1_EF_LVC1_R2")
	)
	(segment
		(start 216.10066 -129.71272)
		(end 215.56472 -130.24866)
		(width 0.127)
		(layer "In2.Cu")
		(net "PWRGD_DRAMPWRGD_CPU1_EF_LVC1_R2")
	)
	(segment
		(start 224.38868 -187.536328)
		(end 224.38868 -189.220348)
		(width 0.127)
		(layer "In13.Cu")
		(net "PWRGD_DRAMPWRGD_CPU1_EF_LVC1_R2")
	)
	(segment
		(start 213.64448 -192.166748)
		(end 211.56168 -192.166748)
		(width 0.127)
		(layer "In13.Cu")
		(net "PWRGD_DRAMPWRGD_CPU1_EF_LVC1_R2")
	)
	(segment
		(start 173.519084 -187.162948)
		(end 172.183298 -188.498734)
		(width 0.127)
		(layer "In13.Cu")
		(net "PWRGD_DRAMPWRGD_CPU1_EF_LVC1_R2")
	)
	(segment
		(start 224.38868 -189.220348)
		(end 220.75648 -192.852548)
		(width 0.127)
		(layer "In13.Cu")
		(net "PWRGD_DRAMPWRGD_CPU1_EF_LVC1_R2")
	)
	(segment
		(start 211.56168 -192.166748)
		(end 209.85988 -190.464948)
		(width 0.127)
		(layer "In13.Cu")
		(net "PWRGD_DRAMPWRGD_CPU1_EF_LVC1_R2")
	)
	(segment
		(start 209.85988 -190.464948)
		(end 204.98308 -190.464948)
		(width 0.127)
		(layer "In13.Cu")
		(net "PWRGD_DRAMPWRGD_CPU1_EF_LVC1_R2")
	)
	(segment
		(start 220.75648 -192.852548)
		(end 214.33028 -192.852548)
		(width 0.127)
		(layer "In13.Cu")
		(net "PWRGD_DRAMPWRGD_CPU1_EF_LVC1_R2")
	)
	(segment
		(start 204.98308 -190.464948)
		(end 201.68108 -187.162948)
		(width 0.127)
		(layer "In13.Cu")
		(net "PWRGD_DRAMPWRGD_CPU1_EF_LVC1_R2")
	)
	(segment
		(start 201.68108 -187.162948)
		(end 173.519084 -187.162948)
		(width 0.127)
		(layer "In13.Cu")
		(net "PWRGD_DRAMPWRGD_CPU1_EF_LVC1_R2")
	)
	(segment
		(start 214.33028 -192.852548)
		(end 213.64448 -192.166748)
		(width 0.127)
		(layer "In13.Cu")
		(net "PWRGD_DRAMPWRGD_CPU1_EF_LVC1_R2")
	)
	(segment
		(start 224.86874 -187.056268)
		(end 224.38868 -187.536328)
		(width 0.127)
		(layer "In13.Cu")
		(net "PWRGD_DRAMPWRGD_CPU1_EF_LVC1_R2")
	)
	(segment
		(start 174.11573 -99.463098)
		(end 174.87138 -99.463098)
		(width 0.12954)
		(layer "F.Cu")
		(net "PWRGD_DRAMPWRGD_CPU1_CD_LVC1_R2")
	)
	(segment
		(start 174.09922 -99.479608)
		(end 174.11573 -99.463098)
		(width 0.12954)
		(layer "F.Cu")
		(net "PWRGD_DRAMPWRGD_CPU1_CD_LVC1_R2")
	)
	(segment
		(start 174.04588 -99.479608)
		(end 174.09922 -99.479608)
		(width 0.12954)
		(layer "F.Cu")
		(net "PWRGD_DRAMPWRGD_CPU1_CD_LVC1_R2")
	)
	(via
		(at 174.04588 -99.479608)
		(size 0.508)
		(drill 0.254)
		(layers "F.Cu" "B.Cu")
		(net "PWRGD_DRAMPWRGD_CPU1_CD_LVC1_R2")
	)
	(via
		(at 65.91554 -192.486788)
		(size 0.508)
		(drill 0.254)
		(layers "F.Cu" "B.Cu")
		(net "PWRGD_DRAMPWRGD_CPU1_CD_LVC1_R2")
	)
	(segment
		(start 64.637158 -194.504818)
		(end 65.364868 -195.232528)
		(width 0.12954)
		(layer "B.Cu")
		(net "PWRGD_DRAMPWRGD_CPU1_CD_LVC1_R2")
	)
	(segment
		(start 64.637158 -193.36258)
		(end 64.637158 -194.504818)
		(width 0.12954)
		(layer "B.Cu")
		(net "PWRGD_DRAMPWRGD_CPU1_CD_LVC1_R2")
	)
	(segment
		(start 65.91554 -192.486788)
		(end 65.039748 -193.36258)
		(width 0.12954)
		(layer "B.Cu")
		(net "PWRGD_DRAMPWRGD_CPU1_CD_LVC1_R2")
	)
	(segment
		(start 65.039748 -193.36258)
		(end 64.637158 -193.36258)
		(width 0.12954)
		(layer "B.Cu")
		(net "PWRGD_DRAMPWRGD_CPU1_CD_LVC1_R2")
	)
	(segment
		(start 142.54226 -122.794776)
		(end 145.75536 -126.007876)
		(width 0.127)
		(layer "In4.Cu")
		(net "PWRGD_DRAMPWRGD_CPU1_CD_LVC1_R2")
	)
	(segment
		(start 109.318806 -146.527774)
		(end 77.345032 -178.501548)
		(width 0.127)
		(layer "In4.Cu")
		(net "PWRGD_DRAMPWRGD_CPU1_CD_LVC1_R2")
	)
	(segment
		(start 143.066516 -130.681984)
		(end 127.220726 -146.527774)
		(width 0.127)
		(layer "In4.Cu")
		(net "PWRGD_DRAMPWRGD_CPU1_CD_LVC1_R2")
	)
	(segment
		(start 174.04588 -99.532948)
		(end 173.70552 -99.873308)
		(width 0.127)
		(layer "In4.Cu")
		(net "PWRGD_DRAMPWRGD_CPU1_CD_LVC1_R2")
	)
	(segment
		(start 173.70552 -99.873308)
		(end 158.91256 -99.873308)
		(width 0.127)
		(layer "In4.Cu")
		(net "PWRGD_DRAMPWRGD_CPU1_CD_LVC1_R2")
	)
	(segment
		(start 144.217644 -130.681984)
		(end 143.066516 -130.681984)
		(width 0.127)
		(layer "In4.Cu")
		(net "PWRGD_DRAMPWRGD_CPU1_CD_LVC1_R2")
	)
	(segment
		(start 54.41188 -191.609218)
		(end 54.41188 -192.827148)
		(width 0.127)
		(layer "In4.Cu")
		(net "PWRGD_DRAMPWRGD_CPU1_CD_LVC1_R2")
	)
	(segment
		(start 53.724556 -190.921894)
		(end 54.41188 -191.609218)
		(width 0.127)
		(layer "In4.Cu")
		(net "PWRGD_DRAMPWRGD_CPU1_CD_LVC1_R2")
	)
	(segment
		(start 49.17948 -187.721748)
		(end 52.379626 -190.921894)
		(width 0.127)
		(layer "In4.Cu")
		(net "PWRGD_DRAMPWRGD_CPU1_CD_LVC1_R2")
	)
	(segment
		(start 50.65268 -184.343548)
		(end 49.17948 -185.816748)
		(width 0.127)
		(layer "In4.Cu")
		(net "PWRGD_DRAMPWRGD_CPU1_CD_LVC1_R2")
	)
	(segment
		(start 70.77964 -180.584348)
		(end 67.9958 -180.584348)
		(width 0.127)
		(layer "In4.Cu")
		(net "PWRGD_DRAMPWRGD_CPU1_CD_LVC1_R2")
	)
	(segment
		(start 67.9958 -180.584348)
		(end 67.451478 -181.12867)
		(width 0.127)
		(layer "In4.Cu")
		(net "PWRGD_DRAMPWRGD_CPU1_CD_LVC1_R2")
	)
	(segment
		(start 145.75536 -126.007876)
		(end 145.75536 -129.144268)
		(width 0.127)
		(layer "In4.Cu")
		(net "PWRGD_DRAMPWRGD_CPU1_CD_LVC1_R2")
	)
	(segment
		(start 49.17948 -185.816748)
		(end 49.17948 -187.721748)
		(width 0.127)
		(layer "In4.Cu")
		(net "PWRGD_DRAMPWRGD_CPU1_CD_LVC1_R2")
	)
	(segment
		(start 149.76856 -103.546148)
		(end 142.54226 -110.772448)
		(width 0.127)
		(layer "In4.Cu")
		(net "PWRGD_DRAMPWRGD_CPU1_CD_LVC1_R2")
	)
	(segment
		(start 67.451478 -181.12867)
		(end 66.457322 -181.12867)
		(width 0.127)
		(layer "In4.Cu")
		(net "PWRGD_DRAMPWRGD_CPU1_CD_LVC1_R2")
	)
	(segment
		(start 64.257936 -193.157348)
		(end 64.928496 -192.486788)
		(width 0.127)
		(layer "In4.Cu")
		(net "PWRGD_DRAMPWRGD_CPU1_CD_LVC1_R2")
	)
	(segment
		(start 158.91256 -99.873308)
		(end 155.23972 -103.546148)
		(width 0.127)
		(layer "In4.Cu")
		(net "PWRGD_DRAMPWRGD_CPU1_CD_LVC1_R2")
	)
	(segment
		(start 52.379626 -190.921894)
		(end 53.724556 -190.921894)
		(width 0.127)
		(layer "In4.Cu")
		(net "PWRGD_DRAMPWRGD_CPU1_CD_LVC1_R2")
	)
	(segment
		(start 66.457322 -181.12867)
		(end 63.242444 -184.343548)
		(width 0.127)
		(layer "In4.Cu")
		(net "PWRGD_DRAMPWRGD_CPU1_CD_LVC1_R2")
	)
	(segment
		(start 174.04588 -99.479608)
		(end 174.04588 -99.532948)
		(width 0.127)
		(layer "In4.Cu")
		(net "PWRGD_DRAMPWRGD_CPU1_CD_LVC1_R2")
	)
	(segment
		(start 54.74208 -193.157348)
		(end 64.257936 -193.157348)
		(width 0.127)
		(layer "In4.Cu")
		(net "PWRGD_DRAMPWRGD_CPU1_CD_LVC1_R2")
	)
	(segment
		(start 145.75536 -129.144268)
		(end 144.217644 -130.681984)
		(width 0.127)
		(layer "In4.Cu")
		(net "PWRGD_DRAMPWRGD_CPU1_CD_LVC1_R2")
	)
	(segment
		(start 127.220726 -146.527774)
		(end 109.318806 -146.527774)
		(width 0.127)
		(layer "In4.Cu")
		(net "PWRGD_DRAMPWRGD_CPU1_CD_LVC1_R2")
	)
	(segment
		(start 142.54226 -110.772448)
		(end 142.54226 -122.794776)
		(width 0.127)
		(layer "In4.Cu")
		(net "PWRGD_DRAMPWRGD_CPU1_CD_LVC1_R2")
	)
	(segment
		(start 155.23972 -103.546148)
		(end 149.76856 -103.546148)
		(width 0.127)
		(layer "In4.Cu")
		(net "PWRGD_DRAMPWRGD_CPU1_CD_LVC1_R2")
	)
	(segment
		(start 64.928496 -192.486788)
		(end 65.91554 -192.486788)
		(width 0.127)
		(layer "In4.Cu")
		(net "PWRGD_DRAMPWRGD_CPU1_CD_LVC1_R2")
	)
	(segment
		(start 72.86244 -178.501548)
		(end 70.77964 -180.584348)
		(width 0.127)
		(layer "In4.Cu")
		(net "PWRGD_DRAMPWRGD_CPU1_CD_LVC1_R2")
	)
	(segment
		(start 63.242444 -184.343548)
		(end 50.65268 -184.343548)
		(width 0.127)
		(layer "In4.Cu")
		(net "PWRGD_DRAMPWRGD_CPU1_CD_LVC1_R2")
	)
	(segment
		(start 54.41188 -192.827148)
		(end 54.74208 -193.157348)
		(width 0.127)
		(layer "In4.Cu")
		(net "PWRGD_DRAMPWRGD_CPU1_CD_LVC1_R2")
	)
	(segment
		(start 77.345032 -178.501548)
		(end 72.86244 -178.501548)
		(width 0.127)
		(layer "In4.Cu")
		(net "PWRGD_DRAMPWRGD_CPU1_CD_LVC1_R2")
	)
	(via
		(at 94.48038 -173.708568)
		(size 0.508)
		(drill 0.254)
		(layers "F.Cu" "B.Cu")
		(net "PWRGD_DRAMPWRGD_CPU1_AB_LVC1_R2")
	)
	(via
		(at 154.86126 -102.314248)
		(size 0.508)
		(drill 0.254)
		(layers "F.Cu" "B.Cu")
		(net "PWRGD_DRAMPWRGD_CPU1_AB_LVC1_R2")
	)
	(via
		(at 62.353698 -191.88049)
		(size 0.508)
		(drill 0.254)
		(layers "F.Cu" "B.Cu")
		(net "PWRGD_DRAMPWRGD_CPU1_AB_LVC1_R2")
	)
	(via
		(at 155.75788 -166.284148)
		(size 0.508)
		(drill 0.254)
		(layers "F.Cu" "B.Cu")
		(net "PWRGD_DRAMPWRGD_CPU1_AB_LVC1_R2")
	)
	(segment
		(start 63.575946 -193.33464)
		(end 63.616078 -193.33464)
		(width 0.12954)
		(layer "B.Cu")
		(net "PWRGD_DRAMPWRGD_CPU1_AB_LVC1_R2")
	)
	(segment
		(start 155.75788 -166.284148)
		(end 101.9048 -166.284148)
		(width 0.12954)
		(layer "B.Cu")
		(net "PWRGD_DRAMPWRGD_CPU1_AB_LVC1_R2")
	)
	(segment
		(start 62.353698 -191.88049)
		(end 62.353698 -192.112392)
		(width 0.12954)
		(layer "B.Cu")
		(net "PWRGD_DRAMPWRGD_CPU1_AB_LVC1_R2")
	)
	(segment
		(start 101.9048 -166.284148)
		(end 94.48038 -173.708568)
		(width 0.12954)
		(layer "B.Cu")
		(net "PWRGD_DRAMPWRGD_CPU1_AB_LVC1_R2")
	)
	(segment
		(start 154.86126 -102.314248)
		(end 155.208478 -102.661466)
		(width 0.12954)
		(layer "B.Cu")
		(net "PWRGD_DRAMPWRGD_CPU1_AB_LVC1_R2")
	)
	(segment
		(start 63.104268 -194.35445)
		(end 63.616078 -193.84264)
		(width 0.12954)
		(layer "B.Cu")
		(net "PWRGD_DRAMPWRGD_CPU1_AB_LVC1_R2")
	)
	(segment
		(start 155.208478 -102.661466)
		(end 156.180028 -102.661466)
		(width 0.12954)
		(layer "B.Cu")
		(net "PWRGD_DRAMPWRGD_CPU1_AB_LVC1_R2")
	)
	(segment
		(start 62.353698 -192.112392)
		(end 63.575946 -193.33464)
		(width 0.12954)
		(layer "B.Cu")
		(net "PWRGD_DRAMPWRGD_CPU1_AB_LVC1_R2")
	)
	(segment
		(start 63.616078 -193.84264)
		(end 63.616078 -193.33464)
		(width 0.12954)
		(layer "B.Cu")
		(net "PWRGD_DRAMPWRGD_CPU1_AB_LVC1_R2")
	)
	(segment
		(start 63.104268 -195.410328)
		(end 63.104268 -194.35445)
		(width 0.12954)
		(layer "B.Cu")
		(net "PWRGD_DRAMPWRGD_CPU1_AB_LVC1_R2")
	)
	(segment
		(start 157.0228 -165.019228)
		(end 155.75788 -166.284148)
		(width 0.127)
		(layer "In2.Cu")
		(net "PWRGD_DRAMPWRGD_CPU1_AB_LVC1_R2")
	)
	(segment
		(start 155.55468 -108.306108)
		(end 158.70936 -111.460788)
		(width 0.127)
		(layer "In2.Cu")
		(net "PWRGD_DRAMPWRGD_CPU1_AB_LVC1_R2")
	)
	(segment
		(start 155.55468 -107.564428)
		(end 155.55468 -108.306108)
		(width 0.127)
		(layer "In2.Cu")
		(net "PWRGD_DRAMPWRGD_CPU1_AB_LVC1_R2")
	)
	(segment
		(start 160.7566 -118.100348)
		(end 160.52546 -118.331488)
		(width 0.127)
		(layer "In2.Cu")
		(net "PWRGD_DRAMPWRGD_CPU1_AB_LVC1_R2")
	)
	(segment
		(start 158.24708 -119.446548)
		(end 157.0228 -120.670828)
		(width 0.127)
		(layer "In2.Cu")
		(net "PWRGD_DRAMPWRGD_CPU1_AB_LVC1_R2")
	)
	(segment
		(start 160.52546 -118.946168)
		(end 160.02508 -119.446548)
		(width 0.127)
		(layer "In2.Cu")
		(net "PWRGD_DRAMPWRGD_CPU1_AB_LVC1_R2")
	)
	(segment
		(start 157.0228 -120.670828)
		(end 157.0228 -165.019228)
		(width 0.127)
		(layer "In2.Cu")
		(net "PWRGD_DRAMPWRGD_CPU1_AB_LVC1_R2")
	)
	(segment
		(start 154.86126 -102.314248)
		(end 154.86126 -106.871008)
		(width 0.127)
		(layer "In2.Cu")
		(net "PWRGD_DRAMPWRGD_CPU1_AB_LVC1_R2")
	)
	(segment
		(start 160.21558 -111.460788)
		(end 160.7566 -112.001808)
		(width 0.127)
		(layer "In2.Cu")
		(net "PWRGD_DRAMPWRGD_CPU1_AB_LVC1_R2")
	)
	(segment
		(start 160.52546 -118.331488)
		(end 160.52546 -118.946168)
		(width 0.127)
		(layer "In2.Cu")
		(net "PWRGD_DRAMPWRGD_CPU1_AB_LVC1_R2")
	)
	(segment
		(start 160.7566 -112.001808)
		(end 160.7566 -118.100348)
		(width 0.127)
		(layer "In2.Cu")
		(net "PWRGD_DRAMPWRGD_CPU1_AB_LVC1_R2")
	)
	(segment
		(start 158.70936 -111.460788)
		(end 160.21558 -111.460788)
		(width 0.127)
		(layer "In2.Cu")
		(net "PWRGD_DRAMPWRGD_CPU1_AB_LVC1_R2")
	)
	(segment
		(start 154.86126 -106.871008)
		(end 155.55468 -107.564428)
		(width 0.127)
		(layer "In2.Cu")
		(net "PWRGD_DRAMPWRGD_CPU1_AB_LVC1_R2")
	)
	(segment
		(start 160.02508 -119.446548)
		(end 158.24708 -119.446548)
		(width 0.127)
		(layer "In2.Cu")
		(net "PWRGD_DRAMPWRGD_CPU1_AB_LVC1_R2")
	)
	(segment
		(start 94.81566 -174.126652)
		(end 94.81566 -176.807622)
		(width 0.127)
		(layer "In11.Cu")
		(net "PWRGD_DRAMPWRGD_CPU1_AB_LVC1_R2")
	)
	(segment
		(start 94.48038 -173.791372)
		(end 94.81566 -174.126652)
		(width 0.127)
		(layer "In11.Cu")
		(net "PWRGD_DRAMPWRGD_CPU1_AB_LVC1_R2")
	)
	(segment
		(start 90.8939 -186.406536)
		(end 88.805258 -188.495178)
		(width 0.127)
		(layer "In11.Cu")
		(net "PWRGD_DRAMPWRGD_CPU1_AB_LVC1_R2")
	)
	(segment
		(start 91.13012 -184.902348)
		(end 90.8939 -185.138568)
		(width 0.127)
		(layer "In11.Cu")
		(net "PWRGD_DRAMPWRGD_CPU1_AB_LVC1_R2")
	)
	(segment
		(start 88.805258 -188.495178)
		(end 79.968852 -188.495178)
		(width 0.127)
		(layer "In11.Cu")
		(net "PWRGD_DRAMPWRGD_CPU1_AB_LVC1_R2")
	)
	(segment
		(start 94.81566 -176.807622)
		(end 91.13012 -180.493162)
		(width 0.127)
		(layer "In11.Cu")
		(net "PWRGD_DRAMPWRGD_CPU1_AB_LVC1_R2")
	)
	(segment
		(start 79.968852 -188.495178)
		(end 77.655166 -190.808864)
		(width 0.127)
		(layer "In11.Cu")
		(net "PWRGD_DRAMPWRGD_CPU1_AB_LVC1_R2")
	)
	(segment
		(start 77.655166 -190.808864)
		(end 63.425324 -190.808864)
		(width 0.127)
		(layer "In11.Cu")
		(net "PWRGD_DRAMPWRGD_CPU1_AB_LVC1_R2")
	)
	(segment
		(start 94.48038 -173.708568)
		(end 94.48038 -173.791372)
		(width 0.127)
		(layer "In11.Cu")
		(net "PWRGD_DRAMPWRGD_CPU1_AB_LVC1_R2")
	)
	(segment
		(start 63.425324 -190.808864)
		(end 62.353698 -191.88049)
		(width 0.127)
		(layer "In11.Cu")
		(net "PWRGD_DRAMPWRGD_CPU1_AB_LVC1_R2")
	)
	(segment
		(start 90.8939 -185.138568)
		(end 90.8939 -186.406536)
		(width 0.127)
		(layer "In11.Cu")
		(net "PWRGD_DRAMPWRGD_CPU1_AB_LVC1_R2")
	)
	(segment
		(start 91.13012 -180.493162)
		(end 91.13012 -184.902348)
		(width 0.127)
		(layer "In11.Cu")
		(net "PWRGD_DRAMPWRGD_CPU1_AB_LVC1_R2")
	)
	(via
		(at 181.04358 -103.332788)
		(size 0.508)
		(drill 0.254)
		(layers "F.Cu" "B.Cu")
		(net "PWRGD_DRAMPWRGD_CPU0_GH_LVC1_R2")
	)
	(via
		(at 255.40208 -129.776728)
		(size 0.508)
		(drill 0.254)
		(layers "F.Cu" "B.Cu")
		(net "PWRGD_DRAMPWRGD_CPU0_GH_LVC1_R2")
	)
	(via
		(at 383.049018 -168.82237)
		(size 0.6604)
		(drill 0.3302)
		(layers "F.Cu" "B.Cu")
		(net "PWRGD_DRAMPWRGD_CPU0_GH_LVC1_R2")
	)
	(segment
		(start 379.24486 -158.26232)
		(end 374.909588 -153.927048)
		(width 0.12954)
		(layer "B.Cu")
		(net "PWRGD_DRAMPWRGD_CPU0_GH_LVC1_R2")
	)
	(segment
		(start 302.903128 -131.128008)
		(end 279.367996 -131.128008)
		(width 0.12954)
		(layer "B.Cu")
		(net "PWRGD_DRAMPWRGD_CPU0_GH_LVC1_R2")
	)
	(segment
		(start 262.343392 -128.45796)
		(end 258.083304 -128.45796)
		(width 0.12954)
		(layer "B.Cu")
		(net "PWRGD_DRAMPWRGD_CPU0_GH_LVC1_R2")
	)
	(segment
		(start 400.710146 -191.152272)
		(end 400.686778 -191.17564)
		(width 0.12954)
		(layer "B.Cu")
		(net "PWRGD_DRAMPWRGD_CPU0_GH_LVC1_R2")
	)
	(segment
		(start 256.764536 -129.776728)
		(end 255.40208 -129.776728)
		(width 0.12954)
		(layer "B.Cu")
		(net "PWRGD_DRAMPWRGD_CPU0_GH_LVC1_R2")
	)
	(segment
		(start 396.18285 -188.87313)
		(end 395.650974 -188.341254)
		(width 0.12954)
		(layer "B.Cu")
		(net "PWRGD_DRAMPWRGD_CPU0_GH_LVC1_R2")
	)
	(segment
		(start 399.447258 -188.87313)
		(end 396.18285 -188.87313)
		(width 0.12954)
		(layer "B.Cu")
		(net "PWRGD_DRAMPWRGD_CPU0_GH_LVC1_R2")
	)
	(segment
		(start 308.543706 -136.768586)
		(end 302.903128 -131.128008)
		(width 0.12954)
		(layer "B.Cu")
		(net "PWRGD_DRAMPWRGD_CPU0_GH_LVC1_R2")
	)
	(segment
		(start 258.083304 -128.45796)
		(end 256.764536 -129.776728)
		(width 0.12954)
		(layer "B.Cu")
		(net "PWRGD_DRAMPWRGD_CPU0_GH_LVC1_R2")
	)
	(segment
		(start 383.049018 -171.48683)
		(end 383.049018 -168.82237)
		(width 0.12954)
		(layer "B.Cu")
		(net "PWRGD_DRAMPWRGD_CPU0_GH_LVC1_R2")
	)
	(segment
		(start 401.328382 -189.69355)
		(end 400.267678 -189.69355)
		(width 0.12954)
		(layer "B.Cu")
		(net "PWRGD_DRAMPWRGD_CPU0_GH_LVC1_R2")
	)
	(segment
		(start 401.152106 -191.17564)
		(end 401.606258 -191.17564)
		(width 0.12954)
		(layer "B.Cu")
		(net "PWRGD_DRAMPWRGD_CPU0_GH_LVC1_R2")
	)
	(segment
		(start 356.113588 -153.927048)
		(end 345.135454 -142.948914)
		(width 0.12954)
		(layer "B.Cu")
		(net "PWRGD_DRAMPWRGD_CPU0_GH_LVC1_R2")
	)
	(segment
		(start 374.909588 -153.927048)
		(end 356.113588 -153.927048)
		(width 0.12954)
		(layer "B.Cu")
		(net "PWRGD_DRAMPWRGD_CPU0_GH_LVC1_R2")
	)
	(segment
		(start 401.45843 -189.823598)
		(end 401.328382 -189.69355)
		(width 0.12954)
		(layer "B.Cu")
		(net "PWRGD_DRAMPWRGD_CPU0_GH_LVC1_R2")
	)
	(segment
		(start 279.367996 -131.128008)
		(end 277.455376 -129.215388)
		(width 0.12954)
		(layer "B.Cu")
		(net "PWRGD_DRAMPWRGD_CPU0_GH_LVC1_R2")
	)
	(segment
		(start 277.455376 -129.215388)
		(end 263.10082 -129.215388)
		(width 0.12954)
		(layer "B.Cu")
		(net "PWRGD_DRAMPWRGD_CPU0_GH_LVC1_R2")
	)
	(segment
		(start 401.606258 -191.17564)
		(end 402.336 -190.445898)
		(width 0.12954)
		(layer "B.Cu")
		(net "PWRGD_DRAMPWRGD_CPU0_GH_LVC1_R2")
	)
	(segment
		(start 383.049018 -167.409876)
		(end 379.24486 -163.605718)
		(width 0.12954)
		(layer "B.Cu")
		(net "PWRGD_DRAMPWRGD_CPU0_GH_LVC1_R2")
	)
	(segment
		(start 333.113126 -142.948914)
		(end 318.192404 -136.768586)
		(width 0.12954)
		(layer "B.Cu")
		(net "PWRGD_DRAMPWRGD_CPU0_GH_LVC1_R2")
	)
	(segment
		(start 318.192404 -136.768586)
		(end 308.543706 -136.768586)
		(width 0.12954)
		(layer "B.Cu")
		(net "PWRGD_DRAMPWRGD_CPU0_GH_LVC1_R2")
	)
	(segment
		(start 263.10082 -129.215388)
		(end 262.343392 -128.45796)
		(width 0.12954)
		(layer "B.Cu")
		(net "PWRGD_DRAMPWRGD_CPU0_GH_LVC1_R2")
	)
	(segment
		(start 400.710146 -191.152272)
		(end 401.45843 -190.403988)
		(width 0.12954)
		(layer "B.Cu")
		(net "PWRGD_DRAMPWRGD_CPU0_GH_LVC1_R2")
	)
	(segment
		(start 383.049018 -168.82237)
		(end 383.049018 -167.409876)
		(width 0.12954)
		(layer "B.Cu")
		(net "PWRGD_DRAMPWRGD_CPU0_GH_LVC1_R2")
	)
	(segment
		(start 401.45843 -190.403988)
		(end 401.45843 -189.823598)
		(width 0.12954)
		(layer "B.Cu")
		(net "PWRGD_DRAMPWRGD_CPU0_GH_LVC1_R2")
	)
	(segment
		(start 395.650974 -188.341254)
		(end 392.988546 -181.914038)
		(width 0.12954)
		(layer "B.Cu")
		(net "PWRGD_DRAMPWRGD_CPU0_GH_LVC1_R2")
	)
	(segment
		(start 181.04358 -103.332788)
		(end 180.449982 -103.926386)
		(width 0.12954)
		(layer "B.Cu")
		(net "PWRGD_DRAMPWRGD_CPU0_GH_LVC1_R2")
	)
	(segment
		(start 392.006328 -180.44414)
		(end 383.049018 -171.48683)
		(width 0.12954)
		(layer "B.Cu")
		(net "PWRGD_DRAMPWRGD_CPU0_GH_LVC1_R2")
	)
	(segment
		(start 392.988546 -181.914038)
		(end 392.006328 -180.44414)
		(width 0.12954)
		(layer "B.Cu")
		(net "PWRGD_DRAMPWRGD_CPU0_GH_LVC1_R2")
	)
	(segment
		(start 400.267678 -189.69355)
		(end 399.447258 -188.87313)
		(width 0.12954)
		(layer "B.Cu")
		(net "PWRGD_DRAMPWRGD_CPU0_GH_LVC1_R2")
	)
	(segment
		(start 345.135454 -142.948914)
		(end 333.113126 -142.948914)
		(width 0.12954)
		(layer "B.Cu")
		(net "PWRGD_DRAMPWRGD_CPU0_GH_LVC1_R2")
	)
	(segment
		(start 180.449982 -103.926386)
		(end 180.449982 -104.720136)
		(width 0.12954)
		(layer "B.Cu")
		(net "PWRGD_DRAMPWRGD_CPU0_GH_LVC1_R2")
	)
	(segment
		(start 401.128738 -191.152272)
		(end 401.152106 -191.17564)
		(width 0.12954)
		(layer "B.Cu")
		(net "PWRGD_DRAMPWRGD_CPU0_GH_LVC1_R2")
	)
	(segment
		(start 400.710146 -191.152272)
		(end 401.128738 -191.152272)
		(width 0.12954)
		(layer "B.Cu")
		(net "PWRGD_DRAMPWRGD_CPU0_GH_LVC1_R2")
	)
	(segment
		(start 379.24486 -163.605718)
		(end 379.24486 -158.26232)
		(width 0.12954)
		(layer "B.Cu")
		(net "PWRGD_DRAMPWRGD_CPU0_GH_LVC1_R2")
	)
	(segment
		(start 196.78396 -116.223288)
		(end 196.78396 -115.415568)
		(width 0.127)
		(layer "In6.Cu")
		(net "PWRGD_DRAMPWRGD_CPU0_GH_LVC1_R2")
	)
	(segment
		(start 253.9492 -125.564646)
		(end 247.336564 -118.95201)
		(width 0.127)
		(layer "In6.Cu")
		(net "PWRGD_DRAMPWRGD_CPU0_GH_LVC1_R2")
	)
	(segment
		(start 247.336564 -118.95201)
		(end 243.630196 -118.95201)
		(width 0.127)
		(layer "In6.Cu")
		(net "PWRGD_DRAMPWRGD_CPU0_GH_LVC1_R2")
	)
	(segment
		(start 179.49926 -113.772188)
		(end 178.64836 -112.921288)
		(width 0.127)
		(layer "In6.Cu")
		(net "PWRGD_DRAMPWRGD_CPU0_GH_LVC1_R2")
	)
	(segment
		(start 255.40208 -129.776728)
		(end 254.32766 -129.776728)
		(width 0.127)
		(layer "In6.Cu")
		(net "PWRGD_DRAMPWRGD_CPU0_GH_LVC1_R2")
	)
	(segment
		(start 178.948588 -104.907588)
		(end 178.64582 -104.60482)
		(width 0.127)
		(layer "In6.Cu")
		(net "PWRGD_DRAMPWRGD_CPU0_GH_LVC1_R2")
	)
	(segment
		(start 178.64582 -103.363268)
		(end 178.7906 -103.218488)
		(width 0.127)
		(layer "In6.Cu")
		(net "PWRGD_DRAMPWRGD_CPU0_GH_LVC1_R2")
	)
	(segment
		(start 220.650054 -119.037608)
		(end 210.82508 -119.037608)
		(width 0.127)
		(layer "In6.Cu")
		(net "PWRGD_DRAMPWRGD_CPU0_GH_LVC1_R2")
	)
	(segment
		(start 198.14032 -117.579648)
		(end 196.78396 -116.223288)
		(width 0.127)
		(layer "In6.Cu")
		(net "PWRGD_DRAMPWRGD_CPU0_GH_LVC1_R2")
	)
	(segment
		(start 180.92928 -103.218488)
		(end 181.04358 -103.332788)
		(width 0.127)
		(layer "In6.Cu")
		(net "PWRGD_DRAMPWRGD_CPU0_GH_LVC1_R2")
	)
	(segment
		(start 196.30898 -114.940588)
		(end 187.84062 -114.940588)
		(width 0.127)
		(layer "In6.Cu")
		(net "PWRGD_DRAMPWRGD_CPU0_GH_LVC1_R2")
	)
	(segment
		(start 239.815878 -115.137692)
		(end 224.54997 -115.137692)
		(width 0.127)
		(layer "In6.Cu")
		(net "PWRGD_DRAMPWRGD_CPU0_GH_LVC1_R2")
	)
	(segment
		(start 201.667872 -118.618)
		(end 200.62952 -117.579648)
		(width 0.127)
		(layer "In6.Cu")
		(net "PWRGD_DRAMPWRGD_CPU0_GH_LVC1_R2")
	)
	(segment
		(start 224.54997 -115.137692)
		(end 220.650054 -119.037608)
		(width 0.127)
		(layer "In6.Cu")
		(net "PWRGD_DRAMPWRGD_CPU0_GH_LVC1_R2")
	)
	(segment
		(start 178.64836 -112.921288)
		(end 178.64836 -109.514132)
		(width 0.127)
		(layer "In6.Cu")
		(net "PWRGD_DRAMPWRGD_CPU0_GH_LVC1_R2")
	)
	(segment
		(start 186.67222 -113.772188)
		(end 179.49926 -113.772188)
		(width 0.127)
		(layer "In6.Cu")
		(net "PWRGD_DRAMPWRGD_CPU0_GH_LVC1_R2")
	)
	(segment
		(start 254.32766 -129.776728)
		(end 253.9492 -129.398268)
		(width 0.127)
		(layer "In6.Cu")
		(net "PWRGD_DRAMPWRGD_CPU0_GH_LVC1_R2")
	)
	(segment
		(start 210.82508 -119.037608)
		(end 210.405472 -118.618)
		(width 0.127)
		(layer "In6.Cu")
		(net "PWRGD_DRAMPWRGD_CPU0_GH_LVC1_R2")
	)
	(segment
		(start 253.9492 -129.398268)
		(end 253.9492 -125.564646)
		(width 0.127)
		(layer "In6.Cu")
		(net "PWRGD_DRAMPWRGD_CPU0_GH_LVC1_R2")
	)
	(segment
		(start 243.630196 -118.95201)
		(end 239.815878 -115.137692)
		(width 0.127)
		(layer "In6.Cu")
		(net "PWRGD_DRAMPWRGD_CPU0_GH_LVC1_R2")
	)
	(segment
		(start 210.405472 -118.618)
		(end 201.667872 -118.618)
		(width 0.127)
		(layer "In6.Cu")
		(net "PWRGD_DRAMPWRGD_CPU0_GH_LVC1_R2")
	)
	(segment
		(start 200.62952 -117.579648)
		(end 198.14032 -117.579648)
		(width 0.127)
		(layer "In6.Cu")
		(net "PWRGD_DRAMPWRGD_CPU0_GH_LVC1_R2")
	)
	(segment
		(start 187.84062 -114.940588)
		(end 186.67222 -113.772188)
		(width 0.127)
		(layer "In6.Cu")
		(net "PWRGD_DRAMPWRGD_CPU0_GH_LVC1_R2")
	)
	(segment
		(start 196.78396 -115.415568)
		(end 196.30898 -114.940588)
		(width 0.127)
		(layer "In6.Cu")
		(net "PWRGD_DRAMPWRGD_CPU0_GH_LVC1_R2")
	)
	(segment
		(start 178.64582 -104.60482)
		(end 178.64582 -103.363268)
		(width 0.127)
		(layer "In6.Cu")
		(net "PWRGD_DRAMPWRGD_CPU0_GH_LVC1_R2")
	)
	(segment
		(start 178.64836 -109.514132)
		(end 178.948588 -109.213904)
		(width 0.127)
		(layer "In6.Cu")
		(net "PWRGD_DRAMPWRGD_CPU0_GH_LVC1_R2")
	)
	(segment
		(start 178.948588 -109.213904)
		(end 178.948588 -104.907588)
		(width 0.127)
		(layer "In6.Cu")
		(net "PWRGD_DRAMPWRGD_CPU0_GH_LVC1_R2")
	)
	(segment
		(start 178.7906 -103.218488)
		(end 180.92928 -103.218488)
		(width 0.127)
		(layer "In6.Cu")
		(net "PWRGD_DRAMPWRGD_CPU0_GH_LVC1_R2")
	)
	(via
		(at 254.81788 -130.266948)
		(size 0.762)
		(drill 0.254)
		(layers "F.Cu" "B.Cu")
		(net "PWRGD_DRAMPWRGD_CPU0_EF_LVC1_R2")
	)
	(via
		(at 179.26812 -104.399588)
		(size 0.508)
		(drill 0.254)
		(layers "F.Cu" "B.Cu")
		(net "PWRGD_DRAMPWRGD_CPU0_EF_LVC1_R2")
	)
	(via
		(at 382.345438 -170.51655)
		(size 0.6604)
		(drill 0.3302)
		(layers "F.Cu" "B.Cu")
		(net "PWRGD_DRAMPWRGD_CPU0_EF_LVC1_R2")
	)
	(segment
		(start 345.133168 -143.678148)
		(end 355.899212 -154.444192)
		(width 0.12954)
		(layer "B.Cu")
		(net "PWRGD_DRAMPWRGD_CPU0_EF_LVC1_R2")
	)
	(segment
		(start 399.670778 -191.596518)
		(end 399.670778 -191.17564)
		(width 0.12954)
		(layer "B.Cu")
		(net "PWRGD_DRAMPWRGD_CPU0_EF_LVC1_R2")
	)
	(segment
		(start 400.298158 -192.223898)
		(end 399.670778 -191.596518)
		(width 0.12954)
		(layer "B.Cu")
		(net "PWRGD_DRAMPWRGD_CPU0_EF_LVC1_R2")
	)
	(segment
		(start 178.4604 -106.045)
		(end 178.633628 -106.045)
		(width 0.12954)
		(layer "B.Cu")
		(net "PWRGD_DRAMPWRGD_CPU0_EF_LVC1_R2")
	)
	(segment
		(start 277.849076 -130.340608)
		(end 279.15362 -131.645152)
		(width 0.12954)
		(layer "B.Cu")
		(net "PWRGD_DRAMPWRGD_CPU0_EF_LVC1_R2")
	)
	(segment
		(start 178.633628 -106.045)
		(end 179.33924 -105.339388)
		(width 0.12954)
		(layer "B.Cu")
		(net "PWRGD_DRAMPWRGD_CPU0_EF_LVC1_R2")
	)
	(segment
		(start 392.748262 -182.404004)
		(end 395.680692 -189.48146)
		(width 0.12954)
		(layer "B.Cu")
		(net "PWRGD_DRAMPWRGD_CPU0_EF_LVC1_R2")
	)
	(segment
		(start 179.33924 -104.470708)
		(end 179.26812 -104.399588)
		(width 0.12954)
		(layer "B.Cu")
		(net "PWRGD_DRAMPWRGD_CPU0_EF_LVC1_R2")
	)
	(segment
		(start 302.688752 -131.645152)
		(end 308.32933 -137.28573)
		(width 0.12954)
		(layer "B.Cu")
		(net "PWRGD_DRAMPWRGD_CPU0_EF_LVC1_R2")
	)
	(segment
		(start 378.727716 -163.820094)
		(end 382.345438 -167.437816)
		(width 0.12954)
		(layer "B.Cu")
		(net "PWRGD_DRAMPWRGD_CPU0_EF_LVC1_R2")
	)
	(segment
		(start 254.81788 -130.266948)
		(end 254.89154 -130.340608)
		(width 0.12954)
		(layer "B.Cu")
		(net "PWRGD_DRAMPWRGD_CPU0_EF_LVC1_R2")
	)
	(segment
		(start 279.15362 -131.645152)
		(end 302.688752 -131.645152)
		(width 0.12954)
		(layer "B.Cu")
		(net "PWRGD_DRAMPWRGD_CPU0_EF_LVC1_R2")
	)
	(segment
		(start 395.680692 -189.48146)
		(end 397.374872 -191.17564)
		(width 0.12954)
		(layer "B.Cu")
		(net "PWRGD_DRAMPWRGD_CPU0_EF_LVC1_R2")
	)
	(segment
		(start 397.374872 -191.17564)
		(end 399.670778 -191.17564)
		(width 0.12954)
		(layer "B.Cu")
		(net "PWRGD_DRAMPWRGD_CPU0_EF_LVC1_R2")
	)
	(segment
		(start 374.695212 -154.444192)
		(end 378.727716 -158.476696)
		(width 0.12954)
		(layer "B.Cu")
		(net "PWRGD_DRAMPWRGD_CPU0_EF_LVC1_R2")
	)
	(segment
		(start 254.89154 -130.340608)
		(end 277.849076 -130.340608)
		(width 0.12954)
		(layer "B.Cu")
		(net "PWRGD_DRAMPWRGD_CPU0_EF_LVC1_R2")
	)
	(segment
		(start 333.015336 -143.678148)
		(end 345.133168 -143.678148)
		(width 0.12954)
		(layer "B.Cu")
		(net "PWRGD_DRAMPWRGD_CPU0_EF_LVC1_R2")
	)
	(segment
		(start 382.345438 -171.51731)
		(end 391.772902 -180.944774)
		(width 0.12954)
		(layer "B.Cu")
		(net "PWRGD_DRAMPWRGD_CPU0_EF_LVC1_R2")
	)
	(segment
		(start 317.58255 -137.28573)
		(end 333.015336 -143.678148)
		(width 0.12954)
		(layer "B.Cu")
		(net "PWRGD_DRAMPWRGD_CPU0_EF_LVC1_R2")
	)
	(segment
		(start 401.828 -192.223898)
		(end 400.298158 -192.223898)
		(width 0.12954)
		(layer "B.Cu")
		(net "PWRGD_DRAMPWRGD_CPU0_EF_LVC1_R2")
	)
	(segment
		(start 391.772902 -180.944774)
		(end 392.748262 -182.404004)
		(width 0.12954)
		(layer "B.Cu")
		(net "PWRGD_DRAMPWRGD_CPU0_EF_LVC1_R2")
	)
	(segment
		(start 378.727716 -158.476696)
		(end 378.727716 -163.820094)
		(width 0.12954)
		(layer "B.Cu")
		(net "PWRGD_DRAMPWRGD_CPU0_EF_LVC1_R2")
	)
	(segment
		(start 308.32933 -137.28573)
		(end 317.58255 -137.28573)
		(width 0.12954)
		(layer "B.Cu")
		(net "PWRGD_DRAMPWRGD_CPU0_EF_LVC1_R2")
	)
	(segment
		(start 382.345438 -167.437816)
		(end 382.345438 -170.51655)
		(width 0.12954)
		(layer "B.Cu")
		(net "PWRGD_DRAMPWRGD_CPU0_EF_LVC1_R2")
	)
	(segment
		(start 179.33924 -105.339388)
		(end 179.33924 -104.470708)
		(width 0.12954)
		(layer "B.Cu")
		(net "PWRGD_DRAMPWRGD_CPU0_EF_LVC1_R2")
	)
	(segment
		(start 355.899212 -154.444192)
		(end 374.695212 -154.444192)
		(width 0.12954)
		(layer "B.Cu")
		(net "PWRGD_DRAMPWRGD_CPU0_EF_LVC1_R2")
	)
	(segment
		(start 382.345438 -170.51655)
		(end 382.345438 -171.51731)
		(width 0.12954)
		(layer "B.Cu")
		(net "PWRGD_DRAMPWRGD_CPU0_EF_LVC1_R2")
	)
	(segment
		(start 197.72122 -116.233448)
		(end 200.54062 -116.233448)
		(width 0.127)
		(layer "In6.Cu")
		(net "PWRGD_DRAMPWRGD_CPU0_EF_LVC1_R2")
	)
	(segment
		(start 186.9313 -113.429288)
		(end 188.00064 -114.498628)
		(width 0.127)
		(layer "In6.Cu")
		(net "PWRGD_DRAMPWRGD_CPU0_EF_LVC1_R2")
	)
	(segment
		(start 254.635 -127.165608)
		(end 256.20472 -128.735328)
		(width 0.127)
		(layer "In6.Cu")
		(net "PWRGD_DRAMPWRGD_CPU0_EF_LVC1_R2")
	)
	(segment
		(start 179.26812 -104.399588)
		(end 179.8574 -104.988868)
		(width 0.127)
		(layer "In6.Cu")
		(net "PWRGD_DRAMPWRGD_CPU0_EF_LVC1_R2")
	)
	(segment
		(start 255.29794 -130.429508)
		(end 255.13538 -130.266948)
		(width 0.127)
		(layer "In6.Cu")
		(net "PWRGD_DRAMPWRGD_CPU0_EF_LVC1_R2")
	)
	(segment
		(start 254.635 -125.610874)
		(end 254.635 -127.165608)
		(width 0.127)
		(layer "In6.Cu")
		(net "PWRGD_DRAMPWRGD_CPU0_EF_LVC1_R2")
	)
	(segment
		(start 224.29089 -114.581432)
		(end 239.870742 -114.581432)
		(width 0.127)
		(layer "In6.Cu")
		(net "PWRGD_DRAMPWRGD_CPU0_EF_LVC1_R2")
	)
	(segment
		(start 178.92522 -112.735868)
		(end 179.61864 -113.429288)
		(width 0.127)
		(layer "In6.Cu")
		(net "PWRGD_DRAMPWRGD_CPU0_EF_LVC1_R2")
	)
	(segment
		(start 255.13538 -130.266948)
		(end 254.81788 -130.266948)
		(width 0.127)
		(layer "In6.Cu")
		(net "PWRGD_DRAMPWRGD_CPU0_EF_LVC1_R2")
	)
	(segment
		(start 179.8574 -109.04982)
		(end 178.92522 -109.982)
		(width 0.127)
		(layer "In6.Cu")
		(net "PWRGD_DRAMPWRGD_CPU0_EF_LVC1_R2")
	)
	(segment
		(start 256.20472 -130.109468)
		(end 255.88468 -130.429508)
		(width 0.127)
		(layer "In6.Cu")
		(net "PWRGD_DRAMPWRGD_CPU0_EF_LVC1_R2")
	)
	(segment
		(start 239.870742 -114.581432)
		(end 243.80952 -118.52021)
		(width 0.127)
		(layer "In6.Cu")
		(net "PWRGD_DRAMPWRGD_CPU0_EF_LVC1_R2")
	)
	(segment
		(start 255.88468 -130.429508)
		(end 255.29794 -130.429508)
		(width 0.127)
		(layer "In6.Cu")
		(net "PWRGD_DRAMPWRGD_CPU0_EF_LVC1_R2")
	)
	(segment
		(start 209.813652 -117.386608)
		(end 211.012532 -118.585488)
		(width 0.127)
		(layer "In6.Cu")
		(net "PWRGD_DRAMPWRGD_CPU0_EF_LVC1_R2")
	)
	(segment
		(start 243.80952 -118.52021)
		(end 247.544336 -118.52021)
		(width 0.127)
		(layer "In6.Cu")
		(net "PWRGD_DRAMPWRGD_CPU0_EF_LVC1_R2")
	)
	(segment
		(start 247.544336 -118.52021)
		(end 254.635 -125.610874)
		(width 0.127)
		(layer "In6.Cu")
		(net "PWRGD_DRAMPWRGD_CPU0_EF_LVC1_R2")
	)
	(segment
		(start 179.8574 -104.988868)
		(end 179.8574 -109.04982)
		(width 0.127)
		(layer "In6.Cu")
		(net "PWRGD_DRAMPWRGD_CPU0_EF_LVC1_R2")
	)
	(segment
		(start 197.27672 -115.788948)
		(end 197.72122 -116.233448)
		(width 0.127)
		(layer "In6.Cu")
		(net "PWRGD_DRAMPWRGD_CPU0_EF_LVC1_R2")
	)
	(segment
		(start 220.286834 -118.585488)
		(end 224.29089 -114.581432)
		(width 0.127)
		(layer "In6.Cu")
		(net "PWRGD_DRAMPWRGD_CPU0_EF_LVC1_R2")
	)
	(segment
		(start 188.00064 -114.498628)
		(end 196.55028 -114.498628)
		(width 0.127)
		(layer "In6.Cu")
		(net "PWRGD_DRAMPWRGD_CPU0_EF_LVC1_R2")
	)
	(segment
		(start 200.54062 -116.233448)
		(end 201.69378 -117.386608)
		(width 0.127)
		(layer "In6.Cu")
		(net "PWRGD_DRAMPWRGD_CPU0_EF_LVC1_R2")
	)
	(segment
		(start 197.27672 -115.225068)
		(end 197.27672 -115.788948)
		(width 0.127)
		(layer "In6.Cu")
		(net "PWRGD_DRAMPWRGD_CPU0_EF_LVC1_R2")
	)
	(segment
		(start 201.69378 -117.386608)
		(end 209.813652 -117.386608)
		(width 0.127)
		(layer "In6.Cu")
		(net "PWRGD_DRAMPWRGD_CPU0_EF_LVC1_R2")
	)
	(segment
		(start 179.61864 -113.429288)
		(end 186.9313 -113.429288)
		(width 0.127)
		(layer "In6.Cu")
		(net "PWRGD_DRAMPWRGD_CPU0_EF_LVC1_R2")
	)
	(segment
		(start 178.92522 -109.982)
		(end 178.92522 -112.735868)
		(width 0.127)
		(layer "In6.Cu")
		(net "PWRGD_DRAMPWRGD_CPU0_EF_LVC1_R2")
	)
	(segment
		(start 211.012532 -118.585488)
		(end 220.286834 -118.585488)
		(width 0.127)
		(layer "In6.Cu")
		(net "PWRGD_DRAMPWRGD_CPU0_EF_LVC1_R2")
	)
	(segment
		(start 256.20472 -128.735328)
		(end 256.20472 -130.109468)
		(width 0.127)
		(layer "In6.Cu")
		(net "PWRGD_DRAMPWRGD_CPU0_EF_LVC1_R2")
	)
	(segment
		(start 196.55028 -114.498628)
		(end 197.27672 -115.225068)
		(width 0.127)
		(layer "In6.Cu")
		(net "PWRGD_DRAMPWRGD_CPU0_EF_LVC1_R2")
	)
	(via
		(at 243.13388 -148.046948)
		(size 0.508)
		(drill 0.254)
		(layers "F.Cu" "B.Cu")
		(net "PWRGD_DRAMPWRGD_CPU0_CD_LVC1_R2")
	)
	(via
		(at 175.85182 -98.742754)
		(size 0.508)
		(drill 0.254)
		(layers "F.Cu" "B.Cu")
		(net "PWRGD_DRAMPWRGD_CPU0_CD_LVC1_R2")
	)
	(via
		(at 170.36288 -131.282948)
		(size 0.508)
		(drill 0.254)
		(layers "F.Cu" "B.Cu")
		(net "PWRGD_DRAMPWRGD_CPU0_CD_LVC1_R2")
	)
	(segment
		(start 299.151294 -194.07378)
		(end 299.679868 -194.602354)
		(width 0.12954)
		(layer "B.Cu")
		(net "PWRGD_DRAMPWRGD_CPU0_CD_LVC1_R2")
	)
	(segment
		(start 243.13388 -148.046948)
		(end 243.13388 -151.983948)
		(width 0.12954)
		(layer "B.Cu")
		(net "PWRGD_DRAMPWRGD_CPU0_CD_LVC1_R2")
	)
	(segment
		(start 294.07358 -187.026804)
		(end 294.07358 -189.23127)
		(width 0.12954)
		(layer "B.Cu")
		(net "PWRGD_DRAMPWRGD_CPU0_CD_LVC1_R2")
	)
	(segment
		(start 299.129958 -194.07378)
		(end 299.151294 -194.07378)
		(width 0.12954)
		(layer "B.Cu")
		(net "PWRGD_DRAMPWRGD_CPU0_CD_LVC1_R2")
	)
	(segment
		(start 286.41548 -182.133748)
		(end 288.16808 -183.886348)
		(width 0.12954)
		(layer "B.Cu")
		(net "PWRGD_DRAMPWRGD_CPU0_CD_LVC1_R2")
	)
	(segment
		(start 175.85182 -97.742502)
		(end 175.830738 -97.72142)
		(width 0.12954)
		(layer "B.Cu")
		(net "PWRGD_DRAMPWRGD_CPU0_CD_LVC1_R2")
	)
	(segment
		(start 273.28368 -182.133748)
		(end 286.41548 -182.133748)
		(width 0.12954)
		(layer "B.Cu")
		(net "PWRGD_DRAMPWRGD_CPU0_CD_LVC1_R2")
	)
	(segment
		(start 288.16808 -183.886348)
		(end 290.933124 -183.886348)
		(width 0.12954)
		(layer "B.Cu")
		(net "PWRGD_DRAMPWRGD_CPU0_CD_LVC1_R2")
	)
	(segment
		(start 175.85182 -98.742754)
		(end 175.85182 -97.742502)
		(width 0.12954)
		(layer "B.Cu")
		(net "PWRGD_DRAMPWRGD_CPU0_CD_LVC1_R2")
	)
	(segment
		(start 294.25265 -189.663578)
		(end 298.639484 -194.050412)
		(width 0.12954)
		(layer "B.Cu")
		(net "PWRGD_DRAMPWRGD_CPU0_CD_LVC1_R2")
	)
	(segment
		(start 294.07358 -189.23127)
		(end 294.25265 -189.663578)
		(width 0.12954)
		(layer "B.Cu")
		(net "PWRGD_DRAMPWRGD_CPU0_CD_LVC1_R2")
	)
	(segment
		(start 290.933124 -183.886348)
		(end 294.07358 -187.026804)
		(width 0.12954)
		(layer "B.Cu")
		(net "PWRGD_DRAMPWRGD_CPU0_CD_LVC1_R2")
	)
	(segment
		(start 298.639484 -194.050412)
		(end 299.10659 -194.050412)
		(width 0.12954)
		(layer "B.Cu")
		(net "PWRGD_DRAMPWRGD_CPU0_CD_LVC1_R2")
	)
	(segment
		(start 299.679868 -194.602354)
		(end 299.679868 -197.797928)
		(width 0.12954)
		(layer "B.Cu")
		(net "PWRGD_DRAMPWRGD_CPU0_CD_LVC1_R2")
	)
	(segment
		(start 299.10659 -194.050412)
		(end 299.129958 -194.07378)
		(width 0.12954)
		(layer "B.Cu")
		(net "PWRGD_DRAMPWRGD_CPU0_CD_LVC1_R2")
	)
	(segment
		(start 243.13388 -151.983948)
		(end 273.28368 -182.133748)
		(width 0.12954)
		(layer "B.Cu")
		(net "PWRGD_DRAMPWRGD_CPU0_CD_LVC1_R2")
	)
	(segment
		(start 167.4495 -126.187708)
		(end 168.94556 -127.683768)
		(width 0.127)
		(layer "In11.Cu")
		(net "PWRGD_DRAMPWRGD_CPU0_CD_LVC1_R2")
	)
	(segment
		(start 173.901608 -98.171)
		(end 172.12564 -99.946968)
		(width 0.127)
		(layer "In11.Cu")
		(net "PWRGD_DRAMPWRGD_CPU0_CD_LVC1_R2")
	)
	(segment
		(start 169.799 -99.946968)
		(end 168.51122 -101.234748)
		(width 0.127)
		(layer "In11.Cu")
		(net "PWRGD_DRAMPWRGD_CPU0_CD_LVC1_R2")
	)
	(segment
		(start 172.12564 -99.946968)
		(end 169.799 -99.946968)
		(width 0.127)
		(layer "In11.Cu")
		(net "PWRGD_DRAMPWRGD_CPU0_CD_LVC1_R2")
	)
	(segment
		(start 175.85182 -98.742754)
		(end 175.280066 -98.171)
		(width 0.127)
		(layer "In11.Cu")
		(net "PWRGD_DRAMPWRGD_CPU0_CD_LVC1_R2")
	)
	(segment
		(start 168.94556 -127.683768)
		(end 168.94556 -129.080768)
		(width 0.127)
		(layer "In11.Cu")
		(net "PWRGD_DRAMPWRGD_CPU0_CD_LVC1_R2")
	)
	(segment
		(start 168.94556 -129.080768)
		(end 170.36288 -130.498088)
		(width 0.127)
		(layer "In11.Cu")
		(net "PWRGD_DRAMPWRGD_CPU0_CD_LVC1_R2")
	)
	(segment
		(start 170.36288 -130.498088)
		(end 170.36288 -131.282948)
		(width 0.127)
		(layer "In11.Cu")
		(net "PWRGD_DRAMPWRGD_CPU0_CD_LVC1_R2")
	)
	(segment
		(start 168.51122 -101.234748)
		(end 168.51122 -123.353068)
		(width 0.127)
		(layer "In11.Cu")
		(net "PWRGD_DRAMPWRGD_CPU0_CD_LVC1_R2")
	)
	(segment
		(start 175.280066 -98.171)
		(end 173.901608 -98.171)
		(width 0.127)
		(layer "In11.Cu")
		(net "PWRGD_DRAMPWRGD_CPU0_CD_LVC1_R2")
	)
	(segment
		(start 168.51122 -123.353068)
		(end 167.4495 -124.414788)
		(width 0.127)
		(layer "In11.Cu")
		(net "PWRGD_DRAMPWRGD_CPU0_CD_LVC1_R2")
	)
	(segment
		(start 167.4495 -124.414788)
		(end 167.4495 -126.187708)
		(width 0.127)
		(layer "In11.Cu")
		(net "PWRGD_DRAMPWRGD_CPU0_CD_LVC1_R2")
	)
	(segment
		(start 171.63288 -133.822948)
		(end 170.87088 -133.060948)
		(width 0.127)
		(layer "In13.Cu")
		(net "PWRGD_DRAMPWRGD_CPU0_CD_LVC1_R2")
	)
	(segment
		(start 170.87088 -131.790948)
		(end 170.36288 -131.282948)
		(width 0.127)
		(layer "In13.Cu")
		(net "PWRGD_DRAMPWRGD_CPU0_CD_LVC1_R2")
	)
	(segment
		(start 177.65268 -140.477748)
		(end 176.07788 -138.902948)
		(width 0.127)
		(layer "In13.Cu")
		(net "PWRGD_DRAMPWRGD_CPU0_CD_LVC1_R2")
	)
	(segment
		(start 174.9298 -133.822948)
		(end 171.63288 -133.822948)
		(width 0.127)
		(layer "In13.Cu")
		(net "PWRGD_DRAMPWRGD_CPU0_CD_LVC1_R2")
	)
	(segment
		(start 242.195604 -147.108672)
		(end 212.553804 -147.108672)
		(width 0.127)
		(layer "In13.Cu")
		(net "PWRGD_DRAMPWRGD_CPU0_CD_LVC1_R2")
	)
	(segment
		(start 212.553804 -147.108672)
		(end 205.92288 -140.477748)
		(width 0.127)
		(layer "In13.Cu")
		(net "PWRGD_DRAMPWRGD_CPU0_CD_LVC1_R2")
	)
	(segment
		(start 176.07788 -134.971028)
		(end 174.9298 -133.822948)
		(width 0.127)
		(layer "In13.Cu")
		(net "PWRGD_DRAMPWRGD_CPU0_CD_LVC1_R2")
	)
	(segment
		(start 243.13388 -148.046948)
		(end 242.195604 -147.108672)
		(width 0.127)
		(layer "In13.Cu")
		(net "PWRGD_DRAMPWRGD_CPU0_CD_LVC1_R2")
	)
	(segment
		(start 176.07788 -138.902948)
		(end 176.07788 -134.971028)
		(width 0.127)
		(layer "In13.Cu")
		(net "PWRGD_DRAMPWRGD_CPU0_CD_LVC1_R2")
	)
	(segment
		(start 205.92288 -140.477748)
		(end 177.65268 -140.477748)
		(width 0.127)
		(layer "In13.Cu")
		(net "PWRGD_DRAMPWRGD_CPU0_CD_LVC1_R2")
	)
	(segment
		(start 170.87088 -133.060948)
		(end 170.87088 -131.790948)
		(width 0.127)
		(layer "In13.Cu")
		(net "PWRGD_DRAMPWRGD_CPU0_CD_LVC1_R2")
	)
	(via
		(at 175.8696 -102.789228)
		(size 0.508)
		(drill 0.254)
		(layers "F.Cu" "B.Cu")
		(net "PWRGD_DRAMPWRGD_CPU0_AB_LVC1_R2")
	)
	(via
		(at 244.17528 -120.965468)
		(size 0.508)
		(drill 0.254)
		(layers "F.Cu" "B.Cu")
		(net "PWRGD_DRAMPWRGD_CPU0_AB_LVC1_R2")
	)
	(via
		(at 294.405812 -193.903854)
		(size 0.6604)
		(drill 0.3302)
		(layers "F.Cu" "B.Cu")
		(net "PWRGD_DRAMPWRGD_CPU0_AB_LVC1_R2")
	)
	(via
		(at 240.0554 -135.753856)
		(size 0.508)
		(drill 0.254)
		(layers "F.Cu" "B.Cu")
		(net "PWRGD_DRAMPWRGD_CPU0_AB_LVC1_R2")
	)
	(segment
		(start 295.167558 -194.6656)
		(end 296.183558 -194.6656)
		(width 0.12954)
		(layer "B.Cu")
		(net "PWRGD_DRAMPWRGD_CPU0_AB_LVC1_R2")
	)
	(segment
		(start 293.105078 -191.972946)
		(end 294.151558 -193.019426)
		(width 0.12954)
		(layer "B.Cu")
		(net "PWRGD_DRAMPWRGD_CPU0_AB_LVC1_R2")
	)
	(segment
		(start 240.406428 -136.26592)
		(end 240.406428 -137.273792)
		(width 0.12954)
		(layer "B.Cu")
		(net "PWRGD_DRAMPWRGD_CPU0_AB_LVC1_R2")
	)
	(segment
		(start 240.0554 -135.914892)
		(end 240.406428 -136.26592)
		(width 0.12954)
		(layer "B.Cu")
		(net "PWRGD_DRAMPWRGD_CPU0_AB_LVC1_R2")
	)
	(segment
		(start 273.114262 -182.542688)
		(end 286.246062 -182.542688)
		(width 0.12954)
		(layer "B.Cu")
		(net "PWRGD_DRAMPWRGD_CPU0_AB_LVC1_R2")
	)
	(segment
		(start 287.998662 -184.295288)
		(end 290.763452 -184.295288)
		(width 0.12954)
		(layer "B.Cu")
		(net "PWRGD_DRAMPWRGD_CPU0_AB_LVC1_R2")
	)
	(segment
		(start 296.16908 -195.290948)
		(end 296.16908 -194.680078)
		(width 0.12954)
		(layer "B.Cu")
		(net "PWRGD_DRAMPWRGD_CPU0_AB_LVC1_R2")
	)
	(segment
		(start 293.105078 -186.636914)
		(end 293.105078 -191.972946)
		(width 0.12954)
		(layer "B.Cu")
		(net "PWRGD_DRAMPWRGD_CPU0_AB_LVC1_R2")
	)
	(segment
		(start 175.8696 -102.789228)
		(end 175.778668 -102.698296)
		(width 0.12954)
		(layer "B.Cu")
		(net "PWRGD_DRAMPWRGD_CPU0_AB_LVC1_R2")
	)
	(segment
		(start 290.763452 -184.295288)
		(end 293.105078 -186.636914)
		(width 0.12954)
		(layer "B.Cu")
		(net "PWRGD_DRAMPWRGD_CPU0_AB_LVC1_R2")
	)
	(segment
		(start 296.66946 -195.791328)
		(end 296.16908 -195.290948)
		(width 0.12954)
		(layer "B.Cu")
		(net "PWRGD_DRAMPWRGD_CPU0_AB_LVC1_R2")
	)
	(segment
		(start 175.778668 -102.698296)
		(end 175.174402 -102.698296)
		(width 0.12954)
		(layer "B.Cu")
		(net "PWRGD_DRAMPWRGD_CPU0_AB_LVC1_R2")
	)
	(segment
		(start 286.246062 -182.542688)
		(end 287.998662 -184.295288)
		(width 0.12954)
		(layer "B.Cu")
		(net "PWRGD_DRAMPWRGD_CPU0_AB_LVC1_R2")
	)
	(segment
		(start 294.405812 -193.903854)
		(end 295.167558 -194.6656)
		(width 0.12954)
		(layer "B.Cu")
		(net "PWRGD_DRAMPWRGD_CPU0_AB_LVC1_R2")
	)
	(segment
		(start 294.151558 -193.019426)
		(end 294.151558 -193.6496)
		(width 0.12954)
		(layer "B.Cu")
		(net "PWRGD_DRAMPWRGD_CPU0_AB_LVC1_R2")
	)
	(segment
		(start 239.45088 -138.22934)
		(end 239.45088 -148.879306)
		(width 0.12954)
		(layer "B.Cu")
		(net "PWRGD_DRAMPWRGD_CPU0_AB_LVC1_R2")
	)
	(segment
		(start 240.406428 -137.273792)
		(end 239.45088 -138.22934)
		(width 0.12954)
		(layer "B.Cu")
		(net "PWRGD_DRAMPWRGD_CPU0_AB_LVC1_R2")
	)
	(segment
		(start 296.16908 -194.680078)
		(end 296.183558 -194.6656)
		(width 0.12954)
		(layer "B.Cu")
		(net "PWRGD_DRAMPWRGD_CPU0_AB_LVC1_R2")
	)
	(segment
		(start 240.0554 -135.753856)
		(end 240.0554 -135.914892)
		(width 0.12954)
		(layer "B.Cu")
		(net "PWRGD_DRAMPWRGD_CPU0_AB_LVC1_R2")
	)
	(segment
		(start 297.876468 -195.791328)
		(end 296.66946 -195.791328)
		(width 0.12954)
		(layer "B.Cu")
		(net "PWRGD_DRAMPWRGD_CPU0_AB_LVC1_R2")
	)
	(segment
		(start 239.45088 -148.879306)
		(end 273.114262 -182.542688)
		(width 0.12954)
		(layer "B.Cu")
		(net "PWRGD_DRAMPWRGD_CPU0_AB_LVC1_R2")
	)
	(segment
		(start 294.151558 -193.6496)
		(end 294.405812 -193.903854)
		(width 0.12954)
		(layer "B.Cu")
		(net "PWRGD_DRAMPWRGD_CPU0_AB_LVC1_R2")
	)
	(segment
		(start 240.0554 -135.68553)
		(end 240.0554 -135.753856)
		(width 0.127)
		(layer "In4.Cu")
		(net "PWRGD_DRAMPWRGD_CPU0_AB_LVC1_R2")
	)
	(segment
		(start 241.109754 -134.631176)
		(end 240.0554 -135.68553)
		(width 0.127)
		(layer "In4.Cu")
		(net "PWRGD_DRAMPWRGD_CPU0_AB_LVC1_R2")
	)
	(segment
		(start 241.69878 -133.056376)
		(end 241.109754 -133.645402)
		(width 0.127)
		(layer "In4.Cu")
		(net "PWRGD_DRAMPWRGD_CPU0_AB_LVC1_R2")
	)
	(segment
		(start 241.109754 -133.645402)
		(end 241.109754 -134.631176)
		(width 0.127)
		(layer "In4.Cu")
		(net "PWRGD_DRAMPWRGD_CPU0_AB_LVC1_R2")
	)
	(segment
		(start 244.17528 -120.965468)
		(end 241.69878 -123.441968)
		(width 0.127)
		(layer "In4.Cu")
		(net "PWRGD_DRAMPWRGD_CPU0_AB_LVC1_R2")
	)
	(segment
		(start 241.69878 -123.441968)
		(end 241.69878 -133.056376)
		(width 0.127)
		(layer "In4.Cu")
		(net "PWRGD_DRAMPWRGD_CPU0_AB_LVC1_R2")
	)
	(segment
		(start 174.96028 -112.857788)
		(end 174.96028 -107.574588)
		(width 0.127)
		(layer "In6.Cu")
		(net "PWRGD_DRAMPWRGD_CPU0_AB_LVC1_R2")
	)
	(segment
		(start 184.55767 -120.763538)
		(end 184.55767 -120.374918)
		(width 0.127)
		(layer "In6.Cu")
		(net "PWRGD_DRAMPWRGD_CPU0_AB_LVC1_R2")
	)
	(segment
		(start 175.64354 -104.379268)
		(end 175.64354 -103.015288)
		(width 0.127)
		(layer "In6.Cu")
		(net "PWRGD_DRAMPWRGD_CPU0_AB_LVC1_R2")
	)
	(segment
		(start 183.16956 -119.375428)
		(end 182.96128 -119.167148)
		(width 0.127)
		(layer "In6.Cu")
		(net "PWRGD_DRAMPWRGD_CPU0_AB_LVC1_R2")
	)
	(segment
		(start 175.64354 -103.015288)
		(end 175.8696 -102.789228)
		(width 0.127)
		(layer "In6.Cu")
		(net "PWRGD_DRAMPWRGD_CPU0_AB_LVC1_R2")
	)
	(segment
		(start 186.17184 -120.980708)
		(end 184.77484 -120.980708)
		(width 0.127)
		(layer "In6.Cu")
		(net "PWRGD_DRAMPWRGD_CPU0_AB_LVC1_R2")
	)
	(segment
		(start 175.12284 -113.020348)
		(end 174.96028 -112.857788)
		(width 0.127)
		(layer "In6.Cu")
		(net "PWRGD_DRAMPWRGD_CPU0_AB_LVC1_R2")
	)
	(segment
		(start 184.77484 -120.980708)
		(end 184.55767 -120.763538)
		(width 0.127)
		(layer "In6.Cu")
		(net "PWRGD_DRAMPWRGD_CPU0_AB_LVC1_R2")
	)
	(segment
		(start 223.59112 -118.956328)
		(end 218.77782 -123.769628)
		(width 0.127)
		(layer "In6.Cu")
		(net "PWRGD_DRAMPWRGD_CPU0_AB_LVC1_R2")
	)
	(segment
		(start 192.14084 -124.719588)
		(end 188.75502 -121.333768)
		(width 0.127)
		(layer "In6.Cu")
		(net "PWRGD_DRAMPWRGD_CPU0_AB_LVC1_R2")
	)
	(segment
		(start 188.75502 -121.333768)
		(end 186.5249 -121.333768)
		(width 0.127)
		(layer "In6.Cu")
		(net "PWRGD_DRAMPWRGD_CPU0_AB_LVC1_R2")
	)
	(segment
		(start 243.9797 -120.769888)
		(end 239.141 -120.769888)
		(width 0.127)
		(layer "In6.Cu")
		(net "PWRGD_DRAMPWRGD_CPU0_AB_LVC1_R2")
	)
	(segment
		(start 179.46624 -118.577868)
		(end 178.63312 -117.744748)
		(width 0.127)
		(layer "In6.Cu")
		(net "PWRGD_DRAMPWRGD_CPU0_AB_LVC1_R2")
	)
	(segment
		(start 237.63224 -119.261128)
		(end 232.73766 -119.261128)
		(width 0.127)
		(layer "In6.Cu")
		(net "PWRGD_DRAMPWRGD_CPU0_AB_LVC1_R2")
	)
	(segment
		(start 244.17528 -120.965468)
		(end 243.9797 -120.769888)
		(width 0.127)
		(layer "In6.Cu")
		(net "PWRGD_DRAMPWRGD_CPU0_AB_LVC1_R2")
	)
	(segment
		(start 232.43286 -118.956328)
		(end 223.59112 -118.956328)
		(width 0.127)
		(layer "In6.Cu")
		(net "PWRGD_DRAMPWRGD_CPU0_AB_LVC1_R2")
	)
	(segment
		(start 183.5277 -119.375428)
		(end 183.16956 -119.375428)
		(width 0.127)
		(layer "In6.Cu")
		(net "PWRGD_DRAMPWRGD_CPU0_AB_LVC1_R2")
	)
	(segment
		(start 239.141 -120.769888)
		(end 237.63224 -119.261128)
		(width 0.127)
		(layer "In6.Cu")
		(net "PWRGD_DRAMPWRGD_CPU0_AB_LVC1_R2")
	)
	(segment
		(start 182.96128 -119.167148)
		(end 182.96128 -118.788688)
		(width 0.127)
		(layer "In6.Cu")
		(net "PWRGD_DRAMPWRGD_CPU0_AB_LVC1_R2")
	)
	(segment
		(start 186.5249 -121.333768)
		(end 186.17184 -120.980708)
		(width 0.127)
		(layer "In6.Cu")
		(net "PWRGD_DRAMPWRGD_CPU0_AB_LVC1_R2")
	)
	(segment
		(start 184.55767 -120.374918)
		(end 184.35828 -120.175528)
		(width 0.127)
		(layer "In6.Cu")
		(net "PWRGD_DRAMPWRGD_CPU0_AB_LVC1_R2")
	)
	(segment
		(start 207.2132 -123.769628)
		(end 206.26324 -124.719588)
		(width 0.127)
		(layer "In6.Cu")
		(net "PWRGD_DRAMPWRGD_CPU0_AB_LVC1_R2")
	)
	(segment
		(start 184.35828 -120.175528)
		(end 183.96966 -120.175528)
		(width 0.127)
		(layer "In6.Cu")
		(net "PWRGD_DRAMPWRGD_CPU0_AB_LVC1_R2")
	)
	(segment
		(start 182.75046 -118.577868)
		(end 179.46624 -118.577868)
		(width 0.127)
		(layer "In6.Cu")
		(net "PWRGD_DRAMPWRGD_CPU0_AB_LVC1_R2")
	)
	(segment
		(start 174.95774 -105.065068)
		(end 175.64354 -104.379268)
		(width 0.127)
		(layer "In6.Cu")
		(net "PWRGD_DRAMPWRGD_CPU0_AB_LVC1_R2")
	)
	(segment
		(start 177.86604 -113.020348)
		(end 175.12284 -113.020348)
		(width 0.127)
		(layer "In6.Cu")
		(net "PWRGD_DRAMPWRGD_CPU0_AB_LVC1_R2")
	)
	(segment
		(start 232.73766 -119.261128)
		(end 232.43286 -118.956328)
		(width 0.127)
		(layer "In6.Cu")
		(net "PWRGD_DRAMPWRGD_CPU0_AB_LVC1_R2")
	)
	(segment
		(start 206.26324 -124.719588)
		(end 192.14084 -124.719588)
		(width 0.127)
		(layer "In6.Cu")
		(net "PWRGD_DRAMPWRGD_CPU0_AB_LVC1_R2")
	)
	(segment
		(start 183.96966 -120.175528)
		(end 183.75503 -119.960898)
		(width 0.127)
		(layer "In6.Cu")
		(net "PWRGD_DRAMPWRGD_CPU0_AB_LVC1_R2")
	)
	(segment
		(start 218.77782 -123.769628)
		(end 207.2132 -123.769628)
		(width 0.127)
		(layer "In6.Cu")
		(net "PWRGD_DRAMPWRGD_CPU0_AB_LVC1_R2")
	)
	(segment
		(start 183.75503 -119.960898)
		(end 183.75503 -119.602758)
		(width 0.127)
		(layer "In6.Cu")
		(net "PWRGD_DRAMPWRGD_CPU0_AB_LVC1_R2")
	)
	(segment
		(start 182.96128 -118.788688)
		(end 182.75046 -118.577868)
		(width 0.127)
		(layer "In6.Cu")
		(net "PWRGD_DRAMPWRGD_CPU0_AB_LVC1_R2")
	)
	(segment
		(start 174.555658 -105.939844)
		(end 174.95774 -105.537762)
		(width 0.127)
		(layer "In6.Cu")
		(net "PWRGD_DRAMPWRGD_CPU0_AB_LVC1_R2")
	)
	(segment
		(start 174.555658 -107.169966)
		(end 174.555658 -105.939844)
		(width 0.127)
		(layer "In6.Cu")
		(net "PWRGD_DRAMPWRGD_CPU0_AB_LVC1_R2")
	)
	(segment
		(start 178.63312 -113.787428)
		(end 177.86604 -113.020348)
		(width 0.127)
		(layer "In6.Cu")
		(net "PWRGD_DRAMPWRGD_CPU0_AB_LVC1_R2")
	)
	(segment
		(start 183.75503 -119.602758)
		(end 183.5277 -119.375428)
		(width 0.127)
		(layer "In6.Cu")
		(net "PWRGD_DRAMPWRGD_CPU0_AB_LVC1_R2")
	)
	(segment
		(start 178.63312 -117.744748)
		(end 178.63312 -113.787428)
		(width 0.127)
		(layer "In6.Cu")
		(net "PWRGD_DRAMPWRGD_CPU0_AB_LVC1_R2")
	)
	(segment
		(start 174.95774 -105.537762)
		(end 174.95774 -105.065068)
		(width 0.127)
		(layer "In6.Cu")
		(net "PWRGD_DRAMPWRGD_CPU0_AB_LVC1_R2")
	)
	(segment
		(start 174.96028 -107.574588)
		(end 174.555658 -107.169966)
		(width 0.127)
		(layer "In6.Cu")
		(net "PWRGD_DRAMPWRGD_CPU0_AB_LVC1_R2")
	)
	(segment
		(start 142.956026 -101.297994)
		(end 143.43888 -101.780848)
		(width 0.12954)
		(layer "F.Cu")
		(net "PD_GTL2014_ERROR_B0")
	)
	(segment
		(start 143.9545 -101.780848)
		(end 144.6784 -102.504748)
		(width 0.12954)
		(layer "F.Cu")
		(net "PD_GTL2014_ERROR_B0")
	)
	(segment
		(start 143.97482 -103.208328)
		(end 143.97482 -106.274108)
		(width 0.12954)
		(layer "F.Cu")
		(net "PD_GTL2014_ERROR_B0")
	)
	(segment
		(start 144.554448 -106.578908)
		(end 144.564608 -106.568748)
		(width 0.12954)
		(layer "F.Cu")
		(net "PD_GTL2014_ERROR_B0")
	)
	(segment
		(start 142.956026 -100.729542)
		(end 142.956026 -101.297994)
		(width 0.12954)
		(layer "F.Cu")
		(net "PD_GTL2014_ERROR_B0")
	)
	(segment
		(start 143.43888 -101.780848)
		(end 143.9545 -101.780848)
		(width 0.12954)
		(layer "F.Cu")
		(net "PD_GTL2014_ERROR_B0")
	)
	(segment
		(start 143.97482 -106.274108)
		(end 144.27962 -106.578908)
		(width 0.12954)
		(layer "F.Cu")
		(net "PD_GTL2014_ERROR_B0")
	)
	(segment
		(start 144.27962 -106.578908)
		(end 144.554448 -106.578908)
		(width 0.12954)
		(layer "F.Cu")
		(net "PD_GTL2014_ERROR_B0")
	)
	(segment
		(start 144.6784 -102.504748)
		(end 143.97482 -103.208328)
		(width 0.12954)
		(layer "F.Cu")
		(net "PD_GTL2014_ERROR_B0")
	)
	(via
		(at 144.6784 -102.504748)
		(size 0.762)
		(drill 0.381)
		(layers "F.Cu" "B.Cu")
		(net "PD_GTL2014_ERROR_B0")
	)
	(segment
		(start 144.9578 -100.188268)
		(end 144.9578 -100.879148)
		(width 0.12954)
		(layer "F.Cu")
		(net "PD_CPU1_ERRS_U306_DIR")
	)
	(segment
		(start 143.606012 -100.729542)
		(end 143.606012 -100.186236)
		(width 0.12954)
		(layer "F.Cu")
		(net "PD_CPU1_ERRS_U306_DIR")
	)
	(segment
		(start 144.69618 -99.926648)
		(end 144.9578 -100.188268)
		(width 0.12954)
		(layer "F.Cu")
		(net "PD_CPU1_ERRS_U306_DIR")
	)
	(segment
		(start 144.6022 -103.495348)
		(end 144.6022 -103.716328)
		(width 0.12954)
		(layer "F.Cu")
		(net "PD_CPU1_ERRS_U306_DIR")
	)
	(segment
		(start 144.9578 -100.879148)
		(end 145.3388 -101.260148)
		(width 0.12954)
		(layer "F.Cu")
		(net "PD_CPU1_ERRS_U306_DIR")
	)
	(segment
		(start 145.3388 -101.260148)
		(end 145.3388 -102.758748)
		(width 0.12954)
		(layer "F.Cu")
		(net "PD_CPU1_ERRS_U306_DIR")
	)
	(segment
		(start 143.606012 -100.186236)
		(end 143.8656 -99.926648)
		(width 0.12954)
		(layer "F.Cu")
		(net "PD_CPU1_ERRS_U306_DIR")
	)
	(segment
		(start 145.3388 -102.758748)
		(end 144.6022 -103.495348)
		(width 0.12954)
		(layer "F.Cu")
		(net "PD_CPU1_ERRS_U306_DIR")
	)
	(segment
		(start 143.8656 -99.926648)
		(end 144.69618 -99.926648)
		(width 0.12954)
		(layer "F.Cu")
		(net "PD_CPU1_ERRS_U306_DIR")
	)
	(via
		(at 144.9578 -100.879148)
		(size 0.762)
		(drill 0.381)
		(layers "F.Cu" "B.Cu")
		(net "PD_CPU1_ERRS_U306_DIR")
	)
	(segment
		(start 196.76364 -68.001388)
		(end 196.68744 -68.001388)
		(width 0.12954)
		(layer "F.Cu")
		(net "P3V3_E1S_GATE_0_PU293")
	)
	(segment
		(start 195.764912 -68.923916)
		(end 195.350638 -68.923916)
		(width 0.12954)
		(layer "F.Cu")
		(net "P3V3_E1S_GATE_0_PU293")
	)
	(segment
		(start 198.01459 -68.026788)
		(end 197.98919 -68.001388)
		(width 0.12954)
		(layer "F.Cu")
		(net "P3V3_E1S_GATE_0_PU293")
	)
	(segment
		(start 197.98919 -68.001388)
		(end 196.76364 -68.001388)
		(width 0.12954)
		(layer "F.Cu")
		(net "P3V3_E1S_GATE_0_PU293")
	)
	(segment
		(start 196.68744 -68.001388)
		(end 195.764912 -68.923916)
		(width 0.12954)
		(layer "F.Cu")
		(net "P3V3_E1S_GATE_0_PU293")
	)
	(via
		(at 196.76364 -68.001388)
		(size 0.762)
		(drill 0.381)
		(layers "F.Cu" "B.Cu")
		(net "P3V3_E1S_GATE_0_PU293")
	)
	(segment
		(start 141.88186 -102.539038)
		(end 141.656054 -102.313232)
		(width 0.12954)
		(layer "F.Cu")
		(net "P0V62_CPU0_ERRS_U306_VREF")
	)
	(segment
		(start 141.656054 -102.313232)
		(end 141.656054 -100.729542)
		(width 0.12954)
		(layer "F.Cu")
		(net "P0V62_CPU0_ERRS_U306_VREF")
	)
	(segment
		(start 142.0622 -103.716328)
		(end 142.0622 -102.693978)
		(width 0.12954)
		(layer "F.Cu")
		(net "P0V62_CPU0_ERRS_U306_VREF")
	)
	(segment
		(start 141.88186 -102.513638)
		(end 141.88186 -102.539038)
		(width 0.12954)
		(layer "F.Cu")
		(net "P0V62_CPU0_ERRS_U306_VREF")
	)
	(segment
		(start 141.4272 -105.329228)
		(end 141.4272 -104.351328)
		(width 0.12954)
		(layer "F.Cu")
		(net "P0V62_CPU0_ERRS_U306_VREF")
	)
	(segment
		(start 142.0622 -105.964228)
		(end 141.4272 -105.329228)
		(width 0.12954)
		(layer "F.Cu")
		(net "P0V62_CPU0_ERRS_U306_VREF")
	)
	(segment
		(start 142.06982 -108.621068)
		(end 141.3256 -107.876848)
		(width 0.12954)
		(layer "F.Cu")
		(net "P0V62_CPU0_ERRS_U306_VREF")
	)
	(segment
		(start 144.3736 -107.795568)
		(end 144.3736 -108.458508)
		(width 0.12954)
		(layer "F.Cu")
		(net "P0V62_CPU0_ERRS_U306_VREF")
	)
	(segment
		(start 141.3256 -107.876848)
		(end 141.3256 -106.700828)
		(width 0.12954)
		(layer "F.Cu")
		(net "P0V62_CPU0_ERRS_U306_VREF")
	)
	(segment
		(start 142.0622 -102.693978)
		(end 141.88186 -102.513638)
		(width 0.12954)
		(layer "F.Cu")
		(net "P0V62_CPU0_ERRS_U306_VREF")
	)
	(segment
		(start 141.4272 -104.351328)
		(end 142.0622 -103.716328)
		(width 0.12954)
		(layer "F.Cu")
		(net "P0V62_CPU0_ERRS_U306_VREF")
	)
	(segment
		(start 144.21104 -108.621068)
		(end 142.06982 -108.621068)
		(width 0.12954)
		(layer "F.Cu")
		(net "P0V62_CPU0_ERRS_U306_VREF")
	)
	(segment
		(start 141.3256 -106.700828)
		(end 142.0622 -105.964228)
		(width 0.12954)
		(layer "F.Cu")
		(net "P0V62_CPU0_ERRS_U306_VREF")
	)
	(segment
		(start 144.3736 -108.458508)
		(end 144.21104 -108.621068)
		(width 0.12954)
		(layer "F.Cu")
		(net "P0V62_CPU0_ERRS_U306_VREF")
	)
	(via
		(at 141.88186 -102.513638)
		(size 0.762)
		(drill 0.381)
		(layers "F.Cu" "B.Cu")
		(net "P0V62_CPU0_ERRS_U306_VREF")
	)
	(segment
		(start 142.956026 -93.98254)
		(end 142.956026 -94.887542)
		(width 0.12954)
		(layer "F.Cu")
		(net "NC_U306_A0")
	)
	(segment
		(start 143.112236 -93.82633)
		(end 142.956026 -93.98254)
		(width 0.12954)
		(layer "F.Cu")
		(net "NC_U306_A0")
	)
	(segment
		(start 146.363182 -94.991174)
		(end 146.363182 -94.530418)
		(width 0.12954)
		(layer "F.Cu")
		(net "NC_U306_A0")
	)
	(segment
		(start 145.659094 -93.82633)
		(end 143.112236 -93.82633)
		(width 0.12954)
		(layer "F.Cu")
		(net "NC_U306_A0")
	)
	(segment
		(start 146.363182 -94.530418)
		(end 145.659094 -93.82633)
		(width 0.12954)
		(layer "F.Cu")
		(net "NC_U306_A0")
	)
	(segment
		(start 146.534378 -95.16237)
		(end 146.363182 -94.991174)
		(width 0.12954)
		(layer "F.Cu")
		(net "NC_U306_A0")
	)
	(via
		(at 146.534378 -95.16237)
		(size 0.762)
		(drill 0.381)
		(layers "F.Cu" "B.Cu")
		(net "NC_U306_A0")
	)
	(via
		(at 40.21709 -410.070808)
		(size 0.508)
		(drill 0.254)
		(layers "F.Cu" "B.Cu")
		(net "NC_J112_S5")
	)
	(segment
		(start 67.36207 -417.21151)
		(end 67.36207 -418.17798)
		(width 0.127)
		(layer "In15.Cu")
		(net "NC_J112_S5")
	)
	(segment
		(start 48.919638 -411.642306)
		(end 53.350414 -411.642306)
		(width 0.127)
		(layer "In15.Cu")
		(net "NC_J112_S5")
	)
	(segment
		(start 66.210688 -414.431988)
		(end 67.36207 -417.21151)
		(width 0.127)
		(layer "In15.Cu")
		(net "NC_J112_S5")
	)
	(segment
		(start 67.36207 -418.17798)
		(end 66.650108 -418.889942)
		(width 0.127)
		(layer "In15.Cu")
		(net "NC_J112_S5")
	)
	(segment
		(start 64.515492 -412.736792)
		(end 66.210688 -414.431988)
		(width 0.127)
		(layer "In15.Cu")
		(net "NC_J112_S5")
	)
	(segment
		(start 47.34814 -410.070808)
		(end 48.919638 -411.642306)
		(width 0.127)
		(layer "In15.Cu")
		(net "NC_J112_S5")
	)
	(segment
		(start 54.4449 -412.736792)
		(end 64.515492 -412.736792)
		(width 0.127)
		(layer "In15.Cu")
		(net "NC_J112_S5")
	)
	(segment
		(start 53.350414 -411.642306)
		(end 54.4449 -412.736792)
		(width 0.127)
		(layer "In15.Cu")
		(net "NC_J112_S5")
	)
	(segment
		(start 40.21709 -410.070808)
		(end 47.34814 -410.070808)
		(width 0.127)
		(layer "In15.Cu")
		(net "NC_J112_S5")
	)
	(via
		(at 38.614604 -409.991052)
		(size 0.508)
		(drill 0.254)
		(layers "F.Cu" "B.Cu")
		(net "NC_J112_R5")
	)
	(segment
		(start 49.028858 -411.21457)
		(end 53.527706 -411.21457)
		(width 0.127)
		(layer "In15.Cu")
		(net "NC_J112_R5")
	)
	(segment
		(start 64.784732 -412.309056)
		(end 66.557144 -414.081468)
		(width 0.127)
		(layer "In15.Cu")
		(net "NC_J112_R5")
	)
	(segment
		(start 47.31766 -409.503372)
		(end 49.028858 -411.21457)
		(width 0.127)
		(layer "In15.Cu")
		(net "NC_J112_R5")
	)
	(segment
		(start 67.829938 -418.910008)
		(end 66.650108 -420.089838)
		(width 0.127)
		(layer "In15.Cu")
		(net "NC_J112_R5")
	)
	(segment
		(start 53.527706 -411.21457)
		(end 54.622192 -412.309056)
		(width 0.127)
		(layer "In15.Cu")
		(net "NC_J112_R5")
	)
	(segment
		(start 54.622192 -412.309056)
		(end 64.784732 -412.309056)
		(width 0.127)
		(layer "In15.Cu")
		(net "NC_J112_R5")
	)
	(segment
		(start 39.102284 -409.503372)
		(end 47.31766 -409.503372)
		(width 0.127)
		(layer "In15.Cu")
		(net "NC_J112_R5")
	)
	(segment
		(start 67.829938 -417.154106)
		(end 67.829938 -418.910008)
		(width 0.127)
		(layer "In15.Cu")
		(net "NC_J112_R5")
	)
	(segment
		(start 66.557144 -414.081468)
		(end 67.829938 -417.154106)
		(width 0.127)
		(layer "In15.Cu")
		(net "NC_J112_R5")
	)
	(segment
		(start 38.614604 -409.991052)
		(end 39.102284 -409.503372)
		(width 0.127)
		(layer "In15.Cu")
		(net "NC_J112_R5")
	)
	(via
		(at 64.67475 -414.617916)
		(size 0.6604)
		(drill 0.3302)
		(layers "F.Cu" "B.Cu")
		(net "NC_J112_P5")
	)
	(segment
		(start 65.878964 -417.096448)
		(end 65.878964 -421.71874)
		(width 0.12954)
		(layer "B.Cu")
		(net "NC_J112_P5")
	)
	(segment
		(start 65.878964 -421.71874)
		(end 66.650108 -422.489884)
		(width 0.12954)
		(layer "B.Cu")
		(net "NC_J112_P5")
	)
	(segment
		(start 64.67475 -415.892234)
		(end 65.878964 -417.096448)
		(width 0.12954)
		(layer "B.Cu")
		(net "NC_J112_P5")
	)
	(segment
		(start 64.67475 -414.617916)
		(end 64.67475 -415.892234)
		(width 0.12954)
		(layer "B.Cu")
		(net "NC_J112_P5")
	)
	(via
		(at 62.704218 -414.697418)
		(size 0.6604)
		(drill 0.3302)
		(layers "F.Cu" "B.Cu")
		(net "NC_J112_O5")
	)
	(segment
		(start 65.40119 -422.440862)
		(end 65.40119 -417.39439)
		(width 0.12954)
		(layer "B.Cu")
		(net "NC_J112_O5")
	)
	(segment
		(start 66.650108 -423.68978)
		(end 65.40119 -422.440862)
		(width 0.12954)
		(layer "B.Cu")
		(net "NC_J112_O5")
	)
	(segment
		(start 65.40119 -417.39439)
		(end 62.704218 -414.697418)
		(width 0.12954)
		(layer "B.Cu")
		(net "NC_J112_O5")
	)
	(via
		(at 56.79186 -415.50336)
		(size 0.6604)
		(drill 0.3302)
		(layers "F.Cu" "B.Cu")
		(net "NC_J112_O2")
	)
	(segment
		(start 59.906916 -416.90671)
		(end 59.906916 -422.746678)
		(width 0.12954)
		(layer "B.Cu")
		(net "NC_J112_O2")
	)
	(segment
		(start 56.79186 -415.50336)
		(end 58.503566 -415.50336)
		(width 0.12954)
		(layer "B.Cu")
		(net "NC_J112_O2")
	)
	(segment
		(start 58.503566 -415.50336)
		(end 59.906916 -416.90671)
		(width 0.12954)
		(layer "B.Cu")
		(net "NC_J112_O2")
	)
	(segment
		(start 59.906916 -422.746678)
		(end 60.65012 -423.489882)
		(width 0.12954)
		(layer "B.Cu")
		(net "NC_J112_O2")
	)
	(via
		(at 55.916068 -416.613086)
		(size 0.6604)
		(drill 0.3302)
		(layers "F.Cu" "B.Cu")
		(net "NC_J112_N2")
	)
	(segment
		(start 59.429142 -417.304728)
		(end 59.429142 -423.4688)
		(width 0.12954)
		(layer "B.Cu")
		(net "NC_J112_N2")
	)
	(segment
		(start 59.429142 -423.4688)
		(end 60.65012 -424.689778)
		(width 0.12954)
		(layer "B.Cu")
		(net "NC_J112_N2")
	)
	(segment
		(start 55.916068 -416.613086)
		(end 58.7375 -416.613086)
		(width 0.12954)
		(layer "B.Cu")
		(net "NC_J112_N2")
	)
	(segment
		(start 58.7375 -416.613086)
		(end 59.429142 -417.304728)
		(width 0.12954)
		(layer "B.Cu")
		(net "NC_J112_N2")
	)
	(via
		(at 323.735192 -421.763444)
		(size 0.6604)
		(drill 0.3302)
		(layers "F.Cu" "B.Cu")
		(net "NC_J108_N6")
	)
	(segment
		(start 324.6501 -422.678352)
		(end 323.735192 -421.763444)
		(width 0.12954)
		(layer "B.Cu")
		(net "NC_J108_N6")
	)
	(segment
		(start 324.6501 -424.689778)
		(end 324.6501 -422.678352)
		(width 0.12954)
		(layer "B.Cu")
		(net "NC_J108_N6")
	)
	(via
		(at 319.895982 -421.763444)
		(size 0.6604)
		(drill 0.3302)
		(layers "F.Cu" "B.Cu")
		(net "NC_J108_N4")
	)
	(segment
		(start 320.650108 -424.689778)
		(end 320.650108 -422.51757)
		(width 0.12954)
		(layer "B.Cu")
		(net "NC_J108_N4")
	)
	(segment
		(start 320.650108 -422.51757)
		(end 319.895982 -421.763444)
		(width 0.12954)
		(layer "B.Cu")
		(net "NC_J108_N4")
	)
	(via
		(at 316.650116 -421.678608)
		(size 0.6604)
		(drill 0.3302)
		(layers "F.Cu" "B.Cu")
		(net "NC_J108_N2")
	)
	(segment
		(start 316.650116 -424.689778)
		(end 316.650116 -421.678608)
		(width 0.12954)
		(layer "B.Cu")
		(net "NC_J108_N2")
	)
	(via
		(at 337.650074 -421.73906)
		(size 0.6604)
		(drill 0.3302)
		(layers "F.Cu" "B.Cu")
		(net "NC_J107_N4")
	)
	(segment
		(start 337.650074 -424.689778)
		(end 337.650074 -421.73906)
		(width 0.12954)
		(layer "B.Cu")
		(net "NC_J107_N4")
	)
	(via
		(at 338.762086 -420.431214)
		(size 0.6604)
		(drill 0.3302)
		(layers "F.Cu" "B.Cu")
		(net "NC_J107_A5")
	)
	(segment
		(start 338.762086 -440.400186)
		(end 338.851748 -440.489848)
		(width 0.12954)
		(layer "B.Cu")
		(net "NC_J107_A5")
	)
	(segment
		(start 338.762086 -420.431214)
		(end 338.762086 -440.400186)
		(width 0.12954)
		(layer "B.Cu")
		(net "NC_J107_A5")
	)
	(segment
		(start 338.851748 -440.489848)
		(end 339.65007 -440.489848)
		(width 0.12954)
		(layer "B.Cu")
		(net "NC_J107_A5")
	)
	(via
		(at 334.810354 -420.438326)
		(size 0.6604)
		(drill 0.3302)
		(layers "F.Cu" "B.Cu")
		(net "NC_J107_A3")
	)
	(segment
		(start 334.969612 -440.489848)
		(end 335.650078 -440.489848)
		(width 0.12954)
		(layer "B.Cu")
		(net "NC_J107_A3")
	)
	(segment
		(start 334.810354 -440.33059)
		(end 334.969612 -440.489848)
		(width 0.12954)
		(layer "B.Cu")
		(net "NC_J107_A3")
	)
	(segment
		(start 334.810354 -420.438326)
		(end 334.810354 -440.33059)
		(width 0.12954)
		(layer "B.Cu")
		(net "NC_J107_A3")
	)
	(via
		(at 332.535276 -420.43477)
		(size 0.6604)
		(drill 0.3302)
		(layers "F.Cu" "B.Cu")
		(net "NC_J107_A1")
	)
	(segment
		(start 330.670154 -440.489848)
		(end 331.650086 -440.489848)
		(width 0.12954)
		(layer "B.Cu")
		(net "NC_J107_A1")
	)
	(segment
		(start 330.41971 -440.239404)
		(end 330.670154 -440.489848)
		(width 0.12954)
		(layer "B.Cu")
		(net "NC_J107_A1")
	)
	(segment
		(start 332.535276 -420.43477)
		(end 330.41971 -422.550336)
		(width 0.12954)
		(layer "B.Cu")
		(net "NC_J107_A1")
	)
	(segment
		(start 330.41971 -422.550336)
		(end 330.41971 -440.239404)
		(width 0.12954)
		(layer "B.Cu")
		(net "NC_J107_A1")
	)
	(via
		(at 388.876794 -421.779192)
		(size 0.6604)
		(drill 0.3302)
		(layers "F.Cu" "B.Cu")
		(net "NC_J106_A5")
	)
	(segment
		(start 389.154162 -440.489848)
		(end 389.750046 -440.489848)
		(width 0.12954)
		(layer "B.Cu")
		(net "NC_J106_A5")
	)
	(segment
		(start 388.876794 -440.21248)
		(end 389.154162 -440.489848)
		(width 0.12954)
		(layer "B.Cu")
		(net "NC_J106_A5")
	)
	(segment
		(start 388.876794 -421.779192)
		(end 388.876794 -440.21248)
		(width 0.12954)
		(layer "B.Cu")
		(net "NC_J106_A5")
	)
	(segment
		(start 125.65888 -94.065598)
		(end 126.01448 -94.421198)
		(width 0.12954)
		(layer "F.Cu")
		(net "H_CPU1_THERMTRIP_VT_R_N")
	)
	(segment
		(start 125.65888 -93.074998)
		(end 125.65888 -94.065598)
		(width 0.12954)
		(layer "F.Cu")
		(net "H_CPU1_THERMTRIP_VT_R_N")
	)
	(segment
		(start 126.01448 -94.421198)
		(end 126.01448 -95.358204)
		(width 0.12954)
		(layer "F.Cu")
		(net "H_CPU1_THERMTRIP_VT_R_N")
	)
	(via
		(at 125.65888 -94.065598)
		(size 0.762)
		(drill 0.381)
		(layers "F.Cu" "B.Cu")
		(net "H_CPU1_THERMTRIP_VT_R_N")
	)
	(segment
		(start 126.764542 -95.358204)
		(end 126.764542 -94.744286)
		(width 0.12954)
		(layer "F.Cu")
		(net "H_CPU1_THERMTRIP_VT_N")
	)
	(segment
		(start 126.67488 -93.53042)
		(end 126.67488 -93.074998)
		(width 0.12954)
		(layer "F.Cu")
		(net "H_CPU1_THERMTRIP_VT_N")
	)
	(segment
		(start 127.17018 -94.02572)
		(end 126.67488 -93.53042)
		(width 0.12954)
		(layer "F.Cu")
		(net "H_CPU1_THERMTRIP_VT_N")
	)
	(segment
		(start 127.69088 -93.074998)
		(end 126.67488 -93.074998)
		(width 0.12954)
		(layer "F.Cu")
		(net "H_CPU1_THERMTRIP_VT_N")
	)
	(segment
		(start 127.17018 -94.338648)
		(end 127.17018 -94.02572)
		(width 0.12954)
		(layer "F.Cu")
		(net "H_CPU1_THERMTRIP_VT_N")
	)
	(segment
		(start 126.764542 -94.744286)
		(end 127.17018 -94.338648)
		(width 0.12954)
		(layer "F.Cu")
		(net "H_CPU1_THERMTRIP_VT_N")
	)
	(via
		(at 127.17018 -94.02572)
		(size 0.762)
		(drill 0.381)
		(layers "F.Cu" "B.Cu")
		(net "H_CPU1_THERMTRIP_VT_N")
	)
	(segment
		(start 127.05588 -99.405948)
		(end 127.05588 -98.72472)
		(width 0.12954)
		(layer "F.Cu")
		(net "H_CPU1_THERMTRIP_R_N")
	)
	(segment
		(start 127.05588 -99.405948)
		(end 126.05893 -99.405948)
		(width 0.12954)
		(layer "F.Cu")
		(net "H_CPU1_THERMTRIP_R_N")
	)
	(segment
		(start 126.01448 -97.68332)
		(end 126.01448 -97.158048)
		(width 0.12954)
		(layer "F.Cu")
		(net "H_CPU1_THERMTRIP_R_N")
	)
	(segment
		(start 127.05588 -98.72472)
		(end 126.01448 -97.68332)
		(width 0.12954)
		(layer "F.Cu")
		(net "H_CPU1_THERMTRIP_R_N")
	)
	(via
		(at 127.05588 -99.405948)
		(size 0.762)
		(drill 0.381)
		(layers "F.Cu" "B.Cu")
		(net "H_CPU1_THERMTRIP_R_N")
	)
	(segment
		(start 124.66574 -98.46056)
		(end 124.66574 -98.08464)
		(width 0.12954)
		(layer "F.Cu")
		(net "H_CPU1_THERMTRIP_N")
	)
	(segment
		(start 125.25883 -99.405948)
		(end 124.976128 -99.405948)
		(width 0.12954)
		(layer "F.Cu")
		(net "H_CPU1_THERMTRIP_N")
	)
	(segment
		(start 124.976128 -99.405948)
		(end 124.66574 -99.09556)
		(width 0.12954)
		(layer "F.Cu")
		(net "H_CPU1_THERMTRIP_N")
	)
	(segment
		(start 124.66574 -98.08464)
		(end 125.264418 -97.485962)
		(width 0.12954)
		(layer "F.Cu")
		(net "H_CPU1_THERMTRIP_N")
	)
	(segment
		(start 124.66574 -99.09556)
		(end 124.66574 -98.46056)
		(width 0.12954)
		(layer "F.Cu")
		(net "H_CPU1_THERMTRIP_N")
	)
	(segment
		(start 125.264418 -97.485962)
		(end 125.264418 -97.158048)
		(width 0.12954)
		(layer "F.Cu")
		(net "H_CPU1_THERMTRIP_N")
	)
	(via
		(at 124.66574 -98.46056)
		(size 0.762)
		(drill 0.381)
		(layers "F.Cu" "B.Cu")
		(net "H_CPU1_THERMTRIP_N")
	)
	(segment
		(start 134.409942 -102.824026)
		(end 134.82828 -102.824026)
		(width 0.12954)
		(layer "F.Cu")
		(net "H_CPU1_MEMTRIP_VT_N")
	)
	(segment
		(start 134.82828 -102.824026)
		(end 135.56488 -102.087426)
		(width 0.12954)
		(layer "F.Cu")
		(net "H_CPU1_MEMTRIP_VT_N")
	)
	(segment
		(start 135.56488 -100.567998)
		(end 134.54888 -100.567998)
		(width 0.12954)
		(layer "F.Cu")
		(net "H_CPU1_MEMTRIP_VT_N")
	)
	(segment
		(start 135.56488 -102.087426)
		(end 135.56488 -101.64064)
		(width 0.12954)
		(layer "F.Cu")
		(net "H_CPU1_MEMTRIP_VT_N")
	)
	(segment
		(start 135.56488 -101.64064)
		(end 135.56488 -100.567998)
		(width 0.12954)
		(layer "F.Cu")
		(net "H_CPU1_MEMTRIP_VT_N")
	)
	(via
		(at 135.56488 -101.64064)
		(size 0.762)
		(drill 0.381)
		(layers "F.Cu" "B.Cu")
		(net "H_CPU1_MEMTRIP_VT_N")
	)
	(segment
		(start 133.65988 -105.12552)
		(end 134.60984 -106.07548)
		(width 0.12954)
		(layer "F.Cu")
		(net "H_CPU1_MEMTRIP_R")
	)
	(segment
		(start 134.147052 -106.898948)
		(end 133.67893 -106.898948)
		(width 0.12954)
		(layer "F.Cu")
		(net "H_CPU1_MEMTRIP_R")
	)
	(segment
		(start 134.60984 -106.07548)
		(end 134.60984 -106.43616)
		(width 0.12954)
		(layer "F.Cu")
		(net "H_CPU1_MEMTRIP_R")
	)
	(segment
		(start 134.60984 -106.43616)
		(end 134.147052 -106.898948)
		(width 0.12954)
		(layer "F.Cu")
		(net "H_CPU1_MEMTRIP_R")
	)
	(segment
		(start 133.65988 -104.62387)
		(end 133.65988 -105.12552)
		(width 0.12954)
		(layer "F.Cu")
		(net "H_CPU1_MEMTRIP_R")
	)
	(via
		(at 134.60984 -106.07548)
		(size 0.762)
		(drill 0.381)
		(layers "F.Cu" "B.Cu")
		(net "H_CPU1_MEMTRIP_R")
	)
	(segment
		(start 133.53288 -100.567998)
		(end 133.52018 -100.580698)
		(width 0.12954)
		(layer "F.Cu")
		(net "H_CPU1_MEMTRIP_OUT_VT_R_N")
	)
	(segment
		(start 133.65988 -102.072948)
		(end 133.65988 -102.824026)
		(width 0.12954)
		(layer "F.Cu")
		(net "H_CPU1_MEMTRIP_OUT_VT_R_N")
	)
	(segment
		(start 133.52018 -101.5619)
		(end 133.52018 -101.933248)
		(width 0.12954)
		(layer "F.Cu")
		(net "H_CPU1_MEMTRIP_OUT_VT_R_N")
	)
	(segment
		(start 133.52018 -100.580698)
		(end 133.52018 -101.5619)
		(width 0.12954)
		(layer "F.Cu")
		(net "H_CPU1_MEMTRIP_OUT_VT_R_N")
	)
	(segment
		(start 133.52018 -101.933248)
		(end 133.65988 -102.072948)
		(width 0.12954)
		(layer "F.Cu")
		(net "H_CPU1_MEMTRIP_OUT_VT_R_N")
	)
	(via
		(at 133.52018 -101.5619)
		(size 0.762)
		(drill 0.381)
		(layers "F.Cu" "B.Cu")
		(net "H_CPU1_MEMTRIP_OUT_VT_R_N")
	)
	(segment
		(start 132.27304 -106.293158)
		(end 132.27304 -105.94594)
		(width 0.12954)
		(layer "F.Cu")
		(net "H_CPU1_MEMTRIP")
	)
	(segment
		(start 132.87883 -106.898948)
		(end 132.27304 -106.293158)
		(width 0.12954)
		(layer "F.Cu")
		(net "H_CPU1_MEMTRIP")
	)
	(segment
		(start 132.909818 -105.309162)
		(end 132.909818 -104.62387)
		(width 0.12954)
		(layer "F.Cu")
		(net "H_CPU1_MEMTRIP")
	)
	(segment
		(start 132.27304 -105.94594)
		(end 132.909818 -105.309162)
		(width 0.12954)
		(layer "F.Cu")
		(net "H_CPU1_MEMTRIP")
	)
	(via
		(at 132.27304 -105.94594)
		(size 0.762)
		(drill 0.381)
		(layers "F.Cu" "B.Cu")
		(net "H_CPU1_MEMTRIP")
	)
	(segment
		(start 134.04088 -94.08922)
		(end 134.42188 -94.47022)
		(width 0.12954)
		(layer "F.Cu")
		(net "H_CPU1_MEMHOT_OUT_VT_R_N")
	)
	(segment
		(start 134.04088 -93.074998)
		(end 134.04088 -94.08922)
		(width 0.12954)
		(layer "F.Cu")
		(net "H_CPU1_MEMHOT_OUT_VT_R_N")
	)
	(segment
		(start 134.42188 -94.47022)
		(end 134.42188 -95.458026)
		(width 0.12954)
		(layer "F.Cu")
		(net "H_CPU1_MEMHOT_OUT_VT_R_N")
	)
	(via
		(at 134.04088 -94.08922)
		(size 0.762)
		(drill 0.381)
		(layers "F.Cu" "B.Cu")
		(net "H_CPU1_MEMHOT_OUT_VT_R_N")
	)
	(segment
		(start 136.12114 -94.0943)
		(end 135.171942 -95.043498)
		(width 0.12954)
		(layer "F.Cu")
		(net "H_CPU1_MEMHOT_OUT_VT_N")
	)
	(segment
		(start 136.07288 -93.074998)
		(end 136.12114 -93.123258)
		(width 0.12954)
		(layer "F.Cu")
		(net "H_CPU1_MEMHOT_OUT_VT_N")
	)
	(segment
		(start 136.07288 -93.074998)
		(end 135.05688 -93.074998)
		(width 0.12954)
		(layer "F.Cu")
		(net "H_CPU1_MEMHOT_OUT_VT_N")
	)
	(segment
		(start 136.12114 -93.123258)
		(end 136.12114 -94.0943)
		(width 0.12954)
		(layer "F.Cu")
		(net "H_CPU1_MEMHOT_OUT_VT_N")
	)
	(segment
		(start 135.171942 -95.043498)
		(end 135.171942 -95.458026)
		(width 0.12954)
		(layer "F.Cu")
		(net "H_CPU1_MEMHOT_OUT_VT_N")
	)
	(via
		(at 136.12114 -94.0943)
		(size 0.762)
		(drill 0.381)
		(layers "F.Cu" "B.Cu")
		(net "H_CPU1_MEMHOT_OUT_VT_N")
	)
	(segment
		(start 134.42188 -98.130614)
		(end 134.025894 -98.5266)
		(width 0.12954)
		(layer "F.Cu")
		(net "H_CPU1_MEMHOT_OUT_R")
	)
	(segment
		(start 132.29082 -98.51136)
		(end 132.29082 -97.525078)
		(width 0.12954)
		(layer "F.Cu")
		(net "H_CPU1_MEMHOT_OUT_R")
	)
	(segment
		(start 132.30606 -98.5266)
		(end 132.29082 -98.51136)
		(width 0.12954)
		(layer "F.Cu")
		(net "H_CPU1_MEMHOT_OUT_R")
	)
	(segment
		(start 134.42188 -97.25787)
		(end 134.42188 -98.130614)
		(width 0.12954)
		(layer "F.Cu")
		(net "H_CPU1_MEMHOT_OUT_R")
	)
	(segment
		(start 134.025894 -98.5266)
		(end 132.30606 -98.5266)
		(width 0.12954)
		(layer "F.Cu")
		(net "H_CPU1_MEMHOT_OUT_R")
	)
	(via
		(at 132.30606 -98.5266)
		(size 0.762)
		(drill 0.381)
		(layers "F.Cu" "B.Cu")
		(net "H_CPU1_MEMHOT_OUT_R")
	)
	(segment
		(start 132.29082 -95.72244)
		(end 132.898134 -95.72244)
		(width 0.12954)
		(layer "F.Cu")
		(net "H_CPU1_MEMHOT_OUT")
	)
	(segment
		(start 133.671818 -96.496124)
		(end 133.671818 -97.25787)
		(width 0.12954)
		(layer "F.Cu")
		(net "H_CPU1_MEMHOT_OUT")
	)
	(segment
		(start 132.29082 -96.724978)
		(end 132.29082 -95.72244)
		(width 0.12954)
		(layer "F.Cu")
		(net "H_CPU1_MEMHOT_OUT")
	)
	(segment
		(start 132.898134 -95.72244)
		(end 133.671818 -96.496124)
		(width 0.12954)
		(layer "F.Cu")
		(net "H_CPU1_MEMHOT_OUT")
	)
	(via
		(at 132.29082 -95.72244)
		(size 0.762)
		(drill 0.381)
		(layers "F.Cu" "B.Cu")
		(net "H_CPU1_MEMHOT_OUT")
	)
	(segment
		(start 198.45528 -101.145848)
		(end 197.81393 -101.145848)
		(width 0.12954)
		(layer "F.Cu")
		(net "H_CPU1_MEMHOT_IN_LVC1_R1_N")
	)
	(segment
		(start 200.62063 -99.939348)
		(end 200.62063 -101.145848)
		(width 0.12954)
		(layer "F.Cu")
		(net "H_CPU1_MEMHOT_IN_LVC1_R1_N")
	)
	(segment
		(start 200.62063 -101.145848)
		(end 198.45528 -101.145848)
		(width 0.12954)
		(layer "F.Cu")
		(net "H_CPU1_MEMHOT_IN_LVC1_R1_N")
	)
	(via
		(at 198.45528 -101.145848)
		(size 0.508)
		(drill 0.254)
		(layers "F.Cu" "B.Cu")
		(net "H_CPU1_MEMHOT_IN_LVC1_R1_N")
	)
	(segment
		(start 121.964196 -94.060264)
		(end 122.61088 -94.706948)
		(width 0.12954)
		(layer "F.Cu")
		(net "H_CPU0_THERMTRIP_VT_R_N")
	)
	(segment
		(start 122.61088 -94.706948)
		(end 122.61088 -95.331026)
		(width 0.12954)
		(layer "F.Cu")
		(net "H_CPU0_THERMTRIP_VT_R_N")
	)
	(segment
		(start 121.59488 -93.690948)
		(end 121.964196 -94.060264)
		(width 0.12954)
		(layer "F.Cu")
		(net "H_CPU0_THERMTRIP_VT_R_N")
	)
	(segment
		(start 121.59488 -93.074998)
		(end 121.59488 -93.690948)
		(width 0.12954)
		(layer "F.Cu")
		(net "H_CPU0_THERMTRIP_VT_R_N")
	)
	(via
		(at 121.964196 -94.060264)
		(size 0.762)
		(drill 0.381)
		(layers "F.Cu" "B.Cu")
		(net "H_CPU0_THERMTRIP_VT_R_N")
	)
	(segment
		(start 123.360942 -94.059756)
		(end 123.62688 -93.793818)
		(width 0.12954)
		(layer "F.Cu")
		(net "H_CPU0_THERMTRIP_VT_N")
	)
	(segment
		(start 122.61088 -93.074998)
		(end 123.62688 -93.074998)
		(width 0.12954)
		(layer "F.Cu")
		(net "H_CPU0_THERMTRIP_VT_N")
	)
	(segment
		(start 123.360942 -95.331026)
		(end 123.360942 -94.059756)
		(width 0.12954)
		(layer "F.Cu")
		(net "H_CPU0_THERMTRIP_VT_N")
	)
	(segment
		(start 123.62688 -93.793818)
		(end 123.62688 -93.074998)
		(width 0.12954)
		(layer "F.Cu")
		(net "H_CPU0_THERMTRIP_VT_N")
	)
	(via
		(at 123.360942 -94.059756)
		(size 0.762)
		(drill 0.381)
		(layers "F.Cu" "B.Cu")
		(net "H_CPU0_THERMTRIP_VT_N")
	)
	(segment
		(start 122.61088 -97.13087)
		(end 122.61088 -98.39198)
		(width 0.12954)
		(layer "F.Cu")
		(net "H_CPU0_THERMTRIP_R_N")
	)
	(segment
		(start 122.61088 -98.39198)
		(end 122.61088 -99.259898)
		(width 0.12954)
		(layer "F.Cu")
		(net "H_CPU0_THERMTRIP_R_N")
	)
	(segment
		(start 122.61088 -99.259898)
		(end 122.75693 -99.405948)
		(width 0.12954)
		(layer "F.Cu")
		(net "H_CPU0_THERMTRIP_R_N")
	)
	(via
		(at 122.61088 -98.39198)
		(size 0.762)
		(drill 0.381)
		(layers "F.Cu" "B.Cu")
		(net "H_CPU0_THERMTRIP_R_N")
	)
	(segment
		(start 120.15724 -97.48647)
		(end 120.51284 -97.13087)
		(width 0.12954)
		(layer "F.Cu")
		(net "H_CPU0_THERMTRIP_N")
	)
	(segment
		(start 120.15724 -98.55708)
		(end 120.15724 -97.48647)
		(width 0.12954)
		(layer "F.Cu")
		(net "H_CPU0_THERMTRIP_N")
	)
	(segment
		(start 121.006108 -99.405948)
		(end 120.15724 -98.55708)
		(width 0.12954)
		(layer "F.Cu")
		(net "H_CPU0_THERMTRIP_N")
	)
	(segment
		(start 121.95683 -99.405948)
		(end 121.006108 -99.405948)
		(width 0.12954)
		(layer "F.Cu")
		(net "H_CPU0_THERMTRIP_N")
	)
	(segment
		(start 120.51284 -97.13087)
		(end 121.860818 -97.13087)
		(width 0.12954)
		(layer "F.Cu")
		(net "H_CPU0_THERMTRIP_N")
	)
	(via
		(at 120.51284 -97.13087)
		(size 0.762)
		(drill 0.381)
		(layers "F.Cu" "B.Cu")
		(net "H_CPU0_THERMTRIP_N")
	)
	(segment
		(start 131.43484 -102.6287)
		(end 131.43484 -101.58984)
		(width 0.12954)
		(layer "F.Cu")
		(net "H_CPU0_MEMTRIP_VT_N")
	)
	(segment
		(start 131.50088 -100.567998)
		(end 131.50088 -101.5238)
		(width 0.12954)
		(layer "F.Cu")
		(net "H_CPU0_MEMTRIP_VT_N")
	)
	(segment
		(start 131.50088 -100.567998)
		(end 130.48488 -100.567998)
		(width 0.12954)
		(layer "F.Cu")
		(net "H_CPU0_MEMTRIP_VT_N")
	)
	(segment
		(start 131.239514 -102.824026)
		(end 131.43484 -102.6287)
		(width 0.12954)
		(layer "F.Cu")
		(net "H_CPU0_MEMTRIP_VT_N")
	)
	(segment
		(start 130.345942 -102.824026)
		(end 131.239514 -102.824026)
		(width 0.12954)
		(layer "F.Cu")
		(net "H_CPU0_MEMTRIP_VT_N")
	)
	(segment
		(start 131.50088 -101.5238)
		(end 131.43484 -101.58984)
		(width 0.12954)
		(layer "F.Cu")
		(net "H_CPU0_MEMTRIP_VT_N")
	)
	(via
		(at 131.43484 -101.58984)
		(size 0.762)
		(drill 0.381)
		(layers "F.Cu" "B.Cu")
		(net "H_CPU0_MEMTRIP_VT_N")
	)
	(segment
		(start 129.86893 -106.18343)
		(end 129.86893 -106.898948)
		(width 0.12954)
		(layer "F.Cu")
		(net "H_CPU0_MEMTRIP_R")
	)
	(segment
		(start 129.59588 -105.91038)
		(end 129.86893 -106.18343)
		(width 0.12954)
		(layer "F.Cu")
		(net "H_CPU0_MEMTRIP_R")
	)
	(segment
		(start 129.59588 -104.62387)
		(end 129.59588 -105.91038)
		(width 0.12954)
		(layer "F.Cu")
		(net "H_CPU0_MEMTRIP_R")
	)
	(via
		(at 129.59588 -105.91038)
		(size 0.762)
		(drill 0.381)
		(layers "F.Cu" "B.Cu")
		(net "H_CPU0_MEMTRIP_R")
	)
	(segment
		(start 129.20726 -101.5619)
		(end 129.20726 -102.00894)
		(width 0.12954)
		(layer "F.Cu")
		(net "H_CPU0_MEMTRIP_OUT_VT_R_N")
	)
	(segment
		(start 129.46888 -101.30028)
		(end 129.20726 -101.5619)
		(width 0.12954)
		(layer "F.Cu")
		(net "H_CPU0_MEMTRIP_OUT_VT_R_N")
	)
	(segment
		(start 129.46888 -100.567998)
		(end 129.46888 -101.30028)
		(width 0.12954)
		(layer "F.Cu")
		(net "H_CPU0_MEMTRIP_OUT_VT_R_N")
	)
	(segment
		(start 129.59588 -102.39756)
		(end 129.59588 -102.824026)
		(width 0.12954)
		(layer "F.Cu")
		(net "H_CPU0_MEMTRIP_OUT_VT_R_N")
	)
	(segment
		(start 129.20726 -102.00894)
		(end 129.59588 -102.39756)
		(width 0.12954)
		(layer "F.Cu")
		(net "H_CPU0_MEMTRIP_OUT_VT_R_N")
	)
	(via
		(at 129.20726 -101.5619)
		(size 0.762)
		(drill 0.381)
		(layers "F.Cu" "B.Cu")
		(net "H_CPU0_MEMTRIP_OUT_VT_R_N")
	)
	(segment
		(start 127.51816 -106.53014)
		(end 127.886968 -106.898948)
		(width 0.12954)
		(layer "F.Cu")
		(net "H_CPU0_MEMTRIP")
	)
	(segment
		(start 128.845818 -104.62387)
		(end 127.51816 -104.62387)
		(width 0.12954)
		(layer "F.Cu")
		(net "H_CPU0_MEMTRIP")
	)
	(segment
		(start 127.51816 -104.62387)
		(end 127.51816 -106.53014)
		(width 0.12954)
		(layer "F.Cu")
		(net "H_CPU0_MEMTRIP")
	)
	(segment
		(start 127.886968 -106.898948)
		(end 129.06883 -106.898948)
		(width 0.12954)
		(layer "F.Cu")
		(net "H_CPU0_MEMTRIP")
	)
	(via
		(at 127.51816 -104.62387)
		(size 0.762)
		(drill 0.381)
		(layers "F.Cu" "B.Cu")
		(net "H_CPU0_MEMTRIP")
	)
	(segment
		(start 129.72288 -94.071694)
		(end 130.10388 -94.452694)
		(width 0.12954)
		(layer "F.Cu")
		(net "H_CPU0_MEMHOT_OUT_VT_R_N")
	)
	(segment
		(start 129.72288 -93.074998)
		(end 129.72288 -94.071694)
		(width 0.12954)
		(layer "F.Cu")
		(net "H_CPU0_MEMHOT_OUT_VT_R_N")
	)
	(segment
		(start 130.10388 -94.452694)
		(end 130.10388 -95.331026)
		(width 0.12954)
		(layer "F.Cu")
		(net "H_CPU0_MEMHOT_OUT_VT_R_N")
	)
	(via
		(at 129.72288 -94.071694)
		(size 0.762)
		(drill 0.381)
		(layers "F.Cu" "B.Cu")
		(net "H_CPU0_MEMHOT_OUT_VT_R_N")
	)
	(segment
		(start 131.68376 -94.09176)
		(end 131.68376 -94.501208)
		(width 0.12954)
		(layer "F.Cu")
		(net "H_CPU0_MEMHOT_OUT_VT_N")
	)
	(segment
		(start 131.3307 -94.0435)
		(end 130.73888 -93.45168)
		(width 0.12954)
		(layer "F.Cu")
		(net "H_CPU0_MEMHOT_OUT_VT_N")
	)
	(segment
		(start 131.68376 -94.501208)
		(end 130.853942 -95.331026)
		(width 0.12954)
		(layer "F.Cu")
		(net "H_CPU0_MEMHOT_OUT_VT_N")
	)
	(segment
		(start 131.75488 -93.074998)
		(end 130.73888 -93.074998)
		(width 0.12954)
		(layer "F.Cu")
		(net "H_CPU0_MEMHOT_OUT_VT_N")
	)
	(segment
		(start 130.73888 -93.45168)
		(end 130.73888 -93.074998)
		(width 0.12954)
		(layer "F.Cu")
		(net "H_CPU0_MEMHOT_OUT_VT_N")
	)
	(segment
		(start 131.6355 -94.0435)
		(end 131.3307 -94.0435)
		(width 0.12954)
		(layer "F.Cu")
		(net "H_CPU0_MEMHOT_OUT_VT_N")
	)
	(segment
		(start 131.6355 -94.0435)
		(end 131.68376 -94.09176)
		(width 0.12954)
		(layer "F.Cu")
		(net "H_CPU0_MEMHOT_OUT_VT_N")
	)
	(via
		(at 131.6355 -94.0435)
		(size 0.762)
		(drill 0.381)
		(layers "F.Cu" "B.Cu")
		(net "H_CPU0_MEMHOT_OUT_VT_N")
	)
	(segment
		(start 128.02616 -97.93224)
		(end 129.743454 -97.93224)
		(width 0.12954)
		(layer "F.Cu")
		(net "H_CPU0_MEMHOT_OUT_R")
	)
	(segment
		(start 128.02616 -96.895158)
		(end 128.02616 -97.93224)
		(width 0.12954)
		(layer "F.Cu")
		(net "H_CPU0_MEMHOT_OUT_R")
	)
	(segment
		(start 130.10388 -97.571814)
		(end 130.10388 -97.13087)
		(width 0.12954)
		(layer "F.Cu")
		(net "H_CPU0_MEMHOT_OUT_R")
	)
	(segment
		(start 129.743454 -97.93224)
		(end 130.10388 -97.571814)
		(width 0.12954)
		(layer "F.Cu")
		(net "H_CPU0_MEMHOT_OUT_R")
	)
	(via
		(at 128.02616 -97.93224)
		(size 0.762)
		(drill 0.381)
		(layers "F.Cu" "B.Cu")
		(net "H_CPU0_MEMHOT_OUT_R")
	)
	(segment
		(start 128.02616 -96.095058)
		(end 128.02616 -95.07728)
		(width 0.12954)
		(layer "F.Cu")
		(net "H_CPU0_MEMHOT_OUT")
	)
	(segment
		(start 128.83134 -96.133158)
		(end 129.353818 -96.655636)
		(width 0.12954)
		(layer "F.Cu")
		(net "H_CPU0_MEMHOT_OUT")
	)
	(segment
		(start 128.02616 -95.07728)
		(end 128.493012 -95.07728)
		(width 0.12954)
		(layer "F.Cu")
		(net "H_CPU0_MEMHOT_OUT")
	)
	(segment
		(start 128.493012 -95.07728)
		(end 128.83134 -95.415608)
		(width 0.12954)
		(layer "F.Cu")
		(net "H_CPU0_MEMHOT_OUT")
	)
	(segment
		(start 129.353818 -96.655636)
		(end 129.353818 -97.13087)
		(width 0.12954)
		(layer "F.Cu")
		(net "H_CPU0_MEMHOT_OUT")
	)
	(segment
		(start 128.83134 -95.415608)
		(end 128.83134 -96.133158)
		(width 0.12954)
		(layer "F.Cu")
		(net "H_CPU0_MEMHOT_OUT")
	)
	(via
		(at 128.02616 -95.07728)
		(size 0.762)
		(drill 0.381)
		(layers "F.Cu" "B.Cu")
		(net "H_CPU0_MEMHOT_OUT")
	)
	(segment
		(start 181.15788 -98.643948)
		(end 181.15788 -97.519998)
		(width 0.12954)
		(layer "F.Cu")
		(net "H_CPU0_MEMHOT_IN_LVC1_R1_N")
	)
	(segment
		(start 181.15788 -99.259898)
		(end 181.15788 -98.643948)
		(width 0.12954)
		(layer "F.Cu")
		(net "H_CPU0_MEMHOT_IN_LVC1_R1_N")
	)
	(segment
		(start 181.15788 -97.519998)
		(end 180.01488 -97.519998)
		(width 0.12954)
		(layer "F.Cu")
		(net "H_CPU0_MEMHOT_IN_LVC1_R1_N")
	)
	(via
		(at 181.15788 -98.643948)
		(size 0.508)
		(drill 0.254)
		(layers "F.Cu" "B.Cu")
		(net "H_CPU0_MEMHOT_IN_LVC1_R1_N")
	)
	(segment
		(start 331.428598 -74.633074)
		(end 331.125068 -74.329544)
		(width 0.13208)
		(layer "F.Cu")
		(net "CLK_100M_PE_M2_0_R_DP")
	)
	(segment
		(start 336.49285 -55.028846)
		(end 335.953608 -55.028846)
		(width 0.13208)
		(layer "F.Cu")
		(net "CLK_100M_PE_M2_0_R_DP")
	)
	(segment
		(start 331.099668 -75.737974)
		(end 331.428598 -75.409044)
		(width 0.13208)
		(layer "F.Cu")
		(net "CLK_100M_PE_M2_0_R_DP")
	)
	(segment
		(start 331.428598 -75.409044)
		(end 331.428598 -74.633074)
		(width 0.13208)
		(layer "F.Cu")
		(net "CLK_100M_PE_M2_0_R_DP")
	)
	(segment
		(start 331.099668 -75.753468)
		(end 331.099668 -75.737974)
		(width 0.13208)
		(layer "F.Cu")
		(net "CLK_100M_PE_M2_0_R_DP")
	)
	(via
		(at 331.125068 -74.329544)
		(size 0.508)
		(drill 0.254)
		(layers "F.Cu" "B.Cu")
		(net "CLK_100M_PE_M2_0_R_DP")
	)
	(via
		(at 335.953608 -55.028846)
		(size 0.4572)
		(drill 0.2032)
		(layers "F.Cu" "B.Cu")
		(net "CLK_100M_PE_M2_0_R_DP")
	)
	(segment
		(start 334.421226 -60.386468)
		(end 331.344016 -63.463932)
		(width 0.14732)
		(layer "In4.Cu")
		(net "CLK_100M_PE_M2_0_R_DP")
	)
	(segment
		(start 335.045558 -59.45251)
		(end 334.421226 -60.386468)
		(width 0.14732)
		(layer "In4.Cu")
		(net "CLK_100M_PE_M2_0_R_DP")
	)
	(segment
		(start 335.47177 -57.729628)
		(end 335.47177 -58.42381)
		(width 0.14732)
		(layer "In4.Cu")
		(net "CLK_100M_PE_M2_0_R_DP")
	)
	(segment
		(start 335.47177 -58.42381)
		(end 335.045558 -59.45251)
		(width 0.14732)
		(layer "In4.Cu")
		(net "CLK_100M_PE_M2_0_R_DP")
	)
	(segment
		(start 331.419454 -73.44918)
		(end 331.419708 -73.449434)
		(width 0.14732)
		(layer "In4.Cu")
		(net "CLK_100M_PE_M2_0_R_DP")
	)
	(segment
		(start 330.644754 -65.152778)
		(end 330.644754 -69.552058)
		(width 0.14732)
		(layer "In4.Cu")
		(net "CLK_100M_PE_M2_0_R_DP")
	)
	(segment
		(start 335.47177 -57.70753)
		(end 335.47177 -57.729628)
		(width 0.0889)
		(layer "In4.Cu")
		(net "CLK_100M_PE_M2_0_R_DP")
	)
	(segment
		(start 331.419708 -73.449434)
		(end 331.419708 -74.034904)
		(width 0.14732)
		(layer "In4.Cu")
		(net "CLK_100M_PE_M2_0_R_DP")
	)
	(segment
		(start 331.419708 -74.034904)
		(end 331.125068 -74.329544)
		(width 0.14732)
		(layer "In4.Cu")
		(net "CLK_100M_PE_M2_0_R_DP")
	)
	(segment
		(start 335.513934 -57.3786)
		(end 335.513934 -57.665366)
		(width 0.0889)
		(layer "In4.Cu")
		(net "CLK_100M_PE_M2_0_R_DP")
	)
	(segment
		(start 335.953608 -55.34152)
		(end 335.888838 -55.40629)
		(width 0.0889)
		(layer "In4.Cu")
		(net "CLK_100M_PE_M2_0_R_DP")
	)
	(segment
		(start 335.513934 -57.665366)
		(end 335.47177 -57.70753)
		(width 0.0889)
		(layer "In4.Cu")
		(net "CLK_100M_PE_M2_0_R_DP")
	)
	(segment
		(start 330.644754 -69.552058)
		(end 331.419454 -73.44918)
		(width 0.14732)
		(layer "In4.Cu")
		(net "CLK_100M_PE_M2_0_R_DP")
	)
	(segment
		(start 331.344016 -63.463932)
		(end 330.644754 -65.152778)
		(width 0.14732)
		(layer "In4.Cu")
		(net "CLK_100M_PE_M2_0_R_DP")
	)
	(segment
		(start 335.953608 -55.028846)
		(end 335.953608 -55.34152)
		(width 0.0889)
		(layer "In4.Cu")
		(net "CLK_100M_PE_M2_0_R_DP")
	)
	(arc
		(start 335.866232 -55.409338)
		(mid 335.633457 -55.501958)
		(end 335.463388 -55.685944)
		(width 0.0889)
		(layer "In4.Cu")
		(net "CLK_100M_PE_M2_0_R_DP")
	)
	(arc
		(start 335.463388 -56.251348)
		(mid 335.513429 -56.438546)
		(end 335.463388 -56.625744)
		(width 0.0889)
		(layer "In4.Cu")
		(net "CLK_100M_PE_M2_0_R_DP")
	)
	(arc
		(start 335.463388 -56.625744)
		(mid 335.387714 -56.908446)
		(end 335.463388 -57.191148)
		(width 0.0889)
		(layer "In4.Cu")
		(net "CLK_100M_PE_M2_0_R_DP")
	)
	(arc
		(start 335.888838 -55.40629)
		(mid 335.877519 -55.407699)
		(end 335.866232 -55.409338)
		(width 0.0889)
		(layer "In4.Cu")
		(net "CLK_100M_PE_M2_0_R_DP")
	)
	(arc
		(start 335.463388 -55.685944)
		(mid 335.387714 -55.968646)
		(end 335.463388 -56.251348)
		(width 0.0889)
		(layer "In4.Cu")
		(net "CLK_100M_PE_M2_0_R_DP")
	)
	(arc
		(start 335.463388 -57.191148)
		(mid 335.501006 -57.281548)
		(end 335.513934 -57.3786)
		(width 0.0889)
		(layer "In4.Cu")
		(net "CLK_100M_PE_M2_0_R_DP")
	)
	(segment
		(start 336.49285 -55.968646)
		(end 335.953608 -55.968646)
		(width 0.13208)
		(layer "F.Cu")
		(net "CLK_100M_PE_M2_0_R_DN")
	)
	(segment
		(start 332.029562 -75.753468)
		(end 331.687678 -75.411584)
		(width 0.13208)
		(layer "F.Cu")
		(net "CLK_100M_PE_M2_0_R_DN")
	)
	(segment
		(start 331.687678 -74.630534)
		(end 331.988668 -74.329544)
		(width 0.13208)
		(layer "F.Cu")
		(net "CLK_100M_PE_M2_0_R_DN")
	)
	(segment
		(start 331.687678 -75.411584)
		(end 331.687678 -74.630534)
		(width 0.13208)
		(layer "F.Cu")
		(net "CLK_100M_PE_M2_0_R_DN")
	)
	(segment
		(start 332.115668 -75.753468)
		(end 332.029562 -75.753468)
		(width 0.13208)
		(layer "F.Cu")
		(net "CLK_100M_PE_M2_0_R_DN")
	)
	(via
		(at 335.953608 -55.968646)
		(size 0.4572)
		(drill 0.2032)
		(layers "F.Cu" "B.Cu")
		(net "CLK_100M_PE_M2_0_R_DN")
	)
	(via
		(at 331.988668 -74.329544)
		(size 0.508)
		(drill 0.254)
		(layers "F.Cu" "B.Cu")
		(net "CLK_100M_PE_M2_0_R_DN")
	)
	(segment
		(start 335.953608 -55.655972)
		(end 335.895696 -55.59806)
		(width 0.0889)
		(layer "In4.Cu")
		(net "CLK_100M_PE_M2_0_R_DN")
	)
	(segment
		(start 331.694028 -73.422002)
		(end 331.694028 -74.034904)
		(width 0.14732)
		(layer "In4.Cu")
		(net "CLK_100M_PE_M2_0_R_DN")
	)
	(segment
		(start 335.953608 -55.968646)
		(end 335.953608 -55.655972)
		(width 0.0889)
		(layer "In4.Cu")
		(net "CLK_100M_PE_M2_0_R_DN")
	)
	(segment
		(start 330.919074 -69.52488)
		(end 331.694028 -73.422002)
		(width 0.14732)
		(layer "In4.Cu")
		(net "CLK_100M_PE_M2_0_R_DN")
	)
	(segment
		(start 333.1972 -61.998606)
		(end 331.57668 -63.61938)
		(width 0.14732)
		(layer "In4.Cu")
		(net "CLK_100M_PE_M2_0_R_DN")
	)
	(segment
		(start 331.57668 -63.61938)
		(end 330.919074 -65.207388)
		(width 0.14732)
		(layer "In4.Cu")
		(net "CLK_100M_PE_M2_0_R_DN")
	)
	(segment
		(start 330.919074 -65.207388)
		(end 330.919074 -69.52488)
		(width 0.14732)
		(layer "In4.Cu")
		(net "CLK_100M_PE_M2_0_R_DN")
	)
	(segment
		(start 333.655416 -61.54039)
		(end 333.655416 -61.738002)
		(width 0.14732)
		(layer "In4.Cu")
		(net "CLK_100M_PE_M2_0_R_DN")
	)
	(segment
		(start 333.655416 -61.738002)
		(end 333.394812 -61.998606)
		(width 0.14732)
		(layer "In4.Cu")
		(net "CLK_100M_PE_M2_0_R_DN")
	)
	(segment
		(start 335.74609 -57.70753)
		(end 335.74609 -57.729628)
		(width 0.0889)
		(layer "In4.Cu")
		(net "CLK_100M_PE_M2_0_R_DN")
	)
	(segment
		(start 333.394812 -61.998606)
		(end 333.1972 -61.998606)
		(width 0.14732)
		(layer "In4.Cu")
		(net "CLK_100M_PE_M2_0_R_DN")
	)
	(segment
		(start 334.373982 -60.821824)
		(end 334.373982 -61.019436)
		(width 0.14732)
		(layer "In4.Cu")
		(net "CLK_100M_PE_M2_0_R_DN")
	)
	(segment
		(start 334.113378 -61.28004)
		(end 333.915766 -61.28004)
		(width 0.14732)
		(layer "In4.Cu")
		(net "CLK_100M_PE_M2_0_R_DN")
	)
	(segment
		(start 331.694028 -74.034904)
		(end 331.988668 -74.329544)
		(width 0.14732)
		(layer "In4.Cu")
		(net "CLK_100M_PE_M2_0_R_DN")
	)
	(segment
		(start 335.74609 -57.729628)
		(end 335.74609 -58.47842)
		(width 0.14732)
		(layer "In4.Cu")
		(net "CLK_100M_PE_M2_0_R_DN")
	)
	(segment
		(start 335.288636 -59.582558)
		(end 334.634332 -60.561474)
		(width 0.14732)
		(layer "In4.Cu")
		(net "CLK_100M_PE_M2_0_R_DN")
	)
	(segment
		(start 335.70418 -57.3786)
		(end 335.70418 -57.66562)
		(width 0.0889)
		(layer "In4.Cu")
		(net "CLK_100M_PE_M2_0_R_DN")
	)
	(segment
		(start 335.74609 -58.47842)
		(end 335.288636 -59.582558)
		(width 0.14732)
		(layer "In4.Cu")
		(net "CLK_100M_PE_M2_0_R_DN")
	)
	(segment
		(start 334.634332 -60.561474)
		(end 334.373982 -60.821824)
		(width 0.14732)
		(layer "In4.Cu")
		(net "CLK_100M_PE_M2_0_R_DN")
	)
	(segment
		(start 335.70418 -57.66562)
		(end 335.74609 -57.70753)
		(width 0.0889)
		(layer "In4.Cu")
		(net "CLK_100M_PE_M2_0_R_DN")
	)
	(segment
		(start 333.915766 -61.28004)
		(end 333.655416 -61.54039)
		(width 0.14732)
		(layer "In4.Cu")
		(net "CLK_100M_PE_M2_0_R_DN")
	)
	(segment
		(start 334.373982 -61.019436)
		(end 334.113378 -61.28004)
		(width 0.14732)
		(layer "In4.Cu")
		(net "CLK_100M_PE_M2_0_R_DN")
	)
	(arc
		(start 335.628488 -56.155844)
		(mid 335.704162 -56.438546)
		(end 335.628488 -56.721248)
		(width 0.0889)
		(layer "In4.Cu")
		(net "CLK_100M_PE_M2_0_R_DN")
	)
	(arc
		(start 335.628488 -56.721248)
		(mid 335.578447 -56.908446)
		(end 335.628488 -57.095644)
		(width 0.0889)
		(layer "In4.Cu")
		(net "CLK_100M_PE_M2_0_R_DN")
	)
	(arc
		(start 335.628488 -57.095644)
		(mid 335.684949 -57.232141)
		(end 335.70418 -57.3786)
		(width 0.0889)
		(layer "In4.Cu")
		(net "CLK_100M_PE_M2_0_R_DN")
	)
	(arc
		(start 335.895696 -55.59806)
		(mid 335.741295 -55.659436)
		(end 335.628488 -55.781448)
		(width 0.0889)
		(layer "In4.Cu")
		(net "CLK_100M_PE_M2_0_R_DN")
	)
	(arc
		(start 335.628488 -55.781448)
		(mid 335.578447 -55.968646)
		(end 335.628488 -56.155844)
		(width 0.0889)
		(layer "In4.Cu")
		(net "CLK_100M_PE_M2_0_R_DN")
	)
	(segment
		(start 328.58202 -73.109328)
		(end 328.90968 -72.781668)
		(width 0.13208)
		(layer "F.Cu")
		(net "CLK_100M_E1S_0_R_DP")
	)
	(segment
		(start 334.090518 -58.992262)
		(end 334.090518 -58.703972)
		(width 0.0889)
		(layer "F.Cu")
		(net "CLK_100M_E1S_0_R_DP")
	)
	(segment
		(start 333.35214 -61.194696)
		(end 334.208374 -60.3377)
		(width 0.0889)
		(layer "F.Cu")
		(net "CLK_100M_E1S_0_R_DP")
	)
	(segment
		(start 334.090518 -58.703972)
		(end 334.39862 -58.39587)
		(width 0.0889)
		(layer "F.Cu")
		(net "CLK_100M_E1S_0_R_DP")
	)
	(segment
		(start 334.208374 -60.3377)
		(end 334.208374 -59.940952)
		(width 0.0889)
		(layer "F.Cu")
		(net "CLK_100M_E1S_0_R_DP")
	)
	(segment
		(start 332.891892 -62.291468)
		(end 332.907386 -62.275974)
		(width 0.0889)
		(layer "F.Cu")
		(net "CLK_100M_E1S_0_R_DP")
	)
	(segment
		(start 334.20812 -59.940698)
		(end 334.20812 -59.109864)
		(width 0.0889)
		(layer "F.Cu")
		(net "CLK_100M_E1S_0_R_DP")
	)
	(segment
		(start 328.90968 -72.781668)
		(end 328.90968 -72.394826)
		(width 0.13208)
		(layer "F.Cu")
		(net "CLK_100M_E1S_0_R_DP")
	)
	(segment
		(start 332.907386 -62.275974)
		(end 332.956154 -62.275974)
		(width 0.0889)
		(layer "F.Cu")
		(net "CLK_100M_E1S_0_R_DP")
	)
	(segment
		(start 332.956154 -62.275974)
		(end 333.35214 -61.879988)
		(width 0.0889)
		(layer "F.Cu")
		(net "CLK_100M_E1S_0_R_DP")
	)
	(segment
		(start 329.26528 -72.039226)
		(end 329.26528 -65.91808)
		(width 0.13208)
		(layer "F.Cu")
		(net "CLK_100M_E1S_0_R_DP")
	)
	(segment
		(start 329.26528 -65.91808)
		(end 332.891892 -62.291468)
		(width 0.13208)
		(layer "F.Cu")
		(net "CLK_100M_E1S_0_R_DP")
	)
	(segment
		(start 333.35214 -61.879988)
		(end 333.35214 -61.194696)
		(width 0.0889)
		(layer "F.Cu")
		(net "CLK_100M_E1S_0_R_DP")
	)
	(segment
		(start 334.39862 -58.39587)
		(end 334.39862 -58.020204)
		(width 0.0889)
		(layer "F.Cu")
		(net "CLK_100M_E1S_0_R_DP")
	)
	(segment
		(start 328.523092 -73.109328)
		(end 328.58202 -73.109328)
		(width 0.13208)
		(layer "F.Cu")
		(net "CLK_100M_E1S_0_R_DP")
	)
	(segment
		(start 334.208374 -59.940952)
		(end 334.20812 -59.940698)
		(width 0.0889)
		(layer "F.Cu")
		(net "CLK_100M_E1S_0_R_DP")
	)
	(segment
		(start 328.90968 -72.394826)
		(end 329.26528 -72.039226)
		(width 0.13208)
		(layer "F.Cu")
		(net "CLK_100M_E1S_0_R_DP")
	)
	(segment
		(start 334.20812 -59.109864)
		(end 334.090518 -58.992262)
		(width 0.0889)
		(layer "F.Cu")
		(net "CLK_100M_E1S_0_R_DP")
	)
	(segment
		(start 334.028796 -60.923424)
		(end 334.213962 -60.738258)
		(width 0.0889)
		(layer "F.Cu")
		(net "CLK_100M_E1S_0_R_DN")
	)
	(segment
		(start 329.52436 -68.479162)
		(end 329.52436 -68.088002)
		(width 0.13208)
		(layer "F.Cu")
		(net "CLK_100M_E1S_0_R_DN")
	)
	(segment
		(start 329.524868 -73.109328)
		(end 329.43546 -73.109328)
		(width 0.13208)
		(layer "F.Cu")
		(net "CLK_100M_E1S_0_R_DN")
	)
	(segment
		(start 333.090774 -62.410594)
		(end 333.542386 -61.958982)
		(width 0.0889)
		(layer "F.Cu")
		(net "CLK_100M_E1S_0_R_DN")
	)
	(segment
		(start 329.16876 -72.502268)
		(end 329.52436 -72.146668)
		(width 0.13208)
		(layer "F.Cu")
		(net "CLK_100M_E1S_0_R_DN")
	)
	(segment
		(start 332.441296 -63.108586)
		(end 333.075026 -62.474856)
		(width 0.13208)
		(layer "F.Cu")
		(net "CLK_100M_E1S_0_R_DN")
	)
	(segment
		(start 329.52436 -69.119242)
		(end 329.64882 -68.994782)
		(width 0.13208)
		(layer "F.Cu")
		(net "CLK_100M_E1S_0_R_DN")
	)
	(segment
		(start 329.43546 -73.109328)
		(end 329.16876 -72.842628)
		(width 0.13208)
		(layer "F.Cu")
		(net "CLK_100M_E1S_0_R_DN")
	)
	(segment
		(start 329.64882 -68.603622)
		(end 329.52436 -68.479162)
		(width 0.13208)
		(layer "F.Cu")
		(net "CLK_100M_E1S_0_R_DN")
	)
	(segment
		(start 329.52436 -71.181722)
		(end 329.64882 -71.057262)
		(width 0.13208)
		(layer "F.Cu")
		(net "CLK_100M_E1S_0_R_DN")
	)
	(segment
		(start 329.64882 -70.666102)
		(end 329.52436 -70.541642)
		(width 0.13208)
		(layer "F.Cu")
		(net "CLK_100M_E1S_0_R_DN")
	)
	(segment
		(start 330.982828 -64.743076)
		(end 330.982828 -64.567054)
		(width 0.13208)
		(layer "F.Cu")
		(net "CLK_100M_E1S_0_R_DN")
	)
	(segment
		(start 329.64882 -67.572382)
		(end 329.52436 -67.447922)
		(width 0.13208)
		(layer "F.Cu")
		(net "CLK_100M_E1S_0_R_DN")
	)
	(segment
		(start 329.976734 -65.74917)
		(end 330.253594 -65.47231)
		(width 0.13208)
		(layer "F.Cu")
		(net "CLK_100M_E1S_0_R_DN")
	)
	(segment
		(start 333.542386 -61.27369)
		(end 333.892144 -60.923424)
		(width 0.0889)
		(layer "F.Cu")
		(net "CLK_100M_E1S_0_R_DN")
	)
	(segment
		(start 329.52436 -70.150482)
		(end 329.64882 -70.026022)
		(width 0.13208)
		(layer "F.Cu")
		(net "CLK_100M_E1S_0_R_DN")
	)
	(segment
		(start 331.712062 -64.013842)
		(end 331.712062 -63.83782)
		(width 0.13208)
		(layer "F.Cu")
		(net "CLK_100M_E1S_0_R_DN")
	)
	(segment
		(start 333.07528 -62.474856)
		(end 333.090774 -62.459362)
		(width 0.0889)
		(layer "F.Cu")
		(net "CLK_100M_E1S_0_R_DN")
	)
	(segment
		(start 331.435202 -64.290702)
		(end 331.712062 -64.013842)
		(width 0.13208)
		(layer "F.Cu")
		(net "CLK_100M_E1S_0_R_DN")
	)
	(segment
		(start 330.253594 -65.296288)
		(end 330.529946 -65.019936)
		(width 0.13208)
		(layer "F.Cu")
		(net "CLK_100M_E1S_0_R_DN")
	)
	(segment
		(start 332.164436 -63.561468)
		(end 332.441296 -63.284608)
		(width 0.13208)
		(layer "F.Cu")
		(net "CLK_100M_E1S_0_R_DN")
	)
	(segment
		(start 334.39862 -59.940952)
		(end 334.49768 -59.841892)
		(width 0.0889)
		(layer "F.Cu")
		(net "CLK_100M_E1S_0_R_DN")
	)
	(segment
		(start 334.49768 -59.664092)
		(end 334.39862 -59.565032)
		(width 0.0889)
		(layer "F.Cu")
		(net "CLK_100M_E1S_0_R_DN")
	)
	(segment
		(start 334.39862 -59.565032)
		(end 334.39862 -58.850276)
		(width 0.0889)
		(layer "F.Cu")
		(net "CLK_100M_E1S_0_R_DN")
	)
	(segment
		(start 333.090774 -62.459362)
		(end 333.090774 -62.410594)
		(width 0.0889)
		(layer "F.Cu")
		(net "CLK_100M_E1S_0_R_DN")
	)
	(segment
		(start 329.64882 -70.026022)
		(end 329.64882 -69.634862)
		(width 0.13208)
		(layer "F.Cu")
		(net "CLK_100M_E1S_0_R_DN")
	)
	(segment
		(start 329.52436 -66.416682)
		(end 329.52436 -66.025522)
		(width 0.13208)
		(layer "F.Cu")
		(net "CLK_100M_E1S_0_R_DN")
	)
	(segment
		(start 330.529946 -65.019936)
		(end 330.705968 -65.019936)
		(width 0.13208)
		(layer "F.Cu")
		(net "CLK_100M_E1S_0_R_DN")
	)
	(segment
		(start 329.52436 -68.088002)
		(end 329.64882 -67.963542)
		(width 0.13208)
		(layer "F.Cu")
		(net "CLK_100M_E1S_0_R_DN")
	)
	(segment
		(start 329.64882 -67.963542)
		(end 329.64882 -67.572382)
		(width 0.13208)
		(layer "F.Cu")
		(net "CLK_100M_E1S_0_R_DN")
	)
	(segment
		(start 329.64882 -66.541142)
		(end 329.52436 -66.416682)
		(width 0.13208)
		(layer "F.Cu")
		(net "CLK_100M_E1S_0_R_DN")
	)
	(segment
		(start 331.712062 -63.83782)
		(end 331.988414 -63.561468)
		(width 0.13208)
		(layer "F.Cu")
		(net "CLK_100M_E1S_0_R_DN")
	)
	(segment
		(start 333.075026 -62.474856)
		(end 333.07528 -62.474856)
		(width 0.13208)
		(layer "F.Cu")
		(net "CLK_100M_E1S_0_R_DN")
	)
	(segment
		(start 334.213962 -60.738258)
		(end 334.213962 -60.601606)
		(width 0.0889)
		(layer "F.Cu")
		(net "CLK_100M_E1S_0_R_DN")
	)
	(segment
		(start 330.982828 -64.567054)
		(end 331.25918 -64.290702)
		(width 0.13208)
		(layer "F.Cu")
		(net "CLK_100M_E1S_0_R_DN")
	)
	(segment
		(start 329.64882 -68.994782)
		(end 329.64882 -68.603622)
		(width 0.13208)
		(layer "F.Cu")
		(net "CLK_100M_E1S_0_R_DN")
	)
	(segment
		(start 329.52436 -67.056762)
		(end 329.64882 -66.932302)
		(width 0.13208)
		(layer "F.Cu")
		(net "CLK_100M_E1S_0_R_DN")
	)
	(segment
		(start 333.542386 -61.958982)
		(end 333.542386 -61.27369)
		(width 0.0889)
		(layer "F.Cu")
		(net "CLK_100M_E1S_0_R_DN")
	)
	(segment
		(start 329.52436 -69.510402)
		(end 329.52436 -69.119242)
		(width 0.13208)
		(layer "F.Cu")
		(net "CLK_100M_E1S_0_R_DN")
	)
	(segment
		(start 329.16876 -72.812148)
		(end 329.16876 -72.502268)
		(width 0.13208)
		(layer "F.Cu")
		(net "CLK_100M_E1S_0_R_DN")
	)
	(segment
		(start 329.52436 -70.541642)
		(end 329.52436 -70.150482)
		(width 0.13208)
		(layer "F.Cu")
		(net "CLK_100M_E1S_0_R_DN")
	)
	(segment
		(start 329.800712 -65.74917)
		(end 329.976734 -65.74917)
		(width 0.13208)
		(layer "F.Cu")
		(net "CLK_100M_E1S_0_R_DN")
	)
	(segment
		(start 330.705968 -65.019936)
		(end 330.982828 -64.743076)
		(width 0.13208)
		(layer "F.Cu")
		(net "CLK_100M_E1S_0_R_DN")
	)
	(segment
		(start 333.892144 -60.923424)
		(end 334.028796 -60.923424)
		(width 0.0889)
		(layer "F.Cu")
		(net "CLK_100M_E1S_0_R_DN")
	)
	(segment
		(start 331.988414 -63.561468)
		(end 332.164436 -63.561468)
		(width 0.13208)
		(layer "F.Cu")
		(net "CLK_100M_E1S_0_R_DN")
	)
	(segment
		(start 332.441296 -63.284608)
		(end 332.441296 -63.108586)
		(width 0.13208)
		(layer "F.Cu")
		(net "CLK_100M_E1S_0_R_DN")
	)
	(segment
		(start 330.253594 -65.47231)
		(end 330.253594 -65.296288)
		(width 0.13208)
		(layer "F.Cu")
		(net "CLK_100M_E1S_0_R_DN")
	)
	(segment
		(start 329.64882 -71.057262)
		(end 329.64882 -70.666102)
		(width 0.13208)
		(layer "F.Cu")
		(net "CLK_100M_E1S_0_R_DN")
	)
	(segment
		(start 329.52436 -72.146668)
		(end 329.52436 -71.181722)
		(width 0.13208)
		(layer "F.Cu")
		(net "CLK_100M_E1S_0_R_DN")
	)
	(segment
		(start 334.39862 -60.416694)
		(end 334.39862 -59.940952)
		(width 0.0889)
		(layer "F.Cu")
		(net "CLK_100M_E1S_0_R_DN")
	)
	(segment
		(start 334.213962 -60.601606)
		(end 334.39862 -60.416694)
		(width 0.0889)
		(layer "F.Cu")
		(net "CLK_100M_E1S_0_R_DN")
	)
	(segment
		(start 329.64882 -69.634862)
		(end 329.52436 -69.510402)
		(width 0.13208)
		(layer "F.Cu")
		(net "CLK_100M_E1S_0_R_DN")
	)
	(segment
		(start 329.16876 -72.842628)
		(end 329.16876 -72.812148)
		(width 0.12954)
		(layer "F.Cu")
		(net "CLK_100M_E1S_0_R_DN")
	)
	(segment
		(start 331.25918 -64.290702)
		(end 331.435202 -64.290702)
		(width 0.13208)
		(layer "F.Cu")
		(net "CLK_100M_E1S_0_R_DN")
	)
	(segment
		(start 329.52436 -67.447922)
		(end 329.52436 -67.056762)
		(width 0.13208)
		(layer "F.Cu")
		(net "CLK_100M_E1S_0_R_DN")
	)
	(segment
		(start 334.49768 -59.841892)
		(end 334.49768 -59.664092)
		(width 0.0889)
		(layer "F.Cu")
		(net "CLK_100M_E1S_0_R_DN")
	)
	(segment
		(start 329.64882 -66.932302)
		(end 329.64882 -66.541142)
		(width 0.13208)
		(layer "F.Cu")
		(net "CLK_100M_E1S_0_R_DN")
	)
	(segment
		(start 329.52436 -66.025522)
		(end 329.800712 -65.74917)
		(width 0.13208)
		(layer "F.Cu")
		(net "CLK_100M_E1S_0_R_DN")
	)
	(segment
		(start 129.29489 -25.269698)
		(end 129.251964 -25.226772)
		(width 0.13208)
		(layer "B.Cu")
		(net "USB3_PCH_TX_BUF_DP<4>")
	)
	(segment
		(start 129.990596 -25.269698)
		(end 129.29489 -25.269698)
		(width 0.13208)
		(layer "B.Cu")
		(net "USB3_PCH_TX_BUF_DP<4>")
	)
	(segment
		(start 131.4196 -24.348948)
		(end 130.911346 -24.348948)
		(width 0.13208)
		(layer "B.Cu")
		(net "USB3_PCH_TX_BUF_DP<4>")
	)
	(segment
		(start 130.911346 -24.348948)
		(end 129.990596 -25.269698)
		(width 0.13208)
		(layer "B.Cu")
		(net "USB3_PCH_TX_BUF_DP<4>")
	)
	(segment
		(start 131.66852 -24.100028)
		(end 131.4196 -24.348948)
		(width 0.13208)
		(layer "B.Cu")
		(net "USB3_PCH_TX_BUF_DP<4>")
	)
	(segment
		(start 129.251964 -25.226772)
		(end 129.065782 -25.226772)
		(width 0.13208)
		(layer "B.Cu")
		(net "USB3_PCH_TX_BUF_DP<4>")
	)
	(segment
		(start 129.29743 -25.528778)
		(end 129.249424 -25.576784)
		(width 0.13208)
		(layer "B.Cu")
		(net "USB3_PCH_TX_BUF_DN<4>")
	)
	(segment
		(start 130.098038 -25.528778)
		(end 129.29743 -25.528778)
		(width 0.13208)
		(layer "B.Cu")
		(net "USB3_PCH_TX_BUF_DN<4>")
	)
	(segment
		(start 131.4323 -24.608028)
		(end 131.018788 -24.608028)
		(width 0.13208)
		(layer "B.Cu")
		(net "USB3_PCH_TX_BUF_DN<4>")
	)
	(segment
		(start 129.249424 -25.576784)
		(end 129.065782 -25.576784)
		(width 0.13208)
		(layer "B.Cu")
		(net "USB3_PCH_TX_BUF_DN<4>")
	)
	(segment
		(start 131.66852 -24.844248)
		(end 131.4323 -24.608028)
		(width 0.13208)
		(layer "B.Cu")
		(net "USB3_PCH_TX_BUF_DN<4>")
	)
	(segment
		(start 131.66852 -24.895048)
		(end 131.66852 -24.844248)
		(width 0.13208)
		(layer "B.Cu")
		(net "USB3_PCH_TX_BUF_DN<4>")
	)
	(segment
		(start 131.018788 -24.608028)
		(end 130.098038 -25.528778)
		(width 0.13208)
		(layer "B.Cu")
		(net "USB3_PCH_TX_BUF_DN<4>")
	)
	(segment
		(start 134.344664 -21.000212)
		(end 134.206742 -21.333714)
		(width 0.13208)
		(layer "F.Cu")
		(net "USB3_PCH_TX_BUF_C_DP<4>")
	)
	(segment
		(start 135.178546 -19.626072)
		(end 135.178546 -19.816318)
		(width 0.13208)
		(layer "F.Cu")
		(net "USB3_PCH_TX_BUF_C_DP<4>")
	)
	(segment
		(start 134.732776 -20.071588)
		(end 134.478014 -20.326604)
		(width 0.13208)
		(layer "F.Cu")
		(net "USB3_PCH_TX_BUF_C_DP<4>")
	)
	(segment
		(start 133.1341 -24.051006)
		(end 133.448552 -24.365458)
		(width 0.13208)
		(layer "F.Cu")
		(net "USB3_PCH_TX_BUF_C_DP<4>")
	)
	(segment
		(start 133.82752 -22.24913)
		(end 133.651244 -22.322028)
		(width 0.13208)
		(layer "F.Cu")
		(net "USB3_PCH_TX_BUF_C_DP<4>")
	)
	(segment
		(start 133.448552 -24.365458)
		(end 133.63702 -24.365458)
		(width 0.13208)
		(layer "F.Cu")
		(net "USB3_PCH_TX_BUF_C_DP<4>")
	)
	(segment
		(start 133.272022 -23.23719)
		(end 133.1341 -23.570184)
		(width 0.13208)
		(layer "F.Cu")
		(net "USB3_PCH_TX_BUF_C_DP<4>")
	)
	(segment
		(start 133.58622 -22.83079)
		(end 133.448298 -23.164292)
		(width 0.13208)
		(layer "F.Cu")
		(net "USB3_PCH_TX_BUF_C_DP<4>")
	)
	(segment
		(start 134.030466 -21.406612)
		(end 133.892544 -21.739606)
		(width 0.13208)
		(layer "F.Cu")
		(net "USB3_PCH_TX_BUF_C_DP<4>")
	)
	(segment
		(start 133.63702 -24.365458)
		(end 133.93674 -24.065738)
		(width 0.13208)
		(layer "F.Cu")
		(net "USB3_PCH_TX_BUF_C_DP<4>")
	)
	(segment
		(start 133.513322 -22.655022)
		(end 133.58622 -22.83079)
		(width 0.13208)
		(layer "F.Cu")
		(net "USB3_PCH_TX_BUF_C_DP<4>")
	)
	(segment
		(start 133.965442 -21.915628)
		(end 133.82752 -22.24913)
		(width 0.13208)
		(layer "F.Cu")
		(net "USB3_PCH_TX_BUF_C_DP<4>")
	)
	(segment
		(start 134.271766 -20.824444)
		(end 134.344664 -21.000212)
		(width 0.13208)
		(layer "F.Cu")
		(net "USB3_PCH_TX_BUF_C_DP<4>")
	)
	(segment
		(start 133.892544 -21.739606)
		(end 133.965442 -21.915628)
		(width 0.13208)
		(layer "F.Cu")
		(net "USB3_PCH_TX_BUF_C_DP<4>")
	)
	(segment
		(start 133.651244 -22.322028)
		(end 133.513322 -22.655022)
		(width 0.13208)
		(layer "F.Cu")
		(net "USB3_PCH_TX_BUF_C_DP<4>")
	)
	(segment
		(start 134.923276 -20.071588)
		(end 134.732776 -20.071588)
		(width 0.13208)
		(layer "F.Cu")
		(net "USB3_PCH_TX_BUF_C_DP<4>")
	)
	(segment
		(start 134.478014 -20.326604)
		(end 134.271766 -20.824444)
		(width 0.13208)
		(layer "F.Cu")
		(net "USB3_PCH_TX_BUF_C_DP<4>")
	)
	(segment
		(start 133.448298 -23.164292)
		(end 133.272022 -23.23719)
		(width 0.13208)
		(layer "F.Cu")
		(net "USB3_PCH_TX_BUF_C_DP<4>")
	)
	(segment
		(start 134.206742 -21.333714)
		(end 134.030466 -21.406612)
		(width 0.13208)
		(layer "F.Cu")
		(net "USB3_PCH_TX_BUF_C_DP<4>")
	)
	(segment
		(start 135.757158 -19.047206)
		(end 135.178546 -19.626072)
		(width 0.13208)
		(layer "F.Cu")
		(net "USB3_PCH_TX_BUF_C_DP<4>")
	)
	(segment
		(start 133.1341 -23.570184)
		(end 133.1341 -24.051006)
		(width 0.13208)
		(layer "F.Cu")
		(net "USB3_PCH_TX_BUF_C_DP<4>")
	)
	(segment
		(start 136.17448 -17.336008)
		(end 136.17448 -18.04035)
		(width 0.13208)
		(layer "F.Cu")
		(net "USB3_PCH_TX_BUF_C_DP<4>")
	)
	(segment
		(start 136.346946 -16.550132)
		(end 136.346946 -17.163542)
		(width 0.13208)
		(layer "F.Cu")
		(net "USB3_PCH_TX_BUF_C_DP<4>")
	)
	(segment
		(start 136.346946 -17.163542)
		(end 136.17448 -17.336008)
		(width 0.13208)
		(layer "F.Cu")
		(net "USB3_PCH_TX_BUF_C_DP<4>")
	)
	(segment
		(start 135.178546 -19.816318)
		(end 134.923276 -20.071588)
		(width 0.13208)
		(layer "F.Cu")
		(net "USB3_PCH_TX_BUF_C_DP<4>")
	)
	(segment
		(start 136.17448 -18.04035)
		(end 135.757158 -19.047206)
		(width 0.13208)
		(layer "F.Cu")
		(net "USB3_PCH_TX_BUF_C_DP<4>")
	)
	(via
		(at 133.93674 -24.065738)
		(size 0.508)
		(drill 0.254)
		(layers "F.Cu" "B.Cu")
		(net "USB3_PCH_TX_BUF_C_DP<4>")
	)
	(segment
		(start 133.62813 -24.374348)
		(end 133.93674 -24.065738)
		(width 0.13208)
		(layer "B.Cu")
		(net "USB3_PCH_TX_BUF_C_DP<4>")
	)
	(segment
		(start 132.47878 -24.374348)
		(end 133.62813 -24.374348)
		(width 0.13208)
		(layer "B.Cu")
		(net "USB3_PCH_TX_BUF_C_DP<4>")
	)
	(segment
		(start 132.20192 -24.100028)
		(end 132.20446 -24.100028)
		(width 0.13208)
		(layer "B.Cu")
		(net "USB3_PCH_TX_BUF_C_DP<4>")
	)
	(segment
		(start 132.20446 -24.100028)
		(end 132.47878 -24.374348)
		(width 0.13208)
		(layer "B.Cu")
		(net "USB3_PCH_TX_BUF_C_DP<4>")
	)
	(segment
		(start 135.746998 -17.170146)
		(end 135.9154 -17.338548)
		(width 0.13208)
		(layer "F.Cu")
		(net "USB3_PCH_TX_BUF_C_DN<4>")
	)
	(segment
		(start 133.34111 -24.624538)
		(end 133.63194 -24.624538)
		(width 0.13208)
		(layer "F.Cu")
		(net "USB3_PCH_TX_BUF_C_DN<4>")
	)
	(segment
		(start 132.87502 -23.518622)
		(end 132.87502 -24.158448)
		(width 0.13208)
		(layer "F.Cu")
		(net "USB3_PCH_TX_BUF_C_DN<4>")
	)
	(segment
		(start 135.537448 -18.900394)
		(end 134.258304 -20.179792)
		(width 0.13208)
		(layer "F.Cu")
		(net "USB3_PCH_TX_BUF_C_DN<4>")
	)
	(segment
		(start 135.9154 -17.338548)
		(end 135.9154 -17.988534)
		(width 0.13208)
		(layer "F.Cu")
		(net "USB3_PCH_TX_BUF_C_DN<4>")
	)
	(segment
		(start 133.63194 -24.624538)
		(end 133.93674 -24.929338)
		(width 0.13208)
		(layer "F.Cu")
		(net "USB3_PCH_TX_BUF_C_DN<4>")
	)
	(segment
		(start 132.87502 -24.158448)
		(end 133.34111 -24.624538)
		(width 0.13208)
		(layer "F.Cu")
		(net "USB3_PCH_TX_BUF_C_DN<4>")
	)
	(segment
		(start 134.258304 -20.179792)
		(end 132.87502 -23.518622)
		(width 0.13208)
		(layer "F.Cu")
		(net "USB3_PCH_TX_BUF_C_DN<4>")
	)
	(segment
		(start 135.9154 -17.988534)
		(end 135.537448 -18.900394)
		(width 0.13208)
		(layer "F.Cu")
		(net "USB3_PCH_TX_BUF_C_DN<4>")
	)
	(segment
		(start 135.746998 -16.550132)
		(end 135.746998 -17.170146)
		(width 0.13208)
		(layer "F.Cu")
		(net "USB3_PCH_TX_BUF_C_DN<4>")
	)
	(via
		(at 133.93674 -24.929338)
		(size 0.508)
		(drill 0.254)
		(layers "F.Cu" "B.Cu")
		(net "USB3_PCH_TX_BUF_C_DN<4>")
	)
	(segment
		(start 132.20192 -24.895048)
		(end 132.46354 -24.633428)
		(width 0.13208)
		(layer "B.Cu")
		(net "USB3_PCH_TX_BUF_C_DN<4>")
	)
	(segment
		(start 132.46354 -24.633428)
		(end 133.64083 -24.633428)
		(width 0.13208)
		(layer "B.Cu")
		(net "USB3_PCH_TX_BUF_C_DN<4>")
	)
	(segment
		(start 133.64083 -24.633428)
		(end 133.93674 -24.929338)
		(width 0.13208)
		(layer "B.Cu")
		(net "USB3_PCH_TX_BUF_C_DN<4>")
	)
	(segment
		(start 347.724222 -52.233576)
		(end 347.546422 -52.233576)
		(width 0.0889)
		(layer "F.Cu")
		(net "USB3_PCH_RX_BUF_DP<4>")
	)
	(segment
		(start 360.89336 -54.381146)
		(end 360.500422 -53.988208)
		(width 0.13208)
		(layer "F.Cu")
		(net "USB3_PCH_RX_BUF_DP<4>")
	)
	(segment
		(start 360.89336 -55.582312)
		(end 360.89336 -54.381146)
		(width 0.13208)
		(layer "F.Cu")
		(net "USB3_PCH_RX_BUF_DP<4>")
	)
	(segment
		(start 347.447616 -52.332382)
		(end 347.269816 -52.332382)
		(width 0.0889)
		(layer "F.Cu")
		(net "USB3_PCH_RX_BUF_DP<4>")
	)
	(segment
		(start 350.308418 -53.415184)
		(end 350.209612 -53.316378)
		(width 0.0889)
		(layer "F.Cu")
		(net "USB3_PCH_RX_BUF_DP<4>")
	)
	(segment
		(start 348.90202 -52.975002)
		(end 348.77629 -52.849272)
		(width 0.0889)
		(layer "F.Cu")
		(net "USB3_PCH_RX_BUF_DP<4>")
	)
	(segment
		(start 351.592642 -53.415184)
		(end 351.414842 -53.415184)
		(width 0.0889)
		(layer "F.Cu")
		(net "USB3_PCH_RX_BUF_DP<4>")
	)
	(segment
		(start 348.244668 -52.457858)
		(end 348.119192 -52.332382)
		(width 0.0889)
		(layer "F.Cu")
		(net "USB3_PCH_RX_BUF_DP<4>")
	)
	(segment
		(start 349.201994 -53.415184)
		(end 348.90202 -53.11521)
		(width 0.0889)
		(layer "F.Cu")
		(net "USB3_PCH_RX_BUF_DP<4>")
	)
	(segment
		(start 361.19562 -55.884572)
		(end 360.89336 -55.582312)
		(width 0.13208)
		(layer "F.Cu")
		(net "USB3_PCH_RX_BUF_DP<4>")
	)
	(segment
		(start 349.755206 -53.415184)
		(end 349.6564 -53.316378)
		(width 0.0889)
		(layer "F.Cu")
		(net "USB3_PCH_RX_BUF_DP<4>")
	)
	(segment
		(start 351.138236 -53.316378)
		(end 351.03943 -53.415184)
		(width 0.0889)
		(layer "F.Cu")
		(net "USB3_PCH_RX_BUF_DP<4>")
	)
	(segment
		(start 349.379794 -53.415184)
		(end 349.201994 -53.415184)
		(width 0.0889)
		(layer "F.Cu")
		(net "USB3_PCH_RX_BUF_DP<4>")
	)
	(segment
		(start 348.119192 -52.332382)
		(end 347.823028 -52.332382)
		(width 0.0889)
		(layer "F.Cu")
		(net "USB3_PCH_RX_BUF_DP<4>")
	)
	(segment
		(start 347.269816 -52.332382)
		(end 347.149928 -52.45227)
		(width 0.0889)
		(layer "F.Cu")
		(net "USB3_PCH_RX_BUF_DP<4>")
	)
	(segment
		(start 348.636082 -52.849272)
		(end 348.510606 -52.723796)
		(width 0.0889)
		(layer "F.Cu")
		(net "USB3_PCH_RX_BUF_DP<4>")
	)
	(segment
		(start 350.031812 -53.316378)
		(end 349.933006 -53.415184)
		(width 0.0889)
		(layer "F.Cu")
		(net "USB3_PCH_RX_BUF_DP<4>")
	)
	(segment
		(start 349.4786 -53.316378)
		(end 349.379794 -53.415184)
		(width 0.0889)
		(layer "F.Cu")
		(net "USB3_PCH_RX_BUF_DP<4>")
	)
	(segment
		(start 354.174298 -53.380894)
		(end 354.1522 -53.380894)
		(width 0.0889)
		(layer "F.Cu")
		(net "USB3_PCH_RX_BUF_DP<4>")
	)
	(segment
		(start 354.1522 -53.380894)
		(end 354.11791 -53.415184)
		(width 0.0889)
		(layer "F.Cu")
		(net "USB3_PCH_RX_BUF_DP<4>")
	)
	(segment
		(start 350.585024 -53.316378)
		(end 350.486218 -53.415184)
		(width 0.0889)
		(layer "F.Cu")
		(net "USB3_PCH_RX_BUF_DP<4>")
	)
	(segment
		(start 350.486218 -53.415184)
		(end 350.308418 -53.415184)
		(width 0.0889)
		(layer "F.Cu")
		(net "USB3_PCH_RX_BUF_DP<4>")
	)
	(segment
		(start 351.03943 -53.415184)
		(end 350.86163 -53.415184)
		(width 0.0889)
		(layer "F.Cu")
		(net "USB3_PCH_RX_BUF_DP<4>")
	)
	(segment
		(start 350.209612 -53.316378)
		(end 350.031812 -53.316378)
		(width 0.0889)
		(layer "F.Cu")
		(net "USB3_PCH_RX_BUF_DP<4>")
	)
	(segment
		(start 351.414842 -53.415184)
		(end 351.316036 -53.316378)
		(width 0.0889)
		(layer "F.Cu")
		(net "USB3_PCH_RX_BUF_DP<4>")
	)
	(segment
		(start 350.762824 -53.316378)
		(end 350.585024 -53.316378)
		(width 0.0889)
		(layer "F.Cu")
		(net "USB3_PCH_RX_BUF_DP<4>")
	)
	(segment
		(start 347.546422 -52.233576)
		(end 347.447616 -52.332382)
		(width 0.0889)
		(layer "F.Cu")
		(net "USB3_PCH_RX_BUF_DP<4>")
	)
	(segment
		(start 349.933006 -53.415184)
		(end 349.755206 -53.415184)
		(width 0.0889)
		(layer "F.Cu")
		(net "USB3_PCH_RX_BUF_DP<4>")
	)
	(segment
		(start 348.510606 -52.583588)
		(end 348.384876 -52.457858)
		(width 0.0889)
		(layer "F.Cu")
		(net "USB3_PCH_RX_BUF_DP<4>")
	)
	(segment
		(start 351.968054 -53.415184)
		(end 351.869248 -53.316378)
		(width 0.0889)
		(layer "F.Cu")
		(net "USB3_PCH_RX_BUF_DP<4>")
	)
	(segment
		(start 349.6564 -53.316378)
		(end 349.4786 -53.316378)
		(width 0.0889)
		(layer "F.Cu")
		(net "USB3_PCH_RX_BUF_DP<4>")
	)
	(segment
		(start 350.86163 -53.415184)
		(end 350.762824 -53.316378)
		(width 0.0889)
		(layer "F.Cu")
		(net "USB3_PCH_RX_BUF_DP<4>")
	)
	(segment
		(start 347.149928 -52.45227)
		(end 346.799662 -52.45227)
		(width 0.0889)
		(layer "F.Cu")
		(net "USB3_PCH_RX_BUF_DP<4>")
	)
	(segment
		(start 351.316036 -53.316378)
		(end 351.138236 -53.316378)
		(width 0.0889)
		(layer "F.Cu")
		(net "USB3_PCH_RX_BUF_DP<4>")
	)
	(segment
		(start 355.481382 -53.988208)
		(end 354.874068 -53.380894)
		(width 0.13208)
		(layer "F.Cu")
		(net "USB3_PCH_RX_BUF_DP<4>")
	)
	(segment
		(start 351.691448 -53.316378)
		(end 351.592642 -53.415184)
		(width 0.0889)
		(layer "F.Cu")
		(net "USB3_PCH_RX_BUF_DP<4>")
	)
	(segment
		(start 348.77629 -52.849272)
		(end 348.636082 -52.849272)
		(width 0.0889)
		(layer "F.Cu")
		(net "USB3_PCH_RX_BUF_DP<4>")
	)
	(segment
		(start 354.11791 -53.415184)
		(end 351.968054 -53.415184)
		(width 0.0889)
		(layer "F.Cu")
		(net "USB3_PCH_RX_BUF_DP<4>")
	)
	(segment
		(start 348.510606 -52.723796)
		(end 348.510606 -52.583588)
		(width 0.0889)
		(layer "F.Cu")
		(net "USB3_PCH_RX_BUF_DP<4>")
	)
	(segment
		(start 348.90202 -53.11521)
		(end 348.90202 -52.975002)
		(width 0.0889)
		(layer "F.Cu")
		(net "USB3_PCH_RX_BUF_DP<4>")
	)
	(segment
		(start 360.500422 -53.988208)
		(end 355.481382 -53.988208)
		(width 0.13208)
		(layer "F.Cu")
		(net "USB3_PCH_RX_BUF_DP<4>")
	)
	(segment
		(start 354.874068 -53.380894)
		(end 354.174298 -53.380894)
		(width 0.13208)
		(layer "F.Cu")
		(net "USB3_PCH_RX_BUF_DP<4>")
	)
	(segment
		(start 351.869248 -53.316378)
		(end 351.691448 -53.316378)
		(width 0.0889)
		(layer "F.Cu")
		(net "USB3_PCH_RX_BUF_DP<4>")
	)
	(segment
		(start 347.823028 -52.332382)
		(end 347.724222 -52.233576)
		(width 0.0889)
		(layer "F.Cu")
		(net "USB3_PCH_RX_BUF_DP<4>")
	)
	(segment
		(start 348.384876 -52.457858)
		(end 348.244668 -52.457858)
		(width 0.0889)
		(layer "F.Cu")
		(net "USB3_PCH_RX_BUF_DP<4>")
	)
	(via
		(at 361.19562 -55.884572)
		(size 0.508)
		(drill 0.254)
		(layers "F.Cu" "B.Cu")
		(net "USB3_PCH_RX_BUF_DP<4>")
	)
	(segment
		(start 357.700072 -57.900062)
		(end 356.01402 -56.21401)
		(width 0.13208)
		(layer "B.Cu")
		(net "USB3_PCH_RX_BUF_DP<4>")
	)
	(segment
		(start 140.103098 -13.703046)
		(end 142.964662 -16.56461)
		(width 0.13208)
		(layer "B.Cu")
		(net "USB3_PCH_RX_BUF_DP<4>")
	)
	(segment
		(start 356.589838 -54.567328)
		(end 360.172762 -54.567328)
		(width 0.13208)
		(layer "B.Cu")
		(net "USB3_PCH_RX_BUF_DP<4>")
	)
	(segment
		(start 183.320944 -52.00904)
		(end 185.118756 -52.754276)
		(width 0.13208)
		(layer "B.Cu")
		(net "USB3_PCH_RX_BUF_DP<4>")
	)
	(segment
		(start 135.082026 -11.623548)
		(end 140.103098 -13.703046)
		(width 0.13208)
		(layer "B.Cu")
		(net "USB3_PCH_RX_BUF_DP<4>")
	)
	(segment
		(start 342.109806 -88.910668)
		(end 344.883486 -88.910668)
		(width 0.13208)
		(layer "B.Cu")
		(net "USB3_PCH_RX_BUF_DP<4>")
	)
	(segment
		(start 166.46398 -38.686994)
		(end 178.04892 -50.271934)
		(width 0.13208)
		(layer "B.Cu")
		(net "USB3_PCH_RX_BUF_DP<4>")
	)
	(segment
		(start 122.22226 -27.54122)
		(end 122.22226 -19.302222)
		(width 0.13208)
		(layer "B.Cu")
		(net "USB3_PCH_RX_BUF_DP<4>")
	)
	(segment
		(start 123.02109 -27.974798)
		(end 122.655838 -27.974798)
		(width 0.13208)
		(layer "B.Cu")
		(net "USB3_PCH_RX_BUF_DP<4>")
	)
	(segment
		(start 123.31192 -28.265628)
		(end 123.02109 -27.974798)
		(width 0.13208)
		(layer "B.Cu")
		(net "USB3_PCH_RX_BUF_DP<4>")
	)
	(segment
		(start 354.11537 -80.113378)
		(end 356.145084 -75.212956)
		(width 0.13208)
		(layer "B.Cu")
		(net "USB3_PCH_RX_BUF_DP<4>")
	)
	(segment
		(start 227.09378 -66.337688)
		(end 229.66934 -68.913248)
		(width 0.13208)
		(layer "B.Cu")
		(net "USB3_PCH_RX_BUF_DP<4>")
	)
	(segment
		(start 360.89336 -55.582312)
		(end 361.19562 -55.884572)
		(width 0.13208)
		(layer "B.Cu")
		(net "USB3_PCH_RX_BUF_DP<4>")
	)
	(segment
		(start 216.159842 -61.808868)
		(end 227.09378 -66.337688)
		(width 0.13208)
		(layer "B.Cu")
		(net "USB3_PCH_RX_BUF_DP<4>")
	)
	(segment
		(start 122.655838 -27.974798)
		(end 122.22226 -27.54122)
		(width 0.13208)
		(layer "B.Cu")
		(net "USB3_PCH_RX_BUF_DP<4>")
	)
	(segment
		(start 181.24551 -51.59629)
		(end 183.320944 -52.00904)
		(width 0.13208)
		(layer "B.Cu")
		(net "USB3_PCH_RX_BUF_DP<4>")
	)
	(segment
		(start 163.345622 -30.481524)
		(end 164.436806 -33.114742)
		(width 0.13208)
		(layer "B.Cu")
		(net "USB3_PCH_RX_BUF_DP<4>")
	)
	(segment
		(start 178.04892 -50.271934)
		(end 181.24551 -51.59629)
		(width 0.13208)
		(layer "B.Cu")
		(net "USB3_PCH_RX_BUF_DP<4>")
	)
	(segment
		(start 356.01402 -56.21401)
		(end 356.01402 -55.143146)
		(width 0.13208)
		(layer "B.Cu")
		(net "USB3_PCH_RX_BUF_DP<4>")
	)
	(segment
		(start 232.11409 -69.925946)
		(end 238.298736 -71.156576)
		(width 0.13208)
		(layer "B.Cu")
		(net "USB3_PCH_RX_BUF_DP<4>")
	)
	(segment
		(start 344.883486 -88.910668)
		(end 345.62542 -88.603328)
		(width 0.13208)
		(layer "B.Cu")
		(net "USB3_PCH_RX_BUF_DP<4>")
	)
	(segment
		(start 201.889614 -61.808868)
		(end 216.159842 -61.808868)
		(width 0.13208)
		(layer "B.Cu")
		(net "USB3_PCH_RX_BUF_DP<4>")
	)
	(segment
		(start 345.62542 -88.603328)
		(end 354.11537 -80.113378)
		(width 0.13208)
		(layer "B.Cu")
		(net "USB3_PCH_RX_BUF_DP<4>")
	)
	(segment
		(start 123.219718 -16.894048)
		(end 127.922274 -12.191492)
		(width 0.13208)
		(layer "B.Cu")
		(net "USB3_PCH_RX_BUF_DP<4>")
	)
	(segment
		(start 238.298736 -71.156576)
		(end 242.271296 -72.801988)
		(width 0.13208)
		(layer "B.Cu")
		(net "USB3_PCH_RX_BUF_DP<4>")
	)
	(segment
		(start 142.964662 -16.56461)
		(end 144.290288 -19.764756)
		(width 0.13208)
		(layer "B.Cu")
		(net "USB3_PCH_RX_BUF_DP<4>")
	)
	(segment
		(start 158.508192 -27.346148)
		(end 161.413698 -28.5496)
		(width 0.13208)
		(layer "B.Cu")
		(net "USB3_PCH_RX_BUF_DP<4>")
	)
	(segment
		(start 149.52599 -25.000458)
		(end 155.189174 -27.346148)
		(width 0.13208)
		(layer "B.Cu")
		(net "USB3_PCH_RX_BUF_DP<4>")
	)
	(segment
		(start 155.189174 -27.346148)
		(end 158.508192 -27.346148)
		(width 0.13208)
		(layer "B.Cu")
		(net "USB3_PCH_RX_BUF_DP<4>")
	)
	(segment
		(start 282.00096 -81.714848)
		(end 287.127442 -83.838288)
		(width 0.13208)
		(layer "B.Cu")
		(net "USB3_PCH_RX_BUF_DP<4>")
	)
	(segment
		(start 161.413698 -28.5496)
		(end 163.345622 -30.481524)
		(width 0.13208)
		(layer "B.Cu")
		(net "USB3_PCH_RX_BUF_DP<4>")
	)
	(segment
		(start 329.863958 -83.838288)
		(end 342.109806 -88.910668)
		(width 0.13208)
		(layer "B.Cu")
		(net "USB3_PCH_RX_BUF_DP<4>")
	)
	(segment
		(start 166.46398 -36.439602)
		(end 166.46398 -38.686994)
		(width 0.13208)
		(layer "B.Cu")
		(net "USB3_PCH_RX_BUF_DP<4>")
	)
	(segment
		(start 196.26199 -58.710576)
		(end 200.074784 -61.258196)
		(width 0.13208)
		(layer "B.Cu")
		(net "USB3_PCH_RX_BUF_DP<4>")
	)
	(segment
		(start 287.127442 -83.838288)
		(end 329.863958 -83.838288)
		(width 0.13208)
		(layer "B.Cu")
		(net "USB3_PCH_RX_BUF_DP<4>")
	)
	(segment
		(start 356.145084 -75.212956)
		(end 357.700072 -67.395852)
		(width 0.13208)
		(layer "B.Cu")
		(net "USB3_PCH_RX_BUF_DP<4>")
	)
	(segment
		(start 166.146734 -35.673538)
		(end 166.46398 -36.439602)
		(width 0.13208)
		(layer "B.Cu")
		(net "USB3_PCH_RX_BUF_DP<4>")
	)
	(segment
		(start 356.01402 -55.143146)
		(end 356.589838 -54.567328)
		(width 0.13208)
		(layer "B.Cu")
		(net "USB3_PCH_RX_BUF_DP<4>")
	)
	(segment
		(start 122.22226 -19.302222)
		(end 123.219718 -16.894048)
		(width 0.13208)
		(layer "B.Cu")
		(net "USB3_PCH_RX_BUF_DP<4>")
	)
	(segment
		(start 357.700072 -67.395852)
		(end 357.700072 -57.900062)
		(width 0.13208)
		(layer "B.Cu")
		(net "USB3_PCH_RX_BUF_DP<4>")
	)
	(segment
		(start 360.172762 -54.567328)
		(end 360.89336 -55.287926)
		(width 0.13208)
		(layer "B.Cu")
		(net "USB3_PCH_RX_BUF_DP<4>")
	)
	(segment
		(start 127.922274 -12.191492)
		(end 129.293366 -11.623548)
		(width 0.13208)
		(layer "B.Cu")
		(net "USB3_PCH_RX_BUF_DP<4>")
	)
	(segment
		(start 144.290288 -19.764756)
		(end 149.52599 -25.000458)
		(width 0.13208)
		(layer "B.Cu")
		(net "USB3_PCH_RX_BUF_DP<4>")
	)
	(segment
		(start 229.66934 -68.913248)
		(end 232.11409 -69.925946)
		(width 0.13208)
		(layer "B.Cu")
		(net "USB3_PCH_RX_BUF_DP<4>")
	)
	(segment
		(start 242.271296 -72.801988)
		(end 251.184156 -81.714848)
		(width 0.13208)
		(layer "B.Cu")
		(net "USB3_PCH_RX_BUF_DP<4>")
	)
	(segment
		(start 164.436806 -33.114742)
		(end 166.146734 -35.673538)
		(width 0.13208)
		(layer "B.Cu")
		(net "USB3_PCH_RX_BUF_DP<4>")
	)
	(segment
		(start 200.074784 -61.258196)
		(end 201.889614 -61.808868)
		(width 0.13208)
		(layer "B.Cu")
		(net "USB3_PCH_RX_BUF_DP<4>")
	)
	(segment
		(start 251.184156 -81.714848)
		(end 282.00096 -81.714848)
		(width 0.13208)
		(layer "B.Cu")
		(net "USB3_PCH_RX_BUF_DP<4>")
	)
	(segment
		(start 129.293366 -11.623548)
		(end 135.082026 -11.623548)
		(width 0.13208)
		(layer "B.Cu")
		(net "USB3_PCH_RX_BUF_DP<4>")
	)
	(segment
		(start 185.118756 -52.754276)
		(end 196.26199 -58.710576)
		(width 0.13208)
		(layer "B.Cu")
		(net "USB3_PCH_RX_BUF_DP<4>")
	)
	(segment
		(start 360.89336 -55.287926)
		(end 360.89336 -55.582312)
		(width 0.13208)
		(layer "B.Cu")
		(net "USB3_PCH_RX_BUF_DP<4>")
	)
	(segment
		(start 360.63428 -55.582312)
		(end 360.63428 -54.488588)
		(width 0.13208)
		(layer "F.Cu")
		(net "USB3_PCH_RX_BUF_DN<4>")
	)
	(segment
		(start 346.957142 -52.751228)
		(end 346.706952 -52.751228)
		(width 0.0889)
		(layer "F.Cu")
		(net "USB3_PCH_RX_BUF_DN<4>")
	)
	(segment
		(start 354.117656 -53.60543)
		(end 349.123 -53.60543)
		(width 0.0889)
		(layer "F.Cu")
		(net "USB3_PCH_RX_BUF_DN<4>")
	)
	(segment
		(start 354.766626 -53.639974)
		(end 354.174298 -53.639974)
		(width 0.13208)
		(layer "F.Cu")
		(net "USB3_PCH_RX_BUF_DN<4>")
	)
	(segment
		(start 347.065854 -52.642516)
		(end 346.957142 -52.751228)
		(width 0.0889)
		(layer "F.Cu")
		(net "USB3_PCH_RX_BUF_DN<4>")
	)
	(segment
		(start 349.123 -53.60543)
		(end 348.040198 -52.522628)
		(width 0.0889)
		(layer "F.Cu")
		(net "USB3_PCH_RX_BUF_DN<4>")
	)
	(segment
		(start 347.228922 -52.642516)
		(end 347.065854 -52.642516)
		(width 0.0889)
		(layer "F.Cu")
		(net "USB3_PCH_RX_BUF_DN<4>")
	)
	(segment
		(start 355.37394 -54.247288)
		(end 354.766626 -53.639974)
		(width 0.13208)
		(layer "F.Cu")
		(net "USB3_PCH_RX_BUF_DN<4>")
	)
	(segment
		(start 348.040198 -52.522628)
		(end 347.34881 -52.522628)
		(width 0.0889)
		(layer "F.Cu")
		(net "USB3_PCH_RX_BUF_DN<4>")
	)
	(segment
		(start 346.706952 -52.751228)
		(end 346.63126 -52.719986)
		(width 0.0889)
		(layer "F.Cu")
		(net "USB3_PCH_RX_BUF_DN<4>")
	)
	(segment
		(start 346.230702 -52.45227)
		(end 345.96959 -52.45227)
		(width 0.0889)
		(layer "F.Cu")
		(net "USB3_PCH_RX_BUF_DN<4>")
	)
	(segment
		(start 360.63428 -54.488588)
		(end 360.39298 -54.247288)
		(width 0.13208)
		(layer "F.Cu")
		(net "USB3_PCH_RX_BUF_DN<4>")
	)
	(segment
		(start 360.33202 -55.884572)
		(end 360.63428 -55.582312)
		(width 0.13208)
		(layer "F.Cu")
		(net "USB3_PCH_RX_BUF_DN<4>")
	)
	(segment
		(start 354.1522 -53.639974)
		(end 354.117656 -53.60543)
		(width 0.0889)
		(layer "F.Cu")
		(net "USB3_PCH_RX_BUF_DN<4>")
	)
	(segment
		(start 346.63126 -52.719986)
		(end 346.230702 -52.45227)
		(width 0.0889)
		(layer "F.Cu")
		(net "USB3_PCH_RX_BUF_DN<4>")
	)
	(segment
		(start 347.34881 -52.522628)
		(end 347.228922 -52.642516)
		(width 0.0889)
		(layer "F.Cu")
		(net "USB3_PCH_RX_BUF_DN<4>")
	)
	(segment
		(start 354.174298 -53.639974)
		(end 354.1522 -53.639974)
		(width 0.0889)
		(layer "F.Cu")
		(net "USB3_PCH_RX_BUF_DN<4>")
	)
	(segment
		(start 360.39298 -54.247288)
		(end 355.37394 -54.247288)
		(width 0.13208)
		(layer "F.Cu")
		(net "USB3_PCH_RX_BUF_DN<4>")
	)
	(via
		(at 360.33202 -55.884572)
		(size 0.508)
		(drill 0.254)
		(layers "F.Cu" "B.Cu")
		(net "USB3_PCH_RX_BUF_DN<4>")
	)
	(segment
		(start 355.260148 -78.35265)
		(end 355.405944 -78.000606)
		(width 0.13208)
		(layer "B.Cu")
		(net "USB3_PCH_RX_BUF_DN<4>")
	)
	(segment
		(start 357.20274 -54.950868)
		(end 357.58374 -54.950868)
		(width 0.13208)
		(layer "B.Cu")
		(net "USB3_PCH_RX_BUF_DN<4>")
	)
	(segment
		(start 161.266886 -28.76931)
		(end 163.125912 -30.628336)
		(width 0.13208)
		(layer "B.Cu")
		(net "USB3_PCH_RX_BUF_DN<4>")
	)
	(segment
		(start 177.902108 -50.491644)
		(end 181.169818 -51.845464)
		(width 0.13208)
		(layer "B.Cu")
		(net "USB3_PCH_RX_BUF_DN<4>")
	)
	(segment
		(start 166.2049 -38.794436)
		(end 177.902108 -50.491644)
		(width 0.13208)
		(layer "B.Cu")
		(net "USB3_PCH_RX_BUF_DN<4>")
	)
	(segment
		(start 155.137612 -27.605228)
		(end 158.45663 -27.605228)
		(width 0.13208)
		(layer "B.Cu")
		(net "USB3_PCH_RX_BUF_DN<4>")
	)
	(segment
		(start 287.07588 -84.097368)
		(end 329.812396 -84.097368)
		(width 0.13208)
		(layer "B.Cu")
		(net "USB3_PCH_RX_BUF_DN<4>")
	)
	(segment
		(start 360.63428 -55.582312)
		(end 360.33202 -55.884572)
		(width 0.13208)
		(layer "B.Cu")
		(net "USB3_PCH_RX_BUF_DN<4>")
	)
	(segment
		(start 342.058244 -89.169748)
		(end 344.935048 -89.169748)
		(width 0.13208)
		(layer "B.Cu")
		(net "USB3_PCH_RX_BUF_DN<4>")
	)
	(segment
		(start 356.394258 -75.288648)
		(end 357.959152 -67.421506)
		(width 0.13208)
		(layer "B.Cu")
		(net "USB3_PCH_RX_BUF_DN<4>")
	)
	(segment
		(start 164.206936 -33.237678)
		(end 165.916864 -35.796474)
		(width 0.13208)
		(layer "B.Cu")
		(net "USB3_PCH_RX_BUF_DN<4>")
	)
	(segment
		(start 355.338634 -77.837792)
		(end 356.394258 -75.288648)
		(width 0.13208)
		(layer "B.Cu")
		(net "USB3_PCH_RX_BUF_DN<4>")
	)
	(segment
		(start 345.772232 -88.823038)
		(end 354.33508 -80.26019)
		(width 0.13208)
		(layer "B.Cu")
		(net "USB3_PCH_RX_BUF_DN<4>")
	)
	(segment
		(start 122.48134 -25.715468)
		(end 122.6058 -25.591008)
		(width 0.13208)
		(layer "B.Cu")
		(net "USB3_PCH_RX_BUF_DN<4>")
	)
	(segment
		(start 126.78029 -13.87602)
		(end 126.78029 -13.699998)
		(width 0.13208)
		(layer "B.Cu")
		(net "USB3_PCH_RX_BUF_DN<4>")
	)
	(segment
		(start 128.069086 -12.411202)
		(end 129.344928 -11.882628)
		(width 0.13208)
		(layer "B.Cu")
		(net "USB3_PCH_RX_BUF_DN<4>")
	)
	(segment
		(start 360.06532 -54.826408)
		(end 360.63428 -55.395368)
		(width 0.13208)
		(layer "B.Cu")
		(net "USB3_PCH_RX_BUF_DN<4>")
	)
	(segment
		(start 122.48134 -19.353784)
		(end 123.439428 -17.04086)
		(width 0.13208)
		(layer "B.Cu")
		(net "USB3_PCH_RX_BUF_DN<4>")
	)
	(segment
		(start 124.9045 -15.575788)
		(end 125.080522 -15.575788)
		(width 0.13208)
		(layer "B.Cu")
		(net "USB3_PCH_RX_BUF_DN<4>")
	)
	(segment
		(start 358.083612 -58.335164)
		(end 357.959152 -58.210704)
		(width 0.13208)
		(layer "B.Cu")
		(net "USB3_PCH_RX_BUF_DN<4>")
	)
	(segment
		(start 344.935048 -89.169748)
		(end 345.772232 -88.823038)
		(width 0.13208)
		(layer "B.Cu")
		(net "USB3_PCH_RX_BUF_DN<4>")
	)
	(segment
		(start 329.812396 -84.097368)
		(end 342.058244 -89.169748)
		(width 0.13208)
		(layer "B.Cu")
		(net "USB3_PCH_RX_BUF_DN<4>")
	)
	(segment
		(start 125.35027 -15.30604)
		(end 125.35027 -15.130018)
		(width 0.13208)
		(layer "B.Cu")
		(net "USB3_PCH_RX_BUF_DN<4>")
	)
	(segment
		(start 126.06528 -14.415008)
		(end 126.33452 -14.145768)
		(width 0.13208)
		(layer "B.Cu")
		(net "USB3_PCH_RX_BUF_DN<4>")
	)
	(segment
		(start 125.080522 -15.575788)
		(end 125.35027 -15.30604)
		(width 0.13208)
		(layer "B.Cu")
		(net "USB3_PCH_RX_BUF_DN<4>")
	)
	(segment
		(start 238.223044 -71.40575)
		(end 242.124484 -73.021698)
		(width 0.13208)
		(layer "B.Cu")
		(net "USB3_PCH_RX_BUF_DN<4>")
	)
	(segment
		(start 122.48134 -25.085548)
		(end 122.48134 -19.353784)
		(width 0.13208)
		(layer "B.Cu")
		(net "USB3_PCH_RX_BUF_DN<4>")
	)
	(segment
		(start 201.851006 -62.067948)
		(end 216.10828 -62.067948)
		(width 0.13208)
		(layer "B.Cu")
		(net "USB3_PCH_RX_BUF_DN<4>")
	)
	(segment
		(start 355.097334 -78.420214)
		(end 355.260148 -78.35265)
		(width 0.13208)
		(layer "B.Cu")
		(net "USB3_PCH_RX_BUF_DN<4>")
	)
	(segment
		(start 354.872798 -79.28737)
		(end 354.805488 -79.12481)
		(width 0.13208)
		(layer "B.Cu")
		(net "USB3_PCH_RX_BUF_DN<4>")
	)
	(segment
		(start 144.070578 -19.911568)
		(end 149.379178 -25.220168)
		(width 0.13208)
		(layer "B.Cu")
		(net "USB3_PCH_RX_BUF_DN<4>")
	)
	(segment
		(start 139.956286 -13.922756)
		(end 142.744952 -16.711422)
		(width 0.13208)
		(layer "B.Cu")
		(net "USB3_PCH_RX_BUF_DN<4>")
	)
	(segment
		(start 166.2049 -36.491418)
		(end 166.2049 -38.794436)
		(width 0.13208)
		(layer "B.Cu")
		(net "USB3_PCH_RX_BUF_DN<4>")
	)
	(segment
		(start 358.685846 -54.950868)
		(end 358.810306 -54.826408)
		(width 0.13208)
		(layer "B.Cu")
		(net "USB3_PCH_RX_BUF_DN<4>")
	)
	(segment
		(start 355.405944 -78.000606)
		(end 355.338634 -77.837792)
		(width 0.13208)
		(layer "B.Cu")
		(net "USB3_PCH_RX_BUF_DN<4>")
	)
	(segment
		(start 126.06528 -14.59103)
		(end 126.06528 -14.415008)
		(width 0.13208)
		(layer "B.Cu")
		(net "USB3_PCH_RX_BUF_DN<4>")
	)
	(segment
		(start 354.805488 -79.12481)
		(end 355.097334 -78.420214)
		(width 0.13208)
		(layer "B.Cu")
		(net "USB3_PCH_RX_BUF_DN<4>")
	)
	(segment
		(start 126.33452 -14.145768)
		(end 126.510542 -14.145768)
		(width 0.13208)
		(layer "B.Cu")
		(net "USB3_PCH_RX_BUF_DN<4>")
	)
	(segment
		(start 358.083612 -59.727084)
		(end 358.083612 -59.346084)
		(width 0.13208)
		(layer "B.Cu")
		(net "USB3_PCH_RX_BUF_DN<4>")
	)
	(segment
		(start 358.083612 -60.738004)
		(end 358.083612 -60.357004)
		(width 0.13208)
		(layer "B.Cu")
		(net "USB3_PCH_RX_BUF_DN<4>")
	)
	(segment
		(start 122.6058 -25.210008)
		(end 122.48134 -25.085548)
		(width 0.13208)
		(layer "B.Cu")
		(net "USB3_PCH_RX_BUF_DN<4>")
	)
	(segment
		(start 354.564188 -79.706978)
		(end 354.727002 -79.639668)
		(width 0.13208)
		(layer "B.Cu")
		(net "USB3_PCH_RX_BUF_DN<4>")
	)
	(segment
		(start 122.48134 -27.433778)
		(end 122.48134 -26.726388)
		(width 0.13208)
		(layer "B.Cu")
		(net "USB3_PCH_RX_BUF_DN<4>")
	)
	(segment
		(start 357.7082 -54.826408)
		(end 358.180386 -54.826408)
		(width 0.13208)
		(layer "B.Cu")
		(net "USB3_PCH_RX_BUF_DN<4>")
	)
	(segment
		(start 122.6058 -26.220928)
		(end 122.48134 -26.096468)
		(width 0.13208)
		(layer "B.Cu")
		(net "USB3_PCH_RX_BUF_DN<4>")
	)
	(segment
		(start 129.344928 -11.882628)
		(end 135.030464 -11.882628)
		(width 0.13208)
		(layer "B.Cu")
		(net "USB3_PCH_RX_BUF_DN<4>")
	)
	(segment
		(start 142.744952 -16.711422)
		(end 144.070578 -19.911568)
		(width 0.13208)
		(layer "B.Cu")
		(net "USB3_PCH_RX_BUF_DN<4>")
	)
	(segment
		(start 357.959152 -59.851544)
		(end 358.083612 -59.727084)
		(width 0.13208)
		(layer "B.Cu")
		(net "USB3_PCH_RX_BUF_DN<4>")
	)
	(segment
		(start 126.78029 -13.699998)
		(end 128.069086 -12.411202)
		(width 0.13208)
		(layer "B.Cu")
		(net "USB3_PCH_RX_BUF_DN<4>")
	)
	(segment
		(start 251.076714 -81.973928)
		(end 281.949398 -81.973928)
		(width 0.13208)
		(layer "B.Cu")
		(net "USB3_PCH_RX_BUF_DN<4>")
	)
	(segment
		(start 135.030464 -11.882628)
		(end 139.956286 -13.922756)
		(width 0.13208)
		(layer "B.Cu")
		(net "USB3_PCH_RX_BUF_DN<4>")
	)
	(segment
		(start 358.083612 -60.357004)
		(end 357.959152 -60.232544)
		(width 0.13208)
		(layer "B.Cu")
		(net "USB3_PCH_RX_BUF_DN<4>")
	)
	(segment
		(start 122.6058 -26.601928)
		(end 122.6058 -26.220928)
		(width 0.13208)
		(layer "B.Cu")
		(net "USB3_PCH_RX_BUF_DN<4>")
	)
	(segment
		(start 356.9462 -56.779668)
		(end 356.2731 -56.106568)
		(width 0.13208)
		(layer "B.Cu")
		(net "USB3_PCH_RX_BUF_DN<4>")
	)
	(segment
		(start 356.2731 -55.250588)
		(end 356.69728 -54.826408)
		(width 0.13208)
		(layer "B.Cu")
		(net "USB3_PCH_RX_BUF_DN<4>")
	)
	(segment
		(start 354.33508 -80.26019)
		(end 354.564188 -79.706978)
		(width 0.13208)
		(layer "B.Cu")
		(net "USB3_PCH_RX_BUF_DN<4>")
	)
	(segment
		(start 149.379178 -25.220168)
		(end 155.137612 -27.605228)
		(width 0.13208)
		(layer "B.Cu")
		(net "USB3_PCH_RX_BUF_DN<4>")
	)
	(segment
		(start 122.48134 -26.726388)
		(end 122.6058 -26.601928)
		(width 0.13208)
		(layer "B.Cu")
		(net "USB3_PCH_RX_BUF_DN<4>")
	)
	(segment
		(start 183.245252 -52.258214)
		(end 185.007758 -52.988972)
		(width 0.13208)
		(layer "B.Cu")
		(net "USB3_PCH_RX_BUF_DN<4>")
	)
	(segment
		(start 357.959152 -60.862464)
		(end 358.083612 -60.738004)
		(width 0.13208)
		(layer "B.Cu")
		(net "USB3_PCH_RX_BUF_DN<4>")
	)
	(segment
		(start 357.959152 -57.79262)
		(end 357.391716 -57.225184)
		(width 0.13208)
		(layer "B.Cu")
		(net "USB3_PCH_RX_BUF_DN<4>")
	)
	(segment
		(start 163.125912 -30.628336)
		(end 164.206936 -33.237678)
		(width 0.13208)
		(layer "B.Cu")
		(net "USB3_PCH_RX_BUF_DN<4>")
	)
	(segment
		(start 125.795532 -14.860778)
		(end 126.06528 -14.59103)
		(width 0.13208)
		(layer "B.Cu")
		(net "USB3_PCH_RX_BUF_DN<4>")
	)
	(segment
		(start 357.58374 -54.950868)
		(end 357.7082 -54.826408)
		(width 0.13208)
		(layer "B.Cu")
		(net "USB3_PCH_RX_BUF_DN<4>")
	)
	(segment
		(start 122.48134 -26.096468)
		(end 122.48134 -25.715468)
		(width 0.13208)
		(layer "B.Cu")
		(net "USB3_PCH_RX_BUF_DN<4>")
	)
	(segment
		(start 356.69728 -54.826408)
		(end 357.07828 -54.826408)
		(width 0.13208)
		(layer "B.Cu")
		(net "USB3_PCH_RX_BUF_DN<4>")
	)
	(segment
		(start 360.63428 -55.395368)
		(end 360.63428 -55.582312)
		(width 0.13208)
		(layer "B.Cu")
		(net "USB3_PCH_RX_BUF_DN<4>")
	)
	(segment
		(start 357.959152 -59.221624)
		(end 357.959152 -58.840624)
		(width 0.13208)
		(layer "B.Cu")
		(net "USB3_PCH_RX_BUF_DN<4>")
	)
	(segment
		(start 181.169818 -51.845464)
		(end 183.245252 -52.258214)
		(width 0.13208)
		(layer "B.Cu")
		(net "USB3_PCH_RX_BUF_DN<4>")
	)
	(segment
		(start 165.916864 -35.796474)
		(end 166.2049 -36.491418)
		(width 0.13208)
		(layer "B.Cu")
		(net "USB3_PCH_RX_BUF_DN<4>")
	)
	(segment
		(start 229.522528 -69.132958)
		(end 232.038398 -70.17512)
		(width 0.13208)
		(layer "B.Cu")
		(net "USB3_PCH_RX_BUF_DN<4>")
	)
	(segment
		(start 125.35027 -15.130018)
		(end 125.61951 -14.860778)
		(width 0.13208)
		(layer "B.Cu")
		(net "USB3_PCH_RX_BUF_DN<4>")
	)
	(segment
		(start 358.180386 -54.826408)
		(end 358.304846 -54.950868)
		(width 0.13208)
		(layer "B.Cu")
		(net "USB3_PCH_RX_BUF_DN<4>")
	)
	(segment
		(start 125.61951 -14.860778)
		(end 125.795532 -14.860778)
		(width 0.13208)
		(layer "B.Cu")
		(net "USB3_PCH_RX_BUF_DN<4>")
	)
	(segment
		(start 358.083612 -58.716164)
		(end 358.083612 -58.335164)
		(width 0.13208)
		(layer "B.Cu")
		(net "USB3_PCH_RX_BUF_DN<4>")
	)
	(segment
		(start 354.727002 -79.639668)
		(end 354.872798 -79.28737)
		(width 0.13208)
		(layer "B.Cu")
		(net "USB3_PCH_RX_BUF_DN<4>")
	)
	(segment
		(start 357.122222 -56.779668)
		(end 356.9462 -56.779668)
		(width 0.13208)
		(layer "B.Cu")
		(net "USB3_PCH_RX_BUF_DN<4>")
	)
	(segment
		(start 123.31192 -27.424888)
		(end 123.02109 -27.715718)
		(width 0.13208)
		(layer "B.Cu")
		(net "USB3_PCH_RX_BUF_DN<4>")
	)
	(segment
		(start 358.810306 -54.826408)
		(end 360.06532 -54.826408)
		(width 0.13208)
		(layer "B.Cu")
		(net "USB3_PCH_RX_BUF_DN<4>")
	)
	(segment
		(start 242.124484 -73.021698)
		(end 251.076714 -81.973928)
		(width 0.13208)
		(layer "B.Cu")
		(net "USB3_PCH_RX_BUF_DN<4>")
	)
	(segment
		(start 216.10828 -62.067948)
		(end 226.946968 -66.557398)
		(width 0.13208)
		(layer "B.Cu")
		(net "USB3_PCH_RX_BUF_DN<4>")
	)
	(segment
		(start 126.510542 -14.145768)
		(end 126.78029 -13.87602)
		(width 0.13208)
		(layer "B.Cu")
		(net "USB3_PCH_RX_BUF_DN<4>")
	)
	(segment
		(start 281.949398 -81.973928)
		(end 287.07588 -84.097368)
		(width 0.13208)
		(layer "B.Cu")
		(net "USB3_PCH_RX_BUF_DN<4>")
	)
	(segment
		(start 357.391716 -57.049162)
		(end 357.122222 -56.779668)
		(width 0.13208)
		(layer "B.Cu")
		(net "USB3_PCH_RX_BUF_DN<4>")
	)
	(segment
		(start 358.304846 -54.950868)
		(end 358.685846 -54.950868)
		(width 0.13208)
		(layer "B.Cu")
		(net "USB3_PCH_RX_BUF_DN<4>")
	)
	(segment
		(start 357.959152 -58.210704)
		(end 357.959152 -57.79262)
		(width 0.13208)
		(layer "B.Cu")
		(net "USB3_PCH_RX_BUF_DN<4>")
	)
	(segment
		(start 357.959152 -60.232544)
		(end 357.959152 -59.851544)
		(width 0.13208)
		(layer "B.Cu")
		(net "USB3_PCH_RX_BUF_DN<4>")
	)
	(segment
		(start 357.07828 -54.826408)
		(end 357.20274 -54.950868)
		(width 0.13208)
		(layer "B.Cu")
		(net "USB3_PCH_RX_BUF_DN<4>")
	)
	(segment
		(start 196.12864 -58.93308)
		(end 199.96277 -61.495178)
		(width 0.13208)
		(layer "B.Cu")
		(net "USB3_PCH_RX_BUF_DN<4>")
	)
	(segment
		(start 357.391716 -57.225184)
		(end 357.391716 -57.049162)
		(width 0.13208)
		(layer "B.Cu")
		(net "USB3_PCH_RX_BUF_DN<4>")
	)
	(segment
		(start 122.76328 -27.715718)
		(end 122.48134 -27.433778)
		(width 0.13208)
		(layer "B.Cu")
		(net "USB3_PCH_RX_BUF_DN<4>")
	)
	(segment
		(start 357.959152 -58.840624)
		(end 358.083612 -58.716164)
		(width 0.13208)
		(layer "B.Cu")
		(net "USB3_PCH_RX_BUF_DN<4>")
	)
	(segment
		(start 232.038398 -70.17512)
		(end 238.223044 -71.40575)
		(width 0.13208)
		(layer "B.Cu")
		(net "USB3_PCH_RX_BUF_DN<4>")
	)
	(segment
		(start 358.083612 -59.346084)
		(end 357.959152 -59.221624)
		(width 0.13208)
		(layer "B.Cu")
		(net "USB3_PCH_RX_BUF_DN<4>")
	)
	(segment
		(start 185.007758 -52.988972)
		(end 196.12864 -58.93308)
		(width 0.13208)
		(layer "B.Cu")
		(net "USB3_PCH_RX_BUF_DN<4>")
	)
	(segment
		(start 357.959152 -67.421506)
		(end 357.959152 -60.862464)
		(width 0.13208)
		(layer "B.Cu")
		(net "USB3_PCH_RX_BUF_DN<4>")
	)
	(segment
		(start 158.45663 -27.605228)
		(end 161.266886 -28.76931)
		(width 0.13208)
		(layer "B.Cu")
		(net "USB3_PCH_RX_BUF_DN<4>")
	)
	(segment
		(start 122.6058 -25.591008)
		(end 122.6058 -25.210008)
		(width 0.13208)
		(layer "B.Cu")
		(net "USB3_PCH_RX_BUF_DN<4>")
	)
	(segment
		(start 226.946968 -66.557398)
		(end 229.522528 -69.132958)
		(width 0.13208)
		(layer "B.Cu")
		(net "USB3_PCH_RX_BUF_DN<4>")
	)
	(segment
		(start 123.02109 -27.715718)
		(end 122.76328 -27.715718)
		(width 0.13208)
		(layer "B.Cu")
		(net "USB3_PCH_RX_BUF_DN<4>")
	)
	(segment
		(start 356.2731 -56.106568)
		(end 356.2731 -55.250588)
		(width 0.13208)
		(layer "B.Cu")
		(net "USB3_PCH_RX_BUF_DN<4>")
	)
	(segment
		(start 199.96277 -61.495178)
		(end 201.851006 -62.067948)
		(width 0.13208)
		(layer "B.Cu")
		(net "USB3_PCH_RX_BUF_DN<4>")
	)
	(segment
		(start 123.439428 -17.04086)
		(end 124.9045 -15.575788)
		(width 0.13208)
		(layer "B.Cu")
		(net "USB3_PCH_RX_BUF_DN<4>")
	)
	(segment
		(start 124.65558 -27.976068)
		(end 125.35027 -27.281378)
		(width 0.13208)
		(layer "B.Cu")
		(net "USB3_PCH_RX_BUF_C_DP<4>")
	)
	(segment
		(start 124.13488 -27.976068)
		(end 124.65558 -27.976068)
		(width 0.13208)
		(layer "B.Cu")
		(net "USB3_PCH_RX_BUF_C_DP<4>")
	)
	(segment
		(start 125.35027 -27.281378)
		(end 126.38659 -27.281378)
		(width 0.13208)
		(layer "B.Cu")
		(net "USB3_PCH_RX_BUF_C_DP<4>")
	)
	(segment
		(start 126.38659 -27.281378)
		(end 126.432056 -27.326844)
		(width 0.13208)
		(layer "B.Cu")
		(net "USB3_PCH_RX_BUF_C_DP<4>")
	)
	(segment
		(start 126.432056 -27.326844)
		(end 126.615698 -27.326844)
		(width 0.13208)
		(layer "B.Cu")
		(net "USB3_PCH_RX_BUF_C_DP<4>")
	)
	(segment
		(start 123.84532 -28.265628)
		(end 124.13488 -27.976068)
		(width 0.13208)
		(layer "B.Cu")
		(net "USB3_PCH_RX_BUF_C_DP<4>")
	)
	(segment
		(start 125.242828 -27.022298)
		(end 126.38659 -27.022298)
		(width 0.13208)
		(layer "B.Cu")
		(net "USB3_PCH_RX_BUF_C_DN<4>")
	)
	(segment
		(start 126.38659 -27.022298)
		(end 126.432056 -26.976832)
		(width 0.13208)
		(layer "B.Cu")
		(net "USB3_PCH_RX_BUF_C_DN<4>")
	)
	(segment
		(start 124.548138 -27.716988)
		(end 125.242828 -27.022298)
		(width 0.13208)
		(layer "B.Cu")
		(net "USB3_PCH_RX_BUF_C_DN<4>")
	)
	(segment
		(start 124.13742 -27.716988)
		(end 124.548138 -27.716988)
		(width 0.13208)
		(layer "B.Cu")
		(net "USB3_PCH_RX_BUF_C_DN<4>")
	)
	(segment
		(start 123.84532 -27.424888)
		(end 124.13742 -27.716988)
		(width 0.13208)
		(layer "B.Cu")
		(net "USB3_PCH_RX_BUF_C_DN<4>")
	)
	(segment
		(start 126.432056 -26.976832)
		(end 126.615698 -26.976832)
		(width 0.13208)
		(layer "B.Cu")
		(net "USB3_PCH_RX_BUF_C_DN<4>")
	)
	(segment
		(start 58.37555 -113.501424)
		(end 57.405524 -113.501424)
		(width 0.12954)
		(layer "F.Cu")
		(net "PU_RST_SMB_PCIE2_N")
	)
	(segment
		(start 55.9308 -114.976148)
		(end 55.9308 -115.357148)
		(width 0.12954)
		(layer "F.Cu")
		(net "PU_RST_SMB_PCIE2_N")
	)
	(segment
		(start 55.568342 -114.99469)
		(end 54.642766 -114.99469)
		(width 0.12954)
		(layer "F.Cu")
		(net "PU_RST_SMB_PCIE2_N")
	)
	(segment
		(start 55.9308 -115.357148)
		(end 55.568342 -114.99469)
		(width 0.12954)
		(layer "F.Cu")
		(net "PU_RST_SMB_PCIE2_N")
	)
	(segment
		(start 57.405524 -113.501424)
		(end 55.9308 -114.976148)
		(width 0.12954)
		(layer "F.Cu")
		(net "PU_RST_SMB_PCIE2_N")
	)
	(via
		(at 55.9308 -115.357148)
		(size 0.762)
		(drill 0.381)
		(layers "F.Cu" "B.Cu")
		(net "PU_RST_SMB_PCIE2_N")
	)
	(via
		(at 127.127 -29.962348)
		(size 0.6604)
		(drill 0.3302)
		(layers "F.Cu" "B.Cu")
		(net "FM_USB3_1_SWB")
	)
	(segment
		(start 127.127 -30.425898)
		(end 127.83058 -31.129478)
		(width 0.12954)
		(layer "B.Cu")
		(net "FM_USB3_1_SWB")
	)
	(segment
		(start 127.127 -29.962348)
		(end 127.127 -30.425898)
		(width 0.12954)
		(layer "B.Cu")
		(net "FM_USB3_1_SWB")
	)
	(segment
		(start 127.83566 -37.159438)
		(end 127.60071 -37.159438)
		(width 0.12954)
		(layer "B.Cu")
		(net "FM_USB3_1_SWB")
	)
	(segment
		(start 127.60071 -37.159438)
		(end 127.23622 -36.794948)
		(width 0.12954)
		(layer "B.Cu")
		(net "FM_USB3_1_SWB")
	)
	(segment
		(start 127.127 -28.362148)
		(end 127.127 -29.962348)
		(width 0.12954)
		(layer "B.Cu")
		(net "FM_USB3_1_SWB")
	)
	(segment
		(start 127.254 -34.571178)
		(end 127.254 -31.706058)
		(width 0.12954)
		(layer "B.Cu")
		(net "FM_USB3_1_SWB")
	)
	(segment
		(start 127.23622 -34.588958)
		(end 127.254 -34.571178)
		(width 0.12954)
		(layer "B.Cu")
		(net "FM_USB3_1_SWB")
	)
	(segment
		(start 127.490728 -27.50185)
		(end 127.490728 -27.99842)
		(width 0.12954)
		(layer "B.Cu")
		(net "FM_USB3_1_SWB")
	)
	(segment
		(start 127.254 -31.706058)
		(end 127.83058 -31.129478)
		(width 0.12954)
		(layer "B.Cu")
		(net "FM_USB3_1_SWB")
	)
	(segment
		(start 127.490728 -27.99842)
		(end 127.127 -28.362148)
		(width 0.12954)
		(layer "B.Cu")
		(net "FM_USB3_1_SWB")
	)
	(segment
		(start 127.23622 -36.794948)
		(end 127.23622 -34.588958)
		(width 0.12954)
		(layer "B.Cu")
		(net "FM_USB3_1_SWB")
	)
	(via
		(at 128.1938 -23.840948)
		(size 0.6604)
		(drill 0.3302)
		(layers "F.Cu" "B.Cu")
		(net "FM_USB3_1_SWA")
	)
	(segment
		(start 128.10109 -21.403818)
		(end 127.7874 -21.403818)
		(width 0.12954)
		(layer "B.Cu")
		(net "FM_USB3_1_SWA")
	)
	(segment
		(start 128.1938 -21.961094)
		(end 127.7874 -21.554694)
		(width 0.12954)
		(layer "B.Cu")
		(net "FM_USB3_1_SWA")
	)
	(segment
		(start 128.33096 -21.173948)
		(end 128.10109 -21.403818)
		(width 0.12954)
		(layer "B.Cu")
		(net "FM_USB3_1_SWA")
	)
	(segment
		(start 127.84074 -24.524462)
		(end 128.1938 -24.171402)
		(width 0.12954)
		(layer "B.Cu")
		(net "FM_USB3_1_SWA")
	)
	(segment
		(start 128.33096 -19.465798)
		(end 128.33096 -21.173948)
		(width 0.12954)
		(layer "B.Cu")
		(net "FM_USB3_1_SWA")
	)
	(segment
		(start 127.7874 -21.554694)
		(end 127.7874 -21.403818)
		(width 0.12954)
		(layer "B.Cu")
		(net "FM_USB3_1_SWA")
	)
	(segment
		(start 127.8001 -18.934938)
		(end 128.33096 -19.465798)
		(width 0.12954)
		(layer "B.Cu")
		(net "FM_USB3_1_SWA")
	)
	(segment
		(start 128.1938 -24.171402)
		(end 128.1938 -23.840948)
		(width 0.12954)
		(layer "B.Cu")
		(net "FM_USB3_1_SWA")
	)
	(segment
		(start 128.1938 -23.840948)
		(end 128.1938 -21.961094)
		(width 0.12954)
		(layer "B.Cu")
		(net "FM_USB3_1_SWA")
	)
	(segment
		(start 127.84074 -25.051766)
		(end 127.84074 -24.524462)
		(width 0.12954)
		(layer "B.Cu")
		(net "FM_USB3_1_SWA")
	)
	(via
		(at 126.4412 -28.844748)
		(size 0.6604)
		(drill 0.3302)
		(layers "F.Cu" "B.Cu")
		(net "FM_USB3_1_RXDET_EN")
	)
	(segment
		(start 126.4412 -28.489148)
		(end 127.140716 -27.789632)
		(width 0.12954)
		(layer "B.Cu")
		(net "FM_USB3_1_RXDET_EN")
	)
	(segment
		(start 125.96114 -31.843218)
		(end 126.67742 -31.126938)
		(width 0.12954)
		(layer "B.Cu")
		(net "FM_USB3_1_RXDET_EN")
	)
	(segment
		(start 126.4412 -28.844748)
		(end 126.4412 -28.489148)
		(width 0.12954)
		(layer "B.Cu")
		(net "FM_USB3_1_RXDET_EN")
	)
	(segment
		(start 126.67742 -31.126938)
		(end 126.4412 -30.890718)
		(width 0.12954)
		(layer "B.Cu")
		(net "FM_USB3_1_RXDET_EN")
	)
	(segment
		(start 126.4412 -30.890718)
		(end 126.4412 -28.844748)
		(width 0.12954)
		(layer "B.Cu")
		(net "FM_USB3_1_RXDET_EN")
	)
	(segment
		(start 126.65202 -37.161978)
		(end 126.39675 -37.161978)
		(width 0.12954)
		(layer "B.Cu")
		(net "FM_USB3_1_RXDET_EN")
	)
	(segment
		(start 127.140716 -27.789632)
		(end 127.140716 -27.50185)
		(width 0.12954)
		(layer "B.Cu")
		(net "FM_USB3_1_RXDET_EN")
	)
	(segment
		(start 125.96114 -36.726368)
		(end 125.96114 -31.843218)
		(width 0.12954)
		(layer "B.Cu")
		(net "FM_USB3_1_RXDET_EN")
	)
	(segment
		(start 126.39675 -37.161978)
		(end 125.96114 -36.726368)
		(width 0.12954)
		(layer "B.Cu")
		(net "FM_USB3_1_RXDET_EN")
	)
	(via
		(at 127.84074 -28.768548)
		(size 0.6604)
		(drill 0.3302)
		(layers "F.Cu" "B.Cu")
		(net "FM_USB3_1_FGB")
	)
	(segment
		(start 128.3462 -34.502598)
		(end 129.60604 -33.242758)
		(width 0.12954)
		(layer "B.Cu")
		(net "FM_USB3_1_FGB")
	)
	(segment
		(start 128.86309 -29.790898)
		(end 128.86309 -31.138368)
		(width 0.12954)
		(layer "B.Cu")
		(net "FM_USB3_1_FGB")
	)
	(segment
		(start 127.84074 -27.50185)
		(end 127.84074 -28.768548)
		(width 0.12954)
		(layer "B.Cu")
		(net "FM_USB3_1_FGB")
	)
	(segment
		(start 128.86309 -31.138368)
		(end 128.85928 -31.142178)
		(width 0.12954)
		(layer "B.Cu")
		(net "FM_USB3_1_FGB")
	)
	(segment
		(start 128.86944 -37.151818)
		(end 128.57607 -37.151818)
		(width 0.12954)
		(layer "B.Cu")
		(net "FM_USB3_1_FGB")
	)
	(segment
		(start 128.3462 -36.921948)
		(end 128.3462 -34.502598)
		(width 0.12954)
		(layer "B.Cu")
		(net "FM_USB3_1_FGB")
	)
	(segment
		(start 129.60604 -33.242758)
		(end 129.60604 -31.888938)
		(width 0.12954)
		(layer "B.Cu")
		(net "FM_USB3_1_FGB")
	)
	(segment
		(start 128.57607 -37.151818)
		(end 128.3462 -36.921948)
		(width 0.12954)
		(layer "B.Cu")
		(net "FM_USB3_1_FGB")
	)
	(segment
		(start 129.60604 -31.888938)
		(end 128.85928 -31.142178)
		(width 0.12954)
		(layer "B.Cu")
		(net "FM_USB3_1_FGB")
	)
	(segment
		(start 127.84074 -28.768548)
		(end 128.86309 -29.790898)
		(width 0.12954)
		(layer "B.Cu")
		(net "FM_USB3_1_FGB")
	)
	(via
		(at 128.86309 -22.570948)
		(size 0.6604)
		(drill 0.3302)
		(layers "F.Cu" "B.Cu")
		(net "FM_USB3_1_FGA")
	)
	(segment
		(start 128.86309 -23.958804)
		(end 128.190752 -24.631142)
		(width 0.12954)
		(layer "B.Cu")
		(net "FM_USB3_1_FGA")
	)
	(segment
		(start 128.190752 -24.631142)
		(end 128.190752 -25.051766)
		(width 0.12954)
		(layer "B.Cu")
		(net "FM_USB3_1_FGA")
	)
	(segment
		(start 128.85674 -21.396198)
		(end 128.86309 -21.402548)
		(width 0.12954)
		(layer "B.Cu")
		(net "FM_USB3_1_FGA")
	)
	(segment
		(start 128.86309 -21.402548)
		(end 128.86309 -22.570948)
		(width 0.12954)
		(layer "B.Cu")
		(net "FM_USB3_1_FGA")
	)
	(segment
		(start 128.85801 -18.938748)
		(end 129.667 -18.938748)
		(width 0.12954)
		(layer "B.Cu")
		(net "FM_USB3_1_FGA")
	)
	(segment
		(start 130.1242 -20.869148)
		(end 129.59715 -21.396198)
		(width 0.12954)
		(layer "B.Cu")
		(net "FM_USB3_1_FGA")
	)
	(segment
		(start 128.85674 -18.940018)
		(end 128.85801 -18.938748)
		(width 0.12954)
		(layer "B.Cu")
		(net "FM_USB3_1_FGA")
	)
	(segment
		(start 129.667 -18.938748)
		(end 130.1242 -19.395948)
		(width 0.12954)
		(layer "B.Cu")
		(net "FM_USB3_1_FGA")
	)
	(segment
		(start 128.86309 -22.570948)
		(end 128.86309 -23.958804)
		(width 0.12954)
		(layer "B.Cu")
		(net "FM_USB3_1_FGA")
	)
	(segment
		(start 129.59715 -21.396198)
		(end 128.85674 -21.396198)
		(width 0.12954)
		(layer "B.Cu")
		(net "FM_USB3_1_FGA")
	)
	(segment
		(start 130.1242 -19.395948)
		(end 130.1242 -20.869148)
		(width 0.12954)
		(layer "B.Cu")
		(net "FM_USB3_1_FGA")
	)
	(segment
		(start 131.39166 -26.480008)
		(end 132.3594 -27.447748)
		(width 0.12954)
		(layer "F.Cu")
		(net "FM_USB3_1_EQB")
	)
	(segment
		(start 132.3594 -27.447748)
		(end 136.22401 -27.447748)
		(width 0.12954)
		(layer "F.Cu")
		(net "FM_USB3_1_EQB")
	)
	(segment
		(start 136.22655 -27.450288)
		(end 136.22401 -27.447748)
		(width 0.12954)
		(layer "F.Cu")
		(net "FM_USB3_1_EQB")
	)
	(segment
		(start 136.22655 -28.578048)
		(end 136.22655 -27.450288)
		(width 0.12954)
		(layer "F.Cu")
		(net "FM_USB3_1_EQB")
	)
	(via
		(at 130.4798 -29.936948)
		(size 0.508)
		(drill 0.254)
		(layers "F.Cu" "B.Cu")
		(net "FM_USB3_1_EQB")
	)
	(via
		(at 131.39166 -26.480008)
		(size 0.508)
		(drill 0.254)
		(layers "F.Cu" "B.Cu")
		(net "FM_USB3_1_EQB")
	)
	(segment
		(start 128.190752 -28.3083)
		(end 128.190752 -27.50185)
		(width 0.12954)
		(layer "B.Cu")
		(net "FM_USB3_1_EQB")
	)
	(segment
		(start 129.6924 -29.149548)
		(end 129.032 -29.149548)
		(width 0.12954)
		(layer "B.Cu")
		(net "FM_USB3_1_EQB")
	)
	(segment
		(start 130.4798 -29.936948)
		(end 129.6924 -29.149548)
		(width 0.12954)
		(layer "B.Cu")
		(net "FM_USB3_1_EQB")
	)
	(segment
		(start 129.032 -29.149548)
		(end 128.190752 -28.3083)
		(width 0.12954)
		(layer "B.Cu")
		(net "FM_USB3_1_EQB")
	)
	(segment
		(start 130.4798 -29.936948)
		(end 130.4798 -27.391868)
		(width 0.127)
		(layer "In2.Cu")
		(net "FM_USB3_1_EQB")
	)
	(segment
		(start 130.4798 -27.391868)
		(end 131.39166 -26.480008)
		(width 0.127)
		(layer "In2.Cu")
		(net "FM_USB3_1_EQB")
	)
	(segment
		(start 136.21131 -25.189688)
		(end 136.21131 -26.246328)
		(width 0.12954)
		(layer "F.Cu")
		(net "FM_USB3_1_EQA")
	)
	(segment
		(start 136.21131 -26.246328)
		(end 136.20623 -26.251408)
		(width 0.12954)
		(layer "F.Cu")
		(net "FM_USB3_1_EQA")
	)
	(segment
		(start 135.508238 -26.9494)
		(end 136.20623 -26.251408)
		(width 0.12954)
		(layer "F.Cu")
		(net "FM_USB3_1_EQA")
	)
	(segment
		(start 132.828792 -26.9494)
		(end 135.508238 -26.9494)
		(width 0.12954)
		(layer "F.Cu")
		(net "FM_USB3_1_EQA")
	)
	(segment
		(start 131.6863 -25.806908)
		(end 132.828792 -26.9494)
		(width 0.12954)
		(layer "F.Cu")
		(net "FM_USB3_1_EQA")
	)
	(via
		(at 129.6924 -23.566628)
		(size 0.508)
		(drill 0.254)
		(layers "F.Cu" "B.Cu")
		(net "FM_USB3_1_EQA")
	)
	(via
		(at 131.6863 -25.806908)
		(size 0.508)
		(drill 0.254)
		(layers "F.Cu" "B.Cu")
		(net "FM_USB3_1_EQA")
	)
	(segment
		(start 129.6924 -23.566628)
		(end 128.540764 -24.718264)
		(width 0.12954)
		(layer "B.Cu")
		(net "FM_USB3_1_EQA")
	)
	(segment
		(start 128.540764 -24.718264)
		(end 128.540764 -25.051766)
		(width 0.12954)
		(layer "B.Cu")
		(net "FM_USB3_1_EQA")
	)
	(segment
		(start 131.6863 -25.806908)
		(end 129.6924 -23.813008)
		(width 0.127)
		(layer "In2.Cu")
		(net "FM_USB3_1_EQA")
	)
	(segment
		(start 129.6924 -23.813008)
		(end 129.6924 -23.566628)
		(width 0.127)
		(layer "In2.Cu")
		(net "FM_USB3_1_EQA")
	)
	(via
		(at 125.504448 -22.36216)
		(size 0.6604)
		(drill 0.3302)
		(layers "F.Cu" "B.Cu")
		(net "FM_USB3_1_EN_N")
	)
	(segment
		(start 125.504448 -21.776182)
		(end 125.894592 -21.386038)
		(width 0.12954)
		(layer "B.Cu")
		(net "FM_USB3_1_EN_N")
	)
	(segment
		(start 125.504448 -22.948138)
		(end 125.504448 -22.36216)
		(width 0.12954)
		(layer "B.Cu")
		(net "FM_USB3_1_EN_N")
	)
	(segment
		(start 127.490728 -23.789386)
		(end 126.89586 -23.194518)
		(width 0.12954)
		(layer "B.Cu")
		(net "FM_USB3_1_EN_N")
	)
	(segment
		(start 125.894592 -21.386038)
		(end 126.87554 -21.386038)
		(width 0.12954)
		(layer "B.Cu")
		(net "FM_USB3_1_EN_N")
	)
	(segment
		(start 125.750828 -23.194518)
		(end 125.504448 -22.948138)
		(width 0.12954)
		(layer "B.Cu")
		(net "FM_USB3_1_EN_N")
	)
	(segment
		(start 127.490728 -25.051766)
		(end 127.490728 -23.789386)
		(width 0.12954)
		(layer "B.Cu")
		(net "FM_USB3_1_EN_N")
	)
	(segment
		(start 126.89586 -23.194518)
		(end 125.750828 -23.194518)
		(width 0.12954)
		(layer "B.Cu")
		(net "FM_USB3_1_EN_N")
	)
	(segment
		(start 125.504448 -22.36216)
		(end 125.504448 -21.776182)
		(width 0.12954)
		(layer "B.Cu")
		(net "FM_USB3_1_EN_N")
	)
	(segment
		(start 118.885208 -15.237714)
		(end 118.22557 -15.237714)
		(width 0.12954)
		(layer "F.Cu")
		(net "U273_3_ADD2")
	)
	(segment
		(start 123.410472 -14.19733)
		(end 122.689874 -14.917928)
		(width 0.12954)
		(layer "F.Cu")
		(net "U273_3_ADD2")
	)
	(segment
		(start 120.29694 -14.917928)
		(end 119.915432 -14.53642)
		(width 0.12954)
		(layer "F.Cu")
		(net "U273_3_ADD2")
	)
	(segment
		(start 118.22557 -15.237714)
		(end 116.96192 -13.974064)
		(width 0.12954)
		(layer "F.Cu")
		(net "U273_3_ADD2")
	)
	(segment
		(start 119.915432 -14.53642)
		(end 119.915432 -14.20749)
		(width 0.12954)
		(layer "F.Cu")
		(net "U273_3_ADD2")
	)
	(segment
		(start 119.915432 -14.20749)
		(end 118.885208 -15.237714)
		(width 0.12954)
		(layer "F.Cu")
		(net "U273_3_ADD2")
	)
	(segment
		(start 122.689874 -14.917928)
		(end 120.29694 -14.917928)
		(width 0.12954)
		(layer "F.Cu")
		(net "U273_3_ADD2")
	)
	(segment
		(start 116.96192 -13.974064)
		(end 115.856512 -13.974064)
		(width 0.12954)
		(layer "F.Cu")
		(net "U273_3_ADD2")
	)
	(via
		(at 118.22557 -15.237714)
		(size 0.762)
		(drill 0.381)
		(layers "F.Cu" "B.Cu")
		(net "U273_3_ADD2")
	)
	(segment
		(start 116.655088 -15.244064)
		(end 115.856512 -15.244064)
		(width 0.12954)
		(layer "F.Cu")
		(net "U273_3_ADD1")
	)
	(segment
		(start 119.926608 -15.845536)
		(end 119.926608 -15.526766)
		(width 0.12954)
		(layer "F.Cu")
		(net "U273_3_ADD1")
	)
	(segment
		(start 117.918738 -16.507714)
		(end 116.655088 -15.244064)
		(width 0.12954)
		(layer "F.Cu")
		(net "U273_3_ADD1")
	)
	(segment
		(start 119.926608 -15.526766)
		(end 118.94566 -16.507714)
		(width 0.12954)
		(layer "F.Cu")
		(net "U273_3_ADD1")
	)
	(segment
		(start 123.369832 -15.54607)
		(end 122.674634 -16.241268)
		(width 0.12954)
		(layer "F.Cu")
		(net "U273_3_ADD1")
	)
	(segment
		(start 118.22557 -16.507714)
		(end 117.918738 -16.507714)
		(width 0.12954)
		(layer "F.Cu")
		(net "U273_3_ADD1")
	)
	(segment
		(start 122.674634 -16.241268)
		(end 120.32234 -16.241268)
		(width 0.12954)
		(layer "F.Cu")
		(net "U273_3_ADD1")
	)
	(segment
		(start 118.94566 -16.507714)
		(end 118.22557 -16.507714)
		(width 0.12954)
		(layer "F.Cu")
		(net "U273_3_ADD1")
	)
	(segment
		(start 120.32234 -16.241268)
		(end 119.926608 -15.845536)
		(width 0.12954)
		(layer "F.Cu")
		(net "U273_3_ADD1")
	)
	(via
		(at 118.22557 -16.507714)
		(size 0.762)
		(drill 0.381)
		(layers "F.Cu" "B.Cu")
		(net "U273_3_ADD1")
	)
	(segment
		(start 119.933212 -16.91005)
		(end 119.065548 -17.777714)
		(width 0.12954)
		(layer "F.Cu")
		(net "U273_3_ADD0")
	)
	(segment
		(start 117.993414 -17.777714)
		(end 116.729764 -16.514064)
		(width 0.12954)
		(layer "F.Cu")
		(net "U273_3_ADD0")
	)
	(segment
		(start 118.22557 -17.777714)
		(end 117.993414 -17.777714)
		(width 0.12954)
		(layer "F.Cu")
		(net "U273_3_ADD0")
	)
	(segment
		(start 119.065548 -17.777714)
		(end 118.22557 -17.777714)
		(width 0.12954)
		(layer "F.Cu")
		(net "U273_3_ADD0")
	)
	(segment
		(start 122.598434 -17.650968)
		(end 120.27408 -17.650968)
		(width 0.12954)
		(layer "F.Cu")
		(net "U273_3_ADD0")
	)
	(segment
		(start 123.341892 -16.90751)
		(end 122.598434 -17.650968)
		(width 0.12954)
		(layer "F.Cu")
		(net "U273_3_ADD0")
	)
	(segment
		(start 116.729764 -16.514064)
		(end 115.856512 -16.514064)
		(width 0.12954)
		(layer "F.Cu")
		(net "U273_3_ADD0")
	)
	(segment
		(start 120.27408 -17.650968)
		(end 119.933212 -17.3101)
		(width 0.12954)
		(layer "F.Cu")
		(net "U273_3_ADD0")
	)
	(segment
		(start 119.933212 -17.3101)
		(end 119.933212 -16.91005)
		(width 0.12954)
		(layer "F.Cu")
		(net "U273_3_ADD0")
	)
	(via
		(at 118.22557 -17.777714)
		(size 0.762)
		(drill 0.381)
		(layers "F.Cu" "B.Cu")
		(net "U273_3_ADD0")
	)
	(segment
		(start 96.93656 -419.395148)
		(end 96.150938 -418.609526)
		(width 0.12954)
		(layer "F.Cu")
		(net "U272_2_ADD2")
	)
	(segment
		(start 98.253296 -420.929816)
		(end 98.253296 -420.35857)
		(width 0.12954)
		(layer "F.Cu")
		(net "U272_2_ADD2")
	)
	(segment
		(start 96.87052 -417.815268)
		(end 96.517968 -418.16782)
		(width 0.12954)
		(layer "F.Cu")
		(net "U272_2_ADD2")
	)
	(segment
		(start 96.517968 -418.16782)
		(end 96.150938 -418.16782)
		(width 0.12954)
		(layer "F.Cu")
		(net "U272_2_ADD2")
	)
	(segment
		(start 96.138238 -415.15538)
		(end 96.87052 -415.887662)
		(width 0.12954)
		(layer "F.Cu")
		(net "U272_2_ADD2")
	)
	(segment
		(start 97.289874 -419.395148)
		(end 96.93656 -419.395148)
		(width 0.12954)
		(layer "F.Cu")
		(net "U272_2_ADD2")
	)
	(segment
		(start 96.150938 -418.609526)
		(end 96.150938 -418.16782)
		(width 0.12954)
		(layer "F.Cu")
		(net "U272_2_ADD2")
	)
	(segment
		(start 96.87052 -415.887662)
		(end 96.87052 -417.815268)
		(width 0.12954)
		(layer "F.Cu")
		(net "U272_2_ADD2")
	)
	(segment
		(start 98.253296 -420.35857)
		(end 97.289874 -419.395148)
		(width 0.12954)
		(layer "F.Cu")
		(net "U272_2_ADD2")
	)
	(via
		(at 96.93656 -419.395148)
		(size 0.762)
		(drill 0.381)
		(layers "F.Cu" "B.Cu")
		(net "U272_2_ADD2")
	)
	(segment
		(start 98.56978 -415.920174)
		(end 98.56978 -417.977828)
		(width 0.12954)
		(layer "F.Cu")
		(net "U272_2_ADD1")
	)
	(segment
		(start 97.821242 -418.707824)
		(end 97.821242 -418.166296)
		(width 0.12954)
		(layer "F.Cu")
		(net "U272_2_ADD1")
	)
	(segment
		(start 98.381312 -418.166296)
		(end 97.821242 -418.166296)
		(width 0.12954)
		(layer "F.Cu")
		(net "U272_2_ADD1")
	)
	(segment
		(start 99.523296 -419.782244)
		(end 98.98126 -419.240208)
		(width 0.12954)
		(layer "F.Cu")
		(net "U272_2_ADD1")
	)
	(segment
		(start 98.98126 -419.240208)
		(end 98.353626 -419.240208)
		(width 0.12954)
		(layer "F.Cu")
		(net "U272_2_ADD1")
	)
	(segment
		(start 97.821242 -415.171636)
		(end 98.56978 -415.920174)
		(width 0.12954)
		(layer "F.Cu")
		(net "U272_2_ADD1")
	)
	(segment
		(start 98.353626 -419.240208)
		(end 97.821242 -418.707824)
		(width 0.12954)
		(layer "F.Cu")
		(net "U272_2_ADD1")
	)
	(segment
		(start 98.56978 -417.977828)
		(end 98.381312 -418.166296)
		(width 0.12954)
		(layer "F.Cu")
		(net "U272_2_ADD1")
	)
	(segment
		(start 99.523296 -420.929816)
		(end 99.523296 -419.782244)
		(width 0.12954)
		(layer "F.Cu")
		(net "U272_2_ADD1")
	)
	(via
		(at 98.98126 -419.240208)
		(size 0.762)
		(drill 0.381)
		(layers "F.Cu" "B.Cu")
		(net "U272_2_ADD1")
	)
	(segment
		(start 100.12934 -416.525202)
		(end 100.12934 -417.778184)
		(width 0.12954)
		(layer "F.Cu")
		(net "U272_2_ADD0")
	)
	(segment
		(start 100.793296 -419.184328)
		(end 100.188776 -419.184328)
		(width 0.12954)
		(layer "F.Cu")
		(net "U272_2_ADD0")
	)
	(segment
		(start 99.480116 -418.008562)
		(end 99.457002 -418.031676)
		(width 0.12954)
		(layer "F.Cu")
		(net "U272_2_ADD0")
	)
	(segment
		(start 100.12934 -417.778184)
		(end 99.898962 -418.008562)
		(width 0.12954)
		(layer "F.Cu")
		(net "U272_2_ADD0")
	)
	(segment
		(start 99.388422 -415.784284)
		(end 100.12934 -416.525202)
		(width 0.12954)
		(layer "F.Cu")
		(net "U272_2_ADD0")
	)
	(segment
		(start 100.793296 -420.929816)
		(end 100.793296 -419.184328)
		(width 0.12954)
		(layer "F.Cu")
		(net "U272_2_ADD0")
	)
	(segment
		(start 99.898962 -418.008562)
		(end 99.480116 -418.008562)
		(width 0.12954)
		(layer "F.Cu")
		(net "U272_2_ADD0")
	)
	(segment
		(start 99.388422 -415.176716)
		(end 99.388422 -415.784284)
		(width 0.12954)
		(layer "F.Cu")
		(net "U272_2_ADD0")
	)
	(segment
		(start 99.457002 -418.452554)
		(end 99.457002 -418.031676)
		(width 0.12954)
		(layer "F.Cu")
		(net "U272_2_ADD0")
	)
	(segment
		(start 100.188776 -419.184328)
		(end 99.457002 -418.452554)
		(width 0.12954)
		(layer "F.Cu")
		(net "U272_2_ADD0")
	)
	(via
		(at 100.793296 -419.184328)
		(size 0.762)
		(drill 0.381)
		(layers "F.Cu" "B.Cu")
		(net "U272_2_ADD0")
	)
	(segment
		(start 299.017436 -14.284452)
		(end 298.544996 -13.812012)
		(width 0.12954)
		(layer "F.Cu")
		(net "U271_1_ADD2")
	)
	(segment
		(start 300.333664 -14.506194)
		(end 299.745654 -14.506194)
		(width 0.12954)
		(layer "F.Cu")
		(net "U271_1_ADD2")
	)
	(segment
		(start 298.544996 -13.812012)
		(end 296.953432 -13.812012)
		(width 0.12954)
		(layer "F.Cu")
		(net "U271_1_ADD2")
	)
	(segment
		(start 295.689274 -13.443204)
		(end 296.752264 -14.506194)
		(width 0.12954)
		(layer "F.Cu")
		(net "U271_1_ADD2")
	)
	(segment
		(start 299.017436 -15.234412)
		(end 299.017436 -14.284452)
		(width 0.12954)
		(layer "F.Cu")
		(net "U271_1_ADD2")
	)
	(segment
		(start 296.752264 -14.01318)
		(end 296.752264 -14.506194)
		(width 0.12954)
		(layer "F.Cu")
		(net "U271_1_ADD2")
	)
	(segment
		(start 296.953432 -13.812012)
		(end 296.752264 -14.01318)
		(width 0.12954)
		(layer "F.Cu")
		(net "U271_1_ADD2")
	)
	(segment
		(start 299.745654 -14.506194)
		(end 299.017436 -15.234412)
		(width 0.12954)
		(layer "F.Cu")
		(net "U271_1_ADD2")
	)
	(segment
		(start 294.482012 -13.443204)
		(end 295.689274 -13.443204)
		(width 0.12954)
		(layer "F.Cu")
		(net "U271_1_ADD2")
	)
	(via
		(at 299.017436 -15.234412)
		(size 0.762)
		(drill 0.381)
		(layers "F.Cu" "B.Cu")
		(net "U271_1_ADD2")
	)
	(segment
		(start 296.934636 -16.174974)
		(end 296.747184 -15.987522)
		(width 0.12954)
		(layer "F.Cu")
		(net "U271_1_ADD1")
	)
	(segment
		(start 295.887394 -14.713204)
		(end 296.747184 -15.572994)
		(width 0.12954)
		(layer "F.Cu")
		(net "U271_1_ADD1")
	)
	(segment
		(start 299.03674 -16.705326)
		(end 298.506388 -16.174974)
		(width 0.12954)
		(layer "F.Cu")
		(net "U271_1_ADD1")
	)
	(segment
		(start 296.747184 -15.987522)
		(end 296.747184 -15.572994)
		(width 0.12954)
		(layer "F.Cu")
		(net "U271_1_ADD1")
	)
	(segment
		(start 300.169072 -15.572994)
		(end 299.03674 -16.705326)
		(width 0.12954)
		(layer "F.Cu")
		(net "U271_1_ADD1")
	)
	(segment
		(start 300.353984 -15.572994)
		(end 300.169072 -15.572994)
		(width 0.12954)
		(layer "F.Cu")
		(net "U271_1_ADD1")
	)
	(segment
		(start 298.506388 -16.174974)
		(end 296.934636 -16.174974)
		(width 0.12954)
		(layer "F.Cu")
		(net "U271_1_ADD1")
	)
	(segment
		(start 294.482012 -14.713204)
		(end 295.887394 -14.713204)
		(width 0.12954)
		(layer "F.Cu")
		(net "U271_1_ADD1")
	)
	(via
		(at 299.03674 -16.705326)
		(size 0.762)
		(drill 0.381)
		(layers "F.Cu" "B.Cu")
		(net "U271_1_ADD1")
	)
	(segment
		(start 297.117516 -18.132552)
		(end 297.34891 -18.132552)
		(width 0.12954)
		(layer "F.Cu")
		(net "U271_1_ADD0")
	)
	(segment
		(start 294.482012 -15.983204)
		(end 296.014394 -15.983204)
		(width 0.12954)
		(layer "F.Cu")
		(net "U271_1_ADD0")
	)
	(segment
		(start 300.328584 -17.892014)
		(end 300.328584 -16.715994)
		(width 0.12954)
		(layer "F.Cu")
		(net "U271_1_ADD0")
	)
	(segment
		(start 300.088046 -18.132552)
		(end 300.328584 -17.892014)
		(width 0.12954)
		(layer "F.Cu")
		(net "U271_1_ADD0")
	)
	(segment
		(start 296.747184 -16.715994)
		(end 296.747184 -17.76222)
		(width 0.12954)
		(layer "F.Cu")
		(net "U271_1_ADD0")
	)
	(segment
		(start 296.014394 -15.983204)
		(end 296.747184 -16.715994)
		(width 0.12954)
		(layer "F.Cu")
		(net "U271_1_ADD0")
	)
	(segment
		(start 296.747184 -17.76222)
		(end 297.117516 -18.132552)
		(width 0.12954)
		(layer "F.Cu")
		(net "U271_1_ADD0")
	)
	(segment
		(start 297.34891 -18.132552)
		(end 300.088046 -18.132552)
		(width 0.12954)
		(layer "F.Cu")
		(net "U271_1_ADD0")
	)
	(via
		(at 297.34891 -18.132552)
		(size 0.762)
		(drill 0.381)
		(layers "F.Cu" "B.Cu")
		(net "U271_1_ADD0")
	)
	(segment
		(start 369.000278 -417.9316)
		(end 369.000278 -418.874448)
		(width 0.12954)
		(layer "F.Cu")
		(net "U270_0_ADD2")
	)
	(segment
		(start 369.358418 -417.57346)
		(end 369.000278 -417.9316)
		(width 0.12954)
		(layer "F.Cu")
		(net "U270_0_ADD2")
	)
	(segment
		(start 369.000278 -418.874448)
		(end 369.000278 -420.582344)
		(width 0.12954)
		(layer "F.Cu")
		(net "U270_0_ADD2")
	)
	(segment
		(start 368.6302 -416.845242)
		(end 368.6302 -414.518348)
		(width 0.12954)
		(layer "F.Cu")
		(net "U270_0_ADD2")
	)
	(segment
		(start 368.6302 -414.518348)
		(end 368.838988 -414.30956)
		(width 0.12954)
		(layer "F.Cu")
		(net "U270_0_ADD2")
	)
	(segment
		(start 368.838988 -414.30956)
		(end 369.368578 -414.30956)
		(width 0.12954)
		(layer "F.Cu")
		(net "U270_0_ADD2")
	)
	(segment
		(start 369.358418 -417.57346)
		(end 368.6302 -416.845242)
		(width 0.12954)
		(layer "F.Cu")
		(net "U270_0_ADD2")
	)
	(via
		(at 369.000278 -418.874448)
		(size 0.762)
		(drill 0.381)
		(layers "F.Cu" "B.Cu")
		(net "U270_0_ADD2")
	)
	(segment
		(start 370.55806 -418.831268)
		(end 370.270278 -419.11905)
		(width 0.12954)
		(layer "F.Cu")
		(net "U270_0_ADD1")
	)
	(segment
		(start 370.618258 -417.57346)
		(end 370.618258 -418.77107)
		(width 0.12954)
		(layer "F.Cu")
		(net "U270_0_ADD1")
	)
	(segment
		(start 370.618258 -418.77107)
		(end 370.55806 -418.831268)
		(width 0.12954)
		(layer "F.Cu")
		(net "U270_0_ADD1")
	)
	(segment
		(start 370.218208 -414.30448)
		(end 370.615718 -414.30448)
		(width 0.12954)
		(layer "F.Cu")
		(net "U270_0_ADD1")
	)
	(segment
		(start 369.95354 -414.569148)
		(end 370.218208 -414.30448)
		(width 0.12954)
		(layer "F.Cu")
		(net "U270_0_ADD1")
	)
	(segment
		(start 370.270278 -419.11905)
		(end 370.270278 -420.582344)
		(width 0.12954)
		(layer "F.Cu")
		(net "U270_0_ADD1")
	)
	(segment
		(start 370.618258 -417.57346)
		(end 369.95354 -416.908742)
		(width 0.12954)
		(layer "F.Cu")
		(net "U270_0_ADD1")
	)
	(segment
		(start 369.95354 -416.908742)
		(end 369.95354 -414.569148)
		(width 0.12954)
		(layer "F.Cu")
		(net "U270_0_ADD1")
	)
	(via
		(at 370.55806 -418.831268)
		(size 0.762)
		(drill 0.381)
		(layers "F.Cu" "B.Cu")
		(net "U270_0_ADD1")
	)
	(segment
		(start 371.540278 -420.08171)
		(end 371.540278 -420.582344)
		(width 0.12954)
		(layer "F.Cu")
		(net "U270_0_ADD0")
	)
	(segment
		(start 372.07952 -419.542468)
		(end 371.540278 -420.08171)
		(width 0.12954)
		(layer "F.Cu")
		(net "U270_0_ADD0")
	)
	(segment
		(start 371.796818 -417.57346)
		(end 371.23878 -417.015422)
		(width 0.12954)
		(layer "F.Cu")
		(net "U270_0_ADD0")
	)
	(segment
		(start 372.07952 -418.874448)
		(end 372.07952 -419.542468)
		(width 0.12954)
		(layer "F.Cu")
		(net "U270_0_ADD0")
	)
	(segment
		(start 371.796818 -417.57346)
		(end 372.07952 -417.856162)
		(width 0.12954)
		(layer "F.Cu")
		(net "U270_0_ADD0")
	)
	(segment
		(start 371.23878 -414.492948)
		(end 371.427248 -414.30448)
		(width 0.12954)
		(layer "F.Cu")
		(net "U270_0_ADD0")
	)
	(segment
		(start 371.427248 -414.30448)
		(end 371.791738 -414.30448)
		(width 0.12954)
		(layer "F.Cu")
		(net "U270_0_ADD0")
	)
	(segment
		(start 371.23878 -417.015422)
		(end 371.23878 -414.492948)
		(width 0.12954)
		(layer "F.Cu")
		(net "U270_0_ADD0")
	)
	(segment
		(start 372.07952 -417.856162)
		(end 372.07952 -418.874448)
		(width 0.12954)
		(layer "F.Cu")
		(net "U270_0_ADD0")
	)
	(via
		(at 372.07952 -418.874448)
		(size 0.762)
		(drill 0.381)
		(layers "F.Cu" "B.Cu")
		(net "U270_0_ADD0")
	)
	(via
		(at 6.99008 -110.487968)
		(size 0.6604)
		(drill 0.3302)
		(layers "F.Cu" "B.Cu")
		(net "TP_USB2_TEST")
	)
	(segment
		(start 10.789412 -111.71936)
		(end 11.276584 -111.71936)
		(width 0.12954)
		(layer "B.Cu")
		(net "TP_USB2_TEST")
	)
	(segment
		(start 6.99008 -110.487968)
		(end 7.62 -109.858048)
		(width 0.12954)
		(layer "B.Cu")
		(net "TP_USB2_TEST")
	)
	(segment
		(start 8.9281 -109.858048)
		(end 10.789412 -111.71936)
		(width 0.12954)
		(layer "B.Cu")
		(net "TP_USB2_TEST")
	)
	(segment
		(start 7.62 -109.858048)
		(end 8.9281 -109.858048)
		(width 0.12954)
		(layer "B.Cu")
		(net "TP_USB2_TEST")
	)
	(segment
		(start 108.839 -17.784064)
		(end 108.067602 -17.784064)
		(width 0.12954)
		(layer "F.Cu")
		(net "SMB_LM75_3_3V3AUX_SDA_R1")
	)
	(segment
		(start 110.556548 -17.784064)
		(end 108.839 -17.784064)
		(width 0.12954)
		(layer "F.Cu")
		(net "SMB_LM75_3_3V3AUX_SDA_R1")
	)
	(segment
		(start 108.067602 -17.784064)
		(end 107.419648 -17.13611)
		(width 0.12954)
		(layer "F.Cu")
		(net "SMB_LM75_3_3V3AUX_SDA_R1")
	)
	(via
		(at 108.839 -17.784064)
		(size 0.508)
		(drill 0.254)
		(layers "F.Cu" "B.Cu")
		(net "SMB_LM75_3_3V3AUX_SDA_R1")
	)
	(segment
		(start 68.481194 -105.696258)
		(end 68.481194 -106.319066)
		(width 0.12954)
		(layer "F.Cu")
		(net "SMB_LM75_3_3V3AUX_SDA")
	)
	(segment
		(start 64.135 -104.885744)
		(end 64.832738 -104.188006)
		(width 0.12954)
		(layer "F.Cu")
		(net "SMB_LM75_3_3V3AUX_SDA")
	)
	(segment
		(start 66.972942 -104.188006)
		(end 68.481194 -105.696258)
		(width 0.12954)
		(layer "F.Cu")
		(net "SMB_LM75_3_3V3AUX_SDA")
	)
	(segment
		(start 64.832738 -104.188006)
		(end 66.972942 -104.188006)
		(width 0.12954)
		(layer "F.Cu")
		(net "SMB_LM75_3_3V3AUX_SDA")
	)
	(segment
		(start 68.485766 -107.37469)
		(end 68.485766 -106.323638)
		(width 0.12954)
		(layer "F.Cu")
		(net "SMB_LM75_3_3V3AUX_SDA")
	)
	(segment
		(start 68.485766 -106.323638)
		(end 68.481194 -106.319066)
		(width 0.12954)
		(layer "F.Cu")
		(net "SMB_LM75_3_3V3AUX_SDA")
	)
	(segment
		(start 106.619548 -17.13611)
		(end 105.6132 -17.13611)
		(width 0.12954)
		(layer "F.Cu")
		(net "SMB_LM75_3_3V3AUX_SDA")
	)
	(segment
		(start 64.135 -105.628948)
		(end 64.135 -104.885744)
		(width 0.12954)
		(layer "F.Cu")
		(net "SMB_LM75_3_3V3AUX_SDA")
	)
	(via
		(at 105.6132 -17.13611)
		(size 0.508)
		(drill 0.254)
		(layers "F.Cu" "B.Cu")
		(net "SMB_LM75_3_3V3AUX_SDA")
	)
	(via
		(at 64.135 -105.628948)
		(size 0.508)
		(drill 0.254)
		(layers "F.Cu" "B.Cu")
		(net "SMB_LM75_3_3V3AUX_SDA")
	)
	(via
		(at 37.01288 -52.415948)
		(size 0.508)
		(drill 0.254)
		(layers "F.Cu" "B.Cu")
		(net "SMB_LM75_3_3V3AUX_SDA")
	)
	(segment
		(start 64.135 -103.513128)
		(end 37.71646 -77.094588)
		(width 0.127)
		(layer "In2.Cu")
		(net "SMB_LM75_3_3V3AUX_SDA")
	)
	(segment
		(start 64.135 -105.628948)
		(end 64.135 -103.513128)
		(width 0.127)
		(layer "In2.Cu")
		(net "SMB_LM75_3_3V3AUX_SDA")
	)
	(segment
		(start 37.71646 -53.119528)
		(end 37.01288 -52.415948)
		(width 0.127)
		(layer "In2.Cu")
		(net "SMB_LM75_3_3V3AUX_SDA")
	)
	(segment
		(start 37.71646 -77.094588)
		(end 37.71646 -53.119528)
		(width 0.127)
		(layer "In2.Cu")
		(net "SMB_LM75_3_3V3AUX_SDA")
	)
	(segment
		(start 39.93388 -47.821088)
		(end 39.93388 -49.494948)
		(width 0.127)
		(layer "In4.Cu")
		(net "SMB_LM75_3_3V3AUX_SDA")
	)
	(segment
		(start 47.68342 -40.071548)
		(end 39.93388 -47.821088)
		(width 0.127)
		(layer "In4.Cu")
		(net "SMB_LM75_3_3V3AUX_SDA")
	)
	(segment
		(start 91.93022 -16.693388)
		(end 85.787738 -22.83587)
		(width 0.127)
		(layer "In4.Cu")
		(net "SMB_LM75_3_3V3AUX_SDA")
	)
	(segment
		(start 85.787738 -22.83587)
		(end 85.787738 -33.773618)
		(width 0.127)
		(layer "In4.Cu")
		(net "SMB_LM75_3_3V3AUX_SDA")
	)
	(segment
		(start 78.372208 -41.189148)
		(end 63.7794 -41.189148)
		(width 0.127)
		(layer "In4.Cu")
		(net "SMB_LM75_3_3V3AUX_SDA")
	)
	(segment
		(start 98.316542 -17.13611)
		(end 97.87382 -16.693388)
		(width 0.127)
		(layer "In4.Cu")
		(net "SMB_LM75_3_3V3AUX_SDA")
	)
	(segment
		(start 63.7794 -41.189148)
		(end 62.6618 -40.071548)
		(width 0.127)
		(layer "In4.Cu")
		(net "SMB_LM75_3_3V3AUX_SDA")
	)
	(segment
		(start 105.6132 -17.13611)
		(end 98.316542 -17.13611)
		(width 0.127)
		(layer "In4.Cu")
		(net "SMB_LM75_3_3V3AUX_SDA")
	)
	(segment
		(start 62.6618 -40.071548)
		(end 47.68342 -40.071548)
		(width 0.127)
		(layer "In4.Cu")
		(net "SMB_LM75_3_3V3AUX_SDA")
	)
	(segment
		(start 39.93388 -49.494948)
		(end 37.01288 -52.415948)
		(width 0.127)
		(layer "In4.Cu")
		(net "SMB_LM75_3_3V3AUX_SDA")
	)
	(segment
		(start 97.87382 -16.693388)
		(end 91.93022 -16.693388)
		(width 0.127)
		(layer "In4.Cu")
		(net "SMB_LM75_3_3V3AUX_SDA")
	)
	(segment
		(start 85.787738 -33.773618)
		(end 78.372208 -41.189148)
		(width 0.127)
		(layer "In4.Cu")
		(net "SMB_LM75_3_3V3AUX_SDA")
	)
	(segment
		(start 108.839 -16.514064)
		(end 108.016802 -16.514064)
		(width 0.12954)
		(layer "F.Cu")
		(net "SMB_LM75_3_3V3AUX_SCL_R1")
	)
	(segment
		(start 110.556548 -16.514064)
		(end 108.839 -16.514064)
		(width 0.12954)
		(layer "F.Cu")
		(net "SMB_LM75_3_3V3AUX_SCL_R1")
	)
	(segment
		(start 108.016802 -16.514064)
		(end 107.419648 -15.91691)
		(width 0.12954)
		(layer "F.Cu")
		(net "SMB_LM75_3_3V3AUX_SCL_R1")
	)
	(via
		(at 108.839 -16.514064)
		(size 0.508)
		(drill 0.254)
		(layers "F.Cu" "B.Cu")
		(net "SMB_LM75_3_3V3AUX_SCL_R1")
	)
	(segment
		(start 69.40042 -108.219748)
		(end 69.229478 -108.39069)
		(width 0.12954)
		(layer "F.Cu")
		(net "SMB_LM75_3_3V3AUX_SCL")
	)
	(segment
		(start 106.619548 -15.91691)
		(end 105.6132 -15.91691)
		(width 0.12954)
		(layer "F.Cu")
		(net "SMB_LM75_3_3V3AUX_SCL")
	)
	(segment
		(start 68.493894 -108.398818)
		(end 68.485766 -108.39069)
		(width 0.12954)
		(layer "F.Cu")
		(net "SMB_LM75_3_3V3AUX_SCL")
	)
	(segment
		(start 69.229478 -108.39069)
		(end 68.485766 -108.39069)
		(width 0.12954)
		(layer "F.Cu")
		(net "SMB_LM75_3_3V3AUX_SCL")
	)
	(segment
		(start 66.82486 -103.017828)
		(end 69.40042 -105.593388)
		(width 0.12954)
		(layer "F.Cu")
		(net "SMB_LM75_3_3V3AUX_SCL")
	)
	(segment
		(start 68.493894 -109.483906)
		(end 68.493894 -108.398818)
		(width 0.12954)
		(layer "F.Cu")
		(net "SMB_LM75_3_3V3AUX_SCL")
	)
	(segment
		(start 69.40042 -105.593388)
		(end 69.40042 -108.219748)
		(width 0.12954)
		(layer "F.Cu")
		(net "SMB_LM75_3_3V3AUX_SCL")
	)
	(segment
		(start 64.97574 -103.017828)
		(end 66.82486 -103.017828)
		(width 0.12954)
		(layer "F.Cu")
		(net "SMB_LM75_3_3V3AUX_SCL")
	)
	(via
		(at 105.6132 -15.91691)
		(size 0.508)
		(drill 0.254)
		(layers "F.Cu" "B.Cu")
		(net "SMB_LM75_3_3V3AUX_SCL")
	)
	(via
		(at 64.97574 -103.017828)
		(size 0.508)
		(drill 0.254)
		(layers "F.Cu" "B.Cu")
		(net "SMB_LM75_3_3V3AUX_SCL")
	)
	(via
		(at 37.01288 -51.526948)
		(size 0.508)
		(drill 0.254)
		(layers "F.Cu" "B.Cu")
		(net "SMB_LM75_3_3V3AUX_SCL")
	)
	(segment
		(start 38.42004 -77.154024)
		(end 38.42004 -52.934108)
		(width 0.127)
		(layer "In2.Cu")
		(net "SMB_LM75_3_3V3AUX_SCL")
	)
	(segment
		(start 64.358266 -103.017828)
		(end 62.68847 -101.348032)
		(width 0.127)
		(layer "In2.Cu")
		(net "SMB_LM75_3_3V3AUX_SCL")
	)
	(segment
		(start 62.68847 -101.168454)
		(end 63.009526 -100.847398)
		(width 0.127)
		(layer "In2.Cu")
		(net "SMB_LM75_3_3V3AUX_SCL")
	)
	(segment
		(start 53.931058 -92.665042)
		(end 38.42004 -77.154024)
		(width 0.127)
		(layer "In2.Cu")
		(net "SMB_LM75_3_3V3AUX_SCL")
	)
	(segment
		(start 62.060074 -100.719636)
		(end 54.00548 -92.665042)
		(width 0.127)
		(layer "In2.Cu")
		(net "SMB_LM75_3_3V3AUX_SCL")
	)
	(segment
		(start 62.739778 -100.398326)
		(end 62.560708 -100.398326)
		(width 0.127)
		(layer "In2.Cu")
		(net "SMB_LM75_3_3V3AUX_SCL")
	)
	(segment
		(start 62.560708 -100.398326)
		(end 62.239398 -100.719636)
		(width 0.127)
		(layer "In2.Cu")
		(net "SMB_LM75_3_3V3AUX_SCL")
	)
	(segment
		(start 54.00548 -92.665042)
		(end 53.931058 -92.665042)
		(width 0.127)
		(layer "In2.Cu")
		(net "SMB_LM75_3_3V3AUX_SCL")
	)
	(segment
		(start 62.239398 -100.719636)
		(end 62.060074 -100.719636)
		(width 0.127)
		(layer "In2.Cu")
		(net "SMB_LM75_3_3V3AUX_SCL")
	)
	(segment
		(start 62.68847 -101.348032)
		(end 62.68847 -101.168454)
		(width 0.127)
		(layer "In2.Cu")
		(net "SMB_LM75_3_3V3AUX_SCL")
	)
	(segment
		(start 64.97574 -103.017828)
		(end 64.358266 -103.017828)
		(width 0.127)
		(layer "In2.Cu")
		(net "SMB_LM75_3_3V3AUX_SCL")
	)
	(segment
		(start 38.42004 -52.934108)
		(end 37.01288 -51.526948)
		(width 0.127)
		(layer "In2.Cu")
		(net "SMB_LM75_3_3V3AUX_SCL")
	)
	(segment
		(start 63.009526 -100.847398)
		(end 63.009526 -100.668074)
		(width 0.127)
		(layer "In2.Cu")
		(net "SMB_LM75_3_3V3AUX_SCL")
	)
	(segment
		(start 63.009526 -100.668074)
		(end 62.739778 -100.398326)
		(width 0.127)
		(layer "In2.Cu")
		(net "SMB_LM75_3_3V3AUX_SCL")
	)
	(segment
		(start 62.611 -39.030148)
		(end 62.9666 -39.385748)
		(width 0.127)
		(layer "In4.Cu")
		(net "SMB_LM75_3_3V3AUX_SCL")
	)
	(segment
		(start 79.234284 -39.715948)
		(end 85.33638 -33.613852)
		(width 0.127)
		(layer "In4.Cu")
		(net "SMB_LM75_3_3V3AUX_SCL")
	)
	(segment
		(start 39.50208 -49.037748)
		(end 39.50208 -47.641764)
		(width 0.127)
		(layer "In4.Cu")
		(net "SMB_LM75_3_3V3AUX_SCL")
	)
	(segment
		(start 62.9666 -39.385748)
		(end 64.5414 -39.385748)
		(width 0.127)
		(layer "In4.Cu")
		(net "SMB_LM75_3_3V3AUX_SCL")
	)
	(segment
		(start 74.14768 -39.385748)
		(end 74.47788 -39.715948)
		(width 0.127)
		(layer "In4.Cu")
		(net "SMB_LM75_3_3V3AUX_SCL")
	)
	(segment
		(start 85.33638 -33.613852)
		(end 85.33638 -21.938996)
		(width 0.127)
		(layer "In4.Cu")
		(net "SMB_LM75_3_3V3AUX_SCL")
	)
	(segment
		(start 39.50208 -47.641764)
		(end 48.113696 -39.030148)
		(width 0.127)
		(layer "In4.Cu")
		(net "SMB_LM75_3_3V3AUX_SCL")
	)
	(segment
		(start 105.100882 -16.429228)
		(end 105.6132 -15.91691)
		(width 0.127)
		(layer "In4.Cu")
		(net "SMB_LM75_3_3V3AUX_SCL")
	)
	(segment
		(start 70.993 -39.385748)
		(end 74.14768 -39.385748)
		(width 0.127)
		(layer "In4.Cu")
		(net "SMB_LM75_3_3V3AUX_SCL")
	)
	(segment
		(start 64.9986 -38.928548)
		(end 70.5358 -38.928548)
		(width 0.127)
		(layer "In4.Cu")
		(net "SMB_LM75_3_3V3AUX_SCL")
	)
	(segment
		(start 91.53525 -15.740126)
		(end 98.26879 -15.740126)
		(width 0.127)
		(layer "In4.Cu")
		(net "SMB_LM75_3_3V3AUX_SCL")
	)
	(segment
		(start 70.5358 -38.928548)
		(end 70.993 -39.385748)
		(width 0.127)
		(layer "In4.Cu")
		(net "SMB_LM75_3_3V3AUX_SCL")
	)
	(segment
		(start 85.33638 -21.938996)
		(end 91.53525 -15.740126)
		(width 0.127)
		(layer "In4.Cu")
		(net "SMB_LM75_3_3V3AUX_SCL")
	)
	(segment
		(start 98.26879 -15.740126)
		(end 98.957892 -16.429228)
		(width 0.127)
		(layer "In4.Cu")
		(net "SMB_LM75_3_3V3AUX_SCL")
	)
	(segment
		(start 48.113696 -39.030148)
		(end 62.611 -39.030148)
		(width 0.127)
		(layer "In4.Cu")
		(net "SMB_LM75_3_3V3AUX_SCL")
	)
	(segment
		(start 64.5414 -39.385748)
		(end 64.9986 -38.928548)
		(width 0.127)
		(layer "In4.Cu")
		(net "SMB_LM75_3_3V3AUX_SCL")
	)
	(segment
		(start 37.01288 -51.526948)
		(end 39.50208 -49.037748)
		(width 0.127)
		(layer "In4.Cu")
		(net "SMB_LM75_3_3V3AUX_SCL")
	)
	(segment
		(start 74.47788 -39.715948)
		(end 79.234284 -39.715948)
		(width 0.127)
		(layer "In4.Cu")
		(net "SMB_LM75_3_3V3AUX_SCL")
	)
	(segment
		(start 98.957892 -16.429228)
		(end 105.100882 -16.429228)
		(width 0.127)
		(layer "In4.Cu")
		(net "SMB_LM75_3_3V3AUX_SCL")
	)
	(segment
		(start 104.203246 -424.962828)
		(end 104.62895 -424.962828)
		(width 0.12954)
		(layer "F.Cu")
		(net "SMB_LM75_2_3V3AUX_SDA_R1")
	)
	(segment
		(start 103.499666 -424.401488)
		(end 103.499666 -424.72864)
		(width 0.12954)
		(layer "F.Cu")
		(net "SMB_LM75_2_3V3AUX_SDA_R1")
	)
	(segment
		(start 102.362 -425.135548)
		(end 102.732586 -425.135548)
		(width 0.12954)
		(layer "F.Cu")
		(net "SMB_LM75_2_3V3AUX_SDA_R1")
	)
	(segment
		(start 102.063296 -426.22978)
		(end 102.063296 -425.434252)
		(width 0.12954)
		(layer "F.Cu")
		(net "SMB_LM75_2_3V3AUX_SDA_R1")
	)
	(segment
		(start 104.62895 -424.962828)
		(end 104.81183 -424.779948)
		(width 0.12954)
		(layer "F.Cu")
		(net "SMB_LM75_2_3V3AUX_SDA_R1")
	)
	(segment
		(start 103.733854 -424.962828)
		(end 104.203246 -424.962828)
		(width 0.12954)
		(layer "F.Cu")
		(net "SMB_LM75_2_3V3AUX_SDA_R1")
	)
	(segment
		(start 102.991666 -424.271948)
		(end 103.370126 -424.271948)
		(width 0.12954)
		(layer "F.Cu")
		(net "SMB_LM75_2_3V3AUX_SDA_R1")
	)
	(segment
		(start 103.370126 -424.271948)
		(end 103.499666 -424.401488)
		(width 0.12954)
		(layer "F.Cu")
		(net "SMB_LM75_2_3V3AUX_SDA_R1")
	)
	(segment
		(start 102.063296 -425.434252)
		(end 102.362 -425.135548)
		(width 0.12954)
		(layer "F.Cu")
		(net "SMB_LM75_2_3V3AUX_SDA_R1")
	)
	(segment
		(start 102.732586 -425.135548)
		(end 102.862126 -425.006008)
		(width 0.12954)
		(layer "F.Cu")
		(net "SMB_LM75_2_3V3AUX_SDA_R1")
	)
	(segment
		(start 103.499666 -424.72864)
		(end 103.733854 -424.962828)
		(width 0.12954)
		(layer "F.Cu")
		(net "SMB_LM75_2_3V3AUX_SDA_R1")
	)
	(segment
		(start 102.862126 -424.401488)
		(end 102.991666 -424.271948)
		(width 0.12954)
		(layer "F.Cu")
		(net "SMB_LM75_2_3V3AUX_SDA_R1")
	)
	(segment
		(start 102.862126 -425.006008)
		(end 102.862126 -424.401488)
		(width 0.12954)
		(layer "F.Cu")
		(net "SMB_LM75_2_3V3AUX_SDA_R1")
	)
	(via
		(at 104.203246 -424.962828)
		(size 0.508)
		(drill 0.254)
		(layers "F.Cu" "B.Cu")
		(net "SMB_LM75_2_3V3AUX_SDA_R1")
	)
	(segment
		(start 78.102714 -416.43554)
		(end 73.347834 -411.68066)
		(width 0.12954)
		(layer "F.Cu")
		(net "SMB_LM75_2_3V3AUX_SDA")
	)
	(segment
		(start 53.842666 -107.88269)
		(end 52.704746 -106.74477)
		(width 0.12954)
		(layer "F.Cu")
		(net "SMB_LM75_2_3V3AUX_SDA")
	)
	(segment
		(start 105.97388 -424.779948)
		(end 106.32948 -424.424348)
		(width 0.12954)
		(layer "F.Cu")
		(net "SMB_LM75_2_3V3AUX_SDA")
	)
	(segment
		(start 94.59722 -423.829988)
		(end 93.33992 -422.572688)
		(width 0.12954)
		(layer "F.Cu")
		(net "SMB_LM75_2_3V3AUX_SDA")
	)
	(segment
		(start 97.28454 -423.829988)
		(end 94.59722 -423.829988)
		(width 0.12954)
		(layer "F.Cu")
		(net "SMB_LM75_2_3V3AUX_SDA")
	)
	(segment
		(start 93.33992 -420.350188)
		(end 89.425272 -416.43554)
		(width 0.12954)
		(layer "F.Cu")
		(net "SMB_LM75_2_3V3AUX_SDA")
	)
	(segment
		(start 53.878988 -411.53334)
		(end 52.86121 -412.551118)
		(width 0.12954)
		(layer "F.Cu")
		(net "SMB_LM75_2_3V3AUX_SDA")
	)
	(segment
		(start 93.33992 -422.572688)
		(end 93.33992 -420.350188)
		(width 0.12954)
		(layer "F.Cu")
		(net "SMB_LM75_2_3V3AUX_SDA")
	)
	(segment
		(start 51.284886 -106.03611)
		(end 51.993546 -106.74477)
		(width 0.12954)
		(layer "F.Cu")
		(net "SMB_LM75_2_3V3AUX_SDA")
	)
	(segment
		(start 52.704746 -106.74477)
		(end 51.993546 -106.74477)
		(width 0.12954)
		(layer "F.Cu")
		(net "SMB_LM75_2_3V3AUX_SDA")
	)
	(segment
		(start 49.5427 -106.03611)
		(end 51.284886 -106.03611)
		(width 0.12954)
		(layer "F.Cu")
		(net "SMB_LM75_2_3V3AUX_SDA")
	)
	(segment
		(start 106.32948 -423.255948)
		(end 105.76814 -422.694608)
		(width 0.12954)
		(layer "F.Cu")
		(net "SMB_LM75_2_3V3AUX_SDA")
	)
	(segment
		(start 73.20026 -411.53334)
		(end 53.878988 -411.53334)
		(width 0.12954)
		(layer "F.Cu")
		(net "SMB_LM75_2_3V3AUX_SDA")
	)
	(segment
		(start 106.32948 -424.424348)
		(end 106.32948 -423.255948)
		(width 0.12954)
		(layer "F.Cu")
		(net "SMB_LM75_2_3V3AUX_SDA")
	)
	(segment
		(start 105.61193 -424.779948)
		(end 105.97388 -424.779948)
		(width 0.12954)
		(layer "F.Cu")
		(net "SMB_LM75_2_3V3AUX_SDA")
	)
	(segment
		(start 73.347834 -411.68066)
		(end 73.34758 -411.68066)
		(width 0.12954)
		(layer "F.Cu")
		(net "SMB_LM75_2_3V3AUX_SDA")
	)
	(segment
		(start 98.41992 -422.694608)
		(end 97.28454 -423.829988)
		(width 0.12954)
		(layer "F.Cu")
		(net "SMB_LM75_2_3V3AUX_SDA")
	)
	(segment
		(start 105.76814 -422.694608)
		(end 98.41992 -422.694608)
		(width 0.12954)
		(layer "F.Cu")
		(net "SMB_LM75_2_3V3AUX_SDA")
	)
	(segment
		(start 89.425272 -416.43554)
		(end 78.102714 -416.43554)
		(width 0.12954)
		(layer "F.Cu")
		(net "SMB_LM75_2_3V3AUX_SDA")
	)
	(segment
		(start 73.34758 -411.68066)
		(end 73.20026 -411.53334)
		(width 0.12954)
		(layer "F.Cu")
		(net "SMB_LM75_2_3V3AUX_SDA")
	)
	(via
		(at 52.86121 -412.551118)
		(size 0.508)
		(drill 0.254)
		(layers "F.Cu" "B.Cu")
		(net "SMB_LM75_2_3V3AUX_SDA")
	)
	(via
		(at 49.5427 -106.03611)
		(size 0.508)
		(drill 0.254)
		(layers "F.Cu" "B.Cu")
		(net "SMB_LM75_2_3V3AUX_SDA")
	)
	(segment
		(start 49.29124 -411.513528)
		(end 46.8757 -409.097988)
		(width 0.127)
		(layer "In2.Cu")
		(net "SMB_LM75_2_3V3AUX_SDA")
	)
	(segment
		(start 14.04874 -184.32526)
		(end 14.04874 -175.231298)
		(width 0.127)
		(layer "In2.Cu")
		(net "SMB_LM75_2_3V3AUX_SDA")
	)
	(segment
		(start 51.69916 -411.513528)
		(end 49.29124 -411.513528)
		(width 0.127)
		(layer "In2.Cu")
		(net "SMB_LM75_2_3V3AUX_SDA")
	)
	(segment
		(start 17.48282 -329.225148)
		(end 15.68704 -327.429368)
		(width 0.127)
		(layer "In2.Cu")
		(net "SMB_LM75_2_3V3AUX_SDA")
	)
	(segment
		(start 52.86121 -412.551118)
		(end 52.73675 -412.551118)
		(width 0.127)
		(layer "In2.Cu")
		(net "SMB_LM75_2_3V3AUX_SDA")
	)
	(segment
		(start 52.73675 -412.551118)
		(end 51.69916 -411.513528)
		(width 0.127)
		(layer "In2.Cu")
		(net "SMB_LM75_2_3V3AUX_SDA")
	)
	(segment
		(start 12.8524 -190.29172)
		(end 12.8524 -185.5216)
		(width 0.127)
		(layer "In2.Cu")
		(net "SMB_LM75_2_3V3AUX_SDA")
	)
	(segment
		(start 46.4693 -107.531408)
		(end 47.63262 -106.368088)
		(width 0.127)
		(layer "In2.Cu")
		(net "SMB_LM75_2_3V3AUX_SDA")
	)
	(segment
		(start 38.0746 -395.25448)
		(end 35.88385 -393.06373)
		(width 0.127)
		(layer "In2.Cu")
		(net "SMB_LM75_2_3V3AUX_SDA")
	)
	(segment
		(start 17.79905 -117.598952)
		(end 38.083744 -117.598952)
		(width 0.127)
		(layer "In2.Cu")
		(net "SMB_LM75_2_3V3AUX_SDA")
	)
	(segment
		(start 17.32788 -323.865748)
		(end 17.32788 -257.749548)
		(width 0.127)
		(layer "In2.Cu")
		(net "SMB_LM75_2_3V3AUX_SDA")
	)
	(segment
		(start 28.93695 -329.225148)
		(end 17.48282 -329.225148)
		(width 0.127)
		(layer "In2.Cu")
		(net "SMB_LM75_2_3V3AUX_SDA")
	)
	(segment
		(start 46.4693 -109.213396)
		(end 46.4693 -107.531408)
		(width 0.127)
		(layer "In2.Cu")
		(net "SMB_LM75_2_3V3AUX_SDA")
	)
	(segment
		(start 16.24838 -253.241048)
		(end 16.83258 -253.241048)
		(width 0.127)
		(layer "In2.Cu")
		(net "SMB_LM75_2_3V3AUX_SDA")
	)
	(segment
		(start 17.1196 -166.451788)
		(end 19.33702 -164.234368)
		(width 0.127)
		(layer "In2.Cu")
		(net "SMB_LM75_2_3V3AUX_SDA")
	)
	(segment
		(start 15.68704 -327.429368)
		(end 15.68704 -325.506588)
		(width 0.127)
		(layer "In2.Cu")
		(net "SMB_LM75_2_3V3AUX_SDA")
	)
	(segment
		(start 16.81988 -194.2592)
		(end 12.8524 -190.29172)
		(width 0.127)
		(layer "In2.Cu")
		(net "SMB_LM75_2_3V3AUX_SDA")
	)
	(segment
		(start 15.77848 -253.710948)
		(end 16.24838 -253.241048)
		(width 0.127)
		(layer "In2.Cu")
		(net "SMB_LM75_2_3V3AUX_SDA")
	)
	(segment
		(start 15.77848 -256.200148)
		(end 15.77848 -253.710948)
		(width 0.127)
		(layer "In2.Cu")
		(net "SMB_LM75_2_3V3AUX_SDA")
	)
	(segment
		(start 14.04874 -175.231298)
		(end 17.1196 -172.160438)
		(width 0.127)
		(layer "In2.Cu")
		(net "SMB_LM75_2_3V3AUX_SDA")
	)
	(segment
		(start 16.81988 -194.833748)
		(end 16.81988 -194.2592)
		(width 0.127)
		(layer "In2.Cu")
		(net "SMB_LM75_2_3V3AUX_SDA")
	)
	(segment
		(start 13.43914 -140.579348)
		(end 13.43914 -121.958862)
		(width 0.127)
		(layer "In2.Cu")
		(net "SMB_LM75_2_3V3AUX_SDA")
	)
	(segment
		(start 38.083744 -117.598952)
		(end 46.4693 -109.213396)
		(width 0.127)
		(layer "In2.Cu")
		(net "SMB_LM75_2_3V3AUX_SDA")
	)
	(segment
		(start 17.32788 -195.341748)
		(end 16.81988 -194.833748)
		(width 0.127)
		(layer "In2.Cu")
		(net "SMB_LM75_2_3V3AUX_SDA")
	)
	(segment
		(start 19.33702 -164.234368)
		(end 19.33702 -146.477228)
		(width 0.127)
		(layer "In2.Cu")
		(net "SMB_LM75_2_3V3AUX_SDA")
	)
	(segment
		(start 42.90568 -395.25448)
		(end 38.0746 -395.25448)
		(width 0.127)
		(layer "In2.Cu")
		(net "SMB_LM75_2_3V3AUX_SDA")
	)
	(segment
		(start 47.63262 -106.368088)
		(end 49.210722 -106.368088)
		(width 0.127)
		(layer "In2.Cu")
		(net "SMB_LM75_2_3V3AUX_SDA")
	)
	(segment
		(start 19.33702 -146.477228)
		(end 13.43914 -140.579348)
		(width 0.127)
		(layer "In2.Cu")
		(net "SMB_LM75_2_3V3AUX_SDA")
	)
	(segment
		(start 49.210722 -106.368088)
		(end 49.5427 -106.03611)
		(width 0.127)
		(layer "In2.Cu")
		(net "SMB_LM75_2_3V3AUX_SDA")
	)
	(segment
		(start 17.32788 -252.745748)
		(end 17.32788 -195.341748)
		(width 0.127)
		(layer "In2.Cu")
		(net "SMB_LM75_2_3V3AUX_SDA")
	)
	(segment
		(start 17.1196 -172.160438)
		(end 17.1196 -166.451788)
		(width 0.127)
		(layer "In2.Cu")
		(net "SMB_LM75_2_3V3AUX_SDA")
	)
	(segment
		(start 35.88385 -393.06373)
		(end 35.88385 -374.272048)
		(width 0.127)
		(layer "In2.Cu")
		(net "SMB_LM75_2_3V3AUX_SDA")
	)
	(segment
		(start 12.8524 -185.5216)
		(end 14.04874 -184.32526)
		(width 0.127)
		(layer "In2.Cu")
		(net "SMB_LM75_2_3V3AUX_SDA")
	)
	(segment
		(start 17.32788 -257.749548)
		(end 15.77848 -256.200148)
		(width 0.127)
		(layer "In2.Cu")
		(net "SMB_LM75_2_3V3AUX_SDA")
	)
	(segment
		(start 46.8757 -399.2245)
		(end 42.90568 -395.25448)
		(width 0.127)
		(layer "In2.Cu")
		(net "SMB_LM75_2_3V3AUX_SDA")
	)
	(segment
		(start 13.43914 -121.958862)
		(end 17.79905 -117.598952)
		(width 0.127)
		(layer "In2.Cu")
		(net "SMB_LM75_2_3V3AUX_SDA")
	)
	(segment
		(start 46.8757 -409.097988)
		(end 46.8757 -399.2245)
		(width 0.127)
		(layer "In2.Cu")
		(net "SMB_LM75_2_3V3AUX_SDA")
	)
	(segment
		(start 30.00248 -330.290678)
		(end 28.93695 -329.225148)
		(width 0.127)
		(layer "In2.Cu")
		(net "SMB_LM75_2_3V3AUX_SDA")
	)
	(segment
		(start 16.83258 -253.241048)
		(end 17.32788 -252.745748)
		(width 0.127)
		(layer "In2.Cu")
		(net "SMB_LM75_2_3V3AUX_SDA")
	)
	(segment
		(start 35.88385 -374.272048)
		(end 30.00248 -368.390678)
		(width 0.127)
		(layer "In2.Cu")
		(net "SMB_LM75_2_3V3AUX_SDA")
	)
	(segment
		(start 15.68704 -325.506588)
		(end 17.32788 -323.865748)
		(width 0.127)
		(layer "In2.Cu")
		(net "SMB_LM75_2_3V3AUX_SDA")
	)
	(segment
		(start 30.00248 -368.390678)
		(end 30.00248 -330.290678)
		(width 0.127)
		(layer "In2.Cu")
		(net "SMB_LM75_2_3V3AUX_SDA")
	)
	(segment
		(start 101.57968 -423.763948)
		(end 104.81183 -423.763948)
		(width 0.12954)
		(layer "F.Cu")
		(net "SMB_LM75_2_3V3AUX_SCL_R1")
	)
	(segment
		(start 100.793296 -425.110148)
		(end 100.793296 -424.550332)
		(width 0.12954)
		(layer "F.Cu")
		(net "SMB_LM75_2_3V3AUX_SCL_R1")
	)
	(segment
		(start 100.793296 -424.550332)
		(end 101.57968 -423.763948)
		(width 0.12954)
		(layer "F.Cu")
		(net "SMB_LM75_2_3V3AUX_SCL_R1")
	)
	(segment
		(start 100.793296 -426.22978)
		(end 100.793296 -425.110148)
		(width 0.12954)
		(layer "F.Cu")
		(net "SMB_LM75_2_3V3AUX_SCL_R1")
	)
	(via
		(at 100.793296 -425.110148)
		(size 0.508)
		(drill 0.254)
		(layers "F.Cu" "B.Cu")
		(net "SMB_LM75_2_3V3AUX_SCL_R1")
	)
	(segment
		(start 53.842666 -106.86669)
		(end 52.323746 -105.34777)
		(width 0.12954)
		(layer "F.Cu")
		(net "SMB_LM75_2_3V3AUX_SCL")
	)
	(segment
		(start 73.241408 -412.18866)
		(end 73.241154 -412.18866)
		(width 0.12954)
		(layer "F.Cu")
		(net "SMB_LM75_2_3V3AUX_SCL")
	)
	(segment
		(start 54.8132 -412.115)
		(end 53.8226 -413.1056)
		(width 0.12954)
		(layer "F.Cu")
		(net "SMB_LM75_2_3V3AUX_SCL")
	)
	(segment
		(start 94.30512 -424.287188)
		(end 92.8624 -422.844468)
		(width 0.12954)
		(layer "F.Cu")
		(net "SMB_LM75_2_3V3AUX_SCL")
	)
	(segment
		(start 73.241154 -412.18866)
		(end 73.167494 -412.115)
		(width 0.12954)
		(layer "F.Cu")
		(net "SMB_LM75_2_3V3AUX_SCL")
	)
	(segment
		(start 77.922628 -416.86988)
		(end 73.241408 -412.18866)
		(width 0.12954)
		(layer "F.Cu")
		(net "SMB_LM75_2_3V3AUX_SCL")
	)
	(segment
		(start 97.61728 -424.287188)
		(end 94.30512 -424.287188)
		(width 0.12954)
		(layer "F.Cu")
		(net "SMB_LM75_2_3V3AUX_SCL")
	)
	(segment
		(start 52.323746 -105.34777)
		(end 51.993546 -105.34777)
		(width 0.12954)
		(layer "F.Cu")
		(net "SMB_LM75_2_3V3AUX_SCL")
	)
	(segment
		(start 92.8624 -420.487094)
		(end 89.245186 -416.86988)
		(width 0.12954)
		(layer "F.Cu")
		(net "SMB_LM75_2_3V3AUX_SCL")
	)
	(segment
		(start 89.245186 -416.86988)
		(end 77.922628 -416.86988)
		(width 0.12954)
		(layer "F.Cu")
		(net "SMB_LM75_2_3V3AUX_SCL")
	)
	(segment
		(start 105.611168 -423.317162)
		(end 105.611168 -423.274236)
		(width 0.12954)
		(layer "F.Cu")
		(net "SMB_LM75_2_3V3AUX_SCL")
	)
	(segment
		(start 98.77552 -423.128948)
		(end 97.61728 -424.287188)
		(width 0.12954)
		(layer "F.Cu")
		(net "SMB_LM75_2_3V3AUX_SCL")
	)
	(segment
		(start 52.003452 -413.1056)
		(end 51.59248 -412.694628)
		(width 0.12954)
		(layer "F.Cu")
		(net "SMB_LM75_2_3V3AUX_SCL")
	)
	(segment
		(start 105.61193 -423.763948)
		(end 105.61193 -423.317924)
		(width 0.12954)
		(layer "F.Cu")
		(net "SMB_LM75_2_3V3AUX_SCL")
	)
	(segment
		(start 51.307746 -104.66197)
		(end 51.993546 -105.34777)
		(width 0.12954)
		(layer "F.Cu")
		(net "SMB_LM75_2_3V3AUX_SCL")
	)
	(segment
		(start 53.8226 -413.1056)
		(end 52.003452 -413.1056)
		(width 0.12954)
		(layer "F.Cu")
		(net "SMB_LM75_2_3V3AUX_SCL")
	)
	(segment
		(start 105.611168 -423.274236)
		(end 105.46588 -423.128948)
		(width 0.12954)
		(layer "F.Cu")
		(net "SMB_LM75_2_3V3AUX_SCL")
	)
	(segment
		(start 105.46588 -423.128948)
		(end 98.77552 -423.128948)
		(width 0.12954)
		(layer "F.Cu")
		(net "SMB_LM75_2_3V3AUX_SCL")
	)
	(segment
		(start 73.167494 -412.115)
		(end 54.8132 -412.115)
		(width 0.12954)
		(layer "F.Cu")
		(net "SMB_LM75_2_3V3AUX_SCL")
	)
	(segment
		(start 105.61193 -423.317924)
		(end 105.611168 -423.317162)
		(width 0.12954)
		(layer "F.Cu")
		(net "SMB_LM75_2_3V3AUX_SCL")
	)
	(segment
		(start 49.5427 -104.66197)
		(end 51.307746 -104.66197)
		(width 0.12954)
		(layer "F.Cu")
		(net "SMB_LM75_2_3V3AUX_SCL")
	)
	(segment
		(start 92.8624 -422.844468)
		(end 92.8624 -420.487094)
		(width 0.12954)
		(layer "F.Cu")
		(net "SMB_LM75_2_3V3AUX_SCL")
	)
	(via
		(at 49.5427 -104.66197)
		(size 0.508)
		(drill 0.254)
		(layers "F.Cu" "B.Cu")
		(net "SMB_LM75_2_3V3AUX_SCL")
	)
	(via
		(at 51.59248 -412.694628)
		(size 0.508)
		(drill 0.254)
		(layers "F.Cu" "B.Cu")
		(net "SMB_LM75_2_3V3AUX_SCL")
	)
	(segment
		(start 44.06138 -111.010446)
		(end 44.06138 -107.484164)
		(width 0.127)
		(layer "In2.Cu")
		(net "SMB_LM75_2_3V3AUX_SCL")
	)
	(segment
		(start 17.226026 -329.656948)
		(end 13.97508 -326.406002)
		(width 0.127)
		(layer "In2.Cu")
		(net "SMB_LM75_2_3V3AUX_SCL")
	)
	(segment
		(start 48.573182 -105.631488)
		(end 49.5427 -104.66197)
		(width 0.127)
		(layer "In2.Cu")
		(net "SMB_LM75_2_3V3AUX_SCL")
	)
	(segment
		(start 13.97508 -251.450348)
		(end 13.92428 -251.399548)
		(width 0.127)
		(layer "In2.Cu")
		(net "SMB_LM75_2_3V3AUX_SCL")
	)
	(segment
		(start 13.00734 -121.613168)
		(end 17.70761 -116.912898)
		(width 0.127)
		(layer "In2.Cu")
		(net "SMB_LM75_2_3V3AUX_SCL")
	)
	(segment
		(start 46.330362 -399.45056)
		(end 42.67962 -395.799818)
		(width 0.127)
		(layer "In2.Cu")
		(net "SMB_LM75_2_3V3AUX_SCL")
	)
	(segment
		(start 13.92428 -192.024)
		(end 12.4206 -190.52032)
		(width 0.127)
		(layer "In2.Cu")
		(net "SMB_LM75_2_3V3AUX_SCL")
	)
	(segment
		(start 51.59248 -412.694628)
		(end 51.15814 -412.260288)
		(width 0.127)
		(layer "In2.Cu")
		(net "SMB_LM75_2_3V3AUX_SCL")
	)
	(segment
		(start 46.330362 -409.23591)
		(end 46.330362 -399.45056)
		(width 0.127)
		(layer "In2.Cu")
		(net "SMB_LM75_2_3V3AUX_SCL")
	)
	(segment
		(start 13.61694 -175.052228)
		(end 16.6878 -171.981368)
		(width 0.127)
		(layer "In2.Cu")
		(net "SMB_LM75_2_3V3AUX_SCL")
	)
	(segment
		(start 13.97508 -326.406002)
		(end 13.97508 -251.450348)
		(width 0.127)
		(layer "In2.Cu")
		(net "SMB_LM75_2_3V3AUX_SCL")
	)
	(segment
		(start 12.4206 -190.52032)
		(end 12.4206 -185.3184)
		(width 0.127)
		(layer "In2.Cu")
		(net "SMB_LM75_2_3V3AUX_SCL")
	)
	(segment
		(start 42.67962 -395.799818)
		(end 37.84854 -395.799818)
		(width 0.127)
		(layer "In2.Cu")
		(net "SMB_LM75_2_3V3AUX_SCL")
	)
	(segment
		(start 18.90522 -164.055044)
		(end 18.90522 -146.656552)
		(width 0.127)
		(layer "In2.Cu")
		(net "SMB_LM75_2_3V3AUX_SCL")
	)
	(segment
		(start 16.6878 -166.272464)
		(end 18.90522 -164.055044)
		(width 0.127)
		(layer "In2.Cu")
		(net "SMB_LM75_2_3V3AUX_SCL")
	)
	(segment
		(start 13.61694 -184.12206)
		(end 13.61694 -175.052228)
		(width 0.127)
		(layer "In2.Cu")
		(net "SMB_LM75_2_3V3AUX_SCL")
	)
	(segment
		(start 28.75788 -329.656948)
		(end 17.226026 -329.656948)
		(width 0.127)
		(layer "In2.Cu")
		(net "SMB_LM75_2_3V3AUX_SCL")
	)
	(segment
		(start 49.35474 -412.260288)
		(end 46.330362 -409.23591)
		(width 0.127)
		(layer "In2.Cu")
		(net "SMB_LM75_2_3V3AUX_SCL")
	)
	(segment
		(start 17.70761 -116.912898)
		(end 38.158928 -116.912898)
		(width 0.127)
		(layer "In2.Cu")
		(net "SMB_LM75_2_3V3AUX_SCL")
	)
	(segment
		(start 13.00734 -140.758672)
		(end 13.00734 -121.613168)
		(width 0.127)
		(layer "In2.Cu")
		(net "SMB_LM75_2_3V3AUX_SCL")
	)
	(segment
		(start 35.338512 -393.28979)
		(end 35.338512 -374.33758)
		(width 0.127)
		(layer "In2.Cu")
		(net "SMB_LM75_2_3V3AUX_SCL")
	)
	(segment
		(start 51.15814 -412.260288)
		(end 49.35474 -412.260288)
		(width 0.127)
		(layer "In2.Cu")
		(net "SMB_LM75_2_3V3AUX_SCL")
	)
	(segment
		(start 35.338512 -374.33758)
		(end 29.57068 -368.569748)
		(width 0.127)
		(layer "In2.Cu")
		(net "SMB_LM75_2_3V3AUX_SCL")
	)
	(segment
		(start 45.914056 -105.631488)
		(end 48.573182 -105.631488)
		(width 0.127)
		(layer "In2.Cu")
		(net "SMB_LM75_2_3V3AUX_SCL")
	)
	(segment
		(start 12.4206 -185.3184)
		(end 13.61694 -184.12206)
		(width 0.127)
		(layer "In2.Cu")
		(net "SMB_LM75_2_3V3AUX_SCL")
	)
	(segment
		(start 29.57068 -330.469748)
		(end 28.75788 -329.656948)
		(width 0.127)
		(layer "In2.Cu")
		(net "SMB_LM75_2_3V3AUX_SCL")
	)
	(segment
		(start 38.158928 -116.912898)
		(end 44.06138 -111.010446)
		(width 0.127)
		(layer "In2.Cu")
		(net "SMB_LM75_2_3V3AUX_SCL")
	)
	(segment
		(start 29.57068 -368.569748)
		(end 29.57068 -330.469748)
		(width 0.127)
		(layer "In2.Cu")
		(net "SMB_LM75_2_3V3AUX_SCL")
	)
	(segment
		(start 13.92428 -251.399548)
		(end 13.92428 -192.024)
		(width 0.127)
		(layer "In2.Cu")
		(net "SMB_LM75_2_3V3AUX_SCL")
	)
	(segment
		(start 37.84854 -395.799818)
		(end 35.338512 -393.28979)
		(width 0.127)
		(layer "In2.Cu")
		(net "SMB_LM75_2_3V3AUX_SCL")
	)
	(segment
		(start 44.06138 -107.484164)
		(end 45.914056 -105.631488)
		(width 0.127)
		(layer "In2.Cu")
		(net "SMB_LM75_2_3V3AUX_SCL")
	)
	(segment
		(start 18.90522 -146.656552)
		(end 13.00734 -140.758672)
		(width 0.127)
		(layer "In2.Cu")
		(net "SMB_LM75_2_3V3AUX_SCL")
	)
	(segment
		(start 16.6878 -171.981368)
		(end 16.6878 -166.272464)
		(width 0.127)
		(layer "In2.Cu")
		(net "SMB_LM75_2_3V3AUX_SCL")
	)
	(segment
		(start 287.019238 -17.745456)
		(end 287.51149 -17.253204)
		(width 0.12954)
		(layer "F.Cu")
		(net "SMB_LM75_1_3V3AUX_SDA_R1")
	)
	(segment
		(start 287.51149 -17.253204)
		(end 289.182048 -17.253204)
		(width 0.12954)
		(layer "F.Cu")
		(net "SMB_LM75_1_3V3AUX_SDA_R1")
	)
	(segment
		(start 285.668212 -16.39443)
		(end 287.019238 -17.745456)
		(width 0.12954)
		(layer "F.Cu")
		(net "SMB_LM75_1_3V3AUX_SDA_R1")
	)
	(via
		(at 287.019238 -17.745456)
		(size 0.508)
		(drill 0.254)
		(layers "F.Cu" "B.Cu")
		(net "SMB_LM75_1_3V3AUX_SDA_R1")
	)
	(segment
		(start 225.43008 -77.701648)
		(end 242.121944 -61.009784)
		(width 0.12954)
		(layer "F.Cu")
		(net "SMB_LM75_1_3V3AUX_SDA")
	)
	(segment
		(start 257.973576 -61.009784)
		(end 260.5405 -58.44286)
		(width 0.12954)
		(layer "F.Cu")
		(net "SMB_LM75_1_3V3AUX_SDA")
	)
	(segment
		(start 272.027396 -43.80865)
		(end 276.31009 -39.525956)
		(width 0.12954)
		(layer "F.Cu")
		(net "SMB_LM75_1_3V3AUX_SDA")
	)
	(segment
		(start 53.466746 -109.53877)
		(end 51.993546 -109.53877)
		(width 0.12954)
		(layer "F.Cu")
		(net "SMB_LM75_1_3V3AUX_SDA")
	)
	(segment
		(start 260.5405 -58.44286)
		(end 260.5405 -50.014632)
		(width 0.12954)
		(layer "F.Cu")
		(net "SMB_LM75_1_3V3AUX_SDA")
	)
	(segment
		(start 51.993546 -109.53877)
		(end 51.993546 -108.900468)
		(width 0.12954)
		(layer "F.Cu")
		(net "SMB_LM75_1_3V3AUX_SDA")
	)
	(segment
		(start 284.63748 -16.625062)
		(end 284.868112 -16.39443)
		(width 0.12954)
		(layer "F.Cu")
		(net "SMB_LM75_1_3V3AUX_SDA")
	)
	(segment
		(start 260.5405 -50.014632)
		(end 261.501382 -47.69485)
		(width 0.12954)
		(layer "F.Cu")
		(net "SMB_LM75_1_3V3AUX_SDA")
	)
	(segment
		(start 53.842666 -109.91469)
		(end 53.466746 -109.53877)
		(width 0.12954)
		(layer "F.Cu")
		(net "SMB_LM75_1_3V3AUX_SDA")
	)
	(segment
		(start 225.43008 -83.200748)
		(end 225.43008 -77.701648)
		(width 0.12954)
		(layer "F.Cu")
		(net "SMB_LM75_1_3V3AUX_SDA")
	)
	(segment
		(start 261.501382 -47.69485)
		(end 265.387582 -43.80865)
		(width 0.12954)
		(layer "F.Cu")
		(net "SMB_LM75_1_3V3AUX_SDA")
	)
	(segment
		(start 284.63748 -21.437854)
		(end 284.63748 -16.625062)
		(width 0.12954)
		(layer "F.Cu")
		(net "SMB_LM75_1_3V3AUX_SDA")
	)
	(segment
		(start 276.31009 -29.765244)
		(end 284.63748 -21.437854)
		(width 0.12954)
		(layer "F.Cu")
		(net "SMB_LM75_1_3V3AUX_SDA")
	)
	(segment
		(start 265.387582 -43.80865)
		(end 272.027396 -43.80865)
		(width 0.12954)
		(layer "F.Cu")
		(net "SMB_LM75_1_3V3AUX_SDA")
	)
	(segment
		(start 276.31009 -39.525956)
		(end 276.31009 -29.765244)
		(width 0.12954)
		(layer "F.Cu")
		(net "SMB_LM75_1_3V3AUX_SDA")
	)
	(segment
		(start 242.121944 -61.009784)
		(end 257.973576 -61.009784)
		(width 0.12954)
		(layer "F.Cu")
		(net "SMB_LM75_1_3V3AUX_SDA")
	)
	(via
		(at 51.993546 -108.900468)
		(size 0.508)
		(drill 0.254)
		(layers "F.Cu" "B.Cu")
		(net "SMB_LM75_1_3V3AUX_SDA")
	)
	(via
		(at 265.15568 -112.766348)
		(size 0.508)
		(drill 0.254)
		(layers "F.Cu" "B.Cu")
		(net "SMB_LM75_1_3V3AUX_SDA")
	)
	(via
		(at 225.43008 -83.200748)
		(size 0.508)
		(drill 0.254)
		(layers "F.Cu" "B.Cu")
		(net "SMB_LM75_1_3V3AUX_SDA")
	)
	(segment
		(start 258.47548 -92.344748)
		(end 254.46228 -92.344748)
		(width 0.127)
		(layer "In2.Cu")
		(net "SMB_LM75_1_3V3AUX_SDA")
	)
	(segment
		(start 265.15568 -112.766348)
		(end 265.15568 -109.858048)
		(width 0.127)
		(layer "In2.Cu")
		(net "SMB_LM75_1_3V3AUX_SDA")
	)
	(segment
		(start 265.15568 -109.858048)
		(end 265.02868 -109.731048)
		(width 0.127)
		(layer "In2.Cu")
		(net "SMB_LM75_1_3V3AUX_SDA")
	)
	(segment
		(start 264.72388 -93.436948)
		(end 259.56768 -93.436948)
		(width 0.127)
		(layer "In2.Cu")
		(net "SMB_LM75_1_3V3AUX_SDA")
	)
	(segment
		(start 252.72873 -90.611198)
		(end 228.19233 -90.611198)
		(width 0.127)
		(layer "In2.Cu")
		(net "SMB_LM75_1_3V3AUX_SDA")
	)
	(segment
		(start 265.02868 -106.973878)
		(end 265.91768 -106.084878)
		(width 0.127)
		(layer "In2.Cu")
		(net "SMB_LM75_1_3V3AUX_SDA")
	)
	(segment
		(start 265.02868 -109.731048)
		(end 265.02868 -106.973878)
		(width 0.127)
		(layer "In2.Cu")
		(net "SMB_LM75_1_3V3AUX_SDA")
	)
	(segment
		(start 228.19233 -90.611198)
		(end 225.43008 -87.848948)
		(width 0.127)
		(layer "In2.Cu")
		(net "SMB_LM75_1_3V3AUX_SDA")
	)
	(segment
		(start 265.91768 -106.084878)
		(end 265.91768 -94.630748)
		(width 0.127)
		(layer "In2.Cu")
		(net "SMB_LM75_1_3V3AUX_SDA")
	)
	(segment
		(start 225.43008 -87.848948)
		(end 225.43008 -83.200748)
		(width 0.127)
		(layer "In2.Cu")
		(net "SMB_LM75_1_3V3AUX_SDA")
	)
	(segment
		(start 259.56768 -93.436948)
		(end 258.47548 -92.344748)
		(width 0.127)
		(layer "In2.Cu")
		(net "SMB_LM75_1_3V3AUX_SDA")
	)
	(segment
		(start 254.46228 -92.344748)
		(end 252.72873 -90.611198)
		(width 0.127)
		(layer "In2.Cu")
		(net "SMB_LM75_1_3V3AUX_SDA")
	)
	(segment
		(start 265.91768 -94.630748)
		(end 264.72388 -93.436948)
		(width 0.127)
		(layer "In2.Cu")
		(net "SMB_LM75_1_3V3AUX_SDA")
	)
	(segment
		(start 265.15568 -113.431066)
		(end 265.15568 -112.766348)
		(width 0.127)
		(layer "In6.Cu")
		(net "SMB_LM75_1_3V3AUX_SDA")
	)
	(segment
		(start 208.534 -112.268)
		(end 222.504 -112.268)
		(width 0.127)
		(layer "In6.Cu")
		(net "SMB_LM75_1_3V3AUX_SDA")
	)
	(segment
		(start 193.88328 -100.175568)
		(end 194.20332 -100.495608)
		(width 0.127)
		(layer "In6.Cu")
		(net "SMB_LM75_1_3V3AUX_SDA")
	)
	(segment
		(start 142.42542 -90.635328)
		(end 147.94992 -96.159828)
		(width 0.127)
		(layer "In6.Cu")
		(net "SMB_LM75_1_3V3AUX_SDA")
	)
	(segment
		(start 66.26352 -99.565968)
		(end 78.40472 -87.424768)
		(width 0.127)
		(layer "In6.Cu")
		(net "SMB_LM75_1_3V3AUX_SDA")
	)
	(segment
		(start 54.52364 -106.619548)
		(end 61.57722 -99.565968)
		(width 0.127)
		(layer "In6.Cu")
		(net "SMB_LM75_1_3V3AUX_SDA")
	)
	(segment
		(start 171.958 -97.742248)
		(end 175.56861 -97.742248)
		(width 0.127)
		(layer "In6.Cu")
		(net "SMB_LM75_1_3V3AUX_SDA")
	)
	(segment
		(start 223.36252 -111.40948)
		(end 236.831886 -111.40948)
		(width 0.127)
		(layer "In6.Cu")
		(net "SMB_LM75_1_3V3AUX_SDA")
	)
	(segment
		(start 61.57722 -99.565968)
		(end 66.26352 -99.565968)
		(width 0.127)
		(layer "In6.Cu")
		(net "SMB_LM75_1_3V3AUX_SDA")
	)
	(segment
		(start 205.133448 -108.867448)
		(end 208.534 -112.268)
		(width 0.127)
		(layer "In6.Cu")
		(net "SMB_LM75_1_3V3AUX_SDA")
	)
	(segment
		(start 197.85838 -100.866448)
		(end 197.85838 -101.374448)
		(width 0.127)
		(layer "In6.Cu")
		(net "SMB_LM75_1_3V3AUX_SDA")
	)
	(segment
		(start 195.70954 -100.040948)
		(end 197.03288 -100.040948)
		(width 0.127)
		(layer "In6.Cu")
		(net "SMB_LM75_1_3V3AUX_SDA")
	)
	(segment
		(start 104.79786 -87.424768)
		(end 108.00842 -90.635328)
		(width 0.127)
		(layer "In6.Cu")
		(net "SMB_LM75_1_3V3AUX_SDA")
	)
	(segment
		(start 199.01408 -103.933244)
		(end 199.724264 -104.643428)
		(width 0.127)
		(layer "In6.Cu")
		(net "SMB_LM75_1_3V3AUX_SDA")
	)
	(segment
		(start 175.94961 -98.123248)
		(end 178.641248 -98.123248)
		(width 0.127)
		(layer "In6.Cu")
		(net "SMB_LM75_1_3V3AUX_SDA")
	)
	(segment
		(start 108.00842 -90.635328)
		(end 142.42542 -90.635328)
		(width 0.127)
		(layer "In6.Cu")
		(net "SMB_LM75_1_3V3AUX_SDA")
	)
	(segment
		(start 51.993546 -108.900468)
		(end 51.993546 -108.400596)
		(width 0.127)
		(layer "In6.Cu")
		(net "SMB_LM75_1_3V3AUX_SDA")
	)
	(segment
		(start 195.25488 -100.495608)
		(end 195.70954 -100.040948)
		(width 0.127)
		(layer "In6.Cu")
		(net "SMB_LM75_1_3V3AUX_SDA")
	)
	(segment
		(start 182.099204 -100.175568)
		(end 193.88328 -100.175568)
		(width 0.127)
		(layer "In6.Cu")
		(net "SMB_LM75_1_3V3AUX_SDA")
	)
	(segment
		(start 263.254998 -115.331748)
		(end 265.15568 -113.431066)
		(width 0.127)
		(layer "In6.Cu")
		(net "SMB_LM75_1_3V3AUX_SDA")
	)
	(segment
		(start 51.993546 -108.400596)
		(end 53.774594 -106.619548)
		(width 0.127)
		(layer "In6.Cu")
		(net "SMB_LM75_1_3V3AUX_SDA")
	)
	(segment
		(start 175.56861 -97.742248)
		(end 175.94961 -98.123248)
		(width 0.127)
		(layer "In6.Cu")
		(net "SMB_LM75_1_3V3AUX_SDA")
	)
	(segment
		(start 199.01408 -102.530148)
		(end 199.01408 -103.933244)
		(width 0.127)
		(layer "In6.Cu")
		(net "SMB_LM75_1_3V3AUX_SDA")
	)
	(segment
		(start 222.504 -112.268)
		(end 223.36252 -111.40948)
		(width 0.127)
		(layer "In6.Cu")
		(net "SMB_LM75_1_3V3AUX_SDA")
	)
	(segment
		(start 159.1691 -96.159828)
		(end 160.24352 -95.085408)
		(width 0.127)
		(layer "In6.Cu")
		(net "SMB_LM75_1_3V3AUX_SDA")
	)
	(segment
		(start 169.30116 -95.085408)
		(end 171.958 -97.742248)
		(width 0.127)
		(layer "In6.Cu")
		(net "SMB_LM75_1_3V3AUX_SDA")
	)
	(segment
		(start 147.94992 -96.159828)
		(end 159.1691 -96.159828)
		(width 0.127)
		(layer "In6.Cu")
		(net "SMB_LM75_1_3V3AUX_SDA")
	)
	(segment
		(start 200.5838 -104.643428)
		(end 204.80782 -108.867448)
		(width 0.127)
		(layer "In6.Cu")
		(net "SMB_LM75_1_3V3AUX_SDA")
	)
	(segment
		(start 179.699666 -99.181666)
		(end 182.099204 -100.175568)
		(width 0.127)
		(layer "In6.Cu")
		(net "SMB_LM75_1_3V3AUX_SDA")
	)
	(segment
		(start 78.40472 -87.424768)
		(end 104.79786 -87.424768)
		(width 0.127)
		(layer "In6.Cu")
		(net "SMB_LM75_1_3V3AUX_SDA")
	)
	(segment
		(start 160.24352 -95.085408)
		(end 169.30116 -95.085408)
		(width 0.127)
		(layer "In6.Cu")
		(net "SMB_LM75_1_3V3AUX_SDA")
	)
	(segment
		(start 197.85838 -101.374448)
		(end 199.01408 -102.530148)
		(width 0.127)
		(layer "In6.Cu")
		(net "SMB_LM75_1_3V3AUX_SDA")
	)
	(segment
		(start 243.249704 -115.331748)
		(end 263.254998 -115.331748)
		(width 0.127)
		(layer "In6.Cu")
		(net "SMB_LM75_1_3V3AUX_SDA")
	)
	(segment
		(start 178.641248 -98.123248)
		(end 179.699666 -99.181666)
		(width 0.127)
		(layer "In6.Cu")
		(net "SMB_LM75_1_3V3AUX_SDA")
	)
	(segment
		(start 236.831886 -111.40948)
		(end 238.077756 -112.65535)
		(width 0.127)
		(layer "In6.Cu")
		(net "SMB_LM75_1_3V3AUX_SDA")
	)
	(segment
		(start 194.20332 -100.495608)
		(end 195.25488 -100.495608)
		(width 0.127)
		(layer "In6.Cu")
		(net "SMB_LM75_1_3V3AUX_SDA")
	)
	(segment
		(start 204.80782 -108.867448)
		(end 205.133448 -108.867448)
		(width 0.127)
		(layer "In6.Cu")
		(net "SMB_LM75_1_3V3AUX_SDA")
	)
	(segment
		(start 199.724264 -104.643428)
		(end 200.5838 -104.643428)
		(width 0.127)
		(layer "In6.Cu")
		(net "SMB_LM75_1_3V3AUX_SDA")
	)
	(segment
		(start 53.774594 -106.619548)
		(end 54.52364 -106.619548)
		(width 0.127)
		(layer "In6.Cu")
		(net "SMB_LM75_1_3V3AUX_SDA")
	)
	(segment
		(start 240.573306 -112.65535)
		(end 243.249704 -115.331748)
		(width 0.127)
		(layer "In6.Cu")
		(net "SMB_LM75_1_3V3AUX_SDA")
	)
	(segment
		(start 197.03288 -100.040948)
		(end 197.85838 -100.866448)
		(width 0.127)
		(layer "In6.Cu")
		(net "SMB_LM75_1_3V3AUX_SDA")
	)
	(segment
		(start 238.077756 -112.65535)
		(end 240.573306 -112.65535)
		(width 0.127)
		(layer "In6.Cu")
		(net "SMB_LM75_1_3V3AUX_SDA")
	)
	(segment
		(start 286.765238 -16.475456)
		(end 287.666938 -16.475456)
		(width 0.12954)
		(layer "F.Cu")
		(net "SMB_LM75_1_3V3AUX_SCL_R1")
	)
	(segment
		(start 288.15919 -15.983204)
		(end 289.182048 -15.983204)
		(width 0.12954)
		(layer "F.Cu")
		(net "SMB_LM75_1_3V3AUX_SCL_R1")
	)
	(segment
		(start 285.668212 -15.37843)
		(end 286.765238 -16.475456)
		(width 0.12954)
		(layer "F.Cu")
		(net "SMB_LM75_1_3V3AUX_SCL_R1")
	)
	(segment
		(start 287.666938 -16.475456)
		(end 288.15919 -15.983204)
		(width 0.12954)
		(layer "F.Cu")
		(net "SMB_LM75_1_3V3AUX_SCL_R1")
	)
	(via
		(at 287.666938 -16.475456)
		(size 0.508)
		(drill 0.254)
		(layers "F.Cu" "B.Cu")
		(net "SMB_LM75_1_3V3AUX_SCL_R1")
	)
	(segment
		(start 284.149546 -21.23567)
		(end 284.149546 -16.096996)
		(width 0.12954)
		(layer "F.Cu")
		(net "SMB_LM75_1_3V3AUX_SCL")
	)
	(segment
		(start 265.231118 -43.320716)
		(end 271.825212 -43.320716)
		(width 0.12954)
		(layer "F.Cu")
		(net "SMB_LM75_1_3V3AUX_SCL")
	)
	(segment
		(start 284.149546 -16.096996)
		(end 284.868112 -15.37843)
		(width 0.12954)
		(layer "F.Cu")
		(net "SMB_LM75_1_3V3AUX_SCL")
	)
	(segment
		(start 241.91976 -60.52185)
		(end 257.771392 -60.52185)
		(width 0.12954)
		(layer "F.Cu")
		(net "SMB_LM75_1_3V3AUX_SCL")
	)
	(segment
		(start 260.052566 -58.240676)
		(end 260.052566 -50.05324)
		(width 0.12954)
		(layer "F.Cu")
		(net "SMB_LM75_1_3V3AUX_SCL")
	)
	(segment
		(start 51.993546 -107.503468)
		(end 51.993546 -108.14177)
		(width 0.12954)
		(layer "F.Cu")
		(net "SMB_LM75_1_3V3AUX_SCL")
	)
	(segment
		(start 224.79508 -82.729324)
		(end 224.942146 -82.582258)
		(width 0.12954)
		(layer "F.Cu")
		(net "SMB_LM75_1_3V3AUX_SCL")
	)
	(segment
		(start 224.942146 -77.499464)
		(end 241.91976 -60.52185)
		(width 0.12954)
		(layer "F.Cu")
		(net "SMB_LM75_1_3V3AUX_SCL")
	)
	(segment
		(start 257.771392 -60.52185)
		(end 260.052566 -58.240676)
		(width 0.12954)
		(layer "F.Cu")
		(net "SMB_LM75_1_3V3AUX_SCL")
	)
	(segment
		(start 275.822156 -39.323772)
		(end 275.822156 -29.56306)
		(width 0.12954)
		(layer "F.Cu")
		(net "SMB_LM75_1_3V3AUX_SCL")
	)
	(segment
		(start 224.942146 -82.582258)
		(end 224.942146 -77.499464)
		(width 0.12954)
		(layer "F.Cu")
		(net "SMB_LM75_1_3V3AUX_SCL")
	)
	(segment
		(start 224.79508 -83.200748)
		(end 224.79508 -82.729324)
		(width 0.12954)
		(layer "F.Cu")
		(net "SMB_LM75_1_3V3AUX_SCL")
	)
	(segment
		(start 275.822156 -29.56306)
		(end 284.149546 -21.23567)
		(width 0.12954)
		(layer "F.Cu")
		(net "SMB_LM75_1_3V3AUX_SCL")
	)
	(segment
		(start 53.842666 -108.89869)
		(end 52.750466 -108.89869)
		(width 0.12954)
		(layer "F.Cu")
		(net "SMB_LM75_1_3V3AUX_SCL")
	)
	(segment
		(start 261.15137 -47.400464)
		(end 265.231118 -43.320716)
		(width 0.12954)
		(layer "F.Cu")
		(net "SMB_LM75_1_3V3AUX_SCL")
	)
	(segment
		(start 260.052566 -50.05324)
		(end 261.15137 -47.400464)
		(width 0.12954)
		(layer "F.Cu")
		(net "SMB_LM75_1_3V3AUX_SCL")
	)
	(segment
		(start 52.750466 -108.89869)
		(end 51.993546 -108.14177)
		(width 0.12954)
		(layer "F.Cu")
		(net "SMB_LM75_1_3V3AUX_SCL")
	)
	(segment
		(start 271.825212 -43.320716)
		(end 275.822156 -39.323772)
		(width 0.12954)
		(layer "F.Cu")
		(net "SMB_LM75_1_3V3AUX_SCL")
	)
	(via
		(at 51.993546 -107.503468)
		(size 0.508)
		(drill 0.254)
		(layers "F.Cu" "B.Cu")
		(net "SMB_LM75_1_3V3AUX_SCL")
	)
	(via
		(at 264.52068 -112.766348)
		(size 0.508)
		(drill 0.254)
		(layers "F.Cu" "B.Cu")
		(net "SMB_LM75_1_3V3AUX_SCL")
	)
	(via
		(at 224.79508 -83.200748)
		(size 0.508)
		(drill 0.254)
		(layers "F.Cu" "B.Cu")
		(net "SMB_LM75_1_3V3AUX_SCL")
	)
	(segment
		(start 259.94868 -94.300548)
		(end 263.27608 -94.300548)
		(width 0.127)
		(layer "In2.Cu")
		(net "SMB_LM75_1_3V3AUX_SCL")
	)
	(segment
		(start 252.339348 -91.11996)
		(end 254.199136 -92.979748)
		(width 0.127)
		(layer "In2.Cu")
		(net "SMB_LM75_1_3V3AUX_SCL")
	)
	(segment
		(start 227.802948 -91.11996)
		(end 252.339348 -91.11996)
		(width 0.127)
		(layer "In2.Cu")
		(net "SMB_LM75_1_3V3AUX_SCL")
	)
	(segment
		(start 265.46048 -96.484948)
		(end 265.46048 -105.679748)
		(width 0.127)
		(layer "In2.Cu")
		(net "SMB_LM75_1_3V3AUX_SCL")
	)
	(segment
		(start 259.59308 -94.656148)
		(end 259.94868 -94.300548)
		(width 0.127)
		(layer "In2.Cu")
		(net "SMB_LM75_1_3V3AUX_SCL")
	)
	(segment
		(start 254.199136 -92.979748)
		(end 256.7432 -92.979748)
		(width 0.127)
		(layer "In2.Cu")
		(net "SMB_LM75_1_3V3AUX_SCL")
	)
	(segment
		(start 256.7432 -92.979748)
		(end 258.4196 -94.656148)
		(width 0.127)
		(layer "In2.Cu")
		(net "SMB_LM75_1_3V3AUX_SCL")
	)
	(segment
		(start 224.79508 -88.112092)
		(end 227.802948 -91.11996)
		(width 0.127)
		(layer "In2.Cu")
		(net "SMB_LM75_1_3V3AUX_SCL")
	)
	(segment
		(start 265.46048 -105.679748)
		(end 264.52068 -106.619548)
		(width 0.127)
		(layer "In2.Cu")
		(net "SMB_LM75_1_3V3AUX_SCL")
	)
	(segment
		(start 263.27608 -94.300548)
		(end 265.46048 -96.484948)
		(width 0.127)
		(layer "In2.Cu")
		(net "SMB_LM75_1_3V3AUX_SCL")
	)
	(segment
		(start 258.4196 -94.656148)
		(end 259.59308 -94.656148)
		(width 0.127)
		(layer "In2.Cu")
		(net "SMB_LM75_1_3V3AUX_SCL")
	)
	(segment
		(start 264.52068 -106.619548)
		(end 264.52068 -112.766348)
		(width 0.127)
		(layer "In2.Cu")
		(net "SMB_LM75_1_3V3AUX_SCL")
	)
	(segment
		(start 224.79508 -83.200748)
		(end 224.79508 -88.112092)
		(width 0.127)
		(layer "In2.Cu")
		(net "SMB_LM75_1_3V3AUX_SCL")
	)
	(segment
		(start 175.74768 -97.310448)
		(end 172.419264 -97.310448)
		(width 0.127)
		(layer "In6.Cu")
		(net "SMB_LM75_1_3V3AUX_SCL")
	)
	(segment
		(start 204.9526 -108.387388)
		(end 200.76922 -104.204008)
		(width 0.127)
		(layer "In6.Cu")
		(net "SMB_LM75_1_3V3AUX_SCL")
	)
	(segment
		(start 108.13542 -89.987628)
		(end 105.08234 -86.934548)
		(width 0.127)
		(layer "In6.Cu")
		(net "SMB_LM75_1_3V3AUX_SCL")
	)
	(segment
		(start 54.306724 -104.992424)
		(end 54.306724 -105.172256)
		(width 0.127)
		(layer "In6.Cu")
		(net "SMB_LM75_1_3V3AUX_SCL")
	)
	(segment
		(start 61.418724 -98.974148)
		(end 55.302658 -105.090214)
		(width 0.127)
		(layer "In6.Cu")
		(net "SMB_LM75_1_3V3AUX_SCL")
	)
	(segment
		(start 263.075928 -114.899948)
		(end 244.321076 -114.899948)
		(width 0.127)
		(layer "In6.Cu")
		(net "SMB_LM75_1_3V3AUX_SCL")
	)
	(segment
		(start 54.306724 -105.172256)
		(end 54.673754 -105.539286)
		(width 0.127)
		(layer "In6.Cu")
		(net "SMB_LM75_1_3V3AUX_SCL")
	)
	(segment
		(start 78.096364 -86.934548)
		(end 66.056764 -98.974148)
		(width 0.127)
		(layer "In6.Cu")
		(net "SMB_LM75_1_3V3AUX_SCL")
	)
	(segment
		(start 105.08234 -86.934548)
		(end 78.096364 -86.934548)
		(width 0.127)
		(layer "In6.Cu")
		(net "SMB_LM75_1_3V3AUX_SCL")
	)
	(segment
		(start 54.673754 -105.539286)
		(end 54.673754 -105.719118)
		(width 0.127)
		(layer "In6.Cu")
		(net "SMB_LM75_1_3V3AUX_SCL")
	)
	(segment
		(start 237.238286 -110.935516)
		(end 223.12503 -110.935516)
		(width 0.127)
		(layer "In6.Cu")
		(net "SMB_LM75_1_3V3AUX_SCL")
	)
	(segment
		(start 244.321076 -114.899948)
		(end 241.582956 -112.161828)
		(width 0.127)
		(layer "In6.Cu")
		(net "SMB_LM75_1_3V3AUX_SCL")
	)
	(segment
		(start 200.76922 -104.204008)
		(end 199.895968 -104.204008)
		(width 0.127)
		(layer "In6.Cu")
		(net "SMB_LM75_1_3V3AUX_SCL")
	)
	(segment
		(start 182.158894 -99.715828)
		(end 179.956714 -98.803714)
		(width 0.127)
		(layer "In6.Cu")
		(net "SMB_LM75_1_3V3AUX_SCL")
	)
	(segment
		(start 178.839368 -97.686368)
		(end 176.1236 -97.686368)
		(width 0.127)
		(layer "In6.Cu")
		(net "SMB_LM75_1_3V3AUX_SCL")
	)
	(segment
		(start 193.929 -99.715828)
		(end 182.158894 -99.715828)
		(width 0.127)
		(layer "In6.Cu")
		(net "SMB_LM75_1_3V3AUX_SCL")
	)
	(segment
		(start 264.52068 -112.766348)
		(end 264.52068 -113.455196)
		(width 0.127)
		(layer "In6.Cu")
		(net "SMB_LM75_1_3V3AUX_SCL")
	)
	(segment
		(start 176.1236 -97.686368)
		(end 175.74768 -97.310448)
		(width 0.127)
		(layer "In6.Cu")
		(net "SMB_LM75_1_3V3AUX_SCL")
	)
	(segment
		(start 199.44588 -101.056948)
		(end 198.73468 -100.345748)
		(width 0.127)
		(layer "In6.Cu")
		(net "SMB_LM75_1_3V3AUX_SCL")
	)
	(segment
		(start 55.302658 -105.090214)
		(end 55.122826 -105.090214)
		(width 0.127)
		(layer "In6.Cu")
		(net "SMB_LM75_1_3V3AUX_SCL")
	)
	(segment
		(start 223.12503 -110.935516)
		(end 222.224346 -111.8362)
		(width 0.127)
		(layer "In6.Cu")
		(net "SMB_LM75_1_3V3AUX_SCL")
	)
	(segment
		(start 208.7626 -111.8362)
		(end 205.313788 -108.387388)
		(width 0.127)
		(layer "In6.Cu")
		(net "SMB_LM75_1_3V3AUX_SCL")
	)
	(segment
		(start 169.762424 -94.653608)
		(end 159.54502 -94.653608)
		(width 0.127)
		(layer "In6.Cu")
		(net "SMB_LM75_1_3V3AUX_SCL")
	)
	(segment
		(start 238.464598 -112.161828)
		(end 237.238286 -110.935516)
		(width 0.127)
		(layer "In6.Cu")
		(net "SMB_LM75_1_3V3AUX_SCL")
	)
	(segment
		(start 222.224346 -111.8362)
		(end 208.7626 -111.8362)
		(width 0.127)
		(layer "In6.Cu")
		(net "SMB_LM75_1_3V3AUX_SCL")
	)
	(segment
		(start 53.410866 -106.086148)
		(end 51.993546 -107.503468)
		(width 0.127)
		(layer "In6.Cu")
		(net "SMB_LM75_1_3V3AUX_SCL")
	)
	(segment
		(start 205.313788 -108.387388)
		(end 204.9526 -108.387388)
		(width 0.127)
		(layer "In6.Cu")
		(net "SMB_LM75_1_3V3AUX_SCL")
	)
	(segment
		(start 194.30746 -99.337368)
		(end 193.929 -99.715828)
		(width 0.127)
		(layer "In6.Cu")
		(net "SMB_LM75_1_3V3AUX_SCL")
	)
	(segment
		(start 199.44588 -103.75392)
		(end 199.44588 -101.056948)
		(width 0.127)
		(layer "In6.Cu")
		(net "SMB_LM75_1_3V3AUX_SCL")
	)
	(segment
		(start 148.206714 -95.718122)
		(end 142.47622 -89.987628)
		(width 0.127)
		(layer "In6.Cu")
		(net "SMB_LM75_1_3V3AUX_SCL")
	)
	(segment
		(start 54.575964 -104.723184)
		(end 54.306724 -104.992424)
		(width 0.127)
		(layer "In6.Cu")
		(net "SMB_LM75_1_3V3AUX_SCL")
	)
	(segment
		(start 159.54502 -94.653608)
		(end 158.480506 -95.718122)
		(width 0.127)
		(layer "In6.Cu")
		(net "SMB_LM75_1_3V3AUX_SCL")
	)
	(segment
		(start 264.52068 -113.455196)
		(end 263.075928 -114.899948)
		(width 0.127)
		(layer "In6.Cu")
		(net "SMB_LM75_1_3V3AUX_SCL")
	)
	(segment
		(start 198.09968 -100.345748)
		(end 197.0913 -99.337368)
		(width 0.127)
		(layer "In6.Cu")
		(net "SMB_LM75_1_3V3AUX_SCL")
	)
	(segment
		(start 54.673754 -105.719118)
		(end 54.306724 -106.086148)
		(width 0.127)
		(layer "In6.Cu")
		(net "SMB_LM75_1_3V3AUX_SCL")
	)
	(segment
		(start 179.956714 -98.803714)
		(end 178.839368 -97.686368)
		(width 0.127)
		(layer "In6.Cu")
		(net "SMB_LM75_1_3V3AUX_SCL")
	)
	(segment
		(start 241.582956 -112.161828)
		(end 238.464598 -112.161828)
		(width 0.127)
		(layer "In6.Cu")
		(net "SMB_LM75_1_3V3AUX_SCL")
	)
	(segment
		(start 198.73468 -100.345748)
		(end 198.09968 -100.345748)
		(width 0.127)
		(layer "In6.Cu")
		(net "SMB_LM75_1_3V3AUX_SCL")
	)
	(segment
		(start 197.0913 -99.337368)
		(end 194.30746 -99.337368)
		(width 0.127)
		(layer "In6.Cu")
		(net "SMB_LM75_1_3V3AUX_SCL")
	)
	(segment
		(start 142.47622 -89.987628)
		(end 108.13542 -89.987628)
		(width 0.127)
		(layer "In6.Cu")
		(net "SMB_LM75_1_3V3AUX_SCL")
	)
	(segment
		(start 55.122826 -105.090214)
		(end 54.755796 -104.723184)
		(width 0.127)
		(layer "In6.Cu")
		(net "SMB_LM75_1_3V3AUX_SCL")
	)
	(segment
		(start 54.755796 -104.723184)
		(end 54.575964 -104.723184)
		(width 0.127)
		(layer "In6.Cu")
		(net "SMB_LM75_1_3V3AUX_SCL")
	)
	(segment
		(start 199.895968 -104.204008)
		(end 199.44588 -103.75392)
		(width 0.127)
		(layer "In6.Cu")
		(net "SMB_LM75_1_3V3AUX_SCL")
	)
	(segment
		(start 66.056764 -98.974148)
		(end 61.418724 -98.974148)
		(width 0.127)
		(layer "In6.Cu")
		(net "SMB_LM75_1_3V3AUX_SCL")
	)
	(segment
		(start 172.419264 -97.310448)
		(end 169.762424 -94.653608)
		(width 0.127)
		(layer "In6.Cu")
		(net "SMB_LM75_1_3V3AUX_SCL")
	)
	(segment
		(start 54.306724 -106.086148)
		(end 53.410866 -106.086148)
		(width 0.127)
		(layer "In6.Cu")
		(net "SMB_LM75_1_3V3AUX_SCL")
	)
	(segment
		(start 158.480506 -95.718122)
		(end 148.206714 -95.718122)
		(width 0.127)
		(layer "In6.Cu")
		(net "SMB_LM75_1_3V3AUX_SCL")
	)
	(segment
		(start 367.46561 -426.709078)
		(end 366.831372 -426.07484)
		(width 0.12954)
		(layer "F.Cu")
		(net "SMB_LM75_0_3V3AUX_SDA_R1")
	)
	(segment
		(start 368.15268 -427.396148)
		(end 367.46561 -426.709078)
		(width 0.12954)
		(layer "F.Cu")
		(net "SMB_LM75_0_3V3AUX_SDA_R1")
	)
	(segment
		(start 372.810278 -425.882308)
		(end 372.810278 -426.213524)
		(width 0.12954)
		(layer "F.Cu")
		(net "SMB_LM75_0_3V3AUX_SDA_R1")
	)
	(segment
		(start 372.810278 -426.213524)
		(end 371.627654 -427.396148)
		(width 0.12954)
		(layer "F.Cu")
		(net "SMB_LM75_0_3V3AUX_SDA_R1")
	)
	(segment
		(start 371.627654 -427.396148)
		(end 368.15268 -427.396148)
		(width 0.12954)
		(layer "F.Cu")
		(net "SMB_LM75_0_3V3AUX_SDA_R1")
	)
	(segment
		(start 366.831372 -426.07484)
		(end 366.831372 -425.18457)
		(width 0.12954)
		(layer "F.Cu")
		(net "SMB_LM75_0_3V3AUX_SDA_R1")
	)
	(via
		(at 367.46561 -426.709078)
		(size 0.508)
		(drill 0.254)
		(layers "F.Cu" "B.Cu")
		(net "SMB_LM75_0_3V3AUX_SDA_R1")
	)
	(segment
		(start 52.379626 -111.94669)
		(end 51.993546 -112.33277)
		(width 0.12954)
		(layer "F.Cu")
		(net "SMB_LM75_0_3V3AUX_SDA")
	)
	(segment
		(start 294.13962 -411.2895)
		(end 293.645844 -411.783276)
		(width 0.12954)
		(layer "F.Cu")
		(net "SMB_LM75_0_3V3AUX_SDA")
	)
	(segment
		(start 299.2755 -408.7114)
		(end 298.56557 -408.7114)
		(width 0.12954)
		(layer "F.Cu")
		(net "SMB_LM75_0_3V3AUX_SDA")
	)
	(segment
		(start 53.842666 -111.94669)
		(end 52.379626 -111.94669)
		(width 0.12954)
		(layer "F.Cu")
		(net "SMB_LM75_0_3V3AUX_SDA")
	)
	(segment
		(start 366.031272 -425.18457)
		(end 365.30788 -425.18457)
		(width 0.12954)
		(layer "F.Cu")
		(net "SMB_LM75_0_3V3AUX_SDA")
	)
	(segment
		(start 293.645844 -411.783276)
		(end 293.645844 -412.07436)
		(width 0.12954)
		(layer "F.Cu")
		(net "SMB_LM75_0_3V3AUX_SDA")
	)
	(segment
		(start 51.310286 -111.64951)
		(end 51.993546 -112.33277)
		(width 0.12954)
		(layer "F.Cu")
		(net "SMB_LM75_0_3V3AUX_SDA")
	)
	(segment
		(start 49.38776 -111.64951)
		(end 51.310286 -111.64951)
		(width 0.12954)
		(layer "F.Cu")
		(net "SMB_LM75_0_3V3AUX_SDA")
	)
	(via
		(at 294.13962 -411.2895)
		(size 0.508)
		(drill 0.254)
		(layers "F.Cu" "B.Cu")
		(net "SMB_LM75_0_3V3AUX_SDA")
	)
	(via
		(at 365.30788 -425.18457)
		(size 0.508)
		(drill 0.254)
		(layers "F.Cu" "B.Cu")
		(net "SMB_LM75_0_3V3AUX_SDA")
	)
	(via
		(at 224.13214 -133.637528)
		(size 0.508)
		(drill 0.254)
		(layers "F.Cu" "B.Cu")
		(net "SMB_LM75_0_3V3AUX_SDA")
	)
	(via
		(at 49.38776 -111.64951)
		(size 0.508)
		(drill 0.254)
		(layers "F.Cu" "B.Cu")
		(net "SMB_LM75_0_3V3AUX_SDA")
	)
	(via
		(at 226.45624 -364.61954)
		(size 0.508)
		(drill 0.254)
		(layers "F.Cu" "B.Cu")
		(net "SMB_LM75_0_3V3AUX_SDA")
	)
	(via
		(at 299.2755 -408.7114)
		(size 0.508)
		(drill 0.254)
		(layers "F.Cu" "B.Cu")
		(net "SMB_LM75_0_3V3AUX_SDA")
	)
	(segment
		(start 247.927368 -160.079944)
		(end 248.19737 -160.349946)
		(width 0.127)
		(layer "In2.Cu")
		(net "SMB_LM75_0_3V3AUX_SDA")
	)
	(segment
		(start 247.298718 -159.451548)
		(end 247.298718 -159.630872)
		(width 0.127)
		(layer "In2.Cu")
		(net "SMB_LM75_0_3V3AUX_SDA")
	)
	(segment
		(start 247.748044 -160.079944)
		(end 247.927368 -160.079944)
		(width 0.127)
		(layer "In2.Cu")
		(net "SMB_LM75_0_3V3AUX_SDA")
	)
	(segment
		(start 296.19448 -408.7114)
		(end 294.13962 -410.76626)
		(width 0.127)
		(layer "In2.Cu")
		(net "SMB_LM75_0_3V3AUX_SDA")
	)
	(segment
		(start 250.7996 -239.961674)
		(end 250.7996 -322.443348)
		(width 0.127)
		(layer "In2.Cu")
		(net "SMB_LM75_0_3V3AUX_SDA")
	)
	(segment
		(start 247.298718 -159.630872)
		(end 247.05691 -159.87268)
		(width 0.127)
		(layer "In2.Cu")
		(net "SMB_LM75_0_3V3AUX_SDA")
	)
	(segment
		(start 247.955562 -160.770824)
		(end 247.955562 -160.950148)
		(width 0.127)
		(layer "In2.Cu")
		(net "SMB_LM75_0_3V3AUX_SDA")
	)
	(segment
		(start 247.506236 -160.321752)
		(end 247.748044 -160.079944)
		(width 0.127)
		(layer "In2.Cu")
		(net "SMB_LM75_0_3V3AUX_SDA")
	)
	(segment
		(start 248.404888 -161.219896)
		(end 248.646696 -160.978088)
		(width 0.127)
		(layer "In2.Cu")
		(net "SMB_LM75_0_3V3AUX_SDA")
	)
	(segment
		(start 249.809 -161.961068)
		(end 249.809 -238.971074)
		(width 0.127)
		(layer "In2.Cu")
		(net "SMB_LM75_0_3V3AUX_SDA")
	)
	(segment
		(start 226.85502 -346.387928)
		(end 226.85502 -364.22076)
		(width 0.127)
		(layer "In2.Cu")
		(net "SMB_LM75_0_3V3AUX_SDA")
	)
	(segment
		(start 224.13214 -133.637528)
		(end 224.13214 -136.283954)
		(width 0.127)
		(layer "In2.Cu")
		(net "SMB_LM75_0_3V3AUX_SDA")
	)
	(segment
		(start 248.22531 -161.219896)
		(end 248.404888 -161.219896)
		(width 0.127)
		(layer "In2.Cu")
		(net "SMB_LM75_0_3V3AUX_SDA")
	)
	(segment
		(start 247.326658 -160.321752)
		(end 247.506236 -160.321752)
		(width 0.127)
		(layer "In2.Cu")
		(net "SMB_LM75_0_3V3AUX_SDA")
	)
	(segment
		(start 247.955562 -160.950148)
		(end 248.22531 -161.219896)
		(width 0.127)
		(layer "In2.Cu")
		(net "SMB_LM75_0_3V3AUX_SDA")
	)
	(segment
		(start 248.19737 -160.529016)
		(end 247.955562 -160.770824)
		(width 0.127)
		(layer "In2.Cu")
		(net "SMB_LM75_0_3V3AUX_SDA")
	)
	(segment
		(start 250.7996 -322.443348)
		(end 226.85502 -346.387928)
		(width 0.127)
		(layer "In2.Cu")
		(net "SMB_LM75_0_3V3AUX_SDA")
	)
	(segment
		(start 247.05691 -159.87268)
		(end 247.05691 -160.052004)
		(width 0.127)
		(layer "In2.Cu")
		(net "SMB_LM75_0_3V3AUX_SDA")
	)
	(segment
		(start 248.19737 -160.349946)
		(end 248.19737 -160.529016)
		(width 0.127)
		(layer "In2.Cu")
		(net "SMB_LM75_0_3V3AUX_SDA")
	)
	(segment
		(start 294.13962 -410.76626)
		(end 294.13962 -411.2895)
		(width 0.127)
		(layer "In2.Cu")
		(net "SMB_LM75_0_3V3AUX_SDA")
	)
	(segment
		(start 299.2755 -408.7114)
		(end 296.19448 -408.7114)
		(width 0.127)
		(layer "In2.Cu")
		(net "SMB_LM75_0_3V3AUX_SDA")
	)
	(segment
		(start 247.05691 -160.052004)
		(end 247.326658 -160.321752)
		(width 0.127)
		(layer "In2.Cu")
		(net "SMB_LM75_0_3V3AUX_SDA")
	)
	(segment
		(start 224.13214 -136.283954)
		(end 247.298718 -159.451548)
		(width 0.127)
		(layer "In2.Cu")
		(net "SMB_LM75_0_3V3AUX_SDA")
	)
	(segment
		(start 248.646696 -160.978088)
		(end 248.82602 -160.978088)
		(width 0.127)
		(layer "In2.Cu")
		(net "SMB_LM75_0_3V3AUX_SDA")
	)
	(segment
		(start 248.82602 -160.978088)
		(end 249.809 -161.961068)
		(width 0.127)
		(layer "In2.Cu")
		(net "SMB_LM75_0_3V3AUX_SDA")
	)
	(segment
		(start 249.809 -238.971074)
		(end 250.7996 -239.961674)
		(width 0.127)
		(layer "In2.Cu")
		(net "SMB_LM75_0_3V3AUX_SDA")
	)
	(segment
		(start 226.85502 -364.22076)
		(end 226.45624 -364.61954)
		(width 0.127)
		(layer "In2.Cu")
		(net "SMB_LM75_0_3V3AUX_SDA")
	)
	(segment
		(start 296.05478 -409.37434)
		(end 294.13962 -411.2895)
		(width 0.127)
		(layer "In4.Cu")
		(net "SMB_LM75_0_3V3AUX_SDA")
	)
	(segment
		(start 271.54378 -385.1402)
		(end 276.14245 -385.1402)
		(width 0.127)
		(layer "In4.Cu")
		(net "SMB_LM75_0_3V3AUX_SDA")
	)
	(segment
		(start 296.05478 -407.14676)
		(end 296.05478 -409.37434)
		(width 0.127)
		(layer "In4.Cu")
		(net "SMB_LM75_0_3V3AUX_SDA")
	)
	(segment
		(start 226.45624 -364.61954)
		(end 242.441984 -380.605284)
		(width 0.127)
		(layer "In4.Cu")
		(net "SMB_LM75_0_3V3AUX_SDA")
	)
	(segment
		(start 296.946828 -397.530828)
		(end 299.05452 -399.63852)
		(width 0.127)
		(layer "In4.Cu")
		(net "SMB_LM75_0_3V3AUX_SDA")
	)
	(segment
		(start 283.190442 -392.188192)
		(end 283.190442 -394.247624)
		(width 0.127)
		(layer "In4.Cu")
		(net "SMB_LM75_0_3V3AUX_SDA")
	)
	(segment
		(start 270.65478 -384.2512)
		(end 271.54378 -385.1402)
		(width 0.127)
		(layer "In4.Cu")
		(net "SMB_LM75_0_3V3AUX_SDA")
	)
	(segment
		(start 299.05452 -404.14702)
		(end 296.05478 -407.14676)
		(width 0.127)
		(layer "In4.Cu")
		(net "SMB_LM75_0_3V3AUX_SDA")
	)
	(segment
		(start 299.05452 -399.63852)
		(end 299.05452 -404.14702)
		(width 0.127)
		(layer "In4.Cu")
		(net "SMB_LM75_0_3V3AUX_SDA")
	)
	(segment
		(start 260.8961 -380.605284)
		(end 264.542016 -384.2512)
		(width 0.127)
		(layer "In4.Cu")
		(net "SMB_LM75_0_3V3AUX_SDA")
	)
	(segment
		(start 264.542016 -384.2512)
		(end 270.65478 -384.2512)
		(width 0.127)
		(layer "In4.Cu")
		(net "SMB_LM75_0_3V3AUX_SDA")
	)
	(segment
		(start 283.190442 -394.247624)
		(end 286.473646 -397.530828)
		(width 0.127)
		(layer "In4.Cu")
		(net "SMB_LM75_0_3V3AUX_SDA")
	)
	(segment
		(start 242.441984 -380.605284)
		(end 260.8961 -380.605284)
		(width 0.127)
		(layer "In4.Cu")
		(net "SMB_LM75_0_3V3AUX_SDA")
	)
	(segment
		(start 286.473646 -397.530828)
		(end 296.946828 -397.530828)
		(width 0.127)
		(layer "In4.Cu")
		(net "SMB_LM75_0_3V3AUX_SDA")
	)
	(segment
		(start 276.14245 -385.1402)
		(end 283.190442 -392.188192)
		(width 0.127)
		(layer "In4.Cu")
		(net "SMB_LM75_0_3V3AUX_SDA")
	)
	(segment
		(start 356.87508 -405.515318)
		(end 356.87508 -416.228022)
		(width 0.127)
		(layer "In6.Cu")
		(net "SMB_LM75_0_3V3AUX_SDA")
	)
	(segment
		(start 350.91751 -399.557748)
		(end 353.809554 -402.449792)
		(width 0.127)
		(layer "In6.Cu")
		(net "SMB_LM75_0_3V3AUX_SDA")
	)
	(segment
		(start 356.87508 -416.228022)
		(end 360.78668 -420.139622)
		(width 0.127)
		(layer "In6.Cu")
		(net "SMB_LM75_0_3V3AUX_SDA")
	)
	(segment
		(start 302.1838 -408.24912)
		(end 302.1838 -401.264882)
		(width 0.127)
		(layer "In6.Cu")
		(net "SMB_LM75_0_3V3AUX_SDA")
	)
	(segment
		(start 302.1838 -401.264882)
		(end 303.890934 -399.557748)
		(width 0.127)
		(layer "In6.Cu")
		(net "SMB_LM75_0_3V3AUX_SDA")
	)
	(segment
		(start 364.05312 -423.929048)
		(end 365.30788 -425.18457)
		(width 0.127)
		(layer "In6.Cu")
		(net "SMB_LM75_0_3V3AUX_SDA")
	)
	(segment
		(start 356.362 -402.9964)
		(end 356.362 -405.002238)
		(width 0.127)
		(layer "In6.Cu")
		(net "SMB_LM75_0_3V3AUX_SDA")
	)
	(segment
		(start 299.2755 -408.7114)
		(end 299.697902 -409.133802)
		(width 0.127)
		(layer "In6.Cu")
		(net "SMB_LM75_0_3V3AUX_SDA")
	)
	(segment
		(start 363.185456 -420.139622)
		(end 364.05312 -421.007286)
		(width 0.127)
		(layer "In6.Cu")
		(net "SMB_LM75_0_3V3AUX_SDA")
	)
	(segment
		(start 355.815392 -402.449792)
		(end 356.362 -402.9964)
		(width 0.127)
		(layer "In6.Cu")
		(net "SMB_LM75_0_3V3AUX_SDA")
	)
	(segment
		(start 303.890934 -399.557748)
		(end 350.91751 -399.557748)
		(width 0.127)
		(layer "In6.Cu")
		(net "SMB_LM75_0_3V3AUX_SDA")
	)
	(segment
		(start 356.362 -405.002238)
		(end 356.87508 -405.515318)
		(width 0.127)
		(layer "In6.Cu")
		(net "SMB_LM75_0_3V3AUX_SDA")
	)
	(segment
		(start 353.809554 -402.449792)
		(end 355.815392 -402.449792)
		(width 0.127)
		(layer "In6.Cu")
		(net "SMB_LM75_0_3V3AUX_SDA")
	)
	(segment
		(start 364.05312 -421.007286)
		(end 364.05312 -423.929048)
		(width 0.127)
		(layer "In6.Cu")
		(net "SMB_LM75_0_3V3AUX_SDA")
	)
	(segment
		(start 301.299118 -409.133802)
		(end 302.1838 -408.24912)
		(width 0.127)
		(layer "In6.Cu")
		(net "SMB_LM75_0_3V3AUX_SDA")
	)
	(segment
		(start 360.78668 -420.139622)
		(end 363.185456 -420.139622)
		(width 0.127)
		(layer "In6.Cu")
		(net "SMB_LM75_0_3V3AUX_SDA")
	)
	(segment
		(start 299.697902 -409.133802)
		(end 301.299118 -409.133802)
		(width 0.127)
		(layer "In6.Cu")
		(net "SMB_LM75_0_3V3AUX_SDA")
	)
	(segment
		(start 51.2826 -98.539808)
		(end 51.79695 -98.025458)
		(width 0.127)
		(layer "In15.Cu")
		(net "SMB_LM75_0_3V3AUX_SDA")
	)
	(segment
		(start 109.30382 -124.932948)
		(end 110.06582 -125.694948)
		(width 0.127)
		(layer "In15.Cu")
		(net "SMB_LM75_0_3V3AUX_SDA")
	)
	(segment
		(start 62.140338 -105.730548)
		(end 62.267338 -105.603548)
		(width 0.127)
		(layer "In15.Cu")
		(net "SMB_LM75_0_3V3AUX_SDA")
	)
	(segment
		(start 61.632338 -105.085388)
		(end 61.632338 -105.603548)
		(width 0.127)
		(layer "In15.Cu")
		(net "SMB_LM75_0_3V3AUX_SDA")
	)
	(segment
		(start 60.870338 -105.730548)
		(end 60.997338 -105.603548)
		(width 0.127)
		(layer "In15.Cu")
		(net "SMB_LM75_0_3V3AUX_SDA")
	)
	(segment
		(start 60.997338 -105.085388)
		(end 61.124338 -104.958388)
		(width 0.127)
		(layer "In15.Cu")
		(net "SMB_LM75_0_3V3AUX_SDA")
	)
	(segment
		(start 59.854338 -104.958388)
		(end 60.235338 -104.958388)
		(width 0.127)
		(layer "In15.Cu")
		(net "SMB_LM75_0_3V3AUX_SDA")
	)
	(segment
		(start 60.362338 -105.603548)
		(end 60.489338 -105.730548)
		(width 0.127)
		(layer "In15.Cu")
		(net "SMB_LM75_0_3V3AUX_SDA")
	)
	(segment
		(start 60.235338 -104.958388)
		(end 60.362338 -105.085388)
		(width 0.127)
		(layer "In15.Cu")
		(net "SMB_LM75_0_3V3AUX_SDA")
	)
	(segment
		(start 150.180548 -138.226038)
		(end 150.38451 -138.43)
		(width 0.127)
		(layer "In15.Cu")
		(net "SMB_LM75_0_3V3AUX_SDA")
	)
	(segment
		(start 54.31536 -104.958388)
		(end 58.965338 -104.958388)
		(width 0.127)
		(layer "In15.Cu")
		(net "SMB_LM75_0_3V3AUX_SDA")
	)
	(segment
		(start 61.505338 -104.958388)
		(end 61.632338 -105.085388)
		(width 0.127)
		(layer "In15.Cu")
		(net "SMB_LM75_0_3V3AUX_SDA")
	)
	(segment
		(start 150.38451 -138.43)
		(end 193.2305 -138.43)
		(width 0.127)
		(layer "In15.Cu")
		(net "SMB_LM75_0_3V3AUX_SDA")
	)
	(segment
		(start 210.698842 -139.325858)
		(end 213.105492 -136.919208)
		(width 0.127)
		(layer "In15.Cu")
		(net "SMB_LM75_0_3V3AUX_SDA")
	)
	(segment
		(start 146.95297 -138.226038)
		(end 150.180548 -138.226038)
		(width 0.127)
		(layer "In15.Cu")
		(net "SMB_LM75_0_3V3AUX_SDA")
	)
	(segment
		(start 49.38776 -111.64951)
		(end 50.01514 -111.02213)
		(width 0.127)
		(layer "In15.Cu")
		(net "SMB_LM75_0_3V3AUX_SDA")
	)
	(segment
		(start 62.267338 -105.085388)
		(end 62.394338 -104.958388)
		(width 0.127)
		(layer "In15.Cu")
		(net "SMB_LM75_0_3V3AUX_SDA")
	)
	(segment
		(start 110.06582 -125.694948)
		(end 128.19888 -125.694948)
		(width 0.127)
		(layer "In15.Cu")
		(net "SMB_LM75_0_3V3AUX_SDA")
	)
	(segment
		(start 58.965338 -104.958388)
		(end 59.092338 -105.085388)
		(width 0.127)
		(layer "In15.Cu")
		(net "SMB_LM75_0_3V3AUX_SDA")
	)
	(segment
		(start 60.489338 -105.730548)
		(end 60.870338 -105.730548)
		(width 0.127)
		(layer "In15.Cu")
		(net "SMB_LM75_0_3V3AUX_SDA")
	)
	(segment
		(start 59.727338 -105.085388)
		(end 59.854338 -104.958388)
		(width 0.127)
		(layer "In15.Cu")
		(net "SMB_LM75_0_3V3AUX_SDA")
	)
	(segment
		(start 51.79695 -98.025458)
		(end 52.58689 -98.025458)
		(width 0.127)
		(layer "In15.Cu")
		(net "SMB_LM75_0_3V3AUX_SDA")
	)
	(segment
		(start 61.124338 -104.958388)
		(end 61.505338 -104.958388)
		(width 0.127)
		(layer "In15.Cu")
		(net "SMB_LM75_0_3V3AUX_SDA")
	)
	(segment
		(start 52.58689 -98.025458)
		(end 53.05298 -98.491548)
		(width 0.127)
		(layer "In15.Cu")
		(net "SMB_LM75_0_3V3AUX_SDA")
	)
	(segment
		(start 220.78188 -136.919208)
		(end 224.06356 -133.637528)
		(width 0.127)
		(layer "In15.Cu")
		(net "SMB_LM75_0_3V3AUX_SDA")
	)
	(segment
		(start 59.092338 -105.603548)
		(end 59.219338 -105.730548)
		(width 0.127)
		(layer "In15.Cu")
		(net "SMB_LM75_0_3V3AUX_SDA")
	)
	(segment
		(start 60.997338 -105.603548)
		(end 60.997338 -105.085388)
		(width 0.127)
		(layer "In15.Cu")
		(net "SMB_LM75_0_3V3AUX_SDA")
	)
	(segment
		(start 137.91946 -129.192528)
		(end 146.95297 -138.226038)
		(width 0.127)
		(layer "In15.Cu")
		(net "SMB_LM75_0_3V3AUX_SDA")
	)
	(segment
		(start 61.632338 -105.603548)
		(end 61.759338 -105.730548)
		(width 0.127)
		(layer "In15.Cu")
		(net "SMB_LM75_0_3V3AUX_SDA")
	)
	(segment
		(start 59.727338 -105.603548)
		(end 59.727338 -105.085388)
		(width 0.127)
		(layer "In15.Cu")
		(net "SMB_LM75_0_3V3AUX_SDA")
	)
	(segment
		(start 61.759338 -105.730548)
		(end 62.140338 -105.730548)
		(width 0.127)
		(layer "In15.Cu")
		(net "SMB_LM75_0_3V3AUX_SDA")
	)
	(segment
		(start 68.8975 -104.958388)
		(end 88.87206 -124.932948)
		(width 0.127)
		(layer "In15.Cu")
		(net "SMB_LM75_0_3V3AUX_SDA")
	)
	(segment
		(start 131.69646 -129.192528)
		(end 137.91946 -129.192528)
		(width 0.127)
		(layer "In15.Cu")
		(net "SMB_LM75_0_3V3AUX_SDA")
	)
	(segment
		(start 53.05298 -103.696008)
		(end 54.31536 -104.958388)
		(width 0.127)
		(layer "In15.Cu")
		(net "SMB_LM75_0_3V3AUX_SDA")
	)
	(segment
		(start 50.01514 -111.02213)
		(end 50.01514 -104.996488)
		(width 0.127)
		(layer "In15.Cu")
		(net "SMB_LM75_0_3V3AUX_SDA")
	)
	(segment
		(start 88.87206 -124.932948)
		(end 109.30382 -124.932948)
		(width 0.127)
		(layer "In15.Cu")
		(net "SMB_LM75_0_3V3AUX_SDA")
	)
	(segment
		(start 62.267338 -105.603548)
		(end 62.267338 -105.085388)
		(width 0.127)
		(layer "In15.Cu")
		(net "SMB_LM75_0_3V3AUX_SDA")
	)
	(segment
		(start 194.126358 -139.325858)
		(end 210.698842 -139.325858)
		(width 0.127)
		(layer "In15.Cu")
		(net "SMB_LM75_0_3V3AUX_SDA")
	)
	(segment
		(start 193.2305 -138.43)
		(end 194.126358 -139.325858)
		(width 0.127)
		(layer "In15.Cu")
		(net "SMB_LM75_0_3V3AUX_SDA")
	)
	(segment
		(start 51.2826 -103.729028)
		(end 51.2826 -98.539808)
		(width 0.127)
		(layer "In15.Cu")
		(net "SMB_LM75_0_3V3AUX_SDA")
	)
	(segment
		(start 59.092338 -105.085388)
		(end 59.092338 -105.603548)
		(width 0.127)
		(layer "In15.Cu")
		(net "SMB_LM75_0_3V3AUX_SDA")
	)
	(segment
		(start 50.01514 -104.996488)
		(end 51.2826 -103.729028)
		(width 0.127)
		(layer "In15.Cu")
		(net "SMB_LM75_0_3V3AUX_SDA")
	)
	(segment
		(start 53.05298 -98.491548)
		(end 53.05298 -103.696008)
		(width 0.127)
		(layer "In15.Cu")
		(net "SMB_LM75_0_3V3AUX_SDA")
	)
	(segment
		(start 59.219338 -105.730548)
		(end 59.600338 -105.730548)
		(width 0.127)
		(layer "In15.Cu")
		(net "SMB_LM75_0_3V3AUX_SDA")
	)
	(segment
		(start 213.105492 -136.919208)
		(end 220.78188 -136.919208)
		(width 0.127)
		(layer "In15.Cu")
		(net "SMB_LM75_0_3V3AUX_SDA")
	)
	(segment
		(start 60.362338 -105.085388)
		(end 60.362338 -105.603548)
		(width 0.127)
		(layer "In15.Cu")
		(net "SMB_LM75_0_3V3AUX_SDA")
	)
	(segment
		(start 59.600338 -105.730548)
		(end 59.727338 -105.603548)
		(width 0.127)
		(layer "In15.Cu")
		(net "SMB_LM75_0_3V3AUX_SDA")
	)
	(segment
		(start 224.06356 -133.637528)
		(end 224.13214 -133.637528)
		(width 0.127)
		(layer "In15.Cu")
		(net "SMB_LM75_0_3V3AUX_SDA")
	)
	(segment
		(start 128.19888 -125.694948)
		(end 131.69646 -129.192528)
		(width 0.127)
		(layer "In15.Cu")
		(net "SMB_LM75_0_3V3AUX_SDA")
	)
	(segment
		(start 62.394338 -104.958388)
		(end 68.8975 -104.958388)
		(width 0.127)
		(layer "In15.Cu")
		(net "SMB_LM75_0_3V3AUX_SDA")
	)
	(segment
		(start 368.55908 -426.888148)
		(end 370.916454 -426.888148)
		(width 0.12954)
		(layer "F.Cu")
		(net "SMB_LM75_0_3V3AUX_SCL_R1")
	)
	(segment
		(start 370.916454 -426.888148)
		(end 371.540278 -426.264324)
		(width 0.12954)
		(layer "F.Cu")
		(net "SMB_LM75_0_3V3AUX_SCL_R1")
	)
	(segment
		(start 371.540278 -426.264324)
		(end 371.540278 -425.882308)
		(width 0.12954)
		(layer "F.Cu")
		(net "SMB_LM75_0_3V3AUX_SCL_R1")
	)
	(segment
		(start 368.02568 -425.465748)
		(end 368.02568 -426.354748)
		(width 0.12954)
		(layer "F.Cu")
		(net "SMB_LM75_0_3V3AUX_SCL_R1")
	)
	(segment
		(start 368.02568 -426.354748)
		(end 368.55908 -426.888148)
		(width 0.12954)
		(layer "F.Cu")
		(net "SMB_LM75_0_3V3AUX_SCL_R1")
	)
	(segment
		(start 367.788698 -424.085766)
		(end 368.02568 -424.322748)
		(width 0.12954)
		(layer "F.Cu")
		(net "SMB_LM75_0_3V3AUX_SCL_R1")
	)
	(segment
		(start 368.02568 -424.322748)
		(end 368.02568 -425.465748)
		(width 0.12954)
		(layer "F.Cu")
		(net "SMB_LM75_0_3V3AUX_SCL_R1")
	)
	(segment
		(start 366.832388 -424.085766)
		(end 367.788698 -424.085766)
		(width 0.12954)
		(layer "F.Cu")
		(net "SMB_LM75_0_3V3AUX_SCL_R1")
	)
	(via
		(at 368.02568 -425.465748)
		(size 0.508)
		(drill 0.254)
		(layers "F.Cu" "B.Cu")
		(net "SMB_LM75_0_3V3AUX_SCL_R1")
	)
	(segment
		(start 299.464984 -409.69184)
		(end 298.53509 -409.69184)
		(width 0.12954)
		(layer "F.Cu")
		(net "SMB_LM75_0_3V3AUX_SCL")
	)
	(segment
		(start 53.837586 -110.93577)
		(end 51.993546 -110.93577)
		(width 0.12954)
		(layer "F.Cu")
		(net "SMB_LM75_0_3V3AUX_SCL")
	)
	(segment
		(start 365.672878 -424.085766)
		(end 366.032288 -424.085766)
		(width 0.12954)
		(layer "F.Cu")
		(net "SMB_LM75_0_3V3AUX_SCL")
	)
	(segment
		(start 49.38776 -110.20933)
		(end 51.267106 -110.20933)
		(width 0.12954)
		(layer "F.Cu")
		(net "SMB_LM75_0_3V3AUX_SCL")
	)
	(segment
		(start 53.842666 -110.93069)
		(end 53.837586 -110.93577)
		(width 0.12954)
		(layer "F.Cu")
		(net "SMB_LM75_0_3V3AUX_SCL")
	)
	(segment
		(start 298.3357 -410.37002)
		(end 298.3357 -409.89123)
		(width 0.12954)
		(layer "F.Cu")
		(net "SMB_LM75_0_3V3AUX_SCL")
	)
	(segment
		(start 51.267106 -110.20933)
		(end 51.993546 -110.93577)
		(width 0.12954)
		(layer "F.Cu")
		(net "SMB_LM75_0_3V3AUX_SCL")
	)
	(segment
		(start 365.33328 -423.746168)
		(end 365.672878 -424.085766)
		(width 0.12954)
		(layer "F.Cu")
		(net "SMB_LM75_0_3V3AUX_SCL")
	)
	(segment
		(start 298.3357 -409.89123)
		(end 298.53509 -409.69184)
		(width 0.12954)
		(layer "F.Cu")
		(net "SMB_LM75_0_3V3AUX_SCL")
	)
	(via
		(at 298.3357 -410.37002)
		(size 0.508)
		(drill 0.254)
		(layers "F.Cu" "B.Cu")
		(net "SMB_LM75_0_3V3AUX_SCL")
	)
	(via
		(at 227.28682 -364.73638)
		(size 0.508)
		(drill 0.254)
		(layers "F.Cu" "B.Cu")
		(net "SMB_LM75_0_3V3AUX_SCL")
	)
	(via
		(at 365.33328 -423.746168)
		(size 0.508)
		(drill 0.254)
		(layers "F.Cu" "B.Cu")
		(net "SMB_LM75_0_3V3AUX_SCL")
	)
	(via
		(at 224.666048 -133.0452)
		(size 0.508)
		(drill 0.254)
		(layers "F.Cu" "B.Cu")
		(net "SMB_LM75_0_3V3AUX_SCL")
	)
	(via
		(at 49.38776 -110.20933)
		(size 0.508)
		(drill 0.254)
		(layers "F.Cu" "B.Cu")
		(net "SMB_LM75_0_3V3AUX_SCL")
	)
	(segment
		(start 251.2822 -322.671694)
		(end 227.28682 -346.667074)
		(width 0.127)
		(layer "In2.Cu")
		(net "SMB_LM75_0_3V3AUX_SCL")
	)
	(segment
		(start 250.2916 -161.636202)
		(end 250.2916 -238.84255)
		(width 0.127)
		(layer "In2.Cu")
		(net "SMB_LM75_0_3V3AUX_SCL")
	)
	(segment
		(start 227.28682 -346.667074)
		(end 227.28682 -364.73638)
		(width 0.127)
		(layer "In2.Cu")
		(net "SMB_LM75_0_3V3AUX_SCL")
	)
	(segment
		(start 251.2822 -239.83315)
		(end 251.2822 -322.671694)
		(width 0.127)
		(layer "In2.Cu")
		(net "SMB_LM75_0_3V3AUX_SCL")
	)
	(segment
		(start 224.666048 -136.01065)
		(end 250.2916 -161.636202)
		(width 0.127)
		(layer "In2.Cu")
		(net "SMB_LM75_0_3V3AUX_SCL")
	)
	(segment
		(start 250.2916 -238.84255)
		(end 251.2822 -239.83315)
		(width 0.127)
		(layer "In2.Cu")
		(net "SMB_LM75_0_3V3AUX_SCL")
	)
	(segment
		(start 224.666048 -133.0452)
		(end 224.666048 -136.01065)
		(width 0.127)
		(layer "In2.Cu")
		(net "SMB_LM75_0_3V3AUX_SCL")
	)
	(segment
		(start 266.539218 -383.0066)
		(end 266.412218 -383.1336)
		(width 0.127)
		(layer "In4.Cu")
		(net "SMB_LM75_0_3V3AUX_SCL")
	)
	(segment
		(start 266.793218 -383.0066)
		(end 266.539218 -383.0066)
		(width 0.127)
		(layer "In4.Cu")
		(net "SMB_LM75_0_3V3AUX_SCL")
	)
	(segment
		(start 265.523218 -383.0066)
		(end 265.396218 -383.1336)
		(width 0.127)
		(layer "In4.Cu")
		(net "SMB_LM75_0_3V3AUX_SCL")
	)
	(segment
		(start 264.62101 -383.68859)
		(end 261.03326 -380.10084)
		(width 0.127)
		(layer "In4.Cu")
		(net "SMB_LM75_0_3V3AUX_SCL")
	)
	(segment
		(start 301.1678 -403.261322)
		(end 301.0408 -403.134322)
		(width 0.127)
		(layer "In4.Cu")
		(net "SMB_LM75_0_3V3AUX_SCL")
	)
	(segment
		(start 267.428218 -383.56159)
		(end 267.301218 -383.68859)
		(width 0.127)
		(layer "In4.Cu")
		(net "SMB_LM75_0_3V3AUX_SCL")
	)
	(segment
		(start 299.57014 -398.9578)
		(end 297.711368 -397.099028)
		(width 0.127)
		(layer "In4.Cu")
		(net "SMB_LM75_0_3V3AUX_SCL")
	)
	(segment
		(start 298.3357 -406.69972)
		(end 299.57014 -405.46528)
		(width 0.127)
		(layer "In4.Cu")
		(net "SMB_LM75_0_3V3AUX_SCL")
	)
	(segment
		(start 265.269218 -383.68859)
		(end 264.62101 -383.68859)
		(width 0.127)
		(layer "In4.Cu")
		(net "SMB_LM75_0_3V3AUX_SCL")
	)
	(segment
		(start 301.1678 -401.991322)
		(end 301.0408 -401.864322)
		(width 0.127)
		(layer "In4.Cu")
		(net "SMB_LM75_0_3V3AUX_SCL")
	)
	(segment
		(start 299.57014 -401.737322)
		(end 299.57014 -398.9578)
		(width 0.127)
		(layer "In4.Cu")
		(net "SMB_LM75_0_3V3AUX_SCL")
	)
	(segment
		(start 269.079218 -383.68859)
		(end 268.952218 -383.56159)
		(width 0.127)
		(layer "In4.Cu")
		(net "SMB_LM75_0_3V3AUX_SCL")
	)
	(segment
		(start 265.396218 -383.56159)
		(end 265.269218 -383.68859)
		(width 0.127)
		(layer "In4.Cu")
		(net "SMB_LM75_0_3V3AUX_SCL")
	)
	(segment
		(start 269.333218 -383.68859)
		(end 269.079218 -383.68859)
		(width 0.127)
		(layer "In4.Cu")
		(net "SMB_LM75_0_3V3AUX_SCL")
	)
	(segment
		(start 301.0408 -403.769322)
		(end 301.1678 -403.642322)
		(width 0.127)
		(layer "In4.Cu")
		(net "SMB_LM75_0_3V3AUX_SCL")
	)
	(segment
		(start 268.571218 -383.0066)
		(end 268.444218 -383.1336)
		(width 0.127)
		(layer "In4.Cu")
		(net "SMB_LM75_0_3V3AUX_SCL")
	)
	(segment
		(start 299.69714 -403.134322)
		(end 299.57014 -403.007322)
		(width 0.127)
		(layer "In4.Cu")
		(net "SMB_LM75_0_3V3AUX_SCL")
	)
	(segment
		(start 270.095218 -383.68859)
		(end 269.968218 -383.56159)
		(width 0.127)
		(layer "In4.Cu")
		(net "SMB_LM75_0_3V3AUX_SCL")
	)
	(segment
		(start 272.653252 -384.64744)
		(end 271.74952 -384.64744)
		(width 0.127)
		(layer "In4.Cu")
		(net "SMB_LM75_0_3V3AUX_SCL")
	)
	(segment
		(start 265.904218 -383.56159)
		(end 265.904218 -383.1336)
		(width 0.127)
		(layer "In4.Cu")
		(net "SMB_LM75_0_3V3AUX_SCL")
	)
	(segment
		(start 267.301218 -383.68859)
		(end 267.047218 -383.68859)
		(width 0.127)
		(layer "In4.Cu")
		(net "SMB_LM75_0_3V3AUX_SCL")
	)
	(segment
		(start 299.57014 -405.46528)
		(end 299.57014 -403.896322)
		(width 0.127)
		(layer "In4.Cu")
		(net "SMB_LM75_0_3V3AUX_SCL")
	)
	(segment
		(start 269.841218 -383.0066)
		(end 269.587218 -383.0066)
		(width 0.127)
		(layer "In4.Cu")
		(net "SMB_LM75_0_3V3AUX_SCL")
	)
	(segment
		(start 268.317218 -383.68859)
		(end 268.063218 -383.68859)
		(width 0.127)
		(layer "In4.Cu")
		(net "SMB_LM75_0_3V3AUX_SCL")
	)
	(segment
		(start 272.943828 -384.64744)
		(end 272.89252 -384.6576)
		(width 0.127)
		(layer "In4.Cu")
		(net "SMB_LM75_0_3V3AUX_SCL")
	)
	(segment
		(start 268.952218 -383.56159)
		(end 268.952218 -383.1336)
		(width 0.127)
		(layer "In4.Cu")
		(net "SMB_LM75_0_3V3AUX_SCL")
	)
	(segment
		(start 268.063218 -383.68859)
		(end 267.936218 -383.56159)
		(width 0.127)
		(layer "In4.Cu")
		(net "SMB_LM75_0_3V3AUX_SCL")
	)
	(segment
		(start 276.26056 -384.64744)
		(end 272.943828 -384.64744)
		(width 0.127)
		(layer "In4.Cu")
		(net "SMB_LM75_0_3V3AUX_SCL")
	)
	(segment
		(start 301.0408 -403.134322)
		(end 299.69714 -403.134322)
		(width 0.127)
		(layer "In4.Cu")
		(net "SMB_LM75_0_3V3AUX_SCL")
	)
	(segment
		(start 301.1678 -403.642322)
		(end 301.1678 -403.261322)
		(width 0.127)
		(layer "In4.Cu")
		(net "SMB_LM75_0_3V3AUX_SCL")
	)
	(segment
		(start 267.047218 -383.68859)
		(end 266.920218 -383.56159)
		(width 0.127)
		(layer "In4.Cu")
		(net "SMB_LM75_0_3V3AUX_SCL")
	)
	(segment
		(start 265.396218 -383.1336)
		(end 265.396218 -383.56159)
		(width 0.127)
		(layer "In4.Cu")
		(net "SMB_LM75_0_3V3AUX_SCL")
	)
	(segment
		(start 265.777218 -383.0066)
		(end 265.523218 -383.0066)
		(width 0.127)
		(layer "In4.Cu")
		(net "SMB_LM75_0_3V3AUX_SCL")
	)
	(segment
		(start 266.920218 -383.56159)
		(end 266.920218 -383.1336)
		(width 0.127)
		(layer "In4.Cu")
		(net "SMB_LM75_0_3V3AUX_SCL")
	)
	(segment
		(start 286.652716 -397.099028)
		(end 283.713174 -394.159486)
		(width 0.127)
		(layer "In4.Cu")
		(net "SMB_LM75_0_3V3AUX_SCL")
	)
	(segment
		(start 301.0408 -402.499322)
		(end 301.1678 -402.372322)
		(width 0.127)
		(layer "In4.Cu")
		(net "SMB_LM75_0_3V3AUX_SCL")
	)
	(segment
		(start 267.555218 -383.0066)
		(end 267.428218 -383.1336)
		(width 0.127)
		(layer "In4.Cu")
		(net "SMB_LM75_0_3V3AUX_SCL")
	)
	(segment
		(start 283.713174 -394.159486)
		(end 283.713174 -392.100054)
		(width 0.127)
		(layer "In4.Cu")
		(net "SMB_LM75_0_3V3AUX_SCL")
	)
	(segment
		(start 301.0408 -401.864322)
		(end 299.69714 -401.864322)
		(width 0.127)
		(layer "In4.Cu")
		(net "SMB_LM75_0_3V3AUX_SCL")
	)
	(segment
		(start 271.74952 -384.64744)
		(end 270.79067 -383.68859)
		(width 0.127)
		(layer "In4.Cu")
		(net "SMB_LM75_0_3V3AUX_SCL")
	)
	(segment
		(start 272.89252 -384.6576)
		(end 272.70456 -384.6576)
		(width 0.127)
		(layer "In4.Cu")
		(net "SMB_LM75_0_3V3AUX_SCL")
	)
	(segment
		(start 299.57014 -403.007322)
		(end 299.57014 -402.626322)
		(width 0.127)
		(layer "In4.Cu")
		(net "SMB_LM75_0_3V3AUX_SCL")
	)
	(segment
		(start 266.285218 -383.68859)
		(end 266.031218 -383.68859)
		(width 0.127)
		(layer "In4.Cu")
		(net "SMB_LM75_0_3V3AUX_SCL")
	)
	(segment
		(start 266.920218 -383.1336)
		(end 266.793218 -383.0066)
		(width 0.127)
		(layer "In4.Cu")
		(net "SMB_LM75_0_3V3AUX_SCL")
	)
	(segment
		(start 301.1678 -402.372322)
		(end 301.1678 -401.991322)
		(width 0.127)
		(layer "In4.Cu")
		(net "SMB_LM75_0_3V3AUX_SCL")
	)
	(segment
		(start 267.936218 -383.1336)
		(end 267.809218 -383.0066)
		(width 0.127)
		(layer "In4.Cu")
		(net "SMB_LM75_0_3V3AUX_SCL")
	)
	(segment
		(start 265.904218 -383.1336)
		(end 265.777218 -383.0066)
		(width 0.127)
		(layer "In4.Cu")
		(net "SMB_LM75_0_3V3AUX_SCL")
	)
	(segment
		(start 268.444218 -383.1336)
		(end 268.444218 -383.56159)
		(width 0.127)
		(layer "In4.Cu")
		(net "SMB_LM75_0_3V3AUX_SCL")
	)
	(segment
		(start 267.809218 -383.0066)
		(end 267.555218 -383.0066)
		(width 0.127)
		(layer "In4.Cu")
		(net "SMB_LM75_0_3V3AUX_SCL")
	)
	(segment
		(start 283.713174 -392.100054)
		(end 276.26056 -384.64744)
		(width 0.127)
		(layer "In4.Cu")
		(net "SMB_LM75_0_3V3AUX_SCL")
	)
	(segment
		(start 272.70456 -384.6576)
		(end 272.653252 -384.64744)
		(width 0.127)
		(layer "In4.Cu")
		(net "SMB_LM75_0_3V3AUX_SCL")
	)
	(segment
		(start 266.031218 -383.68859)
		(end 265.904218 -383.56159)
		(width 0.127)
		(layer "In4.Cu")
		(net "SMB_LM75_0_3V3AUX_SCL")
	)
	(segment
		(start 269.587218 -383.0066)
		(end 269.460218 -383.1336)
		(width 0.127)
		(layer "In4.Cu")
		(net "SMB_LM75_0_3V3AUX_SCL")
	)
	(segment
		(start 266.412218 -383.56159)
		(end 266.285218 -383.68859)
		(width 0.127)
		(layer "In4.Cu")
		(net "SMB_LM75_0_3V3AUX_SCL")
	)
	(segment
		(start 267.936218 -383.56159)
		(end 267.936218 -383.1336)
		(width 0.127)
		(layer "In4.Cu")
		(net "SMB_LM75_0_3V3AUX_SCL")
	)
	(segment
		(start 242.65128 -380.10084)
		(end 227.28682 -364.73638)
		(width 0.127)
		(layer "In4.Cu")
		(net "SMB_LM75_0_3V3AUX_SCL")
	)
	(segment
		(start 267.428218 -383.1336)
		(end 267.428218 -383.56159)
		(width 0.127)
		(layer "In4.Cu")
		(net "SMB_LM75_0_3V3AUX_SCL")
	)
	(segment
		(start 269.968218 -383.1336)
		(end 269.841218 -383.0066)
		(width 0.127)
		(layer "In4.Cu")
		(net "SMB_LM75_0_3V3AUX_SCL")
	)
	(segment
		(start 299.57014 -402.626322)
		(end 299.69714 -402.499322)
		(width 0.127)
		(layer "In4.Cu")
		(net "SMB_LM75_0_3V3AUX_SCL")
	)
	(segment
		(start 268.825218 -383.0066)
		(end 268.571218 -383.0066)
		(width 0.127)
		(layer "In4.Cu")
		(net "SMB_LM75_0_3V3AUX_SCL")
	)
	(segment
		(start 269.460218 -383.1336)
		(end 269.460218 -383.56159)
		(width 0.127)
		(layer "In4.Cu")
		(net "SMB_LM75_0_3V3AUX_SCL")
	)
	(segment
		(start 297.711368 -397.099028)
		(end 286.652716 -397.099028)
		(width 0.127)
		(layer "In4.Cu")
		(net "SMB_LM75_0_3V3AUX_SCL")
	)
	(segment
		(start 268.952218 -383.1336)
		(end 268.825218 -383.0066)
		(width 0.127)
		(layer "In4.Cu")
		(net "SMB_LM75_0_3V3AUX_SCL")
	)
	(segment
		(start 299.69714 -402.499322)
		(end 301.0408 -402.499322)
		(width 0.127)
		(layer "In4.Cu")
		(net "SMB_LM75_0_3V3AUX_SCL")
	)
	(segment
		(start 269.968218 -383.56159)
		(end 269.968218 -383.1336)
		(width 0.127)
		(layer "In4.Cu")
		(net "SMB_LM75_0_3V3AUX_SCL")
	)
	(segment
		(start 261.03326 -380.10084)
		(end 242.65128 -380.10084)
		(width 0.127)
		(layer "In4.Cu")
		(net "SMB_LM75_0_3V3AUX_SCL")
	)
	(segment
		(start 269.460218 -383.56159)
		(end 269.333218 -383.68859)
		(width 0.127)
		(layer "In4.Cu")
		(net "SMB_LM75_0_3V3AUX_SCL")
	)
	(segment
		(start 268.444218 -383.56159)
		(end 268.317218 -383.68859)
		(width 0.127)
		(layer "In4.Cu")
		(net "SMB_LM75_0_3V3AUX_SCL")
	)
	(segment
		(start 266.412218 -383.1336)
		(end 266.412218 -383.56159)
		(width 0.127)
		(layer "In4.Cu")
		(net "SMB_LM75_0_3V3AUX_SCL")
	)
	(segment
		(start 299.69714 -401.864322)
		(end 299.57014 -401.737322)
		(width 0.127)
		(layer "In4.Cu")
		(net "SMB_LM75_0_3V3AUX_SCL")
	)
	(segment
		(start 298.3357 -410.37002)
		(end 298.3357 -406.69972)
		(width 0.127)
		(layer "In4.Cu")
		(net "SMB_LM75_0_3V3AUX_SCL")
	)
	(segment
		(start 299.69714 -403.769322)
		(end 301.0408 -403.769322)
		(width 0.127)
		(layer "In4.Cu")
		(net "SMB_LM75_0_3V3AUX_SCL")
	)
	(segment
		(start 270.79067 -383.68859)
		(end 270.095218 -383.68859)
		(width 0.127)
		(layer "In4.Cu")
		(net "SMB_LM75_0_3V3AUX_SCL")
	)
	(segment
		(start 299.57014 -403.896322)
		(end 299.69714 -403.769322)
		(width 0.127)
		(layer "In4.Cu")
		(net "SMB_LM75_0_3V3AUX_SCL")
	)
	(segment
		(start 356.8192 -402.1328)
		(end 356.8192 -404.848568)
		(width 0.127)
		(layer "In6.Cu")
		(net "SMB_LM75_0_3V3AUX_SCL")
	)
	(segment
		(start 356.145084 -401.458684)
		(end 356.8192 -402.1328)
		(width 0.127)
		(layer "In6.Cu")
		(net "SMB_LM75_0_3V3AUX_SCL")
	)
	(segment
		(start 363.370114 -419.702742)
		(end 364.5154 -420.848028)
		(width 0.127)
		(layer "In6.Cu")
		(net "SMB_LM75_0_3V3AUX_SCL")
	)
	(segment
		(start 299.470318 -408.2415)
		(end 299.93082 -408.702002)
		(width 0.127)
		(layer "In6.Cu")
		(net "SMB_LM75_0_3V3AUX_SCL")
	)
	(segment
		(start 301.7266 -407.89098)
		(end 301.7266 -401.10918)
		(width 0.127)
		(layer "In6.Cu")
		(net "SMB_LM75_0_3V3AUX_SCL")
	)
	(segment
		(start 299.93082 -408.702002)
		(end 300.915578 -408.702002)
		(width 0.127)
		(layer "In6.Cu")
		(net "SMB_LM75_0_3V3AUX_SCL")
	)
	(segment
		(start 356.8192 -404.848568)
		(end 357.30688 -405.336248)
		(width 0.127)
		(layer "In6.Cu")
		(net "SMB_LM75_0_3V3AUX_SCL")
	)
	(segment
		(start 360.984038 -419.702742)
		(end 363.370114 -419.702742)
		(width 0.127)
		(layer "In6.Cu")
		(net "SMB_LM75_0_3V3AUX_SCL")
	)
	(segment
		(start 364.5154 -420.848028)
		(end 364.5154 -422.928288)
		(width 0.127)
		(layer "In6.Cu")
		(net "SMB_LM75_0_3V3AUX_SCL")
	)
	(segment
		(start 299.039534 -408.2415)
		(end 299.470318 -408.2415)
		(width 0.127)
		(layer "In6.Cu")
		(net "SMB_LM75_0_3V3AUX_SCL")
	)
	(segment
		(start 357.30688 -416.025584)
		(end 360.984038 -419.702742)
		(width 0.127)
		(layer "In6.Cu")
		(net "SMB_LM75_0_3V3AUX_SCL")
	)
	(segment
		(start 301.7266 -401.10918)
		(end 303.709832 -399.125948)
		(width 0.127)
		(layer "In6.Cu")
		(net "SMB_LM75_0_3V3AUX_SCL")
	)
	(segment
		(start 357.30688 -405.336248)
		(end 357.30688 -416.025584)
		(width 0.127)
		(layer "In6.Cu")
		(net "SMB_LM75_0_3V3AUX_SCL")
	)
	(segment
		(start 353.429316 -401.458684)
		(end 356.145084 -401.458684)
		(width 0.127)
		(layer "In6.Cu")
		(net "SMB_LM75_0_3V3AUX_SCL")
	)
	(segment
		(start 364.5154 -422.928288)
		(end 365.33328 -423.746168)
		(width 0.127)
		(layer "In6.Cu")
		(net "SMB_LM75_0_3V3AUX_SCL")
	)
	(segment
		(start 351.09658 -399.125948)
		(end 353.429316 -401.458684)
		(width 0.127)
		(layer "In6.Cu")
		(net "SMB_LM75_0_3V3AUX_SCL")
	)
	(segment
		(start 298.3357 -408.945334)
		(end 299.039534 -408.2415)
		(width 0.127)
		(layer "In6.Cu")
		(net "SMB_LM75_0_3V3AUX_SCL")
	)
	(segment
		(start 303.709832 -399.125948)
		(end 351.09658 -399.125948)
		(width 0.127)
		(layer "In6.Cu")
		(net "SMB_LM75_0_3V3AUX_SCL")
	)
	(segment
		(start 300.915578 -408.702002)
		(end 301.7266 -407.89098)
		(width 0.127)
		(layer "In6.Cu")
		(net "SMB_LM75_0_3V3AUX_SCL")
	)
	(segment
		(start 298.3357 -410.37002)
		(end 298.3357 -408.945334)
		(width 0.127)
		(layer "In6.Cu")
		(net "SMB_LM75_0_3V3AUX_SCL")
	)
	(segment
		(start 49.38776 -110.20933)
		(end 49.2125 -110.03407)
		(width 0.127)
		(layer "In15.Cu")
		(net "SMB_LM75_0_3V3AUX_SCL")
	)
	(segment
		(start 48.07458 -103.825548)
		(end 48.96104 -102.939088)
		(width 0.127)
		(layer "In15.Cu")
		(net "SMB_LM75_0_3V3AUX_SCL")
	)
	(segment
		(start 50.5841 -102.420928)
		(end 50.5841 -98.514408)
		(width 0.127)
		(layer "In15.Cu")
		(net "SMB_LM75_0_3V3AUX_SCL")
	)
	(segment
		(start 212.964776 -136.403588)
		(end 220.29166 -136.403588)
		(width 0.127)
		(layer "In15.Cu")
		(net "SMB_LM75_0_3V3AUX_SCL")
	)
	(segment
		(start 210.530186 -138.838178)
		(end 212.964776 -136.403588)
		(width 0.127)
		(layer "In15.Cu")
		(net "SMB_LM75_0_3V3AUX_SCL")
	)
	(segment
		(start 194.322954 -138.838178)
		(end 210.530186 -138.838178)
		(width 0.127)
		(layer "In15.Cu")
		(net "SMB_LM75_0_3V3AUX_SCL")
	)
	(segment
		(start 130.986276 -127.792988)
		(end 137.247884 -127.792988)
		(width 0.127)
		(layer "In15.Cu")
		(net "SMB_LM75_0_3V3AUX_SCL")
	)
	(segment
		(start 220.29166 -136.403588)
		(end 223.650048 -133.0452)
		(width 0.127)
		(layer "In15.Cu")
		(net "SMB_LM75_0_3V3AUX_SCL")
	)
	(segment
		(start 147.195794 -137.740898)
		(end 150.306278 -137.740898)
		(width 0.127)
		(layer "In15.Cu")
		(net "SMB_LM75_0_3V3AUX_SCL")
	)
	(segment
		(start 49.2125 -110.03407)
		(end 49.2125 -107.028488)
		(width 0.127)
		(layer "In15.Cu")
		(net "SMB_LM75_0_3V3AUX_SCL")
	)
	(segment
		(start 49.2125 -107.028488)
		(end 48.07458 -105.890568)
		(width 0.127)
		(layer "In15.Cu")
		(net "SMB_LM75_0_3V3AUX_SCL")
	)
	(segment
		(start 137.247884 -127.792988)
		(end 147.195794 -137.740898)
		(width 0.127)
		(layer "In15.Cu")
		(net "SMB_LM75_0_3V3AUX_SCL")
	)
	(segment
		(start 110.262416 -125.232668)
		(end 128.425956 -125.232668)
		(width 0.127)
		(layer "In15.Cu")
		(net "SMB_LM75_0_3V3AUX_SCL")
	)
	(segment
		(start 89.01176 -124.419868)
		(end 109.449616 -124.419868)
		(width 0.127)
		(layer "In15.Cu")
		(net "SMB_LM75_0_3V3AUX_SCL")
	)
	(segment
		(start 69.088762 -104.49687)
		(end 89.01176 -124.419868)
		(width 0.127)
		(layer "In15.Cu")
		(net "SMB_LM75_0_3V3AUX_SCL")
	)
	(segment
		(start 51.6382 -97.460308)
		(end 52.67452 -97.460308)
		(width 0.127)
		(layer "In15.Cu")
		(net "SMB_LM75_0_3V3AUX_SCL")
	)
	(segment
		(start 53.514498 -98.300286)
		(end 53.514498 -103.504746)
		(width 0.127)
		(layer "In15.Cu")
		(net "SMB_LM75_0_3V3AUX_SCL")
	)
	(segment
		(start 52.67452 -97.460308)
		(end 53.514498 -98.300286)
		(width 0.127)
		(layer "In15.Cu")
		(net "SMB_LM75_0_3V3AUX_SCL")
	)
	(segment
		(start 150.56358 -137.9982)
		(end 193.482976 -137.9982)
		(width 0.127)
		(layer "In15.Cu")
		(net "SMB_LM75_0_3V3AUX_SCL")
	)
	(segment
		(start 48.07458 -105.890568)
		(end 48.07458 -103.825548)
		(width 0.127)
		(layer "In15.Cu")
		(net "SMB_LM75_0_3V3AUX_SCL")
	)
	(segment
		(start 109.449616 -124.419868)
		(end 110.262416 -125.232668)
		(width 0.127)
		(layer "In15.Cu")
		(net "SMB_LM75_0_3V3AUX_SCL")
	)
	(segment
		(start 48.96104 -102.939088)
		(end 50.06594 -102.939088)
		(width 0.127)
		(layer "In15.Cu")
		(net "SMB_LM75_0_3V3AUX_SCL")
	)
	(segment
		(start 223.650048 -133.0452)
		(end 224.666048 -133.0452)
		(width 0.127)
		(layer "In15.Cu")
		(net "SMB_LM75_0_3V3AUX_SCL")
	)
	(segment
		(start 50.5841 -98.514408)
		(end 51.6382 -97.460308)
		(width 0.127)
		(layer "In15.Cu")
		(net "SMB_LM75_0_3V3AUX_SCL")
	)
	(segment
		(start 50.06594 -102.939088)
		(end 50.5841 -102.420928)
		(width 0.127)
		(layer "In15.Cu")
		(net "SMB_LM75_0_3V3AUX_SCL")
	)
	(segment
		(start 128.425956 -125.232668)
		(end 130.986276 -127.792988)
		(width 0.127)
		(layer "In15.Cu")
		(net "SMB_LM75_0_3V3AUX_SCL")
	)
	(segment
		(start 54.506622 -104.49687)
		(end 69.088762 -104.49687)
		(width 0.127)
		(layer "In15.Cu")
		(net "SMB_LM75_0_3V3AUX_SCL")
	)
	(segment
		(start 150.306278 -137.740898)
		(end 150.56358 -137.9982)
		(width 0.127)
		(layer "In15.Cu")
		(net "SMB_LM75_0_3V3AUX_SCL")
	)
	(segment
		(start 193.482976 -137.9982)
		(end 194.322954 -138.838178)
		(width 0.127)
		(layer "In15.Cu")
		(net "SMB_LM75_0_3V3AUX_SCL")
	)
	(segment
		(start 53.514498 -103.504746)
		(end 54.506622 -104.49687)
		(width 0.127)
		(layer "In15.Cu")
		(net "SMB_LM75_0_3V3AUX_SCL")
	)
	(segment
		(start 159.85744 -25.789128)
		(end 159.85744 -22.865334)
		(width 0.12954)
		(layer "F.Cu")
		(net "SMB_2_PLD_3V3AUX_SDA_R1")
	)
	(segment
		(start 160.6042 -26.535888)
		(end 159.85744 -25.789128)
		(width 0.12954)
		(layer "F.Cu")
		(net "SMB_2_PLD_3V3AUX_SDA_R1")
	)
	(segment
		(start 178.9557 -120.975374)
		(end 179.35575 -121.375424)
		(width 0.12954)
		(layer "F.Cu")
		(net "SMB_2_PLD_3V3AUX_SDA_R1")
	)
	(segment
		(start 159.85744 -22.865334)
		(end 160.360868 -22.361906)
		(width 0.12954)
		(layer "F.Cu")
		(net "SMB_2_PLD_3V3AUX_SDA_R1")
	)
	(via
		(at 205.14056 -128.694688)
		(size 0.508)
		(drill 0.254)
		(layers "F.Cu" "B.Cu")
		(net "SMB_2_PLD_3V3AUX_SDA_R1")
	)
	(via
		(at 183.385206 -89.213436)
		(size 0.508)
		(drill 0.254)
		(layers "F.Cu" "B.Cu")
		(net "SMB_2_PLD_3V3AUX_SDA_R1")
	)
	(via
		(at 179.35575 -121.375424)
		(size 0.4572)
		(drill 0.254)
		(layers "F.Cu" "B.Cu")
		(net "SMB_2_PLD_3V3AUX_SDA_R1")
	)
	(via
		(at 160.6042 -26.535888)
		(size 0.508)
		(drill 0.254)
		(layers "F.Cu" "B.Cu")
		(net "SMB_2_PLD_3V3AUX_SDA_R1")
	)
	(segment
		(start 211.328 -120.805448)
		(end 211.328 -118.0338)
		(width 0.12954)
		(layer "B.Cu")
		(net "SMB_2_PLD_3V3AUX_SDA_R1")
	)
	(segment
		(start 205.14056 -128.694688)
		(end 205.14056 -126.992888)
		(width 0.12954)
		(layer "B.Cu")
		(net "SMB_2_PLD_3V3AUX_SDA_R1")
	)
	(segment
		(start 205.14056 -126.992888)
		(end 211.328 -120.805448)
		(width 0.12954)
		(layer "B.Cu")
		(net "SMB_2_PLD_3V3AUX_SDA_R1")
	)
	(segment
		(start 194.103752 -96.393)
		(end 188.693552 -90.9828)
		(width 0.12954)
		(layer "B.Cu")
		(net "SMB_2_PLD_3V3AUX_SDA_R1")
	)
	(segment
		(start 188.693552 -90.9828)
		(end 186.842146 -90.9828)
		(width 0.12954)
		(layer "B.Cu")
		(net "SMB_2_PLD_3V3AUX_SDA_R1")
	)
	(segment
		(start 185.191146 -89.3318)
		(end 183.50357 -89.3318)
		(width 0.12954)
		(layer "B.Cu")
		(net "SMB_2_PLD_3V3AUX_SDA_R1")
	)
	(segment
		(start 211.328 -118.0338)
		(end 210.172046 -116.877846)
		(width 0.12954)
		(layer "B.Cu")
		(net "SMB_2_PLD_3V3AUX_SDA_R1")
	)
	(segment
		(start 207.645 -105.016554)
		(end 207.55991 -104.931464)
		(width 0.12954)
		(layer "B.Cu")
		(net "SMB_2_PLD_3V3AUX_SDA_R1")
	)
	(segment
		(start 207.61071 -101.059742)
		(end 202.943968 -96.393)
		(width 0.12954)
		(layer "B.Cu")
		(net "SMB_2_PLD_3V3AUX_SDA_R1")
	)
	(segment
		(start 207.645 -101.236272)
		(end 207.61071 -101.201982)
		(width 0.12954)
		(layer "B.Cu")
		(net "SMB_2_PLD_3V3AUX_SDA_R1")
	)
	(segment
		(start 210.172046 -115.328954)
		(end 207.645 -112.801908)
		(width 0.12954)
		(layer "B.Cu")
		(net "SMB_2_PLD_3V3AUX_SDA_R1")
	)
	(segment
		(start 202.943968 -96.393)
		(end 194.103752 -96.393)
		(width 0.12954)
		(layer "B.Cu")
		(net "SMB_2_PLD_3V3AUX_SDA_R1")
	)
	(segment
		(start 210.172046 -116.877846)
		(end 210.172046 -115.328954)
		(width 0.12954)
		(layer "B.Cu")
		(net "SMB_2_PLD_3V3AUX_SDA_R1")
	)
	(segment
		(start 207.55991 -104.498648)
		(end 207.645 -104.413558)
		(width 0.12954)
		(layer "B.Cu")
		(net "SMB_2_PLD_3V3AUX_SDA_R1")
	)
	(segment
		(start 207.61071 -101.201982)
		(end 207.61071 -101.059742)
		(width 0.12954)
		(layer "B.Cu")
		(net "SMB_2_PLD_3V3AUX_SDA_R1")
	)
	(segment
		(start 183.50357 -89.3318)
		(end 183.385206 -89.213436)
		(width 0.12954)
		(layer "B.Cu")
		(net "SMB_2_PLD_3V3AUX_SDA_R1")
	)
	(segment
		(start 186.842146 -90.9828)
		(end 185.191146 -89.3318)
		(width 0.12954)
		(layer "B.Cu")
		(net "SMB_2_PLD_3V3AUX_SDA_R1")
	)
	(segment
		(start 207.645 -112.801908)
		(end 207.645 -105.016554)
		(width 0.12954)
		(layer "B.Cu")
		(net "SMB_2_PLD_3V3AUX_SDA_R1")
	)
	(segment
		(start 207.645 -104.413558)
		(end 207.645 -101.236272)
		(width 0.12954)
		(layer "B.Cu")
		(net "SMB_2_PLD_3V3AUX_SDA_R1")
	)
	(segment
		(start 207.55991 -104.931464)
		(end 207.55991 -104.498648)
		(width 0.12954)
		(layer "B.Cu")
		(net "SMB_2_PLD_3V3AUX_SDA_R1")
	)
	(segment
		(start 161.52114 -25.618948)
		(end 160.6042 -26.535888)
		(width 0.127)
		(layer "In2.Cu")
		(net "SMB_2_PLD_3V3AUX_SDA_R1")
	)
	(segment
		(start 182.350664 -89.213436)
		(end 180.810916 -87.673688)
		(width 0.127)
		(layer "In2.Cu")
		(net "SMB_2_PLD_3V3AUX_SDA_R1")
	)
	(segment
		(start 183.385206 -89.213436)
		(end 182.350664 -89.213436)
		(width 0.127)
		(layer "In2.Cu")
		(net "SMB_2_PLD_3V3AUX_SDA_R1")
	)
	(segment
		(start 166.9542 -80.114648)
		(end 166.9542 -29.644848)
		(width 0.127)
		(layer "In2.Cu")
		(net "SMB_2_PLD_3V3AUX_SDA_R1")
	)
	(segment
		(start 180.810916 -87.673688)
		(end 174.51324 -87.673688)
		(width 0.127)
		(layer "In2.Cu")
		(net "SMB_2_PLD_3V3AUX_SDA_R1")
	)
	(segment
		(start 166.9542 -29.644848)
		(end 162.9283 -25.618948)
		(width 0.127)
		(layer "In2.Cu")
		(net "SMB_2_PLD_3V3AUX_SDA_R1")
	)
	(segment
		(start 174.51324 -87.673688)
		(end 166.9542 -80.114648)
		(width 0.127)
		(layer "In2.Cu")
		(net "SMB_2_PLD_3V3AUX_SDA_R1")
	)
	(segment
		(start 162.9283 -25.618948)
		(end 161.52114 -25.618948)
		(width 0.127)
		(layer "In2.Cu")
		(net "SMB_2_PLD_3V3AUX_SDA_R1")
	)
	(segment
		(start 192.694306 -130.581654)
		(end 193.848482 -130.581654)
		(width 0.127)
		(layer "In15.Cu")
		(net "SMB_2_PLD_3V3AUX_SDA_R1")
	)
	(segment
		(start 199.7837 -130.800348)
		(end 201.88936 -128.694688)
		(width 0.127)
		(layer "In15.Cu")
		(net "SMB_2_PLD_3V3AUX_SDA_R1")
	)
	(segment
		(start 179.789074 -121.808748)
		(end 181.75478 -121.808748)
		(width 0.127)
		(layer "In15.Cu")
		(net "SMB_2_PLD_3V3AUX_SDA_R1")
	)
	(segment
		(start 179.35575 -121.375424)
		(end 179.789074 -121.808748)
		(width 0.127)
		(layer "In15.Cu")
		(net "SMB_2_PLD_3V3AUX_SDA_R1")
	)
	(segment
		(start 187.01258 -127.066548)
		(end 187.452 -127.066548)
		(width 0.127)
		(layer "In15.Cu")
		(net "SMB_2_PLD_3V3AUX_SDA_R1")
	)
	(segment
		(start 187.833 -127.447548)
		(end 189.5602 -127.447548)
		(width 0.127)
		(layer "In15.Cu")
		(net "SMB_2_PLD_3V3AUX_SDA_R1")
	)
	(segment
		(start 189.5602 -127.447548)
		(end 192.694306 -130.581654)
		(width 0.127)
		(layer "In15.Cu")
		(net "SMB_2_PLD_3V3AUX_SDA_R1")
	)
	(segment
		(start 201.88936 -128.694688)
		(end 205.14056 -128.694688)
		(width 0.127)
		(layer "In15.Cu")
		(net "SMB_2_PLD_3V3AUX_SDA_R1")
	)
	(segment
		(start 181.75478 -121.808748)
		(end 187.01258 -127.066548)
		(width 0.127)
		(layer "In15.Cu")
		(net "SMB_2_PLD_3V3AUX_SDA_R1")
	)
	(segment
		(start 187.452 -127.066548)
		(end 187.833 -127.447548)
		(width 0.127)
		(layer "In15.Cu")
		(net "SMB_2_PLD_3V3AUX_SDA_R1")
	)
	(segment
		(start 194.067176 -130.800348)
		(end 199.7837 -130.800348)
		(width 0.127)
		(layer "In15.Cu")
		(net "SMB_2_PLD_3V3AUX_SDA_R1")
	)
	(segment
		(start 193.848482 -130.581654)
		(end 194.067176 -130.800348)
		(width 0.127)
		(layer "In15.Cu")
		(net "SMB_2_PLD_3V3AUX_SDA_R1")
	)
	(segment
		(start 163.58616 -22.973538)
		(end 162.973512 -22.36089)
		(width 0.12954)
		(layer "F.Cu")
		(net "SMB_2_PLD_3V3AUX_SCL_R1")
	)
	(segment
		(start 163.58616 -25.605994)
		(end 163.58616 -22.973538)
		(width 0.12954)
		(layer "F.Cu")
		(net "SMB_2_PLD_3V3AUX_SCL_R1")
	)
	(segment
		(start 162.534854 -26.279348)
		(end 162.912806 -26.279348)
		(width 0.12954)
		(layer "F.Cu")
		(net "SMB_2_PLD_3V3AUX_SCL_R1")
	)
	(segment
		(start 178.9557 -121.775474)
		(end 179.35575 -122.175524)
		(width 0.12954)
		(layer "F.Cu")
		(net "SMB_2_PLD_3V3AUX_SCL_R1")
	)
	(segment
		(start 162.912806 -26.279348)
		(end 163.58616 -25.605994)
		(width 0.12954)
		(layer "F.Cu")
		(net "SMB_2_PLD_3V3AUX_SCL_R1")
	)
	(via
		(at 162.534854 -26.279348)
		(size 0.508)
		(drill 0.254)
		(layers "F.Cu" "B.Cu")
		(net "SMB_2_PLD_3V3AUX_SCL_R1")
	)
	(via
		(at 184.123838 -89.887298)
		(size 0.508)
		(drill 0.254)
		(layers "F.Cu" "B.Cu")
		(net "SMB_2_PLD_3V3AUX_SCL_R1")
	)
	(via
		(at 179.35575 -122.175524)
		(size 0.4572)
		(drill 0.254)
		(layers "F.Cu" "B.Cu")
		(net "SMB_2_PLD_3V3AUX_SCL_R1")
	)
	(via
		(at 204.58938 -129.672588)
		(size 0.508)
		(drill 0.254)
		(layers "F.Cu" "B.Cu")
		(net "SMB_2_PLD_3V3AUX_SCL_R1")
	)
	(segment
		(start 188.536326 -91.44)
		(end 186.436 -91.44)
		(width 0.12954)
		(layer "B.Cu")
		(net "SMB_2_PLD_3V3AUX_SCL_R1")
	)
	(segment
		(start 206.5274 -101.111304)
		(end 206.5274 -100.903278)
		(width 0.12954)
		(layer "B.Cu")
		(net "SMB_2_PLD_3V3AUX_SCL_R1")
	)
	(segment
		(start 204.58938 -126.883668)
		(end 210.67268 -120.800368)
		(width 0.12954)
		(layer "B.Cu")
		(net "SMB_2_PLD_3V3AUX_SCL_R1")
	)
	(segment
		(start 209.378296 -116.917216)
		(end 209.378296 -115.46205)
		(width 0.12954)
		(layer "B.Cu")
		(net "SMB_2_PLD_3V3AUX_SCL_R1")
	)
	(segment
		(start 186.436 -91.44)
		(end 184.883298 -89.887298)
		(width 0.12954)
		(layer "B.Cu")
		(net "SMB_2_PLD_3V3AUX_SCL_R1")
	)
	(segment
		(start 209.378296 -115.46205)
		(end 206.5782 -112.661954)
		(width 0.12954)
		(layer "B.Cu")
		(net "SMB_2_PLD_3V3AUX_SCL_R1")
	)
	(segment
		(start 210.67268 -118.2116)
		(end 209.378296 -116.917216)
		(width 0.12954)
		(layer "B.Cu")
		(net "SMB_2_PLD_3V3AUX_SCL_R1")
	)
	(segment
		(start 210.67268 -120.800368)
		(end 210.67268 -118.2116)
		(width 0.12954)
		(layer "B.Cu")
		(net "SMB_2_PLD_3V3AUX_SCL_R1")
	)
	(segment
		(start 194.144646 -97.04832)
		(end 188.536326 -91.44)
		(width 0.12954)
		(layer "B.Cu")
		(net "SMB_2_PLD_3V3AUX_SCL_R1")
	)
	(segment
		(start 206.5782 -101.162104)
		(end 206.5274 -101.111304)
		(width 0.12954)
		(layer "B.Cu")
		(net "SMB_2_PLD_3V3AUX_SCL_R1")
	)
	(segment
		(start 206.5782 -112.661954)
		(end 206.5782 -101.162104)
		(width 0.12954)
		(layer "B.Cu")
		(net "SMB_2_PLD_3V3AUX_SCL_R1")
	)
	(segment
		(start 204.58938 -129.672588)
		(end 204.58938 -126.883668)
		(width 0.12954)
		(layer "B.Cu")
		(net "SMB_2_PLD_3V3AUX_SCL_R1")
	)
	(segment
		(start 206.5274 -100.903278)
		(end 202.672442 -97.04832)
		(width 0.12954)
		(layer "B.Cu")
		(net "SMB_2_PLD_3V3AUX_SCL_R1")
	)
	(segment
		(start 184.883298 -89.887298)
		(end 184.123838 -89.887298)
		(width 0.12954)
		(layer "B.Cu")
		(net "SMB_2_PLD_3V3AUX_SCL_R1")
	)
	(segment
		(start 202.672442 -97.04832)
		(end 194.144646 -97.04832)
		(width 0.12954)
		(layer "B.Cu")
		(net "SMB_2_PLD_3V3AUX_SCL_R1")
	)
	(segment
		(start 184.123838 -89.887298)
		(end 182.413656 -89.887298)
		(width 0.127)
		(layer "In2.Cu")
		(net "SMB_2_PLD_3V3AUX_SCL_R1")
	)
	(segment
		(start 162.661854 -26.279348)
		(end 162.534854 -26.279348)
		(width 0.127)
		(layer "In2.Cu")
		(net "SMB_2_PLD_3V3AUX_SCL_R1")
	)
	(segment
		(start 182.413656 -89.887298)
		(end 180.855366 -88.329008)
		(width 0.127)
		(layer "In2.Cu")
		(net "SMB_2_PLD_3V3AUX_SCL_R1")
	)
	(segment
		(start 166.29888 -80.386174)
		(end 166.29888 -29.916374)
		(width 0.127)
		(layer "In2.Cu")
		(net "SMB_2_PLD_3V3AUX_SCL_R1")
	)
	(segment
		(start 166.29888 -29.916374)
		(end 162.661854 -26.279348)
		(width 0.127)
		(layer "In2.Cu")
		(net "SMB_2_PLD_3V3AUX_SCL_R1")
	)
	(segment
		(start 180.855366 -88.329008)
		(end 174.241714 -88.329008)
		(width 0.127)
		(layer "In2.Cu")
		(net "SMB_2_PLD_3V3AUX_SCL_R1")
	)
	(segment
		(start 174.241714 -88.329008)
		(end 166.29888 -80.386174)
		(width 0.127)
		(layer "In2.Cu")
		(net "SMB_2_PLD_3V3AUX_SCL_R1")
	)
	(segment
		(start 204.05852 -129.141728)
		(end 202.053444 -129.141728)
		(width 0.127)
		(layer "In15.Cu")
		(net "SMB_2_PLD_3V3AUX_SCL_R1")
	)
	(segment
		(start 202.053444 -129.141728)
		(end 199.963024 -131.232148)
		(width 0.127)
		(layer "In15.Cu")
		(net "SMB_2_PLD_3V3AUX_SCL_R1")
	)
	(segment
		(start 193.669412 -131.013454)
		(end 192.414906 -131.013454)
		(width 0.127)
		(layer "In15.Cu")
		(net "SMB_2_PLD_3V3AUX_SCL_R1")
	)
	(segment
		(start 181.481476 -122.175524)
		(end 179.35575 -122.175524)
		(width 0.127)
		(layer "In15.Cu")
		(net "SMB_2_PLD_3V3AUX_SCL_R1")
	)
	(segment
		(start 191.0334 -129.631948)
		(end 189.3824 -129.631948)
		(width 0.127)
		(layer "In15.Cu")
		(net "SMB_2_PLD_3V3AUX_SCL_R1")
	)
	(segment
		(start 186.8043 -127.498348)
		(end 181.481476 -122.175524)
		(width 0.127)
		(layer "In15.Cu")
		(net "SMB_2_PLD_3V3AUX_SCL_R1")
	)
	(segment
		(start 192.414906 -131.013454)
		(end 191.0334 -129.631948)
		(width 0.127)
		(layer "In15.Cu")
		(net "SMB_2_PLD_3V3AUX_SCL_R1")
	)
	(segment
		(start 189.3824 -129.631948)
		(end 187.2488 -127.498348)
		(width 0.127)
		(layer "In15.Cu")
		(net "SMB_2_PLD_3V3AUX_SCL_R1")
	)
	(segment
		(start 187.2488 -127.498348)
		(end 186.8043 -127.498348)
		(width 0.127)
		(layer "In15.Cu")
		(net "SMB_2_PLD_3V3AUX_SCL_R1")
	)
	(segment
		(start 193.888106 -131.232148)
		(end 193.669412 -131.013454)
		(width 0.127)
		(layer "In15.Cu")
		(net "SMB_2_PLD_3V3AUX_SCL_R1")
	)
	(segment
		(start 204.58938 -129.672588)
		(end 204.05852 -129.141728)
		(width 0.127)
		(layer "In15.Cu")
		(net "SMB_2_PLD_3V3AUX_SCL_R1")
	)
	(segment
		(start 199.963024 -131.232148)
		(end 193.888106 -131.232148)
		(width 0.127)
		(layer "In15.Cu")
		(net "SMB_2_PLD_3V3AUX_SCL_R1")
	)
	(segment
		(start 161.24428 -28.240228)
		(end 161.24428 -26.115518)
		(width 0.12954)
		(layer "F.Cu")
		(net "SMB_1_PLD_3V3AUX_SDA_R1")
	)
	(segment
		(start 169.201338 -113.77549)
		(end 170.155616 -113.77549)
		(width 0.12954)
		(layer "F.Cu")
		(net "SMB_1_PLD_3V3AUX_SDA_R1")
	)
	(segment
		(start 165.04793 -116.296948)
		(end 165.65753 -116.296948)
		(width 0.12954)
		(layer "F.Cu")
		(net "SMB_1_PLD_3V3AUX_SDA_R1")
	)
	(segment
		(start 160.360868 -25.232106)
		(end 160.360868 -23.398226)
		(width 0.12954)
		(layer "F.Cu")
		(net "SMB_1_PLD_3V3AUX_SDA_R1")
	)
	(segment
		(start 166.67988 -116.296948)
		(end 169.201338 -113.77549)
		(width 0.12954)
		(layer "F.Cu")
		(net "SMB_1_PLD_3V3AUX_SDA_R1")
	)
	(segment
		(start 161.24428 -26.115518)
		(end 160.360868 -25.232106)
		(width 0.12954)
		(layer "F.Cu")
		(net "SMB_1_PLD_3V3AUX_SDA_R1")
	)
	(segment
		(start 162.55238 -28.928568)
		(end 161.93262 -28.928568)
		(width 0.12954)
		(layer "F.Cu")
		(net "SMB_1_PLD_3V3AUX_SDA_R1")
	)
	(segment
		(start 161.93262 -28.928568)
		(end 161.24428 -28.240228)
		(width 0.12954)
		(layer "F.Cu")
		(net "SMB_1_PLD_3V3AUX_SDA_R1")
	)
	(segment
		(start 165.65753 -116.296948)
		(end 166.67988 -116.296948)
		(width 0.12954)
		(layer "F.Cu")
		(net "SMB_1_PLD_3V3AUX_SDA_R1")
	)
	(via
		(at 160.07588 -79.847948)
		(size 0.508)
		(drill 0.254)
		(layers "F.Cu" "B.Cu")
		(net "SMB_1_PLD_3V3AUX_SDA_R1")
	)
	(via
		(at 162.55238 -28.928568)
		(size 0.508)
		(drill 0.254)
		(layers "F.Cu" "B.Cu")
		(net "SMB_1_PLD_3V3AUX_SDA_R1")
	)
	(via
		(at 165.65753 -116.296948)
		(size 0.508)
		(drill 0.254)
		(layers "F.Cu" "B.Cu")
		(net "SMB_1_PLD_3V3AUX_SDA_R1")
	)
	(segment
		(start 161.302192 -70.305422)
		(end 161.302192 -78.621636)
		(width 0.127)
		(layer "In2.Cu")
		(net "SMB_1_PLD_3V3AUX_SDA_R1")
	)
	(segment
		(start 164.11956 -47.640748)
		(end 161.14268 -50.617628)
		(width 0.127)
		(layer "In2.Cu")
		(net "SMB_1_PLD_3V3AUX_SDA_R1")
	)
	(segment
		(start 161.14268 -70.14591)
		(end 161.302192 -70.305422)
		(width 0.127)
		(layer "In2.Cu")
		(net "SMB_1_PLD_3V3AUX_SDA_R1")
	)
	(segment
		(start 162.55238 -28.928568)
		(end 164.11956 -30.495748)
		(width 0.127)
		(layer "In2.Cu")
		(net "SMB_1_PLD_3V3AUX_SDA_R1")
	)
	(segment
		(start 161.302192 -78.621636)
		(end 160.07588 -79.847948)
		(width 0.127)
		(layer "In2.Cu")
		(net "SMB_1_PLD_3V3AUX_SDA_R1")
	)
	(segment
		(start 164.11956 -30.495748)
		(end 164.11956 -47.640748)
		(width 0.127)
		(layer "In2.Cu")
		(net "SMB_1_PLD_3V3AUX_SDA_R1")
	)
	(segment
		(start 161.14268 -50.617628)
		(end 161.14268 -70.14591)
		(width 0.127)
		(layer "In2.Cu")
		(net "SMB_1_PLD_3V3AUX_SDA_R1")
	)
	(segment
		(start 159.12211 -99.663758)
		(end 160.8709 -97.914968)
		(width 0.127)
		(layer "In13.Cu")
		(net "SMB_1_PLD_3V3AUX_SDA_R1")
	)
	(segment
		(start 160.8709 -109.421168)
		(end 160.8709 -103.736648)
		(width 0.127)
		(layer "In13.Cu")
		(net "SMB_1_PLD_3V3AUX_SDA_R1")
	)
	(segment
		(start 163.0934 -110.200948)
		(end 161.65068 -110.200948)
		(width 0.127)
		(layer "In13.Cu")
		(net "SMB_1_PLD_3V3AUX_SDA_R1")
	)
	(segment
		(start 160.1978 -103.063548)
		(end 159.4612 -103.063548)
		(width 0.127)
		(layer "In13.Cu")
		(net "SMB_1_PLD_3V3AUX_SDA_R1")
	)
	(segment
		(start 160.07588 -79.3623)
		(end 160.07588 -79.847948)
		(width 0.127)
		(layer "In13.Cu")
		(net "SMB_1_PLD_3V3AUX_SDA_R1")
	)
	(segment
		(start 161.65068 -110.200948)
		(end 160.8709 -109.421168)
		(width 0.127)
		(layer "In13.Cu")
		(net "SMB_1_PLD_3V3AUX_SDA_R1")
	)
	(segment
		(start 165.65753 -116.296948)
		(end 164.72408 -115.363498)
		(width 0.127)
		(layer "In13.Cu")
		(net "SMB_1_PLD_3V3AUX_SDA_R1")
	)
	(segment
		(start 159.4612 -103.063548)
		(end 159.12211 -102.724458)
		(width 0.127)
		(layer "In13.Cu")
		(net "SMB_1_PLD_3V3AUX_SDA_R1")
	)
	(segment
		(start 164.72408 -115.363498)
		(end 164.72408 -111.853218)
		(width 0.127)
		(layer "In13.Cu")
		(net "SMB_1_PLD_3V3AUX_SDA_R1")
	)
	(segment
		(start 163.2204 -110.349538)
		(end 163.2204 -110.327948)
		(width 0.127)
		(layer "In13.Cu")
		(net "SMB_1_PLD_3V3AUX_SDA_R1")
	)
	(segment
		(start 161.036 -79.06004)
		(end 160.37814 -79.06004)
		(width 0.127)
		(layer "In13.Cu")
		(net "SMB_1_PLD_3V3AUX_SDA_R1")
	)
	(segment
		(start 160.8709 -97.914968)
		(end 160.8709 -83.21548)
		(width 0.127)
		(layer "In13.Cu")
		(net "SMB_1_PLD_3V3AUX_SDA_R1")
	)
	(segment
		(start 161.45002 -79.47406)
		(end 161.036 -79.06004)
		(width 0.127)
		(layer "In13.Cu")
		(net "SMB_1_PLD_3V3AUX_SDA_R1")
	)
	(segment
		(start 160.8709 -83.21548)
		(end 161.45002 -82.63636)
		(width 0.127)
		(layer "In13.Cu")
		(net "SMB_1_PLD_3V3AUX_SDA_R1")
	)
	(segment
		(start 159.12211 -102.724458)
		(end 159.12211 -99.663758)
		(width 0.127)
		(layer "In13.Cu")
		(net "SMB_1_PLD_3V3AUX_SDA_R1")
	)
	(segment
		(start 160.37814 -79.06004)
		(end 160.07588 -79.3623)
		(width 0.127)
		(layer "In13.Cu")
		(net "SMB_1_PLD_3V3AUX_SDA_R1")
	)
	(segment
		(start 163.2204 -110.327948)
		(end 163.0934 -110.200948)
		(width 0.127)
		(layer "In13.Cu")
		(net "SMB_1_PLD_3V3AUX_SDA_R1")
	)
	(segment
		(start 160.8709 -103.736648)
		(end 160.1978 -103.063548)
		(width 0.127)
		(layer "In13.Cu")
		(net "SMB_1_PLD_3V3AUX_SDA_R1")
	)
	(segment
		(start 161.45002 -82.63636)
		(end 161.45002 -79.47406)
		(width 0.127)
		(layer "In13.Cu")
		(net "SMB_1_PLD_3V3AUX_SDA_R1")
	)
	(segment
		(start 164.72408 -111.853218)
		(end 163.2204 -110.349538)
		(width 0.127)
		(layer "In13.Cu")
		(net "SMB_1_PLD_3V3AUX_SDA_R1")
	)
	(segment
		(start 165.840664 -116.731288)
		(end 165.640004 -116.931948)
		(width 0.12954)
		(layer "F.Cu")
		(net "SMB_1_PLD_3V3AUX_SCL_R1")
	)
	(segment
		(start 162.56 -27.569668)
		(end 161.798 -26.807668)
		(width 0.12954)
		(layer "F.Cu")
		(net "SMB_1_PLD_3V3AUX_SCL_R1")
	)
	(segment
		(start 162.717226 -116.931948)
		(end 162.082226 -116.296948)
		(width 0.12954)
		(layer "F.Cu")
		(net "SMB_1_PLD_3V3AUX_SCL_R1")
	)
	(segment
		(start 170.955716 -113.77549)
		(end 170.567858 -114.163348)
		(width 0.12954)
		(layer "F.Cu")
		(net "SMB_1_PLD_3V3AUX_SCL_R1")
	)
	(segment
		(start 170.567858 -114.163348)
		(end 169.57548 -114.163348)
		(width 0.12954)
		(layer "F.Cu")
		(net "SMB_1_PLD_3V3AUX_SCL_R1")
	)
	(segment
		(start 161.798 -26.807668)
		(end 161.798 -25.972516)
		(width 0.12954)
		(layer "F.Cu")
		(net "SMB_1_PLD_3V3AUX_SCL_R1")
	)
	(segment
		(start 165.640004 -116.931948)
		(end 162.717226 -116.931948)
		(width 0.12954)
		(layer "F.Cu")
		(net "SMB_1_PLD_3V3AUX_SCL_R1")
	)
	(segment
		(start 169.57548 -114.163348)
		(end 167.00754 -116.731288)
		(width 0.12954)
		(layer "F.Cu")
		(net "SMB_1_PLD_3V3AUX_SCL_R1")
	)
	(segment
		(start 162.699446 -25.758648)
		(end 162.963352 -25.494742)
		(width 0.12954)
		(layer "F.Cu")
		(net "SMB_1_PLD_3V3AUX_SCL_R1")
	)
	(segment
		(start 161.23793 -116.296948)
		(end 161.84753 -116.296948)
		(width 0.12954)
		(layer "F.Cu")
		(net "SMB_1_PLD_3V3AUX_SCL_R1")
	)
	(segment
		(start 162.011868 -25.758648)
		(end 162.699446 -25.758648)
		(width 0.12954)
		(layer "F.Cu")
		(net "SMB_1_PLD_3V3AUX_SCL_R1")
	)
	(segment
		(start 162.082226 -116.296948)
		(end 161.84753 -116.296948)
		(width 0.12954)
		(layer "F.Cu")
		(net "SMB_1_PLD_3V3AUX_SCL_R1")
	)
	(segment
		(start 162.963352 -25.494742)
		(end 162.963352 -23.38959)
		(width 0.12954)
		(layer "F.Cu")
		(net "SMB_1_PLD_3V3AUX_SCL_R1")
	)
	(segment
		(start 161.798 -25.972516)
		(end 162.011868 -25.758648)
		(width 0.12954)
		(layer "F.Cu")
		(net "SMB_1_PLD_3V3AUX_SCL_R1")
	)
	(segment
		(start 167.00754 -116.731288)
		(end 165.840664 -116.731288)
		(width 0.12954)
		(layer "F.Cu")
		(net "SMB_1_PLD_3V3AUX_SCL_R1")
	)
	(via
		(at 162.56 -27.569668)
		(size 0.508)
		(drill 0.254)
		(layers "F.Cu" "B.Cu")
		(net "SMB_1_PLD_3V3AUX_SCL_R1")
	)
	(via
		(at 160.8709 -79.847948)
		(size 0.508)
		(drill 0.254)
		(layers "F.Cu" "B.Cu")
		(net "SMB_1_PLD_3V3AUX_SCL_R1")
	)
	(via
		(at 161.84753 -116.296948)
		(size 0.508)
		(drill 0.254)
		(layers "F.Cu" "B.Cu")
		(net "SMB_1_PLD_3V3AUX_SCL_R1")
	)
	(segment
		(start 162.14725 -70.913498)
		(end 161.80308 -70.569328)
		(width 0.127)
		(layer "In2.Cu")
		(net "SMB_1_PLD_3V3AUX_SCL_R1")
	)
	(segment
		(start 164.57676 -29.586428)
		(end 162.56 -27.569668)
		(width 0.127)
		(layer "In2.Cu")
		(net "SMB_1_PLD_3V3AUX_SCL_R1")
	)
	(segment
		(start 161.80308 -50.617628)
		(end 164.57676 -47.843948)
		(width 0.127)
		(layer "In2.Cu")
		(net "SMB_1_PLD_3V3AUX_SCL_R1")
	)
	(segment
		(start 160.8709 -79.847948)
		(end 162.14725 -78.571598)
		(width 0.127)
		(layer "In2.Cu")
		(net "SMB_1_PLD_3V3AUX_SCL_R1")
	)
	(segment
		(start 161.80308 -70.569328)
		(end 161.80308 -50.617628)
		(width 0.127)
		(layer "In2.Cu")
		(net "SMB_1_PLD_3V3AUX_SCL_R1")
	)
	(segment
		(start 164.57676 -47.843948)
		(end 164.57676 -29.586428)
		(width 0.127)
		(layer "In2.Cu")
		(net "SMB_1_PLD_3V3AUX_SCL_R1")
	)
	(segment
		(start 162.14725 -78.571598)
		(end 162.14725 -70.913498)
		(width 0.127)
		(layer "In2.Cu")
		(net "SMB_1_PLD_3V3AUX_SCL_R1")
	)
	(segment
		(start 163.1061 -111.665766)
		(end 163.1061 -111.27613)
		(width 0.127)
		(layer "In13.Cu")
		(net "SMB_1_PLD_3V3AUX_SCL_R1")
	)
	(segment
		(start 160.8709 -81.55432)
		(end 160.8709 -79.847948)
		(width 0.127)
		(layer "In13.Cu")
		(net "SMB_1_PLD_3V3AUX_SCL_R1")
	)
	(segment
		(start 158.65856 -99.294188)
		(end 160.43148 -97.521268)
		(width 0.127)
		(layer "In13.Cu")
		(net "SMB_1_PLD_3V3AUX_SCL_R1")
	)
	(segment
		(start 160.43148 -81.99374)
		(end 160.8709 -81.55432)
		(width 0.127)
		(layer "In13.Cu")
		(net "SMB_1_PLD_3V3AUX_SCL_R1")
	)
	(segment
		(start 161.29508 -110.632748)
		(end 160.43148 -109.769148)
		(width 0.127)
		(layer "In13.Cu")
		(net "SMB_1_PLD_3V3AUX_SCL_R1")
	)
	(segment
		(start 162.599878 -115.5446)
		(end 163.93414 -115.5446)
		(width 0.127)
		(layer "In13.Cu")
		(net "SMB_1_PLD_3V3AUX_SCL_R1")
	)
	(segment
		(start 160.43148 -104.430576)
		(end 159.585152 -103.584248)
		(width 0.127)
		(layer "In13.Cu")
		(net "SMB_1_PLD_3V3AUX_SCL_R1")
	)
	(segment
		(start 164.26688 -112.826546)
		(end 163.1061 -111.665766)
		(width 0.127)
		(layer "In13.Cu")
		(net "SMB_1_PLD_3V3AUX_SCL_R1")
	)
	(segment
		(start 164.26688 -115.21186)
		(end 164.26688 -112.826546)
		(width 0.127)
		(layer "In13.Cu")
		(net "SMB_1_PLD_3V3AUX_SCL_R1")
	)
	(segment
		(start 163.93414 -115.5446)
		(end 164.26688 -115.21186)
		(width 0.127)
		(layer "In13.Cu")
		(net "SMB_1_PLD_3V3AUX_SCL_R1")
	)
	(segment
		(start 163.109148 -111.272828)
		(end 162.469068 -110.632748)
		(width 0.127)
		(layer "In13.Cu")
		(net "SMB_1_PLD_3V3AUX_SCL_R1")
	)
	(segment
		(start 160.43148 -109.769148)
		(end 160.43148 -104.430576)
		(width 0.127)
		(layer "In13.Cu")
		(net "SMB_1_PLD_3V3AUX_SCL_R1")
	)
	(segment
		(start 162.469068 -110.632748)
		(end 161.29508 -110.632748)
		(width 0.127)
		(layer "In13.Cu")
		(net "SMB_1_PLD_3V3AUX_SCL_R1")
	)
	(segment
		(start 160.43148 -97.521268)
		(end 160.43148 -81.99374)
		(width 0.127)
		(layer "In13.Cu")
		(net "SMB_1_PLD_3V3AUX_SCL_R1")
	)
	(segment
		(start 158.65856 -102.948994)
		(end 158.65856 -99.294188)
		(width 0.127)
		(layer "In13.Cu")
		(net "SMB_1_PLD_3V3AUX_SCL_R1")
	)
	(segment
		(start 159.293814 -103.584248)
		(end 158.65856 -102.948994)
		(width 0.127)
		(layer "In13.Cu")
		(net "SMB_1_PLD_3V3AUX_SCL_R1")
	)
	(segment
		(start 161.84753 -116.296948)
		(end 162.599878 -115.5446)
		(width 0.127)
		(layer "In13.Cu")
		(net "SMB_1_PLD_3V3AUX_SCL_R1")
	)
	(segment
		(start 163.1061 -111.27613)
		(end 163.109148 -111.272828)
		(width 0.127)
		(layer "In13.Cu")
		(net "SMB_1_PLD_3V3AUX_SCL_R1")
	)
	(segment
		(start 159.585152 -103.584248)
		(end 159.293814 -103.584248)
		(width 0.127)
		(layer "In13.Cu")
		(net "SMB_1_PLD_3V3AUX_SCL_R1")
	)
	(segment
		(start 134.245096 -41.190418)
		(end 134.868412 -41.190418)
		(width 0.12954)
		(layer "F.Cu")
		(net "RST_PCIE_PCH_DEV_PERST_M2_R_N")
	)
	(segment
		(start 133.83768 -40.985948)
		(end 134.040626 -40.985948)
		(width 0.12954)
		(layer "F.Cu")
		(net "RST_PCIE_PCH_DEV_PERST_M2_R_N")
	)
	(segment
		(start 134.040626 -40.985948)
		(end 134.245096 -41.190418)
		(width 0.12954)
		(layer "F.Cu")
		(net "RST_PCIE_PCH_DEV_PERST_M2_R_N")
	)
	(segment
		(start 205.33741 -119.344948)
		(end 205.94701 -119.344948)
		(width 0.12954)
		(layer "F.Cu")
		(net "RST_PCIE_PCH_DEV_PERST_M2_R_N")
	)
	(via
		(at 205.94701 -119.344948)
		(size 0.508)
		(drill 0.254)
		(layers "F.Cu" "B.Cu")
		(net "RST_PCIE_PCH_DEV_PERST_M2_R_N")
	)
	(via
		(at 133.83768 -40.985948)
		(size 0.508)
		(drill 0.254)
		(layers "F.Cu" "B.Cu")
		(net "RST_PCIE_PCH_DEV_PERST_M2_R_N")
	)
	(segment
		(start 136.35228 -43.500548)
		(end 133.83768 -40.985948)
		(width 0.127)
		(layer "In4.Cu")
		(net "RST_PCIE_PCH_DEV_PERST_M2_R_N")
	)
	(segment
		(start 189.308994 -83.38439)
		(end 177.746406 -83.38439)
		(width 0.127)
		(layer "In4.Cu")
		(net "RST_PCIE_PCH_DEV_PERST_M2_R_N")
	)
	(segment
		(start 198.61022 -99.314)
		(end 197.460616 -99.314)
		(width 0.127)
		(layer "In4.Cu")
		(net "RST_PCIE_PCH_DEV_PERST_M2_R_N")
	)
	(segment
		(start 200.60412 -101.3079)
		(end 198.61022 -99.314)
		(width 0.127)
		(layer "In4.Cu")
		(net "RST_PCIE_PCH_DEV_PERST_M2_R_N")
	)
	(segment
		(start 191.81826 -85.893656)
		(end 189.308994 -83.38439)
		(width 0.127)
		(layer "In4.Cu")
		(net "RST_PCIE_PCH_DEV_PERST_M2_R_N")
	)
	(segment
		(start 200.60412 -104.79532)
		(end 200.60412 -101.3079)
		(width 0.127)
		(layer "In4.Cu")
		(net "RST_PCIE_PCH_DEV_PERST_M2_R_N")
	)
	(segment
		(start 202.06208 -106.25328)
		(end 200.60412 -104.79532)
		(width 0.127)
		(layer "In4.Cu")
		(net "RST_PCIE_PCH_DEV_PERST_M2_R_N")
	)
	(segment
		(start 201.17054 -116.8273)
		(end 201.17054 -111.41202)
		(width 0.127)
		(layer "In4.Cu")
		(net "RST_PCIE_PCH_DEV_PERST_M2_R_N")
	)
	(segment
		(start 201.17054 -111.41202)
		(end 202.06208 -110.52048)
		(width 0.127)
		(layer "In4.Cu")
		(net "RST_PCIE_PCH_DEV_PERST_M2_R_N")
	)
	(segment
		(start 197.460616 -99.314)
		(end 191.81826 -93.671644)
		(width 0.127)
		(layer "In4.Cu")
		(net "RST_PCIE_PCH_DEV_PERST_M2_R_N")
	)
	(segment
		(start 205.94701 -119.344948)
		(end 205.18628 -119.344948)
		(width 0.127)
		(layer "In4.Cu")
		(net "RST_PCIE_PCH_DEV_PERST_M2_R_N")
	)
	(segment
		(start 159.741616 -66.744088)
		(end 158.550356 -65.552828)
		(width 0.127)
		(layer "In4.Cu")
		(net "RST_PCIE_PCH_DEV_PERST_M2_R_N")
	)
	(segment
		(start 204.93228 -117.9449)
		(end 204.50302 -117.51564)
		(width 0.127)
		(layer "In4.Cu")
		(net "RST_PCIE_PCH_DEV_PERST_M2_R_N")
	)
	(segment
		(start 191.81826 -93.671644)
		(end 191.81826 -85.893656)
		(width 0.127)
		(layer "In4.Cu")
		(net "RST_PCIE_PCH_DEV_PERST_M2_R_N")
	)
	(segment
		(start 204.50302 -117.51564)
		(end 201.85888 -117.51564)
		(width 0.127)
		(layer "In4.Cu")
		(net "RST_PCIE_PCH_DEV_PERST_M2_R_N")
	)
	(segment
		(start 204.93228 -119.090948)
		(end 204.93228 -117.9449)
		(width 0.127)
		(layer "In4.Cu")
		(net "RST_PCIE_PCH_DEV_PERST_M2_R_N")
	)
	(segment
		(start 202.06208 -110.52048)
		(end 202.06208 -106.25328)
		(width 0.127)
		(layer "In4.Cu")
		(net "RST_PCIE_PCH_DEV_PERST_M2_R_N")
	)
	(segment
		(start 141.61262 -52.215288)
		(end 136.35228 -46.954948)
		(width 0.127)
		(layer "In4.Cu")
		(net "RST_PCIE_PCH_DEV_PERST_M2_R_N")
	)
	(segment
		(start 136.35228 -46.954948)
		(end 136.35228 -43.500548)
		(width 0.127)
		(layer "In4.Cu")
		(net "RST_PCIE_PCH_DEV_PERST_M2_R_N")
	)
	(segment
		(start 141.61262 -60.521088)
		(end 141.61262 -52.215288)
		(width 0.127)
		(layer "In4.Cu")
		(net "RST_PCIE_PCH_DEV_PERST_M2_R_N")
	)
	(segment
		(start 205.18628 -119.344948)
		(end 204.93228 -119.090948)
		(width 0.127)
		(layer "In4.Cu")
		(net "RST_PCIE_PCH_DEV_PERST_M2_R_N")
	)
	(segment
		(start 177.746406 -83.38439)
		(end 161.106104 -66.744088)
		(width 0.127)
		(layer "In4.Cu")
		(net "RST_PCIE_PCH_DEV_PERST_M2_R_N")
	)
	(segment
		(start 161.106104 -66.744088)
		(end 159.741616 -66.744088)
		(width 0.127)
		(layer "In4.Cu")
		(net "RST_PCIE_PCH_DEV_PERST_M2_R_N")
	)
	(segment
		(start 158.550356 -65.552828)
		(end 146.64436 -65.552828)
		(width 0.127)
		(layer "In4.Cu")
		(net "RST_PCIE_PCH_DEV_PERST_M2_R_N")
	)
	(segment
		(start 201.85888 -117.51564)
		(end 201.17054 -116.8273)
		(width 0.127)
		(layer "In4.Cu")
		(net "RST_PCIE_PCH_DEV_PERST_M2_R_N")
	)
	(segment
		(start 146.64436 -65.552828)
		(end 141.61262 -60.521088)
		(width 0.127)
		(layer "In4.Cu")
		(net "RST_PCIE_PCH_DEV_PERST_M2_R_N")
	)
	(segment
		(start 305.629818 -421.770302)
		(end 305.3588 -422.04132)
		(width 0.12954)
		(layer "F.Cu")
		(net "PWRGD_P3V3_AUX_PDB_R")
	)
	(segment
		(start 305.629818 -420.63924)
		(end 305.629818 -421.770302)
		(width 0.12954)
		(layer "F.Cu")
		(net "PWRGD_P3V3_AUX_PDB_R")
	)
	(segment
		(start 305.3588 -422.53154)
		(end 305.3588 -422.04132)
		(width 0.12954)
		(layer "F.Cu")
		(net "PWRGD_P3V3_AUX_PDB_R")
	)
	(segment
		(start 306.806092 -421.92321)
		(end 306.832 -421.949118)
		(width 0.12954)
		(layer "F.Cu")
		(net "PWRGD_P3V3_AUX_PDB_R")
	)
	(segment
		(start 306.832 -422.6687)
		(end 306.54752 -422.95318)
		(width 0.12954)
		(layer "F.Cu")
		(net "PWRGD_P3V3_AUX_PDB_R")
	)
	(segment
		(start 306.54752 -422.95318)
		(end 305.78044 -422.95318)
		(width 0.12954)
		(layer "F.Cu")
		(net "PWRGD_P3V3_AUX_PDB_R")
	)
	(segment
		(start 306.832 -421.949118)
		(end 306.832 -422.6687)
		(width 0.12954)
		(layer "F.Cu")
		(net "PWRGD_P3V3_AUX_PDB_R")
	)
	(segment
		(start 305.78044 -422.95318)
		(end 305.3588 -422.53154)
		(width 0.12954)
		(layer "F.Cu")
		(net "PWRGD_P3V3_AUX_PDB_R")
	)
	(via
		(at 305.3588 -422.04132)
		(size 0.762)
		(drill 0.381)
		(layers "F.Cu" "B.Cu")
		(net "PWRGD_P3V3_AUX_PDB_R")
	)
	(segment
		(start 307.112416 -427.170342)
		(end 307.53304 -427.170342)
		(width 0.12954)
		(layer "F.Cu")
		(net "PWRGD_P3V3_AUX_PDB_BUF_R")
	)
	(segment
		(start 306.806092 -423.82313)
		(end 306.24399 -423.82313)
		(width 0.12954)
		(layer "F.Cu")
		(net "PWRGD_P3V3_AUX_PDB_BUF_R")
	)
	(segment
		(start 306.490624 -427.167802)
		(end 306.490624 -426.179742)
		(width 0.12954)
		(layer "F.Cu")
		(net "PWRGD_P3V3_AUX_PDB_BUF_R")
	)
	(segment
		(start 306.49164 -427.168818)
		(end 307.110892 -427.168818)
		(width 0.12954)
		(layer "F.Cu")
		(net "PWRGD_P3V3_AUX_PDB_BUF_R")
	)
	(segment
		(start 307.110892 -427.168818)
		(end 307.112416 -427.170342)
		(width 0.12954)
		(layer "F.Cu")
		(net "PWRGD_P3V3_AUX_PDB_BUF_R")
	)
	(segment
		(start 306.24399 -423.82313)
		(end 305.57216 -424.49496)
		(width 0.12954)
		(layer "F.Cu")
		(net "PWRGD_P3V3_AUX_PDB_BUF_R")
	)
	(segment
		(start 306.49164 -427.168818)
		(end 306.490624 -427.167802)
		(width 0.12954)
		(layer "F.Cu")
		(net "PWRGD_P3V3_AUX_PDB_BUF_R")
	)
	(segment
		(start 305.57216 -425.261278)
		(end 306.490624 -426.179742)
		(width 0.12954)
		(layer "F.Cu")
		(net "PWRGD_P3V3_AUX_PDB_BUF_R")
	)
	(segment
		(start 305.57216 -424.49496)
		(end 305.57216 -425.261278)
		(width 0.12954)
		(layer "F.Cu")
		(net "PWRGD_P3V3_AUX_PDB_BUF_R")
	)
	(via
		(at 305.57216 -424.49496)
		(size 0.762)
		(drill 0.381)
		(layers "F.Cu" "B.Cu")
		(net "PWRGD_P3V3_AUX_PDB_BUF_R")
	)
	(segment
		(start 309.030878 -427.86808)
		(end 309.17134 -427.86808)
		(width 0.12954)
		(layer "F.Cu")
		(net "PWRGD_P3V3_AUX_PDB_BUF")
	)
	(segment
		(start 308.33314 -427.170342)
		(end 309.030878 -427.86808)
		(width 0.12954)
		(layer "F.Cu")
		(net "PWRGD_P3V3_AUX_PDB_BUF")
	)
	(via
		(at 309.17134 -427.86808)
		(size 0.508)
		(drill 0.254)
		(layers "F.Cu" "B.Cu")
		(net "PWRGD_P3V3_AUX_PDB_BUF")
	)
	(segment
		(start 240.23574 -437.0197)
		(end 240.23574 -429.91532)
		(width 0.127)
		(layer "In6.Cu")
		(net "PWRGD_P3V3_AUX_PDB_BUF")
	)
	(segment
		(start 284.490414 -436.996586)
		(end 282.321 -439.166)
		(width 0.127)
		(layer "In6.Cu")
		(net "PWRGD_P3V3_AUX_PDB_BUF")
	)
	(segment
		(start 309.17134 -425.93514)
		(end 307.848 -424.6118)
		(width 0.127)
		(layer "In6.Cu")
		(net "PWRGD_P3V3_AUX_PDB_BUF")
	)
	(segment
		(start 237.46206 -429.24476)
		(end 237.08614 -429.62068)
		(width 0.127)
		(layer "In6.Cu")
		(net "PWRGD_P3V3_AUX_PDB_BUF")
	)
	(segment
		(start 307.848 -424.6118)
		(end 292.4048 -424.6118)
		(width 0.127)
		(layer "In6.Cu")
		(net "PWRGD_P3V3_AUX_PDB_BUF")
	)
	(segment
		(start 291.0586 -425.958)
		(end 285.7246 -425.958)
		(width 0.127)
		(layer "In6.Cu")
		(net "PWRGD_P3V3_AUX_PDB_BUF")
	)
	(segment
		(start 309.17134 -427.86808)
		(end 309.17134 -425.93514)
		(width 0.127)
		(layer "In6.Cu")
		(net "PWRGD_P3V3_AUX_PDB_BUF")
	)
	(segment
		(start 237.08614 -429.62068)
		(end 237.08614 -430.97196)
		(width 0.127)
		(layer "In6.Cu")
		(net "PWRGD_P3V3_AUX_PDB_BUF")
	)
	(segment
		(start 239.56518 -429.24476)
		(end 237.46206 -429.24476)
		(width 0.127)
		(layer "In6.Cu")
		(net "PWRGD_P3V3_AUX_PDB_BUF")
	)
	(segment
		(start 284.490414 -427.192186)
		(end 284.490414 -436.996586)
		(width 0.127)
		(layer "In6.Cu")
		(net "PWRGD_P3V3_AUX_PDB_BUF")
	)
	(segment
		(start 242.38204 -439.166)
		(end 240.23574 -437.0197)
		(width 0.127)
		(layer "In6.Cu")
		(net "PWRGD_P3V3_AUX_PDB_BUF")
	)
	(segment
		(start 285.7246 -425.958)
		(end 284.490414 -427.192186)
		(width 0.127)
		(layer "In6.Cu")
		(net "PWRGD_P3V3_AUX_PDB_BUF")
	)
	(segment
		(start 292.4048 -424.6118)
		(end 291.0586 -425.958)
		(width 0.127)
		(layer "In6.Cu")
		(net "PWRGD_P3V3_AUX_PDB_BUF")
	)
	(segment
		(start 240.23574 -429.91532)
		(end 239.56518 -429.24476)
		(width 0.127)
		(layer "In6.Cu")
		(net "PWRGD_P3V3_AUX_PDB_BUF")
	)
	(segment
		(start 282.321 -439.166)
		(end 242.38204 -439.166)
		(width 0.127)
		(layer "In6.Cu")
		(net "PWRGD_P3V3_AUX_PDB_BUF")
	)
	(segment
		(start 235.91012 -432.14798)
		(end 235.91012 -433.04206)
		(width 0.127)
		(layer "In6.Cu")
		(net "PWRGD_P3V3_AUX_PDB_BUF")
	)
	(segment
		(start 237.08614 -430.97196)
		(end 235.91012 -432.14798)
		(width 0.127)
		(layer "In6.Cu")
		(net "PWRGD_P3V3_AUX_PDB_BUF")
	)
	(segment
		(start 305.629818 -419.83914)
		(end 306.27828 -419.83914)
		(width 0.12954)
		(layer "F.Cu")
		(net "PWRGD_P3V3_AUX_PDB")
	)
	(via
		(at 253.47168 -324.805548)
		(size 0.508)
		(drill 0.254)
		(layers "F.Cu" "B.Cu")
		(net "PWRGD_P3V3_AUX_PDB")
	)
	(via
		(at 156.77388 -110.835948)
		(size 0.508)
		(drill 0.254)
		(layers "F.Cu" "B.Cu")
		(net "PWRGD_P3V3_AUX_PDB")
	)
	(via
		(at 306.27828 -419.83914)
		(size 0.508)
		(drill 0.254)
		(layers "F.Cu" "B.Cu")
		(net "PWRGD_P3V3_AUX_PDB")
	)
	(segment
		(start 160.233868 -112.23244)
		(end 160.249362 -112.23879)
		(width 0.12954)
		(layer "B.Cu")
		(net "PWRGD_P3V3_AUX_PDB")
	)
	(segment
		(start 160.017206 -112.015778)
		(end 160.233868 -112.23244)
		(width 0.12954)
		(layer "B.Cu")
		(net "PWRGD_P3V3_AUX_PDB")
	)
	(segment
		(start 159.34817 -111.86541)
		(end 159.348424 -111.86541)
		(width 0.12954)
		(layer "B.Cu")
		(net "PWRGD_P3V3_AUX_PDB")
	)
	(segment
		(start 159.080962 -111.75492)
		(end 159.34817 -111.86541)
		(width 0.12954)
		(layer "B.Cu")
		(net "PWRGD_P3V3_AUX_PDB")
	)
	(segment
		(start 157.570932 -111.633)
		(end 158.786576 -111.633)
		(width 0.12954)
		(layer "B.Cu")
		(net "PWRGD_P3V3_AUX_PDB")
	)
	(segment
		(start 159.711898 -112.015778)
		(end 160.017206 -112.015778)
		(width 0.12954)
		(layer "B.Cu")
		(net "PWRGD_P3V3_AUX_PDB")
	)
	(segment
		(start 158.786576 -111.633)
		(end 159.080962 -111.75492)
		(width 0.12954)
		(layer "B.Cu")
		(net "PWRGD_P3V3_AUX_PDB")
	)
	(segment
		(start 159.348424 -111.86541)
		(end 159.711898 -112.015778)
		(width 0.12954)
		(layer "B.Cu")
		(net "PWRGD_P3V3_AUX_PDB")
	)
	(segment
		(start 156.77388 -110.835948)
		(end 157.570932 -111.633)
		(width 0.12954)
		(layer "B.Cu")
		(net "PWRGD_P3V3_AUX_PDB")
	)
	(segment
		(start 160.43783 -112.427258)
		(end 160.43783 -116.296948)
		(width 0.12954)
		(layer "B.Cu")
		(net "PWRGD_P3V3_AUX_PDB")
	)
	(segment
		(start 160.249362 -112.23879)
		(end 160.43783 -112.427258)
		(width 0.12954)
		(layer "B.Cu")
		(net "PWRGD_P3V3_AUX_PDB")
	)
	(segment
		(start 256.48158 -330.00442)
		(end 256.48158 -327.815448)
		(width 0.127)
		(layer "In2.Cu")
		(net "PWRGD_P3V3_AUX_PDB")
	)
	(segment
		(start 274.88134 -384.74142)
		(end 272.3515 -384.74142)
		(width 0.127)
		(layer "In2.Cu")
		(net "PWRGD_P3V3_AUX_PDB")
	)
	(segment
		(start 256.48158 -327.815448)
		(end 253.47168 -324.805548)
		(width 0.127)
		(layer "In2.Cu")
		(net "PWRGD_P3V3_AUX_PDB")
	)
	(segment
		(start 303.07788 -409.33878)
		(end 303.07788 -406.66416)
		(width 0.127)
		(layer "In2.Cu")
		(net "PWRGD_P3V3_AUX_PDB")
	)
	(segment
		(start 297.391836 -383.67716)
		(end 275.9456 -383.67716)
		(width 0.127)
		(layer "In2.Cu")
		(net "PWRGD_P3V3_AUX_PDB")
	)
	(segment
		(start 302.1584 -410.25826)
		(end 303.07788 -409.33878)
		(width 0.127)
		(layer "In2.Cu")
		(net "PWRGD_P3V3_AUX_PDB")
	)
	(segment
		(start 255.93294 -345.76004)
		(end 255.93294 -330.55306)
		(width 0.127)
		(layer "In2.Cu")
		(net "PWRGD_P3V3_AUX_PDB")
	)
	(segment
		(start 270.05026 -382.44018)
		(end 270.05026 -359.87736)
		(width 0.127)
		(layer "In2.Cu")
		(net "PWRGD_P3V3_AUX_PDB")
	)
	(segment
		(start 255.93294 -330.55306)
		(end 256.48158 -330.00442)
		(width 0.127)
		(layer "In2.Cu")
		(net "PWRGD_P3V3_AUX_PDB")
	)
	(segment
		(start 303.07788 -406.66416)
		(end 302.1584 -405.74468)
		(width 0.127)
		(layer "In2.Cu")
		(net "PWRGD_P3V3_AUX_PDB")
	)
	(segment
		(start 306.27828 -419.83914)
		(end 306.4002 -419.71722)
		(width 0.127)
		(layer "In2.Cu")
		(net "PWRGD_P3V3_AUX_PDB")
	)
	(segment
		(start 300.33976 -397.28902)
		(end 300.33976 -386.625084)
		(width 0.127)
		(layer "In2.Cu")
		(net "PWRGD_P3V3_AUX_PDB")
	)
	(segment
		(start 272.3515 -384.74142)
		(end 270.05026 -382.44018)
		(width 0.127)
		(layer "In2.Cu")
		(net "PWRGD_P3V3_AUX_PDB")
	)
	(segment
		(start 302.1584 -405.74468)
		(end 302.1584 -399.10766)
		(width 0.127)
		(layer "In2.Cu")
		(net "PWRGD_P3V3_AUX_PDB")
	)
	(segment
		(start 302.1584 -399.10766)
		(end 300.33976 -397.28902)
		(width 0.127)
		(layer "In2.Cu")
		(net "PWRGD_P3V3_AUX_PDB")
	)
	(segment
		(start 302.1584 -413.0929)
		(end 302.1584 -410.25826)
		(width 0.127)
		(layer "In2.Cu")
		(net "PWRGD_P3V3_AUX_PDB")
	)
	(segment
		(start 306.4002 -419.71722)
		(end 306.4002 -417.3347)
		(width 0.127)
		(layer "In2.Cu")
		(net "PWRGD_P3V3_AUX_PDB")
	)
	(segment
		(start 270.05026 -359.87736)
		(end 255.93294 -345.76004)
		(width 0.127)
		(layer "In2.Cu")
		(net "PWRGD_P3V3_AUX_PDB")
	)
	(segment
		(start 306.4002 -417.3347)
		(end 302.1584 -413.0929)
		(width 0.127)
		(layer "In2.Cu")
		(net "PWRGD_P3V3_AUX_PDB")
	)
	(segment
		(start 300.33976 -386.625084)
		(end 297.391836 -383.67716)
		(width 0.127)
		(layer "In2.Cu")
		(net "PWRGD_P3V3_AUX_PDB")
	)
	(segment
		(start 275.9456 -383.67716)
		(end 274.88134 -384.74142)
		(width 0.127)
		(layer "In2.Cu")
		(net "PWRGD_P3V3_AUX_PDB")
	)
	(segment
		(start 166.28618 -98.33102)
		(end 166.28618 -95.605092)
		(width 0.127)
		(layer "In11.Cu")
		(net "PWRGD_P3V3_AUX_PDB")
	)
	(segment
		(start 251.03328 -197.272148)
		(end 252.70968 -198.948548)
		(width 0.127)
		(layer "In11.Cu")
		(net "PWRGD_P3V3_AUX_PDB")
	)
	(segment
		(start 277.41118 -99.545648)
		(end 267.0937 -109.863128)
		(width 0.127)
		(layer "In11.Cu")
		(net "PWRGD_P3V3_AUX_PDB")
	)
	(segment
		(start 160.7058 -100.320348)
		(end 164.296852 -100.320348)
		(width 0.127)
		(layer "In11.Cu")
		(net "PWRGD_P3V3_AUX_PDB")
	)
	(segment
		(start 314.30468 -93.965268)
		(end 314.99302 -94.653608)
		(width 0.127)
		(layer "In11.Cu")
		(net "PWRGD_P3V3_AUX_PDB")
	)
	(segment
		(start 209.53349 -100.044758)
		(end 210.03768 -100.548948)
		(width 0.127)
		(layer "In11.Cu")
		(net "PWRGD_P3V3_AUX_PDB")
	)
	(segment
		(start 185.1914 -93.1164)
		(end 185.928 -93.853)
		(width 0.127)
		(layer "In11.Cu")
		(net "PWRGD_P3V3_AUX_PDB")
	)
	(segment
		(start 166.28618 -95.605092)
		(end 171.492672 -90.3986)
		(width 0.127)
		(layer "In11.Cu")
		(net "PWRGD_P3V3_AUX_PDB")
	)
	(segment
		(start 314.99302 -97.234248)
		(end 312.68162 -99.545648)
		(width 0.127)
		(layer "In11.Cu")
		(net "PWRGD_P3V3_AUX_PDB")
	)
	(segment
		(start 210.03768 -100.548948)
		(end 219.125292 -100.548948)
		(width 0.127)
		(layer "In11.Cu")
		(net "PWRGD_P3V3_AUX_PDB")
	)
	(segment
		(start 241.03838 -102.103428)
		(end 242.161568 -102.103428)
		(width 0.127)
		(layer "In11.Cu")
		(net "PWRGD_P3V3_AUX_PDB")
	)
	(segment
		(start 188.8236 -93.853)
		(end 189.628018 -94.657418)
		(width 0.127)
		(layer "In11.Cu")
		(net "PWRGD_P3V3_AUX_PDB")
	)
	(segment
		(start 171.492672 -90.3986)
		(end 182.542434 -90.3986)
		(width 0.127)
		(layer "In11.Cu")
		(net "PWRGD_P3V3_AUX_PDB")
	)
	(segment
		(start 183.685434 -91.5416)
		(end 184.7342 -91.5416)
		(width 0.127)
		(layer "In11.Cu")
		(net "PWRGD_P3V3_AUX_PDB")
	)
	(segment
		(start 219.96908 -99.70516)
		(end 221.95282 -99.70516)
		(width 0.127)
		(layer "In11.Cu")
		(net "PWRGD_P3V3_AUX_PDB")
	)
	(segment
		(start 252.968506 -114.958622)
		(end 252.968506 -137.069322)
		(width 0.127)
		(layer "In11.Cu")
		(net "PWRGD_P3V3_AUX_PDB")
	)
	(segment
		(start 250.29414 -108.549948)
		(end 250.75642 -108.087668)
		(width 0.127)
		(layer "In11.Cu")
		(net "PWRGD_P3V3_AUX_PDB")
	)
	(segment
		(start 184.7342 -91.5416)
		(end 185.1914 -91.9988)
		(width 0.127)
		(layer "In11.Cu")
		(net "PWRGD_P3V3_AUX_PDB")
	)
	(segment
		(start 265.26236 -108.087668)
		(end 276.11578 -97.234248)
		(width 0.127)
		(layer "In11.Cu")
		(net "PWRGD_P3V3_AUX_PDB")
	)
	(segment
		(start 222.938848 -100.691188)
		(end 239.62614 -100.691188)
		(width 0.127)
		(layer "In11.Cu")
		(net "PWRGD_P3V3_AUX_PDB")
	)
	(segment
		(start 242.161568 -102.103428)
		(end 248.608088 -108.549948)
		(width 0.127)
		(layer "In11.Cu")
		(net "PWRGD_P3V3_AUX_PDB")
	)
	(segment
		(start 156.77388 -104.252268)
		(end 160.7058 -100.320348)
		(width 0.127)
		(layer "In11.Cu")
		(net "PWRGD_P3V3_AUX_PDB")
	)
	(segment
		(start 267.0937 -112.55756)
		(end 266.158472 -113.492788)
		(width 0.127)
		(layer "In11.Cu")
		(net "PWRGD_P3V3_AUX_PDB")
	)
	(segment
		(start 156.77388 -110.835948)
		(end 156.77388 -104.252268)
		(width 0.127)
		(layer "In11.Cu")
		(net "PWRGD_P3V3_AUX_PDB")
	)
	(segment
		(start 276.11578 -97.234248)
		(end 306.87264 -97.234248)
		(width 0.127)
		(layer "In11.Cu")
		(net "PWRGD_P3V3_AUX_PDB")
	)
	(segment
		(start 252.70968 -198.948548)
		(end 252.70968 -324.043548)
		(width 0.127)
		(layer "In11.Cu")
		(net "PWRGD_P3V3_AUX_PDB")
	)
	(segment
		(start 206.25816 -100.653088)
		(end 206.86649 -100.044758)
		(width 0.127)
		(layer "In11.Cu")
		(net "PWRGD_P3V3_AUX_PDB")
	)
	(segment
		(start 185.1914 -91.9988)
		(end 185.1914 -93.1164)
		(width 0.127)
		(layer "In11.Cu")
		(net "PWRGD_P3V3_AUX_PDB")
	)
	(segment
		(start 254.43434 -113.492788)
		(end 252.968506 -114.958622)
		(width 0.127)
		(layer "In11.Cu")
		(net "PWRGD_P3V3_AUX_PDB")
	)
	(segment
		(start 219.125292 -100.548948)
		(end 219.96908 -99.70516)
		(width 0.127)
		(layer "In11.Cu")
		(net "PWRGD_P3V3_AUX_PDB")
	)
	(segment
		(start 248.608088 -108.549948)
		(end 250.29414 -108.549948)
		(width 0.127)
		(layer "In11.Cu")
		(net "PWRGD_P3V3_AUX_PDB")
	)
	(segment
		(start 239.62614 -100.691188)
		(end 241.03838 -102.103428)
		(width 0.127)
		(layer "In11.Cu")
		(net "PWRGD_P3V3_AUX_PDB")
	)
	(segment
		(start 252.968506 -137.069322)
		(end 251.03328 -139.004548)
		(width 0.127)
		(layer "In11.Cu")
		(net "PWRGD_P3V3_AUX_PDB")
	)
	(segment
		(start 185.928 -93.853)
		(end 188.8236 -93.853)
		(width 0.127)
		(layer "In11.Cu")
		(net "PWRGD_P3V3_AUX_PDB")
	)
	(segment
		(start 250.75642 -108.087668)
		(end 265.26236 -108.087668)
		(width 0.127)
		(layer "In11.Cu")
		(net "PWRGD_P3V3_AUX_PDB")
	)
	(segment
		(start 192.413382 -94.657418)
		(end 196.298312 -98.542348)
		(width 0.127)
		(layer "In11.Cu")
		(net "PWRGD_P3V3_AUX_PDB")
	)
	(segment
		(start 251.03328 -139.004548)
		(end 251.03328 -197.272148)
		(width 0.127)
		(layer "In11.Cu")
		(net "PWRGD_P3V3_AUX_PDB")
	)
	(segment
		(start 196.298312 -98.542348)
		(end 198.628 -98.542348)
		(width 0.127)
		(layer "In11.Cu")
		(net "PWRGD_P3V3_AUX_PDB")
	)
	(segment
		(start 198.628 -98.542348)
		(end 200.73874 -100.653088)
		(width 0.127)
		(layer "In11.Cu")
		(net "PWRGD_P3V3_AUX_PDB")
	)
	(segment
		(start 267.0937 -109.863128)
		(end 267.0937 -112.55756)
		(width 0.127)
		(layer "In11.Cu")
		(net "PWRGD_P3V3_AUX_PDB")
	)
	(segment
		(start 164.296852 -100.320348)
		(end 166.28618 -98.33102)
		(width 0.127)
		(layer "In11.Cu")
		(net "PWRGD_P3V3_AUX_PDB")
	)
	(segment
		(start 312.68162 -99.545648)
		(end 277.41118 -99.545648)
		(width 0.127)
		(layer "In11.Cu")
		(net "PWRGD_P3V3_AUX_PDB")
	)
	(segment
		(start 200.73874 -100.653088)
		(end 206.25816 -100.653088)
		(width 0.127)
		(layer "In11.Cu")
		(net "PWRGD_P3V3_AUX_PDB")
	)
	(segment
		(start 252.70968 -324.043548)
		(end 253.47168 -324.805548)
		(width 0.127)
		(layer "In11.Cu")
		(net "PWRGD_P3V3_AUX_PDB")
	)
	(segment
		(start 310.14162 -93.965268)
		(end 314.30468 -93.965268)
		(width 0.127)
		(layer "In11.Cu")
		(net "PWRGD_P3V3_AUX_PDB")
	)
	(segment
		(start 314.99302 -94.653608)
		(end 314.99302 -97.234248)
		(width 0.127)
		(layer "In11.Cu")
		(net "PWRGD_P3V3_AUX_PDB")
	)
	(segment
		(start 189.628018 -94.657418)
		(end 192.413382 -94.657418)
		(width 0.127)
		(layer "In11.Cu")
		(net "PWRGD_P3V3_AUX_PDB")
	)
	(segment
		(start 266.158472 -113.492788)
		(end 254.43434 -113.492788)
		(width 0.127)
		(layer "In11.Cu")
		(net "PWRGD_P3V3_AUX_PDB")
	)
	(segment
		(start 182.542434 -90.3986)
		(end 183.685434 -91.5416)
		(width 0.127)
		(layer "In11.Cu")
		(net "PWRGD_P3V3_AUX_PDB")
	)
	(segment
		(start 206.86649 -100.044758)
		(end 209.53349 -100.044758)
		(width 0.127)
		(layer "In11.Cu")
		(net "PWRGD_P3V3_AUX_PDB")
	)
	(segment
		(start 306.87264 -97.234248)
		(end 310.14162 -93.965268)
		(width 0.127)
		(layer "In11.Cu")
		(net "PWRGD_P3V3_AUX_PDB")
	)
	(segment
		(start 221.95282 -99.70516)
		(end 222.938848 -100.691188)
		(width 0.127)
		(layer "In11.Cu")
		(net "PWRGD_P3V3_AUX_PDB")
	)
	(segment
		(start 50.059844 -174.326804)
		(end 50.113946 -174.380906)
		(width 0.254)
		(layer "F.Cu")
		(net "PVCCFA_EHV_CPU1_NC2")
	)
	(segment
		(start 50.113946 -174.380906)
		(end 50.765964 -174.380906)
		(width 0.254)
		(layer "F.Cu")
		(net "PVCCFA_EHV_CPU1_NC2")
	)
	(via
		(at 50.059844 -174.326804)
		(size 0.508)
		(drill 0.254)
		(layers "F.Cu" "B.Cu")
		(net "PVCCFA_EHV_CPU1_NC2")
	)
	(via
		(at 50.683414 -173.876716)
		(size 0.6604)
		(drill 0.3302)
		(layers "F.Cu" "B.Cu")
		(net "PVCCFA_EHV_CPU1_NC2")
	)
	(segment
		(start 50.059844 -174.326804)
		(end 50.233326 -174.326804)
		(width 0.381)
		(layer "B.Cu")
		(net "PVCCFA_EHV_CPU1_NC2")
	)
	(segment
		(start 50.099976 -172.989748)
		(end 49.55413 -172.989748)
		(width 0.381)
		(layer "B.Cu")
		(net "PVCCFA_EHV_CPU1_NC2")
	)
	(segment
		(start 50.683414 -173.573186)
		(end 50.099976 -172.989748)
		(width 0.381)
		(layer "B.Cu")
		(net "PVCCFA_EHV_CPU1_NC2")
	)
	(segment
		(start 50.683414 -173.876716)
		(end 50.683414 -173.573186)
		(width 0.381)
		(layer "B.Cu")
		(net "PVCCFA_EHV_CPU1_NC2")
	)
	(segment
		(start 50.233326 -174.326804)
		(end 50.683414 -173.876716)
		(width 0.381)
		(layer "B.Cu")
		(net "PVCCFA_EHV_CPU1_NC2")
	)
	(segment
		(start 51.830986 -172.034454)
		(end 51.830986 -172.305726)
		(width 0.254)
		(layer "F.Cu")
		(net "PVCCFA_EHV_CPU1_FAULT")
	)
	(segment
		(start 50.04181 -171.541948)
		(end 51.33848 -171.541948)
		(width 0.254)
		(layer "F.Cu")
		(net "PVCCFA_EHV_CPU1_FAULT")
	)
	(segment
		(start 49.97323 -171.473368)
		(end 50.04181 -171.541948)
		(width 0.254)
		(layer "F.Cu")
		(net "PVCCFA_EHV_CPU1_FAULT")
	)
	(segment
		(start 51.33848 -171.541948)
		(end 51.830986 -172.034454)
		(width 0.254)
		(layer "F.Cu")
		(net "PVCCFA_EHV_CPU1_FAULT")
	)
	(segment
		(start 421.80764 -152.977342)
		(end 421.615616 -152.977342)
		(width 0.12954)
		(layer "F.Cu")
		(net "PVCCFA_EHV_CPU0_NC2")
	)
	(segment
		(start 421.615616 -152.977342)
		(end 421.557196 -152.918922)
		(width 0.12954)
		(layer "F.Cu")
		(net "PVCCFA_EHV_CPU0_NC2")
	)
	(segment
		(start 421.557196 -152.918922)
		(end 420.905178 -152.918922)
		(width 0.12954)
		(layer "F.Cu")
		(net "PVCCFA_EHV_CPU0_NC2")
	)
	(via
		(at 421.80764 -152.977342)
		(size 0.508)
		(drill 0.254)
		(layers "F.Cu" "B.Cu")
		(net "PVCCFA_EHV_CPU0_NC2")
	)
	(segment
		(start 421.4749 -154.031188)
		(end 421.70604 -154.262328)
		(width 0.12954)
		(layer "B.Cu")
		(net "PVCCFA_EHV_CPU0_NC2")
	)
	(segment
		(start 421.80764 -152.977342)
		(end 421.60698 -152.977342)
		(width 0.12954)
		(layer "B.Cu")
		(net "PVCCFA_EHV_CPU0_NC2")
	)
	(segment
		(start 421.4749 -153.109422)
		(end 421.4749 -154.031188)
		(width 0.12954)
		(layer "B.Cu")
		(net "PVCCFA_EHV_CPU0_NC2")
	)
	(segment
		(start 421.60698 -152.977342)
		(end 421.4749 -153.109422)
		(width 0.12954)
		(layer "B.Cu")
		(net "PVCCFA_EHV_CPU0_NC2")
	)
	(segment
		(start 421.70604 -154.262328)
		(end 422.11625 -154.262328)
		(width 0.12954)
		(layer "B.Cu")
		(net "PVCCFA_EHV_CPU0_NC2")
	)
	(segment
		(start 420.787576 -156.232098)
		(end 419.840156 -155.284678)
		(width 0.254)
		(layer "F.Cu")
		(net "PVCCFA_EHV_CPU0_FAULT")
	)
	(segment
		(start 420.93388 -156.232098)
		(end 420.787576 -156.232098)
		(width 0.254)
		(layer "F.Cu")
		(net "PVCCFA_EHV_CPU0_FAULT")
	)
	(segment
		(start 419.840156 -155.284678)
		(end 419.840156 -154.994102)
		(width 0.254)
		(layer "F.Cu")
		(net "PVCCFA_EHV_CPU0_FAULT")
	)
	(segment
		(start 340.225126 -40.461946)
		(end 340.562946 -40.461946)
		(width 0.12954)
		(layer "F.Cu")
		(net "PD_PCH_GPP_E_9")
	)
	(segment
		(start 340.162134 -40.12057)
		(end 340.162134 -40.398954)
		(width 0.12954)
		(layer "F.Cu")
		(net "PD_PCH_GPP_E_9")
	)
	(segment
		(start 340.290658 -39.992046)
		(end 340.162134 -40.12057)
		(width 0.12954)
		(layer "F.Cu")
		(net "PD_PCH_GPP_E_9")
	)
	(segment
		(start 340.162134 -40.398954)
		(end 340.225126 -40.461946)
		(width 0.12954)
		(layer "F.Cu")
		(net "PD_PCH_GPP_E_9")
	)
	(via
		(at 340.290658 -39.992046)
		(size 0.4572)
		(drill 0.2032)
		(layers "F.Cu" "B.Cu")
		(net "PD_PCH_GPP_E_9")
	)
	(via
		(at 367.62436 -39.980108)
		(size 0.762)
		(drill 0.254)
		(layers "F.Cu" "B.Cu")
		(net "PD_PCH_GPP_E_9")
	)
	(segment
		(start 367.62436 -39.980108)
		(end 367.7412 -40.096948)
		(width 0.12954)
		(layer "B.Cu")
		(net "PD_PCH_GPP_E_9")
	)
	(segment
		(start 367.7412 -40.096948)
		(end 369.09883 -40.096948)
		(width 0.12954)
		(layer "B.Cu")
		(net "PD_PCH_GPP_E_9")
	)
	(segment
		(start 340.290658 -39.72941)
		(end 340.290658 -39.992046)
		(width 0.127)
		(layer "In2.Cu")
		(net "PD_PCH_GPP_E_9")
	)
	(segment
		(start 348.131892 -41.145968)
		(end 345.236292 -38.250368)
		(width 0.127)
		(layer "In2.Cu")
		(net "PD_PCH_GPP_E_9")
	)
	(segment
		(start 351.225612 -41.145968)
		(end 348.131892 -41.145968)
		(width 0.127)
		(layer "In2.Cu")
		(net "PD_PCH_GPP_E_9")
	)
	(segment
		(start 365.317532 -37.67328)
		(end 354.6983 -37.67328)
		(width 0.127)
		(layer "In2.Cu")
		(net "PD_PCH_GPP_E_9")
	)
	(segment
		(start 341.7697 -38.250368)
		(end 340.290658 -39.72941)
		(width 0.127)
		(layer "In2.Cu")
		(net "PD_PCH_GPP_E_9")
	)
	(segment
		(start 367.62436 -39.980108)
		(end 365.317532 -37.67328)
		(width 0.127)
		(layer "In2.Cu")
		(net "PD_PCH_GPP_E_9")
	)
	(segment
		(start 345.236292 -38.250368)
		(end 341.7697 -38.250368)
		(width 0.127)
		(layer "In2.Cu")
		(net "PD_PCH_GPP_E_9")
	)
	(segment
		(start 354.6983 -37.67328)
		(end 351.225612 -41.145968)
		(width 0.127)
		(layer "In2.Cu")
		(net "PD_PCH_GPP_E_9")
	)
	(segment
		(start 343.81948 -41.401746)
		(end 343.547954 -40.931592)
		(width 0.12954)
		(layer "F.Cu")
		(net "PD_PCH_GPP_E_8")
	)
	(via
		(at 343.547954 -40.931592)
		(size 0.4572)
		(drill 0.2032)
		(layers "F.Cu" "B.Cu")
		(net "PD_PCH_GPP_E_8")
	)
	(via
		(at 368.48288 -44.160948)
		(size 0.762)
		(drill 0.254)
		(layers "F.Cu" "B.Cu")
		(net "PD_PCH_GPP_E_8")
	)
	(segment
		(start 369.09883 -44.160948)
		(end 368.48288 -44.160948)
		(width 0.12954)
		(layer "B.Cu")
		(net "PD_PCH_GPP_E_8")
	)
	(segment
		(start 368.48288 -44.160948)
		(end 366.120172 -41.79824)
		(width 0.127)
		(layer "In2.Cu")
		(net "PD_PCH_GPP_E_8")
	)
	(segment
		(start 366.120172 -41.79824)
		(end 352.69424 -41.79824)
		(width 0.127)
		(layer "In2.Cu")
		(net "PD_PCH_GPP_E_8")
	)
	(segment
		(start 352.69424 -41.79824)
		(end 351.908872 -42.583608)
		(width 0.127)
		(layer "In2.Cu")
		(net "PD_PCH_GPP_E_8")
	)
	(segment
		(start 345.32443 -40.931592)
		(end 343.547954 -40.931592)
		(width 0.127)
		(layer "In2.Cu")
		(net "PD_PCH_GPP_E_8")
	)
	(segment
		(start 346.976446 -42.583608)
		(end 345.32443 -40.931592)
		(width 0.127)
		(layer "In2.Cu")
		(net "PD_PCH_GPP_E_8")
	)
	(segment
		(start 351.908872 -42.583608)
		(end 346.976446 -42.583608)
		(width 0.127)
		(layer "In2.Cu")
		(net "PD_PCH_GPP_E_8")
	)
	(segment
		(start 336.49285 -39.992046)
		(end 335.953608 -39.992046)
		(width 0.12954)
		(layer "F.Cu")
		(net "PD_PCH_GPP_E_3")
	)
	(via
		(at 368.00028 -37.615368)
		(size 0.762)
		(drill 0.254)
		(layers "F.Cu" "B.Cu")
		(net "PD_PCH_GPP_E_3")
	)
	(via
		(at 335.953608 -39.992046)
		(size 0.4572)
		(drill 0.2032)
		(layers "F.Cu" "B.Cu")
		(net "PD_PCH_GPP_E_3")
	)
	(segment
		(start 368.00028 -37.615368)
		(end 368.32286 -37.937948)
		(width 0.12954)
		(layer "B.Cu")
		(net "PD_PCH_GPP_E_3")
	)
	(segment
		(start 368.32286 -37.937948)
		(end 369.09883 -37.937948)
		(width 0.12954)
		(layer "B.Cu")
		(net "PD_PCH_GPP_E_3")
	)
	(segment
		(start 367.15954 -36.774628)
		(end 354.586032 -36.774628)
		(width 0.127)
		(layer "In2.Cu")
		(net "PD_PCH_GPP_E_3")
	)
	(segment
		(start 340.84514 -37.551868)
		(end 337.88096 -40.516048)
		(width 0.127)
		(layer "In2.Cu")
		(net "PD_PCH_GPP_E_3")
	)
	(segment
		(start 354.586032 -36.774628)
		(end 350.913192 -40.447468)
		(width 0.127)
		(layer "In2.Cu")
		(net "PD_PCH_GPP_E_3")
	)
	(segment
		(start 368.00028 -37.615368)
		(end 367.15954 -36.774628)
		(width 0.127)
		(layer "In2.Cu")
		(net "PD_PCH_GPP_E_3")
	)
	(segment
		(start 336.47761 -40.516048)
		(end 335.953608 -39.992046)
		(width 0.127)
		(layer "In2.Cu")
		(net "PD_PCH_GPP_E_3")
	)
	(segment
		(start 345.525852 -37.551868)
		(end 340.84514 -37.551868)
		(width 0.127)
		(layer "In2.Cu")
		(net "PD_PCH_GPP_E_3")
	)
	(segment
		(start 348.421452 -40.447468)
		(end 345.525852 -37.551868)
		(width 0.127)
		(layer "In2.Cu")
		(net "PD_PCH_GPP_E_3")
	)
	(segment
		(start 350.913192 -40.447468)
		(end 348.421452 -40.447468)
		(width 0.127)
		(layer "In2.Cu")
		(net "PD_PCH_GPP_E_3")
	)
	(segment
		(start 337.88096 -40.516048)
		(end 336.47761 -40.516048)
		(width 0.127)
		(layer "In2.Cu")
		(net "PD_PCH_GPP_E_3")
	)
	(segment
		(start 342.490044 -39.788084)
		(end 342.694006 -39.992046)
		(width 0.12954)
		(layer "F.Cu")
		(net "PD_PCH_GPP_E_14")
	)
	(segment
		(start 342.694006 -39.992046)
		(end 343.005156 -39.992046)
		(width 0.12954)
		(layer "F.Cu")
		(net "PD_PCH_GPP_E_14")
	)
	(via
		(at 368.23396 -42.395648)
		(size 0.762)
		(drill 0.254)
		(layers "F.Cu" "B.Cu")
		(net "PD_PCH_GPP_E_14")
	)
	(via
		(at 342.490044 -39.788084)
		(size 0.4572)
		(drill 0.2032)
		(layers "F.Cu" "B.Cu")
		(net "PD_PCH_GPP_E_14")
	)
	(via
		(at 343.889076 -36.797488)
		(size 0.6604)
		(drill 0.3302)
		(layers "F.Cu" "B.Cu")
		(net "PD_PCH_GPP_E_14")
	)
	(segment
		(start 342.490044 -39.788084)
		(end 343.889076 -38.389052)
		(width 0.12954)
		(layer "B.Cu")
		(net "PD_PCH_GPP_E_14")
	)
	(segment
		(start 368.23396 -42.395648)
		(end 368.50066 -42.128948)
		(width 0.12954)
		(layer "B.Cu")
		(net "PD_PCH_GPP_E_14")
	)
	(segment
		(start 368.50066 -42.128948)
		(end 369.09883 -42.128948)
		(width 0.12954)
		(layer "B.Cu")
		(net "PD_PCH_GPP_E_14")
	)
	(segment
		(start 343.889076 -38.389052)
		(end 343.889076 -36.797488)
		(width 0.12954)
		(layer "B.Cu")
		(net "PD_PCH_GPP_E_14")
	)
	(segment
		(start 366.945672 -41.10736)
		(end 352.37166 -41.10736)
		(width 0.127)
		(layer "In2.Cu")
		(net "PD_PCH_GPP_E_14")
	)
	(segment
		(start 351.629472 -41.849548)
		(end 347.8403 -41.849548)
		(width 0.127)
		(layer "In2.Cu")
		(net "PD_PCH_GPP_E_14")
	)
	(segment
		(start 343.32418 -38.953948)
		(end 342.490044 -39.788084)
		(width 0.127)
		(layer "In2.Cu")
		(net "PD_PCH_GPP_E_14")
	)
	(segment
		(start 344.9447 -38.953948)
		(end 343.32418 -38.953948)
		(width 0.127)
		(layer "In2.Cu")
		(net "PD_PCH_GPP_E_14")
	)
	(segment
		(start 347.8403 -41.849548)
		(end 344.9447 -38.953948)
		(width 0.127)
		(layer "In2.Cu")
		(net "PD_PCH_GPP_E_14")
	)
	(segment
		(start 352.37166 -41.10736)
		(end 351.629472 -41.849548)
		(width 0.127)
		(layer "In2.Cu")
		(net "PD_PCH_GPP_E_14")
	)
	(segment
		(start 368.23396 -42.395648)
		(end 366.945672 -41.10736)
		(width 0.127)
		(layer "In2.Cu")
		(net "PD_PCH_GPP_E_14")
	)
	(segment
		(start 341.804752 -40.390572)
		(end 341.876126 -40.461946)
		(width 0.12954)
		(layer "F.Cu")
		(net "PD_PCH_GPP_E_13")
	)
	(segment
		(start 341.91956 -39.992046)
		(end 341.804752 -40.106854)
		(width 0.12954)
		(layer "F.Cu")
		(net "PD_PCH_GPP_E_13")
	)
	(segment
		(start 341.876126 -40.461946)
		(end 342.19134 -40.461946)
		(width 0.12954)
		(layer "F.Cu")
		(net "PD_PCH_GPP_E_13")
	)
	(segment
		(start 341.804752 -40.106854)
		(end 341.804752 -40.390572)
		(width 0.12954)
		(layer "F.Cu")
		(net "PD_PCH_GPP_E_13")
	)
	(via
		(at 368.48288 -41.112948)
		(size 0.762)
		(drill 0.254)
		(layers "F.Cu" "B.Cu")
		(net "PD_PCH_GPP_E_13")
	)
	(via
		(at 343.19591 -38.318694)
		(size 0.6604)
		(drill 0.3302)
		(layers "F.Cu" "B.Cu")
		(net "PD_PCH_GPP_E_13")
	)
	(via
		(at 341.91956 -39.992046)
		(size 0.4572)
		(drill 0.2032)
		(layers "F.Cu" "B.Cu")
		(net "PD_PCH_GPP_E_13")
	)
	(segment
		(start 369.09883 -41.112948)
		(end 368.48288 -41.112948)
		(width 0.12954)
		(layer "B.Cu")
		(net "PD_PCH_GPP_E_13")
	)
	(segment
		(start 341.91956 -39.595044)
		(end 341.91956 -39.992046)
		(width 0.12954)
		(layer "B.Cu")
		(net "PD_PCH_GPP_E_13")
	)
	(segment
		(start 343.19591 -38.318694)
		(end 341.91956 -39.595044)
		(width 0.12954)
		(layer "B.Cu")
		(net "PD_PCH_GPP_E_13")
	)
	(segment
		(start 342.46312 -38.621208)
		(end 341.91956 -39.164768)
		(width 0.127)
		(layer "In2.Cu")
		(net "PD_PCH_GPP_E_13")
	)
	(segment
		(start 368.086132 -40.7162)
		(end 352.2726 -40.7162)
		(width 0.127)
		(layer "In2.Cu")
		(net "PD_PCH_GPP_E_13")
	)
	(segment
		(start 345.082622 -38.621208)
		(end 342.46312 -38.621208)
		(width 0.127)
		(layer "In2.Cu")
		(net "PD_PCH_GPP_E_13")
	)
	(segment
		(start 352.2726 -40.7162)
		(end 351.471992 -41.516808)
		(width 0.127)
		(layer "In2.Cu")
		(net "PD_PCH_GPP_E_13")
	)
	(segment
		(start 341.91956 -39.164768)
		(end 341.91956 -39.992046)
		(width 0.127)
		(layer "In2.Cu")
		(net "PD_PCH_GPP_E_13")
	)
	(segment
		(start 347.978222 -41.516808)
		(end 345.082622 -38.621208)
		(width 0.127)
		(layer "In2.Cu")
		(net "PD_PCH_GPP_E_13")
	)
	(segment
		(start 368.48288 -41.112948)
		(end 368.086132 -40.7162)
		(width 0.127)
		(layer "In2.Cu")
		(net "PD_PCH_GPP_E_13")
	)
	(segment
		(start 351.471992 -41.516808)
		(end 347.978222 -41.516808)
		(width 0.127)
		(layer "In2.Cu")
		(net "PD_PCH_GPP_E_13")
	)
	(segment
		(start 339.748876 -39.992046)
		(end 339.209888 -39.992046)
		(width 0.12954)
		(layer "F.Cu")
		(net "PD_PCH_GPP_E_12")
	)
	(via
		(at 368.48288 -38.953948)
		(size 0.762)
		(drill 0.254)
		(layers "F.Cu" "B.Cu")
		(net "PD_PCH_GPP_E_12")
	)
	(via
		(at 339.209888 -39.992046)
		(size 0.4572)
		(drill 0.2032)
		(layers "F.Cu" "B.Cu")
		(net "PD_PCH_GPP_E_12")
	)
	(segment
		(start 369.09883 -38.953948)
		(end 368.48288 -38.953948)
		(width 0.12954)
		(layer "B.Cu")
		(net "PD_PCH_GPP_E_12")
	)
	(segment
		(start 348.271846 -40.808148)
		(end 345.376246 -37.912548)
		(width 0.127)
		(layer "In2.Cu")
		(net "PD_PCH_GPP_E_12")
	)
	(segment
		(start 345.376246 -37.912548)
		(end 341.289386 -37.912548)
		(width 0.127)
		(layer "In2.Cu")
		(net "PD_PCH_GPP_E_12")
	)
	(segment
		(start 354.61956 -37.20846)
		(end 351.019872 -40.808148)
		(width 0.127)
		(layer "In2.Cu")
		(net "PD_PCH_GPP_E_12")
	)
	(segment
		(start 351.019872 -40.808148)
		(end 348.271846 -40.808148)
		(width 0.127)
		(layer "In2.Cu")
		(net "PD_PCH_GPP_E_12")
	)
	(segment
		(start 368.48288 -38.953948)
		(end 366.737392 -37.20846)
		(width 0.127)
		(layer "In2.Cu")
		(net "PD_PCH_GPP_E_12")
	)
	(segment
		(start 341.289386 -37.912548)
		(end 339.209888 -39.992046)
		(width 0.127)
		(layer "In2.Cu")
		(net "PD_PCH_GPP_E_12")
	)
	(segment
		(start 366.737392 -37.20846)
		(end 354.61956 -37.20846)
		(width 0.127)
		(layer "In2.Cu")
		(net "PD_PCH_GPP_E_12")
	)
	(segment
		(start 343.005156 -41.871646)
		(end 342.733376 -41.401746)
		(width 0.12954)
		(layer "F.Cu")
		(net "PD_PCH_GPP_E_11")
	)
	(via
		(at 342.733376 -41.401746)
		(size 0.4572)
		(drill 0.2032)
		(layers "F.Cu" "B.Cu")
		(net "PD_PCH_GPP_E_11")
	)
	(via
		(at 346.091256 -40.930068)
		(size 0.6604)
		(drill 0.3302)
		(layers "F.Cu" "B.Cu")
		(net "PD_PCH_GPP_E_11")
	)
	(via
		(at 368.48288 -45.176948)
		(size 0.508)
		(drill 0.254)
		(layers "F.Cu" "B.Cu")
		(net "PD_PCH_GPP_E_11")
	)
	(segment
		(start 344.168476 -40.930068)
		(end 343.696798 -41.401746)
		(width 0.12954)
		(layer "B.Cu")
		(net "PD_PCH_GPP_E_11")
	)
	(segment
		(start 369.09883 -45.176948)
		(end 368.48288 -45.176948)
		(width 0.12954)
		(layer "B.Cu")
		(net "PD_PCH_GPP_E_11")
	)
	(segment
		(start 343.696798 -41.401746)
		(end 342.733376 -41.401746)
		(width 0.12954)
		(layer "B.Cu")
		(net "PD_PCH_GPP_E_11")
	)
	(segment
		(start 346.091256 -40.930068)
		(end 344.168476 -40.930068)
		(width 0.12954)
		(layer "B.Cu")
		(net "PD_PCH_GPP_E_11")
	)
	(segment
		(start 352.80092 -42.21734)
		(end 352.099372 -42.918888)
		(width 0.127)
		(layer "In2.Cu")
		(net "PD_PCH_GPP_E_11")
	)
	(segment
		(start 343.704418 -41.401746)
		(end 342.733376 -41.401746)
		(width 0.127)
		(layer "In2.Cu")
		(net "PD_PCH_GPP_E_11")
	)
	(segment
		(start 344.17254 -41.869868)
		(end 343.704418 -41.401746)
		(width 0.127)
		(layer "In2.Cu")
		(net "PD_PCH_GPP_E_11")
	)
	(segment
		(start 365.523272 -42.21734)
		(end 352.80092 -42.21734)
		(width 0.127)
		(layer "In2.Cu")
		(net "PD_PCH_GPP_E_11")
	)
	(segment
		(start 352.099372 -42.918888)
		(end 346.56776 -42.918888)
		(width 0.127)
		(layer "In2.Cu")
		(net "PD_PCH_GPP_E_11")
	)
	(segment
		(start 346.56776 -42.918888)
		(end 345.51874 -41.869868)
		(width 0.127)
		(layer "In2.Cu")
		(net "PD_PCH_GPP_E_11")
	)
	(segment
		(start 345.51874 -41.869868)
		(end 344.17254 -41.869868)
		(width 0.127)
		(layer "In2.Cu")
		(net "PD_PCH_GPP_E_11")
	)
	(segment
		(start 368.48288 -45.176948)
		(end 365.523272 -42.21734)
		(width 0.127)
		(layer "In2.Cu")
		(net "PD_PCH_GPP_E_11")
	)
	(segment
		(start 341.105998 -41.401746)
		(end 340.979252 -41.528492)
		(width 0.12954)
		(layer "F.Cu")
		(net "PD_PCH_GPP_E_10")
	)
	(segment
		(start 341.055452 -41.871646)
		(end 341.37727 -41.871646)
		(width 0.12954)
		(layer "F.Cu")
		(net "PD_PCH_GPP_E_10")
	)
	(segment
		(start 340.979252 -41.528492)
		(end 340.979252 -41.795446)
		(width 0.12954)
		(layer "F.Cu")
		(net "PD_PCH_GPP_E_10")
	)
	(segment
		(start 340.979252 -41.795446)
		(end 341.055452 -41.871646)
		(width 0.12954)
		(layer "F.Cu")
		(net "PD_PCH_GPP_E_10")
	)
	(via
		(at 368.48288 -46.192948)
		(size 0.508)
		(drill 0.254)
		(layers "F.Cu" "B.Cu")
		(net "PD_PCH_GPP_E_10")
	)
	(via
		(at 341.105998 -41.401746)
		(size 0.4572)
		(drill 0.2032)
		(layers "F.Cu" "B.Cu")
		(net "PD_PCH_GPP_E_10")
	)
	(via
		(at 344.808556 -38.123368)
		(size 0.6604)
		(drill 0.3302)
		(layers "F.Cu" "B.Cu")
		(net "PD_PCH_GPP_E_10")
	)
	(segment
		(start 344.808556 -38.123368)
		(end 343.144856 -39.787068)
		(width 0.12954)
		(layer "B.Cu")
		(net "PD_PCH_GPP_E_10")
	)
	(segment
		(start 343.144856 -40.742108)
		(end 342.888316 -40.998648)
		(width 0.12954)
		(layer "B.Cu")
		(net "PD_PCH_GPP_E_10")
	)
	(segment
		(start 342.111838 -41.401746)
		(end 341.105998 -41.401746)
		(width 0.12954)
		(layer "B.Cu")
		(net "PD_PCH_GPP_E_10")
	)
	(segment
		(start 342.514936 -40.998648)
		(end 342.111838 -41.401746)
		(width 0.12954)
		(layer "B.Cu")
		(net "PD_PCH_GPP_E_10")
	)
	(segment
		(start 369.09883 -46.192948)
		(end 368.48288 -46.192948)
		(width 0.12954)
		(layer "B.Cu")
		(net "PD_PCH_GPP_E_10")
	)
	(segment
		(start 343.144856 -39.787068)
		(end 343.144856 -40.742108)
		(width 0.12954)
		(layer "B.Cu")
		(net "PD_PCH_GPP_E_10")
	)
	(segment
		(start 342.888316 -40.998648)
		(end 342.514936 -40.998648)
		(width 0.12954)
		(layer "B.Cu")
		(net "PD_PCH_GPP_E_10")
	)
	(segment
		(start 343.13368 -43.043348)
		(end 343.13368 -42.042588)
		(width 0.127)
		(layer "In2.Cu")
		(net "PD_PCH_GPP_E_10")
	)
	(segment
		(start 342.022938 -41.401746)
		(end 341.105998 -41.401746)
		(width 0.127)
		(layer "In2.Cu")
		(net "PD_PCH_GPP_E_10")
	)
	(segment
		(start 353.0346 -42.60088)
		(end 352.343212 -43.292268)
		(width 0.127)
		(layer "In2.Cu")
		(net "PD_PCH_GPP_E_10")
	)
	(segment
		(start 342.42756 -41.806368)
		(end 342.022938 -41.401746)
		(width 0.127)
		(layer "In2.Cu")
		(net "PD_PCH_GPP_E_10")
	)
	(segment
		(start 352.343212 -43.292268)
		(end 346.35948 -43.292268)
		(width 0.127)
		(layer "In2.Cu")
		(net "PD_PCH_GPP_E_10")
	)
	(segment
		(start 346.35948 -43.292268)
		(end 345.88196 -42.814748)
		(width 0.127)
		(layer "In2.Cu")
		(net "PD_PCH_GPP_E_10")
	)
	(segment
		(start 364.890812 -42.60088)
		(end 353.0346 -42.60088)
		(width 0.127)
		(layer "In2.Cu")
		(net "PD_PCH_GPP_E_10")
	)
	(segment
		(start 343.79916 -43.221148)
		(end 343.31148 -43.221148)
		(width 0.127)
		(layer "In2.Cu")
		(net "PD_PCH_GPP_E_10")
	)
	(segment
		(start 343.31148 -43.221148)
		(end 343.13368 -43.043348)
		(width 0.127)
		(layer "In2.Cu")
		(net "PD_PCH_GPP_E_10")
	)
	(segment
		(start 342.89746 -41.806368)
		(end 342.42756 -41.806368)
		(width 0.127)
		(layer "In2.Cu")
		(net "PD_PCH_GPP_E_10")
	)
	(segment
		(start 368.48288 -46.192948)
		(end 364.890812 -42.60088)
		(width 0.127)
		(layer "In2.Cu")
		(net "PD_PCH_GPP_E_10")
	)
	(segment
		(start 345.88196 -42.814748)
		(end 344.20556 -42.814748)
		(width 0.127)
		(layer "In2.Cu")
		(net "PD_PCH_GPP_E_10")
	)
	(segment
		(start 343.13368 -42.042588)
		(end 342.89746 -41.806368)
		(width 0.127)
		(layer "In2.Cu")
		(net "PD_PCH_GPP_E_10")
	)
	(segment
		(start 344.20556 -42.814748)
		(end 343.79916 -43.221148)
		(width 0.127)
		(layer "In2.Cu")
		(net "PD_PCH_GPP_E_10")
	)
	(segment
		(start 323.354446 -42.584878)
		(end 324.217538 -43.44797)
		(width 0.0889)
		(layer "F.Cu")
		(net "PD_PCH_GPPC_C9")
	)
	(segment
		(start 309.923688 -37.822886)
		(end 310.62168 -37.822886)
		(width 0.12954)
		(layer "F.Cu")
		(net "PD_PCH_GPPC_C9")
	)
	(segment
		(start 321.31254 -41.204388)
		(end 322.488052 -42.3799)
		(width 0.12954)
		(layer "F.Cu")
		(net "PD_PCH_GPPC_C9")
	)
	(segment
		(start 322.703952 -42.508678)
		(end 322.888102 -42.584878)
		(width 0.0889)
		(layer "F.Cu")
		(net "PD_PCH_GPPC_C9")
	)
	(segment
		(start 322.888102 -42.584878)
		(end 323.354446 -42.584878)
		(width 0.0889)
		(layer "F.Cu")
		(net "PD_PCH_GPPC_C9")
	)
	(segment
		(start 324.217538 -43.44797)
		(end 326.999854 -43.44797)
		(width 0.0889)
		(layer "F.Cu")
		(net "PD_PCH_GPPC_C9")
	)
	(segment
		(start 322.488052 -42.3799)
		(end 322.575174 -42.3799)
		(width 0.12954)
		(layer "F.Cu")
		(net "PD_PCH_GPPC_C9")
	)
	(segment
		(start 322.575174 -42.3799)
		(end 322.703952 -42.508678)
		(width 0.0889)
		(layer "F.Cu")
		(net "PD_PCH_GPPC_C9")
	)
	(via
		(at 310.62168 -37.822886)
		(size 0.508)
		(drill 0.254)
		(layers "F.Cu" "B.Cu")
		(net "PD_PCH_GPPC_C9")
	)
	(via
		(at 321.31254 -41.204388)
		(size 0.508)
		(drill 0.254)
		(layers "F.Cu" "B.Cu")
		(net "PD_PCH_GPPC_C9")
	)
	(segment
		(start 311.05348 -38.318948)
		(end 310.62168 -37.887148)
		(width 0.127)
		(layer "In4.Cu")
		(net "PD_PCH_GPPC_C9")
	)
	(segment
		(start 312.14568 -38.318948)
		(end 311.05348 -38.318948)
		(width 0.127)
		(layer "In4.Cu")
		(net "PD_PCH_GPPC_C9")
	)
	(segment
		(start 321.31254 -41.204388)
		(end 315.03112 -41.204388)
		(width 0.127)
		(layer "In4.Cu")
		(net "PD_PCH_GPPC_C9")
	)
	(segment
		(start 315.03112 -41.204388)
		(end 312.14568 -38.318948)
		(width 0.127)
		(layer "In4.Cu")
		(net "PD_PCH_GPPC_C9")
	)
	(segment
		(start 310.62168 -37.887148)
		(end 310.62168 -37.822886)
		(width 0.127)
		(layer "In4.Cu")
		(net "PD_PCH_GPPC_C9")
	)
	(segment
		(start 309.923688 -36.806886)
		(end 310.62168 -36.806886)
		(width 0.12954)
		(layer "F.Cu")
		(net "PD_PCH_GPPC_C5")
	)
	(segment
		(start 324.416166 -43.224196)
		(end 326.672956 -43.224196)
		(width 0.0889)
		(layer "F.Cu")
		(net "PD_PCH_GPPC_C5")
	)
	(segment
		(start 326.862694 -43.128438)
		(end 327.132696 -42.94759)
		(width 0.0889)
		(layer "F.Cu")
		(net "PD_PCH_GPPC_C5")
	)
	(segment
		(start 326.672956 -43.224196)
		(end 326.803766 -43.167554)
		(width 0.0889)
		(layer "F.Cu")
		(net "PD_PCH_GPPC_C5")
	)
	(segment
		(start 327.132696 -42.94759)
		(end 327.41489 -42.94759)
		(width 0.0889)
		(layer "F.Cu")
		(net "PD_PCH_GPPC_C5")
	)
	(segment
		(start 326.803766 -43.167554)
		(end 326.862694 -43.128438)
		(width 0.0889)
		(layer "F.Cu")
		(net "PD_PCH_GPPC_C5")
	)
	(segment
		(start 322.984622 -42.154348)
		(end 323.346318 -42.154348)
		(width 0.0889)
		(layer "F.Cu")
		(net "PD_PCH_GPPC_C5")
	)
	(segment
		(start 323.346318 -42.154348)
		(end 324.416166 -43.224196)
		(width 0.0889)
		(layer "F.Cu")
		(net "PD_PCH_GPPC_C5")
	)
	(via
		(at 310.62168 -36.806886)
		(size 0.508)
		(drill 0.254)
		(layers "F.Cu" "B.Cu")
		(net "PD_PCH_GPPC_C5")
	)
	(via
		(at 322.984622 -42.154348)
		(size 0.508)
		(drill 0.254)
		(layers "F.Cu" "B.Cu")
		(net "PD_PCH_GPPC_C5")
	)
	(segment
		(start 322.28028 -41.450006)
		(end 322.28028 -40.350948)
		(width 0.127)
		(layer "In4.Cu")
		(net "PD_PCH_GPPC_C5")
	)
	(segment
		(start 317.5254 -40.122348)
		(end 315.06668 -40.122348)
		(width 0.127)
		(layer "In4.Cu")
		(net "PD_PCH_GPPC_C5")
	)
	(segment
		(start 315.06668 -40.122348)
		(end 312.17108 -37.226748)
		(width 0.127)
		(layer "In4.Cu")
		(net "PD_PCH_GPPC_C5")
	)
	(segment
		(start 312.17108 -37.226748)
		(end 311.10428 -37.226748)
		(width 0.127)
		(layer "In4.Cu")
		(net "PD_PCH_GPPC_C5")
	)
	(segment
		(start 310.684418 -36.806886)
		(end 310.62168 -36.806886)
		(width 0.127)
		(layer "In4.Cu")
		(net "PD_PCH_GPPC_C5")
	)
	(segment
		(start 322.28028 -40.350948)
		(end 321.79768 -39.868348)
		(width 0.127)
		(layer "In4.Cu")
		(net "PD_PCH_GPPC_C5")
	)
	(segment
		(start 311.10428 -37.226748)
		(end 310.684418 -36.806886)
		(width 0.127)
		(layer "In4.Cu")
		(net "PD_PCH_GPPC_C5")
	)
	(segment
		(start 320.27368 -39.868348)
		(end 319.68948 -40.452548)
		(width 0.127)
		(layer "In4.Cu")
		(net "PD_PCH_GPPC_C5")
	)
	(segment
		(start 321.79768 -39.868348)
		(end 320.27368 -39.868348)
		(width 0.127)
		(layer "In4.Cu")
		(net "PD_PCH_GPPC_C5")
	)
	(segment
		(start 322.984622 -42.154348)
		(end 322.28028 -41.450006)
		(width 0.127)
		(layer "In4.Cu")
		(net "PD_PCH_GPPC_C5")
	)
	(segment
		(start 317.8556 -40.452548)
		(end 317.5254 -40.122348)
		(width 0.127)
		(layer "In4.Cu")
		(net "PD_PCH_GPPC_C5")
	)
	(segment
		(start 319.68948 -40.452548)
		(end 317.8556 -40.452548)
		(width 0.127)
		(layer "In4.Cu")
		(net "PD_PCH_GPPC_C5")
	)
	(segment
		(start 322.575174 -43.741848)
		(end 322.918582 -43.810174)
		(width 0.0889)
		(layer "F.Cu")
		(net "PD_PCH_GPPC_C10")
	)
	(segment
		(start 313.44997 -39.497508)
		(end 316.424056 -39.497508)
		(width 0.12954)
		(layer "F.Cu")
		(net "PD_PCH_GPPC_C10")
	)
	(segment
		(start 317.059056 -39.837868)
		(end 318.387476 -41.166288)
		(width 0.12954)
		(layer "F.Cu")
		(net "PD_PCH_GPPC_C10")
	)
	(segment
		(start 322.918582 -43.810174)
		(end 323.370702 -43.810174)
		(width 0.0889)
		(layer "F.Cu")
		(net "PD_PCH_GPPC_C10")
	)
	(segment
		(start 321.64782 -43.357546)
		(end 322.575174 -43.741848)
		(width 0.12954)
		(layer "F.Cu")
		(net "PD_PCH_GPPC_C10")
	)
	(segment
		(start 320.795142 -42.504868)
		(end 321.64782 -43.357546)
		(width 0.12954)
		(layer "F.Cu")
		(net "PD_PCH_GPPC_C10")
	)
	(segment
		(start 326.719184 -44.224194)
		(end 326.862694 -44.128944)
		(width 0.0889)
		(layer "F.Cu")
		(net "PD_PCH_GPPC_C10")
	)
	(segment
		(start 327.085706 -43.948096)
		(end 327.41489 -43.948096)
		(width 0.0889)
		(layer "F.Cu")
		(net "PD_PCH_GPPC_C10")
	)
	(segment
		(start 318.387476 -41.166288)
		(end 318.821562 -41.166288)
		(width 0.12954)
		(layer "F.Cu")
		(net "PD_PCH_GPPC_C10")
	)
	(segment
		(start 312.843672 -38.89121)
		(end 313.44997 -39.497508)
		(width 0.12954)
		(layer "F.Cu")
		(net "PD_PCH_GPPC_C10")
	)
	(segment
		(start 316.764416 -39.837868)
		(end 317.059056 -39.837868)
		(width 0.12954)
		(layer "F.Cu")
		(net "PD_PCH_GPPC_C10")
	)
	(segment
		(start 326.862694 -44.128944)
		(end 327.085706 -43.948096)
		(width 0.0889)
		(layer "F.Cu")
		(net "PD_PCH_GPPC_C10")
	)
	(segment
		(start 326.409812 -44.224194)
		(end 326.719184 -44.224194)
		(width 0.0889)
		(layer "F.Cu")
		(net "PD_PCH_GPPC_C10")
	)
	(segment
		(start 316.429136 -39.502588)
		(end 316.764416 -39.837868)
		(width 0.12954)
		(layer "F.Cu")
		(net "PD_PCH_GPPC_C10")
	)
	(segment
		(start 323.754242 -44.193714)
		(end 326.306434 -44.193714)
		(width 0.0889)
		(layer "F.Cu")
		(net "PD_PCH_GPPC_C10")
	)
	(segment
		(start 326.306434 -44.193714)
		(end 326.409812 -44.224194)
		(width 0.0889)
		(layer "F.Cu")
		(net "PD_PCH_GPPC_C10")
	)
	(segment
		(start 318.821562 -41.166288)
		(end 319.71107 -42.055796)
		(width 0.12954)
		(layer "F.Cu")
		(net "PD_PCH_GPPC_C10")
	)
	(segment
		(start 319.71107 -42.055796)
		(end 320.795142 -42.504868)
		(width 0.12954)
		(layer "F.Cu")
		(net "PD_PCH_GPPC_C10")
	)
	(segment
		(start 323.370702 -43.810174)
		(end 323.754242 -44.193714)
		(width 0.0889)
		(layer "F.Cu")
		(net "PD_PCH_GPPC_C10")
	)
	(segment
		(start 316.424056 -39.497508)
		(end 316.429136 -39.502588)
		(width 0.12954)
		(layer "F.Cu")
		(net "PD_PCH_GPPC_C10")
	)
	(via
		(at 316.429136 -39.502588)
		(size 0.762)
		(drill 0.381)
		(layers "F.Cu" "B.Cu")
		(net "PD_PCH_GPPC_C10")
	)
	(segment
		(start 331.16774 -29.362908)
		(end 330.72324 -28.918408)
		(width 0.0889)
		(layer "F.Cu")
		(net "PD_PCH_GPPC_A_19")
	)
	(segment
		(start 331.766418 -33.874202)
		(end 331.766418 -31.219648)
		(width 0.0889)
		(layer "F.Cu")
		(net "PD_PCH_GPPC_A_19")
	)
	(segment
		(start 331.16774 -30.181296)
		(end 331.16774 -29.362908)
		(width 0.0889)
		(layer "F.Cu")
		(net "PD_PCH_GPPC_A_19")
	)
	(segment
		(start 331.766418 -31.219648)
		(end 331.478636 -30.931866)
		(width 0.0889)
		(layer "F.Cu")
		(net "PD_PCH_GPPC_A_19")
	)
	(segment
		(start 332.897734 -35.005518)
		(end 331.766418 -33.874202)
		(width 0.0889)
		(layer "F.Cu")
		(net "PD_PCH_GPPC_A_19")
	)
	(segment
		(start 331.478636 -30.931866)
		(end 331.16774 -30.181296)
		(width 0.0889)
		(layer "F.Cu")
		(net "PD_PCH_GPPC_A_19")
	)
	(segment
		(start 332.897734 -37.63518)
		(end 332.897734 -35.005518)
		(width 0.0889)
		(layer "F.Cu")
		(net "PD_PCH_GPPC_A_19")
	)
	(via
		(at 330.72324 -28.918408)
		(size 0.762)
		(drill 0.254)
		(layers "F.Cu" "B.Cu")
		(net "PD_PCH_GPPC_A_19")
	)
	(segment
		(start 331.01788 -28.623768)
		(end 331.01788 -28.101798)
		(width 0.12954)
		(layer "B.Cu")
		(net "PD_PCH_GPPC_A_19")
	)
	(segment
		(start 330.72324 -28.918408)
		(end 331.01788 -28.623768)
		(width 0.12954)
		(layer "B.Cu")
		(net "PD_PCH_GPPC_A_19")
	)
	(segment
		(start 327.61174 -26.154888)
		(end 327.39584 -26.370788)
		(width 0.12954)
		(layer "F.Cu")
		(net "PD_PCH_GPPC_A_18")
	)
	(segment
		(start 329.461622 -32.107124)
		(end 329.713844 -32.359346)
		(width 0.0889)
		(layer "F.Cu")
		(net "PD_PCH_GPPC_A_18")
	)
	(segment
		(start 329.713844 -33.041082)
		(end 330.558394 -33.885632)
		(width 0.0889)
		(layer "F.Cu")
		(net "PD_PCH_GPPC_A_18")
	)
	(segment
		(start 327.39584 -27.733752)
		(end 327.960736 -28.7909)
		(width 0.12954)
		(layer "F.Cu")
		(net "PD_PCH_GPPC_A_18")
	)
	(segment
		(start 327.099422 -24.303228)
		(end 327.099422 -25.12949)
		(width 0.12954)
		(layer "F.Cu")
		(net "PD_PCH_GPPC_A_18")
	)
	(segment
		(start 330.558394 -34.558732)
		(end 331.413358 -35.413696)
		(width 0.0889)
		(layer "F.Cu")
		(net "PD_PCH_GPPC_A_18")
	)
	(segment
		(start 328.610722 -30.564836)
		(end 328.760582 -30.926278)
		(width 0.0889)
		(layer "F.Cu")
		(net "PD_PCH_GPPC_A_18")
	)
	(segment
		(start 330.558394 -33.885632)
		(end 330.558394 -34.558732)
		(width 0.0889)
		(layer "F.Cu")
		(net "PD_PCH_GPPC_A_18")
	)
	(segment
		(start 331.413358 -35.413696)
		(end 331.413358 -37.637212)
		(width 0.0889)
		(layer "F.Cu")
		(net "PD_PCH_GPPC_A_18")
	)
	(segment
		(start 327.099422 -24.194516)
		(end 327.129902 -24.164036)
		(width 0.12954)
		(layer "F.Cu")
		(net "PD_PCH_GPPC_A_18")
	)
	(segment
		(start 327.61174 -25.641808)
		(end 327.61174 -26.154888)
		(width 0.12954)
		(layer "F.Cu")
		(net "PD_PCH_GPPC_A_18")
	)
	(segment
		(start 329.713844 -32.359346)
		(end 329.713844 -33.041082)
		(width 0.0889)
		(layer "F.Cu")
		(net "PD_PCH_GPPC_A_18")
	)
	(segment
		(start 331.413358 -37.637212)
		(end 331.397102 -37.653468)
		(width 0.0889)
		(layer "F.Cu")
		(net "PD_PCH_GPPC_A_18")
	)
	(segment
		(start 327.099422 -25.12949)
		(end 327.61174 -25.641808)
		(width 0.12954)
		(layer "F.Cu")
		(net "PD_PCH_GPPC_A_18")
	)
	(segment
		(start 328.760582 -30.926278)
		(end 329.461622 -31.627318)
		(width 0.0889)
		(layer "F.Cu")
		(net "PD_PCH_GPPC_A_18")
	)
	(segment
		(start 327.099422 -24.303228)
		(end 327.099422 -24.194516)
		(width 0.12954)
		(layer "F.Cu")
		(net "PD_PCH_GPPC_A_18")
	)
	(segment
		(start 327.39584 -26.370788)
		(end 327.39584 -27.733752)
		(width 0.12954)
		(layer "F.Cu")
		(net "PD_PCH_GPPC_A_18")
	)
	(segment
		(start 327.960736 -28.7909)
		(end 328.028808 -29.477208)
		(width 0.0889)
		(layer "F.Cu")
		(net "PD_PCH_GPPC_A_18")
	)
	(segment
		(start 331.397102 -37.653468)
		(end 331.397102 -38.050216)
		(width 0.0889)
		(layer "F.Cu")
		(net "PD_PCH_GPPC_A_18")
	)
	(segment
		(start 329.461622 -31.627318)
		(end 329.461622 -32.107124)
		(width 0.0889)
		(layer "F.Cu")
		(net "PD_PCH_GPPC_A_18")
	)
	(segment
		(start 327.129902 -24.164036)
		(end 327.129902 -23.061676)
		(width 0.12954)
		(layer "F.Cu")
		(net "PD_PCH_GPPC_A_18")
	)
	(segment
		(start 328.028808 -29.477208)
		(end 328.610722 -30.564836)
		(width 0.0889)
		(layer "F.Cu")
		(net "PD_PCH_GPPC_A_18")
	)
	(via
		(at 327.099422 -24.303228)
		(size 0.762)
		(drill 0.381)
		(layers "F.Cu" "B.Cu")
		(net "PD_PCH_GPPC_A_18")
	)
	(segment
		(start 331.575918 -33.953196)
		(end 331.575918 -31.298896)
		(width 0.0889)
		(layer "F.Cu")
		(net "PD_PCH_GPPC_A_15")
	)
	(segment
		(start 332.897734 -38.465252)
		(end 332.897734 -38.182804)
		(width 0.0889)
		(layer "F.Cu")
		(net "PD_PCH_GPPC_A_15")
	)
	(segment
		(start 332.657704 -37.376354)
		(end 332.657704 -35.034982)
		(width 0.0889)
		(layer "F.Cu")
		(net "PD_PCH_GPPC_A_15")
	)
	(segment
		(start 332.657704 -35.034982)
		(end 331.575918 -33.953196)
		(width 0.0889)
		(layer "F.Cu")
		(net "PD_PCH_GPPC_A_15")
	)
	(segment
		(start 332.897734 -38.182804)
		(end 332.611222 -37.754306)
		(width 0.0889)
		(layer "F.Cu")
		(net "PD_PCH_GPPC_A_15")
	)
	(segment
		(start 331.575918 -31.298896)
		(end 331.181964 -30.904942)
		(width 0.0889)
		(layer "F.Cu")
		(net "PD_PCH_GPPC_A_15")
	)
	(segment
		(start 331.181964 -30.904942)
		(end 330.72832 -29.809694)
		(width 0.0889)
		(layer "F.Cu")
		(net "PD_PCH_GPPC_A_15")
	)
	(segment
		(start 332.611222 -37.754306)
		(end 332.611222 -37.534342)
		(width 0.0889)
		(layer "F.Cu")
		(net "PD_PCH_GPPC_A_15")
	)
	(segment
		(start 332.611222 -37.534342)
		(end 332.657704 -37.376354)
		(width 0.0889)
		(layer "F.Cu")
		(net "PD_PCH_GPPC_A_15")
	)
	(segment
		(start 330.72832 -29.809694)
		(end 330.72832 -29.726128)
		(width 0.0889)
		(layer "F.Cu")
		(net "PD_PCH_GPPC_A_15")
	)
	(via
		(at 330.72832 -29.726128)
		(size 0.508)
		(drill 0.254)
		(layers "F.Cu" "B.Cu")
		(net "PD_PCH_GPPC_A_15")
	)
	(segment
		(start 330.72832 -29.611828)
		(end 332.46568 -27.874468)
		(width 0.12954)
		(layer "B.Cu")
		(net "PD_PCH_GPPC_A_15")
	)
	(segment
		(start 331.90688 -26.965148)
		(end 331.49413 -26.552398)
		(width 0.12954)
		(layer "B.Cu")
		(net "PD_PCH_GPPC_A_15")
	)
	(segment
		(start 332.46568 -27.244548)
		(end 332.290928 -27.069796)
		(width 0.12954)
		(layer "B.Cu")
		(net "PD_PCH_GPPC_A_15")
	)
	(segment
		(start 332.038198 -26.965148)
		(end 331.90688 -26.965148)
		(width 0.12954)
		(layer "B.Cu")
		(net "PD_PCH_GPPC_A_15")
	)
	(segment
		(start 332.290928 -27.069796)
		(end 332.038198 -26.965148)
		(width 0.12954)
		(layer "B.Cu")
		(net "PD_PCH_GPPC_A_15")
	)
	(segment
		(start 332.46568 -27.874468)
		(end 332.46568 -27.244548)
		(width 0.12954)
		(layer "B.Cu")
		(net "PD_PCH_GPPC_A_15")
	)
	(segment
		(start 330.72832 -29.726128)
		(end 330.72832 -29.611828)
		(width 0.12954)
		(layer "B.Cu")
		(net "PD_PCH_GPPC_A_15")
	)
	(segment
		(start 331.49413 -26.552398)
		(end 331.49413 -25.212548)
		(width 0.12954)
		(layer "B.Cu")
		(net "PD_PCH_GPPC_A_15")
	)
	(segment
		(start 330.748894 -34.479484)
		(end 330.748894 -33.73882)
		(width 0.0889)
		(layer "F.Cu")
		(net "PD_PCH_GPPC_A_14")
	)
	(segment
		(start 331.651864 -35.382454)
		(end 330.748894 -34.479484)
		(width 0.0889)
		(layer "F.Cu")
		(net "PD_PCH_GPPC_A_14")
	)
	(segment
		(start 331.610716 -37.738558)
		(end 331.610716 -37.48151)
		(width 0.0889)
		(layer "F.Cu")
		(net "PD_PCH_GPPC_A_14")
	)
	(segment
		(start 328.18832 -26.612088)
		(end 327.979278 -26.82113)
		(width 0.12954)
		(layer "F.Cu")
		(net "PD_PCH_GPPC_A_14")
	)
	(segment
		(start 328.123042 -23.074376)
		(end 327.8251 -23.372318)
		(width 0.12954)
		(layer "F.Cu")
		(net "PD_PCH_GPPC_A_14")
	)
	(segment
		(start 330.748894 -33.73882)
		(end 329.969622 -32.959548)
		(width 0.0889)
		(layer "F.Cu")
		(net "PD_PCH_GPPC_A_14")
	)
	(segment
		(start 328.702416 -27.544268)
		(end 327.979278 -26.82113)
		(width 0.12954)
		(layer "F.Cu")
		(net "PD_PCH_GPPC_A_14")
	)
	(segment
		(start 329.766422 -31.554928)
		(end 328.94397 -30.732476)
		(width 0.0889)
		(layer "F.Cu")
		(net "PD_PCH_GPPC_A_14")
	)
	(segment
		(start 328.460354 -28.345384)
		(end 328.702416 -28.103322)
		(width 0.12954)
		(layer "F.Cu")
		(net "PD_PCH_GPPC_A_14")
	)
	(segment
		(start 329.766422 -32.046164)
		(end 329.766422 -31.554928)
		(width 0.0889)
		(layer "F.Cu")
		(net "PD_PCH_GPPC_A_14")
	)
	(segment
		(start 329.969622 -32.959548)
		(end 329.969622 -32.249364)
		(width 0.0889)
		(layer "F.Cu")
		(net "PD_PCH_GPPC_A_14")
	)
	(segment
		(start 328.702416 -28.103322)
		(end 328.702416 -27.544268)
		(width 0.12954)
		(layer "F.Cu")
		(net "PD_PCH_GPPC_A_14")
	)
	(segment
		(start 328.18832 -25.514808)
		(end 328.18832 -26.612088)
		(width 0.12954)
		(layer "F.Cu")
		(net "PD_PCH_GPPC_A_14")
	)
	(segment
		(start 328.94397 -30.732476)
		(end 328.460354 -29.565854)
		(width 0.0889)
		(layer "F.Cu")
		(net "PD_PCH_GPPC_A_14")
	)
	(segment
		(start 327.8251 -23.372318)
		(end 327.8251 -25.151588)
		(width 0.12954)
		(layer "F.Cu")
		(net "PD_PCH_GPPC_A_14")
	)
	(segment
		(start 331.897482 -38.465252)
		(end 331.897482 -38.183058)
		(width 0.0889)
		(layer "F.Cu")
		(net "PD_PCH_GPPC_A_14")
	)
	(segment
		(start 327.8251 -25.151588)
		(end 328.18832 -25.514808)
		(width 0.12954)
		(layer "F.Cu")
		(net "PD_PCH_GPPC_A_14")
	)
	(segment
		(start 331.651864 -37.34181)
		(end 331.651864 -35.382454)
		(width 0.0889)
		(layer "F.Cu")
		(net "PD_PCH_GPPC_A_14")
	)
	(segment
		(start 331.610716 -37.48151)
		(end 331.651864 -37.34181)
		(width 0.0889)
		(layer "F.Cu")
		(net "PD_PCH_GPPC_A_14")
	)
	(segment
		(start 328.460354 -29.565854)
		(end 328.460354 -28.345384)
		(width 0.12954)
		(layer "F.Cu")
		(net "PD_PCH_GPPC_A_14")
	)
	(segment
		(start 331.63002 -37.783008)
		(end 331.610716 -37.738558)
		(width 0.0889)
		(layer "F.Cu")
		(net "PD_PCH_GPPC_A_14")
	)
	(segment
		(start 329.969622 -32.249364)
		(end 329.766422 -32.046164)
		(width 0.0889)
		(layer "F.Cu")
		(net "PD_PCH_GPPC_A_14")
	)
	(segment
		(start 331.897482 -38.183058)
		(end 331.63002 -37.783008)
		(width 0.0889)
		(layer "F.Cu")
		(net "PD_PCH_GPPC_A_14")
	)
	(via
		(at 327.979278 -26.82113)
		(size 0.762)
		(drill 0.381)
		(layers "F.Cu" "B.Cu")
		(net "PD_PCH_GPPC_A_14")
	)
	(segment
		(start 334.39862 -38.518084)
		(end 334.39862 -38.880288)
		(width 0.0889)
		(layer "F.Cu")
		(net "PD_PCH_GPPC_A_10")
	)
	(segment
		(start 334.179164 -36.908486)
		(end 334.179164 -37.817806)
		(width 0.0889)
		(layer "F.Cu")
		(net "PD_PCH_GPPC_A_10")
	)
	(segment
		(start 333.98968 -34.381694)
		(end 334.144366 -34.53638)
		(width 0.0889)
		(layer "F.Cu")
		(net "PD_PCH_GPPC_A_10")
	)
	(segment
		(start 334.097376 -38.19652)
		(end 334.226154 -38.345618)
		(width 0.0889)
		(layer "F.Cu")
		(net "PD_PCH_GPPC_A_10")
	)
	(segment
		(start 323.72808 -22.012148)
		(end 323.72808 -21.446998)
		(width 0.12954)
		(layer "F.Cu")
		(net "PD_PCH_GPPC_A_10")
	)
	(segment
		(start 334.226154 -38.345618)
		(end 334.39862 -38.518084)
		(width 0.0889)
		(layer "F.Cu")
		(net "PD_PCH_GPPC_A_10")
	)
	(segment
		(start 334.144366 -36.732972)
		(end 334.161638 -36.820348)
		(width 0.0889)
		(layer "F.Cu")
		(net "PD_PCH_GPPC_A_10")
	)
	(segment
		(start 334.179164 -37.817806)
		(end 334.097376 -37.899594)
		(width 0.0889)
		(layer "F.Cu")
		(net "PD_PCH_GPPC_A_10")
	)
	(segment
		(start 334.161638 -36.820348)
		(end 334.179164 -36.908486)
		(width 0.0889)
		(layer "F.Cu")
		(net "PD_PCH_GPPC_A_10")
	)
	(segment
		(start 334.097376 -37.899594)
		(end 334.097376 -38.19652)
		(width 0.0889)
		(layer "F.Cu")
		(net "PD_PCH_GPPC_A_10")
	)
	(segment
		(start 324.05828 -22.342348)
		(end 323.72808 -22.012148)
		(width 0.12954)
		(layer "F.Cu")
		(net "PD_PCH_GPPC_A_10")
	)
	(segment
		(start 334.144366 -34.53638)
		(end 334.144366 -36.732972)
		(width 0.0889)
		(layer "F.Cu")
		(net "PD_PCH_GPPC_A_10")
	)
	(via
		(at 333.98968 -34.381694)
		(size 0.508)
		(drill 0.254)
		(layers "F.Cu" "B.Cu")
		(net "PD_PCH_GPPC_A_10")
	)
	(via
		(at 324.05828 -22.342348)
		(size 0.508)
		(drill 0.254)
		(layers "F.Cu" "B.Cu")
		(net "PD_PCH_GPPC_A_10")
	)
	(segment
		(start 333.262732 -33.654746)
		(end 333.262732 -26.543)
		(width 0.127)
		(layer "In2.Cu")
		(net "PD_PCH_GPPC_A_10")
	)
	(segment
		(start 329.21448 -24.399748)
		(end 329.21448 -23.460964)
		(width 0.127)
		(layer "In2.Cu")
		(net "PD_PCH_GPPC_A_10")
	)
	(segment
		(start 331.77988 -25.060148)
		(end 329.87488 -25.060148)
		(width 0.127)
		(layer "In2.Cu")
		(net "PD_PCH_GPPC_A_10")
	)
	(segment
		(start 333.98968 -34.381694)
		(end 333.262732 -33.654746)
		(width 0.127)
		(layer "In2.Cu")
		(net "PD_PCH_GPPC_A_10")
	)
	(segment
		(start 324.68185 -21.718778)
		(end 324.05828 -22.342348)
		(width 0.127)
		(layer "In2.Cu")
		(net "PD_PCH_GPPC_A_10")
	)
	(segment
		(start 329.87488 -25.060148)
		(end 329.21448 -24.399748)
		(width 0.127)
		(layer "In2.Cu")
		(net "PD_PCH_GPPC_A_10")
	)
	(segment
		(start 327.472294 -21.718778)
		(end 324.68185 -21.718778)
		(width 0.127)
		(layer "In2.Cu")
		(net "PD_PCH_GPPC_A_10")
	)
	(segment
		(start 329.21448 -23.460964)
		(end 327.472294 -21.718778)
		(width 0.127)
		(layer "In2.Cu")
		(net "PD_PCH_GPPC_A_10")
	)
	(segment
		(start 333.262732 -26.543)
		(end 331.77988 -25.060148)
		(width 0.127)
		(layer "In2.Cu")
		(net "PD_PCH_GPPC_A_10")
	)
	(segment
		(start 330.921614 -50.329846)
		(end 330.79436 -50.4571)
		(width 0.12954)
		(layer "F.Cu")
		(net "PD_GPP_M_8")
	)
	(segment
		(start 330.79436 -50.4571)
		(end 330.79436 -50.799746)
		(width 0.12954)
		(layer "F.Cu")
		(net "PD_GPP_M_8")
	)
	(segment
		(start 331.065378 -50.329846)
		(end 330.921614 -50.329846)
		(width 0.12954)
		(layer "F.Cu")
		(net "PD_GPP_M_8")
	)
	(via
		(at 332.719172 -51.101498)
		(size 0.6604)
		(drill 0.3302)
		(layers "F.Cu" "B.Cu")
		(net "PD_GPP_M_8")
	)
	(via
		(at 331.065378 -50.329846)
		(size 0.4572)
		(drill 0.2032)
		(layers "F.Cu" "B.Cu")
		(net "PD_GPP_M_8")
	)
	(via
		(at 312.85688 -53.304948)
		(size 0.762)
		(drill 0.254)
		(layers "F.Cu" "B.Cu")
		(net "PD_GPP_M_8")
	)
	(segment
		(start 312.24093 -53.304948)
		(end 312.85688 -53.304948)
		(width 0.12954)
		(layer "B.Cu")
		(net "PD_GPP_M_8")
	)
	(segment
		(start 332.329536 -50.591974)
		(end 332.067408 -50.329846)
		(width 0.12954)
		(layer "B.Cu")
		(net "PD_GPP_M_8")
	)
	(segment
		(start 332.067408 -50.329846)
		(end 331.065378 -50.329846)
		(width 0.12954)
		(layer "B.Cu")
		(net "PD_GPP_M_8")
	)
	(segment
		(start 332.329536 -50.711862)
		(end 332.329536 -50.591974)
		(width 0.12954)
		(layer "B.Cu")
		(net "PD_GPP_M_8")
	)
	(segment
		(start 332.719172 -51.101498)
		(end 332.329536 -50.711862)
		(width 0.12954)
		(layer "B.Cu")
		(net "PD_GPP_M_8")
	)
	(segment
		(start 330.43368 -51.247548)
		(end 330.05268 -51.247548)
		(width 0.127)
		(layer "In15.Cu")
		(net "PD_GPP_M_8")
	)
	(segment
		(start 313.41568 -52.746148)
		(end 312.85688 -53.304948)
		(width 0.127)
		(layer "In15.Cu")
		(net "PD_GPP_M_8")
	)
	(segment
		(start 331.065378 -50.329846)
		(end 331.065378 -50.61585)
		(width 0.127)
		(layer "In15.Cu")
		(net "PD_GPP_M_8")
	)
	(segment
		(start 316.79388 -50.307748)
		(end 314.35548 -52.746148)
		(width 0.127)
		(layer "In15.Cu")
		(net "PD_GPP_M_8")
	)
	(segment
		(start 314.35548 -52.746148)
		(end 313.41568 -52.746148)
		(width 0.127)
		(layer "In15.Cu")
		(net "PD_GPP_M_8")
	)
	(segment
		(start 330.05268 -51.247548)
		(end 329.58278 -50.777648)
		(width 0.127)
		(layer "In15.Cu")
		(net "PD_GPP_M_8")
	)
	(segment
		(start 329.58278 -50.777648)
		(end 327.09866 -50.777648)
		(width 0.127)
		(layer "In15.Cu")
		(net "PD_GPP_M_8")
	)
	(segment
		(start 326.62876 -50.307748)
		(end 316.79388 -50.307748)
		(width 0.127)
		(layer "In15.Cu")
		(net "PD_GPP_M_8")
	)
	(segment
		(start 331.065378 -50.61585)
		(end 330.43368 -51.247548)
		(width 0.127)
		(layer "In15.Cu")
		(net "PD_GPP_M_8")
	)
	(segment
		(start 327.09866 -50.777648)
		(end 326.62876 -50.307748)
		(width 0.127)
		(layer "In15.Cu")
		(net "PD_GPP_M_8")
	)
	(segment
		(start 332.693518 -50.329846)
		(end 332.549246 -50.329846)
		(width 0.12954)
		(layer "F.Cu")
		(net "PD_GPP_M_17")
	)
	(segment
		(start 332.422246 -50.456846)
		(end 332.422246 -50.799746)
		(width 0.12954)
		(layer "F.Cu")
		(net "PD_GPP_M_17")
	)
	(segment
		(start 332.549246 -50.329846)
		(end 332.422246 -50.456846)
		(width 0.12954)
		(layer "F.Cu")
		(net "PD_GPP_M_17")
	)
	(via
		(at 313.253628 -51.27625)
		(size 0.762)
		(drill 0.254)
		(layers "F.Cu" "B.Cu")
		(net "PD_GPP_M_17")
	)
	(via
		(at 332.693518 -50.329846)
		(size 0.4572)
		(drill 0.2032)
		(layers "F.Cu" "B.Cu")
		(net "PD_GPP_M_17")
	)
	(segment
		(start 312.24093 -52.288948)
		(end 313.253628 -51.27625)
		(width 0.12954)
		(layer "B.Cu")
		(net "PD_GPP_M_17")
	)
	(segment
		(start 329.62088 -49.875948)
		(end 315.52388 -49.875948)
		(width 0.127)
		(layer "In15.Cu")
		(net "PD_GPP_M_17")
	)
	(segment
		(start 332.693518 -50.329846)
		(end 331.700378 -50.329846)
		(width 0.127)
		(layer "In15.Cu")
		(net "PD_GPP_M_17")
	)
	(segment
		(start 314.73648 -50.663348)
		(end 313.86653 -50.663348)
		(width 0.127)
		(layer "In15.Cu")
		(net "PD_GPP_M_17")
	)
	(segment
		(start 330.86548 -49.875948)
		(end 330.40066 -50.340768)
		(width 0.127)
		(layer "In15.Cu")
		(net "PD_GPP_M_17")
	)
	(segment
		(start 331.700378 -50.329846)
		(end 331.24648 -49.875948)
		(width 0.127)
		(layer "In15.Cu")
		(net "PD_GPP_M_17")
	)
	(segment
		(start 313.86653 -50.663348)
		(end 313.253628 -51.27625)
		(width 0.127)
		(layer "In15.Cu")
		(net "PD_GPP_M_17")
	)
	(segment
		(start 331.24648 -49.875948)
		(end 330.86548 -49.875948)
		(width 0.127)
		(layer "In15.Cu")
		(net "PD_GPP_M_17")
	)
	(segment
		(start 315.52388 -49.875948)
		(end 314.73648 -50.663348)
		(width 0.127)
		(layer "In15.Cu")
		(net "PD_GPP_M_17")
	)
	(segment
		(start 330.40066 -50.340768)
		(end 330.0857 -50.340768)
		(width 0.127)
		(layer "In15.Cu")
		(net "PD_GPP_M_17")
	)
	(segment
		(start 330.0857 -50.340768)
		(end 329.62088 -49.875948)
		(width 0.127)
		(layer "In15.Cu")
		(net "PD_GPP_M_17")
	)
	(segment
		(start 330.79436 -53.619146)
		(end 330.252578 -53.619146)
		(width 0.12954)
		(layer "F.Cu")
		(net "PD_GPP_M_16")
	)
	(via
		(at 330.252578 -53.619146)
		(size 0.4572)
		(drill 0.2032)
		(layers "F.Cu" "B.Cu")
		(net "PD_GPP_M_16")
	)
	(via
		(at 312.85688 -55.336948)
		(size 0.762)
		(drill 0.254)
		(layers "F.Cu" "B.Cu")
		(net "PD_GPP_M_16")
	)
	(segment
		(start 312.24093 -55.336948)
		(end 312.85688 -55.336948)
		(width 0.12954)
		(layer "B.Cu")
		(net "PD_GPP_M_16")
	)
	(segment
		(start 325.27748 -53.127148)
		(end 324.69328 -53.711348)
		(width 0.127)
		(layer "In15.Cu")
		(net "PD_GPP_M_16")
	)
	(segment
		(start 318.49568 -54.066948)
		(end 317.80988 -54.752748)
		(width 0.127)
		(layer "In15.Cu")
		(net "PD_GPP_M_16")
	)
	(segment
		(start 317.80988 -54.752748)
		(end 313.88304 -54.752748)
		(width 0.127)
		(layer "In15.Cu")
		(net "PD_GPP_M_16")
	)
	(segment
		(start 313.88304 -54.752748)
		(end 313.29884 -55.336948)
		(width 0.127)
		(layer "In15.Cu")
		(net "PD_GPP_M_16")
	)
	(segment
		(start 324.69328 -53.711348)
		(end 320.52768 -53.711348)
		(width 0.127)
		(layer "In15.Cu")
		(net "PD_GPP_M_16")
	)
	(segment
		(start 320.52768 -53.711348)
		(end 320.17208 -54.066948)
		(width 0.127)
		(layer "In15.Cu")
		(net "PD_GPP_M_16")
	)
	(segment
		(start 329.274678 -53.619146)
		(end 328.78268 -53.127148)
		(width 0.127)
		(layer "In15.Cu")
		(net "PD_GPP_M_16")
	)
	(segment
		(start 328.78268 -53.127148)
		(end 325.27748 -53.127148)
		(width 0.127)
		(layer "In15.Cu")
		(net "PD_GPP_M_16")
	)
	(segment
		(start 330.252578 -53.619146)
		(end 329.274678 -53.619146)
		(width 0.127)
		(layer "In15.Cu")
		(net "PD_GPP_M_16")
	)
	(segment
		(start 320.17208 -54.066948)
		(end 318.49568 -54.066948)
		(width 0.127)
		(layer "In15.Cu")
		(net "PD_GPP_M_16")
	)
	(segment
		(start 313.29884 -55.336948)
		(end 312.85688 -55.336948)
		(width 0.127)
		(layer "In15.Cu")
		(net "PD_GPP_M_16")
	)
	(segment
		(start 329.980036 -52.209446)
		(end 329.437746 -52.209446)
		(width 0.12954)
		(layer "F.Cu")
		(net "PD_GPP_M_15")
	)
	(via
		(at 329.437746 -52.209446)
		(size 0.4572)
		(drill 0.2032)
		(layers "F.Cu" "B.Cu")
		(net "PD_GPP_M_15")
	)
	(via
		(at 313.38012 -54.501288)
		(size 0.508)
		(drill 0.254)
		(layers "F.Cu" "B.Cu")
		(net "PD_GPP_M_15")
	)
	(via
		(at 327.381616 -51.816508)
		(size 0.6604)
		(drill 0.3302)
		(layers "F.Cu" "B.Cu")
		(net "PD_GPP_M_15")
	)
	(segment
		(start 312.42127 -54.501288)
		(end 312.24093 -54.320948)
		(width 0.12954)
		(layer "B.Cu")
		(net "PD_GPP_M_15")
	)
	(segment
		(start 329.437746 -52.209446)
		(end 329.437746 -52.203858)
		(width 0.12954)
		(layer "B.Cu")
		(net "PD_GPP_M_15")
	)
	(segment
		(start 329.437746 -52.203858)
		(end 329.050396 -51.816508)
		(width 0.12954)
		(layer "B.Cu")
		(net "PD_GPP_M_15")
	)
	(segment
		(start 313.38012 -54.501288)
		(end 312.42127 -54.501288)
		(width 0.12954)
		(layer "B.Cu")
		(net "PD_GPP_M_15")
	)
	(segment
		(start 329.050396 -51.816508)
		(end 327.381616 -51.816508)
		(width 0.12954)
		(layer "B.Cu")
		(net "PD_GPP_M_15")
	)
	(segment
		(start 313.42584 -54.455568)
		(end 313.38012 -54.501288)
		(width 0.127)
		(layer "In15.Cu")
		(net "PD_GPP_M_15")
	)
	(segment
		(start 326.7964 -51.831748)
		(end 317.32728 -51.831748)
		(width 0.127)
		(layer "In15.Cu")
		(net "PD_GPP_M_15")
	)
	(segment
		(start 317.32728 -51.831748)
		(end 315.44768 -53.711348)
		(width 0.127)
		(layer "In15.Cu")
		(net "PD_GPP_M_15")
	)
	(segment
		(start 313.42584 -54.145688)
		(end 313.42584 -54.455568)
		(width 0.127)
		(layer "In15.Cu")
		(net "PD_GPP_M_15")
	)
	(segment
		(start 327.75652 -52.791868)
		(end 326.7964 -51.831748)
		(width 0.127)
		(layer "In15.Cu")
		(net "PD_GPP_M_15")
	)
	(segment
		(start 329.437746 -52.209446)
		(end 328.855324 -52.791868)
		(width 0.127)
		(layer "In15.Cu")
		(net "PD_GPP_M_15")
	)
	(segment
		(start 313.86018 -53.711348)
		(end 313.42584 -54.145688)
		(width 0.127)
		(layer "In15.Cu")
		(net "PD_GPP_M_15")
	)
	(segment
		(start 315.44768 -53.711348)
		(end 313.86018 -53.711348)
		(width 0.127)
		(layer "In15.Cu")
		(net "PD_GPP_M_15")
	)
	(segment
		(start 328.855324 -52.791868)
		(end 327.75652 -52.791868)
		(width 0.127)
		(layer "In15.Cu")
		(net "PD_GPP_M_15")
	)
	(segment
		(start 326.74433 -51.654202)
		(end 326.893682 -51.753516)
		(width 0.0889)
		(layer "F.Cu")
		(net "PD_GPP_I_17")
	)
	(segment
		(start 326.265032 -51.774344)
		(end 326.39508 -51.644296)
		(width 0.0889)
		(layer "F.Cu")
		(net "PD_GPP_I_17")
	)
	(segment
		(start 326.533002 -51.644296)
		(end 326.74433 -51.654202)
		(width 0.0889)
		(layer "F.Cu")
		(net "PD_GPP_I_17")
	)
	(segment
		(start 327.479406 -51.451764)
		(end 327.829926 -51.451764)
		(width 0.0889)
		(layer "F.Cu")
		(net "PD_GPP_I_17")
	)
	(segment
		(start 322.014342 -52.926742)
		(end 323.07784 -51.863244)
		(width 0.12954)
		(layer "F.Cu")
		(net "PD_GPP_I_17")
	)
	(segment
		(start 323.07784 -51.863244)
		(end 323.16674 -51.774344)
		(width 0.0889)
		(layer "F.Cu")
		(net "PD_GPP_I_17")
	)
	(segment
		(start 323.16674 -51.774344)
		(end 326.265032 -51.774344)
		(width 0.0889)
		(layer "F.Cu")
		(net "PD_GPP_I_17")
	)
	(segment
		(start 326.39508 -51.644296)
		(end 326.533002 -51.644296)
		(width 0.0889)
		(layer "F.Cu")
		(net "PD_GPP_I_17")
	)
	(segment
		(start 327.130156 -51.753516)
		(end 327.479406 -51.451764)
		(width 0.0889)
		(layer "F.Cu")
		(net "PD_GPP_I_17")
	)
	(segment
		(start 326.893682 -51.753516)
		(end 327.130156 -51.753516)
		(width 0.0889)
		(layer "F.Cu")
		(net "PD_GPP_I_17")
	)
	(via
		(at 318.24422 -52.187348)
		(size 0.6604)
		(drill 0.3302)
		(layers "F.Cu" "B.Cu")
		(net "PD_GPP_I_17")
	)
	(via
		(at 322.014342 -52.926742)
		(size 0.508)
		(drill 0.254)
		(layers "F.Cu" "B.Cu")
		(net "PD_GPP_I_17")
	)
	(segment
		(start 321.79768 -52.466748)
		(end 320.57848 -52.466748)
		(width 0.12954)
		(layer "B.Cu")
		(net "PD_GPP_I_17")
	)
	(segment
		(start 320.57848 -52.466748)
		(end 320.29908 -52.187348)
		(width 0.12954)
		(layer "B.Cu")
		(net "PD_GPP_I_17")
	)
	(segment
		(start 318.24422 -52.187348)
		(end 315.510672 -52.187348)
		(width 0.12954)
		(layer "B.Cu")
		(net "PD_GPP_I_17")
	)
	(segment
		(start 322.014342 -52.926742)
		(end 322.014342 -52.68341)
		(width 0.12954)
		(layer "B.Cu")
		(net "PD_GPP_I_17")
	)
	(segment
		(start 320.29908 -52.187348)
		(end 318.24422 -52.187348)
		(width 0.12954)
		(layer "B.Cu")
		(net "PD_GPP_I_17")
	)
	(segment
		(start 322.014342 -52.68341)
		(end 321.79768 -52.466748)
		(width 0.12954)
		(layer "B.Cu")
		(net "PD_GPP_I_17")
	)
	(segment
		(start 321.362578 -52.944268)
		(end 321.796918 -53.378608)
		(width 0.12954)
		(layer "F.Cu")
		(net "PD_GPP_I_16")
	)
	(segment
		(start 326.352154 -51.95189)
		(end 326.584818 -51.95189)
		(width 0.0889)
		(layer "F.Cu")
		(net "PD_GPP_I_16")
	)
	(segment
		(start 322.27393 -53.378608)
		(end 322.561966 -53.090572)
		(width 0.12954)
		(layer "F.Cu")
		(net "PD_GPP_I_16")
	)
	(segment
		(start 323.386704 -52.100734)
		(end 323.48805 -51.999388)
		(width 0.0889)
		(layer "F.Cu")
		(net "PD_GPP_I_16")
	)
	(segment
		(start 322.561966 -53.090572)
		(end 322.561966 -52.925472)
		(width 0.12954)
		(layer "F.Cu")
		(net "PD_GPP_I_16")
	)
	(segment
		(start 323.48805 -51.999388)
		(end 326.304656 -51.999388)
		(width 0.0889)
		(layer "F.Cu")
		(net "PD_GPP_I_16")
	)
	(segment
		(start 322.561966 -52.925472)
		(end 323.386704 -52.100734)
		(width 0.12954)
		(layer "F.Cu")
		(net "PD_GPP_I_16")
	)
	(segment
		(start 326.304656 -51.999388)
		(end 326.352154 -51.95189)
		(width 0.0889)
		(layer "F.Cu")
		(net "PD_GPP_I_16")
	)
	(segment
		(start 321.796918 -53.378608)
		(end 322.27393 -53.378608)
		(width 0.12954)
		(layer "F.Cu")
		(net "PD_GPP_I_16")
	)
	(via
		(at 316.700662 -52.890166)
		(size 0.6604)
		(drill 0.3302)
		(layers "F.Cu" "B.Cu")
		(net "PD_GPP_I_16")
	)
	(via
		(at 321.362578 -52.944268)
		(size 0.508)
		(drill 0.254)
		(layers "F.Cu" "B.Cu")
		(net "PD_GPP_I_16")
	)
	(segment
		(start 320.421 -52.944268)
		(end 320.19748 -52.720748)
		(width 0.12954)
		(layer "B.Cu")
		(net "PD_GPP_I_16")
	)
	(segment
		(start 316.38748 -53.203348)
		(end 315.510672 -53.203348)
		(width 0.12954)
		(layer "B.Cu")
		(net "PD_GPP_I_16")
	)
	(segment
		(start 316.700662 -52.890166)
		(end 316.38748 -53.203348)
		(width 0.12954)
		(layer "B.Cu")
		(net "PD_GPP_I_16")
	)
	(segment
		(start 321.362578 -52.944268)
		(end 320.421 -52.944268)
		(width 0.12954)
		(layer "B.Cu")
		(net "PD_GPP_I_16")
	)
	(segment
		(start 320.19748 -52.720748)
		(end 316.87008 -52.720748)
		(width 0.12954)
		(layer "B.Cu")
		(net "PD_GPP_I_16")
	)
	(segment
		(start 316.87008 -52.720748)
		(end 316.700662 -52.890166)
		(width 0.12954)
		(layer "B.Cu")
		(net "PD_GPP_I_16")
	)
	(segment
		(start 322.379086 -54.015132)
		(end 323.18833 -53.205888)
		(width 0.12954)
		(layer "F.Cu")
		(net "PD_GPP_I_15")
	)
	(segment
		(start 321.244976 -54.015132)
		(end 322.379086 -54.015132)
		(width 0.12954)
		(layer "F.Cu")
		(net "PD_GPP_I_15")
	)
	(segment
		(start 323.812408 -52.45227)
		(end 326.999854 -52.45227)
		(width 0.0889)
		(layer "F.Cu")
		(net "PD_GPP_I_15")
	)
	(segment
		(start 320.999104 -53.76926)
		(end 321.244976 -54.015132)
		(width 0.12954)
		(layer "F.Cu")
		(net "PD_GPP_I_15")
	)
	(segment
		(start 319.202562 -53.230272)
		(end 319.74155 -53.76926)
		(width 0.12954)
		(layer "F.Cu")
		(net "PD_GPP_I_15")
	)
	(segment
		(start 323.18833 -53.205888)
		(end 323.18833 -53.076348)
		(width 0.12954)
		(layer "F.Cu")
		(net "PD_GPP_I_15")
	)
	(segment
		(start 323.18833 -53.076348)
		(end 323.50583 -52.758848)
		(width 0.12954)
		(layer "F.Cu")
		(net "PD_GPP_I_15")
	)
	(segment
		(start 318.925702 -53.230272)
		(end 319.202562 -53.230272)
		(width 0.12954)
		(layer "F.Cu")
		(net "PD_GPP_I_15")
	)
	(segment
		(start 323.50583 -52.758848)
		(end 323.812408 -52.45227)
		(width 0.0889)
		(layer "F.Cu")
		(net "PD_GPP_I_15")
	)
	(segment
		(start 319.74155 -53.76926)
		(end 320.999104 -53.76926)
		(width 0.12954)
		(layer "F.Cu")
		(net "PD_GPP_I_15")
	)
	(via
		(at 317.212472 -54.207156)
		(size 0.6604)
		(drill 0.3302)
		(layers "F.Cu" "B.Cu")
		(net "PD_GPP_I_15")
	)
	(via
		(at 318.925702 -53.230272)
		(size 0.508)
		(drill 0.254)
		(layers "F.Cu" "B.Cu")
		(net "PD_GPP_I_15")
	)
	(segment
		(start 318.925702 -53.230272)
		(end 318.189356 -53.230272)
		(width 0.12954)
		(layer "B.Cu")
		(net "PD_GPP_I_15")
	)
	(segment
		(start 317.212472 -54.207156)
		(end 316.99708 -54.422548)
		(width 0.12954)
		(layer "B.Cu")
		(net "PD_GPP_I_15")
	)
	(segment
		(start 315.713872 -54.422548)
		(end 315.510672 -54.219348)
		(width 0.12954)
		(layer "B.Cu")
		(net "PD_GPP_I_15")
	)
	(segment
		(start 318.189356 -53.230272)
		(end 317.212472 -54.207156)
		(width 0.12954)
		(layer "B.Cu")
		(net "PD_GPP_I_15")
	)
	(segment
		(start 316.99708 -54.422548)
		(end 315.713872 -54.422548)
		(width 0.12954)
		(layer "B.Cu")
		(net "PD_GPP_I_15")
	)
	(segment
		(start 18.15592 -100.597208)
		(end 17.195038 -99.636326)
		(width 0.12954)
		(layer "F.Cu")
		(net "NC_USB_HUB_SDA")
	)
	(segment
		(start 18.15592 -101.458268)
		(end 18.15592 -100.597208)
		(width 0.12954)
		(layer "F.Cu")
		(net "NC_USB_HUB_SDA")
	)
	(segment
		(start 17.195038 -99.636326)
		(end 16.477488 -99.636326)
		(width 0.12954)
		(layer "F.Cu")
		(net "NC_USB_HUB_SDA")
	)
	(via
		(at 18.15592 -101.458268)
		(size 0.762)
		(drill 0.381)
		(layers "F.Cu" "B.Cu")
		(net "NC_USB_HUB_SDA")
	)
	(segment
		(start 12.0142 -95.976948)
		(end 12.6492 -95.976948)
		(width 0.12954)
		(layer "F.Cu")
		(net "NC_USB_HUB_DP4")
	)
	(segment
		(start 12.6492 -95.976948)
		(end 13.064998 -96.392746)
		(width 0.12954)
		(layer "F.Cu")
		(net "NC_USB_HUB_DP4")
	)
	(segment
		(start 11.3538 -95.316548)
		(end 12.0142 -95.976948)
		(width 0.12954)
		(layer "F.Cu")
		(net "NC_USB_HUB_DP4")
	)
	(segment
		(start 13.064998 -96.392746)
		(end 13.064998 -96.723962)
		(width 0.12954)
		(layer "F.Cu")
		(net "NC_USB_HUB_DP4")
	)
	(via
		(at 11.3538 -95.316548)
		(size 0.762)
		(drill 0.381)
		(layers "F.Cu" "B.Cu")
		(net "NC_USB_HUB_DP4")
	)
	(segment
		(start 12.499086 -101.913944)
		(end 11.164316 -101.913944)
		(width 0.12954)
		(layer "F.Cu")
		(net "NC_USB_HUB_DP2")
	)
	(segment
		(start 12.564872 -101.548946)
		(end 12.564872 -101.848158)
		(width 0.12954)
		(layer "F.Cu")
		(net "NC_USB_HUB_DP2")
	)
	(segment
		(start 9.811512 -103.266748)
		(end 8.74776 -103.266748)
		(width 0.12954)
		(layer "F.Cu")
		(net "NC_USB_HUB_DP2")
	)
	(segment
		(start 11.164316 -101.913944)
		(end 9.811512 -103.266748)
		(width 0.12954)
		(layer "F.Cu")
		(net "NC_USB_HUB_DP2")
	)
	(segment
		(start 12.564872 -101.848158)
		(end 12.499086 -101.913944)
		(width 0.12954)
		(layer "F.Cu")
		(net "NC_USB_HUB_DP2")
	)
	(via
		(at 8.74776 -103.266748)
		(size 0.762)
		(drill 0.381)
		(layers "F.Cu" "B.Cu")
		(net "NC_USB_HUB_DP2")
	)
	(segment
		(start 10.2616 -96.357948)
		(end 12.445746 -96.357948)
		(width 0.12954)
		(layer "F.Cu")
		(net "NC_USB_HUB_DM4")
	)
	(segment
		(start 12.564872 -96.477074)
		(end 12.564872 -96.723962)
		(width 0.12954)
		(layer "F.Cu")
		(net "NC_USB_HUB_DM4")
	)
	(segment
		(start 10.0584 -96.154748)
		(end 10.2616 -96.357948)
		(width 0.12954)
		(layer "F.Cu")
		(net "NC_USB_HUB_DM4")
	)
	(segment
		(start 12.445746 -96.357948)
		(end 12.564872 -96.477074)
		(width 0.12954)
		(layer "F.Cu")
		(net "NC_USB_HUB_DM4")
	)
	(via
		(at 10.0584 -96.154748)
		(size 0.762)
		(drill 0.381)
		(layers "F.Cu" "B.Cu")
		(net "NC_USB_HUB_DM4")
	)
	(segment
		(start 8.726424 -104.880156)
		(end 11.366246 -102.240334)
		(width 0.12954)
		(layer "F.Cu")
		(net "NC_USB_HUB_DM2")
	)
	(segment
		(start 13.064998 -101.862382)
		(end 13.064998 -101.548946)
		(width 0.12954)
		(layer "F.Cu")
		(net "NC_USB_HUB_DM2")
	)
	(segment
		(start 11.366246 -102.240334)
		(end 12.687046 -102.240334)
		(width 0.12954)
		(layer "F.Cu")
		(net "NC_USB_HUB_DM2")
	)
	(segment
		(start 12.687046 -102.240334)
		(end 13.064998 -101.862382)
		(width 0.12954)
		(layer "F.Cu")
		(net "NC_USB_HUB_DM2")
	)
	(via
		(at 8.726424 -104.880156)
		(size 0.762)
		(drill 0.381)
		(layers "F.Cu" "B.Cu")
		(net "NC_USB_HUB_DM2")
	)
	(segment
		(start 255.432814 -95.311468)
		(end 255.244346 -95.123)
		(width 0.0889)
		(layer "F.Cu")
		(net "NC_CLK_CK440_100M5_DP")
	)
	(segment
		(start 255.432814 -95.68815)
		(end 255.432814 -95.311468)
		(width 0.0889)
		(layer "F.Cu")
		(net "NC_CLK_CK440_100M5_DP")
	)
	(segment
		(start 255.244346 -94.757494)
		(end 254.836422 -94.34957)
		(width 0.12954)
		(layer "F.Cu")
		(net "NC_CLK_CK440_100M5_DP")
	)
	(segment
		(start 255.244346 -95.123)
		(end 255.244346 -94.757494)
		(width 0.12954)
		(layer "F.Cu")
		(net "NC_CLK_CK440_100M5_DP")
	)
	(via
		(at 254.836422 -94.34957)
		(size 0.762)
		(drill 0.381)
		(layers "F.Cu" "B.Cu")
		(net "NC_CLK_CK440_100M5_DP")
	)
	(segment
		(start 254.301244 -93.791532)
		(end 254.002286 -93.492574)
		(width 0.12954)
		(layer "F.Cu")
		(net "NC_CLK_CK440_100M5_DN")
	)
	(segment
		(start 254.301244 -94.631002)
		(end 254.301244 -93.791532)
		(width 0.0889)
		(layer "F.Cu")
		(net "NC_CLK_CK440_100M5_DN")
	)
	(segment
		(start 254.932688 -95.262446)
		(end 254.301244 -94.631002)
		(width 0.0889)
		(layer "F.Cu")
		(net "NC_CLK_CK440_100M5_DN")
	)
	(segment
		(start 254.932688 -95.68815)
		(end 254.932688 -95.262446)
		(width 0.0889)
		(layer "F.Cu")
		(net "NC_CLK_CK440_100M5_DN")
	)
	(via
		(at 254.002286 -93.492574)
		(size 0.762)
		(drill 0.381)
		(layers "F.Cu" "B.Cu")
		(net "NC_CLK_CK440_100M5_DN")
	)
	(segment
		(start 257.43281 -95.68815)
		(end 257.43281 -95.289878)
		(width 0.0889)
		(layer "F.Cu")
		(net "NC_CLK_CK440_100M3_DP")
	)
	(segment
		(start 257.344672 -95.20174)
		(end 257.344672 -93.50883)
		(width 0.12954)
		(layer "F.Cu")
		(net "NC_CLK_CK440_100M3_DP")
	)
	(segment
		(start 257.43281 -95.289878)
		(end 257.344672 -95.20174)
		(width 0.0889)
		(layer "F.Cu")
		(net "NC_CLK_CK440_100M3_DP")
	)
	(via
		(at 257.344672 -93.50883)
		(size 0.762)
		(drill 0.381)
		(layers "F.Cu" "B.Cu")
		(net "NC_CLK_CK440_100M3_DP")
	)
	(segment
		(start 256.932684 -94.659704)
		(end 256.726944 -94.453964)
		(width 0.12954)
		(layer "F.Cu")
		(net "NC_CLK_CK440_100M3_DN")
	)
	(segment
		(start 256.932684 -95.68815)
		(end 256.932684 -94.659704)
		(width 0.12954)
		(layer "F.Cu")
		(net "NC_CLK_CK440_100M3_DN")
	)
	(via
		(at 256.726944 -94.453964)
		(size 0.762)
		(drill 0.381)
		(layers "F.Cu" "B.Cu")
		(net "NC_CLK_CK440_100M3_DN")
	)
	(segment
		(start 258.93268 -95.68815)
		(end 258.93268 -95.526352)
		(width 0.12954)
		(layer "F.Cu")
		(net "NC_CLK_CK440_100M2_DP")
	)
	(segment
		(start 258.93268 -95.526352)
		(end 260.035548 -94.423484)
		(width 0.12954)
		(layer "F.Cu")
		(net "NC_CLK_CK440_100M2_DP")
	)
	(segment
		(start 260.035548 -94.423484)
		(end 260.035548 -94.08795)
		(width 0.12954)
		(layer "F.Cu")
		(net "NC_CLK_CK440_100M2_DP")
	)
	(via
		(at 260.035548 -94.08795)
		(size 0.762)
		(drill 0.381)
		(layers "F.Cu" "B.Cu")
		(net "NC_CLK_CK440_100M2_DP")
	)
	(segment
		(start 258.432808 -95.450152)
		(end 258.9022 -94.98076)
		(width 0.12954)
		(layer "F.Cu")
		(net "NC_CLK_CK440_100M2_DN")
	)
	(segment
		(start 258.432808 -95.68815)
		(end 258.432808 -95.450152)
		(width 0.12954)
		(layer "F.Cu")
		(net "NC_CLK_CK440_100M2_DN")
	)
	(segment
		(start 258.9022 -94.98076)
		(end 258.9022 -94.44482)
		(width 0.12954)
		(layer "F.Cu")
		(net "NC_CLK_CK440_100M2_DN")
	)
	(via
		(at 258.9022 -94.44482)
		(size 0.762)
		(drill 0.381)
		(layers "F.Cu" "B.Cu")
		(net "NC_CLK_CK440_100M2_DN")
	)
	(segment
		(start 262.710168 -96.694498)
		(end 263.482836 -97.467166)
		(width 0.12954)
		(layer "F.Cu")
		(net "NC_CLK_CK440_100M1_DP")
	)
	(segment
		(start 262.435594 -96.694498)
		(end 262.710168 -96.694498)
		(width 0.12954)
		(layer "F.Cu")
		(net "NC_CLK_CK440_100M1_DP")
	)
	(segment
		(start 260.23824 -97.813114)
		(end 261.356856 -96.694498)
		(width 0.0889)
		(layer "F.Cu")
		(net "NC_CLK_CK440_100M1_DP")
	)
	(segment
		(start 261.356856 -96.694498)
		(end 262.435594 -96.694498)
		(width 0.0889)
		(layer "F.Cu")
		(net "NC_CLK_CK440_100M1_DP")
	)
	(segment
		(start 259.557774 -97.813114)
		(end 260.23824 -97.813114)
		(width 0.0889)
		(layer "F.Cu")
		(net "NC_CLK_CK440_100M1_DP")
	)
	(via
		(at 263.482836 -97.467166)
		(size 0.762)
		(drill 0.381)
		(layers "F.Cu" "B.Cu")
		(net "NC_CLK_CK440_100M1_DP")
	)
	(segment
		(start 259.557774 -97.313242)
		(end 260.33603 -97.313242)
		(width 0.0889)
		(layer "F.Cu")
		(net "NC_CLK_CK440_100M1_DN")
	)
	(segment
		(start 262.32231 -96.337374)
		(end 263.623044 -96.337374)
		(width 0.12954)
		(layer "F.Cu")
		(net "NC_CLK_CK440_100M1_DN")
	)
	(segment
		(start 260.33603 -97.313242)
		(end 261.311898 -96.337374)
		(width 0.0889)
		(layer "F.Cu")
		(net "NC_CLK_CK440_100M1_DN")
	)
	(segment
		(start 261.311898 -96.337374)
		(end 262.32231 -96.337374)
		(width 0.0889)
		(layer "F.Cu")
		(net "NC_CLK_CK440_100M1_DN")
	)
	(segment
		(start 263.623044 -96.337374)
		(end 264.752836 -97.467166)
		(width 0.12954)
		(layer "F.Cu")
		(net "NC_CLK_CK440_100M1_DN")
	)
	(via
		(at 264.752836 -97.467166)
		(size 0.762)
		(drill 0.381)
		(layers "F.Cu" "B.Cu")
		(net "NC_CLK_CK440_100M1_DN")
	)
	(segment
		(start 333.08036 -21.979128)
		(end 332.34376 -21.979128)
		(width 0.12954)
		(layer "F.Cu")
		(net "IRQ_LPC_SERIRQ_ESPI_CS1_R_N")
	)
	(segment
		(start 335.87563 -21.687028)
		(end 333.37246 -21.687028)
		(width 0.12954)
		(layer "F.Cu")
		(net "IRQ_LPC_SERIRQ_ESPI_CS1_R_N")
	)
	(segment
		(start 333.37246 -21.687028)
		(end 333.08036 -21.979128)
		(width 0.12954)
		(layer "F.Cu")
		(net "IRQ_LPC_SERIRQ_ESPI_CS1_R_N")
	)
	(segment
		(start 336.492342 -20.434554)
		(end 336.492342 -21.070316)
		(width 0.12954)
		(layer "F.Cu")
		(net "IRQ_LPC_SERIRQ_ESPI_CS1_R_N")
	)
	(segment
		(start 332.34376 -21.979128)
		(end 332.0161 -21.651468)
		(width 0.12954)
		(layer "F.Cu")
		(net "IRQ_LPC_SERIRQ_ESPI_CS1_R_N")
	)
	(segment
		(start 332.0161 -21.072602)
		(end 332.317852 -20.77085)
		(width 0.12954)
		(layer "F.Cu")
		(net "IRQ_LPC_SERIRQ_ESPI_CS1_R_N")
	)
	(segment
		(start 336.492342 -21.070316)
		(end 335.87563 -21.687028)
		(width 0.12954)
		(layer "F.Cu")
		(net "IRQ_LPC_SERIRQ_ESPI_CS1_R_N")
	)
	(segment
		(start 332.0161 -21.651468)
		(end 332.0161 -21.072602)
		(width 0.12954)
		(layer "F.Cu")
		(net "IRQ_LPC_SERIRQ_ESPI_CS1_R_N")
	)
	(via
		(at 332.34376 -21.979128)
		(size 0.762)
		(drill 0.381)
		(layers "F.Cu" "B.Cu")
		(net "IRQ_LPC_SERIRQ_ESPI_CS1_R_N")
	)
	(segment
		(start 295.398952 -426.227748)
		(end 295.548304 -426.078396)
		(width 0.12954)
		(layer "F.Cu")
		(net "PRSNT_CABLE_GPU_A1")
	)
	(segment
		(start 294.302434 -426.188632)
		(end 294.34155 -426.227748)
		(width 0.12954)
		(layer "F.Cu")
		(net "PRSNT_CABLE_GPU_A1")
	)
	(segment
		(start 294.95242 -424.95597)
		(end 294.302434 -424.95597)
		(width 0.12954)
		(layer "F.Cu")
		(net "PRSNT_CABLE_GPU_A1")
	)
	(segment
		(start 294.34155 -426.227748)
		(end 295.398952 -426.227748)
		(width 0.12954)
		(layer "F.Cu")
		(net "PRSNT_CABLE_GPU_A1")
	)
	(segment
		(start 294.302434 -424.95597)
		(end 294.302434 -426.188632)
		(width 0.12954)
		(layer "F.Cu")
		(net "PRSNT_CABLE_GPU_A1")
	)
	(via
		(at 294.34155 -426.227748)
		(size 0.762)
		(drill 0.381)
		(layers "F.Cu" "B.Cu")
		(net "PRSNT_CABLE_GPU_A1")
	)
	(segment
		(start 200.60031 -116.804948)
		(end 199.97928 -116.804948)
		(width 0.12954)
		(layer "F.Cu")
		(net "PRSNT_CABLE_GPU_A1_ISO_R_N")
	)
	(segment
		(start 185.355738 -113.77549)
		(end 185.755788 -114.17554)
		(width 0.12954)
		(layer "F.Cu")
		(net "PRSNT_CABLE_GPU_A1_ISO_R_N")
	)
	(via
		(at 199.97928 -116.804948)
		(size 0.508)
		(drill 0.254)
		(layers "F.Cu" "B.Cu")
		(net "PRSNT_CABLE_GPU_A1_ISO_R_N")
	)
	(via
		(at 185.755788 -114.17554)
		(size 0.4572)
		(drill 0.254)
		(layers "F.Cu" "B.Cu")
		(net "PRSNT_CABLE_GPU_A1_ISO_R_N")
	)
	(segment
		(start 189.813946 -116.677948)
		(end 187.311538 -114.17554)
		(width 0.127)
		(layer "In2.Cu")
		(net "PRSNT_CABLE_GPU_A1_ISO_R_N")
	)
	(segment
		(start 199.50938 -117.274848)
		(end 192.14338 -117.274848)
		(width 0.127)
		(layer "In2.Cu")
		(net "PRSNT_CABLE_GPU_A1_ISO_R_N")
	)
	(segment
		(start 191.54648 -116.677948)
		(end 189.813946 -116.677948)
		(width 0.127)
		(layer "In2.Cu")
		(net "PRSNT_CABLE_GPU_A1_ISO_R_N")
	)
	(segment
		(start 199.97928 -116.804948)
		(end 199.50938 -117.274848)
		(width 0.127)
		(layer "In2.Cu")
		(net "PRSNT_CABLE_GPU_A1_ISO_R_N")
	)
	(segment
		(start 187.311538 -114.17554)
		(end 185.755788 -114.17554)
		(width 0.127)
		(layer "In2.Cu")
		(net "PRSNT_CABLE_GPU_A1_ISO_R_N")
	)
	(segment
		(start 192.14338 -117.274848)
		(end 191.54648 -116.677948)
		(width 0.127)
		(layer "In2.Cu")
		(net "PRSNT_CABLE_GPU_A1_ISO_R_N")
	)
	(segment
		(start 294.62222 -419.43401)
		(end 294.62222 -419.42766)
		(width 0.12954)
		(layer "F.Cu")
		(net "PRSNT_CABLE_GPU_A1_N")
	)
	(segment
		(start 294.21455 -417.2204)
		(end 294.8559 -417.2204)
		(width 0.12954)
		(layer "F.Cu")
		(net "PRSNT_CABLE_GPU_A1_N")
	)
	(segment
		(start 294.09009 -418.89553)
		(end 294.09009 -417.34486)
		(width 0.12954)
		(layer "F.Cu")
		(net "PRSNT_CABLE_GPU_A1_N")
	)
	(segment
		(start 294.95242 -422.566338)
		(end 294.62222 -422.236138)
		(width 0.12954)
		(layer "F.Cu")
		(net "PRSNT_CABLE_GPU_A1_N")
	)
	(segment
		(start 294.62222 -419.42766)
		(end 294.09009 -418.89553)
		(width 0.12954)
		(layer "F.Cu")
		(net "PRSNT_CABLE_GPU_A1_N")
	)
	(segment
		(start 294.95242 -423.05605)
		(end 294.95242 -422.566338)
		(width 0.12954)
		(layer "F.Cu")
		(net "PRSNT_CABLE_GPU_A1_N")
	)
	(segment
		(start 294.09009 -417.34486)
		(end 294.21455 -417.2204)
		(width 0.12954)
		(layer "F.Cu")
		(net "PRSNT_CABLE_GPU_A1_N")
	)
	(segment
		(start 294.62222 -422.236138)
		(end 294.62222 -421.81526)
		(width 0.12954)
		(layer "F.Cu")
		(net "PRSNT_CABLE_GPU_A1_N")
	)
	(segment
		(start 294.08755 -419.96868)
		(end 294.62222 -419.43401)
		(width 0.12954)
		(layer "F.Cu")
		(net "PRSNT_CABLE_GPU_A1_N")
	)
	(segment
		(start 294.62222 -421.81526)
		(end 294.08755 -421.28059)
		(width 0.12954)
		(layer "F.Cu")
		(net "PRSNT_CABLE_GPU_A1_N")
	)
	(segment
		(start 294.08755 -421.28059)
		(end 294.08755 -419.96868)
		(width 0.12954)
		(layer "F.Cu")
		(net "PRSNT_CABLE_GPU_A1_N")
	)
	(via
		(at 294.21455 -417.2204)
		(size 0.508)
		(drill 0.254)
		(layers "F.Cu" "B.Cu")
		(net "PRSNT_CABLE_GPU_A1_N")
	)
	(via
		(at 357.48976 -395.618208)
		(size 0.508)
		(drill 0.254)
		(layers "F.Cu" "B.Cu")
		(net "PRSNT_CABLE_GPU_A1_N")
	)
	(segment
		(start 370.494052 -414.512252)
		(end 376.655584 -414.512252)
		(width 0.127)
		(layer "In2.Cu")
		(net "PRSNT_CABLE_GPU_A1_N")
	)
	(segment
		(start 357.48976 -397.172688)
		(end 364.104936 -403.787864)
		(width 0.127)
		(layer "In2.Cu")
		(net "PRSNT_CABLE_GPU_A1_N")
	)
	(segment
		(start 364.104936 -408.635454)
		(end 366.084612 -410.61513)
		(width 0.127)
		(layer "In2.Cu")
		(net "PRSNT_CABLE_GPU_A1_N")
	)
	(segment
		(start 357.48976 -395.618208)
		(end 357.48976 -397.172688)
		(width 0.127)
		(layer "In2.Cu")
		(net "PRSNT_CABLE_GPU_A1_N")
	)
	(segment
		(start 366.59693 -410.61513)
		(end 370.494052 -414.512252)
		(width 0.127)
		(layer "In2.Cu")
		(net "PRSNT_CABLE_GPU_A1_N")
	)
	(segment
		(start 392.91768 -421.147748)
		(end 392.91768 -439.65749)
		(width 0.127)
		(layer "In2.Cu")
		(net "PRSNT_CABLE_GPU_A1_N")
	)
	(segment
		(start 380.57328 -418.429948)
		(end 390.19988 -418.429948)
		(width 0.127)
		(layer "In2.Cu")
		(net "PRSNT_CABLE_GPU_A1_N")
	)
	(segment
		(start 366.084612 -410.61513)
		(end 366.59693 -410.61513)
		(width 0.127)
		(layer "In2.Cu")
		(net "PRSNT_CABLE_GPU_A1_N")
	)
	(segment
		(start 364.104936 -403.787864)
		(end 364.104936 -408.635454)
		(width 0.127)
		(layer "In2.Cu")
		(net "PRSNT_CABLE_GPU_A1_N")
	)
	(segment
		(start 390.19988 -418.429948)
		(end 392.91768 -421.147748)
		(width 0.127)
		(layer "In2.Cu")
		(net "PRSNT_CABLE_GPU_A1_N")
	)
	(segment
		(start 376.655584 -414.512252)
		(end 380.57328 -418.429948)
		(width 0.127)
		(layer "In2.Cu")
		(net "PRSNT_CABLE_GPU_A1_N")
	)
	(segment
		(start 392.91768 -439.65749)
		(end 393.750038 -440.489848)
		(width 0.127)
		(layer "In2.Cu")
		(net "PRSNT_CABLE_GPU_A1_N")
	)
	(segment
		(start 351.275904 -398.694148)
		(end 353.520756 -400.939)
		(width 0.127)
		(layer "In6.Cu")
		(net "PRSNT_CABLE_GPU_A1_N")
	)
	(segment
		(start 301.2948 -407.439368)
		(end 301.2948 -400.929856)
		(width 0.127)
		(layer "In6.Cu")
		(net "PRSNT_CABLE_GPU_A1_N")
	)
	(segment
		(start 297.20794 -408.8511)
		(end 298.492672 -407.566368)
		(width 0.127)
		(layer "In6.Cu")
		(net "PRSNT_CABLE_GPU_A1_N")
	)
	(segment
		(start 294.88892 -416.814)
		(end 294.88892 -410.59354)
		(width 0.127)
		(layer "In6.Cu")
		(net "PRSNT_CABLE_GPU_A1_N")
	)
	(segment
		(start 301.2948 -400.929856)
		(end 303.530508 -398.694148)
		(width 0.127)
		(layer "In6.Cu")
		(net "PRSNT_CABLE_GPU_A1_N")
	)
	(segment
		(start 301.1678 -407.566368)
		(end 301.2948 -407.439368)
		(width 0.127)
		(layer "In6.Cu")
		(net "PRSNT_CABLE_GPU_A1_N")
	)
	(segment
		(start 294.48252 -417.2204)
		(end 294.88892 -416.814)
		(width 0.127)
		(layer "In6.Cu")
		(net "PRSNT_CABLE_GPU_A1_N")
	)
	(segment
		(start 294.88892 -410.59354)
		(end 296.63136 -408.8511)
		(width 0.127)
		(layer "In6.Cu")
		(net "PRSNT_CABLE_GPU_A1_N")
	)
	(segment
		(start 353.520756 -400.939)
		(end 357.36276 -400.939)
		(width 0.127)
		(layer "In6.Cu")
		(net "PRSNT_CABLE_GPU_A1_N")
	)
	(segment
		(start 303.530508 -398.694148)
		(end 351.275904 -398.694148)
		(width 0.127)
		(layer "In6.Cu")
		(net "PRSNT_CABLE_GPU_A1_N")
	)
	(segment
		(start 357.36276 -400.939)
		(end 357.48976 -400.812)
		(width 0.127)
		(layer "In6.Cu")
		(net "PRSNT_CABLE_GPU_A1_N")
	)
	(segment
		(start 296.63136 -408.8511)
		(end 297.20794 -408.8511)
		(width 0.127)
		(layer "In6.Cu")
		(net "PRSNT_CABLE_GPU_A1_N")
	)
	(segment
		(start 357.48976 -400.812)
		(end 357.48976 -395.618208)
		(width 0.127)
		(layer "In6.Cu")
		(net "PRSNT_CABLE_GPU_A1_N")
	)
	(segment
		(start 298.492672 -407.566368)
		(end 301.1678 -407.566368)
		(width 0.127)
		(layer "In6.Cu")
		(net "PRSNT_CABLE_GPU_A1_N")
	)
	(segment
		(start 294.21455 -417.2204)
		(end 294.48252 -417.2204)
		(width 0.127)
		(layer "In6.Cu")
		(net "PRSNT_CABLE_GPU_A1_N")
	)
	(segment
		(start 297.13555 -426.227748)
		(end 298.192952 -426.227748)
		(width 0.12954)
		(layer "F.Cu")
		(net "GPU_3V3IO_RSVD5_FFU_N")
	)
	(segment
		(start 297.74642 -424.95597)
		(end 297.096434 -424.95597)
		(width 0.12954)
		(layer "F.Cu")
		(net "GPU_3V3IO_RSVD5_FFU_N")
	)
	(segment
		(start 297.096434 -424.95597)
		(end 297.096434 -426.188632)
		(width 0.12954)
		(layer "F.Cu")
		(net "GPU_3V3IO_RSVD5_FFU_N")
	)
	(segment
		(start 298.192952 -426.227748)
		(end 298.342304 -426.078396)
		(width 0.12954)
		(layer "F.Cu")
		(net "GPU_3V3IO_RSVD5_FFU_N")
	)
	(segment
		(start 297.096434 -426.188632)
		(end 297.13555 -426.227748)
		(width 0.12954)
		(layer "F.Cu")
		(net "GPU_3V3IO_RSVD5_FFU_N")
	)
	(via
		(at 297.13555 -426.227748)
		(size 0.762)
		(drill 0.381)
		(layers "F.Cu" "B.Cu")
		(net "GPU_3V3IO_RSVD5_FFU_N")
	)
	(segment
		(start 185.355738 -112.97539)
		(end 185.755788 -112.57534)
		(width 0.12954)
		(layer "F.Cu")
		(net "GPU_3V3IO_RSVD5_FFU_ISO_R")
	)
	(segment
		(start 200.60031 -111.724948)
		(end 199.97928 -111.724948)
		(width 0.12954)
		(layer "F.Cu")
		(net "GPU_3V3IO_RSVD5_FFU_ISO_R")
	)
	(via
		(at 185.755788 -112.57534)
		(size 0.4572)
		(drill 0.254)
		(layers "F.Cu" "B.Cu")
		(net "GPU_3V3IO_RSVD5_FFU_ISO_R")
	)
	(via
		(at 199.97928 -111.724948)
		(size 0.508)
		(drill 0.254)
		(layers "F.Cu" "B.Cu")
		(net "GPU_3V3IO_RSVD5_FFU_ISO_R")
	)
	(segment
		(start 188.501274 -111.056928)
		(end 191.5033 -111.056928)
		(width 0.127)
		(layer "In2.Cu")
		(net "GPU_3V3IO_RSVD5_FFU_ISO_R")
	)
	(segment
		(start 199.97928 -111.518954)
		(end 199.97928 -111.724948)
		(width 0.127)
		(layer "In2.Cu")
		(net "GPU_3V3IO_RSVD5_FFU_ISO_R")
	)
	(segment
		(start 185.972196 -112.57534)
		(end 186.662568 -111.884968)
		(width 0.127)
		(layer "In2.Cu")
		(net "GPU_3V3IO_RSVD5_FFU_ISO_R")
	)
	(segment
		(start 185.755788 -112.57534)
		(end 185.972196 -112.57534)
		(width 0.127)
		(layer "In2.Cu")
		(net "GPU_3V3IO_RSVD5_FFU_ISO_R")
	)
	(segment
		(start 192.318132 -110.242096)
		(end 198.702422 -110.242096)
		(width 0.127)
		(layer "In2.Cu")
		(net "GPU_3V3IO_RSVD5_FFU_ISO_R")
	)
	(segment
		(start 191.5033 -111.056928)
		(end 192.318132 -110.242096)
		(width 0.127)
		(layer "In2.Cu")
		(net "GPU_3V3IO_RSVD5_FFU_ISO_R")
	)
	(segment
		(start 186.662568 -111.884968)
		(end 187.673234 -111.884968)
		(width 0.127)
		(layer "In2.Cu")
		(net "GPU_3V3IO_RSVD5_FFU_ISO_R")
	)
	(segment
		(start 198.702422 -110.242096)
		(end 199.97928 -111.518954)
		(width 0.127)
		(layer "In2.Cu")
		(net "GPU_3V3IO_RSVD5_FFU_ISO_R")
	)
	(segment
		(start 187.673234 -111.884968)
		(end 188.501274 -111.056928)
		(width 0.127)
		(layer "In2.Cu")
		(net "GPU_3V3IO_RSVD5_FFU_ISO_R")
	)
	(segment
		(start 299.22089 -417.58362)
		(end 298.85767 -417.2204)
		(width 0.12954)
		(layer "F.Cu")
		(net "GPU_3V3IO_RSVD5_FFU_ISO")
	)
	(segment
		(start 298.85767 -417.2204)
		(end 298.45 -417.2204)
		(width 0.12954)
		(layer "F.Cu")
		(net "GPU_3V3IO_RSVD5_FFU_ISO")
	)
	(segment
		(start 298.66082 -419.42766)
		(end 299.22089 -418.86759)
		(width 0.12954)
		(layer "F.Cu")
		(net "GPU_3V3IO_RSVD5_FFU_ISO")
	)
	(segment
		(start 298.039282 -419.73627)
		(end 298.347892 -419.42766)
		(width 0.12954)
		(layer "F.Cu")
		(net "GPU_3V3IO_RSVD5_FFU_ISO")
	)
	(segment
		(start 298.66082 -422.345612)
		(end 298.66082 -421.81526)
		(width 0.12954)
		(layer "F.Cu")
		(net "GPU_3V3IO_RSVD5_FFU_ISO")
	)
	(segment
		(start 299.22089 -418.86759)
		(end 299.22089 -417.58362)
		(width 0.12954)
		(layer "F.Cu")
		(net "GPU_3V3IO_RSVD5_FFU_ISO")
	)
	(segment
		(start 298.66082 -421.81526)
		(end 298.039282 -421.193722)
		(width 0.12954)
		(layer "F.Cu")
		(net "GPU_3V3IO_RSVD5_FFU_ISO")
	)
	(segment
		(start 298.347892 -419.42766)
		(end 298.66082 -419.42766)
		(width 0.12954)
		(layer "F.Cu")
		(net "GPU_3V3IO_RSVD5_FFU_ISO")
	)
	(segment
		(start 201.40041 -111.724948)
		(end 202.01128 -111.724948)
		(width 0.12954)
		(layer "F.Cu")
		(net "GPU_3V3IO_RSVD5_FFU_ISO")
	)
	(segment
		(start 298.396406 -423.05605)
		(end 298.396406 -422.610026)
		(width 0.12954)
		(layer "F.Cu")
		(net "GPU_3V3IO_RSVD5_FFU_ISO")
	)
	(segment
		(start 298.039282 -421.193722)
		(end 298.039282 -419.73627)
		(width 0.12954)
		(layer "F.Cu")
		(net "GPU_3V3IO_RSVD5_FFU_ISO")
	)
	(segment
		(start 298.396406 -422.610026)
		(end 298.66082 -422.345612)
		(width 0.12954)
		(layer "F.Cu")
		(net "GPU_3V3IO_RSVD5_FFU_ISO")
	)
	(via
		(at 209.82686 -341.467948)
		(size 0.508)
		(drill 0.254)
		(layers "F.Cu" "B.Cu")
		(net "GPU_3V3IO_RSVD5_FFU_ISO")
	)
	(via
		(at 298.039282 -419.73627)
		(size 0.508)
		(drill 0.254)
		(layers "F.Cu" "B.Cu")
		(net "GPU_3V3IO_RSVD5_FFU_ISO")
	)
	(via
		(at 202.01128 -111.724948)
		(size 0.508)
		(drill 0.254)
		(layers "F.Cu" "B.Cu")
		(net "GPU_3V3IO_RSVD5_FFU_ISO")
	)
	(segment
		(start 260.524752 -353.360228)
		(end 265.63574 -358.471216)
		(width 0.12954)
		(layer "B.Cu")
		(net "GPU_3V3IO_RSVD5_FFU_ISO")
	)
	(segment
		(start 284.861 -396.061946)
		(end 284.861 -407.141934)
		(width 0.12954)
		(layer "B.Cu")
		(net "GPU_3V3IO_RSVD5_FFU_ISO")
	)
	(segment
		(start 209.82686 -341.467948)
		(end 240.882932 -341.467948)
		(width 0.12954)
		(layer "B.Cu")
		(net "GPU_3V3IO_RSVD5_FFU_ISO")
	)
	(segment
		(start 290.58616 -414.7947)
		(end 293.62146 -417.83)
		(width 0.12954)
		(layer "B.Cu")
		(net "GPU_3V3IO_RSVD5_FFU_ISO")
	)
	(segment
		(start 252.775212 -353.360228)
		(end 260.524752 -353.360228)
		(width 0.12954)
		(layer "B.Cu")
		(net "GPU_3V3IO_RSVD5_FFU_ISO")
	)
	(segment
		(start 283.711142 -394.912088)
		(end 284.861 -396.061946)
		(width 0.12954)
		(layer "B.Cu")
		(net "GPU_3V3IO_RSVD5_FFU_ISO")
	)
	(segment
		(start 294.30218 -419.16096)
		(end 297.463972 -419.16096)
		(width 0.12954)
		(layer "B.Cu")
		(net "GPU_3V3IO_RSVD5_FFU_ISO")
	)
	(segment
		(start 265.63574 -372.30812)
		(end 278.86914 -385.54152)
		(width 0.12954)
		(layer "B.Cu")
		(net "GPU_3V3IO_RSVD5_FFU_ISO")
	)
	(segment
		(start 297.463972 -419.16096)
		(end 298.039282 -419.73627)
		(width 0.12954)
		(layer "B.Cu")
		(net "GPU_3V3IO_RSVD5_FFU_ISO")
	)
	(segment
		(start 284.861 -407.141934)
		(end 288.637726 -410.91866)
		(width 0.12954)
		(layer "B.Cu")
		(net "GPU_3V3IO_RSVD5_FFU_ISO")
	)
	(segment
		(start 289.54222 -410.91866)
		(end 290.58616 -411.9626)
		(width 0.12954)
		(layer "B.Cu")
		(net "GPU_3V3IO_RSVD5_FFU_ISO")
	)
	(segment
		(start 265.63574 -358.471216)
		(end 265.63574 -372.30812)
		(width 0.12954)
		(layer "B.Cu")
		(net "GPU_3V3IO_RSVD5_FFU_ISO")
	)
	(segment
		(start 240.882932 -341.467948)
		(end 252.775212 -353.360228)
		(width 0.12954)
		(layer "B.Cu")
		(net "GPU_3V3IO_RSVD5_FFU_ISO")
	)
	(segment
		(start 288.637726 -410.91866)
		(end 289.54222 -410.91866)
		(width 0.12954)
		(layer "B.Cu")
		(net "GPU_3V3IO_RSVD5_FFU_ISO")
	)
	(segment
		(start 278.86914 -385.54152)
		(end 278.86914 -386.131054)
		(width 0.12954)
		(layer "B.Cu")
		(net "GPU_3V3IO_RSVD5_FFU_ISO")
	)
	(segment
		(start 278.86914 -386.131054)
		(end 283.711142 -390.973056)
		(width 0.12954)
		(layer "B.Cu")
		(net "GPU_3V3IO_RSVD5_FFU_ISO")
	)
	(segment
		(start 293.62146 -418.48024)
		(end 294.30218 -419.16096)
		(width 0.12954)
		(layer "B.Cu")
		(net "GPU_3V3IO_RSVD5_FFU_ISO")
	)
	(segment
		(start 283.711142 -390.973056)
		(end 283.711142 -394.912088)
		(width 0.12954)
		(layer "B.Cu")
		(net "GPU_3V3IO_RSVD5_FFU_ISO")
	)
	(segment
		(start 290.58616 -411.9626)
		(end 290.58616 -414.7947)
		(width 0.12954)
		(layer "B.Cu")
		(net "GPU_3V3IO_RSVD5_FFU_ISO")
	)
	(segment
		(start 293.62146 -417.83)
		(end 293.62146 -418.48024)
		(width 0.12954)
		(layer "B.Cu")
		(net "GPU_3V3IO_RSVD5_FFU_ISO")
	)
	(segment
		(start 202.554332 -112.268)
		(end 204.300836 -112.268)
		(width 0.127)
		(layer "In2.Cu")
		(net "GPU_3V3IO_RSVD5_FFU_ISO")
	)
	(segment
		(start 213.4362 -118.5418)
		(end 213.4362 -122.809)
		(width 0.127)
		(layer "In2.Cu")
		(net "GPU_3V3IO_RSVD5_FFU_ISO")
	)
	(segment
		(start 226.07778 -190.137288)
		(end 226.07778 -233.998008)
		(width 0.127)
		(layer "In2.Cu")
		(net "GPU_3V3IO_RSVD5_FFU_ISO")
	)
	(segment
		(start 224.29216 -147.008088)
		(end 224.29216 -188.351668)
		(width 0.127)
		(layer "In2.Cu")
		(net "GPU_3V3IO_RSVD5_FFU_ISO")
	)
	(segment
		(start 202.01128 -111.724948)
		(end 202.554332 -112.268)
		(width 0.127)
		(layer "In2.Cu")
		(net "GPU_3V3IO_RSVD5_FFU_ISO")
	)
	(segment
		(start 207.505554 -111.3155)
		(end 212.09 -115.899946)
		(width 0.127)
		(layer "In2.Cu")
		(net "GPU_3V3IO_RSVD5_FFU_ISO")
	)
	(segment
		(start 205.253336 -111.3155)
		(end 207.505554 -111.3155)
		(width 0.127)
		(layer "In2.Cu")
		(net "GPU_3V3IO_RSVD5_FFU_ISO")
	)
	(segment
		(start 215.07704 -124.44984)
		(end 215.07704 -137.792968)
		(width 0.127)
		(layer "In2.Cu")
		(net "GPU_3V3IO_RSVD5_FFU_ISO")
	)
	(segment
		(start 224.29216 -188.351668)
		(end 226.07778 -190.137288)
		(width 0.127)
		(layer "In2.Cu")
		(net "GPU_3V3IO_RSVD5_FFU_ISO")
	)
	(segment
		(start 226.07778 -233.998008)
		(end 223.4438 -236.631988)
		(width 0.127)
		(layer "In2.Cu")
		(net "GPU_3V3IO_RSVD5_FFU_ISO")
	)
	(segment
		(start 212.09 -115.899946)
		(end 212.09 -117.1956)
		(width 0.127)
		(layer "In2.Cu")
		(net "GPU_3V3IO_RSVD5_FFU_ISO")
	)
	(segment
		(start 223.4438 -236.631988)
		(end 223.4438 -330.528168)
		(width 0.127)
		(layer "In2.Cu")
		(net "GPU_3V3IO_RSVD5_FFU_ISO")
	)
	(segment
		(start 213.4362 -122.809)
		(end 215.07704 -124.44984)
		(width 0.127)
		(layer "In2.Cu")
		(net "GPU_3V3IO_RSVD5_FFU_ISO")
	)
	(segment
		(start 212.09 -117.1956)
		(end 213.4362 -118.5418)
		(width 0.127)
		(layer "In2.Cu")
		(net "GPU_3V3IO_RSVD5_FFU_ISO")
	)
	(segment
		(start 223.4438 -330.528168)
		(end 212.50402 -341.467948)
		(width 0.127)
		(layer "In2.Cu")
		(net "GPU_3V3IO_RSVD5_FFU_ISO")
	)
	(segment
		(start 215.07704 -137.792968)
		(end 224.29216 -147.008088)
		(width 0.127)
		(layer "In2.Cu")
		(net "GPU_3V3IO_RSVD5_FFU_ISO")
	)
	(segment
		(start 204.300836 -112.268)
		(end 205.253336 -111.3155)
		(width 0.127)
		(layer "In2.Cu")
		(net "GPU_3V3IO_RSVD5_FFU_ISO")
	)
	(segment
		(start 212.50402 -341.467948)
		(end 209.82686 -341.467948)
		(width 0.127)
		(layer "In2.Cu")
		(net "GPU_3V3IO_RSVD5_FFU_ISO")
	)
	(segment
		(start 297.41622 -421.81526)
		(end 296.88155 -421.28059)
		(width 0.12954)
		(layer "F.Cu")
		(net "GPU_3V3IO_RSVD5_FFU")
	)
	(segment
		(start 296.88409 -418.89553)
		(end 296.88409 -417.34486)
		(width 0.12954)
		(layer "F.Cu")
		(net "GPU_3V3IO_RSVD5_FFU")
	)
	(segment
		(start 297.41622 -419.43401)
		(end 297.41622 -419.42766)
		(width 0.12954)
		(layer "F.Cu")
		(net "GPU_3V3IO_RSVD5_FFU")
	)
	(segment
		(start 297.74642 -423.05605)
		(end 297.74642 -422.566338)
		(width 0.12954)
		(layer "F.Cu")
		(net "GPU_3V3IO_RSVD5_FFU")
	)
	(segment
		(start 296.88409 -417.34486)
		(end 297.00855 -417.2204)
		(width 0.12954)
		(layer "F.Cu")
		(net "GPU_3V3IO_RSVD5_FFU")
	)
	(segment
		(start 297.74642 -422.566338)
		(end 297.41622 -422.236138)
		(width 0.12954)
		(layer "F.Cu")
		(net "GPU_3V3IO_RSVD5_FFU")
	)
	(segment
		(start 296.88155 -419.96868)
		(end 297.41622 -419.43401)
		(width 0.12954)
		(layer "F.Cu")
		(net "GPU_3V3IO_RSVD5_FFU")
	)
	(segment
		(start 297.41622 -422.236138)
		(end 297.41622 -421.81526)
		(width 0.12954)
		(layer "F.Cu")
		(net "GPU_3V3IO_RSVD5_FFU")
	)
	(segment
		(start 297.00855 -417.2204)
		(end 297.6499 -417.2204)
		(width 0.12954)
		(layer "F.Cu")
		(net "GPU_3V3IO_RSVD5_FFU")
	)
	(segment
		(start 296.88155 -421.28059)
		(end 296.88155 -419.96868)
		(width 0.12954)
		(layer "F.Cu")
		(net "GPU_3V3IO_RSVD5_FFU")
	)
	(segment
		(start 297.41622 -419.42766)
		(end 296.88409 -418.89553)
		(width 0.12954)
		(layer "F.Cu")
		(net "GPU_3V3IO_RSVD5_FFU")
	)
	(via
		(at 297.00855 -417.2204)
		(size 0.508)
		(drill 0.254)
		(layers "F.Cu" "B.Cu")
		(net "GPU_3V3IO_RSVD5_FFU")
	)
	(segment
		(start 310.26608 -425.10202)
		(end 300.32452 -425.10202)
		(width 0.127)
		(layer "In2.Cu")
		(net "GPU_3V3IO_RSVD5_FFU")
	)
	(segment
		(start 321.87388 -439.713624)
		(end 321.87388 -423.738548)
		(width 0.127)
		(layer "In2.Cu")
		(net "GPU_3V3IO_RSVD5_FFU")
	)
	(segment
		(start 300.32452 -425.10202)
		(end 296.72026 -421.49776)
		(width 0.127)
		(layer "In2.Cu")
		(net "GPU_3V3IO_RSVD5_FFU")
	)
	(segment
		(start 320.90868 -422.773348)
		(end 312.594752 -422.773348)
		(width 0.127)
		(layer "In2.Cu")
		(net "GPU_3V3IO_RSVD5_FFU")
	)
	(segment
		(start 312.594752 -422.773348)
		(end 310.26608 -425.10202)
		(width 0.127)
		(layer "In2.Cu")
		(net "GPU_3V3IO_RSVD5_FFU")
	)
	(segment
		(start 322.650104 -440.489848)
		(end 321.87388 -439.713624)
		(width 0.127)
		(layer "In2.Cu")
		(net "GPU_3V3IO_RSVD5_FFU")
	)
	(segment
		(start 296.72026 -421.49776)
		(end 296.72026 -417.50869)
		(width 0.127)
		(layer "In2.Cu")
		(net "GPU_3V3IO_RSVD5_FFU")
	)
	(segment
		(start 321.87388 -423.738548)
		(end 320.90868 -422.773348)
		(width 0.127)
		(layer "In2.Cu")
		(net "GPU_3V3IO_RSVD5_FFU")
	)
	(segment
		(start 296.72026 -417.50869)
		(end 297.00855 -417.2204)
		(width 0.127)
		(layer "In2.Cu")
		(net "GPU_3V3IO_RSVD5_FFU")
	)
	(segment
		(start 365.928402 -393.33805)
		(end 365.928402 -393.988036)
		(width 0.12954)
		(layer "F.Cu")
		(net "GPU_3V3IO_RSVD4_N")
	)
	(segment
		(start 368.169698 -393.988036)
		(end 368.828828 -394.647166)
		(width 0.12954)
		(layer "F.Cu")
		(net "GPU_3V3IO_RSVD4_N")
	)
	(segment
		(start 365.928402 -393.988036)
		(end 367.33734 -393.988036)
		(width 0.12954)
		(layer "F.Cu")
		(net "GPU_3V3IO_RSVD4_N")
	)
	(segment
		(start 367.33734 -393.988036)
		(end 368.169698 -393.988036)
		(width 0.12954)
		(layer "F.Cu")
		(net "GPU_3V3IO_RSVD4_N")
	)
	(via
		(at 367.33734 -393.988036)
		(size 0.762)
		(drill 0.381)
		(layers "F.Cu" "B.Cu")
		(net "GPU_3V3IO_RSVD4_N")
	)
	(segment
		(start 204.53731 -116.804948)
		(end 203.91374 -116.804948)
		(width 0.12954)
		(layer "F.Cu")
		(net "GPU_3V3IO_RSVD4_ISO_R")
	)
	(segment
		(start 183.755538 -113.77549)
		(end 184.155588 -114.17554)
		(width 0.12954)
		(layer "F.Cu")
		(net "GPU_3V3IO_RSVD4_ISO_R")
	)
	(via
		(at 203.91374 -116.804948)
		(size 0.508)
		(drill 0.254)
		(layers "F.Cu" "B.Cu")
		(net "GPU_3V3IO_RSVD4_ISO_R")
	)
	(via
		(at 184.155588 -114.17554)
		(size 0.4572)
		(drill 0.254)
		(layers "F.Cu" "B.Cu")
		(net "GPU_3V3IO_RSVD4_ISO_R")
	)
	(segment
		(start 203.91374 -116.804948)
		(end 203.11364 -117.605048)
		(width 0.127)
		(layer "In2.Cu")
		(net "GPU_3V3IO_RSVD4_ISO_R")
	)
	(segment
		(start 190.352934 -118.125748)
		(end 189.00648 -116.779294)
		(width 0.127)
		(layer "In2.Cu")
		(net "GPU_3V3IO_RSVD4_ISO_R")
	)
	(segment
		(start 193.56578 -118.125748)
		(end 190.352934 -118.125748)
		(width 0.127)
		(layer "In2.Cu")
		(net "GPU_3V3IO_RSVD4_ISO_R")
	)
	(segment
		(start 189.00648 -116.779294)
		(end 189.00648 -116.459254)
		(width 0.127)
		(layer "In2.Cu")
		(net "GPU_3V3IO_RSVD4_ISO_R")
	)
	(segment
		(start 203.11364 -117.605048)
		(end 194.08648 -117.605048)
		(width 0.127)
		(layer "In2.Cu")
		(net "GPU_3V3IO_RSVD4_ISO_R")
	)
	(segment
		(start 187.121038 -114.573812)
		(end 184.794144 -114.573812)
		(width 0.127)
		(layer "In2.Cu")
		(net "GPU_3V3IO_RSVD4_ISO_R")
	)
	(segment
		(start 189.00648 -116.459254)
		(end 187.121038 -114.573812)
		(width 0.127)
		(layer "In2.Cu")
		(net "GPU_3V3IO_RSVD4_ISO_R")
	)
	(segment
		(start 184.395872 -114.17554)
		(end 184.155588 -114.17554)
		(width 0.127)
		(layer "In2.Cu")
		(net "GPU_3V3IO_RSVD4_ISO_R")
	)
	(segment
		(start 194.08648 -117.605048)
		(end 193.56578 -118.125748)
		(width 0.127)
		(layer "In2.Cu")
		(net "GPU_3V3IO_RSVD4_ISO_R")
	)
	(segment
		(start 184.794144 -114.573812)
		(end 184.395872 -114.17554)
		(width 0.127)
		(layer "In2.Cu")
		(net "GPU_3V3IO_RSVD4_ISO_R")
	)
	(segment
		(start 360.901234 -392.024108)
		(end 360.882692 -392.04265)
		(width 0.12954)
		(layer "F.Cu")
		(net "GPU_3V3IO_RSVD4_ISO")
	)
	(segment
		(start 355.64064 -392.008868)
		(end 354.81895 -392.830558)
		(width 0.12954)
		(layer "F.Cu")
		(net "GPU_3V3IO_RSVD4_ISO")
	)
	(segment
		(start 362.64596 -392.024108)
		(end 363.309916 -392.688064)
		(width 0.12954)
		(layer "F.Cu")
		(net "GPU_3V3IO_RSVD4_ISO")
	)
	(segment
		(start 360.882692 -392.04265)
		(end 360.261154 -392.664188)
		(width 0.12954)
		(layer "F.Cu")
		(net "GPU_3V3IO_RSVD4_ISO")
	)
	(segment
		(start 358.28224 -392.664188)
		(end 357.987092 -392.36904)
		(width 0.12954)
		(layer "F.Cu")
		(net "GPU_3V3IO_RSVD4_ISO")
	)
	(segment
		(start 360.261154 -392.664188)
		(end 358.28224 -392.664188)
		(width 0.12954)
		(layer "F.Cu")
		(net "GPU_3V3IO_RSVD4_ISO")
	)
	(segment
		(start 356.27056 -391.378948)
		(end 355.64064 -392.008868)
		(width 0.12954)
		(layer "F.Cu")
		(net "GPU_3V3IO_RSVD4_ISO")
	)
	(segment
		(start 362.26496 -392.024108)
		(end 362.64596 -392.024108)
		(width 0.12954)
		(layer "F.Cu")
		(net "GPU_3V3IO_RSVD4_ISO")
	)
	(segment
		(start 357.32339 -391.378948)
		(end 356.27056 -391.378948)
		(width 0.12954)
		(layer "F.Cu")
		(net "GPU_3V3IO_RSVD4_ISO")
	)
	(segment
		(start 354.81895 -392.830558)
		(end 354.81895 -393.283948)
		(width 0.12954)
		(layer "F.Cu")
		(net "GPU_3V3IO_RSVD4_ISO")
	)
	(segment
		(start 357.987092 -392.04265)
		(end 357.32339 -391.378948)
		(width 0.12954)
		(layer "F.Cu")
		(net "GPU_3V3IO_RSVD4_ISO")
	)
	(segment
		(start 362.26496 -392.024108)
		(end 360.901234 -392.024108)
		(width 0.12954)
		(layer "F.Cu")
		(net "GPU_3V3IO_RSVD4_ISO")
	)
	(segment
		(start 357.987092 -392.36904)
		(end 357.987092 -392.04265)
		(width 0.12954)
		(layer "F.Cu")
		(net "GPU_3V3IO_RSVD4_ISO")
	)
	(segment
		(start 205.33741 -116.804948)
		(end 205.95844 -116.804948)
		(width 0.12954)
		(layer "F.Cu")
		(net "GPU_3V3IO_RSVD4_ISO")
	)
	(segment
		(start 363.309916 -392.688064)
		(end 364.028482 -392.688064)
		(width 0.12954)
		(layer "F.Cu")
		(net "GPU_3V3IO_RSVD4_ISO")
	)
	(via
		(at 362.26496 -392.024108)
		(size 0.762)
		(drill 0.381)
		(layers "F.Cu" "B.Cu")
		(net "GPU_3V3IO_RSVD4_ISO")
	)
	(via
		(at 205.95844 -116.804948)
		(size 0.508)
		(drill 0.254)
		(layers "F.Cu" "B.Cu")
		(net "GPU_3V3IO_RSVD4_ISO")
	)
	(via
		(at 355.64064 -392.008868)
		(size 0.508)
		(drill 0.254)
		(layers "F.Cu" "B.Cu")
		(net "GPU_3V3IO_RSVD4_ISO")
	)
	(via
		(at 211.35086 -337.022948)
		(size 0.508)
		(drill 0.254)
		(layers "F.Cu" "B.Cu")
		(net "GPU_3V3IO_RSVD4_ISO")
	)
	(segment
		(start 261.9121 -348.915228)
		(end 270.3195 -357.322628)
		(width 0.12954)
		(layer "B.Cu")
		(net "GPU_3V3IO_RSVD4_ISO")
	)
	(segment
		(start 211.35086 -337.022948)
		(end 242.72494 -337.022948)
		(width 0.12954)
		(layer "B.Cu")
		(net "GPU_3V3IO_RSVD4_ISO")
	)
	(segment
		(start 280.957274 -383.487422)
		(end 345.673934 -383.487422)
		(width 0.12954)
		(layer "B.Cu")
		(net "GPU_3V3IO_RSVD4_ISO")
	)
	(segment
		(start 354.19538 -392.008868)
		(end 355.64064 -392.008868)
		(width 0.12954)
		(layer "B.Cu")
		(net "GPU_3V3IO_RSVD4_ISO")
	)
	(segment
		(start 242.72494 -337.022948)
		(end 254.61722 -348.915228)
		(width 0.12954)
		(layer "B.Cu")
		(net "GPU_3V3IO_RSVD4_ISO")
	)
	(segment
		(start 270.3195 -357.322628)
		(end 270.3195 -372.849648)
		(width 0.12954)
		(layer "B.Cu")
		(net "GPU_3V3IO_RSVD4_ISO")
	)
	(segment
		(start 345.673934 -383.487422)
		(end 354.19538 -392.008868)
		(width 0.12954)
		(layer "B.Cu")
		(net "GPU_3V3IO_RSVD4_ISO")
	)
	(segment
		(start 270.3195 -372.849648)
		(end 280.957274 -383.487422)
		(width 0.12954)
		(layer "B.Cu")
		(net "GPU_3V3IO_RSVD4_ISO")
	)
	(segment
		(start 254.61722 -348.915228)
		(end 261.9121 -348.915228)
		(width 0.12954)
		(layer "B.Cu")
		(net "GPU_3V3IO_RSVD4_ISO")
	)
	(segment
		(start 222.75546 -191.214756)
		(end 220.96984 -189.429136)
		(width 0.127)
		(layer "In2.Cu")
		(net "GPU_3V3IO_RSVD4_ISO")
	)
	(segment
		(start 208.93278 -123.396248)
		(end 207.9752 -122.438668)
		(width 0.127)
		(layer "In2.Cu")
		(net "GPU_3V3IO_RSVD4_ISO")
	)
	(segment
		(start 207.9752 -122.438668)
		(end 207.9752 -117.547136)
		(width 0.127)
		(layer "In2.Cu")
		(net "GPU_3V3IO_RSVD4_ISO")
	)
	(segment
		(start 221.73692 -199.893428)
		(end 222.75546 -198.874888)
		(width 0.127)
		(layer "In2.Cu")
		(net "GPU_3V3IO_RSVD4_ISO")
	)
	(segment
		(start 209.36458 -129.060448)
		(end 208.93278 -128.628648)
		(width 0.127)
		(layer "In2.Cu")
		(net "GPU_3V3IO_RSVD4_ISO")
	)
	(segment
		(start 208.93278 -128.628648)
		(end 208.93278 -123.396248)
		(width 0.127)
		(layer "In2.Cu")
		(net "GPU_3V3IO_RSVD4_ISO")
	)
	(segment
		(start 222.75546 -206.073248)
		(end 221.73692 -205.054708)
		(width 0.127)
		(layer "In2.Cu")
		(net "GPU_3V3IO_RSVD4_ISO")
	)
	(segment
		(start 211.35086 -336.5119)
		(end 220.12148 -327.74128)
		(width 0.127)
		(layer "In2.Cu")
		(net "GPU_3V3IO_RSVD4_ISO")
	)
	(segment
		(start 220.96984 -189.429136)
		(end 220.96984 -148.385276)
		(width 0.127)
		(layer "In2.Cu")
		(net "GPU_3V3IO_RSVD4_ISO")
	)
	(segment
		(start 220.12148 -218.42984)
		(end 222.75546 -215.79586)
		(width 0.127)
		(layer "In2.Cu")
		(net "GPU_3V3IO_RSVD4_ISO")
	)
	(segment
		(start 220.12148 -327.74128)
		(end 220.12148 -218.42984)
		(width 0.127)
		(layer "In2.Cu")
		(net "GPU_3V3IO_RSVD4_ISO")
	)
	(segment
		(start 221.73692 -205.054708)
		(end 221.73692 -199.893428)
		(width 0.127)
		(layer "In2.Cu")
		(net "GPU_3V3IO_RSVD4_ISO")
	)
	(segment
		(start 220.96984 -148.385276)
		(end 209.36458 -136.780016)
		(width 0.127)
		(layer "In2.Cu")
		(net "GPU_3V3IO_RSVD4_ISO")
	)
	(segment
		(start 222.75546 -198.874888)
		(end 222.75546 -191.214756)
		(width 0.127)
		(layer "In2.Cu")
		(net "GPU_3V3IO_RSVD4_ISO")
	)
	(segment
		(start 207.233012 -116.804948)
		(end 205.95844 -116.804948)
		(width 0.127)
		(layer "In2.Cu")
		(net "GPU_3V3IO_RSVD4_ISO")
	)
	(segment
		(start 211.35086 -337.022948)
		(end 211.35086 -336.5119)
		(width 0.127)
		(layer "In2.Cu")
		(net "GPU_3V3IO_RSVD4_ISO")
	)
	(segment
		(start 209.36458 -136.780016)
		(end 209.36458 -129.060448)
		(width 0.127)
		(layer "In2.Cu")
		(net "GPU_3V3IO_RSVD4_ISO")
	)
	(segment
		(start 222.75546 -215.79586)
		(end 222.75546 -206.073248)
		(width 0.127)
		(layer "In2.Cu")
		(net "GPU_3V3IO_RSVD4_ISO")
	)
	(segment
		(start 207.9752 -117.547136)
		(end 207.233012 -116.804948)
		(width 0.127)
		(layer "In2.Cu")
		(net "GPU_3V3IO_RSVD4_ISO")
	)
	(segment
		(start 305.92014 -436.59806)
		(end 305.270154 -436.59806)
		(width 0.12954)
		(layer "F.Cu")
		(net "PRSNT_CABLE_GPU_A2")
	)
	(segment
		(start 306.366672 -437.869838)
		(end 306.516024 -437.720486)
		(width 0.12954)
		(layer "F.Cu")
		(net "PRSNT_CABLE_GPU_A2")
	)
	(segment
		(start 305.30927 -437.869838)
		(end 306.366672 -437.869838)
		(width 0.12954)
		(layer "F.Cu")
		(net "PRSNT_CABLE_GPU_A2")
	)
	(segment
		(start 305.270154 -436.59806)
		(end 305.270154 -437.830722)
		(width 0.12954)
		(layer "F.Cu")
		(net "PRSNT_CABLE_GPU_A2")
	)
	(segment
		(start 305.270154 -437.830722)
		(end 305.30927 -437.869838)
		(width 0.12954)
		(layer "F.Cu")
		(net "PRSNT_CABLE_GPU_A2")
	)
	(via
		(at 305.30927 -437.869838)
		(size 0.762)
		(drill 0.381)
		(layers "F.Cu" "B.Cu")
		(net "PRSNT_CABLE_GPU_A2")
	)
	(segment
		(start 204.53731 -114.264948)
		(end 203.91374 -114.264948)
		(width 0.12954)
		(layer "F.Cu")
		(net "PRSNT_CABLE_GPU_A2_ISO_R_N")
	)
	(segment
		(start 183.755538 -112.97539)
		(end 184.155588 -112.57534)
		(width 0.12954)
		(layer "F.Cu")
		(net "PRSNT_CABLE_GPU_A2_ISO_R_N")
	)
	(via
		(at 203.91374 -114.264948)
		(size 0.508)
		(drill 0.254)
		(layers "F.Cu" "B.Cu")
		(net "PRSNT_CABLE_GPU_A2_ISO_R_N")
	)
	(via
		(at 184.155588 -112.57534)
		(size 0.4572)
		(drill 0.254)
		(layers "F.Cu" "B.Cu")
		(net "PRSNT_CABLE_GPU_A2_ISO_R_N")
	)
	(segment
		(start 187.832746 -113.106708)
		(end 184.686956 -113.106708)
		(width 0.127)
		(layer "In2.Cu")
		(net "PRSNT_CABLE_GPU_A2_ISO_R_N")
	)
	(segment
		(start 184.686956 -113.106708)
		(end 184.155588 -112.57534)
		(width 0.127)
		(layer "In2.Cu")
		(net "PRSNT_CABLE_GPU_A2_ISO_R_N")
	)
	(segment
		(start 203.06284 -114.264948)
		(end 202.509374 -114.818414)
		(width 0.127)
		(layer "In2.Cu")
		(net "PRSNT_CABLE_GPU_A2_ISO_R_N")
	)
	(segment
		(start 202.509374 -114.818414)
		(end 189.544452 -114.818414)
		(width 0.127)
		(layer "In2.Cu")
		(net "PRSNT_CABLE_GPU_A2_ISO_R_N")
	)
	(segment
		(start 203.91374 -114.264948)
		(end 203.06284 -114.264948)
		(width 0.127)
		(layer "In2.Cu")
		(net "PRSNT_CABLE_GPU_A2_ISO_R_N")
	)
	(segment
		(start 189.544452 -114.818414)
		(end 187.832746 -113.106708)
		(width 0.127)
		(layer "In2.Cu")
		(net "PRSNT_CABLE_GPU_A2_ISO_R_N")
	)
	(segment
		(start 305.58994 -431.06975)
		(end 305.070002 -430.549812)
		(width 0.12954)
		(layer "F.Cu")
		(net "PRSNT_CABLE_GPU_A2_N")
	)
	(segment
		(start 305.58994 -431.06975)
		(end 305.05527 -431.60442)
		(width 0.12954)
		(layer "F.Cu")
		(net "PRSNT_CABLE_GPU_A2_N")
	)
	(segment
		(start 305.18227 -428.86249)
		(end 305.82362 -428.86249)
		(width 0.12954)
		(layer "F.Cu")
		(net "PRSNT_CABLE_GPU_A2_N")
	)
	(segment
		(start 305.05527 -432.92268)
		(end 305.58994 -433.45735)
		(width 0.12954)
		(layer "F.Cu")
		(net "PRSNT_CABLE_GPU_A2_N")
	)
	(segment
		(start 305.92014 -434.208428)
		(end 305.92014 -434.69814)
		(width 0.12954)
		(layer "F.Cu")
		(net "PRSNT_CABLE_GPU_A2_N")
	)
	(segment
		(start 305.070002 -428.974758)
		(end 305.18227 -428.86249)
		(width 0.12954)
		(layer "F.Cu")
		(net "PRSNT_CABLE_GPU_A2_N")
	)
	(segment
		(start 305.05527 -431.60442)
		(end 305.05527 -432.92268)
		(width 0.12954)
		(layer "F.Cu")
		(net "PRSNT_CABLE_GPU_A2_N")
	)
	(segment
		(start 305.58994 -433.45735)
		(end 305.58994 -433.878228)
		(width 0.12954)
		(layer "F.Cu")
		(net "PRSNT_CABLE_GPU_A2_N")
	)
	(segment
		(start 305.070002 -430.549812)
		(end 305.070002 -428.974758)
		(width 0.12954)
		(layer "F.Cu")
		(net "PRSNT_CABLE_GPU_A2_N")
	)
	(segment
		(start 305.58994 -433.878228)
		(end 305.92014 -434.208428)
		(width 0.12954)
		(layer "F.Cu")
		(net "PRSNT_CABLE_GPU_A2_N")
	)
	(via
		(at 305.18227 -428.86249)
		(size 0.508)
		(drill 0.254)
		(layers "F.Cu" "B.Cu")
		(net "PRSNT_CABLE_GPU_A2_N")
	)
	(segment
		(start 316.890146 -423.707814)
		(end 312.280046 -423.707814)
		(width 0.127)
		(layer "In2.Cu")
		(net "PRSNT_CABLE_GPU_A2_N")
	)
	(segment
		(start 312.280046 -423.707814)
		(end 307.12537 -428.86249)
		(width 0.127)
		(layer "In2.Cu")
		(net "PRSNT_CABLE_GPU_A2_N")
	)
	(segment
		(start 307.12537 -428.86249)
		(end 305.18227 -428.86249)
		(width 0.127)
		(layer "In2.Cu")
		(net "PRSNT_CABLE_GPU_A2_N")
	)
	(segment
		(start 317.78448 -424.602148)
		(end 316.890146 -423.707814)
		(width 0.127)
		(layer "In2.Cu")
		(net "PRSNT_CABLE_GPU_A2_N")
	)
	(segment
		(start 317.78448 -439.624216)
		(end 317.78448 -424.602148)
		(width 0.127)
		(layer "In2.Cu")
		(net "PRSNT_CABLE_GPU_A2_N")
	)
	(segment
		(start 318.650112 -440.489848)
		(end 317.78448 -439.624216)
		(width 0.127)
		(layer "In2.Cu")
		(net "PRSNT_CABLE_GPU_A2_N")
	)
	(segment
		(start 362.53928 -393.33805)
		(end 362.48848 -393.28725)
		(width 0.12954)
		(layer "F.Cu")
		(net "GPU_3V3IO_RSVD4")
	)
	(segment
		(start 360.225594 -393.944348)
		(end 358.3432 -393.944348)
		(width 0.12954)
		(layer "F.Cu")
		(net "GPU_3V3IO_RSVD4")
	)
	(segment
		(start 357.507794 -393.766548)
		(end 356.10165 -393.766548)
		(width 0.12954)
		(layer "F.Cu")
		(net "GPU_3V3IO_RSVD4")
	)
	(segment
		(start 360.882692 -393.28725)
		(end 360.225594 -393.944348)
		(width 0.12954)
		(layer "F.Cu")
		(net "GPU_3V3IO_RSVD4")
	)
	(segment
		(start 357.987092 -393.58824)
		(end 357.987092 -393.28725)
		(width 0.12954)
		(layer "F.Cu")
		(net "GPU_3V3IO_RSVD4")
	)
	(segment
		(start 364.028482 -393.33805)
		(end 362.53928 -393.33805)
		(width 0.12954)
		(layer "F.Cu")
		(net "GPU_3V3IO_RSVD4")
	)
	(segment
		(start 362.48848 -393.28725)
		(end 360.882692 -393.28725)
		(width 0.12954)
		(layer "F.Cu")
		(net "GPU_3V3IO_RSVD4")
	)
	(segment
		(start 357.987092 -393.28725)
		(end 357.507794 -393.766548)
		(width 0.12954)
		(layer "F.Cu")
		(net "GPU_3V3IO_RSVD4")
	)
	(segment
		(start 358.3432 -393.944348)
		(end 357.987092 -393.58824)
		(width 0.12954)
		(layer "F.Cu")
		(net "GPU_3V3IO_RSVD4")
	)
	(segment
		(start 356.10165 -393.766548)
		(end 355.61905 -393.283948)
		(width 0.12954)
		(layer "F.Cu")
		(net "GPU_3V3IO_RSVD4")
	)
	(via
		(at 362.53928 -393.33805)
		(size 0.508)
		(drill 0.254)
		(layers "F.Cu" "B.Cu")
		(net "GPU_3V3IO_RSVD4")
	)
	(segment
		(start 397.41348 -421.782748)
		(end 393.07008 -417.439348)
		(width 0.127)
		(layer "In2.Cu")
		(net "GPU_3V3IO_RSVD4")
	)
	(segment
		(start 398.750028 -440.489848)
		(end 397.41348 -439.1533)
		(width 0.127)
		(layer "In2.Cu")
		(net "GPU_3V3IO_RSVD4")
	)
	(segment
		(start 377.323604 -413.630872)
		(end 371.108224 -413.630872)
		(width 0.127)
		(layer "In2.Cu")
		(net "GPU_3V3IO_RSVD4")
	)
	(segment
		(start 381.13208 -417.439348)
		(end 377.323604 -413.630872)
		(width 0.127)
		(layer "In2.Cu")
		(net "GPU_3V3IO_RSVD4")
	)
	(segment
		(start 371.108224 -413.630872)
		(end 366.90681 -409.429458)
		(width 0.127)
		(layer "In2.Cu")
		(net "GPU_3V3IO_RSVD4")
	)
	(segment
		(start 366.90681 -409.429458)
		(end 366.90681 -402.995638)
		(width 0.127)
		(layer "In2.Cu")
		(net "GPU_3V3IO_RSVD4")
	)
	(segment
		(start 393.07008 -417.439348)
		(end 381.13208 -417.439348)
		(width 0.127)
		(layer "In2.Cu")
		(net "GPU_3V3IO_RSVD4")
	)
	(segment
		(start 362.9406 -399.029428)
		(end 362.9406 -393.73937)
		(width 0.127)
		(layer "In2.Cu")
		(net "GPU_3V3IO_RSVD4")
	)
	(segment
		(start 366.90681 -402.995638)
		(end 362.9406 -399.029428)
		(width 0.127)
		(layer "In2.Cu")
		(net "GPU_3V3IO_RSVD4")
	)
	(segment
		(start 397.41348 -439.1533)
		(end 397.41348 -421.782748)
		(width 0.127)
		(layer "In2.Cu")
		(net "GPU_3V3IO_RSVD4")
	)
	(segment
		(start 362.9406 -393.73937)
		(end 362.53928 -393.33805)
		(width 0.127)
		(layer "In2.Cu")
		(net "GPU_3V3IO_RSVD4")
	)
	(segment
		(start 367.27638 -391.138156)
		(end 368.131598 -391.138156)
		(width 0.12954)
		(layer "F.Cu")
		(net "GPU_3V3IO_RSVD3_N")
	)
	(segment
		(start 365.890302 -390.48817)
		(end 365.890302 -391.138156)
		(width 0.12954)
		(layer "F.Cu")
		(net "GPU_3V3IO_RSVD3_N")
	)
	(segment
		(start 368.131598 -391.138156)
		(end 368.790728 -391.797286)
		(width 0.12954)
		(layer "F.Cu")
		(net "GPU_3V3IO_RSVD3_N")
	)
	(segment
		(start 365.890302 -391.138156)
		(end 367.27638 -391.138156)
		(width 0.12954)
		(layer "F.Cu")
		(net "GPU_3V3IO_RSVD3_N")
	)
	(via
		(at 367.27638 -391.138156)
		(size 0.762)
		(drill 0.381)
		(layers "F.Cu" "B.Cu")
		(net "GPU_3V3IO_RSVD3_N")
	)
	(segment
		(start 204.53731 -118.074948)
		(end 203.91374 -118.074948)
		(width 0.12954)
		(layer "F.Cu")
		(net "GPU_3V3IO_RSVD3_ISO_R")
	)
	(segment
		(start 182.955692 -113.77549)
		(end 183.355742 -114.17554)
		(width 0.12954)
		(layer "F.Cu")
		(net "GPU_3V3IO_RSVD3_ISO_R")
	)
	(via
		(at 183.355742 -114.17554)
		(size 0.4572)
		(drill 0.254)
		(layers "F.Cu" "B.Cu")
		(net "GPU_3V3IO_RSVD3_ISO_R")
	)
	(via
		(at 203.91374 -118.074948)
		(size 0.508)
		(drill 0.254)
		(layers "F.Cu" "B.Cu")
		(net "GPU_3V3IO_RSVD3_ISO_R")
	)
	(segment
		(start 184.703466 -115.374928)
		(end 184.55386 -115.225322)
		(width 0.127)
		(layer "In2.Cu")
		(net "GPU_3V3IO_RSVD3_ISO_R")
	)
	(segment
		(start 184.55386 -115.225322)
		(end 184.55386 -114.798602)
		(width 0.127)
		(layer "In2.Cu")
		(net "GPU_3V3IO_RSVD3_ISO_R")
	)
	(segment
		(start 188.60008 -116.931948)
		(end 188.60008 -116.566188)
		(width 0.127)
		(layer "In2.Cu")
		(net "GPU_3V3IO_RSVD3_ISO_R")
	)
	(segment
		(start 184.55386 -114.798602)
		(end 184.327546 -114.572288)
		(width 0.127)
		(layer "In2.Cu")
		(net "GPU_3V3IO_RSVD3_ISO_R")
	)
	(segment
		(start 203.40574 -118.582948)
		(end 190.25108 -118.582948)
		(width 0.127)
		(layer "In2.Cu")
		(net "GPU_3V3IO_RSVD3_ISO_R")
	)
	(segment
		(start 183.992266 -114.572288)
		(end 183.595518 -114.17554)
		(width 0.127)
		(layer "In2.Cu")
		(net "GPU_3V3IO_RSVD3_ISO_R")
	)
	(segment
		(start 187.40882 -115.374928)
		(end 184.703466 -115.374928)
		(width 0.127)
		(layer "In2.Cu")
		(net "GPU_3V3IO_RSVD3_ISO_R")
	)
	(segment
		(start 203.91374 -118.074948)
		(end 203.40574 -118.582948)
		(width 0.127)
		(layer "In2.Cu")
		(net "GPU_3V3IO_RSVD3_ISO_R")
	)
	(segment
		(start 188.60008 -116.566188)
		(end 187.40882 -115.374928)
		(width 0.127)
		(layer "In2.Cu")
		(net "GPU_3V3IO_RSVD3_ISO_R")
	)
	(segment
		(start 184.327546 -114.572288)
		(end 183.992266 -114.572288)
		(width 0.127)
		(layer "In2.Cu")
		(net "GPU_3V3IO_RSVD3_ISO_R")
	)
	(segment
		(start 183.595518 -114.17554)
		(end 183.355742 -114.17554)
		(width 0.127)
		(layer "In2.Cu")
		(net "GPU_3V3IO_RSVD3_ISO_R")
	)
	(segment
		(start 190.25108 -118.582948)
		(end 188.60008 -116.931948)
		(width 0.127)
		(layer "In2.Cu")
		(net "GPU_3V3IO_RSVD3_ISO_R")
	)
	(segment
		(start 205.33741 -118.074948)
		(end 205.95844 -118.074948)
		(width 0.12954)
		(layer "F.Cu")
		(net "GPU_3V3IO_RSVD3_ISO")
	)
	(segment
		(start 357.948992 -388.330948)
		(end 355.9048 -388.330948)
		(width 0.12954)
		(layer "F.Cu")
		(net "GPU_3V3IO_RSVD3_ISO")
	)
	(segment
		(start 358.22636 -389.814308)
		(end 357.948992 -389.53694)
		(width 0.12954)
		(layer "F.Cu")
		(net "GPU_3V3IO_RSVD3_ISO")
	)
	(segment
		(start 360.863134 -389.174228)
		(end 360.844592 -389.19277)
		(width 0.12954)
		(layer "F.Cu")
		(net "GPU_3V3IO_RSVD3_ISO")
	)
	(segment
		(start 357.948992 -389.19277)
		(end 357.948992 -388.330948)
		(width 0.12954)
		(layer "F.Cu")
		(net "GPU_3V3IO_RSVD3_ISO")
	)
	(segment
		(start 362.22686 -389.174228)
		(end 360.863134 -389.174228)
		(width 0.12954)
		(layer "F.Cu")
		(net "GPU_3V3IO_RSVD3_ISO")
	)
	(segment
		(start 355.9048 -388.330948)
		(end 354.81895 -389.416798)
		(width 0.12954)
		(layer "F.Cu")
		(net "GPU_3V3IO_RSVD3_ISO")
	)
	(segment
		(start 360.844592 -389.19277)
		(end 360.223054 -389.814308)
		(width 0.12954)
		(layer "F.Cu")
		(net "GPU_3V3IO_RSVD3_ISO")
	)
	(segment
		(start 363.990382 -389.838184)
		(end 363.271816 -389.838184)
		(width 0.12954)
		(layer "F.Cu")
		(net "GPU_3V3IO_RSVD3_ISO")
	)
	(segment
		(start 360.223054 -389.814308)
		(end 358.22636 -389.814308)
		(width 0.12954)
		(layer "F.Cu")
		(net "GPU_3V3IO_RSVD3_ISO")
	)
	(segment
		(start 357.948992 -389.53694)
		(end 357.948992 -389.19277)
		(width 0.12954)
		(layer "F.Cu")
		(net "GPU_3V3IO_RSVD3_ISO")
	)
	(segment
		(start 354.81895 -389.416798)
		(end 354.81895 -390.439148)
		(width 0.12954)
		(layer "F.Cu")
		(net "GPU_3V3IO_RSVD3_ISO")
	)
	(segment
		(start 363.271816 -389.838184)
		(end 362.60786 -389.174228)
		(width 0.12954)
		(layer "F.Cu")
		(net "GPU_3V3IO_RSVD3_ISO")
	)
	(segment
		(start 362.60786 -389.174228)
		(end 362.22686 -389.174228)
		(width 0.12954)
		(layer "F.Cu")
		(net "GPU_3V3IO_RSVD3_ISO")
	)
	(via
		(at 301.68088 -389.092948)
		(size 0.508)
		(drill 0.254)
		(layers "F.Cu" "B.Cu")
		(net "GPU_3V3IO_RSVD3_ISO")
	)
	(via
		(at 205.95844 -118.074948)
		(size 0.508)
		(drill 0.254)
		(layers "F.Cu" "B.Cu")
		(net "GPU_3V3IO_RSVD3_ISO")
	)
	(via
		(at 362.22686 -389.174228)
		(size 0.762)
		(drill 0.381)
		(layers "F.Cu" "B.Cu")
		(net "GPU_3V3IO_RSVD3_ISO")
	)
	(via
		(at 240.771934 -203.139294)
		(size 0.508)
		(drill 0.254)
		(layers "F.Cu" "B.Cu")
		(net "GPU_3V3IO_RSVD3_ISO")
	)
	(via
		(at 357.948992 -388.330948)
		(size 0.508)
		(drill 0.254)
		(layers "F.Cu" "B.Cu")
		(net "GPU_3V3IO_RSVD3_ISO")
	)
	(segment
		(start 295.361868 -384.012948)
		(end 289.7632 -384.012948)
		(width 0.127)
		(layer "In4.Cu")
		(net "GPU_3V3IO_RSVD3_ISO")
	)
	(segment
		(start 289.7632 -384.012948)
		(end 279.68956 -373.939308)
		(width 0.127)
		(layer "In4.Cu")
		(net "GPU_3V3IO_RSVD3_ISO")
	)
	(segment
		(start 250.83008 -213.19744)
		(end 240.771934 -203.139294)
		(width 0.127)
		(layer "In4.Cu")
		(net "GPU_3V3IO_RSVD3_ISO")
	)
	(segment
		(start 279.68956 -373.939308)
		(end 279.68956 -359.608628)
		(width 0.127)
		(layer "In4.Cu")
		(net "GPU_3V3IO_RSVD3_ISO")
	)
	(segment
		(start 301.68088 -389.092948)
		(end 300.441868 -389.092948)
		(width 0.127)
		(layer "In4.Cu")
		(net "GPU_3V3IO_RSVD3_ISO")
	)
	(segment
		(start 300.441868 -389.092948)
		(end 295.361868 -384.012948)
		(width 0.127)
		(layer "In4.Cu")
		(net "GPU_3V3IO_RSVD3_ISO")
	)
	(segment
		(start 250.83008 -277.764748)
		(end 250.83008 -213.19744)
		(width 0.127)
		(layer "In4.Cu")
		(net "GPU_3V3IO_RSVD3_ISO")
	)
	(segment
		(start 247.32488 -327.243948)
		(end 247.32488 -281.269948)
		(width 0.127)
		(layer "In4.Cu")
		(net "GPU_3V3IO_RSVD3_ISO")
	)
	(segment
		(start 247.32488 -281.269948)
		(end 250.83008 -277.764748)
		(width 0.127)
		(layer "In4.Cu")
		(net "GPU_3V3IO_RSVD3_ISO")
	)
	(segment
		(start 279.68956 -359.608628)
		(end 247.32488 -327.243948)
		(width 0.127)
		(layer "In4.Cu")
		(net "GPU_3V3IO_RSVD3_ISO")
	)
	(segment
		(start 357.33228 -388.330948)
		(end 355.90988 -386.908548)
		(width 0.127)
		(layer "In6.Cu")
		(net "GPU_3V3IO_RSVD3_ISO")
	)
	(segment
		(start 321.26428 -386.908548)
		(end 319.07988 -389.092948)
		(width 0.127)
		(layer "In6.Cu")
		(net "GPU_3V3IO_RSVD3_ISO")
	)
	(segment
		(start 319.07988 -389.092948)
		(end 301.68088 -389.092948)
		(width 0.127)
		(layer "In6.Cu")
		(net "GPU_3V3IO_RSVD3_ISO")
	)
	(segment
		(start 357.948992 -388.330948)
		(end 357.33228 -388.330948)
		(width 0.127)
		(layer "In6.Cu")
		(net "GPU_3V3IO_RSVD3_ISO")
	)
	(segment
		(start 355.90988 -386.908548)
		(end 321.26428 -386.908548)
		(width 0.127)
		(layer "In6.Cu")
		(net "GPU_3V3IO_RSVD3_ISO")
	)
	(segment
		(start 239.32388 -197.958202)
		(end 239.32388 -201.69124)
		(width 0.127)
		(layer "In11.Cu")
		(net "GPU_3V3IO_RSVD3_ISO")
	)
	(segment
		(start 206.72806 -127.86614)
		(end 206.72806 -129.932684)
		(width 0.127)
		(layer "In11.Cu")
		(net "GPU_3V3IO_RSVD3_ISO")
	)
	(segment
		(start 206.5274 -118.643908)
		(end 206.5274 -122.6312)
		(width 0.127)
		(layer "In11.Cu")
		(net "GPU_3V3IO_RSVD3_ISO")
	)
	(segment
		(start 242.148614 -181.351682)
		(end 242.148614 -195.133468)
		(width 0.127)
		(layer "In11.Cu")
		(net "GPU_3V3IO_RSVD3_ISO")
	)
	(segment
		(start 219.194634 -158.397702)
		(end 242.148614 -181.351682)
		(width 0.127)
		(layer "In11.Cu")
		(net "GPU_3V3IO_RSVD3_ISO")
	)
	(segment
		(start 242.148614 -195.133468)
		(end 239.32388 -197.958202)
		(width 0.127)
		(layer "In11.Cu")
		(net "GPU_3V3IO_RSVD3_ISO")
	)
	(segment
		(start 219.194634 -150.477982)
		(end 219.194634 -158.397702)
		(width 0.127)
		(layer "In11.Cu")
		(net "GPU_3V3IO_RSVD3_ISO")
	)
	(segment
		(start 239.32388 -201.69124)
		(end 240.771934 -203.139294)
		(width 0.127)
		(layer "In11.Cu")
		(net "GPU_3V3IO_RSVD3_ISO")
	)
	(segment
		(start 207.33766 -123.44146)
		(end 207.33766 -127.25654)
		(width 0.127)
		(layer "In11.Cu")
		(net "GPU_3V3IO_RSVD3_ISO")
	)
	(segment
		(start 217.58402 -145.767298)
		(end 217.58402 -148.867368)
		(width 0.127)
		(layer "In11.Cu")
		(net "GPU_3V3IO_RSVD3_ISO")
	)
	(segment
		(start 207.82788 -131.032504)
		(end 207.82788 -136.011158)
		(width 0.127)
		(layer "In11.Cu")
		(net "GPU_3V3IO_RSVD3_ISO")
	)
	(segment
		(start 206.5274 -122.6312)
		(end 207.33766 -123.44146)
		(width 0.127)
		(layer "In11.Cu")
		(net "GPU_3V3IO_RSVD3_ISO")
	)
	(segment
		(start 205.95844 -118.074948)
		(end 206.5274 -118.643908)
		(width 0.127)
		(layer "In11.Cu")
		(net "GPU_3V3IO_RSVD3_ISO")
	)
	(segment
		(start 217.58402 -148.867368)
		(end 219.194634 -150.477982)
		(width 0.127)
		(layer "In11.Cu")
		(net "GPU_3V3IO_RSVD3_ISO")
	)
	(segment
		(start 206.72806 -129.932684)
		(end 207.82788 -131.032504)
		(width 0.127)
		(layer "In11.Cu")
		(net "GPU_3V3IO_RSVD3_ISO")
	)
	(segment
		(start 207.33766 -127.25654)
		(end 206.72806 -127.86614)
		(width 0.127)
		(layer "In11.Cu")
		(net "GPU_3V3IO_RSVD3_ISO")
	)
	(segment
		(start 207.82788 -136.011158)
		(end 217.58402 -145.767298)
		(width 0.127)
		(layer "In11.Cu")
		(net "GPU_3V3IO_RSVD3_ISO")
	)
	(segment
		(start 303.18456 -436.58663)
		(end 302.534574 -436.58663)
		(width 0.12954)
		(layer "F.Cu")
		(net "GPU_3V3IO_RSVD3_FFU_N")
	)
	(segment
		(start 303.631092 -437.858408)
		(end 303.780444 -437.709056)
		(width 0.12954)
		(layer "F.Cu")
		(net "GPU_3V3IO_RSVD3_FFU_N")
	)
	(segment
		(start 302.534574 -437.819292)
		(end 302.57369 -437.858408)
		(width 0.12954)
		(layer "F.Cu")
		(net "GPU_3V3IO_RSVD3_FFU_N")
	)
	(segment
		(start 302.534574 -436.58663)
		(end 302.534574 -437.819292)
		(width 0.12954)
		(layer "F.Cu")
		(net "GPU_3V3IO_RSVD3_FFU_N")
	)
	(segment
		(start 302.57369 -437.858408)
		(end 303.631092 -437.858408)
		(width 0.12954)
		(layer "F.Cu")
		(net "GPU_3V3IO_RSVD3_FFU_N")
	)
	(via
		(at 302.57369 -437.858408)
		(size 0.762)
		(drill 0.381)
		(layers "F.Cu" "B.Cu")
		(net "GPU_3V3IO_RSVD3_FFU_N")
	)
	(segment
		(start 200.60031 -114.264948)
		(end 199.97928 -114.264948)
		(width 0.12954)
		(layer "F.Cu")
		(net "GPU_3V3IO_RSVD3_FFU_ISO_R")
	)
	(segment
		(start 186.955684 -112.97539)
		(end 187.355734 -112.57534)
		(width 0.12954)
		(layer "F.Cu")
		(net "GPU_3V3IO_RSVD3_FFU_ISO_R")
	)
	(via
		(at 187.355734 -112.57534)
		(size 0.4572)
		(drill 0.254)
		(layers "F.Cu" "B.Cu")
		(net "GPU_3V3IO_RSVD3_FFU_ISO_R")
	)
	(via
		(at 199.97928 -114.264948)
		(size 0.508)
		(drill 0.254)
		(layers "F.Cu" "B.Cu")
		(net "GPU_3V3IO_RSVD3_FFU_ISO_R")
	)
	(segment
		(start 189.703202 -114.435636)
		(end 187.842906 -112.57534)
		(width 0.127)
		(layer "In2.Cu")
		(net "GPU_3V3IO_RSVD3_FFU_ISO_R")
	)
	(segment
		(start 187.842906 -112.57534)
		(end 187.355734 -112.57534)
		(width 0.127)
		(layer "In2.Cu")
		(net "GPU_3V3IO_RSVD3_FFU_ISO_R")
	)
	(segment
		(start 199.808592 -114.435636)
		(end 189.703202 -114.435636)
		(width 0.127)
		(layer "In2.Cu")
		(net "GPU_3V3IO_RSVD3_FFU_ISO_R")
	)
	(segment
		(start 199.97928 -114.264948)
		(end 199.808592 -114.435636)
		(width 0.127)
		(layer "In2.Cu")
		(net "GPU_3V3IO_RSVD3_FFU_ISO_R")
	)
	(segment
		(start 201.40041 -114.264948)
		(end 202.01128 -114.264948)
		(width 0.12954)
		(layer "F.Cu")
		(net "GPU_3V3IO_RSVD3_FFU_ISO")
	)
	(segment
		(start 303.834546 -434.68671)
		(end 303.834546 -434.240686)
		(width 0.12954)
		(layer "F.Cu")
		(net "GPU_3V3IO_RSVD3_FFU_ISO")
	)
	(segment
		(start 304.65903 -430.49825)
		(end 304.65903 -429.21428)
		(width 0.12954)
		(layer "F.Cu")
		(net "GPU_3V3IO_RSVD3_FFU_ISO")
	)
	(segment
		(start 304.29581 -428.85106)
		(end 303.88814 -428.85106)
		(width 0.12954)
		(layer "F.Cu")
		(net "GPU_3V3IO_RSVD3_FFU_ISO")
	)
	(segment
		(start 303.834546 -434.240686)
		(end 304.09896 -433.976272)
		(width 0.12954)
		(layer "F.Cu")
		(net "GPU_3V3IO_RSVD3_FFU_ISO")
	)
	(segment
		(start 304.65903 -429.21428)
		(end 304.29581 -428.85106)
		(width 0.12954)
		(layer "F.Cu")
		(net "GPU_3V3IO_RSVD3_FFU_ISO")
	)
	(segment
		(start 303.786032 -431.05832)
		(end 304.09896 -431.05832)
		(width 0.12954)
		(layer "F.Cu")
		(net "GPU_3V3IO_RSVD3_FFU_ISO")
	)
	(segment
		(start 304.09896 -433.976272)
		(end 304.09896 -433.44592)
		(width 0.12954)
		(layer "F.Cu")
		(net "GPU_3V3IO_RSVD3_FFU_ISO")
	)
	(segment
		(start 303.477422 -432.824382)
		(end 303.477422 -431.36693)
		(width 0.12954)
		(layer "F.Cu")
		(net "GPU_3V3IO_RSVD3_FFU_ISO")
	)
	(segment
		(start 304.09896 -433.44592)
		(end 303.477422 -432.824382)
		(width 0.12954)
		(layer "F.Cu")
		(net "GPU_3V3IO_RSVD3_FFU_ISO")
	)
	(segment
		(start 303.477422 -431.36693)
		(end 303.786032 -431.05832)
		(width 0.12954)
		(layer "F.Cu")
		(net "GPU_3V3IO_RSVD3_FFU_ISO")
	)
	(segment
		(start 304.09896 -431.05832)
		(end 304.65903 -430.49825)
		(width 0.12954)
		(layer "F.Cu")
		(net "GPU_3V3IO_RSVD3_FFU_ISO")
	)
	(via
		(at 209.82686 -340.197948)
		(size 0.508)
		(drill 0.254)
		(layers "F.Cu" "B.Cu")
		(net "GPU_3V3IO_RSVD3_FFU_ISO")
	)
	(via
		(at 303.477422 -431.36693)
		(size 0.508)
		(drill 0.254)
		(layers "F.Cu" "B.Cu")
		(net "GPU_3V3IO_RSVD3_FFU_ISO")
	)
	(via
		(at 202.01128 -114.264948)
		(size 0.508)
		(drill 0.254)
		(layers "F.Cu" "B.Cu")
		(net "GPU_3V3IO_RSVD3_FFU_ISO")
	)
	(segment
		(start 261.05104 -352.090228)
		(end 253.3015 -352.090228)
		(width 0.12954)
		(layer "B.Cu")
		(net "GPU_3V3IO_RSVD3_FFU_ISO")
	)
	(segment
		(start 281.1272 -384.99542)
		(end 279.99944 -384.99542)
		(width 0.12954)
		(layer "B.Cu")
		(net "GPU_3V3IO_RSVD3_FFU_ISO")
	)
	(segment
		(start 281.44978 -385.99364)
		(end 281.44978 -385.318)
		(width 0.12954)
		(layer "B.Cu")
		(net "GPU_3V3IO_RSVD3_FFU_ISO")
	)
	(segment
		(start 305.06162 -418.15512)
		(end 302.7045 -415.798)
		(width 0.12954)
		(layer "B.Cu")
		(net "GPU_3V3IO_RSVD3_FFU_ISO")
	)
	(segment
		(start 292.6588 -409.4607)
		(end 288.39414 -409.4607)
		(width 0.12954)
		(layer "B.Cu")
		(net "GPU_3V3IO_RSVD3_FFU_ISO")
	)
	(segment
		(start 241.40922 -340.197948)
		(end 209.82686 -340.197948)
		(width 0.12954)
		(layer "B.Cu")
		(net "GPU_3V3IO_RSVD3_FFU_ISO")
	)
	(segment
		(start 293.45382 -410.25572)
		(end 292.6588 -409.4607)
		(width 0.12954)
		(layer "B.Cu")
		(net "GPU_3V3IO_RSVD3_FFU_ISO")
	)
	(segment
		(start 266.90574 -371.90172)
		(end 266.90574 -357.944928)
		(width 0.12954)
		(layer "B.Cu")
		(net "GPU_3V3IO_RSVD3_FFU_ISO")
	)
	(segment
		(start 308.95798 -429.92802)
		(end 308.95798 -428.5742)
		(width 0.12954)
		(layer "B.Cu")
		(net "GPU_3V3IO_RSVD3_FFU_ISO")
	)
	(segment
		(start 302.7045 -415.798)
		(end 294.46474 -415.798)
		(width 0.12954)
		(layer "B.Cu")
		(net "GPU_3V3IO_RSVD3_FFU_ISO")
	)
	(segment
		(start 279.99944 -384.99542)
		(end 266.90574 -371.90172)
		(width 0.12954)
		(layer "B.Cu")
		(net "GPU_3V3IO_RSVD3_FFU_ISO")
	)
	(segment
		(start 285.661862 -395.872208)
		(end 284.569662 -394.780008)
		(width 0.12954)
		(layer "B.Cu")
		(net "GPU_3V3IO_RSVD3_FFU_ISO")
	)
	(segment
		(start 308.95798 -428.5742)
		(end 305.06162 -424.67784)
		(width 0.12954)
		(layer "B.Cu")
		(net "GPU_3V3IO_RSVD3_FFU_ISO")
	)
	(segment
		(start 305.06162 -424.67784)
		(end 305.06162 -418.15512)
		(width 0.12954)
		(layer "B.Cu")
		(net "GPU_3V3IO_RSVD3_FFU_ISO")
	)
	(segment
		(start 308.55666 -430.32934)
		(end 308.95798 -429.92802)
		(width 0.12954)
		(layer "B.Cu")
		(net "GPU_3V3IO_RSVD3_FFU_ISO")
	)
	(segment
		(start 266.90574 -357.944928)
		(end 261.05104 -352.090228)
		(width 0.12954)
		(layer "B.Cu")
		(net "GPU_3V3IO_RSVD3_FFU_ISO")
	)
	(segment
		(start 303.477422 -431.36693)
		(end 304.417222 -431.36693)
		(width 0.12954)
		(layer "B.Cu")
		(net "GPU_3V3IO_RSVD3_FFU_ISO")
	)
	(segment
		(start 284.569662 -389.113522)
		(end 281.44978 -385.99364)
		(width 0.12954)
		(layer "B.Cu")
		(net "GPU_3V3IO_RSVD3_FFU_ISO")
	)
	(segment
		(start 293.45382 -414.78708)
		(end 293.45382 -410.25572)
		(width 0.12954)
		(layer "B.Cu")
		(net "GPU_3V3IO_RSVD3_FFU_ISO")
	)
	(segment
		(start 285.661862 -406.728422)
		(end 285.661862 -395.872208)
		(width 0.12954)
		(layer "B.Cu")
		(net "GPU_3V3IO_RSVD3_FFU_ISO")
	)
	(segment
		(start 284.569662 -394.780008)
		(end 284.569662 -389.113522)
		(width 0.12954)
		(layer "B.Cu")
		(net "GPU_3V3IO_RSVD3_FFU_ISO")
	)
	(segment
		(start 253.3015 -352.090228)
		(end 241.40922 -340.197948)
		(width 0.12954)
		(layer "B.Cu")
		(net "GPU_3V3IO_RSVD3_FFU_ISO")
	)
	(segment
		(start 288.39414 -409.4607)
		(end 285.661862 -406.728422)
		(width 0.12954)
		(layer "B.Cu")
		(net "GPU_3V3IO_RSVD3_FFU_ISO")
	)
	(segment
		(start 305.454812 -430.32934)
		(end 308.55666 -430.32934)
		(width 0.12954)
		(layer "B.Cu")
		(net "GPU_3V3IO_RSVD3_FFU_ISO")
	)
	(segment
		(start 294.46474 -415.798)
		(end 293.45382 -414.78708)
		(width 0.12954)
		(layer "B.Cu")
		(net "GPU_3V3IO_RSVD3_FFU_ISO")
	)
	(segment
		(start 304.417222 -431.36693)
		(end 305.454812 -430.32934)
		(width 0.12954)
		(layer "B.Cu")
		(net "GPU_3V3IO_RSVD3_FFU_ISO")
	)
	(segment
		(start 281.44978 -385.318)
		(end 281.1272 -384.99542)
		(width 0.12954)
		(layer "B.Cu")
		(net "GPU_3V3IO_RSVD3_FFU_ISO")
	)
	(segment
		(start 214.28964 -138.32078)
		(end 223.36252 -147.39366)
		(width 0.127)
		(layer "In2.Cu")
		(net "GPU_3V3IO_RSVD3_FFU_ISO")
	)
	(segment
		(start 207.772 -113.0554)
		(end 210.2104 -115.4938)
		(width 0.127)
		(layer "In2.Cu")
		(net "GPU_3V3IO_RSVD3_FFU_ISO")
	)
	(segment
		(start 202.9333 -113.726468)
		(end 204.840332 -113.726468)
		(width 0.127)
		(layer "In2.Cu")
		(net "GPU_3V3IO_RSVD3_FFU_ISO")
	)
	(segment
		(start 213.02726 -134.64794)
		(end 214.28964 -135.91032)
		(width 0.127)
		(layer "In2.Cu")
		(net "GPU_3V3IO_RSVD3_FFU_ISO")
	)
	(segment
		(start 205.5114 -113.0554)
		(end 207.772 -113.0554)
		(width 0.127)
		(layer "In2.Cu")
		(net "GPU_3V3IO_RSVD3_FFU_ISO")
	)
	(segment
		(start 214.28964 -124.841)
		(end 214.28964 -131.72694)
		(width 0.127)
		(layer "In2.Cu")
		(net "GPU_3V3IO_RSVD3_FFU_ISO")
	)
	(segment
		(start 223.36252 -147.39366)
		(end 223.36252 -188.73724)
		(width 0.127)
		(layer "In2.Cu")
		(net "GPU_3V3IO_RSVD3_FFU_ISO")
	)
	(segment
		(start 204.840332 -113.726468)
		(end 205.5114 -113.0554)
		(width 0.127)
		(layer "In2.Cu")
		(net "GPU_3V3IO_RSVD3_FFU_ISO")
	)
	(segment
		(start 210.2104 -115.4938)
		(end 210.2104 -116.367306)
		(width 0.127)
		(layer "In2.Cu")
		(net "GPU_3V3IO_RSVD3_FFU_ISO")
	)
	(segment
		(start 210.2104 -116.367306)
		(end 212.725 -118.881906)
		(width 0.127)
		(layer "In2.Cu")
		(net "GPU_3V3IO_RSVD3_FFU_ISO")
	)
	(segment
		(start 214.28964 -135.91032)
		(end 214.28964 -138.32078)
		(width 0.127)
		(layer "In2.Cu")
		(net "GPU_3V3IO_RSVD3_FFU_ISO")
	)
	(segment
		(start 202.39482 -114.264948)
		(end 202.9333 -113.726468)
		(width 0.127)
		(layer "In2.Cu")
		(net "GPU_3V3IO_RSVD3_FFU_ISO")
	)
	(segment
		(start 212.725 -118.881906)
		(end 212.725 -123.27636)
		(width 0.127)
		(layer "In2.Cu")
		(net "GPU_3V3IO_RSVD3_FFU_ISO")
	)
	(segment
		(start 225.14814 -190.52286)
		(end 225.14814 -216.787476)
		(width 0.127)
		(layer "In2.Cu")
		(net "GPU_3V3IO_RSVD3_FFU_ISO")
	)
	(segment
		(start 212.32876 -340.197948)
		(end 209.82686 -340.197948)
		(width 0.127)
		(layer "In2.Cu")
		(net "GPU_3V3IO_RSVD3_FFU_ISO")
	)
	(segment
		(start 202.01128 -114.264948)
		(end 202.39482 -114.264948)
		(width 0.127)
		(layer "In2.Cu")
		(net "GPU_3V3IO_RSVD3_FFU_ISO")
	)
	(segment
		(start 212.725 -123.27636)
		(end 214.28964 -124.841)
		(width 0.127)
		(layer "In2.Cu")
		(net "GPU_3V3IO_RSVD3_FFU_ISO")
	)
	(segment
		(start 213.02726 -132.98932)
		(end 213.02726 -134.64794)
		(width 0.127)
		(layer "In2.Cu")
		(net "GPU_3V3IO_RSVD3_FFU_ISO")
	)
	(segment
		(start 222.51416 -219.421456)
		(end 222.51416 -330.012548)
		(width 0.127)
		(layer "In2.Cu")
		(net "GPU_3V3IO_RSVD3_FFU_ISO")
	)
	(segment
		(start 214.28964 -131.72694)
		(end 213.02726 -132.98932)
		(width 0.127)
		(layer "In2.Cu")
		(net "GPU_3V3IO_RSVD3_FFU_ISO")
	)
	(segment
		(start 222.51416 -330.012548)
		(end 212.32876 -340.197948)
		(width 0.127)
		(layer "In2.Cu")
		(net "GPU_3V3IO_RSVD3_FFU_ISO")
	)
	(segment
		(start 225.14814 -216.787476)
		(end 222.51416 -219.421456)
		(width 0.127)
		(layer "In2.Cu")
		(net "GPU_3V3IO_RSVD3_FFU_ISO")
	)
	(segment
		(start 223.36252 -188.73724)
		(end 225.14814 -190.52286)
		(width 0.127)
		(layer "In2.Cu")
		(net "GPU_3V3IO_RSVD3_FFU_ISO")
	)
	(segment
		(start 302.85436 -433.44592)
		(end 302.85436 -433.866798)
		(width 0.12954)
		(layer "F.Cu")
		(net "GPU_3V3IO_RSVD3_FFU")
	)
	(segment
		(start 302.85436 -431.03292)
		(end 302.85436 -431.05832)
		(width 0.12954)
		(layer "F.Cu")
		(net "GPU_3V3IO_RSVD3_FFU")
	)
	(segment
		(start 302.85436 -433.44592)
		(end 302.31969 -432.91125)
		(width 0.12954)
		(layer "F.Cu")
		(net "GPU_3V3IO_RSVD3_FFU")
	)
	(segment
		(start 302.85436 -431.06467)
		(end 302.85436 -431.05832)
		(width 0.12954)
		(layer "F.Cu")
		(net "GPU_3V3IO_RSVD3_FFU")
	)
	(segment
		(start 302.85436 -433.866798)
		(end 303.18456 -434.196998)
		(width 0.12954)
		(layer "F.Cu")
		(net "GPU_3V3IO_RSVD3_FFU")
	)
	(segment
		(start 302.32223 -428.97552)
		(end 302.32223 -430.50079)
		(width 0.12954)
		(layer "F.Cu")
		(net "GPU_3V3IO_RSVD3_FFU")
	)
	(segment
		(start 303.18456 -434.196998)
		(end 303.18456 -434.68671)
		(width 0.12954)
		(layer "F.Cu")
		(net "GPU_3V3IO_RSVD3_FFU")
	)
	(segment
		(start 302.31969 -431.59934)
		(end 302.85436 -431.06467)
		(width 0.12954)
		(layer "F.Cu")
		(net "GPU_3V3IO_RSVD3_FFU")
	)
	(segment
		(start 302.44669 -428.85106)
		(end 303.08804 -428.85106)
		(width 0.12954)
		(layer "F.Cu")
		(net "GPU_3V3IO_RSVD3_FFU")
	)
	(segment
		(start 302.32223 -430.50079)
		(end 302.85436 -431.03292)
		(width 0.12954)
		(layer "F.Cu")
		(net "GPU_3V3IO_RSVD3_FFU")
	)
	(segment
		(start 302.44669 -428.85106)
		(end 302.32223 -428.97552)
		(width 0.12954)
		(layer "F.Cu")
		(net "GPU_3V3IO_RSVD3_FFU")
	)
	(segment
		(start 302.31969 -432.91125)
		(end 302.31969 -431.59934)
		(width 0.12954)
		(layer "F.Cu")
		(net "GPU_3V3IO_RSVD3_FFU")
	)
	(via
		(at 302.44669 -428.85106)
		(size 0.508)
		(drill 0.254)
		(layers "F.Cu" "B.Cu")
		(net "GPU_3V3IO_RSVD3_FFU")
	)
	(segment
		(start 310.68264 -437.1213)
		(end 303.48936 -437.1213)
		(width 0.127)
		(layer "In2.Cu")
		(net "GPU_3V3IO_RSVD3_FFU")
	)
	(segment
		(start 314.051188 -440.489848)
		(end 310.68264 -437.1213)
		(width 0.127)
		(layer "In2.Cu")
		(net "GPU_3V3IO_RSVD3_FFU")
	)
	(segment
		(start 301.97806 -429.31969)
		(end 302.44669 -428.85106)
		(width 0.127)
		(layer "In2.Cu")
		(net "GPU_3V3IO_RSVD3_FFU")
	)
	(segment
		(start 301.97806 -435.61)
		(end 301.97806 -429.31969)
		(width 0.127)
		(layer "In2.Cu")
		(net "GPU_3V3IO_RSVD3_FFU")
	)
	(segment
		(start 314.65012 -440.489848)
		(end 314.051188 -440.489848)
		(width 0.127)
		(layer "In2.Cu")
		(net "GPU_3V3IO_RSVD3_FFU")
	)
	(segment
		(start 303.48936 -437.1213)
		(end 301.97806 -435.61)
		(width 0.127)
		(layer "In2.Cu")
		(net "GPU_3V3IO_RSVD3_FFU")
	)
	(segment
		(start 356.15245 -389.905748)
		(end 355.61905 -390.439148)
		(width 0.12954)
		(layer "F.Cu")
		(net "GPU_3V3IO_RSVD3")
	)
	(segment
		(start 360.844592 -390.43737)
		(end 360.075734 -391.206228)
		(width 0.12954)
		(layer "F.Cu")
		(net "GPU_3V3IO_RSVD3")
	)
	(segment
		(start 360.895392 -390.48817)
		(end 360.844592 -390.43737)
		(width 0.12954)
		(layer "F.Cu")
		(net "GPU_3V3IO_RSVD3")
	)
	(segment
		(start 357.948992 -390.86536)
		(end 357.948992 -390.43737)
		(width 0.12954)
		(layer "F.Cu")
		(net "GPU_3V3IO_RSVD3")
	)
	(segment
		(start 357.948992 -390.43737)
		(end 357.41737 -389.905748)
		(width 0.12954)
		(layer "F.Cu")
		(net "GPU_3V3IO_RSVD3")
	)
	(segment
		(start 360.075734 -391.206228)
		(end 358.28986 -391.206228)
		(width 0.12954)
		(layer "F.Cu")
		(net "GPU_3V3IO_RSVD3")
	)
	(segment
		(start 363.990382 -390.48817)
		(end 362.48848 -390.48817)
		(width 0.12954)
		(layer "F.Cu")
		(net "GPU_3V3IO_RSVD3")
	)
	(segment
		(start 357.41737 -389.905748)
		(end 356.15245 -389.905748)
		(width 0.12954)
		(layer "F.Cu")
		(net "GPU_3V3IO_RSVD3")
	)
	(segment
		(start 362.48848 -390.48817)
		(end 360.895392 -390.48817)
		(width 0.12954)
		(layer "F.Cu")
		(net "GPU_3V3IO_RSVD3")
	)
	(segment
		(start 358.28986 -391.206228)
		(end 357.948992 -390.86536)
		(width 0.12954)
		(layer "F.Cu")
		(net "GPU_3V3IO_RSVD3")
	)
	(via
		(at 362.48848 -390.48817)
		(size 0.508)
		(drill 0.254)
		(layers "F.Cu" "B.Cu")
		(net "GPU_3V3IO_RSVD3")
	)
	(segment
		(start 363.40288 -391.40257)
		(end 363.40288 -397.119348)
		(width 0.127)
		(layer "In2.Cu")
		(net "GPU_3V3IO_RSVD3")
	)
	(segment
		(start 405.89708 -422.316148)
		(end 405.89708 -439.636916)
		(width 0.127)
		(layer "In2.Cu")
		(net "GPU_3V3IO_RSVD3")
	)
	(segment
		(start 377.549918 -412.88208)
		(end 381.345186 -416.677348)
		(width 0.127)
		(layer "In2.Cu")
		(net "GPU_3V3IO_RSVD3")
	)
	(segment
		(start 372.637812 -412.88208)
		(end 377.549918 -412.88208)
		(width 0.127)
		(layer "In2.Cu")
		(net "GPU_3V3IO_RSVD3")
	)
	(segment
		(start 381.345186 -416.677348)
		(end 400.25828 -416.677348)
		(width 0.127)
		(layer "In2.Cu")
		(net "GPU_3V3IO_RSVD3")
	)
	(segment
		(start 368.66068 -402.377148)
		(end 368.66068 -408.904948)
		(width 0.127)
		(layer "In2.Cu")
		(net "GPU_3V3IO_RSVD3")
	)
	(segment
		(start 368.66068 -408.904948)
		(end 372.637812 -412.88208)
		(width 0.127)
		(layer "In2.Cu")
		(net "GPU_3V3IO_RSVD3")
	)
	(segment
		(start 362.48848 -390.48817)
		(end 363.40288 -391.40257)
		(width 0.127)
		(layer "In2.Cu")
		(net "GPU_3V3IO_RSVD3")
	)
	(segment
		(start 405.89708 -439.636916)
		(end 406.750012 -440.489848)
		(width 0.127)
		(layer "In2.Cu")
		(net "GPU_3V3IO_RSVD3")
	)
	(segment
		(start 363.40288 -397.119348)
		(end 368.66068 -402.377148)
		(width 0.127)
		(layer "In2.Cu")
		(net "GPU_3V3IO_RSVD3")
	)
	(segment
		(start 400.25828 -416.677348)
		(end 405.89708 -422.316148)
		(width 0.127)
		(layer "In2.Cu")
		(net "GPU_3V3IO_RSVD3")
	)
	(segment
		(start 299.890434 -426.188632)
		(end 299.890434 -424.95597)
		(width 0.12954)
		(layer "F.Cu")
		(net "PRSNT_CABLE_GPU_B3")
	)
	(segment
		(start 300.54042 -424.95597)
		(end 299.890434 -424.95597)
		(width 0.12954)
		(layer "F.Cu")
		(net "PRSNT_CABLE_GPU_B3")
	)
	(segment
		(start 300.986952 -426.227748)
		(end 301.136304 -426.078396)
		(width 0.12954)
		(layer "F.Cu")
		(net "PRSNT_CABLE_GPU_B3")
	)
	(segment
		(start 299.92955 -426.227748)
		(end 299.890434 -426.188632)
		(width 0.12954)
		(layer "F.Cu")
		(net "PRSNT_CABLE_GPU_B3")
	)
	(segment
		(start 299.92955 -426.227748)
		(end 300.986952 -426.227748)
		(width 0.12954)
		(layer "F.Cu")
		(net "PRSNT_CABLE_GPU_B3")
	)
	(via
		(at 299.92955 -426.227748)
		(size 0.762)
		(drill 0.381)
		(layers "F.Cu" "B.Cu")
		(net "PRSNT_CABLE_GPU_B3")
	)
	(segment
		(start 200.60031 -112.994948)
		(end 199.97928 -112.994948)
		(width 0.12954)
		(layer "F.Cu")
		(net "PRSNT_CABLE_GPU_B3_ISO_R_N")
	)
	(segment
		(start 186.155584 -112.97539)
		(end 186.555634 -112.57534)
		(width 0.12954)
		(layer "F.Cu")
		(net "PRSNT_CABLE_GPU_B3_ISO_R_N")
	)
	(via
		(at 199.97928 -112.994948)
		(size 0.508)
		(drill 0.254)
		(layers "F.Cu" "B.Cu")
		(net "PRSNT_CABLE_GPU_B3_ISO_R_N")
	)
	(via
		(at 186.555634 -112.57534)
		(size 0.4572)
		(drill 0.254)
		(layers "F.Cu" "B.Cu")
		(net "PRSNT_CABLE_GPU_B3_ISO_R_N")
	)
	(segment
		(start 188.09462 -112.121188)
		(end 187.009786 -112.121188)
		(width 0.127)
		(layer "In2.Cu")
		(net "PRSNT_CABLE_GPU_B3_ISO_R_N")
	)
	(segment
		(start 188.81344 -111.402368)
		(end 188.09462 -112.121188)
		(width 0.127)
		(layer "In2.Cu")
		(net "PRSNT_CABLE_GPU_B3_ISO_R_N")
	)
	(segment
		(start 199.97928 -112.994948)
		(end 199.31888 -112.334548)
		(width 0.127)
		(layer "In2.Cu")
		(net "PRSNT_CABLE_GPU_B3_ISO_R_N")
	)
	(segment
		(start 192.470786 -110.572296)
		(end 191.640714 -111.402368)
		(width 0.127)
		(layer "In2.Cu")
		(net "PRSNT_CABLE_GPU_B3_ISO_R_N")
	)
	(segment
		(start 187.009786 -112.121188)
		(end 186.555634 -112.57534)
		(width 0.127)
		(layer "In2.Cu")
		(net "PRSNT_CABLE_GPU_B3_ISO_R_N")
	)
	(segment
		(start 199.31888 -111.376968)
		(end 198.514208 -110.572296)
		(width 0.127)
		(layer "In2.Cu")
		(net "PRSNT_CABLE_GPU_B3_ISO_R_N")
	)
	(segment
		(start 199.31888 -112.334548)
		(end 199.31888 -111.376968)
		(width 0.127)
		(layer "In2.Cu")
		(net "PRSNT_CABLE_GPU_B3_ISO_R_N")
	)
	(segment
		(start 191.640714 -111.402368)
		(end 188.81344 -111.402368)
		(width 0.127)
		(layer "In2.Cu")
		(net "PRSNT_CABLE_GPU_B3_ISO_R_N")
	)
	(segment
		(start 198.514208 -110.572296)
		(end 192.470786 -110.572296)
		(width 0.127)
		(layer "In2.Cu")
		(net "PRSNT_CABLE_GPU_B3_ISO_R_N")
	)
	(segment
		(start 300.54042 -422.566338)
		(end 300.54042 -423.05605)
		(width 0.12954)
		(layer "F.Cu")
		(net "PRSNT_CABLE_GPU_B3_N")
	)
	(segment
		(start 299.67555 -419.96868)
		(end 300.21022 -419.43401)
		(width 0.12954)
		(layer "F.Cu")
		(net "PRSNT_CABLE_GPU_B3_N")
	)
	(segment
		(start 299.67555 -421.28059)
		(end 299.67555 -419.96868)
		(width 0.12954)
		(layer "F.Cu")
		(net "PRSNT_CABLE_GPU_B3_N")
	)
	(segment
		(start 299.680122 -418.897562)
		(end 299.680122 -417.342828)
		(width 0.12954)
		(layer "F.Cu")
		(net "PRSNT_CABLE_GPU_B3_N")
	)
	(segment
		(start 300.21022 -419.42766)
		(end 299.680122 -418.897562)
		(width 0.12954)
		(layer "F.Cu")
		(net "PRSNT_CABLE_GPU_B3_N")
	)
	(segment
		(start 299.680122 -417.342828)
		(end 299.80255 -417.2204)
		(width 0.12954)
		(layer "F.Cu")
		(net "PRSNT_CABLE_GPU_B3_N")
	)
	(segment
		(start 300.21022 -421.81526)
		(end 300.21022 -422.236138)
		(width 0.12954)
		(layer "F.Cu")
		(net "PRSNT_CABLE_GPU_B3_N")
	)
	(segment
		(start 300.21022 -422.236138)
		(end 300.54042 -422.566338)
		(width 0.12954)
		(layer "F.Cu")
		(net "PRSNT_CABLE_GPU_B3_N")
	)
	(segment
		(start 300.21022 -419.43401)
		(end 300.21022 -419.42766)
		(width 0.12954)
		(layer "F.Cu")
		(net "PRSNT_CABLE_GPU_B3_N")
	)
	(segment
		(start 300.21022 -421.81526)
		(end 299.67555 -421.28059)
		(width 0.12954)
		(layer "F.Cu")
		(net "PRSNT_CABLE_GPU_B3_N")
	)
	(segment
		(start 299.80255 -417.2204)
		(end 300.4439 -417.2204)
		(width 0.12954)
		(layer "F.Cu")
		(net "PRSNT_CABLE_GPU_B3_N")
	)
	(via
		(at 299.80255 -417.2204)
		(size 0.508)
		(drill 0.254)
		(layers "F.Cu" "B.Cu")
		(net "PRSNT_CABLE_GPU_B3_N")
	)
	(via
		(at 172.33646 -430.69764)
		(size 0.508)
		(drill 0.254)
		(layers "F.Cu" "B.Cu")
		(net "PRSNT_CABLE_GPU_B3_N")
	)
	(segment
		(start 158.31312 -435.9529)
		(end 158.31312 -426.29074)
		(width 0.127)
		(layer "In2.Cu")
		(net "PRSNT_CABLE_GPU_B3_N")
	)
	(segment
		(start 172.33646 -437.13146)
		(end 169.8625 -439.60542)
		(width 0.127)
		(layer "In2.Cu")
		(net "PRSNT_CABLE_GPU_B3_N")
	)
	(segment
		(start 172.33646 -430.69764)
		(end 172.33646 -437.13146)
		(width 0.127)
		(layer "In2.Cu")
		(net "PRSNT_CABLE_GPU_B3_N")
	)
	(segment
		(start 161.96564 -439.60542)
		(end 158.31312 -435.9529)
		(width 0.127)
		(layer "In2.Cu")
		(net "PRSNT_CABLE_GPU_B3_N")
	)
	(segment
		(start 169.8625 -439.60542)
		(end 161.96564 -439.60542)
		(width 0.127)
		(layer "In2.Cu")
		(net "PRSNT_CABLE_GPU_B3_N")
	)
	(segment
		(start 156.750004 -424.727624)
		(end 156.750004 -424.689778)
		(width 0.127)
		(layer "In2.Cu")
		(net "PRSNT_CABLE_GPU_B3_N")
	)
	(segment
		(start 158.31312 -426.29074)
		(end 156.750004 -424.727624)
		(width 0.127)
		(layer "In2.Cu")
		(net "PRSNT_CABLE_GPU_B3_N")
	)
	(segment
		(start 299.063156 -427.10481)
		(end 296.548556 -429.61941)
		(width 0.127)
		(layer "In11.Cu")
		(net "PRSNT_CABLE_GPU_B3_N")
	)
	(segment
		(start 299.4914 -419.227)
		(end 299.4914 -420.87292)
		(width 0.127)
		(layer "In11.Cu")
		(net "PRSNT_CABLE_GPU_B3_N")
	)
	(segment
		(start 299.80255 -417.2204)
		(end 299.212 -417.81095)
		(width 0.127)
		(layer "In11.Cu")
		(net "PRSNT_CABLE_GPU_B3_N")
	)
	(segment
		(start 299.4914 -420.87292)
		(end 299.063156 -421.301164)
		(width 0.127)
		(layer "In11.Cu")
		(net "PRSNT_CABLE_GPU_B3_N")
	)
	(segment
		(start 279.63749 -429.61941)
		(end 277.55088 -431.70602)
		(width 0.127)
		(layer "In11.Cu")
		(net "PRSNT_CABLE_GPU_B3_N")
	)
	(segment
		(start 299.212 -417.81095)
		(end 299.212 -418.9476)
		(width 0.127)
		(layer "In11.Cu")
		(net "PRSNT_CABLE_GPU_B3_N")
	)
	(segment
		(start 296.548556 -429.61941)
		(end 279.63749 -429.61941)
		(width 0.127)
		(layer "In11.Cu")
		(net "PRSNT_CABLE_GPU_B3_N")
	)
	(segment
		(start 299.212 -418.9476)
		(end 299.4914 -419.227)
		(width 0.127)
		(layer "In11.Cu")
		(net "PRSNT_CABLE_GPU_B3_N")
	)
	(segment
		(start 188.35116 -429.19904)
		(end 173.83506 -429.19904)
		(width 0.127)
		(layer "In11.Cu")
		(net "PRSNT_CABLE_GPU_B3_N")
	)
	(segment
		(start 299.063156 -421.301164)
		(end 299.063156 -427.10481)
		(width 0.127)
		(layer "In11.Cu")
		(net "PRSNT_CABLE_GPU_B3_N")
	)
	(segment
		(start 198.3232 -439.17108)
		(end 188.35116 -429.19904)
		(width 0.127)
		(layer "In11.Cu")
		(net "PRSNT_CABLE_GPU_B3_N")
	)
	(segment
		(start 173.83506 -429.19904)
		(end 172.33646 -430.69764)
		(width 0.127)
		(layer "In11.Cu")
		(net "PRSNT_CABLE_GPU_B3_N")
	)
	(segment
		(start 273.71294 -439.17108)
		(end 198.3232 -439.17108)
		(width 0.127)
		(layer "In11.Cu")
		(net "PRSNT_CABLE_GPU_B3_N")
	)
	(segment
		(start 277.55088 -431.70602)
		(end 277.55088 -435.33314)
		(width 0.127)
		(layer "In11.Cu")
		(net "PRSNT_CABLE_GPU_B3_N")
	)
	(segment
		(start 277.55088 -435.33314)
		(end 273.71294 -439.17108)
		(width 0.127)
		(layer "In11.Cu")
		(net "PRSNT_CABLE_GPU_B3_N")
	)
	(segment
		(start 367.16462 -387.119876)
		(end 368.070638 -387.119876)
		(width 0.12954)
		(layer "F.Cu")
		(net "GPU_3V3IO_RSVD1_N")
	)
	(segment
		(start 365.829342 -387.119876)
		(end 367.16462 -387.119876)
		(width 0.12954)
		(layer "F.Cu")
		(net "GPU_3V3IO_RSVD1_N")
	)
	(segment
		(start 365.829342 -386.46989)
		(end 365.829342 -387.119876)
		(width 0.12954)
		(layer "F.Cu")
		(net "GPU_3V3IO_RSVD1_N")
	)
	(segment
		(start 368.070638 -387.119876)
		(end 368.729768 -387.779006)
		(width 0.12954)
		(layer "F.Cu")
		(net "GPU_3V3IO_RSVD1_N")
	)
	(via
		(at 367.16462 -387.119876)
		(size 0.762)
		(drill 0.381)
		(layers "F.Cu" "B.Cu")
		(net "GPU_3V3IO_RSVD1_N")
	)
	(segment
		(start 182.155592 -113.77549)
		(end 182.555642 -114.17554)
		(width 0.12954)
		(layer "F.Cu")
		(net "GPU_3V3IO_RSVD1_ISO_R")
	)
	(segment
		(start 208.09331 -118.074948)
		(end 207.46974 -118.074948)
		(width 0.12954)
		(layer "F.Cu")
		(net "GPU_3V3IO_RSVD1_ISO_R")
	)
	(via
		(at 182.555642 -114.17554)
		(size 0.4572)
		(drill 0.254)
		(layers "F.Cu" "B.Cu")
		(net "GPU_3V3IO_RSVD1_ISO_R")
	)
	(via
		(at 207.46974 -118.074948)
		(size 0.508)
		(drill 0.254)
		(layers "F.Cu" "B.Cu")
		(net "GPU_3V3IO_RSVD1_ISO_R")
	)
	(segment
		(start 207.46974 -118.074948)
		(end 207.46974 -119.068088)
		(width 0.127)
		(layer "In2.Cu")
		(net "GPU_3V3IO_RSVD1_ISO_R")
	)
	(segment
		(start 206.55788 -119.979948)
		(end 191.08928 -119.979948)
		(width 0.127)
		(layer "In2.Cu")
		(net "GPU_3V3IO_RSVD1_ISO_R")
	)
	(segment
		(start 188.17082 -116.650008)
		(end 187.70092 -116.180108)
		(width 0.127)
		(layer "In2.Cu")
		(net "GPU_3V3IO_RSVD1_ISO_R")
	)
	(segment
		(start 184.75706 -116.180108)
		(end 183.76138 -115.184428)
		(width 0.127)
		(layer "In2.Cu")
		(net "GPU_3V3IO_RSVD1_ISO_R")
	)
	(segment
		(start 183.76138 -115.184428)
		(end 183.76138 -114.803428)
		(width 0.127)
		(layer "In2.Cu")
		(net "GPU_3V3IO_RSVD1_ISO_R")
	)
	(segment
		(start 183.1848 -114.572288)
		(end 182.788052 -114.17554)
		(width 0.127)
		(layer "In2.Cu")
		(net "GPU_3V3IO_RSVD1_ISO_R")
	)
	(segment
		(start 183.53024 -114.572288)
		(end 183.1848 -114.572288)
		(width 0.127)
		(layer "In2.Cu")
		(net "GPU_3V3IO_RSVD1_ISO_R")
	)
	(segment
		(start 187.70092 -116.180108)
		(end 184.75706 -116.180108)
		(width 0.127)
		(layer "In2.Cu")
		(net "GPU_3V3IO_RSVD1_ISO_R")
	)
	(segment
		(start 188.17082 -117.061488)
		(end 188.17082 -116.650008)
		(width 0.127)
		(layer "In2.Cu")
		(net "GPU_3V3IO_RSVD1_ISO_R")
	)
	(segment
		(start 191.08928 -119.979948)
		(end 188.17082 -117.061488)
		(width 0.127)
		(layer "In2.Cu")
		(net "GPU_3V3IO_RSVD1_ISO_R")
	)
	(segment
		(start 183.76138 -114.803428)
		(end 183.53024 -114.572288)
		(width 0.127)
		(layer "In2.Cu")
		(net "GPU_3V3IO_RSVD1_ISO_R")
	)
	(segment
		(start 207.46974 -119.068088)
		(end 206.55788 -119.979948)
		(width 0.127)
		(layer "In2.Cu")
		(net "GPU_3V3IO_RSVD1_ISO_R")
	)
	(segment
		(start 182.788052 -114.17554)
		(end 182.555642 -114.17554)
		(width 0.127)
		(layer "In2.Cu")
		(net "GPU_3V3IO_RSVD1_ISO_R")
	)
	(segment
		(start 357.758492 -385.790948)
		(end 357.888032 -385.661408)
		(width 0.12954)
		(layer "F.Cu")
		(net "GPU_3V3IO_RSVD1_ISO")
	)
	(segment
		(start 360.162094 -385.796028)
		(end 358.50957 -385.796028)
		(width 0.12954)
		(layer "F.Cu")
		(net "GPU_3V3IO_RSVD1_ISO")
	)
	(segment
		(start 362.5469 -385.155948)
		(end 362.1659 -385.155948)
		(width 0.12954)
		(layer "F.Cu")
		(net "GPU_3V3IO_RSVD1_ISO")
	)
	(segment
		(start 360.783632 -385.17449)
		(end 360.162094 -385.796028)
		(width 0.12954)
		(layer "F.Cu")
		(net "GPU_3V3IO_RSVD1_ISO")
	)
	(segment
		(start 355.092 -385.790948)
		(end 355.65588 -385.790948)
		(width 0.12954)
		(layer "F.Cu")
		(net "GPU_3V3IO_RSVD1_ISO")
	)
	(segment
		(start 363.929422 -385.819904)
		(end 363.210856 -385.819904)
		(width 0.12954)
		(layer "F.Cu")
		(net "GPU_3V3IO_RSVD1_ISO")
	)
	(segment
		(start 358.50957 -385.796028)
		(end 357.888032 -385.17449)
		(width 0.12954)
		(layer "F.Cu")
		(net "GPU_3V3IO_RSVD1_ISO")
	)
	(segment
		(start 354.84435 -386.425948)
		(end 354.84435 -386.038598)
		(width 0.12954)
		(layer "F.Cu")
		(net "GPU_3V3IO_RSVD1_ISO")
	)
	(segment
		(start 355.65588 -385.790948)
		(end 357.758492 -385.790948)
		(width 0.12954)
		(layer "F.Cu")
		(net "GPU_3V3IO_RSVD1_ISO")
	)
	(segment
		(start 363.210856 -385.819904)
		(end 362.5469 -385.155948)
		(width 0.12954)
		(layer "F.Cu")
		(net "GPU_3V3IO_RSVD1_ISO")
	)
	(segment
		(start 360.802174 -385.155948)
		(end 360.783632 -385.17449)
		(width 0.12954)
		(layer "F.Cu")
		(net "GPU_3V3IO_RSVD1_ISO")
	)
	(segment
		(start 362.1659 -385.155948)
		(end 360.802174 -385.155948)
		(width 0.12954)
		(layer "F.Cu")
		(net "GPU_3V3IO_RSVD1_ISO")
	)
	(segment
		(start 357.888032 -385.661408)
		(end 357.888032 -385.17449)
		(width 0.12954)
		(layer "F.Cu")
		(net "GPU_3V3IO_RSVD1_ISO")
	)
	(segment
		(start 354.84435 -386.038598)
		(end 355.092 -385.790948)
		(width 0.12954)
		(layer "F.Cu")
		(net "GPU_3V3IO_RSVD1_ISO")
	)
	(segment
		(start 208.89341 -118.074948)
		(end 209.51444 -118.074948)
		(width 0.12954)
		(layer "F.Cu")
		(net "GPU_3V3IO_RSVD1_ISO")
	)
	(via
		(at 240.483644 -202.002898)
		(size 0.508)
		(drill 0.254)
		(layers "F.Cu" "B.Cu")
		(net "GPU_3V3IO_RSVD1_ISO")
	)
	(via
		(at 362.1659 -385.155948)
		(size 0.762)
		(drill 0.381)
		(layers "F.Cu" "B.Cu")
		(net "GPU_3V3IO_RSVD1_ISO")
	)
	(via
		(at 209.51444 -118.074948)
		(size 0.508)
		(drill 0.254)
		(layers "F.Cu" "B.Cu")
		(net "GPU_3V3IO_RSVD1_ISO")
	)
	(via
		(at 304.402744 -388.457948)
		(size 0.508)
		(drill 0.254)
		(layers "F.Cu" "B.Cu")
		(net "GPU_3V3IO_RSVD1_ISO")
	)
	(via
		(at 355.65588 -385.790948)
		(size 0.508)
		(drill 0.254)
		(layers "F.Cu" "B.Cu")
		(net "GPU_3V3IO_RSVD1_ISO")
	)
	(segment
		(start 295.448228 -383.631948)
		(end 289.84956 -383.631948)
		(width 0.127)
		(layer "In4.Cu")
		(net "GPU_3V3IO_RSVD1_ISO")
	)
	(segment
		(start 289.84956 -383.631948)
		(end 280.07056 -373.852948)
		(width 0.127)
		(layer "In4.Cu")
		(net "GPU_3V3IO_RSVD1_ISO")
	)
	(segment
		(start 248.46788 -327.84796)
		(end 248.46788 -280.665936)
		(width 0.127)
		(layer "In4.Cu")
		(net "GPU_3V3IO_RSVD1_ISO")
	)
	(segment
		(start 280.07056 -373.852948)
		(end 280.07056 -359.45064)
		(width 0.127)
		(layer "In4.Cu")
		(net "GPU_3V3IO_RSVD1_ISO")
	)
	(segment
		(start 304.402744 -388.457948)
		(end 300.274228 -388.457948)
		(width 0.127)
		(layer "In4.Cu")
		(net "GPU_3V3IO_RSVD1_ISO")
	)
	(segment
		(start 251.16028 -212.679534)
		(end 240.483644 -202.002898)
		(width 0.127)
		(layer "In4.Cu")
		(net "GPU_3V3IO_RSVD1_ISO")
	)
	(segment
		(start 300.274228 -388.457948)
		(end 295.448228 -383.631948)
		(width 0.127)
		(layer "In4.Cu")
		(net "GPU_3V3IO_RSVD1_ISO")
	)
	(segment
		(start 251.16028 -277.973536)
		(end 251.16028 -212.679534)
		(width 0.127)
		(layer "In4.Cu")
		(net "GPU_3V3IO_RSVD1_ISO")
	)
	(segment
		(start 280.07056 -359.45064)
		(end 248.46788 -327.84796)
		(width 0.127)
		(layer "In4.Cu")
		(net "GPU_3V3IO_RSVD1_ISO")
	)
	(segment
		(start 248.46788 -280.665936)
		(end 251.16028 -277.973536)
		(width 0.127)
		(layer "In4.Cu")
		(net "GPU_3V3IO_RSVD1_ISO")
	)
	(segment
		(start 355.65588 -385.790948)
		(end 321.36588 -385.790948)
		(width 0.127)
		(layer "In6.Cu")
		(net "GPU_3V3IO_RSVD1_ISO")
	)
	(segment
		(start 321.36588 -385.790948)
		(end 318.69888 -388.457948)
		(width 0.127)
		(layer "In6.Cu")
		(net "GPU_3V3IO_RSVD1_ISO")
	)
	(segment
		(start 318.69888 -388.457948)
		(end 304.402744 -388.457948)
		(width 0.127)
		(layer "In6.Cu")
		(net "GPU_3V3IO_RSVD1_ISO")
	)
	(segment
		(start 209.22488 -136.12622)
		(end 219.709746 -146.611086)
		(width 0.127)
		(layer "In11.Cu")
		(net "GPU_3V3IO_RSVD1_ISO")
	)
	(segment
		(start 219.709746 -158.41726)
		(end 242.49888 -181.206394)
		(width 0.127)
		(layer "In11.Cu")
		(net "GPU_3V3IO_RSVD1_ISO")
	)
	(segment
		(start 219.709746 -146.611086)
		(end 219.709746 -158.41726)
		(width 0.127)
		(layer "In11.Cu")
		(net "GPU_3V3IO_RSVD1_ISO")
	)
	(segment
		(start 207.70088 -126.329948)
		(end 208.58988 -127.218948)
		(width 0.127)
		(layer "In11.Cu")
		(net "GPU_3V3IO_RSVD1_ISO")
	)
	(segment
		(start 209.22488 -129.377948)
		(end 209.22488 -136.12622)
		(width 0.127)
		(layer "In11.Cu")
		(net "GPU_3V3IO_RSVD1_ISO")
	)
	(segment
		(start 208.58988 -128.742948)
		(end 209.22488 -129.377948)
		(width 0.127)
		(layer "In11.Cu")
		(net "GPU_3V3IO_RSVD1_ISO")
	)
	(segment
		(start 207.70088 -122.54992)
		(end 207.70088 -126.329948)
		(width 0.127)
		(layer "In11.Cu")
		(net "GPU_3V3IO_RSVD1_ISO")
	)
	(segment
		(start 239.975644 -201.494898)
		(end 240.483644 -202.002898)
		(width 0.127)
		(layer "In11.Cu")
		(net "GPU_3V3IO_RSVD1_ISO")
	)
	(segment
		(start 242.49888 -195.291202)
		(end 239.975644 -197.814438)
		(width 0.127)
		(layer "In11.Cu")
		(net "GPU_3V3IO_RSVD1_ISO")
	)
	(segment
		(start 242.49888 -181.206394)
		(end 242.49888 -195.291202)
		(width 0.127)
		(layer "In11.Cu")
		(net "GPU_3V3IO_RSVD1_ISO")
	)
	(segment
		(start 207.9244 -122.3264)
		(end 207.70088 -122.54992)
		(width 0.127)
		(layer "In11.Cu")
		(net "GPU_3V3IO_RSVD1_ISO")
	)
	(segment
		(start 209.51444 -118.074948)
		(end 207.9244 -119.664988)
		(width 0.127)
		(layer "In11.Cu")
		(net "GPU_3V3IO_RSVD1_ISO")
	)
	(segment
		(start 239.975644 -197.814438)
		(end 239.975644 -201.494898)
		(width 0.127)
		(layer "In11.Cu")
		(net "GPU_3V3IO_RSVD1_ISO")
	)
	(segment
		(start 207.9244 -119.664988)
		(end 207.9244 -122.3264)
		(width 0.127)
		(layer "In11.Cu")
		(net "GPU_3V3IO_RSVD1_ISO")
	)
	(segment
		(start 208.58988 -127.218948)
		(end 208.58988 -128.742948)
		(width 0.127)
		(layer "In11.Cu")
		(net "GPU_3V3IO_RSVD1_ISO")
	)
	(segment
		(start 308.66334 -436.66537)
		(end 308.013354 -436.66537)
		(width 0.12954)
		(layer "F.Cu")
		(net "GPU_3V3IO_RSVD1_FFU_N")
	)
	(segment
		(start 308.013354 -437.898032)
		(end 308.05247 -437.937148)
		(width 0.12954)
		(layer "F.Cu")
		(net "GPU_3V3IO_RSVD1_FFU_N")
	)
	(segment
		(start 308.013354 -436.66537)
		(end 308.013354 -437.898032)
		(width 0.12954)
		(layer "F.Cu")
		(net "GPU_3V3IO_RSVD1_FFU_N")
	)
	(segment
		(start 309.109872 -437.937148)
		(end 309.259224 -437.787796)
		(width 0.12954)
		(layer "F.Cu")
		(net "GPU_3V3IO_RSVD1_FFU_N")
	)
	(segment
		(start 308.05247 -437.937148)
		(end 309.109872 -437.937148)
		(width 0.12954)
		(layer "F.Cu")
		(net "GPU_3V3IO_RSVD1_FFU_N")
	)
	(via
		(at 308.05247 -437.937148)
		(size 0.762)
		(drill 0.381)
		(layers "F.Cu" "B.Cu")
		(net "GPU_3V3IO_RSVD1_FFU_N")
	)
	(segment
		(start 182.955692 -112.97539)
		(end 183.355742 -112.57534)
		(width 0.12954)
		(layer "F.Cu")
		(net "GPU_3V3IO_RSVD1_FFU_ISO_R")
	)
	(segment
		(start 200.60031 -115.534948)
		(end 199.97928 -115.534948)
		(width 0.12954)
		(layer "F.Cu")
		(net "GPU_3V3IO_RSVD1_FFU_ISO_R")
	)
	(via
		(at 199.97928 -115.534948)
		(size 0.508)
		(drill 0.254)
		(layers "F.Cu" "B.Cu")
		(net "GPU_3V3IO_RSVD1_FFU_ISO_R")
	)
	(via
		(at 183.355742 -112.57534)
		(size 0.4572)
		(drill 0.254)
		(layers "F.Cu" "B.Cu")
		(net "GPU_3V3IO_RSVD1_FFU_ISO_R")
	)
	(segment
		(start 199.97928 -115.534948)
		(end 199.50938 -116.004848)
		(width 0.127)
		(layer "In2.Cu")
		(net "GPU_3V3IO_RSVD1_FFU_ISO_R")
	)
	(segment
		(start 199.50938 -116.004848)
		(end 190.217806 -116.004848)
		(width 0.127)
		(layer "In2.Cu")
		(net "GPU_3V3IO_RSVD1_FFU_ISO_R")
	)
	(segment
		(start 190.217806 -116.004848)
		(end 187.657486 -113.444528)
		(width 0.127)
		(layer "In2.Cu")
		(net "GPU_3V3IO_RSVD1_FFU_ISO_R")
	)
	(segment
		(start 187.657486 -113.444528)
		(end 184.22493 -113.444528)
		(width 0.127)
		(layer "In2.Cu")
		(net "GPU_3V3IO_RSVD1_FFU_ISO_R")
	)
	(segment
		(start 184.22493 -113.444528)
		(end 183.355742 -112.57534)
		(width 0.127)
		(layer "In2.Cu")
		(net "GPU_3V3IO_RSVD1_FFU_ISO_R")
	)
	(segment
		(start 309.57774 -434.055012)
		(end 309.57774 -433.52466)
		(width 0.12954)
		(layer "F.Cu")
		(net "GPU_3V3IO_RSVD1_FFU_ISO")
	)
	(segment
		(start 309.313326 -434.76545)
		(end 309.313326 -434.319426)
		(width 0.12954)
		(layer "F.Cu")
		(net "GPU_3V3IO_RSVD1_FFU_ISO")
	)
	(segment
		(start 310.15305 -429.32604)
		(end 309.75681 -428.9298)
		(width 0.12954)
		(layer "F.Cu")
		(net "GPU_3V3IO_RSVD1_FFU_ISO")
	)
	(segment
		(start 310.15305 -430.56175)
		(end 310.15305 -429.32604)
		(width 0.12954)
		(layer "F.Cu")
		(net "GPU_3V3IO_RSVD1_FFU_ISO")
	)
	(segment
		(start 308.956202 -431.44567)
		(end 309.264812 -431.13706)
		(width 0.12954)
		(layer "F.Cu")
		(net "GPU_3V3IO_RSVD1_FFU_ISO")
	)
	(segment
		(start 309.57774 -431.13706)
		(end 310.15305 -430.56175)
		(width 0.12954)
		(layer "F.Cu")
		(net "GPU_3V3IO_RSVD1_FFU_ISO")
	)
	(segment
		(start 309.313326 -434.319426)
		(end 309.57774 -434.055012)
		(width 0.12954)
		(layer "F.Cu")
		(net "GPU_3V3IO_RSVD1_FFU_ISO")
	)
	(segment
		(start 309.264812 -431.13706)
		(end 309.57774 -431.13706)
		(width 0.12954)
		(layer "F.Cu")
		(net "GPU_3V3IO_RSVD1_FFU_ISO")
	)
	(segment
		(start 201.40041 -115.534948)
		(end 202.01128 -115.534948)
		(width 0.12954)
		(layer "F.Cu")
		(net "GPU_3V3IO_RSVD1_FFU_ISO")
	)
	(segment
		(start 309.57774 -433.52466)
		(end 308.956202 -432.903122)
		(width 0.12954)
		(layer "F.Cu")
		(net "GPU_3V3IO_RSVD1_FFU_ISO")
	)
	(segment
		(start 309.75681 -428.9298)
		(end 309.36692 -428.9298)
		(width 0.12954)
		(layer "F.Cu")
		(net "GPU_3V3IO_RSVD1_FFU_ISO")
	)
	(segment
		(start 308.956202 -432.903122)
		(end 308.956202 -431.44567)
		(width 0.12954)
		(layer "F.Cu")
		(net "GPU_3V3IO_RSVD1_FFU_ISO")
	)
	(via
		(at 202.01128 -115.534948)
		(size 0.508)
		(drill 0.254)
		(layers "F.Cu" "B.Cu")
		(net "GPU_3V3IO_RSVD1_FFU_ISO")
	)
	(via
		(at 209.82686 -338.927948)
		(size 0.508)
		(drill 0.254)
		(layers "F.Cu" "B.Cu")
		(net "GPU_3V3IO_RSVD1_FFU_ISO")
	)
	(via
		(at 308.956202 -431.44567)
		(size 0.508)
		(drill 0.254)
		(layers "F.Cu" "B.Cu")
		(net "GPU_3V3IO_RSVD1_FFU_ISO")
	)
	(segment
		(start 296.3545 -404.97887)
		(end 287.282128 -404.97887)
		(width 0.12954)
		(layer "B.Cu")
		(net "GPU_3V3IO_RSVD1_FFU_ISO")
	)
	(segment
		(start 310.7944 -428.17034)
		(end 309.55742 -426.93336)
		(width 0.12954)
		(layer "B.Cu")
		(net "GPU_3V3IO_RSVD1_FFU_ISO")
	)
	(segment
		(start 282.86964 -384.27914)
		(end 280.5557 -384.27914)
		(width 0.12954)
		(layer "B.Cu")
		(net "GPU_3V3IO_RSVD1_FFU_ISO")
	)
	(segment
		(start 268.17574 -371.89918)
		(end 268.17574 -357.41864)
		(width 0.12954)
		(layer "B.Cu")
		(net "GPU_3V3IO_RSVD1_FFU_ISO")
	)
	(segment
		(start 310.7944 -431.07864)
		(end 310.7944 -428.17034)
		(width 0.12954)
		(layer "B.Cu")
		(net "GPU_3V3IO_RSVD1_FFU_ISO")
	)
	(segment
		(start 286.385762 -404.082504)
		(end 286.385762 -395.504162)
		(width 0.12954)
		(layer "B.Cu")
		(net "GPU_3V3IO_RSVD1_FFU_ISO")
	)
	(segment
		(start 253.827788 -350.820228)
		(end 241.935508 -338.927948)
		(width 0.12954)
		(layer "B.Cu")
		(net "GPU_3V3IO_RSVD1_FFU_ISO")
	)
	(segment
		(start 310.42737 -431.44567)
		(end 310.7944 -431.07864)
		(width 0.12954)
		(layer "B.Cu")
		(net "GPU_3V3IO_RSVD1_FFU_ISO")
	)
	(segment
		(start 308.956202 -431.44567)
		(end 310.42737 -431.44567)
		(width 0.12954)
		(layer "B.Cu")
		(net "GPU_3V3IO_RSVD1_FFU_ISO")
	)
	(segment
		(start 261.577328 -350.820228)
		(end 253.827788 -350.820228)
		(width 0.12954)
		(layer "B.Cu")
		(net "GPU_3V3IO_RSVD1_FFU_ISO")
	)
	(segment
		(start 280.5557 -384.27914)
		(end 268.17574 -371.89918)
		(width 0.12954)
		(layer "B.Cu")
		(net "GPU_3V3IO_RSVD1_FFU_ISO")
	)
	(segment
		(start 309.55742 -426.93336)
		(end 309.55742 -420.664386)
		(width 0.12954)
		(layer "B.Cu")
		(net "GPU_3V3IO_RSVD1_FFU_ISO")
	)
	(segment
		(start 285.395162 -394.513562)
		(end 285.395162 -386.804662)
		(width 0.12954)
		(layer "B.Cu")
		(net "GPU_3V3IO_RSVD1_FFU_ISO")
	)
	(segment
		(start 241.935508 -338.927948)
		(end 209.82686 -338.927948)
		(width 0.12954)
		(layer "B.Cu")
		(net "GPU_3V3IO_RSVD1_FFU_ISO")
	)
	(segment
		(start 285.395162 -386.804662)
		(end 282.86964 -384.27914)
		(width 0.12954)
		(layer "B.Cu")
		(net "GPU_3V3IO_RSVD1_FFU_ISO")
	)
	(segment
		(start 268.17574 -357.41864)
		(end 261.577328 -350.820228)
		(width 0.12954)
		(layer "B.Cu")
		(net "GPU_3V3IO_RSVD1_FFU_ISO")
	)
	(segment
		(start 286.385762 -395.504162)
		(end 285.395162 -394.513562)
		(width 0.12954)
		(layer "B.Cu")
		(net "GPU_3V3IO_RSVD1_FFU_ISO")
	)
	(segment
		(start 302.2981 -410.92247)
		(end 296.3545 -404.97887)
		(width 0.12954)
		(layer "B.Cu")
		(net "GPU_3V3IO_RSVD1_FFU_ISO")
	)
	(segment
		(start 287.282128 -404.97887)
		(end 286.385762 -404.082504)
		(width 0.12954)
		(layer "B.Cu")
		(net "GPU_3V3IO_RSVD1_FFU_ISO")
	)
	(segment
		(start 309.55742 -420.664386)
		(end 302.2981 -413.405066)
		(width 0.12954)
		(layer "B.Cu")
		(net "GPU_3V3IO_RSVD1_FFU_ISO")
	)
	(segment
		(start 302.2981 -413.405066)
		(end 302.2981 -410.92247)
		(width 0.12954)
		(layer "B.Cu")
		(net "GPU_3V3IO_RSVD1_FFU_ISO")
	)
	(segment
		(start 224.11182 -216.358216)
		(end 221.47784 -218.992196)
		(width 0.127)
		(layer "In2.Cu")
		(net "GPU_3V3IO_RSVD1_FFU_ISO")
	)
	(segment
		(start 210.35518 -128.648968)
		(end 210.35518 -135.8519)
		(width 0.127)
		(layer "In2.Cu")
		(net "GPU_3V3IO_RSVD1_FFU_ISO")
	)
	(segment
		(start 212.09762 -338.927948)
		(end 209.82686 -338.927948)
		(width 0.127)
		(layer "In2.Cu")
		(net "GPU_3V3IO_RSVD1_FFU_ISO")
	)
	(segment
		(start 221.47784 -218.992196)
		(end 221.47784 -329.547728)
		(width 0.127)
		(layer "In2.Cu")
		(net "GPU_3V3IO_RSVD1_FFU_ISO")
	)
	(segment
		(start 210.312 -118.207536)
		(end 210.312 -121.4882)
		(width 0.127)
		(layer "In2.Cu")
		(net "GPU_3V3IO_RSVD1_FFU_ISO")
	)
	(segment
		(start 221.47784 -329.547728)
		(end 212.09762 -338.927948)
		(width 0.127)
		(layer "In2.Cu")
		(net "GPU_3V3IO_RSVD1_FFU_ISO")
	)
	(segment
		(start 210.312 -121.4882)
		(end 209.98688 -121.81332)
		(width 0.127)
		(layer "In2.Cu")
		(net "GPU_3V3IO_RSVD1_FFU_ISO")
	)
	(segment
		(start 202.77582 -115.534948)
		(end 203.42352 -114.887248)
		(width 0.127)
		(layer "In2.Cu")
		(net "GPU_3V3IO_RSVD1_FFU_ISO")
	)
	(segment
		(start 224.11182 -190.586868)
		(end 224.11182 -216.358216)
		(width 0.127)
		(layer "In2.Cu")
		(net "GPU_3V3IO_RSVD1_FFU_ISO")
	)
	(segment
		(start 222.3262 -188.801248)
		(end 224.11182 -190.586868)
		(width 0.127)
		(layer "In2.Cu")
		(net "GPU_3V3IO_RSVD1_FFU_ISO")
	)
	(segment
		(start 210.35518 -135.8519)
		(end 222.3262 -147.82292)
		(width 0.127)
		(layer "In2.Cu")
		(net "GPU_3V3IO_RSVD1_FFU_ISO")
	)
	(segment
		(start 202.01128 -115.534948)
		(end 202.77582 -115.534948)
		(width 0.127)
		(layer "In2.Cu")
		(net "GPU_3V3IO_RSVD1_FFU_ISO")
	)
	(segment
		(start 209.98688 -121.81332)
		(end 209.98688 -128.280668)
		(width 0.127)
		(layer "In2.Cu")
		(net "GPU_3V3IO_RSVD1_FFU_ISO")
	)
	(segment
		(start 206.991712 -114.887248)
		(end 210.312 -118.207536)
		(width 0.127)
		(layer "In2.Cu")
		(net "GPU_3V3IO_RSVD1_FFU_ISO")
	)
	(segment
		(start 203.42352 -114.887248)
		(end 206.991712 -114.887248)
		(width 0.127)
		(layer "In2.Cu")
		(net "GPU_3V3IO_RSVD1_FFU_ISO")
	)
	(segment
		(start 209.98688 -128.280668)
		(end 210.35518 -128.648968)
		(width 0.127)
		(layer "In2.Cu")
		(net "GPU_3V3IO_RSVD1_FFU_ISO")
	)
	(segment
		(start 222.3262 -147.82292)
		(end 222.3262 -188.801248)
		(width 0.127)
		(layer "In2.Cu")
		(net "GPU_3V3IO_RSVD1_FFU_ISO")
	)
	(segment
		(start 308.33314 -433.52466)
		(end 308.33314 -433.945538)
		(width 0.12954)
		(layer "F.Cu")
		(net "GPU_3V3IO_RSVD1_FFU")
	)
	(segment
		(start 308.33314 -433.945538)
		(end 308.66334 -434.275738)
		(width 0.12954)
		(layer "F.Cu")
		(net "GPU_3V3IO_RSVD1_FFU")
	)
	(segment
		(start 308.66334 -434.275738)
		(end 308.66334 -434.76545)
		(width 0.12954)
		(layer "F.Cu")
		(net "GPU_3V3IO_RSVD1_FFU")
	)
	(segment
		(start 307.803042 -429.052228)
		(end 307.92547 -428.9298)
		(width 0.12954)
		(layer "F.Cu")
		(net "GPU_3V3IO_RSVD1_FFU")
	)
	(segment
		(start 307.803042 -430.606962)
		(end 307.803042 -429.052228)
		(width 0.12954)
		(layer "F.Cu")
		(net "GPU_3V3IO_RSVD1_FFU")
	)
	(segment
		(start 307.92547 -428.9298)
		(end 308.56682 -428.9298)
		(width 0.12954)
		(layer "F.Cu")
		(net "GPU_3V3IO_RSVD1_FFU")
	)
	(segment
		(start 307.79847 -432.98999)
		(end 307.79847 -431.67808)
		(width 0.12954)
		(layer "F.Cu")
		(net "GPU_3V3IO_RSVD1_FFU")
	)
	(segment
		(start 308.33314 -431.14341)
		(end 308.33314 -431.13706)
		(width 0.12954)
		(layer "F.Cu")
		(net "GPU_3V3IO_RSVD1_FFU")
	)
	(segment
		(start 308.33314 -431.13706)
		(end 307.803042 -430.606962)
		(width 0.12954)
		(layer "F.Cu")
		(net "GPU_3V3IO_RSVD1_FFU")
	)
	(segment
		(start 307.79847 -431.67808)
		(end 308.33314 -431.14341)
		(width 0.12954)
		(layer "F.Cu")
		(net "GPU_3V3IO_RSVD1_FFU")
	)
	(segment
		(start 308.33314 -433.52466)
		(end 307.79847 -432.98999)
		(width 0.12954)
		(layer "F.Cu")
		(net "GPU_3V3IO_RSVD1_FFU")
	)
	(via
		(at 307.92547 -428.9298)
		(size 0.508)
		(drill 0.254)
		(layers "F.Cu" "B.Cu")
		(net "GPU_3V3IO_RSVD1_FFU")
	)
	(segment
		(start 270.208248 -388.10184)
		(end 269.20698 -387.100572)
		(width 0.12954)
		(layer "B.Cu")
		(net "GPU_3V3IO_RSVD1_FFU")
	)
	(segment
		(start 153.797 -423.50182)
		(end 152.750012 -424.548808)
		(width 0.12954)
		(layer "B.Cu")
		(net "GPU_3V3IO_RSVD1_FFU")
	)
	(segment
		(start 174.22368 -394.15212)
		(end 174.22368 -402.19122)
		(width 0.12954)
		(layer "B.Cu")
		(net "GPU_3V3IO_RSVD1_FFU")
	)
	(segment
		(start 287.508696 -413.855662)
		(end 285.171134 -411.5181)
		(width 0.12954)
		(layer "B.Cu")
		(net "GPU_3V3IO_RSVD1_FFU")
	)
	(segment
		(start 175.65624 -413.75838)
		(end 174.2313 -413.75838)
		(width 0.12954)
		(layer "B.Cu")
		(net "GPU_3V3IO_RSVD1_FFU")
	)
	(segment
		(start 174.2313 -413.75838)
		(end 173.1518 -414.83788)
		(width 0.12954)
		(layer "B.Cu")
		(net "GPU_3V3IO_RSVD1_FFU")
	)
	(segment
		(start 306.121054 -428.9298)
		(end 305.343814 -428.15256)
		(width 0.12954)
		(layer "B.Cu")
		(net "GPU_3V3IO_RSVD1_FFU")
	)
	(segment
		(start 282.377642 -409.2956)
		(end 283.4132 -408.260042)
		(width 0.12954)
		(layer "B.Cu")
		(net "GPU_3V3IO_RSVD1_FFU")
	)
	(segment
		(start 174.62246 -393.75334)
		(end 174.22368 -394.15212)
		(width 0.12954)
		(layer "B.Cu")
		(net "GPU_3V3IO_RSVD1_FFU")
	)
	(segment
		(start 174.22368 -402.19122)
		(end 176.0474 -404.01494)
		(width 0.12954)
		(layer "B.Cu")
		(net "GPU_3V3IO_RSVD1_FFU")
	)
	(segment
		(start 176.0474 -404.01494)
		(end 176.0474 -413.36722)
		(width 0.12954)
		(layer "B.Cu")
		(net "GPU_3V3IO_RSVD1_FFU")
	)
	(segment
		(start 174.62246 -393.089892)
		(end 174.62246 -393.75334)
		(width 0.12954)
		(layer "B.Cu")
		(net "GPU_3V3IO_RSVD1_FFU")
	)
	(segment
		(start 305.343814 -428.15256)
		(end 297.67784 -428.15256)
		(width 0.12954)
		(layer "B.Cu")
		(net "GPU_3V3IO_RSVD1_FFU")
	)
	(segment
		(start 173.1518 -414.83788)
		(end 173.1518 -425.19854)
		(width 0.12954)
		(layer "B.Cu")
		(net "GPU_3V3IO_RSVD1_FFU")
	)
	(segment
		(start 282.199842 -392.196574)
		(end 278.105108 -388.10184)
		(width 0.12954)
		(layer "B.Cu")
		(net "GPU_3V3IO_RSVD1_FFU")
	)
	(segment
		(start 297.67784 -428.15256)
		(end 292.430454 -422.905174)
		(width 0.12954)
		(layer "B.Cu")
		(net "GPU_3V3IO_RSVD1_FFU")
	)
	(segment
		(start 283.4132 -408.260042)
		(end 283.4132 -396.418054)
		(width 0.12954)
		(layer "B.Cu")
		(net "GPU_3V3IO_RSVD1_FFU")
	)
	(segment
		(start 166.5224 -426.91812)
		(end 163.1061 -423.50182)
		(width 0.12954)
		(layer "B.Cu")
		(net "GPU_3V3IO_RSVD1_FFU")
	)
	(segment
		(start 307.92547 -428.9298)
		(end 306.121054 -428.9298)
		(width 0.12954)
		(layer "B.Cu")
		(net "GPU_3V3IO_RSVD1_FFU")
	)
	(segment
		(start 278.105108 -388.10184)
		(end 270.208248 -388.10184)
		(width 0.12954)
		(layer "B.Cu")
		(net "GPU_3V3IO_RSVD1_FFU")
	)
	(segment
		(start 283.21762 -411.5181)
		(end 282.377642 -410.678122)
		(width 0.12954)
		(layer "B.Cu")
		(net "GPU_3V3IO_RSVD1_FFU")
	)
	(segment
		(start 288.032952 -413.855662)
		(end 287.508696 -413.855662)
		(width 0.12954)
		(layer "B.Cu")
		(net "GPU_3V3IO_RSVD1_FFU")
	)
	(segment
		(start 176.0474 -413.36722)
		(end 175.65624 -413.75838)
		(width 0.12954)
		(layer "B.Cu")
		(net "GPU_3V3IO_RSVD1_FFU")
	)
	(segment
		(start 262.96366 -377.6599)
		(end 190.052452 -377.6599)
		(width 0.12954)
		(layer "B.Cu")
		(net "GPU_3V3IO_RSVD1_FFU")
	)
	(segment
		(start 163.1061 -423.50182)
		(end 153.797 -423.50182)
		(width 0.12954)
		(layer "B.Cu")
		(net "GPU_3V3IO_RSVD1_FFU")
	)
	(segment
		(start 173.1518 -425.19854)
		(end 171.43222 -426.91812)
		(width 0.12954)
		(layer "B.Cu")
		(net "GPU_3V3IO_RSVD1_FFU")
	)
	(segment
		(start 285.171134 -411.5181)
		(end 283.21762 -411.5181)
		(width 0.12954)
		(layer "B.Cu")
		(net "GPU_3V3IO_RSVD1_FFU")
	)
	(segment
		(start 282.377642 -410.678122)
		(end 282.377642 -409.2956)
		(width 0.12954)
		(layer "B.Cu")
		(net "GPU_3V3IO_RSVD1_FFU")
	)
	(segment
		(start 292.430454 -418.253164)
		(end 288.032952 -413.855662)
		(width 0.12954)
		(layer "B.Cu")
		(net "GPU_3V3IO_RSVD1_FFU")
	)
	(segment
		(start 282.199842 -395.204696)
		(end 282.199842 -392.196574)
		(width 0.12954)
		(layer "B.Cu")
		(net "GPU_3V3IO_RSVD1_FFU")
	)
	(segment
		(start 152.750012 -424.548808)
		(end 152.750012 -424.689778)
		(width 0.12954)
		(layer "B.Cu")
		(net "GPU_3V3IO_RSVD1_FFU")
	)
	(segment
		(start 269.20698 -383.90322)
		(end 262.96366 -377.6599)
		(width 0.12954)
		(layer "B.Cu")
		(net "GPU_3V3IO_RSVD1_FFU")
	)
	(segment
		(start 292.430454 -422.905174)
		(end 292.430454 -418.253164)
		(width 0.12954)
		(layer "B.Cu")
		(net "GPU_3V3IO_RSVD1_FFU")
	)
	(segment
		(start 269.20698 -387.100572)
		(end 269.20698 -383.90322)
		(width 0.12954)
		(layer "B.Cu")
		(net "GPU_3V3IO_RSVD1_FFU")
	)
	(segment
		(start 171.43222 -426.91812)
		(end 166.5224 -426.91812)
		(width 0.12954)
		(layer "B.Cu")
		(net "GPU_3V3IO_RSVD1_FFU")
	)
	(segment
		(start 283.4132 -396.418054)
		(end 282.199842 -395.204696)
		(width 0.12954)
		(layer "B.Cu")
		(net "GPU_3V3IO_RSVD1_FFU")
	)
	(segment
		(start 190.052452 -377.6599)
		(end 174.62246 -393.089892)
		(width 0.12954)
		(layer "B.Cu")
		(net "GPU_3V3IO_RSVD1_FFU")
	)
	(segment
		(start 360.834432 -386.46989)
		(end 360.783632 -386.41909)
		(width 0.12954)
		(layer "F.Cu")
		(net "GPU_3V3IO_RSVD1")
	)
	(segment
		(start 360.014774 -387.187948)
		(end 358.2289 -387.187948)
		(width 0.12954)
		(layer "F.Cu")
		(net "GPU_3V3IO_RSVD1")
	)
	(segment
		(start 357.888032 -386.84708)
		(end 357.888032 -386.41909)
		(width 0.12954)
		(layer "F.Cu")
		(net "GPU_3V3IO_RSVD1")
	)
	(segment
		(start 357.888032 -386.41909)
		(end 357.322374 -386.984748)
		(width 0.12954)
		(layer "F.Cu")
		(net "GPU_3V3IO_RSVD1")
	)
	(segment
		(start 362.20908 -386.46989)
		(end 360.834432 -386.46989)
		(width 0.12954)
		(layer "F.Cu")
		(net "GPU_3V3IO_RSVD1")
	)
	(segment
		(start 356.20325 -386.984748)
		(end 355.64445 -386.425948)
		(width 0.12954)
		(layer "F.Cu")
		(net "GPU_3V3IO_RSVD1")
	)
	(segment
		(start 357.322374 -386.984748)
		(end 356.20325 -386.984748)
		(width 0.12954)
		(layer "F.Cu")
		(net "GPU_3V3IO_RSVD1")
	)
	(segment
		(start 358.2289 -387.187948)
		(end 357.888032 -386.84708)
		(width 0.12954)
		(layer "F.Cu")
		(net "GPU_3V3IO_RSVD1")
	)
	(segment
		(start 363.929422 -386.46989)
		(end 362.20908 -386.46989)
		(width 0.12954)
		(layer "F.Cu")
		(net "GPU_3V3IO_RSVD1")
	)
	(segment
		(start 360.783632 -386.41909)
		(end 360.014774 -387.187948)
		(width 0.12954)
		(layer "F.Cu")
		(net "GPU_3V3IO_RSVD1")
	)
	(via
		(at 362.20908 -386.46989)
		(size 0.508)
		(drill 0.254)
		(layers "F.Cu" "B.Cu")
		(net "GPU_3V3IO_RSVD1")
	)
	(segment
		(start 370.3574 -401.635468)
		(end 369.49888 -400.776948)
		(width 0.127)
		(layer "In2.Cu")
		(net "GPU_3V3IO_RSVD1")
	)
	(segment
		(start 402.46808 -415.635948)
		(end 381.74168 -415.635948)
		(width 0.127)
		(layer "In2.Cu")
		(net "GPU_3V3IO_RSVD1")
	)
	(segment
		(start 369.49888 -393.75969)
		(end 362.20908 -386.46989)
		(width 0.127)
		(layer "In2.Cu")
		(net "GPU_3V3IO_RSVD1")
	)
	(segment
		(start 377.21286 -411.107128)
		(end 372.12143 -411.107128)
		(width 0.127)
		(layer "In2.Cu")
		(net "GPU_3V3IO_RSVD1")
	)
	(segment
		(start 409.85948 -423.027348)
		(end 402.46808 -415.635948)
		(width 0.127)
		(layer "In2.Cu")
		(net "GPU_3V3IO_RSVD1")
	)
	(segment
		(start 369.49888 -400.776948)
		(end 369.49888 -393.75969)
		(width 0.127)
		(layer "In2.Cu")
		(net "GPU_3V3IO_RSVD1")
	)
	(segment
		(start 381.74168 -415.635948)
		(end 377.21286 -411.107128)
		(width 0.127)
		(layer "In2.Cu")
		(net "GPU_3V3IO_RSVD1")
	)
	(segment
		(start 370.3574 -409.343098)
		(end 370.3574 -401.635468)
		(width 0.127)
		(layer "In2.Cu")
		(net "GPU_3V3IO_RSVD1")
	)
	(segment
		(start 409.85948 -439.599324)
		(end 409.85948 -423.027348)
		(width 0.127)
		(layer "In2.Cu")
		(net "GPU_3V3IO_RSVD1")
	)
	(segment
		(start 410.750004 -440.489848)
		(end 409.85948 -439.599324)
		(width 0.127)
		(layer "In2.Cu")
		(net "GPU_3V3IO_RSVD1")
	)
	(segment
		(start 372.12143 -411.107128)
		(end 370.3574 -409.343098)
		(width 0.127)
		(layer "In2.Cu")
		(net "GPU_3V3IO_RSVD1")
	)
	(segment
		(start 303.671732 -426.306488)
		(end 303.821084 -426.157136)
		(width 0.12954)
		(layer "F.Cu")
		(net "GPU_3V3IO_RSVD0_FFU_N")
	)
	(segment
		(start 302.600614 -425.719748)
		(end 302.61433 -425.733464)
		(width 0.12954)
		(layer "F.Cu")
		(net "GPU_3V3IO_RSVD0_FFU_N")
	)
	(segment
		(start 302.600614 -425.03471)
		(end 302.600614 -425.719748)
		(width 0.12954)
		(layer "F.Cu")
		(net "GPU_3V3IO_RSVD0_FFU_N")
	)
	(segment
		(start 302.61433 -426.306488)
		(end 303.671732 -426.306488)
		(width 0.12954)
		(layer "F.Cu")
		(net "GPU_3V3IO_RSVD0_FFU_N")
	)
	(segment
		(start 302.61433 -425.733464)
		(end 302.61433 -426.306488)
		(width 0.12954)
		(layer "F.Cu")
		(net "GPU_3V3IO_RSVD0_FFU_N")
	)
	(segment
		(start 303.2506 -425.03471)
		(end 302.600614 -425.03471)
		(width 0.12954)
		(layer "F.Cu")
		(net "GPU_3V3IO_RSVD0_FFU_N")
	)
	(via
		(at 302.61433 -426.306488)
		(size 0.762)
		(drill 0.381)
		(layers "F.Cu" "B.Cu")
		(net "GPU_3V3IO_RSVD0_FFU_N")
	)
	(segment
		(start 182.155592 -112.97539)
		(end 182.555642 -112.57534)
		(width 0.12954)
		(layer "F.Cu")
		(net "GPU_3V3IO_RSVD0_FFU_ISO_R")
	)
	(segment
		(start 204.53731 -115.534948)
		(end 203.91374 -115.534948)
		(width 0.12954)
		(layer "F.Cu")
		(net "GPU_3V3IO_RSVD0_FFU_ISO_R")
	)
	(via
		(at 203.91374 -115.534948)
		(size 0.508)
		(drill 0.254)
		(layers "F.Cu" "B.Cu")
		(net "GPU_3V3IO_RSVD0_FFU_ISO_R")
	)
	(via
		(at 182.555642 -112.57534)
		(size 0.4572)
		(drill 0.254)
		(layers "F.Cu" "B.Cu")
		(net "GPU_3V3IO_RSVD0_FFU_ISO_R")
	)
	(segment
		(start 183.71947 -113.739168)
		(end 182.555642 -112.57534)
		(width 0.127)
		(layer "In2.Cu")
		(net "GPU_3V3IO_RSVD0_FFU_ISO_R")
	)
	(segment
		(start 189.954154 -116.335048)
		(end 187.358274 -113.739168)
		(width 0.127)
		(layer "In2.Cu")
		(net "GPU_3V3IO_RSVD0_FFU_ISO_R")
	)
	(segment
		(start 203.91374 -115.534948)
		(end 203.48956 -115.534948)
		(width 0.127)
		(layer "In2.Cu")
		(net "GPU_3V3IO_RSVD0_FFU_ISO_R")
	)
	(segment
		(start 202.68946 -116.335048)
		(end 189.954154 -116.335048)
		(width 0.127)
		(layer "In2.Cu")
		(net "GPU_3V3IO_RSVD0_FFU_ISO_R")
	)
	(segment
		(start 203.48956 -115.534948)
		(end 202.68946 -116.335048)
		(width 0.127)
		(layer "In2.Cu")
		(net "GPU_3V3IO_RSVD0_FFU_ISO_R")
	)
	(segment
		(start 187.358274 -113.739168)
		(end 183.71947 -113.739168)
		(width 0.127)
		(layer "In2.Cu")
		(net "GPU_3V3IO_RSVD0_FFU_ISO_R")
	)
	(segment
		(start 303.826672 -419.5064)
		(end 304.1396 -419.5064)
		(width 0.12954)
		(layer "F.Cu")
		(net "GPU_3V3IO_RSVD0_FFU_ISO")
	)
	(segment
		(start 303.900586 -422.663366)
		(end 304.1396 -422.424352)
		(width 0.12954)
		(layer "F.Cu")
		(net "GPU_3V3IO_RSVD0_FFU_ISO")
	)
	(segment
		(start 304.1396 -419.5064)
		(end 304.668682 -418.977318)
		(width 0.12954)
		(layer "F.Cu")
		(net "GPU_3V3IO_RSVD0_FFU_ISO")
	)
	(segment
		(start 304.668682 -418.977318)
		(end 304.668682 -417.589208)
		(width 0.12954)
		(layer "F.Cu")
		(net "GPU_3V3IO_RSVD0_FFU_ISO")
	)
	(segment
		(start 305.2064 -416.02152)
		(end 303.92878 -417.29914)
		(width 0.12954)
		(layer "F.Cu")
		(net "GPU_3V3IO_RSVD0_FFU_ISO")
	)
	(segment
		(start 205.33741 -115.534948)
		(end 205.95844 -115.534948)
		(width 0.12954)
		(layer "F.Cu")
		(net "GPU_3V3IO_RSVD0_FFU_ISO")
	)
	(segment
		(start 304.668682 -417.589208)
		(end 304.378614 -417.29914)
		(width 0.12954)
		(layer "F.Cu")
		(net "GPU_3V3IO_RSVD0_FFU_ISO")
	)
	(segment
		(start 303.900586 -423.13479)
		(end 303.900586 -422.663366)
		(width 0.12954)
		(layer "F.Cu")
		(net "GPU_3V3IO_RSVD0_FFU_ISO")
	)
	(segment
		(start 303.518062 -419.81501)
		(end 303.826672 -419.5064)
		(width 0.12954)
		(layer "F.Cu")
		(net "GPU_3V3IO_RSVD0_FFU_ISO")
	)
	(segment
		(start 304.378614 -417.29914)
		(end 303.92878 -417.29914)
		(width 0.12954)
		(layer "F.Cu")
		(net "GPU_3V3IO_RSVD0_FFU_ISO")
	)
	(segment
		(start 303.518062 -421.272462)
		(end 303.518062 -419.81501)
		(width 0.12954)
		(layer "F.Cu")
		(net "GPU_3V3IO_RSVD0_FFU_ISO")
	)
	(segment
		(start 304.1396 -421.894)
		(end 303.518062 -421.272462)
		(width 0.12954)
		(layer "F.Cu")
		(net "GPU_3V3IO_RSVD0_FFU_ISO")
	)
	(segment
		(start 304.1396 -422.424352)
		(end 304.1396 -421.894)
		(width 0.12954)
		(layer "F.Cu")
		(net "GPU_3V3IO_RSVD0_FFU_ISO")
	)
	(segment
		(start 305.2064 -414.98266)
		(end 305.2064 -416.02152)
		(width 0.12954)
		(layer "F.Cu")
		(net "GPU_3V3IO_RSVD0_FFU_ISO")
	)
	(via
		(at 305.2064 -414.98266)
		(size 0.508)
		(drill 0.254)
		(layers "F.Cu" "B.Cu")
		(net "GPU_3V3IO_RSVD0_FFU_ISO")
	)
	(via
		(at 205.95844 -115.534948)
		(size 0.508)
		(drill 0.254)
		(layers "F.Cu" "B.Cu")
		(net "GPU_3V3IO_RSVD0_FFU_ISO")
	)
	(via
		(at 211.35086 -338.292948)
		(size 0.508)
		(drill 0.254)
		(layers "F.Cu" "B.Cu")
		(net "GPU_3V3IO_RSVD0_FFU_ISO")
	)
	(segment
		(start 283.18968 -383.89306)
		(end 280.6827 -383.89306)
		(width 0.12954)
		(layer "B.Cu")
		(net "GPU_3V3IO_RSVD0_FFU_ISO")
	)
	(segment
		(start 280.6827 -383.89306)
		(end 268.81074 -372.0211)
		(width 0.12954)
		(layer "B.Cu")
		(net "GPU_3V3IO_RSVD0_FFU_ISO")
	)
	(segment
		(start 303.89322 -413.66948)
		(end 303.89322 -411.990032)
		(width 0.12954)
		(layer "B.Cu")
		(net "GPU_3V3IO_RSVD0_FFU_ISO")
	)
	(segment
		(start 299.91685 -408.013662)
		(end 299.91685 -406.53843)
		(width 0.12954)
		(layer "B.Cu")
		(net "GPU_3V3IO_RSVD0_FFU_ISO")
	)
	(segment
		(start 285.788862 -394.221208)
		(end 285.788862 -386.492242)
		(width 0.12954)
		(layer "B.Cu")
		(net "GPU_3V3IO_RSVD0_FFU_ISO")
	)
	(segment
		(start 305.2064 -414.98266)
		(end 303.89322 -413.66948)
		(width 0.12954)
		(layer "B.Cu")
		(net "GPU_3V3IO_RSVD0_FFU_ISO")
	)
	(segment
		(start 286.779462 -403.919182)
		(end 286.779462 -395.211808)
		(width 0.12954)
		(layer "B.Cu")
		(net "GPU_3V3IO_RSVD0_FFU_ISO")
	)
	(segment
		(start 261.840472 -350.185228)
		(end 254.090932 -350.185228)
		(width 0.12954)
		(layer "B.Cu")
		(net "GPU_3V3IO_RSVD0_FFU_ISO")
	)
	(segment
		(start 297.96359 -404.58517)
		(end 287.44545 -404.58517)
		(width 0.12954)
		(layer "B.Cu")
		(net "GPU_3V3IO_RSVD0_FFU_ISO")
	)
	(segment
		(start 242.198652 -338.292948)
		(end 211.35086 -338.292948)
		(width 0.12954)
		(layer "B.Cu")
		(net "GPU_3V3IO_RSVD0_FFU_ISO")
	)
	(segment
		(start 285.788862 -386.492242)
		(end 283.18968 -383.89306)
		(width 0.12954)
		(layer "B.Cu")
		(net "GPU_3V3IO_RSVD0_FFU_ISO")
	)
	(segment
		(start 268.81074 -372.0211)
		(end 268.81074 -357.155496)
		(width 0.12954)
		(layer "B.Cu")
		(net "GPU_3V3IO_RSVD0_FFU_ISO")
	)
	(segment
		(start 299.91685 -406.53843)
		(end 297.96359 -404.58517)
		(width 0.12954)
		(layer "B.Cu")
		(net "GPU_3V3IO_RSVD0_FFU_ISO")
	)
	(segment
		(start 268.81074 -357.155496)
		(end 261.840472 -350.185228)
		(width 0.12954)
		(layer "B.Cu")
		(net "GPU_3V3IO_RSVD0_FFU_ISO")
	)
	(segment
		(start 287.44545 -404.58517)
		(end 286.779462 -403.919182)
		(width 0.12954)
		(layer "B.Cu")
		(net "GPU_3V3IO_RSVD0_FFU_ISO")
	)
	(segment
		(start 286.779462 -395.211808)
		(end 285.788862 -394.221208)
		(width 0.12954)
		(layer "B.Cu")
		(net "GPU_3V3IO_RSVD0_FFU_ISO")
	)
	(segment
		(start 303.89322 -411.990032)
		(end 299.91685 -408.013662)
		(width 0.12954)
		(layer "B.Cu")
		(net "GPU_3V3IO_RSVD0_FFU_ISO")
	)
	(segment
		(start 254.090932 -350.185228)
		(end 242.198652 -338.292948)
		(width 0.12954)
		(layer "B.Cu")
		(net "GPU_3V3IO_RSVD0_FFU_ISO")
	)
	(segment
		(start 209.59318 -128.354328)
		(end 209.59318 -121.83618)
		(width 0.127)
		(layer "In2.Cu")
		(net "GPU_3V3IO_RSVD0_FFU_ISO")
	)
	(segment
		(start 210.02498 -128.786128)
		(end 209.59318 -128.354328)
		(width 0.127)
		(layer "In2.Cu")
		(net "GPU_3V3IO_RSVD0_FFU_ISO")
	)
	(segment
		(start 209.59318 -121.83618)
		(end 208.8134 -121.0564)
		(width 0.127)
		(layer "In2.Cu")
		(net "GPU_3V3IO_RSVD0_FFU_ISO")
	)
	(segment
		(start 221.02318 -329.143868)
		(end 221.02318 -218.803728)
		(width 0.127)
		(layer "In2.Cu")
		(net "GPU_3V3IO_RSVD0_FFU_ISO")
	)
	(segment
		(start 221.87154 -148.011388)
		(end 210.02498 -136.164828)
		(width 0.127)
		(layer "In2.Cu")
		(net "GPU_3V3IO_RSVD0_FFU_ISO")
	)
	(segment
		(start 223.65716 -216.169748)
		(end 223.65716 -190.840868)
		(width 0.127)
		(layer "In2.Cu")
		(net "GPU_3V3IO_RSVD0_FFU_ISO")
	)
	(segment
		(start 208.8134 -121.0564)
		(end 208.8134 -117.451124)
		(width 0.127)
		(layer "In2.Cu")
		(net "GPU_3V3IO_RSVD0_FFU_ISO")
	)
	(segment
		(start 221.87154 -189.055248)
		(end 221.87154 -148.011388)
		(width 0.127)
		(layer "In2.Cu")
		(net "GPU_3V3IO_RSVD0_FFU_ISO")
	)
	(segment
		(start 210.02498 -136.164828)
		(end 210.02498 -128.786128)
		(width 0.127)
		(layer "In2.Cu")
		(net "GPU_3V3IO_RSVD0_FFU_ISO")
	)
	(segment
		(start 208.8134 -117.451124)
		(end 206.897224 -115.534948)
		(width 0.127)
		(layer "In2.Cu")
		(net "GPU_3V3IO_RSVD0_FFU_ISO")
	)
	(segment
		(start 223.65716 -190.840868)
		(end 221.87154 -189.055248)
		(width 0.127)
		(layer "In2.Cu")
		(net "GPU_3V3IO_RSVD0_FFU_ISO")
	)
	(segment
		(start 211.8741 -338.292948)
		(end 221.02318 -329.143868)
		(width 0.127)
		(layer "In2.Cu")
		(net "GPU_3V3IO_RSVD0_FFU_ISO")
	)
	(segment
		(start 221.02318 -218.803728)
		(end 223.65716 -216.169748)
		(width 0.127)
		(layer "In2.Cu")
		(net "GPU_3V3IO_RSVD0_FFU_ISO")
	)
	(segment
		(start 211.35086 -338.292948)
		(end 211.8741 -338.292948)
		(width 0.127)
		(layer "In2.Cu")
		(net "GPU_3V3IO_RSVD0_FFU_ISO")
	)
	(segment
		(start 206.897224 -115.534948)
		(end 205.95844 -115.534948)
		(width 0.127)
		(layer "In2.Cu")
		(net "GPU_3V3IO_RSVD0_FFU_ISO")
	)
	(segment
		(start 302.48733 -417.29914)
		(end 303.12868 -417.29914)
		(width 0.12954)
		(layer "F.Cu")
		(net "GPU_3V3IO_RSVD0_FFU")
	)
	(segment
		(start 303.2252 -422.663366)
		(end 303.2506 -422.688766)
		(width 0.12954)
		(layer "F.Cu")
		(net "GPU_3V3IO_RSVD0_FFU")
	)
	(segment
		(start 302.895 -419.5064)
		(end 302.339502 -418.950902)
		(width 0.12954)
		(layer "F.Cu")
		(net "GPU_3V3IO_RSVD0_FFU")
	)
	(segment
		(start 303.2252 -422.645078)
		(end 303.2252 -422.663366)
		(width 0.12954)
		(layer "F.Cu")
		(net "GPU_3V3IO_RSVD0_FFU")
	)
	(segment
		(start 302.895 -419.5064)
		(end 302.36033 -420.04107)
		(width 0.12954)
		(layer "F.Cu")
		(net "GPU_3V3IO_RSVD0_FFU")
	)
	(segment
		(start 302.339502 -417.446968)
		(end 302.48733 -417.29914)
		(width 0.12954)
		(layer "F.Cu")
		(net "GPU_3V3IO_RSVD0_FFU")
	)
	(segment
		(start 303.2506 -422.688766)
		(end 303.2506 -423.13479)
		(width 0.12954)
		(layer "F.Cu")
		(net "GPU_3V3IO_RSVD0_FFU")
	)
	(segment
		(start 302.895 -421.894)
		(end 302.895 -422.314878)
		(width 0.12954)
		(layer "F.Cu")
		(net "GPU_3V3IO_RSVD0_FFU")
	)
	(segment
		(start 302.339502 -418.950902)
		(end 302.339502 -417.446968)
		(width 0.12954)
		(layer "F.Cu")
		(net "GPU_3V3IO_RSVD0_FFU")
	)
	(segment
		(start 302.895 -422.314878)
		(end 303.2252 -422.645078)
		(width 0.12954)
		(layer "F.Cu")
		(net "GPU_3V3IO_RSVD0_FFU")
	)
	(segment
		(start 302.36033 -420.04107)
		(end 302.36033 -421.35933)
		(width 0.12954)
		(layer "F.Cu")
		(net "GPU_3V3IO_RSVD0_FFU")
	)
	(segment
		(start 302.36033 -421.35933)
		(end 302.895 -421.894)
		(width 0.12954)
		(layer "F.Cu")
		(net "GPU_3V3IO_RSVD0_FFU")
	)
	(via
		(at 302.48733 -417.29914)
		(size 0.508)
		(drill 0.254)
		(layers "F.Cu" "B.Cu")
		(net "GPU_3V3IO_RSVD0_FFU")
	)
	(segment
		(start 173.72584 -396.51686)
		(end 173.16704 -395.95806)
		(width 0.12954)
		(layer "B.Cu")
		(net "GPU_3V3IO_RSVD0_FFU")
	)
	(segment
		(start 282.591002 -392.034522)
		(end 282.591002 -395.1224)
		(width 0.12954)
		(layer "B.Cu")
		(net "GPU_3V3IO_RSVD0_FFU")
	)
	(segment
		(start 263.30656 -377.26874)
		(end 269.76578 -383.72796)
		(width 0.12954)
		(layer "B.Cu")
		(net "GPU_3V3IO_RSVD0_FFU")
	)
	(segment
		(start 269.76578 -387.10616)
		(end 270.3703 -387.71068)
		(width 0.12954)
		(layer "B.Cu")
		(net "GPU_3V3IO_RSVD0_FFU")
	)
	(segment
		(start 292.862 -421.3733)
		(end 294.02278 -422.53408)
		(width 0.12954)
		(layer "B.Cu")
		(net "GPU_3V3IO_RSVD0_FFU")
	)
	(segment
		(start 282.591002 -395.1224)
		(end 283.7688 -396.300198)
		(width 0.12954)
		(layer "B.Cu")
		(net "GPU_3V3IO_RSVD0_FFU")
	)
	(segment
		(start 300.91888 -422.53408)
		(end 302.17364 -421.27932)
		(width 0.12954)
		(layer "B.Cu")
		(net "GPU_3V3IO_RSVD0_FFU")
	)
	(segment
		(start 283.7688 -408.575002)
		(end 282.768802 -409.575)
		(width 0.12954)
		(layer "B.Cu")
		(net "GPU_3V3IO_RSVD0_FFU")
	)
	(segment
		(start 283.4132 -411.0863)
		(end 287.15208 -411.0863)
		(width 0.12954)
		(layer "B.Cu")
		(net "GPU_3V3IO_RSVD0_FFU")
	)
	(segment
		(start 288.30524 -413.51708)
		(end 292.862 -418.07384)
		(width 0.12954)
		(layer "B.Cu")
		(net "GPU_3V3IO_RSVD0_FFU")
	)
	(segment
		(start 282.768802 -409.575)
		(end 282.768802 -410.441902)
		(width 0.12954)
		(layer "B.Cu")
		(net "GPU_3V3IO_RSVD0_FFU")
	)
	(segment
		(start 162.55746 -422.08704)
		(end 166.9161 -426.44568)
		(width 0.12954)
		(layer "B.Cu")
		(net "GPU_3V3IO_RSVD0_FFU")
	)
	(segment
		(start 151.00808 -422.08704)
		(end 162.55746 -422.08704)
		(width 0.12954)
		(layer "B.Cu")
		(net "GPU_3V3IO_RSVD0_FFU")
	)
	(segment
		(start 148.75002 -424.689778)
		(end 148.75002 -424.3451)
		(width 0.12954)
		(layer "B.Cu")
		(net "GPU_3V3IO_RSVD0_FFU")
	)
	(segment
		(start 172.74032 -424.66768)
		(end 172.74032 -412.293308)
		(width 0.12954)
		(layer "B.Cu")
		(net "GPU_3V3IO_RSVD0_FFU")
	)
	(segment
		(start 173.16704 -393.970256)
		(end 173.287436 -393.84986)
		(width 0.12954)
		(layer "B.Cu")
		(net "GPU_3V3IO_RSVD0_FFU")
	)
	(segment
		(start 278.26716 -387.71068)
		(end 282.591002 -392.034522)
		(width 0.12954)
		(layer "B.Cu")
		(net "GPU_3V3IO_RSVD0_FFU")
	)
	(segment
		(start 270.3703 -387.71068)
		(end 278.26716 -387.71068)
		(width 0.12954)
		(layer "B.Cu")
		(net "GPU_3V3IO_RSVD0_FFU")
	)
	(segment
		(start 302.17364 -417.61283)
		(end 302.48733 -417.29914)
		(width 0.12954)
		(layer "B.Cu")
		(net "GPU_3V3IO_RSVD0_FFU")
	)
	(segment
		(start 292.862 -418.07384)
		(end 292.862 -421.3733)
		(width 0.12954)
		(layer "B.Cu")
		(net "GPU_3V3IO_RSVD0_FFU")
	)
	(segment
		(start 174.128938 -393.008358)
		(end 189.868556 -377.26874)
		(width 0.12954)
		(layer "B.Cu")
		(net "GPU_3V3IO_RSVD0_FFU")
	)
	(segment
		(start 302.17364 -421.27932)
		(end 302.17364 -417.61283)
		(width 0.12954)
		(layer "B.Cu")
		(net "GPU_3V3IO_RSVD0_FFU")
	)
	(segment
		(start 174.128938 -393.512802)
		(end 174.128938 -393.008358)
		(width 0.12954)
		(layer "B.Cu")
		(net "GPU_3V3IO_RSVD0_FFU")
	)
	(segment
		(start 288.30524 -412.23946)
		(end 288.30524 -413.51708)
		(width 0.12954)
		(layer "B.Cu")
		(net "GPU_3V3IO_RSVD0_FFU")
	)
	(segment
		(start 172.74032 -412.293308)
		(end 173.72584 -411.307788)
		(width 0.12954)
		(layer "B.Cu")
		(net "GPU_3V3IO_RSVD0_FFU")
	)
	(segment
		(start 166.9161 -426.44568)
		(end 170.96232 -426.44568)
		(width 0.12954)
		(layer "B.Cu")
		(net "GPU_3V3IO_RSVD0_FFU")
	)
	(segment
		(start 148.75002 -424.3451)
		(end 151.00808 -422.08704)
		(width 0.12954)
		(layer "B.Cu")
		(net "GPU_3V3IO_RSVD0_FFU")
	)
	(segment
		(start 189.868556 -377.26874)
		(end 263.30656 -377.26874)
		(width 0.12954)
		(layer "B.Cu")
		(net "GPU_3V3IO_RSVD0_FFU")
	)
	(segment
		(start 294.02278 -422.53408)
		(end 300.91888 -422.53408)
		(width 0.12954)
		(layer "B.Cu")
		(net "GPU_3V3IO_RSVD0_FFU")
	)
	(segment
		(start 173.72584 -411.307788)
		(end 173.72584 -396.51686)
		(width 0.12954)
		(layer "B.Cu")
		(net "GPU_3V3IO_RSVD0_FFU")
	)
	(segment
		(start 170.96232 -426.44568)
		(end 172.74032 -424.66768)
		(width 0.12954)
		(layer "B.Cu")
		(net "GPU_3V3IO_RSVD0_FFU")
	)
	(segment
		(start 173.16704 -395.95806)
		(end 173.16704 -393.970256)
		(width 0.12954)
		(layer "B.Cu")
		(net "GPU_3V3IO_RSVD0_FFU")
	)
	(segment
		(start 283.7688 -396.300198)
		(end 283.7688 -408.575002)
		(width 0.12954)
		(layer "B.Cu")
		(net "GPU_3V3IO_RSVD0_FFU")
	)
	(segment
		(start 173.287436 -393.84986)
		(end 173.79188 -393.84986)
		(width 0.12954)
		(layer "B.Cu")
		(net "GPU_3V3IO_RSVD0_FFU")
	)
	(segment
		(start 173.79188 -393.84986)
		(end 174.128938 -393.512802)
		(width 0.12954)
		(layer "B.Cu")
		(net "GPU_3V3IO_RSVD0_FFU")
	)
	(segment
		(start 287.15208 -411.0863)
		(end 288.30524 -412.23946)
		(width 0.12954)
		(layer "B.Cu")
		(net "GPU_3V3IO_RSVD0_FFU")
	)
	(segment
		(start 269.76578 -383.72796)
		(end 269.76578 -387.10616)
		(width 0.12954)
		(layer "B.Cu")
		(net "GPU_3V3IO_RSVD0_FFU")
	)
	(segment
		(start 282.768802 -410.441902)
		(end 283.4132 -411.0863)
		(width 0.12954)
		(layer "B.Cu")
		(net "GPU_3V3IO_RSVD0_FFU")
	)
	(segment
		(start 177.75428 -122.011948)
		(end 178.00828 -122.265948)
		(width 0.12954)
		(layer "F.Cu")
		(net "FM_THERMAL_ALERT_R_N")
	)
	(segment
		(start 177.75428 -121.529348)
		(end 177.75428 -122.011948)
		(width 0.12954)
		(layer "F.Cu")
		(net "FM_THERMAL_ALERT_R_N")
	)
	(segment
		(start 177.62728 -123.967748)
		(end 177.62728 -125.110748)
		(width 0.12954)
		(layer "F.Cu")
		(net "FM_THERMAL_ALERT_R_N")
	)
	(segment
		(start 178.00828 -122.265948)
		(end 178.00828 -123.586748)
		(width 0.12954)
		(layer "F.Cu")
		(net "FM_THERMAL_ALERT_R_N")
	)
	(segment
		(start 178.1556 -121.128028)
		(end 177.75428 -121.529348)
		(width 0.12954)
		(layer "F.Cu")
		(net "FM_THERMAL_ALERT_R_N")
	)
	(segment
		(start 178.00828 -125.491748)
		(end 178.00828 -131.528058)
		(width 0.12954)
		(layer "F.Cu")
		(net "FM_THERMAL_ALERT_R_N")
	)
	(segment
		(start 178.00828 -123.586748)
		(end 177.62728 -123.967748)
		(width 0.12954)
		(layer "F.Cu")
		(net "FM_THERMAL_ALERT_R_N")
	)
	(segment
		(start 178.1556 -120.975374)
		(end 178.1556 -121.128028)
		(width 0.12954)
		(layer "F.Cu")
		(net "FM_THERMAL_ALERT_R_N")
	)
	(segment
		(start 178.00828 -131.528058)
		(end 177.590196 -131.946142)
		(width 0.12954)
		(layer "F.Cu")
		(net "FM_THERMAL_ALERT_R_N")
	)
	(segment
		(start 177.62728 -125.110748)
		(end 178.00828 -125.491748)
		(width 0.12954)
		(layer "F.Cu")
		(net "FM_THERMAL_ALERT_R_N")
	)
	(segment
		(start 176.58588 -132.950458)
		(end 176.58588 -133.295898)
		(width 0.12954)
		(layer "F.Cu")
		(net "FM_THERMAL_ALERT_R_N")
	)
	(segment
		(start 177.590196 -131.946142)
		(end 176.58588 -132.950458)
		(width 0.12954)
		(layer "F.Cu")
		(net "FM_THERMAL_ALERT_R_N")
	)
	(via
		(at 177.590196 -131.946142)
		(size 0.762)
		(drill 0.381)
		(layers "F.Cu" "B.Cu")
		(net "FM_THERMAL_ALERT_R_N")
	)
	(segment
		(start 224.16008 -82.729324)
		(end 224.16008 -83.200748)
		(width 0.12954)
		(layer "F.Cu")
		(net "FM_THERMAL_ALERT_N")
	)
	(segment
		(start 186.71032 -422.7449)
		(end 186.71032 -422.39692)
		(width 0.12954)
		(layer "F.Cu")
		(net "FM_THERMAL_ALERT_N")
	)
	(segment
		(start 201.280014 -124.368814)
		(end 209.260186 -124.368814)
		(width 0.12954)
		(layer "F.Cu")
		(net "FM_THERMAL_ALERT_N")
	)
	(segment
		(start 259.5499 -58.032396)
		(end 257.508756 -60.07354)
		(width 0.12954)
		(layer "F.Cu")
		(net "FM_THERMAL_ALERT_N")
	)
	(segment
		(start 365.390938 -417.55314)
		(end 366.673638 -417.55314)
		(width 0.12954)
		(layer "F.Cu")
		(net "FM_THERMAL_ALERT_N")
	)
	(segment
		(start 367.920778 -417.5506)
		(end 367.918238 -417.54806)
		(width 0.12954)
		(layer "F.Cu")
		(net "FM_THERMAL_ALERT_N")
	)
	(segment
		(start 366.417098 -421.447468)
		(end 366.417098 -422.3766)
		(width 0.12954)
		(layer "F.Cu")
		(net "FM_THERMAL_ALERT_N")
	)
	(segment
		(start 366.417098 -422.3766)
		(end 366.054132 -422.739566)
		(width 0.12954)
		(layer "F.Cu")
		(net "FM_THERMAL_ALERT_N")
	)
	(segment
		(start 106.648758 -424.978068)
		(end 106.42981 -424.978068)
		(width 0.12954)
		(layer "F.Cu")
		(net "FM_THERMAL_ALERT_N")
	)
	(segment
		(start 275.31949 -39.115492)
		(end 271.616932 -42.81805)
		(width 0.12954)
		(layer "F.Cu")
		(net "FM_THERMAL_ALERT_N")
	)
	(segment
		(start 367.920778 -419.83025)
		(end 367.242852 -420.508176)
		(width 0.12954)
		(layer "F.Cu")
		(net "FM_THERMAL_ALERT_N")
	)
	(segment
		(start 226.93884 -117.884448)
		(end 228.60508 -119.550688)
		(width 0.12954)
		(layer "F.Cu")
		(net "FM_THERMAL_ALERT_N")
	)
	(segment
		(start 284.842712 -14.36243)
		(end 283.64688 -15.558262)
		(width 0.12954)
		(layer "F.Cu")
		(net "FM_THERMAL_ALERT_N")
	)
	(segment
		(start 257.508756 -60.07354)
		(end 241.657124 -60.07354)
		(width 0.12954)
		(layer "F.Cu")
		(net "FM_THERMAL_ALERT_N")
	)
	(segment
		(start 283.64688 -21.02739)
		(end 275.31949 -29.35478)
		(width 0.12954)
		(layer "F.Cu")
		(net "FM_THERMAL_ALERT_N")
	)
	(segment
		(start 197.92188 -134.153148)
		(end 197.92188 -127.726948)
		(width 0.12954)
		(layer "F.Cu")
		(net "FM_THERMAL_ALERT_N")
	)
	(segment
		(start 209.260186 -124.368814)
		(end 210.0072 -123.6218)
		(width 0.12954)
		(layer "F.Cu")
		(net "FM_THERMAL_ALERT_N")
	)
	(segment
		(start 181.89702 -424.26636)
		(end 182.2704 -424.63974)
		(width 0.12954)
		(layer "F.Cu")
		(net "FM_THERMAL_ALERT_N")
	)
	(segment
		(start 181.17312 -414.69056)
		(end 181.89702 -415.41446)
		(width 0.12954)
		(layer "F.Cu")
		(net "FM_THERMAL_ALERT_N")
	)
	(segment
		(start 265.114278 -42.81805)
		(end 260.717284 -47.215044)
		(width 0.12954)
		(layer "F.Cu")
		(net "FM_THERMAL_ALERT_N")
	)
	(segment
		(start 367.242852 -420.508176)
		(end 366.413542 -420.508176)
		(width 0.12954)
		(layer "F.Cu")
		(net "FM_THERMAL_ALERT_N")
	)
	(segment
		(start 367.920778 -417.5506)
		(end 367.920778 -419.83025)
		(width 0.12954)
		(layer "F.Cu")
		(net "FM_THERMAL_ALERT_N")
	)
	(segment
		(start 104.903778 -426.5041)
		(end 105.61193 -425.795948)
		(width 0.12954)
		(layer "F.Cu")
		(net "FM_THERMAL_ALERT_N")
	)
	(segment
		(start 184.81548 -424.63974)
		(end 186.71032 -422.7449)
		(width 0.12954)
		(layer "F.Cu")
		(net "FM_THERMAL_ALERT_N")
	)
	(segment
		(start 176.57572 -410.88818)
		(end 180.3781 -414.69056)
		(width 0.12954)
		(layer "F.Cu")
		(net "FM_THERMAL_ALERT_N")
	)
	(segment
		(start 106.42981 -424.978068)
		(end 105.61193 -425.795948)
		(width 0.12954)
		(layer "F.Cu")
		(net "FM_THERMAL_ALERT_N")
	)
	(segment
		(start 172.407834 -402.83003)
		(end 174.215044 -404.63724)
		(width 0.12954)
		(layer "F.Cu")
		(net "FM_THERMAL_ALERT_N")
	)
	(segment
		(start 367.918238 -417.54806)
		(end 366.678718 -417.54806)
		(width 0.12954)
		(layer "F.Cu")
		(net "FM_THERMAL_ALERT_N")
	)
	(segment
		(start 174.215044 -404.63724)
		(end 175.7045 -404.63724)
		(width 0.12954)
		(layer "F.Cu")
		(net "FM_THERMAL_ALERT_N")
	)
	(segment
		(start 259.5499 -50.033682)
		(end 259.5499 -58.032396)
		(width 0.12954)
		(layer "F.Cu")
		(net "FM_THERMAL_ALERT_N")
	)
	(segment
		(start 104.903778 -426.787818)
		(end 104.903778 -426.5041)
		(width 0.12954)
		(layer "F.Cu")
		(net "FM_THERMAL_ALERT_N")
	)
	(segment
		(start 175.7045 -404.63724)
		(end 176.57572 -405.50846)
		(width 0.12954)
		(layer "F.Cu")
		(net "FM_THERMAL_ALERT_N")
	)
	(segment
		(start 366.417098 -420.511732)
		(end 366.417098 -421.447468)
		(width 0.12954)
		(layer "F.Cu")
		(net "FM_THERMAL_ALERT_N")
	)
	(segment
		(start 181.89702 -422.22674)
		(end 181.89702 -424.26636)
		(width 0.12954)
		(layer "F.Cu")
		(net "FM_THERMAL_ALERT_N")
	)
	(segment
		(start 181.89702 -417.65474)
		(end 181.3941 -418.15766)
		(width 0.12954)
		(layer "F.Cu")
		(net "FM_THERMAL_ALERT_N")
	)
	(segment
		(start 366.673638 -417.55314)
		(end 366.678718 -417.54806)
		(width 0.12954)
		(layer "F.Cu")
		(net "FM_THERMAL_ALERT_N")
	)
	(segment
		(start 210.0072 -123.6218)
		(end 219.5322 -123.6218)
		(width 0.12954)
		(layer "F.Cu")
		(net "FM_THERMAL_ALERT_N")
	)
	(segment
		(start 283.64688 -15.558262)
		(end 283.64688 -21.02739)
		(width 0.12954)
		(layer "F.Cu")
		(net "FM_THERMAL_ALERT_N")
	)
	(segment
		(start 271.616932 -42.81805)
		(end 265.114278 -42.81805)
		(width 0.12954)
		(layer "F.Cu")
		(net "FM_THERMAL_ALERT_N")
	)
	(segment
		(start 107.01528 -424.611546)
		(end 106.648758 -424.978068)
		(width 0.12954)
		(layer "F.Cu")
		(net "FM_THERMAL_ALERT_N")
	)
	(segment
		(start 275.31949 -29.35478)
		(end 275.31949 -39.115492)
		(width 0.12954)
		(layer "F.Cu")
		(net "FM_THERMAL_ALERT_N")
	)
	(segment
		(start 260.717284 -47.215044)
		(end 259.5499 -50.033682)
		(width 0.12954)
		(layer "F.Cu")
		(net "FM_THERMAL_ALERT_N")
	)
	(segment
		(start 241.657124 -60.07354)
		(end 224.43948 -77.291184)
		(width 0.12954)
		(layer "F.Cu")
		(net "FM_THERMAL_ALERT_N")
	)
	(segment
		(start 182.2704 -424.63974)
		(end 184.81548 -424.63974)
		(width 0.12954)
		(layer "F.Cu")
		(net "FM_THERMAL_ALERT_N")
	)
	(segment
		(start 366.054132 -422.739566)
		(end 366.054132 -423.03573)
		(width 0.12954)
		(layer "F.Cu")
		(net "FM_THERMAL_ALERT_N")
	)
	(segment
		(start 366.413542 -420.508176)
		(end 366.417098 -420.511732)
		(width 0.12954)
		(layer "F.Cu")
		(net "FM_THERMAL_ALERT_N")
	)
	(segment
		(start 225.269552 -117.884448)
		(end 226.93884 -117.884448)
		(width 0.12954)
		(layer "F.Cu")
		(net "FM_THERMAL_ALERT_N")
	)
	(segment
		(start 181.3941 -421.72382)
		(end 181.89702 -422.22674)
		(width 0.12954)
		(layer "F.Cu")
		(net "FM_THERMAL_ALERT_N")
	)
	(segment
		(start 176.57572 -405.50846)
		(end 176.57572 -410.88818)
		(width 0.12954)
		(layer "F.Cu")
		(net "FM_THERMAL_ALERT_N")
	)
	(segment
		(start 181.89702 -415.41446)
		(end 181.89702 -417.65474)
		(width 0.12954)
		(layer "F.Cu")
		(net "FM_THERMAL_ALERT_N")
	)
	(segment
		(start 197.36308 -134.711948)
		(end 197.92188 -134.153148)
		(width 0.12954)
		(layer "F.Cu")
		(net "FM_THERMAL_ALERT_N")
	)
	(segment
		(start 180.3781 -414.69056)
		(end 181.17312 -414.69056)
		(width 0.12954)
		(layer "F.Cu")
		(net "FM_THERMAL_ALERT_N")
	)
	(segment
		(start 219.5322 -123.6218)
		(end 225.269552 -117.884448)
		(width 0.12954)
		(layer "F.Cu")
		(net "FM_THERMAL_ALERT_N")
	)
	(segment
		(start 224.43948 -77.291184)
		(end 224.43948 -82.449924)
		(width 0.12954)
		(layer "F.Cu")
		(net "FM_THERMAL_ALERT_N")
	)
	(segment
		(start 181.3941 -418.15766)
		(end 181.3941 -421.72382)
		(width 0.12954)
		(layer "F.Cu")
		(net "FM_THERMAL_ALERT_N")
	)
	(segment
		(start 224.43948 -82.449924)
		(end 224.16008 -82.729324)
		(width 0.12954)
		(layer "F.Cu")
		(net "FM_THERMAL_ALERT_N")
	)
	(segment
		(start 176.58588 -134.095998)
		(end 176.58588 -134.788148)
		(width 0.12954)
		(layer "F.Cu")
		(net "FM_THERMAL_ALERT_N")
	)
	(segment
		(start 197.92188 -127.726948)
		(end 201.280014 -124.368814)
		(width 0.12954)
		(layer "F.Cu")
		(net "FM_THERMAL_ALERT_N")
	)
	(via
		(at 197.36308 -134.711948)
		(size 0.508)
		(drill 0.254)
		(layers "F.Cu" "B.Cu")
		(net "FM_THERMAL_ALERT_N")
	)
	(via
		(at 153.97988 -131.511548)
		(size 0.508)
		(drill 0.254)
		(layers "F.Cu" "B.Cu")
		(net "FM_THERMAL_ALERT_N")
	)
	(via
		(at 228.60508 -119.550688)
		(size 0.508)
		(drill 0.254)
		(layers "F.Cu" "B.Cu")
		(net "FM_THERMAL_ALERT_N")
	)
	(via
		(at 300.59376 -404.27656)
		(size 0.508)
		(drill 0.254)
		(layers "F.Cu" "B.Cu")
		(net "FM_THERMAL_ALERT_N")
	)
	(via
		(at 176.58588 -134.788148)
		(size 0.508)
		(drill 0.254)
		(layers "F.Cu" "B.Cu")
		(net "FM_THERMAL_ALERT_N")
	)
	(via
		(at 172.407834 -402.83003)
		(size 0.508)
		(drill 0.254)
		(layers "F.Cu" "B.Cu")
		(net "FM_THERMAL_ALERT_N")
	)
	(via
		(at 9.77138 -174.147988)
		(size 0.508)
		(drill 0.254)
		(layers "F.Cu" "B.Cu")
		(net "FM_THERMAL_ALERT_N")
	)
	(via
		(at 47.592234 -111.948468)
		(size 0.508)
		(drill 0.254)
		(layers "F.Cu" "B.Cu")
		(net "FM_THERMAL_ALERT_N")
	)
	(via
		(at 186.71032 -422.39692)
		(size 0.508)
		(drill 0.254)
		(layers "F.Cu" "B.Cu")
		(net "FM_THERMAL_ALERT_N")
	)
	(via
		(at 366.417098 -421.447468)
		(size 0.508)
		(drill 0.254)
		(layers "F.Cu" "B.Cu")
		(net "FM_THERMAL_ALERT_N")
	)
	(via
		(at 351.74936 -397.67256)
		(size 0.508)
		(drill 0.254)
		(layers "F.Cu" "B.Cu")
		(net "FM_THERMAL_ALERT_N")
	)
	(via
		(at 151.26208 -111.699548)
		(size 0.508)
		(drill 0.254)
		(layers "F.Cu" "B.Cu")
		(net "FM_THERMAL_ALERT_N")
	)
	(via
		(at 107.01528 -424.611546)
		(size 0.508)
		(drill 0.254)
		(layers "F.Cu" "B.Cu")
		(net "FM_THERMAL_ALERT_N")
	)
	(via
		(at 224.16008 -83.200748)
		(size 0.508)
		(drill 0.254)
		(layers "F.Cu" "B.Cu")
		(net "FM_THERMAL_ALERT_N")
	)
	(segment
		(start 153.97988 -131.511548)
		(end 153.59888 -131.511548)
		(width 0.127)
		(layer "In2.Cu")
		(net "FM_THERMAL_ALERT_N")
	)
	(segment
		(start 154.31008 -123.154948)
		(end 153.70048 -122.545348)
		(width 0.127)
		(layer "In2.Cu")
		(net "FM_THERMAL_ALERT_N")
	)
	(segment
		(start 228.60508 -119.550688)
		(end 228.60508 -118.95582)
		(width 0.127)
		(layer "In2.Cu")
		(net "FM_THERMAL_ALERT_N")
	)
	(segment
		(start 153.37028 -129.250948)
		(end 154.31008 -128.311148)
		(width 0.127)
		(layer "In2.Cu")
		(net "FM_THERMAL_ALERT_N")
	)
	(segment
		(start 153.37028 -131.282948)
		(end 153.37028 -129.250948)
		(width 0.127)
		(layer "In2.Cu")
		(net "FM_THERMAL_ALERT_N")
	)
	(segment
		(start 150.42388 -116.601748)
		(end 151.26208 -115.763548)
		(width 0.127)
		(layer "In2.Cu")
		(net "FM_THERMAL_ALERT_N")
	)
	(segment
		(start 153.59888 -131.511548)
		(end 153.37028 -131.282948)
		(width 0.127)
		(layer "In2.Cu")
		(net "FM_THERMAL_ALERT_N")
	)
	(segment
		(start 153.70048 -120.284748)
		(end 150.42388 -117.008148)
		(width 0.127)
		(layer "In2.Cu")
		(net "FM_THERMAL_ALERT_N")
	)
	(segment
		(start 151.26208 -115.763548)
		(end 151.26208 -111.699548)
		(width 0.127)
		(layer "In2.Cu")
		(net "FM_THERMAL_ALERT_N")
	)
	(segment
		(start 228.60508 -118.95582)
		(end 229.58044 -117.98046)
		(width 0.127)
		(layer "In2.Cu")
		(net "FM_THERMAL_ALERT_N")
	)
	(segment
		(start 154.31008 -128.311148)
		(end 154.31008 -123.154948)
		(width 0.127)
		(layer "In2.Cu")
		(net "FM_THERMAL_ALERT_N")
	)
	(segment
		(start 150.42388 -117.008148)
		(end 150.42388 -116.601748)
		(width 0.127)
		(layer "In2.Cu")
		(net "FM_THERMAL_ALERT_N")
	)
	(segment
		(start 229.58044 -93.706188)
		(end 224.16008 -88.285828)
		(width 0.127)
		(layer "In2.Cu")
		(net "FM_THERMAL_ALERT_N")
	)
	(segment
		(start 229.58044 -117.98046)
		(end 229.58044 -93.706188)
		(width 0.127)
		(layer "In2.Cu")
		(net "FM_THERMAL_ALERT_N")
	)
	(segment
		(start 224.16008 -88.285828)
		(end 224.16008 -83.200748)
		(width 0.127)
		(layer "In2.Cu")
		(net "FM_THERMAL_ALERT_N")
	)
	(segment
		(start 153.70048 -122.545348)
		(end 153.70048 -120.284748)
		(width 0.127)
		(layer "In2.Cu")
		(net "FM_THERMAL_ALERT_N")
	)
	(segment
		(start 30.91688 -366.691418)
		(end 58.22061 -393.995148)
		(width 0.127)
		(layer "In6.Cu")
		(net "FM_THERMAL_ALERT_N")
	)
	(segment
		(start 8.66648 -320.970148)
		(end 13.39088 -325.694548)
		(width 0.127)
		(layer "In6.Cu")
		(net "FM_THERMAL_ALERT_N")
	)
	(segment
		(start 8.66648 -257.520948)
		(end 8.66648 -320.970148)
		(width 0.127)
		(layer "In6.Cu")
		(net "FM_THERMAL_ALERT_N")
	)
	(segment
		(start 305.497484 -398.28724)
		(end 306.112164 -397.67256)
		(width 0.127)
		(layer "In6.Cu")
		(net "FM_THERMAL_ALERT_N")
	)
	(segment
		(start 5.195316 -191.735202)
		(end 5.855716 -192.395602)
		(width 0.127)
		(layer "In6.Cu")
		(net "FM_THERMAL_ALERT_N")
	)
	(segment
		(start 5.854446 -194.002406)
		(end 5.854446 -194.07124)
		(width 0.127)
		(layer "In6.Cu")
		(net "FM_THERMAL_ALERT_N")
	)
	(segment
		(start 306.112164 -397.67256)
		(end 351.74936 -397.67256)
		(width 0.127)
		(layer "In6.Cu")
		(net "FM_THERMAL_ALERT_N")
	)
	(segment
		(start 107.01528 -413.438848)
		(end 107.01528 -424.611546)
		(width 0.127)
		(layer "In6.Cu")
		(net "FM_THERMAL_ALERT_N")
	)
	(segment
		(start 101.000306 -392.775948)
		(end 108.428536 -392.775948)
		(width 0.127)
		(layer "In6.Cu")
		(net "FM_THERMAL_ALERT_N")
	)
	(segment
		(start 58.22061 -393.995148)
		(end 99.781106 -393.995148)
		(width 0.127)
		(layer "In6.Cu")
		(net "FM_THERMAL_ALERT_N")
	)
	(segment
		(start 113.9698 -411.190948)
		(end 109.26318 -411.190948)
		(width 0.127)
		(layer "In6.Cu")
		(net "FM_THERMAL_ALERT_N")
	)
	(segment
		(start 13.39088 -325.694548)
		(end 26.575004 -325.694548)
		(width 0.127)
		(layer "In6.Cu")
		(net "FM_THERMAL_ALERT_N")
	)
	(segment
		(start 116.205 -408.955748)
		(end 113.9698 -411.190948)
		(width 0.127)
		(layer "In6.Cu")
		(net "FM_THERMAL_ALERT_N")
	)
	(segment
		(start 115.2906 -401.9042)
		(end 114.0968 -403.098)
		(width 0.127)
		(layer "In6.Cu")
		(net "FM_THERMAL_ALERT_N")
	)
	(segment
		(start 7.593584 -174.598584)
		(end 5.195316 -176.996852)
		(width 0.127)
		(layer "In6.Cu")
		(net "FM_THERMAL_ALERT_N")
	)
	(segment
		(start 114.0968 -406.4508)
		(end 116.205 -408.559)
		(width 0.127)
		(layer "In6.Cu")
		(net "FM_THERMAL_ALERT_N")
	)
	(segment
		(start 115.616736 -396.662148)
		(end 116.0526 -396.662148)
		(width 0.127)
		(layer "In6.Cu")
		(net "FM_THERMAL_ALERT_N")
	)
	(segment
		(start 300.59376 -404.27656)
		(end 300.11624 -403.79904)
		(width 0.127)
		(layer "In6.Cu")
		(net "FM_THERMAL_ALERT_N")
	)
	(segment
		(start 8.137144 -174.598584)
		(end 7.593584 -174.598584)
		(width 0.127)
		(layer "In6.Cu")
		(net "FM_THERMAL_ALERT_N")
	)
	(segment
		(start 32.66948 -337.176872)
		(end 30.91688 -338.929472)
		(width 0.127)
		(layer "In6.Cu")
		(net "FM_THERMAL_ALERT_N")
	)
	(segment
		(start 108.428536 -392.775948)
		(end 108.572046 -392.919458)
		(width 0.127)
		(layer "In6.Cu")
		(net "FM_THERMAL_ALERT_N")
	)
	(segment
		(start 300.11624 -403.79904)
		(end 300.11624 -398.599152)
		(width 0.127)
		(layer "In6.Cu")
		(net "FM_THERMAL_ALERT_N")
	)
	(segment
		(start 300.428152 -398.28724)
		(end 305.497484 -398.28724)
		(width 0.127)
		(layer "In6.Cu")
		(net "FM_THERMAL_ALERT_N")
	)
	(segment
		(start 5.855716 -192.395602)
		(end 5.855716 -194.001136)
		(width 0.127)
		(layer "In6.Cu")
		(net "FM_THERMAL_ALERT_N")
	)
	(segment
		(start 111.874046 -392.919458)
		(end 115.616736 -396.662148)
		(width 0.127)
		(layer "In6.Cu")
		(net "FM_THERMAL_ALERT_N")
	)
	(segment
		(start 116.1796 -396.789148)
		(end 116.1796 -400.281648)
		(width 0.127)
		(layer "In6.Cu")
		(net "FM_THERMAL_ALERT_N")
	)
	(segment
		(start 300.11624 -398.599152)
		(end 300.428152 -398.28724)
		(width 0.127)
		(layer "In6.Cu")
		(net "FM_THERMAL_ALERT_N")
	)
	(segment
		(start 8.58774 -174.147988)
		(end 8.137144 -174.598584)
		(width 0.127)
		(layer "In6.Cu")
		(net "FM_THERMAL_ALERT_N")
	)
	(segment
		(start 116.0526 -396.662148)
		(end 116.1796 -396.789148)
		(width 0.127)
		(layer "In6.Cu")
		(net "FM_THERMAL_ALERT_N")
	)
	(segment
		(start 26.575004 -325.694548)
		(end 32.66948 -331.789024)
		(width 0.127)
		(layer "In6.Cu")
		(net "FM_THERMAL_ALERT_N")
	)
	(segment
		(start 116.205 -408.559)
		(end 116.205 -408.955748)
		(width 0.127)
		(layer "In6.Cu")
		(net "FM_THERMAL_ALERT_N")
	)
	(segment
		(start 9.77138 -174.147988)
		(end 8.58774 -174.147988)
		(width 0.127)
		(layer "In6.Cu")
		(net "FM_THERMAL_ALERT_N")
	)
	(segment
		(start 108.572046 -392.919458)
		(end 111.874046 -392.919458)
		(width 0.127)
		(layer "In6.Cu")
		(net "FM_THERMAL_ALERT_N")
	)
	(segment
		(start 115.2906 -401.170648)
		(end 115.2906 -401.9042)
		(width 0.127)
		(layer "In6.Cu")
		(net "FM_THERMAL_ALERT_N")
	)
	(segment
		(start 114.0968 -403.098)
		(end 114.0968 -406.4508)
		(width 0.127)
		(layer "In6.Cu")
		(net "FM_THERMAL_ALERT_N")
	)
	(segment
		(start 32.66948 -331.789024)
		(end 32.66948 -337.176872)
		(width 0.127)
		(layer "In6.Cu")
		(net "FM_THERMAL_ALERT_N")
	)
	(segment
		(start 5.195316 -194.73037)
		(end 5.195316 -254.049784)
		(width 0.127)
		(layer "In6.Cu")
		(net "FM_THERMAL_ALERT_N")
	)
	(segment
		(start 5.195316 -254.049784)
		(end 8.66648 -257.520948)
		(width 0.127)
		(layer "In6.Cu")
		(net "FM_THERMAL_ALERT_N")
	)
	(segment
		(start 109.26318 -411.190948)
		(end 107.01528 -413.438848)
		(width 0.127)
		(layer "In6.Cu")
		(net "FM_THERMAL_ALERT_N")
	)
	(segment
		(start 5.195316 -176.996852)
		(end 5.195316 -191.735202)
		(width 0.127)
		(layer "In6.Cu")
		(net "FM_THERMAL_ALERT_N")
	)
	(segment
		(start 5.855716 -194.001136)
		(end 5.854446 -194.002406)
		(width 0.127)
		(layer "In6.Cu")
		(net "FM_THERMAL_ALERT_N")
	)
	(segment
		(start 5.854446 -194.07124)
		(end 5.195316 -194.73037)
		(width 0.127)
		(layer "In6.Cu")
		(net "FM_THERMAL_ALERT_N")
	)
	(segment
		(start 116.1796 -400.281648)
		(end 115.2906 -401.170648)
		(width 0.127)
		(layer "In6.Cu")
		(net "FM_THERMAL_ALERT_N")
	)
	(segment
		(start 30.91688 -338.929472)
		(end 30.91688 -366.691418)
		(width 0.127)
		(layer "In6.Cu")
		(net "FM_THERMAL_ALERT_N")
	)
	(segment
		(start 99.781106 -393.995148)
		(end 101.000306 -392.775948)
		(width 0.127)
		(layer "In6.Cu")
		(net "FM_THERMAL_ALERT_N")
	)
	(segment
		(start 299.593 -411.0228)
		(end 299.593 -413.780732)
		(width 0.127)
		(layer "In11.Cu")
		(net "FM_THERMAL_ALERT_N")
	)
	(segment
		(start 298.57827 -426.97527)
		(end 296.36847 -429.18507)
		(width 0.127)
		(layer "In11.Cu")
		(net "FM_THERMAL_ALERT_N")
	)
	(segment
		(start 198.460106 -438.84088)
		(end 189.67196 -430.052734)
		(width 0.127)
		(layer "In11.Cu")
		(net "FM_THERMAL_ALERT_N")
	)
	(segment
		(start 186.81192 -422.29532)
		(end 186.71032 -422.39692)
		(width 0.127)
		(layer "In11.Cu")
		(net "FM_THERMAL_ALERT_N")
	)
	(segment
		(start 298.0436 -418.719)
		(end 299.1612 -419.8366)
		(width 0.127)
		(layer "In11.Cu")
		(net "FM_THERMAL_ALERT_N")
	)
	(segment
		(start 107.01528 -421.332914)
		(end 107.01528 -424.611546)
		(width 0.127)
		(layer "In11.Cu")
		(net "FM_THERMAL_ALERT_N")
	)
	(segment
		(start 115.52174 -412.99892)
		(end 115.52174 -415.486342)
		(width 0.127)
		(layer "In11.Cu")
		(net "FM_THERMAL_ALERT_N")
	)
	(segment
		(start 168.4782 -400.8628)
		(end 167.106092 -402.234908)
		(width 0.127)
		(layer "In11.Cu")
		(net "FM_THERMAL_ALERT_N")
	)
	(segment
		(start 300.971458 -404.654258)
		(end 301.371 -405.618696)
		(width 0.127)
		(layer "In11.Cu")
		(net "FM_THERMAL_ALERT_N")
	)
	(segment
		(start 298.0436 -415.330132)
		(end 298.0436 -418.719)
		(width 0.127)
		(layer "In11.Cu")
		(net "FM_THERMAL_ALERT_N")
	)
	(segment
		(start 277.11654 -435.153054)
		(end 273.428714 -438.84088)
		(width 0.127)
		(layer "In11.Cu")
		(net "FM_THERMAL_ALERT_N")
	)
	(segment
		(start 167.106092 -402.234908)
		(end 119.508016 -402.234908)
		(width 0.127)
		(layer "In11.Cu")
		(net "FM_THERMAL_ALERT_N")
	)
	(segment
		(start 279.457404 -429.18507)
		(end 277.11654 -431.525934)
		(width 0.127)
		(layer "In11.Cu")
		(net "FM_THERMAL_ALERT_N")
	)
	(segment
		(start 299.593 -413.780732)
		(end 298.0436 -415.330132)
		(width 0.127)
		(layer "In11.Cu")
		(net "FM_THERMAL_ALERT_N")
	)
	(segment
		(start 301.371 -409.2448)
		(end 299.593 -411.0228)
		(width 0.127)
		(layer "In11.Cu")
		(net "FM_THERMAL_ALERT_N")
	)
	(segment
		(start 296.36847 -429.18507)
		(end 279.457404 -429.18507)
		(width 0.127)
		(layer "In11.Cu")
		(net "FM_THERMAL_ALERT_N")
	)
	(segment
		(start 170.440604 -400.8628)
		(end 168.4782 -400.8628)
		(width 0.127)
		(layer "In11.Cu")
		(net "FM_THERMAL_ALERT_N")
	)
	(segment
		(start 189.67196 -424.63466)
		(end 187.33262 -422.29532)
		(width 0.127)
		(layer "In11.Cu")
		(net "FM_THERMAL_ALERT_N")
	)
	(segment
		(start 187.33262 -422.29532)
		(end 186.81192 -422.29532)
		(width 0.127)
		(layer "In11.Cu")
		(net "FM_THERMAL_ALERT_N")
	)
	(segment
		(start 298.57827 -421.15613)
		(end 298.57827 -426.97527)
		(width 0.127)
		(layer "In11.Cu")
		(net "FM_THERMAL_ALERT_N")
	)
	(segment
		(start 113.02238 -420.136828)
		(end 112.71504 -420.444168)
		(width 0.127)
		(layer "In11.Cu")
		(net "FM_THERMAL_ALERT_N")
	)
	(segment
		(start 277.11654 -431.525934)
		(end 277.11654 -435.153054)
		(width 0.127)
		(layer "In11.Cu")
		(net "FM_THERMAL_ALERT_N")
	)
	(segment
		(start 301.371 -405.618696)
		(end 301.371 -409.2448)
		(width 0.127)
		(layer "In11.Cu")
		(net "FM_THERMAL_ALERT_N")
	)
	(segment
		(start 273.428714 -438.84088)
		(end 198.460106 -438.84088)
		(width 0.127)
		(layer "In11.Cu")
		(net "FM_THERMAL_ALERT_N")
	)
	(segment
		(start 189.67196 -430.052734)
		(end 189.67196 -424.63466)
		(width 0.127)
		(layer "In11.Cu")
		(net "FM_THERMAL_ALERT_N")
	)
	(segment
		(start 117.68328 -410.83738)
		(end 115.52174 -412.99892)
		(width 0.127)
		(layer "In11.Cu")
		(net "FM_THERMAL_ALERT_N")
	)
	(segment
		(start 117.68328 -404.059644)
		(end 117.68328 -410.83738)
		(width 0.127)
		(layer "In11.Cu")
		(net "FM_THERMAL_ALERT_N")
	)
	(segment
		(start 113.02238 -417.985702)
		(end 113.02238 -420.136828)
		(width 0.127)
		(layer "In11.Cu")
		(net "FM_THERMAL_ALERT_N")
	)
	(segment
		(start 112.71504 -420.444168)
		(end 107.904026 -420.444168)
		(width 0.127)
		(layer "In11.Cu")
		(net "FM_THERMAL_ALERT_N")
	)
	(segment
		(start 300.59376 -404.27656)
		(end 300.971458 -404.654258)
		(width 0.127)
		(layer "In11.Cu")
		(net "FM_THERMAL_ALERT_N")
	)
	(segment
		(start 172.407834 -402.83003)
		(end 170.440604 -400.8628)
		(width 0.127)
		(layer "In11.Cu")
		(net "FM_THERMAL_ALERT_N")
	)
	(segment
		(start 299.1612 -420.5732)
		(end 298.57827 -421.15613)
		(width 0.127)
		(layer "In11.Cu")
		(net "FM_THERMAL_ALERT_N")
	)
	(segment
		(start 115.52174 -415.486342)
		(end 113.02238 -417.985702)
		(width 0.127)
		(layer "In11.Cu")
		(net "FM_THERMAL_ALERT_N")
	)
	(segment
		(start 119.508016 -402.234908)
		(end 117.68328 -404.059644)
		(width 0.127)
		(layer "In11.Cu")
		(net "FM_THERMAL_ALERT_N")
	)
	(segment
		(start 107.904026 -420.444168)
		(end 107.01528 -421.332914)
		(width 0.127)
		(layer "In11.Cu")
		(net "FM_THERMAL_ALERT_N")
	)
	(segment
		(start 299.1612 -419.8366)
		(end 299.1612 -420.5732)
		(width 0.127)
		(layer "In11.Cu")
		(net "FM_THERMAL_ALERT_N")
	)
	(segment
		(start 364.90402 -410.563568)
		(end 363.98454 -409.644088)
		(width 0.127)
		(layer "In13.Cu")
		(net "FM_THERMAL_ALERT_N")
	)
	(segment
		(start 363.79912 -407.868628)
		(end 362.20908 -407.868628)
		(width 0.127)
		(layer "In13.Cu")
		(net "FM_THERMAL_ALERT_N")
	)
	(segment
		(start 362.20908 -407.868628)
		(end 354.43668 -400.096228)
		(width 0.127)
		(layer "In13.Cu")
		(net "FM_THERMAL_ALERT_N")
	)
	(segment
		(start 144.25676 -108.483908)
		(end 147.8788 -112.105948)
		(width 0.127)
		(layer "In13.Cu")
		(net "FM_THERMAL_ALERT_N")
	)
	(segment
		(start 118.854982 -106.703368)
		(end 126.874778 -106.703368)
		(width 0.127)
		(layer "In13.Cu")
		(net "FM_THERMAL_ALERT_N")
	)
	(segment
		(start 353.98202 -398.24406)
		(end 352.32086 -398.24406)
		(width 0.127)
		(layer "In13.Cu")
		(net "FM_THERMAL_ALERT_N")
	)
	(segment
		(start 147.8788 -112.105948)
		(end 150.85568 -112.105948)
		(width 0.127)
		(layer "In13.Cu")
		(net "FM_THERMAL_ALERT_N")
	)
	(segment
		(start 126.958598 -106.619548)
		(end 138.16076 -106.619548)
		(width 0.127)
		(layer "In13.Cu")
		(net "FM_THERMAL_ALERT_N")
	)
	(segment
		(start 363.98454 -408.054048)
		(end 363.79912 -407.868628)
		(width 0.127)
		(layer "In13.Cu")
		(net "FM_THERMAL_ALERT_N")
	)
	(segment
		(start 47.592234 -111.948468)
		(end 47.59452 -111.948468)
		(width 0.127)
		(layer "In13.Cu")
		(net "FM_THERMAL_ALERT_N")
	)
	(segment
		(start 140.02512 -108.483908)
		(end 144.25676 -108.483908)
		(width 0.127)
		(layer "In13.Cu")
		(net "FM_THERMAL_ALERT_N")
	)
	(segment
		(start 138.16076 -106.619548)
		(end 140.02512 -108.483908)
		(width 0.127)
		(layer "In13.Cu")
		(net "FM_THERMAL_ALERT_N")
	)
	(segment
		(start 176.58588 -135.245348)
		(end 176.58588 -134.788148)
		(width 0.127)
		(layer "In13.Cu")
		(net "FM_THERMAL_ALERT_N")
	)
	(segment
		(start 64.468756 -113.13287)
		(end 66.859658 -110.741968)
		(width 0.127)
		(layer "In13.Cu")
		(net "FM_THERMAL_ALERT_N")
	)
	(segment
		(start 150.85568 -112.105948)
		(end 151.26208 -111.699548)
		(width 0.127)
		(layer "In13.Cu")
		(net "FM_THERMAL_ALERT_N")
	)
	(segment
		(start 177.01768 -135.677148)
		(end 176.58588 -135.245348)
		(width 0.127)
		(layer "In13.Cu")
		(net "FM_THERMAL_ALERT_N")
	)
	(segment
		(start 52.150518 -112.804448)
		(end 52.47894 -113.13287)
		(width 0.127)
		(layer "In13.Cu")
		(net "FM_THERMAL_ALERT_N")
	)
	(segment
		(start 47.59452 -111.948468)
		(end 48.4505 -112.804448)
		(width 0.127)
		(layer "In13.Cu")
		(net "FM_THERMAL_ALERT_N")
	)
	(segment
		(start 66.859658 -110.741968)
		(end 76.750418 -110.741968)
		(width 0.127)
		(layer "In13.Cu")
		(net "FM_THERMAL_ALERT_N")
	)
	(segment
		(start 48.4505 -112.804448)
		(end 52.150518 -112.804448)
		(width 0.127)
		(layer "In13.Cu")
		(net "FM_THERMAL_ALERT_N")
	)
	(segment
		(start 100.395278 -107.721908)
		(end 101.523038 -106.594148)
		(width 0.127)
		(layer "In13.Cu")
		(net "FM_THERMAL_ALERT_N")
	)
	(segment
		(start 126.874778 -106.703368)
		(end 126.958598 -106.619548)
		(width 0.127)
		(layer "In13.Cu")
		(net "FM_THERMAL_ALERT_N")
	)
	(segment
		(start 197.36308 -134.711948)
		(end 196.39788 -135.677148)
		(width 0.127)
		(layer "In13.Cu")
		(net "FM_THERMAL_ALERT_N")
	)
	(segment
		(start 118.745762 -106.594148)
		(end 118.854982 -106.703368)
		(width 0.127)
		(layer "In13.Cu")
		(net "FM_THERMAL_ALERT_N")
	)
	(segment
		(start 79.770478 -107.721908)
		(end 100.395278 -107.721908)
		(width 0.127)
		(layer "In13.Cu")
		(net "FM_THERMAL_ALERT_N")
	)
	(segment
		(start 354.43668 -398.69872)
		(end 353.98202 -398.24406)
		(width 0.127)
		(layer "In13.Cu")
		(net "FM_THERMAL_ALERT_N")
	)
	(segment
		(start 52.47894 -113.13287)
		(end 64.468756 -113.13287)
		(width 0.127)
		(layer "In13.Cu")
		(net "FM_THERMAL_ALERT_N")
	)
	(segment
		(start 366.417098 -421.447468)
		(end 364.90402 -419.93439)
		(width 0.127)
		(layer "In13.Cu")
		(net "FM_THERMAL_ALERT_N")
	)
	(segment
		(start 352.32086 -398.24406)
		(end 351.74936 -397.67256)
		(width 0.127)
		(layer "In13.Cu")
		(net "FM_THERMAL_ALERT_N")
	)
	(segment
		(start 76.750418 -110.741968)
		(end 79.770478 -107.721908)
		(width 0.127)
		(layer "In13.Cu")
		(net "FM_THERMAL_ALERT_N")
	)
	(segment
		(start 196.39788 -135.677148)
		(end 177.01768 -135.677148)
		(width 0.127)
		(layer "In13.Cu")
		(net "FM_THERMAL_ALERT_N")
	)
	(segment
		(start 101.523038 -106.594148)
		(end 118.745762 -106.594148)
		(width 0.127)
		(layer "In13.Cu")
		(net "FM_THERMAL_ALERT_N")
	)
	(segment
		(start 363.98454 -409.644088)
		(end 363.98454 -408.054048)
		(width 0.127)
		(layer "In13.Cu")
		(net "FM_THERMAL_ALERT_N")
	)
	(segment
		(start 364.90402 -419.93439)
		(end 364.90402 -410.563568)
		(width 0.127)
		(layer "In13.Cu")
		(net "FM_THERMAL_ALERT_N")
	)
	(segment
		(start 354.43668 -400.096228)
		(end 354.43668 -398.69872)
		(width 0.127)
		(layer "In13.Cu")
		(net "FM_THERMAL_ALERT_N")
	)
	(segment
		(start 176.02708 -134.229348)
		(end 169.65168 -134.229348)
		(width 0.127)
		(layer "In15.Cu")
		(net "FM_THERMAL_ALERT_N")
	)
	(segment
		(start 16.51508 -168.533572)
		(end 10.900664 -174.147988)
		(width 0.127)
		(layer "In15.Cu")
		(net "FM_THERMAL_ALERT_N")
	)
	(segment
		(start 169.65168 -134.229348)
		(end 169.11828 -134.762748)
		(width 0.127)
		(layer "In15.Cu")
		(net "FM_THERMAL_ALERT_N")
	)
	(segment
		(start 47.592234 -111.948468)
		(end 44.63796 -111.948468)
		(width 0.127)
		(layer "In15.Cu")
		(net "FM_THERMAL_ALERT_N")
	)
	(segment
		(start 163.56076 -133.931914)
		(end 156.400246 -133.931914)
		(width 0.127)
		(layer "In15.Cu")
		(net "FM_THERMAL_ALERT_N")
	)
	(segment
		(start 169.11828 -134.762748)
		(end 164.391594 -134.762748)
		(width 0.127)
		(layer "In15.Cu")
		(net "FM_THERMAL_ALERT_N")
	)
	(segment
		(start 44.63796 -111.948468)
		(end 41.19118 -115.395248)
		(width 0.127)
		(layer "In15.Cu")
		(net "FM_THERMAL_ALERT_N")
	)
	(segment
		(start 16.51508 -128.233424)
		(end 16.51508 -168.533572)
		(width 0.127)
		(layer "In15.Cu")
		(net "FM_THERMAL_ALERT_N")
	)
	(segment
		(start 29.353256 -115.395248)
		(end 16.51508 -128.233424)
		(width 0.127)
		(layer "In15.Cu")
		(net "FM_THERMAL_ALERT_N")
	)
	(segment
		(start 10.900664 -174.147988)
		(end 9.77138 -174.147988)
		(width 0.127)
		(layer "In15.Cu")
		(net "FM_THERMAL_ALERT_N")
	)
	(segment
		(start 156.400246 -133.931914)
		(end 153.97988 -131.511548)
		(width 0.127)
		(layer "In15.Cu")
		(net "FM_THERMAL_ALERT_N")
	)
	(segment
		(start 41.19118 -115.395248)
		(end 29.353256 -115.395248)
		(width 0.127)
		(layer "In15.Cu")
		(net "FM_THERMAL_ALERT_N")
	)
	(segment
		(start 176.58588 -134.788148)
		(end 176.02708 -134.229348)
		(width 0.127)
		(layer "In15.Cu")
		(net "FM_THERMAL_ALERT_N")
	)
	(segment
		(start 164.391594 -134.762748)
		(end 163.56076 -133.931914)
		(width 0.127)
		(layer "In15.Cu")
		(net "FM_THERMAL_ALERT_N")
	)
	(segment
		(start 109.896148 -15.553944)
		(end 110.206028 -15.244064)
		(width 0.12954)
		(layer "F.Cu")
		(net "FM_LM75_3_ALERT_N")
	)
	(segment
		(start 108.48848 -15.204948)
		(end 108.837476 -15.553944)
		(width 0.12954)
		(layer "F.Cu")
		(net "FM_LM75_3_ALERT_N")
	)
	(segment
		(start 366.413542 -419.708076)
		(end 366.413542 -419.064948)
		(width 0.12954)
		(layer "F.Cu")
		(net "FM_LM75_3_ALERT_N")
	)
	(segment
		(start 110.206028 -15.244064)
		(end 110.556548 -15.244064)
		(width 0.12954)
		(layer "F.Cu")
		(net "FM_LM75_3_ALERT_N")
	)
	(segment
		(start 108.837476 -15.553944)
		(end 109.896148 -15.553944)
		(width 0.12954)
		(layer "F.Cu")
		(net "FM_LM75_3_ALERT_N")
	)
	(via
		(at 235.323126 -209.959448)
		(size 0.508)
		(drill 0.254)
		(layers "F.Cu" "B.Cu")
		(net "FM_LM75_3_ALERT_N")
	)
	(via
		(at 213.4616 -106.4006)
		(size 0.508)
		(drill 0.254)
		(layers "F.Cu" "B.Cu")
		(net "FM_LM75_3_ALERT_N")
	)
	(via
		(at 366.413542 -419.064948)
		(size 0.508)
		(drill 0.254)
		(layers "F.Cu" "B.Cu")
		(net "FM_LM75_3_ALERT_N")
	)
	(via
		(at 108.48848 -15.204948)
		(size 0.508)
		(drill 0.254)
		(layers "F.Cu" "B.Cu")
		(net "FM_LM75_3_ALERT_N")
	)
	(via
		(at 186.49188 -60.543948)
		(size 0.508)
		(drill 0.254)
		(layers "F.Cu" "B.Cu")
		(net "FM_LM75_3_ALERT_N")
	)
	(via
		(at 301.68088 -397.048228)
		(size 0.508)
		(drill 0.254)
		(layers "F.Cu" "B.Cu")
		(net "FM_LM75_3_ALERT_N")
	)
	(segment
		(start 199.515222 -82.997548)
		(end 190.603886 -82.997548)
		(width 0.127)
		(layer "In2.Cu")
		(net "FM_LM75_3_ALERT_N")
	)
	(segment
		(start 190.603886 -82.997548)
		(end 186.49188 -78.885542)
		(width 0.127)
		(layer "In2.Cu")
		(net "FM_LM75_3_ALERT_N")
	)
	(segment
		(start 213.79688 -97.279206)
		(end 207.446372 -90.928698)
		(width 0.127)
		(layer "In2.Cu")
		(net "FM_LM75_3_ALERT_N")
	)
	(segment
		(start 207.446372 -90.928698)
		(end 207.446372 -89.833704)
		(width 0.127)
		(layer "In2.Cu")
		(net "FM_LM75_3_ALERT_N")
	)
	(segment
		(start 205.897226 -89.379552)
		(end 199.515222 -82.997548)
		(width 0.127)
		(layer "In2.Cu")
		(net "FM_LM75_3_ALERT_N")
	)
	(segment
		(start 186.49188 -78.885542)
		(end 186.49188 -60.543948)
		(width 0.127)
		(layer "In2.Cu")
		(net "FM_LM75_3_ALERT_N")
	)
	(segment
		(start 213.79688 -106.06532)
		(end 213.79688 -97.279206)
		(width 0.127)
		(layer "In2.Cu")
		(net "FM_LM75_3_ALERT_N")
	)
	(segment
		(start 206.99222 -89.379552)
		(end 205.897226 -89.379552)
		(width 0.127)
		(layer "In2.Cu")
		(net "FM_LM75_3_ALERT_N")
	)
	(segment
		(start 207.446372 -89.833704)
		(end 206.99222 -89.379552)
		(width 0.127)
		(layer "In2.Cu")
		(net "FM_LM75_3_ALERT_N")
	)
	(segment
		(start 213.4616 -106.4006)
		(end 213.79688 -106.06532)
		(width 0.127)
		(layer "In2.Cu")
		(net "FM_LM75_3_ALERT_N")
	)
	(segment
		(start 284.227016 -394.062204)
		(end 284.227016 -391.973816)
		(width 0.127)
		(layer "In4.Cu")
		(net "FM_LM75_3_ALERT_N")
	)
	(segment
		(start 239.95888 -277.586948)
		(end 245.41988 -272.125948)
		(width 0.127)
		(layer "In4.Cu")
		(net "FM_LM75_3_ALERT_N")
	)
	(segment
		(start 245.41988 -220.056202)
		(end 235.323126 -209.959448)
		(width 0.127)
		(layer "In4.Cu")
		(net "FM_LM75_3_ALERT_N")
	)
	(segment
		(start 299.994574 -396.839948)
		(end 299.821854 -396.667228)
		(width 0.127)
		(layer "In4.Cu")
		(net "FM_LM75_3_ALERT_N")
	)
	(segment
		(start 272.26514 -362.471208)
		(end 239.95888 -330.164948)
		(width 0.127)
		(layer "In4.Cu")
		(net "FM_LM75_3_ALERT_N")
	)
	(segment
		(start 301.68088 -397.048228)
		(end 301.4726 -396.839948)
		(width 0.127)
		(layer "In4.Cu")
		(net "FM_LM75_3_ALERT_N")
	)
	(segment
		(start 284.227016 -391.973816)
		(end 272.26514 -380.01194)
		(width 0.127)
		(layer "In4.Cu")
		(net "FM_LM75_3_ALERT_N")
	)
	(segment
		(start 299.821854 -396.667228)
		(end 286.83204 -396.667228)
		(width 0.127)
		(layer "In4.Cu")
		(net "FM_LM75_3_ALERT_N")
	)
	(segment
		(start 272.26514 -380.01194)
		(end 272.26514 -362.471208)
		(width 0.127)
		(layer "In4.Cu")
		(net "FM_LM75_3_ALERT_N")
	)
	(segment
		(start 245.41988 -272.125948)
		(end 245.41988 -220.056202)
		(width 0.127)
		(layer "In4.Cu")
		(net "FM_LM75_3_ALERT_N")
	)
	(segment
		(start 301.4726 -396.839948)
		(end 299.994574 -396.839948)
		(width 0.127)
		(layer "In4.Cu")
		(net "FM_LM75_3_ALERT_N")
	)
	(segment
		(start 286.83204 -396.667228)
		(end 284.227016 -394.062204)
		(width 0.127)
		(layer "In4.Cu")
		(net "FM_LM75_3_ALERT_N")
	)
	(segment
		(start 239.95888 -330.164948)
		(end 239.95888 -277.586948)
		(width 0.127)
		(layer "In4.Cu")
		(net "FM_LM75_3_ALERT_N")
	)
	(segment
		(start 366.09528 -418.746686)
		(end 366.413542 -419.064948)
		(width 0.127)
		(layer "In6.Cu")
		(net "FM_LM75_3_ALERT_N")
	)
	(segment
		(start 366.09528 -415.757868)
		(end 366.09528 -418.746686)
		(width 0.127)
		(layer "In6.Cu")
		(net "FM_LM75_3_ALERT_N")
	)
	(segment
		(start 301.68088 -397.048228)
		(end 303.990248 -394.73886)
		(width 0.127)
		(layer "In6.Cu")
		(net "FM_LM75_3_ALERT_N")
	)
	(segment
		(start 366.8268 -415.026348)
		(end 366.09528 -415.757868)
		(width 0.127)
		(layer "In6.Cu")
		(net "FM_LM75_3_ALERT_N")
	)
	(segment
		(start 357.999792 -394.73886)
		(end 361.39628 -398.135348)
		(width 0.127)
		(layer "In6.Cu")
		(net "FM_LM75_3_ALERT_N")
	)
	(segment
		(start 366.8268 -399.860008)
		(end 366.8268 -415.026348)
		(width 0.127)
		(layer "In6.Cu")
		(net "FM_LM75_3_ALERT_N")
	)
	(segment
		(start 365.10214 -398.135348)
		(end 366.8268 -399.860008)
		(width 0.127)
		(layer "In6.Cu")
		(net "FM_LM75_3_ALERT_N")
	)
	(segment
		(start 303.990248 -394.73886)
		(end 357.999792 -394.73886)
		(width 0.127)
		(layer "In6.Cu")
		(net "FM_LM75_3_ALERT_N")
	)
	(segment
		(start 361.39628 -398.135348)
		(end 365.10214 -398.135348)
		(width 0.127)
		(layer "In6.Cu")
		(net "FM_LM75_3_ALERT_N")
	)
	(segment
		(start 183.542432 -58.232548)
		(end 174.090584 -58.232548)
		(width 0.127)
		(layer "In11.Cu")
		(net "FM_LM75_3_ALERT_N")
	)
	(segment
		(start 104.17048 -15.916148)
		(end 104.88168 -15.204948)
		(width 0.127)
		(layer "In11.Cu")
		(net "FM_LM75_3_ALERT_N")
	)
	(segment
		(start 108.01858 -28.425648)
		(end 104.17048 -24.577548)
		(width 0.127)
		(layer "In11.Cu")
		(net "FM_LM75_3_ALERT_N")
	)
	(segment
		(start 244.78488 -203.418948)
		(end 237.79988 -210.403948)
		(width 0.127)
		(layer "In11.Cu")
		(net "FM_LM75_3_ALERT_N")
	)
	(segment
		(start 109.26318 -28.425648)
		(end 108.01858 -28.425648)
		(width 0.127)
		(layer "In11.Cu")
		(net "FM_LM75_3_ALERT_N")
	)
	(segment
		(start 221.89948 -157.552644)
		(end 244.78488 -180.438044)
		(width 0.127)
		(layer "In11.Cu")
		(net "FM_LM75_3_ALERT_N")
	)
	(segment
		(start 185.853832 -60.543948)
		(end 183.542432 -58.232548)
		(width 0.127)
		(layer "In11.Cu")
		(net "FM_LM75_3_ALERT_N")
	)
	(segment
		(start 244.78488 -180.438044)
		(end 244.78488 -203.418948)
		(width 0.127)
		(layer "In11.Cu")
		(net "FM_LM75_3_ALERT_N")
	)
	(segment
		(start 104.88168 -15.204948)
		(end 108.48848 -15.204948)
		(width 0.127)
		(layer "In11.Cu")
		(net "FM_LM75_3_ALERT_N")
	)
	(segment
		(start 186.49188 -60.543948)
		(end 185.853832 -60.543948)
		(width 0.127)
		(layer "In11.Cu")
		(net "FM_LM75_3_ALERT_N")
	)
	(segment
		(start 213.4616 -106.4006)
		(end 213.4616 -109.342682)
		(width 0.127)
		(layer "In11.Cu")
		(net "FM_LM75_3_ALERT_N")
	)
	(segment
		(start 174.090584 -58.232548)
		(end 171.347384 -60.975748)
		(width 0.127)
		(layer "In11.Cu")
		(net "FM_LM75_3_ALERT_N")
	)
	(segment
		(start 221.89948 -145.703036)
		(end 221.89948 -157.552644)
		(width 0.127)
		(layer "In11.Cu")
		(net "FM_LM75_3_ALERT_N")
	)
	(segment
		(start 211.9757 -124.722128)
		(end 212.17382 -124.920248)
		(width 0.127)
		(layer "In11.Cu")
		(net "FM_LM75_3_ALERT_N")
	)
	(segment
		(start 116.79428 -45.811948)
		(end 116.79428 -35.956748)
		(width 0.127)
		(layer "In11.Cu")
		(net "FM_LM75_3_ALERT_N")
	)
	(segment
		(start 212.17382 -127.85598)
		(end 213.11616 -128.79832)
		(width 0.127)
		(layer "In11.Cu")
		(net "FM_LM75_3_ALERT_N")
	)
	(segment
		(start 213.4616 -109.342682)
		(end 211.9757 -110.828582)
		(width 0.127)
		(layer "In11.Cu")
		(net "FM_LM75_3_ALERT_N")
	)
	(segment
		(start 120.513602 -49.53127)
		(end 116.79428 -45.811948)
		(width 0.127)
		(layer "In11.Cu")
		(net "FM_LM75_3_ALERT_N")
	)
	(segment
		(start 134.950454 -49.53127)
		(end 120.513602 -49.53127)
		(width 0.127)
		(layer "In11.Cu")
		(net "FM_LM75_3_ALERT_N")
	)
	(segment
		(start 146.394932 -60.975748)
		(end 134.950454 -49.53127)
		(width 0.127)
		(layer "In11.Cu")
		(net "FM_LM75_3_ALERT_N")
	)
	(segment
		(start 213.11616 -136.919716)
		(end 221.89948 -145.703036)
		(width 0.127)
		(layer "In11.Cu")
		(net "FM_LM75_3_ALERT_N")
	)
	(segment
		(start 237.79988 -210.403948)
		(end 235.767626 -210.403948)
		(width 0.127)
		(layer "In11.Cu")
		(net "FM_LM75_3_ALERT_N")
	)
	(segment
		(start 211.9757 -110.828582)
		(end 211.9757 -124.722128)
		(width 0.127)
		(layer "In11.Cu")
		(net "FM_LM75_3_ALERT_N")
	)
	(segment
		(start 171.347384 -60.975748)
		(end 146.394932 -60.975748)
		(width 0.127)
		(layer "In11.Cu")
		(net "FM_LM75_3_ALERT_N")
	)
	(segment
		(start 235.767626 -210.403948)
		(end 235.323126 -209.959448)
		(width 0.127)
		(layer "In11.Cu")
		(net "FM_LM75_3_ALERT_N")
	)
	(segment
		(start 104.17048 -24.577548)
		(end 104.17048 -15.916148)
		(width 0.127)
		(layer "In11.Cu")
		(net "FM_LM75_3_ALERT_N")
	)
	(segment
		(start 116.79428 -35.956748)
		(end 109.26318 -28.425648)
		(width 0.127)
		(layer "In11.Cu")
		(net "FM_LM75_3_ALERT_N")
	)
	(segment
		(start 212.17382 -124.920248)
		(end 212.17382 -127.85598)
		(width 0.127)
		(layer "In11.Cu")
		(net "FM_LM75_3_ALERT_N")
	)
	(segment
		(start 213.11616 -128.79832)
		(end 213.11616 -136.919716)
		(width 0.127)
		(layer "In11.Cu")
		(net "FM_LM75_3_ALERT_N")
	)
	(segment
		(start 102.5398 -427.269148)
		(end 102.92842 -426.880528)
		(width 0.12954)
		(layer "F.Cu")
		(net "FM_LM75_2_ALERT_N")
	)
	(segment
		(start 104.59593 -425.580048)
		(end 104.81183 -425.795948)
		(width 0.12954)
		(layer "F.Cu")
		(net "FM_LM75_2_ALERT_N")
	)
	(segment
		(start 99.523296 -426.22978)
		(end 99.523296 -427.041564)
		(width 0.12954)
		(layer "F.Cu")
		(net "FM_LM75_2_ALERT_N")
	)
	(segment
		(start 102.92842 -426.235368)
		(end 103.58374 -425.580048)
		(width 0.12954)
		(layer "F.Cu")
		(net "FM_LM75_2_ALERT_N")
	)
	(segment
		(start 102.92842 -426.880528)
		(end 102.92842 -426.235368)
		(width 0.12954)
		(layer "F.Cu")
		(net "FM_LM75_2_ALERT_N")
	)
	(segment
		(start 99.75088 -427.269148)
		(end 102.5398 -427.269148)
		(width 0.12954)
		(layer "F.Cu")
		(net "FM_LM75_2_ALERT_N")
	)
	(segment
		(start 103.58374 -425.580048)
		(end 104.59593 -425.580048)
		(width 0.12954)
		(layer "F.Cu")
		(net "FM_LM75_2_ALERT_N")
	)
	(segment
		(start 99.523296 -427.041564)
		(end 99.75088 -427.269148)
		(width 0.12954)
		(layer "F.Cu")
		(net "FM_LM75_2_ALERT_N")
	)
	(via
		(at 103.58374 -425.580048)
		(size 0.762)
		(drill 0.381)
		(layers "F.Cu" "B.Cu")
		(net "FM_LM75_2_ALERT_N")
	)
	(segment
		(start 286.505142 -15.22476)
		(end 287.061402 -15.22476)
		(width 0.12954)
		(layer "F.Cu")
		(net "FM_G751_1_ALERT_N")
	)
	(segment
		(start 285.642812 -14.36243)
		(end 286.505142 -15.22476)
		(width 0.12954)
		(layer "F.Cu")
		(net "FM_G751_1_ALERT_N")
	)
	(segment
		(start 287.061402 -15.22476)
		(end 287.572958 -14.713204)
		(width 0.12954)
		(layer "F.Cu")
		(net "FM_G751_1_ALERT_N")
	)
	(segment
		(start 287.572958 -14.713204)
		(end 289.182048 -14.713204)
		(width 0.12954)
		(layer "F.Cu")
		(net "FM_G751_1_ALERT_N")
	)
	(via
		(at 287.061402 -15.22476)
		(size 0.762)
		(drill 0.381)
		(layers "F.Cu" "B.Cu")
		(net "FM_G751_1_ALERT_N")
	)
	(segment
		(start 370.270278 -425.882308)
		(end 370.270278 -424.0149)
		(width 0.12954)
		(layer "F.Cu")
		(net "FM_G751_0_ALERT_N")
	)
	(segment
		(start 367.38052 -421.757348)
		(end 366.854232 -422.283636)
		(width 0.12954)
		(layer "F.Cu")
		(net "FM_G751_0_ALERT_N")
	)
	(segment
		(start 370.270278 -424.0149)
		(end 368.012726 -421.757348)
		(width 0.12954)
		(layer "F.Cu")
		(net "FM_G751_0_ALERT_N")
	)
	(segment
		(start 368.012726 -421.757348)
		(end 367.38052 -421.757348)
		(width 0.12954)
		(layer "F.Cu")
		(net "FM_G751_0_ALERT_N")
	)
	(segment
		(start 366.854232 -422.283636)
		(end 366.854232 -423.03573)
		(width 0.12954)
		(layer "F.Cu")
		(net "FM_G751_0_ALERT_N")
	)
	(via
		(at 367.38052 -421.757348)
		(size 0.762)
		(drill 0.381)
		(layers "F.Cu" "B.Cu")
		(net "FM_G751_0_ALERT_N")
	)
	(segment
		(start 163.88842 -29.540708)
		(end 164.43452 -28.994608)
		(width 0.12954)
		(layer "F.Cu")
		(net "FM_ESPI_PLD_R_EN_BUF_R")
	)
	(segment
		(start 163.88842 -29.957268)
		(end 163.88842 -29.540708)
		(width 0.12954)
		(layer "F.Cu")
		(net "FM_ESPI_PLD_R_EN_BUF_R")
	)
	(segment
		(start 165.61689 -30.584648)
		(end 164.5158 -30.584648)
		(width 0.12954)
		(layer "F.Cu")
		(net "FM_ESPI_PLD_R_EN_BUF_R")
	)
	(segment
		(start 164.43452 -28.994608)
		(end 165.678866 -28.994608)
		(width 0.12954)
		(layer "F.Cu")
		(net "FM_ESPI_PLD_R_EN_BUF_R")
	)
	(segment
		(start 164.5158 -30.584648)
		(end 163.88842 -29.957268)
		(width 0.12954)
		(layer "F.Cu")
		(net "FM_ESPI_PLD_R_EN_BUF_R")
	)
	(via
		(at 163.88842 -29.540708)
		(size 0.762)
		(drill 0.381)
		(layers "F.Cu" "B.Cu")
		(net "FM_ESPI_PLD_R_EN_BUF_R")
	)
	(segment
		(start 376.606562 -283.219652)
		(end 376.606562 -282.683966)
		(width 0.12954)
		(layer "F.Cu")
		(net "Net_654")
	)
	(via
		(at 376.606562 -283.219652)
		(size 0.4572)
		(drill 0.2032)
		(layers "F.Cu" "B.Cu")
		(net "Net_654")
	)
	(segment
		(start 377.076716 -280.778204)
		(end 377.076716 -280.242264)
		(width 0.12954)
		(layer "F.Cu")
		(net "Net_655")
	)
	(via
		(at 377.076716 -280.778204)
		(size 0.4572)
		(drill 0.2032)
		(layers "F.Cu" "B.Cu")
		(net "Net_655")
	)
	(segment
		(start 378.016516 -282.405582)
		(end 378.016516 -281.869896)
		(width 0.12954)
		(layer "F.Cu")
		(net "Net_656")
	)
	(via
		(at 378.016516 -282.405582)
		(size 0.4572)
		(drill 0.2032)
		(layers "F.Cu" "B.Cu")
		(net "Net_656")
	)
	(segment
		(start 377.546362 -281.59202)
		(end 377.546362 -281.05608)
		(width 0.12954)
		(layer "F.Cu")
		(net "Net_657")
	)
	(via
		(at 377.546362 -281.59202)
		(size 0.4572)
		(drill 0.2032)
		(layers "F.Cu" "B.Cu")
		(net "Net_657")
	)
	(segment
		(start 384.595116 -287.288986)
		(end 384.595116 -286.7533)
		(width 0.12954)
		(layer "F.Cu")
		(net "Net_658")
	)
	(via
		(at 384.595116 -287.288986)
		(size 0.4572)
		(drill 0.2032)
		(layers "F.Cu" "B.Cu")
		(net "Net_658")
	)
	(segment
		(start 383.185162 -286.47517)
		(end 383.185162 -285.939484)
		(width 0.12954)
		(layer "F.Cu")
		(net "Net_659")
	)
	(via
		(at 383.185162 -286.47517)
		(size 0.4572)
		(drill 0.2032)
		(layers "F.Cu" "B.Cu")
		(net "Net_659")
	)
	(segment
		(start 386.004562 -286.47517)
		(end 386.004562 -285.939484)
		(width 0.12954)
		(layer "F.Cu")
		(net "Net_660")
	)
	(via
		(at 386.004562 -286.47517)
		(size 0.4572)
		(drill 0.2032)
		(layers "F.Cu" "B.Cu")
		(net "Net_660")
	)
	(segment
		(start 362.509562 -275.080476)
		(end 362.509308 -275.08073)
		(width 0.12954)
		(layer "F.Cu")
		(net "Net_661")
	)
	(segment
		(start 362.509562 -274.54479)
		(end 362.509562 -275.080476)
		(width 0.12954)
		(layer "F.Cu")
		(net "Net_661")
	)
	(via
		(at 362.509308 -275.08073)
		(size 0.4572)
		(drill 0.2032)
		(layers "F.Cu" "B.Cu")
		(net "Net_661")
	)
	(segment
		(start 369.558316 -275.894546)
		(end 369.558316 -275.35886)
		(width 0.12954)
		(layer "F.Cu")
		(net "Net_662")
	)
	(via
		(at 369.558316 -275.894546)
		(size 0.4572)
		(drill 0.2032)
		(layers "F.Cu" "B.Cu")
		(net "Net_662")
	)
	(segment
		(start 365.328962 -276.708362)
		(end 365.328962 -276.172676)
		(width 0.12954)
		(layer "F.Cu")
		(net "Net_663")
	)
	(via
		(at 365.328962 -276.708362)
		(size 0.4572)
		(drill 0.2032)
		(layers "F.Cu" "B.Cu")
		(net "Net_663")
	)
	(segment
		(start 364.389162 -276.708362)
		(end 364.389162 -276.172676)
		(width 0.12954)
		(layer "F.Cu")
		(net "Net_664")
	)
	(via
		(at 364.389162 -276.708362)
		(size 0.4572)
		(drill 0.2032)
		(layers "F.Cu" "B.Cu")
		(net "Net_664")
	)
	(segment
		(start 385.534662 -285.6611)
		(end 385.534662 -285.125414)
		(width 0.12954)
		(layer "F.Cu")
		(net "Net_665")
	)
	(via
		(at 385.534662 -285.6611)
		(size 0.4572)
		(drill 0.2032)
		(layers "F.Cu" "B.Cu")
		(net "Net_665")
	)
	(segment
		(start 363.449362 -278.336248)
		(end 363.449362 -277.800562)
		(width 0.12954)
		(layer "F.Cu")
		(net "Net_666")
	)
	(via
		(at 363.449362 -278.336248)
		(size 0.4572)
		(drill 0.2032)
		(layers "F.Cu" "B.Cu")
		(net "Net_666")
	)
	(segment
		(start 365.799116 -277.522178)
		(end 365.799116 -276.986492)
		(width 0.12954)
		(layer "F.Cu")
		(net "Net_667")
	)
	(via
		(at 365.799116 -277.522178)
		(size 0.4572)
		(drill 0.2032)
		(layers "F.Cu" "B.Cu")
		(net "Net_667")
	)
	(segment
		(start 364.859316 -279.150064)
		(end 364.859316 -278.614378)
		(width 0.12954)
		(layer "F.Cu")
		(net "Net_668")
	)
	(via
		(at 364.859316 -279.150064)
		(size 0.4572)
		(drill 0.2032)
		(layers "F.Cu" "B.Cu")
		(net "Net_668")
	)
	(segment
		(start 366.268762 -278.336248)
		(end 366.268762 -277.800562)
		(width 0.12954)
		(layer "F.Cu")
		(net "Net_669")
	)
	(via
		(at 366.268762 -278.336248)
		(size 0.4572)
		(drill 0.2032)
		(layers "F.Cu" "B.Cu")
		(net "Net_669")
	)
	(segment
		(start 368.618516 -275.894546)
		(end 368.618516 -275.35886)
		(width 0.12954)
		(layer "F.Cu")
		(net "Net_670")
	)
	(via
		(at 368.618516 -275.894546)
		(size 0.4572)
		(drill 0.2032)
		(layers "F.Cu" "B.Cu")
		(net "Net_670")
	)
	(segment
		(start 367.678716 -277.522178)
		(end 367.678716 -276.986492)
		(width 0.12954)
		(layer "F.Cu")
		(net "Net_671")
	)
	(via
		(at 367.678716 -277.522178)
		(size 0.4572)
		(drill 0.2032)
		(layers "F.Cu" "B.Cu")
		(net "Net_671")
	)
	(segment
		(start 369.088162 -278.336248)
		(end 369.088162 -277.800562)
		(width 0.12954)
		(layer "F.Cu")
		(net "Net_672")
	)
	(via
		(at 369.088162 -278.336248)
		(size 0.4572)
		(drill 0.2032)
		(layers "F.Cu" "B.Cu")
		(net "Net_672")
	)
	(segment
		(start 370.498116 -277.522178)
		(end 370.498116 -276.986492)
		(width 0.12954)
		(layer "F.Cu")
		(net "Net_673")
	)
	(via
		(at 370.498116 -277.522178)
		(size 0.4572)
		(drill 0.2032)
		(layers "F.Cu" "B.Cu")
		(net "Net_673")
	)
	(segment
		(start 376.136916 -280.778204)
		(end 376.136916 -280.242264)
		(width 0.12954)
		(layer "F.Cu")
		(net "Net_674")
	)
	(via
		(at 376.136916 -280.778204)
		(size 0.4572)
		(drill 0.2032)
		(layers "F.Cu" "B.Cu")
		(net "Net_674")
	)
	(segment
		(start 375.197116 -282.405582)
		(end 375.197116 -281.869896)
		(width 0.12954)
		(layer "F.Cu")
		(net "Net_675")
	)
	(via
		(at 375.197116 -282.405582)
		(size 0.4572)
		(drill 0.2032)
		(layers "F.Cu" "B.Cu")
		(net "Net_675")
	)
	(segment
		(start 385.064762 -284.847284)
		(end 385.064762 -284.311598)
		(width 0.12954)
		(layer "F.Cu")
		(net "Net_676")
	)
	(via
		(at 385.064762 -284.847284)
		(size 0.4572)
		(drill 0.2032)
		(layers "F.Cu" "B.Cu")
		(net "Net_676")
	)
	(segment
		(start 384.124962 -284.847284)
		(end 384.124962 -284.311598)
		(width 0.12954)
		(layer "F.Cu")
		(net "Net_677")
	)
	(via
		(at 384.124962 -284.847284)
		(size 0.4572)
		(drill 0.2032)
		(layers "F.Cu" "B.Cu")
		(net "Net_677")
	)
	(segment
		(start 376.136916 -282.405582)
		(end 376.136916 -281.869896)
		(width 0.12954)
		(layer "F.Cu")
		(net "Net_678")
	)
	(via
		(at 376.136916 -282.405582)
		(size 0.4572)
		(drill 0.2032)
		(layers "F.Cu" "B.Cu")
		(net "Net_678")
	)
	(segment
		(start 376.606562 -279.96388)
		(end 376.606562 -279.428194)
		(width 0.12954)
		(layer "F.Cu")
		(net "Net_679")
	)
	(via
		(at 376.606562 -279.96388)
		(size 0.4572)
		(drill 0.2032)
		(layers "F.Cu" "B.Cu")
		(net "Net_679")
	)
	(segment
		(start 377.076716 -282.405582)
		(end 377.076716 -281.869896)
		(width 0.12954)
		(layer "F.Cu")
		(net "Net_680")
	)
	(via
		(at 377.076716 -282.405582)
		(size 0.4572)
		(drill 0.2032)
		(layers "F.Cu" "B.Cu")
		(net "Net_680")
	)
	(segment
		(start 378.016516 -280.778204)
		(end 378.016516 -280.242264)
		(width 0.12954)
		(layer "F.Cu")
		(net "Net_681")
	)
	(via
		(at 378.016516 -280.778204)
		(size 0.4572)
		(drill 0.2032)
		(layers "F.Cu" "B.Cu")
		(net "Net_681")
	)
	(segment
		(start 384.124962 -286.47517)
		(end 384.124962 -285.939484)
		(width 0.12954)
		(layer "F.Cu")
		(net "Net_682")
	)
	(via
		(at 384.124962 -286.47517)
		(size 0.4572)
		(drill 0.2032)
		(layers "F.Cu" "B.Cu")
		(net "Net_682")
	)
	(segment
		(start 383.655062 -285.6611)
		(end 383.655062 -285.125414)
		(width 0.12954)
		(layer "F.Cu")
		(net "Net_683")
	)
	(via
		(at 383.655062 -285.6611)
		(size 0.4572)
		(drill 0.2032)
		(layers "F.Cu" "B.Cu")
		(net "Net_683")
	)
	(segment
		(start 385.064762 -286.47517)
		(end 385.064762 -285.939484)
		(width 0.12954)
		(layer "F.Cu")
		(net "Net_684")
	)
	(via
		(at 385.064762 -286.47517)
		(size 0.4572)
		(drill 0.2032)
		(layers "F.Cu" "B.Cu")
		(net "Net_684")
	)
	(segment
		(start 363.449362 -275.080476)
		(end 363.449108 -275.08073)
		(width 0.12954)
		(layer "F.Cu")
		(net "Net_685")
	)
	(segment
		(start 363.449362 -274.54479)
		(end 363.449362 -275.080476)
		(width 0.12954)
		(layer "F.Cu")
		(net "Net_685")
	)
	(via
		(at 363.449108 -275.08073)
		(size 0.4572)
		(drill 0.2032)
		(layers "F.Cu" "B.Cu")
		(net "Net_685")
	)
	(segment
		(start 369.088162 -275.080476)
		(end 369.088162 -274.54479)
		(width 0.12954)
		(layer "F.Cu")
		(net "Net_686")
	)
	(via
		(at 369.088162 -275.080476)
		(size 0.4572)
		(drill 0.2032)
		(layers "F.Cu" "B.Cu")
		(net "Net_686")
	)
	(segment
		(start 364.859316 -275.894546)
		(end 364.859316 -275.35886)
		(width 0.12954)
		(layer "F.Cu")
		(net "Net_687")
	)
	(via
		(at 364.859316 -275.894546)
		(size 0.4572)
		(drill 0.2032)
		(layers "F.Cu" "B.Cu")
		(net "Net_687")
	)
	(segment
		(start 363.449362 -276.708362)
		(end 363.449362 -276.172676)
		(width 0.12954)
		(layer "F.Cu")
		(net "Net_688")
	)
	(via
		(at 363.449362 -276.708362)
		(size 0.4572)
		(drill 0.2032)
		(layers "F.Cu" "B.Cu")
		(net "Net_688")
	)
	(segment
		(start 386.004562 -284.847284)
		(end 386.004562 -284.311598)
		(width 0.12954)
		(layer "F.Cu")
		(net "Net_689")
	)
	(via
		(at 386.004562 -284.847284)
		(size 0.4572)
		(drill 0.2032)
		(layers "F.Cu" "B.Cu")
		(net "Net_689")
	)
	(segment
		(start 363.919516 -277.522178)
		(end 363.919516 -276.986492)
		(width 0.12954)
		(layer "F.Cu")
		(net "Net_690")
	)
	(via
		(at 363.919516 -277.522178)
		(size 0.4572)
		(drill 0.2032)
		(layers "F.Cu" "B.Cu")
		(net "Net_690")
	)
	(segment
		(start 366.268762 -276.708362)
		(end 366.268762 -276.172676)
		(width 0.12954)
		(layer "F.Cu")
		(net "Net_691")
	)
	(via
		(at 366.268762 -276.708362)
		(size 0.4572)
		(drill 0.2032)
		(layers "F.Cu" "B.Cu")
		(net "Net_691")
	)
	(segment
		(start 364.389162 -278.336248)
		(end 364.389162 -277.800562)
		(width 0.12954)
		(layer "F.Cu")
		(net "Net_692")
	)
	(via
		(at 364.389162 -278.336248)
		(size 0.4572)
		(drill 0.2032)
		(layers "F.Cu" "B.Cu")
		(net "Net_692")
	)
	(segment
		(start 365.328962 -278.336248)
		(end 365.328962 -277.800562)
		(width 0.12954)
		(layer "F.Cu")
		(net "Net_693")
	)
	(via
		(at 365.328962 -278.336248)
		(size 0.4572)
		(drill 0.2032)
		(layers "F.Cu" "B.Cu")
		(net "Net_693")
	)
	(segment
		(start 367.678716 -275.894546)
		(end 367.678716 -275.35886)
		(width 0.12954)
		(layer "F.Cu")
		(net "Net_694")
	)
	(via
		(at 367.678716 -275.894546)
		(size 0.4572)
		(drill 0.2032)
		(layers "F.Cu" "B.Cu")
		(net "Net_694")
	)
	(segment
		(start 368.148362 -276.708362)
		(end 368.148362 -276.172676)
		(width 0.12954)
		(layer "F.Cu")
		(net "Net_695")
	)
	(via
		(at 368.148362 -276.708362)
		(size 0.4572)
		(drill 0.2032)
		(layers "F.Cu" "B.Cu")
		(net "Net_695")
	)
	(segment
		(start 368.618516 -277.522178)
		(end 368.618516 -276.986492)
		(width 0.12954)
		(layer "F.Cu")
		(net "Net_696")
	)
	(via
		(at 368.618516 -277.522178)
		(size 0.4572)
		(drill 0.2032)
		(layers "F.Cu" "B.Cu")
		(net "Net_696")
	)
	(segment
		(start 369.558316 -277.522178)
		(end 369.558316 -276.986492)
		(width 0.12954)
		(layer "F.Cu")
		(net "Net_697")
	)
	(via
		(at 369.558316 -277.522178)
		(size 0.4572)
		(drill 0.2032)
		(layers "F.Cu" "B.Cu")
		(net "Net_697")
	)
	(segment
		(start 375.197116 -280.778204)
		(end 375.197116 -280.242264)
		(width 0.12954)
		(layer "F.Cu")
		(net "Net_698")
	)
	(via
		(at 375.197116 -280.778204)
		(size 0.4572)
		(drill 0.2032)
		(layers "F.Cu" "B.Cu")
		(net "Net_698")
	)
	(segment
		(start 375.666762 -281.591766)
		(end 375.666762 -281.05608)
		(width 0.12954)
		(layer "F.Cu")
		(net "Net_699")
	)
	(via
		(at 375.666762 -281.591766)
		(size 0.4572)
		(drill 0.2032)
		(layers "F.Cu" "B.Cu")
		(net "Net_699")
	)
	(segment
		(start 383.185162 -284.847284)
		(end 383.185162 -284.311598)
		(width 0.12954)
		(layer "F.Cu")
		(net "Net_701")
	)
	(via
		(at 383.185162 -284.847284)
		(size 0.4572)
		(drill 0.2032)
		(layers "F.Cu" "B.Cu")
		(net "Net_701")
	)
	(segment
		(start 128.666494 -283.219652)
		(end 128.666494 -282.683966)
		(width 0.12954)
		(layer "F.Cu")
		(net "Net_702")
	)
	(via
		(at 128.666494 -283.219652)
		(size 0.4572)
		(drill 0.2032)
		(layers "F.Cu" "B.Cu")
		(net "Net_702")
	)
	(segment
		(start 129.136648 -280.778204)
		(end 129.136648 -280.242264)
		(width 0.12954)
		(layer "F.Cu")
		(net "Net_703")
	)
	(via
		(at 129.136648 -280.778204)
		(size 0.4572)
		(drill 0.2032)
		(layers "F.Cu" "B.Cu")
		(net "Net_703")
	)
	(segment
		(start 130.076448 -282.405582)
		(end 130.076448 -281.869896)
		(width 0.12954)
		(layer "F.Cu")
		(net "Net_704")
	)
	(via
		(at 130.076448 -282.405582)
		(size 0.4572)
		(drill 0.2032)
		(layers "F.Cu" "B.Cu")
		(net "Net_704")
	)
	(segment
		(start 129.606294 -281.59202)
		(end 129.606294 -281.05608)
		(width 0.12954)
		(layer "F.Cu")
		(net "Net_705")
	)
	(via
		(at 129.606294 -281.59202)
		(size 0.4572)
		(drill 0.2032)
		(layers "F.Cu" "B.Cu")
		(net "Net_705")
	)
	(segment
		(start 136.655048 -287.288986)
		(end 136.655048 -286.7533)
		(width 0.12954)
		(layer "F.Cu")
		(net "Net_706")
	)
	(via
		(at 136.655048 -287.288986)
		(size 0.4572)
		(drill 0.2032)
		(layers "F.Cu" "B.Cu")
		(net "Net_706")
	)
	(segment
		(start 135.245094 -286.47517)
		(end 135.245094 -285.939484)
		(width 0.12954)
		(layer "F.Cu")
		(net "Net_707")
	)
	(via
		(at 135.245094 -286.47517)
		(size 0.4572)
		(drill 0.2032)
		(layers "F.Cu" "B.Cu")
		(net "Net_707")
	)
	(segment
		(start 138.064494 -286.47517)
		(end 138.064494 -285.939484)
		(width 0.12954)
		(layer "F.Cu")
		(net "Net_708")
	)
	(via
		(at 138.064494 -286.47517)
		(size 0.4572)
		(drill 0.2032)
		(layers "F.Cu" "B.Cu")
		(net "Net_708")
	)
	(segment
		(start 114.569494 -274.54479)
		(end 114.569494 -275.080476)
		(width 0.12954)
		(layer "F.Cu")
		(net "Net_709")
	)
	(segment
		(start 114.569494 -275.080476)
		(end 114.56924 -275.08073)
		(width 0.12954)
		(layer "F.Cu")
		(net "Net_709")
	)
	(via
		(at 114.56924 -275.08073)
		(size 0.4572)
		(drill 0.2032)
		(layers "F.Cu" "B.Cu")
		(net "Net_709")
	)
	(segment
		(start 121.618248 -275.894546)
		(end 121.618248 -275.35886)
		(width 0.12954)
		(layer "F.Cu")
		(net "Net_710")
	)
	(via
		(at 121.618248 -275.894546)
		(size 0.4572)
		(drill 0.2032)
		(layers "F.Cu" "B.Cu")
		(net "Net_710")
	)
	(segment
		(start 117.388894 -276.708362)
		(end 117.388894 -276.172676)
		(width 0.12954)
		(layer "F.Cu")
		(net "Net_711")
	)
	(via
		(at 117.388894 -276.708362)
		(size 0.4572)
		(drill 0.2032)
		(layers "F.Cu" "B.Cu")
		(net "Net_711")
	)
	(segment
		(start 116.449094 -276.708362)
		(end 116.449094 -276.172676)
		(width 0.12954)
		(layer "F.Cu")
		(net "Net_712")
	)
	(via
		(at 116.449094 -276.708362)
		(size 0.4572)
		(drill 0.2032)
		(layers "F.Cu" "B.Cu")
		(net "Net_712")
	)
	(segment
		(start 137.594594 -285.6611)
		(end 137.594594 -285.125414)
		(width 0.12954)
		(layer "F.Cu")
		(net "Net_713")
	)
	(via
		(at 137.594594 -285.6611)
		(size 0.4572)
		(drill 0.2032)
		(layers "F.Cu" "B.Cu")
		(net "Net_713")
	)
	(segment
		(start 115.509294 -278.336248)
		(end 115.509294 -277.800562)
		(width 0.12954)
		(layer "F.Cu")
		(net "Net_714")
	)
	(via
		(at 115.509294 -278.336248)
		(size 0.4572)
		(drill 0.2032)
		(layers "F.Cu" "B.Cu")
		(net "Net_714")
	)
	(segment
		(start 117.859048 -277.522178)
		(end 117.859048 -276.986492)
		(width 0.12954)
		(layer "F.Cu")
		(net "Net_715")
	)
	(via
		(at 117.859048 -277.522178)
		(size 0.4572)
		(drill 0.2032)
		(layers "F.Cu" "B.Cu")
		(net "Net_715")
	)
	(segment
		(start 116.919248 -279.150064)
		(end 116.919248 -278.614378)
		(width 0.12954)
		(layer "F.Cu")
		(net "Net_716")
	)
	(via
		(at 116.919248 -279.150064)
		(size 0.4572)
		(drill 0.2032)
		(layers "F.Cu" "B.Cu")
		(net "Net_716")
	)
	(segment
		(start 118.328694 -278.336248)
		(end 118.328694 -277.800562)
		(width 0.12954)
		(layer "F.Cu")
		(net "Net_717")
	)
	(via
		(at 118.328694 -278.336248)
		(size 0.4572)
		(drill 0.2032)
		(layers "F.Cu" "B.Cu")
		(net "Net_717")
	)
	(segment
		(start 120.678448 -275.894546)
		(end 120.678448 -275.35886)
		(width 0.12954)
		(layer "F.Cu")
		(net "Net_718")
	)
	(via
		(at 120.678448 -275.894546)
		(size 0.4572)
		(drill 0.2032)
		(layers "F.Cu" "B.Cu")
		(net "Net_718")
	)
	(segment
		(start 119.738648 -277.522178)
		(end 119.738648 -276.986492)
		(width 0.12954)
		(layer "F.Cu")
		(net "Net_719")
	)
	(via
		(at 119.738648 -277.522178)
		(size 0.4572)
		(drill 0.2032)
		(layers "F.Cu" "B.Cu")
		(net "Net_719")
	)
	(segment
		(start 121.148094 -278.336248)
		(end 121.148094 -277.800562)
		(width 0.12954)
		(layer "F.Cu")
		(net "Net_720")
	)
	(via
		(at 121.148094 -278.336248)
		(size 0.4572)
		(drill 0.2032)
		(layers "F.Cu" "B.Cu")
		(net "Net_720")
	)
	(segment
		(start 122.558048 -277.522178)
		(end 122.558048 -276.986492)
		(width 0.12954)
		(layer "F.Cu")
		(net "Net_721")
	)
	(via
		(at 122.558048 -277.522178)
		(size 0.4572)
		(drill 0.2032)
		(layers "F.Cu" "B.Cu")
		(net "Net_721")
	)
	(segment
		(start 128.196848 -280.778204)
		(end 128.196848 -280.242264)
		(width 0.12954)
		(layer "F.Cu")
		(net "Net_722")
	)
	(via
		(at 128.196848 -280.778204)
		(size 0.4572)
		(drill 0.2032)
		(layers "F.Cu" "B.Cu")
		(net "Net_722")
	)
	(segment
		(start 127.257048 -282.405582)
		(end 127.257048 -281.869896)
		(width 0.12954)
		(layer "F.Cu")
		(net "Net_723")
	)
	(via
		(at 127.257048 -282.405582)
		(size 0.4572)
		(drill 0.2032)
		(layers "F.Cu" "B.Cu")
		(net "Net_723")
	)
	(segment
		(start 137.124694 -284.847284)
		(end 137.124694 -284.311598)
		(width 0.12954)
		(layer "F.Cu")
		(net "Net_724")
	)
	(via
		(at 137.124694 -284.847284)
		(size 0.4572)
		(drill 0.2032)
		(layers "F.Cu" "B.Cu")
		(net "Net_724")
	)
	(segment
		(start 136.184894 -284.847284)
		(end 136.184894 -284.311598)
		(width 0.12954)
		(layer "F.Cu")
		(net "Net_725")
	)
	(via
		(at 136.184894 -284.847284)
		(size 0.4572)
		(drill 0.2032)
		(layers "F.Cu" "B.Cu")
		(net "Net_725")
	)
	(segment
		(start 128.196848 -282.405582)
		(end 128.196848 -281.869896)
		(width 0.12954)
		(layer "F.Cu")
		(net "Net_726")
	)
	(via
		(at 128.196848 -282.405582)
		(size 0.4572)
		(drill 0.2032)
		(layers "F.Cu" "B.Cu")
		(net "Net_726")
	)
	(segment
		(start 128.666494 -279.96388)
		(end 128.666494 -279.428194)
		(width 0.12954)
		(layer "F.Cu")
		(net "Net_727")
	)
	(via
		(at 128.666494 -279.96388)
		(size 0.4572)
		(drill 0.2032)
		(layers "F.Cu" "B.Cu")
		(net "Net_727")
	)
	(segment
		(start 129.136648 -282.405582)
		(end 129.136648 -281.869896)
		(width 0.12954)
		(layer "F.Cu")
		(net "Net_728")
	)
	(via
		(at 129.136648 -282.405582)
		(size 0.4572)
		(drill 0.2032)
		(layers "F.Cu" "B.Cu")
		(net "Net_728")
	)
	(segment
		(start 130.076448 -280.778204)
		(end 130.076448 -280.242264)
		(width 0.12954)
		(layer "F.Cu")
		(net "Net_729")
	)
	(via
		(at 130.076448 -280.778204)
		(size 0.4572)
		(drill 0.2032)
		(layers "F.Cu" "B.Cu")
		(net "Net_729")
	)
	(segment
		(start 136.184894 -286.47517)
		(end 136.184894 -285.939484)
		(width 0.12954)
		(layer "F.Cu")
		(net "Net_730")
	)
	(via
		(at 136.184894 -286.47517)
		(size 0.4572)
		(drill 0.2032)
		(layers "F.Cu" "B.Cu")
		(net "Net_730")
	)
	(segment
		(start 135.714994 -285.6611)
		(end 135.714994 -285.125414)
		(width 0.12954)
		(layer "F.Cu")
		(net "Net_731")
	)
	(via
		(at 135.714994 -285.6611)
		(size 0.4572)
		(drill 0.2032)
		(layers "F.Cu" "B.Cu")
		(net "Net_731")
	)
	(segment
		(start 137.124694 -286.47517)
		(end 137.124694 -285.939484)
		(width 0.12954)
		(layer "F.Cu")
		(net "Net_732")
	)
	(via
		(at 137.124694 -286.47517)
		(size 0.4572)
		(drill 0.2032)
		(layers "F.Cu" "B.Cu")
		(net "Net_732")
	)
	(segment
		(start 115.509294 -274.54479)
		(end 115.509294 -275.080476)
		(width 0.12954)
		(layer "F.Cu")
		(net "Net_733")
	)
	(segment
		(start 115.509294 -275.080476)
		(end 115.50904 -275.08073)
		(width 0.12954)
		(layer "F.Cu")
		(net "Net_733")
	)
	(via
		(at 115.50904 -275.08073)
		(size 0.4572)
		(drill 0.2032)
		(layers "F.Cu" "B.Cu")
		(net "Net_733")
	)
	(segment
		(start 121.148094 -275.080476)
		(end 121.148094 -274.54479)
		(width 0.12954)
		(layer "F.Cu")
		(net "Net_734")
	)
	(via
		(at 121.148094 -275.080476)
		(size 0.4572)
		(drill 0.2032)
		(layers "F.Cu" "B.Cu")
		(net "Net_734")
	)
	(segment
		(start 116.919248 -275.35886)
		(end 116.919248 -275.894546)
		(width 0.12954)
		(layer "F.Cu")
		(net "Net_735")
	)
	(segment
		(start 116.919248 -275.894546)
		(end 116.918994 -275.8948)
		(width 0.12954)
		(layer "F.Cu")
		(net "Net_735")
	)
	(via
		(at 116.918994 -275.8948)
		(size 0.4572)
		(drill 0.2032)
		(layers "F.Cu" "B.Cu")
		(net "Net_735")
	)
	(segment
		(start 115.509294 -276.708362)
		(end 115.509294 -276.172676)
		(width 0.12954)
		(layer "F.Cu")
		(net "Net_736")
	)
	(via
		(at 115.509294 -276.708362)
		(size 0.4572)
		(drill 0.2032)
		(layers "F.Cu" "B.Cu")
		(net "Net_736")
	)
	(segment
		(start 138.064494 -284.847284)
		(end 138.064494 -284.311598)
		(width 0.12954)
		(layer "F.Cu")
		(net "Net_737")
	)
	(via
		(at 138.064494 -284.847284)
		(size 0.4572)
		(drill 0.2032)
		(layers "F.Cu" "B.Cu")
		(net "Net_737")
	)
	(segment
		(start 115.979448 -277.522178)
		(end 115.979448 -276.986492)
		(width 0.12954)
		(layer "F.Cu")
		(net "Net_738")
	)
	(via
		(at 115.979448 -277.522178)
		(size 0.4572)
		(drill 0.2032)
		(layers "F.Cu" "B.Cu")
		(net "Net_738")
	)
	(segment
		(start 118.328694 -276.708362)
		(end 118.328694 -276.172676)
		(width 0.12954)
		(layer "F.Cu")
		(net "Net_739")
	)
	(via
		(at 118.328694 -276.708362)
		(size 0.4572)
		(drill 0.2032)
		(layers "F.Cu" "B.Cu")
		(net "Net_739")
	)
	(segment
		(start 116.449094 -278.336248)
		(end 116.449094 -277.800562)
		(width 0.12954)
		(layer "F.Cu")
		(net "Net_740")
	)
	(via
		(at 116.449094 -278.336248)
		(size 0.4572)
		(drill 0.2032)
		(layers "F.Cu" "B.Cu")
		(net "Net_740")
	)
	(segment
		(start 117.388894 -278.336248)
		(end 117.388894 -277.800562)
		(width 0.12954)
		(layer "F.Cu")
		(net "Net_741")
	)
	(via
		(at 117.388894 -278.336248)
		(size 0.4572)
		(drill 0.2032)
		(layers "F.Cu" "B.Cu")
		(net "Net_741")
	)
	(segment
		(start 119.738648 -275.894546)
		(end 119.738648 -275.35886)
		(width 0.12954)
		(layer "F.Cu")
		(net "Net_742")
	)
	(via
		(at 119.738648 -275.894546)
		(size 0.4572)
		(drill 0.2032)
		(layers "F.Cu" "B.Cu")
		(net "Net_742")
	)
	(segment
		(start 120.208294 -276.708362)
		(end 120.208294 -276.172676)
		(width 0.12954)
		(layer "F.Cu")
		(net "Net_743")
	)
	(via
		(at 120.208294 -276.708362)
		(size 0.4572)
		(drill 0.2032)
		(layers "F.Cu" "B.Cu")
		(net "Net_743")
	)
	(segment
		(start 120.678448 -277.522178)
		(end 120.678448 -276.986492)
		(width 0.12954)
		(layer "F.Cu")
		(net "Net_744")
	)
	(via
		(at 120.678448 -277.522178)
		(size 0.4572)
		(drill 0.2032)
		(layers "F.Cu" "B.Cu")
		(net "Net_744")
	)
	(segment
		(start 121.618248 -277.522178)
		(end 121.618248 -276.986492)
		(width 0.12954)
		(layer "F.Cu")
		(net "Net_745")
	)
	(via
		(at 121.618248 -277.522178)
		(size 0.4572)
		(drill 0.2032)
		(layers "F.Cu" "B.Cu")
		(net "Net_745")
	)
	(segment
		(start 127.257048 -280.778204)
		(end 127.257048 -280.242264)
		(width 0.12954)
		(layer "F.Cu")
		(net "Net_746")
	)
	(via
		(at 127.257048 -280.778204)
		(size 0.4572)
		(drill 0.2032)
		(layers "F.Cu" "B.Cu")
		(net "Net_746")
	)
	(segment
		(start 127.726694 -281.591766)
		(end 127.726694 -281.05608)
		(width 0.12954)
		(layer "F.Cu")
		(net "Net_747")
	)
	(via
		(at 127.726694 -281.591766)
		(size 0.4572)
		(drill 0.2032)
		(layers "F.Cu" "B.Cu")
		(net "Net_747")
	)
	(segment
		(start 136.655048 -284.03296)
		(end 136.65454 -284.033468)
		(width 0.12954)
		(layer "F.Cu")
		(net "Net_748")
	)
	(segment
		(start 136.655048 -283.497782)
		(end 136.655048 -284.03296)
		(width 0.12954)
		(layer "F.Cu")
		(net "Net_748")
	)
	(via
		(at 136.65454 -284.033468)
		(size 0.4572)
		(drill 0.2032)
		(layers "F.Cu" "B.Cu")
		(net "Net_748")
	)
	(segment
		(start 135.245094 -284.847284)
		(end 135.245094 -284.311598)
		(width 0.12954)
		(layer "F.Cu")
		(net "Net_749")
	)
	(via
		(at 135.245094 -284.847284)
		(size 0.4572)
		(drill 0.2032)
		(layers "F.Cu" "B.Cu")
		(net "Net_749")
	)
	(segment
		(start 190.46952 -122.941588)
		(end 192.86474 -125.336808)
		(width 0.12954)
		(layer "F.Cu")
		(net "PULL_FPGA_PB46A")
	)
	(segment
		(start 190.46952 -122.479308)
		(end 190.46952 -122.941588)
		(width 0.12954)
		(layer "F.Cu")
		(net "PULL_FPGA_PB46A")
	)
	(segment
		(start 192.86474 -125.336808)
		(end 192.99555 -125.336808)
		(width 0.12954)
		(layer "F.Cu")
		(net "PULL_FPGA_PB46A")
	)
	(segment
		(start 189.002162 -122.479308)
		(end 190.46952 -122.479308)
		(width 0.12954)
		(layer "F.Cu")
		(net "PULL_FPGA_PB46A")
	)
	(segment
		(start 186.955684 -120.975374)
		(end 187.498228 -120.975374)
		(width 0.12954)
		(layer "F.Cu")
		(net "PULL_FPGA_PB46A")
	)
	(segment
		(start 187.498228 -120.975374)
		(end 189.002162 -122.479308)
		(width 0.12954)
		(layer "F.Cu")
		(net "PULL_FPGA_PB46A")
	)
	(via
		(at 190.46952 -122.479308)
		(size 0.762)
		(drill 0.381)
		(layers "F.Cu" "B.Cu")
		(net "PULL_FPGA_PB46A")
	)
	(segment
		(start 112.93856 -404.15972)
		(end 112.414812 -403.635972)
		(width 0.12954)
		(layer "F.Cu")
		(net "NC_U257_2Y")
	)
	(segment
		(start 112.414812 -403.635972)
		(end 112.414812 -403.095206)
		(width 0.12954)
		(layer "F.Cu")
		(net "NC_U257_2Y")
	)
	(segment
		(start 113.72596 -404.15972)
		(end 112.93856 -404.15972)
		(width 0.12954)
		(layer "F.Cu")
		(net "NC_U257_2Y")
	)
	(via
		(at 113.72596 -404.15972)
		(size 0.762)
		(drill 0.381)
		(layers "F.Cu" "B.Cu")
		(net "NC_U257_2Y")
	)
	(segment
		(start 141.79296 -77.850492)
		(end 141.79296 -76.421488)
		(width 0.12954)
		(layer "F.Cu")
		(net "NC_U150_B1")
	)
	(via
		(at 141.79296 -76.421488)
		(size 0.762)
		(drill 0.381)
		(layers "F.Cu" "B.Cu")
		(net "NC_U150_B1")
	)
	(segment
		(start 140.40104 -76.434188)
		(end 139.89304 -76.942188)
		(width 0.12954)
		(layer "F.Cu")
		(net "NC_U150_A1")
	)
	(segment
		(start 139.89304 -76.942188)
		(end 139.89304 -77.850492)
		(width 0.12954)
		(layer "F.Cu")
		(net "NC_U150_A1")
	)
	(via
		(at 140.40104 -76.434188)
		(size 0.762)
		(drill 0.381)
		(layers "F.Cu" "B.Cu")
		(net "NC_U150_A1")
	)
	(segment
		(start 205.90256 -32.578548)
		(end 207.346042 -34.02203)
		(width 0.12954)
		(layer "F.Cu")
		(net "NC_INA230_5_NC5")
	)
	(segment
		(start 207.346042 -34.02203)
		(end 207.772508 -34.02203)
		(width 0.12954)
		(layer "F.Cu")
		(net "NC_INA230_5_NC5")
	)
	(via
		(at 205.90256 -32.578548)
		(size 0.762)
		(drill 0.381)
		(layers "F.Cu" "B.Cu")
		(net "NC_INA230_5_NC5")
	)
	(segment
		(start 206.144368 -34.522156)
		(end 207.772508 -34.522156)
		(width 0.12954)
		(layer "F.Cu")
		(net "NC_INA230_5_NC4")
	)
	(segment
		(start 205.94574 -34.323528)
		(end 206.144368 -34.522156)
		(width 0.12954)
		(layer "F.Cu")
		(net "NC_INA230_5_NC4")
	)
	(via
		(at 205.94574 -34.323528)
		(size 0.762)
		(drill 0.381)
		(layers "F.Cu" "B.Cu")
		(net "NC_INA230_5_NC4")
	)
	(segment
		(start 205.86192 -36.007548)
		(end 205.86192 -35.707828)
		(width 0.12954)
		(layer "F.Cu")
		(net "NC_INA230_5_NC3")
	)
	(segment
		(start 206.54772 -35.022028)
		(end 207.772508 -35.022028)
		(width 0.12954)
		(layer "F.Cu")
		(net "NC_INA230_5_NC3")
	)
	(segment
		(start 205.86192 -35.707828)
		(end 206.54772 -35.022028)
		(width 0.12954)
		(layer "F.Cu")
		(net "NC_INA230_5_NC3")
	)
	(via
		(at 205.86192 -36.007548)
		(size 0.762)
		(drill 0.381)
		(layers "F.Cu" "B.Cu")
		(net "NC_INA230_5_NC3")
	)
	(segment
		(start 211.08162 -35.634168)
		(end 210.969606 -35.522154)
		(width 0.12954)
		(layer "F.Cu")
		(net "NC_INA230_5_NC2")
	)
	(segment
		(start 210.969606 -35.522154)
		(end 210.572604 -35.522154)
		(width 0.12954)
		(layer "F.Cu")
		(net "NC_INA230_5_NC2")
	)
	(segment
		(start 211.66328 -37.061648)
		(end 211.08162 -36.479988)
		(width 0.12954)
		(layer "F.Cu")
		(net "NC_INA230_5_NC2")
	)
	(segment
		(start 211.08162 -36.479988)
		(end 211.08162 -35.634168)
		(width 0.12954)
		(layer "F.Cu")
		(net "NC_INA230_5_NC2")
	)
	(via
		(at 211.66328 -37.061648)
		(size 0.762)
		(drill 0.381)
		(layers "F.Cu" "B.Cu")
		(net "NC_INA230_5_NC2")
	)
	(segment
		(start 211.80298 -35.674808)
		(end 211.59724 -35.674808)
		(width 0.12954)
		(layer "F.Cu")
		(net "NC_INA230_5_NC1")
	)
	(segment
		(start 210.94446 -35.022028)
		(end 210.572604 -35.022028)
		(width 0.12954)
		(layer "F.Cu")
		(net "NC_INA230_5_NC1")
	)
	(segment
		(start 211.59724 -35.674808)
		(end 210.94446 -35.022028)
		(width 0.12954)
		(layer "F.Cu")
		(net "NC_INA230_5_NC1")
	)
	(segment
		(start 213.22284 -37.094668)
		(end 211.80298 -35.674808)
		(width 0.12954)
		(layer "F.Cu")
		(net "NC_INA230_5_NC1")
	)
	(via
		(at 213.22284 -37.094668)
		(size 0.762)
		(drill 0.381)
		(layers "F.Cu" "B.Cu")
		(net "NC_INA230_5_NC1")
	)
	(segment
		(start 214.93226 -36.896548)
		(end 213.23046 -35.194748)
		(width 0.12954)
		(layer "F.Cu")
		(net "NC_INA230_5_NC0")
	)
	(segment
		(start 210.906868 -34.522156)
		(end 210.572604 -34.522156)
		(width 0.12954)
		(layer "F.Cu")
		(net "NC_INA230_5_NC0")
	)
	(segment
		(start 213.23046 -35.194748)
		(end 211.57946 -35.194748)
		(width 0.12954)
		(layer "F.Cu")
		(net "NC_INA230_5_NC0")
	)
	(segment
		(start 211.57946 -35.194748)
		(end 210.906868 -34.522156)
		(width 0.12954)
		(layer "F.Cu")
		(net "NC_INA230_5_NC0")
	)
	(via
		(at 214.93226 -36.896548)
		(size 0.762)
		(drill 0.381)
		(layers "F.Cu" "B.Cu")
		(net "NC_INA230_5_NC0")
	)
	(segment
		(start 151.549354 -54.336188)
		(end 151.943562 -53.94198)
		(width 0.12954)
		(layer "F.Cu")
		(net "NC_INA230_4_NC5")
	)
	(segment
		(start 151.943562 -53.94198)
		(end 151.943562 -53.71846)
		(width 0.12954)
		(layer "F.Cu")
		(net "NC_INA230_4_NC5")
	)
	(segment
		(start 150.22068 -54.336188)
		(end 151.549354 -54.336188)
		(width 0.12954)
		(layer "F.Cu")
		(net "NC_INA230_4_NC5")
	)
	(via
		(at 150.22068 -54.336188)
		(size 0.762)
		(drill 0.381)
		(layers "F.Cu" "B.Cu")
		(net "NC_INA230_4_NC5")
	)
	(segment
		(start 151.3586 -55.019448)
		(end 151.59228 -55.019448)
		(width 0.12954)
		(layer "F.Cu")
		(net "NC_INA230_4_NC4")
	)
	(segment
		(start 152.443688 -54.16804)
		(end 152.443688 -53.71846)
		(width 0.12954)
		(layer "F.Cu")
		(net "NC_INA230_4_NC4")
	)
	(segment
		(start 151.59228 -55.019448)
		(end 152.443688 -54.16804)
		(width 0.12954)
		(layer "F.Cu")
		(net "NC_INA230_4_NC4")
	)
	(via
		(at 151.3586 -55.019448)
		(size 0.762)
		(drill 0.381)
		(layers "F.Cu" "B.Cu")
		(net "NC_INA230_4_NC4")
	)
	(segment
		(start 152.94356 -54.755288)
		(end 152.94356 -53.71846)
		(width 0.12954)
		(layer "F.Cu")
		(net "NC_INA230_4_NC3")
	)
	(segment
		(start 152.71242 -54.986428)
		(end 152.94356 -54.755288)
		(width 0.12954)
		(layer "F.Cu")
		(net "NC_INA230_4_NC3")
	)
	(via
		(at 152.71242 -54.986428)
		(size 0.762)
		(drill 0.381)
		(layers "F.Cu" "B.Cu")
		(net "NC_INA230_4_NC3")
	)
	(segment
		(start 155.2448 -50.104548)
		(end 153.9748 -50.104548)
		(width 0.12954)
		(layer "F.Cu")
		(net "NC_INA230_4_NC2")
	)
	(segment
		(start 153.9748 -50.104548)
		(end 153.443686 -50.635662)
		(width 0.12954)
		(layer "F.Cu")
		(net "NC_INA230_4_NC2")
	)
	(segment
		(start 153.443686 -50.635662)
		(end 153.443686 -50.918364)
		(width 0.12954)
		(layer "F.Cu")
		(net "NC_INA230_4_NC2")
	)
	(via
		(at 155.2448 -50.104548)
		(size 0.762)
		(drill 0.381)
		(layers "F.Cu" "B.Cu")
		(net "NC_INA230_4_NC2")
	)
	(segment
		(start 152.94356 -50.576988)
		(end 152.94356 -50.918364)
		(width 0.12954)
		(layer "F.Cu")
		(net "NC_INA230_4_NC1")
	)
	(segment
		(start 154.2288 -49.291748)
		(end 152.94356 -50.576988)
		(width 0.12954)
		(layer "F.Cu")
		(net "NC_INA230_4_NC1")
	)
	(via
		(at 154.2288 -49.291748)
		(size 0.762)
		(drill 0.381)
		(layers "F.Cu" "B.Cu")
		(net "NC_INA230_4_NC1")
	)
	(segment
		(start 152.443688 -50.03546)
		(end 152.443688 -50.918364)
		(width 0.12954)
		(layer "F.Cu")
		(net "NC_INA230_4_NC0")
	)
	(segment
		(start 152.908 -49.571148)
		(end 152.443688 -50.03546)
		(width 0.12954)
		(layer "F.Cu")
		(net "NC_INA230_4_NC0")
	)
	(via
		(at 152.908 -49.571148)
		(size 0.762)
		(drill 0.381)
		(layers "F.Cu" "B.Cu")
		(net "NC_INA230_4_NC0")
	)
	(segment
		(start 71.9582 -41.122854)
		(end 71.9582 -40.72001)
		(width 0.12954)
		(layer "F.Cu")
		(net "NC_INA230_3_NC5")
	)
	(segment
		(start 70.163436 -41.9989)
		(end 70.92315 -41.239186)
		(width 0.12954)
		(layer "F.Cu")
		(net "NC_INA230_3_NC5")
	)
	(segment
		(start 70.92315 -41.239186)
		(end 71.841868 -41.239186)
		(width 0.12954)
		(layer "F.Cu")
		(net "NC_INA230_3_NC5")
	)
	(segment
		(start 71.841868 -41.239186)
		(end 71.9582 -41.122854)
		(width 0.12954)
		(layer "F.Cu")
		(net "NC_INA230_3_NC5")
	)
	(via
		(at 70.163436 -41.9989)
		(size 0.762)
		(drill 0.381)
		(layers "F.Cu" "B.Cu")
		(net "NC_INA230_3_NC5")
	)
	(segment
		(start 71.433436 -41.9989)
		(end 71.859648 -41.572688)
		(width 0.12954)
		(layer "F.Cu")
		(net "NC_INA230_3_NC4")
	)
	(segment
		(start 72.235568 -41.572688)
		(end 72.458326 -41.34993)
		(width 0.12954)
		(layer "F.Cu")
		(net "NC_INA230_3_NC4")
	)
	(segment
		(start 72.458326 -41.34993)
		(end 72.458326 -40.72001)
		(width 0.12954)
		(layer "F.Cu")
		(net "NC_INA230_3_NC4")
	)
	(segment
		(start 71.859648 -41.572688)
		(end 72.235568 -41.572688)
		(width 0.12954)
		(layer "F.Cu")
		(net "NC_INA230_3_NC4")
	)
	(via
		(at 71.433436 -41.9989)
		(size 0.762)
		(drill 0.381)
		(layers "F.Cu" "B.Cu")
		(net "NC_INA230_3_NC4")
	)
	(segment
		(start 72.958198 -41.744138)
		(end 72.703436 -41.9989)
		(width 0.12954)
		(layer "F.Cu")
		(net "NC_INA230_3_NC3")
	)
	(segment
		(start 72.958198 -40.72001)
		(end 72.958198 -41.744138)
		(width 0.12954)
		(layer "F.Cu")
		(net "NC_INA230_3_NC3")
	)
	(via
		(at 72.703436 -41.9989)
		(size 0.762)
		(drill 0.381)
		(layers "F.Cu" "B.Cu")
		(net "NC_INA230_3_NC3")
	)
	(segment
		(start 73.458324 -37.822124)
		(end 73.458324 -37.919914)
		(width 0.12954)
		(layer "F.Cu")
		(net "NC_INA230_3_NC2")
	)
	(segment
		(start 75.0062 -37.226748)
		(end 74.0537 -37.226748)
		(width 0.12954)
		(layer "F.Cu")
		(net "NC_INA230_3_NC2")
	)
	(segment
		(start 74.0537 -37.226748)
		(end 73.458324 -37.822124)
		(width 0.12954)
		(layer "F.Cu")
		(net "NC_INA230_3_NC2")
	)
	(segment
		(start 75.6158 -36.617148)
		(end 75.0062 -37.226748)
		(width 0.12954)
		(layer "F.Cu")
		(net "NC_INA230_3_NC2")
	)
	(via
		(at 75.6158 -36.617148)
		(size 0.762)
		(drill 0.381)
		(layers "F.Cu" "B.Cu")
		(net "NC_INA230_3_NC2")
	)
	(segment
		(start 72.958198 -37.61486)
		(end 72.958198 -37.919914)
		(width 0.12954)
		(layer "F.Cu")
		(net "NC_INA230_3_NC1")
	)
	(segment
		(start 73.993756 -36.579302)
		(end 72.958198 -37.61486)
		(width 0.12954)
		(layer "F.Cu")
		(net "NC_INA230_3_NC1")
	)
	(segment
		(start 74.295 -36.579302)
		(end 73.993756 -36.579302)
		(width 0.12954)
		(layer "F.Cu")
		(net "NC_INA230_3_NC1")
	)
	(via
		(at 74.295 -36.579302)
		(size 0.762)
		(drill 0.381)
		(layers "F.Cu" "B.Cu")
		(net "NC_INA230_3_NC1")
	)
	(segment
		(start 72.458326 -37.056822)
		(end 72.458326 -37.919914)
		(width 0.12954)
		(layer "F.Cu")
		(net "NC_INA230_3_NC0")
	)
	(segment
		(start 72.9488 -36.566348)
		(end 72.458326 -37.056822)
		(width 0.12954)
		(layer "F.Cu")
		(net "NC_INA230_3_NC0")
	)
	(via
		(at 72.9488 -36.566348)
		(size 0.762)
		(drill 0.381)
		(layers "F.Cu" "B.Cu")
		(net "NC_INA230_3_NC0")
	)
	(segment
		(start 213.3473 -56.764428)
		(end 213.81466 -56.764428)
		(width 0.12954)
		(layer "F.Cu")
		(net "NC_INA230_2_NC5")
	)
	(segment
		(start 214.509604 -56.069484)
		(end 214.509604 -55.855362)
		(width 0.12954)
		(layer "F.Cu")
		(net "NC_INA230_2_NC5")
	)
	(segment
		(start 213.81466 -56.764428)
		(end 214.509604 -56.069484)
		(width 0.12954)
		(layer "F.Cu")
		(net "NC_INA230_2_NC5")
	)
	(segment
		(start 213.02472 -57.087008)
		(end 213.3473 -56.764428)
		(width 0.12954)
		(layer "F.Cu")
		(net "NC_INA230_2_NC5")
	)
	(via
		(at 213.02472 -57.087008)
		(size 0.762)
		(drill 0.381)
		(layers "F.Cu" "B.Cu")
		(net "NC_INA230_2_NC5")
	)
	(segment
		(start 215.00973 -56.102758)
		(end 215.00973 -55.855362)
		(width 0.12954)
		(layer "F.Cu")
		(net "NC_INA230_2_NC4")
	)
	(segment
		(start 213.59114 -58.781188)
		(end 213.59114 -57.521348)
		(width 0.12954)
		(layer "F.Cu")
		(net "NC_INA230_2_NC4")
	)
	(segment
		(start 213.59114 -57.521348)
		(end 215.00973 -56.102758)
		(width 0.12954)
		(layer "F.Cu")
		(net "NC_INA230_2_NC4")
	)
	(segment
		(start 213.12632 -59.246008)
		(end 213.59114 -58.781188)
		(width 0.12954)
		(layer "F.Cu")
		(net "NC_INA230_2_NC4")
	)
	(via
		(at 213.12632 -59.246008)
		(size 0.762)
		(drill 0.381)
		(layers "F.Cu" "B.Cu")
		(net "NC_INA230_2_NC4")
	)
	(segment
		(start 215.509602 -56.898286)
		(end 215.509602 -55.855362)
		(width 0.12954)
		(layer "F.Cu")
		(net "NC_INA230_2_NC3")
	)
	(segment
		(start 214.25154 -58.156348)
		(end 215.509602 -56.898286)
		(width 0.12954)
		(layer "F.Cu")
		(net "NC_INA230_2_NC3")
	)
	(via
		(at 214.25154 -58.156348)
		(size 0.762)
		(drill 0.381)
		(layers "F.Cu" "B.Cu")
		(net "NC_INA230_2_NC3")
	)
	(segment
		(start 216.63914 -52.012088)
		(end 216.009728 -52.6415)
		(width 0.12954)
		(layer "F.Cu")
		(net "NC_INA230_2_NC2")
	)
	(segment
		(start 216.009728 -52.6415)
		(end 216.009728 -53.055266)
		(width 0.12954)
		(layer "F.Cu")
		(net "NC_INA230_2_NC2")
	)
	(segment
		(start 217.2716 -52.012088)
		(end 216.63914 -52.012088)
		(width 0.12954)
		(layer "F.Cu")
		(net "NC_INA230_2_NC2")
	)
	(via
		(at 217.2716 -52.012088)
		(size 0.762)
		(drill 0.381)
		(layers "F.Cu" "B.Cu")
		(net "NC_INA230_2_NC2")
	)
	(segment
		(start 216.09304 -51.850798)
		(end 215.509602 -52.434236)
		(width 0.12954)
		(layer "F.Cu")
		(net "NC_INA230_2_NC1")
	)
	(segment
		(start 216.09304 -51.438048)
		(end 216.09304 -51.850798)
		(width 0.12954)
		(layer "F.Cu")
		(net "NC_INA230_2_NC1")
	)
	(segment
		(start 215.509602 -52.434236)
		(end 215.509602 -53.055266)
		(width 0.12954)
		(layer "F.Cu")
		(net "NC_INA230_2_NC1")
	)
	(segment
		(start 216.74836 -50.782728)
		(end 216.09304 -51.438048)
		(width 0.12954)
		(layer "F.Cu")
		(net "NC_INA230_2_NC1")
	)
	(via
		(at 216.74836 -50.782728)
		(size 0.762)
		(drill 0.381)
		(layers "F.Cu" "B.Cu")
		(net "NC_INA230_2_NC1")
	)
	(segment
		(start 215.00973 -52.226972)
		(end 215.00973 -53.055266)
		(width 0.12954)
		(layer "F.Cu")
		(net "NC_INA230_2_NC0")
	)
	(segment
		(start 215.72728 -49.919128)
		(end 215.20404 -50.442368)
		(width 0.12954)
		(layer "F.Cu")
		(net "NC_INA230_2_NC0")
	)
	(segment
		(start 215.20404 -52.032662)
		(end 215.00973 -52.226972)
		(width 0.12954)
		(layer "F.Cu")
		(net "NC_INA230_2_NC0")
	)
	(segment
		(start 215.20404 -50.442368)
		(end 215.20404 -52.032662)
		(width 0.12954)
		(layer "F.Cu")
		(net "NC_INA230_2_NC0")
	)
	(via
		(at 215.72728 -49.919128)
		(size 0.762)
		(drill 0.381)
		(layers "F.Cu" "B.Cu")
		(net "NC_INA230_2_NC0")
	)
	(segment
		(start 441.43803 -92.594938)
		(end 441.43803 -92.677488)
		(width 0.12954)
		(layer "F.Cu")
		(net "NC_INA230_1_NC5")
	)
	(segment
		(start 443.35446 -90.678508)
		(end 441.43803 -92.594938)
		(width 0.12954)
		(layer "F.Cu")
		(net "NC_INA230_1_NC5")
	)
	(via
		(at 443.35446 -90.678508)
		(size 0.762)
		(drill 0.381)
		(layers "F.Cu" "B.Cu")
		(net "NC_INA230_1_NC5")
	)
	(segment
		(start 441.57392 -90.952828)
		(end 440.937904 -91.588844)
		(width 0.12954)
		(layer "F.Cu")
		(net "NC_INA230_1_NC4")
	)
	(segment
		(start 440.937904 -91.588844)
		(end 440.937904 -92.677488)
		(width 0.12954)
		(layer "F.Cu")
		(net "NC_INA230_1_NC4")
	)
	(via
		(at 441.57392 -90.952828)
		(size 0.762)
		(drill 0.381)
		(layers "F.Cu" "B.Cu")
		(net "NC_INA230_1_NC4")
	)
	(segment
		(start 439.79338 -90.937588)
		(end 440.438032 -91.58224)
		(width 0.12954)
		(layer "F.Cu")
		(net "NC_INA230_1_NC3")
	)
	(segment
		(start 440.438032 -91.58224)
		(end 440.438032 -92.677488)
		(width 0.12954)
		(layer "F.Cu")
		(net "NC_INA230_1_NC3")
	)
	(via
		(at 439.79338 -90.937588)
		(size 0.762)
		(drill 0.381)
		(layers "F.Cu" "B.Cu")
		(net "NC_INA230_1_NC3")
	)
	(segment
		(start 439.13044 -98.306128)
		(end 439.937906 -97.498662)
		(width 0.12954)
		(layer "F.Cu")
		(net "NC_INA230_1_NC2")
	)
	(segment
		(start 439.937906 -97.498662)
		(end 439.937906 -95.477584)
		(width 0.12954)
		(layer "F.Cu")
		(net "NC_INA230_1_NC2")
	)
	(via
		(at 439.13044 -98.306128)
		(size 0.762)
		(drill 0.381)
		(layers "F.Cu" "B.Cu")
		(net "NC_INA230_1_NC2")
	)
	(segment
		(start 440.438032 -97.84588)
		(end 440.438032 -95.477584)
		(width 0.12954)
		(layer "F.Cu")
		(net "NC_INA230_1_NC1")
	)
	(segment
		(start 440.91098 -98.318828)
		(end 440.438032 -97.84588)
		(width 0.12954)
		(layer "F.Cu")
		(net "NC_INA230_1_NC1")
	)
	(via
		(at 440.91098 -98.318828)
		(size 0.762)
		(drill 0.381)
		(layers "F.Cu" "B.Cu")
		(net "NC_INA230_1_NC1")
	)
	(segment
		(start 442.66358 -98.326448)
		(end 440.937904 -96.600772)
		(width 0.12954)
		(layer "F.Cu")
		(net "NC_INA230_1_NC0")
	)
	(segment
		(start 440.937904 -96.600772)
		(end 440.937904 -95.477584)
		(width 0.12954)
		(layer "F.Cu")
		(net "NC_INA230_1_NC0")
	)
	(via
		(at 442.66358 -98.326448)
		(size 0.762)
		(drill 0.381)
		(layers "F.Cu" "B.Cu")
		(net "NC_INA230_1_NC0")
	)
	(via
		(at 265.61288 -150.284688)
		(size 0.762)
		(drill 0.254)
		(layers "F.Cu" "B.Cu")
		(net "H_CPU0_PMSYNC_CPU1_R1")
	)
	(via
		(at 170.1038 -189.643004)
		(size 0.508)
		(drill 0.254)
		(layers "F.Cu" "B.Cu")
		(net "H_CPU0_PMSYNC_CPU1_R1")
	)
	(via
		(at 145.302478 -146.619468)
		(size 0.508)
		(drill 0.254)
		(layers "F.Cu" "B.Cu")
		(net "H_CPU0_PMSYNC_CPU1_R1")
	)
	(via
		(at 387.604 -189.271148)
		(size 0.6604)
		(drill 0.3302)
		(layers "F.Cu" "B.Cu")
		(net "H_CPU0_PMSYNC_CPU1_R1")
	)
	(segment
		(start 166.199058 -191.997584)
		(end 167.880792 -190.31585)
		(width 0.12954)
		(layer "B.Cu")
		(net "H_CPU0_PMSYNC_CPU1_R1")
	)
	(segment
		(start 164.918898 -207.82915)
		(end 164.918898 -207.27035)
		(width 0.12954)
		(layer "B.Cu")
		(net "H_CPU0_PMSYNC_CPU1_R1")
	)
	(segment
		(start 159.567626 -238.40821)
		(end 164.26688 -236.461808)
		(width 0.12954)
		(layer "B.Cu")
		(net "H_CPU0_PMSYNC_CPU1_R1")
	)
	(segment
		(start 165.597078 -220.80601)
		(end 165.597078 -219.44457)
		(width 0.12954)
		(layer "B.Cu")
		(net "H_CPU0_PMSYNC_CPU1_R1")
	)
	(segment
		(start 386.709158 -187.110624)
		(end 375.94286 -176.33569)
		(width 0.12954)
		(layer "B.Cu")
		(net "H_CPU0_PMSYNC_CPU1_R1")
	)
	(segment
		(start 371.74678 -174.02937)
		(end 370.976398 -174.02937)
		(width 0.12954)
		(layer "B.Cu")
		(net "H_CPU0_PMSYNC_CPU1_R1")
	)
	(segment
		(start 374.962166 -176.33569)
		(end 373.410226 -175.69307)
		(width 0.12954)
		(layer "B.Cu")
		(net "H_CPU0_PMSYNC_CPU1_R1")
	)
	(segment
		(start 370.976398 -174.02937)
		(end 369.820952 -174.507906)
		(width 0.12954)
		(layer "B.Cu")
		(net "H_CPU0_PMSYNC_CPU1_R1")
	)
	(segment
		(start 265.61288 -147.792948)
		(end 265.61288 -150.284688)
		(width 0.12954)
		(layer "B.Cu")
		(net "H_CPU0_PMSYNC_CPU1_R1")
	)
	(segment
		(start 165.98646 -194.640708)
		(end 166.199058 -194.42811)
		(width 0.12954)
		(layer "B.Cu")
		(net "H_CPU0_PMSYNC_CPU1_R1")
	)
	(segment
		(start 387.90499 -189.572138)
		(end 387.604 -189.271148)
		(width 0.12954)
		(layer "B.Cu")
		(net "H_CPU0_PMSYNC_CPU1_R1")
	)
	(segment
		(start 164.725858 -208.02219)
		(end 164.918898 -207.82915)
		(width 0.12954)
		(layer "B.Cu")
		(net "H_CPU0_PMSYNC_CPU1_R1")
	)
	(segment
		(start 164.725858 -221.67723)
		(end 165.597078 -220.80601)
		(width 0.12954)
		(layer "B.Cu")
		(net "H_CPU0_PMSYNC_CPU1_R1")
	)
	(segment
		(start 368.744246 -174.507906)
		(end 362.0643 -167.82796)
		(width 0.12954)
		(layer "B.Cu")
		(net "H_CPU0_PMSYNC_CPU1_R1")
	)
	(segment
		(start 164.725858 -207.07731)
		(end 164.725858 -206.32039)
		(width 0.12954)
		(layer "B.Cu")
		(net "H_CPU0_PMSYNC_CPU1_R1")
	)
	(segment
		(start 166.199058 -194.42811)
		(end 166.199058 -191.997584)
		(width 0.12954)
		(layer "B.Cu")
		(net "H_CPU0_PMSYNC_CPU1_R1")
	)
	(segment
		(start 167.880792 -190.31585)
		(end 169.323258 -190.31585)
		(width 0.12954)
		(layer "B.Cu")
		(net "H_CPU0_PMSYNC_CPU1_R1")
	)
	(segment
		(start 165.597078 -219.44457)
		(end 164.725858 -218.57335)
		(width 0.12954)
		(layer "B.Cu")
		(net "H_CPU0_PMSYNC_CPU1_R1")
	)
	(segment
		(start 164.725858 -205.31455)
		(end 164.725858 -201.03211)
		(width 0.12954)
		(layer "B.Cu")
		(net "H_CPU0_PMSYNC_CPU1_R1")
	)
	(segment
		(start 362.0643 -167.82796)
		(end 348.599252 -162.25012)
		(width 0.12954)
		(layer "B.Cu")
		(net "H_CPU0_PMSYNC_CPU1_R1")
	)
	(segment
		(start 169.996104 -189.643004)
		(end 170.1038 -189.643004)
		(width 0.12954)
		(layer "B.Cu")
		(net "H_CPU0_PMSYNC_CPU1_R1")
	)
	(segment
		(start 164.918898 -207.27035)
		(end 164.725858 -207.07731)
		(width 0.12954)
		(layer "B.Cu")
		(net "H_CPU0_PMSYNC_CPU1_R1")
	)
	(segment
		(start 375.94286 -176.33569)
		(end 374.962166 -176.33569)
		(width 0.12954)
		(layer "B.Cu")
		(net "H_CPU0_PMSYNC_CPU1_R1")
	)
	(segment
		(start 340.390988 -154.041856)
		(end 320.889884 -145.964148)
		(width 0.12954)
		(layer "B.Cu")
		(net "H_CPU0_PMSYNC_CPU1_R1")
	)
	(segment
		(start 164.725858 -216.35085)
		(end 164.725858 -208.02219)
		(width 0.12954)
		(layer "B.Cu")
		(net "H_CPU0_PMSYNC_CPU1_R1")
	)
	(segment
		(start 164.725858 -206.32039)
		(end 165.048438 -205.99781)
		(width 0.12954)
		(layer "B.Cu")
		(net "H_CPU0_PMSYNC_CPU1_R1")
	)
	(segment
		(start 169.323258 -190.31585)
		(end 169.996104 -189.643004)
		(width 0.12954)
		(layer "B.Cu")
		(net "H_CPU0_PMSYNC_CPU1_R1")
	)
	(segment
		(start 164.995098 -216.62009)
		(end 164.725858 -216.35085)
		(width 0.12954)
		(layer "B.Cu")
		(net "H_CPU0_PMSYNC_CPU1_R1")
	)
	(segment
		(start 164.725858 -218.57335)
		(end 164.725858 -217.40495)
		(width 0.12954)
		(layer "B.Cu")
		(net "H_CPU0_PMSYNC_CPU1_R1")
	)
	(segment
		(start 320.889884 -145.964148)
		(end 267.44168 -145.964148)
		(width 0.12954)
		(layer "B.Cu")
		(net "H_CPU0_PMSYNC_CPU1_R1")
	)
	(segment
		(start 387.604 -189.271148)
		(end 386.709158 -187.110624)
		(width 0.12954)
		(layer "B.Cu")
		(net "H_CPU0_PMSYNC_CPU1_R1")
	)
	(segment
		(start 348.599252 -162.25012)
		(end 340.390988 -154.041856)
		(width 0.12954)
		(layer "B.Cu")
		(net "H_CPU0_PMSYNC_CPU1_R1")
	)
	(segment
		(start 369.820952 -174.507906)
		(end 368.744246 -174.507906)
		(width 0.12954)
		(layer "B.Cu")
		(net "H_CPU0_PMSYNC_CPU1_R1")
	)
	(segment
		(start 164.725858 -201.03211)
		(end 165.98646 -199.771508)
		(width 0.12954)
		(layer "B.Cu")
		(net "H_CPU0_PMSYNC_CPU1_R1")
	)
	(segment
		(start 164.26688 -236.461808)
		(end 164.725858 -236.00283)
		(width 0.12954)
		(layer "B.Cu")
		(net "H_CPU0_PMSYNC_CPU1_R1")
	)
	(segment
		(start 156.51353 -238.40821)
		(end 159.567626 -238.40821)
		(width 0.12954)
		(layer "B.Cu")
		(net "H_CPU0_PMSYNC_CPU1_R1")
	)
	(segment
		(start 164.995098 -217.13571)
		(end 164.995098 -216.62009)
		(width 0.12954)
		(layer "B.Cu")
		(net "H_CPU0_PMSYNC_CPU1_R1")
	)
	(segment
		(start 387.90499 -190.42126)
		(end 387.90499 -189.572138)
		(width 0.12954)
		(layer "B.Cu")
		(net "H_CPU0_PMSYNC_CPU1_R1")
	)
	(segment
		(start 165.048438 -205.63713)
		(end 164.725858 -205.31455)
		(width 0.12954)
		(layer "B.Cu")
		(net "H_CPU0_PMSYNC_CPU1_R1")
	)
	(segment
		(start 156.192982 -238.728758)
		(end 156.51353 -238.40821)
		(width 0.12954)
		(layer "B.Cu")
		(net "H_CPU0_PMSYNC_CPU1_R1")
	)
	(segment
		(start 373.410226 -175.69307)
		(end 371.74678 -174.02937)
		(width 0.12954)
		(layer "B.Cu")
		(net "H_CPU0_PMSYNC_CPU1_R1")
	)
	(segment
		(start 164.725858 -236.00283)
		(end 164.725858 -221.67723)
		(width 0.12954)
		(layer "B.Cu")
		(net "H_CPU0_PMSYNC_CPU1_R1")
	)
	(segment
		(start 165.048438 -205.99781)
		(end 165.048438 -205.63713)
		(width 0.12954)
		(layer "B.Cu")
		(net "H_CPU0_PMSYNC_CPU1_R1")
	)
	(segment
		(start 164.725858 -217.40495)
		(end 164.995098 -217.13571)
		(width 0.12954)
		(layer "B.Cu")
		(net "H_CPU0_PMSYNC_CPU1_R1")
	)
	(segment
		(start 165.98646 -199.771508)
		(end 165.98646 -194.640708)
		(width 0.12954)
		(layer "B.Cu")
		(net "H_CPU0_PMSYNC_CPU1_R1")
	)
	(segment
		(start 267.44168 -145.964148)
		(end 265.61288 -147.792948)
		(width 0.12954)
		(layer "B.Cu")
		(net "H_CPU0_PMSYNC_CPU1_R1")
	)
	(segment
		(start 145.302478 -163.35883)
		(end 145.302478 -146.619468)
		(width 0.127)
		(layer "In2.Cu")
		(net "H_CPU0_PMSYNC_CPU1_R1")
	)
	(segment
		(start 170.1038 -189.643004)
		(end 170.1038 -188.160152)
		(width 0.127)
		(layer "In2.Cu")
		(net "H_CPU0_PMSYNC_CPU1_R1")
	)
	(segment
		(start 170.1038 -188.160152)
		(end 145.302478 -163.35883)
		(width 0.127)
		(layer "In2.Cu")
		(net "H_CPU0_PMSYNC_CPU1_R1")
	)
	(segment
		(start 264.97788 -150.967948)
		(end 264.97788 -151.856948)
		(width 0.127)
		(layer "In13.Cu")
		(net "H_CPU0_PMSYNC_CPU1_R1")
	)
	(segment
		(start 177.01006 -164.76218)
		(end 176.4538 -164.20592)
		(width 0.127)
		(layer "In13.Cu")
		(net "H_CPU0_PMSYNC_CPU1_R1")
	)
	(segment
		(start 265.61288 -153.380948)
		(end 262.156448 -156.83738)
		(width 0.127)
		(layer "In13.Cu")
		(net "H_CPU0_PMSYNC_CPU1_R1")
	)
	(segment
		(start 264.97788 -151.856948)
		(end 265.61288 -152.491948)
		(width 0.127)
		(layer "In13.Cu")
		(net "H_CPU0_PMSYNC_CPU1_R1")
	)
	(segment
		(start 170.691048 -151.999188)
		(end 150.682198 -151.999188)
		(width 0.127)
		(layer "In13.Cu")
		(net "H_CPU0_PMSYNC_CPU1_R1")
	)
	(segment
		(start 265.61288 -150.332948)
		(end 264.97788 -150.967948)
		(width 0.127)
		(layer "In13.Cu")
		(net "H_CPU0_PMSYNC_CPU1_R1")
	)
	(segment
		(start 150.682198 -151.999188)
		(end 145.302478 -146.619468)
		(width 0.127)
		(layer "In13.Cu")
		(net "H_CPU0_PMSYNC_CPU1_R1")
	)
	(segment
		(start 176.4538 -164.20592)
		(end 176.4538 -157.76194)
		(width 0.127)
		(layer "In13.Cu")
		(net "H_CPU0_PMSYNC_CPU1_R1")
	)
	(segment
		(start 216.79916 -156.83738)
		(end 208.87436 -164.76218)
		(width 0.127)
		(layer "In13.Cu")
		(net "H_CPU0_PMSYNC_CPU1_R1")
	)
	(segment
		(start 265.61288 -150.284688)
		(end 265.61288 -150.332948)
		(width 0.127)
		(layer "In13.Cu")
		(net "H_CPU0_PMSYNC_CPU1_R1")
	)
	(segment
		(start 262.156448 -156.83738)
		(end 216.79916 -156.83738)
		(width 0.127)
		(layer "In13.Cu")
		(net "H_CPU0_PMSYNC_CPU1_R1")
	)
	(segment
		(start 265.61288 -152.491948)
		(end 265.61288 -153.380948)
		(width 0.127)
		(layer "In13.Cu")
		(net "H_CPU0_PMSYNC_CPU1_R1")
	)
	(segment
		(start 208.87436 -164.76218)
		(end 177.01006 -164.76218)
		(width 0.127)
		(layer "In13.Cu")
		(net "H_CPU0_PMSYNC_CPU1_R1")
	)
	(segment
		(start 176.4538 -157.76194)
		(end 170.691048 -151.999188)
		(width 0.127)
		(layer "In13.Cu")
		(net "H_CPU0_PMSYNC_CPU1_R1")
	)
	(segment
		(start 145.94713 -12.295378)
		(end 146.13382 -12.108688)
		(width 0.12954)
		(layer "F.Cu")
		(net "FM_JTAG_BMC_MUX_SEL_FROM_BMC_R2")
	)
	(segment
		(start 145.94713 -13.600176)
		(end 145.94713 -12.295378)
		(width 0.12954)
		(layer "F.Cu")
		(net "FM_JTAG_BMC_MUX_SEL_FROM_BMC_R2")
	)
	(via
		(at 146.13382 -12.108688)
		(size 0.508)
		(drill 0.254)
		(layers "F.Cu" "B.Cu")
		(net "FM_JTAG_BMC_MUX_SEL_FROM_BMC_R2")
	)
	(segment
		(start 146.13382 -12.108688)
		(end 146.3548 -12.329668)
		(width 0.12954)
		(layer "B.Cu")
		(net "FM_JTAG_BMC_MUX_SEL_FROM_BMC_R2")
	)
	(segment
		(start 146.3548 -12.329668)
		(end 146.3548 -13.372338)
		(width 0.12954)
		(layer "B.Cu")
		(net "FM_JTAG_BMC_MUX_SEL_FROM_BMC_R2")
	)
	(via
		(at 147.0406 -15.331948)
		(size 0.6604)
		(drill 0.3302)
		(layers "F.Cu" "B.Cu")
		(net "FM_JTAG_BMC_MUX_SEL_FROM_BMC_R")
	)
	(segment
		(start 146.3548 -14.646148)
		(end 146.3548 -14.172438)
		(width 0.12954)
		(layer "B.Cu")
		(net "FM_JTAG_BMC_MUX_SEL_FROM_BMC_R")
	)
	(segment
		(start 147.0406 -15.331948)
		(end 146.3548 -14.646148)
		(width 0.12954)
		(layer "B.Cu")
		(net "FM_JTAG_BMC_MUX_SEL_FROM_BMC_R")
	)
	(segment
		(start 147.70608 -14.182598)
		(end 147.70608 -14.666468)
		(width 0.12954)
		(layer "B.Cu")
		(net "FM_JTAG_BMC_MUX_SEL_FROM_BMC_R")
	)
	(segment
		(start 147.70608 -14.666468)
		(end 147.0406 -15.331948)
		(width 0.12954)
		(layer "B.Cu")
		(net "FM_JTAG_BMC_MUX_SEL_FROM_BMC_R")
	)
	(segment
		(start 476.462344 -256.373376)
		(end 476.462344 -331.21092)
		(width 0.127)
		(layer "In15.Cu")
		(net "TDR_SE_50_OHM_IN6")
	)
	(segment
		(start 478.73666 -256.128012)
		(end 476.707708 -256.128012)
		(width 0.127)
		(layer "In15.Cu")
		(net "TDR_SE_50_OHM_IN6")
	)
	(segment
		(start 476.707708 -256.128012)
		(end 476.462344 -256.373376)
		(width 0.127)
		(layer "In15.Cu")
		(net "TDR_SE_50_OHM_IN6")
	)
	(segment
		(start 479.002344 -331.21092)
		(end 479.002344 -256.393696)
		(width 0.127)
		(layer "In15.Cu")
		(net "TDR_SE_50_OHM_IN6")
	)
	(segment
		(start 479.002344 -256.393696)
		(end 478.73666 -256.128012)
		(width 0.127)
		(layer "In15.Cu")
		(net "TDR_SE_50_OHM_IN6")
	)
	(segment
		(start 479.08591 -423.931842)
		(end 479.08591 -349.114618)
		(width 0.127)
		(layer "In13.Cu")
		(net "TDR_SE_50_OHM_IN5")
	)
	(segment
		(start 476.54591 -349.094298)
		(end 476.54591 -423.931842)
		(width 0.127)
		(layer "In13.Cu")
		(net "TDR_SE_50_OHM_IN5")
	)
	(segment
		(start 479.08591 -349.114618)
		(end 478.820226 -348.848934)
		(width 0.127)
		(layer "In13.Cu")
		(net "TDR_SE_50_OHM_IN5")
	)
	(segment
		(start 476.791274 -348.848934)
		(end 476.54591 -349.094298)
		(width 0.127)
		(layer "In13.Cu")
		(net "TDR_SE_50_OHM_IN5")
	)
	(segment
		(start 478.820226 -348.848934)
		(end 476.791274 -348.848934)
		(width 0.127)
		(layer "In13.Cu")
		(net "TDR_SE_50_OHM_IN5")
	)
	(segment
		(start 489.260896 -421.211248)
		(end 491.301024 -421.211248)
		(width 0.18288)
		(layer "In15.Cu")
		(net "TDR_SE_40_OHM_IN6")
	)
	(segment
		(start 489.0008 -346.133928)
		(end 489.0008 -420.951152)
		(width 0.18288)
		(layer "In15.Cu")
		(net "TDR_SE_40_OHM_IN6")
	)
	(segment
		(start 491.5408 -420.971472)
		(end 491.5408 -346.133928)
		(width 0.18288)
		(layer "In15.Cu")
		(net "TDR_SE_40_OHM_IN6")
	)
	(segment
		(start 489.0008 -420.951152)
		(end 489.260896 -421.211248)
		(width 0.18288)
		(layer "In15.Cu")
		(net "TDR_SE_40_OHM_IN6")
	)
	(segment
		(start 491.301024 -421.211248)
		(end 491.5408 -420.971472)
		(width 0.18288)
		(layer "In15.Cu")
		(net "TDR_SE_40_OHM_IN6")
	)
	(segment
		(start 499.50497 -349.32874)
		(end 499.50497 -424.166284)
		(width 0.18288)
		(layer "In13.Cu")
		(net "TDR_SE_40_OHM_IN5")
	)
	(segment
		(start 501.769634 -349.073724)
		(end 499.759986 -349.073724)
		(width 0.18288)
		(layer "In13.Cu")
		(net "TDR_SE_40_OHM_IN5")
	)
	(segment
		(start 502.04497 -424.166284)
		(end 502.04497 -349.34906)
		(width 0.18288)
		(layer "In13.Cu")
		(net "TDR_SE_40_OHM_IN5")
	)
	(segment
		(start 499.759986 -349.073724)
		(end 499.50497 -349.32874)
		(width 0.18288)
		(layer "In13.Cu")
		(net "TDR_SE_40_OHM_IN5")
	)
	(segment
		(start 502.04497 -349.34906)
		(end 501.769634 -349.073724)
		(width 0.18288)
		(layer "In13.Cu")
		(net "TDR_SE_40_OHM_IN5")
	)
	(segment
		(start 500.248428 -153.16454)
		(end 501.233948 -153.16454)
		(width 0.14732)
		(layer "In15.Cu")
		(net "TDR_DIFF_85_IN6_DP")
	)
	(segment
		(start 500.101108 -303.43602)
		(end 500.101108 -153.31186)
		(width 0.14732)
		(layer "In15.Cu")
		(net "TDR_DIFF_85_IN6_DP")
	)
	(segment
		(start 501.233948 -303.58334)
		(end 500.248428 -303.58334)
		(width 0.14732)
		(layer "In15.Cu")
		(net "TDR_DIFF_85_IN6_DP")
	)
	(segment
		(start 500.248428 -303.58334)
		(end 500.101108 -303.43602)
		(width 0.14732)
		(layer "In15.Cu")
		(net "TDR_DIFF_85_IN6_DP")
	)
	(segment
		(start 500.101108 -153.31186)
		(end 500.248428 -153.16454)
		(width 0.14732)
		(layer "In15.Cu")
		(net "TDR_DIFF_85_IN6_DP")
	)
	(segment
		(start 499.679468 -153.16454)
		(end 498.693948 -153.16454)
		(width 0.14732)
		(layer "In15.Cu")
		(net "TDR_DIFF_85_IN6_DN")
	)
	(segment
		(start 499.826788 -153.31186)
		(end 499.679468 -153.16454)
		(width 0.14732)
		(layer "In15.Cu")
		(net "TDR_DIFF_85_IN6_DN")
	)
	(segment
		(start 499.826788 -303.43602)
		(end 499.826788 -153.31186)
		(width 0.14732)
		(layer "In15.Cu")
		(net "TDR_DIFF_85_IN6_DN")
	)
	(segment
		(start 498.693948 -303.58334)
		(end 499.679468 -303.58334)
		(width 0.14732)
		(layer "In15.Cu")
		(net "TDR_DIFF_85_IN6_DN")
	)
	(segment
		(start 499.679468 -303.58334)
		(end 499.826788 -303.43602)
		(width 0.14732)
		(layer "In15.Cu")
		(net "TDR_DIFF_85_IN6_DN")
	)
	(segment
		(start 510.517648 -303.43856)
		(end 510.517648 -153.3144)
		(width 0.14732)
		(layer "In13.Cu")
		(net "TDR_DIFF_85_IN5_DP")
	)
	(segment
		(start 510.517648 -153.3144)
		(end 510.370328 -153.16708)
		(width 0.14732)
		(layer "In13.Cu")
		(net "TDR_DIFF_85_IN5_DP")
	)
	(segment
		(start 510.370328 -153.16708)
		(end 509.384808 -153.16708)
		(width 0.14732)
		(layer "In13.Cu")
		(net "TDR_DIFF_85_IN5_DP")
	)
	(segment
		(start 510.370328 -303.58588)
		(end 510.517648 -303.43856)
		(width 0.14732)
		(layer "In13.Cu")
		(net "TDR_DIFF_85_IN5_DP")
	)
	(segment
		(start 509.384808 -303.58588)
		(end 510.370328 -303.58588)
		(width 0.14732)
		(layer "In13.Cu")
		(net "TDR_DIFF_85_IN5_DP")
	)
	(segment
		(start 510.791968 -303.43856)
		(end 510.791968 -153.3144)
		(width 0.14732)
		(layer "In13.Cu")
		(net "TDR_DIFF_85_IN5_DN")
	)
	(segment
		(start 510.791968 -153.3144)
		(end 510.939288 -153.16708)
		(width 0.14732)
		(layer "In13.Cu")
		(net "TDR_DIFF_85_IN5_DN")
	)
	(segment
		(start 510.939288 -153.16708)
		(end 511.924808 -153.16708)
		(width 0.14732)
		(layer "In13.Cu")
		(net "TDR_DIFF_85_IN5_DN")
	)
	(segment
		(start 511.924808 -303.58588)
		(end 510.939288 -303.58588)
		(width 0.14732)
		(layer "In13.Cu")
		(net "TDR_DIFF_85_IN5_DN")
	)
	(segment
		(start 510.939288 -303.58588)
		(end 510.791968 -303.43856)
		(width 0.14732)
		(layer "In13.Cu")
		(net "TDR_DIFF_85_IN5_DN")
	)
	(segment
		(start 493.36833 -148.094192)
		(end 494.333276 -148.094192)
		(width 0.12446)
		(layer "In15.Cu")
		(net "TDR_DIFF_100_IN6_DP")
	)
	(segment
		(start 494.30178 2.324608)
		(end 493.36833 2.324608)
		(width 0.12446)
		(layer "In15.Cu")
		(net "TDR_DIFF_100_IN6_DP")
	)
	(segment
		(start 494.42624 -148.001228)
		(end 494.42624 2.200148)
		(width 0.12446)
		(layer "In15.Cu")
		(net "TDR_DIFF_100_IN6_DP")
	)
	(segment
		(start 494.42624 2.200148)
		(end 494.30178 2.324608)
		(width 0.12446)
		(layer "In15.Cu")
		(net "TDR_DIFF_100_IN6_DP")
	)
	(segment
		(start 494.333276 -148.094192)
		(end 494.42624 -148.001228)
		(width 0.12446)
		(layer "In15.Cu")
		(net "TDR_DIFF_100_IN6_DP")
	)
	(segment
		(start 494.85042 -147.991068)
		(end 494.85042 2.200148)
		(width 0.12446)
		(layer "In15.Cu")
		(net "TDR_DIFF_100_IN6_DN")
	)
	(segment
		(start 494.85042 2.200148)
		(end 494.97488 2.324608)
		(width 0.12446)
		(layer "In15.Cu")
		(net "TDR_DIFF_100_IN6_DN")
	)
	(segment
		(start 494.97488 2.324608)
		(end 495.90833 2.324608)
		(width 0.12446)
		(layer "In15.Cu")
		(net "TDR_DIFF_100_IN6_DN")
	)
	(segment
		(start 495.90833 -148.094192)
		(end 494.953544 -148.094192)
		(width 0.12446)
		(layer "In15.Cu")
		(net "TDR_DIFF_100_IN6_DN")
	)
	(segment
		(start 494.953544 -148.094192)
		(end 494.85042 -147.991068)
		(width 0.12446)
		(layer "In15.Cu")
		(net "TDR_DIFF_100_IN6_DN")
	)
	(segment
		(start 505.540518 2.20726)
		(end 505.664978 2.33172)
		(width 0.12446)
		(layer "In13.Cu")
		(net "TDR_DIFF_100_IN5_DP")
	)
	(segment
		(start 505.540518 -147.983956)
		(end 505.540518 2.20726)
		(width 0.12446)
		(layer "In13.Cu")
		(net "TDR_DIFF_100_IN5_DP")
	)
	(segment
		(start 506.598428 -148.08708)
		(end 505.643642 -148.08708)
		(width 0.12446)
		(layer "In13.Cu")
		(net "TDR_DIFF_100_IN5_DP")
	)
	(segment
		(start 505.643642 -148.08708)
		(end 505.540518 -147.983956)
		(width 0.12446)
		(layer "In13.Cu")
		(net "TDR_DIFF_100_IN5_DP")
	)
	(segment
		(start 505.664978 2.33172)
		(end 506.598428 2.33172)
		(width 0.12446)
		(layer "In13.Cu")
		(net "TDR_DIFF_100_IN5_DP")
	)
	(segment
		(start 505.116338 -147.994116)
		(end 505.116338 2.20726)
		(width 0.12446)
		(layer "In13.Cu")
		(net "TDR_DIFF_100_IN5_DN")
	)
	(segment
		(start 505.116338 2.20726)
		(end 504.991878 2.33172)
		(width 0.12446)
		(layer "In13.Cu")
		(net "TDR_DIFF_100_IN5_DN")
	)
	(segment
		(start 504.058428 -148.08708)
		(end 505.023374 -148.08708)
		(width 0.12446)
		(layer "In13.Cu")
		(net "TDR_DIFF_100_IN5_DN")
	)
	(segment
		(start 504.991878 2.33172)
		(end 504.058428 2.33172)
		(width 0.12446)
		(layer "In13.Cu")
		(net "TDR_DIFF_100_IN5_DN")
	)
	(segment
		(start 505.023374 -148.08708)
		(end 505.116338 -147.994116)
		(width 0.12446)
		(layer "In13.Cu")
		(net "TDR_DIFF_100_IN5_DN")
	)
	(segment
		(start 444.078614 -71.998078)
		(end 443.576964 -71.998078)
		(width 0.12954)
		(layer "F.Cu")
		(net "P3V3_AUX_VDRV")
	)
	(segment
		(start 443.576964 -71.0692)
		(end 443.576964 -71.998078)
		(width 0.12954)
		(layer "F.Cu")
		(net "P3V3_AUX_VDRV")
	)
	(segment
		(start 444.715138 -72.634602)
		(end 444.078614 -71.998078)
		(width 0.12954)
		(layer "F.Cu")
		(net "P3V3_AUX_VDRV")
	)
	(segment
		(start 446.068958 -73.277476)
		(end 445.358012 -73.277476)
		(width 0.12954)
		(layer "F.Cu")
		(net "P3V3_AUX_VDRV")
	)
	(segment
		(start 445.358012 -73.277476)
		(end 444.715138 -72.634602)
		(width 0.12954)
		(layer "F.Cu")
		(net "P3V3_AUX_VDRV")
	)
	(segment
		(start 443.606936 -71.039228)
		(end 443.576964 -71.0692)
		(width 0.12954)
		(layer "F.Cu")
		(net "P3V3_AUX_VDRV")
	)
	(via
		(at 443.606936 -71.039228)
		(size 0.508)
		(drill 0.254)
		(layers "F.Cu" "B.Cu")
		(net "P3V3_AUX_VDRV")
	)
	(segment
		(start 334.898746 -34.035746)
		(end 334.898746 -37.63518)
		(width 0.0889)
		(layer "F.Cu")
		(net "E1S_0_CLKREQ_N")
	)
	(segment
		(start 223.83115 -51.0921)
		(end 223.83115 -49.71288)
		(width 0.12954)
		(layer "F.Cu")
		(net "E1S_0_CLKREQ_N")
	)
	(segment
		(start 223.004634 -49.949608)
		(end 223.594422 -49.949608)
		(width 0.12954)
		(layer "F.Cu")
		(net "E1S_0_CLKREQ_N")
	)
	(segment
		(start 334.049624 -33.186624)
		(end 334.898746 -34.035746)
		(width 0.0889)
		(layer "F.Cu")
		(net "E1S_0_CLKREQ_N")
	)
	(segment
		(start 223.594422 -49.949608)
		(end 223.83115 -49.71288)
		(width 0.12954)
		(layer "F.Cu")
		(net "E1S_0_CLKREQ_N")
	)
	(via
		(at 310.6674 -33.1978)
		(size 0.508)
		(drill 0.254)
		(layers "F.Cu" "B.Cu")
		(net "E1S_0_CLKREQ_N")
	)
	(via
		(at 223.004634 -49.949608)
		(size 0.508)
		(drill 0.254)
		(layers "F.Cu" "B.Cu")
		(net "E1S_0_CLKREQ_N")
	)
	(via
		(at 334.049624 -33.186624)
		(size 0.508)
		(drill 0.254)
		(layers "F.Cu" "B.Cu")
		(net "E1S_0_CLKREQ_N")
	)
	(via
		(at 237.605316 -61.253116)
		(size 0.508)
		(drill 0.254)
		(layers "F.Cu" "B.Cu")
		(net "E1S_0_CLKREQ_N")
	)
	(segment
		(start 309.95747 -33.22574)
		(end 310.63946 -33.22574)
		(width 0.12954)
		(layer "B.Cu")
		(net "E1S_0_CLKREQ_N")
	)
	(segment
		(start 310.63946 -33.22574)
		(end 310.6674 -33.1978)
		(width 0.12954)
		(layer "B.Cu")
		(net "E1S_0_CLKREQ_N")
	)
	(segment
		(start 237.919768 -61.567568)
		(end 237.605316 -61.253116)
		(width 0.127)
		(layer "In4.Cu")
		(net "E1S_0_CLKREQ_N")
	)
	(segment
		(start 326.940926 -37.668454)
		(end 330.591922 -37.668454)
		(width 0.127)
		(layer "In4.Cu")
		(net "E1S_0_CLKREQ_N")
	)
	(segment
		(start 280.8351 -49.418494)
		(end 277.484078 -57.508394)
		(width 0.127)
		(layer "In4.Cu")
		(net "E1S_0_CLKREQ_N")
	)
	(segment
		(start 312.843164 -33.866836)
		(end 319.110868 -33.866836)
		(width 0.127)
		(layer "In4.Cu")
		(net "E1S_0_CLKREQ_N")
	)
	(segment
		(start 305.584352 -37.313108)
		(end 292.940486 -37.313108)
		(width 0.127)
		(layer "In4.Cu")
		(net "E1S_0_CLKREQ_N")
	)
	(segment
		(start 239.586008 -63.24981)
		(end 237.919768 -61.58357)
		(width 0.127)
		(layer "In4.Cu")
		(net "E1S_0_CLKREQ_N")
	)
	(segment
		(start 325.5137 -37.447982)
		(end 325.6915 -37.270182)
		(width 0.127)
		(layer "In4.Cu")
		(net "E1S_0_CLKREQ_N")
	)
	(segment
		(start 325.6915 -37.270182)
		(end 326.542654 -37.270182)
		(width 0.127)
		(layer "In4.Cu")
		(net "E1S_0_CLKREQ_N")
	)
	(segment
		(start 322.692014 -37.447982)
		(end 325.5137 -37.447982)
		(width 0.127)
		(layer "In4.Cu")
		(net "E1S_0_CLKREQ_N")
	)
	(segment
		(start 330.591922 -37.668454)
		(end 332.96098 -35.299396)
		(width 0.127)
		(layer "In4.Cu")
		(net "E1S_0_CLKREQ_N")
	)
	(segment
		(start 275.752306 -59.240166)
		(end 271.511522 -62.073536)
		(width 0.127)
		(layer "In4.Cu")
		(net "E1S_0_CLKREQ_N")
	)
	(segment
		(start 310.6674 -33.1978)
		(end 312.174128 -33.1978)
		(width 0.127)
		(layer "In4.Cu")
		(net "E1S_0_CLKREQ_N")
	)
	(segment
		(start 333.67345 -33.186624)
		(end 334.049624 -33.186624)
		(width 0.127)
		(layer "In4.Cu")
		(net "E1S_0_CLKREQ_N")
	)
	(segment
		(start 319.110868 -33.866836)
		(end 322.692014 -37.447982)
		(width 0.127)
		(layer "In4.Cu")
		(net "E1S_0_CLKREQ_N")
	)
	(segment
		(start 309.69966 -33.1978)
		(end 305.584352 -37.313108)
		(width 0.127)
		(layer "In4.Cu")
		(net "E1S_0_CLKREQ_N")
	)
	(segment
		(start 277.484078 -57.508394)
		(end 275.752306 -59.240166)
		(width 0.127)
		(layer "In4.Cu")
		(net "E1S_0_CLKREQ_N")
	)
	(segment
		(start 292.940486 -37.313108)
		(end 280.8351 -49.418494)
		(width 0.127)
		(layer "In4.Cu")
		(net "E1S_0_CLKREQ_N")
	)
	(segment
		(start 271.511522 -62.073536)
		(end 268.671802 -63.24981)
		(width 0.127)
		(layer "In4.Cu")
		(net "E1S_0_CLKREQ_N")
	)
	(segment
		(start 237.919768 -61.58357)
		(end 237.919768 -61.567568)
		(width 0.127)
		(layer "In4.Cu")
		(net "E1S_0_CLKREQ_N")
	)
	(segment
		(start 310.6674 -33.1978)
		(end 309.69966 -33.1978)
		(width 0.127)
		(layer "In4.Cu")
		(net "E1S_0_CLKREQ_N")
	)
	(segment
		(start 268.671802 -63.24981)
		(end 239.586008 -63.24981)
		(width 0.127)
		(layer "In4.Cu")
		(net "E1S_0_CLKREQ_N")
	)
	(segment
		(start 312.174128 -33.1978)
		(end 312.843164 -33.866836)
		(width 0.127)
		(layer "In4.Cu")
		(net "E1S_0_CLKREQ_N")
	)
	(segment
		(start 326.542654 -37.270182)
		(end 326.940926 -37.668454)
		(width 0.127)
		(layer "In4.Cu")
		(net "E1S_0_CLKREQ_N")
	)
	(segment
		(start 332.96098 -35.299396)
		(end 332.96098 -33.899094)
		(width 0.127)
		(layer "In4.Cu")
		(net "E1S_0_CLKREQ_N")
	)
	(segment
		(start 332.96098 -33.899094)
		(end 333.67345 -33.186624)
		(width 0.127)
		(layer "In4.Cu")
		(net "E1S_0_CLKREQ_N")
	)
	(segment
		(start 223.554036 -49.949608)
		(end 224.37979 -50.775362)
		(width 0.127)
		(layer "In13.Cu")
		(net "E1S_0_CLKREQ_N")
	)
	(segment
		(start 224.37979 -50.775362)
		(end 224.37979 -54.609746)
		(width 0.127)
		(layer "In13.Cu")
		(net "E1S_0_CLKREQ_N")
	)
	(segment
		(start 237.561882 -60.2996)
		(end 237.561882 -60.765182)
		(width 0.127)
		(layer "In13.Cu")
		(net "E1S_0_CLKREQ_N")
	)
	(segment
		(start 233.491024 -58.748676)
		(end 236.010958 -58.748676)
		(width 0.127)
		(layer "In13.Cu")
		(net "E1S_0_CLKREQ_N")
	)
	(segment
		(start 232.564686 -59.675014)
		(end 233.491024 -58.748676)
		(width 0.127)
		(layer "In13.Cu")
		(net "E1S_0_CLKREQ_N")
	)
	(segment
		(start 229.150926 -58.659014)
		(end 230.166926 -59.675014)
		(width 0.127)
		(layer "In13.Cu")
		(net "E1S_0_CLKREQ_N")
	)
	(segment
		(start 223.004634 -49.949608)
		(end 223.554036 -49.949608)
		(width 0.127)
		(layer "In13.Cu")
		(net "E1S_0_CLKREQ_N")
	)
	(segment
		(start 230.166926 -59.675014)
		(end 232.564686 -59.675014)
		(width 0.127)
		(layer "In13.Cu")
		(net "E1S_0_CLKREQ_N")
	)
	(segment
		(start 224.37979 -54.609746)
		(end 228.429058 -58.659014)
		(width 0.127)
		(layer "In13.Cu")
		(net "E1S_0_CLKREQ_N")
	)
	(segment
		(start 228.429058 -58.659014)
		(end 229.150926 -58.659014)
		(width 0.127)
		(layer "In13.Cu")
		(net "E1S_0_CLKREQ_N")
	)
	(segment
		(start 236.010958 -58.748676)
		(end 237.561882 -60.2996)
		(width 0.127)
		(layer "In13.Cu")
		(net "E1S_0_CLKREQ_N")
	)
	(segment
		(start 237.605316 -60.808616)
		(end 237.605316 -61.253116)
		(width 0.127)
		(layer "In13.Cu")
		(net "E1S_0_CLKREQ_N")
	)
	(segment
		(start 237.561882 -60.765182)
		(end 237.605316 -60.808616)
		(width 0.127)
		(layer "In13.Cu")
		(net "E1S_0_CLKREQ_N")
	)
	(segment
		(start 377.274074 3.17373)
		(end 376.5931 3.355594)
		(width 0.13208)
		(layer "B.Cu")
		(net "DELTA_L_85_5INCH_IN6_DP")
	)
	(segment
		(start 340.124034 3.17373)
		(end 340.805008 3.355594)
		(width 0.13208)
		(layer "B.Cu")
		(net "DELTA_L_85_5INCH_IN6_DP")
	)
	(segment
		(start 358.20985 5.664708)
		(end 359.792016 5.385816)
		(width 0.14732)
		(layer "In15.Cu")
		(net "DELTA_L_85_5INCH_IN6_DP")
	)
	(segment
		(start 359.002584 -0.865124)
		(end 359.121964 -1.035304)
		(width 0.14732)
		(layer "In15.Cu")
		(net "DELTA_L_85_5INCH_IN6_DP")
	)
	(segment
		(start 362.167932 5.674868)
		(end 363.750352 5.395722)
		(width 0.14732)
		(layer "In15.Cu")
		(net "DELTA_L_85_5INCH_IN6_DP")
	)
	(segment
		(start 350.295718 5.660644)
		(end 351.878392 5.381752)
		(width 0.14732)
		(layer "In15.Cu")
		(net "DELTA_L_85_5INCH_IN6_DP")
	)
	(segment
		(start 352.128328 5.024374)
		(end 351.094294 -0.838708)
		(width 0.14732)
		(layer "In15.Cu")
		(net "DELTA_L_85_5INCH_IN6_DP")
	)
	(segment
		(start 362.96854 -0.811784)
		(end 363.08792 -0.982218)
		(width 0.14732)
		(layer "In15.Cu")
		(net "DELTA_L_85_5INCH_IN6_DP")
	)
	(segment
		(start 367.032032 -1.051814)
		(end 368.390424 -1.291336)
		(width 0.14732)
		(layer "In15.Cu")
		(net "DELTA_L_85_5INCH_IN6_DP")
	)
	(segment
		(start 355.173534 -0.991362)
		(end 356.531926 -1.230884)
		(width 0.14732)
		(layer "In15.Cu")
		(net "DELTA_L_85_5INCH_IN6_DP")
	)
	(segment
		(start 355.831902 5.363972)
		(end 356.081584 5.006848)
		(width 0.14732)
		(layer "In15.Cu")
		(net "DELTA_L_85_5INCH_IN6_DP")
	)
	(segment
		(start 367.698528 5.34797)
		(end 367.94821 4.990846)
		(width 0.14732)
		(layer "In15.Cu")
		(net "DELTA_L_85_5INCH_IN6_DP")
	)
	(segment
		(start 363.08792 -0.982218)
		(end 364.446312 -1.22174)
		(width 0.14732)
		(layer "In15.Cu")
		(net "DELTA_L_85_5INCH_IN6_DP")
	)
	(segment
		(start 344.927682 3.060954)
		(end 345.70543 3.838702)
		(width 0.14732)
		(layer "In15.Cu")
		(net "DELTA_L_85_5INCH_IN6_DP")
	)
	(segment
		(start 367.94821 4.990846)
		(end 366.912652 -0.88138)
		(width 0.14732)
		(layer "In15.Cu")
		(net "DELTA_L_85_5INCH_IN6_DP")
	)
	(segment
		(start 376.29846 3.060954)
		(end 376.5931 3.355594)
		(width 0.14732)
		(layer "In15.Cu")
		(net "DELTA_L_85_5INCH_IN6_DP")
	)
	(segment
		(start 345.972384 5.352542)
		(end 346.329 5.602732)
		(width 0.14732)
		(layer "In15.Cu")
		(net "DELTA_L_85_5INCH_IN6_DP")
	)
	(segment
		(start 365.759238 5.376672)
		(end 366.116108 5.626862)
		(width 0.14732)
		(layer "In15.Cu")
		(net "DELTA_L_85_5INCH_IN6_DP")
	)
	(segment
		(start 347.911674 5.32384)
		(end 348.16161 4.966462)
		(width 0.14732)
		(layer "In15.Cu")
		(net "DELTA_L_85_5INCH_IN6_DP")
	)
	(segment
		(start 366.912652 -0.88138)
		(end 367.032032 -1.051814)
		(width 0.14732)
		(layer "In15.Cu")
		(net "DELTA_L_85_5INCH_IN6_DP")
	)
	(segment
		(start 366.116108 5.626862)
		(end 367.698528 5.34797)
		(width 0.14732)
		(layer "In15.Cu")
		(net "DELTA_L_85_5INCH_IN6_DP")
	)
	(segment
		(start 348.618048 -1.234694)
		(end 348.788228 -1.115314)
		(width 0.14732)
		(layer "In15.Cu")
		(net "DELTA_L_85_5INCH_IN6_DP")
	)
	(segment
		(start 356.702106 -1.111758)
		(end 357.852726 5.415026)
		(width 0.14732)
		(layer "In15.Cu")
		(net "DELTA_L_85_5INCH_IN6_DP")
	)
	(segment
		(start 341.099648 3.060954)
		(end 344.927682 3.060954)
		(width 0.14732)
		(layer "In15.Cu")
		(net "DELTA_L_85_5INCH_IN6_DP")
	)
	(segment
		(start 368.390424 -1.291336)
		(end 368.560604 -1.171956)
		(width 0.14732)
		(layer "In15.Cu")
		(net "DELTA_L_85_5INCH_IN6_DP")
	)
	(segment
		(start 364.000034 5.038344)
		(end 362.96854 -0.811784)
		(width 0.14732)
		(layer "In15.Cu")
		(net "DELTA_L_85_5INCH_IN6_DP")
	)
	(segment
		(start 359.121964 -1.035304)
		(end 360.480356 -1.274826)
		(width 0.14732)
		(layer "In15.Cu")
		(net "DELTA_L_85_5INCH_IN6_DP")
	)
	(segment
		(start 361.811062 5.424678)
		(end 362.167932 5.674868)
		(width 0.14732)
		(layer "In15.Cu")
		(net "DELTA_L_85_5INCH_IN6_DP")
	)
	(segment
		(start 352.572066 -1.248918)
		(end 352.742246 -1.129538)
		(width 0.14732)
		(layer "In15.Cu")
		(net "DELTA_L_85_5INCH_IN6_DP")
	)
	(segment
		(start 364.446312 -1.22174)
		(end 364.616492 -1.102614)
		(width 0.14732)
		(layer "In15.Cu")
		(net "DELTA_L_85_5INCH_IN6_DP")
	)
	(segment
		(start 359.792016 5.385816)
		(end 360.041952 5.028946)
		(width 0.14732)
		(layer "In15.Cu")
		(net "DELTA_L_85_5INCH_IN6_DP")
	)
	(segment
		(start 370.87556 -0.84455)
		(end 370.99494 -1.01473)
		(width 0.14732)
		(layer "In15.Cu")
		(net "DELTA_L_85_5INCH_IN6_DP")
	)
	(segment
		(start 371.900958 4.969764)
		(end 370.87556 -0.84455)
		(width 0.14732)
		(layer "In15.Cu")
		(net "DELTA_L_85_5INCH_IN6_DP")
	)
	(segment
		(start 351.878392 5.381752)
		(end 352.128328 5.024374)
		(width 0.14732)
		(layer "In15.Cu")
		(net "DELTA_L_85_5INCH_IN6_DP")
	)
	(segment
		(start 372.523766 -1.135126)
		(end 373.169434 2.52476)
		(width 0.14732)
		(layer "In15.Cu")
		(net "DELTA_L_85_5INCH_IN6_DP")
	)
	(segment
		(start 346.329 5.602732)
		(end 347.911674 5.32384)
		(width 0.14732)
		(layer "In15.Cu")
		(net "DELTA_L_85_5INCH_IN6_DP")
	)
	(segment
		(start 356.531926 -1.230884)
		(end 356.702106 -1.111758)
		(width 0.14732)
		(layer "In15.Cu")
		(net "DELTA_L_85_5INCH_IN6_DP")
	)
	(segment
		(start 360.480356 -1.274826)
		(end 360.650536 -1.155446)
		(width 0.14732)
		(layer "In15.Cu")
		(net "DELTA_L_85_5INCH_IN6_DP")
	)
	(segment
		(start 353.892358 5.393182)
		(end 354.249482 5.642864)
		(width 0.14732)
		(layer "In15.Cu")
		(net "DELTA_L_85_5INCH_IN6_DP")
	)
	(segment
		(start 347.259656 -0.995426)
		(end 348.618048 -1.234694)
		(width 0.14732)
		(layer "In15.Cu")
		(net "DELTA_L_85_5INCH_IN6_DP")
	)
	(segment
		(start 363.750352 5.395722)
		(end 364.000034 5.038344)
		(width 0.14732)
		(layer "In15.Cu")
		(net "DELTA_L_85_5INCH_IN6_DP")
	)
	(segment
		(start 352.742246 -1.129538)
		(end 353.892358 5.393182)
		(width 0.14732)
		(layer "In15.Cu")
		(net "DELTA_L_85_5INCH_IN6_DP")
	)
	(segment
		(start 348.16161 4.966462)
		(end 347.140276 -0.824992)
		(width 0.14732)
		(layer "In15.Cu")
		(net "DELTA_L_85_5INCH_IN6_DP")
	)
	(segment
		(start 370.180616 5.586222)
		(end 370.180616 5.585968)
		(width 0.14732)
		(layer "In15.Cu")
		(net "DELTA_L_85_5INCH_IN6_DP")
	)
	(segment
		(start 357.852726 5.415026)
		(end 358.20985 5.664708)
		(width 0.14732)
		(layer "In15.Cu")
		(net "DELTA_L_85_5INCH_IN6_DP")
	)
	(segment
		(start 348.788228 -1.115314)
		(end 349.939102 5.410454)
		(width 0.14732)
		(layer "In15.Cu")
		(net "DELTA_L_85_5INCH_IN6_DP")
	)
	(segment
		(start 356.081584 5.006848)
		(end 355.054154 -0.82042)
		(width 0.14732)
		(layer "In15.Cu")
		(net "DELTA_L_85_5INCH_IN6_DP")
	)
	(segment
		(start 340.805008 3.355594)
		(end 341.099648 3.060954)
		(width 0.14732)
		(layer "In15.Cu")
		(net "DELTA_L_85_5INCH_IN6_DP")
	)
	(segment
		(start 354.249482 5.642864)
		(end 355.831902 5.363972)
		(width 0.14732)
		(layer "In15.Cu")
		(net "DELTA_L_85_5INCH_IN6_DP")
	)
	(segment
		(start 349.939102 5.410454)
		(end 350.295718 5.660644)
		(width 0.14732)
		(layer "In15.Cu")
		(net "DELTA_L_85_5INCH_IN6_DP")
	)
	(segment
		(start 364.616492 -1.102614)
		(end 365.759238 5.376672)
		(width 0.14732)
		(layer "In15.Cu")
		(net "DELTA_L_85_5INCH_IN6_DP")
	)
	(segment
		(start 345.70543 3.838702)
		(end 345.972384 5.352542)
		(width 0.14732)
		(layer "In15.Cu")
		(net "DELTA_L_85_5INCH_IN6_DP")
	)
	(segment
		(start 351.094294 -0.838708)
		(end 351.213674 -1.009396)
		(width 0.14732)
		(layer "In15.Cu")
		(net "DELTA_L_85_5INCH_IN6_DP")
	)
	(segment
		(start 370.180616 5.585968)
		(end 371.651276 5.326888)
		(width 0.14732)
		(layer "In15.Cu")
		(net "DELTA_L_85_5INCH_IN6_DP")
	)
	(segment
		(start 373.169434 2.52476)
		(end 373.705628 3.060954)
		(width 0.14732)
		(layer "In15.Cu")
		(net "DELTA_L_85_5INCH_IN6_DP")
	)
	(segment
		(start 371.651276 5.326888)
		(end 371.900958 4.969764)
		(width 0.14732)
		(layer "In15.Cu")
		(net "DELTA_L_85_5INCH_IN6_DP")
	)
	(segment
		(start 370.068856 5.60578)
		(end 370.180616 5.586222)
		(width 0.14732)
		(layer "In15.Cu")
		(net "DELTA_L_85_5INCH_IN6_DP")
	)
	(segment
		(start 370.99494 -1.01473)
		(end 372.353332 -1.254506)
		(width 0.14732)
		(layer "In15.Cu")
		(net "DELTA_L_85_5INCH_IN6_DP")
	)
	(segment
		(start 372.353332 -1.254506)
		(end 372.523766 -1.135126)
		(width 0.14732)
		(layer "In15.Cu")
		(net "DELTA_L_85_5INCH_IN6_DP")
	)
	(segment
		(start 360.650536 -1.155446)
		(end 361.811062 5.424678)
		(width 0.14732)
		(layer "In15.Cu")
		(net "DELTA_L_85_5INCH_IN6_DP")
	)
	(segment
		(start 373.705628 3.060954)
		(end 376.29846 3.060954)
		(width 0.14732)
		(layer "In15.Cu")
		(net "DELTA_L_85_5INCH_IN6_DP")
	)
	(segment
		(start 347.140276 -0.824992)
		(end 347.259656 -0.995426)
		(width 0.14732)
		(layer "In15.Cu")
		(net "DELTA_L_85_5INCH_IN6_DP")
	)
	(segment
		(start 360.041952 5.028946)
		(end 359.002584 -0.865124)
		(width 0.14732)
		(layer "In15.Cu")
		(net "DELTA_L_85_5INCH_IN6_DP")
	)
	(segment
		(start 351.213674 -1.009396)
		(end 352.572066 -1.248918)
		(width 0.14732)
		(layer "In15.Cu")
		(net "DELTA_L_85_5INCH_IN6_DP")
	)
	(segment
		(start 355.054154 -0.82042)
		(end 355.173534 -0.991362)
		(width 0.14732)
		(layer "In15.Cu")
		(net "DELTA_L_85_5INCH_IN6_DP")
	)
	(segment
		(start 369.711732 5.356098)
		(end 370.068856 5.60578)
		(width 0.14732)
		(layer "In15.Cu")
		(net "DELTA_L_85_5INCH_IN6_DP")
	)
	(segment
		(start 368.560604 -1.171956)
		(end 369.711732 5.356098)
		(width 0.14732)
		(layer "In15.Cu")
		(net "DELTA_L_85_5INCH_IN6_DP")
	)
	(segment
		(start 377.274074 2.673858)
		(end 376.5931 2.491994)
		(width 0.13208)
		(layer "B.Cu")
		(net "DELTA_L_85_5INCH_IN6_DN")
	)
	(segment
		(start 340.124034 2.673858)
		(end 340.805008 2.491994)
		(width 0.13208)
		(layer "B.Cu")
		(net "DELTA_L_85_5INCH_IN6_DN")
	)
	(segment
		(start 358.103424 5.25526)
		(end 358.274112 5.37464)
		(width 0.14732)
		(layer "In15.Cu")
		(net "DELTA_L_85_5INCH_IN6_DN")
	)
	(segment
		(start 341.099648 2.786634)
		(end 345.041474 2.786634)
		(width 0.14732)
		(layer "In15.Cu")
		(net "DELTA_L_85_5INCH_IN6_DN")
	)
	(segment
		(start 363.709966 4.974336)
		(end 362.678472 -0.876046)
		(width 0.14732)
		(layer "In15.Cu")
		(net "DELTA_L_85_5INCH_IN6_DN")
	)
	(segment
		(start 346.223082 5.19303)
		(end 346.393516 5.312664)
		(width 0.14732)
		(layer "In15.Cu")
		(net "DELTA_L_85_5INCH_IN6_DN")
	)
	(segment
		(start 350.360234 5.370576)
		(end 351.718626 5.131054)
		(width 0.14732)
		(layer "In15.Cu")
		(net "DELTA_L_85_5INCH_IN6_DN")
	)
	(segment
		(start 347.871542 4.9022)
		(end 346.850208 -0.889254)
		(width 0.14732)
		(layer "In15.Cu")
		(net "DELTA_L_85_5INCH_IN6_DN")
	)
	(segment
		(start 354.764086 -0.884682)
		(end 355.013768 -1.241806)
		(width 0.14732)
		(layer "In15.Cu")
		(net "DELTA_L_85_5INCH_IN6_DN")
	)
	(segment
		(start 376.29846 2.786634)
		(end 376.5931 2.491994)
		(width 0.14732)
		(layer "In15.Cu")
		(net "DELTA_L_85_5INCH_IN6_DN")
	)
	(segment
		(start 346.850208 -0.889254)
		(end 347.100144 -1.24587)
		(width 0.14732)
		(layer "In15.Cu")
		(net "DELTA_L_85_5INCH_IN6_DN")
	)
	(segment
		(start 370.585492 -0.908812)
		(end 370.835174 -1.265428)
		(width 0.14732)
		(layer "In15.Cu")
		(net "DELTA_L_85_5INCH_IN6_DN")
	)
	(segment
		(start 366.622584 -0.945642)
		(end 366.872266 -1.302512)
		(width 0.14732)
		(layer "In15.Cu")
		(net "DELTA_L_85_5INCH_IN6_DN")
	)
	(segment
		(start 360.901234 -1.315212)
		(end 362.061506 5.265166)
		(width 0.14732)
		(layer "In15.Cu")
		(net "DELTA_L_85_5INCH_IN6_DN")
	)
	(segment
		(start 351.718626 5.131054)
		(end 351.83826 4.960112)
		(width 0.14732)
		(layer "In15.Cu")
		(net "DELTA_L_85_5INCH_IN6_DN")
	)
	(segment
		(start 366.009682 5.21716)
		(end 366.18037 5.336794)
		(width 0.14732)
		(layer "In15.Cu")
		(net "DELTA_L_85_5INCH_IN6_DN")
	)
	(segment
		(start 348.68231 -1.524762)
		(end 349.038926 -1.27508)
		(width 0.14732)
		(layer "In15.Cu")
		(net "DELTA_L_85_5INCH_IN6_DN")
	)
	(segment
		(start 370.835174 -1.265428)
		(end 372.417594 -1.544574)
		(width 0.14732)
		(layer "In15.Cu")
		(net "DELTA_L_85_5INCH_IN6_DN")
	)
	(segment
		(start 368.454686 -1.581404)
		(end 368.811302 -1.331722)
		(width 0.14732)
		(layer "In15.Cu")
		(net "DELTA_L_85_5INCH_IN6_DN")
	)
	(segment
		(start 373.424704 2.391918)
		(end 373.81942 2.786634)
		(width 0.14732)
		(layer "In15.Cu")
		(net "DELTA_L_85_5INCH_IN6_DN")
	)
	(segment
		(start 355.791516 4.942586)
		(end 354.764086 -0.884682)
		(width 0.14732)
		(layer "In15.Cu")
		(net "DELTA_L_85_5INCH_IN6_DN")
	)
	(segment
		(start 349.038926 -1.27508)
		(end 350.1898 5.250942)
		(width 0.14732)
		(layer "In15.Cu")
		(net "DELTA_L_85_5INCH_IN6_DN")
	)
	(segment
		(start 362.928154 -1.232916)
		(end 364.510574 -1.511808)
		(width 0.14732)
		(layer "In15.Cu")
		(net "DELTA_L_85_5INCH_IN6_DN")
	)
	(segment
		(start 358.962198 -1.286002)
		(end 360.544618 -1.564894)
		(width 0.14732)
		(layer "In15.Cu")
		(net "DELTA_L_85_5INCH_IN6_DN")
	)
	(segment
		(start 351.83826 4.960112)
		(end 350.804226 -0.90297)
		(width 0.14732)
		(layer "In15.Cu")
		(net "DELTA_L_85_5INCH_IN6_DN")
	)
	(segment
		(start 371.61089 4.905502)
		(end 370.585492 -0.908812)
		(width 0.14732)
		(layer "In15.Cu")
		(net "DELTA_L_85_5INCH_IN6_DN")
	)
	(segment
		(start 358.712516 -0.929386)
		(end 358.962198 -1.286002)
		(width 0.14732)
		(layer "In15.Cu")
		(net "DELTA_L_85_5INCH_IN6_DN")
	)
	(segment
		(start 364.510574 -1.511808)
		(end 364.866936 -1.262126)
		(width 0.14732)
		(layer "In15.Cu")
		(net "DELTA_L_85_5INCH_IN6_DN")
	)
	(segment
		(start 368.811302 -1.331722)
		(end 369.96243 5.196332)
		(width 0.14732)
		(layer "In15.Cu")
		(net "DELTA_L_85_5INCH_IN6_DN")
	)
	(segment
		(start 373.81942 2.786634)
		(end 376.29846 2.786634)
		(width 0.14732)
		(layer "In15.Cu")
		(net "DELTA_L_85_5INCH_IN6_DN")
	)
	(segment
		(start 367.538762 5.097272)
		(end 367.658142 4.926584)
		(width 0.14732)
		(layer "In15.Cu")
		(net "DELTA_L_85_5INCH_IN6_DN")
	)
	(segment
		(start 359.751884 4.964684)
		(end 358.712516 -0.929386)
		(width 0.14732)
		(layer "In15.Cu")
		(net "DELTA_L_85_5INCH_IN6_DN")
	)
	(segment
		(start 340.805008 2.491994)
		(end 341.099648 2.786634)
		(width 0.14732)
		(layer "In15.Cu")
		(net "DELTA_L_85_5INCH_IN6_DN")
	)
	(segment
		(start 354.313744 5.352796)
		(end 355.672136 5.113274)
		(width 0.14732)
		(layer "In15.Cu")
		(net "DELTA_L_85_5INCH_IN6_DN")
	)
	(segment
		(start 372.774464 -1.294892)
		(end 373.424704 2.391918)
		(width 0.14732)
		(layer "In15.Cu")
		(net "DELTA_L_85_5INCH_IN6_DN")
	)
	(segment
		(start 356.596188 -1.520952)
		(end 356.95255 -1.27127)
		(width 0.14732)
		(layer "In15.Cu")
		(net "DELTA_L_85_5INCH_IN6_DN")
	)
	(segment
		(start 366.872266 -1.302512)
		(end 368.454686 -1.581404)
		(width 0.14732)
		(layer "In15.Cu")
		(net "DELTA_L_85_5INCH_IN6_DN")
	)
	(segment
		(start 355.013768 -1.241806)
		(end 356.596188 -1.520952)
		(width 0.14732)
		(layer "In15.Cu")
		(net "DELTA_L_85_5INCH_IN6_DN")
	)
	(segment
		(start 350.1898 5.250942)
		(end 350.360234 5.370576)
		(width 0.14732)
		(layer "In15.Cu")
		(net "DELTA_L_85_5INCH_IN6_DN")
	)
	(segment
		(start 364.866936 -1.262126)
		(end 366.009682 5.21716)
		(width 0.14732)
		(layer "In15.Cu")
		(net "DELTA_L_85_5INCH_IN6_DN")
	)
	(segment
		(start 355.672136 5.113274)
		(end 355.791516 4.942586)
		(width 0.14732)
		(layer "In15.Cu")
		(net "DELTA_L_85_5INCH_IN6_DN")
	)
	(segment
		(start 362.061506 5.265166)
		(end 362.232194 5.3848)
		(width 0.14732)
		(layer "In15.Cu")
		(net "DELTA_L_85_5INCH_IN6_DN")
	)
	(segment
		(start 370.133118 5.315712)
		(end 371.49151 5.07619)
		(width 0.14732)
		(layer "In15.Cu")
		(net "DELTA_L_85_5INCH_IN6_DN")
	)
	(segment
		(start 360.544618 -1.564894)
		(end 360.901234 -1.315212)
		(width 0.14732)
		(layer "In15.Cu")
		(net "DELTA_L_85_5INCH_IN6_DN")
	)
	(segment
		(start 347.751908 5.073142)
		(end 347.871542 4.9022)
		(width 0.14732)
		(layer "In15.Cu")
		(net "DELTA_L_85_5INCH_IN6_DN")
	)
	(segment
		(start 352.992944 -1.289304)
		(end 354.143056 5.233416)
		(width 0.14732)
		(layer "In15.Cu")
		(net "DELTA_L_85_5INCH_IN6_DN")
	)
	(segment
		(start 363.590586 5.145278)
		(end 363.709966 4.974336)
		(width 0.14732)
		(layer "In15.Cu")
		(net "DELTA_L_85_5INCH_IN6_DN")
	)
	(segment
		(start 345.041474 2.786634)
		(end 345.9607 3.70586)
		(width 0.14732)
		(layer "In15.Cu")
		(net "DELTA_L_85_5INCH_IN6_DN")
	)
	(segment
		(start 345.9607 3.70586)
		(end 346.223082 5.19303)
		(width 0.14732)
		(layer "In15.Cu")
		(net "DELTA_L_85_5INCH_IN6_DN")
	)
	(segment
		(start 350.804226 -0.90297)
		(end 351.054162 -1.25984)
		(width 0.14732)
		(layer "In15.Cu")
		(net "DELTA_L_85_5INCH_IN6_DN")
	)
	(segment
		(start 371.49151 5.07619)
		(end 371.61089 4.905502)
		(width 0.14732)
		(layer "In15.Cu")
		(net "DELTA_L_85_5INCH_IN6_DN")
	)
	(segment
		(start 351.054162 -1.25984)
		(end 352.636328 -1.538986)
		(width 0.14732)
		(layer "In15.Cu")
		(net "DELTA_L_85_5INCH_IN6_DN")
	)
	(segment
		(start 367.658142 4.926584)
		(end 366.622584 -0.945642)
		(width 0.14732)
		(layer "In15.Cu")
		(net "DELTA_L_85_5INCH_IN6_DN")
	)
	(segment
		(start 372.417594 -1.544574)
		(end 372.774464 -1.294892)
		(width 0.14732)
		(layer "In15.Cu")
		(net "DELTA_L_85_5INCH_IN6_DN")
	)
	(segment
		(start 362.232194 5.3848)
		(end 363.590586 5.145278)
		(width 0.14732)
		(layer "In15.Cu")
		(net "DELTA_L_85_5INCH_IN6_DN")
	)
	(segment
		(start 362.678472 -0.876046)
		(end 362.928154 -1.232916)
		(width 0.14732)
		(layer "In15.Cu")
		(net "DELTA_L_85_5INCH_IN6_DN")
	)
	(segment
		(start 369.96243 5.196332)
		(end 370.133118 5.315712)
		(width 0.14732)
		(layer "In15.Cu")
		(net "DELTA_L_85_5INCH_IN6_DN")
	)
	(segment
		(start 352.636328 -1.538986)
		(end 352.992944 -1.289304)
		(width 0.14732)
		(layer "In15.Cu")
		(net "DELTA_L_85_5INCH_IN6_DN")
	)
	(segment
		(start 346.393516 5.312664)
		(end 347.751908 5.073142)
		(width 0.14732)
		(layer "In15.Cu")
		(net "DELTA_L_85_5INCH_IN6_DN")
	)
	(segment
		(start 356.95255 -1.27127)
		(end 358.103424 5.25526)
		(width 0.14732)
		(layer "In15.Cu")
		(net "DELTA_L_85_5INCH_IN6_DN")
	)
	(segment
		(start 347.100144 -1.24587)
		(end 348.68231 -1.524762)
		(width 0.14732)
		(layer "In15.Cu")
		(net "DELTA_L_85_5INCH_IN6_DN")
	)
	(segment
		(start 359.632504 5.135118)
		(end 359.751884 4.964684)
		(width 0.14732)
		(layer "In15.Cu")
		(net "DELTA_L_85_5INCH_IN6_DN")
	)
	(segment
		(start 358.274112 5.37464)
		(end 359.632504 5.135118)
		(width 0.14732)
		(layer "In15.Cu")
		(net "DELTA_L_85_5INCH_IN6_DN")
	)
	(segment
		(start 366.18037 5.336794)
		(end 367.538762 5.097272)
		(width 0.14732)
		(layer "In15.Cu")
		(net "DELTA_L_85_5INCH_IN6_DN")
	)
	(segment
		(start 354.143056 5.233416)
		(end 354.313744 5.352796)
		(width 0.14732)
		(layer "In15.Cu")
		(net "DELTA_L_85_5INCH_IN6_DN")
	)
	(segment
		(start 377.274074 8.25373)
		(end 376.5931 8.435594)
		(width 0.13208)
		(layer "B.Cu")
		(net "DELTA_L_85_5INCH_IN5_DP")
	)
	(segment
		(start 340.124034 8.25373)
		(end 340.805008 8.435594)
		(width 0.13208)
		(layer "B.Cu")
		(net "DELTA_L_85_5INCH_IN5_DP")
	)
	(segment
		(start 369.711732 10.436098)
		(end 370.068856 10.68578)
		(width 0.14732)
		(layer "In13.Cu")
		(net "DELTA_L_85_5INCH_IN5_DP")
	)
	(segment
		(start 368.560604 3.908044)
		(end 369.711732 10.436098)
		(width 0.14732)
		(layer "In13.Cu")
		(net "DELTA_L_85_5INCH_IN5_DP")
	)
	(segment
		(start 364.000034 10.118344)
		(end 362.96854 4.268216)
		(width 0.14732)
		(layer "In13.Cu")
		(net "DELTA_L_85_5INCH_IN5_DP")
	)
	(segment
		(start 347.911674 10.40384)
		(end 348.16161 10.046462)
		(width 0.14732)
		(layer "In13.Cu")
		(net "DELTA_L_85_5INCH_IN5_DP")
	)
	(segment
		(start 340.805008 8.435594)
		(end 341.099648 8.140954)
		(width 0.14732)
		(layer "In13.Cu")
		(net "DELTA_L_85_5INCH_IN5_DP")
	)
	(segment
		(start 351.878392 10.461752)
		(end 352.128328 10.104374)
		(width 0.14732)
		(layer "In13.Cu")
		(net "DELTA_L_85_5INCH_IN5_DP")
	)
	(segment
		(start 360.480356 3.805174)
		(end 360.650536 3.924554)
		(width 0.14732)
		(layer "In13.Cu")
		(net "DELTA_L_85_5INCH_IN5_DP")
	)
	(segment
		(start 367.698528 10.42797)
		(end 367.94821 10.070846)
		(width 0.14732)
		(layer "In13.Cu")
		(net "DELTA_L_85_5INCH_IN5_DP")
	)
	(segment
		(start 345.70543 8.918702)
		(end 345.972384 10.432542)
		(width 0.14732)
		(layer "In13.Cu")
		(net "DELTA_L_85_5INCH_IN5_DP")
	)
	(segment
		(start 372.523766 3.944874)
		(end 373.169434 7.60476)
		(width 0.14732)
		(layer "In13.Cu")
		(net "DELTA_L_85_5INCH_IN5_DP")
	)
	(segment
		(start 363.08792 4.097782)
		(end 364.446312 3.85826)
		(width 0.14732)
		(layer "In13.Cu")
		(net "DELTA_L_85_5INCH_IN5_DP")
	)
	(segment
		(start 354.249482 10.722864)
		(end 355.831902 10.443972)
		(width 0.14732)
		(layer "In13.Cu")
		(net "DELTA_L_85_5INCH_IN5_DP")
	)
	(segment
		(start 352.128328 10.104374)
		(end 351.094294 4.241292)
		(width 0.14732)
		(layer "In13.Cu")
		(net "DELTA_L_85_5INCH_IN5_DP")
	)
	(segment
		(start 367.032032 4.028186)
		(end 368.390424 3.788664)
		(width 0.14732)
		(layer "In13.Cu")
		(net "DELTA_L_85_5INCH_IN5_DP")
	)
	(segment
		(start 366.116108 10.706862)
		(end 367.698528 10.42797)
		(width 0.14732)
		(layer "In13.Cu")
		(net "DELTA_L_85_5INCH_IN5_DP")
	)
	(segment
		(start 351.094294 4.241292)
		(end 351.213674 4.070604)
		(width 0.14732)
		(layer "In13.Cu")
		(net "DELTA_L_85_5INCH_IN5_DP")
	)
	(segment
		(start 352.572066 3.831082)
		(end 352.742246 3.950462)
		(width 0.14732)
		(layer "In13.Cu")
		(net "DELTA_L_85_5INCH_IN5_DP")
	)
	(segment
		(start 359.792016 10.465816)
		(end 360.041952 10.108946)
		(width 0.14732)
		(layer "In13.Cu")
		(net "DELTA_L_85_5INCH_IN5_DP")
	)
	(segment
		(start 364.616492 3.977386)
		(end 365.759238 10.456672)
		(width 0.14732)
		(layer "In13.Cu")
		(net "DELTA_L_85_5INCH_IN5_DP")
	)
	(segment
		(start 360.041952 10.108946)
		(end 359.002584 4.214876)
		(width 0.14732)
		(layer "In13.Cu")
		(net "DELTA_L_85_5INCH_IN5_DP")
	)
	(segment
		(start 361.811062 10.504678)
		(end 362.167932 10.754868)
		(width 0.14732)
		(layer "In13.Cu")
		(net "DELTA_L_85_5INCH_IN5_DP")
	)
	(segment
		(start 348.618048 3.845306)
		(end 348.788228 3.964686)
		(width 0.14732)
		(layer "In13.Cu")
		(net "DELTA_L_85_5INCH_IN5_DP")
	)
	(segment
		(start 360.650536 3.924554)
		(end 361.811062 10.504678)
		(width 0.14732)
		(layer "In13.Cu")
		(net "DELTA_L_85_5INCH_IN5_DP")
	)
	(segment
		(start 346.329 10.682732)
		(end 347.911674 10.40384)
		(width 0.14732)
		(layer "In13.Cu")
		(net "DELTA_L_85_5INCH_IN5_DP")
	)
	(segment
		(start 348.788228 3.964686)
		(end 349.939102 10.490454)
		(width 0.14732)
		(layer "In13.Cu")
		(net "DELTA_L_85_5INCH_IN5_DP")
	)
	(segment
		(start 373.705628 8.140954)
		(end 376.29846 8.140954)
		(width 0.14732)
		(layer "In13.Cu")
		(net "DELTA_L_85_5INCH_IN5_DP")
	)
	(segment
		(start 356.702106 3.968242)
		(end 357.852726 10.495026)
		(width 0.14732)
		(layer "In13.Cu")
		(net "DELTA_L_85_5INCH_IN5_DP")
	)
	(segment
		(start 367.94821 10.070846)
		(end 366.912652 4.19862)
		(width 0.14732)
		(layer "In13.Cu")
		(net "DELTA_L_85_5INCH_IN5_DP")
	)
	(segment
		(start 370.99494 4.06527)
		(end 372.353332 3.825494)
		(width 0.14732)
		(layer "In13.Cu")
		(net "DELTA_L_85_5INCH_IN5_DP")
	)
	(segment
		(start 370.180616 10.666222)
		(end 370.180616 10.665968)
		(width 0.14732)
		(layer "In13.Cu")
		(net "DELTA_L_85_5INCH_IN5_DP")
	)
	(segment
		(start 344.927682 8.140954)
		(end 345.70543 8.918702)
		(width 0.14732)
		(layer "In13.Cu")
		(net "DELTA_L_85_5INCH_IN5_DP")
	)
	(segment
		(start 356.081584 10.086848)
		(end 355.054154 4.25958)
		(width 0.14732)
		(layer "In13.Cu")
		(net "DELTA_L_85_5INCH_IN5_DP")
	)
	(segment
		(start 353.892358 10.473182)
		(end 354.249482 10.722864)
		(width 0.14732)
		(layer "In13.Cu")
		(net "DELTA_L_85_5INCH_IN5_DP")
	)
	(segment
		(start 355.054154 4.25958)
		(end 355.173534 4.088638)
		(width 0.14732)
		(layer "In13.Cu")
		(net "DELTA_L_85_5INCH_IN5_DP")
	)
	(segment
		(start 370.180616 10.665968)
		(end 371.651276 10.406888)
		(width 0.14732)
		(layer "In13.Cu")
		(net "DELTA_L_85_5INCH_IN5_DP")
	)
	(segment
		(start 356.531926 3.849116)
		(end 356.702106 3.968242)
		(width 0.14732)
		(layer "In13.Cu")
		(net "DELTA_L_85_5INCH_IN5_DP")
	)
	(segment
		(start 359.002584 4.214876)
		(end 359.121964 4.044696)
		(width 0.14732)
		(layer "In13.Cu")
		(net "DELTA_L_85_5INCH_IN5_DP")
	)
	(segment
		(start 358.20985 10.744708)
		(end 359.792016 10.465816)
		(width 0.14732)
		(layer "In13.Cu")
		(net "DELTA_L_85_5INCH_IN5_DP")
	)
	(segment
		(start 357.852726 10.495026)
		(end 358.20985 10.744708)
		(width 0.14732)
		(layer "In13.Cu")
		(net "DELTA_L_85_5INCH_IN5_DP")
	)
	(segment
		(start 362.167932 10.754868)
		(end 363.750352 10.475722)
		(width 0.14732)
		(layer "In13.Cu")
		(net "DELTA_L_85_5INCH_IN5_DP")
	)
	(segment
		(start 347.259656 4.084574)
		(end 348.618048 3.845306)
		(width 0.14732)
		(layer "In13.Cu")
		(net "DELTA_L_85_5INCH_IN5_DP")
	)
	(segment
		(start 352.742246 3.950462)
		(end 353.892358 10.473182)
		(width 0.14732)
		(layer "In13.Cu")
		(net "DELTA_L_85_5INCH_IN5_DP")
	)
	(segment
		(start 371.900958 10.049764)
		(end 370.87556 4.23545)
		(width 0.14732)
		(layer "In13.Cu")
		(net "DELTA_L_85_5INCH_IN5_DP")
	)
	(segment
		(start 355.831902 10.443972)
		(end 356.081584 10.086848)
		(width 0.14732)
		(layer "In13.Cu")
		(net "DELTA_L_85_5INCH_IN5_DP")
	)
	(segment
		(start 359.121964 4.044696)
		(end 360.480356 3.805174)
		(width 0.14732)
		(layer "In13.Cu")
		(net "DELTA_L_85_5INCH_IN5_DP")
	)
	(segment
		(start 376.29846 8.140954)
		(end 376.5931 8.435594)
		(width 0.14732)
		(layer "In13.Cu")
		(net "DELTA_L_85_5INCH_IN5_DP")
	)
	(segment
		(start 365.759238 10.456672)
		(end 366.116108 10.706862)
		(width 0.14732)
		(layer "In13.Cu")
		(net "DELTA_L_85_5INCH_IN5_DP")
	)
	(segment
		(start 350.295718 10.740644)
		(end 351.878392 10.461752)
		(width 0.14732)
		(layer "In13.Cu")
		(net "DELTA_L_85_5INCH_IN5_DP")
	)
	(segment
		(start 372.353332 3.825494)
		(end 372.523766 3.944874)
		(width 0.14732)
		(layer "In13.Cu")
		(net "DELTA_L_85_5INCH_IN5_DP")
	)
	(segment
		(start 347.140276 4.255008)
		(end 347.259656 4.084574)
		(width 0.14732)
		(layer "In13.Cu")
		(net "DELTA_L_85_5INCH_IN5_DP")
	)
	(segment
		(start 348.16161 10.046462)
		(end 347.140276 4.255008)
		(width 0.14732)
		(layer "In13.Cu")
		(net "DELTA_L_85_5INCH_IN5_DP")
	)
	(segment
		(start 373.169434 7.60476)
		(end 373.705628 8.140954)
		(width 0.14732)
		(layer "In13.Cu")
		(net "DELTA_L_85_5INCH_IN5_DP")
	)
	(segment
		(start 371.651276 10.406888)
		(end 371.900958 10.049764)
		(width 0.14732)
		(layer "In13.Cu")
		(net "DELTA_L_85_5INCH_IN5_DP")
	)
	(segment
		(start 355.173534 4.088638)
		(end 356.531926 3.849116)
		(width 0.14732)
		(layer "In13.Cu")
		(net "DELTA_L_85_5INCH_IN5_DP")
	)
	(segment
		(start 370.87556 4.23545)
		(end 370.99494 4.06527)
		(width 0.14732)
		(layer "In13.Cu")
		(net "DELTA_L_85_5INCH_IN5_DP")
	)
	(segment
		(start 364.446312 3.85826)
		(end 364.616492 3.977386)
		(width 0.14732)
		(layer "In13.Cu")
		(net "DELTA_L_85_5INCH_IN5_DP")
	)
	(segment
		(start 351.213674 4.070604)
		(end 352.572066 3.831082)
		(width 0.14732)
		(layer "In13.Cu")
		(net "DELTA_L_85_5INCH_IN5_DP")
	)
	(segment
		(start 366.912652 4.19862)
		(end 367.032032 4.028186)
		(width 0.14732)
		(layer "In13.Cu")
		(net "DELTA_L_85_5INCH_IN5_DP")
	)
	(segment
		(start 341.099648 8.140954)
		(end 344.927682 8.140954)
		(width 0.14732)
		(layer "In13.Cu")
		(net "DELTA_L_85_5INCH_IN5_DP")
	)
	(segment
		(start 370.068856 10.68578)
		(end 370.180616 10.666222)
		(width 0.14732)
		(layer "In13.Cu")
		(net "DELTA_L_85_5INCH_IN5_DP")
	)
	(segment
		(start 345.972384 10.432542)
		(end 346.329 10.682732)
		(width 0.14732)
		(layer "In13.Cu")
		(net "DELTA_L_85_5INCH_IN5_DP")
	)
	(segment
		(start 363.750352 10.475722)
		(end 364.000034 10.118344)
		(width 0.14732)
		(layer "In13.Cu")
		(net "DELTA_L_85_5INCH_IN5_DP")
	)
	(segment
		(start 362.96854 4.268216)
		(end 363.08792 4.097782)
		(width 0.14732)
		(layer "In13.Cu")
		(net "DELTA_L_85_5INCH_IN5_DP")
	)
	(segment
		(start 349.939102 10.490454)
		(end 350.295718 10.740644)
		(width 0.14732)
		(layer "In13.Cu")
		(net "DELTA_L_85_5INCH_IN5_DP")
	)
	(segment
		(start 368.390424 3.788664)
		(end 368.560604 3.908044)
		(width 0.14732)
		(layer "In13.Cu")
		(net "DELTA_L_85_5INCH_IN5_DP")
	)
	(segment
		(start 377.274074 7.753858)
		(end 376.5931 7.571994)
		(width 0.13208)
		(layer "B.Cu")
		(net "DELTA_L_85_5INCH_IN5_DN")
	)
	(segment
		(start 340.124034 7.753858)
		(end 340.805008 7.571994)
		(width 0.13208)
		(layer "B.Cu")
		(net "DELTA_L_85_5INCH_IN5_DN")
	)
	(segment
		(start 373.81942 7.866634)
		(end 376.29846 7.866634)
		(width 0.14732)
		(layer "In13.Cu")
		(net "DELTA_L_85_5INCH_IN5_DN")
	)
	(segment
		(start 376.29846 7.866634)
		(end 376.5931 7.571994)
		(width 0.14732)
		(layer "In13.Cu")
		(net "DELTA_L_85_5INCH_IN5_DN")
	)
	(segment
		(start 355.791516 10.022586)
		(end 354.764086 4.195318)
		(width 0.14732)
		(layer "In13.Cu")
		(net "DELTA_L_85_5INCH_IN5_DN")
	)
	(segment
		(start 366.622584 4.134358)
		(end 366.872266 3.777488)
		(width 0.14732)
		(layer "In13.Cu")
		(net "DELTA_L_85_5INCH_IN5_DN")
	)
	(segment
		(start 372.417594 3.535426)
		(end 372.774464 3.785108)
		(width 0.14732)
		(layer "In13.Cu")
		(net "DELTA_L_85_5INCH_IN5_DN")
	)
	(segment
		(start 347.751908 10.153142)
		(end 347.871542 9.9822)
		(width 0.14732)
		(layer "In13.Cu")
		(net "DELTA_L_85_5INCH_IN5_DN")
	)
	(segment
		(start 340.805008 7.571994)
		(end 341.099648 7.866634)
		(width 0.14732)
		(layer "In13.Cu")
		(net "DELTA_L_85_5INCH_IN5_DN")
	)
	(segment
		(start 364.866936 3.817874)
		(end 366.009682 10.29716)
		(width 0.14732)
		(layer "In13.Cu")
		(net "DELTA_L_85_5INCH_IN5_DN")
	)
	(segment
		(start 350.1898 10.330942)
		(end 350.360234 10.450576)
		(width 0.14732)
		(layer "In13.Cu")
		(net "DELTA_L_85_5INCH_IN5_DN")
	)
	(segment
		(start 358.962198 3.793998)
		(end 360.544618 3.515106)
		(width 0.14732)
		(layer "In13.Cu")
		(net "DELTA_L_85_5INCH_IN5_DN")
	)
	(segment
		(start 368.454686 3.498596)
		(end 368.811302 3.748278)
		(width 0.14732)
		(layer "In13.Cu")
		(net "DELTA_L_85_5INCH_IN5_DN")
	)
	(segment
		(start 367.538762 10.177272)
		(end 367.658142 10.006584)
		(width 0.14732)
		(layer "In13.Cu")
		(net "DELTA_L_85_5INCH_IN5_DN")
	)
	(segment
		(start 366.009682 10.29716)
		(end 366.18037 10.416794)
		(width 0.14732)
		(layer "In13.Cu")
		(net "DELTA_L_85_5INCH_IN5_DN")
	)
	(segment
		(start 356.596188 3.559048)
		(end 356.95255 3.80873)
		(width 0.14732)
		(layer "In13.Cu")
		(net "DELTA_L_85_5INCH_IN5_DN")
	)
	(segment
		(start 351.718626 10.211054)
		(end 351.83826 10.040112)
		(width 0.14732)
		(layer "In13.Cu")
		(net "DELTA_L_85_5INCH_IN5_DN")
	)
	(segment
		(start 354.313744 10.432796)
		(end 355.672136 10.193274)
		(width 0.14732)
		(layer "In13.Cu")
		(net "DELTA_L_85_5INCH_IN5_DN")
	)
	(segment
		(start 346.223082 10.27303)
		(end 346.393516 10.392664)
		(width 0.14732)
		(layer "In13.Cu")
		(net "DELTA_L_85_5INCH_IN5_DN")
	)
	(segment
		(start 345.041474 7.866634)
		(end 345.9607 8.78586)
		(width 0.14732)
		(layer "In13.Cu")
		(net "DELTA_L_85_5INCH_IN5_DN")
	)
	(segment
		(start 369.96243 10.276332)
		(end 370.133118 10.395712)
		(width 0.14732)
		(layer "In13.Cu")
		(net "DELTA_L_85_5INCH_IN5_DN")
	)
	(segment
		(start 370.133118 10.395712)
		(end 371.49151 10.15619)
		(width 0.14732)
		(layer "In13.Cu")
		(net "DELTA_L_85_5INCH_IN5_DN")
	)
	(segment
		(start 360.901234 3.764788)
		(end 362.061506 10.345166)
		(width 0.14732)
		(layer "In13.Cu")
		(net "DELTA_L_85_5INCH_IN5_DN")
	)
	(segment
		(start 352.636328 3.541014)
		(end 352.992944 3.790696)
		(width 0.14732)
		(layer "In13.Cu")
		(net "DELTA_L_85_5INCH_IN5_DN")
	)
	(segment
		(start 364.510574 3.568192)
		(end 364.866936 3.817874)
		(width 0.14732)
		(layer "In13.Cu")
		(net "DELTA_L_85_5INCH_IN5_DN")
	)
	(segment
		(start 359.632504 10.215118)
		(end 359.751884 10.044684)
		(width 0.14732)
		(layer "In13.Cu")
		(net "DELTA_L_85_5INCH_IN5_DN")
	)
	(segment
		(start 354.143056 10.313416)
		(end 354.313744 10.432796)
		(width 0.14732)
		(layer "In13.Cu")
		(net "DELTA_L_85_5INCH_IN5_DN")
	)
	(segment
		(start 356.95255 3.80873)
		(end 358.103424 10.33526)
		(width 0.14732)
		(layer "In13.Cu")
		(net "DELTA_L_85_5INCH_IN5_DN")
	)
	(segment
		(start 363.709966 10.054336)
		(end 362.678472 4.203954)
		(width 0.14732)
		(layer "In13.Cu")
		(net "DELTA_L_85_5INCH_IN5_DN")
	)
	(segment
		(start 360.544618 3.515106)
		(end 360.901234 3.764788)
		(width 0.14732)
		(layer "In13.Cu")
		(net "DELTA_L_85_5INCH_IN5_DN")
	)
	(segment
		(start 358.274112 10.45464)
		(end 359.632504 10.215118)
		(width 0.14732)
		(layer "In13.Cu")
		(net "DELTA_L_85_5INCH_IN5_DN")
	)
	(segment
		(start 341.099648 7.866634)
		(end 345.041474 7.866634)
		(width 0.14732)
		(layer "In13.Cu")
		(net "DELTA_L_85_5INCH_IN5_DN")
	)
	(segment
		(start 350.360234 10.450576)
		(end 351.718626 10.211054)
		(width 0.14732)
		(layer "In13.Cu")
		(net "DELTA_L_85_5INCH_IN5_DN")
	)
	(segment
		(start 362.061506 10.345166)
		(end 362.232194 10.4648)
		(width 0.14732)
		(layer "In13.Cu")
		(net "DELTA_L_85_5INCH_IN5_DN")
	)
	(segment
		(start 370.835174 3.814572)
		(end 372.417594 3.535426)
		(width 0.14732)
		(layer "In13.Cu")
		(net "DELTA_L_85_5INCH_IN5_DN")
	)
	(segment
		(start 362.232194 10.4648)
		(end 363.590586 10.225278)
		(width 0.14732)
		(layer "In13.Cu")
		(net "DELTA_L_85_5INCH_IN5_DN")
	)
	(segment
		(start 366.18037 10.416794)
		(end 367.538762 10.177272)
		(width 0.14732)
		(layer "In13.Cu")
		(net "DELTA_L_85_5INCH_IN5_DN")
	)
	(segment
		(start 347.871542 9.9822)
		(end 346.850208 4.190746)
		(width 0.14732)
		(layer "In13.Cu")
		(net "DELTA_L_85_5INCH_IN5_DN")
	)
	(segment
		(start 371.49151 10.15619)
		(end 371.61089 9.985502)
		(width 0.14732)
		(layer "In13.Cu")
		(net "DELTA_L_85_5INCH_IN5_DN")
	)
	(segment
		(start 362.928154 3.847084)
		(end 364.510574 3.568192)
		(width 0.14732)
		(layer "In13.Cu")
		(net "DELTA_L_85_5INCH_IN5_DN")
	)
	(segment
		(start 358.712516 4.150614)
		(end 358.962198 3.793998)
		(width 0.14732)
		(layer "In13.Cu")
		(net "DELTA_L_85_5INCH_IN5_DN")
	)
	(segment
		(start 359.751884 10.044684)
		(end 358.712516 4.150614)
		(width 0.14732)
		(layer "In13.Cu")
		(net "DELTA_L_85_5INCH_IN5_DN")
	)
	(segment
		(start 366.872266 3.777488)
		(end 368.454686 3.498596)
		(width 0.14732)
		(layer "In13.Cu")
		(net "DELTA_L_85_5INCH_IN5_DN")
	)
	(segment
		(start 348.68231 3.555238)
		(end 349.038926 3.80492)
		(width 0.14732)
		(layer "In13.Cu")
		(net "DELTA_L_85_5INCH_IN5_DN")
	)
	(segment
		(start 352.992944 3.790696)
		(end 354.143056 10.313416)
		(width 0.14732)
		(layer "In13.Cu")
		(net "DELTA_L_85_5INCH_IN5_DN")
	)
	(segment
		(start 358.103424 10.33526)
		(end 358.274112 10.45464)
		(width 0.14732)
		(layer "In13.Cu")
		(net "DELTA_L_85_5INCH_IN5_DN")
	)
	(segment
		(start 363.590586 10.225278)
		(end 363.709966 10.054336)
		(width 0.14732)
		(layer "In13.Cu")
		(net "DELTA_L_85_5INCH_IN5_DN")
	)
	(segment
		(start 355.013768 3.838194)
		(end 356.596188 3.559048)
		(width 0.14732)
		(layer "In13.Cu")
		(net "DELTA_L_85_5INCH_IN5_DN")
	)
	(segment
		(start 372.774464 3.785108)
		(end 373.424704 7.471918)
		(width 0.14732)
		(layer "In13.Cu")
		(net "DELTA_L_85_5INCH_IN5_DN")
	)
	(segment
		(start 349.038926 3.80492)
		(end 350.1898 10.330942)
		(width 0.14732)
		(layer "In13.Cu")
		(net "DELTA_L_85_5INCH_IN5_DN")
	)
	(segment
		(start 371.61089 9.985502)
		(end 370.585492 4.171188)
		(width 0.14732)
		(layer "In13.Cu")
		(net "DELTA_L_85_5INCH_IN5_DN")
	)
	(segment
		(start 347.100144 3.83413)
		(end 348.68231 3.555238)
		(width 0.14732)
		(layer "In13.Cu")
		(net "DELTA_L_85_5INCH_IN5_DN")
	)
	(segment
		(start 351.83826 10.040112)
		(end 350.804226 4.17703)
		(width 0.14732)
		(layer "In13.Cu")
		(net "DELTA_L_85_5INCH_IN5_DN")
	)
	(segment
		(start 362.678472 4.203954)
		(end 362.928154 3.847084)
		(width 0.14732)
		(layer "In13.Cu")
		(net "DELTA_L_85_5INCH_IN5_DN")
	)
	(segment
		(start 367.658142 10.006584)
		(end 366.622584 4.134358)
		(width 0.14732)
		(layer "In13.Cu")
		(net "DELTA_L_85_5INCH_IN5_DN")
	)
	(segment
		(start 346.393516 10.392664)
		(end 347.751908 10.153142)
		(width 0.14732)
		(layer "In13.Cu")
		(net "DELTA_L_85_5INCH_IN5_DN")
	)
	(segment
		(start 355.672136 10.193274)
		(end 355.791516 10.022586)
		(width 0.14732)
		(layer "In13.Cu")
		(net "DELTA_L_85_5INCH_IN5_DN")
	)
	(segment
		(start 345.9607 8.78586)
		(end 346.223082 10.27303)
		(width 0.14732)
		(layer "In13.Cu")
		(net "DELTA_L_85_5INCH_IN5_DN")
	)
	(segment
		(start 368.811302 3.748278)
		(end 369.96243 10.276332)
		(width 0.14732)
		(layer "In13.Cu")
		(net "DELTA_L_85_5INCH_IN5_DN")
	)
	(segment
		(start 373.424704 7.471918)
		(end 373.81942 7.866634)
		(width 0.14732)
		(layer "In13.Cu")
		(net "DELTA_L_85_5INCH_IN5_DN")
	)
	(segment
		(start 370.585492 4.171188)
		(end 370.835174 3.814572)
		(width 0.14732)
		(layer "In13.Cu")
		(net "DELTA_L_85_5INCH_IN5_DN")
	)
	(segment
		(start 346.850208 4.190746)
		(end 347.100144 3.83413)
		(width 0.14732)
		(layer "In13.Cu")
		(net "DELTA_L_85_5INCH_IN5_DN")
	)
	(segment
		(start 351.054162 3.82016)
		(end 352.636328 3.541014)
		(width 0.14732)
		(layer "In13.Cu")
		(net "DELTA_L_85_5INCH_IN5_DN")
	)
	(segment
		(start 350.804226 4.17703)
		(end 351.054162 3.82016)
		(width 0.14732)
		(layer "In13.Cu")
		(net "DELTA_L_85_5INCH_IN5_DN")
	)
	(segment
		(start 354.764086 4.195318)
		(end 355.013768 3.838194)
		(width 0.14732)
		(layer "In13.Cu")
		(net "DELTA_L_85_5INCH_IN5_DN")
	)
	(segment
		(start 328.414888 2.673858)
		(end 327.733914 2.491994)
		(width 0.13208)
		(layer "B.Cu")
		(net "DELTA_L_85_10INCH_IN6_DP")
	)
	(segment
		(start 261.557008 2.673858)
		(end 262.237982 2.491994)
		(width 0.13208)
		(layer "B.Cu")
		(net "DELTA_L_85_10INCH_IN6_DP")
	)
	(segment
		(start 322.077588 -2.079752)
		(end 321.720972 -2.329942)
		(width 0.14732)
		(layer "In15.Cu")
		(net "DELTA_L_85_10INCH_IN6_DP")
	)
	(segment
		(start 273.42465 4.901184)
		(end 272.066004 5.140706)
		(width 0.14732)
		(layer "In15.Cu")
		(net "DELTA_L_85_10INCH_IN6_DP")
	)
	(segment
		(start 286.203644 -1.815084)
		(end 284.621224 -1.535938)
		(width 0.14732)
		(layer "In15.Cu")
		(net "DELTA_L_85_10INCH_IN6_DP")
	)
	(segment
		(start 317.762636 -2.339848)
		(end 316.18047 -2.060956)
		(width 0.14732)
		(layer "In15.Cu")
		(net "DELTA_L_85_10INCH_IN6_DP")
	)
	(segment
		(start 301.23892 4.729988)
		(end 301.11954 4.900422)
		(width 0.14732)
		(layer "In15.Cu")
		(net "DELTA_L_85_10INCH_IN6_DP")
	)
	(segment
		(start 270.382238 -1.788414)
		(end 268.799564 -1.509776)
		(width 0.14732)
		(layer "In15.Cu")
		(net "DELTA_L_85_10INCH_IN6_DP")
	)
	(segment
		(start 315.59373 5.178806)
		(end 315.42355 5.059426)
		(width 0.14732)
		(layer "In15.Cu")
		(net "DELTA_L_85_10INCH_IN6_DP")
	)
	(segment
		(start 289.367214 4.71551)
		(end 289.247834 4.886198)
		(width 0.14732)
		(layer "In15.Cu")
		(net "DELTA_L_85_10INCH_IN6_DP")
	)
	(segment
		(start 319.888616 -1.694434)
		(end 321.02171 4.732528)
		(width 0.14732)
		(layer "In15.Cu")
		(net "DELTA_L_85_10INCH_IN6_DP")
	)
	(segment
		(start 289.247834 4.885944)
		(end 287.889442 5.12572)
		(width 0.14732)
		(layer "In15.Cu")
		(net "DELTA_L_85_10INCH_IN6_DP")
	)
	(segment
		(start 283.92247 5.06603)
		(end 283.751782 4.946142)
		(width 0.14732)
		(layer "In15.Cu")
		(net "DELTA_L_85_10INCH_IN6_DP")
	)
	(segment
		(start 277.48738 4.65709)
		(end 277.368 4.827524)
		(width 0.14732)
		(layer "In15.Cu")
		(net "DELTA_L_85_10INCH_IN6_DP")
	)
	(segment
		(start 289.247834 4.886198)
		(end 289.247834 4.885944)
		(width 0.14732)
		(layer "In15.Cu")
		(net "DELTA_L_85_10INCH_IN6_DP")
	)
	(segment
		(start 288.316924 -1.240282)
		(end 289.367214 4.71551)
		(width 0.14732)
		(layer "In15.Cu")
		(net "DELTA_L_85_10INCH_IN6_DP")
	)
	(segment
		(start 299.761148 5.139944)
		(end 299.590968 5.020564)
		(width 0.14732)
		(layer "In15.Cu")
		(net "DELTA_L_85_10INCH_IN6_DP")
	)
	(segment
		(start 320.138806 -2.05105)
		(end 319.888616 -1.694434)
		(width 0.14732)
		(layer "In15.Cu")
		(net "DELTA_L_85_10INCH_IN6_DP")
	)
	(segment
		(start 276.009608 5.0673)
		(end 275.838666 4.94792)
		(width 0.14732)
		(layer "In15.Cu")
		(net "DELTA_L_85_10INCH_IN6_DP")
	)
	(segment
		(start 269.459456 4.850892)
		(end 268.101064 5.090414)
		(width 0.14732)
		(layer "In15.Cu")
		(net "DELTA_L_85_10INCH_IN6_DP")
	)
	(segment
		(start 309.150258 4.72186)
		(end 309.030878 4.89204)
		(width 0.14732)
		(layer "In15.Cu")
		(net "DELTA_L_85_10INCH_IN6_DP")
	)
	(segment
		(start 287.7185 5.00634)
		(end 286.559752 -1.565148)
		(width 0.14732)
		(layer "In15.Cu")
		(net "DELTA_L_85_10INCH_IN6_DP")
	)
	(segment
		(start 290.149026 -1.876044)
		(end 288.566606 -1.597406)
		(width 0.14732)
		(layer "In15.Cu")
		(net "DELTA_L_85_10INCH_IN6_DP")
	)
	(segment
		(start 322.911978 2.653284)
		(end 322.077588 -2.079752)
		(width 0.14732)
		(layer "In15.Cu")
		(net "DELTA_L_85_10INCH_IN6_DP")
	)
	(segment
		(start 270.7386 -1.538478)
		(end 270.382238 -1.788414)
		(width 0.14732)
		(layer "In15.Cu")
		(net "DELTA_L_85_10INCH_IN6_DP")
	)
	(segment
		(start 296.48404 -1.57353)
		(end 296.23385 -1.216914)
		(width 0.14732)
		(layer "In15.Cu")
		(net "DELTA_L_85_10INCH_IN6_DP")
	)
	(segment
		(start 284.371288 -1.17983)
		(end 285.400242 4.656074)
		(width 0.14732)
		(layer "In15.Cu")
		(net "DELTA_L_85_10INCH_IN6_DP")
	)
	(segment
		(start 282.245816 -1.82245)
		(end 280.663396 -1.543304)
		(width 0.14732)
		(layer "In15.Cu")
		(net "DELTA_L_85_10INCH_IN6_DP")
	)
	(segment
		(start 280.41346 -1.187196)
		(end 281.450288 4.69392)
		(width 0.14732)
		(layer "In15.Cu")
		(net "DELTA_L_85_10INCH_IN6_DP")
	)
	(segment
		(start 291.833554 5.057902)
		(end 291.663374 4.938776)
		(width 0.14732)
		(layer "In15.Cu")
		(net "DELTA_L_85_10INCH_IN6_DP")
	)
	(segment
		(start 274.693888 -1.544574)
		(end 274.33778 -1.79451)
		(width 0.14732)
		(layer "In15.Cu")
		(net "DELTA_L_85_10INCH_IN6_DP")
	)
	(segment
		(start 315.42355 5.059426)
		(end 314.170822 -2.047494)
		(width 0.14732)
		(layer "In15.Cu")
		(net "DELTA_L_85_10INCH_IN6_DP")
	)
	(segment
		(start 327.733914 2.491994)
		(end 327.439274 2.786634)
		(width 0.14732)
		(layer "In15.Cu")
		(net "DELTA_L_85_10INCH_IN6_DP")
	)
	(segment
		(start 303.539144 4.974844)
		(end 302.316642 -1.959102)
		(width 0.14732)
		(layer "In15.Cu")
		(net "DELTA_L_85_10INCH_IN6_DP")
	)
	(segment
		(start 272.755106 -1.515872)
		(end 272.505424 -1.158748)
		(width 0.14732)
		(layer "In15.Cu")
		(net "DELTA_L_85_10INCH_IN6_DP")
	)
	(segment
		(start 288.566606 -1.597406)
		(end 288.316924 -1.240282)
		(width 0.14732)
		(layer "In15.Cu")
		(net "DELTA_L_85_10INCH_IN6_DP")
	)
	(segment
		(start 267.279882 2.786634)
		(end 262.532622 2.786634)
		(width 0.14732)
		(layer "In15.Cu")
		(net "DELTA_L_85_10INCH_IN6_DP")
	)
	(segment
		(start 302.316642 -1.959102)
		(end 301.960026 -2.209292)
		(width 0.14732)
		(layer "In15.Cu")
		(net "DELTA_L_85_10INCH_IN6_DP")
	)
	(segment
		(start 312.231786 -2.01803)
		(end 311.981596 -1.661414)
		(width 0.14732)
		(layer "In15.Cu")
		(net "DELTA_L_85_10INCH_IN6_DP")
	)
	(segment
		(start 309.030878 4.89204)
		(end 307.672486 5.131816)
		(width 0.14732)
		(layer "In15.Cu")
		(net "DELTA_L_85_10INCH_IN6_DP")
	)
	(segment
		(start 305.067716 4.854448)
		(end 303.709578 5.094224)
		(width 0.14732)
		(layer "In15.Cu")
		(net "DELTA_L_85_10INCH_IN6_DP")
	)
	(segment
		(start 272.066004 5.140706)
		(end 271.895316 5.021326)
		(width 0.14732)
		(layer "In15.Cu")
		(net "DELTA_L_85_10INCH_IN6_DP")
	)
	(segment
		(start 281.330908 4.864608)
		(end 279.972516 5.104384)
		(width 0.14732)
		(layer "In15.Cu")
		(net "DELTA_L_85_10INCH_IN6_DP")
	)
	(segment
		(start 279.972516 5.104384)
		(end 279.801828 4.98475)
		(width 0.14732)
		(layer "In15.Cu")
		(net "DELTA_L_85_10INCH_IN6_DP")
	)
	(segment
		(start 262.532622 2.786634)
		(end 262.237982 2.491994)
		(width 0.14732)
		(layer "In15.Cu")
		(net "DELTA_L_85_10INCH_IN6_DP")
	)
	(segment
		(start 295.795954 5.090414)
		(end 295.625774 4.971034)
		(width 0.14732)
		(layer "In15.Cu")
		(net "DELTA_L_85_10INCH_IN6_DP")
	)
	(segment
		(start 294.468804 -1.5875)
		(end 294.112188 -1.837436)
		(width 0.14732)
		(layer "In15.Cu")
		(net "DELTA_L_85_10INCH_IN6_DP")
	)
	(segment
		(start 276.70125 -1.575562)
		(end 276.451314 -1.219454)
		(width 0.14732)
		(layer "In15.Cu")
		(net "DELTA_L_85_10INCH_IN6_DP")
	)
	(segment
		(start 281.330908 4.864862)
		(end 281.330908 4.864608)
		(width 0.14732)
		(layer "In15.Cu")
		(net "DELTA_L_85_10INCH_IN6_DP")
	)
	(segment
		(start 300.12767 -1.573022)
		(end 301.23892 4.729988)
		(width 0.14732)
		(layer "In15.Cu")
		(net "DELTA_L_85_10INCH_IN6_DP")
	)
	(segment
		(start 309.8546 -2.309622)
		(end 308.272688 -2.030476)
		(width 0.14732)
		(layer "In15.Cu")
		(net "DELTA_L_85_10INCH_IN6_DP")
	)
	(segment
		(start 320.90233 4.902962)
		(end 319.543938 5.142484)
		(width 0.14732)
		(layer "In15.Cu")
		(net "DELTA_L_85_10INCH_IN6_DP")
	)
	(segment
		(start 273.543776 4.730496)
		(end 273.42465 4.901184)
		(width 0.14732)
		(layer "In15.Cu")
		(net "DELTA_L_85_10INCH_IN6_DP")
	)
	(segment
		(start 280.663396 -1.543304)
		(end 280.41346 -1.187196)
		(width 0.14732)
		(layer "In15.Cu")
		(net "DELTA_L_85_10INCH_IN6_DP")
	)
	(segment
		(start 304.088546 -1.547622)
		(end 305.187096 4.684014)
		(width 0.14732)
		(layer "In15.Cu")
		(net "DELTA_L_85_10INCH_IN6_DP")
	)
	(segment
		(start 314.170822 -2.047494)
		(end 313.813698 -2.297176)
		(width 0.14732)
		(layer "In15.Cu")
		(net "DELTA_L_85_10INCH_IN6_DP")
	)
	(segment
		(start 313.097672 4.670552)
		(end 312.978292 4.840986)
		(width 0.14732)
		(layer "In15.Cu")
		(net "DELTA_L_85_10INCH_IN6_DP")
	)
	(segment
		(start 293.311326 4.647438)
		(end 293.191946 4.81838)
		(width 0.14732)
		(layer "In15.Cu")
		(net "DELTA_L_85_10INCH_IN6_DP")
	)
	(segment
		(start 294.112188 -1.837436)
		(end 292.530276 -1.55829)
		(width 0.14732)
		(layer "In15.Cu")
		(net "DELTA_L_85_10INCH_IN6_DP")
	)
	(segment
		(start 303.709578 5.094224)
		(end 303.539144 4.974844)
		(width 0.14732)
		(layer "In15.Cu")
		(net "DELTA_L_85_10INCH_IN6_DP")
	)
	(segment
		(start 327.439274 2.786634)
		(end 323.070728 2.786634)
		(width 0.14732)
		(layer "In15.Cu")
		(net "DELTA_L_85_10INCH_IN6_DP")
	)
	(segment
		(start 297.273726 4.680458)
		(end 297.154346 4.850892)
		(width 0.14732)
		(layer "In15.Cu")
		(net "DELTA_L_85_10INCH_IN6_DP")
	)
	(segment
		(start 285.280862 4.826508)
		(end 283.92247 5.06603)
		(width 0.14732)
		(layer "In15.Cu")
		(net "DELTA_L_85_10INCH_IN6_DP")
	)
	(segment
		(start 285.400242 4.656074)
		(end 285.280862 4.826508)
		(width 0.14732)
		(layer "In15.Cu")
		(net "DELTA_L_85_10INCH_IN6_DP")
	)
	(segment
		(start 281.450288 4.69392)
		(end 281.330908 4.864862)
		(width 0.14732)
		(layer "In15.Cu")
		(net "DELTA_L_85_10INCH_IN6_DP")
	)
	(segment
		(start 284.621224 -1.535938)
		(end 284.371288 -1.17983)
		(width 0.14732)
		(layer "In15.Cu")
		(net "DELTA_L_85_10INCH_IN6_DP")
	)
	(segment
		(start 305.187096 4.684014)
		(end 305.067716 4.854448)
		(width 0.14732)
		(layer "In15.Cu")
		(net "DELTA_L_85_10INCH_IN6_DP")
	)
	(segment
		(start 293.191946 4.818126)
		(end 291.833554 5.057902)
		(width 0.14732)
		(layer "In15.Cu")
		(net "DELTA_L_85_10INCH_IN6_DP")
	)
	(segment
		(start 297.154346 4.850892)
		(end 295.795954 5.090414)
		(width 0.14732)
		(layer "In15.Cu")
		(net "DELTA_L_85_10INCH_IN6_DP")
	)
	(segment
		(start 308.022498 -1.67386)
		(end 309.150258 4.72186)
		(width 0.14732)
		(layer "In15.Cu")
		(net "DELTA_L_85_10INCH_IN6_DP")
	)
	(segment
		(start 319.373758 5.023104)
		(end 318.119252 -2.089658)
		(width 0.14732)
		(layer "In15.Cu")
		(net "DELTA_L_85_10INCH_IN6_DP")
	)
	(segment
		(start 307.502306 5.012436)
		(end 306.277772 -1.933194)
		(width 0.14732)
		(layer "In15.Cu")
		(net "DELTA_L_85_10INCH_IN6_DP")
	)
	(segment
		(start 311.44972 4.961382)
		(end 310.211724 -2.05994)
		(width 0.14732)
		(layer "In15.Cu")
		(net "DELTA_L_85_10INCH_IN6_DP")
	)
	(segment
		(start 267.59154 3.048254)
		(end 267.279882 2.786634)
		(width 0.14732)
		(layer "In15.Cu")
		(net "DELTA_L_85_10INCH_IN6_DP")
	)
	(segment
		(start 301.11954 4.900422)
		(end 299.761148 5.139944)
		(width 0.14732)
		(layer "In15.Cu")
		(net "DELTA_L_85_10INCH_IN6_DP")
	)
	(segment
		(start 310.211724 -2.05994)
		(end 309.8546 -2.309622)
		(width 0.14732)
		(layer "In15.Cu")
		(net "DELTA_L_85_10INCH_IN6_DP")
	)
	(segment
		(start 301.960026 -2.209292)
		(end 300.377606 -1.9304)
		(width 0.14732)
		(layer "In15.Cu")
		(net "DELTA_L_85_10INCH_IN6_DP")
	)
	(segment
		(start 304.338736 -1.904238)
		(end 304.088546 -1.547622)
		(width 0.14732)
		(layer "In15.Cu")
		(net "DELTA_L_85_10INCH_IN6_DP")
	)
	(segment
		(start 277.368 4.827524)
		(end 276.009608 5.0673)
		(width 0.14732)
		(layer "In15.Cu")
		(net "DELTA_L_85_10INCH_IN6_DP")
	)
	(segment
		(start 268.799564 -1.509776)
		(end 268.550136 -1.152906)
		(width 0.14732)
		(layer "In15.Cu")
		(net "DELTA_L_85_10INCH_IN6_DP")
	)
	(segment
		(start 300.377606 -1.9304)
		(end 300.12767 -1.573022)
		(width 0.14732)
		(layer "In15.Cu")
		(net "DELTA_L_85_10INCH_IN6_DP")
	)
	(segment
		(start 293.191946 4.81838)
		(end 293.191946 4.818126)
		(width 0.14732)
		(layer "In15.Cu")
		(net "DELTA_L_85_10INCH_IN6_DP")
	)
	(segment
		(start 279.801828 4.98475)
		(end 278.640032 -1.605026)
		(width 0.14732)
		(layer "In15.Cu")
		(net "DELTA_L_85_10INCH_IN6_DP")
	)
	(segment
		(start 267.930376 4.971034)
		(end 267.59154 3.048254)
		(width 0.14732)
		(layer "In15.Cu")
		(net "DELTA_L_85_10INCH_IN6_DP")
	)
	(segment
		(start 305.920648 -2.182876)
		(end 304.338736 -1.904238)
		(width 0.14732)
		(layer "In15.Cu")
		(net "DELTA_L_85_10INCH_IN6_DP")
	)
	(segment
		(start 292.530276 -1.55829)
		(end 292.280086 -1.201674)
		(width 0.14732)
		(layer "In15.Cu")
		(net "DELTA_L_85_10INCH_IN6_DP")
	)
	(segment
		(start 306.277772 -1.933194)
		(end 305.920648 -2.182876)
		(width 0.14732)
		(layer "In15.Cu")
		(net "DELTA_L_85_10INCH_IN6_DP")
	)
	(segment
		(start 268.101064 5.090414)
		(end 267.930376 4.971034)
		(width 0.14732)
		(layer "In15.Cu")
		(net "DELTA_L_85_10INCH_IN6_DP")
	)
	(segment
		(start 299.590968 5.020564)
		(end 298.422822 -1.602486)
		(width 0.14732)
		(layer "In15.Cu")
		(net "DELTA_L_85_10INCH_IN6_DP")
	)
	(segment
		(start 311.6199 5.080762)
		(end 311.44972 4.961382)
		(width 0.14732)
		(layer "In15.Cu")
		(net "DELTA_L_85_10INCH_IN6_DP")
	)
	(segment
		(start 287.889442 5.12572)
		(end 287.7185 5.00634)
		(width 0.14732)
		(layer "In15.Cu")
		(net "DELTA_L_85_10INCH_IN6_DP")
	)
	(segment
		(start 296.23385 -1.216914)
		(end 297.273726 4.680458)
		(width 0.14732)
		(layer "In15.Cu")
		(net "DELTA_L_85_10INCH_IN6_DP")
	)
	(segment
		(start 290.505642 -1.626108)
		(end 290.149026 -1.876044)
		(width 0.14732)
		(layer "In15.Cu")
		(net "DELTA_L_85_10INCH_IN6_DP")
	)
	(segment
		(start 311.981596 -1.661414)
		(end 313.097672 4.670552)
		(width 0.14732)
		(layer "In15.Cu")
		(net "DELTA_L_85_10INCH_IN6_DP")
	)
	(segment
		(start 317.071502 4.76885)
		(end 316.952122 4.939284)
		(width 0.14732)
		(layer "In15.Cu")
		(net "DELTA_L_85_10INCH_IN6_DP")
	)
	(segment
		(start 292.280086 -1.201674)
		(end 293.311326 4.647438)
		(width 0.14732)
		(layer "In15.Cu")
		(net "DELTA_L_85_10INCH_IN6_DP")
	)
	(segment
		(start 271.895316 5.021326)
		(end 270.7386 -1.538478)
		(width 0.14732)
		(layer "In15.Cu")
		(net "DELTA_L_85_10INCH_IN6_DP")
	)
	(segment
		(start 316.18047 -2.060956)
		(end 315.93028 -1.70434)
		(width 0.14732)
		(layer "In15.Cu")
		(net "DELTA_L_85_10INCH_IN6_DP")
	)
	(segment
		(start 295.625774 4.971034)
		(end 294.468804 -1.5875)
		(width 0.14732)
		(layer "In15.Cu")
		(net "DELTA_L_85_10INCH_IN6_DP")
	)
	(segment
		(start 272.505424 -1.158748)
		(end 273.543776 4.730496)
		(width 0.14732)
		(layer "In15.Cu")
		(net "DELTA_L_85_10INCH_IN6_DP")
	)
	(segment
		(start 321.720972 -2.329942)
		(end 320.138806 -2.05105)
		(width 0.14732)
		(layer "In15.Cu")
		(net "DELTA_L_85_10INCH_IN6_DP")
	)
	(segment
		(start 278.283416 -1.854962)
		(end 276.70125 -1.575562)
		(width 0.14732)
		(layer "In15.Cu")
		(net "DELTA_L_85_10INCH_IN6_DP")
	)
	(segment
		(start 274.33778 -1.79451)
		(end 272.755106 -1.515872)
		(width 0.14732)
		(layer "In15.Cu")
		(net "DELTA_L_85_10INCH_IN6_DP")
	)
	(segment
		(start 308.272688 -2.030476)
		(end 308.022498 -1.67386)
		(width 0.14732)
		(layer "In15.Cu")
		(net "DELTA_L_85_10INCH_IN6_DP")
	)
	(segment
		(start 313.813698 -2.297176)
		(end 312.231786 -2.01803)
		(width 0.14732)
		(layer "In15.Cu")
		(net "DELTA_L_85_10INCH_IN6_DP")
	)
	(segment
		(start 286.559752 -1.565148)
		(end 286.203644 -1.815084)
		(width 0.14732)
		(layer "In15.Cu")
		(net "DELTA_L_85_10INCH_IN6_DP")
	)
	(segment
		(start 283.751782 4.946142)
		(end 282.601924 -1.572514)
		(width 0.14732)
		(layer "In15.Cu")
		(net "DELTA_L_85_10INCH_IN6_DP")
	)
	(segment
		(start 298.422822 -1.602486)
		(end 298.066206 -1.852676)
		(width 0.14732)
		(layer "In15.Cu")
		(net "DELTA_L_85_10INCH_IN6_DP")
	)
	(segment
		(start 315.93028 -1.70434)
		(end 317.071502 4.76885)
		(width 0.14732)
		(layer "In15.Cu")
		(net "DELTA_L_85_10INCH_IN6_DP")
	)
	(segment
		(start 312.978292 4.840986)
		(end 311.6199 5.080762)
		(width 0.14732)
		(layer "In15.Cu")
		(net "DELTA_L_85_10INCH_IN6_DP")
	)
	(segment
		(start 321.02171 4.732528)
		(end 320.90233 4.902962)
		(width 0.14732)
		(layer "In15.Cu")
		(net "DELTA_L_85_10INCH_IN6_DP")
	)
	(segment
		(start 269.578582 4.680712)
		(end 269.459456 4.850892)
		(width 0.14732)
		(layer "In15.Cu")
		(net "DELTA_L_85_10INCH_IN6_DP")
	)
	(segment
		(start 276.451314 -1.219454)
		(end 277.48738 4.65709)
		(width 0.14732)
		(layer "In15.Cu")
		(net "DELTA_L_85_10INCH_IN6_DP")
	)
	(segment
		(start 268.550136 -1.152906)
		(end 269.578582 4.680712)
		(width 0.14732)
		(layer "In15.Cu")
		(net "DELTA_L_85_10INCH_IN6_DP")
	)
	(segment
		(start 323.070728 2.786634)
		(end 322.911978 2.653284)
		(width 0.14732)
		(layer "In15.Cu")
		(net "DELTA_L_85_10INCH_IN6_DP")
	)
	(segment
		(start 318.119252 -2.089658)
		(end 317.762636 -2.339848)
		(width 0.14732)
		(layer "In15.Cu")
		(net "DELTA_L_85_10INCH_IN6_DP")
	)
	(segment
		(start 316.952122 4.939284)
		(end 315.59373 5.178806)
		(width 0.14732)
		(layer "In15.Cu")
		(net "DELTA_L_85_10INCH_IN6_DP")
	)
	(segment
		(start 291.663374 4.938776)
		(end 290.505642 -1.626108)
		(width 0.14732)
		(layer "In15.Cu")
		(net "DELTA_L_85_10INCH_IN6_DP")
	)
	(segment
		(start 319.543938 5.142484)
		(end 319.373758 5.023104)
		(width 0.14732)
		(layer "In15.Cu")
		(net "DELTA_L_85_10INCH_IN6_DP")
	)
	(segment
		(start 298.066206 -1.852676)
		(end 296.48404 -1.57353)
		(width 0.14732)
		(layer "In15.Cu")
		(net "DELTA_L_85_10INCH_IN6_DP")
	)
	(segment
		(start 278.640032 -1.605026)
		(end 278.283416 -1.854962)
		(width 0.14732)
		(layer "In15.Cu")
		(net "DELTA_L_85_10INCH_IN6_DP")
	)
	(segment
		(start 282.601924 -1.572514)
		(end 282.245816 -1.82245)
		(width 0.14732)
		(layer "In15.Cu")
		(net "DELTA_L_85_10INCH_IN6_DP")
	)
	(segment
		(start 275.838666 4.94792)
		(end 274.693888 -1.544574)
		(width 0.14732)
		(layer "In15.Cu")
		(net "DELTA_L_85_10INCH_IN6_DP")
	)
	(segment
		(start 307.672486 5.131816)
		(end 307.502306 5.012436)
		(width 0.14732)
		(layer "In15.Cu")
		(net "DELTA_L_85_10INCH_IN6_DP")
	)
	(segment
		(start 328.414888 3.17373)
		(end 327.733914 3.355594)
		(width 0.13208)
		(layer "B.Cu")
		(net "DELTA_L_85_10INCH_IN6_DN")
	)
	(segment
		(start 261.557008 3.17373)
		(end 262.237982 3.355594)
		(width 0.13208)
		(layer "B.Cu")
		(net "DELTA_L_85_10INCH_IN6_DN")
	)
	(segment
		(start 282.1813 -1.532382)
		(end 280.822908 -1.29286)
		(width 0.14732)
		(layer "In15.Cu")
		(net "DELTA_L_85_10INCH_IN6_DN")
	)
	(segment
		(start 279.551384 5.144262)
		(end 278.389588 -1.445514)
		(width 0.14732)
		(layer "In15.Cu")
		(net "DELTA_L_85_10INCH_IN6_DN")
	)
	(segment
		(start 313.38774 4.734814)
		(end 313.138058 5.091684)
		(width 0.14732)
		(layer "In15.Cu")
		(net "DELTA_L_85_10INCH_IN6_DN")
	)
	(segment
		(start 294.21836 -1.427988)
		(end 294.047926 -1.547368)
		(width 0.14732)
		(layer "In15.Cu")
		(net "DELTA_L_85_10INCH_IN6_DN")
	)
	(segment
		(start 272.001742 5.430774)
		(end 271.644618 5.181092)
		(width 0.14732)
		(layer "In15.Cu")
		(net "DELTA_L_85_10INCH_IN6_DN")
	)
	(segment
		(start 317.36157 4.833366)
		(end 317.111888 5.189982)
		(width 0.14732)
		(layer "In15.Cu")
		(net "DELTA_L_85_10INCH_IN6_DN")
	)
	(segment
		(start 300.537372 -1.679702)
		(end 300.417738 -1.50876)
		(width 0.14732)
		(layer "In15.Cu")
		(net "DELTA_L_85_10INCH_IN6_DN")
	)
	(segment
		(start 320.178684 -1.629918)
		(end 321.311778 4.797044)
		(width 0.14732)
		(layer "In15.Cu")
		(net "DELTA_L_85_10INCH_IN6_DN")
	)
	(segment
		(start 286.139128 -1.525016)
		(end 284.780736 -1.285494)
		(width 0.14732)
		(layer "In15.Cu")
		(net "DELTA_L_85_10INCH_IN6_DN")
	)
	(segment
		(start 278.219154 -1.564894)
		(end 276.860762 -1.325118)
		(width 0.14732)
		(layer "In15.Cu")
		(net "DELTA_L_85_10INCH_IN6_DN")
	)
	(segment
		(start 292.570154 -1.137158)
		(end 293.601394 4.711954)
		(width 0.14732)
		(layer "In15.Cu")
		(net "DELTA_L_85_10INCH_IN6_DN")
	)
	(segment
		(start 316.339982 -1.810258)
		(end 316.220348 -1.639824)
		(width 0.14732)
		(layer "In15.Cu")
		(net "DELTA_L_85_10INCH_IN6_DN")
	)
	(segment
		(start 302.065944 -1.79959)
		(end 301.89551 -1.919224)
		(width 0.14732)
		(layer "In15.Cu")
		(net "DELTA_L_85_10INCH_IN6_DN")
	)
	(segment
		(start 281.490674 5.115306)
		(end 279.908 5.394452)
		(width 0.14732)
		(layer "In15.Cu")
		(net "DELTA_L_85_10INCH_IN6_DN")
	)
	(segment
		(start 287.82518 5.415788)
		(end 287.468056 5.166106)
		(width 0.14732)
		(layer "In15.Cu")
		(net "DELTA_L_85_10INCH_IN6_DN")
	)
	(segment
		(start 274.273264 -1.504442)
		(end 272.914872 -1.265174)
		(width 0.14732)
		(layer "In15.Cu")
		(net "DELTA_L_85_10INCH_IN6_DN")
	)
	(segment
		(start 295.731692 5.380482)
		(end 295.375076 5.1308)
		(width 0.14732)
		(layer "In15.Cu")
		(net "DELTA_L_85_10INCH_IN6_DN")
	)
	(segment
		(start 299.696886 5.430012)
		(end 299.34027 5.18033)
		(width 0.14732)
		(layer "In15.Cu")
		(net "DELTA_L_85_10INCH_IN6_DN")
	)
	(segment
		(start 297.563794 4.74472)
		(end 297.314112 5.10159)
		(width 0.14732)
		(layer "In15.Cu")
		(net "DELTA_L_85_10INCH_IN6_DN")
	)
	(segment
		(start 273.833844 4.795266)
		(end 273.584162 5.151628)
		(width 0.14732)
		(layer "In15.Cu")
		(net "DELTA_L_85_10INCH_IN6_DN")
	)
	(segment
		(start 309.190644 5.142738)
		(end 307.608224 5.421884)
		(width 0.14732)
		(layer "In15.Cu")
		(net "DELTA_L_85_10INCH_IN6_DN")
	)
	(segment
		(start 301.89551 -1.919224)
		(end 300.537372 -1.679702)
		(width 0.14732)
		(layer "In15.Cu")
		(net "DELTA_L_85_10INCH_IN6_DN")
	)
	(segment
		(start 272.914872 -1.265174)
		(end 272.795492 -1.094486)
		(width 0.14732)
		(layer "In15.Cu")
		(net "DELTA_L_85_10INCH_IN6_DN")
	)
	(segment
		(start 267.179806 3.060954)
		(end 262.532622 3.060954)
		(width 0.14732)
		(layer "In15.Cu")
		(net "DELTA_L_85_10INCH_IN6_DN")
	)
	(segment
		(start 303.2887 5.134356)
		(end 302.065944 -1.79959)
		(width 0.14732)
		(layer "In15.Cu")
		(net "DELTA_L_85_10INCH_IN6_DN")
	)
	(segment
		(start 281.740356 4.758182)
		(end 281.490674 5.115306)
		(width 0.14732)
		(layer "In15.Cu")
		(net "DELTA_L_85_10INCH_IN6_DN")
	)
	(segment
		(start 321.656456 -2.039874)
		(end 320.298318 -1.800352)
		(width 0.14732)
		(layer "In15.Cu")
		(net "DELTA_L_85_10INCH_IN6_DN")
	)
	(segment
		(start 321.311778 4.797044)
		(end 321.062096 5.15366)
		(width 0.14732)
		(layer "In15.Cu")
		(net "DELTA_L_85_10INCH_IN6_DN")
	)
	(segment
		(start 312.391298 -1.767586)
		(end 312.271664 -1.596898)
		(width 0.14732)
		(layer "In15.Cu")
		(net "DELTA_L_85_10INCH_IN6_DN")
	)
	(segment
		(start 308.4322 -1.780032)
		(end 308.312566 -1.609344)
		(width 0.14732)
		(layer "In15.Cu")
		(net "DELTA_L_85_10INCH_IN6_DN")
	)
	(segment
		(start 286.309308 -1.405636)
		(end 286.139128 -1.525016)
		(width 0.14732)
		(layer "In15.Cu")
		(net "DELTA_L_85_10INCH_IN6_DN")
	)
	(segment
		(start 308.312566 -1.609344)
		(end 309.440326 4.786122)
		(width 0.14732)
		(layer "In15.Cu")
		(net "DELTA_L_85_10INCH_IN6_DN")
	)
	(segment
		(start 292.689788 -1.307846)
		(end 292.570154 -1.137158)
		(width 0.14732)
		(layer "In15.Cu")
		(net "DELTA_L_85_10INCH_IN6_DN")
	)
	(segment
		(start 304.498248 -1.65354)
		(end 304.378614 -1.483106)
		(width 0.14732)
		(layer "In15.Cu")
		(net "DELTA_L_85_10INCH_IN6_DN")
	)
	(segment
		(start 268.036802 5.380482)
		(end 267.679678 5.1308)
		(width 0.14732)
		(layer "In15.Cu")
		(net "DELTA_L_85_10INCH_IN6_DN")
	)
	(segment
		(start 278.389588 -1.445514)
		(end 278.219154 -1.564894)
		(width 0.14732)
		(layer "In15.Cu")
		(net "DELTA_L_85_10INCH_IN6_DN")
	)
	(segment
		(start 327.439274 3.060954)
		(end 322.970906 3.060954)
		(width 0.14732)
		(layer "In15.Cu")
		(net "DELTA_L_85_10INCH_IN6_DN")
	)
	(segment
		(start 280.822908 -1.29286)
		(end 280.703528 -1.12268)
		(width 0.14732)
		(layer "In15.Cu")
		(net "DELTA_L_85_10INCH_IN6_DN")
	)
	(segment
		(start 313.749436 -2.007108)
		(end 312.391298 -1.767586)
		(width 0.14732)
		(layer "In15.Cu")
		(net "DELTA_L_85_10INCH_IN6_DN")
	)
	(segment
		(start 296.643552 -1.323086)
		(end 296.523918 -1.152398)
		(width 0.14732)
		(layer "In15.Cu")
		(net "DELTA_L_85_10INCH_IN6_DN")
	)
	(segment
		(start 287.468056 5.166106)
		(end 286.309308 -1.405636)
		(width 0.14732)
		(layer "In15.Cu")
		(net "DELTA_L_85_10INCH_IN6_DN")
	)
	(segment
		(start 288.726372 -1.346708)
		(end 288.606992 -1.17602)
		(width 0.14732)
		(layer "In15.Cu")
		(net "DELTA_L_85_10INCH_IN6_DN")
	)
	(segment
		(start 271.644618 5.181092)
		(end 270.488156 -1.378966)
		(width 0.14732)
		(layer "In15.Cu")
		(net "DELTA_L_85_10INCH_IN6_DN")
	)
	(segment
		(start 275.945346 5.357368)
		(end 275.588222 5.107686)
		(width 0.14732)
		(layer "In15.Cu")
		(net "DELTA_L_85_10INCH_IN6_DN")
	)
	(segment
		(start 293.351458 5.068824)
		(end 291.769292 5.34797)
		(width 0.14732)
		(layer "In15.Cu")
		(net "DELTA_L_85_10INCH_IN6_DN")
	)
	(segment
		(start 321.827144 -1.92024)
		(end 321.656456 -2.039874)
		(width 0.14732)
		(layer "In15.Cu")
		(net "DELTA_L_85_10INCH_IN6_DN")
	)
	(segment
		(start 304.378614 -1.483106)
		(end 305.477164 4.74853)
		(width 0.14732)
		(layer "In15.Cu")
		(net "DELTA_L_85_10INCH_IN6_DN")
	)
	(segment
		(start 293.601394 4.711954)
		(end 293.351458 5.068824)
		(width 0.14732)
		(layer "In15.Cu")
		(net "DELTA_L_85_10INCH_IN6_DN")
	)
	(segment
		(start 301.279306 5.15112)
		(end 299.696886 5.430012)
		(width 0.14732)
		(layer "In15.Cu")
		(net "DELTA_L_85_10INCH_IN6_DN")
	)
	(segment
		(start 301.528988 4.794504)
		(end 301.279306 5.15112)
		(width 0.14732)
		(layer "In15.Cu")
		(net "DELTA_L_85_10INCH_IN6_DN")
	)
	(segment
		(start 309.790338 -2.019554)
		(end 308.4322 -1.780032)
		(width 0.14732)
		(layer "In15.Cu")
		(net "DELTA_L_85_10INCH_IN6_DN")
	)
	(segment
		(start 296.523918 -1.152398)
		(end 297.563794 4.74472)
		(width 0.14732)
		(layer "In15.Cu")
		(net "DELTA_L_85_10INCH_IN6_DN")
	)
	(segment
		(start 320.298318 -1.800352)
		(end 320.178684 -1.629918)
		(width 0.14732)
		(layer "In15.Cu")
		(net "DELTA_L_85_10INCH_IN6_DN")
	)
	(segment
		(start 291.769292 5.34797)
		(end 291.41293 5.098288)
		(width 0.14732)
		(layer "In15.Cu")
		(net "DELTA_L_85_10INCH_IN6_DN")
	)
	(segment
		(start 311.199022 5.121148)
		(end 309.961026 -1.900174)
		(width 0.14732)
		(layer "In15.Cu")
		(net "DELTA_L_85_10INCH_IN6_DN")
	)
	(segment
		(start 317.69812 -2.04978)
		(end 316.339982 -1.810258)
		(width 0.14732)
		(layer "In15.Cu")
		(net "DELTA_L_85_10INCH_IN6_DN")
	)
	(segment
		(start 280.703528 -1.12268)
		(end 281.740356 4.758182)
		(width 0.14732)
		(layer "In15.Cu")
		(net "DELTA_L_85_10INCH_IN6_DN")
	)
	(segment
		(start 277.527766 5.078222)
		(end 275.945346 5.357368)
		(width 0.14732)
		(layer "In15.Cu")
		(net "DELTA_L_85_10INCH_IN6_DN")
	)
	(segment
		(start 277.777448 4.721606)
		(end 277.527766 5.078222)
		(width 0.14732)
		(layer "In15.Cu")
		(net "DELTA_L_85_10INCH_IN6_DN")
	)
	(segment
		(start 267.679678 5.1308)
		(end 267.338556 3.194304)
		(width 0.14732)
		(layer "In15.Cu")
		(net "DELTA_L_85_10INCH_IN6_DN")
	)
	(segment
		(start 294.047926 -1.547368)
		(end 292.689788 -1.307846)
		(width 0.14732)
		(layer "In15.Cu")
		(net "DELTA_L_85_10INCH_IN6_DN")
	)
	(segment
		(start 305.477164 4.74853)
		(end 305.227482 5.105146)
		(width 0.14732)
		(layer "In15.Cu")
		(net "DELTA_L_85_10INCH_IN6_DN")
	)
	(segment
		(start 300.417738 -1.50876)
		(end 301.528988 4.794504)
		(width 0.14732)
		(layer "In15.Cu")
		(net "DELTA_L_85_10INCH_IN6_DN")
	)
	(segment
		(start 317.868808 -1.930146)
		(end 317.69812 -2.04978)
		(width 0.14732)
		(layer "In15.Cu")
		(net "DELTA_L_85_10INCH_IN6_DN")
	)
	(segment
		(start 268.95933 -1.259332)
		(end 268.840204 -1.088644)
		(width 0.14732)
		(layer "In15.Cu")
		(net "DELTA_L_85_10INCH_IN6_DN")
	)
	(segment
		(start 307.608224 5.421884)
		(end 307.251608 5.172202)
		(width 0.14732)
		(layer "In15.Cu")
		(net "DELTA_L_85_10INCH_IN6_DN")
	)
	(segment
		(start 305.227482 5.105146)
		(end 303.645062 5.384292)
		(width 0.14732)
		(layer "In15.Cu")
		(net "DELTA_L_85_10INCH_IN6_DN")
	)
	(segment
		(start 289.407346 5.136642)
		(end 287.82518 5.415788)
		(width 0.14732)
		(layer "In15.Cu")
		(net "DELTA_L_85_10INCH_IN6_DN")
	)
	(segment
		(start 288.606992 -1.17602)
		(end 289.657282 4.780026)
		(width 0.14732)
		(layer "In15.Cu")
		(net "DELTA_L_85_10INCH_IN6_DN")
	)
	(segment
		(start 262.532622 3.060954)
		(end 262.237982 3.355594)
		(width 0.14732)
		(layer "In15.Cu")
		(net "DELTA_L_85_10INCH_IN6_DN")
	)
	(segment
		(start 322.970906 3.060954)
		(end 322.658994 2.799334)
		(width 0.14732)
		(layer "In15.Cu")
		(net "DELTA_L_85_10INCH_IN6_DN")
	)
	(segment
		(start 272.795492 -1.094486)
		(end 273.833844 4.795266)
		(width 0.14732)
		(layer "In15.Cu")
		(net "DELTA_L_85_10INCH_IN6_DN")
	)
	(segment
		(start 285.440628 5.077206)
		(end 283.857954 5.356098)
		(width 0.14732)
		(layer "In15.Cu")
		(net "DELTA_L_85_10INCH_IN6_DN")
	)
	(segment
		(start 313.138058 5.091684)
		(end 311.555638 5.37083)
		(width 0.14732)
		(layer "In15.Cu")
		(net "DELTA_L_85_10INCH_IN6_DN")
	)
	(segment
		(start 285.69031 4.720336)
		(end 285.440628 5.077206)
		(width 0.14732)
		(layer "In15.Cu")
		(net "DELTA_L_85_10INCH_IN6_DN")
	)
	(segment
		(start 295.375076 5.1308)
		(end 294.21836 -1.427988)
		(width 0.14732)
		(layer "In15.Cu")
		(net "DELTA_L_85_10INCH_IN6_DN")
	)
	(segment
		(start 270.488156 -1.378966)
		(end 270.317722 -1.498346)
		(width 0.14732)
		(layer "In15.Cu")
		(net "DELTA_L_85_10INCH_IN6_DN")
	)
	(segment
		(start 282.35148 -1.413002)
		(end 282.1813 -1.532382)
		(width 0.14732)
		(layer "In15.Cu")
		(net "DELTA_L_85_10INCH_IN6_DN")
	)
	(segment
		(start 273.584162 5.151628)
		(end 272.001742 5.430774)
		(width 0.14732)
		(layer "In15.Cu")
		(net "DELTA_L_85_10INCH_IN6_DN")
	)
	(segment
		(start 269.618968 5.101336)
		(end 268.036802 5.380482)
		(width 0.14732)
		(layer "In15.Cu")
		(net "DELTA_L_85_10INCH_IN6_DN")
	)
	(segment
		(start 315.172852 5.219192)
		(end 313.920124 -1.887728)
		(width 0.14732)
		(layer "In15.Cu")
		(net "DELTA_L_85_10INCH_IN6_DN")
	)
	(segment
		(start 309.961026 -1.900174)
		(end 309.790338 -2.019554)
		(width 0.14732)
		(layer "In15.Cu")
		(net "DELTA_L_85_10INCH_IN6_DN")
	)
	(segment
		(start 283.501084 5.105654)
		(end 282.35148 -1.413002)
		(width 0.14732)
		(layer "In15.Cu")
		(net "DELTA_L_85_10INCH_IN6_DN")
	)
	(segment
		(start 284.780736 -1.285494)
		(end 284.661356 -1.115314)
		(width 0.14732)
		(layer "In15.Cu")
		(net "DELTA_L_85_10INCH_IN6_DN")
	)
	(segment
		(start 317.111888 5.189982)
		(end 315.529468 5.468874)
		(width 0.14732)
		(layer "In15.Cu")
		(net "DELTA_L_85_10INCH_IN6_DN")
	)
	(segment
		(start 268.840204 -1.088644)
		(end 269.86865 4.745228)
		(width 0.14732)
		(layer "In15.Cu")
		(net "DELTA_L_85_10INCH_IN6_DN")
	)
	(segment
		(start 275.588222 5.107686)
		(end 274.443444 -1.385062)
		(width 0.14732)
		(layer "In15.Cu")
		(net "DELTA_L_85_10INCH_IN6_DN")
	)
	(segment
		(start 321.062096 5.15366)
		(end 319.479676 5.432552)
		(width 0.14732)
		(layer "In15.Cu")
		(net "DELTA_L_85_10INCH_IN6_DN")
	)
	(segment
		(start 299.34027 5.18033)
		(end 298.172378 -1.442974)
		(width 0.14732)
		(layer "In15.Cu")
		(net "DELTA_L_85_10INCH_IN6_DN")
	)
	(segment
		(start 305.856386 -1.892808)
		(end 304.498248 -1.65354)
		(width 0.14732)
		(layer "In15.Cu")
		(net "DELTA_L_85_10INCH_IN6_DN")
	)
	(segment
		(start 297.314112 5.10159)
		(end 295.731692 5.380482)
		(width 0.14732)
		(layer "In15.Cu")
		(net "DELTA_L_85_10INCH_IN6_DN")
	)
	(segment
		(start 276.741382 -1.154938)
		(end 277.777448 4.721606)
		(width 0.14732)
		(layer "In15.Cu")
		(net "DELTA_L_85_10INCH_IN6_DN")
	)
	(segment
		(start 327.733914 3.355594)
		(end 327.439274 3.060954)
		(width 0.14732)
		(layer "In15.Cu")
		(net "DELTA_L_85_10INCH_IN6_DN")
	)
	(segment
		(start 270.317722 -1.498346)
		(end 268.95933 -1.259332)
		(width 0.14732)
		(layer "In15.Cu")
		(net "DELTA_L_85_10INCH_IN6_DN")
	)
	(segment
		(start 279.908 5.394452)
		(end 279.551384 5.144262)
		(width 0.14732)
		(layer "In15.Cu")
		(net "DELTA_L_85_10INCH_IN6_DN")
	)
	(segment
		(start 298.172378 -1.442974)
		(end 298.00169 -1.562608)
		(width 0.14732)
		(layer "In15.Cu")
		(net "DELTA_L_85_10INCH_IN6_DN")
	)
	(segment
		(start 303.645062 5.384292)
		(end 303.2887 5.134356)
		(width 0.14732)
		(layer "In15.Cu")
		(net "DELTA_L_85_10INCH_IN6_DN")
	)
	(segment
		(start 322.658994 2.799334)
		(end 321.827144 -1.92024)
		(width 0.14732)
		(layer "In15.Cu")
		(net "DELTA_L_85_10INCH_IN6_DN")
	)
	(segment
		(start 319.12306 5.18287)
		(end 317.868808 -1.930146)
		(width 0.14732)
		(layer "In15.Cu")
		(net "DELTA_L_85_10INCH_IN6_DN")
	)
	(segment
		(start 291.41293 5.098288)
		(end 290.255198 -1.466596)
		(width 0.14732)
		(layer "In15.Cu")
		(net "DELTA_L_85_10INCH_IN6_DN")
	)
	(segment
		(start 316.220348 -1.639824)
		(end 317.36157 4.833366)
		(width 0.14732)
		(layer "In15.Cu")
		(net "DELTA_L_85_10INCH_IN6_DN")
	)
	(segment
		(start 298.00169 -1.562608)
		(end 296.643552 -1.323086)
		(width 0.14732)
		(layer "In15.Cu")
		(net "DELTA_L_85_10INCH_IN6_DN")
	)
	(segment
		(start 276.860762 -1.325118)
		(end 276.741382 -1.154938)
		(width 0.14732)
		(layer "In15.Cu")
		(net "DELTA_L_85_10INCH_IN6_DN")
	)
	(segment
		(start 283.857954 5.356098)
		(end 283.501084 5.105654)
		(width 0.14732)
		(layer "In15.Cu")
		(net "DELTA_L_85_10INCH_IN6_DN")
	)
	(segment
		(start 290.084764 -1.585976)
		(end 288.726372 -1.346708)
		(width 0.14732)
		(layer "In15.Cu")
		(net "DELTA_L_85_10INCH_IN6_DN")
	)
	(segment
		(start 269.86865 4.745228)
		(end 269.618968 5.101336)
		(width 0.14732)
		(layer "In15.Cu")
		(net "DELTA_L_85_10INCH_IN6_DN")
	)
	(segment
		(start 267.338556 3.194304)
		(end 267.179806 3.060954)
		(width 0.14732)
		(layer "In15.Cu")
		(net "DELTA_L_85_10INCH_IN6_DN")
	)
	(segment
		(start 319.479676 5.432552)
		(end 319.12306 5.18287)
		(width 0.14732)
		(layer "In15.Cu")
		(net "DELTA_L_85_10INCH_IN6_DN")
	)
	(segment
		(start 284.661356 -1.115314)
		(end 285.69031 4.720336)
		(width 0.14732)
		(layer "In15.Cu")
		(net "DELTA_L_85_10INCH_IN6_DN")
	)
	(segment
		(start 274.443444 -1.385062)
		(end 274.273264 -1.504442)
		(width 0.14732)
		(layer "In15.Cu")
		(net "DELTA_L_85_10INCH_IN6_DN")
	)
	(segment
		(start 312.271664 -1.596898)
		(end 313.38774 4.734814)
		(width 0.14732)
		(layer "In15.Cu")
		(net "DELTA_L_85_10INCH_IN6_DN")
	)
	(segment
		(start 290.255198 -1.466596)
		(end 290.084764 -1.585976)
		(width 0.14732)
		(layer "In15.Cu")
		(net "DELTA_L_85_10INCH_IN6_DN")
	)
	(segment
		(start 306.027328 -1.773428)
		(end 305.856386 -1.892808)
		(width 0.14732)
		(layer "In15.Cu")
		(net "DELTA_L_85_10INCH_IN6_DN")
	)
	(segment
		(start 313.920124 -1.887728)
		(end 313.749436 -2.007108)
		(width 0.14732)
		(layer "In15.Cu")
		(net "DELTA_L_85_10INCH_IN6_DN")
	)
	(segment
		(start 315.529468 5.468874)
		(end 315.172852 5.219192)
		(width 0.14732)
		(layer "In15.Cu")
		(net "DELTA_L_85_10INCH_IN6_DN")
	)
	(segment
		(start 309.440326 4.786122)
		(end 309.190644 5.142738)
		(width 0.14732)
		(layer "In15.Cu")
		(net "DELTA_L_85_10INCH_IN6_DN")
	)
	(segment
		(start 311.555638 5.37083)
		(end 311.199022 5.121148)
		(width 0.14732)
		(layer "In15.Cu")
		(net "DELTA_L_85_10INCH_IN6_DN")
	)
	(segment
		(start 307.251608 5.172202)
		(end 306.027328 -1.773428)
		(width 0.14732)
		(layer "In15.Cu")
		(net "DELTA_L_85_10INCH_IN6_DN")
	)
	(segment
		(start 289.657282 4.780026)
		(end 289.407346 5.136642)
		(width 0.14732)
		(layer "In15.Cu")
		(net "DELTA_L_85_10INCH_IN6_DN")
	)
	(segment
		(start 261.557008 8.25373)
		(end 262.237982 8.435594)
		(width 0.13208)
		(layer "B.Cu")
		(net "DELTA_L_85_10INCH_IN5_DP")
	)
	(segment
		(start 328.414888 8.25373)
		(end 327.733914 8.435594)
		(width 0.13208)
		(layer "B.Cu")
		(net "DELTA_L_85_10INCH_IN5_DP")
	)
	(segment
		(start 278.219154 3.515106)
		(end 276.860762 3.754882)
		(width 0.14732)
		(layer "In13.Cu")
		(net "DELTA_L_85_10INCH_IN5_DP")
	)
	(segment
		(start 291.769292 10.42797)
		(end 291.41293 10.178288)
		(width 0.14732)
		(layer "In13.Cu")
		(net "DELTA_L_85_10INCH_IN5_DP")
	)
	(segment
		(start 309.190644 10.222738)
		(end 307.608224 10.501884)
		(width 0.14732)
		(layer "In13.Cu")
		(net "DELTA_L_85_10INCH_IN5_DP")
	)
	(segment
		(start 285.69031 9.800336)
		(end 285.440628 10.157206)
		(width 0.14732)
		(layer "In13.Cu")
		(net "DELTA_L_85_10INCH_IN5_DP")
	)
	(segment
		(start 293.351458 10.148824)
		(end 291.769292 10.42797)
		(width 0.14732)
		(layer "In13.Cu")
		(net "DELTA_L_85_10INCH_IN5_DP")
	)
	(segment
		(start 269.86865 9.825228)
		(end 269.618968 10.181336)
		(width 0.14732)
		(layer "In13.Cu")
		(net "DELTA_L_85_10INCH_IN5_DP")
	)
	(segment
		(start 327.733914 8.435594)
		(end 327.439274 8.140954)
		(width 0.14732)
		(layer "In13.Cu")
		(net "DELTA_L_85_10INCH_IN5_DP")
	)
	(segment
		(start 274.443444 3.694938)
		(end 274.273264 3.575558)
		(width 0.14732)
		(layer "In13.Cu")
		(net "DELTA_L_85_10INCH_IN5_DP")
	)
	(segment
		(start 275.588222 10.187686)
		(end 274.443444 3.694938)
		(width 0.14732)
		(layer "In13.Cu")
		(net "DELTA_L_85_10INCH_IN5_DP")
	)
	(segment
		(start 276.741382 3.925062)
		(end 277.777448 9.801606)
		(width 0.14732)
		(layer "In13.Cu")
		(net "DELTA_L_85_10INCH_IN5_DP")
	)
	(segment
		(start 303.645062 10.464292)
		(end 303.2887 10.214356)
		(width 0.14732)
		(layer "In13.Cu")
		(net "DELTA_L_85_10INCH_IN5_DP")
	)
	(segment
		(start 321.311778 9.877044)
		(end 321.062096 10.23366)
		(width 0.14732)
		(layer "In13.Cu")
		(net "DELTA_L_85_10INCH_IN5_DP")
	)
	(segment
		(start 262.532622 8.140954)
		(end 262.237982 8.435594)
		(width 0.14732)
		(layer "In13.Cu")
		(net "DELTA_L_85_10INCH_IN5_DP")
	)
	(segment
		(start 317.868808 3.149854)
		(end 317.69812 3.03022)
		(width 0.14732)
		(layer "In13.Cu")
		(net "DELTA_L_85_10INCH_IN5_DP")
	)
	(segment
		(start 281.740356 9.838182)
		(end 281.490674 10.195306)
		(width 0.14732)
		(layer "In13.Cu")
		(net "DELTA_L_85_10INCH_IN5_DP")
	)
	(segment
		(start 315.529468 10.548874)
		(end 315.172852 10.299192)
		(width 0.14732)
		(layer "In13.Cu")
		(net "DELTA_L_85_10INCH_IN5_DP")
	)
	(segment
		(start 301.279306 10.23112)
		(end 299.696886 10.510012)
		(width 0.14732)
		(layer "In13.Cu")
		(net "DELTA_L_85_10INCH_IN5_DP")
	)
	(segment
		(start 305.477164 9.82853)
		(end 305.227482 10.185146)
		(width 0.14732)
		(layer "In13.Cu")
		(net "DELTA_L_85_10INCH_IN5_DP")
	)
	(segment
		(start 304.498248 3.42646)
		(end 304.378614 3.596894)
		(width 0.14732)
		(layer "In13.Cu")
		(net "DELTA_L_85_10INCH_IN5_DP")
	)
	(segment
		(start 299.696886 10.510012)
		(end 299.34027 10.26033)
		(width 0.14732)
		(layer "In13.Cu")
		(net "DELTA_L_85_10INCH_IN5_DP")
	)
	(segment
		(start 319.479676 10.512552)
		(end 319.12306 10.26287)
		(width 0.14732)
		(layer "In13.Cu")
		(net "DELTA_L_85_10INCH_IN5_DP")
	)
	(segment
		(start 272.914872 3.814826)
		(end 272.795492 3.985514)
		(width 0.14732)
		(layer "In13.Cu")
		(net "DELTA_L_85_10INCH_IN5_DP")
	)
	(segment
		(start 294.21836 3.652012)
		(end 294.047926 3.532632)
		(width 0.14732)
		(layer "In13.Cu")
		(net "DELTA_L_85_10INCH_IN5_DP")
	)
	(segment
		(start 291.41293 10.178288)
		(end 290.255198 3.613404)
		(width 0.14732)
		(layer "In13.Cu")
		(net "DELTA_L_85_10INCH_IN5_DP")
	)
	(segment
		(start 305.856386 3.187192)
		(end 304.498248 3.42646)
		(width 0.14732)
		(layer "In13.Cu")
		(net "DELTA_L_85_10INCH_IN5_DP")
	)
	(segment
		(start 273.833844 9.875266)
		(end 273.584162 10.231628)
		(width 0.14732)
		(layer "In13.Cu")
		(net "DELTA_L_85_10INCH_IN5_DP")
	)
	(segment
		(start 300.417738 3.57124)
		(end 301.528988 9.874504)
		(width 0.14732)
		(layer "In13.Cu")
		(net "DELTA_L_85_10INCH_IN5_DP")
	)
	(segment
		(start 281.490674 10.195306)
		(end 279.908 10.474452)
		(width 0.14732)
		(layer "In13.Cu")
		(net "DELTA_L_85_10INCH_IN5_DP")
	)
	(segment
		(start 273.584162 10.231628)
		(end 272.001742 10.510774)
		(width 0.14732)
		(layer "In13.Cu")
		(net "DELTA_L_85_10INCH_IN5_DP")
	)
	(segment
		(start 268.036802 10.460482)
		(end 267.679678 10.2108)
		(width 0.14732)
		(layer "In13.Cu")
		(net "DELTA_L_85_10INCH_IN5_DP")
	)
	(segment
		(start 317.36157 9.913366)
		(end 317.111888 10.269982)
		(width 0.14732)
		(layer "In13.Cu")
		(net "DELTA_L_85_10INCH_IN5_DP")
	)
	(segment
		(start 290.084764 3.494024)
		(end 288.726372 3.733292)
		(width 0.14732)
		(layer "In13.Cu")
		(net "DELTA_L_85_10INCH_IN5_DP")
	)
	(segment
		(start 280.703528 3.95732)
		(end 281.740356 9.838182)
		(width 0.14732)
		(layer "In13.Cu")
		(net "DELTA_L_85_10INCH_IN5_DP")
	)
	(segment
		(start 321.656456 3.040126)
		(end 320.298318 3.279648)
		(width 0.14732)
		(layer "In13.Cu")
		(net "DELTA_L_85_10INCH_IN5_DP")
	)
	(segment
		(start 295.375076 10.2108)
		(end 294.21836 3.652012)
		(width 0.14732)
		(layer "In13.Cu")
		(net "DELTA_L_85_10INCH_IN5_DP")
	)
	(segment
		(start 272.795492 3.985514)
		(end 273.833844 9.875266)
		(width 0.14732)
		(layer "In13.Cu")
		(net "DELTA_L_85_10INCH_IN5_DP")
	)
	(segment
		(start 276.860762 3.754882)
		(end 276.741382 3.925062)
		(width 0.14732)
		(layer "In13.Cu")
		(net "DELTA_L_85_10INCH_IN5_DP")
	)
	(segment
		(start 286.139128 3.554984)
		(end 284.780736 3.794506)
		(width 0.14732)
		(layer "In13.Cu")
		(net "DELTA_L_85_10INCH_IN5_DP")
	)
	(segment
		(start 298.172378 3.637026)
		(end 298.00169 3.517392)
		(width 0.14732)
		(layer "In13.Cu")
		(net "DELTA_L_85_10INCH_IN5_DP")
	)
	(segment
		(start 283.501084 10.185654)
		(end 282.35148 3.666998)
		(width 0.14732)
		(layer "In13.Cu")
		(net "DELTA_L_85_10INCH_IN5_DP")
	)
	(segment
		(start 275.945346 10.437368)
		(end 275.588222 10.187686)
		(width 0.14732)
		(layer "In13.Cu")
		(net "DELTA_L_85_10INCH_IN5_DP")
	)
	(segment
		(start 321.827144 3.15976)
		(end 321.656456 3.040126)
		(width 0.14732)
		(layer "In13.Cu")
		(net "DELTA_L_85_10INCH_IN5_DP")
	)
	(segment
		(start 322.970906 8.140954)
		(end 322.658994 7.879334)
		(width 0.14732)
		(layer "In13.Cu")
		(net "DELTA_L_85_10INCH_IN5_DP")
	)
	(segment
		(start 311.555638 10.45083)
		(end 311.199022 10.201148)
		(width 0.14732)
		(layer "In13.Cu")
		(net "DELTA_L_85_10INCH_IN5_DP")
	)
	(segment
		(start 316.339982 3.269742)
		(end 316.220348 3.440176)
		(width 0.14732)
		(layer "In13.Cu")
		(net "DELTA_L_85_10INCH_IN5_DP")
	)
	(segment
		(start 268.95933 3.820668)
		(end 268.840204 3.991356)
		(width 0.14732)
		(layer "In13.Cu")
		(net "DELTA_L_85_10INCH_IN5_DP")
	)
	(segment
		(start 308.4322 3.299968)
		(end 308.312566 3.470656)
		(width 0.14732)
		(layer "In13.Cu")
		(net "DELTA_L_85_10INCH_IN5_DP")
	)
	(segment
		(start 299.34027 10.26033)
		(end 298.172378 3.637026)
		(width 0.14732)
		(layer "In13.Cu")
		(net "DELTA_L_85_10INCH_IN5_DP")
	)
	(segment
		(start 282.35148 3.666998)
		(end 282.1813 3.547618)
		(width 0.14732)
		(layer "In13.Cu")
		(net "DELTA_L_85_10INCH_IN5_DP")
	)
	(segment
		(start 296.523918 3.927602)
		(end 297.563794 9.82472)
		(width 0.14732)
		(layer "In13.Cu")
		(net "DELTA_L_85_10INCH_IN5_DP")
	)
	(segment
		(start 267.179806 8.140954)
		(end 262.532622 8.140954)
		(width 0.14732)
		(layer "In13.Cu")
		(net "DELTA_L_85_10INCH_IN5_DP")
	)
	(segment
		(start 294.047926 3.532632)
		(end 292.689788 3.772154)
		(width 0.14732)
		(layer "In13.Cu")
		(net "DELTA_L_85_10INCH_IN5_DP")
	)
	(segment
		(start 303.2887 10.214356)
		(end 302.065944 3.28041)
		(width 0.14732)
		(layer "In13.Cu")
		(net "DELTA_L_85_10INCH_IN5_DP")
	)
	(segment
		(start 313.138058 10.171684)
		(end 311.555638 10.45083)
		(width 0.14732)
		(layer "In13.Cu")
		(net "DELTA_L_85_10INCH_IN5_DP")
	)
	(segment
		(start 292.570154 3.942842)
		(end 293.601394 9.791954)
		(width 0.14732)
		(layer "In13.Cu")
		(net "DELTA_L_85_10INCH_IN5_DP")
	)
	(segment
		(start 319.12306 10.26287)
		(end 317.868808 3.149854)
		(width 0.14732)
		(layer "In13.Cu")
		(net "DELTA_L_85_10INCH_IN5_DP")
	)
	(segment
		(start 292.689788 3.772154)
		(end 292.570154 3.942842)
		(width 0.14732)
		(layer "In13.Cu")
		(net "DELTA_L_85_10INCH_IN5_DP")
	)
	(segment
		(start 277.777448 9.801606)
		(end 277.527766 10.158222)
		(width 0.14732)
		(layer "In13.Cu")
		(net "DELTA_L_85_10INCH_IN5_DP")
	)
	(segment
		(start 313.38774 9.814814)
		(end 313.138058 10.171684)
		(width 0.14732)
		(layer "In13.Cu")
		(net "DELTA_L_85_10INCH_IN5_DP")
	)
	(segment
		(start 285.440628 10.157206)
		(end 283.857954 10.436098)
		(width 0.14732)
		(layer "In13.Cu")
		(net "DELTA_L_85_10INCH_IN5_DP")
	)
	(segment
		(start 270.488156 3.701034)
		(end 270.317722 3.581654)
		(width 0.14732)
		(layer "In13.Cu")
		(net "DELTA_L_85_10INCH_IN5_DP")
	)
	(segment
		(start 306.027328 3.306572)
		(end 305.856386 3.187192)
		(width 0.14732)
		(layer "In13.Cu")
		(net "DELTA_L_85_10INCH_IN5_DP")
	)
	(segment
		(start 295.731692 10.460482)
		(end 295.375076 10.2108)
		(width 0.14732)
		(layer "In13.Cu")
		(net "DELTA_L_85_10INCH_IN5_DP")
	)
	(segment
		(start 317.69812 3.03022)
		(end 316.339982 3.269742)
		(width 0.14732)
		(layer "In13.Cu")
		(net "DELTA_L_85_10INCH_IN5_DP")
	)
	(segment
		(start 283.857954 10.436098)
		(end 283.501084 10.185654)
		(width 0.14732)
		(layer "In13.Cu")
		(net "DELTA_L_85_10INCH_IN5_DP")
	)
	(segment
		(start 313.749436 3.072892)
		(end 312.391298 3.312414)
		(width 0.14732)
		(layer "In13.Cu")
		(net "DELTA_L_85_10INCH_IN5_DP")
	)
	(segment
		(start 298.00169 3.517392)
		(end 296.643552 3.756914)
		(width 0.14732)
		(layer "In13.Cu")
		(net "DELTA_L_85_10INCH_IN5_DP")
	)
	(segment
		(start 278.389588 3.634486)
		(end 278.219154 3.515106)
		(width 0.14732)
		(layer "In13.Cu")
		(net "DELTA_L_85_10INCH_IN5_DP")
	)
	(segment
		(start 269.618968 10.181336)
		(end 268.036802 10.460482)
		(width 0.14732)
		(layer "In13.Cu")
		(net "DELTA_L_85_10INCH_IN5_DP")
	)
	(segment
		(start 320.178684 3.450082)
		(end 321.311778 9.877044)
		(width 0.14732)
		(layer "In13.Cu")
		(net "DELTA_L_85_10INCH_IN5_DP")
	)
	(segment
		(start 290.255198 3.613404)
		(end 290.084764 3.494024)
		(width 0.14732)
		(layer "In13.Cu")
		(net "DELTA_L_85_10INCH_IN5_DP")
	)
	(segment
		(start 307.608224 10.501884)
		(end 307.251608 10.252202)
		(width 0.14732)
		(layer "In13.Cu")
		(net "DELTA_L_85_10INCH_IN5_DP")
	)
	(segment
		(start 302.065944 3.28041)
		(end 301.89551 3.160776)
		(width 0.14732)
		(layer "In13.Cu")
		(net "DELTA_L_85_10INCH_IN5_DP")
	)
	(segment
		(start 267.679678 10.2108)
		(end 267.338556 8.274304)
		(width 0.14732)
		(layer "In13.Cu")
		(net "DELTA_L_85_10INCH_IN5_DP")
	)
	(segment
		(start 305.227482 10.185146)
		(end 303.645062 10.464292)
		(width 0.14732)
		(layer "In13.Cu")
		(net "DELTA_L_85_10INCH_IN5_DP")
	)
	(segment
		(start 271.644618 10.261092)
		(end 270.488156 3.701034)
		(width 0.14732)
		(layer "In13.Cu")
		(net "DELTA_L_85_10INCH_IN5_DP")
	)
	(segment
		(start 279.908 10.474452)
		(end 279.551384 10.224262)
		(width 0.14732)
		(layer "In13.Cu")
		(net "DELTA_L_85_10INCH_IN5_DP")
	)
	(segment
		(start 280.822908 3.78714)
		(end 280.703528 3.95732)
		(width 0.14732)
		(layer "In13.Cu")
		(net "DELTA_L_85_10INCH_IN5_DP")
	)
	(segment
		(start 289.407346 10.216642)
		(end 287.82518 10.495788)
		(width 0.14732)
		(layer "In13.Cu")
		(net "DELTA_L_85_10INCH_IN5_DP")
	)
	(segment
		(start 309.790338 3.060446)
		(end 308.4322 3.299968)
		(width 0.14732)
		(layer "In13.Cu")
		(net "DELTA_L_85_10INCH_IN5_DP")
	)
	(segment
		(start 297.314112 10.18159)
		(end 295.731692 10.460482)
		(width 0.14732)
		(layer "In13.Cu")
		(net "DELTA_L_85_10INCH_IN5_DP")
	)
	(segment
		(start 272.001742 10.510774)
		(end 271.644618 10.261092)
		(width 0.14732)
		(layer "In13.Cu")
		(net "DELTA_L_85_10INCH_IN5_DP")
	)
	(segment
		(start 293.601394 9.791954)
		(end 293.351458 10.148824)
		(width 0.14732)
		(layer "In13.Cu")
		(net "DELTA_L_85_10INCH_IN5_DP")
	)
	(segment
		(start 309.961026 3.179826)
		(end 309.790338 3.060446)
		(width 0.14732)
		(layer "In13.Cu")
		(net "DELTA_L_85_10INCH_IN5_DP")
	)
	(segment
		(start 308.312566 3.470656)
		(end 309.440326 9.866122)
		(width 0.14732)
		(layer "In13.Cu")
		(net "DELTA_L_85_10INCH_IN5_DP")
	)
	(segment
		(start 288.726372 3.733292)
		(end 288.606992 3.90398)
		(width 0.14732)
		(layer "In13.Cu")
		(net "DELTA_L_85_10INCH_IN5_DP")
	)
	(segment
		(start 268.840204 3.991356)
		(end 269.86865 9.825228)
		(width 0.14732)
		(layer "In13.Cu")
		(net "DELTA_L_85_10INCH_IN5_DP")
	)
	(segment
		(start 288.606992 3.90398)
		(end 289.657282 9.860026)
		(width 0.14732)
		(layer "In13.Cu")
		(net "DELTA_L_85_10INCH_IN5_DP")
	)
	(segment
		(start 286.309308 3.674364)
		(end 286.139128 3.554984)
		(width 0.14732)
		(layer "In13.Cu")
		(net "DELTA_L_85_10INCH_IN5_DP")
	)
	(segment
		(start 311.199022 10.201148)
		(end 309.961026 3.179826)
		(width 0.14732)
		(layer "In13.Cu")
		(net "DELTA_L_85_10INCH_IN5_DP")
	)
	(segment
		(start 312.391298 3.312414)
		(end 312.271664 3.483102)
		(width 0.14732)
		(layer "In13.Cu")
		(net "DELTA_L_85_10INCH_IN5_DP")
	)
	(segment
		(start 304.378614 3.596894)
		(end 305.477164 9.82853)
		(width 0.14732)
		(layer "In13.Cu")
		(net "DELTA_L_85_10INCH_IN5_DP")
	)
	(segment
		(start 300.537372 3.400298)
		(end 300.417738 3.57124)
		(width 0.14732)
		(layer "In13.Cu")
		(net "DELTA_L_85_10INCH_IN5_DP")
	)
	(segment
		(start 287.82518 10.495788)
		(end 287.468056 10.246106)
		(width 0.14732)
		(layer "In13.Cu")
		(net "DELTA_L_85_10INCH_IN5_DP")
	)
	(segment
		(start 289.657282 9.860026)
		(end 289.407346 10.216642)
		(width 0.14732)
		(layer "In13.Cu")
		(net "DELTA_L_85_10INCH_IN5_DP")
	)
	(segment
		(start 296.643552 3.756914)
		(end 296.523918 3.927602)
		(width 0.14732)
		(layer "In13.Cu")
		(net "DELTA_L_85_10INCH_IN5_DP")
	)
	(segment
		(start 284.661356 3.964686)
		(end 285.69031 9.800336)
		(width 0.14732)
		(layer "In13.Cu")
		(net "DELTA_L_85_10INCH_IN5_DP")
	)
	(segment
		(start 307.251608 10.252202)
		(end 306.027328 3.306572)
		(width 0.14732)
		(layer "In13.Cu")
		(net "DELTA_L_85_10INCH_IN5_DP")
	)
	(segment
		(start 287.468056 10.246106)
		(end 286.309308 3.674364)
		(width 0.14732)
		(layer "In13.Cu")
		(net "DELTA_L_85_10INCH_IN5_DP")
	)
	(segment
		(start 321.062096 10.23366)
		(end 319.479676 10.512552)
		(width 0.14732)
		(layer "In13.Cu")
		(net "DELTA_L_85_10INCH_IN5_DP")
	)
	(segment
		(start 270.317722 3.581654)
		(end 268.95933 3.820668)
		(width 0.14732)
		(layer "In13.Cu")
		(net "DELTA_L_85_10INCH_IN5_DP")
	)
	(segment
		(start 313.920124 3.192272)
		(end 313.749436 3.072892)
		(width 0.14732)
		(layer "In13.Cu")
		(net "DELTA_L_85_10INCH_IN5_DP")
	)
	(segment
		(start 317.111888 10.269982)
		(end 315.529468 10.548874)
		(width 0.14732)
		(layer "In13.Cu")
		(net "DELTA_L_85_10INCH_IN5_DP")
	)
	(segment
		(start 284.780736 3.794506)
		(end 284.661356 3.964686)
		(width 0.14732)
		(layer "In13.Cu")
		(net "DELTA_L_85_10INCH_IN5_DP")
	)
	(segment
		(start 316.220348 3.440176)
		(end 317.36157 9.913366)
		(width 0.14732)
		(layer "In13.Cu")
		(net "DELTA_L_85_10INCH_IN5_DP")
	)
	(segment
		(start 297.563794 9.82472)
		(end 297.314112 10.18159)
		(width 0.14732)
		(layer "In13.Cu")
		(net "DELTA_L_85_10INCH_IN5_DP")
	)
	(segment
		(start 309.440326 9.866122)
		(end 309.190644 10.222738)
		(width 0.14732)
		(layer "In13.Cu")
		(net "DELTA_L_85_10INCH_IN5_DP")
	)
	(segment
		(start 274.273264 3.575558)
		(end 272.914872 3.814826)
		(width 0.14732)
		(layer "In13.Cu")
		(net "DELTA_L_85_10INCH_IN5_DP")
	)
	(segment
		(start 322.658994 7.879334)
		(end 321.827144 3.15976)
		(width 0.14732)
		(layer "In13.Cu")
		(net "DELTA_L_85_10INCH_IN5_DP")
	)
	(segment
		(start 301.528988 9.874504)
		(end 301.279306 10.23112)
		(width 0.14732)
		(layer "In13.Cu")
		(net "DELTA_L_85_10INCH_IN5_DP")
	)
	(segment
		(start 277.527766 10.158222)
		(end 275.945346 10.437368)
		(width 0.14732)
		(layer "In13.Cu")
		(net "DELTA_L_85_10INCH_IN5_DP")
	)
	(segment
		(start 279.551384 10.224262)
		(end 278.389588 3.634486)
		(width 0.14732)
		(layer "In13.Cu")
		(net "DELTA_L_85_10INCH_IN5_DP")
	)
	(segment
		(start 301.89551 3.160776)
		(end 300.537372 3.400298)
		(width 0.14732)
		(layer "In13.Cu")
		(net "DELTA_L_85_10INCH_IN5_DP")
	)
	(segment
		(start 267.338556 8.274304)
		(end 267.179806 8.140954)
		(width 0.14732)
		(layer "In13.Cu")
		(net "DELTA_L_85_10INCH_IN5_DP")
	)
	(segment
		(start 282.1813 3.547618)
		(end 280.822908 3.78714)
		(width 0.14732)
		(layer "In13.Cu")
		(net "DELTA_L_85_10INCH_IN5_DP")
	)
	(segment
		(start 327.439274 8.140954)
		(end 322.970906 8.140954)
		(width 0.14732)
		(layer "In13.Cu")
		(net "DELTA_L_85_10INCH_IN5_DP")
	)
	(segment
		(start 315.172852 10.299192)
		(end 313.920124 3.192272)
		(width 0.14732)
		(layer "In13.Cu")
		(net "DELTA_L_85_10INCH_IN5_DP")
	)
	(segment
		(start 312.271664 3.483102)
		(end 313.38774 9.814814)
		(width 0.14732)
		(layer "In13.Cu")
		(net "DELTA_L_85_10INCH_IN5_DP")
	)
	(segment
		(start 320.298318 3.279648)
		(end 320.178684 3.450082)
		(width 0.14732)
		(layer "In13.Cu")
		(net "DELTA_L_85_10INCH_IN5_DP")
	)
	(segment
		(start 261.557008 7.753858)
		(end 262.237982 7.571994)
		(width 0.13208)
		(layer "B.Cu")
		(net "DELTA_L_85_10INCH_IN5_DN")
	)
	(segment
		(start 328.414888 7.753858)
		(end 327.733914 7.571994)
		(width 0.13208)
		(layer "B.Cu")
		(net "DELTA_L_85_10INCH_IN5_DN")
	)
	(segment
		(start 313.097672 9.750552)
		(end 312.978292 9.920986)
		(width 0.14732)
		(layer "In13.Cu")
		(net "DELTA_L_85_10INCH_IN5_DN")
	)
	(segment
		(start 327.733914 7.571994)
		(end 327.439274 7.866634)
		(width 0.14732)
		(layer "In13.Cu")
		(net "DELTA_L_85_10INCH_IN5_DN")
	)
	(segment
		(start 308.272688 3.049524)
		(end 308.022498 3.40614)
		(width 0.14732)
		(layer "In13.Cu")
		(net "DELTA_L_85_10INCH_IN5_DN")
	)
	(segment
		(start 312.231786 3.06197)
		(end 311.981596 3.418586)
		(width 0.14732)
		(layer "In13.Cu")
		(net "DELTA_L_85_10INCH_IN5_DN")
	)
	(segment
		(start 272.505424 3.921252)
		(end 273.543776 9.810496)
		(width 0.14732)
		(layer "In13.Cu")
		(net "DELTA_L_85_10INCH_IN5_DN")
	)
	(segment
		(start 311.981596 3.418586)
		(end 313.097672 9.750552)
		(width 0.14732)
		(layer "In13.Cu")
		(net "DELTA_L_85_10INCH_IN5_DN")
	)
	(segment
		(start 291.663374 10.018776)
		(end 290.505642 3.453892)
		(width 0.14732)
		(layer "In13.Cu")
		(net "DELTA_L_85_10INCH_IN5_DN")
	)
	(segment
		(start 303.539144 10.054844)
		(end 302.316642 3.120898)
		(width 0.14732)
		(layer "In13.Cu")
		(net "DELTA_L_85_10INCH_IN5_DN")
	)
	(segment
		(start 270.7386 3.541522)
		(end 270.382238 3.291586)
		(width 0.14732)
		(layer "In13.Cu")
		(net "DELTA_L_85_10INCH_IN5_DN")
	)
	(segment
		(start 296.48404 3.50647)
		(end 296.23385 3.863086)
		(width 0.14732)
		(layer "In13.Cu")
		(net "DELTA_L_85_10INCH_IN5_DN")
	)
	(segment
		(start 315.93028 3.37566)
		(end 317.071502 9.84885)
		(width 0.14732)
		(layer "In13.Cu")
		(net "DELTA_L_85_10INCH_IN5_DN")
	)
	(segment
		(start 317.071502 9.84885)
		(end 316.952122 10.019284)
		(width 0.14732)
		(layer "In13.Cu")
		(net "DELTA_L_85_10INCH_IN5_DN")
	)
	(segment
		(start 278.283416 3.225038)
		(end 276.70125 3.504438)
		(width 0.14732)
		(layer "In13.Cu")
		(net "DELTA_L_85_10INCH_IN5_DN")
	)
	(segment
		(start 278.640032 3.474974)
		(end 278.283416 3.225038)
		(width 0.14732)
		(layer "In13.Cu")
		(net "DELTA_L_85_10INCH_IN5_DN")
	)
	(segment
		(start 307.502306 10.092436)
		(end 306.277772 3.146806)
		(width 0.14732)
		(layer "In13.Cu")
		(net "DELTA_L_85_10INCH_IN5_DN")
	)
	(segment
		(start 307.672486 10.211816)
		(end 307.502306 10.092436)
		(width 0.14732)
		(layer "In13.Cu")
		(net "DELTA_L_85_10INCH_IN5_DN")
	)
	(segment
		(start 304.338736 3.175762)
		(end 304.088546 3.532378)
		(width 0.14732)
		(layer "In13.Cu")
		(net "DELTA_L_85_10INCH_IN5_DN")
	)
	(segment
		(start 284.371288 3.90017)
		(end 285.400242 9.736074)
		(width 0.14732)
		(layer "In13.Cu")
		(net "DELTA_L_85_10INCH_IN5_DN")
	)
	(segment
		(start 293.191946 9.89838)
		(end 293.191946 9.898126)
		(width 0.14732)
		(layer "In13.Cu")
		(net "DELTA_L_85_10INCH_IN5_DN")
	)
	(segment
		(start 302.316642 3.120898)
		(end 301.960026 2.870708)
		(width 0.14732)
		(layer "In13.Cu")
		(net "DELTA_L_85_10INCH_IN5_DN")
	)
	(segment
		(start 305.920648 2.897124)
		(end 304.338736 3.175762)
		(width 0.14732)
		(layer "In13.Cu")
		(net "DELTA_L_85_10INCH_IN5_DN")
	)
	(segment
		(start 288.566606 3.482594)
		(end 288.316924 3.839718)
		(width 0.14732)
		(layer "In13.Cu")
		(net "DELTA_L_85_10INCH_IN5_DN")
	)
	(segment
		(start 269.578582 9.760712)
		(end 269.459456 9.930892)
		(width 0.14732)
		(layer "In13.Cu")
		(net "DELTA_L_85_10INCH_IN5_DN")
	)
	(segment
		(start 267.59154 8.128254)
		(end 267.279882 7.866634)
		(width 0.14732)
		(layer "In13.Cu")
		(net "DELTA_L_85_10INCH_IN5_DN")
	)
	(segment
		(start 290.149026 3.203956)
		(end 288.566606 3.482594)
		(width 0.14732)
		(layer "In13.Cu")
		(net "DELTA_L_85_10INCH_IN5_DN")
	)
	(segment
		(start 322.911978 7.733284)
		(end 322.077588 3.000248)
		(width 0.14732)
		(layer "In13.Cu")
		(net "DELTA_L_85_10INCH_IN5_DN")
	)
	(segment
		(start 309.150258 9.80186)
		(end 309.030878 9.97204)
		(width 0.14732)
		(layer "In13.Cu")
		(net "DELTA_L_85_10INCH_IN5_DN")
	)
	(segment
		(start 277.368 9.907524)
		(end 276.009608 10.1473)
		(width 0.14732)
		(layer "In13.Cu")
		(net "DELTA_L_85_10INCH_IN5_DN")
	)
	(segment
		(start 312.978292 9.920986)
		(end 311.6199 10.160762)
		(width 0.14732)
		(layer "In13.Cu")
		(net "DELTA_L_85_10INCH_IN5_DN")
	)
	(segment
		(start 297.154346 9.930892)
		(end 295.795954 10.170414)
		(width 0.14732)
		(layer "In13.Cu")
		(net "DELTA_L_85_10INCH_IN5_DN")
	)
	(segment
		(start 305.187096 9.764014)
		(end 305.067716 9.934448)
		(width 0.14732)
		(layer "In13.Cu")
		(net "DELTA_L_85_10INCH_IN5_DN")
	)
	(segment
		(start 299.590968 10.100564)
		(end 298.422822 3.477514)
		(width 0.14732)
		(layer "In13.Cu")
		(net "DELTA_L_85_10INCH_IN5_DN")
	)
	(segment
		(start 281.330908 9.944608)
		(end 279.972516 10.184384)
		(width 0.14732)
		(layer "In13.Cu")
		(net "DELTA_L_85_10INCH_IN5_DN")
	)
	(segment
		(start 304.088546 3.532378)
		(end 305.187096 9.764014)
		(width 0.14732)
		(layer "In13.Cu")
		(net "DELTA_L_85_10INCH_IN5_DN")
	)
	(segment
		(start 283.751782 10.026142)
		(end 282.601924 3.507486)
		(width 0.14732)
		(layer "In13.Cu")
		(net "DELTA_L_85_10INCH_IN5_DN")
	)
	(segment
		(start 299.761148 10.219944)
		(end 299.590968 10.100564)
		(width 0.14732)
		(layer "In13.Cu")
		(net "DELTA_L_85_10INCH_IN5_DN")
	)
	(segment
		(start 298.066206 3.227324)
		(end 296.48404 3.50647)
		(width 0.14732)
		(layer "In13.Cu")
		(net "DELTA_L_85_10INCH_IN5_DN")
	)
	(segment
		(start 315.59373 10.258806)
		(end 315.42355 10.139426)
		(width 0.14732)
		(layer "In13.Cu")
		(net "DELTA_L_85_10INCH_IN5_DN")
	)
	(segment
		(start 269.459456 9.930892)
		(end 268.101064 10.170414)
		(width 0.14732)
		(layer "In13.Cu")
		(net "DELTA_L_85_10INCH_IN5_DN")
	)
	(segment
		(start 319.543938 10.222484)
		(end 319.373758 10.103104)
		(width 0.14732)
		(layer "In13.Cu")
		(net "DELTA_L_85_10INCH_IN5_DN")
	)
	(segment
		(start 280.41346 3.892804)
		(end 281.450288 9.77392)
		(width 0.14732)
		(layer "In13.Cu")
		(net "DELTA_L_85_10INCH_IN5_DN")
	)
	(segment
		(start 285.280862 9.906508)
		(end 283.92247 10.14603)
		(width 0.14732)
		(layer "In13.Cu")
		(net "DELTA_L_85_10INCH_IN5_DN")
	)
	(segment
		(start 273.543776 9.810496)
		(end 273.42465 9.981184)
		(width 0.14732)
		(layer "In13.Cu")
		(net "DELTA_L_85_10INCH_IN5_DN")
	)
	(segment
		(start 319.888616 3.385566)
		(end 321.02171 9.812528)
		(width 0.14732)
		(layer "In13.Cu")
		(net "DELTA_L_85_10INCH_IN5_DN")
	)
	(segment
		(start 289.247834 9.965944)
		(end 287.889442 10.20572)
		(width 0.14732)
		(layer "In13.Cu")
		(net "DELTA_L_85_10INCH_IN5_DN")
	)
	(segment
		(start 291.833554 10.137902)
		(end 291.663374 10.018776)
		(width 0.14732)
		(layer "In13.Cu")
		(net "DELTA_L_85_10INCH_IN5_DN")
	)
	(segment
		(start 281.450288 9.77392)
		(end 281.330908 9.944862)
		(width 0.14732)
		(layer "In13.Cu")
		(net "DELTA_L_85_10INCH_IN5_DN")
	)
	(segment
		(start 300.12767 3.506978)
		(end 301.23892 9.809988)
		(width 0.14732)
		(layer "In13.Cu")
		(net "DELTA_L_85_10INCH_IN5_DN")
	)
	(segment
		(start 286.559752 3.514852)
		(end 286.203644 3.264916)
		(width 0.14732)
		(layer "In13.Cu")
		(net "DELTA_L_85_10INCH_IN5_DN")
	)
	(segment
		(start 277.48738 9.73709)
		(end 277.368 9.907524)
		(width 0.14732)
		(layer "In13.Cu")
		(net "DELTA_L_85_10INCH_IN5_DN")
	)
	(segment
		(start 285.400242 9.736074)
		(end 285.280862 9.906508)
		(width 0.14732)
		(layer "In13.Cu")
		(net "DELTA_L_85_10INCH_IN5_DN")
	)
	(segment
		(start 311.44972 10.041382)
		(end 310.211724 3.02006)
		(width 0.14732)
		(layer "In13.Cu")
		(net "DELTA_L_85_10INCH_IN5_DN")
	)
	(segment
		(start 318.119252 2.990342)
		(end 317.762636 2.740152)
		(width 0.14732)
		(layer "In13.Cu")
		(net "DELTA_L_85_10INCH_IN5_DN")
	)
	(segment
		(start 290.505642 3.453892)
		(end 290.149026 3.203956)
		(width 0.14732)
		(layer "In13.Cu")
		(net "DELTA_L_85_10INCH_IN5_DN")
	)
	(segment
		(start 320.138806 3.02895)
		(end 319.888616 3.385566)
		(width 0.14732)
		(layer "In13.Cu")
		(net "DELTA_L_85_10INCH_IN5_DN")
	)
	(segment
		(start 296.23385 3.863086)
		(end 297.273726 9.760458)
		(width 0.14732)
		(layer "In13.Cu")
		(net "DELTA_L_85_10INCH_IN5_DN")
	)
	(segment
		(start 267.930376 10.051034)
		(end 267.59154 8.128254)
		(width 0.14732)
		(layer "In13.Cu")
		(net "DELTA_L_85_10INCH_IN5_DN")
	)
	(segment
		(start 313.813698 2.782824)
		(end 312.231786 3.06197)
		(width 0.14732)
		(layer "In13.Cu")
		(net "DELTA_L_85_10INCH_IN5_DN")
	)
	(segment
		(start 279.972516 10.184384)
		(end 279.801828 10.06475)
		(width 0.14732)
		(layer "In13.Cu")
		(net "DELTA_L_85_10INCH_IN5_DN")
	)
	(segment
		(start 297.273726 9.760458)
		(end 297.154346 9.930892)
		(width 0.14732)
		(layer "In13.Cu")
		(net "DELTA_L_85_10INCH_IN5_DN")
	)
	(segment
		(start 274.693888 3.535426)
		(end 274.33778 3.28549)
		(width 0.14732)
		(layer "In13.Cu")
		(net "DELTA_L_85_10INCH_IN5_DN")
	)
	(segment
		(start 316.952122 10.019284)
		(end 315.59373 10.258806)
		(width 0.14732)
		(layer "In13.Cu")
		(net "DELTA_L_85_10INCH_IN5_DN")
	)
	(segment
		(start 268.101064 10.170414)
		(end 267.930376 10.051034)
		(width 0.14732)
		(layer "In13.Cu")
		(net "DELTA_L_85_10INCH_IN5_DN")
	)
	(segment
		(start 327.439274 7.866634)
		(end 323.070728 7.866634)
		(width 0.14732)
		(layer "In13.Cu")
		(net "DELTA_L_85_10INCH_IN5_DN")
	)
	(segment
		(start 275.838666 10.02792)
		(end 274.693888 3.535426)
		(width 0.14732)
		(layer "In13.Cu")
		(net "DELTA_L_85_10INCH_IN5_DN")
	)
	(segment
		(start 274.33778 3.28549)
		(end 272.755106 3.564128)
		(width 0.14732)
		(layer "In13.Cu")
		(net "DELTA_L_85_10INCH_IN5_DN")
	)
	(segment
		(start 283.92247 10.14603)
		(end 283.751782 10.026142)
		(width 0.14732)
		(layer "In13.Cu")
		(net "DELTA_L_85_10INCH_IN5_DN")
	)
	(segment
		(start 317.762636 2.740152)
		(end 316.18047 3.019044)
		(width 0.14732)
		(layer "In13.Cu")
		(net "DELTA_L_85_10INCH_IN5_DN")
	)
	(segment
		(start 294.112188 3.242564)
		(end 292.530276 3.52171)
		(width 0.14732)
		(layer "In13.Cu")
		(net "DELTA_L_85_10INCH_IN5_DN")
	)
	(segment
		(start 308.022498 3.40614)
		(end 309.150258 9.80186)
		(width 0.14732)
		(layer "In13.Cu")
		(net "DELTA_L_85_10INCH_IN5_DN")
	)
	(segment
		(start 294.468804 3.4925)
		(end 294.112188 3.242564)
		(width 0.14732)
		(layer "In13.Cu")
		(net "DELTA_L_85_10INCH_IN5_DN")
	)
	(segment
		(start 268.799564 3.570224)
		(end 268.550136 3.927094)
		(width 0.14732)
		(layer "In13.Cu")
		(net "DELTA_L_85_10INCH_IN5_DN")
	)
	(segment
		(start 293.311326 9.727438)
		(end 293.191946 9.89838)
		(width 0.14732)
		(layer "In13.Cu")
		(net "DELTA_L_85_10INCH_IN5_DN")
	)
	(segment
		(start 303.709578 10.174224)
		(end 303.539144 10.054844)
		(width 0.14732)
		(layer "In13.Cu")
		(net "DELTA_L_85_10INCH_IN5_DN")
	)
	(segment
		(start 321.02171 9.812528)
		(end 320.90233 9.982962)
		(width 0.14732)
		(layer "In13.Cu")
		(net "DELTA_L_85_10INCH_IN5_DN")
	)
	(segment
		(start 267.279882 7.866634)
		(end 262.532622 7.866634)
		(width 0.14732)
		(layer "In13.Cu")
		(net "DELTA_L_85_10INCH_IN5_DN")
	)
	(segment
		(start 315.42355 10.139426)
		(end 314.170822 3.032506)
		(width 0.14732)
		(layer "In13.Cu")
		(net "DELTA_L_85_10INCH_IN5_DN")
	)
	(segment
		(start 276.70125 3.504438)
		(end 276.451314 3.860546)
		(width 0.14732)
		(layer "In13.Cu")
		(net "DELTA_L_85_10INCH_IN5_DN")
	)
	(segment
		(start 284.621224 3.544062)
		(end 284.371288 3.90017)
		(width 0.14732)
		(layer "In13.Cu")
		(net "DELTA_L_85_10INCH_IN5_DN")
	)
	(segment
		(start 289.247834 9.966198)
		(end 289.247834 9.965944)
		(width 0.14732)
		(layer "In13.Cu")
		(net "DELTA_L_85_10INCH_IN5_DN")
	)
	(segment
		(start 292.280086 3.878326)
		(end 293.311326 9.727438)
		(width 0.14732)
		(layer "In13.Cu")
		(net "DELTA_L_85_10INCH_IN5_DN")
	)
	(segment
		(start 281.330908 9.944862)
		(end 281.330908 9.944608)
		(width 0.14732)
		(layer "In13.Cu")
		(net "DELTA_L_85_10INCH_IN5_DN")
	)
	(segment
		(start 321.720972 2.750058)
		(end 320.138806 3.02895)
		(width 0.14732)
		(layer "In13.Cu")
		(net "DELTA_L_85_10INCH_IN5_DN")
	)
	(segment
		(start 286.203644 3.264916)
		(end 284.621224 3.544062)
		(width 0.14732)
		(layer "In13.Cu")
		(net "DELTA_L_85_10INCH_IN5_DN")
	)
	(segment
		(start 288.316924 3.839718)
		(end 289.367214 9.79551)
		(width 0.14732)
		(layer "In13.Cu")
		(net "DELTA_L_85_10INCH_IN5_DN")
	)
	(segment
		(start 268.550136 3.927094)
		(end 269.578582 9.760712)
		(width 0.14732)
		(layer "In13.Cu")
		(net "DELTA_L_85_10INCH_IN5_DN")
	)
	(segment
		(start 276.451314 3.860546)
		(end 277.48738 9.73709)
		(width 0.14732)
		(layer "In13.Cu")
		(net "DELTA_L_85_10INCH_IN5_DN")
	)
	(segment
		(start 272.066004 10.220706)
		(end 271.895316 10.101326)
		(width 0.14732)
		(layer "In13.Cu")
		(net "DELTA_L_85_10INCH_IN5_DN")
	)
	(segment
		(start 273.42465 9.981184)
		(end 272.066004 10.220706)
		(width 0.14732)
		(layer "In13.Cu")
		(net "DELTA_L_85_10INCH_IN5_DN")
	)
	(segment
		(start 271.895316 10.101326)
		(end 270.7386 3.541522)
		(width 0.14732)
		(layer "In13.Cu")
		(net "DELTA_L_85_10INCH_IN5_DN")
	)
	(segment
		(start 295.625774 10.051034)
		(end 294.468804 3.4925)
		(width 0.14732)
		(layer "In13.Cu")
		(net "DELTA_L_85_10INCH_IN5_DN")
	)
	(segment
		(start 272.755106 3.564128)
		(end 272.505424 3.921252)
		(width 0.14732)
		(layer "In13.Cu")
		(net "DELTA_L_85_10INCH_IN5_DN")
	)
	(segment
		(start 282.601924 3.507486)
		(end 282.245816 3.25755)
		(width 0.14732)
		(layer "In13.Cu")
		(net "DELTA_L_85_10INCH_IN5_DN")
	)
	(segment
		(start 306.277772 3.146806)
		(end 305.920648 2.897124)
		(width 0.14732)
		(layer "In13.Cu")
		(net "DELTA_L_85_10INCH_IN5_DN")
	)
	(segment
		(start 305.067716 9.934448)
		(end 303.709578 10.174224)
		(width 0.14732)
		(layer "In13.Cu")
		(net "DELTA_L_85_10INCH_IN5_DN")
	)
	(segment
		(start 301.960026 2.870708)
		(end 300.377606 3.1496)
		(width 0.14732)
		(layer "In13.Cu")
		(net "DELTA_L_85_10INCH_IN5_DN")
	)
	(segment
		(start 322.077588 3.000248)
		(end 321.720972 2.750058)
		(width 0.14732)
		(layer "In13.Cu")
		(net "DELTA_L_85_10INCH_IN5_DN")
	)
	(segment
		(start 280.663396 3.536696)
		(end 280.41346 3.892804)
		(width 0.14732)
		(layer "In13.Cu")
		(net "DELTA_L_85_10INCH_IN5_DN")
	)
	(segment
		(start 282.245816 3.25755)
		(end 280.663396 3.536696)
		(width 0.14732)
		(layer "In13.Cu")
		(net "DELTA_L_85_10INCH_IN5_DN")
	)
	(segment
		(start 287.889442 10.20572)
		(end 287.7185 10.08634)
		(width 0.14732)
		(layer "In13.Cu")
		(net "DELTA_L_85_10INCH_IN5_DN")
	)
	(segment
		(start 262.532622 7.866634)
		(end 262.237982 7.571994)
		(width 0.14732)
		(layer "In13.Cu")
		(net "DELTA_L_85_10INCH_IN5_DN")
	)
	(segment
		(start 301.23892 9.809988)
		(end 301.11954 9.980422)
		(width 0.14732)
		(layer "In13.Cu")
		(net "DELTA_L_85_10INCH_IN5_DN")
	)
	(segment
		(start 298.422822 3.477514)
		(end 298.066206 3.227324)
		(width 0.14732)
		(layer "In13.Cu")
		(net "DELTA_L_85_10INCH_IN5_DN")
	)
	(segment
		(start 316.18047 3.019044)
		(end 315.93028 3.37566)
		(width 0.14732)
		(layer "In13.Cu")
		(net "DELTA_L_85_10INCH_IN5_DN")
	)
	(segment
		(start 309.8546 2.770378)
		(end 308.272688 3.049524)
		(width 0.14732)
		(layer "In13.Cu")
		(net "DELTA_L_85_10INCH_IN5_DN")
	)
	(segment
		(start 293.191946 9.898126)
		(end 291.833554 10.137902)
		(width 0.14732)
		(layer "In13.Cu")
		(net "DELTA_L_85_10INCH_IN5_DN")
	)
	(segment
		(start 309.030878 9.97204)
		(end 307.672486 10.211816)
		(width 0.14732)
		(layer "In13.Cu")
		(net "DELTA_L_85_10INCH_IN5_DN")
	)
	(segment
		(start 295.795954 10.170414)
		(end 295.625774 10.051034)
		(width 0.14732)
		(layer "In13.Cu")
		(net "DELTA_L_85_10INCH_IN5_DN")
	)
	(segment
		(start 279.801828 10.06475)
		(end 278.640032 3.474974)
		(width 0.14732)
		(layer "In13.Cu")
		(net "DELTA_L_85_10INCH_IN5_DN")
	)
	(segment
		(start 310.211724 3.02006)
		(end 309.8546 2.770378)
		(width 0.14732)
		(layer "In13.Cu")
		(net "DELTA_L_85_10INCH_IN5_DN")
	)
	(segment
		(start 289.367214 9.79551)
		(end 289.247834 9.966198)
		(width 0.14732)
		(layer "In13.Cu")
		(net "DELTA_L_85_10INCH_IN5_DN")
	)
	(segment
		(start 319.373758 10.103104)
		(end 318.119252 2.990342)
		(width 0.14732)
		(layer "In13.Cu")
		(net "DELTA_L_85_10INCH_IN5_DN")
	)
	(segment
		(start 320.90233 9.982962)
		(end 319.543938 10.222484)
		(width 0.14732)
		(layer "In13.Cu")
		(net "DELTA_L_85_10INCH_IN5_DN")
	)
	(segment
		(start 276.009608 10.1473)
		(end 275.838666 10.02792)
		(width 0.14732)
		(layer "In13.Cu")
		(net "DELTA_L_85_10INCH_IN5_DN")
	)
	(segment
		(start 287.7185 10.08634)
		(end 286.559752 3.514852)
		(width 0.14732)
		(layer "In13.Cu")
		(net "DELTA_L_85_10INCH_IN5_DN")
	)
	(segment
		(start 270.382238 3.291586)
		(end 268.799564 3.570224)
		(width 0.14732)
		(layer "In13.Cu")
		(net "DELTA_L_85_10INCH_IN5_DN")
	)
	(segment
		(start 311.6199 10.160762)
		(end 311.44972 10.041382)
		(width 0.14732)
		(layer "In13.Cu")
		(net "DELTA_L_85_10INCH_IN5_DN")
	)
	(segment
		(start 292.530276 3.52171)
		(end 292.280086 3.878326)
		(width 0.14732)
		(layer "In13.Cu")
		(net "DELTA_L_85_10INCH_IN5_DN")
	)
	(segment
		(start 323.070728 7.866634)
		(end 322.911978 7.733284)
		(width 0.14732)
		(layer "In13.Cu")
		(net "DELTA_L_85_10INCH_IN5_DN")
	)
	(segment
		(start 301.11954 9.980422)
		(end 299.761148 10.219944)
		(width 0.14732)
		(layer "In13.Cu")
		(net "DELTA_L_85_10INCH_IN5_DN")
	)
	(segment
		(start 300.377606 3.1496)
		(end 300.12767 3.506978)
		(width 0.14732)
		(layer "In13.Cu")
		(net "DELTA_L_85_10INCH_IN5_DN")
	)
	(segment
		(start 314.170822 3.032506)
		(end 313.813698 2.782824)
		(width 0.14732)
		(layer "In13.Cu")
		(net "DELTA_L_85_10INCH_IN5_DN")
	)
	(segment
		(start 233.529378 -250.3805)
		(end 233.468672 -250.441206)
		(width 0.254)
		(layer "F.Cu")
		(net "VFG_3P3A_CLK_GEN")
	)
	(segment
		(start 233.468672 -250.441206)
		(end 232.368852 -250.441206)
		(width 0.254)
		(layer "F.Cu")
		(net "VFG_3P3A_CLK_GEN")
	)
	(via
		(at 232.368852 -250.441206)
		(size 0.508)
		(drill 0.254)
		(layers "F.Cu" "B.Cu")
		(net "VFG_3P3A_CLK_GEN")
	)
	(segment
		(start 232.363772 -250.436126)
		(end 232.363772 -250.363736)
		(width 0.381)
		(layer "B.Cu")
		(net "VFG_3P3A_CLK_GEN")
	)
	(segment
		(start 233.5022 -250.511818)
		(end 233.445812 -250.568206)
		(width 0.254)
		(layer "B.Cu")
		(net "VFG_3P3A_CLK_GEN")
	)
	(segment
		(start 233.14533 -249.582178)
		(end 233.5149 -249.582178)
		(width 0.381)
		(layer "B.Cu")
		(net "VFG_3P3A_CLK_GEN")
	)
	(segment
		(start 232.495852 -250.568206)
		(end 232.368852 -250.441206)
		(width 0.254)
		(layer "B.Cu")
		(net "VFG_3P3A_CLK_GEN")
	)
	(segment
		(start 232.368852 -250.441206)
		(end 232.363772 -250.436126)
		(width 0.381)
		(layer "B.Cu")
		(net "VFG_3P3A_CLK_GEN")
	)
	(segment
		(start 233.445812 -250.568206)
		(end 232.495852 -250.568206)
		(width 0.254)
		(layer "B.Cu")
		(net "VFG_3P3A_CLK_GEN")
	)
	(segment
		(start 232.363772 -250.363736)
		(end 233.14533 -249.582178)
		(width 0.381)
		(layer "B.Cu")
		(net "VFG_3P3A_CLK_GEN")
	)
	(segment
		(start 233.50855 -250.505468)
		(end 233.5022 -250.511818)
		(width 0.254)
		(layer "B.Cu")
		(net "VFG_3P3A_CLK_GEN")
	)
	(segment
		(start 233.5022 -251.479558)
		(end 233.5022 -250.511818)
		(width 0.254)
		(layer "B.Cu")
		(net "VFG_3P3A_CLK_GEN")
	)
	(segment
		(start 237.279434 -250.3805)
		(end 237.997492 -250.3805)
		(width 0.254)
		(layer "F.Cu")
		(net "VFG3P3_CLK_GEN")
	)
	(segment
		(start 234.654344 -252.505464)
		(end 234.654344 -253.046992)
		(width 0.254)
		(layer "F.Cu")
		(net "VFG3P3_CLK_GEN")
	)
	(segment
		(start 234.654344 -248.093484)
		(end 234.67822 -248.069608)
		(width 0.12954)
		(layer "F.Cu")
		(net "VFG3P3_CLK_GEN")
	)
	(segment
		(start 234.654344 -253.046992)
		(end 234.80776 -253.200408)
		(width 0.254)
		(layer "F.Cu")
		(net "VFG3P3_CLK_GEN")
	)
	(segment
		(start 234.654344 -248.755408)
		(end 234.654344 -248.093484)
		(width 0.12954)
		(layer "F.Cu")
		(net "VFG3P3_CLK_GEN")
	)
	(segment
		(start 236.65434 -253.037848)
		(end 236.80674 -253.190248)
		(width 0.254)
		(layer "F.Cu")
		(net "VFG3P3_CLK_GEN")
	)
	(segment
		(start 236.65434 -252.505464)
		(end 236.65434 -253.037848)
		(width 0.254)
		(layer "F.Cu")
		(net "VFG3P3_CLK_GEN")
	)
	(via
		(at 233.69778 -245.44528)
		(size 0.6604)
		(drill 0.3302)
		(layers "F.Cu" "B.Cu")
		(net "VFG3P3_CLK_GEN")
	)
	(via
		(at 236.80674 -253.190248)
		(size 0.508)
		(drill 0.254)
		(layers "F.Cu" "B.Cu")
		(net "VFG3P3_CLK_GEN")
	)
	(via
		(at 233.16692 -247.637808)
		(size 0.508)
		(drill 0.254)
		(layers "F.Cu" "B.Cu")
		(net "VFG3P3_CLK_GEN")
	)
	(via
		(at 234.67822 -248.069608)
		(size 0.508)
		(drill 0.254)
		(layers "F.Cu" "B.Cu")
		(net "VFG3P3_CLK_GEN")
	)
	(via
		(at 235.65866 -245.4783)
		(size 0.6604)
		(drill 0.3302)
		(layers "F.Cu" "B.Cu")
		(net "VFG3P3_CLK_GEN")
	)
	(via
		(at 237.997492 -250.3805)
		(size 0.508)
		(drill 0.254)
		(layers "F.Cu" "B.Cu")
		(net "VFG3P3_CLK_GEN")
	)
	(via
		(at 234.80776 -253.200408)
		(size 0.508)
		(drill 0.254)
		(layers "F.Cu" "B.Cu")
		(net "VFG3P3_CLK_GEN")
	)
	(segment
		(start 13.589 -95.545148)
		(end 13.589 -94.325948)
		(width 0.12954)
		(layer "F.Cu")
		(net "USB_HUB_TEST")
	)
	(segment
		(start 14.064996 -96.723962)
		(end 14.064996 -96.021144)
		(width 0.12954)
		(layer "F.Cu")
		(net "USB_HUB_TEST")
	)
	(segment
		(start 13.589 -94.325948)
		(end 14.01826 -93.896688)
		(width 0.12954)
		(layer "F.Cu")
		(net "USB_HUB_TEST")
	)
	(segment
		(start 14.01826 -93.896688)
		(end 14.01826 -93.087698)
		(width 0.12954)
		(layer "F.Cu")
		(net "USB_HUB_TEST")
	)
	(segment
		(start 14.064996 -96.021144)
		(end 13.589 -95.545148)
		(width 0.12954)
		(layer "F.Cu")
		(net "USB_HUB_TEST")
	)
	(via
		(at 13.589 -94.325948)
		(size 0.762)
		(drill 0.381)
		(layers "F.Cu" "B.Cu")
		(net "USB_HUB_TEST")
	)
	(segment
		(start 335.953608 -56.908446)
		(end 336.49285 -56.908446)
		(width 0.12954)
		(layer "F.Cu")
		(net "TP_CLK_100M_PCH_1_DP")
	)
	(via
		(at 335.953608 -56.908446)
		(size 0.4572)
		(drill 0.2032)
		(layers "F.Cu" "B.Cu")
		(net "TP_CLK_100M_PCH_1_DP")
	)
	(segment
		(start 336.767424 -56.438546)
		(end 337.306666 -56.438546)
		(width 0.12954)
		(layer "F.Cu")
		(net "TP_CLK_100M_PCH_1_DN")
	)
	(via
		(at 336.767424 -56.438546)
		(size 0.4572)
		(drill 0.2032)
		(layers "F.Cu" "B.Cu")
		(net "TP_CLK_100M_PCH_1_DN")
	)
	(segment
		(start 235.321856 -254.459232)
		(end 235.25988 -254.521208)
		(width 0.12954)
		(layer "F.Cu")
		(net "SMB_HOST_CLK_GEN2_3V3AUX_SDA")
	)
	(segment
		(start 235.25988 -255.495298)
		(end 235.48848 -255.723898)
		(width 0.12954)
		(layer "F.Cu")
		(net "SMB_HOST_CLK_GEN2_3V3AUX_SDA")
	)
	(segment
		(start 235.654342 -254.126746)
		(end 235.321856 -254.459232)
		(width 0.12954)
		(layer "F.Cu")
		(net "SMB_HOST_CLK_GEN2_3V3AUX_SDA")
	)
	(segment
		(start 235.25988 -254.521208)
		(end 235.25988 -255.495298)
		(width 0.12954)
		(layer "F.Cu")
		(net "SMB_HOST_CLK_GEN2_3V3AUX_SDA")
	)
	(segment
		(start 235.654342 -252.505464)
		(end 235.654342 -254.126746)
		(width 0.12954)
		(layer "F.Cu")
		(net "SMB_HOST_CLK_GEN2_3V3AUX_SDA")
	)
	(segment
		(start 235.48848 -255.723898)
		(end 235.51388 -255.723898)
		(width 0.12954)
		(layer "F.Cu")
		(net "SMB_HOST_CLK_GEN2_3V3AUX_SDA")
	)
	(via
		(at 235.321856 -254.459232)
		(size 0.762)
		(drill 0.381)
		(layers "F.Cu" "B.Cu")
		(net "SMB_HOST_CLK_GEN2_3V3AUX_SDA")
	)
	(segment
		(start 236.52988 -255.723898)
		(end 236.78388 -255.469898)
		(width 0.12954)
		(layer "F.Cu")
		(net "SMB_HOST_CLK_GEN2_3V3AUX_SCL")
	)
	(segment
		(start 236.52988 -257.139948)
		(end 236.52988 -255.723898)
		(width 0.12954)
		(layer "F.Cu")
		(net "SMB_HOST_CLK_GEN2_3V3AUX_SCL")
	)
	(segment
		(start 236.78388 -255.469898)
		(end 236.78388 -254.472948)
		(width 0.12954)
		(layer "F.Cu")
		(net "SMB_HOST_CLK_GEN2_3V3AUX_SCL")
	)
	(segment
		(start 236.154468 -252.505464)
		(end 236.154468 -253.843536)
		(width 0.12954)
		(layer "F.Cu")
		(net "SMB_HOST_CLK_GEN2_3V3AUX_SCL")
	)
	(segment
		(start 236.154468 -253.843536)
		(end 236.78388 -254.472948)
		(width 0.12954)
		(layer "F.Cu")
		(net "SMB_HOST_CLK_GEN2_3V3AUX_SCL")
	)
	(via
		(at 236.78388 -254.472948)
		(size 0.762)
		(drill 0.381)
		(layers "F.Cu" "B.Cu")
		(net "SMB_HOST_CLK_GEN2_3V3AUX_SCL")
	)
	(via
		(at 236.52988 -257.139948)
		(size 0.508)
		(drill 0.254)
		(layers "F.Cu" "B.Cu")
		(net "SMB_HOST_CLK_GEN2_3V3AUX_SCL")
	)
	(via
		(at 226.29368 -98.133408)
		(size 0.508)
		(drill 0.254)
		(layers "F.Cu" "B.Cu")
		(net "SMB_HOST_CLK_GEN2_3V3AUX_SCL")
	)
	(via
		(at 246.56542 -95.979488)
		(size 0.508)
		(drill 0.254)
		(layers "F.Cu" "B.Cu")
		(net "SMB_HOST_CLK_GEN2_3V3AUX_SCL")
	)
	(segment
		(start 246.56542 -95.979488)
		(end 246.44985 -96.095058)
		(width 0.12954)
		(layer "B.Cu")
		(net "SMB_HOST_CLK_GEN2_3V3AUX_SCL")
	)
	(segment
		(start 246.44985 -96.095058)
		(end 246.44985 -96.761808)
		(width 0.12954)
		(layer "B.Cu")
		(net "SMB_HOST_CLK_GEN2_3V3AUX_SCL")
	)
	(segment
		(start 226.243896 -130.054858)
		(end 226.243896 -127.573024)
		(width 0.127)
		(layer "In2.Cu")
		(net "SMB_HOST_CLK_GEN2_3V3AUX_SCL")
	)
	(segment
		(start 223.64954 -102.400608)
		(end 226.87788 -99.172268)
		(width 0.127)
		(layer "In2.Cu")
		(net "SMB_HOST_CLK_GEN2_3V3AUX_SCL")
	)
	(segment
		(start 222.66148 -137.257282)
		(end 222.66148 -133.211062)
		(width 0.127)
		(layer "In2.Cu")
		(net "SMB_HOST_CLK_GEN2_3V3AUX_SCL")
	)
	(segment
		(start 223.992694 -131.879848)
		(end 224.418906 -131.879848)
		(width 0.127)
		(layer "In2.Cu")
		(net "SMB_HOST_CLK_GEN2_3V3AUX_SCL")
	)
	(segment
		(start 226.243896 -127.573024)
		(end 223.64954 -124.978668)
		(width 0.127)
		(layer "In2.Cu")
		(net "SMB_HOST_CLK_GEN2_3V3AUX_SCL")
	)
	(segment
		(start 244.5258 -230.884222)
		(end 244.5258 -171.290488)
		(width 0.127)
		(layer "In2.Cu")
		(net "SMB_HOST_CLK_GEN2_3V3AUX_SCL")
	)
	(segment
		(start 224.418906 -131.879848)
		(end 226.243896 -130.054858)
		(width 0.127)
		(layer "In2.Cu")
		(net "SMB_HOST_CLK_GEN2_3V3AUX_SCL")
	)
	(segment
		(start 244.5258 -171.290488)
		(end 241.2873 -168.051988)
		(width 0.127)
		(layer "In2.Cu")
		(net "SMB_HOST_CLK_GEN2_3V3AUX_SCL")
	)
	(segment
		(start 223.64954 -124.978668)
		(end 223.64954 -102.400608)
		(width 0.127)
		(layer "In2.Cu")
		(net "SMB_HOST_CLK_GEN2_3V3AUX_SCL")
	)
	(segment
		(start 236.52988 -257.139948)
		(end 231.8004 -252.410468)
		(width 0.127)
		(layer "In2.Cu")
		(net "SMB_HOST_CLK_GEN2_3V3AUX_SCL")
	)
	(segment
		(start 226.87788 -99.172268)
		(end 226.87788 -98.717608)
		(width 0.127)
		(layer "In2.Cu")
		(net "SMB_HOST_CLK_GEN2_3V3AUX_SCL")
	)
	(segment
		(start 222.66148 -133.211062)
		(end 223.992694 -131.879848)
		(width 0.127)
		(layer "In2.Cu")
		(net "SMB_HOST_CLK_GEN2_3V3AUX_SCL")
	)
	(segment
		(start 226.87788 -98.717608)
		(end 226.29368 -98.133408)
		(width 0.127)
		(layer "In2.Cu")
		(net "SMB_HOST_CLK_GEN2_3V3AUX_SCL")
	)
	(segment
		(start 241.2873 -155.883102)
		(end 222.66148 -137.257282)
		(width 0.127)
		(layer "In2.Cu")
		(net "SMB_HOST_CLK_GEN2_3V3AUX_SCL")
	)
	(segment
		(start 241.2873 -168.051988)
		(end 241.2873 -155.883102)
		(width 0.127)
		(layer "In2.Cu")
		(net "SMB_HOST_CLK_GEN2_3V3AUX_SCL")
	)
	(segment
		(start 231.8004 -243.609622)
		(end 244.5258 -230.884222)
		(width 0.127)
		(layer "In2.Cu")
		(net "SMB_HOST_CLK_GEN2_3V3AUX_SCL")
	)
	(segment
		(start 231.8004 -252.410468)
		(end 231.8004 -243.609622)
		(width 0.127)
		(layer "In2.Cu")
		(net "SMB_HOST_CLK_GEN2_3V3AUX_SCL")
	)
	(segment
		(start 243.017294 -94.181168)
		(end 236.53496 -94.181168)
		(width 0.127)
		(layer "In15.Cu")
		(net "SMB_HOST_CLK_GEN2_3V3AUX_SCL")
	)
	(segment
		(start 246.499126 -95.913194)
		(end 244.74932 -95.913194)
		(width 0.127)
		(layer "In15.Cu")
		(net "SMB_HOST_CLK_GEN2_3V3AUX_SCL")
	)
	(segment
		(start 244.74932 -95.913194)
		(end 243.017294 -94.181168)
		(width 0.127)
		(layer "In15.Cu")
		(net "SMB_HOST_CLK_GEN2_3V3AUX_SCL")
	)
	(segment
		(start 246.56542 -95.979488)
		(end 246.499126 -95.913194)
		(width 0.127)
		(layer "In15.Cu")
		(net "SMB_HOST_CLK_GEN2_3V3AUX_SCL")
	)
	(segment
		(start 236.53496 -94.181168)
		(end 232.24998 -98.466148)
		(width 0.127)
		(layer "In15.Cu")
		(net "SMB_HOST_CLK_GEN2_3V3AUX_SCL")
	)
	(segment
		(start 226.62642 -98.466148)
		(end 226.29368 -98.133408)
		(width 0.127)
		(layer "In15.Cu")
		(net "SMB_HOST_CLK_GEN2_3V3AUX_SCL")
	)
	(segment
		(start 232.24998 -98.466148)
		(end 226.62642 -98.466148)
		(width 0.127)
		(layer "In15.Cu")
		(net "SMB_HOST_CLK_GEN2_3V3AUX_SCL")
	)
	(segment
		(start 190.06312 -425.275248)
		(end 190.05042 -425.287948)
		(width 0.12954)
		(layer "F.Cu")
		(net "PDB_PRSNT_N")
	)
	(segment
		(start 190.05042 -427.319948)
		(end 190.05042 -426.303948)
		(width 0.12954)
		(layer "F.Cu")
		(net "PDB_PRSNT_N")
	)
	(segment
		(start 190.05042 -425.287948)
		(end 190.05042 -426.303948)
		(width 0.12954)
		(layer "F.Cu")
		(net "PDB_PRSNT_N")
	)
	(segment
		(start 190.05042 -427.319948)
		(end 191.883284 -427.319948)
		(width 0.12954)
		(layer "F.Cu")
		(net "PDB_PRSNT_N")
	)
	(segment
		(start 191.883284 -427.319948)
		(end 191.89827 -427.304962)
		(width 0.12954)
		(layer "F.Cu")
		(net "PDB_PRSNT_N")
	)
	(segment
		(start 190.91148 -425.275248)
		(end 190.06312 -425.275248)
		(width 0.12954)
		(layer "F.Cu")
		(net "PDB_PRSNT_N")
	)
	(via
		(at 233.17708 -424.90644)
		(size 0.508)
		(drill 0.254)
		(layers "F.Cu" "B.Cu")
		(net "PDB_PRSNT_N")
	)
	(via
		(at 190.91148 -425.275248)
		(size 0.508)
		(drill 0.254)
		(layers "F.Cu" "B.Cu")
		(net "PDB_PRSNT_N")
	)
	(segment
		(start 232.567734 -427.159674)
		(end 233.37012 -427.96206)
		(width 0.12954)
		(layer "B.Cu")
		(net "PDB_PRSNT_N")
	)
	(segment
		(start 234.26928 -423.81424)
		(end 233.17708 -424.90644)
		(width 0.12954)
		(layer "B.Cu")
		(net "PDB_PRSNT_N")
	)
	(segment
		(start 232.567734 -425.4754)
		(end 232.567734 -427.159674)
		(width 0.12954)
		(layer "B.Cu")
		(net "PDB_PRSNT_N")
	)
	(segment
		(start 234.26928 -423.401998)
		(end 234.26928 -423.81424)
		(width 0.12954)
		(layer "B.Cu")
		(net "PDB_PRSNT_N")
	)
	(segment
		(start 233.136694 -424.90644)
		(end 232.567734 -425.4754)
		(width 0.12954)
		(layer "B.Cu")
		(net "PDB_PRSNT_N")
	)
	(segment
		(start 233.17708 -424.90644)
		(end 233.136694 -424.90644)
		(width 0.12954)
		(layer "B.Cu")
		(net "PDB_PRSNT_N")
	)
	(segment
		(start 190.91148 -425.275248)
		(end 191.1731 -425.536868)
		(width 0.127)
		(layer "In2.Cu")
		(net "PDB_PRSNT_N")
	)
	(segment
		(start 231.46766 -436.3212)
		(end 231.46766 -426.61586)
		(width 0.127)
		(layer "In2.Cu")
		(net "PDB_PRSNT_N")
	)
	(segment
		(start 231.46766 -426.61586)
		(end 233.17708 -424.90644)
		(width 0.127)
		(layer "In2.Cu")
		(net "PDB_PRSNT_N")
	)
	(segment
		(start 191.1731 -429.84166)
		(end 198.82358 -437.49214)
		(width 0.127)
		(layer "In2.Cu")
		(net "PDB_PRSNT_N")
	)
	(segment
		(start 191.1731 -425.536868)
		(end 191.1731 -429.84166)
		(width 0.127)
		(layer "In2.Cu")
		(net "PDB_PRSNT_N")
	)
	(segment
		(start 198.82358 -437.49214)
		(end 230.29672 -437.49214)
		(width 0.127)
		(layer "In2.Cu")
		(net "PDB_PRSNT_N")
	)
	(segment
		(start 230.29672 -437.49214)
		(end 231.46766 -436.3212)
		(width 0.127)
		(layer "In2.Cu")
		(net "PDB_PRSNT_N")
	)
	(segment
		(start 182.78094 -423.33926)
		(end 182.02402 -424.09618)
		(width 0.127)
		(layer "In6.Cu")
		(net "PDB_PRSNT_N")
	)
	(segment
		(start 186.36234 -423.33926)
		(end 182.78094 -423.33926)
		(width 0.127)
		(layer "In6.Cu")
		(net "PDB_PRSNT_N")
	)
	(segment
		(start 176.25314 -423.4434)
		(end 176.25314 -411.0228)
		(width 0.127)
		(layer "In6.Cu")
		(net "PDB_PRSNT_N")
	)
	(segment
		(start 190.631572 -424.99534)
		(end 188.01842 -424.99534)
		(width 0.127)
		(layer "In6.Cu")
		(net "PDB_PRSNT_N")
	)
	(segment
		(start 176.25314 -411.0228)
		(end 174.879 -409.64866)
		(width 0.127)
		(layer "In6.Cu")
		(net "PDB_PRSNT_N")
	)
	(segment
		(start 188.01842 -424.99534)
		(end 186.36234 -423.33926)
		(width 0.127)
		(layer "In6.Cu")
		(net "PDB_PRSNT_N")
	)
	(segment
		(start 182.02402 -424.09618)
		(end 176.90592 -424.09618)
		(width 0.127)
		(layer "In6.Cu")
		(net "PDB_PRSNT_N")
	)
	(segment
		(start 190.91148 -425.275248)
		(end 190.631572 -424.99534)
		(width 0.127)
		(layer "In6.Cu")
		(net "PDB_PRSNT_N")
	)
	(segment
		(start 174.879 -409.64866)
		(end 174.879 -409.4226)
		(width 0.127)
		(layer "In6.Cu")
		(net "PDB_PRSNT_N")
	)
	(segment
		(start 176.90592 -424.09618)
		(end 176.25314 -423.4434)
		(width 0.127)
		(layer "In6.Cu")
		(net "PDB_PRSNT_N")
	)
	(segment
		(start 235.654342 -248.755408)
		(end 235.654342 -247.51538)
		(width 0.12954)
		(layer "F.Cu")
		(net "P3V3_PWRGD_CLKGEN")
	)
	(segment
		(start 234.126278 -245.987316)
		(end 235.133642 -246.99468)
		(width 0.12954)
		(layer "F.Cu")
		(net "P3V3_PWRGD_CLKGEN")
	)
	(segment
		(start 234.126278 -245.811548)
		(end 234.126278 -245.987316)
		(width 0.12954)
		(layer "F.Cu")
		(net "P3V3_PWRGD_CLKGEN")
	)
	(segment
		(start 235.654342 -247.51538)
		(end 235.133642 -246.99468)
		(width 0.12954)
		(layer "F.Cu")
		(net "P3V3_PWRGD_CLKGEN")
	)
	(via
		(at 235.133642 -246.99468)
		(size 0.762)
		(drill 0.381)
		(layers "F.Cu" "B.Cu")
		(net "P3V3_PWRGD_CLKGEN")
	)
	(segment
		(start 61.963808 -39.381176)
		(end 61.53277 -39.381176)
		(width 0.12954)
		(layer "F.Cu")
		(net "P3V3_OCP_UV_2_R1")
	)
	(segment
		(start 62.35446 -40.564308)
		(end 62.35446 -39.771828)
		(width 0.12954)
		(layer "F.Cu")
		(net "P3V3_OCP_UV_2_R1")
	)
	(segment
		(start 62.35446 -39.771828)
		(end 61.963808 -39.381176)
		(width 0.12954)
		(layer "F.Cu")
		(net "P3V3_OCP_UV_2_R1")
	)
	(via
		(at 62.35446 -40.564308)
		(size 0.508)
		(drill 0.254)
		(layers "F.Cu" "B.Cu")
		(net "P3V3_OCP_UV_2_R1")
	)
	(via
		(at 81.51876 -60.546488)
		(size 0.508)
		(drill 0.254)
		(layers "F.Cu" "B.Cu")
		(net "P3V3_OCP_UV_2_R1")
	)
	(segment
		(start 81.51876 -59.497976)
		(end 80.837532 -58.816748)
		(width 0.12954)
		(layer "B.Cu")
		(net "P3V3_OCP_UV_2_R1")
	)
	(segment
		(start 80.837532 -58.816748)
		(end 80.812132 -58.816748)
		(width 0.12954)
		(layer "B.Cu")
		(net "P3V3_OCP_UV_2_R1")
	)
	(segment
		(start 81.51876 -60.546488)
		(end 81.51876 -59.497976)
		(width 0.12954)
		(layer "B.Cu")
		(net "P3V3_OCP_UV_2_R1")
	)
	(segment
		(start 79.49946 -57.495948)
		(end 79.49946 -55.842408)
		(width 0.127)
		(layer "In2.Cu")
		(net "P3V3_OCP_UV_2_R1")
	)
	(segment
		(start 81.51876 -60.546488)
		(end 81.51876 -59.515248)
		(width 0.127)
		(layer "In2.Cu")
		(net "P3V3_OCP_UV_2_R1")
	)
	(segment
		(start 62.35446 -41.504108)
		(end 62.35446 -40.564308)
		(width 0.127)
		(layer "In2.Cu")
		(net "P3V3_OCP_UV_2_R1")
	)
	(segment
		(start 79.49946 -55.842408)
		(end 74.216768 -50.559716)
		(width 0.127)
		(layer "In2.Cu")
		(net "P3V3_OCP_UV_2_R1")
	)
	(segment
		(start 74.216768 -45.705776)
		(end 71.0311 -42.520108)
		(width 0.127)
		(layer "In2.Cu")
		(net "P3V3_OCP_UV_2_R1")
	)
	(segment
		(start 63.37046 -42.520108)
		(end 62.35446 -41.504108)
		(width 0.127)
		(layer "In2.Cu")
		(net "P3V3_OCP_UV_2_R1")
	)
	(segment
		(start 74.216768 -50.559716)
		(end 74.216768 -45.705776)
		(width 0.127)
		(layer "In2.Cu")
		(net "P3V3_OCP_UV_2_R1")
	)
	(segment
		(start 71.0311 -42.520108)
		(end 63.37046 -42.520108)
		(width 0.127)
		(layer "In2.Cu")
		(net "P3V3_OCP_UV_2_R1")
	)
	(segment
		(start 81.51876 -59.515248)
		(end 79.49946 -57.495948)
		(width 0.127)
		(layer "In2.Cu")
		(net "P3V3_OCP_UV_2_R1")
	)
	(segment
		(start 59.95162 -40.6019)
		(end 59.753754 -40.404034)
		(width 0.12954)
		(layer "F.Cu")
		(net "P3V3_OCP_EN_2_R")
	)
	(segment
		(start 60.84062 -41.105328)
		(end 60.84062 -40.277288)
		(width 0.12954)
		(layer "F.Cu")
		(net "P3V3_OCP_EN_2_R")
	)
	(segment
		(start 60.2996 -41.646348)
		(end 59.95162 -41.298368)
		(width 0.12954)
		(layer "F.Cu")
		(net "P3V3_OCP_EN_2_R")
	)
	(segment
		(start 61.086746 -40.031162)
		(end 61.53277 -40.031162)
		(width 0.12954)
		(layer "F.Cu")
		(net "P3V3_OCP_EN_2_R")
	)
	(segment
		(start 60.84062 -40.277288)
		(end 61.086746 -40.031162)
		(width 0.12954)
		(layer "F.Cu")
		(net "P3V3_OCP_EN_2_R")
	)
	(segment
		(start 60.2996 -41.646348)
		(end 60.84062 -41.105328)
		(width 0.12954)
		(layer "F.Cu")
		(net "P3V3_OCP_EN_2_R")
	)
	(segment
		(start 59.33313 -39.148004)
		(end 59.33313 -40.404034)
		(width 0.12954)
		(layer "F.Cu")
		(net "P3V3_OCP_EN_2_R")
	)
	(segment
		(start 59.95162 -41.298368)
		(end 59.95162 -40.6019)
		(width 0.12954)
		(layer "F.Cu")
		(net "P3V3_OCP_EN_2_R")
	)
	(segment
		(start 59.753754 -40.404034)
		(end 59.33313 -40.404034)
		(width 0.12954)
		(layer "F.Cu")
		(net "P3V3_OCP_EN_2_R")
	)
	(via
		(at 60.2996 -41.646348)
		(size 0.762)
		(drill 0.381)
		(layers "F.Cu" "B.Cu")
		(net "P3V3_OCP_EN_2_R")
	)
	(segment
		(start 63.04788 -40.681148)
		(end 62.92088 -40.554148)
		(width 0.12954)
		(layer "F.Cu")
		(net "P3V3_OCP_2_EN_G")
	)
	(segment
		(start 64.06769 -41.316148)
		(end 63.43269 -40.681148)
		(width 0.12954)
		(layer "F.Cu")
		(net "P3V3_OCP_2_EN_G")
	)
	(segment
		(start 62.92088 -40.190928)
		(end 63.080646 -40.031162)
		(width 0.12954)
		(layer "F.Cu")
		(net "P3V3_OCP_2_EN_G")
	)
	(segment
		(start 65.20561 -40.608758)
		(end 65.913 -41.316148)
		(width 0.12954)
		(layer "F.Cu")
		(net "P3V3_OCP_2_EN_G")
	)
	(segment
		(start 64.708024 -40.608758)
		(end 65.20561 -40.608758)
		(width 0.12954)
		(layer "F.Cu")
		(net "P3V3_OCP_2_EN_G")
	)
	(segment
		(start 63.43269 -40.681148)
		(end 63.04788 -40.681148)
		(width 0.12954)
		(layer "F.Cu")
		(net "P3V3_OCP_2_EN_G")
	)
	(segment
		(start 62.92088 -40.554148)
		(end 62.92088 -40.190928)
		(width 0.12954)
		(layer "F.Cu")
		(net "P3V3_OCP_2_EN_G")
	)
	(segment
		(start 63.080646 -40.031162)
		(end 63.43269 -40.031162)
		(width 0.12954)
		(layer "F.Cu")
		(net "P3V3_OCP_2_EN_G")
	)
	(segment
		(start 65.913 -41.316148)
		(end 64.06769 -41.316148)
		(width 0.12954)
		(layer "F.Cu")
		(net "P3V3_OCP_2_EN_G")
	)
	(via
		(at 65.913 -41.316148)
		(size 0.762)
		(drill 0.381)
		(layers "F.Cu" "B.Cu")
		(net "P3V3_OCP_2_EN_G")
	)
	(segment
		(start 462.48701 -41.002458)
		(end 462.052162 -41.002458)
		(width 0.12954)
		(layer "F.Cu")
		(net "P3V3_OCP_1_EN_G")
	)
	(segment
		(start 461.93964 -41.11498)
		(end 461.93964 -41.55694)
		(width 0.12954)
		(layer "F.Cu")
		(net "P3V3_OCP_1_EN_G")
	)
	(segment
		(start 463.82432 -41.56964)
		(end 463.82432 -41.772586)
		(width 0.12954)
		(layer "F.Cu")
		(net "P3V3_OCP_1_EN_G")
	)
	(segment
		(start 461.93964 -41.55694)
		(end 462.035144 -41.652444)
		(width 0.12954)
		(layer "F.Cu")
		(net "P3V3_OCP_1_EN_G")
	)
	(segment
		(start 462.966562 -43.198034)
		(end 462.943448 -43.221148)
		(width 0.12954)
		(layer "F.Cu")
		(net "P3V3_OCP_1_EN_G")
	)
	(segment
		(start 463.7913 -41.53662)
		(end 462.602834 -41.53662)
		(width 0.12954)
		(layer "F.Cu")
		(net "P3V3_OCP_1_EN_G")
	)
	(segment
		(start 463.82432 -41.772586)
		(end 462.966562 -42.630344)
		(width 0.12954)
		(layer "F.Cu")
		(net "P3V3_OCP_1_EN_G")
	)
	(segment
		(start 462.035144 -41.652444)
		(end 462.48701 -41.652444)
		(width 0.12954)
		(layer "F.Cu")
		(net "P3V3_OCP_1_EN_G")
	)
	(segment
		(start 462.966562 -42.630344)
		(end 462.966562 -43.198034)
		(width 0.12954)
		(layer "F.Cu")
		(net "P3V3_OCP_1_EN_G")
	)
	(segment
		(start 463.82432 -41.56964)
		(end 463.7913 -41.53662)
		(width 0.12954)
		(layer "F.Cu")
		(net "P3V3_OCP_1_EN_G")
	)
	(segment
		(start 462.602834 -41.53662)
		(end 462.48701 -41.652444)
		(width 0.12954)
		(layer "F.Cu")
		(net "P3V3_OCP_1_EN_G")
	)
	(segment
		(start 462.052162 -41.002458)
		(end 461.93964 -41.11498)
		(width 0.12954)
		(layer "F.Cu")
		(net "P3V3_OCP_1_EN_G")
	)
	(via
		(at 463.82432 -41.56964)
		(size 0.762)
		(drill 0.381)
		(layers "F.Cu" "B.Cu")
		(net "P3V3_OCP_1_EN_G")
	)
	(segment
		(start 292.342316 -47.352458)
		(end 292.344856 -47.354998)
		(width 0.12954)
		(layer "F.Cu")
		(net "P3V3_E1S_EN_1_R")
	)
	(segment
		(start 292.94328 -58.4454)
		(end 292.928802 -58.459878)
		(width 0.12954)
		(layer "F.Cu")
		(net "P3V3_E1S_EN_1_R")
	)
	(segment
		(start 290.73348 -56.299608)
		(end 290.73348 -47.793148)
		(width 0.12954)
		(layer "F.Cu")
		(net "P3V3_E1S_EN_1_R")
	)
	(segment
		(start 290.73348 -56.657748)
		(end 291.49548 -57.419748)
		(width 0.12954)
		(layer "F.Cu")
		(net "P3V3_E1S_EN_1_R")
	)
	(segment
		(start 292.344856 -47.354998)
		(end 292.79088 -47.354998)
		(width 0.12954)
		(layer "F.Cu")
		(net "P3V3_E1S_EN_1_R")
	)
	(segment
		(start 290.73348 -56.299608)
		(end 290.73348 -56.657748)
		(width 0.12954)
		(layer "F.Cu")
		(net "P3V3_E1S_EN_1_R")
	)
	(segment
		(start 291.49548 -57.419748)
		(end 292.202108 -57.419748)
		(width 0.12954)
		(layer "F.Cu")
		(net "P3V3_E1S_EN_1_R")
	)
	(segment
		(start 292.202108 -57.419748)
		(end 292.94328 -58.16092)
		(width 0.12954)
		(layer "F.Cu")
		(net "P3V3_E1S_EN_1_R")
	)
	(segment
		(start 292.94328 -58.16092)
		(end 292.94328 -58.4454)
		(width 0.12954)
		(layer "F.Cu")
		(net "P3V3_E1S_EN_1_R")
	)
	(segment
		(start 290.73348 -47.793148)
		(end 291.17417 -47.352458)
		(width 0.12954)
		(layer "F.Cu")
		(net "P3V3_E1S_EN_1_R")
	)
	(segment
		(start 291.17417 -47.352458)
		(end 292.342316 -47.352458)
		(width 0.12954)
		(layer "F.Cu")
		(net "P3V3_E1S_EN_1_R")
	)
	(via
		(at 290.73348 -56.299608)
		(size 0.762)
		(drill 0.381)
		(layers "F.Cu" "B.Cu")
		(net "P3V3_E1S_EN_1_R")
	)
	(segment
		(start 292.928802 -57.044082)
		(end 292.928802 -56.559958)
		(width 0.12954)
		(layer "F.Cu")
		(net "P3V3_E1S_0_EN_G")
	)
	(segment
		(start 293.99103 -56.147716)
		(end 293.578788 -56.559958)
		(width 0.12954)
		(layer "F.Cu")
		(net "P3V3_E1S_0_EN_G")
	)
	(segment
		(start 293.07028 -57.18556)
		(end 292.928802 -57.044082)
		(width 0.12954)
		(layer "F.Cu")
		(net "P3V3_E1S_0_EN_G")
	)
	(segment
		(start 293.578788 -57.007252)
		(end 293.40048 -57.18556)
		(width 0.12954)
		(layer "F.Cu")
		(net "P3V3_E1S_0_EN_G")
	)
	(segment
		(start 293.40048 -57.18556)
		(end 293.07028 -57.18556)
		(width 0.12954)
		(layer "F.Cu")
		(net "P3V3_E1S_0_EN_G")
	)
	(segment
		(start 293.99103 -55.113428)
		(end 293.99103 -56.147716)
		(width 0.12954)
		(layer "F.Cu")
		(net "P3V3_E1S_0_EN_G")
	)
	(segment
		(start 293.578788 -56.559958)
		(end 293.578788 -57.007252)
		(width 0.12954)
		(layer "F.Cu")
		(net "P3V3_E1S_0_EN_G")
	)
	(segment
		(start 293.99103 -53.68798)
		(end 293.99103 -55.113428)
		(width 0.12954)
		(layer "F.Cu")
		(net "P3V3_E1S_0_EN_G")
	)
	(via
		(at 293.99103 -55.113428)
		(size 0.762)
		(drill 0.381)
		(layers "F.Cu" "B.Cu")
		(net "P3V3_E1S_0_EN_G")
	)
	(segment
		(start 196.5706 -43.196256)
		(end 196.81063 -42.956226)
		(width 0.12954)
		(layer "F.Cu")
		(net "P12V_SCM_EN_R")
	)
	(segment
		(start 196.81063 -42.956226)
		(end 196.81063 -41.466516)
		(width 0.12954)
		(layer "F.Cu")
		(net "P12V_SCM_EN_R")
	)
	(segment
		(start 195.259452 -43.196256)
		(end 195.25615 -43.199558)
		(width 0.12954)
		(layer "F.Cu")
		(net "P12V_SCM_EN_R")
	)
	(segment
		(start 196.5706 -43.196256)
		(end 195.259452 -43.196256)
		(width 0.12954)
		(layer "F.Cu")
		(net "P12V_SCM_EN_R")
	)
	(via
		(at 196.5706 -43.196256)
		(size 0.762)
		(drill 0.381)
		(layers "F.Cu" "B.Cu")
		(net "P12V_SCM_EN_R")
	)
	(segment
		(start 193.76517 -43.199558)
		(end 193.92646 -43.038268)
		(width 0.12954)
		(layer "F.Cu")
		(net "P12V_SCM_EN_G")
	)
	(segment
		(start 192.76695 -42.554398)
		(end 193.351404 -42.554398)
		(width 0.12954)
		(layer "F.Cu")
		(net "P12V_SCM_EN_G")
	)
	(segment
		(start 193.92646 -43.038268)
		(end 193.92646 -42.761408)
		(width 0.12954)
		(layer "F.Cu")
		(net "P12V_SCM_EN_G")
	)
	(segment
		(start 193.351404 -42.554398)
		(end 193.35623 -42.549572)
		(width 0.12954)
		(layer "F.Cu")
		(net "P12V_SCM_EN_G")
	)
	(segment
		(start 190.82385 -42.554398)
		(end 191.23025 -42.554398)
		(width 0.12954)
		(layer "F.Cu")
		(net "P12V_SCM_EN_G")
	)
	(segment
		(start 193.714624 -42.549572)
		(end 193.35623 -42.549572)
		(width 0.12954)
		(layer "F.Cu")
		(net "P12V_SCM_EN_G")
	)
	(segment
		(start 191.23025 -42.554398)
		(end 191.9986 -43.322748)
		(width 0.12954)
		(layer "F.Cu")
		(net "P12V_SCM_EN_G")
	)
	(segment
		(start 191.9986 -43.322748)
		(end 192.76695 -42.554398)
		(width 0.12954)
		(layer "F.Cu")
		(net "P12V_SCM_EN_G")
	)
	(segment
		(start 193.92646 -42.761408)
		(end 193.714624 -42.549572)
		(width 0.12954)
		(layer "F.Cu")
		(net "P12V_SCM_EN_G")
	)
	(segment
		(start 193.35623 -43.199558)
		(end 193.76517 -43.199558)
		(width 0.12954)
		(layer "F.Cu")
		(net "P12V_SCM_EN_G")
	)
	(via
		(at 191.9986 -43.322748)
		(size 0.762)
		(drill 0.381)
		(layers "F.Cu" "B.Cu")
		(net "P12V_SCM_EN_G")
	)
	(segment
		(start 64.755268 -37.306758)
		(end 66.022982 -37.306758)
		(width 0.12954)
		(layer "F.Cu")
		(net "P12V_OCP_EN_2_R")
	)
	(segment
		(start 63.42253 -37.307266)
		(end 64.75476 -37.307266)
		(width 0.12954)
		(layer "F.Cu")
		(net "P12V_OCP_EN_2_R")
	)
	(segment
		(start 64.75476 -37.307266)
		(end 64.755268 -37.306758)
		(width 0.12954)
		(layer "F.Cu")
		(net "P12V_OCP_EN_2_R")
	)
	(via
		(at 64.75476 -37.307266)
		(size 0.762)
		(drill 0.381)
		(layers "F.Cu" "B.Cu")
		(net "P12V_OCP_EN_2_R")
	)
	(segment
		(start 463.60334 -39.106094)
		(end 462.610708 -39.106094)
		(width 0.12954)
		(layer "F.Cu")
		(net "P12V_OCP_EN_1_R")
	)
	(segment
		(start 462.610708 -39.106094)
		(end 462.589118 -39.084504)
		(width 0.12954)
		(layer "F.Cu")
		(net "P12V_OCP_EN_1_R")
	)
	(segment
		(start 462.589118 -39.084504)
		(end 462.143094 -39.084504)
		(width 0.12954)
		(layer "F.Cu")
		(net "P12V_OCP_EN_1_R")
	)
	(segment
		(start 465.144358 -39.106094)
		(end 463.60334 -39.106094)
		(width 0.12954)
		(layer "F.Cu")
		(net "P12V_OCP_EN_1_R")
	)
	(via
		(at 463.60334 -39.106094)
		(size 0.762)
		(drill 0.381)
		(layers "F.Cu" "B.Cu")
		(net "P12V_OCP_EN_1_R")
	)
	(segment
		(start 61.52261 -37.307266)
		(end 61.862462 -37.307266)
		(width 0.12954)
		(layer "F.Cu")
		(net "P12V_OCP_2_EN_G")
	)
	(segment
		(start 59.490864 -36.60775)
		(end 59.490864 -36.106862)
		(width 0.12954)
		(layer "F.Cu")
		(net "P12V_OCP_2_EN_G")
	)
	(segment
		(start 61.896752 -36.65728)
		(end 61.52261 -36.65728)
		(width 0.12954)
		(layer "F.Cu")
		(net "P12V_OCP_2_EN_G")
	)
	(segment
		(start 60.17768 -37.294566)
		(end 59.490864 -36.60775)
		(width 0.12954)
		(layer "F.Cu")
		(net "P12V_OCP_2_EN_G")
	)
	(segment
		(start 62.060582 -36.82111)
		(end 61.896752 -36.65728)
		(width 0.12954)
		(layer "F.Cu")
		(net "P12V_OCP_2_EN_G")
	)
	(segment
		(start 62.060582 -37.109146)
		(end 62.060582 -36.82111)
		(width 0.12954)
		(layer "F.Cu")
		(net "P12V_OCP_2_EN_G")
	)
	(segment
		(start 61.862462 -37.307266)
		(end 62.060582 -37.109146)
		(width 0.12954)
		(layer "F.Cu")
		(net "P12V_OCP_2_EN_G")
	)
	(segment
		(start 59.490864 -36.106862)
		(end 59.46775 -36.083748)
		(width 0.12954)
		(layer "F.Cu")
		(net "P12V_OCP_2_EN_G")
	)
	(segment
		(start 61.063886 -37.294566)
		(end 61.076586 -37.307266)
		(width 0.12954)
		(layer "F.Cu")
		(net "P12V_OCP_2_EN_G")
	)
	(segment
		(start 61.076586 -37.307266)
		(end 61.52261 -37.307266)
		(width 0.12954)
		(layer "F.Cu")
		(net "P12V_OCP_2_EN_G")
	)
	(segment
		(start 60.17768 -37.294566)
		(end 61.063886 -37.294566)
		(width 0.12954)
		(layer "F.Cu")
		(net "P12V_OCP_2_EN_G")
	)
	(via
		(at 60.17768 -37.294566)
		(size 0.762)
		(drill 0.381)
		(layers "F.Cu" "B.Cu")
		(net "P12V_OCP_2_EN_G")
	)
	(segment
		(start 467.026498 -39.7383)
		(end 466.67166 -39.7383)
		(width 0.12954)
		(layer "F.Cu")
		(net "P12V_OCP_1_EN_G")
	)
	(segment
		(start 467.4997 -39.75608)
		(end 468.33282 -40.5892)
		(width 0.12954)
		(layer "F.Cu")
		(net "P12V_OCP_1_EN_G")
	)
	(segment
		(start 469.669114 -41.4782)
		(end 469.694514 -41.4782)
		(width 0.12954)
		(layer "F.Cu")
		(net "P12V_OCP_1_EN_G")
	)
	(segment
		(start 468.33282 -40.5892)
		(end 468.85733 -41.11371)
		(width 0.12954)
		(layer "F.Cu")
		(net "P12V_OCP_1_EN_G")
	)
	(segment
		(start 466.67166 -39.7383)
		(end 466.592158 -39.658798)
		(width 0.12954)
		(layer "F.Cu")
		(net "P12V_OCP_1_EN_G")
	)
	(segment
		(start 467.044278 -39.75608)
		(end 467.026498 -39.7383)
		(width 0.12954)
		(layer "F.Cu")
		(net "P12V_OCP_1_EN_G")
	)
	(segment
		(start 467.044278 -39.75608)
		(end 467.4997 -39.75608)
		(width 0.12954)
		(layer "F.Cu")
		(net "P12V_OCP_1_EN_G")
	)
	(segment
		(start 469.304624 -41.11371)
		(end 469.669114 -41.4782)
		(width 0.12954)
		(layer "F.Cu")
		(net "P12V_OCP_1_EN_G")
	)
	(segment
		(start 466.684106 -39.106094)
		(end 467.044278 -39.106094)
		(width 0.12954)
		(layer "F.Cu")
		(net "P12V_OCP_1_EN_G")
	)
	(segment
		(start 468.85733 -41.11371)
		(end 469.304624 -41.11371)
		(width 0.12954)
		(layer "F.Cu")
		(net "P12V_OCP_1_EN_G")
	)
	(segment
		(start 466.592158 -39.198042)
		(end 466.684106 -39.106094)
		(width 0.12954)
		(layer "F.Cu")
		(net "P12V_OCP_1_EN_G")
	)
	(segment
		(start 466.592158 -39.658798)
		(end 466.592158 -39.198042)
		(width 0.12954)
		(layer "F.Cu")
		(net "P12V_OCP_1_EN_G")
	)
	(via
		(at 468.33282 -40.5892)
		(size 0.762)
		(drill 0.381)
		(layers "F.Cu" "B.Cu")
		(net "P12V_OCP_1_EN_G")
	)
	(segment
		(start 294.82288 -47.354998)
		(end 293.80688 -47.354998)
		(width 0.12954)
		(layer "F.Cu")
		(net "P12V_E1S_EN_0_R")
	)
	(segment
		(start 293.579042 -48.00346)
		(end 293.80688 -47.775622)
		(width 0.12954)
		(layer "F.Cu")
		(net "P12V_E1S_EN_0_R")
	)
	(segment
		(start 293.579042 -48.793908)
		(end 293.579042 -48.00346)
		(width 0.12954)
		(layer "F.Cu")
		(net "P12V_E1S_EN_0_R")
	)
	(segment
		(start 293.579042 -50.141378)
		(end 293.579042 -48.793908)
		(width 0.12954)
		(layer "F.Cu")
		(net "P12V_E1S_EN_0_R")
	)
	(segment
		(start 293.80688 -47.775622)
		(end 293.80688 -47.354998)
		(width 0.12954)
		(layer "F.Cu")
		(net "P12V_E1S_EN_0_R")
	)
	(via
		(at 293.579042 -48.793908)
		(size 0.762)
		(drill 0.381)
		(layers "F.Cu" "B.Cu")
		(net "P12V_E1S_EN_0_R")
	)
	(segment
		(start 293.04996 -51.40706)
		(end 293.41572 -51.40706)
		(width 0.12954)
		(layer "F.Cu")
		(net "P12V_E1S_0_EN_G")
	)
	(segment
		(start 292.59403 -53.313838)
		(end 292.304724 -53.024532)
		(width 0.12954)
		(layer "F.Cu")
		(net "P12V_E1S_0_EN_G")
	)
	(segment
		(start 291.67582 -53.024532)
		(end 291.521388 -52.8701)
		(width 0.12954)
		(layer "F.Cu")
		(net "P12V_E1S_0_EN_G")
	)
	(segment
		(start 292.929056 -52.041298)
		(end 292.929056 -51.527964)
		(width 0.12954)
		(layer "F.Cu")
		(net "P12V_E1S_0_EN_G")
	)
	(segment
		(start 292.929056 -52.041298)
		(end 291.89172 -52.041298)
		(width 0.12954)
		(layer "F.Cu")
		(net "P12V_E1S_0_EN_G")
	)
	(segment
		(start 291.521388 -52.8701)
		(end 291.521388 -52.41163)
		(width 0.12954)
		(layer "F.Cu")
		(net "P12V_E1S_0_EN_G")
	)
	(segment
		(start 292.304724 -53.024532)
		(end 291.67582 -53.024532)
		(width 0.12954)
		(layer "F.Cu")
		(net "P12V_E1S_0_EN_G")
	)
	(segment
		(start 292.59403 -53.652674)
		(end 292.59403 -53.313838)
		(width 0.12954)
		(layer "F.Cu")
		(net "P12V_E1S_0_EN_G")
	)
	(segment
		(start 291.89172 -52.041298)
		(end 291.521388 -52.41163)
		(width 0.12954)
		(layer "F.Cu")
		(net "P12V_E1S_0_EN_G")
	)
	(segment
		(start 293.41572 -51.40706)
		(end 293.579042 -51.570382)
		(width 0.12954)
		(layer "F.Cu")
		(net "P12V_E1S_0_EN_G")
	)
	(segment
		(start 293.579042 -51.570382)
		(end 293.579042 -52.041298)
		(width 0.12954)
		(layer "F.Cu")
		(net "P12V_E1S_0_EN_G")
	)
	(segment
		(start 292.929056 -51.527964)
		(end 293.04996 -51.40706)
		(width 0.12954)
		(layer "F.Cu")
		(net "P12V_E1S_0_EN_G")
	)
	(via
		(at 291.521388 -52.41163)
		(size 0.762)
		(drill 0.381)
		(layers "F.Cu" "B.Cu")
		(net "P12V_E1S_0_EN_G")
	)
	(segment
		(start 236.154468 -248.755408)
		(end 236.154468 -247.335294)
		(width 0.12954)
		(layer "F.Cu")
		(net "FG_SS_EN")
	)
	(segment
		(start 236.495082 -246.760746)
		(end 236.495082 -246.99468)
		(width 0.12954)
		(layer "F.Cu")
		(net "FG_SS_EN")
	)
	(segment
		(start 236.599984 -245.811548)
		(end 236.591094 -245.802658)
		(width 0.12954)
		(layer "F.Cu")
		(net "FG_SS_EN")
	)
	(segment
		(start 236.599984 -246.655844)
		(end 236.495082 -246.760746)
		(width 0.12954)
		(layer "F.Cu")
		(net "FG_SS_EN")
	)
	(segment
		(start 236.599984 -245.811548)
		(end 236.599984 -246.655844)
		(width 0.12954)
		(layer "F.Cu")
		(net "FG_SS_EN")
	)
	(segment
		(start 236.591094 -245.802658)
		(end 235.413042 -245.802658)
		(width 0.12954)
		(layer "F.Cu")
		(net "FG_SS_EN")
	)
	(segment
		(start 236.154468 -247.335294)
		(end 236.495082 -246.99468)
		(width 0.12954)
		(layer "F.Cu")
		(net "FG_SS_EN")
	)
	(via
		(at 236.495082 -246.99468)
		(size 0.762)
		(drill 0.381)
		(layers "F.Cu" "B.Cu")
		(net "FG_SS_EN")
	)
	(segment
		(start 238.39424 -249.880374)
		(end 238.59236 -250.078494)
		(width 0.12954)
		(layer "F.Cu")
		(net "CLK_GEN2_XTAL_OUT")
	)
	(segment
		(start 238.59236 -250.078494)
		(end 238.59236 -250.789948)
		(width 0.12954)
		(layer "F.Cu")
		(net "CLK_GEN2_XTAL_OUT")
	)
	(segment
		(start 238.90478 -251.102368)
		(end 238.69396 -250.891548)
		(width 0.12954)
		(layer "F.Cu")
		(net "CLK_GEN2_XTAL_OUT")
	)
	(segment
		(start 237.279434 -249.880374)
		(end 238.39424 -249.880374)
		(width 0.12954)
		(layer "F.Cu")
		(net "CLK_GEN2_XTAL_OUT")
	)
	(segment
		(start 238.59236 -250.789948)
		(end 238.69396 -250.891548)
		(width 0.12954)
		(layer "F.Cu")
		(net "CLK_GEN2_XTAL_OUT")
	)
	(segment
		(start 239.841532 -251.102368)
		(end 238.90478 -251.102368)
		(width 0.12954)
		(layer "F.Cu")
		(net "CLK_GEN2_XTAL_OUT")
	)
	(segment
		(start 240.971832 -250.662948)
		(end 241.800126 -250.662948)
		(width 0.12954)
		(layer "F.Cu")
		(net "CLK_GEN2_XTAL_OUT")
	)
	(segment
		(start 240.626392 -250.317508)
		(end 239.841532 -251.102368)
		(width 0.12954)
		(layer "F.Cu")
		(net "CLK_GEN2_XTAL_OUT")
	)
	(segment
		(start 240.626392 -250.317508)
		(end 240.971832 -250.662948)
		(width 0.12954)
		(layer "F.Cu")
		(net "CLK_GEN2_XTAL_OUT")
	)
	(segment
		(start 241.800126 -250.662948)
		(end 242.12169 -250.341384)
		(width 0.12954)
		(layer "F.Cu")
		(net "CLK_GEN2_XTAL_OUT")
	)
	(via
		(at 238.69396 -250.891548)
		(size 0.508)
		(drill 0.254)
		(layers "F.Cu" "B.Cu")
		(net "CLK_GEN2_XTAL_OUT")
	)
	(segment
		(start 237.796832 -249.006868)
		(end 238.49076 -249.006868)
		(width 0.12954)
		(layer "F.Cu")
		(net "CLK_GEN2_XTAL_IN")
	)
	(segment
		(start 237.279434 -249.380502)
		(end 237.423198 -249.380502)
		(width 0.12954)
		(layer "F.Cu")
		(net "CLK_GEN2_XTAL_IN")
	)
	(segment
		(start 238.49076 -249.006868)
		(end 238.50092 -249.017028)
		(width 0.12954)
		(layer "F.Cu")
		(net "CLK_GEN2_XTAL_IN")
	)
	(segment
		(start 239.64519 -249.006868)
		(end 239.7125 -248.939558)
		(width 0.12954)
		(layer "F.Cu")
		(net "CLK_GEN2_XTAL_IN")
	)
	(segment
		(start 238.50092 -249.017028)
		(end 238.51108 -249.006868)
		(width 0.12954)
		(layer "F.Cu")
		(net "CLK_GEN2_XTAL_IN")
	)
	(segment
		(start 237.423198 -249.380502)
		(end 237.796832 -249.006868)
		(width 0.12954)
		(layer "F.Cu")
		(net "CLK_GEN2_XTAL_IN")
	)
	(segment
		(start 238.51108 -249.006868)
		(end 239.64519 -249.006868)
		(width 0.12954)
		(layer "F.Cu")
		(net "CLK_GEN2_XTAL_IN")
	)
	(via
		(at 238.50092 -249.017028)
		(size 0.762)
		(drill 0.381)
		(layers "F.Cu" "B.Cu")
		(net "CLK_GEN2_XTAL_IN")
	)
	(segment
		(start 243.38661 -253.363984)
		(end 242.712494 -252.689868)
		(width 0.12954)
		(layer "F.Cu")
		(net "CLK_GEN2_SMB_SADR")
	)
	(segment
		(start 237.279434 -250.880372)
		(end 237.751874 -250.880372)
		(width 0.12954)
		(layer "F.Cu")
		(net "CLK_GEN2_SMB_SADR")
	)
	(segment
		(start 240.21669 -253.345188)
		(end 238.745268 -251.873766)
		(width 0.12954)
		(layer "F.Cu")
		(net "CLK_GEN2_SMB_SADR")
	)
	(segment
		(start 240.87201 -252.689868)
		(end 240.21669 -253.345188)
		(width 0.12954)
		(layer "F.Cu")
		(net "CLK_GEN2_SMB_SADR")
	)
	(segment
		(start 242.712494 -252.689868)
		(end 240.87201 -252.689868)
		(width 0.12954)
		(layer "F.Cu")
		(net "CLK_GEN2_SMB_SADR")
	)
	(segment
		(start 237.751874 -250.880372)
		(end 238.745268 -251.873766)
		(width 0.12954)
		(layer "F.Cu")
		(net "CLK_GEN2_SMB_SADR")
	)
	(via
		(at 238.745268 -251.873766)
		(size 0.762)
		(drill 0.381)
		(layers "F.Cu" "B.Cu")
		(net "CLK_GEN2_SMB_SADR")
	)
	(segment
		(start 232.911396 -245.811548)
		(end 233.749342 -246.649494)
		(width 0.12954)
		(layer "F.Cu")
		(net "CLK_GEN2_GPU_OE_N")
	)
	(segment
		(start 234.154472 -248.755408)
		(end 234.154472 -247.40997)
		(width 0.12954)
		(layer "F.Cu")
		(net "CLK_GEN2_GPU_OE_N")
	)
	(segment
		(start 234.154472 -247.40997)
		(end 233.749342 -247.00484)
		(width 0.12954)
		(layer "F.Cu")
		(net "CLK_GEN2_GPU_OE_N")
	)
	(segment
		(start 233.749342 -246.649494)
		(end 233.749342 -247.00484)
		(width 0.12954)
		(layer "F.Cu")
		(net "CLK_GEN2_GPU_OE_N")
	)
	(via
		(at 233.749342 -247.00484)
		(size 0.762)
		(drill 0.381)
		(layers "F.Cu" "B.Cu")
		(net "CLK_GEN2_GPU_OE_N")
	)
	(segment
		(start 47.217076 -395.699996)
		(end 47.21733 -395.70025)
		(width 0.10668)
		(layer "F.Cu")
		(net "CLK_GEN2_GPU_FPGA_OE_OR_N")
	)
	(segment
		(start 121.492264 -37.355526)
		(end 122.39752 -37.355526)
		(width 0.12954)
		(layer "F.Cu")
		(net "CLK_GEN2_GPU_FPGA_OE_OR_N")
	)
	(segment
		(start 27.228546 -386.167884)
		(end 27.22118 -386.160518)
		(width 0.12954)
		(layer "F.Cu")
		(net "CLK_GEN2_GPU_FPGA_OE_OR_N")
	)
	(segment
		(start 46.485556 -395.699996)
		(end 47.217076 -395.699996)
		(width 0.10668)
		(layer "F.Cu")
		(net "CLK_GEN2_GPU_FPGA_OE_OR_N")
	)
	(segment
		(start 27.228546 -388.262876)
		(end 27.228546 -387.246876)
		(width 0.12954)
		(layer "F.Cu")
		(net "CLK_GEN2_GPU_FPGA_OE_OR_N")
	)
	(segment
		(start 27.228546 -387.246876)
		(end 27.228546 -386.167884)
		(width 0.12954)
		(layer "F.Cu")
		(net "CLK_GEN2_GPU_FPGA_OE_OR_N")
	)
	(segment
		(start 27.22118 -386.160518)
		(end 28.15844 -386.160518)
		(width 0.12954)
		(layer "F.Cu")
		(net "CLK_GEN2_GPU_FPGA_OE_OR_N")
	)
	(segment
		(start 232.911396 -245.011448)
		(end 232.911396 -244.375432)
		(width 0.12954)
		(layer "F.Cu")
		(net "CLK_GEN2_GPU_FPGA_OE_OR_N")
	)
	(segment
		(start 28.15844 -386.160518)
		(end 28.51658 -385.802378)
		(width 0.12954)
		(layer "F.Cu")
		(net "CLK_GEN2_GPU_FPGA_OE_OR_N")
	)
	(via
		(at 122.770392 -393.207748)
		(size 0.508)
		(drill 0.254)
		(layers "F.Cu" "B.Cu")
		(net "CLK_GEN2_GPU_FPGA_OE_OR_N")
	)
	(via
		(at 232.911396 -244.375432)
		(size 0.508)
		(drill 0.254)
		(layers "F.Cu" "B.Cu")
		(net "CLK_GEN2_GPU_FPGA_OE_OR_N")
	)
	(via
		(at 200.75652 -363.761528)
		(size 0.508)
		(drill 0.254)
		(layers "F.Cu" "B.Cu")
		(net "CLK_GEN2_GPU_FPGA_OE_OR_N")
	)
	(via
		(at 200.46442 -105.395268)
		(size 0.508)
		(drill 0.254)
		(layers "F.Cu" "B.Cu")
		(net "CLK_GEN2_GPU_FPGA_OE_OR_N")
	)
	(via
		(at 47.21733 -395.70025)
		(size 0.508)
		(drill 0.254)
		(layers "F.Cu" "B.Cu")
		(net "CLK_GEN2_GPU_FPGA_OE_OR_N")
	)
	(via
		(at 96.80448 -389.661908)
		(size 0.508)
		(drill 0.254)
		(layers "F.Cu" "B.Cu")
		(net "CLK_GEN2_GPU_FPGA_OE_OR_N")
	)
	(via
		(at 28.51658 -385.802378)
		(size 0.762)
		(drill 0.254)
		(layers "F.Cu" "B.Cu")
		(net "CLK_GEN2_GPU_FPGA_OE_OR_N")
	)
	(via
		(at 122.39752 -37.355526)
		(size 0.508)
		(drill 0.254)
		(layers "F.Cu" "B.Cu")
		(net "CLK_GEN2_GPU_FPGA_OE_OR_N")
	)
	(segment
		(start 92.1004 -394.13942)
		(end 49.27346 -394.13942)
		(width 0.12954)
		(layer "B.Cu")
		(net "CLK_GEN2_GPU_FPGA_OE_OR_N")
	)
	(segment
		(start 96.195388 -390.271)
		(end 93.0148 -390.271)
		(width 0.12954)
		(layer "B.Cu")
		(net "CLK_GEN2_GPU_FPGA_OE_OR_N")
	)
	(segment
		(start 127.59436 -387.502908)
		(end 122.770392 -392.326876)
		(width 0.12954)
		(layer "B.Cu")
		(net "CLK_GEN2_GPU_FPGA_OE_OR_N")
	)
	(segment
		(start 92.5576 -393.68222)
		(end 92.1004 -394.13942)
		(width 0.12954)
		(layer "B.Cu")
		(net "CLK_GEN2_GPU_FPGA_OE_OR_N")
	)
	(segment
		(start 198.472552 -363.761528)
		(end 174.731172 -387.502908)
		(width 0.12954)
		(layer "B.Cu")
		(net "CLK_GEN2_GPU_FPGA_OE_OR_N")
	)
	(segment
		(start 122.770392 -392.326876)
		(end 122.770392 -393.207748)
		(width 0.12954)
		(layer "B.Cu")
		(net "CLK_GEN2_GPU_FPGA_OE_OR_N")
	)
	(segment
		(start 43.45686 -388.08914)
		(end 35.36696 -388.08914)
		(width 0.12954)
		(layer "B.Cu")
		(net "CLK_GEN2_GPU_FPGA_OE_OR_N")
	)
	(segment
		(start 92.5576 -390.7282)
		(end 92.5576 -393.68222)
		(width 0.12954)
		(layer "B.Cu")
		(net "CLK_GEN2_GPU_FPGA_OE_OR_N")
	)
	(segment
		(start 200.75652 -363.761528)
		(end 198.472552 -363.761528)
		(width 0.12954)
		(layer "B.Cu")
		(net "CLK_GEN2_GPU_FPGA_OE_OR_N")
	)
	(segment
		(start 44.7548 -393.23772)
		(end 44.7548 -389.38708)
		(width 0.12954)
		(layer "B.Cu")
		(net "CLK_GEN2_GPU_FPGA_OE_OR_N")
	)
	(segment
		(start 47.71263 -395.70025)
		(end 47.21733 -395.70025)
		(width 0.12954)
		(layer "B.Cu")
		(net "CLK_GEN2_GPU_FPGA_OE_OR_N")
	)
	(segment
		(start 47.21733 -395.70025)
		(end 44.7548 -393.23772)
		(width 0.12954)
		(layer "B.Cu")
		(net "CLK_GEN2_GPU_FPGA_OE_OR_N")
	)
	(segment
		(start 49.27346 -394.13942)
		(end 47.71263 -395.70025)
		(width 0.12954)
		(layer "B.Cu")
		(net "CLK_GEN2_GPU_FPGA_OE_OR_N")
	)
	(segment
		(start 35.36696 -388.08914)
		(end 33.080198 -385.802378)
		(width 0.12954)
		(layer "B.Cu")
		(net "CLK_GEN2_GPU_FPGA_OE_OR_N")
	)
	(segment
		(start 96.80448 -389.661908)
		(end 96.195388 -390.271)
		(width 0.12954)
		(layer "B.Cu")
		(net "CLK_GEN2_GPU_FPGA_OE_OR_N")
	)
	(segment
		(start 44.7548 -389.38708)
		(end 43.45686 -388.08914)
		(width 0.12954)
		(layer "B.Cu")
		(net "CLK_GEN2_GPU_FPGA_OE_OR_N")
	)
	(segment
		(start 93.0148 -390.271)
		(end 92.5576 -390.7282)
		(width 0.12954)
		(layer "B.Cu")
		(net "CLK_GEN2_GPU_FPGA_OE_OR_N")
	)
	(segment
		(start 174.731172 -387.502908)
		(end 127.59436 -387.502908)
		(width 0.12954)
		(layer "B.Cu")
		(net "CLK_GEN2_GPU_FPGA_OE_OR_N")
	)
	(segment
		(start 33.080198 -385.802378)
		(end 28.51658 -385.802378)
		(width 0.12954)
		(layer "B.Cu")
		(net "CLK_GEN2_GPU_FPGA_OE_OR_N")
	)
	(segment
		(start 118.29161 -393.295378)
		(end 118.29161 -392.754358)
		(width 0.127)
		(layer "In2.Cu")
		(net "CLK_GEN2_GPU_FPGA_OE_OR_N")
	)
	(segment
		(start 122.770392 -393.207748)
		(end 122.770392 -393.426696)
		(width 0.127)
		(layer "In2.Cu")
		(net "CLK_GEN2_GPU_FPGA_OE_OR_N")
	)
	(segment
		(start 233.63682 -252.834648)
		(end 233.63682 -245.100856)
		(width 0.127)
		(layer "In2.Cu")
		(net "CLK_GEN2_GPU_FPGA_OE_OR_N")
	)
	(segment
		(start 200.75652 -362.71708)
		(end 229.06228 -334.41132)
		(width 0.127)
		(layer "In2.Cu")
		(net "CLK_GEN2_GPU_FPGA_OE_OR_N")
	)
	(segment
		(start 229.06228 -269.227808)
		(end 237.3884 -260.901688)
		(width 0.127)
		(layer "In2.Cu")
		(net "CLK_GEN2_GPU_FPGA_OE_OR_N")
	)
	(segment
		(start 98.90506 -390.068308)
		(end 98.70186 -390.271508)
		(width 0.127)
		(layer "In2.Cu")
		(net "CLK_GEN2_GPU_FPGA_OE_OR_N")
	)
	(segment
		(start 118.29161 -392.754358)
		(end 117.70614 -392.168888)
		(width 0.127)
		(layer "In2.Cu")
		(net "CLK_GEN2_GPU_FPGA_OE_OR_N")
	)
	(segment
		(start 237.3884 -260.901688)
		(end 237.3884 -256.586228)
		(width 0.127)
		(layer "In2.Cu")
		(net "CLK_GEN2_GPU_FPGA_OE_OR_N")
	)
	(segment
		(start 117.70614 -392.168888)
		(end 105.47604 -392.168888)
		(width 0.127)
		(layer "In2.Cu")
		(net "CLK_GEN2_GPU_FPGA_OE_OR_N")
	)
	(segment
		(start 122.770392 -393.426696)
		(end 122.10034 -394.096748)
		(width 0.127)
		(layer "In2.Cu")
		(net "CLK_GEN2_GPU_FPGA_OE_OR_N")
	)
	(segment
		(start 98.70186 -390.271508)
		(end 97.41408 -390.271508)
		(width 0.127)
		(layer "In2.Cu")
		(net "CLK_GEN2_GPU_FPGA_OE_OR_N")
	)
	(segment
		(start 233.63682 -245.100856)
		(end 232.911396 -244.375432)
		(width 0.127)
		(layer "In2.Cu")
		(net "CLK_GEN2_GPU_FPGA_OE_OR_N")
	)
	(segment
		(start 237.3884 -256.586228)
		(end 233.63682 -252.834648)
		(width 0.127)
		(layer "In2.Cu")
		(net "CLK_GEN2_GPU_FPGA_OE_OR_N")
	)
	(segment
		(start 229.06228 -334.41132)
		(end 229.06228 -269.227808)
		(width 0.127)
		(layer "In2.Cu")
		(net "CLK_GEN2_GPU_FPGA_OE_OR_N")
	)
	(segment
		(start 119.09298 -394.096748)
		(end 118.29161 -393.295378)
		(width 0.127)
		(layer "In2.Cu")
		(net "CLK_GEN2_GPU_FPGA_OE_OR_N")
	)
	(segment
		(start 103.37546 -390.068308)
		(end 98.90506 -390.068308)
		(width 0.127)
		(layer "In2.Cu")
		(net "CLK_GEN2_GPU_FPGA_OE_OR_N")
	)
	(segment
		(start 97.41408 -390.271508)
		(end 96.80448 -389.661908)
		(width 0.127)
		(layer "In2.Cu")
		(net "CLK_GEN2_GPU_FPGA_OE_OR_N")
	)
	(segment
		(start 122.10034 -394.096748)
		(end 119.09298 -394.096748)
		(width 0.127)
		(layer "In2.Cu")
		(net "CLK_GEN2_GPU_FPGA_OE_OR_N")
	)
	(segment
		(start 105.47604 -392.168888)
		(end 103.37546 -390.068308)
		(width 0.127)
		(layer "In2.Cu")
		(net "CLK_GEN2_GPU_FPGA_OE_OR_N")
	)
	(segment
		(start 200.75652 -363.761528)
		(end 200.75652 -362.71708)
		(width 0.127)
		(layer "In2.Cu")
		(net "CLK_GEN2_GPU_FPGA_OE_OR_N")
	)
	(segment
		(start 199.67956 -105.05694)
		(end 199.67956 -104.368092)
		(width 0.127)
		(layer "In4.Cu")
		(net "CLK_GEN2_GPU_FPGA_OE_OR_N")
	)
	(segment
		(start 199.6694 -104.357932)
		(end 199.6694 -104.357678)
		(width 0.127)
		(layer "In4.Cu")
		(net "CLK_GEN2_GPU_FPGA_OE_OR_N")
	)
	(segment
		(start 189.172088 -83.71459)
		(end 177.609246 -83.71459)
		(width 0.127)
		(layer "In4.Cu")
		(net "CLK_GEN2_GPU_FPGA_OE_OR_N")
	)
	(segment
		(start 199.67956 -104.368092)
		(end 199.6694 -104.357932)
		(width 0.127)
		(layer "In4.Cu")
		(net "CLK_GEN2_GPU_FPGA_OE_OR_N")
	)
	(segment
		(start 141.28242 -60.658248)
		(end 141.28242 -52.352448)
		(width 0.127)
		(layer "In4.Cu")
		(net "CLK_GEN2_GPU_FPGA_OE_OR_N")
	)
	(segment
		(start 197.77075 -102.459028)
		(end 197.77075 -100.09124)
		(width 0.127)
		(layer "In4.Cu")
		(net "CLK_GEN2_GPU_FPGA_OE_OR_N")
	)
	(segment
		(start 132.860542 -47.818548)
		(end 122.39752 -37.355526)
		(width 0.127)
		(layer "In4.Cu")
		(net "CLK_GEN2_GPU_FPGA_OE_OR_N")
	)
	(segment
		(start 177.609246 -83.71459)
		(end 160.968944 -67.074288)
		(width 0.127)
		(layer "In4.Cu")
		(net "CLK_GEN2_GPU_FPGA_OE_OR_N")
	)
	(segment
		(start 160.968944 -67.074288)
		(end 159.604456 -67.074288)
		(width 0.127)
		(layer "In4.Cu")
		(net "CLK_GEN2_GPU_FPGA_OE_OR_N")
	)
	(segment
		(start 191.48806 -86.030562)
		(end 189.172088 -83.71459)
		(width 0.127)
		(layer "In4.Cu")
		(net "CLK_GEN2_GPU_FPGA_OE_OR_N")
	)
	(segment
		(start 136.74852 -47.818548)
		(end 132.860542 -47.818548)
		(width 0.127)
		(layer "In4.Cu")
		(net "CLK_GEN2_GPU_FPGA_OE_OR_N")
	)
	(segment
		(start 159.604456 -67.074288)
		(end 158.413196 -65.883028)
		(width 0.127)
		(layer "In4.Cu")
		(net "CLK_GEN2_GPU_FPGA_OE_OR_N")
	)
	(segment
		(start 191.48806 -93.80855)
		(end 191.48806 -86.030562)
		(width 0.127)
		(layer "In4.Cu")
		(net "CLK_GEN2_GPU_FPGA_OE_OR_N")
	)
	(segment
		(start 146.5072 -65.883028)
		(end 141.28242 -60.658248)
		(width 0.127)
		(layer "In4.Cu")
		(net "CLK_GEN2_GPU_FPGA_OE_OR_N")
	)
	(segment
		(start 200.46442 -105.395268)
		(end 200.017888 -105.395268)
		(width 0.127)
		(layer "In4.Cu")
		(net "CLK_GEN2_GPU_FPGA_OE_OR_N")
	)
	(segment
		(start 200.017888 -105.395268)
		(end 199.67956 -105.05694)
		(width 0.127)
		(layer "In4.Cu")
		(net "CLK_GEN2_GPU_FPGA_OE_OR_N")
	)
	(segment
		(start 199.6694 -104.357678)
		(end 197.77075 -102.459028)
		(width 0.127)
		(layer "In4.Cu")
		(net "CLK_GEN2_GPU_FPGA_OE_OR_N")
	)
	(segment
		(start 158.413196 -65.883028)
		(end 146.5072 -65.883028)
		(width 0.127)
		(layer "In4.Cu")
		(net "CLK_GEN2_GPU_FPGA_OE_OR_N")
	)
	(segment
		(start 141.28242 -52.352448)
		(end 136.74852 -47.818548)
		(width 0.127)
		(layer "In4.Cu")
		(net "CLK_GEN2_GPU_FPGA_OE_OR_N")
	)
	(segment
		(start 197.77075 -100.09124)
		(end 191.48806 -93.80855)
		(width 0.127)
		(layer "In4.Cu")
		(net "CLK_GEN2_GPU_FPGA_OE_OR_N")
	)
	(segment
		(start 212.31098 -112.42802)
		(end 212.3059 -112.4331)
		(width 0.127)
		(layer "In11.Cu")
		(net "CLK_GEN2_GPU_FPGA_OE_OR_N")
	)
	(segment
		(start 245.50624 -203.766674)
		(end 232.911396 -216.361518)
		(width 0.127)
		(layer "In11.Cu")
		(net "CLK_GEN2_GPU_FPGA_OE_OR_N")
	)
	(segment
		(start 200.46442 -105.395268)
		(end 201.39533 -105.395268)
		(width 0.127)
		(layer "In11.Cu")
		(net "CLK_GEN2_GPU_FPGA_OE_OR_N")
	)
	(segment
		(start 212.3059 -112.4331)
		(end 212.3059 -121.450608)
		(width 0.127)
		(layer "In11.Cu")
		(net "CLK_GEN2_GPU_FPGA_OE_OR_N")
	)
	(segment
		(start 215.54948 -109.11205)
		(end 212.31098 -112.35055)
		(width 0.127)
		(layer "In11.Cu")
		(net "CLK_GEN2_GPU_FPGA_OE_OR_N")
	)
	(segment
		(start 215.54948 -106.543348)
		(end 215.54948 -109.11205)
		(width 0.127)
		(layer "In11.Cu")
		(net "CLK_GEN2_GPU_FPGA_OE_OR_N")
	)
	(segment
		(start 210.712812 -105.860088)
		(end 214.86622 -105.860088)
		(width 0.127)
		(layer "In11.Cu")
		(net "CLK_GEN2_GPU_FPGA_OE_OR_N")
	)
	(segment
		(start 212.3059 -121.450608)
		(end 217.18778 -126.332488)
		(width 0.127)
		(layer "In11.Cu")
		(net "CLK_GEN2_GPU_FPGA_OE_OR_N")
	)
	(segment
		(start 201.39533 -105.395268)
		(end 201.86015 -105.860088)
		(width 0.127)
		(layer "In11.Cu")
		(net "CLK_GEN2_GPU_FPGA_OE_OR_N")
	)
	(segment
		(start 217.18778 -126.332488)
		(end 217.18778 -134.808468)
		(width 0.127)
		(layer "In11.Cu")
		(net "CLK_GEN2_GPU_FPGA_OE_OR_N")
	)
	(segment
		(start 217.18778 -134.808468)
		(end 241.84356 -159.464248)
		(width 0.127)
		(layer "In11.Cu")
		(net "CLK_GEN2_GPU_FPGA_OE_OR_N")
	)
	(segment
		(start 207.568292 -106.12882)
		(end 210.44408 -106.12882)
		(width 0.127)
		(layer "In11.Cu")
		(net "CLK_GEN2_GPU_FPGA_OE_OR_N")
	)
	(segment
		(start 212.31098 -112.35055)
		(end 212.31098 -112.42802)
		(width 0.127)
		(layer "In11.Cu")
		(net "CLK_GEN2_GPU_FPGA_OE_OR_N")
	)
	(segment
		(start 241.84356 -159.464248)
		(end 241.84356 -169.078148)
		(width 0.127)
		(layer "In11.Cu")
		(net "CLK_GEN2_GPU_FPGA_OE_OR_N")
	)
	(segment
		(start 232.911396 -216.361518)
		(end 232.911396 -244.375432)
		(width 0.127)
		(layer "In11.Cu")
		(net "CLK_GEN2_GPU_FPGA_OE_OR_N")
	)
	(segment
		(start 214.86622 -105.860088)
		(end 215.54948 -106.543348)
		(width 0.127)
		(layer "In11.Cu")
		(net "CLK_GEN2_GPU_FPGA_OE_OR_N")
	)
	(segment
		(start 201.86015 -105.860088)
		(end 207.29956 -105.860088)
		(width 0.127)
		(layer "In11.Cu")
		(net "CLK_GEN2_GPU_FPGA_OE_OR_N")
	)
	(segment
		(start 210.44408 -106.12882)
		(end 210.712812 -105.860088)
		(width 0.127)
		(layer "In11.Cu")
		(net "CLK_GEN2_GPU_FPGA_OE_OR_N")
	)
	(segment
		(start 245.50624 -172.740828)
		(end 245.50624 -203.766674)
		(width 0.127)
		(layer "In11.Cu")
		(net "CLK_GEN2_GPU_FPGA_OE_OR_N")
	)
	(segment
		(start 207.29956 -105.860088)
		(end 207.568292 -106.12882)
		(width 0.127)
		(layer "In11.Cu")
		(net "CLK_GEN2_GPU_FPGA_OE_OR_N")
	)
	(segment
		(start 241.84356 -169.078148)
		(end 245.50624 -172.740828)
		(width 0.127)
		(layer "In11.Cu")
		(net "CLK_GEN2_GPU_FPGA_OE_OR_N")
	)
	(segment
		(start 234.154472 -253.865888)
		(end 234.154472 -255.265682)
		(width 0.12954)
		(layer "F.Cu")
		(net "CLK_GEN2_BMC_RC_OE_R3_N")
	)
	(segment
		(start 234.11688 -255.303274)
		(end 234.11688 -255.723898)
		(width 0.12954)
		(layer "F.Cu")
		(net "CLK_GEN2_BMC_RC_OE_R3_N")
	)
	(segment
		(start 234.154472 -255.265682)
		(end 234.11688 -255.303274)
		(width 0.12954)
		(layer "F.Cu")
		(net "CLK_GEN2_BMC_RC_OE_R3_N")
	)
	(segment
		(start 234.154472 -252.505464)
		(end 234.154472 -253.865888)
		(width 0.12954)
		(layer "F.Cu")
		(net "CLK_GEN2_BMC_RC_OE_R3_N")
	)
	(via
		(at 234.154472 -253.865888)
		(size 0.762)
		(drill 0.381)
		(layers "F.Cu" "B.Cu")
		(net "CLK_GEN2_BMC_RC_OE_R3_N")
	)
	(segment
		(start 234.11688 -256.523998)
		(end 233.35488 -256.523998)
		(width 0.12954)
		(layer "F.Cu")
		(net "CLK_GEN2_BMC_RC_OE_N")
	)
	(segment
		(start 186.955684 -119.375428)
		(end 187.355734 -119.775478)
		(width 0.12954)
		(layer "F.Cu")
		(net "CLK_GEN2_BMC_RC_OE_N")
	)
	(via
		(at 215.54948 -129.477008)
		(size 0.508)
		(drill 0.254)
		(layers "F.Cu" "B.Cu")
		(net "CLK_GEN2_BMC_RC_OE_N")
	)
	(via
		(at 203.90866 -125.895608)
		(size 0.508)
		(drill 0.254)
		(layers "F.Cu" "B.Cu")
		(net "CLK_GEN2_BMC_RC_OE_N")
	)
	(via
		(at 233.35488 -256.523998)
		(size 0.508)
		(drill 0.254)
		(layers "F.Cu" "B.Cu")
		(net "CLK_GEN2_BMC_RC_OE_N")
	)
	(via
		(at 187.355734 -119.775478)
		(size 0.4572)
		(drill 0.254)
		(layers "F.Cu" "B.Cu")
		(net "CLK_GEN2_BMC_RC_OE_N")
	)
	(segment
		(start 191.075056 -122.356118)
		(end 188.494416 -119.775478)
		(width 0.12954)
		(layer "B.Cu")
		(net "CLK_GEN2_BMC_RC_OE_N")
	)
	(segment
		(start 188.494416 -119.775478)
		(end 187.355734 -119.775478)
		(width 0.12954)
		(layer "B.Cu")
		(net "CLK_GEN2_BMC_RC_OE_N")
	)
	(segment
		(start 197.582282 -123.139708)
		(end 196.798692 -122.356118)
		(width 0.12954)
		(layer "B.Cu")
		(net "CLK_GEN2_BMC_RC_OE_N")
	)
	(segment
		(start 196.798692 -122.356118)
		(end 191.075056 -122.356118)
		(width 0.12954)
		(layer "B.Cu")
		(net "CLK_GEN2_BMC_RC_OE_N")
	)
	(segment
		(start 216.46388 -135.001508)
		(end 216.46388 -132.108194)
		(width 0.127)
		(layer "In11.Cu")
		(net "CLK_GEN2_BMC_RC_OE_N")
	)
	(segment
		(start 241.46256 -169.266108)
		(end 241.46256 -160.000188)
		(width 0.127)
		(layer "In11.Cu")
		(net "CLK_GEN2_BMC_RC_OE_N")
	)
	(segment
		(start 233.35488 -256.523998)
		(end 231.25176 -254.420878)
		(width 0.127)
		(layer "In11.Cu")
		(net "CLK_GEN2_BMC_RC_OE_N")
	)
	(segment
		(start 241.46256 -160.000188)
		(end 216.46388 -135.001508)
		(width 0.127)
		(layer "In11.Cu")
		(net "CLK_GEN2_BMC_RC_OE_N")
	)
	(segment
		(start 245.17604 -203.629768)
		(end 245.17604 -172.979588)
		(width 0.127)
		(layer "In11.Cu")
		(net "CLK_GEN2_BMC_RC_OE_N")
	)
	(segment
		(start 215.54948 -131.193794)
		(end 215.54948 -129.477008)
		(width 0.127)
		(layer "In11.Cu")
		(net "CLK_GEN2_BMC_RC_OE_N")
	)
	(segment
		(start 216.46388 -132.108194)
		(end 215.54948 -131.193794)
		(width 0.127)
		(layer "In11.Cu")
		(net "CLK_GEN2_BMC_RC_OE_N")
	)
	(segment
		(start 231.25176 -217.554048)
		(end 245.17604 -203.629768)
		(width 0.127)
		(layer "In11.Cu")
		(net "CLK_GEN2_BMC_RC_OE_N")
	)
	(segment
		(start 245.17604 -172.979588)
		(end 241.46256 -169.266108)
		(width 0.127)
		(layer "In11.Cu")
		(net "CLK_GEN2_BMC_RC_OE_N")
	)
	(segment
		(start 231.25176 -254.420878)
		(end 231.25176 -217.554048)
		(width 0.127)
		(layer "In11.Cu")
		(net "CLK_GEN2_BMC_RC_OE_N")
	)
	(segment
		(start 215.54948 -129.477008)
		(end 215.16086 -129.088388)
		(width 0.127)
		(layer "In13.Cu")
		(net "CLK_GEN2_BMC_RC_OE_N")
	)
	(segment
		(start 215.16086 -129.088388)
		(end 207.10144 -129.088388)
		(width 0.127)
		(layer "In13.Cu")
		(net "CLK_GEN2_BMC_RC_OE_N")
	)
	(segment
		(start 207.10144 -129.088388)
		(end 203.90866 -125.895608)
		(width 0.127)
		(layer "In13.Cu")
		(net "CLK_GEN2_BMC_RC_OE_N")
	)
	(segment
		(start 187.30214 -120.675908)
		(end 187.30214 -119.829072)
		(width 0.127)
		(layer "In15.Cu")
		(net "CLK_GEN2_BMC_RC_OE_N")
	)
	(segment
		(start 189.292738 -121.44629)
		(end 188.072522 -121.44629)
		(width 0.127)
		(layer "In15.Cu")
		(net "CLK_GEN2_BMC_RC_OE_N")
	)
	(segment
		(start 188.072522 -121.44629)
		(end 187.30214 -120.675908)
		(width 0.127)
		(layer "In15.Cu")
		(net "CLK_GEN2_BMC_RC_OE_N")
	)
	(segment
		(start 187.30214 -119.829072)
		(end 187.355734 -119.775478)
		(width 0.127)
		(layer "In15.Cu")
		(net "CLK_GEN2_BMC_RC_OE_N")
	)
	(segment
		(start 194.214496 -126.368048)
		(end 189.292738 -121.44629)
		(width 0.127)
		(layer "In15.Cu")
		(net "CLK_GEN2_BMC_RC_OE_N")
	)
	(segment
		(start 203.43622 -126.368048)
		(end 194.214496 -126.368048)
		(width 0.127)
		(layer "In15.Cu")
		(net "CLK_GEN2_BMC_RC_OE_N")
	)
	(segment
		(start 203.90866 -125.895608)
		(end 203.43622 -126.368048)
		(width 0.127)
		(layer "In15.Cu")
		(net "CLK_GEN2_BMC_RC_OE_N")
	)
	(segment
		(start 186.733942 -133.289548)
		(end 186.733942 -132.425948)
		(width 0.12954)
		(layer "F.Cu")
		(net "PRSNT_SWB_ISO_R_N")
	)
	(segment
		(start 185.355738 -111.375444)
		(end 185.755788 -110.975394)
		(width 0.12954)
		(layer "F.Cu")
		(net "PRSNT_SWB_ISO_R_N")
	)
	(via
		(at 185.755788 -110.975394)
		(size 0.4572)
		(drill 0.254)
		(layers "F.Cu" "B.Cu")
		(net "PRSNT_SWB_ISO_R_N")
	)
	(via
		(at 186.733942 -132.425948)
		(size 0.508)
		(drill 0.254)
		(layers "F.Cu" "B.Cu")
		(net "PRSNT_SWB_ISO_R_N")
	)
	(segment
		(start 186.1566 -119.149368)
		(end 186.55792 -119.550688)
		(width 0.127)
		(layer "In11.Cu")
		(net "PRSNT_SWB_ISO_R_N")
	)
	(segment
		(start 186.1566 -111.376206)
		(end 186.1566 -119.149368)
		(width 0.127)
		(layer "In11.Cu")
		(net "PRSNT_SWB_ISO_R_N")
	)
	(segment
		(start 186.55792 -121.595388)
		(end 186.1566 -121.996708)
		(width 0.127)
		(layer "In11.Cu")
		(net "PRSNT_SWB_ISO_R_N")
	)
	(segment
		(start 186.1566 -131.848606)
		(end 186.733942 -132.425948)
		(width 0.127)
		(layer "In11.Cu")
		(net "PRSNT_SWB_ISO_R_N")
	)
	(segment
		(start 186.55792 -119.550688)
		(end 186.55792 -121.595388)
		(width 0.127)
		(layer "In11.Cu")
		(net "PRSNT_SWB_ISO_R_N")
	)
	(segment
		(start 186.1566 -121.996708)
		(end 186.1566 -131.848606)
		(width 0.127)
		(layer "In11.Cu")
		(net "PRSNT_SWB_ISO_R_N")
	)
	(segment
		(start 185.755788 -110.975394)
		(end 186.1566 -111.376206)
		(width 0.127)
		(layer "In11.Cu")
		(net "PRSNT_SWB_ISO_R_N")
	)
	(segment
		(start 97.6884 -406.6032)
		(end 99.3902 -408.305)
		(width 0.12954)
		(layer "F.Cu")
		(net "PRSNT_SWB_N")
	)
	(segment
		(start 100.8634 -411.7086)
		(end 101.219 -412.0642)
		(width 0.12954)
		(layer "F.Cu")
		(net "PRSNT_SWB_N")
	)
	(segment
		(start 100.8634 -409.702)
		(end 100.8634 -411.7086)
		(width 0.12954)
		(layer "F.Cu")
		(net "PRSNT_SWB_N")
	)
	(segment
		(start 97.6884 -405.1554)
		(end 97.6884 -406.6032)
		(width 0.12954)
		(layer "F.Cu")
		(net "PRSNT_SWB_N")
	)
	(segment
		(start 104.14 -412.0642)
		(end 105.22585 -410.97835)
		(width 0.12954)
		(layer "F.Cu")
		(net "PRSNT_SWB_N")
	)
	(segment
		(start 105.22585 -410.97835)
		(end 105.22585 -410.2608)
		(width 0.12954)
		(layer "F.Cu")
		(net "PRSNT_SWB_N")
	)
	(segment
		(start 105.81005 -408.686)
		(end 105.22585 -409.2702)
		(width 0.12954)
		(layer "F.Cu")
		(net "PRSNT_SWB_N")
	)
	(segment
		(start 101.219 -412.0642)
		(end 104.14 -412.0642)
		(width 0.12954)
		(layer "F.Cu")
		(net "PRSNT_SWB_N")
	)
	(segment
		(start 99.4664 -408.305)
		(end 100.8634 -409.702)
		(width 0.12954)
		(layer "F.Cu")
		(net "PRSNT_SWB_N")
	)
	(segment
		(start 106.41584 -408.686)
		(end 105.81005 -408.686)
		(width 0.12954)
		(layer "F.Cu")
		(net "PRSNT_SWB_N")
	)
	(segment
		(start 99.3902 -408.305)
		(end 99.4664 -408.305)
		(width 0.12954)
		(layer "F.Cu")
		(net "PRSNT_SWB_N")
	)
	(segment
		(start 105.22585 -409.2702)
		(end 105.22585 -410.2608)
		(width 0.12954)
		(layer "F.Cu")
		(net "PRSNT_SWB_N")
	)
	(via
		(at 100.9396 -416.814)
		(size 0.508)
		(drill 0.254)
		(layers "F.Cu" "B.Cu")
		(net "PRSNT_SWB_N")
	)
	(via
		(at 97.6884 -405.1554)
		(size 0.6604)
		(drill 0.254)
		(layers "F.Cu" "B.Cu")
		(net "PRSNT_SWB_N")
	)
	(segment
		(start 71.7931 -417.327588)
		(end 71.7931 -439.798968)
		(width 0.127)
		(layer "In2.Cu")
		(net "PRSNT_SWB_N")
	)
	(segment
		(start 75.58786 -416.662108)
		(end 72.45858 -416.662108)
		(width 0.127)
		(layer "In2.Cu")
		(net "PRSNT_SWB_N")
	)
	(segment
		(start 71.7931 -439.798968)
		(end 71.10222 -440.489848)
		(width 0.127)
		(layer "In2.Cu")
		(net "PRSNT_SWB_N")
	)
	(segment
		(start 100.5586 -417.195)
		(end 100.5586 -419.2778)
		(width 0.127)
		(layer "In2.Cu")
		(net "PRSNT_SWB_N")
	)
	(segment
		(start 100.5586 -419.2778)
		(end 100.453952 -419.382448)
		(width 0.127)
		(layer "In2.Cu")
		(net "PRSNT_SWB_N")
	)
	(segment
		(start 72.45858 -416.662108)
		(end 71.7931 -417.327588)
		(width 0.127)
		(layer "In2.Cu")
		(net "PRSNT_SWB_N")
	)
	(segment
		(start 100.9396 -416.814)
		(end 100.5586 -417.195)
		(width 0.127)
		(layer "In2.Cu")
		(net "PRSNT_SWB_N")
	)
	(segment
		(start 78.3082 -419.382448)
		(end 75.58786 -416.662108)
		(width 0.127)
		(layer "In2.Cu")
		(net "PRSNT_SWB_N")
	)
	(segment
		(start 71.10222 -440.489848)
		(end 70.6501 -440.489848)
		(width 0.127)
		(layer "In2.Cu")
		(net "PRSNT_SWB_N")
	)
	(segment
		(start 100.453952 -419.382448)
		(end 78.3082 -419.382448)
		(width 0.127)
		(layer "In2.Cu")
		(net "PRSNT_SWB_N")
	)
	(segment
		(start 97.5868 -407.6192)
		(end 97.5868 -411.9372)
		(width 0.127)
		(layer "In11.Cu")
		(net "PRSNT_SWB_N")
	)
	(segment
		(start 97.6884 -405.1554)
		(end 97.6884 -407.5176)
		(width 0.127)
		(layer "In11.Cu")
		(net "PRSNT_SWB_N")
	)
	(segment
		(start 97.5868 -411.9372)
		(end 98.5774 -412.9278)
		(width 0.127)
		(layer "In11.Cu")
		(net "PRSNT_SWB_N")
	)
	(segment
		(start 102.0318 -414.3756)
		(end 102.0318 -416.3822)
		(width 0.127)
		(layer "In11.Cu")
		(net "PRSNT_SWB_N")
	)
	(segment
		(start 102.0318 -416.3822)
		(end 101.6 -416.814)
		(width 0.127)
		(layer "In11.Cu")
		(net "PRSNT_SWB_N")
	)
	(segment
		(start 101.6 -416.814)
		(end 100.9396 -416.814)
		(width 0.127)
		(layer "In11.Cu")
		(net "PRSNT_SWB_N")
	)
	(segment
		(start 97.6884 -407.5176)
		(end 97.5868 -407.6192)
		(width 0.127)
		(layer "In11.Cu")
		(net "PRSNT_SWB_N")
	)
	(segment
		(start 98.5774 -412.9278)
		(end 100.584 -412.9278)
		(width 0.127)
		(layer "In11.Cu")
		(net "PRSNT_SWB_N")
	)
	(segment
		(start 100.584 -412.9278)
		(end 102.0318 -414.3756)
		(width 0.127)
		(layer "In11.Cu")
		(net "PRSNT_SWB_N")
	)
	(segment
		(start 224.50298 -69.253608)
		(end 224.836482 -69.253608)
		(width 0.12954)
		(layer "F.Cu")
		(net "TP_P3V3_E1S_PWRGD_0")
	)
	(segment
		(start 225.171762 -68.918328)
		(end 225.171762 -67.921378)
		(width 0.12954)
		(layer "F.Cu")
		(net "TP_P3V3_E1S_PWRGD_0")
	)
	(segment
		(start 224.836482 -69.253608)
		(end 225.171762 -68.918328)
		(width 0.12954)
		(layer "F.Cu")
		(net "TP_P3V3_E1S_PWRGD_0")
	)
	(via
		(at 224.50298 -69.253608)
		(size 0.508)
		(drill 0.254)
		(layers "F.Cu" "B.Cu")
		(net "TP_P3V3_E1S_PWRGD_0")
	)
	(segment
		(start 125.48108 -107.059222)
		(end 125.654054 -107.232196)
		(width 0.12954)
		(layer "F.Cu")
		(net "RST_CPU1_DRAM_GH_PLD_LVT3_R_N")
	)
	(segment
		(start 125.654054 -107.232196)
		(end 125.654054 -108.447586)
		(width 0.12954)
		(layer "F.Cu")
		(net "RST_CPU1_DRAM_GH_PLD_LVT3_R_N")
	)
	(segment
		(start 125.269752 -108.831888)
		(end 125.269752 -110.200948)
		(width 0.12954)
		(layer "F.Cu")
		(net "RST_CPU1_DRAM_GH_PLD_LVT3_R_N")
	)
	(segment
		(start 125.48108 -106.638598)
		(end 125.48108 -107.059222)
		(width 0.12954)
		(layer "F.Cu")
		(net "RST_CPU1_DRAM_GH_PLD_LVT3_R_N")
	)
	(segment
		(start 125.654054 -108.447586)
		(end 125.269752 -108.831888)
		(width 0.12954)
		(layer "F.Cu")
		(net "RST_CPU1_DRAM_GH_PLD_LVT3_R_N")
	)
	(via
		(at 125.654054 -108.447586)
		(size 0.762)
		(drill 0.381)
		(layers "F.Cu" "B.Cu")
		(net "RST_CPU1_DRAM_GH_PLD_LVT3_R_N")
	)
	(segment
		(start 175.755554 -109.775498)
		(end 175.355504 -109.375448)
		(width 0.12954)
		(layer "F.Cu")
		(net "RST_CPU1_DRAM_GH_PLD_LVT3_N")
	)
	(segment
		(start 125.48108 -105.838498)
		(end 125.48108 -105.222548)
		(width 0.12954)
		(layer "F.Cu")
		(net "RST_CPU1_DRAM_GH_PLD_LVT3_N")
	)
	(via
		(at 125.48108 -105.222548)
		(size 0.508)
		(drill 0.254)
		(layers "F.Cu" "B.Cu")
		(net "RST_CPU1_DRAM_GH_PLD_LVT3_N")
	)
	(via
		(at 175.355504 -109.375448)
		(size 0.4572)
		(drill 0.254)
		(layers "F.Cu" "B.Cu")
		(net "RST_CPU1_DRAM_GH_PLD_LVT3_N")
	)
	(segment
		(start 126.24308 -105.984548)
		(end 125.48108 -105.222548)
		(width 0.127)
		(layer "In15.Cu")
		(net "RST_CPU1_DRAM_GH_PLD_LVT3_N")
	)
	(segment
		(start 169.297096 -110.759748)
		(end 160.83788 -110.759748)
		(width 0.127)
		(layer "In15.Cu")
		(net "RST_CPU1_DRAM_GH_PLD_LVT3_N")
	)
	(segment
		(start 152.22728 -111.521748)
		(end 151.69388 -110.988348)
		(width 0.127)
		(layer "In15.Cu")
		(net "RST_CPU1_DRAM_GH_PLD_LVT3_N")
	)
	(segment
		(start 149.292056 -110.988348)
		(end 146.20621 -107.902502)
		(width 0.127)
		(layer "In15.Cu")
		(net "RST_CPU1_DRAM_GH_PLD_LVT3_N")
	)
	(segment
		(start 174.961804 -109.769148)
		(end 172.004736 -109.769148)
		(width 0.127)
		(layer "In15.Cu")
		(net "RST_CPU1_DRAM_GH_PLD_LVT3_N")
	)
	(segment
		(start 129.924302 -107.902502)
		(end 128.006348 -105.984548)
		(width 0.127)
		(layer "In15.Cu")
		(net "RST_CPU1_DRAM_GH_PLD_LVT3_N")
	)
	(segment
		(start 171.496736 -110.277148)
		(end 169.779696 -110.277148)
		(width 0.127)
		(layer "In15.Cu")
		(net "RST_CPU1_DRAM_GH_PLD_LVT3_N")
	)
	(segment
		(start 172.004736 -109.769148)
		(end 171.496736 -110.277148)
		(width 0.127)
		(layer "In15.Cu")
		(net "RST_CPU1_DRAM_GH_PLD_LVT3_N")
	)
	(segment
		(start 128.006348 -105.984548)
		(end 126.24308 -105.984548)
		(width 0.127)
		(layer "In15.Cu")
		(net "RST_CPU1_DRAM_GH_PLD_LVT3_N")
	)
	(segment
		(start 146.20621 -107.902502)
		(end 129.924302 -107.902502)
		(width 0.127)
		(layer "In15.Cu")
		(net "RST_CPU1_DRAM_GH_PLD_LVT3_N")
	)
	(segment
		(start 160.07588 -111.521748)
		(end 152.22728 -111.521748)
		(width 0.127)
		(layer "In15.Cu")
		(net "RST_CPU1_DRAM_GH_PLD_LVT3_N")
	)
	(segment
		(start 169.779696 -110.277148)
		(end 169.297096 -110.759748)
		(width 0.127)
		(layer "In15.Cu")
		(net "RST_CPU1_DRAM_GH_PLD_LVT3_N")
	)
	(segment
		(start 175.355504 -109.375448)
		(end 174.961804 -109.769148)
		(width 0.127)
		(layer "In15.Cu")
		(net "RST_CPU1_DRAM_GH_PLD_LVT3_N")
	)
	(segment
		(start 160.83788 -110.759748)
		(end 160.07588 -111.521748)
		(width 0.127)
		(layer "In15.Cu")
		(net "RST_CPU1_DRAM_GH_PLD_LVT3_N")
	)
	(segment
		(start 151.69388 -110.988348)
		(end 149.292056 -110.988348)
		(width 0.127)
		(layer "In15.Cu")
		(net "RST_CPU1_DRAM_GH_PLD_LVT3_N")
	)
	(segment
		(start 124.619766 -108.302298)
		(end 124.257054 -107.939586)
		(width 0.12954)
		(layer "F.Cu")
		(net "RST_CPU1_DRAM_EF_PLD_LVT3_R_N")
	)
	(segment
		(start 124.257054 -107.939586)
		(end 124.257054 -107.140248)
		(width 0.12954)
		(layer "F.Cu")
		(net "RST_CPU1_DRAM_EF_PLD_LVT3_R_N")
	)
	(segment
		(start 124.619766 -110.200948)
		(end 124.619766 -108.302298)
		(width 0.12954)
		(layer "F.Cu")
		(net "RST_CPU1_DRAM_EF_PLD_LVT3_R_N")
	)
	(segment
		(start 124.257054 -107.140248)
		(end 124.33808 -107.059222)
		(width 0.12954)
		(layer "F.Cu")
		(net "RST_CPU1_DRAM_EF_PLD_LVT3_R_N")
	)
	(segment
		(start 124.33808 -107.059222)
		(end 124.33808 -106.638598)
		(width 0.12954)
		(layer "F.Cu")
		(net "RST_CPU1_DRAM_EF_PLD_LVT3_R_N")
	)
	(via
		(at 124.257054 -107.939586)
		(size 0.762)
		(drill 0.381)
		(layers "F.Cu" "B.Cu")
		(net "RST_CPU1_DRAM_EF_PLD_LVT3_R_N")
	)
	(segment
		(start 124.33808 -105.838498)
		(end 124.33808 -104.612948)
		(width 0.12954)
		(layer "F.Cu")
		(net "RST_CPU1_DRAM_EF_PLD_LVT3_N")
	)
	(segment
		(start 174.955708 -108.975398)
		(end 174.555658 -108.575348)
		(width 0.12954)
		(layer "F.Cu")
		(net "RST_CPU1_DRAM_EF_PLD_LVT3_N")
	)
	(via
		(at 124.33808 -104.612948)
		(size 0.508)
		(drill 0.254)
		(layers "F.Cu" "B.Cu")
		(net "RST_CPU1_DRAM_EF_PLD_LVT3_N")
	)
	(via
		(at 174.555658 -108.575348)
		(size 0.4572)
		(drill 0.254)
		(layers "F.Cu" "B.Cu")
		(net "RST_CPU1_DRAM_EF_PLD_LVT3_N")
	)
	(segment
		(start 169.6847 -108.212128)
		(end 170.45178 -108.979208)
		(width 0.127)
		(layer "In15.Cu")
		(net "RST_CPU1_DRAM_EF_PLD_LVT3_N")
	)
	(segment
		(start 163.875974 -109.0168)
		(end 164.680646 -108.212128)
		(width 0.127)
		(layer "In15.Cu")
		(net "RST_CPU1_DRAM_EF_PLD_LVT3_N")
	)
	(segment
		(start 144.005046 -105.664508)
		(end 145.288 -105.664508)
		(width 0.127)
		(layer "In15.Cu")
		(net "RST_CPU1_DRAM_EF_PLD_LVT3_N")
	)
	(segment
		(start 174.151798 -108.979208)
		(end 174.555658 -108.575348)
		(width 0.127)
		(layer "In15.Cu")
		(net "RST_CPU1_DRAM_EF_PLD_LVT3_N")
	)
	(segment
		(start 164.680646 -108.212128)
		(end 169.6847 -108.212128)
		(width 0.127)
		(layer "In15.Cu")
		(net "RST_CPU1_DRAM_EF_PLD_LVT3_N")
	)
	(segment
		(start 151.28494 -107.406948)
		(end 152.894792 -109.0168)
		(width 0.127)
		(layer "In15.Cu")
		(net "RST_CPU1_DRAM_EF_PLD_LVT3_N")
	)
	(segment
		(start 170.45178 -108.979208)
		(end 174.151798 -108.979208)
		(width 0.127)
		(layer "In15.Cu")
		(net "RST_CPU1_DRAM_EF_PLD_LVT3_N")
	)
	(segment
		(start 145.288 -105.664508)
		(end 147.03044 -107.406948)
		(width 0.127)
		(layer "In15.Cu")
		(net "RST_CPU1_DRAM_EF_PLD_LVT3_N")
	)
	(segment
		(start 124.48032 -104.470708)
		(end 142.811246 -104.470708)
		(width 0.127)
		(layer "In15.Cu")
		(net "RST_CPU1_DRAM_EF_PLD_LVT3_N")
	)
	(segment
		(start 152.894792 -109.0168)
		(end 163.875974 -109.0168)
		(width 0.127)
		(layer "In15.Cu")
		(net "RST_CPU1_DRAM_EF_PLD_LVT3_N")
	)
	(segment
		(start 147.03044 -107.406948)
		(end 151.28494 -107.406948)
		(width 0.127)
		(layer "In15.Cu")
		(net "RST_CPU1_DRAM_EF_PLD_LVT3_N")
	)
	(segment
		(start 142.811246 -104.470708)
		(end 144.005046 -105.664508)
		(width 0.127)
		(layer "In15.Cu")
		(net "RST_CPU1_DRAM_EF_PLD_LVT3_N")
	)
	(segment
		(start 124.33808 -104.612948)
		(end 124.48032 -104.470708)
		(width 0.127)
		(layer "In15.Cu")
		(net "RST_CPU1_DRAM_EF_PLD_LVT3_N")
	)
	(segment
		(start 122.987054 -107.267248)
		(end 123.19508 -107.059222)
		(width 0.12954)
		(layer "F.Cu")
		(net "RST_CPU1_DRAM_CD_PLD_LVT3_R_N")
	)
	(segment
		(start 122.987054 -108.447586)
		(end 122.987054 -107.267248)
		(width 0.12954)
		(layer "F.Cu")
		(net "RST_CPU1_DRAM_CD_PLD_LVT3_R_N")
	)
	(segment
		(start 123.19508 -107.059222)
		(end 123.19508 -106.638598)
		(width 0.12954)
		(layer "F.Cu")
		(net "RST_CPU1_DRAM_CD_PLD_LVT3_R_N")
	)
	(segment
		(start 123.319794 -110.200948)
		(end 123.319794 -108.780326)
		(width 0.12954)
		(layer "F.Cu")
		(net "RST_CPU1_DRAM_CD_PLD_LVT3_R_N")
	)
	(segment
		(start 123.319794 -108.780326)
		(end 122.987054 -108.447586)
		(width 0.12954)
		(layer "F.Cu")
		(net "RST_CPU1_DRAM_CD_PLD_LVT3_R_N")
	)
	(via
		(at 122.987054 -108.447586)
		(size 0.762)
		(drill 0.381)
		(layers "F.Cu" "B.Cu")
		(net "RST_CPU1_DRAM_CD_PLD_LVT3_R_N")
	)
	(segment
		(start 123.19508 -105.838498)
		(end 123.19508 -105.197148)
		(width 0.12954)
		(layer "F.Cu")
		(net "RST_CPU1_DRAM_CD_PLD_LVT3_N")
	)
	(segment
		(start 174.155608 -108.175552)
		(end 173.755558 -107.775502)
		(width 0.12954)
		(layer "F.Cu")
		(net "RST_CPU1_DRAM_CD_PLD_LVT3_N")
	)
	(via
		(at 123.19508 -105.197148)
		(size 0.508)
		(drill 0.254)
		(layers "F.Cu" "B.Cu")
		(net "RST_CPU1_DRAM_CD_PLD_LVT3_N")
	)
	(via
		(at 173.755558 -107.775502)
		(size 0.4572)
		(drill 0.254)
		(layers "F.Cu" "B.Cu")
		(net "RST_CPU1_DRAM_CD_PLD_LVT3_N")
	)
	(segment
		(start 173.755558 -107.775502)
		(end 173.351952 -108.179108)
		(width 0.127)
		(layer "In15.Cu")
		(net "RST_CPU1_DRAM_CD_PLD_LVT3_N")
	)
	(segment
		(start 143.38554 -102.809548)
		(end 138.51128 -102.809548)
		(width 0.127)
		(layer "In15.Cu")
		(net "RST_CPU1_DRAM_CD_PLD_LVT3_N")
	)
	(segment
		(start 147.50034 -106.924348)
		(end 143.38554 -102.809548)
		(width 0.127)
		(layer "In15.Cu")
		(net "RST_CPU1_DRAM_CD_PLD_LVT3_N")
	)
	(segment
		(start 138.51128 -102.809548)
		(end 138.00328 -103.317548)
		(width 0.127)
		(layer "In15.Cu")
		(net "RST_CPU1_DRAM_CD_PLD_LVT3_N")
	)
	(segment
		(start 154.2669 -106.924348)
		(end 147.50034 -106.924348)
		(width 0.127)
		(layer "In15.Cu")
		(net "RST_CPU1_DRAM_CD_PLD_LVT3_N")
	)
	(segment
		(start 170.53814 -107.780328)
		(end 155.12288 -107.780328)
		(width 0.127)
		(layer "In15.Cu")
		(net "RST_CPU1_DRAM_CD_PLD_LVT3_N")
	)
	(segment
		(start 173.351952 -108.179108)
		(end 170.93692 -108.179108)
		(width 0.127)
		(layer "In15.Cu")
		(net "RST_CPU1_DRAM_CD_PLD_LVT3_N")
	)
	(segment
		(start 124.38634 -103.317548)
		(end 123.19508 -104.508808)
		(width 0.127)
		(layer "In15.Cu")
		(net "RST_CPU1_DRAM_CD_PLD_LVT3_N")
	)
	(segment
		(start 170.93692 -108.179108)
		(end 170.53814 -107.780328)
		(width 0.127)
		(layer "In15.Cu")
		(net "RST_CPU1_DRAM_CD_PLD_LVT3_N")
	)
	(segment
		(start 138.00328 -103.317548)
		(end 124.38634 -103.317548)
		(width 0.127)
		(layer "In15.Cu")
		(net "RST_CPU1_DRAM_CD_PLD_LVT3_N")
	)
	(segment
		(start 123.19508 -104.508808)
		(end 123.19508 -105.197148)
		(width 0.127)
		(layer "In15.Cu")
		(net "RST_CPU1_DRAM_CD_PLD_LVT3_N")
	)
	(segment
		(start 155.12288 -107.780328)
		(end 154.2669 -106.924348)
		(width 0.127)
		(layer "In15.Cu")
		(net "RST_CPU1_DRAM_CD_PLD_LVT3_N")
	)
	(segment
		(start 122.669808 -109.01934)
		(end 121.780554 -108.130086)
		(width 0.12954)
		(layer "F.Cu")
		(net "RST_CPU1_DRAM_AB_PLD_LVT3_R_N")
	)
	(segment
		(start 121.780554 -107.075224)
		(end 121.78919 -107.066588)
		(width 0.12954)
		(layer "F.Cu")
		(net "RST_CPU1_DRAM_AB_PLD_LVT3_R_N")
	)
	(segment
		(start 121.780554 -107.876086)
		(end 121.780554 -107.075224)
		(width 0.12954)
		(layer "F.Cu")
		(net "RST_CPU1_DRAM_AB_PLD_LVT3_R_N")
	)
	(segment
		(start 121.780554 -108.130086)
		(end 121.780554 -107.876086)
		(width 0.12954)
		(layer "F.Cu")
		(net "RST_CPU1_DRAM_AB_PLD_LVT3_R_N")
	)
	(segment
		(start 122.669808 -110.200948)
		(end 122.669808 -109.01934)
		(width 0.12954)
		(layer "F.Cu")
		(net "RST_CPU1_DRAM_AB_PLD_LVT3_R_N")
	)
	(segment
		(start 121.78919 -107.003088)
		(end 122.05208 -106.740198)
		(width 0.12954)
		(layer "F.Cu")
		(net "RST_CPU1_DRAM_AB_PLD_LVT3_R_N")
	)
	(segment
		(start 122.05208 -106.740198)
		(end 122.05208 -106.638598)
		(width 0.12954)
		(layer "F.Cu")
		(net "RST_CPU1_DRAM_AB_PLD_LVT3_R_N")
	)
	(segment
		(start 121.78919 -107.066588)
		(end 121.78919 -107.003088)
		(width 0.12954)
		(layer "F.Cu")
		(net "RST_CPU1_DRAM_AB_PLD_LVT3_R_N")
	)
	(via
		(at 121.780554 -107.876086)
		(size 0.762)
		(drill 0.381)
		(layers "F.Cu" "B.Cu")
		(net "RST_CPU1_DRAM_AB_PLD_LVT3_R_N")
	)
	(segment
		(start 173.355762 -107.375452)
		(end 172.955712 -106.975402)
		(width 0.12954)
		(layer "F.Cu")
		(net "RST_CPU1_DRAM_AB_PLD_LVT3_N")
	)
	(segment
		(start 122.05208 -105.838498)
		(end 119.86768 -105.838498)
		(width 0.12954)
		(layer "F.Cu")
		(net "RST_CPU1_DRAM_AB_PLD_LVT3_N")
	)
	(via
		(at 119.86768 -105.838498)
		(size 0.508)
		(drill 0.254)
		(layers "F.Cu" "B.Cu")
		(net "RST_CPU1_DRAM_AB_PLD_LVT3_N")
	)
	(via
		(at 172.955712 -106.975402)
		(size 0.4572)
		(drill 0.254)
		(layers "F.Cu" "B.Cu")
		(net "RST_CPU1_DRAM_AB_PLD_LVT3_N")
	)
	(segment
		(start 120.74652 -101.752908)
		(end 119.86768 -102.631748)
		(width 0.127)
		(layer "In15.Cu")
		(net "RST_CPU1_DRAM_AB_PLD_LVT3_N")
	)
	(segment
		(start 172.54982 -106.56951)
		(end 172.54982 -106.004868)
		(width 0.127)
		(layer "In15.Cu")
		(net "RST_CPU1_DRAM_AB_PLD_LVT3_N")
	)
	(segment
		(start 170.67911 -106.133138)
		(end 165.842442 -106.133138)
		(width 0.127)
		(layer "In15.Cu")
		(net "RST_CPU1_DRAM_AB_PLD_LVT3_N")
	)
	(segment
		(start 146.5453 -104.010968)
		(end 142.8623 -100.327968)
		(width 0.127)
		(layer "In15.Cu")
		(net "RST_CPU1_DRAM_AB_PLD_LVT3_N")
	)
	(segment
		(start 130.44424 -100.327968)
		(end 129.0193 -101.752908)
		(width 0.127)
		(layer "In15.Cu")
		(net "RST_CPU1_DRAM_AB_PLD_LVT3_N")
	)
	(segment
		(start 119.86768 -102.631748)
		(end 119.86768 -105.838498)
		(width 0.127)
		(layer "In15.Cu")
		(net "RST_CPU1_DRAM_AB_PLD_LVT3_N")
	)
	(segment
		(start 163.720272 -104.010968)
		(end 146.5453 -104.010968)
		(width 0.127)
		(layer "In15.Cu")
		(net "RST_CPU1_DRAM_AB_PLD_LVT3_N")
	)
	(segment
		(start 129.0193 -101.752908)
		(end 120.74652 -101.752908)
		(width 0.127)
		(layer "In15.Cu")
		(net "RST_CPU1_DRAM_AB_PLD_LVT3_N")
	)
	(segment
		(start 165.842442 -106.133138)
		(end 163.720272 -104.010968)
		(width 0.127)
		(layer "In15.Cu")
		(net "RST_CPU1_DRAM_AB_PLD_LVT3_N")
	)
	(segment
		(start 172.31868 -105.773728)
		(end 171.03852 -105.773728)
		(width 0.127)
		(layer "In15.Cu")
		(net "RST_CPU1_DRAM_AB_PLD_LVT3_N")
	)
	(segment
		(start 142.8623 -100.327968)
		(end 130.44424 -100.327968)
		(width 0.127)
		(layer "In15.Cu")
		(net "RST_CPU1_DRAM_AB_PLD_LVT3_N")
	)
	(segment
		(start 172.955712 -106.975402)
		(end 172.54982 -106.56951)
		(width 0.127)
		(layer "In15.Cu")
		(net "RST_CPU1_DRAM_AB_PLD_LVT3_N")
	)
	(segment
		(start 172.54982 -106.004868)
		(end 172.31868 -105.773728)
		(width 0.127)
		(layer "In15.Cu")
		(net "RST_CPU1_DRAM_AB_PLD_LVT3_N")
	)
	(segment
		(start 171.03852 -105.773728)
		(end 170.67911 -106.133138)
		(width 0.127)
		(layer "In15.Cu")
		(net "RST_CPU1_DRAM_AB_PLD_LVT3_N")
	)
	(segment
		(start 115.960906 -108.867702)
		(end 115.960906 -110.236762)
		(width 0.12954)
		(layer "F.Cu")
		(net "RST_CPU0_DRAM_GH_PLD_LVT3_R_N")
	)
	(segment
		(start 116.345208 -108.4834)
		(end 115.960906 -108.867702)
		(width 0.12954)
		(layer "F.Cu")
		(net "RST_CPU0_DRAM_GH_PLD_LVT3_R_N")
	)
	(segment
		(start 116.21008 -106.638598)
		(end 116.21008 -107.186222)
		(width 0.12954)
		(layer "F.Cu")
		(net "RST_CPU0_DRAM_GH_PLD_LVT3_R_N")
	)
	(segment
		(start 116.21008 -107.186222)
		(end 116.345208 -107.32135)
		(width 0.12954)
		(layer "F.Cu")
		(net "RST_CPU0_DRAM_GH_PLD_LVT3_R_N")
	)
	(segment
		(start 116.345208 -107.32135)
		(end 116.345208 -108.4834)
		(width 0.12954)
		(layer "F.Cu")
		(net "RST_CPU0_DRAM_GH_PLD_LVT3_R_N")
	)
	(via
		(at 116.345208 -108.4834)
		(size 0.762)
		(drill 0.381)
		(layers "F.Cu" "B.Cu")
		(net "RST_CPU0_DRAM_GH_PLD_LVT3_R_N")
	)
	(segment
		(start 116.4844 -105.222548)
		(end 116.21008 -105.496868)
		(width 0.12954)
		(layer "F.Cu")
		(net "RST_CPU0_DRAM_GH_PLD_LVT3_N")
	)
	(segment
		(start 116.21008 -105.496868)
		(end 116.21008 -105.838498)
		(width 0.12954)
		(layer "F.Cu")
		(net "RST_CPU0_DRAM_GH_PLD_LVT3_N")
	)
	(segment
		(start 174.955708 -109.775498)
		(end 174.555658 -109.375448)
		(width 0.12954)
		(layer "F.Cu")
		(net "RST_CPU0_DRAM_GH_PLD_LVT3_N")
	)
	(via
		(at 116.4844 -105.222548)
		(size 0.508)
		(drill 0.254)
		(layers "F.Cu" "B.Cu")
		(net "RST_CPU0_DRAM_GH_PLD_LVT3_N")
	)
	(via
		(at 174.555658 -109.375448)
		(size 0.4572)
		(drill 0.254)
		(layers "F.Cu" "B.Cu")
		(net "RST_CPU0_DRAM_GH_PLD_LVT3_N")
	)
	(segment
		(start 174.1551 -105.026968)
		(end 173.80458 -104.676448)
		(width 0.127)
		(layer "In15.Cu")
		(net "RST_CPU0_DRAM_GH_PLD_LVT3_N")
	)
	(segment
		(start 121.954544 -98.538284)
		(end 118.31828 -102.174548)
		(width 0.127)
		(layer "In15.Cu")
		(net "RST_CPU0_DRAM_GH_PLD_LVT3_N")
	)
	(segment
		(start 164.07892 -103.147368)
		(end 148.02358 -103.147368)
		(width 0.127)
		(layer "In15.Cu")
		(net "RST_CPU0_DRAM_GH_PLD_LVT3_N")
	)
	(segment
		(start 166.12616 -105.194608)
		(end 164.07892 -103.147368)
		(width 0.127)
		(layer "In15.Cu")
		(net "RST_CPU0_DRAM_GH_PLD_LVT3_N")
	)
	(segment
		(start 174.95012 -108.980986)
		(end 174.95012 -107.582208)
		(width 0.127)
		(layer "In15.Cu")
		(net "RST_CPU0_DRAM_GH_PLD_LVT3_N")
	)
	(segment
		(start 174.1551 -106.787188)
		(end 174.1551 -105.026968)
		(width 0.127)
		(layer "In15.Cu")
		(net "RST_CPU0_DRAM_GH_PLD_LVT3_N")
	)
	(segment
		(start 148.02358 -103.147368)
		(end 143.414496 -98.538284)
		(width 0.127)
		(layer "In15.Cu")
		(net "RST_CPU0_DRAM_GH_PLD_LVT3_N")
	)
	(segment
		(start 170.30954 -104.676448)
		(end 169.79138 -105.194608)
		(width 0.127)
		(layer "In15.Cu")
		(net "RST_CPU0_DRAM_GH_PLD_LVT3_N")
	)
	(segment
		(start 174.555658 -109.375448)
		(end 174.95012 -108.980986)
		(width 0.127)
		(layer "In15.Cu")
		(net "RST_CPU0_DRAM_GH_PLD_LVT3_N")
	)
	(segment
		(start 173.80458 -104.676448)
		(end 170.30954 -104.676448)
		(width 0.127)
		(layer "In15.Cu")
		(net "RST_CPU0_DRAM_GH_PLD_LVT3_N")
	)
	(segment
		(start 174.95012 -107.582208)
		(end 174.1551 -106.787188)
		(width 0.127)
		(layer "In15.Cu")
		(net "RST_CPU0_DRAM_GH_PLD_LVT3_N")
	)
	(segment
		(start 118.31828 -103.388668)
		(end 116.4844 -105.222548)
		(width 0.127)
		(layer "In15.Cu")
		(net "RST_CPU0_DRAM_GH_PLD_LVT3_N")
	)
	(segment
		(start 143.414496 -98.538284)
		(end 121.954544 -98.538284)
		(width 0.127)
		(layer "In15.Cu")
		(net "RST_CPU0_DRAM_GH_PLD_LVT3_N")
	)
	(segment
		(start 118.31828 -102.174548)
		(end 118.31828 -103.388668)
		(width 0.127)
		(layer "In15.Cu")
		(net "RST_CPU0_DRAM_GH_PLD_LVT3_N")
	)
	(segment
		(start 169.79138 -105.194608)
		(end 166.12616 -105.194608)
		(width 0.127)
		(layer "In15.Cu")
		(net "RST_CPU0_DRAM_GH_PLD_LVT3_N")
	)
	(segment
		(start 114.948208 -107.305094)
		(end 115.06708 -107.186222)
		(width 0.12954)
		(layer "F.Cu")
		(net "RST_CPU0_DRAM_EF_PLD_LVT3_R_N")
	)
	(segment
		(start 114.948208 -107.9754)
		(end 114.948208 -107.305094)
		(width 0.12954)
		(layer "F.Cu")
		(net "RST_CPU0_DRAM_EF_PLD_LVT3_R_N")
	)
	(segment
		(start 115.31092 -110.236762)
		(end 115.31092 -108.338112)
		(width 0.12954)
		(layer "F.Cu")
		(net "RST_CPU0_DRAM_EF_PLD_LVT3_R_N")
	)
	(segment
		(start 115.06708 -107.186222)
		(end 115.06708 -106.638598)
		(width 0.12954)
		(layer "F.Cu")
		(net "RST_CPU0_DRAM_EF_PLD_LVT3_R_N")
	)
	(segment
		(start 115.31092 -108.338112)
		(end 114.948208 -107.9754)
		(width 0.12954)
		(layer "F.Cu")
		(net "RST_CPU0_DRAM_EF_PLD_LVT3_R_N")
	)
	(via
		(at 114.948208 -107.9754)
		(size 0.762)
		(drill 0.381)
		(layers "F.Cu" "B.Cu")
		(net "RST_CPU0_DRAM_EF_PLD_LVT3_R_N")
	)
	(segment
		(start 174.155608 -108.975398)
		(end 173.755558 -108.575348)
		(width 0.12954)
		(layer "F.Cu")
		(net "RST_CPU0_DRAM_EF_PLD_LVT3_N")
	)
	(segment
		(start 115.06708 -105.838498)
		(end 115.06708 -105.222548)
		(width 0.12954)
		(layer "F.Cu")
		(net "RST_CPU0_DRAM_EF_PLD_LVT3_N")
	)
	(via
		(at 115.06708 -105.222548)
		(size 0.508)
		(drill 0.254)
		(layers "F.Cu" "B.Cu")
		(net "RST_CPU0_DRAM_EF_PLD_LVT3_N")
	)
	(via
		(at 173.755558 -108.575348)
		(size 0.4572)
		(drill 0.254)
		(layers "F.Cu" "B.Cu")
		(net "RST_CPU0_DRAM_EF_PLD_LVT3_N")
	)
	(segment
		(start 143.98498 -99.878388)
		(end 121.27484 -99.878388)
		(width 0.127)
		(layer "In15.Cu")
		(net "RST_CPU0_DRAM_EF_PLD_LVT3_N")
	)
	(segment
		(start 118.80088 -103.648002)
		(end 116.69268 -105.756202)
		(width 0.127)
		(layer "In15.Cu")
		(net "RST_CPU0_DRAM_EF_PLD_LVT3_N")
	)
	(segment
		(start 118.80088 -102.352348)
		(end 118.80088 -103.648002)
		(width 0.127)
		(layer "In15.Cu")
		(net "RST_CPU0_DRAM_EF_PLD_LVT3_N")
	)
	(segment
		(start 116.69268 -105.756202)
		(end 115.600734 -105.756202)
		(width 0.127)
		(layer "In15.Cu")
		(net "RST_CPU0_DRAM_EF_PLD_LVT3_N")
	)
	(segment
		(start 174.15002 -108.180886)
		(end 174.15002 -107.572048)
		(width 0.127)
		(layer "In15.Cu")
		(net "RST_CPU0_DRAM_EF_PLD_LVT3_N")
	)
	(segment
		(start 173.35754 -107.180888)
		(end 173.35754 -105.169208)
		(width 0.127)
		(layer "In15.Cu")
		(net "RST_CPU0_DRAM_EF_PLD_LVT3_N")
	)
	(segment
		(start 169.67962 -105.677208)
		(end 165.997636 -105.677208)
		(width 0.127)
		(layer "In15.Cu")
		(net "RST_CPU0_DRAM_EF_PLD_LVT3_N")
	)
	(segment
		(start 174.15002 -107.572048)
		(end 173.94936 -107.371388)
		(width 0.127)
		(layer "In15.Cu")
		(net "RST_CPU0_DRAM_EF_PLD_LVT3_N")
	)
	(segment
		(start 163.899596 -103.579168)
		(end 147.68576 -103.579168)
		(width 0.127)
		(layer "In15.Cu")
		(net "RST_CPU0_DRAM_EF_PLD_LVT3_N")
	)
	(segment
		(start 173.35754 -105.169208)
		(end 173.14164 -104.953308)
		(width 0.127)
		(layer "In15.Cu")
		(net "RST_CPU0_DRAM_EF_PLD_LVT3_N")
	)
	(segment
		(start 173.94936 -107.371388)
		(end 173.54804 -107.371388)
		(width 0.127)
		(layer "In15.Cu")
		(net "RST_CPU0_DRAM_EF_PLD_LVT3_N")
	)
	(segment
		(start 115.600734 -105.756202)
		(end 115.06708 -105.222548)
		(width 0.127)
		(layer "In15.Cu")
		(net "RST_CPU0_DRAM_EF_PLD_LVT3_N")
	)
	(segment
		(start 173.54804 -107.371388)
		(end 173.35754 -107.180888)
		(width 0.127)
		(layer "In15.Cu")
		(net "RST_CPU0_DRAM_EF_PLD_LVT3_N")
	)
	(segment
		(start 121.27484 -99.878388)
		(end 118.80088 -102.352348)
		(width 0.127)
		(layer "In15.Cu")
		(net "RST_CPU0_DRAM_EF_PLD_LVT3_N")
	)
	(segment
		(start 173.755558 -108.575348)
		(end 174.15002 -108.180886)
		(width 0.127)
		(layer "In15.Cu")
		(net "RST_CPU0_DRAM_EF_PLD_LVT3_N")
	)
	(segment
		(start 165.997636 -105.677208)
		(end 163.899596 -103.579168)
		(width 0.127)
		(layer "In15.Cu")
		(net "RST_CPU0_DRAM_EF_PLD_LVT3_N")
	)
	(segment
		(start 170.40352 -104.953308)
		(end 169.67962 -105.677208)
		(width 0.127)
		(layer "In15.Cu")
		(net "RST_CPU0_DRAM_EF_PLD_LVT3_N")
	)
	(segment
		(start 173.14164 -104.953308)
		(end 170.40352 -104.953308)
		(width 0.127)
		(layer "In15.Cu")
		(net "RST_CPU0_DRAM_EF_PLD_LVT3_N")
	)
	(segment
		(start 147.68576 -103.579168)
		(end 143.98498 -99.878388)
		(width 0.127)
		(layer "In15.Cu")
		(net "RST_CPU0_DRAM_EF_PLD_LVT3_N")
	)
	(segment
		(start 113.92408 -107.059222)
		(end 113.92408 -106.638598)
		(width 0.12954)
		(layer "F.Cu")
		(net "RST_CPU0_DRAM_CD_PLD_LVT3_R_N")
	)
	(segment
		(start 114.010948 -108.81614)
		(end 113.678208 -108.4834)
		(width 0.12954)
		(layer "F.Cu")
		(net "RST_CPU0_DRAM_CD_PLD_LVT3_R_N")
	)
	(segment
		(start 113.678208 -107.305094)
		(end 113.92408 -107.059222)
		(width 0.12954)
		(layer "F.Cu")
		(net "RST_CPU0_DRAM_CD_PLD_LVT3_R_N")
	)
	(segment
		(start 113.678208 -108.4834)
		(end 113.678208 -107.305094)
		(width 0.12954)
		(layer "F.Cu")
		(net "RST_CPU0_DRAM_CD_PLD_LVT3_R_N")
	)
	(segment
		(start 114.010948 -110.236762)
		(end 114.010948 -108.81614)
		(width 0.12954)
		(layer "F.Cu")
		(net "RST_CPU0_DRAM_CD_PLD_LVT3_R_N")
	)
	(via
		(at 113.678208 -108.4834)
		(size 0.762)
		(drill 0.381)
		(layers "F.Cu" "B.Cu")
		(net "RST_CPU0_DRAM_CD_PLD_LVT3_R_N")
	)
	(segment
		(start 113.92408 -105.380028)
		(end 113.92408 -105.838498)
		(width 0.12954)
		(layer "F.Cu")
		(net "RST_CPU0_DRAM_CD_PLD_LVT3_N")
	)
	(segment
		(start 113.7285 -105.184448)
		(end 113.92408 -105.380028)
		(width 0.12954)
		(layer "F.Cu")
		(net "RST_CPU0_DRAM_CD_PLD_LVT3_N")
	)
	(segment
		(start 172.555662 -107.375452)
		(end 172.155612 -106.975402)
		(width 0.12954)
		(layer "F.Cu")
		(net "RST_CPU0_DRAM_CD_PLD_LVT3_N")
	)
	(via
		(at 172.155612 -106.975402)
		(size 0.4572)
		(drill 0.254)
		(layers "F.Cu" "B.Cu")
		(net "RST_CPU0_DRAM_CD_PLD_LVT3_N")
	)
	(via
		(at 113.7285 -105.184448)
		(size 0.508)
		(drill 0.254)
		(layers "F.Cu" "B.Cu")
		(net "RST_CPU0_DRAM_CD_PLD_LVT3_N")
	)
	(segment
		(start 162.07994 -106.467148)
		(end 147.72386 -106.467148)
		(width 0.127)
		(layer "In15.Cu")
		(net "RST_CPU0_DRAM_CD_PLD_LVT3_N")
	)
	(segment
		(start 162.59048 -106.977688)
		(end 162.07994 -106.467148)
		(width 0.127)
		(layer "In15.Cu")
		(net "RST_CPU0_DRAM_CD_PLD_LVT3_N")
	)
	(segment
		(start 137.41908 -102.885748)
		(end 128.42748 -102.885748)
		(width 0.127)
		(layer "In15.Cu")
		(net "RST_CPU0_DRAM_CD_PLD_LVT3_N")
	)
	(segment
		(start 138.9634 -101.341428)
		(end 137.41908 -102.885748)
		(width 0.127)
		(layer "In15.Cu")
		(net "RST_CPU0_DRAM_CD_PLD_LVT3_N")
	)
	(segment
		(start 121.89968 -102.733348)
		(end 121.67108 -102.961948)
		(width 0.127)
		(layer "In15.Cu")
		(net "RST_CPU0_DRAM_CD_PLD_LVT3_N")
	)
	(segment
		(start 113.92408 -105.380028)
		(end 113.7285 -105.184448)
		(width 0.127)
		(layer "In15.Cu")
		(net "RST_CPU0_DRAM_CD_PLD_LVT3_N")
	)
	(segment
		(start 128.42748 -102.885748)
		(end 128.27508 -102.733348)
		(width 0.127)
		(layer "In15.Cu")
		(net "RST_CPU0_DRAM_CD_PLD_LVT3_N")
	)
	(segment
		(start 147.72386 -106.467148)
		(end 142.59814 -101.341428)
		(width 0.127)
		(layer "In15.Cu")
		(net "RST_CPU0_DRAM_CD_PLD_LVT3_N")
	)
	(segment
		(start 115.67668 -107.254548)
		(end 113.92408 -105.501948)
		(width 0.127)
		(layer "In15.Cu")
		(net "RST_CPU0_DRAM_CD_PLD_LVT3_N")
	)
	(segment
		(start 169.38498 -107.381548)
		(end 169.22496 -107.221528)
		(width 0.127)
		(layer "In15.Cu")
		(net "RST_CPU0_DRAM_CD_PLD_LVT3_N")
	)
	(segment
		(start 120.32488 -107.254548)
		(end 115.67668 -107.254548)
		(width 0.127)
		(layer "In15.Cu")
		(net "RST_CPU0_DRAM_CD_PLD_LVT3_N")
	)
	(segment
		(start 128.27508 -102.733348)
		(end 121.89968 -102.733348)
		(width 0.127)
		(layer "In15.Cu")
		(net "RST_CPU0_DRAM_CD_PLD_LVT3_N")
	)
	(segment
		(start 121.67108 -102.961948)
		(end 121.67108 -105.908348)
		(width 0.127)
		(layer "In15.Cu")
		(net "RST_CPU0_DRAM_CD_PLD_LVT3_N")
	)
	(segment
		(start 121.67108 -105.908348)
		(end 120.32488 -107.254548)
		(width 0.127)
		(layer "In15.Cu")
		(net "RST_CPU0_DRAM_CD_PLD_LVT3_N")
	)
	(segment
		(start 164.87648 -107.221528)
		(end 164.14496 -106.490008)
		(width 0.127)
		(layer "In15.Cu")
		(net "RST_CPU0_DRAM_CD_PLD_LVT3_N")
	)
	(segment
		(start 169.22496 -107.221528)
		(end 164.87648 -107.221528)
		(width 0.127)
		(layer "In15.Cu")
		(net "RST_CPU0_DRAM_CD_PLD_LVT3_N")
	)
	(segment
		(start 162.89274 -106.977688)
		(end 162.59048 -106.977688)
		(width 0.127)
		(layer "In15.Cu")
		(net "RST_CPU0_DRAM_CD_PLD_LVT3_N")
	)
	(segment
		(start 171.749466 -107.381548)
		(end 169.38498 -107.381548)
		(width 0.127)
		(layer "In15.Cu")
		(net "RST_CPU0_DRAM_CD_PLD_LVT3_N")
	)
	(segment
		(start 113.92408 -105.501948)
		(end 113.92408 -105.380028)
		(width 0.127)
		(layer "In15.Cu")
		(net "RST_CPU0_DRAM_CD_PLD_LVT3_N")
	)
	(segment
		(start 164.14496 -106.490008)
		(end 163.38042 -106.490008)
		(width 0.127)
		(layer "In15.Cu")
		(net "RST_CPU0_DRAM_CD_PLD_LVT3_N")
	)
	(segment
		(start 142.59814 -101.341428)
		(end 138.9634 -101.341428)
		(width 0.127)
		(layer "In15.Cu")
		(net "RST_CPU0_DRAM_CD_PLD_LVT3_N")
	)
	(segment
		(start 163.38042 -106.490008)
		(end 162.89274 -106.977688)
		(width 0.127)
		(layer "In15.Cu")
		(net "RST_CPU0_DRAM_CD_PLD_LVT3_N")
	)
	(segment
		(start 172.155612 -106.975402)
		(end 171.749466 -107.381548)
		(width 0.127)
		(layer "In15.Cu")
		(net "RST_CPU0_DRAM_CD_PLD_LVT3_N")
	)
	(segment
		(start 112.78108 -106.765598)
		(end 112.78108 -106.638598)
		(width 0.12954)
		(layer "F.Cu")
		(net "RST_CPU0_DRAM_AB_PLD_LVT3_R_N")
	)
	(segment
		(start 112.471708 -107.07497)
		(end 112.78108 -106.765598)
		(width 0.12954)
		(layer "F.Cu")
		(net "RST_CPU0_DRAM_AB_PLD_LVT3_R_N")
	)
	(segment
		(start 112.471708 -108.1659)
		(end 112.471708 -107.9119)
		(width 0.12954)
		(layer "F.Cu")
		(net "RST_CPU0_DRAM_AB_PLD_LVT3_R_N")
	)
	(segment
		(start 113.360962 -109.055154)
		(end 112.471708 -108.1659)
		(width 0.12954)
		(layer "F.Cu")
		(net "RST_CPU0_DRAM_AB_PLD_LVT3_R_N")
	)
	(segment
		(start 112.471708 -107.9119)
		(end 112.471708 -107.07497)
		(width 0.12954)
		(layer "F.Cu")
		(net "RST_CPU0_DRAM_AB_PLD_LVT3_R_N")
	)
	(segment
		(start 113.360962 -110.236762)
		(end 113.360962 -109.055154)
		(width 0.12954)
		(layer "F.Cu")
		(net "RST_CPU0_DRAM_AB_PLD_LVT3_R_N")
	)
	(via
		(at 112.471708 -107.9119)
		(size 0.762)
		(drill 0.381)
		(layers "F.Cu" "B.Cu")
		(net "RST_CPU0_DRAM_AB_PLD_LVT3_R_N")
	)
	(segment
		(start 112.5982 -105.655618)
		(end 112.78108 -105.838498)
		(width 0.12954)
		(layer "F.Cu")
		(net "RST_CPU0_DRAM_AB_PLD_LVT3_N")
	)
	(segment
		(start 112.5982 -104.384348)
		(end 112.5982 -105.655618)
		(width 0.12954)
		(layer "F.Cu")
		(net "RST_CPU0_DRAM_AB_PLD_LVT3_N")
	)
	(segment
		(start 172.555662 -106.575352)
		(end 172.155612 -106.175302)
		(width 0.12954)
		(layer "F.Cu")
		(net "RST_CPU0_DRAM_AB_PLD_LVT3_N")
	)
	(via
		(at 112.5982 -104.384348)
		(size 0.508)
		(drill 0.254)
		(layers "F.Cu" "B.Cu")
		(net "RST_CPU0_DRAM_AB_PLD_LVT3_N")
	)
	(via
		(at 172.155612 -106.175302)
		(size 0.4572)
		(drill 0.254)
		(layers "F.Cu" "B.Cu")
		(net "RST_CPU0_DRAM_AB_PLD_LVT3_N")
	)
	(segment
		(start 169.18432 -106.571288)
		(end 169.05732 -106.698288)
		(width 0.127)
		(layer "In15.Cu")
		(net "RST_CPU0_DRAM_AB_PLD_LVT3_N")
	)
	(segment
		(start 165.10254 -106.698288)
		(end 164.05606 -105.651808)
		(width 0.127)
		(layer "In15.Cu")
		(net "RST_CPU0_DRAM_AB_PLD_LVT3_N")
	)
	(segment
		(start 169.05732 -106.698288)
		(end 165.10254 -106.698288)
		(width 0.127)
		(layer "In15.Cu")
		(net "RST_CPU0_DRAM_AB_PLD_LVT3_N")
	)
	(segment
		(start 138.41984 -100.868988)
		(end 137.03808 -102.250748)
		(width 0.127)
		(layer "In15.Cu")
		(net "RST_CPU0_DRAM_AB_PLD_LVT3_N")
	)
	(segment
		(start 142.748 -100.868988)
		(end 138.41984 -100.868988)
		(width 0.127)
		(layer "In15.Cu")
		(net "RST_CPU0_DRAM_AB_PLD_LVT3_N")
	)
	(segment
		(start 119.68988 -106.771948)
		(end 115.82908 -106.771948)
		(width 0.127)
		(layer "In15.Cu")
		(net "RST_CPU0_DRAM_AB_PLD_LVT3_N")
	)
	(segment
		(start 172.155612 -106.175302)
		(end 171.759626 -106.571288)
		(width 0.127)
		(layer "In15.Cu")
		(net "RST_CPU0_DRAM_AB_PLD_LVT3_N")
	)
	(segment
		(start 162.45586 -105.651808)
		(end 162.06724 -105.263188)
		(width 0.127)
		(layer "In15.Cu")
		(net "RST_CPU0_DRAM_AB_PLD_LVT3_N")
	)
	(segment
		(start 120.42648 -102.834948)
		(end 120.42648 -106.035348)
		(width 0.127)
		(layer "In15.Cu")
		(net "RST_CPU0_DRAM_AB_PLD_LVT3_N")
	)
	(segment
		(start 164.05606 -105.651808)
		(end 162.45586 -105.651808)
		(width 0.127)
		(layer "In15.Cu")
		(net "RST_CPU0_DRAM_AB_PLD_LVT3_N")
	)
	(segment
		(start 113.97488 -104.384348)
		(end 112.5982 -104.384348)
		(width 0.127)
		(layer "In15.Cu")
		(net "RST_CPU0_DRAM_AB_PLD_LVT3_N")
	)
	(segment
		(start 162.06724 -105.263188)
		(end 147.1422 -105.263188)
		(width 0.127)
		(layer "In15.Cu")
		(net "RST_CPU0_DRAM_AB_PLD_LVT3_N")
	)
	(segment
		(start 137.03808 -102.250748)
		(end 121.01068 -102.250748)
		(width 0.127)
		(layer "In15.Cu")
		(net "RST_CPU0_DRAM_AB_PLD_LVT3_N")
	)
	(segment
		(start 114.52098 -105.463848)
		(end 114.52098 -104.930448)
		(width 0.127)
		(layer "In15.Cu")
		(net "RST_CPU0_DRAM_AB_PLD_LVT3_N")
	)
	(segment
		(start 171.759626 -106.571288)
		(end 169.18432 -106.571288)
		(width 0.127)
		(layer "In15.Cu")
		(net "RST_CPU0_DRAM_AB_PLD_LVT3_N")
	)
	(segment
		(start 114.52098 -104.930448)
		(end 113.97488 -104.384348)
		(width 0.127)
		(layer "In15.Cu")
		(net "RST_CPU0_DRAM_AB_PLD_LVT3_N")
	)
	(segment
		(start 147.1422 -105.263188)
		(end 142.748 -100.868988)
		(width 0.127)
		(layer "In15.Cu")
		(net "RST_CPU0_DRAM_AB_PLD_LVT3_N")
	)
	(segment
		(start 115.82908 -106.771948)
		(end 114.52098 -105.463848)
		(width 0.127)
		(layer "In15.Cu")
		(net "RST_CPU0_DRAM_AB_PLD_LVT3_N")
	)
	(segment
		(start 120.42648 -106.035348)
		(end 119.68988 -106.771948)
		(width 0.127)
		(layer "In15.Cu")
		(net "RST_CPU0_DRAM_AB_PLD_LVT3_N")
	)
	(segment
		(start 121.01068 -102.250748)
		(end 120.42648 -102.834948)
		(width 0.127)
		(layer "In15.Cu")
		(net "RST_CPU0_DRAM_AB_PLD_LVT3_N")
	)
	(segment
		(start 180.555646 -108.175552)
		(end 180.955696 -107.775502)
		(width 0.12954)
		(layer "F.Cu")
		(net "PWRGD_CPUPWRGD_LVC2_R1")
	)
	(segment
		(start 99.275646 -99.423982)
		(end 99.97186 -99.423982)
		(width 0.12954)
		(layer "F.Cu")
		(net "PWRGD_CPUPWRGD_LVC2_R1")
	)
	(segment
		(start 99.11588 -99.583748)
		(end 99.275646 -99.423982)
		(width 0.12954)
		(layer "F.Cu")
		(net "PWRGD_CPUPWRGD_LVC2_R1")
	)
	(via
		(at 99.11588 -99.583748)
		(size 0.508)
		(drill 0.254)
		(layers "F.Cu" "B.Cu")
		(net "PWRGD_CPUPWRGD_LVC2_R1")
	)
	(via
		(at 180.955696 -107.775502)
		(size 0.4572)
		(drill 0.254)
		(layers "F.Cu" "B.Cu")
		(net "PWRGD_CPUPWRGD_LVC2_R1")
	)
	(segment
		(start 99.11588 -99.583748)
		(end 101.07168 -97.627948)
		(width 0.12954)
		(layer "B.Cu")
		(net "PWRGD_CPUPWRGD_LVC2_R1")
	)
	(segment
		(start 110.21695 -97.627948)
		(end 111.10595 -96.738948)
		(width 0.12954)
		(layer "B.Cu")
		(net "PWRGD_CPUPWRGD_LVC2_R1")
	)
	(segment
		(start 101.07168 -97.627948)
		(end 110.21695 -97.627948)
		(width 0.12954)
		(layer "B.Cu")
		(net "PWRGD_CPUPWRGD_LVC2_R1")
	)
	(segment
		(start 129.43078 -86.705948)
		(end 131.86918 -84.267548)
		(width 0.127)
		(layer "In15.Cu")
		(net "PWRGD_CPUPWRGD_LVC2_R1")
	)
	(segment
		(start 129.43078 -86.937088)
		(end 129.43078 -86.705948)
		(width 0.127)
		(layer "In15.Cu")
		(net "PWRGD_CPUPWRGD_LVC2_R1")
	)
	(segment
		(start 99.11588 -99.583748)
		(end 100.20808 -98.491548)
		(width 0.127)
		(layer "In15.Cu")
		(net "PWRGD_CPUPWRGD_LVC2_R1")
	)
	(segment
		(start 178.113182 -100.88753)
		(end 180.06441 -102.838758)
		(width 0.127)
		(layer "In15.Cu")
		(net "PWRGD_CPUPWRGD_LVC2_R1")
	)
	(segment
		(start 131.86918 -84.267548)
		(end 139.60602 -84.267548)
		(width 0.127)
		(layer "In15.Cu")
		(net "PWRGD_CPUPWRGD_LVC2_R1")
	)
	(segment
		(start 125.40996 -91.918028)
		(end 125.40996 -90.957908)
		(width 0.127)
		(layer "In15.Cu")
		(net "PWRGD_CPUPWRGD_LVC2_R1")
	)
	(segment
		(start 158.623 -98.186748)
		(end 159.26943 -97.540318)
		(width 0.127)
		(layer "In15.Cu")
		(net "PWRGD_CPUPWRGD_LVC2_R1")
	)
	(segment
		(start 178.113182 -99.06)
		(end 178.113182 -100.88753)
		(width 0.127)
		(layer "In15.Cu")
		(net "PWRGD_CPUPWRGD_LVC2_R1")
	)
	(segment
		(start 100.20808 -98.491548)
		(end 100.20808 -92.497148)
		(width 0.127)
		(layer "In15.Cu")
		(net "PWRGD_CPUPWRGD_LVC2_R1")
	)
	(segment
		(start 124.94514 -92.382848)
		(end 125.40996 -91.918028)
		(width 0.127)
		(layer "In15.Cu")
		(net "PWRGD_CPUPWRGD_LVC2_R1")
	)
	(segment
		(start 110.72368 -91.410028)
		(end 111.6965 -92.382848)
		(width 0.127)
		(layer "In15.Cu")
		(net "PWRGD_CPUPWRGD_LVC2_R1")
	)
	(segment
		(start 106.63936 -91.410028)
		(end 110.72368 -91.410028)
		(width 0.127)
		(layer "In15.Cu")
		(net "PWRGD_CPUPWRGD_LVC2_R1")
	)
	(segment
		(start 171.758864 -97.540318)
		(end 171.960794 -97.742248)
		(width 0.127)
		(layer "In15.Cu")
		(net "PWRGD_CPUPWRGD_LVC2_R1")
	)
	(segment
		(start 180.23332 -105.616248)
		(end 180.23332 -107.053126)
		(width 0.127)
		(layer "In15.Cu")
		(net "PWRGD_CPUPWRGD_LVC2_R1")
	)
	(segment
		(start 141.38148 -86.043008)
		(end 141.38148 -88.39454)
		(width 0.127)
		(layer "In15.Cu")
		(net "PWRGD_CPUPWRGD_LVC2_R1")
	)
	(segment
		(start 180.06441 -105.447338)
		(end 180.23332 -105.616248)
		(width 0.127)
		(layer "In15.Cu")
		(net "PWRGD_CPUPWRGD_LVC2_R1")
	)
	(segment
		(start 100.20808 -92.497148)
		(end 101.30028 -91.404948)
		(width 0.127)
		(layer "In15.Cu")
		(net "PWRGD_CPUPWRGD_LVC2_R1")
	)
	(segment
		(start 141.38148 -88.39454)
		(end 151.173688 -98.186748)
		(width 0.127)
		(layer "In15.Cu")
		(net "PWRGD_CPUPWRGD_LVC2_R1")
	)
	(segment
		(start 159.26943 -97.540318)
		(end 171.758864 -97.540318)
		(width 0.127)
		(layer "In15.Cu")
		(net "PWRGD_CPUPWRGD_LVC2_R1")
	)
	(segment
		(start 106.63428 -91.404948)
		(end 106.63936 -91.410028)
		(width 0.127)
		(layer "In15.Cu")
		(net "PWRGD_CPUPWRGD_LVC2_R1")
	)
	(segment
		(start 139.60602 -84.267548)
		(end 141.38148 -86.043008)
		(width 0.127)
		(layer "In15.Cu")
		(net "PWRGD_CPUPWRGD_LVC2_R1")
	)
	(segment
		(start 125.40996 -90.957908)
		(end 129.43078 -86.937088)
		(width 0.127)
		(layer "In15.Cu")
		(net "PWRGD_CPUPWRGD_LVC2_R1")
	)
	(segment
		(start 180.06441 -102.838758)
		(end 180.06441 -105.447338)
		(width 0.127)
		(layer "In15.Cu")
		(net "PWRGD_CPUPWRGD_LVC2_R1")
	)
	(segment
		(start 175.181768 -97.742248)
		(end 175.257968 -97.818448)
		(width 0.127)
		(layer "In15.Cu")
		(net "PWRGD_CPUPWRGD_LVC2_R1")
	)
	(segment
		(start 175.257968 -97.818448)
		(end 176.87163 -97.818448)
		(width 0.127)
		(layer "In15.Cu")
		(net "PWRGD_CPUPWRGD_LVC2_R1")
	)
	(segment
		(start 180.23332 -107.053126)
		(end 180.955696 -107.775502)
		(width 0.127)
		(layer "In15.Cu")
		(net "PWRGD_CPUPWRGD_LVC2_R1")
	)
	(segment
		(start 176.87163 -97.818448)
		(end 178.113182 -99.06)
		(width 0.127)
		(layer "In15.Cu")
		(net "PWRGD_CPUPWRGD_LVC2_R1")
	)
	(segment
		(start 151.173688 -98.186748)
		(end 158.623 -98.186748)
		(width 0.127)
		(layer "In15.Cu")
		(net "PWRGD_CPUPWRGD_LVC2_R1")
	)
	(segment
		(start 171.960794 -97.742248)
		(end 175.181768 -97.742248)
		(width 0.127)
		(layer "In15.Cu")
		(net "PWRGD_CPUPWRGD_LVC2_R1")
	)
	(segment
		(start 111.6965 -92.382848)
		(end 124.94514 -92.382848)
		(width 0.127)
		(layer "In15.Cu")
		(net "PWRGD_CPUPWRGD_LVC2_R1")
	)
	(segment
		(start 101.30028 -91.404948)
		(end 106.63428 -91.404948)
		(width 0.127)
		(layer "In15.Cu")
		(net "PWRGD_CPUPWRGD_LVC2_R1")
	)
	(segment
		(start 112.71758 -94.244668)
		(end 113.0554 -94.244668)
		(width 0.12954)
		(layer "F.Cu")
		(net "PWRGD_CPUPWRGD_LVC2_R")
	)
	(segment
		(start 113.919762 -93.380306)
		(end 113.919762 -92.583762)
		(width 0.12954)
		(layer "F.Cu")
		(net "PWRGD_CPUPWRGD_LVC2_R")
	)
	(segment
		(start 113.0554 -94.244668)
		(end 113.919762 -93.380306)
		(width 0.12954)
		(layer "F.Cu")
		(net "PWRGD_CPUPWRGD_LVC2_R")
	)
	(via
		(at 112.71758 -94.244668)
		(size 0.508)
		(drill 0.254)
		(layers "F.Cu" "B.Cu")
		(net "PWRGD_CPUPWRGD_LVC2_R")
	)
	(segment
		(start 112.71758 -95.902018)
		(end 111.90605 -96.713548)
		(width 0.12954)
		(layer "B.Cu")
		(net "PWRGD_CPUPWRGD_LVC2_R")
	)
	(segment
		(start 112.71758 -94.244668)
		(end 112.71758 -95.902018)
		(width 0.12954)
		(layer "B.Cu")
		(net "PWRGD_CPUPWRGD_LVC2_R")
	)
	(segment
		(start 111.90605 -96.713548)
		(end 111.90605 -96.738948)
		(width 0.12954)
		(layer "B.Cu")
		(net "PWRGD_CPUPWRGD_LVC2_R")
	)
	(segment
		(start 340.901782 -36.220146)
		(end 340.901782 -37.63518)
		(width 0.0889)
		(layer "F.Cu")
		(net "PU_OC2_USB_N")
	)
	(segment
		(start 341.130636 -35.991292)
		(end 340.901782 -36.220146)
		(width 0.0889)
		(layer "F.Cu")
		(net "PU_OC2_USB_N")
	)
	(via
		(at 341.130636 -35.991292)
		(size 0.508)
		(drill 0.254)
		(layers "F.Cu" "B.Cu")
		(net "PU_OC2_USB_N")
	)
	(segment
		(start 343.60231 -35.098228)
		(end 343.8779 -34.822638)
		(width 0.12954)
		(layer "B.Cu")
		(net "PU_OC2_USB_N")
	)
	(segment
		(start 341.130636 -35.991292)
		(end 342.0237 -35.098228)
		(width 0.12954)
		(layer "B.Cu")
		(net "PU_OC2_USB_N")
	)
	(segment
		(start 342.0237 -35.098228)
		(end 343.60231 -35.098228)
		(width 0.12954)
		(layer "B.Cu")
		(net "PU_OC2_USB_N")
	)
	(segment
		(start 117.53088 -101.393498)
		(end 118.745 -101.393498)
		(width 0.12954)
		(layer "F.Cu")
		(net "PD_CPU0_ERRS_DIR")
	)
	(segment
		(start 118.745 -101.393498)
		(end 118.745 -100.315522)
		(width 0.12954)
		(layer "F.Cu")
		(net "PD_CPU0_ERRS_DIR")
	)
	(segment
		(start 118.745 -100.315522)
		(end 117.169692 -98.740214)
		(width 0.12954)
		(layer "F.Cu")
		(net "PD_CPU0_ERRS_DIR")
	)
	(segment
		(start 117.169692 -98.740214)
		(end 117.169692 -98.425762)
		(width 0.12954)
		(layer "F.Cu")
		(net "PD_CPU0_ERRS_DIR")
	)
	(via
		(at 118.745 -101.393498)
		(size 0.762)
		(drill 0.381)
		(layers "F.Cu" "B.Cu")
		(net "PD_CPU0_ERRS_DIR")
	)
	(segment
		(start 126.083314 -116.751608)
		(end 125.919738 -116.588032)
		(width 0.12954)
		(layer "F.Cu")
		(net "PD_GTL2014_BMC_JTAG_DIR_1")
	)
	(segment
		(start 127.804926 -119.410734)
		(end 127.804926 -118.032784)
		(width 0.12954)
		(layer "F.Cu")
		(net "PD_GTL2014_BMC_JTAG_DIR_1")
	)
	(segment
		(start 127.804926 -118.032784)
		(end 126.52375 -116.751608)
		(width 0.12954)
		(layer "F.Cu")
		(net "PD_GTL2014_BMC_JTAG_DIR_1")
	)
	(segment
		(start 126.52375 -116.751608)
		(end 126.083314 -116.751608)
		(width 0.12954)
		(layer "F.Cu")
		(net "PD_GTL2014_BMC_JTAG_DIR_1")
	)
	(segment
		(start 125.919738 -116.588032)
		(end 125.919738 -116.042948)
		(width 0.12954)
		(layer "F.Cu")
		(net "PD_GTL2014_BMC_JTAG_DIR_1")
	)
	(via
		(at 127.804926 -118.032784)
		(size 0.762)
		(drill 0.381)
		(layers "F.Cu" "B.Cu")
		(net "PD_GTL2014_BMC_JTAG_DIR_1")
	)
	(segment
		(start 116.841016 -116.948458)
		(end 116.610892 -116.718334)
		(width 0.12954)
		(layer "F.Cu")
		(net "PD_GTL2014_BMC_JTAG_DIR_0")
	)
	(segment
		(start 118.49608 -118.068598)
		(end 118.49608 -119.446548)
		(width 0.12954)
		(layer "F.Cu")
		(net "PD_GTL2014_BMC_JTAG_DIR_0")
	)
	(segment
		(start 118.49608 -118.068598)
		(end 117.37594 -116.948458)
		(width 0.12954)
		(layer "F.Cu")
		(net "PD_GTL2014_BMC_JTAG_DIR_0")
	)
	(segment
		(start 116.610892 -116.718334)
		(end 116.610892 -116.078762)
		(width 0.12954)
		(layer "F.Cu")
		(net "PD_GTL2014_BMC_JTAG_DIR_0")
	)
	(segment
		(start 117.37594 -116.948458)
		(end 116.841016 -116.948458)
		(width 0.12954)
		(layer "F.Cu")
		(net "PD_GTL2014_BMC_JTAG_DIR_0")
	)
	(via
		(at 118.49608 -118.068598)
		(size 0.762)
		(drill 0.381)
		(layers "F.Cu" "B.Cu")
		(net "PD_GTL2014_BMC_JTAG_DIR_0")
	)
	(segment
		(start 220.374972 -73.484994)
		(end 220.363034 -73.496932)
		(width 0.12954)
		(layer "F.Cu")
		(net "P3V3_E1S_VCC_0")
	)
	(segment
		(start 220.612208 -72.526398)
		(end 220.821504 -72.317102)
		(width 0.12954)
		(layer "F.Cu")
		(net "P3V3_E1S_VCC_0")
	)
	(segment
		(start 220.374972 -72.763634)
		(end 220.612208 -72.526398)
		(width 0.12954)
		(layer "F.Cu")
		(net "P3V3_E1S_VCC_0")
	)
	(segment
		(start 220.821504 -72.317102)
		(end 220.821504 -71.62038)
		(width 0.12954)
		(layer "F.Cu")
		(net "P3V3_E1S_VCC_0")
	)
	(segment
		(start 220.374972 -73.484994)
		(end 220.374972 -72.763634)
		(width 0.12954)
		(layer "F.Cu")
		(net "P3V3_E1S_VCC_0")
	)
	(segment
		(start 220.363034 -73.496932)
		(end 220.363034 -74.62774)
		(width 0.12954)
		(layer "F.Cu")
		(net "P3V3_E1S_VCC_0")
	)
	(via
		(at 220.612208 -72.526398)
		(size 0.508)
		(drill 0.254)
		(layers "F.Cu" "B.Cu")
		(net "P3V3_E1S_VCC_0")
	)
	(segment
		(start 292.278816 -58.459878)
		(end 291.266118 -58.459878)
		(width 0.12954)
		(layer "F.Cu")
		(net "P3V3_E1S_UV_0_R")
	)
	(segment
		(start 291.266118 -58.459878)
		(end 291.25418 -58.44794)
		(width 0.12954)
		(layer "F.Cu")
		(net "P3V3_E1S_UV_0_R")
	)
	(via
		(at 287.792414 -49.310798)
		(size 0.508)
		(drill 0.254)
		(layers "F.Cu" "B.Cu")
		(net "P3V3_E1S_UV_0_R")
	)
	(via
		(at 220.278198 -69.42455)
		(size 0.508)
		(drill 0.254)
		(layers "F.Cu" "B.Cu")
		(net "P3V3_E1S_UV_0_R")
	)
	(via
		(at 291.25418 -58.44794)
		(size 0.508)
		(drill 0.254)
		(layers "F.Cu" "B.Cu")
		(net "P3V3_E1S_UV_0_R")
	)
	(segment
		(start 218.910408 -68.854828)
		(end 219.708476 -68.854828)
		(width 0.12954)
		(layer "B.Cu")
		(net "P3V3_E1S_UV_0_R")
	)
	(segment
		(start 218.43746 -68.38188)
		(end 218.910408 -68.854828)
		(width 0.12954)
		(layer "B.Cu")
		(net "P3V3_E1S_UV_0_R")
	)
	(segment
		(start 219.708476 -68.854828)
		(end 220.278198 -69.42455)
		(width 0.12954)
		(layer "B.Cu")
		(net "P3V3_E1S_UV_0_R")
	)
	(segment
		(start 291.25418 -58.44794)
		(end 291.25418 -57.08142)
		(width 0.127)
		(layer "In2.Cu")
		(net "P3V3_E1S_UV_0_R")
	)
	(segment
		(start 290.7411 -56.56834)
		(end 290.7411 -51.257708)
		(width 0.127)
		(layer "In2.Cu")
		(net "P3V3_E1S_UV_0_R")
	)
	(segment
		(start 290.7411 -51.257708)
		(end 288.79419 -49.310798)
		(width 0.127)
		(layer "In2.Cu")
		(net "P3V3_E1S_UV_0_R")
	)
	(segment
		(start 291.25418 -57.08142)
		(end 290.7411 -56.56834)
		(width 0.127)
		(layer "In2.Cu")
		(net "P3V3_E1S_UV_0_R")
	)
	(segment
		(start 288.79419 -49.310798)
		(end 287.792414 -49.310798)
		(width 0.127)
		(layer "In2.Cu")
		(net "P3V3_E1S_UV_0_R")
	)
	(segment
		(start 222.441262 -69.0626)
		(end 221.751906 -69.0626)
		(width 0.127)
		(layer "In13.Cu")
		(net "P3V3_E1S_UV_0_R")
	)
	(segment
		(start 249.04065 -66.60896)
		(end 247.642126 -68.007484)
		(width 0.127)
		(layer "In13.Cu")
		(net "P3V3_E1S_UV_0_R")
	)
	(segment
		(start 222.875094 -68.628768)
		(end 222.441262 -69.0626)
		(width 0.127)
		(layer "In13.Cu")
		(net "P3V3_E1S_UV_0_R")
	)
	(segment
		(start 287.792414 -50.265584)
		(end 276.2758 -61.782198)
		(width 0.127)
		(layer "In13.Cu")
		(net "P3V3_E1S_UV_0_R")
	)
	(segment
		(start 221.751906 -69.0626)
		(end 221.668594 -69.145912)
		(width 0.127)
		(layer "In13.Cu")
		(net "P3V3_E1S_UV_0_R")
	)
	(segment
		(start 268.393672 -63.249048)
		(end 265.932666 -63.249048)
		(width 0.127)
		(layer "In13.Cu")
		(net "P3V3_E1S_UV_0_R")
	)
	(segment
		(start 247.642126 -68.007484)
		(end 223.024192 -68.007484)
		(width 0.127)
		(layer "In13.Cu")
		(net "P3V3_E1S_UV_0_R")
	)
	(segment
		(start 276.2758 -61.782198)
		(end 272.283682 -61.782198)
		(width 0.127)
		(layer "In13.Cu")
		(net "P3V3_E1S_UV_0_R")
	)
	(segment
		(start 220.556836 -69.145912)
		(end 220.278198 -69.42455)
		(width 0.127)
		(layer "In13.Cu")
		(net "P3V3_E1S_UV_0_R")
	)
	(segment
		(start 287.792414 -49.310798)
		(end 287.792414 -50.265584)
		(width 0.127)
		(layer "In13.Cu")
		(net "P3V3_E1S_UV_0_R")
	)
	(segment
		(start 222.875094 -68.156582)
		(end 222.875094 -68.628768)
		(width 0.127)
		(layer "In13.Cu")
		(net "P3V3_E1S_UV_0_R")
	)
	(segment
		(start 221.668594 -69.145912)
		(end 220.556836 -69.145912)
		(width 0.127)
		(layer "In13.Cu")
		(net "P3V3_E1S_UV_0_R")
	)
	(segment
		(start 269.063978 -63.115698)
		(end 268.393672 -63.249048)
		(width 0.127)
		(layer "In13.Cu")
		(net "P3V3_E1S_UV_0_R")
	)
	(segment
		(start 272.283682 -61.782198)
		(end 269.063978 -63.115698)
		(width 0.127)
		(layer "In13.Cu")
		(net "P3V3_E1S_UV_0_R")
	)
	(segment
		(start 265.932666 -63.249048)
		(end 249.04065 -66.60896)
		(width 0.127)
		(layer "In13.Cu")
		(net "P3V3_E1S_UV_0_R")
	)
	(segment
		(start 223.024192 -68.007484)
		(end 222.875094 -68.156582)
		(width 0.127)
		(layer "In13.Cu")
		(net "P3V3_E1S_UV_0_R")
	)
	(segment
		(start 220.180154 -68.354194)
		(end 220.3958 -68.138548)
		(width 0.12954)
		(layer "F.Cu")
		(net "P3V3_E1S_UV_0")
	)
	(segment
		(start 220.839538 -68.582286)
		(end 220.839538 -70.102222)
		(width 0.12954)
		(layer "F.Cu")
		(net "P3V3_E1S_UV_0")
	)
	(segment
		(start 219.276676 -68.354194)
		(end 220.180154 -68.354194)
		(width 0.12954)
		(layer "F.Cu")
		(net "P3V3_E1S_UV_0")
	)
	(segment
		(start 220.839538 -70.102222)
		(end 220.821504 -70.120256)
		(width 0.12954)
		(layer "F.Cu")
		(net "P3V3_E1S_UV_0")
	)
	(segment
		(start 219.26296 -68.340478)
		(end 219.276676 -68.354194)
		(width 0.12954)
		(layer "F.Cu")
		(net "P3V3_E1S_UV_0")
	)
	(segment
		(start 218.282012 -68.340478)
		(end 219.26296 -68.340478)
		(width 0.12954)
		(layer "F.Cu")
		(net "P3V3_E1S_UV_0")
	)
	(segment
		(start 220.3958 -68.138548)
		(end 220.839538 -68.582286)
		(width 0.12954)
		(layer "F.Cu")
		(net "P3V3_E1S_UV_0")
	)
	(via
		(at 220.3958 -68.138548)
		(size 0.508)
		(drill 0.254)
		(layers "F.Cu" "B.Cu")
		(net "P3V3_E1S_UV_0")
	)
	(segment
		(start 220.3958 -68.138548)
		(end 220.180154 -68.354194)
		(width 0.12954)
		(layer "B.Cu")
		(net "P3V3_E1S_UV_0")
	)
	(segment
		(start 220.180154 -68.354194)
		(end 219.265246 -68.354194)
		(width 0.12954)
		(layer "B.Cu")
		(net "P3V3_E1S_UV_0")
	)
	(segment
		(start 219.265246 -68.354194)
		(end 219.23756 -68.38188)
		(width 0.12954)
		(layer "B.Cu")
		(net "P3V3_E1S_UV_0")
	)
	(segment
		(start 218.371166 -72.54367)
		(end 218.411552 -72.446388)
		(width 0.12954)
		(layer "F.Cu")
		(net "P3V3_E1S_SENSE_0")
	)
	(segment
		(start 218.411552 -72.015858)
		(end 219.9259 -72.015858)
		(width 0.12954)
		(layer "F.Cu")
		(net "P3V3_E1S_SENSE_0")
	)
	(segment
		(start 218.157298 -72.757538)
		(end 218.371166 -72.54367)
		(width 0.12954)
		(layer "F.Cu")
		(net "P3V3_E1S_SENSE_0")
	)
	(segment
		(start 217.485722 -72.757538)
		(end 218.157298 -72.757538)
		(width 0.12954)
		(layer "F.Cu")
		(net "P3V3_E1S_SENSE_0")
	)
	(segment
		(start 218.411552 -72.446388)
		(end 218.411552 -72.015858)
		(width 0.12954)
		(layer "F.Cu")
		(net "P3V3_E1S_SENSE_0")
	)
	(segment
		(start 219.9259 -72.015858)
		(end 220.321378 -71.62038)
		(width 0.12954)
		(layer "F.Cu")
		(net "P3V3_E1S_SENSE_0")
	)
	(via
		(at 217.485722 -72.757538)
		(size 0.508)
		(drill 0.254)
		(layers "F.Cu" "B.Cu")
		(net "P3V3_E1S_SENSE_0")
	)
	(segment
		(start 218.91371 -69.52742)
		(end 219.662502 -69.52742)
		(width 0.12954)
		(layer "F.Cu")
		(net "P3V3_E1S_REG_0")
	)
	(segment
		(start 220.255338 -70.120256)
		(end 220.321378 -70.120256)
		(width 0.12954)
		(layer "F.Cu")
		(net "P3V3_E1S_REG_0")
	)
	(segment
		(start 218.419934 -69.52742)
		(end 218.91371 -69.52742)
		(width 0.12954)
		(layer "F.Cu")
		(net "P3V3_E1S_REG_0")
	)
	(segment
		(start 219.662502 -69.52742)
		(end 220.255338 -70.120256)
		(width 0.12954)
		(layer "F.Cu")
		(net "P3V3_E1S_REG_0")
	)
	(segment
		(start 218.289632 -69.397118)
		(end 218.419934 -69.52742)
		(width 0.12954)
		(layer "F.Cu")
		(net "P3V3_E1S_REG_0")
	)
	(via
		(at 218.91371 -69.52742)
		(size 0.508)
		(drill 0.254)
		(layers "F.Cu" "B.Cu")
		(net "P3V3_E1S_REG_0")
	)
	(segment
		(start 223.321626 -68.674488)
		(end 223.415098 -68.581016)
		(width 0.12954)
		(layer "F.Cu")
		(net "P3V3_E1S_PWRGD_0")
	)
	(segment
		(start 223.321626 -70.120256)
		(end 223.321626 -68.674488)
		(width 0.12954)
		(layer "F.Cu")
		(net "P3V3_E1S_PWRGD_0")
	)
	(segment
		(start 223.415098 -68.581016)
		(end 223.712024 -68.581016)
		(width 0.12954)
		(layer "F.Cu")
		(net "P3V3_E1S_PWRGD_0")
	)
	(segment
		(start 223.712024 -68.581016)
		(end 224.371662 -67.921378)
		(width 0.12954)
		(layer "F.Cu")
		(net "P3V3_E1S_PWRGD_0")
	)
	(via
		(at 223.415098 -68.581016)
		(size 0.508)
		(drill 0.254)
		(layers "F.Cu" "B.Cu")
		(net "P3V3_E1S_PWRGD_0")
	)
	(segment
		(start 219.771722 -67.554094)
		(end 219.276676 -67.554094)
		(width 0.12954)
		(layer "F.Cu")
		(net "P3V3_E1S_OV_0")
	)
	(segment
		(start 220.47708 -67.114928)
		(end 220.037914 -67.554094)
		(width 0.12954)
		(layer "F.Cu")
		(net "P3V3_E1S_OV_0")
	)
	(segment
		(start 218.511628 -67.554094)
		(end 218.282012 -67.324478)
		(width 0.12954)
		(layer "F.Cu")
		(net "P3V3_E1S_OV_0")
	)
	(segment
		(start 221.32163 -70.120256)
		(end 221.32163 -68.276724)
		(width 0.12954)
		(layer "F.Cu")
		(net "P3V3_E1S_OV_0")
	)
	(segment
		(start 220.037914 -67.554094)
		(end 219.771722 -67.554094)
		(width 0.12954)
		(layer "F.Cu")
		(net "P3V3_E1S_OV_0")
	)
	(segment
		(start 221.32163 -67.959478)
		(end 220.47708 -67.114928)
		(width 0.12954)
		(layer "F.Cu")
		(net "P3V3_E1S_OV_0")
	)
	(segment
		(start 219.276676 -67.554094)
		(end 218.511628 -67.554094)
		(width 0.12954)
		(layer "F.Cu")
		(net "P3V3_E1S_OV_0")
	)
	(segment
		(start 221.32163 -68.276724)
		(end 221.32163 -67.959478)
		(width 0.12954)
		(layer "F.Cu")
		(net "P3V3_E1S_OV_0")
	)
	(via
		(at 220.47708 -67.114928)
		(size 0.762)
		(drill 0.381)
		(layers "F.Cu" "B.Cu")
		(net "P3V3_E1S_OV_0")
	)
	(segment
		(start 191.55664 -67.391788)
		(end 190.81369 -67.391788)
		(width 0.12954)
		(layer "F.Cu")
		(net "P3V3_E1S_MODE_0")
	)
	(segment
		(start 193.088768 -68.923916)
		(end 192.06464 -67.899788)
		(width 0.12954)
		(layer "F.Cu")
		(net "P3V3_E1S_MODE_0")
	)
	(segment
		(start 192.06464 -67.899788)
		(end 191.55664 -67.391788)
		(width 0.12954)
		(layer "F.Cu")
		(net "P3V3_E1S_MODE_0")
	)
	(segment
		(start 193.350642 -68.923916)
		(end 193.088768 -68.923916)
		(width 0.12954)
		(layer "F.Cu")
		(net "P3V3_E1S_MODE_0")
	)
	(segment
		(start 190.81369 -68.407788)
		(end 190.81369 -67.391788)
		(width 0.12954)
		(layer "F.Cu")
		(net "P3V3_E1S_MODE_0")
	)
	(via
		(at 192.06464 -67.899788)
		(size 0.762)
		(drill 0.381)
		(layers "F.Cu" "B.Cu")
		(net "P3V3_E1S_MODE_0")
	)
	(segment
		(start 192.01384 -69.677788)
		(end 192.26784 -69.423788)
		(width 0.12954)
		(layer "F.Cu")
		(net "P3V3_E1S_ILIMIT_0")
	)
	(segment
		(start 190.81369 -70.185788)
		(end 191.50584 -70.185788)
		(width 0.12954)
		(layer "F.Cu")
		(net "P3V3_E1S_ILIMIT_0")
	)
	(segment
		(start 192.26784 -69.423788)
		(end 193.350642 -69.423788)
		(width 0.12954)
		(layer "F.Cu")
		(net "P3V3_E1S_ILIMIT_0")
	)
	(segment
		(start 191.50584 -70.185788)
		(end 192.01384 -69.677788)
		(width 0.12954)
		(layer "F.Cu")
		(net "P3V3_E1S_ILIMIT_0")
	)
	(via
		(at 192.01384 -69.677788)
		(size 0.762)
		(drill 0.381)
		(layers "F.Cu" "B.Cu")
		(net "P3V3_E1S_ILIMIT_0")
	)
	(segment
		(start 222.97136 -73.517506)
		(end 222.8215 -73.367646)
		(width 0.12954)
		(layer "F.Cu")
		(net "P3V3_E1S_GATE_0")
	)
	(segment
		(start 222.839788 -75.196954)
		(end 222.978472 -75.05827)
		(width 0.12954)
		(layer "F.Cu")
		(net "P3V3_E1S_GATE_0")
	)
	(segment
		(start 222.8215 -73.367646)
		(end 222.8215 -71.62038)
		(width 0.12954)
		(layer "F.Cu")
		(net "P3V3_E1S_GATE_0")
	)
	(segment
		(start 222.984314 -75.86091)
		(end 222.984314 -75.34148)
		(width 0.12954)
		(layer "F.Cu")
		(net "P3V3_E1S_GATE_0")
	)
	(segment
		(start 222.97136 -73.517506)
		(end 222.978472 -73.524618)
		(width 0.12954)
		(layer "F.Cu")
		(net "P3V3_E1S_GATE_0")
	)
	(segment
		(start 222.978472 -73.524618)
		(end 222.978472 -74.510138)
		(width 0.12954)
		(layer "F.Cu")
		(net "P3V3_E1S_GATE_0")
	)
	(segment
		(start 222.978472 -75.05827)
		(end 222.978472 -74.510138)
		(width 0.12954)
		(layer "F.Cu")
		(net "P3V3_E1S_GATE_0")
	)
	(segment
		(start 222.984314 -75.34148)
		(end 222.839788 -75.196954)
		(width 0.12954)
		(layer "F.Cu")
		(net "P3V3_E1S_GATE_0")
	)
	(via
		(at 222.839788 -75.196954)
		(size 0.508)
		(drill 0.254)
		(layers "F.Cu" "B.Cu")
		(net "P3V3_E1S_GATE_0")
	)
	(segment
		(start 224.512886 -71.592948)
		(end 225.171762 -71.592948)
		(width 0.12954)
		(layer "F.Cu")
		(net "P3V3_E1S_FAULT_0")
	)
	(segment
		(start 223.321626 -70.620382)
		(end 223.54032 -70.620382)
		(width 0.12954)
		(layer "F.Cu")
		(net "P3V3_E1S_FAULT_0")
	)
	(segment
		(start 223.54032 -70.620382)
		(end 224.512886 -71.592948)
		(width 0.12954)
		(layer "F.Cu")
		(net "P3V3_E1S_FAULT_0")
	)
	(via
		(at 224.512886 -71.592948)
		(size 0.508)
		(drill 0.254)
		(layers "F.Cu" "B.Cu")
		(net "P3V3_E1S_FAULT_0")
	)
	(segment
		(start 197.88759 -69.931788)
		(end 198.01459 -69.804788)
		(width 0.12954)
		(layer "F.Cu")
		(net "P3V3_E1S_EN_0_R2")
	)
	(segment
		(start 195.350638 -69.423788)
		(end 195.747894 -69.423788)
		(width 0.12954)
		(layer "F.Cu")
		(net "P3V3_E1S_EN_0_R2")
	)
	(segment
		(start 196.76364 -69.931788)
		(end 197.88759 -69.931788)
		(width 0.12954)
		(layer "F.Cu")
		(net "P3V3_E1S_EN_0_R2")
	)
	(segment
		(start 195.747894 -69.423788)
		(end 196.255894 -69.931788)
		(width 0.12954)
		(layer "F.Cu")
		(net "P3V3_E1S_EN_0_R2")
	)
	(segment
		(start 196.255894 -69.931788)
		(end 196.76364 -69.931788)
		(width 0.12954)
		(layer "F.Cu")
		(net "P3V3_E1S_EN_0_R2")
	)
	(via
		(at 196.76364 -69.931788)
		(size 0.762)
		(drill 0.381)
		(layers "F.Cu" "B.Cu")
		(net "P3V3_E1S_EN_0_R2")
	)
	(segment
		(start 196.76364 -71.831708)
		(end 196.76364 -71.862188)
		(width 0.12954)
		(layer "F.Cu")
		(net "P3V3_E1S_DVDT_0")
	)
	(segment
		(start 195.592192 -69.92366)
		(end 196.00164 -70.333108)
		(width 0.12954)
		(layer "F.Cu")
		(net "P3V3_E1S_DVDT_0")
	)
	(segment
		(start 196.76364 -71.862188)
		(end 197.73519 -71.862188)
		(width 0.12954)
		(layer "F.Cu")
		(net "P3V3_E1S_DVDT_0")
	)
	(segment
		(start 196.00164 -71.069708)
		(end 196.76364 -71.831708)
		(width 0.12954)
		(layer "F.Cu")
		(net "P3V3_E1S_DVDT_0")
	)
	(segment
		(start 196.00164 -70.333108)
		(end 196.00164 -71.069708)
		(width 0.12954)
		(layer "F.Cu")
		(net "P3V3_E1S_DVDT_0")
	)
	(segment
		(start 195.350638 -69.92366)
		(end 195.592192 -69.92366)
		(width 0.12954)
		(layer "F.Cu")
		(net "P3V3_E1S_DVDT_0")
	)
	(segment
		(start 197.73519 -71.862188)
		(end 198.01459 -71.582788)
		(width 0.12954)
		(layer "F.Cu")
		(net "P3V3_E1S_DVDT_0")
	)
	(via
		(at 196.76364 -71.862188)
		(size 0.762)
		(drill 0.381)
		(layers "F.Cu" "B.Cu")
		(net "P3V3_E1S_DVDT_0")
	)
	(segment
		(start 219.60586 -71.126858)
		(end 220.314774 -71.126858)
		(width 0.12954)
		(layer "F.Cu")
		(net "P3V3_E1S_CB_0")
	)
	(segment
		(start 219.391738 -71.34098)
		(end 219.177616 -71.126858)
		(width 0.12954)
		(layer "F.Cu")
		(net "P3V3_E1S_CB_0")
	)
	(segment
		(start 218.411552 -71.126858)
		(end 219.177616 -71.126858)
		(width 0.12954)
		(layer "F.Cu")
		(net "P3V3_E1S_CB_0")
	)
	(segment
		(start 219.60586 -71.126858)
		(end 219.391738 -71.34098)
		(width 0.12954)
		(layer "F.Cu")
		(net "P3V3_E1S_CB_0")
	)
	(segment
		(start 220.314774 -71.126858)
		(end 220.321378 -71.120254)
		(width 0.12954)
		(layer "F.Cu")
		(net "P3V3_E1S_CB_0")
	)
	(via
		(at 219.391738 -71.34098)
		(size 0.508)
		(drill 0.254)
		(layers "F.Cu" "B.Cu")
		(net "P3V3_E1S_CB_0")
	)
	(segment
		(start 188.292232 -28.258008)
		(end 188.292232 -27.620468)
		(width 0.12954)
		(layer "F.Cu")
		(net "P12V_SCM_VCC")
	)
	(segment
		(start 188.292232 -28.258008)
		(end 188.292232 -29.348684)
		(width 0.12954)
		(layer "F.Cu")
		(net "P12V_SCM_VCC")
	)
	(segment
		(start 188.292232 -27.620468)
		(end 188.292232 -27.529536)
		(width 0.12954)
		(layer "F.Cu")
		(net "P12V_SCM_VCC")
	)
	(segment
		(start 188.292232 -27.529536)
		(end 188.738764 -27.083004)
		(width 0.12954)
		(layer "F.Cu")
		(net "P12V_SCM_VCC")
	)
	(segment
		(start 188.738764 -27.083004)
		(end 188.738764 -26.393394)
		(width 0.12954)
		(layer "F.Cu")
		(net "P12V_SCM_VCC")
	)
	(segment
		(start 188.292232 -29.348684)
		(end 188.28258 -29.358336)
		(width 0.12954)
		(layer "F.Cu")
		(net "P12V_SCM_VCC")
	)
	(via
		(at 188.292232 -27.620468)
		(size 0.508)
		(drill 0.254)
		(layers "F.Cu" "B.Cu")
		(net "P12V_SCM_VCC")
	)
	(segment
		(start 194.142868 -41.169336)
		(end 194.44208 -41.468548)
		(width 0.12954)
		(layer "F.Cu")
		(net "P12V_SCM_UV_R")
	)
	(segment
		(start 194.44208 -43.678348)
		(end 194.613276 -43.849544)
		(width 0.12954)
		(layer "F.Cu")
		(net "P12V_SCM_UV_R")
	)
	(segment
		(start 193.813684 -40.840152)
		(end 194.142868 -41.169336)
		(width 0.12954)
		(layer "F.Cu")
		(net "P12V_SCM_UV_R")
	)
	(segment
		(start 194.44208 -41.468548)
		(end 194.44208 -43.678348)
		(width 0.12954)
		(layer "F.Cu")
		(net "P12V_SCM_UV_R")
	)
	(segment
		(start 185.37174 -40.840152)
		(end 193.813684 -40.840152)
		(width 0.12954)
		(layer "F.Cu")
		(net "P12V_SCM_UV_R")
	)
	(segment
		(start 184.583832 -40.840152)
		(end 185.37174 -40.840152)
		(width 0.12954)
		(layer "F.Cu")
		(net "P12V_SCM_UV_R")
	)
	(segment
		(start 194.613276 -43.849544)
		(end 195.25615 -43.849544)
		(width 0.12954)
		(layer "F.Cu")
		(net "P12V_SCM_UV_R")
	)
	(via
		(at 194.142868 -41.169336)
		(size 0.762)
		(drill 0.381)
		(layers "F.Cu" "B.Cu")
		(net "P12V_SCM_UV_R")
	)
	(segment
		(start 186.199272 -23.113492)
		(end 187.207906 -23.113492)
		(width 0.12954)
		(layer "F.Cu")
		(net "P12V_SCM_UV")
	)
	(segment
		(start 187.207906 -23.113492)
		(end 187.221622 -23.127208)
		(width 0.12954)
		(layer "F.Cu")
		(net "P12V_SCM_UV")
	)
	(segment
		(start 187.915042 -23.127208)
		(end 188.738764 -23.95093)
		(width 0.12954)
		(layer "F.Cu")
		(net "P12V_SCM_UV")
	)
	(segment
		(start 188.738764 -23.95093)
		(end 188.738764 -24.89327)
		(width 0.12954)
		(layer "F.Cu")
		(net "P12V_SCM_UV")
	)
	(segment
		(start 187.221622 -23.127208)
		(end 187.915042 -23.127208)
		(width 0.12954)
		(layer "F.Cu")
		(net "P12V_SCM_UV")
	)
	(segment
		(start 183.783732 -40.840152)
		(end 183.040782 -40.840152)
		(width 0.12954)
		(layer "F.Cu")
		(net "P12V_SCM_UV")
	)
	(via
		(at 183.040782 -40.840152)
		(size 0.508)
		(drill 0.254)
		(layers "F.Cu" "B.Cu")
		(net "P12V_SCM_UV")
	)
	(via
		(at 187.915042 -23.127208)
		(size 0.508)
		(drill 0.254)
		(layers "F.Cu" "B.Cu")
		(net "P12V_SCM_UV")
	)
	(segment
		(start 184.3786 -34.120328)
		(end 183.040782 -35.458146)
		(width 0.127)
		(layer "In11.Cu")
		(net "P12V_SCM_UV")
	)
	(segment
		(start 188.20892 -23.421086)
		(end 188.20892 -25.479248)
		(width 0.127)
		(layer "In11.Cu")
		(net "P12V_SCM_UV")
	)
	(segment
		(start 187.915042 -23.127208)
		(end 188.20892 -23.421086)
		(width 0.127)
		(layer "In11.Cu")
		(net "P12V_SCM_UV")
	)
	(segment
		(start 184.3786 -29.309568)
		(end 184.3786 -34.120328)
		(width 0.127)
		(layer "In11.Cu")
		(net "P12V_SCM_UV")
	)
	(segment
		(start 183.040782 -35.458146)
		(end 183.040782 -40.840152)
		(width 0.127)
		(layer "In11.Cu")
		(net "P12V_SCM_UV")
	)
	(segment
		(start 188.20892 -25.479248)
		(end 184.3786 -29.309568)
		(width 0.127)
		(layer "In11.Cu")
		(net "P12V_SCM_UV")
	)
	(segment
		(start 179.356766 -32.535622)
		(end 179.580032 -32.312356)
		(width 0.12954)
		(layer "F.Cu")
		(net "P12V_SCM_TIMER")
	)
	(segment
		(start 179.058062 -32.535622)
		(end 179.356766 -32.535622)
		(width 0.12954)
		(layer "F.Cu")
		(net "P12V_SCM_TIMER")
	)
	(segment
		(start 179.580032 -31.954216)
		(end 179.309014 -31.683198)
		(width 0.12954)
		(layer "F.Cu")
		(net "P12V_SCM_TIMER")
	)
	(segment
		(start 179.309014 -31.683198)
		(end 178.507644 -31.683198)
		(width 0.12954)
		(layer "F.Cu")
		(net "P12V_SCM_TIMER")
	)
	(segment
		(start 178.193954 -31.369508)
		(end 178.193954 -30.33776)
		(width 0.12954)
		(layer "F.Cu")
		(net "P12V_SCM_TIMER")
	)
	(segment
		(start 179.580032 -32.312356)
		(end 179.580032 -31.954216)
		(width 0.12954)
		(layer "F.Cu")
		(net "P12V_SCM_TIMER")
	)
	(segment
		(start 178.507644 -31.683198)
		(end 178.193954 -31.369508)
		(width 0.12954)
		(layer "F.Cu")
		(net "P12V_SCM_TIMER")
	)
	(via
		(at 179.580032 -31.954216)
		(size 0.508)
		(drill 0.254)
		(layers "F.Cu" "B.Cu")
		(net "P12V_SCM_TIMER")
	)
	(segment
		(start 177.19421 -31.419038)
		(end 177.19421 -30.33776)
		(width 0.12954)
		(layer "F.Cu")
		(net "P12V_SCM_SS")
	)
	(segment
		(start 176.391062 -32.535622)
		(end 177.19421 -31.732474)
		(width 0.12954)
		(layer "F.Cu")
		(net "P12V_SCM_SS")
	)
	(segment
		(start 177.19421 -31.732474)
		(end 177.19421 -31.419038)
		(width 0.12954)
		(layer "F.Cu")
		(net "P12V_SCM_SS")
	)
	(via
		(at 177.19421 -31.419038)
		(size 0.508)
		(drill 0.254)
		(layers "F.Cu" "B.Cu")
		(net "P12V_SCM_SS")
	)
	(segment
		(start 185.402982 -27.530552)
		(end 186.074558 -27.530552)
		(width 0.12954)
		(layer "F.Cu")
		(net "P12V_SCM_SENSE")
	)
	(segment
		(start 186.328812 -27.276298)
		(end 186.328812 -26.788872)
		(width 0.12954)
		(layer "F.Cu")
		(net "P12V_SCM_SENSE")
	)
	(segment
		(start 186.328812 -26.788872)
		(end 187.84316 -26.788872)
		(width 0.12954)
		(layer "F.Cu")
		(net "P12V_SCM_SENSE")
	)
	(segment
		(start 187.84316 -26.788872)
		(end 188.238638 -26.393394)
		(width 0.12954)
		(layer "F.Cu")
		(net "P12V_SCM_SENSE")
	)
	(segment
		(start 186.074558 -27.530552)
		(end 186.328812 -27.276298)
		(width 0.12954)
		(layer "F.Cu")
		(net "P12V_SCM_SENSE")
	)
	(via
		(at 185.402982 -27.530552)
		(size 0.508)
		(drill 0.254)
		(layers "F.Cu" "B.Cu")
		(net "P12V_SCM_SENSE")
	)
	(segment
		(start 187.47232 -24.126952)
		(end 186.88558 -24.126952)
		(width 0.12954)
		(layer "F.Cu")
		(net "P12V_SCM_REG")
	)
	(segment
		(start 186.250072 -24.126952)
		(end 186.206892 -24.170132)
		(width 0.12954)
		(layer "F.Cu")
		(net "P12V_SCM_REG")
	)
	(segment
		(start 186.88558 -24.126952)
		(end 186.250072 -24.126952)
		(width 0.12954)
		(layer "F.Cu")
		(net "P12V_SCM_REG")
	)
	(segment
		(start 188.238638 -24.89327)
		(end 187.47232 -24.126952)
		(width 0.12954)
		(layer "F.Cu")
		(net "P12V_SCM_REG")
	)
	(via
		(at 186.88558 -24.126952)
		(size 0.508)
		(drill 0.254)
		(layers "F.Cu" "B.Cu")
		(net "P12V_SCM_REG")
	)
	(segment
		(start 171.599098 -24.048974)
		(end 171.599098 -27.369516)
		(width 0.254)
		(layer "F.Cu")
		(net "P12V_SCM_R")
	)
	(segment
		(start 193.425826 -22.017228)
		(end 194.128644 -22.720046)
		(width 0.508)
		(layer "F.Cu")
		(net "P12V_SCM_R")
	)
	(segment
		(start 194.128644 -30.2895)
		(end 194.001644 -30.4165)
		(width 0.508)
		(layer "F.Cu")
		(net "P12V_SCM_R")
	)
	(segment
		(start 208.5086 -37.366448)
		(end 208.5086 -36.909248)
		(width 0.254)
		(layer "F.Cu")
		(net "P12V_SCM_R")
	)
	(segment
		(start 176.071022 -22.697948)
		(end 175.911002 -22.537928)
		(width 0.254)
		(layer "F.Cu")
		(net "P12V_SCM_R")
	)
	(segment
		(start 194.128644 -26.10993)
		(end 194.82562 -26.806906)
		(width 0.508)
		(layer "F.Cu")
		(net "P12V_SCM_R")
	)
	(segment
		(start 172.950124 -22.697948)
		(end 171.599098 -24.048974)
		(width 0.254)
		(layer "F.Cu")
		(net "P12V_SCM_R")
	)
	(segment
		(start 191.69634 -29.28366)
		(end 191.695832 -29.283152)
		(width 0.508)
		(layer "F.Cu")
		(net "P12V_SCM_R")
	)
	(segment
		(start 191.69634 -29.28366)
		(end 191.69634 -30.269688)
		(width 0.508)
		(layer "F.Cu")
		(net "P12V_SCM_R")
	)
	(segment
		(start 194.128644 -22.720046)
		(end 194.128644 -26.10993)
		(width 0.508)
		(layer "F.Cu")
		(net "P12V_SCM_R")
	)
	(segment
		(start 173.584616 -22.537928)
		(end 173.424596 -22.697948)
		(width 0.254)
		(layer "F.Cu")
		(net "P12V_SCM_R")
	)
	(segment
		(start 175.911002 -22.537928)
		(end 173.584616 -22.537928)
		(width 0.254)
		(layer "F.Cu")
		(net "P12V_SCM_R")
	)
	(segment
		(start 194.496944 -30.138624)
		(end 194.128644 -30.138624)
		(width 0.508)
		(layer "F.Cu")
		(net "P12V_SCM_R")
	)
	(segment
		(start 173.424596 -22.697948)
		(end 172.950124 -22.697948)
		(width 0.254)
		(layer "F.Cu")
		(net "P12V_SCM_R")
	)
	(segment
		(start 190.560706 -22.017228)
		(end 193.425826 -22.017228)
		(width 0.508)
		(layer "F.Cu")
		(net "P12V_SCM_R")
	)
	(segment
		(start 208.92262 -36.495228)
		(end 208.92262 -36.17214)
		(width 0.254)
		(layer "F.Cu")
		(net "P12V_SCM_R")
	)
	(segment
		(start 171.599098 -27.369516)
		(end 171.867322 -27.63774)
		(width 0.254)
		(layer "F.Cu")
		(net "P12V_SCM_R")
	)
	(segment
		(start 191.843152 -30.4165)
		(end 191.69634 -30.269688)
		(width 0.508)
		(layer "F.Cu")
		(net "P12V_SCM_R")
	)
	(segment
		(start 194.82562 -29.809948)
		(end 194.496944 -30.138624)
		(width 0.508)
		(layer "F.Cu")
		(net "P12V_SCM_R")
	)
	(segment
		(start 194.001644 -30.4165)
		(end 191.843152 -30.4165)
		(width 0.508)
		(layer "F.Cu")
		(net "P12V_SCM_R")
	)
	(segment
		(start 208.5086 -36.909248)
		(end 208.92262 -36.495228)
		(width 0.254)
		(layer "F.Cu")
		(net "P12V_SCM_R")
	)
	(segment
		(start 194.128644 -30.138624)
		(end 194.128644 -30.2895)
		(width 0.508)
		(layer "F.Cu")
		(net "P12V_SCM_R")
	)
	(segment
		(start 194.82562 -26.806906)
		(end 194.82562 -29.809948)
		(width 0.508)
		(layer "F.Cu")
		(net "P12V_SCM_R")
	)
	(via
		(at 177.60188 -25.949148)
		(size 0.508)
		(drill 0.254)
		(layers "F.Cu" "B.Cu")
		(net "P12V_SCM_R")
	)
	(via
		(at 198.092822 -37.470334)
		(size 0.508)
		(drill 0.254)
		(layers "F.Cu" "B.Cu")
		(net "P12V_SCM_R")
	)
	(via
		(at 176.71288 -25.949148)
		(size 0.508)
		(drill 0.254)
		(layers "F.Cu" "B.Cu")
		(net "P12V_SCM_R")
	)
	(via
		(at 176.87798 -19.942048)
		(size 0.508)
		(drill 0.254)
		(layers "F.Cu" "B.Cu")
		(net "P12V_SCM_R")
	)
	(via
		(at 176.968658 -20.714208)
		(size 0.508)
		(drill 0.254)
		(layers "F.Cu" "B.Cu")
		(net "P12V_SCM_R")
	)
	(via
		(at 176.33188 -26.634948)
		(size 0.508)
		(drill 0.254)
		(layers "F.Cu" "B.Cu")
		(net "P12V_SCM_R")
	)
	(via
		(at 178.10988 -26.634948)
		(size 0.508)
		(drill 0.254)
		(layers "F.Cu" "B.Cu")
		(net "P12V_SCM_R")
	)
	(via
		(at 197.8914 -36.26104)
		(size 0.762)
		(drill 0.381)
		(layers "F.Cu" "B.Cu")
		(net "P12V_SCM_R")
	)
	(via
		(at 198.768462 -38.742874)
		(size 0.508)
		(drill 0.254)
		(layers "F.Cu" "B.Cu")
		(net "P12V_SCM_R")
	)
	(via
		(at 179.50688 -25.517348)
		(size 0.508)
		(drill 0.254)
		(layers "F.Cu" "B.Cu")
		(net "P12V_SCM_R")
	)
	(via
		(at 190.508382 -23.593552)
		(size 0.508)
		(drill 0.254)
		(layers "F.Cu" "B.Cu")
		(net "P12V_SCM_R")
	)
	(via
		(at 188.168026 -20.919948)
		(size 0.508)
		(drill 0.254)
		(layers "F.Cu" "B.Cu")
		(net "P12V_SCM_R")
	)
	(via
		(at 198.092822 -38.105334)
		(size 0.508)
		(drill 0.254)
		(layers "F.Cu" "B.Cu")
		(net "P12V_SCM_R")
	)
	(via
		(at 178.49088 -25.949148)
		(size 0.508)
		(drill 0.254)
		(layers "F.Cu" "B.Cu")
		(net "P12V_SCM_R")
	)
	(via
		(at 177.22088 -26.634948)
		(size 0.508)
		(drill 0.254)
		(layers "F.Cu" "B.Cu")
		(net "P12V_SCM_R")
	)
	(via
		(at 198.768462 -38.107874)
		(size 0.508)
		(drill 0.254)
		(layers "F.Cu" "B.Cu")
		(net "P12V_SCM_R")
	)
	(via
		(at 177.47234 -21.85289)
		(size 0.508)
		(drill 0.254)
		(layers "F.Cu" "B.Cu")
		(net "P12V_SCM_R")
	)
	(via
		(at 176.968658 -21.349208)
		(size 0.508)
		(drill 0.254)
		(layers "F.Cu" "B.Cu")
		(net "P12V_SCM_R")
	)
	(via
		(at 190.508382 -22.856952)
		(size 0.508)
		(drill 0.254)
		(layers "F.Cu" "B.Cu")
		(net "P12V_SCM_R")
	)
	(via
		(at 208.5086 -37.366448)
		(size 0.508)
		(drill 0.254)
		(layers "F.Cu" "B.Cu")
		(net "P12V_SCM_R")
	)
	(via
		(at 182.7784 -26.685748)
		(size 0.762)
		(drill 0.381)
		(layers "F.Cu" "B.Cu")
		(net "P12V_SCM_R")
	)
	(segment
		(start 202.92568 -36.648898)
		(end 202.92568 -37.328348)
		(width 0.381)
		(layer "B.Cu")
		(net "P12V_SCM_R")
	)
	(segment
		(start 198.768462 -38.107874)
		(end 200.233788 -36.642548)
		(width 0.381)
		(layer "B.Cu")
		(net "P12V_SCM_R")
	)
	(segment
		(start 208.09204 -37.783008)
		(end 208.5086 -37.366448)
		(width 0.381)
		(layer "B.Cu")
		(net "P12V_SCM_R")
	)
	(segment
		(start 202.93203 -36.642548)
		(end 202.92568 -36.648898)
		(width 0.381)
		(layer "B.Cu")
		(net "P12V_SCM_R")
	)
	(segment
		(start 208.56448 -37.310568)
		(end 208.56448 -36.204398)
		(width 0.381)
		(layer "B.Cu")
		(net "P12V_SCM_R")
	)
	(segment
		(start 200.233788 -36.642548)
		(end 202.93203 -36.642548)
		(width 0.381)
		(layer "B.Cu")
		(net "P12V_SCM_R")
	)
	(segment
		(start 202.92568 -37.328348)
		(end 203.38034 -37.783008)
		(width 0.381)
		(layer "B.Cu")
		(net "P12V_SCM_R")
	)
	(segment
		(start 203.38034 -37.783008)
		(end 208.09204 -37.783008)
		(width 0.381)
		(layer "B.Cu")
		(net "P12V_SCM_R")
	)
	(segment
		(start 208.5086 -37.366448)
		(end 208.56448 -37.310568)
		(width 0.381)
		(layer "B.Cu")
		(net "P12V_SCM_R")
	)
	(segment
		(start 191.667638 -23.315676)
		(end 192.288922 -22.694392)
		(width 0.12954)
		(layer "F.Cu")
		(net "P12V_SCM_PWRGD")
	)
	(segment
		(start 191.238886 -24.89327)
		(end 191.473328 -24.658828)
		(width 0.12954)
		(layer "F.Cu")
		(net "P12V_SCM_PWRGD")
	)
	(segment
		(start 191.473328 -24.658828)
		(end 191.7192 -24.658828)
		(width 0.12954)
		(layer "F.Cu")
		(net "P12V_SCM_PWRGD")
	)
	(segment
		(start 191.7192 -24.658828)
		(end 191.667638 -24.607266)
		(width 0.12954)
		(layer "F.Cu")
		(net "P12V_SCM_PWRGD")
	)
	(segment
		(start 191.667638 -24.607266)
		(end 191.667638 -23.315676)
		(width 0.12954)
		(layer "F.Cu")
		(net "P12V_SCM_PWRGD")
	)
	(via
		(at 191.7192 -24.658828)
		(size 0.508)
		(drill 0.254)
		(layers "F.Cu" "B.Cu")
		(net "P12V_SCM_PWRGD")
	)
	(segment
		(start 174.756826 -28.288742)
		(end 174.756826 -27.90063)
		(width 0.12954)
		(layer "F.Cu")
		(net "P12V_SCM_OV_FB")
	)
	(segment
		(start 175.294036 -28.43784)
		(end 174.905924 -28.43784)
		(width 0.12954)
		(layer "F.Cu")
		(net "P12V_SCM_OV_FB")
	)
	(segment
		(start 172.878242 -28.43784)
		(end 173.899322 -28.43784)
		(width 0.12954)
		(layer "F.Cu")
		(net "P12V_SCM_OV_FB")
	)
	(segment
		(start 174.905924 -28.43784)
		(end 174.756826 -28.288742)
		(width 0.12954)
		(layer "F.Cu")
		(net "P12V_SCM_OV_FB")
	)
	(segment
		(start 174.756826 -27.90063)
		(end 174.436532 -27.90063)
		(width 0.12954)
		(layer "F.Cu")
		(net "P12V_SCM_OV_FB")
	)
	(segment
		(start 171.867322 -28.43784)
		(end 172.878242 -28.43784)
		(width 0.12954)
		(layer "F.Cu")
		(net "P12V_SCM_OV_FB")
	)
	(segment
		(start 174.436532 -27.90063)
		(end 173.899322 -28.43784)
		(width 0.12954)
		(layer "F.Cu")
		(net "P12V_SCM_OV_FB")
	)
	(via
		(at 174.756826 -27.90063)
		(size 0.508)
		(drill 0.254)
		(layers "F.Cu" "B.Cu")
		(net "P12V_SCM_OV_FB")
	)
	(segment
		(start 189.23889 -24.89327)
		(end 189.23889 -24.036528)
		(width 0.12954)
		(layer "F.Cu")
		(net "P12V_SCM_OV")
	)
	(segment
		(start 186.428888 -22.327108)
		(end 186.199272 -22.097492)
		(width 0.12954)
		(layer "F.Cu")
		(net "P12V_SCM_OV")
	)
	(segment
		(start 187.221622 -22.327108)
		(end 186.428888 -22.327108)
		(width 0.12954)
		(layer "F.Cu")
		(net "P12V_SCM_OV")
	)
	(segment
		(start 189.23889 -23.289514)
		(end 188.276484 -22.327108)
		(width 0.12954)
		(layer "F.Cu")
		(net "P12V_SCM_OV")
	)
	(segment
		(start 189.23889 -24.036528)
		(end 189.23889 -23.289514)
		(width 0.12954)
		(layer "F.Cu")
		(net "P12V_SCM_OV")
	)
	(segment
		(start 188.276484 -22.327108)
		(end 187.221622 -22.327108)
		(width 0.12954)
		(layer "F.Cu")
		(net "P12V_SCM_OV")
	)
	(via
		(at 189.23889 -24.036528)
		(size 0.508)
		(drill 0.254)
		(layers "F.Cu" "B.Cu")
		(net "P12V_SCM_OV")
	)
	(segment
		(start 178.044602 -32.550862)
		(end 177.9524 -32.45866)
		(width 0.12954)
		(layer "F.Cu")
		(net "P12V_SCM_ISET")
	)
	(segment
		(start 177.9524 -32.45866)
		(end 177.9524 -31.828486)
		(width 0.12954)
		(layer "F.Cu")
		(net "P12V_SCM_ISET")
	)
	(segment
		(start 177.694082 -31.570168)
		(end 177.694082 -30.33776)
		(width 0.12954)
		(layer "F.Cu")
		(net "P12V_SCM_ISET")
	)
	(segment
		(start 177.9524 -31.828486)
		(end 177.694082 -31.570168)
		(width 0.12954)
		(layer "F.Cu")
		(net "P12V_SCM_ISET")
	)
	(via
		(at 177.9524 -31.828486)
		(size 0.508)
		(drill 0.254)
		(layers "F.Cu" "B.Cu")
		(net "P12V_SCM_ISET")
	)
	(via
		(at 175.789082 -32.551878)
		(size 0.6604)
		(drill 0.3302)
		(layers "F.Cu" "B.Cu")
		(net "P12V_SCM_ISET")
	)
	(segment
		(start 176.297082 -32.043878)
		(end 175.789082 -32.551878)
		(width 0.12954)
		(layer "B.Cu")
		(net "P12V_SCM_ISET")
	)
	(segment
		(start 177.611024 -31.828486)
		(end 177.395632 -32.043878)
		(width 0.12954)
		(layer "B.Cu")
		(net "P12V_SCM_ISET")
	)
	(segment
		(start 176.97704 -32.551878)
		(end 175.789082 -32.551878)
		(width 0.12954)
		(layer "B.Cu")
		(net "P12V_SCM_ISET")
	)
	(segment
		(start 177.395632 -32.043878)
		(end 176.297082 -32.043878)
		(width 0.12954)
		(layer "B.Cu")
		(net "P12V_SCM_ISET")
	)
	(segment
		(start 177.9524 -31.828486)
		(end 177.611024 -31.828486)
		(width 0.12954)
		(layer "B.Cu")
		(net "P12V_SCM_ISET")
	)
	(segment
		(start 172.991018 -32.535622)
		(end 172.34408 -33.18256)
		(width 0.254)
		(layer "F.Cu")
		(net "P12V_SCM_IMON")
	)
	(segment
		(start 176.193958 -31.141162)
		(end 176.193958 -30.33776)
		(width 0.254)
		(layer "F.Cu")
		(net "P12V_SCM_IMON")
	)
	(segment
		(start 174.799498 -32.535622)
		(end 176.193958 -31.141162)
		(width 0.254)
		(layer "F.Cu")
		(net "P12V_SCM_IMON")
	)
	(segment
		(start 174.613062 -32.535622)
		(end 174.799498 -32.535622)
		(width 0.254)
		(layer "F.Cu")
		(net "P12V_SCM_IMON")
	)
	(segment
		(start 173.597062 -32.535622)
		(end 172.991018 -32.535622)
		(width 0.254)
		(layer "F.Cu")
		(net "P12V_SCM_IMON")
	)
	(segment
		(start 173.597062 -32.535622)
		(end 174.613062 -32.535622)
		(width 0.254)
		(layer "F.Cu")
		(net "P12V_SCM_IMON")
	)
	(via
		(at 172.34408 -33.18256)
		(size 0.762)
		(drill 0.381)
		(layers "F.Cu" "B.Cu")
		(net "P12V_SCM_IMON")
	)
	(segment
		(start 190.895732 -29.283152)
		(end 190.895732 -28.267152)
		(width 0.12954)
		(layer "F.Cu")
		(net "P12V_SCM_GATE")
	)
	(segment
		(start 190.73876 -27.026108)
		(end 190.6778 -27.087068)
		(width 0.12954)
		(layer "F.Cu")
		(net "P12V_SCM_GATE")
	)
	(segment
		(start 190.73876 -28.11018)
		(end 190.895732 -28.267152)
		(width 0.12954)
		(layer "F.Cu")
		(net "P12V_SCM_GATE")
	)
	(segment
		(start 190.6778 -27.087068)
		(end 190.73876 -27.148028)
		(width 0.12954)
		(layer "F.Cu")
		(net "P12V_SCM_GATE")
	)
	(segment
		(start 190.895732 -30.26918)
		(end 190.89624 -30.269688)
		(width 0.12954)
		(layer "F.Cu")
		(net "P12V_SCM_GATE")
	)
	(segment
		(start 190.73876 -27.148028)
		(end 190.73876 -28.11018)
		(width 0.12954)
		(layer "F.Cu")
		(net "P12V_SCM_GATE")
	)
	(segment
		(start 190.73876 -26.393394)
		(end 190.73876 -27.026108)
		(width 0.12954)
		(layer "F.Cu")
		(net "P12V_SCM_GATE")
	)
	(segment
		(start 190.895732 -29.283152)
		(end 190.895732 -30.26918)
		(width 0.12954)
		(layer "F.Cu")
		(net "P12V_SCM_GATE")
	)
	(via
		(at 190.6778 -27.087068)
		(size 0.508)
		(drill 0.254)
		(layers "F.Cu" "B.Cu")
		(net "P12V_SCM_GATE")
	)
	(segment
		(start 180.267102 -31.280862)
		(end 179.694078 -30.707838)
		(width 0.12954)
		(layer "F.Cu")
		(net "P12V_SCM_EN_R2")
	)
	(segment
		(start 179.694078 -30.707838)
		(end 179.694078 -30.312614)
		(width 0.12954)
		(layer "F.Cu")
		(net "P12V_SCM_EN_R2")
	)
	(segment
		(start 180.93436 -32.535622)
		(end 180.074062 -32.535622)
		(width 0.12954)
		(layer "F.Cu")
		(net "P12V_SCM_EN_R2")
	)
	(segment
		(start 180.074062 -32.535622)
		(end 180.074062 -32.38881)
		(width 0.12954)
		(layer "F.Cu")
		(net "P12V_SCM_EN_R2")
	)
	(segment
		(start 180.267102 -32.19577)
		(end 180.267102 -31.280862)
		(width 0.12954)
		(layer "F.Cu")
		(net "P12V_SCM_EN_R2")
	)
	(segment
		(start 180.074062 -32.38881)
		(end 180.267102 -32.19577)
		(width 0.12954)
		(layer "F.Cu")
		(net "P12V_SCM_EN_R2")
	)
	(via
		(at 180.93436 -32.535622)
		(size 0.508)
		(drill 0.254)
		(layers "F.Cu" "B.Cu")
		(net "P12V_SCM_EN_R2")
	)
	(segment
		(start 180.074062 -33.335722)
		(end 180.16728 -33.42894)
		(width 0.12954)
		(layer "F.Cu")
		(net "P12V_SCM_EN")
	)
	(segment
		(start 180.16728 -35.931348)
		(end 182.66918 -38.433248)
		(width 0.12954)
		(layer "F.Cu")
		(net "P12V_SCM_EN")
	)
	(segment
		(start 180.16728 -33.42894)
		(end 180.16728 -35.931348)
		(width 0.12954)
		(layer "F.Cu")
		(net "P12V_SCM_EN")
	)
	(segment
		(start 191.389 -38.433248)
		(end 193.809366 -38.433248)
		(width 0.12954)
		(layer "F.Cu")
		(net "P12V_SCM_EN")
	)
	(segment
		(start 196.967348 -38.433248)
		(end 193.809366 -38.433248)
		(width 0.12954)
		(layer "F.Cu")
		(net "P12V_SCM_EN")
	)
	(segment
		(start 197.577456 -41.433242)
		(end 197.577456 -40.138604)
		(width 0.12954)
		(layer "F.Cu")
		(net "P12V_SCM_EN")
	)
	(segment
		(start 182.66918 -38.433248)
		(end 191.389 -38.433248)
		(width 0.12954)
		(layer "F.Cu")
		(net "P12V_SCM_EN")
	)
	(segment
		(start 197.61073 -41.466516)
		(end 197.577456 -41.433242)
		(width 0.12954)
		(layer "F.Cu")
		(net "P12V_SCM_EN")
	)
	(segment
		(start 197.577456 -39.050468)
		(end 197.577456 -40.138604)
		(width 0.12954)
		(layer "F.Cu")
		(net "P12V_SCM_EN")
	)
	(segment
		(start 197.581012 -39.046912)
		(end 196.967348 -38.433248)
		(width 0.12954)
		(layer "F.Cu")
		(net "P12V_SCM_EN")
	)
	(segment
		(start 197.581012 -39.046912)
		(end 197.577456 -39.050468)
		(width 0.12954)
		(layer "F.Cu")
		(net "P12V_SCM_EN")
	)
	(via
		(at 191.389 -38.433248)
		(size 0.762)
		(drill 0.381)
		(layers "F.Cu" "B.Cu")
		(net "P12V_SCM_EN")
	)
	(segment
		(start 187.12688 -25.822148)
		(end 187.049156 -25.899872)
		(width 0.12954)
		(layer "F.Cu")
		(net "P12V_SCM_CB")
	)
	(segment
		(start 188.238638 -25.893268)
		(end 188.232034 -25.899872)
		(width 0.12954)
		(layer "F.Cu")
		(net "P12V_SCM_CB")
	)
	(segment
		(start 187.204604 -25.899872)
		(end 187.12688 -25.822148)
		(width 0.12954)
		(layer "F.Cu")
		(net "P12V_SCM_CB")
	)
	(segment
		(start 188.232034 -25.899872)
		(end 187.204604 -25.899872)
		(width 0.12954)
		(layer "F.Cu")
		(net "P12V_SCM_CB")
	)
	(segment
		(start 187.049156 -25.899872)
		(end 186.328812 -25.899872)
		(width 0.12954)
		(layer "F.Cu")
		(net "P12V_SCM_CB")
	)
	(via
		(at 187.12688 -25.822148)
		(size 0.508)
		(drill 0.254)
		(layers "F.Cu" "B.Cu")
		(net "P12V_SCM_CB")
	)
	(segment
		(start 174.342044 -23.283672)
		(end 175.483012 -23.283672)
		(width 0.12954)
		(layer "F.Cu")
		(net "P12V_SCM_AVIN_PD")
	)
	(segment
		(start 174.29734 -23.238968)
		(end 174.342044 -23.283672)
		(width 0.12954)
		(layer "F.Cu")
		(net "P12V_SCM_AVIN_PD")
	)
	(via
		(at 174.29734 -23.238968)
		(size 0.762)
		(drill 0.381)
		(layers "F.Cu" "B.Cu")
		(net "P12V_SCM_AVIN_PD")
	)
	(segment
		(start 256.489454 -42.488612)
		(end 255.450086 -42.488612)
		(width 0.12954)
		(layer "F.Cu")
		(net "P12V_E1S_VCC_0")
	)
	(segment
		(start 254.726186 -42.486072)
		(end 254.279654 -42.03954)
		(width 0.12954)
		(layer "F.Cu")
		(net "P12V_E1S_VCC_0")
	)
	(segment
		(start 254.279654 -42.03954)
		(end 253.582932 -42.03954)
		(width 0.12954)
		(layer "F.Cu")
		(net "P12V_E1S_VCC_0")
	)
	(segment
		(start 255.447546 -42.486072)
		(end 254.726186 -42.486072)
		(width 0.12954)
		(layer "F.Cu")
		(net "P12V_E1S_VCC_0")
	)
	(segment
		(start 255.450086 -42.488612)
		(end 255.447546 -42.486072)
		(width 0.12954)
		(layer "F.Cu")
		(net "P12V_E1S_VCC_0")
	)
	(via
		(at 254.279654 -42.03954)
		(size 0.508)
		(drill 0.254)
		(layers "F.Cu" "B.Cu")
		(net "P12V_E1S_VCC_0")
	)
	(segment
		(start 294.229028 -49.572672)
		(end 294.50284 -49.29886)
		(width 0.12954)
		(layer "F.Cu")
		(net "P12V_E1S_UV_0_R")
	)
	(segment
		(start 294.229028 -50.141378)
		(end 294.229028 -49.572672)
		(width 0.12954)
		(layer "F.Cu")
		(net "P12V_E1S_UV_0_R")
	)
	(via
		(at 255.98628 -58.419746)
		(size 0.508)
		(drill 0.254)
		(layers "F.Cu" "B.Cu")
		(net "P12V_E1S_UV_0_R")
	)
	(via
		(at 249.29338 -68.207128)
		(size 0.508)
		(drill 0.254)
		(layers "F.Cu" "B.Cu")
		(net "P12V_E1S_UV_0_R")
	)
	(via
		(at 294.50284 -49.29886)
		(size 0.508)
		(drill 0.254)
		(layers "F.Cu" "B.Cu")
		(net "P12V_E1S_UV_0_R")
	)
	(segment
		(start 291.04082 -49.29886)
		(end 283.600652 -56.739028)
		(width 0.12954)
		(layer "B.Cu")
		(net "P12V_E1S_UV_0_R")
	)
	(segment
		(start 254.80518 -57.238646)
		(end 254.80518 -52.013866)
		(width 0.12954)
		(layer "B.Cu")
		(net "P12V_E1S_UV_0_R")
	)
	(segment
		(start 255.19126 -51.627786)
		(end 255.19126 -48.414686)
		(width 0.12954)
		(layer "B.Cu")
		(net "P12V_E1S_UV_0_R")
	)
	(segment
		(start 254.47752 -47.700946)
		(end 252.91288 -47.700946)
		(width 0.12954)
		(layer "B.Cu")
		(net "P12V_E1S_UV_0_R")
	)
	(segment
		(start 250.591066 -45.379132)
		(end 250.30303 -45.379132)
		(width 0.12954)
		(layer "B.Cu")
		(net "P12V_E1S_UV_0_R")
	)
	(segment
		(start 258.581652 -62.749176)
		(end 253.1237 -68.207128)
		(width 0.12954)
		(layer "B.Cu")
		(net "P12V_E1S_UV_0_R")
	)
	(segment
		(start 252.91288 -47.700946)
		(end 250.591066 -45.379132)
		(width 0.12954)
		(layer "B.Cu")
		(net "P12V_E1S_UV_0_R")
	)
	(segment
		(start 278.8666 -56.739028)
		(end 273.56308 -62.042548)
		(width 0.12954)
		(layer "B.Cu")
		(net "P12V_E1S_UV_0_R")
	)
	(segment
		(start 283.600652 -56.739028)
		(end 278.8666 -56.739028)
		(width 0.12954)
		(layer "B.Cu")
		(net "P12V_E1S_UV_0_R")
	)
	(segment
		(start 255.98628 -58.419746)
		(end 254.80518 -57.238646)
		(width 0.12954)
		(layer "B.Cu")
		(net "P12V_E1S_UV_0_R")
	)
	(segment
		(start 273.56308 -62.042548)
		(end 260.28777 -62.042548)
		(width 0.12954)
		(layer "B.Cu")
		(net "P12V_E1S_UV_0_R")
	)
	(segment
		(start 253.1237 -68.207128)
		(end 249.29338 -68.207128)
		(width 0.12954)
		(layer "B.Cu")
		(net "P12V_E1S_UV_0_R")
	)
	(segment
		(start 254.80518 -52.013866)
		(end 255.19126 -51.627786)
		(width 0.12954)
		(layer "B.Cu")
		(net "P12V_E1S_UV_0_R")
	)
	(segment
		(start 255.19126 -48.414686)
		(end 254.47752 -47.700946)
		(width 0.12954)
		(layer "B.Cu")
		(net "P12V_E1S_UV_0_R")
	)
	(segment
		(start 294.50284 -49.29886)
		(end 291.04082 -49.29886)
		(width 0.12954)
		(layer "B.Cu")
		(net "P12V_E1S_UV_0_R")
	)
	(segment
		(start 260.28777 -62.042548)
		(end 258.581652 -62.749176)
		(width 0.12954)
		(layer "B.Cu")
		(net "P12V_E1S_UV_0_R")
	)
	(segment
		(start 255.98628 -58.419746)
		(end 255.98628 -64.607948)
		(width 0.127)
		(layer "In2.Cu")
		(net "P12V_E1S_UV_0_R")
	)
	(segment
		(start 252.3871 -68.207128)
		(end 249.29338 -68.207128)
		(width 0.127)
		(layer "In2.Cu")
		(net "P12V_E1S_UV_0_R")
	)
	(segment
		(start 255.98628 -64.607948)
		(end 252.3871 -68.207128)
		(width 0.127)
		(layer "In2.Cu")
		(net "P12V_E1S_UV_0_R")
	)
	(segment
		(start 250.316746 -44.565316)
		(end 250.316746 -43.556682)
		(width 0.12954)
		(layer "F.Cu")
		(net "P12V_E1S_UV_0")
	)
	(segment
		(start 250.30303 -44.579032)
		(end 250.316746 -44.565316)
		(width 0.12954)
		(layer "F.Cu")
		(net "P12V_E1S_UV_0")
	)
	(segment
		(start 251.140468 -42.03954)
		(end 252.082808 -42.03954)
		(width 0.12954)
		(layer "F.Cu")
		(net "P12V_E1S_UV_0")
	)
	(segment
		(start 250.316746 -42.863262)
		(end 251.140468 -42.03954)
		(width 0.12954)
		(layer "F.Cu")
		(net "P12V_E1S_UV_0")
	)
	(segment
		(start 250.316746 -43.556682)
		(end 250.316746 -42.863262)
		(width 0.12954)
		(layer "F.Cu")
		(net "P12V_E1S_UV_0")
	)
	(via
		(at 250.316746 -42.863262)
		(size 0.508)
		(drill 0.254)
		(layers "F.Cu" "B.Cu")
		(net "P12V_E1S_UV_0")
	)
	(segment
		(start 250.316746 -42.863262)
		(end 250.30303 -42.876978)
		(width 0.12954)
		(layer "B.Cu")
		(net "P12V_E1S_UV_0")
	)
	(segment
		(start 250.30303 -42.876978)
		(end 250.30303 -44.579032)
		(width 0.12954)
		(layer "B.Cu")
		(net "P12V_E1S_UV_0")
	)
	(segment
		(start 256.594102 -49.86655)
		(end 255.261618 -49.86655)
		(width 0.12954)
		(layer "F.Cu")
		(net "P12V_E1S_TIMER_0")
	)
	(segment
		(start 256.787904 -49.672748)
		(end 256.594102 -49.86655)
		(width 0.12954)
		(layer "F.Cu")
		(net "P12V_E1S_TIMER_0")
	)
	(segment
		(start 256.901696 -49.558956)
		(end 257.975608 -49.558956)
		(width 0.12954)
		(layer "F.Cu")
		(net "P12V_E1S_TIMER_0")
	)
	(segment
		(start 256.787904 -49.672748)
		(end 256.901696 -49.558956)
		(width 0.12954)
		(layer "F.Cu")
		(net "P12V_E1S_TIMER_0")
	)
	(via
		(at 256.787904 -49.672748)
		(size 0.762)
		(drill 0.381)
		(layers "F.Cu" "B.Cu")
		(net "P12V_E1S_TIMER_0")
	)
	(segment
		(start 256.87528 -51.350926)
		(end 257.02006 -51.350926)
		(width 0.12954)
		(layer "F.Cu")
		(net "P12V_E1S_SS_0")
	)
	(segment
		(start 256.535428 -50.866294)
		(end 256.87528 -51.206146)
		(width 0.12954)
		(layer "F.Cu")
		(net "P12V_E1S_SS_0")
	)
	(segment
		(start 255.261618 -50.866294)
		(end 256.535428 -50.866294)
		(width 0.12954)
		(layer "F.Cu")
		(net "P12V_E1S_SS_0")
	)
	(segment
		(start 257.02006 -51.350926)
		(end 257.338576 -51.669442)
		(width 0.12954)
		(layer "F.Cu")
		(net "P12V_E1S_SS_0")
	)
	(segment
		(start 257.338576 -51.669442)
		(end 257.45948 -51.669442)
		(width 0.12954)
		(layer "F.Cu")
		(net "P12V_E1S_SS_0")
	)
	(segment
		(start 256.87528 -51.206146)
		(end 256.87528 -51.350926)
		(width 0.12954)
		(layer "F.Cu")
		(net "P12V_E1S_SS_0")
	)
	(via
		(at 256.87528 -51.350926)
		(size 0.508)
		(drill 0.254)
		(layers "F.Cu" "B.Cu")
		(net "P12V_E1S_SS_0")
	)
	(segment
		(start 258.96062 -57.511442)
		(end 258.25958 -57.511442)
		(width 0.12954)
		(layer "F.Cu")
		(net "P12V_E1S_SENSE_0")
	)
	(segment
		(start 253.97841 -44.449492)
		(end 253.97841 -42.935144)
		(width 0.12954)
		(layer "F.Cu")
		(net "P12V_E1S_SENSE_0")
	)
	(segment
		(start 253.97841 -42.935144)
		(end 253.582932 -42.539666)
		(width 0.12954)
		(layer "F.Cu")
		(net "P12V_E1S_SENSE_0")
	)
	(segment
		(start 254.74168 -44.398946)
		(end 254.691134 -44.449492)
		(width 0.12954)
		(layer "F.Cu")
		(net "P12V_E1S_SENSE_0")
	)
	(segment
		(start 254.691134 -44.449492)
		(end 253.97841 -44.449492)
		(width 0.12954)
		(layer "F.Cu")
		(net "P12V_E1S_SENSE_0")
	)
	(via
		(at 258.96062 -57.511442)
		(size 0.508)
		(drill 0.254)
		(layers "F.Cu" "B.Cu")
		(net "P12V_E1S_SENSE_0")
	)
	(via
		(at 254.74168 -44.398946)
		(size 0.508)
		(drill 0.254)
		(layers "F.Cu" "B.Cu")
		(net "P12V_E1S_SENSE_0")
	)
	(segment
		(start 257.59918 -48.602646)
		(end 256.4892 -47.492666)
		(width 0.127)
		(layer "In2.Cu")
		(net "P12V_E1S_SENSE_0")
	)
	(segment
		(start 256.4892 -45.516546)
		(end 255.3716 -44.398946)
		(width 0.127)
		(layer "In2.Cu")
		(net "P12V_E1S_SENSE_0")
	)
	(segment
		(start 257.59918 -56.194452)
		(end 257.59918 -48.602646)
		(width 0.127)
		(layer "In2.Cu")
		(net "P12V_E1S_SENSE_0")
	)
	(segment
		(start 258.96062 -57.511442)
		(end 258.91617 -57.511442)
		(width 0.127)
		(layer "In2.Cu")
		(net "P12V_E1S_SENSE_0")
	)
	(segment
		(start 258.91617 -57.511442)
		(end 257.59918 -56.194452)
		(width 0.127)
		(layer "In2.Cu")
		(net "P12V_E1S_SENSE_0")
	)
	(segment
		(start 255.3716 -44.398946)
		(end 254.74168 -44.398946)
		(width 0.127)
		(layer "In2.Cu")
		(net "P12V_E1S_SENSE_0")
	)
	(segment
		(start 256.4892 -47.492666)
		(end 256.4892 -45.516546)
		(width 0.127)
		(layer "In2.Cu")
		(net "P12V_E1S_SENSE_0")
	)
	(segment
		(start 251.48921 -44.441872)
		(end 251.35967 -44.571412)
		(width 0.12954)
		(layer "F.Cu")
		(net "P12V_E1S_REG_0")
	)
	(segment
		(start 252.082808 -42.539666)
		(end 251.48921 -43.133264)
		(width 0.12954)
		(layer "F.Cu")
		(net "P12V_E1S_REG_0")
	)
	(segment
		(start 251.48921 -43.951906)
		(end 251.48921 -44.441872)
		(width 0.12954)
		(layer "F.Cu")
		(net "P12V_E1S_REG_0")
	)
	(segment
		(start 251.48921 -43.133264)
		(end 251.48921 -43.951906)
		(width 0.12954)
		(layer "F.Cu")
		(net "P12V_E1S_REG_0")
	)
	(via
		(at 251.48921 -43.951906)
		(size 0.508)
		(drill 0.254)
		(layers "F.Cu" "B.Cu")
		(net "P12V_E1S_REG_0")
	)
	(segment
		(start 251.644658 -39.460932)
		(end 250.537726 -39.460932)
		(width 0.12954)
		(layer "F.Cu")
		(net "P12V_E1S_PWRGD_0")
	)
	(segment
		(start 251.723144 -39.539418)
		(end 251.644658 -39.460932)
		(width 0.12954)
		(layer "F.Cu")
		(net "P12V_E1S_PWRGD_0")
	)
	(segment
		(start 252.082808 -39.539418)
		(end 251.723144 -39.539418)
		(width 0.12954)
		(layer "F.Cu")
		(net "P12V_E1S_PWRGD_0")
	)
	(segment
		(start 250.317 -39.240206)
		(end 250.317 -38.448996)
		(width 0.12954)
		(layer "F.Cu")
		(net "P12V_E1S_PWRGD_0")
	)
	(segment
		(start 250.537726 -39.460932)
		(end 250.317 -39.240206)
		(width 0.12954)
		(layer "F.Cu")
		(net "P12V_E1S_PWRGD_0")
	)
	(via
		(at 250.537726 -39.460932)
		(size 0.508)
		(drill 0.254)
		(layers "F.Cu" "B.Cu")
		(net "P12V_E1S_PWRGD_0")
	)
	(segment
		(start 253.361698 -56.193182)
		(end 253.361698 -55.177182)
		(width 0.12954)
		(layer "F.Cu")
		(net "P12V_E1S_OV_FB_0")
	)
	(segment
		(start 253.361698 -54.161182)
		(end 253.361698 -55.177182)
		(width 0.12954)
		(layer "F.Cu")
		(net "P12V_E1S_OV_FB_0")
	)
	(segment
		(start 253.361698 -52.766468)
		(end 253.361698 -54.161182)
		(width 0.12954)
		(layer "F.Cu")
		(net "P12V_E1S_OV_FB_0")
	)
	(segment
		(start 253.35484 -57.408826)
		(end 253.35484 -56.20004)
		(width 0.12954)
		(layer "F.Cu")
		(net "P12V_E1S_OV_FB_0")
	)
	(segment
		(start 253.35484 -56.20004)
		(end 253.361698 -56.193182)
		(width 0.12954)
		(layer "F.Cu")
		(net "P12V_E1S_OV_FB_0")
	)
	(via
		(at 253.35484 -57.408826)
		(size 0.762)
		(drill 0.381)
		(layers "F.Cu" "B.Cu")
		(net "P12V_E1S_OV_FB_0")
	)
	(segment
		(start 252.082808 -41.539414)
		(end 250.961652 -41.539414)
		(width 0.12954)
		(layer "F.Cu")
		(net "P12V_E1S_OV_0")
	)
	(segment
		(start 249.404124 -43.44416)
		(end 249.516646 -43.556682)
		(width 0.12954)
		(layer "F.Cu")
		(net "P12V_E1S_OV_0")
	)
	(segment
		(start 249.28703 -44.579032)
		(end 249.28703 -44.451524)
		(width 0.12954)
		(layer "F.Cu")
		(net "P12V_E1S_OV_0")
	)
	(segment
		(start 249.28703 -44.451524)
		(end 248.279666 -43.44416)
		(width 0.12954)
		(layer "F.Cu")
		(net "P12V_E1S_OV_0")
	)
	(segment
		(start 248.279666 -43.44416)
		(end 249.404124 -43.44416)
		(width 0.12954)
		(layer "F.Cu")
		(net "P12V_E1S_OV_0")
	)
	(segment
		(start 250.961652 -41.539414)
		(end 249.516646 -42.98442)
		(width 0.12954)
		(layer "F.Cu")
		(net "P12V_E1S_OV_0")
	)
	(segment
		(start 249.516646 -42.98442)
		(end 249.516646 -43.556682)
		(width 0.12954)
		(layer "F.Cu")
		(net "P12V_E1S_OV_0")
	)
	(via
		(at 248.279666 -43.44416)
		(size 0.762)
		(drill 0.381)
		(layers "F.Cu" "B.Cu")
		(net "P12V_E1S_OV_0")
	)
	(segment
		(start 255.261618 -50.366422)
		(end 256.06248 -50.366422)
		(width 0.12954)
		(layer "F.Cu")
		(net "P12V_E1S_ISET_0")
	)
	(segment
		(start 256.54762 -50.370486)
		(end 256.310384 -50.370486)
		(width 0.12954)
		(layer "F.Cu")
		(net "P12V_E1S_ISET_0")
	)
	(segment
		(start 256.74828 -50.571146)
		(end 256.54762 -50.370486)
		(width 0.12954)
		(layer "F.Cu")
		(net "P12V_E1S_ISET_0")
	)
	(segment
		(start 257.547364 -50.571146)
		(end 256.74828 -50.571146)
		(width 0.12954)
		(layer "F.Cu")
		(net "P12V_E1S_ISET_0")
	)
	(segment
		(start 256.310384 -50.370486)
		(end 256.30632 -50.366422)
		(width 0.12954)
		(layer "F.Cu")
		(net "P12V_E1S_ISET_0")
	)
	(segment
		(start 257.97383 -50.565304)
		(end 257.553206 -50.565304)
		(width 0.12954)
		(layer "F.Cu")
		(net "P12V_E1S_ISET_0")
	)
	(segment
		(start 257.553206 -50.565304)
		(end 257.547364 -50.571146)
		(width 0.12954)
		(layer "F.Cu")
		(net "P12V_E1S_ISET_0")
	)
	(segment
		(start 256.30632 -50.366422)
		(end 256.06248 -50.366422)
		(width 0.12954)
		(layer "F.Cu")
		(net "P12V_E1S_ISET_0")
	)
	(via
		(at 256.06248 -50.366422)
		(size 0.508)
		(drill 0.254)
		(layers "F.Cu" "B.Cu")
		(net "P12V_E1S_ISET_0")
	)
	(segment
		(start 256.717038 -50.366422)
		(end 257.23977 -49.84369)
		(width 0.12954)
		(layer "B.Cu")
		(net "P12V_E1S_ISET_0")
	)
	(segment
		(start 256.06248 -50.366422)
		(end 256.717038 -50.366422)
		(width 0.12954)
		(layer "B.Cu")
		(net "P12V_E1S_ISET_0")
	)
	(segment
		(start 257.23977 -49.84369)
		(end 257.23977 -49.430686)
		(width 0.12954)
		(layer "B.Cu")
		(net "P12V_E1S_ISET_0")
	)
	(segment
		(start 257.45948 -55.479442)
		(end 257.45948 -56.495442)
		(width 0.254)
		(layer "F.Cu")
		(net "P12V_E1S_IMON_0")
	)
	(segment
		(start 257.45948 -54.463442)
		(end 257.45948 -55.479442)
		(width 0.254)
		(layer "F.Cu")
		(net "P12V_E1S_IMON_0")
	)
	(segment
		(start 257.45948 -53.447442)
		(end 257.45948 -54.463442)
		(width 0.254)
		(layer "F.Cu")
		(net "P12V_E1S_IMON_0")
	)
	(segment
		(start 256.50952 -52.618386)
		(end 255.75768 -51.866546)
		(width 0.254)
		(layer "F.Cu")
		(net "P12V_E1S_IMON_0")
	)
	(segment
		(start 256.54127 -52.939696)
		(end 256.50952 -52.907946)
		(width 0.254)
		(layer "F.Cu")
		(net "P12V_E1S_IMON_0")
	)
	(segment
		(start 256.50952 -52.907946)
		(end 256.50952 -52.618386)
		(width 0.254)
		(layer "F.Cu")
		(net "P12V_E1S_IMON_0")
	)
	(segment
		(start 257.45948 -53.447442)
		(end 257.049016 -53.447442)
		(width 0.254)
		(layer "F.Cu")
		(net "P12V_E1S_IMON_0")
	)
	(segment
		(start 257.049016 -53.447442)
		(end 256.54127 -52.939696)
		(width 0.254)
		(layer "F.Cu")
		(net "P12V_E1S_IMON_0")
	)
	(segment
		(start 255.75768 -51.866546)
		(end 255.261618 -51.866546)
		(width 0.254)
		(layer "F.Cu")
		(net "P12V_E1S_IMON_0")
	)
	(via
		(at 256.54127 -52.939696)
		(size 0.508)
		(drill 0.254)
		(layers "F.Cu" "B.Cu")
		(net "P12V_E1S_IMON_0")
	)
	(segment
		(start 255.299718 -40.039544)
		(end 255.45669 -39.882572)
		(width 0.12954)
		(layer "F.Cu")
		(net "P12V_E1S_GATE_0")
	)
	(segment
		(start 257.394202 -39.884096)
		(end 257.87985 -39.884096)
		(width 0.12954)
		(layer "F.Cu")
		(net "P12V_E1S_GATE_0")
	)
	(segment
		(start 256.47269 -39.882572)
		(end 257.102102 -39.882572)
		(width 0.12954)
		(layer "F.Cu")
		(net "P12V_E1S_GATE_0")
	)
	(segment
		(start 255.45669 -39.882572)
		(end 256.47269 -39.882572)
		(width 0.12954)
		(layer "F.Cu")
		(net "P12V_E1S_GATE_0")
	)
	(segment
		(start 257.102102 -39.882572)
		(end 257.248914 -40.029384)
		(width 0.12954)
		(layer "F.Cu")
		(net "P12V_E1S_GATE_0")
	)
	(segment
		(start 253.582932 -40.039544)
		(end 255.299718 -40.039544)
		(width 0.12954)
		(layer "F.Cu")
		(net "P12V_E1S_GATE_0")
	)
	(segment
		(start 257.248914 -40.029384)
		(end 257.394202 -39.884096)
		(width 0.12954)
		(layer "F.Cu")
		(net "P12V_E1S_GATE_0")
	)
	(via
		(at 257.248914 -40.029384)
		(size 0.508)
		(drill 0.254)
		(layers "F.Cu" "B.Cu")
		(net "P12V_E1S_GATE_0")
	)
	(via
		(at 255.43256 -53.586126)
		(size 0.508)
		(drill 0.254)
		(layers "F.Cu" "B.Cu")
		(net "P12V_E1S_FLTB_0")
	)
	(segment
		(start 253.59995 -38.212776)
		(end 253.59995 -37.667946)
		(width 0.12954)
		(layer "F.Cu")
		(net "P12V_E1S_FAULT_0")
	)
	(segment
		(start 252.582934 -39.539418)
		(end 252.582934 -39.229792)
		(width 0.12954)
		(layer "F.Cu")
		(net "P12V_E1S_FAULT_0")
	)
	(segment
		(start 252.582934 -39.229792)
		(end 252.77572 -39.037006)
		(width 0.12954)
		(layer "F.Cu")
		(net "P12V_E1S_FAULT_0")
	)
	(segment
		(start 252.77572 -39.037006)
		(end 253.59995 -38.212776)
		(width 0.12954)
		(layer "F.Cu")
		(net "P12V_E1S_FAULT_0")
	)
	(via
		(at 252.77572 -39.037006)
		(size 0.508)
		(drill 0.254)
		(layers "F.Cu" "B.Cu")
		(net "P12V_E1S_FAULT_0")
	)
	(segment
		(start 256.055114 -48.366426)
		(end 256.413254 -48.008286)
		(width 0.12954)
		(layer "F.Cu")
		(net "P12V_E1S_EN_0_R2")
	)
	(segment
		(start 255.236472 -48.366426)
		(end 256.055114 -48.366426)
		(width 0.12954)
		(layer "F.Cu")
		(net "P12V_E1S_EN_0_R2")
	)
	(segment
		(start 256.638552 -48.008286)
		(end 256.999486 -48.36922)
		(width 0.12954)
		(layer "F.Cu")
		(net "P12V_E1S_EN_0_R2")
	)
	(segment
		(start 257.392932 -48.304704)
		(end 257.81381 -48.304704)
		(width 0.12954)
		(layer "F.Cu")
		(net "P12V_E1S_EN_0_R2")
	)
	(segment
		(start 256.999486 -48.36922)
		(end 257.328416 -48.36922)
		(width 0.12954)
		(layer "F.Cu")
		(net "P12V_E1S_EN_0_R2")
	)
	(segment
		(start 257.328416 -48.36922)
		(end 257.392932 -48.304704)
		(width 0.12954)
		(layer "F.Cu")
		(net "P12V_E1S_EN_0_R2")
	)
	(segment
		(start 256.413254 -48.008286)
		(end 256.638552 -48.008286)
		(width 0.12954)
		(layer "F.Cu")
		(net "P12V_E1S_EN_0_R2")
	)
	(via
		(at 256.638552 -48.008286)
		(size 0.762)
		(drill 0.381)
		(layers "F.Cu" "B.Cu")
		(net "P12V_E1S_EN_0_R2")
	)
	(segment
		(start 253.08941 -44.449492)
		(end 253.08941 -43.835066)
		(width 0.12954)
		(layer "F.Cu")
		(net "P12V_E1S_CB_0")
	)
	(segment
		(start 253.08941 -42.54627)
		(end 253.082806 -42.539666)
		(width 0.12954)
		(layer "F.Cu")
		(net "P12V_E1S_CB_0")
	)
	(segment
		(start 253.08941 -43.835066)
		(end 253.08941 -42.54627)
		(width 0.12954)
		(layer "F.Cu")
		(net "P12V_E1S_CB_0")
	)
	(via
		(at 253.08941 -43.835066)
		(size 0.508)
		(drill 0.254)
		(layers "F.Cu" "B.Cu")
		(net "P12V_E1S_CB_0")
	)
	(segment
		(start 248.17578 -53.774086)
		(end 248.20753 -53.742336)
		(width 0.12954)
		(layer "F.Cu")
		(net "P12V_E1S_AVIN_PD_0")
	)
	(segment
		(start 248.20753 -53.742336)
		(end 248.20753 -52.577492)
		(width 0.12954)
		(layer "F.Cu")
		(net "P12V_E1S_AVIN_PD_0")
	)
	(via
		(at 248.17578 -53.774086)
		(size 0.762)
		(drill 0.381)
		(layers "F.Cu" "B.Cu")
		(net "P12V_E1S_AVIN_PD_0")
	)
	(segment
		(start 33.65246 -106.695748)
		(end 34.92246 -105.425748)
		(width 0.254)
		(layer "F.Cu")
		(net "P12V_E1S_0_ISENSE_TIC")
	)
	(segment
		(start 34.92246 -105.425748)
		(end 36.530534 -105.425748)
		(width 0.254)
		(layer "F.Cu")
		(net "P12V_E1S_0_ISENSE_TIC")
	)
	(segment
		(start 32.51581 -107.05846)
		(end 33.289748 -107.05846)
		(width 0.254)
		(layer "F.Cu")
		(net "P12V_E1S_0_ISENSE_TIC")
	)
	(segment
		(start 33.289748 -107.05846)
		(end 33.65246 -106.695748)
		(width 0.254)
		(layer "F.Cu")
		(net "P12V_E1S_0_ISENSE_TIC")
	)
	(via
		(at 259.029708 -54.381146)
		(size 0.508)
		(drill 0.254)
		(layers "F.Cu" "B.Cu")
		(net "P12V_E1S_0_ISENSE_TIC")
	)
	(via
		(at 278.33828 -106.873548)
		(size 0.508)
		(drill 0.254)
		(layers "F.Cu" "B.Cu")
		(net "P12V_E1S_0_ISENSE_TIC")
	)
	(via
		(at 33.65246 -106.695748)
		(size 0.508)
		(drill 0.254)
		(layers "F.Cu" "B.Cu")
		(net "P12V_E1S_0_ISENSE_TIC")
	)
	(segment
		(start 259.029708 -54.381146)
		(end 257.58648 -54.381146)
		(width 0.254)
		(layer "B.Cu")
		(net "P12V_E1S_0_ISENSE_TIC")
	)
	(segment
		(start 257.58648 -54.381146)
		(end 256.95402 -55.013606)
		(width 0.254)
		(layer "B.Cu")
		(net "P12V_E1S_0_ISENSE_TIC")
	)
	(segment
		(start 256.95402 -55.013606)
		(end 256.95402 -55.436262)
		(width 0.254)
		(layer "B.Cu")
		(net "P12V_E1S_0_ISENSE_TIC")
	)
	(segment
		(start 259.11048 -54.524148)
		(end 259.11048 -54.47792)
		(width 0.254)
		(layer "In2.Cu")
		(net "P12V_E1S_0_ISENSE_TIC")
	)
	(segment
		(start 279.197308 -59.650376)
		(end 264.236708 -59.650376)
		(width 0.254)
		(layer "In2.Cu")
		(net "P12V_E1S_0_ISENSE_TIC")
	)
	(segment
		(start 279.25268 -106.517948)
		(end 279.25268 -90.820748)
		(width 0.254)
		(layer "In2.Cu")
		(net "P12V_E1S_0_ISENSE_TIC")
	)
	(segment
		(start 282.45308 -87.620348)
		(end 282.45308 -62.906148)
		(width 0.254)
		(layer "In2.Cu")
		(net "P12V_E1S_0_ISENSE_TIC")
	)
	(segment
		(start 279.25268 -90.820748)
		(end 282.45308 -87.620348)
		(width 0.254)
		(layer "In2.Cu")
		(net "P12V_E1S_0_ISENSE_TIC")
	)
	(segment
		(start 264.236708 -59.650376)
		(end 259.11048 -54.524148)
		(width 0.254)
		(layer "In2.Cu")
		(net "P12V_E1S_0_ISENSE_TIC")
	)
	(segment
		(start 282.45308 -62.906148)
		(end 279.197308 -59.650376)
		(width 0.254)
		(layer "In2.Cu")
		(net "P12V_E1S_0_ISENSE_TIC")
	)
	(segment
		(start 259.11048 -54.47792)
		(end 259.029708 -54.397148)
		(width 0.254)
		(layer "In2.Cu")
		(net "P12V_E1S_0_ISENSE_TIC")
	)
	(segment
		(start 278.33828 -106.873548)
		(end 278.89708 -106.873548)
		(width 0.254)
		(layer "In2.Cu")
		(net "P12V_E1S_0_ISENSE_TIC")
	)
	(segment
		(start 259.029708 -54.397148)
		(end 259.029708 -54.381146)
		(width 0.254)
		(layer "In2.Cu")
		(net "P12V_E1S_0_ISENSE_TIC")
	)
	(segment
		(start 278.89708 -106.873548)
		(end 279.25268 -106.517948)
		(width 0.254)
		(layer "In2.Cu")
		(net "P12V_E1S_0_ISENSE_TIC")
	)
	(segment
		(start 112.011714 -84.727542)
		(end 127.797814 -84.727542)
		(width 0.254)
		(layer "In6.Cu")
		(net "P12V_E1S_0_ISENSE_TIC")
	)
	(segment
		(start 194.1068 -96.078548)
		(end 201.82586 -96.078548)
		(width 0.254)
		(layer "In6.Cu")
		(net "P12V_E1S_0_ISENSE_TIC")
	)
	(segment
		(start 249.7328 -111.242348)
		(end 253.510796 -111.242348)
		(width 0.254)
		(layer "In6.Cu")
		(net "P12V_E1S_0_ISENSE_TIC")
	)
	(segment
		(start 224.567242 -103.955088)
		(end 242.44554 -103.955088)
		(width 0.254)
		(layer "In6.Cu")
		(net "P12V_E1S_0_ISENSE_TIC")
	)
	(segment
		(start 139.06246 -84.963508)
		(end 146.8628 -84.963508)
		(width 0.254)
		(layer "In6.Cu")
		(net "P12V_E1S_0_ISENSE_TIC")
	)
	(segment
		(start 277.859236 -107.352592)
		(end 278.33828 -106.873548)
		(width 0.254)
		(layer "In6.Cu")
		(net "P12V_E1S_0_ISENSE_TIC")
	)
	(segment
		(start 211.826348 -104.163368)
		(end 214.958168 -104.163368)
		(width 0.254)
		(layer "In6.Cu")
		(net "P12V_E1S_0_ISENSE_TIC")
	)
	(segment
		(start 26.23312 -97.932748)
		(end 35.25012 -88.915748)
		(width 0.254)
		(layer "In6.Cu")
		(net "P12V_E1S_0_ISENSE_TIC")
	)
	(segment
		(start 70.69582 -87.869268)
		(end 80.5815 -77.983588)
		(width 0.254)
		(layer "In6.Cu")
		(net "P12V_E1S_0_ISENSE_TIC")
	)
	(segment
		(start 26.23312 -100.312728)
		(end 26.23312 -97.932748)
		(width 0.254)
		(layer "In6.Cu")
		(net "P12V_E1S_0_ISENSE_TIC")
	)
	(segment
		(start 107.99064 -82.159348)
		(end 109.44352 -82.159348)
		(width 0.254)
		(layer "In6.Cu")
		(net "P12V_E1S_0_ISENSE_TIC")
	)
	(segment
		(start 180.479192 -88.621108)
		(end 182.917084 -91.059)
		(width 0.254)
		(layer "In6.Cu")
		(net "P12V_E1S_0_ISENSE_TIC")
	)
	(segment
		(start 214.958168 -104.163368)
		(end 217.669364 -106.874564)
		(width 0.254)
		(layer "In6.Cu")
		(net "P12V_E1S_0_ISENSE_TIC")
	)
	(segment
		(start 128.24968 -85.179408)
		(end 130.06324 -85.179408)
		(width 0.254)
		(layer "In6.Cu")
		(net "P12V_E1S_0_ISENSE_TIC")
	)
	(segment
		(start 28.14828 -102.227888)
		(end 26.23312 -100.312728)
		(width 0.254)
		(layer "In6.Cu")
		(net "P12V_E1S_0_ISENSE_TIC")
	)
	(segment
		(start 80.5815 -77.983588)
		(end 103.81488 -77.983588)
		(width 0.254)
		(layer "In6.Cu")
		(net "P12V_E1S_0_ISENSE_TIC")
	)
	(segment
		(start 32.47136 -105.514648)
		(end 30.16758 -105.514648)
		(width 0.254)
		(layer "In6.Cu")
		(net "P12V_E1S_0_ISENSE_TIC")
	)
	(segment
		(start 103.81488 -77.983588)
		(end 107.99064 -82.159348)
		(width 0.254)
		(layer "In6.Cu")
		(net "P12V_E1S_0_ISENSE_TIC")
	)
	(segment
		(start 259.926836 -107.352592)
		(end 277.859236 -107.352592)
		(width 0.254)
		(layer "In6.Cu")
		(net "P12V_E1S_0_ISENSE_TIC")
	)
	(segment
		(start 33.65246 -106.695748)
		(end 32.47136 -105.514648)
		(width 0.254)
		(layer "In6.Cu")
		(net "P12V_E1S_0_ISENSE_TIC")
	)
	(segment
		(start 146.8628 -84.963508)
		(end 150.5204 -88.621108)
		(width 0.254)
		(layer "In6.Cu")
		(net "P12V_E1S_0_ISENSE_TIC")
	)
	(segment
		(start 47.27448 -87.869268)
		(end 70.69582 -87.869268)
		(width 0.254)
		(layer "In6.Cu")
		(net "P12V_E1S_0_ISENSE_TIC")
	)
	(segment
		(start 207.921352 -102.17404)
		(end 209.83702 -102.17404)
		(width 0.254)
		(layer "In6.Cu")
		(net "P12V_E1S_0_ISENSE_TIC")
	)
	(segment
		(start 30.16758 -105.514648)
		(end 28.14828 -103.495348)
		(width 0.254)
		(layer "In6.Cu")
		(net "P12V_E1S_0_ISENSE_TIC")
	)
	(segment
		(start 189.087252 -91.059)
		(end 194.1068 -96.078548)
		(width 0.254)
		(layer "In6.Cu")
		(net "P12V_E1S_0_ISENSE_TIC")
	)
	(segment
		(start 35.25012 -88.915748)
		(end 46.228 -88.915748)
		(width 0.254)
		(layer "In6.Cu")
		(net "P12V_E1S_0_ISENSE_TIC")
	)
	(segment
		(start 221.647766 -106.874564)
		(end 224.567242 -103.955088)
		(width 0.254)
		(layer "In6.Cu")
		(net "P12V_E1S_0_ISENSE_TIC")
	)
	(segment
		(start 209.83702 -102.17404)
		(end 211.826348 -104.163368)
		(width 0.254)
		(layer "In6.Cu")
		(net "P12V_E1S_0_ISENSE_TIC")
	)
	(segment
		(start 256.761996 -107.991148)
		(end 259.28828 -107.991148)
		(width 0.254)
		(layer "In6.Cu")
		(net "P12V_E1S_0_ISENSE_TIC")
	)
	(segment
		(start 182.917084 -91.059)
		(end 189.087252 -91.059)
		(width 0.254)
		(layer "In6.Cu")
		(net "P12V_E1S_0_ISENSE_TIC")
	)
	(segment
		(start 130.06324 -85.179408)
		(end 130.52298 -84.719668)
		(width 0.254)
		(layer "In6.Cu")
		(net "P12V_E1S_0_ISENSE_TIC")
	)
	(segment
		(start 46.228 -88.915748)
		(end 47.27448 -87.869268)
		(width 0.254)
		(layer "In6.Cu")
		(net "P12V_E1S_0_ISENSE_TIC")
	)
	(segment
		(start 201.82586 -96.078548)
		(end 207.921352 -102.17404)
		(width 0.254)
		(layer "In6.Cu")
		(net "P12V_E1S_0_ISENSE_TIC")
	)
	(segment
		(start 109.44352 -82.159348)
		(end 112.011714 -84.727542)
		(width 0.254)
		(layer "In6.Cu")
		(net "P12V_E1S_0_ISENSE_TIC")
	)
	(segment
		(start 127.797814 -84.727542)
		(end 128.24968 -85.179408)
		(width 0.254)
		(layer "In6.Cu")
		(net "P12V_E1S_0_ISENSE_TIC")
	)
	(segment
		(start 28.14828 -103.495348)
		(end 28.14828 -102.227888)
		(width 0.254)
		(layer "In6.Cu")
		(net "P12V_E1S_0_ISENSE_TIC")
	)
	(segment
		(start 242.44554 -103.955088)
		(end 249.7328 -111.242348)
		(width 0.254)
		(layer "In6.Cu")
		(net "P12V_E1S_0_ISENSE_TIC")
	)
	(segment
		(start 130.52298 -84.719668)
		(end 138.81862 -84.719668)
		(width 0.254)
		(layer "In6.Cu")
		(net "P12V_E1S_0_ISENSE_TIC")
	)
	(segment
		(start 259.28828 -107.991148)
		(end 259.926836 -107.352592)
		(width 0.254)
		(layer "In6.Cu")
		(net "P12V_E1S_0_ISENSE_TIC")
	)
	(segment
		(start 253.510796 -111.242348)
		(end 256.761996 -107.991148)
		(width 0.254)
		(layer "In6.Cu")
		(net "P12V_E1S_0_ISENSE_TIC")
	)
	(segment
		(start 138.81862 -84.719668)
		(end 139.06246 -84.963508)
		(width 0.254)
		(layer "In6.Cu")
		(net "P12V_E1S_0_ISENSE_TIC")
	)
	(segment
		(start 150.5204 -88.621108)
		(end 180.479192 -88.621108)
		(width 0.254)
		(layer "In6.Cu")
		(net "P12V_E1S_0_ISENSE_TIC")
	)
	(segment
		(start 217.669364 -106.874564)
		(end 221.647766 -106.874564)
		(width 0.254)
		(layer "In6.Cu")
		(net "P12V_E1S_0_ISENSE_TIC")
	)
	(segment
		(start 258.91617 -55.479442)
		(end 258.25958 -55.479442)
		(width 0.254)
		(layer "F.Cu")
		(net "P12V_E1S_0_ISENSE_MPS_TIC")
	)
	(via
		(at 258.91617 -55.479442)
		(size 0.508)
		(drill 0.254)
		(layers "F.Cu" "B.Cu")
		(net "P12V_E1S_0_ISENSE_MPS_TIC")
	)
	(segment
		(start 258.91617 -55.479442)
		(end 258.217924 -55.479442)
		(width 0.12954)
		(layer "B.Cu")
		(net "P12V_E1S_0_ISENSE_MPS_TIC")
	)
	(segment
		(start 258.217924 -55.479442)
		(end 258.174744 -55.436262)
		(width 0.12954)
		(layer "B.Cu")
		(net "P12V_E1S_0_ISENSE_MPS_TIC")
	)
	(segment
		(start 258.174744 -55.436262)
		(end 257.75412 -55.436262)
		(width 0.12954)
		(layer "B.Cu")
		(net "P12V_E1S_0_ISENSE_MPS_TIC")
	)
	(segment
		(start 258.91617 -56.495442)
		(end 258.25958 -56.495442)
		(width 0.254)
		(layer "F.Cu")
		(net "P12V_E1S_0_ISENSE_MPS_MAM")
	)
	(via
		(at 40.66286 -100.95738)
		(size 0.508)
		(drill 0.254)
		(layers "F.Cu" "B.Cu")
		(net "P12V_E1S_0_ISENSE_MPS_MAM")
	)
	(via
		(at 258.91617 -56.495442)
		(size 0.508)
		(drill 0.254)
		(layers "F.Cu" "B.Cu")
		(net "P12V_E1S_0_ISENSE_MPS_MAM")
	)
	(via
		(at 274.58543 -110.651798)
		(size 0.508)
		(drill 0.254)
		(layers "F.Cu" "B.Cu")
		(net "P12V_E1S_0_ISENSE_MPS_MAM")
	)
	(segment
		(start 41.830244 -100.95738)
		(end 40.66286 -100.95738)
		(width 0.254)
		(layer "B.Cu")
		(net "P12V_E1S_0_ISENSE_MPS_MAM")
	)
	(segment
		(start 262.604504 -60.183776)
		(end 278.976328 -60.183776)
		(width 0.254)
		(layer "In2.Cu")
		(net "P12V_E1S_0_ISENSE_MPS_MAM")
	)
	(segment
		(start 278.71928 -104.518968)
		(end 274.58543 -108.652818)
		(width 0.254)
		(layer "In2.Cu")
		(net "P12V_E1S_0_ISENSE_MPS_MAM")
	)
	(segment
		(start 278.976328 -60.183776)
		(end 281.91968 -63.127128)
		(width 0.254)
		(layer "In2.Cu")
		(net "P12V_E1S_0_ISENSE_MPS_MAM")
	)
	(segment
		(start 258.91617 -56.495442)
		(end 262.604504 -60.183776)
		(width 0.254)
		(layer "In2.Cu")
		(net "P12V_E1S_0_ISENSE_MPS_MAM")
	)
	(segment
		(start 278.71928 -90.599768)
		(end 278.71928 -104.518968)
		(width 0.254)
		(layer "In2.Cu")
		(net "P12V_E1S_0_ISENSE_MPS_MAM")
	)
	(segment
		(start 281.91968 -87.399368)
		(end 278.71928 -90.599768)
		(width 0.254)
		(layer "In2.Cu")
		(net "P12V_E1S_0_ISENSE_MPS_MAM")
	)
	(segment
		(start 281.91968 -63.127128)
		(end 281.91968 -87.399368)
		(width 0.254)
		(layer "In2.Cu")
		(net "P12V_E1S_0_ISENSE_MPS_MAM")
	)
	(segment
		(start 274.58543 -108.652818)
		(end 274.58543 -110.651798)
		(width 0.254)
		(layer "In2.Cu")
		(net "P12V_E1S_0_ISENSE_MPS_MAM")
	)
	(segment
		(start 222.833184 -110.440216)
		(end 223.12503 -110.440216)
		(width 0.254)
		(layer "In6.Cu")
		(net "P12V_E1S_0_ISENSE_MPS_MAM")
	)
	(segment
		(start 209.0801 -111.3409)
		(end 221.9325 -111.3409)
		(width 0.254)
		(layer "In6.Cu")
		(net "P12V_E1S_0_ISENSE_MPS_MAM")
	)
	(segment
		(start 60.8711 -98.212148)
		(end 65.741042 -98.212148)
		(width 0.254)
		(layer "In6.Cu")
		(net "P12V_E1S_0_ISENSE_MPS_MAM")
	)
	(segment
		(start 177.6222 -96.0628)
		(end 178.7144 -97.155)
		(width 0.254)
		(layer "In6.Cu")
		(net "P12V_E1S_0_ISENSE_MPS_MAM")
	)
	(segment
		(start 205.438248 -107.699048)
		(end 209.0801 -111.3409)
		(width 0.254)
		(layer "In6.Cu")
		(net "P12V_E1S_0_ISENSE_MPS_MAM")
	)
	(segment
		(start 182.649368 -97.533968)
		(end 184.328308 -99.212908)
		(width 0.254)
		(layer "In6.Cu")
		(net "P12V_E1S_0_ISENSE_MPS_MAM")
	)
	(segment
		(start 108.24464 -89.370408)
		(end 142.767558 -89.370408)
		(width 0.254)
		(layer "In6.Cu")
		(net "P12V_E1S_0_ISENSE_MPS_MAM")
	)
	(segment
		(start 198.161402 -98.821748)
		(end 200.08088 -100.741226)
		(width 0.254)
		(layer "In6.Cu")
		(net "P12V_E1S_0_ISENSE_MPS_MAM")
	)
	(segment
		(start 52.00396 -103.238808)
		(end 53.17236 -102.070408)
		(width 0.254)
		(layer "In6.Cu")
		(net "P12V_E1S_0_ISENSE_MPS_MAM")
	)
	(segment
		(start 261.02183 -114.092482)
		(end 263.338564 -111.775748)
		(width 0.254)
		(layer "In6.Cu")
		(net "P12V_E1S_0_ISENSE_MPS_MAM")
	)
	(segment
		(start 65.741042 -98.212148)
		(end 77.625702 -86.327488)
		(width 0.254)
		(layer "In6.Cu")
		(net "P12V_E1S_0_ISENSE_MPS_MAM")
	)
	(segment
		(start 181.954932 -97.155)
		(end 182.3339 -97.533968)
		(width 0.254)
		(layer "In6.Cu")
		(net "P12V_E1S_0_ISENSE_MPS_MAM")
	)
	(segment
		(start 247.991376 -114.092482)
		(end 261.02183 -114.092482)
		(width 0.254)
		(layer "In6.Cu")
		(net "P12V_E1S_0_ISENSE_MPS_MAM")
	)
	(segment
		(start 273.76628 -111.775748)
		(end 274.58543 -110.956598)
		(width 0.254)
		(layer "In6.Cu")
		(net "P12V_E1S_0_ISENSE_MPS_MAM")
	)
	(segment
		(start 105.20172 -86.327488)
		(end 108.24464 -89.370408)
		(width 0.254)
		(layer "In6.Cu")
		(net "P12V_E1S_0_ISENSE_MPS_MAM")
	)
	(segment
		(start 40.66286 -100.95738)
		(end 44.208192 -100.95738)
		(width 0.254)
		(layer "In6.Cu")
		(net "P12V_E1S_0_ISENSE_MPS_MAM")
	)
	(segment
		(start 178.7144 -97.155)
		(end 181.954932 -97.155)
		(width 0.254)
		(layer "In6.Cu")
		(net "P12V_E1S_0_ISENSE_MPS_MAM")
	)
	(segment
		(start 246.590312 -112.682274)
		(end 246.590312 -112.691418)
		(width 0.254)
		(layer "In6.Cu")
		(net "P12V_E1S_0_ISENSE_MPS_MAM")
	)
	(segment
		(start 77.625702 -86.327488)
		(end 105.20172 -86.327488)
		(width 0.254)
		(layer "In6.Cu")
		(net "P12V_E1S_0_ISENSE_MPS_MAM")
	)
	(segment
		(start 200.08088 -100.741226)
		(end 200.08088 -102.674928)
		(width 0.254)
		(layer "In6.Cu")
		(net "P12V_E1S_0_ISENSE_MPS_MAM")
	)
	(segment
		(start 184.328308 -99.212908)
		(end 191.7954 -99.212908)
		(width 0.254)
		(layer "In6.Cu")
		(net "P12V_E1S_0_ISENSE_MPS_MAM")
	)
	(segment
		(start 142.767558 -89.370408)
		(end 147.555458 -94.158308)
		(width 0.254)
		(layer "In6.Cu")
		(net "P12V_E1S_0_ISENSE_MPS_MAM")
	)
	(segment
		(start 240.746026 -106.837988)
		(end 246.590312 -112.682274)
		(width 0.254)
		(layer "In6.Cu")
		(net "P12V_E1S_0_ISENSE_MPS_MAM")
	)
	(segment
		(start 147.555458 -94.158308)
		(end 169.967656 -94.158308)
		(width 0.254)
		(layer "In6.Cu")
		(net "P12V_E1S_0_ISENSE_MPS_MAM")
	)
	(segment
		(start 246.590312 -112.691418)
		(end 247.991376 -114.092482)
		(width 0.254)
		(layer "In6.Cu")
		(net "P12V_E1S_0_ISENSE_MPS_MAM")
	)
	(segment
		(start 191.7954 -99.212908)
		(end 192.18656 -98.821748)
		(width 0.254)
		(layer "In6.Cu")
		(net "P12V_E1S_0_ISENSE_MPS_MAM")
	)
	(segment
		(start 223.12503 -110.440216)
		(end 226.727258 -106.837988)
		(width 0.254)
		(layer "In6.Cu")
		(net "P12V_E1S_0_ISENSE_MPS_MAM")
	)
	(segment
		(start 205.105 -107.699048)
		(end 205.438248 -107.699048)
		(width 0.254)
		(layer "In6.Cu")
		(net "P12V_E1S_0_ISENSE_MPS_MAM")
	)
	(segment
		(start 171.872148 -96.0628)
		(end 177.6222 -96.0628)
		(width 0.254)
		(layer "In6.Cu")
		(net "P12V_E1S_0_ISENSE_MPS_MAM")
	)
	(segment
		(start 46.70552 -103.454708)
		(end 48.1203 -103.454708)
		(width 0.254)
		(layer "In6.Cu")
		(net "P12V_E1S_0_ISENSE_MPS_MAM")
	)
	(segment
		(start 192.18656 -98.821748)
		(end 198.161402 -98.821748)
		(width 0.254)
		(layer "In6.Cu")
		(net "P12V_E1S_0_ISENSE_MPS_MAM")
	)
	(segment
		(start 274.58543 -110.956598)
		(end 274.58543 -110.651798)
		(width 0.254)
		(layer "In6.Cu")
		(net "P12V_E1S_0_ISENSE_MPS_MAM")
	)
	(segment
		(start 48.1203 -103.454708)
		(end 48.3362 -103.238808)
		(width 0.254)
		(layer "In6.Cu")
		(net "P12V_E1S_0_ISENSE_MPS_MAM")
	)
	(segment
		(start 44.208192 -100.95738)
		(end 46.70552 -103.454708)
		(width 0.254)
		(layer "In6.Cu")
		(net "P12V_E1S_0_ISENSE_MPS_MAM")
	)
	(segment
		(start 48.3362 -103.238808)
		(end 52.00396 -103.238808)
		(width 0.254)
		(layer "In6.Cu")
		(net "P12V_E1S_0_ISENSE_MPS_MAM")
	)
	(segment
		(start 57.01284 -102.070408)
		(end 60.8711 -98.212148)
		(width 0.254)
		(layer "In6.Cu")
		(net "P12V_E1S_0_ISENSE_MPS_MAM")
	)
	(segment
		(start 221.9325 -111.3409)
		(end 222.833184 -110.440216)
		(width 0.254)
		(layer "In6.Cu")
		(net "P12V_E1S_0_ISENSE_MPS_MAM")
	)
	(segment
		(start 169.967656 -94.158308)
		(end 171.872148 -96.0628)
		(width 0.254)
		(layer "In6.Cu")
		(net "P12V_E1S_0_ISENSE_MPS_MAM")
	)
	(segment
		(start 200.08088 -102.674928)
		(end 205.105 -107.699048)
		(width 0.254)
		(layer "In6.Cu")
		(net "P12V_E1S_0_ISENSE_MPS_MAM")
	)
	(segment
		(start 53.17236 -102.070408)
		(end 57.01284 -102.070408)
		(width 0.254)
		(layer "In6.Cu")
		(net "P12V_E1S_0_ISENSE_MPS_MAM")
	)
	(segment
		(start 182.3339 -97.533968)
		(end 182.649368 -97.533968)
		(width 0.254)
		(layer "In6.Cu")
		(net "P12V_E1S_0_ISENSE_MPS_MAM")
	)
	(segment
		(start 263.338564 -111.775748)
		(end 273.76628 -111.775748)
		(width 0.254)
		(layer "In6.Cu")
		(net "P12V_E1S_0_ISENSE_MPS_MAM")
	)
	(segment
		(start 226.727258 -106.837988)
		(end 240.746026 -106.837988)
		(width 0.254)
		(layer "In6.Cu")
		(net "P12V_E1S_0_ISENSE_MPS_MAM")
	)
	(segment
		(start 258.25958 -58.311542)
		(end 257.008884 -58.311542)
		(width 0.254)
		(layer "F.Cu")
		(net "P12V_E1S_0_ISENSE_MAM_TIC")
	)
	(segment
		(start 257.008884 -58.311542)
		(end 256.97688 -58.343546)
		(width 0.254)
		(layer "F.Cu")
		(net "P12V_E1S_0_ISENSE_MAM_TIC")
	)
	(via
		(at 256.65938 -56.938926)
		(size 0.6604)
		(drill 0.3302)
		(layers "F.Cu" "B.Cu")
		(net "P12V_E1S_0_ISENSE_MAM_TIC")
	)
	(via
		(at 256.97688 -58.343546)
		(size 0.508)
		(drill 0.254)
		(layers "F.Cu" "B.Cu")
		(net "P12V_E1S_0_ISENSE_MAM_TIC")
	)
	(segment
		(start 256.65938 -58.026046)
		(end 256.65938 -56.938926)
		(width 0.254)
		(layer "B.Cu")
		(net "P12V_E1S_0_ISENSE_MAM_TIC")
	)
	(segment
		(start 256.97688 -58.343546)
		(end 256.65938 -58.026046)
		(width 0.254)
		(layer "B.Cu")
		(net "P12V_E1S_0_ISENSE_MAM_TIC")
	)
	(segment
		(start 256.65938 -56.938926)
		(end 256.177288 -56.456834)
		(width 0.254)
		(layer "B.Cu")
		(net "P12V_E1S_0_ISENSE_MAM_TIC")
	)
	(segment
		(start 256.177288 -55.45963)
		(end 256.15392 -55.436262)
		(width 0.254)
		(layer "B.Cu")
		(net "P12V_E1S_0_ISENSE_MAM_TIC")
	)
	(segment
		(start 256.177288 -56.456834)
		(end 256.177288 -55.45963)
		(width 0.254)
		(layer "B.Cu")
		(net "P12V_E1S_0_ISENSE_MAM_TIC")
	)
	(segment
		(start 257.45948 -57.511442)
		(end 255.776984 -57.511442)
		(width 0.254)
		(layer "F.Cu")
		(net "P12V_E1S_0_ISENSE_MAM_MAM")
	)
	(segment
		(start 255.776984 -57.511442)
		(end 255.30048 -57.987946)
		(width 0.254)
		(layer "F.Cu")
		(net "P12V_E1S_0_ISENSE_MAM_MAM")
	)
	(segment
		(start 255.30048 -57.987946)
		(end 255.30048 -58.521346)
		(width 0.254)
		(layer "F.Cu")
		(net "P12V_E1S_0_ISENSE_MAM_MAM")
	)
	(via
		(at 273.95043 -110.651798)
		(size 0.508)
		(drill 0.254)
		(layers "F.Cu" "B.Cu")
		(net "P12V_E1S_0_ISENSE_MAM_MAM")
	)
	(via
		(at 40.66286 -99.35718)
		(size 0.508)
		(drill 0.254)
		(layers "F.Cu" "B.Cu")
		(net "P12V_E1S_0_ISENSE_MAM_MAM")
	)
	(via
		(at 255.30048 -58.521346)
		(size 0.508)
		(drill 0.254)
		(layers "F.Cu" "B.Cu")
		(net "P12V_E1S_0_ISENSE_MAM_MAM")
	)
	(segment
		(start 41.830244 -99.35718)
		(end 40.66286 -99.35718)
		(width 0.254)
		(layer "B.Cu")
		(net "P12V_E1S_0_ISENSE_MAM_MAM")
	)
	(segment
		(start 274.03679 -108.375196)
		(end 278.13508 -104.276906)
		(width 0.254)
		(layer "In2.Cu")
		(net "P12V_E1S_0_ISENSE_MAM_MAM")
	)
	(segment
		(start 278.734266 -60.767976)
		(end 261.036308 -60.767976)
		(width 0.254)
		(layer "In2.Cu")
		(net "P12V_E1S_0_ISENSE_MAM_MAM")
	)
	(segment
		(start 281.33548 -87.157306)
		(end 281.33548 -63.36919)
		(width 0.254)
		(layer "In2.Cu")
		(net "P12V_E1S_0_ISENSE_MAM_MAM")
	)
	(segment
		(start 255.79832 -57.455308)
		(end 255.30048 -57.953148)
		(width 0.254)
		(layer "In2.Cu")
		(net "P12V_E1S_0_ISENSE_MAM_MAM")
	)
	(segment
		(start 274.03679 -110.565438)
		(end 274.03679 -108.375196)
		(width 0.254)
		(layer "In2.Cu")
		(net "P12V_E1S_0_ISENSE_MAM_MAM")
	)
	(segment
		(start 257.72364 -57.455308)
		(end 255.79832 -57.455308)
		(width 0.254)
		(layer "In2.Cu")
		(net "P12V_E1S_0_ISENSE_MAM_MAM")
	)
	(segment
		(start 255.30048 -57.953148)
		(end 255.30048 -58.521346)
		(width 0.254)
		(layer "In2.Cu")
		(net "P12V_E1S_0_ISENSE_MAM_MAM")
	)
	(segment
		(start 281.33548 -63.36919)
		(end 278.734266 -60.767976)
		(width 0.254)
		(layer "In2.Cu")
		(net "P12V_E1S_0_ISENSE_MAM_MAM")
	)
	(segment
		(start 278.13508 -104.276906)
		(end 278.13508 -90.357706)
		(width 0.254)
		(layer "In2.Cu")
		(net "P12V_E1S_0_ISENSE_MAM_MAM")
	)
	(segment
		(start 273.95043 -110.651798)
		(end 274.03679 -110.565438)
		(width 0.254)
		(layer "In2.Cu")
		(net "P12V_E1S_0_ISENSE_MAM_MAM")
	)
	(segment
		(start 261.036308 -60.767976)
		(end 257.72364 -57.455308)
		(width 0.254)
		(layer "In2.Cu")
		(net "P12V_E1S_0_ISENSE_MAM_MAM")
	)
	(segment
		(start 278.13508 -90.357706)
		(end 281.33548 -87.157306)
		(width 0.254)
		(layer "In2.Cu")
		(net "P12V_E1S_0_ISENSE_MAM_MAM")
	)
	(segment
		(start 143.020034 -88.895428)
		(end 108.778294 -88.895428)
		(width 0.254)
		(layer "In6.Cu")
		(net "P12V_E1S_0_ISENSE_MAM_MAM")
	)
	(segment
		(start 51.64836 -102.713028)
		(end 48.26508 -102.713028)
		(width 0.254)
		(layer "In6.Cu")
		(net "P12V_E1S_0_ISENSE_MAM_MAM")
	)
	(segment
		(start 65.519046 -97.676208)
		(end 60.649104 -97.676208)
		(width 0.254)
		(layer "In6.Cu")
		(net "P12V_E1S_0_ISENSE_MAM_MAM")
	)
	(segment
		(start 205.23962 -107.173268)
		(end 200.56348 -102.497128)
		(width 0.254)
		(layer "In6.Cu")
		(net "P12V_E1S_0_ISENSE_MAM_MAM")
	)
	(segment
		(start 184.5945 -98.034348)
		(end 183.0197 -96.459548)
		(width 0.254)
		(layer "In6.Cu")
		(net "P12V_E1S_0_ISENSE_MAM_MAM")
	)
	(segment
		(start 191.624458 -98.593402)
		(end 188.67247 -98.593402)
		(width 0.254)
		(layer "In6.Cu")
		(net "P12V_E1S_0_ISENSE_MAM_MAM")
	)
	(segment
		(start 200.56348 -100.509832)
		(end 198.418196 -98.364548)
		(width 0.254)
		(layer "In6.Cu")
		(net "P12V_E1S_0_ISENSE_MAM_MAM")
	)
	(segment
		(start 248.218198 -113.629694)
		(end 240.95583 -106.367326)
		(width 0.254)
		(layer "In6.Cu")
		(net "P12V_E1S_0_ISENSE_MAM_MAM")
	)
	(segment
		(start 181.9656 -96.459548)
		(end 181.752748 -96.6724)
		(width 0.254)
		(layer "In6.Cu")
		(net "P12V_E1S_0_ISENSE_MAM_MAM")
	)
	(segment
		(start 209.2833 -110.8837)
		(end 205.572868 -107.173268)
		(width 0.254)
		(layer "In6.Cu")
		(net "P12V_E1S_0_ISENSE_MAM_MAM")
	)
	(segment
		(start 178.6128 -96.012)
		(end 178.6128 -94.996)
		(width 0.254)
		(layer "In6.Cu")
		(net "P12V_E1S_0_ISENSE_MAM_MAM")
	)
	(segment
		(start 179.2732 -96.6724)
		(end 178.6128 -96.012)
		(width 0.254)
		(layer "In6.Cu")
		(net "P12V_E1S_0_ISENSE_MAM_MAM")
	)
	(segment
		(start 188.67247 -98.593402)
		(end 188.113416 -98.034348)
		(width 0.254)
		(layer "In6.Cu")
		(net "P12V_E1S_0_ISENSE_MAM_MAM")
	)
	(segment
		(start 181.752748 -96.6724)
		(end 179.2732 -96.6724)
		(width 0.254)
		(layer "In6.Cu")
		(net "P12V_E1S_0_ISENSE_MAM_MAM")
	)
	(segment
		(start 171.223432 -94.7674)
		(end 170.15714 -93.701108)
		(width 0.254)
		(layer "In6.Cu")
		(net "P12V_E1S_0_ISENSE_MAM_MAM")
	)
	(segment
		(start 60.649104 -97.676208)
		(end 56.790844 -101.534468)
		(width 0.254)
		(layer "In6.Cu")
		(net "P12V_E1S_0_ISENSE_MAM_MAM")
	)
	(segment
		(start 105.641394 -85.758528)
		(end 77.436726 -85.758528)
		(width 0.254)
		(layer "In6.Cu")
		(net "P12V_E1S_0_ISENSE_MAM_MAM")
	)
	(segment
		(start 52.82692 -101.534468)
		(end 51.64836 -102.713028)
		(width 0.254)
		(layer "In6.Cu")
		(net "P12V_E1S_0_ISENSE_MAM_MAM")
	)
	(segment
		(start 188.113416 -98.034348)
		(end 184.5945 -98.034348)
		(width 0.254)
		(layer "In6.Cu")
		(net "P12V_E1S_0_ISENSE_MAM_MAM")
	)
	(segment
		(start 198.418196 -98.364548)
		(end 191.853312 -98.364548)
		(width 0.254)
		(layer "In6.Cu")
		(net "P12V_E1S_0_ISENSE_MAM_MAM")
	)
	(segment
		(start 263.17448 -111.293148)
		(end 260.837934 -113.629694)
		(width 0.254)
		(layer "In6.Cu")
		(net "P12V_E1S_0_ISENSE_MAM_MAM")
	)
	(segment
		(start 77.436726 -85.758528)
		(end 65.519046 -97.676208)
		(width 0.254)
		(layer "In6.Cu")
		(net "P12V_E1S_0_ISENSE_MAM_MAM")
	)
	(segment
		(start 200.56348 -102.497128)
		(end 200.56348 -100.509832)
		(width 0.254)
		(layer "In6.Cu")
		(net "P12V_E1S_0_ISENSE_MAM_MAM")
	)
	(segment
		(start 108.778294 -88.895428)
		(end 105.641394 -85.758528)
		(width 0.254)
		(layer "In6.Cu")
		(net "P12V_E1S_0_ISENSE_MAM_MAM")
	)
	(segment
		(start 240.95583 -106.367326)
		(end 226.527614 -106.367326)
		(width 0.254)
		(layer "In6.Cu")
		(net "P12V_E1S_0_ISENSE_MAM_MAM")
	)
	(segment
		(start 44.909232 -99.35718)
		(end 40.66286 -99.35718)
		(width 0.254)
		(layer "In6.Cu")
		(net "P12V_E1S_0_ISENSE_MAM_MAM")
	)
	(segment
		(start 273.95043 -110.651798)
		(end 273.30908 -111.293148)
		(width 0.254)
		(layer "In6.Cu")
		(net "P12V_E1S_0_ISENSE_MAM_MAM")
	)
	(segment
		(start 178.6128 -94.996)
		(end 178.3842 -94.7674)
		(width 0.254)
		(layer "In6.Cu")
		(net "P12V_E1S_0_ISENSE_MAM_MAM")
	)
	(segment
		(start 147.825714 -93.701108)
		(end 143.020034 -88.895428)
		(width 0.254)
		(layer "In6.Cu")
		(net "P12V_E1S_0_ISENSE_MAM_MAM")
	)
	(segment
		(start 273.30908 -111.293148)
		(end 263.17448 -111.293148)
		(width 0.254)
		(layer "In6.Cu")
		(net "P12V_E1S_0_ISENSE_MAM_MAM")
	)
	(segment
		(start 260.837934 -113.629694)
		(end 248.218198 -113.629694)
		(width 0.254)
		(layer "In6.Cu")
		(net "P12V_E1S_0_ISENSE_MAM_MAM")
	)
	(segment
		(start 205.572868 -107.173268)
		(end 205.23962 -107.173268)
		(width 0.254)
		(layer "In6.Cu")
		(net "P12V_E1S_0_ISENSE_MAM_MAM")
	)
	(segment
		(start 170.15714 -93.701108)
		(end 147.825714 -93.701108)
		(width 0.254)
		(layer "In6.Cu")
		(net "P12V_E1S_0_ISENSE_MAM_MAM")
	)
	(segment
		(start 56.790844 -101.534468)
		(end 52.82692 -101.534468)
		(width 0.254)
		(layer "In6.Cu")
		(net "P12V_E1S_0_ISENSE_MAM_MAM")
	)
	(segment
		(start 222.928688 -109.966252)
		(end 222.341948 -109.966252)
		(width 0.254)
		(layer "In6.Cu")
		(net "P12V_E1S_0_ISENSE_MAM_MAM")
	)
	(segment
		(start 183.0197 -96.459548)
		(end 181.9656 -96.459548)
		(width 0.254)
		(layer "In6.Cu")
		(net "P12V_E1S_0_ISENSE_MAM_MAM")
	)
	(segment
		(start 178.3842 -94.7674)
		(end 171.223432 -94.7674)
		(width 0.254)
		(layer "In6.Cu")
		(net "P12V_E1S_0_ISENSE_MAM_MAM")
	)
	(segment
		(start 222.341948 -109.966252)
		(end 221.4245 -110.8837)
		(width 0.254)
		(layer "In6.Cu")
		(net "P12V_E1S_0_ISENSE_MAM_MAM")
	)
	(segment
		(start 191.853312 -98.364548)
		(end 191.624458 -98.593402)
		(width 0.254)
		(layer "In6.Cu")
		(net "P12V_E1S_0_ISENSE_MAM_MAM")
	)
	(segment
		(start 226.527614 -106.367326)
		(end 222.928688 -109.966252)
		(width 0.254)
		(layer "In6.Cu")
		(net "P12V_E1S_0_ISENSE_MAM_MAM")
	)
	(segment
		(start 221.4245 -110.8837)
		(end 209.2833 -110.8837)
		(width 0.254)
		(layer "In6.Cu")
		(net "P12V_E1S_0_ISENSE_MAM_MAM")
	)
	(segment
		(start 48.26508 -102.713028)
		(end 44.909232 -99.35718)
		(width 0.254)
		(layer "In6.Cu")
		(net "P12V_E1S_0_ISENSE_MAM_MAM")
	)
	(segment
		(start 44.01185 -99.948238)
		(end 43.786298 -100.17379)
		(width 0.12954)
		(layer "F.Cu")
		(net "P12V_E1S_0_ISENSE_MAM")
	)
	(segment
		(start 43.786298 -100.17379)
		(end 42.29862 -100.17379)
		(width 0.12954)
		(layer "F.Cu")
		(net "P12V_E1S_0_ISENSE_MAM")
	)
	(via
		(at 44.01185 -99.948238)
		(size 0.508)
		(drill 0.254)
		(layers "F.Cu" "B.Cu")
		(net "P12V_E1S_0_ISENSE_MAM")
	)
	(segment
		(start 43.786298 -100.17379)
		(end 42.82567 -100.17379)
		(width 0.254)
		(layer "B.Cu")
		(net "P12V_E1S_0_ISENSE_MAM")
	)
	(segment
		(start 41.830244 -100.15728)
		(end 42.787316 -100.15728)
		(width 0.254)
		(layer "B.Cu")
		(net "P12V_E1S_0_ISENSE_MAM")
	)
	(segment
		(start 44.01185 -99.948238)
		(end 43.786298 -100.17379)
		(width 0.254)
		(layer "B.Cu")
		(net "P12V_E1S_0_ISENSE_MAM")
	)
	(segment
		(start 42.82567 -100.17379)
		(end 42.814748 -100.184712)
		(width 0.254)
		(layer "B.Cu")
		(net "P12V_E1S_0_ISENSE_MAM")
	)
	(segment
		(start 42.787316 -100.15728)
		(end 42.814748 -100.184712)
		(width 0.254)
		(layer "B.Cu")
		(net "P12V_E1S_0_ISENSE_MAM")
	)
	(segment
		(start 115.75288 -101.393498)
		(end 115.75288 -100.477066)
		(width 0.12954)
		(layer "F.Cu")
		(net "P0V62_CPU0_ERRS_VREF")
	)
	(segment
		(start 115.75288 -101.393498)
		(end 114.73688 -102.409498)
		(width 0.12954)
		(layer "F.Cu")
		(net "P0V62_CPU0_ERRS_VREF")
	)
	(segment
		(start 115.446302 -100.170488)
		(end 115.219734 -99.94392)
		(width 0.12954)
		(layer "F.Cu")
		(net "P0V62_CPU0_ERRS_VREF")
	)
	(segment
		(start 114.73688 -102.409498)
		(end 114.73688 -103.679498)
		(width 0.12954)
		(layer "F.Cu")
		(net "P0V62_CPU0_ERRS_VREF")
	)
	(segment
		(start 115.75288 -103.679498)
		(end 114.73688 -103.679498)
		(width 0.12954)
		(layer "F.Cu")
		(net "P0V62_CPU0_ERRS_VREF")
	)
	(segment
		(start 115.219734 -99.94392)
		(end 115.219734 -98.425762)
		(width 0.12954)
		(layer "F.Cu")
		(net "P0V62_CPU0_ERRS_VREF")
	)
	(segment
		(start 115.75288 -100.477066)
		(end 115.446302 -100.170488)
		(width 0.12954)
		(layer "F.Cu")
		(net "P0V62_CPU0_ERRS_VREF")
	)
	(via
		(at 115.446302 -100.170488)
		(size 0.762)
		(drill 0.381)
		(layers "F.Cu" "B.Cu")
		(net "P0V62_CPU0_ERRS_VREF")
	)
	(segment
		(start 123.96978 -118.007638)
		(end 123.96978 -116.042948)
		(width 0.12954)
		(layer "F.Cu")
		(net "P0V62_CPU1_RST_DDR_VREF")
	)
	(segment
		(start 123.994926 -118.032784)
		(end 123.96978 -118.007638)
		(width 0.12954)
		(layer "F.Cu")
		(net "P0V62_CPU1_RST_DDR_VREF")
	)
	(segment
		(start 123.994926 -121.696734)
		(end 122.978926 -121.696734)
		(width 0.12954)
		(layer "F.Cu")
		(net "P0V62_CPU1_RST_DDR_VREF")
	)
	(segment
		(start 122.978926 -120.426734)
		(end 123.994926 -119.410734)
		(width 0.12954)
		(layer "F.Cu")
		(net "P0V62_CPU1_RST_DDR_VREF")
	)
	(segment
		(start 123.994926 -119.410734)
		(end 123.994926 -118.032784)
		(width 0.12954)
		(layer "F.Cu")
		(net "P0V62_CPU1_RST_DDR_VREF")
	)
	(segment
		(start 122.978926 -121.696734)
		(end 122.978926 -120.426734)
		(width 0.12954)
		(layer "F.Cu")
		(net "P0V62_CPU1_RST_DDR_VREF")
	)
	(via
		(at 123.994926 -118.032784)
		(size 0.762)
		(drill 0.381)
		(layers "F.Cu" "B.Cu")
		(net "P0V62_CPU1_RST_DDR_VREF")
	)
	(segment
		(start 113.67008 -121.732548)
		(end 113.67008 -120.462548)
		(width 0.12954)
		(layer "F.Cu")
		(net "P0V62_CPU0_RST_DDR_VREF")
	)
	(segment
		(start 113.67008 -120.462548)
		(end 114.68608 -119.446548)
		(width 0.12954)
		(layer "F.Cu")
		(net "P0V62_CPU0_RST_DDR_VREF")
	)
	(segment
		(start 114.68608 -121.732548)
		(end 113.67008 -121.732548)
		(width 0.12954)
		(layer "F.Cu")
		(net "P0V62_CPU0_RST_DDR_VREF")
	)
	(segment
		(start 114.68608 -118.068598)
		(end 114.660934 -118.043452)
		(width 0.12954)
		(layer "F.Cu")
		(net "P0V62_CPU0_RST_DDR_VREF")
	)
	(segment
		(start 114.660934 -118.043452)
		(end 114.660934 -116.078762)
		(width 0.12954)
		(layer "F.Cu")
		(net "P0V62_CPU0_RST_DDR_VREF")
	)
	(segment
		(start 114.68608 -119.446548)
		(end 114.68608 -118.068598)
		(width 0.12954)
		(layer "F.Cu")
		(net "P0V62_CPU0_RST_DDR_VREF")
	)
	(via
		(at 114.68608 -118.068598)
		(size 0.762)
		(drill 0.381)
		(layers "F.Cu" "B.Cu")
		(net "P0V62_CPU0_RST_DDR_VREF")
	)
	(segment
		(start 186.87288 -100.320348)
		(end 185.85688 -101.336348)
		(width 0.12954)
		(layer "F.Cu")
		(net "H_CPU_RMCA_LVC2_R2_N")
	)
	(segment
		(start 186.87288 -98.135948)
		(end 186.87288 -100.320348)
		(width 0.12954)
		(layer "F.Cu")
		(net "H_CPU_RMCA_LVC2_R2_N")
	)
	(segment
		(start 185.85688 -101.336348)
		(end 185.85688 -104.474264)
		(width 0.12954)
		(layer "F.Cu")
		(net "H_CPU_RMCA_LVC2_R2_N")
	)
	(segment
		(start 185.85688 -104.474264)
		(end 185.355738 -104.975406)
		(width 0.12954)
		(layer "F.Cu")
		(net "H_CPU_RMCA_LVC2_R2_N")
	)
	(segment
		(start 187.50788 -97.500948)
		(end 186.87288 -98.135948)
		(width 0.12954)
		(layer "F.Cu")
		(net "H_CPU_RMCA_LVC2_R2_N")
	)
	(via
		(at 187.50788 -97.500948)
		(size 0.508)
		(drill 0.254)
		(layers "F.Cu" "B.Cu")
		(net "H_CPU_RMCA_LVC2_R2_N")
	)
	(via
		(at 115.57 -86.451948)
		(size 0.762)
		(drill 0.254)
		(layers "F.Cu" "B.Cu")
		(net "H_CPU_RMCA_LVC2_R2_N")
	)
	(segment
		(start 115.316 -86.705948)
		(end 114.82705 -86.705948)
		(width 0.12954)
		(layer "B.Cu")
		(net "H_CPU_RMCA_LVC2_R2_N")
	)
	(segment
		(start 115.57 -86.451948)
		(end 115.316 -86.705948)
		(width 0.12954)
		(layer "B.Cu")
		(net "H_CPU_RMCA_LVC2_R2_N")
	)
	(segment
		(start 182.372 -92.5068)
		(end 182.372 -92.3036)
		(width 0.127)
		(layer "In15.Cu")
		(net "H_CPU_RMCA_LVC2_R2_N")
	)
	(segment
		(start 155.048966 -92.2528)
		(end 145.943574 -83.147408)
		(width 0.127)
		(layer "In15.Cu")
		(net "H_CPU_RMCA_LVC2_R2_N")
	)
	(segment
		(start 184.4294 -94.0562)
		(end 183.9214 -94.0562)
		(width 0.127)
		(layer "In15.Cu")
		(net "H_CPU_RMCA_LVC2_R2_N")
	)
	(segment
		(start 128.462532 -82.548476)
		(end 126.2888 -84.722208)
		(width 0.127)
		(layer "In15.Cu")
		(net "H_CPU_RMCA_LVC2_R2_N")
	)
	(segment
		(start 145.943574 -83.147408)
		(end 140.449046 -80.871568)
		(width 0.127)
		(layer "In15.Cu")
		(net "H_CPU_RMCA_LVC2_R2_N")
	)
	(segment
		(start 125.44044 -86.06028)
		(end 119.76608 -86.06028)
		(width 0.127)
		(layer "In15.Cu")
		(net "H_CPU_RMCA_LVC2_R2_N")
	)
	(segment
		(start 169.7736 -92.2528)
		(end 155.048966 -92.2528)
		(width 0.127)
		(layer "In15.Cu")
		(net "H_CPU_RMCA_LVC2_R2_N")
	)
	(segment
		(start 183.9214 -94.0562)
		(end 182.372 -92.5068)
		(width 0.127)
		(layer "In15.Cu")
		(net "H_CPU_RMCA_LVC2_R2_N")
	)
	(segment
		(start 180.9496 -90.8812)
		(end 171.1452 -90.8812)
		(width 0.127)
		(layer "In15.Cu")
		(net "H_CPU_RMCA_LVC2_R2_N")
	)
	(segment
		(start 126.2888 -84.722208)
		(end 126.2888 -85.21192)
		(width 0.127)
		(layer "In15.Cu")
		(net "H_CPU_RMCA_LVC2_R2_N")
	)
	(segment
		(start 182.372 -92.3036)
		(end 180.9496 -90.8812)
		(width 0.127)
		(layer "In15.Cu")
		(net "H_CPU_RMCA_LVC2_R2_N")
	)
	(segment
		(start 185.274966 -94.901766)
		(end 184.4294 -94.0562)
		(width 0.127)
		(layer "In15.Cu")
		(net "H_CPU_RMCA_LVC2_R2_N")
	)
	(segment
		(start 187.50788 -97.500948)
		(end 187.035948 -97.500948)
		(width 0.127)
		(layer "In15.Cu")
		(net "H_CPU_RMCA_LVC2_R2_N")
	)
	(segment
		(start 116.081048 -85.9409)
		(end 115.57 -86.451948)
		(width 0.127)
		(layer "In15.Cu")
		(net "H_CPU_RMCA_LVC2_R2_N")
	)
	(segment
		(start 126.2888 -85.21192)
		(end 125.44044 -86.06028)
		(width 0.127)
		(layer "In15.Cu")
		(net "H_CPU_RMCA_LVC2_R2_N")
	)
	(segment
		(start 132.511038 -80.871568)
		(end 128.462532 -82.548476)
		(width 0.127)
		(layer "In15.Cu")
		(net "H_CPU_RMCA_LVC2_R2_N")
	)
	(segment
		(start 119.6467 -85.9409)
		(end 116.081048 -85.9409)
		(width 0.127)
		(layer "In15.Cu")
		(net "H_CPU_RMCA_LVC2_R2_N")
	)
	(segment
		(start 119.76608 -86.06028)
		(end 119.6467 -85.9409)
		(width 0.127)
		(layer "In15.Cu")
		(net "H_CPU_RMCA_LVC2_R2_N")
	)
	(segment
		(start 140.449046 -80.871568)
		(end 132.511038 -80.871568)
		(width 0.127)
		(layer "In15.Cu")
		(net "H_CPU_RMCA_LVC2_R2_N")
	)
	(segment
		(start 185.274966 -95.739966)
		(end 185.274966 -94.901766)
		(width 0.127)
		(layer "In15.Cu")
		(net "H_CPU_RMCA_LVC2_R2_N")
	)
	(segment
		(start 171.1452 -90.8812)
		(end 169.7736 -92.2528)
		(width 0.127)
		(layer "In15.Cu")
		(net "H_CPU_RMCA_LVC2_R2_N")
	)
	(segment
		(start 187.035948 -97.500948)
		(end 185.274966 -95.739966)
		(width 0.127)
		(layer "In15.Cu")
		(net "H_CPU_RMCA_LVC2_R2_N")
	)
	(segment
		(start 114.427 -91.150948)
		(end 114.569748 -91.293696)
		(width 0.12954)
		(layer "F.Cu")
		(net "H_CPU_RMCA_LVC2_R1_N")
	)
	(segment
		(start 114.569748 -91.293696)
		(end 114.569748 -92.583762)
		(width 0.12954)
		(layer "F.Cu")
		(net "H_CPU_RMCA_LVC2_R1_N")
	)
	(via
		(at 114.427 -91.150948)
		(size 0.508)
		(drill 0.254)
		(layers "F.Cu" "B.Cu")
		(net "H_CPU_RMCA_LVC2_R1_N")
	)
	(segment
		(start 114.427 -91.150948)
		(end 114.56162 -91.016328)
		(width 0.12954)
		(layer "B.Cu")
		(net "H_CPU_RMCA_LVC2_R1_N")
	)
	(segment
		(start 114.02695 -87.213948)
		(end 114.02695 -86.705948)
		(width 0.12954)
		(layer "B.Cu")
		(net "H_CPU_RMCA_LVC2_R1_N")
	)
	(segment
		(start 114.56162 -91.016328)
		(end 114.56162 -87.748618)
		(width 0.12954)
		(layer "B.Cu")
		(net "H_CPU_RMCA_LVC2_R1_N")
	)
	(segment
		(start 114.56162 -87.748618)
		(end 114.02695 -87.213948)
		(width 0.12954)
		(layer "B.Cu")
		(net "H_CPU_RMCA_LVC2_R1_N")
	)
	(segment
		(start 147.479766 -94.207584)
		(end 147.479766 -93.117416)
		(width 0.12954)
		(layer "F.Cu")
		(net "H_CPU_ERR2_LVC2_R_N")
	)
	(segment
		(start 147.385278 -93.022928)
		(end 146.959828 -93.022928)
		(width 0.12954)
		(layer "F.Cu")
		(net "H_CPU_ERR2_LVC2_R_N")
	)
	(segment
		(start 147.479766 -94.207584)
		(end 146.529552 -94.207584)
		(width 0.12954)
		(layer "F.Cu")
		(net "H_CPU_ERR2_LVC2_R_N")
	)
	(segment
		(start 146.529552 -94.207584)
		(end 145.79346 -93.471492)
		(width 0.12954)
		(layer "F.Cu")
		(net "H_CPU_ERR2_LVC2_R_N")
	)
	(segment
		(start 145.67027 -93.022928)
		(end 146.959828 -93.022928)
		(width 0.12954)
		(layer "F.Cu")
		(net "H_CPU_ERR2_LVC2_R_N")
	)
	(segment
		(start 142.506954 -93.471492)
		(end 142.30604 -93.672406)
		(width 0.12954)
		(layer "F.Cu")
		(net "H_CPU_ERR2_LVC2_R_N")
	)
	(segment
		(start 145.65884 -93.034358)
		(end 145.67027 -93.022928)
		(width 0.12954)
		(layer "F.Cu")
		(net "H_CPU_ERR2_LVC2_R_N")
	)
	(segment
		(start 142.30604 -93.672406)
		(end 142.30604 -94.887542)
		(width 0.12954)
		(layer "F.Cu")
		(net "H_CPU_ERR2_LVC2_R_N")
	)
	(segment
		(start 147.479766 -93.117416)
		(end 147.385278 -93.022928)
		(width 0.12954)
		(layer "F.Cu")
		(net "H_CPU_ERR2_LVC2_R_N")
	)
	(segment
		(start 145.79346 -93.471492)
		(end 142.506954 -93.471492)
		(width 0.12954)
		(layer "F.Cu")
		(net "H_CPU_ERR2_LVC2_R_N")
	)
	(via
		(at 147.479766 -94.207584)
		(size 0.762)
		(drill 0.381)
		(layers "F.Cu" "B.Cu")
		(net "H_CPU_ERR2_LVC2_R_N")
	)
	(segment
		(start 182.155592 -107.375452)
		(end 182.555642 -106.975402)
		(width 0.12954)
		(layer "F.Cu")
		(net "H_CPU_ERR2_LVC2_N")
	)
	(segment
		(start 148.86178 -89.484708)
		(end 147.10156 -89.484708)
		(width 0.12954)
		(layer "F.Cu")
		(net "H_CPU_ERR2_LVC2_N")
	)
	(segment
		(start 147.10156 -89.484708)
		(end 145.65884 -90.927428)
		(width 0.12954)
		(layer "F.Cu")
		(net "H_CPU_ERR2_LVC2_N")
	)
	(segment
		(start 145.65884 -90.927428)
		(end 145.65884 -92.234258)
		(width 0.12954)
		(layer "F.Cu")
		(net "H_CPU_ERR2_LVC2_N")
	)
	(via
		(at 148.86178 -89.484708)
		(size 0.508)
		(drill 0.254)
		(layers "F.Cu" "B.Cu")
		(net "H_CPU_ERR2_LVC2_N")
	)
	(via
		(at 182.555642 -106.975402)
		(size 0.4572)
		(drill 0.254)
		(layers "F.Cu" "B.Cu")
		(net "H_CPU_ERR2_LVC2_N")
	)
	(segment
		(start 156.635704 -94.364048)
		(end 177.89398 -94.364048)
		(width 0.127)
		(layer "In15.Cu")
		(net "H_CPU_ERR2_LVC2_N")
	)
	(segment
		(start 182.7403 -98.151188)
		(end 183.21782 -98.628708)
		(width 0.127)
		(layer "In15.Cu")
		(net "H_CPU_ERR2_LVC2_N")
	)
	(segment
		(start 182.9816 -105.377488)
		(end 182.9816 -106.549444)
		(width 0.127)
		(layer "In15.Cu")
		(net "H_CPU_ERR2_LVC2_N")
	)
	(segment
		(start 178.71694 -95.692468)
		(end 179.56022 -96.535748)
		(width 0.127)
		(layer "In15.Cu")
		(net "H_CPU_ERR2_LVC2_N")
	)
	(segment
		(start 148.86178 -89.484708)
		(end 150.2029 -89.484708)
		(width 0.127)
		(layer "In15.Cu")
		(net "H_CPU_ERR2_LVC2_N")
	)
	(segment
		(start 151.55164 -90.833448)
		(end 151.55164 -93.254576)
		(width 0.127)
		(layer "In15.Cu")
		(net "H_CPU_ERR2_LVC2_N")
	)
	(segment
		(start 183.21782 -98.628708)
		(end 183.21782 -105.141268)
		(width 0.127)
		(layer "In15.Cu")
		(net "H_CPU_ERR2_LVC2_N")
	)
	(segment
		(start 182.9816 -106.549444)
		(end 182.555642 -106.975402)
		(width 0.127)
		(layer "In15.Cu")
		(net "H_CPU_ERR2_LVC2_N")
	)
	(segment
		(start 179.56022 -96.535748)
		(end 180.6448 -96.535748)
		(width 0.127)
		(layer "In15.Cu")
		(net "H_CPU_ERR2_LVC2_N")
	)
	(segment
		(start 178.71694 -95.187008)
		(end 178.71694 -95.692468)
		(width 0.127)
		(layer "In15.Cu")
		(net "H_CPU_ERR2_LVC2_N")
	)
	(segment
		(start 151.55164 -93.254576)
		(end 153.925016 -95.627952)
		(width 0.127)
		(layer "In15.Cu")
		(net "H_CPU_ERR2_LVC2_N")
	)
	(segment
		(start 182.26024 -98.151188)
		(end 182.7403 -98.151188)
		(width 0.127)
		(layer "In15.Cu")
		(net "H_CPU_ERR2_LVC2_N")
	)
	(segment
		(start 153.925016 -95.627952)
		(end 155.3718 -95.627952)
		(width 0.127)
		(layer "In15.Cu")
		(net "H_CPU_ERR2_LVC2_N")
	)
	(segment
		(start 183.21782 -105.141268)
		(end 182.9816 -105.377488)
		(width 0.127)
		(layer "In15.Cu")
		(net "H_CPU_ERR2_LVC2_N")
	)
	(segment
		(start 155.3718 -95.627952)
		(end 156.635704 -94.364048)
		(width 0.127)
		(layer "In15.Cu")
		(net "H_CPU_ERR2_LVC2_N")
	)
	(segment
		(start 177.89398 -94.364048)
		(end 178.71694 -95.187008)
		(width 0.127)
		(layer "In15.Cu")
		(net "H_CPU_ERR2_LVC2_N")
	)
	(segment
		(start 180.6448 -96.535748)
		(end 182.26024 -98.151188)
		(width 0.127)
		(layer "In15.Cu")
		(net "H_CPU_ERR2_LVC2_N")
	)
	(segment
		(start 150.2029 -89.484708)
		(end 151.55164 -90.833448)
		(width 0.127)
		(layer "In15.Cu")
		(net "H_CPU_ERR2_LVC2_N")
	)
	(segment
		(start 141.60246 -91.930728)
		(end 142.329662 -91.930728)
		(width 0.12954)
		(layer "F.Cu")
		(net "H_CPU_ERR1_LVC2_R_N")
	)
	(segment
		(start 141.60246 -92.966794)
		(end 141.006068 -93.563186)
		(width 0.12954)
		(layer "F.Cu")
		(net "H_CPU_ERR1_LVC2_R_N")
	)
	(segment
		(start 141.60246 -91.930728)
		(end 141.60246 -92.966794)
		(width 0.12954)
		(layer "F.Cu")
		(net "H_CPU_ERR1_LVC2_R_N")
	)
	(segment
		(start 142.329662 -91.930728)
		(end 143.433292 -93.034358)
		(width 0.12954)
		(layer "F.Cu")
		(net "H_CPU_ERR1_LVC2_R_N")
	)
	(segment
		(start 141.006068 -93.563186)
		(end 141.006068 -94.887542)
		(width 0.12954)
		(layer "F.Cu")
		(net "H_CPU_ERR1_LVC2_R_N")
	)
	(segment
		(start 144.61236 -93.034358)
		(end 143.433292 -93.034358)
		(width 0.12954)
		(layer "F.Cu")
		(net "H_CPU_ERR1_LVC2_R_N")
	)
	(via
		(at 141.60246 -91.930728)
		(size 0.762)
		(drill 0.381)
		(layers "F.Cu" "B.Cu")
		(net "H_CPU_ERR1_LVC2_R_N")
	)
	(segment
		(start 144.61236 -89.220548)
		(end 144.61236 -92.234258)
		(width 0.12954)
		(layer "F.Cu")
		(net "H_CPU_ERR1_LVC2_N")
	)
	(segment
		(start 182.155592 -108.175552)
		(end 182.555642 -107.775502)
		(width 0.12954)
		(layer "F.Cu")
		(net "H_CPU_ERR1_LVC2_N")
	)
	(segment
		(start 145.24482 -88.588088)
		(end 144.61236 -89.220548)
		(width 0.12954)
		(layer "F.Cu")
		(net "H_CPU_ERR1_LVC2_N")
	)
	(via
		(at 145.24482 -88.588088)
		(size 0.508)
		(drill 0.254)
		(layers "F.Cu" "B.Cu")
		(net "H_CPU_ERR1_LVC2_N")
	)
	(via
		(at 182.555642 -107.775502)
		(size 0.4572)
		(drill 0.254)
		(layers "F.Cu" "B.Cu")
		(net "H_CPU_ERR1_LVC2_N")
	)
	(segment
		(start 182.339234 -107.775502)
		(end 182.555642 -107.775502)
		(width 0.127)
		(layer "In15.Cu")
		(net "H_CPU_ERR1_LVC2_N")
	)
	(segment
		(start 180.1495 -100.942648)
		(end 180.5559 -101.349048)
		(width 0.127)
		(layer "In15.Cu")
		(net "H_CPU_ERR1_LVC2_N")
	)
	(segment
		(start 181.38648 -107.373928)
		(end 181.93766 -107.373928)
		(width 0.127)
		(layer "In15.Cu")
		(net "H_CPU_ERR1_LVC2_N")
	)
	(segment
		(start 158.184596 -97.685352)
		(end 158.76143 -97.108518)
		(width 0.127)
		(layer "In15.Cu")
		(net "H_CPU_ERR1_LVC2_N")
	)
	(segment
		(start 175.437038 -97.386648)
		(end 177.096166 -97.386648)
		(width 0.127)
		(layer "In15.Cu")
		(net "H_CPU_ERR1_LVC2_N")
	)
	(segment
		(start 175.360838 -97.310448)
		(end 175.437038 -97.386648)
		(width 0.127)
		(layer "In15.Cu")
		(net "H_CPU_ERR1_LVC2_N")
	)
	(segment
		(start 144.83842 -88.994488)
		(end 144.83842 -90.762328)
		(width 0.127)
		(layer "In15.Cu")
		(net "H_CPU_ERR1_LVC2_N")
	)
	(segment
		(start 144.83842 -90.762328)
		(end 151.761444 -97.685352)
		(width 0.127)
		(layer "In15.Cu")
		(net "H_CPU_ERR1_LVC2_N")
	)
	(segment
		(start 177.096166 -97.386648)
		(end 180.1495 -100.439982)
		(width 0.127)
		(layer "In15.Cu")
		(net "H_CPU_ERR1_LVC2_N")
	)
	(segment
		(start 158.76143 -97.108518)
		(end 171.987972 -97.108518)
		(width 0.127)
		(layer "In15.Cu")
		(net "H_CPU_ERR1_LVC2_N")
	)
	(segment
		(start 151.761444 -97.685352)
		(end 158.184596 -97.685352)
		(width 0.127)
		(layer "In15.Cu")
		(net "H_CPU_ERR1_LVC2_N")
	)
	(segment
		(start 171.987972 -97.108518)
		(end 172.189902 -97.310448)
		(width 0.127)
		(layer "In15.Cu")
		(net "H_CPU_ERR1_LVC2_N")
	)
	(segment
		(start 145.24482 -88.588088)
		(end 144.83842 -88.994488)
		(width 0.127)
		(layer "In15.Cu")
		(net "H_CPU_ERR1_LVC2_N")
	)
	(segment
		(start 180.1495 -100.439982)
		(end 180.1495 -100.942648)
		(width 0.127)
		(layer "In15.Cu")
		(net "H_CPU_ERR1_LVC2_N")
	)
	(segment
		(start 181.93766 -107.373928)
		(end 182.339234 -107.775502)
		(width 0.127)
		(layer "In15.Cu")
		(net "H_CPU_ERR1_LVC2_N")
	)
	(segment
		(start 180.5559 -106.543348)
		(end 181.38648 -107.373928)
		(width 0.127)
		(layer "In15.Cu")
		(net "H_CPU_ERR1_LVC2_N")
	)
	(segment
		(start 172.189902 -97.310448)
		(end 175.360838 -97.310448)
		(width 0.127)
		(layer "In15.Cu")
		(net "H_CPU_ERR1_LVC2_N")
	)
	(segment
		(start 180.5559 -101.349048)
		(end 180.5559 -106.543348)
		(width 0.127)
		(layer "In15.Cu")
		(net "H_CPU_ERR1_LVC2_N")
	)
	(segment
		(start 150.17242 -88.725248)
		(end 148.59 -87.142828)
		(width 0.12954)
		(layer "F.Cu")
		(net "H_CPU_ERR0_LVC2_R_N")
	)
	(segment
		(start 140.23086 -90.919808)
		(end 140.23086 -92.212668)
		(width 0.12954)
		(layer "F.Cu")
		(net "H_CPU_ERR0_LVC2_R_N")
	)
	(segment
		(start 140.222732 -93.044518)
		(end 139.02182 -93.044518)
		(width 0.12954)
		(layer "F.Cu")
		(net "H_CPU_ERR0_LVC2_R_N")
	)
	(segment
		(start 139.7 -92.743528)
		(end 139.1412 -92.743528)
		(width 0.12954)
		(layer "F.Cu")
		(net "H_CPU_ERR0_LVC2_R_N")
	)
	(segment
		(start 148.59 -87.142828)
		(end 144.00784 -87.142828)
		(width 0.12954)
		(layer "F.Cu")
		(net "H_CPU_ERR0_LVC2_R_N")
	)
	(segment
		(start 139.1412 -92.743528)
		(end 139.02182 -92.862908)
		(width 0.12954)
		(layer "F.Cu")
		(net "H_CPU_ERR0_LVC2_R_N")
	)
	(segment
		(start 144.00784 -87.142828)
		(end 140.23086 -90.919808)
		(width 0.12954)
		(layer "F.Cu")
		(net "H_CPU_ERR0_LVC2_R_N")
	)
	(segment
		(start 140.356082 -93.177868)
		(end 140.222732 -93.044518)
		(width 0.12954)
		(layer "F.Cu")
		(net "H_CPU_ERR0_LVC2_R_N")
	)
	(segment
		(start 140.23086 -92.212668)
		(end 139.7 -92.743528)
		(width 0.12954)
		(layer "F.Cu")
		(net "H_CPU_ERR0_LVC2_R_N")
	)
	(segment
		(start 140.356082 -93.177868)
		(end 140.356082 -94.887542)
		(width 0.12954)
		(layer "F.Cu")
		(net "H_CPU_ERR0_LVC2_R_N")
	)
	(segment
		(start 150.17242 -92.291916)
		(end 150.17242 -88.725248)
		(width 0.12954)
		(layer "F.Cu")
		(net "H_CPU_ERR0_LVC2_R_N")
	)
	(segment
		(start 139.02182 -92.862908)
		(end 139.02182 -93.044518)
		(width 0.12954)
		(layer "F.Cu")
		(net "H_CPU_ERR0_LVC2_R_N")
	)
	(via
		(at 140.356082 -93.177868)
		(size 0.762)
		(drill 0.381)
		(layers "F.Cu" "B.Cu")
		(net "H_CPU_ERR0_LVC2_R_N")
	)
	(segment
		(start 182.155592 -108.975398)
		(end 182.555642 -108.575348)
		(width 0.12954)
		(layer "F.Cu")
		(net "H_CPU_ERR0_LVC2_N")
	)
	(segment
		(start 139.50188 -86.280498)
		(end 139.50188 -91.764358)
		(width 0.12954)
		(layer "F.Cu")
		(net "H_CPU_ERR0_LVC2_N")
	)
	(segment
		(start 139.50188 -91.764358)
		(end 139.02182 -92.244418)
		(width 0.12954)
		(layer "F.Cu")
		(net "H_CPU_ERR0_LVC2_N")
	)
	(via
		(at 139.50188 -86.280498)
		(size 0.508)
		(drill 0.254)
		(layers "F.Cu" "B.Cu")
		(net "H_CPU_ERR0_LVC2_N")
	)
	(via
		(at 182.555642 -108.575348)
		(size 0.4572)
		(drill 0.254)
		(layers "F.Cu" "B.Cu")
		(net "H_CPU_ERR0_LVC2_N")
	)
	(segment
		(start 145.29562 -96.360488)
		(end 139.50188 -90.566748)
		(width 0.127)
		(layer "In15.Cu")
		(net "H_CPU_ERR0_LVC2_N")
	)
	(segment
		(start 165.25748 -99.685348)
		(end 150.360888 -99.685348)
		(width 0.127)
		(layer "In15.Cu")
		(net "H_CPU_ERR0_LVC2_N")
	)
	(segment
		(start 178.8668 -107.953048)
		(end 178.8668 -105.664)
		(width 0.127)
		(layer "In15.Cu")
		(net "H_CPU_ERR0_LVC2_N")
	)
	(segment
		(start 179.0192 -105.5116)
		(end 179.0192 -105.2322)
		(width 0.127)
		(layer "In15.Cu")
		(net "H_CPU_ERR0_LVC2_N")
	)
	(segment
		(start 182.161942 -108.969048)
		(end 179.8828 -108.969048)
		(width 0.127)
		(layer "In15.Cu")
		(net "H_CPU_ERR0_LVC2_N")
	)
	(segment
		(start 175.270668 -100.467668)
		(end 166.0398 -100.467668)
		(width 0.127)
		(layer "In15.Cu")
		(net "H_CPU_ERR0_LVC2_N")
	)
	(segment
		(start 139.50188 -90.566748)
		(end 139.50188 -86.280498)
		(width 0.127)
		(layer "In15.Cu")
		(net "H_CPU_ERR0_LVC2_N")
	)
	(segment
		(start 176.62779 -100.921058)
		(end 175.724058 -100.921058)
		(width 0.127)
		(layer "In15.Cu")
		(net "H_CPU_ERR0_LVC2_N")
	)
	(segment
		(start 175.724058 -100.921058)
		(end 175.270668 -100.467668)
		(width 0.127)
		(layer "In15.Cu")
		(net "H_CPU_ERR0_LVC2_N")
	)
	(segment
		(start 178.8668 -105.664)
		(end 179.0192 -105.5116)
		(width 0.127)
		(layer "In15.Cu")
		(net "H_CPU_ERR0_LVC2_N")
	)
	(segment
		(start 179.0192 -105.2322)
		(end 177.81016 -104.02316)
		(width 0.127)
		(layer "In15.Cu")
		(net "H_CPU_ERR0_LVC2_N")
	)
	(segment
		(start 179.8828 -108.969048)
		(end 178.8668 -107.953048)
		(width 0.127)
		(layer "In15.Cu")
		(net "H_CPU_ERR0_LVC2_N")
	)
	(segment
		(start 150.360888 -99.685348)
		(end 147.036028 -96.360488)
		(width 0.127)
		(layer "In15.Cu")
		(net "H_CPU_ERR0_LVC2_N")
	)
	(segment
		(start 147.036028 -96.360488)
		(end 145.29562 -96.360488)
		(width 0.127)
		(layer "In15.Cu")
		(net "H_CPU_ERR0_LVC2_N")
	)
	(segment
		(start 177.81016 -102.103428)
		(end 176.62779 -100.921058)
		(width 0.127)
		(layer "In15.Cu")
		(net "H_CPU_ERR0_LVC2_N")
	)
	(segment
		(start 182.555642 -108.575348)
		(end 182.161942 -108.969048)
		(width 0.127)
		(layer "In15.Cu")
		(net "H_CPU_ERR0_LVC2_N")
	)
	(segment
		(start 166.0398 -100.467668)
		(end 165.25748 -99.685348)
		(width 0.127)
		(layer "In15.Cu")
		(net "H_CPU_ERR0_LVC2_N")
	)
	(segment
		(start 177.81016 -104.02316)
		(end 177.81016 -102.103428)
		(width 0.127)
		(layer "In15.Cu")
		(net "H_CPU_ERR0_LVC2_N")
	)
	(segment
		(start 185.355738 -105.775506)
		(end 185.755788 -105.375456)
		(width 0.12954)
		(layer "F.Cu")
		(net "H_CPU_CATERR_LVC2_R2_N")
	)
	(via
		(at 185.755788 -105.375456)
		(size 0.4572)
		(drill 0.254)
		(layers "F.Cu" "B.Cu")
		(net "H_CPU_CATERR_LVC2_R2_N")
	)
	(via
		(at 118.11 -86.451948)
		(size 0.762)
		(drill 0.254)
		(layers "F.Cu" "B.Cu")
		(net "H_CPU_CATERR_LVC2_R2_N")
	)
	(segment
		(start 117.856 -86.705948)
		(end 117.24005 -86.705948)
		(width 0.12954)
		(layer "B.Cu")
		(net "H_CPU_CATERR_LVC2_R2_N")
	)
	(segment
		(start 118.11 -86.451948)
		(end 117.856 -86.705948)
		(width 0.12954)
		(layer "B.Cu")
		(net "H_CPU_CATERR_LVC2_R2_N")
	)
	(segment
		(start 118.11 -86.451948)
		(end 118.11 -86.88324)
		(width 0.127)
		(layer "In15.Cu")
		(net "H_CPU_CATERR_LVC2_R2_N")
	)
	(segment
		(start 132.561076 -81.234788)
		(end 140.400532 -81.234788)
		(width 0.127)
		(layer "In15.Cu")
		(net "H_CPU_CATERR_LVC2_R2_N")
	)
	(segment
		(start 185.755788 -99.535234)
		(end 185.755788 -105.375456)
		(width 0.127)
		(layer "In15.Cu")
		(net "H_CPU_CATERR_LVC2_R2_N")
	)
	(segment
		(start 181.198266 -92.512134)
		(end 182.967376 -95.159576)
		(width 0.127)
		(layer "In15.Cu")
		(net "H_CPU_CATERR_LVC2_R2_N")
	)
	(segment
		(start 182.967376 -95.159576)
		(end 183.40832 -95.60052)
		(width 0.127)
		(layer "In15.Cu")
		(net "H_CPU_CATERR_LVC2_R2_N")
	)
	(segment
		(start 140.400532 -81.234788)
		(end 145.678144 -83.420966)
		(width 0.127)
		(layer "In15.Cu")
		(net "H_CPU_CATERR_LVC2_R2_N")
	)
	(segment
		(start 126.6952 -84.892388)
		(end 128.791208 -82.79638)
		(width 0.127)
		(layer "In15.Cu")
		(net "H_CPU_CATERR_LVC2_R2_N")
	)
	(segment
		(start 145.678144 -83.420966)
		(end 155.068778 -92.8116)
		(width 0.127)
		(layer "In15.Cu")
		(net "H_CPU_CATERR_LVC2_R2_N")
	)
	(segment
		(start 118.11 -86.88324)
		(end 118.237 -87.01024)
		(width 0.127)
		(layer "In15.Cu")
		(net "H_CPU_CATERR_LVC2_R2_N")
	)
	(segment
		(start 184.73039 -96.57969)
		(end 185.5724 -98.612706)
		(width 0.127)
		(layer "In15.Cu")
		(net "H_CPU_CATERR_LVC2_R2_N")
	)
	(segment
		(start 155.068778 -92.8116)
		(end 170.825922 -92.8116)
		(width 0.127)
		(layer "In15.Cu")
		(net "H_CPU_CATERR_LVC2_R2_N")
	)
	(segment
		(start 180.446426 -91.760294)
		(end 181.198266 -92.512134)
		(width 0.127)
		(layer "In15.Cu")
		(net "H_CPU_CATERR_LVC2_R2_N")
	)
	(segment
		(start 172.359574 -91.277948)
		(end 179.281836 -91.277948)
		(width 0.127)
		(layer "In15.Cu")
		(net "H_CPU_CATERR_LVC2_R2_N")
	)
	(segment
		(start 185.5724 -98.612706)
		(end 185.755788 -99.535234)
		(width 0.127)
		(layer "In15.Cu")
		(net "H_CPU_CATERR_LVC2_R2_N")
	)
	(segment
		(start 184.4421 -96.2914)
		(end 184.73039 -96.57969)
		(width 0.127)
		(layer "In15.Cu")
		(net "H_CPU_CATERR_LVC2_R2_N")
	)
	(segment
		(start 125.09754 -87.01024)
		(end 126.6952 -85.41258)
		(width 0.127)
		(layer "In15.Cu")
		(net "H_CPU_CATERR_LVC2_R2_N")
	)
	(segment
		(start 126.6952 -85.41258)
		(end 126.6952 -84.892388)
		(width 0.127)
		(layer "In15.Cu")
		(net "H_CPU_CATERR_LVC2_R2_N")
	)
	(segment
		(start 118.237 -87.01024)
		(end 125.09754 -87.01024)
		(width 0.127)
		(layer "In15.Cu")
		(net "H_CPU_CATERR_LVC2_R2_N")
	)
	(segment
		(start 183.40832 -95.60052)
		(end 184.4421 -96.2914)
		(width 0.127)
		(layer "In15.Cu")
		(net "H_CPU_CATERR_LVC2_R2_N")
	)
	(segment
		(start 128.791208 -82.79638)
		(end 132.561076 -81.234788)
		(width 0.127)
		(layer "In15.Cu")
		(net "H_CPU_CATERR_LVC2_R2_N")
	)
	(segment
		(start 170.825922 -92.8116)
		(end 172.359574 -91.277948)
		(width 0.127)
		(layer "In15.Cu")
		(net "H_CPU_CATERR_LVC2_R2_N")
	)
	(segment
		(start 179.281836 -91.277948)
		(end 180.446426 -91.760294)
		(width 0.127)
		(layer "In15.Cu")
		(net "H_CPU_CATERR_LVC2_R2_N")
	)
	(segment
		(start 115.99164 -91.229688)
		(end 115.86972 -91.351608)
		(width 0.12954)
		(layer "F.Cu")
		(net "H_CPU_CATERR_LVC2_R1_N")
	)
	(segment
		(start 115.86972 -91.351608)
		(end 115.86972 -92.583762)
		(width 0.12954)
		(layer "F.Cu")
		(net "H_CPU_CATERR_LVC2_R1_N")
	)
	(via
		(at 115.99164 -91.229688)
		(size 0.508)
		(drill 0.254)
		(layers "F.Cu" "B.Cu")
		(net "H_CPU_CATERR_LVC2_R1_N")
	)
	(segment
		(start 116.43995 -90.781378)
		(end 116.43995 -86.705948)
		(width 0.12954)
		(layer "B.Cu")
		(net "H_CPU_CATERR_LVC2_R1_N")
	)
	(segment
		(start 115.99164 -91.229688)
		(end 116.43995 -90.781378)
		(width 0.12954)
		(layer "B.Cu")
		(net "H_CPU_CATERR_LVC2_R1_N")
	)
	(segment
		(start 227.754688 -403.116542)
		(end 228.276658 -402.594572)
		(width 0.254)
		(layer "F.Cu")
		(net "HSC_VDD_R_4")
	)
	(segment
		(start 228.276658 -402.594572)
		(end 228.410008 -402.594572)
		(width 0.254)
		(layer "F.Cu")
		(net "HSC_VDD_R_4")
	)
	(segment
		(start 228.410008 -402.594572)
		(end 228.683312 -402.594572)
		(width 0.254)
		(layer "F.Cu")
		(net "HSC_VDD_R_4")
	)
	(segment
		(start 228.804978 -402.472906)
		(end 229.93858 -402.472906)
		(width 0.254)
		(layer "F.Cu")
		(net "HSC_VDD_R_4")
	)
	(segment
		(start 228.683312 -402.594572)
		(end 228.804978 -402.472906)
		(width 0.254)
		(layer "F.Cu")
		(net "HSC_VDD_R_4")
	)
	(via
		(at 227.754688 -403.116542)
		(size 0.508)
		(drill 0.254)
		(layers "F.Cu" "B.Cu")
		(net "HSC_VDD_R_4")
	)
	(segment
		(start 227.754688 -403.116542)
		(end 227.501958 -403.369272)
		(width 0.254)
		(layer "B.Cu")
		(net "HSC_VDD_R_4")
	)
	(segment
		(start 227.501958 -403.369272)
		(end 226.652328 -403.369272)
		(width 0.254)
		(layer "B.Cu")
		(net "HSC_VDD_R_4")
	)
	(segment
		(start 217.608658 -402.594572)
		(end 217.742008 -402.594572)
		(width 0.254)
		(layer "F.Cu")
		(net "HSC_VDD_R_3")
	)
	(segment
		(start 217.113358 -403.089872)
		(end 217.608658 -402.594572)
		(width 0.254)
		(layer "F.Cu")
		(net "HSC_VDD_R_3")
	)
	(segment
		(start 219.27058 -402.472906)
		(end 218.136978 -402.472906)
		(width 0.254)
		(layer "F.Cu")
		(net "HSC_VDD_R_3")
	)
	(segment
		(start 218.136978 -402.472906)
		(end 218.015312 -402.594572)
		(width 0.254)
		(layer "F.Cu")
		(net "HSC_VDD_R_3")
	)
	(segment
		(start 218.015312 -402.594572)
		(end 217.742008 -402.594572)
		(width 0.254)
		(layer "F.Cu")
		(net "HSC_VDD_R_3")
	)
	(via
		(at 217.113358 -403.089872)
		(size 0.508)
		(drill 0.254)
		(layers "F.Cu" "B.Cu")
		(net "HSC_VDD_R_3")
	)
	(segment
		(start 216.934542 -403.268688)
		(end 216.00541 -403.268688)
		(width 0.254)
		(layer "B.Cu")
		(net "HSC_VDD_R_3")
	)
	(segment
		(start 217.113358 -403.089872)
		(end 216.934542 -403.268688)
		(width 0.254)
		(layer "B.Cu")
		(net "HSC_VDD_R_3")
	)
	(segment
		(start 227.838 -408.887422)
		(end 228.475286 -408.250136)
		(width 0.1524)
		(layer "F.Cu")
		(net "HSC_SCREF_4")
	)
	(segment
		(start 229.751128 -404.472902)
		(end 229.92588 -404.472902)
		(width 0.1524)
		(layer "F.Cu")
		(net "HSC_SCREF_4")
	)
	(segment
		(start 228.475286 -408.250136)
		(end 228.475286 -406.536144)
		(width 0.1524)
		(layer "F.Cu")
		(net "HSC_SCREF_4")
	)
	(segment
		(start 228.475286 -406.536144)
		(end 229.400608 -405.610822)
		(width 0.1524)
		(layer "F.Cu")
		(net "HSC_SCREF_4")
	)
	(segment
		(start 229.400608 -404.823422)
		(end 229.751128 -404.472902)
		(width 0.1524)
		(layer "F.Cu")
		(net "HSC_SCREF_4")
	)
	(segment
		(start 229.400608 -405.610822)
		(end 229.400608 -404.823422)
		(width 0.1524)
		(layer "F.Cu")
		(net "HSC_SCREF_4")
	)
	(segment
		(start 227.133658 -408.887422)
		(end 227.838 -408.887422)
		(width 0.1524)
		(layer "F.Cu")
		(net "HSC_SCREF_4")
	)
	(via
		(at 228.475286 -406.536144)
		(size 0.762)
		(drill 0.381)
		(layers "F.Cu" "B.Cu")
		(net "HSC_SCREF_4")
	)
	(segment
		(start 217.807286 -406.536144)
		(end 218.732608 -405.610822)
		(width 0.1524)
		(layer "F.Cu")
		(net "HSC_SCREF_3")
	)
	(segment
		(start 217.807286 -408.250136)
		(end 217.807286 -406.536144)
		(width 0.1524)
		(layer "F.Cu")
		(net "HSC_SCREF_3")
	)
	(segment
		(start 219.083128 -404.472902)
		(end 219.25788 -404.472902)
		(width 0.1524)
		(layer "F.Cu")
		(net "HSC_SCREF_3")
	)
	(segment
		(start 216.465658 -408.887422)
		(end 217.17 -408.887422)
		(width 0.1524)
		(layer "F.Cu")
		(net "HSC_SCREF_3")
	)
	(segment
		(start 217.17 -408.887422)
		(end 217.807286 -408.250136)
		(width 0.1524)
		(layer "F.Cu")
		(net "HSC_SCREF_3")
	)
	(segment
		(start 218.732608 -404.823422)
		(end 219.083128 -404.472902)
		(width 0.1524)
		(layer "F.Cu")
		(net "HSC_SCREF_3")
	)
	(segment
		(start 218.732608 -405.610822)
		(end 218.732608 -404.823422)
		(width 0.1524)
		(layer "F.Cu")
		(net "HSC_SCREF_3")
	)
	(via
		(at 217.807286 -406.536144)
		(size 0.762)
		(drill 0.381)
		(layers "F.Cu" "B.Cu")
		(net "HSC_SCREF_3")
	)
	(segment
		(start 236.131608 -404.721822)
		(end 235.750608 -405.102822)
		(width 0.1524)
		(layer "F.Cu")
		(net "HSC_MODE_4")
	)
	(segment
		(start 235.120688 -404.472902)
		(end 234.426252 -404.472902)
		(width 0.1524)
		(layer "F.Cu")
		(net "HSC_MODE_4")
	)
	(segment
		(start 235.750608 -405.102822)
		(end 235.120688 -404.472902)
		(width 0.1524)
		(layer "F.Cu")
		(net "HSC_MODE_4")
	)
	(segment
		(start 237.001558 -404.721822)
		(end 236.131608 -404.721822)
		(width 0.1524)
		(layer "F.Cu")
		(net "HSC_MODE_4")
	)
	(via
		(at 235.750608 -405.102822)
		(size 0.762)
		(drill 0.381)
		(layers "F.Cu" "B.Cu")
		(net "HSC_MODE_4")
	)
	(segment
		(start 223.983804 -404.472902)
		(end 223.758252 -404.472902)
		(width 0.1524)
		(layer "F.Cu")
		(net "HSC_MODE_3")
	)
	(segment
		(start 224.227898 -406.762712)
		(end 224.227898 -404.716996)
		(width 0.1524)
		(layer "F.Cu")
		(net "HSC_MODE_3")
	)
	(segment
		(start 226.333558 -407.871422)
		(end 225.336608 -407.871422)
		(width 0.1524)
		(layer "F.Cu")
		(net "HSC_MODE_3")
	)
	(segment
		(start 225.336608 -407.871422)
		(end 224.955608 -407.490422)
		(width 0.1524)
		(layer "F.Cu")
		(net "HSC_MODE_3")
	)
	(segment
		(start 224.955608 -407.490422)
		(end 224.227898 -406.762712)
		(width 0.1524)
		(layer "F.Cu")
		(net "HSC_MODE_3")
	)
	(segment
		(start 224.227898 -404.716996)
		(end 223.983804 -404.472902)
		(width 0.1524)
		(layer "F.Cu")
		(net "HSC_MODE_3")
	)
	(via
		(at 224.955608 -407.490422)
		(size 0.762)
		(drill 0.381)
		(layers "F.Cu" "B.Cu")
		(net "HSC_MODE_3")
	)
	(segment
		(start 235.877608 -403.705822)
		(end 235.750608 -403.832822)
		(width 0.1524)
		(layer "F.Cu")
		(net "HSC_FLT_TYPE_4")
	)
	(segment
		(start 235.750608 -403.832822)
		(end 235.39069 -403.472904)
		(width 0.1524)
		(layer "F.Cu")
		(net "HSC_FLT_TYPE_4")
	)
	(segment
		(start 235.39069 -403.472904)
		(end 234.413552 -403.472904)
		(width 0.1524)
		(layer "F.Cu")
		(net "HSC_FLT_TYPE_4")
	)
	(segment
		(start 237.001558 -403.705822)
		(end 235.877608 -403.705822)
		(width 0.1524)
		(layer "F.Cu")
		(net "HSC_FLT_TYPE_4")
	)
	(via
		(at 235.750608 -403.832822)
		(size 0.762)
		(drill 0.381)
		(layers "F.Cu" "B.Cu")
		(net "HSC_FLT_TYPE_4")
	)
	(segment
		(start 224.955862 -404.514558)
		(end 223.914208 -403.472904)
		(width 0.1524)
		(layer "F.Cu")
		(net "HSC_FLT_TYPE_3")
	)
	(segment
		(start 225.717862 -406.855422)
		(end 224.955862 -406.093422)
		(width 0.1524)
		(layer "F.Cu")
		(net "HSC_FLT_TYPE_3")
	)
	(segment
		(start 223.914208 -403.472904)
		(end 223.745552 -403.472904)
		(width 0.1524)
		(layer "F.Cu")
		(net "HSC_FLT_TYPE_3")
	)
	(segment
		(start 226.333558 -406.855422)
		(end 225.717862 -406.855422)
		(width 0.1524)
		(layer "F.Cu")
		(net "HSC_FLT_TYPE_3")
	)
	(segment
		(start 224.955862 -406.093422)
		(end 224.955862 -404.514558)
		(width 0.1524)
		(layer "F.Cu")
		(net "HSC_FLT_TYPE_3")
	)
	(via
		(at 224.955862 -406.093422)
		(size 0.762)
		(drill 0.381)
		(layers "F.Cu" "B.Cu")
		(net "HSC_FLT_TYPE_3")
	)
	(segment
		(start 234.94365 -401.97278)
		(end 234.413552 -401.97278)
		(width 0.1524)
		(layer "F.Cu")
		(net "HSC_D_OC_4")
	)
	(segment
		(start 236.258608 -401.673822)
		(end 235.750608 -401.165822)
		(width 0.1524)
		(layer "F.Cu")
		(net "HSC_D_OC_4")
	)
	(segment
		(start 235.750608 -401.165822)
		(end 234.94365 -401.97278)
		(width 0.1524)
		(layer "F.Cu")
		(net "HSC_D_OC_4")
	)
	(segment
		(start 237.001558 -401.673822)
		(end 236.258608 -401.673822)
		(width 0.1524)
		(layer "F.Cu")
		(net "HSC_D_OC_4")
	)
	(via
		(at 235.750608 -401.165822)
		(size 0.762)
		(drill 0.381)
		(layers "F.Cu" "B.Cu")
		(net "HSC_D_OC_4")
	)
	(segment
		(start 224.955608 -401.165822)
		(end 224.14865 -401.97278)
		(width 0.1524)
		(layer "F.Cu")
		(net "HSC_D_OC_3")
	)
	(segment
		(start 225.108008 -400.759422)
		(end 224.955608 -400.911822)
		(width 0.1524)
		(layer "F.Cu")
		(net "HSC_D_OC_3")
	)
	(segment
		(start 224.14865 -401.97278)
		(end 223.745552 -401.97278)
		(width 0.1524)
		(layer "F.Cu")
		(net "HSC_D_OC_3")
	)
	(segment
		(start 226.333558 -400.759422)
		(end 225.108008 -400.759422)
		(width 0.1524)
		(layer "F.Cu")
		(net "HSC_D_OC_3")
	)
	(segment
		(start 224.955608 -400.911822)
		(end 224.955608 -401.165822)
		(width 0.1524)
		(layer "F.Cu")
		(net "HSC_D_OC_3")
	)
	(via
		(at 224.955608 -400.911822)
		(size 0.762)
		(drill 0.381)
		(layers "F.Cu" "B.Cu")
		(net "HSC_D_OC_3")
	)
	(segment
		(start 228.95687 -400.975322)
		(end 228.575108 -400.975322)
		(width 0.1524)
		(layer "F.Cu")
		(net "HSC_CS_4")
	)
	(segment
		(start 229.93858 -401.472908)
		(end 229.454456 -401.472908)
		(width 0.1524)
		(layer "F.Cu")
		(net "HSC_CS_4")
	)
	(segment
		(start 229.454456 -401.472908)
		(end 228.95687 -400.975322)
		(width 0.1524)
		(layer "F.Cu")
		(net "HSC_CS_4")
	)
	(segment
		(start 228.575108 -400.975322)
		(end 227.775008 -401.775422)
		(width 0.1524)
		(layer "F.Cu")
		(net "HSC_CS_4")
	)
	(segment
		(start 227.775008 -401.775422)
		(end 227.133658 -401.775422)
		(width 0.1524)
		(layer "F.Cu")
		(net "HSC_CS_4")
	)
	(via
		(at 228.575108 -400.975322)
		(size 0.762)
		(drill 0.381)
		(layers "F.Cu" "B.Cu")
		(net "HSC_CS_4")
	)
	(segment
		(start 219.27058 -401.472908)
		(end 218.786456 -401.472908)
		(width 0.1524)
		(layer "F.Cu")
		(net "HSC_CS_3")
	)
	(segment
		(start 217.907108 -400.975322)
		(end 217.107008 -401.775422)
		(width 0.1524)
		(layer "F.Cu")
		(net "HSC_CS_3")
	)
	(segment
		(start 218.28887 -400.975322)
		(end 217.907108 -400.975322)
		(width 0.1524)
		(layer "F.Cu")
		(net "HSC_CS_3")
	)
	(segment
		(start 218.786456 -401.472908)
		(end 218.28887 -400.975322)
		(width 0.1524)
		(layer "F.Cu")
		(net "HSC_CS_3")
	)
	(segment
		(start 217.107008 -401.775422)
		(end 216.465658 -401.775422)
		(width 0.1524)
		(layer "F.Cu")
		(net "HSC_CS_3")
	)
	(via
		(at 217.907108 -400.975322)
		(size 0.762)
		(drill 0.381)
		(layers "F.Cu" "B.Cu")
		(net "HSC_CS_3")
	)
	(segment
		(start 202.3872 -73.3044)
		(end 203.3524 -72.3392)
		(width 0.12954)
		(layer "F.Cu")
		(net "HP_LVC3_E1S_0_HSC_PWRGD")
	)
	(segment
		(start 254.361442 -53.810408)
		(end 254.361442 -54.43728)
		(width 0.12954)
		(layer "F.Cu")
		(net "HP_LVC3_E1S_0_HSC_PWRGD")
	)
	(segment
		(start 251.82195 -37.667946)
		(end 251.8029 -37.648896)
		(width 0.12954)
		(layer "F.Cu")
		(net "HP_LVC3_E1S_0_HSC_PWRGD")
	)
	(segment
		(start 254.15494 -53.603906)
		(end 254.361442 -53.810408)
		(width 0.12954)
		(layer "F.Cu")
		(net "HP_LVC3_E1S_0_HSC_PWRGD")
	)
	(segment
		(start 188.7474 -66.4972)
		(end 188.7474 -71.9582)
		(width 0.12954)
		(layer "F.Cu")
		(net "HP_LVC3_E1S_0_HSC_PWRGD")
	)
	(segment
		(start 186.69254 -63.3222)
		(end 190.3476 -63.3222)
		(width 0.12954)
		(layer "F.Cu")
		(net "HP_LVC3_E1S_0_HSC_PWRGD")
	)
	(segment
		(start 186.563 -86.0552)
		(end 186.563 -63.45174)
		(width 0.12954)
		(layer "F.Cu")
		(net "HP_LVC3_E1S_0_HSC_PWRGD")
	)
	(segment
		(start 254.361442 -53.397404)
		(end 254.15494 -53.603906)
		(width 0.12954)
		(layer "F.Cu")
		(net "HP_LVC3_E1S_0_HSC_PWRGD")
	)
	(segment
		(start 190.0936 -73.3044)
		(end 202.3872 -73.3044)
		(width 0.12954)
		(layer "F.Cu")
		(net "HP_LVC3_E1S_0_HSC_PWRGD")
	)
	(segment
		(start 186.563 -63.45174)
		(end 186.69254 -63.3222)
		(width 0.12954)
		(layer "F.Cu")
		(net "HP_LVC3_E1S_0_HSC_PWRGD")
	)
	(segment
		(start 251.587254 -38.43655)
		(end 251.82195 -38.201854)
		(width 0.12954)
		(layer "F.Cu")
		(net "HP_LVC3_E1S_0_HSC_PWRGD")
	)
	(segment
		(start 186.8424 -89.2556)
		(end 186.8424 -86.3346)
		(width 0.12954)
		(layer "F.Cu")
		(net "HP_LVC3_E1S_0_HSC_PWRGD")
	)
	(segment
		(start 203.3524 -72.3392)
		(end 203.3524 -70.5358)
		(width 0.12954)
		(layer "F.Cu")
		(net "HP_LVC3_E1S_0_HSC_PWRGD")
	)
	(segment
		(start 190.4746 -63.4492)
		(end 190.4746 -64.77)
		(width 0.12954)
		(layer "F.Cu")
		(net "HP_LVC3_E1S_0_HSC_PWRGD")
	)
	(segment
		(start 201.7522 -68.9356)
		(end 199.4408 -68.9356)
		(width 0.12954)
		(layer "F.Cu")
		(net "HP_LVC3_E1S_0_HSC_PWRGD")
	)
	(segment
		(start 254.361442 -54.43728)
		(end 254.35433 -54.444392)
		(width 0.12954)
		(layer "F.Cu")
		(net "HP_LVC3_E1S_0_HSC_PWRGD")
	)
	(segment
		(start 203.3524 -70.5358)
		(end 201.7522 -68.9356)
		(width 0.12954)
		(layer "F.Cu")
		(net "HP_LVC3_E1S_0_HSC_PWRGD")
	)
	(segment
		(start 186.8424 -86.3346)
		(end 186.563 -86.0552)
		(width 0.12954)
		(layer "F.Cu")
		(net "HP_LVC3_E1S_0_HSC_PWRGD")
	)
	(segment
		(start 190.4746 -64.77)
		(end 188.7474 -66.4972)
		(width 0.12954)
		(layer "F.Cu")
		(net "HP_LVC3_E1S_0_HSC_PWRGD")
	)
	(segment
		(start 251.82195 -38.201854)
		(end 251.82195 -37.667946)
		(width 0.12954)
		(layer "F.Cu")
		(net "HP_LVC3_E1S_0_HSC_PWRGD")
	)
	(segment
		(start 251.587254 -38.708838)
		(end 251.587254 -38.43655)
		(width 0.12954)
		(layer "F.Cu")
		(net "HP_LVC3_E1S_0_HSC_PWRGD")
	)
	(segment
		(start 190.3476 -63.3222)
		(end 190.4746 -63.4492)
		(width 0.12954)
		(layer "F.Cu")
		(net "HP_LVC3_E1S_0_HSC_PWRGD")
	)
	(segment
		(start 251.8029 -37.648896)
		(end 250.317 -37.648896)
		(width 0.12954)
		(layer "F.Cu")
		(net "HP_LVC3_E1S_0_HSC_PWRGD")
	)
	(segment
		(start 183.515 -93.5101)
		(end 183.515 -92.837)
		(width 0.12954)
		(layer "F.Cu")
		(net "HP_LVC3_E1S_0_HSC_PWRGD")
	)
	(segment
		(start 254.361442 -52.766468)
		(end 254.361442 -53.397404)
		(width 0.12954)
		(layer "F.Cu")
		(net "HP_LVC3_E1S_0_HSC_PWRGD")
	)
	(segment
		(start 188.7474 -71.9582)
		(end 190.0936 -73.3044)
		(width 0.12954)
		(layer "F.Cu")
		(net "HP_LVC3_E1S_0_HSC_PWRGD")
	)
	(via
		(at 186.8424 -89.2556)
		(size 0.508)
		(drill 0.254)
		(layers "F.Cu" "B.Cu")
		(net "HP_LVC3_E1S_0_HSC_PWRGD")
	)
	(via
		(at 199.4408 -68.9356)
		(size 0.508)
		(drill 0.254)
		(layers "F.Cu" "B.Cu")
		(net "HP_LVC3_E1S_0_HSC_PWRGD")
	)
	(via
		(at 183.515 -92.837)
		(size 0.508)
		(drill 0.254)
		(layers "F.Cu" "B.Cu")
		(net "HP_LVC3_E1S_0_HSC_PWRGD")
	)
	(via
		(at 251.587254 -38.708838)
		(size 0.508)
		(drill 0.254)
		(layers "F.Cu" "B.Cu")
		(net "HP_LVC3_E1S_0_HSC_PWRGD")
	)
	(via
		(at 254.15494 -53.603906)
		(size 0.508)
		(drill 0.254)
		(layers "F.Cu" "B.Cu")
		(net "HP_LVC3_E1S_0_HSC_PWRGD")
	)
	(segment
		(start 256.1082 -46.024546)
		(end 256.1082 -47.934626)
		(width 0.127)
		(layer "In2.Cu")
		(net "HP_LVC3_E1S_0_HSC_PWRGD")
	)
	(segment
		(start 252.222 -39.03218)
		(end 252.222 -40.863266)
		(width 0.127)
		(layer "In2.Cu")
		(net "HP_LVC3_E1S_0_HSC_PWRGD")
	)
	(segment
		(start 254.33528 -45.262546)
		(end 255.3462 -45.262546)
		(width 0.127)
		(layer "In2.Cu")
		(net "HP_LVC3_E1S_0_HSC_PWRGD")
	)
	(segment
		(start 251.898658 -38.708838)
		(end 252.222 -39.03218)
		(width 0.127)
		(layer "In2.Cu")
		(net "HP_LVC3_E1S_0_HSC_PWRGD")
	)
	(segment
		(start 251.587254 -38.708838)
		(end 251.898658 -38.708838)
		(width 0.127)
		(layer "In2.Cu")
		(net "HP_LVC3_E1S_0_HSC_PWRGD")
	)
	(segment
		(start 252.222 -40.863266)
		(end 253.90348 -42.544746)
		(width 0.127)
		(layer "In2.Cu")
		(net "HP_LVC3_E1S_0_HSC_PWRGD")
	)
	(segment
		(start 255.3462 -45.262546)
		(end 256.1082 -46.024546)
		(width 0.127)
		(layer "In2.Cu")
		(net "HP_LVC3_E1S_0_HSC_PWRGD")
	)
	(segment
		(start 253.90348 -42.544746)
		(end 253.90348 -44.830746)
		(width 0.127)
		(layer "In2.Cu")
		(net "HP_LVC3_E1S_0_HSC_PWRGD")
	)
	(segment
		(start 254.311404 -53.603906)
		(end 254.15494 -53.603906)
		(width 0.127)
		(layer "In2.Cu")
		(net "HP_LVC3_E1S_0_HSC_PWRGD")
	)
	(segment
		(start 253.90348 -44.830746)
		(end 254.33528 -45.262546)
		(width 0.127)
		(layer "In2.Cu")
		(net "HP_LVC3_E1S_0_HSC_PWRGD")
	)
	(segment
		(start 256.1082 -47.934626)
		(end 254.76708 -49.275746)
		(width 0.127)
		(layer "In2.Cu")
		(net "HP_LVC3_E1S_0_HSC_PWRGD")
	)
	(segment
		(start 254.76708 -53.14823)
		(end 254.311404 -53.603906)
		(width 0.127)
		(layer "In2.Cu")
		(net "HP_LVC3_E1S_0_HSC_PWRGD")
	)
	(segment
		(start 254.76708 -49.275746)
		(end 254.76708 -53.14823)
		(width 0.127)
		(layer "In2.Cu")
		(net "HP_LVC3_E1S_0_HSC_PWRGD")
	)
	(segment
		(start 253.3904 -55.6768)
		(end 254.15494 -54.91226)
		(width 0.127)
		(layer "In11.Cu")
		(net "HP_LVC3_E1S_0_HSC_PWRGD")
	)
	(segment
		(start 238.5568 -65.2272)
		(end 242.9764 -60.8076)
		(width 0.127)
		(layer "In11.Cu")
		(net "HP_LVC3_E1S_0_HSC_PWRGD")
	)
	(segment
		(start 253.3904 -60.0202)
		(end 253.3904 -55.6768)
		(width 0.127)
		(layer "In11.Cu")
		(net "HP_LVC3_E1S_0_HSC_PWRGD")
	)
	(segment
		(start 199.4408 -68.9356)
		(end 200.2536 -68.9356)
		(width 0.127)
		(layer "In11.Cu")
		(net "HP_LVC3_E1S_0_HSC_PWRGD")
	)
	(segment
		(start 252.603 -60.8076)
		(end 253.3904 -60.0202)
		(width 0.127)
		(layer "In11.Cu")
		(net "HP_LVC3_E1S_0_HSC_PWRGD")
	)
	(segment
		(start 242.9764 -60.8076)
		(end 252.603 -60.8076)
		(width 0.127)
		(layer "In11.Cu")
		(net "HP_LVC3_E1S_0_HSC_PWRGD")
	)
	(segment
		(start 200.2536 -68.9356)
		(end 203.962 -65.2272)
		(width 0.127)
		(layer "In11.Cu")
		(net "HP_LVC3_E1S_0_HSC_PWRGD")
	)
	(segment
		(start 254.15494 -54.91226)
		(end 254.15494 -53.603906)
		(width 0.127)
		(layer "In11.Cu")
		(net "HP_LVC3_E1S_0_HSC_PWRGD")
	)
	(segment
		(start 203.962 -65.2272)
		(end 238.5568 -65.2272)
		(width 0.127)
		(layer "In11.Cu")
		(net "HP_LVC3_E1S_0_HSC_PWRGD")
	)
	(segment
		(start 184.912 -91.4654)
		(end 186.8424 -89.535)
		(width 0.127)
		(layer "In13.Cu")
		(net "HP_LVC3_E1S_0_HSC_PWRGD")
	)
	(segment
		(start 183.515 -92.837)
		(end 183.515 -91.9226)
		(width 0.127)
		(layer "In13.Cu")
		(net "HP_LVC3_E1S_0_HSC_PWRGD")
	)
	(segment
		(start 186.8424 -89.535)
		(end 186.8424 -89.2556)
		(width 0.127)
		(layer "In13.Cu")
		(net "HP_LVC3_E1S_0_HSC_PWRGD")
	)
	(segment
		(start 183.515 -91.9226)
		(end 183.9722 -91.4654)
		(width 0.127)
		(layer "In13.Cu")
		(net "HP_LVC3_E1S_0_HSC_PWRGD")
	)
	(segment
		(start 183.9722 -91.4654)
		(end 184.912 -91.4654)
		(width 0.127)
		(layer "In13.Cu")
		(net "HP_LVC3_E1S_0_HSC_PWRGD")
	)
	(segment
		(start 265.00582 -104.318816)
		(end 265.00582 -105.077768)
		(width 0.12954)
		(layer "F.Cu")
		(net "NC_CLK_CK440_MXCK6_DP")
	)
	(segment
		(start 263.485884 -103.916988)
		(end 264.603992 -103.916988)
		(width 0.12954)
		(layer "F.Cu")
		(net "NC_CLK_CK440_MXCK6_DP")
	)
	(segment
		(start 260.13283 -101.813106)
		(end 260.527546 -102.207822)
		(width 0.0889)
		(layer "F.Cu")
		(net "NC_CLK_CK440_MXCK6_DP")
	)
	(segment
		(start 264.603992 -103.916988)
		(end 265.00582 -104.318816)
		(width 0.12954)
		(layer "F.Cu")
		(net "NC_CLK_CK440_MXCK6_DP")
	)
	(segment
		(start 260.527546 -102.207822)
		(end 261.776718 -102.207822)
		(width 0.0889)
		(layer "F.Cu")
		(net "NC_CLK_CK440_MXCK6_DP")
	)
	(segment
		(start 261.776718 -102.207822)
		(end 263.485884 -103.916988)
		(width 0.12954)
		(layer "F.Cu")
		(net "NC_CLK_CK440_MXCK6_DP")
	)
	(segment
		(start 259.557774 -101.813106)
		(end 260.13283 -101.813106)
		(width 0.0889)
		(layer "F.Cu")
		(net "NC_CLK_CK440_MXCK6_DP")
	)
	(via
		(at 265.00582 -105.077768)
		(size 0.762)
		(drill 0.381)
		(layers "F.Cu" "B.Cu")
		(net "NC_CLK_CK440_MXCK6_DP")
	)
	(segment
		(start 263.640824 -102.057454)
		(end 264.26795 -102.057454)
		(width 0.12954)
		(layer "F.Cu")
		(net "NC_CLK_CK440_MXCK6_DN")
	)
	(segment
		(start 260.053836 -101.293168)
		(end 261.871714 -101.293168)
		(width 0.0889)
		(layer "F.Cu")
		(net "NC_CLK_CK440_MXCK6_DN")
	)
	(segment
		(start 264.26795 -102.057454)
		(end 264.842498 -102.632002)
		(width 0.12954)
		(layer "F.Cu")
		(net "NC_CLK_CK440_MXCK6_DN")
	)
	(segment
		(start 260.03377 -101.313234)
		(end 260.053836 -101.293168)
		(width 0.0889)
		(layer "F.Cu")
		(net "NC_CLK_CK440_MXCK6_DN")
	)
	(segment
		(start 259.557774 -101.313234)
		(end 260.03377 -101.313234)
		(width 0.0889)
		(layer "F.Cu")
		(net "NC_CLK_CK440_MXCK6_DN")
	)
	(segment
		(start 261.871714 -101.293168)
		(end 262.876538 -101.293168)
		(width 0.12954)
		(layer "F.Cu")
		(net "NC_CLK_CK440_MXCK6_DN")
	)
	(segment
		(start 262.876538 -101.293168)
		(end 263.640824 -102.057454)
		(width 0.12954)
		(layer "F.Cu")
		(net "NC_CLK_CK440_MXCK6_DN")
	)
	(via
		(at 264.842498 -102.632002)
		(size 0.762)
		(drill 0.381)
		(layers "F.Cu" "B.Cu")
		(net "NC_CLK_CK440_MXCK6_DN")
	)
	(segment
		(start 184.113932 -405.307038)
		(end 183.130698 -406.290272)
		(width 0.12954)
		(layer "F.Cu")
		(net "SMB_SML1_PMBUS_HSC_L_SCL")
	)
	(segment
		(start 184.113932 -404.95982)
		(end 184.113932 -405.307038)
		(width 0.12954)
		(layer "F.Cu")
		(net "SMB_SML1_PMBUS_HSC_L_SCL")
	)
	(via
		(at 183.130698 -406.290272)
		(size 0.508)
		(drill 0.254)
		(layers "F.Cu" "B.Cu")
		(net "SMB_SML1_PMBUS_HSC_L_SCL")
	)
	(segment
		(start 182.969408 -407.395172)
		(end 182.969408 -406.451562)
		(width 0.12954)
		(layer "B.Cu")
		(net "SMB_SML1_PMBUS_HSC_L_SCL")
	)
	(segment
		(start 182.908448 -407.456132)
		(end 182.969408 -407.395172)
		(width 0.12954)
		(layer "B.Cu")
		(net "SMB_SML1_PMBUS_HSC_L_SCL")
	)
	(segment
		(start 182.969408 -406.451562)
		(end 183.130698 -406.290272)
		(width 0.12954)
		(layer "B.Cu")
		(net "SMB_SML1_PMBUS_HSC_L_SCL")
	)
	(segment
		(start 182.781448 -407.062432)
		(end 183.379618 -407.062432)
		(width 0.12954)
		(layer "F.Cu")
		(net "IRQ_SML1_PMBUS_ALERT")
	)
	(segment
		(start 183.379618 -407.062432)
		(end 184.427368 -406.014682)
		(width 0.12954)
		(layer "F.Cu")
		(net "IRQ_SML1_PMBUS_ALERT")
	)
	(segment
		(start 184.56402 -404.95982)
		(end 184.56402 -405.87803)
		(width 0.12954)
		(layer "F.Cu")
		(net "IRQ_SML1_PMBUS_ALERT")
	)
	(segment
		(start 184.56402 -405.87803)
		(end 184.427368 -406.014682)
		(width 0.12954)
		(layer "F.Cu")
		(net "IRQ_SML1_PMBUS_ALERT")
	)
	(via
		(at 184.427368 -406.014682)
		(size 0.508)
		(drill 0.254)
		(layers "F.Cu" "B.Cu")
		(net "IRQ_SML1_PMBUS_ALERT")
	)
	(segment
		(start 184.427368 -406.014682)
		(end 184.360058 -405.947372)
		(width 0.12954)
		(layer "B.Cu")
		(net "IRQ_SML1_PMBUS_ALERT")
	)
	(segment
		(start 184.360058 -405.947372)
		(end 184.360058 -404.853902)
		(width 0.12954)
		(layer "B.Cu")
		(net "IRQ_SML1_PMBUS_ALERT")
	)
	(segment
		(start 179.752498 -404.287482)
		(end 179.752498 -405.303482)
		(width 0.1524)
		(layer "F.Cu")
		(net "HSC_VTEMP")
	)
	(segment
		(start 229.93858 -403.972776)
		(end 229.273608 -403.972776)
		(width 0.1524)
		(layer "F.Cu")
		(net "HSC_VTEMP")
	)
	(segment
		(start 180.6829 -404.37308)
		(end 179.752498 -405.303482)
		(width 0.1524)
		(layer "F.Cu")
		(net "HSC_VTEMP")
	)
	(segment
		(start 181.724046 -404.483824)
		(end 181.123844 -404.483824)
		(width 0.1524)
		(layer "F.Cu")
		(net "HSC_VTEMP")
	)
	(segment
		(start 182.36057 -403.8473)
		(end 181.724046 -404.483824)
		(width 0.1524)
		(layer "F.Cu")
		(net "HSC_VTEMP")
	)
	(segment
		(start 197.93458 -403.972776)
		(end 197.338188 -403.972776)
		(width 0.1524)
		(layer "F.Cu")
		(net "HSC_VTEMP")
	)
	(segment
		(start 208.60258 -403.972776)
		(end 207.937608 -403.972776)
		(width 0.1524)
		(layer "F.Cu")
		(net "HSC_VTEMP")
	)
	(segment
		(start 182.676546 -403.8473)
		(end 182.36057 -403.8473)
		(width 0.1524)
		(layer "F.Cu")
		(net "HSC_VTEMP")
	)
	(segment
		(start 219.27058 -403.972776)
		(end 218.605608 -403.972776)
		(width 0.1524)
		(layer "F.Cu")
		(net "HSC_VTEMP")
	)
	(segment
		(start 181.123844 -404.483824)
		(end 180.6829 -404.04288)
		(width 0.1524)
		(layer "F.Cu")
		(net "HSC_VTEMP")
	)
	(segment
		(start 180.6829 -404.04288)
		(end 180.6829 -404.37308)
		(width 0.1524)
		(layer "F.Cu")
		(net "HSC_VTEMP")
	)
	(via
		(at 218.605608 -403.972776)
		(size 0.508)
		(drill 0.254)
		(layers "F.Cu" "B.Cu")
		(net "HSC_VTEMP")
	)
	(via
		(at 180.6829 -404.04288)
		(size 0.508)
		(drill 0.254)
		(layers "F.Cu" "B.Cu")
		(net "HSC_VTEMP")
	)
	(via
		(at 207.937608 -403.972776)
		(size 0.508)
		(drill 0.254)
		(layers "F.Cu" "B.Cu")
		(net "HSC_VTEMP")
	)
	(via
		(at 197.338188 -403.972776)
		(size 0.508)
		(drill 0.254)
		(layers "F.Cu" "B.Cu")
		(net "HSC_VTEMP")
	)
	(via
		(at 229.273608 -403.972776)
		(size 0.508)
		(drill 0.254)
		(layers "F.Cu" "B.Cu")
		(net "HSC_VTEMP")
	)
	(segment
		(start 218.236292 -403.60346)
		(end 218.605608 -403.972776)
		(width 0.1524)
		(layer "In13.Cu")
		(net "HSC_VTEMP")
	)
	(segment
		(start 207.558132 -403.5933)
		(end 207.937608 -403.972776)
		(width 0.1524)
		(layer "In13.Cu")
		(net "HSC_VTEMP")
	)
	(segment
		(start 217.5764 -408.59964)
		(end 217.5764 -410.03982)
		(width 0.1524)
		(layer "In13.Cu")
		(net "HSC_VTEMP")
	)
	(segment
		(start 197.338188 -403.972776)
		(end 196.60362 -404.707344)
		(width 0.1524)
		(layer "In13.Cu")
		(net "HSC_VTEMP")
	)
	(segment
		(start 180.35524 -404.37054)
		(end 180.6829 -404.04288)
		(width 0.1524)
		(layer "In13.Cu")
		(net "HSC_VTEMP")
	)
	(segment
		(start 207.937608 -403.972776)
		(end 208.27492 -404.310088)
		(width 0.1524)
		(layer "In13.Cu")
		(net "HSC_VTEMP")
	)
	(segment
		(start 217.5764 -410.03982)
		(end 217.84564 -410.30906)
		(width 0.1524)
		(layer "In13.Cu")
		(net "HSC_VTEMP")
	)
	(segment
		(start 195.49618 -404.06066)
		(end 195.49618 -410.07538)
		(width 0.1524)
		(layer "In13.Cu")
		(net "HSC_VTEMP")
	)
	(segment
		(start 196.3166 -403.24024)
		(end 195.49618 -404.06066)
		(width 0.1524)
		(layer "In13.Cu")
		(net "HSC_VTEMP")
	)
	(segment
		(start 228.904292 -403.60346)
		(end 229.273608 -403.972776)
		(width 0.1524)
		(layer "In13.Cu")
		(net "HSC_VTEMP")
	)
	(segment
		(start 226.33686 -404.93696)
		(end 227.67036 -403.60346)
		(width 0.1524)
		(layer "In13.Cu")
		(net "HSC_VTEMP")
	)
	(segment
		(start 218.92514 -407.2509)
		(end 217.5764 -408.59964)
		(width 0.1524)
		(layer "In13.Cu")
		(net "HSC_VTEMP")
	)
	(segment
		(start 206.9846 -408.59964)
		(end 206.9846 -410.01188)
		(width 0.1524)
		(layer "In13.Cu")
		(net "HSC_VTEMP")
	)
	(segment
		(start 206.2988 -403.5933)
		(end 207.558132 -403.5933)
		(width 0.1524)
		(layer "In13.Cu")
		(net "HSC_VTEMP")
	)
	(segment
		(start 207.2386 -410.26588)
		(end 215.21928 -410.26588)
		(width 0.1524)
		(layer "In13.Cu")
		(net "HSC_VTEMP")
	)
	(segment
		(start 225.8568 -410.30906)
		(end 226.33686 -409.829)
		(width 0.1524)
		(layer "In13.Cu")
		(net "HSC_VTEMP")
	)
	(segment
		(start 181.29758 -410.58592)
		(end 181.29758 -409.827984)
		(width 0.1524)
		(layer "In13.Cu")
		(net "HSC_VTEMP")
	)
	(segment
		(start 197.338188 -403.972776)
		(end 197.338188 -403.601428)
		(width 0.1524)
		(layer "In13.Cu")
		(net "HSC_VTEMP")
	)
	(segment
		(start 197.338188 -403.601428)
		(end 196.977 -403.24024)
		(width 0.1524)
		(layer "In13.Cu")
		(net "HSC_VTEMP")
	)
	(segment
		(start 205.04658 -410.04744)
		(end 205.04658 -404.84552)
		(width 0.1524)
		(layer "In13.Cu")
		(net "HSC_VTEMP")
	)
	(segment
		(start 215.95588 -404.6093)
		(end 216.96172 -403.60346)
		(width 0.1524)
		(layer "In13.Cu")
		(net "HSC_VTEMP")
	)
	(segment
		(start 208.27492 -407.30932)
		(end 206.9846 -408.59964)
		(width 0.1524)
		(layer "In13.Cu")
		(net "HSC_VTEMP")
	)
	(segment
		(start 196.977 -403.24024)
		(end 196.3166 -403.24024)
		(width 0.1524)
		(layer "In13.Cu")
		(net "HSC_VTEMP")
	)
	(segment
		(start 218.605608 -403.972776)
		(end 218.92514 -404.292308)
		(width 0.1524)
		(layer "In13.Cu")
		(net "HSC_VTEMP")
	)
	(segment
		(start 194.78752 -410.78404)
		(end 181.4957 -410.78404)
		(width 0.1524)
		(layer "In13.Cu")
		(net "HSC_VTEMP")
	)
	(segment
		(start 218.92514 -404.292308)
		(end 218.92514 -407.2509)
		(width 0.1524)
		(layer "In13.Cu")
		(net "HSC_VTEMP")
	)
	(segment
		(start 227.67036 -403.60346)
		(end 228.904292 -403.60346)
		(width 0.1524)
		(layer "In13.Cu")
		(net "HSC_VTEMP")
	)
	(segment
		(start 217.84564 -410.30906)
		(end 225.8568 -410.30906)
		(width 0.1524)
		(layer "In13.Cu")
		(net "HSC_VTEMP")
	)
	(segment
		(start 216.96172 -403.60346)
		(end 218.236292 -403.60346)
		(width 0.1524)
		(layer "In13.Cu")
		(net "HSC_VTEMP")
	)
	(segment
		(start 197.2818 -410.75356)
		(end 204.34046 -410.75356)
		(width 0.1524)
		(layer "In13.Cu")
		(net "HSC_VTEMP")
	)
	(segment
		(start 196.60362 -410.07538)
		(end 197.2818 -410.75356)
		(width 0.1524)
		(layer "In13.Cu")
		(net "HSC_VTEMP")
	)
	(segment
		(start 196.60362 -404.707344)
		(end 196.60362 -410.07538)
		(width 0.1524)
		(layer "In13.Cu")
		(net "HSC_VTEMP")
	)
	(segment
		(start 215.95588 -409.52928)
		(end 215.95588 -404.6093)
		(width 0.1524)
		(layer "In13.Cu")
		(net "HSC_VTEMP")
	)
	(segment
		(start 215.21928 -410.26588)
		(end 215.95588 -409.52928)
		(width 0.1524)
		(layer "In13.Cu")
		(net "HSC_VTEMP")
	)
	(segment
		(start 204.34046 -410.75356)
		(end 205.04658 -410.04744)
		(width 0.1524)
		(layer "In13.Cu")
		(net "HSC_VTEMP")
	)
	(segment
		(start 195.49618 -410.07538)
		(end 194.78752 -410.78404)
		(width 0.1524)
		(layer "In13.Cu")
		(net "HSC_VTEMP")
	)
	(segment
		(start 181.29758 -409.827984)
		(end 180.35524 -408.885644)
		(width 0.1524)
		(layer "In13.Cu")
		(net "HSC_VTEMP")
	)
	(segment
		(start 208.27492 -404.310088)
		(end 208.27492 -407.30932)
		(width 0.1524)
		(layer "In13.Cu")
		(net "HSC_VTEMP")
	)
	(segment
		(start 226.33686 -409.829)
		(end 226.33686 -404.93696)
		(width 0.1524)
		(layer "In13.Cu")
		(net "HSC_VTEMP")
	)
	(segment
		(start 180.35524 -408.885644)
		(end 180.35524 -404.37054)
		(width 0.1524)
		(layer "In13.Cu")
		(net "HSC_VTEMP")
	)
	(segment
		(start 205.04658 -404.84552)
		(end 206.2988 -403.5933)
		(width 0.1524)
		(layer "In13.Cu")
		(net "HSC_VTEMP")
	)
	(segment
		(start 206.9846 -410.01188)
		(end 207.2386 -410.26588)
		(width 0.1524)
		(layer "In13.Cu")
		(net "HSC_VTEMP")
	)
	(segment
		(start 181.4957 -410.78404)
		(end 181.29758 -410.58592)
		(width 0.1524)
		(layer "In13.Cu")
		(net "HSC_VTEMP")
	)
	(segment
		(start 185.245248 -407.587196)
		(end 185.245248 -407.105612)
		(width 0.1524)
		(layer "F.Cu")
		(net "HSC_VSENSE")
	)
	(segment
		(start 184.829958 -408.912822)
		(end 184.98312 -408.75966)
		(width 0.1524)
		(layer "F.Cu")
		(net "HSC_VSENSE")
	)
	(segment
		(start 185.014108 -406.315672)
		(end 185.014108 -404.95982)
		(width 0.1524)
		(layer "F.Cu")
		(net "HSC_VSENSE")
	)
	(segment
		(start 184.98312 -407.849324)
		(end 185.245248 -407.587196)
		(width 0.1524)
		(layer "F.Cu")
		(net "HSC_VSENSE")
	)
	(segment
		(start 184.98312 -408.75966)
		(end 184.98312 -407.849324)
		(width 0.1524)
		(layer "F.Cu")
		(net "HSC_VSENSE")
	)
	(segment
		(start 184.290208 -407.039572)
		(end 185.179208 -407.039572)
		(width 0.1524)
		(layer "F.Cu")
		(net "HSC_VSENSE")
	)
	(segment
		(start 184.290208 -407.039572)
		(end 185.014108 -406.315672)
		(width 0.1524)
		(layer "F.Cu")
		(net "HSC_VSENSE")
	)
	(segment
		(start 185.245248 -407.105612)
		(end 185.179208 -407.039572)
		(width 0.1524)
		(layer "F.Cu")
		(net "HSC_VSENSE")
	)
	(via
		(at 185.179208 -407.039572)
		(size 0.508)
		(drill 0.254)
		(layers "F.Cu" "B.Cu")
		(net "HSC_VSENSE")
	)
	(segment
		(start 183.995568 -407.463752)
		(end 184.755028 -407.463752)
		(width 0.1524)
		(layer "B.Cu")
		(net "HSC_VSENSE")
	)
	(segment
		(start 184.755028 -407.463752)
		(end 185.179208 -407.039572)
		(width 0.1524)
		(layer "B.Cu")
		(net "HSC_VSENSE")
	)
	(segment
		(start 183.598058 -399.544032)
		(end 183.598058 -398.651222)
		(width 0.12954)
		(layer "F.Cu")
		(net "HSC_VOSEN")
	)
	(segment
		(start 183.881268 -399.827242)
		(end 183.598058 -399.544032)
		(width 0.12954)
		(layer "F.Cu")
		(net "HSC_VOSEN")
	)
	(segment
		(start 184.113932 -400.059906)
		(end 183.881268 -399.827242)
		(width 0.1524)
		(layer "F.Cu")
		(net "HSC_VOSEN")
	)
	(segment
		(start 184.113932 -400.484848)
		(end 184.113932 -400.059906)
		(width 0.1524)
		(layer "F.Cu")
		(net "HSC_VOSEN")
	)
	(via
		(at 183.881268 -399.827242)
		(size 0.508)
		(drill 0.254)
		(layers "F.Cu" "B.Cu")
		(net "HSC_VOSEN")
	)
	(segment
		(start 184.575958 -398.651222)
		(end 183.572658 -398.651222)
		(width 0.1524)
		(layer "B.Cu")
		(net "HSC_VOSEN")
	)
	(segment
		(start 183.572658 -398.651222)
		(end 183.572658 -399.518632)
		(width 0.1524)
		(layer "B.Cu")
		(net "HSC_VOSEN")
	)
	(segment
		(start 183.572658 -399.518632)
		(end 183.881268 -399.827242)
		(width 0.1524)
		(layer "B.Cu")
		(net "HSC_VOSEN")
	)
	(segment
		(start 180.978048 -405.469852)
		(end 181.327044 -405.469852)
		(width 0.1524)
		(layer "F.Cu")
		(net "HSC_VIN_UVW_N")
	)
	(segment
		(start 182.499508 -404.297388)
		(end 182.676546 -404.297388)
		(width 0.1524)
		(layer "F.Cu")
		(net "HSC_VIN_UVW_N")
	)
	(segment
		(start 181.327044 -405.469852)
		(end 182.499508 -404.297388)
		(width 0.1524)
		(layer "F.Cu")
		(net "HSC_VIN_UVW_N")
	)
	(via
		(at 180.978048 -405.469852)
		(size 0.762)
		(drill 0.254)
		(layers "F.Cu" "B.Cu")
		(net "HSC_VIN_UVW_N")
	)
	(segment
		(start 179.918868 -405.469852)
		(end 179.854098 -405.405082)
		(width 0.12954)
		(layer "B.Cu")
		(net "HSC_VIN_UVW_N")
	)
	(segment
		(start 180.978048 -405.469852)
		(end 179.918868 -405.469852)
		(width 0.12954)
		(layer "B.Cu")
		(net "HSC_VIN_UVW_N")
	)
	(segment
		(start 179.854098 -405.405082)
		(end 179.854098 -405.288242)
		(width 0.12954)
		(layer "B.Cu")
		(net "HSC_VIN_UVW_N")
	)
	(segment
		(start 207.347312 -402.594572)
		(end 207.074008 -402.594572)
		(width 0.254)
		(layer "F.Cu")
		(net "HSC_VDD_R_2")
	)
	(segment
		(start 206.425292 -403.109938)
		(end 206.940658 -402.594572)
		(width 0.254)
		(layer "F.Cu")
		(net "HSC_VDD_R_2")
	)
	(segment
		(start 207.468978 -402.472906)
		(end 207.347312 -402.594572)
		(width 0.254)
		(layer "F.Cu")
		(net "HSC_VDD_R_2")
	)
	(segment
		(start 208.60258 -402.472906)
		(end 207.468978 -402.472906)
		(width 0.254)
		(layer "F.Cu")
		(net "HSC_VDD_R_2")
	)
	(segment
		(start 206.940658 -402.594572)
		(end 207.074008 -402.594572)
		(width 0.254)
		(layer "F.Cu")
		(net "HSC_VDD_R_2")
	)
	(via
		(at 206.425292 -403.109938)
		(size 0.508)
		(drill 0.254)
		(layers "F.Cu" "B.Cu")
		(net "HSC_VDD_R_2")
	)
	(segment
		(start 206.130398 -403.404832)
		(end 206.425292 -403.109938)
		(width 0.254)
		(layer "B.Cu")
		(net "HSC_VDD_R_2")
	)
	(segment
		(start 205.307438 -403.404832)
		(end 206.130398 -403.404832)
		(width 0.254)
		(layer "B.Cu")
		(net "HSC_VDD_R_2")
	)
	(segment
		(start 196.436742 -402.472906)
		(end 196.329808 -402.365972)
		(width 0.254)
		(layer "F.Cu")
		(net "HSC_VDD_R_1")
	)
	(segment
		(start 197.93458 -402.472906)
		(end 196.436742 -402.472906)
		(width 0.254)
		(layer "F.Cu")
		(net "HSC_VDD_R_1")
	)
	(segment
		(start 195.440808 -402.435822)
		(end 195.510658 -402.365972)
		(width 0.254)
		(layer "F.Cu")
		(net "HSC_VDD_R_1")
	)
	(segment
		(start 195.510658 -402.365972)
		(end 196.329808 -402.365972)
		(width 0.254)
		(layer "F.Cu")
		(net "HSC_VDD_R_1")
	)
	(via
		(at 195.440808 -402.435822)
		(size 0.508)
		(drill 0.254)
		(layers "F.Cu" "B.Cu")
		(net "HSC_VDD_R_1")
	)
	(segment
		(start 195.254626 -402.622004)
		(end 194.357752 -402.622004)
		(width 0.254)
		(layer "B.Cu")
		(net "HSC_VDD_R_1")
	)
	(segment
		(start 195.440808 -402.435822)
		(end 195.254626 -402.622004)
		(width 0.254)
		(layer "B.Cu")
		(net "HSC_VDD_R_1")
	)
	(segment
		(start 181.793388 -403.045422)
		(end 181.298088 -402.550122)
		(width 0.254)
		(layer "F.Cu")
		(net "HSC_VDD_R")
	)
	(segment
		(start 182.676546 -402.947378)
		(end 182.49392 -402.947378)
		(width 0.254)
		(layer "F.Cu")
		(net "HSC_VDD_R")
	)
	(segment
		(start 182.395876 -403.045422)
		(end 181.793388 -403.045422)
		(width 0.254)
		(layer "F.Cu")
		(net "HSC_VDD_R")
	)
	(segment
		(start 181.298088 -402.550122)
		(end 180.995828 -402.550122)
		(width 0.254)
		(layer "F.Cu")
		(net "HSC_VDD_R")
	)
	(segment
		(start 179.752498 -403.271482)
		(end 180.473858 -402.550122)
		(width 0.254)
		(layer "F.Cu")
		(net "HSC_VDD_R")
	)
	(segment
		(start 180.473858 -402.550122)
		(end 180.995828 -402.550122)
		(width 0.254)
		(layer "F.Cu")
		(net "HSC_VDD_R")
	)
	(segment
		(start 182.49392 -402.947378)
		(end 182.395876 -403.045422)
		(width 0.254)
		(layer "F.Cu")
		(net "HSC_VDD_R")
	)
	(via
		(at 180.995828 -402.550122)
		(size 0.508)
		(drill 0.254)
		(layers "F.Cu" "B.Cu")
		(net "HSC_VDD_R")
	)
	(via
		(at 183.50611 -401.851368)
		(size 0.508)
		(drill 0.254)
		(layers "F.Cu" "B.Cu")
		(net "HSC_VDD_R")
	)
	(via
		(at 184.01411 -401.343368)
		(size 0.508)
		(drill 0.254)
		(layers "F.Cu" "B.Cu")
		(net "HSC_VDD_R")
	)
	(via
		(at 184.52211 -401.851368)
		(size 0.508)
		(drill 0.254)
		(layers "F.Cu" "B.Cu")
		(net "HSC_VDD_R")
	)
	(segment
		(start 181.478428 -401.239482)
		(end 181.115208 -401.239482)
		(width 0.1524)
		(layer "F.Cu")
		(net "HSC_VDD18")
	)
	(segment
		(start 182.676546 -402.047456)
		(end 182.630572 -402.001482)
		(width 0.1524)
		(layer "F.Cu")
		(net "HSC_VDD18")
	)
	(segment
		(start 182.630572 -402.001482)
		(end 182.240428 -402.001482)
		(width 0.1524)
		(layer "F.Cu")
		(net "HSC_VDD18")
	)
	(segment
		(start 179.752498 -401.239482)
		(end 181.115208 -401.239482)
		(width 0.1524)
		(layer "F.Cu")
		(net "HSC_VDD18")
	)
	(segment
		(start 182.240428 -402.001482)
		(end 181.478428 -401.239482)
		(width 0.1524)
		(layer "F.Cu")
		(net "HSC_VDD18")
	)
	(via
		(at 181.115208 -401.239482)
		(size 0.762)
		(drill 0.254)
		(layers "F.Cu" "B.Cu")
		(net "HSC_VDD18")
	)
	(segment
		(start 178.960018 -400.212052)
		(end 178.960018 -397.188182)
		(width 0.1524)
		(layer "B.Cu")
		(net "HSC_VDD18")
	)
	(segment
		(start 181.115208 -401.239482)
		(end 179.987448 -401.239482)
		(width 0.1524)
		(layer "B.Cu")
		(net "HSC_VDD18")
	)
	(segment
		(start 179.987448 -401.239482)
		(end 178.960018 -400.212052)
		(width 0.1524)
		(layer "B.Cu")
		(net "HSC_VDD18")
	)
	(via
		(at 204.381608 -403.807422)
		(size 0.508)
		(drill 0.254)
		(layers "F.Cu" "B.Cu")
		(net "HSC_VDD")
	)
	(via
		(at 225.717608 -403.807422)
		(size 0.508)
		(drill 0.254)
		(layers "F.Cu" "B.Cu")
		(net "HSC_VDD")
	)
	(via
		(at 215.049608 -403.807422)
		(size 0.508)
		(drill 0.254)
		(layers "F.Cu" "B.Cu")
		(net "HSC_VDD")
	)
	(via
		(at 178.336448 -405.303482)
		(size 0.508)
		(drill 0.254)
		(layers "F.Cu" "B.Cu")
		(net "HSC_VDD")
	)
	(via
		(at 192.62344 -403.773894)
		(size 0.508)
		(drill 0.254)
		(layers "F.Cu" "B.Cu")
		(net "HSC_VDD")
	)
	(segment
		(start 216.00541 -404.068788)
		(end 215.310974 -404.068788)
		(width 0.254)
		(layer "B.Cu")
		(net "HSC_VDD")
	)
	(segment
		(start 215.310974 -404.068788)
		(end 215.049608 -403.807422)
		(width 0.254)
		(layer "B.Cu")
		(net "HSC_VDD")
	)
	(segment
		(start 205.307438 -404.204932)
		(end 205.284324 -404.181818)
		(width 0.254)
		(layer "B.Cu")
		(net "HSC_VDD")
	)
	(segment
		(start 191.652398 -401.772882)
		(end 191.675766 -401.749514)
		(width 0.254)
		(layer "B.Cu")
		(net "HSC_VDD")
	)
	(segment
		(start 179.038758 -405.303482)
		(end 178.336448 -405.303482)
		(width 0.254)
		(layer "B.Cu")
		(net "HSC_VDD")
	)
	(segment
		(start 226.652328 -404.169372)
		(end 226.079558 -404.169372)
		(width 0.254)
		(layer "B.Cu")
		(net "HSC_VDD")
	)
	(segment
		(start 192.623694 -403.77364)
		(end 193.243708 -403.77364)
		(width 0.254)
		(layer "B.Cu")
		(net "HSC_VDD")
	)
	(segment
		(start 178.952398 -404.287482)
		(end 178.952398 -405.186642)
		(width 0.254)
		(layer "B.Cu")
		(net "HSC_VDD")
	)
	(segment
		(start 191.675766 -401.749514)
		(end 191.675766 -400.63293)
		(width 0.254)
		(layer "B.Cu")
		(net "HSC_VDD")
	)
	(segment
		(start 193.618358 -403.39899)
		(end 194.334638 -403.39899)
		(width 0.254)
		(layer "B.Cu")
		(net "HSC_VDD")
	)
	(segment
		(start 205.284324 -404.181818)
		(end 204.756004 -404.181818)
		(width 0.254)
		(layer "B.Cu")
		(net "HSC_VDD")
	)
	(segment
		(start 191.652398 -402.802852)
		(end 191.652398 -401.772882)
		(width 0.254)
		(layer "B.Cu")
		(net "HSC_VDD")
	)
	(segment
		(start 179.053998 -405.288242)
		(end 179.038758 -405.303482)
		(width 0.254)
		(layer "B.Cu")
		(net "HSC_VDD")
	)
	(segment
		(start 192.62344 -403.773894)
		(end 192.623694 -403.77364)
		(width 0.254)
		(layer "B.Cu")
		(net "HSC_VDD")
	)
	(segment
		(start 204.756004 -404.181818)
		(end 204.381608 -403.807422)
		(width 0.254)
		(layer "B.Cu")
		(net "HSC_VDD")
	)
	(segment
		(start 193.243708 -403.77364)
		(end 193.618358 -403.39899)
		(width 0.254)
		(layer "B.Cu")
		(net "HSC_VDD")
	)
	(segment
		(start 226.079558 -404.169372)
		(end 225.717608 -403.807422)
		(width 0.254)
		(layer "B.Cu")
		(net "HSC_VDD")
	)
	(segment
		(start 192.62344 -403.773894)
		(end 191.652398 -402.802852)
		(width 0.254)
		(layer "B.Cu")
		(net "HSC_VDD")
	)
	(segment
		(start 178.952398 -405.186642)
		(end 179.053998 -405.288242)
		(width 0.254)
		(layer "B.Cu")
		(net "HSC_VDD")
	)
	(segment
		(start 194.334638 -403.39899)
		(end 194.357752 -403.422104)
		(width 0.254)
		(layer "B.Cu")
		(net "HSC_VDD")
	)
	(segment
		(start 191.675766 -400.63293)
		(end 191.652398 -400.609562)
		(width 0.254)
		(layer "B.Cu")
		(net "HSC_VDD")
	)
	(segment
		(start 192.66916 -403.81936)
		(end 192.623694 -403.773894)
		(width 0.254)
		(layer "In4.Cu")
		(net "HSC_VDD")
	)
	(segment
		(start 195.923408 -405.280622)
		(end 194.178428 -403.535642)
		(width 0.254)
		(layer "In4.Cu")
		(net "HSC_VDD")
	)
	(segment
		(start 180.95214 -404.686262)
		(end 178.953668 -404.686262)
		(width 0.254)
		(layer "In4.Cu")
		(net "HSC_VDD")
	)
	(segment
		(start 192.623186 -403.77364)
		(end 191.518794 -403.77364)
		(width 0.254)
		(layer "In4.Cu")
		(net "HSC_VDD")
	)
	(segment
		(start 178.953668 -404.686262)
		(end 178.336448 -405.303482)
		(width 0.254)
		(layer "In4.Cu")
		(net "HSC_VDD")
	)
	(segment
		(start 204.381608 -403.807422)
		(end 202.908408 -405.280622)
		(width 0.254)
		(layer "In4.Cu")
		(net "HSC_VDD")
	)
	(segment
		(start 193.481706 -403.535642)
		(end 193.197988 -403.81936)
		(width 0.254)
		(layer "In4.Cu")
		(net "HSC_VDD")
	)
	(segment
		(start 208.648808 -405.280622)
		(end 208.140808 -405.788622)
		(width 0.254)
		(layer "In4.Cu")
		(net "HSC_VDD")
	)
	(segment
		(start 218.326208 -405.966422)
		(end 216.268808 -405.966422)
		(width 0.254)
		(layer "In4.Cu")
		(net "HSC_VDD")
	)
	(segment
		(start 215.049608 -403.807422)
		(end 213.576408 -405.280622)
		(width 0.254)
		(layer "In4.Cu")
		(net "HSC_VDD")
	)
	(segment
		(start 208.140808 -405.788622)
		(end 205.524608 -405.788622)
		(width 0.254)
		(layer "In4.Cu")
		(net "HSC_VDD")
	)
	(segment
		(start 215.633808 -404.391622)
		(end 215.049608 -403.807422)
		(width 0.254)
		(layer "In4.Cu")
		(net "HSC_VDD")
	)
	(segment
		(start 190.11138 -403.48408)
		(end 188.66866 -404.9268)
		(width 0.254)
		(layer "In4.Cu")
		(net "HSC_VDD")
	)
	(segment
		(start 213.576408 -405.280622)
		(end 208.648808 -405.280622)
		(width 0.254)
		(layer "In4.Cu")
		(net "HSC_VDD")
	)
	(segment
		(start 204.381608 -404.645622)
		(end 204.381608 -403.807422)
		(width 0.254)
		(layer "In4.Cu")
		(net "HSC_VDD")
	)
	(segment
		(start 192.62344 -403.773894)
		(end 192.623186 -403.77364)
		(width 0.254)
		(layer "In4.Cu")
		(net "HSC_VDD")
	)
	(segment
		(start 191.229234 -403.48408)
		(end 190.11138 -403.48408)
		(width 0.254)
		(layer "In4.Cu")
		(net "HSC_VDD")
	)
	(segment
		(start 224.254568 -405.270462)
		(end 219.022168 -405.270462)
		(width 0.254)
		(layer "In4.Cu")
		(net "HSC_VDD")
	)
	(segment
		(start 194.178428 -403.535642)
		(end 193.481706 -403.535642)
		(width 0.254)
		(layer "In4.Cu")
		(net "HSC_VDD")
	)
	(segment
		(start 191.518794 -403.77364)
		(end 191.229234 -403.48408)
		(width 0.254)
		(layer "In4.Cu")
		(net "HSC_VDD")
	)
	(segment
		(start 188.66866 -404.9268)
		(end 181.192678 -404.9268)
		(width 0.254)
		(layer "In4.Cu")
		(net "HSC_VDD")
	)
	(segment
		(start 205.524608 -405.788622)
		(end 204.381608 -404.645622)
		(width 0.254)
		(layer "In4.Cu")
		(net "HSC_VDD")
	)
	(segment
		(start 215.633808 -405.331422)
		(end 215.633808 -404.391622)
		(width 0.254)
		(layer "In4.Cu")
		(net "HSC_VDD")
	)
	(segment
		(start 219.022168 -405.270462)
		(end 218.326208 -405.966422)
		(width 0.254)
		(layer "In4.Cu")
		(net "HSC_VDD")
	)
	(segment
		(start 192.623694 -403.773894)
		(end 192.62344 -403.773894)
		(width 0.254)
		(layer "In4.Cu")
		(net "HSC_VDD")
	)
	(segment
		(start 216.268808 -405.966422)
		(end 215.633808 -405.331422)
		(width 0.254)
		(layer "In4.Cu")
		(net "HSC_VDD")
	)
	(segment
		(start 193.197988 -403.81936)
		(end 192.66916 -403.81936)
		(width 0.254)
		(layer "In4.Cu")
		(net "HSC_VDD")
	)
	(segment
		(start 181.192678 -404.9268)
		(end 180.95214 -404.686262)
		(width 0.254)
		(layer "In4.Cu")
		(net "HSC_VDD")
	)
	(segment
		(start 225.717608 -403.807422)
		(end 224.254568 -405.270462)
		(width 0.254)
		(layer "In4.Cu")
		(net "HSC_VDD")
	)
	(segment
		(start 202.908408 -405.280622)
		(end 195.923408 -405.280622)
		(width 0.254)
		(layer "In4.Cu")
		(net "HSC_VDD")
	)
	(segment
		(start 217.818208 -404.823168)
		(end 217.818208 -404.035768)
		(width 0.1524)
		(layer "F.Cu")
		(net "HSC_SS")
	)
	(segment
		(start 207.149954 -404.036022)
		(end 207.713072 -403.472904)
		(width 0.1524)
		(layer "F.Cu")
		(net "HSC_SS")
	)
	(segment
		(start 218.381072 -403.472904)
		(end 219.27058 -403.472904)
		(width 0.1524)
		(layer "F.Cu")
		(net "HSC_SS")
	)
	(segment
		(start 217.817954 -404.922482)
		(end 217.817954 -404.823422)
		(width 0.1524)
		(layer "F.Cu")
		(net "HSC_SS")
	)
	(segment
		(start 196.17309 -403.934422)
		(end 196.609208 -403.934422)
		(width 0.1524)
		(layer "F.Cu")
		(net "HSC_SS")
	)
	(segment
		(start 227.133658 -405.839422)
		(end 227.569014 -405.839422)
		(width 0.1524)
		(layer "F.Cu")
		(net "HSC_SS")
	)
	(segment
		(start 217.817954 -404.823422)
		(end 217.818208 -404.823168)
		(width 0.1524)
		(layer "F.Cu")
		(net "HSC_SS")
	)
	(segment
		(start 181.865778 -403.436582)
		(end 182.637176 -403.436582)
		(width 0.1524)
		(layer "F.Cu")
		(net "HSC_SS")
	)
	(segment
		(start 216.901014 -405.839422)
		(end 217.817954 -404.922482)
		(width 0.1524)
		(layer "F.Cu")
		(net "HSC_SS")
	)
	(segment
		(start 181.45252 -403.84984)
		(end 181.865778 -403.436582)
		(width 0.1524)
		(layer "F.Cu")
		(net "HSC_SS")
	)
	(segment
		(start 182.637176 -403.436582)
		(end 182.676546 -403.397212)
		(width 0.1524)
		(layer "F.Cu")
		(net "HSC_SS")
	)
	(segment
		(start 216.465658 -405.839422)
		(end 216.901014 -405.839422)
		(width 0.1524)
		(layer "F.Cu")
		(net "HSC_SS")
	)
	(segment
		(start 228.485954 -404.823422)
		(end 228.486208 -404.823168)
		(width 0.1524)
		(layer "F.Cu")
		(net "HSC_SS")
	)
	(segment
		(start 228.486208 -404.823168)
		(end 228.486208 -404.035768)
		(width 0.1524)
		(layer "F.Cu")
		(net "HSC_SS")
	)
	(segment
		(start 227.569014 -405.839422)
		(end 228.485954 -404.922482)
		(width 0.1524)
		(layer "F.Cu")
		(net "HSC_SS")
	)
	(segment
		(start 196.02069 -404.086822)
		(end 196.17309 -403.934422)
		(width 0.1524)
		(layer "F.Cu")
		(net "HSC_SS")
	)
	(segment
		(start 195.256658 -404.086822)
		(end 196.02069 -404.086822)
		(width 0.1524)
		(layer "F.Cu")
		(net "HSC_SS")
	)
	(segment
		(start 197.070726 -403.472904)
		(end 197.93458 -403.472904)
		(width 0.1524)
		(layer "F.Cu")
		(net "HSC_SS")
	)
	(segment
		(start 196.609208 -403.934422)
		(end 197.070726 -403.472904)
		(width 0.1524)
		(layer "F.Cu")
		(net "HSC_SS")
	)
	(segment
		(start 228.486208 -404.035768)
		(end 229.049072 -403.472904)
		(width 0.1524)
		(layer "F.Cu")
		(net "HSC_SS")
	)
	(segment
		(start 205.797658 -405.839422)
		(end 206.233014 -405.839422)
		(width 0.1524)
		(layer "F.Cu")
		(net "HSC_SS")
	)
	(segment
		(start 229.049072 -403.472904)
		(end 229.93858 -403.472904)
		(width 0.1524)
		(layer "F.Cu")
		(net "HSC_SS")
	)
	(segment
		(start 228.485954 -404.922482)
		(end 228.485954 -404.823422)
		(width 0.1524)
		(layer "F.Cu")
		(net "HSC_SS")
	)
	(segment
		(start 207.713072 -403.472904)
		(end 208.60258 -403.472904)
		(width 0.1524)
		(layer "F.Cu")
		(net "HSC_SS")
	)
	(segment
		(start 217.818208 -404.035768)
		(end 218.381072 -403.472904)
		(width 0.1524)
		(layer "F.Cu")
		(net "HSC_SS")
	)
	(segment
		(start 207.149954 -404.922482)
		(end 207.149954 -404.823422)
		(width 0.1524)
		(layer "F.Cu")
		(net "HSC_SS")
	)
	(segment
		(start 206.233014 -405.839422)
		(end 207.149954 -404.922482)
		(width 0.1524)
		(layer "F.Cu")
		(net "HSC_SS")
	)
	(segment
		(start 207.149954 -404.823422)
		(end 207.149954 -404.036022)
		(width 0.1524)
		(layer "F.Cu")
		(net "HSC_SS")
	)
	(via
		(at 181.45252 -403.84984)
		(size 0.762)
		(drill 0.254)
		(layers "F.Cu" "B.Cu")
		(net "HSC_SS")
	)
	(via
		(at 207.149954 -404.823422)
		(size 0.508)
		(drill 0.254)
		(layers "F.Cu" "B.Cu")
		(net "HSC_SS")
	)
	(via
		(at 228.485954 -404.823422)
		(size 0.508)
		(drill 0.254)
		(layers "F.Cu" "B.Cu")
		(net "HSC_SS")
	)
	(via
		(at 196.609208 -403.934422)
		(size 0.508)
		(drill 0.254)
		(layers "F.Cu" "B.Cu")
		(net "HSC_SS")
	)
	(via
		(at 217.817954 -404.823422)
		(size 0.508)
		(drill 0.254)
		(layers "F.Cu" "B.Cu")
		(net "HSC_SS")
	)
	(segment
		(start 180.874162 -403.271482)
		(end 181.45252 -403.84984)
		(width 0.12954)
		(layer "B.Cu")
		(net "HSC_SS")
	)
	(segment
		(start 179.752498 -403.271482)
		(end 180.874162 -403.271482)
		(width 0.12954)
		(layer "B.Cu")
		(net "HSC_SS")
	)
	(segment
		(start 205.55712 -406.416256)
		(end 205.55712 -410.57576)
		(width 0.1524)
		(layer "In13.Cu")
		(net "HSC_SS")
	)
	(segment
		(start 217.06586 -411.2514)
		(end 216.44864 -410.63418)
		(width 0.1524)
		(layer "In13.Cu")
		(net "HSC_SS")
	)
	(segment
		(start 180.807868 -412.847028)
		(end 179.753768 -412.847028)
		(width 0.1524)
		(layer "In13.Cu")
		(net "HSC_SS")
	)
	(segment
		(start 217.817954 -404.823422)
		(end 216.44864 -406.192736)
		(width 0.1524)
		(layer "In13.Cu")
		(net "HSC_SS")
	)
	(segment
		(start 179.451508 -404.278592)
		(end 180.37048 -403.35962)
		(width 0.1524)
		(layer "In13.Cu")
		(net "HSC_SS")
	)
	(segment
		(start 180.37048 -403.35962)
		(end 180.9623 -403.35962)
		(width 0.1524)
		(layer "In13.Cu")
		(net "HSC_SS")
	)
	(segment
		(start 226.82962 -410.49956)
		(end 226.07778 -411.2514)
		(width 0.1524)
		(layer "In13.Cu")
		(net "HSC_SS")
	)
	(segment
		(start 195.184776 -411.47492)
		(end 182.179976 -411.47492)
		(width 0.1524)
		(layer "In13.Cu")
		(net "HSC_SS")
	)
	(segment
		(start 226.82962 -406.479756)
		(end 226.82962 -410.49956)
		(width 0.1524)
		(layer "In13.Cu")
		(net "HSC_SS")
	)
	(segment
		(start 182.179976 -411.47492)
		(end 180.807868 -412.847028)
		(width 0.1524)
		(layer "In13.Cu")
		(net "HSC_SS")
	)
	(segment
		(start 196.055488 -410.604208)
		(end 195.184776 -411.47492)
		(width 0.1524)
		(layer "In13.Cu")
		(net "HSC_SS")
	)
	(segment
		(start 180.9623 -403.35962)
		(end 181.45252 -403.84984)
		(width 0.1524)
		(layer "In13.Cu")
		(net "HSC_SS")
	)
	(segment
		(start 204.7621 -411.37078)
		(end 196.82206 -411.37078)
		(width 0.1524)
		(layer "In13.Cu")
		(net "HSC_SS")
	)
	(segment
		(start 216.44864 -406.192736)
		(end 216.44864 -410.63418)
		(width 0.1524)
		(layer "In13.Cu")
		(net "HSC_SS")
	)
	(segment
		(start 178.378104 -411.471364)
		(end 178.378104 -408.922474)
		(width 0.1524)
		(layer "In13.Cu")
		(net "HSC_SS")
	)
	(segment
		(start 205.55712 -410.57576)
		(end 204.7621 -411.37078)
		(width 0.1524)
		(layer "In13.Cu")
		(net "HSC_SS")
	)
	(segment
		(start 179.753768 -412.847028)
		(end 178.378104 -411.471364)
		(width 0.1524)
		(layer "In13.Cu")
		(net "HSC_SS")
	)
	(segment
		(start 179.451508 -407.84907)
		(end 179.451508 -404.278592)
		(width 0.1524)
		(layer "In13.Cu")
		(net "HSC_SS")
	)
	(segment
		(start 196.609208 -403.934422)
		(end 196.055488 -404.488142)
		(width 0.1524)
		(layer "In13.Cu")
		(net "HSC_SS")
	)
	(segment
		(start 207.149954 -404.823422)
		(end 205.55712 -406.416256)
		(width 0.1524)
		(layer "In13.Cu")
		(net "HSC_SS")
	)
	(segment
		(start 196.82206 -411.37078)
		(end 196.055488 -410.604208)
		(width 0.1524)
		(layer "In13.Cu")
		(net "HSC_SS")
	)
	(segment
		(start 215.75776 -411.32506)
		(end 206.30642 -411.32506)
		(width 0.1524)
		(layer "In13.Cu")
		(net "HSC_SS")
	)
	(segment
		(start 206.30642 -411.32506)
		(end 205.55712 -410.57576)
		(width 0.1524)
		(layer "In13.Cu")
		(net "HSC_SS")
	)
	(segment
		(start 196.055488 -404.488142)
		(end 196.055488 -410.604208)
		(width 0.1524)
		(layer "In13.Cu")
		(net "HSC_SS")
	)
	(segment
		(start 228.485954 -404.823422)
		(end 226.82962 -406.479756)
		(width 0.1524)
		(layer "In13.Cu")
		(net "HSC_SS")
	)
	(segment
		(start 226.07778 -411.2514)
		(end 217.06586 -411.2514)
		(width 0.1524)
		(layer "In13.Cu")
		(net "HSC_SS")
	)
	(segment
		(start 216.44864 -410.63418)
		(end 215.75776 -411.32506)
		(width 0.1524)
		(layer "In13.Cu")
		(net "HSC_SS")
	)
	(segment
		(start 178.378104 -408.922474)
		(end 179.451508 -407.84907)
		(width 0.1524)
		(layer "In13.Cu")
		(net "HSC_SS")
	)
	(segment
		(start 208.064608 -405.610822)
		(end 208.064608 -404.823422)
		(width 0.1524)
		(layer "F.Cu")
		(net "HSC_SCREF_2")
	)
	(segment
		(start 208.064608 -404.823422)
		(end 208.415128 -404.472902)
		(width 0.1524)
		(layer "F.Cu")
		(net "HSC_SCREF_2")
	)
	(segment
		(start 206.502 -408.887422)
		(end 207.139286 -408.250136)
		(width 0.1524)
		(layer "F.Cu")
		(net "HSC_SCREF_2")
	)
	(segment
		(start 208.415128 -404.472902)
		(end 208.58988 -404.472902)
		(width 0.1524)
		(layer "F.Cu")
		(net "HSC_SCREF_2")
	)
	(segment
		(start 207.139286 -408.250136)
		(end 207.139286 -406.536144)
		(width 0.1524)
		(layer "F.Cu")
		(net "HSC_SCREF_2")
	)
	(segment
		(start 207.139286 -406.536144)
		(end 208.064608 -405.610822)
		(width 0.1524)
		(layer "F.Cu")
		(net "HSC_SCREF_2")
	)
	(segment
		(start 205.797658 -408.887422)
		(end 206.502 -408.887422)
		(width 0.1524)
		(layer "F.Cu")
		(net "HSC_SCREF_2")
	)
	(via
		(at 207.139286 -406.536144)
		(size 0.762)
		(drill 0.381)
		(layers "F.Cu" "B.Cu")
		(net "HSC_SCREF_2")
	)
	(segment
		(start 195.256658 -405.102822)
		(end 196.634608 -405.102822)
		(width 0.1524)
		(layer "F.Cu")
		(net "HSC_SCREF_1")
	)
	(segment
		(start 196.634608 -405.102822)
		(end 197.264528 -404.472902)
		(width 0.1524)
		(layer "F.Cu")
		(net "HSC_SCREF_1")
	)
	(segment
		(start 197.264528 -404.472902)
		(end 197.92188 -404.472902)
		(width 0.1524)
		(layer "F.Cu")
		(net "HSC_SCREF_1")
	)
	(via
		(at 196.634608 -405.102822)
		(size 0.762)
		(drill 0.381)
		(layers "F.Cu" "B.Cu")
		(net "HSC_SCREF_1")
	)
	(segment
		(start 184.56402 -399.926302)
		(end 184.56402 -400.484848)
		(width 0.1524)
		(layer "F.Cu")
		(net "HSC_SCREF")
	)
	(segment
		(start 226.333558 -408.887422)
		(end 225.717608 -408.887422)
		(width 0.1524)
		(layer "F.Cu")
		(net "HSC_SCREF")
	)
	(segment
		(start 204.997558 -408.887422)
		(end 204.381608 -408.887422)
		(width 0.1524)
		(layer "F.Cu")
		(net "HSC_SCREF")
	)
	(segment
		(start 184.076848 -398.750028)
		(end 184.56402 -399.926302)
		(width 0.1524)
		(layer "F.Cu")
		(net "HSC_SCREF")
	)
	(segment
		(start 215.665558 -408.887422)
		(end 215.049608 -408.887422)
		(width 0.1524)
		(layer "F.Cu")
		(net "HSC_SCREF")
	)
	(segment
		(start 184.076848 -397.97228)
		(end 184.076848 -398.750028)
		(width 0.12954)
		(layer "F.Cu")
		(net "HSC_SCREF")
	)
	(segment
		(start 194.456558 -405.102822)
		(end 193.840608 -405.102822)
		(width 0.1524)
		(layer "F.Cu")
		(net "HSC_SCREF")
	)
	(via
		(at 193.840608 -405.102822)
		(size 0.508)
		(drill 0.254)
		(layers "F.Cu" "B.Cu")
		(net "HSC_SCREF")
	)
	(via
		(at 215.049608 -408.887422)
		(size 0.508)
		(drill 0.254)
		(layers "F.Cu" "B.Cu")
		(net "HSC_SCREF")
	)
	(via
		(at 184.076848 -397.97228)
		(size 0.508)
		(drill 0.254)
		(layers "F.Cu" "B.Cu")
		(net "HSC_SCREF")
	)
	(via
		(at 225.717608 -408.887422)
		(size 0.508)
		(drill 0.254)
		(layers "F.Cu" "B.Cu")
		(net "HSC_SCREF")
	)
	(via
		(at 204.381608 -408.887422)
		(size 0.508)
		(drill 0.254)
		(layers "F.Cu" "B.Cu")
		(net "HSC_SCREF")
	)
	(segment
		(start 184.076848 -397.97228)
		(end 184.5056 -398.401032)
		(width 0.254)
		(layer "In2.Cu")
		(net "HSC_SCREF")
	)
	(segment
		(start 191.940688 -400.964908)
		(end 191.940688 -404.490174)
		(width 0.254)
		(layer "In2.Cu")
		(net "HSC_SCREF")
	)
	(segment
		(start 193.8274 -405.089614)
		(end 193.840608 -405.102822)
		(width 0.254)
		(layer "In2.Cu")
		(net "HSC_SCREF")
	)
	(segment
		(start 191.940688 -404.490174)
		(end 192.540128 -405.089614)
		(width 0.254)
		(layer "In2.Cu")
		(net "HSC_SCREF")
	)
	(segment
		(start 184.5056 -398.401032)
		(end 184.5056 -400.1516)
		(width 0.254)
		(layer "In2.Cu")
		(net "HSC_SCREF")
	)
	(segment
		(start 184.5056 -400.1516)
		(end 184.82818 -400.47418)
		(width 0.254)
		(layer "In2.Cu")
		(net "HSC_SCREF")
	)
	(segment
		(start 184.82818 -400.47418)
		(end 191.44996 -400.47418)
		(width 0.254)
		(layer "In2.Cu")
		(net "HSC_SCREF")
	)
	(segment
		(start 191.44996 -400.47418)
		(end 191.940688 -400.964908)
		(width 0.254)
		(layer "In2.Cu")
		(net "HSC_SCREF")
	)
	(segment
		(start 192.540128 -405.089614)
		(end 193.8274 -405.089614)
		(width 0.254)
		(layer "In2.Cu")
		(net "HSC_SCREF")
	)
	(segment
		(start 193.840608 -411.048962)
		(end 193.840608 -405.102822)
		(width 0.1524)
		(layer "In4.Cu")
		(net "HSC_SCREF")
	)
	(segment
		(start 203.375768 -412.534862)
		(end 195.326508 -412.534862)
		(width 0.1524)
		(layer "In4.Cu")
		(net "HSC_SCREF")
	)
	(segment
		(start 224.902268 -412.532322)
		(end 215.826848 -412.532322)
		(width 0.1524)
		(layer "In4.Cu")
		(net "HSC_SCREF")
	)
	(segment
		(start 204.381608 -408.887422)
		(end 204.381608 -411.529022)
		(width 0.1524)
		(layer "In4.Cu")
		(net "HSC_SCREF")
	)
	(segment
		(start 204.381608 -411.529022)
		(end 203.375768 -412.534862)
		(width 0.1524)
		(layer "In4.Cu")
		(net "HSC_SCREF")
	)
	(segment
		(start 195.326508 -412.534862)
		(end 193.840608 -411.048962)
		(width 0.1524)
		(layer "In4.Cu")
		(net "HSC_SCREF")
	)
	(segment
		(start 215.049608 -411.755082)
		(end 214.295228 -412.509462)
		(width 0.1524)
		(layer "In4.Cu")
		(net "HSC_SCREF")
	)
	(segment
		(start 225.717608 -408.887422)
		(end 225.717608 -411.716982)
		(width 0.1524)
		(layer "In4.Cu")
		(net "HSC_SCREF")
	)
	(segment
		(start 205.362048 -412.509462)
		(end 204.381608 -411.529022)
		(width 0.1524)
		(layer "In4.Cu")
		(net "HSC_SCREF")
	)
	(segment
		(start 215.826848 -412.532322)
		(end 215.049608 -411.755082)
		(width 0.1524)
		(layer "In4.Cu")
		(net "HSC_SCREF")
	)
	(segment
		(start 225.717608 -411.716982)
		(end 224.902268 -412.532322)
		(width 0.1524)
		(layer "In4.Cu")
		(net "HSC_SCREF")
	)
	(segment
		(start 215.049608 -408.887422)
		(end 215.049608 -411.755082)
		(width 0.1524)
		(layer "In4.Cu")
		(net "HSC_SCREF")
	)
	(segment
		(start 214.295228 -412.509462)
		(end 205.362048 -412.509462)
		(width 0.1524)
		(layer "In4.Cu")
		(net "HSC_SCREF")
	)
	(segment
		(start 190.442088 -402.128482)
		(end 190.401448 -402.087842)
		(width 0.1524)
		(layer "F.Cu")
		(net "HSC_ON_R")
	)
	(segment
		(start 189.992 -402.49729)
		(end 189.151514 -402.49729)
		(width 0.1524)
		(layer "F.Cu")
		(net "HSC_ON_R")
	)
	(segment
		(start 191.652398 -402.128482)
		(end 190.442088 -402.128482)
		(width 0.1524)
		(layer "F.Cu")
		(net "HSC_ON_R")
	)
	(segment
		(start 190.401448 -402.087842)
		(end 189.992 -402.49729)
		(width 0.1524)
		(layer "F.Cu")
		(net "HSC_ON_R")
	)
	(via
		(at 190.401448 -402.087842)
		(size 0.762)
		(drill 0.254)
		(layers "F.Cu" "B.Cu")
		(net "HSC_ON_R")
	)
	(segment
		(start 225.790506 -404.823422)
		(end 226.333558 -404.823422)
		(width 0.1524)
		(layer "F.Cu")
		(net "HSC_ON")
	)
	(segment
		(start 223.745552 -402.472906)
		(end 224.955608 -402.472906)
		(width 0.1524)
		(layer "F.Cu")
		(net "HSC_ON")
	)
	(segment
		(start 224.955608 -402.472906)
		(end 224.955608 -403.988524)
		(width 0.1524)
		(layer "F.Cu")
		(net "HSC_ON")
	)
	(segment
		(start 215.122506 -404.823422)
		(end 214.287608 -403.988524)
		(width 0.1524)
		(layer "F.Cu")
		(net "HSC_ON")
	)
	(segment
		(start 224.955608 -403.988524)
		(end 225.790506 -404.823422)
		(width 0.1524)
		(layer "F.Cu")
		(net "HSC_ON")
	)
	(segment
		(start 203.619608 -402.472906)
		(end 203.619608 -403.988524)
		(width 0.1524)
		(layer "F.Cu")
		(net "HSC_ON")
	)
	(segment
		(start 214.287608 -402.472906)
		(end 213.077552 -402.472906)
		(width 0.1524)
		(layer "F.Cu")
		(net "HSC_ON")
	)
	(segment
		(start 234.413552 -402.472906)
		(end 235.750608 -402.472906)
		(width 0.1524)
		(layer "F.Cu")
		(net "HSC_ON")
	)
	(segment
		(start 235.750608 -402.472906)
		(end 235.967524 -402.689822)
		(width 0.1524)
		(layer "F.Cu")
		(net "HSC_ON")
	)
	(segment
		(start 192.452498 -402.128482)
		(end 193.078608 -402.128482)
		(width 0.1524)
		(layer "F.Cu")
		(net "HSC_ON")
	)
	(segment
		(start 235.967524 -402.689822)
		(end 237.001558 -402.689822)
		(width 0.1524)
		(layer "F.Cu")
		(net "HSC_ON")
	)
	(segment
		(start 203.619608 -403.988524)
		(end 204.454506 -404.823422)
		(width 0.1524)
		(layer "F.Cu")
		(net "HSC_ON")
	)
	(segment
		(start 215.665558 -404.823422)
		(end 215.122506 -404.823422)
		(width 0.1524)
		(layer "F.Cu")
		(net "HSC_ON")
	)
	(segment
		(start 202.409552 -402.472906)
		(end 203.619608 -402.472906)
		(width 0.1524)
		(layer "F.Cu")
		(net "HSC_ON")
	)
	(segment
		(start 214.287608 -403.988524)
		(end 214.287608 -402.472906)
		(width 0.1524)
		(layer "F.Cu")
		(net "HSC_ON")
	)
	(segment
		(start 204.454506 -404.823422)
		(end 204.997558 -404.823422)
		(width 0.1524)
		(layer "F.Cu")
		(net "HSC_ON")
	)
	(via
		(at 235.750608 -402.472906)
		(size 0.508)
		(drill 0.254)
		(layers "F.Cu" "B.Cu")
		(net "HSC_ON")
	)
	(via
		(at 214.287608 -402.472906)
		(size 0.508)
		(drill 0.254)
		(layers "F.Cu" "B.Cu")
		(net "HSC_ON")
	)
	(via
		(at 224.955608 -402.472906)
		(size 0.508)
		(drill 0.254)
		(layers "F.Cu" "B.Cu")
		(net "HSC_ON")
	)
	(via
		(at 193.078608 -402.128482)
		(size 0.508)
		(drill 0.254)
		(layers "F.Cu" "B.Cu")
		(net "HSC_ON")
	)
	(via
		(at 203.619608 -402.472906)
		(size 0.508)
		(drill 0.254)
		(layers "F.Cu" "B.Cu")
		(net "HSC_ON")
	)
	(segment
		(start 194.0814 -402.5392)
		(end 195.988178 -400.632422)
		(width 0.1524)
		(layer "In13.Cu")
		(net "HSC_ON")
	)
	(segment
		(start 212.726524 -400.911822)
		(end 207.429608 -400.911822)
		(width 0.1524)
		(layer "In13.Cu")
		(net "HSC_ON")
	)
	(segment
		(start 203.619608 -401.882102)
		(end 203.619608 -402.472906)
		(width 0.1524)
		(layer "In13.Cu")
		(net "HSC_ON")
	)
	(segment
		(start 193.489326 -402.5392)
		(end 194.0814 -402.5392)
		(width 0.1524)
		(layer "In13.Cu")
		(net "HSC_ON")
	)
	(segment
		(start 228.841808 -400.835622)
		(end 227.394008 -402.283422)
		(width 0.1524)
		(layer "In13.Cu")
		(net "HSC_ON")
	)
	(segment
		(start 224.955608 -402.472906)
		(end 223.369124 -400.886422)
		(width 0.1524)
		(layer "In13.Cu")
		(net "HSC_ON")
	)
	(segment
		(start 214.287608 -402.472906)
		(end 212.726524 -400.911822)
		(width 0.1524)
		(layer "In13.Cu")
		(net "HSC_ON")
	)
	(segment
		(start 223.369124 -400.886422)
		(end 218.072208 -400.886422)
		(width 0.1524)
		(layer "In13.Cu")
		(net "HSC_ON")
	)
	(segment
		(start 195.988178 -400.632422)
		(end 202.369928 -400.632422)
		(width 0.1524)
		(layer "In13.Cu")
		(net "HSC_ON")
	)
	(segment
		(start 193.078608 -402.128482)
		(end 193.489326 -402.5392)
		(width 0.1524)
		(layer "In13.Cu")
		(net "HSC_ON")
	)
	(segment
		(start 225.145092 -402.283422)
		(end 224.955608 -402.472906)
		(width 0.1524)
		(layer "In13.Cu")
		(net "HSC_ON")
	)
	(segment
		(start 216.700608 -402.258022)
		(end 214.502492 -402.258022)
		(width 0.1524)
		(layer "In13.Cu")
		(net "HSC_ON")
	)
	(segment
		(start 203.809092 -402.283422)
		(end 203.619608 -402.472906)
		(width 0.1524)
		(layer "In13.Cu")
		(net "HSC_ON")
	)
	(segment
		(start 218.072208 -400.886422)
		(end 216.700608 -402.258022)
		(width 0.1524)
		(layer "In13.Cu")
		(net "HSC_ON")
	)
	(segment
		(start 227.394008 -402.283422)
		(end 225.145092 -402.283422)
		(width 0.1524)
		(layer "In13.Cu")
		(net "HSC_ON")
	)
	(segment
		(start 207.429608 -400.911822)
		(end 206.058008 -402.283422)
		(width 0.1524)
		(layer "In13.Cu")
		(net "HSC_ON")
	)
	(segment
		(start 206.058008 -402.283422)
		(end 203.809092 -402.283422)
		(width 0.1524)
		(layer "In13.Cu")
		(net "HSC_ON")
	)
	(segment
		(start 202.369928 -400.632422)
		(end 203.619608 -401.882102)
		(width 0.1524)
		(layer "In13.Cu")
		(net "HSC_ON")
	)
	(segment
		(start 235.750608 -402.472906)
		(end 234.113324 -400.835622)
		(width 0.1524)
		(layer "In13.Cu")
		(net "HSC_ON")
	)
	(segment
		(start 234.113324 -400.835622)
		(end 228.841808 -400.835622)
		(width 0.1524)
		(layer "In13.Cu")
		(net "HSC_ON")
	)
	(segment
		(start 214.502492 -402.258022)
		(end 214.287608 -402.472906)
		(width 0.1524)
		(layer "In13.Cu")
		(net "HSC_ON")
	)
	(segment
		(start 228.53904 -399.743422)
		(end 229.7684 -400.972782)
		(width 0.1524)
		(layer "F.Cu")
		(net "HSC_OCREF")
	)
	(segment
		(start 208.404968 -400.972782)
		(end 208.58988 -400.972782)
		(width 0.1524)
		(layer "F.Cu")
		(net "HSC_OCREF")
	)
	(segment
		(start 205.797658 -399.743422)
		(end 207.175608 -399.743422)
		(width 0.1524)
		(layer "F.Cu")
		(net "HSC_OCREF")
	)
	(segment
		(start 196.459348 -399.085562)
		(end 197.396608 -400.022822)
		(width 0.1524)
		(layer "F.Cu")
		(net "HSC_OCREF")
	)
	(segment
		(start 227.133658 -399.743422)
		(end 228.511608 -399.743422)
		(width 0.1524)
		(layer "F.Cu")
		(net "HSC_OCREF")
	)
	(segment
		(start 229.7684 -400.972782)
		(end 229.92588 -400.972782)
		(width 0.1524)
		(layer "F.Cu")
		(net "HSC_OCREF")
	)
	(segment
		(start 197.396608 -400.022822)
		(end 197.396608 -400.657822)
		(width 0.1524)
		(layer "F.Cu")
		(net "HSC_OCREF")
	)
	(segment
		(start 182.635144 -399.905982)
		(end 183.21401 -400.484848)
		(width 0.1524)
		(layer "F.Cu")
		(net "HSC_OCREF")
	)
	(segment
		(start 217.87104 -399.743422)
		(end 219.1004 -400.972782)
		(width 0.1524)
		(layer "F.Cu")
		(net "HSC_OCREF")
	)
	(segment
		(start 217.843608 -399.743422)
		(end 217.87104 -399.743422)
		(width 0.1524)
		(layer "F.Cu")
		(net "HSC_OCREF")
	)
	(segment
		(start 219.1004 -400.972782)
		(end 219.25788 -400.972782)
		(width 0.1524)
		(layer "F.Cu")
		(net "HSC_OCREF")
	)
	(segment
		(start 197.711568 -400.972782)
		(end 197.92188 -400.972782)
		(width 0.1524)
		(layer "F.Cu")
		(net "HSC_OCREF")
	)
	(segment
		(start 228.511608 -399.743422)
		(end 228.53904 -399.743422)
		(width 0.1524)
		(layer "F.Cu")
		(net "HSC_OCREF")
	)
	(segment
		(start 216.465658 -399.743422)
		(end 217.843608 -399.743422)
		(width 0.1524)
		(layer "F.Cu")
		(net "HSC_OCREF")
	)
	(segment
		(start 195.253356 -399.085562)
		(end 196.459348 -399.085562)
		(width 0.1524)
		(layer "F.Cu")
		(net "HSC_OCREF")
	)
	(segment
		(start 207.175608 -399.743422)
		(end 208.404968 -400.972782)
		(width 0.1524)
		(layer "F.Cu")
		(net "HSC_OCREF")
	)
	(segment
		(start 195.253356 -399.743422)
		(end 195.253356 -399.085562)
		(width 0.1524)
		(layer "F.Cu")
		(net "HSC_OCREF")
	)
	(segment
		(start 182.220108 -399.905982)
		(end 182.635144 -399.905982)
		(width 0.1524)
		(layer "F.Cu")
		(net "HSC_OCREF")
	)
	(segment
		(start 197.396608 -400.657822)
		(end 197.711568 -400.972782)
		(width 0.1524)
		(layer "F.Cu")
		(net "HSC_OCREF")
	)
	(via
		(at 207.175608 -399.743422)
		(size 0.508)
		(drill 0.254)
		(layers "F.Cu" "B.Cu")
		(net "HSC_OCREF")
	)
	(via
		(at 195.253356 -399.085562)
		(size 0.508)
		(drill 0.254)
		(layers "F.Cu" "B.Cu")
		(net "HSC_OCREF")
	)
	(via
		(at 182.220108 -399.905982)
		(size 0.508)
		(drill 0.254)
		(layers "F.Cu" "B.Cu")
		(net "HSC_OCREF")
	)
	(via
		(at 228.511608 -399.743422)
		(size 0.508)
		(drill 0.254)
		(layers "F.Cu" "B.Cu")
		(net "HSC_OCREF")
	)
	(via
		(at 217.843608 -399.743422)
		(size 0.508)
		(drill 0.254)
		(layers "F.Cu" "B.Cu")
		(net "HSC_OCREF")
	)
	(segment
		(start 194.027044 -390.822942)
		(end 195.253356 -392.049254)
		(width 0.1524)
		(layer "In4.Cu")
		(net "HSC_OCREF")
	)
	(segment
		(start 183.495188 -390.822942)
		(end 194.027044 -390.822942)
		(width 0.1524)
		(layer "In4.Cu")
		(net "HSC_OCREF")
	)
	(segment
		(start 207.175608 -391.889742)
		(end 206.065628 -390.779762)
		(width 0.1524)
		(layer "In4.Cu")
		(net "HSC_OCREF")
	)
	(segment
		(start 216.878408 -390.734042)
		(end 208.331308 -390.734042)
		(width 0.1524)
		(layer "In4.Cu")
		(net "HSC_OCREF")
	)
	(segment
		(start 218.895168 -390.647682)
		(end 217.843608 -391.699242)
		(width 0.1524)
		(layer "In4.Cu")
		(net "HSC_OCREF")
	)
	(segment
		(start 228.511608 -391.435082)
		(end 227.724208 -390.647682)
		(width 0.1524)
		(layer "In4.Cu")
		(net "HSC_OCREF")
	)
	(segment
		(start 181.58206 -399.267934)
		(end 181.58206 -398.7419)
		(width 0.1524)
		(layer "In4.Cu")
		(net "HSC_OCREF")
	)
	(segment
		(start 228.511608 -399.743422)
		(end 228.511608 -391.435082)
		(width 0.1524)
		(layer "In4.Cu")
		(net "HSC_OCREF")
	)
	(segment
		(start 182.220108 -399.905982)
		(end 181.58206 -399.267934)
		(width 0.1524)
		(layer "In4.Cu")
		(net "HSC_OCREF")
	)
	(segment
		(start 196.522848 -390.779762)
		(end 195.253356 -392.049254)
		(width 0.1524)
		(layer "In4.Cu")
		(net "HSC_OCREF")
	)
	(segment
		(start 181.58206 -398.7419)
		(end 181.046628 -398.206468)
		(width 0.1524)
		(layer "In4.Cu")
		(net "HSC_OCREF")
	)
	(segment
		(start 207.175608 -391.889742)
		(end 207.175608 -399.743422)
		(width 0.1524)
		(layer "In4.Cu")
		(net "HSC_OCREF")
	)
	(segment
		(start 217.843608 -391.699242)
		(end 216.878408 -390.734042)
		(width 0.1524)
		(layer "In4.Cu")
		(net "HSC_OCREF")
	)
	(segment
		(start 181.046628 -398.206468)
		(end 181.046628 -393.271502)
		(width 0.1524)
		(layer "In4.Cu")
		(net "HSC_OCREF")
	)
	(segment
		(start 217.843608 -391.699242)
		(end 217.843608 -399.743422)
		(width 0.1524)
		(layer "In4.Cu")
		(net "HSC_OCREF")
	)
	(segment
		(start 195.253356 -399.085562)
		(end 195.253356 -392.049254)
		(width 0.1524)
		(layer "In4.Cu")
		(net "HSC_OCREF")
	)
	(segment
		(start 206.065628 -390.779762)
		(end 196.522848 -390.779762)
		(width 0.1524)
		(layer "In4.Cu")
		(net "HSC_OCREF")
	)
	(segment
		(start 208.331308 -390.734042)
		(end 207.175608 -391.889742)
		(width 0.1524)
		(layer "In4.Cu")
		(net "HSC_OCREF")
	)
	(segment
		(start 181.046628 -393.271502)
		(end 183.495188 -390.822942)
		(width 0.1524)
		(layer "In4.Cu")
		(net "HSC_OCREF")
	)
	(segment
		(start 227.724208 -390.647682)
		(end 218.895168 -390.647682)
		(width 0.1524)
		(layer "In4.Cu")
		(net "HSC_OCREF")
	)
	(segment
		(start 214.668608 -407.871422)
		(end 214.287608 -407.490422)
		(width 0.1524)
		(layer "F.Cu")
		(net "HSC_MODE_2")
	)
	(segment
		(start 213.559898 -404.716996)
		(end 213.315804 -404.472902)
		(width 0.1524)
		(layer "F.Cu")
		(net "HSC_MODE_2")
	)
	(segment
		(start 213.315804 -404.472902)
		(end 213.090252 -404.472902)
		(width 0.1524)
		(layer "F.Cu")
		(net "HSC_MODE_2")
	)
	(segment
		(start 213.559898 -406.762712)
		(end 213.559898 -404.716996)
		(width 0.1524)
		(layer "F.Cu")
		(net "HSC_MODE_2")
	)
	(segment
		(start 214.287608 -407.490422)
		(end 213.559898 -406.762712)
		(width 0.1524)
		(layer "F.Cu")
		(net "HSC_MODE_2")
	)
	(segment
		(start 215.665558 -407.871422)
		(end 214.668608 -407.871422)
		(width 0.1524)
		(layer "F.Cu")
		(net "HSC_MODE_2")
	)
	(via
		(at 214.287608 -407.490422)
		(size 0.762)
		(drill 0.381)
		(layers "F.Cu" "B.Cu")
		(net "HSC_MODE_2")
	)
	(segment
		(start 202.891898 -404.716996)
		(end 202.647804 -404.472902)
		(width 0.1524)
		(layer "F.Cu")
		(net "HSC_MODE_1")
	)
	(segment
		(start 202.891898 -406.762712)
		(end 202.891898 -404.716996)
		(width 0.1524)
		(layer "F.Cu")
		(net "HSC_MODE_1")
	)
	(segment
		(start 203.619608 -407.490422)
		(end 202.891898 -406.762712)
		(width 0.1524)
		(layer "F.Cu")
		(net "HSC_MODE_1")
	)
	(segment
		(start 204.000608 -407.871422)
		(end 203.619608 -407.490422)
		(width 0.1524)
		(layer "F.Cu")
		(net "HSC_MODE_1")
	)
	(segment
		(start 204.997558 -407.871422)
		(end 204.000608 -407.871422)
		(width 0.1524)
		(layer "F.Cu")
		(net "HSC_MODE_1")
	)
	(segment
		(start 202.647804 -404.472902)
		(end 202.422252 -404.472902)
		(width 0.1524)
		(layer "F.Cu")
		(net "HSC_MODE_1")
	)
	(via
		(at 203.619608 -407.490422)
		(size 0.762)
		(drill 0.381)
		(layers "F.Cu" "B.Cu")
		(net "HSC_MODE_1")
	)
	(segment
		(start 191.441578 -404.414482)
		(end 190.806578 -405.049482)
		(width 0.1524)
		(layer "F.Cu")
		(net "HSC_MODE")
	)
	(segment
		(start 190.806578 -405.049482)
		(end 190.401448 -405.049482)
		(width 0.1524)
		(layer "F.Cu")
		(net "HSC_MODE")
	)
	(segment
		(start 190.401448 -404.899622)
		(end 189.349126 -403.8473)
		(width 0.1524)
		(layer "F.Cu")
		(net "HSC_MODE")
	)
	(segment
		(start 191.652398 -404.414482)
		(end 191.441578 -404.414482)
		(width 0.1524)
		(layer "F.Cu")
		(net "HSC_MODE")
	)
	(segment
		(start 189.349126 -403.8473)
		(end 189.151514 -403.8473)
		(width 0.1524)
		(layer "F.Cu")
		(net "HSC_MODE")
	)
	(segment
		(start 190.401448 -405.049482)
		(end 190.401448 -404.899622)
		(width 0.1524)
		(layer "F.Cu")
		(net "HSC_MODE")
	)
	(via
		(at 190.401448 -405.049482)
		(size 0.508)
		(drill 0.254)
		(layers "F.Cu" "B.Cu")
		(net "HSC_MODE")
	)
	(segment
		(start 197.111366 -401.97278)
		(end 197.93458 -401.97278)
		(width 0.1524)
		(layer "F.Cu")
		(net "HSC_IMON")
	)
	(segment
		(start 181.397148 -400.104102)
		(end 181.397148 -399.880582)
		(width 0.1524)
		(layer "F.Cu")
		(net "HSC_IMON")
	)
	(segment
		(start 208.60258 -401.97278)
		(end 207.175608 -401.97278)
		(width 0.1524)
		(layer "F.Cu")
		(net "HSC_IMON")
	)
	(segment
		(start 227.343462 -402.791422)
		(end 227.133658 -402.791422)
		(width 0.1524)
		(layer "F.Cu")
		(net "HSC_IMON")
	)
	(segment
		(start 216.675462 -402.791422)
		(end 216.465658 -402.791422)
		(width 0.1524)
		(layer "F.Cu")
		(net "HSC_IMON")
	)
	(segment
		(start 217.843608 -401.97278)
		(end 217.494104 -401.97278)
		(width 0.1524)
		(layer "F.Cu")
		(net "HSC_IMON")
	)
	(segment
		(start 181.397148 -399.880582)
		(end 181.150768 -399.634202)
		(width 0.1524)
		(layer "F.Cu")
		(net "HSC_IMON")
	)
	(segment
		(start 195.542408 -401.800822)
		(end 195.898008 -401.445222)
		(width 0.1524)
		(layer "F.Cu")
		(net "HSC_IMON")
	)
	(segment
		(start 219.27058 -401.97278)
		(end 217.843608 -401.97278)
		(width 0.1524)
		(layer "F.Cu")
		(net "HSC_IMON")
	)
	(segment
		(start 180.179218 -399.634202)
		(end 179.752498 -399.207482)
		(width 0.1524)
		(layer "F.Cu")
		(net "HSC_IMON")
	)
	(segment
		(start 195.256658 -401.800822)
		(end 195.542408 -401.800822)
		(width 0.1524)
		(layer "F.Cu")
		(net "HSC_IMON")
	)
	(segment
		(start 217.494104 -401.97278)
		(end 216.675462 -402.791422)
		(width 0.1524)
		(layer "F.Cu")
		(net "HSC_IMON")
	)
	(segment
		(start 207.175608 -401.97278)
		(end 206.749396 -401.97278)
		(width 0.1524)
		(layer "F.Cu")
		(net "HSC_IMON")
	)
	(segment
		(start 196.583808 -401.445222)
		(end 197.111366 -401.97278)
		(width 0.1524)
		(layer "F.Cu")
		(net "HSC_IMON")
	)
	(segment
		(start 228.511608 -401.97278)
		(end 228.162104 -401.97278)
		(width 0.1524)
		(layer "F.Cu")
		(net "HSC_IMON")
	)
	(segment
		(start 205.930754 -402.791422)
		(end 205.797658 -402.791422)
		(width 0.1524)
		(layer "F.Cu")
		(net "HSC_IMON")
	)
	(segment
		(start 181.150768 -399.634202)
		(end 180.179218 -399.634202)
		(width 0.1524)
		(layer "F.Cu")
		(net "HSC_IMON")
	)
	(segment
		(start 228.162104 -401.97278)
		(end 227.343462 -402.791422)
		(width 0.1524)
		(layer "F.Cu")
		(net "HSC_IMON")
	)
	(segment
		(start 179.752498 -398.191482)
		(end 179.752498 -399.207482)
		(width 0.1524)
		(layer "F.Cu")
		(net "HSC_IMON")
	)
	(segment
		(start 182.440326 -401.14728)
		(end 181.397148 -400.104102)
		(width 0.1524)
		(layer "F.Cu")
		(net "HSC_IMON")
	)
	(segment
		(start 229.93858 -401.97278)
		(end 228.511608 -401.97278)
		(width 0.1524)
		(layer "F.Cu")
		(net "HSC_IMON")
	)
	(segment
		(start 206.749396 -401.97278)
		(end 205.930754 -402.791422)
		(width 0.1524)
		(layer "F.Cu")
		(net "HSC_IMON")
	)
	(segment
		(start 195.898008 -401.445222)
		(end 196.583808 -401.445222)
		(width 0.1524)
		(layer "F.Cu")
		(net "HSC_IMON")
	)
	(segment
		(start 182.676546 -401.14728)
		(end 182.440326 -401.14728)
		(width 0.1524)
		(layer "F.Cu")
		(net "HSC_IMON")
	)
	(via
		(at 217.843608 -401.97278)
		(size 0.508)
		(drill 0.254)
		(layers "F.Cu" "B.Cu")
		(net "HSC_IMON")
	)
	(via
		(at 181.397148 -399.880582)
		(size 0.762)
		(drill 0.254)
		(layers "F.Cu" "B.Cu")
		(net "HSC_IMON")
	)
	(via
		(at 196.583808 -401.445222)
		(size 0.508)
		(drill 0.254)
		(layers "F.Cu" "B.Cu")
		(net "HSC_IMON")
	)
	(via
		(at 207.175608 -401.97278)
		(size 0.508)
		(drill 0.254)
		(layers "F.Cu" "B.Cu")
		(net "HSC_IMON")
	)
	(via
		(at 228.511608 -401.97278)
		(size 0.508)
		(drill 0.254)
		(layers "F.Cu" "B.Cu")
		(net "HSC_IMON")
	)
	(segment
		(start 183.09844 -391.97915)
		(end 183.09844 -397.1925)
		(width 0.1524)
		(layer "In4.Cu")
		(net "HSC_IMON")
	)
	(segment
		(start 183.56834 -398.54632)
		(end 183.09844 -399.01622)
		(width 0.1524)
		(layer "In4.Cu")
		(net "HSC_IMON")
	)
	(segment
		(start 219.319348 -391.137902)
		(end 218.504008 -391.953242)
		(width 0.1524)
		(layer "In4.Cu")
		(net "HSC_IMON")
	)
	(segment
		(start 218.504008 -401.31238)
		(end 217.843608 -401.97278)
		(width 0.1524)
		(layer "In4.Cu")
		(net "HSC_IMON")
	)
	(segment
		(start 183.09844 -399.01622)
		(end 183.09844 -400.11096)
		(width 0.1524)
		(layer "In4.Cu")
		(net "HSC_IMON")
	)
	(segment
		(start 217.241628 -400.073622)
		(end 217.241628 -392.021822)
		(width 0.1524)
		(layer "In4.Cu")
		(net "HSC_IMON")
	)
	(segment
		(start 217.843608 -401.97278)
		(end 217.843608 -400.675602)
		(width 0.1524)
		(layer "In4.Cu")
		(net "HSC_IMON")
	)
	(segment
		(start 227.216208 -391.137902)
		(end 219.319348 -391.137902)
		(width 0.1524)
		(layer "In4.Cu")
		(net "HSC_IMON")
	)
	(segment
		(start 206.601568 -400.170142)
		(end 206.601568 -392.278362)
		(width 0.1524)
		(layer "In4.Cu")
		(net "HSC_IMON")
	)
	(segment
		(start 228.511608 -401.97278)
		(end 228.511608 -400.754342)
		(width 0.1524)
		(layer "In4.Cu")
		(net "HSC_IMON")
	)
	(segment
		(start 227.985828 -391.907522)
		(end 227.216208 -391.137902)
		(width 0.1524)
		(layer "In4.Cu")
		(net "HSC_IMON")
	)
	(segment
		(start 207.175608 -400.744182)
		(end 206.601568 -400.170142)
		(width 0.1524)
		(layer "In4.Cu")
		(net "HSC_IMON")
	)
	(segment
		(start 217.843608 -400.675602)
		(end 217.241628 -400.073622)
		(width 0.1524)
		(layer "In4.Cu")
		(net "HSC_IMON")
	)
	(segment
		(start 207.175608 -401.97278)
		(end 207.175608 -400.744182)
		(width 0.1524)
		(layer "In4.Cu")
		(net "HSC_IMON")
	)
	(segment
		(start 181.38902 -399.88871)
		(end 181.397148 -399.880582)
		(width 0.1524)
		(layer "In4.Cu")
		(net "HSC_IMON")
	)
	(segment
		(start 183.56834 -397.6624)
		(end 183.56834 -398.54632)
		(width 0.1524)
		(layer "In4.Cu")
		(net "HSC_IMON")
	)
	(segment
		(start 196.583808 -391.836402)
		(end 196.583808 -401.445222)
		(width 0.1524)
		(layer "In4.Cu")
		(net "HSC_IMON")
	)
	(segment
		(start 183.09844 -400.11096)
		(end 182.46598 -400.74342)
		(width 0.1524)
		(layer "In4.Cu")
		(net "HSC_IMON")
	)
	(segment
		(start 227.985828 -400.228562)
		(end 227.985828 -391.907522)
		(width 0.1524)
		(layer "In4.Cu")
		(net "HSC_IMON")
	)
	(segment
		(start 207.714088 -401.4343)
		(end 207.175608 -401.97278)
		(width 0.1524)
		(layer "In4.Cu")
		(net "HSC_IMON")
	)
	(segment
		(start 194.709288 -392.392662)
		(end 193.731388 -391.414762)
		(width 0.1524)
		(layer "In4.Cu")
		(net "HSC_IMON")
	)
	(segment
		(start 205.682088 -391.358882)
		(end 197.061328 -391.358882)
		(width 0.1524)
		(layer "In4.Cu")
		(net "HSC_IMON")
	)
	(segment
		(start 193.731388 -391.414762)
		(end 183.662828 -391.414762)
		(width 0.1524)
		(layer "In4.Cu")
		(net "HSC_IMON")
	)
	(segment
		(start 183.09844 -397.1925)
		(end 183.56834 -397.6624)
		(width 0.1524)
		(layer "In4.Cu")
		(net "HSC_IMON")
	)
	(segment
		(start 206.601568 -392.278362)
		(end 205.682088 -391.358882)
		(width 0.1524)
		(layer "In4.Cu")
		(net "HSC_IMON")
	)
	(segment
		(start 228.511608 -400.754342)
		(end 227.985828 -400.228562)
		(width 0.1524)
		(layer "In4.Cu")
		(net "HSC_IMON")
	)
	(segment
		(start 181.38902 -400.48942)
		(end 181.38902 -399.88871)
		(width 0.1524)
		(layer "In4.Cu")
		(net "HSC_IMON")
	)
	(segment
		(start 196.583808 -401.445222)
		(end 194.709288 -399.570702)
		(width 0.1524)
		(layer "In4.Cu")
		(net "HSC_IMON")
	)
	(segment
		(start 183.662828 -391.414762)
		(end 183.09844 -391.97915)
		(width 0.1524)
		(layer "In4.Cu")
		(net "HSC_IMON")
	)
	(segment
		(start 208.864708 -391.333482)
		(end 207.714088 -392.484102)
		(width 0.1524)
		(layer "In4.Cu")
		(net "HSC_IMON")
	)
	(segment
		(start 194.709288 -399.570702)
		(end 194.709288 -392.392662)
		(width 0.1524)
		(layer "In4.Cu")
		(net "HSC_IMON")
	)
	(segment
		(start 197.061328 -391.358882)
		(end 196.583808 -391.836402)
		(width 0.1524)
		(layer "In4.Cu")
		(net "HSC_IMON")
	)
	(segment
		(start 217.241628 -392.021822)
		(end 216.553288 -391.333482)
		(width 0.1524)
		(layer "In4.Cu")
		(net "HSC_IMON")
	)
	(segment
		(start 218.504008 -391.953242)
		(end 218.504008 -401.31238)
		(width 0.1524)
		(layer "In4.Cu")
		(net "HSC_IMON")
	)
	(segment
		(start 182.46598 -400.74342)
		(end 181.64302 -400.74342)
		(width 0.1524)
		(layer "In4.Cu")
		(net "HSC_IMON")
	)
	(segment
		(start 216.553288 -391.333482)
		(end 208.864708 -391.333482)
		(width 0.1524)
		(layer "In4.Cu")
		(net "HSC_IMON")
	)
	(segment
		(start 181.64302 -400.74342)
		(end 181.38902 -400.48942)
		(width 0.1524)
		(layer "In4.Cu")
		(net "HSC_IMON")
	)
	(segment
		(start 207.714088 -392.484102)
		(end 207.714088 -401.4343)
		(width 0.1524)
		(layer "In4.Cu")
		(net "HSC_IMON")
	)
	(segment
		(start 214.287862 -404.514558)
		(end 213.246208 -403.472904)
		(width 0.1524)
		(layer "F.Cu")
		(net "HSC_FLT_TYPE_2")
	)
	(segment
		(start 215.049862 -406.855422)
		(end 214.287862 -406.093422)
		(width 0.1524)
		(layer "F.Cu")
		(net "HSC_FLT_TYPE_2")
	)
	(segment
		(start 213.246208 -403.472904)
		(end 213.077552 -403.472904)
		(width 0.1524)
		(layer "F.Cu")
		(net "HSC_FLT_TYPE_2")
	)
	(segment
		(start 215.665558 -406.855422)
		(end 215.049862 -406.855422)
		(width 0.1524)
		(layer "F.Cu")
		(net "HSC_FLT_TYPE_2")
	)
	(segment
		(start 214.287862 -406.093422)
		(end 214.287862 -404.514558)
		(width 0.1524)
		(layer "F.Cu")
		(net "HSC_FLT_TYPE_2")
	)
	(via
		(at 214.287862 -406.093422)
		(size 0.762)
		(drill 0.381)
		(layers "F.Cu" "B.Cu")
		(net "HSC_FLT_TYPE_2")
	)
	(segment
		(start 203.619862 -404.514558)
		(end 202.578208 -403.472904)
		(width 0.1524)
		(layer "F.Cu")
		(net "HSC_FLT_TYPE_1")
	)
	(segment
		(start 202.578208 -403.472904)
		(end 202.409552 -403.472904)
		(width 0.1524)
		(layer "F.Cu")
		(net "HSC_FLT_TYPE_1")
	)
	(segment
		(start 203.619862 -406.093422)
		(end 203.619862 -404.514558)
		(width 0.1524)
		(layer "F.Cu")
		(net "HSC_FLT_TYPE_1")
	)
	(segment
		(start 204.997558 -406.855422)
		(end 204.381862 -406.855422)
		(width 0.1524)
		(layer "F.Cu")
		(net "HSC_FLT_TYPE_1")
	)
	(segment
		(start 204.381862 -406.855422)
		(end 203.619862 -406.093422)
		(width 0.1524)
		(layer "F.Cu")
		(net "HSC_FLT_TYPE_1")
	)
	(via
		(at 203.619862 -406.093422)
		(size 0.762)
		(drill 0.381)
		(layers "F.Cu" "B.Cu")
		(net "HSC_FLT_TYPE_1")
	)
	(segment
		(start 205.797658 -406.855422)
		(end 206.413608 -406.855422)
		(width 0.1524)
		(layer "F.Cu")
		(net "HSC_FLT_TYPE")
	)
	(segment
		(start 227.133658 -406.855422)
		(end 227.749608 -406.855422)
		(width 0.1524)
		(layer "F.Cu")
		(net "HSC_FLT_TYPE")
	)
	(segment
		(start 190.414148 -404.046182)
		(end 189.765178 -403.397212)
		(width 0.1524)
		(layer "F.Cu")
		(net "HSC_FLT_TYPE")
	)
	(segment
		(start 216.465658 -406.855422)
		(end 217.081608 -406.855422)
		(width 0.1524)
		(layer "F.Cu")
		(net "HSC_FLT_TYPE")
	)
	(segment
		(start 189.765178 -403.397212)
		(end 189.151514 -403.397212)
		(width 0.1524)
		(layer "F.Cu")
		(net "HSC_FLT_TYPE")
	)
	(segment
		(start 237.801658 -403.705822)
		(end 238.417608 -403.705822)
		(width 0.1524)
		(layer "F.Cu")
		(net "HSC_FLT_TYPE")
	)
	(via
		(at 190.414148 -404.046182)
		(size 0.762)
		(drill 0.254)
		(layers "F.Cu" "B.Cu")
		(net "HSC_FLT_TYPE")
	)
	(via
		(at 238.417608 -403.705822)
		(size 0.508)
		(drill 0.254)
		(layers "F.Cu" "B.Cu")
		(net "HSC_FLT_TYPE")
	)
	(via
		(at 206.413608 -406.855422)
		(size 0.508)
		(drill 0.254)
		(layers "F.Cu" "B.Cu")
		(net "HSC_FLT_TYPE")
	)
	(via
		(at 217.081608 -406.855422)
		(size 0.508)
		(drill 0.254)
		(layers "F.Cu" "B.Cu")
		(net "HSC_FLT_TYPE")
	)
	(via
		(at 227.749608 -406.855422)
		(size 0.508)
		(drill 0.254)
		(layers "F.Cu" "B.Cu")
		(net "HSC_FLT_TYPE")
	)
	(segment
		(start 227.216208 -409.720034)
		(end 228.569774 -411.0736)
		(width 0.1524)
		(layer "In4.Cu")
		(net "HSC_FLT_TYPE")
	)
	(segment
		(start 203.650088 -408.407362)
		(end 203.650088 -411.306518)
		(width 0.1524)
		(layer "In4.Cu")
		(net "HSC_FLT_TYPE")
	)
	(segment
		(start 214.506048 -411.404562)
		(end 214.506048 -408.359102)
		(width 0.1524)
		(layer "In4.Cu")
		(net "HSC_FLT_TYPE")
	)
	(segment
		(start 217.564208 -407.338022)
		(end 217.564208 -411.335982)
		(width 0.1524)
		(layer "In4.Cu")
		(net "HSC_FLT_TYPE")
	)
	(segment
		(start 205.202028 -406.855422)
		(end 203.650088 -408.407362)
		(width 0.1524)
		(layer "In4.Cu")
		(net "HSC_FLT_TYPE")
	)
	(segment
		(start 225.044508 -411.556962)
		(end 225.044508 -408.458162)
		(width 0.1524)
		(layer "In4.Cu")
		(net "HSC_FLT_TYPE")
	)
	(segment
		(start 206.896208 -407.338022)
		(end 206.896208 -411.308042)
		(width 0.1524)
		(layer "In4.Cu")
		(net "HSC_FLT_TYPE")
	)
	(segment
		(start 206.896208 -411.308042)
		(end 207.566768 -411.978602)
		(width 0.1524)
		(layer "In4.Cu")
		(net "HSC_FLT_TYPE")
	)
	(segment
		(start 193.575178 -404.620222)
		(end 192.81394 -405.38146)
		(width 0.1524)
		(layer "In4.Cu")
		(net "HSC_FLT_TYPE")
	)
	(segment
		(start 216.009728 -406.855422)
		(end 217.081608 -406.855422)
		(width 0.1524)
		(layer "In4.Cu")
		(net "HSC_FLT_TYPE")
	)
	(segment
		(start 191.749426 -405.38146)
		(end 190.414148 -404.046182)
		(width 0.1524)
		(layer "In4.Cu")
		(net "HSC_FLT_TYPE")
	)
	(segment
		(start 227.749608 -406.855422)
		(end 227.216208 -407.388822)
		(width 0.1524)
		(layer "In4.Cu")
		(net "HSC_FLT_TYPE")
	)
	(segment
		(start 227.216208 -407.388822)
		(end 227.216208 -409.720034)
		(width 0.1524)
		(layer "In4.Cu")
		(net "HSC_FLT_TYPE")
	)
	(segment
		(start 203.059284 -411.897322)
		(end 195.405756 -411.897322)
		(width 0.1524)
		(layer "In4.Cu")
		(net "HSC_FLT_TYPE")
	)
	(segment
		(start 194.04076 -404.620222)
		(end 193.575178 -404.620222)
		(width 0.1524)
		(layer "In4.Cu")
		(net "HSC_FLT_TYPE")
	)
	(segment
		(start 206.413608 -406.855422)
		(end 205.202028 -406.855422)
		(width 0.1524)
		(layer "In4.Cu")
		(net "HSC_FLT_TYPE")
	)
	(segment
		(start 225.044508 -408.458162)
		(end 226.647248 -406.855422)
		(width 0.1524)
		(layer "In4.Cu")
		(net "HSC_FLT_TYPE")
	)
	(segment
		(start 236.177328 -408.452066)
		(end 236.177328 -405.946102)
		(width 0.1524)
		(layer "In4.Cu")
		(net "HSC_FLT_TYPE")
	)
	(segment
		(start 206.413608 -406.855422)
		(end 206.896208 -407.338022)
		(width 0.1524)
		(layer "In4.Cu")
		(net "HSC_FLT_TYPE")
	)
	(segment
		(start 192.81394 -405.38146)
		(end 191.749426 -405.38146)
		(width 0.1524)
		(layer "In4.Cu")
		(net "HSC_FLT_TYPE")
	)
	(segment
		(start 217.081608 -406.855422)
		(end 217.564208 -407.338022)
		(width 0.1524)
		(layer "In4.Cu")
		(net "HSC_FLT_TYPE")
	)
	(segment
		(start 194.44462 -405.024082)
		(end 194.04076 -404.620222)
		(width 0.1524)
		(layer "In4.Cu")
		(net "HSC_FLT_TYPE")
	)
	(segment
		(start 236.177328 -405.946102)
		(end 238.417608 -403.705822)
		(width 0.1524)
		(layer "In4.Cu")
		(net "HSC_FLT_TYPE")
	)
	(segment
		(start 207.566768 -411.978602)
		(end 213.932008 -411.978602)
		(width 0.1524)
		(layer "In4.Cu")
		(net "HSC_FLT_TYPE")
	)
	(segment
		(start 203.650088 -411.306518)
		(end 203.059284 -411.897322)
		(width 0.1524)
		(layer "In4.Cu")
		(net "HSC_FLT_TYPE")
	)
	(segment
		(start 214.506048 -408.359102)
		(end 216.009728 -406.855422)
		(width 0.1524)
		(layer "In4.Cu")
		(net "HSC_FLT_TYPE")
	)
	(segment
		(start 217.564208 -411.335982)
		(end 218.275408 -412.047182)
		(width 0.1524)
		(layer "In4.Cu")
		(net "HSC_FLT_TYPE")
	)
	(segment
		(start 233.555794 -411.0736)
		(end 236.177328 -408.452066)
		(width 0.1524)
		(layer "In4.Cu")
		(net "HSC_FLT_TYPE")
	)
	(segment
		(start 228.569774 -411.0736)
		(end 233.555794 -411.0736)
		(width 0.1524)
		(layer "In4.Cu")
		(net "HSC_FLT_TYPE")
	)
	(segment
		(start 195.405756 -411.897322)
		(end 194.44462 -410.936186)
		(width 0.1524)
		(layer "In4.Cu")
		(net "HSC_FLT_TYPE")
	)
	(segment
		(start 218.275408 -412.047182)
		(end 224.554288 -412.047182)
		(width 0.1524)
		(layer "In4.Cu")
		(net "HSC_FLT_TYPE")
	)
	(segment
		(start 213.932008 -411.978602)
		(end 214.506048 -411.404562)
		(width 0.1524)
		(layer "In4.Cu")
		(net "HSC_FLT_TYPE")
	)
	(segment
		(start 226.647248 -406.855422)
		(end 227.749608 -406.855422)
		(width 0.1524)
		(layer "In4.Cu")
		(net "HSC_FLT_TYPE")
	)
	(segment
		(start 194.44462 -410.936186)
		(end 194.44462 -405.024082)
		(width 0.1524)
		(layer "In4.Cu")
		(net "HSC_FLT_TYPE")
	)
	(segment
		(start 224.554288 -412.047182)
		(end 225.044508 -411.556962)
		(width 0.1524)
		(layer "In4.Cu")
		(net "HSC_FLT_TYPE")
	)
	(segment
		(start 190.608712 -403.144482)
		(end 191.652398 -403.144482)
		(width 0.1524)
		(layer "F.Cu")
		(net "HSC_FAULT")
	)
	(segment
		(start 213.077552 -402.972778)
		(end 213.652608 -402.972778)
		(width 0.1524)
		(layer "F.Cu")
		(net "HSC_FAULT")
	)
	(segment
		(start 190.411608 -402.947378)
		(end 190.608712 -403.144482)
		(width 0.1524)
		(layer "F.Cu")
		(net "HSC_FAULT")
	)
	(segment
		(start 223.745552 -402.972778)
		(end 224.320608 -402.972778)
		(width 0.1524)
		(layer "F.Cu")
		(net "HSC_FAULT")
	)
	(segment
		(start 202.409552 -402.972778)
		(end 202.984608 -402.972778)
		(width 0.1524)
		(layer "F.Cu")
		(net "HSC_FAULT")
	)
	(segment
		(start 189.151514 -402.947378)
		(end 190.411608 -402.947378)
		(width 0.1524)
		(layer "F.Cu")
		(net "HSC_FAULT")
	)
	(segment
		(start 234.413552 -402.972778)
		(end 234.988608 -402.972778)
		(width 0.1524)
		(layer "F.Cu")
		(net "HSC_FAULT")
	)
	(via
		(at 234.988608 -402.972778)
		(size 0.508)
		(drill 0.254)
		(layers "F.Cu" "B.Cu")
		(net "HSC_FAULT")
	)
	(via
		(at 190.411608 -402.947378)
		(size 0.508)
		(drill 0.254)
		(layers "F.Cu" "B.Cu")
		(net "HSC_FAULT")
	)
	(via
		(at 213.652608 -402.972778)
		(size 0.508)
		(drill 0.254)
		(layers "F.Cu" "B.Cu")
		(net "HSC_FAULT")
	)
	(via
		(at 202.984608 -402.972778)
		(size 0.508)
		(drill 0.254)
		(layers "F.Cu" "B.Cu")
		(net "HSC_FAULT")
	)
	(via
		(at 224.320608 -402.972778)
		(size 0.508)
		(drill 0.254)
		(layers "F.Cu" "B.Cu")
		(net "HSC_FAULT")
	)
	(segment
		(start 224.320608 -404.010622)
		(end 223.467168 -404.864062)
		(width 0.1524)
		(layer "In4.Cu")
		(net "HSC_FAULT")
	)
	(segment
		(start 193.903346 -402.65096)
		(end 196.126608 -404.874222)
		(width 0.1524)
		(layer "In4.Cu")
		(net "HSC_FAULT")
	)
	(segment
		(start 212.809328 -404.874222)
		(end 208.064608 -404.874222)
		(width 0.1524)
		(layer "In4.Cu")
		(net "HSC_FAULT")
	)
	(segment
		(start 204.584808 -403.324822)
		(end 203.336652 -403.324822)
		(width 0.1524)
		(layer "In4.Cu")
		(net "HSC_FAULT")
	)
	(segment
		(start 223.467168 -404.864062)
		(end 218.793568 -404.864062)
		(width 0.1524)
		(layer "In4.Cu")
		(net "HSC_FAULT")
	)
	(segment
		(start 216.446608 -405.001222)
		(end 216.446608 -404.264622)
		(width 0.1524)
		(layer "In4.Cu")
		(net "HSC_FAULT")
	)
	(segment
		(start 203.336652 -403.324822)
		(end 202.984608 -402.972778)
		(width 0.1524)
		(layer "In4.Cu")
		(net "HSC_FAULT")
	)
	(segment
		(start 234.988608 -402.972778)
		(end 234.988608 -403.452076)
		(width 0.1524)
		(layer "In4.Cu")
		(net "HSC_FAULT")
	)
	(segment
		(start 234.988608 -403.452076)
		(end 233.769662 -404.671022)
		(width 0.1524)
		(layer "In4.Cu")
		(net "HSC_FAULT")
	)
	(segment
		(start 227.317808 -405.306022)
		(end 226.657408 -404.645622)
		(width 0.1524)
		(layer "In4.Cu")
		(net "HSC_FAULT")
	)
	(segment
		(start 213.652608 -402.972778)
		(end 213.652608 -404.030942)
		(width 0.1524)
		(layer "In4.Cu")
		(net "HSC_FAULT")
	)
	(segment
		(start 218.793568 -404.864062)
		(end 218.300808 -405.356822)
		(width 0.1524)
		(layer "In4.Cu")
		(net "HSC_FAULT")
	)
	(segment
		(start 216.802208 -405.356822)
		(end 216.446608 -405.001222)
		(width 0.1524)
		(layer "In4.Cu")
		(net "HSC_FAULT")
	)
	(segment
		(start 224.320608 -402.972778)
		(end 224.320608 -404.010622)
		(width 0.1524)
		(layer "In4.Cu")
		(net "HSC_FAULT")
	)
	(segment
		(start 190.411608 -402.947378)
		(end 190.708026 -402.65096)
		(width 0.1524)
		(layer "In4.Cu")
		(net "HSC_FAULT")
	)
	(segment
		(start 215.506808 -403.324822)
		(end 214.004652 -403.324822)
		(width 0.1524)
		(layer "In4.Cu")
		(net "HSC_FAULT")
	)
	(segment
		(start 229.553008 -404.671022)
		(end 228.918008 -405.306022)
		(width 0.1524)
		(layer "In4.Cu")
		(net "HSC_FAULT")
	)
	(segment
		(start 202.984608 -403.980142)
		(end 202.984608 -402.972778)
		(width 0.1524)
		(layer "In4.Cu")
		(net "HSC_FAULT")
	)
	(segment
		(start 202.090528 -404.874222)
		(end 202.984608 -403.980142)
		(width 0.1524)
		(layer "In4.Cu")
		(net "HSC_FAULT")
	)
	(segment
		(start 214.004652 -403.324822)
		(end 213.652608 -402.972778)
		(width 0.1524)
		(layer "In4.Cu")
		(net "HSC_FAULT")
	)
	(segment
		(start 206.185008 -405.306022)
		(end 205.702408 -404.823422)
		(width 0.1524)
		(layer "In4.Cu")
		(net "HSC_FAULT")
	)
	(segment
		(start 218.300808 -405.356822)
		(end 216.802208 -405.356822)
		(width 0.1524)
		(layer "In4.Cu")
		(net "HSC_FAULT")
	)
	(segment
		(start 213.652608 -404.030942)
		(end 212.809328 -404.874222)
		(width 0.1524)
		(layer "In4.Cu")
		(net "HSC_FAULT")
	)
	(segment
		(start 233.769662 -404.671022)
		(end 229.553008 -404.671022)
		(width 0.1524)
		(layer "In4.Cu")
		(net "HSC_FAULT")
	)
	(segment
		(start 205.702408 -404.823422)
		(end 205.702408 -404.442422)
		(width 0.1524)
		(layer "In4.Cu")
		(net "HSC_FAULT")
	)
	(segment
		(start 216.446608 -404.264622)
		(end 215.506808 -403.324822)
		(width 0.1524)
		(layer "In4.Cu")
		(net "HSC_FAULT")
	)
	(segment
		(start 224.672652 -403.324822)
		(end 224.320608 -402.972778)
		(width 0.1524)
		(layer "In4.Cu")
		(net "HSC_FAULT")
	)
	(segment
		(start 226.174808 -403.324822)
		(end 224.672652 -403.324822)
		(width 0.1524)
		(layer "In4.Cu")
		(net "HSC_FAULT")
	)
	(segment
		(start 228.918008 -405.306022)
		(end 227.317808 -405.306022)
		(width 0.1524)
		(layer "In4.Cu")
		(net "HSC_FAULT")
	)
	(segment
		(start 226.657408 -404.645622)
		(end 226.657408 -403.807422)
		(width 0.1524)
		(layer "In4.Cu")
		(net "HSC_FAULT")
	)
	(segment
		(start 207.632808 -405.306022)
		(end 206.185008 -405.306022)
		(width 0.1524)
		(layer "In4.Cu")
		(net "HSC_FAULT")
	)
	(segment
		(start 196.126608 -404.874222)
		(end 202.090528 -404.874222)
		(width 0.1524)
		(layer "In4.Cu")
		(net "HSC_FAULT")
	)
	(segment
		(start 208.064608 -404.874222)
		(end 207.632808 -405.306022)
		(width 0.1524)
		(layer "In4.Cu")
		(net "HSC_FAULT")
	)
	(segment
		(start 205.702408 -404.442422)
		(end 204.584808 -403.324822)
		(width 0.1524)
		(layer "In4.Cu")
		(net "HSC_FAULT")
	)
	(segment
		(start 190.708026 -402.65096)
		(end 193.903346 -402.65096)
		(width 0.1524)
		(layer "In4.Cu")
		(net "HSC_FAULT")
	)
	(segment
		(start 226.657408 -403.807422)
		(end 226.174808 -403.324822)
		(width 0.1524)
		(layer "In4.Cu")
		(net "HSC_FAULT")
	)
	(segment
		(start 185.160158 -399.911062)
		(end 185.014108 -400.057112)
		(width 0.1524)
		(layer "F.Cu")
		(net "HSC_EN_R")
	)
	(segment
		(start 185.014108 -400.057112)
		(end 185.014108 -400.484848)
		(width 0.1524)
		(layer "F.Cu")
		(net "HSC_EN_R")
	)
	(segment
		(start 185.160158 -399.696686)
		(end 184.575958 -399.112486)
		(width 0.1524)
		(layer "F.Cu")
		(net "HSC_EN_R")
	)
	(segment
		(start 184.575958 -399.112486)
		(end 184.575958 -398.651222)
		(width 0.1524)
		(layer "F.Cu")
		(net "HSC_EN_R")
	)
	(segment
		(start 185.160158 -399.911062)
		(end 185.160158 -399.696686)
		(width 0.1524)
		(layer "F.Cu")
		(net "HSC_EN_R")
	)
	(via
		(at 185.160158 -399.911062)
		(size 0.508)
		(drill 0.254)
		(layers "F.Cu" "B.Cu")
		(net "HSC_EN_R")
	)
	(segment
		(start 185.376058 -398.651222)
		(end 185.376058 -397.996918)
		(width 0.1524)
		(layer "F.Cu")
		(net "HSC_EN")
	)
	(segment
		(start 187.842652 -421.314372)
		(end 187.842652 -424.47972)
		(width 0.12954)
		(layer "F.Cu")
		(net "HSC_EN")
	)
	(segment
		(start 184.657492 -397.278352)
		(end 183.77408 -397.278352)
		(width 0.1524)
		(layer "F.Cu")
		(net "HSC_EN")
	)
	(segment
		(start 193.898266 -425.414186)
		(end 193.898266 -426.355002)
		(width 0.12954)
		(layer "F.Cu")
		(net "HSC_EN")
	)
	(segment
		(start 188.137292 -424.26128)
		(end 187.918852 -424.47972)
		(width 0.12954)
		(layer "F.Cu")
		(net "HSC_EN")
	)
	(segment
		(start 188.839348 -424.26128)
		(end 192.74536 -424.26128)
		(width 0.12954)
		(layer "F.Cu")
		(net "HSC_EN")
	)
	(segment
		(start 192.74536 -424.26128)
		(end 193.898266 -425.414186)
		(width 0.12954)
		(layer "F.Cu")
		(net "HSC_EN")
	)
	(segment
		(start 188.839348 -424.26128)
		(end 188.137292 -424.26128)
		(width 0.12954)
		(layer "F.Cu")
		(net "HSC_EN")
	)
	(segment
		(start 187.21832 -420.57828)
		(end 187.21832 -420.69004)
		(width 0.12954)
		(layer "F.Cu")
		(net "HSC_EN")
	)
	(segment
		(start 183.77408 -397.278352)
		(end 183.77408 -396.647416)
		(width 0.1524)
		(layer "F.Cu")
		(net "HSC_EN")
	)
	(segment
		(start 187.918852 -424.47972)
		(end 187.842652 -424.47972)
		(width 0.12954)
		(layer "F.Cu")
		(net "HSC_EN")
	)
	(segment
		(start 295.480232 -388.349998)
		(end 295.480232 -387.143498)
		(width 0.10668)
		(layer "F.Cu")
		(net "HSC_EN")
	)
	(segment
		(start 187.21832 -420.69004)
		(end 187.842652 -421.314372)
		(width 0.12954)
		(layer "F.Cu")
		(net "HSC_EN")
	)
	(segment
		(start 185.376058 -397.996918)
		(end 184.657492 -397.278352)
		(width 0.1524)
		(layer "F.Cu")
		(net "HSC_EN")
	)
	(via
		(at 183.77408 -396.647416)
		(size 0.508)
		(drill 0.254)
		(layers "F.Cu" "B.Cu")
		(net "HSC_EN")
	)
	(via
		(at 187.21832 -420.57828)
		(size 0.508)
		(drill 0.254)
		(layers "F.Cu" "B.Cu")
		(net "HSC_EN")
	)
	(via
		(at 295.480232 -387.143498)
		(size 0.508)
		(drill 0.254)
		(layers "F.Cu" "B.Cu")
		(net "HSC_EN")
	)
	(segment
		(start 187.21832 -420.57828)
		(end 185.69432 -419.05428)
		(width 0.1524)
		(layer "In11.Cu")
		(net "HSC_EN")
	)
	(segment
		(start 283.16301 -388.37489)
		(end 286.9311 -392.14298)
		(width 0.1524)
		(layer "In11.Cu")
		(net "HSC_EN")
	)
	(segment
		(start 229.54234 -390.0932)
		(end 231.26065 -388.37489)
		(width 0.1524)
		(layer "In11.Cu")
		(net "HSC_EN")
	)
	(segment
		(start 183.14924 -419.05428)
		(end 182.60949 -419.59403)
		(width 0.1524)
		(layer "In11.Cu")
		(net "HSC_EN")
	)
	(segment
		(start 186.726576 -392.099292)
		(end 189.213998 -391.6045)
		(width 0.1524)
		(layer "In11.Cu")
		(net "HSC_EN")
	)
	(segment
		(start 295.480232 -387.823202)
		(end 295.480232 -387.143498)
		(width 0.1524)
		(layer "In11.Cu")
		(net "HSC_EN")
	)
	(segment
		(start 181.46903 -394.27785)
		(end 186.726576 -392.099292)
		(width 0.1524)
		(layer "In11.Cu")
		(net "HSC_EN")
	)
	(segment
		(start 191.352932 -391.6045)
		(end 206.698088 -390.0932)
		(width 0.1524)
		(layer "In11.Cu")
		(net "HSC_EN")
	)
	(segment
		(start 177.28692 -398.45996)
		(end 181.46903 -394.27785)
		(width 0.1524)
		(layer "In11.Cu")
		(net "HSC_EN")
	)
	(segment
		(start 233.957368 -388.49554)
		(end 238.802672 -388.49554)
		(width 0.1524)
		(layer "In11.Cu")
		(net "HSC_EN")
	)
	(segment
		(start 238.923322 -388.37489)
		(end 283.16301 -388.37489)
		(width 0.1524)
		(layer "In11.Cu")
		(net "HSC_EN")
	)
	(segment
		(start 286.9311 -392.14298)
		(end 291.160454 -392.14298)
		(width 0.1524)
		(layer "In11.Cu")
		(net "HSC_EN")
	)
	(segment
		(start 177.89144 -414.52292)
		(end 177.28692 -413.9184)
		(width 0.1524)
		(layer "In11.Cu")
		(net "HSC_EN")
	)
	(segment
		(start 206.698088 -390.0932)
		(end 229.54234 -390.0932)
		(width 0.1524)
		(layer "In11.Cu")
		(net "HSC_EN")
	)
	(segment
		(start 189.213998 -391.6045)
		(end 191.352932 -391.6045)
		(width 0.1524)
		(layer "In11.Cu")
		(net "HSC_EN")
	)
	(segment
		(start 233.836718 -388.37489)
		(end 233.957368 -388.49554)
		(width 0.1524)
		(layer "In11.Cu")
		(net "HSC_EN")
	)
	(segment
		(start 231.26065 -388.37489)
		(end 233.836718 -388.37489)
		(width 0.1524)
		(layer "In11.Cu")
		(net "HSC_EN")
	)
	(segment
		(start 179.35575 -419.59403)
		(end 177.89144 -418.12972)
		(width 0.1524)
		(layer "In11.Cu")
		(net "HSC_EN")
	)
	(segment
		(start 185.69432 -419.05428)
		(end 183.14924 -419.05428)
		(width 0.1524)
		(layer "In11.Cu")
		(net "HSC_EN")
	)
	(segment
		(start 177.89144 -418.12972)
		(end 177.89144 -414.52292)
		(width 0.1524)
		(layer "In11.Cu")
		(net "HSC_EN")
	)
	(segment
		(start 182.60949 -419.59403)
		(end 179.35575 -419.59403)
		(width 0.1524)
		(layer "In11.Cu")
		(net "HSC_EN")
	)
	(segment
		(start 291.160454 -392.14298)
		(end 295.480232 -387.823202)
		(width 0.1524)
		(layer "In11.Cu")
		(net "HSC_EN")
	)
	(segment
		(start 177.28692 -413.9184)
		(end 177.28692 -398.45996)
		(width 0.1524)
		(layer "In11.Cu")
		(net "HSC_EN")
	)
	(segment
		(start 238.802672 -388.49554)
		(end 238.923322 -388.37489)
		(width 0.1524)
		(layer "In11.Cu")
		(net "HSC_EN")
	)
	(segment
		(start 182.17642 -414.92678)
		(end 179.96662 -414.92678)
		(width 0.1524)
		(layer "In13.Cu")
		(net "HSC_EN")
	)
	(segment
		(start 185.87974 -419.2397)
		(end 185.87974 -418.6301)
		(width 0.1524)
		(layer "In13.Cu")
		(net "HSC_EN")
	)
	(segment
		(start 176.79162 -411.75178)
		(end 176.79162 -399.28292)
		(width 0.1524)
		(layer "In13.Cu")
		(net "HSC_EN")
	)
	(segment
		(start 176.79162 -399.28292)
		(end 179.427124 -396.647416)
		(width 0.1524)
		(layer "In13.Cu")
		(net "HSC_EN")
	)
	(segment
		(start 179.427124 -396.647416)
		(end 183.77408 -396.647416)
		(width 0.1524)
		(layer "In13.Cu")
		(net "HSC_EN")
	)
	(segment
		(start 187.21832 -420.57828)
		(end 185.87974 -419.2397)
		(width 0.1524)
		(layer "In13.Cu")
		(net "HSC_EN")
	)
	(segment
		(start 179.96662 -414.92678)
		(end 176.79162 -411.75178)
		(width 0.1524)
		(layer "In13.Cu")
		(net "HSC_EN")
	)
	(segment
		(start 185.87974 -418.6301)
		(end 182.17642 -414.92678)
		(width 0.1524)
		(layer "In13.Cu")
		(net "HSC_EN")
	)
	(segment
		(start 191.652398 -401.112482)
		(end 191.611758 -401.071842)
		(width 0.1524)
		(layer "F.Cu")
		(net "HSC_D_OC_R")
	)
	(segment
		(start 189.575694 -402.047456)
		(end 189.151514 -402.047456)
		(width 0.1524)
		(layer "F.Cu")
		(net "HSC_D_OC_R")
	)
	(segment
		(start 205.797658 -400.759422)
		(end 206.413608 -400.759422)
		(width 0.1524)
		(layer "F.Cu")
		(net "HSC_D_OC_R")
	)
	(segment
		(start 216.465658 -400.759422)
		(end 217.081608 -400.759422)
		(width 0.1524)
		(layer "F.Cu")
		(net "HSC_D_OC_R")
	)
	(segment
		(start 190.401194 -401.222718)
		(end 189.575694 -402.047456)
		(width 0.1524)
		(layer "F.Cu")
		(net "HSC_D_OC_R")
	)
	(segment
		(start 227.133658 -400.759422)
		(end 227.749608 -400.759422)
		(width 0.1524)
		(layer "F.Cu")
		(net "HSC_D_OC_R")
	)
	(segment
		(start 237.801658 -401.673822)
		(end 238.417608 -401.673822)
		(width 0.1524)
		(layer "F.Cu")
		(net "HSC_D_OC_R")
	)
	(segment
		(start 191.611758 -401.071842)
		(end 190.401448 -401.071842)
		(width 0.1524)
		(layer "F.Cu")
		(net "HSC_D_OC_R")
	)
	(segment
		(start 190.401448 -401.071842)
		(end 190.401194 -401.222718)
		(width 0.1524)
		(layer "F.Cu")
		(net "HSC_D_OC_R")
	)
	(via
		(at 217.081608 -400.759422)
		(size 0.508)
		(drill 0.254)
		(layers "F.Cu" "B.Cu")
		(net "HSC_D_OC_R")
	)
	(via
		(at 238.417608 -401.673822)
		(size 0.508)
		(drill 0.254)
		(layers "F.Cu" "B.Cu")
		(net "HSC_D_OC_R")
	)
	(via
		(at 190.401448 -401.071842)
		(size 0.508)
		(drill 0.254)
		(layers "F.Cu" "B.Cu")
		(net "HSC_D_OC_R")
	)
	(via
		(at 227.749608 -400.759422)
		(size 0.508)
		(drill 0.254)
		(layers "F.Cu" "B.Cu")
		(net "HSC_D_OC_R")
	)
	(via
		(at 206.413608 -400.759422)
		(size 0.508)
		(drill 0.254)
		(layers "F.Cu" "B.Cu")
		(net "HSC_D_OC_R")
	)
	(segment
		(start 216.712546 -400.39036)
		(end 208.34096 -400.39036)
		(width 0.1524)
		(layer "In4.Cu")
		(net "HSC_D_OC_R")
	)
	(segment
		(start 218.91752 -400.759422)
		(end 219.301822 -400.37512)
		(width 0.1524)
		(layer "In4.Cu")
		(net "HSC_D_OC_R")
	)
	(segment
		(start 218.29268 -402.52396)
		(end 218.91752 -401.89912)
		(width 0.1524)
		(layer "In4.Cu")
		(net "HSC_D_OC_R")
	)
	(segment
		(start 206.413608 -402.250148)
		(end 206.413608 -400.759422)
		(width 0.1524)
		(layer "In4.Cu")
		(net "HSC_D_OC_R")
	)
	(segment
		(start 217.081608 -400.759422)
		(end 217.081608 -402.300948)
		(width 0.1524)
		(layer "In4.Cu")
		(net "HSC_D_OC_R")
	)
	(segment
		(start 196.84746 -402.05406)
		(end 196.247258 -402.05406)
		(width 0.1524)
		(layer "In4.Cu")
		(net "HSC_D_OC_R")
	)
	(segment
		(start 208.34096 -400.39036)
		(end 208.17078 -400.56054)
		(width 0.1524)
		(layer "In4.Cu")
		(net "HSC_D_OC_R")
	)
	(segment
		(start 197.34276 -401.09648)
		(end 197.34276 -401.55876)
		(width 0.1524)
		(layer "In4.Cu")
		(net "HSC_D_OC_R")
	)
	(segment
		(start 229.690422 -400.3675)
		(end 237.111286 -400.3675)
		(width 0.1524)
		(layer "In4.Cu")
		(net "HSC_D_OC_R")
	)
	(segment
		(start 229.09276 -402.39442)
		(end 229.09276 -400.965162)
		(width 0.1524)
		(layer "In4.Cu")
		(net "HSC_D_OC_R")
	)
	(segment
		(start 196.247258 -402.05406)
		(end 194.41922 -400.226022)
		(width 0.1524)
		(layer "In4.Cu")
		(net "HSC_D_OC_R")
	)
	(segment
		(start 191.247268 -400.226022)
		(end 190.401448 -401.071842)
		(width 0.1524)
		(layer "In4.Cu")
		(net "HSC_D_OC_R")
	)
	(segment
		(start 208.17078 -402.1582)
		(end 207.70342 -402.62556)
		(width 0.1524)
		(layer "In4.Cu")
		(net "HSC_D_OC_R")
	)
	(segment
		(start 219.301822 -400.37512)
		(end 227.113338 -400.37512)
		(width 0.1524)
		(layer "In4.Cu")
		(net "HSC_D_OC_R")
	)
	(segment
		(start 207.70342 -402.62556)
		(end 206.78902 -402.62556)
		(width 0.1524)
		(layer "In4.Cu")
		(net "HSC_D_OC_R")
	)
	(segment
		(start 227.94214 -402.48078)
		(end 229.0064 -402.48078)
		(width 0.1524)
		(layer "In4.Cu")
		(net "HSC_D_OC_R")
	)
	(segment
		(start 229.09276 -400.965162)
		(end 229.690422 -400.3675)
		(width 0.1524)
		(layer "In4.Cu")
		(net "HSC_D_OC_R")
	)
	(segment
		(start 227.749608 -400.759422)
		(end 227.749608 -402.288248)
		(width 0.1524)
		(layer "In4.Cu")
		(net "HSC_D_OC_R")
	)
	(segment
		(start 237.111286 -400.3675)
		(end 238.417608 -401.673822)
		(width 0.1524)
		(layer "In4.Cu")
		(net "HSC_D_OC_R")
	)
	(segment
		(start 194.41922 -400.226022)
		(end 191.247268 -400.226022)
		(width 0.1524)
		(layer "In4.Cu")
		(net "HSC_D_OC_R")
	)
	(segment
		(start 206.78902 -402.62556)
		(end 206.413608 -402.250148)
		(width 0.1524)
		(layer "In4.Cu")
		(net "HSC_D_OC_R")
	)
	(segment
		(start 217.30462 -402.52396)
		(end 218.29268 -402.52396)
		(width 0.1524)
		(layer "In4.Cu")
		(net "HSC_D_OC_R")
	)
	(segment
		(start 206.039466 -400.38528)
		(end 198.05396 -400.38528)
		(width 0.1524)
		(layer "In4.Cu")
		(net "HSC_D_OC_R")
	)
	(segment
		(start 229.0064 -402.48078)
		(end 229.09276 -402.39442)
		(width 0.1524)
		(layer "In4.Cu")
		(net "HSC_D_OC_R")
	)
	(segment
		(start 208.17078 -400.56054)
		(end 208.17078 -402.1582)
		(width 0.1524)
		(layer "In4.Cu")
		(net "HSC_D_OC_R")
	)
	(segment
		(start 217.081608 -402.300948)
		(end 217.30462 -402.52396)
		(width 0.1524)
		(layer "In4.Cu")
		(net "HSC_D_OC_R")
	)
	(segment
		(start 217.081608 -400.759422)
		(end 216.712546 -400.39036)
		(width 0.1524)
		(layer "In4.Cu")
		(net "HSC_D_OC_R")
	)
	(segment
		(start 197.34276 -401.55876)
		(end 196.84746 -402.05406)
		(width 0.1524)
		(layer "In4.Cu")
		(net "HSC_D_OC_R")
	)
	(segment
		(start 206.413608 -400.759422)
		(end 206.039466 -400.38528)
		(width 0.1524)
		(layer "In4.Cu")
		(net "HSC_D_OC_R")
	)
	(segment
		(start 218.91752 -401.89912)
		(end 218.91752 -400.759422)
		(width 0.1524)
		(layer "In4.Cu")
		(net "HSC_D_OC_R")
	)
	(segment
		(start 227.113338 -400.37512)
		(end 227.49764 -400.759422)
		(width 0.1524)
		(layer "In4.Cu")
		(net "HSC_D_OC_R")
	)
	(segment
		(start 227.49764 -400.759422)
		(end 227.749608 -400.759422)
		(width 0.1524)
		(layer "In4.Cu")
		(net "HSC_D_OC_R")
	)
	(segment
		(start 227.749608 -402.288248)
		(end 227.94214 -402.48078)
		(width 0.1524)
		(layer "In4.Cu")
		(net "HSC_D_OC_R")
	)
	(segment
		(start 198.05396 -400.38528)
		(end 197.34276 -401.09648)
		(width 0.1524)
		(layer "In4.Cu")
		(net "HSC_D_OC_R")
	)
	(segment
		(start 214.287608 -400.911822)
		(end 214.287608 -401.165822)
		(width 0.1524)
		(layer "F.Cu")
		(net "HSC_D_OC_2")
	)
	(segment
		(start 214.440008 -400.759422)
		(end 214.287608 -400.911822)
		(width 0.1524)
		(layer "F.Cu")
		(net "HSC_D_OC_2")
	)
	(segment
		(start 214.287608 -401.165822)
		(end 213.48065 -401.97278)
		(width 0.1524)
		(layer "F.Cu")
		(net "HSC_D_OC_2")
	)
	(segment
		(start 213.48065 -401.97278)
		(end 213.077552 -401.97278)
		(width 0.1524)
		(layer "F.Cu")
		(net "HSC_D_OC_2")
	)
	(segment
		(start 215.665558 -400.759422)
		(end 214.440008 -400.759422)
		(width 0.1524)
		(layer "F.Cu")
		(net "HSC_D_OC_2")
	)
	(via
		(at 214.287608 -400.911822)
		(size 0.762)
		(drill 0.381)
		(layers "F.Cu" "B.Cu")
		(net "HSC_D_OC_2")
	)
	(segment
		(start 203.619608 -400.911822)
		(end 203.619608 -401.165822)
		(width 0.1524)
		(layer "F.Cu")
		(net "HSC_D_OC_1")
	)
	(segment
		(start 203.619608 -401.165822)
		(end 202.81265 -401.97278)
		(width 0.1524)
		(layer "F.Cu")
		(net "HSC_D_OC_1")
	)
	(segment
		(start 204.997558 -400.759422)
		(end 203.772008 -400.759422)
		(width 0.1524)
		(layer "F.Cu")
		(net "HSC_D_OC_1")
	)
	(segment
		(start 202.81265 -401.97278)
		(end 202.409552 -401.97278)
		(width 0.1524)
		(layer "F.Cu")
		(net "HSC_D_OC_1")
	)
	(segment
		(start 203.772008 -400.759422)
		(end 203.619608 -400.911822)
		(width 0.1524)
		(layer "F.Cu")
		(net "HSC_D_OC_1")
	)
	(via
		(at 203.619608 -400.911822)
		(size 0.762)
		(drill 0.381)
		(layers "F.Cu" "B.Cu")
		(net "HSC_D_OC_1")
	)
	(segment
		(start 282.73756 -425.54652)
		(end 282.73756 -424.958764)
		(width 0.1524)
		(layer "F.Cu")
		(net "HSC_D_OC")
	)
	(segment
		(start 280.6319 -427.65218)
		(end 277.56104 -427.65218)
		(width 0.1524)
		(layer "F.Cu")
		(net "HSC_D_OC")
	)
	(segment
		(start 276.40661 -424.18381)
		(end 276.40661 -424.424602)
		(width 0.1524)
		(layer "F.Cu")
		(net "HSC_D_OC")
	)
	(segment
		(start 281.51328 -426.7708)
		(end 282.73756 -425.54652)
		(width 0.1524)
		(layer "F.Cu")
		(net "HSC_D_OC")
	)
	(segment
		(start 277.524718 -421.233854)
		(end 277.524718 -421.96131)
		(width 0.1524)
		(layer "F.Cu")
		(net "HSC_D_OC")
	)
	(segment
		(start 277.397464 -421.1066)
		(end 277.524718 -421.233854)
		(width 0.1524)
		(layer "F.Cu")
		(net "HSC_D_OC")
	)
	(segment
		(start 277.56104 -427.65218)
		(end 276.40661 -426.49775)
		(width 0.1524)
		(layer "F.Cu")
		(net "HSC_D_OC")
	)
	(segment
		(start 276.988778 -421.1066)
		(end 277.397464 -421.1066)
		(width 0.1524)
		(layer "F.Cu")
		(net "HSC_D_OC")
	)
	(segment
		(start 277.524718 -423.065702)
		(end 276.40661 -424.18381)
		(width 0.1524)
		(layer "F.Cu")
		(net "HSC_D_OC")
	)
	(segment
		(start 192.452498 -401.112482)
		(end 193.068448 -401.112482)
		(width 0.1524)
		(layer "F.Cu")
		(net "HSC_D_OC")
	)
	(segment
		(start 274.201128 -422.6433)
		(end 275.452078 -422.6433)
		(width 0.1524)
		(layer "F.Cu")
		(net "HSC_D_OC")
	)
	(segment
		(start 275.452078 -422.6433)
		(end 276.988778 -421.1066)
		(width 0.1524)
		(layer "F.Cu")
		(net "HSC_D_OC")
	)
	(segment
		(start 277.524718 -421.96131)
		(end 277.524718 -423.065702)
		(width 0.1524)
		(layer "F.Cu")
		(net "HSC_D_OC")
	)
	(segment
		(start 281.51328 -426.7708)
		(end 280.6319 -427.65218)
		(width 0.1524)
		(layer "F.Cu")
		(net "HSC_D_OC")
	)
	(segment
		(start 276.40661 -426.49775)
		(end 276.40661 -424.424602)
		(width 0.1524)
		(layer "F.Cu")
		(net "HSC_D_OC")
	)
	(via
		(at 244.78488 -111.724948)
		(size 0.508)
		(drill 0.254)
		(layers "F.Cu" "B.Cu")
		(net "HSC_D_OC")
	)
	(via
		(at 252.621796 -329.518772)
		(size 0.508)
		(drill 0.254)
		(layers "F.Cu" "B.Cu")
		(net "HSC_D_OC")
	)
	(via
		(at 199.57288 -108.676948)
		(size 0.508)
		(drill 0.254)
		(layers "F.Cu" "B.Cu")
		(net "HSC_D_OC")
	)
	(via
		(at 281.51328 -426.7708)
		(size 0.508)
		(drill 0.254)
		(layers "F.Cu" "B.Cu")
		(net "HSC_D_OC")
	)
	(via
		(at 193.068448 -401.112482)
		(size 0.508)
		(drill 0.254)
		(layers "F.Cu" "B.Cu")
		(net "HSC_D_OC")
	)
	(via
		(at 275.452078 -422.6433)
		(size 0.762)
		(drill 0.381)
		(layers "F.Cu" "B.Cu")
		(net "HSC_D_OC")
	)
	(segment
		(start 199.57288 -108.676948)
		(end 199.02932 -108.133388)
		(width 0.12954)
		(layer "B.Cu")
		(net "HSC_D_OC")
	)
	(segment
		(start 192.565528 -400.609562)
		(end 193.068448 -401.112482)
		(width 0.1524)
		(layer "B.Cu")
		(net "HSC_D_OC")
	)
	(segment
		(start 199.02932 -108.133388)
		(end 197.99808 -108.133388)
		(width 0.12954)
		(layer "B.Cu")
		(net "HSC_D_OC")
	)
	(segment
		(start 192.452498 -400.609562)
		(end 192.565528 -400.609562)
		(width 0.1524)
		(layer "B.Cu")
		(net "HSC_D_OC")
	)
	(segment
		(start 197.99808 -108.133388)
		(end 197.81393 -107.949238)
		(width 0.12954)
		(layer "B.Cu")
		(net "HSC_D_OC")
	)
	(segment
		(start 197.81393 -107.949238)
		(end 197.81393 -107.495848)
		(width 0.12954)
		(layer "B.Cu")
		(net "HSC_D_OC")
	)
	(segment
		(start 182.09006 -401.828)
		(end 180.44414 -401.828)
		(width 0.1524)
		(layer "In4.Cu")
		(net "HSC_D_OC")
	)
	(segment
		(start 195.16852 -438.855358)
		(end 277.546816 -438.855358)
		(width 0.1524)
		(layer "In4.Cu")
		(net "HSC_D_OC")
	)
	(segment
		(start 177.78222 -397.88084)
		(end 176.33188 -399.33118)
		(width 0.1524)
		(layer "In4.Cu")
		(net "HSC_D_OC")
	)
	(segment
		(start 189.7126 -418.308536)
		(end 189.7126 -433.399438)
		(width 0.1524)
		(layer "In4.Cu")
		(net "HSC_D_OC")
	)
	(segment
		(start 189.91834 -401.55622)
		(end 188.97346 -400.61134)
		(width 0.1524)
		(layer "In4.Cu")
		(net "HSC_D_OC")
	)
	(segment
		(start 178.99126 -397.88084)
		(end 177.78222 -397.88084)
		(width 0.1524)
		(layer "In4.Cu")
		(net "HSC_D_OC")
	)
	(segment
		(start 280.209752 -439.702702)
		(end 284.134052 -435.778402)
		(width 0.1524)
		(layer "In4.Cu")
		(net "HSC_D_OC")
	)
	(segment
		(start 183.30672 -400.61134)
		(end 182.09006 -401.828)
		(width 0.1524)
		(layer "In4.Cu")
		(net "HSC_D_OC")
	)
	(segment
		(start 284.134052 -435.778402)
		(end 284.134052 -429.391572)
		(width 0.1524)
		(layer "In4.Cu")
		(net "HSC_D_OC")
	)
	(segment
		(start 176.33188 -410.310584)
		(end 179.365656 -413.34436)
		(width 0.1524)
		(layer "In4.Cu")
		(net "HSC_D_OC")
	)
	(segment
		(start 278.39416 -439.702702)
		(end 280.209752 -439.702702)
		(width 0.1524)
		(layer "In4.Cu")
		(net "HSC_D_OC")
	)
	(segment
		(start 185.734198 -414.330134)
		(end 189.7126 -418.308536)
		(width 0.1524)
		(layer "In4.Cu")
		(net "HSC_D_OC")
	)
	(segment
		(start 179.504848 -400.888708)
		(end 179.504848 -398.394428)
		(width 0.1524)
		(layer "In4.Cu")
		(net "HSC_D_OC")
	)
	(segment
		(start 183.077866 -414.330134)
		(end 185.734198 -414.330134)
		(width 0.1524)
		(layer "In4.Cu")
		(net "HSC_D_OC")
	)
	(segment
		(start 277.546816 -438.855358)
		(end 278.39416 -439.702702)
		(width 0.1524)
		(layer "In4.Cu")
		(net "HSC_D_OC")
	)
	(segment
		(start 284.134052 -429.391572)
		(end 281.51328 -426.7708)
		(width 0.1524)
		(layer "In4.Cu")
		(net "HSC_D_OC")
	)
	(segment
		(start 193.068448 -401.112482)
		(end 192.62471 -401.55622)
		(width 0.1524)
		(layer "In4.Cu")
		(net "HSC_D_OC")
	)
	(segment
		(start 188.97346 -400.61134)
		(end 183.30672 -400.61134)
		(width 0.1524)
		(layer "In4.Cu")
		(net "HSC_D_OC")
	)
	(segment
		(start 180.44414 -401.828)
		(end 179.504848 -400.888708)
		(width 0.1524)
		(layer "In4.Cu")
		(net "HSC_D_OC")
	)
	(segment
		(start 179.504848 -398.394428)
		(end 178.99126 -397.88084)
		(width 0.1524)
		(layer "In4.Cu")
		(net "HSC_D_OC")
	)
	(segment
		(start 179.365656 -413.34436)
		(end 182.092092 -413.34436)
		(width 0.1524)
		(layer "In4.Cu")
		(net "HSC_D_OC")
	)
	(segment
		(start 176.33188 -399.33118)
		(end 176.33188 -410.310584)
		(width 0.1524)
		(layer "In4.Cu")
		(net "HSC_D_OC")
	)
	(segment
		(start 192.62471 -401.55622)
		(end 189.91834 -401.55622)
		(width 0.1524)
		(layer "In4.Cu")
		(net "HSC_D_OC")
	)
	(segment
		(start 182.092092 -413.34436)
		(end 183.077866 -414.330134)
		(width 0.1524)
		(layer "In4.Cu")
		(net "HSC_D_OC")
	)
	(segment
		(start 189.7126 -433.399438)
		(end 195.16852 -438.855358)
		(width 0.1524)
		(layer "In4.Cu")
		(net "HSC_D_OC")
	)
	(segment
		(start 252.314202 -135.658606)
		(end 252.314202 -124.20727)
		(width 0.1524)
		(layer "In11.Cu")
		(net "HSC_D_OC")
	)
	(segment
		(start 245.99138 -117.884448)
		(end 245.99138 -112.931448)
		(width 0.1524)
		(layer "In11.Cu")
		(net "HSC_D_OC")
	)
	(segment
		(start 249.949208 -138.0236)
		(end 252.314202 -135.658606)
		(width 0.1524)
		(layer "In11.Cu")
		(net "HSC_D_OC")
	)
	(segment
		(start 251.593096 -326.228964)
		(end 251.593096 -199.336914)
		(width 0.1524)
		(layer "In11.Cu")
		(net "HSC_D_OC")
	)
	(segment
		(start 252.314202 -124.20727)
		(end 245.99138 -117.884448)
		(width 0.1524)
		(layer "In11.Cu")
		(net "HSC_D_OC")
	)
	(segment
		(start 245.99138 -112.931448)
		(end 244.78488 -111.724948)
		(width 0.1524)
		(layer "In11.Cu")
		(net "HSC_D_OC")
	)
	(segment
		(start 251.593096 -199.336914)
		(end 249.949208 -197.693026)
		(width 0.1524)
		(layer "In11.Cu")
		(net "HSC_D_OC")
	)
	(segment
		(start 252.621796 -327.257664)
		(end 251.593096 -326.228964)
		(width 0.1524)
		(layer "In11.Cu")
		(net "HSC_D_OC")
	)
	(segment
		(start 252.621796 -329.518772)
		(end 252.621796 -327.257664)
		(width 0.1524)
		(layer "In11.Cu")
		(net "HSC_D_OC")
	)
	(segment
		(start 249.949208 -197.693026)
		(end 249.949208 -138.0236)
		(width 0.1524)
		(layer "In11.Cu")
		(net "HSC_D_OC")
	)
	(segment
		(start 205.76286 -110.073948)
		(end 209.464148 -110.073948)
		(width 0.1524)
		(layer "In13.Cu")
		(net "HSC_D_OC")
	)
	(segment
		(start 234.108752 -105.463848)
		(end 242.627404 -105.463848)
		(width 0.1524)
		(layer "In13.Cu")
		(net "HSC_D_OC")
	)
	(segment
		(start 205.12786 -109.438948)
		(end 205.76286 -110.073948)
		(width 0.1524)
		(layer "In13.Cu")
		(net "HSC_D_OC")
	)
	(segment
		(start 210.185 -110.7948)
		(end 216.884758 -110.7948)
		(width 0.1524)
		(layer "In13.Cu")
		(net "HSC_D_OC")
	)
	(segment
		(start 203.227178 -110.11154)
		(end 203.89977 -109.438948)
		(width 0.1524)
		(layer "In13.Cu")
		(net "HSC_D_OC")
	)
	(segment
		(start 216.884758 -110.7948)
		(end 217.392758 -110.2868)
		(width 0.1524)
		(layer "In13.Cu")
		(net "HSC_D_OC")
	)
	(segment
		(start 200.84288 -108.676948)
		(end 202.277472 -110.11154)
		(width 0.1524)
		(layer "In13.Cu")
		(net "HSC_D_OC")
	)
	(segment
		(start 202.277472 -110.11154)
		(end 203.227178 -110.11154)
		(width 0.1524)
		(layer "In13.Cu")
		(net "HSC_D_OC")
	)
	(segment
		(start 229.2858 -110.2868)
		(end 234.108752 -105.463848)
		(width 0.1524)
		(layer "In13.Cu")
		(net "HSC_D_OC")
	)
	(segment
		(start 209.464148 -110.073948)
		(end 210.185 -110.7948)
		(width 0.1524)
		(layer "In13.Cu")
		(net "HSC_D_OC")
	)
	(segment
		(start 243.721636 -106.55808)
		(end 243.721636 -110.661704)
		(width 0.1524)
		(layer "In13.Cu")
		(net "HSC_D_OC")
	)
	(segment
		(start 203.89977 -109.438948)
		(end 205.12786 -109.438948)
		(width 0.1524)
		(layer "In13.Cu")
		(net "HSC_D_OC")
	)
	(segment
		(start 199.57288 -108.676948)
		(end 200.84288 -108.676948)
		(width 0.1524)
		(layer "In13.Cu")
		(net "HSC_D_OC")
	)
	(segment
		(start 242.627404 -105.463848)
		(end 243.721636 -106.55808)
		(width 0.1524)
		(layer "In13.Cu")
		(net "HSC_D_OC")
	)
	(segment
		(start 243.721636 -110.661704)
		(end 244.78488 -111.724948)
		(width 0.1524)
		(layer "In13.Cu")
		(net "HSC_D_OC")
	)
	(segment
		(start 217.392758 -110.2868)
		(end 229.2858 -110.2868)
		(width 0.1524)
		(layer "In13.Cu")
		(net "HSC_D_OC")
	)
	(segment
		(start 283.39542 -415.64814)
		(end 282.30195 -414.55467)
		(width 0.1524)
		(layer "In15.Cu")
		(net "HSC_D_OC")
	)
	(segment
		(start 291.4015 -415.64814)
		(end 283.39542 -415.64814)
		(width 0.1524)
		(layer "In15.Cu")
		(net "HSC_D_OC")
	)
	(segment
		(start 282.75026 -383.53492)
		(end 278.3586 -383.53492)
		(width 0.1524)
		(layer "In15.Cu")
		(net "HSC_D_OC")
	)
	(segment
		(start 284.0101 -384.79476)
		(end 282.75026 -383.53492)
		(width 0.1524)
		(layer "In15.Cu")
		(net "HSC_D_OC")
	)
	(segment
		(start 282.30195 -414.55467)
		(end 282.30195 -391.77595)
		(width 0.1524)
		(layer "In15.Cu")
		(net "HSC_D_OC")
	)
	(segment
		(start 252.621796 -364.254796)
		(end 252.621796 -329.518772)
		(width 0.1524)
		(layer "In15.Cu")
		(net "HSC_D_OC")
	)
	(segment
		(start 293.46398 -423.0243)
		(end 293.46398 -417.71062)
		(width 0.1524)
		(layer "In15.Cu")
		(net "HSC_D_OC")
	)
	(segment
		(start 261.05358 -366.2299)
		(end 254.5969 -366.2299)
		(width 0.1524)
		(layer "In15.Cu")
		(net "HSC_D_OC")
	)
	(segment
		(start 282.30195 -391.77595)
		(end 284.0101 -390.0678)
		(width 0.1524)
		(layer "In15.Cu")
		(net "HSC_D_OC")
	)
	(segment
		(start 278.3586 -383.53492)
		(end 261.05358 -366.2299)
		(width 0.1524)
		(layer "In15.Cu")
		(net "HSC_D_OC")
	)
	(segment
		(start 284.0101 -390.0678)
		(end 284.0101 -384.79476)
		(width 0.1524)
		(layer "In15.Cu")
		(net "HSC_D_OC")
	)
	(segment
		(start 281.51328 -426.7708)
		(end 289.71748 -426.7708)
		(width 0.1524)
		(layer "In15.Cu")
		(net "HSC_D_OC")
	)
	(segment
		(start 289.71748 -426.7708)
		(end 293.46398 -423.0243)
		(width 0.1524)
		(layer "In15.Cu")
		(net "HSC_D_OC")
	)
	(segment
		(start 293.46398 -417.71062)
		(end 291.4015 -415.64814)
		(width 0.1524)
		(layer "In15.Cu")
		(net "HSC_D_OC")
	)
	(segment
		(start 254.5969 -366.2299)
		(end 252.621796 -364.254796)
		(width 0.1524)
		(layer "In15.Cu")
		(net "HSC_D_OC")
	)
	(segment
		(start 207.239108 -400.975322)
		(end 206.883508 -400.975322)
		(width 0.1524)
		(layer "F.Cu")
		(net "HSC_CS_2")
	)
	(segment
		(start 207.62087 -400.975322)
		(end 207.239108 -400.975322)
		(width 0.1524)
		(layer "F.Cu")
		(net "HSC_CS_2")
	)
	(segment
		(start 206.083408 -401.775422)
		(end 205.797658 -401.775422)
		(width 0.1524)
		(layer "F.Cu")
		(net "HSC_CS_2")
	)
	(segment
		(start 206.883508 -400.975322)
		(end 206.083408 -401.775422)
		(width 0.1524)
		(layer "F.Cu")
		(net "HSC_CS_2")
	)
	(segment
		(start 208.60258 -401.472908)
		(end 208.118456 -401.472908)
		(width 0.1524)
		(layer "F.Cu")
		(net "HSC_CS_2")
	)
	(segment
		(start 208.118456 -401.472908)
		(end 207.62087 -400.975322)
		(width 0.1524)
		(layer "F.Cu")
		(net "HSC_CS_2")
	)
	(via
		(at 207.239108 -400.975322)
		(size 0.762)
		(drill 0.381)
		(layers "F.Cu" "B.Cu")
		(net "HSC_CS_2")
	)
	(segment
		(start 195.256658 -400.784822)
		(end 196.380608 -400.784822)
		(width 0.1524)
		(layer "F.Cu")
		(net "HSC_CS_1")
	)
	(segment
		(start 197.576694 -401.472908)
		(end 197.93458 -401.472908)
		(width 0.1524)
		(layer "F.Cu")
		(net "HSC_CS_1")
	)
	(segment
		(start 196.380608 -400.784822)
		(end 196.634608 -400.530822)
		(width 0.1524)
		(layer "F.Cu")
		(net "HSC_CS_1")
	)
	(segment
		(start 196.634608 -400.530822)
		(end 197.576694 -401.472908)
		(width 0.1524)
		(layer "F.Cu")
		(net "HSC_CS_1")
	)
	(via
		(at 196.634608 -400.530822)
		(size 0.762)
		(drill 0.381)
		(layers "F.Cu" "B.Cu")
		(net "HSC_CS_1")
	)
	(segment
		(start 179.752498 -400.223482)
		(end 180.619908 -400.223482)
		(width 0.1524)
		(layer "F.Cu")
		(net "HSC_CS")
	)
	(segment
		(start 181.013608 -400.617182)
		(end 180.619908 -400.223482)
		(width 0.1524)
		(layer "F.Cu")
		(net "HSC_CS")
	)
	(segment
		(start 182.676546 -401.597368)
		(end 182.306214 -401.597368)
		(width 0.1524)
		(layer "F.Cu")
		(net "HSC_CS")
	)
	(segment
		(start 182.306214 -401.597368)
		(end 181.326028 -400.617182)
		(width 0.1524)
		(layer "F.Cu")
		(net "HSC_CS")
	)
	(segment
		(start 181.326028 -400.617182)
		(end 181.013608 -400.617182)
		(width 0.1524)
		(layer "F.Cu")
		(net "HSC_CS")
	)
	(via
		(at 180.619908 -400.223482)
		(size 0.508)
		(drill 0.254)
		(layers "F.Cu" "B.Cu")
		(net "HSC_CS")
	)
	(segment
		(start 180.584348 -398.012412)
		(end 180.584348 -398.638522)
		(width 0.1524)
		(layer "F.Cu")
		(net "HSC_ADDR")
	)
	(segment
		(start 179.760118 -397.188182)
		(end 180.584348 -398.012412)
		(width 0.1524)
		(layer "F.Cu")
		(net "HSC_ADDR")
	)
	(segment
		(start 180.584348 -398.638522)
		(end 180.904388 -398.958562)
		(width 0.1524)
		(layer "F.Cu")
		(net "HSC_ADDR")
	)
	(segment
		(start 183.664098 -400.484848)
		(end 183.664098 -400.323812)
		(width 0.1524)
		(layer "F.Cu")
		(net "HSC_ADDR")
	)
	(segment
		(start 181.242208 -399.296382)
		(end 180.904388 -398.958562)
		(width 0.1524)
		(layer "F.Cu")
		(net "HSC_ADDR")
	)
	(segment
		(start 182.636668 -399.296382)
		(end 181.242208 -399.296382)
		(width 0.1524)
		(layer "F.Cu")
		(net "HSC_ADDR")
	)
	(segment
		(start 183.664098 -400.323812)
		(end 182.636668 -399.296382)
		(width 0.1524)
		(layer "F.Cu")
		(net "HSC_ADDR")
	)
	(via
		(at 180.904388 -398.958562)
		(size 0.508)
		(drill 0.254)
		(layers "F.Cu" "B.Cu")
		(net "HSC_ADDR")
	)
	(segment
		(start 180.584348 -398.012412)
		(end 179.760118 -397.188182)
		(width 0.1524)
		(layer "B.Cu")
		(net "HSC_ADDR")
	)
	(segment
		(start 180.904388 -398.958562)
		(end 180.741828 -398.958562)
		(width 0.1524)
		(layer "B.Cu")
		(net "HSC_ADDR")
	)
	(segment
		(start 180.584348 -398.801082)
		(end 180.584348 -398.012412)
		(width 0.1524)
		(layer "B.Cu")
		(net "HSC_ADDR")
	)
	(segment
		(start 180.741828 -398.958562)
		(end 180.584348 -398.801082)
		(width 0.1524)
		(layer "B.Cu")
		(net "HSC_ADDR")
	)
	(segment
		(start 342.19134 -50.799746)
		(end 341.921338 -50.329846)
		(width 0.1143)
		(layer "F.Cu")
		(net "TP_P3E_PCH_13_TX_DP")
	)
	(via
		(at 341.921338 -50.329846)
		(size 0.4572)
		(drill 0.2032)
		(layers "F.Cu" "B.Cu")
		(net "TP_P3E_PCH_13_TX_DP")
	)
	(segment
		(start 342.19134 -51.739546)
		(end 341.921338 -51.269646)
		(width 0.1143)
		(layer "F.Cu")
		(net "TP_P3E_PCH_13_TX_DN")
	)
	(via
		(at 341.921338 -51.269646)
		(size 0.4572)
		(drill 0.2032)
		(layers "F.Cu" "B.Cu")
		(net "TP_P3E_PCH_13_TX_DN")
	)
	(segment
		(start 349.327216 -55.715408)
		(end 348.240096 -55.715408)
		(width 0.12954)
		(layer "F.Cu")
		(net "TP_P3E_PCH_13_RX_DP")
	)
	(segment
		(start 347.7006 -55.715408)
		(end 347.43517 -55.449978)
		(width 0.0889)
		(layer "F.Cu")
		(net "TP_P3E_PCH_13_RX_DP")
	)
	(segment
		(start 347.43517 -55.449978)
		(end 347.068394 -55.449978)
		(width 0.0889)
		(layer "F.Cu")
		(net "TP_P3E_PCH_13_RX_DP")
	)
	(segment
		(start 352.443034 -58.147966)
		(end 351.759774 -58.147966)
		(width 0.12954)
		(layer "F.Cu")
		(net "TP_P3E_PCH_13_RX_DP")
	)
	(segment
		(start 354.612956 -61.283088)
		(end 354.612956 -60.317888)
		(width 0.12954)
		(layer "F.Cu")
		(net "TP_P3E_PCH_13_RX_DP")
	)
	(segment
		(start 358.234996 -62.106048)
		(end 355.435916 -62.106048)
		(width 0.12954)
		(layer "F.Cu")
		(net "TP_P3E_PCH_13_RX_DP")
	)
	(segment
		(start 347.068394 -55.449978)
		(end 346.799662 -55.453534)
		(width 0.0889)
		(layer "F.Cu")
		(net "TP_P3E_PCH_13_RX_DP")
	)
	(segment
		(start 355.435916 -62.106048)
		(end 354.612956 -61.283088)
		(width 0.12954)
		(layer "F.Cu")
		(net "TP_P3E_PCH_13_RX_DP")
	)
	(segment
		(start 351.759774 -58.147966)
		(end 349.327216 -55.715408)
		(width 0.12954)
		(layer "F.Cu")
		(net "TP_P3E_PCH_13_RX_DP")
	)
	(segment
		(start 354.612956 -60.317888)
		(end 352.443034 -58.147966)
		(width 0.12954)
		(layer "F.Cu")
		(net "TP_P3E_PCH_13_RX_DP")
	)
	(segment
		(start 358.697276 -61.643768)
		(end 358.234996 -62.106048)
		(width 0.12954)
		(layer "F.Cu")
		(net "TP_P3E_PCH_13_RX_DP")
	)
	(segment
		(start 348.240096 -55.715408)
		(end 347.7006 -55.715408)
		(width 0.0889)
		(layer "F.Cu")
		(net "TP_P3E_PCH_13_RX_DP")
	)
	(via
		(at 358.697276 -61.643768)
		(size 0.762)
		(drill 0.381)
		(layers "F.Cu" "B.Cu")
		(net "TP_P3E_PCH_13_RX_DP")
	)
	(segment
		(start 346.339922 -55.453534)
		(end 345.96959 -55.453534)
		(width 0.0889)
		(layer "F.Cu")
		(net "TP_P3E_PCH_13_RX_DN")
	)
	(segment
		(start 354.237036 -59.535568)
		(end 352.459798 -57.75833)
		(width 0.1143)
		(layer "F.Cu")
		(net "TP_P3E_PCH_13_RX_DN")
	)
	(segment
		(start 346.694252 -55.14721)
		(end 346.339922 -55.453534)
		(width 0.0889)
		(layer "F.Cu")
		(net "TP_P3E_PCH_13_RX_DN")
	)
	(segment
		(start 347.727778 -55.473092)
		(end 347.514164 -55.259478)
		(width 0.0889)
		(layer "F.Cu")
		(net "TP_P3E_PCH_13_RX_DN")
	)
	(segment
		(start 351.790254 -57.75833)
		(end 349.505016 -55.473092)
		(width 0.1143)
		(layer "F.Cu")
		(net "TP_P3E_PCH_13_RX_DN")
	)
	(segment
		(start 355.341936 -59.535568)
		(end 354.237036 -59.535568)
		(width 0.1143)
		(layer "F.Cu")
		(net "TP_P3E_PCH_13_RX_DN")
	)
	(segment
		(start 349.505016 -55.473092)
		(end 348.295976 -55.473092)
		(width 0.1143)
		(layer "F.Cu")
		(net "TP_P3E_PCH_13_RX_DN")
	)
	(segment
		(start 352.459798 -57.75833)
		(end 351.790254 -57.75833)
		(width 0.1143)
		(layer "F.Cu")
		(net "TP_P3E_PCH_13_RX_DN")
	)
	(segment
		(start 347.091 -55.259478)
		(end 346.978732 -55.14721)
		(width 0.0889)
		(layer "F.Cu")
		(net "TP_P3E_PCH_13_RX_DN")
	)
	(segment
		(start 347.514164 -55.259478)
		(end 347.091 -55.259478)
		(width 0.0889)
		(layer "F.Cu")
		(net "TP_P3E_PCH_13_RX_DN")
	)
	(segment
		(start 346.978732 -55.14721)
		(end 346.694252 -55.14721)
		(width 0.0889)
		(layer "F.Cu")
		(net "TP_P3E_PCH_13_RX_DN")
	)
	(segment
		(start 348.295976 -55.473092)
		(end 347.727778 -55.473092)
		(width 0.0889)
		(layer "F.Cu")
		(net "TP_P3E_PCH_13_RX_DN")
	)
	(via
		(at 355.341936 -59.535568)
		(size 0.762)
		(drill 0.381)
		(layers "F.Cu" "B.Cu")
		(net "TP_P3E_PCH_13_RX_DN")
	)
	(segment
		(start 343.81948 -51.739546)
		(end 343.550494 -51.269392)
		(width 0.1143)
		(layer "F.Cu")
		(net "TP_P3E_PCH_12_TX_DP")
	)
	(via
		(at 343.550494 -51.269392)
		(size 0.4572)
		(drill 0.2032)
		(layers "F.Cu" "B.Cu")
		(net "TP_P3E_PCH_12_TX_DP")
	)
	(via
		(at 344.2335 -53.594508)
		(size 0.6604)
		(drill 0.3302)
		(layers "F.Cu" "B.Cu")
		(net "TP_P3E_PCH_12_TX_DP")
	)
	(segment
		(start 343.962736 -53.323744)
		(end 343.962736 -51.945794)
		(width 0.1143)
		(layer "B.Cu")
		(net "TP_P3E_PCH_12_TX_DP")
	)
	(segment
		(start 343.550494 -51.533552)
		(end 343.550494 -51.269392)
		(width 0.1143)
		(layer "B.Cu")
		(net "TP_P3E_PCH_12_TX_DP")
	)
	(segment
		(start 343.962736 -51.945794)
		(end 343.550494 -51.533552)
		(width 0.1143)
		(layer "B.Cu")
		(net "TP_P3E_PCH_12_TX_DP")
	)
	(segment
		(start 344.2335 -53.594508)
		(end 343.962736 -53.323744)
		(width 0.1143)
		(layer "B.Cu")
		(net "TP_P3E_PCH_12_TX_DP")
	)
	(segment
		(start 343.005156 -51.269646)
		(end 342.737694 -50.799492)
		(width 0.1143)
		(layer "F.Cu")
		(net "TP_P3E_PCH_12_TX_DN")
	)
	(via
		(at 342.737694 -50.799492)
		(size 0.4572)
		(drill 0.2032)
		(layers "F.Cu" "B.Cu")
		(net "TP_P3E_PCH_12_TX_DN")
	)
	(via
		(at 346.24518 -51.021488)
		(size 0.6604)
		(drill 0.3302)
		(layers "F.Cu" "B.Cu")
		(net "TP_P3E_PCH_12_TX_DN")
	)
	(segment
		(start 345.34856 -50.124868)
		(end 344.7923 -50.124868)
		(width 0.1143)
		(layer "B.Cu")
		(net "TP_P3E_PCH_12_TX_DN")
	)
	(segment
		(start 344.165936 -50.325528)
		(end 343.691972 -50.799492)
		(width 0.1143)
		(layer "B.Cu")
		(net "TP_P3E_PCH_12_TX_DN")
	)
	(segment
		(start 343.691972 -50.799492)
		(end 342.737694 -50.799492)
		(width 0.1143)
		(layer "B.Cu")
		(net "TP_P3E_PCH_12_TX_DN")
	)
	(segment
		(start 344.59164 -50.325528)
		(end 344.165936 -50.325528)
		(width 0.1143)
		(layer "B.Cu")
		(net "TP_P3E_PCH_12_TX_DN")
	)
	(segment
		(start 344.7923 -50.124868)
		(end 344.59164 -50.325528)
		(width 0.1143)
		(layer "B.Cu")
		(net "TP_P3E_PCH_12_TX_DN")
	)
	(segment
		(start 346.24518 -51.021488)
		(end 345.34856 -50.124868)
		(width 0.1143)
		(layer "B.Cu")
		(net "TP_P3E_PCH_12_TX_DN")
	)
	(segment
		(start 350.37903 -55.758842)
		(end 349.82404 -55.203852)
		(width 0.1143)
		(layer "F.Cu")
		(net "TP_P3E_PCH_12_RX_DP")
	)
	(segment
		(start 353.969574 -58.664348)
		(end 353.134422 -57.829196)
		(width 0.1143)
		(layer "F.Cu")
		(net "TP_P3E_PCH_12_RX_DP")
	)
	(segment
		(start 352.250756 -55.758842)
		(end 350.37903 -55.758842)
		(width 0.1143)
		(layer "F.Cu")
		(net "TP_P3E_PCH_12_RX_DP")
	)
	(segment
		(start 353.134422 -57.521348)
		(end 352.786696 -57.173622)
		(width 0.1143)
		(layer "F.Cu")
		(net "TP_P3E_PCH_12_RX_DP")
	)
	(segment
		(start 347.455236 -54.907688)
		(end 347.302074 -54.907942)
		(width 0.0889)
		(layer "F.Cu")
		(net "TP_P3E_PCH_12_RX_DP")
	)
	(segment
		(start 348.148656 -55.203852)
		(end 347.753432 -55.203852)
		(width 0.0889)
		(layer "F.Cu")
		(net "TP_P3E_PCH_12_RX_DP")
	)
	(segment
		(start 349.82404 -55.203852)
		(end 348.148656 -55.203852)
		(width 0.1143)
		(layer "F.Cu")
		(net "TP_P3E_PCH_12_RX_DP")
	)
	(segment
		(start 352.786696 -56.294782)
		(end 352.250756 -55.758842)
		(width 0.1143)
		(layer "F.Cu")
		(net "TP_P3E_PCH_12_RX_DP")
	)
	(segment
		(start 352.786696 -57.173622)
		(end 352.786696 -56.294782)
		(width 0.1143)
		(layer "F.Cu")
		(net "TP_P3E_PCH_12_RX_DP")
	)
	(segment
		(start 354.201222 -58.664348)
		(end 353.969574 -58.664348)
		(width 0.1143)
		(layer "F.Cu")
		(net "TP_P3E_PCH_12_RX_DP")
	)
	(segment
		(start 353.134422 -57.829196)
		(end 353.134422 -57.521348)
		(width 0.1143)
		(layer "F.Cu")
		(net "TP_P3E_PCH_12_RX_DP")
	)
	(segment
		(start 347.260164 -54.907942)
		(end 347.214698 -54.953408)
		(width 0.0889)
		(layer "F.Cu")
		(net "TP_P3E_PCH_12_RX_DP")
	)
	(segment
		(start 347.302074 -54.907942)
		(end 347.260164 -54.907942)
		(width 0.0889)
		(layer "F.Cu")
		(net "TP_P3E_PCH_12_RX_DP")
	)
	(segment
		(start 347.753432 -55.203852)
		(end 347.455236 -54.907688)
		(width 0.0889)
		(layer "F.Cu")
		(net "TP_P3E_PCH_12_RX_DP")
	)
	(via
		(at 354.201222 -58.664348)
		(size 0.762)
		(drill 0.381)
		(layers "F.Cu" "B.Cu")
		(net "TP_P3E_PCH_12_RX_DP")
	)
	(segment
		(start 347.77172 -54.953408)
		(end 347.492574 -54.675786)
		(width 0.0889)
		(layer "F.Cu")
		(net "TP_P3E_PCH_12_RX_DN")
	)
	(segment
		(start 353.426522 -56.362854)
		(end 352.582226 -55.518558)
		(width 0.1143)
		(layer "F.Cu")
		(net "TP_P3E_PCH_12_RX_DN")
	)
	(segment
		(start 349.94469 -54.953408)
		(end 348.204536 -54.953408)
		(width 0.1143)
		(layer "F.Cu")
		(net "TP_P3E_PCH_12_RX_DN")
	)
	(segment
		(start 346.775278 -54.827424)
		(end 346.649294 -54.953408)
		(width 0.0889)
		(layer "F.Cu")
		(net "TP_P3E_PCH_12_RX_DN")
	)
	(segment
		(start 348.204536 -54.953408)
		(end 347.77172 -54.953408)
		(width 0.0889)
		(layer "F.Cu")
		(net "TP_P3E_PCH_12_RX_DN")
	)
	(segment
		(start 350.50984 -55.518558)
		(end 349.94469 -54.953408)
		(width 0.1143)
		(layer "F.Cu")
		(net "TP_P3E_PCH_12_RX_DN")
	)
	(segment
		(start 352.582226 -55.518558)
		(end 350.50984 -55.518558)
		(width 0.1143)
		(layer "F.Cu")
		(net "TP_P3E_PCH_12_RX_DN")
	)
	(segment
		(start 346.970604 -54.764432)
		(end 346.775278 -54.827424)
		(width 0.0889)
		(layer "F.Cu")
		(net "TP_P3E_PCH_12_RX_DN")
	)
	(segment
		(start 353.426522 -56.772302)
		(end 353.426522 -56.362854)
		(width 0.1143)
		(layer "F.Cu")
		(net "TP_P3E_PCH_12_RX_DN")
	)
	(segment
		(start 347.076522 -54.673246)
		(end 346.970604 -54.764432)
		(width 0.0889)
		(layer "F.Cu")
		(net "TP_P3E_PCH_12_RX_DN")
	)
	(segment
		(start 347.16212 -54.67604)
		(end 347.076522 -54.673246)
		(width 0.0889)
		(layer "F.Cu")
		(net "TP_P3E_PCH_12_RX_DN")
	)
	(segment
		(start 346.649294 -54.953408)
		(end 346.384626 -54.953408)
		(width 0.0889)
		(layer "F.Cu")
		(net "TP_P3E_PCH_12_RX_DN")
	)
	(segment
		(start 347.294962 -54.67604)
		(end 347.16212 -54.67604)
		(width 0.0889)
		(layer "F.Cu")
		(net "TP_P3E_PCH_12_RX_DN")
	)
	(segment
		(start 347.492574 -54.675786)
		(end 347.294962 -54.67604)
		(width 0.0889)
		(layer "F.Cu")
		(net "TP_P3E_PCH_12_RX_DN")
	)
	(via
		(at 353.426522 -56.772302)
		(size 0.762)
		(drill 0.381)
		(layers "F.Cu" "B.Cu")
		(net "TP_P3E_PCH_12_RX_DN")
	)
	(segment
		(start 212.14588 -41.620948)
		(end 212.14588 -42.962068)
		(width 0.12954)
		(layer "F.Cu")
		(net "SMB_SENSOR_E1S_3V3AUX_SDA")
	)
	(segment
		(start 111.074962 -127.417322)
		(end 111.732822 -128.075182)
		(width 0.12954)
		(layer "F.Cu")
		(net "SMB_SENSOR_E1S_3V3AUX_SDA")
	)
	(segment
		(start 113.066322 -129.408682)
		(end 111.732822 -128.075182)
		(width 0.12954)
		(layer "F.Cu")
		(net "SMB_SENSOR_E1S_3V3AUX_SDA")
	)
	(segment
		(start 212.14588 -42.962068)
		(end 213.247224 -44.063412)
		(width 0.12954)
		(layer "F.Cu")
		(net "SMB_SENSOR_E1S_3V3AUX_SDA")
	)
	(segment
		(start 113.094262 -129.408682)
		(end 113.066322 -129.408682)
		(width 0.12954)
		(layer "F.Cu")
		(net "SMB_SENSOR_E1S_3V3AUX_SDA")
	)
	(segment
		(start 109.52988 -127.417322)
		(end 111.074962 -127.417322)
		(width 0.12954)
		(layer "F.Cu")
		(net "SMB_SENSOR_E1S_3V3AUX_SDA")
	)
	(segment
		(start 213.247224 -44.063412)
		(end 214.010748 -44.063412)
		(width 0.12954)
		(layer "F.Cu")
		(net "SMB_SENSOR_E1S_3V3AUX_SDA")
	)
	(via
		(at 212.14588 -41.620948)
		(size 0.508)
		(drill 0.254)
		(layers "F.Cu" "B.Cu")
		(net "SMB_SENSOR_E1S_3V3AUX_SDA")
	)
	(via
		(at 87.7824 -47.793148)
		(size 0.508)
		(drill 0.254)
		(layers "F.Cu" "B.Cu")
		(net "SMB_SENSOR_E1S_3V3AUX_SDA")
	)
	(via
		(at 109.52988 -127.417322)
		(size 0.508)
		(drill 0.254)
		(layers "F.Cu" "B.Cu")
		(net "SMB_SENSOR_E1S_3V3AUX_SDA")
	)
	(segment
		(start 110.55096 -119.046498)
		(end 110.55096 -114.031268)
		(width 0.127)
		(layer "In2.Cu")
		(net "SMB_SENSOR_E1S_3V3AUX_SDA")
	)
	(segment
		(start 109.52988 -127.417322)
		(end 107.30484 -125.192282)
		(width 0.127)
		(layer "In2.Cu")
		(net "SMB_SENSOR_E1S_3V3AUX_SDA")
	)
	(segment
		(start 111.6457 -86.944708)
		(end 106.7181 -82.017108)
		(width 0.127)
		(layer "In2.Cu")
		(net "SMB_SENSOR_E1S_3V3AUX_SDA")
	)
	(segment
		(start 98.68408 -52.238148)
		(end 92.2274 -52.238148)
		(width 0.127)
		(layer "In2.Cu")
		(net "SMB_SENSOR_E1S_3V3AUX_SDA")
	)
	(segment
		(start 105.791 -62.842648)
		(end 105.791 -58.842148)
		(width 0.127)
		(layer "In2.Cu")
		(net "SMB_SENSOR_E1S_3V3AUX_SDA")
	)
	(segment
		(start 115.59032 -110.719108)
		(end 115.80368 -110.505748)
		(width 0.127)
		(layer "In2.Cu")
		(net "SMB_SENSOR_E1S_3V3AUX_SDA")
	)
	(segment
		(start 105.791 -58.842148)
		(end 101.00056 -54.051708)
		(width 0.127)
		(layer "In2.Cu")
		(net "SMB_SENSOR_E1S_3V3AUX_SDA")
	)
	(segment
		(start 110.55096 -114.031268)
		(end 113.86312 -110.719108)
		(width 0.127)
		(layer "In2.Cu")
		(net "SMB_SENSOR_E1S_3V3AUX_SDA")
	)
	(segment
		(start 115.03406 -106.667808)
		(end 112.78108 -106.667808)
		(width 0.127)
		(layer "In2.Cu")
		(net "SMB_SENSOR_E1S_3V3AUX_SDA")
	)
	(segment
		(start 101.00056 -54.051708)
		(end 100.49764 -54.051708)
		(width 0.127)
		(layer "In2.Cu")
		(net "SMB_SENSOR_E1S_3V3AUX_SDA")
	)
	(segment
		(start 100.49764 -54.051708)
		(end 98.68408 -52.238148)
		(width 0.127)
		(layer "In2.Cu")
		(net "SMB_SENSOR_E1S_3V3AUX_SDA")
	)
	(segment
		(start 111.6457 -105.532428)
		(end 111.6457 -86.944708)
		(width 0.127)
		(layer "In2.Cu")
		(net "SMB_SENSOR_E1S_3V3AUX_SDA")
	)
	(segment
		(start 107.30484 -122.292618)
		(end 110.55096 -119.046498)
		(width 0.127)
		(layer "In2.Cu")
		(net "SMB_SENSOR_E1S_3V3AUX_SDA")
	)
	(segment
		(start 107.30484 -125.192282)
		(end 107.30484 -122.292618)
		(width 0.127)
		(layer "In2.Cu")
		(net "SMB_SENSOR_E1S_3V3AUX_SDA")
	)
	(segment
		(start 112.78108 -106.667808)
		(end 111.6457 -105.532428)
		(width 0.127)
		(layer "In2.Cu")
		(net "SMB_SENSOR_E1S_3V3AUX_SDA")
	)
	(segment
		(start 115.80368 -110.505748)
		(end 115.80368 -107.437428)
		(width 0.127)
		(layer "In2.Cu")
		(net "SMB_SENSOR_E1S_3V3AUX_SDA")
	)
	(segment
		(start 106.7181 -63.769748)
		(end 105.791 -62.842648)
		(width 0.127)
		(layer "In2.Cu")
		(net "SMB_SENSOR_E1S_3V3AUX_SDA")
	)
	(segment
		(start 92.2274 -52.238148)
		(end 87.7824 -47.793148)
		(width 0.127)
		(layer "In2.Cu")
		(net "SMB_SENSOR_E1S_3V3AUX_SDA")
	)
	(segment
		(start 115.80368 -107.437428)
		(end 115.03406 -106.667808)
		(width 0.127)
		(layer "In2.Cu")
		(net "SMB_SENSOR_E1S_3V3AUX_SDA")
	)
	(segment
		(start 113.86312 -110.719108)
		(end 115.59032 -110.719108)
		(width 0.127)
		(layer "In2.Cu")
		(net "SMB_SENSOR_E1S_3V3AUX_SDA")
	)
	(segment
		(start 106.7181 -82.017108)
		(end 106.7181 -63.769748)
		(width 0.127)
		(layer "In2.Cu")
		(net "SMB_SENSOR_E1S_3V3AUX_SDA")
	)
	(segment
		(start 194.39128 -35.016948)
		(end 196.3928 -35.016948)
		(width 0.127)
		(layer "In6.Cu")
		(net "SMB_SENSOR_E1S_3V3AUX_SDA")
	)
	(segment
		(start 191.76238 -37.645848)
		(end 194.39128 -35.016948)
		(width 0.127)
		(layer "In6.Cu")
		(net "SMB_SENSOR_E1S_3V3AUX_SDA")
	)
	(segment
		(start 135.2677 -37.605208)
		(end 138.08456 -34.788348)
		(width 0.127)
		(layer "In6.Cu")
		(net "SMB_SENSOR_E1S_3V3AUX_SDA")
	)
	(segment
		(start 138.08456 -34.788348)
		(end 173.0883 -34.788348)
		(width 0.127)
		(layer "In6.Cu")
		(net "SMB_SENSOR_E1S_3V3AUX_SDA")
	)
	(segment
		(start 135.2677 -39.055548)
		(end 135.2677 -37.605208)
		(width 0.127)
		(layer "In6.Cu")
		(net "SMB_SENSOR_E1S_3V3AUX_SDA")
	)
	(segment
		(start 134.98322 -39.340028)
		(end 135.2677 -39.055548)
		(width 0.127)
		(layer "In6.Cu")
		(net "SMB_SENSOR_E1S_3V3AUX_SDA")
	)
	(segment
		(start 117.25656 -39.340028)
		(end 134.98322 -39.340028)
		(width 0.127)
		(layer "In6.Cu")
		(net "SMB_SENSOR_E1S_3V3AUX_SDA")
	)
	(segment
		(start 116.52504 -40.071548)
		(end 117.25656 -39.340028)
		(width 0.127)
		(layer "In6.Cu")
		(net "SMB_SENSOR_E1S_3V3AUX_SDA")
	)
	(segment
		(start 87.7824 -44.794932)
		(end 90.016584 -42.560748)
		(width 0.127)
		(layer "In6.Cu")
		(net "SMB_SENSOR_E1S_3V3AUX_SDA")
	)
	(segment
		(start 109.38256 -36.840668)
		(end 112.61344 -40.071548)
		(width 0.127)
		(layer "In6.Cu")
		(net "SMB_SENSOR_E1S_3V3AUX_SDA")
	)
	(segment
		(start 211.963 -42.878248)
		(end 212.14588 -42.695368)
		(width 0.127)
		(layer "In6.Cu")
		(net "SMB_SENSOR_E1S_3V3AUX_SDA")
	)
	(segment
		(start 90.016584 -42.560748)
		(end 97.81413 -42.560748)
		(width 0.127)
		(layer "In6.Cu")
		(net "SMB_SENSOR_E1S_3V3AUX_SDA")
	)
	(segment
		(start 212.14588 -42.695368)
		(end 212.14588 -41.620948)
		(width 0.127)
		(layer "In6.Cu")
		(net "SMB_SENSOR_E1S_3V3AUX_SDA")
	)
	(segment
		(start 175.9458 -37.645848)
		(end 191.76238 -37.645848)
		(width 0.127)
		(layer "In6.Cu")
		(net "SMB_SENSOR_E1S_3V3AUX_SDA")
	)
	(segment
		(start 204.2541 -42.878248)
		(end 211.963 -42.878248)
		(width 0.127)
		(layer "In6.Cu")
		(net "SMB_SENSOR_E1S_3V3AUX_SDA")
	)
	(segment
		(start 97.81413 -42.560748)
		(end 103.53421 -36.840668)
		(width 0.127)
		(layer "In6.Cu")
		(net "SMB_SENSOR_E1S_3V3AUX_SDA")
	)
	(segment
		(start 112.61344 -40.071548)
		(end 116.52504 -40.071548)
		(width 0.127)
		(layer "In6.Cu")
		(net "SMB_SENSOR_E1S_3V3AUX_SDA")
	)
	(segment
		(start 87.7824 -47.793148)
		(end 87.7824 -44.794932)
		(width 0.127)
		(layer "In6.Cu")
		(net "SMB_SENSOR_E1S_3V3AUX_SDA")
	)
	(segment
		(start 173.0883 -34.788348)
		(end 175.9458 -37.645848)
		(width 0.127)
		(layer "In6.Cu")
		(net "SMB_SENSOR_E1S_3V3AUX_SDA")
	)
	(segment
		(start 196.3928 -35.016948)
		(end 204.2541 -42.878248)
		(width 0.127)
		(layer "In6.Cu")
		(net "SMB_SENSOR_E1S_3V3AUX_SDA")
	)
	(segment
		(start 103.53421 -36.840668)
		(end 109.38256 -36.840668)
		(width 0.127)
		(layer "In6.Cu")
		(net "SMB_SENSOR_E1S_3V3AUX_SDA")
	)
	(segment
		(start 213.303104 -43.413172)
		(end 214.010748 -43.413172)
		(width 0.12954)
		(layer "F.Cu")
		(net "SMB_SENSOR_E1S_3V3AUX_SCL")
	)
	(segment
		(start 212.90788 -43.017948)
		(end 213.303104 -43.413172)
		(width 0.12954)
		(layer "F.Cu")
		(net "SMB_SENSOR_E1S_3V3AUX_SCL")
	)
	(segment
		(start 113.094262 -128.392682)
		(end 111.732822 -127.031242)
		(width 0.12954)
		(layer "F.Cu")
		(net "SMB_SENSOR_E1S_3V3AUX_SCL")
	)
	(segment
		(start 111.130588 -126.075948)
		(end 111.732822 -126.678182)
		(width 0.12954)
		(layer "F.Cu")
		(net "SMB_SENSOR_E1S_3V3AUX_SCL")
	)
	(segment
		(start 109.52988 -126.075948)
		(end 111.130588 -126.075948)
		(width 0.12954)
		(layer "F.Cu")
		(net "SMB_SENSOR_E1S_3V3AUX_SCL")
	)
	(segment
		(start 212.90788 -41.620948)
		(end 212.90788 -43.017948)
		(width 0.12954)
		(layer "F.Cu")
		(net "SMB_SENSOR_E1S_3V3AUX_SCL")
	)
	(segment
		(start 111.732822 -127.031242)
		(end 111.732822 -126.678182)
		(width 0.12954)
		(layer "F.Cu")
		(net "SMB_SENSOR_E1S_3V3AUX_SCL")
	)
	(via
		(at 212.90788 -41.620948)
		(size 0.508)
		(drill 0.254)
		(layers "F.Cu" "B.Cu")
		(net "SMB_SENSOR_E1S_3V3AUX_SCL")
	)
	(via
		(at 88.4174 -47.031148)
		(size 0.508)
		(drill 0.254)
		(layers "F.Cu" "B.Cu")
		(net "SMB_SENSOR_E1S_3V3AUX_SCL")
	)
	(via
		(at 109.52988 -126.075948)
		(size 0.508)
		(drill 0.254)
		(layers "F.Cu" "B.Cu")
		(net "SMB_SENSOR_E1S_3V3AUX_SCL")
	)
	(segment
		(start 110.98276 -114.210338)
		(end 110.98276 -119.225568)
		(width 0.127)
		(layer "In2.Cu")
		(net "SMB_SENSOR_E1S_3V3AUX_SCL")
	)
	(segment
		(start 107.73664 -124.282708)
		(end 109.52988 -126.075948)
		(width 0.127)
		(layer "In2.Cu")
		(net "SMB_SENSOR_E1S_3V3AUX_SCL")
	)
	(segment
		(start 106.2736 -62.360048)
		(end 107.1499 -63.236348)
		(width 0.127)
		(layer "In2.Cu")
		(net "SMB_SENSOR_E1S_3V3AUX_SCL")
	)
	(segment
		(start 88.4174 -47.031148)
		(end 88.4174 -47.817024)
		(width 0.127)
		(layer "In2.Cu")
		(net "SMB_SENSOR_E1S_3V3AUX_SCL")
	)
	(segment
		(start 107.1499 -81.838038)
		(end 112.0775 -86.765638)
		(width 0.127)
		(layer "In2.Cu")
		(net "SMB_SENSOR_E1S_3V3AUX_SCL")
	)
	(segment
		(start 116.23548 -107.258358)
		(end 116.23548 -110.684818)
		(width 0.127)
		(layer "In2.Cu")
		(net "SMB_SENSOR_E1S_3V3AUX_SCL")
	)
	(segment
		(start 116.23548 -110.684818)
		(end 115.76939 -111.150908)
		(width 0.127)
		(layer "In2.Cu")
		(net "SMB_SENSOR_E1S_3V3AUX_SCL")
	)
	(segment
		(start 115.21313 -106.236008)
		(end 116.23548 -107.258358)
		(width 0.127)
		(layer "In2.Cu")
		(net "SMB_SENSOR_E1S_3V3AUX_SCL")
	)
	(segment
		(start 98.86315 -51.806348)
		(end 100.523548 -53.466746)
		(width 0.127)
		(layer "In2.Cu")
		(net "SMB_SENSOR_E1S_3V3AUX_SCL")
	)
	(segment
		(start 100.523548 -53.466746)
		(end 101.101652 -53.466746)
		(width 0.127)
		(layer "In2.Cu")
		(net "SMB_SENSOR_E1S_3V3AUX_SCL")
	)
	(segment
		(start 101.101652 -53.466746)
		(end 106.2736 -58.638694)
		(width 0.127)
		(layer "In2.Cu")
		(net "SMB_SENSOR_E1S_3V3AUX_SCL")
	)
	(segment
		(start 114.04219 -111.150908)
		(end 110.98276 -114.210338)
		(width 0.127)
		(layer "In2.Cu")
		(net "SMB_SENSOR_E1S_3V3AUX_SCL")
	)
	(segment
		(start 112.0775 -86.765638)
		(end 112.0775 -105.353358)
		(width 0.127)
		(layer "In2.Cu")
		(net "SMB_SENSOR_E1S_3V3AUX_SCL")
	)
	(segment
		(start 110.98276 -119.225568)
		(end 107.73664 -122.471688)
		(width 0.127)
		(layer "In2.Cu")
		(net "SMB_SENSOR_E1S_3V3AUX_SCL")
	)
	(segment
		(start 115.76939 -111.150908)
		(end 114.04219 -111.150908)
		(width 0.127)
		(layer "In2.Cu")
		(net "SMB_SENSOR_E1S_3V3AUX_SCL")
	)
	(segment
		(start 92.406724 -51.806348)
		(end 98.86315 -51.806348)
		(width 0.127)
		(layer "In2.Cu")
		(net "SMB_SENSOR_E1S_3V3AUX_SCL")
	)
	(segment
		(start 107.1499 -63.236348)
		(end 107.1499 -81.838038)
		(width 0.127)
		(layer "In2.Cu")
		(net "SMB_SENSOR_E1S_3V3AUX_SCL")
	)
	(segment
		(start 106.2736 -58.638694)
		(end 106.2736 -62.360048)
		(width 0.127)
		(layer "In2.Cu")
		(net "SMB_SENSOR_E1S_3V3AUX_SCL")
	)
	(segment
		(start 88.4174 -47.817024)
		(end 92.406724 -51.806348)
		(width 0.127)
		(layer "In2.Cu")
		(net "SMB_SENSOR_E1S_3V3AUX_SCL")
	)
	(segment
		(start 112.0775 -105.353358)
		(end 112.96015 -106.236008)
		(width 0.127)
		(layer "In2.Cu")
		(net "SMB_SENSOR_E1S_3V3AUX_SCL")
	)
	(segment
		(start 112.96015 -106.236008)
		(end 115.21313 -106.236008)
		(width 0.127)
		(layer "In2.Cu")
		(net "SMB_SENSOR_E1S_3V3AUX_SCL")
	)
	(segment
		(start 107.73664 -122.471688)
		(end 107.73664 -124.282708)
		(width 0.127)
		(layer "In2.Cu")
		(net "SMB_SENSOR_E1S_3V3AUX_SCL")
	)
	(segment
		(start 116.70411 -40.503348)
		(end 117.43563 -39.771828)
		(width 0.127)
		(layer "In6.Cu")
		(net "SMB_SENSOR_E1S_3V3AUX_SCL")
	)
	(segment
		(start 197.663054 -39.690548)
		(end 199.034146 -39.690548)
		(width 0.127)
		(layer "In6.Cu")
		(net "SMB_SENSOR_E1S_3V3AUX_SCL")
	)
	(segment
		(start 97.9932 -42.992548)
		(end 103.71328 -37.272468)
		(width 0.127)
		(layer "In6.Cu")
		(net "SMB_SENSOR_E1S_3V3AUX_SCL")
	)
	(segment
		(start 88.4174 -44.775628)
		(end 90.20048 -42.992548)
		(width 0.127)
		(layer "In6.Cu")
		(net "SMB_SENSOR_E1S_3V3AUX_SCL")
	)
	(segment
		(start 212.90788 -42.020236)
		(end 212.90788 -41.620948)
		(width 0.127)
		(layer "In6.Cu")
		(net "SMB_SENSOR_E1S_3V3AUX_SCL")
	)
	(segment
		(start 135.6995 -39.234618)
		(end 135.6995 -37.784278)
		(width 0.127)
		(layer "In6.Cu")
		(net "SMB_SENSOR_E1S_3V3AUX_SCL")
	)
	(segment
		(start 109.20349 -37.272468)
		(end 112.43437 -40.503348)
		(width 0.127)
		(layer "In6.Cu")
		(net "SMB_SENSOR_E1S_3V3AUX_SCL")
	)
	(segment
		(start 212.74278 -42.709338)
		(end 212.74278 -42.185336)
		(width 0.127)
		(layer "In6.Cu")
		(net "SMB_SENSOR_E1S_3V3AUX_SCL")
	)
	(segment
		(start 88.4174 -47.031148)
		(end 88.4174 -44.775628)
		(width 0.127)
		(layer "In6.Cu")
		(net "SMB_SENSOR_E1S_3V3AUX_SCL")
	)
	(segment
		(start 135.6995 -37.784278)
		(end 138.26363 -35.220148)
		(width 0.127)
		(layer "In6.Cu")
		(net "SMB_SENSOR_E1S_3V3AUX_SCL")
	)
	(segment
		(start 103.71328 -37.272468)
		(end 109.20349 -37.272468)
		(width 0.127)
		(layer "In6.Cu")
		(net "SMB_SENSOR_E1S_3V3AUX_SCL")
	)
	(segment
		(start 175.76673 -38.077648)
		(end 196.050154 -38.077648)
		(width 0.127)
		(layer "In6.Cu")
		(net "SMB_SENSOR_E1S_3V3AUX_SCL")
	)
	(segment
		(start 112.43437 -40.503348)
		(end 116.70411 -40.503348)
		(width 0.127)
		(layer "In6.Cu")
		(net "SMB_SENSOR_E1S_3V3AUX_SCL")
	)
	(segment
		(start 212.14207 -43.310048)
		(end 212.74278 -42.709338)
		(width 0.127)
		(layer "In6.Cu")
		(net "SMB_SENSOR_E1S_3V3AUX_SCL")
	)
	(segment
		(start 117.43563 -39.771828)
		(end 135.16229 -39.771828)
		(width 0.127)
		(layer "In6.Cu")
		(net "SMB_SENSOR_E1S_3V3AUX_SCL")
	)
	(segment
		(start 199.034146 -39.690548)
		(end 202.653646 -43.310048)
		(width 0.127)
		(layer "In6.Cu")
		(net "SMB_SENSOR_E1S_3V3AUX_SCL")
	)
	(segment
		(start 90.20048 -42.992548)
		(end 97.9932 -42.992548)
		(width 0.127)
		(layer "In6.Cu")
		(net "SMB_SENSOR_E1S_3V3AUX_SCL")
	)
	(segment
		(start 196.050154 -38.077648)
		(end 197.663054 -39.690548)
		(width 0.127)
		(layer "In6.Cu")
		(net "SMB_SENSOR_E1S_3V3AUX_SCL")
	)
	(segment
		(start 135.16229 -39.771828)
		(end 135.6995 -39.234618)
		(width 0.127)
		(layer "In6.Cu")
		(net "SMB_SENSOR_E1S_3V3AUX_SCL")
	)
	(segment
		(start 212.74278 -42.185336)
		(end 212.90788 -42.020236)
		(width 0.127)
		(layer "In6.Cu")
		(net "SMB_SENSOR_E1S_3V3AUX_SCL")
	)
	(segment
		(start 202.653646 -43.310048)
		(end 212.14207 -43.310048)
		(width 0.127)
		(layer "In6.Cu")
		(net "SMB_SENSOR_E1S_3V3AUX_SCL")
	)
	(segment
		(start 172.90923 -35.220148)
		(end 175.76673 -38.077648)
		(width 0.127)
		(layer "In6.Cu")
		(net "SMB_SENSOR_E1S_3V3AUX_SCL")
	)
	(segment
		(start 138.26363 -35.220148)
		(end 172.90923 -35.220148)
		(width 0.127)
		(layer "In6.Cu")
		(net "SMB_SENSOR_E1S_3V3AUX_SCL")
	)
	(segment
		(start 157.444186 -64.111378)
		(end 158.004256 -63.551308)
		(width 0.12954)
		(layer "F.Cu")
		(net "SMB_PCIE_E1S_ISO_EN_R2")
	)
	(segment
		(start 158.004256 -63.551308)
		(end 158.258256 -63.297308)
		(width 0.12954)
		(layer "F.Cu")
		(net "SMB_PCIE_E1S_ISO_EN_R2")
	)
	(segment
		(start 158.258256 -63.297308)
		(end 159.255206 -63.297308)
		(width 0.12954)
		(layer "F.Cu")
		(net "SMB_PCIE_E1S_ISO_EN_R2")
	)
	(segment
		(start 156.692346 -64.111378)
		(end 157.444186 -64.111378)
		(width 0.12954)
		(layer "F.Cu")
		(net "SMB_PCIE_E1S_ISO_EN_R2")
	)
	(via
		(at 158.004256 -63.551308)
		(size 0.762)
		(drill 0.381)
		(layers "F.Cu" "B.Cu")
		(net "SMB_PCIE_E1S_ISO_EN_R2")
	)
	(segment
		(start 211.14893 -43.594528)
		(end 211.14893 -44.795948)
		(width 0.12954)
		(layer "F.Cu")
		(net "SMB_PCIE_E1S_ISO_EN_R")
	)
	(segment
		(start 213.2965 -44.788328)
		(end 214.010748 -44.788328)
		(width 0.12954)
		(layer "F.Cu")
		(net "SMB_PCIE_E1S_ISO_EN_R")
	)
	(segment
		(start 213.02218 -45.062648)
		(end 213.2965 -44.788328)
		(width 0.12954)
		(layer "F.Cu")
		(net "SMB_PCIE_E1S_ISO_EN_R")
	)
	(segment
		(start 211.14893 -42.382948)
		(end 211.14893 -43.594528)
		(width 0.12954)
		(layer "F.Cu")
		(net "SMB_PCIE_E1S_ISO_EN_R")
	)
	(segment
		(start 211.41563 -45.062648)
		(end 213.02218 -45.062648)
		(width 0.12954)
		(layer "F.Cu")
		(net "SMB_PCIE_E1S_ISO_EN_R")
	)
	(segment
		(start 211.14893 -44.795948)
		(end 211.41563 -45.062648)
		(width 0.12954)
		(layer "F.Cu")
		(net "SMB_PCIE_E1S_ISO_EN_R")
	)
	(via
		(at 211.14893 -43.594528)
		(size 0.762)
		(drill 0.381)
		(layers "F.Cu" "B.Cu")
		(net "SMB_PCIE_E1S_ISO_EN_R")
	)
	(segment
		(start 195.40474 -48.730408)
		(end 195.40474 -56.881268)
		(width 0.12954)
		(layer "F.Cu")
		(net "SMB_PCIE_E1S_ISO_EN")
	)
	(segment
		(start 164.62502 -64.478408)
		(end 163.095686 -64.478408)
		(width 0.12954)
		(layer "F.Cu")
		(net "SMB_PCIE_E1S_ISO_EN")
	)
	(segment
		(start 162.447986 -63.830708)
		(end 162.447986 -63.297308)
		(width 0.12954)
		(layer "F.Cu")
		(net "SMB_PCIE_E1S_ISO_EN")
	)
	(segment
		(start 195.40474 -56.881268)
		(end 192.99809 -59.287918)
		(width 0.12954)
		(layer "F.Cu")
		(net "SMB_PCIE_E1S_ISO_EN")
	)
	(segment
		(start 192.99809 -59.287918)
		(end 169.81551 -59.287918)
		(width 0.12954)
		(layer "F.Cu")
		(net "SMB_PCIE_E1S_ISO_EN")
	)
	(segment
		(start 169.81551 -59.287918)
		(end 164.62502 -64.478408)
		(width 0.12954)
		(layer "F.Cu")
		(net "SMB_PCIE_E1S_ISO_EN")
	)
	(segment
		(start 210.34883 -44.795948)
		(end 208.79689 -43.244008)
		(width 0.12954)
		(layer "F.Cu")
		(net "SMB_PCIE_E1S_ISO_EN")
	)
	(segment
		(start 160.055306 -63.297308)
		(end 161.25952 -63.297308)
		(width 0.12954)
		(layer "F.Cu")
		(net "SMB_PCIE_E1S_ISO_EN")
	)
	(segment
		(start 161.25952 -63.297308)
		(end 162.447986 -63.297308)
		(width 0.12954)
		(layer "F.Cu")
		(net "SMB_PCIE_E1S_ISO_EN")
	)
	(segment
		(start 200.89114 -43.244008)
		(end 195.40474 -48.730408)
		(width 0.12954)
		(layer "F.Cu")
		(net "SMB_PCIE_E1S_ISO_EN")
	)
	(segment
		(start 163.095686 -64.478408)
		(end 162.447986 -63.830708)
		(width 0.12954)
		(layer "F.Cu")
		(net "SMB_PCIE_E1S_ISO_EN")
	)
	(segment
		(start 208.79689 -43.244008)
		(end 200.89114 -43.244008)
		(width 0.12954)
		(layer "F.Cu")
		(net "SMB_PCIE_E1S_ISO_EN")
	)
	(via
		(at 161.25952 -63.297308)
		(size 0.762)
		(drill 0.381)
		(layers "F.Cu" "B.Cu")
		(net "SMB_PCIE_E1S_ISO_EN")
	)
	(segment
		(start 223.30283 -45.196252)
		(end 222.991934 -45.507148)
		(width 0.12954)
		(layer "F.Cu")
		(net "SMB_E1S_3V3AUX_ISO_SDA_R")
	)
	(segment
		(start 218.360752 -44.063412)
		(end 219.473018 -44.063412)
		(width 0.12954)
		(layer "F.Cu")
		(net "SMB_E1S_3V3AUX_ISO_SDA_R")
	)
	(segment
		(start 222.991934 -45.507148)
		(end 221.85503 -45.507148)
		(width 0.12954)
		(layer "F.Cu")
		(net "SMB_E1S_3V3AUX_ISO_SDA_R")
	)
	(segment
		(start 223.30283 -44.922948)
		(end 223.30283 -45.196252)
		(width 0.12954)
		(layer "F.Cu")
		(net "SMB_E1S_3V3AUX_ISO_SDA_R")
	)
	(segment
		(start 220.078554 -44.668948)
		(end 220.332554 -44.922948)
		(width 0.12954)
		(layer "F.Cu")
		(net "SMB_E1S_3V3AUX_ISO_SDA_R")
	)
	(segment
		(start 219.473018 -44.063412)
		(end 220.078554 -44.668948)
		(width 0.12954)
		(layer "F.Cu")
		(net "SMB_E1S_3V3AUX_ISO_SDA_R")
	)
	(segment
		(start 221.85503 -45.507148)
		(end 221.27083 -44.922948)
		(width 0.12954)
		(layer "F.Cu")
		(net "SMB_E1S_3V3AUX_ISO_SDA_R")
	)
	(segment
		(start 220.332554 -44.922948)
		(end 221.27083 -44.922948)
		(width 0.12954)
		(layer "F.Cu")
		(net "SMB_E1S_3V3AUX_ISO_SDA_R")
	)
	(via
		(at 220.078554 -44.668948)
		(size 0.762)
		(drill 0.381)
		(layers "F.Cu" "B.Cu")
		(net "SMB_E1S_3V3AUX_ISO_SDA_R")
	)
	(segment
		(start 232.000044 -46.764956)
		(end 233.016044 -46.764956)
		(width 0.12954)
		(layer "F.Cu")
		(net "SMB_E1S_3V3AUX_ISO_SDA")
	)
	(segment
		(start 224.10293 -44.922948)
		(end 225.43008 -44.922948)
		(width 0.12954)
		(layer "F.Cu")
		(net "SMB_E1S_3V3AUX_ISO_SDA")
	)
	(via
		(at 225.43008 -44.922948)
		(size 0.508)
		(drill 0.254)
		(layers "F.Cu" "B.Cu")
		(net "SMB_E1S_3V3AUX_ISO_SDA")
	)
	(via
		(at 233.016044 -46.764956)
		(size 0.508)
		(drill 0.254)
		(layers "F.Cu" "B.Cu")
		(net "SMB_E1S_3V3AUX_ISO_SDA")
	)
	(segment
		(start 225.43008 -46.327568)
		(end 225.43008 -44.922948)
		(width 0.12954)
		(layer "B.Cu")
		(net "SMB_E1S_3V3AUX_ISO_SDA")
	)
	(segment
		(start 231.164638 -46.764956)
		(end 230.383588 -47.546006)
		(width 0.12954)
		(layer "B.Cu")
		(net "SMB_E1S_3V3AUX_ISO_SDA")
	)
	(segment
		(start 226.648518 -47.546006)
		(end 225.43008 -46.327568)
		(width 0.12954)
		(layer "B.Cu")
		(net "SMB_E1S_3V3AUX_ISO_SDA")
	)
	(segment
		(start 230.383588 -47.546006)
		(end 226.648518 -47.546006)
		(width 0.12954)
		(layer "B.Cu")
		(net "SMB_E1S_3V3AUX_ISO_SDA")
	)
	(segment
		(start 233.016044 -46.764956)
		(end 231.164638 -46.764956)
		(width 0.12954)
		(layer "B.Cu")
		(net "SMB_E1S_3V3AUX_ISO_SDA")
	)
	(segment
		(start 223.30283 -43.798744)
		(end 222.940626 -44.160948)
		(width 0.12954)
		(layer "F.Cu")
		(net "SMB_E1S_3V3AUX_ISO_SCL_R")
	)
	(segment
		(start 223.30283 -43.525948)
		(end 223.30283 -43.798744)
		(width 0.12954)
		(layer "F.Cu")
		(net "SMB_E1S_3V3AUX_ISO_SCL_R")
	)
	(segment
		(start 221.90583 -44.160948)
		(end 221.27083 -43.525948)
		(width 0.12954)
		(layer "F.Cu")
		(net "SMB_E1S_3V3AUX_ISO_SCL_R")
	)
	(segment
		(start 218.360752 -43.413172)
		(end 218.374976 -43.398948)
		(width 0.12954)
		(layer "F.Cu")
		(net "SMB_E1S_3V3AUX_ISO_SCL_R")
	)
	(segment
		(start 222.940626 -44.160948)
		(end 221.90583 -44.160948)
		(width 0.12954)
		(layer "F.Cu")
		(net "SMB_E1S_3V3AUX_ISO_SCL_R")
	)
	(segment
		(start 221.14383 -43.398948)
		(end 221.27083 -43.525948)
		(width 0.12954)
		(layer "F.Cu")
		(net "SMB_E1S_3V3AUX_ISO_SCL_R")
	)
	(segment
		(start 218.374976 -43.398948)
		(end 220.01988 -43.398948)
		(width 0.12954)
		(layer "F.Cu")
		(net "SMB_E1S_3V3AUX_ISO_SCL_R")
	)
	(segment
		(start 220.01988 -43.398948)
		(end 221.14383 -43.398948)
		(width 0.12954)
		(layer "F.Cu")
		(net "SMB_E1S_3V3AUX_ISO_SCL_R")
	)
	(via
		(at 220.01988 -43.398948)
		(size 0.762)
		(drill 0.381)
		(layers "F.Cu" "B.Cu")
		(net "SMB_E1S_3V3AUX_ISO_SCL_R")
	)
	(segment
		(start 234.2134 -46.174914)
		(end 233.44886 -46.174914)
		(width 0.12954)
		(layer "F.Cu")
		(net "SMB_E1S_3V3AUX_ISO_SCL")
	)
	(segment
		(start 233.44886 -46.174914)
		(end 233.438954 -46.165008)
		(width 0.12954)
		(layer "F.Cu")
		(net "SMB_E1S_3V3AUX_ISO_SCL")
	)
	(segment
		(start 233.438954 -46.165008)
		(end 232.000044 -46.165008)
		(width 0.12954)
		(layer "F.Cu")
		(net "SMB_E1S_3V3AUX_ISO_SCL")
	)
	(segment
		(start 224.10293 -43.525948)
		(end 225.43008 -43.525948)
		(width 0.12954)
		(layer "F.Cu")
		(net "SMB_E1S_3V3AUX_ISO_SCL")
	)
	(via
		(at 225.43008 -43.525948)
		(size 0.508)
		(drill 0.254)
		(layers "F.Cu" "B.Cu")
		(net "SMB_E1S_3V3AUX_ISO_SCL")
	)
	(via
		(at 234.2134 -46.174914)
		(size 0.508)
		(drill 0.254)
		(layers "F.Cu" "B.Cu")
		(net "SMB_E1S_3V3AUX_ISO_SCL")
	)
	(segment
		(start 230.030782 -46.984666)
		(end 227.174298 -46.984666)
		(width 0.12954)
		(layer "B.Cu")
		(net "SMB_E1S_3V3AUX_ISO_SCL")
	)
	(segment
		(start 226.10318 -44.199048)
		(end 225.43008 -43.525948)
		(width 0.12954)
		(layer "B.Cu")
		(net "SMB_E1S_3V3AUX_ISO_SCL")
	)
	(segment
		(start 230.840534 -46.174914)
		(end 230.030782 -46.984666)
		(width 0.12954)
		(layer "B.Cu")
		(net "SMB_E1S_3V3AUX_ISO_SCL")
	)
	(segment
		(start 234.2134 -46.174914)
		(end 230.840534 -46.174914)
		(width 0.12954)
		(layer "B.Cu")
		(net "SMB_E1S_3V3AUX_ISO_SCL")
	)
	(segment
		(start 226.10318 -45.913548)
		(end 226.10318 -44.199048)
		(width 0.12954)
		(layer "B.Cu")
		(net "SMB_E1S_3V3AUX_ISO_SCL")
	)
	(segment
		(start 227.174298 -46.984666)
		(end 226.10318 -45.913548)
		(width 0.12954)
		(layer "B.Cu")
		(net "SMB_E1S_3V3AUX_ISO_SCL")
	)
	(segment
		(start 154.792426 -65.41135)
		(end 155.257754 -65.41135)
		(width 0.12954)
		(layer "F.Cu")
		(net "RST_SMB_E1S_N")
	)
	(segment
		(start 155.456636 -64.313308)
		(end 155.254706 -64.111378)
		(width 0.12954)
		(layer "F.Cu")
		(net "RST_SMB_E1S_N")
	)
	(segment
		(start 155.254706 -64.111378)
		(end 154.792426 -64.111378)
		(width 0.12954)
		(layer "F.Cu")
		(net "RST_SMB_E1S_N")
	)
	(segment
		(start 155.456636 -65.212468)
		(end 155.456636 -64.313308)
		(width 0.12954)
		(layer "F.Cu")
		(net "RST_SMB_E1S_N")
	)
	(segment
		(start 152.244806 -65.413128)
		(end 153.47442 -65.413128)
		(width 0.12954)
		(layer "F.Cu")
		(net "RST_SMB_E1S_N")
	)
	(segment
		(start 153.47442 -65.413128)
		(end 154.790648 -65.413128)
		(width 0.12954)
		(layer "F.Cu")
		(net "RST_SMB_E1S_N")
	)
	(segment
		(start 155.257754 -65.41135)
		(end 155.456636 -65.212468)
		(width 0.12954)
		(layer "F.Cu")
		(net "RST_SMB_E1S_N")
	)
	(segment
		(start 154.790648 -65.413128)
		(end 154.792426 -65.41135)
		(width 0.12954)
		(layer "F.Cu")
		(net "RST_SMB_E1S_N")
	)
	(via
		(at 153.47442 -65.413128)
		(size 0.762)
		(drill 0.381)
		(layers "F.Cu" "B.Cu")
		(net "RST_SMB_E1S_N")
	)
	(segment
		(start 157.960822 -65.79362)
		(end 158.25851 -66.091308)
		(width 0.12954)
		(layer "F.Cu")
		(net "RST_SMB_BUF_E1S_0_N")
	)
	(segment
		(start 156.692346 -65.41135)
		(end 157.578552 -65.41135)
		(width 0.12954)
		(layer "F.Cu")
		(net "RST_SMB_BUF_E1S_0_N")
	)
	(segment
		(start 157.578552 -65.41135)
		(end 157.960822 -65.79362)
		(width 0.12954)
		(layer "F.Cu")
		(net "RST_SMB_BUF_E1S_0_N")
	)
	(segment
		(start 158.25851 -66.091308)
		(end 159.255206 -66.091308)
		(width 0.12954)
		(layer "F.Cu")
		(net "RST_SMB_BUF_E1S_0_N")
	)
	(via
		(at 157.960822 -65.79362)
		(size 0.762)
		(drill 0.381)
		(layers "F.Cu" "B.Cu")
		(net "RST_SMB_BUF_E1S_0_N")
	)
	(segment
		(start 239.58804 -47.968408)
		(end 238.86414 -47.968408)
		(width 0.12954)
		(layer "F.Cu")
		(net "RST_PCIE_PCH_E1S_PERST_N")
	)
	(segment
		(start 238.86414 -47.968408)
		(end 236.603286 -47.968408)
		(width 0.12954)
		(layer "F.Cu")
		(net "RST_PCIE_PCH_E1S_PERST_N")
	)
	(segment
		(start 236.603286 -47.968408)
		(end 236.59973 -47.964852)
		(width 0.12954)
		(layer "F.Cu")
		(net "RST_PCIE_PCH_E1S_PERST_N")
	)
	(segment
		(start 236.59973 -47.964852)
		(end 236.599984 -47.964852)
		(width 0.12954)
		(layer "F.Cu")
		(net "RST_PCIE_PCH_E1S_PERST_N")
	)
	(via
		(at 238.86414 -47.968408)
		(size 0.508)
		(drill 0.254)
		(layers "F.Cu" "B.Cu")
		(net "RST_PCIE_PCH_E1S_PERST_N")
	)
	(segment
		(start 205.33741 -120.614948)
		(end 205.94701 -120.614948)
		(width 0.12954)
		(layer "F.Cu")
		(net "RST_PCIE_PCH_DEV_PERST_E1S_R_N")
	)
	(segment
		(start 240.38814 -48.178466)
		(end 240.38814 -47.968408)
		(width 0.12954)
		(layer "F.Cu")
		(net "RST_PCIE_PCH_DEV_PERST_E1S_R_N")
	)
	(segment
		(start 241.1857 -48.976026)
		(end 240.38814 -48.178466)
		(width 0.12954)
		(layer "F.Cu")
		(net "RST_PCIE_PCH_DEV_PERST_E1S_R_N")
	)
	(via
		(at 195.99402 -65.557908)
		(size 0.508)
		(drill 0.254)
		(layers "F.Cu" "B.Cu")
		(net "RST_PCIE_PCH_DEV_PERST_E1S_R_N")
	)
	(via
		(at 205.94701 -120.614948)
		(size 0.508)
		(drill 0.254)
		(layers "F.Cu" "B.Cu")
		(net "RST_PCIE_PCH_DEV_PERST_E1S_R_N")
	)
	(via
		(at 241.1857 -48.976026)
		(size 0.508)
		(drill 0.254)
		(layers "F.Cu" "B.Cu")
		(net "RST_PCIE_PCH_DEV_PERST_E1S_R_N")
	)
	(segment
		(start 199.0344 -98.298)
		(end 201.51598 -100.77958)
		(width 0.127)
		(layer "In4.Cu")
		(net "RST_PCIE_PCH_DEV_PERST_E1S_R_N")
	)
	(segment
		(start 205.69428 -108.67263)
		(end 205.69428 -112.71885)
		(width 0.127)
		(layer "In4.Cu")
		(net "RST_PCIE_PCH_DEV_PERST_E1S_R_N")
	)
	(segment
		(start 192.76314 -93.41485)
		(end 197.64629 -98.298)
		(width 0.127)
		(layer "In4.Cu")
		(net "RST_PCIE_PCH_DEV_PERST_E1S_R_N")
	)
	(segment
		(start 197.64629 -98.298)
		(end 199.0344 -98.298)
		(width 0.127)
		(layer "In4.Cu")
		(net "RST_PCIE_PCH_DEV_PERST_E1S_R_N")
	)
	(segment
		(start 201.51598 -100.77958)
		(end 201.51598 -104.49433)
		(width 0.127)
		(layer "In4.Cu")
		(net "RST_PCIE_PCH_DEV_PERST_E1S_R_N")
	)
	(segment
		(start 192.76314 -84.2899)
		(end 192.76314 -93.41485)
		(width 0.127)
		(layer "In4.Cu")
		(net "RST_PCIE_PCH_DEV_PERST_E1S_R_N")
	)
	(segment
		(start 195.99402 -67.828668)
		(end 194.6656 -69.157088)
		(width 0.127)
		(layer "In4.Cu")
		(net "RST_PCIE_PCH_DEV_PERST_E1S_R_N")
	)
	(segment
		(start 188.93536 -70.592188)
		(end 188.93536 -74.831448)
		(width 0.127)
		(layer "In4.Cu")
		(net "RST_PCIE_PCH_DEV_PERST_E1S_R_N")
	)
	(segment
		(start 206.8957 -119.74449)
		(end 206.025242 -120.614948)
		(width 0.127)
		(layer "In4.Cu")
		(net "RST_PCIE_PCH_DEV_PERST_E1S_R_N")
	)
	(segment
		(start 191.14516 -77.041248)
		(end 191.14516 -82.67192)
		(width 0.127)
		(layer "In4.Cu")
		(net "RST_PCIE_PCH_DEV_PERST_E1S_R_N")
	)
	(segment
		(start 188.93536 -74.831448)
		(end 191.14516 -77.041248)
		(width 0.127)
		(layer "In4.Cu")
		(net "RST_PCIE_PCH_DEV_PERST_E1S_R_N")
	)
	(segment
		(start 205.69428 -112.71885)
		(end 206.8957 -113.92027)
		(width 0.127)
		(layer "In4.Cu")
		(net "RST_PCIE_PCH_DEV_PERST_E1S_R_N")
	)
	(segment
		(start 206.025242 -120.614948)
		(end 205.94701 -120.614948)
		(width 0.127)
		(layer "In4.Cu")
		(net "RST_PCIE_PCH_DEV_PERST_E1S_R_N")
	)
	(segment
		(start 195.99402 -65.557908)
		(end 195.99402 -67.828668)
		(width 0.127)
		(layer "In4.Cu")
		(net "RST_PCIE_PCH_DEV_PERST_E1S_R_N")
	)
	(segment
		(start 194.6656 -69.157088)
		(end 190.37046 -69.157088)
		(width 0.127)
		(layer "In4.Cu")
		(net "RST_PCIE_PCH_DEV_PERST_E1S_R_N")
	)
	(segment
		(start 206.8957 -113.92027)
		(end 206.8957 -119.74449)
		(width 0.127)
		(layer "In4.Cu")
		(net "RST_PCIE_PCH_DEV_PERST_E1S_R_N")
	)
	(segment
		(start 201.51598 -104.49433)
		(end 205.69428 -108.67263)
		(width 0.127)
		(layer "In4.Cu")
		(net "RST_PCIE_PCH_DEV_PERST_E1S_R_N")
	)
	(segment
		(start 190.37046 -69.157088)
		(end 188.93536 -70.592188)
		(width 0.127)
		(layer "In4.Cu")
		(net "RST_PCIE_PCH_DEV_PERST_E1S_R_N")
	)
	(segment
		(start 191.14516 -82.67192)
		(end 192.76314 -84.2899)
		(width 0.127)
		(layer "In4.Cu")
		(net "RST_PCIE_PCH_DEV_PERST_E1S_R_N")
	)
	(segment
		(start 239.11306 -63.713868)
		(end 238.13008 -64.696848)
		(width 0.127)
		(layer "In11.Cu")
		(net "RST_PCIE_PCH_DEV_PERST_E1S_R_N")
	)
	(segment
		(start 196.85508 -64.696848)
		(end 195.99402 -65.557908)
		(width 0.127)
		(layer "In11.Cu")
		(net "RST_PCIE_PCH_DEV_PERST_E1S_R_N")
	)
	(segment
		(start 241.967766 -49.436782)
		(end 241.967766 -50.454306)
		(width 0.127)
		(layer "In11.Cu")
		(net "RST_PCIE_PCH_DEV_PERST_E1S_R_N")
	)
	(segment
		(start 241.967766 -50.454306)
		(end 239.11306 -53.309012)
		(width 0.127)
		(layer "In11.Cu")
		(net "RST_PCIE_PCH_DEV_PERST_E1S_R_N")
	)
	(segment
		(start 241.50701 -48.976026)
		(end 241.967766 -49.436782)
		(width 0.127)
		(layer "In11.Cu")
		(net "RST_PCIE_PCH_DEV_PERST_E1S_R_N")
	)
	(segment
		(start 241.1857 -48.976026)
		(end 241.50701 -48.976026)
		(width 0.127)
		(layer "In11.Cu")
		(net "RST_PCIE_PCH_DEV_PERST_E1S_R_N")
	)
	(segment
		(start 239.11306 -53.309012)
		(end 239.11306 -63.713868)
		(width 0.127)
		(layer "In11.Cu")
		(net "RST_PCIE_PCH_DEV_PERST_E1S_R_N")
	)
	(segment
		(start 238.13008 -64.696848)
		(end 196.85508 -64.696848)
		(width 0.127)
		(layer "In11.Cu")
		(net "RST_PCIE_PCH_DEV_PERST_E1S_R_N")
	)
	(segment
		(start 140.708126 -40.503348)
		(end 140.09243 -40.503348)
		(width 0.12954)
		(layer "F.Cu")
		(net "RST_PCIE_PCH_DEV_BUF_M2_0_PERST")
	)
	(segment
		(start 137.85088 -40.985948)
		(end 137.64641 -41.190418)
		(width 0.12954)
		(layer "F.Cu")
		(net "RST_PCIE_PCH_DEV_BUF_M2_0_PERST")
	)
	(segment
		(start 140.09243 -40.503348)
		(end 139.60983 -40.985948)
		(width 0.12954)
		(layer "F.Cu")
		(net "RST_PCIE_PCH_DEV_BUF_M2_0_PERST")
	)
	(segment
		(start 138.38428 -40.985948)
		(end 137.85088 -40.985948)
		(width 0.12954)
		(layer "F.Cu")
		(net "RST_PCIE_PCH_DEV_BUF_M2_0_PERST")
	)
	(segment
		(start 139.60983 -40.985948)
		(end 138.38428 -40.985948)
		(width 0.12954)
		(layer "F.Cu")
		(net "RST_PCIE_PCH_DEV_BUF_M2_0_PERST")
	)
	(segment
		(start 141.190726 -40.985948)
		(end 140.708126 -40.503348)
		(width 0.12954)
		(layer "F.Cu")
		(net "RST_PCIE_PCH_DEV_BUF_M2_0_PERST")
	)
	(segment
		(start 142.02283 -40.985948)
		(end 141.190726 -40.985948)
		(width 0.12954)
		(layer "F.Cu")
		(net "RST_PCIE_PCH_DEV_BUF_M2_0_PERST")
	)
	(segment
		(start 137.64641 -41.190418)
		(end 136.868408 -41.190418)
		(width 0.12954)
		(layer "F.Cu")
		(net "RST_PCIE_PCH_DEV_BUF_M2_0_PERST")
	)
	(via
		(at 138.38428 -40.985948)
		(size 0.762)
		(drill 0.381)
		(layers "F.Cu" "B.Cu")
		(net "RST_PCIE_PCH_DEV_BUF_M2_0_PERST")
	)
	(segment
		(start 128.7018 -136.413748)
		(end 128.001522 -137.114026)
		(width 0.12954)
		(layer "F.Cu")
		(net "PCA9548_PCIE3_ADDR2")
	)
	(segment
		(start 127.167386 -137.114026)
		(end 128.001522 -137.114026)
		(width 0.12954)
		(layer "F.Cu")
		(net "PCA9548_PCIE3_ADDR2")
	)
	(segment
		(start 123.708668 -135.59663)
		(end 124.91339 -135.59663)
		(width 0.12954)
		(layer "F.Cu")
		(net "PCA9548_PCIE3_ADDR2")
	)
	(segment
		(start 131.066794 -137.114026)
		(end 131.032758 -137.114026)
		(width 0.12954)
		(layer "F.Cu")
		(net "PCA9548_PCIE3_ADDR2")
	)
	(segment
		(start 126.777242 -136.723882)
		(end 127.167386 -137.114026)
		(width 0.12954)
		(layer "F.Cu")
		(net "PCA9548_PCIE3_ADDR2")
	)
	(segment
		(start 126.040642 -136.723882)
		(end 126.777242 -136.723882)
		(width 0.12954)
		(layer "F.Cu")
		(net "PCA9548_PCIE3_ADDR2")
	)
	(segment
		(start 130.33248 -136.413748)
		(end 128.7018 -136.413748)
		(width 0.12954)
		(layer "F.Cu")
		(net "PCA9548_PCIE3_ADDR2")
	)
	(segment
		(start 124.91339 -135.59663)
		(end 126.040642 -136.723882)
		(width 0.12954)
		(layer "F.Cu")
		(net "PCA9548_PCIE3_ADDR2")
	)
	(segment
		(start 131.032758 -137.114026)
		(end 130.33248 -136.413748)
		(width 0.12954)
		(layer "F.Cu")
		(net "PCA9548_PCIE3_ADDR2")
	)
	(via
		(at 126.777242 -136.723882)
		(size 0.762)
		(drill 0.381)
		(layers "F.Cu" "B.Cu")
		(net "PCA9548_PCIE3_ADDR2")
	)
	(segment
		(start 116.185442 -138.150346)
		(end 117.439186 -136.896602)
		(width 0.12954)
		(layer "F.Cu")
		(net "PCA9548_PCIE3_ADDR1")
	)
	(segment
		(start 114.244882 -138.150346)
		(end 116.185442 -138.150346)
		(width 0.12954)
		(layer "F.Cu")
		(net "PCA9548_PCIE3_ADDR1")
	)
	(segment
		(start 113.260886 -138.433302)
		(end 113.894362 -137.799826)
		(width 0.12954)
		(layer "F.Cu")
		(net "PCA9548_PCIE3_ADDR1")
	)
	(segment
		(start 112.432846 -138.433302)
		(end 113.260886 -138.433302)
		(width 0.12954)
		(layer "F.Cu")
		(net "PCA9548_PCIE3_ADDR1")
	)
	(segment
		(start 111.732822 -139.133326)
		(end 112.432846 -138.433302)
		(width 0.12954)
		(layer "F.Cu")
		(net "PCA9548_PCIE3_ADDR1")
	)
	(segment
		(start 113.894362 -137.799826)
		(end 114.244882 -138.150346)
		(width 0.12954)
		(layer "F.Cu")
		(net "PCA9548_PCIE3_ADDR1")
	)
	(segment
		(start 117.439186 -136.896602)
		(end 118.108476 -136.896602)
		(width 0.12954)
		(layer "F.Cu")
		(net "PCA9548_PCIE3_ADDR1")
	)
	(via
		(at 116.185442 -138.150346)
		(size 0.762)
		(drill 0.381)
		(layers "F.Cu" "B.Cu")
		(net "PCA9548_PCIE3_ADDR1")
	)
	(segment
		(start 117.074442 -138.425682)
		(end 117.074442 -137.917682)
		(width 0.12954)
		(layer "F.Cu")
		(net "PCA9548_PCIE3_ADDR0")
	)
	(segment
		(start 117.074442 -137.917682)
		(end 117.445536 -137.546588)
		(width 0.12954)
		(layer "F.Cu")
		(net "PCA9548_PCIE3_ADDR0")
	)
	(segment
		(start 116.430298 -139.069826)
		(end 117.074442 -138.425682)
		(width 0.12954)
		(layer "F.Cu")
		(net "PCA9548_PCIE3_ADDR0")
	)
	(segment
		(start 113.894362 -139.069826)
		(end 115.169442 -139.069826)
		(width 0.12954)
		(layer "F.Cu")
		(net "PCA9548_PCIE3_ADDR0")
	)
	(segment
		(start 113.894362 -139.069826)
		(end 112.560862 -140.403326)
		(width 0.12954)
		(layer "F.Cu")
		(net "PCA9548_PCIE3_ADDR0")
	)
	(segment
		(start 117.445536 -137.546588)
		(end 118.108476 -137.546588)
		(width 0.12954)
		(layer "F.Cu")
		(net "PCA9548_PCIE3_ADDR0")
	)
	(segment
		(start 112.560862 -140.403326)
		(end 111.732822 -140.403326)
		(width 0.12954)
		(layer "F.Cu")
		(net "PCA9548_PCIE3_ADDR0")
	)
	(segment
		(start 115.169442 -139.069826)
		(end 116.430298 -139.069826)
		(width 0.12954)
		(layer "F.Cu")
		(net "PCA9548_PCIE3_ADDR0")
	)
	(via
		(at 115.169442 -139.069826)
		(size 0.762)
		(drill 0.381)
		(layers "F.Cu" "B.Cu")
		(net "PCA9548_PCIE3_ADDR0")
	)
	(segment
		(start 86.541356 -57.314846)
		(end 86.905846 -57.679336)
		(width 0.12954)
		(layer "F.Cu")
		(net "P3V3_OCP_VCC_2")
	)
	(segment
		(start 85.915246 -56.879236)
		(end 85.889846 -56.879236)
		(width 0.12954)
		(layer "F.Cu")
		(net "P3V3_OCP_VCC_2")
	)
	(segment
		(start 86.905846 -57.679336)
		(end 86.931246 -57.679336)
		(width 0.12954)
		(layer "F.Cu")
		(net "P3V3_OCP_VCC_2")
	)
	(segment
		(start 86.376256 -57.314846)
		(end 86.541356 -57.314846)
		(width 0.12954)
		(layer "F.Cu")
		(net "P3V3_OCP_VCC_2")
	)
	(segment
		(start 85.443314 -56.432704)
		(end 85.194648 -56.432704)
		(width 0.12954)
		(layer "F.Cu")
		(net "P3V3_OCP_VCC_2")
	)
	(segment
		(start 85.915246 -56.879236)
		(end 85.940646 -56.879236)
		(width 0.12954)
		(layer "F.Cu")
		(net "P3V3_OCP_VCC_2")
	)
	(segment
		(start 85.889846 -56.879236)
		(end 85.443314 -56.432704)
		(width 0.12954)
		(layer "F.Cu")
		(net "P3V3_OCP_VCC_2")
	)
	(segment
		(start 85.194648 -56.432704)
		(end 84.050632 -56.432704)
		(width 0.12954)
		(layer "F.Cu")
		(net "P3V3_OCP_VCC_2")
	)
	(segment
		(start 85.940646 -56.879236)
		(end 86.376256 -57.314846)
		(width 0.12954)
		(layer "F.Cu")
		(net "P3V3_OCP_VCC_2")
	)
	(via
		(at 85.194648 -56.432704)
		(size 0.508)
		(drill 0.254)
		(layers "F.Cu" "B.Cu")
		(net "P3V3_OCP_VCC_2")
	)
	(segment
		(start 433.722272 -106.77398)
		(end 433.27574 -106.327448)
		(width 0.12954)
		(layer "F.Cu")
		(net "P3V3_OCP_VCC_1")
	)
	(segment
		(start 435.169564 -106.77398)
		(end 435.177184 -106.76636)
		(width 0.12954)
		(layer "F.Cu")
		(net "P3V3_OCP_VCC_1")
	)
	(segment
		(start 433.27574 -106.327448)
		(end 432.579018 -106.327448)
		(width 0.12954)
		(layer "F.Cu")
		(net "P3V3_OCP_VCC_1")
	)
	(segment
		(start 434.443632 -106.77398)
		(end 433.722272 -106.77398)
		(width 0.12954)
		(layer "F.Cu")
		(net "P3V3_OCP_VCC_1")
	)
	(segment
		(start 434.443632 -106.77398)
		(end 435.169564 -106.77398)
		(width 0.12954)
		(layer "F.Cu")
		(net "P3V3_OCP_VCC_1")
	)
	(segment
		(start 435.177184 -106.76636)
		(end 435.597808 -106.76636)
		(width 0.12954)
		(layer "F.Cu")
		(net "P3V3_OCP_VCC_1")
	)
	(via
		(at 433.722272 -106.77398)
		(size 0.508)
		(drill 0.254)
		(layers "F.Cu" "B.Cu")
		(net "P3V3_OCP_VCC_1")
	)
	(segment
		(start 80.74152 -57.299352)
		(end 80.74152 -57.934606)
		(width 0.12954)
		(layer "F.Cu")
		(net "P3V3_OCP_UV_2")
	)
	(segment
		(start 81.208372 -56.8325)
		(end 80.74152 -57.299352)
		(width 0.12954)
		(layer "F.Cu")
		(net "P3V3_OCP_UV_2")
	)
	(segment
		(start 80.74152 -57.934606)
		(end 80.784446 -57.977532)
		(width 0.12954)
		(layer "F.Cu")
		(net "P3V3_OCP_UV_2")
	)
	(segment
		(start 82.550508 -56.432704)
		(end 81.608168 -56.432704)
		(width 0.12954)
		(layer "F.Cu")
		(net "P3V3_OCP_UV_2")
	)
	(segment
		(start 80.784446 -57.977532)
		(end 80.77073 -57.991248)
		(width 0.12954)
		(layer "F.Cu")
		(net "P3V3_OCP_UV_2")
	)
	(segment
		(start 80.77073 -57.991248)
		(end 80.77073 -58.972196)
		(width 0.12954)
		(layer "F.Cu")
		(net "P3V3_OCP_UV_2")
	)
	(segment
		(start 81.608168 -56.432704)
		(end 81.208372 -56.8325)
		(width 0.12954)
		(layer "F.Cu")
		(net "P3V3_OCP_UV_2")
	)
	(via
		(at 81.208372 -56.8325)
		(size 0.508)
		(drill 0.254)
		(layers "F.Cu" "B.Cu")
		(net "P3V3_OCP_UV_2")
	)
	(segment
		(start 81.208372 -56.8325)
		(end 80.812132 -57.22874)
		(width 0.12954)
		(layer "B.Cu")
		(net "P3V3_OCP_UV_2")
	)
	(segment
		(start 80.812132 -57.22874)
		(end 80.812132 -58.016648)
		(width 0.12954)
		(layer "B.Cu")
		(net "P3V3_OCP_UV_2")
	)
	(segment
		(start 460.58709 -39.48049)
		(end 460.58709 -40.352472)
		(width 0.12954)
		(layer "F.Cu")
		(net "P3V3_OCP_UV_1_R1")
	)
	(via
		(at 460.58709 -39.48049)
		(size 0.508)
		(drill 0.254)
		(layers "F.Cu" "B.Cu")
		(net "P3V3_OCP_UV_1_R1")
	)
	(via
		(at 443.75832 -110.71098)
		(size 0.508)
		(drill 0.254)
		(layers "F.Cu" "B.Cu")
		(net "P3V3_OCP_UV_1_R1")
	)
	(segment
		(start 443.75832 -110.71098)
		(end 430.175416 -110.71098)
		(width 0.12954)
		(layer "B.Cu")
		(net "P3V3_OCP_UV_1_R1")
	)
	(segment
		(start 429.83404 -110.369604)
		(end 429.83404 -110.119922)
		(width 0.12954)
		(layer "B.Cu")
		(net "P3V3_OCP_UV_1_R1")
	)
	(segment
		(start 430.175416 -110.71098)
		(end 429.83404 -110.369604)
		(width 0.12954)
		(layer "B.Cu")
		(net "P3V3_OCP_UV_1_R1")
	)
	(segment
		(start 429.83404 -110.119922)
		(end 429.40224 -109.688122)
		(width 0.12954)
		(layer "B.Cu")
		(net "P3V3_OCP_UV_1_R1")
	)
	(segment
		(start 429.40224 -109.688122)
		(end 429.40224 -109.267498)
		(width 0.12954)
		(layer "B.Cu")
		(net "P3V3_OCP_UV_1_R1")
	)
	(segment
		(start 462.6356 -41.529)
		(end 464.0326 -41.529)
		(width 0.127)
		(layer "In2.Cu")
		(net "P3V3_OCP_UV_1_R1")
	)
	(segment
		(start 465.6201 -49.2379)
		(end 470.027 -53.6448)
		(width 0.127)
		(layer "In2.Cu")
		(net "P3V3_OCP_UV_1_R1")
	)
	(segment
		(start 470.027 -53.6448)
		(end 470.027 -78.1558)
		(width 0.127)
		(layer "In2.Cu")
		(net "P3V3_OCP_UV_1_R1")
	)
	(segment
		(start 464.4898 -95.6818)
		(end 464.4898 -101.3714)
		(width 0.127)
		(layer "In2.Cu")
		(net "P3V3_OCP_UV_1_R1")
	)
	(segment
		(start 460.58709 -39.48049)
		(end 462.6356 -41.529)
		(width 0.127)
		(layer "In2.Cu")
		(net "P3V3_OCP_UV_1_R1")
	)
	(segment
		(start 464.4898 -101.3714)
		(end 463.3976 -102.4636)
		(width 0.127)
		(layer "In2.Cu")
		(net "P3V3_OCP_UV_1_R1")
	)
	(segment
		(start 465.6201 -44.8437)
		(end 465.6201 -49.2379)
		(width 0.127)
		(layer "In2.Cu")
		(net "P3V3_OCP_UV_1_R1")
	)
	(segment
		(start 445.26962 -110.71098)
		(end 443.75832 -110.71098)
		(width 0.127)
		(layer "In2.Cu")
		(net "P3V3_OCP_UV_1_R1")
	)
	(segment
		(start 463.3976 -102.4636)
		(end 463.3976 -105.8418)
		(width 0.127)
		(layer "In2.Cu")
		(net "P3V3_OCP_UV_1_R1")
	)
	(segment
		(start 465.963 -43.4594)
		(end 465.963 -44.5008)
		(width 0.127)
		(layer "In2.Cu")
		(net "P3V3_OCP_UV_1_R1")
	)
	(segment
		(start 456.819 -109.982)
		(end 445.9986 -109.982)
		(width 0.127)
		(layer "In2.Cu")
		(net "P3V3_OCP_UV_1_R1")
	)
	(segment
		(start 445.9986 -109.982)
		(end 445.26962 -110.71098)
		(width 0.127)
		(layer "In2.Cu")
		(net "P3V3_OCP_UV_1_R1")
	)
	(segment
		(start 463.3976 -105.8418)
		(end 462.9404 -106.299)
		(width 0.127)
		(layer "In2.Cu")
		(net "P3V3_OCP_UV_1_R1")
	)
	(segment
		(start 465.963 -44.5008)
		(end 465.6201 -44.8437)
		(width 0.127)
		(layer "In2.Cu")
		(net "P3V3_OCP_UV_1_R1")
	)
	(segment
		(start 470.027 -78.1558)
		(end 466.344 -81.8388)
		(width 0.127)
		(layer "In2.Cu")
		(net "P3V3_OCP_UV_1_R1")
	)
	(segment
		(start 464.0326 -41.529)
		(end 465.963 -43.4594)
		(width 0.127)
		(layer "In2.Cu")
		(net "P3V3_OCP_UV_1_R1")
	)
	(segment
		(start 466.344 -81.8388)
		(end 466.344 -93.8276)
		(width 0.127)
		(layer "In2.Cu")
		(net "P3V3_OCP_UV_1_R1")
	)
	(segment
		(start 460.502 -106.299)
		(end 456.819 -109.982)
		(width 0.127)
		(layer "In2.Cu")
		(net "P3V3_OCP_UV_1_R1")
	)
	(segment
		(start 462.9404 -106.299)
		(end 460.502 -106.299)
		(width 0.127)
		(layer "In2.Cu")
		(net "P3V3_OCP_UV_1_R1")
	)
	(segment
		(start 466.344 -93.8276)
		(end 464.4898 -95.6818)
		(width 0.127)
		(layer "In2.Cu")
		(net "P3V3_OCP_UV_1_R1")
	)
	(segment
		(start 429.312832 -107.872276)
		(end 429.312832 -107.15117)
		(width 0.12954)
		(layer "F.Cu")
		(net "P3V3_OCP_UV_1")
	)
	(segment
		(start 430.136554 -106.327448)
		(end 431.078894 -106.327448)
		(width 0.12954)
		(layer "F.Cu")
		(net "P3V3_OCP_UV_1")
	)
	(segment
		(start 429.312832 -107.15117)
		(end 430.136554 -106.327448)
		(width 0.12954)
		(layer "F.Cu")
		(net "P3V3_OCP_UV_1")
	)
	(segment
		(start 429.312832 -108.853224)
		(end 429.299116 -108.86694)
		(width 0.12954)
		(layer "F.Cu")
		(net "P3V3_OCP_UV_1")
	)
	(segment
		(start 429.312832 -107.872276)
		(end 429.312832 -108.853224)
		(width 0.12954)
		(layer "F.Cu")
		(net "P3V3_OCP_UV_1")
	)
	(via
		(at 429.312832 -107.15117)
		(size 0.508)
		(drill 0.254)
		(layers "F.Cu" "B.Cu")
		(net "P3V3_OCP_UV_1")
	)
	(segment
		(start 429.40224 -108.04652)
		(end 429.40224 -108.467398)
		(width 0.12954)
		(layer "B.Cu")
		(net "P3V3_OCP_UV_1")
	)
	(segment
		(start 429.312832 -107.597194)
		(end 429.298354 -107.611672)
		(width 0.12954)
		(layer "B.Cu")
		(net "P3V3_OCP_UV_1")
	)
	(segment
		(start 429.312832 -107.15117)
		(end 429.312832 -107.597194)
		(width 0.12954)
		(layer "B.Cu")
		(net "P3V3_OCP_UV_1")
	)
	(segment
		(start 429.298354 -107.942634)
		(end 429.40224 -108.04652)
		(width 0.12954)
		(layer "B.Cu")
		(net "P3V3_OCP_UV_1")
	)
	(segment
		(start 429.298354 -107.611672)
		(end 429.298354 -107.942634)
		(width 0.12954)
		(layer "B.Cu")
		(net "P3V3_OCP_UV_1")
	)
	(segment
		(start 84.486242 -58.882788)
		(end 84.44611 -58.842656)
		(width 0.12954)
		(layer "F.Cu")
		(net "P3V3_OCP_SENSE_2")
	)
	(segment
		(start 85.18779 -59.768486)
		(end 85.15604 -59.736736)
		(width 0.12954)
		(layer "F.Cu")
		(net "P3V3_OCP_SENSE_2")
	)
	(segment
		(start 85.15604 -59.06516)
		(end 84.973668 -58.882788)
		(width 0.12954)
		(layer "F.Cu")
		(net "P3V3_OCP_SENSE_2")
	)
	(segment
		(start 84.050632 -56.93283)
		(end 84.44611 -57.328308)
		(width 0.12954)
		(layer "F.Cu")
		(net "P3V3_OCP_SENSE_2")
	)
	(segment
		(start 84.44611 -57.328308)
		(end 84.44611 -58.842656)
		(width 0.12954)
		(layer "F.Cu")
		(net "P3V3_OCP_SENSE_2")
	)
	(segment
		(start 84.973668 -58.882788)
		(end 84.486242 -58.882788)
		(width 0.12954)
		(layer "F.Cu")
		(net "P3V3_OCP_SENSE_2")
	)
	(segment
		(start 85.15604 -59.736736)
		(end 85.15604 -59.06516)
		(width 0.12954)
		(layer "F.Cu")
		(net "P3V3_OCP_SENSE_2")
	)
	(via
		(at 85.18779 -59.768486)
		(size 0.508)
		(drill 0.254)
		(layers "F.Cu" "B.Cu")
		(net "P3V3_OCP_SENSE_2")
	)
	(segment
		(start 432.579018 -106.827574)
		(end 432.974496 -107.223052)
		(width 0.12954)
		(layer "F.Cu")
		(net "P3V3_OCP_SENSE_1")
	)
	(segment
		(start 433.716176 -109.66323)
		(end 433.716176 -108.991654)
		(width 0.254)
		(layer "F.Cu")
		(net "P3V3_OCP_SENSE_1")
	)
	(segment
		(start 433.461922 -108.7374)
		(end 432.974496 -108.7374)
		(width 0.254)
		(layer "F.Cu")
		(net "P3V3_OCP_SENSE_1")
	)
	(segment
		(start 432.974496 -107.223052)
		(end 432.974496 -108.7374)
		(width 0.12954)
		(layer "F.Cu")
		(net "P3V3_OCP_SENSE_1")
	)
	(segment
		(start 433.716176 -108.991654)
		(end 433.461922 -108.7374)
		(width 0.254)
		(layer "F.Cu")
		(net "P3V3_OCP_SENSE_1")
	)
	(via
		(at 433.716176 -109.66323)
		(size 0.508)
		(drill 0.254)
		(layers "F.Cu" "B.Cu")
		(net "P3V3_OCP_SENSE_1")
	)
	(segment
		(start 81.955132 -57.530238)
		(end 81.955132 -58.230516)
		(width 0.12954)
		(layer "F.Cu")
		(net "P3V3_OCP_REG_2")
	)
	(segment
		(start 82.550508 -56.934862)
		(end 81.955132 -57.530238)
		(width 0.12954)
		(layer "F.Cu")
		(net "P3V3_OCP_REG_2")
	)
	(segment
		(start 81.955132 -58.836814)
		(end 81.82737 -58.964576)
		(width 0.12954)
		(layer "F.Cu")
		(net "P3V3_OCP_REG_2")
	)
	(segment
		(start 81.955132 -58.230516)
		(end 81.955132 -58.836814)
		(width 0.12954)
		(layer "F.Cu")
		(net "P3V3_OCP_REG_2")
	)
	(segment
		(start 82.550508 -56.93283)
		(end 82.550508 -56.934862)
		(width 0.12954)
		(layer "F.Cu")
		(net "P3V3_OCP_REG_2")
	)
	(via
		(at 81.955132 -58.230516)
		(size 0.508)
		(drill 0.254)
		(layers "F.Cu" "B.Cu")
		(net "P3V3_OCP_REG_2")
	)
	(segment
		(start 430.64557 -107.260898)
		(end 430.355756 -107.550712)
		(width 0.12954)
		(layer "F.Cu")
		(net "P3V3_OCP_REG_1")
	)
	(segment
		(start 430.355756 -107.550712)
		(end 430.355756 -108.85932)
		(width 0.12954)
		(layer "F.Cu")
		(net "P3V3_OCP_REG_1")
	)
	(segment
		(start 431.078894 -106.827574)
		(end 430.64557 -107.260898)
		(width 0.12954)
		(layer "F.Cu")
		(net "P3V3_OCP_REG_1")
	)
	(via
		(at 430.64557 -107.260898)
		(size 0.508)
		(drill 0.254)
		(layers "F.Cu" "B.Cu")
		(net "P3V3_OCP_REG_1")
	)
	(segment
		(start 82.550508 -53.932582)
		(end 82.121756 -53.50383)
		(width 0.12954)
		(layer "F.Cu")
		(net "P3V3_OCP_PWRGD_2")
	)
	(via
		(at 82.121756 -53.50383)
		(size 0.508)
		(drill 0.254)
		(layers "F.Cu" "B.Cu")
		(net "P3V3_OCP_PWRGD_2")
	)
	(segment
		(start 82.121756 -53.50383)
		(end 80.972914 -53.50383)
		(width 0.12954)
		(layer "B.Cu")
		(net "P3V3_OCP_PWRGD_2")
	)
	(segment
		(start 80.972914 -53.50383)
		(end 80.35163 -52.882546)
		(width 0.12954)
		(layer "B.Cu")
		(net "P3V3_OCP_PWRGD_2")
	)
	(segment
		(start 431.078894 -103.827326)
		(end 431.078894 -103.276908)
		(width 0.12954)
		(layer "F.Cu")
		(net "P3V3_OCP_PWRGD_1")
	)
	(segment
		(start 429.5013 -103.398574)
		(end 428.880016 -102.77729)
		(width 0.12954)
		(layer "F.Cu")
		(net "P3V3_OCP_PWRGD_1")
	)
	(segment
		(start 431.078894 -103.276908)
		(end 430.957228 -103.398574)
		(width 0.12954)
		(layer "F.Cu")
		(net "P3V3_OCP_PWRGD_1")
	)
	(segment
		(start 430.957228 -103.398574)
		(end 429.5013 -103.398574)
		(width 0.12954)
		(layer "F.Cu")
		(net "P3V3_OCP_PWRGD_1")
	)
	(via
		(at 431.078894 -103.276908)
		(size 0.508)
		(drill 0.254)
		(layers "F.Cu" "B.Cu")
		(net "P3V3_OCP_PWRGD_1")
	)
	(segment
		(start 79.984346 -58.002932)
		(end 79.75473 -58.232548)
		(width 0.12954)
		(layer "F.Cu")
		(net "P3V3_OCP_OV_2")
	)
	(segment
		(start 79.984346 -57.977532)
		(end 79.984346 -56.896508)
		(width 0.12954)
		(layer "F.Cu")
		(net "P3V3_OCP_OV_2")
	)
	(segment
		(start 79.819246 -56.713628)
		(end 80.600296 -55.932578)
		(width 0.12954)
		(layer "F.Cu")
		(net "P3V3_OCP_OV_2")
	)
	(segment
		(start 79.819246 -56.731408)
		(end 79.819246 -56.713628)
		(width 0.12954)
		(layer "F.Cu")
		(net "P3V3_OCP_OV_2")
	)
	(segment
		(start 80.600296 -55.932578)
		(end 82.550508 -55.932578)
		(width 0.12954)
		(layer "F.Cu")
		(net "P3V3_OCP_OV_2")
	)
	(segment
		(start 79.984346 -57.977532)
		(end 79.984346 -58.002932)
		(width 0.12954)
		(layer "F.Cu")
		(net "P3V3_OCP_OV_2")
	)
	(segment
		(start 79.984346 -56.896508)
		(end 79.819246 -56.731408)
		(width 0.12954)
		(layer "F.Cu")
		(net "P3V3_OCP_OV_2")
	)
	(segment
		(start 79.75473 -58.232548)
		(end 79.75473 -58.972196)
		(width 0.12954)
		(layer "F.Cu")
		(net "P3V3_OCP_OV_2")
	)
	(via
		(at 79.819246 -56.731408)
		(size 0.762)
		(drill 0.381)
		(layers "F.Cu" "B.Cu")
		(net "P3V3_OCP_OV_2")
	)
	(segment
		(start 431.078894 -105.827322)
		(end 430.2887 -105.827322)
		(width 0.12954)
		(layer "F.Cu")
		(net "P3V3_OCP_OV_1")
	)
	(segment
		(start 428.518066 -107.866942)
		(end 428.512732 -107.872276)
		(width 0.12954)
		(layer "F.Cu")
		(net "P3V3_OCP_OV_1")
	)
	(segment
		(start 428.518066 -106.906822)
		(end 428.518066 -107.866942)
		(width 0.12954)
		(layer "F.Cu")
		(net "P3V3_OCP_OV_1")
	)
	(segment
		(start 428.518066 -107.87761)
		(end 428.518066 -108.63199)
		(width 0.12954)
		(layer "F.Cu")
		(net "P3V3_OCP_OV_1")
	)
	(segment
		(start 428.518066 -108.63199)
		(end 428.283116 -108.86694)
		(width 0.12954)
		(layer "F.Cu")
		(net "P3V3_OCP_OV_1")
	)
	(segment
		(start 429.597566 -105.827322)
		(end 428.518066 -106.906822)
		(width 0.12954)
		(layer "F.Cu")
		(net "P3V3_OCP_OV_1")
	)
	(segment
		(start 428.512732 -107.872276)
		(end 428.518066 -107.87761)
		(width 0.12954)
		(layer "F.Cu")
		(net "P3V3_OCP_OV_1")
	)
	(segment
		(start 430.2887 -105.827322)
		(end 429.597566 -105.827322)
		(width 0.12954)
		(layer "F.Cu")
		(net "P3V3_OCP_OV_1")
	)
	(via
		(at 430.2887 -105.827322)
		(size 0.508)
		(drill 0.254)
		(layers "F.Cu" "B.Cu")
		(net "P3V3_OCP_OV_1")
	)
	(segment
		(start 67.51193 -54.361588)
		(end 68.37172 -54.361588)
		(width 0.12954)
		(layer "F.Cu")
		(net "P3V3_OCP_ILIMIT_2")
	)
	(segment
		(start 68.76796 -54.757828)
		(end 69.02196 -55.011828)
		(width 0.12954)
		(layer "F.Cu")
		(net "P3V3_OCP_ILIMIT_2")
	)
	(segment
		(start 68.37172 -54.361588)
		(end 68.76796 -54.757828)
		(width 0.12954)
		(layer "F.Cu")
		(net "P3V3_OCP_ILIMIT_2")
	)
	(segment
		(start 69.02196 -55.011828)
		(end 69.02196 -56.09463)
		(width 0.12954)
		(layer "F.Cu")
		(net "P3V3_OCP_ILIMIT_2")
	)
	(via
		(at 68.76796 -54.757828)
		(size 0.762)
		(drill 0.381)
		(layers "F.Cu" "B.Cu")
		(net "P3V3_OCP_ILIMIT_2")
	)
	(segment
		(start 70.41896 -60.758578)
		(end 70.44436 -60.733178)
		(width 0.12954)
		(layer "F.Cu")
		(net "P3V3_OCP_GATE_PU207_2")
	)
	(segment
		(start 70.44436 -60.733178)
		(end 70.44436 -59.507628)
		(width 0.12954)
		(layer "F.Cu")
		(net "P3V3_OCP_GATE_PU207_2")
	)
	(segment
		(start 69.521832 -58.5851)
		(end 69.521832 -58.094626)
		(width 0.12954)
		(layer "F.Cu")
		(net "P3V3_OCP_GATE_PU207_2")
	)
	(segment
		(start 70.44436 -59.507628)
		(end 69.521832 -58.5851)
		(width 0.12954)
		(layer "F.Cu")
		(net "P3V3_OCP_GATE_PU207_2")
	)
	(via
		(at 70.44436 -59.507628)
		(size 0.762)
		(drill 0.381)
		(layers "F.Cu" "B.Cu")
		(net "P3V3_OCP_GATE_PU207_2")
	)
	(segment
		(start 433.77612 -104.327452)
		(end 434.448204 -104.327452)
		(width 0.12954)
		(layer "F.Cu")
		(net "P3V3_OCP_GATE_PU202_1")
	)
	(segment
		(start 435.621176 -104.17048)
		(end 435.623208 -104.168448)
		(width 0.12954)
		(layer "F.Cu")
		(net "P3V3_OCP_GATE_PU202_1")
	)
	(segment
		(start 435.623208 -104.168448)
		(end 436.608474 -104.168448)
		(width 0.12954)
		(layer "F.Cu")
		(net "P3V3_OCP_GATE_PU202_1")
	)
	(segment
		(start 435.621176 -104.17048)
		(end 434.605176 -104.17048)
		(width 0.12954)
		(layer "F.Cu")
		(net "P3V3_OCP_GATE_PU202_1")
	)
	(segment
		(start 434.605176 -104.17048)
		(end 434.448204 -104.327452)
		(width 0.12954)
		(layer "F.Cu")
		(net "P3V3_OCP_GATE_PU202_1")
	)
	(segment
		(start 432.579018 -104.327452)
		(end 433.77612 -104.327452)
		(width 0.12954)
		(layer "F.Cu")
		(net "P3V3_OCP_GATE_PU202_1")
	)
	(via
		(at 433.77612 -104.327452)
		(size 0.508)
		(drill 0.254)
		(layers "F.Cu" "B.Cu")
		(net "P3V3_OCP_GATE_PU202_1")
	)
	(segment
		(start 83.050634 -53.70576)
		(end 83.050634 -53.668676)
		(width 0.12954)
		(layer "F.Cu")
		(net "P3V3_OCP_FAULT_2")
	)
	(segment
		(start 83.050634 -53.668676)
		(end 83.461352 -53.257958)
		(width 0.12954)
		(layer "F.Cu")
		(net "P3V3_OCP_FAULT_2")
	)
	(segment
		(start 83.050634 -53.932582)
		(end 83.050634 -53.70576)
		(width 0.12954)
		(layer "F.Cu")
		(net "P3V3_OCP_FAULT_2")
	)
	(via
		(at 83.461352 -53.257958)
		(size 0.508)
		(drill 0.254)
		(layers "F.Cu" "B.Cu")
		(net "P3V3_OCP_FAULT_2")
	)
	(segment
		(start 83.986116 -52.733194)
		(end 83.461352 -53.257958)
		(width 0.12954)
		(layer "B.Cu")
		(net "P3V3_OCP_FAULT_2")
	)
	(segment
		(start 84.0232 -52.733194)
		(end 83.986116 -52.733194)
		(width 0.12954)
		(layer "B.Cu")
		(net "P3V3_OCP_FAULT_2")
	)
	(segment
		(start 84.0232 -52.082446)
		(end 84.0232 -52.733194)
		(width 0.12954)
		(layer "B.Cu")
		(net "P3V3_OCP_FAULT_2")
	)
	(segment
		(start 432.551586 -101.97719)
		(end 432.551586 -102.677722)
		(width 0.17272)
		(layer "F.Cu")
		(net "P3V3_OCP_FAULT_1")
	)
	(segment
		(start 431.57902 -103.650288)
		(end 431.57902 -103.827326)
		(width 0.17272)
		(layer "F.Cu")
		(net "P3V3_OCP_FAULT_1")
	)
	(segment
		(start 432.551586 -102.677722)
		(end 431.57902 -103.650288)
		(width 0.17272)
		(layer "F.Cu")
		(net "P3V3_OCP_FAULT_1")
	)
	(via
		(at 432.551586 -102.677722)
		(size 0.508)
		(drill 0.254)
		(layers "F.Cu" "B.Cu")
		(net "P3V3_OCP_FAULT_1")
	)
	(segment
		(start 420.01694 -107.620308)
		(end 420.01694 -108.744258)
		(width 0.12954)
		(layer "F.Cu")
		(net "P3V3_OCP_EN_1_R2")
	)
	(segment
		(start 420.01694 -108.744258)
		(end 420.14394 -108.871258)
		(width 0.12954)
		(layer "F.Cu")
		(net "P3V3_OCP_EN_1_R2")
	)
	(segment
		(start 420.01694 -107.112562)
		(end 420.01694 -107.620308)
		(width 0.12954)
		(layer "F.Cu")
		(net "P3V3_OCP_EN_1_R2")
	)
	(segment
		(start 420.52494 -106.604562)
		(end 420.01694 -107.112562)
		(width 0.12954)
		(layer "F.Cu")
		(net "P3V3_OCP_EN_1_R2")
	)
	(segment
		(start 420.52494 -106.207306)
		(end 420.52494 -106.604562)
		(width 0.12954)
		(layer "F.Cu")
		(net "P3V3_OCP_EN_1_R2")
	)
	(via
		(at 420.01694 -107.620308)
		(size 0.762)
		(drill 0.381)
		(layers "F.Cu" "B.Cu")
		(net "P3V3_OCP_EN_1_R2")
	)
	(segment
		(start 460.58709 -41.002458)
		(end 459.25994 -41.002458)
		(width 0.12954)
		(layer "F.Cu")
		(net "P3V3_OCP_EN_1_R")
	)
	(segment
		(start 459.25994 -41.002458)
		(end 457.939648 -41.002458)
		(width 0.12954)
		(layer "F.Cu")
		(net "P3V3_OCP_EN_1_R")
	)
	(segment
		(start 457.92136 -42.05351)
		(end 457.929996 -42.049954)
		(width 0.12954)
		(layer "F.Cu")
		(net "P3V3_OCP_EN_1_R")
	)
	(segment
		(start 457.929996 -42.049954)
		(end 457.929996 -41.01211)
		(width 0.12954)
		(layer "F.Cu")
		(net "P3V3_OCP_EN_1_R")
	)
	(segment
		(start 457.939648 -41.002458)
		(end 457.929996 -41.01211)
		(width 0.12954)
		(layer "F.Cu")
		(net "P3V3_OCP_EN_1_R")
	)
	(via
		(at 459.25994 -41.002458)
		(size 0.762)
		(drill 0.381)
		(layers "F.Cu" "B.Cu")
		(net "P3V3_OCP_EN_1_R")
	)
	(segment
		(start 83.55711 -58.842656)
		(end 83.550506 -58.836052)
		(width 0.12954)
		(layer "F.Cu")
		(net "P3V3_OCP_CB_2")
	)
	(segment
		(start 83.550506 -58.201306)
		(end 83.550506 -56.93283)
		(width 0.12954)
		(layer "F.Cu")
		(net "P3V3_OCP_CB_2")
	)
	(segment
		(start 83.550506 -58.836052)
		(end 83.550506 -58.201306)
		(width 0.12954)
		(layer "F.Cu")
		(net "P3V3_OCP_CB_2")
	)
	(via
		(at 83.550506 -58.201306)
		(size 0.508)
		(drill 0.254)
		(layers "F.Cu" "B.Cu")
		(net "P3V3_OCP_CB_2")
	)
	(segment
		(start 432.085496 -108.7374)
		(end 432.085496 -107.645708)
		(width 0.12954)
		(layer "F.Cu")
		(net "P3V3_OCP_CB_1")
	)
	(segment
		(start 432.085496 -107.645708)
		(end 432.085496 -106.834178)
		(width 0.12954)
		(layer "F.Cu")
		(net "P3V3_OCP_CB_1")
	)
	(segment
		(start 432.085496 -106.834178)
		(end 432.078892 -106.827574)
		(width 0.12954)
		(layer "F.Cu")
		(net "P3V3_OCP_CB_1")
	)
	(via
		(at 432.085496 -107.645708)
		(size 0.508)
		(drill 0.254)
		(layers "F.Cu" "B.Cu")
		(net "P3V3_OCP_CB_1")
	)
	(segment
		(start 223.778572 -74.510138)
		(end 223.755204 -74.533506)
		(width 0.508)
		(layer "F.Cu")
		(net "P3V3_E1S_0_R")
	)
	(segment
		(start 223.755204 -74.533506)
		(end 223.755204 -75.141074)
		(width 0.508)
		(layer "F.Cu")
		(net "P3V3_E1S_0_R")
	)
	(segment
		(start 223.761046 -75.146916)
		(end 223.761046 -75.837542)
		(width 0.508)
		(layer "F.Cu")
		(net "P3V3_E1S_0_R")
	)
	(segment
		(start 223.761046 -75.837542)
		(end 223.784414 -75.86091)
		(width 0.508)
		(layer "F.Cu")
		(net "P3V3_E1S_0_R")
	)
	(segment
		(start 216.659714 -54.70525)
		(end 217.406982 -54.70525)
		(width 0.254)
		(layer "F.Cu")
		(net "P3V3_E1S_0_R")
	)
	(segment
		(start 222.772732 -67.114928)
		(end 225.856292 -67.114928)
		(width 0.508)
		(layer "F.Cu")
		(net "P3V3_E1S_0_R")
	)
	(segment
		(start 225.856292 -67.114928)
		(end 226.274122 -67.532758)
		(width 0.508)
		(layer "F.Cu")
		(net "P3V3_E1S_0_R")
	)
	(segment
		(start 223.755204 -75.141074)
		(end 223.761046 -75.146916)
		(width 0.508)
		(layer "F.Cu")
		(net "P3V3_E1S_0_R")
	)
	(segment
		(start 225.766122 -74.510138)
		(end 223.778572 -74.510138)
		(width 0.508)
		(layer "F.Cu")
		(net "P3V3_E1S_0_R")
	)
	(segment
		(start 226.274122 -74.002138)
		(end 225.766122 -74.510138)
		(width 0.508)
		(layer "F.Cu")
		(net "P3V3_E1S_0_R")
	)
	(segment
		(start 226.274122 -67.532758)
		(end 226.274122 -74.002138)
		(width 0.508)
		(layer "F.Cu")
		(net "P3V3_E1S_0_R")
	)
	(via
		(at 217.406982 -54.70525)
		(size 0.508)
		(drill 0.254)
		(layers "F.Cu" "B.Cu")
		(net "P3V3_E1S_0_R")
	)
	(via
		(at 194.64528 -67.282568)
		(size 0.508)
		(drill 0.254)
		(layers "F.Cu" "B.Cu")
		(net "P3V3_E1S_0_R")
	)
	(via
		(at 222.387922 -68.414138)
		(size 0.508)
		(drill 0.254)
		(layers "F.Cu" "B.Cu")
		(net "P3V3_E1S_0_R")
	)
	(via
		(at 220.352112 -58.874152)
		(size 0.508)
		(drill 0.254)
		(layers "F.Cu" "B.Cu")
		(net "P3V3_E1S_0_R")
	)
	(via
		(at 193.88328 -67.282568)
		(size 0.508)
		(drill 0.254)
		(layers "F.Cu" "B.Cu")
		(net "P3V3_E1S_0_R")
	)
	(via
		(at 222.387922 -67.677538)
		(size 0.508)
		(drill 0.254)
		(layers "F.Cu" "B.Cu")
		(net "P3V3_E1S_0_R")
	)
	(segment
		(start 220.352112 -58.874152)
		(end 220.352112 -57.65038)
		(width 0.381)
		(layer "B.Cu")
		(net "P3V3_E1S_0_R")
	)
	(segment
		(start 220.352112 -57.65038)
		(end 217.406982 -54.70525)
		(width 0.381)
		(layer "B.Cu")
		(net "P3V3_E1S_0_R")
	)
	(segment
		(start 217.406982 -54.70525)
		(end 216.835228 -54.70525)
		(width 0.254)
		(layer "B.Cu")
		(net "P3V3_E1S_0_R")
	)
	(segment
		(start 216.835228 -54.70525)
		(end 216.58453 -54.955948)
		(width 0.254)
		(layer "B.Cu")
		(net "P3V3_E1S_0_R")
	)
	(segment
		(start 343.549478 -46.570392)
		(end 343.793826 -46.993048)
		(width 0.13208)
		(layer "F.Cu")
		(net "P3E_PCH_E1S_TX_DP<3>")
	)
	(segment
		(start 343.821258 -47.040292)
		(end 343.81948 -47.040546)
		(width 0.13208)
		(layer "F.Cu")
		(net "P3E_PCH_E1S_TX_DP<3>")
	)
	(segment
		(start 343.793826 -46.993048)
		(end 343.821258 -47.040292)
		(width 0.13208)
		(layer "F.Cu")
		(net "P3E_PCH_E1S_TX_DP<3>")
	)
	(segment
		(start 239.419384 -58.30189)
		(end 239.419384 -58.32729)
		(width 0.13208)
		(layer "F.Cu")
		(net "P3E_PCH_E1S_TX_DP<3>")
	)
	(segment
		(start 240.663984 -58.30189)
		(end 240.361724 -57.99963)
		(width 0.13208)
		(layer "F.Cu")
		(net "P3E_PCH_E1S_TX_DP<3>")
	)
	(segment
		(start 239.721644 -57.99963)
		(end 239.419384 -58.30189)
		(width 0.13208)
		(layer "F.Cu")
		(net "P3E_PCH_E1S_TX_DP<3>")
	)
	(segment
		(start 240.361724 -57.99963)
		(end 239.721644 -57.99963)
		(width 0.13208)
		(layer "F.Cu")
		(net "P3E_PCH_E1S_TX_DP<3>")
	)
	(segment
		(start 340.46541 -19.242786)
		(end 340.264496 -19.282664)
		(width 0.14732)
		(layer "In4.Cu")
		(net "P3E_PCH_E1S_TX_DP<3>")
	)
	(segment
		(start 346.90558 -48.058832)
		(end 346.927678 -48.058832)
		(width 0.0889)
		(layer "In4.Cu")
		(net "P3E_PCH_E1S_TX_DP<3>")
	)
	(segment
		(start 253.573788 -59.723528)
		(end 251.182124 -59.723528)
		(width 0.14732)
		(layer "In4.Cu")
		(net "P3E_PCH_E1S_TX_DP<3>")
	)
	(segment
		(start 343.479374 -21.495766)
		(end 343.191338 -21.064982)
		(width 0.14732)
		(layer "In4.Cu")
		(net "P3E_PCH_E1S_TX_DP<3>")
	)
	(segment
		(start 340.264496 -19.282664)
		(end 339.958172 -19.07794)
		(width 0.14732)
		(layer "In4.Cu")
		(net "P3E_PCH_E1S_TX_DP<3>")
	)
	(segment
		(start 339.612224 -18.672302)
		(end 339.41131 -18.71218)
		(width 0.14732)
		(layer "In4.Cu")
		(net "P3E_PCH_E1S_TX_DP<3>")
	)
	(segment
		(start 240.958624 -58.00725)
		(end 240.663984 -58.30189)
		(width 0.14732)
		(layer "In4.Cu")
		(net "P3E_PCH_E1S_TX_DP<3>")
	)
	(segment
		(start 339.065108 -18.306288)
		(end 338.759038 -18.101818)
		(width 0.14732)
		(layer "In4.Cu")
		(net "P3E_PCH_E1S_TX_DP<3>")
	)
	(segment
		(start 346.927678 -48.058832)
		(end 350.427544 -48.058832)
		(width 0.14732)
		(layer "In4.Cu")
		(net "P3E_PCH_E1S_TX_DP<3>")
	)
	(segment
		(start 298.978066 -22.544786)
		(end 298.788836 -22.4663)
		(width 0.14732)
		(layer "In4.Cu")
		(net "P3E_PCH_E1S_TX_DP<3>")
	)
	(segment
		(start 297.755056 -22.894544)
		(end 297.41495 -23.03526)
		(width 0.14732)
		(layer "In4.Cu")
		(net "P3E_PCH_E1S_TX_DP<3>")
	)
	(segment
		(start 282.18003 -38.059868)
		(end 281.375358 -39.56685)
		(width 0.14732)
		(layer "In4.Cu")
		(net "P3E_PCH_E1S_TX_DP<3>")
	)
	(segment
		(start 281.065732 -40.146986)
		(end 281.065478 -40.14724)
		(width 0.14732)
		(layer "In4.Cu")
		(net "P3E_PCH_E1S_TX_DP<3>")
	)
	(segment
		(start 350.55302 -31.21025)
		(end 349.878904 -29.582872)
		(width 0.14732)
		(layer "In4.Cu")
		(net "P3E_PCH_E1S_TX_DP<3>")
	)
	(segment
		(start 339.958172 -19.07794)
		(end 339.918294 -18.876772)
		(width 0.14732)
		(layer "In4.Cu")
		(net "P3E_PCH_E1S_TX_DP<3>")
	)
	(segment
		(start 349.878904 -29.582872)
		(end 348.500954 -28.204922)
		(width 0.14732)
		(layer "In4.Cu")
		(net "P3E_PCH_E1S_TX_DP<3>")
	)
	(segment
		(start 348.035626 -27.739594)
		(end 347.36024 -27.064208)
		(width 0.14732)
		(layer "In4.Cu")
		(net "P3E_PCH_E1S_TX_DP<3>")
	)
	(segment
		(start 298.788836 -22.4663)
		(end 298.363132 -22.642576)
		(width 0.14732)
		(layer "In4.Cu")
		(net "P3E_PCH_E1S_TX_DP<3>")
	)
	(segment
		(start 352.0186 -43.552364)
		(end 351.90049 -42.958004)
		(width 0.14732)
		(layer "In4.Cu")
		(net "P3E_PCH_E1S_TX_DP<3>")
	)
	(segment
		(start 297.41495 -23.03526)
		(end 293.313104 -25.776174)
		(width 0.14732)
		(layer "In4.Cu")
		(net "P3E_PCH_E1S_TX_DP<3>")
	)
	(segment
		(start 338.2518 -17.936972)
		(end 338.211922 -17.736058)
		(width 0.14732)
		(layer "In4.Cu")
		(net "P3E_PCH_E1S_TX_DP<3>")
	)
	(segment
		(start 279.185878 -43.667172)
		(end 279.18283 -43.66768)
		(width 0.14732)
		(layer "In4.Cu")
		(net "P3E_PCH_E1S_TX_DP<3>")
	)
	(segment
		(start 348.500954 -28.204922)
		(end 348.29623 -28.204922)
		(width 0.14732)
		(layer "In4.Cu")
		(net "P3E_PCH_E1S_TX_DP<3>")
	)
	(segment
		(start 350.427544 -48.058832)
		(end 351.873058 -46.613318)
		(width 0.14732)
		(layer "In4.Cu")
		(net "P3E_PCH_E1S_TX_DP<3>")
	)
	(segment
		(start 351.771966 -42.31259)
		(end 350.55302 -36.184078)
		(width 0.14732)
		(layer "In4.Cu")
		(net "P3E_PCH_E1S_TX_DP<3>")
	)
	(segment
		(start 346.160852 -26.261314)
		(end 345.488006 -25.25395)
		(width 0.14732)
		(layer "In4.Cu")
		(net "P3E_PCH_E1S_TX_DP<3>")
	)
	(segment
		(start 298.2849 -22.831806)
		(end 297.944286 -22.972776)
		(width 0.14732)
		(layer "In4.Cu")
		(net "P3E_PCH_E1S_TX_DP<3>")
	)
	(segment
		(start 351.658174 -42.48277)
		(end 351.771966 -42.31259)
		(width 0.14732)
		(layer "In4.Cu")
		(net "P3E_PCH_E1S_TX_DP<3>")
	)
	(segment
		(start 338.211922 -17.736058)
		(end 337.583526 -17.315942)
		(width 0.14732)
		(layer "In4.Cu")
		(net "P3E_PCH_E1S_TX_DP<3>")
	)
	(segment
		(start 346.683584 -26.783792)
		(end 346.160852 -26.261314)
		(width 0.14732)
		(layer "In4.Cu")
		(net "P3E_PCH_E1S_TX_DP<3>")
	)
	(segment
		(start 323.932296 -16.751808)
		(end 302.099726 -21.094954)
		(width 0.14732)
		(layer "In4.Cu")
		(net "P3E_PCH_E1S_TX_DP<3>")
	)
	(segment
		(start 351.873058 -46.613318)
		(end 352.0186 -46.262036)
		(width 0.14732)
		(layer "In4.Cu")
		(net "P3E_PCH_E1S_TX_DP<3>")
	)
	(segment
		(start 279.18283 -43.66768)
		(end 274.546314 -54.861206)
		(width 0.14732)
		(layer "In4.Cu")
		(net "P3E_PCH_E1S_TX_DP<3>")
	)
	(segment
		(start 344.343736 -47.414942)
		(end 344.348562 -47.415196)
		(width 0.0889)
		(layer "In4.Cu")
		(net "P3E_PCH_E1S_TX_DP<3>")
	)
	(segment
		(start 351.90049 -42.958004)
		(end 351.730056 -42.844212)
		(width 0.14732)
		(layer "In4.Cu")
		(net "P3E_PCH_E1S_TX_DP<3>")
	)
	(segment
		(start 350.55302 -36.184078)
		(end 350.55302 -31.21025)
		(width 0.14732)
		(layer "In4.Cu")
		(net "P3E_PCH_E1S_TX_DP<3>")
	)
	(segment
		(start 336.221324 -16.751808)
		(end 323.932296 -16.751808)
		(width 0.14732)
		(layer "In4.Cu")
		(net "P3E_PCH_E1S_TX_DP<3>")
	)
	(segment
		(start 343.541858 -46.945042)
		(end 343.54897 -46.945042)
		(width 0.0889)
		(layer "In4.Cu")
		(net "P3E_PCH_E1S_TX_DP<3>")
	)
	(segment
		(start 345.488006 -25.25395)
		(end 345.074494 -24.480266)
		(width 0.14732)
		(layer "In4.Cu")
		(net "P3E_PCH_E1S_TX_DP<3>")
	)
	(segment
		(start 344.657172 -47.415196)
		(end 344.687906 -47.384462)
		(width 0.0889)
		(layer "In4.Cu")
		(net "P3E_PCH_E1S_TX_DP<3>")
	)
	(segment
		(start 344.687906 -47.384462)
		(end 345.389454 -47.384462)
		(width 0.0889)
		(layer "In4.Cu")
		(net "P3E_PCH_E1S_TX_DP<3>")
	)
	(segment
		(start 299.396912 -22.214332)
		(end 299.31868 -22.403816)
		(width 0.14732)
		(layer "In4.Cu")
		(net "P3E_PCH_E1S_TX_DP<3>")
	)
	(segment
		(start 251.182124 -59.723528)
		(end 250.071128 -59.26328)
		(width 0.14732)
		(layer "In4.Cu")
		(net "P3E_PCH_E1S_TX_DP<3>")
	)
	(segment
		(start 345.389454 -47.384462)
		(end 346.105734 -48.100742)
		(width 0.0889)
		(layer "In4.Cu")
		(net "P3E_PCH_E1S_TX_DP<3>")
	)
	(segment
		(start 344.70467 -24.09571)
		(end 344.764106 -23.899622)
		(width 0.14732)
		(layer "In4.Cu")
		(net "P3E_PCH_E1S_TX_DP<3>")
	)
	(segment
		(start 293.313104 -25.776174)
		(end 282.18003 -38.059868)
		(width 0.14732)
		(layer "In4.Cu")
		(net "P3E_PCH_E1S_TX_DP<3>")
	)
	(segment
		(start 351.730056 -42.844212)
		(end 351.658174 -42.48277)
		(width 0.14732)
		(layer "In4.Cu")
		(net "P3E_PCH_E1S_TX_DP<3>")
	)
	(segment
		(start 339.918294 -18.876772)
		(end 339.612224 -18.672302)
		(width 0.14732)
		(layer "In4.Cu")
		(net "P3E_PCH_E1S_TX_DP<3>")
	)
	(segment
		(start 299.31868 -22.403816)
		(end 298.978066 -22.544786)
		(width 0.14732)
		(layer "In4.Cu")
		(net "P3E_PCH_E1S_TX_DP<3>")
	)
	(segment
		(start 272.500852 -56.906668)
		(end 267.714476 -59.028838)
		(width 0.14732)
		(layer "In4.Cu")
		(net "P3E_PCH_E1S_TX_DP<3>")
	)
	(segment
		(start 339.41131 -18.71218)
		(end 339.104986 -18.507456)
		(width 0.14732)
		(layer "In4.Cu")
		(net "P3E_PCH_E1S_TX_DP<3>")
	)
	(segment
		(start 343.54897 -46.945042)
		(end 343.57818 -46.945296)
		(width 0.0889)
		(layer "In4.Cu")
		(net "P3E_PCH_E1S_TX_DP<3>")
	)
	(segment
		(start 267.714476 -59.028838)
		(end 253.573788 -59.723528)
		(width 0.14732)
		(layer "In4.Cu")
		(net "P3E_PCH_E1S_TX_DP<3>")
	)
	(segment
		(start 241.232436 -58.00725)
		(end 240.958624 -58.00725)
		(width 0.14732)
		(layer "In4.Cu")
		(net "P3E_PCH_E1S_TX_DP<3>")
	)
	(segment
		(start 346.105734 -48.100742)
		(end 346.86367 -48.100742)
		(width 0.0889)
		(layer "In4.Cu")
		(net "P3E_PCH_E1S_TX_DP<3>")
	)
	(segment
		(start 281.375358 -39.56685)
		(end 281.375104 -39.566088)
		(width 0.14732)
		(layer "In4.Cu")
		(net "P3E_PCH_E1S_TX_DP<3>")
	)
	(segment
		(start 302.099726 -21.094954)
		(end 299.396912 -22.214332)
		(width 0.14732)
		(layer "In4.Cu")
		(net "P3E_PCH_E1S_TX_DP<3>")
	)
	(segment
		(start 298.363132 -22.642576)
		(end 298.2849 -22.831806)
		(width 0.14732)
		(layer "In4.Cu")
		(net "P3E_PCH_E1S_TX_DP<3>")
	)
	(segment
		(start 281.065478 -40.14724)
		(end 279.185878 -43.667172)
		(width 0.14732)
		(layer "In4.Cu")
		(net "P3E_PCH_E1S_TX_DP<3>")
	)
	(segment
		(start 274.546314 -54.861206)
		(end 272.500852 -56.906668)
		(width 0.14732)
		(layer "In4.Cu")
		(net "P3E_PCH_E1S_TX_DP<3>")
	)
	(segment
		(start 347.36024 -27.064208)
		(end 346.683584 -26.783792)
		(width 0.14732)
		(layer "In4.Cu")
		(net "P3E_PCH_E1S_TX_DP<3>")
	)
	(segment
		(start 250.071128 -59.26328)
		(end 244.427756 -56.594248)
		(width 0.14732)
		(layer "In4.Cu")
		(net "P3E_PCH_E1S_TX_DP<3>")
	)
	(segment
		(start 281.375104 -39.566088)
		(end 281.43454 -39.761922)
		(width 0.14732)
		(layer "In4.Cu")
		(net "P3E_PCH_E1S_TX_DP<3>")
	)
	(segment
		(start 344.878406 -24.42083)
		(end 344.70467 -24.09571)
		(width 0.14732)
		(layer "In4.Cu")
		(net "P3E_PCH_E1S_TX_DP<3>")
	)
	(segment
		(start 346.86367 -48.100742)
		(end 346.90558 -48.058832)
		(width 0.0889)
		(layer "In4.Cu")
		(net "P3E_PCH_E1S_TX_DP<3>")
	)
	(segment
		(start 242.645438 -56.594248)
		(end 241.232436 -58.00725)
		(width 0.14732)
		(layer "In4.Cu")
		(net "P3E_PCH_E1S_TX_DP<3>")
	)
	(segment
		(start 337.583526 -17.315942)
		(end 336.221324 -16.751808)
		(width 0.14732)
		(layer "In4.Cu")
		(net "P3E_PCH_E1S_TX_DP<3>")
	)
	(segment
		(start 348.035626 -27.944318)
		(end 348.035626 -27.739594)
		(width 0.14732)
		(layer "In4.Cu")
		(net "P3E_PCH_E1S_TX_DP<3>")
	)
	(segment
		(start 338.759038 -18.101818)
		(end 338.558378 -18.141696)
		(width 0.14732)
		(layer "In4.Cu")
		(net "P3E_PCH_E1S_TX_DP<3>")
	)
	(segment
		(start 281.064716 -40.146478)
		(end 281.065732 -40.146986)
		(width 0.14732)
		(layer "In4.Cu")
		(net "P3E_PCH_E1S_TX_DP<3>")
	)
	(segment
		(start 297.944286 -22.972776)
		(end 297.755056 -22.894544)
		(width 0.14732)
		(layer "In4.Cu")
		(net "P3E_PCH_E1S_TX_DP<3>")
	)
	(segment
		(start 343.27846 -46.726602)
		(end 343.257378 -46.805088)
		(width 0.0889)
		(layer "In4.Cu")
		(net "P3E_PCH_E1S_TX_DP<3>")
	)
	(segment
		(start 343.191338 -21.064982)
		(end 340.46541 -19.242786)
		(width 0.14732)
		(layer "In4.Cu")
		(net "P3E_PCH_E1S_TX_DP<3>")
	)
	(segment
		(start 281.43454 -39.761922)
		(end 281.260804 -40.087042)
		(width 0.14732)
		(layer "In4.Cu")
		(net "P3E_PCH_E1S_TX_DP<3>")
	)
	(segment
		(start 344.764106 -23.899622)
		(end 343.479374 -21.495766)
		(width 0.14732)
		(layer "In4.Cu")
		(net "P3E_PCH_E1S_TX_DP<3>")
	)
	(segment
		(start 348.29623 -28.204922)
		(end 348.035626 -27.944318)
		(width 0.14732)
		(layer "In4.Cu")
		(net "P3E_PCH_E1S_TX_DP<3>")
	)
	(segment
		(start 281.260804 -40.087042)
		(end 281.064716 -40.146478)
		(width 0.14732)
		(layer "In4.Cu")
		(net "P3E_PCH_E1S_TX_DP<3>")
	)
	(segment
		(start 352.0186 -46.262036)
		(end 352.0186 -43.552364)
		(width 0.14732)
		(layer "In4.Cu")
		(net "P3E_PCH_E1S_TX_DP<3>")
	)
	(segment
		(start 338.558378 -18.141696)
		(end 338.2518 -17.936972)
		(width 0.14732)
		(layer "In4.Cu")
		(net "P3E_PCH_E1S_TX_DP<3>")
	)
	(segment
		(start 343.549478 -46.570392)
		(end 343.27846 -46.726602)
		(width 0.0889)
		(layer "In4.Cu")
		(net "P3E_PCH_E1S_TX_DP<3>")
	)
	(segment
		(start 345.074494 -24.480266)
		(end 344.878406 -24.42083)
		(width 0.14732)
		(layer "In4.Cu")
		(net "P3E_PCH_E1S_TX_DP<3>")
	)
	(segment
		(start 344.348562 -47.415196)
		(end 344.657172 -47.415196)
		(width 0.0889)
		(layer "In4.Cu")
		(net "P3E_PCH_E1S_TX_DP<3>")
	)
	(segment
		(start 244.427756 -56.594248)
		(end 242.645438 -56.594248)
		(width 0.14732)
		(layer "In4.Cu")
		(net "P3E_PCH_E1S_TX_DP<3>")
	)
	(segment
		(start 339.104986 -18.507456)
		(end 339.065108 -18.306288)
		(width 0.14732)
		(layer "In4.Cu")
		(net "P3E_PCH_E1S_TX_DP<3>")
	)
	(arc
		(start 343.57818 -46.945296)
		(mid 343.844036 -47.027975)
		(end 344.038174 -47.22749)
		(width 0.0889)
		(layer "In4.Cu")
		(net "P3E_PCH_E1S_TX_DP<3>")
	)
	(arc
		(start 344.038174 -47.22749)
		(mid 344.167117 -47.360074)
		(end 344.343736 -47.414942)
		(width 0.0889)
		(layer "In4.Cu")
		(net "P3E_PCH_E1S_TX_DP<3>")
	)
	(arc
		(start 343.257378 -46.805088)
		(mid 343.38409 -46.906623)
		(end 343.541858 -46.945042)
		(width 0.0889)
		(layer "In4.Cu")
		(net "P3E_PCH_E1S_TX_DP<3>")
	)
	(segment
		(start 241.634264 -56.199532)
		(end 241.80292 -56.368188)
		(width 0.13208)
		(layer "F.Cu")
		(net "P3E_PCH_E1S_TX_DP<2>")
	)
	(segment
		(start 242.263676 -58.260742)
		(end 242.815364 -58.260742)
		(width 0.13208)
		(layer "F.Cu")
		(net "P3E_PCH_E1S_TX_DP<2>")
	)
	(segment
		(start 241.80292 -57.799986)
		(end 242.263676 -58.260742)
		(width 0.13208)
		(layer "F.Cu")
		(net "P3E_PCH_E1S_TX_DP<2>")
	)
	(segment
		(start 344.63355 -46.570646)
		(end 344.363294 -46.100492)
		(width 0.13208)
		(layer "F.Cu")
		(net "P3E_PCH_E1S_TX_DP<2>")
	)
	(segment
		(start 241.121184 -56.527192)
		(end 241.448844 -56.199532)
		(width 0.13208)
		(layer "F.Cu")
		(net "P3E_PCH_E1S_TX_DP<2>")
	)
	(segment
		(start 241.448844 -56.199532)
		(end 241.634264 -56.199532)
		(width 0.13208)
		(layer "F.Cu")
		(net "P3E_PCH_E1S_TX_DP<2>")
	)
	(segment
		(start 242.815364 -58.260742)
		(end 243.117624 -58.563002)
		(width 0.13208)
		(layer "F.Cu")
		(net "P3E_PCH_E1S_TX_DP<2>")
	)
	(segment
		(start 241.80292 -56.368188)
		(end 241.80292 -57.799986)
		(width 0.13208)
		(layer "F.Cu")
		(net "P3E_PCH_E1S_TX_DP<2>")
	)
	(segment
		(start 328.33945 -17.739868)
		(end 332.349348 -18.537428)
		(width 0.14732)
		(layer "In4.Cu")
		(net "P3E_PCH_E1S_TX_DP<2>")
	)
	(segment
		(start 334.99425 -18.682208)
		(end 335.13903 -18.537428)
		(width 0.14732)
		(layer "In4.Cu")
		(net "P3E_PCH_E1S_TX_DP<2>")
	)
	(segment
		(start 282.915614 -39.402512)
		(end 282.856178 -39.206678)
		(width 0.14732)
		(layer "In4.Cu")
		(net "P3E_PCH_E1S_TX_DP<2>")
	)
	(segment
		(start 346.483178 -46.694852)
		(end 346.46108 -46.694852)
		(width 0.0889)
		(layer "In4.Cu")
		(net "P3E_PCH_E1S_TX_DP<2>")
	)
	(segment
		(start 282.856178 -39.206678)
		(end 283.457904 -38.080696)
		(width 0.14732)
		(layer "In4.Cu")
		(net "P3E_PCH_E1S_TX_DP<2>")
	)
	(segment
		(start 282.54579 -39.787068)
		(end 282.742132 -39.727632)
		(width 0.14732)
		(layer "In4.Cu")
		(net "P3E_PCH_E1S_TX_DP<2>")
	)
	(segment
		(start 346.762832 -28.72232)
		(end 348.21114 -29.322268)
		(width 0.14732)
		(layer "In4.Cu")
		(net "P3E_PCH_E1S_TX_DP<2>")
	)
	(segment
		(start 243.718334 -58.268362)
		(end 244.924834 -59.474862)
		(width 0.14732)
		(layer "In4.Cu")
		(net "P3E_PCH_E1S_TX_DP<2>")
	)
	(segment
		(start 279.524714 -45.439584)
		(end 282.54579 -39.787068)
		(width 0.14732)
		(layer "In4.Cu")
		(net "P3E_PCH_E1S_TX_DP<2>")
	)
	(segment
		(start 341.937086 -22.194774)
		(end 345.364308 -27.323796)
		(width 0.14732)
		(layer "In4.Cu")
		(net "P3E_PCH_E1S_TX_DP<2>")
	)
	(segment
		(start 267.979398 -59.946794)
		(end 273.486372 -57.505854)
		(width 0.14732)
		(layer "In4.Cu")
		(net "P3E_PCH_E1S_TX_DP<2>")
	)
	(segment
		(start 298.125134 -24.11349)
		(end 298.203366 -23.924006)
		(width 0.14732)
		(layer "In4.Cu")
		(net "P3E_PCH_E1S_TX_DP<2>")
	)
	(segment
		(start 245.786148 -59.831732)
		(end 249.917458 -60.653168)
		(width 0.14732)
		(layer "In4.Cu")
		(net "P3E_PCH_E1S_TX_DP<2>")
	)
	(segment
		(start 349.53702 -36.6141)
		(end 351.039176 -44.167044)
		(width 0.14732)
		(layer "In4.Cu")
		(net "P3E_PCH_E1S_TX_DP<2>")
	)
	(segment
		(start 243.412264 -58.268362)
		(end 243.718334 -58.268362)
		(width 0.14732)
		(layer "In4.Cu")
		(net "P3E_PCH_E1S_TX_DP<2>")
	)
	(segment
		(start 334.62595 -18.682208)
		(end 334.99425 -18.682208)
		(width 0.14732)
		(layer "In4.Cu")
		(net "P3E_PCH_E1S_TX_DP<2>")
	)
	(segment
		(start 335.13903 -18.537428)
		(end 336.078068 -18.537428)
		(width 0.14732)
		(layer "In4.Cu")
		(net "P3E_PCH_E1S_TX_DP<2>")
	)
	(segment
		(start 339.015578 -20.242784)
		(end 339.321902 -20.447508)
		(width 0.14732)
		(layer "In4.Cu")
		(net "P3E_PCH_E1S_TX_DP<2>")
	)
	(segment
		(start 244.97538 -59.49569)
		(end 245.786148 -59.831732)
		(width 0.14732)
		(layer "In4.Cu")
		(net "P3E_PCH_E1S_TX_DP<2>")
	)
	(segment
		(start 323.81952 -17.739868)
		(end 328.33945 -17.739868)
		(width 0.14732)
		(layer "In4.Cu")
		(net "P3E_PCH_E1S_TX_DP<2>")
	)
	(segment
		(start 337.961478 -19.712686)
		(end 338.162138 -19.672554)
		(width 0.14732)
		(layer "In4.Cu")
		(net "P3E_PCH_E1S_TX_DP<2>")
	)
	(segment
		(start 298.203366 -23.924006)
		(end 299.042074 -23.576788)
		(width 0.14732)
		(layer "In4.Cu")
		(net "P3E_PCH_E1S_TX_DP<2>")
	)
	(segment
		(start 297.032426 -24.409146)
		(end 297.59529 -24.175974)
		(width 0.14732)
		(layer "In4.Cu")
		(net "P3E_PCH_E1S_TX_DP<2>")
	)
	(segment
		(start 333.45501 -18.537428)
		(end 333.59979 -18.682208)
		(width 0.14732)
		(layer "In4.Cu")
		(net "P3E_PCH_E1S_TX_DP<2>")
	)
	(segment
		(start 297.59529 -24.175974)
		(end 297.78452 -24.25446)
		(width 0.14732)
		(layer "In4.Cu")
		(net "P3E_PCH_E1S_TX_DP<2>")
	)
	(segment
		(start 249.917458 -60.653168)
		(end 253.599442 -60.653168)
		(width 0.14732)
		(layer "In4.Cu")
		(net "P3E_PCH_E1S_TX_DP<2>")
	)
	(segment
		(start 338.162138 -19.672554)
		(end 338.468462 -19.877278)
		(width 0.14732)
		(layer "In4.Cu")
		(net "P3E_PCH_E1S_TX_DP<2>")
	)
	(segment
		(start 299.042074 -23.576788)
		(end 299.231304 -23.655274)
		(width 0.14732)
		(layer "In4.Cu")
		(net "P3E_PCH_E1S_TX_DP<2>")
	)
	(segment
		(start 337.655154 -19.507962)
		(end 337.961478 -19.712686)
		(width 0.14732)
		(layer "In4.Cu")
		(net "P3E_PCH_E1S_TX_DP<2>")
	)
	(segment
		(start 283.457904 -38.080696)
		(end 294.030908 -26.414984)
		(width 0.14732)
		(layer "In4.Cu")
		(net "P3E_PCH_E1S_TX_DP<2>")
	)
	(segment
		(start 350.323404 -46.694852)
		(end 346.483178 -46.694852)
		(width 0.14732)
		(layer "In4.Cu")
		(net "P3E_PCH_E1S_TX_DP<2>")
	)
	(segment
		(start 350.945704 -46.072552)
		(end 350.323404 -46.694852)
		(width 0.14732)
		(layer "In4.Cu")
		(net "P3E_PCH_E1S_TX_DP<2>")
	)
	(segment
		(start 299.65015 -23.32482)
		(end 299.65015 -23.325074)
		(width 0.14732)
		(layer "In4.Cu")
		(net "P3E_PCH_E1S_TX_DP<2>")
	)
	(segment
		(start 336.078068 -18.537428)
		(end 337.091782 -18.95729)
		(width 0.14732)
		(layer "In4.Cu")
		(net "P3E_PCH_E1S_TX_DP<2>")
	)
	(segment
		(start 275.262848 -55.729124)
		(end 279.524714 -45.439584)
		(width 0.14732)
		(layer "In4.Cu")
		(net "P3E_PCH_E1S_TX_DP<2>")
	)
	(segment
		(start 244.97538 -59.495944)
		(end 244.97538 -59.49569)
		(width 0.14732)
		(layer "In4.Cu")
		(net "P3E_PCH_E1S_TX_DP<2>")
	)
	(segment
		(start 334.48117 -18.537428)
		(end 334.62595 -18.682208)
		(width 0.14732)
		(layer "In4.Cu")
		(net "P3E_PCH_E1S_TX_DP<2>")
	)
	(segment
		(start 338.468462 -19.877278)
		(end 338.50834 -20.078192)
		(width 0.14732)
		(layer "In4.Cu")
		(net "P3E_PCH_E1S_TX_DP<2>")
	)
	(segment
		(start 339.668358 -20.852892)
		(end 339.869272 -20.813014)
		(width 0.14732)
		(layer "In4.Cu")
		(net "P3E_PCH_E1S_TX_DP<2>")
	)
	(segment
		(start 344.452194 -46.475396)
		(end 344.363294 -46.386496)
		(width 0.0889)
		(layer "In4.Cu")
		(net "P3E_PCH_E1S_TX_DP<2>")
	)
	(segment
		(start 243.117624 -58.563002)
		(end 243.412264 -58.268362)
		(width 0.14732)
		(layer "In4.Cu")
		(net "P3E_PCH_E1S_TX_DP<2>")
	)
	(segment
		(start 344.658188 -46.475396)
		(end 344.452194 -46.475396)
		(width 0.0889)
		(layer "In4.Cu")
		(net "P3E_PCH_E1S_TX_DP<2>")
	)
	(segment
		(start 348.21114 -29.322268)
		(end 349.109538 -30.220666)
		(width 0.14732)
		(layer "In4.Cu")
		(net "P3E_PCH_E1S_TX_DP<2>")
	)
	(segment
		(start 332.349348 -18.537428)
		(end 333.45501 -18.537428)
		(width 0.14732)
		(layer "In4.Cu")
		(net "P3E_PCH_E1S_TX_DP<2>")
	)
	(segment
		(start 344.363294 -46.386496)
		(end 344.363294 -46.100492)
		(width 0.0889)
		(layer "In4.Cu")
		(net "P3E_PCH_E1S_TX_DP<2>")
	)
	(segment
		(start 339.869272 -20.813014)
		(end 341.937086 -22.194774)
		(width 0.14732)
		(layer "In4.Cu")
		(net "P3E_PCH_E1S_TX_DP<2>")
	)
	(segment
		(start 338.50834 -20.078192)
		(end 338.814918 -20.282662)
		(width 0.14732)
		(layer "In4.Cu")
		(net "P3E_PCH_E1S_TX_DP<2>")
	)
	(segment
		(start 303.261776 -21.829268)
		(end 323.81952 -17.739868)
		(width 0.14732)
		(layer "In4.Cu")
		(net "P3E_PCH_E1S_TX_DP<2>")
	)
	(segment
		(start 299.571664 -23.514304)
		(end 299.65015 -23.32482)
		(width 0.14732)
		(layer "In4.Cu")
		(net "P3E_PCH_E1S_TX_DP<2>")
	)
	(segment
		(start 244.924834 -59.474862)
		(end 244.97538 -59.495944)
		(width 0.14732)
		(layer "In4.Cu")
		(net "P3E_PCH_E1S_TX_DP<2>")
	)
	(segment
		(start 299.231304 -23.655274)
		(end 299.571664 -23.514304)
		(width 0.14732)
		(layer "In4.Cu")
		(net "P3E_PCH_E1S_TX_DP<2>")
	)
	(segment
		(start 346.46108 -46.694852)
		(end 346.41917 -46.736762)
		(width 0.0889)
		(layer "In4.Cu")
		(net "P3E_PCH_E1S_TX_DP<2>")
	)
	(segment
		(start 273.486372 -57.505854)
		(end 275.262848 -55.729124)
		(width 0.14732)
		(layer "In4.Cu")
		(net "P3E_PCH_E1S_TX_DP<2>")
	)
	(segment
		(start 339.321902 -20.447508)
		(end 339.36178 -20.648422)
		(width 0.14732)
		(layer "In4.Cu")
		(net "P3E_PCH_E1S_TX_DP<2>")
	)
	(segment
		(start 294.030908 -26.414984)
		(end 297.032426 -24.409146)
		(width 0.14732)
		(layer "In4.Cu")
		(net "P3E_PCH_E1S_TX_DP<2>")
	)
	(segment
		(start 345.364308 -27.323796)
		(end 346.762832 -28.72232)
		(width 0.14732)
		(layer "In4.Cu")
		(net "P3E_PCH_E1S_TX_DP<2>")
	)
	(segment
		(start 349.53702 -31.252668)
		(end 349.53702 -36.6141)
		(width 0.14732)
		(layer "In4.Cu")
		(net "P3E_PCH_E1S_TX_DP<2>")
	)
	(segment
		(start 333.96809 -18.682208)
		(end 334.11287 -18.537428)
		(width 0.14732)
		(layer "In4.Cu")
		(net "P3E_PCH_E1S_TX_DP<2>")
	)
	(segment
		(start 334.11287 -18.537428)
		(end 334.48117 -18.537428)
		(width 0.14732)
		(layer "In4.Cu")
		(net "P3E_PCH_E1S_TX_DP<2>")
	)
	(segment
		(start 346.41917 -46.736762)
		(end 344.919554 -46.736762)
		(width 0.0889)
		(layer "In4.Cu")
		(net "P3E_PCH_E1S_TX_DP<2>")
	)
	(segment
		(start 282.742132 -39.727632)
		(end 282.915614 -39.402512)
		(width 0.14732)
		(layer "In4.Cu")
		(net "P3E_PCH_E1S_TX_DP<2>")
	)
	(segment
		(start 337.091782 -18.95729)
		(end 337.615022 -19.307048)
		(width 0.14732)
		(layer "In4.Cu")
		(net "P3E_PCH_E1S_TX_DP<2>")
	)
	(segment
		(start 351.039176 -44.167044)
		(end 350.945704 -46.072552)
		(width 0.14732)
		(layer "In4.Cu")
		(net "P3E_PCH_E1S_TX_DP<2>")
	)
	(segment
		(start 297.78452 -24.25446)
		(end 298.125134 -24.11349)
		(width 0.14732)
		(layer "In4.Cu")
		(net "P3E_PCH_E1S_TX_DP<2>")
	)
	(segment
		(start 339.36178 -20.648422)
		(end 339.668358 -20.852892)
		(width 0.14732)
		(layer "In4.Cu")
		(net "P3E_PCH_E1S_TX_DP<2>")
	)
	(segment
		(start 337.615022 -19.307048)
		(end 337.655154 -19.507962)
		(width 0.14732)
		(layer "In4.Cu")
		(net "P3E_PCH_E1S_TX_DP<2>")
	)
	(segment
		(start 344.919554 -46.736762)
		(end 344.658188 -46.475396)
		(width 0.0889)
		(layer "In4.Cu")
		(net "P3E_PCH_E1S_TX_DP<2>")
	)
	(segment
		(start 349.109538 -30.220666)
		(end 349.53702 -31.252668)
		(width 0.14732)
		(layer "In4.Cu")
		(net "P3E_PCH_E1S_TX_DP<2>")
	)
	(segment
		(start 333.59979 -18.682208)
		(end 333.96809 -18.682208)
		(width 0.14732)
		(layer "In4.Cu")
		(net "P3E_PCH_E1S_TX_DP<2>")
	)
	(segment
		(start 338.814918 -20.282662)
		(end 339.015578 -20.242784)
		(width 0.14732)
		(layer "In4.Cu")
		(net "P3E_PCH_E1S_TX_DP<2>")
	)
	(segment
		(start 253.599442 -60.653168)
		(end 267.979398 -59.946794)
		(width 0.14732)
		(layer "In4.Cu")
		(net "P3E_PCH_E1S_TX_DP<2>")
	)
	(segment
		(start 299.65015 -23.325074)
		(end 303.261776 -21.829268)
		(width 0.14732)
		(layer "In4.Cu")
		(net "P3E_PCH_E1S_TX_DP<2>")
	)
	(segment
		(start 239.419384 -53.847238)
		(end 239.419384 -53.821838)
		(width 0.13208)
		(layer "F.Cu")
		(net "P3E_PCH_E1S_TX_DP<1>")
	)
	(segment
		(start 240.663984 -53.847238)
		(end 240.361724 -54.149498)
		(width 0.13208)
		(layer "F.Cu")
		(net "P3E_PCH_E1S_TX_DP<1>")
	)
	(segment
		(start 240.361724 -54.149498)
		(end 239.721644 -54.149498)
		(width 0.13208)
		(layer "F.Cu")
		(net "P3E_PCH_E1S_TX_DP<1>")
	)
	(segment
		(start 342.190578 -46.100746)
		(end 342.19134 -46.100746)
		(width 0.13208)
		(layer "F.Cu")
		(net "P3E_PCH_E1S_TX_DP<1>")
	)
	(segment
		(start 341.918798 -45.630846)
		(end 342.190578 -46.100746)
		(width 0.13208)
		(layer "F.Cu")
		(net "P3E_PCH_E1S_TX_DP<1>")
	)
	(segment
		(start 239.721644 -54.149498)
		(end 239.419384 -53.847238)
		(width 0.13208)
		(layer "F.Cu")
		(net "P3E_PCH_E1S_TX_DP<1>")
	)
	(segment
		(start 347.27515 -34.984182)
		(end 345.996768 -31.897828)
		(width 0.14732)
		(layer "In4.Cu")
		(net "P3E_PCH_E1S_TX_DP<1>")
	)
	(segment
		(start 249.84075 -61.590428)
		(end 244.282976 -60.484766)
		(width 0.14732)
		(layer "In4.Cu")
		(net "P3E_PCH_E1S_TX_DP<1>")
	)
	(segment
		(start 347.325696 -45.0596)
		(end 347.590618 -43.726862)
		(width 0.14732)
		(layer "In4.Cu")
		(net "P3E_PCH_E1S_TX_DP<1>")
	)
	(segment
		(start 339.648292 -25.549352)
		(end 336.28076 -23.299166)
		(width 0.14732)
		(layer "In4.Cu")
		(net "P3E_PCH_E1S_TX_DP<1>")
	)
	(segment
		(start 345.61272 -45.698918)
		(end 346.686378 -45.698918)
		(width 0.14732)
		(layer "In4.Cu")
		(net "P3E_PCH_E1S_TX_DP<1>")
	)
	(segment
		(start 296.848276 -25.650952)
		(end 294.78986 -27.026362)
		(width 0.14732)
		(layer "In4.Cu")
		(net "P3E_PCH_E1S_TX_DP<1>")
	)
	(segment
		(start 336.28076 -23.299166)
		(end 334.051656 -22.501352)
		(width 0.14732)
		(layer "In4.Cu")
		(net "P3E_PCH_E1S_TX_DP<1>")
	)
	(segment
		(start 348.50832 -39.11473)
		(end 348.50832 -37.385244)
		(width 0.14732)
		(layer "In4.Cu")
		(net "P3E_PCH_E1S_TX_DP<1>")
	)
	(segment
		(start 244.282976 -60.484766)
		(end 244.282722 -60.484766)
		(width 0.14732)
		(layer "In4.Cu")
		(net "P3E_PCH_E1S_TX_DP<1>")
	)
	(segment
		(start 274.176744 -58.25236)
		(end 268.188948 -60.90666)
		(width 0.14732)
		(layer "In4.Cu")
		(net "P3E_PCH_E1S_TX_DP<1>")
	)
	(segment
		(start 344.91422 -45.740828)
		(end 345.548712 -45.740828)
		(width 0.0889)
		(layer "In4.Cu")
		(net "P3E_PCH_E1S_TX_DP<1>")
	)
	(segment
		(start 237.34014 -57.999122)
		(end 236.935772 -57.5945)
		(width 0.14732)
		(layer "In4.Cu")
		(net "P3E_PCH_E1S_TX_DP<1>")
	)
	(segment
		(start 284.642814 -38.222682)
		(end 279.842468 -47.204884)
		(width 0.14732)
		(layer "In4.Cu")
		(net "P3E_PCH_E1S_TX_DP<1>")
	)
	(segment
		(start 347.548962 -43.194986)
		(end 347.719396 -43.081194)
		(width 0.14732)
		(layer "In4.Cu")
		(net "P3E_PCH_E1S_TX_DP<1>")
	)
	(segment
		(start 347.590618 -43.726862)
		(end 347.47708 -43.556428)
		(width 0.14732)
		(layer "In4.Cu")
		(net "P3E_PCH_E1S_TX_DP<1>")
	)
	(segment
		(start 276.037294 -56.39181)
		(end 274.176744 -58.25236)
		(width 0.14732)
		(layer "In4.Cu")
		(net "P3E_PCH_E1S_TX_DP<1>")
	)
	(segment
		(start 254.266446 -61.590428)
		(end 249.84075 -61.590428)
		(width 0.14732)
		(layer "In4.Cu")
		(net "P3E_PCH_E1S_TX_DP<1>")
	)
	(segment
		(start 238.936276 -59.065414)
		(end 237.34014 -57.999122)
		(width 0.14732)
		(layer "In4.Cu")
		(net "P3E_PCH_E1S_TX_DP<1>")
	)
	(segment
		(start 236.06506 -56.723788)
		(end 236.06506 -54.7116)
		(width 0.14732)
		(layer "In4.Cu")
		(net "P3E_PCH_E1S_TX_DP<1>")
	)
	(segment
		(start 300.00194 -24.34463)
		(end 300.001686 -24.345646)
		(width 0.14732)
		(layer "In4.Cu")
		(net "P3E_PCH_E1S_TX_DP<1>")
	)
	(segment
		(start 323.897752 -18.694908)
		(end 310.999124 -21.260816)
		(width 0.14732)
		(layer "In4.Cu")
		(net "P3E_PCH_E1S_TX_DP<1>")
	)
	(segment
		(start 279.842468 -47.204884)
		(end 276.037294 -56.39181)
		(width 0.14732)
		(layer "In4.Cu")
		(net "P3E_PCH_E1S_TX_DP<1>")
	)
	(segment
		(start 310.999124 -21.260816)
		(end 310.885332 -21.43125)
		(width 0.14732)
		(layer "In4.Cu")
		(net "P3E_PCH_E1S_TX_DP<1>")
	)
	(segment
		(start 347.719396 -43.081194)
		(end 347.921834 -42.0624)
		(width 0.14732)
		(layer "In4.Cu")
		(net "P3E_PCH_E1S_TX_DP<1>")
	)
	(segment
		(start 342.697054 -45.535342)
		(end 342.742266 -45.535342)
		(width 0.0889)
		(layer "In4.Cu")
		(net "P3E_PCH_E1S_TX_DP<1>")
	)
	(segment
		(start 344.038936 -45.34789)
		(end 344.044016 -45.35678)
		(width 0.0889)
		(layer "In4.Cu")
		(net "P3E_PCH_E1S_TX_DP<1>")
	)
	(segment
		(start 344.363294 -45.535342)
		(end 344.708734 -45.535342)
		(width 0.0889)
		(layer "In4.Cu")
		(net "P3E_PCH_E1S_TX_DP<1>")
	)
	(segment
		(start 347.47708 -43.556428)
		(end 347.548962 -43.194986)
		(width 0.14732)
		(layer "In4.Cu")
		(net "P3E_PCH_E1S_TX_DP<1>")
	)
	(segment
		(start 348.050612 -41.416732)
		(end 348.50832 -39.11473)
		(width 0.14732)
		(layer "In4.Cu")
		(net "P3E_PCH_E1S_TX_DP<1>")
	)
	(segment
		(start 347.879924 -41.530524)
		(end 348.050612 -41.416732)
		(width 0.14732)
		(layer "In4.Cu")
		(net "P3E_PCH_E1S_TX_DP<1>")
	)
	(segment
		(start 341.918798 -45.630846)
		(end 342.190578 -45.787056)
		(width 0.0889)
		(layer "In4.Cu")
		(net "P3E_PCH_E1S_TX_DP<1>")
	)
	(segment
		(start 348.50832 -37.385244)
		(end 348.199456 -36.367466)
		(width 0.14732)
		(layer "In4.Cu")
		(net "P3E_PCH_E1S_TX_DP<1>")
	)
	(segment
		(start 310.52389 -21.503132)
		(end 310.353456 -21.38934)
		(width 0.14732)
		(layer "In4.Cu")
		(net "P3E_PCH_E1S_TX_DP<1>")
	)
	(segment
		(start 345.548712 -45.740828)
		(end 345.590622 -45.698918)
		(width 0.0889)
		(layer "In4.Cu")
		(net "P3E_PCH_E1S_TX_DP<1>")
	)
	(segment
		(start 236.935772 -57.5945)
		(end 236.06506 -56.723788)
		(width 0.14732)
		(layer "In4.Cu")
		(net "P3E_PCH_E1S_TX_DP<1>")
	)
	(segment
		(start 236.634782 -54.141878)
		(end 240.369344 -54.141878)
		(width 0.14732)
		(layer "In4.Cu")
		(net "P3E_PCH_E1S_TX_DP<1>")
	)
	(segment
		(start 347.921834 -42.0624)
		(end 347.808296 -41.891966)
		(width 0.14732)
		(layer "In4.Cu")
		(net "P3E_PCH_E1S_TX_DP<1>")
	)
	(segment
		(start 348.199456 -36.367466)
		(end 347.27515 -34.984182)
		(width 0.14732)
		(layer "In4.Cu")
		(net "P3E_PCH_E1S_TX_DP<1>")
	)
	(segment
		(start 344.708734 -45.535342)
		(end 344.91422 -45.740828)
		(width 0.0889)
		(layer "In4.Cu")
		(net "P3E_PCH_E1S_TX_DP<1>")
	)
	(segment
		(start 268.188948 -60.90666)
		(end 254.266446 -61.590428)
		(width 0.14732)
		(layer "In4.Cu")
		(net "P3E_PCH_E1S_TX_DP<1>")
	)
	(segment
		(start 343.530936 -45.065442)
		(end 343.559384 -45.065442)
		(width 0.0889)
		(layer "In4.Cu")
		(net "P3E_PCH_E1S_TX_DP<1>")
	)
	(segment
		(start 328.096118 -18.694908)
		(end 323.897752 -18.694908)
		(width 0.14732)
		(layer "In4.Cu")
		(net "P3E_PCH_E1S_TX_DP<1>")
	)
	(segment
		(start 244.282722 -60.484766)
		(end 240.5888 -59.749944)
		(width 0.14732)
		(layer "In4.Cu")
		(net "P3E_PCH_E1S_TX_DP<1>")
	)
	(segment
		(start 342.190578 -45.787056)
		(end 342.28024 -45.762672)
		(width 0.0889)
		(layer "In4.Cu")
		(net "P3E_PCH_E1S_TX_DP<1>")
	)
	(segment
		(start 310.353456 -21.38934)
		(end 304.166524 -22.61997)
		(width 0.14732)
		(layer "In4.Cu")
		(net "P3E_PCH_E1S_TX_DP<1>")
	)
	(segment
		(start 332.26629 -21.761958)
		(end 329.979274 -19.474942)
		(width 0.14732)
		(layer "In4.Cu")
		(net "P3E_PCH_E1S_TX_DP<1>")
	)
	(segment
		(start 345.996768 -31.897828)
		(end 339.648292 -25.549352)
		(width 0.14732)
		(layer "In4.Cu")
		(net "P3E_PCH_E1S_TX_DP<1>")
	)
	(segment
		(start 347.808296 -41.891966)
		(end 347.879924 -41.530524)
		(width 0.14732)
		(layer "In4.Cu")
		(net "P3E_PCH_E1S_TX_DP<1>")
	)
	(segment
		(start 310.885332 -21.43125)
		(end 310.52389 -21.503132)
		(width 0.14732)
		(layer "In4.Cu")
		(net "P3E_PCH_E1S_TX_DP<1>")
	)
	(segment
		(start 240.369344 -54.141878)
		(end 240.663984 -53.847238)
		(width 0.14732)
		(layer "In4.Cu")
		(net "P3E_PCH_E1S_TX_DP<1>")
	)
	(segment
		(start 294.78986 -27.026362)
		(end 284.642814 -38.222682)
		(width 0.14732)
		(layer "In4.Cu")
		(net "P3E_PCH_E1S_TX_DP<1>")
	)
	(segment
		(start 236.06506 -54.7116)
		(end 236.634782 -54.141878)
		(width 0.14732)
		(layer "In4.Cu")
		(net "P3E_PCH_E1S_TX_DP<1>")
	)
	(segment
		(start 329.979274 -19.474942)
		(end 328.096118 -18.694908)
		(width 0.14732)
		(layer "In4.Cu")
		(net "P3E_PCH_E1S_TX_DP<1>")
	)
	(segment
		(start 346.686378 -45.698918)
		(end 347.325696 -45.0596)
		(width 0.14732)
		(layer "In4.Cu")
		(net "P3E_PCH_E1S_TX_DP<1>")
	)
	(segment
		(start 334.051656 -22.501352)
		(end 332.26629 -21.761958)
		(width 0.14732)
		(layer "In4.Cu")
		(net "P3E_PCH_E1S_TX_DP<1>")
	)
	(segment
		(start 240.5888 -59.749944)
		(end 238.936276 -59.065414)
		(width 0.14732)
		(layer "In4.Cu")
		(net "P3E_PCH_E1S_TX_DP<1>")
	)
	(segment
		(start 304.166524 -22.61997)
		(end 300.00194 -24.34463)
		(width 0.14732)
		(layer "In4.Cu")
		(net "P3E_PCH_E1S_TX_DP<1>")
	)
	(segment
		(start 300.001686 -24.345646)
		(end 296.848276 -25.650952)
		(width 0.14732)
		(layer "In4.Cu")
		(net "P3E_PCH_E1S_TX_DP<1>")
	)
	(segment
		(start 345.590622 -45.698918)
		(end 345.61272 -45.698918)
		(width 0.0889)
		(layer "In4.Cu")
		(net "P3E_PCH_E1S_TX_DP<1>")
	)
	(arc
		(start 342.742266 -45.535342)
		(mid 342.925665 -45.483366)
		(end 343.059766 -45.34789)
		(width 0.0889)
		(layer "In4.Cu")
		(net "P3E_PCH_E1S_TX_DP<1>")
	)
	(arc
		(start 343.059766 -45.34789)
		(mid 343.258747 -45.145604)
		(end 343.530936 -45.065442)
		(width 0.0889)
		(layer "In4.Cu")
		(net "P3E_PCH_E1S_TX_DP<1>")
	)
	(arc
		(start 343.559384 -45.065442)
		(mid 343.836333 -45.143553)
		(end 344.038936 -45.34789)
		(width 0.0889)
		(layer "In4.Cu")
		(net "P3E_PCH_E1S_TX_DP<1>")
	)
	(arc
		(start 344.044016 -45.35678)
		(mid 344.180376 -45.487694)
		(end 344.363294 -45.535342)
		(width 0.0889)
		(layer "In4.Cu")
		(net "P3E_PCH_E1S_TX_DP<1>")
	)
	(arc
		(start 342.28024 -45.762672)
		(mid 342.463678 -45.603223)
		(end 342.697054 -45.535342)
		(width 0.0889)
		(layer "In4.Cu")
		(net "P3E_PCH_E1S_TX_DP<1>")
	)
	(segment
		(start 239.721644 -52.34051)
		(end 239.419384 -52.03825)
		(width 0.13208)
		(layer "F.Cu")
		(net "P3E_PCH_E1S_TX_DP<0>")
	)
	(segment
		(start 242.00612 -52.34051)
		(end 239.721644 -52.34051)
		(width 0.13208)
		(layer "F.Cu")
		(net "P3E_PCH_E1S_TX_DP<0>")
	)
	(segment
		(start 242.30838 -52.03825)
		(end 242.00612 -52.34051)
		(width 0.13208)
		(layer "F.Cu")
		(net "P3E_PCH_E1S_TX_DP<0>")
	)
	(segment
		(start 344.63355 -44.691046)
		(end 344.363294 -44.220892)
		(width 0.13208)
		(layer "F.Cu")
		(net "P3E_PCH_E1S_TX_DP<0>")
	)
	(segment
		(start 239.419384 -52.03825)
		(end 239.419384 -52.01285)
		(width 0.13208)
		(layer "F.Cu")
		(net "P3E_PCH_E1S_TX_DP<0>")
	)
	(segment
		(start 344.754708 -44.595796)
		(end 344.917014 -44.758102)
		(width 0.0889)
		(layer "In4.Cu")
		(net "P3E_PCH_E1S_TX_DP<0>")
	)
	(segment
		(start 295.452038 -27.70251)
		(end 285.66364 -38.503098)
		(width 0.14732)
		(layer "In4.Cu")
		(net "P3E_PCH_E1S_TX_DP<0>")
	)
	(segment
		(start 246.207026 -62.593728)
		(end 243.06784 -61.969396)
		(width 0.14732)
		(layer "In4.Cu")
		(net "P3E_PCH_E1S_TX_DP<0>")
	)
	(segment
		(start 314.101734 -21.940266)
		(end 313.9313 -21.826474)
		(width 0.14732)
		(layer "In4.Cu")
		(net "P3E_PCH_E1S_TX_DP<0>")
	)
	(segment
		(start 268.732508 -61.812932)
		(end 252.834648 -62.593728)
		(width 0.14732)
		(layer "In4.Cu")
		(net "P3E_PCH_E1S_TX_DP<0>")
	)
	(segment
		(start 341.153496 -31.21279)
		(end 340.812882 -31.07182)
		(width 0.14732)
		(layer "In4.Cu")
		(net "P3E_PCH_E1S_TX_DP<0>")
	)
	(segment
		(start 280.342086 -48.466248)
		(end 276.793198 -57.033414)
		(width 0.14732)
		(layer "In4.Cu")
		(net "P3E_PCH_E1S_TX_DP<0>")
	)
	(segment
		(start 346.25026 -41.594278)
		(end 345.3892 -37.246814)
		(width 0.14732)
		(layer "In4.Cu")
		(net "P3E_PCH_E1S_TX_DP<0>")
	)
	(segment
		(start 329.468734 -20.323302)
		(end 327.965816 -19.700748)
		(width 0.14732)
		(layer "In4.Cu")
		(net "P3E_PCH_E1S_TX_DP<0>")
	)
	(segment
		(start 307.923438 -23.169372)
		(end 307.753004 -23.05558)
		(width 0.14732)
		(layer "In4.Cu")
		(net "P3E_PCH_E1S_TX_DP<0>")
	)
	(segment
		(start 344.092276 -44.377356)
		(end 344.071448 -44.455588)
		(width 0.0889)
		(layer "In4.Cu")
		(net "P3E_PCH_E1S_TX_DP<0>")
	)
	(segment
		(start 345.3892 -37.246814)
		(end 345.3892 -33.967674)
		(width 0.14732)
		(layer "In4.Cu")
		(net "P3E_PCH_E1S_TX_DP<0>")
	)
	(segment
		(start 342.147652 -31.624778)
		(end 342.069166 -31.435294)
		(width 0.14732)
		(layer "In4.Cu")
		(net "P3E_PCH_E1S_TX_DP<0>")
	)
	(segment
		(start 340.73465 -30.88259)
		(end 335.504282 -28.71597)
		(width 0.14732)
		(layer "In4.Cu")
		(net "P3E_PCH_E1S_TX_DP<0>")
	)
	(segment
		(start 344.9955 -33.01746)
		(end 344.363802 -32.385762)
		(width 0.14732)
		(layer "In4.Cu")
		(net "P3E_PCH_E1S_TX_DP<0>")
	)
	(segment
		(start 344.363294 -44.595542)
		(end 344.363548 -44.595796)
		(width 0.0889)
		(layer "In4.Cu")
		(net "P3E_PCH_E1S_TX_DP<0>")
	)
	(segment
		(start 276.793198 -57.033414)
		(end 274.627086 -59.199272)
		(width 0.14732)
		(layer "In4.Cu")
		(net "P3E_PCH_E1S_TX_DP<0>")
	)
	(segment
		(start 346.10548 -42.562018)
		(end 346.25026 -42.417238)
		(width 0.14732)
		(layer "In4.Cu")
		(net "P3E_PCH_E1S_TX_DP<0>")
	)
	(segment
		(start 308.28488 -23.09749)
		(end 307.923438 -23.169372)
		(width 0.14732)
		(layer "In4.Cu")
		(net "P3E_PCH_E1S_TX_DP<0>")
	)
	(segment
		(start 324.616826 -19.700748)
		(end 317.868554 -21.043138)
		(width 0.14732)
		(layer "In4.Cu")
		(net "P3E_PCH_E1S_TX_DP<0>")
	)
	(segment
		(start 317.22314 -21.171662)
		(end 314.576968 -21.69795)
		(width 0.14732)
		(layer "In4.Cu")
		(net "P3E_PCH_E1S_TX_DP<0>")
	)
	(segment
		(start 345.9607 -44.716192)
		(end 346.25026 -44.426632)
		(width 0.14732)
		(layer "In4.Cu")
		(net "P3E_PCH_E1S_TX_DP<0>")
	)
	(segment
		(start 236.152436 -59.104784)
		(end 234.74172 -57.694068)
		(width 0.14732)
		(layer "In4.Cu")
		(net "P3E_PCH_E1S_TX_DP<0>")
	)
	(segment
		(start 342.069166 -31.435294)
		(end 341.342726 -31.134304)
		(width 0.14732)
		(layer "In4.Cu")
		(net "P3E_PCH_E1S_TX_DP<0>")
	)
	(segment
		(start 317.868554 -21.043138)
		(end 317.754762 -21.213572)
		(width 0.14732)
		(layer "In4.Cu")
		(net "P3E_PCH_E1S_TX_DP<0>")
	)
	(segment
		(start 345.548712 -44.758102)
		(end 345.590622 -44.716192)
		(width 0.0889)
		(layer "In4.Cu")
		(net "P3E_PCH_E1S_TX_DP<0>")
	)
	(segment
		(start 344.363548 -44.595796)
		(end 344.754708 -44.595796)
		(width 0.0889)
		(layer "In4.Cu")
		(net "P3E_PCH_E1S_TX_DP<0>")
	)
	(segment
		(start 314.463176 -21.868384)
		(end 314.101734 -21.940266)
		(width 0.14732)
		(layer "In4.Cu")
		(net "P3E_PCH_E1S_TX_DP<0>")
	)
	(segment
		(start 274.627086 -59.199272)
		(end 268.732508 -61.812932)
		(width 0.14732)
		(layer "In4.Cu")
		(net "P3E_PCH_E1S_TX_DP<0>")
	)
	(segment
		(start 346.25026 -43.075098)
		(end 346.10548 -42.930318)
		(width 0.14732)
		(layer "In4.Cu")
		(net "P3E_PCH_E1S_TX_DP<0>")
	)
	(segment
		(start 234.74172 -53.259736)
		(end 235.67517 -52.326286)
		(width 0.14732)
		(layer "In4.Cu")
		(net "P3E_PCH_E1S_TX_DP<0>")
	)
	(segment
		(start 341.342726 -31.134304)
		(end 341.153496 -31.21279)
		(width 0.14732)
		(layer "In4.Cu")
		(net "P3E_PCH_E1S_TX_DP<0>")
	)
	(segment
		(start 242.020344 -52.326286)
		(end 242.30838 -52.03825)
		(width 0.14732)
		(layer "In4.Cu")
		(net "P3E_PCH_E1S_TX_DP<0>")
	)
	(segment
		(start 346.25026 -44.426632)
		(end 346.25026 -43.075098)
		(width 0.14732)
		(layer "In4.Cu")
		(net "P3E_PCH_E1S_TX_DP<0>")
	)
	(segment
		(start 285.66364 -38.503098)
		(end 280.342086 -48.466248)
		(width 0.14732)
		(layer "In4.Cu")
		(net "P3E_PCH_E1S_TX_DP<0>")
	)
	(segment
		(start 327.965816 -19.700748)
		(end 324.616826 -19.700748)
		(width 0.14732)
		(layer "In4.Cu")
		(net "P3E_PCH_E1S_TX_DP<0>")
	)
	(segment
		(start 252.834648 -62.593728)
		(end 246.207026 -62.593728)
		(width 0.14732)
		(layer "In4.Cu")
		(net "P3E_PCH_E1S_TX_DP<0>")
	)
	(segment
		(start 307.753004 -23.05558)
		(end 304.83302 -23.636224)
		(width 0.14732)
		(layer "In4.Cu")
		(net "P3E_PCH_E1S_TX_DP<0>")
	)
	(segment
		(start 335.504282 -28.71597)
		(end 332.147672 -25.35936)
		(width 0.14732)
		(layer "In4.Cu")
		(net "P3E_PCH_E1S_TX_DP<0>")
	)
	(segment
		(start 304.83302 -23.636224)
		(end 296.162222 -27.227784)
		(width 0.14732)
		(layer "In4.Cu")
		(net "P3E_PCH_E1S_TX_DP<0>")
	)
	(segment
		(start 311.323228 -22.49297)
		(end 310.961786 -22.564852)
		(width 0.14732)
		(layer "In4.Cu")
		(net "P3E_PCH_E1S_TX_DP<0>")
	)
	(segment
		(start 344.363294 -44.220892)
		(end 344.092276 -44.377356)
		(width 0.0889)
		(layer "In4.Cu")
		(net "P3E_PCH_E1S_TX_DP<0>")
	)
	(segment
		(start 342.677242 -31.687262)
		(end 342.488266 -31.765494)
		(width 0.14732)
		(layer "In4.Cu")
		(net "P3E_PCH_E1S_TX_DP<0>")
	)
	(segment
		(start 308.398672 -22.926802)
		(end 308.28488 -23.09749)
		(width 0.14732)
		(layer "In4.Cu")
		(net "P3E_PCH_E1S_TX_DP<0>")
	)
	(segment
		(start 345.590622 -44.716192)
		(end 345.61272 -44.716192)
		(width 0.0889)
		(layer "In4.Cu")
		(net "P3E_PCH_E1S_TX_DP<0>")
	)
	(segment
		(start 310.791606 -22.45106)
		(end 308.398672 -22.926802)
		(width 0.14732)
		(layer "In4.Cu")
		(net "P3E_PCH_E1S_TX_DP<0>")
	)
	(segment
		(start 317.39332 -21.285454)
		(end 317.22314 -21.171662)
		(width 0.14732)
		(layer "In4.Cu")
		(net "P3E_PCH_E1S_TX_DP<0>")
	)
	(segment
		(start 296.162222 -27.227784)
		(end 295.452038 -27.70251)
		(width 0.14732)
		(layer "In4.Cu")
		(net "P3E_PCH_E1S_TX_DP<0>")
	)
	(segment
		(start 345.61272 -44.716192)
		(end 345.9607 -44.716192)
		(width 0.14732)
		(layer "In4.Cu")
		(net "P3E_PCH_E1S_TX_DP<0>")
	)
	(segment
		(start 311.43702 -22.322536)
		(end 311.323228 -22.49297)
		(width 0.14732)
		(layer "In4.Cu")
		(net "P3E_PCH_E1S_TX_DP<0>")
	)
	(segment
		(start 313.9313 -21.826474)
		(end 311.43702 -22.322536)
		(width 0.14732)
		(layer "In4.Cu")
		(net "P3E_PCH_E1S_TX_DP<0>")
	)
	(segment
		(start 342.488266 -31.765494)
		(end 342.147652 -31.624778)
		(width 0.14732)
		(layer "In4.Cu")
		(net "P3E_PCH_E1S_TX_DP<0>")
	)
	(segment
		(start 310.961786 -22.564852)
		(end 310.791606 -22.45106)
		(width 0.14732)
		(layer "In4.Cu")
		(net "P3E_PCH_E1S_TX_DP<0>")
	)
	(segment
		(start 314.576968 -21.69795)
		(end 314.463176 -21.868384)
		(width 0.14732)
		(layer "In4.Cu")
		(net "P3E_PCH_E1S_TX_DP<0>")
	)
	(segment
		(start 344.363802 -32.385762)
		(end 342.677242 -31.687262)
		(width 0.14732)
		(layer "In4.Cu")
		(net "P3E_PCH_E1S_TX_DP<0>")
	)
	(segment
		(start 345.3892 -33.967674)
		(end 344.9955 -33.01746)
		(width 0.14732)
		(layer "In4.Cu")
		(net "P3E_PCH_E1S_TX_DP<0>")
	)
	(segment
		(start 330.480162 -21.33473)
		(end 329.468734 -20.323302)
		(width 0.14732)
		(layer "In4.Cu")
		(net "P3E_PCH_E1S_TX_DP<0>")
	)
	(segment
		(start 340.73465 -30.882336)
		(end 340.73465 -30.88259)
		(width 0.14732)
		(layer "In4.Cu")
		(net "P3E_PCH_E1S_TX_DP<0>")
	)
	(segment
		(start 235.67517 -52.326286)
		(end 242.020344 -52.326286)
		(width 0.14732)
		(layer "In4.Cu")
		(net "P3E_PCH_E1S_TX_DP<0>")
	)
	(segment
		(start 346.10548 -42.930318)
		(end 346.10548 -42.562018)
		(width 0.14732)
		(layer "In4.Cu")
		(net "P3E_PCH_E1S_TX_DP<0>")
	)
	(segment
		(start 317.754762 -21.213572)
		(end 317.39332 -21.285454)
		(width 0.14732)
		(layer "In4.Cu")
		(net "P3E_PCH_E1S_TX_DP<0>")
	)
	(segment
		(start 234.74172 -57.694068)
		(end 234.74172 -53.259736)
		(width 0.14732)
		(layer "In4.Cu")
		(net "P3E_PCH_E1S_TX_DP<0>")
	)
	(segment
		(start 340.812882 -31.07182)
		(end 340.73465 -30.882336)
		(width 0.14732)
		(layer "In4.Cu")
		(net "P3E_PCH_E1S_TX_DP<0>")
	)
	(segment
		(start 344.917014 -44.758102)
		(end 345.548712 -44.758102)
		(width 0.0889)
		(layer "In4.Cu")
		(net "P3E_PCH_E1S_TX_DP<0>")
	)
	(segment
		(start 243.06784 -61.969396)
		(end 236.152436 -59.104784)
		(width 0.14732)
		(layer "In4.Cu")
		(net "P3E_PCH_E1S_TX_DP<0>")
	)
	(segment
		(start 332.147672 -25.35936)
		(end 330.480162 -21.33473)
		(width 0.14732)
		(layer "In4.Cu")
		(net "P3E_PCH_E1S_TX_DP<0>")
	)
	(segment
		(start 346.25026 -42.417238)
		(end 346.25026 -41.594278)
		(width 0.14732)
		(layer "In4.Cu")
		(net "P3E_PCH_E1S_TX_DP<0>")
	)
	(arc
		(start 344.071448 -44.455588)
		(mid 344.201473 -44.558733)
		(end 344.363294 -44.595542)
		(width 0.0889)
		(layer "In4.Cu")
		(net "P3E_PCH_E1S_TX_DP<0>")
	)
	(segment
		(start 239.721644 -57.74055)
		(end 239.419384 -57.43829)
		(width 0.13208)
		(layer "F.Cu")
		(net "P3E_PCH_E1S_TX_DN<3>")
	)
	(segment
		(start 240.663984 -57.43829)
		(end 240.361724 -57.74055)
		(width 0.13208)
		(layer "F.Cu")
		(net "P3E_PCH_E1S_TX_DN<3>")
	)
	(segment
		(start 343.006934 -47.510192)
		(end 343.005156 -47.510446)
		(width 0.13208)
		(layer "F.Cu")
		(net "P3E_PCH_E1S_TX_DN<3>")
	)
	(segment
		(start 342.735154 -47.040292)
		(end 343.006934 -47.510192)
		(width 0.13208)
		(layer "F.Cu")
		(net "P3E_PCH_E1S_TX_DN<3>")
	)
	(segment
		(start 239.419384 -57.43829)
		(end 239.419384 -57.41289)
		(width 0.13208)
		(layer "F.Cu")
		(net "P3E_PCH_E1S_TX_DN<3>")
	)
	(segment
		(start 240.361724 -57.74055)
		(end 239.721644 -57.74055)
		(width 0.13208)
		(layer "F.Cu")
		(net "P3E_PCH_E1S_TX_DN<3>")
	)
	(segment
		(start 346.863416 -48.290988)
		(end 346.90558 -48.333152)
		(width 0.0889)
		(layer "In4.Cu")
		(net "P3E_PCH_E1S_TX_DN<3>")
	)
	(segment
		(start 281.95397 -37.90061)
		(end 278.92502 -43.572938)
		(width 0.14732)
		(layer "In4.Cu")
		(net "P3E_PCH_E1S_TX_DN<3>")
	)
	(segment
		(start 242.531646 -56.319928)
		(end 241.118644 -57.73293)
		(width 0.14732)
		(layer "In4.Cu")
		(net "P3E_PCH_E1S_TX_DN<3>")
	)
	(segment
		(start 342.735154 -47.040292)
		(end 343.006172 -46.884082)
		(width 0.0889)
		(layer "In4.Cu")
		(net "P3E_PCH_E1S_TX_DN<3>")
	)
	(segment
		(start 343.54643 -47.135542)
		(end 343.56802 -47.135542)
		(width 0.0889)
		(layer "In4.Cu")
		(net "P3E_PCH_E1S_TX_DN<3>")
	)
	(segment
		(start 274.31365 -54.705758)
		(end 272.342864 -56.676544)
		(width 0.14732)
		(layer "In4.Cu")
		(net "P3E_PCH_E1S_TX_DN<3>")
	)
	(segment
		(start 345.723718 -25.112726)
		(end 343.715086 -21.354288)
		(width 0.14732)
		(layer "In4.Cu")
		(net "P3E_PCH_E1S_TX_DN<3>")
	)
	(segment
		(start 278.92502 -43.572938)
		(end 274.31365 -54.705758)
		(width 0.14732)
		(layer "In4.Cu")
		(net "P3E_PCH_E1S_TX_DN<3>")
	)
	(segment
		(start 253.56693 -59.449208)
		(end 251.236734 -59.449208)
		(width 0.14732)
		(layer "In4.Cu")
		(net "P3E_PCH_E1S_TX_DN<3>")
	)
	(segment
		(start 350.82734 -36.1569)
		(end 350.82734 -31.15564)
		(width 0.14732)
		(layer "In4.Cu")
		(net "P3E_PCH_E1S_TX_DN<3>")
	)
	(segment
		(start 352.29292 -43.525186)
		(end 350.82734 -36.1569)
		(width 0.14732)
		(layer "In4.Cu")
		(net "P3E_PCH_E1S_TX_DN<3>")
	)
	(segment
		(start 343.715086 -21.354288)
		(end 343.389204 -20.867116)
		(width 0.14732)
		(layer "In4.Cu")
		(net "P3E_PCH_E1S_TX_DN<3>")
	)
	(segment
		(start 350.541336 -48.333152)
		(end 352.105722 -46.768766)
		(width 0.14732)
		(layer "In4.Cu")
		(net "P3E_PCH_E1S_TX_DN<3>")
	)
	(segment
		(start 339.957918 -18.572226)
		(end 338.364576 -17.507712)
		(width 0.14732)
		(layer "In4.Cu")
		(net "P3E_PCH_E1S_TX_DN<3>")
	)
	(segment
		(start 344.7669 -47.574708)
		(end 345.31046 -47.574708)
		(width 0.0889)
		(layer "In4.Cu")
		(net "P3E_PCH_E1S_TX_DN<3>")
	)
	(segment
		(start 343.006172 -46.884082)
		(end 343.095834 -46.908466)
		(width 0.0889)
		(layer "In4.Cu")
		(net "P3E_PCH_E1S_TX_DN<3>")
	)
	(segment
		(start 344.334084 -47.605442)
		(end 344.736166 -47.605442)
		(width 0.0889)
		(layer "In4.Cu")
		(net "P3E_PCH_E1S_TX_DN<3>")
	)
	(segment
		(start 352.29292 -46.316646)
		(end 352.29292 -43.525186)
		(width 0.14732)
		(layer "In4.Cu")
		(net "P3E_PCH_E1S_TX_DN<3>")
	)
	(segment
		(start 350.82734 -31.15564)
		(end 350.111568 -29.427424)
		(width 0.14732)
		(layer "In4.Cu")
		(net "P3E_PCH_E1S_TX_DN<3>")
	)
	(segment
		(start 346.927678 -48.333152)
		(end 350.541336 -48.333152)
		(width 0.14732)
		(layer "In4.Cu")
		(net "P3E_PCH_E1S_TX_DN<3>")
	)
	(segment
		(start 346.90558 -48.333152)
		(end 346.927678 -48.333152)
		(width 0.0889)
		(layer "In4.Cu")
		(net "P3E_PCH_E1S_TX_DN<3>")
	)
	(segment
		(start 338.364576 -17.507712)
		(end 338.364322 -17.507966)
		(width 0.14732)
		(layer "In4.Cu")
		(net "P3E_PCH_E1S_TX_DN<3>")
	)
	(segment
		(start 297.284902 -22.792182)
		(end 293.13251 -25.566878)
		(width 0.14732)
		(layer "In4.Cu")
		(net "P3E_PCH_E1S_TX_DN<3>")
	)
	(segment
		(start 346.02674 -48.290988)
		(end 346.863416 -48.290988)
		(width 0.0889)
		(layer "In4.Cu")
		(net "P3E_PCH_E1S_TX_DN<3>")
	)
	(segment
		(start 352.105722 -46.768766)
		(end 352.29292 -46.316646)
		(width 0.14732)
		(layer "In4.Cu")
		(net "P3E_PCH_E1S_TX_DN<3>")
	)
	(segment
		(start 343.52992 -47.135288)
		(end 343.54643 -47.135542)
		(width 0.0889)
		(layer "In4.Cu")
		(net "P3E_PCH_E1S_TX_DN<3>")
	)
	(segment
		(start 338.364322 -17.507966)
		(end 337.713574 -17.072864)
		(width 0.14732)
		(layer "In4.Cu")
		(net "P3E_PCH_E1S_TX_DN<3>")
	)
	(segment
		(start 344.736166 -47.605442)
		(end 344.7669 -47.574708)
		(width 0.0889)
		(layer "In4.Cu")
		(net "P3E_PCH_E1S_TX_DN<3>")
	)
	(segment
		(start 336.275934 -16.477488)
		(end 323.905118 -16.477488)
		(width 0.14732)
		(layer "In4.Cu")
		(net "P3E_PCH_E1S_TX_DN<3>")
	)
	(segment
		(start 251.236734 -59.449208)
		(end 250.18238 -59.012328)
		(width 0.14732)
		(layer "In4.Cu")
		(net "P3E_PCH_E1S_TX_DN<3>")
	)
	(segment
		(start 323.905118 -16.477488)
		(end 302.019716 -20.831048)
		(width 0.14732)
		(layer "In4.Cu")
		(net "P3E_PCH_E1S_TX_DN<3>")
	)
	(segment
		(start 293.13251 -25.566878)
		(end 281.95397 -37.90061)
		(width 0.14732)
		(layer "In4.Cu")
		(net "P3E_PCH_E1S_TX_DN<3>")
	)
	(segment
		(start 272.342864 -56.676544)
		(end 267.64996 -58.757312)
		(width 0.14732)
		(layer "In4.Cu")
		(net "P3E_PCH_E1S_TX_DN<3>")
	)
	(segment
		(start 250.18238 -59.012328)
		(end 244.489478 -56.319928)
		(width 0.14732)
		(layer "In4.Cu")
		(net "P3E_PCH_E1S_TX_DN<3>")
	)
	(segment
		(start 244.489478 -56.319928)
		(end 242.531646 -56.319928)
		(width 0.14732)
		(layer "In4.Cu")
		(net "P3E_PCH_E1S_TX_DN<3>")
	)
	(segment
		(start 347.515688 -26.831544)
		(end 346.839032 -26.551128)
		(width 0.14732)
		(layer "In4.Cu")
		(net "P3E_PCH_E1S_TX_DN<3>")
	)
	(segment
		(start 345.31046 -47.574708)
		(end 346.02674 -48.290988)
		(width 0.0889)
		(layer "In4.Cu")
		(net "P3E_PCH_E1S_TX_DN<3>")
	)
	(segment
		(start 267.64996 -58.757312)
		(end 253.56693 -59.449208)
		(width 0.14732)
		(layer "In4.Cu")
		(net "P3E_PCH_E1S_TX_DN<3>")
	)
	(segment
		(start 240.958624 -57.73293)
		(end 240.663984 -57.43829)
		(width 0.14732)
		(layer "In4.Cu")
		(net "P3E_PCH_E1S_TX_DN<3>")
	)
	(segment
		(start 346.839032 -26.551128)
		(end 346.374212 -26.086308)
		(width 0.14732)
		(layer "In4.Cu")
		(net "P3E_PCH_E1S_TX_DN<3>")
	)
	(segment
		(start 346.374212 -26.086308)
		(end 345.723718 -25.112726)
		(width 0.14732)
		(layer "In4.Cu")
		(net "P3E_PCH_E1S_TX_DN<3>")
	)
	(segment
		(start 302.019716 -20.831048)
		(end 297.284902 -22.792182)
		(width 0.14732)
		(layer "In4.Cu")
		(net "P3E_PCH_E1S_TX_DN<3>")
	)
	(segment
		(start 343.389204 -20.867116)
		(end 339.957918 -18.572226)
		(width 0.14732)
		(layer "In4.Cu")
		(net "P3E_PCH_E1S_TX_DN<3>")
	)
	(segment
		(start 337.713574 -17.072864)
		(end 336.275934 -16.477488)
		(width 0.14732)
		(layer "In4.Cu")
		(net "P3E_PCH_E1S_TX_DN<3>")
	)
	(segment
		(start 350.111568 -29.427424)
		(end 347.515688 -26.831544)
		(width 0.14732)
		(layer "In4.Cu")
		(net "P3E_PCH_E1S_TX_DN<3>")
	)
	(segment
		(start 241.118644 -57.73293)
		(end 240.958624 -57.73293)
		(width 0.14732)
		(layer "In4.Cu")
		(net "P3E_PCH_E1S_TX_DN<3>")
	)
	(arc
		(start 343.56802 -47.135542)
		(mid 343.744361 -47.190521)
		(end 343.873074 -47.322994)
		(width 0.0889)
		(layer "In4.Cu")
		(net "P3E_PCH_E1S_TX_DN<3>")
	)
	(arc
		(start 343.873074 -47.322994)
		(mid 344.067668 -47.522829)
		(end 344.334084 -47.605442)
		(width 0.0889)
		(layer "In4.Cu")
		(net "P3E_PCH_E1S_TX_DN<3>")
	)
	(arc
		(start 343.095834 -46.908466)
		(mid 343.287042 -47.071328)
		(end 343.52992 -47.135288)
		(width 0.0889)
		(layer "In4.Cu")
		(net "P3E_PCH_E1S_TX_DN<3>")
	)
	(segment
		(start 242.062 -56.260746)
		(end 242.062 -57.692544)
		(width 0.13208)
		(layer "F.Cu")
		(net "P3E_PCH_E1S_TX_DN<2>")
	)
	(segment
		(start 241.741706 -55.940452)
		(end 242.062 -56.260746)
		(width 0.13208)
		(layer "F.Cu")
		(net "P3E_PCH_E1S_TX_DN<2>")
	)
	(segment
		(start 242.062 -57.692544)
		(end 242.371118 -58.001662)
		(width 0.13208)
		(layer "F.Cu")
		(net "P3E_PCH_E1S_TX_DN<2>")
	)
	(segment
		(start 241.448844 -55.940452)
		(end 241.741706 -55.940452)
		(width 0.13208)
		(layer "F.Cu")
		(net "P3E_PCH_E1S_TX_DN<2>")
	)
	(segment
		(start 242.371118 -58.001662)
		(end 242.815364 -58.001662)
		(width 0.13208)
		(layer "F.Cu")
		(net "P3E_PCH_E1S_TX_DN<2>")
	)
	(segment
		(start 344.63355 -47.510446)
		(end 344.363294 -47.040292)
		(width 0.13208)
		(layer "F.Cu")
		(net "P3E_PCH_E1S_TX_DN<2>")
	)
	(segment
		(start 241.121184 -55.612792)
		(end 241.448844 -55.940452)
		(width 0.13208)
		(layer "F.Cu")
		(net "P3E_PCH_E1S_TX_DN<2>")
	)
	(segment
		(start 242.815364 -58.001662)
		(end 243.117624 -57.699402)
		(width 0.13208)
		(layer "F.Cu")
		(net "P3E_PCH_E1S_TX_DN<2>")
	)
	(segment
		(start 344.84056 -46.927008)
		(end 344.579194 -46.665642)
		(width 0.0889)
		(layer "In4.Cu")
		(net "P3E_PCH_E1S_TX_DN<2>")
	)
	(segment
		(start 349.342202 -30.065218)
		(end 349.81134 -31.198058)
		(width 0.14732)
		(layer "In4.Cu")
		(net "P3E_PCH_E1S_TX_DN<2>")
	)
	(segment
		(start 245.080282 -59.242198)
		(end 245.866158 -59.567826)
		(width 0.14732)
		(layer "In4.Cu")
		(net "P3E_PCH_E1S_TX_DN<2>")
	)
	(segment
		(start 348.366588 -29.089604)
		(end 349.342202 -30.065218)
		(width 0.14732)
		(layer "In4.Cu")
		(net "P3E_PCH_E1S_TX_DN<2>")
	)
	(segment
		(start 245.866158 -59.567826)
		(end 249.944636 -60.378848)
		(width 0.14732)
		(layer "In4.Cu")
		(net "P3E_PCH_E1S_TX_DN<2>")
	)
	(segment
		(start 337.22183 -18.714212)
		(end 342.134952 -21.996908)
		(width 0.14732)
		(layer "In4.Cu")
		(net "P3E_PCH_E1S_TX_DN<2>")
	)
	(segment
		(start 344.579194 -46.665642)
		(end 344.452194 -46.665642)
		(width 0.0889)
		(layer "In4.Cu")
		(net "P3E_PCH_E1S_TX_DN<2>")
	)
	(segment
		(start 336.132678 -18.263108)
		(end 337.22183 -18.714212)
		(width 0.14732)
		(layer "In4.Cu")
		(net "P3E_PCH_E1S_TX_DN<2>")
	)
	(segment
		(start 344.452194 -46.665642)
		(end 344.363294 -46.754542)
		(width 0.0889)
		(layer "In4.Cu")
		(net "P3E_PCH_E1S_TX_DN<2>")
	)
	(segment
		(start 351.31502 -44.146724)
		(end 351.21469 -46.191678)
		(width 0.14732)
		(layer "In4.Cu")
		(net "P3E_PCH_E1S_TX_DN<2>")
	)
	(segment
		(start 332.376526 -18.263108)
		(end 336.132678 -18.263108)
		(width 0.14732)
		(layer "In4.Cu")
		(net "P3E_PCH_E1S_TX_DN<2>")
	)
	(segment
		(start 328.366628 -17.465548)
		(end 332.376526 -18.263108)
		(width 0.14732)
		(layer "In4.Cu")
		(net "P3E_PCH_E1S_TX_DN<2>")
	)
	(segment
		(start 323.792342 -17.465548)
		(end 328.366628 -17.465548)
		(width 0.14732)
		(layer "In4.Cu")
		(net "P3E_PCH_E1S_TX_DN<2>")
	)
	(segment
		(start 346.46108 -46.969172)
		(end 346.418916 -46.927008)
		(width 0.0889)
		(layer "In4.Cu")
		(net "P3E_PCH_E1S_TX_DN<2>")
	)
	(segment
		(start 345.577668 -27.14879)
		(end 346.91828 -28.489656)
		(width 0.14732)
		(layer "In4.Cu")
		(net "P3E_PCH_E1S_TX_DN<2>")
	)
	(segment
		(start 283.231844 -37.921438)
		(end 293.850314 -26.205688)
		(width 0.14732)
		(layer "In4.Cu")
		(net "P3E_PCH_E1S_TX_DN<2>")
	)
	(segment
		(start 350.437196 -46.969172)
		(end 346.483178 -46.969172)
		(width 0.14732)
		(layer "In4.Cu")
		(net "P3E_PCH_E1S_TX_DN<2>")
	)
	(segment
		(start 344.363294 -46.754542)
		(end 344.363294 -47.040292)
		(width 0.0889)
		(layer "In4.Cu")
		(net "P3E_PCH_E1S_TX_DN<2>")
	)
	(segment
		(start 346.483178 -46.969172)
		(end 346.46108 -46.969172)
		(width 0.0889)
		(layer "In4.Cu")
		(net "P3E_PCH_E1S_TX_DN<2>")
	)
	(segment
		(start 279.276302 -45.321982)
		(end 283.231844 -37.921438)
		(width 0.14732)
		(layer "In4.Cu")
		(net "P3E_PCH_E1S_TX_DN<2>")
	)
	(segment
		(start 243.117624 -57.699402)
		(end 243.412264 -57.994042)
		(width 0.14732)
		(layer "In4.Cu")
		(net "P3E_PCH_E1S_TX_DN<2>")
	)
	(segment
		(start 346.418916 -46.927008)
		(end 344.84056 -46.927008)
		(width 0.0889)
		(layer "In4.Cu")
		(net "P3E_PCH_E1S_TX_DN<2>")
	)
	(segment
		(start 349.81134 -36.586922)
		(end 351.31502 -44.146724)
		(width 0.14732)
		(layer "In4.Cu")
		(net "P3E_PCH_E1S_TX_DN<2>")
	)
	(segment
		(start 273.328384 -57.275476)
		(end 275.030184 -55.573676)
		(width 0.14732)
		(layer "In4.Cu")
		(net "P3E_PCH_E1S_TX_DN<2>")
	)
	(segment
		(start 296.902378 -24.166068)
		(end 303.181766 -21.565362)
		(width 0.14732)
		(layer "In4.Cu")
		(net "P3E_PCH_E1S_TX_DN<2>")
	)
	(segment
		(start 253.592584 -60.378848)
		(end 267.914882 -59.675268)
		(width 0.14732)
		(layer "In4.Cu")
		(net "P3E_PCH_E1S_TX_DN<2>")
	)
	(segment
		(start 346.91828 -28.489656)
		(end 348.366588 -29.089604)
		(width 0.14732)
		(layer "In4.Cu")
		(net "P3E_PCH_E1S_TX_DN<2>")
	)
	(segment
		(start 275.030184 -55.573676)
		(end 279.276302 -45.322236)
		(width 0.14732)
		(layer "In4.Cu")
		(net "P3E_PCH_E1S_TX_DN<2>")
	)
	(segment
		(start 249.944636 -60.378848)
		(end 253.592584 -60.378848)
		(width 0.14732)
		(layer "In4.Cu")
		(net "P3E_PCH_E1S_TX_DN<2>")
	)
	(segment
		(start 267.914882 -59.675268)
		(end 273.328384 -57.275476)
		(width 0.14732)
		(layer "In4.Cu")
		(net "P3E_PCH_E1S_TX_DN<2>")
	)
	(segment
		(start 293.850314 -26.205688)
		(end 296.902378 -24.166068)
		(width 0.14732)
		(layer "In4.Cu")
		(net "P3E_PCH_E1S_TX_DN<2>")
	)
	(segment
		(start 303.181766 -21.565362)
		(end 323.792342 -17.465548)
		(width 0.14732)
		(layer "In4.Cu")
		(net "P3E_PCH_E1S_TX_DN<2>")
	)
	(segment
		(start 243.832126 -57.994042)
		(end 245.080282 -59.242198)
		(width 0.14732)
		(layer "In4.Cu")
		(net "P3E_PCH_E1S_TX_DN<2>")
	)
	(segment
		(start 279.276302 -45.322236)
		(end 279.276302 -45.321982)
		(width 0.14732)
		(layer "In4.Cu")
		(net "P3E_PCH_E1S_TX_DN<2>")
	)
	(segment
		(start 351.21469 -46.191678)
		(end 350.437196 -46.969172)
		(width 0.14732)
		(layer "In4.Cu")
		(net "P3E_PCH_E1S_TX_DN<2>")
	)
	(segment
		(start 349.81134 -31.198058)
		(end 349.81134 -36.586922)
		(width 0.14732)
		(layer "In4.Cu")
		(net "P3E_PCH_E1S_TX_DN<2>")
	)
	(segment
		(start 342.134952 -21.996908)
		(end 345.577668 -27.14879)
		(width 0.14732)
		(layer "In4.Cu")
		(net "P3E_PCH_E1S_TX_DN<2>")
	)
	(segment
		(start 243.412264 -57.994042)
		(end 243.832126 -57.994042)
		(width 0.14732)
		(layer "In4.Cu")
		(net "P3E_PCH_E1S_TX_DN<2>")
	)
	(segment
		(start 239.419384 -54.710838)
		(end 239.419384 -54.736238)
		(width 0.13208)
		(layer "F.Cu")
		(net "P3E_PCH_E1S_TX_DN<1>")
	)
	(segment
		(start 239.721644 -54.408578)
		(end 239.419384 -54.710838)
		(width 0.13208)
		(layer "F.Cu")
		(net "P3E_PCH_E1S_TX_DN<1>")
	)
	(segment
		(start 342.735154 -46.100492)
		(end 343.006934 -46.570392)
		(width 0.13208)
		(layer "F.Cu")
		(net "P3E_PCH_E1S_TX_DN<1>")
	)
	(segment
		(start 240.663984 -54.710838)
		(end 240.361724 -54.408578)
		(width 0.13208)
		(layer "F.Cu")
		(net "P3E_PCH_E1S_TX_DN<1>")
	)
	(segment
		(start 343.006934 -46.570392)
		(end 343.005156 -46.570646)
		(width 0.13208)
		(layer "F.Cu")
		(net "P3E_PCH_E1S_TX_DN<1>")
	)
	(segment
		(start 240.361724 -54.408578)
		(end 239.721644 -54.408578)
		(width 0.13208)
		(layer "F.Cu")
		(net "P3E_PCH_E1S_TX_DN<1>")
	)
	(segment
		(start 339.823298 -25.335992)
		(end 336.40522 -23.052024)
		(width 0.14732)
		(layer "In4.Cu")
		(net "P3E_PCH_E1S_TX_DN<1>")
	)
	(segment
		(start 279.594056 -47.087536)
		(end 277.699216 -51.662076)
		(width 0.14732)
		(layer "In4.Cu")
		(net "P3E_PCH_E1S_TX_DN<1>")
	)
	(segment
		(start 343.542366 -45.255942)
		(end 343.549478 -45.255942)
		(width 0.0889)
		(layer "In4.Cu")
		(net "P3E_PCH_E1S_TX_DN<1>")
	)
	(segment
		(start 236.748574 -54.416198)
		(end 238.01959 -54.416198)
		(width 0.14732)
		(layer "In4.Cu")
		(net "P3E_PCH_E1S_TX_DN<1>")
	)
	(segment
		(start 348.78264 -39.141908)
		(end 348.78264 -37.34435)
		(width 0.14732)
		(layer "In4.Cu")
		(net "P3E_PCH_E1S_TX_DN<1>")
	)
	(segment
		(start 240.369344 -54.416198)
		(end 240.663984 -54.710838)
		(width 0.14732)
		(layer "In4.Cu")
		(net "P3E_PCH_E1S_TX_DN<1>")
	)
	(segment
		(start 249.867928 -61.316108)
		(end 244.336316 -60.215526)
		(width 0.14732)
		(layer "In4.Cu")
		(net "P3E_PCH_E1S_TX_DN<1>")
	)
	(segment
		(start 236.33938 -55.554118)
		(end 236.33938 -54.825392)
		(width 0.14732)
		(layer "In4.Cu")
		(net "P3E_PCH_E1S_TX_DN<1>")
	)
	(segment
		(start 238.53267 -54.560978)
		(end 238.67745 -54.416198)
		(width 0.14732)
		(layer "In4.Cu")
		(net "P3E_PCH_E1S_TX_DN<1>")
	)
	(segment
		(start 237.873032 -58.024776)
		(end 237.515146 -57.785762)
		(width 0.14732)
		(layer "In4.Cu")
		(net "P3E_PCH_E1S_TX_DN<1>")
	)
	(segment
		(start 342.735154 -46.100492)
		(end 342.463374 -45.944282)
		(width 0.0889)
		(layer "In4.Cu")
		(net "P3E_PCH_E1S_TX_DN<1>")
	)
	(segment
		(start 274.018756 -58.021982)
		(end 268.124432 -60.635134)
		(width 0.14732)
		(layer "In4.Cu")
		(net "P3E_PCH_E1S_TX_DN<1>")
	)
	(segment
		(start 345.61272 -45.973238)
		(end 346.80017 -45.973238)
		(width 0.14732)
		(layer "In4.Cu")
		(net "P3E_PCH_E1S_TX_DN<1>")
	)
	(segment
		(start 238.67745 -54.416198)
		(end 239.05845 -54.416198)
		(width 0.14732)
		(layer "In4.Cu")
		(net "P3E_PCH_E1S_TX_DN<1>")
	)
	(segment
		(start 284.416754 -38.063424)
		(end 279.594056 -47.087536)
		(width 0.14732)
		(layer "In4.Cu")
		(net "P3E_PCH_E1S_TX_DN<1>")
	)
	(segment
		(start 244.336316 -60.21578)
		(end 244.240558 -60.072016)
		(width 0.14732)
		(layer "In4.Cu")
		(net "P3E_PCH_E1S_TX_DN<1>")
	)
	(segment
		(start 348.450154 -36.248848)
		(end 347.518228 -34.854134)
		(width 0.14732)
		(layer "In4.Cu")
		(net "P3E_PCH_E1S_TX_DN<1>")
	)
	(segment
		(start 277.699216 -51.662076)
		(end 277.699216 -51.66233)
		(width 0.14732)
		(layer "In4.Cu")
		(net "P3E_PCH_E1S_TX_DN<1>")
	)
	(segment
		(start 330.134722 -19.242278)
		(end 328.150728 -18.420588)
		(width 0.14732)
		(layer "In4.Cu")
		(net "P3E_PCH_E1S_TX_DN<1>")
	)
	(segment
		(start 236.33938 -56.211978)
		(end 236.48416 -56.067198)
		(width 0.14732)
		(layer "In4.Cu")
		(net "P3E_PCH_E1S_TX_DN<1>")
	)
	(segment
		(start 344.353388 -45.725842)
		(end 344.629994 -45.725842)
		(width 0.0889)
		(layer "In4.Cu")
		(net "P3E_PCH_E1S_TX_DN<1>")
	)
	(segment
		(start 236.48416 -55.698898)
		(end 236.33938 -55.554118)
		(width 0.14732)
		(layer "In4.Cu")
		(net "P3E_PCH_E1S_TX_DN<1>")
	)
	(segment
		(start 275.80463 -56.236362)
		(end 274.018756 -58.021982)
		(width 0.14732)
		(layer "In4.Cu")
		(net "P3E_PCH_E1S_TX_DN<1>")
	)
	(segment
		(start 239.71631 -54.416198)
		(end 240.369344 -54.416198)
		(width 0.14732)
		(layer "In4.Cu")
		(net "P3E_PCH_E1S_TX_DN<1>")
	)
	(segment
		(start 239.05845 -54.416198)
		(end 239.20323 -54.560978)
		(width 0.14732)
		(layer "In4.Cu")
		(net "P3E_PCH_E1S_TX_DN<1>")
	)
	(segment
		(start 239.066324 -58.822082)
		(end 238.420148 -58.390536)
		(width 0.14732)
		(layer "In4.Cu")
		(net "P3E_PCH_E1S_TX_DN<1>")
	)
	(segment
		(start 244.240558 -60.072016)
		(end 243.811806 -59.986926)
		(width 0.14732)
		(layer "In4.Cu")
		(net "P3E_PCH_E1S_TX_DN<1>")
	)
	(segment
		(start 344.629994 -45.725842)
		(end 344.835226 -45.931074)
		(width 0.0889)
		(layer "In4.Cu")
		(net "P3E_PCH_E1S_TX_DN<1>")
	)
	(segment
		(start 240.66881 -59.486038)
		(end 239.066324 -58.822082)
		(width 0.14732)
		(layer "In4.Cu")
		(net "P3E_PCH_E1S_TX_DN<1>")
	)
	(segment
		(start 334.150462 -22.24532)
		(end 332.421738 -21.529294)
		(width 0.14732)
		(layer "In4.Cu")
		(net "P3E_PCH_E1S_TX_DN<1>")
	)
	(segment
		(start 348.78264 -37.34435)
		(end 348.450154 -36.248848)
		(width 0.14732)
		(layer "In4.Cu")
		(net "P3E_PCH_E1S_TX_DN<1>")
	)
	(segment
		(start 343.873328 -45.442632)
		(end 343.873836 -45.443394)
		(width 0.0889)
		(layer "In4.Cu")
		(net "P3E_PCH_E1S_TX_DN<1>")
	)
	(segment
		(start 238.073692 -57.984898)
		(end 237.873032 -58.024776)
		(width 0.14732)
		(layer "In4.Cu")
		(net "P3E_PCH_E1S_TX_DN<1>")
	)
	(segment
		(start 239.57153 -54.560978)
		(end 239.71631 -54.416198)
		(width 0.14732)
		(layer "In4.Cu")
		(net "P3E_PCH_E1S_TX_DN<1>")
	)
	(segment
		(start 345.548458 -45.931074)
		(end 345.590622 -45.973238)
		(width 0.0889)
		(layer "In4.Cu")
		(net "P3E_PCH_E1S_TX_DN<1>")
	)
	(segment
		(start 346.80017 -45.973238)
		(end 347.57868 -45.194728)
		(width 0.14732)
		(layer "In4.Cu")
		(net "P3E_PCH_E1S_TX_DN<1>")
	)
	(segment
		(start 236.33938 -56.609996)
		(end 236.33938 -56.211978)
		(width 0.14732)
		(layer "In4.Cu")
		(net "P3E_PCH_E1S_TX_DN<1>")
	)
	(segment
		(start 238.16437 -54.560978)
		(end 238.53267 -54.560978)
		(width 0.14732)
		(layer "In4.Cu")
		(net "P3E_PCH_E1S_TX_DN<1>")
	)
	(segment
		(start 342.463374 -45.944282)
		(end 342.442292 -45.86605)
		(width 0.0889)
		(layer "In4.Cu")
		(net "P3E_PCH_E1S_TX_DN<1>")
	)
	(segment
		(start 299.897038 -24.091138)
		(end 299.896276 -24.091392)
		(width 0.14732)
		(layer "In4.Cu")
		(net "P3E_PCH_E1S_TX_DN<1>")
	)
	(segment
		(start 236.48416 -56.067198)
		(end 236.48416 -55.698898)
		(width 0.14732)
		(layer "In4.Cu")
		(net "P3E_PCH_E1S_TX_DN<1>")
	)
	(segment
		(start 342.711786 -45.725842)
		(end 342.753696 -45.725842)
		(width 0.0889)
		(layer "In4.Cu")
		(net "P3E_PCH_E1S_TX_DN<1>")
	)
	(segment
		(start 323.870574 -18.420588)
		(end 304.086514 -22.356064)
		(width 0.14732)
		(layer "In4.Cu")
		(net "P3E_PCH_E1S_TX_DN<1>")
	)
	(segment
		(start 236.33938 -54.825392)
		(end 236.748574 -54.416198)
		(width 0.14732)
		(layer "In4.Cu")
		(net "P3E_PCH_E1S_TX_DN<1>")
	)
	(segment
		(start 304.086514 -22.356064)
		(end 299.897038 -24.091138)
		(width 0.14732)
		(layer "In4.Cu")
		(net "P3E_PCH_E1S_TX_DN<1>")
	)
	(segment
		(start 336.40522 -23.052024)
		(end 334.150462 -22.24532)
		(width 0.14732)
		(layer "In4.Cu")
		(net "P3E_PCH_E1S_TX_DN<1>")
	)
	(segment
		(start 294.609266 -26.817066)
		(end 284.416754 -38.063424)
		(width 0.14732)
		(layer "In4.Cu")
		(net "P3E_PCH_E1S_TX_DN<1>")
	)
	(segment
		(start 345.590622 -45.973238)
		(end 345.61272 -45.973238)
		(width 0.0889)
		(layer "In4.Cu")
		(net "P3E_PCH_E1S_TX_DN<1>")
	)
	(segment
		(start 344.835226 -45.931074)
		(end 345.548458 -45.931074)
		(width 0.0889)
		(layer "In4.Cu")
		(net "P3E_PCH_E1S_TX_DN<1>")
	)
	(segment
		(start 299.833284 -24.117554)
		(end 299.83303 -24.11857)
		(width 0.14732)
		(layer "In4.Cu")
		(net "P3E_PCH_E1S_TX_DN<1>")
	)
	(segment
		(start 239.20323 -54.560978)
		(end 239.57153 -54.560978)
		(width 0.14732)
		(layer "In4.Cu")
		(net "P3E_PCH_E1S_TX_DN<1>")
	)
	(segment
		(start 254.259588 -61.316108)
		(end 249.867928 -61.316108)
		(width 0.14732)
		(layer "In4.Cu")
		(net "P3E_PCH_E1S_TX_DN<1>")
	)
	(segment
		(start 244.336316 -60.215526)
		(end 244.336316 -60.21578)
		(width 0.14732)
		(layer "In4.Cu")
		(net "P3E_PCH_E1S_TX_DN<1>")
	)
	(segment
		(start 296.718228 -25.40762)
		(end 294.609266 -26.817066)
		(width 0.14732)
		(layer "In4.Cu")
		(net "P3E_PCH_E1S_TX_DN<1>")
	)
	(segment
		(start 243.668296 -60.082684)
		(end 240.66881 -59.486038)
		(width 0.14732)
		(layer "In4.Cu")
		(net "P3E_PCH_E1S_TX_DN<1>")
	)
	(segment
		(start 343.868756 -45.434504)
		(end 343.873328 -45.442632)
		(width 0.0889)
		(layer "In4.Cu")
		(net "P3E_PCH_E1S_TX_DN<1>")
	)
	(segment
		(start 237.515146 -57.785762)
		(end 236.33938 -56.609996)
		(width 0.14732)
		(layer "In4.Cu")
		(net "P3E_PCH_E1S_TX_DN<1>")
	)
	(segment
		(start 299.896276 -24.091392)
		(end 299.833284 -24.117554)
		(width 0.14732)
		(layer "In4.Cu")
		(net "P3E_PCH_E1S_TX_DN<1>")
	)
	(segment
		(start 238.38027 -58.189622)
		(end 238.073692 -57.984898)
		(width 0.14732)
		(layer "In4.Cu")
		(net "P3E_PCH_E1S_TX_DN<1>")
	)
	(segment
		(start 268.124432 -60.635134)
		(end 254.259588 -61.316108)
		(width 0.14732)
		(layer "In4.Cu")
		(net "P3E_PCH_E1S_TX_DN<1>")
	)
	(segment
		(start 299.83303 -24.11857)
		(end 296.718228 -25.40762)
		(width 0.14732)
		(layer "In4.Cu")
		(net "P3E_PCH_E1S_TX_DN<1>")
	)
	(segment
		(start 346.229432 -31.74238)
		(end 339.823298 -25.335992)
		(width 0.14732)
		(layer "In4.Cu")
		(net "P3E_PCH_E1S_TX_DN<1>")
	)
	(segment
		(start 238.01959 -54.416198)
		(end 238.16437 -54.560978)
		(width 0.14732)
		(layer "In4.Cu")
		(net "P3E_PCH_E1S_TX_DN<1>")
	)
	(segment
		(start 332.421738 -21.529294)
		(end 330.134722 -19.242278)
		(width 0.14732)
		(layer "In4.Cu")
		(net "P3E_PCH_E1S_TX_DN<1>")
	)
	(segment
		(start 243.811806 -59.986926)
		(end 243.668296 -60.082684)
		(width 0.14732)
		(layer "In4.Cu")
		(net "P3E_PCH_E1S_TX_DN<1>")
	)
	(segment
		(start 277.699216 -51.66233)
		(end 275.80463 -56.236362)
		(width 0.14732)
		(layer "In4.Cu")
		(net "P3E_PCH_E1S_TX_DN<1>")
	)
	(segment
		(start 347.57868 -45.194728)
		(end 348.78264 -39.141908)
		(width 0.14732)
		(layer "In4.Cu")
		(net "P3E_PCH_E1S_TX_DN<1>")
	)
	(segment
		(start 238.420148 -58.390536)
		(end 238.38027 -58.189622)
		(width 0.14732)
		(layer "In4.Cu")
		(net "P3E_PCH_E1S_TX_DN<1>")
	)
	(segment
		(start 347.518228 -34.854134)
		(end 346.229432 -31.74238)
		(width 0.14732)
		(layer "In4.Cu")
		(net "P3E_PCH_E1S_TX_DN<1>")
	)
	(segment
		(start 328.150728 -18.420588)
		(end 323.870574 -18.420588)
		(width 0.14732)
		(layer "In4.Cu")
		(net "P3E_PCH_E1S_TX_DN<1>")
	)
	(arc
		(start 343.873836 -45.443394)
		(mid 344.076441 -45.647729)
		(end 344.353388 -45.725842)
		(width 0.0889)
		(layer "In4.Cu")
		(net "P3E_PCH_E1S_TX_DN<1>")
	)
	(arc
		(start 342.753696 -45.725842)
		(mid 343.025885 -45.64568)
		(end 343.224866 -45.443394)
		(width 0.0889)
		(layer "In4.Cu")
		(net "P3E_PCH_E1S_TX_DN<1>")
	)
	(arc
		(start 343.224866 -45.443394)
		(mid 343.358965 -45.307914)
		(end 343.542366 -45.255942)
		(width 0.0889)
		(layer "In4.Cu")
		(net "P3E_PCH_E1S_TX_DN<1>")
	)
	(arc
		(start 343.549478 -45.255942)
		(mid 343.732378 -45.303621)
		(end 343.868756 -45.434504)
		(width 0.0889)
		(layer "In4.Cu")
		(net "P3E_PCH_E1S_TX_DN<1>")
	)
	(arc
		(start 342.442292 -45.86605)
		(mid 342.562229 -45.767492)
		(end 342.711786 -45.725842)
		(width 0.0889)
		(layer "In4.Cu")
		(net "P3E_PCH_E1S_TX_DN<1>")
	)
	(segment
		(start 343.821258 -45.160692)
		(end 343.81948 -45.160946)
		(width 0.13208)
		(layer "F.Cu")
		(net "P3E_PCH_E1S_TX_DN<0>")
	)
	(segment
		(start 239.419384 -52.90185)
		(end 239.419384 -52.92725)
		(width 0.13208)
		(layer "F.Cu")
		(net "P3E_PCH_E1S_TX_DN<0>")
	)
	(segment
		(start 239.721644 -52.59959)
		(end 239.419384 -52.90185)
		(width 0.13208)
		(layer "F.Cu")
		(net "P3E_PCH_E1S_TX_DN<0>")
	)
	(segment
		(start 242.30838 -52.90185)
		(end 242.00612 -52.59959)
		(width 0.13208)
		(layer "F.Cu")
		(net "P3E_PCH_E1S_TX_DN<0>")
	)
	(segment
		(start 242.00612 -52.59959)
		(end 239.721644 -52.59959)
		(width 0.13208)
		(layer "F.Cu")
		(net "P3E_PCH_E1S_TX_DN<0>")
	)
	(segment
		(start 343.549478 -44.690792)
		(end 343.821258 -45.160692)
		(width 0.13208)
		(layer "F.Cu")
		(net "P3E_PCH_E1S_TX_DN<0>")
	)
	(segment
		(start 238.73333 -52.600606)
		(end 238.87811 -52.745386)
		(width 0.14732)
		(layer "In4.Cu")
		(net "P3E_PCH_E1S_TX_DN<0>")
	)
	(segment
		(start 235.500926 -57.860438)
		(end 235.296202 -57.860438)
		(width 0.14732)
		(layer "In4.Cu")
		(net "P3E_PCH_E1S_TX_DN<0>")
	)
	(segment
		(start 235.01604 -57.580276)
		(end 235.01604 -56.102758)
		(width 0.14732)
		(layer "In4.Cu")
		(net "P3E_PCH_E1S_TX_DN<0>")
	)
	(segment
		(start 235.76153 -58.325766)
		(end 235.76153 -58.121042)
		(width 0.14732)
		(layer "In4.Cu")
		(net "P3E_PCH_E1S_TX_DN<0>")
	)
	(segment
		(start 235.76153 -58.121042)
		(end 235.500926 -57.860438)
		(width 0.14732)
		(layer "In4.Cu")
		(net "P3E_PCH_E1S_TX_DN<0>")
	)
	(segment
		(start 278.327104 -52.61356)
		(end 278.32685 -52.61356)
		(width 0.14732)
		(layer "In4.Cu")
		(net "P3E_PCH_E1S_TX_DN<0>")
	)
	(segment
		(start 285.437326 -38.34384)
		(end 280.093674 -48.3489)
		(width 0.14732)
		(layer "In4.Cu")
		(net "P3E_PCH_E1S_TX_DN<0>")
	)
	(segment
		(start 332.380336 -25.203912)
		(end 330.712826 -21.179282)
		(width 0.14732)
		(layer "In4.Cu")
		(net "P3E_PCH_E1S_TX_DN<0>")
	)
	(segment
		(start 235.01604 -53.971698)
		(end 235.01604 -53.373528)
		(width 0.14732)
		(layer "In4.Cu")
		(net "P3E_PCH_E1S_TX_DN<0>")
	)
	(segment
		(start 346.074492 -44.990512)
		(end 346.52458 -44.540424)
		(width 0.14732)
		(layer "In4.Cu")
		(net "P3E_PCH_E1S_TX_DN<0>")
	)
	(segment
		(start 235.296202 -57.860438)
		(end 235.01604 -57.580276)
		(width 0.14732)
		(layer "In4.Cu")
		(net "P3E_PCH_E1S_TX_DN<0>")
	)
	(segment
		(start 243.14785 -61.70549)
		(end 236.307884 -58.87212)
		(width 0.14732)
		(layer "In4.Cu")
		(net "P3E_PCH_E1S_TX_DN<0>")
	)
	(segment
		(start 235.16082 -55.589678)
		(end 235.01604 -55.444898)
		(width 0.14732)
		(layer "In4.Cu")
		(net "P3E_PCH_E1S_TX_DN<0>")
	)
	(segment
		(start 235.788962 -52.600606)
		(end 236.86897 -52.600606)
		(width 0.14732)
		(layer "In4.Cu")
		(net "P3E_PCH_E1S_TX_DN<0>")
	)
	(segment
		(start 296.032174 -26.984706)
		(end 295.271444 -27.493214)
		(width 0.14732)
		(layer "In4.Cu")
		(net "P3E_PCH_E1S_TX_DN<0>")
	)
	(segment
		(start 330.712826 -21.179282)
		(end 329.624182 -20.090638)
		(width 0.14732)
		(layer "In4.Cu")
		(net "P3E_PCH_E1S_TX_DN<0>")
	)
	(segment
		(start 278.32685 -52.61356)
		(end 276.560534 -56.877966)
		(width 0.14732)
		(layer "In4.Cu")
		(net "P3E_PCH_E1S_TX_DN<0>")
	)
	(segment
		(start 252.82779 -62.319408)
		(end 246.234204 -62.319408)
		(width 0.14732)
		(layer "In4.Cu")
		(net "P3E_PCH_E1S_TX_DN<0>")
	)
	(segment
		(start 329.624182 -20.090638)
		(end 328.82205 -19.758406)
		(width 0.14732)
		(layer "In4.Cu")
		(net "P3E_PCH_E1S_TX_DN<0>")
	)
	(segment
		(start 235.01604 -56.102758)
		(end 235.16082 -55.957978)
		(width 0.14732)
		(layer "In4.Cu")
		(net "P3E_PCH_E1S_TX_DN<0>")
	)
	(segment
		(start 246.234204 -62.319408)
		(end 243.14785 -61.70549)
		(width 0.14732)
		(layer "In4.Cu")
		(net "P3E_PCH_E1S_TX_DN<0>")
	)
	(segment
		(start 237.52683 -52.600606)
		(end 238.73333 -52.600606)
		(width 0.14732)
		(layer "In4.Cu")
		(net "P3E_PCH_E1S_TX_DN<0>")
	)
	(segment
		(start 345.61272 -44.990512)
		(end 346.074492 -44.990512)
		(width 0.14732)
		(layer "In4.Cu")
		(net "P3E_PCH_E1S_TX_DN<0>")
	)
	(segment
		(start 242.007136 -52.600606)
		(end 242.30838 -52.90185)
		(width 0.14732)
		(layer "In4.Cu")
		(net "P3E_PCH_E1S_TX_DN<0>")
	)
	(segment
		(start 238.87811 -52.745386)
		(end 239.24641 -52.745386)
		(width 0.14732)
		(layer "In4.Cu")
		(net "P3E_PCH_E1S_TX_DN<0>")
	)
	(segment
		(start 343.820496 -44.534328)
		(end 343.90965 -44.558458)
		(width 0.0889)
		(layer "In4.Cu")
		(net "P3E_PCH_E1S_TX_DN<0>")
	)
	(segment
		(start 239.24641 -52.745386)
		(end 239.39119 -52.600606)
		(width 0.14732)
		(layer "In4.Cu")
		(net "P3E_PCH_E1S_TX_DN<0>")
	)
	(segment
		(start 236.86897 -52.600606)
		(end 237.01375 -52.745386)
		(width 0.14732)
		(layer "In4.Cu")
		(net "P3E_PCH_E1S_TX_DN<0>")
	)
	(segment
		(start 345.66352 -33.913064)
		(end 345.228164 -32.862012)
		(width 0.14732)
		(layer "In4.Cu")
		(net "P3E_PCH_E1S_TX_DN<0>")
	)
	(segment
		(start 235.16082 -54.484778)
		(end 235.16082 -54.116478)
		(width 0.14732)
		(layer "In4.Cu")
		(net "P3E_PCH_E1S_TX_DN<0>")
	)
	(segment
		(start 344.83802 -44.948348)
		(end 345.548458 -44.948348)
		(width 0.0889)
		(layer "In4.Cu")
		(net "P3E_PCH_E1S_TX_DN<0>")
	)
	(segment
		(start 304.75301 -23.372318)
		(end 296.032174 -26.984706)
		(width 0.14732)
		(layer "In4.Cu")
		(net "P3E_PCH_E1S_TX_DN<0>")
	)
	(segment
		(start 345.590622 -44.990512)
		(end 345.61272 -44.990512)
		(width 0.0889)
		(layer "In4.Cu")
		(net "P3E_PCH_E1S_TX_DN<0>")
	)
	(segment
		(start 235.01604 -54.629558)
		(end 235.16082 -54.484778)
		(width 0.14732)
		(layer "In4.Cu")
		(net "P3E_PCH_E1S_TX_DN<0>")
	)
	(segment
		(start 235.16082 -54.116478)
		(end 235.01604 -53.971698)
		(width 0.14732)
		(layer "In4.Cu")
		(net "P3E_PCH_E1S_TX_DN<0>")
	)
	(segment
		(start 344.675714 -44.786042)
		(end 344.83802 -44.948348)
		(width 0.0889)
		(layer "In4.Cu")
		(net "P3E_PCH_E1S_TX_DN<0>")
	)
	(segment
		(start 295.271444 -27.493214)
		(end 285.437326 -38.34384)
		(width 0.14732)
		(layer "In4.Cu")
		(net "P3E_PCH_E1S_TX_DN<0>")
	)
	(segment
		(start 268.667992 -61.541406)
		(end 252.82779 -62.319408)
		(width 0.14732)
		(layer "In4.Cu")
		(net "P3E_PCH_E1S_TX_DN<0>")
	)
	(segment
		(start 345.228164 -32.862012)
		(end 344.51925 -32.153098)
		(width 0.14732)
		(layer "In4.Cu")
		(net "P3E_PCH_E1S_TX_DN<0>")
	)
	(segment
		(start 276.560534 -56.877966)
		(end 274.469098 -58.969148)
		(width 0.14732)
		(layer "In4.Cu")
		(net "P3E_PCH_E1S_TX_DN<0>")
	)
	(segment
		(start 335.65973 -28.483306)
		(end 332.380336 -25.203912)
		(width 0.14732)
		(layer "In4.Cu")
		(net "P3E_PCH_E1S_TX_DN<0>")
	)
	(segment
		(start 235.01604 -55.444898)
		(end 235.01604 -54.629558)
		(width 0.14732)
		(layer "In4.Cu")
		(net "P3E_PCH_E1S_TX_DN<0>")
	)
	(segment
		(start 345.66352 -37.21989)
		(end 345.66352 -33.913064)
		(width 0.14732)
		(layer "In4.Cu")
		(net "P3E_PCH_E1S_TX_DN<0>")
	)
	(segment
		(start 274.469098 -58.969148)
		(end 268.667992 -61.541406)
		(width 0.14732)
		(layer "In4.Cu")
		(net "P3E_PCH_E1S_TX_DN<0>")
	)
	(segment
		(start 344.51925 -32.153098)
		(end 335.65973 -28.483306)
		(width 0.14732)
		(layer "In4.Cu")
		(net "P3E_PCH_E1S_TX_DN<0>")
	)
	(segment
		(start 328.82205 -19.758406)
		(end 328.020426 -19.426428)
		(width 0.14732)
		(layer "In4.Cu")
		(net "P3E_PCH_E1S_TX_DN<0>")
	)
	(segment
		(start 346.52458 -44.540424)
		(end 346.52458 -41.567354)
		(width 0.14732)
		(layer "In4.Cu")
		(net "P3E_PCH_E1S_TX_DN<0>")
	)
	(segment
		(start 237.38205 -52.745386)
		(end 237.52683 -52.600606)
		(width 0.14732)
		(layer "In4.Cu")
		(net "P3E_PCH_E1S_TX_DN<0>")
	)
	(segment
		(start 235.01604 -53.373528)
		(end 235.788962 -52.600606)
		(width 0.14732)
		(layer "In4.Cu")
		(net "P3E_PCH_E1S_TX_DN<0>")
	)
	(segment
		(start 237.01375 -52.745386)
		(end 237.38205 -52.745386)
		(width 0.14732)
		(layer "In4.Cu")
		(net "P3E_PCH_E1S_TX_DN<0>")
	)
	(segment
		(start 239.39119 -52.600606)
		(end 242.007136 -52.600606)
		(width 0.14732)
		(layer "In4.Cu")
		(net "P3E_PCH_E1S_TX_DN<0>")
	)
	(segment
		(start 343.549478 -44.690792)
		(end 343.820496 -44.534328)
		(width 0.0889)
		(layer "In4.Cu")
		(net "P3E_PCH_E1S_TX_DN<0>")
	)
	(segment
		(start 328.020426 -19.426428)
		(end 324.589648 -19.426428)
		(width 0.14732)
		(layer "In4.Cu")
		(net "P3E_PCH_E1S_TX_DN<0>")
	)
	(segment
		(start 235.16082 -55.957978)
		(end 235.16082 -55.589678)
		(width 0.14732)
		(layer "In4.Cu")
		(net "P3E_PCH_E1S_TX_DN<0>")
	)
	(segment
		(start 236.307884 -58.87212)
		(end 235.76153 -58.325766)
		(width 0.14732)
		(layer "In4.Cu")
		(net "P3E_PCH_E1S_TX_DN<0>")
	)
	(segment
		(start 280.093674 -48.3489)
		(end 278.327104 -52.61356)
		(width 0.14732)
		(layer "In4.Cu")
		(net "P3E_PCH_E1S_TX_DN<0>")
	)
	(segment
		(start 324.589648 -19.426428)
		(end 304.75301 -23.372318)
		(width 0.14732)
		(layer "In4.Cu")
		(net "P3E_PCH_E1S_TX_DN<0>")
	)
	(segment
		(start 346.52458 -41.567354)
		(end 345.66352 -37.21989)
		(width 0.14732)
		(layer "In4.Cu")
		(net "P3E_PCH_E1S_TX_DN<0>")
	)
	(segment
		(start 344.353388 -44.786042)
		(end 344.675714 -44.786042)
		(width 0.0889)
		(layer "In4.Cu")
		(net "P3E_PCH_E1S_TX_DN<0>")
	)
	(segment
		(start 345.548458 -44.948348)
		(end 345.590622 -44.990512)
		(width 0.0889)
		(layer "In4.Cu")
		(net "P3E_PCH_E1S_TX_DN<0>")
	)
	(arc
		(start 343.90965 -44.558458)
		(mid 343.916047 -44.566902)
		(end 343.922604 -44.575222)
		(width 0.0889)
		(layer "In4.Cu")
		(net "P3E_PCH_E1S_TX_DN<0>")
	)
	(arc
		(start 343.922604 -44.575222)
		(mid 344.114523 -44.728606)
		(end 344.353388 -44.786042)
		(width 0.0889)
		(layer "In4.Cu")
		(net "P3E_PCH_E1S_TX_DN<0>")
	)
	(segment
		(start 357.85044 -51.011328)
		(end 357.266748 -51.59502)
		(width 0.0889)
		(layer "F.Cu")
		(net "P3E_PCH_E1S_RX_DP<3>")
	)
	(segment
		(start 348.469966 -51.435254)
		(end 348.373446 -51.531774)
		(width 0.0889)
		(layer "F.Cu")
		(net "P3E_PCH_E1S_RX_DP<3>")
	)
	(segment
		(start 355.10978 -52.187348)
		(end 354.85578 -52.187348)
		(width 0.0889)
		(layer "F.Cu")
		(net "P3E_PCH_E1S_RX_DP<3>")
	)
	(segment
		(start 352.40214 -52.090828)
		(end 352.155506 -51.844194)
		(width 0.0889)
		(layer "F.Cu")
		(net "P3E_PCH_E1S_RX_DP<3>")
	)
	(segment
		(start 352.75266 -52.187348)
		(end 352.65614 -52.090828)
		(width 0.0889)
		(layer "F.Cu")
		(net "P3E_PCH_E1S_RX_DP<3>")
	)
	(segment
		(start 357.266748 -51.731418)
		(end 357.086916 -51.91125)
		(width 0.0889)
		(layer "F.Cu")
		(net "P3E_PCH_E1S_RX_DP<3>")
	)
	(segment
		(start 356.950518 -51.91125)
		(end 356.77094 -52.090828)
		(width 0.0889)
		(layer "F.Cu")
		(net "P3E_PCH_E1S_RX_DP<3>")
	)
	(segment
		(start 354.50526 -52.090828)
		(end 354.40874 -52.187348)
		(width 0.0889)
		(layer "F.Cu")
		(net "P3E_PCH_E1S_RX_DP<3>")
	)
	(segment
		(start 349.132906 -51.844194)
		(end 348.723966 -51.435254)
		(width 0.0889)
		(layer "F.Cu")
		(net "P3E_PCH_E1S_RX_DP<3>")
	)
	(segment
		(start 355.2063 -52.090828)
		(end 355.10978 -52.187348)
		(width 0.0889)
		(layer "F.Cu")
		(net "P3E_PCH_E1S_RX_DP<3>")
	)
	(segment
		(start 353.7077 -52.187348)
		(end 353.4537 -52.187348)
		(width 0.0889)
		(layer "F.Cu")
		(net "P3E_PCH_E1S_RX_DP<3>")
	)
	(segment
		(start 353.4537 -52.187348)
		(end 353.35718 -52.090828)
		(width 0.0889)
		(layer "F.Cu")
		(net "P3E_PCH_E1S_RX_DP<3>")
	)
	(segment
		(start 348.373446 -51.531774)
		(end 348.119446 -51.531774)
		(width 0.0889)
		(layer "F.Cu")
		(net "P3E_PCH_E1S_RX_DP<3>")
	)
	(segment
		(start 348.022926 -51.435254)
		(end 346.816172 -51.435254)
		(width 0.0889)
		(layer "F.Cu")
		(net "P3E_PCH_E1S_RX_DP<3>")
	)
	(segment
		(start 232.000044 -58.164984)
		(end 231.561132 -58.164984)
		(width 0.13208)
		(layer "F.Cu")
		(net "P3E_PCH_E1S_RX_DP<3>")
	)
	(segment
		(start 231.561132 -58.164984)
		(end 231.400604 -58.004456)
		(width 0.13208)
		(layer "F.Cu")
		(net "P3E_PCH_E1S_RX_DP<3>")
	)
	(segment
		(start 354.40874 -52.187348)
		(end 354.15474 -52.187348)
		(width 0.0889)
		(layer "F.Cu")
		(net "P3E_PCH_E1S_RX_DP<3>")
	)
	(segment
		(start 346.816172 -51.435254)
		(end 346.799662 -51.451764)
		(width 0.0889)
		(layer "F.Cu")
		(net "P3E_PCH_E1S_RX_DP<3>")
	)
	(segment
		(start 230.79964 -58.004456)
		(end 230.49738 -58.306716)
		(width 0.13208)
		(layer "F.Cu")
		(net "P3E_PCH_E1S_RX_DP<3>")
	)
	(segment
		(start 353.80422 -52.090828)
		(end 353.7077 -52.187348)
		(width 0.0889)
		(layer "F.Cu")
		(net "P3E_PCH_E1S_RX_DP<3>")
	)
	(segment
		(start 231.400604 -58.004456)
		(end 230.79964 -58.004456)
		(width 0.13208)
		(layer "F.Cu")
		(net "P3E_PCH_E1S_RX_DP<3>")
	)
	(segment
		(start 354.75926 -52.090828)
		(end 354.50526 -52.090828)
		(width 0.0889)
		(layer "F.Cu")
		(net "P3E_PCH_E1S_RX_DP<3>")
	)
	(segment
		(start 354.05822 -52.090828)
		(end 353.80422 -52.090828)
		(width 0.0889)
		(layer "F.Cu")
		(net "P3E_PCH_E1S_RX_DP<3>")
	)
	(segment
		(start 357.086916 -51.91125)
		(end 356.950518 -51.91125)
		(width 0.0889)
		(layer "F.Cu")
		(net "P3E_PCH_E1S_RX_DP<3>")
	)
	(segment
		(start 352.155506 -51.844194)
		(end 349.132906 -51.844194)
		(width 0.0889)
		(layer "F.Cu")
		(net "P3E_PCH_E1S_RX_DP<3>")
	)
	(segment
		(start 352.65614 -52.090828)
		(end 352.40214 -52.090828)
		(width 0.0889)
		(layer "F.Cu")
		(net "P3E_PCH_E1S_RX_DP<3>")
	)
	(segment
		(start 354.85578 -52.187348)
		(end 354.75926 -52.090828)
		(width 0.0889)
		(layer "F.Cu")
		(net "P3E_PCH_E1S_RX_DP<3>")
	)
	(segment
		(start 348.119446 -51.531774)
		(end 348.022926 -51.435254)
		(width 0.0889)
		(layer "F.Cu")
		(net "P3E_PCH_E1S_RX_DP<3>")
	)
	(segment
		(start 353.35718 -52.090828)
		(end 353.10318 -52.090828)
		(width 0.0889)
		(layer "F.Cu")
		(net "P3E_PCH_E1S_RX_DP<3>")
	)
	(segment
		(start 355.55682 -52.187348)
		(end 355.4603 -52.090828)
		(width 0.0889)
		(layer "F.Cu")
		(net "P3E_PCH_E1S_RX_DP<3>")
	)
	(segment
		(start 354.15474 -52.187348)
		(end 354.05822 -52.090828)
		(width 0.0889)
		(layer "F.Cu")
		(net "P3E_PCH_E1S_RX_DP<3>")
	)
	(segment
		(start 356.77094 -52.090828)
		(end 355.90734 -52.090828)
		(width 0.0889)
		(layer "F.Cu")
		(net "P3E_PCH_E1S_RX_DP<3>")
	)
	(segment
		(start 357.85044 -50.544476)
		(end 357.85044 -51.011328)
		(width 0.0889)
		(layer "F.Cu")
		(net "P3E_PCH_E1S_RX_DP<3>")
	)
	(segment
		(start 355.4603 -52.090828)
		(end 355.2063 -52.090828)
		(width 0.0889)
		(layer "F.Cu")
		(net "P3E_PCH_E1S_RX_DP<3>")
	)
	(segment
		(start 353.00666 -52.187348)
		(end 352.75266 -52.187348)
		(width 0.0889)
		(layer "F.Cu")
		(net "P3E_PCH_E1S_RX_DP<3>")
	)
	(segment
		(start 358.187244 -50.207672)
		(end 357.85044 -50.544476)
		(width 0.0889)
		(layer "F.Cu")
		(net "P3E_PCH_E1S_RX_DP<3>")
	)
	(segment
		(start 348.723966 -51.435254)
		(end 348.469966 -51.435254)
		(width 0.0889)
		(layer "F.Cu")
		(net "P3E_PCH_E1S_RX_DP<3>")
	)
	(segment
		(start 355.81082 -52.187348)
		(end 355.55682 -52.187348)
		(width 0.0889)
		(layer "F.Cu")
		(net "P3E_PCH_E1S_RX_DP<3>")
	)
	(segment
		(start 353.10318 -52.090828)
		(end 353.00666 -52.187348)
		(width 0.0889)
		(layer "F.Cu")
		(net "P3E_PCH_E1S_RX_DP<3>")
	)
	(segment
		(start 357.266748 -51.59502)
		(end 357.266748 -51.731418)
		(width 0.0889)
		(layer "F.Cu")
		(net "P3E_PCH_E1S_RX_DP<3>")
	)
	(segment
		(start 355.90734 -52.090828)
		(end 355.81082 -52.187348)
		(width 0.0889)
		(layer "F.Cu")
		(net "P3E_PCH_E1S_RX_DP<3>")
	)
	(segment
		(start 341.994236 -28.645358)
		(end 342.034368 -28.444698)
		(width 0.14732)
		(layer "In6.Cu")
		(net "P3E_PCH_E1S_RX_DP<3>")
	)
	(segment
		(start 350.234758 -35.68573)
		(end 349.87357 -35.614102)
		(width 0.14732)
		(layer "In6.Cu")
		(net "P3E_PCH_E1S_RX_DP<3>")
	)
	(segment
		(start 362.786168 -49.558448)
		(end 363.65434 -48.690276)
		(width 0.14732)
		(layer "In6.Cu")
		(net "P3E_PCH_E1S_RX_DP<3>")
	)
	(segment
		(start 362.32084 -50.023776)
		(end 362.32084 -49.819052)
		(width 0.14732)
		(layer "In6.Cu")
		(net "P3E_PCH_E1S_RX_DP<3>")
	)
	(segment
		(start 317.3984 -20.494752)
		(end 303.50714 -23.258018)
		(width 0.14732)
		(layer "In6.Cu")
		(net "P3E_PCH_E1S_RX_DP<3>")
	)
	(segment
		(start 287.933638 -32.711644)
		(end 277.088854 -43.555412)
		(width 0.14732)
		(layer "In6.Cu")
		(net "P3E_PCH_E1S_RX_DP<3>")
	)
	(segment
		(start 357.892604 -50.947574)
		(end 358.040178 -51.095148)
		(width 0.14732)
		(layer "In6.Cu")
		(net "P3E_PCH_E1S_RX_DP<3>")
	)
	(segment
		(start 363.093508 -45.095922)
		(end 362.952792 -44.755816)
		(width 0.14732)
		(layer "In6.Cu")
		(net "P3E_PCH_E1S_RX_DP<3>")
	)
	(segment
		(start 362.581444 -49.558448)
		(end 362.786168 -49.558448)
		(width 0.14732)
		(layer "In6.Cu")
		(net "P3E_PCH_E1S_RX_DP<3>")
	)
	(segment
		(start 317.568834 -20.608544)
		(end 317.3984 -20.494752)
		(width 0.14732)
		(layer "In6.Cu")
		(net "P3E_PCH_E1S_RX_DP<3>")
	)
	(segment
		(start 346.853764 -35.012884)
		(end 345.55684 -33.716214)
		(width 0.14732)
		(layer "In6.Cu")
		(net "P3E_PCH_E1S_RX_DP<3>")
	)
	(segment
		(start 363.345476 -45.703998)
		(end 363.156246 -45.625766)
		(width 0.14732)
		(layer "In6.Cu")
		(net "P3E_PCH_E1S_RX_DP<3>")
	)
	(segment
		(start 362.763308 -44.67733)
		(end 362.622338 -44.33697)
		(width 0.14732)
		(layer "In6.Cu")
		(net "P3E_PCH_E1S_RX_DP<3>")
	)
	(segment
		(start 355.632512 -36.759642)
		(end 354.656898 -36.56584)
		(width 0.14732)
		(layer "In6.Cu")
		(net "P3E_PCH_E1S_RX_DP<3>")
	)
	(segment
		(start 354.656898 -36.56584)
		(end 354.486718 -36.679378)
		(width 0.14732)
		(layer "In6.Cu")
		(net "P3E_PCH_E1S_RX_DP<3>")
	)
	(segment
		(start 354.011484 -36.437062)
		(end 350.880172 -35.814508)
		(width 0.14732)
		(layer "In6.Cu")
		(net "P3E_PCH_E1S_RX_DP<3>")
	)
	(segment
		(start 299.756322 -24.811482)
		(end 287.933638 -32.711644)
		(width 0.14732)
		(layer "In6.Cu")
		(net "P3E_PCH_E1S_RX_DP<3>")
	)
	(segment
		(start 342.034368 -28.444698)
		(end 340.24316 -25.763982)
		(width 0.14732)
		(layer "In6.Cu")
		(net "P3E_PCH_E1S_RX_DP<3>")
	)
	(segment
		(start 362.70057 -44.14774)
		(end 362.559854 -43.807634)
		(width 0.14732)
		(layer "In6.Cu")
		(net "P3E_PCH_E1S_RX_DP<3>")
	)
	(segment
		(start 317.930276 -20.536662)
		(end 317.568834 -20.608544)
		(width 0.14732)
		(layer "In6.Cu")
		(net "P3E_PCH_E1S_RX_DP<3>")
	)
	(segment
		(start 361.552744 -41.376346)
		(end 358.432608 -38.25621)
		(width 0.14732)
		(layer "In6.Cu")
		(net "P3E_PCH_E1S_RX_DP<3>")
	)
	(segment
		(start 363.65434 -46.449742)
		(end 363.345476 -45.703998)
		(width 0.14732)
		(layer "In6.Cu")
		(net "P3E_PCH_E1S_RX_DP<3>")
	)
	(segment
		(start 263.0932 -58.681874)
		(end 261.155688 -60.619386)
		(width 0.14732)
		(layer "In6.Cu")
		(net "P3E_PCH_E1S_RX_DP<3>")
	)
	(segment
		(start 247.919494 -60.814204)
		(end 241.915188 -60.814204)
		(width 0.14732)
		(layer "In6.Cu")
		(net "P3E_PCH_E1S_RX_DP<3>")
	)
	(segment
		(start 270.365474 -46.340268)
		(end 266.32789 -46.340268)
		(width 0.14732)
		(layer "In6.Cu")
		(net "P3E_PCH_E1S_RX_DP<3>")
	)
	(segment
		(start 325.454772 -19.677888)
		(end 321.50431 -19.677888)
		(width 0.14732)
		(layer "In6.Cu")
		(net "P3E_PCH_E1S_RX_DP<3>")
	)
	(segment
		(start 349.228156 -35.485324)
		(end 348.866968 -35.413696)
		(width 0.14732)
		(layer "In6.Cu")
		(net "P3E_PCH_E1S_RX_DP<3>")
	)
	(segment
		(start 363.156246 -45.625766)
		(end 363.015276 -45.285152)
		(width 0.14732)
		(layer "In6.Cu")
		(net "P3E_PCH_E1S_RX_DP<3>")
	)
	(segment
		(start 363.65434 -48.127158)
		(end 363.50956 -47.982378)
		(width 0.14732)
		(layer "In6.Cu")
		(net "P3E_PCH_E1S_RX_DP<3>")
	)
	(segment
		(start 249.131328 -61.316108)
		(end 247.919494 -60.814204)
		(width 0.14732)
		(layer "In6.Cu")
		(net "P3E_PCH_E1S_RX_DP<3>")
	)
	(segment
		(start 349.87357 -35.614102)
		(end 349.70339 -35.727894)
		(width 0.14732)
		(layer "In6.Cu")
		(net "P3E_PCH_E1S_RX_DP<3>")
	)
	(segment
		(start 362.229654 -43.388788)
		(end 362.307886 -43.199558)
		(width 0.14732)
		(layer "In6.Cu")
		(net "P3E_PCH_E1S_RX_DP<3>")
	)
	(segment
		(start 354.486718 -36.679378)
		(end 354.125276 -36.60775)
		(width 0.14732)
		(layer "In6.Cu")
		(net "P3E_PCH_E1S_RX_DP<3>")
	)
	(segment
		(start 347.214952 -35.084512)
		(end 346.853764 -35.012884)
		(width 0.14732)
		(layer "In6.Cu")
		(net "P3E_PCH_E1S_RX_DP<3>")
	)
	(segment
		(start 259.473446 -61.316108)
		(end 249.131328 -61.316108)
		(width 0.14732)
		(layer "In6.Cu")
		(net "P3E_PCH_E1S_RX_DP<3>")
	)
	(segment
		(start 232.81894 -58.012076)
		(end 230.79202 -58.012076)
		(width 0.14732)
		(layer "In6.Cu")
		(net "P3E_PCH_E1S_RX_DP<3>")
	)
	(segment
		(start 363.50956 -47.982378)
		(end 363.50956 -47.614078)
		(width 0.14732)
		(layer "In6.Cu")
		(net "P3E_PCH_E1S_RX_DP<3>")
	)
	(segment
		(start 345.55684 -33.716214)
		(end 342.400128 -28.991814)
		(width 0.14732)
		(layer "In6.Cu")
		(net "P3E_PCH_E1S_RX_DP<3>")
	)
	(segment
		(start 362.952792 -44.755816)
		(end 362.763308 -44.67733)
		(width 0.14732)
		(layer "In6.Cu")
		(net "P3E_PCH_E1S_RX_DP<3>")
	)
	(segment
		(start 327.268586 -19.317208)
		(end 325.454772 -19.677888)
		(width 0.14732)
		(layer "In6.Cu")
		(net "P3E_PCH_E1S_RX_DP<3>")
	)
	(segment
		(start 342.400128 -28.991814)
		(end 342.19896 -28.951936)
		(width 0.14732)
		(layer "In6.Cu")
		(net "P3E_PCH_E1S_RX_DP<3>")
	)
	(segment
		(start 348.696788 -35.527488)
		(end 348.335092 -35.455606)
		(width 0.14732)
		(layer "In6.Cu")
		(net "P3E_PCH_E1S_RX_DP<3>")
	)
	(segment
		(start 261.155688 -60.619386)
		(end 259.473446 -61.316108)
		(width 0.14732)
		(layer "In6.Cu")
		(net "P3E_PCH_E1S_RX_DP<3>")
	)
	(segment
		(start 318.044068 -20.366228)
		(end 317.930276 -20.536662)
		(width 0.14732)
		(layer "In6.Cu")
		(net "P3E_PCH_E1S_RX_DP<3>")
	)
	(segment
		(start 334.085946 -19.606514)
		(end 333.3877 -19.317208)
		(width 0.14732)
		(layer "In6.Cu")
		(net "P3E_PCH_E1S_RX_DP<3>")
	)
	(segment
		(start 358.040178 -51.095148)
		(end 361.249468 -51.095148)
		(width 0.14732)
		(layer "In6.Cu")
		(net "P3E_PCH_E1S_RX_DP<3>")
	)
	(segment
		(start 362.32084 -49.819052)
		(end 362.581444 -49.558448)
		(width 0.14732)
		(layer "In6.Cu")
		(net "P3E_PCH_E1S_RX_DP<3>")
	)
	(segment
		(start 321.50431 -19.677888)
		(end 318.044068 -20.366228)
		(width 0.14732)
		(layer "In6.Cu")
		(net "P3E_PCH_E1S_RX_DP<3>")
	)
	(segment
		(start 363.50956 -47.614078)
		(end 363.65434 -47.469298)
		(width 0.14732)
		(layer "In6.Cu")
		(net "P3E_PCH_E1S_RX_DP<3>")
	)
	(segment
		(start 263.88695 -48.781208)
		(end 263.0932 -50.69713)
		(width 0.14732)
		(layer "In6.Cu")
		(net "P3E_PCH_E1S_RX_DP<3>")
	)
	(segment
		(start 363.65434 -47.469298)
		(end 363.65434 -46.449742)
		(width 0.14732)
		(layer "In6.Cu")
		(net "P3E_PCH_E1S_RX_DP<3>")
	)
	(segment
		(start 340.24316 -25.763982)
		(end 334.085946 -19.606514)
		(width 0.14732)
		(layer "In6.Cu")
		(net "P3E_PCH_E1S_RX_DP<3>")
	)
	(segment
		(start 333.3877 -19.317208)
		(end 327.268586 -19.317208)
		(width 0.14732)
		(layer "In6.Cu")
		(net "P3E_PCH_E1S_RX_DP<3>")
	)
	(segment
		(start 362.307886 -43.199558)
		(end 361.552744 -41.376346)
		(width 0.14732)
		(layer "In6.Cu")
		(net "P3E_PCH_E1S_RX_DP<3>")
	)
	(segment
		(start 303.50714 -23.258018)
		(end 299.756322 -24.811482)
		(width 0.14732)
		(layer "In6.Cu")
		(net "P3E_PCH_E1S_RX_DP<3>")
	)
	(segment
		(start 230.79202 -58.012076)
		(end 230.49738 -58.306716)
		(width 0.14732)
		(layer "In6.Cu")
		(net "P3E_PCH_E1S_RX_DP<3>")
	)
	(segment
		(start 354.125276 -36.60775)
		(end 354.011484 -36.437062)
		(width 0.14732)
		(layer "In6.Cu")
		(net "P3E_PCH_E1S_RX_DP<3>")
	)
	(segment
		(start 347.32849 -35.2552)
		(end 347.214952 -35.084512)
		(width 0.14732)
		(layer "In6.Cu")
		(net "P3E_PCH_E1S_RX_DP<3>")
	)
	(segment
		(start 361.249468 -51.095148)
		(end 362.32084 -50.023776)
		(width 0.14732)
		(layer "In6.Cu")
		(net "P3E_PCH_E1S_RX_DP<3>")
	)
	(segment
		(start 348.866968 -35.413696)
		(end 348.696788 -35.527488)
		(width 0.14732)
		(layer "In6.Cu")
		(net "P3E_PCH_E1S_RX_DP<3>")
	)
	(segment
		(start 358.187244 -50.207672)
		(end 357.892604 -50.502312)
		(width 0.14732)
		(layer "In6.Cu")
		(net "P3E_PCH_E1S_RX_DP<3>")
	)
	(segment
		(start 362.559854 -43.807634)
		(end 362.370624 -43.729402)
		(width 0.14732)
		(layer "In6.Cu")
		(net "P3E_PCH_E1S_RX_DP<3>")
	)
	(segment
		(start 342.19896 -28.951936)
		(end 341.994236 -28.645358)
		(width 0.14732)
		(layer "In6.Cu")
		(net "P3E_PCH_E1S_RX_DP<3>")
	)
	(segment
		(start 240.733326 -60.638944)
		(end 237.710726 -60.037726)
		(width 0.14732)
		(layer "In6.Cu")
		(net "P3E_PCH_E1S_RX_DP<3>")
	)
	(segment
		(start 263.0932 -50.69713)
		(end 263.0932 -58.681874)
		(width 0.14732)
		(layer "In6.Cu")
		(net "P3E_PCH_E1S_RX_DP<3>")
	)
	(segment
		(start 357.892604 -50.502312)
		(end 357.892604 -50.947574)
		(width 0.14732)
		(layer "In6.Cu")
		(net "P3E_PCH_E1S_RX_DP<3>")
	)
	(segment
		(start 237.710726 -60.037726)
		(end 232.81894 -58.012076)
		(width 0.14732)
		(layer "In6.Cu")
		(net "P3E_PCH_E1S_RX_DP<3>")
	)
	(segment
		(start 349.341694 -35.656012)
		(end 349.228156 -35.485324)
		(width 0.14732)
		(layer "In6.Cu")
		(net "P3E_PCH_E1S_RX_DP<3>")
	)
	(segment
		(start 347.690186 -35.327082)
		(end 347.32849 -35.2552)
		(width 0.14732)
		(layer "In6.Cu")
		(net "P3E_PCH_E1S_RX_DP<3>")
	)
	(segment
		(start 363.65434 -48.690276)
		(end 363.65434 -48.127158)
		(width 0.14732)
		(layer "In6.Cu")
		(net "P3E_PCH_E1S_RX_DP<3>")
	)
	(segment
		(start 358.432608 -38.25621)
		(end 355.632512 -36.759642)
		(width 0.14732)
		(layer "In6.Cu")
		(net "P3E_PCH_E1S_RX_DP<3>")
	)
	(segment
		(start 350.348296 -35.856418)
		(end 350.234758 -35.68573)
		(width 0.14732)
		(layer "In6.Cu")
		(net "P3E_PCH_E1S_RX_DP<3>")
	)
	(segment
		(start 348.221554 -35.284918)
		(end 347.860366 -35.21329)
		(width 0.14732)
		(layer "In6.Cu")
		(net "P3E_PCH_E1S_RX_DP<3>")
	)
	(segment
		(start 350.880172 -35.814508)
		(end 350.709992 -35.9283)
		(width 0.14732)
		(layer "In6.Cu")
		(net "P3E_PCH_E1S_RX_DP<3>")
	)
	(segment
		(start 241.915188 -60.814204)
		(end 240.733326 -60.638944)
		(width 0.14732)
		(layer "In6.Cu")
		(net "P3E_PCH_E1S_RX_DP<3>")
	)
	(segment
		(start 350.709992 -35.9283)
		(end 350.348296 -35.856418)
		(width 0.14732)
		(layer "In6.Cu")
		(net "P3E_PCH_E1S_RX_DP<3>")
	)
	(segment
		(start 363.015276 -45.285152)
		(end 363.093508 -45.095922)
		(width 0.14732)
		(layer "In6.Cu")
		(net "P3E_PCH_E1S_RX_DP<3>")
	)
	(segment
		(start 266.32789 -46.340268)
		(end 263.88695 -48.781208)
		(width 0.14732)
		(layer "In6.Cu")
		(net "P3E_PCH_E1S_RX_DP<3>")
	)
	(segment
		(start 362.622338 -44.33697)
		(end 362.70057 -44.14774)
		(width 0.14732)
		(layer "In6.Cu")
		(net "P3E_PCH_E1S_RX_DP<3>")
	)
	(segment
		(start 277.088854 -43.555412)
		(end 270.365474 -46.340268)
		(width 0.14732)
		(layer "In6.Cu")
		(net "P3E_PCH_E1S_RX_DP<3>")
	)
	(segment
		(start 348.335092 -35.455606)
		(end 348.221554 -35.284918)
		(width 0.14732)
		(layer "In6.Cu")
		(net "P3E_PCH_E1S_RX_DP<3>")
	)
	(segment
		(start 347.860366 -35.21329)
		(end 347.690186 -35.327082)
		(width 0.14732)
		(layer "In6.Cu")
		(net "P3E_PCH_E1S_RX_DP<3>")
	)
	(segment
		(start 362.370624 -43.729402)
		(end 362.229654 -43.388788)
		(width 0.14732)
		(layer "In6.Cu")
		(net "P3E_PCH_E1S_RX_DP<3>")
	)
	(segment
		(start 349.70339 -35.727894)
		(end 349.341694 -35.656012)
		(width 0.14732)
		(layer "In6.Cu")
		(net "P3E_PCH_E1S_RX_DP<3>")
	)
	(segment
		(start 353.8474 -51.554888)
		(end 353.94392 -51.458368)
		(width 0.0889)
		(layer "F.Cu")
		(net "P3E_PCH_E1S_RX_DP<2>")
	)
	(segment
		(start 232.000044 -56.364886)
		(end 231.528366 -56.364886)
		(width 0.13208)
		(layer "F.Cu")
		(net "P3E_PCH_E1S_RX_DP<2>")
	)
	(segment
		(start 354.54844 -51.554888)
		(end 354.64496 -51.458368)
		(width 0.0889)
		(layer "F.Cu")
		(net "P3E_PCH_E1S_RX_DP<2>")
	)
	(segment
		(start 231.528366 -56.364886)
		(end 231.368092 -56.204612)
		(width 0.13208)
		(layer "F.Cu")
		(net "P3E_PCH_E1S_RX_DP<2>")
	)
	(segment
		(start 354.19792 -51.458368)
		(end 354.29444 -51.554888)
		(width 0.0889)
		(layer "F.Cu")
		(net "P3E_PCH_E1S_RX_DP<2>")
	)
	(segment
		(start 353.49688 -51.458368)
		(end 353.5934 -51.554888)
		(width 0.0889)
		(layer "F.Cu")
		(net "P3E_PCH_E1S_RX_DP<2>")
	)
	(segment
		(start 355.518466 -50.917602)
		(end 355.518466 -50.361342)
		(width 0.0889)
		(layer "F.Cu")
		(net "P3E_PCH_E1S_RX_DP<2>")
	)
	(segment
		(start 354.29444 -51.554888)
		(end 354.54844 -51.554888)
		(width 0.0889)
		(layer "F.Cu")
		(net "P3E_PCH_E1S_RX_DP<2>")
	)
	(segment
		(start 354.9777 -51.458368)
		(end 355.518466 -50.917602)
		(width 0.0889)
		(layer "F.Cu")
		(net "P3E_PCH_E1S_RX_DP<2>")
	)
	(segment
		(start 355.518466 -50.361342)
		(end 355.672136 -50.207672)
		(width 0.0889)
		(layer "F.Cu")
		(net "P3E_PCH_E1S_RX_DP<2>")
	)
	(segment
		(start 231.368092 -56.204612)
		(end 229.49916 -56.204612)
		(width 0.13208)
		(layer "F.Cu")
		(net "P3E_PCH_E1S_RX_DP<2>")
	)
	(segment
		(start 353.94392 -51.458368)
		(end 354.19792 -51.458368)
		(width 0.0889)
		(layer "F.Cu")
		(net "P3E_PCH_E1S_RX_DP<2>")
	)
	(segment
		(start 353.14636 -51.554888)
		(end 353.24288 -51.458368)
		(width 0.0889)
		(layer "F.Cu")
		(net "P3E_PCH_E1S_RX_DP<2>")
	)
	(segment
		(start 353.5934 -51.554888)
		(end 353.8474 -51.554888)
		(width 0.0889)
		(layer "F.Cu")
		(net "P3E_PCH_E1S_RX_DP<2>")
	)
	(segment
		(start 229.49916 -56.204612)
		(end 229.1969 -56.506872)
		(width 0.13208)
		(layer "F.Cu")
		(net "P3E_PCH_E1S_RX_DP<2>")
	)
	(segment
		(start 347.69044 -50.951384)
		(end 347.78696 -51.047904)
		(width 0.0889)
		(layer "F.Cu")
		(net "P3E_PCH_E1S_RX_DP<2>")
	)
	(segment
		(start 348.880176 -50.951384)
		(end 349.38716 -51.458368)
		(width 0.0889)
		(layer "F.Cu")
		(net "P3E_PCH_E1S_RX_DP<2>")
	)
	(segment
		(start 352.79584 -51.458368)
		(end 352.89236 -51.554888)
		(width 0.0889)
		(layer "F.Cu")
		(net "P3E_PCH_E1S_RX_DP<2>")
	)
	(segment
		(start 354.64496 -51.458368)
		(end 354.9777 -51.458368)
		(width 0.0889)
		(layer "F.Cu")
		(net "P3E_PCH_E1S_RX_DP<2>")
	)
	(segment
		(start 349.38716 -51.458368)
		(end 352.79584 -51.458368)
		(width 0.0889)
		(layer "F.Cu")
		(net "P3E_PCH_E1S_RX_DP<2>")
	)
	(segment
		(start 347.78696 -51.047904)
		(end 348.04096 -51.047904)
		(width 0.0889)
		(layer "F.Cu")
		(net "P3E_PCH_E1S_RX_DP<2>")
	)
	(segment
		(start 348.04096 -51.047904)
		(end 348.13748 -50.951384)
		(width 0.0889)
		(layer "F.Cu")
		(net "P3E_PCH_E1S_RX_DP<2>")
	)
	(segment
		(start 353.24288 -51.458368)
		(end 353.49688 -51.458368)
		(width 0.0889)
		(layer "F.Cu")
		(net "P3E_PCH_E1S_RX_DP<2>")
	)
	(segment
		(start 352.89236 -51.554888)
		(end 353.14636 -51.554888)
		(width 0.0889)
		(layer "F.Cu")
		(net "P3E_PCH_E1S_RX_DP<2>")
	)
	(segment
		(start 347.214698 -50.951384)
		(end 347.69044 -50.951384)
		(width 0.0889)
		(layer "F.Cu")
		(net "P3E_PCH_E1S_RX_DP<2>")
	)
	(segment
		(start 355.672136 -50.207672)
		(end 355.957124 -50.207672)
		(width 0.0889)
		(layer "F.Cu")
		(net "P3E_PCH_E1S_RX_DP<2>")
	)
	(segment
		(start 348.13748 -50.951384)
		(end 348.880176 -50.951384)
		(width 0.0889)
		(layer "F.Cu")
		(net "P3E_PCH_E1S_RX_DP<2>")
	)
	(segment
		(start 364.8964 -48.962056)
		(end 364.8964 -48.419258)
		(width 0.14732)
		(layer "In6.Cu")
		(net "P3E_PCH_E1S_RX_DP<2>")
	)
	(segment
		(start 239.80013 -59.48299)
		(end 238.420402 -58.91149)
		(width 0.14732)
		(layer "In6.Cu")
		(net "P3E_PCH_E1S_RX_DP<2>")
	)
	(segment
		(start 361.423204 -52.435252)
		(end 361.423204 -52.25923)
		(width 0.14732)
		(layer "In6.Cu")
		(net "P3E_PCH_E1S_RX_DP<2>")
	)
	(segment
		(start 259.306314 -60.378848)
		(end 249.38482 -60.378848)
		(width 0.14732)
		(layer "In6.Cu")
		(net "P3E_PCH_E1S_RX_DP<2>")
	)
	(segment
		(start 242.028218 -59.865768)
		(end 240.729262 -59.673236)
		(width 0.14732)
		(layer "In6.Cu")
		(net "P3E_PCH_E1S_RX_DP<2>")
	)
	(segment
		(start 363.021372 -40.9829)
		(end 362.880656 -40.642286)
		(width 0.14732)
		(layer "In6.Cu")
		(net "P3E_PCH_E1S_RX_DP<2>")
	)
	(segment
		(start 362.880656 -40.642286)
		(end 362.958888 -40.45331)
		(width 0.14732)
		(layer "In6.Cu")
		(net "P3E_PCH_E1S_RX_DP<2>")
	)
	(segment
		(start 361.423204 -52.25923)
		(end 361.732322 -51.950112)
		(width 0.14732)
		(layer "In6.Cu")
		(net "P3E_PCH_E1S_RX_DP<2>")
	)
	(segment
		(start 232.77576 -56.212232)
		(end 229.49154 -56.212232)
		(width 0.14732)
		(layer "In6.Cu")
		(net "P3E_PCH_E1S_RX_DP<2>")
	)
	(segment
		(start 356.763574 -32.240728)
		(end 355.878384 -32.240728)
		(width 0.14732)
		(layer "In6.Cu")
		(net "P3E_PCH_E1S_RX_DP<2>")
	)
	(segment
		(start 363.83341 -42.564558)
		(end 363.62894 -42.070528)
		(width 0.14732)
		(layer "In6.Cu")
		(net "P3E_PCH_E1S_RX_DP<2>")
	)
	(segment
		(start 270.001238 -45.400468)
		(end 265.938254 -45.400468)
		(width 0.14732)
		(layer "In6.Cu")
		(net "P3E_PCH_E1S_RX_DP<2>")
	)
	(segment
		(start 364.8964 -45.130466)
		(end 364.48111 -44.127674)
		(width 0.14732)
		(layer "In6.Cu")
		(net "P3E_PCH_E1S_RX_DP<2>")
	)
	(segment
		(start 360.377486 -52.631848)
		(end 360.499406 -52.753768)
		(width 0.14732)
		(layer "In6.Cu")
		(net "P3E_PCH_E1S_RX_DP<2>")
	)
	(segment
		(start 363.62894 -42.070528)
		(end 363.43971 -41.992296)
		(width 0.14732)
		(layer "In6.Cu")
		(net "P3E_PCH_E1S_RX_DP<2>")
	)
	(segment
		(start 352.672904 -28.327096)
		(end 352.672142 -28.325826)
		(width 0.14732)
		(layer "In6.Cu")
		(net "P3E_PCH_E1S_RX_DP<2>")
	)
	(segment
		(start 364.8964 -47.189898)
		(end 364.75162 -47.045118)
		(width 0.14732)
		(layer "In6.Cu")
		(net "P3E_PCH_E1S_RX_DP<2>")
	)
	(segment
		(start 262.16356 -58.288174)
		(end 260.614922 -59.836812)
		(width 0.14732)
		(layer "In6.Cu")
		(net "P3E_PCH_E1S_RX_DP<2>")
	)
	(segment
		(start 276.362414 -42.765726)
		(end 270.001238 -45.400468)
		(width 0.14732)
		(layer "In6.Cu")
		(net "P3E_PCH_E1S_RX_DP<2>")
	)
	(segment
		(start 325.77151 -18.664428)
		(end 321.833748 -18.664428)
		(width 0.14732)
		(layer "In6.Cu")
		(net "P3E_PCH_E1S_RX_DP<2>")
	)
	(segment
		(start 357.705406 -52.631848)
		(end 358.142286 -52.631848)
		(width 0.14732)
		(layer "In6.Cu")
		(net "P3E_PCH_E1S_RX_DP<2>")
	)
	(segment
		(start 358.823006 -52.631848)
		(end 359.259886 -52.631848)
		(width 0.14732)
		(layer "In6.Cu")
		(net "P3E_PCH_E1S_RX_DP<2>")
	)
	(segment
		(start 364.290356 -49.5681)
		(end 364.8964 -48.962056)
		(width 0.14732)
		(layer "In6.Cu")
		(net "P3E_PCH_E1S_RX_DP<2>")
	)
	(segment
		(start 364.75162 -48.274478)
		(end 364.75162 -47.906178)
		(width 0.14732)
		(layer "In6.Cu")
		(net "P3E_PCH_E1S_RX_DP<2>")
	)
	(segment
		(start 363.376972 -41.462452)
		(end 363.210856 -41.061132)
		(width 0.14732)
		(layer "In6.Cu")
		(net "P3E_PCH_E1S_RX_DP<2>")
	)
	(segment
		(start 364.15091 -43.708828)
		(end 364.229396 -43.519598)
		(width 0.14732)
		(layer "In6.Cu")
		(net "P3E_PCH_E1S_RX_DP<2>")
	)
	(segment
		(start 355.878384 -32.240728)
		(end 354.860606 -31.821374)
		(width 0.14732)
		(layer "In6.Cu")
		(net "P3E_PCH_E1S_RX_DP<2>")
	)
	(segment
		(start 363.32033 -50.362104)
		(end 363.496352 -50.362104)
		(width 0.14732)
		(layer "In6.Cu")
		(net "P3E_PCH_E1S_RX_DP<2>")
	)
	(segment
		(start 286.913828 -32.214566)
		(end 276.362414 -42.765726)
		(width 0.14732)
		(layer "In6.Cu")
		(net "P3E_PCH_E1S_RX_DP<2>")
	)
	(segment
		(start 355.662484 -51.269646)
		(end 357.146606 -52.753768)
		(width 0.14732)
		(layer "In6.Cu")
		(net "P3E_PCH_E1S_RX_DP<2>")
	)
	(segment
		(start 359.818686 -52.753768)
		(end 359.940606 -52.631848)
		(width 0.14732)
		(layer "In6.Cu")
		(net "P3E_PCH_E1S_RX_DP<2>")
	)
	(segment
		(start 239.799876 -59.48299)
		(end 239.80013 -59.48299)
		(width 0.14732)
		(layer "In6.Cu")
		(net "P3E_PCH_E1S_RX_DP<2>")
	)
	(segment
		(start 364.229396 -43.519598)
		(end 364.085632 -43.172634)
		(width 0.14732)
		(layer "In6.Cu")
		(net "P3E_PCH_E1S_RX_DP<2>")
	)
	(segment
		(start 359.381806 -52.753768)
		(end 359.818686 -52.753768)
		(width 0.14732)
		(layer "In6.Cu")
		(net "P3E_PCH_E1S_RX_DP<2>")
	)
	(segment
		(start 265.938254 -45.400468)
		(end 263.032748 -48.305974)
		(width 0.14732)
		(layer "In6.Cu")
		(net "P3E_PCH_E1S_RX_DP<2>")
	)
	(segment
		(start 359.259886 -52.631848)
		(end 359.381806 -52.753768)
		(width 0.14732)
		(layer "In6.Cu")
		(net "P3E_PCH_E1S_RX_DP<2>")
	)
	(segment
		(start 321.833748 -18.664428)
		(end 303.234598 -22.364192)
		(width 0.14732)
		(layer "In6.Cu")
		(net "P3E_PCH_E1S_RX_DP<2>")
	)
	(segment
		(start 364.75162 -47.906178)
		(end 364.8964 -47.761398)
		(width 0.14732)
		(layer "In6.Cu")
		(net "P3E_PCH_E1S_RX_DP<2>")
	)
	(segment
		(start 353.596956 -30.557724)
		(end 352.672904 -28.327096)
		(width 0.14732)
		(layer "In6.Cu")
		(net "P3E_PCH_E1S_RX_DP<2>")
	)
	(segment
		(start 361.104688 -52.753768)
		(end 361.423204 -52.435252)
		(width 0.14732)
		(layer "In6.Cu")
		(net "P3E_PCH_E1S_RX_DP<2>")
	)
	(segment
		(start 337.500976 -18.387568)
		(end 327.163684 -18.387568)
		(width 0.14732)
		(layer "In6.Cu")
		(net "P3E_PCH_E1S_RX_DP<2>")
	)
	(segment
		(start 354.860606 -31.821374)
		(end 353.596956 -30.557724)
		(width 0.14732)
		(layer "In6.Cu")
		(net "P3E_PCH_E1S_RX_DP<2>")
	)
	(segment
		(start 352.672142 -28.325826)
		(end 347.995494 -21.326602)
		(width 0.14732)
		(layer "In6.Cu")
		(net "P3E_PCH_E1S_RX_DP<2>")
	)
	(segment
		(start 362.702348 -51.156108)
		(end 363.011212 -50.847244)
		(width 0.14732)
		(layer "In6.Cu")
		(net "P3E_PCH_E1S_RX_DP<2>")
	)
	(segment
		(start 357.146606 -52.753768)
		(end 357.583486 -52.753768)
		(width 0.14732)
		(layer "In6.Cu")
		(net "P3E_PCH_E1S_RX_DP<2>")
	)
	(segment
		(start 303.234598 -22.364192)
		(end 299.077634 -24.086058)
		(width 0.14732)
		(layer "In6.Cu")
		(net "P3E_PCH_E1S_RX_DP<2>")
	)
	(segment
		(start 363.29874 -41.651682)
		(end 363.376972 -41.462452)
		(width 0.14732)
		(layer "In6.Cu")
		(net "P3E_PCH_E1S_RX_DP<2>")
	)
	(segment
		(start 359.940606 -52.631848)
		(end 360.377486 -52.631848)
		(width 0.14732)
		(layer "In6.Cu")
		(net "P3E_PCH_E1S_RX_DP<2>")
	)
	(segment
		(start 364.8964 -46.532038)
		(end 364.8964 -45.130466)
		(width 0.14732)
		(layer "In6.Cu")
		(net "P3E_PCH_E1S_RX_DP<2>")
	)
	(segment
		(start 363.805216 -50.05324)
		(end 363.805216 -49.877218)
		(width 0.14732)
		(layer "In6.Cu")
		(net "P3E_PCH_E1S_RX_DP<2>")
	)
	(segment
		(start 262.16356 -50.404014)
		(end 262.16356 -58.288174)
		(width 0.14732)
		(layer "In6.Cu")
		(net "P3E_PCH_E1S_RX_DP<2>")
	)
	(segment
		(start 364.75162 -46.676818)
		(end 364.8964 -46.532038)
		(width 0.14732)
		(layer "In6.Cu")
		(net "P3E_PCH_E1S_RX_DP<2>")
	)
	(segment
		(start 239.825022 -59.493404)
		(end 239.799876 -59.48299)
		(width 0.14732)
		(layer "In6.Cu")
		(net "P3E_PCH_E1S_RX_DP<2>")
	)
	(segment
		(start 364.8964 -47.761398)
		(end 364.8964 -47.189898)
		(width 0.14732)
		(layer "In6.Cu")
		(net "P3E_PCH_E1S_RX_DP<2>")
	)
	(segment
		(start 248.146062 -59.865768)
		(end 242.028218 -59.865768)
		(width 0.14732)
		(layer "In6.Cu")
		(net "P3E_PCH_E1S_RX_DP<2>")
	)
	(segment
		(start 237.803436 -58.294524)
		(end 232.77576 -56.212232)
		(width 0.14732)
		(layer "In6.Cu")
		(net "P3E_PCH_E1S_RX_DP<2>")
	)
	(segment
		(start 363.755178 -42.753788)
		(end 363.83341 -42.564558)
		(width 0.14732)
		(layer "In6.Cu")
		(net "P3E_PCH_E1S_RX_DP<2>")
	)
	(segment
		(start 363.210856 -41.061132)
		(end 363.021372 -40.9829)
		(width 0.14732)
		(layer "In6.Cu")
		(net "P3E_PCH_E1S_RX_DP<2>")
	)
	(segment
		(start 229.49154 -56.212232)
		(end 229.1969 -56.506872)
		(width 0.14732)
		(layer "In6.Cu")
		(net "P3E_PCH_E1S_RX_DP<2>")
	)
	(segment
		(start 355.957124 -50.207672)
		(end 355.662484 -50.502312)
		(width 0.14732)
		(layer "In6.Cu")
		(net "P3E_PCH_E1S_RX_DP<2>")
	)
	(segment
		(start 299.077634 -24.086058)
		(end 286.913828 -32.214566)
		(width 0.14732)
		(layer "In6.Cu")
		(net "P3E_PCH_E1S_RX_DP<2>")
	)
	(segment
		(start 327.163684 -18.387568)
		(end 325.77151 -18.664428)
		(width 0.14732)
		(layer "In6.Cu")
		(net "P3E_PCH_E1S_RX_DP<2>")
	)
	(segment
		(start 260.614922 -59.836812)
		(end 259.306314 -60.378848)
		(width 0.14732)
		(layer "In6.Cu")
		(net "P3E_PCH_E1S_RX_DP<2>")
	)
	(segment
		(start 240.729262 -59.673236)
		(end 239.825022 -59.493404)
		(width 0.14732)
		(layer "In6.Cu")
		(net "P3E_PCH_E1S_RX_DP<2>")
	)
	(segment
		(start 238.420402 -58.91149)
		(end 237.803436 -58.294524)
		(width 0.14732)
		(layer "In6.Cu")
		(net "P3E_PCH_E1S_RX_DP<2>")
	)
	(segment
		(start 263.032748 -48.305974)
		(end 262.16356 -50.404014)
		(width 0.14732)
		(layer "In6.Cu")
		(net "P3E_PCH_E1S_RX_DP<2>")
	)
	(segment
		(start 363.011212 -50.847244)
		(end 363.011212 -50.671222)
		(width 0.14732)
		(layer "In6.Cu")
		(net "P3E_PCH_E1S_RX_DP<2>")
	)
	(segment
		(start 347.424248 -20.755102)
		(end 343.020396 -18.931128)
		(width 0.14732)
		(layer "In6.Cu")
		(net "P3E_PCH_E1S_RX_DP<2>")
	)
	(segment
		(start 362.526326 -51.156108)
		(end 362.702348 -51.156108)
		(width 0.14732)
		(layer "In6.Cu")
		(net "P3E_PCH_E1S_RX_DP<2>")
	)
	(segment
		(start 362.217208 -51.641248)
		(end 362.217208 -51.465226)
		(width 0.14732)
		(layer "In6.Cu")
		(net "P3E_PCH_E1S_RX_DP<2>")
	)
	(segment
		(start 363.896148 -43.094148)
		(end 363.755178 -42.753788)
		(width 0.14732)
		(layer "In6.Cu")
		(net "P3E_PCH_E1S_RX_DP<2>")
	)
	(segment
		(start 363.496352 -50.362104)
		(end 363.805216 -50.05324)
		(width 0.14732)
		(layer "In6.Cu")
		(net "P3E_PCH_E1S_RX_DP<2>")
	)
	(segment
		(start 363.011212 -50.671222)
		(end 363.32033 -50.362104)
		(width 0.14732)
		(layer "In6.Cu")
		(net "P3E_PCH_E1S_RX_DP<2>")
	)
	(segment
		(start 362.217208 -51.465226)
		(end 362.526326 -51.156108)
		(width 0.14732)
		(layer "In6.Cu")
		(net "P3E_PCH_E1S_RX_DP<2>")
	)
	(segment
		(start 364.085632 -43.172634)
		(end 363.896148 -43.094148)
		(width 0.14732)
		(layer "In6.Cu")
		(net "P3E_PCH_E1S_RX_DP<2>")
	)
	(segment
		(start 355.662484 -50.502312)
		(end 355.662484 -51.269646)
		(width 0.14732)
		(layer "In6.Cu")
		(net "P3E_PCH_E1S_RX_DP<2>")
	)
	(segment
		(start 347.995494 -21.326602)
		(end 347.424248 -20.755102)
		(width 0.14732)
		(layer "In6.Cu")
		(net "P3E_PCH_E1S_RX_DP<2>")
	)
	(segment
		(start 363.805216 -49.877218)
		(end 364.114334 -49.5681)
		(width 0.14732)
		(layer "In6.Cu")
		(net "P3E_PCH_E1S_RX_DP<2>")
	)
	(segment
		(start 364.75162 -47.045118)
		(end 364.75162 -46.676818)
		(width 0.14732)
		(layer "In6.Cu")
		(net "P3E_PCH_E1S_RX_DP<2>")
	)
	(segment
		(start 357.656384 -32.610552)
		(end 356.763574 -32.240728)
		(width 0.14732)
		(layer "In6.Cu")
		(net "P3E_PCH_E1S_RX_DP<2>")
	)
	(segment
		(start 357.583486 -52.753768)
		(end 357.705406 -52.631848)
		(width 0.14732)
		(layer "In6.Cu")
		(net "P3E_PCH_E1S_RX_DP<2>")
	)
	(segment
		(start 343.020396 -18.931128)
		(end 337.500976 -18.387568)
		(width 0.14732)
		(layer "In6.Cu")
		(net "P3E_PCH_E1S_RX_DP<2>")
	)
	(segment
		(start 364.114334 -49.5681)
		(end 364.290356 -49.5681)
		(width 0.14732)
		(layer "In6.Cu")
		(net "P3E_PCH_E1S_RX_DP<2>")
	)
	(segment
		(start 361.162854 -36.117022)
		(end 357.656384 -32.610552)
		(width 0.14732)
		(layer "In6.Cu")
		(net "P3E_PCH_E1S_RX_DP<2>")
	)
	(segment
		(start 364.48111 -44.127674)
		(end 364.29188 -44.049442)
		(width 0.14732)
		(layer "In6.Cu")
		(net "P3E_PCH_E1S_RX_DP<2>")
	)
	(segment
		(start 361.908344 -51.950112)
		(end 362.217208 -51.641248)
		(width 0.14732)
		(layer "In6.Cu")
		(net "P3E_PCH_E1S_RX_DP<2>")
	)
	(segment
		(start 363.43971 -41.992296)
		(end 363.29874 -41.651682)
		(width 0.14732)
		(layer "In6.Cu")
		(net "P3E_PCH_E1S_RX_DP<2>")
	)
	(segment
		(start 364.29188 -44.049442)
		(end 364.15091 -43.708828)
		(width 0.14732)
		(layer "In6.Cu")
		(net "P3E_PCH_E1S_RX_DP<2>")
	)
	(segment
		(start 360.499406 -52.753768)
		(end 361.104688 -52.753768)
		(width 0.14732)
		(layer "In6.Cu")
		(net "P3E_PCH_E1S_RX_DP<2>")
	)
	(segment
		(start 358.142286 -52.631848)
		(end 358.264206 -52.753768)
		(width 0.14732)
		(layer "In6.Cu")
		(net "P3E_PCH_E1S_RX_DP<2>")
	)
	(segment
		(start 361.732322 -51.950112)
		(end 361.908344 -51.950112)
		(width 0.14732)
		(layer "In6.Cu")
		(net "P3E_PCH_E1S_RX_DP<2>")
	)
	(segment
		(start 362.958888 -40.45331)
		(end 361.162854 -36.117022)
		(width 0.14732)
		(layer "In6.Cu")
		(net "P3E_PCH_E1S_RX_DP<2>")
	)
	(segment
		(start 364.8964 -48.419258)
		(end 364.75162 -48.274478)
		(width 0.14732)
		(layer "In6.Cu")
		(net "P3E_PCH_E1S_RX_DP<2>")
	)
	(segment
		(start 249.38482 -60.378848)
		(end 248.146062 -59.865768)
		(width 0.14732)
		(layer "In6.Cu")
		(net "P3E_PCH_E1S_RX_DP<2>")
	)
	(segment
		(start 358.701086 -52.753768)
		(end 358.823006 -52.631848)
		(width 0.14732)
		(layer "In6.Cu")
		(net "P3E_PCH_E1S_RX_DP<2>")
	)
	(segment
		(start 358.264206 -52.753768)
		(end 358.701086 -52.753768)
		(width 0.14732)
		(layer "In6.Cu")
		(net "P3E_PCH_E1S_RX_DP<2>")
	)
	(segment
		(start 352.628708 -51.051714)
		(end 352.727514 -50.952908)
		(width 0.0889)
		(layer "F.Cu")
		(net "P3E_PCH_E1S_RX_DP<1>")
	)
	(segment
		(start 352.352102 -50.952908)
		(end 352.450908 -51.051714)
		(width 0.0889)
		(layer "F.Cu")
		(net "P3E_PCH_E1S_RX_DP<1>")
	)
	(segment
		(start 348.44101 -50.451258)
		(end 348.61881 -50.451258)
		(width 0.0889)
		(layer "F.Cu")
		(net "P3E_PCH_E1S_RX_DP<1>")
	)
	(segment
		(start 347.516958 -50.451258)
		(end 347.613478 -50.547778)
		(width 0.0889)
		(layer "F.Cu")
		(net "P3E_PCH_E1S_RX_DP<1>")
	)
	(segment
		(start 351.25025 -50.952908)
		(end 351.34677 -51.049428)
		(width 0.0889)
		(layer "F.Cu")
		(net "P3E_PCH_E1S_RX_DP<1>")
	)
	(segment
		(start 350.79813 -51.049428)
		(end 350.97593 -51.049428)
		(width 0.0889)
		(layer "F.Cu")
		(net "P3E_PCH_E1S_RX_DP<1>")
	)
	(segment
		(start 231.557576 -54.565042)
		(end 232.000044 -54.565042)
		(width 0.13208)
		(layer "F.Cu")
		(net "P3E_PCH_E1S_RX_DP<1>")
	)
	(segment
		(start 349.698056 -50.952908)
		(end 350.15297 -50.952908)
		(width 0.0889)
		(layer "F.Cu")
		(net "P3E_PCH_E1S_RX_DP<1>")
	)
	(segment
		(start 350.42729 -51.049428)
		(end 350.52381 -50.952908)
		(width 0.0889)
		(layer "F.Cu")
		(net "P3E_PCH_E1S_RX_DP<1>")
	)
	(segment
		(start 350.15297 -50.952908)
		(end 350.24949 -51.049428)
		(width 0.0889)
		(layer "F.Cu")
		(net "P3E_PCH_E1S_RX_DP<1>")
	)
	(segment
		(start 348.164404 -50.550064)
		(end 348.342204 -50.550064)
		(width 0.0889)
		(layer "F.Cu")
		(net "P3E_PCH_E1S_RX_DP<1>")
	)
	(segment
		(start 348.717616 -50.550064)
		(end 348.895416 -50.550064)
		(width 0.0889)
		(layer "F.Cu")
		(net "P3E_PCH_E1S_RX_DP<1>")
	)
	(segment
		(start 352.727514 -50.952908)
		(end 353.19716 -50.952908)
		(width 0.0889)
		(layer "F.Cu")
		(net "P3E_PCH_E1S_RX_DP<1>")
	)
	(segment
		(start 353.19716 -50.952908)
		(end 353.39782 -50.752248)
		(width 0.0889)
		(layer "F.Cu")
		(net "P3E_PCH_E1S_RX_DP<1>")
	)
	(segment
		(start 347.791278 -50.547778)
		(end 347.887798 -50.451258)
		(width 0.0889)
		(layer "F.Cu")
		(net "P3E_PCH_E1S_RX_DP<1>")
	)
	(segment
		(start 351.897696 -51.051714)
		(end 352.075496 -51.051714)
		(width 0.0889)
		(layer "F.Cu")
		(net "P3E_PCH_E1S_RX_DP<1>")
	)
	(segment
		(start 349.196406 -50.451258)
		(end 349.698056 -50.952908)
		(width 0.0889)
		(layer "F.Cu")
		(net "P3E_PCH_E1S_RX_DP<1>")
	)
	(segment
		(start 351.34677 -51.049428)
		(end 351.52457 -51.049428)
		(width 0.0889)
		(layer "F.Cu")
		(net "P3E_PCH_E1S_RX_DP<1>")
	)
	(segment
		(start 351.52457 -51.049428)
		(end 351.62109 -50.952908)
		(width 0.0889)
		(layer "F.Cu")
		(net "P3E_PCH_E1S_RX_DP<1>")
	)
	(segment
		(start 350.24949 -51.049428)
		(end 350.42729 -51.049428)
		(width 0.0889)
		(layer "F.Cu")
		(net "P3E_PCH_E1S_RX_DP<1>")
	)
	(segment
		(start 348.61881 -50.451258)
		(end 348.717616 -50.550064)
		(width 0.0889)
		(layer "F.Cu")
		(net "P3E_PCH_E1S_RX_DP<1>")
	)
	(segment
		(start 348.065598 -50.451258)
		(end 348.164404 -50.550064)
		(width 0.0889)
		(layer "F.Cu")
		(net "P3E_PCH_E1S_RX_DP<1>")
	)
	(segment
		(start 352.174302 -50.952908)
		(end 352.352102 -50.952908)
		(width 0.0889)
		(layer "F.Cu")
		(net "P3E_PCH_E1S_RX_DP<1>")
	)
	(segment
		(start 350.97593 -51.049428)
		(end 351.07245 -50.952908)
		(width 0.0889)
		(layer "F.Cu")
		(net "P3E_PCH_E1S_RX_DP<1>")
	)
	(segment
		(start 348.342204 -50.550064)
		(end 348.44101 -50.451258)
		(width 0.0889)
		(layer "F.Cu")
		(net "P3E_PCH_E1S_RX_DP<1>")
	)
	(segment
		(start 346.799662 -50.451258)
		(end 347.516958 -50.451258)
		(width 0.0889)
		(layer "F.Cu")
		(net "P3E_PCH_E1S_RX_DP<1>")
	)
	(segment
		(start 353.39782 -50.752248)
		(end 353.39782 -50.544476)
		(width 0.0889)
		(layer "F.Cu")
		(net "P3E_PCH_E1S_RX_DP<1>")
	)
	(segment
		(start 231.40416 -54.411626)
		(end 231.557576 -54.565042)
		(width 0.13208)
		(layer "F.Cu")
		(net "P3E_PCH_E1S_RX_DP<1>")
	)
	(segment
		(start 350.70161 -50.952908)
		(end 350.79813 -51.049428)
		(width 0.0889)
		(layer "F.Cu")
		(net "P3E_PCH_E1S_RX_DP<1>")
	)
	(segment
		(start 350.52381 -50.952908)
		(end 350.70161 -50.952908)
		(width 0.0889)
		(layer "F.Cu")
		(net "P3E_PCH_E1S_RX_DP<1>")
	)
	(segment
		(start 352.075496 -51.051714)
		(end 352.174302 -50.952908)
		(width 0.0889)
		(layer "F.Cu")
		(net "P3E_PCH_E1S_RX_DP<1>")
	)
	(segment
		(start 230.792274 -54.411626)
		(end 231.40416 -54.411626)
		(width 0.13208)
		(layer "F.Cu")
		(net "P3E_PCH_E1S_RX_DP<1>")
	)
	(segment
		(start 352.450908 -51.051714)
		(end 352.628708 -51.051714)
		(width 0.0889)
		(layer "F.Cu")
		(net "P3E_PCH_E1S_RX_DP<1>")
	)
	(segment
		(start 351.07245 -50.952908)
		(end 351.25025 -50.952908)
		(width 0.0889)
		(layer "F.Cu")
		(net "P3E_PCH_E1S_RX_DP<1>")
	)
	(segment
		(start 348.895416 -50.550064)
		(end 348.994222 -50.451258)
		(width 0.0889)
		(layer "F.Cu")
		(net "P3E_PCH_E1S_RX_DP<1>")
	)
	(segment
		(start 230.49738 -54.70652)
		(end 230.792274 -54.411626)
		(width 0.13208)
		(layer "F.Cu")
		(net "P3E_PCH_E1S_RX_DP<1>")
	)
	(segment
		(start 347.613478 -50.547778)
		(end 347.791278 -50.547778)
		(width 0.0889)
		(layer "F.Cu")
		(net "P3E_PCH_E1S_RX_DP<1>")
	)
	(segment
		(start 351.79889 -50.952908)
		(end 351.897696 -51.051714)
		(width 0.0889)
		(layer "F.Cu")
		(net "P3E_PCH_E1S_RX_DP<1>")
	)
	(segment
		(start 353.39782 -50.544476)
		(end 353.734624 -50.207672)
		(width 0.0889)
		(layer "F.Cu")
		(net "P3E_PCH_E1S_RX_DP<1>")
	)
	(segment
		(start 347.887798 -50.451258)
		(end 348.065598 -50.451258)
		(width 0.0889)
		(layer "F.Cu")
		(net "P3E_PCH_E1S_RX_DP<1>")
	)
	(segment
		(start 351.62109 -50.952908)
		(end 351.79889 -50.952908)
		(width 0.0889)
		(layer "F.Cu")
		(net "P3E_PCH_E1S_RX_DP<1>")
	)
	(segment
		(start 348.994222 -50.451258)
		(end 349.196406 -50.451258)
		(width 0.0889)
		(layer "F.Cu")
		(net "P3E_PCH_E1S_RX_DP<1>")
	)
	(segment
		(start 338.739988 -17.032986)
		(end 336.001614 -16.763238)
		(width 0.14732)
		(layer "In6.Cu")
		(net "P3E_PCH_E1S_RX_DP<1>")
	)
	(segment
		(start 232.99166 -54.41188)
		(end 230.79202 -54.41188)
		(width 0.14732)
		(layer "In6.Cu")
		(net "P3E_PCH_E1S_RX_DP<1>")
	)
	(segment
		(start 363.272324 -52.086764)
		(end 363.272324 -51.910742)
		(width 0.14732)
		(layer "In6.Cu")
		(net "P3E_PCH_E1S_RX_DP<1>")
	)
	(segment
		(start 325.68769 -17.610328)
		(end 322.367656 -17.610328)
		(width 0.14732)
		(layer "In6.Cu")
		(net "P3E_PCH_E1S_RX_DP<1>")
	)
	(segment
		(start 363.757464 -51.601624)
		(end 364.066328 -51.29276)
		(width 0.14732)
		(layer "In6.Cu")
		(net "P3E_PCH_E1S_RX_DP<1>")
	)
	(segment
		(start 366.02162 -47.888398)
		(end 366.1664 -47.743618)
		(width 0.14732)
		(layer "In6.Cu")
		(net "P3E_PCH_E1S_RX_DP<1>")
	)
	(segment
		(start 354.87483 -52.42052)
		(end 355.135688 -52.681378)
		(width 0.14732)
		(layer "In6.Cu")
		(net "P3E_PCH_E1S_RX_DP<1>")
	)
	(segment
		(start 361.507024 -32.794956)
		(end 361.506262 -32.794702)
		(width 0.14732)
		(layer "In6.Cu")
		(net "P3E_PCH_E1S_RX_DP<1>")
	)
	(segment
		(start 364.066328 -51.116738)
		(end 364.375446 -50.80762)
		(width 0.14732)
		(layer "In6.Cu")
		(net "P3E_PCH_E1S_RX_DP<1>")
	)
	(segment
		(start 361.587034 -33.366964)
		(end 361.66552 -33.177734)
		(width 0.14732)
		(layer "In6.Cu")
		(net "P3E_PCH_E1S_RX_DP<1>")
	)
	(segment
		(start 353.734624 -50.207672)
		(end 353.439984 -50.502312)
		(width 0.14732)
		(layer "In6.Cu")
		(net "P3E_PCH_E1S_RX_DP<1>")
	)
	(segment
		(start 364.79607 -41.114726)
		(end 364.874556 -40.92575)
		(width 0.14732)
		(layer "In6.Cu")
		(net "P3E_PCH_E1S_RX_DP<1>")
	)
	(segment
		(start 365.189008 -42.062908)
		(end 365.26724 -41.873678)
		(width 0.14732)
		(layer "In6.Cu")
		(net "P3E_PCH_E1S_RX_DP<1>")
	)
	(segment
		(start 366.1664 -44.044362)
		(end 365.946944 -43.514264)
		(width 0.14732)
		(layer "In6.Cu")
		(net "P3E_PCH_E1S_RX_DP<1>")
	)
	(segment
		(start 230.79202 -54.41188)
		(end 230.49738 -54.70652)
		(width 0.14732)
		(layer "In6.Cu")
		(net "P3E_PCH_E1S_RX_DP<1>")
	)
	(segment
		(start 356.065074 -53.815488)
		(end 356.5906 -53.815488)
		(width 0.14732)
		(layer "In6.Cu")
		(net "P3E_PCH_E1S_RX_DP<1>")
	)
	(segment
		(start 351.658174 -21.103082)
		(end 344.687906 -18.216118)
		(width 0.14732)
		(layer "In6.Cu")
		(net "P3E_PCH_E1S_RX_DP<1>")
	)
	(segment
		(start 365.345472 -50.013616)
		(end 366.1664 -49.192688)
		(width 0.14732)
		(layer "In6.Cu")
		(net "P3E_PCH_E1S_RX_DP<1>")
	)
	(segment
		(start 354.12553 -51.67122)
		(end 354.386388 -51.932078)
		(width 0.14732)
		(layer "In6.Cu")
		(net "P3E_PCH_E1S_RX_DP<1>")
	)
	(segment
		(start 361.5436 -53.815488)
		(end 363.272324 -52.086764)
		(width 0.14732)
		(layer "In6.Cu")
		(net "P3E_PCH_E1S_RX_DP<1>")
	)
	(segment
		(start 365.686086 -42.88536)
		(end 365.518954 -42.481754)
		(width 0.14732)
		(layer "In6.Cu")
		(net "P3E_PCH_E1S_RX_DP<1>")
	)
	(segment
		(start 364.066328 -51.29276)
		(end 364.066328 -51.116738)
		(width 0.14732)
		(layer "In6.Cu")
		(net "P3E_PCH_E1S_RX_DP<1>")
	)
	(segment
		(start 361.917488 -33.78581)
		(end 361.728004 -33.707578)
		(width 0.14732)
		(layer "In6.Cu")
		(net "P3E_PCH_E1S_RX_DP<1>")
	)
	(segment
		(start 365.126524 -41.533572)
		(end 364.93704 -41.45534)
		(width 0.14732)
		(layer "In6.Cu")
		(net "P3E_PCH_E1S_RX_DP<1>")
	)
	(segment
		(start 286.076644 -31.654496)
		(end 275.842222 -41.888664)
		(width 0.14732)
		(layer "In6.Cu")
		(net "P3E_PCH_E1S_RX_DP<1>")
	)
	(segment
		(start 361.365546 -32.454596)
		(end 361.176062 -32.37611)
		(width 0.14732)
		(layer "In6.Cu")
		(net "P3E_PCH_E1S_RX_DP<1>")
	)
	(segment
		(start 365.946944 -43.514264)
		(end 365.787432 -43.448478)
		(width 0.14732)
		(layer "In6.Cu")
		(net "P3E_PCH_E1S_RX_DP<1>")
	)
	(segment
		(start 366.02162 -48.256698)
		(end 366.02162 -47.888398)
		(width 0.14732)
		(layer "In6.Cu")
		(net "P3E_PCH_E1S_RX_DP<1>")
	)
	(segment
		(start 364.860332 -50.498756)
		(end 364.860332 -50.322734)
		(width 0.14732)
		(layer "In6.Cu")
		(net "P3E_PCH_E1S_RX_DP<1>")
	)
	(segment
		(start 357.1494 -53.693568)
		(end 357.27132 -53.815488)
		(width 0.14732)
		(layer "In6.Cu")
		(net "P3E_PCH_E1S_RX_DP<1>")
	)
	(segment
		(start 355.135688 -52.886102)
		(end 356.065074 -53.815488)
		(width 0.14732)
		(layer "In6.Cu")
		(net "P3E_PCH_E1S_RX_DP<1>")
	)
	(segment
		(start 365.620046 -43.044618)
		(end 365.686086 -42.88536)
		(width 0.14732)
		(layer "In6.Cu")
		(net "P3E_PCH_E1S_RX_DP<1>")
	)
	(segment
		(start 353.439984 -51.190398)
		(end 353.920806 -51.67122)
		(width 0.14732)
		(layer "In6.Cu")
		(net "P3E_PCH_E1S_RX_DP<1>")
	)
	(segment
		(start 357.27132 -53.815488)
		(end 361.5436 -53.815488)
		(width 0.14732)
		(layer "In6.Cu")
		(net "P3E_PCH_E1S_RX_DP<1>")
	)
	(segment
		(start 359.010458 -26.768552)
		(end 356.742238 -24.500078)
		(width 0.14732)
		(layer "In6.Cu")
		(net "P3E_PCH_E1S_RX_DP<1>")
	)
	(segment
		(start 344.687906 -18.216118)
		(end 338.739988 -17.032986)
		(width 0.14732)
		(layer "In6.Cu")
		(net "P3E_PCH_E1S_RX_DP<1>")
	)
	(segment
		(start 361.728004 -33.707578)
		(end 361.587034 -33.366964)
		(width 0.14732)
		(layer "In6.Cu")
		(net "P3E_PCH_E1S_RX_DP<1>")
	)
	(segment
		(start 356.5906 -53.815488)
		(end 356.71252 -53.693568)
		(width 0.14732)
		(layer "In6.Cu")
		(net "P3E_PCH_E1S_RX_DP<1>")
	)
	(segment
		(start 261.23392 -57.8993)
		(end 260.082284 -59.050936)
		(width 0.14732)
		(layer "In6.Cu")
		(net "P3E_PCH_E1S_RX_DP<1>")
	)
	(segment
		(start 366.1664 -49.192688)
		(end 366.1664 -48.401478)
		(width 0.14732)
		(layer "In6.Cu")
		(net "P3E_PCH_E1S_RX_DP<1>")
	)
	(segment
		(start 361.91698 -33.786572)
		(end 361.917488 -33.78581)
		(width 0.14732)
		(layer "In6.Cu")
		(net "P3E_PCH_E1S_RX_DP<1>")
	)
	(segment
		(start 298.63542 -23.262844)
		(end 286.076644 -31.654496)
		(width 0.14732)
		(layer "In6.Cu")
		(net "P3E_PCH_E1S_RX_DP<1>")
	)
	(segment
		(start 361.66552 -33.177734)
		(end 361.507024 -32.794956)
		(width 0.14732)
		(layer "In6.Cu")
		(net "P3E_PCH_E1S_RX_DP<1>")
	)
	(segment
		(start 364.93704 -41.45534)
		(end 364.79607 -41.114726)
		(width 0.14732)
		(layer "In6.Cu")
		(net "P3E_PCH_E1S_RX_DP<1>")
	)
	(segment
		(start 364.860332 -50.322734)
		(end 365.16945 -50.013616)
		(width 0.14732)
		(layer "In6.Cu")
		(net "P3E_PCH_E1S_RX_DP<1>")
	)
	(segment
		(start 366.1664 -47.743618)
		(end 366.1664 -44.044362)
		(width 0.14732)
		(layer "In6.Cu")
		(net "P3E_PCH_E1S_RX_DP<1>")
	)
	(segment
		(start 366.1664 -48.401478)
		(end 366.02162 -48.256698)
		(width 0.14732)
		(layer "In6.Cu")
		(net "P3E_PCH_E1S_RX_DP<1>")
	)
	(segment
		(start 365.16945 -50.013616)
		(end 365.345472 -50.013616)
		(width 0.14732)
		(layer "In6.Cu")
		(net "P3E_PCH_E1S_RX_DP<1>")
	)
	(segment
		(start 355.135688 -52.681378)
		(end 355.135688 -52.886102)
		(width 0.14732)
		(layer "In6.Cu")
		(net "P3E_PCH_E1S_RX_DP<1>")
	)
	(segment
		(start 365.26724 -41.873678)
		(end 365.126524 -41.533572)
		(width 0.14732)
		(layer "In6.Cu")
		(net "P3E_PCH_E1S_RX_DP<1>")
	)
	(segment
		(start 354.670106 -52.42052)
		(end 354.87483 -52.42052)
		(width 0.14732)
		(layer "In6.Cu")
		(net "P3E_PCH_E1S_RX_DP<1>")
	)
	(segment
		(start 269.693898 -44.435268)
		(end 265.538204 -44.435268)
		(width 0.14732)
		(layer "In6.Cu")
		(net "P3E_PCH_E1S_RX_DP<1>")
	)
	(segment
		(start 354.386388 -51.932078)
		(end 354.386388 -52.136802)
		(width 0.14732)
		(layer "In6.Cu")
		(net "P3E_PCH_E1S_RX_DP<1>")
	)
	(segment
		(start 322.367656 -17.610328)
		(end 302.962056 -21.470366)
		(width 0.14732)
		(layer "In6.Cu")
		(net "P3E_PCH_E1S_RX_DP<1>")
	)
	(segment
		(start 365.787432 -43.448478)
		(end 365.620046 -43.044618)
		(width 0.14732)
		(layer "In6.Cu")
		(net "P3E_PCH_E1S_RX_DP<1>")
	)
	(segment
		(start 262.273796 -47.699676)
		(end 261.23392 -50.210212)
		(width 0.14732)
		(layer "In6.Cu")
		(net "P3E_PCH_E1S_RX_DP<1>")
	)
	(segment
		(start 356.742238 -24.500078)
		(end 351.658174 -21.103082)
		(width 0.14732)
		(layer "In6.Cu")
		(net "P3E_PCH_E1S_RX_DP<1>")
	)
	(segment
		(start 356.71252 -53.693568)
		(end 357.1494 -53.693568)
		(width 0.14732)
		(layer "In6.Cu")
		(net "P3E_PCH_E1S_RX_DP<1>")
	)
	(segment
		(start 354.386388 -52.136802)
		(end 354.670106 -52.42052)
		(width 0.14732)
		(layer "In6.Cu")
		(net "P3E_PCH_E1S_RX_DP<1>")
	)
	(segment
		(start 259.133086 -59.444128)
		(end 249.845322 -59.444128)
		(width 0.14732)
		(layer "In6.Cu")
		(net "P3E_PCH_E1S_RX_DP<1>")
	)
	(segment
		(start 302.962056 -21.470366)
		(end 298.63542 -23.262844)
		(width 0.14732)
		(layer "In6.Cu")
		(net "P3E_PCH_E1S_RX_DP<1>")
	)
	(segment
		(start 260.082284 -59.050936)
		(end 259.133086 -59.444128)
		(width 0.14732)
		(layer "In6.Cu")
		(net "P3E_PCH_E1S_RX_DP<1>")
	)
	(segment
		(start 336.001614 -16.763238)
		(end 329.946762 -16.763238)
		(width 0.14732)
		(layer "In6.Cu")
		(net "P3E_PCH_E1S_RX_DP<1>")
	)
	(segment
		(start 361.035092 -32.03575)
		(end 361.113578 -31.84652)
		(width 0.14732)
		(layer "In6.Cu")
		(net "P3E_PCH_E1S_RX_DP<1>")
	)
	(segment
		(start 247.95988 -57.980326)
		(end 243.71808 -56.223408)
		(width 0.14732)
		(layer "In6.Cu")
		(net "P3E_PCH_E1S_RX_DP<1>")
	)
	(segment
		(start 353.439984 -50.502312)
		(end 353.439984 -51.190398)
		(width 0.14732)
		(layer "In6.Cu")
		(net "P3E_PCH_E1S_RX_DP<1>")
	)
	(segment
		(start 361.113578 -31.84652)
		(end 359.010458 -26.768552)
		(width 0.14732)
		(layer "In6.Cu")
		(net "P3E_PCH_E1S_RX_DP<1>")
	)
	(segment
		(start 364.874556 -40.92575)
		(end 361.91698 -33.786572)
		(width 0.14732)
		(layer "In6.Cu")
		(net "P3E_PCH_E1S_RX_DP<1>")
	)
	(segment
		(start 363.581442 -51.601624)
		(end 363.757464 -51.601624)
		(width 0.14732)
		(layer "In6.Cu")
		(net "P3E_PCH_E1S_RX_DP<1>")
	)
	(segment
		(start 275.842222 -41.888664)
		(end 269.693898 -44.435268)
		(width 0.14732)
		(layer "In6.Cu")
		(net "P3E_PCH_E1S_RX_DP<1>")
	)
	(segment
		(start 243.71808 -56.223408)
		(end 237.36554 -56.223408)
		(width 0.14732)
		(layer "In6.Cu")
		(net "P3E_PCH_E1S_RX_DP<1>")
	)
	(segment
		(start 365.518954 -42.481754)
		(end 365.519208 -42.481754)
		(width 0.14732)
		(layer "In6.Cu")
		(net "P3E_PCH_E1S_RX_DP<1>")
	)
	(segment
		(start 329.946762 -16.763238)
		(end 325.68769 -17.610328)
		(width 0.14732)
		(layer "In6.Cu")
		(net "P3E_PCH_E1S_RX_DP<1>")
	)
	(segment
		(start 249.845322 -59.444128)
		(end 249.12574 -59.146186)
		(width 0.14732)
		(layer "In6.Cu")
		(net "P3E_PCH_E1S_RX_DP<1>")
	)
	(segment
		(start 365.329978 -42.403522)
		(end 365.189008 -42.062908)
		(width 0.14732)
		(layer "In6.Cu")
		(net "P3E_PCH_E1S_RX_DP<1>")
	)
	(segment
		(start 365.519208 -42.481754)
		(end 365.329978 -42.403522)
		(width 0.14732)
		(layer "In6.Cu")
		(net "P3E_PCH_E1S_RX_DP<1>")
	)
	(segment
		(start 249.12574 -59.146186)
		(end 247.95988 -57.980326)
		(width 0.14732)
		(layer "In6.Cu")
		(net "P3E_PCH_E1S_RX_DP<1>")
	)
	(segment
		(start 361.176062 -32.37611)
		(end 361.035092 -32.03575)
		(width 0.14732)
		(layer "In6.Cu")
		(net "P3E_PCH_E1S_RX_DP<1>")
	)
	(segment
		(start 364.375446 -50.80762)
		(end 364.551468 -50.80762)
		(width 0.14732)
		(layer "In6.Cu")
		(net "P3E_PCH_E1S_RX_DP<1>")
	)
	(segment
		(start 364.551468 -50.80762)
		(end 364.860332 -50.498756)
		(width 0.14732)
		(layer "In6.Cu")
		(net "P3E_PCH_E1S_RX_DP<1>")
	)
	(segment
		(start 361.506262 -32.794702)
		(end 361.365546 -32.454596)
		(width 0.14732)
		(layer "In6.Cu")
		(net "P3E_PCH_E1S_RX_DP<1>")
	)
	(segment
		(start 265.538204 -44.435268)
		(end 262.273796 -47.699676)
		(width 0.14732)
		(layer "In6.Cu")
		(net "P3E_PCH_E1S_RX_DP<1>")
	)
	(segment
		(start 363.272324 -51.910742)
		(end 363.581442 -51.601624)
		(width 0.14732)
		(layer "In6.Cu")
		(net "P3E_PCH_E1S_RX_DP<1>")
	)
	(segment
		(start 353.920806 -51.67122)
		(end 354.12553 -51.67122)
		(width 0.14732)
		(layer "In6.Cu")
		(net "P3E_PCH_E1S_RX_DP<1>")
	)
	(segment
		(start 237.36554 -56.223408)
		(end 232.99166 -54.41188)
		(width 0.14732)
		(layer "In6.Cu")
		(net "P3E_PCH_E1S_RX_DP<1>")
	)
	(segment
		(start 261.23392 -50.210212)
		(end 261.23392 -57.8993)
		(width 0.14732)
		(layer "In6.Cu")
		(net "P3E_PCH_E1S_RX_DP<1>")
	)
	(segment
		(start 351.102676 -50.419508)
		(end 351.102676 -49.745138)
		(width 0.0889)
		(layer "F.Cu")
		(net "P3E_PCH_E1S_RX_DP<0>")
	)
	(segment
		(start 349.52305 -49.656238)
		(end 349.238316 -49.656238)
		(width 0.0889)
		(layer "F.Cu")
		(net "P3E_PCH_E1S_RX_DP<0>")
	)
	(segment
		(start 347.514418 -49.865026)
		(end 347.428566 -49.950878)
		(width 0.0889)
		(layer "F.Cu")
		(net "P3E_PCH_E1S_RX_DP<0>")
	)
	(segment
		(start 348.531688 -49.963832)
		(end 348.353888 -49.963832)
		(width 0.0889)
		(layer "F.Cu")
		(net "P3E_PCH_E1S_RX_DP<0>")
	)
	(segment
		(start 351.102676 -49.745138)
		(end 351.013776 -49.656238)
		(width 0.0889)
		(layer "F.Cu")
		(net "P3E_PCH_E1S_RX_DP<0>")
	)
	(segment
		(start 350.076262 -49.656238)
		(end 349.898462 -49.656238)
		(width 0.0889)
		(layer "F.Cu")
		(net "P3E_PCH_E1S_RX_DP<0>")
	)
	(segment
		(start 347.978476 -49.963832)
		(end 347.800676 -49.963832)
		(width 0.0889)
		(layer "F.Cu")
		(net "P3E_PCH_E1S_RX_DP<0>")
	)
	(segment
		(start 229.49027 -52.336446)
		(end 231.383078 -52.336446)
		(width 0.13208)
		(layer "F.Cu")
		(net "P3E_PCH_E1S_RX_DP<0>")
	)
	(segment
		(start 351.013776 -49.656238)
		(end 350.451674 -49.656238)
		(width 0.0889)
		(layer "F.Cu")
		(net "P3E_PCH_E1S_RX_DP<0>")
	)
	(segment
		(start 349.898462 -49.656238)
		(end 349.799656 -49.755044)
		(width 0.0889)
		(layer "F.Cu")
		(net "P3E_PCH_E1S_RX_DP<0>")
	)
	(segment
		(start 348.255082 -49.865026)
		(end 348.077282 -49.865026)
		(width 0.0889)
		(layer "F.Cu")
		(net "P3E_PCH_E1S_RX_DP<0>")
	)
	(segment
		(start 349.799656 -49.755044)
		(end 349.621856 -49.755044)
		(width 0.0889)
		(layer "F.Cu")
		(net "P3E_PCH_E1S_RX_DP<0>")
	)
	(segment
		(start 350.175068 -49.755044)
		(end 350.076262 -49.656238)
		(width 0.0889)
		(layer "F.Cu")
		(net "P3E_PCH_E1S_RX_DP<0>")
	)
	(segment
		(start 348.630494 -49.865026)
		(end 348.531688 -49.963832)
		(width 0.0889)
		(layer "F.Cu")
		(net "P3E_PCH_E1S_RX_DP<0>")
	)
	(segment
		(start 349.029528 -49.865026)
		(end 348.630494 -49.865026)
		(width 0.0889)
		(layer "F.Cu")
		(net "P3E_PCH_E1S_RX_DP<0>")
	)
	(segment
		(start 351.013776 -50.508408)
		(end 351.102676 -50.419508)
		(width 0.0889)
		(layer "F.Cu")
		(net "P3E_PCH_E1S_RX_DP<0>")
	)
	(segment
		(start 349.621856 -49.755044)
		(end 349.52305 -49.656238)
		(width 0.0889)
		(layer "F.Cu")
		(net "P3E_PCH_E1S_RX_DP<0>")
	)
	(segment
		(start 231.383078 -52.336446)
		(end 231.554528 -52.164996)
		(width 0.13208)
		(layer "F.Cu")
		(net "P3E_PCH_E1S_RX_DP<0>")
	)
	(segment
		(start 348.077282 -49.865026)
		(end 347.978476 -49.963832)
		(width 0.0889)
		(layer "F.Cu")
		(net "P3E_PCH_E1S_RX_DP<0>")
	)
	(segment
		(start 350.451674 -49.656238)
		(end 350.352868 -49.755044)
		(width 0.0889)
		(layer "F.Cu")
		(net "P3E_PCH_E1S_RX_DP<0>")
	)
	(segment
		(start 350.876362 -50.508408)
		(end 351.013776 -50.508408)
		(width 0.0889)
		(layer "F.Cu")
		(net "P3E_PCH_E1S_RX_DP<0>")
	)
	(segment
		(start 350.672908 -50.207672)
		(end 350.741742 -50.373788)
		(width 0.0889)
		(layer "F.Cu")
		(net "P3E_PCH_E1S_RX_DP<0>")
	)
	(segment
		(start 349.238316 -49.656238)
		(end 349.029528 -49.865026)
		(width 0.0889)
		(layer "F.Cu")
		(net "P3E_PCH_E1S_RX_DP<0>")
	)
	(segment
		(start 350.352868 -49.755044)
		(end 350.175068 -49.755044)
		(width 0.0889)
		(layer "F.Cu")
		(net "P3E_PCH_E1S_RX_DP<0>")
	)
	(segment
		(start 347.800676 -49.963832)
		(end 347.70187 -49.865026)
		(width 0.0889)
		(layer "F.Cu")
		(net "P3E_PCH_E1S_RX_DP<0>")
	)
	(segment
		(start 229.1969 -52.043076)
		(end 229.49027 -52.336446)
		(width 0.13208)
		(layer "F.Cu")
		(net "P3E_PCH_E1S_RX_DP<0>")
	)
	(segment
		(start 348.353888 -49.963832)
		(end 348.255082 -49.865026)
		(width 0.0889)
		(layer "F.Cu")
		(net "P3E_PCH_E1S_RX_DP<0>")
	)
	(segment
		(start 350.741742 -50.373788)
		(end 350.876362 -50.508408)
		(width 0.0889)
		(layer "F.Cu")
		(net "P3E_PCH_E1S_RX_DP<0>")
	)
	(segment
		(start 347.428566 -49.950878)
		(end 347.214698 -49.950878)
		(width 0.0889)
		(layer "F.Cu")
		(net "P3E_PCH_E1S_RX_DP<0>")
	)
	(segment
		(start 231.554528 -52.164996)
		(end 232.000044 -52.164996)
		(width 0.13208)
		(layer "F.Cu")
		(net "P3E_PCH_E1S_RX_DP<0>")
	)
	(segment
		(start 347.70187 -49.865026)
		(end 347.514418 -49.865026)
		(width 0.0889)
		(layer "F.Cu")
		(net "P3E_PCH_E1S_RX_DP<0>")
	)
	(segment
		(start 249.20702 -57.252108)
		(end 243.066062 -51.11115)
		(width 0.14732)
		(layer "In6.Cu")
		(net "P3E_PCH_E1S_RX_DP<0>")
	)
	(segment
		(start 274.991068 -40.75176)
		(end 269.21333 -43.144948)
		(width 0.14732)
		(layer "In6.Cu")
		(net "P3E_PCH_E1S_RX_DP<0>")
	)
	(segment
		(start 258.29514 -58.189368)
		(end 257.35788 -57.252108)
		(width 0.14732)
		(layer "In6.Cu")
		(net "P3E_PCH_E1S_RX_DP<0>")
	)
	(segment
		(start 260.649466 -48.36287)
		(end 260.649212 -48.36287)
		(width 0.14732)
		(layer "In6.Cu")
		(net "P3E_PCH_E1S_RX_DP<0>")
	)
	(segment
		(start 298.229782 -22.084792)
		(end 284.450536 -31.292292)
		(width 0.14732)
		(layer "In6.Cu")
		(net "P3E_PCH_E1S_RX_DP<0>")
	)
	(segment
		(start 261.239254 -46.938692)
		(end 260.649466 -48.36287)
		(width 0.14732)
		(layer "In6.Cu")
		(net "P3E_PCH_E1S_RX_DP<0>")
	)
	(segment
		(start 265.00328 -43.144948)
		(end 261.260082 -46.888146)
		(width 0.14732)
		(layer "In6.Cu")
		(net "P3E_PCH_E1S_RX_DP<0>")
	)
	(segment
		(start 260.02996 -57.392316)
		(end 259.386578 -58.035698)
		(width 0.14732)
		(layer "In6.Cu")
		(net "P3E_PCH_E1S_RX_DP<0>")
	)
	(segment
		(start 362.101892 -55.154068)
		(end 367.46688 -49.78908)
		(width 0.14732)
		(layer "In6.Cu")
		(net "P3E_PCH_E1S_RX_DP<0>")
	)
	(segment
		(start 336.33537 -15.559278)
		(end 329.789028 -15.559278)
		(width 0.14732)
		(layer "In6.Cu")
		(net "P3E_PCH_E1S_RX_DP<0>")
	)
	(segment
		(start 261.260082 -46.888146)
		(end 261.239 -46.938692)
		(width 0.14732)
		(layer "In6.Cu")
		(net "P3E_PCH_E1S_RX_DP<0>")
	)
	(segment
		(start 229.48011 -52.326286)
		(end 229.1969 -52.043076)
		(width 0.14732)
		(layer "In6.Cu")
		(net "P3E_PCH_E1S_RX_DP<0>")
	)
	(segment
		(start 240.945162 -50.894488)
		(end 237.488476 -52.326286)
		(width 0.14732)
		(layer "In6.Cu")
		(net "P3E_PCH_E1S_RX_DP<0>")
	)
	(segment
		(start 259.015992 -58.189368)
		(end 258.29514 -58.189368)
		(width 0.14732)
		(layer "In6.Cu")
		(net "P3E_PCH_E1S_RX_DP<0>")
	)
	(segment
		(start 367.46688 -43.20667)
		(end 360.579162 -26.578052)
		(width 0.14732)
		(layer "In6.Cu")
		(net "P3E_PCH_E1S_RX_DP<0>")
	)
	(segment
		(start 237.488476 -52.326286)
		(end 229.48011 -52.326286)
		(width 0.14732)
		(layer "In6.Cu")
		(net "P3E_PCH_E1S_RX_DP<0>")
	)
	(segment
		(start 261.239 -46.938692)
		(end 261.239254 -46.938692)
		(width 0.14732)
		(layer "In6.Cu")
		(net "P3E_PCH_E1S_RX_DP<0>")
	)
	(segment
		(start 350.967548 -50.502312)
		(end 350.967548 -51.204622)
		(width 0.14732)
		(layer "In6.Cu")
		(net "P3E_PCH_E1S_RX_DP<0>")
	)
	(segment
		(start 354.916994 -55.154068)
		(end 362.101892 -55.154068)
		(width 0.14732)
		(layer "In6.Cu")
		(net "P3E_PCH_E1S_RX_DP<0>")
	)
	(segment
		(start 302.414432 -20.351496)
		(end 298.229782 -22.084792)
		(width 0.14732)
		(layer "In6.Cu")
		(net "P3E_PCH_E1S_RX_DP<0>")
	)
	(segment
		(start 360.579162 -26.578052)
		(end 357.66883 -23.667212)
		(width 0.14732)
		(layer "In6.Cu")
		(net "P3E_PCH_E1S_RX_DP<0>")
	)
	(segment
		(start 284.450536 -31.292292)
		(end 274.991068 -40.75176)
		(width 0.14732)
		(layer "In6.Cu")
		(net "P3E_PCH_E1S_RX_DP<0>")
	)
	(segment
		(start 322.809616 -16.294608)
		(end 302.414432 -20.351496)
		(width 0.14732)
		(layer "In6.Cu")
		(net "P3E_PCH_E1S_RX_DP<0>")
	)
	(segment
		(start 344.81389 -16.832834)
		(end 340.446106 -15.9639)
		(width 0.14732)
		(layer "In6.Cu")
		(net "P3E_PCH_E1S_RX_DP<0>")
	)
	(segment
		(start 259.386578 -58.035698)
		(end 259.015992 -58.189368)
		(width 0.14732)
		(layer "In6.Cu")
		(net "P3E_PCH_E1S_RX_DP<0>")
	)
	(segment
		(start 340.446106 -15.9639)
		(end 336.33537 -15.559278)
		(width 0.14732)
		(layer "In6.Cu")
		(net "P3E_PCH_E1S_RX_DP<0>")
	)
	(segment
		(start 257.35788 -57.252108)
		(end 249.20702 -57.252108)
		(width 0.14732)
		(layer "In6.Cu")
		(net "P3E_PCH_E1S_RX_DP<0>")
	)
	(segment
		(start 350.672908 -50.207672)
		(end 350.967548 -50.502312)
		(width 0.14732)
		(layer "In6.Cu")
		(net "P3E_PCH_E1S_RX_DP<0>")
	)
	(segment
		(start 351.724214 -19.695414)
		(end 344.81389 -16.832834)
		(width 0.14732)
		(layer "In6.Cu")
		(net "P3E_PCH_E1S_RX_DP<0>")
	)
	(segment
		(start 260.02996 -49.857914)
		(end 260.02996 -57.392316)
		(width 0.14732)
		(layer "In6.Cu")
		(net "P3E_PCH_E1S_RX_DP<0>")
	)
	(segment
		(start 350.967548 -51.204622)
		(end 354.916994 -55.154068)
		(width 0.14732)
		(layer "In6.Cu")
		(net "P3E_PCH_E1S_RX_DP<0>")
	)
	(segment
		(start 269.21333 -43.144948)
		(end 265.00328 -43.144948)
		(width 0.14732)
		(layer "In6.Cu")
		(net "P3E_PCH_E1S_RX_DP<0>")
	)
	(segment
		(start 357.66883 -23.667212)
		(end 351.724214 -19.695414)
		(width 0.14732)
		(layer "In6.Cu")
		(net "P3E_PCH_E1S_RX_DP<0>")
	)
	(segment
		(start 242.543076 -50.894488)
		(end 240.945162 -50.894488)
		(width 0.14732)
		(layer "In6.Cu")
		(net "P3E_PCH_E1S_RX_DP<0>")
	)
	(segment
		(start 326.091804 -16.294608)
		(end 322.809616 -16.294608)
		(width 0.14732)
		(layer "In6.Cu")
		(net "P3E_PCH_E1S_RX_DP<0>")
	)
	(segment
		(start 329.789028 -15.559278)
		(end 326.091804 -16.294608)
		(width 0.14732)
		(layer "In6.Cu")
		(net "P3E_PCH_E1S_RX_DP<0>")
	)
	(segment
		(start 260.649212 -48.36287)
		(end 260.02996 -49.857914)
		(width 0.14732)
		(layer "In6.Cu")
		(net "P3E_PCH_E1S_RX_DP<0>")
	)
	(segment
		(start 243.066062 -51.11115)
		(end 242.543076 -50.894488)
		(width 0.14732)
		(layer "In6.Cu")
		(net "P3E_PCH_E1S_RX_DP<0>")
	)
	(segment
		(start 367.46688 -49.78908)
		(end 367.46688 -43.20667)
		(width 0.14732)
		(layer "In6.Cu")
		(net "P3E_PCH_E1S_RX_DP<0>")
	)
	(segment
		(start 346.75318 -51.14925)
		(end 346.98305 -51.14925)
		(width 0.0889)
		(layer "F.Cu")
		(net "P3E_PCH_E1S_RX_DN<3>")
	)
	(segment
		(start 231.580944 -57.565036)
		(end 231.400604 -57.745376)
		(width 0.13208)
		(layer "F.Cu")
		(net "P3E_PCH_E1S_RX_DN<3>")
	)
	(segment
		(start 346.21343 -51.451764)
		(end 346.415106 -51.368198)
		(width 0.0889)
		(layer "F.Cu")
		(net "P3E_PCH_E1S_RX_DN<3>")
	)
	(segment
		(start 232.000044 -57.565036)
		(end 231.580944 -57.565036)
		(width 0.13208)
		(layer "F.Cu")
		(net "P3E_PCH_E1S_RX_DN<3>")
	)
	(segment
		(start 346.50426 -51.279044)
		(end 346.580206 -51.213512)
		(width 0.0889)
		(layer "F.Cu")
		(net "P3E_PCH_E1S_RX_DN<3>")
	)
	(segment
		(start 349.2119 -51.653948)
		(end 352.2345 -51.653948)
		(width 0.0889)
		(layer "F.Cu")
		(net "P3E_PCH_E1S_RX_DN<3>")
	)
	(segment
		(start 348.80296 -51.245008)
		(end 349.2119 -51.653948)
		(width 0.0889)
		(layer "F.Cu")
		(net "P3E_PCH_E1S_RX_DN<3>")
	)
	(segment
		(start 230.79964 -57.745376)
		(end 230.49738 -57.443116)
		(width 0.13208)
		(layer "F.Cu")
		(net "P3E_PCH_E1S_RX_DN<3>")
	)
	(segment
		(start 357.660194 -50.544222)
		(end 357.323644 -50.207672)
		(width 0.0889)
		(layer "F.Cu")
		(net "P3E_PCH_E1S_RX_DN<3>")
	)
	(segment
		(start 345.96959 -51.451764)
		(end 346.21343 -51.451764)
		(width 0.0889)
		(layer "F.Cu")
		(net "P3E_PCH_E1S_RX_DN<3>")
	)
	(segment
		(start 231.400604 -57.745376)
		(end 230.79964 -57.745376)
		(width 0.13208)
		(layer "F.Cu")
		(net "P3E_PCH_E1S_RX_DN<3>")
	)
	(segment
		(start 352.481134 -51.900582)
		(end 356.691946 -51.900582)
		(width 0.0889)
		(layer "F.Cu")
		(net "P3E_PCH_E1S_RX_DN<3>")
	)
	(segment
		(start 346.98305 -51.14925)
		(end 347.078808 -51.245008)
		(width 0.0889)
		(layer "F.Cu")
		(net "P3E_PCH_E1S_RX_DN<3>")
	)
	(segment
		(start 356.691946 -51.900582)
		(end 357.660194 -50.932334)
		(width 0.0889)
		(layer "F.Cu")
		(net "P3E_PCH_E1S_RX_DN<3>")
	)
	(segment
		(start 346.415106 -51.368198)
		(end 346.50426 -51.279044)
		(width 0.0889)
		(layer "F.Cu")
		(net "P3E_PCH_E1S_RX_DN<3>")
	)
	(segment
		(start 357.660194 -50.932334)
		(end 357.660194 -50.544222)
		(width 0.0889)
		(layer "F.Cu")
		(net "P3E_PCH_E1S_RX_DN<3>")
	)
	(segment
		(start 347.078808 -51.245008)
		(end 348.80296 -51.245008)
		(width 0.0889)
		(layer "F.Cu")
		(net "P3E_PCH_E1S_RX_DN<3>")
	)
	(segment
		(start 352.2345 -51.653948)
		(end 352.481134 -51.900582)
		(width 0.0889)
		(layer "F.Cu")
		(net "P3E_PCH_E1S_RX_DN<3>")
	)
	(segment
		(start 346.580206 -51.213512)
		(end 346.75318 -51.14925)
		(width 0.0889)
		(layer "F.Cu")
		(net "P3E_PCH_E1S_RX_DN<3>")
	)
	(segment
		(start 361.36326 -51.369468)
		(end 363.92866 -48.804068)
		(width 0.14732)
		(layer "In6.Cu")
		(net "P3E_PCH_E1S_RX_DN<3>")
	)
	(segment
		(start 266.214098 -46.065948)
		(end 263.654286 -48.62576)
		(width 0.14732)
		(layer "In6.Cu")
		(net "P3E_PCH_E1S_RX_DN<3>")
	)
	(segment
		(start 261.00024 -60.386722)
		(end 259.418836 -61.041788)
		(width 0.14732)
		(layer "In6.Cu")
		(net "P3E_PCH_E1S_RX_DN<3>")
	)
	(segment
		(start 303.42713 -22.994112)
		(end 299.626274 -24.568404)
		(width 0.14732)
		(layer "In6.Cu")
		(net "P3E_PCH_E1S_RX_DN<3>")
	)
	(segment
		(start 362.561378 -43.094656)
		(end 361.785408 -41.220898)
		(width 0.14732)
		(layer "In6.Cu")
		(net "P3E_PCH_E1S_RX_DN<3>")
	)
	(segment
		(start 334.241394 -19.37385)
		(end 333.44231 -19.042888)
		(width 0.14732)
		(layer "In6.Cu")
		(net "P3E_PCH_E1S_RX_DN<3>")
	)
	(segment
		(start 345.769946 -33.541208)
		(end 340.45652 -25.588976)
		(width 0.14732)
		(layer "In6.Cu")
		(net "P3E_PCH_E1S_RX_DN<3>")
	)
	(segment
		(start 357.618284 -51.061366)
		(end 357.926386 -51.369468)
		(width 0.14732)
		(layer "In6.Cu")
		(net "P3E_PCH_E1S_RX_DN<3>")
	)
	(segment
		(start 276.933406 -43.322748)
		(end 273.622262 -44.694348)
		(width 0.14732)
		(layer "In6.Cu")
		(net "P3E_PCH_E1S_RX_DN<3>")
	)
	(segment
		(start 230.79202 -57.737756)
		(end 230.49738 -57.443116)
		(width 0.14732)
		(layer "In6.Cu")
		(net "P3E_PCH_E1S_RX_DN<3>")
	)
	(segment
		(start 259.418836 -61.041788)
		(end 249.185938 -61.041788)
		(width 0.14732)
		(layer "In6.Cu")
		(net "P3E_PCH_E1S_RX_DN<3>")
	)
	(segment
		(start 333.44231 -19.042888)
		(end 327.241408 -19.042888)
		(width 0.14732)
		(layer "In6.Cu")
		(net "P3E_PCH_E1S_RX_DN<3>")
	)
	(segment
		(start 358.597962 -38.033198)
		(end 355.725984 -36.49853)
		(width 0.14732)
		(layer "In6.Cu")
		(net "P3E_PCH_E1S_RX_DN<3>")
	)
	(segment
		(start 346.988892 -34.7599)
		(end 345.769946 -33.541208)
		(width 0.14732)
		(layer "In6.Cu")
		(net "P3E_PCH_E1S_RX_DN<3>")
	)
	(segment
		(start 325.427594 -19.403568)
		(end 321.477132 -19.403568)
		(width 0.14732)
		(layer "In6.Cu")
		(net "P3E_PCH_E1S_RX_DN<3>")
	)
	(segment
		(start 327.241408 -19.042888)
		(end 325.427594 -19.403568)
		(width 0.14732)
		(layer "In6.Cu")
		(net "P3E_PCH_E1S_RX_DN<3>")
	)
	(segment
		(start 287.758632 -32.498284)
		(end 276.933406 -43.322748)
		(width 0.14732)
		(layer "In6.Cu")
		(net "P3E_PCH_E1S_RX_DN<3>")
	)
	(segment
		(start 355.725984 -36.49853)
		(end 346.988892 -34.7599)
		(width 0.14732)
		(layer "In6.Cu")
		(net "P3E_PCH_E1S_RX_DN<3>")
	)
	(segment
		(start 363.92866 -48.804068)
		(end 363.92866 -46.395132)
		(width 0.14732)
		(layer "In6.Cu")
		(net "P3E_PCH_E1S_RX_DN<3>")
	)
	(segment
		(start 321.477132 -19.403568)
		(end 303.42713 -22.994112)
		(width 0.14732)
		(layer "In6.Cu")
		(net "P3E_PCH_E1S_RX_DN<3>")
	)
	(segment
		(start 241.935508 -60.539884)
		(end 240.780316 -60.368434)
		(width 0.14732)
		(layer "In6.Cu")
		(net "P3E_PCH_E1S_RX_DN<3>")
	)
	(segment
		(start 263.654286 -48.62576)
		(end 262.81888 -50.64252)
		(width 0.14732)
		(layer "In6.Cu")
		(net "P3E_PCH_E1S_RX_DN<3>")
	)
	(segment
		(start 273.622262 -44.694094)
		(end 270.310864 -46.065948)
		(width 0.14732)
		(layer "In6.Cu")
		(net "P3E_PCH_E1S_RX_DN<3>")
	)
	(segment
		(start 262.81888 -58.568082)
		(end 261.00024 -60.386722)
		(width 0.14732)
		(layer "In6.Cu")
		(net "P3E_PCH_E1S_RX_DN<3>")
	)
	(segment
		(start 239.285272 -60.070746)
		(end 237.790736 -59.77382)
		(width 0.14732)
		(layer "In6.Cu")
		(net "P3E_PCH_E1S_RX_DN<3>")
	)
	(segment
		(start 361.785408 -41.220898)
		(end 358.597962 -38.033198)
		(width 0.14732)
		(layer "In6.Cu")
		(net "P3E_PCH_E1S_RX_DN<3>")
	)
	(segment
		(start 232.87355 -57.737756)
		(end 230.79202 -57.737756)
		(width 0.14732)
		(layer "In6.Cu")
		(net "P3E_PCH_E1S_RX_DN<3>")
	)
	(segment
		(start 247.974104 -60.539884)
		(end 241.935508 -60.539884)
		(width 0.14732)
		(layer "In6.Cu")
		(net "P3E_PCH_E1S_RX_DN<3>")
	)
	(segment
		(start 299.626274 -24.568404)
		(end 287.758632 -32.498284)
		(width 0.14732)
		(layer "In6.Cu")
		(net "P3E_PCH_E1S_RX_DN<3>")
	)
	(segment
		(start 363.206284 -44.650914)
		(end 363.206284 -44.651168)
		(width 0.14732)
		(layer "In6.Cu")
		(net "P3E_PCH_E1S_RX_DN<3>")
	)
	(segment
		(start 249.185938 -61.041788)
		(end 247.974104 -60.539884)
		(width 0.14732)
		(layer "In6.Cu")
		(net "P3E_PCH_E1S_RX_DN<3>")
	)
	(segment
		(start 237.790736 -59.77382)
		(end 232.87355 -57.737756)
		(width 0.14732)
		(layer "In6.Cu")
		(net "P3E_PCH_E1S_RX_DN<3>")
	)
	(segment
		(start 270.310864 -46.065948)
		(end 266.214098 -46.065948)
		(width 0.14732)
		(layer "In6.Cu")
		(net "P3E_PCH_E1S_RX_DN<3>")
	)
	(segment
		(start 273.622262 -44.694348)
		(end 273.622262 -44.694094)
		(width 0.14732)
		(layer "In6.Cu")
		(net "P3E_PCH_E1S_RX_DN<3>")
	)
	(segment
		(start 363.206284 -44.651168)
		(end 362.561632 -43.094656)
		(width 0.14732)
		(layer "In6.Cu")
		(net "P3E_PCH_E1S_RX_DN<3>")
	)
	(segment
		(start 240.780316 -60.368434)
		(end 239.285272 -60.071)
		(width 0.14732)
		(layer "In6.Cu")
		(net "P3E_PCH_E1S_RX_DN<3>")
	)
	(segment
		(start 363.92866 -46.395132)
		(end 363.206284 -44.650914)
		(width 0.14732)
		(layer "In6.Cu")
		(net "P3E_PCH_E1S_RX_DN<3>")
	)
	(segment
		(start 357.618284 -50.502312)
		(end 357.618284 -51.061366)
		(width 0.14732)
		(layer "In6.Cu")
		(net "P3E_PCH_E1S_RX_DN<3>")
	)
	(segment
		(start 362.561632 -43.094656)
		(end 362.561378 -43.094656)
		(width 0.14732)
		(layer "In6.Cu")
		(net "P3E_PCH_E1S_RX_DN<3>")
	)
	(segment
		(start 340.45652 -25.588976)
		(end 334.241394 -19.37385)
		(width 0.14732)
		(layer "In6.Cu")
		(net "P3E_PCH_E1S_RX_DN<3>")
	)
	(segment
		(start 357.323644 -50.207672)
		(end 357.618284 -50.502312)
		(width 0.14732)
		(layer "In6.Cu")
		(net "P3E_PCH_E1S_RX_DN<3>")
	)
	(segment
		(start 239.285272 -60.071)
		(end 239.285272 -60.070746)
		(width 0.14732)
		(layer "In6.Cu")
		(net "P3E_PCH_E1S_RX_DN<3>")
	)
	(segment
		(start 357.926386 -51.369468)
		(end 361.36326 -51.369468)
		(width 0.14732)
		(layer "In6.Cu")
		(net "P3E_PCH_E1S_RX_DN<3>")
	)
	(segment
		(start 262.81888 -50.64252)
		(end 262.81888 -58.568082)
		(width 0.14732)
		(layer "In6.Cu")
		(net "P3E_PCH_E1S_RX_DN<3>")
	)
	(segment
		(start 355.32822 -50.442368)
		(end 355.32822 -50.838608)
		(width 0.0889)
		(layer "F.Cu")
		(net "P3E_PCH_E1S_RX_DN<2>")
	)
	(segment
		(start 231.374188 -55.945532)
		(end 229.49916 -55.945532)
		(width 0.13208)
		(layer "F.Cu")
		(net "P3E_PCH_E1S_RX_DN<2>")
	)
	(segment
		(start 347.38564 -50.668428)
		(end 347.05544 -50.668428)
		(width 0.0889)
		(layer "F.Cu")
		(net "P3E_PCH_E1S_RX_DN<2>")
	)
	(segment
		(start 348.95917 -50.761138)
		(end 347.47835 -50.761138)
		(width 0.0889)
		(layer "F.Cu")
		(net "P3E_PCH_E1S_RX_DN<2>")
	)
	(segment
		(start 231.554782 -55.764938)
		(end 231.374188 -55.945532)
		(width 0.13208)
		(layer "F.Cu")
		(net "P3E_PCH_E1S_RX_DN<2>")
	)
	(segment
		(start 349.466154 -51.268122)
		(end 348.95917 -50.761138)
		(width 0.0889)
		(layer "F.Cu")
		(net "P3E_PCH_E1S_RX_DN<2>")
	)
	(segment
		(start 347.47835 -50.761138)
		(end 347.38564 -50.668428)
		(width 0.0889)
		(layer "F.Cu")
		(net "P3E_PCH_E1S_RX_DN<2>")
	)
	(segment
		(start 355.093524 -50.207672)
		(end 355.32822 -50.442368)
		(width 0.0889)
		(layer "F.Cu")
		(net "P3E_PCH_E1S_RX_DN<2>")
	)
	(segment
		(start 354.898706 -51.268122)
		(end 349.466154 -51.268122)
		(width 0.0889)
		(layer "F.Cu")
		(net "P3E_PCH_E1S_RX_DN<2>")
	)
	(segment
		(start 355.32822 -50.838608)
		(end 354.898706 -51.268122)
		(width 0.0889)
		(layer "F.Cu")
		(net "P3E_PCH_E1S_RX_DN<2>")
	)
	(segment
		(start 232.000044 -55.764938)
		(end 231.554782 -55.764938)
		(width 0.13208)
		(layer "F.Cu")
		(net "P3E_PCH_E1S_RX_DN<2>")
	)
	(segment
		(start 229.49916 -55.945532)
		(end 229.1969 -55.643272)
		(width 0.13208)
		(layer "F.Cu")
		(net "P3E_PCH_E1S_RX_DN<2>")
	)
	(segment
		(start 347.05544 -50.668428)
		(end 346.772484 -50.951384)
		(width 0.0889)
		(layer "F.Cu")
		(net "P3E_PCH_E1S_RX_DN<2>")
	)
	(segment
		(start 346.772484 -50.951384)
		(end 346.384626 -50.951384)
		(width 0.0889)
		(layer "F.Cu")
		(net "P3E_PCH_E1S_RX_DN<2>")
	)
	(segment
		(start 353.82962 -30.402276)
		(end 352.915728 -28.196286)
		(width 0.14732)
		(layer "In6.Cu")
		(net "P3E_PCH_E1S_RX_DN<2>")
	)
	(segment
		(start 355.388164 -50.502312)
		(end 355.388164 -51.383438)
		(width 0.14732)
		(layer "In6.Cu")
		(net "P3E_PCH_E1S_RX_DN<2>")
	)
	(segment
		(start 365.17072 -45.075856)
		(end 364.734856 -44.023026)
		(width 0.14732)
		(layer "In6.Cu")
		(net "P3E_PCH_E1S_RX_DN<2>")
	)
	(segment
		(start 355.388164 -51.383438)
		(end 357.032814 -53.028088)
		(width 0.14732)
		(layer "In6.Cu")
		(net "P3E_PCH_E1S_RX_DN<2>")
	)
	(segment
		(start 355.012244 -31.5849)
		(end 353.82962 -30.402276)
		(width 0.14732)
		(layer "In6.Cu")
		(net "P3E_PCH_E1S_RX_DN<2>")
	)
	(segment
		(start 265.824462 -45.126148)
		(end 262.800084 -48.150526)
		(width 0.14732)
		(layer "In6.Cu")
		(net "P3E_PCH_E1S_RX_DN<2>")
	)
	(segment
		(start 361.21848 -53.028088)
		(end 365.17072 -49.075848)
		(width 0.14732)
		(layer "In6.Cu")
		(net "P3E_PCH_E1S_RX_DN<2>")
	)
	(segment
		(start 347.579696 -20.522438)
		(end 343.08796 -18.661888)
		(width 0.14732)
		(layer "In6.Cu")
		(net "P3E_PCH_E1S_RX_DN<2>")
	)
	(segment
		(start 364.734602 -44.023026)
		(end 361.395518 -35.961574)
		(width 0.14732)
		(layer "In6.Cu")
		(net "P3E_PCH_E1S_RX_DN<2>")
	)
	(segment
		(start 242.048538 -59.591448)
		(end 240.776252 -59.402726)
		(width 0.14732)
		(layer "In6.Cu")
		(net "P3E_PCH_E1S_RX_DN<2>")
	)
	(segment
		(start 357.811832 -32.377888)
		(end 356.818184 -31.966408)
		(width 0.14732)
		(layer "In6.Cu")
		(net "P3E_PCH_E1S_RX_DN<2>")
	)
	(segment
		(start 321.80657 -18.390108)
		(end 303.154588 -22.100286)
		(width 0.14732)
		(layer "In6.Cu")
		(net "P3E_PCH_E1S_RX_DN<2>")
	)
	(segment
		(start 238.57585 -58.678826)
		(end 237.958884 -58.06186)
		(width 0.14732)
		(layer "In6.Cu")
		(net "P3E_PCH_E1S_RX_DN<2>")
	)
	(segment
		(start 298.947586 -23.84298)
		(end 286.738822 -32.001206)
		(width 0.14732)
		(layer "In6.Cu")
		(net "P3E_PCH_E1S_RX_DN<2>")
	)
	(segment
		(start 355.932994 -31.966408)
		(end 355.012244 -31.5849)
		(width 0.14732)
		(layer "In6.Cu")
		(net "P3E_PCH_E1S_RX_DN<2>")
	)
	(segment
		(start 262.800084 -48.150526)
		(end 261.88924 -50.349404)
		(width 0.14732)
		(layer "In6.Cu")
		(net "P3E_PCH_E1S_RX_DN<2>")
	)
	(segment
		(start 248.200672 -59.591448)
		(end 242.048538 -59.591448)
		(width 0.14732)
		(layer "In6.Cu")
		(net "P3E_PCH_E1S_RX_DN<2>")
	)
	(segment
		(start 357.032814 -53.028088)
		(end 361.21848 -53.028088)
		(width 0.14732)
		(layer "In6.Cu")
		(net "P3E_PCH_E1S_RX_DN<2>")
	)
	(segment
		(start 364.734856 -44.023026)
		(end 364.734602 -44.023026)
		(width 0.14732)
		(layer "In6.Cu")
		(net "P3E_PCH_E1S_RX_DN<2>")
	)
	(segment
		(start 343.08796 -18.661888)
		(end 337.514692 -18.113248)
		(width 0.14732)
		(layer "In6.Cu")
		(net "P3E_PCH_E1S_RX_DN<2>")
	)
	(segment
		(start 365.17072 -49.075848)
		(end 365.17072 -45.075856)
		(width 0.14732)
		(layer "In6.Cu")
		(net "P3E_PCH_E1S_RX_DN<2>")
	)
	(segment
		(start 355.093524 -50.207672)
		(end 355.388164 -50.502312)
		(width 0.14732)
		(layer "In6.Cu")
		(net "P3E_PCH_E1S_RX_DN<2>")
	)
	(segment
		(start 286.738822 -32.001206)
		(end 276.206966 -42.533062)
		(width 0.14732)
		(layer "In6.Cu")
		(net "P3E_PCH_E1S_RX_DN<2>")
	)
	(segment
		(start 239.905032 -59.229498)
		(end 238.57585 -58.678826)
		(width 0.14732)
		(layer "In6.Cu")
		(net "P3E_PCH_E1S_RX_DN<2>")
	)
	(segment
		(start 276.206966 -42.533062)
		(end 273.076924 -43.829478)
		(width 0.14732)
		(layer "In6.Cu")
		(net "P3E_PCH_E1S_RX_DN<2>")
	)
	(segment
		(start 237.958884 -58.06186)
		(end 232.83037 -55.937912)
		(width 0.14732)
		(layer "In6.Cu")
		(net "P3E_PCH_E1S_RX_DN<2>")
	)
	(segment
		(start 229.49154 -55.937912)
		(end 229.1969 -55.643272)
		(width 0.14732)
		(layer "In6.Cu")
		(net "P3E_PCH_E1S_RX_DN<2>")
	)
	(segment
		(start 260.459474 -59.604148)
		(end 259.251704 -60.104528)
		(width 0.14732)
		(layer "In6.Cu")
		(net "P3E_PCH_E1S_RX_DN<2>")
	)
	(segment
		(start 273.077178 -43.829478)
		(end 269.946628 -45.126148)
		(width 0.14732)
		(layer "In6.Cu")
		(net "P3E_PCH_E1S_RX_DN<2>")
	)
	(segment
		(start 259.251704 -60.104528)
		(end 249.43943 -60.104528)
		(width 0.14732)
		(layer "In6.Cu")
		(net "P3E_PCH_E1S_RX_DN<2>")
	)
	(segment
		(start 327.136506 -18.113248)
		(end 325.744332 -18.390108)
		(width 0.14732)
		(layer "In6.Cu")
		(net "P3E_PCH_E1S_RX_DN<2>")
	)
	(segment
		(start 352.915728 -28.196286)
		(end 348.208854 -21.151596)
		(width 0.14732)
		(layer "In6.Cu")
		(net "P3E_PCH_E1S_RX_DN<2>")
	)
	(segment
		(start 240.776252 -59.402726)
		(end 239.905032 -59.229498)
		(width 0.14732)
		(layer "In6.Cu")
		(net "P3E_PCH_E1S_RX_DN<2>")
	)
	(segment
		(start 261.88924 -58.174382)
		(end 260.459474 -59.604148)
		(width 0.14732)
		(layer "In6.Cu")
		(net "P3E_PCH_E1S_RX_DN<2>")
	)
	(segment
		(start 269.946628 -45.126148)
		(end 265.824462 -45.126148)
		(width 0.14732)
		(layer "In6.Cu")
		(net "P3E_PCH_E1S_RX_DN<2>")
	)
	(segment
		(start 337.514692 -18.113248)
		(end 327.136506 -18.113248)
		(width 0.14732)
		(layer "In6.Cu")
		(net "P3E_PCH_E1S_RX_DN<2>")
	)
	(segment
		(start 356.818184 -31.966408)
		(end 355.932994 -31.966408)
		(width 0.14732)
		(layer "In6.Cu")
		(net "P3E_PCH_E1S_RX_DN<2>")
	)
	(segment
		(start 361.395518 -35.961574)
		(end 357.811832 -32.377888)
		(width 0.14732)
		(layer "In6.Cu")
		(net "P3E_PCH_E1S_RX_DN<2>")
	)
	(segment
		(start 232.83037 -55.937912)
		(end 229.49154 -55.937912)
		(width 0.14732)
		(layer "In6.Cu")
		(net "P3E_PCH_E1S_RX_DN<2>")
	)
	(segment
		(start 303.154588 -22.100286)
		(end 298.947586 -23.84298)
		(width 0.14732)
		(layer "In6.Cu")
		(net "P3E_PCH_E1S_RX_DN<2>")
	)
	(segment
		(start 273.076924 -43.829478)
		(end 273.077178 -43.829478)
		(width 0.14732)
		(layer "In6.Cu")
		(net "P3E_PCH_E1S_RX_DN<2>")
	)
	(segment
		(start 348.208854 -21.151596)
		(end 347.579696 -20.522438)
		(width 0.14732)
		(layer "In6.Cu")
		(net "P3E_PCH_E1S_RX_DN<2>")
	)
	(segment
		(start 249.43943 -60.104528)
		(end 248.200672 -59.591448)
		(width 0.14732)
		(layer "In6.Cu")
		(net "P3E_PCH_E1S_RX_DN<2>")
	)
	(segment
		(start 261.88924 -50.349404)
		(end 261.88924 -58.174382)
		(width 0.14732)
		(layer "In6.Cu")
		(net "P3E_PCH_E1S_RX_DN<2>")
	)
	(segment
		(start 325.744332 -18.390108)
		(end 321.80657 -18.390108)
		(width 0.14732)
		(layer "In6.Cu")
		(net "P3E_PCH_E1S_RX_DN<2>")
	)
	(segment
		(start 349.77705 -50.762662)
		(end 349.2754 -50.261012)
		(width 0.0889)
		(layer "F.Cu")
		(net "P3E_PCH_E1S_RX_DN<1>")
	)
	(segment
		(start 346.763848 -50.147728)
		(end 346.64777 -50.176938)
		(width 0.0889)
		(layer "F.Cu")
		(net "P3E_PCH_E1S_RX_DN<1>")
	)
	(segment
		(start 352.871024 -50.207672)
		(end 353.207574 -50.544222)
		(width 0.0889)
		(layer "F.Cu")
		(net "P3E_PCH_E1S_RX_DN<1>")
	)
	(segment
		(start 353.207574 -50.673254)
		(end 353.118166 -50.762662)
		(width 0.0889)
		(layer "F.Cu")
		(net "P3E_PCH_E1S_RX_DN<1>")
	)
	(segment
		(start 346.64777 -50.176938)
		(end 346.23756 -50.451258)
		(width 0.0889)
		(layer "F.Cu")
		(net "P3E_PCH_E1S_RX_DN<1>")
	)
	(segment
		(start 353.207574 -50.544222)
		(end 353.207574 -50.673254)
		(width 0.0889)
		(layer "F.Cu")
		(net "P3E_PCH_E1S_RX_DN<1>")
	)
	(segment
		(start 230.807006 -54.152546)
		(end 231.393238 -54.152546)
		(width 0.13208)
		(layer "F.Cu")
		(net "P3E_PCH_E1S_RX_DN<1>")
	)
	(segment
		(start 231.58069 -53.965094)
		(end 232.000044 -53.965094)
		(width 0.13208)
		(layer "F.Cu")
		(net "P3E_PCH_E1S_RX_DN<1>")
	)
	(segment
		(start 231.393238 -54.152546)
		(end 231.58069 -53.965094)
		(width 0.13208)
		(layer "F.Cu")
		(net "P3E_PCH_E1S_RX_DN<1>")
	)
	(segment
		(start 347.093286 -50.261012)
		(end 347.003624 -50.17135)
		(width 0.0889)
		(layer "F.Cu")
		(net "P3E_PCH_E1S_RX_DN<1>")
	)
	(segment
		(start 349.2754 -50.261012)
		(end 347.093286 -50.261012)
		(width 0.0889)
		(layer "F.Cu")
		(net "P3E_PCH_E1S_RX_DN<1>")
	)
	(segment
		(start 346.23756 -50.451258)
		(end 345.96959 -50.451258)
		(width 0.0889)
		(layer "F.Cu")
		(net "P3E_PCH_E1S_RX_DN<1>")
	)
	(segment
		(start 347.003624 -50.17135)
		(end 346.763848 -50.147728)
		(width 0.0889)
		(layer "F.Cu")
		(net "P3E_PCH_E1S_RX_DN<1>")
	)
	(segment
		(start 353.118166 -50.762662)
		(end 349.77705 -50.762662)
		(width 0.0889)
		(layer "F.Cu")
		(net "P3E_PCH_E1S_RX_DN<1>")
	)
	(segment
		(start 230.49738 -53.84292)
		(end 230.807006 -54.152546)
		(width 0.13208)
		(layer "F.Cu")
		(net "P3E_PCH_E1S_RX_DN<1>")
	)
	(segment
		(start 275.686774 -41.656)
		(end 269.639288 -44.160948)
		(width 0.14732)
		(layer "In6.Cu")
		(net "P3E_PCH_E1S_RX_DN<1>")
	)
	(segment
		(start 336.01533 -16.488918)
		(end 329.919584 -16.488918)
		(width 0.14732)
		(layer "In6.Cu")
		(net "P3E_PCH_E1S_RX_DN<1>")
	)
	(segment
		(start 338.780374 -16.761206)
		(end 336.01533 -16.488918)
		(width 0.14732)
		(layer "In6.Cu")
		(net "P3E_PCH_E1S_RX_DN<1>")
	)
	(segment
		(start 262.041132 -47.544228)
		(end 260.9596 -50.155602)
		(width 0.14732)
		(layer "In6.Cu")
		(net "P3E_PCH_E1S_RX_DN<1>")
	)
	(segment
		(start 353.165664 -50.502312)
		(end 353.165664 -51.30419)
		(width 0.14732)
		(layer "In6.Cu")
		(net "P3E_PCH_E1S_RX_DN<1>")
	)
	(segment
		(start 243.77269 -55.949088)
		(end 237.42015 -55.949088)
		(width 0.14732)
		(layer "In6.Cu")
		(net "P3E_PCH_E1S_RX_DN<1>")
	)
	(segment
		(start 366.44072 -49.30648)
		(end 366.44072 -43.989752)
		(width 0.14732)
		(layer "In6.Cu")
		(net "P3E_PCH_E1S_RX_DN<1>")
	)
	(segment
		(start 233.04627 -54.13756)
		(end 230.79202 -54.13756)
		(width 0.14732)
		(layer "In6.Cu")
		(net "P3E_PCH_E1S_RX_DN<1>")
	)
	(segment
		(start 302.882046 -21.20646)
		(end 298.505372 -23.019766)
		(width 0.14732)
		(layer "In6.Cu")
		(net "P3E_PCH_E1S_RX_DN<1>")
	)
	(segment
		(start 344.767916 -17.952212)
		(end 338.780374 -16.761206)
		(width 0.14732)
		(layer "In6.Cu")
		(net "P3E_PCH_E1S_RX_DN<1>")
	)
	(segment
		(start 259.926836 -58.818272)
		(end 259.078476 -59.169808)
		(width 0.14732)
		(layer "In6.Cu")
		(net "P3E_PCH_E1S_RX_DN<1>")
	)
	(segment
		(start 265.424412 -44.160948)
		(end 262.041132 -47.544228)
		(width 0.14732)
		(layer "In6.Cu")
		(net "P3E_PCH_E1S_RX_DN<1>")
	)
	(segment
		(start 361.657392 -54.089808)
		(end 366.44072 -49.30648)
		(width 0.14732)
		(layer "In6.Cu")
		(net "P3E_PCH_E1S_RX_DN<1>")
	)
	(segment
		(start 359.243122 -26.613104)
		(end 356.917244 -24.286718)
		(width 0.14732)
		(layer "In6.Cu")
		(net "P3E_PCH_E1S_RX_DN<1>")
	)
	(segment
		(start 355.951282 -54.089808)
		(end 361.657392 -54.089808)
		(width 0.14732)
		(layer "In6.Cu")
		(net "P3E_PCH_E1S_RX_DN<1>")
	)
	(segment
		(start 351.788222 -20.860004)
		(end 344.767916 -17.952212)
		(width 0.14732)
		(layer "In6.Cu")
		(net "P3E_PCH_E1S_RX_DN<1>")
	)
	(segment
		(start 249.281188 -58.913522)
		(end 248.115328 -57.747662)
		(width 0.14732)
		(layer "In6.Cu")
		(net "P3E_PCH_E1S_RX_DN<1>")
	)
	(segment
		(start 249.899932 -59.169808)
		(end 249.281188 -58.913522)
		(width 0.14732)
		(layer "In6.Cu")
		(net "P3E_PCH_E1S_RX_DN<1>")
	)
	(segment
		(start 237.42015 -55.949088)
		(end 233.04627 -54.13756)
		(width 0.14732)
		(layer "In6.Cu")
		(net "P3E_PCH_E1S_RX_DN<1>")
	)
	(segment
		(start 260.9596 -50.155602)
		(end 260.9596 -57.785508)
		(width 0.14732)
		(layer "In6.Cu")
		(net "P3E_PCH_E1S_RX_DN<1>")
	)
	(segment
		(start 285.901638 -31.441136)
		(end 275.686774 -41.656)
		(width 0.14732)
		(layer "In6.Cu")
		(net "P3E_PCH_E1S_RX_DN<1>")
	)
	(segment
		(start 325.660512 -17.336008)
		(end 322.340478 -17.336008)
		(width 0.14732)
		(layer "In6.Cu")
		(net "P3E_PCH_E1S_RX_DN<1>")
	)
	(segment
		(start 298.505372 -23.019766)
		(end 285.901638 -31.441136)
		(width 0.14732)
		(layer "In6.Cu")
		(net "P3E_PCH_E1S_RX_DN<1>")
	)
	(segment
		(start 353.165664 -51.30419)
		(end 355.951282 -54.089808)
		(width 0.14732)
		(layer "In6.Cu")
		(net "P3E_PCH_E1S_RX_DN<1>")
	)
	(segment
		(start 366.44072 -43.989752)
		(end 359.243122 -26.613104)
		(width 0.14732)
		(layer "In6.Cu")
		(net "P3E_PCH_E1S_RX_DN<1>")
	)
	(segment
		(start 269.639288 -44.160948)
		(end 265.424412 -44.160948)
		(width 0.14732)
		(layer "In6.Cu")
		(net "P3E_PCH_E1S_RX_DN<1>")
	)
	(segment
		(start 322.340478 -17.336008)
		(end 302.882046 -21.20646)
		(width 0.14732)
		(layer "In6.Cu")
		(net "P3E_PCH_E1S_RX_DN<1>")
	)
	(segment
		(start 329.919584 -16.488918)
		(end 325.660512 -17.336008)
		(width 0.14732)
		(layer "In6.Cu")
		(net "P3E_PCH_E1S_RX_DN<1>")
	)
	(segment
		(start 356.917244 -24.286718)
		(end 351.788222 -20.860004)
		(width 0.14732)
		(layer "In6.Cu")
		(net "P3E_PCH_E1S_RX_DN<1>")
	)
	(segment
		(start 248.115328 -57.747662)
		(end 243.77269 -55.949088)
		(width 0.14732)
		(layer "In6.Cu")
		(net "P3E_PCH_E1S_RX_DN<1>")
	)
	(segment
		(start 259.078476 -59.169808)
		(end 249.899932 -59.169808)
		(width 0.14732)
		(layer "In6.Cu")
		(net "P3E_PCH_E1S_RX_DN<1>")
	)
	(segment
		(start 230.79202 -54.13756)
		(end 230.49738 -53.84292)
		(width 0.14732)
		(layer "In6.Cu")
		(net "P3E_PCH_E1S_RX_DN<1>")
	)
	(segment
		(start 352.871024 -50.207672)
		(end 353.165664 -50.502312)
		(width 0.14732)
		(layer "In6.Cu")
		(net "P3E_PCH_E1S_RX_DN<1>")
	)
	(segment
		(start 260.9596 -57.785508)
		(end 259.926836 -58.818272)
		(width 0.14732)
		(layer "In6.Cu")
		(net "P3E_PCH_E1S_RX_DN<1>")
	)
	(segment
		(start 231.525572 -52.764944)
		(end 232.000044 -52.764944)
		(width 0.13208)
		(layer "F.Cu")
		(net "P3E_PCH_E1S_RX_DN<0>")
	)
	(segment
		(start 231.356154 -52.595526)
		(end 231.525572 -52.764944)
		(width 0.13208)
		(layer "F.Cu")
		(net "P3E_PCH_E1S_RX_DN<0>")
	)
	(segment
		(start 349.159322 -49.465992)
		(end 348.950534 -49.67478)
		(width 0.0889)
		(layer "F.Cu")
		(net "P3E_PCH_E1S_RX_DN<0>")
	)
	(segment
		(start 351.292922 -49.666144)
		(end 351.09277 -49.465992)
		(width 0.0889)
		(layer "F.Cu")
		(net "P3E_PCH_E1S_RX_DN<0>")
	)
	(segment
		(start 229.50805 -52.595526)
		(end 231.356154 -52.595526)
		(width 0.13208)
		(layer "F.Cu")
		(net "P3E_PCH_E1S_RX_DN<0>")
	)
	(segment
		(start 346.637864 -49.950878)
		(end 346.384626 -49.950878)
		(width 0.0889)
		(layer "F.Cu")
		(net "P3E_PCH_E1S_RX_DN<0>")
	)
	(segment
		(start 351.09277 -49.465992)
		(end 349.159322 -49.465992)
		(width 0.0889)
		(layer "F.Cu")
		(net "P3E_PCH_E1S_RX_DN<0>")
	)
	(segment
		(start 351.536508 -50.207672)
		(end 351.292922 -49.964086)
		(width 0.0889)
		(layer "F.Cu")
		(net "P3E_PCH_E1S_RX_DN<0>")
	)
	(segment
		(start 347.085158 -49.67478)
		(end 346.637864 -49.950878)
		(width 0.0889)
		(layer "F.Cu")
		(net "P3E_PCH_E1S_RX_DN<0>")
	)
	(segment
		(start 351.292922 -49.964086)
		(end 351.292922 -49.666144)
		(width 0.0889)
		(layer "F.Cu")
		(net "P3E_PCH_E1S_RX_DN<0>")
	)
	(segment
		(start 348.950534 -49.67478)
		(end 347.085158 -49.67478)
		(width 0.0889)
		(layer "F.Cu")
		(net "P3E_PCH_E1S_RX_DN<0>")
	)
	(segment
		(start 229.1969 -52.906676)
		(end 229.50805 -52.595526)
		(width 0.13208)
		(layer "F.Cu")
		(net "P3E_PCH_E1S_RX_DN<0>")
	)
	(segment
		(start 237.543086 -52.600606)
		(end 229.50297 -52.600606)
		(width 0.14732)
		(layer "In6.Cu")
		(net "P3E_PCH_E1S_RX_DN<0>")
	)
	(segment
		(start 340.40572 -16.23568)
		(end 336.321654 -15.833598)
		(width 0.14732)
		(layer "In6.Cu")
		(net "P3E_PCH_E1S_RX_DN<0>")
	)
	(segment
		(start 284.625542 -31.505652)
		(end 275.146516 -40.984424)
		(width 0.14732)
		(layer "In6.Cu")
		(net "P3E_PCH_E1S_RX_DN<0>")
	)
	(segment
		(start 275.146516 -40.984424)
		(end 269.26794 -43.419268)
		(width 0.14732)
		(layer "In6.Cu")
		(net "P3E_PCH_E1S_RX_DN<0>")
	)
	(segment
		(start 260.832854 -48.63719)
		(end 260.8326 -48.63719)
		(width 0.14732)
		(layer "In6.Cu")
		(net "P3E_PCH_E1S_RX_DN<0>")
	)
	(segment
		(start 360.8324 -54.879748)
		(end 361.9881 -54.879748)
		(width 0.14732)
		(layer "In6.Cu")
		(net "P3E_PCH_E1S_RX_DN<0>")
	)
	(segment
		(start 352.928428 -52.572666)
		(end 353.189032 -52.83327)
		(width 0.14732)
		(layer "In6.Cu")
		(net "P3E_PCH_E1S_RX_DN<0>")
	)
	(segment
		(start 351.241868 -51.09083)
		(end 351.997772 -51.846734)
		(width 0.14732)
		(layer "In6.Cu")
		(net "P3E_PCH_E1S_RX_DN<0>")
	)
	(segment
		(start 352.723704 -52.572666)
		(end 352.928428 -52.572666)
		(width 0.14732)
		(layer "In6.Cu")
		(net "P3E_PCH_E1S_RX_DN<0>")
	)
	(segment
		(start 358.4194 -54.757828)
		(end 358.54132 -54.879748)
		(width 0.14732)
		(layer "In6.Cu")
		(net "P3E_PCH_E1S_RX_DN<0>")
	)
	(segment
		(start 265.117072 -43.419268)
		(end 261.492746 -47.043594)
		(width 0.14732)
		(layer "In6.Cu")
		(net "P3E_PCH_E1S_RX_DN<0>")
	)
	(segment
		(start 355.030786 -54.879748)
		(end 355.6254 -54.879748)
		(width 0.14732)
		(layer "In6.Cu")
		(net "P3E_PCH_E1S_RX_DN<0>")
	)
	(segment
		(start 260.30428 -49.912524)
		(end 260.30428 -57.506108)
		(width 0.14732)
		(layer "In6.Cu")
		(net "P3E_PCH_E1S_RX_DN<0>")
	)
	(segment
		(start 258.181348 -58.463688)
		(end 257.244088 -57.526428)
		(width 0.14732)
		(layer "In6.Cu")
		(net "P3E_PCH_E1S_RX_DN<0>")
	)
	(segment
		(start 364.195868 -52.67198)
		(end 364.195868 -52.495958)
		(width 0.14732)
		(layer "In6.Cu")
		(net "P3E_PCH_E1S_RX_DN<0>")
	)
	(segment
		(start 356.743 -54.879748)
		(end 356.86492 -54.757828)
		(width 0.14732)
		(layer "In6.Cu")
		(net "P3E_PCH_E1S_RX_DN<0>")
	)
	(segment
		(start 363.401864 -53.289962)
		(end 363.710982 -52.980844)
		(width 0.14732)
		(layer "In6.Cu")
		(net "P3E_PCH_E1S_RX_DN<0>")
	)
	(segment
		(start 362.60786 -54.083966)
		(end 362.916978 -53.774848)
		(width 0.14732)
		(layer "In6.Cu")
		(net "P3E_PCH_E1S_RX_DN<0>")
	)
	(segment
		(start 362.916978 -53.774848)
		(end 363.093 -53.774848)
		(width 0.14732)
		(layer "In6.Cu")
		(net "P3E_PCH_E1S_RX_DN<0>")
	)
	(segment
		(start 357.8606 -54.879748)
		(end 357.98252 -54.757828)
		(width 0.14732)
		(layer "In6.Cu")
		(net "P3E_PCH_E1S_RX_DN<0>")
	)
	(segment
		(start 355.74732 -54.757828)
		(end 356.1842 -54.757828)
		(width 0.14732)
		(layer "In6.Cu")
		(net "P3E_PCH_E1S_RX_DN<0>")
	)
	(segment
		(start 359.7148 -54.879748)
		(end 360.15168 -54.879748)
		(width 0.14732)
		(layer "In6.Cu")
		(net "P3E_PCH_E1S_RX_DN<0>")
	)
	(segment
		(start 362.60786 -54.259988)
		(end 362.60786 -54.083966)
		(width 0.14732)
		(layer "In6.Cu")
		(net "P3E_PCH_E1S_RX_DN<0>")
	)
	(segment
		(start 352.202496 -51.846734)
		(end 352.463354 -52.107592)
		(width 0.14732)
		(layer "In6.Cu")
		(net "P3E_PCH_E1S_RX_DN<0>")
	)
	(segment
		(start 353.654106 -53.298344)
		(end 353.91471 -53.558948)
		(width 0.14732)
		(layer "In6.Cu")
		(net "P3E_PCH_E1S_RX_DN<0>")
	)
	(segment
		(start 357.493824 -23.880572)
		(end 351.594166 -19.938492)
		(width 0.14732)
		(layer "In6.Cu")
		(net "P3E_PCH_E1S_RX_DN<0>")
	)
	(segment
		(start 336.321654 -15.833598)
		(end 329.816206 -15.833598)
		(width 0.14732)
		(layer "In6.Cu")
		(net "P3E_PCH_E1S_RX_DN<0>")
	)
	(segment
		(start 361.9881 -54.879748)
		(end 362.60786 -54.259988)
		(width 0.14732)
		(layer "In6.Cu")
		(net "P3E_PCH_E1S_RX_DN<0>")
	)
	(segment
		(start 355.6254 -54.879748)
		(end 355.74732 -54.757828)
		(width 0.14732)
		(layer "In6.Cu")
		(net "P3E_PCH_E1S_RX_DN<0>")
	)
	(segment
		(start 356.86492 -54.757828)
		(end 357.3018 -54.757828)
		(width 0.14732)
		(layer "In6.Cu")
		(net "P3E_PCH_E1S_RX_DN<0>")
	)
	(segment
		(start 353.189032 -53.037994)
		(end 353.449382 -53.298344)
		(width 0.14732)
		(layer "In6.Cu")
		(net "P3E_PCH_E1S_RX_DN<0>")
	)
	(segment
		(start 360.71048 -54.757828)
		(end 360.8324 -54.879748)
		(width 0.14732)
		(layer "In6.Cu")
		(net "P3E_PCH_E1S_RX_DN<0>")
	)
	(segment
		(start 353.91471 -53.763672)
		(end 355.030786 -54.879748)
		(width 0.14732)
		(layer "In6.Cu")
		(net "P3E_PCH_E1S_RX_DN<0>")
	)
	(segment
		(start 364.504986 -52.18684)
		(end 364.681008 -52.18684)
		(width 0.14732)
		(layer "In6.Cu")
		(net "P3E_PCH_E1S_RX_DN<0>")
	)
	(segment
		(start 257.244088 -57.526428)
		(end 249.093228 -57.526428)
		(width 0.14732)
		(layer "In6.Cu")
		(net "P3E_PCH_E1S_RX_DN<0>")
	)
	(segment
		(start 249.093228 -57.526428)
		(end 242.910614 -51.343814)
		(width 0.14732)
		(layer "In6.Cu")
		(net "P3E_PCH_E1S_RX_DN<0>")
	)
	(segment
		(start 360.15168 -54.879748)
		(end 360.2736 -54.757828)
		(width 0.14732)
		(layer "In6.Cu")
		(net "P3E_PCH_E1S_RX_DN<0>")
	)
	(segment
		(start 322.836794 -16.568928)
		(end 302.494442 -20.615402)
		(width 0.14732)
		(layer "In6.Cu")
		(net "P3E_PCH_E1S_RX_DN<0>")
	)
	(segment
		(start 259.070602 -58.463688)
		(end 258.181348 -58.463688)
		(width 0.14732)
		(layer "In6.Cu")
		(net "P3E_PCH_E1S_RX_DN<0>")
	)
	(segment
		(start 357.42372 -54.879748)
		(end 357.8606 -54.879748)
		(width 0.14732)
		(layer "In6.Cu")
		(net "P3E_PCH_E1S_RX_DN<0>")
	)
	(segment
		(start 261.492746 -47.043594)
		(end 260.832854 -48.63719)
		(width 0.14732)
		(layer "In6.Cu")
		(net "P3E_PCH_E1S_RX_DN<0>")
	)
	(segment
		(start 364.195868 -52.495958)
		(end 364.504986 -52.18684)
		(width 0.14732)
		(layer "In6.Cu")
		(net "P3E_PCH_E1S_RX_DN<0>")
	)
	(segment
		(start 357.3018 -54.757828)
		(end 357.42372 -54.879748)
		(width 0.14732)
		(layer "In6.Cu")
		(net "P3E_PCH_E1S_RX_DN<0>")
	)
	(segment
		(start 353.189032 -52.83327)
		(end 353.189032 -53.037994)
		(width 0.14732)
		(layer "In6.Cu")
		(net "P3E_PCH_E1S_RX_DN<0>")
	)
	(segment
		(start 353.91471 -53.558948)
		(end 353.91471 -53.763672)
		(width 0.14732)
		(layer "In6.Cu")
		(net "P3E_PCH_E1S_RX_DN<0>")
	)
	(segment
		(start 351.594166 -19.938492)
		(end 344.73388 -17.09674)
		(width 0.14732)
		(layer "In6.Cu")
		(net "P3E_PCH_E1S_RX_DN<0>")
	)
	(segment
		(start 344.73388 -17.09674)
		(end 340.40572 -16.23568)
		(width 0.14732)
		(layer "In6.Cu")
		(net "P3E_PCH_E1S_RX_DN<0>")
	)
	(segment
		(start 352.463354 -52.107592)
		(end 352.463354 -52.312316)
		(width 0.14732)
		(layer "In6.Cu")
		(net "P3E_PCH_E1S_RX_DN<0>")
	)
	(segment
		(start 363.887004 -52.980844)
		(end 364.195868 -52.67198)
		(width 0.14732)
		(layer "In6.Cu")
		(net "P3E_PCH_E1S_RX_DN<0>")
	)
	(segment
		(start 302.494442 -20.615402)
		(end 298.35983 -22.32787)
		(width 0.14732)
		(layer "In6.Cu")
		(net "P3E_PCH_E1S_RX_DN<0>")
	)
	(segment
		(start 364.681008 -52.18684)
		(end 367.19256 -49.675288)
		(width 0.14732)
		(layer "In6.Cu")
		(net "P3E_PCH_E1S_RX_DN<0>")
	)
	(segment
		(start 352.463354 -52.312316)
		(end 352.723704 -52.572666)
		(width 0.14732)
		(layer "In6.Cu")
		(net "P3E_PCH_E1S_RX_DN<0>")
	)
	(segment
		(start 367.19256 -43.26128)
		(end 360.346498 -26.7335)
		(width 0.14732)
		(layer "In6.Cu")
		(net "P3E_PCH_E1S_RX_DN<0>")
	)
	(segment
		(start 351.997772 -51.846734)
		(end 352.202496 -51.846734)
		(width 0.14732)
		(layer "In6.Cu")
		(net "P3E_PCH_E1S_RX_DN<0>")
	)
	(segment
		(start 260.8326 -48.63719)
		(end 260.30428 -49.912524)
		(width 0.14732)
		(layer "In6.Cu")
		(net "P3E_PCH_E1S_RX_DN<0>")
	)
	(segment
		(start 353.449382 -53.298344)
		(end 353.654106 -53.298344)
		(width 0.14732)
		(layer "In6.Cu")
		(net "P3E_PCH_E1S_RX_DN<0>")
	)
	(segment
		(start 259.542026 -58.268362)
		(end 259.070602 -58.463688)
		(width 0.14732)
		(layer "In6.Cu")
		(net "P3E_PCH_E1S_RX_DN<0>")
	)
	(segment
		(start 351.241868 -50.502312)
		(end 351.241868 -51.09083)
		(width 0.14732)
		(layer "In6.Cu")
		(net "P3E_PCH_E1S_RX_DN<0>")
	)
	(segment
		(start 363.710982 -52.980844)
		(end 363.887004 -52.980844)
		(width 0.14732)
		(layer "In6.Cu")
		(net "P3E_PCH_E1S_RX_DN<0>")
	)
	(segment
		(start 359.156 -54.757828)
		(end 359.59288 -54.757828)
		(width 0.14732)
		(layer "In6.Cu")
		(net "P3E_PCH_E1S_RX_DN<0>")
	)
	(segment
		(start 298.35983 -22.32787)
		(end 284.625542 -31.505652)
		(width 0.14732)
		(layer "In6.Cu")
		(net "P3E_PCH_E1S_RX_DN<0>")
	)
	(segment
		(start 363.401864 -53.465984)
		(end 363.401864 -53.289962)
		(width 0.14732)
		(layer "In6.Cu")
		(net "P3E_PCH_E1S_RX_DN<0>")
	)
	(segment
		(start 229.50297 -52.600606)
		(end 229.1969 -52.906676)
		(width 0.14732)
		(layer "In6.Cu")
		(net "P3E_PCH_E1S_RX_DN<0>")
	)
	(segment
		(start 356.1842 -54.757828)
		(end 356.30612 -54.879748)
		(width 0.14732)
		(layer "In6.Cu")
		(net "P3E_PCH_E1S_RX_DN<0>")
	)
	(segment
		(start 326.118982 -16.568928)
		(end 322.836794 -16.568928)
		(width 0.14732)
		(layer "In6.Cu")
		(net "P3E_PCH_E1S_RX_DN<0>")
	)
	(segment
		(start 359.03408 -54.879748)
		(end 359.156 -54.757828)
		(width 0.14732)
		(layer "In6.Cu")
		(net "P3E_PCH_E1S_RX_DN<0>")
	)
	(segment
		(start 242.910614 -51.343814)
		(end 242.488466 -51.168808)
		(width 0.14732)
		(layer "In6.Cu")
		(net "P3E_PCH_E1S_RX_DN<0>")
	)
	(segment
		(start 363.093 -53.774848)
		(end 363.401864 -53.465984)
		(width 0.14732)
		(layer "In6.Cu")
		(net "P3E_PCH_E1S_RX_DN<0>")
	)
	(segment
		(start 242.488466 -51.168808)
		(end 240.999772 -51.168808)
		(width 0.14732)
		(layer "In6.Cu")
		(net "P3E_PCH_E1S_RX_DN<0>")
	)
	(segment
		(start 360.346498 -26.7335)
		(end 357.493824 -23.880572)
		(width 0.14732)
		(layer "In6.Cu")
		(net "P3E_PCH_E1S_RX_DN<0>")
	)
	(segment
		(start 351.536508 -50.207672)
		(end 351.241868 -50.502312)
		(width 0.14732)
		(layer "In6.Cu")
		(net "P3E_PCH_E1S_RX_DN<0>")
	)
	(segment
		(start 356.30612 -54.879748)
		(end 356.743 -54.879748)
		(width 0.14732)
		(layer "In6.Cu")
		(net "P3E_PCH_E1S_RX_DN<0>")
	)
	(segment
		(start 329.816206 -15.833598)
		(end 326.118982 -16.568928)
		(width 0.14732)
		(layer "In6.Cu")
		(net "P3E_PCH_E1S_RX_DN<0>")
	)
	(segment
		(start 357.98252 -54.757828)
		(end 358.4194 -54.757828)
		(width 0.14732)
		(layer "In6.Cu")
		(net "P3E_PCH_E1S_RX_DN<0>")
	)
	(segment
		(start 260.30428 -57.506108)
		(end 259.542026 -58.268362)
		(width 0.14732)
		(layer "In6.Cu")
		(net "P3E_PCH_E1S_RX_DN<0>")
	)
	(segment
		(start 359.59288 -54.757828)
		(end 359.7148 -54.879748)
		(width 0.14732)
		(layer "In6.Cu")
		(net "P3E_PCH_E1S_RX_DN<0>")
	)
	(segment
		(start 358.54132 -54.879748)
		(end 359.03408 -54.879748)
		(width 0.14732)
		(layer "In6.Cu")
		(net "P3E_PCH_E1S_RX_DN<0>")
	)
	(segment
		(start 367.19256 -49.675288)
		(end 367.19256 -43.26128)
		(width 0.14732)
		(layer "In6.Cu")
		(net "P3E_PCH_E1S_RX_DN<0>")
	)
	(segment
		(start 360.2736 -54.757828)
		(end 360.71048 -54.757828)
		(width 0.14732)
		(layer "In6.Cu")
		(net "P3E_PCH_E1S_RX_DN<0>")
	)
	(segment
		(start 240.999772 -51.168808)
		(end 237.543086 -52.600606)
		(width 0.14732)
		(layer "In6.Cu")
		(net "P3E_PCH_E1S_RX_DN<0>")
	)
	(segment
		(start 269.26794 -43.419268)
		(end 265.117072 -43.419268)
		(width 0.14732)
		(layer "In6.Cu")
		(net "P3E_PCH_E1S_RX_DN<0>")
	)
	(segment
		(start 77.528928 -22.771354)
		(end 77.712824 -22.587458)
		(width 0.12954)
		(layer "F.Cu")
		(net "P12V_OCP_VCC_2")
	)
	(segment
		(start 77.712824 -22.587458)
		(end 77.909928 -22.587458)
		(width 0.12954)
		(layer "F.Cu")
		(net "P12V_OCP_VCC_2")
	)
	(segment
		(start 78.35646 -22.140926)
		(end 78.35646 -21.444204)
		(width 0.12954)
		(layer "F.Cu")
		(net "P12V_OCP_VCC_2")
	)
	(segment
		(start 77.528928 -23.754842)
		(end 77.55001 -23.775924)
		(width 0.12954)
		(layer "F.Cu")
		(net "P12V_OCP_VCC_2")
	)
	(segment
		(start 77.55001 -23.775924)
		(end 77.55001 -24.313896)
		(width 0.12954)
		(layer "F.Cu")
		(net "P12V_OCP_VCC_2")
	)
	(segment
		(start 78.18628 -24.313896)
		(end 77.55001 -24.313896)
		(width 0.12954)
		(layer "F.Cu")
		(net "P12V_OCP_VCC_2")
	)
	(segment
		(start 77.528928 -23.308818)
		(end 77.528928 -22.771354)
		(width 0.12954)
		(layer "F.Cu")
		(net "P12V_OCP_VCC_2")
	)
	(segment
		(start 77.528928 -23.308818)
		(end 77.528928 -23.754842)
		(width 0.12954)
		(layer "F.Cu")
		(net "P12V_OCP_VCC_2")
	)
	(segment
		(start 77.909928 -22.587458)
		(end 78.35646 -22.140926)
		(width 0.12954)
		(layer "F.Cu")
		(net "P12V_OCP_VCC_2")
	)
	(via
		(at 78.18628 -24.313896)
		(size 0.508)
		(drill 0.254)
		(layers "F.Cu" "B.Cu")
		(net "P12V_OCP_VCC_2")
	)
	(segment
		(start 450.497194 -22.426422)
		(end 450.050662 -22.872954)
		(width 0.12954)
		(layer "F.Cu")
		(net "P12V_OCP_VCC_1")
	)
	(segment
		(start 450.050662 -22.872954)
		(end 450.050662 -23.594314)
		(width 0.12954)
		(layer "F.Cu")
		(net "P12V_OCP_VCC_1")
	)
	(segment
		(start 450.497194 -21.7297)
		(end 450.497194 -22.426422)
		(width 0.12954)
		(layer "F.Cu")
		(net "P12V_OCP_VCC_1")
	)
	(segment
		(start 450.050662 -23.594314)
		(end 450.060314 -23.603966)
		(width 0.12954)
		(layer "F.Cu")
		(net "P12V_OCP_VCC_1")
	)
	(segment
		(start 450.060314 -23.603966)
		(end 450.060314 -24.70023)
		(width 0.12954)
		(layer "F.Cu")
		(net "P12V_OCP_VCC_1")
	)
	(via
		(at 450.497194 -22.426422)
		(size 0.508)
		(drill 0.254)
		(layers "F.Cu" "B.Cu")
		(net "P12V_OCP_VCC_1")
	)
	(segment
		(start 37.057584 -111.095282)
		(end 36.549584 -110.587282)
		(width 0.12954)
		(layer "F.Cu")
		(net "P12V_OCP_V3_2_ISENSE_TIC")
	)
	(segment
		(start 33.349946 -110.308644)
		(end 32.51581 -110.308644)
		(width 0.12954)
		(layer "F.Cu")
		(net "P12V_OCP_V3_2_ISENSE_TIC")
	)
	(segment
		(start 39.719504 -111.095282)
		(end 37.057584 -111.095282)
		(width 0.12954)
		(layer "F.Cu")
		(net "P12V_OCP_V3_2_ISENSE_TIC")
	)
	(segment
		(start 40.227504 -110.587282)
		(end 39.719504 -111.095282)
		(width 0.12954)
		(layer "F.Cu")
		(net "P12V_OCP_V3_2_ISENSE_TIC")
	)
	(segment
		(start 36.530534 -110.587282)
		(end 36.276534 -110.841282)
		(width 0.12954)
		(layer "F.Cu")
		(net "P12V_OCP_V3_2_ISENSE_TIC")
	)
	(segment
		(start 36.549584 -110.587282)
		(end 36.530534 -110.587282)
		(width 0.12954)
		(layer "F.Cu")
		(net "P12V_OCP_V3_2_ISENSE_TIC")
	)
	(segment
		(start 34.263584 -110.841282)
		(end 33.882584 -110.841282)
		(width 0.12954)
		(layer "F.Cu")
		(net "P12V_OCP_V3_2_ISENSE_TIC")
	)
	(segment
		(start 33.882584 -110.841282)
		(end 33.349946 -110.308644)
		(width 0.12954)
		(layer "F.Cu")
		(net "P12V_OCP_V3_2_ISENSE_TIC")
	)
	(segment
		(start 36.276534 -110.841282)
		(end 34.263584 -110.841282)
		(width 0.12954)
		(layer "F.Cu")
		(net "P12V_OCP_V3_2_ISENSE_TIC")
	)
	(via
		(at 34.263584 -110.841282)
		(size 0.762)
		(drill 0.381)
		(layers "F.Cu" "B.Cu")
		(net "P12V_OCP_V3_2_ISENSE_TIC")
	)
	(segment
		(start 60.89396 -34.061908)
		(end 61.543438 -33.41243)
		(width 0.254)
		(layer "F.Cu")
		(net "P12V_OCP_V3_2_ISENSE_MPS_TIC")
	)
	(segment
		(start 41.027604 -110.587282)
		(end 41.637204 -110.587282)
		(width 0.12954)
		(layer "F.Cu")
		(net "P12V_OCP_V3_2_ISENSE_MPS_TIC")
	)
	(segment
		(start 41.06418 -87.513668)
		(end 41.06418 -81.563972)
		(width 0.254)
		(layer "F.Cu")
		(net "P12V_OCP_V3_2_ISENSE_MPS_TIC")
	)
	(segment
		(start 36.36518 -56.203088)
		(end 58.50636 -34.061908)
		(width 0.254)
		(layer "F.Cu")
		(net "P12V_OCP_V3_2_ISENSE_MPS_TIC")
	)
	(segment
		(start 61.543438 -33.41243)
		(end 61.543438 -32.287972)
		(width 0.254)
		(layer "F.Cu")
		(net "P12V_OCP_V3_2_ISENSE_MPS_TIC")
	)
	(segment
		(start 58.50636 -34.061908)
		(end 60.89396 -34.061908)
		(width 0.254)
		(layer "F.Cu")
		(net "P12V_OCP_V3_2_ISENSE_MPS_TIC")
	)
	(segment
		(start 36.36518 -76.864972)
		(end 36.36518 -56.203088)
		(width 0.254)
		(layer "F.Cu")
		(net "P12V_OCP_V3_2_ISENSE_MPS_TIC")
	)
	(segment
		(start 41.06418 -81.563972)
		(end 36.36518 -76.864972)
		(width 0.254)
		(layer "F.Cu")
		(net "P12V_OCP_V3_2_ISENSE_MPS_TIC")
	)
	(via
		(at 41.637204 -110.587282)
		(size 0.508)
		(drill 0.254)
		(layers "F.Cu" "B.Cu")
		(net "P12V_OCP_V3_2_ISENSE_MPS_TIC")
	)
	(via
		(at 60.89396 -34.061908)
		(size 0.762)
		(drill 0.381)
		(layers "F.Cu" "B.Cu")
		(net "P12V_OCP_V3_2_ISENSE_MPS_TIC")
	)
	(via
		(at 41.06418 -87.513668)
		(size 0.508)
		(drill 0.254)
		(layers "F.Cu" "B.Cu")
		(net "P12V_OCP_V3_2_ISENSE_MPS_TIC")
	)
	(segment
		(start 41.637204 -110.587282)
		(end 41.03624 -109.986318)
		(width 0.254)
		(layer "B.Cu")
		(net "P12V_OCP_V3_2_ISENSE_MPS_TIC")
	)
	(segment
		(start 41.03624 -105.720388)
		(end 40.04564 -104.729788)
		(width 0.254)
		(layer "B.Cu")
		(net "P12V_OCP_V3_2_ISENSE_MPS_TIC")
	)
	(segment
		(start 40.04564 -104.729788)
		(end 40.04564 -97.473008)
		(width 0.254)
		(layer "B.Cu")
		(net "P12V_OCP_V3_2_ISENSE_MPS_TIC")
	)
	(segment
		(start 41.03624 -109.986318)
		(end 41.03624 -105.720388)
		(width 0.254)
		(layer "B.Cu")
		(net "P12V_OCP_V3_2_ISENSE_MPS_TIC")
	)
	(segment
		(start 41.06418 -96.454468)
		(end 41.06418 -87.513668)
		(width 0.254)
		(layer "B.Cu")
		(net "P12V_OCP_V3_2_ISENSE_MPS_TIC")
	)
	(segment
		(start 40.04564 -97.473008)
		(end 41.06418 -96.454468)
		(width 0.254)
		(layer "B.Cu")
		(net "P12V_OCP_V3_2_ISENSE_MPS_TIC")
	)
	(segment
		(start 37.38118 -56.056022)
		(end 37.38118 -76.444094)
		(width 0.254)
		(layer "F.Cu")
		(net "P12V_OCP_V3_2_ISENSE_MPS_MAM")
	)
	(segment
		(start 62.559438 -32.287972)
		(end 62.559438 -33.531048)
		(width 0.254)
		(layer "F.Cu")
		(net "P12V_OCP_V3_2_ISENSE_MPS_MAM")
	)
	(segment
		(start 62.559438 -33.531048)
		(end 61.327538 -34.762948)
		(width 0.254)
		(layer "F.Cu")
		(net "P12V_OCP_V3_2_ISENSE_MPS_MAM")
	)
	(segment
		(start 41.86682 -80.929734)
		(end 41.86682 -87.513668)
		(width 0.254)
		(layer "F.Cu")
		(net "P12V_OCP_V3_2_ISENSE_MPS_MAM")
	)
	(segment
		(start 61.327538 -34.762948)
		(end 58.674254 -34.762948)
		(width 0.254)
		(layer "F.Cu")
		(net "P12V_OCP_V3_2_ISENSE_MPS_MAM")
	)
	(segment
		(start 29.732478 -98.570034)
		(end 30.342078 -98.570034)
		(width 0.12954)
		(layer "F.Cu")
		(net "P12V_OCP_V3_2_ISENSE_MPS_MAM")
	)
	(segment
		(start 58.674254 -34.762948)
		(end 37.38118 -56.056022)
		(width 0.254)
		(layer "F.Cu")
		(net "P12V_OCP_V3_2_ISENSE_MPS_MAM")
	)
	(segment
		(start 37.38118 -76.444094)
		(end 41.86682 -80.929734)
		(width 0.254)
		(layer "F.Cu")
		(net "P12V_OCP_V3_2_ISENSE_MPS_MAM")
	)
	(via
		(at 30.342078 -98.570034)
		(size 0.508)
		(drill 0.254)
		(layers "F.Cu" "B.Cu")
		(net "P12V_OCP_V3_2_ISENSE_MPS_MAM")
	)
	(via
		(at 62.559438 -33.531048)
		(size 0.762)
		(drill 0.381)
		(layers "F.Cu" "B.Cu")
		(net "P12V_OCP_V3_2_ISENSE_MPS_MAM")
	)
	(via
		(at 41.86682 -87.513668)
		(size 0.508)
		(drill 0.254)
		(layers "F.Cu" "B.Cu")
		(net "P12V_OCP_V3_2_ISENSE_MPS_MAM")
	)
	(segment
		(start 32.05988 -96.865948)
		(end 31.55188 -96.865948)
		(width 0.254)
		(layer "In2.Cu")
		(net "P12V_OCP_V3_2_ISENSE_MPS_MAM")
	)
	(segment
		(start 31.17088 -97.246948)
		(end 31.17088 -97.741232)
		(width 0.254)
		(layer "In2.Cu")
		(net "P12V_OCP_V3_2_ISENSE_MPS_MAM")
	)
	(segment
		(start 33.73882 -96.992948)
		(end 32.18688 -96.992948)
		(width 0.254)
		(layer "In2.Cu")
		(net "P12V_OCP_V3_2_ISENSE_MPS_MAM")
	)
	(segment
		(start 41.86682 -87.513668)
		(end 41.86682 -88.864948)
		(width 0.254)
		(layer "In2.Cu")
		(net "P12V_OCP_V3_2_ISENSE_MPS_MAM")
	)
	(segment
		(start 41.86682 -88.864948)
		(end 33.73882 -96.992948)
		(width 0.254)
		(layer "In2.Cu")
		(net "P12V_OCP_V3_2_ISENSE_MPS_MAM")
	)
	(segment
		(start 31.55188 -96.865948)
		(end 31.17088 -97.246948)
		(width 0.254)
		(layer "In2.Cu")
		(net "P12V_OCP_V3_2_ISENSE_MPS_MAM")
	)
	(segment
		(start 32.18688 -96.992948)
		(end 32.05988 -96.865948)
		(width 0.254)
		(layer "In2.Cu")
		(net "P12V_OCP_V3_2_ISENSE_MPS_MAM")
	)
	(segment
		(start 31.17088 -97.741232)
		(end 30.342078 -98.570034)
		(width 0.254)
		(layer "In2.Cu")
		(net "P12V_OCP_V3_2_ISENSE_MPS_MAM")
	)
	(segment
		(start 40.42918 -81.643982)
		(end 40.42918 -87.513668)
		(width 0.254)
		(layer "F.Cu")
		(net "P12V_OCP_V3_2_ISENSE_MAM_TIC")
	)
	(segment
		(start 59.727338 -32.94761)
		(end 59.1185 -33.556448)
		(width 0.254)
		(layer "F.Cu")
		(net "P12V_OCP_V3_2_ISENSE_MAM_TIC")
	)
	(segment
		(start 59.1185 -33.556448)
		(end 58.29681 -33.556448)
		(width 0.254)
		(layer "F.Cu")
		(net "P12V_OCP_V3_2_ISENSE_MAM_TIC")
	)
	(segment
		(start 39.077138 -110.587282)
		(end 38.817804 -110.327948)
		(width 0.12954)
		(layer "F.Cu")
		(net "P12V_OCP_V3_2_ISENSE_MAM_TIC")
	)
	(segment
		(start 59.727338 -32.287972)
		(end 59.727338 -32.94761)
		(width 0.254)
		(layer "F.Cu")
		(net "P12V_OCP_V3_2_ISENSE_MAM_TIC")
	)
	(segment
		(start 58.29681 -33.556448)
		(end 35.85972 -55.993538)
		(width 0.254)
		(layer "F.Cu")
		(net "P12V_OCP_V3_2_ISENSE_MAM_TIC")
	)
	(segment
		(start 39.427404 -110.587282)
		(end 39.077138 -110.587282)
		(width 0.12954)
		(layer "F.Cu")
		(net "P12V_OCP_V3_2_ISENSE_MAM_TIC")
	)
	(segment
		(start 35.85972 -77.074522)
		(end 40.42918 -81.643982)
		(width 0.254)
		(layer "F.Cu")
		(net "P12V_OCP_V3_2_ISENSE_MAM_TIC")
	)
	(segment
		(start 35.85972 -55.993538)
		(end 35.85972 -77.074522)
		(width 0.254)
		(layer "F.Cu")
		(net "P12V_OCP_V3_2_ISENSE_MAM_TIC")
	)
	(via
		(at 40.42918 -87.513668)
		(size 0.508)
		(drill 0.254)
		(layers "F.Cu" "B.Cu")
		(net "P12V_OCP_V3_2_ISENSE_MAM_TIC")
	)
	(via
		(at 38.817804 -110.327948)
		(size 0.508)
		(drill 0.254)
		(layers "F.Cu" "B.Cu")
		(net "P12V_OCP_V3_2_ISENSE_MAM_TIC")
	)
	(segment
		(start 40.87876 -86.566248)
		(end 40.42918 -87.015828)
		(width 0.254)
		(layer "In2.Cu")
		(net "P12V_OCP_V3_2_ISENSE_MAM_TIC")
	)
	(segment
		(start 37.465 -95.733108)
		(end 43.10634 -90.091768)
		(width 0.254)
		(layer "In2.Cu")
		(net "P12V_OCP_V3_2_ISENSE_MAM_TIC")
	)
	(segment
		(start 38.817804 -110.327948)
		(end 38.817804 -105.593388)
		(width 0.254)
		(layer "In2.Cu")
		(net "P12V_OCP_V3_2_ISENSE_MAM_TIC")
	)
	(segment
		(start 42.3291 -86.566248)
		(end 40.87876 -86.566248)
		(width 0.254)
		(layer "In2.Cu")
		(net "P12V_OCP_V3_2_ISENSE_MAM_TIC")
	)
	(segment
		(start 43.10634 -90.091768)
		(end 43.10634 -87.343488)
		(width 0.254)
		(layer "In2.Cu")
		(net "P12V_OCP_V3_2_ISENSE_MAM_TIC")
	)
	(segment
		(start 38.817804 -105.593388)
		(end 37.465 -104.240584)
		(width 0.254)
		(layer "In2.Cu")
		(net "P12V_OCP_V3_2_ISENSE_MAM_TIC")
	)
	(segment
		(start 43.10634 -87.343488)
		(end 42.3291 -86.566248)
		(width 0.254)
		(layer "In2.Cu")
		(net "P12V_OCP_V3_2_ISENSE_MAM_TIC")
	)
	(segment
		(start 40.42918 -87.015828)
		(end 40.42918 -87.513668)
		(width 0.254)
		(layer "In2.Cu")
		(net "P12V_OCP_V3_2_ISENSE_MAM_TIC")
	)
	(segment
		(start 37.465 -104.240584)
		(end 37.465 -95.733108)
		(width 0.254)
		(layer "In2.Cu")
		(net "P12V_OCP_V3_2_ISENSE_MAM_TIC")
	)
	(segment
		(start 28.132278 -98.570034)
		(end 27.254454 -98.570034)
		(width 0.254)
		(layer "F.Cu")
		(net "P12V_OCP_V3_2_ISENSE_MAM_MAM")
	)
	(segment
		(start 39.79418 -81.788508)
		(end 39.79418 -87.513668)
		(width 0.254)
		(layer "F.Cu")
		(net "P12V_OCP_V3_2_ISENSE_MAM_MAM")
	)
	(segment
		(start 59.388756 -31.487872)
		(end 58.99404 -31.882588)
		(width 0.254)
		(layer "F.Cu")
		(net "P12V_OCP_V3_2_ISENSE_MAM_MAM")
	)
	(segment
		(start 58.99404 -32.730948)
		(end 58.71972 -33.005268)
		(width 0.254)
		(layer "F.Cu")
		(net "P12V_OCP_V3_2_ISENSE_MAM_MAM")
	)
	(segment
		(start 60.527438 -31.487872)
		(end 59.388756 -31.487872)
		(width 0.254)
		(layer "F.Cu")
		(net "P12V_OCP_V3_2_ISENSE_MAM_MAM")
	)
	(segment
		(start 35.30854 -77.302868)
		(end 39.79418 -81.788508)
		(width 0.254)
		(layer "F.Cu")
		(net "P12V_OCP_V3_2_ISENSE_MAM_MAM")
	)
	(segment
		(start 58.99404 -31.882588)
		(end 58.99404 -32.730948)
		(width 0.254)
		(layer "F.Cu")
		(net "P12V_OCP_V3_2_ISENSE_MAM_MAM")
	)
	(segment
		(start 58.71972 -33.005268)
		(end 58.068464 -33.005268)
		(width 0.254)
		(layer "F.Cu")
		(net "P12V_OCP_V3_2_ISENSE_MAM_MAM")
	)
	(segment
		(start 58.068464 -33.005268)
		(end 35.30854 -55.765192)
		(width 0.254)
		(layer "F.Cu")
		(net "P12V_OCP_V3_2_ISENSE_MAM_MAM")
	)
	(segment
		(start 35.30854 -55.765192)
		(end 35.30854 -77.302868)
		(width 0.254)
		(layer "F.Cu")
		(net "P12V_OCP_V3_2_ISENSE_MAM_MAM")
	)
	(via
		(at 27.254454 -98.570034)
		(size 0.508)
		(drill 0.254)
		(layers "F.Cu" "B.Cu")
		(net "P12V_OCP_V3_2_ISENSE_MAM_MAM")
	)
	(via
		(at 39.79418 -87.513668)
		(size 0.508)
		(drill 0.254)
		(layers "F.Cu" "B.Cu")
		(net "P12V_OCP_V3_2_ISENSE_MAM_MAM")
	)
	(segment
		(start 39.79418 -87.513668)
		(end 39.79418 -88.623648)
		(width 0.254)
		(layer "In2.Cu")
		(net "P12V_OCP_V3_2_ISENSE_MAM_MAM")
	)
	(segment
		(start 39.79418 -88.623648)
		(end 32.18688 -96.230948)
		(width 0.254)
		(layer "In2.Cu")
		(net "P12V_OCP_V3_2_ISENSE_MAM_MAM")
	)
	(segment
		(start 32.18688 -96.230948)
		(end 31.17088 -96.230948)
		(width 0.254)
		(layer "In2.Cu")
		(net "P12V_OCP_V3_2_ISENSE_MAM_MAM")
	)
	(segment
		(start 31.17088 -96.230948)
		(end 30.66288 -95.722948)
		(width 0.254)
		(layer "In2.Cu")
		(net "P12V_OCP_V3_2_ISENSE_MAM_MAM")
	)
	(segment
		(start 30.10154 -95.722948)
		(end 27.254454 -98.570034)
		(width 0.254)
		(layer "In2.Cu")
		(net "P12V_OCP_V3_2_ISENSE_MAM_MAM")
	)
	(segment
		(start 30.66288 -95.722948)
		(end 30.10154 -95.722948)
		(width 0.254)
		(layer "In2.Cu")
		(net "P12V_OCP_V3_2_ISENSE_MAM_MAM")
	)
	(segment
		(start 35.682428 -98.697034)
		(end 35.889184 -98.90379)
		(width 0.12954)
		(layer "F.Cu")
		(net "P12V_OCP_V3_2_ISENSE_MAM")
	)
	(segment
		(start 28.932378 -98.570034)
		(end 29.440378 -98.062034)
		(width 0.12954)
		(layer "F.Cu")
		(net "P12V_OCP_V3_2_ISENSE_MAM")
	)
	(segment
		(start 33.161478 -98.570034)
		(end 33.288478 -98.697034)
		(width 0.12954)
		(layer "F.Cu")
		(net "P12V_OCP_V3_2_ISENSE_MAM")
	)
	(segment
		(start 29.440378 -98.062034)
		(end 32.888428 -98.062034)
		(width 0.12954)
		(layer "F.Cu")
		(net "P12V_OCP_V3_2_ISENSE_MAM")
	)
	(segment
		(start 33.288478 -98.697034)
		(end 34.412428 -98.697034)
		(width 0.12954)
		(layer "F.Cu")
		(net "P12V_OCP_V3_2_ISENSE_MAM")
	)
	(segment
		(start 34.412428 -98.697034)
		(end 35.682428 -98.697034)
		(width 0.12954)
		(layer "F.Cu")
		(net "P12V_OCP_V3_2_ISENSE_MAM")
	)
	(segment
		(start 35.889184 -98.90379)
		(end 36.988496 -98.90379)
		(width 0.12954)
		(layer "F.Cu")
		(net "P12V_OCP_V3_2_ISENSE_MAM")
	)
	(segment
		(start 33.161478 -98.335084)
		(end 33.161478 -98.570034)
		(width 0.12954)
		(layer "F.Cu")
		(net "P12V_OCP_V3_2_ISENSE_MAM")
	)
	(segment
		(start 32.888428 -98.062034)
		(end 33.161478 -98.335084)
		(width 0.12954)
		(layer "F.Cu")
		(net "P12V_OCP_V3_2_ISENSE_MAM")
	)
	(via
		(at 34.412428 -98.697034)
		(size 0.762)
		(drill 0.381)
		(layers "F.Cu" "B.Cu")
		(net "P12V_OCP_V3_2_ISENSE_MAM")
	)
	(segment
		(start 69.672454 -30.162246)
		(end 70.052438 -30.54223)
		(width 0.12954)
		(layer "F.Cu")
		(net "P12V_OCP_V3_2_EN_2_R3")
	)
	(segment
		(start 69.672454 -30.162246)
		(end 69.672454 -29.264864)
		(width 0.12954)
		(layer "F.Cu")
		(net "P12V_OCP_V3_2_EN_2_R3")
	)
	(segment
		(start 70.052438 -30.54223)
		(end 70.052438 -31.487872)
		(width 0.12954)
		(layer "F.Cu")
		(net "P12V_OCP_V3_2_EN_2_R3")
	)
	(via
		(at 70.052438 -30.54223)
		(size 0.508)
		(drill 0.254)
		(layers "F.Cu" "B.Cu")
		(net "P12V_OCP_V3_2_EN_2_R3")
	)
	(segment
		(start 64.72555 -38.591998)
		(end 64.090804 -37.957252)
		(width 0.12954)
		(layer "F.Cu")
		(net "P12V_OCP_UV_2_R")
	)
	(segment
		(start 66.044064 -39.087298)
		(end 65.548764 -38.591998)
		(width 0.12954)
		(layer "F.Cu")
		(net "P12V_OCP_UV_2_R")
	)
	(segment
		(start 65.548764 -38.591998)
		(end 64.72555 -38.591998)
		(width 0.12954)
		(layer "F.Cu")
		(net "P12V_OCP_UV_2_R")
	)
	(segment
		(start 66.0654 -39.087298)
		(end 66.044064 -39.087298)
		(width 0.12954)
		(layer "F.Cu")
		(net "P12V_OCP_UV_2_R")
	)
	(segment
		(start 64.090804 -37.957252)
		(end 63.42253 -37.957252)
		(width 0.12954)
		(layer "F.Cu")
		(net "P12V_OCP_UV_2_R")
	)
	(via
		(at 64.72555 -38.591998)
		(size 0.762)
		(drill 0.381)
		(layers "F.Cu" "B.Cu")
		(net "P12V_OCP_UV_2_R")
	)
	(segment
		(start 76.839318 -18.178018)
		(end 77.532738 -18.178018)
		(width 0.12954)
		(layer "F.Cu")
		(net "P12V_OCP_UV_2")
	)
	(segment
		(start 77.532738 -18.224246)
		(end 78.35646 -19.047968)
		(width 0.12954)
		(layer "F.Cu")
		(net "P12V_OCP_UV_2")
	)
	(segment
		(start 78.35646 -19.047968)
		(end 78.35646 -19.94408)
		(width 0.12954)
		(layer "F.Cu")
		(net "P12V_OCP_UV_2")
	)
	(segment
		(start 77.532738 -18.178018)
		(end 77.532738 -18.224246)
		(width 0.12954)
		(layer "F.Cu")
		(net "P12V_OCP_UV_2")
	)
	(segment
		(start 76.825602 -18.164302)
		(end 76.839318 -18.178018)
		(width 0.12954)
		(layer "F.Cu")
		(net "P12V_OCP_UV_2")
	)
	(segment
		(start 75.816968 -18.164302)
		(end 76.825602 -18.164302)
		(width 0.12954)
		(layer "F.Cu")
		(net "P12V_OCP_UV_2")
	)
	(segment
		(start 66.0654 -39.887398)
		(end 66.0654 -40.528748)
		(width 0.12954)
		(layer "F.Cu")
		(net "P12V_OCP_UV_2")
	)
	(via
		(at 66.0654 -40.528748)
		(size 0.508)
		(drill 0.254)
		(layers "F.Cu" "B.Cu")
		(net "P12V_OCP_UV_2")
	)
	(via
		(at 77.532738 -18.178018)
		(size 0.508)
		(drill 0.254)
		(layers "F.Cu" "B.Cu")
		(net "P12V_OCP_UV_2")
	)
	(segment
		(start 66.0654 -40.528748)
		(end 66.7004 -39.893748)
		(width 0.12954)
		(layer "B.Cu")
		(net "P12V_OCP_UV_2")
	)
	(segment
		(start 76.181966 -18.178018)
		(end 75.604878 -18.755106)
		(width 0.12954)
		(layer "B.Cu")
		(net "P12V_OCP_UV_2")
	)
	(segment
		(start 74.03084 -35.585908)
		(end 74.03084 -31.653988)
		(width 0.12954)
		(layer "B.Cu")
		(net "P12V_OCP_UV_2")
	)
	(segment
		(start 77.532738 -18.178018)
		(end 76.181966 -18.178018)
		(width 0.12954)
		(layer "B.Cu")
		(net "P12V_OCP_UV_2")
	)
	(segment
		(start 75.467718 -25.629108)
		(end 75.604878 -25.491948)
		(width 0.12954)
		(layer "B.Cu")
		(net "P12V_OCP_UV_2")
	)
	(segment
		(start 75.604878 -18.755106)
		(end 75.604878 -25.491948)
		(width 0.12954)
		(layer "B.Cu")
		(net "P12V_OCP_UV_2")
	)
	(segment
		(start 69.723 -39.893748)
		(end 74.03084 -35.585908)
		(width 0.12954)
		(layer "B.Cu")
		(net "P12V_OCP_UV_2")
	)
	(segment
		(start 74.03084 -31.653988)
		(end 75.467718 -30.21711)
		(width 0.12954)
		(layer "B.Cu")
		(net "P12V_OCP_UV_2")
	)
	(segment
		(start 66.7004 -39.893748)
		(end 69.723 -39.893748)
		(width 0.12954)
		(layer "B.Cu")
		(net "P12V_OCP_UV_2")
	)
	(segment
		(start 75.467718 -30.21711)
		(end 75.467718 -25.629108)
		(width 0.12954)
		(layer "B.Cu")
		(net "P12V_OCP_UV_2")
	)
	(segment
		(start 463.8294 -37.14242)
		(end 465.143088 -38.456108)
		(width 0.12954)
		(layer "F.Cu")
		(net "P12V_OCP_UV_1_R")
	)
	(segment
		(start 462.1403 -36.84778)
		(end 462.43494 -37.14242)
		(width 0.12954)
		(layer "F.Cu")
		(net "P12V_OCP_UV_1_R")
	)
	(segment
		(start 462.1403 -36.84778)
		(end 461.87995 -37.10813)
		(width 0.12954)
		(layer "F.Cu")
		(net "P12V_OCP_UV_1_R")
	)
	(segment
		(start 462.43494 -37.14242)
		(end 463.8294 -37.14242)
		(width 0.12954)
		(layer "F.Cu")
		(net "P12V_OCP_UV_1_R")
	)
	(segment
		(start 461.87995 -37.10813)
		(end 460.74457 -37.10813)
		(width 0.12954)
		(layer "F.Cu")
		(net "P12V_OCP_UV_1_R")
	)
	(segment
		(start 465.143088 -38.456108)
		(end 465.144358 -38.456108)
		(width 0.12954)
		(layer "F.Cu")
		(net "P12V_OCP_UV_1_R")
	)
	(via
		(at 462.1403 -36.84778)
		(size 0.762)
		(drill 0.381)
		(layers "F.Cu" "B.Cu")
		(net "P12V_OCP_UV_1_R")
	)
	(segment
		(start 459.706218 -36.30803)
		(end 460.74457 -36.30803)
		(width 0.12954)
		(layer "F.Cu")
		(net "P12V_OCP_UV_1")
	)
	(segment
		(start 449.673472 -18.463514)
		(end 450.497194 -19.287236)
		(width 0.12954)
		(layer "F.Cu")
		(net "P12V_OCP_UV_1")
	)
	(segment
		(start 448.966336 -18.449798)
		(end 448.980052 -18.463514)
		(width 0.12954)
		(layer "F.Cu")
		(net "P12V_OCP_UV_1")
	)
	(segment
		(start 448.980052 -18.463514)
		(end 449.673472 -18.463514)
		(width 0.12954)
		(layer "F.Cu")
		(net "P12V_OCP_UV_1")
	)
	(segment
		(start 450.497194 -19.287236)
		(end 450.497194 -20.229576)
		(width 0.12954)
		(layer "F.Cu")
		(net "P12V_OCP_UV_1")
	)
	(segment
		(start 447.957702 -18.449798)
		(end 448.966336 -18.449798)
		(width 0.12954)
		(layer "F.Cu")
		(net "P12V_OCP_UV_1")
	)
	(segment
		(start 459.46314 -36.551108)
		(end 459.706218 -36.30803)
		(width 0.12954)
		(layer "F.Cu")
		(net "P12V_OCP_UV_1")
	)
	(via
		(at 449.673472 -18.463514)
		(size 0.508)
		(drill 0.254)
		(layers "F.Cu" "B.Cu")
		(net "P12V_OCP_UV_1")
	)
	(via
		(at 459.46314 -36.551108)
		(size 0.508)
		(drill 0.254)
		(layers "F.Cu" "B.Cu")
		(net "P12V_OCP_UV_1")
	)
	(segment
		(start 459.46314 -36.551108)
		(end 452.798434 -36.551108)
		(width 0.12954)
		(layer "B.Cu")
		(net "P12V_OCP_UV_1")
	)
	(segment
		(start 449.94576 -23.249128)
		(end 450.36486 -23.668228)
		(width 0.12954)
		(layer "B.Cu")
		(net "P12V_OCP_UV_1")
	)
	(segment
		(start 452.798434 -36.551108)
		(end 451.489318 -35.241992)
		(width 0.12954)
		(layer "B.Cu")
		(net "P12V_OCP_UV_1")
	)
	(segment
		(start 449.673472 -18.463514)
		(end 449.673472 -19.06778)
		(width 0.12954)
		(layer "B.Cu")
		(net "P12V_OCP_UV_1")
	)
	(segment
		(start 449.94576 -19.340068)
		(end 449.94576 -23.249128)
		(width 0.12954)
		(layer "B.Cu")
		(net "P12V_OCP_UV_1")
	)
	(segment
		(start 450.36486 -29.82341)
		(end 450.36486 -29.417772)
		(width 0.12954)
		(layer "B.Cu")
		(net "P12V_OCP_UV_1")
	)
	(segment
		(start 451.489318 -30.947868)
		(end 450.36486 -29.82341)
		(width 0.12954)
		(layer "B.Cu")
		(net "P12V_OCP_UV_1")
	)
	(segment
		(start 449.673472 -19.06778)
		(end 449.94576 -19.340068)
		(width 0.12954)
		(layer "B.Cu")
		(net "P12V_OCP_UV_1")
	)
	(segment
		(start 451.489318 -35.241992)
		(end 451.489318 -30.947868)
		(width 0.12954)
		(layer "B.Cu")
		(net "P12V_OCP_UV_1")
	)
	(segment
		(start 450.36486 -29.417772)
		(end 450.36486 -23.668228)
		(width 0.12954)
		(layer "B.Cu")
		(net "P12V_OCP_UV_1")
	)
	(segment
		(start 36.530534 -111.603282)
		(end 36.403534 -111.730282)
		(width 0.12954)
		(layer "F.Cu")
		(net "P12V_OCP_SFF_ISENSE_TIC")
	)
	(segment
		(start 35.279584 -111.730282)
		(end 34.136838 -111.730282)
		(width 0.12954)
		(layer "F.Cu")
		(net "P12V_OCP_SFF_ISENSE_TIC")
	)
	(segment
		(start 39.72306 -112.111282)
		(end 37.038534 -112.111282)
		(width 0.12954)
		(layer "F.Cu")
		(net "P12V_OCP_SFF_ISENSE_TIC")
	)
	(segment
		(start 37.038534 -112.111282)
		(end 36.530534 -111.603282)
		(width 0.12954)
		(layer "F.Cu")
		(net "P12V_OCP_SFF_ISENSE_TIC")
	)
	(segment
		(start 40.227504 -111.606838)
		(end 39.72306 -112.111282)
		(width 0.12954)
		(layer "F.Cu")
		(net "P12V_OCP_SFF_ISENSE_TIC")
	)
	(segment
		(start 34.136838 -111.730282)
		(end 33.365186 -110.95863)
		(width 0.12954)
		(layer "F.Cu")
		(net "P12V_OCP_SFF_ISENSE_TIC")
	)
	(segment
		(start 36.403534 -111.730282)
		(end 35.279584 -111.730282)
		(width 0.12954)
		(layer "F.Cu")
		(net "P12V_OCP_SFF_ISENSE_TIC")
	)
	(segment
		(start 33.365186 -110.95863)
		(end 32.51581 -110.95863)
		(width 0.12954)
		(layer "F.Cu")
		(net "P12V_OCP_SFF_ISENSE_TIC")
	)
	(via
		(at 35.279584 -111.730282)
		(size 0.762)
		(drill 0.381)
		(layers "F.Cu" "B.Cu")
		(net "P12V_OCP_SFF_ISENSE_TIC")
	)
	(segment
		(start 436.224172 -34.373058)
		(end 436.224172 -32.573468)
		(width 0.254)
		(layer "F.Cu")
		(net "P12V_OCP_SFF_ISENSE_MPS_TIC")
	)
	(segment
		(start 39.427404 -111.606838)
		(end 38.817804 -111.606838)
		(width 0.12954)
		(layer "F.Cu")
		(net "P12V_OCP_SFF_ISENSE_MPS_TIC")
	)
	(via
		(at 38.817804 -111.606838)
		(size 0.508)
		(drill 0.254)
		(layers "F.Cu" "B.Cu")
		(net "P12V_OCP_SFF_ISENSE_MPS_TIC")
	)
	(via
		(at 40.15994 -95.547688)
		(size 0.508)
		(drill 0.254)
		(layers "F.Cu" "B.Cu")
		(net "P12V_OCP_SFF_ISENSE_MPS_TIC")
	)
	(via
		(at 436.224172 -34.373058)
		(size 0.508)
		(drill 0.254)
		(layers "F.Cu" "B.Cu")
		(net "P12V_OCP_SFF_ISENSE_MPS_TIC")
	)
	(via
		(at 340.28888 -107.483148)
		(size 0.508)
		(drill 0.254)
		(layers "F.Cu" "B.Cu")
		(net "P12V_OCP_SFF_ISENSE_MPS_TIC")
	)
	(segment
		(start 39.50716 -94.569788)
		(end 40.15994 -95.222568)
		(width 0.254)
		(layer "B.Cu")
		(net "P12V_OCP_SFF_ISENSE_MPS_TIC")
	)
	(segment
		(start 428.123096 -83.570318)
		(end 404.970742 -83.570318)
		(width 0.254)
		(layer "B.Cu")
		(net "P12V_OCP_SFF_ISENSE_MPS_TIC")
	)
	(segment
		(start 38.05936 -104.585008)
		(end 38.05936 -95.113348)
		(width 0.254)
		(layer "B.Cu")
		(net "P12V_OCP_SFF_ISENSE_MPS_TIC")
	)
	(segment
		(start 355.007672 -104.130348)
		(end 342.454992 -104.130348)
		(width 0.254)
		(layer "B.Cu")
		(net "P12V_OCP_SFF_ISENSE_MPS_TIC")
	)
	(segment
		(start 38.05936 -95.113348)
		(end 38.60292 -94.569788)
		(width 0.254)
		(layer "B.Cu")
		(net "P12V_OCP_SFF_ISENSE_MPS_TIC")
	)
	(segment
		(start 435.81828 -57.007252)
		(end 434.346096 -58.479436)
		(width 0.254)
		(layer "B.Cu")
		(net "P12V_OCP_SFF_ISENSE_MPS_TIC")
	)
	(segment
		(start 436.75808 -34.906966)
		(end 436.75808 -38.974268)
		(width 0.254)
		(layer "B.Cu")
		(net "P12V_OCP_SFF_ISENSE_MPS_TIC")
	)
	(segment
		(start 435.81828 -50.74158)
		(end 435.81828 -57.007252)
		(width 0.254)
		(layer "B.Cu")
		(net "P12V_OCP_SFF_ISENSE_MPS_TIC")
	)
	(segment
		(start 38.60292 -94.569788)
		(end 39.50716 -94.569788)
		(width 0.254)
		(layer "B.Cu")
		(net "P12V_OCP_SFF_ISENSE_MPS_TIC")
	)
	(segment
		(start 39.76624 -110.658402)
		(end 39.76624 -106.291888)
		(width 0.254)
		(layer "B.Cu")
		(net "P12V_OCP_SFF_ISENSE_MPS_TIC")
	)
	(segment
		(start 384.987292 -103.553768)
		(end 384.987292 -109.28858)
		(width 0.254)
		(layer "B.Cu")
		(net "P12V_OCP_SFF_ISENSE_MPS_TIC")
	)
	(segment
		(start 438.40146 -48.1584)
		(end 435.81828 -50.74158)
		(width 0.254)
		(layer "B.Cu")
		(net "P12V_OCP_SFF_ISENSE_MPS_TIC")
	)
	(segment
		(start 434.346096 -58.479436)
		(end 434.346096 -77.347318)
		(width 0.254)
		(layer "B.Cu")
		(net "P12V_OCP_SFF_ISENSE_MPS_TIC")
	)
	(segment
		(start 39.76624 -106.291888)
		(end 38.05936 -104.585008)
		(width 0.254)
		(layer "B.Cu")
		(net "P12V_OCP_SFF_ISENSE_MPS_TIC")
	)
	(segment
		(start 40.15994 -95.222568)
		(end 40.15994 -95.547688)
		(width 0.254)
		(layer "B.Cu")
		(net "P12V_OCP_SFF_ISENSE_MPS_TIC")
	)
	(segment
		(start 436.224172 -34.373058)
		(end 436.75808 -34.906966)
		(width 0.254)
		(layer "B.Cu")
		(net "P12V_OCP_SFF_ISENSE_MPS_TIC")
	)
	(segment
		(start 342.454992 -104.130348)
		(end 340.28888 -106.29646)
		(width 0.254)
		(layer "B.Cu")
		(net "P12V_OCP_SFF_ISENSE_MPS_TIC")
	)
	(segment
		(start 340.28888 -106.29646)
		(end 340.28888 -107.483148)
		(width 0.254)
		(layer "B.Cu")
		(net "P12V_OCP_SFF_ISENSE_MPS_TIC")
	)
	(segment
		(start 436.75808 -38.974268)
		(end 438.40146 -40.617648)
		(width 0.254)
		(layer "B.Cu")
		(net "P12V_OCP_SFF_ISENSE_MPS_TIC")
	)
	(segment
		(start 38.817804 -111.606838)
		(end 39.76624 -110.658402)
		(width 0.254)
		(layer "B.Cu")
		(net "P12V_OCP_SFF_ISENSE_MPS_TIC")
	)
	(segment
		(start 363.984032 -113.106708)
		(end 355.007672 -104.130348)
		(width 0.254)
		(layer "B.Cu")
		(net "P12V_OCP_SFF_ISENSE_MPS_TIC")
	)
	(segment
		(start 434.346096 -77.347318)
		(end 428.123096 -83.570318)
		(width 0.254)
		(layer "B.Cu")
		(net "P12V_OCP_SFF_ISENSE_MPS_TIC")
	)
	(segment
		(start 404.970742 -83.570318)
		(end 384.987292 -103.553768)
		(width 0.254)
		(layer "B.Cu")
		(net "P12V_OCP_SFF_ISENSE_MPS_TIC")
	)
	(segment
		(start 384.987292 -109.28858)
		(end 381.169164 -113.106708)
		(width 0.254)
		(layer "B.Cu")
		(net "P12V_OCP_SFF_ISENSE_MPS_TIC")
	)
	(segment
		(start 438.40146 -40.617648)
		(end 438.40146 -48.1584)
		(width 0.254)
		(layer "B.Cu")
		(net "P12V_OCP_SFF_ISENSE_MPS_TIC")
	)
	(segment
		(start 381.169164 -113.106708)
		(end 363.984032 -113.106708)
		(width 0.254)
		(layer "B.Cu")
		(net "P12V_OCP_SFF_ISENSE_MPS_TIC")
	)
	(segment
		(start 210.164172 -106.32186)
		(end 208.86928 -106.32186)
		(width 0.254)
		(layer "In6.Cu")
		(net "P12V_OCP_SFF_ISENSE_MPS_TIC")
	)
	(segment
		(start 192.141348 -96.992948)
		(end 187.1218 -91.9734)
		(width 0.254)
		(layer "In6.Cu")
		(net "P12V_OCP_SFF_ISENSE_MPS_TIC")
	)
	(segment
		(start 107.5055 -83.530948)
		(end 103.01224 -79.037688)
		(width 0.254)
		(layer "In6.Cu")
		(net "P12V_OCP_SFF_ISENSE_MPS_TIC")
	)
	(segment
		(start 201.07148 -96.992948)
		(end 192.141348 -96.992948)
		(width 0.254)
		(layer "In6.Cu")
		(net "P12V_OCP_SFF_ISENSE_MPS_TIC")
	)
	(segment
		(start 203.07935 -99.000818)
		(end 201.07148 -96.992948)
		(width 0.254)
		(layer "In6.Cu")
		(net "P12V_OCP_SFF_ISENSE_MPS_TIC")
	)
	(segment
		(start 340.28888 -107.483148)
		(end 340.28888 -108.430568)
		(width 0.254)
		(layer "In6.Cu")
		(net "P12V_OCP_SFF_ISENSE_MPS_TIC")
	)
	(segment
		(start 340.38286 -108.524548)
		(end 340.38286 -111.749586)
		(width 0.254)
		(layer "In6.Cu")
		(net "P12V_OCP_SFF_ISENSE_MPS_TIC")
	)
	(segment
		(start 242.135406 -104.966008)
		(end 225.519996 -104.966008)
		(width 0.254)
		(layer "In6.Cu")
		(net "P12V_OCP_SFF_ISENSE_MPS_TIC")
	)
	(segment
		(start 111.93526 -87.084408)
		(end 108.3818 -83.530948)
		(width 0.254)
		(layer "In6.Cu")
		(net "P12V_OCP_SFF_ISENSE_MPS_TIC")
	)
	(segment
		(start 167.868092 -92.329508)
		(end 152.512014 -92.329508)
		(width 0.254)
		(layer "In6.Cu")
		(net "P12V_OCP_SFF_ISENSE_MPS_TIC")
	)
	(segment
		(start 147.266914 -87.084408)
		(end 111.93526 -87.084408)
		(width 0.254)
		(layer "In6.Cu")
		(net "P12V_OCP_SFF_ISENSE_MPS_TIC")
	)
	(segment
		(start 225.519996 -104.966008)
		(end 222.053404 -108.4326)
		(width 0.254)
		(layer "In6.Cu")
		(net "P12V_OCP_SFF_ISENSE_MPS_TIC")
	)
	(segment
		(start 260.32968 -108.803948)
		(end 256.97688 -112.156748)
		(width 0.254)
		(layer "In6.Cu")
		(net "P12V_OCP_SFF_ISENSE_MPS_TIC")
	)
	(segment
		(start 182.4228 -91.9734)
		(end 181.1528 -90.7034)
		(width 0.254)
		(layer "In6.Cu")
		(net "P12V_OCP_SFF_ISENSE_MPS_TIC")
	)
	(segment
		(start 108.3818 -83.530948)
		(end 107.5055 -83.530948)
		(width 0.254)
		(layer "In6.Cu")
		(net "P12V_OCP_SFF_ISENSE_MPS_TIC")
	)
	(segment
		(start 187.1218 -91.9734)
		(end 182.4228 -91.9734)
		(width 0.254)
		(layer "In6.Cu")
		(net "P12V_OCP_SFF_ISENSE_MPS_TIC")
	)
	(segment
		(start 81.147158 -79.037688)
		(end 64.637158 -95.547688)
		(width 0.254)
		(layer "In6.Cu")
		(net "P12V_OCP_SFF_ISENSE_MPS_TIC")
	)
	(segment
		(start 261.54888 -108.803948)
		(end 260.32968 -108.803948)
		(width 0.254)
		(layer "In6.Cu")
		(net "P12V_OCP_SFF_ISENSE_MPS_TIC")
	)
	(segment
		(start 249.326146 -112.156748)
		(end 242.135406 -104.966008)
		(width 0.254)
		(layer "In6.Cu")
		(net "P12V_OCP_SFF_ISENSE_MPS_TIC")
	)
	(segment
		(start 256.97688 -112.156748)
		(end 249.326146 -112.156748)
		(width 0.254)
		(layer "In6.Cu")
		(net "P12V_OCP_SFF_ISENSE_MPS_TIC")
	)
	(segment
		(start 222.053404 -108.4326)
		(end 212.274912 -108.4326)
		(width 0.254)
		(layer "In6.Cu")
		(net "P12V_OCP_SFF_ISENSE_MPS_TIC")
	)
	(segment
		(start 337.364578 -114.767868)
		(end 325.212456 -114.767868)
		(width 0.254)
		(layer "In6.Cu")
		(net "P12V_OCP_SFF_ISENSE_MPS_TIC")
	)
	(segment
		(start 169.4942 -90.7034)
		(end 167.868092 -92.329508)
		(width 0.254)
		(layer "In6.Cu")
		(net "P12V_OCP_SFF_ISENSE_MPS_TIC")
	)
	(segment
		(start 340.38286 -111.749586)
		(end 337.364578 -114.767868)
		(width 0.254)
		(layer "In6.Cu")
		(net "P12V_OCP_SFF_ISENSE_MPS_TIC")
	)
	(segment
		(start 340.28888 -108.430568)
		(end 340.38286 -108.524548)
		(width 0.254)
		(layer "In6.Cu")
		(net "P12V_OCP_SFF_ISENSE_MPS_TIC")
	)
	(segment
		(start 208.86928 -106.32186)
		(end 203.07935 -100.53193)
		(width 0.254)
		(layer "In6.Cu")
		(net "P12V_OCP_SFF_ISENSE_MPS_TIC")
	)
	(segment
		(start 64.637158 -95.547688)
		(end 40.15994 -95.547688)
		(width 0.254)
		(layer "In6.Cu")
		(net "P12V_OCP_SFF_ISENSE_MPS_TIC")
	)
	(segment
		(start 212.274912 -108.4326)
		(end 210.164172 -106.32186)
		(width 0.254)
		(layer "In6.Cu")
		(net "P12V_OCP_SFF_ISENSE_MPS_TIC")
	)
	(segment
		(start 152.512014 -92.329508)
		(end 147.266914 -87.084408)
		(width 0.254)
		(layer "In6.Cu")
		(net "P12V_OCP_SFF_ISENSE_MPS_TIC")
	)
	(segment
		(start 181.1528 -90.7034)
		(end 169.4942 -90.7034)
		(width 0.254)
		(layer "In6.Cu")
		(net "P12V_OCP_SFF_ISENSE_MPS_TIC")
	)
	(segment
		(start 203.07935 -100.53193)
		(end 203.07935 -99.000818)
		(width 0.254)
		(layer "In6.Cu")
		(net "P12V_OCP_SFF_ISENSE_MPS_TIC")
	)
	(segment
		(start 318.842136 -108.397548)
		(end 261.95528 -108.397548)
		(width 0.254)
		(layer "In6.Cu")
		(net "P12V_OCP_SFF_ISENSE_MPS_TIC")
	)
	(segment
		(start 103.01224 -79.037688)
		(end 81.147158 -79.037688)
		(width 0.254)
		(layer "In6.Cu")
		(net "P12V_OCP_SFF_ISENSE_MPS_TIC")
	)
	(segment
		(start 325.212456 -114.767868)
		(end 318.842136 -108.397548)
		(width 0.254)
		(layer "In6.Cu")
		(net "P12V_OCP_SFF_ISENSE_MPS_TIC")
	)
	(segment
		(start 261.95528 -108.397548)
		(end 261.54888 -108.803948)
		(width 0.254)
		(layer "In6.Cu")
		(net "P12V_OCP_SFF_ISENSE_MPS_TIC")
	)
	(segment
		(start 437.240172 -34.373058)
		(end 437.240172 -32.573468)
		(width 0.254)
		(layer "F.Cu")
		(net "P12V_OCP_SFF_ISENSE_MPS_MAM")
	)
	(segment
		(start 29.732478 -99.586034)
		(end 30.342078 -99.586034)
		(width 0.12954)
		(layer "F.Cu")
		(net "P12V_OCP_SFF_ISENSE_MPS_MAM")
	)
	(via
		(at 340.92388 -107.483148)
		(size 0.508)
		(drill 0.254)
		(layers "F.Cu" "B.Cu")
		(net "P12V_OCP_SFF_ISENSE_MPS_MAM")
	)
	(via
		(at 30.342078 -99.586034)
		(size 0.508)
		(drill 0.254)
		(layers "F.Cu" "B.Cu")
		(net "P12V_OCP_SFF_ISENSE_MPS_MAM")
	)
	(via
		(at 437.240172 -34.373058)
		(size 0.508)
		(drill 0.254)
		(layers "F.Cu" "B.Cu")
		(net "P12V_OCP_SFF_ISENSE_MPS_MAM")
	)
	(segment
		(start 342.718136 -104.765348)
		(end 340.92388 -106.559604)
		(width 0.254)
		(layer "B.Cu")
		(net "P12V_OCP_SFF_ISENSE_MPS_MAM")
	)
	(segment
		(start 437.240172 -34.373058)
		(end 437.240172 -38.847014)
		(width 0.254)
		(layer "B.Cu")
		(net "P12V_OCP_SFF_ISENSE_MPS_MAM")
	)
	(segment
		(start 385.622292 -109.551724)
		(end 381.432308 -113.741708)
		(width 0.254)
		(layer "B.Cu")
		(net "P12V_OCP_SFF_ISENSE_MPS_MAM")
	)
	(segment
		(start 340.92388 -106.559604)
		(end 340.92388 -107.483148)
		(width 0.254)
		(layer "B.Cu")
		(net "P12V_OCP_SFF_ISENSE_MPS_MAM")
	)
	(segment
		(start 354.744528 -104.765348)
		(end 342.718136 -104.765348)
		(width 0.254)
		(layer "B.Cu")
		(net "P12V_OCP_SFF_ISENSE_MPS_MAM")
	)
	(segment
		(start 428.579026 -84.753196)
		(end 404.686008 -84.753196)
		(width 0.254)
		(layer "B.Cu")
		(net "P12V_OCP_SFF_ISENSE_MPS_MAM")
	)
	(segment
		(start 385.622292 -103.816912)
		(end 385.622292 -109.551724)
		(width 0.254)
		(layer "B.Cu")
		(net "P12V_OCP_SFF_ISENSE_MPS_MAM")
	)
	(segment
		(start 436.45328 -51.132994)
		(end 436.45328 -57.270396)
		(width 0.254)
		(layer "B.Cu")
		(net "P12V_OCP_SFF_ISENSE_MPS_MAM")
	)
	(segment
		(start 435.419754 -77.912468)
		(end 428.579026 -84.753196)
		(width 0.254)
		(layer "B.Cu")
		(net "P12V_OCP_SFF_ISENSE_MPS_MAM")
	)
	(segment
		(start 435.419754 -58.303922)
		(end 435.419754 -77.912468)
		(width 0.254)
		(layer "B.Cu")
		(net "P12V_OCP_SFF_ISENSE_MPS_MAM")
	)
	(segment
		(start 439.58764 -41.194482)
		(end 439.58764 -47.998634)
		(width 0.254)
		(layer "B.Cu")
		(net "P12V_OCP_SFF_ISENSE_MPS_MAM")
	)
	(segment
		(start 404.686008 -84.753196)
		(end 385.622292 -103.816912)
		(width 0.254)
		(layer "B.Cu")
		(net "P12V_OCP_SFF_ISENSE_MPS_MAM")
	)
	(segment
		(start 439.58764 -47.998634)
		(end 436.45328 -51.132994)
		(width 0.254)
		(layer "B.Cu")
		(net "P12V_OCP_SFF_ISENSE_MPS_MAM")
	)
	(segment
		(start 381.432308 -113.741708)
		(end 363.720888 -113.741708)
		(width 0.254)
		(layer "B.Cu")
		(net "P12V_OCP_SFF_ISENSE_MPS_MAM")
	)
	(segment
		(start 437.240172 -38.847014)
		(end 439.58764 -41.194482)
		(width 0.254)
		(layer "B.Cu")
		(net "P12V_OCP_SFF_ISENSE_MPS_MAM")
	)
	(segment
		(start 436.45328 -57.270396)
		(end 435.419754 -58.303922)
		(width 0.254)
		(layer "B.Cu")
		(net "P12V_OCP_SFF_ISENSE_MPS_MAM")
	)
	(segment
		(start 363.720888 -113.741708)
		(end 354.744528 -104.765348)
		(width 0.254)
		(layer "B.Cu")
		(net "P12V_OCP_SFF_ISENSE_MPS_MAM")
	)
	(segment
		(start 30.342078 -99.586034)
		(end 30.342078 -100.802948)
		(width 0.254)
		(layer "In6.Cu")
		(net "P12V_OCP_SFF_ISENSE_MPS_MAM")
	)
	(segment
		(start 150.946866 -92.786708)
		(end 171.017692 -92.786708)
		(width 0.254)
		(layer "In6.Cu")
		(net "P12V_OCP_SFF_ISENSE_MPS_MAM")
	)
	(segment
		(start 64.873886 -96.119188)
		(end 76.801726 -84.191348)
		(width 0.254)
		(layer "In6.Cu")
		(net "P12V_OCP_SFF_ISENSE_MPS_MAM")
	)
	(segment
		(start 37.77488 -99.512628)
		(end 40.44188 -96.845628)
		(width 0.254)
		(layer "In6.Cu")
		(net "P12V_OCP_SFF_ISENSE_MPS_MAM")
	)
	(segment
		(start 337.601306 -115.339368)
		(end 340.95436 -111.986314)
		(width 0.254)
		(layer "In6.Cu")
		(net "P12V_OCP_SFF_ISENSE_MPS_MAM")
	)
	(segment
		(start 181.229 -92.65158)
		(end 182.04942 -93.472)
		(width 0.254)
		(layer "In6.Cu")
		(net "P12V_OCP_SFF_ISENSE_MPS_MAM")
	)
	(segment
		(start 145.813526 -87.653368)
		(end 150.946866 -92.786708)
		(width 0.254)
		(layer "In6.Cu")
		(net "P12V_OCP_SFF_ISENSE_MPS_MAM")
	)
	(segment
		(start 30.342078 -100.802948)
		(end 32.247078 -102.707948)
		(width 0.254)
		(layer "In6.Cu")
		(net "P12V_OCP_SFF_ISENSE_MPS_MAM")
	)
	(segment
		(start 180.5432 -91.2622)
		(end 181.229 -91.948)
		(width 0.254)
		(layer "In6.Cu")
		(net "P12V_OCP_SFF_ISENSE_MPS_MAM")
	)
	(segment
		(start 218.44 -109.22)
		(end 218.6686 -108.9914)
		(width 0.254)
		(layer "In6.Cu")
		(net "P12V_OCP_SFF_ISENSE_MPS_MAM")
	)
	(segment
		(start 241.859816 -105.428288)
		(end 249.045476 -112.613948)
		(width 0.254)
		(layer "In6.Cu")
		(net "P12V_OCP_SFF_ISENSE_MPS_MAM")
	)
	(segment
		(start 222.302832 -108.9914)
		(end 225.865944 -105.428288)
		(width 0.254)
		(layer "In6.Cu")
		(net "P12V_OCP_SFF_ISENSE_MPS_MAM")
	)
	(segment
		(start 264.057892 -109.116368)
		(end 318.63792 -109.116368)
		(width 0.254)
		(layer "In6.Cu")
		(net "P12V_OCP_SFF_ISENSE_MPS_MAM")
	)
	(segment
		(start 46.25594 -96.845628)
		(end 46.98238 -96.119188)
		(width 0.254)
		(layer "In6.Cu")
		(net "P12V_OCP_SFF_ISENSE_MPS_MAM")
	)
	(segment
		(start 207.764888 -105.893108)
		(end 207.764888 -106.977688)
		(width 0.254)
		(layer "In6.Cu")
		(net "P12V_OCP_SFF_ISENSE_MPS_MAM")
	)
	(segment
		(start 207.764888 -106.977688)
		(end 210.0072 -109.22)
		(width 0.254)
		(layer "In6.Cu")
		(net "P12V_OCP_SFF_ISENSE_MPS_MAM")
	)
	(segment
		(start 111.02848 -87.653368)
		(end 145.813526 -87.653368)
		(width 0.254)
		(layer "In6.Cu")
		(net "P12V_OCP_SFF_ISENSE_MPS_MAM")
	)
	(segment
		(start 191.887348 -97.450148)
		(end 200.881996 -97.450148)
		(width 0.254)
		(layer "In6.Cu")
		(net "P12V_OCP_SFF_ISENSE_MPS_MAM")
	)
	(segment
		(start 200.881996 -97.450148)
		(end 201.47788 -98.046032)
		(width 0.254)
		(layer "In6.Cu")
		(net "P12V_OCP_SFF_ISENSE_MPS_MAM")
	)
	(segment
		(start 249.045476 -112.613948)
		(end 260.560312 -112.613948)
		(width 0.254)
		(layer "In6.Cu")
		(net "P12V_OCP_SFF_ISENSE_MPS_MAM")
	)
	(segment
		(start 46.98238 -96.119188)
		(end 64.873886 -96.119188)
		(width 0.254)
		(layer "In6.Cu")
		(net "P12V_OCP_SFF_ISENSE_MPS_MAM")
	)
	(segment
		(start 225.865944 -105.428288)
		(end 241.859816 -105.428288)
		(width 0.254)
		(layer "In6.Cu")
		(net "P12V_OCP_SFF_ISENSE_MPS_MAM")
	)
	(segment
		(start 340.92388 -107.978448)
		(end 340.92388 -107.483148)
		(width 0.254)
		(layer "In6.Cu")
		(net "P12V_OCP_SFF_ISENSE_MPS_MAM")
	)
	(segment
		(start 171.017692 -92.786708)
		(end 172.5422 -91.2622)
		(width 0.254)
		(layer "In6.Cu")
		(net "P12V_OCP_SFF_ISENSE_MPS_MAM")
	)
	(segment
		(start 172.5422 -91.2622)
		(end 180.5432 -91.2622)
		(width 0.254)
		(layer "In6.Cu")
		(net "P12V_OCP_SFF_ISENSE_MPS_MAM")
	)
	(segment
		(start 340.95436 -108.008928)
		(end 340.92388 -107.978448)
		(width 0.254)
		(layer "In6.Cu")
		(net "P12V_OCP_SFF_ISENSE_MPS_MAM")
	)
	(segment
		(start 210.0072 -109.22)
		(end 218.44 -109.22)
		(width 0.254)
		(layer "In6.Cu")
		(net "P12V_OCP_SFF_ISENSE_MPS_MAM")
	)
	(segment
		(start 109.87278 -85.875368)
		(end 109.87278 -86.497668)
		(width 0.254)
		(layer "In6.Cu")
		(net "P12V_OCP_SFF_ISENSE_MPS_MAM")
	)
	(segment
		(start 109.87278 -86.497668)
		(end 111.02848 -87.653368)
		(width 0.254)
		(layer "In6.Cu")
		(net "P12V_OCP_SFF_ISENSE_MPS_MAM")
	)
	(segment
		(start 182.04942 -93.472)
		(end 187.9092 -93.472)
		(width 0.254)
		(layer "In6.Cu")
		(net "P12V_OCP_SFF_ISENSE_MPS_MAM")
	)
	(segment
		(start 324.86092 -115.339368)
		(end 337.601306 -115.339368)
		(width 0.254)
		(layer "In6.Cu")
		(net "P12V_OCP_SFF_ISENSE_MPS_MAM")
	)
	(segment
		(start 201.47788 -100.167948)
		(end 201.88301 -100.573078)
		(width 0.254)
		(layer "In6.Cu")
		(net "P12V_OCP_SFF_ISENSE_MPS_MAM")
	)
	(segment
		(start 260.560312 -112.613948)
		(end 264.057892 -109.116368)
		(width 0.254)
		(layer "In6.Cu")
		(net "P12V_OCP_SFF_ISENSE_MPS_MAM")
	)
	(segment
		(start 32.247078 -102.707948)
		(end 37.01288 -102.707948)
		(width 0.254)
		(layer "In6.Cu")
		(net "P12V_OCP_SFF_ISENSE_MPS_MAM")
	)
	(segment
		(start 40.44188 -96.845628)
		(end 46.25594 -96.845628)
		(width 0.254)
		(layer "In6.Cu")
		(net "P12V_OCP_SFF_ISENSE_MPS_MAM")
	)
	(segment
		(start 202.444858 -100.573078)
		(end 207.764888 -105.893108)
		(width 0.254)
		(layer "In6.Cu")
		(net "P12V_OCP_SFF_ISENSE_MPS_MAM")
	)
	(segment
		(start 108.18876 -84.191348)
		(end 109.87278 -85.875368)
		(width 0.254)
		(layer "In6.Cu")
		(net "P12V_OCP_SFF_ISENSE_MPS_MAM")
	)
	(segment
		(start 187.9092 -93.472)
		(end 191.887348 -97.450148)
		(width 0.254)
		(layer "In6.Cu")
		(net "P12V_OCP_SFF_ISENSE_MPS_MAM")
	)
	(segment
		(start 201.88301 -100.573078)
		(end 202.444858 -100.573078)
		(width 0.254)
		(layer "In6.Cu")
		(net "P12V_OCP_SFF_ISENSE_MPS_MAM")
	)
	(segment
		(start 201.47788 -98.046032)
		(end 201.47788 -100.167948)
		(width 0.254)
		(layer "In6.Cu")
		(net "P12V_OCP_SFF_ISENSE_MPS_MAM")
	)
	(segment
		(start 76.801726 -84.191348)
		(end 108.18876 -84.191348)
		(width 0.254)
		(layer "In6.Cu")
		(net "P12V_OCP_SFF_ISENSE_MPS_MAM")
	)
	(segment
		(start 218.6686 -108.9914)
		(end 222.302832 -108.9914)
		(width 0.254)
		(layer "In6.Cu")
		(net "P12V_OCP_SFF_ISENSE_MPS_MAM")
	)
	(segment
		(start 181.229 -91.948)
		(end 181.229 -92.65158)
		(width 0.254)
		(layer "In6.Cu")
		(net "P12V_OCP_SFF_ISENSE_MPS_MAM")
	)
	(segment
		(start 37.01288 -102.707948)
		(end 37.77488 -101.945948)
		(width 0.254)
		(layer "In6.Cu")
		(net "P12V_OCP_SFF_ISENSE_MPS_MAM")
	)
	(segment
		(start 37.77488 -101.945948)
		(end 37.77488 -99.512628)
		(width 0.254)
		(layer "In6.Cu")
		(net "P12V_OCP_SFF_ISENSE_MPS_MAM")
	)
	(segment
		(start 340.95436 -111.986314)
		(end 340.95436 -108.008928)
		(width 0.254)
		(layer "In6.Cu")
		(net "P12V_OCP_SFF_ISENSE_MPS_MAM")
	)
	(segment
		(start 318.63792 -109.116368)
		(end 324.86092 -115.339368)
		(width 0.254)
		(layer "In6.Cu")
		(net "P12V_OCP_SFF_ISENSE_MPS_MAM")
	)
	(segment
		(start 41.027604 -111.606838)
		(end 41.637204 -111.606838)
		(width 0.12954)
		(layer "F.Cu")
		(net "P12V_OCP_SFF_ISENSE_MAM_TIC")
	)
	(segment
		(start 434.408072 -32.573468)
		(end 434.408072 -34.177732)
		(width 0.254)
		(layer "F.Cu")
		(net "P12V_OCP_SFF_ISENSE_MAM_TIC")
	)
	(segment
		(start 434.408072 -34.177732)
		(end 436.15356 -35.92322)
		(width 0.254)
		(layer "F.Cu")
		(net "P12V_OCP_SFF_ISENSE_MAM_TIC")
	)
	(segment
		(start 436.15356 -35.92322)
		(end 436.15356 -37.82314)
		(width 0.254)
		(layer "F.Cu")
		(net "P12V_OCP_SFF_ISENSE_MAM_TIC")
	)
	(via
		(at 39.17188 -95.423228)
		(size 0.508)
		(drill 0.254)
		(layers "F.Cu" "B.Cu")
		(net "P12V_OCP_SFF_ISENSE_MAM_TIC")
	)
	(via
		(at 41.637204 -111.606838)
		(size 0.508)
		(drill 0.254)
		(layers "F.Cu" "B.Cu")
		(net "P12V_OCP_SFF_ISENSE_MAM_TIC")
	)
	(via
		(at 436.15356 -37.82314)
		(size 0.508)
		(drill 0.254)
		(layers "F.Cu" "B.Cu")
		(net "P12V_OCP_SFF_ISENSE_MAM_TIC")
	)
	(via
		(at 339.65388 -107.483148)
		(size 0.508)
		(drill 0.254)
		(layers "F.Cu" "B.Cu")
		(net "P12V_OCP_SFF_ISENSE_MAM_TIC")
	)
	(segment
		(start 380.90602 -112.471708)
		(end 364.247176 -112.471708)
		(width 0.254)
		(layer "B.Cu")
		(net "P12V_OCP_SFF_ISENSE_MAM_TIC")
	)
	(segment
		(start 364.247176 -112.471708)
		(end 355.270816 -103.495348)
		(width 0.254)
		(layer "B.Cu")
		(net "P12V_OCP_SFF_ISENSE_MAM_TIC")
	)
	(segment
		(start 433.385468 -58.54192)
		(end 433.385468 -76.72578)
		(width 0.254)
		(layer "B.Cu")
		(net "P12V_OCP_SFF_ISENSE_MAM_TIC")
	)
	(segment
		(start 436.26024 -48.028606)
		(end 436.26024 -49.62652)
		(width 0.254)
		(layer "B.Cu")
		(net "P12V_OCP_SFF_ISENSE_MAM_TIC")
	)
	(segment
		(start 355.270816 -103.495348)
		(end 342.191848 -103.495348)
		(width 0.254)
		(layer "B.Cu")
		(net "P12V_OCP_SFF_ISENSE_MAM_TIC")
	)
	(segment
		(start 40.2844 -105.877868)
		(end 39.17188 -104.765348)
		(width 0.254)
		(layer "B.Cu")
		(net "P12V_OCP_SFF_ISENSE_MAM_TIC")
	)
	(segment
		(start 435.18328 -56.744108)
		(end 433.385468 -58.54192)
		(width 0.254)
		(layer "B.Cu")
		(net "P12V_OCP_SFF_ISENSE_MAM_TIC")
	)
	(segment
		(start 384.352292 -103.290624)
		(end 384.352292 -109.025436)
		(width 0.254)
		(layer "B.Cu")
		(net "P12V_OCP_SFF_ISENSE_MAM_TIC")
	)
	(segment
		(start 41.637204 -111.606838)
		(end 40.2844 -110.254034)
		(width 0.254)
		(layer "B.Cu")
		(net "P12V_OCP_SFF_ISENSE_MAM_TIC")
	)
	(segment
		(start 436.26024 -49.62652)
		(end 435.18328 -50.70348)
		(width 0.254)
		(layer "B.Cu")
		(net "P12V_OCP_SFF_ISENSE_MAM_TIC")
	)
	(segment
		(start 436.15356 -37.82314)
		(end 436.15356 -39.103808)
		(width 0.254)
		(layer "B.Cu")
		(net "P12V_OCP_SFF_ISENSE_MAM_TIC")
	)
	(segment
		(start 437.56326 -40.513508)
		(end 437.56326 -42.63898)
		(width 0.254)
		(layer "B.Cu")
		(net "P12V_OCP_SFF_ISENSE_MAM_TIC")
	)
	(segment
		(start 437.06542 -43.13682)
		(end 437.06542 -47.223426)
		(width 0.254)
		(layer "B.Cu")
		(net "P12V_OCP_SFF_ISENSE_MAM_TIC")
	)
	(segment
		(start 437.06542 -47.223426)
		(end 436.26024 -48.028606)
		(width 0.254)
		(layer "B.Cu")
		(net "P12V_OCP_SFF_ISENSE_MAM_TIC")
	)
	(segment
		(start 436.15356 -39.103808)
		(end 437.56326 -40.513508)
		(width 0.254)
		(layer "B.Cu")
		(net "P12V_OCP_SFF_ISENSE_MAM_TIC")
	)
	(segment
		(start 339.65388 -106.033316)
		(end 339.65388 -107.483148)
		(width 0.254)
		(layer "B.Cu")
		(net "P12V_OCP_SFF_ISENSE_MAM_TIC")
	)
	(segment
		(start 405.765254 -81.877662)
		(end 384.352292 -103.290624)
		(width 0.254)
		(layer "B.Cu")
		(net "P12V_OCP_SFF_ISENSE_MAM_TIC")
	)
	(segment
		(start 39.17188 -104.765348)
		(end 39.17188 -95.423228)
		(width 0.254)
		(layer "B.Cu")
		(net "P12V_OCP_SFF_ISENSE_MAM_TIC")
	)
	(segment
		(start 433.385468 -76.72578)
		(end 428.233586 -81.877662)
		(width 0.254)
		(layer "B.Cu")
		(net "P12V_OCP_SFF_ISENSE_MAM_TIC")
	)
	(segment
		(start 437.56326 -42.63898)
		(end 437.06542 -43.13682)
		(width 0.254)
		(layer "B.Cu")
		(net "P12V_OCP_SFF_ISENSE_MAM_TIC")
	)
	(segment
		(start 435.18328 -50.70348)
		(end 435.18328 -56.744108)
		(width 0.254)
		(layer "B.Cu")
		(net "P12V_OCP_SFF_ISENSE_MAM_TIC")
	)
	(segment
		(start 342.191848 -103.495348)
		(end 339.65388 -106.033316)
		(width 0.254)
		(layer "B.Cu")
		(net "P12V_OCP_SFF_ISENSE_MAM_TIC")
	)
	(segment
		(start 384.352292 -109.025436)
		(end 380.90602 -112.471708)
		(width 0.254)
		(layer "B.Cu")
		(net "P12V_OCP_SFF_ISENSE_MAM_TIC")
	)
	(segment
		(start 428.233586 -81.877662)
		(end 405.765254 -81.877662)
		(width 0.254)
		(layer "B.Cu")
		(net "P12V_OCP_SFF_ISENSE_MAM_TIC")
	)
	(segment
		(start 40.2844 -110.254034)
		(end 40.2844 -105.877868)
		(width 0.254)
		(layer "B.Cu")
		(net "P12V_OCP_SFF_ISENSE_MAM_TIC")
	)
	(segment
		(start 208.802986 -103.954834)
		(end 208.802986 -105.353866)
		(width 0.254)
		(layer "In6.Cu")
		(net "P12V_OCP_SFF_ISENSE_MAM_TIC")
	)
	(segment
		(start 188.7474 -91.5162)
		(end 193.766948 -96.535748)
		(width 0.254)
		(layer "In6.Cu")
		(net "P12V_OCP_SFF_ISENSE_MAM_TIC")
	)
	(segment
		(start 108.9406 -82.923888)
		(end 111.2901 -85.273388)
		(width 0.254)
		(layer "In6.Cu")
		(net "P12V_OCP_SFF_ISENSE_MAM_TIC")
	)
	(segment
		(start 122.7328 -86.261448)
		(end 138.25982 -86.261448)
		(width 0.254)
		(layer "In6.Cu")
		(net "P12V_OCP_SFF_ISENSE_MAM_TIC")
	)
	(segment
		(start 146.588226 -85.641688)
		(end 150.024846 -89.078308)
		(width 0.254)
		(layer "In6.Cu")
		(net "P12V_OCP_SFF_ISENSE_MAM_TIC")
	)
	(segment
		(start 193.766948 -96.535748)
		(end 201.3839 -96.535748)
		(width 0.254)
		(layer "In6.Cu")
		(net "P12V_OCP_SFF_ISENSE_MAM_TIC")
	)
	(segment
		(start 325.45782 -114.163348)
		(end 337.114134 -114.163348)
		(width 0.254)
		(layer "In6.Cu")
		(net "P12V_OCP_SFF_ISENSE_MAM_TIC")
	)
	(segment
		(start 260.12648 -107.940348)
		(end 319.23482 -107.940348)
		(width 0.254)
		(layer "In6.Cu")
		(net "P12V_OCP_SFF_ISENSE_MAM_TIC")
	)
	(segment
		(start 208.802986 -105.353866)
		(end 209.13598 -105.68686)
		(width 0.254)
		(layer "In6.Cu")
		(net "P12V_OCP_SFF_ISENSE_MAM_TIC")
	)
	(segment
		(start 212.485732 -107.8484)
		(end 221.78264 -107.8484)
		(width 0.254)
		(layer "In6.Cu")
		(net "P12V_OCP_SFF_ISENSE_MAM_TIC")
	)
	(segment
		(start 249.51563 -111.699548)
		(end 253.70028 -111.699548)
		(width 0.254)
		(layer "In6.Cu")
		(net "P12V_OCP_SFF_ISENSE_MAM_TIC")
	)
	(segment
		(start 138.87958 -85.641688)
		(end 146.588226 -85.641688)
		(width 0.254)
		(layer "In6.Cu")
		(net "P12V_OCP_SFF_ISENSE_MAM_TIC")
	)
	(segment
		(start 339.65388 -108.806488)
		(end 339.65388 -107.483148)
		(width 0.254)
		(layer "In6.Cu")
		(net "P12V_OCP_SFF_ISENSE_MAM_TIC")
	)
	(segment
		(start 209.13598 -105.68686)
		(end 210.324192 -105.68686)
		(width 0.254)
		(layer "In6.Cu")
		(net "P12V_OCP_SFF_ISENSE_MAM_TIC")
	)
	(segment
		(start 122.49912 -86.068408)
		(end 122.53976 -86.068408)
		(width 0.254)
		(layer "In6.Cu")
		(net "P12V_OCP_SFF_ISENSE_MAM_TIC")
	)
	(segment
		(start 259.54228 -108.524548)
		(end 260.12648 -107.940348)
		(width 0.254)
		(layer "In6.Cu")
		(net "P12V_OCP_SFF_ISENSE_MAM_TIC")
	)
	(segment
		(start 111.2901 -85.273388)
		(end 121.7041 -85.273388)
		(width 0.254)
		(layer "In6.Cu")
		(net "P12V_OCP_SFF_ISENSE_MAM_TIC")
	)
	(segment
		(start 103.4796 -78.522068)
		(end 107.88142 -82.923888)
		(width 0.254)
		(layer "In6.Cu")
		(net "P12V_OCP_SFF_ISENSE_MAM_TIC")
	)
	(segment
		(start 221.78264 -107.8484)
		(end 225.165412 -104.465628)
		(width 0.254)
		(layer "In6.Cu")
		(net "P12V_OCP_SFF_ISENSE_MAM_TIC")
	)
	(segment
		(start 80.807814 -78.522068)
		(end 103.4796 -78.522068)
		(width 0.254)
		(layer "In6.Cu")
		(net "P12V_OCP_SFF_ISENSE_MAM_TIC")
	)
	(segment
		(start 64.386714 -94.943168)
		(end 80.807814 -78.522068)
		(width 0.254)
		(layer "In6.Cu")
		(net "P12V_OCP_SFF_ISENSE_MAM_TIC")
	)
	(segment
		(start 39.17188 -95.423228)
		(end 39.65194 -94.943168)
		(width 0.254)
		(layer "In6.Cu")
		(net "P12V_OCP_SFF_ISENSE_MAM_TIC")
	)
	(segment
		(start 339.77834 -108.930948)
		(end 339.65388 -108.806488)
		(width 0.254)
		(layer "In6.Cu")
		(net "P12V_OCP_SFF_ISENSE_MAM_TIC")
	)
	(segment
		(start 253.70028 -111.699548)
		(end 256.87528 -108.524548)
		(width 0.254)
		(layer "In6.Cu")
		(net "P12V_OCP_SFF_ISENSE_MAM_TIC")
	)
	(segment
		(start 242.28171 -104.465628)
		(end 249.51563 -111.699548)
		(width 0.254)
		(layer "In6.Cu")
		(net "P12V_OCP_SFF_ISENSE_MAM_TIC")
	)
	(segment
		(start 107.88142 -82.923888)
		(end 108.9406 -82.923888)
		(width 0.254)
		(layer "In6.Cu")
		(net "P12V_OCP_SFF_ISENSE_MAM_TIC")
	)
	(segment
		(start 122.53976 -86.068408)
		(end 122.7328 -86.261448)
		(width 0.254)
		(layer "In6.Cu")
		(net "P12V_OCP_SFF_ISENSE_MAM_TIC")
	)
	(segment
		(start 180.289708 -89.078308)
		(end 182.7276 -91.5162)
		(width 0.254)
		(layer "In6.Cu")
		(net "P12V_OCP_SFF_ISENSE_MAM_TIC")
	)
	(segment
		(start 210.324192 -105.68686)
		(end 212.485732 -107.8484)
		(width 0.254)
		(layer "In6.Cu")
		(net "P12V_OCP_SFF_ISENSE_MAM_TIC")
	)
	(segment
		(start 319.23482 -107.940348)
		(end 325.45782 -114.163348)
		(width 0.254)
		(layer "In6.Cu")
		(net "P12V_OCP_SFF_ISENSE_MAM_TIC")
	)
	(segment
		(start 201.3839 -96.535748)
		(end 208.802986 -103.954834)
		(width 0.254)
		(layer "In6.Cu")
		(net "P12V_OCP_SFF_ISENSE_MAM_TIC")
	)
	(segment
		(start 138.25982 -86.261448)
		(end 138.87958 -85.641688)
		(width 0.254)
		(layer "In6.Cu")
		(net "P12V_OCP_SFF_ISENSE_MAM_TIC")
	)
	(segment
		(start 225.165412 -104.465628)
		(end 242.28171 -104.465628)
		(width 0.254)
		(layer "In6.Cu")
		(net "P12V_OCP_SFF_ISENSE_MAM_TIC")
	)
	(segment
		(start 121.7041 -85.273388)
		(end 122.49912 -86.068408)
		(width 0.254)
		(layer "In6.Cu")
		(net "P12V_OCP_SFF_ISENSE_MAM_TIC")
	)
	(segment
		(start 39.65194 -94.943168)
		(end 64.386714 -94.943168)
		(width 0.254)
		(layer "In6.Cu")
		(net "P12V_OCP_SFF_ISENSE_MAM_TIC")
	)
	(segment
		(start 339.77834 -111.499142)
		(end 339.77834 -108.930948)
		(width 0.254)
		(layer "In6.Cu")
		(net "P12V_OCP_SFF_ISENSE_MAM_TIC")
	)
	(segment
		(start 256.87528 -108.524548)
		(end 259.54228 -108.524548)
		(width 0.254)
		(layer "In6.Cu")
		(net "P12V_OCP_SFF_ISENSE_MAM_TIC")
	)
	(segment
		(start 150.024846 -89.078308)
		(end 180.289708 -89.078308)
		(width 0.254)
		(layer "In6.Cu")
		(net "P12V_OCP_SFF_ISENSE_MAM_TIC")
	)
	(segment
		(start 337.114134 -114.163348)
		(end 339.77834 -111.499142)
		(width 0.254)
		(layer "In6.Cu")
		(net "P12V_OCP_SFF_ISENSE_MAM_TIC")
	)
	(segment
		(start 182.7276 -91.5162)
		(end 188.7474 -91.5162)
		(width 0.254)
		(layer "In6.Cu")
		(net "P12V_OCP_SFF_ISENSE_MAM_TIC")
	)
	(segment
		(start 437.124348 -38.55974)
		(end 437.81218 -37.871908)
		(width 0.254)
		(layer "F.Cu")
		(net "P12V_OCP_SFF_ISENSE_MAM_MAM")
	)
	(segment
		(start 28.132278 -99.586034)
		(end 27.607514 -99.586034)
		(width 0.254)
		(layer "F.Cu")
		(net "P12V_OCP_SFF_ISENSE_MAM_MAM")
	)
	(segment
		(start 434.05806 -36.685728)
		(end 434.05806 -37.88156)
		(width 0.254)
		(layer "F.Cu")
		(net "P12V_OCP_SFF_ISENSE_MAM_MAM")
	)
	(segment
		(start 27.607514 -99.586034)
		(end 27.2288 -99.964748)
		(width 0.254)
		(layer "F.Cu")
		(net "P12V_OCP_SFF_ISENSE_MAM_MAM")
	)
	(segment
		(start 434.05806 -37.88156)
		(end 434.73624 -38.55974)
		(width 0.254)
		(layer "F.Cu")
		(net "P12V_OCP_SFF_ISENSE_MAM_MAM")
	)
	(segment
		(start 433.82946 -31.773368)
		(end 433.10048 -32.502348)
		(width 0.254)
		(layer "F.Cu")
		(net "P12V_OCP_SFF_ISENSE_MAM_MAM")
	)
	(segment
		(start 433.10048 -35.728148)
		(end 434.05806 -36.685728)
		(width 0.254)
		(layer "F.Cu")
		(net "P12V_OCP_SFF_ISENSE_MAM_MAM")
	)
	(segment
		(start 434.73624 -38.55974)
		(end 437.124348 -38.55974)
		(width 0.254)
		(layer "F.Cu")
		(net "P12V_OCP_SFF_ISENSE_MAM_MAM")
	)
	(segment
		(start 433.10048 -32.502348)
		(end 433.10048 -35.728148)
		(width 0.254)
		(layer "F.Cu")
		(net "P12V_OCP_SFF_ISENSE_MAM_MAM")
	)
	(segment
		(start 435.208172 -31.773368)
		(end 433.82946 -31.773368)
		(width 0.254)
		(layer "F.Cu")
		(net "P12V_OCP_SFF_ISENSE_MAM_MAM")
	)
	(via
		(at 341.55888 -107.483148)
		(size 0.508)
		(drill 0.254)
		(layers "F.Cu" "B.Cu")
		(net "P12V_OCP_SFF_ISENSE_MAM_MAM")
	)
	(via
		(at 27.2288 -99.964748)
		(size 0.508)
		(drill 0.254)
		(layers "F.Cu" "B.Cu")
		(net "P12V_OCP_SFF_ISENSE_MAM_MAM")
	)
	(via
		(at 437.81218 -37.871908)
		(size 0.508)
		(drill 0.254)
		(layers "F.Cu" "B.Cu")
		(net "P12V_OCP_SFF_ISENSE_MAM_MAM")
	)
	(segment
		(start 341.55888 -106.822748)
		(end 341.55888 -107.483148)
		(width 0.254)
		(layer "B.Cu")
		(net "P12V_OCP_SFF_ISENSE_MAM_MAM")
	)
	(segment
		(start 440.06516 -48.359822)
		(end 437.228742 -51.19624)
		(width 0.254)
		(layer "B.Cu")
		(net "P12V_OCP_SFF_ISENSE_MAM_MAM")
	)
	(segment
		(start 386.257292 -104.080056)
		(end 386.257292 -109.814868)
		(width 0.254)
		(layer "B.Cu")
		(net "P12V_OCP_SFF_ISENSE_MAM_MAM")
	)
	(segment
		(start 381.695452 -114.376708)
		(end 363.457744 -114.376708)
		(width 0.254)
		(layer "B.Cu")
		(net "P12V_OCP_SFF_ISENSE_MAM_MAM")
	)
	(segment
		(start 386.257292 -109.814868)
		(end 381.695452 -114.376708)
		(width 0.254)
		(layer "B.Cu")
		(net "P12V_OCP_SFF_ISENSE_MAM_MAM")
	)
	(segment
		(start 404.627334 -85.710014)
		(end 386.257292 -104.080056)
		(width 0.254)
		(layer "B.Cu")
		(net "P12V_OCP_SFF_ISENSE_MAM_MAM")
	)
	(segment
		(start 429.54321 -85.710014)
		(end 404.627334 -85.710014)
		(width 0.254)
		(layer "B.Cu")
		(net "P12V_OCP_SFF_ISENSE_MAM_MAM")
	)
	(segment
		(start 437.228742 -51.19624)
		(end 437.228742 -57.393078)
		(width 0.254)
		(layer "B.Cu")
		(net "P12V_OCP_SFF_ISENSE_MAM_MAM")
	)
	(segment
		(start 342.98128 -105.400348)
		(end 341.55888 -106.822748)
		(width 0.254)
		(layer "B.Cu")
		(net "P12V_OCP_SFF_ISENSE_MAM_MAM")
	)
	(segment
		(start 436.66283 -57.95899)
		(end 436.66283 -78.590394)
		(width 0.254)
		(layer "B.Cu")
		(net "P12V_OCP_SFF_ISENSE_MAM_MAM")
	)
	(segment
		(start 438.04332 -37.871908)
		(end 440.06516 -39.893748)
		(width 0.254)
		(layer "B.Cu")
		(net "P12V_OCP_SFF_ISENSE_MAM_MAM")
	)
	(segment
		(start 354.481384 -105.400348)
		(end 342.98128 -105.400348)
		(width 0.254)
		(layer "B.Cu")
		(net "P12V_OCP_SFF_ISENSE_MAM_MAM")
	)
	(segment
		(start 437.228742 -57.393078)
		(end 436.66283 -57.95899)
		(width 0.254)
		(layer "B.Cu")
		(net "P12V_OCP_SFF_ISENSE_MAM_MAM")
	)
	(segment
		(start 440.06516 -39.893748)
		(end 440.06516 -48.359822)
		(width 0.254)
		(layer "B.Cu")
		(net "P12V_OCP_SFF_ISENSE_MAM_MAM")
	)
	(segment
		(start 363.457744 -114.376708)
		(end 354.481384 -105.400348)
		(width 0.254)
		(layer "B.Cu")
		(net "P12V_OCP_SFF_ISENSE_MAM_MAM")
	)
	(segment
		(start 437.81218 -37.871908)
		(end 438.04332 -37.871908)
		(width 0.254)
		(layer "B.Cu")
		(net "P12V_OCP_SFF_ISENSE_MAM_MAM")
	)
	(segment
		(start 436.66283 -78.590394)
		(end 429.54321 -85.710014)
		(width 0.254)
		(layer "B.Cu")
		(net "P12V_OCP_SFF_ISENSE_MAM_MAM")
	)
	(segment
		(start 341.55888 -112.236758)
		(end 341.55888 -107.483148)
		(width 0.254)
		(layer "In6.Cu")
		(net "P12V_OCP_SFF_ISENSE_MAM_MAM")
	)
	(segment
		(start 76.99629 -84.851748)
		(end 107.887008 -84.851748)
		(width 0.254)
		(layer "In6.Cu")
		(net "P12V_OCP_SFF_ISENSE_MAM_MAM")
	)
	(segment
		(start 260.749796 -113.071148)
		(end 264.100056 -109.720888)
		(width 0.254)
		(layer "In6.Cu")
		(net "P12V_OCP_SFF_ISENSE_MAM_MAM")
	)
	(segment
		(start 110.805214 -88.204548)
		(end 143.286734 -88.204548)
		(width 0.254)
		(layer "In6.Cu")
		(net "P12V_OCP_SFF_ISENSE_MAM_MAM")
	)
	(segment
		(start 181.289452 -93.9038)
		(end 181.834536 -93.9038)
		(width 0.254)
		(layer "In6.Cu")
		(net "P12V_OCP_SFF_ISENSE_MAM_MAM")
	)
	(segment
		(start 40.82288 -97.470468)
		(end 46.4947 -97.470468)
		(width 0.254)
		(layer "In6.Cu")
		(net "P12V_OCP_SFF_ISENSE_MAM_MAM")
	)
	(segment
		(start 219.25026 -110.124748)
		(end 219.697808 -109.6772)
		(width 0.254)
		(layer "In6.Cu")
		(net "P12V_OCP_SFF_ISENSE_MAM_MAM")
	)
	(segment
		(start 65.12433 -96.723708)
		(end 76.99629 -84.851748)
		(width 0.254)
		(layer "In6.Cu")
		(net "P12V_OCP_SFF_ISENSE_MAM_MAM")
	)
	(segment
		(start 180.62956 -93.243908)
		(end 181.289452 -93.9038)
		(width 0.254)
		(layer "In6.Cu")
		(net "P12V_OCP_SFF_ISENSE_MAM_MAM")
	)
	(segment
		(start 181.834536 -93.9038)
		(end 181.859936 -93.9292)
		(width 0.254)
		(layer "In6.Cu")
		(net "P12V_OCP_SFF_ISENSE_MAM_MAM")
	)
	(segment
		(start 219.697808 -109.6772)
		(end 221.984316 -109.6772)
		(width 0.254)
		(layer "In6.Cu")
		(net "P12V_OCP_SFF_ISENSE_MAM_MAM")
	)
	(segment
		(start 187.6552 -93.9292)
		(end 191.633348 -97.907348)
		(width 0.254)
		(layer "In6.Cu")
		(net "P12V_OCP_SFF_ISENSE_MAM_MAM")
	)
	(segment
		(start 264.100056 -109.720888)
		(end 315.922914 -109.720888)
		(width 0.254)
		(layer "In6.Cu")
		(net "P12V_OCP_SFF_ISENSE_MAM_MAM")
	)
	(segment
		(start 148.326094 -93.243908)
		(end 180.62956 -93.243908)
		(width 0.254)
		(layer "In6.Cu")
		(net "P12V_OCP_SFF_ISENSE_MAM_MAM")
	)
	(segment
		(start 201.02068 -100.320348)
		(end 201.02068 -102.307644)
		(width 0.254)
		(layer "In6.Cu")
		(net "P12V_OCP_SFF_ISENSE_MAM_MAM")
	)
	(segment
		(start 38.79088 -99.502468)
		(end 40.82288 -97.470468)
		(width 0.254)
		(layer "In6.Cu")
		(net "P12V_OCP_SFF_ISENSE_MAM_MAM")
	)
	(segment
		(start 108.968794 -86.368128)
		(end 110.805214 -88.204548)
		(width 0.254)
		(layer "In6.Cu")
		(net "P12V_OCP_SFF_ISENSE_MAM_MAM")
	)
	(segment
		(start 322.145914 -115.943888)
		(end 337.85175 -115.943888)
		(width 0.254)
		(layer "In6.Cu")
		(net "P12V_OCP_SFF_ISENSE_MAM_MAM")
	)
	(segment
		(start 205.429104 -106.716068)
		(end 205.762352 -106.716068)
		(width 0.254)
		(layer "In6.Cu")
		(net "P12V_OCP_SFF_ISENSE_MAM_MAM")
	)
	(segment
		(start 143.286734 -88.204548)
		(end 148.326094 -93.243908)
		(width 0.254)
		(layer "In6.Cu")
		(net "P12V_OCP_SFF_ISENSE_MAM_MAM")
	)
	(segment
		(start 38.79088 -102.199948)
		(end 38.79088 -99.502468)
		(width 0.254)
		(layer "In6.Cu")
		(net "P12V_OCP_SFF_ISENSE_MAM_MAM")
	)
	(segment
		(start 315.922914 -109.720888)
		(end 322.145914 -115.943888)
		(width 0.254)
		(layer "In6.Cu")
		(net "P12V_OCP_SFF_ISENSE_MAM_MAM")
	)
	(segment
		(start 181.859936 -93.9292)
		(end 187.6552 -93.9292)
		(width 0.254)
		(layer "In6.Cu")
		(net "P12V_OCP_SFF_ISENSE_MAM_MAM")
	)
	(segment
		(start 30.48 -103.215948)
		(end 37.77488 -103.215948)
		(width 0.254)
		(layer "In6.Cu")
		(net "P12V_OCP_SFF_ISENSE_MAM_MAM")
	)
	(segment
		(start 46.4947 -97.470468)
		(end 47.24146 -96.723708)
		(width 0.254)
		(layer "In6.Cu")
		(net "P12V_OCP_SFF_ISENSE_MAM_MAM")
	)
	(segment
		(start 222.152464 -109.509052)
		(end 222.640144 -109.509052)
		(width 0.254)
		(layer "In6.Cu")
		(net "P12V_OCP_SFF_ISENSE_MAM_MAM")
	)
	(segment
		(start 218.8083 -110.124748)
		(end 219.25026 -110.124748)
		(width 0.254)
		(layer "In6.Cu")
		(net "P12V_OCP_SFF_ISENSE_MAM_MAM")
	)
	(segment
		(start 107.887008 -84.851748)
		(end 108.968794 -85.933534)
		(width 0.254)
		(layer "In6.Cu")
		(net "P12V_OCP_SFF_ISENSE_MAM_MAM")
	)
	(segment
		(start 37.77488 -103.215948)
		(end 38.79088 -102.199948)
		(width 0.254)
		(layer "In6.Cu")
		(net "P12V_OCP_SFF_ISENSE_MAM_MAM")
	)
	(segment
		(start 47.24146 -96.723708)
		(end 65.12433 -96.723708)
		(width 0.254)
		(layer "In6.Cu")
		(net "P12V_OCP_SFF_ISENSE_MAM_MAM")
	)
	(segment
		(start 201.02068 -102.307644)
		(end 205.429104 -106.716068)
		(width 0.254)
		(layer "In6.Cu")
		(net "P12V_OCP_SFF_ISENSE_MAM_MAM")
	)
	(segment
		(start 248.647204 -113.071148)
		(end 260.749796 -113.071148)
		(width 0.254)
		(layer "In6.Cu")
		(net "P12V_OCP_SFF_ISENSE_MAM_MAM")
	)
	(segment
		(start 27.2288 -99.964748)
		(end 30.48 -103.215948)
		(width 0.254)
		(layer "In6.Cu")
		(net "P12V_OCP_SFF_ISENSE_MAM_MAM")
	)
	(segment
		(start 218.360752 -109.6772)
		(end 218.8083 -110.124748)
		(width 0.254)
		(layer "In6.Cu")
		(net "P12V_OCP_SFF_ISENSE_MAM_MAM")
	)
	(segment
		(start 191.633348 -97.907348)
		(end 198.60768 -97.907348)
		(width 0.254)
		(layer "In6.Cu")
		(net "P12V_OCP_SFF_ISENSE_MAM_MAM")
	)
	(segment
		(start 241.476784 -105.900728)
		(end 248.647204 -113.071148)
		(width 0.254)
		(layer "In6.Cu")
		(net "P12V_OCP_SFF_ISENSE_MAM_MAM")
	)
	(segment
		(start 208.723484 -109.6772)
		(end 218.360752 -109.6772)
		(width 0.254)
		(layer "In6.Cu")
		(net "P12V_OCP_SFF_ISENSE_MAM_MAM")
	)
	(segment
		(start 205.762352 -106.716068)
		(end 208.723484 -109.6772)
		(width 0.254)
		(layer "In6.Cu")
		(net "P12V_OCP_SFF_ISENSE_MAM_MAM")
	)
	(segment
		(start 226.248468 -105.900728)
		(end 241.476784 -105.900728)
		(width 0.254)
		(layer "In6.Cu")
		(net "P12V_OCP_SFF_ISENSE_MAM_MAM")
	)
	(segment
		(start 221.984316 -109.6772)
		(end 222.152464 -109.509052)
		(width 0.254)
		(layer "In6.Cu")
		(net "P12V_OCP_SFF_ISENSE_MAM_MAM")
	)
	(segment
		(start 198.60768 -97.907348)
		(end 201.02068 -100.320348)
		(width 0.254)
		(layer "In6.Cu")
		(net "P12V_OCP_SFF_ISENSE_MAM_MAM")
	)
	(segment
		(start 108.968794 -85.933534)
		(end 108.968794 -86.368128)
		(width 0.254)
		(layer "In6.Cu")
		(net "P12V_OCP_SFF_ISENSE_MAM_MAM")
	)
	(segment
		(start 337.85175 -115.943888)
		(end 341.55888 -112.236758)
		(width 0.254)
		(layer "In6.Cu")
		(net "P12V_OCP_SFF_ISENSE_MAM_MAM")
	)
	(segment
		(start 222.640144 -109.509052)
		(end 226.248468 -105.900728)
		(width 0.254)
		(layer "In6.Cu")
		(net "P12V_OCP_SFF_ISENSE_MAM_MAM")
	)
	(segment
		(start 33.367218 -99.791774)
		(end 35.174428 -99.791774)
		(width 0.12954)
		(layer "F.Cu")
		(net "P12V_OCP_SFF_ISENSE_MAM")
	)
	(segment
		(start 35.174428 -99.791774)
		(end 35.857688 -99.791774)
		(width 0.12954)
		(layer "F.Cu")
		(net "P12V_OCP_SFF_ISENSE_MAM")
	)
	(segment
		(start 33.161478 -99.351084)
		(end 33.161478 -99.586034)
		(width 0.12954)
		(layer "F.Cu")
		(net "P12V_OCP_SFF_ISENSE_MAM")
	)
	(segment
		(start 33.161478 -99.586034)
		(end 33.367218 -99.791774)
		(width 0.12954)
		(layer "F.Cu")
		(net "P12V_OCP_SFF_ISENSE_MAM")
	)
	(segment
		(start 29.440378 -99.078034)
		(end 32.888428 -99.078034)
		(width 0.12954)
		(layer "F.Cu")
		(net "P12V_OCP_SFF_ISENSE_MAM")
	)
	(segment
		(start 32.888428 -99.078034)
		(end 33.161478 -99.351084)
		(width 0.12954)
		(layer "F.Cu")
		(net "P12V_OCP_SFF_ISENSE_MAM")
	)
	(segment
		(start 36.110672 -99.53879)
		(end 36.988496 -99.53879)
		(width 0.12954)
		(layer "F.Cu")
		(net "P12V_OCP_SFF_ISENSE_MAM")
	)
	(segment
		(start 28.932378 -99.586034)
		(end 29.440378 -99.078034)
		(width 0.12954)
		(layer "F.Cu")
		(net "P12V_OCP_SFF_ISENSE_MAM")
	)
	(segment
		(start 35.857688 -99.791774)
		(end 36.110672 -99.53879)
		(width 0.12954)
		(layer "F.Cu")
		(net "P12V_OCP_SFF_ISENSE_MAM")
	)
	(via
		(at 35.174428 -99.791774)
		(size 0.762)
		(drill 0.381)
		(layers "F.Cu" "B.Cu")
		(net "P12V_OCP_SFF_ISENSE_MAM")
	)
	(segment
		(start 75.946508 -22.327108)
		(end 75.946508 -21.839682)
		(width 0.12954)
		(layer "F.Cu")
		(net "P12V_OCP_SENSE_2")
	)
	(segment
		(start 75.946508 -21.839682)
		(end 77.460856 -21.839682)
		(width 0.12954)
		(layer "F.Cu")
		(net "P12V_OCP_SENSE_2")
	)
	(segment
		(start 75.807316 -22.4663)
		(end 75.946508 -22.327108)
		(width 0.12954)
		(layer "F.Cu")
		(net "P12V_OCP_SENSE_2")
	)
	(segment
		(start 77.460856 -21.839682)
		(end 77.856334 -21.444204)
		(width 0.12954)
		(layer "F.Cu")
		(net "P12V_OCP_SENSE_2")
	)
	(segment
		(start 75.020678 -22.581362)
		(end 75.52944 -22.581362)
		(width 0.12954)
		(layer "F.Cu")
		(net "P12V_OCP_SENSE_2")
	)
	(segment
		(start 60.527438 -32.944562)
		(end 60.527438 -32.287972)
		(width 0.12954)
		(layer "F.Cu")
		(net "P12V_OCP_SENSE_2")
	)
	(segment
		(start 75.52944 -22.581362)
		(end 75.807316 -22.4663)
		(width 0.12954)
		(layer "F.Cu")
		(net "P12V_OCP_SENSE_2")
	)
	(via
		(at 60.527438 -32.944562)
		(size 0.508)
		(drill 0.254)
		(layers "F.Cu" "B.Cu")
		(net "P12V_OCP_SENSE_2")
	)
	(via
		(at 75.020678 -22.581362)
		(size 0.508)
		(drill 0.254)
		(layers "F.Cu" "B.Cu")
		(net "P12V_OCP_SENSE_2")
	)
	(segment
		(start 74.135996 -29.282644)
		(end 74.135996 -25.066244)
		(width 0.12954)
		(layer "B.Cu")
		(net "P12V_OCP_SENSE_2")
	)
	(segment
		(start 70.989952 -32.428688)
		(end 74.135996 -29.282644)
		(width 0.12954)
		(layer "B.Cu")
		(net "P12V_OCP_SENSE_2")
	)
	(segment
		(start 61.043312 -32.428688)
		(end 70.989952 -32.428688)
		(width 0.12954)
		(layer "B.Cu")
		(net "P12V_OCP_SENSE_2")
	)
	(segment
		(start 60.527438 -32.944562)
		(end 61.043312 -32.428688)
		(width 0.12954)
		(layer "B.Cu")
		(net "P12V_OCP_SENSE_2")
	)
	(segment
		(start 75.020678 -24.181562)
		(end 75.020678 -22.581362)
		(width 0.12954)
		(layer "B.Cu")
		(net "P12V_OCP_SENSE_2")
	)
	(segment
		(start 74.135996 -25.066244)
		(end 75.020678 -24.181562)
		(width 0.12954)
		(layer "B.Cu")
		(net "P12V_OCP_SENSE_2")
	)
	(segment
		(start 435.208172 -33.238948)
		(end 435.208172 -32.573468)
		(width 0.12954)
		(layer "F.Cu")
		(net "P12V_OCP_SENSE_1")
	)
	(segment
		(start 449.60159 -22.125178)
		(end 448.087242 -22.125178)
		(width 0.12954)
		(layer "F.Cu")
		(net "P12V_OCP_SENSE_1")
	)
	(segment
		(start 447.832988 -22.866858)
		(end 448.087242 -22.612604)
		(width 0.12954)
		(layer "F.Cu")
		(net "P12V_OCP_SENSE_1")
	)
	(segment
		(start 447.161412 -22.866858)
		(end 447.832988 -22.866858)
		(width 0.12954)
		(layer "F.Cu")
		(net "P12V_OCP_SENSE_1")
	)
	(segment
		(start 449.997068 -21.7297)
		(end 449.60159 -22.125178)
		(width 0.12954)
		(layer "F.Cu")
		(net "P12V_OCP_SENSE_1")
	)
	(segment
		(start 448.087242 -22.612604)
		(end 448.087242 -22.125178)
		(width 0.12954)
		(layer "F.Cu")
		(net "P12V_OCP_SENSE_1")
	)
	(via
		(at 435.208172 -33.238948)
		(size 0.508)
		(drill 0.254)
		(layers "F.Cu" "B.Cu")
		(net "P12V_OCP_SENSE_1")
	)
	(via
		(at 447.161412 -22.866858)
		(size 0.508)
		(drill 0.254)
		(layers "F.Cu" "B.Cu")
		(net "P12V_OCP_SENSE_1")
	)
	(segment
		(start 446.558162 -31.826708)
		(end 435.58206 -31.826708)
		(width 0.12954)
		(layer "B.Cu")
		(net "P12V_OCP_SENSE_1")
	)
	(segment
		(start 449.76542 -23.612094)
		(end 449.76542 -24.40305)
		(width 0.12954)
		(layer "B.Cu")
		(net "P12V_OCP_SENSE_1")
	)
	(segment
		(start 435.58206 -31.826708)
		(end 435.208172 -32.200596)
		(width 0.12954)
		(layer "B.Cu")
		(net "P12V_OCP_SENSE_1")
	)
	(segment
		(start 447.161412 -22.866858)
		(end 449.020184 -22.866858)
		(width 0.12954)
		(layer "B.Cu")
		(net "P12V_OCP_SENSE_1")
	)
	(segment
		(start 435.208172 -32.200596)
		(end 435.208172 -33.238948)
		(width 0.12954)
		(layer "B.Cu")
		(net "P12V_OCP_SENSE_1")
	)
	(segment
		(start 449.76542 -24.40305)
		(end 448.7037 -25.46477)
		(width 0.12954)
		(layer "B.Cu")
		(net "P12V_OCP_SENSE_1")
	)
	(segment
		(start 448.7037 -29.68117)
		(end 446.558162 -31.826708)
		(width 0.12954)
		(layer "B.Cu")
		(net "P12V_OCP_SENSE_1")
	)
	(segment
		(start 448.7037 -25.46477)
		(end 448.7037 -29.68117)
		(width 0.12954)
		(layer "B.Cu")
		(net "P12V_OCP_SENSE_1")
	)
	(segment
		(start 449.020184 -22.866858)
		(end 449.76542 -23.612094)
		(width 0.12954)
		(layer "B.Cu")
		(net "P12V_OCP_SENSE_1")
	)
	(segment
		(start 77.133196 -19.220942)
		(end 77.856334 -19.94408)
		(width 0.12954)
		(layer "F.Cu")
		(net "P12V_OCP_REG_2")
	)
	(segment
		(start 75.824588 -19.220942)
		(end 76.78674 -19.220942)
		(width 0.12954)
		(layer "F.Cu")
		(net "P12V_OCP_REG_2")
	)
	(segment
		(start 76.78674 -19.220942)
		(end 77.133196 -19.220942)
		(width 0.12954)
		(layer "F.Cu")
		(net "P12V_OCP_REG_2")
	)
	(via
		(at 76.78674 -19.220942)
		(size 0.508)
		(drill 0.254)
		(layers "F.Cu" "B.Cu")
		(net "P12V_OCP_REG_2")
	)
	(segment
		(start 449.06946 -19.506438)
		(end 449.27393 -19.506438)
		(width 0.12954)
		(layer "F.Cu")
		(net "P12V_OCP_REG_1")
	)
	(segment
		(start 449.27393 -19.506438)
		(end 449.997068 -20.229576)
		(width 0.12954)
		(layer "F.Cu")
		(net "P12V_OCP_REG_1")
	)
	(segment
		(start 447.965322 -19.506438)
		(end 449.06946 -19.506438)
		(width 0.12954)
		(layer "F.Cu")
		(net "P12V_OCP_REG_1")
	)
	(via
		(at 449.06946 -19.506438)
		(size 0.508)
		(drill 0.254)
		(layers "F.Cu" "B.Cu")
		(net "P12V_OCP_REG_1")
	)
	(segment
		(start 81.38922 -19.812508)
		(end 81.285334 -19.708622)
		(width 0.12954)
		(layer "F.Cu")
		(net "P12V_OCP_PWRGD_2")
	)
	(segment
		(start 81.285334 -18.366486)
		(end 81.906618 -17.745202)
		(width 0.12954)
		(layer "F.Cu")
		(net "P12V_OCP_PWRGD_2")
	)
	(segment
		(start 81.285334 -19.708622)
		(end 81.285334 -18.366486)
		(width 0.12954)
		(layer "F.Cu")
		(net "P12V_OCP_PWRGD_2")
	)
	(segment
		(start 80.988154 -19.812508)
		(end 81.38922 -19.812508)
		(width 0.12954)
		(layer "F.Cu")
		(net "P12V_OCP_PWRGD_2")
	)
	(segment
		(start 80.856582 -19.94408)
		(end 80.988154 -19.812508)
		(width 0.12954)
		(layer "F.Cu")
		(net "P12V_OCP_PWRGD_2")
	)
	(via
		(at 81.38922 -19.812508)
		(size 0.508)
		(drill 0.254)
		(layers "F.Cu" "B.Cu")
		(net "P12V_OCP_PWRGD_2")
	)
	(segment
		(start 452.997316 -20.229576)
		(end 453.426068 -19.800824)
		(width 0.12954)
		(layer "F.Cu")
		(net "P12V_OCP_PWRGD_1")
	)
	(segment
		(start 453.426068 -19.800824)
		(end 453.426068 -19.312128)
		(width 0.12954)
		(layer "F.Cu")
		(net "P12V_OCP_PWRGD_1")
	)
	(segment
		(start 453.426068 -19.312128)
		(end 453.426068 -18.651982)
		(width 0.12954)
		(layer "F.Cu")
		(net "P12V_OCP_PWRGD_1")
	)
	(segment
		(start 453.426068 -18.651982)
		(end 454.047352 -18.030698)
		(width 0.12954)
		(layer "F.Cu")
		(net "P12V_OCP_PWRGD_1")
	)
	(via
		(at 453.426068 -19.312128)
		(size 0.508)
		(drill 0.254)
		(layers "F.Cu" "B.Cu")
		(net "P12V_OCP_PWRGD_1")
	)
	(segment
		(start 78.856586 -19.94408)
		(end 78.856586 -19.276568)
		(width 0.12954)
		(layer "F.Cu")
		(net "P12V_OCP_OV_2")
	)
	(segment
		(start 77.89418 -17.377918)
		(end 76.839318 -17.377918)
		(width 0.12954)
		(layer "F.Cu")
		(net "P12V_OCP_OV_2")
	)
	(segment
		(start 76.371958 -17.377918)
		(end 76.839318 -17.377918)
		(width 0.12954)
		(layer "F.Cu")
		(net "P12V_OCP_OV_2")
	)
	(segment
		(start 76.366624 -17.383252)
		(end 76.371958 -17.377918)
		(width 0.12954)
		(layer "F.Cu")
		(net "P12V_OCP_OV_2")
	)
	(segment
		(start 78.856586 -18.340324)
		(end 77.89418 -17.377918)
		(width 0.12954)
		(layer "F.Cu")
		(net "P12V_OCP_OV_2")
	)
	(segment
		(start 75.816968 -17.148302)
		(end 76.051918 -17.383252)
		(width 0.12954)
		(layer "F.Cu")
		(net "P12V_OCP_OV_2")
	)
	(segment
		(start 76.051918 -17.383252)
		(end 76.366624 -17.383252)
		(width 0.12954)
		(layer "F.Cu")
		(net "P12V_OCP_OV_2")
	)
	(segment
		(start 78.856586 -19.276568)
		(end 78.856586 -18.340324)
		(width 0.12954)
		(layer "F.Cu")
		(net "P12V_OCP_OV_2")
	)
	(via
		(at 78.856586 -19.276568)
		(size 0.508)
		(drill 0.254)
		(layers "F.Cu" "B.Cu")
		(net "P12V_OCP_OV_2")
	)
	(segment
		(start 448.26428 -17.668748)
		(end 448.507358 -17.668748)
		(width 0.12954)
		(layer "F.Cu")
		(net "P12V_OCP_OV_1")
	)
	(segment
		(start 448.980052 -17.663414)
		(end 450.034914 -17.663414)
		(width 0.12954)
		(layer "F.Cu")
		(net "P12V_OCP_OV_1")
	)
	(segment
		(start 448.512692 -17.663414)
		(end 448.980052 -17.663414)
		(width 0.12954)
		(layer "F.Cu")
		(net "P12V_OCP_OV_1")
	)
	(segment
		(start 450.034914 -17.663414)
		(end 450.99732 -18.62582)
		(width 0.12954)
		(layer "F.Cu")
		(net "P12V_OCP_OV_1")
	)
	(segment
		(start 448.02933 -17.433798)
		(end 448.26428 -17.668748)
		(width 0.12954)
		(layer "F.Cu")
		(net "P12V_OCP_OV_1")
	)
	(segment
		(start 448.507358 -17.668748)
		(end 448.512692 -17.663414)
		(width 0.12954)
		(layer "F.Cu")
		(net "P12V_OCP_OV_1")
	)
	(segment
		(start 447.957702 -17.433798)
		(end 448.02933 -17.433798)
		(width 0.12954)
		(layer "F.Cu")
		(net "P12V_OCP_OV_1")
	)
	(segment
		(start 450.99732 -18.62582)
		(end 450.99732 -20.229576)
		(width 0.12954)
		(layer "F.Cu")
		(net "P12V_OCP_OV_1")
	)
	(via
		(at 450.99732 -18.62582)
		(size 0.508)
		(drill 0.254)
		(layers "F.Cu" "B.Cu")
		(net "P12V_OCP_OV_1")
	)
	(segment
		(start 80.53832 -23.342854)
		(end 80.513428 -23.317962)
		(width 0.12954)
		(layer "F.Cu")
		(net "P12V_OCP_GATE_2")
	)
	(segment
		(start 80.356456 -22.659848)
		(end 80.356456 -23.16099)
		(width 0.12954)
		(layer "F.Cu")
		(net "P12V_OCP_GATE_2")
	)
	(segment
		(start 80.513428 -24.333962)
		(end 80.525112 -24.345646)
		(width 0.12954)
		(layer "F.Cu")
		(net "P12V_OCP_GATE_2")
	)
	(segment
		(start 80.356456 -23.16099)
		(end 80.513428 -23.317962)
		(width 0.12954)
		(layer "F.Cu")
		(net "P12V_OCP_GATE_2")
	)
	(segment
		(start 80.53832 -24.30907)
		(end 80.53832 -23.342854)
		(width 0.12954)
		(layer "F.Cu")
		(net "P12V_OCP_GATE_2")
	)
	(segment
		(start 80.513428 -24.333962)
		(end 80.53832 -24.30907)
		(width 0.12954)
		(layer "F.Cu")
		(net "P12V_OCP_GATE_2")
	)
	(segment
		(start 80.356456 -21.444204)
		(end 80.356456 -22.659848)
		(width 0.12954)
		(layer "F.Cu")
		(net "P12V_OCP_GATE_2")
	)
	(segment
		(start 80.525112 -24.345646)
		(end 80.525112 -25.358598)
		(width 0.12954)
		(layer "F.Cu")
		(net "P12V_OCP_GATE_2")
	)
	(via
		(at 80.356456 -22.659848)
		(size 0.508)
		(drill 0.254)
		(layers "F.Cu" "B.Cu")
		(net "P12V_OCP_GATE_2")
	)
	(segment
		(start 452.49719 -21.7297)
		(end 452.49719 -22.400768)
		(width 0.12954)
		(layer "F.Cu")
		(net "P12V_OCP_GATE_1")
	)
	(segment
		(start 452.49719 -23.446486)
		(end 452.654162 -23.603458)
		(width 0.12954)
		(layer "F.Cu")
		(net "P12V_OCP_GATE_1")
	)
	(segment
		(start 452.49719 -22.400768)
		(end 452.49719 -23.446486)
		(width 0.12954)
		(layer "F.Cu")
		(net "P12V_OCP_GATE_1")
	)
	(segment
		(start 452.654162 -23.603458)
		(end 452.654162 -24.619458)
		(width 0.12954)
		(layer "F.Cu")
		(net "P12V_OCP_GATE_1")
	)
	(segment
		(start 452.643494 -24.630126)
		(end 452.643494 -25.638506)
		(width 0.12954)
		(layer "F.Cu")
		(net "P12V_OCP_GATE_1")
	)
	(segment
		(start 452.654162 -24.619458)
		(end 452.643494 -24.630126)
		(width 0.12954)
		(layer "F.Cu")
		(net "P12V_OCP_GATE_1")
	)
	(via
		(at 452.49719 -22.400768)
		(size 0.508)
		(drill 0.254)
		(layers "F.Cu" "B.Cu")
		(net "P12V_OCP_GATE_1")
	)
	(segment
		(start 81.037684 -20.444206)
		(end 82.01025 -21.416772)
		(width 0.12954)
		(layer "F.Cu")
		(net "P12V_OCP_FAULT_2")
	)
	(segment
		(start 82.01025 -21.416772)
		(end 82.706718 -21.416772)
		(width 0.12954)
		(layer "F.Cu")
		(net "P12V_OCP_FAULT_2")
	)
	(segment
		(start 80.856582 -20.444206)
		(end 81.037684 -20.444206)
		(width 0.12954)
		(layer "F.Cu")
		(net "P12V_OCP_FAULT_2")
	)
	(via
		(at 82.01025 -21.416772)
		(size 0.508)
		(drill 0.254)
		(layers "F.Cu" "B.Cu")
		(net "P12V_OCP_FAULT_2")
	)
	(segment
		(start 454.09866 -21.623528)
		(end 454.1774 -21.702268)
		(width 0.12954)
		(layer "F.Cu")
		(net "P12V_OCP_FAULT_1")
	)
	(segment
		(start 454.1774 -21.702268)
		(end 454.847452 -21.702268)
		(width 0.12954)
		(layer "F.Cu")
		(net "P12V_OCP_FAULT_1")
	)
	(segment
		(start 453.204834 -20.729702)
		(end 454.09866 -21.623528)
		(width 0.12954)
		(layer "F.Cu")
		(net "P12V_OCP_FAULT_1")
	)
	(segment
		(start 452.997316 -20.729702)
		(end 453.204834 -20.729702)
		(width 0.12954)
		(layer "F.Cu")
		(net "P12V_OCP_FAULT_1")
	)
	(via
		(at 454.09866 -21.623528)
		(size 0.508)
		(drill 0.254)
		(layers "F.Cu" "B.Cu")
		(net "P12V_OCP_FAULT_1")
	)
	(segment
		(start 444.733172 -30.49778)
		(end 444.733172 -31.773368)
		(width 0.12954)
		(layer "F.Cu")
		(net "P12V_OCP_EN_1_R2")
	)
	(segment
		(start 444.353188 -30.117796)
		(end 444.70828 -30.472888)
		(width 0.12954)
		(layer "F.Cu")
		(net "P12V_OCP_EN_1_R2")
	)
	(segment
		(start 444.353188 -29.55036)
		(end 444.353188 -30.117796)
		(width 0.12954)
		(layer "F.Cu")
		(net "P12V_OCP_EN_1_R2")
	)
	(segment
		(start 444.70828 -30.472888)
		(end 444.733172 -30.49778)
		(width 0.12954)
		(layer "F.Cu")
		(net "P12V_OCP_EN_1_R2")
	)
	(via
		(at 444.70828 -30.472888)
		(size 0.508)
		(drill 0.254)
		(layers "F.Cu" "B.Cu")
		(net "P12V_OCP_EN_1_R2")
	)
	(segment
		(start 76.6064 -20.944078)
		(end 75.953112 -20.944078)
		(width 0.12954)
		(layer "F.Cu")
		(net "P12V_OCP_CB_2")
	)
	(segment
		(start 77.856334 -20.944078)
		(end 76.6064 -20.944078)
		(width 0.12954)
		(layer "F.Cu")
		(net "P12V_OCP_CB_2")
	)
	(segment
		(start 75.953112 -20.944078)
		(end 75.946508 -20.950682)
		(width 0.12954)
		(layer "F.Cu")
		(net "P12V_OCP_CB_2")
	)
	(via
		(at 76.6064 -20.944078)
		(size 0.508)
		(drill 0.254)
		(layers "F.Cu" "B.Cu")
		(net "P12V_OCP_CB_2")
	)
	(segment
		(start 448.087242 -21.236178)
		(end 448.86118 -21.236178)
		(width 0.12954)
		(layer "F.Cu")
		(net "P12V_OCP_CB_1")
	)
	(segment
		(start 449.990464 -21.236178)
		(end 449.997068 -21.229574)
		(width 0.12954)
		(layer "F.Cu")
		(net "P12V_OCP_CB_1")
	)
	(segment
		(start 448.86118 -21.236178)
		(end 449.990464 -21.236178)
		(width 0.12954)
		(layer "F.Cu")
		(net "P12V_OCP_CB_1")
	)
	(via
		(at 448.86118 -21.236178)
		(size 0.508)
		(drill 0.254)
		(layers "F.Cu" "B.Cu")
		(net "P12V_OCP_CB_1")
	)
	(segment
		(start 166.357046 -318.866774)
		(end 164.892228 -318.866774)
		(width 0.12954)
		(layer "F.Cu")
		(net "I3C_SPD_DDREFGH_CPU1_LVC1_SCL_R")
	)
	(segment
		(start 164.892228 -318.866774)
		(end 164.560758 -318.535304)
		(width 0.12954)
		(layer "F.Cu")
		(net "I3C_SPD_DDREFGH_CPU1_LVC1_SCL_R")
	)
	(via
		(at 164.896038 -317.824104)
		(size 0.6604)
		(drill 0.3302)
		(layers "F.Cu" "B.Cu")
		(net "I3C_SPD_DDREFGH_CPU1_LVC1_SCL_R")
	)
	(via
		(at 164.560758 -318.535304)
		(size 0.4572)
		(drill 0.2032)
		(layers "F.Cu" "B.Cu")
		(net "I3C_SPD_DDREFGH_CPU1_LVC1_SCL_R")
	)
	(segment
		(start 164.560758 -318.159384)
		(end 164.896038 -317.824104)
		(width 0.12954)
		(layer "B.Cu")
		(net "I3C_SPD_DDREFGH_CPU1_LVC1_SCL_R")
	)
	(segment
		(start 164.560758 -318.535304)
		(end 164.560758 -318.159384)
		(width 0.12954)
		(layer "B.Cu")
		(net "I3C_SPD_DDREFGH_CPU1_LVC1_SCL_R")
	)
	(segment
		(start 164.896038 -317.824104)
		(end 165.43528 -317.824104)
		(width 0.12954)
		(layer "B.Cu")
		(net "I3C_SPD_DDREFGH_CPU1_LVC1_SCL_R")
	)
	(segment
		(start 166.165784 -317.0936)
		(end 166.165784 -316.992508)
		(width 0.12954)
		(layer "B.Cu")
		(net "I3C_SPD_DDREFGH_CPU1_LVC1_SCL_R")
	)
	(segment
		(start 165.43528 -317.824104)
		(end 166.165784 -317.0936)
		(width 0.12954)
		(layer "B.Cu")
		(net "I3C_SPD_DDREFGH_CPU1_LVC1_SCL_R")
	)
	(segment
		(start 202.25512 -318.618108)
		(end 202.503786 -318.866774)
		(width 0.12954)
		(layer "F.Cu")
		(net "I3C_SPD_DDREFGH_CPU1_LVC1_SCL_7")
	)
	(segment
		(start 202.503786 -318.866774)
		(end 204.076046 -318.866774)
		(width 0.12954)
		(layer "F.Cu")
		(net "I3C_SPD_DDREFGH_CPU1_LVC1_SCL_7")
	)
	(via
		(at 202.25512 -318.618108)
		(size 0.4572)
		(drill 0.2032)
		(layers "F.Cu" "B.Cu")
		(net "I3C_SPD_DDREFGH_CPU1_LVC1_SCL_7")
	)
	(segment
		(start 202.25512 -318.618108)
		(end 202.25512 -318.523112)
		(width 0.12954)
		(layer "B.Cu")
		(net "I3C_SPD_DDREFGH_CPU1_LVC1_SCL_7")
	)
	(segment
		(start 202.25512 -318.523112)
		(end 203.991464 -316.786768)
		(width 0.12954)
		(layer "B.Cu")
		(net "I3C_SPD_DDREFGH_CPU1_LVC1_SCL_7")
	)
	(segment
		(start 210.141566 -318.866774)
		(end 211.619846 -318.866774)
		(width 0.12954)
		(layer "F.Cu")
		(net "I3C_SPD_DDREFGH_CPU1_LVC1_SCL_6")
	)
	(segment
		(start 209.931254 -318.656462)
		(end 210.141566 -318.866774)
		(width 0.12954)
		(layer "F.Cu")
		(net "I3C_SPD_DDREFGH_CPU1_LVC1_SCL_6")
	)
	(via
		(at 209.931254 -318.656462)
		(size 0.4572)
		(drill 0.2032)
		(layers "F.Cu" "B.Cu")
		(net "I3C_SPD_DDREFGH_CPU1_LVC1_SCL_6")
	)
	(via
		(at 209.615024 -317.296038)
		(size 0.6604)
		(drill 0.3302)
		(layers "F.Cu" "B.Cu")
		(net "I3C_SPD_DDREFGH_CPU1_LVC1_SCL_6")
	)
	(segment
		(start 209.931254 -318.656462)
		(end 209.8294 -318.554608)
		(width 0.12954)
		(layer "B.Cu")
		(net "I3C_SPD_DDREFGH_CPU1_LVC1_SCL_6")
	)
	(segment
		(start 209.8294 -317.510414)
		(end 209.615024 -317.296038)
		(width 0.12954)
		(layer "B.Cu")
		(net "I3C_SPD_DDREFGH_CPU1_LVC1_SCL_6")
	)
	(segment
		(start 209.8294 -318.554608)
		(end 209.8294 -317.510414)
		(width 0.12954)
		(layer "B.Cu")
		(net "I3C_SPD_DDREFGH_CPU1_LVC1_SCL_6")
	)
	(segment
		(start 209.615024 -317.296038)
		(end 208.977484 -316.658498)
		(width 0.12954)
		(layer "B.Cu")
		(net "I3C_SPD_DDREFGH_CPU1_LVC1_SCL_6")
	)
	(segment
		(start 208.977484 -316.658498)
		(end 208.30794 -316.658498)
		(width 0.12954)
		(layer "B.Cu")
		(net "I3C_SPD_DDREFGH_CPU1_LVC1_SCL_6")
	)
	(segment
		(start 190.51016 -318.561466)
		(end 190.378588 -318.693038)
		(width 0.12954)
		(layer "F.Cu")
		(net "I3C_SPD_DDREFGH_CPU1_LVC1_SCL_5")
	)
	(segment
		(start 189.973204 -318.693038)
		(end 189.799468 -318.866774)
		(width 0.12954)
		(layer "F.Cu")
		(net "I3C_SPD_DDREFGH_CPU1_LVC1_SCL_5")
	)
	(segment
		(start 189.799468 -318.866774)
		(end 188.988446 -318.866774)
		(width 0.12954)
		(layer "F.Cu")
		(net "I3C_SPD_DDREFGH_CPU1_LVC1_SCL_5")
	)
	(segment
		(start 190.378588 -318.693038)
		(end 189.973204 -318.693038)
		(width 0.12954)
		(layer "F.Cu")
		(net "I3C_SPD_DDREFGH_CPU1_LVC1_SCL_5")
	)
	(via
		(at 190.15202 -317.955168)
		(size 0.6604)
		(drill 0.3302)
		(layers "F.Cu" "B.Cu")
		(net "I3C_SPD_DDREFGH_CPU1_LVC1_SCL_5")
	)
	(via
		(at 190.51016 -318.561466)
		(size 0.4572)
		(drill 0.2032)
		(layers "F.Cu" "B.Cu")
		(net "I3C_SPD_DDREFGH_CPU1_LVC1_SCL_5")
	)
	(segment
		(start 190.15202 -317.955168)
		(end 190.15202 -318.203326)
		(width 0.12954)
		(layer "B.Cu")
		(net "I3C_SPD_DDREFGH_CPU1_LVC1_SCL_5")
	)
	(segment
		(start 188.981588 -317.266828)
		(end 189.46368 -317.266828)
		(width 0.12954)
		(layer "B.Cu")
		(net "I3C_SPD_DDREFGH_CPU1_LVC1_SCL_5")
	)
	(segment
		(start 190.15202 -318.203326)
		(end 190.51016 -318.561466)
		(width 0.12954)
		(layer "B.Cu")
		(net "I3C_SPD_DDREFGH_CPU1_LVC1_SCL_5")
	)
	(segment
		(start 189.46368 -317.266828)
		(end 190.15202 -317.955168)
		(width 0.12954)
		(layer "B.Cu")
		(net "I3C_SPD_DDREFGH_CPU1_LVC1_SCL_5")
	)
	(segment
		(start 194.728846 -318.866774)
		(end 196.532246 -318.866774)
		(width 0.12954)
		(layer "F.Cu")
		(net "I3C_SPD_DDREFGH_CPU1_LVC1_SCL_4")
	)
	(segment
		(start 194.601592 -318.994028)
		(end 194.728846 -318.866774)
		(width 0.12954)
		(layer "F.Cu")
		(net "I3C_SPD_DDREFGH_CPU1_LVC1_SCL_4")
	)
	(via
		(at 194.601592 -318.994028)
		(size 0.4572)
		(drill 0.2032)
		(layers "F.Cu" "B.Cu")
		(net "I3C_SPD_DDREFGH_CPU1_LVC1_SCL_4")
	)
	(via
		(at 194.831462 -317.87592)
		(size 0.6604)
		(drill 0.3302)
		(layers "F.Cu" "B.Cu")
		(net "I3C_SPD_DDREFGH_CPU1_LVC1_SCL_4")
	)
	(segment
		(start 194.601592 -318.10579)
		(end 194.831462 -317.87592)
		(width 0.12954)
		(layer "B.Cu")
		(net "I3C_SPD_DDREFGH_CPU1_LVC1_SCL_4")
	)
	(segment
		(start 195.624958 -317.87592)
		(end 196.23278 -317.268098)
		(width 0.12954)
		(layer "B.Cu")
		(net "I3C_SPD_DDREFGH_CPU1_LVC1_SCL_4")
	)
	(segment
		(start 194.601592 -318.994028)
		(end 194.601592 -318.10579)
		(width 0.12954)
		(layer "B.Cu")
		(net "I3C_SPD_DDREFGH_CPU1_LVC1_SCL_4")
	)
	(segment
		(start 194.831462 -317.87592)
		(end 195.624958 -317.87592)
		(width 0.12954)
		(layer "B.Cu")
		(net "I3C_SPD_DDREFGH_CPU1_LVC1_SCL_4")
	)
	(segment
		(start 174.911004 -318.682624)
		(end 174.726854 -318.866774)
		(width 0.12954)
		(layer "F.Cu")
		(net "I3C_SPD_DDREFGH_CPU1_LVC1_SCL_3")
	)
	(segment
		(start 175.569118 -318.682624)
		(end 174.911004 -318.682624)
		(width 0.12954)
		(layer "F.Cu")
		(net "I3C_SPD_DDREFGH_CPU1_LVC1_SCL_3")
	)
	(segment
		(start 174.726854 -318.866774)
		(end 173.900846 -318.866774)
		(width 0.12954)
		(layer "F.Cu")
		(net "I3C_SPD_DDREFGH_CPU1_LVC1_SCL_3")
	)
	(segment
		(start 175.827182 -318.12992)
		(end 175.827182 -318.42456)
		(width 0.12954)
		(layer "F.Cu")
		(net "I3C_SPD_DDREFGH_CPU1_LVC1_SCL_3")
	)
	(segment
		(start 175.827182 -318.42456)
		(end 175.569118 -318.682624)
		(width 0.12954)
		(layer "F.Cu")
		(net "I3C_SPD_DDREFGH_CPU1_LVC1_SCL_3")
	)
	(via
		(at 175.827182 -318.12992)
		(size 0.4572)
		(drill 0.2032)
		(layers "F.Cu" "B.Cu")
		(net "I3C_SPD_DDREFGH_CPU1_LVC1_SCL_3")
	)
	(segment
		(start 175.827182 -318.12992)
		(end 175.587152 -317.88989)
		(width 0.12954)
		(layer "B.Cu")
		(net "I3C_SPD_DDREFGH_CPU1_LVC1_SCL_3")
	)
	(segment
		(start 175.587152 -317.88989)
		(end 173.91507 -317.88989)
		(width 0.12954)
		(layer "B.Cu")
		(net "I3C_SPD_DDREFGH_CPU1_LVC1_SCL_3")
	)
	(segment
		(start 179.74945 -318.866774)
		(end 181.444646 -318.866774)
		(width 0.12954)
		(layer "F.Cu")
		(net "I3C_SPD_DDREFGH_CPU1_LVC1_SCL_2")
	)
	(segment
		(start 179.449222 -319.167002)
		(end 179.74945 -318.866774)
		(width 0.12954)
		(layer "F.Cu")
		(net "I3C_SPD_DDREFGH_CPU1_LVC1_SCL_2")
	)
	(via
		(at 179.449222 -319.167002)
		(size 0.4572)
		(drill 0.2032)
		(layers "F.Cu" "B.Cu")
		(net "I3C_SPD_DDREFGH_CPU1_LVC1_SCL_2")
	)
	(via
		(at 180.275992 -318.009016)
		(size 0.6604)
		(drill 0.3302)
		(layers "F.Cu" "B.Cu")
		(net "I3C_SPD_DDREFGH_CPU1_LVC1_SCL_2")
	)
	(segment
		(start 179.449222 -319.167002)
		(end 179.449222 -318.835786)
		(width 0.12954)
		(layer "B.Cu")
		(net "I3C_SPD_DDREFGH_CPU1_LVC1_SCL_2")
	)
	(segment
		(start 180.619908 -317.6651)
		(end 181.464458 -317.6651)
		(width 0.12954)
		(layer "B.Cu")
		(net "I3C_SPD_DDREFGH_CPU1_LVC1_SCL_2")
	)
	(segment
		(start 180.275992 -318.009016)
		(end 180.619908 -317.6651)
		(width 0.12954)
		(layer "B.Cu")
		(net "I3C_SPD_DDREFGH_CPU1_LVC1_SCL_2")
	)
	(segment
		(start 179.449222 -318.835786)
		(end 180.275992 -318.009016)
		(width 0.12954)
		(layer "B.Cu")
		(net "I3C_SPD_DDREFGH_CPU1_LVC1_SCL_2")
	)
	(segment
		(start 158.813246 -318.866774)
		(end 159.943546 -318.866774)
		(width 0.12954)
		(layer "F.Cu")
		(net "I3C_SPD_DDREFGH_CPU1_LVC1_SCL_1")
	)
	(via
		(at 159.07004 -317.185548)
		(size 0.6604)
		(drill 0.3302)
		(layers "F.Cu" "B.Cu")
		(net "I3C_SPD_DDREFGH_CPU1_LVC1_SCL_1")
	)
	(via
		(at 159.943546 -318.866774)
		(size 0.4572)
		(drill 0.2032)
		(layers "F.Cu" "B.Cu")
		(net "I3C_SPD_DDREFGH_CPU1_LVC1_SCL_1")
	)
	(segment
		(start 159.943546 -318.866774)
		(end 159.832548 -318.755776)
		(width 0.12954)
		(layer "B.Cu")
		(net "I3C_SPD_DDREFGH_CPU1_LVC1_SCL_1")
	)
	(segment
		(start 159.19958 -317.185548)
		(end 159.07004 -317.185548)
		(width 0.12954)
		(layer "B.Cu")
		(net "I3C_SPD_DDREFGH_CPU1_LVC1_SCL_1")
	)
	(segment
		(start 159.832548 -318.755776)
		(end 159.832548 -317.818516)
		(width 0.12954)
		(layer "B.Cu")
		(net "I3C_SPD_DDREFGH_CPU1_LVC1_SCL_1")
	)
	(segment
		(start 159.097218 -318.336422)
		(end 159.07004 -318.309244)
		(width 0.12954)
		(layer "B.Cu")
		(net "I3C_SPD_DDREFGH_CPU1_LVC1_SCL_1")
	)
	(segment
		(start 159.832548 -317.818516)
		(end 159.19958 -317.185548)
		(width 0.12954)
		(layer "B.Cu")
		(net "I3C_SPD_DDREFGH_CPU1_LVC1_SCL_1")
	)
	(segment
		(start 159.07004 -318.309244)
		(end 159.07004 -317.185548)
		(width 0.12954)
		(layer "B.Cu")
		(net "I3C_SPD_DDREFGH_CPU1_LVC1_SCL_1")
	)
	(segment
		(start 413.021526 -318.866774)
		(end 414.297114 -318.866774)
		(width 0.12954)
		(layer "F.Cu")
		(net "I3C_SPD_DDREFGH_CPU0_LVC1_SCL_R")
	)
	(segment
		(start 412.47822 -318.069468)
		(end 412.47822 -318.323468)
		(width 0.12954)
		(layer "F.Cu")
		(net "I3C_SPD_DDREFGH_CPU0_LVC1_SCL_R")
	)
	(segment
		(start 412.47822 -318.323468)
		(end 413.021526 -318.866774)
		(width 0.12954)
		(layer "F.Cu")
		(net "I3C_SPD_DDREFGH_CPU0_LVC1_SCL_R")
	)
	(via
		(at 412.47822 -318.069468)
		(size 0.4572)
		(drill 0.2032)
		(layers "F.Cu" "B.Cu")
		(net "I3C_SPD_DDREFGH_CPU0_LVC1_SCL_R")
	)
	(segment
		(start 412.47822 -318.069468)
		(end 412.820612 -317.727076)
		(width 0.12954)
		(layer "B.Cu")
		(net "I3C_SPD_DDREFGH_CPU0_LVC1_SCL_R")
	)
	(segment
		(start 413.553148 -317.727076)
		(end 414.258252 -317.021972)
		(width 0.12954)
		(layer "B.Cu")
		(net "I3C_SPD_DDREFGH_CPU0_LVC1_SCL_R")
	)
	(segment
		(start 412.820612 -317.727076)
		(end 413.553148 -317.727076)
		(width 0.12954)
		(layer "B.Cu")
		(net "I3C_SPD_DDREFGH_CPU0_LVC1_SCL_R")
	)
	(segment
		(start 414.258252 -317.021972)
		(end 414.41243 -317.021972)
		(width 0.12954)
		(layer "B.Cu")
		(net "I3C_SPD_DDREFGH_CPU0_LVC1_SCL_R")
	)
	(segment
		(start 450.46392 -318.437768)
		(end 450.46392 -318.663828)
		(width 0.12954)
		(layer "F.Cu")
		(net "I3C_SPD_DDREFGH_CPU0_LVC1_SCL_7")
	)
	(segment
		(start 450.46392 -318.663828)
		(end 450.666866 -318.866774)
		(width 0.12954)
		(layer "F.Cu")
		(net "I3C_SPD_DDREFGH_CPU0_LVC1_SCL_7")
	)
	(segment
		(start 450.666866 -318.866774)
		(end 452.016114 -318.866774)
		(width 0.12954)
		(layer "F.Cu")
		(net "I3C_SPD_DDREFGH_CPU0_LVC1_SCL_7")
	)
	(via
		(at 450.46392 -318.437768)
		(size 0.4572)
		(drill 0.2032)
		(layers "F.Cu" "B.Cu")
		(net "I3C_SPD_DDREFGH_CPU0_LVC1_SCL_7")
	)
	(segment
		(start 451.28688 -317.55588)
		(end 451.812406 -317.55588)
		(width 0.12954)
		(layer "B.Cu")
		(net "I3C_SPD_DDREFGH_CPU0_LVC1_SCL_7")
	)
	(segment
		(start 450.850762 -317.86957)
		(end 450.97319 -317.86957)
		(width 0.12954)
		(layer "B.Cu")
		(net "I3C_SPD_DDREFGH_CPU0_LVC1_SCL_7")
	)
	(segment
		(start 450.46392 -318.256412)
		(end 450.850762 -317.86957)
		(width 0.12954)
		(layer "B.Cu")
		(net "I3C_SPD_DDREFGH_CPU0_LVC1_SCL_7")
	)
	(segment
		(start 450.97319 -317.86957)
		(end 451.28688 -317.55588)
		(width 0.12954)
		(layer "B.Cu")
		(net "I3C_SPD_DDREFGH_CPU0_LVC1_SCL_7")
	)
	(segment
		(start 450.46392 -318.437768)
		(end 450.46392 -318.256412)
		(width 0.12954)
		(layer "B.Cu")
		(net "I3C_SPD_DDREFGH_CPU0_LVC1_SCL_7")
	)
	(segment
		(start 460.708756 -318.692022)
		(end 460.534004 -318.866774)
		(width 0.12954)
		(layer "F.Cu")
		(net "I3C_SPD_DDREFGH_CPU0_LVC1_SCL_6")
	)
	(segment
		(start 460.534004 -318.866774)
		(end 459.559914 -318.866774)
		(width 0.12954)
		(layer "F.Cu")
		(net "I3C_SPD_DDREFGH_CPU0_LVC1_SCL_6")
	)
	(via
		(at 460.708756 -318.692022)
		(size 0.4572)
		(drill 0.2032)
		(layers "F.Cu" "B.Cu")
		(net "I3C_SPD_DDREFGH_CPU0_LVC1_SCL_6")
	)
	(via
		(at 461.130396 -316.603888)
		(size 0.6604)
		(drill 0.3302)
		(layers "F.Cu" "B.Cu")
		(net "I3C_SPD_DDREFGH_CPU0_LVC1_SCL_6")
	)
	(segment
		(start 461.130396 -316.19698)
		(end 461.130396 -316.603888)
		(width 0.12954)
		(layer "B.Cu")
		(net "I3C_SPD_DDREFGH_CPU0_LVC1_SCL_6")
	)
	(segment
		(start 460.708756 -317.756286)
		(end 460.708756 -318.692022)
		(width 0.12954)
		(layer "B.Cu")
		(net "I3C_SPD_DDREFGH_CPU0_LVC1_SCL_6")
	)
	(segment
		(start 461.130396 -316.603888)
		(end 461.130396 -317.334646)
		(width 0.12954)
		(layer "B.Cu")
		(net "I3C_SPD_DDREFGH_CPU0_LVC1_SCL_6")
	)
	(segment
		(start 461.130396 -317.334646)
		(end 460.708756 -317.756286)
		(width 0.12954)
		(layer "B.Cu")
		(net "I3C_SPD_DDREFGH_CPU0_LVC1_SCL_6")
	)
	(segment
		(start 461.35544 -315.971936)
		(end 461.130396 -316.19698)
		(width 0.12954)
		(layer "B.Cu")
		(net "I3C_SPD_DDREFGH_CPU0_LVC1_SCL_6")
	)
	(segment
		(start 461.35544 -315.172344)
		(end 461.35544 -315.971936)
		(width 0.12954)
		(layer "B.Cu")
		(net "I3C_SPD_DDREFGH_CPU0_LVC1_SCL_6")
	)
	(segment
		(start 435.46776 -318.866774)
		(end 436.928514 -318.866774)
		(width 0.12954)
		(layer "F.Cu")
		(net "I3C_SPD_DDREFGH_CPU0_LVC1_SCL_5")
	)
	(via
		(at 435.46776 -318.866774)
		(size 0.4572)
		(drill 0.2032)
		(layers "F.Cu" "B.Cu")
		(net "I3C_SPD_DDREFGH_CPU0_LVC1_SCL_5")
	)
	(segment
		(start 436.321454 -318.435228)
		(end 436.507636 -318.249046)
		(width 0.12954)
		(layer "B.Cu")
		(net "I3C_SPD_DDREFGH_CPU0_LVC1_SCL_5")
	)
	(segment
		(start 435.72176 -318.866774)
		(end 436.153306 -318.435228)
		(width 0.12954)
		(layer "B.Cu")
		(net "I3C_SPD_DDREFGH_CPU0_LVC1_SCL_5")
	)
	(segment
		(start 436.153306 -318.435228)
		(end 436.321454 -318.435228)
		(width 0.12954)
		(layer "B.Cu")
		(net "I3C_SPD_DDREFGH_CPU0_LVC1_SCL_5")
	)
	(segment
		(start 436.507636 -318.249046)
		(end 436.926482 -318.249046)
		(width 0.12954)
		(layer "B.Cu")
		(net "I3C_SPD_DDREFGH_CPU0_LVC1_SCL_5")
	)
	(segment
		(start 435.46776 -318.866774)
		(end 435.72176 -318.866774)
		(width 0.12954)
		(layer "B.Cu")
		(net "I3C_SPD_DDREFGH_CPU0_LVC1_SCL_5")
	)
	(segment
		(start 443.123066 -318.866774)
		(end 444.472314 -318.866774)
		(width 0.12954)
		(layer "F.Cu")
		(net "I3C_SPD_DDREFGH_CPU0_LVC1_SCL_4")
	)
	(segment
		(start 442.553598 -318.0842)
		(end 442.553598 -318.297306)
		(width 0.12954)
		(layer "F.Cu")
		(net "I3C_SPD_DDREFGH_CPU0_LVC1_SCL_4")
	)
	(segment
		(start 442.553598 -318.297306)
		(end 443.123066 -318.866774)
		(width 0.12954)
		(layer "F.Cu")
		(net "I3C_SPD_DDREFGH_CPU0_LVC1_SCL_4")
	)
	(via
		(at 442.553598 -318.0842)
		(size 0.4572)
		(drill 0.2032)
		(layers "F.Cu" "B.Cu")
		(net "I3C_SPD_DDREFGH_CPU0_LVC1_SCL_4")
	)
	(segment
		(start 443.332108 -317.957454)
		(end 444.180468 -317.109094)
		(width 0.12954)
		(layer "B.Cu")
		(net "I3C_SPD_DDREFGH_CPU0_LVC1_SCL_4")
	)
	(segment
		(start 442.680344 -317.957454)
		(end 443.332108 -317.957454)
		(width 0.12954)
		(layer "B.Cu")
		(net "I3C_SPD_DDREFGH_CPU0_LVC1_SCL_4")
	)
	(segment
		(start 444.180468 -317.109094)
		(end 444.42126 -317.109094)
		(width 0.12954)
		(layer "B.Cu")
		(net "I3C_SPD_DDREFGH_CPU0_LVC1_SCL_4")
	)
	(segment
		(start 442.553598 -318.0842)
		(end 442.680344 -317.957454)
		(width 0.12954)
		(layer "B.Cu")
		(net "I3C_SPD_DDREFGH_CPU0_LVC1_SCL_4")
	)
	(segment
		(start 420.527734 -318.866774)
		(end 421.840914 -318.866774)
		(width 0.12954)
		(layer "F.Cu")
		(net "I3C_SPD_DDREFGH_CPU0_LVC1_SCL_3")
	)
	(segment
		(start 419.89756 -319.496948)
		(end 420.527734 -318.866774)
		(width 0.12954)
		(layer "F.Cu")
		(net "I3C_SPD_DDREFGH_CPU0_LVC1_SCL_3")
	)
	(via
		(at 418.991542 -318.247268)
		(size 0.6604)
		(drill 0.3302)
		(layers "F.Cu" "B.Cu")
		(net "I3C_SPD_DDREFGH_CPU0_LVC1_SCL_3")
	)
	(via
		(at 419.89756 -319.496948)
		(size 0.4572)
		(drill 0.2032)
		(layers "F.Cu" "B.Cu")
		(net "I3C_SPD_DDREFGH_CPU0_LVC1_SCL_3")
	)
	(segment
		(start 418.991542 -318.247268)
		(end 419.474142 -318.247268)
		(width 0.12954)
		(layer "B.Cu")
		(net "I3C_SPD_DDREFGH_CPU0_LVC1_SCL_3")
	)
	(segment
		(start 419.479222 -319.30975)
		(end 419.66642 -319.496948)
		(width 0.12954)
		(layer "B.Cu")
		(net "I3C_SPD_DDREFGH_CPU0_LVC1_SCL_3")
	)
	(segment
		(start 419.681914 -318.45504)
		(end 420.152322 -318.45504)
		(width 0.12954)
		(layer "B.Cu")
		(net "I3C_SPD_DDREFGH_CPU0_LVC1_SCL_3")
	)
	(segment
		(start 419.474142 -318.247268)
		(end 419.681914 -318.45504)
		(width 0.12954)
		(layer "B.Cu")
		(net "I3C_SPD_DDREFGH_CPU0_LVC1_SCL_3")
	)
	(segment
		(start 419.479222 -318.734948)
		(end 419.479222 -319.30975)
		(width 0.12954)
		(layer "B.Cu")
		(net "I3C_SPD_DDREFGH_CPU0_LVC1_SCL_3")
	)
	(segment
		(start 418.991542 -318.247268)
		(end 419.479222 -318.734948)
		(width 0.12954)
		(layer "B.Cu")
		(net "I3C_SPD_DDREFGH_CPU0_LVC1_SCL_3")
	)
	(segment
		(start 419.66642 -319.496948)
		(end 419.89756 -319.496948)
		(width 0.12954)
		(layer "B.Cu")
		(net "I3C_SPD_DDREFGH_CPU0_LVC1_SCL_3")
	)
	(segment
		(start 427.628812 -318.46012)
		(end 428.035466 -318.866774)
		(width 0.12954)
		(layer "F.Cu")
		(net "I3C_SPD_DDREFGH_CPU0_LVC1_SCL_2")
	)
	(segment
		(start 428.035466 -318.866774)
		(end 429.384714 -318.866774)
		(width 0.12954)
		(layer "F.Cu")
		(net "I3C_SPD_DDREFGH_CPU0_LVC1_SCL_2")
	)
	(via
		(at 427.628812 -318.46012)
		(size 0.4572)
		(drill 0.2032)
		(layers "F.Cu" "B.Cu")
		(net "I3C_SPD_DDREFGH_CPU0_LVC1_SCL_2")
	)
	(segment
		(start 427.628812 -318.46012)
		(end 428.295562 -317.79337)
		(width 0.12954)
		(layer "B.Cu")
		(net "I3C_SPD_DDREFGH_CPU0_LVC1_SCL_2")
	)
	(segment
		(start 428.295562 -317.79337)
		(end 429.391572 -317.79337)
		(width 0.12954)
		(layer "B.Cu")
		(net "I3C_SPD_DDREFGH_CPU0_LVC1_SCL_2")
	)
	(segment
		(start 408.700224 -317.652908)
		(end 408.700224 -318.349376)
		(width 0.12954)
		(layer "F.Cu")
		(net "I3C_SPD_DDREFGH_CPU0_LVC1_SCL_1")
	)
	(segment
		(start 408.700224 -318.349376)
		(end 408.182826 -318.866774)
		(width 0.12954)
		(layer "F.Cu")
		(net "I3C_SPD_DDREFGH_CPU0_LVC1_SCL_1")
	)
	(segment
		(start 408.182826 -318.866774)
		(end 406.753314 -318.866774)
		(width 0.12954)
		(layer "F.Cu")
		(net "I3C_SPD_DDREFGH_CPU0_LVC1_SCL_1")
	)
	(via
		(at 408.788362 -316.911736)
		(size 0.6604)
		(drill 0.3302)
		(layers "F.Cu" "B.Cu")
		(net "I3C_SPD_DDREFGH_CPU0_LVC1_SCL_1")
	)
	(via
		(at 408.700224 -317.652908)
		(size 0.4572)
		(drill 0.2032)
		(layers "F.Cu" "B.Cu")
		(net "I3C_SPD_DDREFGH_CPU0_LVC1_SCL_1")
	)
	(segment
		(start 408.048968 -317.65113)
		(end 407.0731 -317.65113)
		(width 0.12954)
		(layer "B.Cu")
		(net "I3C_SPD_DDREFGH_CPU0_LVC1_SCL_1")
	)
	(segment
		(start 408.788362 -316.911736)
		(end 408.048968 -317.65113)
		(width 0.12954)
		(layer "B.Cu")
		(net "I3C_SPD_DDREFGH_CPU0_LVC1_SCL_1")
	)
	(segment
		(start 408.788362 -317.56477)
		(end 408.788362 -316.911736)
		(width 0.12954)
		(layer "B.Cu")
		(net "I3C_SPD_DDREFGH_CPU0_LVC1_SCL_1")
	)
	(segment
		(start 408.700224 -317.652908)
		(end 408.788362 -317.56477)
		(width 0.12954)
		(layer "B.Cu")
		(net "I3C_SPD_DDREFGH_CPU0_LVC1_SCL_1")
	)
	(segment
		(start 51.176936 -319.411858)
		(end 51.72202 -318.866774)
		(width 0.12954)
		(layer "F.Cu")
		(net "I3C_SPD_DDRABCD_CPU1_LVC1_SCL_R")
	)
	(segment
		(start 51.72202 -318.866774)
		(end 53.403246 -318.866774)
		(width 0.12954)
		(layer "F.Cu")
		(net "I3C_SPD_DDRABCD_CPU1_LVC1_SCL_R")
	)
	(segment
		(start 51.103022 -319.5066)
		(end 51.176936 -319.432686)
		(width 0.12954)
		(layer "F.Cu")
		(net "I3C_SPD_DDRABCD_CPU1_LVC1_SCL_R")
	)
	(segment
		(start 51.176936 -319.432686)
		(end 51.176936 -319.411858)
		(width 0.12954)
		(layer "F.Cu")
		(net "I3C_SPD_DDRABCD_CPU1_LVC1_SCL_R")
	)
	(via
		(at 53.18506 -317.655956)
		(size 0.6604)
		(drill 0.3302)
		(layers "F.Cu" "B.Cu")
		(net "I3C_SPD_DDRABCD_CPU1_LVC1_SCL_R")
	)
	(via
		(at 51.103022 -319.5066)
		(size 0.4572)
		(drill 0.2032)
		(layers "F.Cu" "B.Cu")
		(net "I3C_SPD_DDRABCD_CPU1_LVC1_SCL_R")
	)
	(segment
		(start 51.103022 -319.5066)
		(end 51.15306 -319.001648)
		(width 0.12954)
		(layer "B.Cu")
		(net "I3C_SPD_DDRABCD_CPU1_LVC1_SCL_R")
	)
	(segment
		(start 53.519578 -317.655956)
		(end 53.845714 -317.32982)
		(width 0.12954)
		(layer "B.Cu")
		(net "I3C_SPD_DDRABCD_CPU1_LVC1_SCL_R")
	)
	(segment
		(start 53.845714 -316.214506)
		(end 53.846476 -316.213744)
		(width 0.12954)
		(layer "B.Cu")
		(net "I3C_SPD_DDRABCD_CPU1_LVC1_SCL_R")
	)
	(segment
		(start 53.845714 -317.32982)
		(end 53.845714 -316.214506)
		(width 0.12954)
		(layer "B.Cu")
		(net "I3C_SPD_DDRABCD_CPU1_LVC1_SCL_R")
	)
	(segment
		(start 52.329334 -317.655956)
		(end 53.18506 -317.655956)
		(width 0.12954)
		(layer "B.Cu")
		(net "I3C_SPD_DDRABCD_CPU1_LVC1_SCL_R")
	)
	(segment
		(start 53.18506 -317.655956)
		(end 53.519578 -317.655956)
		(width 0.12954)
		(layer "B.Cu")
		(net "I3C_SPD_DDRABCD_CPU1_LVC1_SCL_R")
	)
	(segment
		(start 51.15306 -319.001648)
		(end 51.305206 -318.680084)
		(width 0.12954)
		(layer "B.Cu")
		(net "I3C_SPD_DDRABCD_CPU1_LVC1_SCL_R")
	)
	(segment
		(start 51.305206 -318.680084)
		(end 52.329334 -317.655956)
		(width 0.12954)
		(layer "B.Cu")
		(net "I3C_SPD_DDRABCD_CPU1_LVC1_SCL_R")
	)
	(segment
		(start 13.723874 -318.866774)
		(end 15.684246 -318.866774)
		(width 0.12954)
		(layer "F.Cu")
		(net "I3C_SPD_DDRABCD_CPU1_LVC1_SCL_7")
	)
	(segment
		(start 13.41628 -318.480948)
		(end 13.41628 -318.55918)
		(width 0.12954)
		(layer "F.Cu")
		(net "I3C_SPD_DDRABCD_CPU1_LVC1_SCL_7")
	)
	(segment
		(start 13.41628 -318.55918)
		(end 13.723874 -318.866774)
		(width 0.12954)
		(layer "F.Cu")
		(net "I3C_SPD_DDRABCD_CPU1_LVC1_SCL_7")
	)
	(via
		(at 13.41628 -318.480948)
		(size 0.4572)
		(drill 0.2032)
		(layers "F.Cu" "B.Cu")
		(net "I3C_SPD_DDRABCD_CPU1_LVC1_SCL_7")
	)
	(via
		(at 14.421358 -318.032892)
		(size 0.6604)
		(drill 0.3302)
		(layers "F.Cu" "B.Cu")
		(net "I3C_SPD_DDRABCD_CPU1_LVC1_SCL_7")
	)
	(segment
		(start 15.46733 -317.224664)
		(end 15.69085 -317.001144)
		(width 0.12954)
		(layer "B.Cu")
		(net "I3C_SPD_DDRABCD_CPU1_LVC1_SCL_7")
	)
	(segment
		(start 13.620242 -318.276986)
		(end 14.177264 -318.276986)
		(width 0.12954)
		(layer "B.Cu")
		(net "I3C_SPD_DDRABCD_CPU1_LVC1_SCL_7")
	)
	(segment
		(start 14.421358 -318.032892)
		(end 15.229586 -317.224664)
		(width 0.12954)
		(layer "B.Cu")
		(net "I3C_SPD_DDRABCD_CPU1_LVC1_SCL_7")
	)
	(segment
		(start 15.229586 -317.224664)
		(end 15.46733 -317.224664)
		(width 0.12954)
		(layer "B.Cu")
		(net "I3C_SPD_DDRABCD_CPU1_LVC1_SCL_7")
	)
	(segment
		(start 13.41628 -318.480948)
		(end 13.620242 -318.276986)
		(width 0.12954)
		(layer "B.Cu")
		(net "I3C_SPD_DDRABCD_CPU1_LVC1_SCL_7")
	)
	(segment
		(start 14.177264 -318.276986)
		(end 14.421358 -318.032892)
		(width 0.12954)
		(layer "B.Cu")
		(net "I3C_SPD_DDRABCD_CPU1_LVC1_SCL_7")
	)
	(segment
		(start 7.035546 -318.866774)
		(end 8.140446 -318.866774)
		(width 0.12954)
		(layer "F.Cu")
		(net "I3C_SPD_DDRABCD_CPU1_LVC1_SCL_6")
	)
	(via
		(at 6.6167 -318.077088)
		(size 0.6604)
		(drill 0.3302)
		(layers "F.Cu" "B.Cu")
		(net "I3C_SPD_DDRABCD_CPU1_LVC1_SCL_6")
	)
	(via
		(at 7.035546 -318.866774)
		(size 0.4572)
		(drill 0.2032)
		(layers "F.Cu" "B.Cu")
		(net "I3C_SPD_DDRABCD_CPU1_LVC1_SCL_6")
	)
	(segment
		(start 7.035546 -318.866774)
		(end 6.6167 -318.447928)
		(width 0.12954)
		(layer "B.Cu")
		(net "I3C_SPD_DDRABCD_CPU1_LVC1_SCL_6")
	)
	(segment
		(start 6.6167 -318.447928)
		(end 6.6167 -318.077088)
		(width 0.12954)
		(layer "B.Cu")
		(net "I3C_SPD_DDRABCD_CPU1_LVC1_SCL_6")
	)
	(segment
		(start 6.6167 -318.077088)
		(end 6.792722 -318.25311)
		(width 0.12954)
		(layer "B.Cu")
		(net "I3C_SPD_DDRABCD_CPU1_LVC1_SCL_6")
	)
	(segment
		(start 6.792722 -318.25311)
		(end 7.753096 -318.25311)
		(width 0.12954)
		(layer "B.Cu")
		(net "I3C_SPD_DDRABCD_CPU1_LVC1_SCL_6")
	)
	(segment
		(start 29.004514 -318.669416)
		(end 29.201872 -318.866774)
		(width 0.12954)
		(layer "F.Cu")
		(net "I3C_SPD_DDRABCD_CPU1_LVC1_SCL_5")
	)
	(segment
		(start 29.201872 -318.866774)
		(end 30.771846 -318.866774)
		(width 0.12954)
		(layer "F.Cu")
		(net "I3C_SPD_DDRABCD_CPU1_LVC1_SCL_5")
	)
	(via
		(at 29.004514 -318.669416)
		(size 0.4572)
		(drill 0.2032)
		(layers "F.Cu" "B.Cu")
		(net "I3C_SPD_DDRABCD_CPU1_LVC1_SCL_5")
	)
	(via
		(at 29.109416 -317.842392)
		(size 0.6604)
		(drill 0.3302)
		(layers "F.Cu" "B.Cu")
		(net "I3C_SPD_DDRABCD_CPU1_LVC1_SCL_5")
	)
	(segment
		(start 30.289754 -317.721488)
		(end 30.384496 -317.626746)
		(width 0.12954)
		(layer "B.Cu")
		(net "I3C_SPD_DDRABCD_CPU1_LVC1_SCL_5")
	)
	(segment
		(start 29.109416 -317.842392)
		(end 29.23032 -317.721488)
		(width 0.12954)
		(layer "B.Cu")
		(net "I3C_SPD_DDRABCD_CPU1_LVC1_SCL_5")
	)
	(segment
		(start 29.004514 -317.947294)
		(end 29.109416 -317.842392)
		(width 0.12954)
		(layer "B.Cu")
		(net "I3C_SPD_DDRABCD_CPU1_LVC1_SCL_5")
	)
	(segment
		(start 29.004514 -318.669416)
		(end 29.004514 -317.947294)
		(width 0.12954)
		(layer "B.Cu")
		(net "I3C_SPD_DDRABCD_CPU1_LVC1_SCL_5")
	)
	(segment
		(start 29.23032 -317.721488)
		(end 30.289754 -317.721488)
		(width 0.12954)
		(layer "B.Cu")
		(net "I3C_SPD_DDRABCD_CPU1_LVC1_SCL_5")
	)
	(segment
		(start 21.663406 -318.582802)
		(end 21.420836 -318.582802)
		(width 0.12954)
		(layer "F.Cu")
		(net "I3C_SPD_DDRABCD_CPU1_LVC1_SCL_4")
	)
	(segment
		(start 23.228046 -318.866774)
		(end 21.947378 -318.866774)
		(width 0.12954)
		(layer "F.Cu")
		(net "I3C_SPD_DDRABCD_CPU1_LVC1_SCL_4")
	)
	(segment
		(start 21.947378 -318.866774)
		(end 21.663406 -318.582802)
		(width 0.12954)
		(layer "F.Cu")
		(net "I3C_SPD_DDRABCD_CPU1_LVC1_SCL_4")
	)
	(via
		(at 22.2123 -317.929768)
		(size 0.6604)
		(drill 0.3302)
		(layers "F.Cu" "B.Cu")
		(net "I3C_SPD_DDRABCD_CPU1_LVC1_SCL_4")
	)
	(via
		(at 21.420836 -318.582802)
		(size 0.4572)
		(drill 0.2032)
		(layers "F.Cu" "B.Cu")
		(net "I3C_SPD_DDRABCD_CPU1_LVC1_SCL_4")
	)
	(segment
		(start 21.420836 -318.480186)
		(end 21.971254 -317.929768)
		(width 0.12954)
		(layer "B.Cu")
		(net "I3C_SPD_DDRABCD_CPU1_LVC1_SCL_4")
	)
	(segment
		(start 21.971254 -317.929768)
		(end 22.2123 -317.929768)
		(width 0.12954)
		(layer "B.Cu")
		(net "I3C_SPD_DDRABCD_CPU1_LVC1_SCL_4")
	)
	(segment
		(start 21.420836 -318.582802)
		(end 21.420836 -318.480186)
		(width 0.12954)
		(layer "B.Cu")
		(net "I3C_SPD_DDRABCD_CPU1_LVC1_SCL_4")
	)
	(segment
		(start 22.2123 -317.929768)
		(end 22.2123 -317.775082)
		(width 0.12954)
		(layer "B.Cu")
		(net "I3C_SPD_DDRABCD_CPU1_LVC1_SCL_4")
	)
	(segment
		(start 23.145242 -316.84214)
		(end 23.145242 -316.76594)
		(width 0.12954)
		(layer "B.Cu")
		(net "I3C_SPD_DDRABCD_CPU1_LVC1_SCL_4")
	)
	(segment
		(start 22.2123 -317.775082)
		(end 23.145242 -316.84214)
		(width 0.12954)
		(layer "B.Cu")
		(net "I3C_SPD_DDRABCD_CPU1_LVC1_SCL_4")
	)
	(segment
		(start 43.674538 -318.982598)
		(end 43.790362 -318.866774)
		(width 0.12954)
		(layer "F.Cu")
		(net "I3C_SPD_DDRABCD_CPU1_LVC1_SCL_3")
	)
	(segment
		(start 43.790362 -318.866774)
		(end 45.859446 -318.866774)
		(width 0.12954)
		(layer "F.Cu")
		(net "I3C_SPD_DDRABCD_CPU1_LVC1_SCL_3")
	)
	(via
		(at 43.674538 -318.982598)
		(size 0.4572)
		(drill 0.2032)
		(layers "F.Cu" "B.Cu")
		(net "I3C_SPD_DDRABCD_CPU1_LVC1_SCL_3")
	)
	(via
		(at 44.84624 -317.960248)
		(size 0.6604)
		(drill 0.3302)
		(layers "F.Cu" "B.Cu")
		(net "I3C_SPD_DDRABCD_CPU1_LVC1_SCL_3")
	)
	(segment
		(start 44.269406 -318.38773)
		(end 44.418758 -318.38773)
		(width 0.12954)
		(layer "B.Cu")
		(net "I3C_SPD_DDRABCD_CPU1_LVC1_SCL_3")
	)
	(segment
		(start 44.16171 -316.66942)
		(end 44.16171 -315.823854)
		(width 0.12954)
		(layer "B.Cu")
		(net "I3C_SPD_DDRABCD_CPU1_LVC1_SCL_3")
	)
	(segment
		(start 43.674538 -318.982598)
		(end 44.269406 -318.38773)
		(width 0.12954)
		(layer "B.Cu")
		(net "I3C_SPD_DDRABCD_CPU1_LVC1_SCL_3")
	)
	(segment
		(start 44.269406 -316.777116)
		(end 44.16171 -316.66942)
		(width 0.12954)
		(layer "B.Cu")
		(net "I3C_SPD_DDRABCD_CPU1_LVC1_SCL_3")
	)
	(segment
		(start 44.269406 -317.383414)
		(end 44.269406 -316.777116)
		(width 0.12954)
		(layer "B.Cu")
		(net "I3C_SPD_DDRABCD_CPU1_LVC1_SCL_3")
	)
	(segment
		(start 44.84624 -317.960248)
		(end 44.269406 -317.383414)
		(width 0.12954)
		(layer "B.Cu")
		(net "I3C_SPD_DDRABCD_CPU1_LVC1_SCL_3")
	)
	(segment
		(start 44.418758 -318.38773)
		(end 44.84624 -317.960248)
		(width 0.12954)
		(layer "B.Cu")
		(net "I3C_SPD_DDRABCD_CPU1_LVC1_SCL_3")
	)
	(segment
		(start 36.49345 -318.890904)
		(end 36.51758 -318.866774)
		(width 0.12954)
		(layer "F.Cu")
		(net "I3C_SPD_DDRABCD_CPU1_LVC1_SCL_2")
	)
	(segment
		(start 36.49345 -318.914018)
		(end 36.49345 -318.890904)
		(width 0.12954)
		(layer "F.Cu")
		(net "I3C_SPD_DDRABCD_CPU1_LVC1_SCL_2")
	)
	(segment
		(start 36.51758 -318.866774)
		(end 38.315646 -318.866774)
		(width 0.12954)
		(layer "F.Cu")
		(net "I3C_SPD_DDRABCD_CPU1_LVC1_SCL_2")
	)
	(via
		(at 36.49345 -318.914018)
		(size 0.4572)
		(drill 0.2032)
		(layers "F.Cu" "B.Cu")
		(net "I3C_SPD_DDRABCD_CPU1_LVC1_SCL_2")
	)
	(via
		(at 36.667186 -316.652148)
		(size 0.6604)
		(drill 0.3302)
		(layers "F.Cu" "B.Cu")
		(net "I3C_SPD_DDRABCD_CPU1_LVC1_SCL_2")
	)
	(segment
		(start 36.49345 -318.467486)
		(end 36.49345 -318.914018)
		(width 0.12954)
		(layer "B.Cu")
		(net "I3C_SPD_DDRABCD_CPU1_LVC1_SCL_2")
	)
	(segment
		(start 34.403792 -315.557662)
		(end 34.868866 -315.557662)
		(width 0.12954)
		(layer "B.Cu")
		(net "I3C_SPD_DDRABCD_CPU1_LVC1_SCL_2")
	)
	(segment
		(start 36.31311 -315.896244)
		(end 36.667186 -316.25032)
		(width 0.12954)
		(layer "B.Cu")
		(net "I3C_SPD_DDRABCD_CPU1_LVC1_SCL_2")
	)
	(segment
		(start 36.667186 -316.652148)
		(end 36.667186 -318.29375)
		(width 0.12954)
		(layer "B.Cu")
		(net "I3C_SPD_DDRABCD_CPU1_LVC1_SCL_2")
	)
	(segment
		(start 36.667186 -318.29375)
		(end 36.49345 -318.467486)
		(width 0.12954)
		(layer "B.Cu")
		(net "I3C_SPD_DDRABCD_CPU1_LVC1_SCL_2")
	)
	(segment
		(start 35.207448 -315.896244)
		(end 36.31311 -315.896244)
		(width 0.12954)
		(layer "B.Cu")
		(net "I3C_SPD_DDRABCD_CPU1_LVC1_SCL_2")
	)
	(segment
		(start 34.868866 -315.557662)
		(end 35.207448 -315.896244)
		(width 0.12954)
		(layer "B.Cu")
		(net "I3C_SPD_DDRABCD_CPU1_LVC1_SCL_2")
	)
	(segment
		(start 36.667186 -316.25032)
		(end 36.667186 -316.652148)
		(width 0.12954)
		(layer "B.Cu")
		(net "I3C_SPD_DDRABCD_CPU1_LVC1_SCL_2")
	)
	(segment
		(start 58.9153 -318.866774)
		(end 60.947046 -318.866774)
		(width 0.12954)
		(layer "F.Cu")
		(net "I3C_SPD_DDRABCD_CPU1_LVC1_SCL_1")
	)
	(segment
		(start 58.639456 -318.59093)
		(end 58.9153 -318.866774)
		(width 0.12954)
		(layer "F.Cu")
		(net "I3C_SPD_DDRABCD_CPU1_LVC1_SCL_1")
	)
	(via
		(at 58.639456 -318.59093)
		(size 0.508)
		(drill 0.254)
		(layers "F.Cu" "B.Cu")
		(net "I3C_SPD_DDRABCD_CPU1_LVC1_SCL_1")
	)
	(via
		(at 59.42838 -316.276228)
		(size 0.6604)
		(drill 0.3302)
		(layers "F.Cu" "B.Cu")
		(net "I3C_SPD_DDRABCD_CPU1_LVC1_SCL_1")
	)
	(segment
		(start 59.42838 -316.276228)
		(end 58.692034 -315.539882)
		(width 0.12954)
		(layer "B.Cu")
		(net "I3C_SPD_DDRABCD_CPU1_LVC1_SCL_1")
	)
	(segment
		(start 59.342528 -318.205104)
		(end 59.342528 -316.36208)
		(width 0.12954)
		(layer "B.Cu")
		(net "I3C_SPD_DDRABCD_CPU1_LVC1_SCL_1")
	)
	(segment
		(start 58.639456 -318.59093)
		(end 58.956702 -318.59093)
		(width 0.12954)
		(layer "B.Cu")
		(net "I3C_SPD_DDRABCD_CPU1_LVC1_SCL_1")
	)
	(segment
		(start 59.342528 -316.36208)
		(end 59.42838 -316.276228)
		(width 0.12954)
		(layer "B.Cu")
		(net "I3C_SPD_DDRABCD_CPU1_LVC1_SCL_1")
	)
	(segment
		(start 58.956702 -318.59093)
		(end 59.342528 -318.205104)
		(width 0.12954)
		(layer "B.Cu")
		(net "I3C_SPD_DDRABCD_CPU1_LVC1_SCL_1")
	)
	(segment
		(start 58.692034 -315.539882)
		(end 58.28157 -315.539882)
		(width 0.12954)
		(layer "B.Cu")
		(net "I3C_SPD_DDRABCD_CPU1_LVC1_SCL_1")
	)
	(segment
		(start 299.920152 -318.866774)
		(end 301.343314 -318.866774)
		(width 0.12954)
		(layer "F.Cu")
		(net "I3C_SPD_DDRABCD_CPU0_LVC1_SCL_R")
	)
	(segment
		(start 299.024548 -318.903858)
		(end 299.883068 -318.903858)
		(width 0.12954)
		(layer "F.Cu")
		(net "I3C_SPD_DDRABCD_CPU0_LVC1_SCL_R")
	)
	(segment
		(start 299.883068 -318.903858)
		(end 299.920152 -318.866774)
		(width 0.12954)
		(layer "F.Cu")
		(net "I3C_SPD_DDRABCD_CPU0_LVC1_SCL_R")
	)
	(segment
		(start 299.014388 -318.914018)
		(end 299.024548 -318.903858)
		(width 0.12954)
		(layer "F.Cu")
		(net "I3C_SPD_DDRABCD_CPU0_LVC1_SCL_R")
	)
	(via
		(at 299.014388 -318.914018)
		(size 0.4572)
		(drill 0.2032)
		(layers "F.Cu" "B.Cu")
		(net "I3C_SPD_DDRABCD_CPU0_LVC1_SCL_R")
	)
	(segment
		(start 299.014388 -318.238378)
		(end 299.609002 -317.643764)
		(width 0.12954)
		(layer "B.Cu")
		(net "I3C_SPD_DDRABCD_CPU0_LVC1_SCL_R")
	)
	(segment
		(start 299.014388 -318.914018)
		(end 299.014388 -318.238378)
		(width 0.12954)
		(layer "B.Cu")
		(net "I3C_SPD_DDRABCD_CPU0_LVC1_SCL_R")
	)
	(segment
		(start 261.68858 -319.034668)
		(end 261.856474 -318.866774)
		(width 0.12954)
		(layer "F.Cu")
		(net "I3C_SPD_DDRABCD_CPU0_LVC1_SCL_7")
	)
	(segment
		(start 261.856474 -318.866774)
		(end 263.624314 -318.866774)
		(width 0.12954)
		(layer "F.Cu")
		(net "I3C_SPD_DDRABCD_CPU0_LVC1_SCL_7")
	)
	(via
		(at 261.68858 -319.034668)
		(size 0.4572)
		(drill 0.2032)
		(layers "F.Cu" "B.Cu")
		(net "I3C_SPD_DDRABCD_CPU0_LVC1_SCL_7")
	)
	(segment
		(start 261.33552 -318.681608)
		(end 261.33552 -317.881762)
		(width 0.12954)
		(layer "B.Cu")
		(net "I3C_SPD_DDRABCD_CPU0_LVC1_SCL_7")
	)
	(segment
		(start 261.68858 -319.034668)
		(end 261.33552 -318.681608)
		(width 0.12954)
		(layer "B.Cu")
		(net "I3C_SPD_DDRABCD_CPU0_LVC1_SCL_7")
	)
	(segment
		(start 254.668274 -318.866774)
		(end 256.080514 -318.866774)
		(width 0.12954)
		(layer "F.Cu")
		(net "I3C_SPD_DDRABCD_CPU0_LVC1_SCL_6")
	)
	(segment
		(start 254.52578 -319.263268)
		(end 254.52578 -319.009268)
		(width 0.12954)
		(layer "F.Cu")
		(net "I3C_SPD_DDRABCD_CPU0_LVC1_SCL_6")
	)
	(segment
		(start 254.52578 -319.009268)
		(end 254.668274 -318.866774)
		(width 0.12954)
		(layer "F.Cu")
		(net "I3C_SPD_DDRABCD_CPU0_LVC1_SCL_6")
	)
	(via
		(at 254.52578 -319.263268)
		(size 0.4572)
		(drill 0.2032)
		(layers "F.Cu" "B.Cu")
		(net "I3C_SPD_DDRABCD_CPU0_LVC1_SCL_6")
	)
	(segment
		(start 254.52578 -318.948308)
		(end 254.991362 -318.482726)
		(width 0.12954)
		(layer "B.Cu")
		(net "I3C_SPD_DDRABCD_CPU0_LVC1_SCL_6")
	)
	(segment
		(start 254.991362 -318.482726)
		(end 255.69164 -318.482726)
		(width 0.12954)
		(layer "B.Cu")
		(net "I3C_SPD_DDRABCD_CPU0_LVC1_SCL_6")
	)
	(segment
		(start 254.52578 -319.263268)
		(end 254.52578 -318.948308)
		(width 0.12954)
		(layer "B.Cu")
		(net "I3C_SPD_DDRABCD_CPU0_LVC1_SCL_6")
	)
	(segment
		(start 276.418548 -318.291972)
		(end 276.99335 -318.866774)
		(width 0.12954)
		(layer "F.Cu")
		(net "I3C_SPD_DDRABCD_CPU0_LVC1_SCL_5")
	)
	(segment
		(start 276.418548 -318.082422)
		(end 276.418548 -318.291972)
		(width 0.12954)
		(layer "F.Cu")
		(net "I3C_SPD_DDRABCD_CPU0_LVC1_SCL_5")
	)
	(segment
		(start 276.99335 -318.866774)
		(end 278.711914 -318.866774)
		(width 0.12954)
		(layer "F.Cu")
		(net "I3C_SPD_DDRABCD_CPU0_LVC1_SCL_5")
	)
	(via
		(at 276.418548 -318.082422)
		(size 0.4572)
		(drill 0.254)
		(layers "F.Cu" "B.Cu")
		(net "I3C_SPD_DDRABCD_CPU0_LVC1_SCL_5")
	)
	(segment
		(start 277.048214 -317.857886)
		(end 277.468838 -317.857886)
		(width 0.12954)
		(layer "B.Cu")
		(net "I3C_SPD_DDRABCD_CPU0_LVC1_SCL_5")
	)
	(segment
		(start 276.418548 -318.082422)
		(end 276.65045 -317.85052)
		(width 0.12954)
		(layer "B.Cu")
		(net "I3C_SPD_DDRABCD_CPU0_LVC1_SCL_5")
	)
	(segment
		(start 276.65045 -317.85052)
		(end 277.040848 -317.85052)
		(width 0.12954)
		(layer "B.Cu")
		(net "I3C_SPD_DDRABCD_CPU0_LVC1_SCL_5")
	)
	(segment
		(start 277.040848 -317.85052)
		(end 277.048214 -317.857886)
		(width 0.12954)
		(layer "B.Cu")
		(net "I3C_SPD_DDRABCD_CPU0_LVC1_SCL_5")
	)
	(segment
		(start 269.09014 -318.507364)
		(end 269.44955 -318.866774)
		(width 0.12954)
		(layer "F.Cu")
		(net "I3C_SPD_DDRABCD_CPU0_LVC1_SCL_4")
	)
	(segment
		(start 269.44955 -318.866774)
		(end 271.168114 -318.866774)
		(width 0.12954)
		(layer "F.Cu")
		(net "I3C_SPD_DDRABCD_CPU0_LVC1_SCL_4")
	)
	(segment
		(start 269.09014 -318.077088)
		(end 269.09014 -318.507364)
		(width 0.12954)
		(layer "F.Cu")
		(net "I3C_SPD_DDRABCD_CPU0_LVC1_SCL_4")
	)
	(via
		(at 269.09014 -318.077088)
		(size 0.4572)
		(drill 0.2032)
		(layers "F.Cu" "B.Cu")
		(net "I3C_SPD_DDRABCD_CPU0_LVC1_SCL_4")
	)
	(segment
		(start 269.34287 -317.824358)
		(end 270.780764 -317.824358)
		(width 0.12954)
		(layer "B.Cu")
		(net "I3C_SPD_DDRABCD_CPU0_LVC1_SCL_4")
	)
	(segment
		(start 269.09014 -318.077088)
		(end 269.34287 -317.824358)
		(width 0.12954)
		(layer "B.Cu")
		(net "I3C_SPD_DDRABCD_CPU0_LVC1_SCL_4")
	)
	(segment
		(start 291.735002 -319.302638)
		(end 292.170866 -318.866774)
		(width 0.12954)
		(layer "F.Cu")
		(net "I3C_SPD_DDRABCD_CPU0_LVC1_SCL_3")
	)
	(segment
		(start 292.170866 -318.866774)
		(end 293.799514 -318.866774)
		(width 0.12954)
		(layer "F.Cu")
		(net "I3C_SPD_DDRABCD_CPU0_LVC1_SCL_3")
	)
	(via
		(at 291.735002 -319.302638)
		(size 0.4572)
		(drill 0.2032)
		(layers "F.Cu" "B.Cu")
		(net "I3C_SPD_DDRABCD_CPU0_LVC1_SCL_3")
	)
	(segment
		(start 291.280342 -318.530224)
		(end 292.075362 -317.735204)
		(width 0.12954)
		(layer "B.Cu")
		(net "I3C_SPD_DDRABCD_CPU0_LVC1_SCL_3")
	)
	(segment
		(start 291.735002 -319.302638)
		(end 291.280342 -318.847978)
		(width 0.12954)
		(layer "B.Cu")
		(net "I3C_SPD_DDRABCD_CPU0_LVC1_SCL_3")
	)
	(segment
		(start 292.075362 -317.735204)
		(end 292.075362 -317.603886)
		(width 0.12954)
		(layer "B.Cu")
		(net "I3C_SPD_DDRABCD_CPU0_LVC1_SCL_3")
	)
	(segment
		(start 291.280342 -318.847978)
		(end 291.280342 -318.530224)
		(width 0.12954)
		(layer "B.Cu")
		(net "I3C_SPD_DDRABCD_CPU0_LVC1_SCL_3")
	)
	(segment
		(start 287.751266 -318.866774)
		(end 286.255714 -318.866774)
		(width 0.12954)
		(layer "F.Cu")
		(net "I3C_SPD_DDRABCD_CPU0_LVC1_SCL_2")
	)
	(segment
		(start 287.8328 -318.948308)
		(end 287.751266 -318.866774)
		(width 0.12954)
		(layer "F.Cu")
		(net "I3C_SPD_DDRABCD_CPU0_LVC1_SCL_2")
	)
	(via
		(at 287.8328 -318.948308)
		(size 0.4572)
		(drill 0.254)
		(layers "F.Cu" "B.Cu")
		(net "I3C_SPD_DDRABCD_CPU0_LVC1_SCL_2")
	)
	(segment
		(start 287.8328 -318.948308)
		(end 287.522412 -318.63792)
		(width 0.12954)
		(layer "B.Cu")
		(net "I3C_SPD_DDRABCD_CPU0_LVC1_SCL_2")
	)
	(segment
		(start 287.522412 -317.90005)
		(end 287.499044 -317.876682)
		(width 0.12954)
		(layer "B.Cu")
		(net "I3C_SPD_DDRABCD_CPU0_LVC1_SCL_2")
	)
	(segment
		(start 287.522412 -318.63792)
		(end 287.522412 -317.90005)
		(width 0.12954)
		(layer "B.Cu")
		(net "I3C_SPD_DDRABCD_CPU0_LVC1_SCL_2")
	)
	(segment
		(start 306.864004 -318.540384)
		(end 307.111146 -318.540384)
		(width 0.12954)
		(layer "F.Cu")
		(net "I3C_SPD_DDRABCD_CPU0_LVC1_SCL_1")
	)
	(segment
		(start 307.111146 -318.540384)
		(end 307.899562 -318.866774)
		(width 0.12954)
		(layer "F.Cu")
		(net "I3C_SPD_DDRABCD_CPU0_LVC1_SCL_1")
	)
	(segment
		(start 307.899562 -318.866774)
		(end 308.887114 -318.866774)
		(width 0.12954)
		(layer "F.Cu")
		(net "I3C_SPD_DDRABCD_CPU0_LVC1_SCL_1")
	)
	(segment
		(start 306.590192 -318.814196)
		(end 306.864004 -318.540384)
		(width 0.12954)
		(layer "F.Cu")
		(net "I3C_SPD_DDRABCD_CPU0_LVC1_SCL_1")
	)
	(via
		(at 305.89347 -318.646556)
		(size 0.6604)
		(drill 0.3302)
		(layers "F.Cu" "B.Cu")
		(net "I3C_SPD_DDRABCD_CPU0_LVC1_SCL_1")
	)
	(via
		(at 306.590192 -318.814196)
		(size 0.4572)
		(drill 0.2032)
		(layers "F.Cu" "B.Cu")
		(net "I3C_SPD_DDRABCD_CPU0_LVC1_SCL_1")
	)
	(segment
		(start 306.422552 -318.646556)
		(end 306.590192 -318.814196)
		(width 0.12954)
		(layer "B.Cu")
		(net "I3C_SPD_DDRABCD_CPU0_LVC1_SCL_1")
	)
	(segment
		(start 305.89347 -318.646556)
		(end 305.652932 -318.406018)
		(width 0.12954)
		(layer "B.Cu")
		(net "I3C_SPD_DDRABCD_CPU0_LVC1_SCL_1")
	)
	(segment
		(start 305.652932 -318.406018)
		(end 305.652932 -317.631318)
		(width 0.12954)
		(layer "B.Cu")
		(net "I3C_SPD_DDRABCD_CPU0_LVC1_SCL_1")
	)
	(segment
		(start 305.89347 -318.646556)
		(end 306.422552 -318.646556)
		(width 0.12954)
		(layer "B.Cu")
		(net "I3C_SPD_DDRABCD_CPU0_LVC1_SCL_1")
	)
	(segment
		(start 305.652932 -317.631318)
		(end 305.463956 -317.442342)
		(width 0.12954)
		(layer "B.Cu")
		(net "I3C_SPD_DDRABCD_CPU0_LVC1_SCL_1")
	)
	(segment
		(start 140.54709 -13.600176)
		(end 140.54709 -12.485878)
		(width 0.12954)
		(layer "F.Cu")
		(net "FM_UARTSW_MSB_R")
	)
	(segment
		(start 140.54709 -12.485878)
		(end 140.6271 -12.405868)
		(width 0.12954)
		(layer "F.Cu")
		(net "FM_UARTSW_MSB_R")
	)
	(via
		(at 140.6271 -12.405868)
		(size 0.508)
		(drill 0.254)
		(layers "F.Cu" "B.Cu")
		(net "FM_UARTSW_MSB_R")
	)
	(via
		(at 135.81888 -10.902188)
		(size 0.508)
		(drill 0.254)
		(layers "F.Cu" "B.Cu")
		(net "FM_UARTSW_MSB_R")
	)
	(segment
		(start 135.81888 -9.762998)
		(end 135.81888 -10.902188)
		(width 0.12954)
		(layer "B.Cu")
		(net "FM_UARTSW_MSB_R")
	)
	(segment
		(start 136.41324 -11.496548)
		(end 135.81888 -10.902188)
		(width 0.127)
		(layer "In4.Cu")
		(net "FM_UARTSW_MSB_R")
	)
	(segment
		(start 139.71778 -11.496548)
		(end 136.41324 -11.496548)
		(width 0.127)
		(layer "In4.Cu")
		(net "FM_UARTSW_MSB_R")
	)
	(segment
		(start 140.6271 -12.405868)
		(end 139.71778 -11.496548)
		(width 0.127)
		(layer "In4.Cu")
		(net "FM_UARTSW_MSB_R")
	)
	(segment
		(start 178.1556 -120.175528)
		(end 177.75555 -120.575578)
		(width 0.12954)
		(layer "F.Cu")
		(net "FM_UARTSW_MSB_N")
	)
	(via
		(at 144.17802 -84.317332)
		(size 0.508)
		(drill 0.254)
		(layers "F.Cu" "B.Cu")
		(net "FM_UARTSW_MSB_N")
	)
	(via
		(at 149.1234 -125.435868)
		(size 0.508)
		(drill 0.254)
		(layers "F.Cu" "B.Cu")
		(net "FM_UARTSW_MSB_N")
	)
	(via
		(at 135.81888 -7.821168)
		(size 0.508)
		(drill 0.254)
		(layers "F.Cu" "B.Cu")
		(net "FM_UARTSW_MSB_N")
	)
	(via
		(at 131.885944 -51.410616)
		(size 0.508)
		(drill 0.254)
		(layers "F.Cu" "B.Cu")
		(net "FM_UARTSW_MSB_N")
	)
	(via
		(at 177.75555 -120.575578)
		(size 0.4572)
		(drill 0.254)
		(layers "F.Cu" "B.Cu")
		(net "FM_UARTSW_MSB_N")
	)
	(segment
		(start 135.81888 -8.962898)
		(end 135.81888 -7.821168)
		(width 0.12954)
		(layer "B.Cu")
		(net "FM_UARTSW_MSB_N")
	)
	(segment
		(start 130.55092 -18.476976)
		(end 132.61086 -20.536916)
		(width 0.127)
		(layer "In2.Cu")
		(net "FM_UARTSW_MSB_N")
	)
	(segment
		(start 135.81888 -7.821168)
		(end 135.242808 -7.245096)
		(width 0.127)
		(layer "In2.Cu")
		(net "FM_UARTSW_MSB_N")
	)
	(segment
		(start 144.17802 -92.750386)
		(end 144.17802 -84.317332)
		(width 0.127)
		(layer "In2.Cu")
		(net "FM_UARTSW_MSB_N")
	)
	(segment
		(start 148.938742 -125.25121)
		(end 148.938742 -97.511108)
		(width 0.127)
		(layer "In2.Cu")
		(net "FM_UARTSW_MSB_N")
	)
	(segment
		(start 132.61086 -20.536916)
		(end 132.61086 -24.602186)
		(width 0.127)
		(layer "In2.Cu")
		(net "FM_UARTSW_MSB_N")
	)
	(segment
		(start 131.885944 -44.487592)
		(end 131.885944 -51.410616)
		(width 0.127)
		(layer "In2.Cu")
		(net "FM_UARTSW_MSB_N")
	)
	(segment
		(start 130.55092 -9.85901)
		(end 130.55092 -18.476976)
		(width 0.127)
		(layer "In2.Cu")
		(net "FM_UARTSW_MSB_N")
	)
	(segment
		(start 132.61086 -24.602186)
		(end 133.141974 -25.1333)
		(width 0.127)
		(layer "In2.Cu")
		(net "FM_UARTSW_MSB_N")
	)
	(segment
		(start 132.312156 -37.939726)
		(end 131.545076 -38.706806)
		(width 0.127)
		(layer "In2.Cu")
		(net "FM_UARTSW_MSB_N")
	)
	(segment
		(start 133.164834 -7.245096)
		(end 130.55092 -9.85901)
		(width 0.127)
		(layer "In2.Cu")
		(net "FM_UARTSW_MSB_N")
	)
	(segment
		(start 149.1234 -125.435868)
		(end 148.938742 -125.25121)
		(width 0.127)
		(layer "In2.Cu")
		(net "FM_UARTSW_MSB_N")
	)
	(segment
		(start 132.312156 -28.331414)
		(end 132.312156 -37.939726)
		(width 0.127)
		(layer "In2.Cu")
		(net "FM_UARTSW_MSB_N")
	)
	(segment
		(start 135.242808 -7.245096)
		(end 133.164834 -7.245096)
		(width 0.127)
		(layer "In2.Cu")
		(net "FM_UARTSW_MSB_N")
	)
	(segment
		(start 148.938742 -97.511108)
		(end 144.17802 -92.750386)
		(width 0.127)
		(layer "In2.Cu")
		(net "FM_UARTSW_MSB_N")
	)
	(segment
		(start 133.141974 -25.1333)
		(end 133.141974 -27.501596)
		(width 0.127)
		(layer "In2.Cu")
		(net "FM_UARTSW_MSB_N")
	)
	(segment
		(start 133.141974 -27.501596)
		(end 132.312156 -28.331414)
		(width 0.127)
		(layer "In2.Cu")
		(net "FM_UARTSW_MSB_N")
	)
	(segment
		(start 131.545076 -38.706806)
		(end 131.545076 -44.146724)
		(width 0.127)
		(layer "In2.Cu")
		(net "FM_UARTSW_MSB_N")
	)
	(segment
		(start 131.545076 -44.146724)
		(end 131.885944 -44.487592)
		(width 0.127)
		(layer "In2.Cu")
		(net "FM_UARTSW_MSB_N")
	)
	(segment
		(start 149.2885 -125.600968)
		(end 149.1234 -125.435868)
		(width 0.127)
		(layer "In6.Cu")
		(net "FM_UARTSW_MSB_N")
	)
	(segment
		(start 177.16754 -121.806208)
		(end 173.293532 -121.806208)
		(width 0.127)
		(layer "In6.Cu")
		(net "FM_UARTSW_MSB_N")
	)
	(segment
		(start 177.75555 -121.218198)
		(end 177.16754 -121.806208)
		(width 0.127)
		(layer "In6.Cu")
		(net "FM_UARTSW_MSB_N")
	)
	(segment
		(start 167.26916 -126.0729)
		(end 167.07612 -125.87986)
		(width 0.127)
		(layer "In6.Cu")
		(net "FM_UARTSW_MSB_N")
	)
	(segment
		(start 149.318218 -125.600968)
		(end 149.2885 -125.600968)
		(width 0.127)
		(layer "In6.Cu")
		(net "FM_UARTSW_MSB_N")
	)
	(segment
		(start 173.293532 -121.806208)
		(end 169.02684 -126.0729)
		(width 0.127)
		(layer "In6.Cu")
		(net "FM_UARTSW_MSB_N")
	)
	(segment
		(start 169.02684 -126.0729)
		(end 167.26916 -126.0729)
		(width 0.127)
		(layer "In6.Cu")
		(net "FM_UARTSW_MSB_N")
	)
	(segment
		(start 149.59711 -125.87986)
		(end 149.318218 -125.600968)
		(width 0.127)
		(layer "In6.Cu")
		(net "FM_UARTSW_MSB_N")
	)
	(segment
		(start 167.07612 -125.87986)
		(end 149.59711 -125.87986)
		(width 0.127)
		(layer "In6.Cu")
		(net "FM_UARTSW_MSB_N")
	)
	(segment
		(start 177.75555 -120.575578)
		(end 177.75555 -121.218198)
		(width 0.127)
		(layer "In6.Cu")
		(net "FM_UARTSW_MSB_N")
	)
	(segment
		(start 137.85342 -62.186058)
		(end 139.01801 -62.186058)
		(width 0.127)
		(layer "In11.Cu")
		(net "FM_UARTSW_MSB_N")
	)
	(segment
		(start 145.349722 -68.51777)
		(end 145.349722 -76.683108)
		(width 0.127)
		(layer "In11.Cu")
		(net "FM_UARTSW_MSB_N")
	)
	(segment
		(start 131.885944 -51.410616)
		(end 131.885944 -52.951888)
		(width 0.127)
		(layer "In11.Cu")
		(net "FM_UARTSW_MSB_N")
	)
	(segment
		(start 139.01801 -62.186058)
		(end 145.349722 -68.51777)
		(width 0.127)
		(layer "In11.Cu")
		(net "FM_UARTSW_MSB_N")
	)
	(segment
		(start 136.06145 -57.127394)
		(end 136.06145 -60.394088)
		(width 0.127)
		(layer "In11.Cu")
		(net "FM_UARTSW_MSB_N")
	)
	(segment
		(start 144.17802 -77.85481)
		(end 144.17802 -84.317332)
		(width 0.127)
		(layer "In11.Cu")
		(net "FM_UARTSW_MSB_N")
	)
	(segment
		(start 136.06145 -60.394088)
		(end 137.85342 -62.186058)
		(width 0.127)
		(layer "In11.Cu")
		(net "FM_UARTSW_MSB_N")
	)
	(segment
		(start 131.885944 -52.951888)
		(end 136.06145 -57.127394)
		(width 0.127)
		(layer "In11.Cu")
		(net "FM_UARTSW_MSB_N")
	)
	(segment
		(start 145.349722 -76.683108)
		(end 144.17802 -77.85481)
		(width 0.127)
		(layer "In11.Cu")
		(net "FM_UARTSW_MSB_N")
	)
	(segment
		(start 138.746992 -13.600176)
		(end 138.746992 -11.28268)
		(width 0.12954)
		(layer "F.Cu")
		(net "FM_UARTSW_LSB_R")
	)
	(segment
		(start 138.746992 -11.28268)
		(end 138.35888 -10.894568)
		(width 0.12954)
		(layer "F.Cu")
		(net "FM_UARTSW_LSB_R")
	)
	(via
		(at 138.35888 -10.894568)
		(size 0.508)
		(drill 0.254)
		(layers "F.Cu" "B.Cu")
		(net "FM_UARTSW_LSB_R")
	)
	(via
		(at 134.54888 -10.935716)
		(size 0.508)
		(drill 0.254)
		(layers "F.Cu" "B.Cu")
		(net "FM_UARTSW_LSB_R")
	)
	(segment
		(start 134.54888 -9.762998)
		(end 134.54888 -10.935716)
		(width 0.12954)
		(layer "B.Cu")
		(net "FM_UARTSW_LSB_R")
	)
	(segment
		(start 138.35888 -10.894568)
		(end 137.66546 -10.201148)
		(width 0.127)
		(layer "In4.Cu")
		(net "FM_UARTSW_LSB_R")
	)
	(segment
		(start 135.283448 -10.201148)
		(end 134.54888 -10.935716)
		(width 0.127)
		(layer "In4.Cu")
		(net "FM_UARTSW_LSB_R")
	)
	(segment
		(start 137.66546 -10.201148)
		(end 135.283448 -10.201148)
		(width 0.127)
		(layer "In4.Cu")
		(net "FM_UARTSW_LSB_R")
	)
	(segment
		(start 178.1556 -119.375428)
		(end 177.75555 -119.775478)
		(width 0.12954)
		(layer "F.Cu")
		(net "FM_UARTSW_LSB_N")
	)
	(via
		(at 149.1234 -126.070868)
		(size 0.508)
		(drill 0.254)
		(layers "F.Cu" "B.Cu")
		(net "FM_UARTSW_LSB_N")
	)
	(via
		(at 132.673598 -51.410616)
		(size 0.508)
		(drill 0.254)
		(layers "F.Cu" "B.Cu")
		(net "FM_UARTSW_LSB_N")
	)
	(via
		(at 144.89176 -84.31022)
		(size 0.508)
		(drill 0.254)
		(layers "F.Cu" "B.Cu")
		(net "FM_UARTSW_LSB_N")
	)
	(via
		(at 177.75555 -119.775478)
		(size 0.4572)
		(drill 0.254)
		(layers "F.Cu" "B.Cu")
		(net "FM_UARTSW_LSB_N")
	)
	(via
		(at 134.54888 -7.821168)
		(size 0.508)
		(drill 0.254)
		(layers "F.Cu" "B.Cu")
		(net "FM_UARTSW_LSB_N")
	)
	(segment
		(start 134.54888 -8.962898)
		(end 134.54888 -7.821168)
		(width 0.12954)
		(layer "B.Cu")
		(net "FM_UARTSW_LSB_N")
	)
	(segment
		(start 130.930396 -10.196068)
		(end 130.930396 -18.31975)
		(width 0.127)
		(layer "In2.Cu")
		(net "FM_UARTSW_LSB_N")
	)
	(segment
		(start 149.620224 -124.921264)
		(end 149.620224 -125.702314)
		(width 0.127)
		(layer "In2.Cu")
		(net "FM_UARTSW_LSB_N")
	)
	(segment
		(start 132.180076 -38.96995)
		(end 132.180076 -43.88358)
		(width 0.127)
		(layer "In2.Cu")
		(net "FM_UARTSW_LSB_N")
	)
	(segment
		(start 135.09498 -22.484334)
		(end 135.09498 -29.03982)
		(width 0.127)
		(layer "In2.Cu")
		(net "FM_UARTSW_LSB_N")
	)
	(segment
		(start 132.673598 -44.377102)
		(end 132.673598 -51.410616)
		(width 0.127)
		(layer "In2.Cu")
		(net "FM_UARTSW_LSB_N")
	)
	(segment
		(start 149.25167 -126.070868)
		(end 149.1234 -126.070868)
		(width 0.127)
		(layer "In2.Cu")
		(net "FM_UARTSW_LSB_N")
	)
	(segment
		(start 144.64792 -85.374988)
		(end 144.64792 -92.299028)
		(width 0.127)
		(layer "In2.Cu")
		(net "FM_UARTSW_LSB_N")
	)
	(segment
		(start 149.620224 -125.702314)
		(end 149.25167 -126.070868)
		(width 0.127)
		(layer "In2.Cu")
		(net "FM_UARTSW_LSB_N")
	)
	(segment
		(start 134.54888 -7.821168)
		(end 133.305296 -7.821168)
		(width 0.127)
		(layer "In2.Cu")
		(net "FM_UARTSW_LSB_N")
	)
	(segment
		(start 135.09498 -29.03982)
		(end 132.691632 -31.443168)
		(width 0.127)
		(layer "In2.Cu")
		(net "FM_UARTSW_LSB_N")
	)
	(segment
		(start 144.89176 -85.131148)
		(end 144.64792 -85.374988)
		(width 0.127)
		(layer "In2.Cu")
		(net "FM_UARTSW_LSB_N")
	)
	(segment
		(start 144.64792 -92.299028)
		(end 149.307804 -96.958912)
		(width 0.127)
		(layer "In2.Cu")
		(net "FM_UARTSW_LSB_N")
	)
	(segment
		(start 144.89176 -84.31022)
		(end 144.89176 -85.131148)
		(width 0.127)
		(layer "In2.Cu")
		(net "FM_UARTSW_LSB_N")
	)
	(segment
		(start 132.691632 -31.443168)
		(end 132.691632 -38.458394)
		(width 0.127)
		(layer "In2.Cu")
		(net "FM_UARTSW_LSB_N")
	)
	(segment
		(start 149.307804 -96.958912)
		(end 149.307804 -124.608844)
		(width 0.127)
		(layer "In2.Cu")
		(net "FM_UARTSW_LSB_N")
	)
	(segment
		(start 132.180076 -43.88358)
		(end 132.673598 -44.377102)
		(width 0.127)
		(layer "In2.Cu")
		(net "FM_UARTSW_LSB_N")
	)
	(segment
		(start 133.305296 -7.821168)
		(end 130.930396 -10.196068)
		(width 0.127)
		(layer "In2.Cu")
		(net "FM_UARTSW_LSB_N")
	)
	(segment
		(start 149.307804 -124.608844)
		(end 149.620224 -124.921264)
		(width 0.127)
		(layer "In2.Cu")
		(net "FM_UARTSW_LSB_N")
	)
	(segment
		(start 132.691632 -38.458394)
		(end 132.180076 -38.96995)
		(width 0.127)
		(layer "In2.Cu")
		(net "FM_UARTSW_LSB_N")
	)
	(segment
		(start 130.930396 -18.31975)
		(end 135.09498 -22.484334)
		(width 0.127)
		(layer "In2.Cu")
		(net "FM_UARTSW_LSB_N")
	)
	(segment
		(start 178.19624 -120.216168)
		(end 178.19624 -121.239788)
		(width 0.127)
		(layer "In6.Cu")
		(net "FM_UARTSW_LSB_N")
	)
	(segment
		(start 173.505368 -123.8631)
		(end 172.0088 -123.8631)
		(width 0.127)
		(layer "In6.Cu")
		(net "FM_UARTSW_LSB_N")
	)
	(segment
		(start 178.19624 -121.239788)
		(end 177.2158 -122.220228)
		(width 0.127)
		(layer "In6.Cu")
		(net "FM_UARTSW_LSB_N")
	)
	(segment
		(start 169.40784 -126.46406)
		(end 167.121586 -126.46406)
		(width 0.127)
		(layer "In6.Cu")
		(net "FM_UARTSW_LSB_N")
	)
	(segment
		(start 167.121586 -126.46406)
		(end 166.867586 -126.21006)
		(width 0.127)
		(layer "In6.Cu")
		(net "FM_UARTSW_LSB_N")
	)
	(segment
		(start 177.2158 -122.220228)
		(end 175.14824 -122.220228)
		(width 0.127)
		(layer "In6.Cu")
		(net "FM_UARTSW_LSB_N")
	)
	(segment
		(start 177.75555 -119.775478)
		(end 178.19624 -120.216168)
		(width 0.127)
		(layer "In6.Cu")
		(net "FM_UARTSW_LSB_N")
	)
	(segment
		(start 175.14824 -122.220228)
		(end 173.505368 -123.8631)
		(width 0.127)
		(layer "In6.Cu")
		(net "FM_UARTSW_LSB_N")
	)
	(segment
		(start 166.867586 -126.21006)
		(end 149.262592 -126.21006)
		(width 0.127)
		(layer "In6.Cu")
		(net "FM_UARTSW_LSB_N")
	)
	(segment
		(start 172.0088 -123.8631)
		(end 169.40784 -126.46406)
		(width 0.127)
		(layer "In6.Cu")
		(net "FM_UARTSW_LSB_N")
	)
	(segment
		(start 149.262592 -126.21006)
		(end 149.1234 -126.070868)
		(width 0.127)
		(layer "In6.Cu")
		(net "FM_UARTSW_LSB_N")
	)
	(segment
		(start 132.673598 -51.410616)
		(end 132.673598 -52.841398)
		(width 0.127)
		(layer "In11.Cu")
		(net "FM_UARTSW_LSB_N")
	)
	(segment
		(start 138.116564 -61.551058)
		(end 139.281154 -61.551058)
		(width 0.127)
		(layer "In11.Cu")
		(net "FM_UARTSW_LSB_N")
	)
	(segment
		(start 136.69645 -56.86425)
		(end 136.69645 -60.130944)
		(width 0.127)
		(layer "In11.Cu")
		(net "FM_UARTSW_LSB_N")
	)
	(segment
		(start 144.89176 -78.039214)
		(end 144.89176 -84.31022)
		(width 0.127)
		(layer "In11.Cu")
		(net "FM_UARTSW_LSB_N")
	)
	(segment
		(start 139.281154 -61.551058)
		(end 145.984722 -68.254626)
		(width 0.127)
		(layer "In11.Cu")
		(net "FM_UARTSW_LSB_N")
	)
	(segment
		(start 145.984722 -76.946252)
		(end 144.89176 -78.039214)
		(width 0.127)
		(layer "In11.Cu")
		(net "FM_UARTSW_LSB_N")
	)
	(segment
		(start 136.69645 -60.130944)
		(end 138.116564 -61.551058)
		(width 0.127)
		(layer "In11.Cu")
		(net "FM_UARTSW_LSB_N")
	)
	(segment
		(start 145.984722 -68.254626)
		(end 145.984722 -76.946252)
		(width 0.127)
		(layer "In11.Cu")
		(net "FM_UARTSW_LSB_N")
	)
	(segment
		(start 132.673598 -52.841398)
		(end 136.69645 -56.86425)
		(width 0.127)
		(layer "In11.Cu")
		(net "FM_UARTSW_LSB_N")
	)
	(segment
		(start 175.82896 -15.458948)
		(end 175.38954 -15.019528)
		(width 0.12954)
		(layer "F.Cu")
		(net "FM_SOL_UART_CH_SEL_R")
	)
	(segment
		(start 149.68982 -21.575014)
		(end 149.68982 -22.33803)
		(width 0.12954)
		(layer "F.Cu")
		(net "FM_SOL_UART_CH_SEL_R")
	)
	(segment
		(start 183.262016 -16.550132)
		(end 183.262016 -15.633954)
		(width 0.12954)
		(layer "F.Cu")
		(net "FM_SOL_UART_CH_SEL_R")
	)
	(segment
		(start 183.08701 -15.458948)
		(end 175.82896 -15.458948)
		(width 0.12954)
		(layer "F.Cu")
		(net "FM_SOL_UART_CH_SEL_R")
	)
	(segment
		(start 150.03272 -21.232114)
		(end 149.68982 -21.575014)
		(width 0.12954)
		(layer "F.Cu")
		(net "FM_SOL_UART_CH_SEL_R")
	)
	(segment
		(start 183.262016 -15.633954)
		(end 183.08701 -15.458948)
		(width 0.12954)
		(layer "F.Cu")
		(net "FM_SOL_UART_CH_SEL_R")
	)
	(via
		(at 150.03272 -21.232114)
		(size 0.508)
		(drill 0.254)
		(layers "F.Cu" "B.Cu")
		(net "FM_SOL_UART_CH_SEL_R")
	)
	(via
		(at 175.38954 -15.019528)
		(size 0.508)
		(drill 0.254)
		(layers "F.Cu" "B.Cu")
		(net "FM_SOL_UART_CH_SEL_R")
	)
	(segment
		(start 168.28516 -15.458948)
		(end 174.95012 -15.458948)
		(width 0.127)
		(layer "In13.Cu")
		(net "FM_SOL_UART_CH_SEL_R")
	)
	(segment
		(start 147.609306 -21.232114)
		(end 145.73504 -19.357848)
		(width 0.127)
		(layer "In13.Cu")
		(net "FM_SOL_UART_CH_SEL_R")
	)
	(segment
		(start 163.36264 -14.409928)
		(end 167.23614 -14.409928)
		(width 0.127)
		(layer "In13.Cu")
		(net "FM_SOL_UART_CH_SEL_R")
	)
	(segment
		(start 147.53082 -12.794488)
		(end 149.12721 -12.794488)
		(width 0.127)
		(layer "In13.Cu")
		(net "FM_SOL_UART_CH_SEL_R")
	)
	(segment
		(start 150.03272 -21.232114)
		(end 147.609306 -21.232114)
		(width 0.127)
		(layer "In13.Cu")
		(net "FM_SOL_UART_CH_SEL_R")
	)
	(segment
		(start 145.73504 -14.590268)
		(end 147.53082 -12.794488)
		(width 0.127)
		(layer "In13.Cu")
		(net "FM_SOL_UART_CH_SEL_R")
	)
	(segment
		(start 162.2171 -15.555468)
		(end 163.36264 -14.409928)
		(width 0.127)
		(layer "In13.Cu")
		(net "FM_SOL_UART_CH_SEL_R")
	)
	(segment
		(start 149.12721 -12.794488)
		(end 151.88819 -15.555468)
		(width 0.127)
		(layer "In13.Cu")
		(net "FM_SOL_UART_CH_SEL_R")
	)
	(segment
		(start 167.23614 -14.409928)
		(end 168.28516 -15.458948)
		(width 0.127)
		(layer "In13.Cu")
		(net "FM_SOL_UART_CH_SEL_R")
	)
	(segment
		(start 174.95012 -15.458948)
		(end 175.38954 -15.019528)
		(width 0.127)
		(layer "In13.Cu")
		(net "FM_SOL_UART_CH_SEL_R")
	)
	(segment
		(start 151.88819 -15.555468)
		(end 162.2171 -15.555468)
		(width 0.127)
		(layer "In13.Cu")
		(net "FM_SOL_UART_CH_SEL_R")
	)
	(segment
		(start 145.73504 -19.357848)
		(end 145.73504 -14.590268)
		(width 0.127)
		(layer "In13.Cu")
		(net "FM_SOL_UART_CH_SEL_R")
	)
	(segment
		(start 177.60188 -130.978148)
		(end 177.60188 -125.821948)
		(width 0.12954)
		(layer "F.Cu")
		(net "FM_SOL_UART_CH_SEL")
	)
	(segment
		(start 177.29708 -125.517148)
		(end 177.29708 -121.834148)
		(width 0.12954)
		(layer "F.Cu")
		(net "FM_SOL_UART_CH_SEL")
	)
	(segment
		(start 142.25016 -28.920948)
		(end 144.72793 -28.920948)
		(width 0.12954)
		(layer "F.Cu")
		(net "FM_SOL_UART_CH_SEL")
	)
	(segment
		(start 149.68982 -23.959058)
		(end 149.68982 -23.13813)
		(width 0.12954)
		(layer "F.Cu")
		(net "FM_SOL_UART_CH_SEL")
	)
	(segment
		(start 177.60188 -125.821948)
		(end 177.29708 -125.517148)
		(width 0.12954)
		(layer "F.Cu")
		(net "FM_SOL_UART_CH_SEL")
	)
	(segment
		(start 140.012674 -31.158434)
		(end 142.25016 -28.920948)
		(width 0.12954)
		(layer "F.Cu")
		(net "FM_SOL_UART_CH_SEL")
	)
	(segment
		(start 176.58588 -131.994148)
		(end 177.60188 -130.978148)
		(width 0.12954)
		(layer "F.Cu")
		(net "FM_SOL_UART_CH_SEL")
	)
	(segment
		(start 177.29708 -121.834148)
		(end 177.355754 -121.775474)
		(width 0.12954)
		(layer "F.Cu")
		(net "FM_SOL_UART_CH_SEL")
	)
	(segment
		(start 144.72793 -28.920948)
		(end 149.68982 -23.959058)
		(width 0.12954)
		(layer "F.Cu")
		(net "FM_SOL_UART_CH_SEL")
	)
	(via
		(at 176.58588 -131.994148)
		(size 0.508)
		(drill 0.254)
		(layers "F.Cu" "B.Cu")
		(net "FM_SOL_UART_CH_SEL")
	)
	(via
		(at 143.20266 -84.288884)
		(size 0.508)
		(drill 0.254)
		(layers "F.Cu" "B.Cu")
		(net "FM_SOL_UART_CH_SEL")
	)
	(via
		(at 140.012674 -31.158434)
		(size 0.508)
		(drill 0.254)
		(layers "F.Cu" "B.Cu")
		(net "FM_SOL_UART_CH_SEL")
	)
	(via
		(at 143.073374 -137.950702)
		(size 0.508)
		(drill 0.254)
		(layers "F.Cu" "B.Cu")
		(net "FM_SOL_UART_CH_SEL")
	)
	(via
		(at 140.332206 -53.853588)
		(size 0.508)
		(drill 0.254)
		(layers "F.Cu" "B.Cu")
		(net "FM_SOL_UART_CH_SEL")
	)
	(via
		(at 142.576296 -76.491846)
		(size 0.508)
		(drill 0.254)
		(layers "F.Cu" "B.Cu")
		(net "FM_SOL_UART_CH_SEL")
	)
	(segment
		(start 140.332206 -55.30215)
		(end 140.332206 -53.853588)
		(width 0.12954)
		(layer "B.Cu")
		(net "FM_SOL_UART_CH_SEL")
	)
	(segment
		(start 157.772862 -140.1318)
		(end 170.566588 -140.1318)
		(width 0.12954)
		(layer "B.Cu")
		(net "FM_SOL_UART_CH_SEL")
	)
	(segment
		(start 175.837596 -134.860792)
		(end 175.837596 -134.09549)
		(width 0.12954)
		(layer "B.Cu")
		(net "FM_SOL_UART_CH_SEL")
	)
	(segment
		(start 141.695678 -56.665622)
		(end 140.332206 -55.30215)
		(width 0.12954)
		(layer "B.Cu")
		(net "FM_SOL_UART_CH_SEL")
	)
	(segment
		(start 141.695678 -75.611228)
		(end 141.695678 -56.665622)
		(width 0.12954)
		(layer "B.Cu")
		(net "FM_SOL_UART_CH_SEL")
	)
	(segment
		(start 170.566588 -140.1318)
		(end 175.837596 -134.860792)
		(width 0.12954)
		(layer "B.Cu")
		(net "FM_SOL_UART_CH_SEL")
	)
	(segment
		(start 175.837596 -134.09549)
		(end 176.58588 -133.347206)
		(width 0.12954)
		(layer "B.Cu")
		(net "FM_SOL_UART_CH_SEL")
	)
	(segment
		(start 155.591764 -137.950702)
		(end 157.772862 -140.1318)
		(width 0.12954)
		(layer "B.Cu")
		(net "FM_SOL_UART_CH_SEL")
	)
	(segment
		(start 143.073374 -137.950702)
		(end 155.591764 -137.950702)
		(width 0.12954)
		(layer "B.Cu")
		(net "FM_SOL_UART_CH_SEL")
	)
	(segment
		(start 176.58588 -133.347206)
		(end 176.58588 -131.994148)
		(width 0.12954)
		(layer "B.Cu")
		(net "FM_SOL_UART_CH_SEL")
	)
	(segment
		(start 142.576296 -76.491846)
		(end 141.695678 -75.611228)
		(width 0.12954)
		(layer "B.Cu")
		(net "FM_SOL_UART_CH_SEL")
	)
	(segment
		(start 143.258032 -111.29264)
		(end 143.258032 -135.934958)
		(width 0.127)
		(layer "In2.Cu")
		(net "FM_SOL_UART_CH_SEL")
	)
	(segment
		(start 143.073374 -137.703052)
		(end 143.073374 -137.950702)
		(width 0.127)
		(layer "In2.Cu")
		(net "FM_SOL_UART_CH_SEL")
	)
	(segment
		(start 143.726662 -137.049764)
		(end 143.073374 -137.703052)
		(width 0.127)
		(layer "In2.Cu")
		(net "FM_SOL_UART_CH_SEL")
	)
	(segment
		(start 143.726662 -136.403588)
		(end 143.726662 -137.049764)
		(width 0.127)
		(layer "In2.Cu")
		(net "FM_SOL_UART_CH_SEL")
	)
	(segment
		(start 143.20266 -96.987106)
		(end 146.808444 -100.59289)
		(width 0.127)
		(layer "In2.Cu")
		(net "FM_SOL_UART_CH_SEL")
	)
	(segment
		(start 143.20266 -84.288884)
		(end 143.20266 -96.987106)
		(width 0.127)
		(layer "In2.Cu")
		(net "FM_SOL_UART_CH_SEL")
	)
	(segment
		(start 143.258032 -135.934958)
		(end 143.726662 -136.403588)
		(width 0.127)
		(layer "In2.Cu")
		(net "FM_SOL_UART_CH_SEL")
	)
	(segment
		(start 146.808444 -100.59289)
		(end 146.808444 -107.742228)
		(width 0.127)
		(layer "In2.Cu")
		(net "FM_SOL_UART_CH_SEL")
	)
	(segment
		(start 146.808444 -107.742228)
		(end 143.258032 -111.29264)
		(width 0.127)
		(layer "In2.Cu")
		(net "FM_SOL_UART_CH_SEL")
	)
	(segment
		(start 143.231108 -81.890108)
		(end 142.576296 -81.235296)
		(width 0.127)
		(layer "In11.Cu")
		(net "FM_SOL_UART_CH_SEL")
	)
	(segment
		(start 140.332206 -53.853588)
		(end 138.542776 -52.064158)
		(width 0.127)
		(layer "In11.Cu")
		(net "FM_SOL_UART_CH_SEL")
	)
	(segment
		(start 143.20266 -84.288884)
		(end 143.231108 -84.260436)
		(width 0.127)
		(layer "In11.Cu")
		(net "FM_SOL_UART_CH_SEL")
	)
	(segment
		(start 138.542776 -52.064158)
		(end 138.542776 -32.323278)
		(width 0.127)
		(layer "In11.Cu")
		(net "FM_SOL_UART_CH_SEL")
	)
	(segment
		(start 139.70762 -31.158434)
		(end 140.012674 -31.158434)
		(width 0.127)
		(layer "In11.Cu")
		(net "FM_SOL_UART_CH_SEL")
	)
	(segment
		(start 138.542776 -32.323278)
		(end 139.70762 -31.158434)
		(width 0.127)
		(layer "In11.Cu")
		(net "FM_SOL_UART_CH_SEL")
	)
	(segment
		(start 142.576296 -81.235296)
		(end 142.576296 -76.491846)
		(width 0.127)
		(layer "In11.Cu")
		(net "FM_SOL_UART_CH_SEL")
	)
	(segment
		(start 143.231108 -84.260436)
		(end 143.231108 -81.890108)
		(width 0.127)
		(layer "In11.Cu")
		(net "FM_SOL_UART_CH_SEL")
	)
	(segment
		(start 143.696182 -65.837308)
		(end 144.181576 -65.351914)
		(width 0.12954)
		(layer "F.Cu")
		(net "FM_PS_EN_PLD_BUF1_R1")
	)
	(segment
		(start 141.640306 -65.329308)
		(end 142.148306 -65.837308)
		(width 0.12954)
		(layer "F.Cu")
		(net "FM_PS_EN_PLD_BUF1_R1")
	)
	(segment
		(start 142.148306 -65.837308)
		(end 142.891256 -65.837308)
		(width 0.12954)
		(layer "F.Cu")
		(net "FM_PS_EN_PLD_BUF1_R1")
	)
	(segment
		(start 142.891256 -65.837308)
		(end 143.696182 -65.837308)
		(width 0.12954)
		(layer "F.Cu")
		(net "FM_PS_EN_PLD_BUF1_R1")
	)
	(via
		(at 142.891256 -65.837308)
		(size 0.762)
		(drill 0.381)
		(layers "F.Cu" "B.Cu")
		(net "FM_PS_EN_PLD_BUF1_R1")
	)
	(segment
		(start 141.10208 -78.696058)
		(end 141.22019 -78.696058)
		(width 0.12954)
		(layer "F.Cu")
		(net "FM_PS_EN_PLD_BUF1")
	)
	(segment
		(start 141.674596 -79.150464)
		(end 141.79296 -79.150464)
		(width 0.12954)
		(layer "F.Cu")
		(net "FM_PS_EN_PLD_BUF1")
	)
	(segment
		(start 141.22019 -78.696058)
		(end 141.674596 -79.150464)
		(width 0.12954)
		(layer "F.Cu")
		(net "FM_PS_EN_PLD_BUF1")
	)
	(segment
		(start 143.69923 -79.150464)
		(end 141.79296 -79.150464)
		(width 0.12954)
		(layer "F.Cu")
		(net "FM_PS_EN_PLD_BUF1")
	)
	(segment
		(start 140.840206 -65.329308)
		(end 140.230606 -65.329308)
		(width 0.12954)
		(layer "F.Cu")
		(net "FM_PS_EN_PLD_BUF1")
	)
	(segment
		(start 143.894556 -78.955138)
		(end 143.69923 -79.150464)
		(width 0.12954)
		(layer "F.Cu")
		(net "FM_PS_EN_PLD_BUF1")
	)
	(via
		(at 141.10208 -78.696058)
		(size 0.508)
		(drill 0.254)
		(layers "F.Cu" "B.Cu")
		(net "FM_PS_EN_PLD_BUF1")
	)
	(via
		(at 140.230606 -65.329308)
		(size 0.508)
		(drill 0.254)
		(layers "F.Cu" "B.Cu")
		(net "FM_PS_EN_PLD_BUF1")
	)
	(segment
		(start 139.8016 -65.758314)
		(end 140.230606 -65.329308)
		(width 0.127)
		(layer "In2.Cu")
		(net "FM_PS_EN_PLD_BUF1")
	)
	(segment
		(start 140.330936 -78.696058)
		(end 139.8016 -78.166722)
		(width 0.127)
		(layer "In2.Cu")
		(net "FM_PS_EN_PLD_BUF1")
	)
	(segment
		(start 139.8016 -78.166722)
		(end 139.8016 -65.758314)
		(width 0.127)
		(layer "In2.Cu")
		(net "FM_PS_EN_PLD_BUF1")
	)
	(segment
		(start 141.10208 -78.696058)
		(end 140.330936 -78.696058)
		(width 0.127)
		(layer "In2.Cu")
		(net "FM_PS_EN_PLD_BUF1")
	)
	(segment
		(start 337.581748 -39.992046)
		(end 338.120736 -39.992046)
		(width 0.12954)
		(layer "F.Cu")
		(net "FM_M2_E1S_E6_PEDET")
	)
	(via
		(at 337.581748 -39.992046)
		(size 0.4572)
		(drill 0.2032)
		(layers "F.Cu" "B.Cu")
		(net "FM_M2_E1S_E6_PEDET")
	)
	(via
		(at 338.494116 -39.230808)
		(size 0.6604)
		(drill 0.3302)
		(layers "F.Cu" "B.Cu")
		(net "FM_M2_E1S_E6_PEDET")
	)
	(via
		(at 368.36858 -36.327588)
		(size 0.762)
		(drill 0.254)
		(layers "F.Cu" "B.Cu")
		(net "FM_M2_E1S_E6_PEDET")
	)
	(segment
		(start 337.895946 -39.677848)
		(end 338.047076 -39.677848)
		(width 0.12954)
		(layer "B.Cu")
		(net "FM_M2_E1S_E6_PEDET")
	)
	(segment
		(start 372.01983 -36.921948)
		(end 371.38483 -36.286948)
		(width 0.12954)
		(layer "B.Cu")
		(net "FM_M2_E1S_E6_PEDET")
	)
	(segment
		(start 368.36858 -36.622228)
		(end 368.6683 -36.921948)
		(width 0.12954)
		(layer "B.Cu")
		(net "FM_M2_E1S_E6_PEDET")
	)
	(segment
		(start 371.38483 -36.286948)
		(end 369.73383 -36.286948)
		(width 0.12954)
		(layer "B.Cu")
		(net "FM_M2_E1S_E6_PEDET")
	)
	(segment
		(start 368.36858 -36.327588)
		(end 368.36858 -36.622228)
		(width 0.12954)
		(layer "B.Cu")
		(net "FM_M2_E1S_E6_PEDET")
	)
	(segment
		(start 338.047076 -39.677848)
		(end 338.494116 -39.230808)
		(width 0.12954)
		(layer "B.Cu")
		(net "FM_M2_E1S_E6_PEDET")
	)
	(segment
		(start 368.6683 -36.921948)
		(end 369.09883 -36.921948)
		(width 0.12954)
		(layer "B.Cu")
		(net "FM_M2_E1S_E6_PEDET")
	)
	(segment
		(start 369.73383 -36.286948)
		(end 369.09883 -36.921948)
		(width 0.12954)
		(layer "B.Cu")
		(net "FM_M2_E1S_E6_PEDET")
	)
	(segment
		(start 337.581748 -39.992046)
		(end 337.895946 -39.677848)
		(width 0.12954)
		(layer "B.Cu")
		(net "FM_M2_E1S_E6_PEDET")
	)
	(segment
		(start 344.82786 -36.302188)
		(end 342.165686 -36.302188)
		(width 0.127)
		(layer "In2.Cu")
		(net "FM_M2_E1S_E6_PEDET")
	)
	(segment
		(start 340.503256 -37.070538)
		(end 337.581748 -39.992046)
		(width 0.127)
		(layer "In2.Cu")
		(net "FM_M2_E1S_E6_PEDET")
	)
	(segment
		(start 354.26904 -36.327588)
		(end 353.808792 -35.86734)
		(width 0.127)
		(layer "In2.Cu")
		(net "FM_M2_E1S_E6_PEDET")
	)
	(segment
		(start 351.74682 -35.86734)
		(end 348.934532 -38.679628)
		(width 0.127)
		(layer "In2.Cu")
		(net "FM_M2_E1S_E6_PEDET")
	)
	(segment
		(start 342.165686 -36.302188)
		(end 341.397336 -37.070538)
		(width 0.127)
		(layer "In2.Cu")
		(net "FM_M2_E1S_E6_PEDET")
	)
	(segment
		(start 368.36858 -36.327588)
		(end 354.26904 -36.327588)
		(width 0.127)
		(layer "In2.Cu")
		(net "FM_M2_E1S_E6_PEDET")
	)
	(segment
		(start 341.397336 -37.070538)
		(end 340.503256 -37.070538)
		(width 0.127)
		(layer "In2.Cu")
		(net "FM_M2_E1S_E6_PEDET")
	)
	(segment
		(start 347.2053 -38.679628)
		(end 344.82786 -36.302188)
		(width 0.127)
		(layer "In2.Cu")
		(net "FM_M2_E1S_E6_PEDET")
	)
	(segment
		(start 353.808792 -35.86734)
		(end 351.74682 -35.86734)
		(width 0.127)
		(layer "In2.Cu")
		(net "FM_M2_E1S_E6_PEDET")
	)
	(segment
		(start 348.934532 -38.679628)
		(end 347.2053 -38.679628)
		(width 0.127)
		(layer "In2.Cu")
		(net "FM_M2_E1S_E6_PEDET")
	)
	(segment
		(start 139.130024 -63.740538)
		(end 138.176254 -64.694308)
		(width 0.12954)
		(layer "F.Cu")
		(net "E1S_0_PRSNT")
	)
	(segment
		(start 141.640306 -64.313308)
		(end 141.067536 -63.740538)
		(width 0.12954)
		(layer "F.Cu")
		(net "E1S_0_PRSNT")
	)
	(segment
		(start 141.067536 -63.740538)
		(end 139.130024 -63.740538)
		(width 0.12954)
		(layer "F.Cu")
		(net "E1S_0_PRSNT")
	)
	(segment
		(start 142.85976 -64.471804)
		(end 143.089884 -64.701928)
		(width 0.12954)
		(layer "F.Cu")
		(net "E1S_0_PRSNT")
	)
	(segment
		(start 141.640306 -64.313308)
		(end 141.798802 -64.471804)
		(width 0.12954)
		(layer "F.Cu")
		(net "E1S_0_PRSNT")
	)
	(segment
		(start 141.798802 -64.471804)
		(end 142.85976 -64.471804)
		(width 0.12954)
		(layer "F.Cu")
		(net "E1S_0_PRSNT")
	)
	(segment
		(start 143.089884 -64.701928)
		(end 144.181576 -64.701928)
		(width 0.12954)
		(layer "F.Cu")
		(net "E1S_0_PRSNT")
	)
	(via
		(at 142.85976 -64.471804)
		(size 0.762)
		(drill 0.381)
		(layers "F.Cu" "B.Cu")
		(net "E1S_0_PRSNT")
	)
	(segment
		(start 176.555654 -120.175528)
		(end 176.155604 -120.575578)
		(width 0.12954)
		(layer "F.Cu")
		(net "E1S_0_P3V3_ADC_ALERT")
	)
	(via
		(at 219.78366 -126.754128)
		(size 0.508)
		(drill 0.254)
		(layers "F.Cu" "B.Cu")
		(net "E1S_0_P3V3_ADC_ALERT")
	)
	(via
		(at 209.2452 -79.238348)
		(size 0.508)
		(drill 0.254)
		(layers "F.Cu" "B.Cu")
		(net "E1S_0_P3V3_ADC_ALERT")
	)
	(via
		(at 215.28532 -58.984388)
		(size 0.508)
		(drill 0.254)
		(layers "F.Cu" "B.Cu")
		(net "E1S_0_P3V3_ADC_ALERT")
	)
	(via
		(at 176.155604 -120.575578)
		(size 0.4572)
		(drill 0.254)
		(layers "F.Cu" "B.Cu")
		(net "E1S_0_P3V3_ADC_ALERT")
	)
	(segment
		(start 211.99094 -58.984388)
		(end 211.69503 -58.688478)
		(width 0.12954)
		(layer "B.Cu")
		(net "E1S_0_P3V3_ADC_ALERT")
	)
	(segment
		(start 211.69503 -58.688478)
		(end 211.69503 -57.478422)
		(width 0.12954)
		(layer "B.Cu")
		(net "E1S_0_P3V3_ADC_ALERT")
	)
	(segment
		(start 215.28532 -58.984388)
		(end 211.99094 -58.984388)
		(width 0.12954)
		(layer "B.Cu")
		(net "E1S_0_P3V3_ADC_ALERT")
	)
	(segment
		(start 219.78366 -115.530884)
		(end 219.78366 -126.754128)
		(width 0.127)
		(layer "In2.Cu")
		(net "E1S_0_P3V3_ADC_ALERT")
	)
	(segment
		(start 212.7885 -80.561688)
		(end 223.076516 -90.849704)
		(width 0.127)
		(layer "In2.Cu")
		(net "E1S_0_P3V3_ADC_ALERT")
	)
	(segment
		(start 210.22818 -80.561688)
		(end 212.7885 -80.561688)
		(width 0.127)
		(layer "In2.Cu")
		(net "E1S_0_P3V3_ADC_ALERT")
	)
	(segment
		(start 223.076516 -90.849704)
		(end 223.076516 -97.230946)
		(width 0.127)
		(layer "In2.Cu")
		(net "E1S_0_P3V3_ADC_ALERT")
	)
	(segment
		(start 222.34398 -97.963482)
		(end 222.34398 -112.970564)
		(width 0.127)
		(layer "In2.Cu")
		(net "E1S_0_P3V3_ADC_ALERT")
	)
	(segment
		(start 209.2452 -79.238348)
		(end 209.2452 -79.578708)
		(width 0.127)
		(layer "In2.Cu")
		(net "E1S_0_P3V3_ADC_ALERT")
	)
	(segment
		(start 223.076516 -97.230946)
		(end 222.34398 -97.963482)
		(width 0.127)
		(layer "In2.Cu")
		(net "E1S_0_P3V3_ADC_ALERT")
	)
	(segment
		(start 209.2452 -79.578708)
		(end 210.22818 -80.561688)
		(width 0.127)
		(layer "In2.Cu")
		(net "E1S_0_P3V3_ADC_ALERT")
	)
	(segment
		(start 222.34398 -112.970564)
		(end 219.78366 -115.530884)
		(width 0.127)
		(layer "In2.Cu")
		(net "E1S_0_P3V3_ADC_ALERT")
	)
	(segment
		(start 188.996066 -126.10846)
		(end 187.281312 -126.10846)
		(width 0.127)
		(layer "In6.Cu")
		(net "E1S_0_P3V3_ADC_ALERT")
	)
	(segment
		(start 192.545716 -129.65811)
		(end 188.996066 -126.10846)
		(width 0.127)
		(layer "In6.Cu")
		(net "E1S_0_P3V3_ADC_ALERT")
	)
	(segment
		(start 221.593156 -81.140808)
		(end 210.13928 -81.140808)
		(width 0.127)
		(layer "In6.Cu")
		(net "E1S_0_P3V3_ADC_ALERT")
	)
	(segment
		(start 197.690486 -128.549908)
		(end 196.582284 -129.65811)
		(width 0.127)
		(layer "In6.Cu")
		(net "E1S_0_P3V3_ADC_ALERT")
	)
	(segment
		(start 219.78366 -126.474728)
		(end 219.38996 -126.081028)
		(width 0.127)
		(layer "In6.Cu")
		(net "E1S_0_P3V3_ADC_ALERT")
	)
	(segment
		(start 206.783432 -127.970788)
		(end 204.754988 -127.970788)
		(width 0.127)
		(layer "In6.Cu")
		(net "E1S_0_P3V3_ADC_ALERT")
	)
	(segment
		(start 226.7712 -64.976248)
		(end 226.7712 -75.962764)
		(width 0.127)
		(layer "In6.Cu")
		(net "E1S_0_P3V3_ADC_ALERT")
	)
	(segment
		(start 209.2071 -80.208628)
		(end 209.2071 -79.276448)
		(width 0.127)
		(layer "In6.Cu")
		(net "E1S_0_P3V3_ADC_ALERT")
	)
	(segment
		(start 181.0512 -121.775728)
		(end 179.0065 -121.775728)
		(width 0.127)
		(layer "In6.Cu")
		(net "E1S_0_P3V3_ADC_ALERT")
	)
	(segment
		(start 176.620932 -119.380508)
		(end 176.550828 -119.450612)
		(width 0.127)
		(layer "In6.Cu")
		(net "E1S_0_P3V3_ADC_ALERT")
	)
	(segment
		(start 178.55184 -119.982488)
		(end 177.94986 -119.380508)
		(width 0.127)
		(layer "In6.Cu")
		(net "E1S_0_P3V3_ADC_ALERT")
	)
	(segment
		(start 184.31002 -125.034548)
		(end 181.0512 -121.775728)
		(width 0.127)
		(layer "In6.Cu")
		(net "E1S_0_P3V3_ADC_ALERT")
	)
	(segment
		(start 207.664812 -128.852168)
		(end 206.783432 -127.970788)
		(width 0.127)
		(layer "In6.Cu")
		(net "E1S_0_P3V3_ADC_ALERT")
	)
	(segment
		(start 186.2074 -125.034548)
		(end 184.31002 -125.034548)
		(width 0.127)
		(layer "In6.Cu")
		(net "E1S_0_P3V3_ADC_ALERT")
	)
	(segment
		(start 176.550828 -119.450612)
		(end 176.550828 -120.180354)
		(width 0.127)
		(layer "In6.Cu")
		(net "E1S_0_P3V3_ADC_ALERT")
	)
	(segment
		(start 204.754988 -127.970788)
		(end 204.529944 -128.195832)
		(width 0.127)
		(layer "In6.Cu")
		(net "E1S_0_P3V3_ADC_ALERT")
	)
	(segment
		(start 209.2071 -79.276448)
		(end 209.2452 -79.238348)
		(width 0.127)
		(layer "In6.Cu")
		(net "E1S_0_P3V3_ADC_ALERT")
	)
	(segment
		(start 216.489788 -126.081028)
		(end 213.718648 -128.852168)
		(width 0.127)
		(layer "In6.Cu")
		(net "E1S_0_P3V3_ADC_ALERT")
	)
	(segment
		(start 176.550828 -120.180354)
		(end 176.155604 -120.575578)
		(width 0.127)
		(layer "In6.Cu")
		(net "E1S_0_P3V3_ADC_ALERT")
	)
	(segment
		(start 201.478134 -128.549908)
		(end 197.690486 -128.549908)
		(width 0.127)
		(layer "In6.Cu")
		(net "E1S_0_P3V3_ADC_ALERT")
	)
	(segment
		(start 222.31604 -60.521088)
		(end 226.7712 -64.976248)
		(width 0.127)
		(layer "In6.Cu")
		(net "E1S_0_P3V3_ADC_ALERT")
	)
	(segment
		(start 179.0065 -121.775728)
		(end 178.55184 -121.321068)
		(width 0.127)
		(layer "In6.Cu")
		(net "E1S_0_P3V3_ADC_ALERT")
	)
	(segment
		(start 226.7712 -75.962764)
		(end 221.593156 -81.140808)
		(width 0.127)
		(layer "In6.Cu")
		(net "E1S_0_P3V3_ADC_ALERT")
	)
	(segment
		(start 213.718648 -128.852168)
		(end 207.664812 -128.852168)
		(width 0.127)
		(layer "In6.Cu")
		(net "E1S_0_P3V3_ADC_ALERT")
	)
	(segment
		(start 178.55184 -121.321068)
		(end 178.55184 -119.982488)
		(width 0.127)
		(layer "In6.Cu")
		(net "E1S_0_P3V3_ADC_ALERT")
	)
	(segment
		(start 177.94986 -119.380508)
		(end 176.620932 -119.380508)
		(width 0.127)
		(layer "In6.Cu")
		(net "E1S_0_P3V3_ADC_ALERT")
	)
	(segment
		(start 215.28532 -58.984388)
		(end 216.82202 -60.521088)
		(width 0.127)
		(layer "In6.Cu")
		(net "E1S_0_P3V3_ADC_ALERT")
	)
	(segment
		(start 204.529944 -128.195832)
		(end 201.83221 -128.195832)
		(width 0.127)
		(layer "In6.Cu")
		(net "E1S_0_P3V3_ADC_ALERT")
	)
	(segment
		(start 216.82202 -60.521088)
		(end 222.31604 -60.521088)
		(width 0.127)
		(layer "In6.Cu")
		(net "E1S_0_P3V3_ADC_ALERT")
	)
	(segment
		(start 187.281312 -126.10846)
		(end 186.2074 -125.034548)
		(width 0.127)
		(layer "In6.Cu")
		(net "E1S_0_P3V3_ADC_ALERT")
	)
	(segment
		(start 219.38996 -126.081028)
		(end 216.489788 -126.081028)
		(width 0.127)
		(layer "In6.Cu")
		(net "E1S_0_P3V3_ADC_ALERT")
	)
	(segment
		(start 201.83221 -128.195832)
		(end 201.478134 -128.549908)
		(width 0.127)
		(layer "In6.Cu")
		(net "E1S_0_P3V3_ADC_ALERT")
	)
	(segment
		(start 210.13928 -81.140808)
		(end 209.2071 -80.208628)
		(width 0.127)
		(layer "In6.Cu")
		(net "E1S_0_P3V3_ADC_ALERT")
	)
	(segment
		(start 196.582284 -129.65811)
		(end 192.545716 -129.65811)
		(width 0.127)
		(layer "In6.Cu")
		(net "E1S_0_P3V3_ADC_ALERT")
	)
	(segment
		(start 219.78366 -126.754128)
		(end 219.78366 -126.474728)
		(width 0.127)
		(layer "In6.Cu")
		(net "E1S_0_P3V3_ADC_ALERT")
	)
	(segment
		(start 292.79088 -46.554898)
		(end 292.79088 -45.938948)
		(width 0.12954)
		(layer "F.Cu")
		(net "E1S_0_EN")
	)
	(segment
		(start 259.24383 -48.386746)
		(end 258.695952 -48.386746)
		(width 0.12954)
		(layer "F.Cu")
		(net "E1S_0_EN")
	)
	(segment
		(start 147.40128 -64.051942)
		(end 148.96084 -64.051942)
		(width 0.12954)
		(layer "F.Cu")
		(net "E1S_0_EN")
	)
	(segment
		(start 148.968206 -63.752222)
		(end 148.968206 -64.059308)
		(width 0.12954)
		(layer "F.Cu")
		(net "E1S_0_EN")
	)
	(segment
		(start 150.42388 -63.337948)
		(end 149.38248 -63.337948)
		(width 0.12954)
		(layer "F.Cu")
		(net "E1S_0_EN")
	)
	(segment
		(start 198.81469 -69.804788)
		(end 199.42429 -69.804788)
		(width 0.12954)
		(layer "F.Cu")
		(net "E1S_0_EN")
	)
	(segment
		(start 258.695952 -48.386746)
		(end 258.61391 -48.304704)
		(width 0.12954)
		(layer "F.Cu")
		(net "E1S_0_EN")
	)
	(segment
		(start 149.38248 -63.337948)
		(end 148.968206 -63.752222)
		(width 0.12954)
		(layer "F.Cu")
		(net "E1S_0_EN")
	)
	(segment
		(start 148.96084 -64.051942)
		(end 148.968206 -64.059308)
		(width 0.12954)
		(layer "F.Cu")
		(net "E1S_0_EN")
	)
	(segment
		(start 292.79088 -46.554898)
		(end 293.80688 -46.554898)
		(width 0.12954)
		(layer "F.Cu")
		(net "E1S_0_EN")
	)
	(segment
		(start 146.081496 -64.051942)
		(end 147.40128 -64.051942)
		(width 0.12954)
		(layer "F.Cu")
		(net "E1S_0_EN")
	)
	(via
		(at 147.40128 -64.051942)
		(size 0.762)
		(drill 0.381)
		(layers "F.Cu" "B.Cu")
		(net "E1S_0_EN")
	)
	(via
		(at 292.79088 -45.938948)
		(size 0.508)
		(drill 0.254)
		(layers "F.Cu" "B.Cu")
		(net "E1S_0_EN")
	)
	(via
		(at 199.42429 -69.804788)
		(size 0.508)
		(drill 0.254)
		(layers "F.Cu" "B.Cu")
		(net "E1S_0_EN")
	)
	(via
		(at 259.24383 -48.386746)
		(size 0.508)
		(drill 0.254)
		(layers "F.Cu" "B.Cu")
		(net "E1S_0_EN")
	)
	(via
		(at 150.42388 -63.337948)
		(size 0.508)
		(drill 0.254)
		(layers "F.Cu" "B.Cu")
		(net "E1S_0_EN")
	)
	(segment
		(start 259.672582 -48.402748)
		(end 259.65658 -48.386746)
		(width 0.127)
		(layer "In11.Cu")
		(net "E1S_0_EN")
	)
	(segment
		(start 276.431756 -46.827948)
		(end 273.002756 -43.398948)
		(width 0.127)
		(layer "In11.Cu")
		(net "E1S_0_EN")
	)
	(segment
		(start 242.639596 -62.372748)
		(end 254.105156 -62.372748)
		(width 0.127)
		(layer "In11.Cu")
		(net "E1S_0_EN")
	)
	(segment
		(start 260.57098 -48.402748)
		(end 259.672582 -48.402748)
		(width 0.127)
		(layer "In11.Cu")
		(net "E1S_0_EN")
	)
	(segment
		(start 256.632456 -59.845448)
		(end 258.15036 -59.845448)
		(width 0.127)
		(layer "In11.Cu")
		(net "E1S_0_EN")
	)
	(segment
		(start 204.533246 -65.773808)
		(end 239.238536 -65.773808)
		(width 0.127)
		(layer "In11.Cu")
		(net "E1S_0_EN")
	)
	(segment
		(start 200.502266 -69.804788)
		(end 204.533246 -65.773808)
		(width 0.127)
		(layer "In11.Cu")
		(net "E1S_0_EN")
	)
	(segment
		(start 150.42388 -62.067948)
		(end 150.42388 -63.337948)
		(width 0.127)
		(layer "In11.Cu")
		(net "E1S_0_EN")
	)
	(segment
		(start 259.65658 -48.386746)
		(end 259.24383 -48.386746)
		(width 0.127)
		(layer "In11.Cu")
		(net "E1S_0_EN")
	)
	(segment
		(start 259.24383 -50.301398)
		(end 259.24383 -48.386746)
		(width 0.127)
		(layer "In11.Cu")
		(net "E1S_0_EN")
	)
	(segment
		(start 198.96709 -69.347588)
		(end 193.579242 -69.347588)
		(width 0.127)
		(layer "In11.Cu")
		(net "E1S_0_EN")
	)
	(segment
		(start 171.663868 -61.737748)
		(end 150.75408 -61.737748)
		(width 0.127)
		(layer "In11.Cu")
		(net "E1S_0_EN")
	)
	(segment
		(start 290.30168 -46.827948)
		(end 276.431756 -46.827948)
		(width 0.127)
		(layer "In11.Cu")
		(net "E1S_0_EN")
	)
	(segment
		(start 183.256682 -59.025028)
		(end 174.376588 -59.025028)
		(width 0.127)
		(layer "In11.Cu")
		(net "E1S_0_EN")
	)
	(segment
		(start 193.579242 -69.347588)
		(end 183.256682 -59.025028)
		(width 0.127)
		(layer "In11.Cu")
		(net "E1S_0_EN")
	)
	(segment
		(start 260.06552 -57.930288)
		(end 260.06552 -51.123088)
		(width 0.127)
		(layer "In11.Cu")
		(net "E1S_0_EN")
	)
	(segment
		(start 239.238536 -65.773808)
		(end 242.639596 -62.372748)
		(width 0.127)
		(layer "In11.Cu")
		(net "E1S_0_EN")
	)
	(segment
		(start 260.06552 -51.123088)
		(end 259.24383 -50.301398)
		(width 0.127)
		(layer "In11.Cu")
		(net "E1S_0_EN")
	)
	(segment
		(start 273.002756 -43.398948)
		(end 265.57478 -43.398948)
		(width 0.127)
		(layer "In11.Cu")
		(net "E1S_0_EN")
	)
	(segment
		(start 199.42429 -69.804788)
		(end 198.96709 -69.347588)
		(width 0.127)
		(layer "In11.Cu")
		(net "E1S_0_EN")
	)
	(segment
		(start 254.105156 -62.372748)
		(end 256.632456 -59.845448)
		(width 0.127)
		(layer "In11.Cu")
		(net "E1S_0_EN")
	)
	(segment
		(start 258.15036 -59.845448)
		(end 260.06552 -57.930288)
		(width 0.127)
		(layer "In11.Cu")
		(net "E1S_0_EN")
	)
	(segment
		(start 150.75408 -61.737748)
		(end 150.42388 -62.067948)
		(width 0.127)
		(layer "In11.Cu")
		(net "E1S_0_EN")
	)
	(segment
		(start 199.42429 -69.804788)
		(end 200.502266 -69.804788)
		(width 0.127)
		(layer "In11.Cu")
		(net "E1S_0_EN")
	)
	(segment
		(start 265.57478 -43.398948)
		(end 260.57098 -48.402748)
		(width 0.127)
		(layer "In11.Cu")
		(net "E1S_0_EN")
	)
	(segment
		(start 291.19068 -45.938948)
		(end 290.30168 -46.827948)
		(width 0.127)
		(layer "In11.Cu")
		(net "E1S_0_EN")
	)
	(segment
		(start 174.376588 -59.025028)
		(end 171.663868 -61.737748)
		(width 0.127)
		(layer "In11.Cu")
		(net "E1S_0_EN")
	)
	(segment
		(start 292.79088 -45.938948)
		(end 291.19068 -45.938948)
		(width 0.127)
		(layer "In11.Cu")
		(net "E1S_0_EN")
	)
	(segment
		(start 11.444224 -100.636578)
		(end 10.3632 -101.717602)
		(width 0.12954)
		(layer "F.Cu")
		(net "USB_HUB_RREF")
	)
	(segment
		(start 9.168892 -101.844348)
		(end 9.15924 -101.854)
		(width 0.12954)
		(layer "F.Cu")
		(net "USB_HUB_RREF")
	)
	(segment
		(start 10.3632 -101.717602)
		(end 10.3632 -101.844348)
		(width 0.12954)
		(layer "F.Cu")
		(net "USB_HUB_RREF")
	)
	(segment
		(start 10.3632 -101.844348)
		(end 9.168892 -101.844348)
		(width 0.12954)
		(layer "F.Cu")
		(net "USB_HUB_RREF")
	)
	(segment
		(start 11.652504 -100.636578)
		(end 11.444224 -100.636578)
		(width 0.12954)
		(layer "F.Cu")
		(net "USB_HUB_RREF")
	)
	(via
		(at 10.3632 -101.844348)
		(size 0.762)
		(drill 0.381)
		(layers "F.Cu" "B.Cu")
		(net "USB_HUB_RREF")
	)
	(segment
		(start 17.187418 -97.63633)
		(end 16.477488 -97.63633)
		(width 0.12954)
		(layer "F.Cu")
		(net "USB_HUB_PSELF")
	)
	(segment
		(start 20.781264 -97.079308)
		(end 20.781264 -95.510604)
		(width 0.12954)
		(layer "F.Cu")
		(net "USB_HUB_PSELF")
	)
	(segment
		(start 18.8468 -96.916748)
		(end 17.907 -96.916748)
		(width 0.12954)
		(layer "F.Cu")
		(net "USB_HUB_PSELF")
	)
	(segment
		(start 19.3294 -97.399348)
		(end 18.8468 -96.916748)
		(width 0.12954)
		(layer "F.Cu")
		(net "USB_HUB_PSELF")
	)
	(segment
		(start 20.461224 -97.399348)
		(end 19.3294 -97.399348)
		(width 0.12954)
		(layer "F.Cu")
		(net "USB_HUB_PSELF")
	)
	(segment
		(start 20.776946 -97.083626)
		(end 20.781264 -97.079308)
		(width 0.12954)
		(layer "F.Cu")
		(net "USB_HUB_PSELF")
	)
	(segment
		(start 20.776946 -97.083626)
		(end 20.461224 -97.399348)
		(width 0.12954)
		(layer "F.Cu")
		(net "USB_HUB_PSELF")
	)
	(segment
		(start 17.907 -96.916748)
		(end 17.187418 -97.63633)
		(width 0.12954)
		(layer "F.Cu")
		(net "USB_HUB_PSELF")
	)
	(via
		(at 17.907 -96.916748)
		(size 0.762)
		(drill 0.381)
		(layers "F.Cu" "B.Cu")
		(net "USB_HUB_PSELF")
	)
	(segment
		(start 16.477488 -98.136456)
		(end 19.4564 -98.136456)
		(width 0.12954)
		(layer "F.Cu")
		(net "USB_HUB_PGANG")
	)
	(segment
		(start 19.4564 -98.136456)
		(end 20.741894 -98.136456)
		(width 0.12954)
		(layer "F.Cu")
		(net "USB_HUB_PGANG")
	)
	(segment
		(start 20.741894 -98.136456)
		(end 20.776946 -98.171508)
		(width 0.12954)
		(layer "F.Cu")
		(net "USB_HUB_PGANG")
	)
	(via
		(at 19.4564 -98.136456)
		(size 0.762)
		(drill 0.381)
		(layers "F.Cu" "B.Cu")
		(net "USB_HUB_PGANG")
	)
	(segment
		(start 14.564868 -95.316548)
		(end 14.564868 -94.238826)
		(width 0.12954)
		(layer "F.Cu")
		(net "USB_HUB_OVCUR4")
	)
	(segment
		(start 14.564868 -94.238826)
		(end 15.067788 -93.735906)
		(width 0.12954)
		(layer "F.Cu")
		(net "USB_HUB_OVCUR4")
	)
	(segment
		(start 15.067788 -93.735906)
		(end 15.067788 -93.087698)
		(width 0.12954)
		(layer "F.Cu")
		(net "USB_HUB_OVCUR4")
	)
	(segment
		(start 14.564868 -96.723962)
		(end 14.564868 -95.316548)
		(width 0.12954)
		(layer "F.Cu")
		(net "USB_HUB_OVCUR4")
	)
	(via
		(at 14.564868 -95.316548)
		(size 0.762)
		(drill 0.381)
		(layers "F.Cu" "B.Cu")
		(net "USB_HUB_OVCUR4")
	)
	(segment
		(start 15.064994 -95.618554)
		(end 16.0909 -94.592648)
		(width 0.12954)
		(layer "F.Cu")
		(net "USB_HUB_OVCUR3")
	)
	(segment
		(start 16.0909 -94.592648)
		(end 16.0909 -94.325948)
		(width 0.12954)
		(layer "F.Cu")
		(net "USB_HUB_OVCUR3")
	)
	(segment
		(start 15.064994 -96.723962)
		(end 15.064994 -95.618554)
		(width 0.12954)
		(layer "F.Cu")
		(net "USB_HUB_OVCUR3")
	)
	(segment
		(start 16.0909 -94.325948)
		(end 16.0909 -93.107764)
		(width 0.12954)
		(layer "F.Cu")
		(net "USB_HUB_OVCUR3")
	)
	(segment
		(start 16.0909 -93.107764)
		(end 16.110966 -93.087698)
		(width 0.12954)
		(layer "F.Cu")
		(net "USB_HUB_OVCUR3")
	)
	(via
		(at 16.0909 -94.325948)
		(size 0.762)
		(drill 0.381)
		(layers "F.Cu" "B.Cu")
		(net "USB_HUB_OVCUR3")
	)
	(segment
		(start 18.320766 -99.413314)
		(end 20.776946 -99.413314)
		(width 0.12954)
		(layer "F.Cu")
		(net "USB_HUB_OVCUR2")
	)
	(segment
		(start 18.068544 -99.161092)
		(end 18.320766 -99.413314)
		(width 0.12954)
		(layer "F.Cu")
		(net "USB_HUB_OVCUR2")
	)
	(segment
		(start 17.544034 -98.636582)
		(end 18.068544 -99.161092)
		(width 0.12954)
		(layer "F.Cu")
		(net "USB_HUB_OVCUR2")
	)
	(segment
		(start 16.477488 -98.636582)
		(end 17.544034 -98.636582)
		(width 0.12954)
		(layer "F.Cu")
		(net "USB_HUB_OVCUR2")
	)
	(via
		(at 18.068544 -99.161092)
		(size 0.762)
		(drill 0.381)
		(layers "F.Cu" "B.Cu")
		(net "USB_HUB_OVCUR2")
	)
	(segment
		(start 19.3548 -100.54971)
		(end 18.608802 -100.54971)
		(width 0.12954)
		(layer "F.Cu")
		(net "USB_HUB_OVCUR1")
	)
	(segment
		(start 20.776946 -100.54971)
		(end 19.3548 -100.54971)
		(width 0.12954)
		(layer "F.Cu")
		(net "USB_HUB_OVCUR1")
	)
	(segment
		(start 18.608802 -100.54971)
		(end 17.195546 -99.136454)
		(width 0.12954)
		(layer "F.Cu")
		(net "USB_HUB_OVCUR1")
	)
	(segment
		(start 17.195546 -99.136454)
		(end 16.477488 -99.136454)
		(width 0.12954)
		(layer "F.Cu")
		(net "USB_HUB_OVCUR1")
	)
	(via
		(at 19.3548 -100.54971)
		(size 0.762)
		(drill 0.381)
		(layers "F.Cu" "B.Cu")
		(net "USB_HUB_OVCUR1")
	)
	(segment
		(start 17.16532 -94.071948)
		(end 17.16532 -93.113352)
		(width 0.12954)
		(layer "F.Cu")
		(net "USB_HUB_DVDD")
	)
	(segment
		(start 15.56512 -96.723962)
		(end 15.56512 -96.098868)
		(width 0.12954)
		(layer "F.Cu")
		(net "USB_HUB_DVDD")
	)
	(segment
		(start 17.16532 -93.113352)
		(end 17.190974 -93.087698)
		(width 0.12954)
		(layer "F.Cu")
		(net "USB_HUB_DVDD")
	)
	(segment
		(start 16.69034 -95.514668)
		(end 16.69034 -94.546928)
		(width 0.12954)
		(layer "F.Cu")
		(net "USB_HUB_DVDD")
	)
	(segment
		(start 16.14932 -95.514668)
		(end 16.69034 -95.514668)
		(width 0.12954)
		(layer "F.Cu")
		(net "USB_HUB_DVDD")
	)
	(segment
		(start 15.56512 -96.098868)
		(end 16.14932 -95.514668)
		(width 0.12954)
		(layer "F.Cu")
		(net "USB_HUB_DVDD")
	)
	(segment
		(start 16.69034 -94.546928)
		(end 17.16532 -94.071948)
		(width 0.12954)
		(layer "F.Cu")
		(net "USB_HUB_DVDD")
	)
	(via
		(at 16.69034 -95.514668)
		(size 0.762)
		(drill 0.381)
		(layers "F.Cu" "B.Cu")
		(net "USB_HUB_DVDD")
	)
	(segment
		(start 236.599984 -46.764956)
		(end 237.832392 -46.764956)
		(width 0.12954)
		(layer "F.Cu")
		(net "TP_E1S_0_RFU")
	)
	(segment
		(start 237.832392 -46.764956)
		(end 237.851696 -46.78426)
		(width 0.12954)
		(layer "F.Cu")
		(net "TP_E1S_0_RFU")
	)
	(via
		(at 237.851696 -46.78426)
		(size 0.508)
		(drill 0.254)
		(layers "F.Cu" "B.Cu")
		(net "TP_E1S_0_RFU")
	)
	(segment
		(start 234.372404 -44.780708)
		(end 235.756704 -46.165008)
		(width 0.12954)
		(layer "F.Cu")
		(net "TP_E1S_0_MFG")
	)
	(segment
		(start 235.756704 -46.165008)
		(end 236.599984 -46.165008)
		(width 0.12954)
		(layer "F.Cu")
		(net "TP_E1S_0_MFG")
	)
	(via
		(at 234.372404 -44.780708)
		(size 0.508)
		(drill 0.254)
		(layers "F.Cu" "B.Cu")
		(net "TP_E1S_0_MFG")
	)
	(segment
		(start 228.7905 -50.964846)
		(end 232.000044 -50.964846)
		(width 0.12954)
		(layer "F.Cu")
		(net "TP_CLK_100M_E1S_0_DP")
	)
	(segment
		(start 228.473 -51.282346)
		(end 228.7905 -50.964846)
		(width 0.12954)
		(layer "F.Cu")
		(net "TP_CLK_100M_E1S_0_DP")
	)
	(via
		(at 228.473 -51.282346)
		(size 0.762)
		(drill 0.381)
		(layers "F.Cu" "B.Cu")
		(net "TP_CLK_100M_E1S_0_DP")
	)
	(segment
		(start 227.891848 -50.364898)
		(end 232.000044 -50.364898)
		(width 0.12954)
		(layer "F.Cu")
		(net "TP_CLK_100M_E1S_0_DN")
	)
	(segment
		(start 226.9998 -51.256946)
		(end 227.891848 -50.364898)
		(width 0.12954)
		(layer "F.Cu")
		(net "TP_CLK_100M_E1S_0_DN")
	)
	(via
		(at 226.9998 -51.256946)
		(size 0.762)
		(drill 0.381)
		(layers "F.Cu" "B.Cu")
		(net "TP_CLK_100M_E1S_0_DN")
	)
	(segment
		(start 24.484584 -108.047282)
		(end 24.795734 -108.358432)
		(width 0.12954)
		(layer "F.Cu")
		(net "TP_ADC128_INT")
	)
	(segment
		(start 24.795734 -108.358432)
		(end 26.915618 -108.358432)
		(width 0.12954)
		(layer "F.Cu")
		(net "TP_ADC128_INT")
	)
	(via
		(at 24.484584 -108.047282)
		(size 0.762)
		(drill 0.381)
		(layers "F.Cu" "B.Cu")
		(net "TP_ADC128_INT")
	)
	(segment
		(start 65.4685 -114.513868)
		(end 65.106042 -114.15141)
		(width 0.12954)
		(layer "F.Cu")
		(net "SMB_VR_SENSOR_3V3AUX_SDA_R")
	)
	(segment
		(start 65.949322 -114.99469)
		(end 65.4685 -114.513868)
		(width 0.12954)
		(layer "F.Cu")
		(net "SMB_VR_SENSOR_3V3AUX_SDA_R")
	)
	(segment
		(start 67.685666 -114.74069)
		(end 67.431666 -114.99469)
		(width 0.12954)
		(layer "F.Cu")
		(net "SMB_VR_SENSOR_3V3AUX_SDA_R")
	)
	(segment
		(start 67.431666 -114.99469)
		(end 65.949322 -114.99469)
		(width 0.12954)
		(layer "F.Cu")
		(net "SMB_VR_SENSOR_3V3AUX_SDA_R")
	)
	(segment
		(start 65.106042 -114.15141)
		(end 63.975742 -114.15141)
		(width 0.12954)
		(layer "F.Cu")
		(net "SMB_VR_SENSOR_3V3AUX_SDA_R")
	)
	(via
		(at 65.4685 -114.513868)
		(size 0.508)
		(drill 0.254)
		(layers "F.Cu" "B.Cu")
		(net "SMB_VR_SENSOR_3V3AUX_SDA_R")
	)
	(segment
		(start 68.928742 -114.74069)
		(end 68.485766 -114.74069)
		(width 0.12954)
		(layer "F.Cu")
		(net "SMB_VR_SENSOR_3V3AUX_SDA")
	)
	(segment
		(start 69.469 -114.772948)
		(end 69.215 -115.026948)
		(width 0.12954)
		(layer "F.Cu")
		(net "SMB_VR_SENSOR_3V3AUX_SDA")
	)
	(segment
		(start 69.215 -115.026948)
		(end 68.928742 -114.74069)
		(width 0.12954)
		(layer "F.Cu")
		(net "SMB_VR_SENSOR_3V3AUX_SDA")
	)
	(segment
		(start 69.95795 -114.772948)
		(end 69.469 -114.772948)
		(width 0.12954)
		(layer "F.Cu")
		(net "SMB_VR_SENSOR_3V3AUX_SDA")
	)
	(via
		(at 47.90948 -6.137148)
		(size 0.508)
		(drill 0.254)
		(layers "F.Cu" "B.Cu")
		(net "SMB_VR_SENSOR_3V3AUX_SDA")
	)
	(via
		(at 69.215 -115.026948)
		(size 0.508)
		(drill 0.254)
		(layers "F.Cu" "B.Cu")
		(net "SMB_VR_SENSOR_3V3AUX_SDA")
	)
	(via
		(at 178.5874 -14.771878)
		(size 0.508)
		(drill 0.254)
		(layers "F.Cu" "B.Cu")
		(net "SMB_VR_SENSOR_3V3AUX_SDA")
	)
	(segment
		(start 59.35726 -107.401868)
		(end 56.62168 -104.666288)
		(width 0.12954)
		(layer "B.Cu")
		(net "SMB_VR_SENSOR_3V3AUX_SDA")
	)
	(segment
		(start 178.5874 -14.771878)
		(end 178.725576 -14.771878)
		(width 0.12954)
		(layer "B.Cu")
		(net "SMB_VR_SENSOR_3V3AUX_SDA")
	)
	(segment
		(start 65.38976 -115.174268)
		(end 59.35726 -109.141768)
		(width 0.12954)
		(layer "B.Cu")
		(net "SMB_VR_SENSOR_3V3AUX_SDA")
	)
	(segment
		(start 47.90948 -10.551668)
		(end 47.90948 -10.173208)
		(width 0.12954)
		(layer "B.Cu")
		(net "SMB_VR_SENSOR_3V3AUX_SDA")
	)
	(segment
		(start 178.725576 -14.771878)
		(end 179.335176 -14.162278)
		(width 0.12954)
		(layer "B.Cu")
		(net "SMB_VR_SENSOR_3V3AUX_SDA")
	)
	(segment
		(start 56.62168 -83.124548)
		(end 54.7751 -81.277968)
		(width 0.12954)
		(layer "B.Cu")
		(net "SMB_VR_SENSOR_3V3AUX_SDA")
	)
	(segment
		(start 48.786034 -9.914128)
		(end 48.786034 -9.535668)
		(width 0.12954)
		(layer "B.Cu")
		(net "SMB_VR_SENSOR_3V3AUX_SDA")
	)
	(segment
		(start 48.03902 -8.131048)
		(end 47.90948 -8.001508)
		(width 0.12954)
		(layer "B.Cu")
		(net "SMB_VR_SENSOR_3V3AUX_SDA")
	)
	(segment
		(start 47.90948 -10.173208)
		(end 48.03902 -10.043668)
		(width 0.12954)
		(layer "B.Cu")
		(net "SMB_VR_SENSOR_3V3AUX_SDA")
	)
	(segment
		(start 53.63464 -17.937988)
		(end 53.63464 -15.062708)
		(width 0.12954)
		(layer "B.Cu")
		(net "SMB_VR_SENSOR_3V3AUX_SDA")
	)
	(segment
		(start 48.786034 -9.535668)
		(end 48.656494 -9.406128)
		(width 0.12954)
		(layer "B.Cu")
		(net "SMB_VR_SENSOR_3V3AUX_SDA")
	)
	(segment
		(start 47.90948 -9.276588)
		(end 47.90948 -8.898128)
		(width 0.12954)
		(layer "B.Cu")
		(net "SMB_VR_SENSOR_3V3AUX_SDA")
	)
	(segment
		(start 48.656494 -8.768588)
		(end 48.786034 -8.639048)
		(width 0.12954)
		(layer "B.Cu")
		(net "SMB_VR_SENSOR_3V3AUX_SDA")
	)
	(segment
		(start 54.7751 -81.277968)
		(end 54.7751 -19.078448)
		(width 0.12954)
		(layer "B.Cu")
		(net "SMB_VR_SENSOR_3V3AUX_SDA")
	)
	(segment
		(start 48.03902 -8.768588)
		(end 48.656494 -8.768588)
		(width 0.12954)
		(layer "B.Cu")
		(net "SMB_VR_SENSOR_3V3AUX_SDA")
	)
	(segment
		(start 51.97348 -13.401548)
		(end 49.35728 -13.401548)
		(width 0.12954)
		(layer "B.Cu")
		(net "SMB_VR_SENSOR_3V3AUX_SDA")
	)
	(segment
		(start 48.03902 -9.406128)
		(end 47.90948 -9.276588)
		(width 0.12954)
		(layer "B.Cu")
		(net "SMB_VR_SENSOR_3V3AUX_SDA")
	)
	(segment
		(start 47.90948 -8.898128)
		(end 48.03902 -8.768588)
		(width 0.12954)
		(layer "B.Cu")
		(net "SMB_VR_SENSOR_3V3AUX_SDA")
	)
	(segment
		(start 59.35726 -109.141768)
		(end 59.35726 -107.401868)
		(width 0.12954)
		(layer "B.Cu")
		(net "SMB_VR_SENSOR_3V3AUX_SDA")
	)
	(segment
		(start 48.03902 -10.043668)
		(end 48.656494 -10.043668)
		(width 0.12954)
		(layer "B.Cu")
		(net "SMB_VR_SENSOR_3V3AUX_SDA")
	)
	(segment
		(start 69.215 -115.026948)
		(end 69.06768 -115.174268)
		(width 0.12954)
		(layer "B.Cu")
		(net "SMB_VR_SENSOR_3V3AUX_SDA")
	)
	(segment
		(start 179.335176 -14.162278)
		(end 179.729638 -14.162278)
		(width 0.12954)
		(layer "B.Cu")
		(net "SMB_VR_SENSOR_3V3AUX_SDA")
	)
	(segment
		(start 48.03902 -10.681208)
		(end 47.90948 -10.551668)
		(width 0.12954)
		(layer "B.Cu")
		(net "SMB_VR_SENSOR_3V3AUX_SDA")
	)
	(segment
		(start 47.90948 -8.001508)
		(end 47.90948 -6.137148)
		(width 0.12954)
		(layer "B.Cu")
		(net "SMB_VR_SENSOR_3V3AUX_SDA")
	)
	(segment
		(start 48.656494 -10.043668)
		(end 48.786034 -9.914128)
		(width 0.12954)
		(layer "B.Cu")
		(net "SMB_VR_SENSOR_3V3AUX_SDA")
	)
	(segment
		(start 56.62168 -104.666288)
		(end 56.62168 -83.124548)
		(width 0.12954)
		(layer "B.Cu")
		(net "SMB_VR_SENSOR_3V3AUX_SDA")
	)
	(segment
		(start 48.786034 -8.639048)
		(end 48.786034 -8.260588)
		(width 0.12954)
		(layer "B.Cu")
		(net "SMB_VR_SENSOR_3V3AUX_SDA")
	)
	(segment
		(start 69.06768 -115.174268)
		(end 65.38976 -115.174268)
		(width 0.12954)
		(layer "B.Cu")
		(net "SMB_VR_SENSOR_3V3AUX_SDA")
	)
	(segment
		(start 48.656494 -11.318748)
		(end 48.786034 -11.189208)
		(width 0.12954)
		(layer "B.Cu")
		(net "SMB_VR_SENSOR_3V3AUX_SDA")
	)
	(segment
		(start 48.786034 -11.189208)
		(end 48.786034 -10.810748)
		(width 0.12954)
		(layer "B.Cu")
		(net "SMB_VR_SENSOR_3V3AUX_SDA")
	)
	(segment
		(start 48.656494 -8.131048)
		(end 48.03902 -8.131048)
		(width 0.12954)
		(layer "B.Cu")
		(net "SMB_VR_SENSOR_3V3AUX_SDA")
	)
	(segment
		(start 53.63464 -15.062708)
		(end 51.97348 -13.401548)
		(width 0.12954)
		(layer "B.Cu")
		(net "SMB_VR_SENSOR_3V3AUX_SDA")
	)
	(segment
		(start 48.03902 -11.318748)
		(end 48.656494 -11.318748)
		(width 0.12954)
		(layer "B.Cu")
		(net "SMB_VR_SENSOR_3V3AUX_SDA")
	)
	(segment
		(start 48.786034 -10.810748)
		(end 48.656494 -10.681208)
		(width 0.12954)
		(layer "B.Cu")
		(net "SMB_VR_SENSOR_3V3AUX_SDA")
	)
	(segment
		(start 49.35728 -13.401548)
		(end 47.90948 -11.953748)
		(width 0.12954)
		(layer "B.Cu")
		(net "SMB_VR_SENSOR_3V3AUX_SDA")
	)
	(segment
		(start 47.90948 -11.448288)
		(end 48.03902 -11.318748)
		(width 0.12954)
		(layer "B.Cu")
		(net "SMB_VR_SENSOR_3V3AUX_SDA")
	)
	(segment
		(start 54.7751 -19.078448)
		(end 53.63464 -17.937988)
		(width 0.12954)
		(layer "B.Cu")
		(net "SMB_VR_SENSOR_3V3AUX_SDA")
	)
	(segment
		(start 48.786034 -8.260588)
		(end 48.656494 -8.131048)
		(width 0.12954)
		(layer "B.Cu")
		(net "SMB_VR_SENSOR_3V3AUX_SDA")
	)
	(segment
		(start 48.656494 -10.681208)
		(end 48.03902 -10.681208)
		(width 0.12954)
		(layer "B.Cu")
		(net "SMB_VR_SENSOR_3V3AUX_SDA")
	)
	(segment
		(start 47.90948 -11.953748)
		(end 47.90948 -11.448288)
		(width 0.12954)
		(layer "B.Cu")
		(net "SMB_VR_SENSOR_3V3AUX_SDA")
	)
	(segment
		(start 48.656494 -9.406128)
		(end 48.03902 -9.406128)
		(width 0.12954)
		(layer "B.Cu")
		(net "SMB_VR_SENSOR_3V3AUX_SDA")
	)
	(segment
		(start 47.90948 -7.924292)
		(end 47.90948 -6.137148)
		(width 0.127)
		(layer "In13.Cu")
		(net "SMB_VR_SENSOR_3V3AUX_SDA")
	)
	(segment
		(start 170.641264 -14.31671)
		(end 170.260264 -14.31671)
		(width 0.127)
		(layer "In13.Cu")
		(net "SMB_VR_SENSOR_3V3AUX_SDA")
	)
	(segment
		(start 69.845936 -9.185148)
		(end 68.575936 -7.915148)
		(width 0.127)
		(layer "In13.Cu")
		(net "SMB_VR_SENSOR_3V3AUX_SDA")
	)
	(segment
		(start 82.3214 -14.315948)
		(end 79.55788 -11.552428)
		(width 0.127)
		(layer "In13.Cu")
		(net "SMB_VR_SENSOR_3V3AUX_SDA")
	)
	(segment
		(start 48.586136 -8.600948)
		(end 47.90948 -7.924292)
		(width 0.127)
		(layer "In13.Cu")
		(net "SMB_VR_SENSOR_3V3AUX_SDA")
	)
	(segment
		(start 120.62206 -14.856968)
		(end 120.08104 -14.315948)
		(width 0.127)
		(layer "In13.Cu")
		(net "SMB_VR_SENSOR_3V3AUX_SDA")
	)
	(segment
		(start 67.095624 -7.915148)
		(end 66.409824 -8.600948)
		(width 0.127)
		(layer "In13.Cu")
		(net "SMB_VR_SENSOR_3V3AUX_SDA")
	)
	(segment
		(start 170.260264 -14.31671)
		(end 170.133264 -14.18971)
		(width 0.127)
		(layer "In13.Cu")
		(net "SMB_VR_SENSOR_3V3AUX_SDA")
	)
	(segment
		(start 169.498264 -14.18971)
		(end 169.371264 -14.31671)
		(width 0.127)
		(layer "In13.Cu")
		(net "SMB_VR_SENSOR_3V3AUX_SDA")
	)
	(segment
		(start 178.5874 -14.771878)
		(end 178.5874 -14.285468)
		(width 0.127)
		(layer "In13.Cu")
		(net "SMB_VR_SENSOR_3V3AUX_SDA")
	)
	(segment
		(start 134.761224 -13.426948)
		(end 133.872224 -14.315948)
		(width 0.127)
		(layer "In13.Cu")
		(net "SMB_VR_SENSOR_3V3AUX_SDA")
	)
	(segment
		(start 122.174 -14.856968)
		(end 120.62206 -14.856968)
		(width 0.127)
		(layer "In13.Cu")
		(net "SMB_VR_SENSOR_3V3AUX_SDA")
	)
	(segment
		(start 170.006264 -13.782548)
		(end 169.625264 -13.782548)
		(width 0.127)
		(layer "In13.Cu")
		(net "SMB_VR_SENSOR_3V3AUX_SDA")
	)
	(segment
		(start 79.55788 -11.552428)
		(end 79.55788 -10.718292)
		(width 0.127)
		(layer "In13.Cu")
		(net "SMB_VR_SENSOR_3V3AUX_SDA")
	)
	(segment
		(start 122.71502 -14.315948)
		(end 122.174 -14.856968)
		(width 0.127)
		(layer "In13.Cu")
		(net "SMB_VR_SENSOR_3V3AUX_SDA")
	)
	(segment
		(start 149.3647 -12.362688)
		(end 147.351496 -12.362688)
		(width 0.127)
		(layer "In13.Cu")
		(net "SMB_VR_SENSOR_3V3AUX_SDA")
	)
	(segment
		(start 78.024736 -9.185148)
		(end 69.845936 -9.185148)
		(width 0.127)
		(layer "In13.Cu")
		(net "SMB_VR_SENSOR_3V3AUX_SDA")
	)
	(segment
		(start 170.133264 -14.18971)
		(end 170.133264 -13.909548)
		(width 0.127)
		(layer "In13.Cu")
		(net "SMB_VR_SENSOR_3V3AUX_SDA")
	)
	(segment
		(start 79.55788 -10.718292)
		(end 78.024736 -9.185148)
		(width 0.127)
		(layer "In13.Cu")
		(net "SMB_VR_SENSOR_3V3AUX_SDA")
	)
	(segment
		(start 170.768264 -14.18971)
		(end 170.641264 -14.31671)
		(width 0.127)
		(layer "In13.Cu")
		(net "SMB_VR_SENSOR_3V3AUX_SDA")
	)
	(segment
		(start 147.351496 -12.362688)
		(end 146.287236 -13.426948)
		(width 0.127)
		(layer "In13.Cu")
		(net "SMB_VR_SENSOR_3V3AUX_SDA")
	)
	(segment
		(start 168.736264 -13.782548)
		(end 150.78456 -13.782548)
		(width 0.127)
		(layer "In13.Cu")
		(net "SMB_VR_SENSOR_3V3AUX_SDA")
	)
	(segment
		(start 168.863264 -13.909548)
		(end 168.736264 -13.782548)
		(width 0.127)
		(layer "In13.Cu")
		(net "SMB_VR_SENSOR_3V3AUX_SDA")
	)
	(segment
		(start 133.872224 -14.315948)
		(end 122.71502 -14.315948)
		(width 0.127)
		(layer "In13.Cu")
		(net "SMB_VR_SENSOR_3V3AUX_SDA")
	)
	(segment
		(start 168.863264 -14.18971)
		(end 168.863264 -13.909548)
		(width 0.127)
		(layer "In13.Cu")
		(net "SMB_VR_SENSOR_3V3AUX_SDA")
	)
	(segment
		(start 170.895264 -13.782548)
		(end 170.768264 -13.909548)
		(width 0.127)
		(layer "In13.Cu")
		(net "SMB_VR_SENSOR_3V3AUX_SDA")
	)
	(segment
		(start 169.498264 -13.909548)
		(end 169.498264 -14.18971)
		(width 0.127)
		(layer "In13.Cu")
		(net "SMB_VR_SENSOR_3V3AUX_SDA")
	)
	(segment
		(start 120.08104 -14.315948)
		(end 82.3214 -14.315948)
		(width 0.127)
		(layer "In13.Cu")
		(net "SMB_VR_SENSOR_3V3AUX_SDA")
	)
	(segment
		(start 178.08448 -13.782548)
		(end 170.895264 -13.782548)
		(width 0.127)
		(layer "In13.Cu")
		(net "SMB_VR_SENSOR_3V3AUX_SDA")
	)
	(segment
		(start 170.133264 -13.909548)
		(end 170.006264 -13.782548)
		(width 0.127)
		(layer "In13.Cu")
		(net "SMB_VR_SENSOR_3V3AUX_SDA")
	)
	(segment
		(start 168.990264 -14.31671)
		(end 168.863264 -14.18971)
		(width 0.127)
		(layer "In13.Cu")
		(net "SMB_VR_SENSOR_3V3AUX_SDA")
	)
	(segment
		(start 170.768264 -13.909548)
		(end 170.768264 -14.18971)
		(width 0.127)
		(layer "In13.Cu")
		(net "SMB_VR_SENSOR_3V3AUX_SDA")
	)
	(segment
		(start 68.575936 -7.915148)
		(end 67.095624 -7.915148)
		(width 0.127)
		(layer "In13.Cu")
		(net "SMB_VR_SENSOR_3V3AUX_SDA")
	)
	(segment
		(start 150.78456 -13.782548)
		(end 149.3647 -12.362688)
		(width 0.127)
		(layer "In13.Cu")
		(net "SMB_VR_SENSOR_3V3AUX_SDA")
	)
	(segment
		(start 169.371264 -14.31671)
		(end 168.990264 -14.31671)
		(width 0.127)
		(layer "In13.Cu")
		(net "SMB_VR_SENSOR_3V3AUX_SDA")
	)
	(segment
		(start 66.409824 -8.600948)
		(end 48.586136 -8.600948)
		(width 0.127)
		(layer "In13.Cu")
		(net "SMB_VR_SENSOR_3V3AUX_SDA")
	)
	(segment
		(start 146.287236 -13.426948)
		(end 134.761224 -13.426948)
		(width 0.127)
		(layer "In13.Cu")
		(net "SMB_VR_SENSOR_3V3AUX_SDA")
	)
	(segment
		(start 169.625264 -13.782548)
		(end 169.498264 -13.909548)
		(width 0.127)
		(layer "In13.Cu")
		(net "SMB_VR_SENSOR_3V3AUX_SDA")
	)
	(segment
		(start 178.5874 -14.285468)
		(end 178.08448 -13.782548)
		(width 0.127)
		(layer "In13.Cu")
		(net "SMB_VR_SENSOR_3V3AUX_SDA")
	)
	(segment
		(start 67.360038 -113.72469)
		(end 67.685666 -113.72469)
		(width 0.12954)
		(layer "F.Cu")
		(net "SMB_VR_SENSOR_3V3AUX_SCL_R")
	)
	(segment
		(start 63.975742 -113.501424)
		(end 65.136522 -113.501424)
		(width 0.12954)
		(layer "F.Cu")
		(net "SMB_VR_SENSOR_3V3AUX_SCL_R")
	)
	(segment
		(start 65.618106 -113.983008)
		(end 66.81216 -113.983008)
		(width 0.12954)
		(layer "F.Cu")
		(net "SMB_VR_SENSOR_3V3AUX_SCL_R")
	)
	(segment
		(start 65.136522 -113.501424)
		(end 65.618106 -113.983008)
		(width 0.12954)
		(layer "F.Cu")
		(net "SMB_VR_SENSOR_3V3AUX_SCL_R")
	)
	(segment
		(start 67.10172 -113.983008)
		(end 67.360038 -113.72469)
		(width 0.12954)
		(layer "F.Cu")
		(net "SMB_VR_SENSOR_3V3AUX_SCL_R")
	)
	(segment
		(start 66.81216 -113.983008)
		(end 67.10172 -113.983008)
		(width 0.12954)
		(layer "F.Cu")
		(net "SMB_VR_SENSOR_3V3AUX_SCL_R")
	)
	(via
		(at 66.81216 -113.983008)
		(size 0.508)
		(drill 0.254)
		(layers "F.Cu" "B.Cu")
		(net "SMB_VR_SENSOR_3V3AUX_SCL_R")
	)
	(segment
		(start 68.485766 -113.72469)
		(end 69.215 -113.72469)
		(width 0.12954)
		(layer "F.Cu")
		(net "SMB_VR_SENSOR_3V3AUX_SCL")
	)
	(segment
		(start 69.215 -113.72469)
		(end 69.247258 -113.756948)
		(width 0.12954)
		(layer "F.Cu")
		(net "SMB_VR_SENSOR_3V3AUX_SCL")
	)
	(segment
		(start 69.247258 -113.756948)
		(end 69.95795 -113.756948)
		(width 0.12954)
		(layer "F.Cu")
		(net "SMB_VR_SENSOR_3V3AUX_SCL")
	)
	(via
		(at 69.215 -113.72469)
		(size 0.508)
		(drill 0.254)
		(layers "F.Cu" "B.Cu")
		(net "SMB_VR_SENSOR_3V3AUX_SCL")
	)
	(via
		(at 47.27448 -6.137148)
		(size 0.508)
		(drill 0.254)
		(layers "F.Cu" "B.Cu")
		(net "SMB_VR_SENSOR_3V3AUX_SCL")
	)
	(via
		(at 179.544218 -14.782038)
		(size 0.508)
		(drill 0.254)
		(layers "F.Cu" "B.Cu")
		(net "SMB_VR_SENSOR_3V3AUX_SCL")
	)
	(segment
		(start 53.75148 -81.188306)
		(end 53.75148 -24.432768)
		(width 0.12954)
		(layer "B.Cu")
		(net "SMB_VR_SENSOR_3V3AUX_SCL")
	)
	(segment
		(start 70.0151 -114.52479)
		(end 70.0151 -115.496848)
		(width 0.12954)
		(layer "B.Cu")
		(net "SMB_VR_SENSOR_3V3AUX_SCL")
	)
	(segment
		(start 47.40148 -12.164314)
		(end 47.40148 -6.735572)
		(width 0.12954)
		(layer "B.Cu")
		(net "SMB_VR_SENSOR_3V3AUX_SCL")
	)
	(segment
		(start 179.558188 -14.796008)
		(end 180.36286 -14.796008)
		(width 0.12954)
		(layer "B.Cu")
		(net "SMB_VR_SENSOR_3V3AUX_SCL")
	)
	(segment
		(start 53.75148 -24.432768)
		(end 50.98288 -21.664168)
		(width 0.12954)
		(layer "B.Cu")
		(net "SMB_VR_SENSOR_3V3AUX_SCL")
	)
	(segment
		(start 49.146714 -13.909548)
		(end 47.40148 -12.164314)
		(width 0.12954)
		(layer "B.Cu")
		(net "SMB_VR_SENSOR_3V3AUX_SCL")
	)
	(segment
		(start 51.49596 -13.909548)
		(end 49.146714 -13.909548)
		(width 0.12954)
		(layer "B.Cu")
		(net "SMB_VR_SENSOR_3V3AUX_SCL")
	)
	(segment
		(start 69.215 -113.72469)
		(end 70.0151 -114.52479)
		(width 0.12954)
		(layer "B.Cu")
		(net "SMB_VR_SENSOR_3V3AUX_SCL")
	)
	(segment
		(start 69.49186 -116.020088)
		(end 65.60566 -116.020088)
		(width 0.12954)
		(layer "B.Cu")
		(net "SMB_VR_SENSOR_3V3AUX_SCL")
	)
	(segment
		(start 55.96128 -83.398106)
		(end 53.75148 -81.188306)
		(width 0.12954)
		(layer "B.Cu")
		(net "SMB_VR_SENSOR_3V3AUX_SCL")
	)
	(segment
		(start 58.05678 -107.617768)
		(end 55.96128 -105.522268)
		(width 0.12954)
		(layer "B.Cu")
		(net "SMB_VR_SENSOR_3V3AUX_SCL")
	)
	(segment
		(start 58.05678 -108.471208)
		(end 58.05678 -107.617768)
		(width 0.12954)
		(layer "B.Cu")
		(net "SMB_VR_SENSOR_3V3AUX_SCL")
	)
	(segment
		(start 70.0151 -115.496848)
		(end 69.49186 -116.020088)
		(width 0.12954)
		(layer "B.Cu")
		(net "SMB_VR_SENSOR_3V3AUX_SCL")
	)
	(segment
		(start 47.40148 -6.735572)
		(end 47.27448 -6.608572)
		(width 0.12954)
		(layer "B.Cu")
		(net "SMB_VR_SENSOR_3V3AUX_SCL")
	)
	(segment
		(start 50.98288 -21.664168)
		(end 50.98288 -18.867628)
		(width 0.12954)
		(layer "B.Cu")
		(net "SMB_VR_SENSOR_3V3AUX_SCL")
	)
	(segment
		(start 179.544218 -14.782038)
		(end 179.558188 -14.796008)
		(width 0.12954)
		(layer "B.Cu")
		(net "SMB_VR_SENSOR_3V3AUX_SCL")
	)
	(segment
		(start 51.50104 -13.914628)
		(end 51.49596 -13.909548)
		(width 0.12954)
		(layer "B.Cu")
		(net "SMB_VR_SENSOR_3V3AUX_SCL")
	)
	(segment
		(start 180.36286 -14.796008)
		(end 180.814218 -14.34465)
		(width 0.12954)
		(layer "B.Cu")
		(net "SMB_VR_SENSOR_3V3AUX_SCL")
	)
	(segment
		(start 51.50104 -18.349468)
		(end 51.50104 -13.914628)
		(width 0.12954)
		(layer "B.Cu")
		(net "SMB_VR_SENSOR_3V3AUX_SCL")
	)
	(segment
		(start 180.814218 -14.34465)
		(end 180.814218 -14.172438)
		(width 0.12954)
		(layer "B.Cu")
		(net "SMB_VR_SENSOR_3V3AUX_SCL")
	)
	(segment
		(start 50.98288 -18.867628)
		(end 51.50104 -18.349468)
		(width 0.12954)
		(layer "B.Cu")
		(net "SMB_VR_SENSOR_3V3AUX_SCL")
	)
	(segment
		(start 55.96128 -105.522268)
		(end 55.96128 -83.398106)
		(width 0.12954)
		(layer "B.Cu")
		(net "SMB_VR_SENSOR_3V3AUX_SCL")
	)
	(segment
		(start 47.27448 -6.608572)
		(end 47.27448 -6.137148)
		(width 0.12954)
		(layer "B.Cu")
		(net "SMB_VR_SENSOR_3V3AUX_SCL")
	)
	(segment
		(start 65.60566 -116.020088)
		(end 58.05678 -108.471208)
		(width 0.12954)
		(layer "B.Cu")
		(net "SMB_VR_SENSOR_3V3AUX_SCL")
	)
	(segment
		(start 80.19288 -11.557508)
		(end 82.31632 -13.680948)
		(width 0.127)
		(layer "In13.Cu")
		(net "SMB_VR_SENSOR_3V3AUX_SCL")
	)
	(segment
		(start 179.544218 -14.454886)
		(end 179.544218 -14.782038)
		(width 0.127)
		(layer "In13.Cu")
		(net "SMB_VR_SENSOR_3V3AUX_SCL")
	)
	(segment
		(start 178.44008 -13.350748)
		(end 179.544218 -14.454886)
		(width 0.127)
		(layer "In13.Cu")
		(net "SMB_VR_SENSOR_3V3AUX_SCL")
	)
	(segment
		(start 48.74768 -5.806948)
		(end 48.74768 -7.534148)
		(width 0.127)
		(layer "In13.Cu")
		(net "SMB_VR_SENSOR_3V3AUX_SCL")
	)
	(segment
		(start 66.83248 -7.280148)
		(end 68.83908 -7.280148)
		(width 0.127)
		(layer "In13.Cu")
		(net "SMB_VR_SENSOR_3V3AUX_SCL")
	)
	(segment
		(start 78.28788 -8.550148)
		(end 80.19288 -10.455148)
		(width 0.127)
		(layer "In13.Cu")
		(net "SMB_VR_SENSOR_3V3AUX_SCL")
	)
	(segment
		(start 133.60908 -13.680948)
		(end 134.29488 -12.995148)
		(width 0.127)
		(layer "In13.Cu")
		(net "SMB_VR_SENSOR_3V3AUX_SCL")
	)
	(segment
		(start 49.17948 -7.965948)
		(end 66.14668 -7.965948)
		(width 0.127)
		(layer "In13.Cu")
		(net "SMB_VR_SENSOR_3V3AUX_SCL")
	)
	(segment
		(start 146.107912 -12.995148)
		(end 147.172172 -11.930888)
		(width 0.127)
		(layer "In13.Cu")
		(net "SMB_VR_SENSOR_3V3AUX_SCL")
	)
	(segment
		(start 149.62632 -11.930888)
		(end 151.04618 -13.350748)
		(width 0.127)
		(layer "In13.Cu")
		(net "SMB_VR_SENSOR_3V3AUX_SCL")
	)
	(segment
		(start 80.19288 -10.455148)
		(end 80.19288 -11.557508)
		(width 0.127)
		(layer "In13.Cu")
		(net "SMB_VR_SENSOR_3V3AUX_SCL")
	)
	(segment
		(start 48.74768 -7.534148)
		(end 49.17948 -7.965948)
		(width 0.127)
		(layer "In13.Cu")
		(net "SMB_VR_SENSOR_3V3AUX_SCL")
	)
	(segment
		(start 70.10908 -8.550148)
		(end 78.28788 -8.550148)
		(width 0.127)
		(layer "In13.Cu")
		(net "SMB_VR_SENSOR_3V3AUX_SCL")
	)
	(segment
		(start 147.172172 -11.930888)
		(end 149.62632 -11.930888)
		(width 0.127)
		(layer "In13.Cu")
		(net "SMB_VR_SENSOR_3V3AUX_SCL")
	)
	(segment
		(start 47.27448 -6.137148)
		(end 47.27448 -5.679948)
		(width 0.127)
		(layer "In13.Cu")
		(net "SMB_VR_SENSOR_3V3AUX_SCL")
	)
	(segment
		(start 66.14668 -7.965948)
		(end 66.83248 -7.280148)
		(width 0.127)
		(layer "In13.Cu")
		(net "SMB_VR_SENSOR_3V3AUX_SCL")
	)
	(segment
		(start 68.83908 -7.280148)
		(end 70.10908 -8.550148)
		(width 0.127)
		(layer "In13.Cu")
		(net "SMB_VR_SENSOR_3V3AUX_SCL")
	)
	(segment
		(start 151.04618 -13.350748)
		(end 178.44008 -13.350748)
		(width 0.127)
		(layer "In13.Cu")
		(net "SMB_VR_SENSOR_3V3AUX_SCL")
	)
	(segment
		(start 47.27448 -5.679948)
		(end 47.52848 -5.425948)
		(width 0.127)
		(layer "In13.Cu")
		(net "SMB_VR_SENSOR_3V3AUX_SCL")
	)
	(segment
		(start 134.29488 -12.995148)
		(end 146.107912 -12.995148)
		(width 0.127)
		(layer "In13.Cu")
		(net "SMB_VR_SENSOR_3V3AUX_SCL")
	)
	(segment
		(start 48.36668 -5.425948)
		(end 48.74768 -5.806948)
		(width 0.127)
		(layer "In13.Cu")
		(net "SMB_VR_SENSOR_3V3AUX_SCL")
	)
	(segment
		(start 82.31632 -13.680948)
		(end 133.60908 -13.680948)
		(width 0.127)
		(layer "In13.Cu")
		(net "SMB_VR_SENSOR_3V3AUX_SCL")
	)
	(segment
		(start 47.52848 -5.425948)
		(end 48.36668 -5.425948)
		(width 0.127)
		(layer "In13.Cu")
		(net "SMB_VR_SENSOR_3V3AUX_SCL")
	)
	(segment
		(start 55.88 -113.97869)
		(end 56.274716 -113.97869)
		(width 0.12954)
		(layer "F.Cu")
		(net "SMB_VR_3V3AUX_SDA_R6")
	)
	(segment
		(start 57.401968 -112.851438)
		(end 58.37555 -112.851438)
		(width 0.12954)
		(layer "F.Cu")
		(net "SMB_VR_3V3AUX_SDA_R6")
	)
	(segment
		(start 56.274716 -113.97869)
		(end 57.401968 -112.851438)
		(width 0.12954)
		(layer "F.Cu")
		(net "SMB_VR_3V3AUX_SDA_R6")
	)
	(segment
		(start 54.642766 -113.97869)
		(end 55.88 -113.97869)
		(width 0.12954)
		(layer "F.Cu")
		(net "SMB_VR_3V3AUX_SDA_R6")
	)
	(via
		(at 55.88 -113.97869)
		(size 0.508)
		(drill 0.254)
		(layers "F.Cu" "B.Cu")
		(net "SMB_VR_3V3AUX_SDA_R6")
	)
	(segment
		(start 57.162954 -112.201452)
		(end 56.810656 -112.55375)
		(width 0.12954)
		(layer "F.Cu")
		(net "SMB_VR_3V3AUX_SCL_R6")
	)
	(segment
		(start 56.810656 -112.55375)
		(end 56.401716 -112.96269)
		(width 0.12954)
		(layer "F.Cu")
		(net "SMB_VR_3V3AUX_SCL_R6")
	)
	(segment
		(start 58.37555 -112.201452)
		(end 57.162954 -112.201452)
		(width 0.12954)
		(layer "F.Cu")
		(net "SMB_VR_3V3AUX_SCL_R6")
	)
	(segment
		(start 56.401716 -112.96269)
		(end 54.642766 -112.96269)
		(width 0.12954)
		(layer "F.Cu")
		(net "SMB_VR_3V3AUX_SCL_R6")
	)
	(via
		(at 56.810656 -112.55375)
		(size 0.508)
		(drill 0.254)
		(layers "F.Cu" "B.Cu")
		(net "SMB_VR_3V3AUX_SCL_R6")
	)
	(segment
		(start 67.558666 -107.24769)
		(end 67.685666 -107.37469)
		(width 0.12954)
		(layer "F.Cu")
		(net "SMB_LM75_3_3V3AUX_SDA_R")
	)
	(segment
		(start 66.91122 -107.24769)
		(end 67.558666 -107.24769)
		(width 0.12954)
		(layer "F.Cu")
		(net "SMB_LM75_3_3V3AUX_SDA_R")
	)
	(segment
		(start 65.291716 -107.24769)
		(end 66.91122 -107.24769)
		(width 0.12954)
		(layer "F.Cu")
		(net "SMB_LM75_3_3V3AUX_SDA_R")
	)
	(segment
		(start 64.88811 -107.651296)
		(end 65.291716 -107.24769)
		(width 0.12954)
		(layer "F.Cu")
		(net "SMB_LM75_3_3V3AUX_SDA_R")
	)
	(segment
		(start 63.975742 -107.651296)
		(end 64.88811 -107.651296)
		(width 0.12954)
		(layer "F.Cu")
		(net "SMB_LM75_3_3V3AUX_SDA_R")
	)
	(via
		(at 66.91122 -107.24769)
		(size 0.508)
		(drill 0.254)
		(layers "F.Cu" "B.Cu")
		(net "SMB_LM75_3_3V3AUX_SDA_R")
	)
	(segment
		(start 64.948308 -108.301282)
		(end 63.975742 -108.301282)
		(width 0.12954)
		(layer "F.Cu")
		(net "SMB_LM75_3_3V3AUX_SCL_R")
	)
	(segment
		(start 65.548764 -108.39069)
		(end 65.037716 -108.39069)
		(width 0.12954)
		(layer "F.Cu")
		(net "SMB_LM75_3_3V3AUX_SCL_R")
	)
	(segment
		(start 65.037716 -108.39069)
		(end 64.948308 -108.301282)
		(width 0.12954)
		(layer "F.Cu")
		(net "SMB_LM75_3_3V3AUX_SCL_R")
	)
	(segment
		(start 67.685666 -108.39069)
		(end 65.548764 -108.39069)
		(width 0.12954)
		(layer "F.Cu")
		(net "SMB_LM75_3_3V3AUX_SCL_R")
	)
	(via
		(at 65.548764 -108.39069)
		(size 0.508)
		(drill 0.254)
		(layers "F.Cu" "B.Cu")
		(net "SMB_LM75_3_3V3AUX_SCL_R")
	)
	(segment
		(start 56.55818 -108.951268)
		(end 55.87873 -108.271818)
		(width 0.12954)
		(layer "F.Cu")
		(net "SMB_LM75_2_3V3AUX_SDA_R")
	)
	(segment
		(start 58.37555 -108.951268)
		(end 56.55818 -108.951268)
		(width 0.12954)
		(layer "F.Cu")
		(net "SMB_LM75_2_3V3AUX_SDA_R")
	)
	(segment
		(start 55.87873 -108.271818)
		(end 55.489602 -107.88269)
		(width 0.12954)
		(layer "F.Cu")
		(net "SMB_LM75_2_3V3AUX_SDA_R")
	)
	(segment
		(start 55.489602 -107.88269)
		(end 54.642766 -107.88269)
		(width 0.12954)
		(layer "F.Cu")
		(net "SMB_LM75_2_3V3AUX_SDA_R")
	)
	(via
		(at 55.87873 -108.271818)
		(size 0.508)
		(drill 0.254)
		(layers "F.Cu" "B.Cu")
		(net "SMB_LM75_2_3V3AUX_SDA_R")
	)
	(segment
		(start 56.404002 -106.86669)
		(end 54.642766 -106.86669)
		(width 0.12954)
		(layer "F.Cu")
		(net "SMB_LM75_2_3V3AUX_SCL_R")
	)
	(segment
		(start 56.97347 -107.436158)
		(end 56.404002 -106.86669)
		(width 0.12954)
		(layer "F.Cu")
		(net "SMB_LM75_2_3V3AUX_SCL_R")
	)
	(segment
		(start 58.37555 -108.301282)
		(end 57.416446 -108.301282)
		(width 0.12954)
		(layer "F.Cu")
		(net "SMB_LM75_2_3V3AUX_SCL_R")
	)
	(segment
		(start 57.416446 -108.301282)
		(end 56.97347 -107.858306)
		(width 0.12954)
		(layer "F.Cu")
		(net "SMB_LM75_2_3V3AUX_SCL_R")
	)
	(segment
		(start 56.97347 -107.858306)
		(end 56.97347 -107.436158)
		(width 0.12954)
		(layer "F.Cu")
		(net "SMB_LM75_2_3V3AUX_SCL_R")
	)
	(via
		(at 56.97347 -107.436158)
		(size 0.508)
		(drill 0.254)
		(layers "F.Cu" "B.Cu")
		(net "SMB_LM75_2_3V3AUX_SCL_R")
	)
	(segment
		(start 55.71109 -110.25124)
		(end 58.37555 -110.25124)
		(width 0.12954)
		(layer "F.Cu")
		(net "SMB_LM75_1_3V3AUX_SDA_R")
	)
	(segment
		(start 55.37454 -109.91469)
		(end 55.71109 -110.25124)
		(width 0.12954)
		(layer "F.Cu")
		(net "SMB_LM75_1_3V3AUX_SDA_R")
	)
	(segment
		(start 54.642766 -109.91469)
		(end 55.37454 -109.91469)
		(width 0.12954)
		(layer "F.Cu")
		(net "SMB_LM75_1_3V3AUX_SDA_R")
	)
	(via
		(at 55.37454 -109.91469)
		(size 0.508)
		(drill 0.254)
		(layers "F.Cu" "B.Cu")
		(net "SMB_LM75_1_3V3AUX_SDA_R")
	)
	(segment
		(start 56.733694 -109.8169)
		(end 55.96001 -109.8169)
		(width 0.12954)
		(layer "F.Cu")
		(net "SMB_LM75_1_3V3AUX_SCL_R")
	)
	(segment
		(start 55.96001 -109.8169)
		(end 55.399178 -109.256068)
		(width 0.12954)
		(layer "F.Cu")
		(net "SMB_LM75_1_3V3AUX_SCL_R")
	)
	(segment
		(start 55.399178 -109.256068)
		(end 55.000144 -109.256068)
		(width 0.12954)
		(layer "F.Cu")
		(net "SMB_LM75_1_3V3AUX_SCL_R")
	)
	(segment
		(start 55.000144 -109.256068)
		(end 54.642766 -108.89869)
		(width 0.12954)
		(layer "F.Cu")
		(net "SMB_LM75_1_3V3AUX_SCL_R")
	)
	(segment
		(start 56.94934 -109.601254)
		(end 56.733694 -109.8169)
		(width 0.12954)
		(layer "F.Cu")
		(net "SMB_LM75_1_3V3AUX_SCL_R")
	)
	(segment
		(start 56.94934 -109.601254)
		(end 58.37555 -109.601254)
		(width 0.12954)
		(layer "F.Cu")
		(net "SMB_LM75_1_3V3AUX_SCL_R")
	)
	(via
		(at 56.94934 -109.601254)
		(size 0.508)
		(drill 0.254)
		(layers "F.Cu" "B.Cu")
		(net "SMB_LM75_1_3V3AUX_SCL_R")
	)
	(segment
		(start 55.637176 -111.94669)
		(end 56.0324 -111.551466)
		(width 0.12954)
		(layer "F.Cu")
		(net "SMB_LM75_0_3V3AUX_SDA_R")
	)
	(segment
		(start 56.0324 -111.551466)
		(end 58.37555 -111.551466)
		(width 0.12954)
		(layer "F.Cu")
		(net "SMB_LM75_0_3V3AUX_SDA_R")
	)
	(segment
		(start 55.40756 -111.94669)
		(end 55.637176 -111.94669)
		(width 0.12954)
		(layer "F.Cu")
		(net "SMB_LM75_0_3V3AUX_SDA_R")
	)
	(segment
		(start 54.642766 -111.94669)
		(end 55.40756 -111.94669)
		(width 0.12954)
		(layer "F.Cu")
		(net "SMB_LM75_0_3V3AUX_SDA_R")
	)
	(via
		(at 55.40756 -111.94669)
		(size 0.508)
		(drill 0.254)
		(layers "F.Cu" "B.Cu")
		(net "SMB_LM75_0_3V3AUX_SDA_R")
	)
	(segment
		(start 58.37555 -110.901226)
		(end 56.94934 -110.901226)
		(width 0.12954)
		(layer "F.Cu")
		(net "SMB_LM75_0_3V3AUX_SCL_R")
	)
	(segment
		(start 56.147716 -110.93069)
		(end 54.642766 -110.93069)
		(width 0.12954)
		(layer "F.Cu")
		(net "SMB_LM75_0_3V3AUX_SCL_R")
	)
	(segment
		(start 56.94934 -110.901226)
		(end 56.17718 -110.901226)
		(width 0.12954)
		(layer "F.Cu")
		(net "SMB_LM75_0_3V3AUX_SCL_R")
	)
	(segment
		(start 56.17718 -110.901226)
		(end 56.147716 -110.93069)
		(width 0.12954)
		(layer "F.Cu")
		(net "SMB_LM75_0_3V3AUX_SCL_R")
	)
	(via
		(at 56.94934 -110.901226)
		(size 0.508)
		(drill 0.254)
		(layers "F.Cu" "B.Cu")
		(net "SMB_LM75_0_3V3AUX_SCL_R")
	)
	(segment
		(start 23.209504 -112.399826)
		(end 24.45004 -112.399826)
		(width 0.12954)
		(layer "F.Cu")
		(net "SMB_SEN_TIC_3V3AUX_SDA")
	)
	(segment
		(start 24.45004 -112.399826)
		(end 24.738584 -112.111282)
		(width 0.12954)
		(layer "F.Cu")
		(net "SMB_SEN_TIC_3V3AUX_SDA")
	)
	(segment
		(start 24.738584 -112.111282)
		(end 25.891236 -110.95863)
		(width 0.12954)
		(layer "F.Cu")
		(net "SMB_SEN_TIC_3V3AUX_SDA")
	)
	(segment
		(start 25.891236 -110.95863)
		(end 26.915618 -110.95863)
		(width 0.12954)
		(layer "F.Cu")
		(net "SMB_SEN_TIC_3V3AUX_SDA")
	)
	(via
		(at 24.738584 -112.111282)
		(size 0.762)
		(drill 0.381)
		(layers "F.Cu" "B.Cu")
		(net "SMB_SEN_TIC_3V3AUX_SDA")
	)
	(segment
		(start 24.11984 -111.383826)
		(end 23.209504 -111.383826)
		(width 0.12954)
		(layer "F.Cu")
		(net "SMB_SEN_TIC_3V3AUX_SCL")
	)
	(segment
		(start 26.915618 -110.308644)
		(end 25.195022 -110.308644)
		(width 0.12954)
		(layer "F.Cu")
		(net "SMB_SEN_TIC_3V3AUX_SCL")
	)
	(segment
		(start 25.195022 -110.308644)
		(end 24.662384 -110.841282)
		(width 0.12954)
		(layer "F.Cu")
		(net "SMB_SEN_TIC_3V3AUX_SCL")
	)
	(segment
		(start 24.662384 -110.841282)
		(end 24.11984 -111.383826)
		(width 0.12954)
		(layer "F.Cu")
		(net "SMB_SEN_TIC_3V3AUX_SCL")
	)
	(via
		(at 24.662384 -110.841282)
		(size 0.762)
		(drill 0.381)
		(layers "F.Cu" "B.Cu")
		(net "SMB_SEN_TIC_3V3AUX_SCL")
	)
	(segment
		(start 208.10728 -43.678348)
		(end 209.98688 -45.557948)
		(width 0.12954)
		(layer "F.Cu")
		(net "RST_SMB_E1S_0_N")
	)
	(segment
		(start 162.447986 -66.091308)
		(end 162.447986 -65.537842)
		(width 0.12954)
		(layer "F.Cu")
		(net "RST_SMB_E1S_0_N")
	)
	(segment
		(start 193.17843 -59.722258)
		(end 195.83908 -57.061608)
		(width 0.12954)
		(layer "F.Cu")
		(net "RST_SMB_E1S_0_N")
	)
	(segment
		(start 164.80536 -64.912748)
		(end 169.99585 -59.722258)
		(width 0.12954)
		(layer "F.Cu")
		(net "RST_SMB_E1S_0_N")
	)
	(segment
		(start 224.49028 -45.964348)
		(end 224.60966 -46.083728)
		(width 0.12954)
		(layer "F.Cu")
		(net "RST_SMB_E1S_0_N")
	)
	(segment
		(start 209.98688 -45.557948)
		(end 220.959426 -45.557948)
		(width 0.12954)
		(layer "F.Cu")
		(net "RST_SMB_E1S_0_N")
	)
	(segment
		(start 224.60966 -46.508924)
		(end 225.776282 -47.675546)
		(width 0.12954)
		(layer "F.Cu")
		(net "RST_SMB_E1S_0_N")
	)
	(segment
		(start 220.959426 -45.557948)
		(end 221.365826 -45.964348)
		(width 0.12954)
		(layer "F.Cu")
		(net "RST_SMB_E1S_0_N")
	)
	(segment
		(start 160.055306 -66.091308)
		(end 161.24428 -66.091308)
		(width 0.12954)
		(layer "F.Cu")
		(net "RST_SMB_E1S_0_N")
	)
	(segment
		(start 161.24428 -66.091308)
		(end 162.447986 -66.091308)
		(width 0.12954)
		(layer "F.Cu")
		(net "RST_SMB_E1S_0_N")
	)
	(segment
		(start 195.83908 -48.910748)
		(end 201.07148 -43.678348)
		(width 0.12954)
		(layer "F.Cu")
		(net "RST_SMB_E1S_0_N")
	)
	(segment
		(start 201.07148 -43.678348)
		(end 208.10728 -43.678348)
		(width 0.12954)
		(layer "F.Cu")
		(net "RST_SMB_E1S_0_N")
	)
	(segment
		(start 162.447986 -65.537842)
		(end 163.07308 -64.912748)
		(width 0.12954)
		(layer "F.Cu")
		(net "RST_SMB_E1S_0_N")
	)
	(segment
		(start 224.60966 -46.083728)
		(end 224.60966 -46.508924)
		(width 0.12954)
		(layer "F.Cu")
		(net "RST_SMB_E1S_0_N")
	)
	(segment
		(start 169.99585 -59.722258)
		(end 193.17843 -59.722258)
		(width 0.12954)
		(layer "F.Cu")
		(net "RST_SMB_E1S_0_N")
	)
	(segment
		(start 224.60966 -46.524926)
		(end 224.60966 -46.508924)
		(width 0.12954)
		(layer "F.Cu")
		(net "RST_SMB_E1S_0_N")
	)
	(segment
		(start 221.365826 -45.964348)
		(end 224.49028 -45.964348)
		(width 0.12954)
		(layer "F.Cu")
		(net "RST_SMB_E1S_0_N")
	)
	(segment
		(start 225.776282 -47.675546)
		(end 230.310436 -47.675546)
		(width 0.12954)
		(layer "F.Cu")
		(net "RST_SMB_E1S_0_N")
	)
	(segment
		(start 230.621078 -47.364904)
		(end 232.000044 -47.364904)
		(width 0.12954)
		(layer "F.Cu")
		(net "RST_SMB_E1S_0_N")
	)
	(segment
		(start 230.310436 -47.675546)
		(end 230.621078 -47.364904)
		(width 0.12954)
		(layer "F.Cu")
		(net "RST_SMB_E1S_0_N")
	)
	(segment
		(start 195.83908 -57.061608)
		(end 195.83908 -48.910748)
		(width 0.12954)
		(layer "F.Cu")
		(net "RST_SMB_E1S_0_N")
	)
	(segment
		(start 163.07308 -64.912748)
		(end 164.80536 -64.912748)
		(width 0.12954)
		(layer "F.Cu")
		(net "RST_SMB_E1S_0_N")
	)
	(via
		(at 161.24428 -66.091308)
		(size 0.762)
		(drill 0.381)
		(layers "F.Cu" "B.Cu")
		(net "RST_SMB_E1S_0_N")
	)
	(segment
		(start 238.867696 -46.78426)
		(end 239.073182 -46.989746)
		(width 0.12954)
		(layer "F.Cu")
		(net "PU_E1S_0_DUALPORT_EN_N")
	)
	(segment
		(start 239.586262 -46.989746)
		(end 239.60836 -46.967648)
		(width 0.12954)
		(layer "F.Cu")
		(net "PU_E1S_0_DUALPORT_EN_N")
	)
	(segment
		(start 236.599984 -47.364904)
		(end 238.287052 -47.364904)
		(width 0.12954)
		(layer "F.Cu")
		(net "PU_E1S_0_DUALPORT_EN_N")
	)
	(segment
		(start 238.287052 -47.364904)
		(end 238.867696 -46.78426)
		(width 0.12954)
		(layer "F.Cu")
		(net "PU_E1S_0_DUALPORT_EN_N")
	)
	(segment
		(start 239.073182 -46.989746)
		(end 239.586262 -46.989746)
		(width 0.12954)
		(layer "F.Cu")
		(net "PU_E1S_0_DUALPORT_EN_N")
	)
	(via
		(at 238.867696 -46.78426)
		(size 0.508)
		(drill 0.254)
		(layers "F.Cu" "B.Cu")
		(net "PU_E1S_0_DUALPORT_EN_N")
	)
	(segment
		(start 36.022534 -110.079282)
		(end 35.279584 -110.079282)
		(width 0.12954)
		(layer "F.Cu")
		(net "P5V_ADC_TIC")
	)
	(segment
		(start 37.038534 -110.079282)
		(end 36.530534 -109.571282)
		(width 0.12954)
		(layer "F.Cu")
		(net "P5V_ADC_TIC")
	)
	(segment
		(start 35.279584 -110.079282)
		(end 33.755584 -110.079282)
		(width 0.12954)
		(layer "F.Cu")
		(net "P5V_ADC_TIC")
	)
	(segment
		(start 38.104572 -110.079282)
		(end 37.038534 -110.079282)
		(width 0.12954)
		(layer "F.Cu")
		(net "P5V_ADC_TIC")
	)
	(segment
		(start 39.427404 -109.444282)
		(end 38.739572 -109.444282)
		(width 0.12954)
		(layer "F.Cu")
		(net "P5V_ADC_TIC")
	)
	(segment
		(start 33.33496 -109.658658)
		(end 32.51581 -109.658658)
		(width 0.12954)
		(layer "F.Cu")
		(net "P5V_ADC_TIC")
	)
	(segment
		(start 33.755584 -110.079282)
		(end 33.33496 -109.658658)
		(width 0.12954)
		(layer "F.Cu")
		(net "P5V_ADC_TIC")
	)
	(segment
		(start 38.739572 -109.444282)
		(end 38.104572 -110.079282)
		(width 0.12954)
		(layer "F.Cu")
		(net "P5V_ADC_TIC")
	)
	(segment
		(start 36.530534 -109.571282)
		(end 36.022534 -110.079282)
		(width 0.12954)
		(layer "F.Cu")
		(net "P5V_ADC_TIC")
	)
	(via
		(at 35.279584 -110.079282)
		(size 0.762)
		(drill 0.381)
		(layers "F.Cu" "B.Cu")
		(net "P5V_ADC_TIC")
	)
	(segment
		(start 35.428428 -97.554034)
		(end 36.143184 -98.26879)
		(width 0.12954)
		(layer "F.Cu")
		(net "P5V_ADC_MAM")
	)
	(segment
		(start 41.027604 -109.444282)
		(end 41.637204 -109.444282)
		(width 0.12954)
		(layer "F.Cu")
		(net "P5V_ADC_MAM")
	)
	(segment
		(start 36.143184 -98.26879)
		(end 36.988496 -98.26879)
		(width 0.12954)
		(layer "F.Cu")
		(net "P5V_ADC_MAM")
	)
	(segment
		(start 35.174428 -97.554034)
		(end 35.428428 -97.554034)
		(width 0.12954)
		(layer "F.Cu")
		(net "P5V_ADC_MAM")
	)
	(segment
		(start 32.08528 -96.357948)
		(end 33.161478 -97.434146)
		(width 0.254)
		(layer "F.Cu")
		(net "P5V_ADC_MAM")
	)
	(segment
		(start 33.161478 -97.554034)
		(end 35.174428 -97.554034)
		(width 0.12954)
		(layer "F.Cu")
		(net "P5V_ADC_MAM")
	)
	(segment
		(start 30.45968 -96.357948)
		(end 32.08528 -96.357948)
		(width 0.254)
		(layer "F.Cu")
		(net "P5V_ADC_MAM")
	)
	(segment
		(start 33.161478 -97.434146)
		(end 33.161478 -97.554034)
		(width 0.254)
		(layer "F.Cu")
		(net "P5V_ADC_MAM")
	)
	(via
		(at 41.637204 -109.444282)
		(size 0.508)
		(drill 0.254)
		(layers "F.Cu" "B.Cu")
		(net "P5V_ADC_MAM")
	)
	(via
		(at 35.174428 -97.554034)
		(size 0.762)
		(drill 0.381)
		(layers "F.Cu" "B.Cu")
		(net "P5V_ADC_MAM")
	)
	(via
		(at 30.45968 -96.357948)
		(size 0.508)
		(drill 0.254)
		(layers "F.Cu" "B.Cu")
		(net "P5V_ADC_MAM")
	)
	(segment
		(start 41.002204 -109.571282)
		(end 40.535606 -109.571282)
		(width 0.254)
		(layer "In2.Cu")
		(net "P5V_ADC_MAM")
	)
	(segment
		(start 40.3225 -109.784388)
		(end 40.3225 -112.878108)
		(width 0.254)
		(layer "In2.Cu")
		(net "P5V_ADC_MAM")
	)
	(segment
		(start 30.52826 -102.433628)
		(end 29.39034 -101.295708)
		(width 0.254)
		(layer "In2.Cu")
		(net "P5V_ADC_MAM")
	)
	(segment
		(start 30.52826 -108.621068)
		(end 30.52826 -102.433628)
		(width 0.254)
		(layer "In2.Cu")
		(net "P5V_ADC_MAM")
	)
	(segment
		(start 29.39034 -97.427288)
		(end 30.45968 -96.357948)
		(width 0.254)
		(layer "In2.Cu")
		(net "P5V_ADC_MAM")
	)
	(segment
		(start 41.129204 -109.444282)
		(end 41.002204 -109.571282)
		(width 0.254)
		(layer "In2.Cu")
		(net "P5V_ADC_MAM")
	)
	(segment
		(start 40.3225 -112.878108)
		(end 39.81958 -113.381028)
		(width 0.254)
		(layer "In2.Cu")
		(net "P5V_ADC_MAM")
	)
	(segment
		(start 39.81958 -113.381028)
		(end 35.28822 -113.381028)
		(width 0.254)
		(layer "In2.Cu")
		(net "P5V_ADC_MAM")
	)
	(segment
		(start 40.535606 -109.571282)
		(end 40.3225 -109.784388)
		(width 0.254)
		(layer "In2.Cu")
		(net "P5V_ADC_MAM")
	)
	(segment
		(start 41.637204 -109.444282)
		(end 41.129204 -109.444282)
		(width 0.254)
		(layer "In2.Cu")
		(net "P5V_ADC_MAM")
	)
	(segment
		(start 29.39034 -101.295708)
		(end 29.39034 -97.427288)
		(width 0.254)
		(layer "In2.Cu")
		(net "P5V_ADC_MAM")
	)
	(segment
		(start 35.28822 -113.381028)
		(end 30.52826 -108.621068)
		(width 0.254)
		(layer "In2.Cu")
		(net "P5V_ADC_MAM")
	)
	(segment
		(start 43.769534 -109.444282)
		(end 43.464226 -109.444282)
		(width 0.254)
		(layer "F.Cu")
		(net "P5V_ADC")
	)
	(segment
		(start 40.227504 -109.80293)
		(end 40.435784 -110.01121)
		(width 0.254)
		(layer "F.Cu")
		(net "P5V_ADC")
	)
	(segment
		(start 40.435784 -110.01121)
		(end 42.31132 -110.01121)
		(width 0.254)
		(layer "F.Cu")
		(net "P5V_ADC")
	)
	(segment
		(start 43.769534 -109.641894)
		(end 44.150026 -110.022386)
		(width 0.254)
		(layer "F.Cu")
		(net "P5V_ADC")
	)
	(segment
		(start 43.769534 -109.444282)
		(end 43.769534 -109.641894)
		(width 0.254)
		(layer "F.Cu")
		(net "P5V_ADC")
	)
	(segment
		(start 40.227504 -109.444282)
		(end 40.227504 -109.80293)
		(width 0.254)
		(layer "F.Cu")
		(net "P5V_ADC")
	)
	(segment
		(start 42.897298 -110.01121)
		(end 42.31132 -110.01121)
		(width 0.254)
		(layer "F.Cu")
		(net "P5V_ADC")
	)
	(segment
		(start 46.182534 -109.664246)
		(end 46.182534 -109.444282)
		(width 0.254)
		(layer "F.Cu")
		(net "P5V_ADC")
	)
	(segment
		(start 43.464226 -109.444282)
		(end 42.897298 -110.01121)
		(width 0.254)
		(layer "F.Cu")
		(net "P5V_ADC")
	)
	(segment
		(start 44.150026 -110.022386)
		(end 45.824394 -110.022386)
		(width 0.254)
		(layer "F.Cu")
		(net "P5V_ADC")
	)
	(segment
		(start 45.824394 -110.022386)
		(end 46.182534 -109.664246)
		(width 0.254)
		(layer "F.Cu")
		(net "P5V_ADC")
	)
	(via
		(at 42.31132 -110.01121)
		(size 0.762)
		(drill 0.381)
		(layers "F.Cu" "B.Cu")
		(net "P5V_ADC")
	)
	(segment
		(start 37.02431 -107.017058)
		(end 36.530534 -106.523282)
		(width 0.12954)
		(layer "F.Cu")
		(net "P3V3_PDB_AUX_ADC_TIC")
	)
	(segment
		(start 39.427404 -106.015282)
		(end 38.425628 -107.017058)
		(width 0.12954)
		(layer "F.Cu")
		(net "P3V3_PDB_AUX_ADC_TIC")
	)
	(segment
		(start 33.628584 -107.412282)
		(end 33.33242 -107.708446)
		(width 0.12954)
		(layer "F.Cu")
		(net "P3V3_PDB_AUX_ADC_TIC")
	)
	(segment
		(start 35.641534 -107.412282)
		(end 34.263584 -107.412282)
		(width 0.12954)
		(layer "F.Cu")
		(net "P3V3_PDB_AUX_ADC_TIC")
	)
	(segment
		(start 36.530534 -106.523282)
		(end 35.641534 -107.412282)
		(width 0.12954)
		(layer "F.Cu")
		(net "P3V3_PDB_AUX_ADC_TIC")
	)
	(segment
		(start 38.425628 -107.017058)
		(end 37.02431 -107.017058)
		(width 0.12954)
		(layer "F.Cu")
		(net "P3V3_PDB_AUX_ADC_TIC")
	)
	(segment
		(start 33.33242 -107.708446)
		(end 32.51581 -107.708446)
		(width 0.12954)
		(layer "F.Cu")
		(net "P3V3_PDB_AUX_ADC_TIC")
	)
	(segment
		(start 34.263584 -107.412282)
		(end 33.628584 -107.412282)
		(width 0.12954)
		(layer "F.Cu")
		(net "P3V3_PDB_AUX_ADC_TIC")
	)
	(via
		(at 34.263584 -107.412282)
		(size 0.762)
		(drill 0.381)
		(layers "F.Cu" "B.Cu")
		(net "P3V3_PDB_AUX_ADC_TIC")
	)
	(segment
		(start 48.48352 -99.334828)
		(end 46.455584 -99.334828)
		(width 0.12954)
		(layer "F.Cu")
		(net "P3V3_PDB_AUX_ADC_MAM")
	)
	(segment
		(start 43.370246 -99.296728)
		(end 43.128184 -99.53879)
		(width 0.12954)
		(layer "F.Cu")
		(net "P3V3_PDB_AUX_ADC_MAM")
	)
	(segment
		(start 46.455584 -99.334828)
		(end 45.950378 -99.840034)
		(width 0.12954)
		(layer "F.Cu")
		(net "P3V3_PDB_AUX_ADC_MAM")
	)
	(segment
		(start 44.699428 -99.586034)
		(end 44.410122 -99.296728)
		(width 0.12954)
		(layer "F.Cu")
		(net "P3V3_PDB_AUX_ADC_MAM")
	)
	(segment
		(start 43.128184 -99.53879)
		(end 42.29862 -99.53879)
		(width 0.12954)
		(layer "F.Cu")
		(net "P3V3_PDB_AUX_ADC_MAM")
	)
	(segment
		(start 41.142666 -106.015282)
		(end 41.656 -105.501948)
		(width 0.12954)
		(layer "F.Cu")
		(net "P3V3_PDB_AUX_ADC_MAM")
	)
	(segment
		(start 44.953428 -99.840034)
		(end 44.699428 -99.586034)
		(width 0.12954)
		(layer "F.Cu")
		(net "P3V3_PDB_AUX_ADC_MAM")
	)
	(segment
		(start 44.410122 -99.296728)
		(end 43.370246 -99.296728)
		(width 0.12954)
		(layer "F.Cu")
		(net "P3V3_PDB_AUX_ADC_MAM")
	)
	(segment
		(start 45.950378 -99.840034)
		(end 44.953428 -99.840034)
		(width 0.12954)
		(layer "F.Cu")
		(net "P3V3_PDB_AUX_ADC_MAM")
	)
	(segment
		(start 41.027604 -106.015282)
		(end 41.142666 -106.015282)
		(width 0.12954)
		(layer "F.Cu")
		(net "P3V3_PDB_AUX_ADC_MAM")
	)
	(via
		(at 41.656 -105.501948)
		(size 0.508)
		(drill 0.254)
		(layers "F.Cu" "B.Cu")
		(net "P3V3_PDB_AUX_ADC_MAM")
	)
	(via
		(at 48.48352 -99.334828)
		(size 0.508)
		(drill 0.254)
		(layers "F.Cu" "B.Cu")
		(net "P3V3_PDB_AUX_ADC_MAM")
	)
	(via
		(at 44.699428 -99.586034)
		(size 0.762)
		(drill 0.381)
		(layers "F.Cu" "B.Cu")
		(net "P3V3_PDB_AUX_ADC_MAM")
	)
	(segment
		(start 48.48352 -99.565968)
		(end 47.1678 -100.881688)
		(width 0.254)
		(layer "B.Cu")
		(net "P3V3_PDB_AUX_ADC_MAM")
	)
	(segment
		(start 42.3926 -104.765348)
		(end 41.656 -105.501948)
		(width 0.254)
		(layer "B.Cu")
		(net "P3V3_PDB_AUX_ADC_MAM")
	)
	(segment
		(start 43.98518 -103.030528)
		(end 42.63898 -103.030528)
		(width 0.254)
		(layer "B.Cu")
		(net "P3V3_PDB_AUX_ADC_MAM")
	)
	(segment
		(start 42.63898 -103.030528)
		(end 42.3926 -103.276908)
		(width 0.254)
		(layer "B.Cu")
		(net "P3V3_PDB_AUX_ADC_MAM")
	)
	(segment
		(start 47.1678 -100.881688)
		(end 46.13402 -100.881688)
		(width 0.254)
		(layer "B.Cu")
		(net "P3V3_PDB_AUX_ADC_MAM")
	)
	(segment
		(start 46.13402 -100.881688)
		(end 43.98518 -103.030528)
		(width 0.254)
		(layer "B.Cu")
		(net "P3V3_PDB_AUX_ADC_MAM")
	)
	(segment
		(start 48.48352 -99.334828)
		(end 48.48352 -99.565968)
		(width 0.254)
		(layer "B.Cu")
		(net "P3V3_PDB_AUX_ADC_MAM")
	)
	(segment
		(start 42.3926 -103.276908)
		(end 42.3926 -104.765348)
		(width 0.254)
		(layer "B.Cu")
		(net "P3V3_PDB_AUX_ADC_MAM")
	)
	(segment
		(start 43.816778 -105.97007)
		(end 42.688256 -104.841548)
		(width 0.254)
		(layer "F.Cu")
		(net "P3V3_PDB_AUX_ADC")
	)
	(segment
		(start 42.688256 -104.841548)
		(end 41.16705 -104.841548)
		(width 0.254)
		(layer "F.Cu")
		(net "P3V3_PDB_AUX_ADC")
	)
	(segment
		(start 41.16705 -104.841548)
		(end 41.01465 -104.993948)
		(width 0.254)
		(layer "F.Cu")
		(net "P3V3_PDB_AUX_ADC")
	)
	(via
		(at 226.9363 -131.282948)
		(size 0.508)
		(drill 0.254)
		(layers "F.Cu" "B.Cu")
		(net "P3V3_PDB_AUX_ADC")
	)
	(via
		(at 182.1942 -393.03198)
		(size 0.508)
		(drill 0.254)
		(layers "F.Cu" "B.Cu")
		(net "P3V3_PDB_AUX_ADC")
	)
	(via
		(at 180.04282 -412.27121)
		(size 0.508)
		(drill 0.254)
		(layers "F.Cu" "B.Cu")
		(net "P3V3_PDB_AUX_ADC")
	)
	(via
		(at 43.816778 -105.97007)
		(size 0.508)
		(drill 0.254)
		(layers "F.Cu" "B.Cu")
		(net "P3V3_PDB_AUX_ADC")
	)
	(segment
		(start 178.44897 -412.27121)
		(end 177.4952 -411.31744)
		(width 0.254)
		(layer "B.Cu")
		(net "P3V3_PDB_AUX_ADC")
	)
	(segment
		(start 178.49342 -394.46708)
		(end 180.7591 -394.46708)
		(width 0.254)
		(layer "B.Cu")
		(net "P3V3_PDB_AUX_ADC")
	)
	(segment
		(start 177.4952 -397.73098)
		(end 178.18481 -397.04137)
		(width 0.254)
		(layer "B.Cu")
		(net "P3V3_PDB_AUX_ADC")
	)
	(segment
		(start 178.18481 -397.04137)
		(end 178.18481 -394.77569)
		(width 0.254)
		(layer "B.Cu")
		(net "P3V3_PDB_AUX_ADC")
	)
	(segment
		(start 180.04282 -412.27121)
		(end 178.44897 -412.27121)
		(width 0.254)
		(layer "B.Cu")
		(net "P3V3_PDB_AUX_ADC")
	)
	(segment
		(start 180.7591 -394.46708)
		(end 182.1942 -393.03198)
		(width 0.254)
		(layer "B.Cu")
		(net "P3V3_PDB_AUX_ADC")
	)
	(segment
		(start 177.4952 -411.31744)
		(end 177.4952 -397.73098)
		(width 0.254)
		(layer "B.Cu")
		(net "P3V3_PDB_AUX_ADC")
	)
	(segment
		(start 178.18481 -394.77569)
		(end 178.49342 -394.46708)
		(width 0.254)
		(layer "B.Cu")
		(net "P3V3_PDB_AUX_ADC")
	)
	(segment
		(start 227.48494 -133.346952)
		(end 226.9363 -132.798312)
		(width 0.254)
		(layer "In2.Cu")
		(net "P3V3_PDB_AUX_ADC")
	)
	(segment
		(start 218.01836 -374.98528)
		(end 227.94468 -365.05896)
		(width 0.254)
		(layer "In2.Cu")
		(net "P3V3_PDB_AUX_ADC")
	)
	(segment
		(start 190.5381 -427.406054)
		(end 190.5381 -430.713134)
		(width 0.254)
		(layer "In2.Cu")
		(net "P3V3_PDB_AUX_ADC")
	)
	(segment
		(start 182.51678 -391.9728)
		(end 199.5043 -374.98528)
		(width 0.254)
		(layer "In2.Cu")
		(net "P3V3_PDB_AUX_ADC")
	)
	(segment
		(start 250.7996 -238.383826)
		(end 250.7996 -161.127948)
		(width 0.254)
		(layer "In2.Cu")
		(net "P3V3_PDB_AUX_ADC")
	)
	(segment
		(start 182.153052 -412.27121)
		(end 185.91403 -416.032188)
		(width 0.254)
		(layer "In2.Cu")
		(net "P3V3_PDB_AUX_ADC")
	)
	(segment
		(start 185.91403 -416.032188)
		(end 185.91403 -422.781984)
		(width 0.254)
		(layer "In2.Cu")
		(net "P3V3_PDB_AUX_ADC")
	)
	(segment
		(start 182.51678 -392.7094)
		(end 182.51678 -391.9728)
		(width 0.254)
		(layer "In2.Cu")
		(net "P3V3_PDB_AUX_ADC")
	)
	(segment
		(start 180.04282 -412.27121)
		(end 182.153052 -412.27121)
		(width 0.254)
		(layer "In2.Cu")
		(net "P3V3_PDB_AUX_ADC")
	)
	(segment
		(start 182.1942 -393.03198)
		(end 182.51678 -392.7094)
		(width 0.254)
		(layer "In2.Cu")
		(net "P3V3_PDB_AUX_ADC")
	)
	(segment
		(start 230.9495 -438.00268)
		(end 233.37012 -435.58206)
		(width 0.254)
		(layer "In2.Cu")
		(net "P3V3_PDB_AUX_ADC")
	)
	(segment
		(start 199.5043 -374.98528)
		(end 218.01836 -374.98528)
		(width 0.254)
		(layer "In2.Cu")
		(net "P3V3_PDB_AUX_ADC")
	)
	(segment
		(start 227.94468 -346.796868)
		(end 251.8664 -322.875148)
		(width 0.254)
		(layer "In2.Cu")
		(net "P3V3_PDB_AUX_ADC")
	)
	(segment
		(start 251.8664 -239.450626)
		(end 250.7996 -238.383826)
		(width 0.254)
		(layer "In2.Cu")
		(net "P3V3_PDB_AUX_ADC")
	)
	(segment
		(start 197.827646 -438.00268)
		(end 230.9495 -438.00268)
		(width 0.254)
		(layer "In2.Cu")
		(net "P3V3_PDB_AUX_ADC")
	)
	(segment
		(start 190.5381 -430.713134)
		(end 197.827646 -438.00268)
		(width 0.254)
		(layer "In2.Cu")
		(net "P3V3_PDB_AUX_ADC")
	)
	(segment
		(start 250.7996 -161.127948)
		(end 227.48494 -137.813288)
		(width 0.254)
		(layer "In2.Cu")
		(net "P3V3_PDB_AUX_ADC")
	)
	(segment
		(start 227.94468 -365.05896)
		(end 227.94468 -346.796868)
		(width 0.254)
		(layer "In2.Cu")
		(net "P3V3_PDB_AUX_ADC")
	)
	(segment
		(start 226.9363 -132.798312)
		(end 226.9363 -131.282948)
		(width 0.254)
		(layer "In2.Cu")
		(net "P3V3_PDB_AUX_ADC")
	)
	(segment
		(start 251.8664 -322.875148)
		(end 251.8664 -239.450626)
		(width 0.254)
		(layer "In2.Cu")
		(net "P3V3_PDB_AUX_ADC")
	)
	(segment
		(start 185.91403 -422.781984)
		(end 190.5381 -427.406054)
		(width 0.254)
		(layer "In2.Cu")
		(net "P3V3_PDB_AUX_ADC")
	)
	(segment
		(start 227.48494 -137.813288)
		(end 227.48494 -133.346952)
		(width 0.254)
		(layer "In2.Cu")
		(net "P3V3_PDB_AUX_ADC")
	)
	(segment
		(start 212.9663 -131.9784)
		(end 212.4837 -132.461)
		(width 0.254)
		(layer "In15.Cu")
		(net "P3V3_PDB_AUX_ADC")
	)
	(segment
		(start 49.48428 -99.451668)
		(end 49.0347 -99.901248)
		(width 0.254)
		(layer "In15.Cu")
		(net "P3V3_PDB_AUX_ADC")
	)
	(segment
		(start 221.030038 -130.82778)
		(end 219.879418 -131.9784)
		(width 0.254)
		(layer "In15.Cu")
		(net "P3V3_PDB_AUX_ADC")
	)
	(segment
		(start 149.559772 -134.627112)
		(end 138.488928 -123.556268)
		(width 0.254)
		(layer "In15.Cu")
		(net "P3V3_PDB_AUX_ADC")
	)
	(segment
		(start 91.21902 -122.954288)
		(end 63.26251 -94.997778)
		(width 0.254)
		(layer "In15.Cu")
		(net "P3V3_PDB_AUX_ADC")
	)
	(segment
		(start 49.48428 -98.814128)
		(end 49.48428 -99.451668)
		(width 0.254)
		(layer "In15.Cu")
		(net "P3V3_PDB_AUX_ADC")
	)
	(segment
		(start 226.9363 -131.282948)
		(end 226.3267 -130.673348)
		(width 0.254)
		(layer "In15.Cu")
		(net "P3V3_PDB_AUX_ADC")
	)
	(segment
		(start 44.177458 -105.97007)
		(end 43.816778 -105.97007)
		(width 0.254)
		(layer "In15.Cu")
		(net "P3V3_PDB_AUX_ADC")
	)
	(segment
		(start 195.72986 -136.89076)
		(end 194.99834 -136.15924)
		(width 0.254)
		(layer "In15.Cu")
		(net "P3V3_PDB_AUX_ADC")
	)
	(segment
		(start 53.30063 -94.997778)
		(end 49.48428 -98.814128)
		(width 0.254)
		(layer "In15.Cu")
		(net "P3V3_PDB_AUX_ADC")
	)
	(segment
		(start 207.50784 -136.89076)
		(end 195.72986 -136.89076)
		(width 0.254)
		(layer "In15.Cu")
		(net "P3V3_PDB_AUX_ADC")
	)
	(segment
		(start 49.0347 -99.901248)
		(end 49.0347 -102.065328)
		(width 0.254)
		(layer "In15.Cu")
		(net "P3V3_PDB_AUX_ADC")
	)
	(segment
		(start 138.488928 -123.556268)
		(end 129.70256 -123.556268)
		(width 0.254)
		(layer "In15.Cu")
		(net "P3V3_PDB_AUX_ADC")
	)
	(segment
		(start 209.43062 -133.83768)
		(end 209.43062 -134.96798)
		(width 0.254)
		(layer "In15.Cu")
		(net "P3V3_PDB_AUX_ADC")
	)
	(segment
		(start 224.569782 -130.82778)
		(end 221.030038 -130.82778)
		(width 0.254)
		(layer "In15.Cu")
		(net "P3V3_PDB_AUX_ADC")
	)
	(segment
		(start 164.055552 -135.48868)
		(end 163.193984 -134.627112)
		(width 0.254)
		(layer "In15.Cu")
		(net "P3V3_PDB_AUX_ADC")
	)
	(segment
		(start 209.43062 -134.96798)
		(end 207.50784 -136.89076)
		(width 0.254)
		(layer "In15.Cu")
		(net "P3V3_PDB_AUX_ADC")
	)
	(segment
		(start 194.99834 -136.15924)
		(end 179.73802 -136.15924)
		(width 0.254)
		(layer "In15.Cu")
		(net "P3V3_PDB_AUX_ADC")
	)
	(segment
		(start 47.46752 -103.632508)
		(end 46.51502 -103.632508)
		(width 0.254)
		(layer "In15.Cu")
		(net "P3V3_PDB_AUX_ADC")
	)
	(segment
		(start 179.73802 -136.15924)
		(end 179.06746 -135.48868)
		(width 0.254)
		(layer "In15.Cu")
		(net "P3V3_PDB_AUX_ADC")
	)
	(segment
		(start 129.70256 -123.556268)
		(end 129.46126 -123.797568)
		(width 0.254)
		(layer "In15.Cu")
		(net "P3V3_PDB_AUX_ADC")
	)
	(segment
		(start 110.14329 -122.954288)
		(end 91.21902 -122.954288)
		(width 0.254)
		(layer "In15.Cu")
		(net "P3V3_PDB_AUX_ADC")
	)
	(segment
		(start 46.51502 -103.632508)
		(end 44.177458 -105.97007)
		(width 0.254)
		(layer "In15.Cu")
		(net "P3V3_PDB_AUX_ADC")
	)
	(segment
		(start 63.26251 -94.997778)
		(end 53.30063 -94.997778)
		(width 0.254)
		(layer "In15.Cu")
		(net "P3V3_PDB_AUX_ADC")
	)
	(segment
		(start 179.06746 -135.48868)
		(end 164.055552 -135.48868)
		(width 0.254)
		(layer "In15.Cu")
		(net "P3V3_PDB_AUX_ADC")
	)
	(segment
		(start 224.724214 -130.673348)
		(end 224.569782 -130.82778)
		(width 0.254)
		(layer "In15.Cu")
		(net "P3V3_PDB_AUX_ADC")
	)
	(segment
		(start 219.879418 -131.9784)
		(end 212.9663 -131.9784)
		(width 0.254)
		(layer "In15.Cu")
		(net "P3V3_PDB_AUX_ADC")
	)
	(segment
		(start 210.8073 -132.461)
		(end 209.43062 -133.83768)
		(width 0.254)
		(layer "In15.Cu")
		(net "P3V3_PDB_AUX_ADC")
	)
	(segment
		(start 129.46126 -123.797568)
		(end 110.98657 -123.797568)
		(width 0.254)
		(layer "In15.Cu")
		(net "P3V3_PDB_AUX_ADC")
	)
	(segment
		(start 226.3267 -130.673348)
		(end 224.724214 -130.673348)
		(width 0.254)
		(layer "In15.Cu")
		(net "P3V3_PDB_AUX_ADC")
	)
	(segment
		(start 49.0347 -102.065328)
		(end 47.46752 -103.632508)
		(width 0.254)
		(layer "In15.Cu")
		(net "P3V3_PDB_AUX_ADC")
	)
	(segment
		(start 110.98657 -123.797568)
		(end 110.14329 -122.954288)
		(width 0.254)
		(layer "In15.Cu")
		(net "P3V3_PDB_AUX_ADC")
	)
	(segment
		(start 212.4837 -132.461)
		(end 210.8073 -132.461)
		(width 0.254)
		(layer "In15.Cu")
		(net "P3V3_PDB_AUX_ADC")
	)
	(segment
		(start 163.193984 -134.627112)
		(end 149.559772 -134.627112)
		(width 0.254)
		(layer "In15.Cu")
		(net "P3V3_PDB_AUX_ADC")
	)
	(segment
		(start 220.74505 -48.146462)
		(end 221.307152 -47.58436)
		(width 0.381)
		(layer "F.Cu")
		(net "P3V3_E1S_0")
	)
	(segment
		(start 220.74505 -49.911)
		(end 220.74505 -48.146462)
		(width 0.381)
		(layer "F.Cu")
		(net "P3V3_E1S_0")
	)
	(segment
		(start 221.3991 -49.911)
		(end 220.74505 -49.911)
		(width 0.381)
		(layer "F.Cu")
		(net "P3V3_E1S_0")
	)
	(segment
		(start 220.65742 -42.255948)
		(end 220.01226 -41.610788)
		(width 0.381)
		(layer "F.Cu")
		(net "P3V3_E1S_0")
	)
	(segment
		(start 221.27083 -41.620948)
		(end 221.27083 -42.255948)
		(width 0.381)
		(layer "F.Cu")
		(net "P3V3_E1S_0")
	)
	(segment
		(start 220.01226 -41.610788)
		(end 220.01226 -41.755822)
		(width 0.381)
		(layer "F.Cu")
		(net "P3V3_E1S_0")
	)
	(segment
		(start 222.07093 -44.922948)
		(end 222.68053 -44.922948)
		(width 0.381)
		(layer "F.Cu")
		(net "P3V3_E1S_0")
	)
	(segment
		(start 221.27083 -42.255948)
		(end 220.65742 -42.255948)
		(width 0.381)
		(layer "F.Cu")
		(net "P3V3_E1S_0")
	)
	(segment
		(start 223.8121 -47.612046)
		(end 223.06788 -47.612046)
		(width 0.381)
		(layer "F.Cu")
		(net "P3V3_E1S_0")
	)
	(segment
		(start 220.01226 -41.755822)
		(end 219.079826 -42.688256)
		(width 0.381)
		(layer "F.Cu")
		(net "P3V3_E1S_0")
	)
	(segment
		(start 240.40846 -46.967648)
		(end 241.07648 -46.967648)
		(width 0.381)
		(layer "F.Cu")
		(net "P3V3_E1S_0")
	)
	(segment
		(start 223.80956 -46.524926)
		(end 223.095058 -46.524926)
		(width 0.381)
		(layer "F.Cu")
		(net "P3V3_E1S_0")
	)
	(segment
		(start 221.46006 -49.97196)
		(end 221.3991 -49.911)
		(width 0.381)
		(layer "F.Cu")
		(net "P3V3_E1S_0")
	)
	(segment
		(start 219.079826 -42.688256)
		(end 218.360752 -42.688256)
		(width 0.381)
		(layer "F.Cu")
		(net "P3V3_E1S_0")
	)
	(segment
		(start 222.07093 -43.525948)
		(end 222.68053 -43.525948)
		(width 0.381)
		(layer "F.Cu")
		(net "P3V3_E1S_0")
	)
	(via
		(at 220.01226 -41.610788)
		(size 0.762)
		(drill 0.381)
		(layers "F.Cu" "B.Cu")
		(net "P3V3_E1S_0")
	)
	(via
		(at 222.68053 -43.525948)
		(size 0.508)
		(drill 0.254)
		(layers "F.Cu" "B.Cu")
		(net "P3V3_E1S_0")
	)
	(via
		(at 221.46006 -49.97196)
		(size 0.508)
		(drill 0.254)
		(layers "F.Cu" "B.Cu")
		(net "P3V3_E1S_0")
	)
	(via
		(at 220.9546 -53.228748)
		(size 0.762)
		(drill 0.381)
		(layers "F.Cu" "B.Cu")
		(net "P3V3_E1S_0")
	)
	(via
		(at 222.68053 -44.922948)
		(size 0.508)
		(drill 0.254)
		(layers "F.Cu" "B.Cu")
		(net "P3V3_E1S_0")
	)
	(via
		(at 226.47148 -52.619148)
		(size 0.508)
		(drill 0.254)
		(layers "F.Cu" "B.Cu")
		(net "P3V3_E1S_0")
	)
	(via
		(at 238.57458 -48.620426)
		(size 0.508)
		(drill 0.254)
		(layers "F.Cu" "B.Cu")
		(net "P3V3_E1S_0")
	)
	(via
		(at 227.10648 -52.619148)
		(size 0.508)
		(drill 0.254)
		(layers "F.Cu" "B.Cu")
		(net "P3V3_E1S_0")
	)
	(via
		(at 223.06788 -47.612046)
		(size 0.508)
		(drill 0.254)
		(layers "F.Cu" "B.Cu")
		(net "P3V3_E1S_0")
	)
	(via
		(at 223.095058 -46.524926)
		(size 0.508)
		(drill 0.254)
		(layers "F.Cu" "B.Cu")
		(net "P3V3_E1S_0")
	)
	(via
		(at 225.787966 -52.507642)
		(size 0.508)
		(drill 0.254)
		(layers "F.Cu" "B.Cu")
		(net "P3V3_E1S_0")
	)
	(via
		(at 237.68558 -48.620426)
		(size 0.508)
		(drill 0.254)
		(layers "F.Cu" "B.Cu")
		(net "P3V3_E1S_0")
	)
	(via
		(at 227.10648 -53.254148)
		(size 0.508)
		(drill 0.254)
		(layers "F.Cu" "B.Cu")
		(net "P3V3_E1S_0")
	)
	(via
		(at 221.27083 -41.620948)
		(size 0.508)
		(drill 0.254)
		(layers "F.Cu" "B.Cu")
		(net "P3V3_E1S_0")
	)
	(via
		(at 241.07648 -46.967648)
		(size 0.508)
		(drill 0.254)
		(layers "F.Cu" "B.Cu")
		(net "P3V3_E1S_0")
	)
	(via
		(at 227.74148 -53.254148)
		(size 0.508)
		(drill 0.254)
		(layers "F.Cu" "B.Cu")
		(net "P3V3_E1S_0")
	)
	(via
		(at 225.787966 -53.142642)
		(size 0.508)
		(drill 0.254)
		(layers "F.Cu" "B.Cu")
		(net "P3V3_E1S_0")
	)
	(via
		(at 227.74148 -52.619148)
		(size 0.508)
		(drill 0.254)
		(layers "F.Cu" "B.Cu")
		(net "P3V3_E1S_0")
	)
	(via
		(at 226.47148 -53.254148)
		(size 0.508)
		(drill 0.254)
		(layers "F.Cu" "B.Cu")
		(net "P3V3_E1S_0")
	)
	(segment
		(start 11.010138 -100.136452)
		(end 11.652504 -100.136452)
		(width 0.254)
		(layer "F.Cu")
		(net "P3V3_AUX_USB_HUB")
	)
	(segment
		(start 11.296142 -97.63633)
		(end 11.652504 -97.63633)
		(width 0.254)
		(layer "F.Cu")
		(net "P3V3_AUX_USB_HUB")
	)
	(segment
		(start 16.477488 -100.136452)
		(end 17.027144 -100.136452)
		(width 0.254)
		(layer "F.Cu")
		(net "P3V3_AUX_USB_HUB")
	)
	(segment
		(start 10.650982 -100.495608)
		(end 11.010138 -100.136452)
		(width 0.254)
		(layer "F.Cu")
		(net "P3V3_AUX_USB_HUB")
	)
	(segment
		(start 10.92708 -97.267268)
		(end 11.296142 -97.63633)
		(width 0.254)
		(layer "F.Cu")
		(net "P3V3_AUX_USB_HUB")
	)
	(segment
		(start 17.02689 -100.636578)
		(end 16.477488 -100.636578)
		(width 0.254)
		(layer "F.Cu")
		(net "P3V3_AUX_USB_HUB")
	)
	(segment
		(start 17.027144 -100.136452)
		(end 17.27708 -100.386388)
		(width 0.254)
		(layer "F.Cu")
		(net "P3V3_AUX_USB_HUB")
	)
	(segment
		(start 17.190974 -92.287598)
		(end 17.190974 -91.618308)
		(width 0.381)
		(layer "F.Cu")
		(net "P3V3_AUX_USB_HUB")
	)
	(segment
		(start 13.565124 -101.548946)
		(end 13.565124 -102.326948)
		(width 0.254)
		(layer "F.Cu")
		(net "P3V3_AUX_USB_HUB")
	)
	(segment
		(start 17.27708 -100.386388)
		(end 17.02689 -100.636578)
		(width 0.254)
		(layer "F.Cu")
		(net "P3V3_AUX_USB_HUB")
	)
	(via
		(at 10.650982 -100.495608)
		(size 0.508)
		(drill 0.254)
		(layers "F.Cu" "B.Cu")
		(net "P3V3_AUX_USB_HUB")
	)
	(via
		(at 17.27708 -100.386388)
		(size 0.508)
		(drill 0.254)
		(layers "F.Cu" "B.Cu")
		(net "P3V3_AUX_USB_HUB")
	)
	(via
		(at 17.190974 -91.618308)
		(size 0.508)
		(drill 0.254)
		(layers "F.Cu" "B.Cu")
		(net "P3V3_AUX_USB_HUB")
	)
	(via
		(at 18.161 -99.266248)
		(size 0.6604)
		(drill 0.3302)
		(layers "F.Cu" "B.Cu")
		(net "P3V3_AUX_USB_HUB")
	)
	(via
		(at 11.2649 -101.747828)
		(size 0.6604)
		(drill 0.3302)
		(layers "F.Cu" "B.Cu")
		(net "P3V3_AUX_USB_HUB")
	)
	(via
		(at 10.92708 -97.267268)
		(size 0.508)
		(drill 0.254)
		(layers "F.Cu" "B.Cu")
		(net "P3V3_AUX_USB_HUB")
	)
	(via
		(at 13.565124 -102.326948)
		(size 0.508)
		(drill 0.254)
		(layers "F.Cu" "B.Cu")
		(net "P3V3_AUX_USB_HUB")
	)
	(segment
		(start 17.190974 -91.618308)
		(end 17.190974 -94.554294)
		(width 0.381)
		(layer "B.Cu")
		(net "P3V3_AUX_USB_HUB")
	)
	(segment
		(start 16.79448 -94.950788)
		(end 12.37488 -94.950788)
		(width 0.381)
		(layer "B.Cu")
		(net "P3V3_AUX_USB_HUB")
	)
	(segment
		(start 17.190974 -94.554294)
		(end 16.79448 -94.950788)
		(width 0.381)
		(layer "B.Cu")
		(net "P3V3_AUX_USB_HUB")
	)
	(segment
		(start 12.37488 -94.950788)
		(end 10.92708 -96.398588)
		(width 0.381)
		(layer "B.Cu")
		(net "P3V3_AUX_USB_HUB")
	)
	(segment
		(start 10.92708 -96.398588)
		(end 10.92708 -97.267268)
		(width 0.381)
		(layer "B.Cu")
		(net "P3V3_AUX_USB_HUB")
	)
	(segment
		(start 35.279584 -108.358432)
		(end 35.711384 -108.358432)
		(width 0.12954)
		(layer "F.Cu")
		(net "P3V3_AUX_ADC_TIC")
	)
	(segment
		(start 37.038534 -108.047282)
		(end 36.530534 -107.539282)
		(width 0.12954)
		(layer "F.Cu")
		(net "P3V3_AUX_ADC_TIC")
	)
	(segment
		(start 35.711384 -108.358432)
		(end 36.530534 -107.539282)
		(width 0.12954)
		(layer "F.Cu")
		(net "P3V3_AUX_ADC_TIC")
	)
	(segment
		(start 32.51581 -108.358432)
		(end 35.279584 -108.358432)
		(width 0.12954)
		(layer "F.Cu")
		(net "P3V3_AUX_ADC_TIC")
	)
	(segment
		(start 39.427404 -107.031282)
		(end 38.411404 -108.047282)
		(width 0.12954)
		(layer "F.Cu")
		(net "P3V3_AUX_ADC_TIC")
	)
	(segment
		(start 38.411404 -108.047282)
		(end 37.038534 -108.047282)
		(width 0.12954)
		(layer "F.Cu")
		(net "P3V3_AUX_ADC_TIC")
	)
	(via
		(at 35.279584 -108.358432)
		(size 0.762)
		(drill 0.381)
		(layers "F.Cu" "B.Cu")
		(net "P3V3_AUX_ADC_TIC")
	)
	(segment
		(start 46.435264 -98.339148)
		(end 45.950378 -98.824034)
		(width 0.12954)
		(layer "F.Cu")
		(net "P3V3_AUX_ADC_MAM")
	)
	(segment
		(start 43.095672 -98.90379)
		(end 42.29862 -98.90379)
		(width 0.12954)
		(layer "F.Cu")
		(net "P3V3_AUX_ADC_MAM")
	)
	(segment
		(start 45.950378 -98.824034)
		(end 45.569378 -98.443034)
		(width 0.12954)
		(layer "F.Cu")
		(net "P3V3_AUX_ADC_MAM")
	)
	(segment
		(start 43.556428 -98.443034)
		(end 43.095672 -98.90379)
		(width 0.12954)
		(layer "F.Cu")
		(net "P3V3_AUX_ADC_MAM")
	)
	(segment
		(start 41.396666 -107.031282)
		(end 41.656 -106.771948)
		(width 0.12954)
		(layer "F.Cu")
		(net "P3V3_AUX_ADC_MAM")
	)
	(segment
		(start 44.064428 -98.443034)
		(end 43.556428 -98.443034)
		(width 0.12954)
		(layer "F.Cu")
		(net "P3V3_AUX_ADC_MAM")
	)
	(segment
		(start 41.027604 -107.031282)
		(end 41.396666 -107.031282)
		(width 0.12954)
		(layer "F.Cu")
		(net "P3V3_AUX_ADC_MAM")
	)
	(segment
		(start 48.48352 -98.339148)
		(end 46.435264 -98.339148)
		(width 0.12954)
		(layer "F.Cu")
		(net "P3V3_AUX_ADC_MAM")
	)
	(segment
		(start 45.569378 -98.443034)
		(end 44.064428 -98.443034)
		(width 0.12954)
		(layer "F.Cu")
		(net "P3V3_AUX_ADC_MAM")
	)
	(via
		(at 48.48352 -98.339148)
		(size 0.508)
		(drill 0.254)
		(layers "F.Cu" "B.Cu")
		(net "P3V3_AUX_ADC_MAM")
	)
	(via
		(at 44.064428 -98.443034)
		(size 0.762)
		(drill 0.381)
		(layers "F.Cu" "B.Cu")
		(net "P3V3_AUX_ADC_MAM")
	)
	(via
		(at 41.656 -106.771948)
		(size 0.508)
		(drill 0.254)
		(layers "F.Cu" "B.Cu")
		(net "P3V3_AUX_ADC_MAM")
	)
	(segment
		(start 48.20158 -98.057208)
		(end 48.20158 -97.828608)
		(width 0.254)
		(layer "In2.Cu")
		(net "P3V3_AUX_ADC_MAM")
	)
	(segment
		(start 46.59884 -97.142808)
		(end 44.90593 -98.835718)
		(width 0.254)
		(layer "In2.Cu")
		(net "P3V3_AUX_ADC_MAM")
	)
	(segment
		(start 48.48352 -98.339148)
		(end 48.20158 -98.057208)
		(width 0.254)
		(layer "In2.Cu")
		(net "P3V3_AUX_ADC_MAM")
	)
	(segment
		(start 48.20158 -97.828608)
		(end 47.51578 -97.142808)
		(width 0.254)
		(layer "In2.Cu")
		(net "P3V3_AUX_ADC_MAM")
	)
	(segment
		(start 44.03598 -101.130608)
		(end 44.03598 -104.632506)
		(width 0.254)
		(layer "In2.Cu")
		(net "P3V3_AUX_ADC_MAM")
	)
	(segment
		(start 44.90593 -100.260658)
		(end 44.03598 -101.130608)
		(width 0.254)
		(layer "In2.Cu")
		(net "P3V3_AUX_ADC_MAM")
	)
	(segment
		(start 41.896538 -106.771948)
		(end 41.656 -106.771948)
		(width 0.254)
		(layer "In2.Cu")
		(net "P3V3_AUX_ADC_MAM")
	)
	(segment
		(start 47.51578 -97.142808)
		(end 46.59884 -97.142808)
		(width 0.254)
		(layer "In2.Cu")
		(net "P3V3_AUX_ADC_MAM")
	)
	(segment
		(start 44.03598 -104.632506)
		(end 41.896538 -106.771948)
		(width 0.254)
		(layer "In2.Cu")
		(net "P3V3_AUX_ADC_MAM")
	)
	(segment
		(start 44.90593 -98.835718)
		(end 44.90593 -100.260658)
		(width 0.254)
		(layer "In2.Cu")
		(net "P3V3_AUX_ADC_MAM")
	)
	(segment
		(start 46.182534 -107.031282)
		(end 45.711364 -107.502452)
		(width 0.12954)
		(layer "F.Cu")
		(net "P3V3_AUX_ADC")
	)
	(segment
		(start 40.227504 -107.031282)
		(end 40.698674 -107.502452)
		(width 0.12954)
		(layer "F.Cu")
		(net "P3V3_AUX_ADC")
	)
	(segment
		(start 44.240704 -107.502452)
		(end 43.769534 -107.031282)
		(width 0.12954)
		(layer "F.Cu")
		(net "P3V3_AUX_ADC")
	)
	(segment
		(start 45.711364 -107.502452)
		(end 44.240704 -107.502452)
		(width 0.12954)
		(layer "F.Cu")
		(net "P3V3_AUX_ADC")
	)
	(segment
		(start 41.866058 -107.502452)
		(end 42.396918 -106.971592)
		(width 0.12954)
		(layer "F.Cu")
		(net "P3V3_AUX_ADC")
	)
	(segment
		(start 40.698674 -107.502452)
		(end 41.866058 -107.502452)
		(width 0.12954)
		(layer "F.Cu")
		(net "P3V3_AUX_ADC")
	)
	(segment
		(start 43.769534 -107.031282)
		(end 43.709844 -106.971592)
		(width 0.12954)
		(layer "F.Cu")
		(net "P3V3_AUX_ADC")
	)
	(segment
		(start 43.709844 -106.971592)
		(end 42.396918 -106.971592)
		(width 0.12954)
		(layer "F.Cu")
		(net "P3V3_AUX_ADC")
	)
	(via
		(at 42.396918 -106.971592)
		(size 0.762)
		(drill 0.381)
		(layers "F.Cu" "B.Cu")
		(net "P3V3_AUX_ADC")
	)
	(segment
		(start 39.427404 -108.047282)
		(end 39.427404 -108.555282)
		(width 0.12954)
		(layer "F.Cu")
		(net "P3V3_ADC_TIC")
	)
	(segment
		(start 37.057584 -109.063282)
		(end 36.549584 -108.555282)
		(width 0.12954)
		(layer "F.Cu")
		(net "P3V3_ADC_TIC")
	)
	(segment
		(start 33.44672 -109.008418)
		(end 32.51581 -109.008418)
		(width 0.12954)
		(layer "F.Cu")
		(net "P3V3_ADC_TIC")
	)
	(segment
		(start 34.263584 -109.190282)
		(end 33.628584 -109.190282)
		(width 0.12954)
		(layer "F.Cu")
		(net "P3V3_ADC_TIC")
	)
	(segment
		(start 33.628584 -109.190282)
		(end 33.44672 -109.008418)
		(width 0.12954)
		(layer "F.Cu")
		(net "P3V3_ADC_TIC")
	)
	(segment
		(start 35.895534 -109.190282)
		(end 34.263584 -109.190282)
		(width 0.12954)
		(layer "F.Cu")
		(net "P3V3_ADC_TIC")
	)
	(segment
		(start 36.549584 -108.555282)
		(end 36.530534 -108.555282)
		(width 0.12954)
		(layer "F.Cu")
		(net "P3V3_ADC_TIC")
	)
	(segment
		(start 38.919404 -109.063282)
		(end 37.057584 -109.063282)
		(width 0.12954)
		(layer "F.Cu")
		(net "P3V3_ADC_TIC")
	)
	(segment
		(start 36.530534 -108.555282)
		(end 35.895534 -109.190282)
		(width 0.12954)
		(layer "F.Cu")
		(net "P3V3_ADC_TIC")
	)
	(segment
		(start 39.427404 -108.555282)
		(end 38.919404 -109.063282)
		(width 0.12954)
		(layer "F.Cu")
		(net "P3V3_ADC_TIC")
	)
	(via
		(at 34.263584 -109.190282)
		(size 0.762)
		(drill 0.381)
		(layers "F.Cu" "B.Cu")
		(net "P3V3_ADC_TIC")
	)
	(segment
		(start 43.095672 -98.26879)
		(end 42.29862 -98.26879)
		(width 0.12954)
		(layer "F.Cu")
		(net "P3V3_ADC_MAM")
	)
	(segment
		(start 44.699428 -97.300034)
		(end 44.064428 -97.300034)
		(width 0.12954)
		(layer "F.Cu")
		(net "P3V3_ADC_MAM")
	)
	(segment
		(start 46.473364 -97.285048)
		(end 45.950378 -97.808034)
		(width 0.12954)
		(layer "F.Cu")
		(net "P3V3_ADC_MAM")
	)
	(segment
		(start 41.027604 -108.047282)
		(end 41.637204 -108.047282)
		(width 0.12954)
		(layer "F.Cu")
		(net "P3V3_ADC_MAM")
	)
	(segment
		(start 45.950378 -97.808034)
		(end 45.442378 -97.300034)
		(width 0.12954)
		(layer "F.Cu")
		(net "P3V3_ADC_MAM")
	)
	(segment
		(start 48.48352 -97.285048)
		(end 46.473364 -97.285048)
		(width 0.12954)
		(layer "F.Cu")
		(net "P3V3_ADC_MAM")
	)
	(segment
		(start 45.442378 -97.300034)
		(end 44.699428 -97.300034)
		(width 0.12954)
		(layer "F.Cu")
		(net "P3V3_ADC_MAM")
	)
	(segment
		(start 44.064428 -97.300034)
		(end 43.095672 -98.26879)
		(width 0.12954)
		(layer "F.Cu")
		(net "P3V3_ADC_MAM")
	)
	(via
		(at 48.48352 -97.285048)
		(size 0.508)
		(drill 0.254)
		(layers "F.Cu" "B.Cu")
		(net "P3V3_ADC_MAM")
	)
	(via
		(at 44.699428 -97.300034)
		(size 0.762)
		(drill 0.381)
		(layers "F.Cu" "B.Cu")
		(net "P3V3_ADC_MAM")
	)
	(via
		(at 41.637204 -108.047282)
		(size 0.508)
		(drill 0.254)
		(layers "F.Cu" "B.Cu")
		(net "P3V3_ADC_MAM")
	)
	(segment
		(start 45.70476 -96.134428)
		(end 42.3799 -99.459288)
		(width 0.254)
		(layer "In2.Cu")
		(net "P3V3_ADC_MAM")
	)
	(segment
		(start 42.3799 -99.459288)
		(end 42.3799 -101.633528)
		(width 0.254)
		(layer "In2.Cu")
		(net "P3V3_ADC_MAM")
	)
	(segment
		(start 42.3799 -101.633528)
		(end 40.3352 -103.678228)
		(width 0.254)
		(layer "In2.Cu")
		(net "P3V3_ADC_MAM")
	)
	(segment
		(start 40.3352 -103.678228)
		(end 40.3352 -106.745278)
		(width 0.254)
		(layer "In2.Cu")
		(net "P3V3_ADC_MAM")
	)
	(segment
		(start 48.48352 -97.285048)
		(end 47.3329 -96.134428)
		(width 0.254)
		(layer "In2.Cu")
		(net "P3V3_ADC_MAM")
	)
	(segment
		(start 47.3329 -96.134428)
		(end 45.70476 -96.134428)
		(width 0.254)
		(layer "In2.Cu")
		(net "P3V3_ADC_MAM")
	)
	(segment
		(start 40.3352 -106.745278)
		(end 41.637204 -108.047282)
		(width 0.254)
		(layer "In2.Cu")
		(net "P3V3_ADC_MAM")
	)
	(via
		(at 24.509984 -109.317282)
		(size 0.762)
		(drill 0.381)
		(layers "F.Cu" "B.Cu")
		(net "P3V3_ADC128_VCC")
	)
	(segment
		(start 40.508936 -108.644182)
		(end 42.33926 -108.644182)
		(width 0.381)
		(layer "F.Cu")
		(net "P3V3_ADC")
	)
	(segment
		(start 44.06265 -108.644182)
		(end 43.769534 -108.351066)
		(width 0.381)
		(layer "F.Cu")
		(net "P3V3_ADC")
	)
	(segment
		(start 43.288966 -108.047282)
		(end 42.692066 -108.644182)
		(width 0.381)
		(layer "F.Cu")
		(net "P3V3_ADC")
	)
	(segment
		(start 40.227504 -108.36275)
		(end 40.508936 -108.644182)
		(width 0.381)
		(layer "F.Cu")
		(net "P3V3_ADC")
	)
	(segment
		(start 42.692066 -108.644182)
		(end 42.33926 -108.644182)
		(width 0.381)
		(layer "F.Cu")
		(net "P3V3_ADC")
	)
	(segment
		(start 43.769534 -108.047282)
		(end 43.288966 -108.047282)
		(width 0.381)
		(layer "F.Cu")
		(net "P3V3_ADC")
	)
	(segment
		(start 45.839634 -108.644182)
		(end 44.06265 -108.644182)
		(width 0.381)
		(layer "F.Cu")
		(net "P3V3_ADC")
	)
	(segment
		(start 46.182534 -108.047282)
		(end 46.182534 -108.301282)
		(width 0.381)
		(layer "F.Cu")
		(net "P3V3_ADC")
	)
	(segment
		(start 46.182534 -108.301282)
		(end 45.839634 -108.644182)
		(width 0.381)
		(layer "F.Cu")
		(net "P3V3_ADC")
	)
	(segment
		(start 43.769534 -108.351066)
		(end 43.769534 -108.047282)
		(width 0.381)
		(layer "F.Cu")
		(net "P3V3_ADC")
	)
	(segment
		(start 40.227504 -108.047282)
		(end 40.227504 -108.36275)
		(width 0.381)
		(layer "F.Cu")
		(net "P3V3_ADC")
	)
	(via
		(at 42.33926 -108.644182)
		(size 0.762)
		(drill 0.381)
		(layers "F.Cu" "B.Cu")
		(net "P3V3_ADC")
	)
	(segment
		(start 248.40057 -57.061862)
		(end 251.079 -57.061862)
		(width 0.254)
		(layer "F.Cu")
		(net "P12V_E1S_0")
	)
	(segment
		(start 256.47269 -38.748716)
		(end 256.47269 -39.082472)
		(width 0.381)
		(layer "F.Cu")
		(net "P12V_E1S_0")
	)
	(segment
		(start 247.38457 -51.984402)
		(end 247.38457 -56.045862)
		(width 0.254)
		(layer "F.Cu")
		(net "P12V_E1S_0")
	)
	(segment
		(start 257.040126 -39.10584)
		(end 257.04165 -39.107364)
		(width 0.381)
		(layer "F.Cu")
		(net "P12V_E1S_0")
	)
	(segment
		(start 257.04165 -39.107364)
		(end 257.710432 -39.107364)
		(width 0.381)
		(layer "F.Cu")
		(net "P12V_E1S_0")
	)
	(segment
		(start 256.064766 -38.340792)
		(end 256.47269 -38.748716)
		(width 0.381)
		(layer "F.Cu")
		(net "P12V_E1S_0")
	)
	(segment
		(start 252.561598 -56.193182)
		(end 251.692918 -57.061862)
		(width 0.254)
		(layer "F.Cu")
		(net "P12V_E1S_0")
	)
	(segment
		(start 257.710432 -39.107364)
		(end 257.7338 -39.083996)
		(width 0.381)
		(layer "F.Cu")
		(net "P12V_E1S_0")
	)
	(segment
		(start 251.692918 -57.061862)
		(end 251.079 -57.061862)
		(width 0.254)
		(layer "F.Cu")
		(net "P12V_E1S_0")
	)
	(segment
		(start 247.38457 -56.045862)
		(end 248.40057 -57.061862)
		(width 0.254)
		(layer "F.Cu")
		(net "P12V_E1S_0")
	)
	(segment
		(start 256.47269 -39.082472)
		(end 256.496058 -39.10584)
		(width 0.381)
		(layer "F.Cu")
		(net "P12V_E1S_0")
	)
	(segment
		(start 257.7338 -39.083996)
		(end 257.87985 -39.083996)
		(width 0.381)
		(layer "F.Cu")
		(net "P12V_E1S_0")
	)
	(segment
		(start 256.496058 -39.10584)
		(end 257.040126 -39.10584)
		(width 0.381)
		(layer "F.Cu")
		(net "P12V_E1S_0")
	)
	(via
		(at 247.42648 -49.308766)
		(size 0.762)
		(drill 0.381)
		(layers "F.Cu" "B.Cu")
		(net "P12V_E1S_0")
	)
	(via
		(at 251.51588 -49.707546)
		(size 0.508)
		(drill 0.254)
		(layers "F.Cu" "B.Cu")
		(net "P12V_E1S_0")
	)
	(via
		(at 249.887994 -39.800276)
		(size 0.508)
		(drill 0.254)
		(layers "F.Cu" "B.Cu")
		(net "P12V_E1S_0")
	)
	(via
		(at 239.57788 -44.802806)
		(size 0.508)
		(drill 0.254)
		(layers "F.Cu" "B.Cu")
		(net "P12V_E1S_0")
	)
	(via
		(at 251.51588 -50.596546)
		(size 0.508)
		(drill 0.254)
		(layers "F.Cu" "B.Cu")
		(net "P12V_E1S_0")
	)
	(via
		(at 251.51588 -51.485546)
		(size 0.508)
		(drill 0.254)
		(layers "F.Cu" "B.Cu")
		(net "P12V_E1S_0")
	)
	(via
		(at 245.54688 -50.317146)
		(size 0.508)
		(drill 0.254)
		(layers "F.Cu" "B.Cu")
		(net "P12V_E1S_0")
	)
	(via
		(at 248.21388 -51.155346)
		(size 0.508)
		(drill 0.254)
		(layers "F.Cu" "B.Cu")
		(net "P12V_E1S_0")
	)
	(via
		(at 242.67922 -45.755306)
		(size 0.762)
		(drill 0.381)
		(layers "F.Cu" "B.Cu")
		(net "P12V_E1S_0")
	)
	(via
		(at 247.82526 -39.93388)
		(size 0.508)
		(drill 0.254)
		(layers "F.Cu" "B.Cu")
		(net "P12V_E1S_0")
	)
	(via
		(at 246.56288 -50.317146)
		(size 0.508)
		(drill 0.254)
		(layers "F.Cu" "B.Cu")
		(net "P12V_E1S_0")
	)
	(via
		(at 237.6297 -44.787566)
		(size 0.508)
		(drill 0.254)
		(layers "F.Cu" "B.Cu")
		(net "P12V_E1S_0")
	)
	(via
		(at 240.21288 -44.802806)
		(size 0.508)
		(drill 0.254)
		(layers "F.Cu" "B.Cu")
		(net "P12V_E1S_0")
	)
	(via
		(at 237.6297 -44.025566)
		(size 0.508)
		(drill 0.254)
		(layers "F.Cu" "B.Cu")
		(net "P12V_E1S_0")
	)
	(via
		(at 240.8936 -44.830746)
		(size 0.508)
		(drill 0.254)
		(layers "F.Cu" "B.Cu")
		(net "P12V_E1S_0")
	)
	(via
		(at 238.29264 -44.040806)
		(size 0.508)
		(drill 0.254)
		(layers "F.Cu" "B.Cu")
		(net "P12V_E1S_0")
	)
	(via
		(at 256.064766 -38.340792)
		(size 0.508)
		(drill 0.254)
		(layers "F.Cu" "B.Cu")
		(net "P12V_E1S_0")
	)
	(via
		(at 240.21288 -44.040806)
		(size 0.508)
		(drill 0.254)
		(layers "F.Cu" "B.Cu")
		(net "P12V_E1S_0")
	)
	(via
		(at 250.44908 -48.539146)
		(size 0.508)
		(drill 0.254)
		(layers "F.Cu" "B.Cu")
		(net "P12V_E1S_0")
	)
	(via
		(at 251.079 -57.061862)
		(size 0.762)
		(drill 0.381)
		(layers "F.Cu" "B.Cu")
		(net "P12V_E1S_0")
	)
	(via
		(at 250.77928 -49.428146)
		(size 0.508)
		(drill 0.254)
		(layers "F.Cu" "B.Cu")
		(net "P12V_E1S_0")
	)
	(via
		(at 244.12448 -49.097946)
		(size 0.508)
		(drill 0.254)
		(layers "F.Cu" "B.Cu")
		(net "P12V_E1S_0")
	)
	(via
		(at 250.77928 -50.317146)
		(size 0.508)
		(drill 0.254)
		(layers "F.Cu" "B.Cu")
		(net "P12V_E1S_0")
	)
	(via
		(at 250.77928 -51.206146)
		(size 0.508)
		(drill 0.254)
		(layers "F.Cu" "B.Cu")
		(net "P12V_E1S_0")
	)
	(via
		(at 238.94288 -44.802806)
		(size 0.508)
		(drill 0.254)
		(layers "F.Cu" "B.Cu")
		(net "P12V_E1S_0")
	)
	(via
		(at 244.501416 -41.989502)
		(size 0.508)
		(drill 0.254)
		(layers "F.Cu" "B.Cu")
		(net "P12V_E1S_0")
	)
	(via
		(at 245.1481 -49.126648)
		(size 0.508)
		(drill 0.254)
		(layers "F.Cu" "B.Cu")
		(net "P12V_E1S_0")
	)
	(via
		(at 244.464332 -41.249092)
		(size 0.508)
		(drill 0.254)
		(layers "F.Cu" "B.Cu")
		(net "P12V_E1S_0")
	)
	(via
		(at 239.57788 -44.040806)
		(size 0.508)
		(drill 0.254)
		(layers "F.Cu" "B.Cu")
		(net "P12V_E1S_0")
	)
	(via
		(at 238.29264 -44.802806)
		(size 0.508)
		(drill 0.254)
		(layers "F.Cu" "B.Cu")
		(net "P12V_E1S_0")
	)
	(via
		(at 238.94288 -44.040806)
		(size 0.508)
		(drill 0.254)
		(layers "F.Cu" "B.Cu")
		(net "P12V_E1S_0")
	)
	(via
		(at 243.08308 -49.097946)
		(size 0.508)
		(drill 0.254)
		(layers "F.Cu" "B.Cu")
		(net "P12V_E1S_0")
	)
	(segment
		(start 256.064766 -38.340792)
		(end 256.064766 -38.31844)
		(width 0.381)
		(layer "In15.Cu")
		(net "P12V_E1S_0")
	)
	(segment
		(start 256.064766 -38.31844)
		(end 255.011682 -37.265356)
		(width 0.381)
		(layer "In15.Cu")
		(net "P12V_E1S_0")
	)
	(segment
		(start 255.011682 -37.265356)
		(end 250.427998 -37.265356)
		(width 0.381)
		(layer "In15.Cu")
		(net "P12V_E1S_0")
	)
	(segment
		(start 250.427998 -37.265356)
		(end 249.48388 -38.209474)
		(width 0.381)
		(layer "In15.Cu")
		(net "P12V_E1S_0")
	)
	(segment
		(start 249.48388 -39.396162)
		(end 249.887994 -39.800276)
		(width 0.381)
		(layer "In15.Cu")
		(net "P12V_E1S_0")
	)
	(segment
		(start 249.48388 -38.209474)
		(end 249.48388 -39.396162)
		(width 0.381)
		(layer "In15.Cu")
		(net "P12V_E1S_0")
	)
	(segment
		(start 34.263584 -112.619028)
		(end 33.253172 -111.608616)
		(width 0.12954)
		(layer "F.Cu")
		(net "P12V_AUX_ADC_TIC")
	)
	(segment
		(start 34.263584 -112.619282)
		(end 34.263584 -112.619028)
		(width 0.12954)
		(layer "F.Cu")
		(net "P12V_AUX_ADC_TIC")
	)
	(segment
		(start 36.530534 -112.854232)
		(end 36.530534 -112.619282)
		(width 0.12954)
		(layer "F.Cu")
		(net "P12V_AUX_ADC_TIC")
	)
	(segment
		(start 39.427404 -112.603026)
		(end 38.776148 -113.254282)
		(width 0.12954)
		(layer "F.Cu")
		(net "P12V_AUX_ADC_TIC")
	)
	(segment
		(start 33.253172 -111.608616)
		(end 32.51581 -111.608616)
		(width 0.12954)
		(layer "F.Cu")
		(net "P12V_AUX_ADC_TIC")
	)
	(segment
		(start 38.776148 -113.254282)
		(end 36.930584 -113.254282)
		(width 0.12954)
		(layer "F.Cu")
		(net "P12V_AUX_ADC_TIC")
	)
	(segment
		(start 36.930584 -113.254282)
		(end 36.530534 -112.854232)
		(width 0.12954)
		(layer "F.Cu")
		(net "P12V_AUX_ADC_TIC")
	)
	(segment
		(start 36.530534 -112.619282)
		(end 34.263584 -112.619282)
		(width 0.12954)
		(layer "F.Cu")
		(net "P12V_AUX_ADC_TIC")
	)
	(via
		(at 34.263584 -112.619282)
		(size 0.762)
		(drill 0.381)
		(layers "F.Cu" "B.Cu")
		(net "P12V_AUX_ADC_TIC")
	)
	(segment
		(start 41.027604 -112.603026)
		(end 41.637204 -112.603026)
		(width 0.12954)
		(layer "F.Cu")
		(net "P12V_AUX_ADC_MAM")
	)
	(segment
		(start 35.602672 -100.17379)
		(end 34.920428 -100.856034)
		(width 0.12954)
		(layer "F.Cu")
		(net "P12V_AUX_ADC_MAM")
	)
	(segment
		(start 34.920428 -100.856034)
		(end 34.34588 -100.856034)
		(width 0.12954)
		(layer "F.Cu")
		(net "P12V_AUX_ADC_MAM")
	)
	(segment
		(start 36.988496 -100.17379)
		(end 35.602672 -100.17379)
		(width 0.12954)
		(layer "F.Cu")
		(net "P12V_AUX_ADC_MAM")
	)
	(segment
		(start 33.415478 -100.856034)
		(end 33.161478 -100.602034)
		(width 0.12954)
		(layer "F.Cu")
		(net "P12V_AUX_ADC_MAM")
	)
	(segment
		(start 34.34588 -100.856034)
		(end 33.415478 -100.856034)
		(width 0.12954)
		(layer "F.Cu")
		(net "P12V_AUX_ADC_MAM")
	)
	(via
		(at 41.637204 -112.603026)
		(size 0.508)
		(drill 0.254)
		(layers "F.Cu" "B.Cu")
		(net "P12V_AUX_ADC_MAM")
	)
	(via
		(at 34.34588 -100.856034)
		(size 0.508)
		(drill 0.254)
		(layers "F.Cu" "B.Cu")
		(net "P12V_AUX_ADC_MAM")
	)
	(segment
		(start 36.24834 -112.552988)
		(end 36.24834 -105.489248)
		(width 0.254)
		(layer "B.Cu")
		(net "P12V_AUX_ADC_MAM")
	)
	(segment
		(start 34.34588 -103.586788)
		(end 34.34588 -100.856034)
		(width 0.254)
		(layer "B.Cu")
		(net "P12V_AUX_ADC_MAM")
	)
	(segment
		(start 41.637204 -112.603026)
		(end 40.862758 -113.377472)
		(width 0.254)
		(layer "B.Cu")
		(net "P12V_AUX_ADC_MAM")
	)
	(segment
		(start 36.24834 -105.489248)
		(end 34.34588 -103.586788)
		(width 0.254)
		(layer "B.Cu")
		(net "P12V_AUX_ADC_MAM")
	)
	(segment
		(start 37.072824 -113.377472)
		(end 36.24834 -112.552988)
		(width 0.254)
		(layer "B.Cu")
		(net "P12V_AUX_ADC_MAM")
	)
	(segment
		(start 40.862758 -113.377472)
		(end 37.072824 -113.377472)
		(width 0.254)
		(layer "B.Cu")
		(net "P12V_AUX_ADC_MAM")
	)
	(segment
		(start 46.182534 -112.619282)
		(end 45.702728 -113.099088)
		(width 0.12954)
		(layer "F.Cu")
		(net "P12V_AUX_ADC")
	)
	(segment
		(start 43.769534 -112.619282)
		(end 42.626534 -112.619282)
		(width 0.12954)
		(layer "F.Cu")
		(net "P12V_AUX_ADC")
	)
	(segment
		(start 43.769534 -112.644682)
		(end 43.769534 -112.619282)
		(width 0.12954)
		(layer "F.Cu")
		(net "P12V_AUX_ADC")
	)
	(segment
		(start 42.118534 -113.127282)
		(end 42.509186 -112.73663)
		(width 0.12954)
		(layer "F.Cu")
		(net "P12V_AUX_ADC")
	)
	(segment
		(start 42.626534 -112.619282)
		(end 42.509186 -112.73663)
		(width 0.12954)
		(layer "F.Cu")
		(net "P12V_AUX_ADC")
	)
	(segment
		(start 40.227504 -112.868202)
		(end 40.486584 -113.127282)
		(width 0.12954)
		(layer "F.Cu")
		(net "P12V_AUX_ADC")
	)
	(segment
		(start 40.227504 -112.603026)
		(end 40.227504 -112.868202)
		(width 0.12954)
		(layer "F.Cu")
		(net "P12V_AUX_ADC")
	)
	(segment
		(start 40.486584 -113.127282)
		(end 42.118534 -113.127282)
		(width 0.12954)
		(layer "F.Cu")
		(net "P12V_AUX_ADC")
	)
	(segment
		(start 45.702728 -113.099088)
		(end 44.22394 -113.099088)
		(width 0.12954)
		(layer "F.Cu")
		(net "P12V_AUX_ADC")
	)
	(segment
		(start 44.22394 -113.099088)
		(end 43.769534 -112.644682)
		(width 0.12954)
		(layer "F.Cu")
		(net "P12V_AUX_ADC")
	)
	(via
		(at 42.509186 -112.73663)
		(size 0.762)
		(drill 0.381)
		(layers "F.Cu" "B.Cu")
		(net "P12V_AUX_ADC")
	)
	(segment
		(start 191.861186 -437.688736)
		(end 192.601342 -436.94858)
		(width 0.12954)
		(layer "F.Cu")
		(net "GPU_PRSNT_R")
	)
	(segment
		(start 191.861186 -437.77408)
		(end 191.861186 -437.688736)
		(width 0.12954)
		(layer "F.Cu")
		(net "GPU_PRSNT_R")
	)
	(segment
		(start 192.601342 -436.94858)
		(end 192.601342 -436.55996)
		(width 0.12954)
		(layer "F.Cu")
		(net "GPU_PRSNT_R")
	)
	(segment
		(start 192.601342 -436.55996)
		(end 192.601342 -435.169056)
		(width 0.12954)
		(layer "F.Cu")
		(net "GPU_PRSNT_R")
	)
	(via
		(at 192.601342 -436.55996)
		(size 0.762)
		(drill 0.381)
		(layers "F.Cu" "B.Cu")
		(net "GPU_PRSNT_R")
	)
	(segment
		(start 236.599984 -49.165002)
		(end 234.654344 -49.165002)
		(width 0.12954)
		(layer "F.Cu")
		(net "E1S_0_PWRDIS")
	)
	(via
		(at 234.654344 -49.165002)
		(size 0.508)
		(drill 0.254)
		(layers "F.Cu" "B.Cu")
		(net "E1S_0_PWRDIS")
	)
	(segment
		(start 235.472224 -49.165002)
		(end 235.938568 -49.631346)
		(width 0.12954)
		(layer "B.Cu")
		(net "E1S_0_PWRDIS")
	)
	(segment
		(start 235.938568 -49.631346)
		(end 236.038898 -49.631346)
		(width 0.12954)
		(layer "B.Cu")
		(net "E1S_0_PWRDIS")
	)
	(segment
		(start 236.601 -51.209448)
		(end 236.601 -50.193448)
		(width 0.12954)
		(layer "B.Cu")
		(net "E1S_0_PWRDIS")
	)
	(segment
		(start 236.038898 -49.631346)
		(end 236.601 -50.193448)
		(width 0.12954)
		(layer "B.Cu")
		(net "E1S_0_PWRDIS")
	)
	(segment
		(start 234.654344 -49.165002)
		(end 235.472224 -49.165002)
		(width 0.12954)
		(layer "B.Cu")
		(net "E1S_0_PWRDIS")
	)
	(segment
		(start 226.137216 -51.0921)
		(end 228.064314 -49.165002)
		(width 0.12954)
		(layer "F.Cu")
		(net "E1S_0_PRSNT_N")
	)
	(segment
		(start 136.176258 -65.644268)
		(end 136.176258 -66.242692)
		(width 0.12954)
		(layer "F.Cu")
		(net "E1S_0_PRSNT_N")
	)
	(segment
		(start 136.268206 -67.231768)
		(end 136.268206 -68.445888)
		(width 0.12954)
		(layer "F.Cu")
		(net "E1S_0_PRSNT_N")
	)
	(segment
		(start 224.63125 -51.0921)
		(end 226.137216 -51.0921)
		(width 0.12954)
		(layer "F.Cu")
		(net "E1S_0_PRSNT_N")
	)
	(segment
		(start 224.374456 -51.852576)
		(end 224.63125 -51.595782)
		(width 0.12954)
		(layer "F.Cu")
		(net "E1S_0_PRSNT_N")
	)
	(segment
		(start 136.268206 -66.33464)
		(end 136.268206 -67.231768)
		(width 0.12954)
		(layer "F.Cu")
		(net "E1S_0_PRSNT_N")
	)
	(segment
		(start 224.63125 -51.595782)
		(end 224.63125 -51.0921)
		(width 0.12954)
		(layer "F.Cu")
		(net "E1S_0_PRSNT_N")
	)
	(segment
		(start 136.176258 -66.242692)
		(end 136.268206 -66.33464)
		(width 0.12954)
		(layer "F.Cu")
		(net "E1S_0_PRSNT_N")
	)
	(segment
		(start 222.941896 -51.012598)
		(end 223.781874 -51.852576)
		(width 0.12954)
		(layer "F.Cu")
		(net "E1S_0_PRSNT_N")
	)
	(segment
		(start 183.755538 -112.175544)
		(end 184.155588 -111.775494)
		(width 0.12954)
		(layer "F.Cu")
		(net "E1S_0_PRSNT_N")
	)
	(segment
		(start 137.11682 -69.827648)
		(end 136.268206 -68.979034)
		(width 0.12954)
		(layer "F.Cu")
		(net "E1S_0_PRSNT_N")
	)
	(segment
		(start 228.064314 -49.165002)
		(end 232.000044 -49.165002)
		(width 0.12954)
		(layer "F.Cu")
		(net "E1S_0_PRSNT_N")
	)
	(segment
		(start 136.268206 -68.979034)
		(end 136.268206 -68.445888)
		(width 0.12954)
		(layer "F.Cu")
		(net "E1S_0_PRSNT_N")
	)
	(segment
		(start 223.781874 -51.852576)
		(end 224.374456 -51.852576)
		(width 0.12954)
		(layer "F.Cu")
		(net "E1S_0_PRSNT_N")
	)
	(via
		(at 180.12664 -98.22942)
		(size 0.508)
		(drill 0.254)
		(layers "F.Cu" "B.Cu")
		(net "E1S_0_PRSNT_N")
	)
	(via
		(at 222.941896 -51.012598)
		(size 0.508)
		(drill 0.254)
		(layers "F.Cu" "B.Cu")
		(net "E1S_0_PRSNT_N")
	)
	(via
		(at 136.268206 -67.231768)
		(size 0.762)
		(drill 0.381)
		(layers "F.Cu" "B.Cu")
		(net "E1S_0_PRSNT_N")
	)
	(via
		(at 145.37944 -89.398348)
		(size 0.508)
		(drill 0.254)
		(layers "F.Cu" "B.Cu")
		(net "E1S_0_PRSNT_N")
	)
	(via
		(at 137.11682 -69.827648)
		(size 0.508)
		(drill 0.254)
		(layers "F.Cu" "B.Cu")
		(net "E1S_0_PRSNT_N")
	)
	(via
		(at 184.155588 -111.775494)
		(size 0.4572)
		(drill 0.254)
		(layers "F.Cu" "B.Cu")
		(net "E1S_0_PRSNT_N")
	)
	(segment
		(start 143.3322 -76.043028)
		(end 137.11682 -69.827648)
		(width 0.127)
		(layer "In11.Cu")
		(net "E1S_0_PRSNT_N")
	)
	(segment
		(start 183.75376 -111.373666)
		(end 183.75376 -105.362248)
		(width 0.127)
		(layer "In11.Cu")
		(net "E1S_0_PRSNT_N")
	)
	(segment
		(start 183.75376 -105.362248)
		(end 182.753 -104.361488)
		(width 0.127)
		(layer "In11.Cu")
		(net "E1S_0_PRSNT_N")
	)
	(segment
		(start 184.155588 -111.775494)
		(end 183.75376 -111.373666)
		(width 0.127)
		(layer "In11.Cu")
		(net "E1S_0_PRSNT_N")
	)
	(segment
		(start 143.69288 -88.407748)
		(end 143.69288 -78.677008)
		(width 0.127)
		(layer "In11.Cu")
		(net "E1S_0_PRSNT_N")
	)
	(segment
		(start 143.3322 -78.316328)
		(end 143.3322 -76.043028)
		(width 0.127)
		(layer "In11.Cu")
		(net "E1S_0_PRSNT_N")
	)
	(segment
		(start 182.753 -104.361488)
		(end 182.753 -101.325426)
		(width 0.127)
		(layer "In11.Cu")
		(net "E1S_0_PRSNT_N")
	)
	(segment
		(start 182.753 -101.325426)
		(end 180.12664 -98.699066)
		(width 0.127)
		(layer "In11.Cu")
		(net "E1S_0_PRSNT_N")
	)
	(segment
		(start 144.68348 -89.398348)
		(end 143.69288 -88.407748)
		(width 0.127)
		(layer "In11.Cu")
		(net "E1S_0_PRSNT_N")
	)
	(segment
		(start 180.12664 -98.699066)
		(end 180.12664 -98.22942)
		(width 0.127)
		(layer "In11.Cu")
		(net "E1S_0_PRSNT_N")
	)
	(segment
		(start 145.37944 -89.398348)
		(end 144.68348 -89.398348)
		(width 0.127)
		(layer "In11.Cu")
		(net "E1S_0_PRSNT_N")
	)
	(segment
		(start 143.69288 -78.677008)
		(end 143.3322 -78.316328)
		(width 0.127)
		(layer "In11.Cu")
		(net "E1S_0_PRSNT_N")
	)
	(segment
		(start 146.53768 -91.310968)
		(end 152.378664 -97.151952)
		(width 0.127)
		(layer "In15.Cu")
		(net "E1S_0_PRSNT_N")
	)
	(segment
		(start 165.899846 -96.650048)
		(end 166.194994 -96.3549)
		(width 0.127)
		(layer "In15.Cu")
		(net "E1S_0_PRSNT_N")
	)
	(segment
		(start 178.558952 -98.22942)
		(end 180.12664 -98.22942)
		(width 0.127)
		(layer "In15.Cu")
		(net "E1S_0_PRSNT_N")
	)
	(segment
		(start 176.68748 -96.357948)
		(end 178.558952 -98.22942)
		(width 0.127)
		(layer "In15.Cu")
		(net "E1S_0_PRSNT_N")
	)
	(segment
		(start 145.37944 -89.398348)
		(end 146.53768 -90.556588)
		(width 0.127)
		(layer "In15.Cu")
		(net "E1S_0_PRSNT_N")
	)
	(segment
		(start 208.15808 -45.786548)
		(end 186.08548 -45.786548)
		(width 0.127)
		(layer "In15.Cu")
		(net "E1S_0_PRSNT_N")
	)
	(segment
		(start 142.831312 -69.827648)
		(end 137.11682 -69.827648)
		(width 0.127)
		(layer "In15.Cu")
		(net "E1S_0_PRSNT_N")
	)
	(segment
		(start 157.988 -97.151952)
		(end 158.489904 -96.650048)
		(width 0.127)
		(layer "In15.Cu")
		(net "E1S_0_PRSNT_N")
	)
	(segment
		(start 146.53768 -90.556588)
		(end 146.53768 -91.310968)
		(width 0.127)
		(layer "In15.Cu")
		(net "E1S_0_PRSNT_N")
	)
	(segment
		(start 222.941896 -51.012598)
		(end 222.778574 -51.17592)
		(width 0.127)
		(layer "In15.Cu")
		(net "E1S_0_PRSNT_N")
	)
	(segment
		(start 161.7345 -47.745396)
		(end 161.7345 -49.563528)
		(width 0.127)
		(layer "In15.Cu")
		(net "E1S_0_PRSNT_N")
	)
	(segment
		(start 186.08548 -45.786548)
		(end 181.66588 -41.366948)
		(width 0.127)
		(layer "In15.Cu")
		(net "E1S_0_PRSNT_N")
	)
	(segment
		(start 222.778574 -51.17592)
		(end 213.547452 -51.17592)
		(width 0.127)
		(layer "In15.Cu")
		(net "E1S_0_PRSNT_N")
	)
	(segment
		(start 154.31008 -58.34888)
		(end 142.831312 -69.827648)
		(width 0.127)
		(layer "In15.Cu")
		(net "E1S_0_PRSNT_N")
	)
	(segment
		(start 161.7345 -49.563528)
		(end 154.31008 -56.987948)
		(width 0.127)
		(layer "In15.Cu")
		(net "E1S_0_PRSNT_N")
	)
	(segment
		(start 181.66588 -41.366948)
		(end 168.112948 -41.366948)
		(width 0.127)
		(layer "In15.Cu")
		(net "E1S_0_PRSNT_N")
	)
	(segment
		(start 158.489904 -96.650048)
		(end 165.899846 -96.650048)
		(width 0.127)
		(layer "In15.Cu")
		(net "E1S_0_PRSNT_N")
	)
	(segment
		(start 174.087536 -96.3549)
		(end 174.090584 -96.357948)
		(width 0.127)
		(layer "In15.Cu")
		(net "E1S_0_PRSNT_N")
	)
	(segment
		(start 152.378664 -97.151952)
		(end 157.988 -97.151952)
		(width 0.127)
		(layer "In15.Cu")
		(net "E1S_0_PRSNT_N")
	)
	(segment
		(start 166.194994 -96.3549)
		(end 174.087536 -96.3549)
		(width 0.127)
		(layer "In15.Cu")
		(net "E1S_0_PRSNT_N")
	)
	(segment
		(start 213.547452 -51.17592)
		(end 208.15808 -45.786548)
		(width 0.127)
		(layer "In15.Cu")
		(net "E1S_0_PRSNT_N")
	)
	(segment
		(start 174.090584 -96.357948)
		(end 176.68748 -96.357948)
		(width 0.127)
		(layer "In15.Cu")
		(net "E1S_0_PRSNT_N")
	)
	(segment
		(start 168.112948 -41.366948)
		(end 161.7345 -47.745396)
		(width 0.127)
		(layer "In15.Cu")
		(net "E1S_0_PRSNT_N")
	)
	(segment
		(start 154.31008 -56.987948)
		(end 154.31008 -58.34888)
		(width 0.127)
		(layer "In15.Cu")
		(net "E1S_0_PRSNT_N")
	)
	(segment
		(start 224.63125 -48.80102)
		(end 224.63125 -49.71288)
		(width 0.12954)
		(layer "F.Cu")
		(net "E1S_0_PERST1_CLKREQ_N")
	)
	(segment
		(start 227.012754 -49.654206)
		(end 225.8949 -49.654206)
		(width 0.12954)
		(layer "F.Cu")
		(net "E1S_0_PERST1_CLKREQ_N")
	)
	(segment
		(start 232.000044 -48.565054)
		(end 228.101906 -48.565054)
		(width 0.12954)
		(layer "F.Cu")
		(net "E1S_0_PERST1_CLKREQ_N")
	)
	(segment
		(start 224.6122 -47.612046)
		(end 225.8949 -48.894746)
		(width 0.12954)
		(layer "F.Cu")
		(net "E1S_0_PERST1_CLKREQ_N")
	)
	(segment
		(start 225.8949 -48.894746)
		(end 225.8949 -49.654206)
		(width 0.12954)
		(layer "F.Cu")
		(net "E1S_0_PERST1_CLKREQ_N")
	)
	(segment
		(start 224.6122 -48.78197)
		(end 224.63125 -48.80102)
		(width 0.12954)
		(layer "F.Cu")
		(net "E1S_0_PERST1_CLKREQ_N")
	)
	(segment
		(start 224.6122 -48.78197)
		(end 224.6122 -47.612046)
		(width 0.12954)
		(layer "F.Cu")
		(net "E1S_0_PERST1_CLKREQ_N")
	)
	(segment
		(start 228.101906 -48.565054)
		(end 227.012754 -49.654206)
		(width 0.12954)
		(layer "F.Cu")
		(net "E1S_0_PERST1_CLKREQ_N")
	)
	(via
		(at 225.8949 -49.654206)
		(size 0.762)
		(drill 0.381)
		(layers "F.Cu" "B.Cu")
		(net "E1S_0_PERST1_CLKREQ_N")
	)
	(segment
		(start 194.056 -93.201998)
		(end 194.056 -93.894148)
		(width 0.12954)
		(layer "F.Cu")
		(net "E1S_0_LED_ACT_N")
	)
	(segment
		(start 230.78948 -47.980346)
		(end 230.804974 -47.964852)
		(width 0.12954)
		(layer "F.Cu")
		(net "E1S_0_LED_ACT_N")
	)
	(segment
		(start 230.804974 -47.964852)
		(end 232.000044 -47.964852)
		(width 0.12954)
		(layer "F.Cu")
		(net "E1S_0_LED_ACT_N")
	)
	(via
		(at 222.292926 -47.018702)
		(size 0.508)
		(drill 0.254)
		(layers "F.Cu" "B.Cu")
		(net "E1S_0_LED_ACT_N")
	)
	(via
		(at 194.056 -93.894148)
		(size 0.508)
		(drill 0.254)
		(layers "F.Cu" "B.Cu")
		(net "E1S_0_LED_ACT_N")
	)
	(via
		(at 230.78948 -47.980346)
		(size 0.508)
		(drill 0.254)
		(layers "F.Cu" "B.Cu")
		(net "E1S_0_LED_ACT_N")
	)
	(segment
		(start 224.586038 -47.980346)
		(end 223.624394 -47.018702)
		(width 0.12954)
		(layer "B.Cu")
		(net "E1S_0_LED_ACT_N")
	)
	(segment
		(start 230.78948 -47.980346)
		(end 224.586038 -47.980346)
		(width 0.12954)
		(layer "B.Cu")
		(net "E1S_0_LED_ACT_N")
	)
	(segment
		(start 223.624394 -47.018702)
		(end 222.292926 -47.018702)
		(width 0.12954)
		(layer "B.Cu")
		(net "E1S_0_LED_ACT_N")
	)
	(segment
		(start 189.474094 -86.959948)
		(end 194.427094 -91.912948)
		(width 0.127)
		(layer "In15.Cu")
		(net "E1S_0_LED_ACT_N")
	)
	(segment
		(start 194.427094 -91.912948)
		(end 197.221094 -91.912948)
		(width 0.127)
		(layer "In15.Cu")
		(net "E1S_0_LED_ACT_N")
	)
	(segment
		(start 212.8774 -51.577748)
		(end 207.4418 -46.142148)
		(width 0.127)
		(layer "In15.Cu")
		(net "E1S_0_LED_ACT_N")
	)
	(segment
		(start 223.8248 -47.564548)
		(end 223.8248 -51.145948)
		(width 0.127)
		(layer "In15.Cu")
		(net "E1S_0_LED_ACT_N")
	)
	(segment
		(start 175.1838 -44.440348)
		(end 175.1838 -59.654948)
		(width 0.127)
		(layer "In15.Cu")
		(net "E1S_0_LED_ACT_N")
	)
	(segment
		(start 181.528974 -41.697148)
		(end 177.927 -41.697148)
		(width 0.127)
		(layer "In15.Cu")
		(net "E1S_0_LED_ACT_N")
	)
	(segment
		(start 171.7548 -63.083948)
		(end 171.7548 -77.511148)
		(width 0.127)
		(layer "In15.Cu")
		(net "E1S_0_LED_ACT_N")
	)
	(segment
		(start 185.973974 -46.142148)
		(end 181.528974 -41.697148)
		(width 0.127)
		(layer "In15.Cu")
		(net "E1S_0_LED_ACT_N")
	)
	(segment
		(start 223.8248 -51.145948)
		(end 223.393 -51.577748)
		(width 0.127)
		(layer "In15.Cu")
		(net "E1S_0_LED_ACT_N")
	)
	(segment
		(start 197.7898 -92.481654)
		(end 197.7898 -93.960442)
		(width 0.127)
		(layer "In15.Cu")
		(net "E1S_0_LED_ACT_N")
	)
	(segment
		(start 197.221094 -91.912948)
		(end 197.7898 -92.481654)
		(width 0.127)
		(layer "In15.Cu")
		(net "E1S_0_LED_ACT_N")
	)
	(segment
		(start 222.292926 -47.018702)
		(end 223.278954 -47.018702)
		(width 0.127)
		(layer "In15.Cu")
		(net "E1S_0_LED_ACT_N")
	)
	(segment
		(start 197.322694 -94.427548)
		(end 194.5894 -94.427548)
		(width 0.127)
		(layer "In15.Cu")
		(net "E1S_0_LED_ACT_N")
	)
	(segment
		(start 197.7898 -93.960442)
		(end 197.322694 -94.427548)
		(width 0.127)
		(layer "In15.Cu")
		(net "E1S_0_LED_ACT_N")
	)
	(segment
		(start 177.927 -41.697148)
		(end 175.1838 -44.440348)
		(width 0.127)
		(layer "In15.Cu")
		(net "E1S_0_LED_ACT_N")
	)
	(segment
		(start 223.393 -51.577748)
		(end 212.8774 -51.577748)
		(width 0.127)
		(layer "In15.Cu")
		(net "E1S_0_LED_ACT_N")
	)
	(segment
		(start 194.5894 -94.427548)
		(end 194.056 -93.894148)
		(width 0.127)
		(layer "In15.Cu")
		(net "E1S_0_LED_ACT_N")
	)
	(segment
		(start 171.7548 -77.511148)
		(end 181.2036 -86.959948)
		(width 0.127)
		(layer "In15.Cu")
		(net "E1S_0_LED_ACT_N")
	)
	(segment
		(start 223.278954 -47.018702)
		(end 223.8248 -47.564548)
		(width 0.127)
		(layer "In15.Cu")
		(net "E1S_0_LED_ACT_N")
	)
	(segment
		(start 181.2036 -86.959948)
		(end 189.474094 -86.959948)
		(width 0.127)
		(layer "In15.Cu")
		(net "E1S_0_LED_ACT_N")
	)
	(segment
		(start 175.1838 -59.654948)
		(end 171.7548 -63.083948)
		(width 0.127)
		(layer "In15.Cu")
		(net "E1S_0_LED_ACT_N")
	)
	(segment
		(start 207.4418 -46.142148)
		(end 185.973974 -46.142148)
		(width 0.127)
		(layer "In15.Cu")
		(net "E1S_0_LED_ACT_N")
	)
	(segment
		(start 239.53978 -49.964086)
		(end 239.8395 -50.263806)
		(width 0.13208)
		(layer "F.Cu")
		(net "CLK_100M_E1S_0_DP")
	)
	(segment
		(start 238.9886 -49.964086)
		(end 239.53978 -49.964086)
		(width 0.13208)
		(layer "F.Cu")
		(net "CLK_100M_E1S_0_DP")
	)
	(segment
		(start 328.523092 -73.909428)
		(end 328.60488 -73.909428)
		(width 0.13208)
		(layer "F.Cu")
		(net "CLK_100M_E1S_0_DP")
	)
	(segment
		(start 236.599984 -50.964846)
		(end 237.03788 -50.964846)
		(width 0.13208)
		(layer "F.Cu")
		(net "CLK_100M_E1S_0_DP")
	)
	(segment
		(start 328.60488 -73.909428)
		(end 328.8538 -74.158348)
		(width 0.13208)
		(layer "F.Cu")
		(net "CLK_100M_E1S_0_DP")
	)
	(segment
		(start 238.148114 -50.804572)
		(end 238.9886 -49.964086)
		(width 0.13208)
		(layer "F.Cu")
		(net "CLK_100M_E1S_0_DP")
	)
	(segment
		(start 328.24166 -75.819508)
		(end 327.9394 -76.121768)
		(width 0.13208)
		(layer "F.Cu")
		(net "CLK_100M_E1S_0_DP")
	)
	(segment
		(start 237.03788 -50.964846)
		(end 237.198154 -50.804572)
		(width 0.13208)
		(layer "F.Cu")
		(net "CLK_100M_E1S_0_DP")
	)
	(segment
		(start 328.385678 -75.019408)
		(end 328.24166 -75.36688)
		(width 0.13208)
		(layer "F.Cu")
		(net "CLK_100M_E1S_0_DP")
	)
	(segment
		(start 237.198154 -50.804572)
		(end 238.148114 -50.804572)
		(width 0.13208)
		(layer "F.Cu")
		(net "CLK_100M_E1S_0_DP")
	)
	(segment
		(start 328.24166 -75.36688)
		(end 328.24166 -75.819508)
		(width 0.13208)
		(layer "F.Cu")
		(net "CLK_100M_E1S_0_DP")
	)
	(segment
		(start 328.763122 -74.641964)
		(end 328.385678 -75.019408)
		(width 0.13208)
		(layer "F.Cu")
		(net "CLK_100M_E1S_0_DP")
	)
	(segment
		(start 328.8538 -74.158348)
		(end 328.8538 -74.42327)
		(width 0.13208)
		(layer "F.Cu")
		(net "CLK_100M_E1S_0_DP")
	)
	(segment
		(start 328.8538 -74.42327)
		(end 328.763122 -74.641964)
		(width 0.13208)
		(layer "F.Cu")
		(net "CLK_100M_E1S_0_DP")
	)
	(via
		(at 239.8395 -50.263806)
		(size 0.508)
		(drill 0.254)
		(layers "F.Cu" "B.Cu")
		(net "CLK_100M_E1S_0_DP")
	)
	(via
		(at 327.9394 -76.121768)
		(size 0.508)
		(drill 0.254)
		(layers "F.Cu" "B.Cu")
		(net "CLK_100M_E1S_0_DP")
	)
	(segment
		(start 326.971152 -77.230986)
		(end 327.311512 -77.090016)
		(width 0.14732)
		(layer "In4.Cu")
		(net "CLK_100M_E1S_0_DP")
	)
	(segment
		(start 327.494138 -77.165454)
		(end 327.834244 -77.024738)
		(width 0.14732)
		(layer "In4.Cu")
		(net "CLK_100M_E1S_0_DP")
	)
	(segment
		(start 232.67416 -56.303672)
		(end 231.71404 -61.13018)
		(width 0.14732)
		(layer "In4.Cu")
		(net "CLK_100M_E1S_0_DP")
	)
	(segment
		(start 321.6275 -79.174848)
		(end 321.7672 -79.035148)
		(width 0.14732)
		(layer "In4.Cu")
		(net "CLK_100M_E1S_0_DP")
	)
	(segment
		(start 325.433944 -77.867764)
		(end 325.61657 -77.943202)
		(width 0.14732)
		(layer "In4.Cu")
		(net "CLK_100M_E1S_0_DP")
	)
	(segment
		(start 326.555354 -77.554328)
		(end 326.89546 -77.413612)
		(width 0.14732)
		(layer "In4.Cu")
		(net "CLK_100M_E1S_0_DP")
	)
	(segment
		(start 233.258868 -54.002686)
		(end 233.11231 -54.100476)
		(width 0.14732)
		(layer "In4.Cu")
		(net "CLK_100M_E1S_0_DP")
	)
	(segment
		(start 233.421174 -52.547774)
		(end 233.246168 -53.42763)
		(width 0.14732)
		(layer "In4.Cu")
		(net "CLK_100M_E1S_0_DP")
	)
	(segment
		(start 236.00029 -50.770028)
		(end 235.19892 -50.770028)
		(width 0.14732)
		(layer "In4.Cu")
		(net "CLK_100M_E1S_0_DP")
	)
	(segment
		(start 239.092486 -49.969166)
		(end 238.489998 -50.219102)
		(width 0.14732)
		(layer "In4.Cu")
		(net "CLK_100M_E1S_0_DP")
	)
	(segment
		(start 232.028746 -62.799468)
		(end 233.424984 -64.196214)
		(width 0.14732)
		(layer "In4.Cu")
		(net "CLK_100M_E1S_0_DP")
	)
	(segment
		(start 328.23404 -76.624942)
		(end 328.23404 -76.416408)
		(width 0.14732)
		(layer "In4.Cu")
		(net "CLK_100M_E1S_0_DP")
	)
	(segment
		(start 238.489998 -50.219102)
		(end 237.86211 -50.63871)
		(width 0.14732)
		(layer "In4.Cu")
		(net "CLK_100M_E1S_0_DP")
	)
	(segment
		(start 231.71404 -61.13018)
		(end 231.71404 -62.040008)
		(width 0.14732)
		(layer "In4.Cu")
		(net "CLK_100M_E1S_0_DP")
	)
	(segment
		(start 324.07606 -78.581504)
		(end 324.151752 -78.398624)
		(width 0.14732)
		(layer "In4.Cu")
		(net "CLK_100M_E1S_0_DP")
	)
	(segment
		(start 326.032368 -77.61986)
		(end 326.372728 -77.47889)
		(width 0.14732)
		(layer "In4.Cu")
		(net "CLK_100M_E1S_0_DP")
	)
	(segment
		(start 327.311512 -77.090016)
		(end 327.494138 -77.165454)
		(width 0.14732)
		(layer "In4.Cu")
		(net "CLK_100M_E1S_0_DP")
	)
	(segment
		(start 233.039666 -55.10403)
		(end 232.893108 -55.20182)
		(width 0.14732)
		(layer "In4.Cu")
		(net "CLK_100M_E1S_0_DP")
	)
	(segment
		(start 324.492112 -78.257908)
		(end 324.674738 -78.333346)
		(width 0.14732)
		(layer "In4.Cu")
		(net "CLK_100M_E1S_0_DP")
	)
	(segment
		(start 233.02722 -54.52872)
		(end 233.12501 -54.675278)
		(width 0.14732)
		(layer "In4.Cu")
		(net "CLK_100M_E1S_0_DP")
	)
	(segment
		(start 320.88709 -79.035148)
		(end 321.02679 -79.174848)
		(width 0.14732)
		(layer "In4.Cu")
		(net "CLK_100M_E1S_0_DP")
	)
	(segment
		(start 326.372728 -77.47889)
		(end 326.555354 -77.554328)
		(width 0.14732)
		(layer "In4.Cu")
		(net "CLK_100M_E1S_0_DP")
	)
	(segment
		(start 239.54486 -49.969166)
		(end 239.092486 -49.969166)
		(width 0.14732)
		(layer "In4.Cu")
		(net "CLK_100M_E1S_0_DP")
	)
	(segment
		(start 327.834244 -77.024738)
		(end 328.23404 -76.624942)
		(width 0.14732)
		(layer "In4.Cu")
		(net "CLK_100M_E1S_0_DP")
	)
	(segment
		(start 325.956676 -77.802486)
		(end 326.032368 -77.61986)
		(width 0.14732)
		(layer "In4.Cu")
		(net "CLK_100M_E1S_0_DP")
	)
	(segment
		(start 237.86211 -50.63871)
		(end 237.545118 -50.770028)
		(width 0.14732)
		(layer "In4.Cu")
		(net "CLK_100M_E1S_0_DP")
	)
	(segment
		(start 232.673906 -56.303164)
		(end 232.67416 -56.303418)
		(width 0.14732)
		(layer "In4.Cu")
		(net "CLK_100M_E1S_0_DP")
	)
	(segment
		(start 233.11231 -54.100476)
		(end 233.02722 -54.52872)
		(width 0.14732)
		(layer "In4.Cu")
		(net "CLK_100M_E1S_0_DP")
	)
	(segment
		(start 233.424984 -64.196214)
		(end 240.171224 -68.703698)
		(width 0.14732)
		(layer "In4.Cu")
		(net "CLK_100M_E1S_0_DP")
	)
	(segment
		(start 319.38595 -79.035148)
		(end 319.75425 -79.035148)
		(width 0.14732)
		(layer "In4.Cu")
		(net "CLK_100M_E1S_0_DP")
	)
	(segment
		(start 233.681524 -52.287424)
		(end 233.421174 -52.547774)
		(width 0.14732)
		(layer "In4.Cu")
		(net "CLK_100M_E1S_0_DP")
	)
	(segment
		(start 322.1355 -79.035148)
		(end 322.2752 -79.174848)
		(width 0.14732)
		(layer "In4.Cu")
		(net "CLK_100M_E1S_0_DP")
	)
	(segment
		(start 324.674738 -78.333346)
		(end 325.017892 -78.19136)
		(width 0.14732)
		(layer "In4.Cu")
		(net "CLK_100M_E1S_0_DP")
	)
	(segment
		(start 319.24625 -79.174848)
		(end 319.38595 -79.035148)
		(width 0.14732)
		(layer "In4.Cu")
		(net "CLK_100M_E1S_0_DP")
	)
	(segment
		(start 232.893108 -55.20182)
		(end 232.808018 -55.630064)
		(width 0.14732)
		(layer "In4.Cu")
		(net "CLK_100M_E1S_0_DP")
	)
	(segment
		(start 235.19892 -50.770028)
		(end 234.13974 -51.829208)
		(width 0.14732)
		(layer "In4.Cu")
		(net "CLK_100M_E1S_0_DP")
	)
	(segment
		(start 320.37909 -79.174848)
		(end 320.51879 -79.035148)
		(width 0.14732)
		(layer "In4.Cu")
		(net "CLK_100M_E1S_0_DP")
	)
	(segment
		(start 239.8395 -50.263806)
		(end 239.54486 -49.969166)
		(width 0.14732)
		(layer "In4.Cu")
		(net "CLK_100M_E1S_0_DP")
	)
	(segment
		(start 325.017892 -78.19136)
		(end 325.093584 -78.008734)
		(width 0.14732)
		(layer "In4.Cu")
		(net "CLK_100M_E1S_0_DP")
	)
	(segment
		(start 319.89395 -79.174848)
		(end 320.37909 -79.174848)
		(width 0.14732)
		(layer "In4.Cu")
		(net "CLK_100M_E1S_0_DP")
	)
	(segment
		(start 255.282192 -79.174848)
		(end 264.981436 -83.192366)
		(width 0.14732)
		(layer "In4.Cu")
		(net "CLK_100M_E1S_0_DP")
	)
	(segment
		(start 325.093584 -78.008734)
		(end 325.433944 -77.867764)
		(width 0.14732)
		(layer "In4.Cu")
		(net "CLK_100M_E1S_0_DP")
	)
	(segment
		(start 240.171224 -68.703698)
		(end 248.057162 -76.58989)
		(width 0.14732)
		(layer "In4.Cu")
		(net "CLK_100M_E1S_0_DP")
	)
	(segment
		(start 326.89546 -77.413612)
		(end 326.971152 -77.230986)
		(width 0.14732)
		(layer "In4.Cu")
		(net "CLK_100M_E1S_0_DP")
	)
	(segment
		(start 233.879136 -52.287424)
		(end 233.681524 -52.287424)
		(width 0.14732)
		(layer "In4.Cu")
		(net "CLK_100M_E1S_0_DP")
	)
	(segment
		(start 233.12501 -54.675278)
		(end 233.039666 -55.10403)
		(width 0.14732)
		(layer "In4.Cu")
		(net "CLK_100M_E1S_0_DP")
	)
	(segment
		(start 236.50829 -50.909728)
		(end 236.13999 -50.909728)
		(width 0.14732)
		(layer "In4.Cu")
		(net "CLK_100M_E1S_0_DP")
	)
	(segment
		(start 320.51879 -79.035148)
		(end 320.88709 -79.035148)
		(width 0.14732)
		(layer "In4.Cu")
		(net "CLK_100M_E1S_0_DP")
	)
	(segment
		(start 232.808018 -55.630064)
		(end 232.905808 -55.776622)
		(width 0.14732)
		(layer "In4.Cu")
		(net "CLK_100M_E1S_0_DP")
	)
	(segment
		(start 325.61657 -77.943202)
		(end 325.956676 -77.802486)
		(width 0.14732)
		(layer "In4.Cu")
		(net "CLK_100M_E1S_0_DP")
	)
	(segment
		(start 319.75425 -79.035148)
		(end 319.89395 -79.174848)
		(width 0.14732)
		(layer "In4.Cu")
		(net "CLK_100M_E1S_0_DP")
	)
	(segment
		(start 236.13999 -50.909728)
		(end 236.00029 -50.770028)
		(width 0.14732)
		(layer "In4.Cu")
		(net "CLK_100M_E1S_0_DP")
	)
	(segment
		(start 234.13974 -51.829208)
		(end 234.13974 -52.02682)
		(width 0.14732)
		(layer "In4.Cu")
		(net "CLK_100M_E1S_0_DP")
	)
	(segment
		(start 233.343958 -53.574188)
		(end 233.258868 -54.002686)
		(width 0.14732)
		(layer "In4.Cu")
		(net "CLK_100M_E1S_0_DP")
	)
	(segment
		(start 248.057162 -76.58989)
		(end 254.297434 -79.174848)
		(width 0.14732)
		(layer "In4.Cu")
		(net "CLK_100M_E1S_0_DP")
	)
	(segment
		(start 232.67416 -56.303418)
		(end 232.67416 -56.303672)
		(width 0.14732)
		(layer "In4.Cu")
		(net "CLK_100M_E1S_0_DP")
	)
	(segment
		(start 233.246168 -53.42763)
		(end 233.343958 -53.574188)
		(width 0.14732)
		(layer "In4.Cu")
		(net "CLK_100M_E1S_0_DP")
	)
	(segment
		(start 322.6435 -79.174848)
		(end 324.07606 -78.581504)
		(width 0.14732)
		(layer "In4.Cu")
		(net "CLK_100M_E1S_0_DP")
	)
	(segment
		(start 264.981436 -83.192366)
		(end 303.354232 -83.192366)
		(width 0.14732)
		(layer "In4.Cu")
		(net "CLK_100M_E1S_0_DP")
	)
	(segment
		(start 234.13974 -52.02682)
		(end 233.879136 -52.287424)
		(width 0.14732)
		(layer "In4.Cu")
		(net "CLK_100M_E1S_0_DP")
	)
	(segment
		(start 321.02679 -79.174848)
		(end 321.6275 -79.174848)
		(width 0.14732)
		(layer "In4.Cu")
		(net "CLK_100M_E1S_0_DP")
	)
	(segment
		(start 328.23404 -76.416408)
		(end 327.9394 -76.121768)
		(width 0.14732)
		(layer "In4.Cu")
		(net "CLK_100M_E1S_0_DP")
	)
	(segment
		(start 254.297434 -79.174848)
		(end 255.282192 -79.174848)
		(width 0.14732)
		(layer "In4.Cu")
		(net "CLK_100M_E1S_0_DP")
	)
	(segment
		(start 232.905808 -55.776622)
		(end 232.820464 -56.205374)
		(width 0.14732)
		(layer "In4.Cu")
		(net "CLK_100M_E1S_0_DP")
	)
	(segment
		(start 236.64799 -50.770028)
		(end 236.50829 -50.909728)
		(width 0.14732)
		(layer "In4.Cu")
		(net "CLK_100M_E1S_0_DP")
	)
	(segment
		(start 324.151752 -78.398624)
		(end 324.492112 -78.257908)
		(width 0.14732)
		(layer "In4.Cu")
		(net "CLK_100M_E1S_0_DP")
	)
	(segment
		(start 321.7672 -79.035148)
		(end 322.1355 -79.035148)
		(width 0.14732)
		(layer "In4.Cu")
		(net "CLK_100M_E1S_0_DP")
	)
	(segment
		(start 322.2752 -79.174848)
		(end 322.6435 -79.174848)
		(width 0.14732)
		(layer "In4.Cu")
		(net "CLK_100M_E1S_0_DP")
	)
	(segment
		(start 232.820464 -56.205374)
		(end 232.673906 -56.303164)
		(width 0.14732)
		(layer "In4.Cu")
		(net "CLK_100M_E1S_0_DP")
	)
	(segment
		(start 231.71404 -62.040008)
		(end 232.028746 -62.799468)
		(width 0.14732)
		(layer "In4.Cu")
		(net "CLK_100M_E1S_0_DP")
	)
	(segment
		(start 237.545118 -50.770028)
		(end 236.64799 -50.770028)
		(width 0.14732)
		(layer "In4.Cu")
		(net "CLK_100M_E1S_0_DP")
	)
	(segment
		(start 303.354232 -83.192366)
		(end 313.053476 -79.174848)
		(width 0.14732)
		(layer "In4.Cu")
		(net "CLK_100M_E1S_0_DP")
	)
	(segment
		(start 313.053476 -79.174848)
		(end 319.24625 -79.174848)
		(width 0.14732)
		(layer "In4.Cu")
		(net "CLK_100M_E1S_0_DP")
	)
	(segment
		(start 329.524868 -73.909428)
		(end 329.3618 -73.909428)
		(width 0.13208)
		(layer "F.Cu")
		(net "CLK_100M_E1S_0_DN")
	)
	(segment
		(start 237.205266 -50.545492)
		(end 237.024672 -50.364898)
		(width 0.13208)
		(layer "F.Cu")
		(net "CLK_100M_E1S_0_DN")
	)
	(segment
		(start 328.982832 -74.788776)
		(end 328.605388 -75.16622)
		(width 0.13208)
		(layer "F.Cu")
		(net "CLK_100M_E1S_0_DN")
	)
	(segment
		(start 238.881158 -49.705006)
		(end 238.040672 -50.545492)
		(width 0.13208)
		(layer "F.Cu")
		(net "CLK_100M_E1S_0_DN")
	)
	(segment
		(start 329.3618 -73.909428)
		(end 329.11288 -74.158348)
		(width 0.13208)
		(layer "F.Cu")
		(net "CLK_100M_E1S_0_DN")
	)
	(segment
		(start 329.11288 -74.475086)
		(end 328.982832 -74.788776)
		(width 0.13208)
		(layer "F.Cu")
		(net "CLK_100M_E1S_0_DN")
	)
	(segment
		(start 239.5347 -49.705006)
		(end 238.881158 -49.705006)
		(width 0.13208)
		(layer "F.Cu")
		(net "CLK_100M_E1S_0_DN")
	)
	(segment
		(start 237.024672 -50.364898)
		(end 236.599984 -50.364898)
		(width 0.13208)
		(layer "F.Cu")
		(net "CLK_100M_E1S_0_DN")
	)
	(segment
		(start 238.040672 -50.545492)
		(end 237.205266 -50.545492)
		(width 0.13208)
		(layer "F.Cu")
		(net "CLK_100M_E1S_0_DN")
	)
	(segment
		(start 329.11288 -74.158348)
		(end 329.11288 -74.475086)
		(width 0.13208)
		(layer "F.Cu")
		(net "CLK_100M_E1S_0_DN")
	)
	(segment
		(start 239.8395 -49.400206)
		(end 239.5347 -49.705006)
		(width 0.13208)
		(layer "F.Cu")
		(net "CLK_100M_E1S_0_DN")
	)
	(segment
		(start 328.50074 -75.819508)
		(end 328.803 -76.121768)
		(width 0.13208)
		(layer "F.Cu")
		(net "CLK_100M_E1S_0_DN")
	)
	(segment
		(start 328.50074 -75.418696)
		(end 328.50074 -75.819508)
		(width 0.13208)
		(layer "F.Cu")
		(net "CLK_100M_E1S_0_DN")
	)
	(segment
		(start 328.605388 -75.16622)
		(end 328.50074 -75.418696)
		(width 0.13208)
		(layer "F.Cu")
		(net "CLK_100M_E1S_0_DN")
	)
	(via
		(at 328.803 -76.121768)
		(size 0.508)
		(drill 0.254)
		(layers "F.Cu" "B.Cu")
		(net "CLK_100M_E1S_0_DN")
	)
	(via
		(at 239.8395 -49.400206)
		(size 0.508)
		(drill 0.254)
		(layers "F.Cu" "B.Cu")
		(net "CLK_100M_E1S_0_DN")
	)
	(segment
		(start 322.69811 -79.449168)
		(end 327.989692 -77.257402)
		(width 0.14732)
		(layer "In4.Cu")
		(net "CLK_100M_E1S_0_DN")
	)
	(segment
		(start 264.926826 -83.466686)
		(end 303.408842 -83.466686)
		(width 0.14732)
		(layer "In4.Cu")
		(net "CLK_100M_E1S_0_DN")
	)
	(segment
		(start 237.490508 -50.495708)
		(end 235.085128 -50.495708)
		(width 0.14732)
		(layer "In4.Cu")
		(net "CLK_100M_E1S_0_DN")
	)
	(segment
		(start 328.50836 -76.738734)
		(end 328.50836 -76.416408)
		(width 0.14732)
		(layer "In4.Cu")
		(net "CLK_100M_E1S_0_DN")
	)
	(segment
		(start 255.227582 -79.449168)
		(end 264.926826 -83.466686)
		(width 0.14732)
		(layer "In4.Cu")
		(net "CLK_100M_E1S_0_DN")
	)
	(segment
		(start 239.037622 -49.694846)
		(end 238.35995 -49.976024)
		(width 0.14732)
		(layer "In4.Cu")
		(net "CLK_100M_E1S_0_DN")
	)
	(segment
		(start 235.085128 -50.495708)
		(end 233.16819 -52.412646)
		(width 0.14732)
		(layer "In4.Cu")
		(net "CLK_100M_E1S_0_DN")
	)
	(segment
		(start 233.249978 -64.40932)
		(end 239.996218 -68.917058)
		(width 0.14732)
		(layer "In4.Cu")
		(net "CLK_100M_E1S_0_DN")
	)
	(segment
		(start 239.8395 -49.400206)
		(end 239.54486 -49.694846)
		(width 0.14732)
		(layer "In4.Cu")
		(net "CLK_100M_E1S_0_DN")
	)
	(segment
		(start 231.43972 -61.103002)
		(end 231.43972 -62.094618)
		(width 0.14732)
		(layer "In4.Cu")
		(net "CLK_100M_E1S_0_DN")
	)
	(segment
		(start 328.50836 -76.416408)
		(end 328.803 -76.121768)
		(width 0.14732)
		(layer "In4.Cu")
		(net "CLK_100M_E1S_0_DN")
	)
	(segment
		(start 247.901714 -76.822554)
		(end 254.242824 -79.449168)
		(width 0.14732)
		(layer "In4.Cu")
		(net "CLK_100M_E1S_0_DN")
	)
	(segment
		(start 327.989692 -77.257402)
		(end 328.50836 -76.738734)
		(width 0.14732)
		(layer "In4.Cu")
		(net "CLK_100M_E1S_0_DN")
	)
	(segment
		(start 231.43972 -62.094618)
		(end 231.796082 -62.954916)
		(width 0.14732)
		(layer "In4.Cu")
		(net "CLK_100M_E1S_0_DN")
	)
	(segment
		(start 254.242824 -79.449168)
		(end 255.227582 -79.449168)
		(width 0.14732)
		(layer "In4.Cu")
		(net "CLK_100M_E1S_0_DN")
	)
	(segment
		(start 237.732062 -50.395632)
		(end 237.490508 -50.495708)
		(width 0.14732)
		(layer "In4.Cu")
		(net "CLK_100M_E1S_0_DN")
	)
	(segment
		(start 239.996218 -68.917058)
		(end 247.901714 -76.822554)
		(width 0.14732)
		(layer "In4.Cu")
		(net "CLK_100M_E1S_0_DN")
	)
	(segment
		(start 313.108086 -79.449168)
		(end 322.69811 -79.449168)
		(width 0.14732)
		(layer "In4.Cu")
		(net "CLK_100M_E1S_0_DN")
	)
	(segment
		(start 238.35995 -49.976024)
		(end 237.732062 -50.395632)
		(width 0.14732)
		(layer "In4.Cu")
		(net "CLK_100M_E1S_0_DN")
	)
	(segment
		(start 233.16819 -52.412646)
		(end 231.43972 -61.103002)
		(width 0.14732)
		(layer "In4.Cu")
		(net "CLK_100M_E1S_0_DN")
	)
	(segment
		(start 239.54486 -49.694846)
		(end 239.037622 -49.694846)
		(width 0.14732)
		(layer "In4.Cu")
		(net "CLK_100M_E1S_0_DN")
	)
	(segment
		(start 231.796082 -62.954916)
		(end 233.249978 -64.40932)
		(width 0.14732)
		(layer "In4.Cu")
		(net "CLK_100M_E1S_0_DN")
	)
	(segment
		(start 303.408842 -83.466686)
		(end 313.108086 -79.449168)
		(width 0.14732)
		(layer "In4.Cu")
		(net "CLK_100M_E1S_0_DN")
	)
	(segment
		(start 24.763984 -113.415826)
		(end 25.906984 -112.272826)
		(width 0.12954)
		(layer "F.Cu")
		(net "ADC128_VREF")
	)
	(segment
		(start 22.409404 -108.793026)
		(end 21.799804 -108.793026)
		(width 0.12954)
		(layer "F.Cu")
		(net "ADC128_VREF")
	)
	(segment
		(start 25.906984 -111.882682)
		(end 26.18105 -111.608616)
		(width 0.12954)
		(layer "F.Cu")
		(net "ADC128_VREF")
	)
	(segment
		(start 26.18105 -111.608616)
		(end 26.915618 -111.608616)
		(width 0.12954)
		(layer "F.Cu")
		(net "ADC128_VREF")
	)
	(segment
		(start 23.209504 -114.431826)
		(end 23.876254 -114.431826)
		(width 0.12954)
		(layer "F.Cu")
		(net "ADC128_VREF")
	)
	(segment
		(start 24.763984 -113.544096)
		(end 23.987506 -114.320574)
		(width 0.12954)
		(layer "F.Cu")
		(net "ADC128_VREF")
	)
	(segment
		(start 23.876254 -114.431826)
		(end 23.987506 -114.320574)
		(width 0.12954)
		(layer "F.Cu")
		(net "ADC128_VREF")
	)
	(segment
		(start 25.906984 -112.272826)
		(end 25.906984 -111.882682)
		(width 0.12954)
		(layer "F.Cu")
		(net "ADC128_VREF")
	)
	(segment
		(start 24.763984 -113.415826)
		(end 24.763984 -113.544096)
		(width 0.12954)
		(layer "F.Cu")
		(net "ADC128_VREF")
	)
	(via
		(at 24.763984 -113.415826)
		(size 0.762)
		(drill 0.381)
		(layers "F.Cu" "B.Cu")
		(net "ADC128_VREF")
	)
	(via
		(at 21.799804 -108.793026)
		(size 0.508)
		(drill 0.254)
		(layers "F.Cu" "B.Cu")
		(net "ADC128_VREF")
	)
	(via
		(at 23.987506 -114.320574)
		(size 0.508)
		(drill 0.254)
		(layers "F.Cu" "B.Cu")
		(net "ADC128_VREF")
	)
	(segment
		(start 23.987506 -114.320574)
		(end 23.80234 -114.135408)
		(width 0.12954)
		(layer "B.Cu")
		(net "ADC128_VREF")
	)
	(segment
		(start 23.80234 -110.795562)
		(end 21.799804 -108.793026)
		(width 0.12954)
		(layer "B.Cu")
		(net "ADC128_VREF")
	)
	(segment
		(start 23.80234 -114.135408)
		(end 23.80234 -110.795562)
		(width 0.12954)
		(layer "B.Cu")
		(net "ADC128_VREF")
	)
	(segment
		(start 23.209504 -106.761026)
		(end 22.46376 -106.015282)
		(width 0.12954)
		(layer "F.Cu")
		(net "ADC128_A1")
	)
	(segment
		(start 24.865584 -105.761282)
		(end 26.162762 -107.05846)
		(width 0.12954)
		(layer "F.Cu")
		(net "ADC128_A1")
	)
	(segment
		(start 23.209504 -106.761026)
		(end 24.209248 -105.761282)
		(width 0.12954)
		(layer "F.Cu")
		(net "ADC128_A1")
	)
	(segment
		(start 26.162762 -107.05846)
		(end 26.915618 -107.05846)
		(width 0.12954)
		(layer "F.Cu")
		(net "ADC128_A1")
	)
	(segment
		(start 21.336508 -106.015282)
		(end 20.590764 -106.761026)
		(width 0.12954)
		(layer "F.Cu")
		(net "ADC128_A1")
	)
	(segment
		(start 24.209248 -105.761282)
		(end 24.484584 -105.761282)
		(width 0.12954)
		(layer "F.Cu")
		(net "ADC128_A1")
	)
	(segment
		(start 24.484584 -105.761282)
		(end 24.865584 -105.761282)
		(width 0.12954)
		(layer "F.Cu")
		(net "ADC128_A1")
	)
	(segment
		(start 22.46376 -106.015282)
		(end 21.336508 -106.015282)
		(width 0.12954)
		(layer "F.Cu")
		(net "ADC128_A1")
	)
	(via
		(at 24.484584 -105.761282)
		(size 0.762)
		(drill 0.381)
		(layers "F.Cu" "B.Cu")
		(net "ADC128_A1")
	)
	(segment
		(start 24.082248 -106.904282)
		(end 25.119584 -106.904282)
		(width 0.12954)
		(layer "F.Cu")
		(net "ADC128_A0")
	)
	(segment
		(start 25.119584 -106.904282)
		(end 25.923748 -107.708446)
		(width 0.12954)
		(layer "F.Cu")
		(net "ADC128_A0")
	)
	(segment
		(start 25.923748 -107.708446)
		(end 26.915618 -107.708446)
		(width 0.12954)
		(layer "F.Cu")
		(net "ADC128_A0")
	)
	(segment
		(start 21.082508 -107.285282)
		(end 20.590764 -107.777026)
		(width 0.12954)
		(layer "F.Cu")
		(net "ADC128_A0")
	)
	(segment
		(start 22.71776 -107.285282)
		(end 21.082508 -107.285282)
		(width 0.12954)
		(layer "F.Cu")
		(net "ADC128_A0")
	)
	(segment
		(start 23.209504 -107.777026)
		(end 22.71776 -107.285282)
		(width 0.12954)
		(layer "F.Cu")
		(net "ADC128_A0")
	)
	(segment
		(start 23.209504 -107.777026)
		(end 24.082248 -106.904282)
		(width 0.12954)
		(layer "F.Cu")
		(net "ADC128_A0")
	)
	(via
		(at 25.119584 -106.904282)
		(size 0.762)
		(drill 0.381)
		(layers "F.Cu" "B.Cu")
		(net "ADC128_A0")
	)
	(segment
		(start 354.354638 -40.8051)
		(end 354.320348 -40.77081)
		(width 0.0889)
		(layer "F.Cu")
		(net "TP_USB2_1_DP")
	)
	(segment
		(start 350.364298 -44.168568)
		(end 349.548196 -44.168568)
		(width 0.0889)
		(layer "F.Cu")
		(net "TP_USB2_1_DP")
	)
	(segment
		(start 349.548196 -44.168568)
		(end 349.253556 -43.873928)
		(width 0.0889)
		(layer "F.Cu")
		(net "TP_USB2_1_DP")
	)
	(segment
		(start 349.253556 -43.873928)
		(end 347.882464 -43.873928)
		(width 0.0889)
		(layer "F.Cu")
		(net "TP_USB2_1_DP")
	)
	(segment
		(start 347.651832 -44.104814)
		(end 347.363034 -44.224448)
		(width 0.0889)
		(layer "F.Cu")
		(net "TP_USB2_1_DP")
	)
	(segment
		(start 347.039692 -44.224448)
		(end 346.995242 -44.186094)
		(width 0.0889)
		(layer "F.Cu")
		(net "TP_USB2_1_DP")
	)
	(segment
		(start 347.363034 -44.224448)
		(end 347.039692 -44.224448)
		(width 0.0889)
		(layer "F.Cu")
		(net "TP_USB2_1_DP")
	)
	(segment
		(start 346.995242 -44.186094)
		(end 346.639134 -43.948096)
		(width 0.0889)
		(layer "F.Cu")
		(net "TP_USB2_1_DP")
	)
	(segment
		(start 357.45166 -40.8051)
		(end 354.376736 -40.8051)
		(width 0.13208)
		(layer "F.Cu")
		(net "TP_USB2_1_DP")
	)
	(segment
		(start 347.882464 -43.873928)
		(end 347.651832 -44.104814)
		(width 0.0889)
		(layer "F.Cu")
		(net "TP_USB2_1_DP")
	)
	(segment
		(start 354.376736 -40.8051)
		(end 354.354638 -40.8051)
		(width 0.0889)
		(layer "F.Cu")
		(net "TP_USB2_1_DP")
	)
	(segment
		(start 346.639134 -43.948096)
		(end 346.384626 -43.948096)
		(width 0.0889)
		(layer "F.Cu")
		(net "TP_USB2_1_DP")
	)
	(segment
		(start 354.320348 -40.77081)
		(end 353.762056 -40.77081)
		(width 0.0889)
		(layer "F.Cu")
		(net "TP_USB2_1_DP")
	)
	(segment
		(start 353.762056 -40.77081)
		(end 350.364298 -44.168568)
		(width 0.0889)
		(layer "F.Cu")
		(net "TP_USB2_1_DP")
	)
	(via
		(at 357.45166 -40.8051)
		(size 0.762)
		(drill 0.381)
		(layers "F.Cu" "B.Cu")
		(net "TP_USB2_1_DP")
	)
	(segment
		(start 351.87382 -42.389806)
		(end 351.733612 -42.389806)
		(width 0.0889)
		(layer "F.Cu")
		(net "TP_USB2_1_DN")
	)
	(segment
		(start 352.782124 -41.341294)
		(end 352.782124 -41.481502)
		(width 0.0889)
		(layer "F.Cu")
		(net "TP_USB2_1_DN")
	)
	(segment
		(start 352.51644 -41.606978)
		(end 352.39071 -41.732708)
		(width 0.0889)
		(layer "F.Cu")
		(net "TP_USB2_1_DN")
	)
	(segment
		(start 353.299268 -40.82415)
		(end 353.173538 -40.94988)
		(width 0.0889)
		(layer "F.Cu")
		(net "TP_USB2_1_DN")
	)
	(segment
		(start 349.77959 -43.978322)
		(end 349.62719 -43.978322)
		(width 0.0889)
		(layer "F.Cu")
		(net "TP_USB2_1_DN")
	)
	(segment
		(start 349.878396 -43.879516)
		(end 349.77959 -43.978322)
		(width 0.0889)
		(layer "F.Cu")
		(net "TP_USB2_1_DN")
	)
	(segment
		(start 350.43364 -43.689778)
		(end 350.43364 -43.829986)
		(width 0.0889)
		(layer "F.Cu")
		(net "TP_USB2_1_DN")
	)
	(segment
		(start 350.699578 -43.564048)
		(end 350.55937 -43.564048)
		(width 0.0889)
		(layer "F.Cu")
		(net "TP_USB2_1_DN")
	)
	(segment
		(start 351.607882 -42.655744)
		(end 351.482406 -42.78122)
		(width 0.0889)
		(layer "F.Cu")
		(net "TP_USB2_1_DN")
	)
	(segment
		(start 351.090992 -43.172634)
		(end 350.950784 -43.172634)
		(width 0.0889)
		(layer "F.Cu")
		(net "TP_USB2_1_DN")
	)
	(segment
		(start 351.999296 -42.124122)
		(end 351.999296 -42.26433)
		(width 0.0889)
		(layer "F.Cu")
		(net "TP_USB2_1_DN")
	)
	(segment
		(start 351.999296 -42.26433)
		(end 351.87382 -42.389806)
		(width 0.0889)
		(layer "F.Cu")
		(net "TP_USB2_1_DN")
	)
	(segment
		(start 350.155002 -43.978322)
		(end 350.056196 -43.879516)
		(width 0.0889)
		(layer "F.Cu")
		(net "TP_USB2_1_DN")
	)
	(segment
		(start 352.782124 -41.481502)
		(end 352.656648 -41.606978)
		(width 0.0889)
		(layer "F.Cu")
		(net "TP_USB2_1_DN")
	)
	(segment
		(start 351.216468 -42.90695)
		(end 351.216468 -43.047158)
		(width 0.0889)
		(layer "F.Cu")
		(net "TP_USB2_1_DN")
	)
	(segment
		(start 350.056196 -43.879516)
		(end 349.878396 -43.879516)
		(width 0.0889)
		(layer "F.Cu")
		(net "TP_USB2_1_DN")
	)
	(segment
		(start 351.482406 -42.78122)
		(end 351.342198 -42.78122)
		(width 0.0889)
		(layer "F.Cu")
		(net "TP_USB2_1_DN")
	)
	(segment
		(start 353.439476 -40.82415)
		(end 353.299268 -40.82415)
		(width 0.0889)
		(layer "F.Cu")
		(net "TP_USB2_1_DN")
	)
	(segment
		(start 350.825054 -43.438572)
		(end 350.699578 -43.564048)
		(width 0.0889)
		(layer "F.Cu")
		(net "TP_USB2_1_DN")
	)
	(segment
		(start 351.342198 -42.78122)
		(end 351.216468 -42.90695)
		(width 0.0889)
		(layer "F.Cu")
		(net "TP_USB2_1_DN")
	)
	(segment
		(start 352.656648 -41.606978)
		(end 352.51644 -41.606978)
		(width 0.0889)
		(layer "F.Cu")
		(net "TP_USB2_1_DN")
	)
	(segment
		(start 353.173538 -41.090088)
		(end 353.048062 -41.215564)
		(width 0.0889)
		(layer "F.Cu")
		(net "TP_USB2_1_DN")
	)
	(segment
		(start 354.320094 -40.580564)
		(end 353.683062 -40.580564)
		(width 0.0889)
		(layer "F.Cu")
		(net "TP_USB2_1_DN")
	)
	(segment
		(start 354.376736 -40.54602)
		(end 354.354638 -40.54602)
		(width 0.0889)
		(layer "F.Cu")
		(net "TP_USB2_1_DN")
	)
	(segment
		(start 352.39071 -41.732708)
		(end 352.39071 -41.872916)
		(width 0.0889)
		(layer "F.Cu")
		(net "TP_USB2_1_DN")
	)
	(segment
		(start 353.173538 -40.94988)
		(end 353.173538 -41.090088)
		(width 0.0889)
		(layer "F.Cu")
		(net "TP_USB2_1_DN")
	)
	(segment
		(start 350.285304 -43.978322)
		(end 350.155002 -43.978322)
		(width 0.0889)
		(layer "F.Cu")
		(net "TP_USB2_1_DN")
	)
	(segment
		(start 355.651816 -40.54602)
		(end 354.376736 -40.54602)
		(width 0.13208)
		(layer "F.Cu")
		(net "TP_USB2_1_DN")
	)
	(segment
		(start 350.950784 -43.172634)
		(end 350.825054 -43.298364)
		(width 0.0889)
		(layer "F.Cu")
		(net "TP_USB2_1_DN")
	)
	(segment
		(start 350.825054 -43.298364)
		(end 350.825054 -43.438572)
		(width 0.0889)
		(layer "F.Cu")
		(net "TP_USB2_1_DN")
	)
	(segment
		(start 353.683062 -40.580564)
		(end 353.439476 -40.82415)
		(width 0.0889)
		(layer "F.Cu")
		(net "TP_USB2_1_DN")
	)
	(segment
		(start 352.265234 -41.998392)
		(end 352.125026 -41.998392)
		(width 0.0889)
		(layer "F.Cu")
		(net "TP_USB2_1_DN")
	)
	(segment
		(start 349.33255 -43.683682)
		(end 347.80347 -43.683682)
		(width 0.0889)
		(layer "F.Cu")
		(net "TP_USB2_1_DN")
	)
	(segment
		(start 352.125026 -41.998392)
		(end 351.999296 -42.124122)
		(width 0.0889)
		(layer "F.Cu")
		(net "TP_USB2_1_DN")
	)
	(segment
		(start 352.907854 -41.215564)
		(end 352.782124 -41.341294)
		(width 0.0889)
		(layer "F.Cu")
		(net "TP_USB2_1_DN")
	)
	(segment
		(start 352.39071 -41.872916)
		(end 352.265234 -41.998392)
		(width 0.0889)
		(layer "F.Cu")
		(net "TP_USB2_1_DN")
	)
	(segment
		(start 354.354638 -40.54602)
		(end 354.320094 -40.580564)
		(width 0.0889)
		(layer "F.Cu")
		(net "TP_USB2_1_DN")
	)
	(segment
		(start 349.62719 -43.978322)
		(end 349.33255 -43.683682)
		(width 0.0889)
		(layer "F.Cu")
		(net "TP_USB2_1_DN")
	)
	(segment
		(start 350.55937 -43.564048)
		(end 350.43364 -43.689778)
		(width 0.0889)
		(layer "F.Cu")
		(net "TP_USB2_1_DN")
	)
	(segment
		(start 351.607882 -42.515536)
		(end 351.607882 -42.655744)
		(width 0.0889)
		(layer "F.Cu")
		(net "TP_USB2_1_DN")
	)
	(segment
		(start 353.048062 -41.215564)
		(end 352.907854 -41.215564)
		(width 0.0889)
		(layer "F.Cu")
		(net "TP_USB2_1_DN")
	)
	(segment
		(start 350.43364 -43.829986)
		(end 350.285304 -43.978322)
		(width 0.0889)
		(layer "F.Cu")
		(net "TP_USB2_1_DN")
	)
	(segment
		(start 356.01656 -40.181276)
		(end 355.651816 -40.54602)
		(width 0.13208)
		(layer "F.Cu")
		(net "TP_USB2_1_DN")
	)
	(segment
		(start 351.733612 -42.389806)
		(end 351.607882 -42.515536)
		(width 0.0889)
		(layer "F.Cu")
		(net "TP_USB2_1_DN")
	)
	(segment
		(start 351.216468 -43.047158)
		(end 351.090992 -43.172634)
		(width 0.0889)
		(layer "F.Cu")
		(net "TP_USB2_1_DN")
	)
	(segment
		(start 347.80347 -43.683682)
		(end 347.543882 -43.94327)
		(width 0.0889)
		(layer "F.Cu")
		(net "TP_USB2_1_DN")
	)
	(segment
		(start 347.532198 -43.948096)
		(end 347.214698 -43.948096)
		(width 0.0889)
		(layer "F.Cu")
		(net "TP_USB2_1_DN")
	)
	(segment
		(start 347.543882 -43.94327)
		(end 347.532198 -43.948096)
		(width 0.0889)
		(layer "F.Cu")
		(net "TP_USB2_1_DN")
	)
	(via
		(at 356.01656 -40.181276)
		(size 0.762)
		(drill 0.381)
		(layers "F.Cu" "B.Cu")
		(net "TP_USB2_1_DN")
	)
	(segment
		(start 254.18669 -92.443554)
		(end 254.18669 -92.291408)
		(width 0.12954)
		(layer "F.Cu")
		(net "CK440Q_OE_6")
	)
	(segment
		(start 252.880368 -93.749876)
		(end 253.218188 -93.412056)
		(width 0.0889)
		(layer "F.Cu")
		(net "CK440Q_OE_6")
	)
	(segment
		(start 254.182626 -95.31731)
		(end 253.925832 -95.060516)
		(width 0.0889)
		(layer "F.Cu")
		(net "CK440Q_OE_6")
	)
	(segment
		(start 253.747016 -95.060516)
		(end 252.880368 -94.193868)
		(width 0.0889)
		(layer "F.Cu")
		(net "CK440Q_OE_6")
	)
	(segment
		(start 253.218188 -93.412056)
		(end 254.18669 -92.443554)
		(width 0.12954)
		(layer "F.Cu")
		(net "CK440Q_OE_6")
	)
	(segment
		(start 252.880368 -94.193868)
		(end 252.880368 -93.749876)
		(width 0.0889)
		(layer "F.Cu")
		(net "CK440Q_OE_6")
	)
	(segment
		(start 253.925832 -95.060516)
		(end 253.747016 -95.060516)
		(width 0.0889)
		(layer "F.Cu")
		(net "CK440Q_OE_6")
	)
	(segment
		(start 254.182626 -96.438212)
		(end 254.182626 -95.31731)
		(width 0.0889)
		(layer "F.Cu")
		(net "CK440Q_OE_6")
	)
	(via
		(at 253.218188 -93.412056)
		(size 0.508)
		(drill 0.254)
		(layers "F.Cu" "B.Cu")
		(net "CK440Q_OE_6")
	)
	(segment
		(start 253.85776 -94.520512)
		(end 253.85776 -94.432628)
		(width 0.0889)
		(layer "F.Cu")
		(net "CK440Q_OE_5")
	)
	(segment
		(start 254.682752 -96.438212)
		(end 254.682752 -95.345504)
		(width 0.0889)
		(layer "F.Cu")
		(net "CK440Q_OE_5")
	)
	(segment
		(start 254.682752 -95.345504)
		(end 253.85776 -94.520512)
		(width 0.0889)
		(layer "F.Cu")
		(net "CK440Q_OE_5")
	)
	(via
		(at 253.85776 -94.432628)
		(size 0.508)
		(drill 0.254)
		(layers "F.Cu" "B.Cu")
		(net "CK440Q_OE_5")
	)
	(segment
		(start 254.90805 -95.482918)
		(end 254.90805 -96.738948)
		(width 0.12954)
		(layer "B.Cu")
		(net "CK440Q_OE_5")
	)
	(segment
		(start 253.85776 -94.432628)
		(end 254.90805 -95.482918)
		(width 0.12954)
		(layer "B.Cu")
		(net "CK440Q_OE_5")
	)
	(segment
		(start 256.682748 -95.164656)
		(end 256.188972 -94.67088)
		(width 0.0889)
		(layer "F.Cu")
		(net "CK440Q_OE_4")
	)
	(segment
		(start 256.682748 -96.438212)
		(end 256.682748 -95.164656)
		(width 0.0889)
		(layer "F.Cu")
		(net "CK440Q_OE_4")
	)
	(segment
		(start 256.188972 -93.78188)
		(end 256.510282 -93.46057)
		(width 0.0889)
		(layer "F.Cu")
		(net "CK440Q_OE_4")
	)
	(segment
		(start 256.188972 -94.67088)
		(end 256.188972 -93.78188)
		(width 0.0889)
		(layer "F.Cu")
		(net "CK440Q_OE_4")
	)
	(segment
		(start 256.873502 -93.09735)
		(end 256.510282 -93.46057)
		(width 0.12954)
		(layer "F.Cu")
		(net "CK440Q_OE_4")
	)
	(segment
		(start 256.873502 -92.292424)
		(end 256.873502 -93.09735)
		(width 0.12954)
		(layer "F.Cu")
		(net "CK440Q_OE_4")
	)
	(via
		(at 256.510282 -93.46057)
		(size 0.508)
		(drill 0.254)
		(layers "F.Cu" "B.Cu")
		(net "CK440Q_OE_4")
	)
	(segment
		(start 257.932682 -95.68815)
		(end 257.93192 -95.687388)
		(width 0.12954)
		(layer "F.Cu")
		(net "CK440Q_OE_3")
	)
	(segment
		(start 258.294632 -95.139002)
		(end 258.294632 -93.527372)
		(width 0.12954)
		(layer "F.Cu")
		(net "CK440Q_OE_3")
	)
	(segment
		(start 257.78333 -92.63253)
		(end 257.78333 -92.258388)
		(width 0.12954)
		(layer "F.Cu")
		(net "CK440Q_OE_3")
	)
	(segment
		(start 258.359402 -93.462602)
		(end 258.359402 -93.208602)
		(width 0.12954)
		(layer "F.Cu")
		(net "CK440Q_OE_3")
	)
	(segment
		(start 258.294632 -93.527372)
		(end 258.359402 -93.462602)
		(width 0.12954)
		(layer "F.Cu")
		(net "CK440Q_OE_3")
	)
	(segment
		(start 257.93192 -95.501714)
		(end 258.294632 -95.139002)
		(width 0.12954)
		(layer "F.Cu")
		(net "CK440Q_OE_3")
	)
	(segment
		(start 258.359402 -93.208602)
		(end 257.78333 -92.63253)
		(width 0.12954)
		(layer "F.Cu")
		(net "CK440Q_OE_3")
	)
	(segment
		(start 257.93192 -95.687388)
		(end 257.93192 -95.501714)
		(width 0.12954)
		(layer "F.Cu")
		(net "CK440Q_OE_3")
	)
	(via
		(at 258.359402 -93.462602)
		(size 0.762)
		(drill 0.254)
		(layers "F.Cu" "B.Cu")
		(net "CK440Q_OE_3")
	)
	(segment
		(start 260.593332 -92.897706)
		(end 260.593332 -94.921832)
		(width 0.12954)
		(layer "F.Cu")
		(net "CK440Q_OE_2")
	)
	(segment
		(start 260.593332 -94.921832)
		(end 260.351016 -95.164148)
		(width 0.12954)
		(layer "F.Cu")
		(net "CK440Q_OE_2")
	)
	(segment
		(start 259.822696 -96.18599)
		(end 259.822696 -95.692468)
		(width 0.12954)
		(layer "F.Cu")
		(net "CK440Q_OE_2")
	)
	(segment
		(start 259.695442 -96.313244)
		(end 259.822696 -96.18599)
		(width 0.12954)
		(layer "F.Cu")
		(net "CK440Q_OE_2")
	)
	(segment
		(start 259.822696 -95.692468)
		(end 260.351016 -95.164148)
		(width 0.12954)
		(layer "F.Cu")
		(net "CK440Q_OE_2")
	)
	(segment
		(start 259.557774 -96.313244)
		(end 259.695442 -96.313244)
		(width 0.12954)
		(layer "F.Cu")
		(net "CK440Q_OE_2")
	)
	(via
		(at 260.351016 -95.164148)
		(size 0.508)
		(drill 0.254)
		(layers "F.Cu" "B.Cu")
		(net "CK440Q_OE_2")
	)
	(segment
		(start 259.557774 -96.813116)
		(end 259.702046 -96.813116)
		(width 0.12954)
		(layer "F.Cu")
		(net "CK440Q_OE_1")
	)
	(segment
		(start 259.702046 -96.813116)
		(end 260.330188 -96.184974)
		(width 0.12954)
		(layer "F.Cu")
		(net "CK440Q_OE_1")
	)
	(segment
		(start 261.426706 -94.460822)
		(end 261.600188 -94.28734)
		(width 0.12954)
		(layer "F.Cu")
		(net "CK440Q_OE_1")
	)
	(segment
		(start 261.600188 -94.28734)
		(end 261.600188 -92.898976)
		(width 0.12954)
		(layer "F.Cu")
		(net "CK440Q_OE_1")
	)
	(segment
		(start 260.86562 -95.340678)
		(end 260.86562 -95.021908)
		(width 0.12954)
		(layer "F.Cu")
		(net "CK440Q_OE_1")
	)
	(segment
		(start 260.330188 -96.184974)
		(end 260.330188 -95.87611)
		(width 0.12954)
		(layer "F.Cu")
		(net "CK440Q_OE_1")
	)
	(segment
		(start 260.86562 -95.021908)
		(end 261.426706 -94.460822)
		(width 0.12954)
		(layer "F.Cu")
		(net "CK440Q_OE_1")
	)
	(segment
		(start 260.330188 -95.87611)
		(end 260.86562 -95.340678)
		(width 0.12954)
		(layer "F.Cu")
		(net "CK440Q_OE_1")
	)
	(via
		(at 261.426706 -94.460822)
		(size 0.762)
		(drill 0.381)
		(layers "F.Cu" "B.Cu")
		(net "CK440Q_OE_1")
	)
	(segment
		(start 75.305412 -40.310562)
		(end 75.305412 -39.675562)
		(width 0.381)
		(layer "F.Cu")
		(net "P3V3_OCP_V3_2_R")
	)
	(segment
		(start 86.94039 -53.475636)
		(end 86.944962 -53.480208)
		(width 0.508)
		(layer "F.Cu")
		(net "P3V3_OCP_V3_2_R")
	)
	(segment
		(start 86.33079 -51.730148)
		(end 86.94039 -52.339748)
		(width 0.508)
		(layer "F.Cu")
		(net "P3V3_OCP_V3_2_R")
	)
	(segment
		(start 75.305412 -39.675562)
		(end 74.544428 -39.675562)
		(width 0.2286)
		(layer "F.Cu")
		(net "P3V3_OCP_V3_2_R")
	)
	(segment
		(start 74.438764 -39.569898)
		(end 74.10831 -39.569898)
		(width 0.2286)
		(layer "F.Cu")
		(net "P3V3_OCP_V3_2_R")
	)
	(segment
		(start 79.63662 -53.678836)
		(end 81.585308 -51.730148)
		(width 0.508)
		(layer "F.Cu")
		(net "P3V3_OCP_V3_2_R")
	)
	(segment
		(start 81.585308 -51.730148)
		(end 86.33079 -51.730148)
		(width 0.508)
		(layer "F.Cu")
		(net "P3V3_OCP_V3_2_R")
	)
	(segment
		(start 79.63662 -54.338728)
		(end 79.63662 -53.678836)
		(width 0.508)
		(layer "F.Cu")
		(net "P3V3_OCP_V3_2_R")
	)
	(segment
		(start 86.944962 -53.480208)
		(end 87.935562 -53.480208)
		(width 0.508)
		(layer "F.Cu")
		(net "P3V3_OCP_V3_2_R")
	)
	(segment
		(start 74.544428 -39.675562)
		(end 74.438764 -39.569898)
		(width 0.2286)
		(layer "F.Cu")
		(net "P3V3_OCP_V3_2_R")
	)
	(segment
		(start 86.94039 -52.339748)
		(end 86.94039 -53.475636)
		(width 0.508)
		(layer "F.Cu")
		(net "P3V3_OCP_V3_2_R")
	)
	(via
		(at 80.35798 -55.242968)
		(size 0.508)
		(drill 0.254)
		(layers "F.Cu" "B.Cu")
		(net "P3V3_OCP_V3_2_R")
	)
	(via
		(at 78.71714 -57.953148)
		(size 0.508)
		(drill 0.254)
		(layers "F.Cu" "B.Cu")
		(net "P3V3_OCP_V3_2_R")
	)
	(via
		(at 81.11998 -54.480968)
		(size 0.508)
		(drill 0.254)
		(layers "F.Cu" "B.Cu")
		(net "P3V3_OCP_V3_2_R")
	)
	(via
		(at 78.43266 -50.195988)
		(size 0.508)
		(drill 0.254)
		(layers "F.Cu" "B.Cu")
		(net "P3V3_OCP_V3_2_R")
	)
	(via
		(at 78.14056 -59.601608)
		(size 0.762)
		(drill 0.381)
		(layers "F.Cu" "B.Cu")
		(net "P3V3_OCP_V3_2_R")
	)
	(via
		(at 76.78166 -48.570388)
		(size 0.762)
		(drill 0.381)
		(layers "F.Cu" "B.Cu")
		(net "P3V3_OCP_V3_2_R")
	)
	(via
		(at 81.11998 -55.242968)
		(size 0.508)
		(drill 0.254)
		(layers "F.Cu" "B.Cu")
		(net "P3V3_OCP_V3_2_R")
	)
	(via
		(at 78.71714 -57.191148)
		(size 0.508)
		(drill 0.254)
		(layers "F.Cu" "B.Cu")
		(net "P3V3_OCP_V3_2_R")
	)
	(via
		(at 80.35798 -54.480968)
		(size 0.508)
		(drill 0.254)
		(layers "F.Cu" "B.Cu")
		(net "P3V3_OCP_V3_2_R")
	)
	(via
		(at 78.678024 -46.088046)
		(size 0.508)
		(drill 0.254)
		(layers "F.Cu" "B.Cu")
		(net "P3V3_OCP_V3_2_R")
	)
	(via
		(at 75.305412 -40.310562)
		(size 0.508)
		(drill 0.254)
		(layers "F.Cu" "B.Cu")
		(net "P3V3_OCP_V3_2_R")
	)
	(via
		(at 77.95514 -57.953148)
		(size 0.508)
		(drill 0.254)
		(layers "F.Cu" "B.Cu")
		(net "P3V3_OCP_V3_2_R")
	)
	(via
		(at 78.98638 -49.621948)
		(size 0.508)
		(drill 0.254)
		(layers "F.Cu" "B.Cu")
		(net "P3V3_OCP_V3_2_R")
	)
	(via
		(at 77.95514 -57.191148)
		(size 0.508)
		(drill 0.254)
		(layers "F.Cu" "B.Cu")
		(net "P3V3_OCP_V3_2_R")
	)
	(segment
		(start 78.678024 -46.088046)
		(end 76.471272 -46.088046)
		(width 0.381)
		(layer "In11.Cu")
		(net "P3V3_OCP_V3_2_R")
	)
	(segment
		(start 75.83424 -41.313862)
		(end 75.305412 -40.785034)
		(width 0.381)
		(layer "In11.Cu")
		(net "P3V3_OCP_V3_2_R")
	)
	(segment
		(start 76.471272 -46.088046)
		(end 75.83424 -45.451014)
		(width 0.381)
		(layer "In11.Cu")
		(net "P3V3_OCP_V3_2_R")
	)
	(segment
		(start 75.83424 -45.451014)
		(end 75.83424 -41.313862)
		(width 0.381)
		(layer "In11.Cu")
		(net "P3V3_OCP_V3_2_R")
	)
	(segment
		(start 75.305412 -40.785034)
		(end 75.305412 -40.310562)
		(width 0.381)
		(layer "In11.Cu")
		(net "P3V3_OCP_V3_2_R")
	)
	(segment
		(start 438.51195 -93.671898)
		(end 438.667652 -93.8276)
		(width 0.254)
		(layer "F.Cu")
		(net "P3V3_OCP_SFF_R")
	)
	(segment
		(start 427.93666 -101.539548)
		(end 428.41164 -101.064568)
		(width 0.381)
		(layer "F.Cu")
		(net "P3V3_OCP_SFF_R")
	)
	(segment
		(start 435.623208 -103.368348)
		(end 436.608474 -103.368348)
		(width 0.381)
		(layer "F.Cu")
		(net "P3V3_OCP_SFF_R")
	)
	(segment
		(start 437.15305 -93.671898)
		(end 437.515 -93.671898)
		(width 0.381)
		(layer "F.Cu")
		(net "P3V3_OCP_SFF_R")
	)
	(segment
		(start 435.468776 -102.67188)
		(end 435.621176 -102.82428)
		(width 0.381)
		(layer "F.Cu")
		(net "P3V3_OCP_SFF_R")
	)
	(segment
		(start 427.93666 -103.998268)
		(end 427.93666 -101.539548)
		(width 0.381)
		(layer "F.Cu")
		(net "P3V3_OCP_SFF_R")
	)
	(segment
		(start 436.6768 -94.148148)
		(end 437.15305 -93.671898)
		(width 0.381)
		(layer "F.Cu")
		(net "P3V3_OCP_SFF_R")
	)
	(segment
		(start 436.6768 -94.275148)
		(end 436.6768 -94.148148)
		(width 0.381)
		(layer "F.Cu")
		(net "P3V3_OCP_SFF_R")
	)
	(segment
		(start 428.41164 -101.064568)
		(end 434.94706 -101.064568)
		(width 0.381)
		(layer "F.Cu")
		(net "P3V3_OCP_SFF_R")
	)
	(segment
		(start 437.515 -93.671898)
		(end 438.51195 -93.671898)
		(width 0.381)
		(layer "F.Cu")
		(net "P3V3_OCP_SFF_R")
	)
	(segment
		(start 435.468776 -101.586284)
		(end 435.468776 -102.67188)
		(width 0.381)
		(layer "F.Cu")
		(net "P3V3_OCP_SFF_R")
	)
	(segment
		(start 435.621176 -102.82428)
		(end 435.621176 -103.37038)
		(width 0.381)
		(layer "F.Cu")
		(net "P3V3_OCP_SFF_R")
	)
	(segment
		(start 438.667652 -93.8276)
		(end 439.28792 -93.8276)
		(width 0.254)
		(layer "F.Cu")
		(net "P3V3_OCP_SFF_R")
	)
	(segment
		(start 434.94706 -101.064568)
		(end 435.468776 -101.586284)
		(width 0.381)
		(layer "F.Cu")
		(net "P3V3_OCP_SFF_R")
	)
	(segment
		(start 435.621176 -103.37038)
		(end 435.623208 -103.368348)
		(width 0.381)
		(layer "F.Cu")
		(net "P3V3_OCP_SFF_R")
	)
	(via
		(at 426.72508 -106.713528)
		(size 0.762)
		(drill 0.381)
		(layers "F.Cu" "B.Cu")
		(net "P3V3_OCP_SFF_R")
	)
	(via
		(at 436.6768 -94.275148)
		(size 0.508)
		(drill 0.254)
		(layers "F.Cu" "B.Cu")
		(net "P3V3_OCP_SFF_R")
	)
	(via
		(at 431.34788 -93.891608)
		(size 0.508)
		(drill 0.254)
		(layers "F.Cu" "B.Cu")
		(net "P3V3_OCP_SFF_R")
	)
	(segment
		(start 431.91938 -93.891608)
		(end 431.34788 -93.891608)
		(width 0.381)
		(layer "In2.Cu")
		(net "P3V3_OCP_SFF_R")
	)
	(segment
		(start 436.229252 -93.8276)
		(end 431.983388 -93.8276)
		(width 0.381)
		(layer "In2.Cu")
		(net "P3V3_OCP_SFF_R")
	)
	(segment
		(start 431.983388 -93.8276)
		(end 431.91938 -93.891608)
		(width 0.381)
		(layer "In2.Cu")
		(net "P3V3_OCP_SFF_R")
	)
	(segment
		(start 436.6768 -94.275148)
		(end 436.229252 -93.8276)
		(width 0.381)
		(layer "In2.Cu")
		(net "P3V3_OCP_SFF_R")
	)
	(segment
		(start 70.60946 -54.745128)
		(end 71.05396 -54.300628)
		(width 0.12954)
		(layer "F.Cu")
		(net "P3V3_OCP_MODE_2")
	)
	(segment
		(start 69.521832 -56.09463)
		(end 69.521832 -55.832756)
		(width 0.12954)
		(layer "F.Cu")
		(net "P3V3_OCP_MODE_2")
	)
	(segment
		(start 70.53707 -53.543708)
		(end 70.116446 -53.543708)
		(width 0.12954)
		(layer "F.Cu")
		(net "P3V3_OCP_MODE_2")
	)
	(segment
		(start 70.15226 -54.745128)
		(end 70.60946 -54.745128)
		(width 0.12954)
		(layer "F.Cu")
		(net "P3V3_OCP_MODE_2")
	)
	(segment
		(start 70.56247 -53.543708)
		(end 70.53707 -53.543708)
		(width 0.12954)
		(layer "F.Cu")
		(net "P3V3_OCP_MODE_2")
	)
	(segment
		(start 71.05396 -54.035198)
		(end 70.56247 -53.543708)
		(width 0.12954)
		(layer "F.Cu")
		(net "P3V3_OCP_MODE_2")
	)
	(segment
		(start 71.05396 -54.300628)
		(end 71.05396 -54.035198)
		(width 0.12954)
		(layer "F.Cu")
		(net "P3V3_OCP_MODE_2")
	)
	(segment
		(start 70.111366 -53.548788)
		(end 69.56933 -53.548788)
		(width 0.12954)
		(layer "F.Cu")
		(net "P3V3_OCP_MODE_2")
	)
	(segment
		(start 70.15226 -55.202328)
		(end 70.15226 -54.745128)
		(width 0.12954)
		(layer "F.Cu")
		(net "P3V3_OCP_MODE_2")
	)
	(segment
		(start 70.116446 -53.543708)
		(end 70.111366 -53.548788)
		(width 0.12954)
		(layer "F.Cu")
		(net "P3V3_OCP_MODE_2")
	)
	(segment
		(start 69.521832 -55.832756)
		(end 70.15226 -55.202328)
		(width 0.12954)
		(layer "F.Cu")
		(net "P3V3_OCP_MODE_2")
	)
	(via
		(at 70.15226 -54.745128)
		(size 0.762)
		(drill 0.381)
		(layers "F.Cu" "B.Cu")
		(net "P3V3_OCP_MODE_2")
	)
	(segment
		(start 422.55694 -102.413308)
		(end 422.04894 -102.921308)
		(width 0.12954)
		(layer "F.Cu")
		(net "P3V3_OCP_MODE_1")
	)
	(segment
		(start 422.04894 -102.921308)
		(end 421.024812 -103.945436)
		(width 0.12954)
		(layer "F.Cu")
		(net "P3V3_OCP_MODE_1")
	)
	(segment
		(start 421.54094 -101.670358)
		(end 422.55694 -101.670358)
		(width 0.12954)
		(layer "F.Cu")
		(net "P3V3_OCP_MODE_1")
	)
	(segment
		(start 422.55694 -101.670358)
		(end 422.55694 -102.413308)
		(width 0.12954)
		(layer "F.Cu")
		(net "P3V3_OCP_MODE_1")
	)
	(segment
		(start 421.024812 -103.945436)
		(end 421.024812 -104.20731)
		(width 0.12954)
		(layer "F.Cu")
		(net "P3V3_OCP_MODE_1")
	)
	(via
		(at 422.04894 -102.921308)
		(size 0.762)
		(drill 0.381)
		(layers "F.Cu" "B.Cu")
		(net "P3V3_OCP_MODE_1")
	)
	(segment
		(start 419.76294 -101.670358)
		(end 419.76294 -102.362508)
		(width 0.12954)
		(layer "F.Cu")
		(net "P3V3_OCP_ILIMIT_1")
	)
	(segment
		(start 419.76294 -102.362508)
		(end 420.27094 -102.870508)
		(width 0.12954)
		(layer "F.Cu")
		(net "P3V3_OCP_ILIMIT_1")
	)
	(segment
		(start 420.27094 -102.870508)
		(end 420.52494 -103.124508)
		(width 0.12954)
		(layer "F.Cu")
		(net "P3V3_OCP_ILIMIT_1")
	)
	(segment
		(start 420.52494 -103.124508)
		(end 420.52494 -104.20731)
		(width 0.12954)
		(layer "F.Cu")
		(net "P3V3_OCP_ILIMIT_1")
	)
	(via
		(at 420.27094 -102.870508)
		(size 0.762)
		(drill 0.381)
		(layers "F.Cu" "B.Cu")
		(net "P3V3_OCP_ILIMIT_1")
	)
	(segment
		(start 84.08416 -54.39918)
		(end 85.23605 -54.39918)
		(width 0.12954)
		(layer "F.Cu")
		(net "P3V3_OCP_GATE_2")
	)
	(segment
		(start 85.919818 -54.280308)
		(end 85.92439 -54.275736)
		(width 0.12954)
		(layer "F.Cu")
		(net "P3V3_OCP_GATE_2")
	)
	(segment
		(start 86.94039 -54.275736)
		(end 86.944962 -54.280308)
		(width 0.12954)
		(layer "F.Cu")
		(net "P3V3_OCP_GATE_2")
	)
	(segment
		(start 85.92439 -54.275736)
		(end 86.94039 -54.275736)
		(width 0.12954)
		(layer "F.Cu")
		(net "P3V3_OCP_GATE_2")
	)
	(segment
		(start 85.800946 -54.39918)
		(end 85.919818 -54.280308)
		(width 0.12954)
		(layer "F.Cu")
		(net "P3V3_OCP_GATE_2")
	)
	(segment
		(start 85.23605 -54.39918)
		(end 85.800946 -54.39918)
		(width 0.12954)
		(layer "F.Cu")
		(net "P3V3_OCP_GATE_2")
	)
	(segment
		(start 86.944962 -54.280308)
		(end 87.935562 -54.280308)
		(width 0.12954)
		(layer "F.Cu")
		(net "P3V3_OCP_GATE_2")
	)
	(segment
		(start 84.050632 -54.432708)
		(end 84.08416 -54.39918)
		(width 0.12954)
		(layer "F.Cu")
		(net "P3V3_OCP_GATE_2")
	)
	(via
		(at 85.23605 -54.39918)
		(size 0.508)
		(drill 0.254)
		(layers "F.Cu" "B.Cu")
		(net "P3V3_OCP_GATE_2")
	)
	(segment
		(start 421.94734 -107.620308)
		(end 421.024812 -106.69778)
		(width 0.12954)
		(layer "F.Cu")
		(net "P3V3_OCP_GATE_1")
	)
	(segment
		(start 421.94734 -108.845858)
		(end 421.94734 -107.620308)
		(width 0.12954)
		(layer "F.Cu")
		(net "P3V3_OCP_GATE_1")
	)
	(segment
		(start 421.92194 -108.871258)
		(end 421.94734 -108.845858)
		(width 0.12954)
		(layer "F.Cu")
		(net "P3V3_OCP_GATE_1")
	)
	(segment
		(start 421.024812 -106.69778)
		(end 421.024812 -106.207306)
		(width 0.12954)
		(layer "F.Cu")
		(net "P3V3_OCP_GATE_1")
	)
	(via
		(at 421.94734 -107.620308)
		(size 0.762)
		(drill 0.381)
		(layers "F.Cu" "B.Cu")
		(net "P3V3_OCP_GATE_1")
	)
	(segment
		(start 69.02196 -58.094626)
		(end 69.02196 -58.491882)
		(width 0.12954)
		(layer "F.Cu")
		(net "P3V3_OCP_EN_2")
	)
	(segment
		(start 68.51396 -59.507628)
		(end 68.51396 -60.631578)
		(width 0.12954)
		(layer "F.Cu")
		(net "P3V3_OCP_EN_2")
	)
	(segment
		(start 69.02196 -58.491882)
		(end 68.51396 -58.999882)
		(width 0.12954)
		(layer "F.Cu")
		(net "P3V3_OCP_EN_2")
	)
	(segment
		(start 68.51396 -58.999882)
		(end 68.51396 -59.507628)
		(width 0.12954)
		(layer "F.Cu")
		(net "P3V3_OCP_EN_2")
	)
	(segment
		(start 68.51396 -60.631578)
		(end 68.64096 -60.758578)
		(width 0.12954)
		(layer "F.Cu")
		(net "P3V3_OCP_EN_2")
	)
	(via
		(at 68.51396 -59.507628)
		(size 0.762)
		(drill 0.381)
		(layers "F.Cu" "B.Cu")
		(net "P3V3_OCP_EN_2")
	)
	(segment
		(start 68.17233 -29.29001)
		(end 68.17233 -30.555184)
		(width 0.12954)
		(layer "F.Cu")
		(net "P12V_OCP_TIMER_2")
	)
	(segment
		(start 69.036438 -31.419292)
		(end 69.036438 -31.487872)
		(width 0.12954)
		(layer "F.Cu")
		(net "P12V_OCP_TIMER_2")
	)
	(segment
		(start 68.17233 -30.555184)
		(end 68.374514 -30.757368)
		(width 0.12954)
		(layer "F.Cu")
		(net "P12V_OCP_TIMER_2")
	)
	(segment
		(start 68.374514 -30.757368)
		(end 69.036438 -31.419292)
		(width 0.12954)
		(layer "F.Cu")
		(net "P12V_OCP_TIMER_2")
	)
	(via
		(at 68.374514 -30.757368)
		(size 0.508)
		(drill 0.254)
		(layers "F.Cu" "B.Cu")
		(net "P12V_OCP_TIMER_2")
	)
	(segment
		(start 443.23254 -31.229808)
		(end 443.717172 -31.71444)
		(width 0.12954)
		(layer "F.Cu")
		(net "P12V_OCP_TIMER_1")
	)
	(segment
		(start 443.717172 -31.71444)
		(end 443.717172 -31.773368)
		(width 0.12954)
		(layer "F.Cu")
		(net "P12V_OCP_TIMER_1")
	)
	(segment
		(start 442.853064 -30.850332)
		(end 443.23254 -31.229808)
		(width 0.12954)
		(layer "F.Cu")
		(net "P12V_OCP_TIMER_1")
	)
	(segment
		(start 442.853064 -29.575506)
		(end 442.853064 -30.850332)
		(width 0.12954)
		(layer "F.Cu")
		(net "P12V_OCP_TIMER_1")
	)
	(via
		(at 443.23254 -31.229808)
		(size 0.508)
		(drill 0.254)
		(layers "F.Cu" "B.Cu")
		(net "P12V_OCP_TIMER_1")
	)
	(segment
		(start 66.369438 -31.444184)
		(end 66.369438 -31.487872)
		(width 0.12954)
		(layer "F.Cu")
		(net "P12V_OCP_SS_2")
	)
	(segment
		(start 67.099434 -30.714188)
		(end 66.9417 -30.714188)
		(width 0.12954)
		(layer "F.Cu")
		(net "P12V_OCP_SS_2")
	)
	(segment
		(start 67.172586 -30.641036)
		(end 67.099434 -30.714188)
		(width 0.12954)
		(layer "F.Cu")
		(net "P12V_OCP_SS_2")
	)
	(segment
		(start 66.9417 -30.871922)
		(end 66.369438 -31.444184)
		(width 0.12954)
		(layer "F.Cu")
		(net "P12V_OCP_SS_2")
	)
	(segment
		(start 66.9417 -30.714188)
		(end 66.9417 -30.871922)
		(width 0.12954)
		(layer "F.Cu")
		(net "P12V_OCP_SS_2")
	)
	(segment
		(start 67.172586 -29.29001)
		(end 67.172586 -30.641036)
		(width 0.12954)
		(layer "F.Cu")
		(net "P12V_OCP_SS_2")
	)
	(via
		(at 66.9417 -30.714188)
		(size 0.508)
		(drill 0.254)
		(layers "F.Cu" "B.Cu")
		(net "P12V_OCP_SS_2")
	)
	(segment
		(start 441.85332 -30.671008)
		(end 441.88888 -30.706568)
		(width 0.12954)
		(layer "F.Cu")
		(net "P12V_OCP_SS_1")
	)
	(segment
		(start 441.85332 -29.575506)
		(end 441.85332 -30.671008)
		(width 0.12954)
		(layer "F.Cu")
		(net "P12V_OCP_SS_1")
	)
	(segment
		(start 441.88888 -30.706568)
		(end 441.85332 -30.742128)
		(width 0.12954)
		(layer "F.Cu")
		(net "P12V_OCP_SS_1")
	)
	(segment
		(start 441.85332 -30.97022)
		(end 441.050172 -31.773368)
		(width 0.12954)
		(layer "F.Cu")
		(net "P12V_OCP_SS_1")
	)
	(segment
		(start 441.85332 -30.742128)
		(end 441.85332 -30.97022)
		(width 0.12954)
		(layer "F.Cu")
		(net "P12V_OCP_SS_1")
	)
	(via
		(at 441.88888 -30.706568)
		(size 0.508)
		(drill 0.254)
		(layers "F.Cu" "B.Cu")
		(net "P12V_OCP_SS_1")
	)
	(segment
		(start 61.845698 -27.39009)
		(end 60.434982 -27.39009)
		(width 0.12954)
		(layer "F.Cu")
		(net "P12V_OCP_OV_FB_2")
	)
	(segment
		(start 61.845698 -27.39009)
		(end 62.861698 -27.39009)
		(width 0.12954)
		(layer "F.Cu")
		(net "P12V_OCP_OV_FB_2")
	)
	(segment
		(start 62.861698 -27.39009)
		(end 63.877698 -27.39009)
		(width 0.12954)
		(layer "F.Cu")
		(net "P12V_OCP_OV_FB_2")
	)
	(segment
		(start 65.272412 -27.39009)
		(end 63.877698 -27.39009)
		(width 0.12954)
		(layer "F.Cu")
		(net "P12V_OCP_OV_FB_2")
	)
	(via
		(at 60.434982 -27.39009)
		(size 0.762)
		(drill 0.381)
		(layers "F.Cu" "B.Cu")
		(net "P12V_OCP_OV_FB_2")
	)
	(segment
		(start 436.0164 -28.859988)
		(end 436.0164 -28.185618)
		(width 0.12954)
		(layer "F.Cu")
		(net "P12V_OCP_OV_FB_1")
	)
	(segment
		(start 436.0164 -28.185618)
		(end 436.526432 -27.675586)
		(width 0.12954)
		(layer "F.Cu")
		(net "P12V_OCP_OV_FB_1")
	)
	(segment
		(start 438.558432 -27.675586)
		(end 437.542432 -27.675586)
		(width 0.12954)
		(layer "F.Cu")
		(net "P12V_OCP_OV_FB_1")
	)
	(segment
		(start 439.953146 -27.675586)
		(end 438.558432 -27.675586)
		(width 0.12954)
		(layer "F.Cu")
		(net "P12V_OCP_OV_FB_1")
	)
	(segment
		(start 436.526432 -27.675586)
		(end 437.542432 -27.675586)
		(width 0.12954)
		(layer "F.Cu")
		(net "P12V_OCP_OV_FB_1")
	)
	(via
		(at 436.0164 -28.859988)
		(size 0.762)
		(drill 0.381)
		(layers "F.Cu" "B.Cu")
		(net "P12V_OCP_OV_FB_1")
	)
	(segment
		(start 67.672458 -31.74365)
		(end 67.54114 -31.874968)
		(width 0.12954)
		(layer "F.Cu")
		(net "P12V_OCP_ISET_2")
	)
	(segment
		(start 67.672458 -29.29001)
		(end 67.672458 -31.74365)
		(width 0.12954)
		(layer "F.Cu")
		(net "P12V_OCP_ISET_2")
	)
	(segment
		(start 67.54114 -31.976822)
		(end 67.94119 -32.376872)
		(width 0.12954)
		(layer "F.Cu")
		(net "P12V_OCP_ISET_2")
	)
	(segment
		(start 67.54114 -31.874968)
		(end 67.54114 -31.976822)
		(width 0.12954)
		(layer "F.Cu")
		(net "P12V_OCP_ISET_2")
	)
	(segment
		(start 67.94119 -32.376872)
		(end 68.147438 -32.376872)
		(width 0.12954)
		(layer "F.Cu")
		(net "P12V_OCP_ISET_2")
	)
	(via
		(at 67.54114 -31.874968)
		(size 0.508)
		(drill 0.254)
		(layers "F.Cu" "B.Cu")
		(net "P12V_OCP_ISET_2")
	)
	(segment
		(start 442.40196 -30.155642)
		(end 442.40196 -31.389828)
		(width 0.12954)
		(layer "F.Cu")
		(net "P12V_OCP_ISET_1")
	)
	(segment
		(start 442.40196 -31.389828)
		(end 442.439044 -31.426912)
		(width 0.12954)
		(layer "F.Cu")
		(net "P12V_OCP_ISET_1")
	)
	(segment
		(start 442.353192 -30.106874)
		(end 442.40196 -30.155642)
		(width 0.12954)
		(layer "F.Cu")
		(net "P12V_OCP_ISET_1")
	)
	(segment
		(start 442.439044 -31.426912)
		(end 442.828172 -31.81604)
		(width 0.12954)
		(layer "F.Cu")
		(net "P12V_OCP_ISET_1")
	)
	(segment
		(start 442.828172 -31.81604)
		(end 442.828172 -32.662368)
		(width 0.12954)
		(layer "F.Cu")
		(net "P12V_OCP_ISET_1")
	)
	(segment
		(start 442.353192 -29.575506)
		(end 442.353192 -30.106874)
		(width 0.12954)
		(layer "F.Cu")
		(net "P12V_OCP_ISET_1")
	)
	(via
		(at 442.439044 -31.426912)
		(size 0.762)
		(drill 0.381)
		(layers "F.Cu" "B.Cu")
		(net "P12V_OCP_ISET_1")
	)
	(via
		(at 64.49314 -29.393388)
		(size 0.508)
		(drill 0.254)
		(layers "F.Cu" "B.Cu")
		(net "P12V_OCP_FLTB_2")
	)
	(via
		(at 439.18632 -30.005528)
		(size 0.508)
		(drill 0.254)
		(layers "F.Cu" "B.Cu")
		(net "P12V_OCP_FLTB_1")
	)
	(segment
		(start 64.28486 -22.189948)
		(end 64.330834 -22.235922)
		(width 0.12954)
		(layer "F.Cu")
		(net "P12V_OCP_AVIN_PD_2")
	)
	(segment
		(start 64.330834 -22.235922)
		(end 65.461388 -22.235922)
		(width 0.12954)
		(layer "F.Cu")
		(net "P12V_OCP_AVIN_PD_2")
	)
	(via
		(at 64.28486 -22.189948)
		(size 0.762)
		(drill 0.381)
		(layers "F.Cu" "B.Cu")
		(net "P12V_OCP_AVIN_PD_2")
	)
	(via
		(at 438.99074 -22.464268)
		(size 0.762)
		(drill 0.381)
		(layers "F.Cu" "B.Cu")
		(net "P12V_OCP_AVIN_PD_1")
	)
	(segment
		(start 207.772508 -35.522154)
		(end 206.890874 -35.522154)
		(width 0.12954)
		(layer "F.Cu")
		(net "VSENSE_P12V_INA230_5_INP")
	)
	(via
		(at 206.890874 -35.522154)
		(size 0.508)
		(drill 0.254)
		(layers "F.Cu" "B.Cu")
		(net "VSENSE_P12V_INA230_5_INP")
	)
	(segment
		(start 206.890874 -35.522154)
		(end 206.814674 -35.522154)
		(width 0.12954)
		(layer "B.Cu")
		(net "VSENSE_P12V_INA230_5_INP")
	)
	(segment
		(start 205.29423 -36.363148)
		(end 205.28788 -36.356798)
		(width 0.12954)
		(layer "B.Cu")
		(net "VSENSE_P12V_INA230_5_INP")
	)
	(segment
		(start 205.00213 -36.642548)
		(end 205.28788 -36.356798)
		(width 0.12954)
		(layer "B.Cu")
		(net "VSENSE_P12V_INA230_5_INP")
	)
	(segment
		(start 205.97368 -36.363148)
		(end 205.29423 -36.363148)
		(width 0.12954)
		(layer "B.Cu")
		(net "VSENSE_P12V_INA230_5_INP")
	)
	(segment
		(start 206.814674 -35.522154)
		(end 205.97368 -36.363148)
		(width 0.12954)
		(layer "B.Cu")
		(net "VSENSE_P12V_INA230_5_INP")
	)
	(segment
		(start 203.73213 -36.642548)
		(end 205.00213 -36.642548)
		(width 0.12954)
		(layer "B.Cu")
		(net "VSENSE_P12V_INA230_5_INP")
	)
	(segment
		(start 206.90078 -37.071808)
		(end 207.800448 -36.17214)
		(width 0.12954)
		(layer "F.Cu")
		(net "VSENSE_P12V_INA230_5_INN")
	)
	(segment
		(start 207.800448 -36.17214)
		(end 208.422494 -36.17214)
		(width 0.12954)
		(layer "F.Cu")
		(net "VSENSE_P12V_INA230_5_INN")
	)
	(via
		(at 206.90078 -37.071808)
		(size 0.508)
		(drill 0.254)
		(layers "F.Cu" "B.Cu")
		(net "VSENSE_P12V_INA230_5_INN")
	)
	(segment
		(start 207.21828 -34.889948)
		(end 205.95463 -34.889948)
		(width 0.12954)
		(layer "B.Cu")
		(net "VSENSE_P12V_INA230_5_INN")
	)
	(segment
		(start 207.54848 -36.424108)
		(end 207.54848 -35.220148)
		(width 0.12954)
		(layer "B.Cu")
		(net "VSENSE_P12V_INA230_5_INN")
	)
	(segment
		(start 206.90078 -37.071808)
		(end 207.54848 -36.424108)
		(width 0.12954)
		(layer "B.Cu")
		(net "VSENSE_P12V_INA230_5_INN")
	)
	(segment
		(start 207.54848 -35.220148)
		(end 207.21828 -34.889948)
		(width 0.12954)
		(layer "B.Cu")
		(net "VSENSE_P12V_INA230_5_INN")
	)
	(segment
		(start 205.95463 -34.889948)
		(end 205.28788 -35.556698)
		(width 0.12954)
		(layer "B.Cu")
		(net "VSENSE_P12V_INA230_5_INN")
	)
	(segment
		(start 205.10373 -35.372548)
		(end 205.28788 -35.556698)
		(width 0.12954)
		(layer "B.Cu")
		(net "VSENSE_P12V_INA230_5_INN")
	)
	(segment
		(start 203.73213 -35.372548)
		(end 205.10373 -35.372548)
		(width 0.12954)
		(layer "B.Cu")
		(net "VSENSE_P12V_INA230_5_INN")
	)
	(segment
		(start 154.68473 -54.929278)
		(end 154.32913 -54.929278)
		(width 0.254)
		(layer "F.Cu")
		(net "VSENSE_P12V_INA230_4_INP")
	)
	(segment
		(start 157.096968 -53.759354)
		(end 155.927044 -54.929278)
		(width 0.254)
		(layer "F.Cu")
		(net "VSENSE_P12V_INA230_4_INP")
	)
	(segment
		(start 158.867094 -53.867304)
		(end 158.550356 -53.867304)
		(width 0.254)
		(layer "F.Cu")
		(net "VSENSE_P12V_INA230_4_INP")
	)
	(segment
		(start 154.32913 -54.929278)
		(end 153.443686 -54.043834)
		(width 0.254)
		(layer "F.Cu")
		(net "VSENSE_P12V_INA230_4_INP")
	)
	(segment
		(start 158.550356 -53.867304)
		(end 158.37916 -53.696108)
		(width 0.254)
		(layer "F.Cu")
		(net "VSENSE_P12V_INA230_4_INP")
	)
	(segment
		(start 158.37916 -53.696108)
		(end 157.93339 -53.696108)
		(width 0.254)
		(layer "F.Cu")
		(net "VSENSE_P12V_INA230_4_INP")
	)
	(segment
		(start 157.870144 -53.759354)
		(end 157.096968 -53.759354)
		(width 0.254)
		(layer "F.Cu")
		(net "VSENSE_P12V_INA230_4_INP")
	)
	(segment
		(start 155.927044 -54.929278)
		(end 154.68473 -54.929278)
		(width 0.254)
		(layer "F.Cu")
		(net "VSENSE_P12V_INA230_4_INP")
	)
	(segment
		(start 153.443686 -54.043834)
		(end 153.443686 -53.71846)
		(width 0.254)
		(layer "F.Cu")
		(net "VSENSE_P12V_INA230_4_INP")
	)
	(segment
		(start 157.93339 -53.696108)
		(end 157.870144 -53.759354)
		(width 0.254)
		(layer "F.Cu")
		(net "VSENSE_P12V_INA230_4_INP")
	)
	(via
		(at 154.68473 -54.929278)
		(size 0.762)
		(drill 0.381)
		(layers "F.Cu" "B.Cu")
		(net "VSENSE_P12V_INA230_4_INP")
	)
	(segment
		(start 158.867094 -52.851304)
		(end 157.978094 -52.851304)
		(width 0.254)
		(layer "F.Cu")
		(net "VSENSE_P12V_INA230_4_INN")
	)
	(segment
		(start 155.234386 -54.031134)
		(end 155.582874 -54.031134)
		(width 0.254)
		(layer "F.Cu")
		(net "VSENSE_P12V_INA230_4_INN")
	)
	(segment
		(start 157.353 -52.959254)
		(end 157.870144 -52.959254)
		(width 0.254)
		(layer "F.Cu")
		(net "VSENSE_P12V_INA230_4_INN")
	)
	(segment
		(start 157.978094 -52.851304)
		(end 157.870144 -52.959254)
		(width 0.254)
		(layer "F.Cu")
		(net "VSENSE_P12V_INA230_4_INN")
	)
	(segment
		(start 154.093672 -53.068474)
		(end 154.271726 -53.068474)
		(width 0.254)
		(layer "F.Cu")
		(net "VSENSE_P12V_INA230_4_INN")
	)
	(segment
		(start 154.271726 -53.068474)
		(end 155.234386 -54.031134)
		(width 0.254)
		(layer "F.Cu")
		(net "VSENSE_P12V_INA230_4_INN")
	)
	(segment
		(start 155.582874 -54.031134)
		(end 156.28112 -54.031134)
		(width 0.254)
		(layer "F.Cu")
		(net "VSENSE_P12V_INA230_4_INN")
	)
	(segment
		(start 156.28112 -54.031134)
		(end 157.353 -52.959254)
		(width 0.254)
		(layer "F.Cu")
		(net "VSENSE_P12V_INA230_4_INN")
	)
	(via
		(at 155.582874 -54.031134)
		(size 0.762)
		(drill 0.381)
		(layers "F.Cu" "B.Cu")
		(net "VSENSE_P12V_INA230_4_INN")
	)
	(segment
		(start 73.83399 -42.023538)
		(end 73.458324 -41.647872)
		(width 0.254)
		(layer "F.Cu")
		(net "VSENSE_P12V_INA230_3_INP")
	)
	(segment
		(start 73.458324 -41.647872)
		(end 73.458324 -40.72001)
		(width 0.254)
		(layer "F.Cu")
		(net "VSENSE_P12V_INA230_3_INP")
	)
	(via
		(at 73.83399 -42.023538)
		(size 0.508)
		(drill 0.254)
		(layers "F.Cu" "B.Cu")
		(net "VSENSE_P12V_INA230_3_INP")
	)
	(segment
		(start 74.27849 -42.468038)
		(end 74.27849 -43.413426)
		(width 0.254)
		(layer "B.Cu")
		(net "VSENSE_P12V_INA230_3_INP")
	)
	(segment
		(start 75.536044 -45.727366)
		(end 75.745594 -45.936916)
		(width 0.254)
		(layer "B.Cu")
		(net "VSENSE_P12V_INA230_3_INP")
	)
	(segment
		(start 74.68616 -43.821096)
		(end 74.68616 -45.339762)
		(width 0.254)
		(layer "B.Cu")
		(net "VSENSE_P12V_INA230_3_INP")
	)
	(segment
		(start 75.073764 -45.727366)
		(end 75.536044 -45.727366)
		(width 0.254)
		(layer "B.Cu")
		(net "VSENSE_P12V_INA230_3_INP")
	)
	(segment
		(start 76.742544 -46.044866)
		(end 76.634594 -45.936916)
		(width 0.254)
		(layer "B.Cu")
		(net "VSENSE_P12V_INA230_3_INP")
	)
	(segment
		(start 74.68616 -45.339762)
		(end 75.073764 -45.727366)
		(width 0.254)
		(layer "B.Cu")
		(net "VSENSE_P12V_INA230_3_INP")
	)
	(segment
		(start 73.83399 -42.023538)
		(end 74.27849 -42.468038)
		(width 0.254)
		(layer "B.Cu")
		(net "VSENSE_P12V_INA230_3_INP")
	)
	(segment
		(start 76.634594 -45.936916)
		(end 75.745594 -45.936916)
		(width 0.254)
		(layer "B.Cu")
		(net "VSENSE_P12V_INA230_3_INP")
	)
	(segment
		(start 74.27849 -43.413426)
		(end 74.68616 -43.821096)
		(width 0.254)
		(layer "B.Cu")
		(net "VSENSE_P12V_INA230_3_INP")
	)
	(segment
		(start 74.5744 -40.298116)
		(end 74.346308 -40.070024)
		(width 0.254)
		(layer "F.Cu")
		(net "VSENSE_P12V_INA230_3_INN")
	)
	(segment
		(start 74.346308 -40.070024)
		(end 74.10831 -40.070024)
		(width 0.254)
		(layer "F.Cu")
		(net "VSENSE_P12V_INA230_3_INN")
	)
	(segment
		(start 74.5744 -41.493948)
		(end 74.5744 -40.298116)
		(width 0.254)
		(layer "F.Cu")
		(net "VSENSE_P12V_INA230_3_INN")
	)
	(segment
		(start 75.10399 -42.023538)
		(end 74.5744 -41.493948)
		(width 0.254)
		(layer "F.Cu")
		(net "VSENSE_P12V_INA230_3_INN")
	)
	(via
		(at 75.10399 -42.023538)
		(size 0.508)
		(drill 0.254)
		(layers "F.Cu" "B.Cu")
		(net "VSENSE_P12V_INA230_3_INN")
	)
	(segment
		(start 75.06716 -43.663108)
		(end 75.06716 -45.181774)
		(width 0.254)
		(layer "B.Cu")
		(net "VSENSE_P12V_INA230_3_INN")
	)
	(segment
		(start 75.231752 -45.346366)
		(end 75.536044 -45.346366)
		(width 0.254)
		(layer "B.Cu")
		(net "VSENSE_P12V_INA230_3_INN")
	)
	(segment
		(start 75.536044 -45.346366)
		(end 75.745594 -45.136816)
		(width 0.254)
		(layer "B.Cu")
		(net "VSENSE_P12V_INA230_3_INN")
	)
	(segment
		(start 75.10399 -42.023538)
		(end 74.65949 -42.468038)
		(width 0.254)
		(layer "B.Cu")
		(net "VSENSE_P12V_INA230_3_INN")
	)
	(segment
		(start 74.65949 -43.255438)
		(end 75.06716 -43.663108)
		(width 0.254)
		(layer "B.Cu")
		(net "VSENSE_P12V_INA230_3_INN")
	)
	(segment
		(start 76.634594 -45.136816)
		(end 75.745594 -45.136816)
		(width 0.254)
		(layer "B.Cu")
		(net "VSENSE_P12V_INA230_3_INN")
	)
	(segment
		(start 75.06716 -45.181774)
		(end 75.231752 -45.346366)
		(width 0.254)
		(layer "B.Cu")
		(net "VSENSE_P12V_INA230_3_INN")
	)
	(segment
		(start 74.65949 -42.468038)
		(end 74.65949 -43.255438)
		(width 0.254)
		(layer "B.Cu")
		(net "VSENSE_P12V_INA230_3_INN")
	)
	(segment
		(start 76.742544 -45.028866)
		(end 76.634594 -45.136816)
		(width 0.254)
		(layer "B.Cu")
		(net "VSENSE_P12V_INA230_3_INN")
	)
	(segment
		(start 215.7984 -57.247282)
		(end 215.7984 -57.950608)
		(width 0.254)
		(layer "F.Cu")
		(net "VSENSE_P3V3_INA230_2_INP")
	)
	(segment
		(start 216.009728 -57.035954)
		(end 215.7984 -57.247282)
		(width 0.254)
		(layer "F.Cu")
		(net "VSENSE_P3V3_INA230_2_INP")
	)
	(segment
		(start 219.457778 -57.518808)
		(end 218.411806 -57.518808)
		(width 0.254)
		(layer "F.Cu")
		(net "VSENSE_P3V3_INA230_2_INP")
	)
	(segment
		(start 219.790772 -57.851802)
		(end 219.457778 -57.518808)
		(width 0.254)
		(layer "F.Cu")
		(net "VSENSE_P3V3_INA230_2_INP")
	)
	(segment
		(start 215.7984 -57.950608)
		(end 215.949276 -57.799732)
		(width 0.254)
		(layer "F.Cu")
		(net "VSENSE_P3V3_INA230_2_INP")
	)
	(segment
		(start 218.411806 -57.518808)
		(end 218.130882 -57.799732)
		(width 0.254)
		(layer "F.Cu")
		(net "VSENSE_P3V3_INA230_2_INP")
	)
	(segment
		(start 216.009728 -55.855362)
		(end 216.009728 -57.035954)
		(width 0.254)
		(layer "F.Cu")
		(net "VSENSE_P3V3_INA230_2_INP")
	)
	(segment
		(start 215.949276 -57.799732)
		(end 218.130882 -57.799732)
		(width 0.254)
		(layer "F.Cu")
		(net "VSENSE_P3V3_INA230_2_INP")
	)
	(via
		(at 215.7984 -57.950608)
		(size 0.762)
		(drill 0.381)
		(layers "F.Cu" "B.Cu")
		(net "VSENSE_P3V3_INA230_2_INP")
	)
	(segment
		(start 216.875868 -57.150508)
		(end 217.980006 -57.150508)
		(width 0.254)
		(layer "F.Cu")
		(net "VSENSE_P3V3_INA230_2_INN")
	)
	(segment
		(start 217.980006 -57.150508)
		(end 218.130882 -56.999632)
		(width 0.254)
		(layer "F.Cu")
		(net "VSENSE_P3V3_INA230_2_INN")
	)
	(segment
		(start 219.790772 -56.835802)
		(end 219.488766 -57.137808)
		(width 0.254)
		(layer "F.Cu")
		(net "VSENSE_P3V3_INA230_2_INN")
	)
	(segment
		(start 219.488766 -57.137808)
		(end 218.269058 -57.137808)
		(width 0.254)
		(layer "F.Cu")
		(net "VSENSE_P3V3_INA230_2_INN")
	)
	(segment
		(start 216.659714 -55.205376)
		(end 216.659714 -56.934354)
		(width 0.254)
		(layer "F.Cu")
		(net "VSENSE_P3V3_INA230_2_INN")
	)
	(segment
		(start 216.659714 -56.934354)
		(end 216.875868 -57.150508)
		(width 0.254)
		(layer "F.Cu")
		(net "VSENSE_P3V3_INA230_2_INN")
	)
	(segment
		(start 218.269058 -57.137808)
		(end 218.130882 -56.999632)
		(width 0.254)
		(layer "F.Cu")
		(net "VSENSE_P3V3_INA230_2_INN")
	)
	(via
		(at 216.875868 -57.150508)
		(size 0.762)
		(drill 0.381)
		(layers "F.Cu" "B.Cu")
		(net "VSENSE_P3V3_INA230_2_INN")
	)
	(segment
		(start 437.02986 -91.222068)
		(end 438.14238 -92.334588)
		(width 0.254)
		(layer "F.Cu")
		(net "VSENSE_P3V3_INA230_1_INP")
	)
	(segment
		(start 435.737 -91.745308)
		(end 436.26024 -91.222068)
		(width 0.254)
		(layer "F.Cu")
		(net "VSENSE_P3V3_INA230_1_INP")
	)
	(segment
		(start 433.359052 -94.244668)
		(end 433.036726 -93.922342)
		(width 0.254)
		(layer "F.Cu")
		(net "VSENSE_P3V3_INA230_1_INP")
	)
	(segment
		(start 435.51221 -92.700348)
		(end 435.737 -92.475558)
		(width 0.254)
		(layer "F.Cu")
		(net "VSENSE_P3V3_INA230_1_INP")
	)
	(segment
		(start 439.68797 -92.427552)
		(end 439.937906 -92.677488)
		(width 0.254)
		(layer "F.Cu")
		(net "VSENSE_P3V3_INA230_1_INP")
	)
	(segment
		(start 435.72176 -93.817694)
		(end 435.297326 -94.242128)
		(width 0.254)
		(layer "F.Cu")
		(net "VSENSE_P3V3_INA230_1_INP")
	)
	(segment
		(start 433.78882 -94.244668)
		(end 433.359052 -94.244668)
		(width 0.254)
		(layer "F.Cu")
		(net "VSENSE_P3V3_INA230_1_INP")
	)
	(segment
		(start 435.737 -92.475558)
		(end 435.737 -91.745308)
		(width 0.254)
		(layer "F.Cu")
		(net "VSENSE_P3V3_INA230_1_INP")
	)
	(segment
		(start 435.51221 -92.700348)
		(end 435.72176 -92.909898)
		(width 0.254)
		(layer "F.Cu")
		(net "VSENSE_P3V3_INA230_1_INP")
	)
	(segment
		(start 435.297326 -94.242128)
		(end 434.68036 -94.242128)
		(width 0.254)
		(layer "F.Cu")
		(net "VSENSE_P3V3_INA230_1_INP")
	)
	(segment
		(start 439.036714 -92.334588)
		(end 439.225436 -92.52331)
		(width 0.254)
		(layer "F.Cu")
		(net "VSENSE_P3V3_INA230_1_INP")
	)
	(segment
		(start 435.72176 -92.909898)
		(end 435.72176 -93.817694)
		(width 0.254)
		(layer "F.Cu")
		(net "VSENSE_P3V3_INA230_1_INP")
	)
	(segment
		(start 436.26024 -91.222068)
		(end 437.02986 -91.222068)
		(width 0.254)
		(layer "F.Cu")
		(net "VSENSE_P3V3_INA230_1_INP")
	)
	(segment
		(start 439.504582 -92.427552)
		(end 439.68797 -92.427552)
		(width 0.254)
		(layer "F.Cu")
		(net "VSENSE_P3V3_INA230_1_INP")
	)
	(segment
		(start 439.225436 -92.52331)
		(end 439.408824 -92.52331)
		(width 0.254)
		(layer "F.Cu")
		(net "VSENSE_P3V3_INA230_1_INP")
	)
	(segment
		(start 439.408824 -92.52331)
		(end 439.504582 -92.427552)
		(width 0.254)
		(layer "F.Cu")
		(net "VSENSE_P3V3_INA230_1_INP")
	)
	(segment
		(start 438.14238 -92.334588)
		(end 439.036714 -92.334588)
		(width 0.254)
		(layer "F.Cu")
		(net "VSENSE_P3V3_INA230_1_INP")
	)
	(segment
		(start 434.23586 -93.797628)
		(end 433.78882 -94.244668)
		(width 0.254)
		(layer "F.Cu")
		(net "VSENSE_P3V3_INA230_1_INP")
	)
	(segment
		(start 434.68036 -94.242128)
		(end 434.23586 -93.797628)
		(width 0.254)
		(layer "F.Cu")
		(net "VSENSE_P3V3_INA230_1_INP")
	)
	(via
		(at 434.23586 -93.797628)
		(size 0.762)
		(drill 0.381)
		(layers "F.Cu" "B.Cu")
		(net "VSENSE_P3V3_INA230_1_INP")
	)
	(segment
		(start 438.859422 -92.715588)
		(end 439.037984 -92.89415)
		(width 0.254)
		(layer "F.Cu")
		(net "VSENSE_P3V3_INA230_1_INN")
	)
	(segment
		(start 436.118 -92.506038)
		(end 436.118 -91.903296)
		(width 0.254)
		(layer "F.Cu")
		(net "VSENSE_P3V3_INA230_1_INN")
	)
	(segment
		(start 435.455314 -94.623128)
		(end 434.68036 -94.623128)
		(width 0.254)
		(layer "F.Cu")
		(net "VSENSE_P3V3_INA230_1_INN")
	)
	(segment
		(start 436.10276 -93.975682)
		(end 435.455314 -94.623128)
		(width 0.254)
		(layer "F.Cu")
		(net "VSENSE_P3V3_INA230_1_INN")
	)
	(segment
		(start 433.3494 -94.625668)
		(end 433.036726 -94.938342)
		(width 0.254)
		(layer "F.Cu")
		(net "VSENSE_P3V3_INA230_1_INN")
	)
	(segment
		(start 436.118 -91.903296)
		(end 436.418228 -91.603068)
		(width 0.254)
		(layer "F.Cu")
		(net "VSENSE_P3V3_INA230_1_INN")
	)
	(segment
		(start 433.7939 -94.625668)
		(end 433.3494 -94.625668)
		(width 0.254)
		(layer "F.Cu")
		(net "VSENSE_P3V3_INA230_1_INN")
	)
	(segment
		(start 436.31231 -92.700348)
		(end 436.118 -92.506038)
		(width 0.254)
		(layer "F.Cu")
		(net "VSENSE_P3V3_INA230_1_INN")
	)
	(segment
		(start 436.418228 -91.603068)
		(end 436.871872 -91.603068)
		(width 0.254)
		(layer "F.Cu")
		(net "VSENSE_P3V3_INA230_1_INN")
	)
	(segment
		(start 434.68036 -94.623128)
		(end 434.23586 -95.067628)
		(width 0.254)
		(layer "F.Cu")
		(net "VSENSE_P3V3_INA230_1_INN")
	)
	(segment
		(start 439.037984 -93.077538)
		(end 439.28792 -93.327474)
		(width 0.254)
		(layer "F.Cu")
		(net "VSENSE_P3V3_INA230_1_INN")
	)
	(segment
		(start 436.10276 -92.909898)
		(end 436.10276 -93.975682)
		(width 0.254)
		(layer "F.Cu")
		(net "VSENSE_P3V3_INA230_1_INN")
	)
	(segment
		(start 436.871872 -91.603068)
		(end 437.984392 -92.715588)
		(width 0.254)
		(layer "F.Cu")
		(net "VSENSE_P3V3_INA230_1_INN")
	)
	(segment
		(start 434.23586 -95.067628)
		(end 433.7939 -94.625668)
		(width 0.254)
		(layer "F.Cu")
		(net "VSENSE_P3V3_INA230_1_INN")
	)
	(segment
		(start 437.984392 -92.715588)
		(end 438.859422 -92.715588)
		(width 0.254)
		(layer "F.Cu")
		(net "VSENSE_P3V3_INA230_1_INN")
	)
	(segment
		(start 439.037984 -92.89415)
		(end 439.037984 -93.077538)
		(width 0.254)
		(layer "F.Cu")
		(net "VSENSE_P3V3_INA230_1_INN")
	)
	(segment
		(start 436.31231 -92.700348)
		(end 436.10276 -92.909898)
		(width 0.254)
		(layer "F.Cu")
		(net "VSENSE_P3V3_INA230_1_INN")
	)
	(via
		(at 434.23586 -95.067628)
		(size 0.762)
		(drill 0.381)
		(layers "F.Cu" "B.Cu")
		(net "VSENSE_P3V3_INA230_1_INN")
	)
	(segment
		(start 115.677442 -130.445002)
		(end 116.9289 -131.69646)
		(width 0.12954)
		(layer "F.Cu")
		(net "SMB_PCIE0_3V3AUX_SDA_R5")
	)
	(segment
		(start 116.9289 -131.69646)
		(end 118.108476 -131.69646)
		(width 0.12954)
		(layer "F.Cu")
		(net "SMB_PCIE0_3V3AUX_SDA_R5")
	)
	(segment
		(start 115.677442 -129.789682)
		(end 115.677442 -130.445002)
		(width 0.12954)
		(layer "F.Cu")
		(net "SMB_PCIE0_3V3AUX_SDA_R5")
	)
	(segment
		(start 115.296442 -129.408682)
		(end 115.677442 -129.789682)
		(width 0.12954)
		(layer "F.Cu")
		(net "SMB_PCIE0_3V3AUX_SDA_R5")
	)
	(segment
		(start 113.894362 -129.408682)
		(end 115.296442 -129.408682)
		(width 0.12954)
		(layer "F.Cu")
		(net "SMB_PCIE0_3V3AUX_SDA_R5")
	)
	(via
		(at 115.677442 -129.789682)
		(size 0.762)
		(drill 0.381)
		(layers "F.Cu" "B.Cu")
		(net "SMB_PCIE0_3V3AUX_SDA_R5")
	)
	(segment
		(start 116.312442 -130.424682)
		(end 116.934234 -131.046474)
		(width 0.12954)
		(layer "F.Cu")
		(net "SMB_PCIE0_3V3AUX_SCL_R5")
	)
	(segment
		(start 116.934234 -131.046474)
		(end 118.108476 -131.046474)
		(width 0.12954)
		(layer "F.Cu")
		(net "SMB_PCIE0_3V3AUX_SCL_R5")
	)
	(segment
		(start 113.894362 -128.392682)
		(end 115.169442 -128.392682)
		(width 0.12954)
		(layer "F.Cu")
		(net "SMB_PCIE0_3V3AUX_SCL_R5")
	)
	(segment
		(start 115.169442 -128.392682)
		(end 116.312442 -129.535682)
		(width 0.12954)
		(layer "F.Cu")
		(net "SMB_PCIE0_3V3AUX_SCL_R5")
	)
	(segment
		(start 116.312442 -129.535682)
		(end 116.312442 -130.424682)
		(width 0.12954)
		(layer "F.Cu")
		(net "SMB_PCIE0_3V3AUX_SCL_R5")
	)
	(via
		(at 115.169442 -128.392682)
		(size 0.762)
		(drill 0.381)
		(layers "F.Cu" "B.Cu")
		(net "SMB_PCIE0_3V3AUX_SCL_R5")
	)
	(segment
		(start 212.68055 -32.816292)
		(end 211.737956 -32.816292)
		(width 0.12954)
		(layer "F.Cu")
		(net "SMB_INA230_5_3V3AUX_SDA_R1")
	)
	(segment
		(start 211.737956 -32.816292)
		(end 210.213956 -32.816292)
		(width 0.12954)
		(layer "F.Cu")
		(net "SMB_INA230_5_3V3AUX_SDA_R1")
	)
	(segment
		(start 210.213956 -32.816292)
		(end 209.922618 -33.10763)
		(width 0.12954)
		(layer "F.Cu")
		(net "SMB_INA230_5_3V3AUX_SDA_R1")
	)
	(segment
		(start 213.14283 -32.857948)
		(end 212.722206 -32.857948)
		(width 0.12954)
		(layer "F.Cu")
		(net "SMB_INA230_5_3V3AUX_SDA_R1")
	)
	(segment
		(start 212.722206 -32.857948)
		(end 212.68055 -32.816292)
		(width 0.12954)
		(layer "F.Cu")
		(net "SMB_INA230_5_3V3AUX_SDA_R1")
	)
	(segment
		(start 209.922618 -33.10763)
		(end 209.922618 -33.372044)
		(width 0.12954)
		(layer "F.Cu")
		(net "SMB_INA230_5_3V3AUX_SDA_R1")
	)
	(via
		(at 211.737956 -32.816292)
		(size 0.762)
		(drill 0.381)
		(layers "F.Cu" "B.Cu")
		(net "SMB_INA230_5_3V3AUX_SDA_R1")
	)
	(segment
		(start 213.94293 -32.857948)
		(end 214.68588 -32.857948)
		(width 0.12954)
		(layer "F.Cu")
		(net "SMB_INA230_5_3V3AUX_SDA_R")
	)
	(segment
		(start 215.55583 -32.857948)
		(end 214.68588 -32.857948)
		(width 0.12954)
		(layer "F.Cu")
		(net "SMB_INA230_5_3V3AUX_SDA_R")
	)
	(via
		(at 214.68588 -32.857948)
		(size 0.508)
		(drill 0.254)
		(layers "F.Cu" "B.Cu")
		(net "SMB_INA230_5_3V3AUX_SDA_R")
	)
	(segment
		(start 212.722206 -34.508948)
		(end 212.68055 -34.467292)
		(width 0.12954)
		(layer "F.Cu")
		(net "SMB_INA230_5_3V3AUX_SCL_R1")
	)
	(segment
		(start 211.864956 -34.467292)
		(end 211.419694 -34.02203)
		(width 0.12954)
		(layer "F.Cu")
		(net "SMB_INA230_5_3V3AUX_SCL_R1")
	)
	(segment
		(start 213.14283 -34.508948)
		(end 212.722206 -34.508948)
		(width 0.12954)
		(layer "F.Cu")
		(net "SMB_INA230_5_3V3AUX_SCL_R1")
	)
	(segment
		(start 212.68055 -34.467292)
		(end 211.864956 -34.467292)
		(width 0.12954)
		(layer "F.Cu")
		(net "SMB_INA230_5_3V3AUX_SCL_R1")
	)
	(segment
		(start 211.419694 -34.02203)
		(end 210.572604 -34.02203)
		(width 0.12954)
		(layer "F.Cu")
		(net "SMB_INA230_5_3V3AUX_SCL_R1")
	)
	(via
		(at 211.864956 -34.467292)
		(size 0.762)
		(drill 0.381)
		(layers "F.Cu" "B.Cu")
		(net "SMB_INA230_5_3V3AUX_SCL_R1")
	)
	(segment
		(start 215.55583 -34.508948)
		(end 214.68588 -34.508948)
		(width 0.12954)
		(layer "F.Cu")
		(net "SMB_INA230_5_3V3AUX_SCL_R")
	)
	(segment
		(start 213.94293 -34.508948)
		(end 214.68588 -34.508948)
		(width 0.12954)
		(layer "F.Cu")
		(net "SMB_INA230_5_3V3AUX_SCL_R")
	)
	(via
		(at 214.68588 -34.508948)
		(size 0.508)
		(drill 0.254)
		(layers "F.Cu" "B.Cu")
		(net "SMB_INA230_5_3V3AUX_SCL_R")
	)
	(segment
		(start 150.0886 -49.672748)
		(end 150.737824 -50.321972)
		(width 0.12954)
		(layer "F.Cu")
		(net "SMB_INA230_4_3V3AUX_SDA_R1")
	)
	(segment
		(start 150.737824 -51.277012)
		(end 151.029162 -51.56835)
		(width 0.12954)
		(layer "F.Cu")
		(net "SMB_INA230_4_3V3AUX_SDA_R1")
	)
	(segment
		(start 150.67788 -48.370998)
		(end 150.67788 -49.083468)
		(width 0.12954)
		(layer "F.Cu")
		(net "SMB_INA230_4_3V3AUX_SDA_R1")
	)
	(segment
		(start 151.029162 -51.56835)
		(end 151.293576 -51.56835)
		(width 0.12954)
		(layer "F.Cu")
		(net "SMB_INA230_4_3V3AUX_SDA_R1")
	)
	(segment
		(start 150.67788 -49.083468)
		(end 150.0886 -49.672748)
		(width 0.12954)
		(layer "F.Cu")
		(net "SMB_INA230_4_3V3AUX_SDA_R1")
	)
	(segment
		(start 150.737824 -50.321972)
		(end 150.737824 -51.277012)
		(width 0.12954)
		(layer "F.Cu")
		(net "SMB_INA230_4_3V3AUX_SDA_R1")
	)
	(via
		(at 150.0886 -49.672748)
		(size 0.762)
		(drill 0.381)
		(layers "F.Cu" "B.Cu")
		(net "SMB_INA230_4_3V3AUX_SDA_R1")
	)
	(segment
		(start 150.67788 -46.338998)
		(end 150.67788 -46.961298)
		(width 0.12954)
		(layer "F.Cu")
		(net "SMB_INA230_4_3V3AUX_SDA_R")
	)
	(segment
		(start 150.67788 -47.570898)
		(end 150.67788 -46.961298)
		(width 0.12954)
		(layer "F.Cu")
		(net "SMB_INA230_4_3V3AUX_SDA_R")
	)
	(via
		(at 150.67788 -46.961298)
		(size 0.508)
		(drill 0.254)
		(layers "F.Cu" "B.Cu")
		(net "SMB_INA230_4_3V3AUX_SDA_R")
	)
	(segment
		(start 151.530304 -49.590198)
		(end 151.943562 -50.003456)
		(width 0.12954)
		(layer "F.Cu")
		(net "SMB_INA230_4_3V3AUX_SCL_R1")
	)
	(segment
		(start 152.32888 -48.370998)
		(end 152.32888 -48.791622)
		(width 0.12954)
		(layer "F.Cu")
		(net "SMB_INA230_4_3V3AUX_SCL_R1")
	)
	(segment
		(start 152.32888 -48.791622)
		(end 151.530304 -49.590198)
		(width 0.12954)
		(layer "F.Cu")
		(net "SMB_INA230_4_3V3AUX_SCL_R1")
	)
	(segment
		(start 151.943562 -50.003456)
		(end 151.943562 -50.918364)
		(width 0.12954)
		(layer "F.Cu")
		(net "SMB_INA230_4_3V3AUX_SCL_R1")
	)
	(via
		(at 151.530304 -49.590198)
		(size 0.762)
		(drill 0.381)
		(layers "F.Cu" "B.Cu")
		(net "SMB_INA230_4_3V3AUX_SCL_R1")
	)
	(segment
		(start 152.32888 -47.570898)
		(end 152.32888 -46.961298)
		(width 0.12954)
		(layer "F.Cu")
		(net "SMB_INA230_4_3V3AUX_SCL_R")
	)
	(segment
		(start 152.32888 -46.338998)
		(end 152.32888 -46.961298)
		(width 0.12954)
		(layer "F.Cu")
		(net "SMB_INA230_4_3V3AUX_SCL_R")
	)
	(via
		(at 152.32888 -46.961298)
		(size 0.508)
		(drill 0.254)
		(layers "F.Cu" "B.Cu")
		(net "SMB_INA230_4_3V3AUX_SCL_R")
	)
	(segment
		(start 70.752462 -38.278562)
		(end 71.0438 -38.5699)
		(width 0.12954)
		(layer "F.Cu")
		(net "SMB_INA230_3_3V3AUX_SDA_R1")
	)
	(segment
		(start 71.0438 -38.5699)
		(end 71.308214 -38.5699)
		(width 0.12954)
		(layer "F.Cu")
		(net "SMB_INA230_3_3V3AUX_SDA_R1")
	)
	(segment
		(start 70.358 -36.566348)
		(end 70.752462 -36.96081)
		(width 0.12954)
		(layer "F.Cu")
		(net "SMB_INA230_3_3V3AUX_SDA_R1")
	)
	(segment
		(start 70.752462 -36.96081)
		(end 70.752462 -38.278562)
		(width 0.12954)
		(layer "F.Cu")
		(net "SMB_INA230_3_3V3AUX_SDA_R1")
	)
	(segment
		(start 70.752462 -36.171886)
		(end 70.358 -36.566348)
		(width 0.12954)
		(layer "F.Cu")
		(net "SMB_INA230_3_3V3AUX_SDA_R1")
	)
	(segment
		(start 70.809358 -35.09264)
		(end 70.809358 -36.11499)
		(width 0.12954)
		(layer "F.Cu")
		(net "SMB_INA230_3_3V3AUX_SDA_R1")
	)
	(segment
		(start 70.809358 -36.11499)
		(end 70.752462 -36.171886)
		(width 0.12954)
		(layer "F.Cu")
		(net "SMB_INA230_3_3V3AUX_SDA_R1")
	)
	(segment
		(start 71.11365 -34.788348)
		(end 70.809358 -35.09264)
		(width 0.12954)
		(layer "F.Cu")
		(net "SMB_INA230_3_3V3AUX_SDA_R1")
	)
	(via
		(at 70.358 -36.566348)
		(size 0.762)
		(drill 0.381)
		(layers "F.Cu" "B.Cu")
		(net "SMB_INA230_3_3V3AUX_SDA_R1")
	)
	(segment
		(start 70.31355 -34.788348)
		(end 70.31355 -35.677348)
		(width 0.12954)
		(layer "F.Cu")
		(net "SMB_INA230_3_3V3AUX_SDA_R")
	)
	(segment
		(start 69.36105 -34.788348)
		(end 70.31355 -34.788348)
		(width 0.12954)
		(layer "F.Cu")
		(net "SMB_INA230_3_3V3AUX_SDA_R")
	)
	(via
		(at 70.31355 -35.677348)
		(size 0.508)
		(drill 0.254)
		(layers "F.Cu" "B.Cu")
		(net "SMB_INA230_3_3V3AUX_SDA_R")
	)
	(segment
		(start 71.895462 -34.959036)
		(end 72.06615 -34.788348)
		(width 0.12954)
		(layer "F.Cu")
		(net "SMB_INA230_3_3V3AUX_SCL_R1")
	)
	(segment
		(start 71.895462 -35.376612)
		(end 71.895462 -35.490912)
		(width 0.12954)
		(layer "F.Cu")
		(net "SMB_INA230_3_3V3AUX_SCL_R1")
	)
	(segment
		(start 71.895462 -35.490912)
		(end 71.895462 -36.298886)
		(width 0.12954)
		(layer "F.Cu")
		(net "SMB_INA230_3_3V3AUX_SCL_R1")
	)
	(segment
		(start 71.9582 -36.896548)
		(end 71.9582 -37.919914)
		(width 0.12954)
		(layer "F.Cu")
		(net "SMB_INA230_3_3V3AUX_SCL_R1")
	)
	(segment
		(start 67.812412 -38.405562)
		(end 67.202812 -38.405562)
		(width 0.12954)
		(layer "F.Cu")
		(net "SMB_INA230_3_3V3AUX_SCL_R1")
	)
	(segment
		(start 71.895462 -35.376612)
		(end 71.895462 -34.959036)
		(width 0.12954)
		(layer "F.Cu")
		(net "SMB_INA230_3_3V3AUX_SCL_R1")
	)
	(segment
		(start 71.895462 -36.298886)
		(end 71.628 -36.566348)
		(width 0.12954)
		(layer "F.Cu")
		(net "SMB_INA230_3_3V3AUX_SCL_R1")
	)
	(segment
		(start 71.628 -36.566348)
		(end 71.9582 -36.896548)
		(width 0.12954)
		(layer "F.Cu")
		(net "SMB_INA230_3_3V3AUX_SCL_R1")
	)
	(via
		(at 67.202812 -38.405562)
		(size 0.508)
		(drill 0.254)
		(layers "F.Cu" "B.Cu")
		(net "SMB_INA230_3_3V3AUX_SCL_R1")
	)
	(via
		(at 71.628 -36.566348)
		(size 0.762)
		(drill 0.381)
		(layers "F.Cu" "B.Cu")
		(net "SMB_INA230_3_3V3AUX_SCL_R1")
	)
	(via
		(at 71.895462 -35.490912)
		(size 0.508)
		(drill 0.254)
		(layers "F.Cu" "B.Cu")
		(net "SMB_INA230_3_3V3AUX_SCL_R1")
	)
	(segment
		(start 71.895462 -35.490912)
		(end 71.895462 -36.629086)
		(width 0.12954)
		(layer "B.Cu")
		(net "SMB_INA230_3_3V3AUX_SCL_R1")
	)
	(segment
		(start 71.895462 -36.629086)
		(end 70.118986 -38.405562)
		(width 0.12954)
		(layer "B.Cu")
		(net "SMB_INA230_3_3V3AUX_SCL_R1")
	)
	(segment
		(start 70.118986 -38.405562)
		(end 67.202812 -38.405562)
		(width 0.12954)
		(layer "B.Cu")
		(net "SMB_INA230_3_3V3AUX_SCL_R1")
	)
	(segment
		(start 72.898 -34.820098)
		(end 72.898 -35.524948)
		(width 0.12954)
		(layer "F.Cu")
		(net "SMB_INA230_3_3V3AUX_SCL_R")
	)
	(segment
		(start 72.86625 -34.788348)
		(end 72.898 -34.820098)
		(width 0.12954)
		(layer "F.Cu")
		(net "SMB_INA230_3_3V3AUX_SCL_R")
	)
	(segment
		(start 72.898 -35.524948)
		(end 73.64095 -35.524948)
		(width 0.12954)
		(layer "F.Cu")
		(net "SMB_INA230_3_3V3AUX_SCL_R")
	)
	(segment
		(start 73.64095 -35.524948)
		(end 73.81875 -35.347148)
		(width 0.12954)
		(layer "F.Cu")
		(net "SMB_INA230_3_3V3AUX_SCL_R")
	)
	(via
		(at 72.898 -35.524948)
		(size 0.508)
		(drill 0.254)
		(layers "F.Cu" "B.Cu")
		(net "SMB_INA230_3_3V3AUX_SCL_R")
	)
	(segment
		(start 127.656336 -133.050026)
		(end 126.80061 -133.905752)
		(width 0.12954)
		(layer "F.Cu")
		(net "SMB_INA230_3V3AUX_SDA_R")
	)
	(segment
		(start 128.001522 -133.050026)
		(end 127.656336 -133.050026)
		(width 0.12954)
		(layer "F.Cu")
		(net "SMB_INA230_3V3AUX_SDA_R")
	)
	(segment
		(start 126.80061 -133.905752)
		(end 125.425962 -133.905752)
		(width 0.12954)
		(layer "F.Cu")
		(net "SMB_INA230_3V3AUX_SDA_R")
	)
	(segment
		(start 124.516642 -132.996432)
		(end 123.708668 -132.996432)
		(width 0.12954)
		(layer "F.Cu")
		(net "SMB_INA230_3V3AUX_SDA_R")
	)
	(segment
		(start 125.425962 -133.905752)
		(end 124.516642 -132.996432)
		(width 0.12954)
		(layer "F.Cu")
		(net "SMB_INA230_3V3AUX_SDA_R")
	)
	(via
		(at 126.80061 -133.905752)
		(size 0.762)
		(drill 0.381)
		(layers "F.Cu" "B.Cu")
		(net "SMB_INA230_3V3AUX_SDA_R")
	)
	(segment
		(start 128.801622 -133.050026)
		(end 130.723894 -133.050026)
		(width 0.12954)
		(layer "F.Cu")
		(net "SMB_INA230_3V3AUX_SDA")
	)
	(segment
		(start 213.41588 -46.70044)
		(end 213.41588 -46.935898)
		(width 0.12954)
		(layer "F.Cu")
		(net "SMB_INA230_3V3AUX_SDA")
	)
	(segment
		(start 449.01993 -95.872808)
		(end 449.63588 -95.872808)
		(width 0.12954)
		(layer "F.Cu")
		(net "SMB_INA230_3V3AUX_SDA")
	)
	(segment
		(start 130.723894 -133.050026)
		(end 131.066794 -132.707126)
		(width 0.12954)
		(layer "F.Cu")
		(net "SMB_INA230_3V3AUX_SDA")
	)
	(segment
		(start 150.67788 -45.538898)
		(end 150.289768 -45.538898)
		(width 0.12954)
		(layer "F.Cu")
		(net "SMB_INA230_3V3AUX_SDA")
	)
	(segment
		(start 214.05088 -46.06544)
		(end 213.41588 -46.70044)
		(width 0.12954)
		(layer "F.Cu")
		(net "SMB_INA230_3V3AUX_SDA")
	)
	(segment
		(start 69.2912 -35.601148)
		(end 68.955158 -35.601148)
		(width 0.12954)
		(layer "F.Cu")
		(net "SMB_INA230_3V3AUX_SDA")
	)
	(segment
		(start 133.27888 -132.014722)
		(end 131.759198 -132.014722)
		(width 0.12954)
		(layer "F.Cu")
		(net "SMB_INA230_3V3AUX_SDA")
	)
	(segment
		(start 68.584318 -34.811716)
		(end 68.56095 -34.788348)
		(width 0.12954)
		(layer "F.Cu")
		(net "SMB_INA230_3V3AUX_SDA")
	)
	(segment
		(start 68.584318 -35.230308)
		(end 68.584318 -34.811716)
		(width 0.12954)
		(layer "F.Cu")
		(net "SMB_INA230_3V3AUX_SDA")
	)
	(segment
		(start 150.289768 -45.538898)
		(end 149.931374 -45.897292)
		(width 0.12954)
		(layer "F.Cu")
		(net "SMB_INA230_3V3AUX_SDA")
	)
	(segment
		(start 216.35593 -32.857948)
		(end 216.97188 -32.857948)
		(width 0.12954)
		(layer "F.Cu")
		(net "SMB_INA230_3V3AUX_SDA")
	)
	(segment
		(start 68.955158 -35.601148)
		(end 68.584318 -35.230308)
		(width 0.12954)
		(layer "F.Cu")
		(net "SMB_INA230_3V3AUX_SDA")
	)
	(segment
		(start 131.759198 -132.014722)
		(end 131.066794 -132.707126)
		(width 0.12954)
		(layer "F.Cu")
		(net "SMB_INA230_3V3AUX_SDA")
	)
	(via
		(at 100.203 -132.806948)
		(size 0.508)
		(drill 0.254)
		(layers "F.Cu" "B.Cu")
		(net "SMB_INA230_3V3AUX_SDA")
	)
	(via
		(at 328.041 -80.101948)
		(size 0.508)
		(drill 0.254)
		(layers "F.Cu" "B.Cu")
		(net "SMB_INA230_3V3AUX_SDA")
	)
	(via
		(at 214.05088 -46.06544)
		(size 0.508)
		(drill 0.254)
		(layers "F.Cu" "B.Cu")
		(net "SMB_INA230_3V3AUX_SDA")
	)
	(via
		(at 449.63588 -95.872808)
		(size 0.508)
		(drill 0.254)
		(layers "F.Cu" "B.Cu")
		(net "SMB_INA230_3V3AUX_SDA")
	)
	(via
		(at 133.27888 -132.014722)
		(size 0.508)
		(drill 0.254)
		(layers "F.Cu" "B.Cu")
		(net "SMB_INA230_3V3AUX_SDA")
	)
	(via
		(at 216.97188 -32.857948)
		(size 0.508)
		(drill 0.254)
		(layers "F.Cu" "B.Cu")
		(net "SMB_INA230_3V3AUX_SDA")
	)
	(via
		(at 69.2912 -35.601148)
		(size 0.508)
		(drill 0.254)
		(layers "F.Cu" "B.Cu")
		(net "SMB_INA230_3V3AUX_SDA")
	)
	(via
		(at 149.931374 -45.897292)
		(size 0.508)
		(drill 0.254)
		(layers "F.Cu" "B.Cu")
		(net "SMB_INA230_3V3AUX_SDA")
	)
	(segment
		(start 93.14688 -122.265948)
		(end 98.09988 -127.218948)
		(width 0.127)
		(layer "In2.Cu")
		(net "SMB_INA230_3V3AUX_SDA")
	)
	(segment
		(start 87.93988 -76.799948)
		(end 82.35188 -82.387948)
		(width 0.127)
		(layer "In2.Cu")
		(net "SMB_INA230_3V3AUX_SDA")
	)
	(segment
		(start 98.09988 -133.441948)
		(end 98.48088 -133.822948)
		(width 0.127)
		(layer "In2.Cu")
		(net "SMB_INA230_3V3AUX_SDA")
	)
	(segment
		(start 89.146888 -108.208572)
		(end 89.146888 -112.423956)
		(width 0.127)
		(layer "In2.Cu")
		(net "SMB_INA230_3V3AUX_SDA")
	)
	(segment
		(start 84.63788 -58.384948)
		(end 87.93988 -61.686948)
		(width 0.127)
		(layer "In2.Cu")
		(net "SMB_INA230_3V3AUX_SDA")
	)
	(segment
		(start 74.85888 -44.755308)
		(end 74.85888 -49.621948)
		(width 0.127)
		(layer "In2.Cu")
		(net "SMB_INA230_3V3AUX_SDA")
	)
	(segment
		(start 93.14688 -116.423948)
		(end 93.14688 -122.265948)
		(width 0.127)
		(layer "In2.Cu")
		(net "SMB_INA230_3V3AUX_SDA")
	)
	(segment
		(start 89.146888 -112.423956)
		(end 93.14688 -116.423948)
		(width 0.127)
		(layer "In2.Cu")
		(net "SMB_INA230_3V3AUX_SDA")
	)
	(segment
		(start 69.2912 -35.601148)
		(end 69.2912 -36.866068)
		(width 0.127)
		(layer "In2.Cu")
		(net "SMB_INA230_3V3AUX_SDA")
	)
	(segment
		(start 79.17688 -53.939948)
		(end 81.27746 -53.939948)
		(width 0.127)
		(layer "In2.Cu")
		(net "SMB_INA230_3V3AUX_SDA")
	)
	(segment
		(start 70.17766 -37.752528)
		(end 70.17766 -40.881808)
		(width 0.127)
		(layer "In2.Cu")
		(net "SMB_INA230_3V3AUX_SDA")
	)
	(segment
		(start 98.48088 -133.822948)
		(end 99.695 -133.822948)
		(width 0.127)
		(layer "In2.Cu")
		(net "SMB_INA230_3V3AUX_SDA")
	)
	(segment
		(start 70.17766 -40.881808)
		(end 72.77608 -43.480228)
		(width 0.127)
		(layer "In2.Cu")
		(net "SMB_INA230_3V3AUX_SDA")
	)
	(segment
		(start 216.08288 -33.746948)
		(end 216.97188 -32.857948)
		(width 0.127)
		(layer "In2.Cu")
		(net "SMB_INA230_3V3AUX_SDA")
	)
	(segment
		(start 85.90788 -104.969564)
		(end 89.146888 -108.208572)
		(width 0.127)
		(layer "In2.Cu")
		(net "SMB_INA230_3V3AUX_SDA")
	)
	(segment
		(start 84.63788 -57.300368)
		(end 84.63788 -58.384948)
		(width 0.127)
		(layer "In2.Cu")
		(net "SMB_INA230_3V3AUX_SDA")
	)
	(segment
		(start 82.35188 -82.387948)
		(end 82.35188 -96.557592)
		(width 0.127)
		(layer "In2.Cu")
		(net "SMB_INA230_3V3AUX_SDA")
	)
	(segment
		(start 69.2912 -36.866068)
		(end 70.17766 -37.752528)
		(width 0.127)
		(layer "In2.Cu")
		(net "SMB_INA230_3V3AUX_SDA")
	)
	(segment
		(start 74.85888 -49.621948)
		(end 79.17688 -53.939948)
		(width 0.127)
		(layer "In2.Cu")
		(net "SMB_INA230_3V3AUX_SDA")
	)
	(segment
		(start 87.93988 -61.686948)
		(end 87.93988 -76.799948)
		(width 0.127)
		(layer "In2.Cu")
		(net "SMB_INA230_3V3AUX_SDA")
	)
	(segment
		(start 82.35188 -96.557592)
		(end 85.90788 -100.113592)
		(width 0.127)
		(layer "In2.Cu")
		(net "SMB_INA230_3V3AUX_SDA")
	)
	(segment
		(start 99.695 -133.822948)
		(end 100.203 -133.314948)
		(width 0.127)
		(layer "In2.Cu")
		(net "SMB_INA230_3V3AUX_SDA")
	)
	(segment
		(start 73.5838 -43.480228)
		(end 74.85888 -44.755308)
		(width 0.127)
		(layer "In2.Cu")
		(net "SMB_INA230_3V3AUX_SDA")
	)
	(segment
		(start 81.27746 -53.939948)
		(end 84.63788 -57.300368)
		(width 0.127)
		(layer "In2.Cu")
		(net "SMB_INA230_3V3AUX_SDA")
	)
	(segment
		(start 85.90788 -100.113592)
		(end 85.90788 -104.969564)
		(width 0.127)
		(layer "In2.Cu")
		(net "SMB_INA230_3V3AUX_SDA")
	)
	(segment
		(start 98.09988 -127.218948)
		(end 98.09988 -133.441948)
		(width 0.127)
		(layer "In2.Cu")
		(net "SMB_INA230_3V3AUX_SDA")
	)
	(segment
		(start 216.08288 -34.254948)
		(end 216.08288 -33.746948)
		(width 0.127)
		(layer "In2.Cu")
		(net "SMB_INA230_3V3AUX_SDA")
	)
	(segment
		(start 72.77608 -43.480228)
		(end 73.5838 -43.480228)
		(width 0.127)
		(layer "In2.Cu")
		(net "SMB_INA230_3V3AUX_SDA")
	)
	(segment
		(start 214.05088 -46.06544)
		(end 214.05088 -36.286948)
		(width 0.127)
		(layer "In2.Cu")
		(net "SMB_INA230_3V3AUX_SDA")
	)
	(segment
		(start 214.05088 -36.286948)
		(end 216.08288 -34.254948)
		(width 0.127)
		(layer "In2.Cu")
		(net "SMB_INA230_3V3AUX_SDA")
	)
	(segment
		(start 100.203 -133.314948)
		(end 100.203 -132.806948)
		(width 0.127)
		(layer "In2.Cu")
		(net "SMB_INA230_3V3AUX_SDA")
	)
	(segment
		(start 246.639588 -78.888082)
		(end 253.739904 -81.829148)
		(width 0.127)
		(layer "In4.Cu")
		(net "SMB_INA230_3V3AUX_SDA")
	)
	(segment
		(start 326.03948 -81.829148)
		(end 327.76668 -80.101948)
		(width 0.127)
		(layer "In4.Cu")
		(net "SMB_INA230_3V3AUX_SDA")
	)
	(segment
		(start 238.734854 -70.983348)
		(end 246.639588 -78.888082)
		(width 0.127)
		(layer "In4.Cu")
		(net "SMB_INA230_3V3AUX_SDA")
	)
	(segment
		(start 199.37095 -43.602148)
		(end 197.97395 -44.999148)
		(width 0.127)
		(layer "In4.Cu")
		(net "SMB_INA230_3V3AUX_SDA")
	)
	(segment
		(start 214.05088 -46.06544)
		(end 214.05088 -46.651672)
		(width 0.127)
		(layer "In4.Cu")
		(net "SMB_INA230_3V3AUX_SDA")
	)
	(segment
		(start 214.05088 -46.651672)
		(end 223.01708 -55.617872)
		(width 0.127)
		(layer "In4.Cu")
		(net "SMB_INA230_3V3AUX_SDA")
	)
	(segment
		(start 312.607452 -81.829148)
		(end 326.03948 -81.829148)
		(width 0.127)
		(layer "In4.Cu")
		(net "SMB_INA230_3V3AUX_SDA")
	)
	(segment
		(start 255.576578 -81.829148)
		(end 265.275822 -85.846666)
		(width 0.127)
		(layer "In4.Cu")
		(net "SMB_INA230_3V3AUX_SDA")
	)
	(segment
		(start 183.92521 -41.925748)
		(end 180.47081 -41.925748)
		(width 0.127)
		(layer "In4.Cu")
		(net "SMB_INA230_3V3AUX_SDA")
	)
	(segment
		(start 214.05088 -44.892468)
		(end 212.76056 -43.602148)
		(width 0.127)
		(layer "In4.Cu")
		(net "SMB_INA230_3V3AUX_SDA")
	)
	(segment
		(start 150.293324 -45.897292)
		(end 149.931374 -45.897292)
		(width 0.127)
		(layer "In4.Cu")
		(net "SMB_INA230_3V3AUX_SDA")
	)
	(segment
		(start 265.275822 -85.846666)
		(end 302.908208 -85.846666)
		(width 0.127)
		(layer "In4.Cu")
		(net "SMB_INA230_3V3AUX_SDA")
	)
	(segment
		(start 155.408376 -49.11852)
		(end 152.661874 -46.372018)
		(width 0.127)
		(layer "In4.Cu")
		(net "SMB_INA230_3V3AUX_SDA")
	)
	(segment
		(start 180.47081 -41.925748)
		(end 180.24221 -41.697148)
		(width 0.127)
		(layer "In4.Cu")
		(net "SMB_INA230_3V3AUX_SDA")
	)
	(segment
		(start 160.83026 -49.11852)
		(end 155.408376 -49.11852)
		(width 0.127)
		(layer "In4.Cu")
		(net "SMB_INA230_3V3AUX_SDA")
	)
	(segment
		(start 162.180524 -47.768256)
		(end 160.83026 -49.11852)
		(width 0.127)
		(layer "In4.Cu")
		(net "SMB_INA230_3V3AUX_SDA")
	)
	(segment
		(start 253.739904 -81.829148)
		(end 255.576578 -81.829148)
		(width 0.127)
		(layer "In4.Cu")
		(net "SMB_INA230_3V3AUX_SDA")
	)
	(segment
		(start 223.01708 -57.056274)
		(end 236.944154 -70.983348)
		(width 0.127)
		(layer "In4.Cu")
		(net "SMB_INA230_3V3AUX_SDA")
	)
	(segment
		(start 236.944154 -70.983348)
		(end 238.734854 -70.983348)
		(width 0.127)
		(layer "In4.Cu")
		(net "SMB_INA230_3V3AUX_SDA")
	)
	(segment
		(start 212.76056 -43.602148)
		(end 199.37095 -43.602148)
		(width 0.127)
		(layer "In4.Cu")
		(net "SMB_INA230_3V3AUX_SDA")
	)
	(segment
		(start 214.05088 -46.06544)
		(end 214.05088 -44.892468)
		(width 0.127)
		(layer "In4.Cu")
		(net "SMB_INA230_3V3AUX_SDA")
	)
	(segment
		(start 167.6654 -41.697148)
		(end 162.180524 -47.182024)
		(width 0.127)
		(layer "In4.Cu")
		(net "SMB_INA230_3V3AUX_SDA")
	)
	(segment
		(start 150.76805 -46.372018)
		(end 150.293324 -45.897292)
		(width 0.127)
		(layer "In4.Cu")
		(net "SMB_INA230_3V3AUX_SDA")
	)
	(segment
		(start 223.01708 -55.617872)
		(end 223.01708 -57.056274)
		(width 0.127)
		(layer "In4.Cu")
		(net "SMB_INA230_3V3AUX_SDA")
	)
	(segment
		(start 197.97395 -44.999148)
		(end 186.99861 -44.999148)
		(width 0.127)
		(layer "In4.Cu")
		(net "SMB_INA230_3V3AUX_SDA")
	)
	(segment
		(start 162.180524 -47.182024)
		(end 162.180524 -47.768256)
		(width 0.127)
		(layer "In4.Cu")
		(net "SMB_INA230_3V3AUX_SDA")
	)
	(segment
		(start 180.24221 -41.697148)
		(end 167.6654 -41.697148)
		(width 0.127)
		(layer "In4.Cu")
		(net "SMB_INA230_3V3AUX_SDA")
	)
	(segment
		(start 186.99861 -44.999148)
		(end 183.92521 -41.925748)
		(width 0.127)
		(layer "In4.Cu")
		(net "SMB_INA230_3V3AUX_SDA")
	)
	(segment
		(start 302.908208 -85.846666)
		(end 312.607452 -81.829148)
		(width 0.127)
		(layer "In4.Cu")
		(net "SMB_INA230_3V3AUX_SDA")
	)
	(segment
		(start 152.661874 -46.372018)
		(end 150.76805 -46.372018)
		(width 0.127)
		(layer "In4.Cu")
		(net "SMB_INA230_3V3AUX_SDA")
	)
	(segment
		(start 327.76668 -80.101948)
		(end 328.041 -80.101948)
		(width 0.127)
		(layer "In4.Cu")
		(net "SMB_INA230_3V3AUX_SDA")
	)
	(segment
		(start 353.76993 -56.815228)
		(end 352.53041 -55.575708)
		(width 0.127)
		(layer "In6.Cu")
		(net "SMB_INA230_3V3AUX_SDA")
	)
	(segment
		(start 451.155054 -90.89136)
		(end 451.282054 -90.76436)
		(width 0.127)
		(layer "In6.Cu")
		(net "SMB_INA230_3V3AUX_SDA")
	)
	(segment
		(start 358.18826 -59.65571)
		(end 357.792274 -59.259724)
		(width 0.127)
		(layer "In6.Cu")
		(net "SMB_INA230_3V3AUX_SDA")
	)
	(segment
		(start 100.38588 -134.457948)
		(end 100.203 -134.275068)
		(width 0.127)
		(layer "In6.Cu")
		(net "SMB_INA230_3V3AUX_SDA")
	)
	(segment
		(start 103.20401 -134.12089)
		(end 103.07701 -133.99389)
		(width 0.127)
		(layer "In6.Cu")
		(net "SMB_INA230_3V3AUX_SDA")
	)
	(segment
		(start 451.87108 -86.121748)
		(end 450.95668 -85.207348)
		(width 0.127)
		(layer "In6.Cu")
		(net "SMB_INA230_3V3AUX_SDA")
	)
	(segment
		(start 344.67546 -62.603888)
		(end 341.0204 -66.258948)
		(width 0.127)
		(layer "In6.Cu")
		(net "SMB_INA230_3V3AUX_SDA")
	)
	(segment
		(start 331.806804 -71.5772)
		(end 331.156056 -72.227948)
		(width 0.127)
		(layer "In6.Cu")
		(net "SMB_INA230_3V3AUX_SDA")
	)
	(segment
		(start 341.0204 -66.258948)
		(end 341.0204 -67.99072)
		(width 0.127)
		(layer "In6.Cu")
		(net "SMB_INA230_3V3AUX_SDA")
	)
	(segment
		(start 435.91988 -86.172548)
		(end 366.54994 -86.172548)
		(width 0.127)
		(layer "In6.Cu")
		(net "SMB_INA230_3V3AUX_SDA")
	)
	(segment
		(start 330.284582 -73.464166)
		(end 330.284582 -78.265782)
		(width 0.127)
		(layer "In6.Cu")
		(net "SMB_INA230_3V3AUX_SDA")
	)
	(segment
		(start 116.49456 -134.457948)
		(end 103.33101 -134.457948)
		(width 0.127)
		(layer "In6.Cu")
		(net "SMB_INA230_3V3AUX_SDA")
	)
	(segment
		(start 355.71176 -57.446418)
		(end 355.08057 -56.815228)
		(width 0.127)
		(layer "In6.Cu")
		(net "SMB_INA230_3V3AUX_SDA")
	)
	(segment
		(start 451.74408 -89.49436)
		(end 451.87108 -89.36736)
		(width 0.127)
		(layer "In6.Cu")
		(net "SMB_INA230_3V3AUX_SDA")
	)
	(segment
		(start 118.937786 -132.014722)
		(end 116.49456 -134.457948)
		(width 0.127)
		(layer "In6.Cu")
		(net "SMB_INA230_3V3AUX_SDA")
	)
	(segment
		(start 436.88508 -85.207348)
		(end 435.91988 -86.172548)
		(width 0.127)
		(layer "In6.Cu")
		(net "SMB_INA230_3V3AUX_SDA")
	)
	(segment
		(start 102.56901 -134.12089)
		(end 102.56901 -134.330948)
		(width 0.127)
		(layer "In6.Cu")
		(net "SMB_INA230_3V3AUX_SDA")
	)
	(segment
		(start 451.87108 -90.63736)
		(end 451.87108 -90.25636)
		(width 0.127)
		(layer "In6.Cu")
		(net "SMB_INA230_3V3AUX_SDA")
	)
	(segment
		(start 103.20401 -134.330948)
		(end 103.20401 -134.12089)
		(width 0.127)
		(layer "In6.Cu")
		(net "SMB_INA230_3V3AUX_SDA")
	)
	(segment
		(start 103.07701 -133.99389)
		(end 102.69601 -133.99389)
		(width 0.127)
		(layer "In6.Cu")
		(net "SMB_INA230_3V3AUX_SDA")
	)
	(segment
		(start 100.203 -134.275068)
		(end 100.203 -132.806948)
		(width 0.127)
		(layer "In6.Cu")
		(net "SMB_INA230_3V3AUX_SDA")
	)
	(segment
		(start 449.63588 -95.872808)
		(end 451.87108 -93.637608)
		(width 0.127)
		(layer "In6.Cu")
		(net "SMB_INA230_3V3AUX_SDA")
	)
	(segment
		(start 337.43392 -71.5772)
		(end 331.806804 -71.5772)
		(width 0.127)
		(layer "In6.Cu")
		(net "SMB_INA230_3V3AUX_SDA")
	)
	(segment
		(start 451.74408 -90.76436)
		(end 451.87108 -90.63736)
		(width 0.127)
		(layer "In6.Cu")
		(net "SMB_INA230_3V3AUX_SDA")
	)
	(segment
		(start 362.15828 -81.780888)
		(end 362.15828 -73.523348)
		(width 0.127)
		(layer "In6.Cu")
		(net "SMB_INA230_3V3AUX_SDA")
	)
	(segment
		(start 102.44201 -134.457948)
		(end 100.38588 -134.457948)
		(width 0.127)
		(layer "In6.Cu")
		(net "SMB_INA230_3V3AUX_SDA")
	)
	(segment
		(start 102.69601 -133.99389)
		(end 102.56901 -134.12089)
		(width 0.127)
		(layer "In6.Cu")
		(net "SMB_INA230_3V3AUX_SDA")
	)
	(segment
		(start 330.284582 -78.265782)
		(end 328.448416 -80.101948)
		(width 0.127)
		(layer "In6.Cu")
		(net "SMB_INA230_3V3AUX_SDA")
	)
	(segment
		(start 102.56901 -134.330948)
		(end 102.44201 -134.457948)
		(width 0.127)
		(layer "In6.Cu")
		(net "SMB_INA230_3V3AUX_SDA")
	)
	(segment
		(start 451.155054 -90.00236)
		(end 451.155054 -89.62136)
		(width 0.127)
		(layer "In6.Cu")
		(net "SMB_INA230_3V3AUX_SDA")
	)
	(segment
		(start 356.63505 -59.259724)
		(end 355.71176 -58.336434)
		(width 0.127)
		(layer "In6.Cu")
		(net "SMB_INA230_3V3AUX_SDA")
	)
	(segment
		(start 355.08057 -56.815228)
		(end 353.76993 -56.815228)
		(width 0.127)
		(layer "In6.Cu")
		(net "SMB_INA230_3V3AUX_SDA")
	)
	(segment
		(start 344.67546 -57.596278)
		(end 344.67546 -62.603888)
		(width 0.127)
		(layer "In6.Cu")
		(net "SMB_INA230_3V3AUX_SDA")
	)
	(segment
		(start 346.69603 -55.575708)
		(end 344.67546 -57.596278)
		(width 0.127)
		(layer "In6.Cu")
		(net "SMB_INA230_3V3AUX_SDA")
	)
	(segment
		(start 451.87108 -91.52636)
		(end 451.74408 -91.39936)
		(width 0.127)
		(layer "In6.Cu")
		(net "SMB_INA230_3V3AUX_SDA")
	)
	(segment
		(start 366.54994 -86.172548)
		(end 362.15828 -81.780888)
		(width 0.127)
		(layer "In6.Cu")
		(net "SMB_INA230_3V3AUX_SDA")
	)
	(segment
		(start 352.53041 -55.575708)
		(end 346.69603 -55.575708)
		(width 0.127)
		(layer "In6.Cu")
		(net "SMB_INA230_3V3AUX_SDA")
	)
	(segment
		(start 357.792274 -59.259724)
		(end 356.63505 -59.259724)
		(width 0.127)
		(layer "In6.Cu")
		(net "SMB_INA230_3V3AUX_SDA")
	)
	(segment
		(start 451.74408 -91.39936)
		(end 451.282054 -91.39936)
		(width 0.127)
		(layer "In6.Cu")
		(net "SMB_INA230_3V3AUX_SDA")
	)
	(segment
		(start 451.74408 -90.12936)
		(end 451.282054 -90.12936)
		(width 0.127)
		(layer "In6.Cu")
		(net "SMB_INA230_3V3AUX_SDA")
	)
	(segment
		(start 328.448416 -80.101948)
		(end 328.041 -80.101948)
		(width 0.127)
		(layer "In6.Cu")
		(net "SMB_INA230_3V3AUX_SDA")
	)
	(segment
		(start 362.15828 -73.523348)
		(end 358.18826 -69.553328)
		(width 0.127)
		(layer "In6.Cu")
		(net "SMB_INA230_3V3AUX_SDA")
	)
	(segment
		(start 341.0204 -67.99072)
		(end 337.43392 -71.5772)
		(width 0.127)
		(layer "In6.Cu")
		(net "SMB_INA230_3V3AUX_SDA")
	)
	(segment
		(start 358.18826 -69.553328)
		(end 358.18826 -59.65571)
		(width 0.127)
		(layer "In6.Cu")
		(net "SMB_INA230_3V3AUX_SDA")
	)
	(segment
		(start 331.156056 -72.592692)
		(end 330.284582 -73.464166)
		(width 0.127)
		(layer "In6.Cu")
		(net "SMB_INA230_3V3AUX_SDA")
	)
	(segment
		(start 133.27888 -132.014722)
		(end 118.937786 -132.014722)
		(width 0.127)
		(layer "In6.Cu")
		(net "SMB_INA230_3V3AUX_SDA")
	)
	(segment
		(start 451.282054 -90.12936)
		(end 451.155054 -90.00236)
		(width 0.127)
		(layer "In6.Cu")
		(net "SMB_INA230_3V3AUX_SDA")
	)
	(segment
		(start 451.282054 -90.76436)
		(end 451.74408 -90.76436)
		(width 0.127)
		(layer "In6.Cu")
		(net "SMB_INA230_3V3AUX_SDA")
	)
	(segment
		(start 451.87108 -93.637608)
		(end 451.87108 -91.52636)
		(width 0.127)
		(layer "In6.Cu")
		(net "SMB_INA230_3V3AUX_SDA")
	)
	(segment
		(start 451.87108 -90.25636)
		(end 451.74408 -90.12936)
		(width 0.127)
		(layer "In6.Cu")
		(net "SMB_INA230_3V3AUX_SDA")
	)
	(segment
		(start 451.155054 -89.62136)
		(end 451.282054 -89.49436)
		(width 0.127)
		(layer "In6.Cu")
		(net "SMB_INA230_3V3AUX_SDA")
	)
	(segment
		(start 331.156056 -72.227948)
		(end 331.156056 -72.592692)
		(width 0.127)
		(layer "In6.Cu")
		(net "SMB_INA230_3V3AUX_SDA")
	)
	(segment
		(start 355.71176 -58.336434)
		(end 355.71176 -57.446418)
		(width 0.127)
		(layer "In6.Cu")
		(net "SMB_INA230_3V3AUX_SDA")
	)
	(segment
		(start 450.95668 -85.207348)
		(end 436.88508 -85.207348)
		(width 0.127)
		(layer "In6.Cu")
		(net "SMB_INA230_3V3AUX_SDA")
	)
	(segment
		(start 451.282054 -89.49436)
		(end 451.74408 -89.49436)
		(width 0.127)
		(layer "In6.Cu")
		(net "SMB_INA230_3V3AUX_SDA")
	)
	(segment
		(start 451.87108 -89.36736)
		(end 451.87108 -86.121748)
		(width 0.127)
		(layer "In6.Cu")
		(net "SMB_INA230_3V3AUX_SDA")
	)
	(segment
		(start 451.155054 -91.27236)
		(end 451.155054 -90.89136)
		(width 0.127)
		(layer "In6.Cu")
		(net "SMB_INA230_3V3AUX_SDA")
	)
	(segment
		(start 103.33101 -134.457948)
		(end 103.20401 -134.330948)
		(width 0.127)
		(layer "In6.Cu")
		(net "SMB_INA230_3V3AUX_SDA")
	)
	(segment
		(start 451.282054 -91.39936)
		(end 451.155054 -91.27236)
		(width 0.127)
		(layer "In6.Cu")
		(net "SMB_INA230_3V3AUX_SDA")
	)
	(segment
		(start 122.14225 -35.234118)
		(end 88.678004 -35.234118)
		(width 0.127)
		(layer "In15.Cu")
		(net "SMB_INA230_3V3AUX_SDA")
	)
	(segment
		(start 69.9516 -34.940748)
		(end 69.2912 -35.601148)
		(width 0.127)
		(layer "In15.Cu")
		(net "SMB_INA230_3V3AUX_SDA")
	)
	(segment
		(start 150.40483 -46.008798)
		(end 151.780748 -46.008798)
		(width 0.127)
		(layer "In15.Cu")
		(net "SMB_INA230_3V3AUX_SDA")
	)
	(segment
		(start 151.63292 -42.588688)
		(end 150.5966 -42.588688)
		(width 0.127)
		(layer "In15.Cu")
		(net "SMB_INA230_3V3AUX_SDA")
	)
	(segment
		(start 145.67281 -38.903148)
		(end 142.72895 -38.903148)
		(width 0.127)
		(layer "In15.Cu")
		(net "SMB_INA230_3V3AUX_SDA")
	)
	(segment
		(start 152.5016 -45.287946)
		(end 152.5016 -43.457368)
		(width 0.127)
		(layer "In15.Cu")
		(net "SMB_INA230_3V3AUX_SDA")
	)
	(segment
		(start 137.67181 -38.141148)
		(end 137.29081 -38.522148)
		(width 0.127)
		(layer "In15.Cu")
		(net "SMB_INA230_3V3AUX_SDA")
	)
	(segment
		(start 150.5966 -42.588688)
		(end 148.62048 -40.612568)
		(width 0.127)
		(layer "In15.Cu")
		(net "SMB_INA230_3V3AUX_SDA")
	)
	(segment
		(start 87.536274 -36.375848)
		(end 79.56804 -36.375848)
		(width 0.127)
		(layer "In15.Cu")
		(net "SMB_INA230_3V3AUX_SDA")
	)
	(segment
		(start 79.56804 -36.375848)
		(end 78.13294 -34.940748)
		(width 0.127)
		(layer "In15.Cu")
		(net "SMB_INA230_3V3AUX_SDA")
	)
	(segment
		(start 125.43028 -38.522148)
		(end 122.14225 -35.234118)
		(width 0.127)
		(layer "In15.Cu")
		(net "SMB_INA230_3V3AUX_SDA")
	)
	(segment
		(start 152.5016 -43.457368)
		(end 151.63292 -42.588688)
		(width 0.127)
		(layer "In15.Cu")
		(net "SMB_INA230_3V3AUX_SDA")
	)
	(segment
		(start 137.29081 -38.522148)
		(end 125.43028 -38.522148)
		(width 0.127)
		(layer "In15.Cu")
		(net "SMB_INA230_3V3AUX_SDA")
	)
	(segment
		(start 149.931374 -45.897292)
		(end 150.293324 -45.897292)
		(width 0.127)
		(layer "In15.Cu")
		(net "SMB_INA230_3V3AUX_SDA")
	)
	(segment
		(start 148.62048 -38.997128)
		(end 148.0185 -38.395148)
		(width 0.127)
		(layer "In15.Cu")
		(net "SMB_INA230_3V3AUX_SDA")
	)
	(segment
		(start 148.0185 -38.395148)
		(end 146.18081 -38.395148)
		(width 0.127)
		(layer "In15.Cu")
		(net "SMB_INA230_3V3AUX_SDA")
	)
	(segment
		(start 142.72895 -38.903148)
		(end 141.96695 -38.141148)
		(width 0.127)
		(layer "In15.Cu")
		(net "SMB_INA230_3V3AUX_SDA")
	)
	(segment
		(start 141.96695 -38.141148)
		(end 137.67181 -38.141148)
		(width 0.127)
		(layer "In15.Cu")
		(net "SMB_INA230_3V3AUX_SDA")
	)
	(segment
		(start 148.62048 -40.612568)
		(end 148.62048 -38.997128)
		(width 0.127)
		(layer "In15.Cu")
		(net "SMB_INA230_3V3AUX_SDA")
	)
	(segment
		(start 88.678004 -35.234118)
		(end 87.536274 -36.375848)
		(width 0.127)
		(layer "In15.Cu")
		(net "SMB_INA230_3V3AUX_SDA")
	)
	(segment
		(start 146.18081 -38.395148)
		(end 145.67281 -38.903148)
		(width 0.127)
		(layer "In15.Cu")
		(net "SMB_INA230_3V3AUX_SDA")
	)
	(segment
		(start 151.780748 -46.008798)
		(end 152.5016 -45.287946)
		(width 0.127)
		(layer "In15.Cu")
		(net "SMB_INA230_3V3AUX_SDA")
	)
	(segment
		(start 150.293324 -45.897292)
		(end 150.40483 -46.008798)
		(width 0.127)
		(layer "In15.Cu")
		(net "SMB_INA230_3V3AUX_SDA")
	)
	(segment
		(start 78.13294 -34.940748)
		(end 69.9516 -34.940748)
		(width 0.127)
		(layer "In15.Cu")
		(net "SMB_INA230_3V3AUX_SDA")
	)
	(segment
		(start 127.69723 -134.066026)
		(end 128.001522 -134.066026)
		(width 0.12954)
		(layer "F.Cu")
		(net "SMB_INA230_3V3AUX_SCL_R")
	)
	(segment
		(start 124.474478 -133.646418)
		(end 125.472698 -134.644638)
		(width 0.12954)
		(layer "F.Cu")
		(net "SMB_INA230_3V3AUX_SCL_R")
	)
	(segment
		(start 125.472698 -134.644638)
		(end 127.118618 -134.644638)
		(width 0.12954)
		(layer "F.Cu")
		(net "SMB_INA230_3V3AUX_SCL_R")
	)
	(segment
		(start 127.118618 -134.644638)
		(end 127.69723 -134.066026)
		(width 0.12954)
		(layer "F.Cu")
		(net "SMB_INA230_3V3AUX_SCL_R")
	)
	(segment
		(start 123.708668 -133.646418)
		(end 124.474478 -133.646418)
		(width 0.12954)
		(layer "F.Cu")
		(net "SMB_INA230_3V3AUX_SCL_R")
	)
	(via
		(at 125.472698 -134.644638)
		(size 0.762)
		(drill 0.381)
		(layers "F.Cu" "B.Cu")
		(net "SMB_INA230_3V3AUX_SCL_R")
	)
	(segment
		(start 216.35593 -34.508948)
		(end 216.97188 -34.508948)
		(width 0.12954)
		(layer "F.Cu")
		(net "SMB_INA230_3V3AUX_SCL")
	)
	(segment
		(start 214.81288 -46.554898)
		(end 214.43188 -46.935898)
		(width 0.12954)
		(layer "F.Cu")
		(net "SMB_INA230_3V3AUX_SCL")
	)
	(segment
		(start 74.61885 -35.347148)
		(end 75.2348 -35.347148)
		(width 0.12954)
		(layer "F.Cu")
		(net "SMB_INA230_3V3AUX_SCL")
	)
	(segment
		(start 215.47709 -47.196248)
		(end 214.69223 -47.196248)
		(width 0.12954)
		(layer "F.Cu")
		(net "SMB_INA230_3V3AUX_SCL")
	)
	(segment
		(start 133.27888 -133.424422)
		(end 131.746498 -133.424422)
		(width 0.12954)
		(layer "F.Cu")
		(net "SMB_INA230_3V3AUX_SCL")
	)
	(segment
		(start 214.69223 -47.196248)
		(end 214.43188 -46.935898)
		(width 0.12954)
		(layer "F.Cu")
		(net "SMB_INA230_3V3AUX_SCL")
	)
	(segment
		(start 128.801622 -134.066026)
		(end 128.839722 -134.104126)
		(width 0.12954)
		(layer "F.Cu")
		(net "SMB_INA230_3V3AUX_SCL")
	)
	(segment
		(start 75.2348 -35.347148)
		(end 75.3872 -35.499548)
		(width 0.12954)
		(layer "F.Cu")
		(net "SMB_INA230_3V3AUX_SCL")
	)
	(segment
		(start 152.32888 -45.538898)
		(end 151.58593 -45.538898)
		(width 0.12954)
		(layer "F.Cu")
		(net "SMB_INA230_3V3AUX_SCL")
	)
	(segment
		(start 128.839722 -134.104126)
		(end 131.066794 -134.104126)
		(width 0.12954)
		(layer "F.Cu")
		(net "SMB_INA230_3V3AUX_SCL")
	)
	(segment
		(start 131.746498 -133.424422)
		(end 131.066794 -134.104126)
		(width 0.12954)
		(layer "F.Cu")
		(net "SMB_INA230_3V3AUX_SCL")
	)
	(segment
		(start 214.81288 -46.065948)
		(end 214.81288 -46.554898)
		(width 0.12954)
		(layer "F.Cu")
		(net "SMB_INA230_3V3AUX_SCL")
	)
	(via
		(at 133.27888 -133.424422)
		(size 0.508)
		(drill 0.254)
		(layers "F.Cu" "B.Cu")
		(net "SMB_INA230_3V3AUX_SCL")
	)
	(via
		(at 98.81108 -132.806948)
		(size 0.508)
		(drill 0.254)
		(layers "F.Cu" "B.Cu")
		(net "SMB_INA230_3V3AUX_SCL")
	)
	(via
		(at 216.97188 -34.508948)
		(size 0.508)
		(drill 0.254)
		(layers "F.Cu" "B.Cu")
		(net "SMB_INA230_3V3AUX_SCL")
	)
	(via
		(at 75.3872 -35.499548)
		(size 0.508)
		(drill 0.254)
		(layers "F.Cu" "B.Cu")
		(net "SMB_INA230_3V3AUX_SCL")
	)
	(via
		(at 214.81288 -46.065948)
		(size 0.508)
		(drill 0.254)
		(layers "F.Cu" "B.Cu")
		(net "SMB_INA230_3V3AUX_SCL")
	)
	(via
		(at 151.58593 -45.538898)
		(size 0.508)
		(drill 0.254)
		(layers "F.Cu" "B.Cu")
		(net "SMB_INA230_3V3AUX_SCL")
	)
	(segment
		(start 214.93988 -37.776404)
		(end 215.345264 -37.776404)
		(width 0.127)
		(layer "In2.Cu")
		(net "SMB_INA230_3V3AUX_SCL")
	)
	(segment
		(start 99.475544 -131.156964)
		(end 99.475544 -131.537964)
		(width 0.127)
		(layer "In2.Cu")
		(net "SMB_INA230_3V3AUX_SCL")
	)
	(segment
		(start 99.348544 -131.029964)
		(end 99.475544 -131.156964)
		(width 0.127)
		(layer "In2.Cu")
		(net "SMB_INA230_3V3AUX_SCL")
	)
	(segment
		(start 98.93808 -131.664964)
		(end 98.81108 -131.791964)
		(width 0.127)
		(layer "In2.Cu")
		(net "SMB_INA230_3V3AUX_SCL")
	)
	(segment
		(start 215.472264 -37.268404)
		(end 215.345264 -37.141404)
		(width 0.127)
		(layer "In2.Cu")
		(net "SMB_INA230_3V3AUX_SCL")
	)
	(segment
		(start 87.909908 -104.915716)
		(end 88.089232 -104.915716)
		(width 0.127)
		(layer "In2.Cu")
		(net "SMB_INA230_3V3AUX_SCL")
	)
	(segment
		(start 89.578688 -112.244886)
		(end 93.57868 -116.244878)
		(width 0.127)
		(layer "In2.Cu")
		(net "SMB_INA230_3V3AUX_SCL")
	)
	(segment
		(start 98.81108 -130.902964)
		(end 98.93808 -131.029964)
		(width 0.127)
		(layer "In2.Cu")
		(net "SMB_INA230_3V3AUX_SCL")
	)
	(segment
		(start 99.475544 -130.267964)
		(end 99.348544 -130.394964)
		(width 0.127)
		(layer "In2.Cu")
		(net "SMB_INA230_3V3AUX_SCL")
	)
	(segment
		(start 214.81288 -38.284404)
		(end 214.81288 -37.903404)
		(width 0.127)
		(layer "In2.Cu")
		(net "SMB_INA230_3V3AUX_SCL")
	)
	(segment
		(start 88.37168 -61.507878)
		(end 88.37168 -76.979018)
		(width 0.127)
		(layer "In2.Cu")
		(net "SMB_INA230_3V3AUX_SCL")
	)
	(segment
		(start 88.624156 -106.895646)
		(end 88.624156 -107.07497)
		(width 0.127)
		(layer "In2.Cu")
		(net "SMB_INA230_3V3AUX_SCL")
	)
	(segment
		(start 98.93808 -131.029964)
		(end 99.348544 -131.029964)
		(width 0.127)
		(layer "In2.Cu")
		(net "SMB_INA230_3V3AUX_SCL")
	)
	(segment
		(start 87.726012 -105.997502)
		(end 87.726012 -106.176826)
		(width 0.127)
		(layer "In2.Cu")
		(net "SMB_INA230_3V3AUX_SCL")
	)
	(segment
		(start 86.33968 -99.934522)
		(end 86.33968 -104.790494)
		(width 0.127)
		(layer "In2.Cu")
		(net "SMB_INA230_3V3AUX_SCL")
	)
	(segment
		(start 87.726012 -106.176826)
		(end 87.99576 -106.446574)
		(width 0.127)
		(layer "In2.Cu")
		(net "SMB_INA230_3V3AUX_SCL")
	)
	(segment
		(start 82.78368 -96.378522)
		(end 86.33968 -99.934522)
		(width 0.127)
		(layer "In2.Cu")
		(net "SMB_INA230_3V3AUX_SCL")
	)
	(segment
		(start 87.99576 -106.446574)
		(end 88.175084 -106.446574)
		(width 0.127)
		(layer "In2.Cu")
		(net "SMB_INA230_3V3AUX_SCL")
	)
	(segment
		(start 99.475544 -131.537964)
		(end 99.348544 -131.664964)
		(width 0.127)
		(layer "In2.Cu")
		(net "SMB_INA230_3V3AUX_SCL")
	)
	(segment
		(start 98.81108 -127.319278)
		(end 98.81108 -129.632964)
		(width 0.127)
		(layer "In2.Cu")
		(net "SMB_INA230_3V3AUX_SCL")
	)
	(segment
		(start 75.29068 -44.432728)
		(end 75.29068 -47.843694)
		(width 0.127)
		(layer "In2.Cu")
		(net "SMB_INA230_3V3AUX_SCL")
	)
	(segment
		(start 82.78368 -82.567018)
		(end 82.78368 -96.378522)
		(width 0.127)
		(layer "In2.Cu")
		(net "SMB_INA230_3V3AUX_SCL")
	)
	(segment
		(start 88.624156 -107.07497)
		(end 89.578688 -108.029502)
		(width 0.127)
		(layer "In2.Cu")
		(net "SMB_INA230_3V3AUX_SCL")
	)
	(segment
		(start 99.348544 -131.664964)
		(end 98.93808 -131.664964)
		(width 0.127)
		(layer "In2.Cu")
		(net "SMB_INA230_3V3AUX_SCL")
	)
	(segment
		(start 74.09688 -36.789868)
		(end 74.09688 -40.267128)
		(width 0.127)
		(layer "In2.Cu")
		(net "SMB_INA230_3V3AUX_SCL")
	)
	(segment
		(start 85.06968 -58.205878)
		(end 88.37168 -61.507878)
		(width 0.127)
		(layer "In2.Cu")
		(net "SMB_INA230_3V3AUX_SCL")
	)
	(segment
		(start 215.345264 -39.046404)
		(end 215.472264 -38.919404)
		(width 0.127)
		(layer "In2.Cu")
		(net "SMB_INA230_3V3AUX_SCL")
	)
	(segment
		(start 73.15454 -41.209468)
		(end 73.15454 -42.296588)
		(width 0.127)
		(layer "In2.Cu")
		(net "SMB_INA230_3V3AUX_SCL")
	)
	(segment
		(start 88.089232 -104.915716)
		(end 88.35898 -105.185464)
		(width 0.127)
		(layer "In2.Cu")
		(net "SMB_INA230_3V3AUX_SCL")
	)
	(segment
		(start 75.29068 -47.843694)
		(end 80.955134 -53.508148)
		(width 0.127)
		(layer "In2.Cu")
		(net "SMB_INA230_3V3AUX_SCL")
	)
	(segment
		(start 88.37168 -76.979018)
		(end 82.78368 -82.567018)
		(width 0.127)
		(layer "In2.Cu")
		(net "SMB_INA230_3V3AUX_SCL")
	)
	(segment
		(start 215.345264 -37.141404)
		(end 214.93988 -37.141404)
		(width 0.127)
		(layer "In2.Cu")
		(net "SMB_INA230_3V3AUX_SCL")
	)
	(segment
		(start 214.93988 -37.141404)
		(end 214.81288 -37.014404)
		(width 0.127)
		(layer "In2.Cu")
		(net "SMB_INA230_3V3AUX_SCL")
	)
	(segment
		(start 87.097616 -105.54843)
		(end 87.27694 -105.54843)
		(width 0.127)
		(layer "In2.Cu")
		(net "SMB_INA230_3V3AUX_SCL")
	)
	(segment
		(start 98.93808 -129.759964)
		(end 99.348544 -129.759964)
		(width 0.127)
		(layer "In2.Cu")
		(net "SMB_INA230_3V3AUX_SCL")
	)
	(segment
		(start 86.33968 -104.790494)
		(end 87.097616 -105.54843)
		(width 0.127)
		(layer "In2.Cu")
		(net "SMB_INA230_3V3AUX_SCL")
	)
	(segment
		(start 98.81108 -130.521964)
		(end 98.81108 -130.902964)
		(width 0.127)
		(layer "In2.Cu")
		(net "SMB_INA230_3V3AUX_SCL")
	)
	(segment
		(start 88.808052 -105.81386)
		(end 88.987376 -105.81386)
		(width 0.127)
		(layer "In2.Cu")
		(net "SMB_INA230_3V3AUX_SCL")
	)
	(segment
		(start 85.06968 -57.121298)
		(end 85.06968 -58.205878)
		(width 0.127)
		(layer "In2.Cu")
		(net "SMB_INA230_3V3AUX_SCL")
	)
	(segment
		(start 214.81288 -36.667948)
		(end 216.97188 -34.508948)
		(width 0.127)
		(layer "In2.Cu")
		(net "SMB_INA230_3V3AUX_SCL")
	)
	(segment
		(start 89.257124 -106.262932)
		(end 88.624156 -106.895646)
		(width 0.127)
		(layer "In2.Cu")
		(net "SMB_INA230_3V3AUX_SCL")
	)
	(segment
		(start 99.348544 -129.759964)
		(end 99.475544 -129.886964)
		(width 0.127)
		(layer "In2.Cu")
		(net "SMB_INA230_3V3AUX_SCL")
	)
	(segment
		(start 215.345264 -37.776404)
		(end 215.472264 -37.649404)
		(width 0.127)
		(layer "In2.Cu")
		(net "SMB_INA230_3V3AUX_SCL")
	)
	(segment
		(start 73.15454 -42.296588)
		(end 75.29068 -44.432728)
		(width 0.127)
		(layer "In2.Cu")
		(net "SMB_INA230_3V3AUX_SCL")
	)
	(segment
		(start 75.3872 -35.499548)
		(end 74.09688 -36.789868)
		(width 0.127)
		(layer "In2.Cu")
		(net "SMB_INA230_3V3AUX_SCL")
	)
	(segment
		(start 215.472264 -38.538404)
		(end 215.345264 -38.411404)
		(width 0.127)
		(layer "In2.Cu")
		(net "SMB_INA230_3V3AUX_SCL")
	)
	(segment
		(start 214.81288 -39.173404)
		(end 214.93988 -39.046404)
		(width 0.127)
		(layer "In2.Cu")
		(net "SMB_INA230_3V3AUX_SCL")
	)
	(segment
		(start 81.45653 -53.508148)
		(end 85.06968 -57.121298)
		(width 0.127)
		(layer "In2.Cu")
		(net "SMB_INA230_3V3AUX_SCL")
	)
	(segment
		(start 98.93808 -130.394964)
		(end 98.81108 -130.521964)
		(width 0.127)
		(layer "In2.Cu")
		(net "SMB_INA230_3V3AUX_SCL")
	)
	(segment
		(start 89.578688 -108.029502)
		(end 89.578688 -112.244886)
		(width 0.127)
		(layer "In2.Cu")
		(net "SMB_INA230_3V3AUX_SCL")
	)
	(segment
		(start 88.987376 -105.81386)
		(end 89.257124 -106.083608)
		(width 0.127)
		(layer "In2.Cu")
		(net "SMB_INA230_3V3AUX_SCL")
	)
	(segment
		(start 214.93988 -38.411404)
		(end 214.81288 -38.284404)
		(width 0.127)
		(layer "In2.Cu")
		(net "SMB_INA230_3V3AUX_SCL")
	)
	(segment
		(start 89.257124 -106.083608)
		(end 89.257124 -106.262932)
		(width 0.127)
		(layer "In2.Cu")
		(net "SMB_INA230_3V3AUX_SCL")
	)
	(segment
		(start 215.472264 -38.919404)
		(end 215.472264 -38.538404)
		(width 0.127)
		(layer "In2.Cu")
		(net "SMB_INA230_3V3AUX_SCL")
	)
	(segment
		(start 215.472264 -37.649404)
		(end 215.472264 -37.268404)
		(width 0.127)
		(layer "In2.Cu")
		(net "SMB_INA230_3V3AUX_SCL")
	)
	(segment
		(start 214.81288 -37.903404)
		(end 214.93988 -37.776404)
		(width 0.127)
		(layer "In2.Cu")
		(net "SMB_INA230_3V3AUX_SCL")
	)
	(segment
		(start 215.345264 -38.411404)
		(end 214.93988 -38.411404)
		(width 0.127)
		(layer "In2.Cu")
		(net "SMB_INA230_3V3AUX_SCL")
	)
	(segment
		(start 74.09688 -40.267128)
		(end 73.15454 -41.209468)
		(width 0.127)
		(layer "In2.Cu")
		(net "SMB_INA230_3V3AUX_SCL")
	)
	(segment
		(start 98.81108 -131.791964)
		(end 98.81108 -132.806948)
		(width 0.127)
		(layer "In2.Cu")
		(net "SMB_INA230_3V3AUX_SCL")
	)
	(segment
		(start 98.81108 -129.632964)
		(end 98.93808 -129.759964)
		(width 0.127)
		(layer "In2.Cu")
		(net "SMB_INA230_3V3AUX_SCL")
	)
	(segment
		(start 214.93988 -39.046404)
		(end 215.345264 -39.046404)
		(width 0.127)
		(layer "In2.Cu")
		(net "SMB_INA230_3V3AUX_SCL")
	)
	(segment
		(start 87.27694 -105.54843)
		(end 87.909908 -104.915716)
		(width 0.127)
		(layer "In2.Cu")
		(net "SMB_INA230_3V3AUX_SCL")
	)
	(segment
		(start 88.175084 -106.446574)
		(end 88.808052 -105.81386)
		(width 0.127)
		(layer "In2.Cu")
		(net "SMB_INA230_3V3AUX_SCL")
	)
	(segment
		(start 88.35898 -105.364788)
		(end 87.726012 -105.997502)
		(width 0.127)
		(layer "In2.Cu")
		(net "SMB_INA230_3V3AUX_SCL")
	)
	(segment
		(start 88.35898 -105.185464)
		(end 88.35898 -105.364788)
		(width 0.127)
		(layer "In2.Cu")
		(net "SMB_INA230_3V3AUX_SCL")
	)
	(segment
		(start 80.955134 -53.508148)
		(end 81.45653 -53.508148)
		(width 0.127)
		(layer "In2.Cu")
		(net "SMB_INA230_3V3AUX_SCL")
	)
	(segment
		(start 99.475544 -129.886964)
		(end 99.475544 -130.267964)
		(width 0.127)
		(layer "In2.Cu")
		(net "SMB_INA230_3V3AUX_SCL")
	)
	(segment
		(start 99.348544 -130.394964)
		(end 98.93808 -130.394964)
		(width 0.127)
		(layer "In2.Cu")
		(net "SMB_INA230_3V3AUX_SCL")
	)
	(segment
		(start 214.81288 -37.014404)
		(end 214.81288 -36.667948)
		(width 0.127)
		(layer "In2.Cu")
		(net "SMB_INA230_3V3AUX_SCL")
	)
	(segment
		(start 93.57868 -116.244878)
		(end 93.57868 -122.086878)
		(width 0.127)
		(layer "In2.Cu")
		(net "SMB_INA230_3V3AUX_SCL")
	)
	(segment
		(start 93.57868 -122.086878)
		(end 98.81108 -127.319278)
		(width 0.127)
		(layer "In2.Cu")
		(net "SMB_INA230_3V3AUX_SCL")
	)
	(segment
		(start 214.81288 -46.065948)
		(end 214.81288 -39.173404)
		(width 0.127)
		(layer "In2.Cu")
		(net "SMB_INA230_3V3AUX_SCL")
	)
	(segment
		(start 161.995358 -46.44009)
		(end 161.68878 -46.746668)
		(width 0.127)
		(layer "In4.Cu")
		(net "SMB_INA230_3V3AUX_SCL")
	)
	(segment
		(start 161.68878 -46.746668)
		(end 153.940764 -46.746668)
		(width 0.127)
		(layer "In4.Cu")
		(net "SMB_INA230_3V3AUX_SCL")
	)
	(segment
		(start 161.70021 -45.785278)
		(end 161.70021 -45.96511)
		(width 0.127)
		(layer "In4.Cu")
		(net "SMB_INA230_3V3AUX_SCL")
	)
	(segment
		(start 187.17768 -44.567348)
		(end 184.10428 -41.493948)
		(width 0.127)
		(layer "In4.Cu")
		(net "SMB_INA230_3V3AUX_SCL")
	)
	(segment
		(start 161.96945 -45.516038)
		(end 161.70021 -45.785278)
		(width 0.127)
		(layer "In4.Cu")
		(net "SMB_INA230_3V3AUX_SCL")
	)
	(segment
		(start 161.70021 -45.96511)
		(end 161.995358 -46.260258)
		(width 0.127)
		(layer "In4.Cu")
		(net "SMB_INA230_3V3AUX_SCL")
	)
	(segment
		(start 197.79488 -44.567348)
		(end 187.17768 -44.567348)
		(width 0.127)
		(layer "In4.Cu")
		(net "SMB_INA230_3V3AUX_SCL")
	)
	(segment
		(start 153.940764 -46.746668)
		(end 153.096214 -45.902118)
		(width 0.127)
		(layer "In4.Cu")
		(net "SMB_INA230_3V3AUX_SCL")
	)
	(segment
		(start 167.1701 -41.265348)
		(end 162.624262 -45.811186)
		(width 0.127)
		(layer "In4.Cu")
		(net "SMB_INA230_3V3AUX_SCL")
	)
	(segment
		(start 151.94915 -45.902118)
		(end 151.58593 -45.538898)
		(width 0.127)
		(layer "In4.Cu")
		(net "SMB_INA230_3V3AUX_SCL")
	)
	(segment
		(start 213.06536 -43.170348)
		(end 199.19188 -43.170348)
		(width 0.127)
		(layer "In4.Cu")
		(net "SMB_INA230_3V3AUX_SCL")
	)
	(segment
		(start 180.64988 -41.493948)
		(end 180.42128 -41.265348)
		(width 0.127)
		(layer "In4.Cu")
		(net "SMB_INA230_3V3AUX_SCL")
	)
	(segment
		(start 184.10428 -41.493948)
		(end 180.64988 -41.493948)
		(width 0.127)
		(layer "In4.Cu")
		(net "SMB_INA230_3V3AUX_SCL")
	)
	(segment
		(start 162.44443 -45.811186)
		(end 162.149282 -45.516038)
		(width 0.127)
		(layer "In4.Cu")
		(net "SMB_INA230_3V3AUX_SCL")
	)
	(segment
		(start 153.096214 -45.902118)
		(end 151.94915 -45.902118)
		(width 0.127)
		(layer "In4.Cu")
		(net "SMB_INA230_3V3AUX_SCL")
	)
	(segment
		(start 180.42128 -41.265348)
		(end 167.1701 -41.265348)
		(width 0.127)
		(layer "In4.Cu")
		(net "SMB_INA230_3V3AUX_SCL")
	)
	(segment
		(start 199.19188 -43.170348)
		(end 197.79488 -44.567348)
		(width 0.127)
		(layer "In4.Cu")
		(net "SMB_INA230_3V3AUX_SCL")
	)
	(segment
		(start 214.81288 -44.917868)
		(end 213.06536 -43.170348)
		(width 0.127)
		(layer "In4.Cu")
		(net "SMB_INA230_3V3AUX_SCL")
	)
	(segment
		(start 162.624262 -45.811186)
		(end 162.44443 -45.811186)
		(width 0.127)
		(layer "In4.Cu")
		(net "SMB_INA230_3V3AUX_SCL")
	)
	(segment
		(start 162.149282 -45.516038)
		(end 161.96945 -45.516038)
		(width 0.127)
		(layer "In4.Cu")
		(net "SMB_INA230_3V3AUX_SCL")
	)
	(segment
		(start 161.995358 -46.260258)
		(end 161.995358 -46.44009)
		(width 0.127)
		(layer "In4.Cu")
		(net "SMB_INA230_3V3AUX_SCL")
	)
	(segment
		(start 214.81288 -46.065948)
		(end 214.81288 -44.917868)
		(width 0.127)
		(layer "In4.Cu")
		(net "SMB_INA230_3V3AUX_SCL")
	)
	(segment
		(start 118.305326 -133.424422)
		(end 116.84 -134.889748)
		(width 0.127)
		(layer "In6.Cu")
		(net "SMB_INA230_3V3AUX_SCL")
	)
	(segment
		(start 99.95281 -134.889748)
		(end 98.81108 -133.748018)
		(width 0.127)
		(layer "In6.Cu")
		(net "SMB_INA230_3V3AUX_SCL")
	)
	(segment
		(start 98.81108 -133.748018)
		(end 98.81108 -132.806948)
		(width 0.127)
		(layer "In6.Cu")
		(net "SMB_INA230_3V3AUX_SCL")
	)
	(segment
		(start 116.84 -134.889748)
		(end 99.95281 -134.889748)
		(width 0.127)
		(layer "In6.Cu")
		(net "SMB_INA230_3V3AUX_SCL")
	)
	(segment
		(start 133.27888 -133.424422)
		(end 118.305326 -133.424422)
		(width 0.127)
		(layer "In6.Cu")
		(net "SMB_INA230_3V3AUX_SCL")
	)
	(segment
		(start 148.690584 -44.994576)
		(end 150.4315 -43.25366)
		(width 0.127)
		(layer "In15.Cu")
		(net "SMB_INA230_3V3AUX_SCL")
	)
	(segment
		(start 149.713188 -42.355516)
		(end 149.982428 -42.624756)
		(width 0.127)
		(layer "In15.Cu")
		(net "SMB_INA230_3V3AUX_SCL")
	)
	(segment
		(start 149.533356 -42.355516)
		(end 149.713188 -42.355516)
		(width 0.127)
		(layer "In15.Cu")
		(net "SMB_INA230_3V3AUX_SCL")
	)
	(segment
		(start 145.85188 -39.334948)
		(end 146.35988 -38.826948)
		(width 0.127)
		(layer "In15.Cu")
		(net "SMB_INA230_3V3AUX_SCL")
	)
	(segment
		(start 87.715598 -36.807648)
		(end 88.857328 -35.665918)
		(width 0.127)
		(layer "In15.Cu")
		(net "SMB_INA230_3V3AUX_SCL")
	)
	(segment
		(start 137.46988 -38.953948)
		(end 137.85088 -38.572948)
		(width 0.127)
		(layer "In15.Cu")
		(net "SMB_INA230_3V3AUX_SCL")
	)
	(segment
		(start 149.084284 -41.906444)
		(end 147.343368 -43.64736)
		(width 0.127)
		(layer "In15.Cu")
		(net "SMB_INA230_3V3AUX_SCL")
	)
	(segment
		(start 148.16836 -40.810688)
		(end 149.084284 -41.726612)
		(width 0.127)
		(layer "In15.Cu")
		(net "SMB_INA230_3V3AUX_SCL")
	)
	(segment
		(start 149.084284 -41.726612)
		(end 149.084284 -41.906444)
		(width 0.127)
		(layer "In15.Cu")
		(net "SMB_INA230_3V3AUX_SCL")
	)
	(segment
		(start 121.96318 -35.665918)
		(end 125.25121 -38.953948)
		(width 0.127)
		(layer "In15.Cu")
		(net "SMB_INA230_3V3AUX_SCL")
	)
	(segment
		(start 142.54988 -39.334948)
		(end 145.85188 -39.334948)
		(width 0.127)
		(layer "In15.Cu")
		(net "SMB_INA230_3V3AUX_SCL")
	)
	(segment
		(start 148.241512 -44.545504)
		(end 148.241512 -44.725336)
		(width 0.127)
		(layer "In15.Cu")
		(net "SMB_INA230_3V3AUX_SCL")
	)
	(segment
		(start 150.611332 -43.25366)
		(end 151.29256 -43.934888)
		(width 0.127)
		(layer "In15.Cu")
		(net "SMB_INA230_3V3AUX_SCL")
	)
	(segment
		(start 147.81784 -38.826948)
		(end 148.16836 -39.177468)
		(width 0.127)
		(layer "In15.Cu")
		(net "SMB_INA230_3V3AUX_SCL")
	)
	(segment
		(start 151.29256 -45.245528)
		(end 151.58593 -45.538898)
		(width 0.127)
		(layer "In15.Cu")
		(net "SMB_INA230_3V3AUX_SCL")
	)
	(segment
		(start 125.25121 -38.953948)
		(end 137.46988 -38.953948)
		(width 0.127)
		(layer "In15.Cu")
		(net "SMB_INA230_3V3AUX_SCL")
	)
	(segment
		(start 147.343368 -43.64736)
		(end 147.343368 -43.827192)
		(width 0.127)
		(layer "In15.Cu")
		(net "SMB_INA230_3V3AUX_SCL")
	)
	(segment
		(start 147.343368 -43.827192)
		(end 147.612608 -44.096432)
		(width 0.127)
		(layer "In15.Cu")
		(net "SMB_INA230_3V3AUX_SCL")
	)
	(segment
		(start 137.85088 -38.572948)
		(end 141.78788 -38.572948)
		(width 0.127)
		(layer "In15.Cu")
		(net "SMB_INA230_3V3AUX_SCL")
	)
	(segment
		(start 88.857328 -35.665918)
		(end 121.96318 -35.665918)
		(width 0.127)
		(layer "In15.Cu")
		(net "SMB_INA230_3V3AUX_SCL")
	)
	(segment
		(start 149.982428 -42.624756)
		(end 149.982428 -42.804588)
		(width 0.127)
		(layer "In15.Cu")
		(net "SMB_INA230_3V3AUX_SCL")
	)
	(segment
		(start 150.4315 -43.25366)
		(end 150.611332 -43.25366)
		(width 0.127)
		(layer "In15.Cu")
		(net "SMB_INA230_3V3AUX_SCL")
	)
	(segment
		(start 148.16836 -39.177468)
		(end 148.16836 -40.810688)
		(width 0.127)
		(layer "In15.Cu")
		(net "SMB_INA230_3V3AUX_SCL")
	)
	(segment
		(start 79.62646 -37.097208)
		(end 81.853024 -37.097208)
		(width 0.127)
		(layer "In15.Cu")
		(net "SMB_INA230_3V3AUX_SCL")
	)
	(segment
		(start 75.3872 -35.499548)
		(end 78.0288 -35.499548)
		(width 0.127)
		(layer "In15.Cu")
		(net "SMB_INA230_3V3AUX_SCL")
	)
	(segment
		(start 147.79244 -44.096432)
		(end 149.533356 -42.355516)
		(width 0.127)
		(layer "In15.Cu")
		(net "SMB_INA230_3V3AUX_SCL")
	)
	(segment
		(start 148.510752 -44.994576)
		(end 148.690584 -44.994576)
		(width 0.127)
		(layer "In15.Cu")
		(net "SMB_INA230_3V3AUX_SCL")
	)
	(segment
		(start 147.612608 -44.096432)
		(end 147.79244 -44.096432)
		(width 0.127)
		(layer "In15.Cu")
		(net "SMB_INA230_3V3AUX_SCL")
	)
	(segment
		(start 82.142584 -36.807648)
		(end 87.715598 -36.807648)
		(width 0.127)
		(layer "In15.Cu")
		(net "SMB_INA230_3V3AUX_SCL")
	)
	(segment
		(start 151.29256 -43.934888)
		(end 151.29256 -45.245528)
		(width 0.127)
		(layer "In15.Cu")
		(net "SMB_INA230_3V3AUX_SCL")
	)
	(segment
		(start 141.78788 -38.572948)
		(end 142.54988 -39.334948)
		(width 0.127)
		(layer "In15.Cu")
		(net "SMB_INA230_3V3AUX_SCL")
	)
	(segment
		(start 148.241512 -44.725336)
		(end 148.510752 -44.994576)
		(width 0.127)
		(layer "In15.Cu")
		(net "SMB_INA230_3V3AUX_SCL")
	)
	(segment
		(start 149.982428 -42.804588)
		(end 148.241512 -44.545504)
		(width 0.127)
		(layer "In15.Cu")
		(net "SMB_INA230_3V3AUX_SCL")
	)
	(segment
		(start 78.0288 -35.499548)
		(end 79.62646 -37.097208)
		(width 0.127)
		(layer "In15.Cu")
		(net "SMB_INA230_3V3AUX_SCL")
	)
	(segment
		(start 146.35988 -38.826948)
		(end 147.81784 -38.826948)
		(width 0.127)
		(layer "In15.Cu")
		(net "SMB_INA230_3V3AUX_SCL")
	)
	(segment
		(start 81.853024 -37.097208)
		(end 82.142584 -36.807648)
		(width 0.127)
		(layer "In15.Cu")
		(net "SMB_INA230_3V3AUX_SCL")
	)
	(segment
		(start 213.06028 -52.545488)
		(end 213.507574 -53.625242)
		(width 0.12954)
		(layer "F.Cu")
		(net "SMB_INA230_2_3V3AUX_SDA_R1")
	)
	(segment
		(start 213.41588 -51.037998)
		(end 213.06028 -51.393598)
		(width 0.12954)
		(layer "F.Cu")
		(net "SMB_INA230_2_3V3AUX_SDA_R1")
	)
	(segment
		(start 213.507574 -53.625242)
		(end 213.587584 -53.705252)
		(width 0.12954)
		(layer "F.Cu")
		(net "SMB_INA230_2_3V3AUX_SDA_R1")
	)
	(segment
		(start 213.06028 -51.393598)
		(end 213.06028 -52.545488)
		(width 0.12954)
		(layer "F.Cu")
		(net "SMB_INA230_2_3V3AUX_SDA_R1")
	)
	(segment
		(start 213.587584 -53.705252)
		(end 213.859618 -53.705252)
		(width 0.12954)
		(layer "F.Cu")
		(net "SMB_INA230_2_3V3AUX_SDA_R1")
	)
	(via
		(at 213.06028 -52.545488)
		(size 0.508)
		(drill 0.254)
		(layers "F.Cu" "B.Cu")
		(net "SMB_INA230_2_3V3AUX_SDA_R1")
	)
	(segment
		(start 213.06028 -52.545488)
		(end 213.79688 -53.282088)
		(width 0.12954)
		(layer "B.Cu")
		(net "SMB_INA230_2_3V3AUX_SDA_R1")
	)
	(segment
		(start 213.79688 -53.282088)
		(end 213.79688 -54.047898)
		(width 0.12954)
		(layer "B.Cu")
		(net "SMB_INA230_2_3V3AUX_SDA_R1")
	)
	(segment
		(start 213.16188 -47.989998)
		(end 213.16188 -48.986948)
		(width 0.12954)
		(layer "F.Cu")
		(net "SMB_INA230_2_3V3AUX_SDA_R")
	)
	(segment
		(start 213.41588 -47.735998)
		(end 213.16188 -47.989998)
		(width 0.12954)
		(layer "F.Cu")
		(net "SMB_INA230_2_3V3AUX_SDA_R")
	)
	(segment
		(start 213.16188 -48.986948)
		(end 213.16188 -49.983898)
		(width 0.12954)
		(layer "F.Cu")
		(net "SMB_INA230_2_3V3AUX_SDA_R")
	)
	(segment
		(start 213.16188 -49.983898)
		(end 213.41588 -50.237898)
		(width 0.12954)
		(layer "F.Cu")
		(net "SMB_INA230_2_3V3AUX_SDA_R")
	)
	(via
		(at 213.16188 -48.986948)
		(size 0.762)
		(drill 0.381)
		(layers "F.Cu" "B.Cu")
		(net "SMB_INA230_2_3V3AUX_SDA_R")
	)
	(segment
		(start 214.509604 -52.061872)
		(end 214.509604 -51.536346)
		(width 0.12954)
		(layer "F.Cu")
		(net "SMB_INA230_2_3V3AUX_SCL_R1")
	)
	(segment
		(start 214.509604 -51.536346)
		(end 214.43188 -51.458622)
		(width 0.12954)
		(layer "F.Cu")
		(net "SMB_INA230_2_3V3AUX_SCL_R1")
	)
	(segment
		(start 214.43188 -51.458622)
		(end 214.43188 -51.037998)
		(width 0.12954)
		(layer "F.Cu")
		(net "SMB_INA230_2_3V3AUX_SCL_R1")
	)
	(segment
		(start 214.509604 -53.055266)
		(end 214.509604 -52.061872)
		(width 0.12954)
		(layer "F.Cu")
		(net "SMB_INA230_2_3V3AUX_SCL_R1")
	)
	(via
		(at 214.509604 -52.061872)
		(size 0.508)
		(drill 0.254)
		(layers "F.Cu" "B.Cu")
		(net "SMB_INA230_2_3V3AUX_SCL_R1")
	)
	(segment
		(start 214.68588 -47.989998)
		(end 214.68588 -48.986948)
		(width 0.12954)
		(layer "F.Cu")
		(net "SMB_INA230_2_3V3AUX_SCL_R")
	)
	(segment
		(start 214.68588 -48.986948)
		(end 214.68588 -49.983898)
		(width 0.12954)
		(layer "F.Cu")
		(net "SMB_INA230_2_3V3AUX_SCL_R")
	)
	(segment
		(start 214.68588 -49.983898)
		(end 214.43188 -50.237898)
		(width 0.12954)
		(layer "F.Cu")
		(net "SMB_INA230_2_3V3AUX_SCL_R")
	)
	(segment
		(start 214.43188 -47.735998)
		(end 214.68588 -47.989998)
		(width 0.12954)
		(layer "F.Cu")
		(net "SMB_INA230_2_3V3AUX_SCL_R")
	)
	(via
		(at 214.68588 -48.986948)
		(size 0.762)
		(drill 0.381)
		(layers "F.Cu" "B.Cu")
		(net "SMB_INA230_2_3V3AUX_SCL_R")
	)
	(segment
		(start 442.52388 -95.291148)
		(end 442.52388 -94.986348)
		(width 0.12954)
		(layer "F.Cu")
		(net "SMB_INA230_1_3V3AUX_SDA_R1")
	)
	(segment
		(start 443.10554 -95.872808)
		(end 442.52388 -95.291148)
		(width 0.12954)
		(layer "F.Cu")
		(net "SMB_INA230_1_3V3AUX_SDA_R1")
	)
	(segment
		(start 442.52388 -94.986348)
		(end 442.36513 -94.827598)
		(width 0.12954)
		(layer "F.Cu")
		(net "SMB_INA230_1_3V3AUX_SDA_R1")
	)
	(segment
		(start 442.36513 -94.827598)
		(end 442.088016 -94.827598)
		(width 0.12954)
		(layer "F.Cu")
		(net "SMB_INA230_1_3V3AUX_SDA_R1")
	)
	(segment
		(start 444.79083 -95.872808)
		(end 443.10554 -95.872808)
		(width 0.12954)
		(layer "F.Cu")
		(net "SMB_INA230_1_3V3AUX_SDA_R1")
	)
	(via
		(at 443.10554 -95.872808)
		(size 0.508)
		(drill 0.254)
		(layers "F.Cu" "B.Cu")
		(net "SMB_INA230_1_3V3AUX_SDA_R1")
	)
	(segment
		(start 446.84188 -95.872808)
		(end 448.21983 -95.872808)
		(width 0.12954)
		(layer "F.Cu")
		(net "SMB_INA230_1_3V3AUX_SDA_R")
	)
	(segment
		(start 445.59093 -95.872808)
		(end 446.84188 -95.872808)
		(width 0.12954)
		(layer "F.Cu")
		(net "SMB_INA230_1_3V3AUX_SDA_R")
	)
	(via
		(at 446.84188 -95.872808)
		(size 0.762)
		(drill 0.381)
		(layers "F.Cu" "B.Cu")
		(net "SMB_INA230_1_3V3AUX_SDA_R")
	)
	(segment
		(start 443.07252 -97.254568)
		(end 444.77559 -97.254568)
		(width 0.12954)
		(layer "F.Cu")
		(net "SMB_INA230_1_3V3AUX_SCL_R1")
	)
	(segment
		(start 441.43803 -95.477584)
		(end 441.43803 -95.861378)
		(width 0.12954)
		(layer "F.Cu")
		(net "SMB_INA230_1_3V3AUX_SCL_R1")
	)
	(segment
		(start 444.77559 -97.254568)
		(end 444.79083 -97.269808)
		(width 0.12954)
		(layer "F.Cu")
		(net "SMB_INA230_1_3V3AUX_SCL_R1")
	)
	(segment
		(start 441.43803 -95.861378)
		(end 442.83122 -97.254568)
		(width 0.12954)
		(layer "F.Cu")
		(net "SMB_INA230_1_3V3AUX_SCL_R1")
	)
	(segment
		(start 442.83122 -97.254568)
		(end 443.07252 -97.254568)
		(width 0.12954)
		(layer "F.Cu")
		(net "SMB_INA230_1_3V3AUX_SCL_R1")
	)
	(via
		(at 443.07252 -97.254568)
		(size 0.508)
		(drill 0.254)
		(layers "F.Cu" "B.Cu")
		(net "SMB_INA230_1_3V3AUX_SCL_R1")
	)
	(segment
		(start 216.27719 -46.778164)
		(end 215.986614 -46.487588)
		(width 0.12954)
		(layer "F.Cu")
		(net "SMB_INA230_1_3V3AUX_SCL_R")
	)
	(segment
		(start 216.27719 -47.196248)
		(end 216.27719 -46.778164)
		(width 0.12954)
		(layer "F.Cu")
		(net "SMB_INA230_1_3V3AUX_SCL_R")
	)
	(segment
		(start 445.59093 -97.269808)
		(end 446.84188 -97.269808)
		(width 0.12954)
		(layer "F.Cu")
		(net "SMB_INA230_1_3V3AUX_SCL_R")
	)
	(segment
		(start 215.52154 -46.487588)
		(end 215.48344 -46.449488)
		(width 0.12954)
		(layer "F.Cu")
		(net "SMB_INA230_1_3V3AUX_SCL_R")
	)
	(segment
		(start 446.84188 -97.269808)
		(end 449.63588 -97.269808)
		(width 0.12954)
		(layer "F.Cu")
		(net "SMB_INA230_1_3V3AUX_SCL_R")
	)
	(segment
		(start 215.986614 -46.487588)
		(end 215.52154 -46.487588)
		(width 0.12954)
		(layer "F.Cu")
		(net "SMB_INA230_1_3V3AUX_SCL_R")
	)
	(via
		(at 449.63588 -97.269808)
		(size 0.508)
		(drill 0.254)
		(layers "F.Cu" "B.Cu")
		(net "SMB_INA230_1_3V3AUX_SCL_R")
	)
	(via
		(at 328.041 -79.466948)
		(size 0.508)
		(drill 0.254)
		(layers "F.Cu" "B.Cu")
		(net "SMB_INA230_1_3V3AUX_SCL_R")
	)
	(via
		(at 215.48344 -46.449488)
		(size 0.508)
		(drill 0.254)
		(layers "F.Cu" "B.Cu")
		(net "SMB_INA230_1_3V3AUX_SCL_R")
	)
	(via
		(at 446.84188 -97.269808)
		(size 0.762)
		(drill 0.381)
		(layers "F.Cu" "B.Cu")
		(net "SMB_INA230_1_3V3AUX_SCL_R")
	)
	(segment
		(start 220.039692 -51.304444)
		(end 220.308932 -51.573684)
		(width 0.127)
		(layer "In4.Cu")
		(net "SMB_INA230_1_3V3AUX_SCL_R")
	)
	(segment
		(start 215.44026 -47.429928)
		(end 219.497402 -51.48707)
		(width 0.127)
		(layer "In4.Cu")
		(net "SMB_INA230_1_3V3AUX_SCL_R")
	)
	(segment
		(start 325.73468 -81.397348)
		(end 327.66508 -79.466948)
		(width 0.127)
		(layer "In4.Cu")
		(net "SMB_INA230_1_3V3AUX_SCL_R")
	)
	(segment
		(start 220.126306 -51.936142)
		(end 220.126306 -52.115974)
		(width 0.127)
		(layer "In4.Cu")
		(net "SMB_INA230_1_3V3AUX_SCL_R")
	)
	(segment
		(start 219.497402 -51.48707)
		(end 219.677234 -51.48707)
		(width 0.127)
		(layer "In4.Cu")
		(net "SMB_INA230_1_3V3AUX_SCL_R")
	)
	(segment
		(start 237.123224 -70.551548)
		(end 238.913924 -70.551548)
		(width 0.127)
		(layer "In4.Cu")
		(net "SMB_INA230_1_3V3AUX_SCL_R")
	)
	(segment
		(start 265.51382 -85.414866)
		(end 302.821848 -85.414866)
		(width 0.127)
		(layer "In4.Cu")
		(net "SMB_INA230_1_3V3AUX_SCL_R")
	)
	(segment
		(start 215.48344 -46.449488)
		(end 215.44026 -46.492668)
		(width 0.127)
		(layer "In4.Cu")
		(net "SMB_INA230_1_3V3AUX_SCL_R")
	)
	(segment
		(start 220.308932 -51.573684)
		(end 220.308932 -51.753516)
		(width 0.127)
		(layer "In4.Cu")
		(net "SMB_INA230_1_3V3AUX_SCL_R")
	)
	(segment
		(start 219.85986 -51.304444)
		(end 220.039692 -51.304444)
		(width 0.127)
		(layer "In4.Cu")
		(net "SMB_INA230_1_3V3AUX_SCL_R")
	)
	(segment
		(start 255.814576 -81.397348)
		(end 265.51382 -85.414866)
		(width 0.127)
		(layer "In4.Cu")
		(net "SMB_INA230_1_3V3AUX_SCL_R")
	)
	(segment
		(start 223.44888 -56.877204)
		(end 237.123224 -70.551548)
		(width 0.127)
		(layer "In4.Cu")
		(net "SMB_INA230_1_3V3AUX_SCL_R")
	)
	(segment
		(start 312.521092 -81.397348)
		(end 325.73468 -81.397348)
		(width 0.127)
		(layer "In4.Cu")
		(net "SMB_INA230_1_3V3AUX_SCL_R")
	)
	(segment
		(start 219.677234 -51.48707)
		(end 219.85986 -51.304444)
		(width 0.127)
		(layer "In4.Cu")
		(net "SMB_INA230_1_3V3AUX_SCL_R")
	)
	(segment
		(start 302.821848 -85.414866)
		(end 312.521092 -81.397348)
		(width 0.127)
		(layer "In4.Cu")
		(net "SMB_INA230_1_3V3AUX_SCL_R")
	)
	(segment
		(start 215.44026 -46.492668)
		(end 215.44026 -47.429928)
		(width 0.127)
		(layer "In4.Cu")
		(net "SMB_INA230_1_3V3AUX_SCL_R")
	)
	(segment
		(start 220.126306 -52.115974)
		(end 223.44888 -55.438548)
		(width 0.127)
		(layer "In4.Cu")
		(net "SMB_INA230_1_3V3AUX_SCL_R")
	)
	(segment
		(start 253.826264 -81.397348)
		(end 255.814576 -81.397348)
		(width 0.127)
		(layer "In4.Cu")
		(net "SMB_INA230_1_3V3AUX_SCL_R")
	)
	(segment
		(start 220.308932 -51.753516)
		(end 220.126306 -51.936142)
		(width 0.127)
		(layer "In4.Cu")
		(net "SMB_INA230_1_3V3AUX_SCL_R")
	)
	(segment
		(start 246.88419 -78.521814)
		(end 253.826264 -81.397348)
		(width 0.127)
		(layer "In4.Cu")
		(net "SMB_INA230_1_3V3AUX_SCL_R")
	)
	(segment
		(start 238.913924 -70.551548)
		(end 246.88419 -78.521814)
		(width 0.127)
		(layer "In4.Cu")
		(net "SMB_INA230_1_3V3AUX_SCL_R")
	)
	(segment
		(start 223.44888 -55.438548)
		(end 223.44888 -56.877204)
		(width 0.127)
		(layer "In4.Cu")
		(net "SMB_INA230_1_3V3AUX_SCL_R")
	)
	(segment
		(start 327.66508 -79.466948)
		(end 328.041 -79.466948)
		(width 0.127)
		(layer "In4.Cu")
		(net "SMB_INA230_1_3V3AUX_SCL_R")
	)
	(segment
		(start 436.70601 -84.775548)
		(end 435.74081 -85.740748)
		(width 0.127)
		(layer "In6.Cu")
		(net "SMB_INA230_1_3V3AUX_SCL_R")
	)
	(segment
		(start 352.70948 -55.143908)
		(end 346.51696 -55.143908)
		(width 0.127)
		(layer "In6.Cu")
		(net "SMB_INA230_1_3V3AUX_SCL_R")
	)
	(segment
		(start 362.59008 -81.601818)
		(end 362.59008 -73.344278)
		(width 0.127)
		(layer "In6.Cu")
		(net "SMB_INA230_1_3V3AUX_SCL_R")
	)
	(segment
		(start 452.30288 -85.942678)
		(end 451.13575 -84.775548)
		(width 0.127)
		(layer "In6.Cu")
		(net "SMB_INA230_1_3V3AUX_SCL_R")
	)
	(segment
		(start 356.14356 -58.157364)
		(end 356.14356 -57.267348)
		(width 0.127)
		(layer "In6.Cu")
		(net "SMB_INA230_1_3V3AUX_SCL_R")
	)
	(segment
		(start 344.24366 -62.121288)
		(end 340.5124 -65.852548)
		(width 0.127)
		(layer "In6.Cu")
		(net "SMB_INA230_1_3V3AUX_SCL_R")
	)
	(segment
		(start 357.971344 -58.827924)
		(end 356.81412 -58.827924)
		(width 0.127)
		(layer "In6.Cu")
		(net "SMB_INA230_1_3V3AUX_SCL_R")
	)
	(segment
		(start 355.25964 -56.383428)
		(end 353.949 -56.383428)
		(width 0.127)
		(layer "In6.Cu")
		(net "SMB_INA230_1_3V3AUX_SCL_R")
	)
	(segment
		(start 358.62006 -69.374258)
		(end 358.62006 -59.47664)
		(width 0.127)
		(layer "In6.Cu")
		(net "SMB_INA230_1_3V3AUX_SCL_R")
	)
	(segment
		(start 362.59008 -73.344278)
		(end 358.62006 -69.374258)
		(width 0.127)
		(layer "In6.Cu")
		(net "SMB_INA230_1_3V3AUX_SCL_R")
	)
	(segment
		(start 331.500988 -71.05396)
		(end 329.695302 -72.859646)
		(width 0.127)
		(layer "In6.Cu")
		(net "SMB_INA230_1_3V3AUX_SCL_R")
	)
	(segment
		(start 344.24366 -57.417208)
		(end 344.24366 -62.121288)
		(width 0.127)
		(layer "In6.Cu")
		(net "SMB_INA230_1_3V3AUX_SCL_R")
	)
	(segment
		(start 366.72901 -85.740748)
		(end 362.59008 -81.601818)
		(width 0.127)
		(layer "In6.Cu")
		(net "SMB_INA230_1_3V3AUX_SCL_R")
	)
	(segment
		(start 449.63588 -97.269808)
		(end 452.30288 -94.602808)
		(width 0.127)
		(layer "In6.Cu")
		(net "SMB_INA230_1_3V3AUX_SCL_R")
	)
	(segment
		(start 329.695302 -72.859646)
		(end 329.695302 -78.243938)
		(width 0.127)
		(layer "In6.Cu")
		(net "SMB_INA230_1_3V3AUX_SCL_R")
	)
	(segment
		(start 340.5124 -67.77228)
		(end 337.23072 -71.05396)
		(width 0.127)
		(layer "In6.Cu")
		(net "SMB_INA230_1_3V3AUX_SCL_R")
	)
	(segment
		(start 337.23072 -71.05396)
		(end 331.500988 -71.05396)
		(width 0.127)
		(layer "In6.Cu")
		(net "SMB_INA230_1_3V3AUX_SCL_R")
	)
	(segment
		(start 435.74081 -85.740748)
		(end 366.72901 -85.740748)
		(width 0.127)
		(layer "In6.Cu")
		(net "SMB_INA230_1_3V3AUX_SCL_R")
	)
	(segment
		(start 356.14356 -57.267348)
		(end 355.25964 -56.383428)
		(width 0.127)
		(layer "In6.Cu")
		(net "SMB_INA230_1_3V3AUX_SCL_R")
	)
	(segment
		(start 328.472292 -79.466948)
		(end 328.041 -79.466948)
		(width 0.127)
		(layer "In6.Cu")
		(net "SMB_INA230_1_3V3AUX_SCL_R")
	)
	(segment
		(start 358.62006 -59.47664)
		(end 357.971344 -58.827924)
		(width 0.127)
		(layer "In6.Cu")
		(net "SMB_INA230_1_3V3AUX_SCL_R")
	)
	(segment
		(start 353.949 -56.383428)
		(end 352.70948 -55.143908)
		(width 0.127)
		(layer "In6.Cu")
		(net "SMB_INA230_1_3V3AUX_SCL_R")
	)
	(segment
		(start 356.81412 -58.827924)
		(end 356.14356 -58.157364)
		(width 0.127)
		(layer "In6.Cu")
		(net "SMB_INA230_1_3V3AUX_SCL_R")
	)
	(segment
		(start 451.13575 -84.775548)
		(end 436.70601 -84.775548)
		(width 0.127)
		(layer "In6.Cu")
		(net "SMB_INA230_1_3V3AUX_SCL_R")
	)
	(segment
		(start 346.51696 -55.143908)
		(end 344.24366 -57.417208)
		(width 0.127)
		(layer "In6.Cu")
		(net "SMB_INA230_1_3V3AUX_SCL_R")
	)
	(segment
		(start 340.5124 -65.852548)
		(end 340.5124 -67.77228)
		(width 0.127)
		(layer "In6.Cu")
		(net "SMB_INA230_1_3V3AUX_SCL_R")
	)
	(segment
		(start 452.30288 -94.602808)
		(end 452.30288 -85.942678)
		(width 0.127)
		(layer "In6.Cu")
		(net "SMB_INA230_1_3V3AUX_SCL_R")
	)
	(segment
		(start 329.695302 -78.243938)
		(end 328.472292 -79.466948)
		(width 0.127)
		(layer "In6.Cu")
		(net "SMB_INA230_1_3V3AUX_SCL_R")
	)
	(segment
		(start 144.94383 -42.446448)
		(end 144.33423 -42.446448)
		(width 0.381)
		(layer "F.Cu")
		(net "P3V3_M2_0")
	)
	(via
		(at 165.91534 -54.18328)
		(size 0.762)
		(drill 0.381)
		(layers "F.Cu" "B.Cu")
		(net "P3V3_M2_0")
	)
	(via
		(at 167.60952 -52.898548)
		(size 0.508)
		(drill 0.254)
		(layers "F.Cu" "B.Cu")
		(net "P3V3_M2_0")
	)
	(via
		(at 168.37152 -38.077648)
		(size 0.508)
		(drill 0.254)
		(layers "F.Cu" "B.Cu")
		(net "P3V3_M2_0")
	)
	(via
		(at 168.34612 -52.796948)
		(size 0.508)
		(drill 0.254)
		(layers "F.Cu" "B.Cu")
		(net "P3V3_M2_0")
	)
	(via
		(at 168.34612 -52.161948)
		(size 0.508)
		(drill 0.254)
		(layers "F.Cu" "B.Cu")
		(net "P3V3_M2_0")
	)
	(via
		(at 167.60952 -53.533548)
		(size 0.508)
		(drill 0.254)
		(layers "F.Cu" "B.Cu")
		(net "P3V3_M2_0")
	)
	(via
		(at 165.91534 -50.62728)
		(size 0.762)
		(drill 0.381)
		(layers "F.Cu" "B.Cu")
		(net "P3V3_M2_0")
	)
	(via
		(at 168.34612 -53.431948)
		(size 0.508)
		(drill 0.254)
		(layers "F.Cu" "B.Cu")
		(net "P3V3_M2_0")
	)
	(via
		(at 144.33423 -42.446448)
		(size 0.508)
		(drill 0.254)
		(layers "F.Cu" "B.Cu")
		(net "P3V3_M2_0")
	)
	(via
		(at 165.91534 -52.40528)
		(size 0.762)
		(drill 0.381)
		(layers "F.Cu" "B.Cu")
		(net "P3V3_M2_0")
	)
	(via
		(at 169.0751 -37.513768)
		(size 0.508)
		(drill 0.254)
		(layers "F.Cu" "B.Cu")
		(net "P3V3_M2_0")
	)
	(via
		(at 159.87522 -50.98034)
		(size 0.762)
		(drill 0.381)
		(layers "F.Cu" "B.Cu")
		(net "P3V3_M2_0")
	)
	(via
		(at 167.60952 -52.263548)
		(size 0.508)
		(drill 0.254)
		(layers "F.Cu" "B.Cu")
		(net "P3V3_M2_0")
	)
	(via
		(at 168.37152 -37.315648)
		(size 0.508)
		(drill 0.254)
		(layers "F.Cu" "B.Cu")
		(net "P3V3_M2_0")
	)
	(via
		(at 167.76446 -50.843688)
		(size 0.6604)
		(drill 0.3302)
		(layers "F.Cu" "B.Cu")
		(net "P3V3_M2_0")
	)
	(segment
		(start 168.34612 -52.161948)
		(end 166.30904 -50.124868)
		(width 0.381)
		(layer "In4.Cu")
		(net "P3V3_M2_0")
	)
	(segment
		(start 152.38984 -50.124868)
		(end 144.71142 -42.446448)
		(width 0.381)
		(layer "In4.Cu")
		(net "P3V3_M2_0")
	)
	(segment
		(start 166.30904 -50.124868)
		(end 152.38984 -50.124868)
		(width 0.381)
		(layer "In4.Cu")
		(net "P3V3_M2_0")
	)
	(segment
		(start 144.71142 -42.446448)
		(end 144.33423 -42.446448)
		(width 0.381)
		(layer "In4.Cu")
		(net "P3V3_M2_0")
	)
	(segment
		(start 237.023402 -58.164984)
		(end 237.18393 -58.004456)
		(width 0.13208)
		(layer "F.Cu")
		(net "P3E_PCH_E1S_TX_C_DP<3>")
	)
	(segment
		(start 237.18393 -58.004456)
		(end 238.56315 -58.004456)
		(width 0.13208)
		(layer "F.Cu")
		(net "P3E_PCH_E1S_TX_C_DP<3>")
	)
	(segment
		(start 238.56315 -58.004456)
		(end 238.885984 -58.32729)
		(width 0.13208)
		(layer "F.Cu")
		(net "P3E_PCH_E1S_TX_C_DP<3>")
	)
	(segment
		(start 236.599984 -58.164984)
		(end 237.023402 -58.164984)
		(width 0.13208)
		(layer "F.Cu")
		(net "P3E_PCH_E1S_TX_C_DP<3>")
	)
	(segment
		(start 236.599984 -56.364886)
		(end 237.08106 -56.364886)
		(width 0.13208)
		(layer "F.Cu")
		(net "P3E_PCH_E1S_TX_C_DP<2>")
	)
	(segment
		(start 240.265204 -56.204612)
		(end 240.587784 -56.527192)
		(width 0.13208)
		(layer "F.Cu")
		(net "P3E_PCH_E1S_TX_C_DP<2>")
	)
	(segment
		(start 237.08106 -56.364886)
		(end 237.241334 -56.204612)
		(width 0.13208)
		(layer "F.Cu")
		(net "P3E_PCH_E1S_TX_C_DP<2>")
	)
	(segment
		(start 237.241334 -56.204612)
		(end 240.265204 -56.204612)
		(width 0.13208)
		(layer "F.Cu")
		(net "P3E_PCH_E1S_TX_C_DP<2>")
	)
	(segment
		(start 236.599984 -53.965094)
		(end 237.002574 -53.965094)
		(width 0.13208)
		(layer "F.Cu")
		(net "P3E_PCH_E1S_TX_C_DP<1>")
	)
	(segment
		(start 238.562388 -54.145434)
		(end 238.885984 -53.821838)
		(width 0.13208)
		(layer "F.Cu")
		(net "P3E_PCH_E1S_TX_C_DP<1>")
	)
	(segment
		(start 237.182914 -54.145434)
		(end 238.562388 -54.145434)
		(width 0.13208)
		(layer "F.Cu")
		(net "P3E_PCH_E1S_TX_C_DP<1>")
	)
	(segment
		(start 237.002574 -53.965094)
		(end 237.182914 -54.145434)
		(width 0.13208)
		(layer "F.Cu")
		(net "P3E_PCH_E1S_TX_C_DP<1>")
	)
	(segment
		(start 238.553498 -52.345336)
		(end 238.885984 -52.01285)
		(width 0.13208)
		(layer "F.Cu")
		(net "P3E_PCH_E1S_TX_C_DP<0>")
	)
	(segment
		(start 237.00105 -52.164996)
		(end 237.18139 -52.345336)
		(width 0.13208)
		(layer "F.Cu")
		(net "P3E_PCH_E1S_TX_C_DP<0>")
	)
	(segment
		(start 237.18139 -52.345336)
		(end 238.553498 -52.345336)
		(width 0.13208)
		(layer "F.Cu")
		(net "P3E_PCH_E1S_TX_C_DP<0>")
	)
	(segment
		(start 236.599984 -52.164996)
		(end 237.00105 -52.164996)
		(width 0.13208)
		(layer "F.Cu")
		(net "P3E_PCH_E1S_TX_C_DP<0>")
	)
	(segment
		(start 236.599984 -57.565036)
		(end 237.00867 -57.565036)
		(width 0.13208)
		(layer "F.Cu")
		(net "P3E_PCH_E1S_TX_C_DN<3>")
	)
	(segment
		(start 238.553498 -57.745376)
		(end 238.885984 -57.41289)
		(width 0.13208)
		(layer "F.Cu")
		(net "P3E_PCH_E1S_TX_C_DN<3>")
	)
	(segment
		(start 237.18901 -57.745376)
		(end 238.553498 -57.745376)
		(width 0.13208)
		(layer "F.Cu")
		(net "P3E_PCH_E1S_TX_C_DN<3>")
	)
	(segment
		(start 237.00867 -57.565036)
		(end 237.18901 -57.745376)
		(width 0.13208)
		(layer "F.Cu")
		(net "P3E_PCH_E1S_TX_C_DN<3>")
	)
	(segment
		(start 237.225586 -55.945532)
		(end 240.255044 -55.945532)
		(width 0.13208)
		(layer "F.Cu")
		(net "P3E_PCH_E1S_TX_C_DN<2>")
	)
	(segment
		(start 236.599984 -55.764938)
		(end 237.044992 -55.764938)
		(width 0.13208)
		(layer "F.Cu")
		(net "P3E_PCH_E1S_TX_C_DN<2>")
	)
	(segment
		(start 237.044992 -55.764938)
		(end 237.225586 -55.945532)
		(width 0.13208)
		(layer "F.Cu")
		(net "P3E_PCH_E1S_TX_C_DN<2>")
	)
	(segment
		(start 240.255044 -55.945532)
		(end 240.587784 -55.612792)
		(width 0.13208)
		(layer "F.Cu")
		(net "P3E_PCH_E1S_TX_C_DN<2>")
	)
	(segment
		(start 237.179866 -54.404514)
		(end 238.55426 -54.404514)
		(width 0.13208)
		(layer "F.Cu")
		(net "P3E_PCH_E1S_TX_C_DN<1>")
	)
	(segment
		(start 237.019338 -54.565042)
		(end 237.179866 -54.404514)
		(width 0.13208)
		(layer "F.Cu")
		(net "P3E_PCH_E1S_TX_C_DN<1>")
	)
	(segment
		(start 236.599984 -54.565042)
		(end 237.019338 -54.565042)
		(width 0.13208)
		(layer "F.Cu")
		(net "P3E_PCH_E1S_TX_C_DN<1>")
	)
	(segment
		(start 238.55426 -54.404514)
		(end 238.885984 -54.736238)
		(width 0.13208)
		(layer "F.Cu")
		(net "P3E_PCH_E1S_TX_C_DN<1>")
	)
	(segment
		(start 237.023402 -52.764944)
		(end 237.18393 -52.604416)
		(width 0.13208)
		(layer "F.Cu")
		(net "P3E_PCH_E1S_TX_C_DN<0>")
	)
	(segment
		(start 236.599984 -52.764944)
		(end 237.023402 -52.764944)
		(width 0.13208)
		(layer "F.Cu")
		(net "P3E_PCH_E1S_TX_C_DN<0>")
	)
	(segment
		(start 237.18393 -52.604416)
		(end 238.56315 -52.604416)
		(width 0.13208)
		(layer "F.Cu")
		(net "P3E_PCH_E1S_TX_C_DN<0>")
	)
	(segment
		(start 238.56315 -52.604416)
		(end 238.885984 -52.92725)
		(width 0.13208)
		(layer "F.Cu")
		(net "P3E_PCH_E1S_TX_C_DN<0>")
	)
	(segment
		(start 69.863462 -37.770562)
		(end 69.863462 -38.024816)
		(width 0.12954)
		(layer "F.Cu")
		(net "OCP_V3_2_P3V3_ADC_ALERT_R")
	)
	(segment
		(start 68.612512 -37.389562)
		(end 68.61175 -37.3888)
		(width 0.12954)
		(layer "F.Cu")
		(net "OCP_V3_2_P3V3_ADC_ALERT_R")
	)
	(segment
		(start 69.863462 -38.024816)
		(end 70.908672 -39.070026)
		(width 0.12954)
		(layer "F.Cu")
		(net "OCP_V3_2_P3V3_ADC_ALERT_R")
	)
	(segment
		(start 68.61175 -37.3888)
		(end 68.61175 -36.294568)
		(width 0.12954)
		(layer "F.Cu")
		(net "OCP_V3_2_P3V3_ADC_ALERT_R")
	)
	(segment
		(start 68.612512 -37.389562)
		(end 69.228462 -37.389562)
		(width 0.12954)
		(layer "F.Cu")
		(net "OCP_V3_2_P3V3_ADC_ALERT_R")
	)
	(segment
		(start 69.609462 -37.770562)
		(end 69.863462 -37.770562)
		(width 0.12954)
		(layer "F.Cu")
		(net "OCP_V3_2_P3V3_ADC_ALERT_R")
	)
	(segment
		(start 69.228462 -37.389562)
		(end 69.609462 -37.770562)
		(width 0.12954)
		(layer "F.Cu")
		(net "OCP_V3_2_P3V3_ADC_ALERT_R")
	)
	(segment
		(start 70.908672 -39.070026)
		(end 71.308214 -39.070026)
		(width 0.12954)
		(layer "F.Cu")
		(net "OCP_V3_2_P3V3_ADC_ALERT_R")
	)
	(via
		(at 69.863462 -37.770562)
		(size 0.762)
		(drill 0.381)
		(layers "F.Cu" "B.Cu")
		(net "OCP_V3_2_P3V3_ADC_ALERT_R")
	)
	(segment
		(start 67.812412 -37.389562)
		(end 67.172586 -37.389562)
		(width 0.12954)
		(layer "F.Cu")
		(net "OCP_V3_2_P3V3_ADC_ALERT")
	)
	(segment
		(start 67.172586 -37.389562)
		(end 66.1924 -38.369748)
		(width 0.12954)
		(layer "F.Cu")
		(net "OCP_V3_2_P3V3_ADC_ALERT")
	)
	(segment
		(start 177.355754 -118.575328)
		(end 176.955704 -118.975378)
		(width 0.12954)
		(layer "F.Cu")
		(net "OCP_V3_2_P3V3_ADC_ALERT")
	)
	(via
		(at 150.19274 -55.773828)
		(size 0.508)
		(drill 0.254)
		(layers "F.Cu" "B.Cu")
		(net "OCP_V3_2_P3V3_ADC_ALERT")
	)
	(via
		(at 66.1924 -38.369748)
		(size 0.508)
		(drill 0.254)
		(layers "F.Cu" "B.Cu")
		(net "OCP_V3_2_P3V3_ADC_ALERT")
	)
	(via
		(at 176.955704 -118.975378)
		(size 0.4572)
		(drill 0.254)
		(layers "F.Cu" "B.Cu")
		(net "OCP_V3_2_P3V3_ADC_ALERT")
	)
	(segment
		(start 171.75988 -117.958108)
		(end 171.75988 -118.361968)
		(width 0.127)
		(layer "In2.Cu")
		(net "OCP_V3_2_P3V3_ADC_ALERT")
	)
	(segment
		(start 149.171406 -68.70827)
		(end 149.171406 -56.795162)
		(width 0.127)
		(layer "In2.Cu")
		(net "OCP_V3_2_P3V3_ADC_ALERT")
	)
	(segment
		(start 169.3926 -118.585488)
		(end 168.03116 -117.224048)
		(width 0.127)
		(layer "In2.Cu")
		(net "OCP_V3_2_P3V3_ADC_ALERT")
	)
	(segment
		(start 157.11932 -97.658428)
		(end 159.016446 -95.761302)
		(width 0.127)
		(layer "In2.Cu")
		(net "OCP_V3_2_P3V3_ADC_ALERT")
	)
	(segment
		(start 158.44012 -104.016048)
		(end 157.11932 -102.695248)
		(width 0.127)
		(layer "In2.Cu")
		(net "OCP_V3_2_P3V3_ADC_ALERT")
	)
	(segment
		(start 148.63318 -75.644248)
		(end 148.63318 -69.246496)
		(width 0.127)
		(layer "In2.Cu")
		(net "OCP_V3_2_P3V3_ADC_ALERT")
	)
	(segment
		(start 151.97328 -82.113628)
		(end 150.16988 -80.310228)
		(width 0.127)
		(layer "In2.Cu")
		(net "OCP_V3_2_P3V3_ADC_ALERT")
	)
	(segment
		(start 168.03116 -117.224048)
		(end 168.03116 -115.743228)
		(width 0.127)
		(layer "In2.Cu")
		(net "OCP_V3_2_P3V3_ADC_ALERT")
	)
	(segment
		(start 164.91458 -106.605578)
		(end 163.72459 -105.415588)
		(width 0.127)
		(layer "In2.Cu")
		(net "OCP_V3_2_P3V3_ADC_ALERT")
	)
	(segment
		(start 163.72459 -105.415588)
		(end 163.448492 -105.415588)
		(width 0.127)
		(layer "In2.Cu")
		(net "OCP_V3_2_P3V3_ADC_ALERT")
	)
	(segment
		(start 159.016446 -95.761302)
		(end 159.016446 -92.205048)
		(width 0.127)
		(layer "In2.Cu")
		(net "OCP_V3_2_P3V3_ADC_ALERT")
	)
	(segment
		(start 162.048952 -104.016048)
		(end 158.44012 -104.016048)
		(width 0.127)
		(layer "In2.Cu")
		(net "OCP_V3_2_P3V3_ADC_ALERT")
	)
	(segment
		(start 176.31156 -116.970048)
		(end 173.96968 -116.970048)
		(width 0.127)
		(layer "In2.Cu")
		(net "OCP_V3_2_P3V3_ADC_ALERT")
	)
	(segment
		(start 176.55794 -118.577614)
		(end 176.55794 -117.216428)
		(width 0.127)
		(layer "In2.Cu")
		(net "OCP_V3_2_P3V3_ADC_ALERT")
	)
	(segment
		(start 171.75988 -118.361968)
		(end 171.53636 -118.585488)
		(width 0.127)
		(layer "In2.Cu")
		(net "OCP_V3_2_P3V3_ADC_ALERT")
	)
	(segment
		(start 176.55794 -117.216428)
		(end 176.31156 -116.970048)
		(width 0.127)
		(layer "In2.Cu")
		(net "OCP_V3_2_P3V3_ADC_ALERT")
	)
	(segment
		(start 176.955704 -118.975378)
		(end 176.55794 -118.577614)
		(width 0.127)
		(layer "In2.Cu")
		(net "OCP_V3_2_P3V3_ADC_ALERT")
	)
	(segment
		(start 150.16988 -80.310228)
		(end 150.16988 -77.180948)
		(width 0.127)
		(layer "In2.Cu")
		(net "OCP_V3_2_P3V3_ADC_ALERT")
	)
	(segment
		(start 164.91458 -112.626648)
		(end 164.91458 -106.605578)
		(width 0.127)
		(layer "In2.Cu")
		(net "OCP_V3_2_P3V3_ADC_ALERT")
	)
	(segment
		(start 148.63318 -69.246496)
		(end 149.171406 -68.70827)
		(width 0.127)
		(layer "In2.Cu")
		(net "OCP_V3_2_P3V3_ADC_ALERT")
	)
	(segment
		(start 171.93768 -117.780308)
		(end 171.75988 -117.958108)
		(width 0.127)
		(layer "In2.Cu")
		(net "OCP_V3_2_P3V3_ADC_ALERT")
	)
	(segment
		(start 150.16988 -77.180948)
		(end 148.63318 -75.644248)
		(width 0.127)
		(layer "In2.Cu")
		(net "OCP_V3_2_P3V3_ADC_ALERT")
	)
	(segment
		(start 151.97328 -85.161882)
		(end 151.97328 -82.113628)
		(width 0.127)
		(layer "In2.Cu")
		(net "OCP_V3_2_P3V3_ADC_ALERT")
	)
	(segment
		(start 149.171406 -56.795162)
		(end 150.19274 -55.773828)
		(width 0.127)
		(layer "In2.Cu")
		(net "OCP_V3_2_P3V3_ADC_ALERT")
	)
	(segment
		(start 171.53636 -118.585488)
		(end 169.3926 -118.585488)
		(width 0.127)
		(layer "In2.Cu")
		(net "OCP_V3_2_P3V3_ADC_ALERT")
	)
	(segment
		(start 163.448492 -105.415588)
		(end 162.048952 -104.016048)
		(width 0.127)
		(layer "In2.Cu")
		(net "OCP_V3_2_P3V3_ADC_ALERT")
	)
	(segment
		(start 173.96968 -116.970048)
		(end 173.15942 -117.780308)
		(width 0.127)
		(layer "In2.Cu")
		(net "OCP_V3_2_P3V3_ADC_ALERT")
	)
	(segment
		(start 173.15942 -117.780308)
		(end 171.93768 -117.780308)
		(width 0.127)
		(layer "In2.Cu")
		(net "OCP_V3_2_P3V3_ADC_ALERT")
	)
	(segment
		(start 168.03116 -115.743228)
		(end 164.91458 -112.626648)
		(width 0.127)
		(layer "In2.Cu")
		(net "OCP_V3_2_P3V3_ADC_ALERT")
	)
	(segment
		(start 159.016446 -92.205048)
		(end 151.97328 -85.161882)
		(width 0.127)
		(layer "In2.Cu")
		(net "OCP_V3_2_P3V3_ADC_ALERT")
	)
	(segment
		(start 157.11932 -102.695248)
		(end 157.11932 -97.658428)
		(width 0.127)
		(layer "In2.Cu")
		(net "OCP_V3_2_P3V3_ADC_ALERT")
	)
	(segment
		(start 144.28216 -54.244748)
		(end 138.8618 -48.824388)
		(width 0.127)
		(layer "In15.Cu")
		(net "OCP_V3_2_P3V3_ADC_ALERT")
	)
	(segment
		(start 114.3381 -39.576248)
		(end 114.3381 -38.636448)
		(width 0.127)
		(layer "In15.Cu")
		(net "OCP_V3_2_P3V3_ADC_ALERT")
	)
	(segment
		(start 89.378282 -39.971726)
		(end 83.055968 -39.971726)
		(width 0.127)
		(layer "In15.Cu")
		(net "OCP_V3_2_P3V3_ADC_ALERT")
	)
	(segment
		(start 76.608178 -41.112948)
		(end 76.328778 -40.833548)
		(width 0.127)
		(layer "In15.Cu")
		(net "OCP_V3_2_P3V3_ADC_ALERT")
	)
	(segment
		(start 113.7666 -38.064948)
		(end 112.0648 -38.064948)
		(width 0.127)
		(layer "In15.Cu")
		(net "OCP_V3_2_P3V3_ADC_ALERT")
	)
	(segment
		(start 83.055968 -39.971726)
		(end 81.914746 -41.112948)
		(width 0.127)
		(layer "In15.Cu")
		(net "OCP_V3_2_P3V3_ADC_ALERT")
	)
	(segment
		(start 150.19274 -55.773828)
		(end 148.66366 -54.244748)
		(width 0.127)
		(layer "In15.Cu")
		(net "OCP_V3_2_P3V3_ADC_ALERT")
	)
	(segment
		(start 138.8618 -48.824388)
		(end 128.17602 -48.824388)
		(width 0.127)
		(layer "In15.Cu")
		(net "OCP_V3_2_P3V3_ADC_ALERT")
	)
	(segment
		(start 105.1052 -37.226748)
		(end 103.36276 -38.969188)
		(width 0.127)
		(layer "In15.Cu")
		(net "OCP_V3_2_P3V3_ADC_ALERT")
	)
	(segment
		(start 111.2266 -37.226748)
		(end 105.1052 -37.226748)
		(width 0.127)
		(layer "In15.Cu")
		(net "OCP_V3_2_P3V3_ADC_ALERT")
	)
	(segment
		(start 114.69116 -39.929308)
		(end 114.3381 -39.576248)
		(width 0.127)
		(layer "In15.Cu")
		(net "OCP_V3_2_P3V3_ADC_ALERT")
	)
	(segment
		(start 81.914746 -41.112948)
		(end 76.608178 -41.112948)
		(width 0.127)
		(layer "In15.Cu")
		(net "OCP_V3_2_P3V3_ADC_ALERT")
	)
	(segment
		(start 112.0648 -38.064948)
		(end 111.2266 -37.226748)
		(width 0.127)
		(layer "In15.Cu")
		(net "OCP_V3_2_P3V3_ADC_ALERT")
	)
	(segment
		(start 103.36276 -38.969188)
		(end 90.38082 -38.969188)
		(width 0.127)
		(layer "In15.Cu")
		(net "OCP_V3_2_P3V3_ADC_ALERT")
	)
	(segment
		(start 76.328778 -40.833548)
		(end 72.8726 -40.833548)
		(width 0.127)
		(layer "In15.Cu")
		(net "OCP_V3_2_P3V3_ADC_ALERT")
	)
	(segment
		(start 148.66366 -54.244748)
		(end 144.28216 -54.244748)
		(width 0.127)
		(layer "In15.Cu")
		(net "OCP_V3_2_P3V3_ADC_ALERT")
	)
	(segment
		(start 66.7512 -38.928548)
		(end 66.1924 -38.369748)
		(width 0.127)
		(layer "In15.Cu")
		(net "OCP_V3_2_P3V3_ADC_ALERT")
	)
	(segment
		(start 114.3381 -38.636448)
		(end 113.7666 -38.064948)
		(width 0.127)
		(layer "In15.Cu")
		(net "OCP_V3_2_P3V3_ADC_ALERT")
	)
	(segment
		(start 70.9676 -38.928548)
		(end 66.7512 -38.928548)
		(width 0.127)
		(layer "In15.Cu")
		(net "OCP_V3_2_P3V3_ADC_ALERT")
	)
	(segment
		(start 128.17602 -48.824388)
		(end 119.28094 -39.929308)
		(width 0.127)
		(layer "In15.Cu")
		(net "OCP_V3_2_P3V3_ADC_ALERT")
	)
	(segment
		(start 90.38082 -38.969188)
		(end 89.378282 -39.971726)
		(width 0.127)
		(layer "In15.Cu")
		(net "OCP_V3_2_P3V3_ADC_ALERT")
	)
	(segment
		(start 119.28094 -39.929308)
		(end 114.69116 -39.929308)
		(width 0.127)
		(layer "In15.Cu")
		(net "OCP_V3_2_P3V3_ADC_ALERT")
	)
	(segment
		(start 72.8726 -40.833548)
		(end 70.9676 -38.928548)
		(width 0.127)
		(layer "In15.Cu")
		(net "OCP_V3_2_P3V3_ADC_ALERT")
	)
	(segment
		(start 212.63864 -54.154578)
		(end 212.68944 -54.205378)
		(width 0.12954)
		(layer "F.Cu")
		(net "E1S_0_P3V3_ADC_ALERT_R")
	)
	(segment
		(start 212.68944 -54.205378)
		(end 213.859618 -54.205378)
		(width 0.12954)
		(layer "F.Cu")
		(net "E1S_0_P3V3_ADC_ALERT_R")
	)
	(via
		(at 212.63864 -54.154578)
		(size 0.508)
		(drill 0.254)
		(layers "F.Cu" "B.Cu")
		(net "E1S_0_P3V3_ADC_ALERT_R")
	)
	(segment
		(start 211.69503 -54.906418)
		(end 211.69503 -56.678322)
		(width 0.12954)
		(layer "B.Cu")
		(net "E1S_0_P3V3_ADC_ALERT_R")
	)
	(segment
		(start 212.708236 -56.678322)
		(end 212.725 -56.661558)
		(width 0.12954)
		(layer "B.Cu")
		(net "E1S_0_P3V3_ADC_ALERT_R")
	)
	(segment
		(start 211.69503 -56.678322)
		(end 212.708236 -56.678322)
		(width 0.12954)
		(layer "B.Cu")
		(net "E1S_0_P3V3_ADC_ALERT_R")
	)
	(segment
		(start 212.63864 -54.154578)
		(end 212.58784 -54.205378)
		(width 0.12954)
		(layer "B.Cu")
		(net "E1S_0_P3V3_ADC_ALERT_R")
	)
	(segment
		(start 212.39607 -54.205378)
		(end 211.69503 -54.906418)
		(width 0.12954)
		(layer "B.Cu")
		(net "E1S_0_P3V3_ADC_ALERT_R")
	)
	(segment
		(start 212.58784 -54.205378)
		(end 212.39607 -54.205378)
		(width 0.12954)
		(layer "B.Cu")
		(net "E1S_0_P3V3_ADC_ALERT_R")
	)
	(segment
		(start 448.21983 -94.602808)
		(end 448.112134 -94.602808)
		(width 0.12954)
		(layer "F.Cu")
		(net "OCP_SFF_P3V3_ADC_ALERT_R")
	)
	(segment
		(start 444.79083 -94.964758)
		(end 444.79083 -94.602808)
		(width 0.12954)
		(layer "F.Cu")
		(net "OCP_SFF_P3V3_ADC_ALERT_R")
	)
	(segment
		(start 448.112134 -94.602808)
		(end 447.477134 -95.237808)
		(width 0.12954)
		(layer "F.Cu")
		(net "OCP_SFF_P3V3_ADC_ALERT_R")
	)
	(segment
		(start 443.73292 -94.602808)
		(end 444.79083 -94.602808)
		(width 0.12954)
		(layer "F.Cu")
		(net "OCP_SFF_P3V3_ADC_ALERT_R")
	)
	(segment
		(start 442.489844 -94.327472)
		(end 443.03696 -94.874588)
		(width 0.12954)
		(layer "F.Cu")
		(net "OCP_SFF_P3V3_ADC_ALERT_R")
	)
	(segment
		(start 442.088016 -94.327472)
		(end 442.489844 -94.327472)
		(width 0.12954)
		(layer "F.Cu")
		(net "OCP_SFF_P3V3_ADC_ALERT_R")
	)
	(segment
		(start 445.06388 -95.237808)
		(end 444.79083 -94.964758)
		(width 0.12954)
		(layer "F.Cu")
		(net "OCP_SFF_P3V3_ADC_ALERT_R")
	)
	(segment
		(start 443.03696 -94.874588)
		(end 443.46114 -94.874588)
		(width 0.12954)
		(layer "F.Cu")
		(net "OCP_SFF_P3V3_ADC_ALERT_R")
	)
	(segment
		(start 447.477134 -95.237808)
		(end 445.06388 -95.237808)
		(width 0.12954)
		(layer "F.Cu")
		(net "OCP_SFF_P3V3_ADC_ALERT_R")
	)
	(segment
		(start 443.46114 -94.874588)
		(end 443.73292 -94.602808)
		(width 0.12954)
		(layer "F.Cu")
		(net "OCP_SFF_P3V3_ADC_ALERT_R")
	)
	(via
		(at 443.46114 -94.874588)
		(size 0.762)
		(drill 0.381)
		(layers "F.Cu" "B.Cu")
		(net "OCP_SFF_P3V3_ADC_ALERT_R")
	)
	(segment
		(start 177.355754 -120.175528)
		(end 176.955704 -120.575578)
		(width 0.12954)
		(layer "F.Cu")
		(net "OCP_SFF_P3V3_ADC_ALERT")
	)
	(segment
		(start 445.59093 -94.602808)
		(end 446.260982 -94.602808)
		(width 0.12954)
		(layer "F.Cu")
		(net "OCP_SFF_P3V3_ADC_ALERT")
	)
	(via
		(at 176.955704 -120.575578)
		(size 0.4572)
		(drill 0.254)
		(layers "F.Cu" "B.Cu")
		(net "OCP_SFF_P3V3_ADC_ALERT")
	)
	(via
		(at 446.260982 -94.602808)
		(size 0.508)
		(drill 0.254)
		(layers "F.Cu" "B.Cu")
		(net "OCP_SFF_P3V3_ADC_ALERT")
	)
	(segment
		(start 217.238834 -117.3226)
		(end 219.44711 -115.114324)
		(width 0.127)
		(layer "In13.Cu")
		(net "OCP_SFF_P3V3_ADC_ALERT")
	)
	(segment
		(start 201.243946 -119.9642)
		(end 202.4634 -119.9642)
		(width 0.127)
		(layer "In13.Cu")
		(net "OCP_SFF_P3V3_ADC_ALERT")
	)
	(segment
		(start 200.805796 -120.40235)
		(end 201.243946 -119.9642)
		(width 0.127)
		(layer "In13.Cu")
		(net "OCP_SFF_P3V3_ADC_ALERT")
	)
	(segment
		(start 223.657922 -112.497362)
		(end 232.874058 -112.497362)
		(width 0.127)
		(layer "In13.Cu")
		(net "OCP_SFF_P3V3_ADC_ALERT")
	)
	(segment
		(start 194.041268 -120.025414)
		(end 199.092312 -120.025414)
		(width 0.127)
		(layer "In13.Cu")
		(net "OCP_SFF_P3V3_ADC_ALERT")
	)
	(segment
		(start 199.092312 -120.025414)
		(end 199.469248 -120.40235)
		(width 0.127)
		(layer "In13.Cu")
		(net "OCP_SFF_P3V3_ADC_ALERT")
	)
	(segment
		(start 186.846718 -120.176036)
		(end 187.37961 -120.708928)
		(width 0.127)
		(layer "In13.Cu")
		(net "OCP_SFF_P3V3_ADC_ALERT")
	)
	(segment
		(start 232.874058 -112.497362)
		(end 233.40187 -111.96955)
		(width 0.127)
		(layer "In13.Cu")
		(net "OCP_SFF_P3V3_ADC_ALERT")
	)
	(segment
		(start 233.40187 -111.96955)
		(end 236.613954 -111.96955)
		(width 0.127)
		(layer "In13.Cu")
		(net "OCP_SFF_P3V3_ADC_ALERT")
	)
	(segment
		(start 177.91176 -120.995948)
		(end 178.731672 -120.176036)
		(width 0.127)
		(layer "In13.Cu")
		(net "OCP_SFF_P3V3_ADC_ALERT")
	)
	(segment
		(start 176.955704 -120.575578)
		(end 177.376074 -120.995948)
		(width 0.127)
		(layer "In13.Cu")
		(net "OCP_SFF_P3V3_ADC_ALERT")
	)
	(segment
		(start 439.668158 -112.01273)
		(end 445.95796 -105.722928)
		(width 0.127)
		(layer "In13.Cu")
		(net "OCP_SFF_P3V3_ADC_ALERT")
	)
	(segment
		(start 240.965482 -112.680496)
		(end 243.270024 -114.985038)
		(width 0.127)
		(layer "In13.Cu")
		(net "OCP_SFF_P3V3_ADC_ALERT")
	)
	(segment
		(start 199.469248 -120.40235)
		(end 200.805796 -120.40235)
		(width 0.127)
		(layer "In13.Cu")
		(net "OCP_SFF_P3V3_ADC_ALERT")
	)
	(segment
		(start 192.948814 -121.117868)
		(end 194.041268 -120.025414)
		(width 0.127)
		(layer "In13.Cu")
		(net "OCP_SFF_P3V3_ADC_ALERT")
	)
	(segment
		(start 188.09462 -121.117868)
		(end 192.948814 -121.117868)
		(width 0.127)
		(layer "In13.Cu")
		(net "OCP_SFF_P3V3_ADC_ALERT")
	)
	(segment
		(start 177.376074 -120.995948)
		(end 177.91176 -120.995948)
		(width 0.127)
		(layer "In13.Cu")
		(net "OCP_SFF_P3V3_ADC_ALERT")
	)
	(segment
		(start 187.68568 -120.708928)
		(end 188.09462 -121.117868)
		(width 0.127)
		(layer "In13.Cu")
		(net "OCP_SFF_P3V3_ADC_ALERT")
	)
	(segment
		(start 294.534082 -114.985038)
		(end 295.051226 -115.502182)
		(width 0.127)
		(layer "In13.Cu")
		(net "OCP_SFF_P3V3_ADC_ALERT")
	)
	(segment
		(start 422.17848 -113.864898)
		(end 424.030648 -112.01273)
		(width 0.127)
		(layer "In13.Cu")
		(net "OCP_SFF_P3V3_ADC_ALERT")
	)
	(segment
		(start 219.44711 -115.114324)
		(end 221.04096 -115.114324)
		(width 0.127)
		(layer "In13.Cu")
		(net "OCP_SFF_P3V3_ADC_ALERT")
	)
	(segment
		(start 203.8096 -118.618)
		(end 209.9564 -118.618)
		(width 0.127)
		(layer "In13.Cu")
		(net "OCP_SFF_P3V3_ADC_ALERT")
	)
	(segment
		(start 237.3249 -112.680496)
		(end 240.965482 -112.680496)
		(width 0.127)
		(layer "In13.Cu")
		(net "OCP_SFF_P3V3_ADC_ALERT")
	)
	(segment
		(start 221.04096 -115.114324)
		(end 223.657922 -112.497362)
		(width 0.127)
		(layer "In13.Cu")
		(net "OCP_SFF_P3V3_ADC_ALERT")
	)
	(segment
		(start 314.738258 -115.502182)
		(end 316.375542 -113.864898)
		(width 0.127)
		(layer "In13.Cu")
		(net "OCP_SFF_P3V3_ADC_ALERT")
	)
	(segment
		(start 424.030648 -112.01273)
		(end 439.668158 -112.01273)
		(width 0.127)
		(layer "In13.Cu")
		(net "OCP_SFF_P3V3_ADC_ALERT")
	)
	(segment
		(start 445.95796 -94.90583)
		(end 446.260982 -94.602808)
		(width 0.127)
		(layer "In13.Cu")
		(net "OCP_SFF_P3V3_ADC_ALERT")
	)
	(segment
		(start 445.95796 -105.722928)
		(end 445.95796 -94.90583)
		(width 0.127)
		(layer "In13.Cu")
		(net "OCP_SFF_P3V3_ADC_ALERT")
	)
	(segment
		(start 211.2518 -117.3226)
		(end 217.238834 -117.3226)
		(width 0.127)
		(layer "In13.Cu")
		(net "OCP_SFF_P3V3_ADC_ALERT")
	)
	(segment
		(start 178.731672 -120.176036)
		(end 186.846718 -120.176036)
		(width 0.127)
		(layer "In13.Cu")
		(net "OCP_SFF_P3V3_ADC_ALERT")
	)
	(segment
		(start 187.37961 -120.708928)
		(end 187.68568 -120.708928)
		(width 0.127)
		(layer "In13.Cu")
		(net "OCP_SFF_P3V3_ADC_ALERT")
	)
	(segment
		(start 316.375542 -113.864898)
		(end 422.17848 -113.864898)
		(width 0.127)
		(layer "In13.Cu")
		(net "OCP_SFF_P3V3_ADC_ALERT")
	)
	(segment
		(start 202.4634 -119.9642)
		(end 203.8096 -118.618)
		(width 0.127)
		(layer "In13.Cu")
		(net "OCP_SFF_P3V3_ADC_ALERT")
	)
	(segment
		(start 209.9564 -118.618)
		(end 211.2518 -117.3226)
		(width 0.127)
		(layer "In13.Cu")
		(net "OCP_SFF_P3V3_ADC_ALERT")
	)
	(segment
		(start 243.270024 -114.985038)
		(end 294.534082 -114.985038)
		(width 0.127)
		(layer "In13.Cu")
		(net "OCP_SFF_P3V3_ADC_ALERT")
	)
	(segment
		(start 236.613954 -111.96955)
		(end 237.3249 -112.680496)
		(width 0.127)
		(layer "In13.Cu")
		(net "OCP_SFF_P3V3_ADC_ALERT")
	)
	(segment
		(start 295.051226 -115.502182)
		(end 314.738258 -115.502182)
		(width 0.127)
		(layer "In13.Cu")
		(net "OCP_SFF_P3V3_ADC_ALERT")
	)
	(segment
		(start 210.868006 -31.927292)
		(end 212.118956 -30.676342)
		(width 0.12954)
		(layer "F.Cu")
		(net "P12V_SCM_ADC_ALERT_R")
	)
	(segment
		(start 212.118956 -30.676342)
		(end 213.167976 -30.676342)
		(width 0.12954)
		(layer "F.Cu")
		(net "P12V_SCM_ADC_ALERT_R")
	)
	(segment
		(start 209.422492 -32.972502)
		(end 210.467702 -31.927292)
		(width 0.12954)
		(layer "F.Cu")
		(net "P12V_SCM_ADC_ALERT_R")
	)
	(segment
		(start 210.467956 -31.927292)
		(end 210.868006 -31.927292)
		(width 0.12954)
		(layer "F.Cu")
		(net "P12V_SCM_ADC_ALERT_R")
	)
	(segment
		(start 209.422492 -33.372044)
		(end 209.422492 -32.972502)
		(width 0.12954)
		(layer "F.Cu")
		(net "P12V_SCM_ADC_ALERT_R")
	)
	(segment
		(start 210.467702 -31.927292)
		(end 210.467956 -31.927292)
		(width 0.12954)
		(layer "F.Cu")
		(net "P12V_SCM_ADC_ALERT_R")
	)
	(segment
		(start 213.167976 -30.676342)
		(end 213.19744 -30.646878)
		(width 0.12954)
		(layer "F.Cu")
		(net "P12V_SCM_ADC_ALERT_R")
	)
	(via
		(at 210.467956 -31.927292)
		(size 0.762)
		(drill 0.381)
		(layers "F.Cu" "B.Cu")
		(net "P12V_SCM_ADC_ALERT_R")
	)
	(segment
		(start 212.118956 -29.876242)
		(end 212.118956 -29.266642)
		(width 0.12954)
		(layer "F.Cu")
		(net "P12V_SCM_ADC_ALERT")
	)
	(segment
		(start 177.355754 -116.975382)
		(end 176.955704 -117.375432)
		(width 0.12954)
		(layer "F.Cu")
		(net "P12V_SCM_ADC_ALERT")
	)
	(via
		(at 176.955704 -117.375432)
		(size 0.4572)
		(drill 0.254)
		(layers "F.Cu" "B.Cu")
		(net "P12V_SCM_ADC_ALERT")
	)
	(via
		(at 212.118956 -29.266642)
		(size 0.508)
		(drill 0.254)
		(layers "F.Cu" "B.Cu")
		(net "P12V_SCM_ADC_ALERT")
	)
	(via
		(at 212.67928 -44.478448)
		(size 0.508)
		(drill 0.254)
		(layers "F.Cu" "B.Cu")
		(net "P12V_SCM_ADC_ALERT")
	)
	(via
		(at 220.49994 -126.782068)
		(size 0.508)
		(drill 0.254)
		(layers "F.Cu" "B.Cu")
		(net "P12V_SCM_ADC_ALERT")
	)
	(via
		(at 209.8802 -79.238348)
		(size 0.508)
		(drill 0.254)
		(layers "F.Cu" "B.Cu")
		(net "P12V_SCM_ADC_ALERT")
	)
	(segment
		(start 210.4263 -80.183228)
		(end 212.8901 -80.183228)
		(width 0.127)
		(layer "In2.Cu")
		(net "P12V_SCM_ADC_ALERT")
	)
	(segment
		(start 212.8901 -80.183228)
		(end 223.534478 -90.827606)
		(width 0.127)
		(layer "In2.Cu")
		(net "P12V_SCM_ADC_ALERT")
	)
	(segment
		(start 211.37118 -42.832528)
		(end 211.37118 -30.014418)
		(width 0.127)
		(layer "In2.Cu")
		(net "P12V_SCM_ADC_ALERT")
	)
	(segment
		(start 222.69958 -98.332798)
		(end 222.69958 -113.513108)
		(width 0.127)
		(layer "In2.Cu")
		(net "P12V_SCM_ADC_ALERT")
	)
	(segment
		(start 223.534478 -97.4979)
		(end 222.69958 -98.332798)
		(width 0.127)
		(layer "In2.Cu")
		(net "P12V_SCM_ADC_ALERT")
	)
	(segment
		(start 212.67928 -44.140628)
		(end 211.37118 -42.832528)
		(width 0.127)
		(layer "In2.Cu")
		(net "P12V_SCM_ADC_ALERT")
	)
	(segment
		(start 220.49994 -115.712748)
		(end 220.49994 -126.782068)
		(width 0.127)
		(layer "In2.Cu")
		(net "P12V_SCM_ADC_ALERT")
	)
	(segment
		(start 223.534478 -90.827606)
		(end 223.534478 -97.4979)
		(width 0.127)
		(layer "In2.Cu")
		(net "P12V_SCM_ADC_ALERT")
	)
	(segment
		(start 209.8802 -79.238348)
		(end 209.8802 -79.637128)
		(width 0.127)
		(layer "In2.Cu")
		(net "P12V_SCM_ADC_ALERT")
	)
	(segment
		(start 209.8802 -79.637128)
		(end 210.4263 -80.183228)
		(width 0.127)
		(layer "In2.Cu")
		(net "P12V_SCM_ADC_ALERT")
	)
	(segment
		(start 222.69958 -113.513108)
		(end 220.49994 -115.712748)
		(width 0.127)
		(layer "In2.Cu")
		(net "P12V_SCM_ADC_ALERT")
	)
	(segment
		(start 212.67928 -44.478448)
		(end 212.67928 -44.140628)
		(width 0.127)
		(layer "In2.Cu")
		(net "P12V_SCM_ADC_ALERT")
	)
	(segment
		(start 211.37118 -30.014418)
		(end 212.118956 -29.266642)
		(width 0.127)
		(layer "In2.Cu")
		(net "P12V_SCM_ADC_ALERT")
	)
	(segment
		(start 213.27364 -58.786268)
		(end 213.27364 -54.900068)
		(width 0.127)
		(layer "In6.Cu")
		(net "P12V_SCM_ADC_ALERT")
	)
	(segment
		(start 212.54974 -48.382428)
		(end 212.54974 -44.607988)
		(width 0.127)
		(layer "In6.Cu")
		(net "P12V_SCM_ADC_ALERT")
	)
	(segment
		(start 178.85664 -120.117108)
		(end 179.71262 -120.973088)
		(width 0.127)
		(layer "In6.Cu")
		(net "P12V_SCM_ADC_ALERT")
	)
	(segment
		(start 213.27364 -54.900068)
		(end 213.6902 -54.483508)
		(width 0.127)
		(layer "In6.Cu")
		(net "P12V_SCM_ADC_ALERT")
	)
	(segment
		(start 216.04478 -61.557408)
		(end 213.27364 -58.786268)
		(width 0.127)
		(layer "In6.Cu")
		(net "P12V_SCM_ADC_ALERT")
	)
	(segment
		(start 177.94986 -118.577868)
		(end 178.85664 -119.484648)
		(width 0.127)
		(layer "In6.Cu")
		(net "P12V_SCM_ADC_ALERT")
	)
	(segment
		(start 192.760092 -129.291588)
		(end 194.96024 -129.291588)
		(width 0.127)
		(layer "In6.Cu")
		(net "P12V_SCM_ADC_ALERT")
	)
	(segment
		(start 204.401674 -127.785114)
		(end 204.597 -127.589788)
		(width 0.127)
		(layer "In6.Cu")
		(net "P12V_SCM_ADC_ALERT")
	)
	(segment
		(start 220.49994 -126.479808)
		(end 220.49994 -126.782068)
		(width 0.127)
		(layer "In6.Cu")
		(net "P12V_SCM_ADC_ALERT")
	)
	(segment
		(start 201.27468 -128.219708)
		(end 201.709274 -127.785114)
		(width 0.127)
		(layer "In6.Cu")
		(net "P12V_SCM_ADC_ALERT")
	)
	(segment
		(start 204.597 -127.589788)
		(end 206.94142 -127.589788)
		(width 0.127)
		(layer "In6.Cu")
		(net "P12V_SCM_ADC_ALERT")
	)
	(segment
		(start 194.96024 -129.291588)
		(end 196.03212 -128.219708)
		(width 0.127)
		(layer "In6.Cu")
		(net "P12V_SCM_ADC_ALERT")
	)
	(segment
		(start 219.72016 -125.700028)
		(end 220.49994 -126.479808)
		(width 0.127)
		(layer "In6.Cu")
		(net "P12V_SCM_ADC_ALERT")
	)
	(segment
		(start 184.69356 -124.704348)
		(end 188.172852 -124.704348)
		(width 0.127)
		(layer "In6.Cu")
		(net "P12V_SCM_ADC_ALERT")
	)
	(segment
		(start 201.709274 -127.785114)
		(end 204.401674 -127.785114)
		(width 0.127)
		(layer "In6.Cu")
		(net "P12V_SCM_ADC_ALERT")
	)
	(segment
		(start 178.85664 -119.484648)
		(end 178.85664 -120.117108)
		(width 0.127)
		(layer "In6.Cu")
		(net "P12V_SCM_ADC_ALERT")
	)
	(segment
		(start 212.54974 -44.607988)
		(end 212.67928 -44.478448)
		(width 0.127)
		(layer "In6.Cu")
		(net "P12V_SCM_ADC_ALERT")
	)
	(segment
		(start 180.9623 -120.973088)
		(end 184.69356 -124.704348)
		(width 0.127)
		(layer "In6.Cu")
		(net "P12V_SCM_ADC_ALERT")
	)
	(segment
		(start 220.990668 -80.622648)
		(end 226.021138 -75.592178)
		(width 0.127)
		(layer "In6.Cu")
		(net "P12V_SCM_ADC_ALERT")
	)
	(segment
		(start 213.56066 -128.471168)
		(end 216.3318 -125.700028)
		(width 0.127)
		(layer "In6.Cu")
		(net "P12V_SCM_ADC_ALERT")
	)
	(segment
		(start 179.71262 -120.973088)
		(end 180.9623 -120.973088)
		(width 0.127)
		(layer "In6.Cu")
		(net "P12V_SCM_ADC_ALERT")
	)
	(segment
		(start 216.3318 -125.700028)
		(end 219.72016 -125.700028)
		(width 0.127)
		(layer "In6.Cu")
		(net "P12V_SCM_ADC_ALERT")
	)
	(segment
		(start 207.8228 -128.471168)
		(end 213.56066 -128.471168)
		(width 0.127)
		(layer "In6.Cu")
		(net "P12V_SCM_ADC_ALERT")
	)
	(segment
		(start 213.6902 -54.483508)
		(end 213.6902 -49.522888)
		(width 0.127)
		(layer "In6.Cu")
		(net "P12V_SCM_ADC_ALERT")
	)
	(segment
		(start 177.36058 -117.780308)
		(end 177.36058 -118.384828)
		(width 0.127)
		(layer "In6.Cu")
		(net "P12V_SCM_ADC_ALERT")
	)
	(segment
		(start 209.8802 -79.238348)
		(end 209.8802 -80.000348)
		(width 0.127)
		(layer "In6.Cu")
		(net "P12V_SCM_ADC_ALERT")
	)
	(segment
		(start 206.94142 -127.589788)
		(end 207.8228 -128.471168)
		(width 0.127)
		(layer "In6.Cu")
		(net "P12V_SCM_ADC_ALERT")
	)
	(segment
		(start 209.8802 -80.000348)
		(end 210.5025 -80.622648)
		(width 0.127)
		(layer "In6.Cu")
		(net "P12V_SCM_ADC_ALERT")
	)
	(segment
		(start 177.55362 -118.577868)
		(end 177.94986 -118.577868)
		(width 0.127)
		(layer "In6.Cu")
		(net "P12V_SCM_ADC_ALERT")
	)
	(segment
		(start 176.955704 -117.375432)
		(end 177.36058 -117.780308)
		(width 0.127)
		(layer "In6.Cu")
		(net "P12V_SCM_ADC_ALERT")
	)
	(segment
		(start 213.6902 -49.522888)
		(end 212.54974 -48.382428)
		(width 0.127)
		(layer "In6.Cu")
		(net "P12V_SCM_ADC_ALERT")
	)
	(segment
		(start 226.021138 -65.107566)
		(end 222.47098 -61.557408)
		(width 0.127)
		(layer "In6.Cu")
		(net "P12V_SCM_ADC_ALERT")
	)
	(segment
		(start 177.36058 -118.384828)
		(end 177.55362 -118.577868)
		(width 0.127)
		(layer "In6.Cu")
		(net "P12V_SCM_ADC_ALERT")
	)
	(segment
		(start 210.5025 -80.622648)
		(end 220.990668 -80.622648)
		(width 0.127)
		(layer "In6.Cu")
		(net "P12V_SCM_ADC_ALERT")
	)
	(segment
		(start 222.47098 -61.557408)
		(end 216.04478 -61.557408)
		(width 0.127)
		(layer "In6.Cu")
		(net "P12V_SCM_ADC_ALERT")
	)
	(segment
		(start 196.03212 -128.219708)
		(end 201.27468 -128.219708)
		(width 0.127)
		(layer "In6.Cu")
		(net "P12V_SCM_ADC_ALERT")
	)
	(segment
		(start 226.021138 -75.592178)
		(end 226.021138 -65.107566)
		(width 0.127)
		(layer "In6.Cu")
		(net "P12V_SCM_ADC_ALERT")
	)
	(segment
		(start 188.172852 -124.704348)
		(end 192.760092 -129.291588)
		(width 0.127)
		(layer "In6.Cu")
		(net "P12V_SCM_ADC_ALERT")
	)
	(segment
		(start 149.848824 -51.023266)
		(end 149.848824 -51.023012)
		(width 0.12954)
		(layer "F.Cu")
		(net "M2_0_P3V3_ADC_ALERT_R")
	)
	(segment
		(start 150.894034 -52.068476)
		(end 149.848824 -51.023266)
		(width 0.12954)
		(layer "F.Cu")
		(net "M2_0_P3V3_ADC_ALERT_R")
	)
	(segment
		(start 148.597874 -49.372012)
		(end 148.59635 -49.370488)
		(width 0.12954)
		(layer "F.Cu")
		(net "M2_0_P3V3_ADC_ALERT_R")
	)
	(segment
		(start 149.848824 -51.023012)
		(end 149.848824 -50.622962)
		(width 0.12954)
		(layer "F.Cu")
		(net "M2_0_P3V3_ADC_ALERT_R")
	)
	(segment
		(start 148.59635 -49.370488)
		(end 148.59635 -48.283368)
		(width 0.12954)
		(layer "F.Cu")
		(net "M2_0_P3V3_ADC_ALERT_R")
	)
	(segment
		(start 151.293576 -52.068476)
		(end 150.894034 -52.068476)
		(width 0.12954)
		(layer "F.Cu")
		(net "M2_0_P3V3_ADC_ALERT_R")
	)
	(segment
		(start 149.848824 -50.622962)
		(end 148.597874 -49.372012)
		(width 0.12954)
		(layer "F.Cu")
		(net "M2_0_P3V3_ADC_ALERT_R")
	)
	(via
		(at 149.848824 -51.023012)
		(size 0.762)
		(drill 0.381)
		(layers "F.Cu" "B.Cu")
		(net "M2_0_P3V3_ADC_ALERT_R")
	)
	(segment
		(start 147.797774 -49.372012)
		(end 147.188174 -49.372012)
		(width 0.12954)
		(layer "F.Cu")
		(net "M2_0_P3V3_ADC_ALERT")
	)
	(segment
		(start 177.355754 -117.775482)
		(end 176.955704 -118.175532)
		(width 0.12954)
		(layer "F.Cu")
		(net "M2_0_P3V3_ADC_ALERT")
	)
	(via
		(at 147.188174 -49.372012)
		(size 0.508)
		(drill 0.254)
		(layers "F.Cu" "B.Cu")
		(net "M2_0_P3V3_ADC_ALERT")
	)
	(via
		(at 176.955704 -118.175532)
		(size 0.4572)
		(drill 0.254)
		(layers "F.Cu" "B.Cu")
		(net "M2_0_P3V3_ADC_ALERT")
	)
	(segment
		(start 159.8295 -103.685848)
		(end 162.186112 -103.685848)
		(width 0.127)
		(layer "In2.Cu")
		(net "M2_0_P3V3_ADC_ALERT")
	)
	(segment
		(start 151.00808 -55.717948)
		(end 151.00808 -56.505348)
		(width 0.127)
		(layer "In2.Cu")
		(net "M2_0_P3V3_ADC_ALERT")
	)
	(segment
		(start 170.80992 -117.780308)
		(end 170.95724 -117.632988)
		(width 0.127)
		(layer "In2.Cu")
		(net "M2_0_P3V3_ADC_ALERT")
	)
	(segment
		(start 147.188174 -49.372012)
		(end 148.51888 -49.372012)
		(width 0.127)
		(layer "In2.Cu")
		(net "M2_0_P3V3_ADC_ALERT")
	)
	(segment
		(start 172.41012 -116.977668)
		(end 172.55744 -116.830348)
		(width 0.127)
		(layer "In2.Cu")
		(net "M2_0_P3V3_ADC_ALERT")
	)
	(segment
		(start 176.76876 -116.970048)
		(end 177.15992 -116.970048)
		(width 0.127)
		(layer "In2.Cu")
		(net "M2_0_P3V3_ADC_ALERT")
	)
	(segment
		(start 172.55744 -116.32692)
		(end 172.709332 -116.175028)
		(width 0.127)
		(layer "In2.Cu")
		(net "M2_0_P3V3_ADC_ALERT")
	)
	(segment
		(start 165.24478 -106.468672)
		(end 165.24478 -112.469168)
		(width 0.127)
		(layer "In2.Cu")
		(net "M2_0_P3V3_ADC_ALERT")
	)
	(segment
		(start 169.52722 -117.780308)
		(end 170.80992 -117.780308)
		(width 0.127)
		(layer "In2.Cu")
		(net "M2_0_P3V3_ADC_ALERT")
	)
	(segment
		(start 159.346646 -95.898462)
		(end 158.7373 -96.507808)
		(width 0.127)
		(layer "In2.Cu")
		(net "M2_0_P3V3_ADC_ALERT")
	)
	(segment
		(start 176.5554 -116.360448)
		(end 176.5554 -116.756688)
		(width 0.127)
		(layer "In2.Cu")
		(net "M2_0_P3V3_ADC_ALERT")
	)
	(segment
		(start 165.24478 -112.469168)
		(end 168.47058 -115.694968)
		(width 0.127)
		(layer "In2.Cu")
		(net "M2_0_P3V3_ADC_ALERT")
	)
	(segment
		(start 162.186112 -103.685848)
		(end 162.546792 -104.046528)
		(width 0.127)
		(layer "In2.Cu")
		(net "M2_0_P3V3_ADC_ALERT")
	)
	(segment
		(start 150.72868 -80.330548)
		(end 152.30348 -81.905348)
		(width 0.127)
		(layer "In2.Cu")
		(net "M2_0_P3V3_ADC_ALERT")
	)
	(segment
		(start 168.47058 -115.694968)
		(end 168.47058 -116.723668)
		(width 0.127)
		(layer "In2.Cu")
		(net "M2_0_P3V3_ADC_ALERT")
	)
	(segment
		(start 162.546792 -104.046528)
		(end 163.755832 -104.046528)
		(width 0.127)
		(layer "In2.Cu")
		(net "M2_0_P3V3_ADC_ALERT")
	)
	(segment
		(start 170.95724 -117.213888)
		(end 171.19346 -116.977668)
		(width 0.127)
		(layer "In2.Cu")
		(net "M2_0_P3V3_ADC_ALERT")
	)
	(segment
		(start 149.33168 -54.041548)
		(end 151.00808 -55.717948)
		(width 0.127)
		(layer "In2.Cu")
		(net "M2_0_P3V3_ADC_ALERT")
	)
	(segment
		(start 177.35296 -117.163088)
		(end 177.35296 -117.551708)
		(width 0.127)
		(layer "In2.Cu")
		(net "M2_0_P3V3_ADC_ALERT")
	)
	(segment
		(start 149.33168 -50.184812)
		(end 149.33168 -54.041548)
		(width 0.127)
		(layer "In2.Cu")
		(net "M2_0_P3V3_ADC_ALERT")
	)
	(segment
		(start 172.709332 -116.175028)
		(end 176.36998 -116.175028)
		(width 0.127)
		(layer "In2.Cu")
		(net "M2_0_P3V3_ADC_ALERT")
	)
	(segment
		(start 164.1348 -105.358692)
		(end 165.24478 -106.468672)
		(width 0.127)
		(layer "In2.Cu")
		(net "M2_0_P3V3_ADC_ALERT")
	)
	(segment
		(start 159.346646 -92.03944)
		(end 159.346646 -95.898462)
		(width 0.127)
		(layer "In2.Cu")
		(net "M2_0_P3V3_ADC_ALERT")
	)
	(segment
		(start 158.7373 -96.507808)
		(end 158.7373 -102.593648)
		(width 0.127)
		(layer "In2.Cu")
		(net "M2_0_P3V3_ADC_ALERT")
	)
	(segment
		(start 152.30348 -81.905348)
		(end 152.30348 -84.996274)
		(width 0.127)
		(layer "In2.Cu")
		(net "M2_0_P3V3_ADC_ALERT")
	)
	(segment
		(start 172.55744 -116.830348)
		(end 172.55744 -116.32692)
		(width 0.127)
		(layer "In2.Cu")
		(net "M2_0_P3V3_ADC_ALERT")
	)
	(segment
		(start 151.00808 -56.505348)
		(end 149.66188 -57.851548)
		(width 0.127)
		(layer "In2.Cu")
		(net "M2_0_P3V3_ADC_ALERT")
	)
	(segment
		(start 177.15992 -116.970048)
		(end 177.35296 -117.163088)
		(width 0.127)
		(layer "In2.Cu")
		(net "M2_0_P3V3_ADC_ALERT")
	)
	(segment
		(start 176.36998 -116.175028)
		(end 176.5554 -116.360448)
		(width 0.127)
		(layer "In2.Cu")
		(net "M2_0_P3V3_ADC_ALERT")
	)
	(segment
		(start 152.30348 -84.996274)
		(end 159.346646 -92.03944)
		(width 0.127)
		(layer "In2.Cu")
		(net "M2_0_P3V3_ADC_ALERT")
	)
	(segment
		(start 149.66188 -57.851548)
		(end 149.66188 -71.719948)
		(width 0.127)
		(layer "In2.Cu")
		(net "M2_0_P3V3_ADC_ALERT")
	)
	(segment
		(start 177.35296 -117.551708)
		(end 176.955704 -117.948964)
		(width 0.127)
		(layer "In2.Cu")
		(net "M2_0_P3V3_ADC_ALERT")
	)
	(segment
		(start 176.5554 -116.756688)
		(end 176.76876 -116.970048)
		(width 0.127)
		(layer "In2.Cu")
		(net "M2_0_P3V3_ADC_ALERT")
	)
	(segment
		(start 149.02688 -75.148948)
		(end 150.72868 -76.850748)
		(width 0.127)
		(layer "In2.Cu")
		(net "M2_0_P3V3_ADC_ALERT")
	)
	(segment
		(start 164.1348 -104.425496)
		(end 164.1348 -105.358692)
		(width 0.127)
		(layer "In2.Cu")
		(net "M2_0_P3V3_ADC_ALERT")
	)
	(segment
		(start 148.51888 -49.372012)
		(end 149.33168 -50.184812)
		(width 0.127)
		(layer "In2.Cu")
		(net "M2_0_P3V3_ADC_ALERT")
	)
	(segment
		(start 158.7373 -102.593648)
		(end 159.8295 -103.685848)
		(width 0.127)
		(layer "In2.Cu")
		(net "M2_0_P3V3_ADC_ALERT")
	)
	(segment
		(start 163.755832 -104.046528)
		(end 164.1348 -104.425496)
		(width 0.127)
		(layer "In2.Cu")
		(net "M2_0_P3V3_ADC_ALERT")
	)
	(segment
		(start 171.19346 -116.977668)
		(end 172.41012 -116.977668)
		(width 0.127)
		(layer "In2.Cu")
		(net "M2_0_P3V3_ADC_ALERT")
	)
	(segment
		(start 149.02688 -72.354948)
		(end 149.02688 -75.148948)
		(width 0.127)
		(layer "In2.Cu")
		(net "M2_0_P3V3_ADC_ALERT")
	)
	(segment
		(start 150.72868 -76.850748)
		(end 150.72868 -80.330548)
		(width 0.127)
		(layer "In2.Cu")
		(net "M2_0_P3V3_ADC_ALERT")
	)
	(segment
		(start 168.47058 -116.723668)
		(end 169.52722 -117.780308)
		(width 0.127)
		(layer "In2.Cu")
		(net "M2_0_P3V3_ADC_ALERT")
	)
	(segment
		(start 176.955704 -117.948964)
		(end 176.955704 -118.175532)
		(width 0.127)
		(layer "In2.Cu")
		(net "M2_0_P3V3_ADC_ALERT")
	)
	(segment
		(start 170.95724 -117.632988)
		(end 170.95724 -117.213888)
		(width 0.127)
		(layer "In2.Cu")
		(net "M2_0_P3V3_ADC_ALERT")
	)
	(segment
		(start 149.66188 -71.719948)
		(end 149.02688 -72.354948)
		(width 0.127)
		(layer "In2.Cu")
		(net "M2_0_P3V3_ADC_ALERT")
	)
	(segment
		(start 206.784956 -30.676342)
		(end 208.422494 -32.31388)
		(width 0.12954)
		(layer "F.Cu")
		(net "INA230_5_A1")
	)
	(segment
		(start 208.054956 -30.676342)
		(end 206.784956 -30.676342)
		(width 0.12954)
		(layer "F.Cu")
		(net "INA230_5_A1")
	)
	(segment
		(start 208.422494 -32.31388)
		(end 208.422494 -33.372044)
		(width 0.12954)
		(layer "F.Cu")
		(net "INA230_5_A1")
	)
	(segment
		(start 209.070956 -30.676342)
		(end 208.054956 -30.676342)
		(width 0.12954)
		(layer "F.Cu")
		(net "INA230_5_A1")
	)
	(via
		(at 206.784956 -30.676342)
		(size 0.762)
		(drill 0.381)
		(layers "F.Cu" "B.Cu")
		(net "INA230_5_A1")
	)
	(segment
		(start 208.92262 -33.372044)
		(end 208.92262 -31.927292)
		(width 0.12954)
		(layer "F.Cu")
		(net "INA230_5_A0")
	)
	(segment
		(start 208.92262 -31.840678)
		(end 210.086956 -30.676342)
		(width 0.12954)
		(layer "F.Cu")
		(net "INA230_5_A0")
	)
	(segment
		(start 208.92262 -31.927292)
		(end 208.92262 -31.840678)
		(width 0.12954)
		(layer "F.Cu")
		(net "INA230_5_A0")
	)
	(segment
		(start 211.102956 -30.676342)
		(end 210.086956 -30.676342)
		(width 0.12954)
		(layer "F.Cu")
		(net "INA230_5_A0")
	)
	(via
		(at 208.92262 -31.927292)
		(size 0.762)
		(drill 0.381)
		(layers "F.Cu" "B.Cu")
		(net "INA230_5_A0")
	)
	(segment
		(start 150.235412 -53.068474)
		(end 151.293576 -53.068474)
		(width 0.12954)
		(layer "F.Cu")
		(net "INA230_4_A1")
	)
	(segment
		(start 148.597874 -54.706012)
		(end 150.235412 -53.068474)
		(width 0.12954)
		(layer "F.Cu")
		(net "INA230_4_A1")
	)
	(segment
		(start 148.597874 -53.436012)
		(end 148.597874 -54.706012)
		(width 0.12954)
		(layer "F.Cu")
		(net "INA230_4_A1")
	)
	(segment
		(start 148.597874 -53.436012)
		(end 148.597874 -52.420012)
		(width 0.12954)
		(layer "F.Cu")
		(net "INA230_4_A1")
	)
	(via
		(at 148.597874 -54.706012)
		(size 0.762)
		(drill 0.381)
		(layers "F.Cu" "B.Cu")
		(net "INA230_4_A1")
	)
	(segment
		(start 149.848824 -52.568348)
		(end 149.76221 -52.568348)
		(width 0.12954)
		(layer "F.Cu")
		(net "INA230_4_A0")
	)
	(segment
		(start 151.293576 -52.568348)
		(end 149.848824 -52.568348)
		(width 0.12954)
		(layer "F.Cu")
		(net "INA230_4_A0")
	)
	(segment
		(start 148.597874 -50.388012)
		(end 148.597874 -51.404012)
		(width 0.12954)
		(layer "F.Cu")
		(net "INA230_4_A0")
	)
	(segment
		(start 149.76221 -52.568348)
		(end 148.597874 -51.404012)
		(width 0.12954)
		(layer "F.Cu")
		(net "INA230_4_A0")
	)
	(via
		(at 149.848824 -52.568348)
		(size 0.762)
		(drill 0.381)
		(layers "F.Cu" "B.Cu")
		(net "INA230_4_A0")
	)
	(segment
		(start 68.612512 -40.437562)
		(end 69.85 -40.437562)
		(width 0.12954)
		(layer "F.Cu")
		(net "INA230_3_A1")
	)
	(segment
		(start 69.85 -40.437562)
		(end 70.217538 -40.070024)
		(width 0.12954)
		(layer "F.Cu")
		(net "INA230_3_A1")
	)
	(segment
		(start 70.217538 -40.070024)
		(end 71.308214 -40.070024)
		(width 0.12954)
		(layer "F.Cu")
		(net "INA230_3_A1")
	)
	(via
		(at 69.85 -40.437562)
		(size 0.762)
		(drill 0.381)
		(layers "F.Cu" "B.Cu")
		(net "INA230_3_A1")
	)
	(segment
		(start 68.953126 -39.080948)
		(end 68.612512 -39.421562)
		(width 0.12954)
		(layer "F.Cu")
		(net "INA230_3_A0")
	)
	(segment
		(start 69.85 -39.080948)
		(end 68.953126 -39.080948)
		(width 0.12954)
		(layer "F.Cu")
		(net "INA230_3_A0")
	)
	(segment
		(start 68.612512 -38.405562)
		(end 68.612512 -39.421562)
		(width 0.12954)
		(layer "F.Cu")
		(net "INA230_3_A0")
	)
	(segment
		(start 70.33895 -39.569898)
		(end 71.308214 -39.569898)
		(width 0.12954)
		(layer "F.Cu")
		(net "INA230_3_A0")
	)
	(segment
		(start 69.85 -39.080948)
		(end 70.33895 -39.569898)
		(width 0.12954)
		(layer "F.Cu")
		(net "INA230_3_A0")
	)
	(via
		(at 69.85 -39.080948)
		(size 0.762)
		(drill 0.381)
		(layers "F.Cu" "B.Cu")
		(net "INA230_3_A0")
	)
	(segment
		(start 213.639146 -55.205376)
		(end 212.88756 -55.956962)
		(width 0.12954)
		(layer "F.Cu")
		(net "INA230_2_A1")
	)
	(segment
		(start 212.06968 -55.956962)
		(end 211.76361 -56.263032)
		(width 0.12954)
		(layer "F.Cu")
		(net "INA230_2_A1")
	)
	(segment
		(start 211.76361 -56.263032)
		(end 211.76361 -57.148222)
		(width 0.12954)
		(layer "F.Cu")
		(net "INA230_2_A1")
	)
	(segment
		(start 212.88756 -55.956962)
		(end 212.06968 -55.956962)
		(width 0.12954)
		(layer "F.Cu")
		(net "INA230_2_A1")
	)
	(segment
		(start 213.859618 -55.205376)
		(end 213.639146 -55.205376)
		(width 0.12954)
		(layer "F.Cu")
		(net "INA230_2_A1")
	)
	(via
		(at 212.06968 -55.956962)
		(size 0.762)
		(drill 0.381)
		(layers "F.Cu" "B.Cu")
		(net "INA230_2_A1")
	)
	(segment
		(start 213.359238 -54.70525)
		(end 213.859618 -54.70525)
		(width 0.12954)
		(layer "F.Cu")
		(net "INA230_2_A0")
	)
	(segment
		(start 212.63864 -55.425848)
		(end 213.359238 -54.70525)
		(width 0.12954)
		(layer "F.Cu")
		(net "INA230_2_A0")
	)
	(via
		(at 212.63864 -55.425848)
		(size 0.508)
		(drill 0.254)
		(layers "F.Cu" "B.Cu")
		(net "INA230_2_A0")
	)
	(segment
		(start 212.63864 -55.425848)
		(end 213.21649 -54.847998)
		(width 0.12954)
		(layer "B.Cu")
		(net "INA230_2_A0")
	)
	(segment
		(start 213.79688 -55.736998)
		(end 213.79688 -54.847998)
		(width 0.12954)
		(layer "B.Cu")
		(net "INA230_2_A0")
	)
	(segment
		(start 213.21649 -54.847998)
		(end 213.79688 -54.847998)
		(width 0.12954)
		(layer "B.Cu")
		(net "INA230_2_A0")
	)
	(segment
		(start 214.03183 -55.971948)
		(end 213.79688 -55.736998)
		(width 0.12954)
		(layer "B.Cu")
		(net "INA230_2_A0")
	)
	(segment
		(start 442.54166 -92.508324)
		(end 442.819536 -92.230448)
		(width 0.12954)
		(layer "F.Cu")
		(net "INA230_1_A1")
	)
	(segment
		(start 442.088016 -93.327474)
		(end 442.32576 -93.327474)
		(width 0.12954)
		(layer "F.Cu")
		(net "INA230_1_A1")
	)
	(segment
		(start 448.272408 -92.493592)
		(end 447.824352 -92.941648)
		(width 0.12954)
		(layer "F.Cu")
		(net "INA230_1_A1")
	)
	(segment
		(start 443.46114 -92.230448)
		(end 444.519304 -92.230448)
		(width 0.12954)
		(layer "F.Cu")
		(net "INA230_1_A1")
	)
	(segment
		(start 444.519304 -92.230448)
		(end 444.757048 -92.468192)
		(width 0.12954)
		(layer "F.Cu")
		(net "INA230_1_A1")
	)
	(segment
		(start 445.08928 -92.941648)
		(end 444.757048 -92.609416)
		(width 0.12954)
		(layer "F.Cu")
		(net "INA230_1_A1")
	)
	(segment
		(start 447.824352 -92.941648)
		(end 445.08928 -92.941648)
		(width 0.12954)
		(layer "F.Cu")
		(net "INA230_1_A1")
	)
	(segment
		(start 442.819536 -92.230448)
		(end 443.46114 -92.230448)
		(width 0.12954)
		(layer "F.Cu")
		(net "INA230_1_A1")
	)
	(segment
		(start 444.757048 -92.609416)
		(end 444.757048 -92.468192)
		(width 0.12954)
		(layer "F.Cu")
		(net "INA230_1_A1")
	)
	(segment
		(start 442.54166 -93.111574)
		(end 442.54166 -92.508324)
		(width 0.12954)
		(layer "F.Cu")
		(net "INA230_1_A1")
	)
	(segment
		(start 442.32576 -93.327474)
		(end 442.54166 -93.111574)
		(width 0.12954)
		(layer "F.Cu")
		(net "INA230_1_A1")
	)
	(via
		(at 443.46114 -92.230448)
		(size 0.762)
		(drill 0.381)
		(layers "F.Cu" "B.Cu")
		(net "INA230_1_A1")
	)
	(segment
		(start 442.539628 -93.8276)
		(end 442.8617 -93.505528)
		(width 0.12954)
		(layer "F.Cu")
		(net "INA230_1_A0")
	)
	(segment
		(start 448.272408 -93.509592)
		(end 447.814192 -93.967808)
		(width 0.12954)
		(layer "F.Cu")
		(net "INA230_1_A0")
	)
	(segment
		(start 442.088016 -93.8276)
		(end 442.539628 -93.8276)
		(width 0.12954)
		(layer "F.Cu")
		(net "INA230_1_A0")
	)
	(segment
		(start 445.240664 -93.967808)
		(end 444.757048 -93.484192)
		(width 0.12954)
		(layer "F.Cu")
		(net "INA230_1_A0")
	)
	(segment
		(start 443.51448 -93.505528)
		(end 443.535816 -93.484192)
		(width 0.12954)
		(layer "F.Cu")
		(net "INA230_1_A0")
	)
	(segment
		(start 442.8617 -93.505528)
		(end 443.51448 -93.505528)
		(width 0.12954)
		(layer "F.Cu")
		(net "INA230_1_A0")
	)
	(segment
		(start 443.535816 -93.484192)
		(end 444.757048 -93.484192)
		(width 0.12954)
		(layer "F.Cu")
		(net "INA230_1_A0")
	)
	(segment
		(start 447.814192 -93.967808)
		(end 445.240664 -93.967808)
		(width 0.12954)
		(layer "F.Cu")
		(net "INA230_1_A0")
	)
	(via
		(at 443.51448 -93.505528)
		(size 0.762)
		(drill 0.381)
		(layers "F.Cu" "B.Cu")
		(net "INA230_1_A0")
	)
	(segment
		(start 37.337492 -406.380188)
		(end 36.888674 -405.93137)
		(width 0.13208)
		(layer "B.Cu")
		(net "USB2_HUB_BUF_SWB_DP")
	)
	(segment
		(start 58.175398 -419.364668)
		(end 55.853838 -419.364668)
		(width 0.13208)
		(layer "B.Cu")
		(net "USB2_HUB_BUF_SWB_DP")
	)
	(segment
		(start 55.853838 -419.364668)
		(end 48.580548 -412.092394)
		(width 0.13208)
		(layer "B.Cu")
		(net "USB2_HUB_BUF_SWB_DP")
	)
	(segment
		(start 38.086538 -406.380188)
		(end 37.337492 -406.380188)
		(width 0.13208)
		(layer "B.Cu")
		(net "USB2_HUB_BUF_SWB_DP")
	)
	(segment
		(start 58.650124 -418.889942)
		(end 58.175398 -419.364668)
		(width 0.13208)
		(layer "B.Cu")
		(net "USB2_HUB_BUF_SWB_DP")
	)
	(segment
		(start 48.580548 -412.092394)
		(end 40.780716 -407.275792)
		(width 0.13208)
		(layer "B.Cu")
		(net "USB2_HUB_BUF_SWB_DP")
	)
	(segment
		(start 40.780716 -407.275792)
		(end 38.086538 -406.380188)
		(width 0.13208)
		(layer "B.Cu")
		(net "USB2_HUB_BUF_SWB_DP")
	)
	(segment
		(start 54.555644 -418.43325)
		(end 54.383178 -418.43325)
		(width 0.13208)
		(layer "B.Cu")
		(net "USB2_HUB_BUF_SWB_DN")
	)
	(segment
		(start 58.650124 -420.089838)
		(end 58.184034 -419.623748)
		(width 0.13208)
		(layer "B.Cu")
		(net "USB2_HUB_BUF_SWB_DN")
	)
	(segment
		(start 55.746396 -419.623748)
		(end 54.555644 -418.43325)
		(width 0.13208)
		(layer "B.Cu")
		(net "USB2_HUB_BUF_SWB_DN")
	)
	(segment
		(start 48.418496 -412.297118)
		(end 40.670226 -407.512266)
		(width 0.13208)
		(layer "B.Cu")
		(net "USB2_HUB_BUF_SWB_DN")
	)
	(segment
		(start 54.11343 -418.163502)
		(end 54.11343 -417.991036)
		(width 0.13208)
		(layer "B.Cu")
		(net "USB2_HUB_BUF_SWB_DN")
	)
	(segment
		(start 54.11343 -417.991036)
		(end 48.418496 -412.297118)
		(width 0.13208)
		(layer "B.Cu")
		(net "USB2_HUB_BUF_SWB_DN")
	)
	(segment
		(start 38.044374 -406.639268)
		(end 37.34562 -406.639268)
		(width 0.13208)
		(layer "B.Cu")
		(net "USB2_HUB_BUF_SWB_DN")
	)
	(segment
		(start 54.383178 -418.43325)
		(end 54.11343 -418.163502)
		(width 0.13208)
		(layer "B.Cu")
		(net "USB2_HUB_BUF_SWB_DN")
	)
	(segment
		(start 58.184034 -419.623748)
		(end 55.746396 -419.623748)
		(width 0.13208)
		(layer "B.Cu")
		(net "USB2_HUB_BUF_SWB_DN")
	)
	(segment
		(start 37.34562 -406.639268)
		(end 36.907724 -407.077164)
		(width 0.13208)
		(layer "B.Cu")
		(net "USB2_HUB_BUF_SWB_DN")
	)
	(segment
		(start 40.670226 -407.512266)
		(end 38.044374 -406.639268)
		(width 0.13208)
		(layer "B.Cu")
		(net "USB2_HUB_BUF_SWB_DN")
	)
	(segment
		(start 36.907724 -407.077164)
		(end 36.888674 -407.077164)
		(width 0.13208)
		(layer "B.Cu")
		(net "USB2_HUB_BUF_SWB_DN")
	)
	(segment
		(start 233.34345 -124.517912)
		(end 233.247946 -124.517912)
		(width 0.0889)
		(layer "F.Cu")
		(net "FM_DB2000_12_OE_N")
	)
	(segment
		(start 233.982006 -124.989844)
		(end 233.815382 -124.989844)
		(width 0.0889)
		(layer "F.Cu")
		(net "FM_DB2000_12_OE_N")
	)
	(segment
		(start 233.815382 -124.989844)
		(end 233.34345 -124.517912)
		(width 0.0889)
		(layer "F.Cu")
		(net "FM_DB2000_12_OE_N")
	)
	(via
		(at 231.721152 -119.99722)
		(size 0.762)
		(drill 0.254)
		(layers "F.Cu" "B.Cu")
		(net "FM_DB2000_12_OE_N")
	)
	(via
		(at 233.982006 -124.989844)
		(size 0.49022)
		(drill 0.254)
		(layers "F.Cu" "B.Cu")
		(net "FM_DB2000_12_OE_N")
	)
	(segment
		(start 231.52608 -119.802148)
		(end 231.52608 -119.160798)
		(width 0.12954)
		(layer "B.Cu")
		(net "FM_DB2000_12_OE_N")
	)
	(segment
		(start 231.721152 -119.99722)
		(end 231.52608 -119.802148)
		(width 0.12954)
		(layer "B.Cu")
		(net "FM_DB2000_12_OE_N")
	)
	(segment
		(start 233.05008 -124.043948)
		(end 233.05008 -121.326148)
		(width 0.127)
		(layer "In2.Cu")
		(net "FM_DB2000_12_OE_N")
	)
	(segment
		(start 233.982006 -124.975874)
		(end 233.05008 -124.043948)
		(width 0.127)
		(layer "In2.Cu")
		(net "FM_DB2000_12_OE_N")
	)
	(segment
		(start 233.05008 -121.326148)
		(end 231.721152 -119.99722)
		(width 0.127)
		(layer "In2.Cu")
		(net "FM_DB2000_12_OE_N")
	)
	(segment
		(start 233.982006 -124.989844)
		(end 233.982006 -124.975874)
		(width 0.127)
		(layer "In2.Cu")
		(net "FM_DB2000_12_OE_N")
	)
	(segment
		(start 233.051858 -125.441456)
		(end 232.844848 -125.162564)
		(width 0.0889)
		(layer "F.Cu")
		(net "FM_DB2000_11_OE_N")
	)
	(segment
		(start 232.844848 -125.162564)
		(end 232.748074 -125.017784)
		(width 0.0889)
		(layer "F.Cu")
		(net "FM_DB2000_11_OE_N")
	)
	(segment
		(start 233.191812 -125.58141)
		(end 233.051858 -125.441456)
		(width 0.0889)
		(layer "F.Cu")
		(net "FM_DB2000_11_OE_N")
	)
	(segment
		(start 233.191812 -125.774958)
		(end 233.191812 -125.58141)
		(width 0.0889)
		(layer "F.Cu")
		(net "FM_DB2000_11_OE_N")
	)
	(via
		(at 230.93426 -120.241568)
		(size 0.508)
		(drill 0.254)
		(layers "F.Cu" "B.Cu")
		(net "FM_DB2000_11_OE_N")
	)
	(via
		(at 233.191812 -125.774958)
		(size 0.49022)
		(drill 0.254)
		(layers "F.Cu" "B.Cu")
		(net "FM_DB2000_11_OE_N")
	)
	(segment
		(start 230.48468 -119.791988)
		(end 230.48468 -119.160798)
		(width 0.12954)
		(layer "B.Cu")
		(net "FM_DB2000_11_OE_N")
	)
	(segment
		(start 230.93426 -120.241568)
		(end 230.48468 -119.791988)
		(width 0.12954)
		(layer "B.Cu")
		(net "FM_DB2000_11_OE_N")
	)
	(segment
		(start 232.03408 -122.05589)
		(end 230.93426 -120.95607)
		(width 0.127)
		(layer "In2.Cu")
		(net "FM_DB2000_11_OE_N")
	)
	(segment
		(start 233.191812 -125.774958)
		(end 232.03408 -124.617226)
		(width 0.127)
		(layer "In2.Cu")
		(net "FM_DB2000_11_OE_N")
	)
	(segment
		(start 232.03408 -124.617226)
		(end 232.03408 -122.05589)
		(width 0.127)
		(layer "In2.Cu")
		(net "FM_DB2000_11_OE_N")
	)
	(segment
		(start 230.93426 -120.95607)
		(end 230.93426 -120.241568)
		(width 0.127)
		(layer "In2.Cu")
		(net "FM_DB2000_11_OE_N")
	)
	(segment
		(start 12.530582 -422.566846)
		(end 12.530582 -423.229786)
		(width 0.12954)
		(layer "F.Cu")
		(net "SMB_IOEXP_3V3AUX_SDA_R1")
	)
	(segment
		(start 14.389862 -420.707566)
		(end 13.85189 -421.245538)
		(width 0.12954)
		(layer "F.Cu")
		(net "SMB_IOEXP_3V3AUX_SDA_R1")
	)
	(segment
		(start 13.85189 -421.245538)
		(end 12.530582 -422.566846)
		(width 0.12954)
		(layer "F.Cu")
		(net "SMB_IOEXP_3V3AUX_SDA_R1")
	)
	(segment
		(start 14.389862 -420.12743)
		(end 14.389862 -420.707566)
		(width 0.12954)
		(layer "F.Cu")
		(net "SMB_IOEXP_3V3AUX_SDA_R1")
	)
	(via
		(at 13.85189 -421.245538)
		(size 0.508)
		(drill 0.254)
		(layers "F.Cu" "B.Cu")
		(net "SMB_IOEXP_3V3AUX_SDA_R1")
	)
	(segment
		(start 117.012466 -134.296658)
		(end 118.108476 -134.296658)
		(width 0.12954)
		(layer "F.Cu")
		(net "SMB_IOEXP_3V3AUX_SDA_R")
	)
	(segment
		(start 116.693442 -134.615682)
		(end 117.012466 -134.296658)
		(width 0.12954)
		(layer "F.Cu")
		(net "SMB_IOEXP_3V3AUX_SDA_R")
	)
	(segment
		(start 116.185442 -134.615682)
		(end 116.693442 -134.615682)
		(width 0.12954)
		(layer "F.Cu")
		(net "SMB_IOEXP_3V3AUX_SDA_R")
	)
	(segment
		(start 113.894362 -133.721602)
		(end 114.788442 -134.615682)
		(width 0.12954)
		(layer "F.Cu")
		(net "SMB_IOEXP_3V3AUX_SDA_R")
	)
	(segment
		(start 114.788442 -134.615682)
		(end 116.185442 -134.615682)
		(width 0.12954)
		(layer "F.Cu")
		(net "SMB_IOEXP_3V3AUX_SDA_R")
	)
	(segment
		(start 113.894362 -133.472682)
		(end 113.894362 -133.721602)
		(width 0.12954)
		(layer "F.Cu")
		(net "SMB_IOEXP_3V3AUX_SDA_R")
	)
	(via
		(at 116.185442 -134.615682)
		(size 0.762)
		(drill 0.381)
		(layers "F.Cu" "B.Cu")
		(net "SMB_IOEXP_3V3AUX_SDA_R")
	)
	(segment
		(start 113.094262 -133.472682)
		(end 112.903762 -133.663182)
		(width 0.12954)
		(layer "F.Cu")
		(net "SMB_IOEXP_3V3AUX_SDA")
	)
	(segment
		(start 12.260326 -424.300142)
		(end 12.530582 -424.029886)
		(width 0.12954)
		(layer "F.Cu")
		(net "SMB_IOEXP_3V3AUX_SDA")
	)
	(segment
		(start 112.903762 -133.663182)
		(end 111.732822 -133.663182)
		(width 0.12954)
		(layer "F.Cu")
		(net "SMB_IOEXP_3V3AUX_SDA")
	)
	(segment
		(start 111.003588 -132.933948)
		(end 111.732822 -133.663182)
		(width 0.12954)
		(layer "F.Cu")
		(net "SMB_IOEXP_3V3AUX_SDA")
	)
	(segment
		(start 12.260326 -424.883834)
		(end 12.260326 -424.300142)
		(width 0.12954)
		(layer "F.Cu")
		(net "SMB_IOEXP_3V3AUX_SDA")
	)
	(segment
		(start 109.52988 -132.933948)
		(end 111.003588 -132.933948)
		(width 0.12954)
		(layer "F.Cu")
		(net "SMB_IOEXP_3V3AUX_SDA")
	)
	(via
		(at 8.31088 -151.994108)
		(size 0.508)
		(drill 0.254)
		(layers "F.Cu" "B.Cu")
		(net "SMB_IOEXP_3V3AUX_SDA")
	)
	(via
		(at 12.260326 -424.883834)
		(size 0.508)
		(drill 0.254)
		(layers "F.Cu" "B.Cu")
		(net "SMB_IOEXP_3V3AUX_SDA")
	)
	(via
		(at 109.52988 -132.933948)
		(size 0.508)
		(drill 0.254)
		(layers "F.Cu" "B.Cu")
		(net "SMB_IOEXP_3V3AUX_SDA")
	)
	(segment
		(start 5.26288 -401.24507)
		(end 5.26288 -375.479818)
		(width 0.127)
		(layer "In2.Cu")
		(net "SMB_IOEXP_3V3AUX_SDA")
	)
	(segment
		(start 12.962382 -424.181778)
		(end 12.962382 -416.12058)
		(width 0.127)
		(layer "In2.Cu")
		(net "SMB_IOEXP_3V3AUX_SDA")
	)
	(segment
		(start 12.962382 -416.12058)
		(end 9.19988 -412.358078)
		(width 0.127)
		(layer "In2.Cu")
		(net "SMB_IOEXP_3V3AUX_SDA")
	)
	(segment
		(start 5.26288 -375.479818)
		(end 16.94688 -363.795818)
		(width 0.127)
		(layer "In2.Cu")
		(net "SMB_IOEXP_3V3AUX_SDA")
	)
	(segment
		(start 9.19988 -405.18207)
		(end 5.26288 -401.24507)
		(width 0.127)
		(layer "In2.Cu")
		(net "SMB_IOEXP_3V3AUX_SDA")
	)
	(segment
		(start 3.87858 -156.797248)
		(end 8.31088 -152.364948)
		(width 0.127)
		(layer "In2.Cu")
		(net "SMB_IOEXP_3V3AUX_SDA")
	)
	(segment
		(start 16.94688 -345.962478)
		(end 3.87858 -332.894178)
		(width 0.127)
		(layer "In2.Cu")
		(net "SMB_IOEXP_3V3AUX_SDA")
	)
	(segment
		(start 12.260326 -424.883834)
		(end 12.962382 -424.181778)
		(width 0.127)
		(layer "In2.Cu")
		(net "SMB_IOEXP_3V3AUX_SDA")
	)
	(segment
		(start 9.19988 -412.358078)
		(end 9.19988 -405.18207)
		(width 0.127)
		(layer "In2.Cu")
		(net "SMB_IOEXP_3V3AUX_SDA")
	)
	(segment
		(start 3.87858 -332.894178)
		(end 3.87858 -156.797248)
		(width 0.127)
		(layer "In2.Cu")
		(net "SMB_IOEXP_3V3AUX_SDA")
	)
	(segment
		(start 8.31088 -152.364948)
		(end 8.31088 -151.994108)
		(width 0.127)
		(layer "In2.Cu")
		(net "SMB_IOEXP_3V3AUX_SDA")
	)
	(segment
		(start 16.94688 -363.795818)
		(end 16.94688 -345.962478)
		(width 0.127)
		(layer "In2.Cu")
		(net "SMB_IOEXP_3V3AUX_SDA")
	)
	(segment
		(start 8.31088 -151.994108)
		(end 9.18972 -152.872948)
		(width 0.127)
		(layer "In6.Cu")
		(net "SMB_IOEXP_3V3AUX_SDA")
	)
	(segment
		(start 108.633514 -132.037582)
		(end 109.52988 -132.933948)
		(width 0.127)
		(layer "In6.Cu")
		(net "SMB_IOEXP_3V3AUX_SDA")
	)
	(segment
		(start 15.95628 -148.457158)
		(end 15.95628 -129.864358)
		(width 0.127)
		(layer "In6.Cu")
		(net "SMB_IOEXP_3V3AUX_SDA")
	)
	(segment
		(start 105.000044 -132.037582)
		(end 108.633514 -132.037582)
		(width 0.127)
		(layer "In6.Cu")
		(net "SMB_IOEXP_3V3AUX_SDA")
	)
	(segment
		(start 11.54049 -152.872948)
		(end 15.95628 -148.457158)
		(width 0.127)
		(layer "In6.Cu")
		(net "SMB_IOEXP_3V3AUX_SDA")
	)
	(segment
		(start 30.15869 -121.072148)
		(end 31.55569 -119.675148)
		(width 0.127)
		(layer "In6.Cu")
		(net "SMB_IOEXP_3V3AUX_SDA")
	)
	(segment
		(start 9.18972 -152.872948)
		(end 11.54049 -152.872948)
		(width 0.127)
		(layer "In6.Cu")
		(net "SMB_IOEXP_3V3AUX_SDA")
	)
	(segment
		(start 43.00347 -119.675148)
		(end 50.77587 -127.447548)
		(width 0.127)
		(layer "In6.Cu")
		(net "SMB_IOEXP_3V3AUX_SDA")
	)
	(segment
		(start 100.41001 -127.447548)
		(end 105.000044 -132.037582)
		(width 0.127)
		(layer "In6.Cu")
		(net "SMB_IOEXP_3V3AUX_SDA")
	)
	(segment
		(start 50.77587 -127.447548)
		(end 100.41001 -127.447548)
		(width 0.127)
		(layer "In6.Cu")
		(net "SMB_IOEXP_3V3AUX_SDA")
	)
	(segment
		(start 15.95628 -129.864358)
		(end 24.74849 -121.072148)
		(width 0.127)
		(layer "In6.Cu")
		(net "SMB_IOEXP_3V3AUX_SDA")
	)
	(segment
		(start 24.74849 -121.072148)
		(end 30.15869 -121.072148)
		(width 0.127)
		(layer "In6.Cu")
		(net "SMB_IOEXP_3V3AUX_SDA")
	)
	(segment
		(start 31.55569 -119.675148)
		(end 43.00347 -119.675148)
		(width 0.127)
		(layer "In6.Cu")
		(net "SMB_IOEXP_3V3AUX_SDA")
	)
	(segment
		(start 15.039848 -421.36949)
		(end 15.039848 -420.12743)
		(width 0.12954)
		(layer "F.Cu")
		(net "SMB_IOEXP_3V3AUX_SCL_R1")
	)
	(segment
		(start 13.837412 -422.571926)
		(end 15.039848 -421.36949)
		(width 0.12954)
		(layer "F.Cu")
		(net "SMB_IOEXP_3V3AUX_SCL_R1")
	)
	(segment
		(start 13.546582 -422.862756)
		(end 13.837412 -422.571926)
		(width 0.12954)
		(layer "F.Cu")
		(net "SMB_IOEXP_3V3AUX_SCL_R1")
	)
	(segment
		(start 13.546582 -423.229786)
		(end 13.546582 -422.862756)
		(width 0.12954)
		(layer "F.Cu")
		(net "SMB_IOEXP_3V3AUX_SCL_R1")
	)
	(via
		(at 13.837412 -422.571926)
		(size 0.508)
		(drill 0.254)
		(layers "F.Cu" "B.Cu")
		(net "SMB_IOEXP_3V3AUX_SCL_R1")
	)
	(segment
		(start 113.894362 -132.705602)
		(end 114.835178 -133.646418)
		(width 0.12954)
		(layer "F.Cu")
		(net "SMB_IOEXP_3V3AUX_SCL_R")
	)
	(segment
		(start 115.169442 -133.646418)
		(end 118.108476 -133.646418)
		(width 0.12954)
		(layer "F.Cu")
		(net "SMB_IOEXP_3V3AUX_SCL_R")
	)
	(segment
		(start 113.894362 -132.456682)
		(end 113.894362 -132.705602)
		(width 0.12954)
		(layer "F.Cu")
		(net "SMB_IOEXP_3V3AUX_SCL_R")
	)
	(segment
		(start 114.835178 -133.646418)
		(end 115.169442 -133.646418)
		(width 0.12954)
		(layer "F.Cu")
		(net "SMB_IOEXP_3V3AUX_SCL_R")
	)
	(via
		(at 115.169442 -133.646418)
		(size 0.762)
		(drill 0.381)
		(layers "F.Cu" "B.Cu")
		(net "SMB_IOEXP_3V3AUX_SCL_R")
	)
	(segment
		(start 109.52988 -131.605782)
		(end 111.072422 -131.605782)
		(width 0.12954)
		(layer "F.Cu")
		(net "SMB_IOEXP_3V3AUX_SCL")
	)
	(segment
		(start 111.072422 -131.605782)
		(end 111.732822 -132.266182)
		(width 0.12954)
		(layer "F.Cu")
		(net "SMB_IOEXP_3V3AUX_SCL")
	)
	(segment
		(start 113.094262 -132.456682)
		(end 111.923322 -132.456682)
		(width 0.12954)
		(layer "F.Cu")
		(net "SMB_IOEXP_3V3AUX_SCL")
	)
	(segment
		(start 111.923322 -132.456682)
		(end 111.732822 -132.266182)
		(width 0.12954)
		(layer "F.Cu")
		(net "SMB_IOEXP_3V3AUX_SCL")
	)
	(segment
		(start 13.546582 -424.029886)
		(end 13.546582 -424.652948)
		(width 0.12954)
		(layer "F.Cu")
		(net "SMB_IOEXP_3V3AUX_SCL")
	)
	(via
		(at 13.546582 -424.652948)
		(size 0.508)
		(drill 0.254)
		(layers "F.Cu" "B.Cu")
		(net "SMB_IOEXP_3V3AUX_SCL")
	)
	(via
		(at 109.52988 -131.605782)
		(size 0.508)
		(drill 0.254)
		(layers "F.Cu" "B.Cu")
		(net "SMB_IOEXP_3V3AUX_SCL")
	)
	(via
		(at 8.38708 -151.188928)
		(size 0.508)
		(drill 0.254)
		(layers "F.Cu" "B.Cu")
		(net "SMB_IOEXP_3V3AUX_SCL")
	)
	(segment
		(start 8.76808 -412.537148)
		(end 8.76808 -405.36114)
		(width 0.127)
		(layer "In2.Cu")
		(net "SMB_IOEXP_3V3AUX_SCL")
	)
	(segment
		(start 12.14882 -425.460668)
		(end 11.57224 -424.884088)
		(width 0.127)
		(layer "In2.Cu")
		(net "SMB_IOEXP_3V3AUX_SCL")
	)
	(segment
		(start 12.530582 -416.29965)
		(end 8.76808 -412.537148)
		(width 0.127)
		(layer "In2.Cu")
		(net "SMB_IOEXP_3V3AUX_SCL")
	)
	(segment
		(start 12.738862 -425.460668)
		(end 12.14882 -425.460668)
		(width 0.127)
		(layer "In2.Cu")
		(net "SMB_IOEXP_3V3AUX_SCL")
	)
	(segment
		(start 8.001 -151.188928)
		(end 8.38708 -151.188928)
		(width 0.127)
		(layer "In2.Cu")
		(net "SMB_IOEXP_3V3AUX_SCL")
	)
	(segment
		(start 8.76808 -405.36114)
		(end 4.83108 -401.42414)
		(width 0.127)
		(layer "In2.Cu")
		(net "SMB_IOEXP_3V3AUX_SCL")
	)
	(segment
		(start 3.44678 -155.743148)
		(end 8.001 -151.188928)
		(width 0.127)
		(layer "In2.Cu")
		(net "SMB_IOEXP_3V3AUX_SCL")
	)
	(segment
		(start 12.530582 -422.874948)
		(end 12.530582 -416.29965)
		(width 0.127)
		(layer "In2.Cu")
		(net "SMB_IOEXP_3V3AUX_SCL")
	)
	(segment
		(start 11.57224 -424.884088)
		(end 11.57224 -423.83329)
		(width 0.127)
		(layer "In2.Cu")
		(net "SMB_IOEXP_3V3AUX_SCL")
	)
	(segment
		(start 13.546582 -424.652948)
		(end 12.738862 -425.460668)
		(width 0.127)
		(layer "In2.Cu")
		(net "SMB_IOEXP_3V3AUX_SCL")
	)
	(segment
		(start 4.83108 -375.300748)
		(end 16.51508 -363.616748)
		(width 0.127)
		(layer "In2.Cu")
		(net "SMB_IOEXP_3V3AUX_SCL")
	)
	(segment
		(start 4.83108 -401.42414)
		(end 4.83108 -375.300748)
		(width 0.127)
		(layer "In2.Cu")
		(net "SMB_IOEXP_3V3AUX_SCL")
	)
	(segment
		(start 11.57224 -423.83329)
		(end 12.530582 -422.874948)
		(width 0.127)
		(layer "In2.Cu")
		(net "SMB_IOEXP_3V3AUX_SCL")
	)
	(segment
		(start 16.51508 -346.141548)
		(end 3.44678 -333.073248)
		(width 0.127)
		(layer "In2.Cu")
		(net "SMB_IOEXP_3V3AUX_SCL")
	)
	(segment
		(start 3.44678 -333.073248)
		(end 3.44678 -155.743148)
		(width 0.127)
		(layer "In2.Cu")
		(net "SMB_IOEXP_3V3AUX_SCL")
	)
	(segment
		(start 16.51508 -363.616748)
		(end 16.51508 -346.141548)
		(width 0.127)
		(layer "In2.Cu")
		(net "SMB_IOEXP_3V3AUX_SCL")
	)
	(segment
		(start 29.97962 -120.640348)
		(end 31.37662 -119.243348)
		(width 0.127)
		(layer "In6.Cu")
		(net "SMB_IOEXP_3V3AUX_SCL")
	)
	(segment
		(start 100.58908 -127.015748)
		(end 105.179114 -131.605782)
		(width 0.127)
		(layer "In6.Cu")
		(net "SMB_IOEXP_3V3AUX_SCL")
	)
	(segment
		(start 15.52448 -148.278088)
		(end 15.52448 -129.685288)
		(width 0.127)
		(layer "In6.Cu")
		(net "SMB_IOEXP_3V3AUX_SCL")
	)
	(segment
		(start 50.95494 -127.015748)
		(end 100.58908 -127.015748)
		(width 0.127)
		(layer "In6.Cu")
		(net "SMB_IOEXP_3V3AUX_SCL")
	)
	(segment
		(start 11.69162 -152.110948)
		(end 15.52448 -148.278088)
		(width 0.127)
		(layer "In6.Cu")
		(net "SMB_IOEXP_3V3AUX_SCL")
	)
	(segment
		(start 24.56942 -120.640348)
		(end 29.97962 -120.640348)
		(width 0.127)
		(layer "In6.Cu")
		(net "SMB_IOEXP_3V3AUX_SCL")
	)
	(segment
		(start 43.18254 -119.243348)
		(end 50.95494 -127.015748)
		(width 0.127)
		(layer "In6.Cu")
		(net "SMB_IOEXP_3V3AUX_SCL")
	)
	(segment
		(start 8.38708 -151.188928)
		(end 9.3091 -152.110948)
		(width 0.127)
		(layer "In6.Cu")
		(net "SMB_IOEXP_3V3AUX_SCL")
	)
	(segment
		(start 15.52448 -129.685288)
		(end 24.56942 -120.640348)
		(width 0.127)
		(layer "In6.Cu")
		(net "SMB_IOEXP_3V3AUX_SCL")
	)
	(segment
		(start 9.3091 -152.110948)
		(end 11.69162 -152.110948)
		(width 0.127)
		(layer "In6.Cu")
		(net "SMB_IOEXP_3V3AUX_SCL")
	)
	(segment
		(start 31.37662 -119.243348)
		(end 43.18254 -119.243348)
		(width 0.127)
		(layer "In6.Cu")
		(net "SMB_IOEXP_3V3AUX_SCL")
	)
	(segment
		(start 105.179114 -131.605782)
		(end 109.52988 -131.605782)
		(width 0.127)
		(layer "In6.Cu")
		(net "SMB_IOEXP_3V3AUX_SCL")
	)
	(segment
		(start 292.22827 -92.260674)
		(end 292.10127 -92.133674)
		(width 0.12954)
		(layer "F.Cu")
		(net "SMB_FRU_3V3AUX_SDA")
	)
	(segment
		(start 128.801622 -131.018026)
		(end 129.961894 -131.018026)
		(width 0.12954)
		(layer "F.Cu")
		(net "SMB_FRU_3V3AUX_SDA")
	)
	(segment
		(start 291.133784 -92.51569)
		(end 286.994854 -92.51569)
		(width 0.12954)
		(layer "F.Cu")
		(net "SMB_FRU_3V3AUX_SDA")
	)
	(segment
		(start 292.10127 -92.133674)
		(end 291.5158 -92.133674)
		(width 0.12954)
		(layer "F.Cu")
		(net "SMB_FRU_3V3AUX_SDA")
	)
	(segment
		(start 291.5158 -92.133674)
		(end 291.133784 -92.51569)
		(width 0.12954)
		(layer "F.Cu")
		(net "SMB_FRU_3V3AUX_SDA")
	)
	(segment
		(start 133.15188 -129.504948)
		(end 132.867654 -129.220722)
		(width 0.12954)
		(layer "F.Cu")
		(net "SMB_FRU_3V3AUX_SDA")
	)
	(segment
		(start 131.759198 -129.220722)
		(end 131.066794 -129.913126)
		(width 0.12954)
		(layer "F.Cu")
		(net "SMB_FRU_3V3AUX_SDA")
	)
	(segment
		(start 133.15188 -129.885948)
		(end 133.15188 -129.504948)
		(width 0.12954)
		(layer "F.Cu")
		(net "SMB_FRU_3V3AUX_SDA")
	)
	(segment
		(start 132.867654 -129.220722)
		(end 131.759198 -129.220722)
		(width 0.12954)
		(layer "F.Cu")
		(net "SMB_FRU_3V3AUX_SDA")
	)
	(segment
		(start 129.961894 -131.018026)
		(end 131.066794 -129.913126)
		(width 0.12954)
		(layer "F.Cu")
		(net "SMB_FRU_3V3AUX_SDA")
	)
	(via
		(at 290.75888 -126.660148)
		(size 0.508)
		(drill 0.254)
		(layers "F.Cu" "B.Cu")
		(net "SMB_FRU_3V3AUX_SDA")
	)
	(via
		(at 291.5158 -92.133674)
		(size 0.508)
		(drill 0.254)
		(layers "F.Cu" "B.Cu")
		(net "SMB_FRU_3V3AUX_SDA")
	)
	(via
		(at 133.15188 -129.885948)
		(size 0.508)
		(drill 0.254)
		(layers "F.Cu" "B.Cu")
		(net "SMB_FRU_3V3AUX_SDA")
	)
	(segment
		(start 290.75888 -126.660148)
		(end 290.75888 -92.890594)
		(width 0.127)
		(layer "In2.Cu")
		(net "SMB_FRU_3V3AUX_SDA")
	)
	(segment
		(start 290.75888 -92.890594)
		(end 291.5158 -92.133674)
		(width 0.127)
		(layer "In2.Cu")
		(net "SMB_FRU_3V3AUX_SDA")
	)
	(segment
		(start 211.00161 -140.569188)
		(end 213.49843 -138.072368)
		(width 0.127)
		(layer "In15.Cu")
		(net "SMB_FRU_3V3AUX_SDA")
	)
	(segment
		(start 133.27888 -130.368548)
		(end 138.43635 -130.368548)
		(width 0.127)
		(layer "In15.Cu")
		(net "SMB_FRU_3V3AUX_SDA")
	)
	(segment
		(start 252.73381 -128.819148)
		(end 256.54381 -128.819148)
		(width 0.127)
		(layer "In15.Cu")
		(net "SMB_FRU_3V3AUX_SDA")
	)
	(segment
		(start 133.15188 -130.241548)
		(end 133.27888 -130.368548)
		(width 0.127)
		(layer "In15.Cu")
		(net "SMB_FRU_3V3AUX_SDA")
	)
	(segment
		(start 147.05965 -138.991848)
		(end 156.64307 -138.991848)
		(width 0.127)
		(layer "In15.Cu")
		(net "SMB_FRU_3V3AUX_SDA")
	)
	(segment
		(start 213.49843 -138.072368)
		(end 247.197626 -138.072368)
		(width 0.127)
		(layer "In15.Cu")
		(net "SMB_FRU_3V3AUX_SDA")
	)
	(segment
		(start 247.197626 -138.072368)
		(end 249.547888 -135.722106)
		(width 0.127)
		(layer "In15.Cu")
		(net "SMB_FRU_3V3AUX_SDA")
	)
	(segment
		(start 256.54381 -128.819148)
		(end 258.70281 -126.660148)
		(width 0.127)
		(layer "In15.Cu")
		(net "SMB_FRU_3V3AUX_SDA")
	)
	(segment
		(start 258.70281 -126.660148)
		(end 290.75888 -126.660148)
		(width 0.127)
		(layer "In15.Cu")
		(net "SMB_FRU_3V3AUX_SDA")
	)
	(segment
		(start 158.22041 -140.569188)
		(end 211.00161 -140.569188)
		(width 0.127)
		(layer "In15.Cu")
		(net "SMB_FRU_3V3AUX_SDA")
	)
	(segment
		(start 138.43635 -130.368548)
		(end 147.05965 -138.991848)
		(width 0.127)
		(layer "In15.Cu")
		(net "SMB_FRU_3V3AUX_SDA")
	)
	(segment
		(start 249.547888 -132.00507)
		(end 252.73381 -128.819148)
		(width 0.127)
		(layer "In15.Cu")
		(net "SMB_FRU_3V3AUX_SDA")
	)
	(segment
		(start 249.547888 -135.722106)
		(end 249.547888 -132.00507)
		(width 0.127)
		(layer "In15.Cu")
		(net "SMB_FRU_3V3AUX_SDA")
	)
	(segment
		(start 156.64307 -138.991848)
		(end 158.22041 -140.569188)
		(width 0.127)
		(layer "In15.Cu")
		(net "SMB_FRU_3V3AUX_SDA")
	)
	(segment
		(start 133.15188 -129.885948)
		(end 133.15188 -130.241548)
		(width 0.127)
		(layer "In15.Cu")
		(net "SMB_FRU_3V3AUX_SDA")
	)
	(segment
		(start 133.15188 -131.155948)
		(end 132.672074 -130.676142)
		(width 0.12954)
		(layer "F.Cu")
		(net "SMB_FRU_3V3AUX_SCL")
	)
	(segment
		(start 130.342894 -132.034026)
		(end 131.066794 -131.310126)
		(width 0.12954)
		(layer "F.Cu")
		(net "SMB_FRU_3V3AUX_SCL")
	)
	(segment
		(start 132.672074 -130.676142)
		(end 131.700778 -130.676142)
		(width 0.12954)
		(layer "F.Cu")
		(net "SMB_FRU_3V3AUX_SCL")
	)
	(segment
		(start 131.700778 -130.676142)
		(end 131.066794 -131.310126)
		(width 0.12954)
		(layer "F.Cu")
		(net "SMB_FRU_3V3AUX_SCL")
	)
	(segment
		(start 128.801622 -132.034026)
		(end 130.342894 -132.034026)
		(width 0.12954)
		(layer "F.Cu")
		(net "SMB_FRU_3V3AUX_SCL")
	)
	(segment
		(start 291.212524 -93.78569)
		(end 286.994854 -93.78569)
		(width 0.12954)
		(layer "F.Cu")
		(net "SMB_FRU_3V3AUX_SCL")
	)
	(segment
		(start 292.21049 -93.482414)
		(end 291.5158 -93.482414)
		(width 0.12954)
		(layer "F.Cu")
		(net "SMB_FRU_3V3AUX_SCL")
	)
	(segment
		(start 133.15188 -131.282948)
		(end 133.15188 -131.155948)
		(width 0.12954)
		(layer "F.Cu")
		(net "SMB_FRU_3V3AUX_SCL")
	)
	(segment
		(start 291.5158 -93.482414)
		(end 291.212524 -93.78569)
		(width 0.12954)
		(layer "F.Cu")
		(net "SMB_FRU_3V3AUX_SCL")
	)
	(via
		(at 290.75888 -127.345948)
		(size 0.508)
		(drill 0.254)
		(layers "F.Cu" "B.Cu")
		(net "SMB_FRU_3V3AUX_SCL")
	)
	(via
		(at 133.15188 -131.282948)
		(size 0.508)
		(drill 0.254)
		(layers "F.Cu" "B.Cu")
		(net "SMB_FRU_3V3AUX_SCL")
	)
	(via
		(at 291.5158 -93.482414)
		(size 0.508)
		(drill 0.254)
		(layers "F.Cu" "B.Cu")
		(net "SMB_FRU_3V3AUX_SCL")
	)
	(segment
		(start 291.39388 -126.710948)
		(end 291.39388 -93.604334)
		(width 0.127)
		(layer "In2.Cu")
		(net "SMB_FRU_3V3AUX_SCL")
	)
	(segment
		(start 290.75888 -127.345948)
		(end 291.39388 -126.710948)
		(width 0.127)
		(layer "In2.Cu")
		(net "SMB_FRU_3V3AUX_SCL")
	)
	(segment
		(start 291.39388 -93.604334)
		(end 291.5158 -93.482414)
		(width 0.127)
		(layer "In2.Cu")
		(net "SMB_FRU_3V3AUX_SCL")
	)
	(segment
		(start 249.997976 -132.165852)
		(end 249.997976 -135.896096)
		(width 0.127)
		(layer "In15.Cu")
		(net "SMB_FRU_3V3AUX_SCL")
	)
	(segment
		(start 146.88058 -139.423648)
		(end 138.25728 -130.800348)
		(width 0.127)
		(layer "In15.Cu")
		(net "SMB_FRU_3V3AUX_SCL")
	)
	(segment
		(start 133.27888 -130.800348)
		(end 133.15188 -130.927348)
		(width 0.127)
		(layer "In15.Cu")
		(net "SMB_FRU_3V3AUX_SCL")
	)
	(segment
		(start 290.50488 -127.091948)
		(end 258.88188 -127.091948)
		(width 0.127)
		(layer "In15.Cu")
		(net "SMB_FRU_3V3AUX_SCL")
	)
	(segment
		(start 258.88188 -127.091948)
		(end 256.72288 -129.250948)
		(width 0.127)
		(layer "In15.Cu")
		(net "SMB_FRU_3V3AUX_SCL")
	)
	(segment
		(start 249.997976 -135.896096)
		(end 247.389904 -138.504168)
		(width 0.127)
		(layer "In15.Cu")
		(net "SMB_FRU_3V3AUX_SCL")
	)
	(segment
		(start 213.6775 -138.504168)
		(end 211.18068 -141.000988)
		(width 0.127)
		(layer "In15.Cu")
		(net "SMB_FRU_3V3AUX_SCL")
	)
	(segment
		(start 138.25728 -130.800348)
		(end 133.27888 -130.800348)
		(width 0.127)
		(layer "In15.Cu")
		(net "SMB_FRU_3V3AUX_SCL")
	)
	(segment
		(start 133.15188 -130.927348)
		(end 133.15188 -131.282948)
		(width 0.127)
		(layer "In15.Cu")
		(net "SMB_FRU_3V3AUX_SCL")
	)
	(segment
		(start 290.75888 -127.345948)
		(end 290.50488 -127.091948)
		(width 0.127)
		(layer "In15.Cu")
		(net "SMB_FRU_3V3AUX_SCL")
	)
	(segment
		(start 252.91288 -129.250948)
		(end 249.997976 -132.165852)
		(width 0.127)
		(layer "In15.Cu")
		(net "SMB_FRU_3V3AUX_SCL")
	)
	(segment
		(start 211.18068 -141.000988)
		(end 158.04134 -141.000988)
		(width 0.127)
		(layer "In15.Cu")
		(net "SMB_FRU_3V3AUX_SCL")
	)
	(segment
		(start 156.464 -139.423648)
		(end 146.88058 -139.423648)
		(width 0.127)
		(layer "In15.Cu")
		(net "SMB_FRU_3V3AUX_SCL")
	)
	(segment
		(start 158.04134 -141.000988)
		(end 156.464 -139.423648)
		(width 0.127)
		(layer "In15.Cu")
		(net "SMB_FRU_3V3AUX_SCL")
	)
	(segment
		(start 256.72288 -129.250948)
		(end 252.91288 -129.250948)
		(width 0.127)
		(layer "In15.Cu")
		(net "SMB_FRU_3V3AUX_SCL")
	)
	(segment
		(start 247.389904 -138.504168)
		(end 213.6775 -138.504168)
		(width 0.127)
		(layer "In15.Cu")
		(net "SMB_FRU_3V3AUX_SCL")
	)
	(segment
		(start 165.53815 -418.114226)
		(end 165.53815 -417.422838)
		(width 0.12954)
		(layer "F.Cu")
		(net "SMB_BMC_SWB_BUF_SDA")
	)
	(segment
		(start 162.348164 -417.542218)
		(end 163.05149 -416.838892)
		(width 0.12954)
		(layer "F.Cu")
		(net "SMB_BMC_SWB_BUF_SDA")
	)
	(segment
		(start 161.45256 -423.51706)
		(end 162.348164 -422.621456)
		(width 0.12954)
		(layer "F.Cu")
		(net "SMB_BMC_SWB_BUF_SDA")
	)
	(segment
		(start 161.722308 -426.11294)
		(end 161.45256 -425.843192)
		(width 0.12954)
		(layer "F.Cu")
		(net "SMB_BMC_SWB_BUF_SDA")
	)
	(segment
		(start 163.05149 -416.838892)
		(end 165.332156 -416.838892)
		(width 0.12954)
		(layer "F.Cu")
		(net "SMB_BMC_SWB_BUF_SDA")
	)
	(segment
		(start 165.332156 -416.838892)
		(end 165.53815 -417.044886)
		(width 0.12954)
		(layer "F.Cu")
		(net "SMB_BMC_SWB_BUF_SDA")
	)
	(segment
		(start 162.348164 -422.621456)
		(end 162.348164 -417.542218)
		(width 0.12954)
		(layer "F.Cu")
		(net "SMB_BMC_SWB_BUF_SDA")
	)
	(segment
		(start 161.45256 -425.843192)
		(end 161.45256 -423.51706)
		(width 0.12954)
		(layer "F.Cu")
		(net "SMB_BMC_SWB_BUF_SDA")
	)
	(segment
		(start 165.53815 -417.044886)
		(end 165.53815 -417.422838)
		(width 0.12954)
		(layer "F.Cu")
		(net "SMB_BMC_SWB_BUF_SDA")
	)
	(via
		(at 165.53815 -417.422838)
		(size 0.508)
		(drill 0.254)
		(layers "F.Cu" "B.Cu")
		(net "SMB_BMC_SWB_BUF_SDA")
	)
	(via
		(at 161.722308 -426.11294)
		(size 0.508)
		(drill 0.254)
		(layers "F.Cu" "B.Cu")
		(net "SMB_BMC_SWB_BUF_SDA")
	)
	(segment
		(start 159.1056 -425.90466)
		(end 159.1056 -428.672752)
		(width 0.127)
		(layer "In2.Cu")
		(net "SMB_BMC_SWB_BUF_SDA")
	)
	(segment
		(start 160.3756 -428.672752)
		(end 160.510982 -428.808134)
		(width 0.127)
		(layer "In2.Cu")
		(net "SMB_BMC_SWB_BUF_SDA")
	)
	(segment
		(start 159.1056 -428.672752)
		(end 159.240982 -428.808134)
		(width 0.127)
		(layer "In2.Cu")
		(net "SMB_BMC_SWB_BUF_SDA")
	)
	(segment
		(start 159.621982 -428.808134)
		(end 159.7406 -428.689516)
		(width 0.127)
		(layer "In2.Cu")
		(net "SMB_BMC_SWB_BUF_SDA")
	)
	(segment
		(start 161.0106 -428.689516)
		(end 161.0106 -425.90466)
		(width 0.127)
		(layer "In2.Cu")
		(net "SMB_BMC_SWB_BUF_SDA")
	)
	(segment
		(start 159.7406 -428.689516)
		(end 159.7406 -425.90466)
		(width 0.127)
		(layer "In2.Cu")
		(net "SMB_BMC_SWB_BUF_SDA")
	)
	(segment
		(start 160.891982 -428.808134)
		(end 161.0106 -428.689516)
		(width 0.127)
		(layer "In2.Cu")
		(net "SMB_BMC_SWB_BUF_SDA")
	)
	(segment
		(start 161.0106 -425.90466)
		(end 161.1376 -425.77766)
		(width 0.127)
		(layer "In2.Cu")
		(net "SMB_BMC_SWB_BUF_SDA")
	)
	(segment
		(start 160.2486 -425.77766)
		(end 160.3756 -425.90466)
		(width 0.127)
		(layer "In2.Cu")
		(net "SMB_BMC_SWB_BUF_SDA")
	)
	(segment
		(start 158.140908 -425.404788)
		(end 158.51378 -425.77766)
		(width 0.127)
		(layer "In2.Cu")
		(net "SMB_BMC_SWB_BUF_SDA")
	)
	(segment
		(start 159.7406 -425.90466)
		(end 159.8676 -425.77766)
		(width 0.127)
		(layer "In2.Cu")
		(net "SMB_BMC_SWB_BUF_SDA")
	)
	(segment
		(start 158.51378 -425.77766)
		(end 158.9786 -425.77766)
		(width 0.127)
		(layer "In2.Cu")
		(net "SMB_BMC_SWB_BUF_SDA")
	)
	(segment
		(start 157.941772 -423.510202)
		(end 158.140908 -423.709338)
		(width 0.127)
		(layer "In2.Cu")
		(net "SMB_BMC_SWB_BUF_SDA")
	)
	(segment
		(start 159.8676 -425.77766)
		(end 160.2486 -425.77766)
		(width 0.127)
		(layer "In2.Cu")
		(net "SMB_BMC_SWB_BUF_SDA")
	)
	(segment
		(start 153.964132 -439.703972)
		(end 153.964132 -423.91838)
		(width 0.127)
		(layer "In2.Cu")
		(net "SMB_BMC_SWB_BUF_SDA")
	)
	(segment
		(start 160.3756 -425.90466)
		(end 160.3756 -428.672752)
		(width 0.127)
		(layer "In2.Cu")
		(net "SMB_BMC_SWB_BUF_SDA")
	)
	(segment
		(start 158.140908 -423.709338)
		(end 158.140908 -425.404788)
		(width 0.127)
		(layer "In2.Cu")
		(net "SMB_BMC_SWB_BUF_SDA")
	)
	(segment
		(start 161.387028 -425.77766)
		(end 161.722308 -426.11294)
		(width 0.127)
		(layer "In2.Cu")
		(net "SMB_BMC_SWB_BUF_SDA")
	)
	(segment
		(start 153.964132 -423.91838)
		(end 154.37231 -423.510202)
		(width 0.127)
		(layer "In2.Cu")
		(net "SMB_BMC_SWB_BUF_SDA")
	)
	(segment
		(start 154.37231 -423.510202)
		(end 157.941772 -423.510202)
		(width 0.127)
		(layer "In2.Cu")
		(net "SMB_BMC_SWB_BUF_SDA")
	)
	(segment
		(start 154.750008 -440.489848)
		(end 153.964132 -439.703972)
		(width 0.127)
		(layer "In2.Cu")
		(net "SMB_BMC_SWB_BUF_SDA")
	)
	(segment
		(start 161.1376 -425.77766)
		(end 161.387028 -425.77766)
		(width 0.127)
		(layer "In2.Cu")
		(net "SMB_BMC_SWB_BUF_SDA")
	)
	(segment
		(start 160.510982 -428.808134)
		(end 160.891982 -428.808134)
		(width 0.127)
		(layer "In2.Cu")
		(net "SMB_BMC_SWB_BUF_SDA")
	)
	(segment
		(start 158.9786 -425.77766)
		(end 159.1056 -425.90466)
		(width 0.127)
		(layer "In2.Cu")
		(net "SMB_BMC_SWB_BUF_SDA")
	)
	(segment
		(start 159.240982 -428.808134)
		(end 159.621982 -428.808134)
		(width 0.127)
		(layer "In2.Cu")
		(net "SMB_BMC_SWB_BUF_SDA")
	)
	(segment
		(start 161.58464 -434.508148)
		(end 161.63544 -434.558948)
		(width 0.12954)
		(layer "F.Cu")
		(net "SMB_BMC_SWB_BUF_SCL")
	)
	(segment
		(start 161.63544 -434.558948)
		(end 164.689282 -434.558948)
		(width 0.12954)
		(layer "F.Cu")
		(net "SMB_BMC_SWB_BUF_SCL")
	)
	(segment
		(start 166.860982 -434.558948)
		(end 167.933116 -434.558948)
		(width 0.12954)
		(layer "F.Cu")
		(net "SMB_BMC_SWB_BUF_SCL")
	)
	(segment
		(start 164.948362 -435.276498)
		(end 165.326822 -435.276498)
		(width 0.12954)
		(layer "F.Cu")
		(net "SMB_BMC_SWB_BUF_SCL")
	)
	(segment
		(start 165.964362 -434.558948)
		(end 166.093902 -434.688488)
		(width 0.12954)
		(layer "F.Cu")
		(net "SMB_BMC_SWB_BUF_SCL")
	)
	(segment
		(start 166.223442 -435.276498)
		(end 166.601902 -435.276498)
		(width 0.12954)
		(layer "F.Cu")
		(net "SMB_BMC_SWB_BUF_SCL")
	)
	(segment
		(start 167.794432 -433.265326)
		(end 165.15715 -433.265326)
		(width 0.12954)
		(layer "F.Cu")
		(net "SMB_BMC_SWB_BUF_SCL")
	)
	(segment
		(start 164.818822 -434.688488)
		(end 164.818822 -435.146958)
		(width 0.12954)
		(layer "F.Cu")
		(net "SMB_BMC_SWB_BUF_SCL")
	)
	(segment
		(start 166.731442 -434.688488)
		(end 166.860982 -434.558948)
		(width 0.12954)
		(layer "F.Cu")
		(net "SMB_BMC_SWB_BUF_SCL")
	)
	(segment
		(start 166.601902 -435.276498)
		(end 166.731442 -435.146958)
		(width 0.12954)
		(layer "F.Cu")
		(net "SMB_BMC_SWB_BUF_SCL")
	)
	(segment
		(start 165.585902 -434.558948)
		(end 165.964362 -434.558948)
		(width 0.12954)
		(layer "F.Cu")
		(net "SMB_BMC_SWB_BUF_SCL")
	)
	(segment
		(start 165.456362 -434.688488)
		(end 165.585902 -434.558948)
		(width 0.12954)
		(layer "F.Cu")
		(net "SMB_BMC_SWB_BUF_SCL")
	)
	(segment
		(start 164.818822 -435.146958)
		(end 164.948362 -435.276498)
		(width 0.12954)
		(layer "F.Cu")
		(net "SMB_BMC_SWB_BUF_SCL")
	)
	(segment
		(start 165.326822 -435.276498)
		(end 165.456362 -435.146958)
		(width 0.12954)
		(layer "F.Cu")
		(net "SMB_BMC_SWB_BUF_SCL")
	)
	(segment
		(start 166.093902 -434.688488)
		(end 166.093902 -435.146958)
		(width 0.12954)
		(layer "F.Cu")
		(net "SMB_BMC_SWB_BUF_SCL")
	)
	(segment
		(start 166.093902 -435.146958)
		(end 166.223442 -435.276498)
		(width 0.12954)
		(layer "F.Cu")
		(net "SMB_BMC_SWB_BUF_SCL")
	)
	(segment
		(start 165.456362 -435.146958)
		(end 165.456362 -434.688488)
		(width 0.12954)
		(layer "F.Cu")
		(net "SMB_BMC_SWB_BUF_SCL")
	)
	(segment
		(start 168.0464 -434.445664)
		(end 168.0464 -433.517294)
		(width 0.12954)
		(layer "F.Cu")
		(net "SMB_BMC_SWB_BUF_SCL")
	)
	(segment
		(start 168.0464 -433.517294)
		(end 167.794432 -433.265326)
		(width 0.12954)
		(layer "F.Cu")
		(net "SMB_BMC_SWB_BUF_SCL")
	)
	(segment
		(start 164.689282 -434.558948)
		(end 164.818822 -434.688488)
		(width 0.12954)
		(layer "F.Cu")
		(net "SMB_BMC_SWB_BUF_SCL")
	)
	(segment
		(start 166.731442 -435.146958)
		(end 166.731442 -434.688488)
		(width 0.12954)
		(layer "F.Cu")
		(net "SMB_BMC_SWB_BUF_SCL")
	)
	(segment
		(start 167.933116 -434.558948)
		(end 168.0464 -434.445664)
		(width 0.12954)
		(layer "F.Cu")
		(net "SMB_BMC_SWB_BUF_SCL")
	)
	(via
		(at 161.58464 -434.508148)
		(size 0.508)
		(drill 0.254)
		(layers "F.Cu" "B.Cu")
		(net "SMB_BMC_SWB_BUF_SCL")
	)
	(segment
		(start 158.78556 -423.672508)
		(end 158.78556 -424.84548)
		(width 0.127)
		(layer "In2.Cu")
		(net "SMB_BMC_SWB_BUF_SCL")
	)
	(segment
		(start 161.58464 -427.808136)
		(end 161.58464 -434.508148)
		(width 0.127)
		(layer "In2.Cu")
		(net "SMB_BMC_SWB_BUF_SCL")
	)
	(segment
		(start 150.750016 -440.489848)
		(end 151.89454 -439.345324)
		(width 0.127)
		(layer "In2.Cu")
		(net "SMB_BMC_SWB_BUF_SCL")
	)
	(segment
		(start 158.78556 -424.84548)
		(end 159.094932 -425.154852)
		(width 0.127)
		(layer "In2.Cu")
		(net "SMB_BMC_SWB_BUF_SCL")
	)
	(segment
		(start 158.013146 -422.900094)
		(end 158.78556 -423.672508)
		(width 0.127)
		(layer "In2.Cu")
		(net "SMB_BMC_SWB_BUF_SCL")
	)
	(segment
		(start 151.89454 -439.345324)
		(end 151.89454 -424.101768)
		(width 0.127)
		(layer "In2.Cu")
		(net "SMB_BMC_SWB_BUF_SCL")
	)
	(segment
		(start 151.89454 -424.101768)
		(end 153.096214 -422.900094)
		(width 0.127)
		(layer "In2.Cu")
		(net "SMB_BMC_SWB_BUF_SCL")
	)
	(segment
		(start 162.332924 -425.408852)
		(end 162.332924 -427.059852)
		(width 0.127)
		(layer "In2.Cu")
		(net "SMB_BMC_SWB_BUF_SCL")
	)
	(segment
		(start 162.078924 -425.154852)
		(end 162.332924 -425.408852)
		(width 0.127)
		(layer "In2.Cu")
		(net "SMB_BMC_SWB_BUF_SCL")
	)
	(segment
		(start 153.096214 -422.900094)
		(end 158.013146 -422.900094)
		(width 0.127)
		(layer "In2.Cu")
		(net "SMB_BMC_SWB_BUF_SCL")
	)
	(segment
		(start 159.094932 -425.154852)
		(end 162.078924 -425.154852)
		(width 0.127)
		(layer "In2.Cu")
		(net "SMB_BMC_SWB_BUF_SCL")
	)
	(segment
		(start 162.332924 -427.059852)
		(end 161.58464 -427.808136)
		(width 0.127)
		(layer "In2.Cu")
		(net "SMB_BMC_SWB_BUF_SCL")
	)
	(segment
		(start 175.77943 -422.366948)
		(end 175.77943 -423.382948)
		(width 0.12954)
		(layer "F.Cu")
		(net "RST_SWB_BIC_BUF_R_N")
	)
	(segment
		(start 175.104806 -423.128948)
		(end 174.52848 -423.128948)
		(width 0.12954)
		(layer "F.Cu")
		(net "RST_SWB_BIC_BUF_R_N")
	)
	(segment
		(start 174.52848 -423.128948)
		(end 173.939454 -423.128948)
		(width 0.12954)
		(layer "F.Cu")
		(net "RST_SWB_BIC_BUF_R_N")
	)
	(segment
		(start 173.939454 -423.128948)
		(end 173.31944 -423.748962)
		(width 0.12954)
		(layer "F.Cu")
		(net "RST_SWB_BIC_BUF_R_N")
	)
	(segment
		(start 175.358806 -423.382948)
		(end 175.104806 -423.128948)
		(width 0.12954)
		(layer "F.Cu")
		(net "RST_SWB_BIC_BUF_R_N")
	)
	(segment
		(start 175.77943 -421.350948)
		(end 175.77943 -422.366948)
		(width 0.12954)
		(layer "F.Cu")
		(net "RST_SWB_BIC_BUF_R_N")
	)
	(segment
		(start 175.77943 -423.382948)
		(end 175.358806 -423.382948)
		(width 0.12954)
		(layer "F.Cu")
		(net "RST_SWB_BIC_BUF_R_N")
	)
	(via
		(at 174.52848 -423.128948)
		(size 0.762)
		(drill 0.381)
		(layers "F.Cu" "B.Cu")
		(net "RST_SWB_BIC_BUF_R_N")
	)
	(segment
		(start 176.57953 -423.382948)
		(end 177.18913 -423.382948)
		(width 0.12954)
		(layer "F.Cu")
		(net "RST_SWB_BIC_BUF_N")
	)
	(via
		(at 300.80966 -398.80032)
		(size 0.508)
		(drill 0.254)
		(layers "F.Cu" "B.Cu")
		(net "RST_SWB_BIC_BUF_N")
	)
	(via
		(at 369.2144 -405.298148)
		(size 0.508)
		(drill 0.254)
		(layers "F.Cu" "B.Cu")
		(net "RST_SWB_BIC_BUF_N")
	)
	(via
		(at 282.78455 -413.50565)
		(size 0.508)
		(drill 0.254)
		(layers "F.Cu" "B.Cu")
		(net "RST_SWB_BIC_BUF_N")
	)
	(via
		(at 177.18913 -423.382948)
		(size 0.508)
		(drill 0.254)
		(layers "F.Cu" "B.Cu")
		(net "RST_SWB_BIC_BUF_N")
	)
	(segment
		(start 277.97506 -388.59968)
		(end 269.95628 -388.59968)
		(width 0.12954)
		(layer "B.Cu")
		(net "RST_SWB_BIC_BUF_N")
	)
	(segment
		(start 268.72946 -387.37286)
		(end 268.72946 -384.54584)
		(width 0.12954)
		(layer "B.Cu")
		(net "RST_SWB_BIC_BUF_N")
	)
	(segment
		(start 263.322562 -379.138942)
		(end 189.155578 -379.138942)
		(width 0.12954)
		(layer "B.Cu")
		(net "RST_SWB_BIC_BUF_N")
	)
	(segment
		(start 269.95628 -388.59968)
		(end 268.72946 -387.37286)
		(width 0.12954)
		(layer "B.Cu")
		(net "RST_SWB_BIC_BUF_N")
	)
	(segment
		(start 281.790902 -392.415522)
		(end 277.97506 -388.59968)
		(width 0.12954)
		(layer "B.Cu")
		(net "RST_SWB_BIC_BUF_N")
	)
	(segment
		(start 301.398432 -398.211548)
		(end 300.80966 -398.80032)
		(width 0.12954)
		(layer "B.Cu")
		(net "RST_SWB_BIC_BUF_N")
	)
	(segment
		(start 367.93932 -398.643348)
		(end 367.50752 -398.211548)
		(width 0.12954)
		(layer "B.Cu")
		(net "RST_SWB_BIC_BUF_N")
	)
	(segment
		(start 177.70094 -414.35528)
		(end 177.70094 -419.6842)
		(width 0.12954)
		(layer "B.Cu")
		(net "RST_SWB_BIC_BUF_N")
	)
	(segment
		(start 174.668434 -394.285724)
		(end 174.668434 -401.579334)
		(width 0.12954)
		(layer "B.Cu")
		(net "RST_SWB_BIC_BUF_N")
	)
	(segment
		(start 281.790902 -395.379702)
		(end 281.790902 -392.415522)
		(width 0.12954)
		(layer "B.Cu")
		(net "RST_SWB_BIC_BUF_N")
	)
	(segment
		(start 174.668434 -401.579334)
		(end 176.80432 -403.71522)
		(width 0.12954)
		(layer "B.Cu")
		(net "RST_SWB_BIC_BUF_N")
	)
	(segment
		(start 177.70094 -419.6842)
		(end 176.48174 -420.9034)
		(width 0.12954)
		(layer "B.Cu")
		(net "RST_SWB_BIC_BUF_N")
	)
	(segment
		(start 282.78455 -413.50565)
		(end 282.32989 -413.50565)
		(width 0.12954)
		(layer "B.Cu")
		(net "RST_SWB_BIC_BUF_N")
	)
	(segment
		(start 281.968702 -413.144462)
		(end 281.968702 -408.9654)
		(width 0.12954)
		(layer "B.Cu")
		(net "RST_SWB_BIC_BUF_N")
	)
	(segment
		(start 268.72946 -384.54584)
		(end 263.322562 -379.138942)
		(width 0.12954)
		(layer "B.Cu")
		(net "RST_SWB_BIC_BUF_N")
	)
	(segment
		(start 369.2144 -405.298148)
		(end 368.48796 -405.298148)
		(width 0.12954)
		(layer "B.Cu")
		(net "RST_SWB_BIC_BUF_N")
	)
	(segment
		(start 282.32989 -413.50565)
		(end 281.968702 -413.144462)
		(width 0.12954)
		(layer "B.Cu")
		(net "RST_SWB_BIC_BUF_N")
	)
	(segment
		(start 367.93932 -404.749508)
		(end 367.93932 -398.643348)
		(width 0.12954)
		(layer "B.Cu")
		(net "RST_SWB_BIC_BUF_N")
	)
	(segment
		(start 189.155578 -379.138942)
		(end 175.0314 -393.26312)
		(width 0.12954)
		(layer "B.Cu")
		(net "RST_SWB_BIC_BUF_N")
	)
	(segment
		(start 176.48174 -422.675558)
		(end 177.18913 -423.382948)
		(width 0.12954)
		(layer "B.Cu")
		(net "RST_SWB_BIC_BUF_N")
	)
	(segment
		(start 175.0314 -393.922758)
		(end 174.668434 -394.285724)
		(width 0.12954)
		(layer "B.Cu")
		(net "RST_SWB_BIC_BUF_N")
	)
	(segment
		(start 176.48174 -420.9034)
		(end 176.48174 -422.675558)
		(width 0.12954)
		(layer "B.Cu")
		(net "RST_SWB_BIC_BUF_N")
	)
	(segment
		(start 281.968702 -408.9654)
		(end 282.956 -407.978102)
		(width 0.12954)
		(layer "B.Cu")
		(net "RST_SWB_BIC_BUF_N")
	)
	(segment
		(start 176.80432 -403.71522)
		(end 176.80432 -413.45866)
		(width 0.12954)
		(layer "B.Cu")
		(net "RST_SWB_BIC_BUF_N")
	)
	(segment
		(start 175.0314 -393.26312)
		(end 175.0314 -393.922758)
		(width 0.12954)
		(layer "B.Cu")
		(net "RST_SWB_BIC_BUF_N")
	)
	(segment
		(start 367.50752 -398.211548)
		(end 301.398432 -398.211548)
		(width 0.12954)
		(layer "B.Cu")
		(net "RST_SWB_BIC_BUF_N")
	)
	(segment
		(start 368.48796 -405.298148)
		(end 367.93932 -404.749508)
		(width 0.12954)
		(layer "B.Cu")
		(net "RST_SWB_BIC_BUF_N")
	)
	(segment
		(start 176.80432 -413.45866)
		(end 177.70094 -414.35528)
		(width 0.12954)
		(layer "B.Cu")
		(net "RST_SWB_BIC_BUF_N")
	)
	(segment
		(start 282.956 -407.978102)
		(end 282.956 -396.5448)
		(width 0.12954)
		(layer "B.Cu")
		(net "RST_SWB_BIC_BUF_N")
	)
	(segment
		(start 282.956 -396.5448)
		(end 281.790902 -395.379702)
		(width 0.12954)
		(layer "B.Cu")
		(net "RST_SWB_BIC_BUF_N")
	)
	(segment
		(start 371.977158 -411.579314)
		(end 369.2144 -408.816556)
		(width 0.127)
		(layer "In2.Cu")
		(net "RST_SWB_BIC_BUF_N")
	)
	(segment
		(start 408.750008 -423.746676)
		(end 401.14728 -416.143948)
		(width 0.127)
		(layer "In2.Cu")
		(net "RST_SWB_BIC_BUF_N")
	)
	(segment
		(start 376.858022 -411.579314)
		(end 371.977158 -411.579314)
		(width 0.127)
		(layer "In2.Cu")
		(net "RST_SWB_BIC_BUF_N")
	)
	(segment
		(start 408.750008 -424.689778)
		(end 408.750008 -423.746676)
		(width 0.127)
		(layer "In2.Cu")
		(net "RST_SWB_BIC_BUF_N")
	)
	(segment
		(start 369.2144 -408.816556)
		(end 369.2144 -405.298148)
		(width 0.127)
		(layer "In2.Cu")
		(net "RST_SWB_BIC_BUF_N")
	)
	(segment
		(start 381.422656 -416.143948)
		(end 376.858022 -411.579314)
		(width 0.127)
		(layer "In2.Cu")
		(net "RST_SWB_BIC_BUF_N")
	)
	(segment
		(start 401.14728 -416.143948)
		(end 381.422656 -416.143948)
		(width 0.127)
		(layer "In2.Cu")
		(net "RST_SWB_BIC_BUF_N")
	)
	(segment
		(start 300.16196 -399.39722)
		(end 300.16196 -400.23288)
		(width 0.127)
		(layer "In4.Cu")
		(net "RST_SWB_BIC_BUF_N")
	)
	(segment
		(start 295.76776 -412.3944)
		(end 288.8869 -412.3944)
		(width 0.127)
		(layer "In4.Cu")
		(net "RST_SWB_BIC_BUF_N")
	)
	(segment
		(start 301.92472 -407.93416)
		(end 298.38269 -411.47619)
		(width 0.127)
		(layer "In4.Cu")
		(net "RST_SWB_BIC_BUF_N")
	)
	(segment
		(start 300.75886 -398.80032)
		(end 300.16196 -399.39722)
		(width 0.127)
		(layer "In4.Cu")
		(net "RST_SWB_BIC_BUF_N")
	)
	(segment
		(start 296.68597 -411.47619)
		(end 295.76776 -412.3944)
		(width 0.127)
		(layer "In4.Cu")
		(net "RST_SWB_BIC_BUF_N")
	)
	(segment
		(start 300.16196 -400.23288)
		(end 301.92472 -401.99564)
		(width 0.127)
		(layer "In4.Cu")
		(net "RST_SWB_BIC_BUF_N")
	)
	(segment
		(start 288.8869 -412.3944)
		(end 287.99536 -411.50286)
		(width 0.127)
		(layer "In4.Cu")
		(net "RST_SWB_BIC_BUF_N")
	)
	(segment
		(start 300.80966 -398.80032)
		(end 300.75886 -398.80032)
		(width 0.127)
		(layer "In4.Cu")
		(net "RST_SWB_BIC_BUF_N")
	)
	(segment
		(start 283.32684 -411.50286)
		(end 282.78455 -412.04515)
		(width 0.127)
		(layer "In4.Cu")
		(net "RST_SWB_BIC_BUF_N")
	)
	(segment
		(start 282.78455 -412.04515)
		(end 282.78455 -413.50565)
		(width 0.127)
		(layer "In4.Cu")
		(net "RST_SWB_BIC_BUF_N")
	)
	(segment
		(start 287.99536 -411.50286)
		(end 283.32684 -411.50286)
		(width 0.127)
		(layer "In4.Cu")
		(net "RST_SWB_BIC_BUF_N")
	)
	(segment
		(start 301.92472 -401.99564)
		(end 301.92472 -407.93416)
		(width 0.127)
		(layer "In4.Cu")
		(net "RST_SWB_BIC_BUF_N")
	)
	(segment
		(start 298.38269 -411.47619)
		(end 296.68597 -411.47619)
		(width 0.127)
		(layer "In4.Cu")
		(net "RST_SWB_BIC_BUF_N")
	)
	(segment
		(start 26.72588 -427.573948)
		(end 26.583894 -427.431962)
		(width 0.12954)
		(layer "F.Cu")
		(net "RST_PERST_SWB_R_N")
	)
	(segment
		(start 26.02992 -428.731934)
		(end 25.39492 -428.731934)
		(width 0.12954)
		(layer "F.Cu")
		(net "RST_PERST_SWB_R_N")
	)
	(segment
		(start 25.39492 -428.731934)
		(end 25.092406 -428.731934)
		(width 0.12954)
		(layer "F.Cu")
		(net "RST_PERST_SWB_R_N")
	)
	(segment
		(start 23.860506 -427.500034)
		(end 23.32228 -427.500034)
		(width 0.12954)
		(layer "F.Cu")
		(net "RST_PERST_SWB_R_N")
	)
	(segment
		(start 26.72588 -428.589948)
		(end 26.72588 -427.573948)
		(width 0.12954)
		(layer "F.Cu")
		(net "RST_PERST_SWB_R_N")
	)
	(segment
		(start 26.02992 -431.525934)
		(end 25.39492 -431.525934)
		(width 0.12954)
		(layer "F.Cu")
		(net "RST_PERST_SWB_R_N")
	)
	(segment
		(start 26.583894 -427.431962)
		(end 26.02992 -427.431962)
		(width 0.12954)
		(layer "F.Cu")
		(net "RST_PERST_SWB_R_N")
	)
	(segment
		(start 25.092406 -428.731934)
		(end 23.860506 -427.500034)
		(width 0.12954)
		(layer "F.Cu")
		(net "RST_PERST_SWB_R_N")
	)
	(segment
		(start 26.02992 -428.731934)
		(end 26.583894 -428.731934)
		(width 0.12954)
		(layer "F.Cu")
		(net "RST_PERST_SWB_R_N")
	)
	(segment
		(start 26.583894 -428.731934)
		(end 26.72588 -428.589948)
		(width 0.12954)
		(layer "F.Cu")
		(net "RST_PERST_SWB_R_N")
	)
	(via
		(at 25.39492 -431.525934)
		(size 0.508)
		(drill 0.254)
		(layers "F.Cu" "B.Cu")
		(net "RST_PERST_SWB_R_N")
	)
	(via
		(at 25.39492 -428.731934)
		(size 0.508)
		(drill 0.254)
		(layers "F.Cu" "B.Cu")
		(net "RST_PERST_SWB_R_N")
	)
	(segment
		(start 25.631394 -431.525934)
		(end 25.39492 -431.525934)
		(width 0.127)
		(layer "In2.Cu")
		(net "RST_PERST_SWB_R_N")
	)
	(segment
		(start 25.39492 -428.731934)
		(end 26.0096 -429.346614)
		(width 0.127)
		(layer "In2.Cu")
		(net "RST_PERST_SWB_R_N")
	)
	(segment
		(start 26.0096 -429.346614)
		(end 26.0096 -431.147728)
		(width 0.127)
		(layer "In2.Cu")
		(net "RST_PERST_SWB_R_N")
	)
	(segment
		(start 26.0096 -431.147728)
		(end 25.631394 -431.525934)
		(width 0.127)
		(layer "In2.Cu")
		(net "RST_PERST_SWB_R_N")
	)
	(segment
		(start 28.264866 -431.525934)
		(end 27.92984 -431.525934)
		(width 0.12954)
		(layer "F.Cu")
		(net "RST_PERST_2_SWB_BUF_R_N")
	)
	(segment
		(start 30.89783 -432.907948)
		(end 30.89783 -433.923948)
		(width 0.12954)
		(layer "F.Cu")
		(net "RST_PERST_2_SWB_BUF_R_N")
	)
	(segment
		(start 29.64688 -432.907948)
		(end 29.207714 -432.468782)
		(width 0.12954)
		(layer "F.Cu")
		(net "RST_PERST_2_SWB_BUF_R_N")
	)
	(segment
		(start 30.89783 -432.907948)
		(end 29.64688 -432.907948)
		(width 0.12954)
		(layer "F.Cu")
		(net "RST_PERST_2_SWB_BUF_R_N")
	)
	(segment
		(start 29.207714 -432.468782)
		(end 28.264866 -431.525934)
		(width 0.12954)
		(layer "F.Cu")
		(net "RST_PERST_2_SWB_BUF_R_N")
	)
	(via
		(at 29.207714 -432.468782)
		(size 0.762)
		(drill 0.381)
		(layers "F.Cu" "B.Cu")
		(net "RST_PERST_2_SWB_BUF_R_N")
	)
	(segment
		(start 31.69793 -432.907948)
		(end 32.30753 -432.907948)
		(width 0.12954)
		(layer "F.Cu")
		(net "RST_PERST_2_SWB_BUF_N")
	)
	(via
		(at 32.30753 -432.907948)
		(size 0.508)
		(drill 0.254)
		(layers "F.Cu" "B.Cu")
		(net "RST_PERST_2_SWB_BUF_N")
	)
	(segment
		(start 58.650124 -440.489848)
		(end 56.26608 -438.105804)
		(width 0.12954)
		(layer "B.Cu")
		(net "RST_PERST_2_SWB_BUF_N")
	)
	(segment
		(start 56.26608 -435.574948)
		(end 53.970174 -433.279042)
		(width 0.12954)
		(layer "B.Cu")
		(net "RST_PERST_2_SWB_BUF_N")
	)
	(segment
		(start 56.26608 -438.105804)
		(end 56.26608 -435.574948)
		(width 0.12954)
		(layer "B.Cu")
		(net "RST_PERST_2_SWB_BUF_N")
	)
	(segment
		(start 32.678624 -433.279042)
		(end 32.30753 -432.907948)
		(width 0.12954)
		(layer "B.Cu")
		(net "RST_PERST_2_SWB_BUF_N")
	)
	(segment
		(start 53.970174 -433.279042)
		(end 32.678624 -433.279042)
		(width 0.12954)
		(layer "B.Cu")
		(net "RST_PERST_2_SWB_BUF_N")
	)
	(segment
		(start 27.92984 -426.049948)
		(end 30.13583 -426.049948)
		(width 0.12954)
		(layer "F.Cu")
		(net "RST_PERST_1_SWB_BUF_R_N")
	)
	(segment
		(start 30.89783 -424.271948)
		(end 30.89783 -425.287948)
		(width 0.12954)
		(layer "F.Cu")
		(net "RST_PERST_1_SWB_BUF_R_N")
	)
	(segment
		(start 27.92984 -427.431962)
		(end 27.92984 -426.049948)
		(width 0.12954)
		(layer "F.Cu")
		(net "RST_PERST_1_SWB_BUF_R_N")
	)
	(segment
		(start 30.13583 -426.049948)
		(end 30.89783 -425.287948)
		(width 0.12954)
		(layer "F.Cu")
		(net "RST_PERST_1_SWB_BUF_R_N")
	)
	(via
		(at 27.92984 -426.049948)
		(size 0.762)
		(drill 0.381)
		(layers "F.Cu" "B.Cu")
		(net "RST_PERST_1_SWB_BUF_R_N")
	)
	(segment
		(start 31.69793 -425.287948)
		(end 32.56153 -425.287948)
		(width 0.12954)
		(layer "F.Cu")
		(net "RST_PERST_1_SWB_BUF_N")
	)
	(via
		(at 32.56153 -425.287948)
		(size 0.508)
		(drill 0.254)
		(layers "F.Cu" "B.Cu")
		(net "RST_PERST_1_SWB_BUF_N")
	)
	(segment
		(start 34.19348 -415.412428)
		(end 38.68674 -410.919168)
		(width 0.127)
		(layer "In15.Cu")
		(net "RST_PERST_1_SWB_BUF_N")
	)
	(segment
		(start 47.564548 -410.919168)
		(end 49.941988 -413.296608)
		(width 0.127)
		(layer "In15.Cu")
		(net "RST_PERST_1_SWB_BUF_N")
	)
	(segment
		(start 32.56153 -425.287948)
		(end 34.19348 -423.655998)
		(width 0.127)
		(layer "In15.Cu")
		(net "RST_PERST_1_SWB_BUF_N")
	)
	(segment
		(start 49.941988 -413.296608)
		(end 64.13754 -413.296608)
		(width 0.127)
		(layer "In15.Cu")
		(net "RST_PERST_1_SWB_BUF_N")
	)
	(segment
		(start 65.86728 -439.70702)
		(end 66.650108 -440.489848)
		(width 0.127)
		(layer "In15.Cu")
		(net "RST_PERST_1_SWB_BUF_N")
	)
	(segment
		(start 34.19348 -423.655998)
		(end 34.19348 -415.412428)
		(width 0.127)
		(layer "In15.Cu")
		(net "RST_PERST_1_SWB_BUF_N")
	)
	(segment
		(start 65.86728 -415.026348)
		(end 65.86728 -439.70702)
		(width 0.127)
		(layer "In15.Cu")
		(net "RST_PERST_1_SWB_BUF_N")
	)
	(segment
		(start 64.13754 -413.296608)
		(end 65.86728 -415.026348)
		(width 0.127)
		(layer "In15.Cu")
		(net "RST_PERST_1_SWB_BUF_N")
	)
	(segment
		(start 38.68674 -410.919168)
		(end 47.564548 -410.919168)
		(width 0.127)
		(layer "In15.Cu")
		(net "RST_PERST_1_SWB_BUF_N")
	)
	(segment
		(start 30.785816 -428.731934)
		(end 27.92984 -428.731934)
		(width 0.12954)
		(layer "F.Cu")
		(net "RST_PERST_0_SWB_BUF_R_N")
	)
	(segment
		(start 30.89783 -428.843948)
		(end 30.785816 -428.731934)
		(width 0.12954)
		(layer "F.Cu")
		(net "RST_PERST_0_SWB_BUF_R_N")
	)
	(segment
		(start 30.89783 -427.573948)
		(end 30.89783 -428.843948)
		(width 0.12954)
		(layer "F.Cu")
		(net "RST_PERST_0_SWB_BUF_R_N")
	)
	(segment
		(start 30.89783 -426.303948)
		(end 30.89783 -427.573948)
		(width 0.12954)
		(layer "F.Cu")
		(net "RST_PERST_0_SWB_BUF_R_N")
	)
	(via
		(at 30.89783 -427.573948)
		(size 0.762)
		(drill 0.381)
		(layers "F.Cu" "B.Cu")
		(net "RST_PERST_0_SWB_BUF_R_N")
	)
	(segment
		(start 43.713146 -403.387814)
		(end 33.639506 -403.387814)
		(width 0.12954)
		(layer "F.Cu")
		(net "RST_PERST_0_SWB_BUF_N")
	)
	(segment
		(start 33.639506 -403.387814)
		(end 31.30042 -405.7269)
		(width 0.12954)
		(layer "F.Cu")
		(net "RST_PERST_0_SWB_BUF_N")
	)
	(segment
		(start 31.69793 -426.303948)
		(end 31.69793 -427.188884)
		(width 0.12954)
		(layer "F.Cu")
		(net "RST_PERST_0_SWB_BUF_N")
	)
	(via
		(at 31.30042 -405.7269)
		(size 0.508)
		(drill 0.254)
		(layers "F.Cu" "B.Cu")
		(net "RST_PERST_0_SWB_BUF_N")
	)
	(via
		(at 31.69793 -427.188884)
		(size 0.508)
		(drill 0.254)
		(layers "F.Cu" "B.Cu")
		(net "RST_PERST_0_SWB_BUF_N")
	)
	(via
		(at 43.713146 -403.387814)
		(size 0.508)
		(drill 0.254)
		(layers "F.Cu" "B.Cu")
		(net "RST_PERST_0_SWB_BUF_N")
	)
	(segment
		(start 72.1741 -405.689308)
		(end 46.01464 -405.689308)
		(width 0.127)
		(layer "In15.Cu")
		(net "RST_PERST_0_SWB_BUF_N")
	)
	(segment
		(start 72.81164 -417.32835)
		(end 72.81164 -406.326848)
		(width 0.127)
		(layer "In15.Cu")
		(net "RST_PERST_0_SWB_BUF_N")
	)
	(segment
		(start 72.650096 -417.489894)
		(end 72.81164 -417.32835)
		(width 0.127)
		(layer "In15.Cu")
		(net "RST_PERST_0_SWB_BUF_N")
	)
	(segment
		(start 31.30042 -408.755088)
		(end 31.69793 -409.152598)
		(width 0.127)
		(layer "In15.Cu")
		(net "RST_PERST_0_SWB_BUF_N")
	)
	(segment
		(start 72.81164 -406.326848)
		(end 72.1741 -405.689308)
		(width 0.127)
		(layer "In15.Cu")
		(net "RST_PERST_0_SWB_BUF_N")
	)
	(segment
		(start 31.69793 -409.152598)
		(end 31.69793 -427.188884)
		(width 0.127)
		(layer "In15.Cu")
		(net "RST_PERST_0_SWB_BUF_N")
	)
	(segment
		(start 31.30042 -405.7269)
		(end 31.30042 -408.755088)
		(width 0.127)
		(layer "In15.Cu")
		(net "RST_PERST_0_SWB_BUF_N")
	)
	(segment
		(start 46.01464 -405.689308)
		(end 43.713146 -403.387814)
		(width 0.127)
		(layer "In15.Cu")
		(net "RST_PERST_0_SWB_BUF_N")
	)
	(segment
		(start 426.29836 -381.218948)
		(end 424.731942 -381.218948)
		(width 0.12954)
		(layer "F.Cu")
		(net "RST_BMC_FROM_SWB_N")
	)
	(segment
		(start 424.731942 -381.218948)
		(end 424.604942 -381.345948)
		(width 0.12954)
		(layer "F.Cu")
		(net "RST_BMC_FROM_SWB_N")
	)
	(segment
		(start 424.604942 -382.361948)
		(end 424.604942 -381.345948)
		(width 0.12954)
		(layer "F.Cu")
		(net "RST_BMC_FROM_SWB_N")
	)
	(segment
		(start 427.230032 -381.218948)
		(end 426.29836 -381.218948)
		(width 0.12954)
		(layer "F.Cu")
		(net "RST_BMC_FROM_SWB_N")
	)
	(via
		(at 426.29836 -381.218948)
		(size 0.508)
		(drill 0.254)
		(layers "F.Cu" "B.Cu")
		(net "RST_BMC_FROM_SWB_N")
	)
	(segment
		(start 412.75 -424.689778)
		(end 412.75 -422.346628)
		(width 0.12954)
		(layer "B.Cu")
		(net "RST_BMC_FROM_SWB_N")
	)
	(segment
		(start 412.75 -422.346628)
		(end 427.863 -407.233628)
		(width 0.12954)
		(layer "B.Cu")
		(net "RST_BMC_FROM_SWB_N")
	)
	(segment
		(start 427.863 -382.072388)
		(end 427.00956 -381.218948)
		(width 0.12954)
		(layer "B.Cu")
		(net "RST_BMC_FROM_SWB_N")
	)
	(segment
		(start 427.00956 -381.218948)
		(end 426.29836 -381.218948)
		(width 0.12954)
		(layer "B.Cu")
		(net "RST_BMC_FROM_SWB_N")
	)
	(segment
		(start 427.863 -407.233628)
		(end 427.863 -382.072388)
		(width 0.12954)
		(layer "B.Cu")
		(net "RST_BMC_FROM_SWB_N")
	)
	(segment
		(start 174.155608 -110.575344)
		(end 173.755558 -110.175294)
		(width 0.12954)
		(layer "F.Cu")
		(net "RST_BMC_FROM_SWB_ISO_R_N")
	)
	(segment
		(start 161.23793 -109.565948)
		(end 161.85388 -109.565948)
		(width 0.12954)
		(layer "F.Cu")
		(net "RST_BMC_FROM_SWB_ISO_R_N")
	)
	(via
		(at 173.755558 -110.175294)
		(size 0.4572)
		(drill 0.254)
		(layers "F.Cu" "B.Cu")
		(net "RST_BMC_FROM_SWB_ISO_R_N")
	)
	(via
		(at 161.85388 -109.565948)
		(size 0.508)
		(drill 0.254)
		(layers "F.Cu" "B.Cu")
		(net "RST_BMC_FROM_SWB_ISO_R_N")
	)
	(segment
		(start 173.35754 -109.093)
		(end 173.23054 -108.966)
		(width 0.127)
		(layer "In6.Cu")
		(net "RST_BMC_FROM_SWB_ISO_R_N")
	)
	(segment
		(start 162.352228 -109.0676)
		(end 161.85388 -109.565948)
		(width 0.127)
		(layer "In6.Cu")
		(net "RST_BMC_FROM_SWB_ISO_R_N")
	)
	(segment
		(start 173.755558 -110.175294)
		(end 173.35754 -109.777276)
		(width 0.127)
		(layer "In6.Cu")
		(net "RST_BMC_FROM_SWB_ISO_R_N")
	)
	(segment
		(start 167.4368 -109.0676)
		(end 162.352228 -109.0676)
		(width 0.127)
		(layer "In6.Cu")
		(net "RST_BMC_FROM_SWB_ISO_R_N")
	)
	(segment
		(start 170.736514 -108.968286)
		(end 170.327828 -108.5596)
		(width 0.127)
		(layer "In6.Cu")
		(net "RST_BMC_FROM_SWB_ISO_R_N")
	)
	(segment
		(start 170.327828 -108.5596)
		(end 167.9448 -108.5596)
		(width 0.127)
		(layer "In6.Cu")
		(net "RST_BMC_FROM_SWB_ISO_R_N")
	)
	(segment
		(start 173.35754 -109.777276)
		(end 173.35754 -109.093)
		(width 0.127)
		(layer "In6.Cu")
		(net "RST_BMC_FROM_SWB_ISO_R_N")
	)
	(segment
		(start 173.23054 -108.966)
		(end 173.228254 -108.968286)
		(width 0.127)
		(layer "In6.Cu")
		(net "RST_BMC_FROM_SWB_ISO_R_N")
	)
	(segment
		(start 173.228254 -108.968286)
		(end 170.736514 -108.968286)
		(width 0.127)
		(layer "In6.Cu")
		(net "RST_BMC_FROM_SWB_ISO_R_N")
	)
	(segment
		(start 167.9448 -108.5596)
		(end 167.4368 -109.0676)
		(width 0.127)
		(layer "In6.Cu")
		(net "RST_BMC_FROM_SWB_ISO_R_N")
	)
	(segment
		(start 177.355754 -110.575344)
		(end 176.955704 -110.175294)
		(width 0.381)
		(layer "F.Cu")
		(net "P3V3_AUX_FPGA_VCCIO5")
	)
	(segment
		(start 176.555654 -110.575344)
		(end 176.155604 -110.175294)
		(width 0.381)
		(layer "F.Cu")
		(net "P3V3_AUX_FPGA_VCCIO5")
	)
	(segment
		(start 174.155608 -106.575352)
		(end 173.755558 -106.175302)
		(width 0.381)
		(layer "F.Cu")
		(net "P3V3_AUX_FPGA_VCCIO5")
	)
	(via
		(at 176.155604 -110.175294)
		(size 0.4572)
		(drill 0.254)
		(layers "F.Cu" "B.Cu")
		(net "P3V3_AUX_FPGA_VCCIO5")
	)
	(via
		(at 173.755558 -106.175302)
		(size 0.4572)
		(drill 0.254)
		(layers "F.Cu" "B.Cu")
		(net "P3V3_AUX_FPGA_VCCIO5")
	)
	(via
		(at 174.625 -101.448108)
		(size 0.762)
		(drill 0.254)
		(layers "F.Cu" "B.Cu")
		(net "P3V3_AUX_FPGA_VCCIO5")
	)
	(via
		(at 174.05858 -102.682548)
		(size 0.508)
		(drill 0.254)
		(layers "F.Cu" "B.Cu")
		(net "P3V3_AUX_FPGA_VCCIO5")
	)
	(via
		(at 175.39208 -101.503988)
		(size 0.6604)
		(drill 0.3302)
		(layers "F.Cu" "B.Cu")
		(net "P3V3_AUX_FPGA_VCCIO5")
	)
	(via
		(at 174.05858 -103.723948)
		(size 0.508)
		(drill 0.254)
		(layers "F.Cu" "B.Cu")
		(net "P3V3_AUX_FPGA_VCCIO5")
	)
	(via
		(at 176.955704 -110.175294)
		(size 0.4572)
		(drill 0.254)
		(layers "F.Cu" "B.Cu")
		(net "P3V3_AUX_FPGA_VCCIO5")
	)
	(segment
		(start 174.155354 -105.775506)
		(end 174.155608 -105.775506)
		(width 0.381)
		(layer "B.Cu")
		(net "P3V3_AUX_FPGA_VCCIO5")
	)
	(segment
		(start 173.755558 -106.175302)
		(end 174.155354 -105.775506)
		(width 0.381)
		(layer "B.Cu")
		(net "P3V3_AUX_FPGA_VCCIO5")
	)
	(segment
		(start 178.9557 -106.575352)
		(end 179.35575 -106.175302)
		(width 0.381)
		(layer "F.Cu")
		(net "P3V3_AUX_FPGA_VCCIO4")
	)
	(segment
		(start 178.9557 -110.575344)
		(end 179.35575 -110.175294)
		(width 0.381)
		(layer "F.Cu")
		(net "P3V3_AUX_FPGA_VCCIO4")
	)
	(segment
		(start 178.1556 -110.575344)
		(end 177.75555 -110.175294)
		(width 0.381)
		(layer "F.Cu")
		(net "P3V3_AUX_FPGA_VCCIO4")
	)
	(via
		(at 179.66182 -103.182928)
		(size 0.6604)
		(drill 0.3302)
		(layers "F.Cu" "B.Cu")
		(net "P3V3_AUX_FPGA_VCCIO4")
	)
	(via
		(at 177.75555 -110.175294)
		(size 0.4572)
		(drill 0.254)
		(layers "F.Cu" "B.Cu")
		(net "P3V3_AUX_FPGA_VCCIO4")
	)
	(via
		(at 179.35575 -106.175302)
		(size 0.4572)
		(drill 0.254)
		(layers "F.Cu" "B.Cu")
		(net "P3V3_AUX_FPGA_VCCIO4")
	)
	(via
		(at 179.63388 -101.437948)
		(size 0.762)
		(drill 0.254)
		(layers "F.Cu" "B.Cu")
		(net "P3V3_AUX_FPGA_VCCIO4")
	)
	(via
		(at 179.11953 -102.682548)
		(size 0.508)
		(drill 0.254)
		(layers "F.Cu" "B.Cu")
		(net "P3V3_AUX_FPGA_VCCIO4")
	)
	(via
		(at 179.11953 -103.723948)
		(size 0.508)
		(drill 0.254)
		(layers "F.Cu" "B.Cu")
		(net "P3V3_AUX_FPGA_VCCIO4")
	)
	(via
		(at 179.35575 -110.175294)
		(size 0.4572)
		(drill 0.254)
		(layers "F.Cu" "B.Cu")
		(net "P3V3_AUX_FPGA_VCCIO4")
	)
	(segment
		(start 179.542948 -106.3625)
		(end 179.35575 -106.175302)
		(width 0.381)
		(layer "B.Cu")
		(net "P3V3_AUX_FPGA_VCCIO4")
	)
	(segment
		(start 179.9082 -106.3625)
		(end 179.542948 -106.3625)
		(width 0.381)
		(layer "B.Cu")
		(net "P3V3_AUX_FPGA_VCCIO4")
	)
	(segment
		(start 179.755546 -110.575344)
		(end 180.155596 -110.175294)
		(width 0.381)
		(layer "F.Cu")
		(net "P3V3_AUX_FPGA_VCCIO3")
	)
	(segment
		(start 180.555646 -110.575344)
		(end 180.955696 -110.175294)
		(width 0.381)
		(layer "F.Cu")
		(net "P3V3_AUX_FPGA_VCCIO3")
	)
	(segment
		(start 183.755538 -106.575352)
		(end 184.155588 -106.175302)
		(width 0.381)
		(layer "F.Cu")
		(net "P3V3_AUX_FPGA_VCCIO3")
	)
	(via
		(at 180.955696 -110.175294)
		(size 0.4572)
		(drill 0.254)
		(layers "F.Cu" "B.Cu")
		(net "P3V3_AUX_FPGA_VCCIO3")
	)
	(via
		(at 183.69153 -102.682548)
		(size 0.508)
		(drill 0.254)
		(layers "F.Cu" "B.Cu")
		(net "P3V3_AUX_FPGA_VCCIO3")
	)
	(via
		(at 184.20588 -101.564948)
		(size 0.508)
		(drill 0.254)
		(layers "F.Cu" "B.Cu")
		(net "P3V3_AUX_FPGA_VCCIO3")
	)
	(via
		(at 180.155596 -110.175294)
		(size 0.4572)
		(drill 0.254)
		(layers "F.Cu" "B.Cu")
		(net "P3V3_AUX_FPGA_VCCIO3")
	)
	(via
		(at 183.69153 -103.723948)
		(size 0.508)
		(drill 0.254)
		(layers "F.Cu" "B.Cu")
		(net "P3V3_AUX_FPGA_VCCIO3")
	)
	(via
		(at 184.22112 -103.185468)
		(size 0.6604)
		(drill 0.3302)
		(layers "F.Cu" "B.Cu")
		(net "P3V3_AUX_FPGA_VCCIO3")
	)
	(via
		(at 184.155588 -106.175302)
		(size 0.4572)
		(drill 0.254)
		(layers "F.Cu" "B.Cu")
		(net "P3V3_AUX_FPGA_VCCIO3")
	)
	(segment
		(start 183.755792 -105.775506)
		(end 183.755538 -105.775506)
		(width 0.381)
		(layer "B.Cu")
		(net "P3V3_AUX_FPGA_VCCIO3")
	)
	(segment
		(start 184.155588 -106.175302)
		(end 183.755792 -105.775506)
		(width 0.381)
		(layer "B.Cu")
		(net "P3V3_AUX_FPGA_VCCIO3")
	)
	(segment
		(start 181.355746 -114.575336)
		(end 181.755796 -114.975386)
		(width 0.381)
		(layer "F.Cu")
		(net "P3V3_AUX_FPGA_VCCIO2")
	)
	(segment
		(start 184.555638 -116.975382)
		(end 184.955688 -117.375432)
		(width 0.381)
		(layer "F.Cu")
		(net "P3V3_AUX_FPGA_VCCIO2")
	)
	(segment
		(start 181.355746 -112.175544)
		(end 181.755796 -111.775494)
		(width 0.381)
		(layer "F.Cu")
		(net "P3V3_AUX_FPGA_VCCIO2")
	)
	(segment
		(start 184.555638 -109.775498)
		(end 184.955688 -109.375448)
		(width 0.381)
		(layer "F.Cu")
		(net "P3V3_AUX_FPGA_VCCIO2")
	)
	(segment
		(start 181.355746 -115.375436)
		(end 181.755796 -115.775486)
		(width 0.381)
		(layer "F.Cu")
		(net "P3V3_AUX_FPGA_VCCIO2")
	)
	(segment
		(start 181.355746 -111.375444)
		(end 181.755796 -110.975394)
		(width 0.381)
		(layer "F.Cu")
		(net "P3V3_AUX_FPGA_VCCIO2")
	)
	(segment
		(start 193.79565 -125.336808)
		(end 194.69354 -125.336808)
		(width 0.381)
		(layer "F.Cu")
		(net "P3V3_AUX_FPGA_VCCIO2")
	)
	(segment
		(start 181.355746 -112.97539)
		(end 181.755796 -112.57534)
		(width 0.381)
		(layer "F.Cu")
		(net "P3V3_AUX_FPGA_VCCIO2")
	)
	(segment
		(start 184.555638 -112.97539)
		(end 184.955688 -112.57534)
		(width 0.381)
		(layer "F.Cu")
		(net "P3V3_AUX_FPGA_VCCIO2")
	)
	(segment
		(start 181.355746 -113.77549)
		(end 181.755796 -114.17554)
		(width 0.381)
		(layer "F.Cu")
		(net "P3V3_AUX_FPGA_VCCIO2")
	)
	(via
		(at 184.955688 -109.375448)
		(size 0.4572)
		(drill 0.254)
		(layers "F.Cu" "B.Cu")
		(net "P3V3_AUX_FPGA_VCCIO2")
	)
	(via
		(at 186.87923 -103.723948)
		(size 0.508)
		(drill 0.254)
		(layers "F.Cu" "B.Cu")
		(net "P3V3_AUX_FPGA_VCCIO2")
	)
	(via
		(at 194.69354 -125.336808)
		(size 0.508)
		(drill 0.254)
		(layers "F.Cu" "B.Cu")
		(net "P3V3_AUX_FPGA_VCCIO2")
	)
	(via
		(at 181.755796 -115.775486)
		(size 0.4572)
		(drill 0.254)
		(layers "F.Cu" "B.Cu")
		(net "P3V3_AUX_FPGA_VCCIO2")
	)
	(via
		(at 184.955688 -112.57534)
		(size 0.4572)
		(drill 0.254)
		(layers "F.Cu" "B.Cu")
		(net "P3V3_AUX_FPGA_VCCIO2")
	)
	(via
		(at 181.755796 -111.775494)
		(size 0.4572)
		(drill 0.254)
		(layers "F.Cu" "B.Cu")
		(net "P3V3_AUX_FPGA_VCCIO2")
	)
	(via
		(at 186.36488 -101.564948)
		(size 0.508)
		(drill 0.254)
		(layers "F.Cu" "B.Cu")
		(net "P3V3_AUX_FPGA_VCCIO2")
	)
	(via
		(at 186.33186 -103.185468)
		(size 0.6604)
		(drill 0.3302)
		(layers "F.Cu" "B.Cu")
		(net "P3V3_AUX_FPGA_VCCIO2")
	)
	(via
		(at 181.755796 -114.975386)
		(size 0.4572)
		(drill 0.254)
		(layers "F.Cu" "B.Cu")
		(net "P3V3_AUX_FPGA_VCCIO2")
	)
	(via
		(at 181.755796 -110.975394)
		(size 0.4572)
		(drill 0.254)
		(layers "F.Cu" "B.Cu")
		(net "P3V3_AUX_FPGA_VCCIO2")
	)
	(via
		(at 181.755796 -114.17554)
		(size 0.4572)
		(drill 0.254)
		(layers "F.Cu" "B.Cu")
		(net "P3V3_AUX_FPGA_VCCIO2")
	)
	(via
		(at 186.87923 -102.682548)
		(size 0.508)
		(drill 0.254)
		(layers "F.Cu" "B.Cu")
		(net "P3V3_AUX_FPGA_VCCIO2")
	)
	(via
		(at 181.755796 -112.57534)
		(size 0.4572)
		(drill 0.254)
		(layers "F.Cu" "B.Cu")
		(net "P3V3_AUX_FPGA_VCCIO2")
	)
	(via
		(at 189.4078 -124.983748)
		(size 0.6604)
		(drill 0.3302)
		(layers "F.Cu" "B.Cu")
		(net "P3V3_AUX_FPGA_VCCIO2")
	)
	(via
		(at 184.955688 -117.375432)
		(size 0.4572)
		(drill 0.254)
		(layers "F.Cu" "B.Cu")
		(net "P3V3_AUX_FPGA_VCCIO2")
	)
	(segment
		(start 185.355738 -116.975382)
		(end 184.955688 -117.375432)
		(width 0.381)
		(layer "B.Cu")
		(net "P3V3_AUX_FPGA_VCCIO2")
	)
	(segment
		(start 185.355738 -109.775498)
		(end 184.955688 -109.375448)
		(width 0.381)
		(layer "B.Cu")
		(net "P3V3_AUX_FPGA_VCCIO2")
	)
	(segment
		(start 184.555638 -112.97539)
		(end 184.955688 -112.57534)
		(width 0.381)
		(layer "B.Cu")
		(net "P3V3_AUX_FPGA_VCCIO2")
	)
	(segment
		(start 177.355754 -116.175536)
		(end 176.955704 -116.575586)
		(width 0.381)
		(layer "F.Cu")
		(net "P3V3_AUX_FPGA_VCCIO1")
	)
	(segment
		(start 180.555646 -116.175536)
		(end 180.955696 -116.575586)
		(width 0.381)
		(layer "F.Cu")
		(net "P3V3_AUX_FPGA_VCCIO1")
	)
	(segment
		(start 183.755538 -120.175528)
		(end 184.155588 -120.575578)
		(width 0.381)
		(layer "F.Cu")
		(net "P3V3_AUX_FPGA_VCCIO1")
	)
	(segment
		(start 174.155608 -120.175528)
		(end 173.755558 -120.575578)
		(width 0.381)
		(layer "F.Cu")
		(net "P3V3_AUX_FPGA_VCCIO1")
	)
	(segment
		(start 179.755546 -116.175536)
		(end 180.155596 -116.575586)
		(width 0.381)
		(layer "F.Cu")
		(net "P3V3_AUX_FPGA_VCCIO1")
	)
	(segment
		(start 176.555654 -116.175536)
		(end 176.155604 -116.575586)
		(width 0.381)
		(layer "F.Cu")
		(net "P3V3_AUX_FPGA_VCCIO1")
	)
	(segment
		(start 178.1556 -116.175536)
		(end 177.75555 -116.575586)
		(width 0.381)
		(layer "F.Cu")
		(net "P3V3_AUX_FPGA_VCCIO1")
	)
	(segment
		(start 178.9557 -118.575328)
		(end 179.35575 -118.975378)
		(width 0.381)
		(layer "F.Cu")
		(net "P3V3_AUX_FPGA_VCCIO1")
	)
	(segment
		(start 178.9557 -116.175536)
		(end 179.35575 -116.575586)
		(width 0.381)
		(layer "F.Cu")
		(net "P3V3_AUX_FPGA_VCCIO1")
	)
	(via
		(at 179.35575 -118.975378)
		(size 0.4572)
		(drill 0.254)
		(layers "F.Cu" "B.Cu")
		(net "P3V3_AUX_FPGA_VCCIO1")
	)
	(via
		(at 175.40732 -122.679968)
		(size 0.508)
		(drill 0.254)
		(layers "F.Cu" "B.Cu")
		(net "P3V3_AUX_FPGA_VCCIO1")
	)
	(via
		(at 176.40554 -122.667268)
		(size 0.508)
		(drill 0.254)
		(layers "F.Cu" "B.Cu")
		(net "P3V3_AUX_FPGA_VCCIO1")
	)
	(via
		(at 184.155588 -120.575578)
		(size 0.4572)
		(drill 0.254)
		(layers "F.Cu" "B.Cu")
		(net "P3V3_AUX_FPGA_VCCIO1")
	)
	(via
		(at 174.27448 -122.392948)
		(size 0.508)
		(drill 0.254)
		(layers "F.Cu" "B.Cu")
		(net "P3V3_AUX_FPGA_VCCIO1")
	)
	(via
		(at 180.955696 -116.575586)
		(size 0.4572)
		(drill 0.254)
		(layers "F.Cu" "B.Cu")
		(net "P3V3_AUX_FPGA_VCCIO1")
	)
	(via
		(at 180.155596 -116.575586)
		(size 0.4572)
		(drill 0.254)
		(layers "F.Cu" "B.Cu")
		(net "P3V3_AUX_FPGA_VCCIO1")
	)
	(via
		(at 179.35575 -116.575586)
		(size 0.4572)
		(drill 0.254)
		(layers "F.Cu" "B.Cu")
		(net "P3V3_AUX_FPGA_VCCIO1")
	)
	(via
		(at 177.284888 -122.360436)
		(size 0.6604)
		(drill 0.3302)
		(layers "F.Cu" "B.Cu")
		(net "P3V3_AUX_FPGA_VCCIO1")
	)
	(via
		(at 176.955704 -116.575586)
		(size 0.4572)
		(drill 0.254)
		(layers "F.Cu" "B.Cu")
		(net "P3V3_AUX_FPGA_VCCIO1")
	)
	(via
		(at 173.755558 -120.575578)
		(size 0.4572)
		(drill 0.254)
		(layers "F.Cu" "B.Cu")
		(net "P3V3_AUX_FPGA_VCCIO1")
	)
	(via
		(at 176.155604 -116.575586)
		(size 0.4572)
		(drill 0.254)
		(layers "F.Cu" "B.Cu")
		(net "P3V3_AUX_FPGA_VCCIO1")
	)
	(via
		(at 177.75555 -116.575586)
		(size 0.4572)
		(drill 0.254)
		(layers "F.Cu" "B.Cu")
		(net "P3V3_AUX_FPGA_VCCIO1")
	)
	(segment
		(start 174.155354 -120.975374)
		(end 174.155608 -120.975374)
		(width 0.381)
		(layer "B.Cu")
		(net "P3V3_AUX_FPGA_VCCIO1")
	)
	(segment
		(start 173.755558 -120.575578)
		(end 174.155354 -120.975374)
		(width 0.381)
		(layer "B.Cu")
		(net "P3V3_AUX_FPGA_VCCIO1")
	)
	(segment
		(start 183.755792 -120.975374)
		(end 183.755538 -120.975374)
		(width 0.381)
		(layer "B.Cu")
		(net "P3V3_AUX_FPGA_VCCIO1")
	)
	(segment
		(start 178.9557 -118.575328)
		(end 179.35575 -118.975378)
		(width 0.381)
		(layer "B.Cu")
		(net "P3V3_AUX_FPGA_VCCIO1")
	)
	(segment
		(start 184.155588 -120.575578)
		(end 183.755792 -120.975374)
		(width 0.381)
		(layer "B.Cu")
		(net "P3V3_AUX_FPGA_VCCIO1")
	)
	(segment
		(start 174.955708 -112.175544)
		(end 174.555658 -111.775494)
		(width 0.381)
		(layer "F.Cu")
		(net "P3V3_AUX_FPGA_VCCIO0")
	)
	(segment
		(start 171.755562 -116.975382)
		(end 171.355512 -117.375432)
		(width 0.381)
		(layer "F.Cu")
		(net "P3V3_AUX_FPGA_VCCIO0")
	)
	(segment
		(start 175.755554 -113.77549)
		(end 175.355504 -114.17554)
		(width 0.381)
		(layer "F.Cu")
		(net "P3V3_AUX_FPGA_VCCIO0")
	)
	(segment
		(start 171.755562 -109.775498)
		(end 171.355512 -109.375448)
		(width 0.381)
		(layer "F.Cu")
		(net "P3V3_AUX_FPGA_VCCIO0")
	)
	(segment
		(start 174.955708 -114.575336)
		(end 174.555658 -114.975386)
		(width 0.381)
		(layer "F.Cu")
		(net "P3V3_AUX_FPGA_VCCIO0")
	)
	(segment
		(start 175.755554 -111.375444)
		(end 175.355504 -110.975394)
		(width 0.381)
		(layer "F.Cu")
		(net "P3V3_AUX_FPGA_VCCIO0")
	)
	(segment
		(start 175.755554 -112.97539)
		(end 175.355504 -112.57534)
		(width 0.381)
		(layer "F.Cu")
		(net "P3V3_AUX_FPGA_VCCIO0")
	)
	(segment
		(start 175.755554 -115.375436)
		(end 175.355504 -115.775486)
		(width 0.381)
		(layer "F.Cu")
		(net "P3V3_AUX_FPGA_VCCIO0")
	)
	(segment
		(start 171.755562 -113.77549)
		(end 171.355512 -114.17554)
		(width 0.381)
		(layer "F.Cu")
		(net "P3V3_AUX_FPGA_VCCIO0")
	)
	(via
		(at 174.555658 -111.775494)
		(size 0.4572)
		(drill 0.254)
		(layers "F.Cu" "B.Cu")
		(net "P3V3_AUX_FPGA_VCCIO0")
	)
	(via
		(at 171.355512 -109.375448)
		(size 0.4572)
		(drill 0.254)
		(layers "F.Cu" "B.Cu")
		(net "P3V3_AUX_FPGA_VCCIO0")
	)
	(via
		(at 169.84853 -102.682548)
		(size 0.508)
		(drill 0.254)
		(layers "F.Cu" "B.Cu")
		(net "P3V3_AUX_FPGA_VCCIO0")
	)
	(via
		(at 170.41876 -103.238808)
		(size 0.6604)
		(drill 0.3302)
		(layers "F.Cu" "B.Cu")
		(net "P3V3_AUX_FPGA_VCCIO0")
	)
	(via
		(at 169.84853 -103.723948)
		(size 0.508)
		(drill 0.254)
		(layers "F.Cu" "B.Cu")
		(net "P3V3_AUX_FPGA_VCCIO0")
	)
	(via
		(at 175.355504 -115.775486)
		(size 0.4572)
		(drill 0.254)
		(layers "F.Cu" "B.Cu")
		(net "P3V3_AUX_FPGA_VCCIO0")
	)
	(via
		(at 171.355512 -117.375432)
		(size 0.4572)
		(drill 0.254)
		(layers "F.Cu" "B.Cu")
		(net "P3V3_AUX_FPGA_VCCIO0")
	)
	(via
		(at 170.36288 -101.564948)
		(size 0.508)
		(drill 0.254)
		(layers "F.Cu" "B.Cu")
		(net "P3V3_AUX_FPGA_VCCIO0")
	)
	(via
		(at 171.355512 -114.17554)
		(size 0.4572)
		(drill 0.254)
		(layers "F.Cu" "B.Cu")
		(net "P3V3_AUX_FPGA_VCCIO0")
	)
	(via
		(at 175.355504 -110.975394)
		(size 0.4572)
		(drill 0.254)
		(layers "F.Cu" "B.Cu")
		(net "P3V3_AUX_FPGA_VCCIO0")
	)
	(via
		(at 175.355504 -114.17554)
		(size 0.4572)
		(drill 0.254)
		(layers "F.Cu" "B.Cu")
		(net "P3V3_AUX_FPGA_VCCIO0")
	)
	(via
		(at 174.555658 -114.975386)
		(size 0.4572)
		(drill 0.254)
		(layers "F.Cu" "B.Cu")
		(net "P3V3_AUX_FPGA_VCCIO0")
	)
	(via
		(at 175.355504 -112.57534)
		(size 0.4572)
		(drill 0.254)
		(layers "F.Cu" "B.Cu")
		(net "P3V3_AUX_FPGA_VCCIO0")
	)
	(segment
		(start 170.955716 -109.775244)
		(end 170.955716 -109.775498)
		(width 0.381)
		(layer "B.Cu")
		(net "P3V3_AUX_FPGA_VCCIO0")
	)
	(segment
		(start 171.755562 -113.77549)
		(end 171.355512 -114.17554)
		(width 0.381)
		(layer "B.Cu")
		(net "P3V3_AUX_FPGA_VCCIO0")
	)
	(segment
		(start 171.355512 -117.375432)
		(end 170.955716 -116.975636)
		(width 0.381)
		(layer "B.Cu")
		(net "P3V3_AUX_FPGA_VCCIO0")
	)
	(segment
		(start 170.955716 -116.975636)
		(end 170.955716 -116.975382)
		(width 0.381)
		(layer "B.Cu")
		(net "P3V3_AUX_FPGA_VCCIO0")
	)
	(segment
		(start 171.355512 -109.375448)
		(end 170.955716 -109.775244)
		(width 0.381)
		(layer "B.Cu")
		(net "P3V3_AUX_FPGA_VCCIO0")
	)
	(segment
		(start 98.57105 -389.75919)
		(end 100.33762 -387.99262)
		(width 0.13208)
		(layer "F.Cu")
		(net "P3E_PCH_NVS_TX_DP<1>")
	)
	(segment
		(start 168.71315 -383.03835)
		(end 170.505882 -383.03835)
		(width 0.13208)
		(layer "F.Cu")
		(net "P3E_PCH_NVS_TX_DP<1>")
	)
	(segment
		(start 100.33762 -387.99262)
		(end 168.71315 -383.03835)
		(width 0.13208)
		(layer "F.Cu")
		(net "P3E_PCH_NVS_TX_DP<1>")
	)
	(segment
		(start 245.154196 -197.079362)
		(end 246.721884 -191.504824)
		(width 0.13208)
		(layer "F.Cu")
		(net "P3E_PCH_NVS_TX_DP<1>")
	)
	(segment
		(start 99.09556 -403.44598)
		(end 98.894646 -403.646894)
		(width 0.13208)
		(layer "F.Cu")
		(net "P3E_PCH_NVS_TX_DP<1>")
	)
	(segment
		(start 170.505882 -383.03835)
		(end 170.50639 -383.038858)
		(width 0.13208)
		(layer "F.Cu")
		(net "P3E_PCH_NVS_TX_DP<1>")
	)
	(segment
		(start 246.721884 -191.504824)
		(end 253.568708 -184.658)
		(width 0.13208)
		(layer "F.Cu")
		(net "P3E_PCH_NVS_TX_DP<1>")
	)
	(segment
		(start 173.766226 -382.300734)
		(end 180.909468 -378.031756)
		(width 0.13208)
		(layer "F.Cu")
		(net "P3E_PCH_NVS_TX_DP<1>")
	)
	(segment
		(start 228.518466 -309.497476)
		(end 228.51872 -309.497222)
		(width 0.13208)
		(layer "F.Cu")
		(net "P3E_PCH_NVS_TX_DP<1>")
	)
	(segment
		(start 97.29978 -402.39188)
		(end 98.57105 -389.75919)
		(width 0.13208)
		(layer "F.Cu")
		(net "P3E_PCH_NVS_TX_DP<1>")
	)
	(segment
		(start 99.39782 -402.62937)
		(end 99.09556 -402.93163)
		(width 0.13208)
		(layer "F.Cu")
		(net "P3E_PCH_NVS_TX_DP<1>")
	)
	(segment
		(start 99.09556 -402.93163)
		(end 99.09556 -403.44598)
		(width 0.13208)
		(layer "F.Cu")
		(net "P3E_PCH_NVS_TX_DP<1>")
	)
	(segment
		(start 228.51872 -309.497222)
		(end 244.540786 -275.153374)
		(width 0.13208)
		(layer "F.Cu")
		(net "P3E_PCH_NVS_TX_DP<1>")
	)
	(segment
		(start 245.7831 -246.358918)
		(end 245.154196 -197.079362)
		(width 0.13208)
		(layer "F.Cu")
		(net "P3E_PCH_NVS_TX_DP<1>")
	)
	(segment
		(start 344.63355 -51.269646)
		(end 344.36431 -50.799746)
		(width 0.13208)
		(layer "F.Cu")
		(net "P3E_PCH_NVS_TX_DP<1>")
	)
	(segment
		(start 253.568708 -184.658)
		(end 284.709362 -171.759118)
		(width 0.13208)
		(layer "F.Cu")
		(net "P3E_PCH_NVS_TX_DP<1>")
	)
	(segment
		(start 180.909468 -378.031756)
		(end 212.496654 -343.84107)
		(width 0.13208)
		(layer "F.Cu")
		(net "P3E_PCH_NVS_TX_DP<1>")
	)
	(segment
		(start 98.894646 -403.646894)
		(end 97.786698 -403.646894)
		(width 0.13208)
		(layer "F.Cu")
		(net "P3E_PCH_NVS_TX_DP<1>")
	)
	(segment
		(start 245.7831 -263.616186)
		(end 245.7831 -246.358918)
		(width 0.13208)
		(layer "F.Cu")
		(net "P3E_PCH_NVS_TX_DP<1>")
	)
	(segment
		(start 97.786698 -403.646894)
		(end 97.29978 -403.159976)
		(width 0.13208)
		(layer "F.Cu")
		(net "P3E_PCH_NVS_TX_DP<1>")
	)
	(segment
		(start 293.25824 -162.403028)
		(end 292.95598 -162.100768)
		(width 0.13208)
		(layer "F.Cu")
		(net "P3E_PCH_NVS_TX_DP<1>")
	)
	(segment
		(start 244.540786 -275.153374)
		(end 245.7831 -263.616186)
		(width 0.13208)
		(layer "F.Cu")
		(net "P3E_PCH_NVS_TX_DP<1>")
	)
	(segment
		(start 212.496654 -343.84107)
		(end 228.518466 -309.497476)
		(width 0.13208)
		(layer "F.Cu")
		(net "P3E_PCH_NVS_TX_DP<1>")
	)
	(segment
		(start 293.25824 -163.21024)
		(end 293.25824 -162.403028)
		(width 0.13208)
		(layer "F.Cu")
		(net "P3E_PCH_NVS_TX_DP<1>")
	)
	(segment
		(start 170.50639 -383.038858)
		(end 173.766226 -382.300734)
		(width 0.13208)
		(layer "F.Cu")
		(net "P3E_PCH_NVS_TX_DP<1>")
	)
	(segment
		(start 284.709362 -171.759118)
		(end 293.25824 -163.21024)
		(width 0.13208)
		(layer "F.Cu")
		(net "P3E_PCH_NVS_TX_DP<1>")
	)
	(segment
		(start 97.29978 -403.159976)
		(end 97.29978 -402.39188)
		(width 0.13208)
		(layer "F.Cu")
		(net "P3E_PCH_NVS_TX_DP<1>")
	)
	(via
		(at 99.39782 -402.62937)
		(size 0.508)
		(drill 0.254)
		(layers "F.Cu" "B.Cu")
		(net "P3E_PCH_NVS_TX_DP<1>")
	)
	(segment
		(start 99.10318 -402.92401)
		(end 99.10318 -403.90318)
		(width 0.13208)
		(layer "B.Cu")
		(net "P3E_PCH_NVS_TX_DP<1>")
	)
	(segment
		(start 99.39782 -402.62937)
		(end 99.10318 -402.92401)
		(width 0.13208)
		(layer "B.Cu")
		(net "P3E_PCH_NVS_TX_DP<1>")
	)
	(segment
		(start 99.10318 -403.90318)
		(end 99.419918 -404.219918)
		(width 0.13208)
		(layer "B.Cu")
		(net "P3E_PCH_NVS_TX_DP<1>")
	)
	(segment
		(start 296.653458 -158.182818)
		(end 296.4942 -158.116778)
		(width 0.14732)
		(layer "In2.Cu")
		(net "P3E_PCH_NVS_TX_DP<1>")
	)
	(segment
		(start 346.008706 -71.694294)
		(end 347.62313 -84.874608)
		(width 0.14732)
		(layer "In2.Cu")
		(net "P3E_PCH_NVS_TX_DP<1>")
	)
	(segment
		(start 299.122846 -157.160214)
		(end 298.718986 -157.327346)
		(width 0.14732)
		(layer "In2.Cu")
		(net "P3E_PCH_NVS_TX_DP<1>")
	)
	(segment
		(start 300.434756 -156.48432)
		(end 300.367192 -156.647134)
		(width 0.14732)
		(layer "In2.Cu")
		(net "P3E_PCH_NVS_TX_DP<1>")
	)
	(segment
		(start 345.329256 -68.752974)
		(end 345.385136 -70.215252)
		(width 0.14732)
		(layer "In2.Cu")
		(net "P3E_PCH_NVS_TX_DP<1>")
	)
	(segment
		(start 346.218764 -51.243992)
		(end 346.218764 -56.395366)
		(width 0.14732)
		(layer "In2.Cu")
		(net "P3E_PCH_NVS_TX_DP<1>")
	)
	(segment
		(start 299.805598 -156.745178)
		(end 299.188886 -157.000448)
		(width 0.14732)
		(layer "In2.Cu")
		(net "P3E_PCH_NVS_TX_DP<1>")
	)
	(segment
		(start 345.67622 -50.956972)
		(end 345.698318 -50.956972)
		(width 0.0889)
		(layer "In2.Cu")
		(net "P3E_PCH_NVS_TX_DP<1>")
	)
	(segment
		(start 346.218764 -56.395366)
		(end 346.70238 -58.82767)
		(width 0.14732)
		(layer "In2.Cu")
		(net "P3E_PCH_NVS_TX_DP<1>")
	)
	(segment
		(start 291.883084 -161.281364)
		(end 291.57422 -161.590228)
		(width 0.14732)
		(layer "In2.Cu")
		(net "P3E_PCH_NVS_TX_DP<1>")
	)
	(segment
		(start 292.05555 -161.281364)
		(end 291.883084 -161.281364)
		(width 0.14732)
		(layer "In2.Cu")
		(net "P3E_PCH_NVS_TX_DP<1>")
	)
	(segment
		(start 296.090594 -158.28391)
		(end 296.024554 -158.443422)
		(width 0.14732)
		(layer "In2.Cu")
		(net "P3E_PCH_NVS_TX_DP<1>")
	)
	(segment
		(start 346.70238 -58.82767)
		(end 346.70238 -60.48756)
		(width 0.14732)
		(layer "In2.Cu")
		(net "P3E_PCH_NVS_TX_DP<1>")
	)
	(segment
		(start 340.31936 -139.97559)
		(end 340.289642 -139.97559)
		(width 0.14732)
		(layer "In2.Cu")
		(net "P3E_PCH_NVS_TX_DP<1>")
	)
	(segment
		(start 299.968158 -156.812488)
		(end 299.805598 -156.745178)
		(width 0.14732)
		(layer "In2.Cu")
		(net "P3E_PCH_NVS_TX_DP<1>")
	)
	(segment
		(start 293.25062 -162.395408)
		(end 292.95598 -162.100768)
		(width 0.14732)
		(layer "In2.Cu")
		(net "P3E_PCH_NVS_TX_DP<1>")
	)
	(segment
		(start 292.364668 -160.79978)
		(end 292.364668 -160.972246)
		(width 0.14732)
		(layer "In2.Cu")
		(net "P3E_PCH_NVS_TX_DP<1>")
	)
	(segment
		(start 297.057318 -158.015686)
		(end 296.653458 -158.182818)
		(width 0.14732)
		(layer "In2.Cu")
		(net "P3E_PCH_NVS_TX_DP<1>")
	)
	(segment
		(start 346.70238 -60.48756)
		(end 345.329256 -68.752974)
		(width 0.14732)
		(layer "In2.Cu")
		(net "P3E_PCH_NVS_TX_DP<1>")
	)
	(segment
		(start 299.188886 -157.000702)
		(end 299.122846 -157.160214)
		(width 0.14732)
		(layer "In2.Cu")
		(net "P3E_PCH_NVS_TX_DP<1>")
	)
	(segment
		(start 298.090082 -157.58795)
		(end 297.686222 -157.755082)
		(width 0.14732)
		(layer "In2.Cu")
		(net "P3E_PCH_NVS_TX_DP<1>")
	)
	(segment
		(start 297.123358 -157.856174)
		(end 297.057318 -158.015686)
		(width 0.14732)
		(layer "In2.Cu")
		(net "P3E_PCH_NVS_TX_DP<1>")
	)
	(segment
		(start 293.155116 -160.181798)
		(end 292.845998 -160.490916)
		(width 0.14732)
		(layer "In2.Cu")
		(net "P3E_PCH_NVS_TX_DP<1>")
	)
	(segment
		(start 293.037514 -162.817048)
		(end 293.25062 -162.603942)
		(width 0.14732)
		(layer "In2.Cu")
		(net "P3E_PCH_NVS_TX_DP<1>")
	)
	(segment
		(start 342.788494 -137.506456)
		(end 340.31936 -139.97559)
		(width 0.14732)
		(layer "In2.Cu")
		(net "P3E_PCH_NVS_TX_DP<1>")
	)
	(segment
		(start 300.367192 -156.647134)
		(end 299.968158 -156.812488)
		(width 0.14732)
		(layer "In2.Cu")
		(net "P3E_PCH_NVS_TX_DP<1>")
	)
	(segment
		(start 291.91712 -162.817048)
		(end 293.037514 -162.817048)
		(width 0.14732)
		(layer "In2.Cu")
		(net "P3E_PCH_NVS_TX_DP<1>")
	)
	(segment
		(start 347.62313 -84.874608)
		(end 343.208356 -136.076436)
		(width 0.14732)
		(layer "In2.Cu")
		(net "P3E_PCH_NVS_TX_DP<1>")
	)
	(segment
		(start 345.698318 -50.956972)
		(end 345.931744 -50.956972)
		(width 0.14732)
		(layer "In2.Cu")
		(net "P3E_PCH_NVS_TX_DP<1>")
	)
	(segment
		(start 297.686222 -157.755082)
		(end 297.526964 -157.689042)
		(width 0.14732)
		(layer "In2.Cu")
		(net "P3E_PCH_NVS_TX_DP<1>")
	)
	(segment
		(start 299.188886 -157.000448)
		(end 299.188886 -157.000702)
		(width 0.14732)
		(layer "In2.Cu")
		(net "P3E_PCH_NVS_TX_DP<1>")
	)
	(segment
		(start 297.526964 -157.689042)
		(end 297.123358 -157.856174)
		(width 0.14732)
		(layer "In2.Cu")
		(net "P3E_PCH_NVS_TX_DP<1>")
	)
	(segment
		(start 294.58793 -159.03829)
		(end 294.428672 -158.97225)
		(width 0.14732)
		(layer "In2.Cu")
		(net "P3E_PCH_NVS_TX_DP<1>")
	)
	(segment
		(start 292.673532 -160.490916)
		(end 292.364668 -160.79978)
		(width 0.14732)
		(layer "In2.Cu")
		(net "P3E_PCH_NVS_TX_DP<1>")
	)
	(segment
		(start 295.620694 -158.610554)
		(end 295.461436 -158.544514)
		(width 0.14732)
		(layer "In2.Cu")
		(net "P3E_PCH_NVS_TX_DP<1>")
	)
	(segment
		(start 345.931744 -50.956972)
		(end 346.218764 -51.243992)
		(width 0.14732)
		(layer "In2.Cu")
		(net "P3E_PCH_NVS_TX_DP<1>")
	)
	(segment
		(start 292.364668 -160.972246)
		(end 292.05555 -161.281364)
		(width 0.14732)
		(layer "In2.Cu")
		(net "P3E_PCH_NVS_TX_DP<1>")
	)
	(segment
		(start 344.563446 -50.998882)
		(end 345.63431 -50.998882)
		(width 0.0889)
		(layer "In2.Cu")
		(net "P3E_PCH_NVS_TX_DP<1>")
	)
	(segment
		(start 343.208356 -136.076436)
		(end 342.788494 -137.506456)
		(width 0.14732)
		(layer "In2.Cu")
		(net "P3E_PCH_NVS_TX_DP<1>")
	)
	(segment
		(start 292.845998 -160.490916)
		(end 292.673532 -160.490916)
		(width 0.14732)
		(layer "In2.Cu")
		(net "P3E_PCH_NVS_TX_DP<1>")
	)
	(segment
		(start 294.025066 -159.139382)
		(end 293.155116 -160.009332)
		(width 0.14732)
		(layer "In2.Cu")
		(net "P3E_PCH_NVS_TX_DP<1>")
	)
	(segment
		(start 296.024554 -158.443422)
		(end 295.620694 -158.610554)
		(width 0.14732)
		(layer "In2.Cu")
		(net "P3E_PCH_NVS_TX_DP<1>")
	)
	(segment
		(start 294.99179 -158.871158)
		(end 294.58793 -159.03829)
		(width 0.14732)
		(layer "In2.Cu")
		(net "P3E_PCH_NVS_TX_DP<1>")
	)
	(segment
		(start 295.05783 -158.711646)
		(end 294.99179 -158.871158)
		(width 0.14732)
		(layer "In2.Cu")
		(net "P3E_PCH_NVS_TX_DP<1>")
	)
	(segment
		(start 340.289642 -139.97559)
		(end 300.434756 -156.48432)
		(width 0.14732)
		(layer "In2.Cu")
		(net "P3E_PCH_NVS_TX_DP<1>")
	)
	(segment
		(start 345.63431 -50.998882)
		(end 345.67622 -50.956972)
		(width 0.0889)
		(layer "In2.Cu")
		(net "P3E_PCH_NVS_TX_DP<1>")
	)
	(segment
		(start 293.155116 -160.009332)
		(end 293.155116 -160.181798)
		(width 0.14732)
		(layer "In2.Cu")
		(net "P3E_PCH_NVS_TX_DP<1>")
	)
	(segment
		(start 298.559728 -157.261306)
		(end 298.156122 -157.428438)
		(width 0.14732)
		(layer "In2.Cu")
		(net "P3E_PCH_NVS_TX_DP<1>")
	)
	(segment
		(start 295.461436 -158.544514)
		(end 295.05783 -158.711646)
		(width 0.14732)
		(layer "In2.Cu")
		(net "P3E_PCH_NVS_TX_DP<1>")
	)
	(segment
		(start 291.57422 -161.590228)
		(end 291.57422 -162.474148)
		(width 0.14732)
		(layer "In2.Cu")
		(net "P3E_PCH_NVS_TX_DP<1>")
	)
	(segment
		(start 296.4942 -158.116778)
		(end 296.090594 -158.28391)
		(width 0.14732)
		(layer "In2.Cu")
		(net "P3E_PCH_NVS_TX_DP<1>")
	)
	(segment
		(start 298.718986 -157.327346)
		(end 298.559728 -157.261306)
		(width 0.14732)
		(layer "In2.Cu")
		(net "P3E_PCH_NVS_TX_DP<1>")
	)
	(segment
		(start 293.25062 -162.603942)
		(end 293.25062 -162.395408)
		(width 0.14732)
		(layer "In2.Cu")
		(net "P3E_PCH_NVS_TX_DP<1>")
	)
	(segment
		(start 345.385136 -70.215252)
		(end 346.008706 -71.694294)
		(width 0.14732)
		(layer "In2.Cu")
		(net "P3E_PCH_NVS_TX_DP<1>")
	)
	(segment
		(start 294.428672 -158.97225)
		(end 294.025066 -159.139382)
		(width 0.14732)
		(layer "In2.Cu")
		(net "P3E_PCH_NVS_TX_DP<1>")
	)
	(segment
		(start 298.156122 -157.428438)
		(end 298.090082 -157.58795)
		(width 0.14732)
		(layer "In2.Cu")
		(net "P3E_PCH_NVS_TX_DP<1>")
	)
	(segment
		(start 344.36431 -50.799746)
		(end 344.563446 -50.998882)
		(width 0.0889)
		(layer "In2.Cu")
		(net "P3E_PCH_NVS_TX_DP<1>")
	)
	(segment
		(start 291.57422 -162.474148)
		(end 291.91712 -162.817048)
		(width 0.14732)
		(layer "In2.Cu")
		(net "P3E_PCH_NVS_TX_DP<1>")
	)
	(segment
		(start 167.041576 -387.30047)
		(end 173.050708 -385.496054)
		(width 0.13208)
		(layer "F.Cu")
		(net "P3E_PCH_NVS_TX_DP<0>")
	)
	(segment
		(start 102.57282 -407.38298)
		(end 104.81818 -405.13762)
		(width 0.13208)
		(layer "F.Cu")
		(net "P3E_PCH_NVS_TX_DP<0>")
	)
	(segment
		(start 248.2088 -246.342916)
		(end 247.584468 -197.398386)
		(width 0.13208)
		(layer "F.Cu")
		(net "P3E_PCH_NVS_TX_DP<0>")
	)
	(segment
		(start 106.331004 -391.831576)
		(end 109.099096 -390.457944)
		(width 0.13208)
		(layer "F.Cu")
		(net "P3E_PCH_NVS_TX_DP<0>")
	)
	(segment
		(start 173.050708 -385.496054)
		(end 182.573676 -379.806708)
		(width 0.13208)
		(layer "F.Cu")
		(net "P3E_PCH_NVS_TX_DP<0>")
	)
	(segment
		(start 109.099096 -390.457944)
		(end 111.455454 -389.801354)
		(width 0.13208)
		(layer "F.Cu")
		(net "P3E_PCH_NVS_TX_DP<0>")
	)
	(segment
		(start 297.43654 -161.859468)
		(end 297.13428 -161.557208)
		(width 0.13208)
		(layer "F.Cu")
		(net "P3E_PCH_NVS_TX_DP<0>")
	)
	(segment
		(start 344.63355 -50.329846)
		(end 344.365834 -49.859692)
		(width 0.13208)
		(layer "F.Cu")
		(net "P3E_PCH_NVS_TX_DP<0>")
	)
	(segment
		(start 248.886218 -192.771522)
		(end 254.829818 -186.827922)
		(width 0.13208)
		(layer "F.Cu")
		(net "P3E_PCH_NVS_TX_DP<0>")
	)
	(segment
		(start 254.829818 -186.827922)
		(end 291.300916 -171.721272)
		(width 0.13208)
		(layer "F.Cu")
		(net "P3E_PCH_NVS_TX_DP<0>")
	)
	(segment
		(start 105.4862 -395.368526)
		(end 105.4862 -392.764772)
		(width 0.13208)
		(layer "F.Cu")
		(net "P3E_PCH_NVS_TX_DP<0>")
	)
	(segment
		(start 104.81818 -396.981426)
		(end 105.4862 -395.368526)
		(width 0.13208)
		(layer "F.Cu")
		(net "P3E_PCH_NVS_TX_DP<0>")
	)
	(segment
		(start 105.4862 -392.764772)
		(end 106.331004 -391.831576)
		(width 0.13208)
		(layer "F.Cu")
		(net "P3E_PCH_NVS_TX_DP<0>")
	)
	(segment
		(start 248.2088 -264.947908)
		(end 248.2088 -246.342916)
		(width 0.13208)
		(layer "F.Cu")
		(net "P3E_PCH_NVS_TX_DP<0>")
	)
	(segment
		(start 104.81818 -405.13762)
		(end 104.81818 -396.981426)
		(width 0.13208)
		(layer "F.Cu")
		(net "P3E_PCH_NVS_TX_DP<0>")
	)
	(segment
		(start 214.434674 -345.319604)
		(end 247.09247 -275.313394)
		(width 0.13208)
		(layer "F.Cu")
		(net "P3E_PCH_NVS_TX_DP<0>")
	)
	(segment
		(start 247.09247 -275.313394)
		(end 248.2088 -264.947908)
		(width 0.13208)
		(layer "F.Cu")
		(net "P3E_PCH_NVS_TX_DP<0>")
	)
	(segment
		(start 102.306374 -409.31084)
		(end 102.57282 -409.044394)
		(width 0.13208)
		(layer "F.Cu")
		(net "P3E_PCH_NVS_TX_DP<0>")
	)
	(segment
		(start 291.300916 -171.721272)
		(end 297.43654 -165.585648)
		(width 0.13208)
		(layer "F.Cu")
		(net "P3E_PCH_NVS_TX_DP<0>")
	)
	(segment
		(start 102.57282 -409.044394)
		(end 102.57282 -407.38298)
		(width 0.13208)
		(layer "F.Cu")
		(net "P3E_PCH_NVS_TX_DP<0>")
	)
	(segment
		(start 297.43654 -165.585648)
		(end 297.43654 -161.859468)
		(width 0.13208)
		(layer "F.Cu")
		(net "P3E_PCH_NVS_TX_DP<0>")
	)
	(segment
		(start 111.455454 -389.801354)
		(end 167.041576 -387.30047)
		(width 0.13208)
		(layer "F.Cu")
		(net "P3E_PCH_NVS_TX_DP<0>")
	)
	(segment
		(start 247.584468 -197.398386)
		(end 248.886218 -192.771522)
		(width 0.13208)
		(layer "F.Cu")
		(net "P3E_PCH_NVS_TX_DP<0>")
	)
	(segment
		(start 182.573676 -379.806708)
		(end 214.434674 -345.319604)
		(width 0.13208)
		(layer "F.Cu")
		(net "P3E_PCH_NVS_TX_DP<0>")
	)
	(segment
		(start 345.71432 -49.120552)
		(end 345.736418 -49.120552)
		(width 0.0889)
		(layer "In2.Cu")
		(net "P3E_PCH_NVS_TX_DP<0>")
	)
	(segment
		(start 345.736418 -49.120552)
		(end 345.798902 -49.120552)
		(width 0.14732)
		(layer "In2.Cu")
		(net "P3E_PCH_NVS_TX_DP<0>")
	)
	(segment
		(start 344.345514 -49.485042)
		(end 344.365072 -49.485042)
		(width 0.0889)
		(layer "In2.Cu")
		(net "P3E_PCH_NVS_TX_DP<0>")
	)
	(segment
		(start 348.421706 -70.843394)
		(end 348.4499 -71.191628)
		(width 0.14732)
		(layer "In2.Cu")
		(net "P3E_PCH_NVS_TX_DP<0>")
	)
	(segment
		(start 347.697044 -64.101218)
		(end 347.57995 -64.22771)
		(width 0.14732)
		(layer "In2.Cu")
		(net "P3E_PCH_NVS_TX_DP<0>")
	)
	(segment
		(start 340.723474 -140.523468)
		(end 301.2567 -156.871416)
		(width 0.14732)
		(layer "In2.Cu")
		(net "P3E_PCH_NVS_TX_DP<0>")
	)
	(segment
		(start 347.091 -51.82108)
		(end 346.96908 -51.943)
		(width 0.14732)
		(layer "In2.Cu")
		(net "P3E_PCH_NVS_TX_DP<0>")
	)
	(segment
		(start 346.5576 -50.051716)
		(end 346.730066 -50.051716)
		(width 0.14732)
		(layer "In2.Cu")
		(net "P3E_PCH_NVS_TX_DP<0>")
	)
	(segment
		(start 347.091 -50.41265)
		(end 347.091 -50.70348)
		(width 0.14732)
		(layer "In2.Cu")
		(net "P3E_PCH_NVS_TX_DP<0>")
	)
	(segment
		(start 347.477588 -59.173364)
		(end 347.544644 -60.002166)
		(width 0.14732)
		(layer "In2.Cu")
		(net "P3E_PCH_NVS_TX_DP<0>")
	)
	(segment
		(start 347.681042 -63.664846)
		(end 347.697044 -64.101218)
		(width 0.14732)
		(layer "In2.Cu")
		(net "P3E_PCH_NVS_TX_DP<0>")
	)
	(segment
		(start 297.13428 -161.506408)
		(end 297.13428 -161.557208)
		(width 0.14732)
		(layer "In2.Cu")
		(net "P3E_PCH_NVS_TX_DP<0>")
	)
	(segment
		(start 347.891608 -69.320156)
		(end 348.421706 -70.843394)
		(width 0.14732)
		(layer "In2.Cu")
		(net "P3E_PCH_NVS_TX_DP<0>")
	)
	(segment
		(start 345.798902 -49.120552)
		(end 346.248482 -49.570132)
		(width 0.14732)
		(layer "In2.Cu")
		(net "P3E_PCH_NVS_TX_DP<0>")
	)
	(segment
		(start 347.091 -52.93868)
		(end 346.96908 -53.0606)
		(width 0.14732)
		(layer "In2.Cu")
		(net "P3E_PCH_NVS_TX_DP<0>")
	)
	(segment
		(start 347.764354 -65.898522)
		(end 347.891608 -69.320156)
		(width 0.14732)
		(layer "In2.Cu")
		(net "P3E_PCH_NVS_TX_DP<0>")
	)
	(segment
		(start 346.96908 -53.49748)
		(end 347.091 -53.6194)
		(width 0.14732)
		(layer "In2.Cu")
		(net "P3E_PCH_NVS_TX_DP<0>")
	)
	(segment
		(start 346.96908 -50.8254)
		(end 346.96908 -51.26228)
		(width 0.14732)
		(layer "In2.Cu")
		(net "P3E_PCH_NVS_TX_DP<0>")
	)
	(segment
		(start 346.96908 -51.943)
		(end 346.96908 -52.37988)
		(width 0.14732)
		(layer "In2.Cu")
		(net "P3E_PCH_NVS_TX_DP<0>")
	)
	(segment
		(start 347.596206 -64.66459)
		(end 347.722698 -64.781684)
		(width 0.14732)
		(layer "In2.Cu")
		(net "P3E_PCH_NVS_TX_DP<0>")
	)
	(segment
		(start 348.28226 -84.930488)
		(end 343.852246 -136.352026)
		(width 0.14732)
		(layer "In2.Cu")
		(net "P3E_PCH_NVS_TX_DP<0>")
	)
	(segment
		(start 347.722698 -64.781684)
		(end 347.7387 -65.218056)
		(width 0.14732)
		(layer "In2.Cu")
		(net "P3E_PCH_NVS_TX_DP<0>")
	)
	(segment
		(start 344.959178 -49.078388)
		(end 345.672156 -49.078388)
		(width 0.0889)
		(layer "In2.Cu")
		(net "P3E_PCH_NVS_TX_DP<0>")
	)
	(segment
		(start 347.091 -52.5018)
		(end 347.091 -52.93868)
		(width 0.14732)
		(layer "In2.Cu")
		(net "P3E_PCH_NVS_TX_DP<0>")
	)
	(segment
		(start 347.637862 -65.781428)
		(end 347.764354 -65.898522)
		(width 0.14732)
		(layer "In2.Cu")
		(net "P3E_PCH_NVS_TX_DP<0>")
	)
	(segment
		(start 297.48226 -160.645856)
		(end 297.48226 -161.158428)
		(width 0.14732)
		(layer "In2.Cu")
		(net "P3E_PCH_NVS_TX_DP<0>")
	)
	(segment
		(start 347.544644 -60.002166)
		(end 347.655642 -62.98438)
		(width 0.14732)
		(layer "In2.Cu")
		(net "P3E_PCH_NVS_TX_DP<0>")
	)
	(segment
		(start 344.365072 -49.485042)
		(end 344.394028 -49.484788)
		(width 0.0889)
		(layer "In2.Cu")
		(net "P3E_PCH_NVS_TX_DP<0>")
	)
	(segment
		(start 344.365834 -49.859692)
		(end 344.094308 -50.015902)
		(width 0.0889)
		(layer "In2.Cu")
		(net "P3E_PCH_NVS_TX_DP<0>")
	)
	(segment
		(start 343.406222 -137.84072)
		(end 340.723474 -140.523468)
		(width 0.14732)
		(layer "In2.Cu")
		(net "P3E_PCH_NVS_TX_DP<0>")
	)
	(segment
		(start 343.852246 -136.352026)
		(end 343.406222 -137.84072)
		(width 0.14732)
		(layer "In2.Cu")
		(net "P3E_PCH_NVS_TX_DP<0>")
	)
	(segment
		(start 346.96908 -53.0606)
		(end 346.96908 -53.49748)
		(width 0.14732)
		(layer "In2.Cu")
		(net "P3E_PCH_NVS_TX_DP<0>")
	)
	(segment
		(start 347.538294 -63.110872)
		(end 347.55455 -63.547498)
		(width 0.14732)
		(layer "In2.Cu")
		(net "P3E_PCH_NVS_TX_DP<0>")
	)
	(segment
		(start 347.655642 -62.98438)
		(end 347.538294 -63.110872)
		(width 0.14732)
		(layer "In2.Cu")
		(net "P3E_PCH_NVS_TX_DP<0>")
	)
	(segment
		(start 346.96908 -54.1782)
		(end 346.96908 -54.61508)
		(width 0.14732)
		(layer "In2.Cu")
		(net "P3E_PCH_NVS_TX_DP<0>")
	)
	(segment
		(start 347.57995 -64.22771)
		(end 347.596206 -64.66459)
		(width 0.14732)
		(layer "In2.Cu")
		(net "P3E_PCH_NVS_TX_DP<0>")
	)
	(segment
		(start 347.091 -53.6194)
		(end 347.091 -54.05628)
		(width 0.14732)
		(layer "In2.Cu")
		(net "P3E_PCH_NVS_TX_DP<0>")
	)
	(segment
		(start 346.96908 -51.26228)
		(end 347.091 -51.3842)
		(width 0.14732)
		(layer "In2.Cu")
		(net "P3E_PCH_NVS_TX_DP<0>")
	)
	(segment
		(start 346.248482 -49.570132)
		(end 346.248482 -49.742598)
		(width 0.14732)
		(layer "In2.Cu")
		(net "P3E_PCH_NVS_TX_DP<0>")
	)
	(segment
		(start 346.96908 -52.37988)
		(end 347.091 -52.5018)
		(width 0.14732)
		(layer "In2.Cu")
		(net "P3E_PCH_NVS_TX_DP<0>")
	)
	(segment
		(start 347.091 -54.737)
		(end 347.091 -57.237376)
		(width 0.14732)
		(layer "In2.Cu")
		(net "P3E_PCH_NVS_TX_DP<0>")
	)
	(segment
		(start 347.7387 -65.218056)
		(end 347.621606 -65.344548)
		(width 0.14732)
		(layer "In2.Cu")
		(net "P3E_PCH_NVS_TX_DP<0>")
	)
	(segment
		(start 348.4499 -71.191628)
		(end 348.28226 -84.930488)
		(width 0.14732)
		(layer "In2.Cu")
		(net "P3E_PCH_NVS_TX_DP<0>")
	)
	(segment
		(start 346.248482 -49.742598)
		(end 346.5576 -50.051716)
		(width 0.14732)
		(layer "In2.Cu")
		(net "P3E_PCH_NVS_TX_DP<0>")
	)
	(segment
		(start 346.96908 -54.61508)
		(end 347.091 -54.737)
		(width 0.14732)
		(layer "In2.Cu")
		(net "P3E_PCH_NVS_TX_DP<0>")
	)
	(segment
		(start 344.91295 -49.124616)
		(end 344.959178 -49.078388)
		(width 0.0889)
		(layer "In2.Cu")
		(net "P3E_PCH_NVS_TX_DP<0>")
	)
	(segment
		(start 347.091 -57.237376)
		(end 347.477588 -59.173364)
		(width 0.14732)
		(layer "In2.Cu")
		(net "P3E_PCH_NVS_TX_DP<0>")
	)
	(segment
		(start 301.2567 -156.871416)
		(end 297.48226 -160.645856)
		(width 0.14732)
		(layer "In2.Cu")
		(net "P3E_PCH_NVS_TX_DP<0>")
	)
	(segment
		(start 297.48226 -161.158428)
		(end 297.13428 -161.506408)
		(width 0.14732)
		(layer "In2.Cu")
		(net "P3E_PCH_NVS_TX_DP<0>")
	)
	(segment
		(start 347.091 -51.3842)
		(end 347.091 -51.82108)
		(width 0.14732)
		(layer "In2.Cu")
		(net "P3E_PCH_NVS_TX_DP<0>")
	)
	(segment
		(start 345.672156 -49.078388)
		(end 345.71432 -49.120552)
		(width 0.0889)
		(layer "In2.Cu")
		(net "P3E_PCH_NVS_TX_DP<0>")
	)
	(segment
		(start 347.091 -50.70348)
		(end 346.96908 -50.8254)
		(width 0.14732)
		(layer "In2.Cu")
		(net "P3E_PCH_NVS_TX_DP<0>")
	)
	(segment
		(start 347.621606 -65.344548)
		(end 347.637862 -65.781428)
		(width 0.14732)
		(layer "In2.Cu")
		(net "P3E_PCH_NVS_TX_DP<0>")
	)
	(segment
		(start 347.091 -54.05628)
		(end 346.96908 -54.1782)
		(width 0.14732)
		(layer "In2.Cu")
		(net "P3E_PCH_NVS_TX_DP<0>")
	)
	(segment
		(start 344.094308 -50.015902)
		(end 344.016076 -49.994566)
		(width 0.0889)
		(layer "In2.Cu")
		(net "P3E_PCH_NVS_TX_DP<0>")
	)
	(segment
		(start 346.730066 -50.051716)
		(end 347.091 -50.41265)
		(width 0.14732)
		(layer "In2.Cu")
		(net "P3E_PCH_NVS_TX_DP<0>")
	)
	(segment
		(start 347.55455 -63.547498)
		(end 347.681042 -63.664846)
		(width 0.14732)
		(layer "In2.Cu")
		(net "P3E_PCH_NVS_TX_DP<0>")
	)
	(arc
		(start 344.897202 -49.141634)
		(mid 344.904942 -49.133001)
		(end 344.91295 -49.124616)
		(width 0.0889)
		(layer "In2.Cu")
		(net "P3E_PCH_NVS_TX_DP<0>")
	)
	(arc
		(start 344.853514 -49.202594)
		(mid 344.87383 -49.171019)
		(end 344.897202 -49.141634)
		(width 0.0889)
		(layer "In2.Cu")
		(net "P3E_PCH_NVS_TX_DP<0>")
	)
	(arc
		(start 344.394028 -49.484788)
		(mid 344.659574 -49.401976)
		(end 344.853514 -49.202594)
		(width 0.0889)
		(layer "In2.Cu")
		(net "P3E_PCH_NVS_TX_DP<0>")
	)
	(arc
		(start 344.016076 -49.994566)
		(mid 344.050972 -49.655796)
		(end 344.345514 -49.485042)
		(width 0.0889)
		(layer "In2.Cu")
		(net "P3E_PCH_NVS_TX_DP<0>")
	)
	(segment
		(start 98.630232 -392.984228)
		(end 98.592132 -393.36345)
		(width 0.13208)
		(layer "F.Cu")
		(net "P3E_PCH_NVS_TX_DN<1>")
	)
	(segment
		(start 98.285554 -396.408402)
		(end 98.15195 -396.517622)
		(width 0.13208)
		(layer "F.Cu")
		(net "P3E_PCH_NVS_TX_DN<1>")
	)
	(segment
		(start 98.11385 -396.89659)
		(end 98.222816 -397.030194)
		(width 0.13208)
		(layer "F.Cu")
		(net "P3E_PCH_NVS_TX_DN<1>")
	)
	(segment
		(start 98.315526 -394.894562)
		(end 98.424492 -395.028166)
		(width 0.13208)
		(layer "F.Cu")
		(net "P3E_PCH_NVS_TX_DN<1>")
	)
	(segment
		(start 97.781364 -401.413472)
		(end 97.647506 -401.522438)
		(width 0.13208)
		(layer "F.Cu")
		(net "P3E_PCH_NVS_TX_DN<1>")
	)
	(segment
		(start 97.849436 -399.520664)
		(end 97.811336 -399.899632)
		(width 0.13208)
		(layer "F.Cu")
		(net "P3E_PCH_NVS_TX_DN<1>")
	)
	(segment
		(start 98.02114 -399.032222)
		(end 97.98304 -399.411444)
		(width 0.13208)
		(layer "F.Cu")
		(net "P3E_PCH_NVS_TX_DN<1>")
	)
	(segment
		(start 98.386392 -395.407388)
		(end 98.252788 -395.516608)
		(width 0.13208)
		(layer "F.Cu")
		(net "P3E_PCH_NVS_TX_DN<1>")
	)
	(segment
		(start 98.35769 -394.47343)
		(end 98.315526 -394.894562)
		(width 0.13208)
		(layer "F.Cu")
		(net "P3E_PCH_NVS_TX_DN<1>")
	)
	(segment
		(start 97.882202 -400.412712)
		(end 97.748598 -400.521678)
		(width 0.13208)
		(layer "F.Cu")
		(net "P3E_PCH_NVS_TX_DN<1>")
	)
	(segment
		(start 98.83648 -403.338538)
		(end 98.83648 -402.93163)
		(width 0.13208)
		(layer "F.Cu")
		(net "P3E_PCH_NVS_TX_DN<1>")
	)
	(segment
		(start 293.81958 -162.100768)
		(end 293.51732 -162.403028)
		(width 0.13208)
		(layer "F.Cu")
		(net "P3E_PCH_NVS_TX_DN<1>")
	)
	(segment
		(start 212.714586 -343.987374)
		(end 181.074568 -378.23521)
		(width 0.13208)
		(layer "F.Cu")
		(net "P3E_PCH_NVS_TX_DN<1>")
	)
	(segment
		(start 98.819716 -389.877046)
		(end 98.521012 -392.850624)
		(width 0.13208)
		(layer "F.Cu")
		(net "P3E_PCH_NVS_TX_DN<1>")
	)
	(segment
		(start 284.856174 -171.978828)
		(end 253.71552 -184.87771)
		(width 0.13208)
		(layer "F.Cu")
		(net "P3E_PCH_NVS_TX_DN<1>")
	)
	(segment
		(start 98.323654 -396.02918)
		(end 98.285554 -396.408402)
		(width 0.13208)
		(layer "F.Cu")
		(net "P3E_PCH_NVS_TX_DN<1>")
	)
	(segment
		(start 168.722548 -383.29743)
		(end 100.452682 -388.24408)
		(width 0.13208)
		(layer "F.Cu")
		(net "P3E_PCH_NVS_TX_DN<1>")
	)
	(segment
		(start 97.98304 -399.411444)
		(end 97.849436 -399.520664)
		(width 0.13208)
		(layer "F.Cu")
		(net "P3E_PCH_NVS_TX_DN<1>")
	)
	(segment
		(start 173.863762 -382.54432)
		(end 170.537632 -383.29743)
		(width 0.13208)
		(layer "F.Cu")
		(net "P3E_PCH_NVS_TX_DN<1>")
	)
	(segment
		(start 246.04218 -246.35714)
		(end 246.04218 -263.630156)
		(width 0.13208)
		(layer "F.Cu")
		(net "P3E_PCH_NVS_TX_DN<1>")
	)
	(segment
		(start 98.521012 -392.850624)
		(end 98.630232 -392.984228)
		(width 0.13208)
		(layer "F.Cu")
		(net "P3E_PCH_NVS_TX_DN<1>")
	)
	(segment
		(start 170.537632 -383.29743)
		(end 168.722548 -383.29743)
		(width 0.13208)
		(layer "F.Cu")
		(net "P3E_PCH_NVS_TX_DN<1>")
	)
	(segment
		(start 100.452682 -388.24408)
		(end 98.819716 -389.877046)
		(width 0.13208)
		(layer "F.Cu")
		(net "P3E_PCH_NVS_TX_DN<1>")
	)
	(segment
		(start 98.252788 -395.516608)
		(end 98.214688 -395.895576)
		(width 0.13208)
		(layer "F.Cu")
		(net "P3E_PCH_NVS_TX_DN<1>")
	)
	(segment
		(start 97.647506 -401.522438)
		(end 97.55886 -402.405088)
		(width 0.13208)
		(layer "F.Cu")
		(net "P3E_PCH_NVS_TX_DN<1>")
	)
	(segment
		(start 293.51732 -162.403028)
		(end 293.51732 -163.317682)
		(width 0.13208)
		(layer "F.Cu")
		(net "P3E_PCH_NVS_TX_DN<1>")
	)
	(segment
		(start 244.79377 -275.223986)
		(end 212.714586 -343.987374)
		(width 0.13208)
		(layer "F.Cu")
		(net "P3E_PCH_NVS_TX_DN<1>")
	)
	(segment
		(start 97.920302 -400.033236)
		(end 97.882202 -400.412712)
		(width 0.13208)
		(layer "F.Cu")
		(net "P3E_PCH_NVS_TX_DN<1>")
	)
	(segment
		(start 181.074568 -378.23521)
		(end 173.863762 -382.54432)
		(width 0.13208)
		(layer "F.Cu")
		(net "P3E_PCH_NVS_TX_DN<1>")
	)
	(segment
		(start 98.15195 -396.517622)
		(end 98.11385 -396.89659)
		(width 0.13208)
		(layer "F.Cu")
		(net "P3E_PCH_NVS_TX_DN<1>")
	)
	(segment
		(start 97.748598 -400.521678)
		(end 97.710498 -400.900646)
		(width 0.13208)
		(layer "F.Cu")
		(net "P3E_PCH_NVS_TX_DN<1>")
	)
	(segment
		(start 246.953024 -191.640206)
		(end 245.413784 -197.113398)
		(width 0.13208)
		(layer "F.Cu")
		(net "P3E_PCH_NVS_TX_DN<1>")
	)
	(segment
		(start 97.55886 -402.405088)
		(end 97.55886 -403.052534)
		(width 0.13208)
		(layer "F.Cu")
		(net "P3E_PCH_NVS_TX_DN<1>")
	)
	(segment
		(start 253.71552 -184.87771)
		(end 246.953024 -191.640206)
		(width 0.13208)
		(layer "F.Cu")
		(net "P3E_PCH_NVS_TX_DN<1>")
	)
	(segment
		(start 98.222816 -397.030194)
		(end 98.184716 -397.409416)
		(width 0.13208)
		(layer "F.Cu")
		(net "P3E_PCH_NVS_TX_DN<1>")
	)
	(segment
		(start 97.912174 -398.898618)
		(end 98.02114 -399.032222)
		(width 0.13208)
		(layer "F.Cu")
		(net "P3E_PCH_NVS_TX_DN<1>")
	)
	(segment
		(start 97.55886 -403.052534)
		(end 97.89414 -403.387814)
		(width 0.13208)
		(layer "F.Cu")
		(net "P3E_PCH_NVS_TX_DN<1>")
	)
	(segment
		(start 97.811336 -399.899632)
		(end 97.920302 -400.033236)
		(width 0.13208)
		(layer "F.Cu")
		(net "P3E_PCH_NVS_TX_DN<1>")
	)
	(segment
		(start 98.529648 -393.984988)
		(end 98.491548 -394.364464)
		(width 0.13208)
		(layer "F.Cu")
		(net "P3E_PCH_NVS_TX_DN<1>")
	)
	(segment
		(start 98.083878 -398.41043)
		(end 97.950274 -398.51965)
		(width 0.13208)
		(layer "F.Cu")
		(net "P3E_PCH_NVS_TX_DN<1>")
	)
	(segment
		(start 98.214688 -395.895576)
		(end 98.323654 -396.02918)
		(width 0.13208)
		(layer "F.Cu")
		(net "P3E_PCH_NVS_TX_DN<1>")
	)
	(segment
		(start 98.051112 -397.518636)
		(end 98.013012 -397.897604)
		(width 0.13208)
		(layer "F.Cu")
		(net "P3E_PCH_NVS_TX_DN<1>")
	)
	(segment
		(start 98.121978 -398.031208)
		(end 98.083878 -398.41043)
		(width 0.13208)
		(layer "F.Cu")
		(net "P3E_PCH_NVS_TX_DN<1>")
	)
	(segment
		(start 97.89414 -403.387814)
		(end 98.787204 -403.387814)
		(width 0.13208)
		(layer "F.Cu")
		(net "P3E_PCH_NVS_TX_DN<1>")
	)
	(segment
		(start 98.592132 -393.36345)
		(end 98.458274 -393.47267)
		(width 0.13208)
		(layer "F.Cu")
		(net "P3E_PCH_NVS_TX_DN<1>")
	)
	(segment
		(start 293.51732 -163.317682)
		(end 284.856174 -171.978828)
		(width 0.13208)
		(layer "F.Cu")
		(net "P3E_PCH_NVS_TX_DN<1>")
	)
	(segment
		(start 245.413784 -197.113398)
		(end 246.04218 -246.35714)
		(width 0.13208)
		(layer "F.Cu")
		(net "P3E_PCH_NVS_TX_DN<1>")
	)
	(segment
		(start 344.63355 -52.209446)
		(end 344.36431 -51.739546)
		(width 0.13208)
		(layer "F.Cu")
		(net "P3E_PCH_NVS_TX_DN<1>")
	)
	(segment
		(start 98.013012 -397.897604)
		(end 98.121978 -398.031208)
		(width 0.13208)
		(layer "F.Cu")
		(net "P3E_PCH_NVS_TX_DN<1>")
	)
	(segment
		(start 98.458274 -393.47267)
		(end 98.420428 -393.851638)
		(width 0.13208)
		(layer "F.Cu")
		(net "P3E_PCH_NVS_TX_DN<1>")
	)
	(segment
		(start 98.83648 -402.93163)
		(end 98.53422 -402.62937)
		(width 0.13208)
		(layer "F.Cu")
		(net "P3E_PCH_NVS_TX_DN<1>")
	)
	(segment
		(start 246.04218 -263.630156)
		(end 244.79377 -275.223986)
		(width 0.13208)
		(layer "F.Cu")
		(net "P3E_PCH_NVS_TX_DN<1>")
	)
	(segment
		(start 97.819464 -401.033996)
		(end 97.781364 -401.413472)
		(width 0.13208)
		(layer "F.Cu")
		(net "P3E_PCH_NVS_TX_DN<1>")
	)
	(segment
		(start 98.420428 -393.851638)
		(end 98.529648 -393.984988)
		(width 0.13208)
		(layer "F.Cu")
		(net "P3E_PCH_NVS_TX_DN<1>")
	)
	(segment
		(start 98.787204 -403.387814)
		(end 98.83648 -403.338538)
		(width 0.13208)
		(layer "F.Cu")
		(net "P3E_PCH_NVS_TX_DN<1>")
	)
	(segment
		(start 98.491548 -394.364464)
		(end 98.35769 -394.47343)
		(width 0.13208)
		(layer "F.Cu")
		(net "P3E_PCH_NVS_TX_DN<1>")
	)
	(segment
		(start 97.710498 -400.900646)
		(end 97.819464 -401.033996)
		(width 0.13208)
		(layer "F.Cu")
		(net "P3E_PCH_NVS_TX_DN<1>")
	)
	(segment
		(start 98.424492 -395.028166)
		(end 98.386392 -395.407388)
		(width 0.13208)
		(layer "F.Cu")
		(net "P3E_PCH_NVS_TX_DN<1>")
	)
	(segment
		(start 97.950274 -398.51965)
		(end 97.912174 -398.898618)
		(width 0.13208)
		(layer "F.Cu")
		(net "P3E_PCH_NVS_TX_DN<1>")
	)
	(segment
		(start 98.184716 -397.409416)
		(end 98.051112 -397.518636)
		(width 0.13208)
		(layer "F.Cu")
		(net "P3E_PCH_NVS_TX_DN<1>")
	)
	(via
		(at 98.53422 -402.62937)
		(size 0.508)
		(drill 0.254)
		(layers "F.Cu" "B.Cu")
		(net "P3E_PCH_NVS_TX_DN<1>")
	)
	(segment
		(start 98.8441 -403.887686)
		(end 98.511868 -404.219918)
		(width 0.13208)
		(layer "B.Cu")
		(net "P3E_PCH_NVS_TX_DN<1>")
	)
	(segment
		(start 98.8441 -402.93925)
		(end 98.8441 -403.887686)
		(width 0.13208)
		(layer "B.Cu")
		(net "P3E_PCH_NVS_TX_DN<1>")
	)
	(segment
		(start 98.53422 -402.62937)
		(end 98.8441 -402.93925)
		(width 0.13208)
		(layer "B.Cu")
		(net "P3E_PCH_NVS_TX_DN<1>")
	)
	(segment
		(start 291.2999 -162.58794)
		(end 291.803328 -163.091368)
		(width 0.14732)
		(layer "In2.Cu")
		(net "P3E_PCH_NVS_TX_DN<1>")
	)
	(segment
		(start 293.52494 -162.717734)
		(end 293.52494 -162.395408)
		(width 0.14732)
		(layer "In2.Cu")
		(net "P3E_PCH_NVS_TX_DN<1>")
	)
	(segment
		(start 345.67622 -51.231292)
		(end 345.698318 -51.231292)
		(width 0.0889)
		(layer "In2.Cu")
		(net "P3E_PCH_NVS_TX_DN<1>")
	)
	(segment
		(start 345.05392 -68.735448)
		(end 345.112848 -70.275704)
		(width 0.14732)
		(layer "In2.Cu")
		(net "P3E_PCH_NVS_TX_DN<1>")
	)
	(segment
		(start 345.698318 -51.231292)
		(end 345.817952 -51.231292)
		(width 0.14732)
		(layer "In2.Cu")
		(net "P3E_PCH_NVS_TX_DN<1>")
	)
	(segment
		(start 342.545162 -137.360406)
		(end 342.544654 -137.36193)
		(width 0.14732)
		(layer "In2.Cu")
		(net "P3E_PCH_NVS_TX_DN<1>")
	)
	(segment
		(start 345.112848 -70.275704)
		(end 345.74099 -71.765668)
		(width 0.14732)
		(layer "In2.Cu")
		(net "P3E_PCH_NVS_TX_DN<1>")
	)
	(segment
		(start 345.944444 -51.357784)
		(end 345.944444 -56.422544)
		(width 0.14732)
		(layer "In2.Cu")
		(net "P3E_PCH_NVS_TX_DN<1>")
	)
	(segment
		(start 342.544654 -137.36193)
		(end 342.544908 -137.36193)
		(width 0.14732)
		(layer "In2.Cu")
		(net "P3E_PCH_NVS_TX_DN<1>")
	)
	(segment
		(start 342.544908 -137.36193)
		(end 340.18474 -139.722098)
		(width 0.14732)
		(layer "In2.Cu")
		(net "P3E_PCH_NVS_TX_DN<1>")
	)
	(segment
		(start 291.803328 -163.091368)
		(end 293.151306 -163.091368)
		(width 0.14732)
		(layer "In2.Cu")
		(net "P3E_PCH_NVS_TX_DN<1>")
	)
	(segment
		(start 293.151306 -163.091368)
		(end 293.52494 -162.717734)
		(width 0.14732)
		(layer "In2.Cu")
		(net "P3E_PCH_NVS_TX_DN<1>")
	)
	(segment
		(start 342.937338 -136.025382)
		(end 342.545162 -137.360406)
		(width 0.14732)
		(layer "In2.Cu")
		(net "P3E_PCH_NVS_TX_DN<1>")
	)
	(segment
		(start 344.36431 -51.739546)
		(end 344.36431 -51.420522)
		(width 0.0889)
		(layer "In2.Cu")
		(net "P3E_PCH_NVS_TX_DN<1>")
	)
	(segment
		(start 293.869618 -158.906718)
		(end 291.2999 -161.476436)
		(width 0.14732)
		(layer "In2.Cu")
		(net "P3E_PCH_NVS_TX_DN<1>")
	)
	(segment
		(start 346.42806 -58.854848)
		(end 346.42806 -60.4647)
		(width 0.14732)
		(layer "In2.Cu")
		(net "P3E_PCH_NVS_TX_DN<1>")
	)
	(segment
		(start 293.52494 -162.395408)
		(end 293.81958 -162.100768)
		(width 0.14732)
		(layer "In2.Cu")
		(net "P3E_PCH_NVS_TX_DN<1>")
	)
	(segment
		(start 345.817952 -51.231292)
		(end 345.944444 -51.357784)
		(width 0.14732)
		(layer "In2.Cu")
		(net "P3E_PCH_NVS_TX_DN<1>")
	)
	(segment
		(start 345.74099 -71.765668)
		(end 347.347286 -84.879434)
		(width 0.14732)
		(layer "In2.Cu")
		(net "P3E_PCH_NVS_TX_DN<1>")
	)
	(segment
		(start 291.2999 -161.476436)
		(end 291.2999 -162.58794)
		(width 0.14732)
		(layer "In2.Cu")
		(net "P3E_PCH_NVS_TX_DN<1>")
	)
	(segment
		(start 344.36431 -51.420522)
		(end 344.595704 -51.189128)
		(width 0.0889)
		(layer "In2.Cu")
		(net "P3E_PCH_NVS_TX_DN<1>")
	)
	(segment
		(start 345.944444 -56.422544)
		(end 346.42806 -58.854848)
		(width 0.14732)
		(layer "In2.Cu")
		(net "P3E_PCH_NVS_TX_DN<1>")
	)
	(segment
		(start 347.347286 -84.879434)
		(end 342.937338 -136.025382)
		(width 0.14732)
		(layer "In2.Cu")
		(net "P3E_PCH_NVS_TX_DN<1>")
	)
	(segment
		(start 344.595704 -51.189128)
		(end 345.634056 -51.189128)
		(width 0.0889)
		(layer "In2.Cu")
		(net "P3E_PCH_NVS_TX_DN<1>")
	)
	(segment
		(start 340.18474 -139.722098)
		(end 293.869618 -158.906718)
		(width 0.14732)
		(layer "In2.Cu")
		(net "P3E_PCH_NVS_TX_DN<1>")
	)
	(segment
		(start 346.42806 -60.4647)
		(end 345.05392 -68.735448)
		(width 0.14732)
		(layer "In2.Cu")
		(net "P3E_PCH_NVS_TX_DN<1>")
	)
	(segment
		(start 345.634056 -51.189128)
		(end 345.67622 -51.231292)
		(width 0.0889)
		(layer "In2.Cu")
		(net "P3E_PCH_NVS_TX_DN<1>")
	)
	(segment
		(start 103.103426 -409.31084)
		(end 102.8319 -409.039314)
		(width 0.13208)
		(layer "F.Cu")
		(net "P3E_PCH_NVS_TX_DN<0>")
	)
	(segment
		(start 105.077514 -397.032988)
		(end 105.74528 -395.420088)
		(width 0.13208)
		(layer "F.Cu")
		(net "P3E_PCH_NVS_TX_DN<0>")
	)
	(segment
		(start 105.07726 -397.033242)
		(end 105.077514 -397.032988)
		(width 0.13208)
		(layer "F.Cu")
		(net "P3E_PCH_NVS_TX_DN<0>")
	)
	(segment
		(start 105.07726 -405.245062)
		(end 105.07726 -397.033242)
		(width 0.13208)
		(layer "F.Cu")
		(net "P3E_PCH_NVS_TX_DN<0>")
	)
	(segment
		(start 297.69562 -161.859468)
		(end 297.99788 -161.557208)
		(width 0.13208)
		(layer "F.Cu")
		(net "P3E_PCH_NVS_TX_DN<0>")
	)
	(segment
		(start 105.74528 -392.864848)
		(end 106.490262 -392.042142)
		(width 0.13208)
		(layer "F.Cu")
		(net "P3E_PCH_NVS_TX_DN<0>")
	)
	(segment
		(start 167.085264 -387.558026)
		(end 173.156118 -385.735068)
		(width 0.13208)
		(layer "F.Cu")
		(net "P3E_PCH_NVS_TX_DN<0>")
	)
	(segment
		(start 106.490262 -392.042142)
		(end 109.192314 -390.701022)
		(width 0.13208)
		(layer "F.Cu")
		(net "P3E_PCH_NVS_TX_DN<0>")
	)
	(segment
		(start 105.74528 -395.420088)
		(end 105.74528 -392.864848)
		(width 0.13208)
		(layer "F.Cu")
		(net "P3E_PCH_NVS_TX_DN<0>")
	)
	(segment
		(start 182.738776 -380.010162)
		(end 214.652606 -345.465908)
		(width 0.13208)
		(layer "F.Cu")
		(net "P3E_PCH_NVS_TX_DN<0>")
	)
	(segment
		(start 249.117358 -192.906904)
		(end 254.97663 -187.047632)
		(width 0.13208)
		(layer "F.Cu")
		(net "P3E_PCH_NVS_TX_DN<0>")
	)
	(segment
		(start 247.345454 -275.384006)
		(end 248.46788 -264.961878)
		(width 0.13208)
		(layer "F.Cu")
		(net "P3E_PCH_NVS_TX_DN<0>")
	)
	(segment
		(start 109.192314 -390.701022)
		(end 111.496602 -390.05891)
		(width 0.13208)
		(layer "F.Cu")
		(net "P3E_PCH_NVS_TX_DN<0>")
	)
	(segment
		(start 102.8319 -407.490422)
		(end 105.07726 -405.245062)
		(width 0.13208)
		(layer "F.Cu")
		(net "P3E_PCH_NVS_TX_DN<0>")
	)
	(segment
		(start 297.69562 -165.69309)
		(end 297.69562 -161.859468)
		(width 0.13208)
		(layer "F.Cu")
		(net "P3E_PCH_NVS_TX_DN<0>")
	)
	(segment
		(start 214.652606 -345.465908)
		(end 247.345454 -275.384006)
		(width 0.13208)
		(layer "F.Cu")
		(net "P3E_PCH_NVS_TX_DN<0>")
	)
	(segment
		(start 247.844056 -197.432422)
		(end 249.117358 -192.906904)
		(width 0.13208)
		(layer "F.Cu")
		(net "P3E_PCH_NVS_TX_DN<0>")
	)
	(segment
		(start 173.156118 -385.735068)
		(end 182.738776 -380.010162)
		(width 0.13208)
		(layer "F.Cu")
		(net "P3E_PCH_NVS_TX_DN<0>")
	)
	(segment
		(start 254.97663 -187.047632)
		(end 291.447728 -171.940982)
		(width 0.13208)
		(layer "F.Cu")
		(net "P3E_PCH_NVS_TX_DN<0>")
	)
	(segment
		(start 248.46788 -246.341138)
		(end 247.844056 -197.432422)
		(width 0.13208)
		(layer "F.Cu")
		(net "P3E_PCH_NVS_TX_DN<0>")
	)
	(segment
		(start 291.447728 -171.940982)
		(end 297.69562 -165.69309)
		(width 0.13208)
		(layer "F.Cu")
		(net "P3E_PCH_NVS_TX_DN<0>")
	)
	(segment
		(start 111.496602 -390.05891)
		(end 167.085264 -387.558026)
		(width 0.13208)
		(layer "F.Cu")
		(net "P3E_PCH_NVS_TX_DN<0>")
	)
	(segment
		(start 102.8319 -409.039314)
		(end 102.8319 -407.490422)
		(width 0.13208)
		(layer "F.Cu")
		(net "P3E_PCH_NVS_TX_DN<0>")
	)
	(segment
		(start 248.46788 -264.961878)
		(end 248.46788 -246.341138)
		(width 0.13208)
		(layer "F.Cu")
		(net "P3E_PCH_NVS_TX_DN<0>")
	)
	(segment
		(start 343.81948 -50.79873)
		(end 343.81948 -50.799746)
		(width 0.13208)
		(layer "F.Cu")
		(net "P3E_PCH_NVS_TX_DN<0>")
	)
	(segment
		(start 343.550494 -50.329592)
		(end 343.81948 -50.79873)
		(width 0.13208)
		(layer "F.Cu")
		(net "P3E_PCH_NVS_TX_DN<0>")
	)
	(segment
		(start 344.3351 -49.294796)
		(end 344.364056 -49.294542)
		(width 0.0889)
		(layer "In2.Cu")
		(net "P3E_PCH_NVS_TX_DN<0>")
	)
	(segment
		(start 347.36532 -57.210198)
		(end 347.749876 -59.135264)
		(width 0.14732)
		(layer "In2.Cu")
		(net "P3E_PCH_NVS_TX_DN<0>")
	)
	(segment
		(start 343.82202 -50.173382)
		(end 343.84615 -50.083974)
		(width 0.0889)
		(layer "In2.Cu")
		(net "P3E_PCH_NVS_TX_DN<0>")
	)
	(segment
		(start 344.123264 -136.403842)
		(end 343.6493 -137.986008)
		(width 0.14732)
		(layer "In2.Cu")
		(net "P3E_PCH_NVS_TX_DN<0>")
	)
	(segment
		(start 347.36532 -50.298858)
		(end 347.36532 -57.210198)
		(width 0.14732)
		(layer "In2.Cu")
		(net "P3E_PCH_NVS_TX_DN<0>")
	)
	(segment
		(start 344.880184 -48.888142)
		(end 345.67241 -48.888142)
		(width 0.0889)
		(layer "In2.Cu")
		(net "P3E_PCH_NVS_TX_DN<0>")
	)
	(segment
		(start 345.71432 -48.846232)
		(end 345.736418 -48.846232)
		(width 0.0889)
		(layer "In2.Cu")
		(net "P3E_PCH_NVS_TX_DN<0>")
	)
	(segment
		(start 297.75658 -161.315908)
		(end 297.99788 -161.557208)
		(width 0.14732)
		(layer "In2.Cu")
		(net "P3E_PCH_NVS_TX_DN<0>")
	)
	(segment
		(start 345.736418 -48.846232)
		(end 345.912694 -48.846232)
		(width 0.14732)
		(layer "In2.Cu")
		(net "P3E_PCH_NVS_TX_DN<0>")
	)
	(segment
		(start 344.778076 -48.989996)
		(end 344.880184 -48.888142)
		(width 0.0889)
		(layer "In2.Cu")
		(net "P3E_PCH_NVS_TX_DN<0>")
	)
	(segment
		(start 348.55658 -84.94395)
		(end 344.123264 -136.403842)
		(width 0.14732)
		(layer "In2.Cu")
		(net "P3E_PCH_NVS_TX_DN<0>")
	)
	(segment
		(start 347.81871 -59.98591)
		(end 348.164404 -69.268848)
		(width 0.14732)
		(layer "In2.Cu")
		(net "P3E_PCH_NVS_TX_DN<0>")
	)
	(segment
		(start 348.164404 -69.268848)
		(end 348.69247 -70.786244)
		(width 0.14732)
		(layer "In2.Cu")
		(net "P3E_PCH_NVS_TX_DN<0>")
	)
	(segment
		(start 348.724474 -71.18223)
		(end 348.55658 -84.94395)
		(width 0.14732)
		(layer "In2.Cu")
		(net "P3E_PCH_NVS_TX_DN<0>")
	)
	(segment
		(start 348.69247 -70.786244)
		(end 348.724474 -71.18223)
		(width 0.14732)
		(layer "In2.Cu")
		(net "P3E_PCH_NVS_TX_DN<0>")
	)
	(segment
		(start 301.412148 -157.10408)
		(end 297.75658 -160.759648)
		(width 0.14732)
		(layer "In2.Cu")
		(net "P3E_PCH_NVS_TX_DN<0>")
	)
	(segment
		(start 344.364056 -49.294542)
		(end 344.383614 -49.294542)
		(width 0.0889)
		(layer "In2.Cu")
		(net "P3E_PCH_NVS_TX_DN<0>")
	)
	(segment
		(start 343.550494 -50.329592)
		(end 343.82202 -50.173382)
		(width 0.0889)
		(layer "In2.Cu")
		(net "P3E_PCH_NVS_TX_DN<0>")
	)
	(segment
		(start 345.912694 -48.846232)
		(end 347.36532 -50.298858)
		(width 0.14732)
		(layer "In2.Cu")
		(net "P3E_PCH_NVS_TX_DN<0>")
	)
	(segment
		(start 340.878922 -140.756132)
		(end 301.412148 -157.10408)
		(width 0.14732)
		(layer "In2.Cu")
		(net "P3E_PCH_NVS_TX_DN<0>")
	)
	(segment
		(start 347.749876 -59.135264)
		(end 347.81871 -59.98591)
		(width 0.14732)
		(layer "In2.Cu")
		(net "P3E_PCH_NVS_TX_DN<0>")
	)
	(segment
		(start 343.6493 -137.986008)
		(end 340.878922 -140.756132)
		(width 0.14732)
		(layer "In2.Cu")
		(net "P3E_PCH_NVS_TX_DN<0>")
	)
	(segment
		(start 297.75658 -160.759648)
		(end 297.75658 -161.315908)
		(width 0.14732)
		(layer "In2.Cu")
		(net "P3E_PCH_NVS_TX_DN<0>")
	)
	(segment
		(start 345.67241 -48.888142)
		(end 345.71432 -48.846232)
		(width 0.0889)
		(layer "In2.Cu")
		(net "P3E_PCH_NVS_TX_DN<0>")
	)
	(arc
		(start 344.383614 -49.294542)
		(mid 344.559816 -49.239509)
		(end 344.688414 -49.10709)
		(width 0.0889)
		(layer "In2.Cu")
		(net "P3E_PCH_NVS_TX_DN<0>")
	)
	(arc
		(start 344.753946 -49.015904)
		(mid 344.76581 -49.002763)
		(end 344.778076 -48.989996)
		(width 0.0889)
		(layer "In2.Cu")
		(net "P3E_PCH_NVS_TX_DN<0>")
	)
	(arc
		(start 343.84615 -50.083974)
		(mid 343.841857 -50.073729)
		(end 343.837768 -50.0634)
		(width 0.0889)
		(layer "In2.Cu")
		(net "P3E_PCH_NVS_TX_DN<0>")
	)
	(arc
		(start 343.837768 -50.0634)
		(mid 343.890734 -49.552493)
		(end 344.3351 -49.294796)
		(width 0.0889)
		(layer "In2.Cu")
		(net "P3E_PCH_NVS_TX_DN<0>")
	)
	(arc
		(start 344.688414 -49.10709)
		(mid 344.718917 -49.059871)
		(end 344.753946 -49.015904)
		(width 0.0889)
		(layer "In2.Cu")
		(net "P3E_PCH_NVS_TX_DN<0>")
	)
	(segment
		(start 96.404684 -411.856428)
		(end 97.9424 -410.385768)
		(width 0.13208)
		(layer "B.Cu")
		(net "P3E_PCH_NVS_TX_C_DP<1>")
	)
	(segment
		(start 73.871328 -414.485836)
		(end 73.979024 -414.350962)
		(width 0.13208)
		(layer "B.Cu")
		(net "P3E_PCH_NVS_TX_C_DP<1>")
	)
	(segment
		(start 74.492104 -414.416748)
		(end 74.871072 -414.374584)
		(width 0.13208)
		(layer "B.Cu")
		(net "P3E_PCH_NVS_TX_C_DP<1>")
	)
	(segment
		(start 70.177152 -419.36289)
		(end 69.991478 -419.36289)
		(width 0.13208)
		(layer "B.Cu")
		(net "P3E_PCH_NVS_TX_C_DP<1>")
	)
	(segment
		(start 73.979024 -414.350962)
		(end 74.357484 -414.309052)
		(width 0.13208)
		(layer "B.Cu")
		(net "P3E_PCH_NVS_TX_C_DP<1>")
	)
	(segment
		(start 70.93331 -415.69767)
		(end 71.822056 -414.808924)
		(width 0.13208)
		(layer "B.Cu")
		(net "P3E_PCH_NVS_TX_C_DP<1>")
	)
	(segment
		(start 69.991478 -419.36289)
		(end 69.813678 -419.18509)
		(width 0.13208)
		(layer "B.Cu")
		(net "P3E_PCH_NVS_TX_C_DP<1>")
	)
	(segment
		(start 73.35774 -414.420304)
		(end 73.49236 -414.528)
		(width 0.13208)
		(layer "B.Cu")
		(net "P3E_PCH_NVS_TX_C_DP<1>")
	)
	(segment
		(start 70.93331 -415.869882)
		(end 70.93331 -415.69767)
		(width 0.13208)
		(layer "B.Cu")
		(net "P3E_PCH_NVS_TX_C_DP<1>")
	)
	(segment
		(start 99.08032 -406.500584)
		(end 99.08032 -405.092916)
		(width 0.13208)
		(layer "B.Cu")
		(net "P3E_PCH_NVS_TX_C_DP<1>")
	)
	(segment
		(start 69.813678 -416.817048)
		(end 70.491096 -416.13963)
		(width 0.13208)
		(layer "B.Cu")
		(net "P3E_PCH_NVS_TX_C_DP<1>")
	)
	(segment
		(start 71.822056 -414.808924)
		(end 72.411336 -414.52546)
		(width 0.13208)
		(layer "B.Cu")
		(net "P3E_PCH_NVS_TX_C_DP<1>")
	)
	(segment
		(start 70.6501 -418.889942)
		(end 70.177152 -419.36289)
		(width 0.13208)
		(layer "B.Cu")
		(net "P3E_PCH_NVS_TX_C_DP<1>")
	)
	(segment
		(start 70.491096 -416.13963)
		(end 70.663562 -416.13963)
		(width 0.13208)
		(layer "B.Cu")
		(net "P3E_PCH_NVS_TX_C_DP<1>")
	)
	(segment
		(start 69.813678 -419.18509)
		(end 69.813678 -416.817048)
		(width 0.13208)
		(layer "B.Cu")
		(net "P3E_PCH_NVS_TX_C_DP<1>")
	)
	(segment
		(start 73.49236 -414.528)
		(end 73.871328 -414.485836)
		(width 0.13208)
		(layer "B.Cu")
		(net "P3E_PCH_NVS_TX_C_DP<1>")
	)
	(segment
		(start 97.9424 -410.385768)
		(end 99.08032 -406.500584)
		(width 0.13208)
		(layer "B.Cu")
		(net "P3E_PCH_NVS_TX_C_DP<1>")
	)
	(segment
		(start 99.08032 -405.092916)
		(end 99.419918 -404.753318)
		(width 0.13208)
		(layer "B.Cu")
		(net "P3E_PCH_NVS_TX_C_DP<1>")
	)
	(segment
		(start 74.978768 -414.23971)
		(end 96.404684 -411.856428)
		(width 0.13208)
		(layer "B.Cu")
		(net "P3E_PCH_NVS_TX_C_DP<1>")
	)
	(segment
		(start 70.663562 -416.13963)
		(end 70.93331 -415.869882)
		(width 0.13208)
		(layer "B.Cu")
		(net "P3E_PCH_NVS_TX_C_DP<1>")
	)
	(segment
		(start 74.357484 -414.309052)
		(end 74.492104 -414.416748)
		(width 0.13208)
		(layer "B.Cu")
		(net "P3E_PCH_NVS_TX_C_DP<1>")
	)
	(segment
		(start 72.411336 -414.52546)
		(end 73.35774 -414.420304)
		(width 0.13208)
		(layer "B.Cu")
		(net "P3E_PCH_NVS_TX_C_DP<1>")
	)
	(segment
		(start 74.871072 -414.374584)
		(end 74.978768 -414.23971)
		(width 0.13208)
		(layer "B.Cu")
		(net "P3E_PCH_NVS_TX_C_DP<1>")
	)
	(segment
		(start 102.56012 -410.097986)
		(end 102.56012 -410.911548)
		(width 0.13208)
		(layer "F.Cu")
		(net "P3E_PCH_NVS_TX_C_DP<0>")
	)
	(segment
		(start 102.306374 -409.84424)
		(end 102.56012 -410.097986)
		(width 0.13208)
		(layer "F.Cu")
		(net "P3E_PCH_NVS_TX_C_DP<0>")
	)
	(segment
		(start 102.56012 -410.911548)
		(end 102.25786 -411.213808)
		(width 0.13208)
		(layer "F.Cu")
		(net "P3E_PCH_NVS_TX_C_DP<0>")
	)
	(segment
		(start 95.929704 -412.487364)
		(end 96.552766 -411.864302)
		(width 0.14732)
		(layer "In15.Cu")
		(net "P3E_PCH_NVS_TX_C_DP<0>")
	)
	(segment
		(start 73.063354 -420.303198)
		(end 74.91095 -420.303198)
		(width 0.14732)
		(layer "In15.Cu")
		(net "P3E_PCH_NVS_TX_C_DP<0>")
	)
	(segment
		(start 93.64218 -414.774888)
		(end 94.406466 -414.010602)
		(width 0.14732)
		(layer "In15.Cu")
		(net "P3E_PCH_NVS_TX_C_DP<0>")
	)
	(segment
		(start 92.21343 -414.630108)
		(end 92.58173 -414.630108)
		(width 0.14732)
		(layer "In15.Cu")
		(net "P3E_PCH_NVS_TX_C_DP<0>")
	)
	(segment
		(start 96.552766 -411.864302)
		(end 102.40518 -411.864302)
		(width 0.14732)
		(layer "In15.Cu")
		(net "P3E_PCH_NVS_TX_C_DP<0>")
	)
	(segment
		(start 94.871794 -413.545274)
		(end 95.464376 -412.952692)
		(width 0.14732)
		(layer "In15.Cu")
		(net "P3E_PCH_NVS_TX_C_DP<0>")
	)
	(segment
		(start 92.72651 -414.774888)
		(end 93.64218 -414.774888)
		(width 0.14732)
		(layer "In15.Cu")
		(net "P3E_PCH_NVS_TX_C_DP<0>")
	)
	(segment
		(start 92.06865 -414.774888)
		(end 92.21343 -414.630108)
		(width 0.14732)
		(layer "In15.Cu")
		(net "P3E_PCH_NVS_TX_C_DP<0>")
	)
	(segment
		(start 95.464376 -412.952692)
		(end 95.464376 -412.747968)
		(width 0.14732)
		(layer "In15.Cu")
		(net "P3E_PCH_NVS_TX_C_DP<0>")
	)
	(segment
		(start 95.72498 -412.487364)
		(end 95.929704 -412.487364)
		(width 0.14732)
		(layer "In15.Cu")
		(net "P3E_PCH_NVS_TX_C_DP<0>")
	)
	(segment
		(start 74.91095 -420.303198)
		(end 80.43926 -414.774888)
		(width 0.14732)
		(layer "In15.Cu")
		(net "P3E_PCH_NVS_TX_C_DP<0>")
	)
	(segment
		(start 80.43926 -414.774888)
		(end 92.06865 -414.774888)
		(width 0.14732)
		(layer "In15.Cu")
		(net "P3E_PCH_NVS_TX_C_DP<0>")
	)
	(segment
		(start 94.406466 -413.805878)
		(end 94.66707 -413.545274)
		(width 0.14732)
		(layer "In15.Cu")
		(net "P3E_PCH_NVS_TX_C_DP<0>")
	)
	(segment
		(start 102.5525 -411.508448)
		(end 102.25786 -411.213808)
		(width 0.14732)
		(layer "In15.Cu")
		(net "P3E_PCH_NVS_TX_C_DP<0>")
	)
	(segment
		(start 102.5525 -411.716982)
		(end 102.5525 -411.508448)
		(width 0.14732)
		(layer "In15.Cu")
		(net "P3E_PCH_NVS_TX_C_DP<0>")
	)
	(segment
		(start 95.464376 -412.747968)
		(end 95.72498 -412.487364)
		(width 0.14732)
		(layer "In15.Cu")
		(net "P3E_PCH_NVS_TX_C_DP<0>")
	)
	(segment
		(start 92.58173 -414.630108)
		(end 92.72651 -414.774888)
		(width 0.14732)
		(layer "In15.Cu")
		(net "P3E_PCH_NVS_TX_C_DP<0>")
	)
	(segment
		(start 102.40518 -411.864302)
		(end 102.5525 -411.716982)
		(width 0.14732)
		(layer "In15.Cu")
		(net "P3E_PCH_NVS_TX_C_DP<0>")
	)
	(segment
		(start 94.66707 -413.545274)
		(end 94.871794 -413.545274)
		(width 0.14732)
		(layer "In15.Cu")
		(net "P3E_PCH_NVS_TX_C_DP<0>")
	)
	(segment
		(start 94.406466 -414.010602)
		(end 94.406466 -413.805878)
		(width 0.14732)
		(layer "In15.Cu")
		(net "P3E_PCH_NVS_TX_C_DP<0>")
	)
	(segment
		(start 72.650096 -419.88994)
		(end 73.063354 -420.303198)
		(width 0.14732)
		(layer "In15.Cu")
		(net "P3E_PCH_NVS_TX_C_DP<0>")
	)
	(segment
		(start 71.66991 -414.594548)
		(end 71.66991 -414.594294)
		(width 0.13208)
		(layer "B.Cu")
		(net "P3E_PCH_NVS_TX_C_DN<1>")
	)
	(segment
		(start 70.6501 -420.089838)
		(end 70.182232 -419.62197)
		(width 0.13208)
		(layer "B.Cu")
		(net "P3E_PCH_NVS_TX_C_DN<1>")
	)
	(segment
		(start 69.554598 -416.709606)
		(end 71.66991 -414.594548)
		(width 0.13208)
		(layer "B.Cu")
		(net "P3E_PCH_NVS_TX_C_DN<1>")
	)
	(segment
		(start 96.28886 -411.608524)
		(end 97.713038 -410.246322)
		(width 0.13208)
		(layer "B.Cu")
		(net "P3E_PCH_NVS_TX_C_DN<1>")
	)
	(segment
		(start 72.338946 -414.27273)
		(end 72.338692 -414.27273)
		(width 0.13208)
		(layer "B.Cu")
		(net "P3E_PCH_NVS_TX_C_DN<1>")
	)
	(segment
		(start 69.884036 -419.62197)
		(end 69.554598 -419.292532)
		(width 0.13208)
		(layer "B.Cu")
		(net "P3E_PCH_NVS_TX_C_DN<1>")
	)
	(segment
		(start 97.713038 -410.246322)
		(end 98.82124 -406.463246)
		(width 0.13208)
		(layer "B.Cu")
		(net "P3E_PCH_NVS_TX_C_DN<1>")
	)
	(segment
		(start 98.82124 -405.06269)
		(end 98.511868 -404.753318)
		(width 0.13208)
		(layer "B.Cu")
		(net "P3E_PCH_NVS_TX_C_DN<1>")
	)
	(segment
		(start 70.182232 -419.62197)
		(end 69.884036 -419.62197)
		(width 0.13208)
		(layer "B.Cu")
		(net "P3E_PCH_NVS_TX_C_DN<1>")
	)
	(segment
		(start 98.82124 -406.463246)
		(end 98.82124 -405.06269)
		(width 0.13208)
		(layer "B.Cu")
		(net "P3E_PCH_NVS_TX_C_DN<1>")
	)
	(segment
		(start 69.554598 -419.292532)
		(end 69.554598 -416.709606)
		(width 0.13208)
		(layer "B.Cu")
		(net "P3E_PCH_NVS_TX_C_DN<1>")
	)
	(segment
		(start 72.338692 -414.27273)
		(end 96.28886 -411.608524)
		(width 0.13208)
		(layer "B.Cu")
		(net "P3E_PCH_NVS_TX_C_DN<1>")
	)
	(segment
		(start 71.66991 -414.594294)
		(end 72.338946 -414.27273)
		(width 0.13208)
		(layer "B.Cu")
		(net "P3E_PCH_NVS_TX_C_DN<1>")
	)
	(segment
		(start 102.8192 -410.911548)
		(end 103.12146 -411.213808)
		(width 0.13208)
		(layer "F.Cu")
		(net "P3E_PCH_NVS_TX_C_DN<0>")
	)
	(segment
		(start 103.103426 -409.84424)
		(end 102.8192 -410.128466)
		(width 0.13208)
		(layer "F.Cu")
		(net "P3E_PCH_NVS_TX_C_DN<0>")
	)
	(segment
		(start 102.8192 -410.128466)
		(end 102.8192 -410.911548)
		(width 0.13208)
		(layer "F.Cu")
		(net "P3E_PCH_NVS_TX_C_DN<0>")
	)
	(segment
		(start 102.82682 -411.508448)
		(end 103.12146 -411.213808)
		(width 0.14732)
		(layer "In15.Cu")
		(net "P3E_PCH_NVS_TX_C_DN<0>")
	)
	(segment
		(start 80.553052 -415.049208)
		(end 93.755972 -415.049208)
		(width 0.14732)
		(layer "In15.Cu")
		(net "P3E_PCH_NVS_TX_C_DN<0>")
	)
	(segment
		(start 96.666558 -412.138622)
		(end 102.518972 -412.138622)
		(width 0.14732)
		(layer "In15.Cu")
		(net "P3E_PCH_NVS_TX_C_DN<0>")
	)
	(segment
		(start 102.82682 -411.830774)
		(end 102.82682 -411.508448)
		(width 0.14732)
		(layer "In15.Cu")
		(net "P3E_PCH_NVS_TX_C_DN<0>")
	)
	(segment
		(start 72.650096 -421.089582)
		(end 73.11263 -420.627048)
		(width 0.14732)
		(layer "In15.Cu")
		(net "P3E_PCH_NVS_TX_C_DN<0>")
	)
	(segment
		(start 102.518972 -412.138622)
		(end 102.82682 -411.830774)
		(width 0.14732)
		(layer "In15.Cu")
		(net "P3E_PCH_NVS_TX_C_DN<0>")
	)
	(segment
		(start 93.755972 -415.049208)
		(end 96.666558 -412.138622)
		(width 0.14732)
		(layer "In15.Cu")
		(net "P3E_PCH_NVS_TX_C_DN<0>")
	)
	(segment
		(start 73.11263 -420.627048)
		(end 74.975212 -420.627048)
		(width 0.14732)
		(layer "In15.Cu")
		(net "P3E_PCH_NVS_TX_C_DN<0>")
	)
	(segment
		(start 72.650096 -421.089836)
		(end 72.650096 -421.089582)
		(width 0.14732)
		(layer "In15.Cu")
		(net "P3E_PCH_NVS_TX_C_DN<0>")
	)
	(segment
		(start 74.975212 -420.627048)
		(end 80.553052 -415.049208)
		(width 0.14732)
		(layer "In15.Cu")
		(net "P3E_PCH_NVS_TX_C_DN<0>")
	)
	(segment
		(start 352.960432 -54.981094)
		(end 352.875596 -54.981094)
		(width 0.0889)
		(layer "F.Cu")
		(net "P3E_PCH_NVS_RX_DP<1>")
	)
	(segment
		(start 101.098604 -400.83486)
		(end 101.018594 -400.451828)
		(width 0.13208)
		(layer "F.Cu")
		(net "P3E_PCH_NVS_RX_DP<1>")
	)
	(segment
		(start 101.00437 -400.979132)
		(end 101.098604 -400.83486)
		(width 0.13208)
		(layer "F.Cu")
		(net "P3E_PCH_NVS_RX_DP<1>")
	)
	(segment
		(start 356.223316 -60.162948)
		(end 356.100126 -60.039758)
		(width 0.13208)
		(layer "F.Cu")
		(net "P3E_PCH_NVS_RX_DP<1>")
	)
	(segment
		(start 354.378514 -56.442356)
		(end 354.097844 -56.16194)
		(width 0.13208)
		(layer "F.Cu")
		(net "P3E_PCH_NVS_RX_DP<1>")
	)
	(segment
		(start 350.070674 -54.571392)
		(end 349.892874 -54.571392)
		(width 0.0889)
		(layer "F.Cu")
		(net "P3E_PCH_NVS_RX_DP<1>")
	)
	(segment
		(start 287.682178 -172.215556)
		(end 295.67378 -164.223954)
		(width 0.13208)
		(layer "F.Cu")
		(net "P3E_PCH_NVS_RX_DP<1>")
	)
	(segment
		(start 247.2436 -246.34317)
		(end 246.61749 -197.27164)
		(width 0.13208)
		(layer "F.Cu")
		(net "P3E_PCH_NVS_RX_DP<1>")
	)
	(segment
		(start 295.67378 -163.398708)
		(end 295.97604 -163.096448)
		(width 0.13208)
		(layer "F.Cu")
		(net "P3E_PCH_NVS_RX_DP<1>")
	)
	(segment
		(start 350.751394 -54.639718)
		(end 350.586548 -54.571392)
		(width 0.0889)
		(layer "F.Cu")
		(net "P3E_PCH_NVS_RX_DP<1>")
	)
	(segment
		(start 348.409514 -54.571392)
		(end 348.231714 -54.571392)
		(width 0.0889)
		(layer "F.Cu")
		(net "P3E_PCH_NVS_RX_DP<1>")
	)
	(segment
		(start 349.062294 -54.670452)
		(end 348.963234 -54.571392)
		(width 0.0889)
		(layer "F.Cu")
		(net "P3E_PCH_NVS_RX_DP<1>")
	)
	(segment
		(start 352.050096 -55.080154)
		(end 351.785936 -55.080154)
		(width 0.0889)
		(layer "F.Cu")
		(net "P3E_PCH_NVS_RX_DP<1>")
	)
	(segment
		(start 356.223316 -58.301636)
		(end 356.089966 -57.979818)
		(width 0.13208)
		(layer "F.Cu")
		(net "P3E_PCH_NVS_RX_DP<1>")
	)
	(segment
		(start 354.552504 -56.442356)
		(end 354.378514 -56.442356)
		(width 0.13208)
		(layer "F.Cu")
		(net "P3E_PCH_NVS_RX_DP<1>")
	)
	(segment
		(start 348.686374 -54.670452)
		(end 348.508574 -54.670452)
		(width 0.0889)
		(layer "F.Cu")
		(net "P3E_PCH_NVS_RX_DP<1>")
	)
	(segment
		(start 181.873906 -379.141482)
		(end 197.799452 -361.90301)
		(width 0.13208)
		(layer "F.Cu")
		(net "P3E_PCH_NVS_RX_DP<1>")
	)
	(segment
		(start 354.832666 -56.896762)
		(end 354.832666 -56.722518)
		(width 0.13208)
		(layer "F.Cu")
		(net "P3E_PCH_NVS_RX_DP<1>")
	)
	(segment
		(start 101.424232 -402.988272)
		(end 101.51872 -402.844)
		(width 0.13208)
		(layer "F.Cu")
		(net "P3E_PCH_NVS_RX_DP<1>")
	)
	(segment
		(start 254.057912 -186.234832)
		(end 254.418084 -185.994294)
		(width 0.13208)
		(layer "F.Cu")
		(net "P3E_PCH_NVS_RX_DP<1>")
	)
	(segment
		(start 351.181924 -54.928008)
		(end 350.993964 -54.850284)
		(width 0.0889)
		(layer "F.Cu")
		(net "P3E_PCH_NVS_RX_DP<1>")
	)
	(segment
		(start 170.597322 -384.49631)
		(end 174.323248 -383.652522)
		(width 0.13208)
		(layer "F.Cu")
		(net "P3E_PCH_NVS_RX_DP<1>")
	)
	(segment
		(start 197.799706 -361.902756)
		(end 213.727284 -344.662506)
		(width 0.13208)
		(layer "F.Cu")
		(net "P3E_PCH_NVS_RX_DP<1>")
	)
	(segment
		(start 101.308662 -401.83943)
		(end 101.228652 -401.456398)
		(width 0.13208)
		(layer "F.Cu")
		(net "P3E_PCH_NVS_RX_DP<1>")
	)
	(segment
		(start 349.516954 -54.571392)
		(end 349.339154 -54.571392)
		(width 0.0889)
		(layer "F.Cu")
		(net "P3E_PCH_NVS_RX_DP<1>")
	)
	(segment
		(start 355.113336 -57.177178)
		(end 354.832666 -56.896762)
		(width 0.13208)
		(layer "F.Cu")
		(net "P3E_PCH_NVS_RX_DP<1>")
	)
	(segment
		(start 101.504242 -403.37105)
		(end 101.424232 -402.988272)
		(width 0.13208)
		(layer "F.Cu")
		(net "P3E_PCH_NVS_RX_DP<1>")
	)
	(segment
		(start 101.648768 -403.465538)
		(end 101.504242 -403.37105)
		(width 0.13208)
		(layer "F.Cu")
		(net "P3E_PCH_NVS_RX_DP<1>")
	)
	(segment
		(start 356.022148 -57.912)
		(end 355.848158 -57.912)
		(width 0.13208)
		(layer "F.Cu")
		(net "P3E_PCH_NVS_RX_DP<1>")
	)
	(segment
		(start 351.785936 -55.080154)
		(end 351.686876 -54.981094)
		(width 0.0889)
		(layer "F.Cu")
		(net "P3E_PCH_NVS_RX_DP<1>")
	)
	(segment
		(start 102.35946 -404.62962)
		(end 101.943916 -404.62962)
		(width 0.13208)
		(layer "F.Cu")
		(net "P3E_PCH_NVS_RX_DP<1>")
	)
	(segment
		(start 349.616014 -54.670452)
		(end 349.516954 -54.571392)
		(width 0.0889)
		(layer "F.Cu")
		(net "P3E_PCH_NVS_RX_DP<1>")
	)
	(segment
		(start 101.729032 -403.84857)
		(end 101.648768 -403.465538)
		(width 0.13208)
		(layer "F.Cu")
		(net "P3E_PCH_NVS_RX_DP<1>")
	)
	(segment
		(start 347.85554 -54.571138)
		(end 347.755718 -54.571138)
		(width 0.0889)
		(layer "F.Cu")
		(net "P3E_PCH_NVS_RX_DP<1>")
	)
	(segment
		(start 356.100126 -58.604658)
		(end 356.223316 -58.481468)
		(width 0.13208)
		(layer "F.Cu")
		(net "P3E_PCH_NVS_RX_DP<1>")
	)
	(segment
		(start 346.831666 -54.422548)
		(end 346.799662 -54.453028)
		(width 0.0889)
		(layer "F.Cu")
		(net "P3E_PCH_NVS_RX_DP<1>")
	)
	(segment
		(start 348.508574 -54.670452)
		(end 348.409514 -54.571392)
		(width 0.0889)
		(layer "F.Cu")
		(net "P3E_PCH_NVS_RX_DP<1>")
	)
	(segment
		(start 174.323248 -383.652522)
		(end 181.873906 -379.141482)
		(width 0.13208)
		(layer "F.Cu")
		(net "P3E_PCH_NVS_RX_DP<1>")
	)
	(segment
		(start 100.00742 -392.247374)
		(end 100.00742 -390.385046)
		(width 0.13208)
		(layer "F.Cu")
		(net "P3E_PCH_NVS_RX_DP<1>")
	)
	(segment
		(start 356.100126 -59.643518)
		(end 356.223316 -59.520328)
		(width 0.13208)
		(layer "F.Cu")
		(net "P3E_PCH_NVS_RX_DP<1>")
	)
	(segment
		(start 356.100126 -59.000898)
		(end 356.100126 -58.604658)
		(width 0.13208)
		(layer "F.Cu")
		(net "P3E_PCH_NVS_RX_DP<1>")
	)
	(segment
		(start 101.228652 -401.456398)
		(end 101.084126 -401.36191)
		(width 0.13208)
		(layer "F.Cu")
		(net "P3E_PCH_NVS_RX_DP<1>")
	)
	(segment
		(start 248.22658 -192.066164)
		(end 254.057912 -186.234832)
		(width 0.13208)
		(layer "F.Cu")
		(net "P3E_PCH_NVS_RX_DP<1>")
	)
	(segment
		(start 348.963234 -54.571392)
		(end 348.785434 -54.571392)
		(width 0.0889)
		(layer "F.Cu")
		(net "P3E_PCH_NVS_RX_DP<1>")
	)
	(segment
		(start 347.755718 -54.571138)
		(end 347.390212 -54.419754)
		(width 0.0889)
		(layer "F.Cu")
		(net "P3E_PCH_NVS_RX_DP<1>")
	)
	(segment
		(start 353.477576 -55.31866)
		(end 353.267264 -55.108348)
		(width 0.0889)
		(layer "F.Cu")
		(net "P3E_PCH_NVS_RX_DP<1>")
	)
	(segment
		(start 247.947942 -192.54216)
		(end 248.22658 -192.066164)
		(width 0.13208)
		(layer "F.Cu")
		(net "P3E_PCH_NVS_RX_DP<1>")
	)
	(segment
		(start 352.149156 -54.981094)
		(end 352.050096 -55.080154)
		(width 0.0889)
		(layer "F.Cu")
		(net "P3E_PCH_NVS_RX_DP<1>")
	)
	(segment
		(start 355.969316 -61.195966)
		(end 356.223316 -60.941966)
		(width 0.13208)
		(layer "F.Cu")
		(net "P3E_PCH_NVS_RX_DP<1>")
	)
	(segment
		(start 349.240094 -54.670452)
		(end 349.062294 -54.670452)
		(width 0.0889)
		(layer "F.Cu")
		(net "P3E_PCH_NVS_RX_DP<1>")
	)
	(segment
		(start 101.720904 -404.406354)
		(end 101.634544 -403.992842)
		(width 0.13208)
		(layer "F.Cu")
		(net "P3E_PCH_NVS_RX_DP<1>")
	)
	(segment
		(start 347.071696 -54.419754)
		(end 347.068902 -54.422548)
		(width 0.0889)
		(layer "F.Cu")
		(net "P3E_PCH_NVS_RX_DP<1>")
	)
	(segment
		(start 168.765982 -384.49631)
		(end 170.597322 -384.49631)
		(width 0.13208)
		(layer "F.Cu")
		(net "P3E_PCH_NVS_RX_DP<1>")
	)
	(segment
		(start 350.9391 -54.717442)
		(end 350.751394 -54.639718)
		(width 0.0889)
		(layer "F.Cu")
		(net "P3E_PCH_NVS_RX_DP<1>")
	)
	(segment
		(start 350.347534 -54.670452)
		(end 350.169734 -54.670452)
		(width 0.0889)
		(layer "F.Cu")
		(net "P3E_PCH_NVS_RX_DP<1>")
	)
	(segment
		(start 100.00742 -390.385046)
		(end 100.984812 -389.407654)
		(width 0.13208)
		(layer "F.Cu")
		(net "P3E_PCH_NVS_RX_DP<1>")
	)
	(segment
		(start 101.084126 -401.36191)
		(end 101.00437 -400.979132)
		(width 0.13208)
		(layer "F.Cu")
		(net "P3E_PCH_NVS_RX_DP<1>")
	)
	(segment
		(start 353.267264 -55.108348)
		(end 352.960432 -54.981094)
		(width 0.0889)
		(layer "F.Cu")
		(net "P3E_PCH_NVS_RX_DP<1>")
	)
	(segment
		(start 348.132654 -54.670452)
		(end 347.954854 -54.670452)
		(width 0.0889)
		(layer "F.Cu")
		(net "P3E_PCH_NVS_RX_DP<1>")
	)
	(segment
		(start 101.214174 -401.983702)
		(end 101.308662 -401.83943)
		(width 0.13208)
		(layer "F.Cu")
		(net "P3E_PCH_NVS_RX_DP<1>")
	)
	(segment
		(start 102.62362 -404.36546)
		(end 102.35946 -404.62962)
		(width 0.13208)
		(layer "F.Cu")
		(net "P3E_PCH_NVS_RX_DP<1>")
	)
	(segment
		(start 247.2436 -265.126724)
		(end 247.2436 -246.34317)
		(width 0.13208)
		(layer "F.Cu")
		(net "P3E_PCH_NVS_RX_DP<1>")
	)
	(segment
		(start 101.51872 -402.844)
		(end 101.43871 -402.460968)
		(width 0.13208)
		(layer "F.Cu")
		(net "P3E_PCH_NVS_RX_DP<1>")
	)
	(segment
		(start 347.068902 -54.422548)
		(end 346.831666 -54.422548)
		(width 0.0889)
		(layer "F.Cu")
		(net "P3E_PCH_NVS_RX_DP<1>")
	)
	(segment
		(start 351.314766 -54.873144)
		(end 351.181924 -54.928008)
		(width 0.0889)
		(layer "F.Cu")
		(net "P3E_PCH_NVS_RX_DP<1>")
	)
	(segment
		(start 351.686876 -54.981094)
		(end 351.575624 -54.981094)
		(width 0.0889)
		(layer "F.Cu")
		(net "P3E_PCH_NVS_RX_DP<1>")
	)
	(segment
		(start 246.61749 -197.27164)
		(end 247.947942 -192.54216)
		(width 0.13208)
		(layer "F.Cu")
		(net "P3E_PCH_NVS_RX_DP<1>")
	)
	(segment
		(start 352.776536 -55.080154)
		(end 352.512376 -55.080154)
		(width 0.0889)
		(layer "F.Cu")
		(net "P3E_PCH_NVS_RX_DP<1>")
	)
	(segment
		(start 352.512376 -55.080154)
		(end 352.413316 -54.981094)
		(width 0.0889)
		(layer "F.Cu")
		(net "P3E_PCH_NVS_RX_DP<1>")
	)
	(segment
		(start 213.727284 -344.662506)
		(end 246.166894 -275.124672)
		(width 0.13208)
		(layer "F.Cu")
		(net "P3E_PCH_NVS_RX_DP<1>")
	)
	(segment
		(start 101.294184 -402.36648)
		(end 101.214174 -401.983702)
		(width 0.13208)
		(layer "F.Cu")
		(net "P3E_PCH_NVS_RX_DP<1>")
	)
	(segment
		(start 355.85019 -61.195966)
		(end 355.969316 -61.195966)
		(width 0.13208)
		(layer "F.Cu")
		(net "P3E_PCH_NVS_RX_DP<1>")
	)
	(segment
		(start 354.097844 -56.16194)
		(end 354.097844 -55.987696)
		(width 0.13208)
		(layer "F.Cu")
		(net "P3E_PCH_NVS_RX_DP<1>")
	)
	(segment
		(start 351.575624 -54.981094)
		(end 351.314766 -54.873144)
		(width 0.0889)
		(layer "F.Cu")
		(net "P3E_PCH_NVS_RX_DP<1>")
	)
	(segment
		(start 350.169734 -54.670452)
		(end 350.070674 -54.571392)
		(width 0.0889)
		(layer "F.Cu")
		(net "P3E_PCH_NVS_RX_DP<1>")
	)
	(segment
		(start 100.984812 -389.407654)
		(end 168.765982 -384.49631)
		(width 0.13208)
		(layer "F.Cu")
		(net "P3E_PCH_NVS_RX_DP<1>")
	)
	(segment
		(start 254.418084 -185.994294)
		(end 287.682178 -172.215556)
		(width 0.13208)
		(layer "F.Cu")
		(net "P3E_PCH_NVS_RX_DP<1>")
	)
	(segment
		(start 355.567488 -57.45734)
		(end 355.287326 -57.177178)
		(width 0.13208)
		(layer "F.Cu")
		(net "P3E_PCH_NVS_RX_DP<1>")
	)
	(segment
		(start 356.223316 -60.941966)
		(end 356.223316 -60.162948)
		(width 0.13208)
		(layer "F.Cu")
		(net "P3E_PCH_NVS_RX_DP<1>")
	)
	(segment
		(start 352.875596 -54.981094)
		(end 352.776536 -55.080154)
		(width 0.0889)
		(layer "F.Cu")
		(net "P3E_PCH_NVS_RX_DP<1>")
	)
	(segment
		(start 355.567488 -57.631584)
		(end 355.567488 -57.45734)
		(width 0.13208)
		(layer "F.Cu")
		(net "P3E_PCH_NVS_RX_DP<1>")
	)
	(segment
		(start 355.287326 -57.177178)
		(end 355.113336 -57.177178)
		(width 0.13208)
		(layer "F.Cu")
		(net "P3E_PCH_NVS_RX_DP<1>")
	)
	(segment
		(start 356.100126 -60.039758)
		(end 356.100126 -59.643518)
		(width 0.13208)
		(layer "F.Cu")
		(net "P3E_PCH_NVS_RX_DP<1>")
	)
	(segment
		(start 246.166894 -275.124672)
		(end 247.2436 -265.126724)
		(width 0.13208)
		(layer "F.Cu")
		(net "P3E_PCH_NVS_RX_DP<1>")
	)
	(segment
		(start 349.793814 -54.670452)
		(end 349.616014 -54.670452)
		(width 0.0889)
		(layer "F.Cu")
		(net "P3E_PCH_NVS_RX_DP<1>")
	)
	(segment
		(start 356.089966 -57.979818)
		(end 356.022148 -57.912)
		(width 0.13208)
		(layer "F.Cu")
		(net "P3E_PCH_NVS_RX_DP<1>")
	)
	(segment
		(start 355.848158 -57.912)
		(end 355.567488 -57.631584)
		(width 0.13208)
		(layer "F.Cu")
		(net "P3E_PCH_NVS_RX_DP<1>")
	)
	(segment
		(start 356.223316 -59.124088)
		(end 356.100126 -59.000898)
		(width 0.13208)
		(layer "F.Cu")
		(net "P3E_PCH_NVS_RX_DP<1>")
	)
	(segment
		(start 100.355654 -397.875252)
		(end 100.00742 -392.247374)
		(width 0.13208)
		(layer "F.Cu")
		(net "P3E_PCH_NVS_RX_DP<1>")
	)
	(segment
		(start 349.339154 -54.571392)
		(end 349.240094 -54.670452)
		(width 0.0889)
		(layer "F.Cu")
		(net "P3E_PCH_NVS_RX_DP<1>")
	)
	(segment
		(start 356.223316 -59.520328)
		(end 356.223316 -59.124088)
		(width 0.13208)
		(layer "F.Cu")
		(net "P3E_PCH_NVS_RX_DP<1>")
	)
	(segment
		(start 350.586548 -54.571392)
		(end 350.446594 -54.571392)
		(width 0.0889)
		(layer "F.Cu")
		(net "P3E_PCH_NVS_RX_DP<1>")
	)
	(segment
		(start 353.49307 -55.382922)
		(end 353.477576 -55.367428)
		(width 0.0889)
		(layer "F.Cu")
		(net "P3E_PCH_NVS_RX_DP<1>")
	)
	(segment
		(start 354.832666 -56.722518)
		(end 354.552504 -56.442356)
		(width 0.13208)
		(layer "F.Cu")
		(net "P3E_PCH_NVS_RX_DP<1>")
	)
	(segment
		(start 353.477576 -55.367428)
		(end 353.477576 -55.31866)
		(width 0.0889)
		(layer "F.Cu")
		(net "P3E_PCH_NVS_RX_DP<1>")
	)
	(segment
		(start 356.223316 -58.481468)
		(end 356.223316 -58.301636)
		(width 0.13208)
		(layer "F.Cu")
		(net "P3E_PCH_NVS_RX_DP<1>")
	)
	(segment
		(start 295.67378 -164.223954)
		(end 295.67378 -163.398708)
		(width 0.13208)
		(layer "F.Cu")
		(net "P3E_PCH_NVS_RX_DP<1>")
	)
	(segment
		(start 350.993964 -54.850284)
		(end 350.9391 -54.717442)
		(width 0.0889)
		(layer "F.Cu")
		(net "P3E_PCH_NVS_RX_DP<1>")
	)
	(segment
		(start 101.43871 -402.460968)
		(end 101.294184 -402.36648)
		(width 0.13208)
		(layer "F.Cu")
		(net "P3E_PCH_NVS_RX_DP<1>")
	)
	(segment
		(start 348.231714 -54.571392)
		(end 348.132654 -54.670452)
		(width 0.0889)
		(layer "F.Cu")
		(net "P3E_PCH_NVS_RX_DP<1>")
	)
	(segment
		(start 101.018594 -400.451828)
		(end 100.874068 -400.35734)
		(width 0.13208)
		(layer "F.Cu")
		(net "P3E_PCH_NVS_RX_DP<1>")
	)
	(segment
		(start 350.446594 -54.571392)
		(end 350.347534 -54.670452)
		(width 0.0889)
		(layer "F.Cu")
		(net "P3E_PCH_NVS_RX_DP<1>")
	)
	(segment
		(start 347.954854 -54.670452)
		(end 347.85554 -54.571138)
		(width 0.0889)
		(layer "F.Cu")
		(net "P3E_PCH_NVS_RX_DP<1>")
	)
	(segment
		(start 354.097844 -55.987696)
		(end 353.49307 -55.382922)
		(width 0.13208)
		(layer "F.Cu")
		(net "P3E_PCH_NVS_RX_DP<1>")
	)
	(segment
		(start 101.634544 -403.992842)
		(end 101.729032 -403.84857)
		(width 0.13208)
		(layer "F.Cu")
		(net "P3E_PCH_NVS_RX_DP<1>")
	)
	(segment
		(start 348.785434 -54.571392)
		(end 348.686374 -54.670452)
		(width 0.0889)
		(layer "F.Cu")
		(net "P3E_PCH_NVS_RX_DP<1>")
	)
	(segment
		(start 349.892874 -54.571392)
		(end 349.793814 -54.670452)
		(width 0.0889)
		(layer "F.Cu")
		(net "P3E_PCH_NVS_RX_DP<1>")
	)
	(segment
		(start 352.413316 -54.981094)
		(end 352.149156 -54.981094)
		(width 0.0889)
		(layer "F.Cu")
		(net "P3E_PCH_NVS_RX_DP<1>")
	)
	(segment
		(start 197.799452 -361.90301)
		(end 197.799706 -361.902756)
		(width 0.13208)
		(layer "F.Cu")
		(net "P3E_PCH_NVS_RX_DP<1>")
	)
	(segment
		(start 101.943916 -404.62962)
		(end 101.720904 -404.406354)
		(width 0.13208)
		(layer "F.Cu")
		(net "P3E_PCH_NVS_RX_DP<1>")
	)
	(segment
		(start 347.390212 -54.419754)
		(end 347.071696 -54.419754)
		(width 0.0889)
		(layer "F.Cu")
		(net "P3E_PCH_NVS_RX_DP<1>")
	)
	(segment
		(start 100.874068 -400.35734)
		(end 100.355654 -397.875252)
		(width 0.13208)
		(layer "F.Cu")
		(net "P3E_PCH_NVS_RX_DP<1>")
	)
	(via
		(at 102.62362 -404.36546)
		(size 0.508)
		(drill 0.254)
		(layers "F.Cu" "B.Cu")
		(net "P3E_PCH_NVS_RX_DP<1>")
	)
	(segment
		(start 100.13823 -406.413462)
		(end 100.138484 -406.4127)
		(width 0.13208)
		(layer "B.Cu")
		(net "P3E_PCH_NVS_RX_DP<1>")
	)
	(segment
		(start 71.51116 -422.752774)
		(end 71.51116 -416.98418)
		(width 0.13208)
		(layer "B.Cu")
		(net "P3E_PCH_NVS_RX_DP<1>")
	)
	(segment
		(start 72.710548 -415.784284)
		(end 96.381062 -413.151828)
		(width 0.13208)
		(layer "B.Cu")
		(net "P3E_PCH_NVS_RX_DP<1>")
	)
	(segment
		(start 101.524054 -404.66264)
		(end 102.32644 -404.66264)
		(width 0.13208)
		(layer "B.Cu")
		(net "P3E_PCH_NVS_RX_DP<1>")
	)
	(segment
		(start 100.138484 -406.4127)
		(end 100.28936 -405.897334)
		(width 0.13208)
		(layer "B.Cu")
		(net "P3E_PCH_NVS_RX_DP<1>")
	)
	(segment
		(start 98.858578 -410.782262)
		(end 100.13823 -406.413462)
		(width 0.13208)
		(layer "B.Cu")
		(net "P3E_PCH_NVS_RX_DP<1>")
	)
	(segment
		(start 71.51116 -416.98418)
		(end 72.710548 -415.784284)
		(width 0.13208)
		(layer "B.Cu")
		(net "P3E_PCH_NVS_RX_DP<1>")
	)
	(segment
		(start 71.117968 -422.957752)
		(end 71.306182 -422.957752)
		(width 0.13208)
		(layer "B.Cu")
		(net "P3E_PCH_NVS_RX_DP<1>")
	)
	(segment
		(start 102.32644 -404.66264)
		(end 102.62362 -404.36546)
		(width 0.13208)
		(layer "B.Cu")
		(net "P3E_PCH_NVS_RX_DP<1>")
	)
	(segment
		(start 70.6501 -422.489884)
		(end 71.117968 -422.957752)
		(width 0.13208)
		(layer "B.Cu")
		(net "P3E_PCH_NVS_RX_DP<1>")
	)
	(segment
		(start 71.306182 -422.957752)
		(end 71.51116 -422.752774)
		(width 0.13208)
		(layer "B.Cu")
		(net "P3E_PCH_NVS_RX_DP<1>")
	)
	(segment
		(start 96.381062 -413.151828)
		(end 98.858578 -410.782262)
		(width 0.13208)
		(layer "B.Cu")
		(net "P3E_PCH_NVS_RX_DP<1>")
	)
	(segment
		(start 100.28936 -405.897334)
		(end 101.524054 -404.66264)
		(width 0.13208)
		(layer "B.Cu")
		(net "P3E_PCH_NVS_RX_DP<1>")
	)
	(segment
		(start 346.577158 -123.052078)
		(end 346.41409 -123.176284)
		(width 0.14732)
		(layer "In2.Cu")
		(net "P3E_PCH_NVS_RX_DP<1>")
	)
	(segment
		(start 346.365576 -123.54179)
		(end 346.490036 -123.70435)
		(width 0.14732)
		(layer "In2.Cu")
		(net "P3E_PCH_NVS_RX_DP<1>")
	)
	(segment
		(start 346.541598 -122.21972)
		(end 346.666058 -122.38228)
		(width 0.14732)
		(layer "In2.Cu")
		(net "P3E_PCH_NVS_RX_DP<1>")
	)
	(segment
		(start 353.478592 -71.160132)
		(end 346.93733 -120.338596)
		(width 0.14732)
		(layer "In2.Cu")
		(net "P3E_PCH_NVS_RX_DP<1>")
	)
	(segment
		(start 346.304108 -125.098556)
		(end 346.1131 -126.53518)
		(width 0.14732)
		(layer "In2.Cu")
		(net "P3E_PCH_NVS_RX_DP<1>")
	)
	(segment
		(start 346.179902 -124.93625)
		(end 346.304108 -125.098556)
		(width 0.14732)
		(layer "In2.Cu")
		(net "P3E_PCH_NVS_RX_DP<1>")
	)
	(segment
		(start 346.938346 -120.338596)
		(end 346.775532 -120.463056)
		(width 0.14732)
		(layer "In2.Cu")
		(net "P3E_PCH_NVS_RX_DP<1>")
	)
	(segment
		(start 346.851478 -120.991122)
		(end 346.850462 -120.991122)
		(width 0.14732)
		(layer "In2.Cu")
		(net "P3E_PCH_NVS_RX_DP<1>")
	)
	(segment
		(start 356.14483 -61.490606)
		(end 356.14483 -62.153292)
		(width 0.14732)
		(layer "In2.Cu")
		(net "P3E_PCH_NVS_RX_DP<1>")
	)
	(segment
		(start 346.775532 -120.463056)
		(end 346.727018 -120.828308)
		(width 0.14732)
		(layer "In2.Cu")
		(net "P3E_PCH_NVS_RX_DP<1>")
	)
	(segment
		(start 356.14483 -62.153292)
		(end 353.478592 -71.160132)
		(width 0.14732)
		(layer "In2.Cu")
		(net "P3E_PCH_NVS_RX_DP<1>")
	)
	(segment
		(start 346.112846 -126.535942)
		(end 346.113354 -126.535942)
		(width 0.14732)
		(layer "In2.Cu")
		(net "P3E_PCH_NVS_RX_DP<1>")
	)
	(segment
		(start 346.391484 -124.446538)
		(end 346.228416 -124.570744)
		(width 0.14732)
		(layer "In2.Cu")
		(net "P3E_PCH_NVS_RX_DP<1>")
	)
	(segment
		(start 345.595194 -130.429508)
		(end 345.492578 -131.20116)
		(width 0.14732)
		(layer "In2.Cu")
		(net "P3E_PCH_NVS_RX_DP<1>")
	)
	(segment
		(start 341.253318 -141.321536)
		(end 304.007774 -156.749242)
		(width 0.14732)
		(layer "In2.Cu")
		(net "P3E_PCH_NVS_RX_DP<1>")
	)
	(segment
		(start 346.66555 -122.38228)
		(end 346.57665 -123.052078)
		(width 0.14732)
		(layer "In2.Cu")
		(net "P3E_PCH_NVS_RX_DP<1>")
	)
	(segment
		(start 345.66352 -128.818386)
		(end 345.787726 -128.980692)
		(width 0.14732)
		(layer "In2.Cu")
		(net "P3E_PCH_NVS_RX_DP<1>")
	)
	(segment
		(start 346.850462 -120.991122)
		(end 346.752164 -121.730008)
		(width 0.14732)
		(layer "In2.Cu")
		(net "P3E_PCH_NVS_RX_DP<1>")
	)
	(segment
		(start 346.666058 -122.38228)
		(end 346.66555 -122.38228)
		(width 0.14732)
		(layer "In2.Cu")
		(net "P3E_PCH_NVS_RX_DP<1>")
	)
	(segment
		(start 355.85019 -61.195966)
		(end 356.14483 -61.490606)
		(width 0.14732)
		(layer "In2.Cu")
		(net "P3E_PCH_NVS_RX_DP<1>")
	)
	(segment
		(start 304.007774 -156.749242)
		(end 299.440346 -161.31667)
		(width 0.14732)
		(layer "In2.Cu")
		(net "P3E_PCH_NVS_RX_DP<1>")
	)
	(segment
		(start 346.1131 -126.53518)
		(end 346.112846 -126.535942)
		(width 0.14732)
		(layer "In2.Cu")
		(net "P3E_PCH_NVS_RX_DP<1>")
	)
	(segment
		(start 345.874594 -128.32842)
		(end 345.87434 -128.328674)
		(width 0.14732)
		(layer "In2.Cu")
		(net "P3E_PCH_NVS_RX_DP<1>")
	)
	(segment
		(start 345.28125 -131.690872)
		(end 345.40571 -131.853432)
		(width 0.14732)
		(layer "In2.Cu")
		(net "P3E_PCH_NVS_RX_DP<1>")
	)
	(segment
		(start 295.82872 -163.746942)
		(end 295.6814 -163.599622)
		(width 0.14732)
		(layer "In2.Cu")
		(net "P3E_PCH_NVS_RX_DP<1>")
	)
	(segment
		(start 346.590366 -121.854214)
		(end 346.541598 -122.21972)
		(width 0.14732)
		(layer "In2.Cu")
		(net "P3E_PCH_NVS_RX_DP<1>")
	)
	(segment
		(start 346.228416 -124.570744)
		(end 346.179902 -124.93625)
		(width 0.14732)
		(layer "In2.Cu")
		(net "P3E_PCH_NVS_RX_DP<1>")
	)
	(segment
		(start 295.6814 -163.391088)
		(end 295.97604 -163.096448)
		(width 0.14732)
		(layer "In2.Cu")
		(net "P3E_PCH_NVS_RX_DP<1>")
	)
	(segment
		(start 345.681554 -129.777236)
		(end 345.682062 -129.777236)
		(width 0.14732)
		(layer "In2.Cu")
		(net "P3E_PCH_NVS_RX_DP<1>")
	)
	(segment
		(start 345.40571 -131.853432)
		(end 344.781886 -136.54405)
		(width 0.14732)
		(layer "In2.Cu")
		(net "P3E_PCH_NVS_RX_DP<1>")
	)
	(segment
		(start 345.329764 -131.32562)
		(end 345.28125 -131.690872)
		(width 0.14732)
		(layer "In2.Cu")
		(net "P3E_PCH_NVS_RX_DP<1>")
	)
	(segment
		(start 346.026486 -127.188468)
		(end 346.025978 -127.188468)
		(width 0.14732)
		(layer "In2.Cu")
		(net "P3E_PCH_NVS_RX_DP<1>")
	)
	(segment
		(start 346.752164 -121.730008)
		(end 346.75318 -121.730008)
		(width 0.14732)
		(layer "In2.Cu")
		(net "P3E_PCH_NVS_RX_DP<1>")
	)
	(segment
		(start 299.440346 -161.31667)
		(end 298.791884 -162.882072)
		(width 0.14732)
		(layer "In2.Cu")
		(net "P3E_PCH_NVS_RX_DP<1>")
	)
	(segment
		(start 345.87434 -128.328674)
		(end 345.874848 -128.328674)
		(width 0.14732)
		(layer "In2.Cu")
		(net "P3E_PCH_NVS_RX_DP<1>")
	)
	(segment
		(start 346.390976 -124.44603)
		(end 346.390722 -124.446538)
		(width 0.14732)
		(layer "In2.Cu")
		(net "P3E_PCH_NVS_RX_DP<1>")
	)
	(segment
		(start 346.41409 -123.176284)
		(end 346.365576 -123.54179)
		(width 0.14732)
		(layer "In2.Cu")
		(net "P3E_PCH_NVS_RX_DP<1>")
	)
	(segment
		(start 346.93733 -120.338596)
		(end 346.938346 -120.338596)
		(width 0.14732)
		(layer "In2.Cu")
		(net "P3E_PCH_NVS_RX_DP<1>")
	)
	(segment
		(start 345.902026 -127.025654)
		(end 346.026486 -127.188468)
		(width 0.14732)
		(layer "In2.Cu")
		(net "P3E_PCH_NVS_RX_DP<1>")
	)
	(segment
		(start 346.727018 -120.828308)
		(end 346.851478 -120.991122)
		(width 0.14732)
		(layer "In2.Cu")
		(net "P3E_PCH_NVS_RX_DP<1>")
	)
	(segment
		(start 295.6814 -163.599622)
		(end 295.6814 -163.391088)
		(width 0.14732)
		(layer "In2.Cu")
		(net "P3E_PCH_NVS_RX_DP<1>")
	)
	(segment
		(start 298.521374 -163.152582)
		(end 297.086528 -163.746942)
		(width 0.14732)
		(layer "In2.Cu")
		(net "P3E_PCH_NVS_RX_DP<1>")
	)
	(segment
		(start 344.781886 -136.54405)
		(end 344.231214 -138.34364)
		(width 0.14732)
		(layer "In2.Cu")
		(net "P3E_PCH_NVS_RX_DP<1>")
	)
	(segment
		(start 346.57665 -123.052078)
		(end 346.577158 -123.052078)
		(width 0.14732)
		(layer "In2.Cu")
		(net "P3E_PCH_NVS_RX_DP<1>")
	)
	(segment
		(start 297.086528 -163.746942)
		(end 295.82872 -163.746942)
		(width 0.14732)
		(layer "In2.Cu")
		(net "P3E_PCH_NVS_RX_DP<1>")
	)
	(segment
		(start 346.75318 -121.730008)
		(end 346.590366 -121.854214)
		(width 0.14732)
		(layer "In2.Cu")
		(net "P3E_PCH_NVS_RX_DP<1>")
	)
	(segment
		(start 345.492578 -131.20116)
		(end 345.329764 -131.32562)
		(width 0.14732)
		(layer "In2.Cu")
		(net "P3E_PCH_NVS_RX_DP<1>")
	)
	(segment
		(start 344.231214 -138.34364)
		(end 341.253318 -141.321536)
		(width 0.14732)
		(layer "In2.Cu")
		(net "P3E_PCH_NVS_RX_DP<1>")
	)
	(segment
		(start 346.390722 -124.446538)
		(end 346.391484 -124.446538)
		(width 0.14732)
		(layer "In2.Cu")
		(net "P3E_PCH_NVS_RX_DP<1>")
	)
	(segment
		(start 346.025978 -127.188468)
		(end 345.874594 -128.32842)
		(width 0.14732)
		(layer "In2.Cu")
		(net "P3E_PCH_NVS_RX_DP<1>")
	)
	(segment
		(start 345.682062 -129.777236)
		(end 345.519248 -129.901696)
		(width 0.14732)
		(layer "In2.Cu")
		(net "P3E_PCH_NVS_RX_DP<1>")
	)
	(segment
		(start 345.470734 -130.266948)
		(end 345.595194 -130.429508)
		(width 0.14732)
		(layer "In2.Cu")
		(net "P3E_PCH_NVS_RX_DP<1>")
	)
	(segment
		(start 298.791884 -162.882072)
		(end 298.521374 -163.152582)
		(width 0.14732)
		(layer "In2.Cu")
		(net "P3E_PCH_NVS_RX_DP<1>")
	)
	(segment
		(start 345.874848 -128.328674)
		(end 345.712034 -128.45288)
		(width 0.14732)
		(layer "In2.Cu")
		(net "P3E_PCH_NVS_RX_DP<1>")
	)
	(segment
		(start 345.95054 -126.660402)
		(end 345.902026 -127.025654)
		(width 0.14732)
		(layer "In2.Cu")
		(net "P3E_PCH_NVS_RX_DP<1>")
	)
	(segment
		(start 345.712034 -128.45288)
		(end 345.66352 -128.818386)
		(width 0.14732)
		(layer "In2.Cu")
		(net "P3E_PCH_NVS_RX_DP<1>")
	)
	(segment
		(start 345.519248 -129.901696)
		(end 345.470734 -130.266948)
		(width 0.14732)
		(layer "In2.Cu")
		(net "P3E_PCH_NVS_RX_DP<1>")
	)
	(segment
		(start 346.490036 -123.70435)
		(end 346.489528 -123.70435)
		(width 0.14732)
		(layer "In2.Cu")
		(net "P3E_PCH_NVS_RX_DP<1>")
	)
	(segment
		(start 345.787726 -128.980692)
		(end 345.681554 -129.777236)
		(width 0.14732)
		(layer "In2.Cu")
		(net "P3E_PCH_NVS_RX_DP<1>")
	)
	(segment
		(start 346.489528 -123.70435)
		(end 346.390976 -124.44603)
		(width 0.14732)
		(layer "In2.Cu")
		(net "P3E_PCH_NVS_RX_DP<1>")
	)
	(segment
		(start 346.113354 -126.535942)
		(end 345.95054 -126.660402)
		(width 0.14732)
		(layer "In2.Cu")
		(net "P3E_PCH_NVS_RX_DP<1>")
	)
	(segment
		(start 173.770544 -386.766308)
		(end 166.568628 -388.929118)
		(width 0.13208)
		(layer "F.Cu")
		(net "P3E_PCH_NVS_RX_DP<0>")
	)
	(segment
		(start 351.269046 -54.088792)
		(end 351.172526 -54.185312)
		(width 0.0889)
		(layer "F.Cu")
		(net "P3E_PCH_NVS_RX_DP<0>")
	)
	(segment
		(start 113.477802 -391.31748)
		(end 112.27054 -392.028426)
		(width 0.13208)
		(layer "F.Cu")
		(net "P3E_PCH_NVS_RX_DP<0>")
	)
	(segment
		(start 356.636574 -56.860948)
		(end 355.055932 -55.280306)
		(width 0.13208)
		(layer "F.Cu")
		(net "P3E_PCH_NVS_RX_DP<0>")
	)
	(segment
		(start 350.623886 -54.185312)
		(end 350.446086 -54.185312)
		(width 0.0889)
		(layer "F.Cu")
		(net "P3E_PCH_NVS_RX_DP<0>")
	)
	(segment
		(start 350.349566 -54.088792)
		(end 350.171766 -54.088792)
		(width 0.0889)
		(layer "F.Cu")
		(net "P3E_PCH_NVS_RX_DP<0>")
	)
	(segment
		(start 111.46028 -393.344908)
		(end 111.46028 -395.617192)
		(width 0.13208)
		(layer "F.Cu")
		(net "P3E_PCH_NVS_RX_DP<0>")
	)
	(segment
		(start 351.172526 -54.185312)
		(end 350.994726 -54.185312)
		(width 0.0889)
		(layer "F.Cu")
		(net "P3E_PCH_NVS_RX_DP<0>")
	)
	(segment
		(start 249.81408 -246.332248)
		(end 249.81408 -263.603232)
		(width 0.13208)
		(layer "F.Cu")
		(net "P3E_PCH_NVS_RX_DP<0>")
	)
	(segment
		(start 250.317254 -193.610992)
		(end 249.192796 -197.610222)
		(width 0.13208)
		(layer "F.Cu")
		(net "P3E_PCH_NVS_RX_DP<0>")
	)
	(segment
		(start 350.720406 -54.088792)
		(end 350.623886 -54.185312)
		(width 0.0889)
		(layer "F.Cu")
		(net "P3E_PCH_NVS_RX_DP<0>")
	)
	(segment
		(start 351.543366 -54.185312)
		(end 351.446846 -54.088792)
		(width 0.0889)
		(layer "F.Cu")
		(net "P3E_PCH_NVS_RX_DP<0>")
	)
	(segment
		(start 358.34828 -55.884572)
		(end 358.04602 -56.186832)
		(width 0.13208)
		(layer "F.Cu")
		(net "P3E_PCH_NVS_RX_DP<0>")
	)
	(segment
		(start 111.46028 -395.617192)
		(end 111.234728 -396.162276)
		(width 0.13208)
		(layer "F.Cu")
		(net "P3E_PCH_NVS_RX_DP<0>")
	)
	(segment
		(start 301.13478 -164.01161)
		(end 292.266116 -172.880274)
		(width 0.13208)
		(layer "F.Cu")
		(net "P3E_PCH_NVS_RX_DP<0>")
	)
	(segment
		(start 350.994726 -54.185312)
		(end 350.898206 -54.088792)
		(width 0.0889)
		(layer "F.Cu")
		(net "P3E_PCH_NVS_RX_DP<0>")
	)
	(segment
		(start 349.897446 -54.185312)
		(end 349.800926 -54.088792)
		(width 0.0889)
		(layer "F.Cu")
		(net "P3E_PCH_NVS_RX_DP<0>")
	)
	(segment
		(start 348.977966 -54.185312)
		(end 348.800166 -54.185312)
		(width 0.0889)
		(layer "F.Cu")
		(net "P3E_PCH_NVS_RX_DP<0>")
	)
	(segment
		(start 355.040438 -55.264812)
		(end 355.040438 -55.216044)
		(width 0.0889)
		(layer "F.Cu")
		(net "P3E_PCH_NVS_RX_DP<0>")
	)
	(segment
		(start 110.653576 -396.743428)
		(end 107.09402 -398.217898)
		(width 0.13208)
		(layer "F.Cu")
		(net "P3E_PCH_NVS_RX_DP<0>")
	)
	(segment
		(start 355.055932 -55.280306)
		(end 355.040438 -55.264812)
		(width 0.0889)
		(layer "F.Cu")
		(net "P3E_PCH_NVS_RX_DP<0>")
	)
	(segment
		(start 348.525846 -54.088792)
		(end 348.426786 -54.187852)
		(width 0.0889)
		(layer "F.Cu")
		(net "P3E_PCH_NVS_RX_DP<0>")
	)
	(segment
		(start 358.04602 -56.70423)
		(end 357.889302 -56.860948)
		(width 0.13208)
		(layer "F.Cu")
		(net "P3E_PCH_NVS_RX_DP<0>")
	)
	(segment
		(start 349.074486 -54.088792)
		(end 348.977966 -54.185312)
		(width 0.0889)
		(layer "F.Cu")
		(net "P3E_PCH_NVS_RX_DP<0>")
	)
	(segment
		(start 348.703646 -54.088792)
		(end 348.525846 -54.088792)
		(width 0.0889)
		(layer "F.Cu")
		(net "P3E_PCH_NVS_RX_DP<0>")
	)
	(segment
		(start 348.426786 -54.187852)
		(end 348.248986 -54.187852)
		(width 0.0889)
		(layer "F.Cu")
		(net "P3E_PCH_NVS_RX_DP<0>")
	)
	(segment
		(start 249.192796 -197.610222)
		(end 249.81408 -246.332248)
		(width 0.13208)
		(layer "F.Cu")
		(net "P3E_PCH_NVS_RX_DP<0>")
	)
	(segment
		(start 347.726 -54.088792)
		(end 347.59011 -53.952902)
		(width 0.0889)
		(layer "F.Cu")
		(net "P3E_PCH_NVS_RX_DP<0>")
	)
	(segment
		(start 349.526606 -54.185312)
		(end 349.348806 -54.185312)
		(width 0.0889)
		(layer "F.Cu")
		(net "P3E_PCH_NVS_RX_DP<0>")
	)
	(segment
		(start 256.044192 -187.884054)
		(end 250.317254 -193.610992)
		(width 0.13208)
		(layer "F.Cu")
		(net "P3E_PCH_NVS_RX_DP<0>")
	)
	(segment
		(start 107.16768 -406.791668)
		(end 107.48772 -407.111708)
		(width 0.13208)
		(layer "F.Cu")
		(net "P3E_PCH_NVS_RX_DP<0>")
	)
	(segment
		(start 350.898206 -54.088792)
		(end 350.720406 -54.088792)
		(width 0.0889)
		(layer "F.Cu")
		(net "P3E_PCH_NVS_RX_DP<0>")
	)
	(segment
		(start 111.234728 -396.162276)
		(end 110.653576 -396.743428)
		(width 0.13208)
		(layer "F.Cu")
		(net "P3E_PCH_NVS_RX_DP<0>")
	)
	(segment
		(start 183.945784 -380.687834)
		(end 173.770544 -386.766308)
		(width 0.13208)
		(layer "F.Cu")
		(net "P3E_PCH_NVS_RX_DP<0>")
	)
	(segment
		(start 107.09402 -398.217898)
		(end 106.83113 -398.480788)
		(width 0.13208)
		(layer "F.Cu")
		(net "P3E_PCH_NVS_RX_DP<0>")
	)
	(segment
		(start 248.515632 -275.660866)
		(end 215.407494 -346.633038)
		(width 0.13208)
		(layer "F.Cu")
		(net "P3E_PCH_NVS_RX_DP<0>")
	)
	(segment
		(start 351.446846 -54.088792)
		(end 351.269046 -54.088792)
		(width 0.0889)
		(layer "F.Cu")
		(net "P3E_PCH_NVS_RX_DP<0>")
	)
	(segment
		(start 249.81408 -263.603232)
		(end 248.515632 -275.660866)
		(width 0.13208)
		(layer "F.Cu")
		(net "P3E_PCH_NVS_RX_DP<0>")
	)
	(segment
		(start 353.913186 -54.088792)
		(end 351.817686 -54.088792)
		(width 0.0889)
		(layer "F.Cu")
		(net "P3E_PCH_NVS_RX_DP<0>")
	)
	(segment
		(start 106.83113 -404.59025)
		(end 107.16768 -404.9268)
		(width 0.13208)
		(layer "F.Cu")
		(net "P3E_PCH_NVS_RX_DP<0>")
	)
	(segment
		(start 348.149926 -54.088792)
		(end 347.726 -54.088792)
		(width 0.0889)
		(layer "F.Cu")
		(net "P3E_PCH_NVS_RX_DP<0>")
	)
	(segment
		(start 348.248986 -54.187852)
		(end 348.149926 -54.088792)
		(width 0.0889)
		(layer "F.Cu")
		(net "P3E_PCH_NVS_RX_DP<0>")
	)
	(segment
		(start 350.446086 -54.185312)
		(end 350.349566 -54.088792)
		(width 0.0889)
		(layer "F.Cu")
		(net "P3E_PCH_NVS_RX_DP<0>")
	)
	(segment
		(start 350.075246 -54.185312)
		(end 349.897446 -54.185312)
		(width 0.0889)
		(layer "F.Cu")
		(net "P3E_PCH_NVS_RX_DP<0>")
	)
	(segment
		(start 351.721166 -54.185312)
		(end 351.543366 -54.185312)
		(width 0.0889)
		(layer "F.Cu")
		(net "P3E_PCH_NVS_RX_DP<0>")
	)
	(segment
		(start 301.43704 -163.083748)
		(end 301.13478 -163.386008)
		(width 0.13208)
		(layer "F.Cu")
		(net "P3E_PCH_NVS_RX_DP<0>")
	)
	(segment
		(start 106.83113 -398.480788)
		(end 106.83113 -404.59025)
		(width 0.13208)
		(layer "F.Cu")
		(net "P3E_PCH_NVS_RX_DP<0>")
	)
	(segment
		(start 292.266116 -172.880274)
		(end 256.044192 -187.884054)
		(width 0.13208)
		(layer "F.Cu")
		(net "P3E_PCH_NVS_RX_DP<0>")
	)
	(segment
		(start 349.800926 -54.088792)
		(end 349.623126 -54.088792)
		(width 0.0889)
		(layer "F.Cu")
		(net "P3E_PCH_NVS_RX_DP<0>")
	)
	(segment
		(start 215.407494 -346.633038)
		(end 183.945784 -380.687834)
		(width 0.13208)
		(layer "F.Cu")
		(net "P3E_PCH_NVS_RX_DP<0>")
	)
	(segment
		(start 347.59011 -53.952902)
		(end 347.214698 -53.952902)
		(width 0.0889)
		(layer "F.Cu")
		(net "P3E_PCH_NVS_RX_DP<0>")
	)
	(segment
		(start 349.348806 -54.185312)
		(end 349.252286 -54.088792)
		(width 0.0889)
		(layer "F.Cu")
		(net "P3E_PCH_NVS_RX_DP<0>")
	)
	(segment
		(start 357.889302 -56.860948)
		(end 356.636574 -56.860948)
		(width 0.13208)
		(layer "F.Cu")
		(net "P3E_PCH_NVS_RX_DP<0>")
	)
	(segment
		(start 301.13478 -163.386008)
		(end 301.13478 -164.01161)
		(width 0.13208)
		(layer "F.Cu")
		(net "P3E_PCH_NVS_RX_DP<0>")
	)
	(segment
		(start 349.252286 -54.088792)
		(end 349.074486 -54.088792)
		(width 0.0889)
		(layer "F.Cu")
		(net "P3E_PCH_NVS_RX_DP<0>")
	)
	(segment
		(start 166.568628 -388.929118)
		(end 113.477802 -391.31748)
		(width 0.13208)
		(layer "F.Cu")
		(net "P3E_PCH_NVS_RX_DP<0>")
	)
	(segment
		(start 351.817686 -54.088792)
		(end 351.721166 -54.185312)
		(width 0.0889)
		(layer "F.Cu")
		(net "P3E_PCH_NVS_RX_DP<0>")
	)
	(segment
		(start 358.04602 -56.186832)
		(end 358.04602 -56.70423)
		(width 0.13208)
		(layer "F.Cu")
		(net "P3E_PCH_NVS_RX_DP<0>")
	)
	(segment
		(start 112.27054 -392.028426)
		(end 111.46028 -393.344908)
		(width 0.13208)
		(layer "F.Cu")
		(net "P3E_PCH_NVS_RX_DP<0>")
	)
	(segment
		(start 349.623126 -54.088792)
		(end 349.526606 -54.185312)
		(width 0.0889)
		(layer "F.Cu")
		(net "P3E_PCH_NVS_RX_DP<0>")
	)
	(segment
		(start 355.040438 -55.216044)
		(end 353.913186 -54.088792)
		(width 0.0889)
		(layer "F.Cu")
		(net "P3E_PCH_NVS_RX_DP<0>")
	)
	(segment
		(start 350.171766 -54.088792)
		(end 350.075246 -54.185312)
		(width 0.0889)
		(layer "F.Cu")
		(net "P3E_PCH_NVS_RX_DP<0>")
	)
	(segment
		(start 348.800166 -54.185312)
		(end 348.703646 -54.088792)
		(width 0.0889)
		(layer "F.Cu")
		(net "P3E_PCH_NVS_RX_DP<0>")
	)
	(segment
		(start 107.16768 -404.9268)
		(end 107.16768 -406.791668)
		(width 0.13208)
		(layer "F.Cu")
		(net "P3E_PCH_NVS_RX_DP<0>")
	)
	(segment
		(start 301.12208 -161.668968)
		(end 301.12208 -162.768788)
		(width 0.14732)
		(layer "In2.Cu")
		(net "P3E_PCH_NVS_RX_DP<0>")
	)
	(segment
		(start 305.145948 -157.6451)
		(end 301.12208 -161.668968)
		(width 0.14732)
		(layer "In2.Cu")
		(net "P3E_PCH_NVS_RX_DP<0>")
	)
	(segment
		(start 341.832184 -142.449296)
		(end 305.145948 -157.6451)
		(width 0.14732)
		(layer "In2.Cu")
		(net "P3E_PCH_NVS_RX_DP<0>")
	)
	(segment
		(start 358.05364 -62.427358)
		(end 346.00896 -136.718548)
		(width 0.14732)
		(layer "In2.Cu")
		(net "P3E_PCH_NVS_RX_DP<0>")
	)
	(segment
		(start 345.37015 -138.91133)
		(end 341.832184 -142.449296)
		(width 0.14732)
		(layer "In2.Cu")
		(net "P3E_PCH_NVS_RX_DP<0>")
	)
	(segment
		(start 358.05364 -56.179212)
		(end 358.05364 -62.427358)
		(width 0.14732)
		(layer "In2.Cu")
		(net "P3E_PCH_NVS_RX_DP<0>")
	)
	(segment
		(start 301.12208 -162.768788)
		(end 301.43704 -163.083748)
		(width 0.14732)
		(layer "In2.Cu")
		(net "P3E_PCH_NVS_RX_DP<0>")
	)
	(segment
		(start 346.00896 -136.718548)
		(end 345.37015 -138.91133)
		(width 0.14732)
		(layer "In2.Cu")
		(net "P3E_PCH_NVS_RX_DP<0>")
	)
	(segment
		(start 358.34828 -55.884572)
		(end 358.05364 -56.179212)
		(width 0.14732)
		(layer "In2.Cu")
		(net "P3E_PCH_NVS_RX_DP<0>")
	)
	(segment
		(start 73.063354 -423.90314)
		(end 73.668128 -423.90314)
		(width 0.14732)
		(layer "In15.Cu")
		(net "P3E_PCH_NVS_RX_DP<0>")
	)
	(segment
		(start 94.00286 -416.410648)
		(end 97.50552 -412.907988)
		(width 0.14732)
		(layer "In15.Cu")
		(net "P3E_PCH_NVS_RX_DP<0>")
	)
	(segment
		(start 105.48366 -406.052528)
		(end 105.87228 -405.663908)
		(width 0.14732)
		(layer "In15.Cu")
		(net "P3E_PCH_NVS_RX_DP<0>")
	)
	(segment
		(start 97.50552 -412.907988)
		(end 103.0605 -412.907988)
		(width 0.14732)
		(layer "In15.Cu")
		(net "P3E_PCH_NVS_RX_DP<0>")
	)
	(segment
		(start 107.19308 -405.963628)
		(end 107.19308 -406.817068)
		(width 0.14732)
		(layer "In15.Cu")
		(net "P3E_PCH_NVS_RX_DP<0>")
	)
	(segment
		(start 81.16062 -416.410648)
		(end 94.00286 -416.410648)
		(width 0.14732)
		(layer "In15.Cu")
		(net "P3E_PCH_NVS_RX_DP<0>")
	)
	(segment
		(start 107.19308 -406.817068)
		(end 107.48772 -407.111708)
		(width 0.14732)
		(layer "In15.Cu")
		(net "P3E_PCH_NVS_RX_DP<0>")
	)
	(segment
		(start 72.650096 -423.489882)
		(end 73.063354 -423.90314)
		(width 0.14732)
		(layer "In15.Cu")
		(net "P3E_PCH_NVS_RX_DP<0>")
	)
	(segment
		(start 106.89336 -405.663908)
		(end 107.19308 -405.963628)
		(width 0.14732)
		(layer "In15.Cu")
		(net "P3E_PCH_NVS_RX_DP<0>")
	)
	(segment
		(start 105.48366 -410.484828)
		(end 105.48366 -406.052528)
		(width 0.14732)
		(layer "In15.Cu")
		(net "P3E_PCH_NVS_RX_DP<0>")
	)
	(segment
		(start 105.87228 -405.663908)
		(end 106.89336 -405.663908)
		(width 0.14732)
		(layer "In15.Cu")
		(net "P3E_PCH_NVS_RX_DP<0>")
	)
	(segment
		(start 103.0605 -412.907988)
		(end 105.48366 -410.484828)
		(width 0.14732)
		(layer "In15.Cu")
		(net "P3E_PCH_NVS_RX_DP<0>")
	)
	(segment
		(start 73.668128 -423.90314)
		(end 81.16062 -416.410648)
		(width 0.14732)
		(layer "In15.Cu")
		(net "P3E_PCH_NVS_RX_DP<0>")
	)
	(segment
		(start 247.707404 -192.439798)
		(end 248.01957 -191.906398)
		(width 0.13208)
		(layer "F.Cu")
		(net "P3E_PCH_NVS_RX_DN<1>")
	)
	(segment
		(start 174.225712 -383.408936)
		(end 181.708806 -378.938028)
		(width 0.13208)
		(layer "F.Cu")
		(net "P3E_PCH_NVS_RX_DN<1>")
	)
	(segment
		(start 205.559152 -353.121722)
		(end 213.509352 -344.516202)
		(width 0.13208)
		(layer "F.Cu")
		(net "P3E_PCH_NVS_RX_DN<1>")
	)
	(segment
		(start 168.756584 -384.23723)
		(end 170.568112 -384.23723)
		(width 0.13208)
		(layer "F.Cu")
		(net "P3E_PCH_NVS_RX_DN<1>")
	)
	(segment
		(start 99.74834 -392.255502)
		(end 99.74834 -390.277604)
		(width 0.13208)
		(layer "F.Cu")
		(net "P3E_PCH_NVS_RX_DN<1>")
	)
	(segment
		(start 213.509352 -344.516202)
		(end 245.91391 -275.05406)
		(width 0.13208)
		(layer "F.Cu")
		(net "P3E_PCH_NVS_RX_DN<1>")
	)
	(segment
		(start 347.071696 -54.229508)
		(end 347.428058 -54.229508)
		(width 0.0889)
		(layer "F.Cu")
		(net "P3E_PCH_NVS_RX_DN<1>")
	)
	(segment
		(start 347.428058 -54.229508)
		(end 347.793564 -54.380892)
		(width 0.0889)
		(layer "F.Cu")
		(net "P3E_PCH_NVS_RX_DN<1>")
	)
	(segment
		(start 100.098098 -397.91005)
		(end 100.096828 -397.891)
		(width 0.13208)
		(layer "F.Cu")
		(net "P3E_PCH_NVS_RX_DN<1>")
	)
	(segment
		(start 356.482396 -58.250074)
		(end 356.482396 -60.964572)
		(width 0.13208)
		(layer "F.Cu")
		(net "P3E_PCH_NVS_RX_DN<1>")
	)
	(segment
		(start 356.12959 -57.65292)
		(end 356.309676 -57.833006)
		(width 0.13208)
		(layer "F.Cu")
		(net "P3E_PCH_NVS_RX_DN<1>")
	)
	(segment
		(start 353.612196 -55.18404)
		(end 353.660964 -55.18404)
		(width 0.0889)
		(layer "F.Cu")
		(net "P3E_PCH_NVS_RX_DN<1>")
	)
	(segment
		(start 246.98452 -246.351044)
		(end 246.357902 -197.237604)
		(width 0.13208)
		(layer "F.Cu")
		(net "P3E_PCH_NVS_RX_DN<1>")
	)
	(segment
		(start 346.700348 -54.150768)
		(end 346.88145 -54.150768)
		(width 0.0889)
		(layer "F.Cu")
		(net "P3E_PCH_NVS_RX_DN<1>")
	)
	(segment
		(start 287.535366 -171.995846)
		(end 295.4147 -164.116512)
		(width 0.13208)
		(layer "F.Cu")
		(net "P3E_PCH_NVS_RX_DN<1>")
	)
	(segment
		(start 170.568112 -384.23723)
		(end 174.225712 -383.408936)
		(width 0.13208)
		(layer "F.Cu")
		(net "P3E_PCH_NVS_RX_DN<1>")
	)
	(segment
		(start 100.86975 -389.156194)
		(end 168.756584 -384.23723)
		(width 0.13208)
		(layer "F.Cu")
		(net "P3E_PCH_NVS_RX_DN<1>")
	)
	(segment
		(start 101.836474 -404.8887)
		(end 101.482906 -404.535132)
		(width 0.13208)
		(layer "F.Cu")
		(net "P3E_PCH_NVS_RX_DN<1>")
	)
	(segment
		(start 353.676458 -55.199534)
		(end 356.129844 -57.65292)
		(width 0.13208)
		(layer "F.Cu")
		(net "P3E_PCH_NVS_RX_DN<1>")
	)
	(segment
		(start 351.61347 -54.790848)
		(end 352.998532 -54.790848)
		(width 0.0889)
		(layer "F.Cu")
		(net "P3E_PCH_NVS_RX_DN<1>")
	)
	(segment
		(start 181.708806 -378.938028)
		(end 205.559152 -353.121722)
		(width 0.13208)
		(layer "F.Cu")
		(net "P3E_PCH_NVS_RX_DN<1>")
	)
	(segment
		(start 246.98452 -265.112754)
		(end 246.98452 -246.351044)
		(width 0.13208)
		(layer "F.Cu")
		(net "P3E_PCH_NVS_RX_DN<1>")
	)
	(segment
		(start 353.660964 -55.18404)
		(end 353.676458 -55.199534)
		(width 0.0889)
		(layer "F.Cu")
		(net "P3E_PCH_NVS_RX_DN<1>")
	)
	(segment
		(start 248.01957 -191.906398)
		(end 253.892558 -186.03341)
		(width 0.13208)
		(layer "F.Cu")
		(net "P3E_PCH_NVS_RX_DN<1>")
	)
	(segment
		(start 99.74834 -390.277604)
		(end 100.86975 -389.156194)
		(width 0.13208)
		(layer "F.Cu")
		(net "P3E_PCH_NVS_RX_DN<1>")
	)
	(segment
		(start 254.295402 -185.764678)
		(end 287.535366 -171.995846)
		(width 0.13208)
		(layer "F.Cu")
		(net "P3E_PCH_NVS_RX_DN<1>")
	)
	(segment
		(start 356.129844 -57.65292)
		(end 356.12959 -57.65292)
		(width 0.13208)
		(layer "F.Cu")
		(net "P3E_PCH_NVS_RX_DN<1>")
	)
	(segment
		(start 102.62362 -405.22906)
		(end 102.28326 -404.8887)
		(width 0.13208)
		(layer "F.Cu")
		(net "P3E_PCH_NVS_RX_DN<1>")
	)
	(segment
		(start 346.422726 -54.382924)
		(end 346.622624 -54.183026)
		(width 0.0889)
		(layer "F.Cu")
		(net "P3E_PCH_NVS_RX_DN<1>")
	)
	(segment
		(start 356.309676 -57.833006)
		(end 356.482396 -58.250074)
		(width 0.13208)
		(layer "F.Cu")
		(net "P3E_PCH_NVS_RX_DN<1>")
	)
	(segment
		(start 346.622624 -54.183026)
		(end 346.700348 -54.150768)
		(width 0.0889)
		(layer "F.Cu")
		(net "P3E_PCH_NVS_RX_DN<1>")
	)
	(segment
		(start 100.096828 -397.891)
		(end 99.74834 -392.255502)
		(width 0.13208)
		(layer "F.Cu")
		(net "P3E_PCH_NVS_RX_DN<1>")
	)
	(segment
		(start 346.88145 -54.150768)
		(end 347.071696 -54.229508)
		(width 0.0889)
		(layer "F.Cu")
		(net "P3E_PCH_NVS_RX_DN<1>")
	)
	(segment
		(start 101.482906 -404.535132)
		(end 100.098098 -397.91005)
		(width 0.13208)
		(layer "F.Cu")
		(net "P3E_PCH_NVS_RX_DN<1>")
	)
	(segment
		(start 353.375214 -54.946804)
		(end 353.612196 -55.18404)
		(width 0.0889)
		(layer "F.Cu")
		(net "P3E_PCH_NVS_RX_DN<1>")
	)
	(segment
		(start 295.4147 -164.116512)
		(end 295.4147 -163.398708)
		(width 0.13208)
		(layer "F.Cu")
		(net "P3E_PCH_NVS_RX_DN<1>")
	)
	(segment
		(start 295.4147 -163.398708)
		(end 295.11244 -163.096448)
		(width 0.13208)
		(layer "F.Cu")
		(net "P3E_PCH_NVS_RX_DN<1>")
	)
	(segment
		(start 345.96959 -54.453028)
		(end 346.253562 -54.453028)
		(width 0.0889)
		(layer "F.Cu")
		(net "P3E_PCH_NVS_RX_DN<1>")
	)
	(segment
		(start 246.357902 -197.237604)
		(end 247.707404 -192.439798)
		(width 0.13208)
		(layer "F.Cu")
		(net "P3E_PCH_NVS_RX_DN<1>")
	)
	(segment
		(start 347.794072 -54.381146)
		(end 350.624394 -54.381146)
		(width 0.0889)
		(layer "F.Cu")
		(net "P3E_PCH_NVS_RX_DN<1>")
	)
	(segment
		(start 350.824292 -54.46395)
		(end 351.61347 -54.790848)
		(width 0.0889)
		(layer "F.Cu")
		(net "P3E_PCH_NVS_RX_DN<1>")
	)
	(segment
		(start 102.28326 -404.8887)
		(end 101.836474 -404.8887)
		(width 0.13208)
		(layer "F.Cu")
		(net "P3E_PCH_NVS_RX_DN<1>")
	)
	(segment
		(start 352.998532 -54.790848)
		(end 353.375214 -54.946804)
		(width 0.0889)
		(layer "F.Cu")
		(net "P3E_PCH_NVS_RX_DN<1>")
	)
	(segment
		(start 347.793564 -54.380892)
		(end 347.794072 -54.381146)
		(width 0.0889)
		(layer "F.Cu")
		(net "P3E_PCH_NVS_RX_DN<1>")
	)
	(segment
		(start 356.482396 -60.964572)
		(end 356.71379 -61.195966)
		(width 0.13208)
		(layer "F.Cu")
		(net "P3E_PCH_NVS_RX_DN<1>")
	)
	(segment
		(start 245.91391 -275.05406)
		(end 246.98452 -265.112754)
		(width 0.13208)
		(layer "F.Cu")
		(net "P3E_PCH_NVS_RX_DN<1>")
	)
	(segment
		(start 350.624394 -54.381146)
		(end 350.824292 -54.46395)
		(width 0.0889)
		(layer "F.Cu")
		(net "P3E_PCH_NVS_RX_DN<1>")
	)
	(segment
		(start 346.253562 -54.453028)
		(end 346.422726 -54.382924)
		(width 0.0889)
		(layer "F.Cu")
		(net "P3E_PCH_NVS_RX_DN<1>")
	)
	(segment
		(start 253.892558 -186.03341)
		(end 254.295402 -185.764678)
		(width 0.13208)
		(layer "F.Cu")
		(net "P3E_PCH_NVS_RX_DN<1>")
	)
	(via
		(at 102.62362 -405.22906)
		(size 0.508)
		(drill 0.254)
		(layers "F.Cu" "B.Cu")
		(net "P3E_PCH_NVS_RX_DN<1>")
	)
	(segment
		(start 100.519484 -406.033732)
		(end 101.631496 -404.92172)
		(width 0.13208)
		(layer "B.Cu")
		(net "P3E_PCH_NVS_RX_DN<1>")
	)
	(segment
		(start 99.08794 -410.921708)
		(end 100.208334 -407.095452)
		(width 0.13208)
		(layer "B.Cu")
		(net "P3E_PCH_NVS_RX_DN<1>")
	)
	(segment
		(start 100.38715 -406.485852)
		(end 100.519484 -406.033732)
		(width 0.13208)
		(layer "B.Cu")
		(net "P3E_PCH_NVS_RX_DN<1>")
	)
	(segment
		(start 70.6501 -423.689526)
		(end 71.120254 -423.219372)
		(width 0.13208)
		(layer "B.Cu")
		(net "P3E_PCH_NVS_RX_DN<1>")
	)
	(segment
		(start 96.496886 -413.399732)
		(end 99.08794 -410.921708)
		(width 0.13208)
		(layer "B.Cu")
		(net "P3E_PCH_NVS_RX_DN<1>")
	)
	(segment
		(start 71.77024 -417.091622)
		(end 72.829674 -416.031934)
		(width 0.13208)
		(layer "B.Cu")
		(net "P3E_PCH_NVS_RX_DN<1>")
	)
	(segment
		(start 71.411084 -423.219372)
		(end 71.77024 -422.860216)
		(width 0.13208)
		(layer "B.Cu")
		(net "P3E_PCH_NVS_RX_DN<1>")
	)
	(segment
		(start 102.31628 -404.92172)
		(end 102.62362 -405.22906)
		(width 0.13208)
		(layer "B.Cu")
		(net "P3E_PCH_NVS_RX_DN<1>")
	)
	(segment
		(start 71.120254 -423.219372)
		(end 71.411084 -423.219372)
		(width 0.13208)
		(layer "B.Cu")
		(net "P3E_PCH_NVS_RX_DN<1>")
	)
	(segment
		(start 101.631496 -404.92172)
		(end 102.31628 -404.92172)
		(width 0.13208)
		(layer "B.Cu")
		(net "P3E_PCH_NVS_RX_DN<1>")
	)
	(segment
		(start 70.6501 -423.68978)
		(end 70.6501 -423.689526)
		(width 0.13208)
		(layer "B.Cu")
		(net "P3E_PCH_NVS_RX_DN<1>")
	)
	(segment
		(start 72.829674 -416.031934)
		(end 96.496886 -413.399732)
		(width 0.13208)
		(layer "B.Cu")
		(net "P3E_PCH_NVS_RX_DN<1>")
	)
	(segment
		(start 100.469954 -406.637236)
		(end 100.38715 -406.485852)
		(width 0.13208)
		(layer "B.Cu")
		(net "P3E_PCH_NVS_RX_DN<1>")
	)
	(segment
		(start 100.208334 -407.095452)
		(end 100.359972 -407.012902)
		(width 0.13208)
		(layer "B.Cu")
		(net "P3E_PCH_NVS_RX_DN<1>")
	)
	(segment
		(start 100.359972 -407.012902)
		(end 100.469954 -406.637236)
		(width 0.13208)
		(layer "B.Cu")
		(net "P3E_PCH_NVS_RX_DN<1>")
	)
	(segment
		(start 71.77024 -422.860216)
		(end 71.77024 -417.091622)
		(width 0.13208)
		(layer "B.Cu")
		(net "P3E_PCH_NVS_RX_DN<1>")
	)
	(segment
		(start 356.41915 -61.490606)
		(end 356.41915 -62.19317)
		(width 0.14732)
		(layer "In2.Cu")
		(net "P3E_PCH_NVS_RX_DN<1>")
	)
	(segment
		(start 295.40708 -163.713414)
		(end 295.40708 -163.391088)
		(width 0.14732)
		(layer "In2.Cu")
		(net "P3E_PCH_NVS_RX_DN<1>")
	)
	(segment
		(start 297.141138 -164.021262)
		(end 295.714928 -164.021262)
		(width 0.14732)
		(layer "In2.Cu")
		(net "P3E_PCH_NVS_RX_DN<1>")
	)
	(segment
		(start 356.71379 -61.195966)
		(end 356.41915 -61.490606)
		(width 0.14732)
		(layer "In2.Cu")
		(net "P3E_PCH_NVS_RX_DN<1>")
	)
	(segment
		(start 353.747832 -71.217536)
		(end 345.050872 -136.602724)
		(width 0.14732)
		(layer "In2.Cu")
		(net "P3E_PCH_NVS_RX_DN<1>")
	)
	(segment
		(start 299.024548 -163.03752)
		(end 298.676822 -163.385246)
		(width 0.14732)
		(layer "In2.Cu")
		(net "P3E_PCH_NVS_RX_DN<1>")
	)
	(segment
		(start 295.714928 -164.021262)
		(end 295.40708 -163.713414)
		(width 0.14732)
		(layer "In2.Cu")
		(net "P3E_PCH_NVS_RX_DN<1>")
	)
	(segment
		(start 304.163222 -156.981906)
		(end 299.67301 -161.472118)
		(width 0.14732)
		(layer "In2.Cu")
		(net "P3E_PCH_NVS_RX_DN<1>")
	)
	(segment
		(start 299.67301 -161.472118)
		(end 299.024548 -163.03752)
		(width 0.14732)
		(layer "In2.Cu")
		(net "P3E_PCH_NVS_RX_DN<1>")
	)
	(segment
		(start 345.050872 -136.602724)
		(end 344.473784 -138.489436)
		(width 0.14732)
		(layer "In2.Cu")
		(net "P3E_PCH_NVS_RX_DN<1>")
	)
	(segment
		(start 344.473784 -138.489436)
		(end 341.408766 -141.5542)
		(width 0.14732)
		(layer "In2.Cu")
		(net "P3E_PCH_NVS_RX_DN<1>")
	)
	(segment
		(start 295.40708 -163.391088)
		(end 295.11244 -163.096448)
		(width 0.14732)
		(layer "In2.Cu")
		(net "P3E_PCH_NVS_RX_DN<1>")
	)
	(segment
		(start 341.408766 -141.5542)
		(end 304.163222 -156.981906)
		(width 0.14732)
		(layer "In2.Cu")
		(net "P3E_PCH_NVS_RX_DN<1>")
	)
	(segment
		(start 356.41915 -62.19317)
		(end 353.747832 -71.217536)
		(width 0.14732)
		(layer "In2.Cu")
		(net "P3E_PCH_NVS_RX_DN<1>")
	)
	(segment
		(start 298.676822 -163.385246)
		(end 297.141138 -164.021262)
		(width 0.14732)
		(layer "In2.Cu")
		(net "P3E_PCH_NVS_RX_DN<1>")
	)
	(segment
		(start 300.8757 -163.386008)
		(end 300.8757 -163.904168)
		(width 0.13208)
		(layer "F.Cu")
		(net "P3E_PCH_NVS_RX_DN<0>")
	)
	(segment
		(start 106.9086 -406.827228)
		(end 106.62412 -407.111708)
		(width 0.13208)
		(layer "F.Cu")
		(net "P3E_PCH_NVS_RX_DN<0>")
	)
	(segment
		(start 292.119304 -172.660564)
		(end 255.89738 -187.664344)
		(width 0.13208)
		(layer "F.Cu")
		(net "P3E_PCH_NVS_RX_DN<0>")
	)
	(segment
		(start 347.039184 -53.676804)
		(end 346.919296 -53.780436)
		(width 0.0889)
		(layer "F.Cu")
		(net "P3E_PCH_NVS_RX_DN<0>")
	)
	(segment
		(start 357.78694 -56.186832)
		(end 357.78694 -56.596788)
		(width 0.13208)
		(layer "F.Cu")
		(net "P3E_PCH_NVS_RX_DN<0>")
	)
	(segment
		(start 173.665134 -386.527294)
		(end 166.52494 -388.671562)
		(width 0.13208)
		(layer "F.Cu")
		(net "P3E_PCH_NVS_RX_DN<0>")
	)
	(segment
		(start 111.015018 -396.015464)
		(end 110.506764 -396.523718)
		(width 0.13208)
		(layer "F.Cu")
		(net "P3E_PCH_NVS_RX_DN<0>")
	)
	(segment
		(start 111.2012 -393.271502)
		(end 111.2012 -395.56563)
		(width 0.13208)
		(layer "F.Cu")
		(net "P3E_PCH_NVS_RX_DN<0>")
	)
	(segment
		(start 348.703646 -53.898546)
		(end 347.804994 -53.898546)
		(width 0.0889)
		(layer "F.Cu")
		(net "P3E_PCH_NVS_RX_DN<0>")
	)
	(segment
		(start 106.9086 -405.034242)
		(end 106.9086 -406.827228)
		(width 0.13208)
		(layer "F.Cu")
		(net "P3E_PCH_NVS_RX_DN<0>")
	)
	(segment
		(start 347.393006 -53.676804)
		(end 347.039184 -53.676804)
		(width 0.0889)
		(layer "F.Cu")
		(net "P3E_PCH_NVS_RX_DN<0>")
	)
	(segment
		(start 347.804994 -53.898546)
		(end 347.669104 -53.762656)
		(width 0.0889)
		(layer "F.Cu")
		(net "P3E_PCH_NVS_RX_DN<0>")
	)
	(segment
		(start 300.8757 -163.904168)
		(end 292.119304 -172.660564)
		(width 0.13208)
		(layer "F.Cu")
		(net "P3E_PCH_NVS_RX_DN<0>")
	)
	(segment
		(start 249.555 -246.334026)
		(end 249.555 -263.589262)
		(width 0.13208)
		(layer "F.Cu")
		(net "P3E_PCH_NVS_RX_DN<0>")
	)
	(segment
		(start 346.919296 -53.780436)
		(end 346.74683 -53.952902)
		(width 0.0889)
		(layer "F.Cu")
		(net "P3E_PCH_NVS_RX_DN<0>")
	)
	(segment
		(start 348.7039 -53.898292)
		(end 348.703646 -53.898546)
		(width 0.0889)
		(layer "F.Cu")
		(net "P3E_PCH_NVS_RX_DN<0>")
	)
	(segment
		(start 347.478858 -53.762656)
		(end 347.393006 -53.676804)
		(width 0.0889)
		(layer "F.Cu")
		(net "P3E_PCH_NVS_RX_DN<0>")
	)
	(segment
		(start 106.947208 -397.998188)
		(end 106.57205 -398.373346)
		(width 0.13208)
		(layer "F.Cu")
		(net "P3E_PCH_NVS_RX_DN<0>")
	)
	(segment
		(start 215.189562 -346.486734)
		(end 183.780684 -380.48438)
		(width 0.13208)
		(layer "F.Cu")
		(net "P3E_PCH_NVS_RX_DN<0>")
	)
	(segment
		(start 353.99218 -53.898546)
		(end 348.704154 -53.898546)
		(width 0.0889)
		(layer "F.Cu")
		(net "P3E_PCH_NVS_RX_DN<0>")
	)
	(segment
		(start 113.401856 -391.061448)
		(end 112.083342 -391.837672)
		(width 0.13208)
		(layer "F.Cu")
		(net "P3E_PCH_NVS_RX_DN<0>")
	)
	(segment
		(start 106.57205 -398.373346)
		(end 106.57205 -404.697692)
		(width 0.13208)
		(layer "F.Cu")
		(net "P3E_PCH_NVS_RX_DN<0>")
	)
	(segment
		(start 255.89738 -187.664344)
		(end 250.086114 -193.47561)
		(width 0.13208)
		(layer "F.Cu")
		(net "P3E_PCH_NVS_RX_DN<0>")
	)
	(segment
		(start 111.2012 -395.56563)
		(end 111.015018 -396.015464)
		(width 0.13208)
		(layer "F.Cu")
		(net "P3E_PCH_NVS_RX_DN<0>")
	)
	(segment
		(start 347.669104 -53.762656)
		(end 347.478858 -53.762656)
		(width 0.0889)
		(layer "F.Cu")
		(net "P3E_PCH_NVS_RX_DN<0>")
	)
	(segment
		(start 183.780684 -380.48438)
		(end 173.665134 -386.527294)
		(width 0.13208)
		(layer "F.Cu")
		(net "P3E_PCH_NVS_RX_DN<0>")
	)
	(segment
		(start 357.78186 -56.601868)
		(end 356.74427 -56.601868)
		(width 0.13208)
		(layer "F.Cu")
		(net "P3E_PCH_NVS_RX_DN<0>")
	)
	(segment
		(start 112.083342 -391.837672)
		(end 111.2012 -393.271502)
		(width 0.13208)
		(layer "F.Cu")
		(net "P3E_PCH_NVS_RX_DN<0>")
	)
	(segment
		(start 248.262648 -275.590254)
		(end 215.189562 -346.486734)
		(width 0.13208)
		(layer "F.Cu")
		(net "P3E_PCH_NVS_RX_DN<0>")
	)
	(segment
		(start 356.74427 -56.601868)
		(end 355.23932 -55.096918)
		(width 0.13208)
		(layer "F.Cu")
		(net "P3E_PCH_NVS_RX_DN<0>")
	)
	(segment
		(start 250.086114 -193.47561)
		(end 248.933208 -197.576186)
		(width 0.13208)
		(layer "F.Cu")
		(net "P3E_PCH_NVS_RX_DN<0>")
	)
	(segment
		(start 348.704154 -53.898546)
		(end 348.7039 -53.898292)
		(width 0.0889)
		(layer "F.Cu")
		(net "P3E_PCH_NVS_RX_DN<0>")
	)
	(segment
		(start 249.555 -263.589262)
		(end 248.262648 -275.590254)
		(width 0.13208)
		(layer "F.Cu")
		(net "P3E_PCH_NVS_RX_DN<0>")
	)
	(segment
		(start 248.933208 -197.576186)
		(end 249.555 -246.334026)
		(width 0.13208)
		(layer "F.Cu")
		(net "P3E_PCH_NVS_RX_DN<0>")
	)
	(segment
		(start 106.57205 -404.697692)
		(end 106.9086 -405.034242)
		(width 0.13208)
		(layer "F.Cu")
		(net "P3E_PCH_NVS_RX_DN<0>")
	)
	(segment
		(start 357.48468 -55.884572)
		(end 357.78694 -56.186832)
		(width 0.13208)
		(layer "F.Cu")
		(net "P3E_PCH_NVS_RX_DN<0>")
	)
	(segment
		(start 355.23932 -55.096918)
		(end 355.223826 -55.081424)
		(width 0.0889)
		(layer "F.Cu")
		(net "P3E_PCH_NVS_RX_DN<0>")
	)
	(segment
		(start 346.74683 -53.952902)
		(end 346.384626 -53.952902)
		(width 0.0889)
		(layer "F.Cu")
		(net "P3E_PCH_NVS_RX_DN<0>")
	)
	(segment
		(start 357.78694 -56.596788)
		(end 357.78186 -56.601868)
		(width 0.13208)
		(layer "F.Cu")
		(net "P3E_PCH_NVS_RX_DN<0>")
	)
	(segment
		(start 355.223826 -55.081424)
		(end 355.175058 -55.081424)
		(width 0.0889)
		(layer "F.Cu")
		(net "P3E_PCH_NVS_RX_DN<0>")
	)
	(segment
		(start 166.52494 -388.671562)
		(end 113.401856 -391.061448)
		(width 0.13208)
		(layer "F.Cu")
		(net "P3E_PCH_NVS_RX_DN<0>")
	)
	(segment
		(start 300.57344 -163.083748)
		(end 300.8757 -163.386008)
		(width 0.13208)
		(layer "F.Cu")
		(net "P3E_PCH_NVS_RX_DN<0>")
	)
	(segment
		(start 355.175058 -55.081424)
		(end 353.99218 -53.898546)
		(width 0.0889)
		(layer "F.Cu")
		(net "P3E_PCH_NVS_RX_DN<0>")
	)
	(segment
		(start 110.506764 -396.523718)
		(end 106.947208 -397.998188)
		(width 0.13208)
		(layer "F.Cu")
		(net "P3E_PCH_NVS_RX_DN<0>")
	)
	(segment
		(start 300.84776 -162.809428)
		(end 300.57344 -163.083748)
		(width 0.14732)
		(layer "In2.Cu")
		(net "P3E_PCH_NVS_RX_DN<0>")
	)
	(segment
		(start 345.740736 -136.657842)
		(end 345.12631 -138.767058)
		(width 0.14732)
		(layer "In2.Cu")
		(net "P3E_PCH_NVS_RX_DN<0>")
	)
	(segment
		(start 357.77932 -56.179212)
		(end 357.77932 -62.40526)
		(width 0.14732)
		(layer "In2.Cu")
		(net "P3E_PCH_NVS_RX_DN<0>")
	)
	(segment
		(start 300.84776 -161.555176)
		(end 300.84776 -162.809428)
		(width 0.14732)
		(layer "In2.Cu")
		(net "P3E_PCH_NVS_RX_DN<0>")
	)
	(segment
		(start 357.48468 -55.884572)
		(end 357.77932 -56.179212)
		(width 0.14732)
		(layer "In2.Cu")
		(net "P3E_PCH_NVS_RX_DN<0>")
	)
	(segment
		(start 304.9905 -157.412436)
		(end 300.84776 -161.555176)
		(width 0.14732)
		(layer "In2.Cu")
		(net "P3E_PCH_NVS_RX_DN<0>")
	)
	(segment
		(start 345.12631 -138.767058)
		(end 341.676736 -142.216632)
		(width 0.14732)
		(layer "In2.Cu")
		(net "P3E_PCH_NVS_RX_DN<0>")
	)
	(segment
		(start 341.676736 -142.216632)
		(end 304.9905 -157.412436)
		(width 0.14732)
		(layer "In2.Cu")
		(net "P3E_PCH_NVS_RX_DN<0>")
	)
	(segment
		(start 357.77932 -62.40526)
		(end 345.740736 -136.657842)
		(width 0.14732)
		(layer "In2.Cu")
		(net "P3E_PCH_NVS_RX_DN<0>")
	)
	(segment
		(start 106.91876 -406.07742)
		(end 106.91876 -406.817068)
		(width 0.14732)
		(layer "In15.Cu")
		(net "P3E_PCH_NVS_RX_DN<0>")
	)
	(segment
		(start 72.650096 -424.689524)
		(end 73.11263 -424.22699)
		(width 0.14732)
		(layer "In15.Cu")
		(net "P3E_PCH_NVS_RX_DN<0>")
	)
	(segment
		(start 94.812612 -415.989008)
		(end 95.017336 -415.989008)
		(width 0.14732)
		(layer "In15.Cu")
		(net "P3E_PCH_NVS_RX_DN<0>")
	)
	(segment
		(start 95.27794 -415.52368)
		(end 95.570802 -415.230818)
		(width 0.14732)
		(layer "In15.Cu")
		(net "P3E_PCH_NVS_RX_DN<0>")
	)
	(segment
		(start 99.31527 -413.327088)
		(end 99.46005 -413.182308)
		(width 0.14732)
		(layer "In15.Cu")
		(net "P3E_PCH_NVS_RX_DN<0>")
	)
	(segment
		(start 96.482662 -414.318958)
		(end 96.687386 -414.318958)
		(width 0.14732)
		(layer "In15.Cu")
		(net "P3E_PCH_NVS_RX_DN<0>")
	)
	(segment
		(start 96.03613 -414.970214)
		(end 96.03613 -414.76549)
		(width 0.14732)
		(layer "In15.Cu")
		(net "P3E_PCH_NVS_RX_DN<0>")
	)
	(segment
		(start 96.03613 -414.76549)
		(end 96.482662 -414.318958)
		(width 0.14732)
		(layer "In15.Cu")
		(net "P3E_PCH_NVS_RX_DN<0>")
	)
	(segment
		(start 105.75798 -406.16632)
		(end 105.986072 -405.938228)
		(width 0.14732)
		(layer "In15.Cu")
		(net "P3E_PCH_NVS_RX_DN<0>")
	)
	(segment
		(start 96.687386 -414.318958)
		(end 96.94799 -414.058354)
		(width 0.14732)
		(layer "In15.Cu")
		(net "P3E_PCH_NVS_RX_DN<0>")
	)
	(segment
		(start 95.570802 -415.230818)
		(end 95.775526 -415.230818)
		(width 0.14732)
		(layer "In15.Cu")
		(net "P3E_PCH_NVS_RX_DN<0>")
	)
	(segment
		(start 105.75798 -410.59862)
		(end 105.75798 -406.16632)
		(width 0.14732)
		(layer "In15.Cu")
		(net "P3E_PCH_NVS_RX_DN<0>")
	)
	(segment
		(start 95.775526 -415.230818)
		(end 96.03613 -414.970214)
		(width 0.14732)
		(layer "In15.Cu")
		(net "P3E_PCH_NVS_RX_DN<0>")
	)
	(segment
		(start 106.91876 -406.817068)
		(end 106.62412 -407.111708)
		(width 0.14732)
		(layer "In15.Cu")
		(net "P3E_PCH_NVS_RX_DN<0>")
	)
	(segment
		(start 97.619312 -413.182308)
		(end 98.80219 -413.182308)
		(width 0.14732)
		(layer "In15.Cu")
		(net "P3E_PCH_NVS_RX_DN<0>")
	)
	(segment
		(start 94.116652 -416.684968)
		(end 94.812612 -415.989008)
		(width 0.14732)
		(layer "In15.Cu")
		(net "P3E_PCH_NVS_RX_DN<0>")
	)
	(segment
		(start 95.017336 -415.989008)
		(end 95.27794 -415.728404)
		(width 0.14732)
		(layer "In15.Cu")
		(net "P3E_PCH_NVS_RX_DN<0>")
	)
	(segment
		(start 96.94799 -414.058354)
		(end 96.94799 -413.85363)
		(width 0.14732)
		(layer "In15.Cu")
		(net "P3E_PCH_NVS_RX_DN<0>")
	)
	(segment
		(start 98.94697 -413.327088)
		(end 99.31527 -413.327088)
		(width 0.14732)
		(layer "In15.Cu")
		(net "P3E_PCH_NVS_RX_DN<0>")
	)
	(segment
		(start 96.94799 -413.85363)
		(end 97.619312 -413.182308)
		(width 0.14732)
		(layer "In15.Cu")
		(net "P3E_PCH_NVS_RX_DN<0>")
	)
	(segment
		(start 106.779568 -405.938228)
		(end 106.91876 -406.07742)
		(width 0.14732)
		(layer "In15.Cu")
		(net "P3E_PCH_NVS_RX_DN<0>")
	)
	(segment
		(start 81.274412 -416.684968)
		(end 94.116652 -416.684968)
		(width 0.14732)
		(layer "In15.Cu")
		(net "P3E_PCH_NVS_RX_DN<0>")
	)
	(segment
		(start 98.80219 -413.182308)
		(end 98.94697 -413.327088)
		(width 0.14732)
		(layer "In15.Cu")
		(net "P3E_PCH_NVS_RX_DN<0>")
	)
	(segment
		(start 95.27794 -415.728404)
		(end 95.27794 -415.52368)
		(width 0.14732)
		(layer "In15.Cu")
		(net "P3E_PCH_NVS_RX_DN<0>")
	)
	(segment
		(start 103.174292 -413.182308)
		(end 105.75798 -410.59862)
		(width 0.14732)
		(layer "In15.Cu")
		(net "P3E_PCH_NVS_RX_DN<0>")
	)
	(segment
		(start 72.650096 -424.689778)
		(end 72.650096 -424.689524)
		(width 0.14732)
		(layer "In15.Cu")
		(net "P3E_PCH_NVS_RX_DN<0>")
	)
	(segment
		(start 105.986072 -405.938228)
		(end 106.779568 -405.938228)
		(width 0.14732)
		(layer "In15.Cu")
		(net "P3E_PCH_NVS_RX_DN<0>")
	)
	(segment
		(start 99.46005 -413.182308)
		(end 103.174292 -413.182308)
		(width 0.14732)
		(layer "In15.Cu")
		(net "P3E_PCH_NVS_RX_DN<0>")
	)
	(segment
		(start 73.73239 -424.22699)
		(end 81.274412 -416.684968)
		(width 0.14732)
		(layer "In15.Cu")
		(net "P3E_PCH_NVS_RX_DN<0>")
	)
	(segment
		(start 73.11263 -424.22699)
		(end 73.73239 -424.22699)
		(width 0.14732)
		(layer "In15.Cu")
		(net "P3E_PCH_NVS_RX_DN<0>")
	)
	(segment
		(start 255.432814 -103.707438)
		(end 255.566926 -103.84155)
		(width 0.12954)
		(layer "F.Cu")
		(net "NC_CLK_CK440_MXCK1_DP")
	)
	(segment
		(start 255.566926 -103.84155)
		(end 255.566926 -104.931464)
		(width 0.12954)
		(layer "F.Cu")
		(net "NC_CLK_CK440_MXCK1_DP")
	)
	(segment
		(start 255.432814 -103.438198)
		(end 255.432814 -103.707438)
		(width 0.12954)
		(layer "F.Cu")
		(net "NC_CLK_CK440_MXCK1_DP")
	)
	(segment
		(start 255.028446 -109.037882)
		(end 254.82169 -109.244638)
		(width 0.12954)
		(layer "F.Cu")
		(net "NC_CLK_CK440_MXCK1_DP")
	)
	(segment
		(start 255.028446 -106.587036)
		(end 255.028446 -109.037882)
		(width 0.12954)
		(layer "F.Cu")
		(net "NC_CLK_CK440_MXCK1_DP")
	)
	(segment
		(start 255.566926 -104.931464)
		(end 255.851406 -105.215944)
		(width 0.12954)
		(layer "F.Cu")
		(net "NC_CLK_CK440_MXCK1_DP")
	)
	(segment
		(start 255.851406 -105.215944)
		(end 255.851406 -105.764076)
		(width 0.12954)
		(layer "F.Cu")
		(net "NC_CLK_CK440_MXCK1_DP")
	)
	(segment
		(start 255.851406 -105.764076)
		(end 255.028446 -106.587036)
		(width 0.12954)
		(layer "F.Cu")
		(net "NC_CLK_CK440_MXCK1_DP")
	)
	(via
		(at 254.82169 -109.244638)
		(size 0.762)
		(drill 0.381)
		(layers "F.Cu" "B.Cu")
		(net "NC_CLK_CK440_MXCK1_DP")
	)
	(segment
		(start 255.828546 -103.812594)
		(end 255.828546 -104.823006)
		(width 0.12954)
		(layer "F.Cu")
		(net "NC_CLK_CK440_MXCK1_DN")
	)
	(segment
		(start 255.932686 -103.438198)
		(end 255.932686 -103.708454)
		(width 0.12954)
		(layer "F.Cu")
		(net "NC_CLK_CK440_MXCK1_DN")
	)
	(segment
		(start 255.32588 -106.797348)
		(end 255.32588 -107.78998)
		(width 0.12954)
		(layer "F.Cu")
		(net "NC_CLK_CK440_MXCK1_DN")
	)
	(segment
		(start 256.113026 -106.010202)
		(end 255.32588 -106.797348)
		(width 0.12954)
		(layer "F.Cu")
		(net "NC_CLK_CK440_MXCK1_DN")
	)
	(segment
		(start 255.32588 -107.78998)
		(end 255.841246 -108.305346)
		(width 0.12954)
		(layer "F.Cu")
		(net "NC_CLK_CK440_MXCK1_DN")
	)
	(segment
		(start 255.932686 -103.708454)
		(end 255.828546 -103.812594)
		(width 0.12954)
		(layer "F.Cu")
		(net "NC_CLK_CK440_MXCK1_DN")
	)
	(segment
		(start 256.113026 -105.107486)
		(end 256.113026 -106.010202)
		(width 0.12954)
		(layer "F.Cu")
		(net "NC_CLK_CK440_MXCK1_DN")
	)
	(segment
		(start 255.828546 -104.823006)
		(end 256.113026 -105.107486)
		(width 0.12954)
		(layer "F.Cu")
		(net "NC_CLK_CK440_MXCK1_DN")
	)
	(via
		(at 255.841246 -108.305346)
		(size 0.762)
		(drill 0.381)
		(layers "F.Cu" "B.Cu")
		(net "NC_CLK_CK440_MXCK1_DN")
	)
	(segment
		(start 253.32817 -107.277408)
		(end 253.111508 -107.277408)
		(width 0.12954)
		(layer "F.Cu")
		(net "NC_CLK_CK440_MXCK0_DP")
	)
	(segment
		(start 254.512064 -105.45826)
		(end 254.063246 -106.542332)
		(width 0.12954)
		(layer "F.Cu")
		(net "NC_CLK_CK440_MXCK0_DP")
	)
	(segment
		(start 254.063246 -106.542332)
		(end 253.32817 -107.277408)
		(width 0.12954)
		(layer "F.Cu")
		(net "NC_CLK_CK440_MXCK0_DP")
	)
	(segment
		(start 254.512064 -103.759254)
		(end 254.512064 -105.45826)
		(width 0.12954)
		(layer "F.Cu")
		(net "NC_CLK_CK440_MXCK0_DP")
	)
	(segment
		(start 253.111508 -107.277408)
		(end 253.023116 -107.3658)
		(width 0.12954)
		(layer "F.Cu")
		(net "NC_CLK_CK440_MXCK0_DP")
	)
	(segment
		(start 254.432816 -103.680006)
		(end 254.512064 -103.759254)
		(width 0.12954)
		(layer "F.Cu")
		(net "NC_CLK_CK440_MXCK0_DP")
	)
	(segment
		(start 254.432816 -103.438198)
		(end 254.432816 -103.680006)
		(width 0.12954)
		(layer "F.Cu")
		(net "NC_CLK_CK440_MXCK0_DP")
	)
	(via
		(at 253.023116 -107.3658)
		(size 0.762)
		(drill 0.381)
		(layers "F.Cu" "B.Cu")
		(net "NC_CLK_CK440_MXCK0_DP")
	)
	(segment
		(start 254.773684 -103.797354)
		(end 254.773684 -105.51033)
		(width 0.12954)
		(layer "F.Cu")
		(net "NC_CLK_CK440_MXCK0_DN")
	)
	(segment
		(start 254.506984 -106.154474)
		(end 254.506984 -107.056682)
		(width 0.12954)
		(layer "F.Cu")
		(net "NC_CLK_CK440_MXCK0_DN")
	)
	(segment
		(start 254.506984 -107.056682)
		(end 254.437134 -107.126532)
		(width 0.12954)
		(layer "F.Cu")
		(net "NC_CLK_CK440_MXCK0_DN")
	)
	(segment
		(start 254.773684 -105.51033)
		(end 254.506984 -106.154474)
		(width 0.12954)
		(layer "F.Cu")
		(net "NC_CLK_CK440_MXCK0_DN")
	)
	(segment
		(start 254.932688 -103.438198)
		(end 254.932688 -103.63835)
		(width 0.12954)
		(layer "F.Cu")
		(net "NC_CLK_CK440_MXCK0_DN")
	)
	(segment
		(start 254.932688 -103.63835)
		(end 254.773684 -103.797354)
		(width 0.12954)
		(layer "F.Cu")
		(net "NC_CLK_CK440_MXCK0_DN")
	)
	(via
		(at 254.437134 -107.126532)
		(size 0.762)
		(drill 0.381)
		(layers "F.Cu" "B.Cu")
		(net "NC_CLK_CK440_MXCK0_DN")
	)
	(segment
		(start 354.287582 -397.519398)
		(end 353.32797 -397.519398)
		(width 0.12954)
		(layer "F.Cu")
		(net "I3C_BMC_SWB_BUF_SDA")
	)
	(via
		(at 353.32797 -397.519398)
		(size 0.508)
		(drill 0.254)
		(layers "F.Cu" "B.Cu")
		(net "I3C_BMC_SWB_BUF_SDA")
	)
	(segment
		(start 383.49809 -424.689778)
		(end 376.932952 -418.12464)
		(width 0.127)
		(layer "In2.Cu")
		(net "I3C_BMC_SWB_BUF_SDA")
	)
	(segment
		(start 356.235 -402.209)
		(end 353.6188 -399.5928)
		(width 0.127)
		(layer "In2.Cu")
		(net "I3C_BMC_SWB_BUF_SDA")
	)
	(segment
		(start 376.932952 -418.12464)
		(end 369.089432 -418.12464)
		(width 0.127)
		(layer "In2.Cu")
		(net "I3C_BMC_SWB_BUF_SDA")
	)
	(segment
		(start 366.347248 -415.635948)
		(end 364.236 -413.5247)
		(width 0.127)
		(layer "In2.Cu")
		(net "I3C_BMC_SWB_BUF_SDA")
	)
	(segment
		(start 367.148618 -415.91103)
		(end 366.873536 -415.635948)
		(width 0.127)
		(layer "In2.Cu")
		(net "I3C_BMC_SWB_BUF_SDA")
	)
	(segment
		(start 367.148618 -416.183826)
		(end 367.148618 -415.91103)
		(width 0.127)
		(layer "In2.Cu")
		(net "I3C_BMC_SWB_BUF_SDA")
	)
	(segment
		(start 364.236 -413.5247)
		(end 364.236 -412.0642)
		(width 0.127)
		(layer "In2.Cu")
		(net "I3C_BMC_SWB_BUF_SDA")
	)
	(segment
		(start 356.235 -404.0632)
		(end 356.235 -402.209)
		(width 0.127)
		(layer "In2.Cu")
		(net "I3C_BMC_SWB_BUF_SDA")
	)
	(segment
		(start 369.089432 -418.12464)
		(end 367.148618 -416.183826)
		(width 0.127)
		(layer "In2.Cu")
		(net "I3C_BMC_SWB_BUF_SDA")
	)
	(segment
		(start 352.80346 -399.43786)
		(end 352.80346 -397.843248)
		(width 0.127)
		(layer "In2.Cu")
		(net "I3C_BMC_SWB_BUF_SDA")
	)
	(segment
		(start 353.6188 -399.5928)
		(end 352.9584 -399.5928)
		(width 0.127)
		(layer "In2.Cu")
		(net "I3C_BMC_SWB_BUF_SDA")
	)
	(segment
		(start 383.750058 -424.689778)
		(end 383.49809 -424.689778)
		(width 0.127)
		(layer "In2.Cu")
		(net "I3C_BMC_SWB_BUF_SDA")
	)
	(segment
		(start 352.80346 -397.843248)
		(end 353.12731 -397.519398)
		(width 0.127)
		(layer "In2.Cu")
		(net "I3C_BMC_SWB_BUF_SDA")
	)
	(segment
		(start 366.873536 -415.635948)
		(end 366.347248 -415.635948)
		(width 0.127)
		(layer "In2.Cu")
		(net "I3C_BMC_SWB_BUF_SDA")
	)
	(segment
		(start 364.236 -412.0642)
		(end 356.235 -404.0632)
		(width 0.127)
		(layer "In2.Cu")
		(net "I3C_BMC_SWB_BUF_SDA")
	)
	(segment
		(start 352.9584 -399.5928)
		(end 352.80346 -399.43786)
		(width 0.127)
		(layer "In2.Cu")
		(net "I3C_BMC_SWB_BUF_SDA")
	)
	(segment
		(start 353.12731 -397.519398)
		(end 353.32797 -397.519398)
		(width 0.127)
		(layer "In2.Cu")
		(net "I3C_BMC_SWB_BUF_SDA")
	)
	(segment
		(start 354.287582 -398.789398)
		(end 353.48037 -398.789398)
		(width 0.12954)
		(layer "F.Cu")
		(net "I3C_BMC_SWB_BUF_SCL")
	)
	(via
		(at 353.48037 -398.789398)
		(size 0.508)
		(drill 0.254)
		(layers "F.Cu" "B.Cu")
		(net "I3C_BMC_SWB_BUF_SCL")
	)
	(segment
		(start 361.7468 -407.472388)
		(end 361.7468 -408.5336)
		(width 0.127)
		(layer "In2.Cu")
		(net "I3C_BMC_SWB_BUF_SCL")
	)
	(segment
		(start 353.48037 -398.789398)
		(end 353.729798 -398.789398)
		(width 0.127)
		(layer "In2.Cu")
		(net "I3C_BMC_SWB_BUF_SCL")
	)
	(segment
		(start 370.58854 -417.380928)
		(end 377.28906 -417.380928)
		(width 0.127)
		(layer "In2.Cu")
		(net "I3C_BMC_SWB_BUF_SCL")
	)
	(segment
		(start 361.7468 -408.5336)
		(end 362.331 -409.1178)
		(width 0.127)
		(layer "In2.Cu")
		(net "I3C_BMC_SWB_BUF_SCL")
	)
	(segment
		(start 365.7473 -411.749748)
		(end 365.7473 -411.751018)
		(width 0.127)
		(layer "In2.Cu")
		(net "I3C_BMC_SWB_BUF_SCL")
	)
	(segment
		(start 366.285018 -412.0261)
		(end 366.6871 -412.428182)
		(width 0.127)
		(layer "In2.Cu")
		(net "I3C_BMC_SWB_BUF_SCL")
	)
	(segment
		(start 362.331 -409.1178)
		(end 363.5502 -409.1178)
		(width 0.127)
		(layer "In2.Cu")
		(net "I3C_BMC_SWB_BUF_SCL")
	)
	(segment
		(start 366.022382 -412.0261)
		(end 366.285018 -412.0261)
		(width 0.127)
		(layer "In2.Cu")
		(net "I3C_BMC_SWB_BUF_SCL")
	)
	(segment
		(start 365.4298 -410.9974)
		(end 365.4298 -411.432248)
		(width 0.127)
		(layer "In2.Cu")
		(net "I3C_BMC_SWB_BUF_SCL")
	)
	(segment
		(start 387.749796 -424.689778)
		(end 387.75005 -424.689778)
		(width 0.127)
		(layer "In2.Cu")
		(net "I3C_BMC_SWB_BUF_SCL")
	)
	(segment
		(start 379.53188 -419.623748)
		(end 382.683766 -419.623748)
		(width 0.127)
		(layer "In2.Cu")
		(net "I3C_BMC_SWB_BUF_SCL")
	)
	(segment
		(start 356.9716 -402.697188)
		(end 361.7468 -407.472388)
		(width 0.127)
		(layer "In2.Cu")
		(net "I3C_BMC_SWB_BUF_SCL")
	)
	(segment
		(start 365.7473 -411.751018)
		(end 366.022382 -412.0261)
		(width 0.127)
		(layer "In2.Cu")
		(net "I3C_BMC_SWB_BUF_SCL")
	)
	(segment
		(start 377.28906 -417.380928)
		(end 379.53188 -419.623748)
		(width 0.127)
		(layer "In2.Cu")
		(net "I3C_BMC_SWB_BUF_SCL")
	)
	(segment
		(start 382.683766 -419.623748)
		(end 387.749796 -424.689778)
		(width 0.127)
		(layer "In2.Cu")
		(net "I3C_BMC_SWB_BUF_SCL")
	)
	(segment
		(start 353.729798 -398.789398)
		(end 356.9716 -402.0312)
		(width 0.127)
		(layer "In2.Cu")
		(net "I3C_BMC_SWB_BUF_SCL")
	)
	(segment
		(start 370.1034 -416.895788)
		(end 370.58854 -417.380928)
		(width 0.127)
		(layer "In2.Cu")
		(net "I3C_BMC_SWB_BUF_SCL")
	)
	(segment
		(start 365.4298 -411.432248)
		(end 365.7473 -411.749748)
		(width 0.127)
		(layer "In2.Cu")
		(net "I3C_BMC_SWB_BUF_SCL")
	)
	(segment
		(start 366.6871 -412.428182)
		(end 366.6871 -412.689548)
		(width 0.127)
		(layer "In2.Cu")
		(net "I3C_BMC_SWB_BUF_SCL")
	)
	(segment
		(start 363.5502 -409.1178)
		(end 365.4298 -410.9974)
		(width 0.127)
		(layer "In2.Cu")
		(net "I3C_BMC_SWB_BUF_SCL")
	)
	(segment
		(start 370.1034 -416.105848)
		(end 370.1034 -416.895788)
		(width 0.127)
		(layer "In2.Cu")
		(net "I3C_BMC_SWB_BUF_SCL")
	)
	(segment
		(start 356.9716 -402.0312)
		(end 356.9716 -402.697188)
		(width 0.127)
		(layer "In2.Cu")
		(net "I3C_BMC_SWB_BUF_SCL")
	)
	(segment
		(start 366.6871 -412.689548)
		(end 370.1034 -416.105848)
		(width 0.127)
		(layer "In2.Cu")
		(net "I3C_BMC_SWB_BUF_SCL")
	)
	(segment
		(start 167.517826 -113.706148)
		(end 166.57828 -113.706148)
		(width 0.12954)
		(layer "F.Cu")
		(net "GPU_WP_HW_CTRL_R_N")
	)
	(segment
		(start 165.09873 -113.706148)
		(end 165.04793 -113.756948)
		(width 0.12954)
		(layer "F.Cu")
		(net "GPU_WP_HW_CTRL_R_N")
	)
	(segment
		(start 168.248584 -112.97539)
		(end 167.517826 -113.706148)
		(width 0.12954)
		(layer "F.Cu")
		(net "GPU_WP_HW_CTRL_R_N")
	)
	(segment
		(start 166.57828 -113.706148)
		(end 165.09873 -113.706148)
		(width 0.12954)
		(layer "F.Cu")
		(net "GPU_WP_HW_CTRL_R_N")
	)
	(segment
		(start 170.155616 -112.97539)
		(end 168.248584 -112.97539)
		(width 0.12954)
		(layer "F.Cu")
		(net "GPU_WP_HW_CTRL_R_N")
	)
	(via
		(at 166.57828 -113.706148)
		(size 0.762)
		(drill 0.381)
		(layers "F.Cu" "B.Cu")
		(net "GPU_WP_HW_CTRL_R_N")
	)
	(segment
		(start 164.24783 -113.756948)
		(end 163.63188 -113.756948)
		(width 0.12954)
		(layer "F.Cu")
		(net "GPU_WP_HW_CTRL_N")
	)
	(segment
		(start 424.623992 -402.671534)
		(end 425.25188 -402.671534)
		(width 0.12954)
		(layer "F.Cu")
		(net "GPU_WP_HW_CTRL_N")
	)
	(segment
		(start 424.623992 -401.655534)
		(end 427.230032 -401.655534)
		(width 0.12954)
		(layer "F.Cu")
		(net "GPU_WP_HW_CTRL_N")
	)
	(segment
		(start 424.623992 -402.671534)
		(end 424.623992 -401.655534)
		(width 0.12954)
		(layer "F.Cu")
		(net "GPU_WP_HW_CTRL_N")
	)
	(via
		(at 197.78218 -125.329188)
		(size 0.508)
		(drill 0.254)
		(layers "F.Cu" "B.Cu")
		(net "GPU_WP_HW_CTRL_N")
	)
	(via
		(at 301.68088 -395.905228)
		(size 0.762)
		(drill 0.254)
		(layers "F.Cu" "B.Cu")
		(net "GPU_WP_HW_CTRL_N")
	)
	(via
		(at 163.63188 -113.756948)
		(size 0.508)
		(drill 0.254)
		(layers "F.Cu" "B.Cu")
		(net "GPU_WP_HW_CTRL_N")
	)
	(via
		(at 425.25188 -402.671534)
		(size 0.508)
		(drill 0.254)
		(layers "F.Cu" "B.Cu")
		(net "GPU_WP_HW_CTRL_N")
	)
	(via
		(at 235.00588 -207.736948)
		(size 0.508)
		(drill 0.254)
		(layers "F.Cu" "B.Cu")
		(net "GPU_WP_HW_CTRL_N")
	)
	(segment
		(start 285.165546 -393.394946)
		(end 285.165546 -391.820146)
		(width 0.127)
		(layer "In4.Cu")
		(net "GPU_WP_HW_CTRL_N")
	)
	(segment
		(start 191.095376 -123.134628)
		(end 192.629536 -124.668788)
		(width 0.127)
		(layer "In4.Cu")
		(net "GPU_WP_HW_CTRL_N")
	)
	(segment
		(start 168.1226 -113.993168)
		(end 168.1226 -121.88444)
		(width 0.127)
		(layer "In4.Cu")
		(net "GPU_WP_HW_CTRL_N")
	)
	(segment
		(start 197.78218 -125.077728)
		(end 197.78218 -125.329188)
		(width 0.127)
		(layer "In4.Cu")
		(net "GPU_WP_HW_CTRL_N")
	)
	(segment
		(start 168.1226 -121.88444)
		(end 169.812208 -123.574048)
		(width 0.127)
		(layer "In4.Cu")
		(net "GPU_WP_HW_CTRL_N")
	)
	(segment
		(start 163.63188 -113.756948)
		(end 167.88638 -113.756948)
		(width 0.127)
		(layer "In4.Cu")
		(net "GPU_WP_HW_CTRL_N")
	)
	(segment
		(start 288.1376 -395.605)
		(end 287.3756 -395.605)
		(width 0.127)
		(layer "In4.Cu")
		(net "GPU_WP_HW_CTRL_N")
	)
	(segment
		(start 167.88638 -113.756948)
		(end 168.1226 -113.993168)
		(width 0.127)
		(layer "In4.Cu")
		(net "GPU_WP_HW_CTRL_N")
	)
	(segment
		(start 182.60314 -123.134628)
		(end 191.095376 -123.134628)
		(width 0.127)
		(layer "In4.Cu")
		(net "GPU_WP_HW_CTRL_N")
	)
	(segment
		(start 272.92554 -361.74807)
		(end 241.008154 -329.830684)
		(width 0.127)
		(layer "In4.Cu")
		(net "GPU_WP_HW_CTRL_N")
	)
	(segment
		(start 272.92554 -379.58014)
		(end 272.92554 -361.74807)
		(width 0.127)
		(layer "In4.Cu")
		(net "GPU_WP_HW_CTRL_N")
	)
	(segment
		(start 246.08028 -273.230086)
		(end 246.08028 -218.811348)
		(width 0.127)
		(layer "In4.Cu")
		(net "GPU_WP_HW_CTRL_N")
	)
	(segment
		(start 192.629536 -124.668788)
		(end 197.37324 -124.668788)
		(width 0.127)
		(layer "In4.Cu")
		(net "GPU_WP_HW_CTRL_N")
	)
	(segment
		(start 288.6202 -395.1224)
		(end 288.1376 -395.605)
		(width 0.127)
		(layer "In4.Cu")
		(net "GPU_WP_HW_CTRL_N")
	)
	(segment
		(start 181.96814 -122.499628)
		(end 182.60314 -123.134628)
		(width 0.127)
		(layer "In4.Cu")
		(net "GPU_WP_HW_CTRL_N")
	)
	(segment
		(start 241.008154 -278.302212)
		(end 246.08028 -273.230086)
		(width 0.127)
		(layer "In4.Cu")
		(net "GPU_WP_HW_CTRL_N")
	)
	(segment
		(start 301.68088 -395.905228)
		(end 290.011104 -395.905228)
		(width 0.127)
		(layer "In4.Cu")
		(net "GPU_WP_HW_CTRL_N")
	)
	(segment
		(start 180.81498 -122.679968)
		(end 180.99532 -122.499628)
		(width 0.127)
		(layer "In4.Cu")
		(net "GPU_WP_HW_CTRL_N")
	)
	(segment
		(start 177.87366 -123.574048)
		(end 178.76774 -122.679968)
		(width 0.127)
		(layer "In4.Cu")
		(net "GPU_WP_HW_CTRL_N")
	)
	(segment
		(start 287.3756 -395.605)
		(end 285.165546 -393.394946)
		(width 0.127)
		(layer "In4.Cu")
		(net "GPU_WP_HW_CTRL_N")
	)
	(segment
		(start 290.011104 -395.905228)
		(end 289.228276 -395.1224)
		(width 0.127)
		(layer "In4.Cu")
		(net "GPU_WP_HW_CTRL_N")
	)
	(segment
		(start 289.228276 -395.1224)
		(end 288.6202 -395.1224)
		(width 0.127)
		(layer "In4.Cu")
		(net "GPU_WP_HW_CTRL_N")
	)
	(segment
		(start 180.99532 -122.499628)
		(end 181.96814 -122.499628)
		(width 0.127)
		(layer "In4.Cu")
		(net "GPU_WP_HW_CTRL_N")
	)
	(segment
		(start 197.37324 -124.668788)
		(end 197.78218 -125.077728)
		(width 0.127)
		(layer "In4.Cu")
		(net "GPU_WP_HW_CTRL_N")
	)
	(segment
		(start 285.165546 -391.820146)
		(end 272.92554 -379.58014)
		(width 0.127)
		(layer "In4.Cu")
		(net "GPU_WP_HW_CTRL_N")
	)
	(segment
		(start 241.008154 -329.830684)
		(end 241.008154 -278.302212)
		(width 0.127)
		(layer "In4.Cu")
		(net "GPU_WP_HW_CTRL_N")
	)
	(segment
		(start 246.08028 -218.811348)
		(end 235.00588 -207.736948)
		(width 0.127)
		(layer "In4.Cu")
		(net "GPU_WP_HW_CTRL_N")
	)
	(segment
		(start 178.76774 -122.679968)
		(end 180.81498 -122.679968)
		(width 0.127)
		(layer "In4.Cu")
		(net "GPU_WP_HW_CTRL_N")
	)
	(segment
		(start 169.812208 -123.574048)
		(end 177.87366 -123.574048)
		(width 0.127)
		(layer "In4.Cu")
		(net "GPU_WP_HW_CTRL_N")
	)
	(segment
		(start 199.1868 -134.297928)
		(end 197.88632 -132.997448)
		(width 0.127)
		(layer "In11.Cu")
		(net "GPU_WP_HW_CTRL_N")
	)
	(segment
		(start 213.506812 -159.306514)
		(end 213.506812 -149.55647)
		(width 0.127)
		(layer "In11.Cu")
		(net "GPU_WP_HW_CTRL_N")
	)
	(segment
		(start 235.00588 -207.736948)
		(end 235.00588 -204.180948)
		(width 0.127)
		(layer "In11.Cu")
		(net "GPU_WP_HW_CTRL_N")
	)
	(segment
		(start 197.88632 -125.433328)
		(end 197.78218 -125.329188)
		(width 0.127)
		(layer "In11.Cu")
		(net "GPU_WP_HW_CTRL_N")
	)
	(segment
		(start 429.41748 -399.532348)
		(end 426.77588 -399.532348)
		(width 0.127)
		(layer "In11.Cu")
		(net "GPU_WP_HW_CTRL_N")
	)
	(segment
		(start 373.9007 -398.135348)
		(end 371.52326 -395.757908)
		(width 0.127)
		(layer "In11.Cu")
		(net "GPU_WP_HW_CTRL_N")
	)
	(segment
		(start 227.32238 -173.122082)
		(end 213.506812 -159.306514)
		(width 0.127)
		(layer "In11.Cu")
		(net "GPU_WP_HW_CTRL_N")
	)
	(segment
		(start 227.32238 -196.497448)
		(end 227.32238 -173.122082)
		(width 0.127)
		(layer "In11.Cu")
		(net "GPU_WP_HW_CTRL_N")
	)
	(segment
		(start 366.35182 -395.757908)
		(end 365.9251 -396.184628)
		(width 0.127)
		(layer "In11.Cu")
		(net "GPU_WP_HW_CTRL_N")
	)
	(segment
		(start 235.00588 -204.180948)
		(end 227.32238 -196.497448)
		(width 0.127)
		(layer "In11.Cu")
		(net "GPU_WP_HW_CTRL_N")
	)
	(segment
		(start 197.88632 -132.997448)
		(end 197.88632 -125.433328)
		(width 0.127)
		(layer "In11.Cu")
		(net "GPU_WP_HW_CTRL_N")
	)
	(segment
		(start 355.737414 -395.905228)
		(end 301.68088 -395.905228)
		(width 0.127)
		(layer "In11.Cu")
		(net "GPU_WP_HW_CTRL_N")
	)
	(segment
		(start 426.77588 -399.532348)
		(end 425.37888 -398.135348)
		(width 0.127)
		(layer "In11.Cu")
		(net "GPU_WP_HW_CTRL_N")
	)
	(segment
		(start 430.58588 -400.700748)
		(end 429.41748 -399.532348)
		(width 0.127)
		(layer "In11.Cu")
		(net "GPU_WP_HW_CTRL_N")
	)
	(segment
		(start 356.016814 -396.184628)
		(end 355.737414 -395.905228)
		(width 0.127)
		(layer "In11.Cu")
		(net "GPU_WP_HW_CTRL_N")
	)
	(segment
		(start 371.52326 -395.757908)
		(end 366.35182 -395.757908)
		(width 0.127)
		(layer "In11.Cu")
		(net "GPU_WP_HW_CTRL_N")
	)
	(segment
		(start 430.58588 -402.173948)
		(end 430.58588 -400.700748)
		(width 0.127)
		(layer "In11.Cu")
		(net "GPU_WP_HW_CTRL_N")
	)
	(segment
		(start 213.506812 -149.55647)
		(end 199.1868 -135.236458)
		(width 0.127)
		(layer "In11.Cu")
		(net "GPU_WP_HW_CTRL_N")
	)
	(segment
		(start 365.9251 -396.184628)
		(end 356.016814 -396.184628)
		(width 0.127)
		(layer "In11.Cu")
		(net "GPU_WP_HW_CTRL_N")
	)
	(segment
		(start 425.592494 -403.012148)
		(end 429.74768 -403.012148)
		(width 0.127)
		(layer "In11.Cu")
		(net "GPU_WP_HW_CTRL_N")
	)
	(segment
		(start 199.1868 -135.236458)
		(end 199.1868 -134.297928)
		(width 0.127)
		(layer "In11.Cu")
		(net "GPU_WP_HW_CTRL_N")
	)
	(segment
		(start 429.74768 -403.012148)
		(end 430.58588 -402.173948)
		(width 0.127)
		(layer "In11.Cu")
		(net "GPU_WP_HW_CTRL_N")
	)
	(segment
		(start 425.25188 -402.671534)
		(end 425.592494 -403.012148)
		(width 0.127)
		(layer "In11.Cu")
		(net "GPU_WP_HW_CTRL_N")
	)
	(segment
		(start 425.37888 -398.135348)
		(end 373.9007 -398.135348)
		(width 0.127)
		(layer "In11.Cu")
		(net "GPU_WP_HW_CTRL_N")
	)
	(segment
		(start 431.828956 -402.30552)
		(end 431.843942 -402.290534)
		(width 0.12954)
		(layer "F.Cu")
		(net "GPU_WP_HW_CTRL_ISO")
	)
	(segment
		(start 429.129952 -402.30552)
		(end 431.828956 -402.30552)
		(width 0.12954)
		(layer "F.Cu")
		(net "GPU_WP_HW_CTRL_ISO")
	)
	(segment
		(start 426.27042 -403.997668)
		(end 430.136808 -403.997668)
		(width 0.12954)
		(layer "F.Cu")
		(net "GPU_WP_HW_CTRL_ISO")
	)
	(segment
		(start 430.136808 -403.997668)
		(end 431.828956 -402.30552)
		(width 0.12954)
		(layer "F.Cu")
		(net "GPU_WP_HW_CTRL_ISO")
	)
	(via
		(at 426.27042 -403.997668)
		(size 0.508)
		(drill 0.254)
		(layers "F.Cu" "B.Cu")
		(net "GPU_WP_HW_CTRL_ISO")
	)
	(segment
		(start 402.75002 -440.489848)
		(end 402.9075 -440.489848)
		(width 0.12954)
		(layer "B.Cu")
		(net "GPU_WP_HW_CTRL_ISO")
	)
	(segment
		(start 426.27042 -407.099008)
		(end 426.27042 -403.997668)
		(width 0.12954)
		(layer "B.Cu")
		(net "GPU_WP_HW_CTRL_ISO")
	)
	(segment
		(start 403.87524 -439.522108)
		(end 403.87524 -423.530268)
		(width 0.12954)
		(layer "B.Cu")
		(net "GPU_WP_HW_CTRL_ISO")
	)
	(segment
		(start 405.02586 -422.379648)
		(end 410.98978 -422.379648)
		(width 0.12954)
		(layer "B.Cu")
		(net "GPU_WP_HW_CTRL_ISO")
	)
	(segment
		(start 403.87524 -423.530268)
		(end 405.02586 -422.379648)
		(width 0.12954)
		(layer "B.Cu")
		(net "GPU_WP_HW_CTRL_ISO")
	)
	(segment
		(start 402.9075 -440.489848)
		(end 403.87524 -439.522108)
		(width 0.12954)
		(layer "B.Cu")
		(net "GPU_WP_HW_CTRL_ISO")
	)
	(segment
		(start 410.98978 -422.379648)
		(end 426.27042 -407.099008)
		(width 0.12954)
		(layer "B.Cu")
		(net "GPU_WP_HW_CTRL_ISO")
	)
	(segment
		(start 173.355762 -112.97539)
		(end 172.955712 -112.57534)
		(width 0.12954)
		(layer "F.Cu")
		(net "GPU_PRSNT_N_ISO_R")
	)
	(via
		(at 166.1922 -113.538508)
		(size 0.6604)
		(drill 0.3302)
		(layers "F.Cu" "B.Cu")
		(net "GPU_PRSNT_N_ISO_R")
	)
	(via
		(at 172.955712 -112.57534)
		(size 0.4572)
		(drill 0.254)
		(layers "F.Cu" "B.Cu")
		(net "GPU_PRSNT_N_ISO_R")
	)
	(segment
		(start 172.5549 -112.174528)
		(end 172.955712 -112.57534)
		(width 0.12954)
		(layer "B.Cu")
		(net "GPU_PRSNT_N_ISO_R")
	)
	(segment
		(start 172.41774 -111.379508)
		(end 172.5549 -111.516668)
		(width 0.12954)
		(layer "B.Cu")
		(net "GPU_PRSNT_N_ISO_R")
	)
	(segment
		(start 165.26637 -113.538508)
		(end 166.1922 -113.538508)
		(width 0.12954)
		(layer "B.Cu")
		(net "GPU_PRSNT_N_ISO_R")
	)
	(segment
		(start 165.04793 -113.756948)
		(end 165.26637 -113.538508)
		(width 0.12954)
		(layer "B.Cu")
		(net "GPU_PRSNT_N_ISO_R")
	)
	(segment
		(start 170.949874 -111.602774)
		(end 171.17314 -111.379508)
		(width 0.12954)
		(layer "B.Cu")
		(net "GPU_PRSNT_N_ISO_R")
	)
	(segment
		(start 170.789092 -113.538508)
		(end 170.949874 -113.377726)
		(width 0.12954)
		(layer "B.Cu")
		(net "GPU_PRSNT_N_ISO_R")
	)
	(segment
		(start 170.949874 -113.377726)
		(end 170.949874 -111.602774)
		(width 0.12954)
		(layer "B.Cu")
		(net "GPU_PRSNT_N_ISO_R")
	)
	(segment
		(start 172.5549 -111.516668)
		(end 172.5549 -112.174528)
		(width 0.12954)
		(layer "B.Cu")
		(net "GPU_PRSNT_N_ISO_R")
	)
	(segment
		(start 166.1922 -113.538508)
		(end 170.789092 -113.538508)
		(width 0.12954)
		(layer "B.Cu")
		(net "GPU_PRSNT_N_ISO_R")
	)
	(segment
		(start 171.17314 -111.379508)
		(end 172.41774 -111.379508)
		(width 0.12954)
		(layer "B.Cu")
		(net "GPU_PRSNT_N_ISO_R")
	)
	(segment
		(start 26.126948 -410.784548)
		(end 26.0096 -410.6672)
		(width 0.12954)
		(layer "F.Cu")
		(net "GPU_PRSNT_N_ISO")
	)
	(segment
		(start 30.186122 -409.44165)
		(end 31.4325 -410.688028)
		(width 0.12954)
		(layer "F.Cu")
		(net "GPU_PRSNT_N_ISO")
	)
	(segment
		(start 26.6446 -409.44165)
		(end 26.6446 -409.8544)
		(width 0.12954)
		(layer "F.Cu")
		(net "GPU_PRSNT_N_ISO")
	)
	(segment
		(start 89.720674 -415.98342)
		(end 78.26502 -415.98342)
		(width 0.12954)
		(layer "F.Cu")
		(net "GPU_PRSNT_N_ISO")
	)
	(segment
		(start 26.7716 -409.9814)
		(end 26.9748 -409.9814)
		(width 0.12954)
		(layer "F.Cu")
		(net "GPU_PRSNT_N_ISO")
	)
	(segment
		(start 48.128428 -410.688028)
		(end 31.4325 -410.688028)
		(width 0.12954)
		(layer "F.Cu")
		(net "GPU_PRSNT_N_ISO")
	)
	(segment
		(start 26.9748 -409.9814)
		(end 27.131772 -410.138372)
		(width 0.12954)
		(layer "F.Cu")
		(net "GPU_PRSNT_N_ISO")
	)
	(segment
		(start 27.131772 -410.138372)
		(end 27.131772 -410.784548)
		(width 0.12954)
		(layer "F.Cu")
		(net "GPU_PRSNT_N_ISO")
	)
	(segment
		(start 27.131772 -410.784548)
		(end 26.126948 -410.784548)
		(width 0.12954)
		(layer "F.Cu")
		(net "GPU_PRSNT_N_ISO")
	)
	(segment
		(start 26.6446 -409.44165)
		(end 27.6352 -409.44165)
		(width 0.12954)
		(layer "F.Cu")
		(net "GPU_PRSNT_N_ISO")
	)
	(segment
		(start 27.6352 -409.44165)
		(end 30.186122 -409.44165)
		(width 0.12954)
		(layer "F.Cu")
		(net "GPU_PRSNT_N_ISO")
	)
	(segment
		(start 26.0096 -410.6672)
		(end 26.0096 -410.1084)
		(width 0.12954)
		(layer "F.Cu")
		(net "GPU_PRSNT_N_ISO")
	)
	(segment
		(start 24.7142 -408.813)
		(end 20.1676 -408.813)
		(width 0.12954)
		(layer "F.Cu")
		(net "GPU_PRSNT_N_ISO")
	)
	(segment
		(start 26.0096 -410.1084)
		(end 24.7142 -408.813)
		(width 0.12954)
		(layer "F.Cu")
		(net "GPU_PRSNT_N_ISO")
	)
	(segment
		(start 48.5394 -411.099)
		(end 48.128428 -410.688028)
		(width 0.12954)
		(layer "F.Cu")
		(net "GPU_PRSNT_N_ISO")
	)
	(segment
		(start 73.3806 -411.099)
		(end 48.5394 -411.099)
		(width 0.12954)
		(layer "F.Cu")
		(net "GPU_PRSNT_N_ISO")
	)
	(segment
		(start 20.1676 -408.813)
		(end 19.812 -409.1686)
		(width 0.12954)
		(layer "F.Cu")
		(net "GPU_PRSNT_N_ISO")
	)
	(segment
		(start 26.6446 -409.8544)
		(end 26.7716 -409.9814)
		(width 0.12954)
		(layer "F.Cu")
		(net "GPU_PRSNT_N_ISO")
	)
	(segment
		(start 19.812 -409.1686)
		(end 19.812 -410.39415)
		(width 0.12954)
		(layer "F.Cu")
		(net "GPU_PRSNT_N_ISO")
	)
	(segment
		(start 92.583254 -418.846)
		(end 89.720674 -415.98342)
		(width 0.12954)
		(layer "F.Cu")
		(net "GPU_PRSNT_N_ISO")
	)
	(segment
		(start 93.1418 -418.846)
		(end 92.583254 -418.846)
		(width 0.12954)
		(layer "F.Cu")
		(net "GPU_PRSNT_N_ISO")
	)
	(segment
		(start 78.26502 -415.98342)
		(end 73.3806 -411.099)
		(width 0.12954)
		(layer "F.Cu")
		(net "GPU_PRSNT_N_ISO")
	)
	(via
		(at 235.772198 -209.510376)
		(size 0.508)
		(drill 0.254)
		(layers "F.Cu" "B.Cu")
		(net "GPU_PRSNT_N_ISO")
	)
	(via
		(at 31.4325 -410.688028)
		(size 0.762)
		(drill 0.381)
		(layers "F.Cu" "B.Cu")
		(net "GPU_PRSNT_N_ISO")
	)
	(via
		(at 162.79368 -113.756948)
		(size 0.508)
		(drill 0.254)
		(layers "F.Cu" "B.Cu")
		(net "GPU_PRSNT_N_ISO")
	)
	(via
		(at 197.14718 -125.329188)
		(size 0.508)
		(drill 0.254)
		(layers "F.Cu" "B.Cu")
		(net "GPU_PRSNT_N_ISO")
	)
	(via
		(at 93.1418 -418.846)
		(size 0.508)
		(drill 0.254)
		(layers "F.Cu" "B.Cu")
		(net "GPU_PRSNT_N_ISO")
	)
	(via
		(at 172.4406 -405.2316)
		(size 0.508)
		(drill 0.254)
		(layers "F.Cu" "B.Cu")
		(net "GPU_PRSNT_N_ISO")
	)
	(via
		(at 295.422066 -406.775666)
		(size 0.508)
		(drill 0.254)
		(layers "F.Cu" "B.Cu")
		(net "GPU_PRSNT_N_ISO")
	)
	(via
		(at 304.402744 -396.509748)
		(size 0.508)
		(drill 0.254)
		(layers "F.Cu" "B.Cu")
		(net "GPU_PRSNT_N_ISO")
	)
	(segment
		(start 163.93668 -113.121948)
		(end 164.24783 -113.433098)
		(width 0.12954)
		(layer "B.Cu")
		(net "GPU_PRSNT_N_ISO")
	)
	(segment
		(start 164.24783 -113.433098)
		(end 164.24783 -113.756948)
		(width 0.12954)
		(layer "B.Cu")
		(net "GPU_PRSNT_N_ISO")
	)
	(segment
		(start 162.79368 -113.756948)
		(end 162.79368 -113.401348)
		(width 0.12954)
		(layer "B.Cu")
		(net "GPU_PRSNT_N_ISO")
	)
	(segment
		(start 162.79368 -113.401348)
		(end 163.07308 -113.121948)
		(width 0.12954)
		(layer "B.Cu")
		(net "GPU_PRSNT_N_ISO")
	)
	(segment
		(start 163.07308 -113.121948)
		(end 163.93668 -113.121948)
		(width 0.12954)
		(layer "B.Cu")
		(net "GPU_PRSNT_N_ISO")
	)
	(segment
		(start 260.874764 -381.245364)
		(end 264.3124 -384.683)
		(width 0.127)
		(layer "In4.Cu")
		(net "GPU_PRSNT_N_ISO")
	)
	(segment
		(start 286.9692 -396.337028)
		(end 299.95876 -396.337028)
		(width 0.127)
		(layer "In4.Cu")
		(net "GPU_PRSNT_N_ISO")
	)
	(segment
		(start 272.59534 -362.272834)
		(end 272.59534 -379.7808)
		(width 0.127)
		(layer "In4.Cu")
		(net "GPU_PRSNT_N_ISO")
	)
	(segment
		(start 172.4406 -405.2316)
		(end 172.1612 -405.2316)
		(width 0.127)
		(layer "In4.Cu")
		(net "GPU_PRSNT_N_ISO")
	)
	(segment
		(start 240.403634 -278.051768)
		(end 240.403634 -330.081128)
		(width 0.127)
		(layer "In4.Cu")
		(net "GPU_PRSNT_N_ISO")
	)
	(segment
		(start 173.4058 -401.8788)
		(end 173.4058 -398.4752)
		(width 0.127)
		(layer "In4.Cu")
		(net "GPU_PRSNT_N_ISO")
	)
	(segment
		(start 245.75008 -219.488258)
		(end 245.75008 -272.705322)
		(width 0.127)
		(layer "In4.Cu")
		(net "GPU_PRSNT_N_ISO")
	)
	(segment
		(start 182.74538 -123.510548)
		(end 182.61584 -123.640088)
		(width 0.127)
		(layer "In4.Cu")
		(net "GPU_PRSNT_N_ISO")
	)
	(segment
		(start 277.51278 -387.1214)
		(end 282.5242 -392.13282)
		(width 0.127)
		(layer "In4.Cu")
		(net "GPU_PRSNT_N_ISO")
	)
	(segment
		(start 167.73398 -114.625628)
		(end 167.40886 -114.300508)
		(width 0.127)
		(layer "In4.Cu")
		(net "GPU_PRSNT_N_ISO")
	)
	(segment
		(start 299.95876 -396.337028)
		(end 300.13148 -396.509748)
		(width 0.127)
		(layer "In4.Cu")
		(net "GPU_PRSNT_N_ISO")
	)
	(segment
		(start 286.13862 -397.97482)
		(end 295.10482 -397.97482)
		(width 0.127)
		(layer "In4.Cu")
		(net "GPU_PRSNT_N_ISO")
	)
	(segment
		(start 172.94606 -402.33854)
		(end 173.4058 -401.8788)
		(width 0.127)
		(layer "In4.Cu")
		(net "GPU_PRSNT_N_ISO")
	)
	(segment
		(start 176.6316 -395.2494)
		(end 176.6316 -388.095744)
		(width 0.127)
		(layer "In4.Cu")
		(net "GPU_PRSNT_N_ISO")
	)
	(segment
		(start 284.732476 -394.100304)
		(end 286.9692 -396.337028)
		(width 0.127)
		(layer "In4.Cu")
		(net "GPU_PRSNT_N_ISO")
	)
	(segment
		(start 171.4754 -404.5458)
		(end 171.4754 -402.7424)
		(width 0.127)
		(layer "In4.Cu")
		(net "GPU_PRSNT_N_ISO")
	)
	(segment
		(start 272.59534 -379.7808)
		(end 284.732476 -391.917936)
		(width 0.127)
		(layer "In4.Cu")
		(net "GPU_PRSNT_N_ISO")
	)
	(segment
		(start 193.243708 -125.806708)
		(end 190.947548 -123.510548)
		(width 0.127)
		(layer "In4.Cu")
		(net "GPU_PRSNT_N_ISO")
	)
	(segment
		(start 171.87926 -402.33854)
		(end 172.94606 -402.33854)
		(width 0.127)
		(layer "In4.Cu")
		(net "GPU_PRSNT_N_ISO")
	)
	(segment
		(start 284.732476 -391.917936)
		(end 284.732476 -394.100304)
		(width 0.127)
		(layer "In4.Cu")
		(net "GPU_PRSNT_N_ISO")
	)
	(segment
		(start 176.6316 -388.095744)
		(end 183.48198 -381.245364)
		(width 0.127)
		(layer "In4.Cu")
		(net "GPU_PRSNT_N_ISO")
	)
	(segment
		(start 195.43522 -125.329188)
		(end 194.9577 -125.806708)
		(width 0.127)
		(layer "In4.Cu")
		(net "GPU_PRSNT_N_ISO")
	)
	(segment
		(start 245.75008 -272.705322)
		(end 240.403634 -278.051768)
		(width 0.127)
		(layer "In4.Cu")
		(net "GPU_PRSNT_N_ISO")
	)
	(segment
		(start 169.651172 -123.962668)
		(end 167.73398 -122.045476)
		(width 0.127)
		(layer "In4.Cu")
		(net "GPU_PRSNT_N_ISO")
	)
	(segment
		(start 197.14718 -125.329188)
		(end 195.43522 -125.329188)
		(width 0.127)
		(layer "In4.Cu")
		(net "GPU_PRSNT_N_ISO")
	)
	(segment
		(start 267.8176 -384.683)
		(end 270.256 -387.1214)
		(width 0.127)
		(layer "In4.Cu")
		(net "GPU_PRSNT_N_ISO")
	)
	(segment
		(start 240.403634 -330.081128)
		(end 272.59534 -362.272834)
		(width 0.127)
		(layer "In4.Cu")
		(net "GPU_PRSNT_N_ISO")
	)
	(segment
		(start 172.1612 -405.2316)
		(end 171.4754 -404.5458)
		(width 0.127)
		(layer "In4.Cu")
		(net "GPU_PRSNT_N_ISO")
	)
	(segment
		(start 296.672 -405.525732)
		(end 295.422066 -406.775666)
		(width 0.127)
		(layer "In4.Cu")
		(net "GPU_PRSNT_N_ISO")
	)
	(segment
		(start 167.73398 -122.045476)
		(end 167.73398 -114.625628)
		(width 0.127)
		(layer "In4.Cu")
		(net "GPU_PRSNT_N_ISO")
	)
	(segment
		(start 171.4754 -402.7424)
		(end 171.87926 -402.33854)
		(width 0.127)
		(layer "In4.Cu")
		(net "GPU_PRSNT_N_ISO")
	)
	(segment
		(start 182.61584 -123.640088)
		(end 178.52136 -123.640088)
		(width 0.127)
		(layer "In4.Cu")
		(net "GPU_PRSNT_N_ISO")
	)
	(segment
		(start 296.672 -399.542)
		(end 296.672 -405.525732)
		(width 0.127)
		(layer "In4.Cu")
		(net "GPU_PRSNT_N_ISO")
	)
	(segment
		(start 270.256 -387.1214)
		(end 277.51278 -387.1214)
		(width 0.127)
		(layer "In4.Cu")
		(net "GPU_PRSNT_N_ISO")
	)
	(segment
		(start 173.4058 -398.4752)
		(end 176.6316 -395.2494)
		(width 0.127)
		(layer "In4.Cu")
		(net "GPU_PRSNT_N_ISO")
	)
	(segment
		(start 194.9577 -125.806708)
		(end 193.243708 -125.806708)
		(width 0.127)
		(layer "In4.Cu")
		(net "GPU_PRSNT_N_ISO")
	)
	(segment
		(start 295.10482 -397.97482)
		(end 296.672 -399.542)
		(width 0.127)
		(layer "In4.Cu")
		(net "GPU_PRSNT_N_ISO")
	)
	(segment
		(start 264.3124 -384.683)
		(end 267.8176 -384.683)
		(width 0.127)
		(layer "In4.Cu")
		(net "GPU_PRSNT_N_ISO")
	)
	(segment
		(start 162.79368 -114.010948)
		(end 162.79368 -113.756948)
		(width 0.127)
		(layer "In4.Cu")
		(net "GPU_PRSNT_N_ISO")
	)
	(segment
		(start 163.08324 -114.300508)
		(end 162.79368 -114.010948)
		(width 0.127)
		(layer "In4.Cu")
		(net "GPU_PRSNT_N_ISO")
	)
	(segment
		(start 167.40886 -114.300508)
		(end 163.08324 -114.300508)
		(width 0.127)
		(layer "In4.Cu")
		(net "GPU_PRSNT_N_ISO")
	)
	(segment
		(start 178.52136 -123.640088)
		(end 178.19878 -123.962668)
		(width 0.127)
		(layer "In4.Cu")
		(net "GPU_PRSNT_N_ISO")
	)
	(segment
		(start 178.19878 -123.962668)
		(end 169.651172 -123.962668)
		(width 0.127)
		(layer "In4.Cu")
		(net "GPU_PRSNT_N_ISO")
	)
	(segment
		(start 282.5242 -394.3604)
		(end 286.13862 -397.97482)
		(width 0.127)
		(layer "In4.Cu")
		(net "GPU_PRSNT_N_ISO")
	)
	(segment
		(start 190.947548 -123.510548)
		(end 182.74538 -123.510548)
		(width 0.127)
		(layer "In4.Cu")
		(net "GPU_PRSNT_N_ISO")
	)
	(segment
		(start 235.772198 -209.510376)
		(end 245.75008 -219.488258)
		(width 0.127)
		(layer "In4.Cu")
		(net "GPU_PRSNT_N_ISO")
	)
	(segment
		(start 300.13148 -396.509748)
		(end 304.402744 -396.509748)
		(width 0.127)
		(layer "In4.Cu")
		(net "GPU_PRSNT_N_ISO")
	)
	(segment
		(start 183.48198 -381.245364)
		(end 260.874764 -381.245364)
		(width 0.127)
		(layer "In4.Cu")
		(net "GPU_PRSNT_N_ISO")
	)
	(segment
		(start 282.5242 -392.13282)
		(end 282.5242 -394.3604)
		(width 0.127)
		(layer "In4.Cu")
		(net "GPU_PRSNT_N_ISO")
	)
	(segment
		(start 170.8404 -405.2316)
		(end 170.7134 -405.3586)
		(width 0.127)
		(layer "In6.Cu")
		(net "GPU_PRSNT_N_ISO")
	)
	(segment
		(start 170.7134 -407.473658)
		(end 169.272458 -408.9146)
		(width 0.127)
		(layer "In6.Cu")
		(net "GPU_PRSNT_N_ISO")
	)
	(segment
		(start 120.4468 -409.448)
		(end 120.4468 -417.119054)
		(width 0.127)
		(layer "In6.Cu")
		(net "GPU_PRSNT_N_ISO")
	)
	(segment
		(start 108.4326 -420.6748)
		(end 108.3056 -420.8018)
		(width 0.127)
		(layer "In6.Cu")
		(net "GPU_PRSNT_N_ISO")
	)
	(segment
		(start 120.4468 -417.119054)
		(end 116.891054 -420.6748)
		(width 0.127)
		(layer "In6.Cu")
		(net "GPU_PRSNT_N_ISO")
	)
	(segment
		(start 97.917 -426.6692)
		(end 96.3422 -428.244)
		(width 0.127)
		(layer "In6.Cu")
		(net "GPU_PRSNT_N_ISO")
	)
	(segment
		(start 108.3056 -425.323)
		(end 106.9594 -426.6692)
		(width 0.127)
		(layer "In6.Cu")
		(net "GPU_PRSNT_N_ISO")
	)
	(segment
		(start 96.3422 -428.244)
		(end 93.7768 -428.244)
		(width 0.127)
		(layer "In6.Cu")
		(net "GPU_PRSNT_N_ISO")
	)
	(segment
		(start 93.7768 -428.244)
		(end 93.1418 -427.609)
		(width 0.127)
		(layer "In6.Cu")
		(net "GPU_PRSNT_N_ISO")
	)
	(segment
		(start 172.4406 -405.2316)
		(end 170.8404 -405.2316)
		(width 0.127)
		(layer "In6.Cu")
		(net "GPU_PRSNT_N_ISO")
	)
	(segment
		(start 116.891054 -420.6748)
		(end 108.4326 -420.6748)
		(width 0.127)
		(layer "In6.Cu")
		(net "GPU_PRSNT_N_ISO")
	)
	(segment
		(start 93.1418 -427.609)
		(end 93.1418 -418.846)
		(width 0.127)
		(layer "In6.Cu")
		(net "GPU_PRSNT_N_ISO")
	)
	(segment
		(start 108.3056 -420.8018)
		(end 108.3056 -425.323)
		(width 0.127)
		(layer "In6.Cu")
		(net "GPU_PRSNT_N_ISO")
	)
	(segment
		(start 170.7134 -405.3586)
		(end 170.7134 -407.473658)
		(width 0.127)
		(layer "In6.Cu")
		(net "GPU_PRSNT_N_ISO")
	)
	(segment
		(start 120.9802 -408.9146)
		(end 120.4468 -409.448)
		(width 0.127)
		(layer "In6.Cu")
		(net "GPU_PRSNT_N_ISO")
	)
	(segment
		(start 106.9594 -426.6692)
		(end 97.917 -426.6692)
		(width 0.127)
		(layer "In6.Cu")
		(net "GPU_PRSNT_N_ISO")
	)
	(segment
		(start 169.272458 -408.9146)
		(end 120.9802 -408.9146)
		(width 0.127)
		(layer "In6.Cu")
		(net "GPU_PRSNT_N_ISO")
	)
	(segment
		(start 297.814492 -406.1714)
		(end 299.592746 -404.393146)
		(width 0.127)
		(layer "In11.Cu")
		(net "GPU_PRSNT_N_ISO")
	)
	(segment
		(start 295.422066 -406.775666)
		(end 296.026332 -406.1714)
		(width 0.127)
		(layer "In11.Cu")
		(net "GPU_PRSNT_N_ISO")
	)
	(segment
		(start 235.772198 -209.510376)
		(end 234.37088 -208.109058)
		(width 0.127)
		(layer "In11.Cu")
		(net "GPU_PRSNT_N_ISO")
	)
	(segment
		(start 197.14718 -125.956568)
		(end 197.14718 -125.329188)
		(width 0.127)
		(layer "In11.Cu")
		(net "GPU_PRSNT_N_ISO")
	)
	(segment
		(start 226.868228 -196.510402)
		(end 226.868228 -173.310296)
		(width 0.127)
		(layer "In11.Cu")
		(net "GPU_PRSNT_N_ISO")
	)
	(segment
		(start 197.4469 -133.025388)
		(end 197.4469 -126.256288)
		(width 0.127)
		(layer "In11.Cu")
		(net "GPU_PRSNT_N_ISO")
	)
	(segment
		(start 198.8566 -135.373364)
		(end 198.8566 -134.435088)
		(width 0.127)
		(layer "In11.Cu")
		(net "GPU_PRSNT_N_ISO")
	)
	(segment
		(start 299.592746 -404.393146)
		(end 299.592746 -397.002254)
		(width 0.127)
		(layer "In11.Cu")
		(net "GPU_PRSNT_N_ISO")
	)
	(segment
		(start 234.37088 -208.109058)
		(end 234.37088 -204.013054)
		(width 0.127)
		(layer "In11.Cu")
		(net "GPU_PRSNT_N_ISO")
	)
	(segment
		(start 213.05266 -149.569424)
		(end 198.8566 -135.373364)
		(width 0.127)
		(layer "In11.Cu")
		(net "GPU_PRSNT_N_ISO")
	)
	(segment
		(start 299.592746 -397.002254)
		(end 300.085252 -396.509748)
		(width 0.127)
		(layer "In11.Cu")
		(net "GPU_PRSNT_N_ISO")
	)
	(segment
		(start 213.05266 -159.494728)
		(end 213.05266 -149.569424)
		(width 0.127)
		(layer "In11.Cu")
		(net "GPU_PRSNT_N_ISO")
	)
	(segment
		(start 198.8566 -134.435088)
		(end 197.4469 -133.025388)
		(width 0.127)
		(layer "In11.Cu")
		(net "GPU_PRSNT_N_ISO")
	)
	(segment
		(start 197.4469 -126.256288)
		(end 197.14718 -125.956568)
		(width 0.127)
		(layer "In11.Cu")
		(net "GPU_PRSNT_N_ISO")
	)
	(segment
		(start 234.37088 -204.013054)
		(end 226.868228 -196.510402)
		(width 0.127)
		(layer "In11.Cu")
		(net "GPU_PRSNT_N_ISO")
	)
	(segment
		(start 296.026332 -406.1714)
		(end 297.814492 -406.1714)
		(width 0.127)
		(layer "In11.Cu")
		(net "GPU_PRSNT_N_ISO")
	)
	(segment
		(start 300.085252 -396.509748)
		(end 304.402744 -396.509748)
		(width 0.127)
		(layer "In11.Cu")
		(net "GPU_PRSNT_N_ISO")
	)
	(segment
		(start 226.868228 -173.310296)
		(end 213.05266 -159.494728)
		(width 0.127)
		(layer "In11.Cu")
		(net "GPU_PRSNT_N_ISO")
	)
	(segment
		(start 25.795732 -411.434534)
		(end 24.469852 -411.434534)
		(width 0.12954)
		(layer "F.Cu")
		(net "GPU_PRSNT_N")
	)
	(segment
		(start 25.534366 -413.515048)
		(end 24.469852 -412.450534)
		(width 0.12954)
		(layer "F.Cu")
		(net "GPU_PRSNT_N")
	)
	(segment
		(start 27.131772 -411.434534)
		(end 25.795732 -411.434534)
		(width 0.12954)
		(layer "F.Cu")
		(net "GPU_PRSNT_N")
	)
	(segment
		(start 24.469852 -412.450534)
		(end 24.469852 -411.434534)
		(width 0.12954)
		(layer "F.Cu")
		(net "GPU_PRSNT_N")
	)
	(segment
		(start 26.52522 -413.515048)
		(end 25.534366 -413.515048)
		(width 0.12954)
		(layer "F.Cu")
		(net "GPU_PRSNT_N")
	)
	(via
		(at 96.539558 -420.128446)
		(size 0.508)
		(drill 0.254)
		(layers "F.Cu" "B.Cu")
		(net "GPU_PRSNT_N")
	)
	(via
		(at 26.52522 -413.515048)
		(size 0.508)
		(drill 0.254)
		(layers "F.Cu" "B.Cu")
		(net "GPU_PRSNT_N")
	)
	(via
		(at 25.795732 -411.434534)
		(size 0.762)
		(drill 0.381)
		(layers "F.Cu" "B.Cu")
		(net "GPU_PRSNT_N")
	)
	(segment
		(start 98.6917 -413.596328)
		(end 98.6917 -410.594048)
		(width 0.127)
		(layer "In6.Cu")
		(net "GPU_PRSNT_N")
	)
	(segment
		(start 96.539558 -420.128446)
		(end 97.05086 -419.617144)
		(width 0.127)
		(layer "In6.Cu")
		(net "GPU_PRSNT_N")
	)
	(segment
		(start 97.05086 -415.237168)
		(end 98.6917 -413.596328)
		(width 0.127)
		(layer "In6.Cu")
		(net "GPU_PRSNT_N")
	)
	(segment
		(start 97.5106 -409.412948)
		(end 97.5106 -408.799284)
		(width 0.127)
		(layer "In6.Cu")
		(net "GPU_PRSNT_N")
	)
	(segment
		(start 97.133664 -408.422348)
		(end 38.28542 -408.422348)
		(width 0.127)
		(layer "In6.Cu")
		(net "GPU_PRSNT_N")
	)
	(segment
		(start 38.28542 -408.422348)
		(end 33.53562 -413.172148)
		(width 0.127)
		(layer "In6.Cu")
		(net "GPU_PRSNT_N")
	)
	(segment
		(start 98.6917 -410.594048)
		(end 97.5106 -409.412948)
		(width 0.127)
		(layer "In6.Cu")
		(net "GPU_PRSNT_N")
	)
	(segment
		(start 97.05086 -419.617144)
		(end 97.05086 -415.237168)
		(width 0.127)
		(layer "In6.Cu")
		(net "GPU_PRSNT_N")
	)
	(segment
		(start 26.86812 -413.172148)
		(end 26.52522 -413.515048)
		(width 0.127)
		(layer "In6.Cu")
		(net "GPU_PRSNT_N")
	)
	(segment
		(start 33.53562 -413.172148)
		(end 26.86812 -413.172148)
		(width 0.127)
		(layer "In6.Cu")
		(net "GPU_PRSNT_N")
	)
	(segment
		(start 97.5106 -408.799284)
		(end 97.133664 -408.422348)
		(width 0.127)
		(layer "In6.Cu")
		(net "GPU_PRSNT_N")
	)
	(segment
		(start 95.80626 -419.395148)
		(end 96.539558 -420.128446)
		(width 0.127)
		(layer "In15.Cu")
		(net "GPU_PRSNT_N")
	)
	(segment
		(start 78.04531 -424.689778)
		(end 83.33994 -419.395148)
		(width 0.127)
		(layer "In15.Cu")
		(net "GPU_PRSNT_N")
	)
	(segment
		(start 77.650086 -424.689778)
		(end 78.04531 -424.689778)
		(width 0.127)
		(layer "In15.Cu")
		(net "GPU_PRSNT_N")
	)
	(segment
		(start 83.33994 -419.395148)
		(end 95.80626 -419.395148)
		(width 0.127)
		(layer "In15.Cu")
		(net "GPU_PRSNT_N")
	)
	(segment
		(start 30.353 -412.08452)
		(end 31.730696 -412.08452)
		(width 0.12954)
		(layer "F.Cu")
		(net "GPU_PRSNT")
	)
	(segment
		(start 191.861186 -438.57418)
		(end 191.23025 -438.57418)
		(width 0.12954)
		(layer "F.Cu")
		(net "GPU_PRSNT")
	)
	(segment
		(start 28.3718 -411.9626)
		(end 28.3718 -411.5308)
		(width 0.12954)
		(layer "F.Cu")
		(net "GPU_PRSNT")
	)
	(segment
		(start 29.031692 -412.08452)
		(end 30.353 -412.08452)
		(width 0.12954)
		(layer "F.Cu")
		(net "GPU_PRSNT")
	)
	(segment
		(start 28.49372 -412.08452)
		(end 28.3718 -411.9626)
		(width 0.12954)
		(layer "F.Cu")
		(net "GPU_PRSNT")
	)
	(segment
		(start 28.468066 -411.434534)
		(end 29.031692 -411.434534)
		(width 0.12954)
		(layer "F.Cu")
		(net "GPU_PRSNT")
	)
	(segment
		(start 31.730696 -412.08452)
		(end 31.745682 -412.069534)
		(width 0.12954)
		(layer "F.Cu")
		(net "GPU_PRSNT")
	)
	(segment
		(start 28.3718 -411.5308)
		(end 28.468066 -411.434534)
		(width 0.12954)
		(layer "F.Cu")
		(net "GPU_PRSNT")
	)
	(segment
		(start 29.031692 -412.08452)
		(end 28.49372 -412.08452)
		(width 0.12954)
		(layer "F.Cu")
		(net "GPU_PRSNT")
	)
	(via
		(at 351.1804 -397.12392)
		(size 0.508)
		(drill 0.254)
		(layers "F.Cu" "B.Cu")
		(net "GPU_PRSNT")
	)
	(via
		(at 168.80586 -414.43148)
		(size 0.508)
		(drill 0.254)
		(layers "F.Cu" "B.Cu")
		(net "GPU_PRSNT")
	)
	(via
		(at 191.23025 -438.57418)
		(size 0.508)
		(drill 0.254)
		(layers "F.Cu" "B.Cu")
		(net "GPU_PRSNT")
	)
	(via
		(at 30.353 -412.08452)
		(size 0.508)
		(drill 0.254)
		(layers "F.Cu" "B.Cu")
		(net "GPU_PRSNT")
	)
	(via
		(at 186.10707 -424.0403)
		(size 0.508)
		(drill 0.254)
		(layers "F.Cu" "B.Cu")
		(net "GPU_PRSNT")
	)
	(via
		(at 300.58614 -404.9903)
		(size 0.508)
		(drill 0.254)
		(layers "F.Cu" "B.Cu")
		(net "GPU_PRSNT")
	)
	(via
		(at 102.87 -397.93418)
		(size 0.508)
		(drill 0.254)
		(layers "F.Cu" "B.Cu")
		(net "GPU_PRSNT")
	)
	(segment
		(start 167.8686 -399.1864)
		(end 167.9956 -399.3134)
		(width 0.12954)
		(layer "B.Cu")
		(net "GPU_PRSNT")
	)
	(segment
		(start 120.3706 -399.1864)
		(end 167.8686 -399.1864)
		(width 0.12954)
		(layer "B.Cu")
		(net "GPU_PRSNT")
	)
	(segment
		(start 168.79824 -414.42386)
		(end 168.80586 -414.43148)
		(width 0.12954)
		(layer "B.Cu")
		(net "GPU_PRSNT")
	)
	(segment
		(start 169.40022 -406.53462)
		(end 169.40022 -410.69768)
		(width 0.12954)
		(layer "B.Cu")
		(net "GPU_PRSNT")
	)
	(segment
		(start 115.28806 -396.2273)
		(end 116.80952 -397.74876)
		(width 0.12954)
		(layer "B.Cu")
		(net "GPU_PRSNT")
	)
	(segment
		(start 118.93296 -397.74876)
		(end 120.3706 -399.1864)
		(width 0.12954)
		(layer "B.Cu")
		(net "GPU_PRSNT")
	)
	(segment
		(start 102.87 -397.93418)
		(end 103.89108 -396.9131)
		(width 0.12954)
		(layer "B.Cu")
		(net "GPU_PRSNT")
	)
	(segment
		(start 116.80952 -397.74876)
		(end 118.93296 -397.74876)
		(width 0.12954)
		(layer "B.Cu")
		(net "GPU_PRSNT")
	)
	(segment
		(start 169.40022 -410.69768)
		(end 168.79824 -411.29966)
		(width 0.12954)
		(layer "B.Cu")
		(net "GPU_PRSNT")
	)
	(segment
		(start 167.9956 -399.3134)
		(end 167.9956 -405.13)
		(width 0.12954)
		(layer "B.Cu")
		(net "GPU_PRSNT")
	)
	(segment
		(start 167.9956 -405.13)
		(end 169.40022 -406.53462)
		(width 0.12954)
		(layer "B.Cu")
		(net "GPU_PRSNT")
	)
	(segment
		(start 112.78616 -396.9131)
		(end 113.47196 -396.2273)
		(width 0.12954)
		(layer "B.Cu")
		(net "GPU_PRSNT")
	)
	(segment
		(start 103.89108 -396.9131)
		(end 112.78616 -396.9131)
		(width 0.12954)
		(layer "B.Cu")
		(net "GPU_PRSNT")
	)
	(segment
		(start 168.79824 -411.29966)
		(end 168.79824 -414.42386)
		(width 0.12954)
		(layer "B.Cu")
		(net "GPU_PRSNT")
	)
	(segment
		(start 113.47196 -396.2273)
		(end 115.28806 -396.2273)
		(width 0.12954)
		(layer "B.Cu")
		(net "GPU_PRSNT")
	)
	(segment
		(start 299.78604 -398.462246)
		(end 300.291246 -397.95704)
		(width 0.127)
		(layer "In6.Cu")
		(net "GPU_PRSNT")
	)
	(segment
		(start 169.77614 -415.40176)
		(end 169.77614 -420.34714)
		(width 0.127)
		(layer "In6.Cu")
		(net "GPU_PRSNT")
	)
	(segment
		(start 300.291246 -397.95704)
		(end 305.360578 -397.95704)
		(width 0.127)
		(layer "In6.Cu")
		(net "GPU_PRSNT")
	)
	(segment
		(start 187.79617 -425.7294)
		(end 186.10707 -424.0403)
		(width 0.127)
		(layer "In6.Cu")
		(net "GPU_PRSNT")
	)
	(segment
		(start 169.77614 -420.34714)
		(end 172.59808 -423.16908)
		(width 0.127)
		(layer "In6.Cu")
		(net "GPU_PRSNT")
	)
	(segment
		(start 189.58052 -436.92445)
		(end 189.58052 -425.8564)
		(width 0.127)
		(layer "In6.Cu")
		(net "GPU_PRSNT")
	)
	(segment
		(start 305.360578 -397.95704)
		(end 306.193698 -397.12392)
		(width 0.127)
		(layer "In6.Cu")
		(net "GPU_PRSNT")
	)
	(segment
		(start 189.45352 -425.7294)
		(end 187.79617 -425.7294)
		(width 0.127)
		(layer "In6.Cu")
		(net "GPU_PRSNT")
	)
	(segment
		(start 191.23025 -438.57418)
		(end 189.58052 -436.92445)
		(width 0.127)
		(layer "In6.Cu")
		(net "GPU_PRSNT")
	)
	(segment
		(start 185.69051 -424.45686)
		(end 186.10707 -424.0403)
		(width 0.127)
		(layer "In6.Cu")
		(net "GPU_PRSNT")
	)
	(segment
		(start 176.77384 -424.45686)
		(end 185.69051 -424.45686)
		(width 0.127)
		(layer "In6.Cu")
		(net "GPU_PRSNT")
	)
	(segment
		(start 168.80586 -414.43148)
		(end 169.77614 -415.40176)
		(width 0.127)
		(layer "In6.Cu")
		(net "GPU_PRSNT")
	)
	(segment
		(start 172.59808 -423.16908)
		(end 175.48606 -423.16908)
		(width 0.127)
		(layer "In6.Cu")
		(net "GPU_PRSNT")
	)
	(segment
		(start 306.193698 -397.12392)
		(end 351.1804 -397.12392)
		(width 0.127)
		(layer "In6.Cu")
		(net "GPU_PRSNT")
	)
	(segment
		(start 300.58614 -404.9903)
		(end 299.78604 -404.1902)
		(width 0.127)
		(layer "In6.Cu")
		(net "GPU_PRSNT")
	)
	(segment
		(start 299.78604 -404.1902)
		(end 299.78604 -398.462246)
		(width 0.127)
		(layer "In6.Cu")
		(net "GPU_PRSNT")
	)
	(segment
		(start 189.58052 -425.8564)
		(end 189.45352 -425.7294)
		(width 0.127)
		(layer "In6.Cu")
		(net "GPU_PRSNT")
	)
	(segment
		(start 175.48606 -423.16908)
		(end 176.77384 -424.45686)
		(width 0.127)
		(layer "In6.Cu")
		(net "GPU_PRSNT")
	)
	(segment
		(start 190.36284 -421.513)
		(end 186.13374 -421.513)
		(width 0.127)
		(layer "In11.Cu")
		(net "GPU_PRSNT")
	)
	(segment
		(start 276.16658 -431.132234)
		(end 276.16658 -434.759354)
		(width 0.127)
		(layer "In11.Cu")
		(net "GPU_PRSNT")
	)
	(segment
		(start 96.755712 -399.458688)
		(end 97.924112 -398.290288)
		(width 0.127)
		(layer "In11.Cu")
		(net "GPU_PRSNT")
	)
	(segment
		(start 299.7962 -405.52878)
		(end 299.7962 -409.683712)
		(width 0.127)
		(layer "In11.Cu")
		(net "GPU_PRSNT")
	)
	(segment
		(start 191.44234 -426.06214)
		(end 191.44234 -422.5925)
		(width 0.127)
		(layer "In11.Cu")
		(net "GPU_PRSNT")
	)
	(segment
		(start 190.87338 -430.225454)
		(end 190.87338 -426.6311)
		(width 0.127)
		(layer "In11.Cu")
		(net "GPU_PRSNT")
	)
	(segment
		(start 299.7962 -409.683712)
		(end 298.537376 -410.942536)
		(width 0.127)
		(layer "In11.Cu")
		(net "GPU_PRSNT")
	)
	(segment
		(start 296.428414 -419.991794)
		(end 296.428414 -427.322996)
		(width 0.127)
		(layer "In11.Cu")
		(net "GPU_PRSNT")
	)
	(segment
		(start 279.063704 -428.23511)
		(end 276.16658 -431.132234)
		(width 0.127)
		(layer "In11.Cu")
		(net "GPU_PRSNT")
	)
	(segment
		(start 295.5163 -428.23511)
		(end 279.063704 -428.23511)
		(width 0.127)
		(layer "In11.Cu")
		(net "GPU_PRSNT")
	)
	(segment
		(start 185.56478 -422.08196)
		(end 185.56478 -423.49801)
		(width 0.127)
		(layer "In11.Cu")
		(net "GPU_PRSNT")
	)
	(segment
		(start 272.745454 -438.18048)
		(end 198.828406 -438.18048)
		(width 0.127)
		(layer "In11.Cu")
		(net "GPU_PRSNT")
	)
	(segment
		(start 276.16658 -434.759354)
		(end 272.745454 -438.18048)
		(width 0.127)
		(layer "In11.Cu")
		(net "GPU_PRSNT")
	)
	(segment
		(start 47.77994 -399.458688)
		(end 96.755712 -399.458688)
		(width 0.127)
		(layer "In11.Cu")
		(net "GPU_PRSNT")
	)
	(segment
		(start 190.87338 -426.6311)
		(end 191.44234 -426.06214)
		(width 0.127)
		(layer "In11.Cu")
		(net "GPU_PRSNT")
	)
	(segment
		(start 97.924112 -398.290288)
		(end 102.513892 -398.290288)
		(width 0.127)
		(layer "In11.Cu")
		(net "GPU_PRSNT")
	)
	(segment
		(start 298.537376 -410.942536)
		(end 298.537376 -412.479744)
		(width 0.127)
		(layer "In11.Cu")
		(net "GPU_PRSNT")
	)
	(segment
		(start 185.56478 -423.49801)
		(end 186.10707 -424.0403)
		(width 0.127)
		(layer "In11.Cu")
		(net "GPU_PRSNT")
	)
	(segment
		(start 46.9138 -405.30272)
		(end 46.921674 -405.294846)
		(width 0.127)
		(layer "In11.Cu")
		(net "GPU_PRSNT")
	)
	(segment
		(start 191.44234 -422.5925)
		(end 190.36284 -421.513)
		(width 0.127)
		(layer "In11.Cu")
		(net "GPU_PRSNT")
	)
	(segment
		(start 31.222188 -412.953708)
		(end 40.16756 -412.953708)
		(width 0.127)
		(layer "In11.Cu")
		(net "GPU_PRSNT")
	)
	(segment
		(start 30.353 -412.08452)
		(end 31.222188 -412.953708)
		(width 0.127)
		(layer "In11.Cu")
		(net "GPU_PRSNT")
	)
	(segment
		(start 300.33468 -404.9903)
		(end 299.7962 -405.52878)
		(width 0.127)
		(layer "In11.Cu")
		(net "GPU_PRSNT")
	)
	(segment
		(start 300.58614 -404.9903)
		(end 300.33468 -404.9903)
		(width 0.127)
		(layer "In11.Cu")
		(net "GPU_PRSNT")
	)
	(segment
		(start 198.828406 -438.18048)
		(end 190.87338 -430.225454)
		(width 0.127)
		(layer "In11.Cu")
		(net "GPU_PRSNT")
	)
	(segment
		(start 46.9138 -406.207468)
		(end 46.9138 -405.30272)
		(width 0.127)
		(layer "In11.Cu")
		(net "GPU_PRSNT")
	)
	(segment
		(start 186.13374 -421.513)
		(end 185.56478 -422.08196)
		(width 0.127)
		(layer "In11.Cu")
		(net "GPU_PRSNT")
	)
	(segment
		(start 298.537376 -412.479744)
		(end 295.39692 -415.6202)
		(width 0.127)
		(layer "In11.Cu")
		(net "GPU_PRSNT")
	)
	(segment
		(start 40.16756 -412.953708)
		(end 46.9138 -406.207468)
		(width 0.127)
		(layer "In11.Cu")
		(net "GPU_PRSNT")
	)
	(segment
		(start 295.39692 -415.6202)
		(end 295.39692 -418.9603)
		(width 0.127)
		(layer "In11.Cu")
		(net "GPU_PRSNT")
	)
	(segment
		(start 295.39692 -418.9603)
		(end 296.428414 -419.991794)
		(width 0.127)
		(layer "In11.Cu")
		(net "GPU_PRSNT")
	)
	(segment
		(start 46.921674 -405.294846)
		(end 46.921674 -400.316954)
		(width 0.127)
		(layer "In11.Cu")
		(net "GPU_PRSNT")
	)
	(segment
		(start 46.921674 -400.316954)
		(end 47.77994 -399.458688)
		(width 0.127)
		(layer "In11.Cu")
		(net "GPU_PRSNT")
	)
	(segment
		(start 296.428414 -427.322996)
		(end 295.5163 -428.23511)
		(width 0.127)
		(layer "In11.Cu")
		(net "GPU_PRSNT")
	)
	(segment
		(start 102.513892 -398.290288)
		(end 102.87 -397.93418)
		(width 0.127)
		(layer "In11.Cu")
		(net "GPU_PRSNT")
	)
	(segment
		(start 17.294352 -421.279066)
		(end 17.294352 -421.815514)
		(width 0.12954)
		(layer "F.Cu")
		(net "GPU_PEX_STRAP1_R")
	)
	(segment
		(start 17.640046 -420.12743)
		(end 17.640046 -420.933372)
		(width 0.12954)
		(layer "F.Cu")
		(net "GPU_PEX_STRAP1_R")
	)
	(segment
		(start 17.294352 -421.815514)
		(end 17.294352 -422.786556)
		(width 0.12954)
		(layer "F.Cu")
		(net "GPU_PEX_STRAP1_R")
	)
	(segment
		(start 17.294352 -422.786556)
		(end 17.737582 -423.229786)
		(width 0.12954)
		(layer "F.Cu")
		(net "GPU_PEX_STRAP1_R")
	)
	(segment
		(start 17.640046 -420.933372)
		(end 17.294352 -421.279066)
		(width 0.12954)
		(layer "F.Cu")
		(net "GPU_PEX_STRAP1_R")
	)
	(via
		(at 17.294352 -421.815514)
		(size 0.762)
		(drill 0.381)
		(layers "F.Cu" "B.Cu")
		(net "GPU_PEX_STRAP1_R")
	)
	(segment
		(start 17.737582 -426.359828)
		(end 17.737582 -424.029886)
		(width 0.12954)
		(layer "F.Cu")
		(net "GPU_PEX_STRAP1")
	)
	(segment
		(start 10.58164 -420.494968)
		(end 10.58164 -425.31284)
		(width 0.12954)
		(layer "F.Cu")
		(net "GPU_PEX_STRAP1")
	)
	(segment
		(start 75.22718 -412.204408)
		(end 78.642972 -415.6202)
		(width 0.12954)
		(layer "F.Cu")
		(net "GPU_PEX_STRAP1")
	)
	(segment
		(start 11.801856 -426.533056)
		(end 12.927584 -426.9994)
		(width 0.12954)
		(layer "F.Cu")
		(net "GPU_PEX_STRAP1")
	)
	(segment
		(start 78.642972 -415.6202)
		(end 90.9447 -415.6202)
		(width 0.12954)
		(layer "F.Cu")
		(net "GPU_PEX_STRAP1")
	)
	(segment
		(start 39.64178 -427.34738)
		(end 38.1508 -425.8564)
		(width 0.12954)
		(layer "F.Cu")
		(net "GPU_PEX_STRAP1")
	)
	(segment
		(start 16.9418 -427.863)
		(end 17.180814 -427.623986)
		(width 0.12954)
		(layer "F.Cu")
		(net "GPU_PEX_STRAP1")
	)
	(segment
		(start 39.64178 -430.708308)
		(end 39.64178 -427.34738)
		(width 0.12954)
		(layer "F.Cu")
		(net "GPU_PEX_STRAP1")
	)
	(segment
		(start 13.774928 -426.9994)
		(end 15.860014 -427.863)
		(width 0.12954)
		(layer "F.Cu")
		(net "GPU_PEX_STRAP1")
	)
	(segment
		(start 33.317688 -418.635688)
		(end 12.44092 -418.635688)
		(width 0.12954)
		(layer "F.Cu")
		(net "GPU_PEX_STRAP1")
	)
	(segment
		(start 15.860014 -427.863)
		(end 16.9418 -427.863)
		(width 0.12954)
		(layer "F.Cu")
		(net "GPU_PEX_STRAP1")
	)
	(segment
		(start 10.58164 -425.31284)
		(end 11.801856 -426.533056)
		(width 0.12954)
		(layer "F.Cu")
		(net "GPU_PEX_STRAP1")
	)
	(segment
		(start 12.44092 -418.635688)
		(end 10.58164 -420.494968)
		(width 0.12954)
		(layer "F.Cu")
		(net "GPU_PEX_STRAP1")
	)
	(segment
		(start 12.927584 -426.9994)
		(end 13.774928 -426.9994)
		(width 0.12954)
		(layer "F.Cu")
		(net "GPU_PEX_STRAP1")
	)
	(segment
		(start 17.737582 -427.623986)
		(end 17.737582 -426.359828)
		(width 0.12954)
		(layer "F.Cu")
		(net "GPU_PEX_STRAP1")
	)
	(segment
		(start 38.1508 -423.4688)
		(end 33.317688 -418.635688)
		(width 0.12954)
		(layer "F.Cu")
		(net "GPU_PEX_STRAP1")
	)
	(segment
		(start 17.180814 -427.623986)
		(end 17.737582 -427.623986)
		(width 0.12954)
		(layer "F.Cu")
		(net "GPU_PEX_STRAP1")
	)
	(segment
		(start 90.9447 -415.6202)
		(end 93.25356 -417.92906)
		(width 0.12954)
		(layer "F.Cu")
		(net "GPU_PEX_STRAP1")
	)
	(segment
		(start 38.1508 -425.8564)
		(end 38.1508 -423.4688)
		(width 0.12954)
		(layer "F.Cu")
		(net "GPU_PEX_STRAP1")
	)
	(via
		(at 93.25356 -417.92906)
		(size 0.508)
		(drill 0.254)
		(layers "F.Cu" "B.Cu")
		(net "GPU_PEX_STRAP1")
	)
	(via
		(at 75.22718 -412.204408)
		(size 0.508)
		(drill 0.254)
		(layers "F.Cu" "B.Cu")
		(net "GPU_PEX_STRAP1")
	)
	(via
		(at 17.737582 -426.359828)
		(size 0.762)
		(drill 0.254)
		(layers "F.Cu" "B.Cu")
		(net "GPU_PEX_STRAP1")
	)
	(via
		(at 39.64178 -430.708308)
		(size 0.508)
		(drill 0.254)
		(layers "F.Cu" "B.Cu")
		(net "GPU_PEX_STRAP1")
	)
	(segment
		(start 74.93254 -417.92906)
		(end 93.25356 -417.92906)
		(width 0.12954)
		(layer "B.Cu")
		(net "GPU_PEX_STRAP1")
	)
	(segment
		(start 75.65009 -440.489848)
		(end 75.65009 -440.475878)
		(width 0.12954)
		(layer "B.Cu")
		(net "GPU_PEX_STRAP1")
	)
	(segment
		(start 75.65009 -440.475878)
		(end 73.9267 -438.752488)
		(width 0.12954)
		(layer "B.Cu")
		(net "GPU_PEX_STRAP1")
	)
	(segment
		(start 73.9267 -438.752488)
		(end 73.9267 -418.9349)
		(width 0.12954)
		(layer "B.Cu")
		(net "GPU_PEX_STRAP1")
	)
	(segment
		(start 73.9267 -418.9349)
		(end 74.93254 -417.92906)
		(width 0.12954)
		(layer "B.Cu")
		(net "GPU_PEX_STRAP1")
	)
	(segment
		(start 55.12562 -415.628328)
		(end 55.12562 -427.411388)
		(width 0.127)
		(layer "In2.Cu")
		(net "GPU_PEX_STRAP1")
	)
	(segment
		(start 75.11034 -412.087568)
		(end 58.66638 -412.087568)
		(width 0.127)
		(layer "In2.Cu")
		(net "GPU_PEX_STRAP1")
	)
	(segment
		(start 58.66638 -412.087568)
		(end 55.12562 -415.628328)
		(width 0.127)
		(layer "In2.Cu")
		(net "GPU_PEX_STRAP1")
	)
	(segment
		(start 55.12562 -427.411388)
		(end 51.8287 -430.708308)
		(width 0.127)
		(layer "In2.Cu")
		(net "GPU_PEX_STRAP1")
	)
	(segment
		(start 51.8287 -430.708308)
		(end 39.64178 -430.708308)
		(width 0.127)
		(layer "In2.Cu")
		(net "GPU_PEX_STRAP1")
	)
	(segment
		(start 75.22718 -412.204408)
		(end 75.11034 -412.087568)
		(width 0.127)
		(layer "In2.Cu")
		(net "GPU_PEX_STRAP1")
	)
	(segment
		(start 18.290032 -421.642286)
		(end 18.626582 -421.978836)
		(width 0.12954)
		(layer "F.Cu")
		(net "GPU_PEX_STRAP0_R")
	)
	(segment
		(start 18.626582 -421.978836)
		(end 18.753582 -422.105836)
		(width 0.12954)
		(layer "F.Cu")
		(net "GPU_PEX_STRAP0_R")
	)
	(segment
		(start 18.753582 -422.105836)
		(end 18.753582 -423.229786)
		(width 0.12954)
		(layer "F.Cu")
		(net "GPU_PEX_STRAP0_R")
	)
	(segment
		(start 18.290032 -420.12743)
		(end 18.290032 -421.642286)
		(width 0.12954)
		(layer "F.Cu")
		(net "GPU_PEX_STRAP0_R")
	)
	(via
		(at 18.626582 -421.978836)
		(size 0.762)
		(drill 0.381)
		(layers "F.Cu" "B.Cu")
		(net "GPU_PEX_STRAP0_R")
	)
	(segment
		(start 18.753582 -427.649386)
		(end 18.753582 -425.260008)
		(width 0.12954)
		(layer "F.Cu")
		(net "GPU_PEX_STRAP0")
	)
	(segment
		(start 18.753582 -425.260008)
		(end 18.753582 -424.029886)
		(width 0.12954)
		(layer "F.Cu")
		(net "GPU_PEX_STRAP0")
	)
	(via
		(at 18.753582 -425.260008)
		(size 0.762)
		(drill 0.254)
		(layers "F.Cu" "B.Cu")
		(net "GPU_PEX_STRAP0")
	)
	(via
		(at 94.65056 -422.176448)
		(size 0.508)
		(drill 0.254)
		(layers "F.Cu" "B.Cu")
		(net "GPU_PEX_STRAP0")
	)
	(segment
		(start 27.3558 -423.233088)
		(end 27.3558 -418.541708)
		(width 0.127)
		(layer "In6.Cu")
		(net "GPU_PEX_STRAP0")
	)
	(segment
		(start 101.08946 -409.8671)
		(end 101.08946 -413.377888)
		(width 0.127)
		(layer "In6.Cu")
		(net "GPU_PEX_STRAP0")
	)
	(segment
		(start 96.680528 -405.458168)
		(end 101.08946 -409.8671)
		(width 0.127)
		(layer "In6.Cu")
		(net "GPU_PEX_STRAP0")
	)
	(segment
		(start 25.729184 -424.859704)
		(end 27.3558 -423.233088)
		(width 0.127)
		(layer "In6.Cu")
		(net "GPU_PEX_STRAP0")
	)
	(segment
		(start 34.021014 -409.895548)
		(end 38.458394 -405.458168)
		(width 0.127)
		(layer "In6.Cu")
		(net "GPU_PEX_STRAP0")
	)
	(segment
		(start 102.34676 -414.635188)
		(end 102.34676 -416.644328)
		(width 0.127)
		(layer "In6.Cu")
		(net "GPU_PEX_STRAP0")
	)
	(segment
		(start 19.153886 -424.859704)
		(end 25.729184 -424.859704)
		(width 0.127)
		(layer "In6.Cu")
		(net "GPU_PEX_STRAP0")
	)
	(segment
		(start 18.753582 -425.260008)
		(end 19.153886 -424.859704)
		(width 0.127)
		(layer "In6.Cu")
		(net "GPU_PEX_STRAP0")
	)
	(segment
		(start 94.65056 -422.384728)
		(end 94.65056 -422.176448)
		(width 0.127)
		(layer "In6.Cu")
		(net "GPU_PEX_STRAP0")
	)
	(segment
		(start 24.86406 -412.819088)
		(end 27.7876 -409.895548)
		(width 0.127)
		(layer "In6.Cu")
		(net "GPU_PEX_STRAP0")
	)
	(segment
		(start 38.458394 -405.458168)
		(end 96.680528 -405.458168)
		(width 0.127)
		(layer "In6.Cu")
		(net "GPU_PEX_STRAP0")
	)
	(segment
		(start 102.34676 -416.644328)
		(end 96.02851 -422.962578)
		(width 0.127)
		(layer "In6.Cu")
		(net "GPU_PEX_STRAP0")
	)
	(segment
		(start 24.86406 -416.049968)
		(end 24.86406 -412.819088)
		(width 0.127)
		(layer "In6.Cu")
		(net "GPU_PEX_STRAP0")
	)
	(segment
		(start 27.3558 -418.541708)
		(end 24.86406 -416.049968)
		(width 0.127)
		(layer "In6.Cu")
		(net "GPU_PEX_STRAP0")
	)
	(segment
		(start 96.02851 -422.962578)
		(end 95.22841 -422.962578)
		(width 0.127)
		(layer "In6.Cu")
		(net "GPU_PEX_STRAP0")
	)
	(segment
		(start 95.22841 -422.962578)
		(end 94.65056 -422.384728)
		(width 0.127)
		(layer "In6.Cu")
		(net "GPU_PEX_STRAP0")
	)
	(segment
		(start 101.08946 -413.377888)
		(end 102.34676 -414.635188)
		(width 0.127)
		(layer "In6.Cu")
		(net "GPU_PEX_STRAP0")
	)
	(segment
		(start 27.7876 -409.895548)
		(end 34.021014 -409.895548)
		(width 0.127)
		(layer "In6.Cu")
		(net "GPU_PEX_STRAP0")
	)
	(segment
		(start 82.69986 -439.717688)
		(end 82.69986 -423.515028)
		(width 0.127)
		(layer "In15.Cu")
		(net "GPU_PEX_STRAP0")
	)
	(segment
		(start 83.004914 -439.844688)
		(end 82.82686 -439.844688)
		(width 0.127)
		(layer "In15.Cu")
		(net "GPU_PEX_STRAP0")
	)
	(segment
		(start 83.650074 -440.489848)
		(end 83.004914 -439.844688)
		(width 0.127)
		(layer "In15.Cu")
		(net "GPU_PEX_STRAP0")
	)
	(segment
		(start 82.69986 -423.515028)
		(end 84.03844 -422.176448)
		(width 0.127)
		(layer "In15.Cu")
		(net "GPU_PEX_STRAP0")
	)
	(segment
		(start 82.82686 -439.844688)
		(end 82.69986 -439.717688)
		(width 0.127)
		(layer "In15.Cu")
		(net "GPU_PEX_STRAP0")
	)
	(segment
		(start 84.03844 -422.176448)
		(end 94.65056 -422.176448)
		(width 0.127)
		(layer "In15.Cu")
		(net "GPU_PEX_STRAP0")
	)
	(segment
		(start 166.57828 -111.166148)
		(end 165.51148 -112.232948)
		(width 0.12954)
		(layer "F.Cu")
		(net "GPU_NVS_PWR_BRAKE_R_N")
	)
	(segment
		(start 165.51148 -112.232948)
		(end 165.04793 -112.232948)
		(width 0.12954)
		(layer "F.Cu")
		(net "GPU_NVS_PWR_BRAKE_R_N")
	)
	(segment
		(start 166.787576 -111.375444)
		(end 166.57828 -111.166148)
		(width 0.12954)
		(layer "F.Cu")
		(net "GPU_NVS_PWR_BRAKE_R_N")
	)
	(segment
		(start 170.155616 -111.375444)
		(end 166.787576 -111.375444)
		(width 0.12954)
		(layer "F.Cu")
		(net "GPU_NVS_PWR_BRAKE_R_N")
	)
	(via
		(at 166.57828 -111.166148)
		(size 0.762)
		(drill 0.381)
		(layers "F.Cu" "B.Cu")
		(net "GPU_NVS_PWR_BRAKE_R_N")
	)
	(segment
		(start 104.418638 -393.061698)
		(end 103.453184 -392.096244)
		(width 0.12954)
		(layer "F.Cu")
		(net "GPU_NVS_PWR_BRAKE_N_R")
	)
	(segment
		(start 102.913688 -392.63574)
		(end 102.233984 -392.63574)
		(width 0.12954)
		(layer "F.Cu")
		(net "GPU_NVS_PWR_BRAKE_N_R")
	)
	(segment
		(start 103.453184 -392.096244)
		(end 102.913688 -392.63574)
		(width 0.12954)
		(layer "F.Cu")
		(net "GPU_NVS_PWR_BRAKE_N_R")
	)
	(segment
		(start 104.746044 -393.061698)
		(end 104.418638 -393.061698)
		(width 0.12954)
		(layer "F.Cu")
		(net "GPU_NVS_PWR_BRAKE_N_R")
	)
	(segment
		(start 102.233984 -390.60374)
		(end 102.233984 -391.61974)
		(width 0.12954)
		(layer "F.Cu")
		(net "GPU_NVS_PWR_BRAKE_N_R")
	)
	(segment
		(start 102.233984 -391.61974)
		(end 102.233984 -392.63574)
		(width 0.12954)
		(layer "F.Cu")
		(net "GPU_NVS_PWR_BRAKE_N_R")
	)
	(via
		(at 103.453184 -392.096244)
		(size 0.762)
		(drill 0.381)
		(layers "F.Cu" "B.Cu")
		(net "GPU_NVS_PWR_BRAKE_N_R")
	)
	(segment
		(start 100.824284 -390.558528)
		(end 101.388672 -390.558528)
		(width 0.12954)
		(layer "F.Cu")
		(net "GPU_NVS_PWR_BRAKE_N_BUF")
	)
	(segment
		(start 101.388672 -390.558528)
		(end 101.433884 -390.60374)
		(width 0.12954)
		(layer "F.Cu")
		(net "GPU_NVS_PWR_BRAKE_N_BUF")
	)
	(via
		(at 100.824284 -390.558528)
		(size 0.508)
		(drill 0.254)
		(layers "F.Cu" "B.Cu")
		(net "GPU_NVS_PWR_BRAKE_N_BUF")
	)
	(via
		(at 39.41572 -411.447488)
		(size 0.508)
		(drill 0.254)
		(layers "F.Cu" "B.Cu")
		(net "GPU_NVS_PWR_BRAKE_N_BUF")
	)
	(segment
		(start 46.223428 -405.005286)
		(end 39.781226 -411.447488)
		(width 0.127)
		(layer "In11.Cu")
		(net "GPU_NVS_PWR_BRAKE_N_BUF")
	)
	(segment
		(start 47.810674 -396.855188)
		(end 46.223428 -398.442434)
		(width 0.127)
		(layer "In11.Cu")
		(net "GPU_NVS_PWR_BRAKE_N_BUF")
	)
	(segment
		(start 39.781226 -411.447488)
		(end 39.41572 -411.447488)
		(width 0.127)
		(layer "In11.Cu")
		(net "GPU_NVS_PWR_BRAKE_N_BUF")
	)
	(segment
		(start 100.23856 -393.33424)
		(end 97.774252 -395.798548)
		(width 0.127)
		(layer "In11.Cu")
		(net "GPU_NVS_PWR_BRAKE_N_BUF")
	)
	(segment
		(start 100.824284 -390.558528)
		(end 100.23856 -391.144252)
		(width 0.127)
		(layer "In11.Cu")
		(net "GPU_NVS_PWR_BRAKE_N_BUF")
	)
	(segment
		(start 46.223428 -398.442434)
		(end 46.223428 -405.005286)
		(width 0.127)
		(layer "In11.Cu")
		(net "GPU_NVS_PWR_BRAKE_N_BUF")
	)
	(segment
		(start 100.23856 -391.144252)
		(end 100.23856 -393.33424)
		(width 0.127)
		(layer "In11.Cu")
		(net "GPU_NVS_PWR_BRAKE_N_BUF")
	)
	(segment
		(start 97.545652 -395.798548)
		(end 96.489012 -396.855188)
		(width 0.127)
		(layer "In11.Cu")
		(net "GPU_NVS_PWR_BRAKE_N_BUF")
	)
	(segment
		(start 96.489012 -396.855188)
		(end 47.810674 -396.855188)
		(width 0.127)
		(layer "In11.Cu")
		(net "GPU_NVS_PWR_BRAKE_N_BUF")
	)
	(segment
		(start 97.774252 -395.798548)
		(end 97.545652 -395.798548)
		(width 0.127)
		(layer "In11.Cu")
		(net "GPU_NVS_PWR_BRAKE_N_BUF")
	)
	(segment
		(start 41.3131 -411.447488)
		(end 41.40454 -411.356048)
		(width 0.127)
		(layer "In15.Cu")
		(net "GPU_NVS_PWR_BRAKE_N_BUF")
	)
	(segment
		(start 41.40454 -411.356048)
		(end 47.368968 -411.356048)
		(width 0.127)
		(layer "In15.Cu")
		(net "GPU_NVS_PWR_BRAKE_N_BUF")
	)
	(segment
		(start 49.771808 -413.758888)
		(end 63.55842 -413.758888)
		(width 0.127)
		(layer "In15.Cu")
		(net "GPU_NVS_PWR_BRAKE_N_BUF")
	)
	(segment
		(start 63.55842 -413.758888)
		(end 64.649858 -414.850326)
		(width 0.127)
		(layer "In15.Cu")
		(net "GPU_NVS_PWR_BRAKE_N_BUF")
	)
	(segment
		(start 39.41572 -411.447488)
		(end 41.3131 -411.447488)
		(width 0.127)
		(layer "In15.Cu")
		(net "GPU_NVS_PWR_BRAKE_N_BUF")
	)
	(segment
		(start 64.649858 -414.850326)
		(end 64.649858 -417.48964)
		(width 0.127)
		(layer "In15.Cu")
		(net "GPU_NVS_PWR_BRAKE_N_BUF")
	)
	(segment
		(start 64.649858 -417.48964)
		(end 64.650112 -417.489894)
		(width 0.127)
		(layer "In15.Cu")
		(net "GPU_NVS_PWR_BRAKE_N_BUF")
	)
	(segment
		(start 47.368968 -411.356048)
		(end 49.771808 -413.758888)
		(width 0.127)
		(layer "In15.Cu")
		(net "GPU_NVS_PWR_BRAKE_N_BUF")
	)
	(segment
		(start 108.438188 -392.76274)
		(end 107.929934 -392.76274)
		(width 0.12954)
		(layer "F.Cu")
		(net "GPU_NVS_PWR_BRAKE_N")
	)
	(segment
		(start 107.929934 -392.76274)
		(end 107.294934 -392.76274)
		(width 0.12954)
		(layer "F.Cu")
		(net "GPU_NVS_PWR_BRAKE_N")
	)
	(segment
		(start 162.1155 -111.5695)
		(end 162.597846 -111.5695)
		(width 0.12954)
		(layer "F.Cu")
		(net "GPU_NVS_PWR_BRAKE_N")
	)
	(segment
		(start 109.180884 -392.12774)
		(end 109.180884 -393.14374)
		(width 0.12954)
		(layer "F.Cu")
		(net "GPU_NVS_PWR_BRAKE_N")
	)
	(segment
		(start 107.294934 -392.76274)
		(end 106.995976 -393.061698)
		(width 0.12954)
		(layer "F.Cu")
		(net "GPU_NVS_PWR_BRAKE_N")
	)
	(segment
		(start 109.180884 -393.14374)
		(end 108.819188 -393.14374)
		(width 0.12954)
		(layer "F.Cu")
		(net "GPU_NVS_PWR_BRAKE_N")
	)
	(segment
		(start 108.819188 -393.14374)
		(end 108.438188 -392.76274)
		(width 0.12954)
		(layer "F.Cu")
		(net "GPU_NVS_PWR_BRAKE_N")
	)
	(segment
		(start 106.995976 -393.061698)
		(end 106.645964 -393.061698)
		(width 0.12954)
		(layer "F.Cu")
		(net "GPU_NVS_PWR_BRAKE_N")
	)
	(segment
		(start 109.63148 -391.505948)
		(end 109.180884 -391.956544)
		(width 0.12954)
		(layer "F.Cu")
		(net "GPU_NVS_PWR_BRAKE_N")
	)
	(segment
		(start 109.180884 -391.956544)
		(end 109.180884 -392.12774)
		(width 0.12954)
		(layer "F.Cu")
		(net "GPU_NVS_PWR_BRAKE_N")
	)
	(segment
		(start 163.261294 -112.232948)
		(end 164.24783 -112.232948)
		(width 0.12954)
		(layer "F.Cu")
		(net "GPU_NVS_PWR_BRAKE_N")
	)
	(segment
		(start 162.597846 -111.5695)
		(end 163.261294 -112.232948)
		(width 0.12954)
		(layer "F.Cu")
		(net "GPU_NVS_PWR_BRAKE_N")
	)
	(via
		(at 162.1155 -111.5695)
		(size 0.508)
		(drill 0.254)
		(layers "F.Cu" "B.Cu")
		(net "GPU_NVS_PWR_BRAKE_N")
	)
	(via
		(at 47.043594 -115.301268)
		(size 0.508)
		(drill 0.254)
		(layers "F.Cu" "B.Cu")
		(net "GPU_NVS_PWR_BRAKE_N")
	)
	(via
		(at 109.63148 -391.505948)
		(size 0.508)
		(drill 0.254)
		(layers "F.Cu" "B.Cu")
		(net "GPU_NVS_PWR_BRAKE_N")
	)
	(via
		(at 9.77138 -176.687988)
		(size 0.508)
		(drill 0.254)
		(layers "F.Cu" "B.Cu")
		(net "GPU_NVS_PWR_BRAKE_N")
	)
	(via
		(at 107.929934 -392.76274)
		(size 0.762)
		(drill 0.381)
		(layers "F.Cu" "B.Cu")
		(net "GPU_NVS_PWR_BRAKE_N")
	)
	(segment
		(start 94.39148 -390.210548)
		(end 92.81668 -391.785348)
		(width 0.127)
		(layer "In6.Cu")
		(net "GPU_NVS_PWR_BRAKE_N")
	)
	(segment
		(start 8.623046 -195.509896)
		(end 8.623046 -192.733422)
		(width 0.127)
		(layer "In6.Cu")
		(net "GPU_NVS_PWR_BRAKE_N")
	)
	(segment
		(start 6.55828 -197.116446)
		(end 6.969506 -196.70522)
		(width 0.127)
		(layer "In6.Cu")
		(net "GPU_NVS_PWR_BRAKE_N")
	)
	(segment
		(start 101.19868 -391.074148)
		(end 99.75088 -391.074148)
		(width 0.127)
		(layer "In6.Cu")
		(net "GPU_NVS_PWR_BRAKE_N")
	)
	(segment
		(start 12.80668 -321.555872)
		(end 12.80668 -257.317748)
		(width 0.127)
		(layer "In6.Cu")
		(net "GPU_NVS_PWR_BRAKE_N")
	)
	(segment
		(start 6.55828 -190.668656)
		(end 6.55828 -179.901088)
		(width 0.127)
		(layer "In6.Cu")
		(net "GPU_NVS_PWR_BRAKE_N")
	)
	(segment
		(start 109.63148 -391.505948)
		(end 101.63048 -391.505948)
		(width 0.127)
		(layer "In6.Cu")
		(net "GPU_NVS_PWR_BRAKE_N")
	)
	(segment
		(start 27.25928 -324.043548)
		(end 15.29588 -324.043548)
		(width 0.127)
		(layer "In6.Cu")
		(net "GPU_NVS_PWR_BRAKE_N")
	)
	(segment
		(start 6.55828 -179.901088)
		(end 9.77138 -176.687988)
		(width 0.127)
		(layer "In6.Cu")
		(net "GPU_NVS_PWR_BRAKE_N")
	)
	(segment
		(start 9.25068 -256.047748)
		(end 6.55828 -253.355348)
		(width 0.127)
		(layer "In6.Cu")
		(net "GPU_NVS_PWR_BRAKE_N")
	)
	(segment
		(start 92.81668 -391.785348)
		(end 58.118248 -391.785348)
		(width 0.127)
		(layer "In6.Cu")
		(net "GPU_NVS_PWR_BRAKE_N")
	)
	(segment
		(start 7.427722 -196.70522)
		(end 8.623046 -195.509896)
		(width 0.127)
		(layer "In6.Cu")
		(net "GPU_NVS_PWR_BRAKE_N")
	)
	(segment
		(start 99.75088 -391.074148)
		(end 98.88728 -390.210548)
		(width 0.127)
		(layer "In6.Cu")
		(net "GPU_NVS_PWR_BRAKE_N")
	)
	(segment
		(start 98.88728 -390.210548)
		(end 94.39148 -390.210548)
		(width 0.127)
		(layer "In6.Cu")
		(net "GPU_NVS_PWR_BRAKE_N")
	)
	(segment
		(start 101.63048 -391.505948)
		(end 101.19868 -391.074148)
		(width 0.127)
		(layer "In6.Cu")
		(net "GPU_NVS_PWR_BRAKE_N")
	)
	(segment
		(start 15.29588 -324.043548)
		(end 13.36548 -322.113148)
		(width 0.127)
		(layer "In6.Cu")
		(net "GPU_NVS_PWR_BRAKE_N")
	)
	(segment
		(start 34.32048 -331.104748)
		(end 27.25928 -324.043548)
		(width 0.127)
		(layer "In6.Cu")
		(net "GPU_NVS_PWR_BRAKE_N")
	)
	(segment
		(start 32.23768 -339.943948)
		(end 34.32048 -337.861148)
		(width 0.127)
		(layer "In6.Cu")
		(net "GPU_NVS_PWR_BRAKE_N")
	)
	(segment
		(start 32.23768 -365.90478)
		(end 32.23768 -339.943948)
		(width 0.127)
		(layer "In6.Cu")
		(net "GPU_NVS_PWR_BRAKE_N")
	)
	(segment
		(start 8.623046 -192.733422)
		(end 6.55828 -190.668656)
		(width 0.127)
		(layer "In6.Cu")
		(net "GPU_NVS_PWR_BRAKE_N")
	)
	(segment
		(start 34.32048 -337.861148)
		(end 34.32048 -331.104748)
		(width 0.127)
		(layer "In6.Cu")
		(net "GPU_NVS_PWR_BRAKE_N")
	)
	(segment
		(start 58.118248 -391.785348)
		(end 32.23768 -365.90478)
		(width 0.127)
		(layer "In6.Cu")
		(net "GPU_NVS_PWR_BRAKE_N")
	)
	(segment
		(start 6.969506 -196.70522)
		(end 7.427722 -196.70522)
		(width 0.127)
		(layer "In6.Cu")
		(net "GPU_NVS_PWR_BRAKE_N")
	)
	(segment
		(start 6.55828 -253.355348)
		(end 6.55828 -197.116446)
		(width 0.127)
		(layer "In6.Cu")
		(net "GPU_NVS_PWR_BRAKE_N")
	)
	(segment
		(start 12.80668 -257.317748)
		(end 11.53668 -256.047748)
		(width 0.127)
		(layer "In6.Cu")
		(net "GPU_NVS_PWR_BRAKE_N")
	)
	(segment
		(start 11.53668 -256.047748)
		(end 9.25068 -256.047748)
		(width 0.127)
		(layer "In6.Cu")
		(net "GPU_NVS_PWR_BRAKE_N")
	)
	(segment
		(start 13.363956 -322.113148)
		(end 12.80668 -321.555872)
		(width 0.127)
		(layer "In6.Cu")
		(net "GPU_NVS_PWR_BRAKE_N")
	)
	(segment
		(start 13.36548 -322.113148)
		(end 13.363956 -322.113148)
		(width 0.127)
		(layer "In6.Cu")
		(net "GPU_NVS_PWR_BRAKE_N")
	)
	(segment
		(start 140.745464 -111.468662)
		(end 142.907258 -111.468662)
		(width 0.127)
		(layer "In13.Cu")
		(net "GPU_NVS_PWR_BRAKE_N")
	)
	(segment
		(start 67.5259 -113.561114)
		(end 69.179186 -111.907828)
		(width 0.127)
		(layer "In13.Cu")
		(net "GPU_NVS_PWR_BRAKE_N")
	)
	(segment
		(start 97.37344 -109.913928)
		(end 99.89947 -109.913928)
		(width 0.127)
		(layer "In13.Cu")
		(net "GPU_NVS_PWR_BRAKE_N")
	)
	(segment
		(start 100.14839 -109.665008)
		(end 118.24589 -109.665008)
		(width 0.127)
		(layer "In13.Cu")
		(net "GPU_NVS_PWR_BRAKE_N")
	)
	(segment
		(start 154.040586 -110.277148)
		(end 157.35808 -110.277148)
		(width 0.127)
		(layer "In13.Cu")
		(net "GPU_NVS_PWR_BRAKE_N")
	)
	(segment
		(start 99.89947 -109.913928)
		(end 100.14839 -109.665008)
		(width 0.127)
		(layer "In13.Cu")
		(net "GPU_NVS_PWR_BRAKE_N")
	)
	(segment
		(start 144.896332 -110.59922)
		(end 147.06346 -112.766348)
		(width 0.127)
		(layer "In13.Cu")
		(net "GPU_NVS_PWR_BRAKE_N")
	)
	(segment
		(start 51.40198 -114.800888)
		(end 63.51778 -114.800888)
		(width 0.127)
		(layer "In13.Cu")
		(net "GPU_NVS_PWR_BRAKE_N")
	)
	(segment
		(start 51.24958 -114.648488)
		(end 51.40198 -114.800888)
		(width 0.127)
		(layer "In13.Cu")
		(net "GPU_NVS_PWR_BRAKE_N")
	)
	(segment
		(start 125.836426 -108.346748)
		(end 127.058166 -109.568488)
		(width 0.127)
		(layer "In13.Cu")
		(net "GPU_NVS_PWR_BRAKE_N")
	)
	(segment
		(start 147.06346 -112.766348)
		(end 151.551386 -112.766348)
		(width 0.127)
		(layer "In13.Cu")
		(net "GPU_NVS_PWR_BRAKE_N")
	)
	(segment
		(start 157.35808 -110.277148)
		(end 158.650432 -111.5695)
		(width 0.127)
		(layer "In13.Cu")
		(net "GPU_NVS_PWR_BRAKE_N")
	)
	(segment
		(start 77.12837 -111.907828)
		(end 80.25511 -108.781088)
		(width 0.127)
		(layer "In13.Cu")
		(net "GPU_NVS_PWR_BRAKE_N")
	)
	(segment
		(start 127.058166 -109.568488)
		(end 138.84529 -109.568488)
		(width 0.127)
		(layer "In13.Cu")
		(net "GPU_NVS_PWR_BRAKE_N")
	)
	(segment
		(start 49.40808 -114.648488)
		(end 51.24958 -114.648488)
		(width 0.127)
		(layer "In13.Cu")
		(net "GPU_NVS_PWR_BRAKE_N")
	)
	(segment
		(start 49.2125 -114.844068)
		(end 49.40808 -114.648488)
		(width 0.127)
		(layer "In13.Cu")
		(net "GPU_NVS_PWR_BRAKE_N")
	)
	(segment
		(start 143.7767 -110.59922)
		(end 144.896332 -110.59922)
		(width 0.127)
		(layer "In13.Cu")
		(net "GPU_NVS_PWR_BRAKE_N")
	)
	(segment
		(start 63.51778 -114.800888)
		(end 63.76416 -115.047268)
		(width 0.127)
		(layer "In13.Cu")
		(net "GPU_NVS_PWR_BRAKE_N")
	)
	(segment
		(start 80.25511 -108.781088)
		(end 96.2406 -108.781088)
		(width 0.127)
		(layer "In13.Cu")
		(net "GPU_NVS_PWR_BRAKE_N")
	)
	(segment
		(start 151.551386 -112.766348)
		(end 154.040586 -110.277148)
		(width 0.127)
		(layer "In13.Cu")
		(net "GPU_NVS_PWR_BRAKE_N")
	)
	(segment
		(start 47.500794 -114.844068)
		(end 49.2125 -114.844068)
		(width 0.127)
		(layer "In13.Cu")
		(net "GPU_NVS_PWR_BRAKE_N")
	)
	(segment
		(start 69.179186 -111.907828)
		(end 77.12837 -111.907828)
		(width 0.127)
		(layer "In13.Cu")
		(net "GPU_NVS_PWR_BRAKE_N")
	)
	(segment
		(start 66.664586 -115.047268)
		(end 67.5259 -114.185954)
		(width 0.127)
		(layer "In13.Cu")
		(net "GPU_NVS_PWR_BRAKE_N")
	)
	(segment
		(start 138.84529 -109.568488)
		(end 140.745464 -111.468662)
		(width 0.127)
		(layer "In13.Cu")
		(net "GPU_NVS_PWR_BRAKE_N")
	)
	(segment
		(start 119.56415 -108.346748)
		(end 125.836426 -108.346748)
		(width 0.127)
		(layer "In13.Cu")
		(net "GPU_NVS_PWR_BRAKE_N")
	)
	(segment
		(start 158.650432 -111.5695)
		(end 162.1155 -111.5695)
		(width 0.127)
		(layer "In13.Cu")
		(net "GPU_NVS_PWR_BRAKE_N")
	)
	(segment
		(start 63.76416 -115.047268)
		(end 66.664586 -115.047268)
		(width 0.127)
		(layer "In13.Cu")
		(net "GPU_NVS_PWR_BRAKE_N")
	)
	(segment
		(start 67.5259 -114.185954)
		(end 67.5259 -113.561114)
		(width 0.127)
		(layer "In13.Cu")
		(net "GPU_NVS_PWR_BRAKE_N")
	)
	(segment
		(start 47.043594 -115.301268)
		(end 47.500794 -114.844068)
		(width 0.127)
		(layer "In13.Cu")
		(net "GPU_NVS_PWR_BRAKE_N")
	)
	(segment
		(start 118.24589 -109.665008)
		(end 119.56415 -108.346748)
		(width 0.127)
		(layer "In13.Cu")
		(net "GPU_NVS_PWR_BRAKE_N")
	)
	(segment
		(start 142.907258 -111.468662)
		(end 143.7767 -110.59922)
		(width 0.127)
		(layer "In13.Cu")
		(net "GPU_NVS_PWR_BRAKE_N")
	)
	(segment
		(start 96.2406 -108.781088)
		(end 97.37344 -109.913928)
		(width 0.127)
		(layer "In13.Cu")
		(net "GPU_NVS_PWR_BRAKE_N")
	)
	(segment
		(start 17.83588 -170.805348)
		(end 11.95324 -176.687988)
		(width 0.127)
		(layer "In15.Cu")
		(net "GPU_NVS_PWR_BRAKE_N")
	)
	(segment
		(start 17.83588 -128.781048)
		(end 17.83588 -170.805348)
		(width 0.127)
		(layer "In15.Cu")
		(net "GPU_NVS_PWR_BRAKE_N")
	)
	(segment
		(start 42.05224 -117.780308)
		(end 28.83662 -117.780308)
		(width 0.127)
		(layer "In15.Cu")
		(net "GPU_NVS_PWR_BRAKE_N")
	)
	(segment
		(start 11.95324 -176.687988)
		(end 9.77138 -176.687988)
		(width 0.127)
		(layer "In15.Cu")
		(net "GPU_NVS_PWR_BRAKE_N")
	)
	(segment
		(start 46.009052 -116.33581)
		(end 43.496738 -116.33581)
		(width 0.127)
		(layer "In15.Cu")
		(net "GPU_NVS_PWR_BRAKE_N")
	)
	(segment
		(start 47.043594 -115.301268)
		(end 46.009052 -116.33581)
		(width 0.127)
		(layer "In15.Cu")
		(net "GPU_NVS_PWR_BRAKE_N")
	)
	(segment
		(start 43.496738 -116.33581)
		(end 42.05224 -117.780308)
		(width 0.127)
		(layer "In15.Cu")
		(net "GPU_NVS_PWR_BRAKE_N")
	)
	(segment
		(start 28.83662 -117.780308)
		(end 17.83588 -128.781048)
		(width 0.127)
		(layer "In15.Cu")
		(net "GPU_NVS_PWR_BRAKE_N")
	)
	(segment
		(start 173.533054 -415.900362)
		(end 173.719998 -415.713418)
		(width 0.12954)
		(layer "F.Cu")
		(net "GPU_HMC_PRSNT_N")
	)
	(segment
		(start 173.719998 -415.713418)
		(end 174.408338 -415.713418)
		(width 0.12954)
		(layer "F.Cu")
		(net "GPU_HMC_PRSNT_N")
	)
	(segment
		(start 175.659288 -414.07334)
		(end 175.659288 -414.697418)
		(width 0.12954)
		(layer "F.Cu")
		(net "GPU_HMC_PRSNT_N")
	)
	(segment
		(start 161.39414 -422.71188)
		(end 161.39414 -417.4871)
		(width 0.12954)
		(layer "F.Cu")
		(net "GPU_HMC_PRSNT_N")
	)
	(segment
		(start 162.84702 -416.03422)
		(end 166.48176 -416.03422)
		(width 0.12954)
		(layer "F.Cu")
		(net "GPU_HMC_PRSNT_N")
	)
	(segment
		(start 175.659288 -414.697418)
		(end 175.659288 -415.713418)
		(width 0.12954)
		(layer "F.Cu")
		(net "GPU_HMC_PRSNT_N")
	)
	(segment
		(start 172.997368 -415.900362)
		(end 173.533054 -415.900362)
		(width 0.12954)
		(layer "F.Cu")
		(net "GPU_HMC_PRSNT_N")
	)
	(segment
		(start 174.408338 -415.713418)
		(end 175.659288 -415.713418)
		(width 0.12954)
		(layer "F.Cu")
		(net "GPU_HMC_PRSNT_N")
	)
	(segment
		(start 175.529748 -413.9438)
		(end 175.659288 -414.07334)
		(width 0.12954)
		(layer "F.Cu")
		(net "GPU_HMC_PRSNT_N")
	)
	(segment
		(start 174.16272 -413.9438)
		(end 175.529748 -413.9438)
		(width 0.12954)
		(layer "F.Cu")
		(net "GPU_HMC_PRSNT_N")
	)
	(segment
		(start 169.26814 -413.24784)
		(end 173.46676 -413.24784)
		(width 0.12954)
		(layer "F.Cu")
		(net "GPU_HMC_PRSNT_N")
	)
	(segment
		(start 166.48176 -416.03422)
		(end 169.26814 -413.24784)
		(width 0.12954)
		(layer "F.Cu")
		(net "GPU_HMC_PRSNT_N")
	)
	(segment
		(start 161.39414 -417.4871)
		(end 162.84702 -416.03422)
		(width 0.12954)
		(layer "F.Cu")
		(net "GPU_HMC_PRSNT_N")
	)
	(segment
		(start 173.46676 -413.24784)
		(end 174.16272 -413.9438)
		(width 0.12954)
		(layer "F.Cu")
		(net "GPU_HMC_PRSNT_N")
	)
	(via
		(at 174.408338 -415.713418)
		(size 0.762)
		(drill 0.381)
		(layers "F.Cu" "B.Cu")
		(net "GPU_HMC_PRSNT_N")
	)
	(via
		(at 161.39414 -422.71188)
		(size 0.508)
		(drill 0.254)
		(layers "F.Cu" "B.Cu")
		(net "GPU_HMC_PRSNT_N")
	)
	(segment
		(start 130.84048 -422.925748)
		(end 133.006338 -420.75989)
		(width 0.127)
		(layer "In2.Cu")
		(net "GPU_HMC_PRSNT_N")
	)
	(segment
		(start 161.046668 -422.364408)
		(end 161.39414 -422.71188)
		(width 0.127)
		(layer "In2.Cu")
		(net "GPU_HMC_PRSNT_N")
	)
	(segment
		(start 129.750058 -440.489848)
		(end 130.11658 -440.489848)
		(width 0.127)
		(layer "In2.Cu")
		(net "GPU_HMC_PRSNT_N")
	)
	(segment
		(start 130.11658 -440.489848)
		(end 130.84048 -439.765948)
		(width 0.127)
		(layer "In2.Cu")
		(net "GPU_HMC_PRSNT_N")
	)
	(segment
		(start 160.60674 -422.364408)
		(end 161.046668 -422.364408)
		(width 0.127)
		(layer "In2.Cu")
		(net "GPU_HMC_PRSNT_N")
	)
	(segment
		(start 130.84048 -439.765948)
		(end 130.84048 -422.925748)
		(width 0.127)
		(layer "In2.Cu")
		(net "GPU_HMC_PRSNT_N")
	)
	(segment
		(start 133.006338 -420.75989)
		(end 159.002222 -420.75989)
		(width 0.127)
		(layer "In2.Cu")
		(net "GPU_HMC_PRSNT_N")
	)
	(segment
		(start 159.002222 -420.75989)
		(end 160.60674 -422.364408)
		(width 0.127)
		(layer "In2.Cu")
		(net "GPU_HMC_PRSNT_N")
	)
	(segment
		(start 157.42793 -112.486948)
		(end 158.04388 -112.486948)
		(width 0.12954)
		(layer "F.Cu")
		(net "GPU_HMC_PRSNT_ISO_R_N")
	)
	(segment
		(start 173.355762 -112.175544)
		(end 172.955712 -111.775494)
		(width 0.12954)
		(layer "F.Cu")
		(net "GPU_HMC_PRSNT_ISO_R_N")
	)
	(via
		(at 158.04388 -112.486948)
		(size 0.508)
		(drill 0.254)
		(layers "F.Cu" "B.Cu")
		(net "GPU_HMC_PRSNT_ISO_R_N")
	)
	(via
		(at 172.955712 -111.775494)
		(size 0.4572)
		(drill 0.254)
		(layers "F.Cu" "B.Cu")
		(net "GPU_HMC_PRSNT_ISO_R_N")
	)
	(segment
		(start 172.55744 -110.767368)
		(end 172.36186 -110.571788)
		(width 0.127)
		(layer "In6.Cu")
		(net "GPU_HMC_PRSNT_ISO_R_N")
	)
	(segment
		(start 161.57448 -110.780068)
		(end 160.6423 -111.712248)
		(width 0.127)
		(layer "In6.Cu")
		(net "GPU_HMC_PRSNT_ISO_R_N")
	)
	(segment
		(start 160.6423 -111.712248)
		(end 158.81858 -111.712248)
		(width 0.127)
		(layer "In6.Cu")
		(net "GPU_HMC_PRSNT_ISO_R_N")
	)
	(segment
		(start 169.39514 -110.571788)
		(end 169.18686 -110.780068)
		(width 0.127)
		(layer "In6.Cu")
		(net "GPU_HMC_PRSNT_ISO_R_N")
	)
	(segment
		(start 169.18686 -110.780068)
		(end 161.57448 -110.780068)
		(width 0.127)
		(layer "In6.Cu")
		(net "GPU_HMC_PRSNT_ISO_R_N")
	)
	(segment
		(start 172.955712 -111.775494)
		(end 172.55744 -111.377222)
		(width 0.127)
		(layer "In6.Cu")
		(net "GPU_HMC_PRSNT_ISO_R_N")
	)
	(segment
		(start 172.55744 -111.377222)
		(end 172.55744 -110.767368)
		(width 0.127)
		(layer "In6.Cu")
		(net "GPU_HMC_PRSNT_ISO_R_N")
	)
	(segment
		(start 172.36186 -110.571788)
		(end 169.39514 -110.571788)
		(width 0.127)
		(layer "In6.Cu")
		(net "GPU_HMC_PRSNT_ISO_R_N")
	)
	(segment
		(start 158.81858 -111.712248)
		(end 158.04388 -112.486948)
		(width 0.127)
		(layer "In6.Cu")
		(net "GPU_HMC_PRSNT_ISO_R_N")
	)
	(segment
		(start 156.62783 -112.486948)
		(end 156.01188 -112.486948)
		(width 0.12954)
		(layer "F.Cu")
		(net "GPU_HMC_PRSNT_ISO_N")
	)
	(segment
		(start 239.726724 -155.539948)
		(end 207.323436 -155.539948)
		(width 0.12954)
		(layer "F.Cu")
		(net "GPU_HMC_PRSNT_ISO_N")
	)
	(segment
		(start 191.82588 -162.316668)
		(end 189.4332 -164.709348)
		(width 0.12954)
		(layer "F.Cu")
		(net "GPU_HMC_PRSNT_ISO_N")
	)
	(segment
		(start 172.997368 -416.550348)
		(end 173.176438 -416.729418)
		(width 0.12954)
		(layer "F.Cu")
		(net "GPU_HMC_PRSNT_ISO_N")
	)
	(segment
		(start 183.81472 -163.388548)
		(end 183.72836 -163.302188)
		(width 0.12954)
		(layer "F.Cu")
		(net "GPU_HMC_PRSNT_ISO_N")
	)
	(segment
		(start 186.65952 -164.709348)
		(end 185.33872 -163.388548)
		(width 0.12954)
		(layer "F.Cu")
		(net "GPU_HMC_PRSNT_ISO_N")
	)
	(segment
		(start 200.546716 -162.316668)
		(end 191.82588 -162.316668)
		(width 0.12954)
		(layer "F.Cu")
		(net "GPU_HMC_PRSNT_ISO_N")
	)
	(segment
		(start 244.78488 -160.598104)
		(end 239.726724 -155.539948)
		(width 0.12954)
		(layer "F.Cu")
		(net "GPU_HMC_PRSNT_ISO_N")
	)
	(segment
		(start 174.29988 -416.729418)
		(end 175.678338 -416.729418)
		(width 0.12954)
		(layer "F.Cu")
		(net "GPU_HMC_PRSNT_ISO_N")
	)
	(segment
		(start 207.323436 -155.539948)
		(end 200.546716 -162.316668)
		(width 0.12954)
		(layer "F.Cu")
		(net "GPU_HMC_PRSNT_ISO_N")
	)
	(segment
		(start 244.78488 -164.404548)
		(end 244.78488 -160.598104)
		(width 0.12954)
		(layer "F.Cu")
		(net "GPU_HMC_PRSNT_ISO_N")
	)
	(segment
		(start 189.4332 -164.709348)
		(end 186.65952 -164.709348)
		(width 0.12954)
		(layer "F.Cu")
		(net "GPU_HMC_PRSNT_ISO_N")
	)
	(segment
		(start 175.678338 -417.745418)
		(end 175.678338 -416.729418)
		(width 0.12954)
		(layer "F.Cu")
		(net "GPU_HMC_PRSNT_ISO_N")
	)
	(segment
		(start 173.176438 -416.729418)
		(end 174.29988 -416.729418)
		(width 0.12954)
		(layer "F.Cu")
		(net "GPU_HMC_PRSNT_ISO_N")
	)
	(segment
		(start 185.33872 -163.388548)
		(end 183.81472 -163.388548)
		(width 0.12954)
		(layer "F.Cu")
		(net "GPU_HMC_PRSNT_ISO_N")
	)
	(via
		(at 156.01188 -112.486948)
		(size 0.508)
		(drill 0.254)
		(layers "F.Cu" "B.Cu")
		(net "GPU_HMC_PRSNT_ISO_N")
	)
	(via
		(at 244.78488 -164.404548)
		(size 0.508)
		(drill 0.254)
		(layers "F.Cu" "B.Cu")
		(net "GPU_HMC_PRSNT_ISO_N")
	)
	(via
		(at 183.72836 -163.302188)
		(size 0.508)
		(drill 0.254)
		(layers "F.Cu" "B.Cu")
		(net "GPU_HMC_PRSNT_ISO_N")
	)
	(via
		(at 174.29988 -416.729418)
		(size 0.508)
		(drill 0.254)
		(layers "F.Cu" "B.Cu")
		(net "GPU_HMC_PRSNT_ISO_N")
	)
	(segment
		(start 179.3494 -396.74038)
		(end 179.3494 -392.711432)
		(width 0.127)
		(layer "In2.Cu")
		(net "GPU_HMC_PRSNT_ISO_N")
	)
	(segment
		(start 177.4952 -417.26104)
		(end 178.34102 -416.41522)
		(width 0.127)
		(layer "In2.Cu")
		(net "GPU_HMC_PRSNT_ISO_N")
	)
	(segment
		(start 248.68886 -239.871504)
		(end 248.68886 -167.732964)
		(width 0.127)
		(layer "In2.Cu")
		(net "GPU_HMC_PRSNT_ISO_N")
	)
	(segment
		(start 249.301 -240.483644)
		(end 248.68886 -239.871504)
		(width 0.127)
		(layer "In2.Cu")
		(net "GPU_HMC_PRSNT_ISO_N")
	)
	(segment
		(start 199.450452 -372.61038)
		(end 216.05875 -372.61038)
		(width 0.127)
		(layer "In2.Cu")
		(net "GPU_HMC_PRSNT_ISO_N")
	)
	(segment
		(start 216.05875 -372.61038)
		(end 225.25228 -363.41685)
		(width 0.127)
		(layer "In2.Cu")
		(net "GPU_HMC_PRSNT_ISO_N")
	)
	(segment
		(start 178.34102 -416.41522)
		(end 178.34102 -408.8765)
		(width 0.127)
		(layer "In2.Cu")
		(net "GPU_HMC_PRSNT_ISO_N")
	)
	(segment
		(start 225.25228 -363.41685)
		(end 225.25228 -346.009468)
		(width 0.127)
		(layer "In2.Cu")
		(net "GPU_HMC_PRSNT_ISO_N")
	)
	(segment
		(start 248.68886 -167.732964)
		(end 245.360444 -164.404548)
		(width 0.127)
		(layer "In2.Cu")
		(net "GPU_HMC_PRSNT_ISO_N")
	)
	(segment
		(start 179.3494 -392.711432)
		(end 199.450452 -372.61038)
		(width 0.127)
		(layer "In2.Cu")
		(net "GPU_HMC_PRSNT_ISO_N")
	)
	(segment
		(start 249.301 -321.960748)
		(end 249.301 -240.483644)
		(width 0.127)
		(layer "In2.Cu")
		(net "GPU_HMC_PRSNT_ISO_N")
	)
	(segment
		(start 179.412138 -396.803118)
		(end 179.3494 -396.74038)
		(width 0.127)
		(layer "In2.Cu")
		(net "GPU_HMC_PRSNT_ISO_N")
	)
	(segment
		(start 179.412138 -407.805382)
		(end 179.412138 -396.803118)
		(width 0.127)
		(layer "In2.Cu")
		(net "GPU_HMC_PRSNT_ISO_N")
	)
	(segment
		(start 178.34102 -408.8765)
		(end 179.412138 -407.805382)
		(width 0.127)
		(layer "In2.Cu")
		(net "GPU_HMC_PRSNT_ISO_N")
	)
	(segment
		(start 225.25228 -346.009468)
		(end 249.301 -321.960748)
		(width 0.127)
		(layer "In2.Cu")
		(net "GPU_HMC_PRSNT_ISO_N")
	)
	(segment
		(start 174.29988 -416.729418)
		(end 174.831502 -417.26104)
		(width 0.127)
		(layer "In2.Cu")
		(net "GPU_HMC_PRSNT_ISO_N")
	)
	(segment
		(start 245.360444 -164.404548)
		(end 244.78488 -164.404548)
		(width 0.127)
		(layer "In2.Cu")
		(net "GPU_HMC_PRSNT_ISO_N")
	)
	(segment
		(start 174.831502 -417.26104)
		(end 177.4952 -417.26104)
		(width 0.127)
		(layer "In2.Cu")
		(net "GPU_HMC_PRSNT_ISO_N")
	)
	(segment
		(start 183.13908 -162.855148)
		(end 181.437026 -162.855148)
		(width 0.127)
		(layer "In11.Cu")
		(net "GPU_HMC_PRSNT_ISO_N")
	)
	(segment
		(start 156.34208 -112.486948)
		(end 156.01188 -112.486948)
		(width 0.127)
		(layer "In11.Cu")
		(net "GPU_HMC_PRSNT_ISO_N")
	)
	(segment
		(start 183.72836 -163.302188)
		(end 183.58612 -163.302188)
		(width 0.127)
		(layer "In11.Cu")
		(net "GPU_HMC_PRSNT_ISO_N")
	)
	(segment
		(start 181.17566 -163.116514)
		(end 181.17566 -164.232082)
		(width 0.127)
		(layer "In11.Cu")
		(net "GPU_HMC_PRSNT_ISO_N")
	)
	(segment
		(start 181.17566 -164.232082)
		(end 180.198776 -165.208966)
		(width 0.127)
		(layer "In11.Cu")
		(net "GPU_HMC_PRSNT_ISO_N")
	)
	(segment
		(start 183.58612 -163.302188)
		(end 183.13908 -162.855148)
		(width 0.127)
		(layer "In11.Cu")
		(net "GPU_HMC_PRSNT_ISO_N")
	)
	(segment
		(start 180.198776 -165.208966)
		(end 178.558698 -165.208966)
		(width 0.127)
		(layer "In11.Cu")
		(net "GPU_HMC_PRSNT_ISO_N")
	)
	(segment
		(start 176.40808 -163.058348)
		(end 176.40808 -159.59709)
		(width 0.127)
		(layer "In11.Cu")
		(net "GPU_HMC_PRSNT_ISO_N")
	)
	(segment
		(start 157.40888 -140.59789)
		(end 157.40888 -113.553748)
		(width 0.127)
		(layer "In11.Cu")
		(net "GPU_HMC_PRSNT_ISO_N")
	)
	(segment
		(start 181.437026 -162.855148)
		(end 181.17566 -163.116514)
		(width 0.127)
		(layer "In11.Cu")
		(net "GPU_HMC_PRSNT_ISO_N")
	)
	(segment
		(start 157.40888 -113.553748)
		(end 156.34208 -112.486948)
		(width 0.127)
		(layer "In11.Cu")
		(net "GPU_HMC_PRSNT_ISO_N")
	)
	(segment
		(start 178.558698 -165.208966)
		(end 176.40808 -163.058348)
		(width 0.127)
		(layer "In11.Cu")
		(net "GPU_HMC_PRSNT_ISO_N")
	)
	(segment
		(start 176.40808 -159.59709)
		(end 157.40888 -140.59789)
		(width 0.127)
		(layer "In11.Cu")
		(net "GPU_HMC_PRSNT_ISO_N")
	)
	(segment
		(start 171.590462 -415.250376)
		(end 171.097448 -415.250376)
		(width 0.12954)
		(layer "F.Cu")
		(net "GPU_HMC_PRSNT")
	)
	(segment
		(start 171.585128 -415.900362)
		(end 171.747688 -415.737802)
		(width 0.12954)
		(layer "F.Cu")
		(net "GPU_HMC_PRSNT")
	)
	(segment
		(start 171.097448 -415.900362)
		(end 169.836338 -415.900362)
		(width 0.12954)
		(layer "F.Cu")
		(net "GPU_HMC_PRSNT")
	)
	(segment
		(start 171.097448 -415.900362)
		(end 171.585128 -415.900362)
		(width 0.12954)
		(layer "F.Cu")
		(net "GPU_HMC_PRSNT")
	)
	(segment
		(start 171.747688 -415.407602)
		(end 171.590462 -415.250376)
		(width 0.12954)
		(layer "F.Cu")
		(net "GPU_HMC_PRSNT")
	)
	(segment
		(start 171.747688 -415.737802)
		(end 171.747688 -415.407602)
		(width 0.12954)
		(layer "F.Cu")
		(net "GPU_HMC_PRSNT")
	)
	(segment
		(start 169.836338 -415.900362)
		(end 169.836338 -417.237418)
		(width 0.12954)
		(layer "F.Cu")
		(net "GPU_HMC_PRSNT")
	)
	(via
		(at 169.836338 -415.900362)
		(size 0.762)
		(drill 0.381)
		(layers "F.Cu" "B.Cu")
		(net "GPU_HMC_PRSNT")
	)
	(segment
		(start 26.47823 -406.569418)
		(end 26.596086 -406.687274)
		(width 0.12954)
		(layer "F.Cu")
		(net "GPU_FPGA_THERM_OVERT_N")
	)
	(segment
		(start 26.596086 -406.687274)
		(end 27.131772 -406.687274)
		(width 0.12954)
		(layer "F.Cu")
		(net "GPU_FPGA_THERM_OVERT_N")
	)
	(segment
		(start 24.774652 -406.569418)
		(end 25.746202 -406.569418)
		(width 0.12954)
		(layer "F.Cu")
		(net "GPU_FPGA_THERM_OVERT_N")
	)
	(segment
		(start 25.746202 -406.569418)
		(end 26.47823 -406.569418)
		(width 0.12954)
		(layer "F.Cu")
		(net "GPU_FPGA_THERM_OVERT_N")
	)
	(segment
		(start 24.469852 -407.890218)
		(end 24.469852 -406.874218)
		(width 0.12954)
		(layer "F.Cu")
		(net "GPU_FPGA_THERM_OVERT_N")
	)
	(segment
		(start 24.469852 -406.874218)
		(end 24.774652 -406.569418)
		(width 0.12954)
		(layer "F.Cu")
		(net "GPU_FPGA_THERM_OVERT_N")
	)
	(segment
		(start 24.469852 -407.890218)
		(end 25.079452 -407.890218)
		(width 0.12954)
		(layer "F.Cu")
		(net "GPU_FPGA_THERM_OVERT_N")
	)
	(via
		(at 25.079452 -407.890218)
		(size 0.508)
		(drill 0.254)
		(layers "F.Cu" "B.Cu")
		(net "GPU_FPGA_THERM_OVERT_N")
	)
	(via
		(at 25.746202 -406.569418)
		(size 0.762)
		(drill 0.381)
		(layers "F.Cu" "B.Cu")
		(net "GPU_FPGA_THERM_OVERT_N")
	)
	(segment
		(start 50.0253 -404.261828)
		(end 50.0253 -402.874988)
		(width 0.12954)
		(layer "B.Cu")
		(net "GPU_FPGA_THERM_OVERT_N")
	)
	(segment
		(start 24.9555 -400.42084)
		(end 24.9555 -407.766266)
		(width 0.12954)
		(layer "B.Cu")
		(net "GPU_FPGA_THERM_OVERT_N")
	)
	(segment
		(start 49.46396 -402.313648)
		(end 47.6123 -402.313648)
		(width 0.12954)
		(layer "B.Cu")
		(net "GPU_FPGA_THERM_OVERT_N")
	)
	(segment
		(start 24.9555 -407.766266)
		(end 25.079452 -407.890218)
		(width 0.12954)
		(layer "B.Cu")
		(net "GPU_FPGA_THERM_OVERT_N")
	)
	(segment
		(start 68.64985 -417.48964)
		(end 68.64985 -414.412938)
		(width 0.12954)
		(layer "B.Cu")
		(net "GPU_FPGA_THERM_OVERT_N")
	)
	(segment
		(start 27.33548 -395.90726)
		(end 26.3525 -394.92428)
		(width 0.12954)
		(layer "B.Cu")
		(net "GPU_FPGA_THERM_OVERT_N")
	)
	(segment
		(start 26.3525 -394.92428)
		(end 25.29332 -394.92428)
		(width 0.12954)
		(layer "B.Cu")
		(net "GPU_FPGA_THERM_OVERT_N")
	)
	(segment
		(start 33.77692 -400.4056)
		(end 29.27858 -395.90726)
		(width 0.12954)
		(layer "B.Cu")
		(net "GPU_FPGA_THERM_OVERT_N")
	)
	(segment
		(start 47.6123 -402.313648)
		(end 45.704252 -400.4056)
		(width 0.12954)
		(layer "B.Cu")
		(net "GPU_FPGA_THERM_OVERT_N")
	)
	(segment
		(start 24.50592 -399.97126)
		(end 24.9555 -400.42084)
		(width 0.12954)
		(layer "B.Cu")
		(net "GPU_FPGA_THERM_OVERT_N")
	)
	(segment
		(start 25.29332 -394.92428)
		(end 24.50592 -395.71168)
		(width 0.12954)
		(layer "B.Cu")
		(net "GPU_FPGA_THERM_OVERT_N")
	)
	(segment
		(start 45.704252 -400.4056)
		(end 33.77692 -400.4056)
		(width 0.12954)
		(layer "B.Cu")
		(net "GPU_FPGA_THERM_OVERT_N")
	)
	(segment
		(start 68.64985 -414.412938)
		(end 67.18808 -412.951168)
		(width 0.12954)
		(layer "B.Cu")
		(net "GPU_FPGA_THERM_OVERT_N")
	)
	(segment
		(start 50.0253 -402.874988)
		(end 49.46396 -402.313648)
		(width 0.12954)
		(layer "B.Cu")
		(net "GPU_FPGA_THERM_OVERT_N")
	)
	(segment
		(start 29.27858 -395.90726)
		(end 27.33548 -395.90726)
		(width 0.12954)
		(layer "B.Cu")
		(net "GPU_FPGA_THERM_OVERT_N")
	)
	(segment
		(start 24.50592 -395.71168)
		(end 24.50592 -399.97126)
		(width 0.12954)
		(layer "B.Cu")
		(net "GPU_FPGA_THERM_OVERT_N")
	)
	(segment
		(start 67.18808 -411.041088)
		(end 66.74866 -410.601668)
		(width 0.12954)
		(layer "B.Cu")
		(net "GPU_FPGA_THERM_OVERT_N")
	)
	(segment
		(start 66.74866 -410.601668)
		(end 66.74866 -405.925528)
		(width 0.12954)
		(layer "B.Cu")
		(net "GPU_FPGA_THERM_OVERT_N")
	)
	(segment
		(start 66.27368 -405.450548)
		(end 51.21402 -405.450548)
		(width 0.12954)
		(layer "B.Cu")
		(net "GPU_FPGA_THERM_OVERT_N")
	)
	(segment
		(start 66.74866 -405.925528)
		(end 66.27368 -405.450548)
		(width 0.12954)
		(layer "B.Cu")
		(net "GPU_FPGA_THERM_OVERT_N")
	)
	(segment
		(start 67.18808 -412.951168)
		(end 67.18808 -411.041088)
		(width 0.12954)
		(layer "B.Cu")
		(net "GPU_FPGA_THERM_OVERT_N")
	)
	(segment
		(start 68.650104 -417.489894)
		(end 68.64985 -417.48964)
		(width 0.12954)
		(layer "B.Cu")
		(net "GPU_FPGA_THERM_OVERT_N")
	)
	(segment
		(start 51.21402 -405.450548)
		(end 50.0253 -404.261828)
		(width 0.12954)
		(layer "B.Cu")
		(net "GPU_FPGA_THERM_OVERT_N")
	)
	(segment
		(start 167.23868 -111.775748)
		(end 166.57828 -112.436148)
		(width 0.12954)
		(layer "F.Cu")
		(net "GPU_FPGA_THERM_OVERT_ISO_R_N")
	)
	(segment
		(start 166.27348 -112.740948)
		(end 166.57828 -112.436148)
		(width 0.12954)
		(layer "F.Cu")
		(net "GPU_FPGA_THERM_OVERT_ISO_R_N")
	)
	(segment
		(start 163.199826 -112.918748)
		(end 165.33368 -112.918748)
		(width 0.12954)
		(layer "F.Cu")
		(net "GPU_FPGA_THERM_OVERT_ISO_R_N")
	)
	(segment
		(start 170.555412 -111.775748)
		(end 167.23868 -111.775748)
		(width 0.12954)
		(layer "F.Cu")
		(net "GPU_FPGA_THERM_OVERT_ISO_R_N")
	)
	(segment
		(start 170.955716 -111.375444)
		(end 170.555412 -111.775748)
		(width 0.12954)
		(layer "F.Cu")
		(net "GPU_FPGA_THERM_OVERT_ISO_R_N")
	)
	(segment
		(start 161.23793 -112.232948)
		(end 162.514026 -112.232948)
		(width 0.12954)
		(layer "F.Cu")
		(net "GPU_FPGA_THERM_OVERT_ISO_R_N")
	)
	(segment
		(start 165.33368 -112.918748)
		(end 165.51148 -112.740948)
		(width 0.12954)
		(layer "F.Cu")
		(net "GPU_FPGA_THERM_OVERT_ISO_R_N")
	)
	(segment
		(start 162.514026 -112.232948)
		(end 163.199826 -112.918748)
		(width 0.12954)
		(layer "F.Cu")
		(net "GPU_FPGA_THERM_OVERT_ISO_R_N")
	)
	(segment
		(start 165.51148 -112.740948)
		(end 166.27348 -112.740948)
		(width 0.12954)
		(layer "F.Cu")
		(net "GPU_FPGA_THERM_OVERT_ISO_R_N")
	)
	(via
		(at 166.57828 -112.436148)
		(size 0.762)
		(drill 0.381)
		(layers "F.Cu" "B.Cu")
		(net "GPU_FPGA_THERM_OVERT_ISO_R_N")
	)
	(segment
		(start 24.831802 -405.477218)
		(end 24.450802 -405.858218)
		(width 0.12954)
		(layer "F.Cu")
		(net "GPU_FPGA_THERM_OVERT_ISO_N")
	)
	(segment
		(start 160.18383 -112.486948)
		(end 160.43783 -112.232948)
		(width 0.12954)
		(layer "F.Cu")
		(net "GPU_FPGA_THERM_OVERT_ISO_N")
	)
	(segment
		(start 26.571702 -405.477218)
		(end 25.55748 -405.477218)
		(width 0.12954)
		(layer "F.Cu")
		(net "GPU_FPGA_THERM_OVERT_ISO_N")
	)
	(segment
		(start 27.131772 -406.037288)
		(end 26.571702 -405.477218)
		(width 0.12954)
		(layer "F.Cu")
		(net "GPU_FPGA_THERM_OVERT_ISO_N")
	)
	(segment
		(start 159.82188 -112.486948)
		(end 160.18383 -112.486948)
		(width 0.12954)
		(layer "F.Cu")
		(net "GPU_FPGA_THERM_OVERT_ISO_N")
	)
	(segment
		(start 25.55748 -405.477218)
		(end 24.831802 -405.477218)
		(width 0.12954)
		(layer "F.Cu")
		(net "GPU_FPGA_THERM_OVERT_ISO_N")
	)
	(segment
		(start 24.450802 -404.842218)
		(end 24.450802 -405.858218)
		(width 0.12954)
		(layer "F.Cu")
		(net "GPU_FPGA_THERM_OVERT_ISO_N")
	)
	(via
		(at 159.82188 -112.486948)
		(size 0.508)
		(drill 0.254)
		(layers "F.Cu" "B.Cu")
		(net "GPU_FPGA_THERM_OVERT_ISO_N")
	)
	(via
		(at 144.09928 -116.195348)
		(size 0.508)
		(drill 0.254)
		(layers "F.Cu" "B.Cu")
		(net "GPU_FPGA_THERM_OVERT_ISO_N")
	)
	(via
		(at 25.55748 -405.477218)
		(size 0.508)
		(drill 0.254)
		(layers "F.Cu" "B.Cu")
		(net "GPU_FPGA_THERM_OVERT_ISO_N")
	)
	(segment
		(start 156.64688 -114.264948)
		(end 157.84068 -113.071148)
		(width 0.127)
		(layer "In4.Cu")
		(net "GPU_FPGA_THERM_OVERT_ISO_N")
	)
	(segment
		(start 159.79648 -112.512348)
		(end 159.82188 -112.486948)
		(width 0.127)
		(layer "In4.Cu")
		(net "GPU_FPGA_THERM_OVERT_ISO_N")
	)
	(segment
		(start 159.49168 -113.071148)
		(end 159.79648 -112.766348)
		(width 0.127)
		(layer "In4.Cu")
		(net "GPU_FPGA_THERM_OVERT_ISO_N")
	)
	(segment
		(start 147.47748 -116.195348)
		(end 150.33498 -113.337848)
		(width 0.127)
		(layer "In4.Cu")
		(net "GPU_FPGA_THERM_OVERT_ISO_N")
	)
	(segment
		(start 155.293568 -114.264948)
		(end 156.64688 -114.264948)
		(width 0.127)
		(layer "In4.Cu")
		(net "GPU_FPGA_THERM_OVERT_ISO_N")
	)
	(segment
		(start 144.09928 -116.195348)
		(end 147.47748 -116.195348)
		(width 0.127)
		(layer "In4.Cu")
		(net "GPU_FPGA_THERM_OVERT_ISO_N")
	)
	(segment
		(start 159.79648 -112.766348)
		(end 159.79648 -112.512348)
		(width 0.127)
		(layer "In4.Cu")
		(net "GPU_FPGA_THERM_OVERT_ISO_N")
	)
	(segment
		(start 154.366468 -113.337848)
		(end 155.293568 -114.264948)
		(width 0.127)
		(layer "In4.Cu")
		(net "GPU_FPGA_THERM_OVERT_ISO_N")
	)
	(segment
		(start 157.84068 -113.071148)
		(end 159.49168 -113.071148)
		(width 0.127)
		(layer "In4.Cu")
		(net "GPU_FPGA_THERM_OVERT_ISO_N")
	)
	(segment
		(start 150.33498 -113.337848)
		(end 154.366468 -113.337848)
		(width 0.127)
		(layer "In4.Cu")
		(net "GPU_FPGA_THERM_OVERT_ISO_N")
	)
	(segment
		(start 4.998974 -196.492114)
		(end 5.457444 -196.950584)
		(width 0.127)
		(layer "In13.Cu")
		(net "GPU_FPGA_THERM_OVERT_ISO_N")
	)
	(segment
		(start 143.967708 -116.195348)
		(end 141.53642 -113.76406)
		(width 0.127)
		(layer "In13.Cu")
		(net "GPU_FPGA_THERM_OVERT_ISO_N")
	)
	(segment
		(start 4.52628 -164.247068)
		(end 5.661152 -165.38194)
		(width 0.127)
		(layer "In13.Cu")
		(net "GPU_FPGA_THERM_OVERT_ISO_N")
	)
	(segment
		(start 4.80568 -131.237228)
		(end 4.80568 -154.682952)
		(width 0.127)
		(layer "In13.Cu")
		(net "GPU_FPGA_THERM_OVERT_ISO_N")
	)
	(segment
		(start 134.218426 -111.563658)
		(end 131.866386 -113.915698)
		(width 0.127)
		(layer "In13.Cu")
		(net "GPU_FPGA_THERM_OVERT_ISO_N")
	)
	(segment
		(start 106.339386 -113.915698)
		(end 104.154986 -116.100098)
		(width 0.127)
		(layer "In13.Cu")
		(net "GPU_FPGA_THERM_OVERT_ISO_N")
	)
	(segment
		(start 4.80568 -154.682952)
		(end 4.52628 -154.962352)
		(width 0.127)
		(layer "In13.Cu")
		(net "GPU_FPGA_THERM_OVERT_ISO_N")
	)
	(segment
		(start 16.5227 -400.789648)
		(end 21.106892 -405.37384)
		(width 0.127)
		(layer "In13.Cu")
		(net "GPU_FPGA_THERM_OVERT_ISO_N")
	)
	(segment
		(start 92.166186 -118.309898)
		(end 52.70119 -118.309898)
		(width 0.127)
		(layer "In13.Cu")
		(net "GPU_FPGA_THERM_OVERT_ISO_N")
	)
	(segment
		(start 94.375986 -116.100098)
		(end 92.166186 -118.309898)
		(width 0.127)
		(layer "In13.Cu")
		(net "GPU_FPGA_THERM_OVERT_ISO_N")
	)
	(segment
		(start 4.998974 -194.051936)
		(end 4.998974 -196.492114)
		(width 0.127)
		(layer "In13.Cu")
		(net "GPU_FPGA_THERM_OVERT_ISO_N")
	)
	(segment
		(start 18.923 -359.273348)
		(end 18.923 -381.083312)
		(width 0.127)
		(layer "In13.Cu")
		(net "GPU_FPGA_THERM_OVERT_ISO_N")
	)
	(segment
		(start 7.360412 -353.4537)
		(end 13.103352 -353.4537)
		(width 0.127)
		(layer "In13.Cu")
		(net "GPU_FPGA_THERM_OVERT_ISO_N")
	)
	(segment
		(start 144.09928 -116.195348)
		(end 143.967708 -116.195348)
		(width 0.127)
		(layer "In13.Cu")
		(net "GPU_FPGA_THERM_OVERT_ISO_N")
	)
	(segment
		(start 5.661152 -165.38194)
		(end 5.661152 -193.389758)
		(width 0.127)
		(layer "In13.Cu")
		(net "GPU_FPGA_THERM_OVERT_ISO_N")
	)
	(segment
		(start 25.454102 -405.37384)
		(end 25.55748 -405.477218)
		(width 0.127)
		(layer "In13.Cu")
		(net "GPU_FPGA_THERM_OVERT_ISO_N")
	)
	(segment
		(start 21.106892 -405.37384)
		(end 25.454102 -405.37384)
		(width 0.127)
		(layer "In13.Cu")
		(net "GPU_FPGA_THERM_OVERT_ISO_N")
	)
	(segment
		(start 13.103352 -353.4537)
		(end 18.923 -359.273348)
		(width 0.127)
		(layer "In13.Cu")
		(net "GPU_FPGA_THERM_OVERT_ISO_N")
	)
	(segment
		(start 131.866386 -113.915698)
		(end 106.339386 -113.915698)
		(width 0.127)
		(layer "In13.Cu")
		(net "GPU_FPGA_THERM_OVERT_ISO_N")
	)
	(segment
		(start 141.53642 -113.76406)
		(end 138.2649 -113.76406)
		(width 0.127)
		(layer "In13.Cu")
		(net "GPU_FPGA_THERM_OVERT_ISO_N")
	)
	(segment
		(start 4.7498 -350.843088)
		(end 7.360412 -353.4537)
		(width 0.127)
		(layer "In13.Cu")
		(net "GPU_FPGA_THERM_OVERT_ISO_N")
	)
	(segment
		(start 4.52628 -154.962352)
		(end 4.52628 -164.247068)
		(width 0.127)
		(layer "In13.Cu")
		(net "GPU_FPGA_THERM_OVERT_ISO_N")
	)
	(segment
		(start 4.7498 -335.143348)
		(end 4.7498 -350.843088)
		(width 0.127)
		(layer "In13.Cu")
		(net "GPU_FPGA_THERM_OVERT_ISO_N")
	)
	(segment
		(start 138.2649 -113.76406)
		(end 136.064498 -111.563658)
		(width 0.127)
		(layer "In13.Cu")
		(net "GPU_FPGA_THERM_OVERT_ISO_N")
	)
	(segment
		(start 18.923 -381.083312)
		(end 16.5227 -383.483612)
		(width 0.127)
		(layer "In13.Cu")
		(net "GPU_FPGA_THERM_OVERT_ISO_N")
	)
	(segment
		(start 5.661152 -193.389758)
		(end 4.998974 -194.051936)
		(width 0.127)
		(layer "In13.Cu")
		(net "GPU_FPGA_THERM_OVERT_ISO_N")
	)
	(segment
		(start 16.5227 -383.483612)
		(end 16.5227 -400.789648)
		(width 0.127)
		(layer "In13.Cu")
		(net "GPU_FPGA_THERM_OVERT_ISO_N")
	)
	(segment
		(start 136.064498 -111.563658)
		(end 134.218426 -111.563658)
		(width 0.127)
		(layer "In13.Cu")
		(net "GPU_FPGA_THERM_OVERT_ISO_N")
	)
	(segment
		(start 18.7071 -117.335808)
		(end 4.80568 -131.237228)
		(width 0.127)
		(layer "In13.Cu")
		(net "GPU_FPGA_THERM_OVERT_ISO_N")
	)
	(segment
		(start 104.154986 -116.100098)
		(end 94.375986 -116.100098)
		(width 0.127)
		(layer "In13.Cu")
		(net "GPU_FPGA_THERM_OVERT_ISO_N")
	)
	(segment
		(start 51.7271 -117.335808)
		(end 18.7071 -117.335808)
		(width 0.127)
		(layer "In13.Cu")
		(net "GPU_FPGA_THERM_OVERT_ISO_N")
	)
	(segment
		(start 5.457444 -334.435704)
		(end 4.7498 -335.143348)
		(width 0.127)
		(layer "In13.Cu")
		(net "GPU_FPGA_THERM_OVERT_ISO_N")
	)
	(segment
		(start 52.70119 -118.309898)
		(end 51.7271 -117.335808)
		(width 0.127)
		(layer "In13.Cu")
		(net "GPU_FPGA_THERM_OVERT_ISO_N")
	)
	(segment
		(start 5.457444 -196.950584)
		(end 5.457444 -334.435704)
		(width 0.127)
		(layer "In13.Cu")
		(net "GPU_FPGA_THERM_OVERT_ISO_N")
	)
	(segment
		(start 28.564332 -406.816814)
		(end 28.693872 -406.687274)
		(width 0.12954)
		(layer "F.Cu")
		(net "GPU_FPGA_THERM_OVERT")
	)
	(segment
		(start 28.693872 -406.687274)
		(end 29.031692 -406.687274)
		(width 0.12954)
		(layer "F.Cu")
		(net "GPU_FPGA_THERM_OVERT")
	)
	(segment
		(start 30.292802 -406.687274)
		(end 30.740858 -406.687274)
		(width 0.12954)
		(layer "F.Cu")
		(net "GPU_FPGA_THERM_OVERT")
	)
	(segment
		(start 29.031692 -406.687274)
		(end 30.292802 -406.687274)
		(width 0.12954)
		(layer "F.Cu")
		(net "GPU_FPGA_THERM_OVERT")
	)
	(segment
		(start 30.740858 -406.687274)
		(end 31.562802 -407.509218)
		(width 0.12954)
		(layer "F.Cu")
		(net "GPU_FPGA_THERM_OVERT")
	)
	(segment
		(start 28.564332 -407.192734)
		(end 28.564332 -406.816814)
		(width 0.12954)
		(layer "F.Cu")
		(net "GPU_FPGA_THERM_OVERT")
	)
	(segment
		(start 28.708858 -407.33726)
		(end 28.564332 -407.192734)
		(width 0.12954)
		(layer "F.Cu")
		(net "GPU_FPGA_THERM_OVERT")
	)
	(segment
		(start 29.031692 -407.33726)
		(end 28.708858 -407.33726)
		(width 0.12954)
		(layer "F.Cu")
		(net "GPU_FPGA_THERM_OVERT")
	)
	(via
		(at 30.292802 -406.687274)
		(size 0.762)
		(drill 0.381)
		(layers "F.Cu" "B.Cu")
		(net "GPU_FPGA_THERM_OVERT")
	)
	(segment
		(start 119.96039 -428.107348)
		(end 119.96039 -427.091348)
		(width 0.12954)
		(layer "F.Cu")
		(net "GPU_FPGA_RST_R_N")
	)
	(segment
		(start 113.56086 -418.457888)
		(end 114.3 -417.718748)
		(width 0.12954)
		(layer "F.Cu")
		(net "GPU_FPGA_RST_R_N")
	)
	(segment
		(start 114.3 -417.718748)
		(end 114.3 -417.17468)
		(width 0.12954)
		(layer "F.Cu")
		(net "GPU_FPGA_RST_R_N")
	)
	(segment
		(start 114.731038 -416.743642)
		(end 115.46332 -416.743642)
		(width 0.12954)
		(layer "F.Cu")
		(net "GPU_FPGA_RST_R_N")
	)
	(segment
		(start 114.3 -417.17468)
		(end 114.731038 -416.743642)
		(width 0.12954)
		(layer "F.Cu")
		(net "GPU_FPGA_RST_R_N")
	)
	(segment
		(start 201.03465 -122.748548)
		(end 201.64425 -122.748548)
		(width 0.12954)
		(layer "F.Cu")
		(net "GPU_FPGA_RST_R_N")
	)
	(segment
		(start 118.40972 -426.311568)
		(end 119.13108 -427.032928)
		(width 0.12954)
		(layer "F.Cu")
		(net "GPU_FPGA_RST_R_N")
	)
	(segment
		(start 119.90197 -427.032928)
		(end 119.96039 -427.091348)
		(width 0.12954)
		(layer "F.Cu")
		(net "GPU_FPGA_RST_R_N")
	)
	(segment
		(start 119.13108 -427.032928)
		(end 119.90197 -427.032928)
		(width 0.12954)
		(layer "F.Cu")
		(net "GPU_FPGA_RST_R_N")
	)
	(via
		(at 118.40972 -426.311568)
		(size 0.508)
		(drill 0.254)
		(layers "F.Cu" "B.Cu")
		(net "GPU_FPGA_RST_R_N")
	)
	(via
		(at 201.64425 -122.748548)
		(size 0.508)
		(drill 0.254)
		(layers "F.Cu" "B.Cu")
		(net "GPU_FPGA_RST_R_N")
	)
	(via
		(at 45.88256 -113.581688)
		(size 0.508)
		(drill 0.254)
		(layers "F.Cu" "B.Cu")
		(net "GPU_FPGA_RST_R_N")
	)
	(via
		(at 113.56086 -418.457888)
		(size 0.508)
		(drill 0.254)
		(layers "F.Cu" "B.Cu")
		(net "GPU_FPGA_RST_R_N")
	)
	(via
		(at 9.77138 -175.417988)
		(size 0.508)
		(drill 0.254)
		(layers "F.Cu" "B.Cu")
		(net "GPU_FPGA_RST_R_N")
	)
	(via
		(at 142.17142 -110.432088)
		(size 0.508)
		(drill 0.254)
		(layers "F.Cu" "B.Cu")
		(net "GPU_FPGA_RST_R_N")
	)
	(segment
		(start 185.56732 -118.570248)
		(end 185.3565 -118.781068)
		(width 0.127)
		(layer "In4.Cu")
		(net "GPU_FPGA_RST_R_N")
	)
	(segment
		(start 188.308234 -120.978168)
		(end 188.958474 -121.628408)
		(width 0.127)
		(layer "In4.Cu")
		(net "GPU_FPGA_RST_R_N")
	)
	(segment
		(start 142.17142 -109.223048)
		(end 151.85136 -99.543108)
		(width 0.127)
		(layer "In4.Cu")
		(net "GPU_FPGA_RST_R_N")
	)
	(segment
		(start 180.12918 -97.274888)
		(end 180.594 -97.739708)
		(width 0.127)
		(layer "In4.Cu")
		(net "GPU_FPGA_RST_R_N")
	)
	(segment
		(start 195.9864 -122.128788)
		(end 199.99452 -122.128788)
		(width 0.127)
		(layer "In4.Cu")
		(net "GPU_FPGA_RST_R_N")
	)
	(segment
		(start 185.3565 -118.781068)
		(end 185.3565 -120.744488)
		(width 0.127)
		(layer "In4.Cu")
		(net "GPU_FPGA_RST_R_N")
	)
	(segment
		(start 193.398902 -122.354848)
		(end 195.76034 -122.354848)
		(width 0.127)
		(layer "In4.Cu")
		(net "GPU_FPGA_RST_R_N")
	)
	(segment
		(start 171.30776 -99.543108)
		(end 172.7835 -98.067368)
		(width 0.127)
		(layer "In4.Cu")
		(net "GPU_FPGA_RST_R_N")
	)
	(segment
		(start 187.77458 -118.570248)
		(end 185.56732 -118.570248)
		(width 0.127)
		(layer "In4.Cu")
		(net "GPU_FPGA_RST_R_N")
	)
	(segment
		(start 178.0413 -97.274888)
		(end 180.12918 -97.274888)
		(width 0.127)
		(layer "In4.Cu")
		(net "GPU_FPGA_RST_R_N")
	)
	(segment
		(start 188.86678 -99.517708)
		(end 189.24778 -99.898708)
		(width 0.127)
		(layer "In4.Cu")
		(net "GPU_FPGA_RST_R_N")
	)
	(segment
		(start 185.59018 -120.978168)
		(end 188.308234 -120.978168)
		(width 0.127)
		(layer "In4.Cu")
		(net "GPU_FPGA_RST_R_N")
	)
	(segment
		(start 186.5249 -97.739708)
		(end 186.86272 -98.077528)
		(width 0.127)
		(layer "In4.Cu")
		(net "GPU_FPGA_RST_R_N")
	)
	(segment
		(start 187.83554 -98.077528)
		(end 188.86678 -99.108768)
		(width 0.127)
		(layer "In4.Cu")
		(net "GPU_FPGA_RST_R_N")
	)
	(segment
		(start 151.85136 -99.543108)
		(end 171.30776 -99.543108)
		(width 0.127)
		(layer "In4.Cu")
		(net "GPU_FPGA_RST_R_N")
	)
	(segment
		(start 199.99452 -122.128788)
		(end 200.61428 -122.748548)
		(width 0.127)
		(layer "In4.Cu")
		(net "GPU_FPGA_RST_R_N")
	)
	(segment
		(start 188.2648 -118.080028)
		(end 187.77458 -118.570248)
		(width 0.127)
		(layer "In4.Cu")
		(net "GPU_FPGA_RST_R_N")
	)
	(segment
		(start 117.80012 -422.697148)
		(end 113.56086 -418.457888)
		(width 0.127)
		(layer "In4.Cu")
		(net "GPU_FPGA_RST_R_N")
	)
	(segment
		(start 195.76034 -122.354848)
		(end 195.9864 -122.128788)
		(width 0.127)
		(layer "In4.Cu")
		(net "GPU_FPGA_RST_R_N")
	)
	(segment
		(start 186.86272 -98.077528)
		(end 187.83554 -98.077528)
		(width 0.127)
		(layer "In4.Cu")
		(net "GPU_FPGA_RST_R_N")
	)
	(segment
		(start 177.24882 -98.067368)
		(end 178.0413 -97.274888)
		(width 0.127)
		(layer "In4.Cu")
		(net "GPU_FPGA_RST_R_N")
	)
	(segment
		(start 189.24778 -99.898708)
		(end 189.24778 -100.775008)
		(width 0.127)
		(layer "In4.Cu")
		(net "GPU_FPGA_RST_R_N")
	)
	(segment
		(start 188.958474 -121.628408)
		(end 192.672462 -121.628408)
		(width 0.127)
		(layer "In4.Cu")
		(net "GPU_FPGA_RST_R_N")
	)
	(segment
		(start 172.7835 -98.067368)
		(end 177.24882 -98.067368)
		(width 0.127)
		(layer "In4.Cu")
		(net "GPU_FPGA_RST_R_N")
	)
	(segment
		(start 188.2648 -101.757988)
		(end 188.2648 -118.080028)
		(width 0.127)
		(layer "In4.Cu")
		(net "GPU_FPGA_RST_R_N")
	)
	(segment
		(start 200.61428 -122.748548)
		(end 201.64425 -122.748548)
		(width 0.127)
		(layer "In4.Cu")
		(net "GPU_FPGA_RST_R_N")
	)
	(segment
		(start 189.24778 -100.775008)
		(end 188.2648 -101.757988)
		(width 0.127)
		(layer "In4.Cu")
		(net "GPU_FPGA_RST_R_N")
	)
	(segment
		(start 142.17142 -110.432088)
		(end 142.17142 -109.223048)
		(width 0.127)
		(layer "In4.Cu")
		(net "GPU_FPGA_RST_R_N")
	)
	(segment
		(start 185.3565 -120.744488)
		(end 185.59018 -120.978168)
		(width 0.127)
		(layer "In4.Cu")
		(net "GPU_FPGA_RST_R_N")
	)
	(segment
		(start 192.672462 -121.628408)
		(end 193.398902 -122.354848)
		(width 0.127)
		(layer "In4.Cu")
		(net "GPU_FPGA_RST_R_N")
	)
	(segment
		(start 117.80012 -425.701968)
		(end 117.80012 -422.697148)
		(width 0.127)
		(layer "In4.Cu")
		(net "GPU_FPGA_RST_R_N")
	)
	(segment
		(start 180.594 -97.739708)
		(end 186.5249 -97.739708)
		(width 0.127)
		(layer "In4.Cu")
		(net "GPU_FPGA_RST_R_N")
	)
	(segment
		(start 188.86678 -99.108768)
		(end 188.86678 -99.517708)
		(width 0.127)
		(layer "In4.Cu")
		(net "GPU_FPGA_RST_R_N")
	)
	(segment
		(start 118.40972 -426.311568)
		(end 117.80012 -425.701968)
		(width 0.127)
		(layer "In4.Cu")
		(net "GPU_FPGA_RST_R_N")
	)
	(segment
		(start 5.87248 -253.639574)
		(end 8.966454 -256.733548)
		(width 0.127)
		(layer "In6.Cu")
		(net "GPU_FPGA_RST_R_N")
	)
	(segment
		(start 5.87248 -191.35344)
		(end 7.814564 -193.295524)
		(width 0.127)
		(layer "In6.Cu")
		(net "GPU_FPGA_RST_R_N")
	)
	(segment
		(start 117.1956 -398.399)
		(end 117.9322 -399.1356)
		(width 0.127)
		(layer "In6.Cu")
		(net "GPU_FPGA_RST_R_N")
	)
	(segment
		(start 33.50768 -337.524344)
		(end 31.57728 -339.454744)
		(width 0.127)
		(layer "In6.Cu")
		(net "GPU_FPGA_RST_R_N")
	)
	(segment
		(start 118.30685 -416.965638)
		(end 116.03228 -419.240208)
		(width 0.127)
		(layer "In6.Cu")
		(net "GPU_FPGA_RST_R_N")
	)
	(segment
		(start 117.348 -402.4884)
		(end 116.2304 -403.606)
		(width 0.127)
		(layer "In6.Cu")
		(net "GPU_FPGA_RST_R_N")
	)
	(segment
		(start 7.403846 -195.137786)
		(end 6.844538 -195.137786)
		(width 0.127)
		(layer "In6.Cu")
		(net "GPU_FPGA_RST_R_N")
	)
	(segment
		(start 58.492644 -393.309348)
		(end 99.31908 -393.309348)
		(width 0.127)
		(layer "In6.Cu")
		(net "GPU_FPGA_RST_R_N")
	)
	(segment
		(start 8.966454 -256.733548)
		(end 11.252454 -256.733548)
		(width 0.127)
		(layer "In6.Cu")
		(net "GPU_FPGA_RST_R_N")
	)
	(segment
		(start 115.44808 -395.214348)
		(end 116.500148 -395.214348)
		(width 0.127)
		(layer "In6.Cu")
		(net "GPU_FPGA_RST_R_N")
	)
	(segment
		(start 108.89488 -392.140948)
		(end 112.37468 -392.140948)
		(width 0.127)
		(layer "In6.Cu")
		(net "GPU_FPGA_RST_R_N")
	)
	(segment
		(start 114.34318 -419.240208)
		(end 113.56086 -418.457888)
		(width 0.127)
		(layer "In6.Cu")
		(net "GPU_FPGA_RST_R_N")
	)
	(segment
		(start 7.732014 -175.417988)
		(end 5.87248 -177.277522)
		(width 0.127)
		(layer "In6.Cu")
		(net "GPU_FPGA_RST_R_N")
	)
	(segment
		(start 116.2304 -403.606)
		(end 116.2304 -404.4696)
		(width 0.127)
		(layer "In6.Cu")
		(net "GPU_FPGA_RST_R_N")
	)
	(segment
		(start 116.03228 -419.240208)
		(end 114.34318 -419.240208)
		(width 0.127)
		(layer "In6.Cu")
		(net "GPU_FPGA_RST_R_N")
	)
	(segment
		(start 117.1956 -395.9098)
		(end 117.1956 -398.399)
		(width 0.127)
		(layer "In6.Cu")
		(net "GPU_FPGA_RST_R_N")
	)
	(segment
		(start 117.9322 -400.2024)
		(end 117.348 -400.7866)
		(width 0.127)
		(layer "In6.Cu")
		(net "GPU_FPGA_RST_R_N")
	)
	(segment
		(start 31.57728 -339.454744)
		(end 31.57728 -366.393984)
		(width 0.127)
		(layer "In6.Cu")
		(net "GPU_FPGA_RST_R_N")
	)
	(segment
		(start 33.50768 -331.441552)
		(end 33.50768 -337.524344)
		(width 0.127)
		(layer "In6.Cu")
		(net "GPU_FPGA_RST_R_N")
	)
	(segment
		(start 112.37468 -392.140948)
		(end 115.44808 -395.214348)
		(width 0.127)
		(layer "In6.Cu")
		(net "GPU_FPGA_RST_R_N")
	)
	(segment
		(start 7.814564 -194.727068)
		(end 7.403846 -195.137786)
		(width 0.127)
		(layer "In6.Cu")
		(net "GPU_FPGA_RST_R_N")
	)
	(segment
		(start 116.500148 -395.214348)
		(end 117.1956 -395.9098)
		(width 0.127)
		(layer "In6.Cu")
		(net "GPU_FPGA_RST_R_N")
	)
	(segment
		(start 31.57728 -366.393984)
		(end 58.492644 -393.309348)
		(width 0.127)
		(layer "In6.Cu")
		(net "GPU_FPGA_RST_R_N")
	)
	(segment
		(start 5.87248 -177.277522)
		(end 5.87248 -191.35344)
		(width 0.127)
		(layer "In6.Cu")
		(net "GPU_FPGA_RST_R_N")
	)
	(segment
		(start 15.136876 -324.856348)
		(end 26.922476 -324.856348)
		(width 0.127)
		(layer "In6.Cu")
		(net "GPU_FPGA_RST_R_N")
	)
	(segment
		(start 12.12088 -257.601974)
		(end 12.12088 -321.840352)
		(width 0.127)
		(layer "In6.Cu")
		(net "GPU_FPGA_RST_R_N")
	)
	(segment
		(start 99.31908 -393.309348)
		(end 100.53828 -392.090148)
		(width 0.127)
		(layer "In6.Cu")
		(net "GPU_FPGA_RST_R_N")
	)
	(segment
		(start 7.814564 -193.295524)
		(end 7.814564 -194.727068)
		(width 0.127)
		(layer "In6.Cu")
		(net "GPU_FPGA_RST_R_N")
	)
	(segment
		(start 100.53828 -392.090148)
		(end 108.84408 -392.090148)
		(width 0.127)
		(layer "In6.Cu")
		(net "GPU_FPGA_RST_R_N")
	)
	(segment
		(start 26.922476 -324.856348)
		(end 33.50768 -331.441552)
		(width 0.127)
		(layer "In6.Cu")
		(net "GPU_FPGA_RST_R_N")
	)
	(segment
		(start 117.348 -400.7866)
		(end 117.348 -402.4884)
		(width 0.127)
		(layer "In6.Cu")
		(net "GPU_FPGA_RST_R_N")
	)
	(segment
		(start 6.844538 -195.137786)
		(end 5.87248 -196.109844)
		(width 0.127)
		(layer "In6.Cu")
		(net "GPU_FPGA_RST_R_N")
	)
	(segment
		(start 117.9322 -399.1356)
		(end 117.9322 -400.2024)
		(width 0.127)
		(layer "In6.Cu")
		(net "GPU_FPGA_RST_R_N")
	)
	(segment
		(start 116.2304 -404.4696)
		(end 118.30685 -406.54605)
		(width 0.127)
		(layer "In6.Cu")
		(net "GPU_FPGA_RST_R_N")
	)
	(segment
		(start 12.12088 -321.840352)
		(end 15.136876 -324.856348)
		(width 0.127)
		(layer "In6.Cu")
		(net "GPU_FPGA_RST_R_N")
	)
	(segment
		(start 118.30685 -406.54605)
		(end 118.30685 -416.965638)
		(width 0.127)
		(layer "In6.Cu")
		(net "GPU_FPGA_RST_R_N")
	)
	(segment
		(start 9.77138 -175.417988)
		(end 7.732014 -175.417988)
		(width 0.127)
		(layer "In6.Cu")
		(net "GPU_FPGA_RST_R_N")
	)
	(segment
		(start 108.84408 -392.090148)
		(end 108.89488 -392.140948)
		(width 0.127)
		(layer "In6.Cu")
		(net "GPU_FPGA_RST_R_N")
	)
	(segment
		(start 5.87248 -196.109844)
		(end 5.87248 -253.639574)
		(width 0.127)
		(layer "In6.Cu")
		(net "GPU_FPGA_RST_R_N")
	)
	(segment
		(start 11.252454 -256.733548)
		(end 12.12088 -257.601974)
		(width 0.127)
		(layer "In6.Cu")
		(net "GPU_FPGA_RST_R_N")
	)
	(segment
		(start 140.95984 -110.432088)
		(end 137.78992 -107.262168)
		(width 0.127)
		(layer "In13.Cu")
		(net "GPU_FPGA_RST_R_N")
	)
	(segment
		(start 118.5799 -106.929428)
		(end 101.762814 -106.929428)
		(width 0.127)
		(layer "In13.Cu")
		(net "GPU_FPGA_RST_R_N")
	)
	(segment
		(start 142.17142 -110.432088)
		(end 140.95984 -110.432088)
		(width 0.127)
		(layer "In13.Cu")
		(net "GPU_FPGA_RST_R_N")
	)
	(segment
		(start 46.3931 -114.092228)
		(end 45.88256 -113.581688)
		(width 0.127)
		(layer "In13.Cu")
		(net "GPU_FPGA_RST_R_N")
	)
	(segment
		(start 64.629538 -113.46307)
		(end 51.52644 -113.46307)
		(width 0.127)
		(layer "In13.Cu")
		(net "GPU_FPGA_RST_R_N")
	)
	(segment
		(start 51.220878 -113.157508)
		(end 48.68164 -113.157508)
		(width 0.127)
		(layer "In13.Cu")
		(net "GPU_FPGA_RST_R_N")
	)
	(segment
		(start 80.039718 -108.062268)
		(end 76.854558 -111.247428)
		(width 0.127)
		(layer "In13.Cu")
		(net "GPU_FPGA_RST_R_N")
	)
	(segment
		(start 137.78992 -107.262168)
		(end 118.91264 -107.262168)
		(width 0.127)
		(layer "In13.Cu")
		(net "GPU_FPGA_RST_R_N")
	)
	(segment
		(start 118.91264 -107.262168)
		(end 118.5799 -106.929428)
		(width 0.127)
		(layer "In13.Cu")
		(net "GPU_FPGA_RST_R_N")
	)
	(segment
		(start 76.854558 -111.247428)
		(end 66.84518 -111.247428)
		(width 0.127)
		(layer "In13.Cu")
		(net "GPU_FPGA_RST_R_N")
	)
	(segment
		(start 47.74692 -114.092228)
		(end 46.3931 -114.092228)
		(width 0.127)
		(layer "In13.Cu")
		(net "GPU_FPGA_RST_R_N")
	)
	(segment
		(start 51.52644 -113.46307)
		(end 51.220878 -113.157508)
		(width 0.127)
		(layer "In13.Cu")
		(net "GPU_FPGA_RST_R_N")
	)
	(segment
		(start 101.762814 -106.929428)
		(end 100.629974 -108.062268)
		(width 0.127)
		(layer "In13.Cu")
		(net "GPU_FPGA_RST_R_N")
	)
	(segment
		(start 66.84518 -111.247428)
		(end 64.629538 -113.46307)
		(width 0.127)
		(layer "In13.Cu")
		(net "GPU_FPGA_RST_R_N")
	)
	(segment
		(start 100.629974 -108.062268)
		(end 80.039718 -108.062268)
		(width 0.127)
		(layer "In13.Cu")
		(net "GPU_FPGA_RST_R_N")
	)
	(segment
		(start 48.68164 -113.157508)
		(end 47.74692 -114.092228)
		(width 0.127)
		(layer "In13.Cu")
		(net "GPU_FPGA_RST_R_N")
	)
	(segment
		(start 11.426952 -175.417988)
		(end 9.77138 -175.417988)
		(width 0.127)
		(layer "In15.Cu")
		(net "GPU_FPGA_RST_R_N")
	)
	(segment
		(start 45.35932 -114.104928)
		(end 43.97248 -114.104928)
		(width 0.127)
		(layer "In15.Cu")
		(net "GPU_FPGA_RST_R_N")
	)
	(segment
		(start 45.88256 -113.581688)
		(end 45.35932 -114.104928)
		(width 0.127)
		(layer "In15.Cu")
		(net "GPU_FPGA_RST_R_N")
	)
	(segment
		(start 17.17548 -169.66946)
		(end 11.426952 -175.417988)
		(width 0.127)
		(layer "In15.Cu")
		(net "GPU_FPGA_RST_R_N")
	)
	(segment
		(start 29.172408 -116.510308)
		(end 17.17548 -128.507236)
		(width 0.127)
		(layer "In15.Cu")
		(net "GPU_FPGA_RST_R_N")
	)
	(segment
		(start 43.97248 -114.104928)
		(end 41.5671 -116.510308)
		(width 0.127)
		(layer "In15.Cu")
		(net "GPU_FPGA_RST_R_N")
	)
	(segment
		(start 41.5671 -116.510308)
		(end 29.172408 -116.510308)
		(width 0.127)
		(layer "In15.Cu")
		(net "GPU_FPGA_RST_R_N")
	)
	(segment
		(start 17.17548 -128.507236)
		(end 17.17548 -169.66946)
		(width 0.127)
		(layer "In15.Cu")
		(net "GPU_FPGA_RST_R_N")
	)
	(segment
		(start 120.6881 -420.192708)
		(end 120.77827 -420.102538)
		(width 0.12954)
		(layer "F.Cu")
		(net "GPU_FPGA_RST_R_BUF_N")
	)
	(segment
		(start 120.77827 -420.102538)
		(end 120.77827 -419.415468)
		(width 0.12954)
		(layer "F.Cu")
		(net "GPU_FPGA_RST_R_BUF_N")
	)
	(via
		(at 120.6881 -420.192708)
		(size 0.508)
		(drill 0.254)
		(layers "F.Cu" "B.Cu")
		(net "GPU_FPGA_RST_R_BUF_N")
	)
	(segment
		(start 87.92972 -440.489848)
		(end 88.76792 -439.651648)
		(width 0.127)
		(layer "In15.Cu")
		(net "GPU_FPGA_RST_R_BUF_N")
	)
	(segment
		(start 112.93348 -418.569648)
		(end 113.33226 -418.968428)
		(width 0.127)
		(layer "In15.Cu")
		(net "GPU_FPGA_RST_R_BUF_N")
	)
	(segment
		(start 89.31148 -423.367708)
		(end 96.37522 -423.367708)
		(width 0.127)
		(layer "In15.Cu")
		(net "GPU_FPGA_RST_R_BUF_N")
	)
	(segment
		(start 98.46818 -421.274748)
		(end 101.51364 -421.274748)
		(width 0.127)
		(layer "In15.Cu")
		(net "GPU_FPGA_RST_R_BUF_N")
	)
	(segment
		(start 96.37522 -423.367708)
		(end 98.46818 -421.274748)
		(width 0.127)
		(layer "In15.Cu")
		(net "GPU_FPGA_RST_R_BUF_N")
	)
	(segment
		(start 102.0572 -421.818308)
		(end 105.94086 -421.818308)
		(width 0.127)
		(layer "In15.Cu")
		(net "GPU_FPGA_RST_R_BUF_N")
	)
	(segment
		(start 113.33226 -418.968428)
		(end 115.13058 -418.968428)
		(width 0.127)
		(layer "In15.Cu")
		(net "GPU_FPGA_RST_R_BUF_N")
	)
	(segment
		(start 101.51364 -421.274748)
		(end 102.0572 -421.818308)
		(width 0.127)
		(layer "In15.Cu")
		(net "GPU_FPGA_RST_R_BUF_N")
	)
	(segment
		(start 119.06504 -418.569648)
		(end 120.6881 -420.192708)
		(width 0.127)
		(layer "In15.Cu")
		(net "GPU_FPGA_RST_R_BUF_N")
	)
	(segment
		(start 115.52936 -418.569648)
		(end 119.06504 -418.569648)
		(width 0.127)
		(layer "In15.Cu")
		(net "GPU_FPGA_RST_R_BUF_N")
	)
	(segment
		(start 105.94086 -421.818308)
		(end 109.18952 -418.569648)
		(width 0.127)
		(layer "In15.Cu")
		(net "GPU_FPGA_RST_R_BUF_N")
	)
	(segment
		(start 88.76792 -439.651648)
		(end 88.76792 -423.911268)
		(width 0.127)
		(layer "In15.Cu")
		(net "GPU_FPGA_RST_R_BUF_N")
	)
	(segment
		(start 109.18952 -418.569648)
		(end 112.93348 -418.569648)
		(width 0.127)
		(layer "In15.Cu")
		(net "GPU_FPGA_RST_R_BUF_N")
	)
	(segment
		(start 88.76792 -423.911268)
		(end 89.31148 -423.367708)
		(width 0.127)
		(layer "In15.Cu")
		(net "GPU_FPGA_RST_R_BUF_N")
	)
	(segment
		(start 87.650066 -440.489848)
		(end 87.92972 -440.489848)
		(width 0.127)
		(layer "In15.Cu")
		(net "GPU_FPGA_RST_R_BUF_N")
	)
	(segment
		(start 115.13058 -418.968428)
		(end 115.52936 -418.569648)
		(width 0.127)
		(layer "In15.Cu")
		(net "GPU_FPGA_RST_R_BUF_N")
	)
	(segment
		(start 119.97817 -418.399468)
		(end 119.97817 -417.383468)
		(width 0.12954)
		(layer "F.Cu")
		(net "GPU_FPGA_RST_R1_BUF_N")
	)
	(segment
		(start 118.58752 -417.383468)
		(end 117.947694 -416.743642)
		(width 0.12954)
		(layer "F.Cu")
		(net "GPU_FPGA_RST_R1_BUF_N")
	)
	(segment
		(start 118.59514 -417.383468)
		(end 118.58752 -417.383468)
		(width 0.12954)
		(layer "F.Cu")
		(net "GPU_FPGA_RST_R1_BUF_N")
	)
	(segment
		(start 119.97817 -417.383468)
		(end 118.59514 -417.383468)
		(width 0.12954)
		(layer "F.Cu")
		(net "GPU_FPGA_RST_R1_BUF_N")
	)
	(segment
		(start 117.947694 -416.743642)
		(end 117.36324 -416.743642)
		(width 0.12954)
		(layer "F.Cu")
		(net "GPU_FPGA_RST_R1_BUF_N")
	)
	(segment
		(start 119.97817 -419.415468)
		(end 119.97817 -418.399468)
		(width 0.12954)
		(layer "F.Cu")
		(net "GPU_FPGA_RST_R1_BUF_N")
	)
	(via
		(at 118.59514 -417.383468)
		(size 0.762)
		(drill 0.381)
		(layers "F.Cu" "B.Cu")
		(net "GPU_FPGA_RST_R1_BUF_N")
	)
	(segment
		(start 199.7202 -122.748548)
		(end 200.23455 -122.748548)
		(width 0.12954)
		(layer "F.Cu")
		(net "GPU_FPGA_RST_N")
	)
	(segment
		(start 185.355738 -120.975374)
		(end 185.755788 -121.375424)
		(width 0.12954)
		(layer "F.Cu")
		(net "GPU_FPGA_RST_N")
	)
	(segment
		(start 199.5932 -122.621548)
		(end 199.7202 -122.748548)
		(width 0.12954)
		(layer "F.Cu")
		(net "GPU_FPGA_RST_N")
	)
	(via
		(at 199.5932 -122.621548)
		(size 0.508)
		(drill 0.254)
		(layers "F.Cu" "B.Cu")
		(net "GPU_FPGA_RST_N")
	)
	(via
		(at 185.755788 -121.375424)
		(size 0.4572)
		(drill 0.254)
		(layers "F.Cu" "B.Cu")
		(net "GPU_FPGA_RST_N")
	)
	(segment
		(start 193.838068 -123.353068)
		(end 192.6082 -122.1232)
		(width 0.127)
		(layer "In4.Cu")
		(net "GPU_FPGA_RST_N")
	)
	(segment
		(start 195.9864 -123.353068)
		(end 193.838068 -123.353068)
		(width 0.127)
		(layer "In4.Cu")
		(net "GPU_FPGA_RST_N")
	)
	(segment
		(start 188.131196 -121.375424)
		(end 185.755788 -121.375424)
		(width 0.127)
		(layer "In4.Cu")
		(net "GPU_FPGA_RST_N")
	)
	(segment
		(start 196.71792 -122.621548)
		(end 195.9864 -123.353068)
		(width 0.127)
		(layer "In4.Cu")
		(net "GPU_FPGA_RST_N")
	)
	(segment
		(start 199.5932 -122.621548)
		(end 196.71792 -122.621548)
		(width 0.127)
		(layer "In4.Cu")
		(net "GPU_FPGA_RST_N")
	)
	(segment
		(start 192.6082 -122.1232)
		(end 188.878972 -122.1232)
		(width 0.127)
		(layer "In4.Cu")
		(net "GPU_FPGA_RST_N")
	)
	(segment
		(start 188.878972 -122.1232)
		(end 188.131196 -121.375424)
		(width 0.127)
		(layer "In4.Cu")
		(net "GPU_FPGA_RST_N")
	)
	(segment
		(start 116.559584 -39.335456)
		(end 117.810534 -39.335456)
		(width 0.12954)
		(layer "F.Cu")
		(net "GPU_FPGA_READY_R_N")
	)
	(segment
		(start 118.445534 -39.335456)
		(end 119.125492 -38.655498)
		(width 0.12954)
		(layer "F.Cu")
		(net "GPU_FPGA_READY_R_N")
	)
	(segment
		(start 117.810534 -39.335456)
		(end 118.445534 -39.335456)
		(width 0.12954)
		(layer "F.Cu")
		(net "GPU_FPGA_READY_R_N")
	)
	(segment
		(start 119.125492 -38.655498)
		(end 119.714264 -38.655498)
		(width 0.12954)
		(layer "F.Cu")
		(net "GPU_FPGA_READY_R_N")
	)
	(via
		(at 117.810534 -39.335456)
		(size 0.762)
		(drill 0.381)
		(layers "F.Cu" "B.Cu")
		(net "GPU_FPGA_READY_R_N")
	)
	(segment
		(start 30.348682 -403.695408)
		(end 29.666692 -403.695408)
		(width 0.12954)
		(layer "F.Cu")
		(net "GPU_FPGA_READY_N")
	)
	(segment
		(start 29.666692 -403.695408)
		(end 29.031692 -403.695408)
		(width 0.12954)
		(layer "F.Cu")
		(net "GPU_FPGA_READY_N")
	)
	(segment
		(start 115.759484 -39.335456)
		(end 115.069112 -39.335456)
		(width 0.12954)
		(layer "F.Cu")
		(net "GPU_FPGA_READY_N")
	)
	(segment
		(start 29.031692 -404.345394)
		(end 29.031692 -403.695408)
		(width 0.12954)
		(layer "F.Cu")
		(net "GPU_FPGA_READY_N")
	)
	(via
		(at 29.666692 -403.695408)
		(size 0.508)
		(drill 0.254)
		(layers "F.Cu" "B.Cu")
		(net "GPU_FPGA_READY_N")
	)
	(via
		(at 33.93186 -53.945028)
		(size 0.508)
		(drill 0.254)
		(layers "F.Cu" "B.Cu")
		(net "GPU_FPGA_READY_N")
	)
	(via
		(at 115.069112 -39.335456)
		(size 0.508)
		(drill 0.254)
		(layers "F.Cu" "B.Cu")
		(net "GPU_FPGA_READY_N")
	)
	(segment
		(start 22.9997 -109.002068)
		(end 22.9997 -101.839268)
		(width 0.127)
		(layer "In2.Cu")
		(net "GPU_FPGA_READY_N")
	)
	(segment
		(start 7.87146 -390.93902)
		(end 7.87146 -376.24512)
		(width 0.127)
		(layer "In2.Cu")
		(net "GPU_FPGA_READY_N")
	)
	(segment
		(start 14.5288 -171.086018)
		(end 14.5288 -165.376352)
		(width 0.127)
		(layer "In2.Cu")
		(net "GPU_FPGA_READY_N")
	)
	(segment
		(start 24.50084 -95.184468)
		(end 24.82342 -94.861888)
		(width 0.127)
		(layer "In2.Cu")
		(net "GPU_FPGA_READY_N")
	)
	(segment
		(start 29.297884 -403.3266)
		(end 27.51836 -403.3266)
		(width 0.127)
		(layer "In2.Cu")
		(net "GPU_FPGA_READY_N")
	)
	(segment
		(start 20.25904 -403.3266)
		(end 7.87146 -390.93902)
		(width 0.127)
		(layer "In2.Cu")
		(net "GPU_FPGA_READY_N")
	)
	(segment
		(start 14.5288 -165.376352)
		(end 16.74622 -163.158932)
		(width 0.127)
		(layer "In2.Cu")
		(net "GPU_FPGA_READY_N")
	)
	(segment
		(start 33.89376 -53.945028)
		(end 33.93186 -53.945028)
		(width 0.127)
		(layer "In2.Cu")
		(net "GPU_FPGA_READY_N")
	)
	(segment
		(start 6.477 -186.088528)
		(end 11.45794 -181.107588)
		(width 0.127)
		(layer "In2.Cu")
		(net "GPU_FPGA_READY_N")
	)
	(segment
		(start 7.03834 -194.846702)
		(end 7.29107 -194.846702)
		(width 0.127)
		(layer "In2.Cu")
		(net "GPU_FPGA_READY_N")
	)
	(segment
		(start 7.676896 -194.460876)
		(end 7.676896 -192.229994)
		(width 0.127)
		(layer "In2.Cu")
		(net "GPU_FPGA_READY_N")
	)
	(segment
		(start 19.32432 -364.79226)
		(end 19.32432 -345.486228)
		(width 0.127)
		(layer "In2.Cu")
		(net "GPU_FPGA_READY_N")
	)
	(segment
		(start 16.74622 -147.552156)
		(end 5.40258 -136.208516)
		(width 0.127)
		(layer "In2.Cu")
		(net "GPU_FPGA_READY_N")
	)
	(segment
		(start 24.82342 -94.861888)
		(end 24.82342 -88.026748)
		(width 0.127)
		(layer "In2.Cu")
		(net "GPU_FPGA_READY_N")
	)
	(segment
		(start 7.29107 -194.846702)
		(end 7.676896 -194.460876)
		(width 0.127)
		(layer "In2.Cu")
		(net "GPU_FPGA_READY_N")
	)
	(segment
		(start 15.458186 -113.899188)
		(end 19.10334 -113.899188)
		(width 0.127)
		(layer "In2.Cu")
		(net "GPU_FPGA_READY_N")
	)
	(segment
		(start 24.50084 -100.338128)
		(end 24.50084 -95.184468)
		(width 0.127)
		(layer "In2.Cu")
		(net "GPU_FPGA_READY_N")
	)
	(segment
		(start 6.477 -191.030098)
		(end 6.477 -186.088528)
		(width 0.127)
		(layer "In2.Cu")
		(net "GPU_FPGA_READY_N")
	)
	(segment
		(start 5.85978 -196.025262)
		(end 7.03834 -194.846702)
		(width 0.127)
		(layer "In2.Cu")
		(net "GPU_FPGA_READY_N")
	)
	(segment
		(start 16.74622 -163.158932)
		(end 16.74622 -147.552156)
		(width 0.127)
		(layer "In2.Cu")
		(net "GPU_FPGA_READY_N")
	)
	(segment
		(start 22.9997 -101.839268)
		(end 24.50084 -100.338128)
		(width 0.127)
		(layer "In2.Cu")
		(net "GPU_FPGA_READY_N")
	)
	(segment
		(start 26.09596 -403.1615)
		(end 25.93086 -403.3266)
		(width 0.127)
		(layer "In2.Cu")
		(net "GPU_FPGA_READY_N")
	)
	(segment
		(start 29.666692 -403.695408)
		(end 29.297884 -403.3266)
		(width 0.127)
		(layer "In2.Cu")
		(net "GPU_FPGA_READY_N")
	)
	(segment
		(start 7.676896 -192.229994)
		(end 6.477 -191.030098)
		(width 0.127)
		(layer "In2.Cu")
		(net "GPU_FPGA_READY_N")
	)
	(segment
		(start 11.45794 -174.156878)
		(end 14.5288 -171.086018)
		(width 0.127)
		(layer "In2.Cu")
		(net "GPU_FPGA_READY_N")
	)
	(segment
		(start 11.45794 -181.107588)
		(end 11.45794 -174.156878)
		(width 0.127)
		(layer "In2.Cu")
		(net "GPU_FPGA_READY_N")
	)
	(segment
		(start 25.93086 -403.3266)
		(end 20.25904 -403.3266)
		(width 0.127)
		(layer "In2.Cu")
		(net "GPU_FPGA_READY_N")
	)
	(segment
		(start 27.35326 -403.1615)
		(end 26.09596 -403.1615)
		(width 0.127)
		(layer "In2.Cu")
		(net "GPU_FPGA_READY_N")
	)
	(segment
		(start 33.767776 -79.082392)
		(end 33.767776 -54.071012)
		(width 0.127)
		(layer "In2.Cu")
		(net "GPU_FPGA_READY_N")
	)
	(segment
		(start 5.40258 -123.954794)
		(end 15.458186 -113.899188)
		(width 0.127)
		(layer "In2.Cu")
		(net "GPU_FPGA_READY_N")
	)
	(segment
		(start 7.87146 -376.24512)
		(end 19.32432 -364.79226)
		(width 0.127)
		(layer "In2.Cu")
		(net "GPU_FPGA_READY_N")
	)
	(segment
		(start 24.82342 -88.026748)
		(end 33.767776 -79.082392)
		(width 0.127)
		(layer "In2.Cu")
		(net "GPU_FPGA_READY_N")
	)
	(segment
		(start 5.85978 -332.021688)
		(end 5.85978 -196.025262)
		(width 0.127)
		(layer "In2.Cu")
		(net "GPU_FPGA_READY_N")
	)
	(segment
		(start 19.10334 -113.899188)
		(end 19.95932 -113.043208)
		(width 0.127)
		(layer "In2.Cu")
		(net "GPU_FPGA_READY_N")
	)
	(segment
		(start 27.51836 -403.3266)
		(end 27.35326 -403.1615)
		(width 0.127)
		(layer "In2.Cu")
		(net "GPU_FPGA_READY_N")
	)
	(segment
		(start 19.95932 -112.042448)
		(end 22.9997 -109.002068)
		(width 0.127)
		(layer "In2.Cu")
		(net "GPU_FPGA_READY_N")
	)
	(segment
		(start 19.95932 -113.043208)
		(end 19.95932 -112.042448)
		(width 0.127)
		(layer "In2.Cu")
		(net "GPU_FPGA_READY_N")
	)
	(segment
		(start 5.40258 -136.208516)
		(end 5.40258 -123.954794)
		(width 0.127)
		(layer "In2.Cu")
		(net "GPU_FPGA_READY_N")
	)
	(segment
		(start 19.32432 -345.486228)
		(end 5.85978 -332.021688)
		(width 0.127)
		(layer "In2.Cu")
		(net "GPU_FPGA_READY_N")
	)
	(segment
		(start 33.767776 -54.071012)
		(end 33.89376 -53.945028)
		(width 0.127)
		(layer "In2.Cu")
		(net "GPU_FPGA_READY_N")
	)
	(segment
		(start 115.069112 -38.73246)
		(end 113.96472 -37.628068)
		(width 0.127)
		(layer "In15.Cu")
		(net "GPU_FPGA_READY_N")
	)
	(segment
		(start 115.069112 -39.335456)
		(end 115.069112 -38.73246)
		(width 0.127)
		(layer "In15.Cu")
		(net "GPU_FPGA_READY_N")
	)
	(segment
		(start 51.17084 -39.784528)
		(end 37.01034 -53.945028)
		(width 0.127)
		(layer "In15.Cu")
		(net "GPU_FPGA_READY_N")
	)
	(segment
		(start 113.96472 -37.628068)
		(end 112.1918 -37.628068)
		(width 0.127)
		(layer "In15.Cu")
		(net "GPU_FPGA_READY_N")
	)
	(segment
		(start 103.15448 -38.618668)
		(end 90.0811 -38.618668)
		(width 0.127)
		(layer "In15.Cu")
		(net "GPU_FPGA_READY_N")
	)
	(segment
		(start 66.1162 -37.582348)
		(end 63.91402 -39.784528)
		(width 0.127)
		(layer "In15.Cu")
		(net "GPU_FPGA_READY_N")
	)
	(segment
		(start 72.5678 -37.582348)
		(end 66.1162 -37.582348)
		(width 0.127)
		(layer "In15.Cu")
		(net "GPU_FPGA_READY_N")
	)
	(segment
		(start 90.0811 -38.618668)
		(end 89.058242 -39.641526)
		(width 0.127)
		(layer "In15.Cu")
		(net "GPU_FPGA_READY_N")
	)
	(segment
		(start 63.91402 -39.784528)
		(end 51.17084 -39.784528)
		(width 0.127)
		(layer "In15.Cu")
		(net "GPU_FPGA_READY_N")
	)
	(segment
		(start 104.9274 -36.845748)
		(end 103.15448 -38.618668)
		(width 0.127)
		(layer "In15.Cu")
		(net "GPU_FPGA_READY_N")
	)
	(segment
		(start 37.01034 -53.945028)
		(end 33.93186 -53.945028)
		(width 0.127)
		(layer "In15.Cu")
		(net "GPU_FPGA_READY_N")
	)
	(segment
		(start 89.058242 -39.641526)
		(end 74.626978 -39.641526)
		(width 0.127)
		(layer "In15.Cu")
		(net "GPU_FPGA_READY_N")
	)
	(segment
		(start 74.626978 -39.641526)
		(end 72.5678 -37.582348)
		(width 0.127)
		(layer "In15.Cu")
		(net "GPU_FPGA_READY_N")
	)
	(segment
		(start 111.40948 -36.845748)
		(end 104.9274 -36.845748)
		(width 0.127)
		(layer "In15.Cu")
		(net "GPU_FPGA_READY_N")
	)
	(segment
		(start 112.1918 -37.628068)
		(end 111.40948 -36.845748)
		(width 0.127)
		(layer "In15.Cu")
		(net "GPU_FPGA_READY_N")
	)
	(segment
		(start 170.150028 -118.56974)
		(end 167.631872 -118.56974)
		(width 0.12954)
		(layer "F.Cu")
		(net "GPU_FPGA_READY_ISO_R")
	)
	(segment
		(start 167.631872 -118.56974)
		(end 167.086788 -118.024656)
		(width 0.12954)
		(layer "F.Cu")
		(net "GPU_FPGA_READY_ISO_R")
	)
	(segment
		(start 166.069772 -118.024656)
		(end 166.5478 -118.024656)
		(width 0.12954)
		(layer "F.Cu")
		(net "GPU_FPGA_READY_ISO_R")
	)
	(segment
		(start 165.04793 -118.836948)
		(end 165.25748 -118.836948)
		(width 0.12954)
		(layer "F.Cu")
		(net "GPU_FPGA_READY_ISO_R")
	)
	(segment
		(start 167.086788 -118.024656)
		(end 166.5478 -118.024656)
		(width 0.12954)
		(layer "F.Cu")
		(net "GPU_FPGA_READY_ISO_R")
	)
	(segment
		(start 165.25748 -118.836948)
		(end 166.069772 -118.024656)
		(width 0.12954)
		(layer "F.Cu")
		(net "GPU_FPGA_READY_ISO_R")
	)
	(segment
		(start 170.155616 -118.575328)
		(end 170.150028 -118.56974)
		(width 0.12954)
		(layer "F.Cu")
		(net "GPU_FPGA_READY_ISO_R")
	)
	(via
		(at 166.5478 -118.024656)
		(size 0.762)
		(drill 0.381)
		(layers "F.Cu" "B.Cu")
		(net "GPU_FPGA_READY_ISO_R")
	)
	(segment
		(start 162.76828 -119.319548)
		(end 162.89528 -119.446548)
		(width 0.12954)
		(layer "F.Cu")
		(net "GPU_FPGA_READY_ISO")
	)
	(segment
		(start 162.76828 -118.836948)
		(end 162.76828 -119.319548)
		(width 0.12954)
		(layer "F.Cu")
		(net "GPU_FPGA_READY_ISO")
	)
	(segment
		(start 26.788364 -402.421598)
		(end 27.131772 -402.765006)
		(width 0.12954)
		(layer "F.Cu")
		(net "GPU_FPGA_READY_ISO")
	)
	(segment
		(start 164.24783 -119.262652)
		(end 164.24783 -118.836948)
		(width 0.12954)
		(layer "F.Cu")
		(net "GPU_FPGA_READY_ISO")
	)
	(segment
		(start 26.391108 -402.421598)
		(end 26.229056 -402.421598)
		(width 0.12954)
		(layer "F.Cu")
		(net "GPU_FPGA_READY_ISO")
	)
	(segment
		(start 25.844246 -402.806408)
		(end 24.450802 -402.806408)
		(width 0.12954)
		(layer "F.Cu")
		(net "GPU_FPGA_READY_ISO")
	)
	(segment
		(start 162.89528 -119.446548)
		(end 164.063934 -119.446548)
		(width 0.12954)
		(layer "F.Cu")
		(net "GPU_FPGA_READY_ISO")
	)
	(segment
		(start 164.063934 -119.446548)
		(end 164.24783 -119.262652)
		(width 0.12954)
		(layer "F.Cu")
		(net "GPU_FPGA_READY_ISO")
	)
	(segment
		(start 26.229056 -402.421598)
		(end 25.844246 -402.806408)
		(width 0.12954)
		(layer "F.Cu")
		(net "GPU_FPGA_READY_ISO")
	)
	(segment
		(start 24.450802 -402.806408)
		(end 24.450802 -401.790408)
		(width 0.12954)
		(layer "F.Cu")
		(net "GPU_FPGA_READY_ISO")
	)
	(segment
		(start 26.391108 -402.421598)
		(end 26.788364 -402.421598)
		(width 0.12954)
		(layer "F.Cu")
		(net "GPU_FPGA_READY_ISO")
	)
	(segment
		(start 27.131772 -402.765006)
		(end 27.131772 -403.045422)
		(width 0.12954)
		(layer "F.Cu")
		(net "GPU_FPGA_READY_ISO")
	)
	(via
		(at 26.391108 -402.421598)
		(size 0.508)
		(drill 0.254)
		(layers "F.Cu" "B.Cu")
		(net "GPU_FPGA_READY_ISO")
	)
	(via
		(at 162.76828 -118.836948)
		(size 0.508)
		(drill 0.254)
		(layers "F.Cu" "B.Cu")
		(net "GPU_FPGA_READY_ISO")
	)
	(segment
		(start 51.80076 -119.090948)
		(end 94.107 -119.090948)
		(width 0.127)
		(layer "In13.Cu")
		(net "GPU_FPGA_READY_ISO")
	)
	(segment
		(start 127.38608 -114.849148)
		(end 130.99288 -114.849148)
		(width 0.127)
		(layer "In13.Cu")
		(net "GPU_FPGA_READY_ISO")
	)
	(segment
		(start 19.06524 -402.29028)
		(end 17.2593 -400.48434)
		(width 0.127)
		(layer "In13.Cu")
		(net "GPU_FPGA_READY_ISO")
	)
	(segment
		(start 103.25608 -118.074948)
		(end 105.89768 -115.433348)
		(width 0.127)
		(layer "In13.Cu")
		(net "GPU_FPGA_READY_ISO")
	)
	(segment
		(start 151.49068 -120.030748)
		(end 153.34488 -118.176548)
		(width 0.127)
		(layer "In13.Cu")
		(net "GPU_FPGA_READY_ISO")
	)
	(segment
		(start 16.48968 -162.829748)
		(end 16.48968 -158.079948)
		(width 0.127)
		(layer "In13.Cu")
		(net "GPU_FPGA_READY_ISO")
	)
	(segment
		(start 156.7434 -118.903496)
		(end 156.7434 -120.02516)
		(width 0.127)
		(layer "In13.Cu")
		(net "GPU_FPGA_READY_ISO")
	)
	(segment
		(start 134.004812 -115.407948)
		(end 134.54888 -114.86388)
		(width 0.127)
		(layer "In13.Cu")
		(net "GPU_FPGA_READY_ISO")
	)
	(segment
		(start 140.133832 -115.95608)
		(end 141.848332 -115.95608)
		(width 0.127)
		(layer "In13.Cu")
		(net "GPU_FPGA_READY_ISO")
	)
	(segment
		(start 6.43128 -195.489576)
		(end 7.58444 -194.336416)
		(width 0.127)
		(layer "In13.Cu")
		(net "GPU_FPGA_READY_ISO")
	)
	(segment
		(start 137.314432 -114.86388)
		(end 137.8585 -115.407948)
		(width 0.127)
		(layer "In13.Cu")
		(net "GPU_FPGA_READY_ISO")
	)
	(segment
		(start 126.80188 -115.433348)
		(end 127.38608 -114.849148)
		(width 0.127)
		(layer "In13.Cu")
		(net "GPU_FPGA_READY_ISO")
	)
	(segment
		(start 7.58444 -194.336416)
		(end 7.58444 -191.587628)
		(width 0.127)
		(layer "In13.Cu")
		(net "GPU_FPGA_READY_ISO")
	)
	(segment
		(start 94.107 -119.090948)
		(end 95.123 -118.074948)
		(width 0.127)
		(layer "In13.Cu")
		(net "GPU_FPGA_READY_ISO")
	)
	(segment
		(start 16.48968 -158.079948)
		(end 14.0208 -155.611068)
		(width 0.127)
		(layer "In13.Cu")
		(net "GPU_FPGA_READY_ISO")
	)
	(segment
		(start 6.43128 -334.787748)
		(end 6.43128 -195.489576)
		(width 0.127)
		(layer "In13.Cu")
		(net "GPU_FPGA_READY_ISO")
	)
	(segment
		(start 137.8585 -115.407948)
		(end 139.5857 -115.407948)
		(width 0.127)
		(layer "In13.Cu")
		(net "GPU_FPGA_READY_ISO")
	)
	(segment
		(start 17.2593 -383.78892)
		(end 19.6596 -381.38862)
		(width 0.127)
		(layer "In13.Cu")
		(net "GPU_FPGA_READY_ISO")
	)
	(segment
		(start 130.99288 -114.849148)
		(end 131.55168 -115.407948)
		(width 0.127)
		(layer "In13.Cu")
		(net "GPU_FPGA_READY_ISO")
	)
	(segment
		(start 134.54888 -114.86388)
		(end 137.314432 -114.86388)
		(width 0.127)
		(layer "In13.Cu")
		(net "GPU_FPGA_READY_ISO")
	)
	(segment
		(start 141.848332 -115.95608)
		(end 145.923 -120.030748)
		(width 0.127)
		(layer "In13.Cu")
		(net "GPU_FPGA_READY_ISO")
	)
	(segment
		(start 139.5857 -115.407948)
		(end 140.133832 -115.95608)
		(width 0.127)
		(layer "In13.Cu")
		(net "GPU_FPGA_READY_ISO")
	)
	(segment
		(start 162.016948 -119.58828)
		(end 162.76828 -118.836948)
		(width 0.127)
		(layer "In13.Cu")
		(net "GPU_FPGA_READY_ISO")
	)
	(segment
		(start 14.0208 -155.611068)
		(end 14.0208 -124.760228)
		(width 0.127)
		(layer "In13.Cu")
		(net "GPU_FPGA_READY_ISO")
	)
	(segment
		(start 6.43128 -190.434468)
		(end 6.43128 -172.888148)
		(width 0.127)
		(layer "In13.Cu")
		(net "GPU_FPGA_READY_ISO")
	)
	(segment
		(start 160.4137 -120.70334)
		(end 161.52876 -119.58828)
		(width 0.127)
		(layer "In13.Cu")
		(net "GPU_FPGA_READY_ISO")
	)
	(segment
		(start 156.7434 -120.02516)
		(end 157.42158 -120.70334)
		(width 0.127)
		(layer "In13.Cu")
		(net "GPU_FPGA_READY_ISO")
	)
	(segment
		(start 6.43128 -172.888148)
		(end 16.48968 -162.829748)
		(width 0.127)
		(layer "In13.Cu")
		(net "GPU_FPGA_READY_ISO")
	)
	(segment
		(start 95.123 -118.074948)
		(end 103.25608 -118.074948)
		(width 0.127)
		(layer "In13.Cu")
		(net "GPU_FPGA_READY_ISO")
	)
	(segment
		(start 145.923 -120.030748)
		(end 151.49068 -120.030748)
		(width 0.127)
		(layer "In13.Cu")
		(net "GPU_FPGA_READY_ISO")
	)
	(segment
		(start 19.6596 -348.016068)
		(end 6.43128 -334.787748)
		(width 0.127)
		(layer "In13.Cu")
		(net "GPU_FPGA_READY_ISO")
	)
	(segment
		(start 17.2593 -400.48434)
		(end 17.2593 -383.78892)
		(width 0.127)
		(layer "In13.Cu")
		(net "GPU_FPGA_READY_ISO")
	)
	(segment
		(start 157.42158 -120.70334)
		(end 160.4137 -120.70334)
		(width 0.127)
		(layer "In13.Cu")
		(net "GPU_FPGA_READY_ISO")
	)
	(segment
		(start 105.89768 -115.433348)
		(end 126.80188 -115.433348)
		(width 0.127)
		(layer "In13.Cu")
		(net "GPU_FPGA_READY_ISO")
	)
	(segment
		(start 26.391108 -402.421598)
		(end 26.25979 -402.29028)
		(width 0.127)
		(layer "In13.Cu")
		(net "GPU_FPGA_READY_ISO")
	)
	(segment
		(start 26.25979 -402.29028)
		(end 19.06524 -402.29028)
		(width 0.127)
		(layer "In13.Cu")
		(net "GPU_FPGA_READY_ISO")
	)
	(segment
		(start 7.58444 -191.587628)
		(end 6.43128 -190.434468)
		(width 0.127)
		(layer "In13.Cu")
		(net "GPU_FPGA_READY_ISO")
	)
	(segment
		(start 153.34488 -118.176548)
		(end 156.016452 -118.176548)
		(width 0.127)
		(layer "In13.Cu")
		(net "GPU_FPGA_READY_ISO")
	)
	(segment
		(start 14.0208 -124.760228)
		(end 20.73148 -118.049548)
		(width 0.127)
		(layer "In13.Cu")
		(net "GPU_FPGA_READY_ISO")
	)
	(segment
		(start 19.6596 -381.38862)
		(end 19.6596 -348.016068)
		(width 0.127)
		(layer "In13.Cu")
		(net "GPU_FPGA_READY_ISO")
	)
	(segment
		(start 156.016452 -118.176548)
		(end 156.7434 -118.903496)
		(width 0.127)
		(layer "In13.Cu")
		(net "GPU_FPGA_READY_ISO")
	)
	(segment
		(start 50.75936 -118.049548)
		(end 51.80076 -119.090948)
		(width 0.127)
		(layer "In13.Cu")
		(net "GPU_FPGA_READY_ISO")
	)
	(segment
		(start 161.52876 -119.58828)
		(end 162.016948 -119.58828)
		(width 0.127)
		(layer "In13.Cu")
		(net "GPU_FPGA_READY_ISO")
	)
	(segment
		(start 131.55168 -115.407948)
		(end 134.004812 -115.407948)
		(width 0.127)
		(layer "In13.Cu")
		(net "GPU_FPGA_READY_ISO")
	)
	(segment
		(start 20.73148 -118.049548)
		(end 50.75936 -118.049548)
		(width 0.127)
		(layer "In13.Cu")
		(net "GPU_FPGA_READY_ISO")
	)
	(segment
		(start 27.131772 -403.695408)
		(end 26.496772 -403.695408)
		(width 0.12954)
		(layer "F.Cu")
		(net "GPU_FPGA_READY")
	)
	(segment
		(start 22.67077 -403.30882)
		(end 23.937214 -403.30882)
		(width 0.12954)
		(layer "F.Cu")
		(net "GPU_FPGA_READY")
	)
	(segment
		(start 23.937214 -403.30882)
		(end 24.450802 -403.822408)
		(width 0.12954)
		(layer "F.Cu")
		(net "GPU_FPGA_READY")
	)
	(segment
		(start 26.496772 -403.695408)
		(end 24.577802 -403.695408)
		(width 0.12954)
		(layer "F.Cu")
		(net "GPU_FPGA_READY")
	)
	(segment
		(start 24.577802 -403.695408)
		(end 24.450802 -403.822408)
		(width 0.12954)
		(layer "F.Cu")
		(net "GPU_FPGA_READY")
	)
	(segment
		(start 22.152102 -403.827488)
		(end 22.67077 -403.30882)
		(width 0.12954)
		(layer "F.Cu")
		(net "GPU_FPGA_READY")
	)
	(via
		(at 26.496772 -403.695408)
		(size 0.508)
		(drill 0.254)
		(layers "F.Cu" "B.Cu")
		(net "GPU_FPGA_READY")
	)
	(segment
		(start 60.65012 -416.445446)
		(end 60.65012 -417.489894)
		(width 0.12954)
		(layer "B.Cu")
		(net "GPU_FPGA_READY")
	)
	(segment
		(start 26.496772 -403.695408)
		(end 27.277568 -404.476204)
		(width 0.12954)
		(layer "B.Cu")
		(net "GPU_FPGA_READY")
	)
	(segment
		(start 48.716692 -411.276292)
		(end 49.05883 -411.48762)
		(width 0.12954)
		(layer "B.Cu")
		(net "GPU_FPGA_READY")
	)
	(segment
		(start 49.05883 -411.48762)
		(end 52.417726 -414.846008)
		(width 0.12954)
		(layer "B.Cu")
		(net "GPU_FPGA_READY")
	)
	(segment
		(start 59.050682 -414.846008)
		(end 60.65012 -416.445446)
		(width 0.12954)
		(layer "B.Cu")
		(net "GPU_FPGA_READY")
	)
	(segment
		(start 40.638476 -404.476204)
		(end 44.0182 -407.855928)
		(width 0.12954)
		(layer "B.Cu")
		(net "GPU_FPGA_READY")
	)
	(segment
		(start 44.0182 -407.855928)
		(end 45.296328 -407.855928)
		(width 0.12954)
		(layer "B.Cu")
		(net "GPU_FPGA_READY")
	)
	(segment
		(start 52.417726 -414.846008)
		(end 59.050682 -414.846008)
		(width 0.12954)
		(layer "B.Cu")
		(net "GPU_FPGA_READY")
	)
	(segment
		(start 27.277568 -404.476204)
		(end 40.638476 -404.476204)
		(width 0.12954)
		(layer "B.Cu")
		(net "GPU_FPGA_READY")
	)
	(segment
		(start 45.296328 -407.855928)
		(end 48.716692 -411.276292)
		(width 0.12954)
		(layer "B.Cu")
		(net "GPU_FPGA_READY")
	)
	(segment
		(start 424.60164 -398.630648)
		(end 424.623992 -398.608296)
		(width 0.12954)
		(layer "F.Cu")
		(net "GPU_FPGA_OVERT_N")
	)
	(segment
		(start 425.819062 -396.635478)
		(end 426.507402 -396.635478)
		(width 0.12954)
		(layer "F.Cu")
		(net "GPU_FPGA_OVERT_N")
	)
	(segment
		(start 424.623992 -396.635478)
		(end 424.623992 -397.651478)
		(width 0.12954)
		(layer "F.Cu")
		(net "GPU_FPGA_OVERT_N")
	)
	(segment
		(start 424.623992 -398.608296)
		(end 424.623992 -397.651478)
		(width 0.12954)
		(layer "F.Cu")
		(net "GPU_FPGA_OVERT_N")
	)
	(segment
		(start 426.694346 -396.448534)
		(end 427.230032 -396.448534)
		(width 0.12954)
		(layer "F.Cu")
		(net "GPU_FPGA_OVERT_N")
	)
	(segment
		(start 424.623992 -396.635478)
		(end 425.819062 -396.635478)
		(width 0.12954)
		(layer "F.Cu")
		(net "GPU_FPGA_OVERT_N")
	)
	(segment
		(start 426.507402 -396.635478)
		(end 426.694346 -396.448534)
		(width 0.12954)
		(layer "F.Cu")
		(net "GPU_FPGA_OVERT_N")
	)
	(via
		(at 424.60164 -398.630648)
		(size 0.508)
		(drill 0.254)
		(layers "F.Cu" "B.Cu")
		(net "GPU_FPGA_OVERT_N")
	)
	(via
		(at 425.819062 -396.635478)
		(size 0.762)
		(drill 0.381)
		(layers "F.Cu" "B.Cu")
		(net "GPU_FPGA_OVERT_N")
	)
	(segment
		(start 327.75144 -422.468548)
		(end 327.75144 -439.638948)
		(width 0.12954)
		(layer "B.Cu")
		(net "GPU_FPGA_OVERT_N")
	)
	(segment
		(start 352.7044 -416.2044)
		(end 351.409 -416.2044)
		(width 0.12954)
		(layer "B.Cu")
		(net "GPU_FPGA_OVERT_N")
	)
	(segment
		(start 424.1673 -399.064988)
		(end 424.1673 -407.446988)
		(width 0.12954)
		(layer "B.Cu")
		(net "GPU_FPGA_OVERT_N")
	)
	(segment
		(start 424.60164 -398.630648)
		(end 424.1673 -399.064988)
		(width 0.12954)
		(layer "B.Cu")
		(net "GPU_FPGA_OVERT_N")
	)
	(segment
		(start 373.670068 -419.6842)
		(end 356.1842 -419.6842)
		(width 0.12954)
		(layer "B.Cu")
		(net "GPU_FPGA_OVERT_N")
	)
	(segment
		(start 351.409 -416.2044)
		(end 349.6564 -417.957)
		(width 0.12954)
		(layer "B.Cu")
		(net "GPU_FPGA_OVERT_N")
	)
	(segment
		(start 332.262988 -417.957)
		(end 327.75144 -422.468548)
		(width 0.12954)
		(layer "B.Cu")
		(net "GPU_FPGA_OVERT_N")
	)
	(segment
		(start 326.90054 -440.489848)
		(end 326.650096 -440.489848)
		(width 0.12954)
		(layer "B.Cu")
		(net "GPU_FPGA_OVERT_N")
	)
	(segment
		(start 412.80334 -418.810948)
		(end 374.54332 -418.810948)
		(width 0.12954)
		(layer "B.Cu")
		(net "GPU_FPGA_OVERT_N")
	)
	(segment
		(start 349.6564 -417.957)
		(end 332.262988 -417.957)
		(width 0.12954)
		(layer "B.Cu")
		(net "GPU_FPGA_OVERT_N")
	)
	(segment
		(start 424.1673 -407.446988)
		(end 412.80334 -418.810948)
		(width 0.12954)
		(layer "B.Cu")
		(net "GPU_FPGA_OVERT_N")
	)
	(segment
		(start 327.75144 -439.638948)
		(end 326.90054 -440.489848)
		(width 0.12954)
		(layer "B.Cu")
		(net "GPU_FPGA_OVERT_N")
	)
	(segment
		(start 356.1842 -419.6842)
		(end 352.7044 -416.2044)
		(width 0.12954)
		(layer "B.Cu")
		(net "GPU_FPGA_OVERT_N")
	)
	(segment
		(start 374.54332 -418.810948)
		(end 373.670068 -419.6842)
		(width 0.12954)
		(layer "B.Cu")
		(net "GPU_FPGA_OVERT_N")
	)
	(segment
		(start 161.23793 -113.756948)
		(end 161.23793 -113.284)
		(width 0.12954)
		(layer "F.Cu")
		(net "GPU_FPGA_OVERT_ISO_R_N")
	)
	(segment
		(start 167.5892 -114.427)
		(end 168.64076 -113.37544)
		(width 0.12954)
		(layer "F.Cu")
		(net "GPU_FPGA_OVERT_ISO_R_N")
	)
	(segment
		(start 162.44443 -113.07953)
		(end 162.306 -113.21796)
		(width 0.12954)
		(layer "F.Cu")
		(net "GPU_FPGA_OVERT_ISO_R_N")
	)
	(segment
		(start 162.306 -114.0714)
		(end 162.6616 -114.427)
		(width 0.12954)
		(layer "F.Cu")
		(net "GPU_FPGA_OVERT_ISO_R_N")
	)
	(segment
		(start 170.555666 -113.37544)
		(end 170.955716 -112.97539)
		(width 0.12954)
		(layer "F.Cu")
		(net "GPU_FPGA_OVERT_ISO_R_N")
	)
	(segment
		(start 162.306 -113.21796)
		(end 162.306 -114.0714)
		(width 0.12954)
		(layer "F.Cu")
		(net "GPU_FPGA_OVERT_ISO_R_N")
	)
	(segment
		(start 162.6616 -114.427)
		(end 167.5892 -114.427)
		(width 0.12954)
		(layer "F.Cu")
		(net "GPU_FPGA_OVERT_ISO_R_N")
	)
	(segment
		(start 161.23793 -113.284)
		(end 161.4424 -113.07953)
		(width 0.12954)
		(layer "F.Cu")
		(net "GPU_FPGA_OVERT_ISO_R_N")
	)
	(segment
		(start 168.64076 -113.37544)
		(end 170.555666 -113.37544)
		(width 0.12954)
		(layer "F.Cu")
		(net "GPU_FPGA_OVERT_ISO_R_N")
	)
	(segment
		(start 161.4424 -113.07953)
		(end 162.44443 -113.07953)
		(width 0.12954)
		(layer "F.Cu")
		(net "GPU_FPGA_OVERT_ISO_R_N")
	)
	(via
		(at 162.44443 -113.07953)
		(size 0.762)
		(drill 0.381)
		(layers "F.Cu" "B.Cu")
		(net "GPU_FPGA_OVERT_ISO_R_N")
	)
	(segment
		(start 426.669962 -395.238478)
		(end 424.985942 -395.238478)
		(width 0.12954)
		(layer "F.Cu")
		(net "GPU_FPGA_OVERT_ISO_N")
	)
	(segment
		(start 160.43783 -113.756948)
		(end 159.82188 -113.756948)
		(width 0.12954)
		(layer "F.Cu")
		(net "GPU_FPGA_OVERT_ISO_N")
	)
	(segment
		(start 424.985942 -395.238478)
		(end 424.604942 -395.619478)
		(width 0.12954)
		(layer "F.Cu")
		(net "GPU_FPGA_OVERT_ISO_N")
	)
	(segment
		(start 424.604942 -394.603478)
		(end 424.604942 -395.619478)
		(width 0.12954)
		(layer "F.Cu")
		(net "GPU_FPGA_OVERT_ISO_N")
	)
	(segment
		(start 427.230032 -395.798548)
		(end 426.669962 -395.238478)
		(width 0.12954)
		(layer "F.Cu")
		(net "GPU_FPGA_OVERT_ISO_N")
	)
	(segment
		(start 424.604942 -394.603478)
		(end 424.604942 -393.90701)
		(width 0.12954)
		(layer "F.Cu")
		(net "GPU_FPGA_OVERT_ISO_N")
	)
	(via
		(at 236.419644 -206.19339)
		(size 0.508)
		(drill 0.254)
		(layers "F.Cu" "B.Cu")
		(net "GPU_FPGA_OVERT_ISO_N")
	)
	(via
		(at 424.604942 -393.90701)
		(size 0.508)
		(drill 0.254)
		(layers "F.Cu" "B.Cu")
		(net "GPU_FPGA_OVERT_ISO_N")
	)
	(via
		(at 198.41718 -125.329188)
		(size 0.508)
		(drill 0.254)
		(layers "F.Cu" "B.Cu")
		(net "GPU_FPGA_OVERT_ISO_N")
	)
	(via
		(at 159.82188 -113.756948)
		(size 0.508)
		(drill 0.254)
		(layers "F.Cu" "B.Cu")
		(net "GPU_FPGA_OVERT_ISO_N")
	)
	(via
		(at 304.402744 -394.002768)
		(size 0.508)
		(drill 0.254)
		(layers "F.Cu" "B.Cu")
		(net "GPU_FPGA_OVERT_ISO_N")
	)
	(segment
		(start 171.75988 -120.82018)
		(end 171.12234 -120.18264)
		(width 0.127)
		(layer "In4.Cu")
		(net "GPU_FPGA_OVERT_ISO_N")
	)
	(segment
		(start 191.3509 -122.804428)
		(end 182.92318 -122.804428)
		(width 0.127)
		(layer "In4.Cu")
		(net "GPU_FPGA_OVERT_ISO_N")
	)
	(segment
		(start 179.77612 -121.770648)
		(end 178.92776 -121.770648)
		(width 0.127)
		(layer "In4.Cu")
		(net "GPU_FPGA_OVERT_ISO_N")
	)
	(segment
		(start 168.57472 -119.85498)
		(end 168.57472 -113.769648)
		(width 0.127)
		(layer "In4.Cu")
		(net "GPU_FPGA_OVERT_ISO_N")
	)
	(segment
		(start 247.37568 -274.625562)
		(end 242.910614 -279.090628)
		(width 0.127)
		(layer "In4.Cu")
		(net "GPU_FPGA_OVERT_ISO_N")
	)
	(segment
		(start 182.16118 -122.042428)
		(end 180.0479 -122.042428)
		(width 0.127)
		(layer "In4.Cu")
		(net "GPU_FPGA_OVERT_ISO_N")
	)
	(segment
		(start 198.41718 -124.871988)
		(end 197.24624 -123.701048)
		(width 0.127)
		(layer "In4.Cu")
		(net "GPU_FPGA_OVERT_ISO_N")
	)
	(segment
		(start 242.910614 -329.042268)
		(end 275.216874 -361.348528)
		(width 0.127)
		(layer "In4.Cu")
		(net "GPU_FPGA_OVERT_ISO_N")
	)
	(segment
		(start 284.734 -385.8768)
		(end 284.734 -389.128)
		(width 0.127)
		(layer "In4.Cu")
		(net "GPU_FPGA_OVERT_ISO_N")
	)
	(segment
		(start 300.76902 -394.3223)
		(end 301.088552 -394.002768)
		(width 0.127)
		(layer "In4.Cu")
		(net "GPU_FPGA_OVERT_ISO_N")
	)
	(segment
		(start 280.8732 -382.016)
		(end 284.734 -385.8768)
		(width 0.127)
		(layer "In4.Cu")
		(net "GPU_FPGA_OVERT_ISO_N")
	)
	(segment
		(start 301.088552 -394.002768)
		(end 304.402744 -394.002768)
		(width 0.127)
		(layer "In4.Cu")
		(net "GPU_FPGA_OVERT_ISO_N")
	)
	(segment
		(start 296.7863 -394.3223)
		(end 300.76902 -394.3223)
		(width 0.127)
		(layer "In4.Cu")
		(net "GPU_FPGA_OVERT_ISO_N")
	)
	(segment
		(start 178.92776 -121.770648)
		(end 177.57648 -123.121928)
		(width 0.127)
		(layer "In4.Cu")
		(net "GPU_FPGA_OVERT_ISO_N")
	)
	(segment
		(start 288.02457 -392.41857)
		(end 295.63695 -392.41857)
		(width 0.127)
		(layer "In4.Cu")
		(net "GPU_FPGA_OVERT_ISO_N")
	)
	(segment
		(start 296.49928 -394.03528)
		(end 296.7863 -394.3223)
		(width 0.127)
		(layer "In4.Cu")
		(net "GPU_FPGA_OVERT_ISO_N")
	)
	(segment
		(start 198.41718 -125.329188)
		(end 198.41718 -124.871988)
		(width 0.127)
		(layer "In4.Cu")
		(net "GPU_FPGA_OVERT_ISO_N")
	)
	(segment
		(start 161.50336 -113.756948)
		(end 159.82188 -113.756948)
		(width 0.127)
		(layer "In4.Cu")
		(net "GPU_FPGA_OVERT_ISO_N")
	)
	(segment
		(start 162.22853 -113.031778)
		(end 161.50336 -113.756948)
		(width 0.127)
		(layer "In4.Cu")
		(net "GPU_FPGA_OVERT_ISO_N")
	)
	(segment
		(start 171.12234 -120.18264)
		(end 168.90238 -120.18264)
		(width 0.127)
		(layer "In4.Cu")
		(net "GPU_FPGA_OVERT_ISO_N")
	)
	(segment
		(start 236.419644 -206.19339)
		(end 247.37568 -217.149426)
		(width 0.127)
		(layer "In4.Cu")
		(net "GPU_FPGA_OVERT_ISO_N")
	)
	(segment
		(start 171.75988 -121.64314)
		(end 171.75988 -120.82018)
		(width 0.127)
		(layer "In4.Cu")
		(net "GPU_FPGA_OVERT_ISO_N")
	)
	(segment
		(start 192.24752 -123.701048)
		(end 191.3509 -122.804428)
		(width 0.127)
		(layer "In4.Cu")
		(net "GPU_FPGA_OVERT_ISO_N")
	)
	(segment
		(start 177.57648 -123.121928)
		(end 173.238668 -123.121928)
		(width 0.127)
		(layer "In4.Cu")
		(net "GPU_FPGA_OVERT_ISO_N")
	)
	(segment
		(start 296.49928 -393.2809)
		(end 296.49928 -394.03528)
		(width 0.127)
		(layer "In4.Cu")
		(net "GPU_FPGA_OVERT_ISO_N")
	)
	(segment
		(start 180.0479 -122.042428)
		(end 179.77612 -121.770648)
		(width 0.127)
		(layer "In4.Cu")
		(net "GPU_FPGA_OVERT_ISO_N")
	)
	(segment
		(start 275.501354 -376.644154)
		(end 275.501354 -377.427236)
		(width 0.127)
		(layer "In4.Cu")
		(net "GPU_FPGA_OVERT_ISO_N")
	)
	(segment
		(start 182.92318 -122.804428)
		(end 182.16118 -122.042428)
		(width 0.127)
		(layer "In4.Cu")
		(net "GPU_FPGA_OVERT_ISO_N")
	)
	(segment
		(start 275.216874 -376.359674)
		(end 275.501354 -376.644154)
		(width 0.127)
		(layer "In4.Cu")
		(net "GPU_FPGA_OVERT_ISO_N")
	)
	(segment
		(start 280.090118 -382.016)
		(end 280.8732 -382.016)
		(width 0.127)
		(layer "In4.Cu")
		(net "GPU_FPGA_OVERT_ISO_N")
	)
	(segment
		(start 168.90238 -120.18264)
		(end 168.57472 -119.85498)
		(width 0.127)
		(layer "In4.Cu")
		(net "GPU_FPGA_OVERT_ISO_N")
	)
	(segment
		(start 168.57472 -113.769648)
		(end 167.83685 -113.031778)
		(width 0.127)
		(layer "In4.Cu")
		(net "GPU_FPGA_OVERT_ISO_N")
	)
	(segment
		(start 197.24624 -123.701048)
		(end 192.24752 -123.701048)
		(width 0.127)
		(layer "In4.Cu")
		(net "GPU_FPGA_OVERT_ISO_N")
	)
	(segment
		(start 295.63695 -392.41857)
		(end 296.49928 -393.2809)
		(width 0.127)
		(layer "In4.Cu")
		(net "GPU_FPGA_OVERT_ISO_N")
	)
	(segment
		(start 242.910614 -279.090628)
		(end 242.910614 -329.042268)
		(width 0.127)
		(layer "In4.Cu")
		(net "GPU_FPGA_OVERT_ISO_N")
	)
	(segment
		(start 247.37568 -217.149426)
		(end 247.37568 -274.625562)
		(width 0.127)
		(layer "In4.Cu")
		(net "GPU_FPGA_OVERT_ISO_N")
	)
	(segment
		(start 284.734 -389.128)
		(end 288.02457 -392.41857)
		(width 0.127)
		(layer "In4.Cu")
		(net "GPU_FPGA_OVERT_ISO_N")
	)
	(segment
		(start 275.216874 -361.348528)
		(end 275.216874 -376.359674)
		(width 0.127)
		(layer "In4.Cu")
		(net "GPU_FPGA_OVERT_ISO_N")
	)
	(segment
		(start 173.238668 -123.121928)
		(end 171.75988 -121.64314)
		(width 0.127)
		(layer "In4.Cu")
		(net "GPU_FPGA_OVERT_ISO_N")
	)
	(segment
		(start 167.83685 -113.031778)
		(end 162.22853 -113.031778)
		(width 0.127)
		(layer "In4.Cu")
		(net "GPU_FPGA_OVERT_ISO_N")
	)
	(segment
		(start 275.501354 -377.427236)
		(end 280.090118 -382.016)
		(width 0.127)
		(layer "In4.Cu")
		(net "GPU_FPGA_OVERT_ISO_N")
	)
	(segment
		(start 213.837012 -159.169608)
		(end 213.837012 -149.147784)
		(width 0.127)
		(layer "In11.Cu")
		(net "GPU_FPGA_OVERT_ISO_N")
	)
	(segment
		(start 199.517 -134.160768)
		(end 198.41718 -133.060948)
		(width 0.127)
		(layer "In11.Cu")
		(net "GPU_FPGA_OVERT_ISO_N")
	)
	(segment
		(start 368.36096 -393.875768)
		(end 304.529744 -393.875768)
		(width 0.127)
		(layer "In11.Cu")
		(net "GPU_FPGA_OVERT_ISO_N")
	)
	(segment
		(start 304.529744 -393.875768)
		(end 304.402744 -394.002768)
		(width 0.127)
		(layer "In11.Cu")
		(net "GPU_FPGA_OVERT_ISO_N")
	)
	(segment
		(start 421.26408 -394.884148)
		(end 375.247916 -394.884148)
		(width 0.127)
		(layer "In11.Cu")
		(net "GPU_FPGA_OVERT_ISO_N")
	)
	(segment
		(start 213.837012 -149.147784)
		(end 199.517 -134.827772)
		(width 0.127)
		(layer "In11.Cu")
		(net "GPU_FPGA_OVERT_ISO_N")
	)
	(segment
		(start 369.1382 -393.098528)
		(end 368.36096 -393.875768)
		(width 0.127)
		(layer "In11.Cu")
		(net "GPU_FPGA_OVERT_ISO_N")
	)
	(segment
		(start 424.604942 -393.90701)
		(end 422.241218 -393.90701)
		(width 0.127)
		(layer "In11.Cu")
		(net "GPU_FPGA_OVERT_ISO_N")
	)
	(segment
		(start 375.247916 -394.884148)
		(end 373.462296 -393.098528)
		(width 0.127)
		(layer "In11.Cu")
		(net "GPU_FPGA_OVERT_ISO_N")
	)
	(segment
		(start 198.41718 -133.060948)
		(end 198.41718 -125.329188)
		(width 0.127)
		(layer "In11.Cu")
		(net "GPU_FPGA_OVERT_ISO_N")
	)
	(segment
		(start 227.65258 -196.319902)
		(end 227.65258 -172.985176)
		(width 0.127)
		(layer "In11.Cu")
		(net "GPU_FPGA_OVERT_ISO_N")
	)
	(segment
		(start 227.65258 -172.985176)
		(end 213.837012 -159.169608)
		(width 0.127)
		(layer "In11.Cu")
		(net "GPU_FPGA_OVERT_ISO_N")
	)
	(segment
		(start 236.419644 -206.19339)
		(end 235.595668 -205.369414)
		(width 0.127)
		(layer "In11.Cu")
		(net "GPU_FPGA_OVERT_ISO_N")
	)
	(segment
		(start 422.241218 -393.90701)
		(end 421.26408 -394.884148)
		(width 0.127)
		(layer "In11.Cu")
		(net "GPU_FPGA_OVERT_ISO_N")
	)
	(segment
		(start 373.462296 -393.098528)
		(end 369.1382 -393.098528)
		(width 0.127)
		(layer "In11.Cu")
		(net "GPU_FPGA_OVERT_ISO_N")
	)
	(segment
		(start 235.595668 -204.26299)
		(end 227.65258 -196.319902)
		(width 0.127)
		(layer "In11.Cu")
		(net "GPU_FPGA_OVERT_ISO_N")
	)
	(segment
		(start 235.595668 -205.369414)
		(end 235.595668 -204.26299)
		(width 0.127)
		(layer "In11.Cu")
		(net "GPU_FPGA_OVERT_ISO_N")
	)
	(segment
		(start 199.517 -134.827772)
		(end 199.517 -134.160768)
		(width 0.127)
		(layer "In11.Cu")
		(net "GPU_FPGA_OVERT_ISO_N")
	)
	(segment
		(start 428.791878 -397.09852)
		(end 429.129952 -397.09852)
		(width 0.12954)
		(layer "F.Cu")
		(net "GPU_FPGA_OVERT")
	)
	(segment
		(start 430.839118 -396.448534)
		(end 431.661062 -397.270478)
		(width 0.12954)
		(layer "F.Cu")
		(net "GPU_FPGA_OVERT")
	)
	(segment
		(start 428.814992 -396.448534)
		(end 428.634652 -396.628874)
		(width 0.12954)
		(layer "F.Cu")
		(net "GPU_FPGA_OVERT")
	)
	(segment
		(start 429.129952 -396.448534)
		(end 430.391062 -396.448534)
		(width 0.12954)
		(layer "F.Cu")
		(net "GPU_FPGA_OVERT")
	)
	(segment
		(start 430.391062 -396.448534)
		(end 430.839118 -396.448534)
		(width 0.12954)
		(layer "F.Cu")
		(net "GPU_FPGA_OVERT")
	)
	(segment
		(start 429.129952 -396.448534)
		(end 428.814992 -396.448534)
		(width 0.12954)
		(layer "F.Cu")
		(net "GPU_FPGA_OVERT")
	)
	(segment
		(start 428.634652 -396.628874)
		(end 428.634652 -396.941294)
		(width 0.12954)
		(layer "F.Cu")
		(net "GPU_FPGA_OVERT")
	)
	(segment
		(start 428.634652 -396.941294)
		(end 428.791878 -397.09852)
		(width 0.12954)
		(layer "F.Cu")
		(net "GPU_FPGA_OVERT")
	)
	(via
		(at 430.391062 -396.448534)
		(size 0.762)
		(drill 0.381)
		(layers "F.Cu" "B.Cu")
		(net "GPU_FPGA_OVERT")
	)
	(segment
		(start 174.155608 -111.375444)
		(end 173.755558 -110.975394)
		(width 0.12954)
		(layer "F.Cu")
		(net "GPU_FPGA_EROT_RST_R_N")
	)
	(via
		(at 173.755558 -110.975394)
		(size 0.4572)
		(drill 0.254)
		(layers "F.Cu" "B.Cu")
		(net "GPU_FPGA_EROT_RST_R_N")
	)
	(via
		(at 158.90748 -115.026948)
		(size 0.508)
		(drill 0.254)
		(layers "F.Cu" "B.Cu")
		(net "GPU_FPGA_EROT_RST_R_N")
	)
	(segment
		(start 158.72968 -114.518948)
		(end 157.61208 -114.518948)
		(width 0.12954)
		(layer "B.Cu")
		(net "GPU_FPGA_EROT_RST_R_N")
	)
	(segment
		(start 157.42793 -114.703098)
		(end 157.42793 -115.026948)
		(width 0.12954)
		(layer "B.Cu")
		(net "GPU_FPGA_EROT_RST_R_N")
	)
	(segment
		(start 157.61208 -114.518948)
		(end 157.42793 -114.703098)
		(width 0.12954)
		(layer "B.Cu")
		(net "GPU_FPGA_EROT_RST_R_N")
	)
	(segment
		(start 158.90748 -114.696748)
		(end 158.72968 -114.518948)
		(width 0.12954)
		(layer "B.Cu")
		(net "GPU_FPGA_EROT_RST_R_N")
	)
	(segment
		(start 158.90748 -115.026948)
		(end 158.90748 -114.696748)
		(width 0.12954)
		(layer "B.Cu")
		(net "GPU_FPGA_EROT_RST_R_N")
	)
	(segment
		(start 159.4993 -114.435128)
		(end 158.90748 -115.026948)
		(width 0.127)
		(layer "In15.Cu")
		(net "GPU_FPGA_EROT_RST_R_N")
	)
	(segment
		(start 171.16044 -111.371888)
		(end 169.89298 -112.639348)
		(width 0.127)
		(layer "In15.Cu")
		(net "GPU_FPGA_EROT_RST_R_N")
	)
	(segment
		(start 164.35578 -114.435128)
		(end 159.4993 -114.435128)
		(width 0.127)
		(layer "In15.Cu")
		(net "GPU_FPGA_EROT_RST_R_N")
	)
	(segment
		(start 166.15156 -112.639348)
		(end 164.35578 -114.435128)
		(width 0.127)
		(layer "In15.Cu")
		(net "GPU_FPGA_EROT_RST_R_N")
	)
	(segment
		(start 169.89298 -112.639348)
		(end 166.15156 -112.639348)
		(width 0.127)
		(layer "In15.Cu")
		(net "GPU_FPGA_EROT_RST_R_N")
	)
	(segment
		(start 173.359064 -111.371888)
		(end 171.16044 -111.371888)
		(width 0.127)
		(layer "In15.Cu")
		(net "GPU_FPGA_EROT_RST_R_N")
	)
	(segment
		(start 173.755558 -110.975394)
		(end 173.359064 -111.371888)
		(width 0.127)
		(layer "In15.Cu")
		(net "GPU_FPGA_EROT_RST_R_N")
	)
	(segment
		(start 109.180884 -395.17574)
		(end 109.180884 -394.15974)
		(width 0.12954)
		(layer "F.Cu")
		(net "GPU_FPGA_EROT_RST_N")
	)
	(segment
		(start 108.819188 -394.15974)
		(end 109.180884 -394.15974)
		(width 0.12954)
		(layer "F.Cu")
		(net "GPU_FPGA_EROT_RST_N")
	)
	(segment
		(start 107.90428 -394.36167)
		(end 108.617258 -394.36167)
		(width 0.12954)
		(layer "F.Cu")
		(net "GPU_FPGA_EROT_RST_N")
	)
	(segment
		(start 106.645964 -394.36167)
		(end 107.90428 -394.36167)
		(width 0.12954)
		(layer "F.Cu")
		(net "GPU_FPGA_EROT_RST_N")
	)
	(segment
		(start 108.617258 -394.36167)
		(end 108.819188 -394.15974)
		(width 0.12954)
		(layer "F.Cu")
		(net "GPU_FPGA_EROT_RST_N")
	)
	(via
		(at 155.12288 -115.026948)
		(size 0.508)
		(drill 0.254)
		(layers "F.Cu" "B.Cu")
		(net "GPU_FPGA_EROT_RST_N")
	)
	(via
		(at 150.327106 -108.232448)
		(size 0.508)
		(drill 0.254)
		(layers "F.Cu" "B.Cu")
		(net "GPU_FPGA_EROT_RST_N")
	)
	(via
		(at 9.77138 -172.877988)
		(size 0.508)
		(drill 0.254)
		(layers "F.Cu" "B.Cu")
		(net "GPU_FPGA_EROT_RST_N")
	)
	(via
		(at 46.8757 -110.670848)
		(size 0.508)
		(drill 0.254)
		(layers "F.Cu" "B.Cu")
		(net "GPU_FPGA_EROT_RST_N")
	)
	(via
		(at 107.90428 -394.36167)
		(size 0.508)
		(drill 0.254)
		(layers "F.Cu" "B.Cu")
		(net "GPU_FPGA_EROT_RST_N")
	)
	(segment
		(start 155.12288 -115.026948)
		(end 155.12288 -114.671348)
		(width 0.12954)
		(layer "B.Cu")
		(net "GPU_FPGA_EROT_RST_N")
	)
	(segment
		(start 155.12288 -114.671348)
		(end 155.30068 -114.493548)
		(width 0.12954)
		(layer "B.Cu")
		(net "GPU_FPGA_EROT_RST_N")
	)
	(segment
		(start 156.44368 -114.493548)
		(end 156.62783 -114.677698)
		(width 0.12954)
		(layer "B.Cu")
		(net "GPU_FPGA_EROT_RST_N")
	)
	(segment
		(start 156.62783 -114.677698)
		(end 156.62783 -115.026948)
		(width 0.12954)
		(layer "B.Cu")
		(net "GPU_FPGA_EROT_RST_N")
	)
	(segment
		(start 155.30068 -114.493548)
		(end 156.44368 -114.493548)
		(width 0.12954)
		(layer "B.Cu")
		(net "GPU_FPGA_EROT_RST_N")
	)
	(segment
		(start 155.12288 -115.026948)
		(end 154.86888 -114.772948)
		(width 0.127)
		(layer "In2.Cu")
		(net "GPU_FPGA_EROT_RST_N")
	)
	(segment
		(start 151.36368 -111.013748)
		(end 150.14448 -111.013748)
		(width 0.127)
		(layer "In2.Cu")
		(net "GPU_FPGA_EROT_RST_N")
	)
	(segment
		(start 150.14448 -111.013748)
		(end 149.779228 -110.648496)
		(width 0.127)
		(layer "In2.Cu")
		(net "GPU_FPGA_EROT_RST_N")
	)
	(segment
		(start 154.86888 -114.772948)
		(end 154.86888 -114.518948)
		(width 0.127)
		(layer "In2.Cu")
		(net "GPU_FPGA_EROT_RST_N")
	)
	(segment
		(start 154.86888 -114.518948)
		(end 151.36368 -111.013748)
		(width 0.127)
		(layer "In2.Cu")
		(net "GPU_FPGA_EROT_RST_N")
	)
	(segment
		(start 149.779228 -110.648496)
		(end 149.779228 -108.780326)
		(width 0.127)
		(layer "In2.Cu")
		(net "GPU_FPGA_EROT_RST_N")
	)
	(segment
		(start 149.779228 -108.780326)
		(end 150.327106 -108.232448)
		(width 0.127)
		(layer "In2.Cu")
		(net "GPU_FPGA_EROT_RST_N")
	)
	(segment
		(start 8.58774 -172.877988)
		(end 9.77138 -172.877988)
		(width 0.127)
		(layer "In6.Cu")
		(net "GPU_FPGA_EROT_RST_N")
	)
	(segment
		(start 101.457252 -394.757148)
		(end 57.904888 -394.757148)
		(width 0.127)
		(layer "In6.Cu")
		(net "GPU_FPGA_EROT_RST_N")
	)
	(segment
		(start 31.90748 -336.86115)
		(end 31.90748 -331.99705)
		(width 0.127)
		(layer "In6.Cu")
		(net "GPU_FPGA_EROT_RST_N")
	)
	(segment
		(start 31.90748 -331.99705)
		(end 28.322778 -328.412348)
		(width 0.127)
		(layer "In6.Cu")
		(net "GPU_FPGA_EROT_RST_N")
	)
	(segment
		(start 104.88422 -393.758928)
		(end 102.455472 -393.758928)
		(width 0.127)
		(layer "In6.Cu")
		(net "GPU_FPGA_EROT_RST_N")
	)
	(segment
		(start 8.00608 -321.351148)
		(end 8.00608 -257.830574)
		(width 0.127)
		(layer "In6.Cu")
		(net "GPU_FPGA_EROT_RST_N")
	)
	(segment
		(start 107.90428 -394.36167)
		(end 107.746038 -394.203428)
		(width 0.127)
		(layer "In6.Cu")
		(net "GPU_FPGA_EROT_RST_N")
	)
	(segment
		(start 7.552944 -173.912784)
		(end 8.58774 -172.877988)
		(width 0.127)
		(layer "In6.Cu")
		(net "GPU_FPGA_EROT_RST_N")
	)
	(segment
		(start 4.214114 -254.038608)
		(end 4.214114 -177.008028)
		(width 0.127)
		(layer "In6.Cu")
		(net "GPU_FPGA_EROT_RST_N")
	)
	(segment
		(start 4.214114 -177.008028)
		(end 7.309358 -173.912784)
		(width 0.127)
		(layer "In6.Cu")
		(net "GPU_FPGA_EROT_RST_N")
	)
	(segment
		(start 107.746038 -394.203428)
		(end 105.32872 -394.203428)
		(width 0.127)
		(layer "In6.Cu")
		(net "GPU_FPGA_EROT_RST_N")
	)
	(segment
		(start 102.455472 -393.758928)
		(end 101.457252 -394.757148)
		(width 0.127)
		(layer "In6.Cu")
		(net "GPU_FPGA_EROT_RST_N")
	)
	(segment
		(start 8.00608 -257.830574)
		(end 4.214114 -254.038608)
		(width 0.127)
		(layer "In6.Cu")
		(net "GPU_FPGA_EROT_RST_N")
	)
	(segment
		(start 28.322778 -328.412348)
		(end 15.06728 -328.412348)
		(width 0.127)
		(layer "In6.Cu")
		(net "GPU_FPGA_EROT_RST_N")
	)
	(segment
		(start 30.15488 -338.61375)
		(end 31.90748 -336.86115)
		(width 0.127)
		(layer "In6.Cu")
		(net "GPU_FPGA_EROT_RST_N")
	)
	(segment
		(start 105.32872 -394.203428)
		(end 104.88422 -393.758928)
		(width 0.127)
		(layer "In6.Cu")
		(net "GPU_FPGA_EROT_RST_N")
	)
	(segment
		(start 7.309358 -173.912784)
		(end 7.552944 -173.912784)
		(width 0.127)
		(layer "In6.Cu")
		(net "GPU_FPGA_EROT_RST_N")
	)
	(segment
		(start 57.904888 -394.757148)
		(end 30.15488 -367.00714)
		(width 0.127)
		(layer "In6.Cu")
		(net "GPU_FPGA_EROT_RST_N")
	)
	(segment
		(start 30.15488 -367.00714)
		(end 30.15488 -338.61375)
		(width 0.127)
		(layer "In6.Cu")
		(net "GPU_FPGA_EROT_RST_N")
	)
	(segment
		(start 15.06728 -328.412348)
		(end 8.00608 -321.351148)
		(width 0.127)
		(layer "In6.Cu")
		(net "GPU_FPGA_EROT_RST_N")
	)
	(segment
		(start 150.327106 -108.232448)
		(end 146.400266 -104.305608)
		(width 0.127)
		(layer "In13.Cu")
		(net "GPU_FPGA_EROT_RST_N")
	)
	(segment
		(start 57.45734 -110.419388)
		(end 50.09388 -110.419388)
		(width 0.127)
		(layer "In13.Cu")
		(net "GPU_FPGA_EROT_RST_N")
	)
	(segment
		(start 66.44894 -109.751368)
		(end 64.7827 -111.417608)
		(width 0.127)
		(layer "In13.Cu")
		(net "GPU_FPGA_EROT_RST_N")
	)
	(segment
		(start 58.45556 -111.417608)
		(end 57.45734 -110.419388)
		(width 0.127)
		(layer "In13.Cu")
		(net "GPU_FPGA_EROT_RST_N")
	)
	(segment
		(start 64.7827 -111.417608)
		(end 58.45556 -111.417608)
		(width 0.127)
		(layer "In13.Cu")
		(net "GPU_FPGA_EROT_RST_N")
	)
	(segment
		(start 112.649 -103.393748)
		(end 110.4392 -105.603548)
		(width 0.127)
		(layer "In13.Cu")
		(net "GPU_FPGA_EROT_RST_N")
	)
	(segment
		(start 79.35976 -106.731308)
		(end 76.3397 -109.751368)
		(width 0.127)
		(layer "In13.Cu")
		(net "GPU_FPGA_EROT_RST_N")
	)
	(segment
		(start 48.65116 -110.800388)
		(end 48.52162 -110.670848)
		(width 0.127)
		(layer "In13.Cu")
		(net "GPU_FPGA_EROT_RST_N")
	)
	(segment
		(start 110.4392 -105.603548)
		(end 101.11232 -105.603548)
		(width 0.127)
		(layer "In13.Cu")
		(net "GPU_FPGA_EROT_RST_N")
	)
	(segment
		(start 126.54788 -105.628948)
		(end 126.46406 -105.712768)
		(width 0.127)
		(layer "In13.Cu")
		(net "GPU_FPGA_EROT_RST_N")
	)
	(segment
		(start 122.30354 -105.712768)
		(end 119.98452 -103.393748)
		(width 0.127)
		(layer "In13.Cu")
		(net "GPU_FPGA_EROT_RST_N")
	)
	(segment
		(start 138.56462 -104.305608)
		(end 137.24128 -105.628948)
		(width 0.127)
		(layer "In13.Cu")
		(net "GPU_FPGA_EROT_RST_N")
	)
	(segment
		(start 49.71288 -110.800388)
		(end 48.65116 -110.800388)
		(width 0.127)
		(layer "In13.Cu")
		(net "GPU_FPGA_EROT_RST_N")
	)
	(segment
		(start 119.98452 -103.393748)
		(end 112.649 -103.393748)
		(width 0.127)
		(layer "In13.Cu")
		(net "GPU_FPGA_EROT_RST_N")
	)
	(segment
		(start 146.400266 -104.305608)
		(end 138.56462 -104.305608)
		(width 0.127)
		(layer "In13.Cu")
		(net "GPU_FPGA_EROT_RST_N")
	)
	(segment
		(start 50.09388 -110.419388)
		(end 49.71288 -110.800388)
		(width 0.127)
		(layer "In13.Cu")
		(net "GPU_FPGA_EROT_RST_N")
	)
	(segment
		(start 137.24128 -105.628948)
		(end 126.54788 -105.628948)
		(width 0.127)
		(layer "In13.Cu")
		(net "GPU_FPGA_EROT_RST_N")
	)
	(segment
		(start 99.98456 -106.731308)
		(end 79.35976 -106.731308)
		(width 0.127)
		(layer "In13.Cu")
		(net "GPU_FPGA_EROT_RST_N")
	)
	(segment
		(start 76.3397 -109.751368)
		(end 66.44894 -109.751368)
		(width 0.127)
		(layer "In13.Cu")
		(net "GPU_FPGA_EROT_RST_N")
	)
	(segment
		(start 101.11232 -105.603548)
		(end 99.98456 -106.731308)
		(width 0.127)
		(layer "In13.Cu")
		(net "GPU_FPGA_EROT_RST_N")
	)
	(segment
		(start 126.46406 -105.712768)
		(end 122.30354 -105.712768)
		(width 0.127)
		(layer "In13.Cu")
		(net "GPU_FPGA_EROT_RST_N")
	)
	(segment
		(start 48.52162 -110.670848)
		(end 46.8757 -110.670848)
		(width 0.127)
		(layer "In13.Cu")
		(net "GPU_FPGA_EROT_RST_N")
	)
	(segment
		(start 15.85468 -167.397684)
		(end 10.374376 -172.877988)
		(width 0.127)
		(layer "In15.Cu")
		(net "GPU_FPGA_EROT_RST_N")
	)
	(segment
		(start 44.41698 -110.670848)
		(end 40.54348 -114.544348)
		(width 0.127)
		(layer "In15.Cu")
		(net "GPU_FPGA_EROT_RST_N")
	)
	(segment
		(start 40.54348 -114.544348)
		(end 29.269944 -114.544348)
		(width 0.127)
		(layer "In15.Cu")
		(net "GPU_FPGA_EROT_RST_N")
	)
	(segment
		(start 10.374376 -172.877988)
		(end 9.77138 -172.877988)
		(width 0.127)
		(layer "In15.Cu")
		(net "GPU_FPGA_EROT_RST_N")
	)
	(segment
		(start 29.269944 -114.544348)
		(end 15.85468 -127.959612)
		(width 0.127)
		(layer "In15.Cu")
		(net "GPU_FPGA_EROT_RST_N")
	)
	(segment
		(start 15.85468 -127.959612)
		(end 15.85468 -167.397684)
		(width 0.127)
		(layer "In15.Cu")
		(net "GPU_FPGA_EROT_RST_N")
	)
	(segment
		(start 46.8757 -110.670848)
		(end 44.41698 -110.670848)
		(width 0.127)
		(layer "In15.Cu")
		(net "GPU_FPGA_EROT_RST_N")
	)
	(segment
		(start 102.233984 -397.46174)
		(end 102.233984 -396.44574)
		(width 0.12954)
		(layer "F.Cu")
		(net "GPU_FPGA_EROT_RST_BUF_R_N")
	)
	(segment
		(start 103.44404 -395.42974)
		(end 102.233984 -395.42974)
		(width 0.12954)
		(layer "F.Cu")
		(net "GPU_FPGA_EROT_RST_BUF_R_N")
	)
	(segment
		(start 104.51211 -394.36167)
		(end 103.44404 -395.42974)
		(width 0.12954)
		(layer "F.Cu")
		(net "GPU_FPGA_EROT_RST_BUF_R_N")
	)
	(segment
		(start 102.233984 -396.44574)
		(end 102.233984 -395.42974)
		(width 0.12954)
		(layer "F.Cu")
		(net "GPU_FPGA_EROT_RST_BUF_R_N")
	)
	(segment
		(start 104.746044 -394.36167)
		(end 104.51211 -394.36167)
		(width 0.12954)
		(layer "F.Cu")
		(net "GPU_FPGA_EROT_RST_BUF_R_N")
	)
	(via
		(at 103.44404 -395.42974)
		(size 0.762)
		(drill 0.381)
		(layers "F.Cu" "B.Cu")
		(net "GPU_FPGA_EROT_RST_BUF_R_N")
	)
	(segment
		(start 103.92156 -397.990568)
		(end 103.279448 -398.63268)
		(width 0.12954)
		(layer "F.Cu")
		(net "GPU_FPGA_EROT_RST_BUF_N")
	)
	(segment
		(start 102.604824 -398.63268)
		(end 101.433884 -397.46174)
		(width 0.12954)
		(layer "F.Cu")
		(net "GPU_FPGA_EROT_RST_BUF_N")
	)
	(segment
		(start 103.279448 -398.63268)
		(end 102.604824 -398.63268)
		(width 0.12954)
		(layer "F.Cu")
		(net "GPU_FPGA_EROT_RST_BUF_N")
	)
	(via
		(at 103.92156 -397.990568)
		(size 0.508)
		(drill 0.254)
		(layers "F.Cu" "B.Cu")
		(net "GPU_FPGA_EROT_RST_BUF_N")
	)
	(segment
		(start 114.5413 -396.92072)
		(end 115.27536 -396.92072)
		(width 0.12954)
		(layer "B.Cu")
		(net "GPU_FPGA_EROT_RST_BUF_N")
	)
	(segment
		(start 141.7828 -422.657016)
		(end 139.750038 -424.689778)
		(width 0.12954)
		(layer "B.Cu")
		(net "GPU_FPGA_EROT_RST_BUF_N")
	)
	(segment
		(start 109.713268 -397.47952)
		(end 113.9825 -397.47952)
		(width 0.12954)
		(layer "B.Cu")
		(net "GPU_FPGA_EROT_RST_BUF_N")
	)
	(segment
		(start 143.40078 -404.805388)
		(end 141.7828 -406.423368)
		(width 0.12954)
		(layer "B.Cu")
		(net "GPU_FPGA_EROT_RST_BUF_N")
	)
	(segment
		(start 143.40078 -399.6944)
		(end 143.40078 -404.805388)
		(width 0.12954)
		(layer "B.Cu")
		(net "GPU_FPGA_EROT_RST_BUF_N")
	)
	(segment
		(start 141.7828 -406.423368)
		(end 141.7828 -422.657016)
		(width 0.12954)
		(layer "B.Cu")
		(net "GPU_FPGA_EROT_RST_BUF_N")
	)
	(segment
		(start 143.27378 -399.5674)
		(end 143.40078 -399.6944)
		(width 0.12954)
		(layer "B.Cu")
		(net "GPU_FPGA_EROT_RST_BUF_N")
	)
	(segment
		(start 117.21592 -398.86128)
		(end 119.10568 -398.86128)
		(width 0.12954)
		(layer "B.Cu")
		(net "GPU_FPGA_EROT_RST_BUF_N")
	)
	(segment
		(start 103.92156 -397.990568)
		(end 109.20222 -397.990568)
		(width 0.12954)
		(layer "B.Cu")
		(net "GPU_FPGA_EROT_RST_BUF_N")
	)
	(segment
		(start 119.10568 -398.86128)
		(end 119.8118 -399.5674)
		(width 0.12954)
		(layer "B.Cu")
		(net "GPU_FPGA_EROT_RST_BUF_N")
	)
	(segment
		(start 115.27536 -396.92072)
		(end 117.21592 -398.86128)
		(width 0.12954)
		(layer "B.Cu")
		(net "GPU_FPGA_EROT_RST_BUF_N")
	)
	(segment
		(start 119.8118 -399.5674)
		(end 143.27378 -399.5674)
		(width 0.12954)
		(layer "B.Cu")
		(net "GPU_FPGA_EROT_RST_BUF_N")
	)
	(segment
		(start 113.9825 -397.47952)
		(end 114.5413 -396.92072)
		(width 0.12954)
		(layer "B.Cu")
		(net "GPU_FPGA_EROT_RST_BUF_N")
	)
	(segment
		(start 109.20222 -397.990568)
		(end 109.713268 -397.47952)
		(width 0.12954)
		(layer "B.Cu")
		(net "GPU_FPGA_EROT_RST_BUF_N")
	)
	(segment
		(start 161.39668 -114.435128)
		(end 161.23793 -114.593878)
		(width 0.12954)
		(layer "F.Cu")
		(net "GPU_FPGA_EROT_RECOV_R_N")
	)
	(segment
		(start 174.155608 -112.97539)
		(end 173.755558 -112.57534)
		(width 0.12954)
		(layer "F.Cu")
		(net "GPU_FPGA_EROT_RECOV_R_N")
	)
	(segment
		(start 162.15106 -114.435128)
		(end 161.39668 -114.435128)
		(width 0.12954)
		(layer "F.Cu")
		(net "GPU_FPGA_EROT_RECOV_R_N")
	)
	(segment
		(start 161.23793 -114.593878)
		(end 161.23793 -115.026948)
		(width 0.12954)
		(layer "F.Cu")
		(net "GPU_FPGA_EROT_RECOV_R_N")
	)
	(segment
		(start 162.74288 -115.026948)
		(end 162.15106 -114.435128)
		(width 0.12954)
		(layer "F.Cu")
		(net "GPU_FPGA_EROT_RECOV_R_N")
	)
	(via
		(at 173.755558 -112.57534)
		(size 0.4572)
		(drill 0.254)
		(layers "F.Cu" "B.Cu")
		(net "GPU_FPGA_EROT_RECOV_R_N")
	)
	(via
		(at 162.74288 -115.026948)
		(size 0.508)
		(drill 0.254)
		(layers "F.Cu" "B.Cu")
		(net "GPU_FPGA_EROT_RECOV_R_N")
	)
	(segment
		(start 164.18052 -114.351308)
		(end 163.41852 -114.351308)
		(width 0.127)
		(layer "In6.Cu")
		(net "GPU_FPGA_EROT_RECOV_R_N")
	)
	(segment
		(start 170.71848 -113.768378)
		(end 170.392852 -113.768378)
		(width 0.127)
		(layer "In6.Cu")
		(net "GPU_FPGA_EROT_RECOV_R_N")
	)
	(segment
		(start 172.564298 -113.7666)
		(end 170.720258 -113.7666)
		(width 0.127)
		(layer "In6.Cu")
		(net "GPU_FPGA_EROT_RECOV_R_N")
	)
	(segment
		(start 170.392852 -113.768378)
		(end 170.391074 -113.7666)
		(width 0.127)
		(layer "In6.Cu")
		(net "GPU_FPGA_EROT_RECOV_R_N")
	)
	(segment
		(start 173.755558 -112.57534)
		(end 172.564298 -113.7666)
		(width 0.127)
		(layer "In6.Cu")
		(net "GPU_FPGA_EROT_RECOV_R_N")
	)
	(segment
		(start 164.765228 -113.7666)
		(end 164.18052 -114.351308)
		(width 0.127)
		(layer "In6.Cu")
		(net "GPU_FPGA_EROT_RECOV_R_N")
	)
	(segment
		(start 163.41852 -114.351308)
		(end 162.74288 -115.026948)
		(width 0.127)
		(layer "In6.Cu")
		(net "GPU_FPGA_EROT_RECOV_R_N")
	)
	(segment
		(start 170.720258 -113.7666)
		(end 170.71848 -113.768378)
		(width 0.127)
		(layer "In6.Cu")
		(net "GPU_FPGA_EROT_RECOV_R_N")
	)
	(segment
		(start 170.391074 -113.7666)
		(end 164.765228 -113.7666)
		(width 0.127)
		(layer "In6.Cu")
		(net "GPU_FPGA_EROT_RECOV_R_N")
	)
	(segment
		(start 111.11484 -401.195286)
		(end 110.0709 -401.195286)
		(width 0.12954)
		(layer "F.Cu")
		(net "GPU_FPGA_EROT_RECOV_N")
	)
	(segment
		(start 109.25048 -401.184364)
		(end 110.059978 -401.184364)
		(width 0.12954)
		(layer "F.Cu")
		(net "GPU_FPGA_EROT_RECOV_N")
	)
	(segment
		(start 160.43783 -115.026948)
		(end 159.82188 -115.026948)
		(width 0.12954)
		(layer "F.Cu")
		(net "GPU_FPGA_EROT_RECOV_N")
	)
	(segment
		(start 110.059978 -401.184364)
		(end 110.0709 -401.195286)
		(width 0.12954)
		(layer "F.Cu")
		(net "GPU_FPGA_EROT_RECOV_N")
	)
	(segment
		(start 109.25048 -402.200364)
		(end 109.25048 -401.184364)
		(width 0.12954)
		(layer "F.Cu")
		(net "GPU_FPGA_EROT_RECOV_N")
	)
	(via
		(at 95.1992 -392.7856)
		(size 0.508)
		(drill 0.254)
		(layers "F.Cu" "B.Cu")
		(net "GPU_FPGA_EROT_RECOV_N")
	)
	(via
		(at 46.226476 -115.298728)
		(size 0.508)
		(drill 0.254)
		(layers "F.Cu" "B.Cu")
		(net "GPU_FPGA_EROT_RECOV_N")
	)
	(via
		(at 159.82188 -115.026948)
		(size 0.508)
		(drill 0.254)
		(layers "F.Cu" "B.Cu")
		(net "GPU_FPGA_EROT_RECOV_N")
	)
	(via
		(at 9.77138 -176.052988)
		(size 0.508)
		(drill 0.254)
		(layers "F.Cu" "B.Cu")
		(net "GPU_FPGA_EROT_RECOV_N")
	)
	(via
		(at 110.0709 -401.195286)
		(size 0.508)
		(drill 0.254)
		(layers "F.Cu" "B.Cu")
		(net "GPU_FPGA_EROT_RECOV_N")
	)
	(segment
		(start 95.1992 -394.6398)
		(end 95.66656 -395.10716)
		(width 0.12954)
		(layer "B.Cu")
		(net "GPU_FPGA_EROT_RECOV_N")
	)
	(segment
		(start 108.498894 -399.62328)
		(end 110.0709 -401.195286)
		(width 0.12954)
		(layer "B.Cu")
		(net "GPU_FPGA_EROT_RECOV_N")
	)
	(segment
		(start 97.44964 -395.10716)
		(end 101.96576 -399.62328)
		(width 0.12954)
		(layer "B.Cu")
		(net "GPU_FPGA_EROT_RECOV_N")
	)
	(segment
		(start 101.96576 -399.62328)
		(end 108.498894 -399.62328)
		(width 0.12954)
		(layer "B.Cu")
		(net "GPU_FPGA_EROT_RECOV_N")
	)
	(segment
		(start 95.66656 -395.10716)
		(end 97.44964 -395.10716)
		(width 0.12954)
		(layer "B.Cu")
		(net "GPU_FPGA_EROT_RECOV_N")
	)
	(segment
		(start 95.1992 -392.7856)
		(end 95.1992 -394.6398)
		(width 0.12954)
		(layer "B.Cu")
		(net "GPU_FPGA_EROT_RECOV_N")
	)
	(segment
		(start 31.90748 -339.627464)
		(end 33.86328 -337.671664)
		(width 0.127)
		(layer "In6.Cu")
		(net "GPU_FPGA_EROT_RECOV_N")
	)
	(segment
		(start 6.91642 -196.222874)
		(end 7.32663 -196.222874)
		(width 0.127)
		(layer "In6.Cu")
		(net "GPU_FPGA_EROT_RECOV_N")
	)
	(segment
		(start 11.399774 -256.377948)
		(end 9.113774 -256.377948)
		(width 0.127)
		(layer "In6.Cu")
		(net "GPU_FPGA_EROT_RECOV_N")
	)
	(segment
		(start 6.22808 -196.911214)
		(end 6.91642 -196.222874)
		(width 0.127)
		(layer "In6.Cu")
		(net "GPU_FPGA_EROT_RECOV_N")
	)
	(segment
		(start 27.069796 -324.500748)
		(end 15.284196 -324.500748)
		(width 0.127)
		(layer "In6.Cu")
		(net "GPU_FPGA_EROT_RECOV_N")
	)
	(segment
		(start 33.86328 -337.671664)
		(end 33.86328 -331.294232)
		(width 0.127)
		(layer "In6.Cu")
		(net "GPU_FPGA_EROT_RECOV_N")
	)
	(segment
		(start 33.86328 -331.294232)
		(end 27.069796 -324.500748)
		(width 0.127)
		(layer "In6.Cu")
		(net "GPU_FPGA_EROT_RECOV_N")
	)
	(segment
		(start 7.32663 -196.222874)
		(end 8.18896 -195.360544)
		(width 0.127)
		(layer "In6.Cu")
		(net "GPU_FPGA_EROT_RECOV_N")
	)
	(segment
		(start 7.599934 -176.052988)
		(end 9.77138 -176.052988)
		(width 0.127)
		(layer "In6.Cu")
		(net "GPU_FPGA_EROT_RECOV_N")
	)
	(segment
		(start 6.22808 -177.424842)
		(end 7.599934 -176.052988)
		(width 0.127)
		(layer "In6.Cu")
		(net "GPU_FPGA_EROT_RECOV_N")
	)
	(segment
		(start 12.47648 -257.454654)
		(end 11.399774 -256.377948)
		(width 0.127)
		(layer "In6.Cu")
		(net "GPU_FPGA_EROT_RECOV_N")
	)
	(segment
		(start 6.22808 -191.024256)
		(end 6.22808 -177.424842)
		(width 0.127)
		(layer "In6.Cu")
		(net "GPU_FPGA_EROT_RECOV_N")
	)
	(segment
		(start 12.47648 -321.693032)
		(end 12.47648 -257.454654)
		(width 0.127)
		(layer "In6.Cu")
		(net "GPU_FPGA_EROT_RECOV_N")
	)
	(segment
		(start 95.005652 -392.979148)
		(end 58.665364 -392.979148)
		(width 0.127)
		(layer "In6.Cu")
		(net "GPU_FPGA_EROT_RECOV_N")
	)
	(segment
		(start 31.90748 -366.221264)
		(end 31.90748 -339.627464)
		(width 0.127)
		(layer "In6.Cu")
		(net "GPU_FPGA_EROT_RECOV_N")
	)
	(segment
		(start 8.18896 -195.360544)
		(end 8.18896 -192.985136)
		(width 0.127)
		(layer "In6.Cu")
		(net "GPU_FPGA_EROT_RECOV_N")
	)
	(segment
		(start 9.113774 -256.377948)
		(end 6.22808 -253.492254)
		(width 0.127)
		(layer "In6.Cu")
		(net "GPU_FPGA_EROT_RECOV_N")
	)
	(segment
		(start 6.22808 -253.492254)
		(end 6.22808 -196.911214)
		(width 0.127)
		(layer "In6.Cu")
		(net "GPU_FPGA_EROT_RECOV_N")
	)
	(segment
		(start 8.18896 -192.985136)
		(end 6.22808 -191.024256)
		(width 0.127)
		(layer "In6.Cu")
		(net "GPU_FPGA_EROT_RECOV_N")
	)
	(segment
		(start 95.1992 -392.7856)
		(end 95.005652 -392.979148)
		(width 0.127)
		(layer "In6.Cu")
		(net "GPU_FPGA_EROT_RECOV_N")
	)
	(segment
		(start 15.284196 -324.500748)
		(end 12.47648 -321.693032)
		(width 0.127)
		(layer "In6.Cu")
		(net "GPU_FPGA_EROT_RECOV_N")
	)
	(segment
		(start 58.665364 -392.979148)
		(end 31.90748 -366.221264)
		(width 0.127)
		(layer "In6.Cu")
		(net "GPU_FPGA_EROT_RECOV_N")
	)
	(segment
		(start 49.20742 -114.239548)
		(end 54.54904 -114.239548)
		(width 0.127)
		(layer "In13.Cu")
		(net "GPU_FPGA_EROT_RECOV_N")
	)
	(segment
		(start 119.1133 -108.016548)
		(end 126.028704 -108.016548)
		(width 0.127)
		(layer "In13.Cu")
		(net "GPU_FPGA_EROT_RECOV_N")
	)
	(segment
		(start 157.66288 -109.946948)
		(end 158.13278 -110.416848)
		(width 0.127)
		(layer "In13.Cu")
		(net "GPU_FPGA_EROT_RECOV_N")
	)
	(segment
		(start 76.991464 -111.577628)
		(end 80.118204 -108.450888)
		(width 0.127)
		(layer "In13.Cu")
		(net "GPU_FPGA_EROT_RECOV_N")
	)
	(segment
		(start 147.45462 -112.436148)
		(end 151.41448 -112.436148)
		(width 0.127)
		(layer "In13.Cu")
		(net "GPU_FPGA_EROT_RECOV_N")
	)
	(segment
		(start 80.118204 -108.450888)
		(end 100.895404 -108.450888)
		(width 0.127)
		(layer "In13.Cu")
		(net "GPU_FPGA_EROT_RECOV_N")
	)
	(segment
		(start 67.183 -111.577628)
		(end 76.991464 -111.577628)
		(width 0.127)
		(layer "In13.Cu")
		(net "GPU_FPGA_EROT_RECOV_N")
	)
	(segment
		(start 162.6362 -112.212628)
		(end 159.82188 -115.026948)
		(width 0.127)
		(layer "In13.Cu")
		(net "GPU_FPGA_EROT_RECOV_N")
	)
	(segment
		(start 143.22298 -110.25378)
		(end 145.272252 -110.25378)
		(width 0.127)
		(layer "In13.Cu")
		(net "GPU_FPGA_EROT_RECOV_N")
	)
	(segment
		(start 160.11398 -110.416848)
		(end 160.796732 -111.0996)
		(width 0.127)
		(layer "In13.Cu")
		(net "GPU_FPGA_EROT_RECOV_N")
	)
	(segment
		(start 162.6362 -111.41075)
		(end 162.6362 -112.212628)
		(width 0.127)
		(layer "In13.Cu")
		(net "GPU_FPGA_EROT_RECOV_N")
	)
	(segment
		(start 118.42496 -107.328208)
		(end 119.1133 -108.016548)
		(width 0.127)
		(layer "In13.Cu")
		(net "GPU_FPGA_EROT_RECOV_N")
	)
	(segment
		(start 160.796732 -111.0996)
		(end 162.32505 -111.0996)
		(width 0.127)
		(layer "In13.Cu")
		(net "GPU_FPGA_EROT_RECOV_N")
	)
	(segment
		(start 142.412974 -111.063786)
		(end 143.22298 -110.25378)
		(width 0.127)
		(layer "In13.Cu")
		(net "GPU_FPGA_EROT_RECOV_N")
	)
	(segment
		(start 100.895404 -108.450888)
		(end 101.035104 -108.311188)
		(width 0.127)
		(layer "In13.Cu")
		(net "GPU_FPGA_EROT_RECOV_N")
	)
	(segment
		(start 162.32505 -111.0996)
		(end 162.6362 -111.41075)
		(width 0.127)
		(layer "In13.Cu")
		(net "GPU_FPGA_EROT_RECOV_N")
	)
	(segment
		(start 48.93564 -114.511328)
		(end 49.20742 -114.239548)
		(width 0.127)
		(layer "In13.Cu")
		(net "GPU_FPGA_EROT_RECOV_N")
	)
	(segment
		(start 64.187324 -113.881408)
		(end 64.87922 -113.881408)
		(width 0.127)
		(layer "In13.Cu")
		(net "GPU_FPGA_EROT_RECOV_N")
	)
	(segment
		(start 158.13278 -110.416848)
		(end 160.11398 -110.416848)
		(width 0.127)
		(layer "In13.Cu")
		(net "GPU_FPGA_EROT_RECOV_N")
	)
	(segment
		(start 54.54904 -114.239548)
		(end 54.7624 -114.452908)
		(width 0.127)
		(layer "In13.Cu")
		(net "GPU_FPGA_EROT_RECOV_N")
	)
	(segment
		(start 46.226476 -115.298728)
		(end 47.013876 -114.511328)
		(width 0.127)
		(layer "In13.Cu")
		(net "GPU_FPGA_EROT_RECOV_N")
	)
	(segment
		(start 47.013876 -114.511328)
		(end 48.93564 -114.511328)
		(width 0.127)
		(layer "In13.Cu")
		(net "GPU_FPGA_EROT_RECOV_N")
	)
	(segment
		(start 151.41448 -112.436148)
		(end 153.90368 -109.946948)
		(width 0.127)
		(layer "In13.Cu")
		(net "GPU_FPGA_EROT_RECOV_N")
	)
	(segment
		(start 117.55882 -107.328208)
		(end 118.42496 -107.328208)
		(width 0.127)
		(layer "In13.Cu")
		(net "GPU_FPGA_EROT_RECOV_N")
	)
	(segment
		(start 63.615824 -114.452908)
		(end 64.187324 -113.881408)
		(width 0.127)
		(layer "In13.Cu")
		(net "GPU_FPGA_EROT_RECOV_N")
	)
	(segment
		(start 116.57584 -108.311188)
		(end 117.55882 -107.328208)
		(width 0.127)
		(layer "In13.Cu")
		(net "GPU_FPGA_EROT_RECOV_N")
	)
	(segment
		(start 64.87922 -113.881408)
		(end 67.183 -111.577628)
		(width 0.127)
		(layer "In13.Cu")
		(net "GPU_FPGA_EROT_RECOV_N")
	)
	(segment
		(start 145.272252 -110.25378)
		(end 147.45462 -112.436148)
		(width 0.127)
		(layer "In13.Cu")
		(net "GPU_FPGA_EROT_RECOV_N")
	)
	(segment
		(start 138.982196 -109.238288)
		(end 140.807694 -111.063786)
		(width 0.127)
		(layer "In13.Cu")
		(net "GPU_FPGA_EROT_RECOV_N")
	)
	(segment
		(start 153.90368 -109.946948)
		(end 157.66288 -109.946948)
		(width 0.127)
		(layer "In13.Cu")
		(net "GPU_FPGA_EROT_RECOV_N")
	)
	(segment
		(start 140.807694 -111.063786)
		(end 142.412974 -111.063786)
		(width 0.127)
		(layer "In13.Cu")
		(net "GPU_FPGA_EROT_RECOV_N")
	)
	(segment
		(start 126.028704 -108.016548)
		(end 127.250444 -109.238288)
		(width 0.127)
		(layer "In13.Cu")
		(net "GPU_FPGA_EROT_RECOV_N")
	)
	(segment
		(start 127.250444 -109.238288)
		(end 138.982196 -109.238288)
		(width 0.127)
		(layer "In13.Cu")
		(net "GPU_FPGA_EROT_RECOV_N")
	)
	(segment
		(start 54.7624 -114.452908)
		(end 63.615824 -114.452908)
		(width 0.127)
		(layer "In13.Cu")
		(net "GPU_FPGA_EROT_RECOV_N")
	)
	(segment
		(start 101.035104 -108.311188)
		(end 116.57584 -108.311188)
		(width 0.127)
		(layer "In13.Cu")
		(net "GPU_FPGA_EROT_RECOV_N")
	)
	(segment
		(start 11.690096 -176.052988)
		(end 9.77138 -176.052988)
		(width 0.127)
		(layer "In15.Cu")
		(net "GPU_FPGA_EROT_RECOV_N")
	)
	(segment
		(start 41.68648 -117.145308)
		(end 29.004514 -117.145308)
		(width 0.127)
		(layer "In15.Cu")
		(net "GPU_FPGA_EROT_RECOV_N")
	)
	(segment
		(start 29.004514 -117.145308)
		(end 17.50568 -128.644142)
		(width 0.127)
		(layer "In15.Cu")
		(net "GPU_FPGA_EROT_RECOV_N")
	)
	(segment
		(start 17.50568 -128.644142)
		(end 17.50568 -170.237404)
		(width 0.127)
		(layer "In15.Cu")
		(net "GPU_FPGA_EROT_RECOV_N")
	)
	(segment
		(start 42.868342 -115.963446)
		(end 41.68648 -117.145308)
		(width 0.127)
		(layer "In15.Cu")
		(net "GPU_FPGA_EROT_RECOV_N")
	)
	(segment
		(start 46.226476 -115.298728)
		(end 45.561758 -115.963446)
		(width 0.127)
		(layer "In15.Cu")
		(net "GPU_FPGA_EROT_RECOV_N")
	)
	(segment
		(start 17.50568 -170.237404)
		(end 11.690096 -176.052988)
		(width 0.127)
		(layer "In15.Cu")
		(net "GPU_FPGA_EROT_RECOV_N")
	)
	(segment
		(start 45.561758 -115.963446)
		(end 42.868342 -115.963446)
		(width 0.127)
		(layer "In15.Cu")
		(net "GPU_FPGA_EROT_RECOV_N")
	)
	(segment
		(start 110.841282 -403.645116)
		(end 110.841282 -404.358856)
		(width 0.12954)
		(layer "F.Cu")
		(net "GPU_FPGA_EROT_RECOV_BUF_R_N")
	)
	(segment
		(start 110.079282 -405.658066)
		(end 111.095282 -405.658066)
		(width 0.12954)
		(layer "F.Cu")
		(net "GPU_FPGA_EROT_RECOV_BUF_R_N")
	)
	(segment
		(start 110.841282 -405.042116)
		(end 111.095282 -405.296116)
		(width 0.12954)
		(layer "F.Cu")
		(net "GPU_FPGA_EROT_RECOV_BUF_R_N")
	)
	(segment
		(start 110.841282 -404.358856)
		(end 110.841282 -405.042116)
		(width 0.12954)
		(layer "F.Cu")
		(net "GPU_FPGA_EROT_RECOV_BUF_R_N")
	)
	(segment
		(start 111.095282 -405.296116)
		(end 111.095282 -405.658066)
		(width 0.12954)
		(layer "F.Cu")
		(net "GPU_FPGA_EROT_RECOV_BUF_R_N")
	)
	(segment
		(start 109.063282 -405.658066)
		(end 110.079282 -405.658066)
		(width 0.12954)
		(layer "F.Cu")
		(net "GPU_FPGA_EROT_RECOV_BUF_R_N")
	)
	(segment
		(start 111.11484 -403.371558)
		(end 110.841282 -403.645116)
		(width 0.12954)
		(layer "F.Cu")
		(net "GPU_FPGA_EROT_RECOV_BUF_R_N")
	)
	(segment
		(start 111.11484 -403.095206)
		(end 111.11484 -403.371558)
		(width 0.12954)
		(layer "F.Cu")
		(net "GPU_FPGA_EROT_RECOV_BUF_R_N")
	)
	(via
		(at 110.841282 -404.358856)
		(size 0.762)
		(drill 0.381)
		(layers "F.Cu" "B.Cu")
		(net "GPU_FPGA_EROT_RECOV_BUF_R_N")
	)
	(segment
		(start 109.7788 -408.19324)
		(end 109.7788 -407.703528)
		(width 0.12954)
		(layer "F.Cu")
		(net "GPU_FPGA_EROT_RECOV_BUF_N")
	)
	(segment
		(start 109.063282 -406.98801)
		(end 109.063282 -406.458166)
		(width 0.12954)
		(layer "F.Cu")
		(net "GPU_FPGA_EROT_RECOV_BUF_N")
	)
	(segment
		(start 109.7788 -407.703528)
		(end 109.063282 -406.98801)
		(width 0.12954)
		(layer "F.Cu")
		(net "GPU_FPGA_EROT_RECOV_BUF_N")
	)
	(via
		(at 109.7788 -408.19324)
		(size 0.508)
		(drill 0.254)
		(layers "F.Cu" "B.Cu")
		(net "GPU_FPGA_EROT_RECOV_BUF_N")
	)
	(segment
		(start 116.0145 -411.198568)
		(end 116.0145 -411.178248)
		(width 0.12954)
		(layer "B.Cu")
		(net "GPU_FPGA_EROT_RECOV_BUF_N")
	)
	(segment
		(start 123.35002 -438.165748)
		(end 123.22048 -438.036208)
		(width 0.12954)
		(layer "B.Cu")
		(net "GPU_FPGA_EROT_RECOV_BUF_N")
	)
	(segment
		(start 112.80648 -407.970228)
		(end 110.001812 -407.970228)
		(width 0.12954)
		(layer "B.Cu")
		(net "GPU_FPGA_EROT_RECOV_BUF_N")
	)
	(segment
		(start 123.425966 -438.165748)
		(end 123.35002 -438.165748)
		(width 0.12954)
		(layer "B.Cu")
		(net "GPU_FPGA_EROT_RECOV_BUF_N")
	)
	(segment
		(start 123.22048 -418.404548)
		(end 116.0145 -411.198568)
		(width 0.12954)
		(layer "B.Cu")
		(net "GPU_FPGA_EROT_RECOV_BUF_N")
	)
	(segment
		(start 123.22048 -438.036208)
		(end 123.22048 -418.404548)
		(width 0.12954)
		(layer "B.Cu")
		(net "GPU_FPGA_EROT_RECOV_BUF_N")
	)
	(segment
		(start 110.001812 -407.970228)
		(end 109.7788 -408.19324)
		(width 0.12954)
		(layer "B.Cu")
		(net "GPU_FPGA_EROT_RECOV_BUF_N")
	)
	(segment
		(start 125.750066 -440.489848)
		(end 123.425966 -438.165748)
		(width 0.12954)
		(layer "B.Cu")
		(net "GPU_FPGA_EROT_RECOV_BUF_N")
	)
	(segment
		(start 116.0145 -411.178248)
		(end 112.80648 -407.970228)
		(width 0.12954)
		(layer "B.Cu")
		(net "GPU_FPGA_EROT_RECOV_BUF_N")
	)
	(segment
		(start 95.125286 -427.376336)
		(end 94.490286 -427.376336)
		(width 0.12954)
		(layer "F.Cu")
		(net "GPU_FPGA_EROT_FATALERR_N")
	)
	(segment
		(start 96.141286 -426.106336)
		(end 96.039686 -426.004736)
		(width 0.12954)
		(layer "F.Cu")
		(net "GPU_FPGA_EROT_FATALERR_N")
	)
	(segment
		(start 95.125286 -427.376336)
		(end 96.141286 -427.376336)
		(width 0.12954)
		(layer "F.Cu")
		(net "GPU_FPGA_EROT_FATALERR_N")
	)
	(segment
		(start 96.039686 -426.004736)
		(end 96.039686 -424.770296)
		(width 0.12954)
		(layer "F.Cu")
		(net "GPU_FPGA_EROT_FATALERR_N")
	)
	(segment
		(start 96.141286 -427.376336)
		(end 96.141286 -426.106336)
		(width 0.12954)
		(layer "F.Cu")
		(net "GPU_FPGA_EROT_FATALERR_N")
	)
	(via
		(at 94.490286 -427.376336)
		(size 0.508)
		(drill 0.254)
		(layers "F.Cu" "B.Cu")
		(net "GPU_FPGA_EROT_FATALERR_N")
	)
	(via
		(at 96.141286 -426.106336)
		(size 0.762)
		(drill 0.381)
		(layers "F.Cu" "B.Cu")
		(net "GPU_FPGA_EROT_FATALERR_N")
	)
	(segment
		(start 144.749774 -424.689778)
		(end 143.481044 -423.421048)
		(width 0.127)
		(layer "In15.Cu")
		(net "GPU_FPGA_EROT_FATALERR_N")
	)
	(segment
		(start 143.481044 -423.421048)
		(end 122.7455 -423.421048)
		(width 0.127)
		(layer "In15.Cu")
		(net "GPU_FPGA_EROT_FATALERR_N")
	)
	(segment
		(start 101.65842 -422.435528)
		(end 97.2947 -426.799248)
		(width 0.127)
		(layer "In15.Cu")
		(net "GPU_FPGA_EROT_FATALERR_N")
	)
	(segment
		(start 144.750028 -424.689778)
		(end 144.749774 -424.689778)
		(width 0.127)
		(layer "In15.Cu")
		(net "GPU_FPGA_EROT_FATALERR_N")
	)
	(segment
		(start 122.7455 -423.421048)
		(end 122.27814 -422.953688)
		(width 0.127)
		(layer "In15.Cu")
		(net "GPU_FPGA_EROT_FATALERR_N")
	)
	(segment
		(start 119.97944 -422.953688)
		(end 117.33276 -420.307008)
		(width 0.127)
		(layer "In15.Cu")
		(net "GPU_FPGA_EROT_FATALERR_N")
	)
	(segment
		(start 117.33276 -420.307008)
		(end 108.42244 -420.307008)
		(width 0.127)
		(layer "In15.Cu")
		(net "GPU_FPGA_EROT_FATALERR_N")
	)
	(segment
		(start 97.2947 -426.799248)
		(end 95.067374 -426.799248)
		(width 0.127)
		(layer "In15.Cu")
		(net "GPU_FPGA_EROT_FATALERR_N")
	)
	(segment
		(start 106.29392 -422.435528)
		(end 101.65842 -422.435528)
		(width 0.127)
		(layer "In15.Cu")
		(net "GPU_FPGA_EROT_FATALERR_N")
	)
	(segment
		(start 95.067374 -426.799248)
		(end 94.490286 -427.376336)
		(width 0.127)
		(layer "In15.Cu")
		(net "GPU_FPGA_EROT_FATALERR_N")
	)
	(segment
		(start 122.27814 -422.953688)
		(end 119.97944 -422.953688)
		(width 0.127)
		(layer "In15.Cu")
		(net "GPU_FPGA_EROT_FATALERR_N")
	)
	(segment
		(start 108.42244 -420.307008)
		(end 106.29392 -422.435528)
		(width 0.127)
		(layer "In15.Cu")
		(net "GPU_FPGA_EROT_FATALERR_N")
	)
	(segment
		(start 172.555662 -112.97539)
		(end 172.155612 -112.57534)
		(width 0.12954)
		(layer "F.Cu")
		(net "GPU_FPGA_EROT_FATALERR_ISO_R_N")
	)
	(via
		(at 168.26992 -114.244628)
		(size 0.6604)
		(drill 0.3302)
		(layers "F.Cu" "B.Cu")
		(net "GPU_FPGA_EROT_FATALERR_ISO_R_N")
	)
	(via
		(at 172.155612 -112.57534)
		(size 0.4572)
		(drill 0.254)
		(layers "F.Cu" "B.Cu")
		(net "GPU_FPGA_EROT_FATALERR_ISO_R_N")
	)
	(segment
		(start 168.604692 -114.5794)
		(end 172.374306 -114.5794)
		(width 0.12954)
		(layer "B.Cu")
		(net "GPU_FPGA_EROT_FATALERR_ISO_R_N")
	)
	(segment
		(start 166.318946 -114.244628)
		(end 165.536626 -115.026948)
		(width 0.12954)
		(layer "B.Cu")
		(net "GPU_FPGA_EROT_FATALERR_ISO_R_N")
	)
	(segment
		(start 168.26992 -114.244628)
		(end 166.318946 -114.244628)
		(width 0.12954)
		(layer "B.Cu")
		(net "GPU_FPGA_EROT_FATALERR_ISO_R_N")
	)
	(segment
		(start 172.54982 -113.24082)
		(end 172.155612 -112.846612)
		(width 0.12954)
		(layer "B.Cu")
		(net "GPU_FPGA_EROT_FATALERR_ISO_R_N")
	)
	(segment
		(start 165.536626 -115.026948)
		(end 165.04793 -115.026948)
		(width 0.12954)
		(layer "B.Cu")
		(net "GPU_FPGA_EROT_FATALERR_ISO_R_N")
	)
	(segment
		(start 172.374306 -114.5794)
		(end 172.54982 -114.403886)
		(width 0.12954)
		(layer "B.Cu")
		(net "GPU_FPGA_EROT_FATALERR_ISO_R_N")
	)
	(segment
		(start 168.26992 -114.244628)
		(end 168.604692 -114.5794)
		(width 0.12954)
		(layer "B.Cu")
		(net "GPU_FPGA_EROT_FATALERR_ISO_R_N")
	)
	(segment
		(start 172.155612 -112.846612)
		(end 172.155612 -112.57534)
		(width 0.12954)
		(layer "B.Cu")
		(net "GPU_FPGA_EROT_FATALERR_ISO_R_N")
	)
	(segment
		(start 172.54982 -114.403886)
		(end 172.54982 -113.24082)
		(width 0.12954)
		(layer "B.Cu")
		(net "GPU_FPGA_EROT_FATALERR_ISO_R_N")
	)
	(segment
		(start 25.40508 -410.418534)
		(end 24.877014 -410.9466)
		(width 0.12954)
		(layer "F.Cu")
		(net "GPU_FPGA_EROT_FATALERR_ISO_N")
	)
	(segment
		(start 22.479 -412.9278)
		(end 22.606 -413.0548)
		(width 0.12954)
		(layer "F.Cu")
		(net "GPU_FPGA_EROT_FATALERR_ISO_N")
	)
	(segment
		(start 24.384 -413.0548)
		(end 25.3746 -414.0454)
		(width 0.12954)
		(layer "F.Cu")
		(net "GPU_FPGA_EROT_FATALERR_ISO_N")
	)
	(segment
		(start 55.245 -412.623)
		(end 73.061068 -412.623)
		(width 0.12954)
		(layer "F.Cu")
		(net "GPU_FPGA_EROT_FATALERR_ISO_N")
	)
	(segment
		(start 47.6758 -411.226)
		(end 50.1269 -413.6771)
		(width 0.12954)
		(layer "F.Cu")
		(net "GPU_FPGA_EROT_FATALERR_ISO_N")
	)
	(segment
		(start 40.513 -412.8008)
		(end 42.0878 -411.226)
		(width 0.12954)
		(layer "F.Cu")
		(net "GPU_FPGA_EROT_FATALERR_ISO_N")
	)
	(segment
		(start 24.469852 -409.402534)
		(end 24.469852 -410.418534)
		(width 0.12954)
		(layer "F.Cu")
		(net "GPU_FPGA_EROT_FATALERR_ISO_N")
	)
	(segment
		(start 73.061068 -412.623)
		(end 73.134728 -412.69666)
		(width 0.12954)
		(layer "F.Cu")
		(net "GPU_FPGA_EROT_FATALERR_ISO_N")
	)
	(segment
		(start 24.469852 -410.418534)
		(end 25.40508 -410.418534)
		(width 0.12954)
		(layer "F.Cu")
		(net "GPU_FPGA_EROT_FATALERR_ISO_N")
	)
	(segment
		(start 22.606 -410.9466)
		(end 22.479 -411.0736)
		(width 0.12954)
		(layer "F.Cu")
		(net "GPU_FPGA_EROT_FATALERR_ISO_N")
	)
	(segment
		(start 22.479 -411.0736)
		(end 22.479 -412.9278)
		(width 0.12954)
		(layer "F.Cu")
		(net "GPU_FPGA_EROT_FATALERR_ISO_N")
	)
	(segment
		(start 42.0878 -411.226)
		(end 47.6758 -411.226)
		(width 0.12954)
		(layer "F.Cu")
		(net "GPU_FPGA_EROT_FATALERR_ISO_N")
	)
	(segment
		(start 54.1909 -413.6771)
		(end 55.245 -412.623)
		(width 0.12954)
		(layer "F.Cu")
		(net "GPU_FPGA_EROT_FATALERR_ISO_N")
	)
	(segment
		(start 25.3746 -414.0454)
		(end 27.5082 -414.0454)
		(width 0.12954)
		(layer "F.Cu")
		(net "GPU_FPGA_EROT_FATALERR_ISO_N")
	)
	(segment
		(start 73.134728 -412.69666)
		(end 73.134982 -412.69666)
		(width 0.12954)
		(layer "F.Cu")
		(net "GPU_FPGA_EROT_FATALERR_ISO_N")
	)
	(segment
		(start 77.742542 -417.30422)
		(end 89.0651 -417.30422)
		(width 0.12954)
		(layer "F.Cu")
		(net "GPU_FPGA_EROT_FATALERR_ISO_N")
	)
	(segment
		(start 22.606 -413.0548)
		(end 24.384 -413.0548)
		(width 0.12954)
		(layer "F.Cu")
		(net "GPU_FPGA_EROT_FATALERR_ISO_N")
	)
	(segment
		(start 27.5082 -414.0454)
		(end 28.7528 -412.8008)
		(width 0.12954)
		(layer "F.Cu")
		(net "GPU_FPGA_EROT_FATALERR_ISO_N")
	)
	(segment
		(start 89.0651 -417.30422)
		(end 92.4052 -420.64432)
		(width 0.12954)
		(layer "F.Cu")
		(net "GPU_FPGA_EROT_FATALERR_ISO_N")
	)
	(segment
		(start 50.1269 -413.6771)
		(end 54.1909 -413.6771)
		(width 0.12954)
		(layer "F.Cu")
		(net "GPU_FPGA_EROT_FATALERR_ISO_N")
	)
	(segment
		(start 28.7528 -412.8008)
		(end 35.1282 -412.8008)
		(width 0.12954)
		(layer "F.Cu")
		(net "GPU_FPGA_EROT_FATALERR_ISO_N")
	)
	(segment
		(start 73.134982 -412.69666)
		(end 77.742542 -417.30422)
		(width 0.12954)
		(layer "F.Cu")
		(net "GPU_FPGA_EROT_FATALERR_ISO_N")
	)
	(segment
		(start 92.4052 -423.291)
		(end 93.884496 -424.770296)
		(width 0.12954)
		(layer "F.Cu")
		(net "GPU_FPGA_EROT_FATALERR_ISO_N")
	)
	(segment
		(start 92.4052 -420.64432)
		(end 92.4052 -423.291)
		(width 0.12954)
		(layer "F.Cu")
		(net "GPU_FPGA_EROT_FATALERR_ISO_N")
	)
	(segment
		(start 35.1282 -412.8008)
		(end 40.513 -412.8008)
		(width 0.12954)
		(layer "F.Cu")
		(net "GPU_FPGA_EROT_FATALERR_ISO_N")
	)
	(segment
		(start 93.884496 -424.770296)
		(end 95.3897 -424.770296)
		(width 0.12954)
		(layer "F.Cu")
		(net "GPU_FPGA_EROT_FATALERR_ISO_N")
	)
	(segment
		(start 24.877014 -410.9466)
		(end 22.606 -410.9466)
		(width 0.12954)
		(layer "F.Cu")
		(net "GPU_FPGA_EROT_FATALERR_ISO_N")
	)
	(via
		(at 35.1282 -412.8008)
		(size 0.762)
		(drill 0.381)
		(layers "F.Cu" "B.Cu")
		(net "GPU_FPGA_EROT_FATALERR_ISO_N")
	)
	(via
		(at 25.40508 -410.418534)
		(size 0.508)
		(drill 0.254)
		(layers "F.Cu" "B.Cu")
		(net "GPU_FPGA_EROT_FATALERR_ISO_N")
	)
	(via
		(at 144.09928 -116.830348)
		(size 0.508)
		(drill 0.254)
		(layers "F.Cu" "B.Cu")
		(net "GPU_FPGA_EROT_FATALERR_ISO_N")
	)
	(via
		(at 161.85388 -115.026948)
		(size 0.508)
		(drill 0.254)
		(layers "F.Cu" "B.Cu")
		(net "GPU_FPGA_EROT_FATALERR_ISO_N")
	)
	(segment
		(start 164.24783 -114.677698)
		(end 164.24783 -115.026948)
		(width 0.12954)
		(layer "B.Cu")
		(net "GPU_FPGA_EROT_FATALERR_ISO_N")
	)
	(segment
		(start 164.01288 -114.442748)
		(end 164.24783 -114.677698)
		(width 0.12954)
		(layer "B.Cu")
		(net "GPU_FPGA_EROT_FATALERR_ISO_N")
	)
	(segment
		(start 162.43808 -114.442748)
		(end 164.01288 -114.442748)
		(width 0.12954)
		(layer "B.Cu")
		(net "GPU_FPGA_EROT_FATALERR_ISO_N")
	)
	(segment
		(start 161.85388 -115.026948)
		(end 162.43808 -114.442748)
		(width 0.12954)
		(layer "B.Cu")
		(net "GPU_FPGA_EROT_FATALERR_ISO_N")
	)
	(segment
		(start 161.85388 -115.026948)
		(end 161.37128 -115.026948)
		(width 0.127)
		(layer "In4.Cu")
		(net "GPU_FPGA_EROT_FATALERR_ISO_N")
	)
	(segment
		(start 152.83942 -116.4844)
		(end 152.036272 -115.681252)
		(width 0.127)
		(layer "In4.Cu")
		(net "GPU_FPGA_EROT_FATALERR_ISO_N")
	)
	(segment
		(start 160.76168 -115.636548)
		(end 155.061412 -115.636548)
		(width 0.127)
		(layer "In4.Cu")
		(net "GPU_FPGA_EROT_FATALERR_ISO_N")
	)
	(segment
		(start 147.60448 -116.830348)
		(end 144.09928 -116.830348)
		(width 0.127)
		(layer "In4.Cu")
		(net "GPU_FPGA_EROT_FATALERR_ISO_N")
	)
	(segment
		(start 148.753576 -115.681252)
		(end 147.60448 -116.830348)
		(width 0.127)
		(layer "In4.Cu")
		(net "GPU_FPGA_EROT_FATALERR_ISO_N")
	)
	(segment
		(start 155.061412 -115.636548)
		(end 154.21356 -116.4844)
		(width 0.127)
		(layer "In4.Cu")
		(net "GPU_FPGA_EROT_FATALERR_ISO_N")
	)
	(segment
		(start 154.21356 -116.4844)
		(end 152.83942 -116.4844)
		(width 0.127)
		(layer "In4.Cu")
		(net "GPU_FPGA_EROT_FATALERR_ISO_N")
	)
	(segment
		(start 161.37128 -115.026948)
		(end 160.76168 -115.636548)
		(width 0.127)
		(layer "In4.Cu")
		(net "GPU_FPGA_EROT_FATALERR_ISO_N")
	)
	(segment
		(start 152.036272 -115.681252)
		(end 148.753576 -115.681252)
		(width 0.127)
		(layer "In4.Cu")
		(net "GPU_FPGA_EROT_FATALERR_ISO_N")
	)
	(segment
		(start 5.16128 -154.830272)
		(end 5.16128 -133.137148)
		(width 0.127)
		(layer "In13.Cu")
		(net "GPU_FPGA_EROT_FATALERR_ISO_N")
	)
	(segment
		(start 24.33066 -403.29104)
		(end 19.527012 -403.29104)
		(width 0.127)
		(layer "In13.Cu")
		(net "GPU_FPGA_EROT_FATALERR_ISO_N")
	)
	(segment
		(start 26.21788 -405.17826)
		(end 24.33066 -403.29104)
		(width 0.127)
		(layer "In13.Cu")
		(net "GPU_FPGA_EROT_FATALERR_ISO_N")
	)
	(segment
		(start 6.10108 -335.046828)
		(end 6.10108 -196.69252)
		(width 0.127)
		(layer "In13.Cu")
		(net "GPU_FPGA_EROT_FATALERR_ISO_N")
	)
	(segment
		(start 19.2786 -381.230632)
		(end 19.2786 -348.224348)
		(width 0.127)
		(layer "In13.Cu")
		(net "GPU_FPGA_EROT_FATALERR_ISO_N")
	)
	(segment
		(start 16.8783 -400.642328)
		(end 16.8783 -383.630932)
		(width 0.127)
		(layer "In13.Cu")
		(net "GPU_FPGA_EROT_FATALERR_ISO_N")
	)
	(segment
		(start 4.88188 -164.099748)
		(end 4.88188 -155.109672)
		(width 0.127)
		(layer "In13.Cu")
		(net "GPU_FPGA_EROT_FATALERR_ISO_N")
	)
	(segment
		(start 24.4856 -408.3304)
		(end 24.4856 -407.3144)
		(width 0.127)
		(layer "In13.Cu")
		(net "GPU_FPGA_EROT_FATALERR_ISO_N")
	)
	(segment
		(start 5.16128 -133.137148)
		(end 20.63242 -117.666008)
		(width 0.127)
		(layer "In13.Cu")
		(net "GPU_FPGA_EROT_FATALERR_ISO_N")
	)
	(segment
		(start 26.21788 -405.58212)
		(end 26.21788 -405.17826)
		(width 0.127)
		(layer "In13.Cu")
		(net "GPU_FPGA_EROT_FATALERR_ISO_N")
	)
	(segment
		(start 16.8783 -383.630932)
		(end 19.2786 -381.230632)
		(width 0.127)
		(layer "In13.Cu")
		(net "GPU_FPGA_EROT_FATALERR_ISO_N")
	)
	(segment
		(start 5.388356 -194.250564)
		(end 6.10108 -193.53784)
		(width 0.127)
		(layer "In13.Cu")
		(net "GPU_FPGA_EROT_FATALERR_ISO_N")
	)
	(segment
		(start 5.388356 -195.979796)
		(end 5.388356 -194.250564)
		(width 0.127)
		(layer "In13.Cu")
		(net "GPU_FPGA_EROT_FATALERR_ISO_N")
	)
	(segment
		(start 6.10108 -193.53784)
		(end 6.10108 -165.318948)
		(width 0.127)
		(layer "In13.Cu")
		(net "GPU_FPGA_EROT_FATALERR_ISO_N")
	)
	(segment
		(start 24.4856 -407.3144)
		(end 26.21788 -405.58212)
		(width 0.127)
		(layer "In13.Cu")
		(net "GPU_FPGA_EROT_FATALERR_ISO_N")
	)
	(segment
		(start 143.927068 -116.830348)
		(end 144.09928 -116.830348)
		(width 0.127)
		(layer "In13.Cu")
		(net "GPU_FPGA_EROT_FATALERR_ISO_N")
	)
	(segment
		(start 25.40508 -409.24988)
		(end 24.4856 -408.3304)
		(width 0.127)
		(layer "In13.Cu")
		(net "GPU_FPGA_EROT_FATALERR_ISO_N")
	)
	(segment
		(start 6.10108 -165.318948)
		(end 4.88188 -164.099748)
		(width 0.127)
		(layer "In13.Cu")
		(net "GPU_FPGA_EROT_FATALERR_ISO_N")
	)
	(segment
		(start 136.4869 -112.87506)
		(end 137.97788 -114.36604)
		(width 0.127)
		(layer "In13.Cu")
		(net "GPU_FPGA_EROT_FATALERR_ISO_N")
	)
	(segment
		(start 94.523306 -116.455698)
		(end 104.302306 -116.455698)
		(width 0.127)
		(layer "In13.Cu")
		(net "GPU_FPGA_EROT_FATALERR_ISO_N")
	)
	(segment
		(start 92.313506 -118.665498)
		(end 94.523306 -116.455698)
		(width 0.127)
		(layer "In13.Cu")
		(net "GPU_FPGA_EROT_FATALERR_ISO_N")
	)
	(segment
		(start 104.302306 -116.455698)
		(end 106.486706 -114.271298)
		(width 0.127)
		(layer "In13.Cu")
		(net "GPU_FPGA_EROT_FATALERR_ISO_N")
	)
	(segment
		(start 106.486706 -114.271298)
		(end 132.013706 -114.271298)
		(width 0.127)
		(layer "In13.Cu")
		(net "GPU_FPGA_EROT_FATALERR_ISO_N")
	)
	(segment
		(start 25.40508 -410.418534)
		(end 25.40508 -409.24988)
		(width 0.127)
		(layer "In13.Cu")
		(net "GPU_FPGA_EROT_FATALERR_ISO_N")
	)
	(segment
		(start 4.88188 -155.109672)
		(end 5.16128 -154.830272)
		(width 0.127)
		(layer "In13.Cu")
		(net "GPU_FPGA_EROT_FATALERR_ISO_N")
	)
	(segment
		(start 137.97788 -114.36604)
		(end 141.46276 -114.36604)
		(width 0.127)
		(layer "In13.Cu")
		(net "GPU_FPGA_EROT_FATALERR_ISO_N")
	)
	(segment
		(start 133.409944 -112.87506)
		(end 136.4869 -112.87506)
		(width 0.127)
		(layer "In13.Cu")
		(net "GPU_FPGA_EROT_FATALERR_ISO_N")
	)
	(segment
		(start 51.22291 -117.666008)
		(end 52.2224 -118.665498)
		(width 0.127)
		(layer "In13.Cu")
		(net "GPU_FPGA_EROT_FATALERR_ISO_N")
	)
	(segment
		(start 132.013706 -114.271298)
		(end 133.409944 -112.87506)
		(width 0.127)
		(layer "In13.Cu")
		(net "GPU_FPGA_EROT_FATALERR_ISO_N")
	)
	(segment
		(start 19.2786 -348.224348)
		(end 6.10108 -335.046828)
		(width 0.127)
		(layer "In13.Cu")
		(net "GPU_FPGA_EROT_FATALERR_ISO_N")
	)
	(segment
		(start 19.527012 -403.29104)
		(end 16.8783 -400.642328)
		(width 0.127)
		(layer "In13.Cu")
		(net "GPU_FPGA_EROT_FATALERR_ISO_N")
	)
	(segment
		(start 6.10108 -196.69252)
		(end 5.388356 -195.979796)
		(width 0.127)
		(layer "In13.Cu")
		(net "GPU_FPGA_EROT_FATALERR_ISO_N")
	)
	(segment
		(start 20.63242 -117.666008)
		(end 51.22291 -117.666008)
		(width 0.127)
		(layer "In13.Cu")
		(net "GPU_FPGA_EROT_FATALERR_ISO_N")
	)
	(segment
		(start 141.46276 -114.36604)
		(end 143.927068 -116.830348)
		(width 0.127)
		(layer "In13.Cu")
		(net "GPU_FPGA_EROT_FATALERR_ISO_N")
	)
	(segment
		(start 52.2224 -118.665498)
		(end 92.313506 -118.665498)
		(width 0.127)
		(layer "In13.Cu")
		(net "GPU_FPGA_EROT_FATALERR_ISO_N")
	)
	(segment
		(start 96.689672 -423.1894)
		(end 96.562672 -423.3164)
		(width 0.12954)
		(layer "F.Cu")
		(net "GPU_FPGA_EROT_FATALERR")
	)
	(segment
		(start 96.039686 -423.1894)
		(end 96.039686 -422.870376)
		(width 0.12954)
		(layer "F.Cu")
		(net "GPU_FPGA_EROT_FATALERR")
	)
	(segment
		(start 95.095314 -421.000428)
		(end 95.095314 -420.122604)
		(width 0.12954)
		(layer "F.Cu")
		(net "GPU_FPGA_EROT_FATALERR")
	)
	(segment
		(start 96.562672 -423.3164)
		(end 96.166686 -423.3164)
		(width 0.12954)
		(layer "F.Cu")
		(net "GPU_FPGA_EROT_FATALERR")
	)
	(segment
		(start 95.482156 -421.38727)
		(end 95.095314 -421.000428)
		(width 0.12954)
		(layer "F.Cu")
		(net "GPU_FPGA_EROT_FATALERR")
	)
	(segment
		(start 96.689672 -422.870376)
		(end 96.689672 -423.1894)
		(width 0.12954)
		(layer "F.Cu")
		(net "GPU_FPGA_EROT_FATALERR")
	)
	(segment
		(start 96.039686 -421.9448)
		(end 95.482156 -421.38727)
		(width 0.12954)
		(layer "F.Cu")
		(net "GPU_FPGA_EROT_FATALERR")
	)
	(segment
		(start 96.166686 -423.3164)
		(end 96.039686 -423.1894)
		(width 0.12954)
		(layer "F.Cu")
		(net "GPU_FPGA_EROT_FATALERR")
	)
	(segment
		(start 96.039686 -422.870376)
		(end 96.039686 -421.9448)
		(width 0.12954)
		(layer "F.Cu")
		(net "GPU_FPGA_EROT_FATALERR")
	)
	(via
		(at 95.482156 -421.38727)
		(size 0.762)
		(drill 0.381)
		(layers "F.Cu" "B.Cu")
		(net "GPU_FPGA_EROT_FATALERR")
	)
	(segment
		(start 157.42793 -116.296948)
		(end 158.04388 -116.296948)
		(width 0.12954)
		(layer "F.Cu")
		(net "GPU_FPGA_BOOT_EN_R")
	)
	(segment
		(start 174.955708 -112.97539)
		(end 174.555658 -112.57534)
		(width 0.12954)
		(layer "F.Cu")
		(net "GPU_FPGA_BOOT_EN_R")
	)
	(via
		(at 173.12894 -113.299748)
		(size 0.6604)
		(drill 0.3302)
		(layers "F.Cu" "B.Cu")
		(net "GPU_FPGA_BOOT_EN_R")
	)
	(via
		(at 158.04388 -116.296948)
		(size 0.508)
		(drill 0.254)
		(layers "F.Cu" "B.Cu")
		(net "GPU_FPGA_BOOT_EN_R")
	)
	(via
		(at 174.555658 -112.57534)
		(size 0.4572)
		(drill 0.254)
		(layers "F.Cu" "B.Cu")
		(net "GPU_FPGA_BOOT_EN_R")
	)
	(segment
		(start 174.379128 -112.57534)
		(end 173.65472 -113.299748)
		(width 0.12954)
		(layer "B.Cu")
		(net "GPU_FPGA_BOOT_EN_R")
	)
	(segment
		(start 174.555658 -112.57534)
		(end 174.379128 -112.57534)
		(width 0.12954)
		(layer "B.Cu")
		(net "GPU_FPGA_BOOT_EN_R")
	)
	(segment
		(start 173.65472 -113.299748)
		(end 173.12894 -113.299748)
		(width 0.12954)
		(layer "B.Cu")
		(net "GPU_FPGA_BOOT_EN_R")
	)
	(segment
		(start 171.146978 -113.459768)
		(end 170.814746 -113.792)
		(width 0.127)
		(layer "In15.Cu")
		(net "GPU_FPGA_BOOT_EN_R")
	)
	(segment
		(start 161.28492 -116.464588)
		(end 160.54832 -116.464588)
		(width 0.127)
		(layer "In15.Cu")
		(net "GPU_FPGA_BOOT_EN_R")
	)
	(segment
		(start 160.54832 -116.464588)
		(end 160.08604 -116.926868)
		(width 0.127)
		(layer "In15.Cu")
		(net "GPU_FPGA_BOOT_EN_R")
	)
	(segment
		(start 170.814746 -113.792)
		(end 167.554148 -113.792)
		(width 0.127)
		(layer "In15.Cu")
		(net "GPU_FPGA_BOOT_EN_R")
	)
	(segment
		(start 167.554148 -113.792)
		(end 167.2717 -114.074448)
		(width 0.127)
		(layer "In15.Cu")
		(net "GPU_FPGA_BOOT_EN_R")
	)
	(segment
		(start 158.6738 -116.926868)
		(end 158.04388 -116.296948)
		(width 0.127)
		(layer "In15.Cu")
		(net "GPU_FPGA_BOOT_EN_R")
	)
	(segment
		(start 173.67123 -113.459768)
		(end 171.146978 -113.459768)
		(width 0.127)
		(layer "In15.Cu")
		(net "GPU_FPGA_BOOT_EN_R")
	)
	(segment
		(start 167.2717 -114.074448)
		(end 166.74338 -114.074448)
		(width 0.127)
		(layer "In15.Cu")
		(net "GPU_FPGA_BOOT_EN_R")
	)
	(segment
		(start 174.555658 -112.57534)
		(end 173.67123 -113.459768)
		(width 0.127)
		(layer "In15.Cu")
		(net "GPU_FPGA_BOOT_EN_R")
	)
	(segment
		(start 160.08604 -116.926868)
		(end 158.6738 -116.926868)
		(width 0.127)
		(layer "In15.Cu")
		(net "GPU_FPGA_BOOT_EN_R")
	)
	(segment
		(start 163.89096 -116.926868)
		(end 161.7472 -116.926868)
		(width 0.127)
		(layer "In15.Cu")
		(net "GPU_FPGA_BOOT_EN_R")
	)
	(segment
		(start 161.7472 -116.926868)
		(end 161.28492 -116.464588)
		(width 0.127)
		(layer "In15.Cu")
		(net "GPU_FPGA_BOOT_EN_R")
	)
	(segment
		(start 166.74338 -114.074448)
		(end 163.89096 -116.926868)
		(width 0.127)
		(layer "In15.Cu")
		(net "GPU_FPGA_BOOT_EN_R")
	)
	(segment
		(start 169.83583 -440.019948)
		(end 169.83583 -439.003948)
		(width 0.12954)
		(layer "F.Cu")
		(net "GPU_FPGA_BOOT_EN_BUF_R")
	)
	(segment
		(start 169.83583 -437.987948)
		(end 169.32783 -438.495948)
		(width 0.12954)
		(layer "F.Cu")
		(net "GPU_FPGA_BOOT_EN_BUF_R")
	)
	(segment
		(start 169.32783 -438.495948)
		(end 168.58488 -438.495948)
		(width 0.12954)
		(layer "F.Cu")
		(net "GPU_FPGA_BOOT_EN_BUF_R")
	)
	(segment
		(start 168.58488 -438.495948)
		(end 168.249854 -438.495948)
		(width 0.12954)
		(layer "F.Cu")
		(net "GPU_FPGA_BOOT_EN_BUF_R")
	)
	(segment
		(start 168.249854 -438.495948)
		(end 167.37584 -437.621934)
		(width 0.12954)
		(layer "F.Cu")
		(net "GPU_FPGA_BOOT_EN_BUF_R")
	)
	(segment
		(start 169.83583 -439.003948)
		(end 169.83583 -437.987948)
		(width 0.12954)
		(layer "F.Cu")
		(net "GPU_FPGA_BOOT_EN_BUF_R")
	)
	(via
		(at 168.58488 -438.495948)
		(size 0.762)
		(drill 0.381)
		(layers "F.Cu" "B.Cu")
		(net "GPU_FPGA_BOOT_EN_BUF_R")
	)
	(segment
		(start 170.94708 -437.987948)
		(end 170.63593 -437.987948)
		(width 0.12954)
		(layer "F.Cu")
		(net "GPU_FPGA_BOOT_EN_BUF")
	)
	(segment
		(start 171.48048 -437.454548)
		(end 170.94708 -437.987948)
		(width 0.12954)
		(layer "F.Cu")
		(net "GPU_FPGA_BOOT_EN_BUF")
	)
	(segment
		(start 171.48048 -435.925468)
		(end 171.48048 -437.454548)
		(width 0.12954)
		(layer "F.Cu")
		(net "GPU_FPGA_BOOT_EN_BUF")
	)
	(via
		(at 171.48048 -435.925468)
		(size 0.508)
		(drill 0.254)
		(layers "F.Cu" "B.Cu")
		(net "GPU_FPGA_BOOT_EN_BUF")
	)
	(segment
		(start 163.91128 -435.524148)
		(end 163.91128 -437.810148)
		(width 0.127)
		(layer "In2.Cu")
		(net "GPU_FPGA_BOOT_EN_BUF")
	)
	(segment
		(start 162.61588 -432.120548)
		(end 162.61588 -434.228748)
		(width 0.127)
		(layer "In2.Cu")
		(net "GPU_FPGA_BOOT_EN_BUF")
	)
	(segment
		(start 163.49726 -431.239168)
		(end 162.61588 -432.120548)
		(width 0.127)
		(layer "In2.Cu")
		(net "GPU_FPGA_BOOT_EN_BUF")
	)
	(segment
		(start 160.33242 -420.220648)
		(end 163.49726 -423.385488)
		(width 0.127)
		(layer "In2.Cu")
		(net "GPU_FPGA_BOOT_EN_BUF")
	)
	(segment
		(start 164.34308 -438.241948)
		(end 169.11828 -438.241948)
		(width 0.127)
		(layer "In2.Cu")
		(net "GPU_FPGA_BOOT_EN_BUF")
	)
	(segment
		(start 128.406652 -424.032934)
		(end 132.218938 -420.220648)
		(width 0.127)
		(layer "In2.Cu")
		(net "GPU_FPGA_BOOT_EN_BUF")
	)
	(segment
		(start 163.49726 -423.385488)
		(end 163.49726 -431.239168)
		(width 0.127)
		(layer "In2.Cu")
		(net "GPU_FPGA_BOOT_EN_BUF")
	)
	(segment
		(start 128.406652 -424.033188)
		(end 128.406652 -424.032934)
		(width 0.127)
		(layer "In2.Cu")
		(net "GPU_FPGA_BOOT_EN_BUF")
	)
	(segment
		(start 170.95216 -436.794148)
		(end 171.48048 -436.265828)
		(width 0.127)
		(layer "In2.Cu")
		(net "GPU_FPGA_BOOT_EN_BUF")
	)
	(segment
		(start 171.48048 -436.265828)
		(end 171.48048 -435.925468)
		(width 0.127)
		(layer "In2.Cu")
		(net "GPU_FPGA_BOOT_EN_BUF")
	)
	(segment
		(start 169.11828 -438.241948)
		(end 170.56608 -436.794148)
		(width 0.127)
		(layer "In2.Cu")
		(net "GPU_FPGA_BOOT_EN_BUF")
	)
	(segment
		(start 163.91128 -437.810148)
		(end 164.34308 -438.241948)
		(width 0.127)
		(layer "In2.Cu")
		(net "GPU_FPGA_BOOT_EN_BUF")
	)
	(segment
		(start 162.61588 -434.228748)
		(end 163.91128 -435.524148)
		(width 0.127)
		(layer "In2.Cu")
		(net "GPU_FPGA_BOOT_EN_BUF")
	)
	(segment
		(start 132.218938 -420.220648)
		(end 160.33242 -420.220648)
		(width 0.127)
		(layer "In2.Cu")
		(net "GPU_FPGA_BOOT_EN_BUF")
	)
	(segment
		(start 170.56608 -436.794148)
		(end 170.95216 -436.794148)
		(width 0.127)
		(layer "In2.Cu")
		(net "GPU_FPGA_BOOT_EN_BUF")
	)
	(segment
		(start 127.750062 -424.689778)
		(end 128.406652 -424.033188)
		(width 0.127)
		(layer "In2.Cu")
		(net "GPU_FPGA_BOOT_EN_BUF")
	)
	(segment
		(start 190.211964 -166.588948)
		(end 186.57316 -166.588948)
		(width 0.12954)
		(layer "F.Cu")
		(net "GPU_FPGA_BOOT_EN")
	)
	(segment
		(start 244.07368 -166.309548)
		(end 244.07368 -166.055548)
		(width 0.12954)
		(layer "F.Cu")
		(net "GPU_FPGA_BOOT_EN")
	)
	(segment
		(start 185.0517 -165.067488)
		(end 182.14848 -165.067488)
		(width 0.12954)
		(layer "F.Cu")
		(net "GPU_FPGA_BOOT_EN")
	)
	(segment
		(start 192.604644 -164.196268)
		(end 190.211964 -166.588948)
		(width 0.12954)
		(layer "F.Cu")
		(net "GPU_FPGA_BOOT_EN")
	)
	(segment
		(start 156.62783 -116.296948)
		(end 156.01188 -116.296948)
		(width 0.12954)
		(layer "F.Cu")
		(net "GPU_FPGA_BOOT_EN")
	)
	(segment
		(start 181.66588 -164.584888)
		(end 181.66588 -163.388548)
		(width 0.12954)
		(layer "F.Cu")
		(net "GPU_FPGA_BOOT_EN")
	)
	(segment
		(start 242.90528 -164.887148)
		(end 242.90528 -161.376868)
		(width 0.12954)
		(layer "F.Cu")
		(net "GPU_FPGA_BOOT_EN")
	)
	(segment
		(start 201.32548 -164.196268)
		(end 192.604644 -164.196268)
		(width 0.12954)
		(layer "F.Cu")
		(net "GPU_FPGA_BOOT_EN")
	)
	(segment
		(start 165.47592 -437.621934)
		(end 164.64788 -437.621934)
		(width 0.12954)
		(layer "F.Cu")
		(net "GPU_FPGA_BOOT_EN")
	)
	(segment
		(start 208.1022 -157.419548)
		(end 201.32548 -164.196268)
		(width 0.12954)
		(layer "F.Cu")
		(net "GPU_FPGA_BOOT_EN")
	)
	(segment
		(start 244.07368 -166.055548)
		(end 242.90528 -164.887148)
		(width 0.12954)
		(layer "F.Cu")
		(net "GPU_FPGA_BOOT_EN")
	)
	(segment
		(start 164.046916 -437.621934)
		(end 163.90493 -437.479948)
		(width 0.12954)
		(layer "F.Cu")
		(net "GPU_FPGA_BOOT_EN")
	)
	(segment
		(start 164.64788 -437.621934)
		(end 164.046916 -437.621934)
		(width 0.12954)
		(layer "F.Cu")
		(net "GPU_FPGA_BOOT_EN")
	)
	(segment
		(start 163.90493 -438.495948)
		(end 163.90493 -437.479948)
		(width 0.12954)
		(layer "F.Cu")
		(net "GPU_FPGA_BOOT_EN")
	)
	(segment
		(start 186.57316 -166.588948)
		(end 185.0517 -165.067488)
		(width 0.12954)
		(layer "F.Cu")
		(net "GPU_FPGA_BOOT_EN")
	)
	(segment
		(start 242.90528 -161.376868)
		(end 238.94796 -157.419548)
		(width 0.12954)
		(layer "F.Cu")
		(net "GPU_FPGA_BOOT_EN")
	)
	(segment
		(start 238.94796 -157.419548)
		(end 208.1022 -157.419548)
		(width 0.12954)
		(layer "F.Cu")
		(net "GPU_FPGA_BOOT_EN")
	)
	(segment
		(start 182.14848 -165.067488)
		(end 181.66588 -164.584888)
		(width 0.12954)
		(layer "F.Cu")
		(net "GPU_FPGA_BOOT_EN")
	)
	(via
		(at 244.07368 -166.309548)
		(size 0.508)
		(drill 0.254)
		(layers "F.Cu" "B.Cu")
		(net "GPU_FPGA_BOOT_EN")
	)
	(via
		(at 164.64788 -437.621934)
		(size 0.508)
		(drill 0.254)
		(layers "F.Cu" "B.Cu")
		(net "GPU_FPGA_BOOT_EN")
	)
	(via
		(at 156.01188 -116.296948)
		(size 0.508)
		(drill 0.254)
		(layers "F.Cu" "B.Cu")
		(net "GPU_FPGA_BOOT_EN")
	)
	(via
		(at 181.66588 -163.388548)
		(size 0.508)
		(drill 0.254)
		(layers "F.Cu" "B.Cu")
		(net "GPU_FPGA_BOOT_EN")
	)
	(segment
		(start 169.28846 -433.578)
		(end 165.244526 -437.621934)
		(width 0.127)
		(layer "In2.Cu")
		(net "GPU_FPGA_BOOT_EN")
	)
	(segment
		(start 215.627204 -371.56898)
		(end 199.018906 -371.56898)
		(width 0.127)
		(layer "In2.Cu")
		(net "GPU_FPGA_BOOT_EN")
	)
	(segment
		(start 176.64176 -399.469864)
		(end 176.64176 -404.852632)
		(width 0.127)
		(layer "In2.Cu")
		(net "GPU_FPGA_BOOT_EN")
	)
	(segment
		(start 170.13428 -417.54552)
		(end 169.28846 -418.39134)
		(width 0.127)
		(layer "In2.Cu")
		(net "GPU_FPGA_BOOT_EN")
	)
	(segment
		(start 165.244526 -437.621934)
		(end 164.64788 -437.621934)
		(width 0.127)
		(layer "In2.Cu")
		(net "GPU_FPGA_BOOT_EN")
	)
	(segment
		(start 244.07368 -166.309548)
		(end 245.792498 -166.309548)
		(width 0.127)
		(layer "In2.Cu")
		(net "GPU_FPGA_BOOT_EN")
	)
	(segment
		(start 248.02846 -168.54551)
		(end 248.02846 -240.66373)
		(width 0.127)
		(layer "In2.Cu")
		(net "GPU_FPGA_BOOT_EN")
	)
	(segment
		(start 169.28846 -418.39134)
		(end 169.28846 -433.578)
		(width 0.127)
		(layer "In2.Cu")
		(net "GPU_FPGA_BOOT_EN")
	)
	(segment
		(start 176.6316 -415.18332)
		(end 176.07026 -415.74466)
		(width 0.127)
		(layer "In2.Cu")
		(net "GPU_FPGA_BOOT_EN")
	)
	(segment
		(start 224.21088 -362.985304)
		(end 215.627204 -371.56898)
		(width 0.127)
		(layer "In2.Cu")
		(net "GPU_FPGA_BOOT_EN")
	)
	(segment
		(start 177.90668 -396.416022)
		(end 176.64176 -399.469864)
		(width 0.127)
		(layer "In2.Cu")
		(net "GPU_FPGA_BOOT_EN")
	)
	(segment
		(start 199.018906 -371.56898)
		(end 177.90668 -392.681206)
		(width 0.127)
		(layer "In2.Cu")
		(net "GPU_FPGA_BOOT_EN")
	)
	(segment
		(start 171.27474 -417.54552)
		(end 170.13428 -417.54552)
		(width 0.127)
		(layer "In2.Cu")
		(net "GPU_FPGA_BOOT_EN")
	)
	(segment
		(start 248.02846 -240.66373)
		(end 248.3612 -240.99647)
		(width 0.127)
		(layer "In2.Cu")
		(net "GPU_FPGA_BOOT_EN")
	)
	(segment
		(start 176.64176 -404.852632)
		(end 177.68062 -405.891492)
		(width 0.127)
		(layer "In2.Cu")
		(net "GPU_FPGA_BOOT_EN")
	)
	(segment
		(start 248.3612 -321.681094)
		(end 224.21088 -345.831414)
		(width 0.127)
		(layer "In2.Cu")
		(net "GPU_FPGA_BOOT_EN")
	)
	(segment
		(start 177.90668 -392.681206)
		(end 177.90668 -396.416022)
		(width 0.127)
		(layer "In2.Cu")
		(net "GPU_FPGA_BOOT_EN")
	)
	(segment
		(start 224.21088 -345.831414)
		(end 224.21088 -362.985304)
		(width 0.127)
		(layer "In2.Cu")
		(net "GPU_FPGA_BOOT_EN")
	)
	(segment
		(start 177.68062 -405.891492)
		(end 177.68062 -414.90392)
		(width 0.127)
		(layer "In2.Cu")
		(net "GPU_FPGA_BOOT_EN")
	)
	(segment
		(start 176.07026 -415.74466)
		(end 173.0756 -415.74466)
		(width 0.127)
		(layer "In2.Cu")
		(net "GPU_FPGA_BOOT_EN")
	)
	(segment
		(start 248.3612 -240.99647)
		(end 248.3612 -321.681094)
		(width 0.127)
		(layer "In2.Cu")
		(net "GPU_FPGA_BOOT_EN")
	)
	(segment
		(start 177.40122 -415.18332)
		(end 176.6316 -415.18332)
		(width 0.127)
		(layer "In2.Cu")
		(net "GPU_FPGA_BOOT_EN")
	)
	(segment
		(start 173.0756 -415.74466)
		(end 171.27474 -417.54552)
		(width 0.127)
		(layer "In2.Cu")
		(net "GPU_FPGA_BOOT_EN")
	)
	(segment
		(start 177.68062 -414.90392)
		(end 177.40122 -415.18332)
		(width 0.127)
		(layer "In2.Cu")
		(net "GPU_FPGA_BOOT_EN")
	)
	(segment
		(start 245.792498 -166.309548)
		(end 248.02846 -168.54551)
		(width 0.127)
		(layer "In2.Cu")
		(net "GPU_FPGA_BOOT_EN")
	)
	(segment
		(start 178.40071 -165.589966)
		(end 176.02708 -163.216336)
		(width 0.127)
		(layer "In11.Cu")
		(net "GPU_FPGA_BOOT_EN")
	)
	(segment
		(start 176.02708 -163.216336)
		(end 176.02708 -159.755078)
		(width 0.127)
		(layer "In11.Cu")
		(net "GPU_FPGA_BOOT_EN")
	)
	(segment
		(start 180.815996 -165.589966)
		(end 178.40071 -165.589966)
		(width 0.127)
		(layer "In11.Cu")
		(net "GPU_FPGA_BOOT_EN")
	)
	(segment
		(start 181.66588 -163.388548)
		(end 181.66588 -164.740082)
		(width 0.127)
		(layer "In11.Cu")
		(net "GPU_FPGA_BOOT_EN")
	)
	(segment
		(start 156.62148 -116.296948)
		(end 156.01188 -116.296948)
		(width 0.127)
		(layer "In11.Cu")
		(net "GPU_FPGA_BOOT_EN")
	)
	(segment
		(start 157.02788 -116.703348)
		(end 156.62148 -116.296948)
		(width 0.127)
		(layer "In11.Cu")
		(net "GPU_FPGA_BOOT_EN")
	)
	(segment
		(start 176.02708 -159.755078)
		(end 157.02788 -140.755878)
		(width 0.127)
		(layer "In11.Cu")
		(net "GPU_FPGA_BOOT_EN")
	)
	(segment
		(start 157.02788 -140.755878)
		(end 157.02788 -116.703348)
		(width 0.127)
		(layer "In11.Cu")
		(net "GPU_FPGA_BOOT_EN")
	)
	(segment
		(start 181.66588 -164.740082)
		(end 180.815996 -165.589966)
		(width 0.127)
		(layer "In11.Cu")
		(net "GPU_FPGA_BOOT_EN")
	)
	(segment
		(start 174.955708 -111.375444)
		(end 174.555658 -110.975394)
		(width 0.12954)
		(layer "F.Cu")
		(net "GPU_BASE_STBY_EN_R")
	)
	(via
		(at 158.90748 -112.486948)
		(size 0.508)
		(drill 0.254)
		(layers "F.Cu" "B.Cu")
		(net "GPU_BASE_STBY_EN_R")
	)
	(via
		(at 174.555658 -110.975394)
		(size 0.4572)
		(drill 0.254)
		(layers "F.Cu" "B.Cu")
		(net "GPU_BASE_STBY_EN_R")
	)
	(segment
		(start 157.42793 -112.163098)
		(end 157.42793 -112.486948)
		(width 0.12954)
		(layer "B.Cu")
		(net "GPU_BASE_STBY_EN_R")
	)
	(segment
		(start 158.39948 -111.978948)
		(end 157.61208 -111.978948)
		(width 0.12954)
		(layer "B.Cu")
		(net "GPU_BASE_STBY_EN_R")
	)
	(segment
		(start 158.90748 -112.486948)
		(end 158.39948 -111.978948)
		(width 0.12954)
		(layer "B.Cu")
		(net "GPU_BASE_STBY_EN_R")
	)
	(segment
		(start 157.61208 -111.978948)
		(end 157.42793 -112.163098)
		(width 0.12954)
		(layer "B.Cu")
		(net "GPU_BASE_STBY_EN_R")
	)
	(segment
		(start 161.10712 -111.953548)
		(end 159.44088 -111.953548)
		(width 0.127)
		(layer "In15.Cu")
		(net "GPU_BASE_STBY_EN_R")
	)
	(segment
		(start 161.83102 -112.677448)
		(end 161.10712 -111.953548)
		(width 0.127)
		(layer "In15.Cu")
		(net "GPU_BASE_STBY_EN_R")
	)
	(segment
		(start 170.15206 -110.752128)
		(end 170.15206 -111.199168)
		(width 0.127)
		(layer "In15.Cu")
		(net "GPU_BASE_STBY_EN_R")
	)
	(segment
		(start 166.105078 -111.36884)
		(end 164.79647 -112.677448)
		(width 0.127)
		(layer "In15.Cu")
		(net "GPU_BASE_STBY_EN_R")
	)
	(segment
		(start 159.44088 -111.953548)
		(end 158.90748 -112.486948)
		(width 0.127)
		(layer "In15.Cu")
		(net "GPU_BASE_STBY_EN_R")
	)
	(segment
		(start 174.152052 -110.571788)
		(end 170.3324 -110.571788)
		(width 0.127)
		(layer "In15.Cu")
		(net "GPU_BASE_STBY_EN_R")
	)
	(segment
		(start 164.79647 -112.677448)
		(end 161.83102 -112.677448)
		(width 0.127)
		(layer "In15.Cu")
		(net "GPU_BASE_STBY_EN_R")
	)
	(segment
		(start 170.15206 -111.199168)
		(end 169.982388 -111.36884)
		(width 0.127)
		(layer "In15.Cu")
		(net "GPU_BASE_STBY_EN_R")
	)
	(segment
		(start 170.3324 -110.571788)
		(end 170.15206 -110.752128)
		(width 0.127)
		(layer "In15.Cu")
		(net "GPU_BASE_STBY_EN_R")
	)
	(segment
		(start 169.982388 -111.36884)
		(end 166.105078 -111.36884)
		(width 0.127)
		(layer "In15.Cu")
		(net "GPU_BASE_STBY_EN_R")
	)
	(segment
		(start 174.555658 -110.975394)
		(end 174.152052 -110.571788)
		(width 0.127)
		(layer "In15.Cu")
		(net "GPU_BASE_STBY_EN_R")
	)
	(segment
		(start 168.58488 -435.701948)
		(end 169.161206 -435.701948)
		(width 0.12954)
		(layer "F.Cu")
		(net "GPU_BASE_STBY_EN_BUF_R")
	)
	(segment
		(start 169.161206 -435.701948)
		(end 169.415206 -435.955948)
		(width 0.12954)
		(layer "F.Cu")
		(net "GPU_BASE_STBY_EN_BUF_R")
	)
	(segment
		(start 167.995854 -435.701948)
		(end 168.58488 -435.701948)
		(width 0.12954)
		(layer "F.Cu")
		(net "GPU_BASE_STBY_EN_BUF_R")
	)
	(segment
		(start 169.83583 -434.939948)
		(end 169.83583 -433.923948)
		(width 0.12954)
		(layer "F.Cu")
		(net "GPU_BASE_STBY_EN_BUF_R")
	)
	(segment
		(start 169.83583 -435.955948)
		(end 169.83583 -434.939948)
		(width 0.12954)
		(layer "F.Cu")
		(net "GPU_BASE_STBY_EN_BUF_R")
	)
	(segment
		(start 167.37584 -436.321962)
		(end 167.995854 -435.701948)
		(width 0.12954)
		(layer "F.Cu")
		(net "GPU_BASE_STBY_EN_BUF_R")
	)
	(segment
		(start 169.415206 -435.955948)
		(end 169.83583 -435.955948)
		(width 0.12954)
		(layer "F.Cu")
		(net "GPU_BASE_STBY_EN_BUF_R")
	)
	(via
		(at 168.58488 -435.701948)
		(size 0.762)
		(drill 0.381)
		(layers "F.Cu" "B.Cu")
		(net "GPU_BASE_STBY_EN_BUF_R")
	)
	(segment
		(start 170.63593 -437.168798)
		(end 170.63593 -435.955948)
		(width 0.12954)
		(layer "F.Cu")
		(net "GPU_BASE_STBY_EN_BUF")
	)
	(segment
		(start 170.75658 -437.289448)
		(end 170.63593 -437.168798)
		(width 0.12954)
		(layer "F.Cu")
		(net "GPU_BASE_STBY_EN_BUF")
	)
	(via
		(at 170.75658 -437.289448)
		(size 0.508)
		(drill 0.254)
		(layers "F.Cu" "B.Cu")
		(net "GPU_BASE_STBY_EN_BUF")
	)
	(segment
		(start 138.96848 -439.27141)
		(end 138.96848 -424.101768)
		(width 0.127)
		(layer "In2.Cu")
		(net "GPU_BASE_STBY_EN_BUF")
	)
	(segment
		(start 162.13328 -428.27448)
		(end 162.13328 -434.304948)
		(width 0.127)
		(layer "In2.Cu")
		(net "GPU_BASE_STBY_EN_BUF")
	)
	(segment
		(start 138.96848 -424.101768)
		(end 141.32687 -421.743378)
		(width 0.127)
		(layer "In2.Cu")
		(net "GPU_BASE_STBY_EN_BUF")
	)
	(segment
		(start 162.951668 -427.456092)
		(end 162.13328 -428.27448)
		(width 0.127)
		(layer "In2.Cu")
		(net "GPU_BASE_STBY_EN_BUF")
	)
	(segment
		(start 169.70248 -438.749948)
		(end 170.75658 -437.695848)
		(width 0.127)
		(layer "In2.Cu")
		(net "GPU_BASE_STBY_EN_BUF")
	)
	(segment
		(start 170.75658 -437.695848)
		(end 170.75658 -437.289448)
		(width 0.127)
		(layer "In2.Cu")
		(net "GPU_BASE_STBY_EN_BUF")
	)
	(segment
		(start 137.750042 -440.489848)
		(end 138.96848 -439.27141)
		(width 0.127)
		(layer "In2.Cu")
		(net "GPU_BASE_STBY_EN_BUF")
	)
	(segment
		(start 162.951668 -425.008294)
		(end 162.951668 -427.456092)
		(width 0.127)
		(layer "In2.Cu")
		(net "GPU_BASE_STBY_EN_BUF")
	)
	(segment
		(start 158.215838 -421.743378)
		(end 161.14776 -424.6753)
		(width 0.127)
		(layer "In2.Cu")
		(net "GPU_BASE_STBY_EN_BUF")
	)
	(segment
		(start 163.27628 -435.447948)
		(end 163.27628 -437.987948)
		(width 0.127)
		(layer "In2.Cu")
		(net "GPU_BASE_STBY_EN_BUF")
	)
	(segment
		(start 162.618674 -424.6753)
		(end 162.951668 -425.008294)
		(width 0.127)
		(layer "In2.Cu")
		(net "GPU_BASE_STBY_EN_BUF")
	)
	(segment
		(start 162.13328 -434.304948)
		(end 163.27628 -435.447948)
		(width 0.127)
		(layer "In2.Cu")
		(net "GPU_BASE_STBY_EN_BUF")
	)
	(segment
		(start 161.14776 -424.6753)
		(end 162.618674 -424.6753)
		(width 0.127)
		(layer "In2.Cu")
		(net "GPU_BASE_STBY_EN_BUF")
	)
	(segment
		(start 163.27628 -437.987948)
		(end 164.03828 -438.749948)
		(width 0.127)
		(layer "In2.Cu")
		(net "GPU_BASE_STBY_EN_BUF")
	)
	(segment
		(start 164.03828 -438.749948)
		(end 169.70248 -438.749948)
		(width 0.127)
		(layer "In2.Cu")
		(net "GPU_BASE_STBY_EN_BUF")
	)
	(segment
		(start 141.32687 -421.743378)
		(end 158.215838 -421.743378)
		(width 0.127)
		(layer "In2.Cu")
		(net "GPU_BASE_STBY_EN_BUF")
	)
	(segment
		(start 165.249606 -436.095648)
		(end 164.64788 -436.095648)
		(width 0.12954)
		(layer "F.Cu")
		(net "GPU_BASE_STBY_EN")
	)
	(segment
		(start 164.64788 -436.095648)
		(end 164.27958 -436.463948)
		(width 0.12954)
		(layer "F.Cu")
		(net "GPU_BASE_STBY_EN")
	)
	(segment
		(start 163.90493 -435.447948)
		(end 163.90493 -436.463948)
		(width 0.12954)
		(layer "F.Cu")
		(net "GPU_BASE_STBY_EN")
	)
	(segment
		(start 165.47592 -436.321962)
		(end 165.249606 -436.095648)
		(width 0.12954)
		(layer "F.Cu")
		(net "GPU_BASE_STBY_EN")
	)
	(segment
		(start 164.27958 -436.463948)
		(end 163.90493 -436.463948)
		(width 0.12954)
		(layer "F.Cu")
		(net "GPU_BASE_STBY_EN")
	)
	(via
		(at 155.12288 -112.486948)
		(size 0.508)
		(drill 0.254)
		(layers "F.Cu" "B.Cu")
		(net "GPU_BASE_STBY_EN")
	)
	(via
		(at 164.64788 -436.095648)
		(size 0.508)
		(drill 0.254)
		(layers "F.Cu" "B.Cu")
		(net "GPU_BASE_STBY_EN")
	)
	(via
		(at 250.550172 -134.624826)
		(size 0.508)
		(drill 0.254)
		(layers "F.Cu" "B.Cu")
		(net "GPU_BASE_STBY_EN")
	)
	(via
		(at 155.12288 -139.918948)
		(size 0.508)
		(drill 0.254)
		(layers "F.Cu" "B.Cu")
		(net "GPU_BASE_STBY_EN")
	)
	(via
		(at 247.8786 -321.325748)
		(size 0.508)
		(drill 0.254)
		(layers "F.Cu" "B.Cu")
		(net "GPU_BASE_STBY_EN")
	)
	(segment
		(start 155.30068 -111.953548)
		(end 156.44368 -111.953548)
		(width 0.12954)
		(layer "B.Cu")
		(net "GPU_BASE_STBY_EN")
	)
	(segment
		(start 155.12288 -112.131348)
		(end 155.30068 -111.953548)
		(width 0.12954)
		(layer "B.Cu")
		(net "GPU_BASE_STBY_EN")
	)
	(segment
		(start 156.62783 -112.137698)
		(end 156.62783 -112.486948)
		(width 0.12954)
		(layer "B.Cu")
		(net "GPU_BASE_STBY_EN")
	)
	(segment
		(start 156.44368 -111.953548)
		(end 156.62783 -112.137698)
		(width 0.12954)
		(layer "B.Cu")
		(net "GPU_BASE_STBY_EN")
	)
	(segment
		(start 155.12288 -112.486948)
		(end 155.12288 -112.131348)
		(width 0.12954)
		(layer "B.Cu")
		(net "GPU_BASE_STBY_EN")
	)
	(segment
		(start 173.21276 -414.68802)
		(end 175.99152 -414.68802)
		(width 0.127)
		(layer "In2.Cu")
		(net "GPU_BASE_STBY_EN")
	)
	(segment
		(start 198.882 -371.23878)
		(end 215.490298 -371.23878)
		(width 0.127)
		(layer "In2.Cu")
		(net "GPU_BASE_STBY_EN")
	)
	(segment
		(start 168.95826 -418.254434)
		(end 169.997374 -417.21532)
		(width 0.127)
		(layer "In2.Cu")
		(net "GPU_BASE_STBY_EN")
	)
	(segment
		(start 223.82988 -362.899198)
		(end 223.82988 -345.374468)
		(width 0.127)
		(layer "In2.Cu")
		(net "GPU_BASE_STBY_EN")
	)
	(segment
		(start 171.7294 -416.623754)
		(end 171.7294 -416.17138)
		(width 0.127)
		(layer "In2.Cu")
		(net "GPU_BASE_STBY_EN")
	)
	(segment
		(start 164.64788 -436.095648)
		(end 166.303706 -436.095648)
		(width 0.127)
		(layer "In2.Cu")
		(net "GPU_BASE_STBY_EN")
	)
	(segment
		(start 176.31156 -404.989538)
		(end 176.31156 -399.403824)
		(width 0.127)
		(layer "In2.Cu")
		(net "GPU_BASE_STBY_EN")
	)
	(segment
		(start 169.997374 -417.21532)
		(end 171.137834 -417.21532)
		(width 0.127)
		(layer "In2.Cu")
		(net "GPU_BASE_STBY_EN")
	)
	(segment
		(start 175.99152 -414.68802)
		(end 177.35042 -413.32912)
		(width 0.127)
		(layer "In2.Cu")
		(net "GPU_BASE_STBY_EN")
	)
	(segment
		(start 177.35042 -406.028398)
		(end 176.31156 -404.989538)
		(width 0.127)
		(layer "In2.Cu")
		(net "GPU_BASE_STBY_EN")
	)
	(segment
		(start 166.303706 -436.095648)
		(end 168.95826 -433.441094)
		(width 0.127)
		(layer "In2.Cu")
		(net "GPU_BASE_STBY_EN")
	)
	(segment
		(start 177.35042 -413.32912)
		(end 177.35042 -406.028398)
		(width 0.127)
		(layer "In2.Cu")
		(net "GPU_BASE_STBY_EN")
	)
	(segment
		(start 168.95826 -433.441094)
		(end 168.95826 -418.254434)
		(width 0.127)
		(layer "In2.Cu")
		(net "GPU_BASE_STBY_EN")
	)
	(segment
		(start 171.137834 -417.21532)
		(end 171.7294 -416.623754)
		(width 0.127)
		(layer "In2.Cu")
		(net "GPU_BASE_STBY_EN")
	)
	(segment
		(start 176.31156 -399.403824)
		(end 177.5587 -396.392654)
		(width 0.127)
		(layer "In2.Cu")
		(net "GPU_BASE_STBY_EN")
	)
	(segment
		(start 223.82988 -345.374468)
		(end 247.8786 -321.325748)
		(width 0.127)
		(layer "In2.Cu")
		(net "GPU_BASE_STBY_EN")
	)
	(segment
		(start 215.490298 -371.23878)
		(end 223.82988 -362.899198)
		(width 0.127)
		(layer "In2.Cu")
		(net "GPU_BASE_STBY_EN")
	)
	(segment
		(start 177.5587 -396.392654)
		(end 177.5587 -392.56208)
		(width 0.127)
		(layer "In2.Cu")
		(net "GPU_BASE_STBY_EN")
	)
	(segment
		(start 171.7294 -416.17138)
		(end 173.21276 -414.68802)
		(width 0.127)
		(layer "In2.Cu")
		(net "GPU_BASE_STBY_EN")
	)
	(segment
		(start 177.5587 -392.56208)
		(end 198.882 -371.23878)
		(width 0.127)
		(layer "In2.Cu")
		(net "GPU_BASE_STBY_EN")
	)
	(segment
		(start 248.5136 -321.325748)
		(end 247.8786 -321.325748)
		(width 0.127)
		(layer "In11.Cu")
		(net "GPU_BASE_STBY_EN")
	)
	(segment
		(start 153.34488 -129.504948)
		(end 153.34488 -138.140948)
		(width 0.127)
		(layer "In11.Cu")
		(net "GPU_BASE_STBY_EN")
	)
	(segment
		(start 155.12288 -112.486948)
		(end 154.65298 -112.956848)
		(width 0.127)
		(layer "In11.Cu")
		(net "GPU_BASE_STBY_EN")
	)
	(segment
		(start 249.30608 -202.192128)
		(end 249.30608 -320.533268)
		(width 0.127)
		(layer "In11.Cu")
		(net "GPU_BASE_STBY_EN")
	)
	(segment
		(start 249.30608 -320.533268)
		(end 248.5136 -321.325748)
		(width 0.127)
		(layer "In11.Cu")
		(net "GPU_BASE_STBY_EN")
	)
	(segment
		(start 247.45188 -137.723118)
		(end 247.45188 -200.337928)
		(width 0.127)
		(layer "In11.Cu")
		(net "GPU_BASE_STBY_EN")
	)
	(segment
		(start 154.65298 -112.956848)
		(end 154.65298 -128.196848)
		(width 0.127)
		(layer "In11.Cu")
		(net "GPU_BASE_STBY_EN")
	)
	(segment
		(start 247.45188 -200.337928)
		(end 249.30608 -202.192128)
		(width 0.127)
		(layer "In11.Cu")
		(net "GPU_BASE_STBY_EN")
	)
	(segment
		(start 153.34488 -138.140948)
		(end 155.12288 -139.918948)
		(width 0.127)
		(layer "In11.Cu")
		(net "GPU_BASE_STBY_EN")
	)
	(segment
		(start 154.65298 -128.196848)
		(end 153.34488 -129.504948)
		(width 0.127)
		(layer "In11.Cu")
		(net "GPU_BASE_STBY_EN")
	)
	(segment
		(start 250.550172 -134.624826)
		(end 247.45188 -137.723118)
		(width 0.127)
		(layer "In11.Cu")
		(net "GPU_BASE_STBY_EN")
	)
	(segment
		(start 211.66328 -141.493748)
		(end 156.69768 -141.493748)
		(width 0.127)
		(layer "In15.Cu")
		(net "GPU_BASE_STBY_EN")
	)
	(segment
		(start 250.550172 -134.624826)
		(end 251.023882 -135.098536)
		(width 0.127)
		(layer "In15.Cu")
		(net "GPU_BASE_STBY_EN")
	)
	(segment
		(start 156.69768 -141.493748)
		(end 155.12288 -139.918948)
		(width 0.127)
		(layer "In15.Cu")
		(net "GPU_BASE_STBY_EN")
	)
	(segment
		(start 214.140796 -139.016232)
		(end 211.66328 -141.493748)
		(width 0.127)
		(layer "In15.Cu")
		(net "GPU_BASE_STBY_EN")
	)
	(segment
		(start 251.023882 -135.098536)
		(end 251.023882 -135.608568)
		(width 0.127)
		(layer "In15.Cu")
		(net "GPU_BASE_STBY_EN")
	)
	(segment
		(start 247.616218 -139.016232)
		(end 214.140796 -139.016232)
		(width 0.127)
		(layer "In15.Cu")
		(net "GPU_BASE_STBY_EN")
	)
	(segment
		(start 251.023882 -135.608568)
		(end 247.616218 -139.016232)
		(width 0.127)
		(layer "In15.Cu")
		(net "GPU_BASE_STBY_EN")
	)
	(segment
		(start 18.940018 -421.022272)
		(end 19.896582 -421.978836)
		(width 0.12954)
		(layer "F.Cu")
		(net "GPU_BASE_ID1_R")
	)
	(segment
		(start 19.896582 -421.978836)
		(end 19.896582 -423.102786)
		(width 0.12954)
		(layer "F.Cu")
		(net "GPU_BASE_ID1_R")
	)
	(segment
		(start 19.896582 -423.102786)
		(end 19.769582 -423.229786)
		(width 0.12954)
		(layer "F.Cu")
		(net "GPU_BASE_ID1_R")
	)
	(segment
		(start 18.940018 -420.12743)
		(end 18.940018 -421.022272)
		(width 0.12954)
		(layer "F.Cu")
		(net "GPU_BASE_ID1_R")
	)
	(via
		(at 19.896582 -421.978836)
		(size 0.762)
		(drill 0.381)
		(layers "F.Cu" "B.Cu")
		(net "GPU_BASE_ID1_R")
	)
	(segment
		(start 19.769582 -427.623986)
		(end 19.769582 -426.441108)
		(width 0.12954)
		(layer "F.Cu")
		(net "GPU_BASE_ID1")
	)
	(segment
		(start 19.769582 -426.441108)
		(end 19.769582 -424.029886)
		(width 0.12954)
		(layer "F.Cu")
		(net "GPU_BASE_ID1")
	)
	(via
		(at 94.14129 -425.65828)
		(size 0.508)
		(drill 0.254)
		(layers "F.Cu" "B.Cu")
		(net "GPU_BASE_ID1")
	)
	(via
		(at 19.769582 -426.441108)
		(size 0.762)
		(drill 0.254)
		(layers "F.Cu" "B.Cu")
		(net "GPU_BASE_ID1")
	)
	(segment
		(start 95.10522 -424.815508)
		(end 97.16516 -424.815508)
		(width 0.127)
		(layer "In6.Cu")
		(net "GPU_BASE_ID1")
	)
	(segment
		(start 26.68778 -418.755068)
		(end 26.68778 -423.118788)
		(width 0.127)
		(layer "In6.Cu")
		(net "GPU_BASE_ID1")
	)
	(segment
		(start 18.67408 -424.376088)
		(end 18.20926 -424.840908)
		(width 0.127)
		(layer "In6.Cu")
		(net "GPU_BASE_ID1")
	)
	(segment
		(start 25.43048 -424.376088)
		(end 18.67408 -424.376088)
		(width 0.127)
		(layer "In6.Cu")
		(net "GPU_BASE_ID1")
	)
	(segment
		(start 26.68778 -423.118788)
		(end 25.43048 -424.376088)
		(width 0.127)
		(layer "In6.Cu")
		(net "GPU_BASE_ID1")
	)
	(segment
		(start 38.30574 -405.089868)
		(end 33.86836 -409.527248)
		(width 0.127)
		(layer "In6.Cu")
		(net "GPU_BASE_ID1")
	)
	(segment
		(start 18.9865 -426.441108)
		(end 19.769582 -426.441108)
		(width 0.127)
		(layer "In6.Cu")
		(net "GPU_BASE_ID1")
	)
	(segment
		(start 101.48316 -409.70962)
		(end 96.863408 -405.089868)
		(width 0.127)
		(layer "In6.Cu")
		(net "GPU_BASE_ID1")
	)
	(segment
		(start 103.22814 -418.752528)
		(end 103.22814 -414.454848)
		(width 0.127)
		(layer "In6.Cu")
		(net "GPU_BASE_ID1")
	)
	(segment
		(start 103.22814 -414.454848)
		(end 101.48316 -412.709868)
		(width 0.127)
		(layer "In6.Cu")
		(net "GPU_BASE_ID1")
	)
	(segment
		(start 96.863408 -405.089868)
		(end 38.30574 -405.089868)
		(width 0.127)
		(layer "In6.Cu")
		(net "GPU_BASE_ID1")
	)
	(segment
		(start 101.48316 -412.709868)
		(end 101.48316 -409.70962)
		(width 0.127)
		(layer "In6.Cu")
		(net "GPU_BASE_ID1")
	)
	(segment
		(start 24.43226 -416.499548)
		(end 26.68778 -418.755068)
		(width 0.127)
		(layer "In6.Cu")
		(net "GPU_BASE_ID1")
	)
	(segment
		(start 24.43226 -412.473648)
		(end 24.43226 -416.499548)
		(width 0.127)
		(layer "In6.Cu")
		(net "GPU_BASE_ID1")
	)
	(segment
		(start 33.86836 -409.527248)
		(end 27.37866 -409.527248)
		(width 0.127)
		(layer "In6.Cu")
		(net "GPU_BASE_ID1")
	)
	(segment
		(start 27.37866 -409.527248)
		(end 24.43226 -412.473648)
		(width 0.127)
		(layer "In6.Cu")
		(net "GPU_BASE_ID1")
	)
	(segment
		(start 94.262448 -425.65828)
		(end 95.10522 -424.815508)
		(width 0.127)
		(layer "In6.Cu")
		(net "GPU_BASE_ID1")
	)
	(segment
		(start 97.16516 -424.815508)
		(end 103.22814 -418.752528)
		(width 0.127)
		(layer "In6.Cu")
		(net "GPU_BASE_ID1")
	)
	(segment
		(start 18.20926 -425.663868)
		(end 18.9865 -426.441108)
		(width 0.127)
		(layer "In6.Cu")
		(net "GPU_BASE_ID1")
	)
	(segment
		(start 94.14129 -425.65828)
		(end 94.262448 -425.65828)
		(width 0.127)
		(layer "In6.Cu")
		(net "GPU_BASE_ID1")
	)
	(segment
		(start 18.20926 -424.840908)
		(end 18.20926 -425.663868)
		(width 0.127)
		(layer "In6.Cu")
		(net "GPU_BASE_ID1")
	)
	(segment
		(start 93.172788 -424.689778)
		(end 94.14129 -425.65828)
		(width 0.127)
		(layer "In15.Cu")
		(net "GPU_BASE_ID1")
	)
	(segment
		(start 89.650062 -424.689778)
		(end 93.172788 -424.689778)
		(width 0.127)
		(layer "In15.Cu")
		(net "GPU_BASE_ID1")
	)
	(segment
		(start 19.590004 -420.793672)
		(end 20.4597 -421.663368)
		(width 0.12954)
		(layer "F.Cu")
		(net "GPU_BASE_ID0_R")
	)
	(segment
		(start 20.881594 -421.663368)
		(end 21.166582 -421.948356)
		(width 0.12954)
		(layer "F.Cu")
		(net "GPU_BASE_ID0_R")
	)
	(segment
		(start 21.166582 -422.848786)
		(end 20.785582 -423.229786)
		(width 0.12954)
		(layer "F.Cu")
		(net "GPU_BASE_ID0_R")
	)
	(segment
		(start 21.166582 -421.948356)
		(end 21.166582 -422.848786)
		(width 0.12954)
		(layer "F.Cu")
		(net "GPU_BASE_ID0_R")
	)
	(segment
		(start 19.590004 -420.12743)
		(end 19.590004 -420.793672)
		(width 0.12954)
		(layer "F.Cu")
		(net "GPU_BASE_ID0_R")
	)
	(segment
		(start 20.4597 -421.663368)
		(end 20.881594 -421.663368)
		(width 0.12954)
		(layer "F.Cu")
		(net "GPU_BASE_ID0_R")
	)
	(via
		(at 21.166582 -421.948356)
		(size 0.762)
		(drill 0.381)
		(layers "F.Cu" "B.Cu")
		(net "GPU_BASE_ID0_R")
	)
	(segment
		(start 20.785582 -425.329604)
		(end 20.785582 -424.029886)
		(width 0.12954)
		(layer "F.Cu")
		(net "GPU_BASE_ID0")
	)
	(segment
		(start 20.785582 -427.623986)
		(end 20.785582 -425.329604)
		(width 0.12954)
		(layer "F.Cu")
		(net "GPU_BASE_ID0")
	)
	(via
		(at 94.107 -420.207948)
		(size 0.508)
		(drill 0.254)
		(layers "F.Cu" "B.Cu")
		(net "GPU_BASE_ID0")
	)
	(via
		(at 20.785582 -425.329604)
		(size 0.762)
		(drill 0.254)
		(layers "F.Cu" "B.Cu")
		(net "GPU_BASE_ID0")
	)
	(segment
		(start 96.95688 -408.849068)
		(end 38.462204 -408.849068)
		(width 0.127)
		(layer "In6.Cu")
		(net "GPU_BASE_ID0")
	)
	(segment
		(start 30.67304 -413.598868)
		(end 28.49372 -415.778188)
		(width 0.127)
		(layer "In6.Cu")
		(net "GPU_BASE_ID0")
	)
	(segment
		(start 24.86914 -426.804328)
		(end 21.721318 -426.804328)
		(width 0.127)
		(layer "In6.Cu")
		(net "GPU_BASE_ID0")
	)
	(segment
		(start 28.49372 -415.778188)
		(end 28.49372 -423.179748)
		(width 0.127)
		(layer "In6.Cu")
		(net "GPU_BASE_ID0")
	)
	(segment
		(start 93.79204 -417.632642)
		(end 98.26498 -413.159702)
		(width 0.127)
		(layer "In6.Cu")
		(net "GPU_BASE_ID0")
	)
	(segment
		(start 33.712404 -413.598868)
		(end 30.67304 -413.598868)
		(width 0.127)
		(layer "In6.Cu")
		(net "GPU_BASE_ID0")
	)
	(segment
		(start 97.08388 -408.976068)
		(end 96.95688 -408.849068)
		(width 0.127)
		(layer "In6.Cu")
		(net "GPU_BASE_ID0")
	)
	(segment
		(start 97.08388 -409.589732)
		(end 97.08388 -408.976068)
		(width 0.127)
		(layer "In6.Cu")
		(net "GPU_BASE_ID0")
	)
	(segment
		(start 20.785582 -425.868592)
		(end 20.785582 -425.329604)
		(width 0.127)
		(layer "In6.Cu")
		(net "GPU_BASE_ID0")
	)
	(segment
		(start 98.26498 -413.159702)
		(end 98.26498 -410.770832)
		(width 0.127)
		(layer "In6.Cu")
		(net "GPU_BASE_ID0")
	)
	(segment
		(start 38.462204 -408.849068)
		(end 33.712404 -413.598868)
		(width 0.127)
		(layer "In6.Cu")
		(net "GPU_BASE_ID0")
	)
	(segment
		(start 28.49372 -423.179748)
		(end 24.86914 -426.804328)
		(width 0.127)
		(layer "In6.Cu")
		(net "GPU_BASE_ID0")
	)
	(segment
		(start 94.107 -420.207948)
		(end 93.79204 -419.892988)
		(width 0.127)
		(layer "In6.Cu")
		(net "GPU_BASE_ID0")
	)
	(segment
		(start 21.721318 -426.804328)
		(end 20.785582 -425.868592)
		(width 0.127)
		(layer "In6.Cu")
		(net "GPU_BASE_ID0")
	)
	(segment
		(start 93.79204 -419.892988)
		(end 93.79204 -417.632642)
		(width 0.127)
		(layer "In6.Cu")
		(net "GPU_BASE_ID0")
	)
	(segment
		(start 98.26498 -410.770832)
		(end 97.08388 -409.589732)
		(width 0.127)
		(layer "In6.Cu")
		(net "GPU_BASE_ID0")
	)
	(segment
		(start 80.76184 -422.999408)
		(end 80.76184 -439.534808)
		(width 0.127)
		(layer "In15.Cu")
		(net "GPU_BASE_ID0")
	)
	(segment
		(start 83.5533 -420.207948)
		(end 80.76184 -422.999408)
		(width 0.127)
		(layer "In15.Cu")
		(net "GPU_BASE_ID0")
	)
	(segment
		(start 80.76184 -439.534808)
		(end 79.8068 -440.489848)
		(width 0.127)
		(layer "In15.Cu")
		(net "GPU_BASE_ID0")
	)
	(segment
		(start 79.8068 -440.489848)
		(end 79.650082 -440.489848)
		(width 0.127)
		(layer "In15.Cu")
		(net "GPU_BASE_ID0")
	)
	(segment
		(start 94.107 -420.207948)
		(end 83.5533 -420.207948)
		(width 0.127)
		(layer "In15.Cu")
		(net "GPU_BASE_ID0")
	)
	(segment
		(start 174.403512 -420.324534)
		(end 174.060612 -420.324534)
		(width 0.12954)
		(layer "F.Cu")
		(net "GPU_BASE_HMC_READY_N")
	)
	(segment
		(start 173.903132 -420.840154)
		(end 174.037498 -420.97452)
		(width 0.12954)
		(layer "F.Cu")
		(net "GPU_BASE_HMC_READY_N")
	)
	(segment
		(start 175.664622 -420.108888)
		(end 176.480978 -419.292532)
		(width 0.12954)
		(layer "F.Cu")
		(net "GPU_BASE_HMC_READY_N")
	)
	(segment
		(start 176.480978 -419.292532)
		(end 176.480978 -418.806122)
		(width 0.12954)
		(layer "F.Cu")
		(net "GPU_BASE_HMC_READY_N")
	)
	(segment
		(start 174.060612 -420.324534)
		(end 173.903132 -420.482014)
		(width 0.12954)
		(layer "F.Cu")
		(net "GPU_BASE_HMC_READY_N")
	)
	(segment
		(start 174.403512 -420.324534)
		(end 175.448976 -420.324534)
		(width 0.12954)
		(layer "F.Cu")
		(net "GPU_BASE_HMC_READY_N")
	)
	(segment
		(start 174.037498 -420.97452)
		(end 174.403512 -420.97452)
		(width 0.12954)
		(layer "F.Cu")
		(net "GPU_BASE_HMC_READY_N")
	)
	(segment
		(start 175.448976 -420.324534)
		(end 175.664622 -420.108888)
		(width 0.12954)
		(layer "F.Cu")
		(net "GPU_BASE_HMC_READY_N")
	)
	(segment
		(start 173.903132 -420.482014)
		(end 173.903132 -420.840154)
		(width 0.12954)
		(layer "F.Cu")
		(net "GPU_BASE_HMC_READY_N")
	)
	(via
		(at 175.664622 -420.108888)
		(size 0.762)
		(drill 0.381)
		(layers "F.Cu" "B.Cu")
		(net "GPU_BASE_HMC_READY_N")
	)
	(segment
		(start 174.155608 -112.175544)
		(end 173.755558 -111.775494)
		(width 0.12954)
		(layer "F.Cu")
		(net "GPU_BASE_HMC_READY_ISO_R")
	)
	(via
		(at 173.755558 -111.775494)
		(size 0.4572)
		(drill 0.254)
		(layers "F.Cu" "B.Cu")
		(net "GPU_BASE_HMC_READY_ISO_R")
	)
	(via
		(at 158.90748 -116.296948)
		(size 0.508)
		(drill 0.254)
		(layers "F.Cu" "B.Cu")
		(net "GPU_BASE_HMC_READY_ISO_R")
	)
	(segment
		(start 158.90748 -115.966748)
		(end 158.72968 -115.788948)
		(width 0.12954)
		(layer "B.Cu")
		(net "GPU_BASE_HMC_READY_ISO_R")
	)
	(segment
		(start 157.42793 -115.973098)
		(end 157.42793 -116.296948)
		(width 0.12954)
		(layer "B.Cu")
		(net "GPU_BASE_HMC_READY_ISO_R")
	)
	(segment
		(start 158.72968 -115.788948)
		(end 157.61208 -115.788948)
		(width 0.12954)
		(layer "B.Cu")
		(net "GPU_BASE_HMC_READY_ISO_R")
	)
	(segment
		(start 158.90748 -116.296948)
		(end 158.90748 -115.966748)
		(width 0.12954)
		(layer "B.Cu")
		(net "GPU_BASE_HMC_READY_ISO_R")
	)
	(segment
		(start 157.61208 -115.788948)
		(end 157.42793 -115.973098)
		(width 0.12954)
		(layer "B.Cu")
		(net "GPU_BASE_HMC_READY_ISO_R")
	)
	(segment
		(start 173.157388 -112.9792)
		(end 173.36008 -112.776508)
		(width 0.127)
		(layer "In15.Cu")
		(net "GPU_BASE_HMC_READY_ISO_R")
	)
	(segment
		(start 158.90748 -116.296948)
		(end 159.56534 -115.639088)
		(width 0.127)
		(layer "In15.Cu")
		(net "GPU_BASE_HMC_READY_ISO_R")
	)
	(segment
		(start 173.36008 -112.776508)
		(end 173.36008 -112.170972)
		(width 0.127)
		(layer "In15.Cu")
		(net "GPU_BASE_HMC_READY_ISO_R")
	)
	(segment
		(start 166.492428 -112.9792)
		(end 173.157388 -112.9792)
		(width 0.127)
		(layer "In15.Cu")
		(net "GPU_BASE_HMC_READY_ISO_R")
	)
	(segment
		(start 173.36008 -112.170972)
		(end 173.755558 -111.775494)
		(width 0.127)
		(layer "In15.Cu")
		(net "GPU_BASE_HMC_READY_ISO_R")
	)
	(segment
		(start 159.56534 -115.639088)
		(end 163.83254 -115.639088)
		(width 0.127)
		(layer "In15.Cu")
		(net "GPU_BASE_HMC_READY_ISO_R")
	)
	(segment
		(start 163.83254 -115.639088)
		(end 166.492428 -112.9792)
		(width 0.127)
		(layer "In15.Cu")
		(net "GPU_BASE_HMC_READY_ISO_R")
	)
	(segment
		(start 171.943522 -419.114478)
		(end 171.04868 -419.114478)
		(width 0.12954)
		(layer "F.Cu")
		(net "GPU_BASE_HMC_READY_ISO")
	)
	(segment
		(start 239.158526 -156.911548)
		(end 207.891634 -156.911548)
		(width 0.12954)
		(layer "F.Cu")
		(net "GPU_BASE_HMC_READY_ISO")
	)
	(segment
		(start 190.001398 -166.080948)
		(end 186.73826 -166.080948)
		(width 0.12954)
		(layer "F.Cu")
		(net "GPU_BASE_HMC_READY_ISO")
	)
	(segment
		(start 185.25236 -164.595048)
		(end 183.7563 -164.595048)
		(width 0.12954)
		(layer "F.Cu")
		(net "GPU_BASE_HMC_READY_ISO")
	)
	(segment
		(start 170.193462 -418.479478)
		(end 170.50766 -418.16528)
		(width 0.12954)
		(layer "F.Cu")
		(net "GPU_BASE_HMC_READY_ISO")
	)
	(segment
		(start 183.7563 -164.595048)
		(end 182.5498 -163.388548)
		(width 0.12954)
		(layer "F.Cu")
		(net "GPU_BASE_HMC_READY_ISO")
	)
	(segment
		(start 171.04868 -419.114478)
		(end 170.203622 -419.114478)
		(width 0.12954)
		(layer "F.Cu")
		(net "GPU_BASE_HMC_READY_ISO")
	)
	(segment
		(start 182.5498 -163.388548)
		(end 182.30088 -163.388548)
		(width 0.12954)
		(layer "F.Cu")
		(net "GPU_BASE_HMC_READY_ISO")
	)
	(segment
		(start 201.114914 -163.688268)
		(end 192.394078 -163.688268)
		(width 0.12954)
		(layer "F.Cu")
		(net "GPU_BASE_HMC_READY_ISO")
	)
	(segment
		(start 172.503592 -419.674548)
		(end 171.943522 -419.114478)
		(width 0.12954)
		(layer "F.Cu")
		(net "GPU_BASE_HMC_READY_ISO")
	)
	(segment
		(start 169.822622 -418.479478)
		(end 170.193462 -418.479478)
		(width 0.12954)
		(layer "F.Cu")
		(net "GPU_BASE_HMC_READY_ISO")
	)
	(segment
		(start 243.41328 -161.166302)
		(end 239.158526 -156.911548)
		(width 0.12954)
		(layer "F.Cu")
		(net "GPU_BASE_HMC_READY_ISO")
	)
	(segment
		(start 207.891634 -156.911548)
		(end 201.114914 -163.688268)
		(width 0.12954)
		(layer "F.Cu")
		(net "GPU_BASE_HMC_READY_ISO")
	)
	(segment
		(start 244.07368 -165.039548)
		(end 244.07368 -165.014148)
		(width 0.12954)
		(layer "F.Cu")
		(net "GPU_BASE_HMC_READY_ISO")
	)
	(segment
		(start 192.394078 -163.688268)
		(end 190.001398 -166.080948)
		(width 0.12954)
		(layer "F.Cu")
		(net "GPU_BASE_HMC_READY_ISO")
	)
	(segment
		(start 243.41328 -164.353748)
		(end 243.41328 -161.166302)
		(width 0.12954)
		(layer "F.Cu")
		(net "GPU_BASE_HMC_READY_ISO")
	)
	(segment
		(start 170.203622 -419.114478)
		(end 169.822622 -419.495478)
		(width 0.12954)
		(layer "F.Cu")
		(net "GPU_BASE_HMC_READY_ISO")
	)
	(segment
		(start 244.07368 -165.014148)
		(end 243.41328 -164.353748)
		(width 0.12954)
		(layer "F.Cu")
		(net "GPU_BASE_HMC_READY_ISO")
	)
	(segment
		(start 186.73826 -166.080948)
		(end 185.25236 -164.595048)
		(width 0.12954)
		(layer "F.Cu")
		(net "GPU_BASE_HMC_READY_ISO")
	)
	(segment
		(start 169.822622 -418.479478)
		(end 169.822622 -419.495478)
		(width 0.12954)
		(layer "F.Cu")
		(net "GPU_BASE_HMC_READY_ISO")
	)
	(via
		(at 170.50766 -418.16528)
		(size 0.508)
		(drill 0.254)
		(layers "F.Cu" "B.Cu")
		(net "GPU_BASE_HMC_READY_ISO")
	)
	(via
		(at 155.12288 -116.296948)
		(size 0.508)
		(drill 0.254)
		(layers "F.Cu" "B.Cu")
		(net "GPU_BASE_HMC_READY_ISO")
	)
	(via
		(at 182.30088 -163.388548)
		(size 0.508)
		(drill 0.254)
		(layers "F.Cu" "B.Cu")
		(net "GPU_BASE_HMC_READY_ISO")
	)
	(via
		(at 171.04868 -419.114478)
		(size 0.508)
		(drill 0.254)
		(layers "F.Cu" "B.Cu")
		(net "GPU_BASE_HMC_READY_ISO")
	)
	(via
		(at 244.07368 -165.039548)
		(size 0.508)
		(drill 0.254)
		(layers "F.Cu" "B.Cu")
		(net "GPU_BASE_HMC_READY_ISO")
	)
	(segment
		(start 155.30068 -115.763548)
		(end 156.44368 -115.763548)
		(width 0.12954)
		(layer "B.Cu")
		(net "GPU_BASE_HMC_READY_ISO")
	)
	(segment
		(start 156.62783 -115.947698)
		(end 156.62783 -116.296948)
		(width 0.12954)
		(layer "B.Cu")
		(net "GPU_BASE_HMC_READY_ISO")
	)
	(segment
		(start 156.44368 -115.763548)
		(end 156.62783 -115.947698)
		(width 0.12954)
		(layer "B.Cu")
		(net "GPU_BASE_HMC_READY_ISO")
	)
	(segment
		(start 155.12288 -115.941348)
		(end 155.30068 -115.763548)
		(width 0.12954)
		(layer "B.Cu")
		(net "GPU_BASE_HMC_READY_ISO")
	)
	(segment
		(start 155.12288 -116.296948)
		(end 155.12288 -115.941348)
		(width 0.12954)
		(layer "B.Cu")
		(net "GPU_BASE_HMC_READY_ISO")
	)
	(segment
		(start 248.35866 -168.157144)
		(end 248.35866 -240.275364)
		(width 0.127)
		(layer "In2.Cu")
		(net "GPU_BASE_HMC_READY_ISO")
	)
	(segment
		(start 248.8184 -240.735104)
		(end 248.8184 -321.833748)
		(width 0.127)
		(layer "In2.Cu")
		(net "GPU_BASE_HMC_READY_ISO")
	)
	(segment
		(start 178.01082 -415.7345)
		(end 177.55108 -416.19424)
		(width 0.127)
		(layer "In2.Cu")
		(net "GPU_BASE_HMC_READY_ISO")
	)
	(segment
		(start 177.55108 -416.19424)
		(end 173.51502 -416.19424)
		(width 0.127)
		(layer "In2.Cu")
		(net "GPU_BASE_HMC_READY_ISO")
	)
	(segment
		(start 171.54398 -418.16528)
		(end 170.50766 -418.16528)
		(width 0.127)
		(layer "In2.Cu")
		(net "GPU_BASE_HMC_READY_ISO")
	)
	(segment
		(start 173.51502 -416.19424)
		(end 171.54398 -418.16528)
		(width 0.127)
		(layer "In2.Cu")
		(net "GPU_BASE_HMC_READY_ISO")
	)
	(segment
		(start 178.9176 -392.388852)
		(end 178.9176 -396.52448)
		(width 0.127)
		(layer "In2.Cu")
		(net "GPU_BASE_HMC_READY_ISO")
	)
	(segment
		(start 177.97526 -397.46682)
		(end 177.00498 -399.809462)
		(width 0.127)
		(layer "In2.Cu")
		(net "GPU_BASE_HMC_READY_ISO")
	)
	(segment
		(start 177.00498 -404.748492)
		(end 178.01082 -405.754332)
		(width 0.127)
		(layer "In2.Cu")
		(net "GPU_BASE_HMC_READY_ISO")
	)
	(segment
		(start 178.01082 -405.754332)
		(end 178.01082 -415.7345)
		(width 0.127)
		(layer "In2.Cu")
		(net "GPU_BASE_HMC_READY_ISO")
	)
	(segment
		(start 245.241064 -165.039548)
		(end 248.35866 -168.157144)
		(width 0.127)
		(layer "In2.Cu")
		(net "GPU_BASE_HMC_READY_ISO")
	)
	(segment
		(start 244.07368 -165.039548)
		(end 245.241064 -165.039548)
		(width 0.127)
		(layer "In2.Cu")
		(net "GPU_BASE_HMC_READY_ISO")
	)
	(segment
		(start 177.00498 -399.809462)
		(end 177.00498 -404.748492)
		(width 0.127)
		(layer "In2.Cu")
		(net "GPU_BASE_HMC_READY_ISO")
	)
	(segment
		(start 224.71888 -345.933268)
		(end 224.71888 -363.19587)
		(width 0.127)
		(layer "In2.Cu")
		(net "GPU_BASE_HMC_READY_ISO")
	)
	(segment
		(start 248.8184 -321.833748)
		(end 224.71888 -345.933268)
		(width 0.127)
		(layer "In2.Cu")
		(net "GPU_BASE_HMC_READY_ISO")
	)
	(segment
		(start 215.83777 -372.07698)
		(end 199.229472 -372.07698)
		(width 0.127)
		(layer "In2.Cu")
		(net "GPU_BASE_HMC_READY_ISO")
	)
	(segment
		(start 224.71888 -363.19587)
		(end 215.83777 -372.07698)
		(width 0.127)
		(layer "In2.Cu")
		(net "GPU_BASE_HMC_READY_ISO")
	)
	(segment
		(start 248.35866 -240.275364)
		(end 248.8184 -240.735104)
		(width 0.127)
		(layer "In2.Cu")
		(net "GPU_BASE_HMC_READY_ISO")
	)
	(segment
		(start 178.9176 -396.52448)
		(end 177.97526 -397.46682)
		(width 0.127)
		(layer "In2.Cu")
		(net "GPU_BASE_HMC_READY_ISO")
	)
	(segment
		(start 199.229472 -372.07698)
		(end 178.9176 -392.388852)
		(width 0.127)
		(layer "In2.Cu")
		(net "GPU_BASE_HMC_READY_ISO")
	)
	(segment
		(start 156.59608 -117.338348)
		(end 156.21508 -116.957348)
		(width 0.127)
		(layer "In11.Cu")
		(net "GPU_BASE_HMC_READY_ISO")
	)
	(segment
		(start 182.11038 -164.906452)
		(end 180.995066 -166.021766)
		(width 0.127)
		(layer "In11.Cu")
		(net "GPU_BASE_HMC_READY_ISO")
	)
	(segment
		(start 175.59528 -163.395406)
		(end 175.59528 -159.934148)
		(width 0.127)
		(layer "In11.Cu")
		(net "GPU_BASE_HMC_READY_ISO")
	)
	(segment
		(start 182.30088 -163.388548)
		(end 182.11038 -163.579048)
		(width 0.127)
		(layer "In11.Cu")
		(net "GPU_BASE_HMC_READY_ISO")
	)
	(segment
		(start 182.11038 -163.579048)
		(end 182.11038 -164.906452)
		(width 0.127)
		(layer "In11.Cu")
		(net "GPU_BASE_HMC_READY_ISO")
	)
	(segment
		(start 178.22164 -166.021766)
		(end 175.59528 -163.395406)
		(width 0.127)
		(layer "In11.Cu")
		(net "GPU_BASE_HMC_READY_ISO")
	)
	(segment
		(start 156.21508 -116.957348)
		(end 155.52928 -116.957348)
		(width 0.127)
		(layer "In11.Cu")
		(net "GPU_BASE_HMC_READY_ISO")
	)
	(segment
		(start 155.12288 -116.550948)
		(end 155.12288 -116.296948)
		(width 0.127)
		(layer "In11.Cu")
		(net "GPU_BASE_HMC_READY_ISO")
	)
	(segment
		(start 175.59528 -159.934148)
		(end 156.59608 -140.934948)
		(width 0.127)
		(layer "In11.Cu")
		(net "GPU_BASE_HMC_READY_ISO")
	)
	(segment
		(start 155.52928 -116.957348)
		(end 155.12288 -116.550948)
		(width 0.127)
		(layer "In11.Cu")
		(net "GPU_BASE_HMC_READY_ISO")
	)
	(segment
		(start 180.995066 -166.021766)
		(end 178.22164 -166.021766)
		(width 0.127)
		(layer "In11.Cu")
		(net "GPU_BASE_HMC_READY_ISO")
	)
	(segment
		(start 156.59608 -140.934948)
		(end 156.59608 -117.338348)
		(width 0.127)
		(layer "In11.Cu")
		(net "GPU_BASE_HMC_READY_ISO")
	)
	(segment
		(start 167.8559 -422.2115)
		(end 169.16146 -422.2115)
		(width 0.12954)
		(layer "F.Cu")
		(net "GPU_BASE_HMC_READY")
	)
	(segment
		(start 161.93516 -424.04792)
		(end 166.01948 -424.04792)
		(width 0.12954)
		(layer "F.Cu")
		(net "GPU_BASE_HMC_READY")
	)
	(segment
		(start 166.01948 -424.04792)
		(end 167.8559 -422.2115)
		(width 0.12954)
		(layer "F.Cu")
		(net "GPU_BASE_HMC_READY")
	)
	(segment
		(start 169.16146 -422.2115)
		(end 169.841672 -421.531288)
		(width 0.12954)
		(layer "F.Cu")
		(net "GPU_BASE_HMC_READY")
	)
	(segment
		(start 171.967906 -420.324534)
		(end 172.503592 -420.324534)
		(width 0.12954)
		(layer "F.Cu")
		(net "GPU_BASE_HMC_READY")
	)
	(segment
		(start 171.780962 -420.511478)
		(end 171.967906 -420.324534)
		(width 0.12954)
		(layer "F.Cu")
		(net "GPU_BASE_HMC_READY")
	)
	(segment
		(start 171.092622 -420.511478)
		(end 171.780962 -420.511478)
		(width 0.12954)
		(layer "F.Cu")
		(net "GPU_BASE_HMC_READY")
	)
	(segment
		(start 169.841672 -421.527478)
		(end 169.841672 -420.511478)
		(width 0.12954)
		(layer "F.Cu")
		(net "GPU_BASE_HMC_READY")
	)
	(segment
		(start 169.841672 -421.531288)
		(end 169.841672 -421.527478)
		(width 0.12954)
		(layer "F.Cu")
		(net "GPU_BASE_HMC_READY")
	)
	(segment
		(start 169.841672 -420.511478)
		(end 171.092622 -420.511478)
		(width 0.12954)
		(layer "F.Cu")
		(net "GPU_BASE_HMC_READY")
	)
	(via
		(at 161.93516 -424.04792)
		(size 0.508)
		(drill 0.254)
		(layers "F.Cu" "B.Cu")
		(net "GPU_BASE_HMC_READY")
	)
	(via
		(at 171.092622 -420.511478)
		(size 0.762)
		(drill 0.381)
		(layers "F.Cu" "B.Cu")
		(net "GPU_BASE_HMC_READY")
	)
	(segment
		(start 134.87908 -422.646348)
		(end 136.264142 -421.261286)
		(width 0.127)
		(layer "In2.Cu")
		(net "GPU_BASE_HMC_READY")
	)
	(segment
		(start 133.75005 -440.489848)
		(end 134.05358 -440.489848)
		(width 0.127)
		(layer "In2.Cu")
		(net "GPU_BASE_HMC_READY")
	)
	(segment
		(start 136.264142 -421.261286)
		(end 158.46171 -421.261286)
		(width 0.127)
		(layer "In2.Cu")
		(net "GPU_BASE_HMC_READY")
	)
	(segment
		(start 134.05358 -440.489848)
		(end 134.87908 -439.664348)
		(width 0.127)
		(layer "In2.Cu")
		(net "GPU_BASE_HMC_READY")
	)
	(segment
		(start 134.87908 -439.664348)
		(end 134.87908 -422.646348)
		(width 0.127)
		(layer "In2.Cu")
		(net "GPU_BASE_HMC_READY")
	)
	(segment
		(start 161.248344 -424.04792)
		(end 161.93516 -424.04792)
		(width 0.127)
		(layer "In2.Cu")
		(net "GPU_BASE_HMC_READY")
	)
	(segment
		(start 158.46171 -421.261286)
		(end 161.248344 -424.04792)
		(width 0.127)
		(layer "In2.Cu")
		(net "GPU_BASE_HMC_READY")
	)
	(segment
		(start 31.69793 -431.891948)
		(end 32.30753 -431.891948)
		(width 0.12954)
		(layer "F.Cu")
		(net "FM_SWB_PWR_EN_R_BUF")
	)
	(via
		(at 32.30753 -431.891948)
		(size 0.508)
		(drill 0.254)
		(layers "F.Cu" "B.Cu")
		(net "FM_SWB_PWR_EN_R_BUF")
	)
	(via
		(at 300.81982 -399.60804)
		(size 0.508)
		(drill 0.254)
		(layers "F.Cu" "B.Cu")
		(net "FM_SWB_PWR_EN_R_BUF")
	)
	(via
		(at 364.16488 -398.719548)
		(size 0.508)
		(drill 0.254)
		(layers "F.Cu" "B.Cu")
		(net "FM_SWB_PWR_EN_R_BUF")
	)
	(via
		(at 175.7934 -398.06626)
		(size 0.508)
		(drill 0.254)
		(layers "F.Cu" "B.Cu")
		(net "FM_SWB_PWR_EN_R_BUF")
	)
	(via
		(at 282.95346 -414.36798)
		(size 0.508)
		(drill 0.254)
		(layers "F.Cu" "B.Cu")
		(net "FM_SWB_PWR_EN_R_BUF")
	)
	(segment
		(start 282.5242 -407.796746)
		(end 281.519122 -408.801824)
		(width 0.12954)
		(layer "B.Cu")
		(net "FM_SWB_PWR_EN_R_BUF")
	)
	(segment
		(start 175.91024 -397.94942)
		(end 175.91024 -392.97102)
		(width 0.12954)
		(layer "B.Cu")
		(net "FM_SWB_PWR_EN_R_BUF")
	)
	(segment
		(start 268.27988 -387.559296)
		(end 269.769844 -389.04926)
		(width 0.12954)
		(layer "B.Cu")
		(net "FM_SWB_PWR_EN_R_BUF")
	)
	(segment
		(start 277.788624 -389.04926)
		(end 281.341322 -392.601958)
		(width 0.12954)
		(layer "B.Cu")
		(net "FM_SWB_PWR_EN_R_BUF")
	)
	(segment
		(start 281.341322 -395.514576)
		(end 282.5242 -396.697454)
		(width 0.12954)
		(layer "B.Cu")
		(net "FM_SWB_PWR_EN_R_BUF")
	)
	(segment
		(start 282.5242 -396.697454)
		(end 282.5242 -407.796746)
		(width 0.12954)
		(layer "B.Cu")
		(net "FM_SWB_PWR_EN_R_BUF")
	)
	(segment
		(start 281.341322 -392.601958)
		(end 281.341322 -395.514576)
		(width 0.12954)
		(layer "B.Cu")
		(net "FM_SWB_PWR_EN_R_BUF")
	)
	(segment
		(start 269.769844 -389.04926)
		(end 277.788624 -389.04926)
		(width 0.12954)
		(layer "B.Cu")
		(net "FM_SWB_PWR_EN_R_BUF")
	)
	(segment
		(start 282.556204 -414.36798)
		(end 282.95346 -414.36798)
		(width 0.12954)
		(layer "B.Cu")
		(net "FM_SWB_PWR_EN_R_BUF")
	)
	(segment
		(start 189.051438 -379.829822)
		(end 263.036304 -379.829822)
		(width 0.12954)
		(layer "B.Cu")
		(net "FM_SWB_PWR_EN_R_BUF")
	)
	(segment
		(start 300.81982 -399.60804)
		(end 301.022512 -399.405348)
		(width 0.12954)
		(layer "B.Cu")
		(net "FM_SWB_PWR_EN_R_BUF")
	)
	(segment
		(start 364.08106 -398.803368)
		(end 364.16488 -398.719548)
		(width 0.12954)
		(layer "B.Cu")
		(net "FM_SWB_PWR_EN_R_BUF")
	)
	(segment
		(start 175.7934 -398.06626)
		(end 175.91024 -397.94942)
		(width 0.12954)
		(layer "B.Cu")
		(net "FM_SWB_PWR_EN_R_BUF")
	)
	(segment
		(start 357.1875 -399.405348)
		(end 357.78948 -398.803368)
		(width 0.12954)
		(layer "B.Cu")
		(net "FM_SWB_PWR_EN_R_BUF")
	)
	(segment
		(start 268.27988 -385.073398)
		(end 268.27988 -387.559296)
		(width 0.12954)
		(layer "B.Cu")
		(net "FM_SWB_PWR_EN_R_BUF")
	)
	(segment
		(start 357.78948 -398.803368)
		(end 364.08106 -398.803368)
		(width 0.12954)
		(layer "B.Cu")
		(net "FM_SWB_PWR_EN_R_BUF")
	)
	(segment
		(start 175.91024 -392.97102)
		(end 189.051438 -379.829822)
		(width 0.12954)
		(layer "B.Cu")
		(net "FM_SWB_PWR_EN_R_BUF")
	)
	(segment
		(start 281.519122 -408.801824)
		(end 281.519122 -413.330898)
		(width 0.12954)
		(layer "B.Cu")
		(net "FM_SWB_PWR_EN_R_BUF")
	)
	(segment
		(start 263.036304 -379.829822)
		(end 268.27988 -385.073398)
		(width 0.12954)
		(layer "B.Cu")
		(net "FM_SWB_PWR_EN_R_BUF")
	)
	(segment
		(start 301.022512 -399.405348)
		(end 357.1875 -399.405348)
		(width 0.12954)
		(layer "B.Cu")
		(net "FM_SWB_PWR_EN_R_BUF")
	)
	(segment
		(start 281.519122 -413.330898)
		(end 282.556204 -414.36798)
		(width 0.12954)
		(layer "B.Cu")
		(net "FM_SWB_PWR_EN_R_BUF")
	)
	(segment
		(start 400.750024 -420.877492)
		(end 396.88008 -417.007548)
		(width 0.127)
		(layer "In2.Cu")
		(net "FM_SWB_PWR_EN_R_BUF")
	)
	(segment
		(start 400.750024 -424.689778)
		(end 400.750024 -420.877492)
		(width 0.127)
		(layer "In2.Cu")
		(net "FM_SWB_PWR_EN_R_BUF")
	)
	(segment
		(start 396.88008 -417.007548)
		(end 381.20828 -417.007548)
		(width 0.127)
		(layer "In2.Cu")
		(net "FM_SWB_PWR_EN_R_BUF")
	)
	(segment
		(start 381.20828 -417.007548)
		(end 377.413012 -413.21228)
		(width 0.127)
		(layer "In2.Cu")
		(net "FM_SWB_PWR_EN_R_BUF")
	)
	(segment
		(start 367.995962 -402.55063)
		(end 364.16488 -398.719548)
		(width 0.127)
		(layer "In2.Cu")
		(net "FM_SWB_PWR_EN_R_BUF")
	)
	(segment
		(start 367.995962 -409.941014)
		(end 367.995962 -402.55063)
		(width 0.127)
		(layer "In2.Cu")
		(net "FM_SWB_PWR_EN_R_BUF")
	)
	(segment
		(start 377.413012 -413.21228)
		(end 371.267228 -413.21228)
		(width 0.127)
		(layer "In2.Cu")
		(net "FM_SWB_PWR_EN_R_BUF")
	)
	(segment
		(start 371.267228 -413.21228)
		(end 367.995962 -409.941014)
		(width 0.127)
		(layer "In2.Cu")
		(net "FM_SWB_PWR_EN_R_BUF")
	)
	(segment
		(start 285.99638 -412.36392)
		(end 288.128202 -412.36392)
		(width 0.127)
		(layer "In4.Cu")
		(net "FM_SWB_PWR_EN_R_BUF")
	)
	(segment
		(start 283.99232 -414.36798)
		(end 285.99638 -412.36392)
		(width 0.127)
		(layer "In4.Cu")
		(net "FM_SWB_PWR_EN_R_BUF")
	)
	(segment
		(start 302.4378 -401.873974)
		(end 300.81982 -400.255994)
		(width 0.127)
		(layer "In4.Cu")
		(net "FM_SWB_PWR_EN_R_BUF")
	)
	(segment
		(start 288.6075 -412.843218)
		(end 299.812202 -412.843218)
		(width 0.127)
		(layer "In4.Cu")
		(net "FM_SWB_PWR_EN_R_BUF")
	)
	(segment
		(start 288.128202 -412.36392)
		(end 288.6075 -412.843218)
		(width 0.127)
		(layer "In4.Cu")
		(net "FM_SWB_PWR_EN_R_BUF")
	)
	(segment
		(start 300.81982 -400.255994)
		(end 300.81982 -399.60804)
		(width 0.127)
		(layer "In4.Cu")
		(net "FM_SWB_PWR_EN_R_BUF")
	)
	(segment
		(start 299.812202 -412.843218)
		(end 302.4378 -410.21762)
		(width 0.127)
		(layer "In4.Cu")
		(net "FM_SWB_PWR_EN_R_BUF")
	)
	(segment
		(start 282.95346 -414.36798)
		(end 283.99232 -414.36798)
		(width 0.127)
		(layer "In4.Cu")
		(net "FM_SWB_PWR_EN_R_BUF")
	)
	(segment
		(start 302.4378 -410.21762)
		(end 302.4378 -401.873974)
		(width 0.127)
		(layer "In4.Cu")
		(net "FM_SWB_PWR_EN_R_BUF")
	)
	(segment
		(start 109.65942 -395.237208)
		(end 108.94314 -395.953488)
		(width 0.127)
		(layer "In11.Cu")
		(net "FM_SWB_PWR_EN_R_BUF")
	)
	(segment
		(start 101.5619 -393.758928)
		(end 101.19868 -394.122148)
		(width 0.127)
		(layer "In11.Cu")
		(net "FM_SWB_PWR_EN_R_BUF")
	)
	(segment
		(start 173.523656 -396.832328)
		(end 171.873926 -396.832328)
		(width 0.127)
		(layer "In11.Cu")
		(net "FM_SWB_PWR_EN_R_BUF")
	)
	(segment
		(start 31.313374 -431.891948)
		(end 32.30753 -431.891948)
		(width 0.127)
		(layer "In11.Cu")
		(net "FM_SWB_PWR_EN_R_BUF")
	)
	(segment
		(start 175.00981 -397.28267)
		(end 173.973998 -397.28267)
		(width 0.127)
		(layer "In11.Cu")
		(net "FM_SWB_PWR_EN_R_BUF")
	)
	(segment
		(start 165.263322 -396.324582)
		(end 163.670234 -396.324582)
		(width 0.127)
		(layer "In11.Cu")
		(net "FM_SWB_PWR_EN_R_BUF")
	)
	(segment
		(start 116.786914 -395.261338)
		(end 115.475766 -395.261338)
		(width 0.127)
		(layer "In11.Cu")
		(net "FM_SWB_PWR_EN_R_BUF")
	)
	(segment
		(start 98.858832 -396.128748)
		(end 97.774252 -396.128748)
		(width 0.127)
		(layer "In11.Cu")
		(net "FM_SWB_PWR_EN_R_BUF")
	)
	(segment
		(start 163.670234 -396.324582)
		(end 163.66998 -396.324328)
		(width 0.127)
		(layer "In11.Cu")
		(net "FM_SWB_PWR_EN_R_BUF")
	)
	(segment
		(start 28.506674 -429.085248)
		(end 31.313374 -431.891948)
		(width 0.127)
		(layer "In11.Cu")
		(net "FM_SWB_PWR_EN_R_BUF")
	)
	(segment
		(start 115.116356 -395.620748)
		(end 111.18088 -395.620748)
		(width 0.127)
		(layer "In11.Cu")
		(net "FM_SWB_PWR_EN_R_BUF")
	)
	(segment
		(start 110.79734 -395.237208)
		(end 109.65942 -395.237208)
		(width 0.127)
		(layer "In11.Cu")
		(net "FM_SWB_PWR_EN_R_BUF")
	)
	(segment
		(start 101.19868 -394.122148)
		(end 100.865432 -394.122148)
		(width 0.127)
		(layer "In11.Cu")
		(net "FM_SWB_PWR_EN_R_BUF")
	)
	(segment
		(start 171.873926 -396.832328)
		(end 171.423584 -397.28267)
		(width 0.127)
		(layer "In11.Cu")
		(net "FM_SWB_PWR_EN_R_BUF")
	)
	(segment
		(start 108.94314 -395.953488)
		(end 106.55554 -395.953488)
		(width 0.127)
		(layer "In11.Cu")
		(net "FM_SWB_PWR_EN_R_BUF")
	)
	(segment
		(start 97.774252 -396.128748)
		(end 96.679512 -397.223488)
		(width 0.127)
		(layer "In11.Cu")
		(net "FM_SWB_PWR_EN_R_BUF")
	)
	(segment
		(start 104.36098 -393.758928)
		(end 101.5619 -393.758928)
		(width 0.127)
		(layer "In11.Cu")
		(net "FM_SWB_PWR_EN_R_BUF")
	)
	(segment
		(start 123.473972 -396.845028)
		(end 118.370604 -396.845028)
		(width 0.127)
		(layer "In11.Cu")
		(net "FM_SWB_PWR_EN_R_BUF")
	)
	(segment
		(start 30.568392 -410.584142)
		(end 28.506674 -412.64586)
		(width 0.127)
		(layer "In11.Cu")
		(net "FM_SWB_PWR_EN_R_BUF")
	)
	(segment
		(start 166.22141 -397.28267)
		(end 165.263322 -396.324582)
		(width 0.127)
		(layer "In11.Cu")
		(net "FM_SWB_PWR_EN_R_BUF")
	)
	(segment
		(start 173.973998 -397.28267)
		(end 173.523656 -396.832328)
		(width 0.127)
		(layer "In11.Cu")
		(net "FM_SWB_PWR_EN_R_BUF")
	)
	(segment
		(start 39.811452 -411.937962)
		(end 35.042348 -411.937962)
		(width 0.127)
		(layer "In11.Cu")
		(net "FM_SWB_PWR_EN_R_BUF")
	)
	(segment
		(start 163.66998 -396.324328)
		(end 123.994672 -396.324328)
		(width 0.127)
		(layer "In11.Cu")
		(net "FM_SWB_PWR_EN_R_BUF")
	)
	(segment
		(start 100.865432 -394.122148)
		(end 98.858832 -396.128748)
		(width 0.127)
		(layer "In11.Cu")
		(net "FM_SWB_PWR_EN_R_BUF")
	)
	(segment
		(start 175.7934 -398.06626)
		(end 175.00981 -397.28267)
		(width 0.127)
		(layer "In11.Cu")
		(net "FM_SWB_PWR_EN_R_BUF")
	)
	(segment
		(start 123.994672 -396.324328)
		(end 123.473972 -396.845028)
		(width 0.127)
		(layer "In11.Cu")
		(net "FM_SWB_PWR_EN_R_BUF")
	)
	(segment
		(start 96.679512 -397.223488)
		(end 47.980854 -397.223488)
		(width 0.127)
		(layer "In11.Cu")
		(net "FM_SWB_PWR_EN_R_BUF")
	)
	(segment
		(start 115.475766 -395.261338)
		(end 115.116356 -395.620748)
		(width 0.127)
		(layer "In11.Cu")
		(net "FM_SWB_PWR_EN_R_BUF")
	)
	(segment
		(start 46.591474 -398.612868)
		(end 46.591474 -405.15794)
		(width 0.127)
		(layer "In11.Cu")
		(net "FM_SWB_PWR_EN_R_BUF")
	)
	(segment
		(start 46.591474 -405.15794)
		(end 39.811452 -411.937962)
		(width 0.127)
		(layer "In11.Cu")
		(net "FM_SWB_PWR_EN_R_BUF")
	)
	(segment
		(start 35.042348 -411.937962)
		(end 33.688528 -410.584142)
		(width 0.127)
		(layer "In11.Cu")
		(net "FM_SWB_PWR_EN_R_BUF")
	)
	(segment
		(start 111.18088 -395.620748)
		(end 110.79734 -395.237208)
		(width 0.127)
		(layer "In11.Cu")
		(net "FM_SWB_PWR_EN_R_BUF")
	)
	(segment
		(start 33.688528 -410.584142)
		(end 30.568392 -410.584142)
		(width 0.127)
		(layer "In11.Cu")
		(net "FM_SWB_PWR_EN_R_BUF")
	)
	(segment
		(start 47.980854 -397.223488)
		(end 46.591474 -398.612868)
		(width 0.127)
		(layer "In11.Cu")
		(net "FM_SWB_PWR_EN_R_BUF")
	)
	(segment
		(start 171.423584 -397.28267)
		(end 166.22141 -397.28267)
		(width 0.127)
		(layer "In11.Cu")
		(net "FM_SWB_PWR_EN_R_BUF")
	)
	(segment
		(start 28.506674 -412.64586)
		(end 28.506674 -429.085248)
		(width 0.127)
		(layer "In11.Cu")
		(net "FM_SWB_PWR_EN_R_BUF")
	)
	(segment
		(start 118.370604 -396.845028)
		(end 116.786914 -395.261338)
		(width 0.127)
		(layer "In11.Cu")
		(net "FM_SWB_PWR_EN_R_BUF")
	)
	(segment
		(start 106.55554 -395.953488)
		(end 104.36098 -393.758928)
		(width 0.127)
		(layer "In11.Cu")
		(net "FM_SWB_PWR_EN_R_BUF")
	)
	(segment
		(start 29.13888 -429.605948)
		(end 30.64383 -429.605948)
		(width 0.12954)
		(layer "F.Cu")
		(net "FM_SWB_PWR_EN_R1_BUF")
	)
	(segment
		(start 30.64383 -429.605948)
		(end 30.89783 -429.859948)
		(width 0.12954)
		(layer "F.Cu")
		(net "FM_SWB_PWR_EN_R1_BUF")
	)
	(segment
		(start 27.92984 -430.225962)
		(end 28.549854 -429.605948)
		(width 0.12954)
		(layer "F.Cu")
		(net "FM_SWB_PWR_EN_R1_BUF")
	)
	(segment
		(start 30.89783 -430.875948)
		(end 30.89783 -429.859948)
		(width 0.12954)
		(layer "F.Cu")
		(net "FM_SWB_PWR_EN_R1_BUF")
	)
	(segment
		(start 30.89783 -430.875948)
		(end 30.89783 -431.891948)
		(width 0.12954)
		(layer "F.Cu")
		(net "FM_SWB_PWR_EN_R1_BUF")
	)
	(segment
		(start 28.549854 -429.605948)
		(end 29.13888 -429.605948)
		(width 0.12954)
		(layer "F.Cu")
		(net "FM_SWB_PWR_EN_R1_BUF")
	)
	(via
		(at 29.13888 -429.605948)
		(size 0.762)
		(drill 0.381)
		(layers "F.Cu" "B.Cu")
		(net "FM_SWB_PWR_EN_R1_BUF")
	)
	(segment
		(start 23.736554 -430.367948)
		(end 23.31593 -430.367948)
		(width 0.12954)
		(layer "F.Cu")
		(net "FM_SWB_PWR_EN_R")
	)
	(segment
		(start 170.99788 -98.643948)
		(end 170.99788 -99.463098)
		(width 0.12954)
		(layer "F.Cu")
		(net "FM_SWB_PWR_EN_R")
	)
	(segment
		(start 23.87854 -430.225962)
		(end 23.736554 -430.367948)
		(width 0.12954)
		(layer "F.Cu")
		(net "FM_SWB_PWR_EN_R")
	)
	(segment
		(start 26.02992 -430.225962)
		(end 24.49068 -430.225962)
		(width 0.12954)
		(layer "F.Cu")
		(net "FM_SWB_PWR_EN_R")
	)
	(segment
		(start 24.49068 -430.225962)
		(end 23.87854 -430.225962)
		(width 0.12954)
		(layer "F.Cu")
		(net "FM_SWB_PWR_EN_R")
	)
	(segment
		(start 23.31593 -429.351948)
		(end 23.31593 -430.367948)
		(width 0.12954)
		(layer "F.Cu")
		(net "FM_SWB_PWR_EN_R")
	)
	(segment
		(start 170.99788 -99.463098)
		(end 170.99407 -99.466908)
		(width 0.12954)
		(layer "F.Cu")
		(net "FM_SWB_PWR_EN_R")
	)
	(via
		(at 147.04568 -118.481348)
		(size 0.508)
		(drill 0.254)
		(layers "F.Cu" "B.Cu")
		(net "FM_SWB_PWR_EN_R")
	)
	(via
		(at 170.99788 -98.643948)
		(size 0.508)
		(drill 0.254)
		(layers "F.Cu" "B.Cu")
		(net "FM_SWB_PWR_EN_R")
	)
	(via
		(at 24.49068 -430.225962)
		(size 0.508)
		(drill 0.254)
		(layers "F.Cu" "B.Cu")
		(net "FM_SWB_PWR_EN_R")
	)
	(segment
		(start 152.22728 -102.199948)
		(end 156.06522 -98.362008)
		(width 0.12954)
		(layer "B.Cu")
		(net "FM_SWB_PWR_EN_R")
	)
	(segment
		(start 152.22728 -107.381548)
		(end 152.22728 -102.199948)
		(width 0.12954)
		(layer "B.Cu")
		(net "FM_SWB_PWR_EN_R")
	)
	(segment
		(start 152.5016 -110.2614)
		(end 153.46045 -109.30255)
		(width 0.12954)
		(layer "B.Cu")
		(net "FM_SWB_PWR_EN_R")
	)
	(segment
		(start 170.71594 -98.362008)
		(end 170.99788 -98.643948)
		(width 0.12954)
		(layer "B.Cu")
		(net "FM_SWB_PWR_EN_R")
	)
	(segment
		(start 156.06522 -98.362008)
		(end 170.71594 -98.362008)
		(width 0.12954)
		(layer "B.Cu")
		(net "FM_SWB_PWR_EN_R")
	)
	(segment
		(start 153.46045 -108.614718)
		(end 152.22728 -107.381548)
		(width 0.12954)
		(layer "B.Cu")
		(net "FM_SWB_PWR_EN_R")
	)
	(segment
		(start 150.24608 -111.907574)
		(end 151.892254 -110.2614)
		(width 0.12954)
		(layer "B.Cu")
		(net "FM_SWB_PWR_EN_R")
	)
	(segment
		(start 150.24608 -114.468148)
		(end 150.24608 -111.907574)
		(width 0.12954)
		(layer "B.Cu")
		(net "FM_SWB_PWR_EN_R")
	)
	(segment
		(start 151.892254 -110.2614)
		(end 152.5016 -110.2614)
		(width 0.12954)
		(layer "B.Cu")
		(net "FM_SWB_PWR_EN_R")
	)
	(segment
		(start 147.04568 -117.668548)
		(end 150.24608 -114.468148)
		(width 0.12954)
		(layer "B.Cu")
		(net "FM_SWB_PWR_EN_R")
	)
	(segment
		(start 147.04568 -118.481348)
		(end 147.04568 -117.668548)
		(width 0.12954)
		(layer "B.Cu")
		(net "FM_SWB_PWR_EN_R")
	)
	(segment
		(start 153.46045 -109.30255)
		(end 153.46045 -108.614718)
		(width 0.12954)
		(layer "B.Cu")
		(net "FM_SWB_PWR_EN_R")
	)
	(segment
		(start 105.84815 -112.817148)
		(end 103.66375 -115.001548)
		(width 0.127)
		(layer "In13.Cu")
		(net "FM_SWB_PWR_EN_R")
	)
	(segment
		(start 3.60299 -164.629592)
		(end 3.9624 -164.989002)
		(width 0.127)
		(layer "In13.Cu")
		(net "FM_SWB_PWR_EN_R")
	)
	(segment
		(start 17.5514 -413.344868)
		(end 24.49068 -420.284148)
		(width 0.127)
		(layer "In13.Cu")
		(net "FM_SWB_PWR_EN_R")
	)
	(segment
		(start 93.98635 -115.001548)
		(end 91.44635 -117.541548)
		(width 0.127)
		(layer "In13.Cu")
		(net "FM_SWB_PWR_EN_R")
	)
	(segment
		(start 7.01167 -354.294948)
		(end 12.75461 -354.294948)
		(width 0.127)
		(layer "In13.Cu")
		(net "FM_SWB_PWR_EN_R")
	)
	(segment
		(start 144.211548 -112.451388)
		(end 140.218414 -112.451388)
		(width 0.127)
		(layer "In13.Cu")
		(net "FM_SWB_PWR_EN_R")
	)
	(segment
		(start 146.0373 -113.4491)
		(end 145.49882 -112.91062)
		(width 0.127)
		(layer "In13.Cu")
		(net "FM_SWB_PWR_EN_R")
	)
	(segment
		(start 55.745126 -115.664488)
		(end 51.73218 -115.664488)
		(width 0.127)
		(layer "In13.Cu")
		(net "FM_SWB_PWR_EN_R")
	)
	(segment
		(start 18.081752 -359.62209)
		(end 18.081752 -380.73457)
		(width 0.127)
		(layer "In13.Cu")
		(net "FM_SWB_PWR_EN_R")
	)
	(segment
		(start 18.061686 -116.675408)
		(end 3.88239 -130.854704)
		(width 0.127)
		(layer "In13.Cu")
		(net "FM_SWB_PWR_EN_R")
	)
	(segment
		(start 24.49068 -420.284148)
		(end 24.49068 -430.225962)
		(width 0.127)
		(layer "In13.Cu")
		(net "FM_SWB_PWR_EN_R")
	)
	(segment
		(start 145.49882 -112.91062)
		(end 144.67078 -112.91062)
		(width 0.127)
		(layer "In13.Cu")
		(net "FM_SWB_PWR_EN_R")
	)
	(segment
		(start 12.75461 -354.294948)
		(end 18.081752 -359.62209)
		(width 0.127)
		(layer "In13.Cu")
		(net "FM_SWB_PWR_EN_R")
	)
	(segment
		(start 18.081752 -380.73457)
		(end 15.681452 -383.13487)
		(width 0.127)
		(layer "In13.Cu")
		(net "FM_SWB_PWR_EN_R")
	)
	(segment
		(start 17.5514 -403.008338)
		(end 17.5514 -413.344868)
		(width 0.127)
		(layer "In13.Cu")
		(net "FM_SWB_PWR_EN_R")
	)
	(segment
		(start 68.32092 -116.291868)
		(end 56.372506 -116.291868)
		(width 0.127)
		(layer "In13.Cu")
		(net "FM_SWB_PWR_EN_R")
	)
	(segment
		(start 51.73218 -115.664488)
		(end 50.72126 -116.675408)
		(width 0.127)
		(layer "In13.Cu")
		(net "FM_SWB_PWR_EN_R")
	)
	(segment
		(start 144.67078 -112.91062)
		(end 144.211548 -112.451388)
		(width 0.127)
		(layer "In13.Cu")
		(net "FM_SWB_PWR_EN_R")
	)
	(segment
		(start 131.32435 -112.817148)
		(end 105.84815 -112.817148)
		(width 0.127)
		(layer "In13.Cu")
		(net "FM_SWB_PWR_EN_R")
	)
	(segment
		(start 56.372506 -116.291868)
		(end 55.745126 -115.664488)
		(width 0.127)
		(layer "In13.Cu")
		(net "FM_SWB_PWR_EN_R")
	)
	(segment
		(start 91.44635 -117.541548)
		(end 69.5706 -117.541548)
		(width 0.127)
		(layer "In13.Cu")
		(net "FM_SWB_PWR_EN_R")
	)
	(segment
		(start 3.88239 -154.300428)
		(end 3.60299 -154.579828)
		(width 0.127)
		(layer "In13.Cu")
		(net "FM_SWB_PWR_EN_R")
	)
	(segment
		(start 147.04568 -116.984018)
		(end 146.0373 -115.975638)
		(width 0.127)
		(layer "In13.Cu")
		(net "FM_SWB_PWR_EN_R")
	)
	(segment
		(start 147.04568 -118.481348)
		(end 147.04568 -116.984018)
		(width 0.127)
		(layer "In13.Cu")
		(net "FM_SWB_PWR_EN_R")
	)
	(segment
		(start 3.88239 -130.854704)
		(end 3.88239 -154.300428)
		(width 0.127)
		(layer "In13.Cu")
		(net "FM_SWB_PWR_EN_R")
	)
	(segment
		(start 146.0373 -115.975638)
		(end 146.0373 -113.4491)
		(width 0.127)
		(layer "In13.Cu")
		(net "FM_SWB_PWR_EN_R")
	)
	(segment
		(start 3.9624 -351.245678)
		(end 7.01167 -354.294948)
		(width 0.127)
		(layer "In13.Cu")
		(net "FM_SWB_PWR_EN_R")
	)
	(segment
		(start 140.218414 -112.451388)
		(end 138.267694 -110.500668)
		(width 0.127)
		(layer "In13.Cu")
		(net "FM_SWB_PWR_EN_R")
	)
	(segment
		(start 3.9624 -164.989002)
		(end 3.9624 -351.245678)
		(width 0.127)
		(layer "In13.Cu")
		(net "FM_SWB_PWR_EN_R")
	)
	(segment
		(start 138.267694 -110.500668)
		(end 133.64083 -110.500668)
		(width 0.127)
		(layer "In13.Cu")
		(net "FM_SWB_PWR_EN_R")
	)
	(segment
		(start 103.66375 -115.001548)
		(end 93.98635 -115.001548)
		(width 0.127)
		(layer "In13.Cu")
		(net "FM_SWB_PWR_EN_R")
	)
	(segment
		(start 69.5706 -117.541548)
		(end 68.32092 -116.291868)
		(width 0.127)
		(layer "In13.Cu")
		(net "FM_SWB_PWR_EN_R")
	)
	(segment
		(start 50.72126 -116.675408)
		(end 18.061686 -116.675408)
		(width 0.127)
		(layer "In13.Cu")
		(net "FM_SWB_PWR_EN_R")
	)
	(segment
		(start 133.64083 -110.500668)
		(end 131.32435 -112.817148)
		(width 0.127)
		(layer "In13.Cu")
		(net "FM_SWB_PWR_EN_R")
	)
	(segment
		(start 15.681452 -401.13839)
		(end 17.5514 -403.008338)
		(width 0.127)
		(layer "In13.Cu")
		(net "FM_SWB_PWR_EN_R")
	)
	(segment
		(start 15.681452 -383.13487)
		(end 15.681452 -401.13839)
		(width 0.127)
		(layer "In13.Cu")
		(net "FM_SWB_PWR_EN_R")
	)
	(segment
		(start 3.60299 -154.579828)
		(end 3.60299 -164.629592)
		(width 0.127)
		(layer "In13.Cu")
		(net "FM_SWB_PWR_EN_R")
	)
	(segment
		(start 170.89628 -104.91597)
		(end 170.89628 -100.716588)
		(width 0.12954)
		(layer "F.Cu")
		(net "FM_SWB_PWR_EN")
	)
	(segment
		(start 170.19397 -100.014278)
		(end 170.19397 -99.466908)
		(width 0.12954)
		(layer "F.Cu")
		(net "FM_SWB_PWR_EN")
	)
	(segment
		(start 170.89628 -100.716588)
		(end 170.19397 -100.014278)
		(width 0.12954)
		(layer "F.Cu")
		(net "FM_SWB_PWR_EN")
	)
	(segment
		(start 170.955716 -104.975406)
		(end 170.89628 -104.91597)
		(width 0.12954)
		(layer "F.Cu")
		(net "FM_SWB_PWR_EN")
	)
	(via
		(at 170.89628 -100.716588)
		(size 0.762)
		(drill 0.381)
		(layers "F.Cu" "B.Cu")
		(net "FM_SWB_PWR_EN")
	)
	(segment
		(start 173.355762 -108.975398)
		(end 172.955712 -108.575348)
		(width 0.12954)
		(layer "F.Cu")
		(net "FM_SWB_PWRGD_ISO_R")
	)
	(via
		(at 172.955712 -108.575348)
		(size 0.4572)
		(drill 0.254)
		(layers "F.Cu" "B.Cu")
		(net "FM_SWB_PWRGD_ISO_R")
	)
	(via
		(at 167.63238 -106.578908)
		(size 0.6604)
		(drill 0.3302)
		(layers "F.Cu" "B.Cu")
		(net "FM_SWB_PWRGD_ISO_R")
	)
	(segment
		(start 172.35678 -106.578908)
		(end 167.63238 -106.578908)
		(width 0.12954)
		(layer "B.Cu")
		(net "FM_SWB_PWRGD_ISO_R")
	)
	(segment
		(start 172.55998 -106.782108)
		(end 172.35678 -106.578908)
		(width 0.12954)
		(layer "B.Cu")
		(net "FM_SWB_PWRGD_ISO_R")
	)
	(segment
		(start 172.55998 -108.179616)
		(end 172.55998 -106.782108)
		(width 0.12954)
		(layer "B.Cu")
		(net "FM_SWB_PWRGD_ISO_R")
	)
	(segment
		(start 167.63238 -106.578908)
		(end 166.486586 -106.578908)
		(width 0.12954)
		(layer "B.Cu")
		(net "FM_SWB_PWRGD_ISO_R")
	)
	(segment
		(start 165.663626 -105.755948)
		(end 165.04793 -105.755948)
		(width 0.12954)
		(layer "B.Cu")
		(net "FM_SWB_PWRGD_ISO_R")
	)
	(segment
		(start 166.486586 -106.578908)
		(end 165.663626 -105.755948)
		(width 0.12954)
		(layer "B.Cu")
		(net "FM_SWB_PWRGD_ISO_R")
	)
	(segment
		(start 172.955712 -108.575348)
		(end 172.55998 -108.179616)
		(width 0.12954)
		(layer "B.Cu")
		(net "FM_SWB_PWRGD_ISO_R")
	)
	(segment
		(start 427.230032 -386.171948)
		(end 426.19422 -386.171948)
		(width 0.12954)
		(layer "F.Cu")
		(net "FM_SWB_PWRGD")
	)
	(segment
		(start 424.731942 -386.171948)
		(end 424.604942 -386.298948)
		(width 0.12954)
		(layer "F.Cu")
		(net "FM_SWB_PWRGD")
	)
	(segment
		(start 426.19422 -386.171948)
		(end 424.731942 -386.171948)
		(width 0.12954)
		(layer "F.Cu")
		(net "FM_SWB_PWRGD")
	)
	(segment
		(start 424.604942 -386.298948)
		(end 424.604942 -387.314948)
		(width 0.12954)
		(layer "F.Cu")
		(net "FM_SWB_PWRGD")
	)
	(via
		(at 426.19422 -386.171948)
		(size 0.508)
		(drill 0.254)
		(layers "F.Cu" "B.Cu")
		(net "FM_SWB_PWRGD")
	)
	(segment
		(start 388.17296 -419.814248)
		(end 412.66364 -419.814248)
		(width 0.12954)
		(layer "B.Cu")
		(net "FM_SWB_PWRGD")
	)
	(segment
		(start 386.02666 -440.489848)
		(end 386.9944 -439.522108)
		(width 0.12954)
		(layer "B.Cu")
		(net "FM_SWB_PWRGD")
	)
	(segment
		(start 386.9944 -420.992808)
		(end 388.17296 -419.814248)
		(width 0.12954)
		(layer "B.Cu")
		(net "FM_SWB_PWRGD")
	)
	(segment
		(start 425.7421 -406.735788)
		(end 425.7421 -386.624068)
		(width 0.12954)
		(layer "B.Cu")
		(net "FM_SWB_PWRGD")
	)
	(segment
		(start 386.9944 -439.522108)
		(end 386.9944 -420.992808)
		(width 0.12954)
		(layer "B.Cu")
		(net "FM_SWB_PWRGD")
	)
	(segment
		(start 385.750054 -440.489848)
		(end 386.02666 -440.489848)
		(width 0.12954)
		(layer "B.Cu")
		(net "FM_SWB_PWRGD")
	)
	(segment
		(start 412.66364 -419.814248)
		(end 425.7421 -406.735788)
		(width 0.12954)
		(layer "B.Cu")
		(net "FM_SWB_PWRGD")
	)
	(segment
		(start 425.7421 -386.624068)
		(end 426.19422 -386.171948)
		(width 0.12954)
		(layer "B.Cu")
		(net "FM_SWB_PWRGD")
	)
	(segment
		(start 426.29836 -391.505948)
		(end 424.731942 -391.505948)
		(width 0.12954)
		(layer "F.Cu")
		(net "FM_SWB_BIC_READY_N")
	)
	(segment
		(start 424.731942 -391.505948)
		(end 424.604942 -391.632948)
		(width 0.12954)
		(layer "F.Cu")
		(net "FM_SWB_BIC_READY_N")
	)
	(segment
		(start 424.604942 -391.632948)
		(end 424.604942 -392.648948)
		(width 0.12954)
		(layer "F.Cu")
		(net "FM_SWB_BIC_READY_N")
	)
	(segment
		(start 427.230032 -391.505948)
		(end 426.29836 -391.505948)
		(width 0.12954)
		(layer "F.Cu")
		(net "FM_SWB_BIC_READY_N")
	)
	(via
		(at 426.29836 -391.505948)
		(size 0.508)
		(drill 0.254)
		(layers "F.Cu" "B.Cu")
		(net "FM_SWB_BIC_READY_N")
	)
	(segment
		(start 404.750016 -424.689778)
		(end 404.750016 -423.869612)
		(width 0.12954)
		(layer "B.Cu")
		(net "FM_SWB_BIC_READY_N")
	)
	(segment
		(start 426.99178 -391.505948)
		(end 426.29836 -391.505948)
		(width 0.12954)
		(layer "B.Cu")
		(net "FM_SWB_BIC_READY_N")
	)
	(segment
		(start 427.3169 -391.831068)
		(end 426.99178 -391.505948)
		(width 0.12954)
		(layer "B.Cu")
		(net "FM_SWB_BIC_READY_N")
	)
	(segment
		(start 404.750016 -423.869612)
		(end 405.44242 -423.177208)
		(width 0.12954)
		(layer "B.Cu")
		(net "FM_SWB_BIC_READY_N")
	)
	(segment
		(start 410.82722 -423.177208)
		(end 427.3169 -406.687528)
		(width 0.12954)
		(layer "B.Cu")
		(net "FM_SWB_BIC_READY_N")
	)
	(segment
		(start 427.3169 -406.687528)
		(end 427.3169 -391.831068)
		(width 0.12954)
		(layer "B.Cu")
		(net "FM_SWB_BIC_READY_N")
	)
	(segment
		(start 405.44242 -423.177208)
		(end 410.82722 -423.177208)
		(width 0.12954)
		(layer "B.Cu")
		(net "FM_SWB_BIC_READY_N")
	)
	(segment
		(start 166.52748 -105.578148)
		(end 166.34968 -105.755948)
		(width 0.12954)
		(layer "F.Cu")
		(net "FM_SWB_BIC_READY_ISO_R_N")
	)
	(segment
		(start 167.11168 -106.162348)
		(end 166.52748 -105.578148)
		(width 0.12954)
		(layer "F.Cu")
		(net "FM_SWB_BIC_READY_ISO_R_N")
	)
	(segment
		(start 166.34968 -105.755948)
		(end 165.04793 -105.755948)
		(width 0.12954)
		(layer "F.Cu")
		(net "FM_SWB_BIC_READY_ISO_R_N")
	)
	(segment
		(start 170.955716 -106.575352)
		(end 170.542712 -106.162348)
		(width 0.12954)
		(layer "F.Cu")
		(net "FM_SWB_BIC_READY_ISO_R_N")
	)
	(segment
		(start 170.542712 -106.162348)
		(end 167.11168 -106.162348)
		(width 0.12954)
		(layer "F.Cu")
		(net "FM_SWB_BIC_READY_ISO_R_N")
	)
	(via
		(at 166.52748 -105.578148)
		(size 0.762)
		(drill 0.381)
		(layers "F.Cu" "B.Cu")
		(net "FM_SWB_BIC_READY_ISO_R_N")
	)
	(segment
		(start 198.8312 -129.193798)
		(end 198.8312 -129.870708)
		(width 0.12954)
		(layer "F.Cu")
		(net "FM_PCH_SPKR")
	)
	(segment
		(start 237.83798 -63.254128)
		(end 229.19436 -71.897748)
		(width 0.12954)
		(layer "F.Cu")
		(net "FM_PCH_SPKR")
	)
	(segment
		(start 229.19436 -71.897748)
		(end 227.27158 -71.897748)
		(width 0.12954)
		(layer "F.Cu")
		(net "FM_PCH_SPKR")
	)
	(segment
		(start 237.156244 -61.702188)
		(end 237.83798 -62.383924)
		(width 0.12954)
		(layer "F.Cu")
		(net "FM_PCH_SPKR")
	)
	(segment
		(start 130.450844 -22.301962)
		(end 130.10388 -21.954998)
		(width 0.12954)
		(layer "F.Cu")
		(net "FM_PCH_SPKR")
	)
	(segment
		(start 130.450844 -23.570946)
		(end 130.450844 -22.301962)
		(width 0.12954)
		(layer "F.Cu")
		(net "FM_PCH_SPKR")
	)
	(segment
		(start 198.8312 -129.870708)
		(end 198.9836 -130.023108)
		(width 0.12954)
		(layer "F.Cu")
		(net "FM_PCH_SPKR")
	)
	(segment
		(start 237.83798 -62.383924)
		(end 237.83798 -63.254128)
		(width 0.12954)
		(layer "F.Cu")
		(net "FM_PCH_SPKR")
	)
	(segment
		(start 128.78816 -21.954998)
		(end 130.10388 -21.954998)
		(width 0.12954)
		(layer "F.Cu")
		(net "FM_PCH_SPKR")
	)
	(segment
		(start 334.05064 -42.341546)
		(end 333.510382 -42.341546)
		(width 0.12954)
		(layer "F.Cu")
		(net "FM_PCH_SPKR")
	)
	(segment
		(start 128.78435 -21.951188)
		(end 128.78816 -21.954998)
		(width 0.12954)
		(layer "F.Cu")
		(net "FM_PCH_SPKR")
	)
	(via
		(at 337.013804 -35.286188)
		(size 0.6604)
		(drill 0.3302)
		(layers "F.Cu" "B.Cu")
		(net "FM_PCH_SPKR")
	)
	(via
		(at 131.619244 -35.514534)
		(size 0.508)
		(drill 0.254)
		(layers "F.Cu" "B.Cu")
		(net "FM_PCH_SPKR")
	)
	(via
		(at 237.156244 -61.702188)
		(size 0.508)
		(drill 0.254)
		(layers "F.Cu" "B.Cu")
		(net "FM_PCH_SPKR")
	)
	(via
		(at 198.9836 -130.023108)
		(size 0.508)
		(drill 0.254)
		(layers "F.Cu" "B.Cu")
		(net "FM_PCH_SPKR")
	)
	(via
		(at 130.450844 -23.570946)
		(size 0.508)
		(drill 0.254)
		(layers "F.Cu" "B.Cu")
		(net "FM_PCH_SPKR")
	)
	(via
		(at 227.27158 -71.897748)
		(size 0.508)
		(drill 0.254)
		(layers "F.Cu" "B.Cu")
		(net "FM_PCH_SPKR")
	)
	(via
		(at 338.454238 -34.018474)
		(size 0.508)
		(drill 0.254)
		(layers "F.Cu" "B.Cu")
		(net "FM_PCH_SPKR")
	)
	(via
		(at 333.510382 -42.341546)
		(size 0.4572)
		(drill 0.2032)
		(layers "F.Cu" "B.Cu")
		(net "FM_PCH_SPKR")
	)
	(segment
		(start 338.454238 -34.018474)
		(end 338.346542 -34.12617)
		(width 0.12954)
		(layer "B.Cu")
		(net "FM_PCH_SPKR")
	)
	(segment
		(start 333.82458 -40.25519)
		(end 333.835756 -40.274748)
		(width 0.0889)
		(layer "B.Cu")
		(net "FM_PCH_SPKR")
	)
	(segment
		(start 333.750158 -39.644574)
		(end 333.750158 -39.953692)
		(width 0.0889)
		(layer "B.Cu")
		(net "FM_PCH_SPKR")
	)
	(segment
		(start 335.713578 -36.99129)
		(end 335.713578 -37.868606)
		(width 0.12954)
		(layer "B.Cu")
		(net "FM_PCH_SPKR")
	)
	(segment
		(start 333.510636 -42.649648)
		(end 333.510382 -42.341546)
		(width 0.0889)
		(layer "B.Cu")
		(net "FM_PCH_SPKR")
	)
	(segment
		(start 334.20558 -39.189152)
		(end 333.750158 -39.644574)
		(width 0.0889)
		(layer "B.Cu")
		(net "FM_PCH_SPKR")
	)
	(segment
		(start 335.040224 -38.354508)
		(end 334.20558 -39.189152)
		(width 0.12954)
		(layer "B.Cu")
		(net "FM_PCH_SPKR")
	)
	(segment
		(start 337.013804 -35.691064)
		(end 335.713578 -36.99129)
		(width 0.12954)
		(layer "B.Cu")
		(net "FM_PCH_SPKR")
	)
	(segment
		(start 338.346542 -34.12617)
		(end 337.552284 -34.12617)
		(width 0.12954)
		(layer "B.Cu")
		(net "FM_PCH_SPKR")
	)
	(segment
		(start 335.227676 -38.354508)
		(end 335.040224 -38.354508)
		(width 0.12954)
		(layer "B.Cu")
		(net "FM_PCH_SPKR")
	)
	(segment
		(start 337.552284 -34.65068)
		(end 337.013804 -35.18916)
		(width 0.12954)
		(layer "B.Cu")
		(net "FM_PCH_SPKR")
	)
	(segment
		(start 337.013804 -35.18916)
		(end 337.013804 -35.286188)
		(width 0.12954)
		(layer "B.Cu")
		(net "FM_PCH_SPKR")
	)
	(segment
		(start 333.510636 -42.65422)
		(end 333.510636 -42.649648)
		(width 0.0889)
		(layer "B.Cu")
		(net "FM_PCH_SPKR")
	)
	(segment
		(start 337.552284 -34.12617)
		(end 337.552284 -34.65068)
		(width 0.12954)
		(layer "B.Cu")
		(net "FM_PCH_SPKR")
	)
	(segment
		(start 333.568294 -42.711878)
		(end 333.510636 -42.65422)
		(width 0.0889)
		(layer "B.Cu")
		(net "FM_PCH_SPKR")
	)
	(segment
		(start 335.713578 -37.868606)
		(end 335.227676 -38.354508)
		(width 0.12954)
		(layer "B.Cu")
		(net "FM_PCH_SPKR")
	)
	(segment
		(start 337.013804 -35.286188)
		(end 337.013804 -35.691064)
		(width 0.12954)
		(layer "B.Cu")
		(net "FM_PCH_SPKR")
	)
	(segment
		(start 333.835756 -41.588944)
		(end 333.82458 -41.608502)
		(width 0.0889)
		(layer "B.Cu")
		(net "FM_PCH_SPKR")
	)
	(arc
		(start 333.835248 -42.528744)
		(mid 333.722578 -42.650664)
		(end 333.568294 -42.711878)
		(width 0.0889)
		(layer "B.Cu")
		(net "FM_PCH_SPKR")
	)
	(arc
		(start 333.835756 -40.274748)
		(mid 333.885899 -40.461946)
		(end 333.835756 -40.649144)
		(width 0.0889)
		(layer "B.Cu")
		(net "FM_PCH_SPKR")
	)
	(arc
		(start 333.835248 -42.154348)
		(mid 333.885323 -42.341546)
		(end 333.835248 -42.528744)
		(width 0.0889)
		(layer "B.Cu")
		(net "FM_PCH_SPKR")
	)
	(arc
		(start 333.82458 -41.608502)
		(mid 333.759774 -41.882784)
		(end 333.835248 -42.154348)
		(width 0.0889)
		(layer "B.Cu")
		(net "FM_PCH_SPKR")
	)
	(arc
		(start 333.750158 -39.953692)
		(mid 333.769045 -40.108963)
		(end 333.82458 -40.25519)
		(width 0.0889)
		(layer "B.Cu")
		(net "FM_PCH_SPKR")
	)
	(arc
		(start 333.835756 -41.214548)
		(mid 333.885899 -41.401746)
		(end 333.835756 -41.588944)
		(width 0.0889)
		(layer "B.Cu")
		(net "FM_PCH_SPKR")
	)
	(arc
		(start 333.835756 -40.649144)
		(mid 333.760014 -40.931846)
		(end 333.835756 -41.214548)
		(width 0.0889)
		(layer "B.Cu")
		(net "FM_PCH_SPKR")
	)
	(segment
		(start 131.619244 -28.10383)
		(end 132.70992 -27.013154)
		(width 0.127)
		(layer "In2.Cu")
		(net "FM_PCH_SPKR")
	)
	(segment
		(start 132.70992 -27.013154)
		(end 132.70992 -25.25776)
		(width 0.127)
		(layer "In2.Cu")
		(net "FM_PCH_SPKR")
	)
	(segment
		(start 131.619244 -35.514534)
		(end 131.619244 -28.10383)
		(width 0.127)
		(layer "In2.Cu")
		(net "FM_PCH_SPKR")
	)
	(segment
		(start 132.70992 -25.25776)
		(end 131.8387 -24.38654)
		(width 0.127)
		(layer "In2.Cu")
		(net "FM_PCH_SPKR")
	)
	(segment
		(start 131.8387 -24.38654)
		(end 131.8387 -23.338028)
		(width 0.127)
		(layer "In2.Cu")
		(net "FM_PCH_SPKR")
	)
	(segment
		(start 131.629912 -23.12924)
		(end 130.89255 -23.12924)
		(width 0.127)
		(layer "In2.Cu")
		(net "FM_PCH_SPKR")
	)
	(segment
		(start 131.8387 -23.338028)
		(end 131.629912 -23.12924)
		(width 0.127)
		(layer "In2.Cu")
		(net "FM_PCH_SPKR")
	)
	(segment
		(start 130.89255 -23.12924)
		(end 130.450844 -23.570946)
		(width 0.127)
		(layer "In2.Cu")
		(net "FM_PCH_SPKR")
	)
	(segment
		(start 200.83526 -128.171448)
		(end 211.28228 -128.171448)
		(width 0.127)
		(layer "In4.Cu")
		(net "FM_PCH_SPKR")
	)
	(segment
		(start 319.90284 -35.207448)
		(end 323.117972 -38.42258)
		(width 0.127)
		(layer "In4.Cu")
		(net "FM_PCH_SPKR")
	)
	(segment
		(start 327.14565 -38.120828)
		(end 331.647292 -38.120828)
		(width 0.127)
		(layer "In4.Cu")
		(net "FM_PCH_SPKR")
	)
	(segment
		(start 335.749646 -34.018474)
		(end 338.454238 -34.018474)
		(width 0.127)
		(layer "In4.Cu")
		(net "FM_PCH_SPKR")
	)
	(segment
		(start 224.028 -99.193604)
		(end 223.11106 -98.276664)
		(width 0.127)
		(layer "In4.Cu")
		(net "FM_PCH_SPKR")
	)
	(segment
		(start 218.089988 -118.4656)
		(end 224.028 -112.527588)
		(width 0.127)
		(layer "In4.Cu")
		(net "FM_PCH_SPKR")
	)
	(segment
		(start 293.101268 -37.700966)
		(end 305.713638 -37.700966)
		(width 0.127)
		(layer "In4.Cu")
		(net "FM_PCH_SPKR")
	)
	(segment
		(start 271.602962 -62.436756)
		(end 276.127972 -59.41314)
		(width 0.127)
		(layer "In4.Cu")
		(net "FM_PCH_SPKR")
	)
	(segment
		(start 276.127972 -59.41314)
		(end 277.871936 -57.669176)
		(width 0.127)
		(layer "In4.Cu")
		(net "FM_PCH_SPKR")
	)
	(segment
		(start 223.11106 -98.276664)
		(end 223.11106 -81.549748)
		(width 0.127)
		(layer "In4.Cu")
		(net "FM_PCH_SPKR")
	)
	(segment
		(start 212.44814 -120.21566)
		(end 214.1982 -118.4656)
		(width 0.127)
		(layer "In4.Cu")
		(net "FM_PCH_SPKR")
	)
	(segment
		(start 331.647292 -38.120828)
		(end 335.749646 -34.018474)
		(width 0.127)
		(layer "In4.Cu")
		(net "FM_PCH_SPKR")
	)
	(segment
		(start 212.44814 -127.005588)
		(end 212.44814 -120.21566)
		(width 0.127)
		(layer "In4.Cu")
		(net "FM_PCH_SPKR")
	)
	(segment
		(start 308.793896 -34.620708)
		(end 312.90768 -34.620708)
		(width 0.127)
		(layer "In4.Cu")
		(net "FM_PCH_SPKR")
	)
	(segment
		(start 224.028 -112.527588)
		(end 224.028 -99.193604)
		(width 0.127)
		(layer "In4.Cu")
		(net "FM_PCH_SPKR")
	)
	(segment
		(start 237.470696 -62.032642)
		(end 239.075722 -63.637668)
		(width 0.127)
		(layer "In4.Cu")
		(net "FM_PCH_SPKR")
	)
	(segment
		(start 305.713638 -37.700966)
		(end 308.793896 -34.620708)
		(width 0.127)
		(layer "In4.Cu")
		(net "FM_PCH_SPKR")
	)
	(segment
		(start 268.703806 -63.637668)
		(end 271.602962 -62.436756)
		(width 0.127)
		(layer "In4.Cu")
		(net "FM_PCH_SPKR")
	)
	(segment
		(start 313.49442 -35.207448)
		(end 319.90284 -35.207448)
		(width 0.127)
		(layer "In4.Cu")
		(net "FM_PCH_SPKR")
	)
	(segment
		(start 323.117972 -38.42258)
		(end 326.843898 -38.42258)
		(width 0.127)
		(layer "In4.Cu")
		(net "FM_PCH_SPKR")
	)
	(segment
		(start 281.222958 -49.579276)
		(end 293.101268 -37.700966)
		(width 0.127)
		(layer "In4.Cu")
		(net "FM_PCH_SPKR")
	)
	(segment
		(start 326.843898 -38.42258)
		(end 327.14565 -38.120828)
		(width 0.127)
		(layer "In4.Cu")
		(net "FM_PCH_SPKR")
	)
	(segment
		(start 214.1982 -118.4656)
		(end 218.089988 -118.4656)
		(width 0.127)
		(layer "In4.Cu")
		(net "FM_PCH_SPKR")
	)
	(segment
		(start 237.156244 -61.702188)
		(end 237.470696 -62.01664)
		(width 0.127)
		(layer "In4.Cu")
		(net "FM_PCH_SPKR")
	)
	(segment
		(start 239.075722 -63.637668)
		(end 268.703806 -63.637668)
		(width 0.127)
		(layer "In4.Cu")
		(net "FM_PCH_SPKR")
	)
	(segment
		(start 312.90768 -34.620708)
		(end 313.49442 -35.207448)
		(width 0.127)
		(layer "In4.Cu")
		(net "FM_PCH_SPKR")
	)
	(segment
		(start 227.27158 -77.389228)
		(end 227.27158 -71.897748)
		(width 0.127)
		(layer "In4.Cu")
		(net "FM_PCH_SPKR")
	)
	(segment
		(start 198.9836 -130.023108)
		(end 200.83526 -128.171448)
		(width 0.127)
		(layer "In4.Cu")
		(net "FM_PCH_SPKR")
	)
	(segment
		(start 211.28228 -128.171448)
		(end 212.44814 -127.005588)
		(width 0.127)
		(layer "In4.Cu")
		(net "FM_PCH_SPKR")
	)
	(segment
		(start 277.871936 -57.669176)
		(end 281.222958 -49.579276)
		(width 0.127)
		(layer "In4.Cu")
		(net "FM_PCH_SPKR")
	)
	(segment
		(start 223.11106 -81.549748)
		(end 227.27158 -77.389228)
		(width 0.127)
		(layer "In4.Cu")
		(net "FM_PCH_SPKR")
	)
	(segment
		(start 237.470696 -62.01664)
		(end 237.470696 -62.032642)
		(width 0.127)
		(layer "In4.Cu")
		(net "FM_PCH_SPKR")
	)
	(segment
		(start 236.657134 -61.053472)
		(end 237.026958 -61.423296)
		(width 0.127)
		(layer "In13.Cu")
		(net "FM_PCH_SPKR")
	)
	(segment
		(start 233.964734 -59.136534)
		(end 235.68787 -59.136534)
		(width 0.127)
		(layer "In13.Cu")
		(net "FM_PCH_SPKR")
	)
	(segment
		(start 142.959836 -38.53053)
		(end 142.959836 -39.876476)
		(width 0.127)
		(layer "In13.Cu")
		(net "FM_PCH_SPKR")
	)
	(segment
		(start 179.598828 -44.421298)
		(end 180.718968 -43.301158)
		(width 0.127)
		(layer "In13.Cu")
		(net "FM_PCH_SPKR")
	)
	(segment
		(start 223.367346 -50.452528)
		(end 223.75495 -50.840132)
		(width 0.127)
		(layer "In13.Cu")
		(net "FM_PCH_SPKR")
	)
	(segment
		(start 157.886908 -43.624246)
		(end 159.480758 -42.030396)
		(width 0.127)
		(layer "In13.Cu")
		(net "FM_PCH_SPKR")
	)
	(segment
		(start 139.94384 -35.514534)
		(end 142.959836 -38.53053)
		(width 0.127)
		(layer "In13.Cu")
		(net "FM_PCH_SPKR")
	)
	(segment
		(start 176.60493 -44.421298)
		(end 179.598828 -44.421298)
		(width 0.127)
		(layer "In13.Cu")
		(net "FM_PCH_SPKR")
	)
	(segment
		(start 222.71228 -50.452528)
		(end 223.367346 -50.452528)
		(width 0.127)
		(layer "In13.Cu")
		(net "FM_PCH_SPKR")
	)
	(segment
		(start 196.05498 -43.301412)
		(end 196.916548 -42.439844)
		(width 0.127)
		(layer "In13.Cu")
		(net "FM_PCH_SPKR")
	)
	(segment
		(start 175.03267 -42.849038)
		(end 176.60493 -44.421298)
		(width 0.127)
		(layer "In13.Cu")
		(net "FM_PCH_SPKR")
	)
	(segment
		(start 223.75495 -50.840132)
		(end 223.75495 -54.781958)
		(width 0.127)
		(layer "In13.Cu")
		(net "FM_PCH_SPKR")
	)
	(segment
		(start 228.299772 -59.32678)
		(end 228.87432 -59.32678)
		(width 0.127)
		(layer "In13.Cu")
		(net "FM_PCH_SPKR")
	)
	(segment
		(start 161.35477 -42.030396)
		(end 162.173412 -42.849038)
		(width 0.127)
		(layer "In13.Cu")
		(net "FM_PCH_SPKR")
	)
	(segment
		(start 236.657134 -60.105798)
		(end 236.657134 -61.053472)
		(width 0.127)
		(layer "In13.Cu")
		(net "FM_PCH_SPKR")
	)
	(segment
		(start 228.87432 -59.32678)
		(end 229.89032 -60.34278)
		(width 0.127)
		(layer "In13.Cu")
		(net "FM_PCH_SPKR")
	)
	(segment
		(start 235.68787 -59.136534)
		(end 236.657134 -60.105798)
		(width 0.127)
		(layer "In13.Cu")
		(net "FM_PCH_SPKR")
	)
	(segment
		(start 190.17488 -43.301158)
		(end 190.777876 -42.698162)
		(width 0.127)
		(layer "In13.Cu")
		(net "FM_PCH_SPKR")
	)
	(segment
		(start 180.718968 -43.301158)
		(end 190.17488 -43.301158)
		(width 0.127)
		(layer "In13.Cu")
		(net "FM_PCH_SPKR")
	)
	(segment
		(start 222.019368 -51.14544)
		(end 222.71228 -50.452528)
		(width 0.127)
		(layer "In13.Cu")
		(net "FM_PCH_SPKR")
	)
	(segment
		(start 194.913504 -42.698162)
		(end 195.516754 -43.301412)
		(width 0.127)
		(layer "In13.Cu")
		(net "FM_PCH_SPKR")
	)
	(segment
		(start 142.959836 -39.876476)
		(end 145.910554 -42.827194)
		(width 0.127)
		(layer "In13.Cu")
		(net "FM_PCH_SPKR")
	)
	(segment
		(start 232.758488 -60.34278)
		(end 233.964734 -59.136534)
		(width 0.127)
		(layer "In13.Cu")
		(net "FM_PCH_SPKR")
	)
	(segment
		(start 195.516754 -43.301412)
		(end 196.05498 -43.301412)
		(width 0.127)
		(layer "In13.Cu")
		(net "FM_PCH_SPKR")
	)
	(segment
		(start 229.89032 -60.34278)
		(end 232.758488 -60.34278)
		(width 0.127)
		(layer "In13.Cu")
		(net "FM_PCH_SPKR")
	)
	(segment
		(start 237.156244 -61.550296)
		(end 237.156244 -61.702188)
		(width 0.127)
		(layer "In13.Cu")
		(net "FM_PCH_SPKR")
	)
	(segment
		(start 145.910554 -42.827194)
		(end 152.416002 -42.827194)
		(width 0.127)
		(layer "In13.Cu")
		(net "FM_PCH_SPKR")
	)
	(segment
		(start 131.619244 -35.514534)
		(end 139.94384 -35.514534)
		(width 0.127)
		(layer "In13.Cu")
		(net "FM_PCH_SPKR")
	)
	(segment
		(start 220.39326 -51.14544)
		(end 222.019368 -51.14544)
		(width 0.127)
		(layer "In13.Cu")
		(net "FM_PCH_SPKR")
	)
	(segment
		(start 153.213054 -43.624246)
		(end 157.886908 -43.624246)
		(width 0.127)
		(layer "In13.Cu")
		(net "FM_PCH_SPKR")
	)
	(segment
		(start 219.700348 -50.452528)
		(end 220.39326 -51.14544)
		(width 0.127)
		(layer "In13.Cu")
		(net "FM_PCH_SPKR")
	)
	(segment
		(start 237.026958 -61.423296)
		(end 237.029244 -61.423296)
		(width 0.127)
		(layer "In13.Cu")
		(net "FM_PCH_SPKR")
	)
	(segment
		(start 190.777876 -42.698162)
		(end 194.913504 -42.698162)
		(width 0.127)
		(layer "In13.Cu")
		(net "FM_PCH_SPKR")
	)
	(segment
		(start 223.75495 -54.781958)
		(end 228.299772 -59.32678)
		(width 0.127)
		(layer "In13.Cu")
		(net "FM_PCH_SPKR")
	)
	(segment
		(start 217.551508 -50.452528)
		(end 219.700348 -50.452528)
		(width 0.127)
		(layer "In13.Cu")
		(net "FM_PCH_SPKR")
	)
	(segment
		(start 237.029244 -61.423296)
		(end 237.156244 -61.550296)
		(width 0.127)
		(layer "In13.Cu")
		(net "FM_PCH_SPKR")
	)
	(segment
		(start 209.538824 -42.439844)
		(end 217.551508 -50.452528)
		(width 0.127)
		(layer "In13.Cu")
		(net "FM_PCH_SPKR")
	)
	(segment
		(start 196.916548 -42.439844)
		(end 209.538824 -42.439844)
		(width 0.127)
		(layer "In13.Cu")
		(net "FM_PCH_SPKR")
	)
	(segment
		(start 159.480758 -42.030396)
		(end 161.35477 -42.030396)
		(width 0.127)
		(layer "In13.Cu")
		(net "FM_PCH_SPKR")
	)
	(segment
		(start 162.173412 -42.849038)
		(end 175.03267 -42.849038)
		(width 0.127)
		(layer "In13.Cu")
		(net "FM_PCH_SPKR")
	)
	(segment
		(start 152.416002 -42.827194)
		(end 153.213054 -43.624246)
		(width 0.127)
		(layer "In13.Cu")
		(net "FM_PCH_SPKR")
	)
	(segment
		(start 174.155608 -109.775498)
		(end 173.755558 -109.375448)
		(width 0.12954)
		(layer "F.Cu")
		(net "FM_GPU_PWRGD_ISO_R")
	)
	(via
		(at 173.755558 -109.375448)
		(size 0.4572)
		(drill 0.254)
		(layers "F.Cu" "B.Cu")
		(net "FM_GPU_PWRGD_ISO_R")
	)
	(via
		(at 166.24554 -109.565948)
		(size 0.6604)
		(drill 0.3302)
		(layers "F.Cu" "B.Cu")
		(net "FM_GPU_PWRGD_ISO_R")
	)
	(segment
		(start 173.755558 -109.375448)
		(end 173.356778 -108.976668)
		(width 0.12954)
		(layer "B.Cu")
		(net "FM_GPU_PWRGD_ISO_R")
	)
	(segment
		(start 170.59656 -108.577888)
		(end 168.206166 -108.577888)
		(width 0.12954)
		(layer "B.Cu")
		(net "FM_GPU_PWRGD_ISO_R")
	)
	(segment
		(start 173.356778 -108.976668)
		(end 170.99534 -108.976668)
		(width 0.12954)
		(layer "B.Cu")
		(net "FM_GPU_PWRGD_ISO_R")
	)
	(segment
		(start 167.218106 -109.565948)
		(end 166.24554 -109.565948)
		(width 0.12954)
		(layer "B.Cu")
		(net "FM_GPU_PWRGD_ISO_R")
	)
	(segment
		(start 166.24554 -109.565948)
		(end 165.04793 -109.565948)
		(width 0.12954)
		(layer "B.Cu")
		(net "FM_GPU_PWRGD_ISO_R")
	)
	(segment
		(start 170.99534 -108.976668)
		(end 170.59656 -108.577888)
		(width 0.12954)
		(layer "B.Cu")
		(net "FM_GPU_PWRGD_ISO_R")
	)
	(segment
		(start 168.206166 -108.577888)
		(end 167.218106 -109.565948)
		(width 0.12954)
		(layer "B.Cu")
		(net "FM_GPU_PWRGD_ISO_R")
	)
	(segment
		(start 184.555638 -117.775482)
		(end 184.955688 -118.175532)
		(width 0.12954)
		(layer "F.Cu")
		(net "CLK_SWB_OE_N")
	)
	(via
		(at 184.955688 -118.175532)
		(size 0.4572)
		(drill 0.254)
		(layers "F.Cu" "B.Cu")
		(net "CLK_SWB_OE_N")
	)
	(via
		(at 14.62913 -153.282904)
		(size 0.508)
		(drill 0.254)
		(layers "F.Cu" "B.Cu")
		(net "CLK_SWB_OE_N")
	)
	(via
		(at 47.038514 -127.619506)
		(size 0.508)
		(drill 0.254)
		(layers "F.Cu" "B.Cu")
		(net "CLK_SWB_OE_N")
	)
	(via
		(at 181.82844 -148.72716)
		(size 0.508)
		(drill 0.254)
		(layers "F.Cu" "B.Cu")
		(net "CLK_SWB_OE_N")
	)
	(via
		(at 225.44786 -119.774208)
		(size 0.508)
		(drill 0.254)
		(layers "F.Cu" "B.Cu")
		(net "CLK_SWB_OE_N")
	)
	(segment
		(start 228.41966 -128.600708)
		(end 227.76942 -128.600708)
		(width 0.12954)
		(layer "B.Cu")
		(net "CLK_SWB_OE_N")
	)
	(segment
		(start 15.701518 -152.210516)
		(end 14.62913 -153.282904)
		(width 0.12954)
		(layer "B.Cu")
		(net "CLK_SWB_OE_N")
	)
	(segment
		(start 19.47926 -152.210516)
		(end 15.701518 -152.210516)
		(width 0.12954)
		(layer "B.Cu")
		(net "CLK_SWB_OE_N")
	)
	(segment
		(start 227.76942 -128.600708)
		(end 227.623878 -128.74625)
		(width 0.12954)
		(layer "B.Cu")
		(net "CLK_SWB_OE_N")
	)
	(segment
		(start 47.038514 -127.619506)
		(end 47.038514 -131.951222)
		(width 0.12954)
		(layer "B.Cu")
		(net "CLK_SWB_OE_N")
	)
	(segment
		(start 229.49027 -127.922274)
		(end 229.069646 -127.922274)
		(width 0.12954)
		(layer "B.Cu")
		(net "CLK_SWB_OE_N")
	)
	(segment
		(start 222.534988 -129.275586)
		(end 223.029526 -129.770124)
		(width 0.12954)
		(layer "B.Cu")
		(net "CLK_SWB_OE_N")
	)
	(segment
		(start 223.029526 -129.770124)
		(end 224.385124 -129.770124)
		(width 0.12954)
		(layer "B.Cu")
		(net "CLK_SWB_OE_N")
	)
	(segment
		(start 224.385124 -129.770124)
		(end 224.83699 -129.318258)
		(width 0.12954)
		(layer "B.Cu")
		(net "CLK_SWB_OE_N")
	)
	(segment
		(start 228.6254 -128.394968)
		(end 228.41966 -128.600708)
		(width 0.12954)
		(layer "B.Cu")
		(net "CLK_SWB_OE_N")
	)
	(segment
		(start 222.534988 -122.68708)
		(end 222.534988 -129.275586)
		(width 0.12954)
		(layer "B.Cu")
		(net "CLK_SWB_OE_N")
	)
	(segment
		(start 47.038514 -131.951222)
		(end 39.326566 -139.66317)
		(width 0.12954)
		(layer "B.Cu")
		(net "CLK_SWB_OE_N")
	)
	(segment
		(start 227.471224 -129.184146)
		(end 227.471224 -128.74625)
		(width 0.12954)
		(layer "B.Cu")
		(net "CLK_SWB_OE_N")
	)
	(segment
		(start 228.6254 -128.36652)
		(end 228.6254 -128.394968)
		(width 0.12954)
		(layer "B.Cu")
		(net "CLK_SWB_OE_N")
	)
	(segment
		(start 39.326566 -139.66317)
		(end 32.026606 -139.66317)
		(width 0.12954)
		(layer "B.Cu")
		(net "CLK_SWB_OE_N")
	)
	(segment
		(start 32.026606 -139.66317)
		(end 19.47926 -152.210516)
		(width 0.12954)
		(layer "B.Cu")
		(net "CLK_SWB_OE_N")
	)
	(segment
		(start 227.337112 -129.318258)
		(end 227.471224 -129.184146)
		(width 0.12954)
		(layer "B.Cu")
		(net "CLK_SWB_OE_N")
	)
	(segment
		(start 224.83699 -129.318258)
		(end 227.337112 -129.318258)
		(width 0.12954)
		(layer "B.Cu")
		(net "CLK_SWB_OE_N")
	)
	(segment
		(start 227.623878 -128.74625)
		(end 227.471224 -128.74625)
		(width 0.12954)
		(layer "B.Cu")
		(net "CLK_SWB_OE_N")
	)
	(segment
		(start 229.069646 -127.922274)
		(end 228.6254 -128.36652)
		(width 0.12954)
		(layer "B.Cu")
		(net "CLK_SWB_OE_N")
	)
	(segment
		(start 225.44786 -119.774208)
		(end 222.534988 -122.68708)
		(width 0.12954)
		(layer "B.Cu")
		(net "CLK_SWB_OE_N")
	)
	(segment
		(start 185.35396 -121.643648)
		(end 185.40476 -121.694448)
		(width 0.127)
		(layer "In11.Cu")
		(net "CLK_SWB_OE_N")
	)
	(segment
		(start 185.13552 -120.175528)
		(end 185.35396 -120.393968)
		(width 0.127)
		(layer "In11.Cu")
		(net "CLK_SWB_OE_N")
	)
	(segment
		(start 185.40476 -121.694448)
		(end 185.40476 -126.014988)
		(width 0.127)
		(layer "In11.Cu")
		(net "CLK_SWB_OE_N")
	)
	(segment
		(start 184.78754 -120.175528)
		(end 185.13552 -120.175528)
		(width 0.127)
		(layer "In11.Cu")
		(net "CLK_SWB_OE_N")
	)
	(segment
		(start 185.40476 -126.014988)
		(end 184.26938 -127.150368)
		(width 0.127)
		(layer "In11.Cu")
		(net "CLK_SWB_OE_N")
	)
	(segment
		(start 184.56148 -119.949468)
		(end 184.78754 -120.175528)
		(width 0.127)
		(layer "In11.Cu")
		(net "CLK_SWB_OE_N")
	)
	(segment
		(start 184.26938 -139.285726)
		(end 181.82844 -141.726666)
		(width 0.127)
		(layer "In11.Cu")
		(net "CLK_SWB_OE_N")
	)
	(segment
		(start 184.26938 -127.150368)
		(end 184.26938 -139.285726)
		(width 0.127)
		(layer "In11.Cu")
		(net "CLK_SWB_OE_N")
	)
	(segment
		(start 184.955688 -118.41734)
		(end 184.56148 -118.811548)
		(width 0.127)
		(layer "In11.Cu")
		(net "CLK_SWB_OE_N")
	)
	(segment
		(start 184.56148 -118.811548)
		(end 184.56148 -119.949468)
		(width 0.127)
		(layer "In11.Cu")
		(net "CLK_SWB_OE_N")
	)
	(segment
		(start 184.955688 -118.175532)
		(end 184.955688 -118.41734)
		(width 0.127)
		(layer "In11.Cu")
		(net "CLK_SWB_OE_N")
	)
	(segment
		(start 181.82844 -141.726666)
		(end 181.82844 -148.72716)
		(width 0.127)
		(layer "In11.Cu")
		(net "CLK_SWB_OE_N")
	)
	(segment
		(start 185.35396 -120.393968)
		(end 185.35396 -121.643648)
		(width 0.127)
		(layer "In11.Cu")
		(net "CLK_SWB_OE_N")
	)
	(segment
		(start 185.5724 -117.7798)
		(end 185.970926 -117.7798)
		(width 0.127)
		(layer "In15.Cu")
		(net "CLK_SWB_OE_N")
	)
	(segment
		(start 202.31608 -125.286008)
		(end 204.33538 -125.286008)
		(width 0.127)
		(layer "In15.Cu")
		(net "CLK_SWB_OE_N")
	)
	(segment
		(start 220.941392 -119.774208)
		(end 225.44786 -119.774208)
		(width 0.127)
		(layer "In15.Cu")
		(net "CLK_SWB_OE_N")
	)
	(segment
		(start 192.327022 -122.175524)
		(end 193.074544 -122.923046)
		(width 0.127)
		(layer "In15.Cu")
		(net "CLK_SWB_OE_N")
	)
	(segment
		(start 216.783412 -123.932188)
		(end 220.941392 -119.774208)
		(width 0.127)
		(layer "In15.Cu")
		(net "CLK_SWB_OE_N")
	)
	(segment
		(start 187.827666 -118.548912)
		(end 191.454278 -122.175524)
		(width 0.127)
		(layer "In15.Cu")
		(net "CLK_SWB_OE_N")
	)
	(segment
		(start 204.33538 -125.286008)
		(end 204.98562 -125.936248)
		(width 0.127)
		(layer "In15.Cu")
		(net "CLK_SWB_OE_N")
	)
	(segment
		(start 206.44358 -125.936248)
		(end 208.44764 -123.932188)
		(width 0.127)
		(layer "In15.Cu")
		(net "CLK_SWB_OE_N")
	)
	(segment
		(start 201.66584 -125.936248)
		(end 202.31608 -125.286008)
		(width 0.127)
		(layer "In15.Cu")
		(net "CLK_SWB_OE_N")
	)
	(segment
		(start 194.628262 -125.936248)
		(end 201.66584 -125.936248)
		(width 0.127)
		(layer "In15.Cu")
		(net "CLK_SWB_OE_N")
	)
	(segment
		(start 193.074544 -124.38253)
		(end 194.628262 -125.936248)
		(width 0.127)
		(layer "In15.Cu")
		(net "CLK_SWB_OE_N")
	)
	(segment
		(start 136.69645 -148.354542)
		(end 102.771194 -148.354542)
		(width 0.127)
		(layer "In15.Cu")
		(net "CLK_SWB_OE_N")
	)
	(segment
		(start 185.176668 -118.175532)
		(end 185.5724 -117.7798)
		(width 0.127)
		(layer "In15.Cu")
		(net "CLK_SWB_OE_N")
	)
	(segment
		(start 193.074544 -122.923046)
		(end 193.074544 -124.38253)
		(width 0.127)
		(layer "In15.Cu")
		(net "CLK_SWB_OE_N")
	)
	(segment
		(start 185.970926 -117.7798)
		(end 186.851544 -118.144544)
		(width 0.127)
		(layer "In15.Cu")
		(net "CLK_SWB_OE_N")
	)
	(segment
		(start 102.771194 -148.354542)
		(end 82.036158 -127.619506)
		(width 0.127)
		(layer "In15.Cu")
		(net "CLK_SWB_OE_N")
	)
	(segment
		(start 141.923008 -146.763994)
		(end 138.286998 -146.763994)
		(width 0.127)
		(layer "In15.Cu")
		(net "CLK_SWB_OE_N")
	)
	(segment
		(start 175.619664 -148.269452)
		(end 143.428466 -148.269452)
		(width 0.127)
		(layer "In15.Cu")
		(net "CLK_SWB_OE_N")
	)
	(segment
		(start 184.955688 -118.175532)
		(end 185.176668 -118.175532)
		(width 0.127)
		(layer "In15.Cu")
		(net "CLK_SWB_OE_N")
	)
	(segment
		(start 176.077372 -148.72716)
		(end 175.619664 -148.269452)
		(width 0.127)
		(layer "In15.Cu")
		(net "CLK_SWB_OE_N")
	)
	(segment
		(start 191.454278 -122.175524)
		(end 192.327022 -122.175524)
		(width 0.127)
		(layer "In15.Cu")
		(net "CLK_SWB_OE_N")
	)
	(segment
		(start 204.98562 -125.936248)
		(end 206.44358 -125.936248)
		(width 0.127)
		(layer "In15.Cu")
		(net "CLK_SWB_OE_N")
	)
	(segment
		(start 208.44764 -123.932188)
		(end 216.783412 -123.932188)
		(width 0.127)
		(layer "In15.Cu")
		(net "CLK_SWB_OE_N")
	)
	(segment
		(start 181.82844 -148.72716)
		(end 176.077372 -148.72716)
		(width 0.127)
		(layer "In15.Cu")
		(net "CLK_SWB_OE_N")
	)
	(segment
		(start 138.286998 -146.763994)
		(end 136.69645 -148.354542)
		(width 0.127)
		(layer "In15.Cu")
		(net "CLK_SWB_OE_N")
	)
	(segment
		(start 186.851544 -118.144544)
		(end 187.827666 -118.548912)
		(width 0.127)
		(layer "In15.Cu")
		(net "CLK_SWB_OE_N")
	)
	(segment
		(start 82.036158 -127.619506)
		(end 47.038514 -127.619506)
		(width 0.127)
		(layer "In15.Cu")
		(net "CLK_SWB_OE_N")
	)
	(segment
		(start 143.428466 -148.269452)
		(end 141.923008 -146.763994)
		(width 0.127)
		(layer "In15.Cu")
		(net "CLK_SWB_OE_N")
	)
	(segment
		(start 119.403368 -38.005512)
		(end 119.714264 -38.005512)
		(width 0.12954)
		(layer "F.Cu")
		(net "CLK_GEN2_GPU_FPGA_OE_R2_N")
	)
	(segment
		(start 117.937534 -38.065456)
		(end 119.343424 -38.065456)
		(width 0.12954)
		(layer "F.Cu")
		(net "CLK_GEN2_GPU_FPGA_OE_R2_N")
	)
	(segment
		(start 114.888772 -37.450268)
		(end 114.282474 -38.056566)
		(width 0.12954)
		(layer "F.Cu")
		(net "CLK_GEN2_GPU_FPGA_OE_R2_N")
	)
	(segment
		(start 114.282474 -38.056566)
		(end 114.282474 -37.01034)
		(width 0.12954)
		(layer "F.Cu")
		(net "CLK_GEN2_GPU_FPGA_OE_R2_N")
	)
	(segment
		(start 119.343424 -38.065456)
		(end 119.403368 -38.005512)
		(width 0.12954)
		(layer "F.Cu")
		(net "CLK_GEN2_GPU_FPGA_OE_R2_N")
	)
	(segment
		(start 116.559584 -38.065456)
		(end 115.944396 -37.450268)
		(width 0.12954)
		(layer "F.Cu")
		(net "CLK_GEN2_GPU_FPGA_OE_R2_N")
	)
	(segment
		(start 116.559584 -38.065456)
		(end 117.937534 -38.065456)
		(width 0.12954)
		(layer "F.Cu")
		(net "CLK_GEN2_GPU_FPGA_OE_R2_N")
	)
	(segment
		(start 114.282474 -38.056566)
		(end 114.273584 -38.065456)
		(width 0.12954)
		(layer "F.Cu")
		(net "CLK_GEN2_GPU_FPGA_OE_R2_N")
	)
	(segment
		(start 115.944396 -37.450268)
		(end 114.888772 -37.450268)
		(width 0.12954)
		(layer "F.Cu")
		(net "CLK_GEN2_GPU_FPGA_OE_R2_N")
	)
	(via
		(at 117.937534 -38.065456)
		(size 0.762)
		(drill 0.381)
		(layers "F.Cu" "B.Cu")
		(net "CLK_GEN2_GPU_FPGA_OE_R2_N")
	)
	(segment
		(start 197.104 -93.201998)
		(end 197.104 -93.894148)
		(width 0.12954)
		(layer "F.Cu")
		(net "CLK_GEN2_GPU_FPGA_OE_N")
	)
	(segment
		(start 113.473484 -38.065456)
		(end 113.473484 -38.776148)
		(width 0.12954)
		(layer "F.Cu")
		(net "CLK_GEN2_GPU_FPGA_OE_N")
	)
	(via
		(at 113.473484 -38.776148)
		(size 0.508)
		(drill 0.254)
		(layers "F.Cu" "B.Cu")
		(net "CLK_GEN2_GPU_FPGA_OE_N")
	)
	(via
		(at 197.104 -93.894148)
		(size 0.508)
		(drill 0.254)
		(layers "F.Cu" "B.Cu")
		(net "CLK_GEN2_GPU_FPGA_OE_N")
	)
	(segment
		(start 114.591592 -66.958464)
		(end 113.473484 -65.840356)
		(width 0.127)
		(layer "In15.Cu")
		(net "CLK_GEN2_GPU_FPGA_OE_N")
	)
	(segment
		(start 189.641226 -87.862664)
		(end 180.250592 -87.862664)
		(width 0.127)
		(layer "In15.Cu")
		(net "CLK_GEN2_GPU_FPGA_OE_N")
	)
	(segment
		(start 196.6341 -93.424248)
		(end 195.20281 -93.424248)
		(width 0.127)
		(layer "In15.Cu")
		(net "CLK_GEN2_GPU_FPGA_OE_N")
	)
	(segment
		(start 135.952992 -71.606664)
		(end 131.304792 -66.958464)
		(width 0.127)
		(layer "In15.Cu")
		(net "CLK_GEN2_GPU_FPGA_OE_N")
	)
	(segment
		(start 197.104 -93.894148)
		(end 196.6341 -93.424248)
		(width 0.127)
		(layer "In15.Cu")
		(net "CLK_GEN2_GPU_FPGA_OE_N")
	)
	(segment
		(start 195.20281 -93.424248)
		(end 189.641226 -87.862664)
		(width 0.127)
		(layer "In15.Cu")
		(net "CLK_GEN2_GPU_FPGA_OE_N")
	)
	(segment
		(start 148.679408 -70.768464)
		(end 147.841208 -71.606664)
		(width 0.127)
		(layer "In15.Cu")
		(net "CLK_GEN2_GPU_FPGA_OE_N")
	)
	(segment
		(start 147.841208 -71.606664)
		(end 135.952992 -71.606664)
		(width 0.127)
		(layer "In15.Cu")
		(net "CLK_GEN2_GPU_FPGA_OE_N")
	)
	(segment
		(start 131.304792 -66.958464)
		(end 114.591592 -66.958464)
		(width 0.127)
		(layer "In15.Cu")
		(net "CLK_GEN2_GPU_FPGA_OE_N")
	)
	(segment
		(start 180.250592 -87.862664)
		(end 163.156392 -70.768464)
		(width 0.127)
		(layer "In15.Cu")
		(net "CLK_GEN2_GPU_FPGA_OE_N")
	)
	(segment
		(start 163.156392 -70.768464)
		(end 148.679408 -70.768464)
		(width 0.127)
		(layer "In15.Cu")
		(net "CLK_GEN2_GPU_FPGA_OE_N")
	)
	(segment
		(start 113.473484 -65.840356)
		(end 113.473484 -38.776148)
		(width 0.127)
		(layer "In15.Cu")
		(net "CLK_GEN2_GPU_FPGA_OE_N")
	)
	(segment
		(start 111.894874 -416.143948)
		(end 112.015524 -416.023298)
		(width 0.13208)
		(layer "F.Cu")
		(net "CLK_100M_SWB_R_DP")
	)
	(segment
		(start 111.894874 -417.256722)
		(end 111.894874 -416.143948)
		(width 0.13208)
		(layer "F.Cu")
		(net "CLK_100M_SWB_R_DP")
	)
	(segment
		(start 112.26546 -417.627308)
		(end 111.894874 -417.256722)
		(width 0.13208)
		(layer "F.Cu")
		(net "CLK_100M_SWB_R_DP")
	)
	(segment
		(start 112.015524 -416.023298)
		(end 112.015524 -415.783268)
		(width 0.13208)
		(layer "F.Cu")
		(net "CLK_100M_SWB_R_DP")
	)
	(segment
		(start 111.515398 -416.03168)
		(end 111.515398 -415.783268)
		(width 0.13208)
		(layer "F.Cu")
		(net "CLK_100M_SWB_R_DN")
	)
	(segment
		(start 111.24946 -417.627308)
		(end 111.635794 -417.240974)
		(width 0.13208)
		(layer "F.Cu")
		(net "CLK_100M_SWB_R_DN")
	)
	(segment
		(start 111.635794 -416.152076)
		(end 111.515398 -416.03168)
		(width 0.13208)
		(layer "F.Cu")
		(net "CLK_100M_SWB_R_DN")
	)
	(segment
		(start 111.635794 -417.240974)
		(end 111.635794 -416.152076)
		(width 0.13208)
		(layer "F.Cu")
		(net "CLK_100M_SWB_R_DN")
	)
	(segment
		(start 112.26546 -418.427408)
		(end 111.8997 -418.793168)
		(width 0.13208)
		(layer "F.Cu")
		(net "CLK_100M_SWB_DP")
	)
	(segment
		(start 111.8997 -419.373304)
		(end 112.20196 -419.675564)
		(width 0.13208)
		(layer "F.Cu")
		(net "CLK_100M_SWB_DP")
	)
	(segment
		(start 111.8997 -418.793168)
		(end 111.8997 -419.373304)
		(width 0.13208)
		(layer "F.Cu")
		(net "CLK_100M_SWB_DP")
	)
	(via
		(at 112.20196 -419.675564)
		(size 0.508)
		(drill 0.254)
		(layers "F.Cu" "B.Cu")
		(net "CLK_100M_SWB_DP")
	)
	(segment
		(start 111.609886 -420.507668)
		(end 111.90732 -420.210234)
		(width 0.14732)
		(layer "In2.Cu")
		(net "CLK_100M_SWB_DP")
	)
	(segment
		(start 62.06871 -416.03168)
		(end 62.273434 -416.03168)
		(width 0.14732)
		(layer "In2.Cu")
		(net "CLK_100M_SWB_DP")
	)
	(segment
		(start 62.187328 -422.952672)
		(end 61.97854 -422.952672)
		(width 0.14732)
		(layer "In2.Cu")
		(net "CLK_100M_SWB_DP")
	)
	(segment
		(start 62.650116 -422.489884)
		(end 62.187328 -422.952672)
		(width 0.14732)
		(layer "In2.Cu")
		(net "CLK_100M_SWB_DP")
	)
	(segment
		(start 100.41128 -413.878268)
		(end 105.90149 -416.152584)
		(width 0.14732)
		(layer "In2.Cu")
		(net "CLK_100M_SWB_DP")
	)
	(segment
		(start 111.90732 -420.210234)
		(end 111.90732 -419.970204)
		(width 0.14732)
		(layer "In2.Cu")
		(net "CLK_100M_SWB_DP")
	)
	(segment
		(start 105.90149 -416.152584)
		(end 110.256574 -420.507668)
		(width 0.14732)
		(layer "In2.Cu")
		(net "CLK_100M_SWB_DP")
	)
	(segment
		(start 63.635382 -414.833308)
		(end 63.780162 -414.978088)
		(width 0.14732)
		(layer "In2.Cu")
		(net "CLK_100M_SWB_DP")
	)
	(segment
		(start 61.75502 -422.729152)
		(end 61.75502 -416.34537)
		(width 0.14732)
		(layer "In2.Cu")
		(net "CLK_100M_SWB_DP")
	)
	(segment
		(start 62.534292 -415.566098)
		(end 63.267082 -414.833308)
		(width 0.14732)
		(layer "In2.Cu")
		(net "CLK_100M_SWB_DP")
	)
	(segment
		(start 111.90732 -419.970204)
		(end 112.20196 -419.675564)
		(width 0.14732)
		(layer "In2.Cu")
		(net "CLK_100M_SWB_DP")
	)
	(segment
		(start 64.148462 -414.978088)
		(end 64.293242 -414.833308)
		(width 0.14732)
		(layer "In2.Cu")
		(net "CLK_100M_SWB_DP")
	)
	(segment
		(start 63.780162 -414.978088)
		(end 64.148462 -414.978088)
		(width 0.14732)
		(layer "In2.Cu")
		(net "CLK_100M_SWB_DP")
	)
	(segment
		(start 61.97854 -422.952672)
		(end 61.75502 -422.729152)
		(width 0.14732)
		(layer "In2.Cu")
		(net "CLK_100M_SWB_DP")
	)
	(segment
		(start 94.424754 -413.878268)
		(end 100.41128 -413.878268)
		(width 0.14732)
		(layer "In2.Cu")
		(net "CLK_100M_SWB_DP")
	)
	(segment
		(start 62.273434 -416.03168)
		(end 62.534292 -415.770822)
		(width 0.14732)
		(layer "In2.Cu")
		(net "CLK_100M_SWB_DP")
	)
	(segment
		(start 110.256574 -420.507668)
		(end 111.609886 -420.507668)
		(width 0.14732)
		(layer "In2.Cu")
		(net "CLK_100M_SWB_DP")
	)
	(segment
		(start 62.534292 -415.770822)
		(end 62.534292 -415.566098)
		(width 0.14732)
		(layer "In2.Cu")
		(net "CLK_100M_SWB_DP")
	)
	(segment
		(start 63.267082 -414.833308)
		(end 63.635382 -414.833308)
		(width 0.14732)
		(layer "In2.Cu")
		(net "CLK_100M_SWB_DP")
	)
	(segment
		(start 61.75502 -416.34537)
		(end 62.06871 -416.03168)
		(width 0.14732)
		(layer "In2.Cu")
		(net "CLK_100M_SWB_DP")
	)
	(segment
		(start 92.118942 -414.833308)
		(end 94.424754 -413.878268)
		(width 0.14732)
		(layer "In2.Cu")
		(net "CLK_100M_SWB_DP")
	)
	(segment
		(start 64.293242 -414.833308)
		(end 92.118942 -414.833308)
		(width 0.14732)
		(layer "In2.Cu")
		(net "CLK_100M_SWB_DP")
	)
	(segment
		(start 111.24946 -418.427408)
		(end 111.64062 -418.818568)
		(width 0.13208)
		(layer "F.Cu")
		(net "CLK_100M_SWB_DN")
	)
	(segment
		(start 111.64062 -419.373304)
		(end 111.33836 -419.675564)
		(width 0.13208)
		(layer "F.Cu")
		(net "CLK_100M_SWB_DN")
	)
	(segment
		(start 111.64062 -418.818568)
		(end 111.64062 -419.373304)
		(width 0.13208)
		(layer "F.Cu")
		(net "CLK_100M_SWB_DN")
	)
	(via
		(at 111.33836 -419.675564)
		(size 0.508)
		(drill 0.254)
		(layers "F.Cu" "B.Cu")
		(net "CLK_100M_SWB_DN")
	)
	(segment
		(start 92.064332 -414.558988)
		(end 94.370144 -413.603948)
		(width 0.14732)
		(layer "In2.Cu")
		(net "CLK_100M_SWB_DN")
	)
	(segment
		(start 106.056938 -415.91992)
		(end 110.370366 -420.233348)
		(width 0.14732)
		(layer "In2.Cu")
		(net "CLK_100M_SWB_DN")
	)
	(segment
		(start 61.864748 -423.226992)
		(end 61.4807 -422.842944)
		(width 0.14732)
		(layer "In2.Cu")
		(net "CLK_100M_SWB_DN")
	)
	(segment
		(start 111.633 -420.096442)
		(end 111.633 -419.970204)
		(width 0.14732)
		(layer "In2.Cu")
		(net "CLK_100M_SWB_DN")
	)
	(segment
		(start 110.370366 -420.233348)
		(end 111.496094 -420.233348)
		(width 0.14732)
		(layer "In2.Cu")
		(net "CLK_100M_SWB_DN")
	)
	(segment
		(start 94.370144 -413.603948)
		(end 100.46589 -413.603948)
		(width 0.14732)
		(layer "In2.Cu")
		(net "CLK_100M_SWB_DN")
	)
	(segment
		(start 63.15329 -414.558988)
		(end 92.064332 -414.558988)
		(width 0.14732)
		(layer "In2.Cu")
		(net "CLK_100M_SWB_DN")
	)
	(segment
		(start 62.650116 -423.68978)
		(end 62.187328 -423.226992)
		(width 0.14732)
		(layer "In2.Cu")
		(net "CLK_100M_SWB_DN")
	)
	(segment
		(start 61.4807 -422.842944)
		(end 61.4807 -416.231578)
		(width 0.14732)
		(layer "In2.Cu")
		(net "CLK_100M_SWB_DN")
	)
	(segment
		(start 111.496094 -420.233348)
		(end 111.633 -420.096442)
		(width 0.14732)
		(layer "In2.Cu")
		(net "CLK_100M_SWB_DN")
	)
	(segment
		(start 61.4807 -416.231578)
		(end 63.15329 -414.558988)
		(width 0.14732)
		(layer "In2.Cu")
		(net "CLK_100M_SWB_DN")
	)
	(segment
		(start 111.633 -419.970204)
		(end 111.33836 -419.675564)
		(width 0.14732)
		(layer "In2.Cu")
		(net "CLK_100M_SWB_DN")
	)
	(segment
		(start 100.46589 -413.603948)
		(end 106.056938 -415.91992)
		(width 0.14732)
		(layer "In2.Cu")
		(net "CLK_100M_SWB_DN")
	)
	(segment
		(start 62.187328 -423.226992)
		(end 61.864748 -423.226992)
		(width 0.14732)
		(layer "In2.Cu")
		(net "CLK_100M_SWB_DN")
	)
	(segment
		(start 233.529378 -249.880374)
		(end 233.392726 -249.880374)
		(width 0.13208)
		(layer "F.Cu")
		(net "CLK_100M_GPU_FPGA_DP_R")
	)
	(segment
		(start 233.250232 -249.73788)
		(end 232.61574 -249.73788)
		(width 0.13208)
		(layer "F.Cu")
		(net "CLK_100M_GPU_FPGA_DP_R")
	)
	(segment
		(start 231.62006 -247.31218)
		(end 231.020112 -247.31218)
		(width 0.13208)
		(layer "F.Cu")
		(net "CLK_100M_GPU_FPGA_DP_R")
	)
	(segment
		(start 233.392726 -249.880374)
		(end 233.250232 -249.73788)
		(width 0.13208)
		(layer "F.Cu")
		(net "CLK_100M_GPU_FPGA_DP_R")
	)
	(segment
		(start 231.95534 -249.07748)
		(end 231.95534 -247.64746)
		(width 0.13208)
		(layer "F.Cu")
		(net "CLK_100M_GPU_FPGA_DP_R")
	)
	(segment
		(start 231.95534 -247.64746)
		(end 231.62006 -247.31218)
		(width 0.13208)
		(layer "F.Cu")
		(net "CLK_100M_GPU_FPGA_DP_R")
	)
	(segment
		(start 232.61574 -249.73788)
		(end 231.95534 -249.07748)
		(width 0.13208)
		(layer "F.Cu")
		(net "CLK_100M_GPU_FPGA_DP_R")
	)
	(segment
		(start 231.020112 -247.31218)
		(end 230.648256 -247.684036)
		(width 0.13208)
		(layer "F.Cu")
		(net "CLK_100M_GPU_FPGA_DP_R")
	)
	(segment
		(start 228.857556 -247.3198)
		(end 228.55682 -247.620536)
		(width 0.13208)
		(layer "F.Cu")
		(net "CLK_100M_GPU_FPGA_DP")
	)
	(segment
		(start 229.848156 -247.684036)
		(end 229.48392 -247.3198)
		(width 0.13208)
		(layer "F.Cu")
		(net "CLK_100M_GPU_FPGA_DP")
	)
	(segment
		(start 229.48392 -247.3198)
		(end 228.857556 -247.3198)
		(width 0.13208)
		(layer "F.Cu")
		(net "CLK_100M_GPU_FPGA_DP")
	)
	(via
		(at 228.55682 -247.620536)
		(size 0.508)
		(drill 0.254)
		(layers "F.Cu" "B.Cu")
		(net "CLK_100M_GPU_FPGA_DP")
	)
	(segment
		(start 226.73056 -248.84634)
		(end 226.87534 -248.70156)
		(width 0.14732)
		(layer "In2.Cu")
		(net "CLK_100M_GPU_FPGA_DP")
	)
	(segment
		(start 171.25188 -394.799312)
		(end 171.25188 -389.412734)
		(width 0.14732)
		(layer "In2.Cu")
		(net "CLK_100M_GPU_FPGA_DP")
	)
	(segment
		(start 60.532518 -416.169348)
		(end 60.792868 -415.908998)
		(width 0.14732)
		(layer "In2.Cu")
		(net "CLK_100M_GPU_FPGA_DP")
	)
	(segment
		(start 171.25188 -389.412734)
		(end 226.73056 -333.934054)
		(width 0.14732)
		(layer "In2.Cu")
		(net "CLK_100M_GPU_FPGA_DP")
	)
	(segment
		(start 106.4641 -414.619948)
		(end 109.60354 -411.480508)
		(width 0.14732)
		(layer "In2.Cu")
		(net "CLK_100M_GPU_FPGA_DP")
	)
	(segment
		(start 100.643944 -412.994348)
		(end 104.568752 -414.619948)
		(width 0.14732)
		(layer "In2.Cu")
		(net "CLK_100M_GPU_FPGA_DP")
	)
	(segment
		(start 62.630558 -414.071308)
		(end 91.56573 -414.071308)
		(width 0.14732)
		(layer "In2.Cu")
		(net "CLK_100M_GPU_FPGA_DP")
	)
	(segment
		(start 226.87534 -250.793758)
		(end 226.87534 -250.425458)
		(width 0.14732)
		(layer "In2.Cu")
		(net "CLK_100M_GPU_FPGA_DP")
	)
	(segment
		(start 226.87534 -248.33326)
		(end 226.73056 -248.18848)
		(width 0.14732)
		(layer "In2.Cu")
		(net "CLK_100M_GPU_FPGA_DP")
	)
	(segment
		(start 60.997592 -415.908998)
		(end 61.258196 -415.648394)
		(width 0.14732)
		(layer "In2.Cu")
		(net "CLK_100M_GPU_FPGA_DP")
	)
	(segment
		(start 59.80684 -416.895026)
		(end 60.06719 -416.634676)
		(width 0.14732)
		(layer "In2.Cu")
		(net "CLK_100M_GPU_FPGA_DP")
	)
	(segment
		(start 226.73056 -250.280678)
		(end 226.73056 -249.912378)
		(width 0.14732)
		(layer "In2.Cu")
		(net "CLK_100M_GPU_FPGA_DP")
	)
	(segment
		(start 226.73056 -250.938538)
		(end 226.87534 -250.793758)
		(width 0.14732)
		(layer "In2.Cu")
		(net "CLK_100M_GPU_FPGA_DP")
	)
	(segment
		(start 226.73056 -248.18848)
		(end 226.73056 -247.82018)
		(width 0.14732)
		(layer "In2.Cu")
		(net "CLK_100M_GPU_FPGA_DP")
	)
	(segment
		(start 104.568752 -414.619948)
		(end 106.4641 -414.619948)
		(width 0.14732)
		(layer "In2.Cu")
		(net "CLK_100M_GPU_FPGA_DP")
	)
	(segment
		(start 60.532518 -416.374072)
		(end 60.532518 -416.169348)
		(width 0.14732)
		(layer "In2.Cu")
		(net "CLK_100M_GPU_FPGA_DP")
	)
	(segment
		(start 158.16707 -415.989008)
		(end 168.487598 -411.714442)
		(width 0.14732)
		(layer "In2.Cu")
		(net "CLK_100M_GPU_FPGA_DP")
	)
	(segment
		(start 60.792868 -415.908998)
		(end 60.997592 -415.908998)
		(width 0.14732)
		(layer "In2.Cu")
		(net "CLK_100M_GPU_FPGA_DP")
	)
	(segment
		(start 60.65012 -419.88994)
		(end 60.187332 -420.352728)
		(width 0.14732)
		(layer "In2.Cu")
		(net "CLK_100M_GPU_FPGA_DP")
	)
	(segment
		(start 226.87534 -248.70156)
		(end 226.87534 -248.33326)
		(width 0.14732)
		(layer "In2.Cu")
		(net "CLK_100M_GPU_FPGA_DP")
	)
	(segment
		(start 226.73056 -333.934054)
		(end 226.73056 -250.938538)
		(width 0.14732)
		(layer "In2.Cu")
		(net "CLK_100M_GPU_FPGA_DP")
	)
	(segment
		(start 109.60354 -411.480508)
		(end 116.94922 -411.480508)
		(width 0.14732)
		(layer "In2.Cu")
		(net "CLK_100M_GPU_FPGA_DP")
	)
	(segment
		(start 226.73056 -249.254518)
		(end 226.73056 -248.84634)
		(width 0.14732)
		(layer "In2.Cu")
		(net "CLK_100M_GPU_FPGA_DP")
	)
	(segment
		(start 61.518546 -415.18332)
		(end 61.72327 -415.18332)
		(width 0.14732)
		(layer "In2.Cu")
		(net "CLK_100M_GPU_FPGA_DP")
	)
	(segment
		(start 91.56573 -414.071308)
		(end 94.165928 -412.994348)
		(width 0.14732)
		(layer "In2.Cu")
		(net "CLK_100M_GPU_FPGA_DP")
	)
	(segment
		(start 226.73056 -249.912378)
		(end 226.87534 -249.767598)
		(width 0.14732)
		(layer "In2.Cu")
		(net "CLK_100M_GPU_FPGA_DP")
	)
	(segment
		(start 61.258196 -415.648394)
		(end 61.258196 -415.44367)
		(width 0.14732)
		(layer "In2.Cu")
		(net "CLK_100M_GPU_FPGA_DP")
	)
	(segment
		(start 61.258196 -415.44367)
		(end 61.518546 -415.18332)
		(width 0.14732)
		(layer "In2.Cu")
		(net "CLK_100M_GPU_FPGA_DP")
	)
	(segment
		(start 168.487598 -411.714442)
		(end 170.42384 -409.7782)
		(width 0.14732)
		(layer "In2.Cu")
		(net "CLK_100M_GPU_FPGA_DP")
	)
	(segment
		(start 227.232972 -247.317768)
		(end 228.254052 -247.317768)
		(width 0.14732)
		(layer "In2.Cu")
		(net "CLK_100M_GPU_FPGA_DP")
	)
	(segment
		(start 116.94922 -411.480508)
		(end 119.59844 -414.129728)
		(width 0.14732)
		(layer "In2.Cu")
		(net "CLK_100M_GPU_FPGA_DP")
	)
	(segment
		(start 170.42384 -395.627352)
		(end 171.25188 -394.799312)
		(width 0.14732)
		(layer "In2.Cu")
		(net "CLK_100M_GPU_FPGA_DP")
	)
	(segment
		(start 59.978544 -420.352728)
		(end 59.80684 -420.181024)
		(width 0.14732)
		(layer "In2.Cu")
		(net "CLK_100M_GPU_FPGA_DP")
	)
	(segment
		(start 226.87534 -250.425458)
		(end 226.73056 -250.280678)
		(width 0.14732)
		(layer "In2.Cu")
		(net "CLK_100M_GPU_FPGA_DP")
	)
	(segment
		(start 170.42384 -409.7782)
		(end 170.42384 -395.627352)
		(width 0.14732)
		(layer "In2.Cu")
		(net "CLK_100M_GPU_FPGA_DP")
	)
	(segment
		(start 124.841 -414.129728)
		(end 126.70028 -415.989008)
		(width 0.14732)
		(layer "In2.Cu")
		(net "CLK_100M_GPU_FPGA_DP")
	)
	(segment
		(start 94.165928 -412.994348)
		(end 100.643944 -412.994348)
		(width 0.14732)
		(layer "In2.Cu")
		(net "CLK_100M_GPU_FPGA_DP")
	)
	(segment
		(start 226.87534 -249.767598)
		(end 226.87534 -249.399298)
		(width 0.14732)
		(layer "In2.Cu")
		(net "CLK_100M_GPU_FPGA_DP")
	)
	(segment
		(start 228.254052 -247.317768)
		(end 228.55682 -247.620536)
		(width 0.14732)
		(layer "In2.Cu")
		(net "CLK_100M_GPU_FPGA_DP")
	)
	(segment
		(start 60.271914 -416.634676)
		(end 60.532518 -416.374072)
		(width 0.14732)
		(layer "In2.Cu")
		(net "CLK_100M_GPU_FPGA_DP")
	)
	(segment
		(start 119.59844 -414.129728)
		(end 124.841 -414.129728)
		(width 0.14732)
		(layer "In2.Cu")
		(net "CLK_100M_GPU_FPGA_DP")
	)
	(segment
		(start 61.983874 -414.717992)
		(end 62.630558 -414.071308)
		(width 0.14732)
		(layer "In2.Cu")
		(net "CLK_100M_GPU_FPGA_DP")
	)
	(segment
		(start 60.187332 -420.352728)
		(end 59.978544 -420.352728)
		(width 0.14732)
		(layer "In2.Cu")
		(net "CLK_100M_GPU_FPGA_DP")
	)
	(segment
		(start 126.70028 -415.989008)
		(end 158.16707 -415.989008)
		(width 0.14732)
		(layer "In2.Cu")
		(net "CLK_100M_GPU_FPGA_DP")
	)
	(segment
		(start 61.983874 -414.922716)
		(end 61.983874 -414.717992)
		(width 0.14732)
		(layer "In2.Cu")
		(net "CLK_100M_GPU_FPGA_DP")
	)
	(segment
		(start 226.73056 -247.82018)
		(end 227.232972 -247.317768)
		(width 0.14732)
		(layer "In2.Cu")
		(net "CLK_100M_GPU_FPGA_DP")
	)
	(segment
		(start 59.80684 -420.181024)
		(end 59.80684 -416.895026)
		(width 0.14732)
		(layer "In2.Cu")
		(net "CLK_100M_GPU_FPGA_DP")
	)
	(segment
		(start 61.72327 -415.18332)
		(end 61.983874 -414.922716)
		(width 0.14732)
		(layer "In2.Cu")
		(net "CLK_100M_GPU_FPGA_DP")
	)
	(segment
		(start 60.06719 -416.634676)
		(end 60.271914 -416.634676)
		(width 0.14732)
		(layer "In2.Cu")
		(net "CLK_100M_GPU_FPGA_DP")
	)
	(segment
		(start 226.87534 -249.399298)
		(end 226.73056 -249.254518)
		(width 0.14732)
		(layer "In2.Cu")
		(net "CLK_100M_GPU_FPGA_DP")
	)
	(segment
		(start 231.00792 -247.0531)
		(end 230.648256 -246.693436)
		(width 0.13208)
		(layer "F.Cu")
		(net "CLK_100M_GPU_FPGA_DN_R")
	)
	(segment
		(start 232.723182 -249.4788)
		(end 232.21442 -248.970038)
		(width 0.13208)
		(layer "F.Cu")
		(net "CLK_100M_GPU_FPGA_DN_R")
	)
	(segment
		(start 233.284268 -249.4788)
		(end 232.723182 -249.4788)
		(width 0.13208)
		(layer "F.Cu")
		(net "CLK_100M_GPU_FPGA_DN_R")
	)
	(segment
		(start 232.21442 -248.970038)
		(end 232.21442 -247.540018)
		(width 0.13208)
		(layer "F.Cu")
		(net "CLK_100M_GPU_FPGA_DN_R")
	)
	(segment
		(start 231.727502 -247.0531)
		(end 231.00792 -247.0531)
		(width 0.13208)
		(layer "F.Cu")
		(net "CLK_100M_GPU_FPGA_DN_R")
	)
	(segment
		(start 233.529378 -249.380502)
		(end 233.382566 -249.380502)
		(width 0.13208)
		(layer "F.Cu")
		(net "CLK_100M_GPU_FPGA_DN_R")
	)
	(segment
		(start 232.21442 -247.540018)
		(end 231.727502 -247.0531)
		(width 0.13208)
		(layer "F.Cu")
		(net "CLK_100M_GPU_FPGA_DN_R")
	)
	(segment
		(start 233.382566 -249.380502)
		(end 233.284268 -249.4788)
		(width 0.13208)
		(layer "F.Cu")
		(net "CLK_100M_GPU_FPGA_DN_R")
	)
	(segment
		(start 229.480872 -247.06072)
		(end 228.860604 -247.06072)
		(width 0.13208)
		(layer "F.Cu")
		(net "CLK_100M_GPU_FPGA_DN")
	)
	(segment
		(start 228.860604 -247.06072)
		(end 228.55682 -246.756936)
		(width 0.13208)
		(layer "F.Cu")
		(net "CLK_100M_GPU_FPGA_DN")
	)
	(segment
		(start 229.848156 -246.693436)
		(end 229.480872 -247.06072)
		(width 0.13208)
		(layer "F.Cu")
		(net "CLK_100M_GPU_FPGA_DN")
	)
	(via
		(at 228.55682 -246.756936)
		(size 0.508)
		(drill 0.254)
		(layers "F.Cu" "B.Cu")
		(net "CLK_100M_GPU_FPGA_DN")
	)
	(segment
		(start 62.516766 -413.796988)
		(end 91.51112 -413.796988)
		(width 0.14732)
		(layer "In2.Cu")
		(net "CLK_100M_GPU_FPGA_DN")
	)
	(segment
		(start 227.11918 -247.043448)
		(end 228.270308 -247.043448)
		(width 0.14732)
		(layer "In2.Cu")
		(net "CLK_100M_GPU_FPGA_DN")
	)
	(segment
		(start 117.063012 -411.206188)
		(end 119.712232 -413.855408)
		(width 0.14732)
		(layer "In2.Cu")
		(net "CLK_100M_GPU_FPGA_DN")
	)
	(segment
		(start 170.97756 -389.298942)
		(end 226.45624 -333.820262)
		(width 0.14732)
		(layer "In2.Cu")
		(net "CLK_100M_GPU_FPGA_DN")
	)
	(segment
		(start 59.53252 -416.781234)
		(end 62.516766 -413.796988)
		(width 0.14732)
		(layer "In2.Cu")
		(net "CLK_100M_GPU_FPGA_DN")
	)
	(segment
		(start 106.350308 -414.345628)
		(end 109.489748 -411.206188)
		(width 0.14732)
		(layer "In2.Cu")
		(net "CLK_100M_GPU_FPGA_DN")
	)
	(segment
		(start 170.14952 -409.664408)
		(end 170.14952 -395.51356)
		(width 0.14732)
		(layer "In2.Cu")
		(net "CLK_100M_GPU_FPGA_DN")
	)
	(segment
		(start 60.65012 -421.089836)
		(end 60.187332 -420.627048)
		(width 0.14732)
		(layer "In2.Cu")
		(net "CLK_100M_GPU_FPGA_DN")
	)
	(segment
		(start 104.623362 -414.345628)
		(end 106.350308 -414.345628)
		(width 0.14732)
		(layer "In2.Cu")
		(net "CLK_100M_GPU_FPGA_DN")
	)
	(segment
		(start 126.814072 -415.714688)
		(end 158.11246 -415.714688)
		(width 0.14732)
		(layer "In2.Cu")
		(net "CLK_100M_GPU_FPGA_DN")
	)
	(segment
		(start 100.698554 -412.720028)
		(end 104.623362 -414.345628)
		(width 0.14732)
		(layer "In2.Cu")
		(net "CLK_100M_GPU_FPGA_DN")
	)
	(segment
		(start 226.45624 -333.820262)
		(end 226.45624 -247.706388)
		(width 0.14732)
		(layer "In2.Cu")
		(net "CLK_100M_GPU_FPGA_DN")
	)
	(segment
		(start 59.864752 -420.627048)
		(end 59.53252 -420.294816)
		(width 0.14732)
		(layer "In2.Cu")
		(net "CLK_100M_GPU_FPGA_DN")
	)
	(segment
		(start 119.712232 -413.855408)
		(end 124.954792 -413.855408)
		(width 0.14732)
		(layer "In2.Cu")
		(net "CLK_100M_GPU_FPGA_DN")
	)
	(segment
		(start 228.270308 -247.043448)
		(end 228.55682 -246.756936)
		(width 0.14732)
		(layer "In2.Cu")
		(net "CLK_100M_GPU_FPGA_DN")
	)
	(segment
		(start 60.187332 -420.627048)
		(end 59.864752 -420.627048)
		(width 0.14732)
		(layer "In2.Cu")
		(net "CLK_100M_GPU_FPGA_DN")
	)
	(segment
		(start 168.33215 -411.481778)
		(end 170.14952 -409.664408)
		(width 0.14732)
		(layer "In2.Cu")
		(net "CLK_100M_GPU_FPGA_DN")
	)
	(segment
		(start 59.53252 -420.294816)
		(end 59.53252 -416.781234)
		(width 0.14732)
		(layer "In2.Cu")
		(net "CLK_100M_GPU_FPGA_DN")
	)
	(segment
		(start 124.954792 -413.855408)
		(end 126.814072 -415.714688)
		(width 0.14732)
		(layer "In2.Cu")
		(net "CLK_100M_GPU_FPGA_DN")
	)
	(segment
		(start 158.11246 -415.714688)
		(end 168.33215 -411.481778)
		(width 0.14732)
		(layer "In2.Cu")
		(net "CLK_100M_GPU_FPGA_DN")
	)
	(segment
		(start 170.97756 -394.68552)
		(end 170.97756 -389.298942)
		(width 0.14732)
		(layer "In2.Cu")
		(net "CLK_100M_GPU_FPGA_DN")
	)
	(segment
		(start 170.14952 -395.51356)
		(end 170.97756 -394.68552)
		(width 0.14732)
		(layer "In2.Cu")
		(net "CLK_100M_GPU_FPGA_DN")
	)
	(segment
		(start 94.111318 -412.720028)
		(end 100.698554 -412.720028)
		(width 0.14732)
		(layer "In2.Cu")
		(net "CLK_100M_GPU_FPGA_DN")
	)
	(segment
		(start 91.51112 -413.796988)
		(end 94.111318 -412.720028)
		(width 0.14732)
		(layer "In2.Cu")
		(net "CLK_100M_GPU_FPGA_DN")
	)
	(segment
		(start 226.45624 -247.706388)
		(end 227.11918 -247.043448)
		(width 0.14732)
		(layer "In2.Cu")
		(net "CLK_100M_GPU_FPGA_DN")
	)
	(segment
		(start 109.489748 -411.206188)
		(end 117.063012 -411.206188)
		(width 0.14732)
		(layer "In2.Cu")
		(net "CLK_100M_GPU_FPGA_DN")
	)
	(segment
		(start 109.409738 -412.53537)
		(end 109.599476 -412.53537)
		(width 0.13208)
		(layer "F.Cu")
		(net "CLK_100M_GPU_2_R_DP")
	)
	(segment
		(start 107.51312 -413.283908)
		(end 107.996228 -413.283908)
		(width 0.13208)
		(layer "F.Cu")
		(net "CLK_100M_GPU_2_R_DP")
	)
	(segment
		(start 107.10926 -413.687768)
		(end 107.51312 -413.283908)
		(width 0.13208)
		(layer "F.Cu")
		(net "CLK_100M_GPU_2_R_DP")
	)
	(segment
		(start 107.996228 -413.283908)
		(end 108.636054 -412.85668)
		(width 0.13208)
		(layer "F.Cu")
		(net "CLK_100M_GPU_2_R_DP")
	)
	(segment
		(start 108.636054 -412.85668)
		(end 109.409738 -412.53537)
		(width 0.13208)
		(layer "F.Cu")
		(net "CLK_100M_GPU_2_R_DP")
	)
	(segment
		(start 109.599476 -412.53537)
		(end 109.722412 -412.658306)
		(width 0.13208)
		(layer "F.Cu")
		(net "CLK_100M_GPU_2_R_DP")
	)
	(segment
		(start 109.722412 -412.658306)
		(end 109.89056 -412.658306)
		(width 0.13208)
		(layer "F.Cu")
		(net "CLK_100M_GPU_2_R_DP")
	)
	(segment
		(start 109.582204 -412.27629)
		(end 109.70006 -412.158434)
		(width 0.13208)
		(layer "F.Cu")
		(net "CLK_100M_GPU_2_R_DN")
	)
	(segment
		(start 108.513372 -412.627064)
		(end 109.357922 -412.27629)
		(width 0.13208)
		(layer "F.Cu")
		(net "CLK_100M_GPU_2_R_DN")
	)
	(segment
		(start 107.917488 -413.024828)
		(end 108.513372 -412.627064)
		(width 0.13208)
		(layer "F.Cu")
		(net "CLK_100M_GPU_2_R_DN")
	)
	(segment
		(start 109.357922 -412.27629)
		(end 109.582204 -412.27629)
		(width 0.13208)
		(layer "F.Cu")
		(net "CLK_100M_GPU_2_R_DN")
	)
	(segment
		(start 109.70006 -412.158434)
		(end 109.89056 -412.158434)
		(width 0.13208)
		(layer "F.Cu")
		(net "CLK_100M_GPU_2_R_DN")
	)
	(segment
		(start 107.10926 -412.671768)
		(end 107.46232 -413.024828)
		(width 0.13208)
		(layer "F.Cu")
		(net "CLK_100M_GPU_2_R_DN")
	)
	(segment
		(start 107.46232 -413.024828)
		(end 107.917488 -413.024828)
		(width 0.13208)
		(layer "F.Cu")
		(net "CLK_100M_GPU_2_R_DN")
	)
	(segment
		(start 106.30916 -413.687768)
		(end 105.9307 -413.309308)
		(width 0.13208)
		(layer "F.Cu")
		(net "CLK_100M_GPU_2_DP")
	)
	(segment
		(start 105.561384 -413.309308)
		(end 105.259124 -413.611568)
		(width 0.13208)
		(layer "F.Cu")
		(net "CLK_100M_GPU_2_DP")
	)
	(segment
		(start 105.9307 -413.309308)
		(end 105.561384 -413.309308)
		(width 0.13208)
		(layer "F.Cu")
		(net "CLK_100M_GPU_2_DP")
	)
	(via
		(at 105.259124 -413.611568)
		(size 0.508)
		(drill 0.254)
		(layers "F.Cu" "B.Cu")
		(net "CLK_100M_GPU_2_DP")
	)
	(segment
		(start 104.46893 -413.324548)
		(end 104.972104 -413.324548)
		(width 0.14732)
		(layer "In2.Cu")
		(net "CLK_100M_GPU_2_DP")
	)
	(segment
		(start 101.882702 -412.410148)
		(end 102.223062 -412.551118)
		(width 0.14732)
		(layer "In2.Cu")
		(net "CLK_100M_GPU_2_DP")
	)
	(segment
		(start 59.474608 -415.634678)
		(end 59.734958 -415.374328)
		(width 0.14732)
		(layer "In2.Cu")
		(net "CLK_100M_GPU_2_DP")
	)
	(segment
		(start 101.804216 -412.220664)
		(end 101.882702 -412.410148)
		(width 0.14732)
		(layer "In2.Cu")
		(net "CLK_100M_GPU_2_DP")
	)
	(segment
		(start 59.00928 -416.100006)
		(end 59.214004 -416.100006)
		(width 0.14732)
		(layer "In2.Cu")
		(net "CLK_100M_GPU_2_DP")
	)
	(segment
		(start 102.830884 -412.803086)
		(end 103.171244 -412.944056)
		(width 0.14732)
		(layer "In2.Cu")
		(net "CLK_100M_GPU_2_DP")
	)
	(segment
		(start 103.360474 -412.86557)
		(end 104.46893 -413.324548)
		(width 0.14732)
		(layer "In2.Cu")
		(net "CLK_100M_GPU_2_DP")
	)
	(segment
		(start 60.925964 -414.388046)
		(end 60.925964 -414.183322)
		(width 0.14732)
		(layer "In2.Cu")
		(net "CLK_100M_GPU_2_DP")
	)
	(segment
		(start 104.972104 -413.324548)
		(end 105.259124 -413.611568)
		(width 0.14732)
		(layer "In2.Cu")
		(net "CLK_100M_GPU_2_DP")
	)
	(segment
		(start 101.46411 -412.079948)
		(end 101.804216 -412.220664)
		(width 0.14732)
		(layer "In2.Cu")
		(net "CLK_100M_GPU_2_DP")
	)
	(segment
		(start 60.66536 -414.64865)
		(end 60.925964 -414.388046)
		(width 0.14732)
		(layer "In2.Cu")
		(net "CLK_100M_GPU_2_DP")
	)
	(segment
		(start 102.412292 -412.472886)
		(end 102.752398 -412.613602)
		(width 0.14732)
		(layer "In2.Cu")
		(net "CLK_100M_GPU_2_DP")
	)
	(segment
		(start 57.26938 -417.839906)
		(end 58.283348 -416.825938)
		(width 0.14732)
		(layer "In2.Cu")
		(net "CLK_100M_GPU_2_DP")
	)
	(segment
		(start 60.200286 -414.909)
		(end 60.460636 -414.64865)
		(width 0.14732)
		(layer "In2.Cu")
		(net "CLK_100M_GPU_2_DP")
	)
	(segment
		(start 58.283348 -416.825938)
		(end 58.488072 -416.825938)
		(width 0.14732)
		(layer "In2.Cu")
		(net "CLK_100M_GPU_2_DP")
	)
	(segment
		(start 59.939682 -415.374328)
		(end 60.200286 -415.113724)
		(width 0.14732)
		(layer "In2.Cu")
		(net "CLK_100M_GPU_2_DP")
	)
	(segment
		(start 90.779854 -413.344868)
		(end 93.833696 -412.079948)
		(width 0.14732)
		(layer "In2.Cu")
		(net "CLK_100M_GPU_2_DP")
	)
	(segment
		(start 58.74893 -416.56508)
		(end 58.74893 -416.360356)
		(width 0.14732)
		(layer "In2.Cu")
		(net "CLK_100M_GPU_2_DP")
	)
	(segment
		(start 60.460636 -414.64865)
		(end 60.66536 -414.64865)
		(width 0.14732)
		(layer "In2.Cu")
		(net "CLK_100M_GPU_2_DP")
	)
	(segment
		(start 59.214004 -416.100006)
		(end 59.474608 -415.839402)
		(width 0.14732)
		(layer "In2.Cu")
		(net "CLK_100M_GPU_2_DP")
	)
	(segment
		(start 57.26938 -422.243504)
		(end 57.26938 -417.839906)
		(width 0.14732)
		(layer "In2.Cu")
		(net "CLK_100M_GPU_2_DP")
	)
	(segment
		(start 59.734958 -415.374328)
		(end 59.939682 -415.374328)
		(width 0.14732)
		(layer "In2.Cu")
		(net "CLK_100M_GPU_2_DP")
	)
	(segment
		(start 60.200286 -415.113724)
		(end 60.200286 -414.909)
		(width 0.14732)
		(layer "In2.Cu")
		(net "CLK_100M_GPU_2_DP")
	)
	(segment
		(start 58.74893 -416.360356)
		(end 59.00928 -416.100006)
		(width 0.14732)
		(layer "In2.Cu")
		(net "CLK_100M_GPU_2_DP")
	)
	(segment
		(start 58.650124 -422.489884)
		(end 58.187336 -422.952672)
		(width 0.14732)
		(layer "In2.Cu")
		(net "CLK_100M_GPU_2_DP")
	)
	(segment
		(start 58.187336 -422.952672)
		(end 57.978548 -422.952672)
		(width 0.14732)
		(layer "In2.Cu")
		(net "CLK_100M_GPU_2_DP")
	)
	(segment
		(start 102.223062 -412.551118)
		(end 102.412292 -412.472886)
		(width 0.14732)
		(layer "In2.Cu")
		(net "CLK_100M_GPU_2_DP")
	)
	(segment
		(start 93.833696 -412.079948)
		(end 101.46411 -412.079948)
		(width 0.14732)
		(layer "In2.Cu")
		(net "CLK_100M_GPU_2_DP")
	)
	(segment
		(start 102.752398 -412.613602)
		(end 102.830884 -412.803086)
		(width 0.14732)
		(layer "In2.Cu")
		(net "CLK_100M_GPU_2_DP")
	)
	(segment
		(start 61.764418 -413.344868)
		(end 90.779854 -413.344868)
		(width 0.14732)
		(layer "In2.Cu")
		(net "CLK_100M_GPU_2_DP")
	)
	(segment
		(start 103.171244 -412.944056)
		(end 103.360474 -412.86557)
		(width 0.14732)
		(layer "In2.Cu")
		(net "CLK_100M_GPU_2_DP")
	)
	(segment
		(start 57.978548 -422.952672)
		(end 57.26938 -422.243504)
		(width 0.14732)
		(layer "In2.Cu")
		(net "CLK_100M_GPU_2_DP")
	)
	(segment
		(start 60.925964 -414.183322)
		(end 61.764418 -413.344868)
		(width 0.14732)
		(layer "In2.Cu")
		(net "CLK_100M_GPU_2_DP")
	)
	(segment
		(start 58.488072 -416.825938)
		(end 58.74893 -416.56508)
		(width 0.14732)
		(layer "In2.Cu")
		(net "CLK_100M_GPU_2_DP")
	)
	(segment
		(start 59.474608 -415.839402)
		(end 59.474608 -415.634678)
		(width 0.14732)
		(layer "In2.Cu")
		(net "CLK_100M_GPU_2_DP")
	)
	(segment
		(start 105.9307 -413.050228)
		(end 105.561384 -413.050228)
		(width 0.13208)
		(layer "F.Cu")
		(net "CLK_100M_GPU_2_DN")
	)
	(segment
		(start 105.561384 -413.050228)
		(end 105.259124 -412.747968)
		(width 0.13208)
		(layer "F.Cu")
		(net "CLK_100M_GPU_2_DN")
	)
	(segment
		(start 106.30916 -412.671768)
		(end 105.9307 -413.050228)
		(width 0.13208)
		(layer "F.Cu")
		(net "CLK_100M_GPU_2_DN")
	)
	(via
		(at 105.259124 -412.747968)
		(size 0.508)
		(drill 0.254)
		(layers "F.Cu" "B.Cu")
		(net "CLK_100M_GPU_2_DN")
	)
	(segment
		(start 58.187336 -423.226992)
		(end 57.864756 -423.226992)
		(width 0.14732)
		(layer "In2.Cu")
		(net "CLK_100M_GPU_2_DN")
	)
	(segment
		(start 57.864756 -423.226992)
		(end 56.99506 -422.357296)
		(width 0.14732)
		(layer "In2.Cu")
		(net "CLK_100M_GPU_2_DN")
	)
	(segment
		(start 56.99506 -417.726114)
		(end 61.650626 -413.070548)
		(width 0.14732)
		(layer "In2.Cu")
		(net "CLK_100M_GPU_2_DN")
	)
	(segment
		(start 90.725244 -413.070548)
		(end 93.779086 -411.805628)
		(width 0.14732)
		(layer "In2.Cu")
		(net "CLK_100M_GPU_2_DN")
	)
	(segment
		(start 104.52354 -413.050228)
		(end 104.91978 -413.050228)
		(width 0.14732)
		(layer "In2.Cu")
		(net "CLK_100M_GPU_2_DN")
	)
	(segment
		(start 105.22204 -412.747968)
		(end 105.259124 -412.747968)
		(width 0.14732)
		(layer "In2.Cu")
		(net "CLK_100M_GPU_2_DN")
	)
	(segment
		(start 93.779086 -411.805628)
		(end 101.51872 -411.805628)
		(width 0.14732)
		(layer "In2.Cu")
		(net "CLK_100M_GPU_2_DN")
	)
	(segment
		(start 58.650124 -423.68978)
		(end 58.187336 -423.226992)
		(width 0.14732)
		(layer "In2.Cu")
		(net "CLK_100M_GPU_2_DN")
	)
	(segment
		(start 56.99506 -422.357296)
		(end 56.99506 -417.726114)
		(width 0.14732)
		(layer "In2.Cu")
		(net "CLK_100M_GPU_2_DN")
	)
	(segment
		(start 101.51872 -411.805628)
		(end 104.52354 -413.050228)
		(width 0.14732)
		(layer "In2.Cu")
		(net "CLK_100M_GPU_2_DN")
	)
	(segment
		(start 61.650626 -413.070548)
		(end 90.725244 -413.070548)
		(width 0.14732)
		(layer "In2.Cu")
		(net "CLK_100M_GPU_2_DN")
	)
	(segment
		(start 104.91978 -413.050228)
		(end 105.22204 -412.747968)
		(width 0.14732)
		(layer "In2.Cu")
		(net "CLK_100M_GPU_2_DN")
	)
	(segment
		(start 107.52074 -415.326068)
		(end 107.669076 -415.326068)
		(width 0.13208)
		(layer "F.Cu")
		(net "CLK_100M_GPU_1_R_DP")
	)
	(segment
		(start 109.093508 -414.043368)
		(end 109.63148 -414.043368)
		(width 0.13208)
		(layer "F.Cu")
		(net "CLK_100M_GPU_1_R_DP")
	)
	(segment
		(start 108.333794 -414.66135)
		(end 108.475526 -414.66135)
		(width 0.13208)
		(layer "F.Cu")
		(net "CLK_100M_GPU_1_R_DP")
	)
	(segment
		(start 107.10926 -415.757868)
		(end 107.10926 -415.737548)
		(width 0.13208)
		(layer "F.Cu")
		(net "CLK_100M_GPU_1_R_DP")
	)
	(segment
		(start 107.10926 -415.737548)
		(end 107.52074 -415.326068)
		(width 0.13208)
		(layer "F.Cu")
		(net "CLK_100M_GPU_1_R_DP")
	)
	(segment
		(start 109.746542 -414.15843)
		(end 109.89056 -414.15843)
		(width 0.13208)
		(layer "F.Cu")
		(net "CLK_100M_GPU_1_R_DP")
	)
	(segment
		(start 109.63148 -414.043368)
		(end 109.746542 -414.15843)
		(width 0.13208)
		(layer "F.Cu")
		(net "CLK_100M_GPU_1_R_DP")
	)
	(segment
		(start 108.475526 -414.66135)
		(end 109.093508 -414.043368)
		(width 0.13208)
		(layer "F.Cu")
		(net "CLK_100M_GPU_1_R_DP")
	)
	(segment
		(start 107.669076 -415.326068)
		(end 108.333794 -414.66135)
		(width 0.13208)
		(layer "F.Cu")
		(net "CLK_100M_GPU_1_R_DP")
	)
	(segment
		(start 109.709204 -413.658304)
		(end 109.89056 -413.658304)
		(width 0.13208)
		(layer "F.Cu")
		(net "CLK_100M_GPU_1_R_DN")
	)
	(segment
		(start 107.561634 -415.066988)
		(end 108.226352 -414.40227)
		(width 0.13208)
		(layer "F.Cu")
		(net "CLK_100M_GPU_1_R_DN")
	)
	(segment
		(start 107.43438 -415.066988)
		(end 107.561634 -415.066988)
		(width 0.13208)
		(layer "F.Cu")
		(net "CLK_100M_GPU_1_R_DN")
	)
	(segment
		(start 108.226352 -414.40227)
		(end 108.368084 -414.40227)
		(width 0.13208)
		(layer "F.Cu")
		(net "CLK_100M_GPU_1_R_DN")
	)
	(segment
		(start 108.986066 -413.784288)
		(end 109.58322 -413.784288)
		(width 0.13208)
		(layer "F.Cu")
		(net "CLK_100M_GPU_1_R_DN")
	)
	(segment
		(start 109.58322 -413.784288)
		(end 109.709204 -413.658304)
		(width 0.13208)
		(layer "F.Cu")
		(net "CLK_100M_GPU_1_R_DN")
	)
	(segment
		(start 108.368084 -414.40227)
		(end 108.986066 -413.784288)
		(width 0.13208)
		(layer "F.Cu")
		(net "CLK_100M_GPU_1_R_DN")
	)
	(segment
		(start 107.10926 -414.741868)
		(end 107.43438 -415.066988)
		(width 0.13208)
		(layer "F.Cu")
		(net "CLK_100M_GPU_1_R_DN")
	)
	(segment
		(start 101.243384 -415.379408)
		(end 100.941124 -415.681668)
		(width 0.13208)
		(layer "F.Cu")
		(net "CLK_100M_GPU_1_DP")
	)
	(segment
		(start 106.30916 -415.757868)
		(end 105.9307 -415.379408)
		(width 0.13208)
		(layer "F.Cu")
		(net "CLK_100M_GPU_1_DP")
	)
	(segment
		(start 105.9307 -415.379408)
		(end 101.243384 -415.379408)
		(width 0.13208)
		(layer "F.Cu")
		(net "CLK_100M_GPU_1_DP")
	)
	(via
		(at 100.941124 -415.681668)
		(size 0.508)
		(drill 0.254)
		(layers "F.Cu" "B.Cu")
		(net "CLK_100M_GPU_1_DP")
	)
	(segment
		(start 63.831216 -417.191444)
		(end 64.455802 -416.566858)
		(width 0.14732)
		(layer "In2.Cu")
		(net "CLK_100M_GPU_1_DP")
	)
	(segment
		(start 65.457832 -415.564828)
		(end 65.826132 -415.564828)
		(width 0.14732)
		(layer "In2.Cu")
		(net "CLK_100M_GPU_1_DP")
	)
	(segment
		(start 65.826132 -415.564828)
		(end 65.970912 -415.709608)
		(width 0.14732)
		(layer "In2.Cu")
		(net "CLK_100M_GPU_1_DP")
	)
	(segment
		(start 66.483992 -415.564828)
		(end 66.86169 -415.564828)
		(width 0.14732)
		(layer "In2.Cu")
		(net "CLK_100M_GPU_1_DP")
	)
	(segment
		(start 99.041712 -415.564828)
		(end 99.222052 -415.384488)
		(width 0.14732)
		(layer "In2.Cu")
		(net "CLK_100M_GPU_1_DP")
	)
	(segment
		(start 71.62419 -415.564828)
		(end 99.041712 -415.564828)
		(width 0.14732)
		(layer "In2.Cu")
		(net "CLK_100M_GPU_1_DP")
	)
	(segment
		(start 67.00647 -415.709608)
		(end 67.37477 -415.709608)
		(width 0.14732)
		(layer "In2.Cu")
		(net "CLK_100M_GPU_1_DP")
	)
	(segment
		(start 71.47941 -415.709608)
		(end 71.62419 -415.564828)
		(width 0.14732)
		(layer "In2.Cu")
		(net "CLK_100M_GPU_1_DP")
	)
	(segment
		(start 69.57187 -415.564828)
		(end 69.94017 -415.564828)
		(width 0.14732)
		(layer "In2.Cu")
		(net "CLK_100M_GPU_1_DP")
	)
	(segment
		(start 71.11111 -415.709608)
		(end 71.47941 -415.709608)
		(width 0.14732)
		(layer "In2.Cu")
		(net "CLK_100M_GPU_1_DP")
	)
	(segment
		(start 66.339212 -415.709608)
		(end 66.483992 -415.564828)
		(width 0.14732)
		(layer "In2.Cu")
		(net "CLK_100M_GPU_1_DP")
	)
	(segment
		(start 66.86169 -415.564828)
		(end 67.00647 -415.709608)
		(width 0.14732)
		(layer "In2.Cu")
		(net "CLK_100M_GPU_1_DP")
	)
	(segment
		(start 65.970912 -415.709608)
		(end 66.339212 -415.709608)
		(width 0.14732)
		(layer "In2.Cu")
		(net "CLK_100M_GPU_1_DP")
	)
	(segment
		(start 67.51955 -415.564828)
		(end 67.88785 -415.564828)
		(width 0.14732)
		(layer "In2.Cu")
		(net "CLK_100M_GPU_1_DP")
	)
	(segment
		(start 100.643944 -415.384488)
		(end 100.941124 -415.681668)
		(width 0.14732)
		(layer "In2.Cu")
		(net "CLK_100M_GPU_1_DP")
	)
	(segment
		(start 69.94017 -415.564828)
		(end 70.08495 -415.709608)
		(width 0.14732)
		(layer "In2.Cu")
		(net "CLK_100M_GPU_1_DP")
	)
	(segment
		(start 70.45325 -415.709608)
		(end 70.59803 -415.564828)
		(width 0.14732)
		(layer "In2.Cu")
		(net "CLK_100M_GPU_1_DP")
	)
	(segment
		(start 67.37477 -415.709608)
		(end 67.51955 -415.564828)
		(width 0.14732)
		(layer "In2.Cu")
		(net "CLK_100M_GPU_1_DP")
	)
	(segment
		(start 64.650112 -423.489882)
		(end 64.187324 -423.95267)
		(width 0.14732)
		(layer "In2.Cu")
		(net "CLK_100M_GPU_1_DP")
	)
	(segment
		(start 64.455802 -416.566858)
		(end 64.660526 -416.566858)
		(width 0.14732)
		(layer "In2.Cu")
		(net "CLK_100M_GPU_1_DP")
	)
	(segment
		(start 64.187324 -423.95267)
		(end 63.978536 -423.95267)
		(width 0.14732)
		(layer "In2.Cu")
		(net "CLK_100M_GPU_1_DP")
	)
	(segment
		(start 64.92113 -416.10153)
		(end 65.457832 -415.564828)
		(width 0.14732)
		(layer "In2.Cu")
		(net "CLK_100M_GPU_1_DP")
	)
	(segment
		(start 68.40093 -415.709608)
		(end 68.54571 -415.564828)
		(width 0.14732)
		(layer "In2.Cu")
		(net "CLK_100M_GPU_1_DP")
	)
	(segment
		(start 69.05879 -415.709608)
		(end 69.42709 -415.709608)
		(width 0.14732)
		(layer "In2.Cu")
		(net "CLK_100M_GPU_1_DP")
	)
	(segment
		(start 67.88785 -415.564828)
		(end 68.03263 -415.709608)
		(width 0.14732)
		(layer "In2.Cu")
		(net "CLK_100M_GPU_1_DP")
	)
	(segment
		(start 69.42709 -415.709608)
		(end 69.57187 -415.564828)
		(width 0.14732)
		(layer "In2.Cu")
		(net "CLK_100M_GPU_1_DP")
	)
	(segment
		(start 68.03263 -415.709608)
		(end 68.40093 -415.709608)
		(width 0.14732)
		(layer "In2.Cu")
		(net "CLK_100M_GPU_1_DP")
	)
	(segment
		(start 64.660526 -416.566858)
		(end 64.92113 -416.306254)
		(width 0.14732)
		(layer "In2.Cu")
		(net "CLK_100M_GPU_1_DP")
	)
	(segment
		(start 68.54571 -415.564828)
		(end 68.91401 -415.564828)
		(width 0.14732)
		(layer "In2.Cu")
		(net "CLK_100M_GPU_1_DP")
	)
	(segment
		(start 70.96633 -415.564828)
		(end 71.11111 -415.709608)
		(width 0.14732)
		(layer "In2.Cu")
		(net "CLK_100M_GPU_1_DP")
	)
	(segment
		(start 63.978536 -423.95267)
		(end 63.831216 -423.80535)
		(width 0.14732)
		(layer "In2.Cu")
		(net "CLK_100M_GPU_1_DP")
	)
	(segment
		(start 99.222052 -415.384488)
		(end 100.643944 -415.384488)
		(width 0.14732)
		(layer "In2.Cu")
		(net "CLK_100M_GPU_1_DP")
	)
	(segment
		(start 64.92113 -416.306254)
		(end 64.92113 -416.10153)
		(width 0.14732)
		(layer "In2.Cu")
		(net "CLK_100M_GPU_1_DP")
	)
	(segment
		(start 70.08495 -415.709608)
		(end 70.45325 -415.709608)
		(width 0.14732)
		(layer "In2.Cu")
		(net "CLK_100M_GPU_1_DP")
	)
	(segment
		(start 70.59803 -415.564828)
		(end 70.96633 -415.564828)
		(width 0.14732)
		(layer "In2.Cu")
		(net "CLK_100M_GPU_1_DP")
	)
	(segment
		(start 63.831216 -423.80535)
		(end 63.831216 -417.191444)
		(width 0.14732)
		(layer "In2.Cu")
		(net "CLK_100M_GPU_1_DP")
	)
	(segment
		(start 68.91401 -415.564828)
		(end 69.05879 -415.709608)
		(width 0.14732)
		(layer "In2.Cu")
		(net "CLK_100M_GPU_1_DP")
	)
	(segment
		(start 101.243384 -415.120328)
		(end 100.941124 -414.818068)
		(width 0.13208)
		(layer "F.Cu")
		(net "CLK_100M_GPU_1_DN")
	)
	(segment
		(start 106.30916 -414.741868)
		(end 105.9307 -415.120328)
		(width 0.13208)
		(layer "F.Cu")
		(net "CLK_100M_GPU_1_DN")
	)
	(segment
		(start 105.9307 -415.120328)
		(end 101.243384 -415.120328)
		(width 0.13208)
		(layer "F.Cu")
		(net "CLK_100M_GPU_1_DN")
	)
	(via
		(at 100.941124 -414.818068)
		(size 0.508)
		(drill 0.254)
		(layers "F.Cu" "B.Cu")
		(net "CLK_100M_GPU_1_DN")
	)
	(segment
		(start 98.92792 -415.290508)
		(end 99.10826 -415.110168)
		(width 0.14732)
		(layer "In2.Cu")
		(net "CLK_100M_GPU_1_DN")
	)
	(segment
		(start 63.556896 -417.077652)
		(end 65.34404 -415.290508)
		(width 0.14732)
		(layer "In2.Cu")
		(net "CLK_100M_GPU_1_DN")
	)
	(segment
		(start 65.34404 -415.290508)
		(end 98.92792 -415.290508)
		(width 0.14732)
		(layer "In2.Cu")
		(net "CLK_100M_GPU_1_DN")
	)
	(segment
		(start 100.649024 -415.110168)
		(end 100.941124 -414.818068)
		(width 0.14732)
		(layer "In2.Cu")
		(net "CLK_100M_GPU_1_DN")
	)
	(segment
		(start 64.187324 -424.22699)
		(end 63.864744 -424.22699)
		(width 0.14732)
		(layer "In2.Cu")
		(net "CLK_100M_GPU_1_DN")
	)
	(segment
		(start 99.10826 -415.110168)
		(end 100.649024 -415.110168)
		(width 0.14732)
		(layer "In2.Cu")
		(net "CLK_100M_GPU_1_DN")
	)
	(segment
		(start 64.650112 -424.689778)
		(end 64.187324 -424.22699)
		(width 0.14732)
		(layer "In2.Cu")
		(net "CLK_100M_GPU_1_DN")
	)
	(segment
		(start 63.864744 -424.22699)
		(end 63.556896 -423.919142)
		(width 0.14732)
		(layer "In2.Cu")
		(net "CLK_100M_GPU_1_DN")
	)
	(segment
		(start 63.556896 -423.919142)
		(end 63.556896 -417.077652)
		(width 0.14732)
		(layer "In2.Cu")
		(net "CLK_100M_GPU_1_DN")
	)
	(segment
		(start 233.230166 -251.759974)
		(end 231.068118 -251.759974)
		(width 0.13208)
		(layer "F.Cu")
		(net "CLK_100M_BMC_RC_DP_R")
	)
	(segment
		(start 233.529378 -251.88037)
		(end 233.350562 -251.88037)
		(width 0.13208)
		(layer "F.Cu")
		(net "CLK_100M_BMC_RC_DP_R")
	)
	(segment
		(start 233.350562 -251.88037)
		(end 233.230166 -251.759974)
		(width 0.13208)
		(layer "F.Cu")
		(net "CLK_100M_BMC_RC_DP_R")
	)
	(segment
		(start 231.068118 -251.759974)
		(end 230.648256 -252.179836)
		(width 0.13208)
		(layer "F.Cu")
		(net "CLK_100M_BMC_RC_DP_R")
	)
	(segment
		(start 167.153082 -171.17568)
		(end 186.880754 -175.09998)
		(width 0.13208)
		(layer "F.Cu")
		(net "CLK_100M_BMC_RC_DP")
	)
	(segment
		(start 137.16889 -77.101954)
		(end 137.16889 -77.103478)
		(width 0.13208)
		(layer "F.Cu")
		(net "CLK_100M_BMC_RC_DP")
	)
	(segment
		(start 137.165588 -77.072744)
		(end 137.165842 -77.072744)
		(width 0.13208)
		(layer "F.Cu")
		(net "CLK_100M_BMC_RC_DP")
	)
	(segment
		(start 136.275572 -72.596756)
		(end 137.165588 -77.072744)
		(width 0.13208)
		(layer "F.Cu")
		(net "CLK_100M_BMC_RC_DP")
	)
	(segment
		(start 130.946906 -13.127228)
		(end 130.776218 -12.95654)
		(width 0.13208)
		(layer "F.Cu")
		(net "CLK_100M_BMC_RC_DP")
	)
	(segment
		(start 137.67816 -82.2579)
		(end 137.67816 -105.309162)
		(width 0.13208)
		(layer "F.Cu")
		(net "CLK_100M_BMC_RC_DP")
	)
	(segment
		(start 137.67816 -105.309162)
		(end 140.53312 -112.201706)
		(width 0.13208)
		(layer "F.Cu")
		(net "CLK_100M_BMC_RC_DP")
	)
	(segment
		(start 128.717294 -12.158472)
		(end 125.659896 -19.539966)
		(width 0.13208)
		(layer "F.Cu")
		(net "CLK_100M_BMC_RC_DP")
	)
	(segment
		(start 139.40028 -125.034548)
		(end 139.40028 -143.805148)
		(width 0.13208)
		(layer "F.Cu")
		(net "CLK_100M_BMC_RC_DP")
	)
	(segment
		(start 226.964494 -246.28094)
		(end 226.964494 -250.241562)
		(width 0.13208)
		(layer "F.Cu")
		(net "CLK_100M_BMC_RC_DP")
	)
	(segment
		(start 140.53312 -144.937988)
		(end 140.53312 -148.696934)
		(width 0.13208)
		(layer "F.Cu")
		(net "CLK_100M_BMC_RC_DP")
	)
	(segment
		(start 137.168636 -77.100684)
		(end 137.16889 -77.101954)
		(width 0.13208)
		(layer "F.Cu")
		(net "CLK_100M_BMC_RC_DP")
	)
	(segment
		(start 229.00132 -233.35234)
		(end 226.964494 -246.28094)
		(width 0.13208)
		(layer "F.Cu")
		(net "CLK_100M_BMC_RC_DP")
	)
	(segment
		(start 129.201418 -11.674348)
		(end 128.717294 -12.158472)
		(width 0.13208)
		(layer "F.Cu")
		(net "CLK_100M_BMC_RC_DP")
	)
	(segment
		(start 140.53312 -148.696934)
		(end 160.082484 -168.246552)
		(width 0.13208)
		(layer "F.Cu")
		(net "CLK_100M_BMC_RC_DP")
	)
	(segment
		(start 186.880754 -175.09998)
		(end 218.1352 -188.046106)
		(width 0.13208)
		(layer "F.Cu")
		(net "CLK_100M_BMC_RC_DP")
	)
	(segment
		(start 137.16762 -77.081634)
		(end 137.16762 -77.086714)
		(width 0.13208)
		(layer "F.Cu")
		(net "CLK_100M_BMC_RC_DP")
	)
	(segment
		(start 226.964494 -250.241562)
		(end 228.537008 -251.814076)
		(width 0.13208)
		(layer "F.Cu")
		(net "CLK_100M_BMC_RC_DP")
	)
	(segment
		(start 229.482396 -251.814076)
		(end 229.848156 -252.179836)
		(width 0.13208)
		(layer "F.Cu")
		(net "CLK_100M_BMC_RC_DP")
	)
	(segment
		(start 134.859522 -69.178932)
		(end 136.275572 -72.596756)
		(width 0.13208)
		(layer "F.Cu")
		(net "CLK_100M_BMC_RC_DP")
	)
	(segment
		(start 133.638036 -65.152016)
		(end 134.859522 -69.178932)
		(width 0.13208)
		(layer "F.Cu")
		(net "CLK_100M_BMC_RC_DP")
	)
	(segment
		(start 137.16762 -77.086714)
		(end 137.168636 -77.099414)
		(width 0.13208)
		(layer "F.Cu")
		(net "CLK_100M_BMC_RC_DP")
	)
	(segment
		(start 133.638036 -59.201304)
		(end 133.638036 -65.152016)
		(width 0.13208)
		(layer "F.Cu")
		(net "CLK_100M_BMC_RC_DP")
	)
	(segment
		(start 137.168636 -77.099414)
		(end 137.168636 -77.100684)
		(width 0.13208)
		(layer "F.Cu")
		(net "CLK_100M_BMC_RC_DP")
	)
	(segment
		(start 130.776218 -12.95654)
		(end 130.776218 -12.056364)
		(width 0.13208)
		(layer "F.Cu")
		(net "CLK_100M_BMC_RC_DP")
	)
	(segment
		(start 218.1352 -188.046106)
		(end 220.096588 -189.356746)
		(width 0.13208)
		(layer "F.Cu")
		(net "CLK_100M_BMC_RC_DP")
	)
	(segment
		(start 139.40028 -143.805148)
		(end 140.53312 -144.937988)
		(width 0.13208)
		(layer "F.Cu")
		(net "CLK_100M_BMC_RC_DP")
	)
	(segment
		(start 129.042668 -50.003202)
		(end 131.633722 -52.594256)
		(width 0.13208)
		(layer "F.Cu")
		(net "CLK_100M_BMC_RC_DP")
	)
	(segment
		(start 140.53312 -112.201706)
		(end 140.53312 -123.901708)
		(width 0.13208)
		(layer "F.Cu")
		(net "CLK_100M_BMC_RC_DP")
	)
	(segment
		(start 137.165842 -77.072744)
		(end 137.167112 -77.078078)
		(width 0.13208)
		(layer "F.Cu")
		(net "CLK_100M_BMC_RC_DP")
	)
	(segment
		(start 137.16889 -77.103478)
		(end 137.67816 -82.2579)
		(width 0.13208)
		(layer "F.Cu")
		(net "CLK_100M_BMC_RC_DP")
	)
	(segment
		(start 130.946906 -13.600176)
		(end 130.946906 -13.127228)
		(width 0.13208)
		(layer "F.Cu")
		(net "CLK_100M_BMC_RC_DP")
	)
	(segment
		(start 160.082484 -168.246552)
		(end 167.153082 -171.17568)
		(width 0.13208)
		(layer "F.Cu")
		(net "CLK_100M_BMC_RC_DP")
	)
	(segment
		(start 125.464824 -20.520152)
		(end 125.464824 -38.208712)
		(width 0.13208)
		(layer "F.Cu")
		(net "CLK_100M_BMC_RC_DP")
	)
	(segment
		(start 228.537008 -251.814076)
		(end 229.482396 -251.814076)
		(width 0.13208)
		(layer "F.Cu")
		(net "CLK_100M_BMC_RC_DP")
	)
	(segment
		(start 229.00132 -198.261478)
		(end 229.00132 -233.35234)
		(width 0.13208)
		(layer "F.Cu")
		(net "CLK_100M_BMC_RC_DP")
	)
	(segment
		(start 131.633722 -52.594256)
		(end 133.638036 -59.201304)
		(width 0.13208)
		(layer "F.Cu")
		(net "CLK_100M_BMC_RC_DP")
	)
	(segment
		(start 137.167112 -77.078078)
		(end 137.16762 -77.081634)
		(width 0.13208)
		(layer "F.Cu")
		(net "CLK_100M_BMC_RC_DP")
	)
	(segment
		(start 130.394202 -11.674348)
		(end 129.201418 -11.674348)
		(width 0.13208)
		(layer "F.Cu")
		(net "CLK_100M_BMC_RC_DP")
	)
	(segment
		(start 125.464824 -38.208712)
		(end 129.042668 -50.003202)
		(width 0.13208)
		(layer "F.Cu")
		(net "CLK_100M_BMC_RC_DP")
	)
	(segment
		(start 125.659896 -19.539966)
		(end 125.464824 -20.520152)
		(width 0.13208)
		(layer "F.Cu")
		(net "CLK_100M_BMC_RC_DP")
	)
	(segment
		(start 140.53312 -123.901708)
		(end 139.40028 -125.034548)
		(width 0.13208)
		(layer "F.Cu")
		(net "CLK_100M_BMC_RC_DP")
	)
	(segment
		(start 130.776218 -12.056364)
		(end 130.394202 -11.674348)
		(width 0.13208)
		(layer "F.Cu")
		(net "CLK_100M_BMC_RC_DP")
	)
	(segment
		(start 220.096588 -189.356746)
		(end 229.00132 -198.261478)
		(width 0.13208)
		(layer "F.Cu")
		(net "CLK_100M_BMC_RC_DP")
	)
	(segment
		(start 233.37139 -251.380498)
		(end 233.250994 -251.500894)
		(width 0.13208)
		(layer "F.Cu")
		(net "CLK_100M_BMC_RC_DN_R")
	)
	(segment
		(start 233.250994 -251.500894)
		(end 230.959914 -251.500894)
		(width 0.13208)
		(layer "F.Cu")
		(net "CLK_100M_BMC_RC_DN_R")
	)
	(segment
		(start 233.529378 -251.380498)
		(end 233.37139 -251.380498)
		(width 0.13208)
		(layer "F.Cu")
		(net "CLK_100M_BMC_RC_DN_R")
	)
	(segment
		(start 230.959914 -251.500894)
		(end 230.648256 -251.189236)
		(width 0.13208)
		(layer "F.Cu")
		(net "CLK_100M_BMC_RC_DN_R")
	)
	(segment
		(start 160.229296 -168.026842)
		(end 167.228266 -170.926506)
		(width 0.13208)
		(layer "F.Cu")
		(net "CLK_100M_BMC_RC_DN")
	)
	(segment
		(start 130.517138 -12.962636)
		(end 130.517138 -12.163806)
		(width 0.13208)
		(layer "F.Cu")
		(net "CLK_100M_BMC_RC_DN")
	)
	(segment
		(start 227.223574 -249.1232)
		(end 227.348034 -249.24766)
		(width 0.13208)
		(layer "F.Cu")
		(net "CLK_100M_BMC_RC_DN")
	)
	(segment
		(start 151.822912 -159.444182)
		(end 151.822912 -159.620204)
		(width 0.13208)
		(layer "F.Cu")
		(net "CLK_100M_BMC_RC_DN")
	)
	(segment
		(start 140.7922 -144.830546)
		(end 140.7922 -148.589492)
		(width 0.13208)
		(layer "F.Cu")
		(net "CLK_100M_BMC_RC_DN")
	)
	(segment
		(start 130.28676 -11.933428)
		(end 129.30886 -11.933428)
		(width 0.13208)
		(layer "F.Cu")
		(net "CLK_100M_BMC_RC_DN")
	)
	(segment
		(start 136.524746 -72.521064)
		(end 137.4267 -77.055472)
		(width 0.13208)
		(layer "F.Cu")
		(net "CLK_100M_BMC_RC_DN")
	)
	(segment
		(start 147.687792 -155.485084)
		(end 148.461984 -156.259276)
		(width 0.13208)
		(layer "F.Cu")
		(net "CLK_100M_BMC_RC_DN")
	)
	(segment
		(start 167.228266 -170.926506)
		(end 167.228774 -170.926506)
		(width 0.13208)
		(layer "F.Cu")
		(net "CLK_100M_BMC_RC_DN")
	)
	(segment
		(start 127.071628 -16.808196)
		(end 127.071882 -16.80845)
		(width 0.13208)
		(layer "F.Cu")
		(net "CLK_100M_BMC_RC_DN")
	)
	(segment
		(start 129.271776 -49.865788)
		(end 131.86283 -52.456842)
		(width 0.13208)
		(layer "F.Cu")
		(net "CLK_100M_BMC_RC_DN")
	)
	(segment
		(start 137.4267 -77.055472)
		(end 137.4267 -77.0763)
		(width 0.13208)
		(layer "F.Cu")
		(net "CLK_100M_BMC_RC_DN")
	)
	(segment
		(start 150.411942 -158.033212)
		(end 150.411942 -158.209234)
		(width 0.13208)
		(layer "F.Cu")
		(net "CLK_100M_BMC_RC_DN")
	)
	(segment
		(start 167.228774 -170.926506)
		(end 186.956446 -174.850806)
		(width 0.13208)
		(layer "F.Cu")
		(net "CLK_100M_BMC_RC_DN")
	)
	(segment
		(start 128.534414 -13.602716)
		(end 128.384554 -13.964412)
		(width 0.13208)
		(layer "F.Cu")
		(net "CLK_100M_BMC_RC_DN")
	)
	(segment
		(start 128.384554 -13.964412)
		(end 128.22174 -14.031722)
		(width 0.13208)
		(layer "F.Cu")
		(net "CLK_100M_BMC_RC_DN")
	)
	(segment
		(start 128.467104 -13.440156)
		(end 128.534414 -13.602716)
		(width 0.13208)
		(layer "F.Cu")
		(net "CLK_100M_BMC_RC_DN")
	)
	(segment
		(start 147.687792 -155.309062)
		(end 147.687792 -155.485084)
		(width 0.13208)
		(layer "F.Cu")
		(net "CLK_100M_BMC_RC_DN")
	)
	(segment
		(start 128.221994 -14.031976)
		(end 127.960882 -14.662404)
		(width 0.13208)
		(layer "F.Cu")
		(net "CLK_100M_BMC_RC_DN")
	)
	(segment
		(start 152.956006 -160.577276)
		(end 153.232612 -160.853882)
		(width 0.13208)
		(layer "F.Cu")
		(net "CLK_100M_BMC_RC_DN")
	)
	(segment
		(start 186.956446 -174.850806)
		(end 218.258136 -187.816236)
		(width 0.13208)
		(layer "F.Cu")
		(net "CLK_100M_BMC_RC_DN")
	)
	(segment
		(start 147.411186 -155.032456)
		(end 147.687792 -155.309062)
		(width 0.13208)
		(layer "F.Cu")
		(net "CLK_100M_BMC_RC_DN")
	)
	(segment
		(start 227.348034 -248.61774)
		(end 227.223574 -248.7422)
		(width 0.13208)
		(layer "F.Cu")
		(net "CLK_100M_BMC_RC_DN")
	)
	(segment
		(start 227.579174 -250.48972)
		(end 227.755196 -250.48972)
		(width 0.13208)
		(layer "F.Cu")
		(net "CLK_100M_BMC_RC_DN")
	)
	(segment
		(start 125.90907 -19.615658)
		(end 125.723904 -20.545806)
		(width 0.13208)
		(layer "F.Cu")
		(net "CLK_100M_BMC_RC_DN")
	)
	(segment
		(start 151.370284 -159.167576)
		(end 151.546306 -159.167576)
		(width 0.13208)
		(layer "F.Cu")
		(net "CLK_100M_BMC_RC_DN")
	)
	(segment
		(start 129.30886 -11.933428)
		(end 128.937004 -12.305284)
		(width 0.13208)
		(layer "F.Cu")
		(net "CLK_100M_BMC_RC_DN")
	)
	(segment
		(start 133.897116 -65.113408)
		(end 135.10387 -69.091556)
		(width 0.13208)
		(layer "F.Cu")
		(net "CLK_100M_BMC_RC_DN")
	)
	(segment
		(start 229.2604 -232.99166)
		(end 229.2604 -233.37266)
		(width 0.13208)
		(layer "F.Cu")
		(net "CLK_100M_BMC_RC_DN")
	)
	(segment
		(start 227.223574 -246.30126)
		(end 227.223574 -248.11228)
		(width 0.13208)
		(layer "F.Cu")
		(net "CLK_100M_BMC_RC_DN")
	)
	(segment
		(start 153.232612 -160.853882)
		(end 153.232612 -161.030158)
		(width 0.13208)
		(layer "F.Cu")
		(net "CLK_100M_BMC_RC_DN")
	)
	(segment
		(start 128.028192 -14.82471)
		(end 127.878332 -15.186406)
		(width 0.13208)
		(layer "F.Cu")
		(net "CLK_100M_BMC_RC_DN")
	)
	(segment
		(start 229.38486 -232.8672)
		(end 229.2604 -232.99166)
		(width 0.13208)
		(layer "F.Cu")
		(net "CLK_100M_BMC_RC_DN")
	)
	(segment
		(start 150.135336 -157.756606)
		(end 150.411942 -158.033212)
		(width 0.13208)
		(layer "F.Cu")
		(net "CLK_100M_BMC_RC_DN")
	)
	(segment
		(start 127.234442 -16.740886)
		(end 127.071628 -16.808196)
		(width 0.13208)
		(layer "F.Cu")
		(net "CLK_100M_BMC_RC_DN")
	)
	(segment
		(start 128.22174 -14.031722)
		(end 128.221994 -14.031976)
		(width 0.13208)
		(layer "F.Cu")
		(net "CLK_100M_BMC_RC_DN")
	)
	(segment
		(start 139.65936 -125.14199)
		(end 139.65936 -143.697706)
		(width 0.13208)
		(layer "F.Cu")
		(net "CLK_100M_BMC_RC_DN")
	)
	(segment
		(start 137.4267 -77.0763)
		(end 137.426954 -77.077824)
		(width 0.13208)
		(layer "F.Cu")
		(net "CLK_100M_BMC_RC_DN")
	)
	(segment
		(start 148.914612 -156.711904)
		(end 149.959314 -157.756606)
		(width 0.13208)
		(layer "F.Cu")
		(net "CLK_100M_BMC_RC_DN")
	)
	(segment
		(start 139.65936 -143.697706)
		(end 140.7922 -144.830546)
		(width 0.13208)
		(layer "F.Cu")
		(net "CLK_100M_BMC_RC_DN")
	)
	(segment
		(start 125.723904 -38.170104)
		(end 129.271776 -49.865788)
		(width 0.13208)
		(layer "F.Cu")
		(net "CLK_100M_BMC_RC_DN")
	)
	(segment
		(start 220.261942 -189.155324)
		(end 229.2604 -198.154036)
		(width 0.13208)
		(layer "F.Cu")
		(net "CLK_100M_BMC_RC_DN")
	)
	(segment
		(start 127.316738 -16.21663)
		(end 127.384302 -16.37919)
		(width 0.13208)
		(layer "F.Cu")
		(net "CLK_100M_BMC_RC_DN")
	)
	(segment
		(start 127.071882 -16.80845)
		(end 125.90907 -19.615658)
		(width 0.13208)
		(layer "F.Cu")
		(net "CLK_100M_BMC_RC_DN")
	)
	(segment
		(start 229.2604 -232.36174)
		(end 229.38486 -232.4862)
		(width 0.13208)
		(layer "F.Cu")
		(net "CLK_100M_BMC_RC_DN")
	)
	(segment
		(start 227.755196 -250.48972)
		(end 228.024944 -250.759468)
		(width 0.13208)
		(layer "F.Cu")
		(net "CLK_100M_BMC_RC_DN")
	)
	(segment
		(start 127.384302 -16.37919)
		(end 127.234442 -16.740886)
		(width 0.13208)
		(layer "F.Cu")
		(net "CLK_100M_BMC_RC_DN")
	)
	(segment
		(start 127.316992 -16.216122)
		(end 127.316738 -16.21663)
		(width 0.13208)
		(layer "F.Cu")
		(net "CLK_100M_BMC_RC_DN")
	)
	(segment
		(start 147.235164 -155.032456)
		(end 147.411186 -155.032456)
		(width 0.13208)
		(layer "F.Cu")
		(net "CLK_100M_BMC_RC_DN")
	)
	(segment
		(start 149.959314 -157.756606)
		(end 150.135336 -157.756606)
		(width 0.13208)
		(layer "F.Cu")
		(net "CLK_100M_BMC_RC_DN")
	)
	(segment
		(start 148.914612 -156.535882)
		(end 148.914612 -156.711904)
		(width 0.13208)
		(layer "F.Cu")
		(net "CLK_100M_BMC_RC_DN")
	)
	(segment
		(start 227.348034 -249.24766)
		(end 227.348034 -249.62866)
		(width 0.13208)
		(layer "F.Cu")
		(net "CLK_100M_BMC_RC_DN")
	)
	(segment
		(start 151.822912 -159.620204)
		(end 152.779984 -160.577276)
		(width 0.13208)
		(layer "F.Cu")
		(net "CLK_100M_BMC_RC_DN")
	)
	(segment
		(start 137.93724 -82.244946)
		(end 137.93724 -105.2576)
		(width 0.13208)
		(layer "F.Cu")
		(net "CLK_100M_BMC_RC_DN")
	)
	(segment
		(start 131.86283 -52.456842)
		(end 133.897116 -59.162696)
		(width 0.13208)
		(layer "F.Cu")
		(net "CLK_100M_BMC_RC_DN")
	)
	(segment
		(start 229.2604 -198.154036)
		(end 229.2604 -232.36174)
		(width 0.13208)
		(layer "F.Cu")
		(net "CLK_100M_BMC_RC_DN")
	)
	(segment
		(start 125.723904 -20.545806)
		(end 125.723904 -38.170104)
		(width 0.13208)
		(layer "F.Cu")
		(net "CLK_100M_BMC_RC_DN")
	)
	(segment
		(start 227.223574 -248.7422)
		(end 227.223574 -249.1232)
		(width 0.13208)
		(layer "F.Cu")
		(net "CLK_100M_BMC_RC_DN")
	)
	(segment
		(start 127.715772 -15.253716)
		(end 127.316992 -16.216122)
		(width 0.13208)
		(layer "F.Cu")
		(net "CLK_100M_BMC_RC_DN")
	)
	(segment
		(start 137.93724 -105.2576)
		(end 140.7922 -112.150144)
		(width 0.13208)
		(layer "F.Cu")
		(net "CLK_100M_BMC_RC_DN")
	)
	(segment
		(start 133.897116 -59.162696)
		(end 133.897116 -65.113408)
		(width 0.13208)
		(layer "F.Cu")
		(net "CLK_100M_BMC_RC_DN")
	)
	(segment
		(start 151.546306 -159.167576)
		(end 151.822912 -159.444182)
		(width 0.13208)
		(layer "F.Cu")
		(net "CLK_100M_BMC_RC_DN")
	)
	(segment
		(start 130.346958 -13.132816)
		(end 130.517138 -12.962636)
		(width 0.13208)
		(layer "F.Cu")
		(net "CLK_100M_BMC_RC_DN")
	)
	(segment
		(start 228.024944 -250.759468)
		(end 228.024944 -250.93549)
		(width 0.13208)
		(layer "F.Cu")
		(net "CLK_100M_BMC_RC_DN")
	)
	(segment
		(start 152.779984 -160.577276)
		(end 152.956006 -160.577276)
		(width 0.13208)
		(layer "F.Cu")
		(net "CLK_100M_BMC_RC_DN")
	)
	(segment
		(start 150.411942 -158.209234)
		(end 151.370284 -159.167576)
		(width 0.13208)
		(layer "F.Cu")
		(net "CLK_100M_BMC_RC_DN")
	)
	(segment
		(start 229.38486 -232.4862)
		(end 229.38486 -232.8672)
		(width 0.13208)
		(layer "F.Cu")
		(net "CLK_100M_BMC_RC_DN")
	)
	(segment
		(start 218.258136 -187.816236)
		(end 220.261942 -189.155324)
		(width 0.13208)
		(layer "F.Cu")
		(net "CLK_100M_BMC_RC_DN")
	)
	(segment
		(start 148.461984 -156.259276)
		(end 148.638006 -156.259276)
		(width 0.13208)
		(layer "F.Cu")
		(net "CLK_100M_BMC_RC_DN")
	)
	(segment
		(start 135.10387 -69.091556)
		(end 136.524746 -72.521064)
		(width 0.13208)
		(layer "F.Cu")
		(net "CLK_100M_BMC_RC_DN")
	)
	(segment
		(start 153.232612 -161.030158)
		(end 160.229296 -168.026842)
		(width 0.13208)
		(layer "F.Cu")
		(net "CLK_100M_BMC_RC_DN")
	)
	(segment
		(start 130.346958 -13.600176)
		(end 130.346958 -13.132816)
		(width 0.13208)
		(layer "F.Cu")
		(net "CLK_100M_BMC_RC_DN")
	)
	(segment
		(start 228.64445 -251.554996)
		(end 229.482396 -251.554996)
		(width 0.13208)
		(layer "F.Cu")
		(net "CLK_100M_BMC_RC_DN")
	)
	(segment
		(start 227.223574 -249.75312)
		(end 227.223574 -250.13412)
		(width 0.13208)
		(layer "F.Cu")
		(net "CLK_100M_BMC_RC_DN")
	)
	(segment
		(start 229.482396 -251.554996)
		(end 229.848156 -251.189236)
		(width 0.13208)
		(layer "F.Cu")
		(net "CLK_100M_BMC_RC_DN")
	)
	(segment
		(start 137.426954 -77.077824)
		(end 137.93724 -82.244946)
		(width 0.13208)
		(layer "F.Cu")
		(net "CLK_100M_BMC_RC_DN")
	)
	(segment
		(start 229.2604 -233.37266)
		(end 227.223574 -246.30126)
		(width 0.13208)
		(layer "F.Cu")
		(net "CLK_100M_BMC_RC_DN")
	)
	(segment
		(start 227.348034 -248.23674)
		(end 227.348034 -248.61774)
		(width 0.13208)
		(layer "F.Cu")
		(net "CLK_100M_BMC_RC_DN")
	)
	(segment
		(start 228.024944 -250.93549)
		(end 228.64445 -251.554996)
		(width 0.13208)
		(layer "F.Cu")
		(net "CLK_100M_BMC_RC_DN")
	)
	(segment
		(start 227.223574 -250.13412)
		(end 227.579174 -250.48972)
		(width 0.13208)
		(layer "F.Cu")
		(net "CLK_100M_BMC_RC_DN")
	)
	(segment
		(start 227.223574 -248.11228)
		(end 227.348034 -248.23674)
		(width 0.13208)
		(layer "F.Cu")
		(net "CLK_100M_BMC_RC_DN")
	)
	(segment
		(start 227.348034 -249.62866)
		(end 227.223574 -249.75312)
		(width 0.13208)
		(layer "F.Cu")
		(net "CLK_100M_BMC_RC_DN")
	)
	(segment
		(start 140.7922 -112.150144)
		(end 140.7922 -124.00915)
		(width 0.13208)
		(layer "F.Cu")
		(net "CLK_100M_BMC_RC_DN")
	)
	(segment
		(start 128.937004 -12.305284)
		(end 128.467104 -13.440156)
		(width 0.13208)
		(layer "F.Cu")
		(net "CLK_100M_BMC_RC_DN")
	)
	(segment
		(start 127.960882 -14.662404)
		(end 128.028192 -14.82471)
		(width 0.13208)
		(layer "F.Cu")
		(net "CLK_100M_BMC_RC_DN")
	)
	(segment
		(start 140.7922 -148.589492)
		(end 147.235164 -155.032456)
		(width 0.13208)
		(layer "F.Cu")
		(net "CLK_100M_BMC_RC_DN")
	)
	(segment
		(start 140.7922 -124.00915)
		(end 139.65936 -125.14199)
		(width 0.13208)
		(layer "F.Cu")
		(net "CLK_100M_BMC_RC_DN")
	)
	(segment
		(start 130.517138 -12.163806)
		(end 130.28676 -11.933428)
		(width 0.13208)
		(layer "F.Cu")
		(net "CLK_100M_BMC_RC_DN")
	)
	(segment
		(start 148.638006 -156.259276)
		(end 148.914612 -156.535882)
		(width 0.13208)
		(layer "F.Cu")
		(net "CLK_100M_BMC_RC_DN")
	)
	(segment
		(start 127.878332 -15.186406)
		(end 127.715772 -15.253716)
		(width 0.13208)
		(layer "F.Cu")
		(net "CLK_100M_BMC_RC_DN")
	)
	(segment
		(start 161.23793 -104.485948)
		(end 161.85388 -104.485948)
		(width 0.12954)
		(layer "F.Cu")
		(net "BIC_MONITER_ISO_R")
	)
	(segment
		(start 171.755562 -106.575352)
		(end 171.355512 -106.175302)
		(width 0.12954)
		(layer "F.Cu")
		(net "BIC_MONITER_ISO_R")
	)
	(via
		(at 171.355512 -106.175302)
		(size 0.4572)
		(drill 0.254)
		(layers "F.Cu" "B.Cu")
		(net "BIC_MONITER_ISO_R")
	)
	(via
		(at 161.85388 -104.485948)
		(size 0.508)
		(drill 0.254)
		(layers "F.Cu" "B.Cu")
		(net "BIC_MONITER_ISO_R")
	)
	(segment
		(start 167.65778 -105.240328)
		(end 168.91508 -106.497628)
		(width 0.127)
		(layer "In6.Cu")
		(net "BIC_MONITER_ISO_R")
	)
	(segment
		(start 161.85388 -104.485948)
		(end 162.59048 -105.222548)
		(width 0.127)
		(layer "In6.Cu")
		(net "BIC_MONITER_ISO_R")
	)
	(segment
		(start 162.59048 -105.222548)
		(end 163.7665 -105.222548)
		(width 0.127)
		(layer "In6.Cu")
		(net "BIC_MONITER_ISO_R")
	)
	(segment
		(start 168.91508 -106.497628)
		(end 171.033186 -106.497628)
		(width 0.127)
		(layer "In6.Cu")
		(net "BIC_MONITER_ISO_R")
	)
	(segment
		(start 163.78428 -105.240328)
		(end 167.65778 -105.240328)
		(width 0.127)
		(layer "In6.Cu")
		(net "BIC_MONITER_ISO_R")
	)
	(segment
		(start 171.033186 -106.497628)
		(end 171.355512 -106.175302)
		(width 0.127)
		(layer "In6.Cu")
		(net "BIC_MONITER_ISO_R")
	)
	(segment
		(start 163.7665 -105.222548)
		(end 163.78428 -105.240328)
		(width 0.127)
		(layer "In6.Cu")
		(net "BIC_MONITER_ISO_R")
	)
	(segment
		(start 178.1556 -113.77549)
		(end 177.75555 -114.17554)
		(width 0.381)
		(layer "F.Cu")
		(net "VCC_PLD_CORE")
	)
	(segment
		(start 179.755546 -113.77549)
		(end 180.155596 -114.17554)
		(width 0.381)
		(layer "F.Cu")
		(net "VCC_PLD_CORE")
	)
	(segment
		(start 178.1556 -112.97539)
		(end 177.75555 -112.57534)
		(width 0.381)
		(layer "F.Cu")
		(net "VCC_PLD_CORE")
	)
	(segment
		(start 177.355754 -112.97539)
		(end 176.955704 -112.57534)
		(width 0.381)
		(layer "F.Cu")
		(net "VCC_PLD_CORE")
	)
	(segment
		(start 179.755546 -112.97539)
		(end 180.155596 -112.57534)
		(width 0.381)
		(layer "F.Cu")
		(net "VCC_PLD_CORE")
	)
	(segment
		(start 177.355754 -112.175544)
		(end 176.955704 -111.775494)
		(width 0.381)
		(layer "F.Cu")
		(net "VCC_PLD_CORE")
	)
	(segment
		(start 179.755546 -114.575336)
		(end 180.155596 -114.975386)
		(width 0.381)
		(layer "F.Cu")
		(net "VCC_PLD_CORE")
	)
	(segment
		(start 177.355754 -113.77549)
		(end 176.955704 -114.17554)
		(width 0.381)
		(layer "F.Cu")
		(net "VCC_PLD_CORE")
	)
	(segment
		(start 178.9557 -112.97539)
		(end 179.35575 -112.57534)
		(width 0.381)
		(layer "F.Cu")
		(net "VCC_PLD_CORE")
	)
	(segment
		(start 179.755546 -112.175544)
		(end 180.155596 -111.775494)
		(width 0.381)
		(layer "F.Cu")
		(net "VCC_PLD_CORE")
	)
	(segment
		(start 178.9557 -113.77549)
		(end 179.35575 -114.17554)
		(width 0.381)
		(layer "F.Cu")
		(net "VCC_PLD_CORE")
	)
	(segment
		(start 177.355754 -114.575336)
		(end 176.955704 -114.975386)
		(width 0.381)
		(layer "F.Cu")
		(net "VCC_PLD_CORE")
	)
	(via
		(at 178.61788 -124.551948)
		(size 0.508)
		(drill 0.254)
		(layers "F.Cu" "B.Cu")
		(net "VCC_PLD_CORE")
	)
	(via
		(at 177.75555 -114.17554)
		(size 0.4572)
		(drill 0.254)
		(layers "F.Cu" "B.Cu")
		(net "VCC_PLD_CORE")
	)
	(via
		(at 176.955704 -114.17554)
		(size 0.4572)
		(drill 0.254)
		(layers "F.Cu" "B.Cu")
		(net "VCC_PLD_CORE")
	)
	(via
		(at 180.155596 -114.17554)
		(size 0.4572)
		(drill 0.254)
		(layers "F.Cu" "B.Cu")
		(net "VCC_PLD_CORE")
	)
	(via
		(at 176.955704 -114.975386)
		(size 0.4572)
		(drill 0.254)
		(layers "F.Cu" "B.Cu")
		(net "VCC_PLD_CORE")
	)
	(via
		(at 179.35575 -114.17554)
		(size 0.4572)
		(drill 0.254)
		(layers "F.Cu" "B.Cu")
		(net "VCC_PLD_CORE")
	)
	(via
		(at 179.25288 -123.154948)
		(size 0.508)
		(drill 0.254)
		(layers "F.Cu" "B.Cu")
		(net "VCC_PLD_CORE")
	)
	(via
		(at 178.54676 -123.609608)
		(size 0.6604)
		(drill 0.3302)
		(layers "F.Cu" "B.Cu")
		(net "VCC_PLD_CORE")
	)
	(via
		(at 180.155596 -114.975386)
		(size 0.4572)
		(drill 0.254)
		(layers "F.Cu" "B.Cu")
		(net "VCC_PLD_CORE")
	)
	(via
		(at 179.35575 -112.57534)
		(size 0.4572)
		(drill 0.254)
		(layers "F.Cu" "B.Cu")
		(net "VCC_PLD_CORE")
	)
	(via
		(at 180.155596 -111.775494)
		(size 0.4572)
		(drill 0.254)
		(layers "F.Cu" "B.Cu")
		(net "VCC_PLD_CORE")
	)
	(via
		(at 180.155596 -112.57534)
		(size 0.4572)
		(drill 0.254)
		(layers "F.Cu" "B.Cu")
		(net "VCC_PLD_CORE")
	)
	(via
		(at 179.25288 -124.170948)
		(size 0.508)
		(drill 0.254)
		(layers "F.Cu" "B.Cu")
		(net "VCC_PLD_CORE")
	)
	(via
		(at 176.955704 -111.775494)
		(size 0.4572)
		(drill 0.254)
		(layers "F.Cu" "B.Cu")
		(net "VCC_PLD_CORE")
	)
	(via
		(at 177.75555 -112.57534)
		(size 0.4572)
		(drill 0.254)
		(layers "F.Cu" "B.Cu")
		(net "VCC_PLD_CORE")
	)
	(via
		(at 176.955704 -112.57534)
		(size 0.4572)
		(drill 0.254)
		(layers "F.Cu" "B.Cu")
		(net "VCC_PLD_CORE")
	)
	(segment
		(start 188.662056 -16.549878)
		(end 188.661802 -16.549624)
		(width 0.12954)
		(layer "F.Cu")
		(net "UART_BMC_BIC_TX")
	)
	(segment
		(start 188.662056 -16.550132)
		(end 188.662056 -16.549878)
		(width 0.12954)
		(layer "F.Cu")
		(net "UART_BMC_BIC_TX")
	)
	(segment
		(start 188.661802 -15.85087)
		(end 188.27496 -15.464028)
		(width 0.12954)
		(layer "F.Cu")
		(net "UART_BMC_BIC_TX")
	)
	(segment
		(start 188.27496 -15.464028)
		(end 186.9694 -15.464028)
		(width 0.12954)
		(layer "F.Cu")
		(net "UART_BMC_BIC_TX")
	)
	(segment
		(start 186.9694 -15.464028)
		(end 186.91352 -15.408148)
		(width 0.12954)
		(layer "F.Cu")
		(net "UART_BMC_BIC_TX")
	)
	(segment
		(start 188.661802 -16.549624)
		(end 188.661802 -15.85087)
		(width 0.12954)
		(layer "F.Cu")
		(net "UART_BMC_BIC_TX")
	)
	(via
		(at 252.715268 -197.37197)
		(size 0.508)
		(drill 0.254)
		(layers "F.Cu" "B.Cu")
		(net "UART_BMC_BIC_TX")
	)
	(via
		(at 186.91352 -15.408148)
		(size 0.508)
		(drill 0.254)
		(layers "F.Cu" "B.Cu")
		(net "UART_BMC_BIC_TX")
	)
	(via
		(at 362.10748 -395.392148)
		(size 0.508)
		(drill 0.254)
		(layers "F.Cu" "B.Cu")
		(net "UART_BMC_BIC_TX")
	)
	(segment
		(start 251.652532 -198.434706)
		(end 251.652532 -327.050146)
		(width 0.12954)
		(layer "B.Cu")
		(net "UART_BMC_BIC_TX")
	)
	(segment
		(start 271.439132 -346.836746)
		(end 271.439132 -372.965726)
		(width 0.12954)
		(layer "B.Cu")
		(net "UART_BMC_BIC_TX")
	)
	(segment
		(start 252.715268 -197.37197)
		(end 251.652532 -198.434706)
		(width 0.12954)
		(layer "B.Cu")
		(net "UART_BMC_BIC_TX")
	)
	(segment
		(start 350.783906 -382.74752)
		(end 357.545132 -389.508746)
		(width 0.12954)
		(layer "B.Cu")
		(net "UART_BMC_BIC_TX")
	)
	(segment
		(start 357.545132 -389.508746)
		(end 357.545132 -393.521946)
		(width 0.12954)
		(layer "B.Cu")
		(net "UART_BMC_BIC_TX")
	)
	(segment
		(start 361.894628 -395.179296)
		(end 362.10748 -395.392148)
		(width 0.12954)
		(layer "B.Cu")
		(net "UART_BMC_BIC_TX")
	)
	(segment
		(start 281.220926 -382.74752)
		(end 350.783906 -382.74752)
		(width 0.12954)
		(layer "B.Cu")
		(net "UART_BMC_BIC_TX")
	)
	(segment
		(start 357.545132 -393.521946)
		(end 359.202482 -395.179296)
		(width 0.12954)
		(layer "B.Cu")
		(net "UART_BMC_BIC_TX")
	)
	(segment
		(start 271.439132 -372.965726)
		(end 281.220926 -382.74752)
		(width 0.12954)
		(layer "B.Cu")
		(net "UART_BMC_BIC_TX")
	)
	(segment
		(start 359.202482 -395.179296)
		(end 361.894628 -395.179296)
		(width 0.12954)
		(layer "B.Cu")
		(net "UART_BMC_BIC_TX")
	)
	(segment
		(start 251.652532 -327.050146)
		(end 271.439132 -346.836746)
		(width 0.12954)
		(layer "B.Cu")
		(net "UART_BMC_BIC_TX")
	)
	(segment
		(start 191.525906 -33.370774)
		(end 191.525906 -36.322762)
		(width 0.127)
		(layer "In2.Cu")
		(net "UART_BMC_BIC_TX")
	)
	(segment
		(start 370.8781 -414.075372)
		(end 377.006104 -414.075372)
		(width 0.127)
		(layer "In2.Cu")
		(net "UART_BMC_BIC_TX")
	)
	(segment
		(start 187.576206 -29.421074)
		(end 191.525906 -33.370774)
		(width 0.127)
		(layer "In2.Cu")
		(net "UART_BMC_BIC_TX")
	)
	(segment
		(start 227.9142 -118.214648)
		(end 227.584 -118.544848)
		(width 0.127)
		(layer "In2.Cu")
		(net "UART_BMC_BIC_TX")
	)
	(segment
		(start 191.356488 -36.49218)
		(end 191.356488 -44.209716)
		(width 0.127)
		(layer "In2.Cu")
		(net "UART_BMC_BIC_TX")
	)
	(segment
		(start 231.7496 -133.873748)
		(end 232.3846 -134.508748)
		(width 0.127)
		(layer "In2.Cu")
		(net "UART_BMC_BIC_TX")
	)
	(segment
		(start 209.17789 -75.239118)
		(end 227.9142 -93.975428)
		(width 0.127)
		(layer "In2.Cu")
		(net "UART_BMC_BIC_TX")
	)
	(segment
		(start 362.10748 -395.392148)
		(end 362.10748 -399.039588)
		(width 0.127)
		(layer "In2.Cu")
		(net "UART_BMC_BIC_TX")
	)
	(segment
		(start 192.84442 -45.697648)
		(end 192.84442 -53.816504)
		(width 0.127)
		(layer "In2.Cu")
		(net "UART_BMC_BIC_TX")
	)
	(segment
		(start 232.3846 -136.068308)
		(end 252.29058 -155.974288)
		(width 0.127)
		(layer "In2.Cu")
		(net "UART_BMC_BIC_TX")
	)
	(segment
		(start 187.98794 -17.747488)
		(end 187.98794 -19.457416)
		(width 0.127)
		(layer "In2.Cu")
		(net "UART_BMC_BIC_TX")
	)
	(segment
		(start 380.80188 -417.871148)
		(end 392.40968 -417.871148)
		(width 0.127)
		(layer "In2.Cu")
		(net "UART_BMC_BIC_TX")
	)
	(segment
		(start 231.1146 -133.873748)
		(end 231.7496 -133.873748)
		(width 0.127)
		(layer "In2.Cu")
		(net "UART_BMC_BIC_TX")
	)
	(segment
		(start 366.3696 -403.301708)
		(end 366.3696 -409.566872)
		(width 0.127)
		(layer "In2.Cu")
		(net "UART_BMC_BIC_TX")
	)
	(segment
		(start 229.738428 -129.885948)
		(end 229.738428 -132.497576)
		(width 0.127)
		(layer "In2.Cu")
		(net "UART_BMC_BIC_TX")
	)
	(segment
		(start 187.576206 -28.40482)
		(end 187.576206 -29.421074)
		(width 0.127)
		(layer "In2.Cu")
		(net "UART_BMC_BIC_TX")
	)
	(segment
		(start 186.370976 -21.07438)
		(end 186.370976 -21.589492)
		(width 0.127)
		(layer "In2.Cu")
		(net "UART_BMC_BIC_TX")
	)
	(segment
		(start 392.40968 -417.871148)
		(end 395.750034 -421.211502)
		(width 0.127)
		(layer "In2.Cu")
		(net "UART_BMC_BIC_TX")
	)
	(segment
		(start 228.45268 -128.6002)
		(end 229.738428 -129.885948)
		(width 0.127)
		(layer "In2.Cu")
		(net "UART_BMC_BIC_TX")
	)
	(segment
		(start 188.04128 -16.490188)
		(end 188.04128 -17.694148)
		(width 0.127)
		(layer "In2.Cu")
		(net "UART_BMC_BIC_TX")
	)
	(segment
		(start 186.95924 -15.408148)
		(end 188.04128 -16.490188)
		(width 0.127)
		(layer "In2.Cu")
		(net "UART_BMC_BIC_TX")
	)
	(segment
		(start 185.98388 -26.812494)
		(end 187.576206 -28.40482)
		(width 0.127)
		(layer "In2.Cu")
		(net "UART_BMC_BIC_TX")
	)
	(segment
		(start 185.98388 -21.976588)
		(end 185.98388 -26.812494)
		(width 0.127)
		(layer "In2.Cu")
		(net "UART_BMC_BIC_TX")
	)
	(segment
		(start 227.9142 -93.975428)
		(end 227.9142 -118.214648)
		(width 0.127)
		(layer "In2.Cu")
		(net "UART_BMC_BIC_TX")
	)
	(segment
		(start 229.738428 -132.497576)
		(end 231.1146 -133.873748)
		(width 0.127)
		(layer "In2.Cu")
		(net "UART_BMC_BIC_TX")
	)
	(segment
		(start 188.04128 -17.694148)
		(end 187.98794 -17.747488)
		(width 0.127)
		(layer "In2.Cu")
		(net "UART_BMC_BIC_TX")
	)
	(segment
		(start 186.91352 -15.408148)
		(end 186.95924 -15.408148)
		(width 0.127)
		(layer "In2.Cu")
		(net "UART_BMC_BIC_TX")
	)
	(segment
		(start 366.3696 -409.566872)
		(end 370.8781 -414.075372)
		(width 0.127)
		(layer "In2.Cu")
		(net "UART_BMC_BIC_TX")
	)
	(segment
		(start 186.370976 -21.589492)
		(end 185.98388 -21.976588)
		(width 0.127)
		(layer "In2.Cu")
		(net "UART_BMC_BIC_TX")
	)
	(segment
		(start 192.84442 -53.816504)
		(end 209.17789 -70.149974)
		(width 0.127)
		(layer "In2.Cu")
		(net "UART_BMC_BIC_TX")
	)
	(segment
		(start 187.98794 -19.457416)
		(end 186.370976 -21.07438)
		(width 0.127)
		(layer "In2.Cu")
		(net "UART_BMC_BIC_TX")
	)
	(segment
		(start 227.584 -121.003568)
		(end 228.45268 -121.872248)
		(width 0.127)
		(layer "In2.Cu")
		(net "UART_BMC_BIC_TX")
	)
	(segment
		(start 191.356488 -44.209716)
		(end 192.84442 -45.697648)
		(width 0.127)
		(layer "In2.Cu")
		(net "UART_BMC_BIC_TX")
	)
	(segment
		(start 362.10748 -399.039588)
		(end 366.3696 -403.301708)
		(width 0.127)
		(layer "In2.Cu")
		(net "UART_BMC_BIC_TX")
	)
	(segment
		(start 227.584 -118.544848)
		(end 227.584 -121.003568)
		(width 0.127)
		(layer "In2.Cu")
		(net "UART_BMC_BIC_TX")
	)
	(segment
		(start 232.3846 -134.508748)
		(end 232.3846 -136.068308)
		(width 0.127)
		(layer "In2.Cu")
		(net "UART_BMC_BIC_TX")
	)
	(segment
		(start 191.525906 -36.322762)
		(end 191.356488 -36.49218)
		(width 0.127)
		(layer "In2.Cu")
		(net "UART_BMC_BIC_TX")
	)
	(segment
		(start 377.006104 -414.075372)
		(end 380.80188 -417.871148)
		(width 0.127)
		(layer "In2.Cu")
		(net "UART_BMC_BIC_TX")
	)
	(segment
		(start 252.29058 -196.947282)
		(end 252.715268 -197.37197)
		(width 0.127)
		(layer "In2.Cu")
		(net "UART_BMC_BIC_TX")
	)
	(segment
		(start 209.17789 -70.149974)
		(end 209.17789 -75.239118)
		(width 0.127)
		(layer "In2.Cu")
		(net "UART_BMC_BIC_TX")
	)
	(segment
		(start 252.29058 -155.974288)
		(end 252.29058 -196.947282)
		(width 0.127)
		(layer "In2.Cu")
		(net "UART_BMC_BIC_TX")
	)
	(segment
		(start 228.45268 -121.872248)
		(end 228.45268 -128.6002)
		(width 0.127)
		(layer "In2.Cu")
		(net "UART_BMC_BIC_TX")
	)
	(segment
		(start 395.750034 -421.211502)
		(end 395.750034 -424.689778)
		(width 0.127)
		(layer "In2.Cu")
		(net "UART_BMC_BIC_TX")
	)
	(segment
		(start 374.744996 -414.318958)
		(end 374.03151 -414.318958)
		(width 0.12954)
		(layer "F.Cu")
		(net "UART_BMC_BIC_RX")
	)
	(segment
		(start 375.427494 -415.001456)
		(end 374.744996 -414.318958)
		(width 0.12954)
		(layer "F.Cu")
		(net "UART_BMC_BIC_RX")
	)
	(segment
		(start 372.83136 -414.318958)
		(end 374.03151 -414.318958)
		(width 0.12954)
		(layer "F.Cu")
		(net "UART_BMC_BIC_RX")
	)
	(via
		(at 375.427494 -415.001456)
		(size 0.508)
		(drill 0.254)
		(layers "F.Cu" "B.Cu")
		(net "UART_BMC_BIC_RX")
	)
	(segment
		(start 389.31596 -418.983668)
		(end 391.750042 -421.41775)
		(width 0.127)
		(layer "In2.Cu")
		(net "UART_BMC_BIC_RX")
	)
	(segment
		(start 391.750042 -421.41775)
		(end 391.750042 -424.689778)
		(width 0.127)
		(layer "In2.Cu")
		(net "UART_BMC_BIC_RX")
	)
	(segment
		(start 376.121168 -415.001456)
		(end 380.10338 -418.983668)
		(width 0.127)
		(layer "In2.Cu")
		(net "UART_BMC_BIC_RX")
	)
	(segment
		(start 380.10338 -418.983668)
		(end 389.31596 -418.983668)
		(width 0.127)
		(layer "In2.Cu")
		(net "UART_BMC_BIC_RX")
	)
	(segment
		(start 375.427494 -415.001456)
		(end 376.121168 -415.001456)
		(width 0.127)
		(layer "In2.Cu")
		(net "UART_BMC_BIC_RX")
	)
	(segment
		(start 188.061854 -17.714722)
		(end 188.49848 -18.151348)
		(width 0.12954)
		(layer "F.Cu")
		(net "UART_BMC_BIC_BUF_RX")
	)
	(segment
		(start 188.49848 -18.151348)
		(end 188.54928 -18.151348)
		(width 0.12954)
		(layer "F.Cu")
		(net "UART_BMC_BIC_BUF_RX")
	)
	(segment
		(start 188.061854 -17.466056)
		(end 188.061854 -17.714722)
		(width 0.12954)
		(layer "F.Cu")
		(net "UART_BMC_BIC_BUF_RX")
	)
	(segment
		(start 188.062108 -16.550132)
		(end 188.062108 -17.465802)
		(width 0.12954)
		(layer "F.Cu")
		(net "UART_BMC_BIC_BUF_RX")
	)
	(segment
		(start 369.11407 -402.910548)
		(end 369.85448 -402.910548)
		(width 0.12954)
		(layer "F.Cu")
		(net "UART_BMC_BIC_BUF_RX")
	)
	(segment
		(start 188.54928 -18.151348)
		(end 188.62548 -18.227548)
		(width 0.12954)
		(layer "F.Cu")
		(net "UART_BMC_BIC_BUF_RX")
	)
	(segment
		(start 188.062108 -17.465802)
		(end 188.061854 -17.466056)
		(width 0.12954)
		(layer "F.Cu")
		(net "UART_BMC_BIC_BUF_RX")
	)
	(via
		(at 367.94948 -395.265148)
		(size 0.508)
		(drill 0.254)
		(layers "F.Cu" "B.Cu")
		(net "UART_BMC_BIC_BUF_RX")
	)
	(via
		(at 369.85448 -402.910548)
		(size 0.508)
		(drill 0.254)
		(layers "F.Cu" "B.Cu")
		(net "UART_BMC_BIC_BUF_RX")
	)
	(via
		(at 252.76048 -196.372988)
		(size 0.508)
		(drill 0.254)
		(layers "F.Cu" "B.Cu")
		(net "UART_BMC_BIC_BUF_RX")
	)
	(via
		(at 188.62548 -18.227548)
		(size 0.508)
		(drill 0.254)
		(layers "F.Cu" "B.Cu")
		(net "UART_BMC_BIC_BUF_RX")
	)
	(segment
		(start 358.11968 -389.270748)
		(end 351.238312 -382.38938)
		(width 0.12954)
		(layer "B.Cu")
		(net "UART_BMC_BIC_BUF_RX")
	)
	(segment
		(start 359.44048 -394.604748)
		(end 358.11968 -393.283948)
		(width 0.12954)
		(layer "B.Cu")
		(net "UART_BMC_BIC_BUF_RX")
	)
	(segment
		(start 367.28908 -394.604748)
		(end 359.44048 -394.604748)
		(width 0.12954)
		(layer "B.Cu")
		(net "UART_BMC_BIC_BUF_RX")
	)
	(segment
		(start 252.22708 -199.365108)
		(end 253.186438 -198.40575)
		(width 0.12954)
		(layer "B.Cu")
		(net "UART_BMC_BIC_BUF_RX")
	)
	(segment
		(start 351.238312 -382.38938)
		(end 281.83078 -382.38938)
		(width 0.12954)
		(layer "B.Cu")
		(net "UART_BMC_BIC_BUF_RX")
	)
	(segment
		(start 367.94948 -395.265148)
		(end 367.28908 -394.604748)
		(width 0.12954)
		(layer "B.Cu")
		(net "UART_BMC_BIC_BUF_RX")
	)
	(segment
		(start 272.01368 -372.57228)
		(end 272.01368 -346.598748)
		(width 0.12954)
		(layer "B.Cu")
		(net "UART_BMC_BIC_BUF_RX")
	)
	(segment
		(start 358.11968 -393.283948)
		(end 358.11968 -389.270748)
		(width 0.12954)
		(layer "B.Cu")
		(net "UART_BMC_BIC_BUF_RX")
	)
	(segment
		(start 252.22708 -326.812148)
		(end 252.22708 -199.365108)
		(width 0.12954)
		(layer "B.Cu")
		(net "UART_BMC_BIC_BUF_RX")
	)
	(segment
		(start 281.83078 -382.38938)
		(end 272.01368 -372.57228)
		(width 0.12954)
		(layer "B.Cu")
		(net "UART_BMC_BIC_BUF_RX")
	)
	(segment
		(start 253.186438 -198.40575)
		(end 253.186438 -196.798946)
		(width 0.12954)
		(layer "B.Cu")
		(net "UART_BMC_BIC_BUF_RX")
	)
	(segment
		(start 253.186438 -196.798946)
		(end 252.76048 -196.372988)
		(width 0.12954)
		(layer "B.Cu")
		(net "UART_BMC_BIC_BUF_RX")
	)
	(segment
		(start 272.01368 -346.598748)
		(end 252.22708 -326.812148)
		(width 0.12954)
		(layer "B.Cu")
		(net "UART_BMC_BIC_BUF_RX")
	)
	(segment
		(start 230.20528 -132.304282)
		(end 230.20528 -129.741676)
		(width 0.127)
		(layer "In2.Cu")
		(net "UART_BMC_BIC_BUF_RX")
	)
	(segment
		(start 228.0158 -118.783608)
		(end 228.346 -118.453408)
		(width 0.127)
		(layer "In2.Cu")
		(net "UART_BMC_BIC_BUF_RX")
	)
	(segment
		(start 231.342946 -133.441948)
		(end 230.20528 -132.304282)
		(width 0.127)
		(layer "In2.Cu")
		(net "UART_BMC_BIC_BUF_RX")
	)
	(segment
		(start 187.318142 -23.77567)
		(end 187.318142 -20.918678)
		(width 0.127)
		(layer "In2.Cu")
		(net "UART_BMC_BIC_BUF_RX")
	)
	(segment
		(start 228.0158 -120.654572)
		(end 228.0158 -118.783608)
		(width 0.127)
		(layer "In2.Cu")
		(net "UART_BMC_BIC_BUF_RX")
	)
	(segment
		(start 188.299344 -29.438346)
		(end 188.299344 -28.422092)
		(width 0.127)
		(layer "In2.Cu")
		(net "UART_BMC_BIC_BUF_RX")
	)
	(segment
		(start 232.8418 -134.330948)
		(end 231.9528 -133.441948)
		(width 0.127)
		(layer "In2.Cu")
		(net "UART_BMC_BIC_BUF_RX")
	)
	(segment
		(start 369.85448 -402.834348)
		(end 367.94948 -400.929348)
		(width 0.127)
		(layer "In2.Cu")
		(net "UART_BMC_BIC_BUF_RX")
	)
	(segment
		(start 209.60969 -75.040998)
		(end 209.60969 -69.921374)
		(width 0.127)
		(layer "In2.Cu")
		(net "UART_BMC_BIC_BUF_RX")
	)
	(segment
		(start 187.86856 -24.326088)
		(end 187.318142 -23.77567)
		(width 0.127)
		(layer "In2.Cu")
		(net "UART_BMC_BIC_BUF_RX")
	)
	(segment
		(start 369.85448 -402.910548)
		(end 369.85448 -402.834348)
		(width 0.127)
		(layer "In2.Cu")
		(net "UART_BMC_BIC_BUF_RX")
	)
	(segment
		(start 209.60969 -69.921374)
		(end 193.311272 -53.622956)
		(width 0.127)
		(layer "In2.Cu")
		(net "UART_BMC_BIC_BUF_RX")
	)
	(segment
		(start 252.76048 -196.372988)
		(end 252.76048 -155.826968)
		(width 0.127)
		(layer "In2.Cu")
		(net "UART_BMC_BIC_BUF_RX")
	)
	(segment
		(start 228.346 -118.453408)
		(end 228.346 -93.777308)
		(width 0.127)
		(layer "In2.Cu")
		(net "UART_BMC_BIC_BUF_RX")
	)
	(segment
		(start 232.8418 -135.908288)
		(end 232.8418 -134.330948)
		(width 0.127)
		(layer "In2.Cu")
		(net "UART_BMC_BIC_BUF_RX")
	)
	(segment
		(start 193.311272 -53.622956)
		(end 193.311272 -45.5041)
		(width 0.127)
		(layer "In2.Cu")
		(net "UART_BMC_BIC_BUF_RX")
	)
	(segment
		(start 193.311272 -45.5041)
		(end 191.82334 -44.016168)
		(width 0.127)
		(layer "In2.Cu")
		(net "UART_BMC_BIC_BUF_RX")
	)
	(segment
		(start 187.86856 -25.944322)
		(end 187.86856 -24.326088)
		(width 0.127)
		(layer "In2.Cu")
		(net "UART_BMC_BIC_BUF_RX")
	)
	(segment
		(start 187.644786 -26.168096)
		(end 187.86856 -25.944322)
		(width 0.127)
		(layer "In2.Cu")
		(net "UART_BMC_BIC_BUF_RX")
	)
	(segment
		(start 191.82334 -36.693348)
		(end 192.076832 -36.439856)
		(width 0.127)
		(layer "In2.Cu")
		(net "UART_BMC_BIC_BUF_RX")
	)
	(segment
		(start 228.88448 -121.523252)
		(end 228.0158 -120.654572)
		(width 0.127)
		(layer "In2.Cu")
		(net "UART_BMC_BIC_BUF_RX")
	)
	(segment
		(start 188.62548 -19.61134)
		(end 188.62548 -18.227548)
		(width 0.127)
		(layer "In2.Cu")
		(net "UART_BMC_BIC_BUF_RX")
	)
	(segment
		(start 187.644786 -27.767534)
		(end 187.644786 -26.168096)
		(width 0.127)
		(layer "In2.Cu")
		(net "UART_BMC_BIC_BUF_RX")
	)
	(segment
		(start 228.88448 -128.420876)
		(end 228.88448 -121.523252)
		(width 0.127)
		(layer "In2.Cu")
		(net "UART_BMC_BIC_BUF_RX")
	)
	(segment
		(start 192.076832 -36.439856)
		(end 192.076832 -33.215834)
		(width 0.127)
		(layer "In2.Cu")
		(net "UART_BMC_BIC_BUF_RX")
	)
	(segment
		(start 187.318142 -20.918678)
		(end 188.62548 -19.61134)
		(width 0.127)
		(layer "In2.Cu")
		(net "UART_BMC_BIC_BUF_RX")
	)
	(segment
		(start 252.76048 -155.826968)
		(end 232.8418 -135.908288)
		(width 0.127)
		(layer "In2.Cu")
		(net "UART_BMC_BIC_BUF_RX")
	)
	(segment
		(start 228.346 -93.777308)
		(end 209.60969 -75.040998)
		(width 0.127)
		(layer "In2.Cu")
		(net "UART_BMC_BIC_BUF_RX")
	)
	(segment
		(start 191.82334 -44.016168)
		(end 191.82334 -36.693348)
		(width 0.127)
		(layer "In2.Cu")
		(net "UART_BMC_BIC_BUF_RX")
	)
	(segment
		(start 188.299344 -28.422092)
		(end 187.644786 -27.767534)
		(width 0.127)
		(layer "In2.Cu")
		(net "UART_BMC_BIC_BUF_RX")
	)
	(segment
		(start 230.20528 -129.741676)
		(end 228.88448 -128.420876)
		(width 0.127)
		(layer "In2.Cu")
		(net "UART_BMC_BIC_BUF_RX")
	)
	(segment
		(start 192.076832 -33.215834)
		(end 188.299344 -29.438346)
		(width 0.127)
		(layer "In2.Cu")
		(net "UART_BMC_BIC_BUF_RX")
	)
	(segment
		(start 231.9528 -133.441948)
		(end 231.342946 -133.441948)
		(width 0.127)
		(layer "In2.Cu")
		(net "UART_BMC_BIC_BUF_RX")
	)
	(segment
		(start 367.94948 -400.929348)
		(end 367.94948 -395.265148)
		(width 0.127)
		(layer "In2.Cu")
		(net "UART_BMC_BIC_BUF_RX")
	)
	(segment
		(start 120.47474 -72.195182)
		(end 121.92 -70.749922)
		(width 0.12954)
		(layer "F.Cu")
		(net "TP_PLD_CONN_P5")
	)
	(segment
		(start 120.47474 -74.427588)
		(end 120.47474 -72.195182)
		(width 0.12954)
		(layer "F.Cu")
		(net "TP_PLD_CONN_P5")
	)
	(via
		(at 120.47474 -74.427588)
		(size 0.762)
		(drill 0.381)
		(layers "F.Cu" "B.Cu")
		(net "TP_PLD_CONN_P5")
	)
	(segment
		(start 455.621136 -112.041432)
		(end 455.94524 -111.717328)
		(width 0.12954)
		(layer "F.Cu")
		(net "TP_PCA9555_0_P7")
	)
	(segment
		(start 455.94524 -111.717328)
		(end 455.94524 -110.028228)
		(width 0.12954)
		(layer "F.Cu")
		(net "TP_PCA9555_0_P7")
	)
	(segment
		(start 454.798684 -112.041432)
		(end 455.621136 -112.041432)
		(width 0.12954)
		(layer "F.Cu")
		(net "TP_PCA9555_0_P7")
	)
	(via
		(at 455.94524 -110.028228)
		(size 0.762)
		(drill 0.381)
		(layers "F.Cu" "B.Cu")
		(net "TP_PCA9555_0_P7")
	)
	(segment
		(start 455.610976 -112.691418)
		(end 457.44892 -110.853474)
		(width 0.12954)
		(layer "F.Cu")
		(net "TP_PCA9555_0_P6")
	)
	(segment
		(start 457.44892 -110.853474)
		(end 457.44892 -110.015528)
		(width 0.12954)
		(layer "F.Cu")
		(net "TP_PCA9555_0_P6")
	)
	(segment
		(start 454.798684 -112.691418)
		(end 455.610976 -112.691418)
		(width 0.12954)
		(layer "F.Cu")
		(net "TP_PCA9555_0_P6")
	)
	(via
		(at 457.44892 -110.015528)
		(size 0.762)
		(drill 0.381)
		(layers "F.Cu" "B.Cu")
		(net "TP_PCA9555_0_P6")
	)
	(segment
		(start 460.648812 -115.941602)
		(end 462.49336 -115.941602)
		(width 0.12954)
		(layer "F.Cu")
		(net "TP_PCA9555_0_P17")
	)
	(via
		(at 462.49336 -115.941602)
		(size 0.762)
		(drill 0.381)
		(layers "F.Cu" "B.Cu")
		(net "TP_PCA9555_0_P17")
	)
	(segment
		(start 463.272632 -115.291616)
		(end 463.93608 -114.628168)
		(width 0.12954)
		(layer "F.Cu")
		(net "TP_PCA9555_0_P16")
	)
	(segment
		(start 460.648812 -115.291616)
		(end 463.272632 -115.291616)
		(width 0.12954)
		(layer "F.Cu")
		(net "TP_PCA9555_0_P16")
	)
	(via
		(at 463.93608 -114.628168)
		(size 0.762)
		(drill 0.381)
		(layers "F.Cu" "B.Cu")
		(net "TP_PCA9555_0_P16")
	)
	(segment
		(start 460.648812 -114.641376)
		(end 462.48066 -114.641376)
		(width 0.12954)
		(layer "F.Cu")
		(net "TP_PCA9555_0_P15")
	)
	(via
		(at 462.48066 -114.641376)
		(size 0.762)
		(drill 0.381)
		(layers "F.Cu" "B.Cu")
		(net "TP_PCA9555_0_P15")
	)
	(segment
		(start 460.648812 -113.99139)
		(end 463.175858 -113.99139)
		(width 0.12954)
		(layer "F.Cu")
		(net "TP_PCA9555_0_P14")
	)
	(segment
		(start 463.175858 -113.99139)
		(end 463.89036 -113.276888)
		(width 0.12954)
		(layer "F.Cu")
		(net "TP_PCA9555_0_P14")
	)
	(via
		(at 463.89036 -113.276888)
		(size 0.762)
		(drill 0.381)
		(layers "F.Cu" "B.Cu")
		(net "TP_PCA9555_0_P14")
	)
	(segment
		(start 460.648812 -113.341404)
		(end 462.4451 -113.341404)
		(width 0.12954)
		(layer "F.Cu")
		(net "TP_PCA9555_0_P13")
	)
	(via
		(at 462.4451 -113.341404)
		(size 0.762)
		(drill 0.381)
		(layers "F.Cu" "B.Cu")
		(net "TP_PCA9555_0_P13")
	)
	(segment
		(start 460.648812 -112.691418)
		(end 462.92897 -112.691418)
		(width 0.12954)
		(layer "F.Cu")
		(net "TP_PCA9555_0_P12")
	)
	(segment
		(start 462.92897 -112.691418)
		(end 463.93735 -111.683038)
		(width 0.12954)
		(layer "F.Cu")
		(net "TP_PCA9555_0_P12")
	)
	(via
		(at 463.93735 -111.683038)
		(size 0.762)
		(drill 0.381)
		(layers "F.Cu" "B.Cu")
		(net "TP_PCA9555_0_P12")
	)
	(segment
		(start 460.648812 -112.041432)
		(end 462.062576 -112.041432)
		(width 0.12954)
		(layer "F.Cu")
		(net "TP_PCA9555_0_P11")
	)
	(segment
		(start 462.062576 -112.041432)
		(end 462.48066 -111.623348)
		(width 0.12954)
		(layer "F.Cu")
		(net "TP_PCA9555_0_P11")
	)
	(via
		(at 462.48066 -111.623348)
		(size 0.762)
		(drill 0.381)
		(layers "F.Cu" "B.Cu")
		(net "TP_PCA9555_0_P11")
	)
	(segment
		(start 461.9498 -110.028228)
		(end 461.9498 -110.988348)
		(width 0.12954)
		(layer "F.Cu")
		(net "TP_PCA9555_0_P10")
	)
	(segment
		(start 461.646524 -111.291624)
		(end 460.648812 -111.291624)
		(width 0.12954)
		(layer "F.Cu")
		(net "TP_PCA9555_0_P10")
	)
	(segment
		(start 461.9498 -110.988348)
		(end 461.646524 -111.291624)
		(width 0.12954)
		(layer "F.Cu")
		(net "TP_PCA9555_0_P10")
	)
	(via
		(at 461.9498 -110.028228)
		(size 0.762)
		(drill 0.381)
		(layers "F.Cu" "B.Cu")
		(net "TP_PCA9555_0_P10")
	)
	(segment
		(start 454.798684 -115.941602)
		(end 455.998834 -115.941602)
		(width 0.12954)
		(layer "F.Cu")
		(net "TP_PCA9555_0_P01")
	)
	(segment
		(start 456.62088 -116.563648)
		(end 456.62088 -121.374408)
		(width 0.12954)
		(layer "F.Cu")
		(net "TP_PCA9555_0_P01")
	)
	(segment
		(start 455.998834 -115.941602)
		(end 456.62088 -116.563648)
		(width 0.12954)
		(layer "F.Cu")
		(net "TP_PCA9555_0_P01")
	)
	(via
		(at 456.62088 -121.374408)
		(size 0.762)
		(drill 0.381)
		(layers "F.Cu" "B.Cu")
		(net "TP_PCA9555_0_P01")
	)
	(segment
		(start 455.729594 -116.591588)
		(end 455.970894 -116.832888)
		(width 0.12954)
		(layer "F.Cu")
		(net "TP_PCA9555_0_P00")
	)
	(segment
		(start 455.970894 -116.832888)
		(end 455.970894 -120.045988)
		(width 0.12954)
		(layer "F.Cu")
		(net "TP_PCA9555_0_P00")
	)
	(segment
		(start 454.798684 -116.591588)
		(end 455.729594 -116.591588)
		(width 0.12954)
		(layer "F.Cu")
		(net "TP_PCA9555_0_P00")
	)
	(via
		(at 455.970894 -120.045988)
		(size 0.762)
		(drill 0.381)
		(layers "F.Cu" "B.Cu")
		(net "TP_PCA9555_0_P00")
	)
	(segment
		(start 17.34693 -10.570972)
		(end 17.063974 -10.288016)
		(width 0.12954)
		(layer "F.Cu")
		(net "TP_OCP_V3_2_B69")
	)
	(segment
		(start 17.063974 -10.288016)
		(end 16.467328 -10.288016)
		(width 0.12954)
		(layer "F.Cu")
		(net "TP_OCP_V3_2_B69")
	)
	(segment
		(start 14.79804 -14.199108)
		(end 15.09014 -14.491208)
		(width 0.12954)
		(layer "F.Cu")
		(net "TP_OCP_V3_2_B69")
	)
	(segment
		(start 16.467328 -10.288016)
		(end 16.22044 -10.534904)
		(width 0.12954)
		(layer "F.Cu")
		(net "TP_OCP_V3_2_B69")
	)
	(segment
		(start 17.34693 -11.26998)
		(end 17.34693 -10.570972)
		(width 0.12954)
		(layer "F.Cu")
		(net "TP_OCP_V3_2_B69")
	)
	(segment
		(start 14.79804 -13.904468)
		(end 14.79804 -14.199108)
		(width 0.12954)
		(layer "F.Cu")
		(net "TP_OCP_V3_2_B69")
	)
	(segment
		(start 16.22044 -12.482068)
		(end 14.79804 -13.904468)
		(width 0.12954)
		(layer "F.Cu")
		(net "TP_OCP_V3_2_B69")
	)
	(segment
		(start 16.22044 -10.534904)
		(end 16.22044 -12.482068)
		(width 0.12954)
		(layer "F.Cu")
		(net "TP_OCP_V3_2_B69")
	)
	(via
		(at 15.09014 -14.491208)
		(size 0.762)
		(drill 0.381)
		(layers "F.Cu" "B.Cu")
		(net "TP_OCP_V3_2_B69")
	)
	(segment
		(start 16.486886 -9.688068)
		(end 15.83436 -10.340594)
		(width 0.12954)
		(layer "F.Cu")
		(net "TP_OCP_V3_2_B68")
	)
	(segment
		(start 14.47038 -13.609574)
		(end 14.47038 -15.235428)
		(width 0.12954)
		(layer "F.Cu")
		(net "TP_OCP_V3_2_B68")
	)
	(segment
		(start 17.946878 -11.26998)
		(end 17.946878 -10.322306)
		(width 0.12954)
		(layer "F.Cu")
		(net "TP_OCP_V3_2_B68")
	)
	(segment
		(start 14.6431 -15.408148)
		(end 14.6431 -16.579088)
		(width 0.12954)
		(layer "F.Cu")
		(net "TP_OCP_V3_2_B68")
	)
	(segment
		(start 14.6431 -16.579088)
		(end 14.31798 -16.904208)
		(width 0.12954)
		(layer "F.Cu")
		(net "TP_OCP_V3_2_B68")
	)
	(segment
		(start 15.83436 -12.245594)
		(end 14.47038 -13.609574)
		(width 0.12954)
		(layer "F.Cu")
		(net "TP_OCP_V3_2_B68")
	)
	(segment
		(start 17.946878 -10.322306)
		(end 17.31264 -9.688068)
		(width 0.12954)
		(layer "F.Cu")
		(net "TP_OCP_V3_2_B68")
	)
	(segment
		(start 14.47038 -15.235428)
		(end 14.6431 -15.408148)
		(width 0.12954)
		(layer "F.Cu")
		(net "TP_OCP_V3_2_B68")
	)
	(segment
		(start 17.31264 -9.688068)
		(end 16.486886 -9.688068)
		(width 0.12954)
		(layer "F.Cu")
		(net "TP_OCP_V3_2_B68")
	)
	(segment
		(start 15.83436 -10.340594)
		(end 15.83436 -12.245594)
		(width 0.12954)
		(layer "F.Cu")
		(net "TP_OCP_V3_2_B68")
	)
	(via
		(at 14.31798 -16.904208)
		(size 0.762)
		(drill 0.381)
		(layers "F.Cu" "B.Cu")
		(net "TP_OCP_V3_2_B68")
	)
	(segment
		(start 153.05659 -76.570078)
		(end 152.286208 -76.570078)
		(width 0.12954)
		(layer "F.Cu")
		(net "SMB_S3M_CPU1_PIROM_3V3AUX_SDA_R")
	)
	(segment
		(start 156.35224 -79.626968)
		(end 156.35224 -78.196948)
		(width 0.12954)
		(layer "F.Cu")
		(net "SMB_S3M_CPU1_PIROM_3V3AUX_SDA_R")
	)
	(segment
		(start 153.89098 -75.735688)
		(end 153.05659 -76.570078)
		(width 0.12954)
		(layer "F.Cu")
		(net "SMB_S3M_CPU1_PIROM_3V3AUX_SDA_R")
	)
	(segment
		(start 156.35224 -78.196948)
		(end 153.89098 -75.735688)
		(width 0.12954)
		(layer "F.Cu")
		(net "SMB_S3M_CPU1_PIROM_3V3AUX_SDA_R")
	)
	(segment
		(start 157.40126 -81.458054)
		(end 157.40126 -80.675988)
		(width 0.12954)
		(layer "F.Cu")
		(net "SMB_S3M_CPU1_PIROM_3V3AUX_SDA_R")
	)
	(segment
		(start 157.351984 -81.50733)
		(end 157.40126 -81.458054)
		(width 0.12954)
		(layer "F.Cu")
		(net "SMB_S3M_CPU1_PIROM_3V3AUX_SDA_R")
	)
	(segment
		(start 157.40126 -80.675988)
		(end 156.35224 -79.626968)
		(width 0.12954)
		(layer "F.Cu")
		(net "SMB_S3M_CPU1_PIROM_3V3AUX_SDA_R")
	)
	(via
		(at 153.89098 -75.735688)
		(size 0.508)
		(drill 0.254)
		(layers "F.Cu" "B.Cu")
		(net "SMB_S3M_CPU1_PIROM_3V3AUX_SDA_R")
	)
	(segment
		(start 156.25572 -83.925918)
		(end 157.351984 -82.829654)
		(width 0.12954)
		(layer "F.Cu")
		(net "SMB_S3M_CPU1_PIROM_3V3AUX_SDA")
	)
	(segment
		(start 157.351984 -82.30743)
		(end 158.33344 -82.30743)
		(width 0.12954)
		(layer "F.Cu")
		(net "SMB_S3M_CPU1_PIROM_3V3AUX_SDA")
	)
	(segment
		(start 157.351984 -82.829654)
		(end 157.351984 -82.30743)
		(width 0.12954)
		(layer "F.Cu")
		(net "SMB_S3M_CPU1_PIROM_3V3AUX_SDA")
	)
	(segment
		(start 158.33344 -82.30743)
		(end 158.33471 -82.3087)
		(width 0.12954)
		(layer "F.Cu")
		(net "SMB_S3M_CPU1_PIROM_3V3AUX_SDA")
	)
	(segment
		(start 156.25572 -85.550248)
		(end 156.25572 -83.925918)
		(width 0.12954)
		(layer "F.Cu")
		(net "SMB_S3M_CPU1_PIROM_3V3AUX_SDA")
	)
	(via
		(at 156.25572 -85.550248)
		(size 0.508)
		(drill 0.254)
		(layers "F.Cu" "B.Cu")
		(net "SMB_S3M_CPU1_PIROM_3V3AUX_SDA")
	)
	(via
		(at 179.65928 -330.495148)
		(size 0.508)
		(drill 0.254)
		(layers "F.Cu" "B.Cu")
		(net "SMB_S3M_CPU1_PIROM_3V3AUX_SDA")
	)
	(segment
		(start 179.65928 -330.495148)
		(end 179.01793 -330.495148)
		(width 0.12954)
		(layer "B.Cu")
		(net "SMB_S3M_CPU1_PIROM_3V3AUX_SDA")
	)
	(segment
		(start 178.53914 -329.375008)
		(end 178.53914 -328.508868)
		(width 0.127)
		(layer "In11.Cu")
		(net "SMB_S3M_CPU1_PIROM_3V3AUX_SDA")
	)
	(segment
		(start 156.52242 -191.559688)
		(end 154.41168 -189.448948)
		(width 0.127)
		(layer "In11.Cu")
		(net "SMB_S3M_CPU1_PIROM_3V3AUX_SDA")
	)
	(segment
		(start 143.32966 -103.182928)
		(end 142.93088 -102.784148)
		(width 0.127)
		(layer "In11.Cu")
		(net "SMB_S3M_CPU1_PIROM_3V3AUX_SDA")
	)
	(segment
		(start 178.76266 -328.285348)
		(end 188.82868 -328.285348)
		(width 0.127)
		(layer "In11.Cu")
		(net "SMB_S3M_CPU1_PIROM_3V3AUX_SDA")
	)
	(segment
		(start 142.93088 -97.348548)
		(end 145.54708 -94.732348)
		(width 0.127)
		(layer "In11.Cu")
		(net "SMB_S3M_CPU1_PIROM_3V3AUX_SDA")
	)
	(segment
		(start 213.51748 -246.090948)
		(end 213.51748 -200.396348)
		(width 0.127)
		(layer "In11.Cu")
		(net "SMB_S3M_CPU1_PIROM_3V3AUX_SDA")
	)
	(segment
		(start 217.4748 -246.878348)
		(end 214.30488 -246.878348)
		(width 0.127)
		(layer "In11.Cu")
		(net "SMB_S3M_CPU1_PIROM_3V3AUX_SDA")
	)
	(segment
		(start 214.30488 -246.878348)
		(end 213.51748 -246.090948)
		(width 0.127)
		(layer "In11.Cu")
		(net "SMB_S3M_CPU1_PIROM_3V3AUX_SDA")
	)
	(segment
		(start 215.44788 -284.698948)
		(end 218.41968 -281.727148)
		(width 0.127)
		(layer "In11.Cu")
		(net "SMB_S3M_CPU1_PIROM_3V3AUX_SDA")
	)
	(segment
		(start 142.97914 -118.5672)
		(end 142.93088 -118.51894)
		(width 0.127)
		(layer "In11.Cu")
		(net "SMB_S3M_CPU1_PIROM_3V3AUX_SDA")
	)
	(segment
		(start 218.41968 -247.823228)
		(end 217.4748 -246.878348)
		(width 0.127)
		(layer "In11.Cu")
		(net "SMB_S3M_CPU1_PIROM_3V3AUX_SDA")
	)
	(segment
		(start 215.34628 -198.567548)
		(end 215.34628 -192.867788)
		(width 0.127)
		(layer "In11.Cu")
		(net "SMB_S3M_CPU1_PIROM_3V3AUX_SDA")
	)
	(segment
		(start 189.99708 -329.453748)
		(end 207.85328 -329.453748)
		(width 0.127)
		(layer "In11.Cu")
		(net "SMB_S3M_CPU1_PIROM_3V3AUX_SDA")
	)
	(segment
		(start 178.53914 -328.508868)
		(end 178.76266 -328.285348)
		(width 0.127)
		(layer "In11.Cu")
		(net "SMB_S3M_CPU1_PIROM_3V3AUX_SDA")
	)
	(segment
		(start 215.44788 -323.967348)
		(end 215.44788 -284.698948)
		(width 0.127)
		(layer "In11.Cu")
		(net "SMB_S3M_CPU1_PIROM_3V3AUX_SDA")
	)
	(segment
		(start 214.58428 -324.830948)
		(end 215.44788 -323.967348)
		(width 0.127)
		(layer "In11.Cu")
		(net "SMB_S3M_CPU1_PIROM_3V3AUX_SDA")
	)
	(segment
		(start 143.32966 -107.64774)
		(end 143.32966 -103.182928)
		(width 0.127)
		(layer "In11.Cu")
		(net "SMB_S3M_CPU1_PIROM_3V3AUX_SDA")
	)
	(segment
		(start 179.65928 -330.495148)
		(end 178.53914 -329.375008)
		(width 0.127)
		(layer "In11.Cu")
		(net "SMB_S3M_CPU1_PIROM_3V3AUX_SDA")
	)
	(segment
		(start 213.51748 -200.396348)
		(end 215.34628 -198.567548)
		(width 0.127)
		(layer "In11.Cu")
		(net "SMB_S3M_CPU1_PIROM_3V3AUX_SDA")
	)
	(segment
		(start 207.85328 -329.453748)
		(end 212.47608 -324.830948)
		(width 0.127)
		(layer "In11.Cu")
		(net "SMB_S3M_CPU1_PIROM_3V3AUX_SDA")
	)
	(segment
		(start 156.25572 -88.316308)
		(end 156.25572 -85.550248)
		(width 0.127)
		(layer "In11.Cu")
		(net "SMB_S3M_CPU1_PIROM_3V3AUX_SDA")
	)
	(segment
		(start 218.41968 -281.727148)
		(end 218.41968 -247.823228)
		(width 0.127)
		(layer "In11.Cu")
		(net "SMB_S3M_CPU1_PIROM_3V3AUX_SDA")
	)
	(segment
		(start 208.40192 -191.882268)
		(end 194.289934 -191.882268)
		(width 0.127)
		(layer "In11.Cu")
		(net "SMB_S3M_CPU1_PIROM_3V3AUX_SDA")
	)
	(segment
		(start 147.75688 -138.369548)
		(end 142.97914 -133.591808)
		(width 0.127)
		(layer "In11.Cu")
		(net "SMB_S3M_CPU1_PIROM_3V3AUX_SDA")
	)
	(segment
		(start 193.967354 -191.559688)
		(end 156.52242 -191.559688)
		(width 0.127)
		(layer "In11.Cu")
		(net "SMB_S3M_CPU1_PIROM_3V3AUX_SDA")
	)
	(segment
		(start 147.75688 -176.207928)
		(end 147.75688 -138.369548)
		(width 0.127)
		(layer "In11.Cu")
		(net "SMB_S3M_CPU1_PIROM_3V3AUX_SDA")
	)
	(segment
		(start 214.252048 -191.773556)
		(end 208.510632 -191.773556)
		(width 0.127)
		(layer "In11.Cu")
		(net "SMB_S3M_CPU1_PIROM_3V3AUX_SDA")
	)
	(segment
		(start 142.93088 -102.784148)
		(end 142.93088 -97.348548)
		(width 0.127)
		(layer "In11.Cu")
		(net "SMB_S3M_CPU1_PIROM_3V3AUX_SDA")
	)
	(segment
		(start 215.34628 -192.867788)
		(end 214.252048 -191.773556)
		(width 0.127)
		(layer "In11.Cu")
		(net "SMB_S3M_CPU1_PIROM_3V3AUX_SDA")
	)
	(segment
		(start 194.289934 -191.882268)
		(end 193.967354 -191.559688)
		(width 0.127)
		(layer "In11.Cu")
		(net "SMB_S3M_CPU1_PIROM_3V3AUX_SDA")
	)
	(segment
		(start 208.510632 -191.773556)
		(end 208.40192 -191.882268)
		(width 0.127)
		(layer "In11.Cu")
		(net "SMB_S3M_CPU1_PIROM_3V3AUX_SDA")
	)
	(segment
		(start 145.54708 -94.732348)
		(end 149.83968 -94.732348)
		(width 0.127)
		(layer "In11.Cu")
		(net "SMB_S3M_CPU1_PIROM_3V3AUX_SDA")
	)
	(segment
		(start 149.83968 -94.732348)
		(end 156.25572 -88.316308)
		(width 0.127)
		(layer "In11.Cu")
		(net "SMB_S3M_CPU1_PIROM_3V3AUX_SDA")
	)
	(segment
		(start 142.93088 -108.04652)
		(end 143.32966 -107.64774)
		(width 0.127)
		(layer "In11.Cu")
		(net "SMB_S3M_CPU1_PIROM_3V3AUX_SDA")
	)
	(segment
		(start 142.97914 -133.591808)
		(end 142.97914 -118.5672)
		(width 0.127)
		(layer "In11.Cu")
		(net "SMB_S3M_CPU1_PIROM_3V3AUX_SDA")
	)
	(segment
		(start 154.41168 -189.448948)
		(end 154.41168 -182.862728)
		(width 0.127)
		(layer "In11.Cu")
		(net "SMB_S3M_CPU1_PIROM_3V3AUX_SDA")
	)
	(segment
		(start 188.82868 -328.285348)
		(end 189.99708 -329.453748)
		(width 0.127)
		(layer "In11.Cu")
		(net "SMB_S3M_CPU1_PIROM_3V3AUX_SDA")
	)
	(segment
		(start 142.93088 -118.51894)
		(end 142.93088 -108.04652)
		(width 0.127)
		(layer "In11.Cu")
		(net "SMB_S3M_CPU1_PIROM_3V3AUX_SDA")
	)
	(segment
		(start 154.41168 -182.862728)
		(end 147.75688 -176.207928)
		(width 0.127)
		(layer "In11.Cu")
		(net "SMB_S3M_CPU1_PIROM_3V3AUX_SDA")
	)
	(segment
		(start 212.47608 -324.830948)
		(end 214.58428 -324.830948)
		(width 0.127)
		(layer "In11.Cu")
		(net "SMB_S3M_CPU1_PIROM_3V3AUX_SDA")
	)
	(segment
		(start 153.05913 -75.919838)
		(end 152.286208 -75.919838)
		(width 0.12954)
		(layer "F.Cu")
		(net "SMB_S3M_CPU1_PIROM_3V3AUX_SCL_R")
	)
	(segment
		(start 153.21788 -74.986388)
		(end 153.21788 -75.761088)
		(width 0.12954)
		(layer "F.Cu")
		(net "SMB_S3M_CPU1_PIROM_3V3AUX_SCL_R")
	)
	(segment
		(start 156.97454 -77.661008)
		(end 153.7589 -74.445368)
		(width 0.12954)
		(layer "F.Cu")
		(net "SMB_S3M_CPU1_PIROM_3V3AUX_SCL_R")
	)
	(segment
		(start 159.317944 -81.502504)
		(end 158.93923 -81.12379)
		(width 0.12954)
		(layer "F.Cu")
		(net "SMB_S3M_CPU1_PIROM_3V3AUX_SCL_R")
	)
	(segment
		(start 153.7589 -74.445368)
		(end 153.21788 -74.986388)
		(width 0.12954)
		(layer "F.Cu")
		(net "SMB_S3M_CPU1_PIROM_3V3AUX_SCL_R")
	)
	(segment
		(start 158.93923 -81.12379)
		(end 158.93923 -80.052418)
		(width 0.12954)
		(layer "F.Cu")
		(net "SMB_S3M_CPU1_PIROM_3V3AUX_SCL_R")
	)
	(segment
		(start 158.93923 -80.052418)
		(end 158.6484 -79.761588)
		(width 0.12954)
		(layer "F.Cu")
		(net "SMB_S3M_CPU1_PIROM_3V3AUX_SCL_R")
	)
	(segment
		(start 156.97454 -79.238348)
		(end 156.97454 -77.661008)
		(width 0.12954)
		(layer "F.Cu")
		(net "SMB_S3M_CPU1_PIROM_3V3AUX_SCL_R")
	)
	(segment
		(start 157.49778 -79.761588)
		(end 156.97454 -79.238348)
		(width 0.12954)
		(layer "F.Cu")
		(net "SMB_S3M_CPU1_PIROM_3V3AUX_SCL_R")
	)
	(segment
		(start 153.21788 -75.761088)
		(end 153.05913 -75.919838)
		(width 0.12954)
		(layer "F.Cu")
		(net "SMB_S3M_CPU1_PIROM_3V3AUX_SCL_R")
	)
	(segment
		(start 158.6484 -79.761588)
		(end 157.49778 -79.761588)
		(width 0.12954)
		(layer "F.Cu")
		(net "SMB_S3M_CPU1_PIROM_3V3AUX_SCL_R")
	)
	(via
		(at 153.7589 -74.445368)
		(size 0.508)
		(drill 0.254)
		(layers "F.Cu" "B.Cu")
		(net "SMB_S3M_CPU1_PIROM_3V3AUX_SCL_R")
	)
	(segment
		(start 157.346396 -84.115148)
		(end 159.15894 -82.302604)
		(width 0.12954)
		(layer "F.Cu")
		(net "SMB_S3M_CPU1_PIROM_3V3AUX_SCL")
	)
	(segment
		(start 160.311084 -82.31251)
		(end 160.301178 -82.302604)
		(width 0.12954)
		(layer "F.Cu")
		(net "SMB_S3M_CPU1_PIROM_3V3AUX_SCL")
	)
	(segment
		(start 160.301178 -82.302604)
		(end 159.317944 -82.302604)
		(width 0.12954)
		(layer "F.Cu")
		(net "SMB_S3M_CPU1_PIROM_3V3AUX_SCL")
	)
	(segment
		(start 159.15894 -82.302604)
		(end 159.317944 -82.302604)
		(width 0.12954)
		(layer "F.Cu")
		(net "SMB_S3M_CPU1_PIROM_3V3AUX_SCL")
	)
	(via
		(at 157.346396 -84.115148)
		(size 0.508)
		(drill 0.254)
		(layers "F.Cu" "B.Cu")
		(net "SMB_S3M_CPU1_PIROM_3V3AUX_SCL")
	)
	(via
		(at 179.01793 -328.817986)
		(size 0.508)
		(drill 0.254)
		(layers "F.Cu" "B.Cu")
		(net "SMB_S3M_CPU1_PIROM_3V3AUX_SCL")
	)
	(segment
		(start 179.01793 -328.817986)
		(end 179.01793 -329.479148)
		(width 0.12954)
		(layer "B.Cu")
		(net "SMB_S3M_CPU1_PIROM_3V3AUX_SCL")
	)
	(segment
		(start 218.85148 -281.906218)
		(end 218.85148 -247.644158)
		(width 0.127)
		(layer "In11.Cu")
		(net "SMB_S3M_CPU1_PIROM_3V3AUX_SCL")
	)
	(segment
		(start 157.04947 -84.115148)
		(end 157.346396 -84.115148)
		(width 0.127)
		(layer "In11.Cu")
		(net "SMB_S3M_CPU1_PIROM_3V3AUX_SCL")
	)
	(segment
		(start 143.36268 -97.527618)
		(end 145.72615 -95.164148)
		(width 0.127)
		(layer "In11.Cu")
		(net "SMB_S3M_CPU1_PIROM_3V3AUX_SCL")
	)
	(segment
		(start 213.94928 -200.575418)
		(end 215.77808 -198.746618)
		(width 0.127)
		(layer "In11.Cu")
		(net "SMB_S3M_CPU1_PIROM_3V3AUX_SCL")
	)
	(segment
		(start 208.03235 -329.885548)
		(end 212.65515 -325.262748)
		(width 0.127)
		(layer "In11.Cu")
		(net "SMB_S3M_CPU1_PIROM_3V3AUX_SCL")
	)
	(segment
		(start 143.41094 -108.25734)
		(end 143.764 -107.90428)
		(width 0.127)
		(layer "In11.Cu")
		(net "SMB_S3M_CPU1_PIROM_3V3AUX_SCL")
	)
	(segment
		(start 194.47256 -191.445388)
		(end 194.15506 -191.127888)
		(width 0.127)
		(layer "In11.Cu")
		(net "SMB_S3M_CPU1_PIROM_3V3AUX_SCL")
	)
	(segment
		(start 215.87968 -284.878018)
		(end 218.85148 -281.906218)
		(width 0.127)
		(layer "In11.Cu")
		(net "SMB_S3M_CPU1_PIROM_3V3AUX_SCL")
	)
	(segment
		(start 154.84348 -182.683658)
		(end 148.18868 -176.028858)
		(width 0.127)
		(layer "In11.Cu")
		(net "SMB_S3M_CPU1_PIROM_3V3AUX_SCL")
	)
	(segment
		(start 156.92247 -88.260428)
		(end 156.92247 -84.242148)
		(width 0.127)
		(layer "In11.Cu")
		(net "SMB_S3M_CPU1_PIROM_3V3AUX_SCL")
	)
	(segment
		(start 215.77808 -198.746618)
		(end 215.77808 -192.641982)
		(width 0.127)
		(layer "In11.Cu")
		(net "SMB_S3M_CPU1_PIROM_3V3AUX_SCL")
	)
	(segment
		(start 218.85148 -247.644158)
		(end 217.65387 -246.446548)
		(width 0.127)
		(layer "In11.Cu")
		(net "SMB_S3M_CPU1_PIROM_3V3AUX_SCL")
	)
	(segment
		(start 189.81801 -329.885548)
		(end 208.03235 -329.885548)
		(width 0.127)
		(layer "In11.Cu")
		(net "SMB_S3M_CPU1_PIROM_3V3AUX_SCL")
	)
	(segment
		(start 143.764 -103.006398)
		(end 143.36268 -102.605078)
		(width 0.127)
		(layer "In11.Cu")
		(net "SMB_S3M_CPU1_PIROM_3V3AUX_SCL")
	)
	(segment
		(start 156.70149 -191.127888)
		(end 154.84348 -189.269878)
		(width 0.127)
		(layer "In11.Cu")
		(net "SMB_S3M_CPU1_PIROM_3V3AUX_SCL")
	)
	(segment
		(start 208.227168 -191.445388)
		(end 194.47256 -191.445388)
		(width 0.127)
		(layer "In11.Cu")
		(net "SMB_S3M_CPU1_PIROM_3V3AUX_SCL")
	)
	(segment
		(start 143.41094 -133.412738)
		(end 143.41094 -108.25734)
		(width 0.127)
		(layer "In11.Cu")
		(net "SMB_S3M_CPU1_PIROM_3V3AUX_SCL")
	)
	(segment
		(start 154.84348 -189.269878)
		(end 154.84348 -182.683658)
		(width 0.127)
		(layer "In11.Cu")
		(net "SMB_S3M_CPU1_PIROM_3V3AUX_SCL")
	)
	(segment
		(start 194.15506 -191.127888)
		(end 156.70149 -191.127888)
		(width 0.127)
		(layer "In11.Cu")
		(net "SMB_S3M_CPU1_PIROM_3V3AUX_SCL")
	)
	(segment
		(start 217.65387 -246.446548)
		(end 214.48395 -246.446548)
		(width 0.127)
		(layer "In11.Cu")
		(net "SMB_S3M_CPU1_PIROM_3V3AUX_SCL")
	)
	(segment
		(start 208.33588 -191.336676)
		(end 208.227168 -191.445388)
		(width 0.127)
		(layer "In11.Cu")
		(net "SMB_S3M_CPU1_PIROM_3V3AUX_SCL")
	)
	(segment
		(start 214.472774 -191.336676)
		(end 208.33588 -191.336676)
		(width 0.127)
		(layer "In11.Cu")
		(net "SMB_S3M_CPU1_PIROM_3V3AUX_SCL")
	)
	(segment
		(start 179.01793 -328.817986)
		(end 181.375558 -328.817986)
		(width 0.127)
		(layer "In11.Cu")
		(net "SMB_S3M_CPU1_PIROM_3V3AUX_SCL")
	)
	(segment
		(start 213.94928 -245.911878)
		(end 213.94928 -200.575418)
		(width 0.127)
		(layer "In11.Cu")
		(net "SMB_S3M_CPU1_PIROM_3V3AUX_SCL")
	)
	(segment
		(start 148.18868 -138.190478)
		(end 143.41094 -133.412738)
		(width 0.127)
		(layer "In11.Cu")
		(net "SMB_S3M_CPU1_PIROM_3V3AUX_SCL")
	)
	(segment
		(start 214.76335 -325.262748)
		(end 215.87968 -324.146418)
		(width 0.127)
		(layer "In11.Cu")
		(net "SMB_S3M_CPU1_PIROM_3V3AUX_SCL")
	)
	(segment
		(start 150.01875 -95.164148)
		(end 156.92247 -88.260428)
		(width 0.127)
		(layer "In11.Cu")
		(net "SMB_S3M_CPU1_PIROM_3V3AUX_SCL")
	)
	(segment
		(start 143.764 -107.90428)
		(end 143.764 -103.006398)
		(width 0.127)
		(layer "In11.Cu")
		(net "SMB_S3M_CPU1_PIROM_3V3AUX_SCL")
	)
	(segment
		(start 215.87968 -324.146418)
		(end 215.87968 -284.878018)
		(width 0.127)
		(layer "In11.Cu")
		(net "SMB_S3M_CPU1_PIROM_3V3AUX_SCL")
	)
	(segment
		(start 188.64961 -328.717148)
		(end 189.81801 -329.885548)
		(width 0.127)
		(layer "In11.Cu")
		(net "SMB_S3M_CPU1_PIROM_3V3AUX_SCL")
	)
	(segment
		(start 145.72615 -95.164148)
		(end 150.01875 -95.164148)
		(width 0.127)
		(layer "In11.Cu")
		(net "SMB_S3M_CPU1_PIROM_3V3AUX_SCL")
	)
	(segment
		(start 181.476396 -328.717148)
		(end 188.64961 -328.717148)
		(width 0.127)
		(layer "In11.Cu")
		(net "SMB_S3M_CPU1_PIROM_3V3AUX_SCL")
	)
	(segment
		(start 212.65515 -325.262748)
		(end 214.76335 -325.262748)
		(width 0.127)
		(layer "In11.Cu")
		(net "SMB_S3M_CPU1_PIROM_3V3AUX_SCL")
	)
	(segment
		(start 143.36268 -102.605078)
		(end 143.36268 -97.527618)
		(width 0.127)
		(layer "In11.Cu")
		(net "SMB_S3M_CPU1_PIROM_3V3AUX_SCL")
	)
	(segment
		(start 181.375558 -328.817986)
		(end 181.476396 -328.717148)
		(width 0.127)
		(layer "In11.Cu")
		(net "SMB_S3M_CPU1_PIROM_3V3AUX_SCL")
	)
	(segment
		(start 214.48395 -246.446548)
		(end 213.94928 -245.911878)
		(width 0.127)
		(layer "In11.Cu")
		(net "SMB_S3M_CPU1_PIROM_3V3AUX_SCL")
	)
	(segment
		(start 148.18868 -176.028858)
		(end 148.18868 -138.190478)
		(width 0.127)
		(layer "In11.Cu")
		(net "SMB_S3M_CPU1_PIROM_3V3AUX_SCL")
	)
	(segment
		(start 215.77808 -192.641982)
		(end 214.472774 -191.336676)
		(width 0.127)
		(layer "In11.Cu")
		(net "SMB_S3M_CPU1_PIROM_3V3AUX_SCL")
	)
	(segment
		(start 156.92247 -84.242148)
		(end 157.04947 -84.115148)
		(width 0.127)
		(layer "In11.Cu")
		(net "SMB_S3M_CPU1_PIROM_3V3AUX_SCL")
	)
	(segment
		(start 153.36266 -80.907128)
		(end 153.36266 -81.473802)
		(width 0.12954)
		(layer "F.Cu")
		(net "SMB_S3M_CPU0_PIROM_3V3AUX_SDA_R")
	)
	(segment
		(start 154.32786 -79.941928)
		(end 153.36266 -80.907128)
		(width 0.12954)
		(layer "F.Cu")
		(net "SMB_S3M_CPU0_PIROM_3V3AUX_SDA_R")
	)
	(segment
		(start 153.36266 -81.473802)
		(end 153.370788 -81.48193)
		(width 0.12954)
		(layer "F.Cu")
		(net "SMB_S3M_CPU0_PIROM_3V3AUX_SDA_R")
	)
	(segment
		(start 152.905968 -78.520036)
		(end 154.32786 -79.941928)
		(width 0.12954)
		(layer "F.Cu")
		(net "SMB_S3M_CPU0_PIROM_3V3AUX_SDA_R")
	)
	(segment
		(start 152.286208 -78.520036)
		(end 152.905968 -78.520036)
		(width 0.12954)
		(layer "F.Cu")
		(net "SMB_S3M_CPU0_PIROM_3V3AUX_SDA_R")
	)
	(via
		(at 154.32786 -79.941928)
		(size 0.508)
		(drill 0.254)
		(layers "F.Cu" "B.Cu")
		(net "SMB_S3M_CPU0_PIROM_3V3AUX_SDA_R")
	)
	(segment
		(start 153.370788 -83.738466)
		(end 153.370788 -82.28203)
		(width 0.12954)
		(layer "F.Cu")
		(net "SMB_S3M_CPU0_PIROM_3V3AUX_SDA")
	)
	(segment
		(start 153.378154 -82.289396)
		(end 154.34945 -82.289396)
		(width 0.12954)
		(layer "F.Cu")
		(net "SMB_S3M_CPU0_PIROM_3V3AUX_SDA")
	)
	(segment
		(start 153.370788 -82.28203)
		(end 153.378154 -82.289396)
		(width 0.12954)
		(layer "F.Cu")
		(net "SMB_S3M_CPU0_PIROM_3V3AUX_SDA")
	)
	(segment
		(start 153.74747 -84.115148)
		(end 153.370788 -83.738466)
		(width 0.12954)
		(layer "F.Cu")
		(net "SMB_S3M_CPU0_PIROM_3V3AUX_SDA")
	)
	(via
		(at 153.74747 -84.115148)
		(size 0.508)
		(drill 0.254)
		(layers "F.Cu" "B.Cu")
		(net "SMB_S3M_CPU0_PIROM_3V3AUX_SDA")
	)
	(via
		(at 179.25288 -326.812148)
		(size 0.508)
		(drill 0.254)
		(layers "F.Cu" "B.Cu")
		(net "SMB_S3M_CPU0_PIROM_3V3AUX_SDA")
	)
	(segment
		(start 180.50383 -330.495148)
		(end 179.755038 -329.746356)
		(width 0.12954)
		(layer "B.Cu")
		(net "SMB_S3M_CPU0_PIROM_3V3AUX_SDA")
	)
	(segment
		(start 179.755038 -329.746356)
		(end 179.755038 -328.861674)
		(width 0.12954)
		(layer "B.Cu")
		(net "SMB_S3M_CPU0_PIROM_3V3AUX_SDA")
	)
	(segment
		(start 179.25288 -328.359516)
		(end 179.25288 -326.812148)
		(width 0.12954)
		(layer "B.Cu")
		(net "SMB_S3M_CPU0_PIROM_3V3AUX_SDA")
	)
	(segment
		(start 179.755038 -328.861674)
		(end 179.25288 -328.359516)
		(width 0.12954)
		(layer "B.Cu")
		(net "SMB_S3M_CPU0_PIROM_3V3AUX_SDA")
	)
	(segment
		(start 206.5782 -192.761108)
		(end 207.244696 -192.761108)
		(width 0.127)
		(layer "In11.Cu")
		(net "SMB_S3M_CPU0_PIROM_3V3AUX_SDA")
	)
	(segment
		(start 204.30744 -193.665348)
		(end 205.67396 -193.665348)
		(width 0.127)
		(layer "In11.Cu")
		(net "SMB_S3M_CPU0_PIROM_3V3AUX_SDA")
	)
	(segment
		(start 155.771342 -194.42811)
		(end 159.450278 -194.42811)
		(width 0.127)
		(layer "In11.Cu")
		(net "SMB_S3M_CPU0_PIROM_3V3AUX_SDA")
	)
	(segment
		(start 215.170258 -282.58135)
		(end 214.537798 -283.21381)
		(width 0.127)
		(layer "In11.Cu")
		(net "SMB_S3M_CPU0_PIROM_3V3AUX_SDA")
	)
	(segment
		(start 153.74747 -84.115148)
		(end 154.11958 -84.487258)
		(width 0.127)
		(layer "In11.Cu")
		(net "SMB_S3M_CPU0_PIROM_3V3AUX_SDA")
	)
	(segment
		(start 210.801458 -194.18173)
		(end 211.151978 -194.53225)
		(width 0.127)
		(layer "In11.Cu")
		(net "SMB_S3M_CPU0_PIROM_3V3AUX_SDA")
	)
	(segment
		(start 211.151978 -247.76303)
		(end 213.257638 -249.86869)
		(width 0.127)
		(layer "In11.Cu")
		(net "SMB_S3M_CPU0_PIROM_3V3AUX_SDA")
	)
	(segment
		(start 153.266648 -189.137036)
		(end 153.266648 -191.923416)
		(width 0.127)
		(layer "In11.Cu")
		(net "SMB_S3M_CPU0_PIROM_3V3AUX_SDA")
	)
	(segment
		(start 166.069518 -194.09283)
		(end 167.73906 -192.423288)
		(width 0.127)
		(layer "In11.Cu")
		(net "SMB_S3M_CPU0_PIROM_3V3AUX_SDA")
	)
	(segment
		(start 146.89328 -176.566322)
		(end 152.76068 -182.433722)
		(width 0.127)
		(layer "In11.Cu")
		(net "SMB_S3M_CPU0_PIROM_3V3AUX_SDA")
	)
	(segment
		(start 215.524588 -250.4948)
		(end 215.524588 -252.13564)
		(width 0.127)
		(layer "In11.Cu")
		(net "SMB_S3M_CPU0_PIROM_3V3AUX_SDA")
	)
	(segment
		(start 146.89328 -138.974068)
		(end 146.89328 -176.566322)
		(width 0.127)
		(layer "In11.Cu")
		(net "SMB_S3M_CPU0_PIROM_3V3AUX_SDA")
	)
	(segment
		(start 149.20468 -93.081348)
		(end 144.839944 -93.081348)
		(width 0.127)
		(layer "In11.Cu")
		(net "SMB_S3M_CPU0_PIROM_3V3AUX_SDA")
	)
	(segment
		(start 211.38388 -321.630548)
		(end 208.467198 -324.54723)
		(width 0.127)
		(layer "In11.Cu")
		(net "SMB_S3M_CPU0_PIROM_3V3AUX_SDA")
	)
	(segment
		(start 159.785558 -194.09283)
		(end 166.069518 -194.09283)
		(width 0.127)
		(layer "In11.Cu")
		(net "SMB_S3M_CPU0_PIROM_3V3AUX_SDA")
	)
	(segment
		(start 179.25288 -326.052688)
		(end 179.25288 -326.812148)
		(width 0.127)
		(layer "In11.Cu")
		(net "SMB_S3M_CPU0_PIROM_3V3AUX_SDA")
	)
	(segment
		(start 208.467198 -324.54723)
		(end 180.758338 -324.54723)
		(width 0.127)
		(layer "In11.Cu")
		(net "SMB_S3M_CPU0_PIROM_3V3AUX_SDA")
	)
	(segment
		(start 154.11958 -88.166448)
		(end 149.20468 -93.081348)
		(width 0.127)
		(layer "In11.Cu")
		(net "SMB_S3M_CPU0_PIROM_3V3AUX_SDA")
	)
	(segment
		(start 144.839944 -93.081348)
		(end 140.54328 -97.378012)
		(width 0.127)
		(layer "In11.Cu")
		(net "SMB_S3M_CPU0_PIROM_3V3AUX_SDA")
	)
	(segment
		(start 140.54328 -117.78234)
		(end 141.91488 -119.15394)
		(width 0.127)
		(layer "In11.Cu")
		(net "SMB_S3M_CPU0_PIROM_3V3AUX_SDA")
	)
	(segment
		(start 211.38388 -285.460948)
		(end 211.38388 -321.630548)
		(width 0.127)
		(layer "In11.Cu")
		(net "SMB_S3M_CPU0_PIROM_3V3AUX_SDA")
	)
	(segment
		(start 215.170258 -273.76755)
		(end 215.170258 -282.58135)
		(width 0.127)
		(layer "In11.Cu")
		(net "SMB_S3M_CPU0_PIROM_3V3AUX_SDA")
	)
	(segment
		(start 207.244696 -192.761108)
		(end 208.665318 -194.18173)
		(width 0.127)
		(layer "In11.Cu")
		(net "SMB_S3M_CPU0_PIROM_3V3AUX_SDA")
	)
	(segment
		(start 194.392296 -192.761108)
		(end 203.4032 -192.761108)
		(width 0.127)
		(layer "In11.Cu")
		(net "SMB_S3M_CPU0_PIROM_3V3AUX_SDA")
	)
	(segment
		(start 211.151978 -194.53225)
		(end 211.151978 -247.76303)
		(width 0.127)
		(layer "In11.Cu")
		(net "SMB_S3M_CPU0_PIROM_3V3AUX_SDA")
	)
	(segment
		(start 215.524588 -252.13564)
		(end 217.387932 -253.998984)
		(width 0.127)
		(layer "In11.Cu")
		(net "SMB_S3M_CPU0_PIROM_3V3AUX_SDA")
	)
	(segment
		(start 154.11958 -84.487258)
		(end 154.11958 -88.166448)
		(width 0.127)
		(layer "In11.Cu")
		(net "SMB_S3M_CPU0_PIROM_3V3AUX_SDA")
	)
	(segment
		(start 213.631018 -283.21381)
		(end 211.38388 -285.460948)
		(width 0.127)
		(layer "In11.Cu")
		(net "SMB_S3M_CPU0_PIROM_3V3AUX_SDA")
	)
	(segment
		(start 193.922396 -193.231008)
		(end 194.392296 -192.761108)
		(width 0.127)
		(layer "In11.Cu")
		(net "SMB_S3M_CPU0_PIROM_3V3AUX_SDA")
	)
	(segment
		(start 205.67396 -193.665348)
		(end 206.5782 -192.761108)
		(width 0.127)
		(layer "In11.Cu")
		(net "SMB_S3M_CPU0_PIROM_3V3AUX_SDA")
	)
	(segment
		(start 203.4032 -192.761108)
		(end 204.30744 -193.665348)
		(width 0.127)
		(layer "In11.Cu")
		(net "SMB_S3M_CPU0_PIROM_3V3AUX_SDA")
	)
	(segment
		(start 140.54328 -97.378012)
		(end 140.54328 -117.78234)
		(width 0.127)
		(layer "In11.Cu")
		(net "SMB_S3M_CPU0_PIROM_3V3AUX_SDA")
	)
	(segment
		(start 208.665318 -194.18173)
		(end 210.801458 -194.18173)
		(width 0.127)
		(layer "In11.Cu")
		(net "SMB_S3M_CPU0_PIROM_3V3AUX_SDA")
	)
	(segment
		(start 217.387932 -271.549876)
		(end 215.170258 -273.76755)
		(width 0.127)
		(layer "In11.Cu")
		(net "SMB_S3M_CPU0_PIROM_3V3AUX_SDA")
	)
	(segment
		(start 167.73906 -192.423288)
		(end 192.50152 -192.423288)
		(width 0.127)
		(layer "In11.Cu")
		(net "SMB_S3M_CPU0_PIROM_3V3AUX_SDA")
	)
	(segment
		(start 159.450278 -194.42811)
		(end 159.785558 -194.09283)
		(width 0.127)
		(layer "In11.Cu")
		(net "SMB_S3M_CPU0_PIROM_3V3AUX_SDA")
	)
	(segment
		(start 192.50152 -192.423288)
		(end 193.30924 -193.231008)
		(width 0.127)
		(layer "In11.Cu")
		(net "SMB_S3M_CPU0_PIROM_3V3AUX_SDA")
	)
	(segment
		(start 213.257638 -249.86869)
		(end 214.898478 -249.86869)
		(width 0.127)
		(layer "In11.Cu")
		(net "SMB_S3M_CPU0_PIROM_3V3AUX_SDA")
	)
	(segment
		(start 193.30924 -193.231008)
		(end 193.922396 -193.231008)
		(width 0.127)
		(layer "In11.Cu")
		(net "SMB_S3M_CPU0_PIROM_3V3AUX_SDA")
	)
	(segment
		(start 152.76068 -182.433722)
		(end 152.76068 -188.631068)
		(width 0.127)
		(layer "In11.Cu")
		(net "SMB_S3M_CPU0_PIROM_3V3AUX_SDA")
	)
	(segment
		(start 217.387932 -253.998984)
		(end 217.387932 -271.549876)
		(width 0.127)
		(layer "In11.Cu")
		(net "SMB_S3M_CPU0_PIROM_3V3AUX_SDA")
	)
	(segment
		(start 214.537798 -283.21381)
		(end 213.631018 -283.21381)
		(width 0.127)
		(layer "In11.Cu")
		(net "SMB_S3M_CPU0_PIROM_3V3AUX_SDA")
	)
	(segment
		(start 141.91488 -133.995668)
		(end 146.89328 -138.974068)
		(width 0.127)
		(layer "In11.Cu")
		(net "SMB_S3M_CPU0_PIROM_3V3AUX_SDA")
	)
	(segment
		(start 153.266648 -191.923416)
		(end 155.771342 -194.42811)
		(width 0.127)
		(layer "In11.Cu")
		(net "SMB_S3M_CPU0_PIROM_3V3AUX_SDA")
	)
	(segment
		(start 141.91488 -119.15394)
		(end 141.91488 -133.995668)
		(width 0.127)
		(layer "In11.Cu")
		(net "SMB_S3M_CPU0_PIROM_3V3AUX_SDA")
	)
	(segment
		(start 152.76068 -188.631068)
		(end 153.266648 -189.137036)
		(width 0.127)
		(layer "In11.Cu")
		(net "SMB_S3M_CPU0_PIROM_3V3AUX_SDA")
	)
	(segment
		(start 214.898478 -249.86869)
		(end 215.524588 -250.4948)
		(width 0.127)
		(layer "In11.Cu")
		(net "SMB_S3M_CPU0_PIROM_3V3AUX_SDA")
	)
	(segment
		(start 180.758338 -324.54723)
		(end 179.25288 -326.052688)
		(width 0.127)
		(layer "In11.Cu")
		(net "SMB_S3M_CPU0_PIROM_3V3AUX_SDA")
	)
	(segment
		(start 152.286208 -77.87005)
		(end 152.998678 -77.87005)
		(width 0.12954)
		(layer "F.Cu")
		(net "SMB_S3M_CPU0_PIROM_3V3AUX_SCL_R")
	)
	(segment
		(start 152.998678 -77.87005)
		(end 153.81224 -77.056488)
		(width 0.12954)
		(layer "F.Cu")
		(net "SMB_S3M_CPU0_PIROM_3V3AUX_SCL_R")
	)
	(segment
		(start 153.81224 -77.056488)
		(end 155.29052 -78.534768)
		(width 0.12954)
		(layer "F.Cu")
		(net "SMB_S3M_CPU0_PIROM_3V3AUX_SCL_R")
	)
	(segment
		(start 155.29052 -78.534768)
		(end 155.29052 -81.436464)
		(width 0.12954)
		(layer "F.Cu")
		(net "SMB_S3M_CPU0_PIROM_3V3AUX_SCL_R")
	)
	(segment
		(start 155.29052 -81.436464)
		(end 155.348686 -81.49463)
		(width 0.12954)
		(layer "F.Cu")
		(net "SMB_S3M_CPU0_PIROM_3V3AUX_SCL_R")
	)
	(via
		(at 153.81224 -77.056488)
		(size 0.508)
		(drill 0.254)
		(layers "F.Cu" "B.Cu")
		(net "SMB_S3M_CPU0_PIROM_3V3AUX_SCL_R")
	)
	(segment
		(start 156.3624 -82.29473)
		(end 155.348686 -82.29473)
		(width 0.12954)
		(layer "F.Cu")
		(net "SMB_S3M_CPU0_PIROM_3V3AUX_SCL")
	)
	(segment
		(start 156.37129 -82.30362)
		(end 156.3624 -82.29473)
		(width 0.12954)
		(layer "F.Cu")
		(net "SMB_S3M_CPU0_PIROM_3V3AUX_SCL")
	)
	(segment
		(start 155.98902 -83.505548)
		(end 155.98902 -82.935064)
		(width 0.12954)
		(layer "F.Cu")
		(net "SMB_S3M_CPU0_PIROM_3V3AUX_SCL")
	)
	(segment
		(start 155.98902 -82.935064)
		(end 155.348686 -82.29473)
		(width 0.12954)
		(layer "F.Cu")
		(net "SMB_S3M_CPU0_PIROM_3V3AUX_SCL")
	)
	(via
		(at 155.98902 -83.505548)
		(size 0.508)
		(drill 0.254)
		(layers "F.Cu" "B.Cu")
		(net "SMB_S3M_CPU0_PIROM_3V3AUX_SCL")
	)
	(via
		(at 179.76088 -327.701148)
		(size 0.508)
		(drill 0.254)
		(layers "F.Cu" "B.Cu")
		(net "SMB_S3M_CPU0_PIROM_3V3AUX_SCL")
	)
	(segment
		(start 180.50383 -329.479148)
		(end 180.50383 -328.8411)
		(width 0.12954)
		(layer "B.Cu")
		(net "SMB_S3M_CPU0_PIROM_3V3AUX_SCL")
	)
	(segment
		(start 180.549804 -328.107548)
		(end 180.549804 -327.856088)
		(width 0.12954)
		(layer "B.Cu")
		(net "SMB_S3M_CPU0_PIROM_3V3AUX_SCL")
	)
	(segment
		(start 180.120544 -328.592688)
		(end 180.120544 -328.341228)
		(width 0.12954)
		(layer "B.Cu")
		(net "SMB_S3M_CPU0_PIROM_3V3AUX_SCL")
	)
	(segment
		(start 180.50383 -328.8411)
		(end 180.384958 -328.722228)
		(width 0.12954)
		(layer "B.Cu")
		(net "SMB_S3M_CPU0_PIROM_3V3AUX_SCL")
	)
	(segment
		(start 180.445664 -328.211688)
		(end 180.549804 -328.107548)
		(width 0.12954)
		(layer "B.Cu")
		(net "SMB_S3M_CPU0_PIROM_3V3AUX_SCL")
	)
	(segment
		(start 180.250084 -328.211688)
		(end 180.445664 -328.211688)
		(width 0.12954)
		(layer "B.Cu")
		(net "SMB_S3M_CPU0_PIROM_3V3AUX_SCL")
	)
	(segment
		(start 180.250084 -328.722228)
		(end 180.120544 -328.592688)
		(width 0.12954)
		(layer "B.Cu")
		(net "SMB_S3M_CPU0_PIROM_3V3AUX_SCL")
	)
	(segment
		(start 180.384958 -328.722228)
		(end 180.250084 -328.722228)
		(width 0.12954)
		(layer "B.Cu")
		(net "SMB_S3M_CPU0_PIROM_3V3AUX_SCL")
	)
	(segment
		(start 180.549804 -327.856088)
		(end 180.394864 -327.701148)
		(width 0.12954)
		(layer "B.Cu")
		(net "SMB_S3M_CPU0_PIROM_3V3AUX_SCL")
	)
	(segment
		(start 180.394864 -327.701148)
		(end 179.76088 -327.701148)
		(width 0.12954)
		(layer "B.Cu")
		(net "SMB_S3M_CPU0_PIROM_3V3AUX_SCL")
	)
	(segment
		(start 180.120544 -328.341228)
		(end 180.250084 -328.211688)
		(width 0.12954)
		(layer "B.Cu")
		(net "SMB_S3M_CPU0_PIROM_3V3AUX_SCL")
	)
	(segment
		(start 216.010998 -249.85345)
		(end 214.520018 -248.36247)
		(width 0.127)
		(layer "In11.Cu")
		(net "SMB_S3M_CPU0_PIROM_3V3AUX_SCL")
	)
	(segment
		(start 211.61248 -246.370348)
		(end 211.61248 -194.235832)
		(width 0.127)
		(layer "In11.Cu")
		(net "SMB_S3M_CPU0_PIROM_3V3AUX_SCL")
	)
	(segment
		(start 141.02588 -117.5004)
		(end 141.02588 -97.548446)
		(width 0.127)
		(layer "In11.Cu")
		(net "SMB_S3M_CPU0_PIROM_3V3AUX_SCL")
	)
	(segment
		(start 211.883498 -285.80334)
		(end 213.914228 -283.77261)
		(width 0.127)
		(layer "In11.Cu")
		(net "SMB_S3M_CPU0_PIROM_3V3AUX_SCL")
	)
	(segment
		(start 142.37716 -133.847078)
		(end 142.37716 -118.85168)
		(width 0.127)
		(layer "In11.Cu")
		(net "SMB_S3M_CPU0_PIROM_3V3AUX_SCL")
	)
	(segment
		(start 181.056026 -325.110348)
		(end 208.69783 -325.110348)
		(width 0.127)
		(layer "In11.Cu")
		(net "SMB_S3M_CPU0_PIROM_3V3AUX_SCL")
	)
	(segment
		(start 154.669744 -192.55359)
		(end 153.76144 -191.645286)
		(width 0.127)
		(layer "In11.Cu")
		(net "SMB_S3M_CPU0_PIROM_3V3AUX_SCL")
	)
	(segment
		(start 206.39532 -192.324228)
		(end 205.613 -193.106548)
		(width 0.127)
		(layer "In11.Cu")
		(net "SMB_S3M_CPU0_PIROM_3V3AUX_SCL")
	)
	(segment
		(start 211.883498 -321.92468)
		(end 211.883498 -285.80334)
		(width 0.127)
		(layer "In11.Cu")
		(net "SMB_S3M_CPU0_PIROM_3V3AUX_SCL")
	)
	(segment
		(start 149.585934 -93.589348)
		(end 154.58948 -88.585802)
		(width 0.127)
		(layer "In11.Cu")
		(net "SMB_S3M_CPU0_PIROM_3V3AUX_SCL")
	)
	(segment
		(start 142.37716 -118.85168)
		(end 141.02588 -117.5004)
		(width 0.127)
		(layer "In11.Cu")
		(net "SMB_S3M_CPU0_PIROM_3V3AUX_SCL")
	)
	(segment
		(start 204.3938 -193.106548)
		(end 203.61148 -192.324228)
		(width 0.127)
		(layer "In11.Cu")
		(net "SMB_S3M_CPU0_PIROM_3V3AUX_SCL")
	)
	(segment
		(start 165.749478 -193.62801)
		(end 158.947358 -193.62801)
		(width 0.127)
		(layer "In11.Cu")
		(net "SMB_S3M_CPU0_PIROM_3V3AUX_SCL")
	)
	(segment
		(start 154.58948 -84.905088)
		(end 155.98902 -83.505548)
		(width 0.127)
		(layer "In11.Cu")
		(net "SMB_S3M_CPU0_PIROM_3V3AUX_SCL")
	)
	(segment
		(start 158.947358 -193.62801)
		(end 157.872938 -192.55359)
		(width 0.127)
		(layer "In11.Cu")
		(net "SMB_S3M_CPU0_PIROM_3V3AUX_SCL")
	)
	(segment
		(start 213.914228 -283.77261)
		(end 214.645748 -283.77261)
		(width 0.127)
		(layer "In11.Cu")
		(net "SMB_S3M_CPU0_PIROM_3V3AUX_SCL")
	)
	(segment
		(start 208.073498 -192.81521)
		(end 207.582516 -192.324228)
		(width 0.127)
		(layer "In11.Cu")
		(net "SMB_S3M_CPU0_PIROM_3V3AUX_SCL")
	)
	(segment
		(start 153.76144 -182.823612)
		(end 147.32508 -176.387252)
		(width 0.127)
		(layer "In11.Cu")
		(net "SMB_S3M_CPU0_PIROM_3V3AUX_SCL")
	)
	(segment
		(start 205.613 -193.106548)
		(end 204.3938 -193.106548)
		(width 0.127)
		(layer "In11.Cu")
		(net "SMB_S3M_CPU0_PIROM_3V3AUX_SCL")
	)
	(segment
		(start 215.62568 -274.932902)
		(end 217.863928 -272.694654)
		(width 0.127)
		(layer "In11.Cu")
		(net "SMB_S3M_CPU0_PIROM_3V3AUX_SCL")
	)
	(segment
		(start 207.582516 -192.324228)
		(end 206.39532 -192.324228)
		(width 0.127)
		(layer "In11.Cu")
		(net "SMB_S3M_CPU0_PIROM_3V3AUX_SCL")
	)
	(segment
		(start 179.76088 -326.405494)
		(end 181.056026 -325.110348)
		(width 0.127)
		(layer "In11.Cu")
		(net "SMB_S3M_CPU0_PIROM_3V3AUX_SCL")
	)
	(segment
		(start 194.09664 -192.324228)
		(end 193.7639 -191.991488)
		(width 0.127)
		(layer "In11.Cu")
		(net "SMB_S3M_CPU0_PIROM_3V3AUX_SCL")
	)
	(segment
		(start 154.58948 -88.585802)
		(end 154.58948 -84.905088)
		(width 0.127)
		(layer "In11.Cu")
		(net "SMB_S3M_CPU0_PIROM_3V3AUX_SCL")
	)
	(segment
		(start 210.976718 -193.60007)
		(end 210.242658 -193.60007)
		(width 0.127)
		(layer "In11.Cu")
		(net "SMB_S3M_CPU0_PIROM_3V3AUX_SCL")
	)
	(segment
		(start 141.02588 -97.548446)
		(end 144.984978 -93.589348)
		(width 0.127)
		(layer "In11.Cu")
		(net "SMB_S3M_CPU0_PIROM_3V3AUX_SCL")
	)
	(segment
		(start 147.32508 -138.794998)
		(end 142.37716 -133.847078)
		(width 0.127)
		(layer "In11.Cu")
		(net "SMB_S3M_CPU0_PIROM_3V3AUX_SCL")
	)
	(segment
		(start 193.7639 -191.991488)
		(end 167.386 -191.991488)
		(width 0.127)
		(layer "In11.Cu")
		(net "SMB_S3M_CPU0_PIROM_3V3AUX_SCL")
	)
	(segment
		(start 217.863928 -253.485142)
		(end 216.010998 -251.632212)
		(width 0.127)
		(layer "In11.Cu")
		(net "SMB_S3M_CPU0_PIROM_3V3AUX_SCL")
	)
	(segment
		(start 213.604602 -248.36247)
		(end 211.61248 -246.370348)
		(width 0.127)
		(layer "In11.Cu")
		(net "SMB_S3M_CPU0_PIROM_3V3AUX_SCL")
	)
	(segment
		(start 217.863928 -272.694654)
		(end 217.863928 -253.485142)
		(width 0.127)
		(layer "In11.Cu")
		(net "SMB_S3M_CPU0_PIROM_3V3AUX_SCL")
	)
	(segment
		(start 210.242658 -193.60007)
		(end 209.457798 -192.81521)
		(width 0.127)
		(layer "In11.Cu")
		(net "SMB_S3M_CPU0_PIROM_3V3AUX_SCL")
	)
	(segment
		(start 208.69783 -325.110348)
		(end 211.883498 -321.92468)
		(width 0.127)
		(layer "In11.Cu")
		(net "SMB_S3M_CPU0_PIROM_3V3AUX_SCL")
	)
	(segment
		(start 211.61248 -194.235832)
		(end 210.976718 -193.60007)
		(width 0.127)
		(layer "In11.Cu")
		(net "SMB_S3M_CPU0_PIROM_3V3AUX_SCL")
	)
	(segment
		(start 216.010998 -251.632212)
		(end 216.010998 -249.85345)
		(width 0.127)
		(layer "In11.Cu")
		(net "SMB_S3M_CPU0_PIROM_3V3AUX_SCL")
	)
	(segment
		(start 214.645748 -283.77261)
		(end 215.62568 -282.792678)
		(width 0.127)
		(layer "In11.Cu")
		(net "SMB_S3M_CPU0_PIROM_3V3AUX_SCL")
	)
	(segment
		(start 215.62568 -282.792678)
		(end 215.62568 -274.932902)
		(width 0.127)
		(layer "In11.Cu")
		(net "SMB_S3M_CPU0_PIROM_3V3AUX_SCL")
	)
	(segment
		(start 214.520018 -248.36247)
		(end 213.604602 -248.36247)
		(width 0.127)
		(layer "In11.Cu")
		(net "SMB_S3M_CPU0_PIROM_3V3AUX_SCL")
	)
	(segment
		(start 153.76144 -191.645286)
		(end 153.76144 -182.823612)
		(width 0.127)
		(layer "In11.Cu")
		(net "SMB_S3M_CPU0_PIROM_3V3AUX_SCL")
	)
	(segment
		(start 209.457798 -192.81521)
		(end 208.073498 -192.81521)
		(width 0.127)
		(layer "In11.Cu")
		(net "SMB_S3M_CPU0_PIROM_3V3AUX_SCL")
	)
	(segment
		(start 167.386 -191.991488)
		(end 165.749478 -193.62801)
		(width 0.127)
		(layer "In11.Cu")
		(net "SMB_S3M_CPU0_PIROM_3V3AUX_SCL")
	)
	(segment
		(start 157.872938 -192.55359)
		(end 154.669744 -192.55359)
		(width 0.127)
		(layer "In11.Cu")
		(net "SMB_S3M_CPU0_PIROM_3V3AUX_SCL")
	)
	(segment
		(start 144.984978 -93.589348)
		(end 149.585934 -93.589348)
		(width 0.127)
		(layer "In11.Cu")
		(net "SMB_S3M_CPU0_PIROM_3V3AUX_SCL")
	)
	(segment
		(start 147.32508 -176.387252)
		(end 147.32508 -138.794998)
		(width 0.127)
		(layer "In11.Cu")
		(net "SMB_S3M_CPU0_PIROM_3V3AUX_SCL")
	)
	(segment
		(start 203.61148 -192.324228)
		(end 194.09664 -192.324228)
		(width 0.127)
		(layer "In11.Cu")
		(net "SMB_S3M_CPU0_PIROM_3V3AUX_SCL")
	)
	(segment
		(start 179.76088 -327.701148)
		(end 179.76088 -326.405494)
		(width 0.127)
		(layer "In11.Cu")
		(net "SMB_S3M_CPU0_PIROM_3V3AUX_SCL")
	)
	(segment
		(start 145.38452 -125.425708)
		(end 146.25066 -126.291848)
		(width 0.12954)
		(layer "F.Cu")
		(net "SMB_PEHPCPU1_LVC3_R3_SDA")
	)
	(segment
		(start 143.658844 -124.136912)
		(end 144.423384 -124.136912)
		(width 0.12954)
		(layer "F.Cu")
		(net "SMB_PEHPCPU1_LVC3_R3_SDA")
	)
	(segment
		(start 144.423384 -124.136912)
		(end 145.38452 -125.098048)
		(width 0.12954)
		(layer "F.Cu")
		(net "SMB_PEHPCPU1_LVC3_R3_SDA")
	)
	(segment
		(start 146.25066 -126.291848)
		(end 146.68373 -126.291848)
		(width 0.12954)
		(layer "F.Cu")
		(net "SMB_PEHPCPU1_LVC3_R3_SDA")
	)
	(segment
		(start 145.38452 -125.098048)
		(end 145.38452 -125.425708)
		(width 0.12954)
		(layer "F.Cu")
		(net "SMB_PEHPCPU1_LVC3_R3_SDA")
	)
	(via
		(at 145.38452 -125.425708)
		(size 0.762)
		(drill 0.381)
		(layers "F.Cu" "B.Cu")
		(net "SMB_PEHPCPU1_LVC3_R3_SDA")
	)
	(segment
		(start 144.751298 -123.486926)
		(end 145.3896 -124.125228)
		(width 0.12954)
		(layer "F.Cu")
		(net "SMB_PEHPCPU1_LVC3_R3_SCL")
	)
	(segment
		(start 146.54022 -125.275848)
		(end 146.68373 -125.275848)
		(width 0.12954)
		(layer "F.Cu")
		(net "SMB_PEHPCPU1_LVC3_R3_SCL")
	)
	(segment
		(start 145.3896 -124.125228)
		(end 146.54022 -125.275848)
		(width 0.12954)
		(layer "F.Cu")
		(net "SMB_PEHPCPU1_LVC3_R3_SCL")
	)
	(segment
		(start 143.658844 -123.486926)
		(end 144.751298 -123.486926)
		(width 0.12954)
		(layer "F.Cu")
		(net "SMB_PEHPCPU1_LVC3_R3_SCL")
	)
	(via
		(at 145.3896 -124.125228)
		(size 0.762)
		(drill 0.381)
		(layers "F.Cu" "B.Cu")
		(net "SMB_PEHPCPU1_LVC3_R3_SCL")
	)
	(segment
		(start 170.99026 -10.366248)
		(end 170.7515 -10.366248)
		(width 0.12954)
		(layer "F.Cu")
		(net "SMB_OCP_V3_2_3V3AUX_SDA_R0")
	)
	(segment
		(start 172.1231 -12.886182)
		(end 172.1231 -11.499088)
		(width 0.12954)
		(layer "F.Cu")
		(net "SMB_OCP_V3_2_3V3AUX_SDA_R0")
	)
	(segment
		(start 172.267118 -13.0302)
		(end 172.1231 -12.886182)
		(width 0.12954)
		(layer "F.Cu")
		(net "SMB_OCP_V3_2_3V3AUX_SDA_R0")
	)
	(segment
		(start 172.1231 -11.499088)
		(end 170.99026 -10.366248)
		(width 0.12954)
		(layer "F.Cu")
		(net "SMB_OCP_V3_2_3V3AUX_SDA_R0")
	)
	(segment
		(start 172.267118 -13.600176)
		(end 172.267118 -13.0302)
		(width 0.12954)
		(layer "F.Cu")
		(net "SMB_OCP_V3_2_3V3AUX_SDA_R0")
	)
	(via
		(at 170.7515 -10.366248)
		(size 0.508)
		(drill 0.254)
		(layers "F.Cu" "B.Cu")
		(net "SMB_OCP_V3_2_3V3AUX_SDA_R0")
	)
	(segment
		(start 170.93692 -10.366248)
		(end 171.61891 -11.048238)
		(width 0.12954)
		(layer "B.Cu")
		(net "SMB_OCP_V3_2_3V3AUX_SDA_R0")
	)
	(segment
		(start 172.15612 -13.293598)
		(end 172.2247 -13.362178)
		(width 0.12954)
		(layer "B.Cu")
		(net "SMB_OCP_V3_2_3V3AUX_SDA_R0")
	)
	(segment
		(start 172.15612 -12.345162)
		(end 172.15612 -13.293598)
		(width 0.12954)
		(layer "B.Cu")
		(net "SMB_OCP_V3_2_3V3AUX_SDA_R0")
	)
	(segment
		(start 171.61891 -11.048238)
		(end 172.15612 -12.345162)
		(width 0.12954)
		(layer "B.Cu")
		(net "SMB_OCP_V3_2_3V3AUX_SDA_R0")
	)
	(segment
		(start 170.7515 -10.366248)
		(end 170.93692 -10.366248)
		(width 0.12954)
		(layer "B.Cu")
		(net "SMB_OCP_V3_2_3V3AUX_SDA_R0")
	)
	(segment
		(start 106.82351 -32.056578)
		(end 107.58932 -32.822388)
		(width 0.12954)
		(layer "F.Cu")
		(net "SMB_OCP_V3_2_3V3AUX_SDA")
	)
	(segment
		(start 108.936282 -33.27781)
		(end 108.936028 -33.277556)
		(width 0.12954)
		(layer "F.Cu")
		(net "SMB_OCP_V3_2_3V3AUX_SDA")
	)
	(segment
		(start 106.030522 -32.056578)
		(end 106.82351 -32.056578)
		(width 0.12954)
		(layer "F.Cu")
		(net "SMB_OCP_V3_2_3V3AUX_SDA")
	)
	(segment
		(start 108.936028 -33.277556)
		(end 108.936028 -32.644588)
		(width 0.12954)
		(layer "F.Cu")
		(net "SMB_OCP_V3_2_3V3AUX_SDA")
	)
	(segment
		(start 108.936028 -32.644588)
		(end 108.937806 -32.64281)
		(width 0.12954)
		(layer "F.Cu")
		(net "SMB_OCP_V3_2_3V3AUX_SDA")
	)
	(segment
		(start 107.58932 -32.822388)
		(end 107.76712 -32.644588)
		(width 0.12954)
		(layer "F.Cu")
		(net "SMB_OCP_V3_2_3V3AUX_SDA")
	)
	(segment
		(start 107.76712 -32.644588)
		(end 108.936028 -32.644588)
		(width 0.12954)
		(layer "F.Cu")
		(net "SMB_OCP_V3_2_3V3AUX_SDA")
	)
	(via
		(at 107.58932 -32.822388)
		(size 0.762)
		(drill 0.381)
		(layers "F.Cu" "B.Cu")
		(net "SMB_OCP_V3_2_3V3AUX_SDA")
	)
	(via
		(at 108.936282 -33.27781)
		(size 0.508)
		(drill 0.254)
		(layers "F.Cu" "B.Cu")
		(net "SMB_OCP_V3_2_3V3AUX_SDA")
	)
	(via
		(at 172.2247 -14.771878)
		(size 0.508)
		(drill 0.254)
		(layers "F.Cu" "B.Cu")
		(net "SMB_OCP_V3_2_3V3AUX_SDA")
	)
	(segment
		(start 172.2247 -14.162278)
		(end 172.2247 -14.771878)
		(width 0.12954)
		(layer "B.Cu")
		(net "SMB_OCP_V3_2_3V3AUX_SDA")
	)
	(segment
		(start 115.15725 -36.072318)
		(end 110.33125 -36.072318)
		(width 0.127)
		(layer "In6.Cu")
		(net "SMB_OCP_V3_2_3V3AUX_SDA")
	)
	(segment
		(start 153.746962 -33.246568)
		(end 153.619962 -33.373568)
		(width 0.127)
		(layer "In6.Cu")
		(net "SMB_OCP_V3_2_3V3AUX_SDA")
	)
	(segment
		(start 151.841962 -32.850328)
		(end 151.714962 -32.723328)
		(width 0.127)
		(layer "In6.Cu")
		(net "SMB_OCP_V3_2_3V3AUX_SDA")
	)
	(segment
		(start 151.714962 -32.723328)
		(end 145.60042 -32.723328)
		(width 0.127)
		(layer "In6.Cu")
		(net "SMB_OCP_V3_2_3V3AUX_SDA")
	)
	(segment
		(start 170.6499 -17.577816)
		(end 170.335956 -17.263872)
		(width 0.127)
		(layer "In6.Cu")
		(net "SMB_OCP_V3_2_3V3AUX_SDA")
	)
	(segment
		(start 152.349962 -33.373568)
		(end 151.968962 -33.373568)
		(width 0.127)
		(layer "In6.Cu")
		(net "SMB_OCP_V3_2_3V3AUX_SDA")
	)
	(segment
		(start 153.746962 -32.850328)
		(end 153.746962 -33.246568)
		(width 0.127)
		(layer "In6.Cu")
		(net "SMB_OCP_V3_2_3V3AUX_SDA")
	)
	(segment
		(start 160.436814 -32.723328)
		(end 155.143962 -32.723328)
		(width 0.127)
		(layer "In6.Cu")
		(net "SMB_OCP_V3_2_3V3AUX_SDA")
	)
	(segment
		(start 153.873962 -32.723328)
		(end 153.746962 -32.850328)
		(width 0.127)
		(layer "In6.Cu")
		(net "SMB_OCP_V3_2_3V3AUX_SDA")
	)
	(segment
		(start 108.936282 -34.67735)
		(end 108.936282 -33.27781)
		(width 0.127)
		(layer "In6.Cu")
		(net "SMB_OCP_V3_2_3V3AUX_SDA")
	)
	(segment
		(start 152.476962 -32.850328)
		(end 152.476962 -33.246568)
		(width 0.127)
		(layer "In6.Cu")
		(net "SMB_OCP_V3_2_3V3AUX_SDA")
	)
	(segment
		(start 152.476962 -33.246568)
		(end 152.349962 -33.373568)
		(width 0.127)
		(layer "In6.Cu")
		(net "SMB_OCP_V3_2_3V3AUX_SDA")
	)
	(segment
		(start 138.1125 -32.723328)
		(end 132.64388 -38.191948)
		(width 0.127)
		(layer "In6.Cu")
		(net "SMB_OCP_V3_2_3V3AUX_SDA")
	)
	(segment
		(start 170.785028 -16.8148)
		(end 171.098972 -17.128744)
		(width 0.127)
		(layer "In6.Cu")
		(net "SMB_OCP_V3_2_3V3AUX_SDA")
	)
	(segment
		(start 154.381962 -33.246568)
		(end 154.381962 -32.850328)
		(width 0.127)
		(layer "In6.Cu")
		(net "SMB_OCP_V3_2_3V3AUX_SDA")
	)
	(segment
		(start 170.335956 -17.263872)
		(end 170.156124 -17.263872)
		(width 0.127)
		(layer "In6.Cu")
		(net "SMB_OCP_V3_2_3V3AUX_SDA")
	)
	(segment
		(start 170.829732 -17.577816)
		(end 170.6499 -17.577816)
		(width 0.127)
		(layer "In6.Cu")
		(net "SMB_OCP_V3_2_3V3AUX_SDA")
	)
	(segment
		(start 153.238962 -33.373568)
		(end 153.111962 -33.246568)
		(width 0.127)
		(layer "In6.Cu")
		(net "SMB_OCP_V3_2_3V3AUX_SDA")
	)
	(segment
		(start 117.27688 -38.191948)
		(end 115.15725 -36.072318)
		(width 0.127)
		(layer "In6.Cu")
		(net "SMB_OCP_V3_2_3V3AUX_SDA")
	)
	(segment
		(start 171.054268 -16.365728)
		(end 170.785028 -16.634968)
		(width 0.127)
		(layer "In6.Cu")
		(net "SMB_OCP_V3_2_3V3AUX_SDA")
	)
	(segment
		(start 154.254962 -32.723328)
		(end 153.873962 -32.723328)
		(width 0.127)
		(layer "In6.Cu")
		(net "SMB_OCP_V3_2_3V3AUX_SDA")
	)
	(segment
		(start 172.2247 -14.771878)
		(end 172.2247 -16.182848)
		(width 0.127)
		(layer "In6.Cu")
		(net "SMB_OCP_V3_2_3V3AUX_SDA")
	)
	(segment
		(start 168.21404 -20.193508)
		(end 168.21404 -24.946102)
		(width 0.127)
		(layer "In6.Cu")
		(net "SMB_OCP_V3_2_3V3AUX_SDA")
	)
	(segment
		(start 170.156124 -17.263872)
		(end 169.886884 -17.533112)
		(width 0.127)
		(layer "In6.Cu")
		(net "SMB_OCP_V3_2_3V3AUX_SDA")
	)
	(segment
		(start 171.098972 -17.128744)
		(end 171.098972 -17.308576)
		(width 0.127)
		(layer "In6.Cu")
		(net "SMB_OCP_V3_2_3V3AUX_SDA")
	)
	(segment
		(start 171.098972 -17.308576)
		(end 170.829732 -17.577816)
		(width 0.127)
		(layer "In6.Cu")
		(net "SMB_OCP_V3_2_3V3AUX_SDA")
	)
	(segment
		(start 132.64388 -38.191948)
		(end 117.27688 -38.191948)
		(width 0.127)
		(layer "In6.Cu")
		(net "SMB_OCP_V3_2_3V3AUX_SDA")
	)
	(segment
		(start 155.016962 -33.246568)
		(end 154.889962 -33.373568)
		(width 0.127)
		(layer "In6.Cu")
		(net "SMB_OCP_V3_2_3V3AUX_SDA")
	)
	(segment
		(start 171.727876 -16.679672)
		(end 171.548044 -16.679672)
		(width 0.127)
		(layer "In6.Cu")
		(net "SMB_OCP_V3_2_3V3AUX_SDA")
	)
	(segment
		(start 110.33125 -36.072318)
		(end 108.936282 -34.67735)
		(width 0.127)
		(layer "In6.Cu")
		(net "SMB_OCP_V3_2_3V3AUX_SDA")
	)
	(segment
		(start 155.016962 -32.850328)
		(end 155.016962 -33.246568)
		(width 0.127)
		(layer "In6.Cu")
		(net "SMB_OCP_V3_2_3V3AUX_SDA")
	)
	(segment
		(start 145.60042 -32.723328)
		(end 145.1483 -32.271208)
		(width 0.127)
		(layer "In6.Cu")
		(net "SMB_OCP_V3_2_3V3AUX_SDA")
	)
	(segment
		(start 153.111962 -32.850328)
		(end 152.984962 -32.723328)
		(width 0.127)
		(layer "In6.Cu")
		(net "SMB_OCP_V3_2_3V3AUX_SDA")
	)
	(segment
		(start 154.889962 -33.373568)
		(end 154.508962 -33.373568)
		(width 0.127)
		(layer "In6.Cu")
		(net "SMB_OCP_V3_2_3V3AUX_SDA")
	)
	(segment
		(start 151.841962 -33.246568)
		(end 151.841962 -32.850328)
		(width 0.127)
		(layer "In6.Cu")
		(net "SMB_OCP_V3_2_3V3AUX_SDA")
	)
	(segment
		(start 168.21404 -24.946102)
		(end 160.436814 -32.723328)
		(width 0.127)
		(layer "In6.Cu")
		(net "SMB_OCP_V3_2_3V3AUX_SDA")
	)
	(segment
		(start 153.111962 -33.246568)
		(end 153.111962 -32.850328)
		(width 0.127)
		(layer "In6.Cu")
		(net "SMB_OCP_V3_2_3V3AUX_SDA")
	)
	(segment
		(start 169.886884 -17.712944)
		(end 170.200828 -18.026888)
		(width 0.127)
		(layer "In6.Cu")
		(net "SMB_OCP_V3_2_3V3AUX_SDA")
	)
	(segment
		(start 171.2341 -16.365728)
		(end 171.054268 -16.365728)
		(width 0.127)
		(layer "In6.Cu")
		(net "SMB_OCP_V3_2_3V3AUX_SDA")
	)
	(segment
		(start 170.200828 -18.20672)
		(end 168.21404 -20.193508)
		(width 0.127)
		(layer "In6.Cu")
		(net "SMB_OCP_V3_2_3V3AUX_SDA")
	)
	(segment
		(start 152.984962 -32.723328)
		(end 152.603962 -32.723328)
		(width 0.127)
		(layer "In6.Cu")
		(net "SMB_OCP_V3_2_3V3AUX_SDA")
	)
	(segment
		(start 143.13662 -32.271208)
		(end 142.6845 -32.723328)
		(width 0.127)
		(layer "In6.Cu")
		(net "SMB_OCP_V3_2_3V3AUX_SDA")
	)
	(segment
		(start 170.200828 -18.026888)
		(end 170.200828 -18.20672)
		(width 0.127)
		(layer "In6.Cu")
		(net "SMB_OCP_V3_2_3V3AUX_SDA")
	)
	(segment
		(start 170.785028 -16.634968)
		(end 170.785028 -16.8148)
		(width 0.127)
		(layer "In6.Cu")
		(net "SMB_OCP_V3_2_3V3AUX_SDA")
	)
	(segment
		(start 151.968962 -33.373568)
		(end 151.841962 -33.246568)
		(width 0.127)
		(layer "In6.Cu")
		(net "SMB_OCP_V3_2_3V3AUX_SDA")
	)
	(segment
		(start 154.508962 -33.373568)
		(end 154.381962 -33.246568)
		(width 0.127)
		(layer "In6.Cu")
		(net "SMB_OCP_V3_2_3V3AUX_SDA")
	)
	(segment
		(start 152.603962 -32.723328)
		(end 152.476962 -32.850328)
		(width 0.127)
		(layer "In6.Cu")
		(net "SMB_OCP_V3_2_3V3AUX_SDA")
	)
	(segment
		(start 169.886884 -17.533112)
		(end 169.886884 -17.712944)
		(width 0.127)
		(layer "In6.Cu")
		(net "SMB_OCP_V3_2_3V3AUX_SDA")
	)
	(segment
		(start 154.381962 -32.850328)
		(end 154.254962 -32.723328)
		(width 0.127)
		(layer "In6.Cu")
		(net "SMB_OCP_V3_2_3V3AUX_SDA")
	)
	(segment
		(start 171.548044 -16.679672)
		(end 171.2341 -16.365728)
		(width 0.127)
		(layer "In6.Cu")
		(net "SMB_OCP_V3_2_3V3AUX_SDA")
	)
	(segment
		(start 172.2247 -16.182848)
		(end 171.727876 -16.679672)
		(width 0.127)
		(layer "In6.Cu")
		(net "SMB_OCP_V3_2_3V3AUX_SDA")
	)
	(segment
		(start 145.1483 -32.271208)
		(end 143.13662 -32.271208)
		(width 0.127)
		(layer "In6.Cu")
		(net "SMB_OCP_V3_2_3V3AUX_SDA")
	)
	(segment
		(start 155.143962 -32.723328)
		(end 155.016962 -32.850328)
		(width 0.127)
		(layer "In6.Cu")
		(net "SMB_OCP_V3_2_3V3AUX_SDA")
	)
	(segment
		(start 142.6845 -32.723328)
		(end 138.1125 -32.723328)
		(width 0.127)
		(layer "In6.Cu")
		(net "SMB_OCP_V3_2_3V3AUX_SDA")
	)
	(segment
		(start 153.619962 -33.373568)
		(end 153.238962 -33.373568)
		(width 0.127)
		(layer "In6.Cu")
		(net "SMB_OCP_V3_2_3V3AUX_SDA")
	)
	(segment
		(start 172.867066 -13.337286)
		(end 172.57014 -12.621768)
		(width 0.12954)
		(layer "F.Cu")
		(net "SMB_OCP_V3_2_3V3AUX_SCL_R0")
	)
	(segment
		(start 172.57014 -12.621768)
		(end 172.57014 -10.775188)
		(width 0.12954)
		(layer "F.Cu")
		(net "SMB_OCP_V3_2_3V3AUX_SCL_R0")
	)
	(segment
		(start 172.867066 -13.600176)
		(end 172.867066 -13.337286)
		(width 0.12954)
		(layer "F.Cu")
		(net "SMB_OCP_V3_2_3V3AUX_SCL_R0")
	)
	(segment
		(start 172.57014 -10.775188)
		(end 172.10024 -10.305288)
		(width 0.12954)
		(layer "F.Cu")
		(net "SMB_OCP_V3_2_3V3AUX_SCL_R0")
	)
	(via
		(at 172.10024 -10.305288)
		(size 0.508)
		(drill 0.254)
		(layers "F.Cu" "B.Cu")
		(net "SMB_OCP_V3_2_3V3AUX_SCL_R0")
	)
	(segment
		(start 172.62094 -12.925806)
		(end 173.057312 -13.362178)
		(width 0.12954)
		(layer "B.Cu")
		(net "SMB_OCP_V3_2_3V3AUX_SCL_R0")
	)
	(segment
		(start 172.10024 -10.305288)
		(end 172.10024 -10.945622)
		(width 0.12954)
		(layer "B.Cu")
		(net "SMB_OCP_V3_2_3V3AUX_SCL_R0")
	)
	(segment
		(start 172.10024 -10.945622)
		(end 172.62094 -12.202414)
		(width 0.12954)
		(layer "B.Cu")
		(net "SMB_OCP_V3_2_3V3AUX_SCL_R0")
	)
	(segment
		(start 172.62094 -12.202414)
		(end 172.62094 -12.925806)
		(width 0.12954)
		(layer "B.Cu")
		(net "SMB_OCP_V3_2_3V3AUX_SCL_R0")
	)
	(segment
		(start 173.057312 -13.362178)
		(end 173.22292 -13.362178)
		(width 0.12954)
		(layer "B.Cu")
		(net "SMB_OCP_V3_2_3V3AUX_SCL_R0")
	)
	(segment
		(start 108.937806 -30.86481)
		(end 108.937806 -31.49981)
		(width 0.12954)
		(layer "F.Cu")
		(net "SMB_OCP_V3_2_3V3AUX_SCL")
	)
	(segment
		(start 108.844334 -31.406338)
		(end 108.937806 -31.49981)
		(width 0.12954)
		(layer "F.Cu")
		(net "SMB_OCP_V3_2_3V3AUX_SCL")
	)
	(segment
		(start 107.569 -31.406338)
		(end 108.844334 -31.406338)
		(width 0.12954)
		(layer "F.Cu")
		(net "SMB_OCP_V3_2_3V3AUX_SCL")
	)
	(segment
		(start 106.030522 -31.406338)
		(end 107.569 -31.406338)
		(width 0.12954)
		(layer "F.Cu")
		(net "SMB_OCP_V3_2_3V3AUX_SCL")
	)
	(via
		(at 108.937806 -30.86481)
		(size 0.508)
		(drill 0.254)
		(layers "F.Cu" "B.Cu")
		(net "SMB_OCP_V3_2_3V3AUX_SCL")
	)
	(via
		(at 107.569 -31.406338)
		(size 0.762)
		(drill 0.381)
		(layers "F.Cu" "B.Cu")
		(net "SMB_OCP_V3_2_3V3AUX_SCL")
	)
	(via
		(at 173.22292 -14.771878)
		(size 0.508)
		(drill 0.254)
		(layers "F.Cu" "B.Cu")
		(net "SMB_OCP_V3_2_3V3AUX_SCL")
	)
	(segment
		(start 173.22292 -14.162278)
		(end 173.22292 -14.771878)
		(width 0.12954)
		(layer "B.Cu")
		(net "SMB_OCP_V3_2_3V3AUX_SCL")
	)
	(segment
		(start 159.475678 -34.295588)
		(end 143.89608 -34.295588)
		(width 0.127)
		(layer "In6.Cu")
		(net "SMB_OCP_V3_2_3V3AUX_SCL")
	)
	(segment
		(start 142.8496 -33.249108)
		(end 138.19759 -33.249108)
		(width 0.127)
		(layer "In6.Cu")
		(net "SMB_OCP_V3_2_3V3AUX_SCL")
	)
	(segment
		(start 117.09781 -38.623748)
		(end 114.986308 -36.512246)
		(width 0.127)
		(layer "In6.Cu")
		(net "SMB_OCP_V3_2_3V3AUX_SCL")
	)
	(segment
		(start 132.82295 -38.623748)
		(end 117.09781 -38.623748)
		(width 0.127)
		(layer "In6.Cu")
		(net "SMB_OCP_V3_2_3V3AUX_SCL")
	)
	(segment
		(start 138.19759 -33.249108)
		(end 132.82295 -38.623748)
		(width 0.127)
		(layer "In6.Cu")
		(net "SMB_OCP_V3_2_3V3AUX_SCL")
	)
	(segment
		(start 108.466382 -31.336234)
		(end 108.937806 -30.86481)
		(width 0.127)
		(layer "In6.Cu")
		(net "SMB_OCP_V3_2_3V3AUX_SCL")
	)
	(segment
		(start 114.986308 -36.512246)
		(end 110.160308 -36.512246)
		(width 0.127)
		(layer "In6.Cu")
		(net "SMB_OCP_V3_2_3V3AUX_SCL")
	)
	(segment
		(start 173.22292 -14.771878)
		(end 173.22292 -15.801848)
		(width 0.127)
		(layer "In6.Cu")
		(net "SMB_OCP_V3_2_3V3AUX_SCL")
	)
	(segment
		(start 108.466382 -34.81832)
		(end 108.466382 -31.336234)
		(width 0.127)
		(layer "In6.Cu")
		(net "SMB_OCP_V3_2_3V3AUX_SCL")
	)
	(segment
		(start 143.89608 -34.295588)
		(end 142.8496 -33.249108)
		(width 0.127)
		(layer "In6.Cu")
		(net "SMB_OCP_V3_2_3V3AUX_SCL")
	)
	(segment
		(start 110.160308 -36.512246)
		(end 108.466382 -34.81832)
		(width 0.127)
		(layer "In6.Cu")
		(net "SMB_OCP_V3_2_3V3AUX_SCL")
	)
	(segment
		(start 168.70426 -25.067006)
		(end 159.475678 -34.295588)
		(width 0.127)
		(layer "In6.Cu")
		(net "SMB_OCP_V3_2_3V3AUX_SCL")
	)
	(segment
		(start 173.22292 -15.801848)
		(end 168.70426 -20.320508)
		(width 0.127)
		(layer "In6.Cu")
		(net "SMB_OCP_V3_2_3V3AUX_SCL")
	)
	(segment
		(start 168.70426 -20.320508)
		(end 168.70426 -25.067006)
		(width 0.127)
		(layer "In6.Cu")
		(net "SMB_OCP_V3_2_3V3AUX_SCL")
	)
	(segment
		(start 99.946714 -32.636714)
		(end 98.7171 -32.636714)
		(width 0.12954)
		(layer "F.Cu")
		(net "SMB_OCP_V3_2_3V3AUX_BUF_SDA")
	)
	(segment
		(start 96.34093 -33.274508)
		(end 98.09734 -33.274508)
		(width 0.12954)
		(layer "F.Cu")
		(net "SMB_OCP_V3_2_3V3AUX_BUF_SDA")
	)
	(segment
		(start 98.09734 -33.274508)
		(end 98.7171 -32.654748)
		(width 0.12954)
		(layer "F.Cu")
		(net "SMB_OCP_V3_2_3V3AUX_BUF_SDA")
	)
	(segment
		(start 100.52685 -32.056578)
		(end 99.946714 -32.636714)
		(width 0.12954)
		(layer "F.Cu")
		(net "SMB_OCP_V3_2_3V3AUX_BUF_SDA")
	)
	(segment
		(start 101.680518 -32.056578)
		(end 100.52685 -32.056578)
		(width 0.12954)
		(layer "F.Cu")
		(net "SMB_OCP_V3_2_3V3AUX_BUF_SDA")
	)
	(segment
		(start 98.7171 -32.654748)
		(end 98.7171 -32.636714)
		(width 0.12954)
		(layer "F.Cu")
		(net "SMB_OCP_V3_2_3V3AUX_BUF_SDA")
	)
	(segment
		(start 96.34093 -32.626808)
		(end 96.34093 -33.274508)
		(width 0.12954)
		(layer "F.Cu")
		(net "SMB_OCP_V3_2_3V3AUX_BUF_SDA")
	)
	(via
		(at 96.34093 -33.274508)
		(size 0.508)
		(drill 0.254)
		(layers "F.Cu" "B.Cu")
		(net "SMB_OCP_V3_2_3V3AUX_BUF_SDA")
	)
	(segment
		(start 98.73869 -31.577788)
		(end 98.73869 -31.552388)
		(width 0.12954)
		(layer "F.Cu")
		(net "SMB_OCP_V3_2_3V3AUX_BUF_SCL")
	)
	(segment
		(start 96.34601 -31.403798)
		(end 96.34601 -31.575248)
		(width 0.12954)
		(layer "F.Cu")
		(net "SMB_OCP_V3_2_3V3AUX_BUF_SCL")
	)
	(segment
		(start 99.159314 -31.577788)
		(end 99.20224 -31.620714)
		(width 0.12954)
		(layer "F.Cu")
		(net "SMB_OCP_V3_2_3V3AUX_BUF_SCL")
	)
	(segment
		(start 99.20224 -31.620714)
		(end 99.80422 -31.620714)
		(width 0.12954)
		(layer "F.Cu")
		(net "SMB_OCP_V3_2_3V3AUX_BUF_SCL")
	)
	(segment
		(start 98.73869 -31.577788)
		(end 99.159314 -31.577788)
		(width 0.12954)
		(layer "F.Cu")
		(net "SMB_OCP_V3_2_3V3AUX_BUF_SCL")
	)
	(segment
		(start 98.73869 -31.552388)
		(end 98.17989 -30.993588)
		(width 0.12954)
		(layer "F.Cu")
		(net "SMB_OCP_V3_2_3V3AUX_BUF_SCL")
	)
	(segment
		(start 100.018596 -31.406338)
		(end 101.680518 -31.406338)
		(width 0.12954)
		(layer "F.Cu")
		(net "SMB_OCP_V3_2_3V3AUX_BUF_SCL")
	)
	(segment
		(start 98.17989 -30.993588)
		(end 96.75622 -30.993588)
		(width 0.12954)
		(layer "F.Cu")
		(net "SMB_OCP_V3_2_3V3AUX_BUF_SCL")
	)
	(segment
		(start 96.75622 -30.993588)
		(end 96.34601 -31.403798)
		(width 0.12954)
		(layer "F.Cu")
		(net "SMB_OCP_V3_2_3V3AUX_BUF_SCL")
	)
	(segment
		(start 99.80422 -31.620714)
		(end 100.018596 -31.406338)
		(width 0.12954)
		(layer "F.Cu")
		(net "SMB_OCP_V3_2_3V3AUX_BUF_SCL")
	)
	(via
		(at 96.75622 -30.993588)
		(size 0.508)
		(drill 0.254)
		(layers "F.Cu" "B.Cu")
		(net "SMB_OCP_V3_2_3V3AUX_BUF_SCL")
	)
	(segment
		(start 61.666882 -6.76148)
		(end 61.667136 -6.760718)
		(width 0.12954)
		(layer "F.Cu")
		(net "SMB_OCP_V3_2_3V3AUX_BUF_R_SDA")
	)
	(segment
		(start 95.4024 -32.626808)
		(end 95.54083 -32.626808)
		(width 0.12954)
		(layer "F.Cu")
		(net "SMB_OCP_V3_2_3V3AUX_BUF_R_SDA")
	)
	(segment
		(start 62.61354 -5.814314)
		(end 62.61354 -5.171948)
		(width 0.12954)
		(layer "F.Cu")
		(net "SMB_OCP_V3_2_3V3AUX_BUF_R_SDA")
	)
	(segment
		(start 61.667136 -6.760718)
		(end 62.61354 -5.814314)
		(width 0.12954)
		(layer "F.Cu")
		(net "SMB_OCP_V3_2_3V3AUX_BUF_R_SDA")
	)
	(segment
		(start 94.7928 -32.017208)
		(end 95.4024 -32.626808)
		(width 0.12954)
		(layer "F.Cu")
		(net "SMB_OCP_V3_2_3V3AUX_BUF_R_SDA")
	)
	(segment
		(start 61.666882 -8.320024)
		(end 61.666882 -6.76148)
		(width 0.12954)
		(layer "F.Cu")
		(net "SMB_OCP_V3_2_3V3AUX_BUF_R_SDA")
	)
	(via
		(at 67.81546 -10.625328)
		(size 0.508)
		(drill 0.254)
		(layers "F.Cu" "B.Cu")
		(net "SMB_OCP_V3_2_3V3AUX_BUF_R_SDA")
	)
	(via
		(at 62.61354 -5.171948)
		(size 0.508)
		(drill 0.254)
		(layers "F.Cu" "B.Cu")
		(net "SMB_OCP_V3_2_3V3AUX_BUF_R_SDA")
	)
	(via
		(at 94.7928 -32.017208)
		(size 0.508)
		(drill 0.254)
		(layers "F.Cu" "B.Cu")
		(net "SMB_OCP_V3_2_3V3AUX_BUF_R_SDA")
	)
	(segment
		(start 68.25488 -6.695694)
		(end 66.731134 -5.171948)
		(width 0.12954)
		(layer "B.Cu")
		(net "SMB_OCP_V3_2_3V3AUX_BUF_R_SDA")
	)
	(segment
		(start 66.731134 -5.171948)
		(end 62.61354 -5.171948)
		(width 0.12954)
		(layer "B.Cu")
		(net "SMB_OCP_V3_2_3V3AUX_BUF_R_SDA")
	)
	(segment
		(start 68.25488 -10.185908)
		(end 68.25488 -6.695694)
		(width 0.12954)
		(layer "B.Cu")
		(net "SMB_OCP_V3_2_3V3AUX_BUF_R_SDA")
	)
	(segment
		(start 67.81546 -10.625328)
		(end 68.25488 -10.185908)
		(width 0.12954)
		(layer "B.Cu")
		(net "SMB_OCP_V3_2_3V3AUX_BUF_R_SDA")
	)
	(segment
		(start 85.04174 -25.979628)
		(end 85.04174 -19.106896)
		(width 0.127)
		(layer "In13.Cu")
		(net "SMB_OCP_V3_2_3V3AUX_BUF_R_SDA")
	)
	(segment
		(start 85.04174 -19.106896)
		(end 80.677512 -14.742668)
		(width 0.127)
		(layer "In13.Cu")
		(net "SMB_OCP_V3_2_3V3AUX_BUF_R_SDA")
	)
	(segment
		(start 94.7928 -32.017208)
		(end 94.54134 -31.765748)
		(width 0.127)
		(layer "In13.Cu")
		(net "SMB_OCP_V3_2_3V3AUX_BUF_R_SDA")
	)
	(segment
		(start 70.751954 -14.742668)
		(end 67.81546 -11.806174)
		(width 0.127)
		(layer "In13.Cu")
		(net "SMB_OCP_V3_2_3V3AUX_BUF_R_SDA")
	)
	(segment
		(start 94.54134 -31.765748)
		(end 90.82786 -31.765748)
		(width 0.127)
		(layer "In13.Cu")
		(net "SMB_OCP_V3_2_3V3AUX_BUF_R_SDA")
	)
	(segment
		(start 90.82786 -31.765748)
		(end 85.04174 -25.979628)
		(width 0.127)
		(layer "In13.Cu")
		(net "SMB_OCP_V3_2_3V3AUX_BUF_R_SDA")
	)
	(segment
		(start 67.81546 -11.806174)
		(end 67.81546 -10.625328)
		(width 0.127)
		(layer "In13.Cu")
		(net "SMB_OCP_V3_2_3V3AUX_BUF_R_SDA")
	)
	(segment
		(start 80.677512 -14.742668)
		(end 70.751954 -14.742668)
		(width 0.127)
		(layer "In13.Cu")
		(net "SMB_OCP_V3_2_3V3AUX_BUF_R_SDA")
	)
	(segment
		(start 94.96298 -31.575248)
		(end 95.54591 -31.575248)
		(width 0.12954)
		(layer "F.Cu")
		(net "SMB_OCP_V3_2_3V3AUX_BUF_R_SCL")
	)
	(segment
		(start 62.267084 -7.128764)
		(end 62.57544 -6.820408)
		(width 0.12954)
		(layer "F.Cu")
		(net "SMB_OCP_V3_2_3V3AUX_BUF_R_SCL")
	)
	(segment
		(start 62.267084 -8.320024)
		(end 62.267084 -7.128764)
		(width 0.12954)
		(layer "F.Cu")
		(net "SMB_OCP_V3_2_3V3AUX_BUF_R_SCL")
	)
	(segment
		(start 94.62262 -31.234888)
		(end 94.96298 -31.575248)
		(width 0.12954)
		(layer "F.Cu")
		(net "SMB_OCP_V3_2_3V3AUX_BUF_R_SCL")
	)
	(via
		(at 94.62262 -31.234888)
		(size 0.508)
		(drill 0.254)
		(layers "F.Cu" "B.Cu")
		(net "SMB_OCP_V3_2_3V3AUX_BUF_R_SCL")
	)
	(via
		(at 66.86296 -9.682988)
		(size 0.508)
		(drill 0.254)
		(layers "F.Cu" "B.Cu")
		(net "SMB_OCP_V3_2_3V3AUX_BUF_R_SCL")
	)
	(via
		(at 62.57544 -6.820408)
		(size 0.508)
		(drill 0.254)
		(layers "F.Cu" "B.Cu")
		(net "SMB_OCP_V3_2_3V3AUX_BUF_R_SCL")
	)
	(segment
		(start 66.22288 -6.187948)
		(end 63.2079 -6.187948)
		(width 0.12954)
		(layer "B.Cu")
		(net "SMB_OCP_V3_2_3V3AUX_BUF_R_SCL")
	)
	(segment
		(start 66.86296 -9.682988)
		(end 67.29984 -9.682988)
		(width 0.12954)
		(layer "B.Cu")
		(net "SMB_OCP_V3_2_3V3AUX_BUF_R_SCL")
	)
	(segment
		(start 63.2079 -6.187948)
		(end 62.57544 -6.820408)
		(width 0.12954)
		(layer "B.Cu")
		(net "SMB_OCP_V3_2_3V3AUX_BUF_R_SCL")
	)
	(segment
		(start 67.29984 -9.682988)
		(end 67.49288 -9.489948)
		(width 0.12954)
		(layer "B.Cu")
		(net "SMB_OCP_V3_2_3V3AUX_BUF_R_SCL")
	)
	(segment
		(start 67.49288 -9.489948)
		(end 67.49288 -7.457948)
		(width 0.12954)
		(layer "B.Cu")
		(net "SMB_OCP_V3_2_3V3AUX_BUF_R_SCL")
	)
	(segment
		(start 67.49288 -7.457948)
		(end 66.22288 -6.187948)
		(width 0.12954)
		(layer "B.Cu")
		(net "SMB_OCP_V3_2_3V3AUX_BUF_R_SCL")
	)
	(segment
		(start 85.47354 -18.910808)
		(end 80.85836 -14.295628)
		(width 0.127)
		(layer "In13.Cu")
		(net "SMB_OCP_V3_2_3V3AUX_BUF_R_SCL")
	)
	(segment
		(start 70.95744 -14.295628)
		(end 68.46062 -11.798808)
		(width 0.127)
		(layer "In13.Cu")
		(net "SMB_OCP_V3_2_3V3AUX_BUF_R_SCL")
	)
	(segment
		(start 80.85836 -14.295628)
		(end 70.95744 -14.295628)
		(width 0.127)
		(layer "In13.Cu")
		(net "SMB_OCP_V3_2_3V3AUX_BUF_R_SCL")
	)
	(segment
		(start 85.47354 -25.800304)
		(end 85.47354 -18.910808)
		(width 0.127)
		(layer "In13.Cu")
		(net "SMB_OCP_V3_2_3V3AUX_BUF_R_SCL")
	)
	(segment
		(start 68.46062 -9.972548)
		(end 68.17106 -9.682988)
		(width 0.127)
		(layer "In13.Cu")
		(net "SMB_OCP_V3_2_3V3AUX_BUF_R_SCL")
	)
	(segment
		(start 90.219784 -30.546548)
		(end 85.47354 -25.800304)
		(width 0.127)
		(layer "In13.Cu")
		(net "SMB_OCP_V3_2_3V3AUX_BUF_R_SCL")
	)
	(segment
		(start 68.46062 -11.798808)
		(end 68.46062 -9.972548)
		(width 0.127)
		(layer "In13.Cu")
		(net "SMB_OCP_V3_2_3V3AUX_BUF_R_SCL")
	)
	(segment
		(start 93.93428 -30.546548)
		(end 90.219784 -30.546548)
		(width 0.127)
		(layer "In13.Cu")
		(net "SMB_OCP_V3_2_3V3AUX_BUF_R_SCL")
	)
	(segment
		(start 68.17106 -9.682988)
		(end 66.86296 -9.682988)
		(width 0.127)
		(layer "In13.Cu")
		(net "SMB_OCP_V3_2_3V3AUX_BUF_R_SCL")
	)
	(segment
		(start 94.62262 -31.234888)
		(end 93.93428 -30.546548)
		(width 0.127)
		(layer "In13.Cu")
		(net "SMB_OCP_V3_2_3V3AUX_BUF_R_SCL")
	)
	(segment
		(start 178.266852 -12.17676)
		(end 178.267106 -12.177014)
		(width 0.12954)
		(layer "F.Cu")
		(net "SMB_OCP_SFF_3V3AUX_SDA_R0")
	)
	(segment
		(start 178.267106 -12.177014)
		(end 178.267106 -13.600176)
		(width 0.12954)
		(layer "F.Cu")
		(net "SMB_OCP_SFF_3V3AUX_SDA_R0")
	)
	(via
		(at 182.6006 -17.694148)
		(size 0.508)
		(drill 0.254)
		(layers "F.Cu" "B.Cu")
		(net "SMB_OCP_SFF_3V3AUX_SDA_R0")
	)
	(via
		(at 178.266852 -12.17676)
		(size 0.508)
		(drill 0.254)
		(layers "F.Cu" "B.Cu")
		(net "SMB_OCP_SFF_3V3AUX_SDA_R0")
	)
	(segment
		(start 182.6006 -17.694148)
		(end 182.871618 -17.965166)
		(width 0.12954)
		(layer "B.Cu")
		(net "SMB_OCP_SFF_3V3AUX_SDA_R0")
	)
	(segment
		(start 182.871618 -17.965166)
		(end 182.871618 -18.310098)
		(width 0.12954)
		(layer "B.Cu")
		(net "SMB_OCP_SFF_3V3AUX_SDA_R0")
	)
	(segment
		(start 182.6006 -17.368012)
		(end 181.422294 -14.523466)
		(width 0.127)
		(layer "In6.Cu")
		(net "SMB_OCP_SFF_3V3AUX_SDA_R0")
	)
	(segment
		(start 178.53152 -12.441428)
		(end 178.266852 -12.17676)
		(width 0.127)
		(layer "In6.Cu")
		(net "SMB_OCP_SFF_3V3AUX_SDA_R0")
	)
	(segment
		(start 181.422294 -14.523466)
		(end 179.340256 -12.441428)
		(width 0.127)
		(layer "In6.Cu")
		(net "SMB_OCP_SFF_3V3AUX_SDA_R0")
	)
	(segment
		(start 182.6006 -17.694148)
		(end 182.6006 -17.368012)
		(width 0.127)
		(layer "In6.Cu")
		(net "SMB_OCP_SFF_3V3AUX_SDA_R0")
	)
	(segment
		(start 179.340256 -12.441428)
		(end 178.53152 -12.441428)
		(width 0.127)
		(layer "In6.Cu")
		(net "SMB_OCP_SFF_3V3AUX_SDA_R0")
	)
	(segment
		(start 178.867054 -13.600176)
		(end 178.867054 -11.31951)
		(width 0.12954)
		(layer "F.Cu")
		(net "SMB_OCP_SFF_3V3AUX_SCL_R0")
	)
	(segment
		(start 178.867054 -11.31951)
		(end 178.266852 -10.719308)
		(width 0.12954)
		(layer "F.Cu")
		(net "SMB_OCP_SFF_3V3AUX_SCL_R0")
	)
	(via
		(at 183.38546 -17.719548)
		(size 0.508)
		(drill 0.254)
		(layers "F.Cu" "B.Cu")
		(net "SMB_OCP_SFF_3V3AUX_SCL_R0")
	)
	(via
		(at 178.266852 -10.719308)
		(size 0.508)
		(drill 0.254)
		(layers "F.Cu" "B.Cu")
		(net "SMB_OCP_SFF_3V3AUX_SCL_R0")
	)
	(segment
		(start 183.38546 -17.719548)
		(end 183.885078 -18.219166)
		(width 0.12954)
		(layer "B.Cu")
		(net "SMB_OCP_SFF_3V3AUX_SCL_R0")
	)
	(segment
		(start 183.885078 -18.219166)
		(end 183.885078 -18.310098)
		(width 0.12954)
		(layer "B.Cu")
		(net "SMB_OCP_SFF_3V3AUX_SCL_R0")
	)
	(segment
		(start 181.873906 -14.070838)
		(end 181.873906 -13.609828)
		(width 0.127)
		(layer "In6.Cu")
		(net "SMB_OCP_SFF_3V3AUX_SCL_R0")
	)
	(segment
		(start 181.873906 -13.609828)
		(end 178.983386 -10.719308)
		(width 0.127)
		(layer "In6.Cu")
		(net "SMB_OCP_SFF_3V3AUX_SCL_R0")
	)
	(segment
		(start 183.38546 -17.719548)
		(end 181.873906 -14.070838)
		(width 0.127)
		(layer "In6.Cu")
		(net "SMB_OCP_SFF_3V3AUX_SCL_R0")
	)
	(segment
		(start 178.983386 -10.719308)
		(end 178.266852 -10.719308)
		(width 0.127)
		(layer "In6.Cu")
		(net "SMB_OCP_SFF_3V3AUX_SCL_R0")
	)
	(segment
		(start 448.8942 -44.345098)
		(end 449.863464 -44.345098)
		(width 0.12954)
		(layer "F.Cu")
		(net "SMB_OCP_SFF_3V3AUX_BUF_SDA")
	)
	(segment
		(start 449.863464 -44.345098)
		(end 450.0372 -44.171362)
		(width 0.12954)
		(layer "F.Cu")
		(net "SMB_OCP_SFF_3V3AUX_BUF_SDA")
	)
	(segment
		(start 447.048382 -44.345098)
		(end 448.8942 -44.345098)
		(width 0.12954)
		(layer "F.Cu")
		(net "SMB_OCP_SFF_3V3AUX_BUF_SDA")
	)
	(via
		(at 448.8942 -44.345098)
		(size 0.508)
		(drill 0.254)
		(layers "F.Cu" "B.Cu")
		(net "SMB_OCP_SFF_3V3AUX_BUF_SDA")
	)
	(segment
		(start 448.8942 -44.345098)
		(end 449.116958 -44.345098)
		(width 0.12954)
		(layer "B.Cu")
		(net "SMB_OCP_SFF_3V3AUX_BUF_SDA")
	)
	(segment
		(start 449.116958 -44.345098)
		(end 449.290694 -44.171362)
		(width 0.12954)
		(layer "B.Cu")
		(net "SMB_OCP_SFF_3V3AUX_BUF_SDA")
	)
	(segment
		(start 449.290694 -44.171362)
		(end 450.0372 -44.171362)
		(width 0.12954)
		(layer "B.Cu")
		(net "SMB_OCP_SFF_3V3AUX_BUF_SDA")
	)
	(segment
		(start 448.51828 -46.299628)
		(end 449.503546 -45.314362)
		(width 0.12954)
		(layer "F.Cu")
		(net "SMB_OCP_SFF_3V3AUX_BUF_SCL")
	)
	(segment
		(start 449.503546 -45.314362)
		(end 450.0372 -45.314362)
		(width 0.12954)
		(layer "F.Cu")
		(net "SMB_OCP_SFF_3V3AUX_BUF_SCL")
	)
	(segment
		(start 449.718176 -44.995338)
		(end 447.048382 -44.995338)
		(width 0.12954)
		(layer "F.Cu")
		(net "SMB_OCP_SFF_3V3AUX_BUF_SCL")
	)
	(segment
		(start 450.0372 -45.314362)
		(end 449.718176 -44.995338)
		(width 0.12954)
		(layer "F.Cu")
		(net "SMB_OCP_SFF_3V3AUX_BUF_SCL")
	)
	(via
		(at 448.51828 -46.299628)
		(size 0.508)
		(drill 0.254)
		(layers "F.Cu" "B.Cu")
		(net "SMB_OCP_SFF_3V3AUX_BUF_SCL")
	)
	(segment
		(start 450.0372 -45.288962)
		(end 449.528946 -45.288962)
		(width 0.12954)
		(layer "B.Cu")
		(net "SMB_OCP_SFF_3V3AUX_BUF_SCL")
	)
	(segment
		(start 449.528946 -45.288962)
		(end 448.51828 -46.299628)
		(width 0.12954)
		(layer "B.Cu")
		(net "SMB_OCP_SFF_3V3AUX_BUF_SCL")
	)
	(segment
		(start 436.166768 -7.066534)
		(end 436.140606 -7.040372)
		(width 0.12954)
		(layer "F.Cu")
		(net "SMB_OCP_SFF_3V3AUX_BUF_R_SDA")
	)
	(segment
		(start 436.166768 -8.320024)
		(end 436.166768 -7.066534)
		(width 0.12954)
		(layer "F.Cu")
		(net "SMB_OCP_SFF_3V3AUX_BUF_R_SDA")
	)
	(segment
		(start 436.140606 -7.040372)
		(end 436.140606 -6.568948)
		(width 0.12954)
		(layer "F.Cu")
		(net "SMB_OCP_SFF_3V3AUX_BUF_R_SDA")
	)
	(via
		(at 451.993 -43.609768)
		(size 0.508)
		(drill 0.254)
		(layers "F.Cu" "B.Cu")
		(net "SMB_OCP_SFF_3V3AUX_BUF_R_SDA")
	)
	(via
		(at 436.140606 -6.568948)
		(size 0.508)
		(drill 0.254)
		(layers "F.Cu" "B.Cu")
		(net "SMB_OCP_SFF_3V3AUX_BUF_R_SDA")
	)
	(via
		(at 443.92088 -8.727948)
		(size 0.508)
		(drill 0.254)
		(layers "F.Cu" "B.Cu")
		(net "SMB_OCP_SFF_3V3AUX_BUF_R_SDA")
	)
	(segment
		(start 436.898288 -9.489948)
		(end 436.124604 -8.716264)
		(width 0.12954)
		(layer "B.Cu")
		(net "SMB_OCP_SFF_3V3AUX_BUF_R_SDA")
	)
	(segment
		(start 436.124604 -8.716264)
		(end 436.124604 -6.58495)
		(width 0.12954)
		(layer "B.Cu")
		(net "SMB_OCP_SFF_3V3AUX_BUF_R_SDA")
	)
	(segment
		(start 451.83298 -44.701968)
		(end 451.0532 -44.701968)
		(width 0.12954)
		(layer "B.Cu")
		(net "SMB_OCP_SFF_3V3AUX_BUF_R_SDA")
	)
	(segment
		(start 442.904626 -8.727948)
		(end 442.142626 -9.489948)
		(width 0.12954)
		(layer "B.Cu")
		(net "SMB_OCP_SFF_3V3AUX_BUF_R_SDA")
	)
	(segment
		(start 451.993 -44.541948)
		(end 451.83298 -44.701968)
		(width 0.12954)
		(layer "B.Cu")
		(net "SMB_OCP_SFF_3V3AUX_BUF_R_SDA")
	)
	(segment
		(start 443.92088 -8.727948)
		(end 442.904626 -8.727948)
		(width 0.12954)
		(layer "B.Cu")
		(net "SMB_OCP_SFF_3V3AUX_BUF_R_SDA")
	)
	(segment
		(start 451.993 -43.609768)
		(end 451.993 -44.541948)
		(width 0.12954)
		(layer "B.Cu")
		(net "SMB_OCP_SFF_3V3AUX_BUF_R_SDA")
	)
	(segment
		(start 442.142626 -9.489948)
		(end 436.898288 -9.489948)
		(width 0.12954)
		(layer "B.Cu")
		(net "SMB_OCP_SFF_3V3AUX_BUF_R_SDA")
	)
	(segment
		(start 451.0532 -44.701968)
		(end 450.8373 -44.486068)
		(width 0.12954)
		(layer "B.Cu")
		(net "SMB_OCP_SFF_3V3AUX_BUF_R_SDA")
	)
	(segment
		(start 436.124604 -6.58495)
		(end 436.140606 -6.568948)
		(width 0.12954)
		(layer "B.Cu")
		(net "SMB_OCP_SFF_3V3AUX_BUF_R_SDA")
	)
	(segment
		(start 450.8373 -44.486068)
		(end 450.8373 -44.171362)
		(width 0.12954)
		(layer "B.Cu")
		(net "SMB_OCP_SFF_3V3AUX_BUF_R_SDA")
	)
	(segment
		(start 451.66788 -43.284648)
		(end 451.993 -43.609768)
		(width 0.127)
		(layer "In2.Cu")
		(net "SMB_OCP_SFF_3V3AUX_BUF_R_SDA")
	)
	(segment
		(start 450.80174 -38.484048)
		(end 449.6308 -38.484048)
		(width 0.127)
		(layer "In2.Cu")
		(net "SMB_OCP_SFF_3V3AUX_BUF_R_SDA")
	)
	(segment
		(start 450.80174 -39.096188)
		(end 450.90588 -39.200328)
		(width 0.127)
		(layer "In2.Cu")
		(net "SMB_OCP_SFF_3V3AUX_BUF_R_SDA")
	)
	(segment
		(start 447.26098 -16.934688)
		(end 447.26098 -22.207728)
		(width 0.127)
		(layer "In2.Cu")
		(net "SMB_OCP_SFF_3V3AUX_BUF_R_SDA")
	)
	(segment
		(start 449.38188 -13.607288)
		(end 449.38188 -14.813788)
		(width 0.127)
		(layer "In2.Cu")
		(net "SMB_OCP_SFF_3V3AUX_BUF_R_SDA")
	)
	(segment
		(start 449.38188 -14.813788)
		(end 447.26098 -16.934688)
		(width 0.127)
		(layer "In2.Cu")
		(net "SMB_OCP_SFF_3V3AUX_BUF_R_SDA")
	)
	(segment
		(start 447.26098 -22.207728)
		(end 447.68008 -22.626828)
		(width 0.127)
		(layer "In2.Cu")
		(net "SMB_OCP_SFF_3V3AUX_BUF_R_SDA")
	)
	(segment
		(start 449.6308 -39.708328)
		(end 449.52666 -39.812468)
		(width 0.127)
		(layer "In2.Cu")
		(net "SMB_OCP_SFF_3V3AUX_BUF_R_SDA")
	)
	(segment
		(start 450.90588 -40.424608)
		(end 450.90588 -40.731948)
		(width 0.127)
		(layer "In2.Cu")
		(net "SMB_OCP_SFF_3V3AUX_BUF_R_SDA")
	)
	(segment
		(start 450.90588 -38.379908)
		(end 450.80174 -38.484048)
		(width 0.127)
		(layer "In2.Cu")
		(net "SMB_OCP_SFF_3V3AUX_BUF_R_SDA")
	)
	(segment
		(start 449.6308 -38.484048)
		(end 449.52666 -38.588188)
		(width 0.127)
		(layer "In2.Cu")
		(net "SMB_OCP_SFF_3V3AUX_BUF_R_SDA")
	)
	(segment
		(start 450.90588 -39.200328)
		(end 450.90588 -39.604188)
		(width 0.127)
		(layer "In2.Cu")
		(net "SMB_OCP_SFF_3V3AUX_BUF_R_SDA")
	)
	(segment
		(start 449.6308 -39.096188)
		(end 450.80174 -39.096188)
		(width 0.127)
		(layer "In2.Cu")
		(net "SMB_OCP_SFF_3V3AUX_BUF_R_SDA")
	)
	(segment
		(start 449.52666 -38.588188)
		(end 449.52666 -38.992048)
		(width 0.127)
		(layer "In2.Cu")
		(net "SMB_OCP_SFF_3V3AUX_BUF_R_SDA")
	)
	(segment
		(start 443.92088 -8.727948)
		(end 444.81242 -8.727948)
		(width 0.127)
		(layer "In2.Cu")
		(net "SMB_OCP_SFF_3V3AUX_BUF_R_SDA")
	)
	(segment
		(start 450.80174 -39.708328)
		(end 449.6308 -39.708328)
		(width 0.127)
		(layer "In2.Cu")
		(net "SMB_OCP_SFF_3V3AUX_BUF_R_SDA")
	)
	(segment
		(start 449.52666 -39.812468)
		(end 449.52666 -40.216328)
		(width 0.127)
		(layer "In2.Cu")
		(net "SMB_OCP_SFF_3V3AUX_BUF_R_SDA")
	)
	(segment
		(start 451.66788 -41.493948)
		(end 451.66788 -43.284648)
		(width 0.127)
		(layer "In2.Cu")
		(net "SMB_OCP_SFF_3V3AUX_BUF_R_SDA")
	)
	(segment
		(start 449.52666 -38.992048)
		(end 449.6308 -39.096188)
		(width 0.127)
		(layer "In2.Cu")
		(net "SMB_OCP_SFF_3V3AUX_BUF_R_SDA")
	)
	(segment
		(start 449.93306 -13.056108)
		(end 449.38188 -13.607288)
		(width 0.127)
		(layer "In2.Cu")
		(net "SMB_OCP_SFF_3V3AUX_BUF_R_SDA")
	)
	(segment
		(start 449.93306 -12.522708)
		(end 449.93306 -13.056108)
		(width 0.127)
		(layer "In2.Cu")
		(net "SMB_OCP_SFF_3V3AUX_BUF_R_SDA")
	)
	(segment
		(start 449.6308 -40.320468)
		(end 450.80174 -40.320468)
		(width 0.127)
		(layer "In2.Cu")
		(net "SMB_OCP_SFF_3V3AUX_BUF_R_SDA")
	)
	(segment
		(start 450.90588 -40.731948)
		(end 451.66788 -41.493948)
		(width 0.127)
		(layer "In2.Cu")
		(net "SMB_OCP_SFF_3V3AUX_BUF_R_SDA")
	)
	(segment
		(start 444.81242 -8.727948)
		(end 445.52489 -9.440418)
		(width 0.127)
		(layer "In2.Cu")
		(net "SMB_OCP_SFF_3V3AUX_BUF_R_SDA")
	)
	(segment
		(start 450.80174 -40.320468)
		(end 450.90588 -40.424608)
		(width 0.127)
		(layer "In2.Cu")
		(net "SMB_OCP_SFF_3V3AUX_BUF_R_SDA")
	)
	(segment
		(start 450.90588 -39.604188)
		(end 450.80174 -39.708328)
		(width 0.127)
		(layer "In2.Cu")
		(net "SMB_OCP_SFF_3V3AUX_BUF_R_SDA")
	)
	(segment
		(start 449.52666 -40.216328)
		(end 449.6308 -40.320468)
		(width 0.127)
		(layer "In2.Cu")
		(net "SMB_OCP_SFF_3V3AUX_BUF_R_SDA")
	)
	(segment
		(start 450.90588 -27.523948)
		(end 450.90588 -38.379908)
		(width 0.127)
		(layer "In2.Cu")
		(net "SMB_OCP_SFF_3V3AUX_BUF_R_SDA")
	)
	(segment
		(start 446.85077 -9.440418)
		(end 449.93306 -12.522708)
		(width 0.127)
		(layer "In2.Cu")
		(net "SMB_OCP_SFF_3V3AUX_BUF_R_SDA")
	)
	(segment
		(start 445.52489 -9.440418)
		(end 446.85077 -9.440418)
		(width 0.127)
		(layer "In2.Cu")
		(net "SMB_OCP_SFF_3V3AUX_BUF_R_SDA")
	)
	(segment
		(start 447.68008 -24.298148)
		(end 450.90588 -27.523948)
		(width 0.127)
		(layer "In2.Cu")
		(net "SMB_OCP_SFF_3V3AUX_BUF_R_SDA")
	)
	(segment
		(start 447.68008 -22.626828)
		(end 447.68008 -24.298148)
		(width 0.127)
		(layer "In2.Cu")
		(net "SMB_OCP_SFF_3V3AUX_BUF_R_SDA")
	)
	(segment
		(start 436.76697 -8.320024)
		(end 436.76697 -6.577584)
		(width 0.12954)
		(layer "F.Cu")
		(net "SMB_OCP_SFF_3V3AUX_BUF_R_SCL")
	)
	(segment
		(start 436.76697 -6.577584)
		(end 436.775606 -6.568948)
		(width 0.12954)
		(layer "F.Cu")
		(net "SMB_OCP_SFF_3V3AUX_BUF_R_SCL")
	)
	(via
		(at 452.7804 -44.686728)
		(size 0.508)
		(drill 0.254)
		(layers "F.Cu" "B.Cu")
		(net "SMB_OCP_SFF_3V3AUX_BUF_R_SCL")
	)
	(via
		(at 443.92088 -8.092948)
		(size 0.508)
		(drill 0.254)
		(layers "F.Cu" "B.Cu")
		(net "SMB_OCP_SFF_3V3AUX_BUF_R_SCL")
	)
	(via
		(at 436.775606 -6.568948)
		(size 0.508)
		(drill 0.254)
		(layers "F.Cu" "B.Cu")
		(net "SMB_OCP_SFF_3V3AUX_BUF_R_SCL")
	)
	(segment
		(start 450.8373 -45.588428)
		(end 450.8373 -45.288962)
		(width 0.12954)
		(layer "B.Cu")
		(net "SMB_OCP_SFF_3V3AUX_BUF_R_SCL")
	)
	(segment
		(start 437.307228 -7.10057)
		(end 436.775606 -6.568948)
		(width 0.12954)
		(layer "B.Cu")
		(net "SMB_OCP_SFF_3V3AUX_BUF_R_SCL")
	)
	(segment
		(start 452.7804 -45.278548)
		(end 452.26732 -45.791628)
		(width 0.12954)
		(layer "B.Cu")
		(net "SMB_OCP_SFF_3V3AUX_BUF_R_SCL")
	)
	(segment
		(start 452.7804 -44.686728)
		(end 452.7804 -45.278548)
		(width 0.12954)
		(layer "B.Cu")
		(net "SMB_OCP_SFF_3V3AUX_BUF_R_SCL")
	)
	(segment
		(start 443.92088 -8.092948)
		(end 442.52388 -8.092948)
		(width 0.12954)
		(layer "B.Cu")
		(net "SMB_OCP_SFF_3V3AUX_BUF_R_SCL")
	)
	(segment
		(start 441.56122 -9.055608)
		(end 437.681116 -9.055608)
		(width 0.12954)
		(layer "B.Cu")
		(net "SMB_OCP_SFF_3V3AUX_BUF_R_SCL")
	)
	(segment
		(start 437.681116 -9.055608)
		(end 437.307228 -8.68172)
		(width 0.12954)
		(layer "B.Cu")
		(net "SMB_OCP_SFF_3V3AUX_BUF_R_SCL")
	)
	(segment
		(start 452.26732 -45.791628)
		(end 451.0405 -45.791628)
		(width 0.12954)
		(layer "B.Cu")
		(net "SMB_OCP_SFF_3V3AUX_BUF_R_SCL")
	)
	(segment
		(start 442.52388 -8.092948)
		(end 441.56122 -9.055608)
		(width 0.12954)
		(layer "B.Cu")
		(net "SMB_OCP_SFF_3V3AUX_BUF_R_SCL")
	)
	(segment
		(start 451.0405 -45.791628)
		(end 450.8373 -45.588428)
		(width 0.12954)
		(layer "B.Cu")
		(net "SMB_OCP_SFF_3V3AUX_BUF_R_SCL")
	)
	(segment
		(start 437.307228 -8.68172)
		(end 437.307228 -7.10057)
		(width 0.12954)
		(layer "B.Cu")
		(net "SMB_OCP_SFF_3V3AUX_BUF_R_SCL")
	)
	(segment
		(start 447.82232 -17.145508)
		(end 450.77888 -14.188948)
		(width 0.127)
		(layer "In2.Cu")
		(net "SMB_OCP_SFF_3V3AUX_BUF_R_SCL")
	)
	(segment
		(start 445.56426 -6.053328)
		(end 443.92088 -7.696708)
		(width 0.127)
		(layer "In2.Cu")
		(net "SMB_OCP_SFF_3V3AUX_BUF_R_SCL")
	)
	(segment
		(start 452.7804 -41.995598)
		(end 451.33768 -40.552878)
		(width 0.127)
		(layer "In2.Cu")
		(net "SMB_OCP_SFF_3V3AUX_BUF_R_SCL")
	)
	(segment
		(start 452.7804 -44.686728)
		(end 452.7804 -41.995598)
		(width 0.127)
		(layer "In2.Cu")
		(net "SMB_OCP_SFF_3V3AUX_BUF_R_SCL")
	)
	(segment
		(start 450.77888 -14.188948)
		(end 450.77888 -13.442188)
		(width 0.127)
		(layer "In2.Cu")
		(net "SMB_OCP_SFF_3V3AUX_BUF_R_SCL")
	)
	(segment
		(start 448.13474 -22.309328)
		(end 447.82232 -21.996908)
		(width 0.127)
		(layer "In2.Cu")
		(net "SMB_OCP_SFF_3V3AUX_BUF_R_SCL")
	)
	(segment
		(start 446.94602 -6.053328)
		(end 445.56426 -6.053328)
		(width 0.127)
		(layer "In2.Cu")
		(net "SMB_OCP_SFF_3V3AUX_BUF_R_SCL")
	)
	(segment
		(start 451.33768 -40.552878)
		(end 451.33768 -27.344878)
		(width 0.127)
		(layer "In2.Cu")
		(net "SMB_OCP_SFF_3V3AUX_BUF_R_SCL")
	)
	(segment
		(start 443.92088 -7.696708)
		(end 443.92088 -8.092948)
		(width 0.127)
		(layer "In2.Cu")
		(net "SMB_OCP_SFF_3V3AUX_BUF_R_SCL")
	)
	(segment
		(start 451.15988 -10.267188)
		(end 446.94602 -6.053328)
		(width 0.127)
		(layer "In2.Cu")
		(net "SMB_OCP_SFF_3V3AUX_BUF_R_SCL")
	)
	(segment
		(start 450.77888 -13.442188)
		(end 451.15988 -13.061188)
		(width 0.127)
		(layer "In2.Cu")
		(net "SMB_OCP_SFF_3V3AUX_BUF_R_SCL")
	)
	(segment
		(start 447.82232 -21.996908)
		(end 447.82232 -17.145508)
		(width 0.127)
		(layer "In2.Cu")
		(net "SMB_OCP_SFF_3V3AUX_BUF_R_SCL")
	)
	(segment
		(start 451.15988 -13.061188)
		(end 451.15988 -10.267188)
		(width 0.127)
		(layer "In2.Cu")
		(net "SMB_OCP_SFF_3V3AUX_BUF_R_SCL")
	)
	(segment
		(start 448.13474 -24.141938)
		(end 448.13474 -22.309328)
		(width 0.127)
		(layer "In2.Cu")
		(net "SMB_OCP_SFF_3V3AUX_BUF_R_SCL")
	)
	(segment
		(start 451.33768 -27.344878)
		(end 448.13474 -24.141938)
		(width 0.127)
		(layer "In2.Cu")
		(net "SMB_OCP_SFF_3V3AUX_BUF_R_SCL")
	)
	(segment
		(start 31.93288 -437.219598)
		(end 32.380428 -437.667146)
		(width 0.12954)
		(layer "F.Cu")
		(net "SMB_2_BMC_GPU_BUF_SDA")
	)
	(segment
		(start 31.93288 -436.692548)
		(end 31.93288 -437.219598)
		(width 0.12954)
		(layer "F.Cu")
		(net "SMB_2_BMC_GPU_BUF_SDA")
	)
	(segment
		(start 32.380428 -437.667146)
		(end 32.380428 -437.688228)
		(width 0.12954)
		(layer "F.Cu")
		(net "SMB_2_BMC_GPU_BUF_SDA")
	)
	(via
		(at 31.93288 -436.692548)
		(size 0.508)
		(drill 0.254)
		(layers "F.Cu" "B.Cu")
		(net "SMB_2_BMC_GPU_BUF_SDA")
	)
	(segment
		(start 62.650116 -418.889942)
		(end 61.87948 -418.119306)
		(width 0.127)
		(layer "In15.Cu")
		(net "SMB_2_BMC_GPU_BUF_SDA")
	)
	(segment
		(start 41.61028 -437.657494)
		(end 41.127934 -437.175148)
		(width 0.127)
		(layer "In15.Cu")
		(net "SMB_2_BMC_GPU_BUF_SDA")
	)
	(segment
		(start 42.526712 -437.657494)
		(end 41.61028 -437.657494)
		(width 0.127)
		(layer "In15.Cu")
		(net "SMB_2_BMC_GPU_BUF_SDA")
	)
	(segment
		(start 55.65648 -435.828948)
		(end 55.242968 -436.24246)
		(width 0.127)
		(layer "In15.Cu")
		(net "SMB_2_BMC_GPU_BUF_SDA")
	)
	(segment
		(start 55.242968 -436.24246)
		(end 54.914038 -436.24246)
		(width 0.127)
		(layer "In15.Cu")
		(net "SMB_2_BMC_GPU_BUF_SDA")
	)
	(segment
		(start 35.332416 -437.175148)
		(end 34.849816 -436.692548)
		(width 0.127)
		(layer "In15.Cu")
		(net "SMB_2_BMC_GPU_BUF_SDA")
	)
	(segment
		(start 61.87948 -416.499548)
		(end 60.83808 -415.458148)
		(width 0.127)
		(layer "In15.Cu")
		(net "SMB_2_BMC_GPU_BUF_SDA")
	)
	(segment
		(start 41.127934 -437.175148)
		(end 35.332416 -437.175148)
		(width 0.127)
		(layer "In15.Cu")
		(net "SMB_2_BMC_GPU_BUF_SDA")
	)
	(segment
		(start 54.914038 -436.24246)
		(end 54.732936 -436.423562)
		(width 0.127)
		(layer "In15.Cu")
		(net "SMB_2_BMC_GPU_BUF_SDA")
	)
	(segment
		(start 57.707276 -415.458148)
		(end 55.65648 -417.508944)
		(width 0.127)
		(layer "In15.Cu")
		(net "SMB_2_BMC_GPU_BUF_SDA")
	)
	(segment
		(start 34.849816 -436.692548)
		(end 31.93288 -436.692548)
		(width 0.127)
		(layer "In15.Cu")
		(net "SMB_2_BMC_GPU_BUF_SDA")
	)
	(segment
		(start 55.65648 -417.508944)
		(end 55.65648 -435.828948)
		(width 0.127)
		(layer "In15.Cu")
		(net "SMB_2_BMC_GPU_BUF_SDA")
	)
	(segment
		(start 42.996866 -436.843424)
		(end 42.996866 -437.18734)
		(width 0.127)
		(layer "In15.Cu")
		(net "SMB_2_BMC_GPU_BUF_SDA")
	)
	(segment
		(start 54.732936 -436.423562)
		(end 43.416728 -436.423562)
		(width 0.127)
		(layer "In15.Cu")
		(net "SMB_2_BMC_GPU_BUF_SDA")
	)
	(segment
		(start 42.996866 -437.18734)
		(end 42.526712 -437.657494)
		(width 0.127)
		(layer "In15.Cu")
		(net "SMB_2_BMC_GPU_BUF_SDA")
	)
	(segment
		(start 61.87948 -418.119306)
		(end 61.87948 -416.499548)
		(width 0.127)
		(layer "In15.Cu")
		(net "SMB_2_BMC_GPU_BUF_SDA")
	)
	(segment
		(start 43.416728 -436.423562)
		(end 42.996866 -436.843424)
		(width 0.127)
		(layer "In15.Cu")
		(net "SMB_2_BMC_GPU_BUF_SDA")
	)
	(segment
		(start 60.83808 -415.458148)
		(end 57.707276 -415.458148)
		(width 0.127)
		(layer "In15.Cu")
		(net "SMB_2_BMC_GPU_BUF_SDA")
	)
	(segment
		(start 47.953676 -438.173368)
		(end 47.572676 -437.792368)
		(width 0.12954)
		(layer "F.Cu")
		(net "SMB_2_BMC_GPU_BUF_SCL")
	)
	(segment
		(start 47.572676 -437.792368)
		(end 47.026068 -437.792368)
		(width 0.12954)
		(layer "F.Cu")
		(net "SMB_2_BMC_GPU_BUF_SCL")
	)
	(via
		(at 47.953676 -438.173368)
		(size 0.508)
		(drill 0.254)
		(layers "F.Cu" "B.Cu")
		(net "SMB_2_BMC_GPU_BUF_SCL")
	)
	(segment
		(start 56.08828 -424.520106)
		(end 56.08828 -424.139106)
		(width 0.127)
		(layer "In15.Cu")
		(net "SMB_2_BMC_GPU_BUF_SCL")
	)
	(segment
		(start 56.08828 -430.489106)
		(end 56.21528 -430.362106)
		(width 0.127)
		(layer "In15.Cu")
		(net "SMB_2_BMC_GPU_BUF_SCL")
	)
	(segment
		(start 57.14746 -428.965106)
		(end 57.14746 -428.584106)
		(width 0.127)
		(layer "In15.Cu")
		(net "SMB_2_BMC_GPU_BUF_SCL")
	)
	(segment
		(start 56.21528 -425.282106)
		(end 57.02046 -425.282106)
		(width 0.127)
		(layer "In15.Cu")
		(net "SMB_2_BMC_GPU_BUF_SCL")
	)
	(segment
		(start 56.21528 -422.742106)
		(end 57.02046 -422.742106)
		(width 0.127)
		(layer "In15.Cu")
		(net "SMB_2_BMC_GPU_BUF_SCL")
	)
	(segment
		(start 56.08828 -429.219106)
		(end 56.21528 -429.092106)
		(width 0.127)
		(layer "In15.Cu")
		(net "SMB_2_BMC_GPU_BUF_SCL")
	)
	(segment
		(start 57.14746 -425.155106)
		(end 57.14746 -424.774106)
		(width 0.127)
		(layer "In15.Cu")
		(net "SMB_2_BMC_GPU_BUF_SCL")
	)
	(segment
		(start 57.02046 -425.917106)
		(end 56.21528 -425.917106)
		(width 0.127)
		(layer "In15.Cu")
		(net "SMB_2_BMC_GPU_BUF_SCL")
	)
	(segment
		(start 56.21528 -420.837106)
		(end 56.08828 -420.710106)
		(width 0.127)
		(layer "In15.Cu")
		(net "SMB_2_BMC_GPU_BUF_SCL")
	)
	(segment
		(start 56.08828 -429.600106)
		(end 56.08828 -429.219106)
		(width 0.127)
		(layer "In15.Cu")
		(net "SMB_2_BMC_GPU_BUF_SCL")
	)
	(segment
		(start 57.14746 -427.695106)
		(end 57.14746 -427.314106)
		(width 0.127)
		(layer "In15.Cu")
		(net "SMB_2_BMC_GPU_BUF_SCL")
	)
	(segment
		(start 56.08828 -421.599106)
		(end 56.21528 -421.472106)
		(width 0.127)
		(layer "In15.Cu")
		(net "SMB_2_BMC_GPU_BUF_SCL")
	)
	(segment
		(start 57.02046 -427.822106)
		(end 57.14746 -427.695106)
		(width 0.127)
		(layer "In15.Cu")
		(net "SMB_2_BMC_GPU_BUF_SCL")
	)
	(segment
		(start 57.02046 -420.837106)
		(end 56.21528 -420.837106)
		(width 0.127)
		(layer "In15.Cu")
		(net "SMB_2_BMC_GPU_BUF_SCL")
	)
	(segment
		(start 56.21528 -426.552106)
		(end 57.02046 -426.552106)
		(width 0.127)
		(layer "In15.Cu")
		(net "SMB_2_BMC_GPU_BUF_SCL")
	)
	(segment
		(start 56.08828 -427.949106)
		(end 56.21528 -427.822106)
		(width 0.127)
		(layer "In15.Cu")
		(net "SMB_2_BMC_GPU_BUF_SCL")
	)
	(segment
		(start 57.726834 -416.067748)
		(end 60.53328 -416.067748)
		(width 0.127)
		(layer "In15.Cu")
		(net "SMB_2_BMC_GPU_BUF_SCL")
	)
	(segment
		(start 57.14746 -420.075106)
		(end 57.14746 -419.694106)
		(width 0.127)
		(layer "In15.Cu")
		(net "SMB_2_BMC_GPU_BUF_SCL")
	)
	(segment
		(start 56.21528 -424.647106)
		(end 56.08828 -424.520106)
		(width 0.127)
		(layer "In15.Cu")
		(net "SMB_2_BMC_GPU_BUF_SCL")
	)
	(segment
		(start 57.02046 -425.282106)
		(end 57.14746 -425.155106)
		(width 0.127)
		(layer "In15.Cu")
		(net "SMB_2_BMC_GPU_BUF_SCL")
	)
	(segment
		(start 54.273958 -437.97347)
		(end 56.08828 -436.159148)
		(width 0.127)
		(layer "In15.Cu")
		(net "SMB_2_BMC_GPU_BUF_SCL")
	)
	(segment
		(start 56.21528 -419.567106)
		(end 56.08828 -419.440106)
		(width 0.127)
		(layer "In15.Cu")
		(net "SMB_2_BMC_GPU_BUF_SCL")
	)
	(segment
		(start 56.08828 -421.980106)
		(end 56.08828 -421.599106)
		(width 0.127)
		(layer "In15.Cu")
		(net "SMB_2_BMC_GPU_BUF_SCL")
	)
	(segment
		(start 57.14746 -428.584106)
		(end 57.02046 -428.457106)
		(width 0.127)
		(layer "In15.Cu")
		(net "SMB_2_BMC_GPU_BUF_SCL")
	)
	(segment
		(start 47.953676 -438.173368)
		(end 49.34966 -438.173368)
		(width 0.127)
		(layer "In15.Cu")
		(net "SMB_2_BMC_GPU_BUF_SCL")
	)
	(segment
		(start 57.02046 -422.742106)
		(end 57.14746 -422.615106)
		(width 0.127)
		(layer "In15.Cu")
		(net "SMB_2_BMC_GPU_BUF_SCL")
	)
	(segment
		(start 56.21528 -429.727106)
		(end 56.08828 -429.600106)
		(width 0.127)
		(layer "In15.Cu")
		(net "SMB_2_BMC_GPU_BUF_SCL")
	)
	(segment
		(start 57.14746 -423.885106)
		(end 57.14746 -423.504106)
		(width 0.127)
		(layer "In15.Cu")
		(net "SMB_2_BMC_GPU_BUF_SCL")
	)
	(segment
		(start 56.08828 -423.250106)
		(end 56.08828 -422.869106)
		(width 0.127)
		(layer "In15.Cu")
		(net "SMB_2_BMC_GPU_BUF_SCL")
	)
	(segment
		(start 57.02046 -422.107106)
		(end 56.21528 -422.107106)
		(width 0.127)
		(layer "In15.Cu")
		(net "SMB_2_BMC_GPU_BUF_SCL")
	)
	(segment
		(start 57.14746 -422.234106)
		(end 57.02046 -422.107106)
		(width 0.127)
		(layer "In15.Cu")
		(net "SMB_2_BMC_GPU_BUF_SCL")
	)
	(segment
		(start 57.14746 -422.615106)
		(end 57.14746 -422.234106)
		(width 0.127)
		(layer "In15.Cu")
		(net "SMB_2_BMC_GPU_BUF_SCL")
	)
	(segment
		(start 57.02046 -429.727106)
		(end 56.21528 -429.727106)
		(width 0.127)
		(layer "In15.Cu")
		(net "SMB_2_BMC_GPU_BUF_SCL")
	)
	(segment
		(start 57.14746 -426.425106)
		(end 57.14746 -426.044106)
		(width 0.127)
		(layer "In15.Cu")
		(net "SMB_2_BMC_GPU_BUF_SCL")
	)
	(segment
		(start 56.08828 -420.710106)
		(end 56.08828 -420.329106)
		(width 0.127)
		(layer "In15.Cu")
		(net "SMB_2_BMC_GPU_BUF_SCL")
	)
	(segment
		(start 56.21528 -422.107106)
		(end 56.08828 -421.980106)
		(width 0.127)
		(layer "In15.Cu")
		(net "SMB_2_BMC_GPU_BUF_SCL")
	)
	(segment
		(start 56.08828 -419.440106)
		(end 56.08828 -417.706302)
		(width 0.127)
		(layer "In15.Cu")
		(net "SMB_2_BMC_GPU_BUF_SCL")
	)
	(segment
		(start 56.08828 -425.409106)
		(end 56.21528 -425.282106)
		(width 0.127)
		(layer "In15.Cu")
		(net "SMB_2_BMC_GPU_BUF_SCL")
	)
	(segment
		(start 49.34966 -438.173368)
		(end 49.549558 -437.97347)
		(width 0.127)
		(layer "In15.Cu")
		(net "SMB_2_BMC_GPU_BUF_SCL")
	)
	(segment
		(start 57.14746 -429.854106)
		(end 57.02046 -429.727106)
		(width 0.127)
		(layer "In15.Cu")
		(net "SMB_2_BMC_GPU_BUF_SCL")
	)
	(segment
		(start 56.21528 -424.012106)
		(end 57.02046 -424.012106)
		(width 0.127)
		(layer "In15.Cu")
		(net "SMB_2_BMC_GPU_BUF_SCL")
	)
	(segment
		(start 56.21528 -428.457106)
		(end 56.08828 -428.330106)
		(width 0.127)
		(layer "In15.Cu")
		(net "SMB_2_BMC_GPU_BUF_SCL")
	)
	(segment
		(start 57.14746 -421.345106)
		(end 57.14746 -420.964106)
		(width 0.127)
		(layer "In15.Cu")
		(net "SMB_2_BMC_GPU_BUF_SCL")
	)
	(segment
		(start 57.02046 -420.202106)
		(end 57.14746 -420.075106)
		(width 0.127)
		(layer "In15.Cu")
		(net "SMB_2_BMC_GPU_BUF_SCL")
	)
	(segment
		(start 56.08828 -426.679106)
		(end 56.21528 -426.552106)
		(width 0.127)
		(layer "In15.Cu")
		(net "SMB_2_BMC_GPU_BUF_SCL")
	)
	(segment
		(start 57.02046 -419.567106)
		(end 56.21528 -419.567106)
		(width 0.127)
		(layer "In15.Cu")
		(net "SMB_2_BMC_GPU_BUF_SCL")
	)
	(segment
		(start 56.21528 -425.917106)
		(end 56.08828 -425.790106)
		(width 0.127)
		(layer "In15.Cu")
		(net "SMB_2_BMC_GPU_BUF_SCL")
	)
	(segment
		(start 57.02046 -421.472106)
		(end 57.14746 -421.345106)
		(width 0.127)
		(layer "In15.Cu")
		(net "SMB_2_BMC_GPU_BUF_SCL")
	)
	(segment
		(start 60.53328 -416.067748)
		(end 61.39688 -416.931348)
		(width 0.127)
		(layer "In15.Cu")
		(net "SMB_2_BMC_GPU_BUF_SCL")
	)
	(segment
		(start 49.549558 -437.97347)
		(end 54.273958 -437.97347)
		(width 0.127)
		(layer "In15.Cu")
		(net "SMB_2_BMC_GPU_BUF_SCL")
	)
	(segment
		(start 57.02046 -423.377106)
		(end 56.21528 -423.377106)
		(width 0.127)
		(layer "In15.Cu")
		(net "SMB_2_BMC_GPU_BUF_SCL")
	)
	(segment
		(start 56.21528 -427.187106)
		(end 56.08828 -427.060106)
		(width 0.127)
		(layer "In15.Cu")
		(net "SMB_2_BMC_GPU_BUF_SCL")
	)
	(segment
		(start 61.39688 -416.931348)
		(end 61.39688 -418.836602)
		(width 0.127)
		(layer "In15.Cu")
		(net "SMB_2_BMC_GPU_BUF_SCL")
	)
	(segment
		(start 57.14746 -419.694106)
		(end 57.02046 -419.567106)
		(width 0.127)
		(layer "In15.Cu")
		(net "SMB_2_BMC_GPU_BUF_SCL")
	)
	(segment
		(start 56.08828 -424.139106)
		(end 56.21528 -424.012106)
		(width 0.127)
		(layer "In15.Cu")
		(net "SMB_2_BMC_GPU_BUF_SCL")
	)
	(segment
		(start 56.08828 -428.330106)
		(end 56.08828 -427.949106)
		(width 0.127)
		(layer "In15.Cu")
		(net "SMB_2_BMC_GPU_BUF_SCL")
	)
	(segment
		(start 57.02046 -427.187106)
		(end 56.21528 -427.187106)
		(width 0.127)
		(layer "In15.Cu")
		(net "SMB_2_BMC_GPU_BUF_SCL")
	)
	(segment
		(start 57.14746 -423.504106)
		(end 57.02046 -423.377106)
		(width 0.127)
		(layer "In15.Cu")
		(net "SMB_2_BMC_GPU_BUF_SCL")
	)
	(segment
		(start 56.21528 -429.092106)
		(end 57.02046 -429.092106)
		(width 0.127)
		(layer "In15.Cu")
		(net "SMB_2_BMC_GPU_BUF_SCL")
	)
	(segment
		(start 56.08828 -417.706302)
		(end 57.726834 -416.067748)
		(width 0.127)
		(layer "In15.Cu")
		(net "SMB_2_BMC_GPU_BUF_SCL")
	)
	(segment
		(start 56.08828 -436.159148)
		(end 56.08828 -430.489106)
		(width 0.127)
		(layer "In15.Cu")
		(net "SMB_2_BMC_GPU_BUF_SCL")
	)
	(segment
		(start 56.21528 -421.472106)
		(end 57.02046 -421.472106)
		(width 0.127)
		(layer "In15.Cu")
		(net "SMB_2_BMC_GPU_BUF_SCL")
	)
	(segment
		(start 56.21528 -423.377106)
		(end 56.08828 -423.250106)
		(width 0.127)
		(layer "In15.Cu")
		(net "SMB_2_BMC_GPU_BUF_SCL")
	)
	(segment
		(start 61.39688 -418.836602)
		(end 62.650116 -420.089838)
		(width 0.127)
		(layer "In15.Cu")
		(net "SMB_2_BMC_GPU_BUF_SCL")
	)
	(segment
		(start 57.14746 -424.774106)
		(end 57.02046 -424.647106)
		(width 0.127)
		(layer "In15.Cu")
		(net "SMB_2_BMC_GPU_BUF_SCL")
	)
	(segment
		(start 57.02046 -424.012106)
		(end 57.14746 -423.885106)
		(width 0.127)
		(layer "In15.Cu")
		(net "SMB_2_BMC_GPU_BUF_SCL")
	)
	(segment
		(start 57.02046 -426.552106)
		(end 57.14746 -426.425106)
		(width 0.127)
		(layer "In15.Cu")
		(net "SMB_2_BMC_GPU_BUF_SCL")
	)
	(segment
		(start 56.08828 -427.060106)
		(end 56.08828 -426.679106)
		(width 0.127)
		(layer "In15.Cu")
		(net "SMB_2_BMC_GPU_BUF_SCL")
	)
	(segment
		(start 57.02046 -424.647106)
		(end 56.21528 -424.647106)
		(width 0.127)
		(layer "In15.Cu")
		(net "SMB_2_BMC_GPU_BUF_SCL")
	)
	(segment
		(start 57.02046 -430.362106)
		(end 57.14746 -430.235106)
		(width 0.127)
		(layer "In15.Cu")
		(net "SMB_2_BMC_GPU_BUF_SCL")
	)
	(segment
		(start 56.08828 -422.869106)
		(end 56.21528 -422.742106)
		(width 0.127)
		(layer "In15.Cu")
		(net "SMB_2_BMC_GPU_BUF_SCL")
	)
	(segment
		(start 56.21528 -430.362106)
		(end 57.02046 -430.362106)
		(width 0.127)
		(layer "In15.Cu")
		(net "SMB_2_BMC_GPU_BUF_SCL")
	)
	(segment
		(start 57.14746 -420.964106)
		(end 57.02046 -420.837106)
		(width 0.127)
		(layer "In15.Cu")
		(net "SMB_2_BMC_GPU_BUF_SCL")
	)
	(segment
		(start 57.14746 -426.044106)
		(end 57.02046 -425.917106)
		(width 0.127)
		(layer "In15.Cu")
		(net "SMB_2_BMC_GPU_BUF_SCL")
	)
	(segment
		(start 56.08828 -425.790106)
		(end 56.08828 -425.409106)
		(width 0.127)
		(layer "In15.Cu")
		(net "SMB_2_BMC_GPU_BUF_SCL")
	)
	(segment
		(start 57.14746 -430.235106)
		(end 57.14746 -429.854106)
		(width 0.127)
		(layer "In15.Cu")
		(net "SMB_2_BMC_GPU_BUF_SCL")
	)
	(segment
		(start 56.21528 -420.202106)
		(end 57.02046 -420.202106)
		(width 0.127)
		(layer "In15.Cu")
		(net "SMB_2_BMC_GPU_BUF_SCL")
	)
	(segment
		(start 57.02046 -429.092106)
		(end 57.14746 -428.965106)
		(width 0.127)
		(layer "In15.Cu")
		(net "SMB_2_BMC_GPU_BUF_SCL")
	)
	(segment
		(start 57.02046 -428.457106)
		(end 56.21528 -428.457106)
		(width 0.127)
		(layer "In15.Cu")
		(net "SMB_2_BMC_GPU_BUF_SCL")
	)
	(segment
		(start 57.14746 -427.314106)
		(end 57.02046 -427.187106)
		(width 0.127)
		(layer "In15.Cu")
		(net "SMB_2_BMC_GPU_BUF_SCL")
	)
	(segment
		(start 56.08828 -420.329106)
		(end 56.21528 -420.202106)
		(width 0.127)
		(layer "In15.Cu")
		(net "SMB_2_BMC_GPU_BUF_SCL")
	)
	(segment
		(start 56.21528 -427.822106)
		(end 57.02046 -427.822106)
		(width 0.127)
		(layer "In15.Cu")
		(net "SMB_2_BMC_GPU_BUF_SCL")
	)
	(segment
		(start 161.21126 -21.727668)
		(end 161.160968 -21.77796)
		(width 0.12954)
		(layer "F.Cu")
		(net "SMB_1_PLD_3V3AUX_SDA")
	)
	(segment
		(start 161.160968 -23.398226)
		(end 161.160968 -22.361906)
		(width 0.12954)
		(layer "F.Cu")
		(net "SMB_1_PLD_3V3AUX_SDA")
	)
	(segment
		(start 161.163 -21.065998)
		(end 161.21126 -21.114258)
		(width 0.12954)
		(layer "F.Cu")
		(net "SMB_1_PLD_3V3AUX_SDA")
	)
	(segment
		(start 161.21126 -21.114258)
		(end 161.21126 -21.727668)
		(width 0.12954)
		(layer "F.Cu")
		(net "SMB_1_PLD_3V3AUX_SDA")
	)
	(segment
		(start 161.160968 -21.77796)
		(end 161.160968 -22.361906)
		(width 0.12954)
		(layer "F.Cu")
		(net "SMB_1_PLD_3V3AUX_SDA")
	)
	(via
		(at 161.21126 -21.727668)
		(size 0.508)
		(drill 0.254)
		(layers "F.Cu" "B.Cu")
		(net "SMB_1_PLD_3V3AUX_SDA")
	)
	(segment
		(start 162.61588 -21.727668)
		(end 162.61588 -21.918422)
		(width 0.12954)
		(layer "F.Cu")
		(net "SMB_1_PLD_3V3AUX_SCL")
	)
	(segment
		(start 162.61588 -21.502878)
		(end 162.61588 -21.727668)
		(width 0.12954)
		(layer "F.Cu")
		(net "SMB_1_PLD_3V3AUX_SCL")
	)
	(segment
		(start 162.163252 -22.37105)
		(end 162.173412 -22.36089)
		(width 0.12954)
		(layer "F.Cu")
		(net "SMB_1_PLD_3V3AUX_SCL")
	)
	(segment
		(start 162.163252 -23.38959)
		(end 162.163252 -22.37105)
		(width 0.12954)
		(layer "F.Cu")
		(net "SMB_1_PLD_3V3AUX_SCL")
	)
	(segment
		(start 162.61588 -21.918422)
		(end 162.173412 -22.36089)
		(width 0.12954)
		(layer "F.Cu")
		(net "SMB_1_PLD_3V3AUX_SCL")
	)
	(segment
		(start 162.179 -21.065998)
		(end 162.61588 -21.502878)
		(width 0.12954)
		(layer "F.Cu")
		(net "SMB_1_PLD_3V3AUX_SCL")
	)
	(via
		(at 162.61588 -21.727668)
		(size 0.508)
		(drill 0.254)
		(layers "F.Cu" "B.Cu")
		(net "SMB_1_PLD_3V3AUX_SCL")
	)
	(segment
		(start 52.90693 -434.304948)
		(end 52.91328 -434.298598)
		(width 0.12954)
		(layer "F.Cu")
		(net "SMB_1_BMC_GPU_SDA")
	)
	(segment
		(start 52.91328 -434.298598)
		(end 53.87848 -434.298598)
		(width 0.12954)
		(layer "F.Cu")
		(net "SMB_1_BMC_GPU_SDA")
	)
	(segment
		(start 52.90693 -432.653948)
		(end 52.90693 -434.304948)
		(width 0.12954)
		(layer "F.Cu")
		(net "SMB_1_BMC_GPU_SDA")
	)
	(via
		(at 52.90693 -432.653948)
		(size 0.508)
		(drill 0.254)
		(layers "F.Cu" "B.Cu")
		(net "SMB_1_BMC_GPU_SDA")
	)
	(via
		(at 152.70988 -19.522948)
		(size 0.508)
		(drill 0.254)
		(layers "F.Cu" "B.Cu")
		(net "SMB_1_BMC_GPU_SDA")
	)
	(via
		(at 37.01288 -47.361348)
		(size 0.508)
		(drill 0.254)
		(layers "F.Cu" "B.Cu")
		(net "SMB_1_BMC_GPU_SDA")
	)
	(segment
		(start 152.9969 -16.253968)
		(end 152.9969 -14.162278)
		(width 0.12954)
		(layer "B.Cu")
		(net "SMB_1_BMC_GPU_SDA")
	)
	(segment
		(start 152.70988 -19.522948)
		(end 152.12568 -18.938748)
		(width 0.12954)
		(layer "B.Cu")
		(net "SMB_1_BMC_GPU_SDA")
	)
	(segment
		(start 152.12568 -18.938748)
		(end 152.12568 -17.125188)
		(width 0.12954)
		(layer "B.Cu")
		(net "SMB_1_BMC_GPU_SDA")
	)
	(segment
		(start 152.12568 -17.125188)
		(end 152.9969 -16.253968)
		(width 0.12954)
		(layer "B.Cu")
		(net "SMB_1_BMC_GPU_SDA")
	)
	(segment
		(start 16.97355 -330.088748)
		(end 28.14955 -330.088748)
		(width 0.127)
		(layer "In2.Cu")
		(net "SMB_1_BMC_GPU_SDA")
	)
	(segment
		(start 34.79292 -374.934988)
		(end 34.79292 -399.801588)
		(width 0.127)
		(layer "In2.Cu")
		(net "SMB_1_BMC_GPU_SDA")
	)
	(segment
		(start 11.9888 -191.333628)
		(end 10.668 -192.654428)
		(width 0.127)
		(layer "In2.Cu")
		(net "SMB_1_BMC_GPU_SDA")
	)
	(segment
		(start 13.18514 -183.8706)
		(end 11.9888 -185.06694)
		(width 0.127)
		(layer "In2.Cu")
		(net "SMB_1_BMC_GPU_SDA")
	)
	(segment
		(start 26.83002 -114.727228)
		(end 25.17394 -116.383308)
		(width 0.127)
		(layer "In2.Cu")
		(net "SMB_1_BMC_GPU_SDA")
	)
	(segment
		(start 40.017446 -432.653948)
		(end 52.90693 -432.653948)
		(width 0.127)
		(layer "In2.Cu")
		(net "SMB_1_BMC_GPU_SDA")
	)
	(segment
		(start 35.901884 -80.607154)
		(end 27.3939 -89.115138)
		(width 0.127)
		(layer "In2.Cu")
		(net "SMB_1_BMC_GPU_SDA")
	)
	(segment
		(start 26.4414 -100.236528)
		(end 27.2161 -101.011228)
		(width 0.127)
		(layer "In2.Cu")
		(net "SMB_1_BMC_GPU_SDA")
	)
	(segment
		(start 27.2161 -103.779828)
		(end 26.83002 -104.165908)
		(width 0.127)
		(layer "In2.Cu")
		(net "SMB_1_BMC_GPU_SDA")
	)
	(segment
		(start 35.901884 -48.472344)
		(end 35.901884 -80.607154)
		(width 0.127)
		(layer "In2.Cu")
		(net "SMB_1_BMC_GPU_SDA")
	)
	(segment
		(start 16.256 -166.09314)
		(end 16.256 -171.802298)
		(width 0.127)
		(layer "In2.Cu")
		(net "SMB_1_BMC_GPU_SDA")
	)
	(segment
		(start 13.18514 -174.873158)
		(end 13.18514 -183.8706)
		(width 0.127)
		(layer "In2.Cu")
		(net "SMB_1_BMC_GPU_SDA")
	)
	(segment
		(start 37.62248 -430.258982)
		(end 40.017446 -432.653948)
		(width 0.127)
		(layer "In2.Cu")
		(net "SMB_1_BMC_GPU_SDA")
	)
	(segment
		(start 10.62228 -257.520948)
		(end 10.62228 -323.737478)
		(width 0.127)
		(layer "In2.Cu")
		(net "SMB_1_BMC_GPU_SDA")
	)
	(segment
		(start 37.01288 -47.361348)
		(end 35.901884 -48.472344)
		(width 0.127)
		(layer "In2.Cu")
		(net "SMB_1_BMC_GPU_SDA")
	)
	(segment
		(start 27.2161 -101.011228)
		(end 27.2161 -103.779828)
		(width 0.127)
		(layer "In2.Cu")
		(net "SMB_1_BMC_GPU_SDA")
	)
	(segment
		(start 18.47342 -163.87572)
		(end 16.256 -166.09314)
		(width 0.127)
		(layer "In2.Cu")
		(net "SMB_1_BMC_GPU_SDA")
	)
	(segment
		(start 17.22882 -116.383308)
		(end 7.12978 -126.482348)
		(width 0.127)
		(layer "In2.Cu")
		(net "SMB_1_BMC_GPU_SDA")
	)
	(segment
		(start 11.9888 -185.06694)
		(end 11.9888 -191.333628)
		(width 0.127)
		(layer "In2.Cu")
		(net "SMB_1_BMC_GPU_SDA")
	)
	(segment
		(start 27.3939 -97.445068)
		(end 26.4414 -98.397568)
		(width 0.127)
		(layer "In2.Cu")
		(net "SMB_1_BMC_GPU_SDA")
	)
	(segment
		(start 16.256 -171.802298)
		(end 13.18514 -174.873158)
		(width 0.127)
		(layer "In2.Cu")
		(net "SMB_1_BMC_GPU_SDA")
	)
	(segment
		(start 12.37488 -255.768348)
		(end 10.62228 -257.520948)
		(width 0.127)
		(layer "In2.Cu")
		(net "SMB_1_BMC_GPU_SDA")
	)
	(segment
		(start 27.3939 -89.115138)
		(end 27.3939 -97.445068)
		(width 0.127)
		(layer "In2.Cu")
		(net "SMB_1_BMC_GPU_SDA")
	)
	(segment
		(start 34.79292 -399.801588)
		(end 37.62248 -402.631148)
		(width 0.127)
		(layer "In2.Cu")
		(net "SMB_1_BMC_GPU_SDA")
	)
	(segment
		(start 37.62248 -402.631148)
		(end 37.62248 -430.258982)
		(width 0.127)
		(layer "In2.Cu")
		(net "SMB_1_BMC_GPU_SDA")
	)
	(segment
		(start 10.668 -192.654428)
		(end 10.668 -251.343668)
		(width 0.127)
		(layer "In2.Cu")
		(net "SMB_1_BMC_GPU_SDA")
	)
	(segment
		(start 7.12978 -126.482348)
		(end 7.12978 -135.492236)
		(width 0.127)
		(layer "In2.Cu")
		(net "SMB_1_BMC_GPU_SDA")
	)
	(segment
		(start 26.4414 -98.397568)
		(end 26.4414 -100.236528)
		(width 0.127)
		(layer "In2.Cu")
		(net "SMB_1_BMC_GPU_SDA")
	)
	(segment
		(start 7.12978 -135.492236)
		(end 18.47342 -146.835876)
		(width 0.127)
		(layer "In2.Cu")
		(net "SMB_1_BMC_GPU_SDA")
	)
	(segment
		(start 10.62228 -323.737478)
		(end 16.97355 -330.088748)
		(width 0.127)
		(layer "In2.Cu")
		(net "SMB_1_BMC_GPU_SDA")
	)
	(segment
		(start 28.96108 -369.103148)
		(end 34.79292 -374.934988)
		(width 0.127)
		(layer "In2.Cu")
		(net "SMB_1_BMC_GPU_SDA")
	)
	(segment
		(start 12.37488 -253.050548)
		(end 12.37488 -255.768348)
		(width 0.127)
		(layer "In2.Cu")
		(net "SMB_1_BMC_GPU_SDA")
	)
	(segment
		(start 18.47342 -146.835876)
		(end 18.47342 -163.87572)
		(width 0.127)
		(layer "In2.Cu")
		(net "SMB_1_BMC_GPU_SDA")
	)
	(segment
		(start 26.83002 -104.165908)
		(end 26.83002 -114.727228)
		(width 0.127)
		(layer "In2.Cu")
		(net "SMB_1_BMC_GPU_SDA")
	)
	(segment
		(start 10.668 -251.343668)
		(end 12.37488 -253.050548)
		(width 0.127)
		(layer "In2.Cu")
		(net "SMB_1_BMC_GPU_SDA")
	)
	(segment
		(start 28.96108 -330.900278)
		(end 28.96108 -369.103148)
		(width 0.127)
		(layer "In2.Cu")
		(net "SMB_1_BMC_GPU_SDA")
	)
	(segment
		(start 25.17394 -116.383308)
		(end 17.22882 -116.383308)
		(width 0.127)
		(layer "In2.Cu")
		(net "SMB_1_BMC_GPU_SDA")
	)
	(segment
		(start 28.14955 -330.088748)
		(end 28.96108 -330.900278)
		(width 0.127)
		(layer "In2.Cu")
		(net "SMB_1_BMC_GPU_SDA")
	)
	(segment
		(start 122.20067 -32.121348)
		(end 115.97767 -25.898348)
		(width 0.127)
		(layer "In6.Cu")
		(net "SMB_1_BMC_GPU_SDA")
	)
	(segment
		(start 45.52188 -47.361348)
		(end 37.01288 -47.361348)
		(width 0.127)
		(layer "In6.Cu")
		(net "SMB_1_BMC_GPU_SDA")
	)
	(segment
		(start 148.452332 -24.942038)
		(end 148.452332 -25.121362)
		(width 0.127)
		(layer "In6.Cu")
		(net "SMB_1_BMC_GPU_SDA")
	)
	(segment
		(start 101.17328 -30.182566)
		(end 101.17328 -33.014158)
		(width 0.127)
		(layer "In6.Cu")
		(net "SMB_1_BMC_GPU_SDA")
	)
	(segment
		(start 65.13068 -39.360348)
		(end 63.0428 -39.360348)
		(width 0.127)
		(layer "In6.Cu")
		(net "SMB_1_BMC_GPU_SDA")
	)
	(segment
		(start 62.7126 -39.030148)
		(end 53.85308 -39.030148)
		(width 0.127)
		(layer "In6.Cu")
		(net "SMB_1_BMC_GPU_SDA")
	)
	(segment
		(start 132.54609 -32.121348)
		(end 122.20067 -32.121348)
		(width 0.127)
		(layer "In6.Cu")
		(net "SMB_1_BMC_GPU_SDA")
	)
	(segment
		(start 146.185382 -27.208988)
		(end 137.45845 -27.208988)
		(width 0.127)
		(layer "In6.Cu")
		(net "SMB_1_BMC_GPU_SDA")
	)
	(segment
		(start 65.56248 -38.928548)
		(end 65.13068 -39.360348)
		(width 0.127)
		(layer "In6.Cu")
		(net "SMB_1_BMC_GPU_SDA")
	)
	(segment
		(start 69.7738 -40.401748)
		(end 68.3006 -38.928548)
		(width 0.127)
		(layer "In6.Cu")
		(net "SMB_1_BMC_GPU_SDA")
	)
	(segment
		(start 152.70988 -20.68449)
		(end 148.452332 -24.942038)
		(width 0.127)
		(layer "In6.Cu")
		(net "SMB_1_BMC_GPU_SDA")
	)
	(segment
		(start 148.740876 -25.409906)
		(end 148.740876 -25.588976)
		(width 0.127)
		(layer "In6.Cu")
		(net "SMB_1_BMC_GPU_SDA")
	)
	(segment
		(start 111.46409 -25.898348)
		(end 110.90529 -26.457148)
		(width 0.127)
		(layer "In6.Cu")
		(net "SMB_1_BMC_GPU_SDA")
	)
	(segment
		(start 93.56598 -35.202368)
		(end 89.8398 -38.928548)
		(width 0.127)
		(layer "In6.Cu")
		(net "SMB_1_BMC_GPU_SDA")
	)
	(segment
		(start 110.90529 -26.457148)
		(end 104.898698 -26.457148)
		(width 0.127)
		(layer "In6.Cu")
		(net "SMB_1_BMC_GPU_SDA")
	)
	(segment
		(start 148.003514 -25.570434)
		(end 147.823936 -25.570434)
		(width 0.127)
		(layer "In6.Cu")
		(net "SMB_1_BMC_GPU_SDA")
	)
	(segment
		(start 98.98507 -35.202368)
		(end 93.56598 -35.202368)
		(width 0.127)
		(layer "In6.Cu")
		(net "SMB_1_BMC_GPU_SDA")
	)
	(segment
		(start 152.70988 -19.522948)
		(end 152.70988 -20.68449)
		(width 0.127)
		(layer "In6.Cu")
		(net "SMB_1_BMC_GPU_SDA")
	)
	(segment
		(start 104.898698 -26.457148)
		(end 101.17328 -30.182566)
		(width 0.127)
		(layer "In6.Cu")
		(net "SMB_1_BMC_GPU_SDA")
	)
	(segment
		(start 147.823936 -25.570434)
		(end 146.185382 -27.208988)
		(width 0.127)
		(layer "In6.Cu")
		(net "SMB_1_BMC_GPU_SDA")
	)
	(segment
		(start 137.45845 -27.208988)
		(end 132.54609 -32.121348)
		(width 0.127)
		(layer "In6.Cu")
		(net "SMB_1_BMC_GPU_SDA")
	)
	(segment
		(start 53.85308 -39.030148)
		(end 45.52188 -47.361348)
		(width 0.127)
		(layer "In6.Cu")
		(net "SMB_1_BMC_GPU_SDA")
	)
	(segment
		(start 148.471128 -25.858724)
		(end 148.291804 -25.858724)
		(width 0.127)
		(layer "In6.Cu")
		(net "SMB_1_BMC_GPU_SDA")
	)
	(segment
		(start 63.0428 -39.360348)
		(end 62.7126 -39.030148)
		(width 0.127)
		(layer "In6.Cu")
		(net "SMB_1_BMC_GPU_SDA")
	)
	(segment
		(start 148.740876 -25.588976)
		(end 148.471128 -25.858724)
		(width 0.127)
		(layer "In6.Cu")
		(net "SMB_1_BMC_GPU_SDA")
	)
	(segment
		(start 101.17328 -33.014158)
		(end 98.98507 -35.202368)
		(width 0.127)
		(layer "In6.Cu")
		(net "SMB_1_BMC_GPU_SDA")
	)
	(segment
		(start 115.97767 -25.898348)
		(end 111.46409 -25.898348)
		(width 0.127)
		(layer "In6.Cu")
		(net "SMB_1_BMC_GPU_SDA")
	)
	(segment
		(start 68.3006 -38.928548)
		(end 65.56248 -38.928548)
		(width 0.127)
		(layer "In6.Cu")
		(net "SMB_1_BMC_GPU_SDA")
	)
	(segment
		(start 148.291804 -25.858724)
		(end 148.003514 -25.570434)
		(width 0.127)
		(layer "In6.Cu")
		(net "SMB_1_BMC_GPU_SDA")
	)
	(segment
		(start 148.452332 -25.121362)
		(end 148.740876 -25.409906)
		(width 0.127)
		(layer "In6.Cu")
		(net "SMB_1_BMC_GPU_SDA")
	)
	(segment
		(start 89.8398 -38.928548)
		(end 75.9714 -38.928548)
		(width 0.127)
		(layer "In6.Cu")
		(net "SMB_1_BMC_GPU_SDA")
	)
	(segment
		(start 75.9714 -38.928548)
		(end 74.4982 -40.401748)
		(width 0.127)
		(layer "In6.Cu")
		(net "SMB_1_BMC_GPU_SDA")
	)
	(segment
		(start 74.4982 -40.401748)
		(end 69.7738 -40.401748)
		(width 0.127)
		(layer "In6.Cu")
		(net "SMB_1_BMC_GPU_SDA")
	)
	(segment
		(start 37.62883 -433.923948)
		(end 36.54933 -433.923948)
		(width 0.12954)
		(layer "F.Cu")
		(net "SMB_1_BMC_GPU_SCL")
	)
	(segment
		(start 37.62883 -432.272948)
		(end 37.62883 -433.923948)
		(width 0.12954)
		(layer "F.Cu")
		(net "SMB_1_BMC_GPU_SCL")
	)
	(via
		(at 152.70988 -18.760948)
		(size 0.508)
		(drill 0.254)
		(layers "F.Cu" "B.Cu")
		(net "SMB_1_BMC_GPU_SCL")
	)
	(via
		(at 37.62883 -432.272948)
		(size 0.508)
		(drill 0.254)
		(layers "F.Cu" "B.Cu")
		(net "SMB_1_BMC_GPU_SCL")
	)
	(via
		(at 36.44138 -46.739048)
		(size 0.508)
		(drill 0.254)
		(layers "F.Cu" "B.Cu")
		(net "SMB_1_BMC_GPU_SCL")
	)
	(segment
		(start 154.339798 -15.068804)
		(end 154.13736 -15.068804)
		(width 0.12954)
		(layer "B.Cu")
		(net "SMB_1_BMC_GPU_SCL")
	)
	(segment
		(start 154.13736 -15.706344)
		(end 154.339798 -15.706344)
		(width 0.12954)
		(layer "B.Cu")
		(net "SMB_1_BMC_GPU_SCL")
	)
	(segment
		(start 154.339798 -15.706344)
		(end 154.469338 -15.576804)
		(width 0.12954)
		(layer "B.Cu")
		(net "SMB_1_BMC_GPU_SCL")
	)
	(segment
		(start 154.13736 -15.068804)
		(end 154.00782 -14.939264)
		(width 0.12954)
		(layer "B.Cu")
		(net "SMB_1_BMC_GPU_SCL")
	)
	(segment
		(start 154.00782 -17.793208)
		(end 154.00782 -15.835884)
		(width 0.12954)
		(layer "B.Cu")
		(net "SMB_1_BMC_GPU_SCL")
	)
	(segment
		(start 154.00782 -14.939264)
		(end 154.00782 -14.162278)
		(width 0.12954)
		(layer "B.Cu")
		(net "SMB_1_BMC_GPU_SCL")
	)
	(segment
		(start 154.469338 -15.198344)
		(end 154.339798 -15.068804)
		(width 0.12954)
		(layer "B.Cu")
		(net "SMB_1_BMC_GPU_SCL")
	)
	(segment
		(start 153.04008 -18.760948)
		(end 154.00782 -17.793208)
		(width 0.12954)
		(layer "B.Cu")
		(net "SMB_1_BMC_GPU_SCL")
	)
	(segment
		(start 152.70988 -18.760948)
		(end 153.04008 -18.760948)
		(width 0.12954)
		(layer "B.Cu")
		(net "SMB_1_BMC_GPU_SCL")
	)
	(segment
		(start 154.469338 -15.576804)
		(end 154.469338 -15.198344)
		(width 0.12954)
		(layer "B.Cu")
		(net "SMB_1_BMC_GPU_SCL")
	)
	(segment
		(start 154.00782 -15.835884)
		(end 154.13736 -15.706344)
		(width 0.12954)
		(layer "B.Cu")
		(net "SMB_1_BMC_GPU_SCL")
	)
	(segment
		(start 24.98852 -113.459514)
		(end 24.86152 -113.332514)
		(width 0.127)
		(layer "In2.Cu")
		(net "SMB_1_BMC_GPU_SCL")
	)
	(segment
		(start 10.19048 -323.916548)
		(end 10.19048 -257.165348)
		(width 0.127)
		(layer "In2.Cu")
		(net "SMB_1_BMC_GPU_SCL")
	)
	(segment
		(start 25.918668 -105.386632)
		(end 24.98852 -105.386632)
		(width 0.127)
		(layer "In2.Cu")
		(net "SMB_1_BMC_GPU_SCL")
	)
	(segment
		(start 26.045668 -104.624632)
		(end 26.045668 -104.243632)
		(width 0.127)
		(layer "In2.Cu")
		(net "SMB_1_BMC_GPU_SCL")
	)
	(segment
		(start 11.291824 -253.143258)
		(end 10.790936 -253.143258)
		(width 0.127)
		(layer "In2.Cu")
		(net "SMB_1_BMC_GPU_SCL")
	)
	(segment
		(start 24.98852 -112.189514)
		(end 24.86152 -112.062514)
		(width 0.127)
		(layer "In2.Cu")
		(net "SMB_1_BMC_GPU_SCL")
	)
	(segment
		(start 24.86152 -114.831368)
		(end 24.86152 -114.221514)
		(width 0.127)
		(layer "In2.Cu")
		(net "SMB_1_BMC_GPU_SCL")
	)
	(segment
		(start 25.97658 -112.316514)
		(end 25.84958 -112.189514)
		(width 0.127)
		(layer "In2.Cu")
		(net "SMB_1_BMC_GPU_SCL")
	)
	(segment
		(start 24.86152 -111.681514)
		(end 24.98852 -111.554514)
		(width 0.127)
		(layer "In2.Cu")
		(net "SMB_1_BMC_GPU_SCL")
	)
	(segment
		(start 24.98852 -107.291632)
		(end 25.918668 -107.291632)
		(width 0.127)
		(layer "In2.Cu")
		(net "SMB_1_BMC_GPU_SCL")
	)
	(segment
		(start 6.69798 -126.162308)
		(end 17.04594 -115.814348)
		(width 0.127)
		(layer "In2.Cu")
		(net "SMB_1_BMC_GPU_SCL")
	)
	(segment
		(start 24.98852 -102.846632)
		(end 24.86152 -102.719632)
		(width 0.127)
		(layer "In2.Cu")
		(net "SMB_1_BMC_GPU_SCL")
	)
	(segment
		(start 28.52928 -331.079348)
		(end 27.99588 -330.545948)
		(width 0.127)
		(layer "In2.Cu")
		(net "SMB_1_BMC_GPU_SCL")
	)
	(segment
		(start 24.86152 -103.989632)
		(end 24.86152 -103.608632)
		(width 0.127)
		(layer "In2.Cu")
		(net "SMB_1_BMC_GPU_SCL")
	)
	(segment
		(start 26.045668 -107.164632)
		(end 26.045668 -106.783632)
		(width 0.127)
		(layer "In2.Cu")
		(net "SMB_1_BMC_GPU_SCL")
	)
	(segment
		(start 27.99588 -330.545948)
		(end 16.81988 -330.545948)
		(width 0.127)
		(layer "In2.Cu")
		(net "SMB_1_BMC_GPU_SCL")
	)
	(segment
		(start 15.8242 -171.623228)
		(end 15.8242 -165.91407)
		(width 0.127)
		(layer "In2.Cu")
		(net "SMB_1_BMC_GPU_SCL")
	)
	(segment
		(start 24.98852 -114.094514)
		(end 25.84958 -114.094514)
		(width 0.127)
		(layer "In2.Cu")
		(net "SMB_1_BMC_GPU_SCL")
	)
	(segment
		(start 7.95528 -186.83986)
		(end 12.75334 -182.0418)
		(width 0.127)
		(layer "In2.Cu")
		(net "SMB_1_BMC_GPU_SCL")
	)
	(segment
		(start 26.045668 -103.354632)
		(end 26.045668 -102.973632)
		(width 0.127)
		(layer "In2.Cu")
		(net "SMB_1_BMC_GPU_SCL")
	)
	(segment
		(start 37.19068 -431.834798)
		(end 37.19068 -402.810218)
		(width 0.127)
		(layer "In2.Cu")
		(net "SMB_1_BMC_GPU_SCL")
	)
	(segment
		(start 24.86152 -102.719632)
		(end 24.86152 -102.085648)
		(width 0.127)
		(layer "In2.Cu")
		(net "SMB_1_BMC_GPU_SCL")
	)
	(segment
		(start 24.86152 -105.259632)
		(end 24.86152 -104.878632)
		(width 0.127)
		(layer "In2.Cu")
		(net "SMB_1_BMC_GPU_SCL")
	)
	(segment
		(start 24.98852 -106.021632)
		(end 25.918668 -106.021632)
		(width 0.127)
		(layer "In2.Cu")
		(net "SMB_1_BMC_GPU_SCL")
	)
	(segment
		(start 24.98852 -111.554514)
		(end 25.84958 -111.554514)
		(width 0.127)
		(layer "In2.Cu")
		(net "SMB_1_BMC_GPU_SCL")
	)
	(segment
		(start 26.91892 -88.979248)
		(end 35.46348 -80.434688)
		(width 0.127)
		(layer "In2.Cu")
		(net "SMB_1_BMC_GPU_SCL")
	)
	(segment
		(start 24.98852 -104.116632)
		(end 24.86152 -103.989632)
		(width 0.127)
		(layer "In2.Cu")
		(net "SMB_1_BMC_GPU_SCL")
	)
	(segment
		(start 25.97658 -112.697514)
		(end 25.97658 -112.316514)
		(width 0.127)
		(layer "In2.Cu")
		(net "SMB_1_BMC_GPU_SCL")
	)
	(segment
		(start 12.75334 -174.694088)
		(end 15.8242 -171.623228)
		(width 0.127)
		(layer "In2.Cu")
		(net "SMB_1_BMC_GPU_SCL")
	)
	(segment
		(start 24.86152 -114.221514)
		(end 24.98852 -114.094514)
		(width 0.127)
		(layer "In2.Cu")
		(net "SMB_1_BMC_GPU_SCL")
	)
	(segment
		(start 25.918668 -106.656632)
		(end 24.98852 -106.656632)
		(width 0.127)
		(layer "In2.Cu")
		(net "SMB_1_BMC_GPU_SCL")
	)
	(segment
		(start 25.918668 -104.751632)
		(end 26.045668 -104.624632)
		(width 0.127)
		(layer "In2.Cu")
		(net "SMB_1_BMC_GPU_SCL")
	)
	(segment
		(start 26.045668 -106.783632)
		(end 25.918668 -106.656632)
		(width 0.127)
		(layer "In2.Cu")
		(net "SMB_1_BMC_GPU_SCL")
	)
	(segment
		(start 10.19048 -257.165348)
		(end 11.86688 -255.488948)
		(width 0.127)
		(layer "In2.Cu")
		(net "SMB_1_BMC_GPU_SCL")
	)
	(segment
		(start 24.86152 -104.878632)
		(end 24.98852 -104.751632)
		(width 0.127)
		(layer "In2.Cu")
		(net "SMB_1_BMC_GPU_SCL")
	)
	(segment
		(start 24.86152 -106.529632)
		(end 24.86152 -106.148632)
		(width 0.127)
		(layer "In2.Cu")
		(net "SMB_1_BMC_GPU_SCL")
	)
	(segment
		(start 24.86152 -110.792514)
		(end 24.86152 -107.418632)
		(width 0.127)
		(layer "In2.Cu")
		(net "SMB_1_BMC_GPU_SCL")
	)
	(segment
		(start 16.81988 -330.545948)
		(end 10.19048 -323.916548)
		(width 0.127)
		(layer "In2.Cu")
		(net "SMB_1_BMC_GPU_SCL")
	)
	(segment
		(start 35.46348 -47.716948)
		(end 36.44138 -46.739048)
		(width 0.127)
		(layer "In2.Cu")
		(net "SMB_1_BMC_GPU_SCL")
	)
	(segment
		(start 24.86152 -102.085648)
		(end 25.92324 -101.023928)
		(width 0.127)
		(layer "In2.Cu")
		(net "SMB_1_BMC_GPU_SCL")
	)
	(segment
		(start 24.98852 -104.751632)
		(end 25.918668 -104.751632)
		(width 0.127)
		(layer "In2.Cu")
		(net "SMB_1_BMC_GPU_SCL")
	)
	(segment
		(start 24.98852 -106.656632)
		(end 24.86152 -106.529632)
		(width 0.127)
		(layer "In2.Cu")
		(net "SMB_1_BMC_GPU_SCL")
	)
	(segment
		(start 26.045668 -102.973632)
		(end 25.918668 -102.846632)
		(width 0.127)
		(layer "In2.Cu")
		(net "SMB_1_BMC_GPU_SCL")
	)
	(segment
		(start 12.75334 -182.0418)
		(end 12.75334 -174.694088)
		(width 0.127)
		(layer "In2.Cu")
		(net "SMB_1_BMC_GPU_SCL")
	)
	(segment
		(start 24.98852 -112.824514)
		(end 25.84958 -112.824514)
		(width 0.127)
		(layer "In2.Cu")
		(net "SMB_1_BMC_GPU_SCL")
	)
	(segment
		(start 25.97658 -111.427514)
		(end 25.97658 -111.046514)
		(width 0.127)
		(layer "In2.Cu")
		(net "SMB_1_BMC_GPU_SCL")
	)
	(segment
		(start 24.86152 -112.951514)
		(end 24.98852 -112.824514)
		(width 0.127)
		(layer "In2.Cu")
		(net "SMB_1_BMC_GPU_SCL")
	)
	(segment
		(start 26.045668 -105.894632)
		(end 26.045668 -105.513632)
		(width 0.127)
		(layer "In2.Cu")
		(net "SMB_1_BMC_GPU_SCL")
	)
	(segment
		(start 25.918668 -103.481632)
		(end 26.045668 -103.354632)
		(width 0.127)
		(layer "In2.Cu")
		(net "SMB_1_BMC_GPU_SCL")
	)
	(segment
		(start 37.62883 -432.272948)
		(end 37.19068 -431.834798)
		(width 0.127)
		(layer "In2.Cu")
		(net "SMB_1_BMC_GPU_SCL")
	)
	(segment
		(start 23.87854 -115.814348)
		(end 24.86152 -114.831368)
		(width 0.127)
		(layer "In2.Cu")
		(net "SMB_1_BMC_GPU_SCL")
	)
	(segment
		(start 25.84958 -113.459514)
		(end 24.98852 -113.459514)
		(width 0.127)
		(layer "In2.Cu")
		(net "SMB_1_BMC_GPU_SCL")
	)
	(segment
		(start 11.86688 -255.488948)
		(end 11.86688 -253.718314)
		(width 0.127)
		(layer "In2.Cu")
		(net "SMB_1_BMC_GPU_SCL")
	)
	(segment
		(start 10.790936 -253.143258)
		(end 10.22858 -252.580902)
		(width 0.127)
		(layer "In2.Cu")
		(net "SMB_1_BMC_GPU_SCL")
	)
	(segment
		(start 10.22858 -192.408302)
		(end 7.95528 -190.135002)
		(width 0.127)
		(layer "In2.Cu")
		(net "SMB_1_BMC_GPU_SCL")
	)
	(segment
		(start 28.52928 -369.282218)
		(end 28.52928 -331.079348)
		(width 0.127)
		(layer "In2.Cu")
		(net "SMB_1_BMC_GPU_SCL")
	)
	(segment
		(start 17.04594 -115.814348)
		(end 23.87854 -115.814348)
		(width 0.127)
		(layer "In2.Cu")
		(net "SMB_1_BMC_GPU_SCL")
	)
	(segment
		(start 24.86152 -106.148632)
		(end 24.98852 -106.021632)
		(width 0.127)
		(layer "In2.Cu")
		(net "SMB_1_BMC_GPU_SCL")
	)
	(segment
		(start 10.22858 -252.580902)
		(end 10.22858 -192.408302)
		(width 0.127)
		(layer "In2.Cu")
		(net "SMB_1_BMC_GPU_SCL")
	)
	(segment
		(start 15.8242 -165.91407)
		(end 18.04162 -163.69665)
		(width 0.127)
		(layer "In2.Cu")
		(net "SMB_1_BMC_GPU_SCL")
	)
	(segment
		(start 24.98852 -110.919514)
		(end 24.86152 -110.792514)
		(width 0.127)
		(layer "In2.Cu")
		(net "SMB_1_BMC_GPU_SCL")
	)
	(segment
		(start 6.69798 -135.671306)
		(end 6.69798 -126.162308)
		(width 0.127)
		(layer "In2.Cu")
		(net "SMB_1_BMC_GPU_SCL")
	)
	(segment
		(start 24.86152 -107.418632)
		(end 24.98852 -107.291632)
		(width 0.127)
		(layer "In2.Cu")
		(net "SMB_1_BMC_GPU_SCL")
	)
	(segment
		(start 25.97658 -111.046514)
		(end 25.84958 -110.919514)
		(width 0.127)
		(layer "In2.Cu")
		(net "SMB_1_BMC_GPU_SCL")
	)
	(segment
		(start 24.98852 -105.386632)
		(end 24.86152 -105.259632)
		(width 0.127)
		(layer "In2.Cu")
		(net "SMB_1_BMC_GPU_SCL")
	)
	(segment
		(start 25.92324 -98.140774)
		(end 26.91892 -97.145094)
		(width 0.127)
		(layer "In2.Cu")
		(net "SMB_1_BMC_GPU_SCL")
	)
	(segment
		(start 25.97658 -113.586514)
		(end 25.84958 -113.459514)
		(width 0.127)
		(layer "In2.Cu")
		(net "SMB_1_BMC_GPU_SCL")
	)
	(segment
		(start 18.04162 -147.014946)
		(end 6.69798 -135.671306)
		(width 0.127)
		(layer "In2.Cu")
		(net "SMB_1_BMC_GPU_SCL")
	)
	(segment
		(start 26.91892 -97.145094)
		(end 26.91892 -88.979248)
		(width 0.127)
		(layer "In2.Cu")
		(net "SMB_1_BMC_GPU_SCL")
	)
	(segment
		(start 24.98852 -103.481632)
		(end 25.918668 -103.481632)
		(width 0.127)
		(layer "In2.Cu")
		(net "SMB_1_BMC_GPU_SCL")
	)
	(segment
		(start 7.95528 -190.135002)
		(end 7.95528 -186.83986)
		(width 0.127)
		(layer "In2.Cu")
		(net "SMB_1_BMC_GPU_SCL")
	)
	(segment
		(start 25.918668 -106.021632)
		(end 26.045668 -105.894632)
		(width 0.127)
		(layer "In2.Cu")
		(net "SMB_1_BMC_GPU_SCL")
	)
	(segment
		(start 25.92324 -101.023928)
		(end 25.92324 -98.140774)
		(width 0.127)
		(layer "In2.Cu")
		(net "SMB_1_BMC_GPU_SCL")
	)
	(segment
		(start 25.84958 -114.094514)
		(end 25.97658 -113.967514)
		(width 0.127)
		(layer "In2.Cu")
		(net "SMB_1_BMC_GPU_SCL")
	)
	(segment
		(start 24.86152 -103.608632)
		(end 24.98852 -103.481632)
		(width 0.127)
		(layer "In2.Cu")
		(net "SMB_1_BMC_GPU_SCL")
	)
	(segment
		(start 24.86152 -112.062514)
		(end 24.86152 -111.681514)
		(width 0.127)
		(layer "In2.Cu")
		(net "SMB_1_BMC_GPU_SCL")
	)
	(segment
		(start 11.86688 -253.718314)
		(end 11.291824 -253.143258)
		(width 0.127)
		(layer "In2.Cu")
		(net "SMB_1_BMC_GPU_SCL")
	)
	(segment
		(start 26.045668 -105.513632)
		(end 25.918668 -105.386632)
		(width 0.127)
		(layer "In2.Cu")
		(net "SMB_1_BMC_GPU_SCL")
	)
	(segment
		(start 34.36112 -399.980658)
		(end 34.36112 -375.114058)
		(width 0.127)
		(layer "In2.Cu")
		(net "SMB_1_BMC_GPU_SCL")
	)
	(segment
		(start 25.918668 -104.116632)
		(end 24.98852 -104.116632)
		(width 0.127)
		(layer "In2.Cu")
		(net "SMB_1_BMC_GPU_SCL")
	)
	(segment
		(start 24.86152 -113.332514)
		(end 24.86152 -112.951514)
		(width 0.127)
		(layer "In2.Cu")
		(net "SMB_1_BMC_GPU_SCL")
	)
	(segment
		(start 37.19068 -402.810218)
		(end 34.36112 -399.980658)
		(width 0.127)
		(layer "In2.Cu")
		(net "SMB_1_BMC_GPU_SCL")
	)
	(segment
		(start 25.97658 -113.967514)
		(end 25.97658 -113.586514)
		(width 0.127)
		(layer "In2.Cu")
		(net "SMB_1_BMC_GPU_SCL")
	)
	(segment
		(start 26.045668 -104.243632)
		(end 25.918668 -104.116632)
		(width 0.127)
		(layer "In2.Cu")
		(net "SMB_1_BMC_GPU_SCL")
	)
	(segment
		(start 25.84958 -112.824514)
		(end 25.97658 -112.697514)
		(width 0.127)
		(layer "In2.Cu")
		(net "SMB_1_BMC_GPU_SCL")
	)
	(segment
		(start 34.36112 -375.114058)
		(end 28.52928 -369.282218)
		(width 0.127)
		(layer "In2.Cu")
		(net "SMB_1_BMC_GPU_SCL")
	)
	(segment
		(start 25.918668 -107.291632)
		(end 26.045668 -107.164632)
		(width 0.127)
		(layer "In2.Cu")
		(net "SMB_1_BMC_GPU_SCL")
	)
	(segment
		(start 18.04162 -163.69665)
		(end 18.04162 -147.014946)
		(width 0.127)
		(layer "In2.Cu")
		(net "SMB_1_BMC_GPU_SCL")
	)
	(segment
		(start 25.84958 -111.554514)
		(end 25.97658 -111.427514)
		(width 0.127)
		(layer "In2.Cu")
		(net "SMB_1_BMC_GPU_SCL")
	)
	(segment
		(start 25.918668 -102.846632)
		(end 24.98852 -102.846632)
		(width 0.127)
		(layer "In2.Cu")
		(net "SMB_1_BMC_GPU_SCL")
	)
	(segment
		(start 25.84958 -110.919514)
		(end 24.98852 -110.919514)
		(width 0.127)
		(layer "In2.Cu")
		(net "SMB_1_BMC_GPU_SCL")
	)
	(segment
		(start 25.84958 -112.189514)
		(end 24.98852 -112.189514)
		(width 0.127)
		(layer "In2.Cu")
		(net "SMB_1_BMC_GPU_SCL")
	)
	(segment
		(start 35.46348 -80.434688)
		(end 35.46348 -47.716948)
		(width 0.127)
		(layer "In2.Cu")
		(net "SMB_1_BMC_GPU_SCL")
	)
	(segment
		(start 54.18963 -38.064948)
		(end 45.51553 -46.739048)
		(width 0.127)
		(layer "In6.Cu")
		(net "SMB_1_BMC_GPU_SCL")
	)
	(segment
		(start 45.51553 -46.739048)
		(end 36.44138 -46.739048)
		(width 0.127)
		(layer "In6.Cu")
		(net "SMB_1_BMC_GPU_SCL")
	)
	(segment
		(start 152.1714 -20.6121)
		(end 146.031712 -26.751788)
		(width 0.127)
		(layer "In6.Cu")
		(net "SMB_1_BMC_GPU_SCL")
	)
	(segment
		(start 146.031712 -26.751788)
		(end 137.30478 -26.751788)
		(width 0.127)
		(layer "In6.Cu")
		(net "SMB_1_BMC_GPU_SCL")
	)
	(segment
		(start 100.74148 -32.835088)
		(end 98.806 -34.770568)
		(width 0.127)
		(layer "In6.Cu")
		(net "SMB_1_BMC_GPU_SCL")
	)
	(segment
		(start 74.422 -38.496748)
		(end 73.6346 -39.284148)
		(width 0.127)
		(layer "In6.Cu")
		(net "SMB_1_BMC_GPU_SCL")
	)
	(segment
		(start 152.1714 -19.299428)
		(end 152.1714 -20.6121)
		(width 0.127)
		(layer "In6.Cu")
		(net "SMB_1_BMC_GPU_SCL")
	)
	(segment
		(start 111.28502 -25.466548)
		(end 110.72622 -26.025348)
		(width 0.127)
		(layer "In6.Cu")
		(net "SMB_1_BMC_GPU_SCL")
	)
	(segment
		(start 80.24241 -37.201348)
		(end 78.94701 -38.496748)
		(width 0.127)
		(layer "In6.Cu")
		(net "SMB_1_BMC_GPU_SCL")
	)
	(segment
		(start 65.71488 -38.064948)
		(end 54.18963 -38.064948)
		(width 0.127)
		(layer "In6.Cu")
		(net "SMB_1_BMC_GPU_SCL")
	)
	(segment
		(start 73.6346 -39.284148)
		(end 69.626734 -39.284148)
		(width 0.127)
		(layer "In6.Cu")
		(net "SMB_1_BMC_GPU_SCL")
	)
	(segment
		(start 90.932 -37.201348)
		(end 80.24241 -37.201348)
		(width 0.127)
		(layer "In6.Cu")
		(net "SMB_1_BMC_GPU_SCL")
	)
	(segment
		(start 68.229734 -37.887148)
		(end 65.89268 -37.887148)
		(width 0.127)
		(layer "In6.Cu")
		(net "SMB_1_BMC_GPU_SCL")
	)
	(segment
		(start 110.72622 -26.025348)
		(end 104.719628 -26.025348)
		(width 0.127)
		(layer "In6.Cu")
		(net "SMB_1_BMC_GPU_SCL")
	)
	(segment
		(start 116.15674 -25.466548)
		(end 111.28502 -25.466548)
		(width 0.127)
		(layer "In6.Cu")
		(net "SMB_1_BMC_GPU_SCL")
	)
	(segment
		(start 104.719628 -26.025348)
		(end 100.74148 -30.003496)
		(width 0.127)
		(layer "In6.Cu")
		(net "SMB_1_BMC_GPU_SCL")
	)
	(segment
		(start 137.30478 -26.751788)
		(end 132.36702 -31.689548)
		(width 0.127)
		(layer "In6.Cu")
		(net "SMB_1_BMC_GPU_SCL")
	)
	(segment
		(start 93.36278 -34.770568)
		(end 90.932 -37.201348)
		(width 0.127)
		(layer "In6.Cu")
		(net "SMB_1_BMC_GPU_SCL")
	)
	(segment
		(start 122.37974 -31.689548)
		(end 116.15674 -25.466548)
		(width 0.127)
		(layer "In6.Cu")
		(net "SMB_1_BMC_GPU_SCL")
	)
	(segment
		(start 69.626734 -39.284148)
		(end 68.229734 -37.887148)
		(width 0.127)
		(layer "In6.Cu")
		(net "SMB_1_BMC_GPU_SCL")
	)
	(segment
		(start 100.74148 -30.003496)
		(end 100.74148 -32.835088)
		(width 0.127)
		(layer "In6.Cu")
		(net "SMB_1_BMC_GPU_SCL")
	)
	(segment
		(start 132.36702 -31.689548)
		(end 122.37974 -31.689548)
		(width 0.127)
		(layer "In6.Cu")
		(net "SMB_1_BMC_GPU_SCL")
	)
	(segment
		(start 152.70988 -18.760948)
		(end 152.1714 -19.299428)
		(width 0.127)
		(layer "In6.Cu")
		(net "SMB_1_BMC_GPU_SCL")
	)
	(segment
		(start 78.94701 -38.496748)
		(end 74.422 -38.496748)
		(width 0.127)
		(layer "In6.Cu")
		(net "SMB_1_BMC_GPU_SCL")
	)
	(segment
		(start 65.89268 -37.887148)
		(end 65.71488 -38.064948)
		(width 0.127)
		(layer "In6.Cu")
		(net "SMB_1_BMC_GPU_SCL")
	)
	(segment
		(start 98.806 -34.770568)
		(end 93.36278 -34.770568)
		(width 0.127)
		(layer "In6.Cu")
		(net "SMB_1_BMC_GPU_SCL")
	)
	(segment
		(start 53.79085 -436.376318)
		(end 52.881022 -436.376318)
		(width 0.12954)
		(layer "F.Cu")
		(net "SMB_1_BMC_GPU_BUF_SDA")
	)
	(segment
		(start 54.41188 -435.755288)
		(end 53.79085 -436.376318)
		(width 0.12954)
		(layer "F.Cu")
		(net "SMB_1_BMC_GPU_BUF_SDA")
	)
	(segment
		(start 54.41188 -435.244748)
		(end 54.41188 -435.755288)
		(width 0.12954)
		(layer "F.Cu")
		(net "SMB_1_BMC_GPU_BUF_SDA")
	)
	(segment
		(start 54.38648 -435.219348)
		(end 54.41188 -435.244748)
		(width 0.12954)
		(layer "F.Cu")
		(net "SMB_1_BMC_GPU_BUF_SDA")
	)
	(via
		(at 54.38648 -435.219348)
		(size 0.508)
		(drill 0.254)
		(layers "F.Cu" "B.Cu")
		(net "SMB_1_BMC_GPU_BUF_SDA")
	)
	(segment
		(start 54.48808 -425.172632)
		(end 54.61508 -425.299632)
		(width 0.127)
		(layer "In15.Cu")
		(net "SMB_1_BMC_GPU_BUF_SDA")
	)
	(segment
		(start 53.52034 -423.394632)
		(end 53.52034 -423.775632)
		(width 0.127)
		(layer "In15.Cu")
		(net "SMB_1_BMC_GPU_BUF_SDA")
	)
	(segment
		(start 53.64734 -427.712632)
		(end 54.48808 -427.712632)
		(width 0.127)
		(layer "In15.Cu")
		(net "SMB_1_BMC_GPU_BUF_SDA")
	)
	(segment
		(start 53.64734 -430.252632)
		(end 54.48808 -430.252632)
		(width 0.127)
		(layer "In15.Cu")
		(net "SMB_1_BMC_GPU_BUF_SDA")
	)
	(segment
		(start 54.61508 -423.140632)
		(end 54.48808 -423.267632)
		(width 0.127)
		(layer "In15.Cu")
		(net "SMB_1_BMC_GPU_BUF_SDA")
	)
	(segment
		(start 54.61508 -429.490632)
		(end 54.48808 -429.617632)
		(width 0.127)
		(layer "In15.Cu")
		(net "SMB_1_BMC_GPU_BUF_SDA")
	)
	(segment
		(start 53.52034 -421.235632)
		(end 53.64734 -421.362632)
		(width 0.127)
		(layer "In15.Cu")
		(net "SMB_1_BMC_GPU_BUF_SDA")
	)
	(segment
		(start 53.52034 -427.204632)
		(end 53.52034 -427.585632)
		(width 0.127)
		(layer "In15.Cu")
		(net "SMB_1_BMC_GPU_BUF_SDA")
	)
	(segment
		(start 54.48808 -425.807632)
		(end 53.64734 -425.807632)
		(width 0.127)
		(layer "In15.Cu")
		(net "SMB_1_BMC_GPU_BUF_SDA")
	)
	(segment
		(start 54.48808 -421.362632)
		(end 54.61508 -421.489632)
		(width 0.127)
		(layer "In15.Cu")
		(net "SMB_1_BMC_GPU_BUF_SDA")
	)
	(segment
		(start 53.52034 -428.855632)
		(end 53.64734 -428.982632)
		(width 0.127)
		(layer "In15.Cu")
		(net "SMB_1_BMC_GPU_BUF_SDA")
	)
	(segment
		(start 54.48808 -429.617632)
		(end 53.64734 -429.617632)
		(width 0.127)
		(layer "In15.Cu")
		(net "SMB_1_BMC_GPU_BUF_SDA")
	)
	(segment
		(start 54.48808 -431.522632)
		(end 54.61508 -431.649632)
		(width 0.127)
		(layer "In15.Cu")
		(net "SMB_1_BMC_GPU_BUF_SDA")
	)
	(segment
		(start 54.61508 -426.950632)
		(end 54.48808 -427.077632)
		(width 0.127)
		(layer "In15.Cu")
		(net "SMB_1_BMC_GPU_BUF_SDA")
	)
	(segment
		(start 53.64734 -424.537632)
		(end 53.52034 -424.664632)
		(width 0.127)
		(layer "In15.Cu")
		(net "SMB_1_BMC_GPU_BUF_SDA")
	)
	(segment
		(start 54.61508 -416.978084)
		(end 54.61508 -419.330632)
		(width 0.127)
		(layer "In15.Cu")
		(net "SMB_1_BMC_GPU_BUF_SDA")
	)
	(segment
		(start 54.61508 -428.220632)
		(end 54.48808 -428.347632)
		(width 0.127)
		(layer "In15.Cu")
		(net "SMB_1_BMC_GPU_BUF_SDA")
	)
	(segment
		(start 54.48808 -419.457632)
		(end 53.64734 -419.457632)
		(width 0.127)
		(layer "In15.Cu")
		(net "SMB_1_BMC_GPU_BUF_SDA")
	)
	(segment
		(start 54.38648 -434.762148)
		(end 54.38648 -435.219348)
		(width 0.127)
		(layer "In15.Cu")
		(net "SMB_1_BMC_GPU_BUF_SDA")
	)
	(segment
		(start 53.64734 -428.347632)
		(end 53.52034 -428.474632)
		(width 0.127)
		(layer "In15.Cu")
		(net "SMB_1_BMC_GPU_BUF_SDA")
	)
	(segment
		(start 62.71768 -414.264348)
		(end 57.328816 -414.264348)
		(width 0.127)
		(layer "In15.Cu")
		(net "SMB_1_BMC_GPU_BUF_SDA")
	)
	(segment
		(start 53.52034 -422.505632)
		(end 53.64734 -422.632632)
		(width 0.127)
		(layer "In15.Cu")
		(net "SMB_1_BMC_GPU_BUF_SDA")
	)
	(segment
		(start 54.48808 -423.267632)
		(end 53.64734 -423.267632)
		(width 0.127)
		(layer "In15.Cu")
		(net "SMB_1_BMC_GPU_BUF_SDA")
	)
	(segment
		(start 53.52034 -423.775632)
		(end 53.64734 -423.902632)
		(width 0.127)
		(layer "In15.Cu")
		(net "SMB_1_BMC_GPU_BUF_SDA")
	)
	(segment
		(start 53.52034 -427.585632)
		(end 53.64734 -427.712632)
		(width 0.127)
		(layer "In15.Cu")
		(net "SMB_1_BMC_GPU_BUF_SDA")
	)
	(segment
		(start 54.61508 -424.029632)
		(end 54.61508 -424.410632)
		(width 0.127)
		(layer "In15.Cu")
		(net "SMB_1_BMC_GPU_BUF_SDA")
	)
	(segment
		(start 53.64734 -431.522632)
		(end 54.48808 -431.522632)
		(width 0.127)
		(layer "In15.Cu")
		(net "SMB_1_BMC_GPU_BUF_SDA")
	)
	(segment
		(start 53.52034 -431.395632)
		(end 53.64734 -431.522632)
		(width 0.127)
		(layer "In15.Cu")
		(net "SMB_1_BMC_GPU_BUF_SDA")
	)
	(segment
		(start 54.48808 -430.252632)
		(end 54.61508 -430.379632)
		(width 0.127)
		(layer "In15.Cu")
		(net "SMB_1_BMC_GPU_BUF_SDA")
	)
	(segment
		(start 54.48808 -422.632632)
		(end 54.61508 -422.759632)
		(width 0.127)
		(layer "In15.Cu")
		(net "SMB_1_BMC_GPU_BUF_SDA")
	)
	(segment
		(start 54.61508 -420.600632)
		(end 54.48808 -420.727632)
		(width 0.127)
		(layer "In15.Cu")
		(net "SMB_1_BMC_GPU_BUF_SDA")
	)
	(segment
		(start 53.64734 -423.267632)
		(end 53.52034 -423.394632)
		(width 0.127)
		(layer "In15.Cu")
		(net "SMB_1_BMC_GPU_BUF_SDA")
	)
	(segment
		(start 53.52034 -424.664632)
		(end 53.52034 -425.045632)
		(width 0.127)
		(layer "In15.Cu")
		(net "SMB_1_BMC_GPU_BUF_SDA")
	)
	(segment
		(start 54.61508 -429.109632)
		(end 54.61508 -429.490632)
		(width 0.127)
		(layer "In15.Cu")
		(net "SMB_1_BMC_GPU_BUF_SDA")
	)
	(segment
		(start 54.48808 -423.902632)
		(end 54.61508 -424.029632)
		(width 0.127)
		(layer "In15.Cu")
		(net "SMB_1_BMC_GPU_BUF_SDA")
	)
	(segment
		(start 54.61508 -426.569632)
		(end 54.61508 -426.950632)
		(width 0.127)
		(layer "In15.Cu")
		(net "SMB_1_BMC_GPU_BUF_SDA")
	)
	(segment
		(start 63.86068 -415.407348)
		(end 62.71768 -414.264348)
		(width 0.127)
		(layer "In15.Cu")
		(net "SMB_1_BMC_GPU_BUF_SDA")
	)
	(segment
		(start 53.64734 -428.982632)
		(end 54.48808 -428.982632)
		(width 0.127)
		(layer "In15.Cu")
		(net "SMB_1_BMC_GPU_BUF_SDA")
	)
	(segment
		(start 53.52034 -428.474632)
		(end 53.52034 -428.855632)
		(width 0.127)
		(layer "In15.Cu")
		(net "SMB_1_BMC_GPU_BUF_SDA")
	)
	(segment
		(start 54.48808 -428.347632)
		(end 53.64734 -428.347632)
		(width 0.127)
		(layer "In15.Cu")
		(net "SMB_1_BMC_GPU_BUF_SDA")
	)
	(segment
		(start 63.86068 -419.100508)
		(end 63.86068 -415.407348)
		(width 0.127)
		(layer "In15.Cu")
		(net "SMB_1_BMC_GPU_BUF_SDA")
	)
	(segment
		(start 53.52034 -425.934632)
		(end 53.52034 -426.315632)
		(width 0.127)
		(layer "In15.Cu")
		(net "SMB_1_BMC_GPU_BUF_SDA")
	)
	(segment
		(start 54.48808 -420.727632)
		(end 53.64734 -420.727632)
		(width 0.127)
		(layer "In15.Cu")
		(net "SMB_1_BMC_GPU_BUF_SDA")
	)
	(segment
		(start 53.52034 -430.125632)
		(end 53.64734 -430.252632)
		(width 0.127)
		(layer "In15.Cu")
		(net "SMB_1_BMC_GPU_BUF_SDA")
	)
	(segment
		(start 53.52034 -426.315632)
		(end 53.64734 -426.442632)
		(width 0.127)
		(layer "In15.Cu")
		(net "SMB_1_BMC_GPU_BUF_SDA")
	)
	(segment
		(start 54.48808 -420.092632)
		(end 54.61508 -420.219632)
		(width 0.127)
		(layer "In15.Cu")
		(net "SMB_1_BMC_GPU_BUF_SDA")
	)
	(segment
		(start 53.52034 -420.854632)
		(end 53.52034 -421.235632)
		(width 0.127)
		(layer "In15.Cu")
		(net "SMB_1_BMC_GPU_BUF_SDA")
	)
	(segment
		(start 54.48808 -421.997632)
		(end 53.64734 -421.997632)
		(width 0.127)
		(layer "In15.Cu")
		(net "SMB_1_BMC_GPU_BUF_SDA")
	)
	(segment
		(start 54.48808 -427.077632)
		(end 53.64734 -427.077632)
		(width 0.127)
		(layer "In15.Cu")
		(net "SMB_1_BMC_GPU_BUF_SDA")
	)
	(segment
		(start 53.52034 -429.744632)
		(end 53.52034 -430.125632)
		(width 0.127)
		(layer "In15.Cu")
		(net "SMB_1_BMC_GPU_BUF_SDA")
	)
	(segment
		(start 54.61508 -425.299632)
		(end 54.61508 -425.680632)
		(width 0.127)
		(layer "In15.Cu")
		(net "SMB_1_BMC_GPU_BUF_SDA")
	)
	(segment
		(start 54.61508 -431.649632)
		(end 54.61508 -434.533548)
		(width 0.127)
		(layer "In15.Cu")
		(net "SMB_1_BMC_GPU_BUF_SDA")
	)
	(segment
		(start 53.52034 -431.014632)
		(end 53.52034 -431.395632)
		(width 0.127)
		(layer "In15.Cu")
		(net "SMB_1_BMC_GPU_BUF_SDA")
	)
	(segment
		(start 53.64734 -422.632632)
		(end 54.48808 -422.632632)
		(width 0.127)
		(layer "In15.Cu")
		(net "SMB_1_BMC_GPU_BUF_SDA")
	)
	(segment
		(start 54.61508 -421.870632)
		(end 54.48808 -421.997632)
		(width 0.127)
		(layer "In15.Cu")
		(net "SMB_1_BMC_GPU_BUF_SDA")
	)
	(segment
		(start 53.64734 -425.172632)
		(end 54.48808 -425.172632)
		(width 0.127)
		(layer "In15.Cu")
		(net "SMB_1_BMC_GPU_BUF_SDA")
	)
	(segment
		(start 54.48808 -426.442632)
		(end 54.61508 -426.569632)
		(width 0.127)
		(layer "In15.Cu")
		(net "SMB_1_BMC_GPU_BUF_SDA")
	)
	(segment
		(start 54.61508 -424.410632)
		(end 54.48808 -424.537632)
		(width 0.127)
		(layer "In15.Cu")
		(net "SMB_1_BMC_GPU_BUF_SDA")
	)
	(segment
		(start 54.48808 -428.982632)
		(end 54.61508 -429.109632)
		(width 0.127)
		(layer "In15.Cu")
		(net "SMB_1_BMC_GPU_BUF_SDA")
	)
	(segment
		(start 53.64734 -426.442632)
		(end 54.48808 -426.442632)
		(width 0.127)
		(layer "In15.Cu")
		(net "SMB_1_BMC_GPU_BUF_SDA")
	)
	(segment
		(start 54.61508 -422.759632)
		(end 54.61508 -423.140632)
		(width 0.127)
		(layer "In15.Cu")
		(net "SMB_1_BMC_GPU_BUF_SDA")
	)
	(segment
		(start 53.64734 -430.887632)
		(end 53.52034 -431.014632)
		(width 0.127)
		(layer "In15.Cu")
		(net "SMB_1_BMC_GPU_BUF_SDA")
	)
	(segment
		(start 57.328816 -414.264348)
		(end 54.61508 -416.978084)
		(width 0.127)
		(layer "In15.Cu")
		(net "SMB_1_BMC_GPU_BUF_SDA")
	)
	(segment
		(start 54.61508 -430.379632)
		(end 54.61508 -430.760632)
		(width 0.127)
		(layer "In15.Cu")
		(net "SMB_1_BMC_GPU_BUF_SDA")
	)
	(segment
		(start 53.64734 -427.077632)
		(end 53.52034 -427.204632)
		(width 0.127)
		(layer "In15.Cu")
		(net "SMB_1_BMC_GPU_BUF_SDA")
	)
	(segment
		(start 53.64734 -429.617632)
		(end 53.52034 -429.744632)
		(width 0.127)
		(layer "In15.Cu")
		(net "SMB_1_BMC_GPU_BUF_SDA")
	)
	(segment
		(start 53.52034 -419.584632)
		(end 53.52034 -419.965632)
		(width 0.127)
		(layer "In15.Cu")
		(net "SMB_1_BMC_GPU_BUF_SDA")
	)
	(segment
		(start 53.64734 -425.807632)
		(end 53.52034 -425.934632)
		(width 0.127)
		(layer "In15.Cu")
		(net "SMB_1_BMC_GPU_BUF_SDA")
	)
	(segment
		(start 54.61508 -427.839632)
		(end 54.61508 -428.220632)
		(width 0.127)
		(layer "In15.Cu")
		(net "SMB_1_BMC_GPU_BUF_SDA")
	)
	(segment
		(start 54.61508 -421.489632)
		(end 54.61508 -421.870632)
		(width 0.127)
		(layer "In15.Cu")
		(net "SMB_1_BMC_GPU_BUF_SDA")
	)
	(segment
		(start 54.48808 -430.887632)
		(end 53.64734 -430.887632)
		(width 0.127)
		(layer "In15.Cu")
		(net "SMB_1_BMC_GPU_BUF_SDA")
	)
	(segment
		(start 54.48808 -424.537632)
		(end 53.64734 -424.537632)
		(width 0.127)
		(layer "In15.Cu")
		(net "SMB_1_BMC_GPU_BUF_SDA")
	)
	(segment
		(start 54.61508 -434.533548)
		(end 54.38648 -434.762148)
		(width 0.127)
		(layer "In15.Cu")
		(net "SMB_1_BMC_GPU_BUF_SDA")
	)
	(segment
		(start 53.64734 -419.457632)
		(end 53.52034 -419.584632)
		(width 0.127)
		(layer "In15.Cu")
		(net "SMB_1_BMC_GPU_BUF_SDA")
	)
	(segment
		(start 54.48808 -427.712632)
		(end 54.61508 -427.839632)
		(width 0.127)
		(layer "In15.Cu")
		(net "SMB_1_BMC_GPU_BUF_SDA")
	)
	(segment
		(start 53.64734 -420.092632)
		(end 54.48808 -420.092632)
		(width 0.127)
		(layer "In15.Cu")
		(net "SMB_1_BMC_GPU_BUF_SDA")
	)
	(segment
		(start 64.650112 -419.88994)
		(end 63.86068 -419.100508)
		(width 0.127)
		(layer "In15.Cu")
		(net "SMB_1_BMC_GPU_BUF_SDA")
	)
	(segment
		(start 54.61508 -420.219632)
		(end 54.61508 -420.600632)
		(width 0.127)
		(layer "In15.Cu")
		(net "SMB_1_BMC_GPU_BUF_SDA")
	)
	(segment
		(start 54.61508 -419.330632)
		(end 54.48808 -419.457632)
		(width 0.127)
		(layer "In15.Cu")
		(net "SMB_1_BMC_GPU_BUF_SDA")
	)
	(segment
		(start 53.52034 -422.124632)
		(end 53.52034 -422.505632)
		(width 0.127)
		(layer "In15.Cu")
		(net "SMB_1_BMC_GPU_BUF_SDA")
	)
	(segment
		(start 53.64734 -421.997632)
		(end 53.52034 -422.124632)
		(width 0.127)
		(layer "In15.Cu")
		(net "SMB_1_BMC_GPU_BUF_SDA")
	)
	(segment
		(start 53.64734 -420.727632)
		(end 53.52034 -420.854632)
		(width 0.127)
		(layer "In15.Cu")
		(net "SMB_1_BMC_GPU_BUF_SDA")
	)
	(segment
		(start 53.52034 -419.965632)
		(end 53.64734 -420.092632)
		(width 0.127)
		(layer "In15.Cu")
		(net "SMB_1_BMC_GPU_BUF_SDA")
	)
	(segment
		(start 53.64734 -423.902632)
		(end 54.48808 -423.902632)
		(width 0.127)
		(layer "In15.Cu")
		(net "SMB_1_BMC_GPU_BUF_SDA")
	)
	(segment
		(start 53.52034 -425.045632)
		(end 53.64734 -425.172632)
		(width 0.127)
		(layer "In15.Cu")
		(net "SMB_1_BMC_GPU_BUF_SDA")
	)
	(segment
		(start 54.61508 -430.760632)
		(end 54.48808 -430.887632)
		(width 0.127)
		(layer "In15.Cu")
		(net "SMB_1_BMC_GPU_BUF_SDA")
	)
	(segment
		(start 54.61508 -425.680632)
		(end 54.48808 -425.807632)
		(width 0.127)
		(layer "In15.Cu")
		(net "SMB_1_BMC_GPU_BUF_SDA")
	)
	(segment
		(start 53.64734 -421.362632)
		(end 54.48808 -421.362632)
		(width 0.127)
		(layer "In15.Cu")
		(net "SMB_1_BMC_GPU_BUF_SDA")
	)
	(segment
		(start 37.413692 -436.184548)
		(end 37.62883 -435.96941)
		(width 0.12954)
		(layer "F.Cu")
		(net "SMB_1_BMC_GPU_BUF_SCL")
	)
	(segment
		(start 37.62883 -435.96941)
		(end 37.62883 -435.955948)
		(width 0.12954)
		(layer "F.Cu")
		(net "SMB_1_BMC_GPU_BUF_SCL")
	)
	(segment
		(start 36.78428 -436.184548)
		(end 37.413692 -436.184548)
		(width 0.12954)
		(layer "F.Cu")
		(net "SMB_1_BMC_GPU_BUF_SCL")
	)
	(segment
		(start 36.70808 -436.260748)
		(end 36.78428 -436.184548)
		(width 0.12954)
		(layer "F.Cu")
		(net "SMB_1_BMC_GPU_BUF_SCL")
	)
	(via
		(at 36.70808 -436.260748)
		(size 0.508)
		(drill 0.254)
		(layers "F.Cu" "B.Cu")
		(net "SMB_1_BMC_GPU_BUF_SCL")
	)
	(segment
		(start 62.15888 -414.746948)
		(end 63.37808 -415.966148)
		(width 0.127)
		(layer "In15.Cu")
		(net "SMB_1_BMC_GPU_BUF_SCL")
	)
	(segment
		(start 36.70808 -436.260748)
		(end 36.93668 -436.260748)
		(width 0.127)
		(layer "In15.Cu")
		(net "SMB_1_BMC_GPU_BUF_SCL")
	)
	(segment
		(start 55.19928 -435.346348)
		(end 55.19928 -417.195254)
		(width 0.127)
		(layer "In15.Cu")
		(net "SMB_1_BMC_GPU_BUF_SCL")
	)
	(segment
		(start 63.37808 -419.817804)
		(end 64.650112 -421.089836)
		(width 0.127)
		(layer "In15.Cu")
		(net "SMB_1_BMC_GPU_BUF_SCL")
	)
	(segment
		(start 36.93668 -436.260748)
		(end 37.41928 -436.743348)
		(width 0.127)
		(layer "In15.Cu")
		(net "SMB_1_BMC_GPU_BUF_SCL")
	)
	(segment
		(start 54.553866 -435.991762)
		(end 55.19928 -435.346348)
		(width 0.127)
		(layer "In15.Cu")
		(net "SMB_1_BMC_GPU_BUF_SCL")
	)
	(segment
		(start 55.19928 -417.195254)
		(end 57.647586 -414.746948)
		(width 0.127)
		(layer "In15.Cu")
		(net "SMB_1_BMC_GPU_BUF_SCL")
	)
	(segment
		(start 42.265854 -435.991762)
		(end 54.553866 -435.991762)
		(width 0.127)
		(layer "In15.Cu")
		(net "SMB_1_BMC_GPU_BUF_SCL")
	)
	(segment
		(start 57.647586 -414.746948)
		(end 62.15888 -414.746948)
		(width 0.127)
		(layer "In15.Cu")
		(net "SMB_1_BMC_GPU_BUF_SCL")
	)
	(segment
		(start 63.37808 -415.966148)
		(end 63.37808 -419.817804)
		(width 0.127)
		(layer "In15.Cu")
		(net "SMB_1_BMC_GPU_BUF_SCL")
	)
	(segment
		(start 41.514268 -436.743348)
		(end 42.265854 -435.991762)
		(width 0.127)
		(layer "In15.Cu")
		(net "SMB_1_BMC_GPU_BUF_SCL")
	)
	(segment
		(start 37.41928 -436.743348)
		(end 41.514268 -436.743348)
		(width 0.127)
		(layer "In15.Cu")
		(net "SMB_1_BMC_GPU_BUF_SCL")
	)
	(segment
		(start 172.555662 -117.775482)
		(end 172.155612 -118.175532)
		(width 0.12954)
		(layer "F.Cu")
		(net "SGPIO_OCP_V3_2_LD_N")
	)
	(segment
		(start 76.861924 -12.635992)
		(end 77.14361 -12.917678)
		(width 0.12954)
		(layer "F.Cu")
		(net "SGPIO_OCP_V3_2_LD_N")
	)
	(segment
		(start 76.861924 -11.26998)
		(end 76.861924 -12.635992)
		(width 0.12954)
		(layer "F.Cu")
		(net "SGPIO_OCP_V3_2_LD_N")
	)
	(via
		(at 113.84788 -81.244948)
		(size 0.508)
		(drill 0.254)
		(layers "F.Cu" "B.Cu")
		(net "SGPIO_OCP_V3_2_LD_N")
	)
	(via
		(at 77.14361 -12.917678)
		(size 0.508)
		(drill 0.254)
		(layers "F.Cu" "B.Cu")
		(net "SGPIO_OCP_V3_2_LD_N")
	)
	(via
		(at 172.155612 -118.175532)
		(size 0.4572)
		(drill 0.254)
		(layers "F.Cu" "B.Cu")
		(net "SGPIO_OCP_V3_2_LD_N")
	)
	(via
		(at 149.97938 -81.074768)
		(size 0.508)
		(drill 0.254)
		(layers "F.Cu" "B.Cu")
		(net "SGPIO_OCP_V3_2_LD_N")
	)
	(segment
		(start 74.85888 -11.902948)
		(end 74.85888 -11.667998)
		(width 0.12954)
		(layer "B.Cu")
		(net "SGPIO_OCP_V3_2_LD_N")
	)
	(segment
		(start 77.14361 -12.917678)
		(end 76.38034 -12.154408)
		(width 0.12954)
		(layer "B.Cu")
		(net "SGPIO_OCP_V3_2_LD_N")
	)
	(segment
		(start 76.38034 -12.154408)
		(end 75.11034 -12.154408)
		(width 0.12954)
		(layer "B.Cu")
		(net "SGPIO_OCP_V3_2_LD_N")
	)
	(segment
		(start 75.11034 -12.154408)
		(end 74.85888 -11.902948)
		(width 0.12954)
		(layer "B.Cu")
		(net "SGPIO_OCP_V3_2_LD_N")
	)
	(segment
		(start 163.54552 -105.847388)
		(end 163.03244 -105.847388)
		(width 0.127)
		(layer "In2.Cu")
		(net "SGPIO_OCP_V3_2_LD_N")
	)
	(segment
		(start 166.0525 -115.913408)
		(end 166.0525 -114.813588)
		(width 0.127)
		(layer "In2.Cu")
		(net "SGPIO_OCP_V3_2_LD_N")
	)
	(segment
		(start 163.8808 -110.706408)
		(end 163.8808 -110.020608)
		(width 0.127)
		(layer "In2.Cu")
		(net "SGPIO_OCP_V3_2_LD_N")
	)
	(segment
		(start 87.05088 -19.218148)
		(end 87.05088 -29.7053)
		(width 0.127)
		(layer "In2.Cu")
		(net "SGPIO_OCP_V3_2_LD_N")
	)
	(segment
		(start 171.656756 -118.890288)
		(end 169.02938 -118.890288)
		(width 0.127)
		(layer "In2.Cu")
		(net "SGPIO_OCP_V3_2_LD_N")
	)
	(segment
		(start 81.886552 -15.992348)
		(end 83.82508 -15.992348)
		(width 0.127)
		(layer "In2.Cu")
		(net "SGPIO_OCP_V3_2_LD_N")
	)
	(segment
		(start 172.155612 -118.175532)
		(end 172.155612 -118.391432)
		(width 0.127)
		(layer "In2.Cu")
		(net "SGPIO_OCP_V3_2_LD_N")
	)
	(segment
		(start 150.2537 -81.074768)
		(end 149.97938 -81.074768)
		(width 0.127)
		(layer "In2.Cu")
		(net "SGPIO_OCP_V3_2_LD_N")
	)
	(segment
		(start 156.62656 -103.505508)
		(end 156.62656 -96.810068)
		(width 0.127)
		(layer "In2.Cu")
		(net "SGPIO_OCP_V3_2_LD_N")
	)
	(segment
		(start 111.75746 -51.650392)
		(end 112.36198 -52.254912)
		(width 0.127)
		(layer "In2.Cu")
		(net "SGPIO_OCP_V3_2_LD_N")
	)
	(segment
		(start 162.433 -105.247948)
		(end 158.369 -105.247948)
		(width 0.127)
		(layer "In2.Cu")
		(net "SGPIO_OCP_V3_2_LD_N")
	)
	(segment
		(start 113.47958 -79.156814)
		(end 113.84788 -79.525114)
		(width 0.127)
		(layer "In2.Cu")
		(net "SGPIO_OCP_V3_2_LD_N")
	)
	(segment
		(start 158.496 -94.940628)
		(end 158.496 -92.327222)
		(width 0.127)
		(layer "In2.Cu")
		(net "SGPIO_OCP_V3_2_LD_N")
	)
	(segment
		(start 158.369 -105.247948)
		(end 156.62656 -103.505508)
		(width 0.127)
		(layer "In2.Cu")
		(net "SGPIO_OCP_V3_2_LD_N")
	)
	(segment
		(start 111.75746 -47.985172)
		(end 111.75746 -51.650392)
		(width 0.127)
		(layer "In2.Cu")
		(net "SGPIO_OCP_V3_2_LD_N")
	)
	(segment
		(start 83.82508 -15.992348)
		(end 87.05088 -19.218148)
		(width 0.127)
		(layer "In2.Cu")
		(net "SGPIO_OCP_V3_2_LD_N")
	)
	(segment
		(start 164.32784 -109.573568)
		(end 164.32784 -106.629708)
		(width 0.127)
		(layer "In2.Cu")
		(net "SGPIO_OCP_V3_2_LD_N")
	)
	(segment
		(start 172.155612 -118.391432)
		(end 171.656756 -118.890288)
		(width 0.127)
		(layer "In2.Cu")
		(net "SGPIO_OCP_V3_2_LD_N")
	)
	(segment
		(start 113.47958 -73.007728)
		(end 113.47958 -79.156814)
		(width 0.127)
		(layer "In2.Cu")
		(net "SGPIO_OCP_V3_2_LD_N")
	)
	(segment
		(start 112.36198 -52.254912)
		(end 112.36198 -71.890128)
		(width 0.127)
		(layer "In2.Cu")
		(net "SGPIO_OCP_V3_2_LD_N")
	)
	(segment
		(start 164.32784 -106.629708)
		(end 163.54552 -105.847388)
		(width 0.127)
		(layer "In2.Cu")
		(net "SGPIO_OCP_V3_2_LD_N")
	)
	(segment
		(start 164.35832 -113.119408)
		(end 164.35832 -111.183928)
		(width 0.127)
		(layer "In2.Cu")
		(net "SGPIO_OCP_V3_2_LD_N")
	)
	(segment
		(start 169.02938 -118.890288)
		(end 166.0525 -115.913408)
		(width 0.127)
		(layer "In2.Cu")
		(net "SGPIO_OCP_V3_2_LD_N")
	)
	(segment
		(start 151.54148 -82.362548)
		(end 150.2537 -81.074768)
		(width 0.127)
		(layer "In2.Cu")
		(net "SGPIO_OCP_V3_2_LD_N")
	)
	(segment
		(start 98.445828 -41.100248)
		(end 104.872536 -41.100248)
		(width 0.127)
		(layer "In2.Cu")
		(net "SGPIO_OCP_V3_2_LD_N")
	)
	(segment
		(start 77.49794 -13.272008)
		(end 79.166212 -13.272008)
		(width 0.127)
		(layer "In2.Cu")
		(net "SGPIO_OCP_V3_2_LD_N")
	)
	(segment
		(start 113.84788 -79.525114)
		(end 113.84788 -81.244948)
		(width 0.127)
		(layer "In2.Cu")
		(net "SGPIO_OCP_V3_2_LD_N")
	)
	(segment
		(start 77.14361 -12.917678)
		(end 77.49794 -13.272008)
		(width 0.127)
		(layer "In2.Cu")
		(net "SGPIO_OCP_V3_2_LD_N")
	)
	(segment
		(start 163.8808 -110.020608)
		(end 164.32784 -109.573568)
		(width 0.127)
		(layer "In2.Cu")
		(net "SGPIO_OCP_V3_2_LD_N")
	)
	(segment
		(start 166.0525 -114.813588)
		(end 164.35832 -113.119408)
		(width 0.127)
		(layer "In2.Cu")
		(net "SGPIO_OCP_V3_2_LD_N")
	)
	(segment
		(start 164.35832 -111.183928)
		(end 163.8808 -110.706408)
		(width 0.127)
		(layer "In2.Cu")
		(net "SGPIO_OCP_V3_2_LD_N")
	)
	(segment
		(start 104.872536 -41.100248)
		(end 111.75746 -47.985172)
		(width 0.127)
		(layer "In2.Cu")
		(net "SGPIO_OCP_V3_2_LD_N")
	)
	(segment
		(start 79.166212 -13.272008)
		(end 81.886552 -15.992348)
		(width 0.127)
		(layer "In2.Cu")
		(net "SGPIO_OCP_V3_2_LD_N")
	)
	(segment
		(start 156.62656 -96.810068)
		(end 158.496 -94.940628)
		(width 0.127)
		(layer "In2.Cu")
		(net "SGPIO_OCP_V3_2_LD_N")
	)
	(segment
		(start 87.05088 -29.7053)
		(end 98.445828 -41.100248)
		(width 0.127)
		(layer "In2.Cu")
		(net "SGPIO_OCP_V3_2_LD_N")
	)
	(segment
		(start 158.496 -92.327222)
		(end 151.54148 -85.372702)
		(width 0.127)
		(layer "In2.Cu")
		(net "SGPIO_OCP_V3_2_LD_N")
	)
	(segment
		(start 151.54148 -85.372702)
		(end 151.54148 -82.362548)
		(width 0.127)
		(layer "In2.Cu")
		(net "SGPIO_OCP_V3_2_LD_N")
	)
	(segment
		(start 163.03244 -105.847388)
		(end 162.433 -105.247948)
		(width 0.127)
		(layer "In2.Cu")
		(net "SGPIO_OCP_V3_2_LD_N")
	)
	(segment
		(start 112.36198 -71.890128)
		(end 113.47958 -73.007728)
		(width 0.127)
		(layer "In2.Cu")
		(net "SGPIO_OCP_V3_2_LD_N")
	)
	(segment
		(start 114.165634 -81.562702)
		(end 113.84788 -81.244948)
		(width 0.127)
		(layer "In6.Cu")
		(net "SGPIO_OCP_V3_2_LD_N")
	)
	(segment
		(start 149.97938 -81.074768)
		(end 149.87524 -80.970628)
		(width 0.127)
		(layer "In6.Cu")
		(net "SGPIO_OCP_V3_2_LD_N")
	)
	(segment
		(start 131.587748 -81.562702)
		(end 114.165634 -81.562702)
		(width 0.127)
		(layer "In6.Cu")
		(net "SGPIO_OCP_V3_2_LD_N")
	)
	(segment
		(start 149.87524 -80.970628)
		(end 132.179822 -80.970628)
		(width 0.127)
		(layer "In6.Cu")
		(net "SGPIO_OCP_V3_2_LD_N")
	)
	(segment
		(start 132.179822 -80.970628)
		(end 131.587748 -81.562702)
		(width 0.127)
		(layer "In6.Cu")
		(net "SGPIO_OCP_V3_2_LD_N")
	)
	(segment
		(start 75.662028 -11.26998)
		(end 75.662028 -12.185904)
		(width 0.12954)
		(layer "F.Cu")
		(net "SGPIO_OCP_V3_2_DATAOUT")
	)
	(segment
		(start 75.8317 -12.355576)
		(end 75.8317 -13.106908)
		(width 0.12954)
		(layer "F.Cu")
		(net "SGPIO_OCP_V3_2_DATAOUT")
	)
	(segment
		(start 75.662028 -12.185904)
		(end 75.8317 -12.355576)
		(width 0.12954)
		(layer "F.Cu")
		(net "SGPIO_OCP_V3_2_DATAOUT")
	)
	(segment
		(start 170.155616 -117.775482)
		(end 169.755566 -118.175532)
		(width 0.12954)
		(layer "F.Cu")
		(net "SGPIO_OCP_V3_2_DATAOUT")
	)
	(via
		(at 148.29028 -79.924148)
		(size 0.508)
		(drill 0.254)
		(layers "F.Cu" "B.Cu")
		(net "SGPIO_OCP_V3_2_DATAOUT")
	)
	(via
		(at 111.53648 -79.898748)
		(size 0.508)
		(drill 0.254)
		(layers "F.Cu" "B.Cu")
		(net "SGPIO_OCP_V3_2_DATAOUT")
	)
	(via
		(at 158.12008 -118.836948)
		(size 0.508)
		(drill 0.254)
		(layers "F.Cu" "B.Cu")
		(net "SGPIO_OCP_V3_2_DATAOUT")
	)
	(via
		(at 75.8317 -13.106908)
		(size 0.508)
		(drill 0.254)
		(layers "F.Cu" "B.Cu")
		(net "SGPIO_OCP_V3_2_DATAOUT")
	)
	(via
		(at 156.01188 -110.835948)
		(size 0.508)
		(drill 0.254)
		(layers "F.Cu" "B.Cu")
		(net "SGPIO_OCP_V3_2_DATAOUT")
	)
	(via
		(at 169.755566 -118.175532)
		(size 0.4572)
		(drill 0.254)
		(layers "F.Cu" "B.Cu")
		(net "SGPIO_OCP_V3_2_DATAOUT")
	)
	(segment
		(start 157.42793 -118.836948)
		(end 158.12008 -118.836948)
		(width 0.12954)
		(layer "B.Cu")
		(net "SGPIO_OCP_V3_2_DATAOUT")
	)
	(segment
		(start 75.8317 -13.106908)
		(end 75.8317 -13.500608)
		(width 0.127)
		(layer "In2.Cu")
		(net "SGPIO_OCP_V3_2_DATAOUT")
	)
	(segment
		(start 156.01188 -110.835948)
		(end 156.01188 -110.72368)
		(width 0.127)
		(layer "In2.Cu")
		(net "SGPIO_OCP_V3_2_DATAOUT")
	)
	(segment
		(start 110.81766 -50.102008)
		(end 110.81766 -51.932332)
		(width 0.127)
		(layer "In2.Cu")
		(net "SGPIO_OCP_V3_2_DATAOUT")
	)
	(segment
		(start 98.08718 -41.963848)
		(end 102.6795 -41.963848)
		(width 0.127)
		(layer "In2.Cu")
		(net "SGPIO_OCP_V3_2_DATAOUT")
	)
	(segment
		(start 78.64348 -14.138148)
		(end 81.38668 -16.881348)
		(width 0.127)
		(layer "In2.Cu")
		(net "SGPIO_OCP_V3_2_DATAOUT")
	)
	(segment
		(start 152.36698 -107.07878)
		(end 152.36698 -90.902536)
		(width 0.127)
		(layer "In2.Cu")
		(net "SGPIO_OCP_V3_2_DATAOUT")
	)
	(segment
		(start 111.49838 -52.613052)
		(end 111.49838 -79.860648)
		(width 0.127)
		(layer "In2.Cu")
		(net "SGPIO_OCP_V3_2_DATAOUT")
	)
	(segment
		(start 148.74748 -87.283036)
		(end 148.74748 -81.824068)
		(width 0.127)
		(layer "In2.Cu")
		(net "SGPIO_OCP_V3_2_DATAOUT")
	)
	(segment
		(start 75.8317 -13.500608)
		(end 76.46924 -14.138148)
		(width 0.127)
		(layer "In2.Cu")
		(net "SGPIO_OCP_V3_2_DATAOUT")
	)
	(segment
		(start 110.81766 -51.932332)
		(end 111.49838 -52.613052)
		(width 0.127)
		(layer "In2.Cu")
		(net "SGPIO_OCP_V3_2_DATAOUT")
	)
	(segment
		(start 156.01188 -110.72368)
		(end 152.36698 -107.07878)
		(width 0.127)
		(layer "In2.Cu")
		(net "SGPIO_OCP_V3_2_DATAOUT")
	)
	(segment
		(start 148.74748 -81.824068)
		(end 148.29028 -81.366868)
		(width 0.127)
		(layer "In2.Cu")
		(net "SGPIO_OCP_V3_2_DATAOUT")
	)
	(segment
		(start 83.36788 -16.881348)
		(end 85.84692 -19.360388)
		(width 0.127)
		(layer "In2.Cu")
		(net "SGPIO_OCP_V3_2_DATAOUT")
	)
	(segment
		(start 86.9696 -32.192468)
		(end 88.3158 -32.192468)
		(width 0.127)
		(layer "In2.Cu")
		(net "SGPIO_OCP_V3_2_DATAOUT")
	)
	(segment
		(start 85.84692 -31.069788)
		(end 86.9696 -32.192468)
		(width 0.127)
		(layer "In2.Cu")
		(net "SGPIO_OCP_V3_2_DATAOUT")
	)
	(segment
		(start 152.36698 -90.902536)
		(end 148.74748 -87.283036)
		(width 0.127)
		(layer "In2.Cu")
		(net "SGPIO_OCP_V3_2_DATAOUT")
	)
	(segment
		(start 85.84692 -19.360388)
		(end 85.84692 -31.069788)
		(width 0.127)
		(layer "In2.Cu")
		(net "SGPIO_OCP_V3_2_DATAOUT")
	)
	(segment
		(start 102.6795 -41.963848)
		(end 110.81766 -50.102008)
		(width 0.127)
		(layer "In2.Cu")
		(net "SGPIO_OCP_V3_2_DATAOUT")
	)
	(segment
		(start 81.38668 -16.881348)
		(end 83.36788 -16.881348)
		(width 0.127)
		(layer "In2.Cu")
		(net "SGPIO_OCP_V3_2_DATAOUT")
	)
	(segment
		(start 148.29028 -81.366868)
		(end 148.29028 -79.924148)
		(width 0.127)
		(layer "In2.Cu")
		(net "SGPIO_OCP_V3_2_DATAOUT")
	)
	(segment
		(start 76.46924 -14.138148)
		(end 78.64348 -14.138148)
		(width 0.127)
		(layer "In2.Cu")
		(net "SGPIO_OCP_V3_2_DATAOUT")
	)
	(segment
		(start 111.49838 -79.860648)
		(end 111.53648 -79.898748)
		(width 0.127)
		(layer "In2.Cu")
		(net "SGPIO_OCP_V3_2_DATAOUT")
	)
	(segment
		(start 88.3158 -32.192468)
		(end 98.08718 -41.963848)
		(width 0.127)
		(layer "In2.Cu")
		(net "SGPIO_OCP_V3_2_DATAOUT")
	)
	(segment
		(start 131.438396 -81.020158)
		(end 114.63274 -81.020158)
		(width 0.127)
		(layer "In6.Cu")
		(net "SGPIO_OCP_V3_2_DATAOUT")
	)
	(segment
		(start 114.12093 -80.508348)
		(end 112.14608 -80.508348)
		(width 0.127)
		(layer "In6.Cu")
		(net "SGPIO_OCP_V3_2_DATAOUT")
	)
	(segment
		(start 112.14608 -80.508348)
		(end 111.53648 -79.898748)
		(width 0.127)
		(layer "In6.Cu")
		(net "SGPIO_OCP_V3_2_DATAOUT")
	)
	(segment
		(start 148.29028 -79.924148)
		(end 147.70608 -80.508348)
		(width 0.127)
		(layer "In6.Cu")
		(net "SGPIO_OCP_V3_2_DATAOUT")
	)
	(segment
		(start 147.70608 -80.508348)
		(end 131.950206 -80.508348)
		(width 0.127)
		(layer "In6.Cu")
		(net "SGPIO_OCP_V3_2_DATAOUT")
	)
	(segment
		(start 114.63274 -81.020158)
		(end 114.12093 -80.508348)
		(width 0.127)
		(layer "In6.Cu")
		(net "SGPIO_OCP_V3_2_DATAOUT")
	)
	(segment
		(start 131.950206 -80.508348)
		(end 131.438396 -81.020158)
		(width 0.127)
		(layer "In6.Cu")
		(net "SGPIO_OCP_V3_2_DATAOUT")
	)
	(segment
		(start 158.5468 -118.410228)
		(end 158.12008 -118.836948)
		(width 0.127)
		(layer "In13.Cu")
		(net "SGPIO_OCP_V3_2_DATAOUT")
	)
	(segment
		(start 158.5468 -117.37848)
		(end 158.5468 -118.410228)
		(width 0.127)
		(layer "In13.Cu")
		(net "SGPIO_OCP_V3_2_DATAOUT")
	)
	(segment
		(start 158.12008 -118.836948)
		(end 157.53334 -118.250208)
		(width 0.127)
		(layer "In13.Cu")
		(net "SGPIO_OCP_V3_2_DATAOUT")
	)
	(segment
		(start 169.755566 -118.175532)
		(end 169.72915 -118.201948)
		(width 0.127)
		(layer "In13.Cu")
		(net "SGPIO_OCP_V3_2_DATAOUT")
	)
	(segment
		(start 156.01188 -111.470948)
		(end 156.01188 -110.835948)
		(width 0.127)
		(layer "In13.Cu")
		(net "SGPIO_OCP_V3_2_DATAOUT")
	)
	(segment
		(start 157.53334 -118.250208)
		(end 157.53334 -112.992408)
		(width 0.127)
		(layer "In13.Cu")
		(net "SGPIO_OCP_V3_2_DATAOUT")
	)
	(segment
		(start 169.72915 -118.201948)
		(end 166.500048 -118.201948)
		(width 0.127)
		(layer "In13.Cu")
		(net "SGPIO_OCP_V3_2_DATAOUT")
	)
	(segment
		(start 158.87954 -117.04574)
		(end 158.5468 -117.37848)
		(width 0.127)
		(layer "In13.Cu")
		(net "SGPIO_OCP_V3_2_DATAOUT")
	)
	(segment
		(start 157.53334 -112.992408)
		(end 156.01188 -111.470948)
		(width 0.127)
		(layer "In13.Cu")
		(net "SGPIO_OCP_V3_2_DATAOUT")
	)
	(segment
		(start 166.500048 -118.201948)
		(end 165.34384 -117.04574)
		(width 0.127)
		(layer "In13.Cu")
		(net "SGPIO_OCP_V3_2_DATAOUT")
	)
	(segment
		(start 165.34384 -117.04574)
		(end 158.87954 -117.04574)
		(width 0.127)
		(layer "In13.Cu")
		(net "SGPIO_OCP_V3_2_DATAOUT")
	)
	(segment
		(start 173.355762 -116.975382)
		(end 172.955712 -117.375432)
		(width 0.12954)
		(layer "F.Cu")
		(net "SGPIO_OCP_V3_2_DATAIN")
	)
	(segment
		(start 76.261976 -12.569444)
		(end 76.53274 -12.840208)
		(width 0.12954)
		(layer "F.Cu")
		(net "SGPIO_OCP_V3_2_DATAIN")
	)
	(segment
		(start 76.53274 -12.840208)
		(end 76.53274 -13.330428)
		(width 0.12954)
		(layer "F.Cu")
		(net "SGPIO_OCP_V3_2_DATAIN")
	)
	(segment
		(start 76.261976 -11.26998)
		(end 76.261976 -12.569444)
		(width 0.12954)
		(layer "F.Cu")
		(net "SGPIO_OCP_V3_2_DATAIN")
	)
	(segment
		(start 157.42793 -117.566948)
		(end 158.04388 -117.566948)
		(width 0.12954)
		(layer "F.Cu")
		(net "SGPIO_OCP_V3_2_DATAIN")
	)
	(via
		(at 172.955712 -117.375432)
		(size 0.4572)
		(drill 0.254)
		(layers "F.Cu" "B.Cu")
		(net "SGPIO_OCP_V3_2_DATAIN")
	)
	(via
		(at 113.84788 -82.189828)
		(size 0.508)
		(drill 0.254)
		(layers "F.Cu" "B.Cu")
		(net "SGPIO_OCP_V3_2_DATAIN")
	)
	(via
		(at 158.04388 -117.566948)
		(size 0.508)
		(drill 0.254)
		(layers "F.Cu" "B.Cu")
		(net "SGPIO_OCP_V3_2_DATAIN")
	)
	(via
		(at 150.04288 -82.443828)
		(size 0.508)
		(drill 0.254)
		(layers "F.Cu" "B.Cu")
		(net "SGPIO_OCP_V3_2_DATAIN")
	)
	(via
		(at 76.53274 -13.330428)
		(size 0.508)
		(drill 0.254)
		(layers "F.Cu" "B.Cu")
		(net "SGPIO_OCP_V3_2_DATAIN")
	)
	(segment
		(start 111.32566 -49.942242)
		(end 111.32566 -51.829462)
		(width 0.127)
		(layer "In2.Cu")
		(net "SGPIO_OCP_V3_2_DATAIN")
	)
	(segment
		(start 160.05048 -111.999268)
		(end 160.3248 -112.273588)
		(width 0.127)
		(layer "In2.Cu")
		(net "SGPIO_OCP_V3_2_DATAIN")
	)
	(segment
		(start 98.266504 -41.532048)
		(end 102.915466 -41.532048)
		(width 0.127)
		(layer "In2.Cu")
		(net "SGPIO_OCP_V3_2_DATAIN")
	)
	(segment
		(start 112.95888 -79.083408)
		(end 112.73282 -79.309468)
		(width 0.127)
		(layer "In2.Cu")
		(net "SGPIO_OCP_V3_2_DATAIN")
	)
	(segment
		(start 160.3248 -116.675408)
		(end 160.0581 -116.942108)
		(width 0.127)
		(layer "In2.Cu")
		(net "SGPIO_OCP_V3_2_DATAIN")
	)
	(segment
		(start 111.93018 -52.433982)
		(end 111.93018 -72.189848)
		(width 0.127)
		(layer "In2.Cu")
		(net "SGPIO_OCP_V3_2_DATAIN")
	)
	(segment
		(start 112.73282 -79.309468)
		(end 112.73282 -81.074768)
		(width 0.127)
		(layer "In2.Cu")
		(net "SGPIO_OCP_V3_2_DATAIN")
	)
	(segment
		(start 111.32566 -51.829462)
		(end 111.93018 -52.433982)
		(width 0.127)
		(layer "In2.Cu")
		(net "SGPIO_OCP_V3_2_DATAIN")
	)
	(segment
		(start 76.53274 -13.330428)
		(end 76.90866 -13.706348)
		(width 0.127)
		(layer "In2.Cu")
		(net "SGPIO_OCP_V3_2_DATAIN")
	)
	(segment
		(start 86.54288 -29.808424)
		(end 98.266504 -41.532048)
		(width 0.127)
		(layer "In2.Cu")
		(net "SGPIO_OCP_V3_2_DATAIN")
	)
	(segment
		(start 155.12288 -107.859068)
		(end 155.12288 -108.485432)
		(width 0.127)
		(layer "In2.Cu")
		(net "SGPIO_OCP_V3_2_DATAIN")
	)
	(segment
		(start 76.90866 -13.706348)
		(end 78.989682 -13.706348)
		(width 0.127)
		(layer "In2.Cu")
		(net "SGPIO_OCP_V3_2_DATAIN")
	)
	(segment
		(start 111.93018 -72.189848)
		(end 112.95888 -73.218548)
		(width 0.127)
		(layer "In2.Cu")
		(net "SGPIO_OCP_V3_2_DATAIN")
	)
	(segment
		(start 155.12288 -108.485432)
		(end 158.636716 -111.999268)
		(width 0.127)
		(layer "In2.Cu")
		(net "SGPIO_OCP_V3_2_DATAIN")
	)
	(segment
		(start 160.0581 -116.942108)
		(end 158.66872 -116.942108)
		(width 0.127)
		(layer "In2.Cu")
		(net "SGPIO_OCP_V3_2_DATAIN")
	)
	(segment
		(start 86.54288 -19.370294)
		(end 86.54288 -29.808424)
		(width 0.127)
		(layer "In2.Cu")
		(net "SGPIO_OCP_V3_2_DATAIN")
	)
	(segment
		(start 83.596734 -16.424148)
		(end 86.54288 -19.370294)
		(width 0.127)
		(layer "In2.Cu")
		(net "SGPIO_OCP_V3_2_DATAIN")
	)
	(segment
		(start 158.636716 -111.999268)
		(end 160.05048 -111.999268)
		(width 0.127)
		(layer "In2.Cu")
		(net "SGPIO_OCP_V3_2_DATAIN")
	)
	(segment
		(start 149.28088 -83.205828)
		(end 149.28088 -87.205312)
		(width 0.127)
		(layer "In2.Cu")
		(net "SGPIO_OCP_V3_2_DATAIN")
	)
	(segment
		(start 150.04288 -82.443828)
		(end 149.28088 -83.205828)
		(width 0.127)
		(layer "In2.Cu")
		(net "SGPIO_OCP_V3_2_DATAIN")
	)
	(segment
		(start 160.3248 -112.273588)
		(end 160.3248 -116.675408)
		(width 0.127)
		(layer "In2.Cu")
		(net "SGPIO_OCP_V3_2_DATAIN")
	)
	(segment
		(start 158.66872 -116.942108)
		(end 158.04388 -117.566948)
		(width 0.127)
		(layer "In2.Cu")
		(net "SGPIO_OCP_V3_2_DATAIN")
	)
	(segment
		(start 78.989682 -13.706348)
		(end 81.707482 -16.424148)
		(width 0.127)
		(layer "In2.Cu")
		(net "SGPIO_OCP_V3_2_DATAIN")
	)
	(segment
		(start 102.915466 -41.532048)
		(end 111.32566 -49.942242)
		(width 0.127)
		(layer "In2.Cu")
		(net "SGPIO_OCP_V3_2_DATAIN")
	)
	(segment
		(start 81.707482 -16.424148)
		(end 83.596734 -16.424148)
		(width 0.127)
		(layer "In2.Cu")
		(net "SGPIO_OCP_V3_2_DATAIN")
	)
	(segment
		(start 112.73282 -81.074768)
		(end 113.84788 -82.189828)
		(width 0.127)
		(layer "In2.Cu")
		(net "SGPIO_OCP_V3_2_DATAIN")
	)
	(segment
		(start 152.79878 -90.723212)
		(end 152.79878 -105.534968)
		(width 0.127)
		(layer "In2.Cu")
		(net "SGPIO_OCP_V3_2_DATAIN")
	)
	(segment
		(start 112.95888 -73.218548)
		(end 112.95888 -79.083408)
		(width 0.127)
		(layer "In2.Cu")
		(net "SGPIO_OCP_V3_2_DATAIN")
	)
	(segment
		(start 149.28088 -87.205312)
		(end 152.79878 -90.723212)
		(width 0.127)
		(layer "In2.Cu")
		(net "SGPIO_OCP_V3_2_DATAIN")
	)
	(segment
		(start 152.79878 -105.534968)
		(end 155.12288 -107.859068)
		(width 0.127)
		(layer "In2.Cu")
		(net "SGPIO_OCP_V3_2_DATAIN")
	)
	(segment
		(start 166.04488 -118.575328)
		(end 164.46627 -118.575328)
		(width 0.127)
		(layer "In6.Cu")
		(net "SGPIO_OCP_V3_2_DATAIN")
	)
	(segment
		(start 167.809926 -118.316248)
		(end 166.30396 -118.316248)
		(width 0.127)
		(layer "In6.Cu")
		(net "SGPIO_OCP_V3_2_DATAIN")
	)
	(segment
		(start 143.44396 -81.417668)
		(end 132.6896 -81.417668)
		(width 0.127)
		(layer "In6.Cu")
		(net "SGPIO_OCP_V3_2_DATAIN")
	)
	(segment
		(start 172.555916 -117.775228)
		(end 171.95038 -117.775228)
		(width 0.127)
		(layer "In6.Cu")
		(net "SGPIO_OCP_V3_2_DATAIN")
	)
	(segment
		(start 164.46627 -118.575328)
		(end 164.11956 -118.228618)
		(width 0.127)
		(layer "In6.Cu")
		(net "SGPIO_OCP_V3_2_DATAIN")
	)
	(segment
		(start 168.076626 -118.582948)
		(end 167.809926 -118.316248)
		(width 0.127)
		(layer "In6.Cu")
		(net "SGPIO_OCP_V3_2_DATAIN")
	)
	(segment
		(start 171.7548 -117.970808)
		(end 171.7548 -118.356888)
		(width 0.127)
		(layer "In6.Cu")
		(net "SGPIO_OCP_V3_2_DATAIN")
	)
	(segment
		(start 158.70555 -118.228618)
		(end 158.04388 -117.566948)
		(width 0.127)
		(layer "In6.Cu")
		(net "SGPIO_OCP_V3_2_DATAIN")
	)
	(segment
		(start 172.955712 -117.375432)
		(end 172.555916 -117.775228)
		(width 0.127)
		(layer "In6.Cu")
		(net "SGPIO_OCP_V3_2_DATAIN")
	)
	(segment
		(start 132.6896 -81.417668)
		(end 131.91744 -82.189828)
		(width 0.127)
		(layer "In6.Cu")
		(net "SGPIO_OCP_V3_2_DATAIN")
	)
	(segment
		(start 171.52874 -118.582948)
		(end 168.076626 -118.582948)
		(width 0.127)
		(layer "In6.Cu")
		(net "SGPIO_OCP_V3_2_DATAIN")
	)
	(segment
		(start 171.95038 -117.775228)
		(end 171.7548 -117.970808)
		(width 0.127)
		(layer "In6.Cu")
		(net "SGPIO_OCP_V3_2_DATAIN")
	)
	(segment
		(start 171.7548 -118.356888)
		(end 171.52874 -118.582948)
		(width 0.127)
		(layer "In6.Cu")
		(net "SGPIO_OCP_V3_2_DATAIN")
	)
	(segment
		(start 144.47012 -82.443828)
		(end 143.44396 -81.417668)
		(width 0.127)
		(layer "In6.Cu")
		(net "SGPIO_OCP_V3_2_DATAIN")
	)
	(segment
		(start 166.30396 -118.316248)
		(end 166.04488 -118.575328)
		(width 0.127)
		(layer "In6.Cu")
		(net "SGPIO_OCP_V3_2_DATAIN")
	)
	(segment
		(start 131.91744 -82.189828)
		(end 113.84788 -82.189828)
		(width 0.127)
		(layer "In6.Cu")
		(net "SGPIO_OCP_V3_2_DATAIN")
	)
	(segment
		(start 164.11956 -118.228618)
		(end 158.70555 -118.228618)
		(width 0.127)
		(layer "In6.Cu")
		(net "SGPIO_OCP_V3_2_DATAIN")
	)
	(segment
		(start 150.04288 -82.443828)
		(end 144.47012 -82.443828)
		(width 0.127)
		(layer "In6.Cu")
		(net "SGPIO_OCP_V3_2_DATAIN")
	)
	(segment
		(start 75.06208 -13.230352)
		(end 75.063096 -13.231368)
		(width 0.12954)
		(layer "F.Cu")
		(net "SGPIO_OCP_V3_2_CLK")
	)
	(segment
		(start 170.541696 -118.989348)
		(end 170.955716 -118.575328)
		(width 0.12954)
		(layer "F.Cu")
		(net "SGPIO_OCP_V3_2_CLK")
	)
	(segment
		(start 166.78148 -118.989348)
		(end 168.85158 -118.989348)
		(width 0.12954)
		(layer "F.Cu")
		(net "SGPIO_OCP_V3_2_CLK")
	)
	(segment
		(start 168.85158 -118.989348)
		(end 168.90746 -118.933468)
		(width 0.12954)
		(layer "F.Cu")
		(net "SGPIO_OCP_V3_2_CLK")
	)
	(segment
		(start 166.57828 -118.938548)
		(end 165.40988 -120.106948)
		(width 0.12954)
		(layer "F.Cu")
		(net "SGPIO_OCP_V3_2_CLK")
	)
	(segment
		(start 166.57828 -118.786148)
		(end 166.78148 -118.989348)
		(width 0.12954)
		(layer "F.Cu")
		(net "SGPIO_OCP_V3_2_CLK")
	)
	(segment
		(start 166.57828 -118.786148)
		(end 166.57828 -118.938548)
		(width 0.12954)
		(layer "F.Cu")
		(net "SGPIO_OCP_V3_2_CLK")
	)
	(segment
		(start 170.120056 -118.989348)
		(end 170.541696 -118.989348)
		(width 0.12954)
		(layer "F.Cu")
		(net "SGPIO_OCP_V3_2_CLK")
	)
	(segment
		(start 170.064176 -118.933468)
		(end 170.120056 -118.989348)
		(width 0.12954)
		(layer "F.Cu")
		(net "SGPIO_OCP_V3_2_CLK")
	)
	(segment
		(start 165.40988 -120.106948)
		(end 165.04793 -120.106948)
		(width 0.12954)
		(layer "F.Cu")
		(net "SGPIO_OCP_V3_2_CLK")
	)
	(segment
		(start 168.90746 -118.933468)
		(end 170.064176 -118.933468)
		(width 0.12954)
		(layer "F.Cu")
		(net "SGPIO_OCP_V3_2_CLK")
	)
	(segment
		(start 75.06208 -11.26998)
		(end 75.06208 -13.230352)
		(width 0.12954)
		(layer "F.Cu")
		(net "SGPIO_OCP_V3_2_CLK")
	)
	(via
		(at 166.57828 -118.786148)
		(size 0.508)
		(drill 0.254)
		(layers "F.Cu" "B.Cu")
		(net "SGPIO_OCP_V3_2_CLK")
	)
	(via
		(at 112.32388 -82.133948)
		(size 0.508)
		(drill 0.254)
		(layers "F.Cu" "B.Cu")
		(net "SGPIO_OCP_V3_2_CLK")
	)
	(via
		(at 75.063096 -13.231368)
		(size 0.508)
		(drill 0.254)
		(layers "F.Cu" "B.Cu")
		(net "SGPIO_OCP_V3_2_CLK")
	)
	(via
		(at 150.04288 -83.276948)
		(size 0.508)
		(drill 0.254)
		(layers "F.Cu" "B.Cu")
		(net "SGPIO_OCP_V3_2_CLK")
	)
	(segment
		(start 110.38586 -52.111656)
		(end 110.38586 -50.305462)
		(width 0.127)
		(layer "In2.Cu")
		(net "SGPIO_OCP_V3_2_CLK")
	)
	(segment
		(start 165.13556 -117.795548)
		(end 166.12616 -118.786148)
		(width 0.127)
		(layer "In2.Cu")
		(net "SGPIO_OCP_V3_2_CLK")
	)
	(segment
		(start 110.38586 -50.305462)
		(end 102.476046 -42.395648)
		(width 0.127)
		(layer "In2.Cu")
		(net "SGPIO_OCP_V3_2_CLK")
	)
	(segment
		(start 150.67788 -83.911948)
		(end 150.67788 -86.058248)
		(width 0.127)
		(layer "In2.Cu")
		(net "SGPIO_OCP_V3_2_CLK")
	)
	(segment
		(start 160.402524 -106.111548)
		(end 160.94583 -106.654854)
		(width 0.127)
		(layer "In2.Cu")
		(net "SGPIO_OCP_V3_2_CLK")
	)
	(segment
		(start 78.44028 -14.569948)
		(end 76.25588 -14.569948)
		(width 0.127)
		(layer "In2.Cu")
		(net "SGPIO_OCP_V3_2_CLK")
	)
	(segment
		(start 81.20888 -17.338548)
		(end 78.44028 -14.569948)
		(width 0.127)
		(layer "In2.Cu")
		(net "SGPIO_OCP_V3_2_CLK")
	)
	(segment
		(start 85.39988 -19.802348)
		(end 82.93608 -17.338548)
		(width 0.127)
		(layer "In2.Cu")
		(net "SGPIO_OCP_V3_2_CLK")
	)
	(segment
		(start 86.75878 -32.667448)
		(end 85.39988 -31.308548)
		(width 0.127)
		(layer "In2.Cu")
		(net "SGPIO_OCP_V3_2_CLK")
	)
	(segment
		(start 82.93608 -17.338548)
		(end 81.20888 -17.338548)
		(width 0.127)
		(layer "In2.Cu")
		(net "SGPIO_OCP_V3_2_CLK")
	)
	(segment
		(start 160.94583 -109.452918)
		(end 163.0172 -111.524288)
		(width 0.127)
		(layer "In2.Cu")
		(net "SGPIO_OCP_V3_2_CLK")
	)
	(segment
		(start 102.476046 -42.395648)
		(end 97.85858 -42.395648)
		(width 0.127)
		(layer "In2.Cu")
		(net "SGPIO_OCP_V3_2_CLK")
	)
	(segment
		(start 150.04288 -83.276948)
		(end 150.67788 -83.911948)
		(width 0.127)
		(layer "In2.Cu")
		(net "SGPIO_OCP_V3_2_CLK")
	)
	(segment
		(start 112.32388 -82.133948)
		(end 111.06658 -80.876648)
		(width 0.127)
		(layer "In2.Cu")
		(net "SGPIO_OCP_V3_2_CLK")
	)
	(segment
		(start 111.06658 -80.876648)
		(end 111.06658 -52.792376)
		(width 0.127)
		(layer "In2.Cu")
		(net "SGPIO_OCP_V3_2_CLK")
	)
	(segment
		(start 163.0172 -112.415828)
		(end 165.13556 -114.534188)
		(width 0.127)
		(layer "In2.Cu")
		(net "SGPIO_OCP_V3_2_CLK")
	)
	(segment
		(start 150.67788 -86.058248)
		(end 155.76296 -91.143328)
		(width 0.127)
		(layer "In2.Cu")
		(net "SGPIO_OCP_V3_2_CLK")
	)
	(segment
		(start 88.13038 -32.667448)
		(end 86.75878 -32.667448)
		(width 0.127)
		(layer "In2.Cu")
		(net "SGPIO_OCP_V3_2_CLK")
	)
	(segment
		(start 97.85858 -42.395648)
		(end 88.13038 -32.667448)
		(width 0.127)
		(layer "In2.Cu")
		(net "SGPIO_OCP_V3_2_CLK")
	)
	(segment
		(start 111.06658 -52.792376)
		(end 110.38586 -52.111656)
		(width 0.127)
		(layer "In2.Cu")
		(net "SGPIO_OCP_V3_2_CLK")
	)
	(segment
		(start 166.12616 -118.786148)
		(end 166.57828 -118.786148)
		(width 0.127)
		(layer "In2.Cu")
		(net "SGPIO_OCP_V3_2_CLK")
	)
	(segment
		(start 85.39988 -31.308548)
		(end 85.39988 -19.802348)
		(width 0.127)
		(layer "In2.Cu")
		(net "SGPIO_OCP_V3_2_CLK")
	)
	(segment
		(start 155.76296 -91.143328)
		(end 155.76296 -103.864156)
		(width 0.127)
		(layer "In2.Cu")
		(net "SGPIO_OCP_V3_2_CLK")
	)
	(segment
		(start 165.13556 -114.534188)
		(end 165.13556 -117.795548)
		(width 0.127)
		(layer "In2.Cu")
		(net "SGPIO_OCP_V3_2_CLK")
	)
	(segment
		(start 155.76296 -103.864156)
		(end 158.010352 -106.111548)
		(width 0.127)
		(layer "In2.Cu")
		(net "SGPIO_OCP_V3_2_CLK")
	)
	(segment
		(start 160.94583 -106.654854)
		(end 160.94583 -109.452918)
		(width 0.127)
		(layer "In2.Cu")
		(net "SGPIO_OCP_V3_2_CLK")
	)
	(segment
		(start 76.25588 -14.569948)
		(end 75.063096 -13.377164)
		(width 0.127)
		(layer "In2.Cu")
		(net "SGPIO_OCP_V3_2_CLK")
	)
	(segment
		(start 75.063096 -13.377164)
		(end 75.063096 -13.231368)
		(width 0.127)
		(layer "In2.Cu")
		(net "SGPIO_OCP_V3_2_CLK")
	)
	(segment
		(start 163.0172 -111.524288)
		(end 163.0172 -112.415828)
		(width 0.127)
		(layer "In2.Cu")
		(net "SGPIO_OCP_V3_2_CLK")
	)
	(segment
		(start 158.010352 -106.111548)
		(end 160.402524 -106.111548)
		(width 0.127)
		(layer "In2.Cu")
		(net "SGPIO_OCP_V3_2_CLK")
	)
	(segment
		(start 149.89556 -83.129628)
		(end 113.31956 -83.129628)
		(width 0.127)
		(layer "In6.Cu")
		(net "SGPIO_OCP_V3_2_CLK")
	)
	(segment
		(start 150.04288 -83.276948)
		(end 149.89556 -83.129628)
		(width 0.127)
		(layer "In6.Cu")
		(net "SGPIO_OCP_V3_2_CLK")
	)
	(segment
		(start 113.31956 -83.129628)
		(end 112.32388 -82.133948)
		(width 0.127)
		(layer "In6.Cu")
		(net "SGPIO_OCP_V3_2_CLK")
	)
	(segment
		(start 61.066934 -8.320024)
		(end 61.066934 -5.387594)
		(width 0.12954)
		(layer "F.Cu")
		(net "RST_SMB_OCP_V3_2_N")
	)
	(segment
		(start 152.81783 -114.137948)
		(end 152.48763 -113.807748)
		(width 0.12954)
		(layer "F.Cu")
		(net "RST_SMB_OCP_V3_2_N")
	)
	(segment
		(start 152.48763 -113.807748)
		(end 152.16632 -113.807748)
		(width 0.12954)
		(layer "F.Cu")
		(net "RST_SMB_OCP_V3_2_N")
	)
	(segment
		(start 61.066934 -5.387594)
		(end 61.29274 -5.161788)
		(width 0.12954)
		(layer "F.Cu")
		(net "RST_SMB_OCP_V3_2_N")
	)
	(via
		(at 152.16632 -113.807748)
		(size 0.508)
		(drill 0.254)
		(layers "F.Cu" "B.Cu")
		(net "RST_SMB_OCP_V3_2_N")
	)
	(via
		(at 61.29274 -5.161788)
		(size 0.508)
		(drill 0.254)
		(layers "F.Cu" "B.Cu")
		(net "RST_SMB_OCP_V3_2_N")
	)
	(via
		(at 129.87528 -111.242348)
		(size 0.508)
		(drill 0.254)
		(layers "F.Cu" "B.Cu")
		(net "RST_SMB_OCP_V3_2_N")
	)
	(segment
		(start 116.454174 -83.762088)
		(end 113.126774 -83.762088)
		(width 0.127)
		(layer "In2.Cu")
		(net "RST_SMB_OCP_V3_2_N")
	)
	(segment
		(start 120.309386 -97.427288)
		(end 118.18874 -95.306642)
		(width 0.127)
		(layer "In2.Cu")
		(net "RST_SMB_OCP_V3_2_N")
	)
	(segment
		(start 117.475 -84.782914)
		(end 116.454174 -83.762088)
		(width 0.127)
		(layer "In2.Cu")
		(net "RST_SMB_OCP_V3_2_N")
	)
	(segment
		(start 109.95406 -50.584354)
		(end 102.197154 -42.827448)
		(width 0.127)
		(layer "In2.Cu")
		(net "RST_SMB_OCP_V3_2_N")
	)
	(segment
		(start 88.117172 -35.12312)
		(end 84.91728 -31.923228)
		(width 0.127)
		(layer "In2.Cu")
		(net "RST_SMB_OCP_V3_2_N")
	)
	(segment
		(start 59.707526 -4.757928)
		(end 60.88888 -4.757928)
		(width 0.127)
		(layer "In2.Cu")
		(net "RST_SMB_OCP_V3_2_N")
	)
	(segment
		(start 123.44654 -100.086668)
		(end 120.78716 -97.427288)
		(width 0.127)
		(layer "In2.Cu")
		(net "RST_SMB_OCP_V3_2_N")
	)
	(segment
		(start 110.63478 -53.063394)
		(end 109.95406 -52.382674)
		(width 0.127)
		(layer "In2.Cu")
		(net "RST_SMB_OCP_V3_2_N")
	)
	(segment
		(start 97.597976 -42.827448)
		(end 89.893648 -35.12312)
		(width 0.127)
		(layer "In2.Cu")
		(net "RST_SMB_OCP_V3_2_N")
	)
	(segment
		(start 61.52388 -14.399768)
		(end 60.42406 -14.399768)
		(width 0.127)
		(layer "In2.Cu")
		(net "RST_SMB_OCP_V3_2_N")
	)
	(segment
		(start 59.28614 -5.179314)
		(end 59.707526 -4.757928)
		(width 0.127)
		(layer "In2.Cu")
		(net "RST_SMB_OCP_V3_2_N")
	)
	(segment
		(start 109.95406 -52.382674)
		(end 109.95406 -50.584354)
		(width 0.127)
		(layer "In2.Cu")
		(net "RST_SMB_OCP_V3_2_N")
	)
	(segment
		(start 123.44654 -100.978208)
		(end 123.44654 -100.086668)
		(width 0.127)
		(layer "In2.Cu")
		(net "RST_SMB_OCP_V3_2_N")
	)
	(segment
		(start 60.88888 -4.757928)
		(end 61.29274 -5.161788)
		(width 0.127)
		(layer "In2.Cu")
		(net "RST_SMB_OCP_V3_2_N")
	)
	(segment
		(start 118.18874 -95.306642)
		(end 118.18874 -88.181688)
		(width 0.127)
		(layer "In2.Cu")
		(net "RST_SMB_OCP_V3_2_N")
	)
	(segment
		(start 130.23342 -110.884208)
		(end 130.23342 -107.866688)
		(width 0.127)
		(layer "In2.Cu")
		(net "RST_SMB_OCP_V3_2_N")
	)
	(segment
		(start 84.91728 -31.923228)
		(end 84.91728 -19.980148)
		(width 0.127)
		(layer "In2.Cu")
		(net "RST_SMB_OCP_V3_2_N")
	)
	(segment
		(start 102.197154 -42.827448)
		(end 97.597976 -42.827448)
		(width 0.127)
		(layer "In2.Cu")
		(net "RST_SMB_OCP_V3_2_N")
	)
	(segment
		(start 130.23342 -107.866688)
		(end 127.907542 -105.54081)
		(width 0.127)
		(layer "In2.Cu")
		(net "RST_SMB_OCP_V3_2_N")
	)
	(segment
		(start 89.893648 -35.12312)
		(end 88.117172 -35.12312)
		(width 0.127)
		(layer "In2.Cu")
		(net "RST_SMB_OCP_V3_2_N")
	)
	(segment
		(start 60.42406 -14.399768)
		(end 59.28614 -13.261848)
		(width 0.127)
		(layer "In2.Cu")
		(net "RST_SMB_OCP_V3_2_N")
	)
	(segment
		(start 124.07392 -101.605588)
		(end 123.44654 -100.978208)
		(width 0.127)
		(layer "In2.Cu")
		(net "RST_SMB_OCP_V3_2_N")
	)
	(segment
		(start 76.02728 -15.001748)
		(end 75.4253 -14.399768)
		(width 0.127)
		(layer "In2.Cu")
		(net "RST_SMB_OCP_V3_2_N")
	)
	(segment
		(start 127.907542 -105.54081)
		(end 127.907542 -103.292656)
		(width 0.127)
		(layer "In2.Cu")
		(net "RST_SMB_OCP_V3_2_N")
	)
	(segment
		(start 126.220474 -101.605588)
		(end 124.07392 -101.605588)
		(width 0.127)
		(layer "In2.Cu")
		(net "RST_SMB_OCP_V3_2_N")
	)
	(segment
		(start 127.907542 -103.292656)
		(end 126.220474 -101.605588)
		(width 0.127)
		(layer "In2.Cu")
		(net "RST_SMB_OCP_V3_2_N")
	)
	(segment
		(start 81.00568 -17.770348)
		(end 78.23708 -15.001748)
		(width 0.127)
		(layer "In2.Cu")
		(net "RST_SMB_OCP_V3_2_N")
	)
	(segment
		(start 78.23708 -15.001748)
		(end 76.02728 -15.001748)
		(width 0.127)
		(layer "In2.Cu")
		(net "RST_SMB_OCP_V3_2_N")
	)
	(segment
		(start 62.2173 -13.706348)
		(end 61.52388 -14.399768)
		(width 0.127)
		(layer "In2.Cu")
		(net "RST_SMB_OCP_V3_2_N")
	)
	(segment
		(start 129.87528 -111.242348)
		(end 130.23342 -110.884208)
		(width 0.127)
		(layer "In2.Cu")
		(net "RST_SMB_OCP_V3_2_N")
	)
	(segment
		(start 110.63478 -81.270094)
		(end 110.63478 -53.063394)
		(width 0.127)
		(layer "In2.Cu")
		(net "RST_SMB_OCP_V3_2_N")
	)
	(segment
		(start 70.41388 -14.399768)
		(end 69.72046 -13.706348)
		(width 0.127)
		(layer "In2.Cu")
		(net "RST_SMB_OCP_V3_2_N")
	)
	(segment
		(start 69.72046 -13.706348)
		(end 62.2173 -13.706348)
		(width 0.127)
		(layer "In2.Cu")
		(net "RST_SMB_OCP_V3_2_N")
	)
	(segment
		(start 120.78716 -97.427288)
		(end 120.309386 -97.427288)
		(width 0.127)
		(layer "In2.Cu")
		(net "RST_SMB_OCP_V3_2_N")
	)
	(segment
		(start 75.4253 -14.399768)
		(end 70.41388 -14.399768)
		(width 0.127)
		(layer "In2.Cu")
		(net "RST_SMB_OCP_V3_2_N")
	)
	(segment
		(start 113.126774 -83.762088)
		(end 110.63478 -81.270094)
		(width 0.127)
		(layer "In2.Cu")
		(net "RST_SMB_OCP_V3_2_N")
	)
	(segment
		(start 117.475 -87.467948)
		(end 117.475 -84.782914)
		(width 0.127)
		(layer "In2.Cu")
		(net "RST_SMB_OCP_V3_2_N")
	)
	(segment
		(start 82.70748 -17.770348)
		(end 81.00568 -17.770348)
		(width 0.127)
		(layer "In2.Cu")
		(net "RST_SMB_OCP_V3_2_N")
	)
	(segment
		(start 59.28614 -13.261848)
		(end 59.28614 -5.179314)
		(width 0.127)
		(layer "In2.Cu")
		(net "RST_SMB_OCP_V3_2_N")
	)
	(segment
		(start 118.18874 -88.181688)
		(end 117.475 -87.467948)
		(width 0.127)
		(layer "In2.Cu")
		(net "RST_SMB_OCP_V3_2_N")
	)
	(segment
		(start 84.91728 -19.980148)
		(end 82.70748 -17.770348)
		(width 0.127)
		(layer "In2.Cu")
		(net "RST_SMB_OCP_V3_2_N")
	)
	(segment
		(start 145.86204 -109.79404)
		(end 131.323588 -109.79404)
		(width 0.127)
		(layer "In6.Cu")
		(net "RST_SMB_OCP_V3_2_N")
	)
	(segment
		(start 131.323588 -109.79404)
		(end 129.87528 -111.242348)
		(width 0.127)
		(layer "In6.Cu")
		(net "RST_SMB_OCP_V3_2_N")
	)
	(segment
		(start 149.875748 -113.807748)
		(end 145.86204 -109.79404)
		(width 0.127)
		(layer "In6.Cu")
		(net "RST_SMB_OCP_V3_2_N")
	)
	(segment
		(start 152.16632 -113.807748)
		(end 149.875748 -113.807748)
		(width 0.127)
		(layer "In6.Cu")
		(net "RST_SMB_OCP_V3_2_N")
	)
	(segment
		(start 435.56682 -7.101586)
		(end 435.505606 -7.040372)
		(width 0.12954)
		(layer "F.Cu")
		(net "RST_SMB_OCP_SFF_N")
	)
	(segment
		(start 463.963004 -92.387674)
		(end 464.614006 -92.387674)
		(width 0.12954)
		(layer "F.Cu")
		(net "RST_SMB_OCP_SFF_N")
	)
	(segment
		(start 435.505606 -7.040372)
		(end 435.505606 -5.476748)
		(width 0.12954)
		(layer "F.Cu")
		(net "RST_SMB_OCP_SFF_N")
	)
	(segment
		(start 435.56682 -8.320024)
		(end 435.56682 -7.101586)
		(width 0.12954)
		(layer "F.Cu")
		(net "RST_SMB_OCP_SFF_N")
	)
	(via
		(at 440.41568 -38.445948)
		(size 0.508)
		(drill 0.254)
		(layers "F.Cu" "B.Cu")
		(net "RST_SMB_OCP_SFF_N")
	)
	(via
		(at 464.614006 -92.387674)
		(size 0.508)
		(drill 0.254)
		(layers "F.Cu" "B.Cu")
		(net "RST_SMB_OCP_SFF_N")
	)
	(via
		(at 435.505606 -5.476748)
		(size 0.508)
		(drill 0.254)
		(layers "F.Cu" "B.Cu")
		(net "RST_SMB_OCP_SFF_N")
	)
	(segment
		(start 460.43088 -87.950548)
		(end 464.614006 -92.133674)
		(width 0.12954)
		(layer "B.Cu")
		(net "RST_SMB_OCP_SFF_N")
	)
	(segment
		(start 438.167526 -59.993276)
		(end 438.167526 -78.829408)
		(width 0.12954)
		(layer "B.Cu")
		(net "RST_SMB_OCP_SFF_N")
	)
	(segment
		(start 438.167526 -78.829408)
		(end 447.288666 -87.950548)
		(width 0.12954)
		(layer "B.Cu")
		(net "RST_SMB_OCP_SFF_N")
	)
	(segment
		(start 443.38748 -41.417748)
		(end 450.85508 -41.417748)
		(width 0.12954)
		(layer "B.Cu")
		(net "RST_SMB_OCP_SFF_N")
	)
	(segment
		(start 447.252344 -44.73067)
		(end 445.345058 -44.73067)
		(width 0.12954)
		(layer "B.Cu")
		(net "RST_SMB_OCP_SFF_N")
	)
	(segment
		(start 464.614006 -92.133674)
		(end 464.614006 -92.387674)
		(width 0.12954)
		(layer "B.Cu")
		(net "RST_SMB_OCP_SFF_N")
	)
	(segment
		(start 440.41568 -38.445948)
		(end 443.38748 -41.417748)
		(width 0.12954)
		(layer "B.Cu")
		(net "RST_SMB_OCP_SFF_N")
	)
	(segment
		(start 450.57314 -43.645328)
		(end 448.337686 -43.645328)
		(width 0.12954)
		(layer "B.Cu")
		(net "RST_SMB_OCP_SFF_N")
	)
	(segment
		(start 450.85508 -41.417748)
		(end 451.503796 -42.066464)
		(width 0.12954)
		(layer "B.Cu")
		(net "RST_SMB_OCP_SFF_N")
	)
	(segment
		(start 451.503796 -42.714672)
		(end 450.57314 -43.645328)
		(width 0.12954)
		(layer "B.Cu")
		(net "RST_SMB_OCP_SFF_N")
	)
	(segment
		(start 438.4802 -51.595528)
		(end 438.4802 -59.680602)
		(width 0.12954)
		(layer "B.Cu")
		(net "RST_SMB_OCP_SFF_N")
	)
	(segment
		(start 447.288666 -87.950548)
		(end 460.43088 -87.950548)
		(width 0.12954)
		(layer "B.Cu")
		(net "RST_SMB_OCP_SFF_N")
	)
	(segment
		(start 438.4802 -59.680602)
		(end 438.167526 -59.993276)
		(width 0.12954)
		(layer "B.Cu")
		(net "RST_SMB_OCP_SFF_N")
	)
	(segment
		(start 451.503796 -42.066464)
		(end 451.503796 -42.714672)
		(width 0.12954)
		(layer "B.Cu")
		(net "RST_SMB_OCP_SFF_N")
	)
	(segment
		(start 445.345058 -44.73067)
		(end 438.4802 -51.595528)
		(width 0.12954)
		(layer "B.Cu")
		(net "RST_SMB_OCP_SFF_N")
	)
	(segment
		(start 448.337686 -43.645328)
		(end 447.252344 -44.73067)
		(width 0.12954)
		(layer "B.Cu")
		(net "RST_SMB_OCP_SFF_N")
	)
	(segment
		(start 436.58028 -12.131548)
		(end 434.5051 -14.206728)
		(width 0.127)
		(layer "In6.Cu")
		(net "RST_SMB_OCP_SFF_N")
	)
	(segment
		(start 435.505606 -5.476748)
		(end 435.505606 -7.754874)
		(width 0.127)
		(layer "In6.Cu")
		(net "RST_SMB_OCP_SFF_N")
	)
	(segment
		(start 435.053232 -36.7919)
		(end 439.191654 -36.7919)
		(width 0.127)
		(layer "In6.Cu")
		(net "RST_SMB_OCP_SFF_N")
	)
	(segment
		(start 440.41568 -38.015926)
		(end 440.41568 -38.445948)
		(width 0.127)
		(layer "In6.Cu")
		(net "RST_SMB_OCP_SFF_N")
	)
	(segment
		(start 434.762148 -18.322036)
		(end 434.762148 -19.896582)
		(width 0.127)
		(layer "In6.Cu")
		(net "RST_SMB_OCP_SFF_N")
	)
	(segment
		(start 435.505606 -7.754874)
		(end 436.58028 -8.829548)
		(width 0.127)
		(layer "In6.Cu")
		(net "RST_SMB_OCP_SFF_N")
	)
	(segment
		(start 434.5051 -18.064988)
		(end 434.762148 -18.322036)
		(width 0.127)
		(layer "In6.Cu")
		(net "RST_SMB_OCP_SFF_N")
	)
	(segment
		(start 434.762148 -19.896582)
		(end 432.10988 -22.54885)
		(width 0.127)
		(layer "In6.Cu")
		(net "RST_SMB_OCP_SFF_N")
	)
	(segment
		(start 434.5051 -14.206728)
		(end 434.5051 -18.064988)
		(width 0.127)
		(layer "In6.Cu")
		(net "RST_SMB_OCP_SFF_N")
	)
	(segment
		(start 436.58028 -8.829548)
		(end 436.58028 -12.131548)
		(width 0.127)
		(layer "In6.Cu")
		(net "RST_SMB_OCP_SFF_N")
	)
	(segment
		(start 432.10988 -22.54885)
		(end 432.10988 -33.848548)
		(width 0.127)
		(layer "In6.Cu")
		(net "RST_SMB_OCP_SFF_N")
	)
	(segment
		(start 432.10988 -33.848548)
		(end 435.053232 -36.7919)
		(width 0.127)
		(layer "In6.Cu")
		(net "RST_SMB_OCP_SFF_N")
	)
	(segment
		(start 439.191654 -36.7919)
		(end 440.41568 -38.015926)
		(width 0.127)
		(layer "In6.Cu")
		(net "RST_SMB_OCP_SFF_N")
	)
	(segment
		(start 77.461872 -8.320024)
		(end 77.462126 -8.31977)
		(width 0.12954)
		(layer "F.Cu")
		(net "RST_PERST3_OCP_V3_2_N")
	)
	(segment
		(start 77.462126 -8.31977)
		(end 77.462126 -8.319262)
		(width 0.12954)
		(layer "F.Cu")
		(net "RST_PERST3_OCP_V3_2_N")
	)
	(segment
		(start 106.876088 -38.983158)
		(end 109.16412 -38.983158)
		(width 0.12954)
		(layer "F.Cu")
		(net "RST_PERST3_OCP_V3_2_N")
	)
	(segment
		(start 77.462126 -8.319262)
		(end 77.462888 -8.3185)
		(width 0.12954)
		(layer "F.Cu")
		(net "RST_PERST3_OCP_V3_2_N")
	)
	(segment
		(start 77.462888 -8.3185)
		(end 77.462888 -7.203948)
		(width 0.12954)
		(layer "F.Cu")
		(net "RST_PERST3_OCP_V3_2_N")
	)
	(via
		(at 109.16412 -38.983158)
		(size 0.508)
		(drill 0.254)
		(layers "F.Cu" "B.Cu")
		(net "RST_PERST3_OCP_V3_2_N")
	)
	(via
		(at 77.462888 -7.203948)
		(size 0.508)
		(drill 0.254)
		(layers "F.Cu" "B.Cu")
		(net "RST_PERST3_OCP_V3_2_N")
	)
	(segment
		(start 89.022174 -28.946602)
		(end 91.71432 -31.638748)
		(width 0.127)
		(layer "In2.Cu")
		(net "RST_PERST3_OCP_V3_2_N")
	)
	(segment
		(start 91.71432 -31.638748)
		(end 93.038168 -31.638748)
		(width 0.127)
		(layer "In2.Cu")
		(net "RST_PERST3_OCP_V3_2_N")
	)
	(segment
		(start 94.255844 -33.278572)
		(end 97.027746 -36.050474)
		(width 0.127)
		(layer "In2.Cu")
		(net "RST_PERST3_OCP_V3_2_N")
	)
	(segment
		(start 77.462888 -7.203948)
		(end 77.462888 -7.7978)
		(width 0.127)
		(layer "In2.Cu")
		(net "RST_PERST3_OCP_V3_2_N")
	)
	(segment
		(start 97.027746 -36.050474)
		(end 106.231436 -36.050474)
		(width 0.127)
		(layer "In2.Cu")
		(net "RST_PERST3_OCP_V3_2_N")
	)
	(segment
		(start 89.022174 -18.56867)
		(end 89.022174 -28.946602)
		(width 0.127)
		(layer "In2.Cu")
		(net "RST_PERST3_OCP_V3_2_N")
	)
	(segment
		(start 94.255844 -32.856424)
		(end 94.255844 -33.278572)
		(width 0.127)
		(layer "In2.Cu")
		(net "RST_PERST3_OCP_V3_2_N")
	)
	(segment
		(start 84.57946 -14.125956)
		(end 89.022174 -18.56867)
		(width 0.127)
		(layer "In2.Cu")
		(net "RST_PERST3_OCP_V3_2_N")
	)
	(segment
		(start 106.231436 -36.050474)
		(end 109.16412 -38.983158)
		(width 0.127)
		(layer "In2.Cu")
		(net "RST_PERST3_OCP_V3_2_N")
	)
	(segment
		(start 79.277972 -9.612884)
		(end 79.277972 -10.938764)
		(width 0.127)
		(layer "In2.Cu")
		(net "RST_PERST3_OCP_V3_2_N")
	)
	(segment
		(start 79.277972 -10.938764)
		(end 82.465164 -14.125956)
		(width 0.127)
		(layer "In2.Cu")
		(net "RST_PERST3_OCP_V3_2_N")
	)
	(segment
		(start 77.462888 -7.7978)
		(end 79.277972 -9.612884)
		(width 0.127)
		(layer "In2.Cu")
		(net "RST_PERST3_OCP_V3_2_N")
	)
	(segment
		(start 93.038168 -31.638748)
		(end 94.255844 -32.856424)
		(width 0.127)
		(layer "In2.Cu")
		(net "RST_PERST3_OCP_V3_2_N")
	)
	(segment
		(start 82.465164 -14.125956)
		(end 84.57946 -14.125956)
		(width 0.127)
		(layer "In2.Cu")
		(net "RST_PERST3_OCP_V3_2_N")
	)
	(segment
		(start 78.062074 -6.872732)
		(end 77.451458 -6.262116)
		(width 0.12954)
		(layer "F.Cu")
		(net "RST_PERST2_OCP_V3_2_N")
	)
	(segment
		(start 106.876088 -37.940742)
		(end 109.16412 -37.940742)
		(width 0.12954)
		(layer "F.Cu")
		(net "RST_PERST2_OCP_V3_2_N")
	)
	(segment
		(start 78.062074 -8.320024)
		(end 78.062074 -6.872732)
		(width 0.12954)
		(layer "F.Cu")
		(net "RST_PERST2_OCP_V3_2_N")
	)
	(via
		(at 77.451458 -6.262116)
		(size 0.508)
		(drill 0.254)
		(layers "F.Cu" "B.Cu")
		(net "RST_PERST2_OCP_V3_2_N")
	)
	(via
		(at 109.16412 -37.940742)
		(size 0.762)
		(drill 0.254)
		(layers "F.Cu" "B.Cu")
		(net "RST_PERST2_OCP_V3_2_N")
	)
	(segment
		(start 84.764118 -13.680186)
		(end 82.630518 -13.680186)
		(width 0.127)
		(layer "In2.Cu")
		(net "RST_PERST2_OCP_V3_2_N")
	)
	(segment
		(start 95.439992 -32.914082)
		(end 94.926658 -32.914082)
		(width 0.127)
		(layer "In2.Cu")
		(net "RST_PERST2_OCP_V3_2_N")
	)
	(segment
		(start 95.715074 -33.189164)
		(end 95.439992 -32.914082)
		(width 0.127)
		(layer "In2.Cu")
		(net "RST_PERST2_OCP_V3_2_N")
	)
	(segment
		(start 97.473008 -35.604704)
		(end 95.715074 -33.84677)
		(width 0.127)
		(layer "In2.Cu")
		(net "RST_PERST2_OCP_V3_2_N")
	)
	(segment
		(start 82.630518 -13.680186)
		(end 79.726536 -10.776204)
		(width 0.127)
		(layer "In2.Cu")
		(net "RST_PERST2_OCP_V3_2_N")
	)
	(segment
		(start 77.98308 -7.676642)
		(end 77.98308 -6.793738)
		(width 0.127)
		(layer "In2.Cu")
		(net "RST_PERST2_OCP_V3_2_N")
	)
	(segment
		(start 109.16412 -37.940742)
		(end 106.828082 -35.604704)
		(width 0.127)
		(layer "In2.Cu")
		(net "RST_PERST2_OCP_V3_2_N")
	)
	(segment
		(start 95.715074 -33.84677)
		(end 95.715074 -33.189164)
		(width 0.127)
		(layer "In2.Cu")
		(net "RST_PERST2_OCP_V3_2_N")
	)
	(segment
		(start 77.98308 -6.793738)
		(end 77.451458 -6.262116)
		(width 0.127)
		(layer "In2.Cu")
		(net "RST_PERST2_OCP_V3_2_N")
	)
	(segment
		(start 79.726536 -10.776204)
		(end 79.726536 -9.420098)
		(width 0.127)
		(layer "In2.Cu")
		(net "RST_PERST2_OCP_V3_2_N")
	)
	(segment
		(start 94.926658 -32.914082)
		(end 89.467944 -27.455368)
		(width 0.127)
		(layer "In2.Cu")
		(net "RST_PERST2_OCP_V3_2_N")
	)
	(segment
		(start 89.467944 -18.384012)
		(end 84.764118 -13.680186)
		(width 0.127)
		(layer "In2.Cu")
		(net "RST_PERST2_OCP_V3_2_N")
	)
	(segment
		(start 106.828082 -35.604704)
		(end 97.473008 -35.604704)
		(width 0.127)
		(layer "In2.Cu")
		(net "RST_PERST2_OCP_V3_2_N")
	)
	(segment
		(start 89.467944 -27.455368)
		(end 89.467944 -18.384012)
		(width 0.127)
		(layer "In2.Cu")
		(net "RST_PERST2_OCP_V3_2_N")
	)
	(segment
		(start 79.726536 -9.420098)
		(end 77.98308 -7.676642)
		(width 0.127)
		(layer "In2.Cu")
		(net "RST_PERST2_OCP_V3_2_N")
	)
	(segment
		(start 59.867038 -5.482844)
		(end 59.868054 -5.481828)
		(width 0.12954)
		(layer "F.Cu")
		(net "RST_PERST1_OCP_V3_2_N")
	)
	(segment
		(start 106.876088 -41.012364)
		(end 109.16412 -41.012364)
		(width 0.12954)
		(layer "F.Cu")
		(net "RST_PERST1_OCP_V3_2_N")
	)
	(segment
		(start 59.867038 -8.320024)
		(end 59.867038 -5.482844)
		(width 0.12954)
		(layer "F.Cu")
		(net "RST_PERST1_OCP_V3_2_N")
	)
	(via
		(at 109.16412 -41.012364)
		(size 0.508)
		(drill 0.254)
		(layers "F.Cu" "B.Cu")
		(net "RST_PERST1_OCP_V3_2_N")
	)
	(via
		(at 59.868054 -5.481828)
		(size 0.508)
		(drill 0.254)
		(layers "F.Cu" "B.Cu")
		(net "RST_PERST1_OCP_V3_2_N")
	)
	(segment
		(start 61.087 -6.294882)
		(end 61.087 -7.549388)
		(width 0.127)
		(layer "In2.Cu")
		(net "RST_PERST1_OCP_V3_2_N")
	)
	(segment
		(start 61.55944 -8.021828)
		(end 69.34962 -8.021828)
		(width 0.127)
		(layer "In2.Cu")
		(net "RST_PERST1_OCP_V3_2_N")
	)
	(segment
		(start 61.087 -7.549388)
		(end 61.55944 -8.021828)
		(width 0.127)
		(layer "In2.Cu")
		(net "RST_PERST1_OCP_V3_2_N")
	)
	(segment
		(start 88.550242 -18.76425)
		(end 88.550242 -29.371798)
		(width 0.127)
		(layer "In2.Cu")
		(net "RST_PERST1_OCP_V3_2_N")
	)
	(segment
		(start 77.672692 -8.914384)
		(end 78.705456 -9.947148)
		(width 0.127)
		(layer "In2.Cu")
		(net "RST_PERST1_OCP_V3_2_N")
	)
	(segment
		(start 76.326746 -8.914384)
		(end 77.672692 -8.914384)
		(width 0.127)
		(layer "In2.Cu")
		(net "RST_PERST1_OCP_V3_2_N")
	)
	(segment
		(start 60.273946 -5.481828)
		(end 61.087 -6.294882)
		(width 0.127)
		(layer "In2.Cu")
		(net "RST_PERST1_OCP_V3_2_N")
	)
	(segment
		(start 78.705456 -9.947148)
		(end 78.705456 -10.977372)
		(width 0.127)
		(layer "In2.Cu")
		(net "RST_PERST1_OCP_V3_2_N")
	)
	(segment
		(start 82.325972 -14.597888)
		(end 84.38388 -14.597888)
		(width 0.127)
		(layer "In2.Cu")
		(net "RST_PERST1_OCP_V3_2_N")
	)
	(segment
		(start 75.824588 -9.416542)
		(end 76.326746 -8.914384)
		(width 0.127)
		(layer "In2.Cu")
		(net "RST_PERST1_OCP_V3_2_N")
	)
	(segment
		(start 84.38388 -14.597888)
		(end 88.550242 -18.76425)
		(width 0.127)
		(layer "In2.Cu")
		(net "RST_PERST1_OCP_V3_2_N")
	)
	(segment
		(start 96.880426 -36.522406)
		(end 104.674162 -36.522406)
		(width 0.127)
		(layer "In2.Cu")
		(net "RST_PERST1_OCP_V3_2_N")
	)
	(segment
		(start 59.868054 -5.481828)
		(end 60.273946 -5.481828)
		(width 0.127)
		(layer "In2.Cu")
		(net "RST_PERST1_OCP_V3_2_N")
	)
	(segment
		(start 92.163392 -32.984948)
		(end 93.342968 -32.984948)
		(width 0.127)
		(layer "In2.Cu")
		(net "RST_PERST1_OCP_V3_2_N")
	)
	(segment
		(start 88.550242 -29.371798)
		(end 92.163392 -32.984948)
		(width 0.127)
		(layer "In2.Cu")
		(net "RST_PERST1_OCP_V3_2_N")
	)
	(segment
		(start 78.705456 -10.977372)
		(end 82.325972 -14.597888)
		(width 0.127)
		(layer "In2.Cu")
		(net "RST_PERST1_OCP_V3_2_N")
	)
	(segment
		(start 70.744334 -9.416542)
		(end 75.824588 -9.416542)
		(width 0.127)
		(layer "In2.Cu")
		(net "RST_PERST1_OCP_V3_2_N")
	)
	(segment
		(start 69.34962 -8.021828)
		(end 70.744334 -9.416542)
		(width 0.127)
		(layer "In2.Cu")
		(net "RST_PERST1_OCP_V3_2_N")
	)
	(segment
		(start 104.674162 -36.522406)
		(end 109.16412 -41.012364)
		(width 0.127)
		(layer "In2.Cu")
		(net "RST_PERST1_OCP_V3_2_N")
	)
	(segment
		(start 93.342968 -32.984948)
		(end 96.880426 -36.522406)
		(width 0.127)
		(layer "In2.Cu")
		(net "RST_PERST1_OCP_V3_2_N")
	)
	(segment
		(start 60.466986 -11.26998)
		(end 60.466986 -13.360654)
		(width 0.12954)
		(layer "F.Cu")
		(net "RST_PERST0_OCP_V3_2_N")
	)
	(segment
		(start 106.876088 -39.996364)
		(end 109.16412 -39.996364)
		(width 0.12954)
		(layer "F.Cu")
		(net "RST_PERST0_OCP_V3_2_N")
	)
	(segment
		(start 60.466986 -13.360654)
		(end 60.91428 -13.807948)
		(width 0.12954)
		(layer "F.Cu")
		(net "RST_PERST0_OCP_V3_2_N")
	)
	(via
		(at 109.16412 -39.996364)
		(size 0.508)
		(drill 0.254)
		(layers "F.Cu" "B.Cu")
		(net "RST_PERST0_OCP_V3_2_N")
	)
	(via
		(at 60.91428 -13.807948)
		(size 0.508)
		(drill 0.254)
		(layers "F.Cu" "B.Cu")
		(net "RST_PERST0_OCP_V3_2_N")
	)
	(segment
		(start 109.16412 -39.996364)
		(end 109.93882 -40.771064)
		(width 0.127)
		(layer "In2.Cu")
		(net "RST_PERST0_OCP_V3_2_N")
	)
	(segment
		(start 93.210888 -33.505648)
		(end 92.072968 -33.505648)
		(width 0.127)
		(layer "In2.Cu")
		(net "RST_PERST0_OCP_V3_2_N")
	)
	(segment
		(start 69.525134 -11.608308)
		(end 61.36132 -11.608308)
		(width 0.127)
		(layer "In2.Cu")
		(net "RST_PERST0_OCP_V3_2_N")
	)
	(segment
		(start 109.93882 -40.771064)
		(end 109.93882 -41.232328)
		(width 0.127)
		(layer "In2.Cu")
		(net "RST_PERST0_OCP_V3_2_N")
	)
	(segment
		(start 71.12889 -10.004552)
		(end 69.525134 -11.608308)
		(width 0.127)
		(layer "In2.Cu")
		(net "RST_PERST0_OCP_V3_2_N")
	)
	(segment
		(start 73.914 -11.608308)
		(end 72.310244 -10.004552)
		(width 0.127)
		(layer "In2.Cu")
		(net "RST_PERST0_OCP_V3_2_N")
	)
	(segment
		(start 60.91428 -12.055348)
		(end 60.91428 -13.807948)
		(width 0.127)
		(layer "In2.Cu")
		(net "RST_PERST0_OCP_V3_2_N")
	)
	(segment
		(start 88.10498 -19.025108)
		(end 84.123022 -15.04315)
		(width 0.127)
		(layer "In2.Cu")
		(net "RST_PERST0_OCP_V3_2_N")
	)
	(segment
		(start 84.123022 -15.04315)
		(end 82.16011 -15.04315)
		(width 0.127)
		(layer "In2.Cu")
		(net "RST_PERST0_OCP_V3_2_N")
	)
	(segment
		(start 82.16011 -15.04315)
		(end 78.724506 -11.608308)
		(width 0.127)
		(layer "In2.Cu")
		(net "RST_PERST0_OCP_V3_2_N")
	)
	(segment
		(start 92.072968 -33.505648)
		(end 88.10498 -29.53766)
		(width 0.127)
		(layer "In2.Cu")
		(net "RST_PERST0_OCP_V3_2_N")
	)
	(segment
		(start 109.3978 -41.773348)
		(end 108.9914 -41.773348)
		(width 0.127)
		(layer "In2.Cu")
		(net "RST_PERST0_OCP_V3_2_N")
	)
	(segment
		(start 109.93882 -41.232328)
		(end 109.3978 -41.773348)
		(width 0.127)
		(layer "In2.Cu")
		(net "RST_PERST0_OCP_V3_2_N")
	)
	(segment
		(start 61.36132 -11.608308)
		(end 60.91428 -12.055348)
		(width 0.127)
		(layer "In2.Cu")
		(net "RST_PERST0_OCP_V3_2_N")
	)
	(segment
		(start 96.672908 -36.967668)
		(end 93.210888 -33.505648)
		(width 0.127)
		(layer "In2.Cu")
		(net "RST_PERST0_OCP_V3_2_N")
	)
	(segment
		(start 88.10498 -29.53766)
		(end 88.10498 -19.025108)
		(width 0.127)
		(layer "In2.Cu")
		(net "RST_PERST0_OCP_V3_2_N")
	)
	(segment
		(start 108.9914 -41.773348)
		(end 104.18572 -36.967668)
		(width 0.127)
		(layer "In2.Cu")
		(net "RST_PERST0_OCP_V3_2_N")
	)
	(segment
		(start 78.724506 -11.608308)
		(end 73.914 -11.608308)
		(width 0.127)
		(layer "In2.Cu")
		(net "RST_PERST0_OCP_V3_2_N")
	)
	(segment
		(start 104.18572 -36.967668)
		(end 96.672908 -36.967668)
		(width 0.127)
		(layer "In2.Cu")
		(net "RST_PERST0_OCP_V3_2_N")
	)
	(segment
		(start 72.310244 -10.004552)
		(end 71.12889 -10.004552)
		(width 0.127)
		(layer "In2.Cu")
		(net "RST_PERST0_OCP_V3_2_N")
	)
	(segment
		(start 89.1794 -37.085016)
		(end 89.114122 -37.019738)
		(width 0.12954)
		(layer "F.Cu")
		(net "RST_OCP_V3_2_N")
	)
	(segment
		(start 88.417146 -37.019738)
		(end 88.255602 -36.858194)
		(width 0.12954)
		(layer "F.Cu")
		(net "RST_OCP_V3_2_N")
	)
	(segment
		(start 88.360504 -38.659308)
		(end 88.72474 -38.659308)
		(width 0.12954)
		(layer "F.Cu")
		(net "RST_OCP_V3_2_N")
	)
	(segment
		(start 88.255602 -36.858194)
		(end 88.255602 -36.288726)
		(width 0.12954)
		(layer "F.Cu")
		(net "RST_OCP_V3_2_N")
	)
	(segment
		(start 89.114122 -37.019738)
		(end 88.417146 -37.019738)
		(width 0.12954)
		(layer "F.Cu")
		(net "RST_OCP_V3_2_N")
	)
	(segment
		(start 88.72474 -38.659308)
		(end 89.1794 -38.204648)
		(width 0.12954)
		(layer "F.Cu")
		(net "RST_OCP_V3_2_N")
	)
	(segment
		(start 89.1794 -38.204648)
		(end 89.1794 -37.085016)
		(width 0.12954)
		(layer "F.Cu")
		(net "RST_OCP_V3_2_N")
	)
	(via
		(at 89.1794 -38.204648)
		(size 0.508)
		(drill 0.254)
		(layers "F.Cu" "B.Cu")
		(net "RST_OCP_V3_2_N")
	)
	(segment
		(start 106.075988 -38.983158)
		(end 106.075988 -39.996364)
		(width 0.12954)
		(layer "F.Cu")
		(net "RST_OCP_V3_2_BUF_N")
	)
	(segment
		(start 104.1146 -39.581582)
		(end 105.545382 -41.012364)
		(width 0.12954)
		(layer "F.Cu")
		(net "RST_OCP_V3_2_BUF_N")
	)
	(segment
		(start 106.075988 -37.940742)
		(end 106.075988 -38.983158)
		(width 0.12954)
		(layer "F.Cu")
		(net "RST_OCP_V3_2_BUF_N")
	)
	(segment
		(start 106.075988 -39.996364)
		(end 106.075988 -41.012364)
		(width 0.12954)
		(layer "F.Cu")
		(net "RST_OCP_V3_2_BUF_N")
	)
	(segment
		(start 105.545382 -41.012364)
		(end 106.075988 -41.012364)
		(width 0.12954)
		(layer "F.Cu")
		(net "RST_OCP_V3_2_BUF_N")
	)
	(segment
		(start 102.16388 -39.581582)
		(end 104.1146 -39.581582)
		(width 0.12954)
		(layer "F.Cu")
		(net "RST_OCP_V3_2_BUF_N")
	)
	(via
		(at 104.1146 -39.581582)
		(size 0.762)
		(drill 0.381)
		(layers "F.Cu" "B.Cu")
		(net "RST_OCP_V3_2_BUF_N")
	)
	(segment
		(start 153.613866 -110.846362)
		(end 153.613866 -110.261908)
		(width 0.12954)
		(layer "F.Cu")
		(net "RST_HP_OCP_V3_2_R_N")
	)
	(segment
		(start 153.61793 -114.137948)
		(end 153.61793 -112.867948)
		(width 0.12954)
		(layer "F.Cu")
		(net "RST_HP_OCP_V3_2_R_N")
	)
	(segment
		(start 153.613866 -112.349534)
		(end 152.86228 -111.597948)
		(width 0.12954)
		(layer "F.Cu")
		(net "RST_HP_OCP_V3_2_R_N")
	)
	(segment
		(start 152.86228 -111.597948)
		(end 153.613866 -110.846362)
		(width 0.12954)
		(layer "F.Cu")
		(net "RST_HP_OCP_V3_2_R_N")
	)
	(segment
		(start 153.613866 -112.863884)
		(end 153.613866 -112.349534)
		(width 0.12954)
		(layer "F.Cu")
		(net "RST_HP_OCP_V3_2_R_N")
	)
	(segment
		(start 153.61793 -112.867948)
		(end 153.613866 -112.863884)
		(width 0.12954)
		(layer "F.Cu")
		(net "RST_HP_OCP_V3_2_R_N")
	)
	(via
		(at 152.86228 -111.597948)
		(size 0.762)
		(drill 0.381)
		(layers "F.Cu" "B.Cu")
		(net "RST_HP_OCP_V3_2_R_N")
	)
	(segment
		(start 93.304614 -38.430962)
		(end 95.10522 -40.231568)
		(width 0.12954)
		(layer "F.Cu")
		(net "RST_HP_OCP_V3_2_N")
	)
	(segment
		(start 92.583 -37.709348)
		(end 93.304614 -38.430962)
		(width 0.12954)
		(layer "F.Cu")
		(net "RST_HP_OCP_V3_2_N")
	)
	(segment
		(start 90.760296 -37.709348)
		(end 92.583 -37.709348)
		(width 0.12954)
		(layer "F.Cu")
		(net "RST_HP_OCP_V3_2_N")
	)
	(segment
		(start 95.10522 -40.231568)
		(end 100.27412 -40.231568)
		(width 0.12954)
		(layer "F.Cu")
		(net "RST_HP_OCP_V3_2_N")
	)
	(via
		(at 93.304614 -38.430962)
		(size 0.762)
		(drill 0.381)
		(layers "F.Cu" "B.Cu")
		(net "RST_HP_OCP_V3_2_N")
	)
	(segment
		(start 463.162904 -92.387674)
		(end 463.162904 -93.396054)
		(width 0.12954)
		(layer "F.Cu")
		(net "RST_HP_OCP_SFF_R_N")
	)
	(segment
		(start 463.162904 -92.387674)
		(end 462.206848 -92.387674)
		(width 0.12954)
		(layer "F.Cu")
		(net "RST_HP_OCP_SFF_R_N")
	)
	(segment
		(start 460.387446 -92.304108)
		(end 460.387446 -92.977462)
		(width 0.12954)
		(layer "F.Cu")
		(net "RST_HP_OCP_SFF_R_N")
	)
	(segment
		(start 460.669132 -92.022422)
		(end 460.387446 -92.304108)
		(width 0.12954)
		(layer "F.Cu")
		(net "RST_HP_OCP_SFF_R_N")
	)
	(segment
		(start 462.206848 -92.387674)
		(end 461.841596 -92.022422)
		(width 0.12954)
		(layer "F.Cu")
		(net "RST_HP_OCP_SFF_R_N")
	)
	(segment
		(start 461.841596 -92.022422)
		(end 460.669132 -92.022422)
		(width 0.12954)
		(layer "F.Cu")
		(net "RST_HP_OCP_SFF_R_N")
	)
	(via
		(at 461.841596 -92.022422)
		(size 0.762)
		(drill 0.381)
		(layers "F.Cu" "B.Cu")
		(net "RST_HP_OCP_SFF_R_N")
	)
	(segment
		(start 21.713698 -389.425942)
		(end 21.713698 -388.94385)
		(width 0.10668)
		(layer "F.Cu")
		(net "PU_TEST")
	)
	(segment
		(start 21.456396 -387.702044)
		(end 21.8567 -388.102348)
		(width 0.10668)
		(layer "F.Cu")
		(net "PU_TEST")
	)
	(segment
		(start 21.456396 -386.884926)
		(end 21.456396 -387.702044)
		(width 0.10668)
		(layer "F.Cu")
		(net "PU_TEST")
	)
	(segment
		(start 21.713698 -388.94385)
		(end 21.8567 -388.800848)
		(width 0.10668)
		(layer "F.Cu")
		(net "PU_TEST")
	)
	(segment
		(start 21.8567 -388.800848)
		(end 21.8567 -388.102348)
		(width 0.10668)
		(layer "F.Cu")
		(net "PU_TEST")
	)
	(via
		(at 21.8567 -388.102348)
		(size 0.762)
		(drill 0.381)
		(layers "F.Cu" "B.Cu")
		(net "PU_TEST")
	)
	(segment
		(start 279.71496 -18.629122)
		(end 279.988518 -18.355564)
		(width 0.12954)
		(layer "F.Cu")
		(net "PU_OCP_V3_2_WAKE_OE")
	)
	(segment
		(start 279.364694 -18.629122)
		(end 279.71496 -18.629122)
		(width 0.12954)
		(layer "F.Cu")
		(net "PU_OCP_V3_2_WAKE_OE")
	)
	(segment
		(start 279.988518 -18.355564)
		(end 280.750264 -18.355564)
		(width 0.12954)
		(layer "F.Cu")
		(net "PU_OCP_V3_2_WAKE_OE")
	)
	(segment
		(start 280.750264 -18.355564)
		(end 281.916378 -18.355564)
		(width 0.12954)
		(layer "F.Cu")
		(net "PU_OCP_V3_2_WAKE_OE")
	)
	(segment
		(start 281.916378 -18.355564)
		(end 282.052776 -18.491962)
		(width 0.12954)
		(layer "F.Cu")
		(net "PU_OCP_V3_2_WAKE_OE")
	)
	(via
		(at 280.750264 -18.355564)
		(size 0.762)
		(drill 0.381)
		(layers "F.Cu" "B.Cu")
		(net "PU_OCP_V3_2_WAKE_OE")
	)
	(segment
		(start 130.346958 -16.550132)
		(end 130.346958 -19.279362)
		(width 0.12954)
		(layer "F.Cu")
		(net "TP_PCIE_HPM_TXN<3>")
	)
	(segment
		(start 130.36804 -20.579842)
		(end 130.36804 -19.873468)
		(width 0.12954)
		(layer "F.Cu")
		(net "TP_PCIE_HPM_TXN<3>")
	)
	(segment
		(start 130.346958 -19.279362)
		(end 130.36804 -19.300444)
		(width 0.12954)
		(layer "F.Cu")
		(net "TP_PCIE_HPM_TXN<3>")
	)
	(segment
		(start 130.10388 -21.154898)
		(end 130.10388 -20.844002)
		(width 0.12954)
		(layer "F.Cu")
		(net "TP_PCIE_HPM_TXN<3>")
	)
	(segment
		(start 130.10388 -20.844002)
		(end 130.36804 -20.579842)
		(width 0.12954)
		(layer "F.Cu")
		(net "TP_PCIE_HPM_TXN<3>")
	)
	(segment
		(start 130.36804 -19.300444)
		(end 130.36804 -19.873468)
		(width 0.12954)
		(layer "F.Cu")
		(net "TP_PCIE_HPM_TXN<3>")
	)
	(via
		(at 130.36804 -19.873468)
		(size 0.762)
		(drill 0.381)
		(layers "F.Cu" "B.Cu")
		(net "TP_PCIE_HPM_TXN<3>")
	)
	(segment
		(start 173.355762 -116.175536)
		(end 172.955712 -116.575586)
		(width 0.12954)
		(layer "F.Cu")
		(net "PU_FPGA_D12_PROGRAMN")
	)
	(segment
		(start 161.23793 -117.566948)
		(end 161.85388 -117.566948)
		(width 0.12954)
		(layer "F.Cu")
		(net "PU_FPGA_D12_PROGRAMN")
	)
	(via
		(at 172.955712 -116.575586)
		(size 0.4572)
		(drill 0.254)
		(layers "F.Cu" "B.Cu")
		(net "PU_FPGA_D12_PROGRAMN")
	)
	(via
		(at 161.85388 -117.566948)
		(size 0.508)
		(drill 0.254)
		(layers "F.Cu" "B.Cu")
		(net "PU_FPGA_D12_PROGRAMN")
	)
	(segment
		(start 164.96538 -118.057168)
		(end 165.93312 -118.057168)
		(width 0.127)
		(layer "In6.Cu")
		(net "PU_FPGA_D12_PROGRAMN")
	)
	(segment
		(start 166.221918 -117.76837)
		(end 171.571158 -117.76837)
		(width 0.127)
		(layer "In6.Cu")
		(net "PU_FPGA_D12_PROGRAMN")
	)
	(segment
		(start 171.571158 -117.76837)
		(end 171.75988 -117.579648)
		(width 0.127)
		(layer "In6.Cu")
		(net "PU_FPGA_D12_PROGRAMN")
	)
	(segment
		(start 171.75988 -117.579648)
		(end 171.75988 -117.170708)
		(width 0.127)
		(layer "In6.Cu")
		(net "PU_FPGA_D12_PROGRAMN")
	)
	(segment
		(start 172.56125 -116.970048)
		(end 172.955712 -116.575586)
		(width 0.127)
		(layer "In6.Cu")
		(net "PU_FPGA_D12_PROGRAMN")
	)
	(segment
		(start 171.96054 -116.970048)
		(end 172.56125 -116.970048)
		(width 0.127)
		(layer "In6.Cu")
		(net "PU_FPGA_D12_PROGRAMN")
	)
	(segment
		(start 165.93312 -118.057168)
		(end 166.221918 -117.76837)
		(width 0.127)
		(layer "In6.Cu")
		(net "PU_FPGA_D12_PROGRAMN")
	)
	(segment
		(start 161.85388 -117.566948)
		(end 162.876992 -117.566948)
		(width 0.127)
		(layer "In6.Cu")
		(net "PU_FPGA_D12_PROGRAMN")
	)
	(segment
		(start 162.876992 -117.566948)
		(end 163.346892 -117.097048)
		(width 0.127)
		(layer "In6.Cu")
		(net "PU_FPGA_D12_PROGRAMN")
	)
	(segment
		(start 171.75988 -117.170708)
		(end 171.96054 -116.970048)
		(width 0.127)
		(layer "In6.Cu")
		(net "PU_FPGA_D12_PROGRAMN")
	)
	(segment
		(start 164.00526 -117.097048)
		(end 164.96538 -118.057168)
		(width 0.127)
		(layer "In6.Cu")
		(net "PU_FPGA_D12_PROGRAMN")
	)
	(segment
		(start 163.346892 -117.097048)
		(end 164.00526 -117.097048)
		(width 0.127)
		(layer "In6.Cu")
		(net "PU_FPGA_D12_PROGRAMN")
	)
	(segment
		(start 144.145 -46.472348)
		(end 147.479258 -43.13809)
		(width 0.12954)
		(layer "F.Cu")
		(net "PU_BUFFER_HDD_ACTIVITY")
	)
	(segment
		(start 147.479258 -43.13809)
		(end 148.30425 -43.13809)
		(width 0.12954)
		(layer "F.Cu")
		(net "PU_BUFFER_HDD_ACTIVITY")
	)
	(segment
		(start 142.94993 -46.954948)
		(end 144.145 -46.954948)
		(width 0.12954)
		(layer "F.Cu")
		(net "PU_BUFFER_HDD_ACTIVITY")
	)
	(segment
		(start 144.145 -46.954948)
		(end 144.145 -46.472348)
		(width 0.12954)
		(layer "F.Cu")
		(net "PU_BUFFER_HDD_ACTIVITY")
	)
	(via
		(at 144.145 -46.954948)
		(size 0.762)
		(drill 0.381)
		(layers "F.Cu" "B.Cu")
		(net "PU_BUFFER_HDD_ACTIVITY")
	)
	(segment
		(start 135.86206 -123.486926)
		(end 135.114538 -124.234448)
		(width 0.12954)
		(layer "F.Cu")
		(net "PD_SMB_OCP2_HP_ADD2")
	)
	(segment
		(start 134.61365 -124.234448)
		(end 134.02945 -123.650248)
		(width 0.12954)
		(layer "F.Cu")
		(net "PD_SMB_OCP2_HP_ADD2")
	)
	(segment
		(start 135.114538 -124.234448)
		(end 134.61365 -124.234448)
		(width 0.12954)
		(layer "F.Cu")
		(net "PD_SMB_OCP2_HP_ADD2")
	)
	(segment
		(start 134.02945 -123.650248)
		(end 132.65785 -123.650248)
		(width 0.12954)
		(layer "F.Cu")
		(net "PD_SMB_OCP2_HP_ADD2")
	)
	(segment
		(start 132.65785 -123.650248)
		(end 132.07365 -124.234448)
		(width 0.12954)
		(layer "F.Cu")
		(net "PD_SMB_OCP2_HP_ADD2")
	)
	(segment
		(start 137.808716 -123.486926)
		(end 135.86206 -123.486926)
		(width 0.12954)
		(layer "F.Cu")
		(net "PD_SMB_OCP2_HP_ADD2")
	)
	(via
		(at 135.86206 -123.486926)
		(size 0.762)
		(drill 0.381)
		(layers "F.Cu" "B.Cu")
		(net "PD_SMB_OCP2_HP_ADD2")
	)
	(segment
		(start 132.72897 -125.103128)
		(end 133.95833 -125.103128)
		(width 0.12954)
		(layer "F.Cu")
		(net "PD_SMB_OCP2_HP_ADD1")
	)
	(segment
		(start 133.95833 -125.103128)
		(end 134.61365 -125.758448)
		(width 0.12954)
		(layer "F.Cu")
		(net "PD_SMB_OCP2_HP_ADD1")
	)
	(segment
		(start 132.07365 -125.758448)
		(end 132.72897 -125.103128)
		(width 0.12954)
		(layer "F.Cu")
		(net "PD_SMB_OCP2_HP_ADD1")
	)
	(segment
		(start 134.94004 -125.758448)
		(end 134.61365 -125.758448)
		(width 0.12954)
		(layer "F.Cu")
		(net "PD_SMB_OCP2_HP_ADD1")
	)
	(segment
		(start 136.561576 -124.136912)
		(end 135.91032 -124.788168)
		(width 0.12954)
		(layer "F.Cu")
		(net "PD_SMB_OCP2_HP_ADD1")
	)
	(segment
		(start 137.808716 -124.136912)
		(end 136.561576 -124.136912)
		(width 0.12954)
		(layer "F.Cu")
		(net "PD_SMB_OCP2_HP_ADD1")
	)
	(segment
		(start 135.91032 -124.788168)
		(end 134.94004 -125.758448)
		(width 0.12954)
		(layer "F.Cu")
		(net "PD_SMB_OCP2_HP_ADD1")
	)
	(via
		(at 135.91032 -124.788168)
		(size 0.762)
		(drill 0.381)
		(layers "F.Cu" "B.Cu")
		(net "PD_SMB_OCP2_HP_ADD1")
	)
	(segment
		(start 149.35073 -124.005848)
		(end 148.73351 -124.623068)
		(width 0.12954)
		(layer "F.Cu")
		(net "PD_SMB_OCP2_HP_ADD0")
	)
	(segment
		(start 143.658844 -122.83694)
		(end 145.400268 -122.83694)
		(width 0.12954)
		(layer "F.Cu")
		(net "PD_SMB_OCP2_HP_ADD0")
	)
	(segment
		(start 147.30095 -124.623068)
		(end 146.68373 -124.005848)
		(width 0.12954)
		(layer "F.Cu")
		(net "PD_SMB_OCP2_HP_ADD0")
	)
	(segment
		(start 146.68373 -123.808998)
		(end 146.68373 -124.005848)
		(width 0.12954)
		(layer "F.Cu")
		(net "PD_SMB_OCP2_HP_ADD0")
	)
	(segment
		(start 145.69186 -122.817128)
		(end 146.68373 -123.808998)
		(width 0.12954)
		(layer "F.Cu")
		(net "PD_SMB_OCP2_HP_ADD0")
	)
	(segment
		(start 145.400268 -122.83694)
		(end 145.42008 -122.817128)
		(width 0.12954)
		(layer "F.Cu")
		(net "PD_SMB_OCP2_HP_ADD0")
	)
	(segment
		(start 148.73351 -124.623068)
		(end 147.30095 -124.623068)
		(width 0.12954)
		(layer "F.Cu")
		(net "PD_SMB_OCP2_HP_ADD0")
	)
	(segment
		(start 145.42008 -122.817128)
		(end 145.69186 -122.817128)
		(width 0.12954)
		(layer "F.Cu")
		(net "PD_SMB_OCP2_HP_ADD0")
	)
	(via
		(at 145.42008 -122.817128)
		(size 0.762)
		(drill 0.381)
		(layers "F.Cu" "B.Cu")
		(net "PD_SMB_OCP2_HP_ADD0")
	)
	(segment
		(start 149.74443 -75.712828)
		(end 149.38248 -75.350878)
		(width 0.12954)
		(layer "F.Cu")
		(net "PCA9545_S3M_INT_N")
	)
	(segment
		(start 151.414226 -75.712828)
		(end 150.605744 -75.712828)
		(width 0.12954)
		(layer "F.Cu")
		(net "PCA9545_S3M_INT_N")
	)
	(segment
		(start 151.857202 -75.269852)
		(end 151.414226 -75.712828)
		(width 0.12954)
		(layer "F.Cu")
		(net "PCA9545_S3M_INT_N")
	)
	(segment
		(start 150.605744 -75.712828)
		(end 149.74443 -75.712828)
		(width 0.12954)
		(layer "F.Cu")
		(net "PCA9545_S3M_INT_N")
	)
	(segment
		(start 152.286208 -75.269852)
		(end 151.857202 -75.269852)
		(width 0.12954)
		(layer "F.Cu")
		(net "PCA9545_S3M_INT_N")
	)
	(via
		(at 150.605744 -75.712828)
		(size 0.762)
		(drill 0.381)
		(layers "F.Cu" "B.Cu")
		(net "PCA9545_S3M_INT_N")
	)
	(segment
		(start 152.286208 -77.220064)
		(end 150.700994 -77.220064)
		(width 0.12954)
		(layer "F.Cu")
		(net "PCA9543_S3M_INT3_N")
	)
	(segment
		(start 150.700994 -77.220064)
		(end 149.391624 -77.220064)
		(width 0.12954)
		(layer "F.Cu")
		(net "PCA9543_S3M_INT3_N")
	)
	(segment
		(start 149.391624 -77.220064)
		(end 149.38248 -77.229208)
		(width 0.12954)
		(layer "F.Cu")
		(net "PCA9543_S3M_INT3_N")
	)
	(via
		(at 150.700994 -77.220064)
		(size 0.762)
		(drill 0.381)
		(layers "F.Cu" "B.Cu")
		(net "PCA9543_S3M_INT3_N")
	)
	(segment
		(start 149.413468 -79.170022)
		(end 149.38248 -79.139034)
		(width 0.12954)
		(layer "F.Cu")
		(net "PCA9543_S3M_INT2_N")
	)
	(segment
		(start 152.286208 -79.170022)
		(end 150.68931 -79.170022)
		(width 0.12954)
		(layer "F.Cu")
		(net "PCA9543_S3M_INT2_N")
	)
	(segment
		(start 150.68931 -79.170022)
		(end 149.413468 -79.170022)
		(width 0.12954)
		(layer "F.Cu")
		(net "PCA9543_S3M_INT2_N")
	)
	(via
		(at 150.68931 -79.170022)
		(size 0.762)
		(drill 0.381)
		(layers "F.Cu" "B.Cu")
		(net "PCA9543_S3M_INT2_N")
	)
	(segment
		(start 97.917 -32.636714)
		(end 97.29724 -32.636714)
		(width 0.381)
		(layer "F.Cu")
		(net "P3V3_OCP_V3_2")
	)
	(segment
		(start 78.79969 -38.693852)
		(end 79.318358 -38.693852)
		(width 0.381)
		(layer "F.Cu")
		(net "P3V3_OCP_V3_2")
	)
	(segment
		(start 156.62783 -117.566948)
		(end 156.01188 -117.566948)
		(width 0.381)
		(layer "F.Cu")
		(net "P3V3_OCP_V3_2")
	)
	(segment
		(start 282.852876 -18.491962)
		(end 282.852876 -19.699986)
		(width 0.381)
		(layer "F.Cu")
		(net "P3V3_OCP_V3_2")
	)
	(segment
		(start 162.762692 -120.125236)
		(end 163.389564 -120.752108)
		(width 0.381)
		(layer "F.Cu")
		(net "P3V3_OCP_V3_2")
	)
	(segment
		(start 98.985324 -30.681422)
		(end 101.680518 -30.681422)
		(width 0.381)
		(layer "F.Cu")
		(net "P3V3_OCP_V3_2")
	)
	(segment
		(start 59.867038 -11.26998)
		(end 59.868054 -11.268964)
		(width 0.381)
		(layer "F.Cu")
		(net "P3V3_OCP_V3_2")
	)
	(segment
		(start 163.389564 -120.752108)
		(end 164.02812 -120.752108)
		(width 0.381)
		(layer "F.Cu")
		(net "P3V3_OCP_V3_2")
	)
	(segment
		(start 98.73869 -30.434788)
		(end 98.985324 -30.681422)
		(width 0.381)
		(layer "F.Cu")
		(net "P3V3_OCP_V3_2")
	)
	(segment
		(start 97.93859 -31.577788)
		(end 97.32264 -31.577788)
		(width 0.381)
		(layer "F.Cu")
		(net "P3V3_OCP_V3_2")
	)
	(segment
		(start 98.73869 -29.799788)
		(end 98.73869 -30.434788)
		(width 0.381)
		(layer "F.Cu")
		(net "P3V3_OCP_V3_2")
	)
	(segment
		(start 78.27645 -38.170612)
		(end 78.79969 -38.693852)
		(width 0.381)
		(layer "F.Cu")
		(net "P3V3_OCP_V3_2")
	)
	(segment
		(start 164.24783 -120.532398)
		(end 164.24783 -120.106948)
		(width 0.381)
		(layer "F.Cu")
		(net "P3V3_OCP_V3_2")
	)
	(segment
		(start 282.852876 -17.744948)
		(end 282.852876 -18.491962)
		(width 0.381)
		(layer "F.Cu")
		(net "P3V3_OCP_V3_2")
	)
	(segment
		(start 59.868054 -11.268964)
		(end 59.868054 -10.05078)
		(width 0.381)
		(layer "F.Cu")
		(net "P3V3_OCP_V3_2")
	)
	(segment
		(start 78.27645 -36.627308)
		(end 78.27645 -37.262308)
		(width 0.381)
		(layer "F.Cu")
		(net "P3V3_OCP_V3_2")
	)
	(segment
		(start 164.02812 -120.752108)
		(end 164.24783 -120.532398)
		(width 0.381)
		(layer "F.Cu")
		(net "P3V3_OCP_V3_2")
	)
	(segment
		(start 78.27645 -37.262308)
		(end 78.27645 -38.170612)
		(width 0.381)
		(layer "F.Cu")
		(net "P3V3_OCP_V3_2")
	)
	(via
		(at 282.852876 -17.744948)
		(size 0.508)
		(drill 0.254)
		(layers "F.Cu" "B.Cu")
		(net "P3V3_OCP_V3_2")
	)
	(via
		(at 77.90942 -44.155868)
		(size 0.508)
		(drill 0.254)
		(layers "F.Cu" "B.Cu")
		(net "P3V3_OCP_V3_2")
	)
	(via
		(at 63.55588 -9.997948)
		(size 0.508)
		(drill 0.254)
		(layers "F.Cu" "B.Cu")
		(net "P3V3_OCP_V3_2")
	)
	(via
		(at 78.54442 -44.155868)
		(size 0.508)
		(drill 0.254)
		(layers "F.Cu" "B.Cu")
		(net "P3V3_OCP_V3_2")
	)
	(via
		(at 138.876532 -91.567508)
		(size 0.508)
		(drill 0.254)
		(layers "F.Cu" "B.Cu")
		(net "P3V3_OCP_V3_2")
	)
	(via
		(at 62.53988 -9.997948)
		(size 0.508)
		(drill 0.254)
		(layers "F.Cu" "B.Cu")
		(net "P3V3_OCP_V3_2")
	)
	(via
		(at 59.868054 -10.05078)
		(size 0.508)
		(drill 0.254)
		(layers "F.Cu" "B.Cu")
		(net "P3V3_OCP_V3_2")
	)
	(via
		(at 64.5287 -10.013188)
		(size 0.508)
		(drill 0.254)
		(layers "F.Cu" "B.Cu")
		(net "P3V3_OCP_V3_2")
	)
	(via
		(at 79.0448 -42.052748)
		(size 0.508)
		(drill 0.254)
		(layers "F.Cu" "B.Cu")
		(net "P3V3_OCP_V3_2")
	)
	(via
		(at 73.84288 -10.164318)
		(size 0.508)
		(drill 0.254)
		(layers "F.Cu" "B.Cu")
		(net "P3V3_OCP_V3_2")
	)
	(via
		(at 162.762692 -120.125236)
		(size 0.508)
		(drill 0.254)
		(layers "F.Cu" "B.Cu")
		(net "P3V3_OCP_V3_2")
	)
	(via
		(at 78.678024 -45.072046)
		(size 0.508)
		(drill 0.254)
		(layers "F.Cu" "B.Cu")
		(net "P3V3_OCP_V3_2")
	)
	(via
		(at 61.52388 -9.997948)
		(size 0.508)
		(drill 0.254)
		(layers "F.Cu" "B.Cu")
		(net "P3V3_OCP_V3_2")
	)
	(via
		(at 97.29724 -32.636714)
		(size 0.508)
		(drill 0.254)
		(layers "F.Cu" "B.Cu")
		(net "P3V3_OCP_V3_2")
	)
	(via
		(at 139.309856 -115.959636)
		(size 0.508)
		(drill 0.254)
		(layers "F.Cu" "B.Cu")
		(net "P3V3_OCP_V3_2")
	)
	(via
		(at 75.06208 -3.241548)
		(size 0.508)
		(drill 0.254)
		(layers "F.Cu" "B.Cu")
		(net "P3V3_OCP_V3_2")
	)
	(via
		(at 216.9414 -33.774888)
		(size 0.508)
		(drill 0.254)
		(layers "F.Cu" "B.Cu")
		(net "P3V3_OCP_V3_2")
	)
	(via
		(at 77.724 -42.078148)
		(size 0.508)
		(drill 0.254)
		(layers "F.Cu" "B.Cu")
		(net "P3V3_OCP_V3_2")
	)
	(via
		(at 78.27645 -36.627308)
		(size 0.508)
		(drill 0.254)
		(layers "F.Cu" "B.Cu")
		(net "P3V3_OCP_V3_2")
	)
	(via
		(at 97.32264 -31.577788)
		(size 0.508)
		(drill 0.254)
		(layers "F.Cu" "B.Cu")
		(net "P3V3_OCP_V3_2")
	)
	(via
		(at 78.359 -42.078148)
		(size 0.508)
		(drill 0.254)
		(layers "F.Cu" "B.Cu")
		(net "P3V3_OCP_V3_2")
	)
	(via
		(at 156.01188 -117.566948)
		(size 0.508)
		(drill 0.254)
		(layers "F.Cu" "B.Cu")
		(net "P3V3_OCP_V3_2")
	)
	(via
		(at 98.73869 -29.799788)
		(size 0.508)
		(drill 0.254)
		(layers "F.Cu" "B.Cu")
		(net "P3V3_OCP_V3_2")
	)
	(via
		(at 74.85888 -10.164318)
		(size 0.508)
		(drill 0.254)
		(layers "F.Cu" "B.Cu")
		(net "P3V3_OCP_V3_2")
	)
	(segment
		(start 74.85888 -10.867898)
		(end 74.85888 -10.164318)
		(width 0.381)
		(layer "B.Cu")
		(net "P3V3_OCP_V3_2")
	)
	(segment
		(start 140.843508 -114.425984)
		(end 140.843508 -100.976176)
		(width 0.381)
		(layer "B.Cu")
		(net "P3V3_OCP_V3_2")
	)
	(segment
		(start 140.843508 -100.976176)
		(end 138.876532 -99.0092)
		(width 0.381)
		(layer "B.Cu")
		(net "P3V3_OCP_V3_2")
	)
	(segment
		(start 139.309856 -115.959636)
		(end 140.843508 -114.425984)
		(width 0.381)
		(layer "B.Cu")
		(net "P3V3_OCP_V3_2")
	)
	(segment
		(start 75.06208 -3.851148)
		(end 75.06208 -3.241548)
		(width 0.381)
		(layer "B.Cu")
		(net "P3V3_OCP_V3_2")
	)
	(segment
		(start 73.84288 -10.867898)
		(end 73.84288 -10.164318)
		(width 0.381)
		(layer "B.Cu")
		(net "P3V3_OCP_V3_2")
	)
	(segment
		(start 138.876532 -99.0092)
		(end 138.876532 -91.567508)
		(width 0.381)
		(layer "B.Cu")
		(net "P3V3_OCP_V3_2")
	)
	(segment
		(start 162.132264 -119.494808)
		(end 157.85592 -119.494808)
		(width 0.381)
		(layer "In4.Cu")
		(net "P3V3_OCP_V3_2")
	)
	(segment
		(start 162.762692 -120.125236)
		(end 162.132264 -119.494808)
		(width 0.381)
		(layer "In4.Cu")
		(net "P3V3_OCP_V3_2")
	)
	(segment
		(start 157.85592 -119.494808)
		(end 156.01188 -117.650768)
		(width 0.381)
		(layer "In4.Cu")
		(net "P3V3_OCP_V3_2")
	)
	(segment
		(start 156.01188 -117.650768)
		(end 156.01188 -117.566948)
		(width 0.381)
		(layer "In4.Cu")
		(net "P3V3_OCP_V3_2")
	)
	(segment
		(start 139.309856 -115.774724)
		(end 139.309856 -115.959636)
		(width 0.381)
		(layer "In6.Cu")
		(net "P3V3_OCP_V3_2")
	)
	(segment
		(start 151.551894 -118.217696)
		(end 151.035258 -117.70106)
		(width 0.381)
		(layer "In6.Cu")
		(net "P3V3_OCP_V3_2")
	)
	(segment
		(start 143.58112 -117.70106)
		(end 142.96644 -117.08638)
		(width 0.381)
		(layer "In6.Cu")
		(net "P3V3_OCP_V3_2")
	)
	(segment
		(start 140.304012 -114.780568)
		(end 139.309856 -115.774724)
		(width 0.381)
		(layer "In6.Cu")
		(net "P3V3_OCP_V3_2")
	)
	(segment
		(start 142.657068 -114.780568)
		(end 140.304012 -114.780568)
		(width 0.381)
		(layer "In6.Cu")
		(net "P3V3_OCP_V3_2")
	)
	(segment
		(start 154.818588 -118.302786)
		(end 154.464004 -117.948202)
		(width 0.381)
		(layer "In6.Cu")
		(net "P3V3_OCP_V3_2")
	)
	(segment
		(start 155.276042 -118.302786)
		(end 154.818588 -118.302786)
		(width 0.381)
		(layer "In6.Cu")
		(net "P3V3_OCP_V3_2")
	)
	(segment
		(start 153.667714 -117.948202)
		(end 153.39822 -118.217696)
		(width 0.381)
		(layer "In6.Cu")
		(net "P3V3_OCP_V3_2")
	)
	(segment
		(start 154.464004 -117.948202)
		(end 153.667714 -117.948202)
		(width 0.381)
		(layer "In6.Cu")
		(net "P3V3_OCP_V3_2")
	)
	(segment
		(start 142.96644 -115.08994)
		(end 142.657068 -114.780568)
		(width 0.381)
		(layer "In6.Cu")
		(net "P3V3_OCP_V3_2")
	)
	(segment
		(start 153.39822 -118.217696)
		(end 151.551894 -118.217696)
		(width 0.381)
		(layer "In6.Cu")
		(net "P3V3_OCP_V3_2")
	)
	(segment
		(start 142.96644 -117.08638)
		(end 142.96644 -115.08994)
		(width 0.381)
		(layer "In6.Cu")
		(net "P3V3_OCP_V3_2")
	)
	(segment
		(start 151.035258 -117.70106)
		(end 143.58112 -117.70106)
		(width 0.381)
		(layer "In6.Cu")
		(net "P3V3_OCP_V3_2")
	)
	(segment
		(start 156.01188 -117.566948)
		(end 155.276042 -118.302786)
		(width 0.381)
		(layer "In6.Cu")
		(net "P3V3_OCP_V3_2")
	)
	(segment
		(start 258.4196 -36.749228)
		(end 220.35516 -36.749228)
		(width 0.381)
		(layer "In11.Cu")
		(net "P3V3_OCP_V3_2")
	)
	(segment
		(start 281.23388 -17.744948)
		(end 267.77188 -31.206948)
		(width 0.381)
		(layer "In11.Cu")
		(net "P3V3_OCP_V3_2")
	)
	(segment
		(start 101.9048 -40.681148)
		(end 112.776508 -51.552856)
		(width 0.381)
		(layer "In11.Cu")
		(net "P3V3_OCP_V3_2")
	)
	(segment
		(start 261.358126 -32.018478)
		(end 261.358126 -33.810702)
		(width 0.381)
		(layer "In11.Cu")
		(net "P3V3_OCP_V3_2")
	)
	(segment
		(start 99.161346 -40.681148)
		(end 101.9048 -40.681148)
		(width 0.381)
		(layer "In11.Cu")
		(net "P3V3_OCP_V3_2")
	)
	(segment
		(start 133.174486 -72.117458)
		(end 133.174486 -74.970894)
		(width 0.381)
		(layer "In11.Cu")
		(net "P3V3_OCP_V3_2")
	)
	(segment
		(start 220.35516 -36.749228)
		(end 217.38082 -33.774888)
		(width 0.381)
		(layer "In11.Cu")
		(net "P3V3_OCP_V3_2")
	)
	(segment
		(start 261.358126 -33.810702)
		(end 258.4196 -36.749228)
		(width 0.381)
		(layer "In11.Cu")
		(net "P3V3_OCP_V3_2")
	)
	(segment
		(start 133.174486 -74.970894)
		(end 134.248906 -77.564996)
		(width 0.381)
		(layer "In11.Cu")
		(net "P3V3_OCP_V3_2")
	)
	(segment
		(start 262.169656 -31.206948)
		(end 261.358126 -32.018478)
		(width 0.381)
		(layer "In11.Cu")
		(net "P3V3_OCP_V3_2")
	)
	(segment
		(start 134.537958 -70.753986)
		(end 133.174486 -72.117458)
		(width 0.381)
		(layer "In11.Cu")
		(net "P3V3_OCP_V3_2")
	)
	(segment
		(start 267.77188 -31.206948)
		(end 262.169656 -31.206948)
		(width 0.381)
		(layer "In11.Cu")
		(net "P3V3_OCP_V3_2")
	)
	(segment
		(start 134.537958 -56.651906)
		(end 134.537958 -70.753986)
		(width 0.381)
		(layer "In11.Cu")
		(net "P3V3_OCP_V3_2")
	)
	(segment
		(start 282.852876 -17.744948)
		(end 281.23388 -17.744948)
		(width 0.381)
		(layer "In11.Cu")
		(net "P3V3_OCP_V3_2")
	)
	(segment
		(start 136.980676 -89.671652)
		(end 138.876532 -91.567508)
		(width 0.381)
		(layer "In11.Cu")
		(net "P3V3_OCP_V3_2")
	)
	(segment
		(start 129.438908 -51.552856)
		(end 134.537958 -56.651906)
		(width 0.381)
		(layer "In11.Cu")
		(net "P3V3_OCP_V3_2")
	)
	(segment
		(start 98.1456 -39.665402)
		(end 99.161346 -40.681148)
		(width 0.381)
		(layer "In11.Cu")
		(net "P3V3_OCP_V3_2")
	)
	(segment
		(start 112.776508 -51.552856)
		(end 129.438908 -51.552856)
		(width 0.381)
		(layer "In11.Cu")
		(net "P3V3_OCP_V3_2")
	)
	(segment
		(start 136.980676 -80.296766)
		(end 136.980676 -89.671652)
		(width 0.381)
		(layer "In11.Cu")
		(net "P3V3_OCP_V3_2")
	)
	(segment
		(start 134.248906 -77.564996)
		(end 136.980676 -80.296766)
		(width 0.381)
		(layer "In11.Cu")
		(net "P3V3_OCP_V3_2")
	)
	(segment
		(start 217.38082 -33.774888)
		(end 216.9414 -33.774888)
		(width 0.381)
		(layer "In11.Cu")
		(net "P3V3_OCP_V3_2")
	)
	(segment
		(start 188.44768 -36.261548)
		(end 189.00648 -36.820348)
		(width 0.381)
		(layer "In13.Cu")
		(net "P3V3_OCP_V3_2")
	)
	(segment
		(start 160.92678 -23.574248)
		(end 165.381432 -23.574248)
		(width 0.381)
		(layer "In13.Cu")
		(net "P3V3_OCP_V3_2")
	)
	(segment
		(start 213.31174 -33.774888)
		(end 216.9414 -33.774888)
		(width 0.381)
		(layer "In13.Cu")
		(net "P3V3_OCP_V3_2")
	)
	(segment
		(start 195.529454 -33.827974)
		(end 206.61376 -33.827974)
		(width 0.381)
		(layer "In13.Cu")
		(net "P3V3_OCP_V3_2")
	)
	(segment
		(start 98.73869 -29.799788)
		(end 98.73869 -28.431998)
		(width 0.381)
		(layer "In13.Cu")
		(net "P3V3_OCP_V3_2")
	)
	(segment
		(start 166.57828 -24.771096)
		(end 166.57828 -28.133548)
		(width 0.381)
		(layer "In13.Cu")
		(net "P3V3_OCP_V3_2")
	)
	(segment
		(start 159.8041 -22.451568)
		(end 160.92678 -23.574248)
		(width 0.381)
		(layer "In13.Cu")
		(net "P3V3_OCP_V3_2")
	)
	(segment
		(start 103.81488 -23.355808)
		(end 114.79784 -23.355808)
		(width 0.381)
		(layer "In13.Cu")
		(net "P3V3_OCP_V3_2")
	)
	(segment
		(start 206.906876 -33.534858)
		(end 213.07171 -33.534858)
		(width 0.381)
		(layer "In13.Cu")
		(net "P3V3_OCP_V3_2")
	)
	(segment
		(start 117.1829 -25.740868)
		(end 126.29388 -25.740868)
		(width 0.381)
		(layer "In13.Cu")
		(net "P3V3_OCP_V3_2")
	)
	(segment
		(start 176.00168 -37.556948)
		(end 184.86628 -37.556948)
		(width 0.381)
		(layer "In13.Cu")
		(net "P3V3_OCP_V3_2")
	)
	(segment
		(start 186.16168 -36.261548)
		(end 188.44768 -36.261548)
		(width 0.381)
		(layer "In13.Cu")
		(net "P3V3_OCP_V3_2")
	)
	(segment
		(start 184.86628 -37.556948)
		(end 186.16168 -36.261548)
		(width 0.381)
		(layer "In13.Cu")
		(net "P3V3_OCP_V3_2")
	)
	(segment
		(start 126.29388 -25.740868)
		(end 129.58318 -22.451568)
		(width 0.381)
		(layer "In13.Cu")
		(net "P3V3_OCP_V3_2")
	)
	(segment
		(start 192.53708 -36.820348)
		(end 195.529454 -33.827974)
		(width 0.381)
		(layer "In13.Cu")
		(net "P3V3_OCP_V3_2")
	)
	(segment
		(start 129.58318 -22.451568)
		(end 159.8041 -22.451568)
		(width 0.381)
		(layer "In13.Cu")
		(net "P3V3_OCP_V3_2")
	)
	(segment
		(start 114.79784 -23.355808)
		(end 117.1829 -25.740868)
		(width 0.381)
		(layer "In13.Cu")
		(net "P3V3_OCP_V3_2")
	)
	(segment
		(start 165.381432 -23.574248)
		(end 166.57828 -24.771096)
		(width 0.381)
		(layer "In13.Cu")
		(net "P3V3_OCP_V3_2")
	)
	(segment
		(start 213.07171 -33.534858)
		(end 213.31174 -33.774888)
		(width 0.381)
		(layer "In13.Cu")
		(net "P3V3_OCP_V3_2")
	)
	(segment
		(start 166.57828 -28.133548)
		(end 176.00168 -37.556948)
		(width 0.381)
		(layer "In13.Cu")
		(net "P3V3_OCP_V3_2")
	)
	(segment
		(start 189.00648 -36.820348)
		(end 192.53708 -36.820348)
		(width 0.381)
		(layer "In13.Cu")
		(net "P3V3_OCP_V3_2")
	)
	(segment
		(start 98.73869 -28.431998)
		(end 103.81488 -23.355808)
		(width 0.381)
		(layer "In13.Cu")
		(net "P3V3_OCP_V3_2")
	)
	(segment
		(start 206.61376 -33.827974)
		(end 206.906876 -33.534858)
		(width 0.381)
		(layer "In13.Cu")
		(net "P3V3_OCP_V3_2")
	)
	(segment
		(start 67.34556 -58.745628)
		(end 66.58356 -59.507628)
		(width 0.12954)
		(layer "F.Cu")
		(net "P3V3_OCP_DVDT_2")
	)
	(segment
		(start 66.58356 -59.507628)
		(end 66.58356 -60.479178)
		(width 0.12954)
		(layer "F.Cu")
		(net "P3V3_OCP_DVDT_2")
	)
	(segment
		(start 68.522088 -58.094626)
		(end 68.522088 -58.3565)
		(width 0.12954)
		(layer "F.Cu")
		(net "P3V3_OCP_DVDT_2")
	)
	(segment
		(start 68.13296 -58.745628)
		(end 67.34556 -58.745628)
		(width 0.12954)
		(layer "F.Cu")
		(net "P3V3_OCP_DVDT_2")
	)
	(segment
		(start 68.522088 -58.3565)
		(end 68.13296 -58.745628)
		(width 0.12954)
		(layer "F.Cu")
		(net "P3V3_OCP_DVDT_2")
	)
	(segment
		(start 66.58356 -60.479178)
		(end 66.86296 -60.758578)
		(width 0.12954)
		(layer "F.Cu")
		(net "P3V3_OCP_DVDT_2")
	)
	(via
		(at 66.58356 -59.507628)
		(size 0.762)
		(drill 0.381)
		(layers "F.Cu" "B.Cu")
		(net "P3V3_OCP_DVDT_2")
	)
	(segment
		(start 27.228546 -389.304276)
		(end 27.228546 -390.294876)
		(width 0.10668)
		(layer "F.Cu")
		(net "FM_P2E_SWB")
	)
	(segment
		(start 27.228546 -389.304276)
		(end 26.460196 -389.304276)
		(width 0.10668)
		(layer "F.Cu")
		(net "FM_P2E_SWB")
	)
	(segment
		(start 24.163528 -390.275826)
		(end 25.488646 -390.275826)
		(width 0.10668)
		(layer "F.Cu")
		(net "FM_P2E_SWB")
	)
	(segment
		(start 25.488646 -390.275826)
		(end 25.723596 -390.040876)
		(width 0.10668)
		(layer "F.Cu")
		(net "FM_P2E_SWB")
	)
	(segment
		(start 27.228546 -390.294876)
		(end 27.228546 -391.310876)
		(width 0.10668)
		(layer "F.Cu")
		(net "FM_P2E_SWB")
	)
	(segment
		(start 26.460196 -389.304276)
		(end 25.723596 -390.040876)
		(width 0.10668)
		(layer "F.Cu")
		(net "FM_P2E_SWB")
	)
	(via
		(at 25.723596 -390.040876)
		(size 0.762)
		(drill 0.381)
		(layers "F.Cu" "B.Cu")
		(net "FM_P2E_SWB")
	)
	(segment
		(start 15.836646 -390.167876)
		(end 15.836646 -389.151876)
		(width 0.10668)
		(layer "F.Cu")
		(net "FM_P2E_SWA")
	)
	(segment
		(start 16.563848 -388.161276)
		(end 17.341596 -388.939024)
		(width 0.10668)
		(layer "F.Cu")
		(net "FM_P2E_SWA")
	)
	(segment
		(start 15.836646 -388.161276)
		(end 16.563848 -388.161276)
		(width 0.10668)
		(layer "F.Cu")
		(net "FM_P2E_SWA")
	)
	(segment
		(start 15.836646 -389.151876)
		(end 15.836646 -388.161276)
		(width 0.10668)
		(layer "F.Cu")
		(net "FM_P2E_SWA")
	)
	(segment
		(start 17.341596 -388.939024)
		(end 17.341596 -389.532876)
		(width 0.10668)
		(layer "F.Cu")
		(net "FM_P2E_SWA")
	)
	(segment
		(start 18.084546 -390.275826)
		(end 17.341596 -389.532876)
		(width 0.10668)
		(layer "F.Cu")
		(net "FM_P2E_SWA")
	)
	(segment
		(start 19.663664 -390.275826)
		(end 18.084546 -390.275826)
		(width 0.10668)
		(layer "F.Cu")
		(net "FM_P2E_SWA")
	)
	(via
		(at 17.341596 -389.532876)
		(size 0.762)
		(drill 0.381)
		(layers "F.Cu" "B.Cu")
		(net "FM_P2E_SWA")
	)
	(segment
		(start 15.836646 -387.119876)
		(end 15.836646 -386.129276)
		(width 0.10668)
		(layer "F.Cu")
		(net "FM_P2E_MODE")
	)
	(segment
		(start 15.8369 -386.12953)
		(end 16.514826 -386.12953)
		(width 0.10668)
		(layer "F.Cu")
		(net "FM_P2E_MODE")
	)
	(segment
		(start 18.357596 -387.9723)
		(end 18.357596 -388.643876)
		(width 0.10668)
		(layer "F.Cu")
		(net "FM_P2E_MODE")
	)
	(segment
		(start 15.836646 -386.129276)
		(end 15.836646 -386.103876)
		(width 0.10668)
		(layer "F.Cu")
		(net "FM_P2E_MODE")
	)
	(segment
		(start 18.700496 -389.875776)
		(end 18.357596 -389.532876)
		(width 0.10668)
		(layer "F.Cu")
		(net "FM_P2E_MODE")
	)
	(segment
		(start 16.514826 -386.12953)
		(end 18.357596 -387.9723)
		(width 0.10668)
		(layer "F.Cu")
		(net "FM_P2E_MODE")
	)
	(segment
		(start 18.357596 -389.532876)
		(end 18.357596 -388.643876)
		(width 0.10668)
		(layer "F.Cu")
		(net "FM_P2E_MODE")
	)
	(segment
		(start 19.663664 -389.875776)
		(end 18.700496 -389.875776)
		(width 0.10668)
		(layer "F.Cu")
		(net "FM_P2E_MODE")
	)
	(segment
		(start 15.836646 -386.129276)
		(end 15.8369 -386.12953)
		(width 0.10668)
		(layer "F.Cu")
		(net "FM_P2E_MODE")
	)
	(via
		(at 18.357596 -388.643876)
		(size 0.762)
		(drill 0.381)
		(layers "F.Cu" "B.Cu")
		(net "FM_P2E_MODE")
	)
	(segment
		(start 132.747004 -17.074388)
		(end 132.575808 -17.245584)
		(width 0.13208)
		(layer "F.Cu")
		(net "P2E_MB_BMC_TX_C_DP<0>")
	)
	(segment
		(start 132.747004 -16.550132)
		(end 132.747004 -17.074388)
		(width 0.13208)
		(layer "F.Cu")
		(net "P2E_MB_BMC_TX_C_DP<0>")
	)
	(segment
		(start 132.575808 -17.245584)
		(end 132.575808 -17.842484)
		(width 0.13208)
		(layer "F.Cu")
		(net "P2E_MB_BMC_TX_C_DP<0>")
	)
	(segment
		(start 132.575808 -17.842484)
		(end 132.878068 -18.144744)
		(width 0.13208)
		(layer "F.Cu")
		(net "P2E_MB_BMC_TX_C_DP<0>")
	)
	(segment
		(start 19.84248 -385.72694)
		(end 19.84248 -385.784344)
		(width 0.13208)
		(layer "F.Cu")
		(net "P2E_MB_BMC_TX_C_DP<0>")
	)
	(segment
		(start 19.19859 -385.465574)
		(end 19.581114 -385.465574)
		(width 0.13208)
		(layer "F.Cu")
		(net "P2E_MB_BMC_TX_C_DP<0>")
	)
	(segment
		(start 19.581114 -385.465574)
		(end 19.84248 -385.72694)
		(width 0.13208)
		(layer "F.Cu")
		(net "P2E_MB_BMC_TX_C_DP<0>")
	)
	(segment
		(start 8.802878 -315.185552)
		(end 9.716008 -314.50915)
		(width 0.14732)
		(layer "In4.Cu")
		(net "P2E_MB_BMC_TX_C_DP<0>")
	)
	(segment
		(start 59.740292 -56.470042)
		(end 60.498228 -56.156098)
		(width 0.14732)
		(layer "In4.Cu")
		(net "P2E_MB_BMC_TX_C_DP<0>")
	)
	(segment
		(start 34.064448 -90.179398)
		(end 34.269172 -90.179398)
		(width 0.14732)
		(layer "In4.Cu")
		(net "P2E_MB_BMC_TX_C_DP<0>")
	)
	(segment
		(start 6.75767 -318.120776)
		(end 7.12978 -318.02959)
		(width 0.14732)
		(layer "In4.Cu")
		(net "P2E_MB_BMC_TX_C_DP<0>")
	)
	(segment
		(start 13.103352 -192.919858)
		(end 12.975336 -192.760346)
		(width 0.14732)
		(layer "In4.Cu")
		(net "P2E_MB_BMC_TX_C_DP<0>")
	)
	(segment
		(start 25.36698 -386.483352)
		(end 25.36698 -374.350788)
		(width 0.14732)
		(layer "In4.Cu")
		(net "P2E_MB_BMC_TX_C_DP<0>")
	)
	(segment
		(start 35.56635 -88.849708)
		(end 35.56635 -88.677496)
		(width 0.14732)
		(layer "In4.Cu")
		(net "P2E_MB_BMC_TX_C_DP<0>")
	)
	(segment
		(start 14.0335 -188.447934)
		(end 14.929866 -185.674508)
		(width 0.14732)
		(layer "In4.Cu")
		(net "P2E_MB_BMC_TX_C_DP<0>")
	)
	(segment
		(start 13.14577 -191.194436)
		(end 14.0335 -188.447934)
		(width 0.14732)
		(layer "In4.Cu")
		(net "P2E_MB_BMC_TX_C_DP<0>")
	)
	(segment
		(start 12.336526 -254.035306)
		(end 12.558014 -224.264474)
		(width 0.14732)
		(layer "In4.Cu")
		(net "P2E_MB_BMC_TX_C_DP<0>")
	)
	(segment
		(start 24.436832 -387.4135)
		(end 25.36698 -386.483352)
		(width 0.14732)
		(layer "In4.Cu")
		(net "P2E_MB_BMC_TX_C_DP<0>")
	)
	(segment
		(start 36.173156 -88.07069)
		(end 36.595304 -87.895938)
		(width 0.14732)
		(layer "In4.Cu")
		(net "P2E_MB_BMC_TX_C_DP<0>")
	)
	(segment
		(start 34.53003 -89.713816)
		(end 35.088576 -89.15527)
		(width 0.14732)
		(layer "In4.Cu")
		(net "P2E_MB_BMC_TX_C_DP<0>")
	)
	(segment
		(start 13.063474 -193.28638)
		(end 13.103352 -192.919858)
		(width 0.14732)
		(layer "In4.Cu")
		(net "P2E_MB_BMC_TX_C_DP<0>")
	)
	(segment
		(start 132.094478 -19.25066)
		(end 132.583428 -18.76171)
		(width 0.14732)
		(layer "In4.Cu")
		(net "P2E_MB_BMC_TX_C_DP<0>")
	)
	(segment
		(start 59.132216 -56.722264)
		(end 59.321446 -56.800496)
		(width 0.14732)
		(layer "In4.Cu")
		(net "P2E_MB_BMC_TX_C_DP<0>")
	)
	(segment
		(start 125.544834 -19.605498)
		(end 126.401068 -19.25066)
		(width 0.14732)
		(layer "In4.Cu")
		(net "P2E_MB_BMC_TX_C_DP<0>")
	)
	(segment
		(start 19.84248 -385.7498)
		(end 20.14728 -385.445)
		(width 0.14732)
		(layer "In4.Cu")
		(net "P2E_MB_BMC_TX_C_DP<0>")
	)
	(segment
		(start 12.558014 -224.26422)
		(end 12.779248 -194.557396)
		(width 0.14732)
		(layer "In4.Cu")
		(net "P2E_MB_BMC_TX_C_DP<0>")
	)
	(segment
		(start 132.583428 -18.439384)
		(end 132.878068 -18.144744)
		(width 0.14732)
		(layer "In4.Cu")
		(net "P2E_MB_BMC_TX_C_DP<0>")
	)
	(segment
		(start 12.903708 -193.41465)
		(end 13.063474 -193.28638)
		(width 0.14732)
		(layer "In4.Cu")
		(net "P2E_MB_BMC_TX_C_DP<0>")
	)
	(segment
		(start 12.779248 -194.557396)
		(end 12.903708 -193.41465)
		(width 0.14732)
		(layer "In4.Cu")
		(net "P2E_MB_BMC_TX_C_DP<0>")
	)
	(segment
		(start 53.23586 -74.609198)
		(end 53.23586 -62.012068)
		(width 0.14732)
		(layer "In4.Cu")
		(net "P2E_MB_BMC_TX_C_DP<0>")
	)
	(segment
		(start 5.416804 -351.064068)
		(end 4.4704 -348.77883)
		(width 0.14732)
		(layer "In4.Cu")
		(net "P2E_MB_BMC_TX_C_DP<0>")
	)
	(segment
		(start 9.716008 -314.50915)
		(end 10.019538 -314.10021)
		(width 0.14732)
		(layer "In4.Cu")
		(net "P2E_MB_BMC_TX_C_DP<0>")
	)
	(segment
		(start 10.659872 -258.336034)
		(end 12.336526 -254.035306)
		(width 0.14732)
		(layer "In4.Cu")
		(net "P2E_MB_BMC_TX_C_DP<0>")
	)
	(segment
		(start 35.088576 -89.15527)
		(end 35.260788 -89.15527)
		(width 0.14732)
		(layer "In4.Cu")
		(net "P2E_MB_BMC_TX_C_DP<0>")
	)
	(segment
		(start 17.96796 -356.791768)
		(end 14.67231 -353.496118)
		(width 0.14732)
		(layer "In4.Cu")
		(net "P2E_MB_BMC_TX_C_DP<0>")
	)
	(segment
		(start 35.260788 -89.15527)
		(end 35.56635 -88.849708)
		(width 0.14732)
		(layer "In4.Cu")
		(net "P2E_MB_BMC_TX_C_DP<0>")
	)
	(segment
		(start 71.766938 -53.914548)
		(end 74.803 -52.656994)
		(width 0.14732)
		(layer "In4.Cu")
		(net "P2E_MB_BMC_TX_C_DP<0>")
	)
	(segment
		(start 17.96796 -366.951768)
		(end 17.96796 -356.791768)
		(width 0.14732)
		(layer "In4.Cu")
		(net "P2E_MB_BMC_TX_C_DP<0>")
	)
	(segment
		(start 23.377144 -113.255552)
		(end 25.884886 -98.35896)
		(width 0.14732)
		(layer "In4.Cu")
		(net "P2E_MB_BMC_TX_C_DP<0>")
	)
	(segment
		(start 58.096912 -57.151016)
		(end 59.132216 -56.722264)
		(width 0.14732)
		(layer "In4.Cu")
		(net "P2E_MB_BMC_TX_C_DP<0>")
	)
	(segment
		(start 123.392184 -21.758148)
		(end 125.544834 -19.605498)
		(width 0.14732)
		(layer "In4.Cu")
		(net "P2E_MB_BMC_TX_C_DP<0>")
	)
	(segment
		(start 59.321446 -56.800496)
		(end 59.661806 -56.659526)
		(width 0.14732)
		(layer "In4.Cu")
		(net "P2E_MB_BMC_TX_C_DP<0>")
	)
	(segment
		(start 33.061148 -91.182698)
		(end 33.265872 -91.182698)
		(width 0.14732)
		(layer "In4.Cu")
		(net "P2E_MB_BMC_TX_C_DP<0>")
	)
	(segment
		(start 105.468928 -29.138626)
		(end 107.073192 -27.534362)
		(width 0.14732)
		(layer "In4.Cu")
		(net "P2E_MB_BMC_TX_C_DP<0>")
	)
	(segment
		(start 53.23586 -62.012068)
		(end 58.096912 -57.151016)
		(width 0.14732)
		(layer "In4.Cu")
		(net "P2E_MB_BMC_TX_C_DP<0>")
	)
	(segment
		(start 34.269172 -90.179398)
		(end 34.53003 -89.91854)
		(width 0.14732)
		(layer "In4.Cu")
		(net "P2E_MB_BMC_TX_C_DP<0>")
	)
	(segment
		(start 7.74065 -317.637668)
		(end 8.802878 -315.185552)
		(width 0.14732)
		(layer "In4.Cu")
		(net "P2E_MB_BMC_TX_C_DP<0>")
	)
	(segment
		(start 7.848854 -353.496118)
		(end 5.416804 -351.064068)
		(width 0.14732)
		(layer "In4.Cu")
		(net "P2E_MB_BMC_TX_C_DP<0>")
	)
	(segment
		(start 33.52673 -90.92184)
		(end 33.52673 -90.717116)
		(width 0.14732)
		(layer "In4.Cu")
		(net "P2E_MB_BMC_TX_C_DP<0>")
	)
	(segment
		(start 12.975336 -192.760346)
		(end 13.14577 -191.194436)
		(width 0.14732)
		(layer "In4.Cu")
		(net "P2E_MB_BMC_TX_C_DP<0>")
	)
	(segment
		(start 10.019538 -314.10021)
		(end 10.659872 -258.336034)
		(width 0.14732)
		(layer "In4.Cu")
		(net "P2E_MB_BMC_TX_C_DP<0>")
	)
	(segment
		(start 51.15052 -79.643732)
		(end 53.23586 -74.609198)
		(width 0.14732)
		(layer "In4.Cu")
		(net "P2E_MB_BMC_TX_C_DP<0>")
	)
	(segment
		(start 47.35576 -83.438492)
		(end 51.15052 -79.643732)
		(width 0.14732)
		(layer "In4.Cu")
		(net "P2E_MB_BMC_TX_C_DP<0>")
	)
	(segment
		(start 37.15385 -87.796624)
		(end 37.21989 -87.637112)
		(width 0.14732)
		(layer "In4.Cu")
		(net "P2E_MB_BMC_TX_C_DP<0>")
	)
	(segment
		(start 107.073192 -27.534362)
		(end 123.392184 -21.758148)
		(width 0.14732)
		(layer "In4.Cu")
		(net "P2E_MB_BMC_TX_C_DP<0>")
	)
	(segment
		(start 36.754816 -87.961724)
		(end 37.15385 -87.796624)
		(width 0.14732)
		(layer "In4.Cu")
		(net "P2E_MB_BMC_TX_C_DP<0>")
	)
	(segment
		(start 126.401068 -19.25066)
		(end 132.094478 -19.25066)
		(width 0.14732)
		(layer "In4.Cu")
		(net "P2E_MB_BMC_TX_C_DP<0>")
	)
	(segment
		(start 7.12978 -318.02959)
		(end 7.74065 -317.637668)
		(width 0.14732)
		(layer "In4.Cu")
		(net "P2E_MB_BMC_TX_C_DP<0>")
	)
	(segment
		(start 33.52673 -90.717116)
		(end 34.064448 -90.179398)
		(width 0.14732)
		(layer "In4.Cu")
		(net "P2E_MB_BMC_TX_C_DP<0>")
	)
	(segment
		(start 37.21989 -87.637112)
		(end 47.35576 -83.438492)
		(width 0.14732)
		(layer "In4.Cu")
		(net "P2E_MB_BMC_TX_C_DP<0>")
	)
	(segment
		(start 59.661806 -56.659526)
		(end 59.740292 -56.470042)
		(width 0.14732)
		(layer "In4.Cu")
		(net "P2E_MB_BMC_TX_C_DP<0>")
	)
	(segment
		(start 25.36698 -374.350788)
		(end 17.96796 -366.951768)
		(width 0.14732)
		(layer "In4.Cu")
		(net "P2E_MB_BMC_TX_C_DP<0>")
	)
	(segment
		(start 20.14728 -385.445)
		(end 20.31746 -385.445)
		(width 0.14732)
		(layer "In4.Cu")
		(net "P2E_MB_BMC_TX_C_DP<0>")
	)
	(segment
		(start 103.864664 -30.743144)
		(end 105.468928 -29.138626)
		(width 0.14732)
		(layer "In4.Cu")
		(net "P2E_MB_BMC_TX_C_DP<0>")
	)
	(segment
		(start 14.67231 -353.496118)
		(end 7.848854 -353.496118)
		(width 0.14732)
		(layer "In4.Cu")
		(net "P2E_MB_BMC_TX_C_DP<0>")
	)
	(segment
		(start 132.583428 -18.76171)
		(end 132.583428 -18.439384)
		(width 0.14732)
		(layer "In4.Cu")
		(net "P2E_MB_BMC_TX_C_DP<0>")
	)
	(segment
		(start 12.558014 -224.264474)
		(end 12.558014 -224.26422)
		(width 0.14732)
		(layer "In4.Cu")
		(net "P2E_MB_BMC_TX_C_DP<0>")
	)
	(segment
		(start 14.929866 -185.674508)
		(end 23.377144 -113.255552)
		(width 0.14732)
		(layer "In4.Cu")
		(net "P2E_MB_BMC_TX_C_DP<0>")
	)
	(segment
		(start 22.28596 -387.4135)
		(end 24.436832 -387.4135)
		(width 0.14732)
		(layer "In4.Cu")
		(net "P2E_MB_BMC_TX_C_DP<0>")
	)
	(segment
		(start 19.84248 -385.784344)
		(end 19.84248 -385.7498)
		(width 0.14732)
		(layer "In4.Cu")
		(net "P2E_MB_BMC_TX_C_DP<0>")
	)
	(segment
		(start 36.595304 -87.895938)
		(end 36.754816 -87.961724)
		(width 0.14732)
		(layer "In4.Cu")
		(net "P2E_MB_BMC_TX_C_DP<0>")
	)
	(segment
		(start 74.803 -52.656994)
		(end 82.323432 -45.136816)
		(width 0.14732)
		(layer "In4.Cu")
		(net "P2E_MB_BMC_TX_C_DP<0>")
	)
	(segment
		(start 34.53003 -89.91854)
		(end 34.53003 -89.713816)
		(width 0.14732)
		(layer "In4.Cu")
		(net "P2E_MB_BMC_TX_C_DP<0>")
	)
	(segment
		(start 20.31746 -385.445)
		(end 22.28596 -387.4135)
		(width 0.14732)
		(layer "In4.Cu")
		(net "P2E_MB_BMC_TX_C_DP<0>")
	)
	(segment
		(start 60.498228 -56.156098)
		(end 71.766938 -53.914548)
		(width 0.14732)
		(layer "In4.Cu")
		(net "P2E_MB_BMC_TX_C_DP<0>")
	)
	(segment
		(start 35.56635 -88.677496)
		(end 36.173156 -88.07069)
		(width 0.14732)
		(layer "In4.Cu")
		(net "P2E_MB_BMC_TX_C_DP<0>")
	)
	(segment
		(start 4.4704 -348.77883)
		(end 4.4704 -320.407792)
		(width 0.14732)
		(layer "In4.Cu")
		(net "P2E_MB_BMC_TX_C_DP<0>")
	)
	(segment
		(start 4.4704 -320.407792)
		(end 6.75767 -318.120776)
		(width 0.14732)
		(layer "In4.Cu")
		(net "P2E_MB_BMC_TX_C_DP<0>")
	)
	(segment
		(start 82.323432 -45.136816)
		(end 103.864664 -30.743144)
		(width 0.14732)
		(layer "In4.Cu")
		(net "P2E_MB_BMC_TX_C_DP<0>")
	)
	(segment
		(start 33.265872 -91.182698)
		(end 33.52673 -90.92184)
		(width 0.14732)
		(layer "In4.Cu")
		(net "P2E_MB_BMC_TX_C_DP<0>")
	)
	(segment
		(start 25.884886 -98.35896)
		(end 33.061148 -91.182698)
		(width 0.14732)
		(layer "In4.Cu")
		(net "P2E_MB_BMC_TX_C_DP<0>")
	)
	(segment
		(start 132.147056 -17.088612)
		(end 132.316728 -17.258284)
		(width 0.13208)
		(layer "F.Cu")
		(net "P2E_MB_BMC_TX_C_DN<0>")
	)
	(segment
		(start 132.147056 -16.550132)
		(end 132.147056 -17.088612)
		(width 0.13208)
		(layer "F.Cu")
		(net "P2E_MB_BMC_TX_C_DN<0>")
	)
	(segment
		(start 132.316728 -17.258284)
		(end 132.316728 -17.842484)
		(width 0.13208)
		(layer "F.Cu")
		(net "P2E_MB_BMC_TX_C_DN<0>")
	)
	(segment
		(start 132.316728 -17.842484)
		(end 132.014468 -18.144744)
		(width 0.13208)
		(layer "F.Cu")
		(net "P2E_MB_BMC_TX_C_DN<0>")
	)
	(segment
		(start 20.485608 -385.466844)
		(end 20.38858 -385.466844)
		(width 0.13208)
		(layer "F.Cu")
		(net "P2E_MB_BMC_TX_C_DN<0>")
	)
	(segment
		(start 20.38858 -385.466844)
		(end 19.84248 -384.920744)
		(width 0.13208)
		(layer "F.Cu")
		(net "P2E_MB_BMC_TX_C_DN<0>")
	)
	(segment
		(start 24.97074 -383.60096)
		(end 24.97074 -383.16916)
		(width 0.14732)
		(layer "In4.Cu")
		(net "P2E_MB_BMC_TX_C_DN<0>")
	)
	(segment
		(start 20.431252 -385.17068)
		(end 21.61667 -386.356098)
		(width 0.14732)
		(layer "In4.Cu")
		(net "P2E_MB_BMC_TX_C_DN<0>")
	)
	(segment
		(start 25.628854 -98.22688)
		(end 36.017708 -87.838026)
		(width 0.14732)
		(layer "In4.Cu")
		(net "P2E_MB_BMC_TX_C_DN<0>")
	)
	(segment
		(start 13.772388 -188.363352)
		(end 14.660372 -185.615834)
		(width 0.14732)
		(layer "In4.Cu")
		(net "P2E_MB_BMC_TX_C_DN<0>")
	)
	(segment
		(start 47.200312 -83.205828)
		(end 50.917856 -79.488284)
		(width 0.14732)
		(layer "In4.Cu")
		(net "P2E_MB_BMC_TX_C_DN<0>")
	)
	(segment
		(start 7.735062 -353.770438)
		(end 5.18414 -351.219516)
		(width 0.14732)
		(layer "In4.Cu")
		(net "P2E_MB_BMC_TX_C_DN<0>")
	)
	(segment
		(start 5.18414 -351.219516)
		(end 4.19608 -348.83344)
		(width 0.14732)
		(layer "In4.Cu")
		(net "P2E_MB_BMC_TX_C_DN<0>")
	)
	(segment
		(start 23.896066 -373.267986)
		(end 17.69364 -367.06556)
		(width 0.14732)
		(layer "In4.Cu")
		(net "P2E_MB_BMC_TX_C_DN<0>")
	)
	(segment
		(start 23.2156 -387.13918)
		(end 23.33752 -387.01726)
		(width 0.14732)
		(layer "In4.Cu")
		(net "P2E_MB_BMC_TX_C_DN<0>")
	)
	(segment
		(start 25.09266 -379.29312)
		(end 24.97074 -379.1712)
		(width 0.14732)
		(layer "In4.Cu")
		(net "P2E_MB_BMC_TX_C_DN<0>")
	)
	(segment
		(start 129.05994 -18.97634)
		(end 129.18186 -18.85442)
		(width 0.14732)
		(layer "In4.Cu")
		(net "P2E_MB_BMC_TX_C_DN<0>")
	)
	(segment
		(start 6.617716 -317.872364)
		(end 7.020052 -317.773812)
		(width 0.14732)
		(layer "In4.Cu")
		(net "P2E_MB_BMC_TX_C_DN<0>")
	)
	(segment
		(start 132.309108 -18.439384)
		(end 132.014468 -18.144744)
		(width 0.14732)
		(layer "In4.Cu")
		(net "P2E_MB_BMC_TX_C_DN<0>")
	)
	(segment
		(start 12.884658 -191.110108)
		(end 13.772388 -188.363098)
		(width 0.14732)
		(layer "In4.Cu")
		(net "P2E_MB_BMC_TX_C_DN<0>")
	)
	(segment
		(start 24.97074 -378.06376)
		(end 24.97074 -377.63196)
		(width 0.14732)
		(layer "In4.Cu")
		(net "P2E_MB_BMC_TX_C_DN<0>")
	)
	(segment
		(start 24.97074 -380.27864)
		(end 24.97074 -379.84684)
		(width 0.14732)
		(layer "In4.Cu")
		(net "P2E_MB_BMC_TX_C_DN<0>")
	)
	(segment
		(start 24.97074 -379.84684)
		(end 25.09266 -379.72492)
		(width 0.14732)
		(layer "In4.Cu")
		(net "P2E_MB_BMC_TX_C_DN<0>")
	)
	(segment
		(start 22.094444 -386.833872)
		(end 22.399752 -387.13918)
		(width 0.14732)
		(layer "In4.Cu")
		(net "P2E_MB_BMC_TX_C_DN<0>")
	)
	(segment
		(start 25.09266 -386.36956)
		(end 25.09266 -385.93776)
		(width 0.14732)
		(layer "In4.Cu")
		(net "P2E_MB_BMC_TX_C_DN<0>")
	)
	(segment
		(start 21.788882 -386.356098)
		(end 22.094444 -386.66166)
		(width 0.14732)
		(layer "In4.Cu")
		(net "P2E_MB_BMC_TX_C_DN<0>")
	)
	(segment
		(start 17.69364 -356.90556)
		(end 14.558518 -353.770438)
		(width 0.14732)
		(layer "In4.Cu")
		(net "P2E_MB_BMC_TX_C_DN<0>")
	)
	(segment
		(start 24.97074 -377.63196)
		(end 25.09266 -377.51004)
		(width 0.14732)
		(layer "In4.Cu")
		(net "P2E_MB_BMC_TX_C_DN<0>")
	)
	(segment
		(start 23.76932 -387.01726)
		(end 23.89124 -387.13918)
		(width 0.14732)
		(layer "In4.Cu")
		(net "P2E_MB_BMC_TX_C_DN<0>")
	)
	(segment
		(start 60.418218 -55.892192)
		(end 71.686928 -53.650642)
		(width 0.14732)
		(layer "In4.Cu")
		(net "P2E_MB_BMC_TX_C_DN<0>")
	)
	(segment
		(start 12.06246 -253.982728)
		(end 12.504928 -194.541394)
		(width 0.14732)
		(layer "In4.Cu")
		(net "P2E_MB_BMC_TX_C_DN<0>")
	)
	(segment
		(start 17.69364 -367.06556)
		(end 17.69364 -356.90556)
		(width 0.14732)
		(layer "In4.Cu")
		(net "P2E_MB_BMC_TX_C_DN<0>")
	)
	(segment
		(start 24.374094 -373.746014)
		(end 24.201628 -373.746014)
		(width 0.14732)
		(layer "In4.Cu")
		(net "P2E_MB_BMC_TX_C_DN<0>")
	)
	(segment
		(start 103.689658 -30.529784)
		(end 106.923078 -27.296364)
		(width 0.14732)
		(layer "In4.Cu")
		(net "P2E_MB_BMC_TX_C_DN<0>")
	)
	(segment
		(start 25.09266 -380.83236)
		(end 25.09266 -380.40056)
		(width 0.14732)
		(layer "In4.Cu")
		(net "P2E_MB_BMC_TX_C_DN<0>")
	)
	(segment
		(start 25.09266 -383.04724)
		(end 25.09266 -382.61544)
		(width 0.14732)
		(layer "In4.Cu")
		(net "P2E_MB_BMC_TX_C_DN<0>")
	)
	(segment
		(start 23.33752 -387.01726)
		(end 23.76932 -387.01726)
		(width 0.14732)
		(layer "In4.Cu")
		(net "P2E_MB_BMC_TX_C_DN<0>")
	)
	(segment
		(start 24.201628 -373.746014)
		(end 23.896066 -373.440452)
		(width 0.14732)
		(layer "In4.Cu")
		(net "P2E_MB_BMC_TX_C_DN<0>")
	)
	(segment
		(start 23.896066 -373.440452)
		(end 23.896066 -373.267986)
		(width 0.14732)
		(layer "In4.Cu")
		(net "P2E_MB_BMC_TX_C_DN<0>")
	)
	(segment
		(start 25.09266 -383.72288)
		(end 24.97074 -383.60096)
		(width 0.14732)
		(layer "In4.Cu")
		(net "P2E_MB_BMC_TX_C_DN<0>")
	)
	(segment
		(start 123.24207 -21.52015)
		(end 125.389386 -19.372834)
		(width 0.14732)
		(layer "In4.Cu")
		(net "P2E_MB_BMC_TX_C_DN<0>")
	)
	(segment
		(start 23.89124 -387.13918)
		(end 24.32304 -387.13918)
		(width 0.14732)
		(layer "In4.Cu")
		(net "P2E_MB_BMC_TX_C_DN<0>")
	)
	(segment
		(start 71.686928 -53.650642)
		(end 74.647552 -52.42433)
		(width 0.14732)
		(layer "In4.Cu")
		(net "P2E_MB_BMC_TX_C_DN<0>")
	)
	(segment
		(start 12.884404 -191.110108)
		(end 12.884658 -191.110108)
		(width 0.14732)
		(layer "In4.Cu")
		(net "P2E_MB_BMC_TX_C_DN<0>")
	)
	(segment
		(start 24.97074 -382.06172)
		(end 25.09266 -381.9398)
		(width 0.14732)
		(layer "In4.Cu")
		(net "P2E_MB_BMC_TX_C_DN<0>")
	)
	(segment
		(start 21.61667 -386.356098)
		(end 21.788882 -386.356098)
		(width 0.14732)
		(layer "In4.Cu")
		(net "P2E_MB_BMC_TX_C_DN<0>")
	)
	(segment
		(start 7.020052 -317.773812)
		(end 7.521956 -317.45174)
		(width 0.14732)
		(layer "In4.Cu")
		(net "P2E_MB_BMC_TX_C_DN<0>")
	)
	(segment
		(start 9.74598 -314.008008)
		(end 10.38606 -258.282948)
		(width 0.14732)
		(layer "In4.Cu")
		(net "P2E_MB_BMC_TX_C_DN<0>")
	)
	(segment
		(start 12.876022 -191.136778)
		(end 12.884404 -191.110108)
		(width 0.14732)
		(layer "In4.Cu")
		(net "P2E_MB_BMC_TX_C_DN<0>")
	)
	(segment
		(start 4.19608 -320.294)
		(end 6.617716 -317.872364)
		(width 0.14732)
		(layer "In4.Cu")
		(net "P2E_MB_BMC_TX_C_DN<0>")
	)
	(segment
		(start 14.558518 -353.770438)
		(end 7.735062 -353.770438)
		(width 0.14732)
		(layer "In4.Cu")
		(net "P2E_MB_BMC_TX_C_DN<0>")
	)
	(segment
		(start 23.105364 -113.216944)
		(end 25.628854 -98.22688)
		(width 0.14732)
		(layer "In4.Cu")
		(net "P2E_MB_BMC_TX_C_DN<0>")
	)
	(segment
		(start 57.941464 -56.918352)
		(end 60.418218 -55.892192)
		(width 0.14732)
		(layer "In4.Cu")
		(net "P2E_MB_BMC_TX_C_DN<0>")
	)
	(segment
		(start 24.97074 -385.38404)
		(end 25.09266 -385.26212)
		(width 0.14732)
		(layer "In4.Cu")
		(net "P2E_MB_BMC_TX_C_DN<0>")
	)
	(segment
		(start 12.504928 -194.541394)
		(end 12.876022 -191.136778)
		(width 0.14732)
		(layer "In4.Cu")
		(net "P2E_MB_BMC_TX_C_DN<0>")
	)
	(segment
		(start 106.923078 -27.296364)
		(end 123.24207 -21.52015)
		(width 0.14732)
		(layer "In4.Cu")
		(net "P2E_MB_BMC_TX_C_DN<0>")
	)
	(segment
		(start 24.97074 -381.38608)
		(end 24.97074 -380.95428)
		(width 0.14732)
		(layer "In4.Cu")
		(net "P2E_MB_BMC_TX_C_DN<0>")
	)
	(segment
		(start 24.97074 -384.2766)
		(end 25.09266 -384.15468)
		(width 0.14732)
		(layer "In4.Cu")
		(net "P2E_MB_BMC_TX_C_DN<0>")
	)
	(segment
		(start 129.73558 -18.97634)
		(end 131.980686 -18.97634)
		(width 0.14732)
		(layer "In4.Cu")
		(net "P2E_MB_BMC_TX_C_DN<0>")
	)
	(segment
		(start 36.017708 -87.838026)
		(end 47.200312 -83.205828)
		(width 0.14732)
		(layer "In4.Cu")
		(net "P2E_MB_BMC_TX_C_DN<0>")
	)
	(segment
		(start 129.61366 -18.85442)
		(end 129.73558 -18.97634)
		(width 0.14732)
		(layer "In4.Cu")
		(net "P2E_MB_BMC_TX_C_DN<0>")
	)
	(segment
		(start 7.521956 -317.45174)
		(end 8.58012 -315.008768)
		(width 0.14732)
		(layer "In4.Cu")
		(net "P2E_MB_BMC_TX_C_DN<0>")
	)
	(segment
		(start 24.97074 -385.81584)
		(end 24.97074 -385.38404)
		(width 0.14732)
		(layer "In4.Cu")
		(net "P2E_MB_BMC_TX_C_DN<0>")
	)
	(segment
		(start 132.309108 -18.647918)
		(end 132.309108 -18.439384)
		(width 0.14732)
		(layer "In4.Cu")
		(net "P2E_MB_BMC_TX_C_DN<0>")
	)
	(segment
		(start 25.09266 -381.9398)
		(end 25.09266 -381.508)
		(width 0.14732)
		(layer "In4.Cu")
		(net "P2E_MB_BMC_TX_C_DN<0>")
	)
	(segment
		(start 24.97074 -380.95428)
		(end 25.09266 -380.83236)
		(width 0.14732)
		(layer "In4.Cu")
		(net "P2E_MB_BMC_TX_C_DN<0>")
	)
	(segment
		(start 8.58012 -315.008768)
		(end 9.519666 -314.312808)
		(width 0.14732)
		(layer "In4.Cu")
		(net "P2E_MB_BMC_TX_C_DN<0>")
	)
	(segment
		(start 4.19608 -348.83344)
		(end 4.19608 -320.294)
		(width 0.14732)
		(layer "In4.Cu")
		(net "P2E_MB_BMC_TX_C_DN<0>")
	)
	(segment
		(start 22.094444 -386.66166)
		(end 22.094444 -386.833872)
		(width 0.14732)
		(layer "In4.Cu")
		(net "P2E_MB_BMC_TX_C_DN<0>")
	)
	(segment
		(start 19.84248 -384.920744)
		(end 20.092416 -385.17068)
		(width 0.14732)
		(layer "In4.Cu")
		(net "P2E_MB_BMC_TX_C_DN<0>")
	)
	(segment
		(start 24.97074 -383.16916)
		(end 25.09266 -383.04724)
		(width 0.14732)
		(layer "In4.Cu")
		(net "P2E_MB_BMC_TX_C_DN<0>")
	)
	(segment
		(start 25.09266 -381.508)
		(end 24.97074 -381.38608)
		(width 0.14732)
		(layer "In4.Cu")
		(net "P2E_MB_BMC_TX_C_DN<0>")
	)
	(segment
		(start 22.399752 -387.13918)
		(end 23.2156 -387.13918)
		(width 0.14732)
		(layer "In4.Cu")
		(net "P2E_MB_BMC_TX_C_DN<0>")
	)
	(segment
		(start 24.97074 -379.1712)
		(end 24.97074 -378.7394)
		(width 0.14732)
		(layer "In4.Cu")
		(net "P2E_MB_BMC_TX_C_DN<0>")
	)
	(segment
		(start 52.96154 -74.554588)
		(end 52.96154 -61.898276)
		(width 0.14732)
		(layer "In4.Cu")
		(net "P2E_MB_BMC_TX_C_DN<0>")
	)
	(segment
		(start 14.660372 -185.615834)
		(end 23.105364 -113.216944)
		(width 0.14732)
		(layer "In4.Cu")
		(net "P2E_MB_BMC_TX_C_DN<0>")
	)
	(segment
		(start 126.346458 -18.97634)
		(end 129.05994 -18.97634)
		(width 0.14732)
		(layer "In4.Cu")
		(net "P2E_MB_BMC_TX_C_DN<0>")
	)
	(segment
		(start 25.09266 -384.83032)
		(end 24.97074 -384.7084)
		(width 0.14732)
		(layer "In4.Cu")
		(net "P2E_MB_BMC_TX_C_DN<0>")
	)
	(segment
		(start 52.96154 -61.898276)
		(end 57.941464 -56.918352)
		(width 0.14732)
		(layer "In4.Cu")
		(net "P2E_MB_BMC_TX_C_DN<0>")
	)
	(segment
		(start 129.18186 -18.85442)
		(end 129.61366 -18.85442)
		(width 0.14732)
		(layer "In4.Cu")
		(net "P2E_MB_BMC_TX_C_DN<0>")
	)
	(segment
		(start 82.148426 -44.923456)
		(end 103.689658 -30.529784)
		(width 0.14732)
		(layer "In4.Cu")
		(net "P2E_MB_BMC_TX_C_DN<0>")
	)
	(segment
		(start 24.97074 -384.7084)
		(end 24.97074 -384.2766)
		(width 0.14732)
		(layer "In4.Cu")
		(net "P2E_MB_BMC_TX_C_DN<0>")
	)
	(segment
		(start 50.917856 -79.488284)
		(end 52.96154 -74.554588)
		(width 0.14732)
		(layer "In4.Cu")
		(net "P2E_MB_BMC_TX_C_DN<0>")
	)
	(segment
		(start 24.97074 -382.49352)
		(end 24.97074 -382.06172)
		(width 0.14732)
		(layer "In4.Cu")
		(net "P2E_MB_BMC_TX_C_DN<0>")
	)
	(segment
		(start 25.09266 -378.18568)
		(end 24.97074 -378.06376)
		(width 0.14732)
		(layer "In4.Cu")
		(net "P2E_MB_BMC_TX_C_DN<0>")
	)
	(segment
		(start 20.092416 -385.17068)
		(end 20.431252 -385.17068)
		(width 0.14732)
		(layer "In4.Cu")
		(net "P2E_MB_BMC_TX_C_DN<0>")
	)
	(segment
		(start 74.647552 -52.42433)
		(end 82.148426 -44.923456)
		(width 0.14732)
		(layer "In4.Cu")
		(net "P2E_MB_BMC_TX_C_DN<0>")
	)
	(segment
		(start 25.09266 -385.26212)
		(end 25.09266 -384.83032)
		(width 0.14732)
		(layer "In4.Cu")
		(net "P2E_MB_BMC_TX_C_DN<0>")
	)
	(segment
		(start 25.09266 -384.15468)
		(end 25.09266 -383.72288)
		(width 0.14732)
		(layer "In4.Cu")
		(net "P2E_MB_BMC_TX_C_DN<0>")
	)
	(segment
		(start 25.09266 -374.46458)
		(end 24.374094 -373.746014)
		(width 0.14732)
		(layer "In4.Cu")
		(net "P2E_MB_BMC_TX_C_DN<0>")
	)
	(segment
		(start 13.772388 -188.363098)
		(end 13.772388 -188.363352)
		(width 0.14732)
		(layer "In4.Cu")
		(net "P2E_MB_BMC_TX_C_DN<0>")
	)
	(segment
		(start 25.09266 -377.51004)
		(end 25.09266 -374.46458)
		(width 0.14732)
		(layer "In4.Cu")
		(net "P2E_MB_BMC_TX_C_DN<0>")
	)
	(segment
		(start 25.09266 -380.40056)
		(end 24.97074 -380.27864)
		(width 0.14732)
		(layer "In4.Cu")
		(net "P2E_MB_BMC_TX_C_DN<0>")
	)
	(segment
		(start 24.32304 -387.13918)
		(end 25.09266 -386.36956)
		(width 0.14732)
		(layer "In4.Cu")
		(net "P2E_MB_BMC_TX_C_DN<0>")
	)
	(segment
		(start 125.389386 -19.372834)
		(end 126.346458 -18.97634)
		(width 0.14732)
		(layer "In4.Cu")
		(net "P2E_MB_BMC_TX_C_DN<0>")
	)
	(segment
		(start 9.519666 -314.312808)
		(end 9.74598 -314.008008)
		(width 0.14732)
		(layer "In4.Cu")
		(net "P2E_MB_BMC_TX_C_DN<0>")
	)
	(segment
		(start 25.09266 -379.72492)
		(end 25.09266 -379.29312)
		(width 0.14732)
		(layer "In4.Cu")
		(net "P2E_MB_BMC_TX_C_DN<0>")
	)
	(segment
		(start 25.09266 -378.61748)
		(end 25.09266 -378.18568)
		(width 0.14732)
		(layer "In4.Cu")
		(net "P2E_MB_BMC_TX_C_DN<0>")
	)
	(segment
		(start 24.97074 -378.7394)
		(end 25.09266 -378.61748)
		(width 0.14732)
		(layer "In4.Cu")
		(net "P2E_MB_BMC_TX_C_DN<0>")
	)
	(segment
		(start 25.09266 -385.93776)
		(end 24.97074 -385.81584)
		(width 0.14732)
		(layer "In4.Cu")
		(net "P2E_MB_BMC_TX_C_DN<0>")
	)
	(segment
		(start 131.980686 -18.97634)
		(end 132.309108 -18.647918)
		(width 0.14732)
		(layer "In4.Cu")
		(net "P2E_MB_BMC_TX_C_DN<0>")
	)
	(segment
		(start 25.09266 -382.61544)
		(end 24.97074 -382.49352)
		(width 0.14732)
		(layer "In4.Cu")
		(net "P2E_MB_BMC_TX_C_DN<0>")
	)
	(segment
		(start 10.38606 -258.282948)
		(end 12.06246 -253.982728)
		(width 0.14732)
		(layer "In4.Cu")
		(net "P2E_MB_BMC_TX_C_DN<0>")
	)
	(segment
		(start 18.736818 -396.494)
		(end 19.0373 -396.494)
		(width 0.12954)
		(layer "F.Cu")
		(net "P2E_MB_BMC_TX_BUF_C_DP<0>")
	)
	(segment
		(start 18.640806 -396.410688)
		(end 18.653506 -396.410688)
		(width 0.12954)
		(layer "F.Cu")
		(net "P2E_MB_BMC_TX_BUF_C_DP<0>")
	)
	(segment
		(start 18.653506 -396.410688)
		(end 18.736818 -396.494)
		(width 0.12954)
		(layer "F.Cu")
		(net "P2E_MB_BMC_TX_BUF_C_DP<0>")
	)
	(segment
		(start 19.284188 -396.740888)
		(end 19.284188 -396.842996)
		(width 0.12954)
		(layer "F.Cu")
		(net "P2E_MB_BMC_TX_BUF_C_DP<0>")
	)
	(segment
		(start 19.0373 -396.494)
		(end 19.284188 -396.740888)
		(width 0.12954)
		(layer "F.Cu")
		(net "P2E_MB_BMC_TX_BUF_C_DP<0>")
	)
	(segment
		(start 34.698432 -402.755862)
		(end 34.627566 -402.563584)
		(width 0.14732)
		(layer "In15.Cu")
		(net "P2E_MB_BMC_TX_BUF_C_DP<0>")
	)
	(segment
		(start 48.61306 -408.620468)
		(end 40.317674 -405.184356)
		(width 0.14732)
		(layer "In15.Cu")
		(net "P2E_MB_BMC_TX_BUF_C_DP<0>")
	)
	(segment
		(start 20.8915 -397.652494)
		(end 19.787362 -396.548356)
		(width 0.14732)
		(layer "In15.Cu")
		(net "P2E_MB_BMC_TX_BUF_C_DP<0>")
	)
	(segment
		(start 69.49694 -416.573208)
		(end 68.948808 -416.025076)
		(width 0.14732)
		(layer "In15.Cu")
		(net "P2E_MB_BMC_TX_BUF_C_DP<0>")
	)
	(segment
		(start 35.033204 -402.91004)
		(end 34.698432 -402.755862)
		(width 0.14732)
		(layer "In15.Cu")
		(net "P2E_MB_BMC_TX_BUF_C_DP<0>")
	)
	(segment
		(start 23.152862 -401.071842)
		(end 20.8915 -398.81048)
		(width 0.14732)
		(layer "In15.Cu")
		(net "P2E_MB_BMC_TX_BUF_C_DP<0>")
	)
	(segment
		(start 35.225228 -402.83892)
		(end 35.033204 -402.91004)
		(width 0.14732)
		(layer "In15.Cu")
		(net "P2E_MB_BMC_TX_BUF_C_DP<0>")
	)
	(segment
		(start 34.038032 -402.45157)
		(end 33.70326 -402.297646)
		(width 0.14732)
		(layer "In15.Cu")
		(net "P2E_MB_BMC_TX_BUF_C_DP<0>")
	)
	(segment
		(start 66.468498 -409.349702)
		(end 66.31686 -408.98318)
		(width 0.14732)
		(layer "In15.Cu")
		(net "P2E_MB_BMC_TX_BUF_C_DP<0>")
	)
	(segment
		(start 30.401768 -401.6375)
		(end 29.81198 -401.6375)
		(width 0.14732)
		(layer "In15.Cu")
		(net "P2E_MB_BMC_TX_BUF_C_DP<0>")
	)
	(segment
		(start 31.077408 -401.6375)
		(end 30.955488 -401.75942)
		(width 0.14732)
		(layer "In15.Cu")
		(net "P2E_MB_BMC_TX_BUF_C_DP<0>")
	)
	(segment
		(start 68.062602 -415.13887)
		(end 66.468498 -411.290262)
		(width 0.14732)
		(layer "In15.Cu")
		(net "P2E_MB_BMC_TX_BUF_C_DP<0>")
	)
	(segment
		(start 33.632394 -402.105368)
		(end 32.616648 -401.6375)
		(width 0.14732)
		(layer "In15.Cu")
		(net "P2E_MB_BMC_TX_BUF_C_DP<0>")
	)
	(segment
		(start 68.490592 -415.56686)
		(end 68.062602 -415.13887)
		(width 0.14732)
		(layer "In15.Cu")
		(net "P2E_MB_BMC_TX_BUF_C_DP<0>")
	)
	(segment
		(start 31.509208 -401.6375)
		(end 31.077408 -401.6375)
		(width 0.14732)
		(layer "In15.Cu")
		(net "P2E_MB_BMC_TX_BUF_C_DP<0>")
	)
	(segment
		(start 29.25826 -401.75942)
		(end 29.13634 -401.6375)
		(width 0.14732)
		(layer "In15.Cu")
		(net "P2E_MB_BMC_TX_BUF_C_DP<0>")
	)
	(segment
		(start 24.518366 -401.6375)
		(end 23.152862 -401.071842)
		(width 0.14732)
		(layer "In15.Cu")
		(net "P2E_MB_BMC_TX_BUF_C_DP<0>")
	)
	(segment
		(start 68.751196 -416.025076)
		(end 68.490592 -415.764472)
		(width 0.14732)
		(layer "In15.Cu")
		(net "P2E_MB_BMC_TX_BUF_C_DP<0>")
	)
	(segment
		(start 28.0289 -401.6375)
		(end 24.518366 -401.6375)
		(width 0.14732)
		(layer "In15.Cu")
		(net "P2E_MB_BMC_TX_BUF_C_DP<0>")
	)
	(segment
		(start 29.81198 -401.6375)
		(end 29.69006 -401.75942)
		(width 0.14732)
		(layer "In15.Cu")
		(net "P2E_MB_BMC_TX_BUF_C_DP<0>")
	)
	(segment
		(start 66.31686 -408.98318)
		(end 66.15684 -408.82316)
		(width 0.14732)
		(layer "In15.Cu")
		(net "P2E_MB_BMC_TX_BUF_C_DP<0>")
	)
	(segment
		(start 31.631128 -401.75942)
		(end 31.509208 -401.6375)
		(width 0.14732)
		(layer "In15.Cu")
		(net "P2E_MB_BMC_TX_BUF_C_DP<0>")
	)
	(segment
		(start 28.58262 -401.75942)
		(end 28.15082 -401.75942)
		(width 0.14732)
		(layer "In15.Cu")
		(net "P2E_MB_BMC_TX_BUF_C_DP<0>")
	)
	(segment
		(start 65.667636 -408.620468)
		(end 48.61306 -408.620468)
		(width 0.14732)
		(layer "In15.Cu")
		(net "P2E_MB_BMC_TX_BUF_C_DP<0>")
	)
	(segment
		(start 33.70326 -402.297646)
		(end 33.632394 -402.105368)
		(width 0.14732)
		(layer "In15.Cu")
		(net "P2E_MB_BMC_TX_BUF_C_DP<0>")
	)
	(segment
		(start 32.062928 -401.75942)
		(end 31.631128 -401.75942)
		(width 0.14732)
		(layer "In15.Cu")
		(net "P2E_MB_BMC_TX_BUF_C_DP<0>")
	)
	(segment
		(start 69.370702 -420.303198)
		(end 69.49694 -420.17696)
		(width 0.14732)
		(layer "In15.Cu")
		(net "P2E_MB_BMC_TX_BUF_C_DP<0>")
	)
	(segment
		(start 69.063362 -420.303198)
		(end 69.370702 -420.303198)
		(width 0.14732)
		(layer "In15.Cu")
		(net "P2E_MB_BMC_TX_BUF_C_DP<0>")
	)
	(segment
		(start 35.7759 -403.092412)
		(end 35.225228 -402.83892)
		(width 0.14732)
		(layer "In15.Cu")
		(net "P2E_MB_BMC_TX_BUF_C_DP<0>")
	)
	(segment
		(start 30.523688 -401.75942)
		(end 30.401768 -401.6375)
		(width 0.14732)
		(layer "In15.Cu")
		(net "P2E_MB_BMC_TX_BUF_C_DP<0>")
	)
	(segment
		(start 30.955488 -401.75942)
		(end 30.523688 -401.75942)
		(width 0.14732)
		(layer "In15.Cu")
		(net "P2E_MB_BMC_TX_BUF_C_DP<0>")
	)
	(segment
		(start 29.69006 -401.75942)
		(end 29.25826 -401.75942)
		(width 0.14732)
		(layer "In15.Cu")
		(net "P2E_MB_BMC_TX_BUF_C_DP<0>")
	)
	(segment
		(start 68.650104 -419.88994)
		(end 69.063362 -420.303198)
		(width 0.14732)
		(layer "In15.Cu")
		(net "P2E_MB_BMC_TX_BUF_C_DP<0>")
	)
	(segment
		(start 66.15684 -408.82316)
		(end 65.667636 -408.620468)
		(width 0.14732)
		(layer "In15.Cu")
		(net "P2E_MB_BMC_TX_BUF_C_DP<0>")
	)
	(segment
		(start 20.8915 -398.81048)
		(end 20.8915 -397.652494)
		(width 0.14732)
		(layer "In15.Cu")
		(net "P2E_MB_BMC_TX_BUF_C_DP<0>")
	)
	(segment
		(start 35.776154 -403.093174)
		(end 35.7759 -403.092412)
		(width 0.14732)
		(layer "In15.Cu")
		(net "P2E_MB_BMC_TX_BUF_C_DP<0>")
	)
	(segment
		(start 29.13634 -401.6375)
		(end 28.70454 -401.6375)
		(width 0.14732)
		(layer "In15.Cu")
		(net "P2E_MB_BMC_TX_BUF_C_DP<0>")
	)
	(segment
		(start 34.627566 -402.563584)
		(end 34.230056 -402.380704)
		(width 0.14732)
		(layer "In15.Cu")
		(net "P2E_MB_BMC_TX_BUF_C_DP<0>")
	)
	(segment
		(start 28.70454 -401.6375)
		(end 28.58262 -401.75942)
		(width 0.14732)
		(layer "In15.Cu")
		(net "P2E_MB_BMC_TX_BUF_C_DP<0>")
	)
	(segment
		(start 19.787362 -396.548356)
		(end 19.578828 -396.548356)
		(width 0.14732)
		(layer "In15.Cu")
		(net "P2E_MB_BMC_TX_BUF_C_DP<0>")
	)
	(segment
		(start 68.490592 -415.764472)
		(end 68.490592 -415.56686)
		(width 0.14732)
		(layer "In15.Cu")
		(net "P2E_MB_BMC_TX_BUF_C_DP<0>")
	)
	(segment
		(start 40.317674 -405.184356)
		(end 35.776154 -403.093174)
		(width 0.14732)
		(layer "In15.Cu")
		(net "P2E_MB_BMC_TX_BUF_C_DP<0>")
	)
	(segment
		(start 68.948808 -416.025076)
		(end 68.751196 -416.025076)
		(width 0.14732)
		(layer "In15.Cu")
		(net "P2E_MB_BMC_TX_BUF_C_DP<0>")
	)
	(segment
		(start 19.578828 -396.548356)
		(end 19.284188 -396.842996)
		(width 0.14732)
		(layer "In15.Cu")
		(net "P2E_MB_BMC_TX_BUF_C_DP<0>")
	)
	(segment
		(start 66.468498 -411.290262)
		(end 66.468498 -409.349702)
		(width 0.14732)
		(layer "In15.Cu")
		(net "P2E_MB_BMC_TX_BUF_C_DP<0>")
	)
	(segment
		(start 28.15082 -401.75942)
		(end 28.0289 -401.6375)
		(width 0.14732)
		(layer "In15.Cu")
		(net "P2E_MB_BMC_TX_BUF_C_DP<0>")
	)
	(segment
		(start 34.230056 -402.380704)
		(end 34.038032 -402.45157)
		(width 0.14732)
		(layer "In15.Cu")
		(net "P2E_MB_BMC_TX_BUF_C_DP<0>")
	)
	(segment
		(start 32.184848 -401.6375)
		(end 32.062928 -401.75942)
		(width 0.14732)
		(layer "In15.Cu")
		(net "P2E_MB_BMC_TX_BUF_C_DP<0>")
	)
	(segment
		(start 69.49694 -420.17696)
		(end 69.49694 -416.573208)
		(width 0.14732)
		(layer "In15.Cu")
		(net "P2E_MB_BMC_TX_BUF_C_DP<0>")
	)
	(segment
		(start 32.616648 -401.6375)
		(end 32.184848 -401.6375)
		(width 0.14732)
		(layer "In15.Cu")
		(net "P2E_MB_BMC_TX_BUF_C_DP<0>")
	)
	(segment
		(start 19.927824 -396.411958)
		(end 19.71675 -396.411958)
		(width 0.12954)
		(layer "F.Cu")
		(net "P2E_MB_BMC_TX_BUF_C_DN<0>")
	)
	(segment
		(start 19.71675 -396.411958)
		(end 19.284188 -395.979396)
		(width 0.12954)
		(layer "F.Cu")
		(net "P2E_MB_BMC_TX_BUF_C_DN<0>")
	)
	(segment
		(start 21.16582 -397.538702)
		(end 19.901154 -396.274036)
		(width 0.14732)
		(layer "In15.Cu")
		(net "P2E_MB_BMC_TX_BUF_C_DN<0>")
	)
	(segment
		(start 19.578828 -396.274036)
		(end 19.284188 -395.979396)
		(width 0.14732)
		(layer "In15.Cu")
		(net "P2E_MB_BMC_TX_BUF_C_DN<0>")
	)
	(segment
		(start 40.427656 -404.932896)
		(end 35.998912 -402.893276)
		(width 0.14732)
		(layer "In15.Cu")
		(net "P2E_MB_BMC_TX_BUF_C_DN<0>")
	)
	(segment
		(start 69.77126 -420.290752)
		(end 69.77126 -416.459416)
		(width 0.14732)
		(layer "In15.Cu")
		(net "P2E_MB_BMC_TX_BUF_C_DN<0>")
	)
	(segment
		(start 23.30831 -400.839178)
		(end 21.16582 -398.696688)
		(width 0.14732)
		(layer "In15.Cu")
		(net "P2E_MB_BMC_TX_BUF_C_DN<0>")
	)
	(segment
		(start 35.890708 -402.842984)
		(end 32.686244 -401.367498)
		(width 0.14732)
		(layer "In15.Cu")
		(net "P2E_MB_BMC_TX_BUF_C_DN<0>")
	)
	(segment
		(start 21.16582 -398.696688)
		(end 21.16582 -397.538702)
		(width 0.14732)
		(layer "In15.Cu")
		(net "P2E_MB_BMC_TX_BUF_C_DN<0>")
	)
	(segment
		(start 69.77126 -416.459416)
		(end 68.295266 -414.983422)
		(width 0.14732)
		(layer "In15.Cu")
		(net "P2E_MB_BMC_TX_BUF_C_DN<0>")
	)
	(segment
		(start 47.363888 -407.806144)
		(end 40.427656 -404.932896)
		(width 0.14732)
		(layer "In15.Cu")
		(net "P2E_MB_BMC_TX_BUF_C_DN<0>")
	)
	(segment
		(start 35.998658 -402.892768)
		(end 35.89147 -402.843238)
		(width 0.14732)
		(layer "In15.Cu")
		(net "P2E_MB_BMC_TX_BUF_C_DN<0>")
	)
	(segment
		(start 48.66767 -408.346148)
		(end 47.962566 -408.054048)
		(width 0.14732)
		(layer "In15.Cu")
		(net "P2E_MB_BMC_TX_BUF_C_DN<0>")
	)
	(segment
		(start 66.312288 -408.590496)
		(end 65.722246 -408.346148)
		(width 0.14732)
		(layer "In15.Cu")
		(net "P2E_MB_BMC_TX_BUF_C_DN<0>")
	)
	(segment
		(start 32.681926 -401.36318)
		(end 24.572976 -401.36318)
		(width 0.14732)
		(layer "In15.Cu")
		(net "P2E_MB_BMC_TX_BUF_C_DN<0>")
	)
	(segment
		(start 35.998912 -402.893276)
		(end 35.998658 -402.892768)
		(width 0.14732)
		(layer "In15.Cu")
		(net "P2E_MB_BMC_TX_BUF_C_DN<0>")
	)
	(segment
		(start 47.962566 -408.054048)
		(end 47.887128 -407.871422)
		(width 0.14732)
		(layer "In15.Cu")
		(net "P2E_MB_BMC_TX_BUF_C_DN<0>")
	)
	(segment
		(start 68.295266 -414.983422)
		(end 66.742818 -411.235652)
		(width 0.14732)
		(layer "In15.Cu")
		(net "P2E_MB_BMC_TX_BUF_C_DN<0>")
	)
	(segment
		(start 69.112638 -420.627048)
		(end 69.434964 -420.627048)
		(width 0.14732)
		(layer "In15.Cu")
		(net "P2E_MB_BMC_TX_BUF_C_DN<0>")
	)
	(segment
		(start 68.650104 -421.089582)
		(end 69.112638 -420.627048)
		(width 0.14732)
		(layer "In15.Cu")
		(net "P2E_MB_BMC_TX_BUF_C_DN<0>")
	)
	(segment
		(start 66.742818 -409.295092)
		(end 66.549524 -408.827732)
		(width 0.14732)
		(layer "In15.Cu")
		(net "P2E_MB_BMC_TX_BUF_C_DN<0>")
	)
	(segment
		(start 68.650104 -421.089836)
		(end 68.650104 -421.089582)
		(width 0.14732)
		(layer "In15.Cu")
		(net "P2E_MB_BMC_TX_BUF_C_DN<0>")
	)
	(segment
		(start 69.434964 -420.627048)
		(end 69.77126 -420.290752)
		(width 0.14732)
		(layer "In15.Cu")
		(net "P2E_MB_BMC_TX_BUF_C_DN<0>")
	)
	(segment
		(start 47.546514 -407.730452)
		(end 47.363888 -407.806144)
		(width 0.14732)
		(layer "In15.Cu")
		(net "P2E_MB_BMC_TX_BUF_C_DN<0>")
	)
	(segment
		(start 35.89147 -402.843238)
		(end 35.890708 -402.842984)
		(width 0.14732)
		(layer "In15.Cu")
		(net "P2E_MB_BMC_TX_BUF_C_DN<0>")
	)
	(segment
		(start 24.572976 -401.36318)
		(end 23.30831 -400.839178)
		(width 0.14732)
		(layer "In15.Cu")
		(net "P2E_MB_BMC_TX_BUF_C_DN<0>")
	)
	(segment
		(start 19.901154 -396.274036)
		(end 19.578828 -396.274036)
		(width 0.14732)
		(layer "In15.Cu")
		(net "P2E_MB_BMC_TX_BUF_C_DN<0>")
	)
	(segment
		(start 65.722246 -408.346148)
		(end 48.66767 -408.346148)
		(width 0.14732)
		(layer "In15.Cu")
		(net "P2E_MB_BMC_TX_BUF_C_DN<0>")
	)
	(segment
		(start 66.549524 -408.827732)
		(end 66.312288 -408.590496)
		(width 0.14732)
		(layer "In15.Cu")
		(net "P2E_MB_BMC_TX_BUF_C_DN<0>")
	)
	(segment
		(start 66.742818 -411.235652)
		(end 66.742818 -409.295092)
		(width 0.14732)
		(layer "In15.Cu")
		(net "P2E_MB_BMC_TX_BUF_C_DN<0>")
	)
	(segment
		(start 47.887128 -407.871422)
		(end 47.546514 -407.730452)
		(width 0.14732)
		(layer "In15.Cu")
		(net "P2E_MB_BMC_TX_BUF_C_DN<0>")
	)
	(segment
		(start 32.686244 -401.367498)
		(end 32.681926 -401.36318)
		(width 0.14732)
		(layer "In15.Cu")
		(net "P2E_MB_BMC_TX_BUF_C_DN<0>")
	)
	(segment
		(start 20.513548 -392.255248)
		(end 20.513548 -391.92581)
		(width 0.13208)
		(layer "F.Cu")
		(net "P2E_MB_BMC_TX_BUF_DP<0>")
	)
	(segment
		(start 18.640806 -395.610588)
		(end 18.640806 -395.278102)
		(width 0.13208)
		(layer "F.Cu")
		(net "P2E_MB_BMC_TX_BUF_DP<0>")
	)
	(segment
		(start 19.155918 -394.612622)
		(end 20.55368 -393.21486)
		(width 0.13208)
		(layer "F.Cu")
		(net "P2E_MB_BMC_TX_BUF_DP<0>")
	)
	(segment
		(start 20.55368 -392.29538)
		(end 20.513548 -392.255248)
		(width 0.13208)
		(layer "F.Cu")
		(net "P2E_MB_BMC_TX_BUF_DP<0>")
	)
	(segment
		(start 20.55368 -393.21486)
		(end 20.55368 -392.29538)
		(width 0.13208)
		(layer "F.Cu")
		(net "P2E_MB_BMC_TX_BUF_DP<0>")
	)
	(segment
		(start 19.155918 -394.762228)
		(end 19.155918 -394.612622)
		(width 0.13208)
		(layer "F.Cu")
		(net "P2E_MB_BMC_TX_BUF_DP<0>")
	)
	(segment
		(start 18.640806 -395.278102)
		(end 18.654014 -395.264894)
		(width 0.13208)
		(layer "F.Cu")
		(net "P2E_MB_BMC_TX_BUF_DP<0>")
	)
	(segment
		(start 18.654014 -395.264894)
		(end 19.155918 -394.762228)
		(width 0.13208)
		(layer "F.Cu")
		(net "P2E_MB_BMC_TX_BUF_DP<0>")
	)
	(segment
		(start 19.927824 -395.302486)
		(end 19.915632 -395.290294)
		(width 0.13208)
		(layer "F.Cu")
		(net "P2E_MB_BMC_TX_BUF_DN<0>")
	)
	(segment
		(start 19.414998 -394.720064)
		(end 20.81276 -393.322302)
		(width 0.13208)
		(layer "F.Cu")
		(net "P2E_MB_BMC_TX_BUF_DN<0>")
	)
	(segment
		(start 19.414998 -394.788644)
		(end 19.414998 -394.720064)
		(width 0.13208)
		(layer "F.Cu")
		(net "P2E_MB_BMC_TX_BUF_DN<0>")
	)
	(segment
		(start 20.913598 -392.21664)
		(end 20.913598 -391.92581)
		(width 0.13208)
		(layer "F.Cu")
		(net "P2E_MB_BMC_TX_BUF_DN<0>")
	)
	(segment
		(start 20.81276 -392.317478)
		(end 20.913598 -392.21664)
		(width 0.13208)
		(layer "F.Cu")
		(net "P2E_MB_BMC_TX_BUF_DN<0>")
	)
	(segment
		(start 19.915632 -395.290294)
		(end 19.414998 -394.788644)
		(width 0.13208)
		(layer "F.Cu")
		(net "P2E_MB_BMC_TX_BUF_DN<0>")
	)
	(segment
		(start 20.81276 -393.322302)
		(end 20.81276 -392.317478)
		(width 0.13208)
		(layer "F.Cu")
		(net "P2E_MB_BMC_TX_BUF_DN<0>")
	)
	(segment
		(start 19.927824 -395.611858)
		(end 19.927824 -395.302486)
		(width 0.13208)
		(layer "F.Cu")
		(net "P2E_MB_BMC_TX_BUF_DN<0>")
	)
	(segment
		(start 25.3365 -396.742412)
		(end 25.8826 -397.288512)
		(width 0.13208)
		(layer "F.Cu")
		(net "P2E_MB_BMC_RX_DP<0>")
	)
	(segment
		(start 25.8826 -397.288512)
		(end 25.9715 -397.288512)
		(width 0.13208)
		(layer "F.Cu")
		(net "P2E_MB_BMC_RX_DP<0>")
	)
	(via
		(at 25.3365 -396.742412)
		(size 0.508)
		(drill 0.254)
		(layers "F.Cu" "B.Cu")
		(net "P2E_MB_BMC_RX_DP<0>")
	)
	(segment
		(start 26.931874 -397.044672)
		(end 32.350202 -402.463)
		(width 0.13208)
		(layer "B.Cu")
		(net "P2E_MB_BMC_RX_DP<0>")
	)
	(segment
		(start 32.350202 -402.463)
		(end 41.320212 -402.463)
		(width 0.13208)
		(layer "B.Cu")
		(net "P2E_MB_BMC_RX_DP<0>")
	)
	(segment
		(start 41.320212 -402.463)
		(end 43.054016 -404.196804)
		(width 0.13208)
		(layer "B.Cu")
		(net "P2E_MB_BMC_RX_DP<0>")
	)
	(segment
		(start 63.198248 -408.465528)
		(end 63.67526 -408.94254)
		(width 0.13208)
		(layer "B.Cu")
		(net "P2E_MB_BMC_RX_DP<0>")
	)
	(segment
		(start 25.3365 -396.742412)
		(end 25.63876 -397.044672)
		(width 0.13208)
		(layer "B.Cu")
		(net "P2E_MB_BMC_RX_DP<0>")
	)
	(segment
		(start 67.989196 -423.967148)
		(end 68.172838 -423.967148)
		(width 0.13208)
		(layer "B.Cu")
		(net "P2E_MB_BMC_RX_DP<0>")
	)
	(segment
		(start 67.73418 -415.944304)
		(end 67.73418 -423.712132)
		(width 0.13208)
		(layer "B.Cu")
		(net "P2E_MB_BMC_RX_DP<0>")
	)
	(segment
		(start 63.67526 -410.798772)
		(end 64.443864 -412.653988)
		(width 0.13208)
		(layer "B.Cu")
		(net "P2E_MB_BMC_RX_DP<0>")
	)
	(segment
		(start 63.67526 -408.94254)
		(end 63.67526 -410.798772)
		(width 0.13208)
		(layer "B.Cu")
		(net "P2E_MB_BMC_RX_DP<0>")
	)
	(segment
		(start 48.733964 -408.465528)
		(end 63.198248 -408.465528)
		(width 0.13208)
		(layer "B.Cu")
		(net "P2E_MB_BMC_RX_DP<0>")
	)
	(segment
		(start 45.463714 -405.195278)
		(end 48.733964 -408.465528)
		(width 0.13208)
		(layer "B.Cu")
		(net "P2E_MB_BMC_RX_DP<0>")
	)
	(segment
		(start 68.172838 -423.967148)
		(end 68.650104 -423.489882)
		(width 0.13208)
		(layer "B.Cu")
		(net "P2E_MB_BMC_RX_DP<0>")
	)
	(segment
		(start 67.73418 -423.712132)
		(end 67.989196 -423.967148)
		(width 0.13208)
		(layer "B.Cu")
		(net "P2E_MB_BMC_RX_DP<0>")
	)
	(segment
		(start 43.054016 -404.196804)
		(end 45.463714 -405.195278)
		(width 0.13208)
		(layer "B.Cu")
		(net "P2E_MB_BMC_RX_DP<0>")
	)
	(segment
		(start 64.443864 -412.653988)
		(end 67.73418 -415.944304)
		(width 0.13208)
		(layer "B.Cu")
		(net "P2E_MB_BMC_RX_DP<0>")
	)
	(segment
		(start 25.63876 -397.044672)
		(end 26.931874 -397.044672)
		(width 0.13208)
		(layer "B.Cu")
		(net "P2E_MB_BMC_RX_DP<0>")
	)
	(segment
		(start 25.01773 -397.287242)
		(end 24.684482 -397.287242)
		(width 0.13208)
		(layer "F.Cu")
		(net "P2E_MB_BMC_RX_DN<0>")
	)
	(segment
		(start 25.3365 -397.606012)
		(end 25.01773 -397.287242)
		(width 0.13208)
		(layer "F.Cu")
		(net "P2E_MB_BMC_RX_DN<0>")
	)
	(via
		(at 25.3365 -397.606012)
		(size 0.508)
		(drill 0.254)
		(layers "F.Cu" "B.Cu")
		(net "P2E_MB_BMC_RX_DN<0>")
	)
	(segment
		(start 63.41618 -409.049982)
		(end 63.41618 -410.850334)
		(width 0.13208)
		(layer "B.Cu")
		(net "P2E_MB_BMC_RX_DN<0>")
	)
	(segment
		(start 41.661842 -403.171406)
		(end 42.907204 -404.416514)
		(width 0.13208)
		(layer "B.Cu")
		(net "P2E_MB_BMC_RX_DN<0>")
	)
	(segment
		(start 26.824432 -397.303752)
		(end 32.24276 -402.72208)
		(width 0.13208)
		(layer "B.Cu")
		(net "P2E_MB_BMC_RX_DN<0>")
	)
	(segment
		(start 63.41618 -410.850334)
		(end 64.224154 -412.8008)
		(width 0.13208)
		(layer "B.Cu")
		(net "P2E_MB_BMC_RX_DN<0>")
	)
	(segment
		(start 67.881754 -424.226228)
		(end 68.186554 -424.226228)
		(width 0.13208)
		(layer "B.Cu")
		(net "P2E_MB_BMC_RX_DN<0>")
	)
	(segment
		(start 67.4751 -416.051746)
		(end 67.4751 -423.819574)
		(width 0.13208)
		(layer "B.Cu")
		(net "P2E_MB_BMC_RX_DN<0>")
	)
	(segment
		(start 32.24276 -402.72208)
		(end 41.21277 -402.72208)
		(width 0.13208)
		(layer "B.Cu")
		(net "P2E_MB_BMC_RX_DN<0>")
	)
	(segment
		(start 68.186554 -424.226228)
		(end 68.650104 -424.689778)
		(width 0.13208)
		(layer "B.Cu")
		(net "P2E_MB_BMC_RX_DN<0>")
	)
	(segment
		(start 67.4751 -423.819574)
		(end 67.881754 -424.226228)
		(width 0.13208)
		(layer "B.Cu")
		(net "P2E_MB_BMC_RX_DN<0>")
	)
	(segment
		(start 42.907204 -404.416514)
		(end 45.316902 -405.414988)
		(width 0.13208)
		(layer "B.Cu")
		(net "P2E_MB_BMC_RX_DN<0>")
	)
	(segment
		(start 41.21277 -402.72208)
		(end 41.661842 -403.171152)
		(width 0.13208)
		(layer "B.Cu")
		(net "P2E_MB_BMC_RX_DN<0>")
	)
	(segment
		(start 41.661842 -403.171152)
		(end 41.661842 -403.171406)
		(width 0.13208)
		(layer "B.Cu")
		(net "P2E_MB_BMC_RX_DN<0>")
	)
	(segment
		(start 45.316902 -405.414988)
		(end 48.626522 -408.724608)
		(width 0.13208)
		(layer "B.Cu")
		(net "P2E_MB_BMC_RX_DN<0>")
	)
	(segment
		(start 64.224154 -412.8008)
		(end 67.4751 -416.051746)
		(width 0.13208)
		(layer "B.Cu")
		(net "P2E_MB_BMC_RX_DN<0>")
	)
	(segment
		(start 25.3365 -397.606012)
		(end 25.63876 -397.303752)
		(width 0.13208)
		(layer "B.Cu")
		(net "P2E_MB_BMC_RX_DN<0>")
	)
	(segment
		(start 63.090806 -408.724608)
		(end 63.41618 -409.049982)
		(width 0.13208)
		(layer "B.Cu")
		(net "P2E_MB_BMC_RX_DN<0>")
	)
	(segment
		(start 25.63876 -397.303752)
		(end 26.824432 -397.303752)
		(width 0.13208)
		(layer "B.Cu")
		(net "P2E_MB_BMC_RX_DN<0>")
	)
	(segment
		(start 48.626522 -408.724608)
		(end 63.090806 -408.724608)
		(width 0.13208)
		(layer "B.Cu")
		(net "P2E_MB_BMC_RX_DN<0>")
	)
	(segment
		(start 132.747004 -13.019532)
		(end 132.576316 -12.848844)
		(width 0.13208)
		(layer "F.Cu")
		(net "P2E_MB_BMC_RX_BUF_DP<0>")
	)
	(segment
		(start 132.747004 -13.600176)
		(end 132.747004 -13.019532)
		(width 0.13208)
		(layer "F.Cu")
		(net "P2E_MB_BMC_RX_BUF_DP<0>")
	)
	(segment
		(start 23.767034 -385.378198)
		(end 23.545292 -385.378198)
		(width 0.12954)
		(layer "F.Cu")
		(net "P2E_MB_BMC_RX_BUF_DP<0>")
	)
	(segment
		(start 23.545292 -385.378198)
		(end 23.113492 -384.946398)
		(width 0.12954)
		(layer "F.Cu")
		(net "P2E_MB_BMC_RX_BUF_DP<0>")
	)
	(segment
		(start 132.576316 -11.315954)
		(end 132.58038 -11.31189)
		(width 0.13208)
		(layer "F.Cu")
		(net "P2E_MB_BMC_RX_BUF_DP<0>")
	)
	(segment
		(start 132.58038 -11.31189)
		(end 132.58038 -10.546588)
		(width 0.13208)
		(layer "F.Cu")
		(net "P2E_MB_BMC_RX_BUF_DP<0>")
	)
	(segment
		(start 132.58038 -10.546588)
		(end 132.883656 -10.243312)
		(width 0.13208)
		(layer "F.Cu")
		(net "P2E_MB_BMC_RX_BUF_DP<0>")
	)
	(segment
		(start 132.576316 -12.848844)
		(end 132.576316 -11.315954)
		(width 0.13208)
		(layer "F.Cu")
		(net "P2E_MB_BMC_RX_BUF_DP<0>")
	)
	(segment
		(start 17.307306 -372.055898)
		(end 17.141952 -371.656864)
		(width 0.14732)
		(layer "In4.Cu")
		(net "P2E_MB_BMC_RX_BUF_DP<0>")
	)
	(segment
		(start 17.830292 -373.637556)
		(end 17.665192 -373.238776)
		(width 0.14732)
		(layer "In4.Cu")
		(net "P2E_MB_BMC_RX_BUF_DP<0>")
	)
	(segment
		(start 118.518686 -21.600414)
		(end 123.488704 -16.630396)
		(width 0.14732)
		(layer "In4.Cu")
		(net "P2E_MB_BMC_RX_BUF_DP<0>")
	)
	(segment
		(start 17.406366 -372.61419)
		(end 17.241266 -372.21541)
		(width 0.14732)
		(layer "In4.Cu")
		(net "P2E_MB_BMC_RX_BUF_DP<0>")
	)
	(segment
		(start 106.705146 -26.493978)
		(end 118.518686 -21.600414)
		(width 0.14732)
		(layer "In4.Cu")
		(net "P2E_MB_BMC_RX_BUF_DP<0>")
	)
	(segment
		(start 132.589016 -10.537952)
		(end 132.883656 -10.243312)
		(width 0.14732)
		(layer "In4.Cu")
		(net "P2E_MB_BMC_RX_BUF_DP<0>")
	)
	(segment
		(start 22.182836 -113.57864)
		(end 24.850598 -97.733104)
		(width 0.14732)
		(layer "In4.Cu")
		(net "P2E_MB_BMC_RX_BUF_DP<0>")
	)
	(segment
		(start 130.377184 -15.352268)
		(end 131.319016 -14.962124)
		(width 0.14732)
		(layer "In4.Cu")
		(net "P2E_MB_BMC_RX_BUF_DP<0>")
	)
	(segment
		(start 132.589016 -13.692124)
		(end 132.589016 -10.537952)
		(width 0.14732)
		(layer "In4.Cu")
		(net "P2E_MB_BMC_RX_BUF_DP<0>")
	)
	(segment
		(start 8.509762 -253.295912)
		(end 10.116058 -251.936504)
		(width 0.14732)
		(layer "In4.Cu")
		(net "P2E_MB_BMC_RX_BUF_DP<0>")
	)
	(segment
		(start 131.319016 -14.962124)
		(end 132.589016 -13.692124)
		(width 0.14732)
		(layer "In4.Cu")
		(net "P2E_MB_BMC_RX_BUF_DP<0>")
	)
	(segment
		(start 6.323838 -258.491482)
		(end 8.169402 -253.957836)
		(width 0.14732)
		(layer "In4.Cu")
		(net "P2E_MB_BMC_RX_BUF_DP<0>")
	)
	(segment
		(start 17.731232 -373.079264)
		(end 17.565878 -372.68023)
		(width 0.14732)
		(layer "In4.Cu")
		(net "P2E_MB_BMC_RX_BUF_DP<0>")
	)
	(segment
		(start 10.508996 -194.76847)
		(end 13.727938 -186.06135)
		(width 0.14732)
		(layer "In4.Cu")
		(net "P2E_MB_BMC_RX_BUF_DP<0>")
	)
	(segment
		(start 17.241266 -372.21541)
		(end 17.307306 -372.055898)
		(width 0.14732)
		(layer "In4.Cu")
		(net "P2E_MB_BMC_RX_BUF_DP<0>")
	)
	(segment
		(start 10.116058 -251.936504)
		(end 10.508996 -194.76847)
		(width 0.14732)
		(layer "In4.Cu")
		(net "P2E_MB_BMC_RX_BUF_DP<0>")
	)
	(segment
		(start 17.989804 -373.703596)
		(end 17.830292 -373.637556)
		(width 0.14732)
		(layer "In4.Cu")
		(net "P2E_MB_BMC_RX_BUF_DP<0>")
	)
	(segment
		(start 18.089118 -374.262142)
		(end 18.155158 -374.10263)
		(width 0.14732)
		(layer "In4.Cu")
		(net "P2E_MB_BMC_RX_BUF_DP<0>")
	)
	(segment
		(start 18.155158 -374.10263)
		(end 17.989804 -373.703596)
		(width 0.14732)
		(layer "In4.Cu")
		(net "P2E_MB_BMC_RX_BUF_DP<0>")
	)
	(segment
		(start 24.850598 -97.733104)
		(end 35.284156 -87.299546)
		(width 0.14732)
		(layer "In4.Cu")
		(net "P2E_MB_BMC_RX_BUF_DP<0>")
	)
	(segment
		(start 22.80539 -385.2545)
		(end 22.47646 -385.2545)
		(width 0.14732)
		(layer "In4.Cu")
		(net "P2E_MB_BMC_RX_BUF_DP<0>")
	)
	(segment
		(start 128.56591 -15.352268)
		(end 130.377184 -15.352268)
		(width 0.14732)
		(layer "In4.Cu")
		(net "P2E_MB_BMC_RX_BUF_DP<0>")
	)
	(segment
		(start 21.392642 -381.919226)
		(end 21.227542 -381.520192)
		(width 0.14732)
		(layer "In4.Cu")
		(net "P2E_MB_BMC_RX_BUF_DP<0>")
	)
	(segment
		(start 3.3655 -319.410588)
		(end 5.41401 -306.769262)
		(width 0.14732)
		(layer "In4.Cu")
		(net "P2E_MB_BMC_RX_BUF_DP<0>")
	)
	(segment
		(start 14.24559 -354.496878)
		(end 7.46887 -354.496878)
		(width 0.14732)
		(layer "In4.Cu")
		(net "P2E_MB_BMC_RX_BUF_DP<0>")
	)
	(segment
		(start 13.727938 -186.06135)
		(end 22.182836 -113.57864)
		(width 0.14732)
		(layer "In4.Cu")
		(net "P2E_MB_BMC_RX_BUF_DP<0>")
	)
	(segment
		(start 81.859628 -44.19219)
		(end 103.399336 -29.800042)
		(width 0.14732)
		(layer "In4.Cu")
		(net "P2E_MB_BMC_RX_BUF_DP<0>")
	)
	(segment
		(start 21.56714 -383.861056)
		(end 21.56714 -382.659128)
		(width 0.14732)
		(layer "In4.Cu")
		(net "P2E_MB_BMC_RX_BUF_DP<0>")
	)
	(segment
		(start 123.488704 -16.630396)
		(end 123.937268 -16.444468)
		(width 0.14732)
		(layer "In4.Cu")
		(net "P2E_MB_BMC_RX_BUF_DP<0>")
	)
	(segment
		(start 52.24018 -74.393552)
		(end 52.24018 -61.599318)
		(width 0.14732)
		(layer "In4.Cu")
		(net "P2E_MB_BMC_RX_BUF_DP<0>")
	)
	(segment
		(start 4.446016 -351.474024)
		(end 3.905504 -350.169734)
		(width 0.14732)
		(layer "In4.Cu")
		(net "P2E_MB_BMC_RX_BUF_DP<0>")
	)
	(segment
		(start 52.24018 -61.599318)
		(end 57.480708 -56.35879)
		(width 0.14732)
		(layer "In4.Cu")
		(net "P2E_MB_BMC_RX_BUF_DP<0>")
	)
	(segment
		(start 21.909532 -384.687572)
		(end 21.56714 -383.861056)
		(width 0.14732)
		(layer "In4.Cu")
		(net "P2E_MB_BMC_RX_BUF_DP<0>")
	)
	(segment
		(start 60.161932 -55.248302)
		(end 71.552054 -52.982368)
		(width 0.14732)
		(layer "In4.Cu")
		(net "P2E_MB_BMC_RX_BUF_DP<0>")
	)
	(segment
		(start 103.399336 -29.800042)
		(end 106.705146 -26.493978)
		(width 0.14732)
		(layer "In4.Cu")
		(net "P2E_MB_BMC_RX_BUF_DP<0>")
	)
	(segment
		(start 16.81734 -371.192044)
		(end 16.81734 -357.068628)
		(width 0.14732)
		(layer "In4.Cu")
		(net "P2E_MB_BMC_RX_BUF_DP<0>")
	)
	(segment
		(start 22.47646 -385.2545)
		(end 21.909532 -384.687572)
		(width 0.14732)
		(layer "In4.Cu")
		(net "P2E_MB_BMC_RX_BUF_DP<0>")
	)
	(segment
		(start 74.142092 -51.909472)
		(end 81.859628 -44.19219)
		(width 0.14732)
		(layer "In4.Cu")
		(net "P2E_MB_BMC_RX_BUF_DP<0>")
	)
	(segment
		(start 3.905758 -350.169734)
		(end 3.3655 -348.865444)
		(width 0.14732)
		(layer "In4.Cu")
		(net "P2E_MB_BMC_RX_BUF_DP<0>")
	)
	(segment
		(start 35.284156 -87.299546)
		(end 47.033942 -82.432652)
		(width 0.14732)
		(layer "In4.Cu")
		(net "P2E_MB_BMC_RX_BUF_DP<0>")
	)
	(segment
		(start 3.905504 -350.169734)
		(end 3.905758 -350.169734)
		(width 0.14732)
		(layer "In4.Cu")
		(net "P2E_MB_BMC_RX_BUF_DP<0>")
	)
	(segment
		(start 17.665192 -373.238776)
		(end 17.731232 -373.079264)
		(width 0.14732)
		(layer "In4.Cu")
		(net "P2E_MB_BMC_RX_BUF_DP<0>")
	)
	(segment
		(start 21.06803 -381.454152)
		(end 18.089118 -374.262142)
		(width 0.14732)
		(layer "In4.Cu")
		(net "P2E_MB_BMC_RX_BUF_DP<0>")
	)
	(segment
		(start 8.169402 -253.957836)
		(end 8.509762 -253.295912)
		(width 0.14732)
		(layer "In4.Cu")
		(net "P2E_MB_BMC_RX_BUF_DP<0>")
	)
	(segment
		(start 17.565878 -372.68023)
		(end 17.406366 -372.61419)
		(width 0.14732)
		(layer "In4.Cu")
		(net "P2E_MB_BMC_RX_BUF_DP<0>")
	)
	(segment
		(start 47.033942 -82.432652)
		(end 50.23739 -79.229204)
		(width 0.14732)
		(layer "In4.Cu")
		(net "P2E_MB_BMC_RX_BUF_DP<0>")
	)
	(segment
		(start 7.46887 -354.496878)
		(end 4.446016 -351.474024)
		(width 0.14732)
		(layer "In4.Cu")
		(net "P2E_MB_BMC_RX_BUF_DP<0>")
	)
	(segment
		(start 5.41401 -306.769262)
		(end 6.323838 -258.491482)
		(width 0.14732)
		(layer "In4.Cu")
		(net "P2E_MB_BMC_RX_BUF_DP<0>")
	)
	(segment
		(start 16.98244 -371.590824)
		(end 16.81734 -371.192044)
		(width 0.14732)
		(layer "In4.Cu")
		(net "P2E_MB_BMC_RX_BUF_DP<0>")
	)
	(segment
		(start 17.141952 -371.656864)
		(end 16.98244 -371.590824)
		(width 0.14732)
		(layer "In4.Cu")
		(net "P2E_MB_BMC_RX_BUF_DP<0>")
	)
	(segment
		(start 3.3655 -348.865444)
		(end 3.3655 -319.410588)
		(width 0.14732)
		(layer "In4.Cu")
		(net "P2E_MB_BMC_RX_BUF_DP<0>")
	)
	(segment
		(start 23.113492 -384.946398)
		(end 22.80539 -385.2545)
		(width 0.14732)
		(layer "In4.Cu")
		(net "P2E_MB_BMC_RX_BUF_DP<0>")
	)
	(segment
		(start 21.326856 -382.078738)
		(end 21.392642 -381.919226)
		(width 0.14732)
		(layer "In4.Cu")
		(net "P2E_MB_BMC_RX_BUF_DP<0>")
	)
	(segment
		(start 125.929644 -16.444468)
		(end 128.56591 -15.352268)
		(width 0.14732)
		(layer "In4.Cu")
		(net "P2E_MB_BMC_RX_BUF_DP<0>")
	)
	(segment
		(start 71.552054 -52.982368)
		(end 74.142092 -51.909472)
		(width 0.14732)
		(layer "In4.Cu")
		(net "P2E_MB_BMC_RX_BUF_DP<0>")
	)
	(segment
		(start 16.81734 -357.068628)
		(end 14.24559 -354.496878)
		(width 0.14732)
		(layer "In4.Cu")
		(net "P2E_MB_BMC_RX_BUF_DP<0>")
	)
	(segment
		(start 57.480708 -56.35879)
		(end 60.161932 -55.248302)
		(width 0.14732)
		(layer "In4.Cu")
		(net "P2E_MB_BMC_RX_BUF_DP<0>")
	)
	(segment
		(start 21.227542 -381.520192)
		(end 21.06803 -381.454152)
		(width 0.14732)
		(layer "In4.Cu")
		(net "P2E_MB_BMC_RX_BUF_DP<0>")
	)
	(segment
		(start 21.56714 -382.659128)
		(end 21.326856 -382.078738)
		(width 0.14732)
		(layer "In4.Cu")
		(net "P2E_MB_BMC_RX_BUF_DP<0>")
	)
	(segment
		(start 123.937268 -16.444468)
		(end 125.929644 -16.444468)
		(width 0.14732)
		(layer "In4.Cu")
		(net "P2E_MB_BMC_RX_BUF_DP<0>")
	)
	(segment
		(start 50.23739 -79.229204)
		(end 52.24018 -74.393552)
		(width 0.14732)
		(layer "In4.Cu")
		(net "P2E_MB_BMC_RX_BUF_DP<0>")
	)
	(segment
		(start 22.681692 -385.378198)
		(end 23.113492 -385.809998)
		(width 0.12954)
		(layer "F.Cu")
		(net "P2E_MB_BMC_RX_BUF_DN<0>")
	)
	(segment
		(start 132.147056 -13.027152)
		(end 132.317236 -12.856972)
		(width 0.13208)
		(layer "F.Cu")
		(net "P2E_MB_BMC_RX_BUF_DN<0>")
	)
	(segment
		(start 132.147056 -13.600176)
		(end 132.147056 -13.027152)
		(width 0.13208)
		(layer "F.Cu")
		(net "P2E_MB_BMC_RX_BUF_DN<0>")
	)
	(segment
		(start 22.460204 -385.378198)
		(end 22.681692 -385.378198)
		(width 0.12954)
		(layer "F.Cu")
		(net "P2E_MB_BMC_RX_BUF_DN<0>")
	)
	(segment
		(start 132.317236 -11.208512)
		(end 132.3213 -11.204448)
		(width 0.13208)
		(layer "F.Cu")
		(net "P2E_MB_BMC_RX_BUF_DN<0>")
	)
	(segment
		(start 132.3213 -11.204448)
		(end 132.3213 -10.544556)
		(width 0.13208)
		(layer "F.Cu")
		(net "P2E_MB_BMC_RX_BUF_DN<0>")
	)
	(segment
		(start 132.3213 -10.544556)
		(end 132.020056 -10.243312)
		(width 0.13208)
		(layer "F.Cu")
		(net "P2E_MB_BMC_RX_BUF_DN<0>")
	)
	(segment
		(start 132.317236 -12.856972)
		(end 132.317236 -11.208512)
		(width 0.13208)
		(layer "F.Cu")
		(net "P2E_MB_BMC_RX_BUF_DN<0>")
	)
	(segment
		(start 57.32526 -56.126126)
		(end 60.081922 -54.984396)
		(width 0.14732)
		(layer "In4.Cu")
		(net "P2E_MB_BMC_RX_BUF_DN<0>")
	)
	(segment
		(start 118.363238 -21.36775)
		(end 123.333256 -16.397732)
		(width 0.14732)
		(layer "In4.Cu")
		(net "P2E_MB_BMC_RX_BUF_DN<0>")
	)
	(segment
		(start 21.29282 -382.713738)
		(end 16.54302 -371.246654)
		(width 0.14732)
		(layer "In4.Cu")
		(net "P2E_MB_BMC_RX_BUF_DN<0>")
	)
	(segment
		(start 8.29056 -253.121668)
		(end 9.8425 -251.808488)
		(width 0.14732)
		(layer "In4.Cu")
		(net "P2E_MB_BMC_RX_BUF_DN<0>")
	)
	(segment
		(start 51.96586 -74.338942)
		(end 51.96586 -61.485526)
		(width 0.14732)
		(layer "In4.Cu")
		(net "P2E_MB_BMC_RX_BUF_DN<0>")
	)
	(segment
		(start 24.594566 -97.601024)
		(end 35.128708 -87.066882)
		(width 0.14732)
		(layer "In4.Cu")
		(net "P2E_MB_BMC_RX_BUF_DN<0>")
	)
	(segment
		(start 123.333256 -16.397732)
		(end 123.882658 -16.170148)
		(width 0.14732)
		(layer "In4.Cu")
		(net "P2E_MB_BMC_RX_BUF_DN<0>")
	)
	(segment
		(start 22.362668 -385.52882)
		(end 21.676868 -384.84302)
		(width 0.14732)
		(layer "In4.Cu")
		(net "P2E_MB_BMC_RX_BUF_DN<0>")
	)
	(segment
		(start 7.91972 -253.843028)
		(end 8.29056 -253.121668)
		(width 0.14732)
		(layer "In4.Cu")
		(net "P2E_MB_BMC_RX_BUF_DN<0>")
	)
	(segment
		(start 103.22433 -29.586682)
		(end 106.549698 -26.261314)
		(width 0.14732)
		(layer "In4.Cu")
		(net "P2E_MB_BMC_RX_BUF_DN<0>")
	)
	(segment
		(start 7.355078 -354.771198)
		(end 4.213352 -351.629472)
		(width 0.14732)
		(layer "In4.Cu")
		(net "P2E_MB_BMC_RX_BUF_DN<0>")
	)
	(segment
		(start 10.23493 -194.718432)
		(end 13.459206 -185.997088)
		(width 0.14732)
		(layer "In4.Cu")
		(net "P2E_MB_BMC_RX_BUF_DN<0>")
	)
	(segment
		(start 35.128708 -87.066882)
		(end 46.878494 -82.199988)
		(width 0.14732)
		(layer "In4.Cu")
		(net "P2E_MB_BMC_RX_BUF_DN<0>")
	)
	(segment
		(start 22.832314 -385.52882)
		(end 22.362668 -385.52882)
		(width 0.14732)
		(layer "In4.Cu")
		(net "P2E_MB_BMC_RX_BUF_DN<0>")
	)
	(segment
		(start 128.5113 -15.077948)
		(end 130.322574 -15.077948)
		(width 0.14732)
		(layer "In4.Cu")
		(net "P2E_MB_BMC_RX_BUF_DN<0>")
	)
	(segment
		(start 16.54302 -357.18242)
		(end 14.131798 -354.771198)
		(width 0.14732)
		(layer "In4.Cu")
		(net "P2E_MB_BMC_RX_BUF_DN<0>")
	)
	(segment
		(start 51.96586 -61.485526)
		(end 57.32526 -56.126126)
		(width 0.14732)
		(layer "In4.Cu")
		(net "P2E_MB_BMC_RX_BUF_DN<0>")
	)
	(segment
		(start 131.163568 -14.72946)
		(end 132.314696 -13.578332)
		(width 0.14732)
		(layer "In4.Cu")
		(net "P2E_MB_BMC_RX_BUF_DN<0>")
	)
	(segment
		(start 21.676868 -384.84302)
		(end 21.29282 -383.915666)
		(width 0.14732)
		(layer "In4.Cu")
		(net "P2E_MB_BMC_RX_BUF_DN<0>")
	)
	(segment
		(start 21.911056 -113.540032)
		(end 24.594566 -97.601024)
		(width 0.14732)
		(layer "In4.Cu")
		(net "P2E_MB_BMC_RX_BUF_DN<0>")
	)
	(segment
		(start 46.878494 -82.199988)
		(end 50.004726 -79.073756)
		(width 0.14732)
		(layer "In4.Cu")
		(net "P2E_MB_BMC_RX_BUF_DN<0>")
	)
	(segment
		(start 3.09118 -348.920054)
		(end 3.09118 -319.38849)
		(width 0.14732)
		(layer "In4.Cu")
		(net "P2E_MB_BMC_RX_BUF_DN<0>")
	)
	(segment
		(start 6.05028 -258.435348)
		(end 7.91972 -253.843028)
		(width 0.14732)
		(layer "In4.Cu")
		(net "P2E_MB_BMC_RX_BUF_DN<0>")
	)
	(segment
		(start 60.081922 -54.984396)
		(end 71.472044 -52.718462)
		(width 0.14732)
		(layer "In4.Cu")
		(net "P2E_MB_BMC_RX_BUF_DN<0>")
	)
	(segment
		(start 73.986644 -51.676808)
		(end 81.684622 -43.97883)
		(width 0.14732)
		(layer "In4.Cu")
		(net "P2E_MB_BMC_RX_BUF_DN<0>")
	)
	(segment
		(start 50.004726 -79.073756)
		(end 51.96586 -74.338942)
		(width 0.14732)
		(layer "In4.Cu")
		(net "P2E_MB_BMC_RX_BUF_DN<0>")
	)
	(segment
		(start 14.131798 -354.771198)
		(end 7.355078 -354.771198)
		(width 0.14732)
		(layer "In4.Cu")
		(net "P2E_MB_BMC_RX_BUF_DN<0>")
	)
	(segment
		(start 16.54302 -371.246654)
		(end 16.54302 -357.18242)
		(width 0.14732)
		(layer "In4.Cu")
		(net "P2E_MB_BMC_RX_BUF_DN<0>")
	)
	(segment
		(start 132.314696 -10.537952)
		(end 132.020056 -10.243312)
		(width 0.14732)
		(layer "In4.Cu")
		(net "P2E_MB_BMC_RX_BUF_DN<0>")
	)
	(segment
		(start 106.549698 -26.261314)
		(end 118.363238 -21.36775)
		(width 0.14732)
		(layer "In4.Cu")
		(net "P2E_MB_BMC_RX_BUF_DN<0>")
	)
	(segment
		(start 13.459206 -185.997088)
		(end 21.911056 -113.540032)
		(width 0.14732)
		(layer "In4.Cu")
		(net "P2E_MB_BMC_RX_BUF_DN<0>")
	)
	(segment
		(start 9.8425 -251.808488)
		(end 10.23493 -194.718432)
		(width 0.14732)
		(layer "In4.Cu")
		(net "P2E_MB_BMC_RX_BUF_DN<0>")
	)
	(segment
		(start 123.882658 -16.170148)
		(end 125.875034 -16.170148)
		(width 0.14732)
		(layer "In4.Cu")
		(net "P2E_MB_BMC_RX_BUF_DN<0>")
	)
	(segment
		(start 71.472044 -52.718462)
		(end 73.986644 -51.676808)
		(width 0.14732)
		(layer "In4.Cu")
		(net "P2E_MB_BMC_RX_BUF_DN<0>")
	)
	(segment
		(start 130.322574 -15.077948)
		(end 131.163568 -14.72946)
		(width 0.14732)
		(layer "In4.Cu")
		(net "P2E_MB_BMC_RX_BUF_DN<0>")
	)
	(segment
		(start 4.213352 -351.629472)
		(end 3.09118 -348.920054)
		(width 0.14732)
		(layer "In4.Cu")
		(net "P2E_MB_BMC_RX_BUF_DN<0>")
	)
	(segment
		(start 21.29282 -383.915666)
		(end 21.29282 -382.713738)
		(width 0.14732)
		(layer "In4.Cu")
		(net "P2E_MB_BMC_RX_BUF_DN<0>")
	)
	(segment
		(start 132.314696 -13.578332)
		(end 132.314696 -10.537952)
		(width 0.14732)
		(layer "In4.Cu")
		(net "P2E_MB_BMC_RX_BUF_DN<0>")
	)
	(segment
		(start 3.09118 -319.38849)
		(end 5.139944 -306.744624)
		(width 0.14732)
		(layer "In4.Cu")
		(net "P2E_MB_BMC_RX_BUF_DN<0>")
	)
	(segment
		(start 125.875034 -16.170148)
		(end 128.5113 -15.077948)
		(width 0.14732)
		(layer "In4.Cu")
		(net "P2E_MB_BMC_RX_BUF_DN<0>")
	)
	(segment
		(start 5.139944 -306.744624)
		(end 6.05028 -258.435348)
		(width 0.14732)
		(layer "In4.Cu")
		(net "P2E_MB_BMC_RX_BUF_DN<0>")
	)
	(segment
		(start 23.113492 -385.809998)
		(end 22.832314 -385.52882)
		(width 0.14732)
		(layer "In4.Cu")
		(net "P2E_MB_BMC_RX_BUF_DN<0>")
	)
	(segment
		(start 81.684622 -43.97883)
		(end 103.22433 -29.586682)
		(width 0.14732)
		(layer "In4.Cu")
		(net "P2E_MB_BMC_RX_BUF_DN<0>")
	)
	(segment
		(start 23.313644 -389.190484)
		(end 23.243286 -389.120126)
		(width 0.13208)
		(layer "F.Cu")
		(net "P2E_MB_BMC_RX_BUF_C_DP<0>")
	)
	(segment
		(start 23.313644 -389.425942)
		(end 23.313644 -389.190484)
		(width 0.13208)
		(layer "F.Cu")
		(net "P2E_MB_BMC_RX_BUF_C_DP<0>")
	)
	(segment
		(start 23.767034 -386.599938)
		(end 23.767034 -386.178298)
		(width 0.13208)
		(layer "F.Cu")
		(net "P2E_MB_BMC_RX_BUF_C_DP<0>")
	)
	(segment
		(start 23.243286 -389.120126)
		(end 23.243286 -387.123686)
		(width 0.13208)
		(layer "F.Cu")
		(net "P2E_MB_BMC_RX_BUF_C_DP<0>")
	)
	(segment
		(start 23.243286 -387.123686)
		(end 23.767034 -386.599938)
		(width 0.13208)
		(layer "F.Cu")
		(net "P2E_MB_BMC_RX_BUF_C_DP<0>")
	)
	(segment
		(start 22.460204 -386.599938)
		(end 22.460204 -386.178298)
		(width 0.13208)
		(layer "F.Cu")
		(net "P2E_MB_BMC_RX_BUF_C_DN<0>")
	)
	(segment
		(start 22.984206 -389.115554)
		(end 22.984206 -387.12394)
		(width 0.13208)
		(layer "F.Cu")
		(net "P2E_MB_BMC_RX_BUF_C_DN<0>")
	)
	(segment
		(start 22.984206 -387.12394)
		(end 22.460204 -386.599938)
		(width 0.13208)
		(layer "F.Cu")
		(net "P2E_MB_BMC_RX_BUF_C_DN<0>")
	)
	(segment
		(start 22.913594 -389.186166)
		(end 22.984206 -389.115554)
		(width 0.13208)
		(layer "F.Cu")
		(net "P2E_MB_BMC_RX_BUF_C_DN<0>")
	)
	(segment
		(start 22.913594 -389.425942)
		(end 22.913594 -389.186166)
		(width 0.13208)
		(layer "F.Cu")
		(net "P2E_MB_BMC_RX_BUF_C_DN<0>")
	)
	(segment
		(start 25.469596 -391.310876)
		(end 26.485596 -392.326876)
		(width 0.10668)
		(layer "F.Cu")
		(net "FM_P2E_FGB")
	)
	(segment
		(start 26.485596 -392.326876)
		(end 27.228546 -392.326876)
		(width 0.10668)
		(layer "F.Cu")
		(net "FM_P2E_FGB")
	)
	(segment
		(start 27.228546 -392.326876)
		(end 27.228546 -393.342876)
		(width 0.10668)
		(layer "F.Cu")
		(net "FM_P2E_FGB")
	)
	(segment
		(start 24.163528 -391.075926)
		(end 25.234646 -391.075926)
		(width 0.10668)
		(layer "F.Cu")
		(net "FM_P2E_FGB")
	)
	(segment
		(start 27.228546 -393.342876)
		(end 27.228546 -394.358876)
		(width 0.10668)
		(layer "F.Cu")
		(net "FM_P2E_FGB")
	)
	(segment
		(start 25.234646 -391.075926)
		(end 25.469596 -391.310876)
		(width 0.10668)
		(layer "F.Cu")
		(net "FM_P2E_FGB")
	)
	(via
		(at 25.469596 -391.310876)
		(size 0.762)
		(drill 0.381)
		(layers "F.Cu" "B.Cu")
		(net "FM_P2E_FGB")
	)
	(segment
		(start 15.836646 -393.215876)
		(end 15.836646 -392.199876)
		(width 0.10668)
		(layer "F.Cu")
		(net "FM_P2E_FGA")
	)
	(segment
		(start 15.836646 -392.199876)
		(end 15.836646 -391.183876)
		(width 0.10668)
		(layer "F.Cu")
		(net "FM_P2E_FGA")
	)
	(segment
		(start 19.663664 -391.075926)
		(end 17.741646 -391.075926)
		(width 0.10668)
		(layer "F.Cu")
		(net "FM_P2E_FGA")
	)
	(segment
		(start 15.836646 -391.183876)
		(end 16.090646 -390.929876)
		(width 0.10668)
		(layer "F.Cu")
		(net "FM_P2E_FGA")
	)
	(segment
		(start 17.741646 -391.075926)
		(end 17.595596 -390.929876)
		(width 0.10668)
		(layer "F.Cu")
		(net "FM_P2E_FGA")
	)
	(segment
		(start 16.090646 -390.929876)
		(end 17.595596 -390.929876)
		(width 0.10668)
		(layer "F.Cu")
		(net "FM_P2E_FGA")
	)
	(via
		(at 17.595596 -390.929876)
		(size 0.762)
		(drill 0.381)
		(layers "F.Cu" "B.Cu")
		(net "FM_P2E_FGA")
	)
	(segment
		(start 24.163528 -391.475976)
		(end 24.491696 -391.475976)
		(width 0.10668)
		(layer "F.Cu")
		(net "FM_P2E_EQB1")
	)
	(segment
		(start 27.228546 -396.390876)
		(end 27.228546 -395.374876)
		(width 0.10668)
		(layer "F.Cu")
		(net "FM_P2E_EQB1")
	)
	(segment
		(start 25.2476 -392.23188)
		(end 25.2476 -393.36853)
		(width 0.10668)
		(layer "F.Cu")
		(net "FM_P2E_EQB1")
	)
	(segment
		(start 25.2476 -393.36853)
		(end 25.459944 -393.580874)
		(width 0.10668)
		(layer "F.Cu")
		(net "FM_P2E_EQB1")
	)
	(segment
		(start 27.228546 -395.349476)
		(end 27.228546 -395.374876)
		(width 0.10668)
		(layer "F.Cu")
		(net "FM_P2E_EQB1")
	)
	(segment
		(start 25.459944 -393.580874)
		(end 27.228546 -395.349476)
		(width 0.10668)
		(layer "F.Cu")
		(net "FM_P2E_EQB1")
	)
	(segment
		(start 24.491696 -391.475976)
		(end 25.2476 -392.23188)
		(width 0.10668)
		(layer "F.Cu")
		(net "FM_P2E_EQB1")
	)
	(segment
		(start 27.228546 -397.406876)
		(end 27.228546 -396.390876)
		(width 0.10668)
		(layer "F.Cu")
		(net "FM_P2E_EQB1")
	)
	(via
		(at 25.459944 -393.580874)
		(size 0.762)
		(drill 0.381)
		(layers "F.Cu" "B.Cu")
		(net "FM_P2E_EQB1")
	)
	(segment
		(start 23.241 -396.625826)
		(end 23.241 -396.42288)
		(width 0.10668)
		(layer "F.Cu")
		(net "FM_P2E_EQB0")
	)
	(segment
		(start 23.420578 -396.625826)
		(end 23.884382 -397.08963)
		(width 0.10668)
		(layer "F.Cu")
		(net "FM_P2E_EQB0")
	)
	(segment
		(start 22.113494 -391.92581)
		(end 22.113494 -394.58392)
		(width 0.10668)
		(layer "F.Cu")
		(net "FM_P2E_EQB0")
	)
	(segment
		(start 22.77745 -395.247876)
		(end 23.603712 -395.247876)
		(width 0.10668)
		(layer "F.Cu")
		(net "FM_P2E_EQB0")
	)
	(segment
		(start 23.884382 -398.679416)
		(end 23.431754 -399.132044)
		(width 0.10668)
		(layer "F.Cu")
		(net "FM_P2E_EQB0")
	)
	(segment
		(start 23.603712 -396.060168)
		(end 23.603712 -395.247876)
		(width 0.10668)
		(layer "F.Cu")
		(net "FM_P2E_EQB0")
	)
	(segment
		(start 23.884382 -397.08963)
		(end 23.884382 -398.679416)
		(width 0.10668)
		(layer "F.Cu")
		(net "FM_P2E_EQB0")
	)
	(segment
		(start 23.431754 -399.132044)
		(end 24.447754 -399.132044)
		(width 0.10668)
		(layer "F.Cu")
		(net "FM_P2E_EQB0")
	)
	(segment
		(start 23.241 -396.42288)
		(end 23.603712 -396.060168)
		(width 0.10668)
		(layer "F.Cu")
		(net "FM_P2E_EQB0")
	)
	(segment
		(start 23.241 -396.625826)
		(end 23.420578 -396.625826)
		(width 0.10668)
		(layer "F.Cu")
		(net "FM_P2E_EQB0")
	)
	(segment
		(start 22.113494 -394.58392)
		(end 22.77745 -395.247876)
		(width 0.10668)
		(layer "F.Cu")
		(net "FM_P2E_EQB0")
	)
	(via
		(at 23.603712 -395.247876)
		(size 0.762)
		(drill 0.381)
		(layers "F.Cu" "B.Cu")
		(net "FM_P2E_EQB0")
	)
	(segment
		(start 15.836646 -394.231876)
		(end 15.836646 -395.247876)
		(width 0.10668)
		(layer "F.Cu")
		(net "FM_P2E_EQA1")
	)
	(segment
		(start 15.836646 -396.263876)
		(end 15.836646 -395.247876)
		(width 0.10668)
		(layer "F.Cu")
		(net "FM_P2E_EQA1")
	)
	(segment
		(start 15.836646 -394.231876)
		(end 15.836646 -394.20673)
		(width 0.10668)
		(layer "F.Cu")
		(net "FM_P2E_EQA1")
	)
	(segment
		(start 15.836646 -394.20673)
		(end 17.8435 -392.199876)
		(width 0.10668)
		(layer "F.Cu")
		(net "FM_P2E_EQA1")
	)
	(segment
		(start 18.5674 -391.475976)
		(end 17.8435 -392.199876)
		(width 0.10668)
		(layer "F.Cu")
		(net "FM_P2E_EQA1")
	)
	(segment
		(start 19.663664 -391.475976)
		(end 18.5674 -391.475976)
		(width 0.10668)
		(layer "F.Cu")
		(net "FM_P2E_EQA1")
	)
	(via
		(at 17.8435 -392.199876)
		(size 0.762)
		(drill 0.381)
		(layers "F.Cu" "B.Cu")
		(net "FM_P2E_EQA1")
	)
	(segment
		(start 22.225 -395.886178)
		(end 21.713698 -395.374876)
		(width 0.10668)
		(layer "F.Cu")
		(net "FM_P2E_EQA0")
	)
	(segment
		(start 21.713698 -391.92581)
		(end 21.713698 -395.374876)
		(width 0.10668)
		(layer "F.Cu")
		(net "FM_P2E_EQA0")
	)
	(segment
		(start 22.225 -396.625826)
		(end 22.225 -395.886178)
		(width 0.10668)
		(layer "F.Cu")
		(net "FM_P2E_EQA0")
	)
	(segment
		(start 22.058376 -396.625826)
		(end 21.553424 -397.130778)
		(width 0.10668)
		(layer "F.Cu")
		(net "FM_P2E_EQA0")
	)
	(segment
		(start 21.553424 -397.130778)
		(end 21.553424 -398.321276)
		(width 0.10668)
		(layer "F.Cu")
		(net "FM_P2E_EQA0")
	)
	(segment
		(start 21.553424 -398.321276)
		(end 22.364192 -399.132044)
		(width 0.10668)
		(layer "F.Cu")
		(net "FM_P2E_EQA0")
	)
	(segment
		(start 22.225 -396.625826)
		(end 22.058376 -396.625826)
		(width 0.10668)
		(layer "F.Cu")
		(net "FM_P2E_EQA0")
	)
	(segment
		(start 21.348192 -399.132044)
		(end 22.364192 -399.132044)
		(width 0.10668)
		(layer "F.Cu")
		(net "FM_P2E_EQA0")
	)
	(via
		(at 21.713698 -395.374876)
		(size 0.762)
		(drill 0.381)
		(layers "F.Cu" "B.Cu")
		(net "FM_P2E_EQA0")
	)
	(segment
		(start 25.92578 -388.831582)
		(end 25.92578 -387.272276)
		(width 0.10668)
		(layer "F.Cu")
		(net "FM_P2E_EN_N")
	)
	(segment
		(start 24.163528 -389.875776)
		(end 24.881586 -389.875776)
		(width 0.10668)
		(layer "F.Cu")
		(net "FM_P2E_EN_N")
	)
	(segment
		(start 25.92578 -387.272276)
		(end 25.92578 -386.655818)
		(width 0.10668)
		(layer "F.Cu")
		(net "FM_P2E_EN_N")
	)
	(segment
		(start 25.92578 -386.655818)
		(end 27.22118 -385.360418)
		(width 0.10668)
		(layer "F.Cu")
		(net "FM_P2E_EN_N")
	)
	(segment
		(start 24.881586 -389.875776)
		(end 25.92578 -388.831582)
		(width 0.10668)
		(layer "F.Cu")
		(net "FM_P2E_EN_N")
	)
	(via
		(at 25.92578 -387.272276)
		(size 0.762)
		(drill 0.381)
		(layers "F.Cu" "B.Cu")
		(net "FM_P2E_EN_N")
	)
	(segment
		(start 83.301078 -24.333962)
		(end 81.313528 -24.333962)
		(width 0.508)
		(layer "F.Cu")
		(net "P12V_OCP_V3_2")
	)
	(segment
		(start 81.313528 -24.333962)
		(end 81.325212 -24.345646)
		(width 0.508)
		(layer "F.Cu")
		(net "P12V_OCP_V3_2")
	)
	(segment
		(start 83.809078 -17.462246)
		(end 83.809078 -23.825962)
		(width 0.508)
		(layer "F.Cu")
		(net "P12V_OCP_V3_2")
	)
	(segment
		(start 61.993018 -21.412962)
		(end 60.977018 -22.428962)
		(width 0.254)
		(layer "F.Cu")
		(net "P12V_OCP_V3_2")
	)
	(segment
		(start 83.809078 -23.825962)
		(end 83.301078 -24.333962)
		(width 0.508)
		(layer "F.Cu")
		(net "P12V_OCP_V3_2")
	)
	(segment
		(start 60.977018 -25.72131)
		(end 61.845698 -26.58999)
		(width 0.254)
		(layer "F.Cu")
		(net "P12V_OCP_V3_2")
	)
	(segment
		(start 83.31708 -16.970248)
		(end 83.809078 -17.462246)
		(width 0.508)
		(layer "F.Cu")
		(net "P12V_OCP_V3_2")
	)
	(segment
		(start 81.325212 -24.345646)
		(end 81.325212 -25.358598)
		(width 0.508)
		(layer "F.Cu")
		(net "P12V_OCP_V3_2")
	)
	(segment
		(start 80.28178 -16.970248)
		(end 83.31708 -16.970248)
		(width 0.508)
		(layer "F.Cu")
		(net "P12V_OCP_V3_2")
	)
	(segment
		(start 60.977018 -22.428962)
		(end 60.977018 -25.72131)
		(width 0.254)
		(layer "F.Cu")
		(net "P12V_OCP_V3_2")
	)
	(segment
		(start 66.339466 -21.412962)
		(end 61.993018 -21.412962)
		(width 0.254)
		(layer "F.Cu")
		(net "P12V_OCP_V3_2")
	)
	(via
		(at 66.78168 -24.882348)
		(size 0.508)
		(drill 0.254)
		(layers "F.Cu" "B.Cu")
		(net "P12V_OCP_V3_2")
	)
	(via
		(at 67.24396 -12.492228)
		(size 0.508)
		(drill 0.254)
		(layers "F.Cu" "B.Cu")
		(net "P12V_OCP_V3_2")
	)
	(via
		(at 77.659738 -16.259302)
		(size 0.508)
		(drill 0.254)
		(layers "F.Cu" "B.Cu")
		(net "P12V_OCP_V3_2")
	)
	(via
		(at 67.23888 -15.331948)
		(size 0.508)
		(drill 0.254)
		(layers "F.Cu" "B.Cu")
		(net "P12V_OCP_V3_2")
	)
	(via
		(at 67.67068 -24.882348)
		(size 0.508)
		(drill 0.254)
		(layers "F.Cu" "B.Cu")
		(net "P12V_OCP_V3_2")
	)
	(via
		(at 66.50228 -12.436348)
		(size 0.508)
		(drill 0.254)
		(layers "F.Cu" "B.Cu")
		(net "P12V_OCP_V3_2")
	)
	(via
		(at 64.97828 -12.436348)
		(size 0.508)
		(drill 0.254)
		(layers "F.Cu" "B.Cu")
		(net "P12V_OCP_V3_2")
	)
	(via
		(at 66.88328 -22.266148)
		(size 0.508)
		(drill 0.254)
		(layers "F.Cu" "B.Cu")
		(net "P12V_OCP_V3_2")
	)
	(via
		(at 67.23888 -14.315948)
		(size 0.508)
		(drill 0.254)
		(layers "F.Cu" "B.Cu")
		(net "P12V_OCP_V3_2")
	)
	(via
		(at 66.40068 -25.568148)
		(size 0.508)
		(drill 0.254)
		(layers "F.Cu" "B.Cu")
		(net "P12V_OCP_V3_2")
	)
	(via
		(at 67.715638 -20.326604)
		(size 0.508)
		(drill 0.254)
		(layers "F.Cu" "B.Cu")
		(net "P12V_OCP_V3_2")
	)
	(via
		(at 67.28968 -25.568148)
		(size 0.508)
		(drill 0.254)
		(layers "F.Cu" "B.Cu")
		(net "P12V_OCP_V3_2")
	)
	(via
		(at 64.08928 -12.436348)
		(size 0.508)
		(drill 0.254)
		(layers "F.Cu" "B.Cu")
		(net "P12V_OCP_V3_2")
	)
	(via
		(at 67.715638 -19.691604)
		(size 0.508)
		(drill 0.254)
		(layers "F.Cu" "B.Cu")
		(net "P12V_OCP_V3_2")
	)
	(via
		(at 65.86728 -12.436348)
		(size 0.508)
		(drill 0.254)
		(layers "F.Cu" "B.Cu")
		(net "P12V_OCP_V3_2")
	)
	(via
		(at 68.17868 -25.568148)
		(size 0.508)
		(drill 0.254)
		(layers "F.Cu" "B.Cu")
		(net "P12V_OCP_V3_2")
	)
	(via
		(at 66.29908 -13.096748)
		(size 0.508)
		(drill 0.254)
		(layers "F.Cu" "B.Cu")
		(net "P12V_OCP_V3_2")
	)
	(via
		(at 69.49948 -24.552148)
		(size 0.508)
		(drill 0.254)
		(layers "F.Cu" "B.Cu")
		(net "P12V_OCP_V3_2")
	)
	(via
		(at 77.659738 -15.522702)
		(size 0.508)
		(drill 0.254)
		(layers "F.Cu" "B.Cu")
		(net "P12V_OCP_V3_2")
	)
	(via
		(at 64.52108 -13.096748)
		(size 0.508)
		(drill 0.254)
		(layers "F.Cu" "B.Cu")
		(net "P12V_OCP_V3_2")
	)
	(via
		(at 63.63208 -13.096748)
		(size 0.508)
		(drill 0.254)
		(layers "F.Cu" "B.Cu")
		(net "P12V_OCP_V3_2")
	)
	(via
		(at 67.690238 -17.662144)
		(size 0.508)
		(drill 0.254)
		(layers "F.Cu" "B.Cu")
		(net "P12V_OCP_V3_2")
	)
	(via
		(at 65.41008 -13.096748)
		(size 0.508)
		(drill 0.254)
		(layers "F.Cu" "B.Cu")
		(net "P12V_OCP_V3_2")
	)
	(via
		(at 63.20028 -12.436348)
		(size 0.508)
		(drill 0.254)
		(layers "F.Cu" "B.Cu")
		(net "P12V_OCP_V3_2")
	)
	(via
		(at 79.922878 -18.237962)
		(size 0.508)
		(drill 0.254)
		(layers "F.Cu" "B.Cu")
		(net "P12V_OCP_V3_2")
	)
	(via
		(at 66.93408 -13.096748)
		(size 0.508)
		(drill 0.254)
		(layers "F.Cu" "B.Cu")
		(net "P12V_OCP_V3_2")
	)
	(via
		(at 67.23888 -16.347948)
		(size 0.508)
		(drill 0.254)
		(layers "F.Cu" "B.Cu")
		(net "P12V_OCP_V3_2")
	)
	(via
		(at 79.922878 -17.501362)
		(size 0.508)
		(drill 0.254)
		(layers "F.Cu" "B.Cu")
		(net "P12V_OCP_V3_2")
	)
	(via
		(at 68.55968 -24.882348)
		(size 0.508)
		(drill 0.254)
		(layers "F.Cu" "B.Cu")
		(net "P12V_OCP_V3_2")
	)
	(via
		(at 67.690238 -18.297144)
		(size 0.508)
		(drill 0.254)
		(layers "F.Cu" "B.Cu")
		(net "P12V_OCP_V3_2")
	)
	(segment
		(start 64.591438 -31.487872)
		(end 66.172334 -29.906976)
		(width 0.254)
		(layer "F.Cu")
		(net "P12V_OCP_IMON_2")
	)
	(segment
		(start 62.21476 -30.302708)
		(end 62.559438 -30.647386)
		(width 0.254)
		(layer "F.Cu")
		(net "P12V_OCP_IMON_2")
	)
	(segment
		(start 62.559438 -31.487872)
		(end 63.575438 -31.487872)
		(width 0.254)
		(layer "F.Cu")
		(net "P12V_OCP_IMON_2")
	)
	(segment
		(start 61.543438 -31.130748)
		(end 61.30544 -30.89275)
		(width 0.254)
		(layer "F.Cu")
		(net "P12V_OCP_IMON_2")
	)
	(segment
		(start 62.559438 -30.647386)
		(end 62.559438 -31.487872)
		(width 0.254)
		(layer "F.Cu")
		(net "P12V_OCP_IMON_2")
	)
	(segment
		(start 63.575438 -31.487872)
		(end 64.591438 -31.487872)
		(width 0.254)
		(layer "F.Cu")
		(net "P12V_OCP_IMON_2")
	)
	(segment
		(start 61.30544 -30.516068)
		(end 61.5188 -30.302708)
		(width 0.254)
		(layer "F.Cu")
		(net "P12V_OCP_IMON_2")
	)
	(segment
		(start 61.30544 -30.89275)
		(end 61.30544 -30.516068)
		(width 0.254)
		(layer "F.Cu")
		(net "P12V_OCP_IMON_2")
	)
	(segment
		(start 61.5188 -30.302708)
		(end 62.21476 -30.302708)
		(width 0.254)
		(layer "F.Cu")
		(net "P12V_OCP_IMON_2")
	)
	(segment
		(start 61.543438 -31.487872)
		(end 61.543438 -31.130748)
		(width 0.254)
		(layer "F.Cu")
		(net "P12V_OCP_IMON_2")
	)
	(segment
		(start 66.172334 -29.906976)
		(end 66.172334 -29.29001)
		(width 0.254)
		(layer "F.Cu")
		(net "P12V_OCP_IMON_2")
	)
	(via
		(at 61.5188 -30.302708)
		(size 0.762)
		(drill 0.381)
		(layers "F.Cu" "B.Cu")
		(net "P12V_OCP_IMON_2")
	)
	(segment
		(start 272.32356 -17.470628)
		(end 273.31416 -18.461228)
		(width 0.12954)
		(layer "F.Cu")
		(net "OCP_V3_2_WAKE_BUFF_R_N")
	)
	(segment
		(start 278.44496 -19.540728)
		(end 278.44496 -20.765008)
		(width 0.12954)
		(layer "F.Cu")
		(net "OCP_V3_2_WAKE_BUFF_R_N")
	)
	(segment
		(start 274.746212 -21.910548)
		(end 274.094956 -21.259292)
		(width 0.12954)
		(layer "F.Cu")
		(net "OCP_V3_2_WAKE_BUFF_R_N")
	)
	(segment
		(start 274.80514 -18.461228)
		(end 275.52142 -19.177508)
		(width 0.12954)
		(layer "F.Cu")
		(net "OCP_V3_2_WAKE_BUFF_R_N")
	)
	(segment
		(start 273.2278 -15.093188)
		(end 272.32356 -15.997428)
		(width 0.12954)
		(layer "F.Cu")
		(net "OCP_V3_2_WAKE_BUFF_R_N")
	)
	(segment
		(start 277.29942 -21.910548)
		(end 274.746212 -21.910548)
		(width 0.12954)
		(layer "F.Cu")
		(net "OCP_V3_2_WAKE_BUFF_R_N")
	)
	(segment
		(start 278.44496 -20.765008)
		(end 277.29942 -21.910548)
		(width 0.12954)
		(layer "F.Cu")
		(net "OCP_V3_2_WAKE_BUFF_R_N")
	)
	(segment
		(start 278.08174 -19.177508)
		(end 278.44496 -19.540728)
		(width 0.12954)
		(layer "F.Cu")
		(net "OCP_V3_2_WAKE_BUFF_R_N")
	)
	(segment
		(start 273.31416 -18.461228)
		(end 274.12696 -18.461228)
		(width 0.12954)
		(layer "F.Cu")
		(net "OCP_V3_2_WAKE_BUFF_R_N")
	)
	(segment
		(start 272.32356 -15.997428)
		(end 272.32356 -17.470628)
		(width 0.12954)
		(layer "F.Cu")
		(net "OCP_V3_2_WAKE_BUFF_R_N")
	)
	(segment
		(start 275.52142 -19.177508)
		(end 278.08174 -19.177508)
		(width 0.12954)
		(layer "F.Cu")
		(net "OCP_V3_2_WAKE_BUFF_R_N")
	)
	(segment
		(start 274.12315 -15.093188)
		(end 273.2278 -15.093188)
		(width 0.12954)
		(layer "F.Cu")
		(net "OCP_V3_2_WAKE_BUFF_R_N")
	)
	(segment
		(start 274.12696 -18.461228)
		(end 274.80514 -18.461228)
		(width 0.12954)
		(layer "F.Cu")
		(net "OCP_V3_2_WAKE_BUFF_R_N")
	)
	(via
		(at 274.12696 -18.461228)
		(size 0.762)
		(drill 0.381)
		(layers "F.Cu" "B.Cu")
		(net "OCP_V3_2_WAKE_BUFF_R_N")
	)
	(segment
		(start 274.918424 -19.929094)
		(end 274.895056 -19.952462)
		(width 0.12954)
		(layer "F.Cu")
		(net "OCP_V3_2_WAKE_BUFF_N")
	)
	(segment
		(start 274.895056 -21.259292)
		(end 274.895056 -19.952462)
		(width 0.12954)
		(layer "F.Cu")
		(net "OCP_V3_2_WAKE_BUFF_N")
	)
	(segment
		(start 277.464774 -19.929094)
		(end 276.178264 -19.929094)
		(width 0.12954)
		(layer "F.Cu")
		(net "OCP_V3_2_WAKE_BUFF_N")
	)
	(segment
		(start 276.178264 -19.929094)
		(end 274.918424 -19.929094)
		(width 0.12954)
		(layer "F.Cu")
		(net "OCP_V3_2_WAKE_BUFF_N")
	)
	(via
		(at 276.178264 -19.929094)
		(size 0.762)
		(drill 0.381)
		(layers "F.Cu" "B.Cu")
		(net "OCP_V3_2_WAKE_BUFF_N")
	)
	(segment
		(start 13.996924 -12.549886)
		(end 13.996924 -12.725908)
		(width 0.13208)
		(layer "F.Cu")
		(net "USB2_5_R1_DP")
	)
	(segment
		(start 17.319752 -6.355588)
		(end 17.09166 -6.355588)
		(width 0.13208)
		(layer "F.Cu")
		(net "USB2_5_R1_DP")
	)
	(segment
		(start 16.46174 -6.355588)
		(end 16.220948 -6.355588)
		(width 0.13208)
		(layer "F.Cu")
		(net "USB2_5_R1_DP")
	)
	(segment
		(start 14.64056 -12.082272)
		(end 14.370812 -12.35202)
		(width 0.13208)
		(layer "F.Cu")
		(net "USB2_5_R1_DP")
	)
	(segment
		(start 14.9098 -10.699496)
		(end 14.9098 -11.63701)
		(width 0.13208)
		(layer "F.Cu")
		(net "USB2_5_R1_DP")
	)
	(segment
		(start 17.51838 -6.554216)
		(end 17.319752 -6.355588)
		(width 0.13208)
		(layer "F.Cu")
		(net "USB2_5_R1_DP")
	)
	(segment
		(start 14.19479 -12.35202)
		(end 13.996924 -12.549886)
		(width 0.13208)
		(layer "F.Cu")
		(net "USB2_5_R1_DP")
	)
	(segment
		(start 15.03426 -10.194036)
		(end 15.03426 -10.575036)
		(width 0.13208)
		(layer "F.Cu")
		(net "USB2_5_R1_DP")
	)
	(segment
		(start 14.370812 -12.35202)
		(end 14.19479 -12.35202)
		(width 0.13208)
		(layer "F.Cu")
		(net "USB2_5_R1_DP")
	)
	(segment
		(start 15.03426 -9.183116)
		(end 15.03426 -9.564116)
		(width 0.13208)
		(layer "F.Cu")
		(net "USB2_5_R1_DP")
	)
	(segment
		(start 13.996924 -12.725908)
		(end 13.727176 -12.995656)
		(width 0.13208)
		(layer "F.Cu")
		(net "USB2_5_R1_DP")
	)
	(segment
		(start 13.55598 -13.614908)
		(end 13.55598 -13.995908)
		(width 0.13208)
		(layer "F.Cu")
		(net "USB2_5_R1_DP")
	)
	(segment
		(start 17.09166 -6.355588)
		(end 16.9672 -6.480048)
		(width 0.13208)
		(layer "F.Cu")
		(net "USB2_5_R1_DP")
	)
	(segment
		(start 14.9098 -11.63701)
		(end 14.64056 -11.90625)
		(width 0.13208)
		(layer "F.Cu")
		(net "USB2_5_R1_DP")
	)
	(segment
		(start 13.43152 -14.120368)
		(end 13.43152 -14.478508)
		(width 0.13208)
		(layer "F.Cu")
		(net "USB2_5_R1_DP")
	)
	(segment
		(start 16.5862 -6.480048)
		(end 16.46174 -6.355588)
		(width 0.13208)
		(layer "F.Cu")
		(net "USB2_5_R1_DP")
	)
	(segment
		(start 13.55598 -13.995908)
		(end 13.43152 -14.120368)
		(width 0.13208)
		(layer "F.Cu")
		(net "USB2_5_R1_DP")
	)
	(segment
		(start 14.9098 -10.069576)
		(end 15.03426 -10.194036)
		(width 0.13208)
		(layer "F.Cu")
		(net "USB2_5_R1_DP")
	)
	(segment
		(start 15.771622 -6.980936)
		(end 15.502128 -7.25043)
		(width 0.13208)
		(layer "F.Cu")
		(net "USB2_5_R1_DP")
	)
	(segment
		(start 14.9098 -8.047736)
		(end 15.03426 -8.172196)
		(width 0.13208)
		(layer "F.Cu")
		(net "USB2_5_R1_DP")
	)
	(segment
		(start 17.51838 -7.620508)
		(end 17.51838 -6.554216)
		(width 0.13208)
		(layer "F.Cu")
		(net "USB2_5_R1_DP")
	)
	(segment
		(start 14.9098 -8.677656)
		(end 14.9098 -9.058656)
		(width 0.13208)
		(layer "F.Cu")
		(net "USB2_5_R1_DP")
	)
	(segment
		(start 13.43152 -14.478508)
		(end 13.87348 -14.920468)
		(width 0.13208)
		(layer "F.Cu")
		(net "USB2_5_R1_DP")
	)
	(segment
		(start 13.551154 -12.995656)
		(end 13.43152 -13.11529)
		(width 0.13208)
		(layer "F.Cu")
		(net "USB2_5_R1_DP")
	)
	(segment
		(start 17.34693 -8.320024)
		(end 17.34693 -7.791958)
		(width 0.13208)
		(layer "F.Cu")
		(net "USB2_5_R1_DP")
	)
	(segment
		(start 13.43152 -13.11529)
		(end 13.43152 -13.490448)
		(width 0.13208)
		(layer "F.Cu")
		(net "USB2_5_R1_DP")
	)
	(segment
		(start 14.64056 -11.90625)
		(end 14.64056 -12.082272)
		(width 0.13208)
		(layer "F.Cu")
		(net "USB2_5_R1_DP")
	)
	(segment
		(start 15.03426 -10.575036)
		(end 14.9098 -10.699496)
		(width 0.13208)
		(layer "F.Cu")
		(net "USB2_5_R1_DP")
	)
	(segment
		(start 14.9098 -9.688576)
		(end 14.9098 -10.069576)
		(width 0.13208)
		(layer "F.Cu")
		(net "USB2_5_R1_DP")
	)
	(segment
		(start 14.9098 -9.058656)
		(end 15.03426 -9.183116)
		(width 0.13208)
		(layer "F.Cu")
		(net "USB2_5_R1_DP")
	)
	(segment
		(start 14.9098 -7.666736)
		(end 14.9098 -8.047736)
		(width 0.13208)
		(layer "F.Cu")
		(net "USB2_5_R1_DP")
	)
	(segment
		(start 13.727176 -12.995656)
		(end 13.551154 -12.995656)
		(width 0.13208)
		(layer "F.Cu")
		(net "USB2_5_R1_DP")
	)
	(segment
		(start 17.34693 -7.791958)
		(end 17.51838 -7.620508)
		(width 0.13208)
		(layer "F.Cu")
		(net "USB2_5_R1_DP")
	)
	(segment
		(start 15.03426 -9.564116)
		(end 14.9098 -9.688576)
		(width 0.13208)
		(layer "F.Cu")
		(net "USB2_5_R1_DP")
	)
	(segment
		(start 15.326106 -7.25043)
		(end 14.9098 -7.666736)
		(width 0.13208)
		(layer "F.Cu")
		(net "USB2_5_R1_DP")
	)
	(segment
		(start 16.9672 -6.480048)
		(end 16.5862 -6.480048)
		(width 0.13208)
		(layer "F.Cu")
		(net "USB2_5_R1_DP")
	)
	(segment
		(start 15.771622 -6.804914)
		(end 15.771622 -6.980936)
		(width 0.13208)
		(layer "F.Cu")
		(net "USB2_5_R1_DP")
	)
	(segment
		(start 15.03426 -8.172196)
		(end 15.03426 -8.553196)
		(width 0.13208)
		(layer "F.Cu")
		(net "USB2_5_R1_DP")
	)
	(segment
		(start 16.220948 -6.355588)
		(end 15.771622 -6.804914)
		(width 0.13208)
		(layer "F.Cu")
		(net "USB2_5_R1_DP")
	)
	(segment
		(start 15.502128 -7.25043)
		(end 15.326106 -7.25043)
		(width 0.13208)
		(layer "F.Cu")
		(net "USB2_5_R1_DP")
	)
	(segment
		(start 15.03426 -8.553196)
		(end 14.9098 -8.677656)
		(width 0.13208)
		(layer "F.Cu")
		(net "USB2_5_R1_DP")
	)
	(segment
		(start 13.43152 -13.490448)
		(end 13.55598 -13.614908)
		(width 0.13208)
		(layer "F.Cu")
		(net "USB2_5_R1_DP")
	)
	(segment
		(start 17.77746 -7.590028)
		(end 17.77746 -6.446774)
		(width 0.13208)
		(layer "F.Cu")
		(net "USB2_5_R1_DN")
	)
	(segment
		(start 13.17244 -14.52626)
		(end 12.778232 -14.920468)
		(width 0.13208)
		(layer "F.Cu")
		(net "USB2_5_R1_DN")
	)
	(segment
		(start 16.113506 -6.096508)
		(end 14.65072 -7.559294)
		(width 0.13208)
		(layer "F.Cu")
		(net "USB2_5_R1_DN")
	)
	(segment
		(start 14.65072 -7.559294)
		(end 14.65072 -11.529568)
		(width 0.13208)
		(layer "F.Cu")
		(net "USB2_5_R1_DN")
	)
	(segment
		(start 14.65072 -11.529568)
		(end 13.17244 -13.007848)
		(width 0.13208)
		(layer "F.Cu")
		(net "USB2_5_R1_DN")
	)
	(segment
		(start 17.946878 -8.320024)
		(end 17.946878 -7.759446)
		(width 0.13208)
		(layer "F.Cu")
		(net "USB2_5_R1_DN")
	)
	(segment
		(start 13.17244 -13.007848)
		(end 13.17244 -14.52626)
		(width 0.13208)
		(layer "F.Cu")
		(net "USB2_5_R1_DN")
	)
	(segment
		(start 17.427194 -6.096508)
		(end 16.113506 -6.096508)
		(width 0.13208)
		(layer "F.Cu")
		(net "USB2_5_R1_DN")
	)
	(segment
		(start 17.946878 -7.759446)
		(end 17.77746 -7.590028)
		(width 0.13208)
		(layer "F.Cu")
		(net "USB2_5_R1_DN")
	)
	(segment
		(start 17.77746 -6.446774)
		(end 17.427194 -6.096508)
		(width 0.13208)
		(layer "F.Cu")
		(net "USB2_5_R1_DN")
	)
	(segment
		(start 131.998466 -37.399722)
		(end 135.006842 -37.399722)
		(width 0.12954)
		(layer "F.Cu")
		(net "OCP_V3_2_RBT_ARB_OUT")
	)
	(segment
		(start 131.82854 -37.569648)
		(end 131.998466 -37.399722)
		(width 0.12954)
		(layer "F.Cu")
		(net "OCP_V3_2_RBT_ARB_OUT")
	)
	(via
		(at 198.32828 -70.678548)
		(size 0.508)
		(drill 0.254)
		(layers "F.Cu" "B.Cu")
		(net "OCP_V3_2_RBT_ARB_OUT")
	)
	(via
		(at 202.16368 -79.416148)
		(size 0.508)
		(drill 0.254)
		(layers "F.Cu" "B.Cu")
		(net "OCP_V3_2_RBT_ARB_OUT")
	)
	(via
		(at 131.82854 -37.569648)
		(size 0.508)
		(drill 0.254)
		(layers "F.Cu" "B.Cu")
		(net "OCP_V3_2_RBT_ARB_OUT")
	)
	(segment
		(start 197.453758 -71.55307)
		(end 195.55333 -71.55307)
		(width 0.12954)
		(layer "B.Cu")
		(net "OCP_V3_2_RBT_ARB_OUT")
	)
	(segment
		(start 202.16368 -79.416148)
		(end 202.16368 -79.060548)
		(width 0.12954)
		(layer "B.Cu")
		(net "OCP_V3_2_RBT_ARB_OUT")
	)
	(segment
		(start 202.16368 -79.060548)
		(end 202.64501 -78.579218)
		(width 0.12954)
		(layer "B.Cu")
		(net "OCP_V3_2_RBT_ARB_OUT")
	)
	(segment
		(start 198.32828 -70.678548)
		(end 197.453758 -71.55307)
		(width 0.12954)
		(layer "B.Cu")
		(net "OCP_V3_2_RBT_ARB_OUT")
	)
	(segment
		(start 202.64501 -78.579218)
		(end 202.64501 -78.247748)
		(width 0.12954)
		(layer "B.Cu")
		(net "OCP_V3_2_RBT_ARB_OUT")
	)
	(segment
		(start 204.978 -80.076548)
		(end 208.04759 -77.006958)
		(width 0.127)
		(layer "In2.Cu")
		(net "OCP_V3_2_RBT_ARB_OUT")
	)
	(segment
		(start 199.8218 -70.678548)
		(end 198.32828 -70.678548)
		(width 0.127)
		(layer "In2.Cu")
		(net "OCP_V3_2_RBT_ARB_OUT")
	)
	(segment
		(start 206.493364 -70.433184)
		(end 200.067164 -70.433184)
		(width 0.127)
		(layer "In2.Cu")
		(net "OCP_V3_2_RBT_ARB_OUT")
	)
	(segment
		(start 202.16368 -79.764128)
		(end 202.4761 -80.076548)
		(width 0.127)
		(layer "In2.Cu")
		(net "OCP_V3_2_RBT_ARB_OUT")
	)
	(segment
		(start 200.067164 -70.433184)
		(end 199.8218 -70.678548)
		(width 0.127)
		(layer "In2.Cu")
		(net "OCP_V3_2_RBT_ARB_OUT")
	)
	(segment
		(start 202.4761 -80.076548)
		(end 204.978 -80.076548)
		(width 0.127)
		(layer "In2.Cu")
		(net "OCP_V3_2_RBT_ARB_OUT")
	)
	(segment
		(start 208.04759 -77.006958)
		(end 208.04759 -70.293484)
		(width 0.127)
		(layer "In2.Cu")
		(net "OCP_V3_2_RBT_ARB_OUT")
	)
	(segment
		(start 207.594454 -69.840348)
		(end 207.0862 -69.840348)
		(width 0.127)
		(layer "In2.Cu")
		(net "OCP_V3_2_RBT_ARB_OUT")
	)
	(segment
		(start 207.0862 -69.840348)
		(end 206.493364 -70.433184)
		(width 0.127)
		(layer "In2.Cu")
		(net "OCP_V3_2_RBT_ARB_OUT")
	)
	(segment
		(start 208.04759 -70.293484)
		(end 207.594454 -69.840348)
		(width 0.127)
		(layer "In2.Cu")
		(net "OCP_V3_2_RBT_ARB_OUT")
	)
	(segment
		(start 202.16368 -79.416148)
		(end 202.16368 -79.764128)
		(width 0.127)
		(layer "In2.Cu")
		(net "OCP_V3_2_RBT_ARB_OUT")
	)
	(segment
		(start 170.86834 -55.443628)
		(end 174.88408 -55.443628)
		(width 0.127)
		(layer "In4.Cu")
		(net "OCP_V3_2_RBT_ARB_OUT")
	)
	(segment
		(start 144.44472 -41.610788)
		(end 144.653 -41.610788)
		(width 0.127)
		(layer "In4.Cu")
		(net "OCP_V3_2_RBT_ARB_OUT")
	)
	(segment
		(start 134.18566 -39.563548)
		(end 139.14628 -39.563548)
		(width 0.127)
		(layer "In4.Cu")
		(net "OCP_V3_2_RBT_ARB_OUT")
	)
	(segment
		(start 132.19176 -37.569648)
		(end 134.18566 -39.563548)
		(width 0.127)
		(layer "In4.Cu")
		(net "OCP_V3_2_RBT_ARB_OUT")
	)
	(segment
		(start 166.92372 -49.606708)
		(end 169.54754 -52.230528)
		(width 0.127)
		(layer "In4.Cu")
		(net "OCP_V3_2_RBT_ARB_OUT")
	)
	(segment
		(start 144.653 -41.610788)
		(end 152.64892 -49.606708)
		(width 0.127)
		(layer "In4.Cu")
		(net "OCP_V3_2_RBT_ARB_OUT")
	)
	(segment
		(start 169.54754 -52.230528)
		(end 169.54754 -54.122828)
		(width 0.127)
		(layer "In4.Cu")
		(net "OCP_V3_2_RBT_ARB_OUT")
	)
	(segment
		(start 177.8508 -58.410348)
		(end 182.4228 -58.410348)
		(width 0.127)
		(layer "In4.Cu")
		(net "OCP_V3_2_RBT_ARB_OUT")
	)
	(segment
		(start 197.65264 -70.002908)
		(end 198.32828 -70.678548)
		(width 0.127)
		(layer "In4.Cu")
		(net "OCP_V3_2_RBT_ARB_OUT")
	)
	(segment
		(start 139.97432 -40.391588)
		(end 143.22552 -40.391588)
		(width 0.127)
		(layer "In4.Cu")
		(net "OCP_V3_2_RBT_ARB_OUT")
	)
	(segment
		(start 152.64892 -49.606708)
		(end 166.92372 -49.606708)
		(width 0.127)
		(layer "In4.Cu")
		(net "OCP_V3_2_RBT_ARB_OUT")
	)
	(segment
		(start 182.4228 -58.410348)
		(end 186.78652 -62.774068)
		(width 0.127)
		(layer "In4.Cu")
		(net "OCP_V3_2_RBT_ARB_OUT")
	)
	(segment
		(start 169.54754 -54.122828)
		(end 170.86834 -55.443628)
		(width 0.127)
		(layer "In4.Cu")
		(net "OCP_V3_2_RBT_ARB_OUT")
	)
	(segment
		(start 143.22552 -40.391588)
		(end 144.44472 -41.610788)
		(width 0.127)
		(layer "In4.Cu")
		(net "OCP_V3_2_RBT_ARB_OUT")
	)
	(segment
		(start 131.82854 -37.569648)
		(end 132.19176 -37.569648)
		(width 0.127)
		(layer "In4.Cu")
		(net "OCP_V3_2_RBT_ARB_OUT")
	)
	(segment
		(start 139.14628 -39.563548)
		(end 139.97432 -40.391588)
		(width 0.127)
		(layer "In4.Cu")
		(net "OCP_V3_2_RBT_ARB_OUT")
	)
	(segment
		(start 197.65264 -64.897508)
		(end 197.65264 -70.002908)
		(width 0.127)
		(layer "In4.Cu")
		(net "OCP_V3_2_RBT_ARB_OUT")
	)
	(segment
		(start 186.78652 -62.774068)
		(end 195.5292 -62.774068)
		(width 0.127)
		(layer "In4.Cu")
		(net "OCP_V3_2_RBT_ARB_OUT")
	)
	(segment
		(start 195.5292 -62.774068)
		(end 197.65264 -64.897508)
		(width 0.127)
		(layer "In4.Cu")
		(net "OCP_V3_2_RBT_ARB_OUT")
	)
	(segment
		(start 174.88408 -55.443628)
		(end 177.8508 -58.410348)
		(width 0.127)
		(layer "In4.Cu")
		(net "OCP_V3_2_RBT_ARB_OUT")
	)
	(via
		(at 204.61478 -78.135988)
		(size 0.6604)
		(drill 0.3302)
		(layers "F.Cu" "B.Cu")
		(net "OCP_V3_2_RBT_ARB_IN_R")
	)
	(segment
		(start 204.83703 -77.913738)
		(end 206.374746 -77.913738)
		(width 0.12954)
		(layer "B.Cu")
		(net "OCP_V3_2_RBT_ARB_IN_R")
	)
	(segment
		(start 203.447396 -78.245462)
		(end 204.505306 -78.245462)
		(width 0.12954)
		(layer "B.Cu")
		(net "OCP_V3_2_RBT_ARB_IN_R")
	)
	(segment
		(start 204.505306 -78.245462)
		(end 204.61478 -78.135988)
		(width 0.12954)
		(layer "B.Cu")
		(net "OCP_V3_2_RBT_ARB_IN_R")
	)
	(segment
		(start 203.447396 -77.009752)
		(end 203.447396 -78.245462)
		(width 0.12954)
		(layer "B.Cu")
		(net "OCP_V3_2_RBT_ARB_IN_R")
	)
	(segment
		(start 203.447396 -78.245462)
		(end 203.44511 -78.247748)
		(width 0.12954)
		(layer "B.Cu")
		(net "OCP_V3_2_RBT_ARB_IN_R")
	)
	(segment
		(start 204.61478 -78.135988)
		(end 204.83703 -77.913738)
		(width 0.12954)
		(layer "B.Cu")
		(net "OCP_V3_2_RBT_ARB_IN_R")
	)
	(segment
		(start 135.006842 -32.827722)
		(end 133.89864 -32.827722)
		(width 0.12954)
		(layer "F.Cu")
		(net "OCP_V3_2_RBT_ARB_IN")
	)
	(via
		(at 134.494778 -51.421792)
		(size 0.508)
		(drill 0.254)
		(layers "F.Cu" "B.Cu")
		(net "OCP_V3_2_RBT_ARB_IN")
	)
	(via
		(at 146.729704 -76.268072)
		(size 0.508)
		(drill 0.254)
		(layers "F.Cu" "B.Cu")
		(net "OCP_V3_2_RBT_ARB_IN")
	)
	(via
		(at 203.12888 -76.317348)
		(size 0.508)
		(drill 0.254)
		(layers "F.Cu" "B.Cu")
		(net "OCP_V3_2_RBT_ARB_IN")
	)
	(via
		(at 133.89864 -32.827722)
		(size 0.508)
		(drill 0.254)
		(layers "F.Cu" "B.Cu")
		(net "OCP_V3_2_RBT_ARB_IN")
	)
	(segment
		(start 203.12888 -76.317348)
		(end 202.647296 -76.798932)
		(width 0.12954)
		(layer "B.Cu")
		(net "OCP_V3_2_RBT_ARB_IN")
	)
	(segment
		(start 202.647296 -76.798932)
		(end 202.647296 -77.009752)
		(width 0.12954)
		(layer "B.Cu")
		(net "OCP_V3_2_RBT_ARB_IN")
	)
	(segment
		(start 134.75335 -33.110678)
		(end 134.62635 -32.983678)
		(width 0.127)
		(layer "In2.Cu")
		(net "OCP_V3_2_RBT_ARB_IN")
	)
	(segment
		(start 135.658098 -42.245788)
		(end 134.75335 -41.34104)
		(width 0.127)
		(layer "In2.Cu")
		(net "OCP_V3_2_RBT_ARB_IN")
	)
	(segment
		(start 134.494778 -48.104806)
		(end 135.658098 -46.941486)
		(width 0.127)
		(layer "In2.Cu")
		(net "OCP_V3_2_RBT_ARB_IN")
	)
	(segment
		(start 134.62635 -32.983678)
		(end 134.054596 -32.983678)
		(width 0.127)
		(layer "In2.Cu")
		(net "OCP_V3_2_RBT_ARB_IN")
	)
	(segment
		(start 134.054596 -32.983678)
		(end 133.89864 -32.827722)
		(width 0.127)
		(layer "In2.Cu")
		(net "OCP_V3_2_RBT_ARB_IN")
	)
	(segment
		(start 134.494778 -51.421792)
		(end 134.494778 -48.104806)
		(width 0.127)
		(layer "In2.Cu")
		(net "OCP_V3_2_RBT_ARB_IN")
	)
	(segment
		(start 135.658098 -46.941486)
		(end 135.658098 -42.245788)
		(width 0.127)
		(layer "In2.Cu")
		(net "OCP_V3_2_RBT_ARB_IN")
	)
	(segment
		(start 134.75335 -41.34104)
		(end 134.75335 -33.110678)
		(width 0.127)
		(layer "In2.Cu")
		(net "OCP_V3_2_RBT_ARB_IN")
	)
	(segment
		(start 142.550388 -59.477402)
		(end 134.494778 -51.421792)
		(width 0.127)
		(layer "In11.Cu")
		(net "OCP_V3_2_RBT_ARB_IN")
	)
	(segment
		(start 203.70165 -79.918814)
		(end 202.609196 -81.011268)
		(width 0.127)
		(layer "In11.Cu")
		(net "OCP_V3_2_RBT_ARB_IN")
	)
	(segment
		(start 151.228552 -79.345536)
		(end 148.151088 -76.268072)
		(width 0.127)
		(layer "In11.Cu")
		(net "OCP_V3_2_RBT_ARB_IN")
	)
	(segment
		(start 195.380356 -81.011268)
		(end 194.9958 -81.395824)
		(width 0.127)
		(layer "In11.Cu")
		(net "OCP_V3_2_RBT_ARB_IN")
	)
	(segment
		(start 148.151088 -76.268072)
		(end 146.729704 -76.268072)
		(width 0.127)
		(layer "In11.Cu")
		(net "OCP_V3_2_RBT_ARB_IN")
	)
	(segment
		(start 146.729704 -76.268072)
		(end 146.729704 -68.58889)
		(width 0.127)
		(layer "In11.Cu")
		(net "OCP_V3_2_RBT_ARB_IN")
	)
	(segment
		(start 164.016436 -81.395824)
		(end 161.963608 -79.342996)
		(width 0.127)
		(layer "In11.Cu")
		(net "OCP_V3_2_RBT_ARB_IN")
	)
	(segment
		(start 147.591272 -64.130428)
		(end 142.938246 -59.477402)
		(width 0.127)
		(layer "In11.Cu")
		(net "OCP_V3_2_RBT_ARB_IN")
	)
	(segment
		(start 159.201104 -79.735934)
		(end 158.636208 -79.735934)
		(width 0.127)
		(layer "In11.Cu")
		(net "OCP_V3_2_RBT_ARB_IN")
	)
	(segment
		(start 203.12888 -76.317348)
		(end 203.12888 -78.26883)
		(width 0.127)
		(layer "In11.Cu")
		(net "OCP_V3_2_RBT_ARB_IN")
	)
	(segment
		(start 203.12888 -78.26883)
		(end 203.70165 -78.8416)
		(width 0.127)
		(layer "In11.Cu")
		(net "OCP_V3_2_RBT_ARB_IN")
	)
	(segment
		(start 147.591272 -67.727322)
		(end 147.591272 -64.130428)
		(width 0.127)
		(layer "In11.Cu")
		(net "OCP_V3_2_RBT_ARB_IN")
	)
	(segment
		(start 202.609196 -81.011268)
		(end 195.380356 -81.011268)
		(width 0.127)
		(layer "In11.Cu")
		(net "OCP_V3_2_RBT_ARB_IN")
	)
	(segment
		(start 146.729704 -68.58889)
		(end 147.591272 -67.727322)
		(width 0.127)
		(layer "In11.Cu")
		(net "OCP_V3_2_RBT_ARB_IN")
	)
	(segment
		(start 194.9958 -81.395824)
		(end 164.016436 -81.395824)
		(width 0.127)
		(layer "In11.Cu")
		(net "OCP_V3_2_RBT_ARB_IN")
	)
	(segment
		(start 158.636208 -79.735934)
		(end 158.24581 -79.345536)
		(width 0.127)
		(layer "In11.Cu")
		(net "OCP_V3_2_RBT_ARB_IN")
	)
	(segment
		(start 161.963608 -79.342996)
		(end 159.594042 -79.342996)
		(width 0.127)
		(layer "In11.Cu")
		(net "OCP_V3_2_RBT_ARB_IN")
	)
	(segment
		(start 159.594042 -79.342996)
		(end 159.201104 -79.735934)
		(width 0.127)
		(layer "In11.Cu")
		(net "OCP_V3_2_RBT_ARB_IN")
	)
	(segment
		(start 142.938246 -59.477402)
		(end 142.550388 -59.477402)
		(width 0.127)
		(layer "In11.Cu")
		(net "OCP_V3_2_RBT_ARB_IN")
	)
	(segment
		(start 203.70165 -78.8416)
		(end 203.70165 -79.918814)
		(width 0.127)
		(layer "In11.Cu")
		(net "OCP_V3_2_RBT_ARB_IN")
	)
	(segment
		(start 158.24581 -79.345536)
		(end 151.228552 -79.345536)
		(width 0.127)
		(layer "In11.Cu")
		(net "OCP_V3_2_RBT_ARB_IN")
	)
	(segment
		(start 116.767356 -29.450792)
		(end 117.42928 -29.450792)
		(width 0.12954)
		(layer "F.Cu")
		(net "OCP_V3_2_PWRBRK_N")
	)
	(segment
		(start 16.746982 -8.320024)
		(end 16.747236 -8.31977)
		(width 0.12954)
		(layer "F.Cu")
		(net "OCP_V3_2_PWRBRK_N")
	)
	(segment
		(start 16.747236 -8.31977)
		(end 16.747236 -8.319262)
		(width 0.12954)
		(layer "F.Cu")
		(net "OCP_V3_2_PWRBRK_N")
	)
	(segment
		(start 16.747236 -8.319262)
		(end 16.747998 -8.3185)
		(width 0.12954)
		(layer "F.Cu")
		(net "OCP_V3_2_PWRBRK_N")
	)
	(segment
		(start 16.747998 -8.3185)
		(end 16.747998 -7.214362)
		(width 0.12954)
		(layer "F.Cu")
		(net "OCP_V3_2_PWRBRK_N")
	)
	(via
		(at 16.747998 -7.214362)
		(size 0.508)
		(drill 0.254)
		(layers "F.Cu" "B.Cu")
		(net "OCP_V3_2_PWRBRK_N")
	)
	(via
		(at 117.42928 -29.450792)
		(size 0.508)
		(drill 0.254)
		(layers "F.Cu" "B.Cu")
		(net "OCP_V3_2_PWRBRK_N")
	)
	(segment
		(start 20.492212 -3.470148)
		(end 16.747998 -7.214362)
		(width 0.127)
		(layer "In2.Cu")
		(net "OCP_V3_2_PWRBRK_N")
	)
	(segment
		(start 46.91888 -4.562348)
		(end 45.89272 -3.536188)
		(width 0.127)
		(layer "In2.Cu")
		(net "OCP_V3_2_PWRBRK_N")
	)
	(segment
		(start 96.04248 -13.172948)
		(end 82.75828 -13.172948)
		(width 0.127)
		(layer "In2.Cu")
		(net "OCP_V3_2_PWRBRK_N")
	)
	(segment
		(start 72.57288 -4.511548)
		(end 72.09028 -4.994148)
		(width 0.127)
		(layer "In2.Cu")
		(net "OCP_V3_2_PWRBRK_N")
	)
	(segment
		(start 62.66688 -3.520948)
		(end 50.88128 -3.520948)
		(width 0.127)
		(layer "In2.Cu")
		(net "OCP_V3_2_PWRBRK_N")
	)
	(segment
		(start 45.89272 -3.536188)
		(end 40.12184 -3.536188)
		(width 0.127)
		(layer "In2.Cu")
		(net "OCP_V3_2_PWRBRK_N")
	)
	(segment
		(start 33.91408 -4.638548)
		(end 32.74568 -3.470148)
		(width 0.127)
		(layer "In2.Cu")
		(net "OCP_V3_2_PWRBRK_N")
	)
	(segment
		(start 116.797836 -28.819348)
		(end 107.242864 -28.819348)
		(width 0.127)
		(layer "In2.Cu")
		(net "OCP_V3_2_PWRBRK_N")
	)
	(segment
		(start 32.74568 -3.470148)
		(end 20.492212 -3.470148)
		(width 0.127)
		(layer "In2.Cu")
		(net "OCP_V3_2_PWRBRK_N")
	)
	(segment
		(start 40.12184 -3.536188)
		(end 39.01948 -4.638548)
		(width 0.127)
		(layer "In2.Cu")
		(net "OCP_V3_2_PWRBRK_N")
	)
	(segment
		(start 106.35488 -23.485348)
		(end 96.04248 -13.172948)
		(width 0.127)
		(layer "In2.Cu")
		(net "OCP_V3_2_PWRBRK_N")
	)
	(segment
		(start 80.168496 -10.583164)
		(end 80.168496 -9.154668)
		(width 0.127)
		(layer "In2.Cu")
		(net "OCP_V3_2_PWRBRK_N")
	)
	(segment
		(start 50.88128 -3.520948)
		(end 49.83988 -4.562348)
		(width 0.127)
		(layer "In2.Cu")
		(net "OCP_V3_2_PWRBRK_N")
	)
	(segment
		(start 117.42928 -29.450792)
		(end 116.797836 -28.819348)
		(width 0.127)
		(layer "In2.Cu")
		(net "OCP_V3_2_PWRBRK_N")
	)
	(segment
		(start 72.09028 -4.994148)
		(end 64.14008 -4.994148)
		(width 0.127)
		(layer "In2.Cu")
		(net "OCP_V3_2_PWRBRK_N")
	)
	(segment
		(start 49.83988 -4.562348)
		(end 46.91888 -4.562348)
		(width 0.127)
		(layer "In2.Cu")
		(net "OCP_V3_2_PWRBRK_N")
	)
	(segment
		(start 78.41488 -7.401052)
		(end 78.41488 -6.441948)
		(width 0.127)
		(layer "In2.Cu")
		(net "OCP_V3_2_PWRBRK_N")
	)
	(segment
		(start 107.242864 -28.819348)
		(end 106.35488 -27.931364)
		(width 0.127)
		(layer "In2.Cu")
		(net "OCP_V3_2_PWRBRK_N")
	)
	(segment
		(start 106.35488 -27.931364)
		(end 106.35488 -23.485348)
		(width 0.127)
		(layer "In2.Cu")
		(net "OCP_V3_2_PWRBRK_N")
	)
	(segment
		(start 76.48448 -4.511548)
		(end 72.57288 -4.511548)
		(width 0.127)
		(layer "In2.Cu")
		(net "OCP_V3_2_PWRBRK_N")
	)
	(segment
		(start 64.14008 -4.994148)
		(end 62.66688 -3.520948)
		(width 0.127)
		(layer "In2.Cu")
		(net "OCP_V3_2_PWRBRK_N")
	)
	(segment
		(start 78.41488 -6.441948)
		(end 76.48448 -4.511548)
		(width 0.127)
		(layer "In2.Cu")
		(net "OCP_V3_2_PWRBRK_N")
	)
	(segment
		(start 39.01948 -4.638548)
		(end 33.91408 -4.638548)
		(width 0.127)
		(layer "In2.Cu")
		(net "OCP_V3_2_PWRBRK_N")
	)
	(segment
		(start 82.75828 -13.172948)
		(end 80.168496 -10.583164)
		(width 0.127)
		(layer "In2.Cu")
		(net "OCP_V3_2_PWRBRK_N")
	)
	(segment
		(start 80.168496 -9.154668)
		(end 78.41488 -7.401052)
		(width 0.127)
		(layer "In2.Cu")
		(net "OCP_V3_2_PWRBRK_N")
	)
	(segment
		(start 115.443 -31.245048)
		(end 115.967256 -30.720792)
		(width 0.12954)
		(layer "F.Cu")
		(net "OCP_V3_2_PWRBRK_BUFF_N")
	)
	(segment
		(start 115.967256 -30.720792)
		(end 115.967256 -29.450792)
		(width 0.12954)
		(layer "F.Cu")
		(net "OCP_V3_2_PWRBRK_BUFF_N")
	)
	(segment
		(start 114.39652 -29.76753)
		(end 114.39652 -31.245048)
		(width 0.12954)
		(layer "F.Cu")
		(net "OCP_V3_2_PWRBRK_BUFF_N")
	)
	(segment
		(start 114.39652 -31.245048)
		(end 115.443 -31.245048)
		(width 0.12954)
		(layer "F.Cu")
		(net "OCP_V3_2_PWRBRK_BUFF_N")
	)
	(via
		(at 114.39652 -31.245048)
		(size 0.762)
		(drill 0.381)
		(layers "F.Cu" "B.Cu")
		(net "OCP_V3_2_PWRBRK_BUFF_N")
	)
	(segment
		(start 142.00251 -35.391852)
		(end 141.605254 -34.994596)
		(width 0.12954)
		(layer "F.Cu")
		(net "OCP_V3_2_PRSNT_ALL_R_N")
	)
	(segment
		(start 141.10843 -39.085012)
		(end 141.61135 -39.085012)
		(width 0.12954)
		(layer "F.Cu")
		(net "OCP_V3_2_PRSNT_ALL_R_N")
	)
	(segment
		(start 141.61135 -39.085012)
		(end 142.00251 -38.693852)
		(width 0.12954)
		(layer "F.Cu")
		(net "OCP_V3_2_PRSNT_ALL_R_N")
	)
	(segment
		(start 141.10843 -39.085012)
		(end 141.10843 -39.741348)
		(width 0.12954)
		(layer "F.Cu")
		(net "OCP_V3_2_PRSNT_ALL_R_N")
	)
	(segment
		(start 141.605254 -34.994596)
		(end 141.10843 -34.994596)
		(width 0.12954)
		(layer "F.Cu")
		(net "OCP_V3_2_PRSNT_ALL_R_N")
	)
	(segment
		(start 142.00251 -38.693852)
		(end 142.00251 -35.391852)
		(width 0.12954)
		(layer "F.Cu")
		(net "OCP_V3_2_PRSNT_ALL_R_N")
	)
	(segment
		(start 11.351768 -74.521568)
		(end 10.16 -74.521568)
		(width 0.12954)
		(layer "F.Cu")
		(net "OCP_V3_2_PRSNT_ALL_R_N")
	)
	(via
		(at 141.10843 -39.741348)
		(size 0.508)
		(drill 0.254)
		(layers "F.Cu" "B.Cu")
		(net "OCP_V3_2_PRSNT_ALL_R_N")
	)
	(via
		(at 10.16 -74.521568)
		(size 0.508)
		(drill 0.254)
		(layers "F.Cu" "B.Cu")
		(net "OCP_V3_2_PRSNT_ALL_R_N")
	)
	(segment
		(start 119.58828 -36.167568)
		(end 123.16206 -39.741348)
		(width 0.127)
		(layer "In15.Cu")
		(net "OCP_V3_2_PRSNT_ALL_R_N")
	)
	(segment
		(start 8.34898 -49.825148)
		(end 38.9636 -49.825148)
		(width 0.127)
		(layer "In15.Cu")
		(net "OCP_V3_2_PRSNT_ALL_R_N")
	)
	(segment
		(start 76.4286 -36.337748)
		(end 77.7494 -37.658548)
		(width 0.127)
		(layer "In15.Cu")
		(net "OCP_V3_2_PRSNT_ALL_R_N")
	)
	(segment
		(start 81.902808 -37.658548)
		(end 82.321908 -37.239448)
		(width 0.127)
		(layer "In15.Cu")
		(net "OCP_V3_2_PRSNT_ALL_R_N")
	)
	(segment
		(start 88.966548 -36.167568)
		(end 119.58828 -36.167568)
		(width 0.127)
		(layer "In15.Cu")
		(net "OCP_V3_2_PRSNT_ALL_R_N")
	)
	(segment
		(start 7.42188 -50.752248)
		(end 8.34898 -49.825148)
		(width 0.127)
		(layer "In15.Cu")
		(net "OCP_V3_2_PRSNT_ALL_R_N")
	)
	(segment
		(start 82.321908 -37.239448)
		(end 87.894668 -37.239448)
		(width 0.127)
		(layer "In15.Cu")
		(net "OCP_V3_2_PRSNT_ALL_R_N")
	)
	(segment
		(start 5.4102 -69.771768)
		(end 5.4102 -54.049168)
		(width 0.127)
		(layer "In15.Cu")
		(net "OCP_V3_2_PRSNT_ALL_R_N")
	)
	(segment
		(start 87.894668 -37.239448)
		(end 88.966548 -36.167568)
		(width 0.127)
		(layer "In15.Cu")
		(net "OCP_V3_2_PRSNT_ALL_R_N")
	)
	(segment
		(start 7.42188 -52.037488)
		(end 7.42188 -50.752248)
		(width 0.127)
		(layer "In15.Cu")
		(net "OCP_V3_2_PRSNT_ALL_R_N")
	)
	(segment
		(start 63.5254 -35.321748)
		(end 64.5414 -36.337748)
		(width 0.127)
		(layer "In15.Cu")
		(net "OCP_V3_2_PRSNT_ALL_R_N")
	)
	(segment
		(start 123.16206 -39.741348)
		(end 141.10843 -39.741348)
		(width 0.127)
		(layer "In15.Cu")
		(net "OCP_V3_2_PRSNT_ALL_R_N")
	)
	(segment
		(start 38.9636 -49.825148)
		(end 53.467 -35.321748)
		(width 0.127)
		(layer "In15.Cu")
		(net "OCP_V3_2_PRSNT_ALL_R_N")
	)
	(segment
		(start 5.4102 -54.049168)
		(end 7.42188 -52.037488)
		(width 0.127)
		(layer "In15.Cu")
		(net "OCP_V3_2_PRSNT_ALL_R_N")
	)
	(segment
		(start 10.16 -74.521568)
		(end 5.4102 -69.771768)
		(width 0.127)
		(layer "In15.Cu")
		(net "OCP_V3_2_PRSNT_ALL_R_N")
	)
	(segment
		(start 53.467 -35.321748)
		(end 63.5254 -35.321748)
		(width 0.127)
		(layer "In15.Cu")
		(net "OCP_V3_2_PRSNT_ALL_R_N")
	)
	(segment
		(start 77.7494 -37.658548)
		(end 81.902808 -37.658548)
		(width 0.127)
		(layer "In15.Cu")
		(net "OCP_V3_2_PRSNT_ALL_R_N")
	)
	(segment
		(start 64.5414 -36.337748)
		(end 76.4286 -36.337748)
		(width 0.127)
		(layer "In15.Cu")
		(net "OCP_V3_2_PRSNT_ALL_R_N")
	)
	(segment
		(start 140.292074 -35.010852)
		(end 140.30833 -34.994596)
		(width 0.12954)
		(layer "F.Cu")
		(net "OCP_V3_2_PRSNT_ALL_R3_N")
	)
	(segment
		(start 138.452352 -34.127694)
		(end 138.801094 -34.476436)
		(width 0.12954)
		(layer "F.Cu")
		(net "OCP_V3_2_PRSNT_ALL_R3_N")
	)
	(segment
		(start 138.801094 -34.476436)
		(end 139.33551 -35.010852)
		(width 0.12954)
		(layer "F.Cu")
		(net "OCP_V3_2_PRSNT_ALL_R3_N")
	)
	(segment
		(start 139.33551 -35.010852)
		(end 140.292074 -35.010852)
		(width 0.12954)
		(layer "F.Cu")
		(net "OCP_V3_2_PRSNT_ALL_R3_N")
	)
	(segment
		(start 137.006838 -34.127694)
		(end 138.452352 -34.127694)
		(width 0.12954)
		(layer "F.Cu")
		(net "OCP_V3_2_PRSNT_ALL_R3_N")
	)
	(via
		(at 138.801094 -34.476436)
		(size 0.762)
		(drill 0.381)
		(layers "F.Cu" "B.Cu")
		(net "OCP_V3_2_PRSNT_ALL_R3_N")
	)
	(segment
		(start 137.006838 -38.699694)
		(end 138.412982 -38.699694)
		(width 0.12954)
		(layer "F.Cu")
		(net "OCP_V3_2_PRSNT_ALL_R1_N")
	)
	(segment
		(start 139.3825 -39.085012)
		(end 140.30833 -39.085012)
		(width 0.12954)
		(layer "F.Cu")
		(net "OCP_V3_2_PRSNT_ALL_R1_N")
	)
	(segment
		(start 138.412982 -38.699694)
		(end 139.0904 -39.377112)
		(width 0.12954)
		(layer "F.Cu")
		(net "OCP_V3_2_PRSNT_ALL_R1_N")
	)
	(segment
		(start 139.0904 -39.377112)
		(end 139.3825 -39.085012)
		(width 0.12954)
		(layer "F.Cu")
		(net "OCP_V3_2_PRSNT_ALL_R1_N")
	)
	(via
		(at 139.0904 -39.377112)
		(size 0.762)
		(drill 0.381)
		(layers "F.Cu" "B.Cu")
		(net "OCP_V3_2_PRSNT_ALL_R1_N")
	)
	(segment
		(start 24.14524 -71.171562)
		(end 23.7236 -71.171562)
		(width 0.12954)
		(layer "F.Cu")
		(net "OCP_V3_2_PRSNT3_R_N")
	)
	(segment
		(start 16.747998 -11.270996)
		(end 16.747998 -12.37488)
		(width 0.12954)
		(layer "F.Cu")
		(net "OCP_V3_2_PRSNT3_R_N")
	)
	(segment
		(start 19.19478 -73.497948)
		(end 23.80488 -73.497948)
		(width 0.12954)
		(layer "F.Cu")
		(net "OCP_V3_2_PRSNT3_R_N")
	)
	(segment
		(start 18.07972 -72.382888)
		(end 19.19478 -73.497948)
		(width 0.12954)
		(layer "F.Cu")
		(net "OCP_V3_2_PRSNT3_R_N")
	)
	(segment
		(start 7.129272 -74.394568)
		(end 8.76808 -74.394568)
		(width 0.12954)
		(layer "F.Cu")
		(net "OCP_V3_2_PRSNT3_R_N")
	)
	(segment
		(start 24.43988 -71.466202)
		(end 24.14524 -71.171562)
		(width 0.12954)
		(layer "F.Cu")
		(net "OCP_V3_2_PRSNT3_R_N")
	)
	(segment
		(start 22.31263 -70.814692)
		(end 22.6695 -71.171562)
		(width 0.12954)
		(layer "F.Cu")
		(net "OCP_V3_2_PRSNT3_R_N")
	)
	(segment
		(start 22.6695 -71.171562)
		(end 23.7236 -71.171562)
		(width 0.12954)
		(layer "F.Cu")
		(net "OCP_V3_2_PRSNT3_R_N")
	)
	(segment
		(start 24.43988 -72.862948)
		(end 24.43988 -71.466202)
		(width 0.12954)
		(layer "F.Cu")
		(net "OCP_V3_2_PRSNT3_R_N")
	)
	(segment
		(start 21.00961 -70.814692)
		(end 22.31263 -70.814692)
		(width 0.12954)
		(layer "F.Cu")
		(net "OCP_V3_2_PRSNT3_R_N")
	)
	(segment
		(start 16.746982 -11.26998)
		(end 16.747998 -11.270996)
		(width 0.12954)
		(layer "F.Cu")
		(net "OCP_V3_2_PRSNT3_R_N")
	)
	(segment
		(start 8.76808 -74.394568)
		(end 10.77976 -72.382888)
		(width 0.12954)
		(layer "F.Cu")
		(net "OCP_V3_2_PRSNT3_R_N")
	)
	(segment
		(start 10.77976 -72.382888)
		(end 18.07972 -72.382888)
		(width 0.12954)
		(layer "F.Cu")
		(net "OCP_V3_2_PRSNT3_R_N")
	)
	(segment
		(start 23.80488 -73.497948)
		(end 24.43988 -72.862948)
		(width 0.12954)
		(layer "F.Cu")
		(net "OCP_V3_2_PRSNT3_R_N")
	)
	(via
		(at 16.747998 -12.37488)
		(size 0.508)
		(drill 0.254)
		(layers "F.Cu" "B.Cu")
		(net "OCP_V3_2_PRSNT3_R_N")
	)
	(via
		(at 22.31263 -70.814692)
		(size 0.508)
		(drill 0.254)
		(layers "F.Cu" "B.Cu")
		(net "OCP_V3_2_PRSNT3_R_N")
	)
	(segment
		(start 16.747998 -13.32611)
		(end 19.585178 -16.16329)
		(width 0.12954)
		(layer "B.Cu")
		(net "OCP_V3_2_PRSNT3_R_N")
	)
	(segment
		(start 28.03525 -16.16329)
		(end 28.79344 -16.92148)
		(width 0.12954)
		(layer "B.Cu")
		(net "OCP_V3_2_PRSNT3_R_N")
	)
	(segment
		(start 16.747998 -12.37488)
		(end 16.747998 -13.32611)
		(width 0.12954)
		(layer "B.Cu")
		(net "OCP_V3_2_PRSNT3_R_N")
	)
	(segment
		(start 30.15234 -39.314628)
		(end 22.500336 -46.966632)
		(width 0.12954)
		(layer "B.Cu")
		(net "OCP_V3_2_PRSNT3_R_N")
	)
	(segment
		(start 28.79344 -17.955768)
		(end 28.29814 -18.451068)
		(width 0.12954)
		(layer "B.Cu")
		(net "OCP_V3_2_PRSNT3_R_N")
	)
	(segment
		(start 19.585178 -16.16329)
		(end 28.03525 -16.16329)
		(width 0.12954)
		(layer "B.Cu")
		(net "OCP_V3_2_PRSNT3_R_N")
	)
	(segment
		(start 30.15234 -21.758148)
		(end 30.15234 -39.314628)
		(width 0.12954)
		(layer "B.Cu")
		(net "OCP_V3_2_PRSNT3_R_N")
	)
	(segment
		(start 22.500336 -46.966632)
		(end 22.500336 -70.626986)
		(width 0.12954)
		(layer "B.Cu")
		(net "OCP_V3_2_PRSNT3_R_N")
	)
	(segment
		(start 28.79344 -16.92148)
		(end 28.79344 -17.955768)
		(width 0.12954)
		(layer "B.Cu")
		(net "OCP_V3_2_PRSNT3_R_N")
	)
	(segment
		(start 22.500336 -70.626986)
		(end 22.31263 -70.814692)
		(width 0.12954)
		(layer "B.Cu")
		(net "OCP_V3_2_PRSNT3_R_N")
	)
	(segment
		(start 28.29814 -18.451068)
		(end 28.29814 -19.903948)
		(width 0.12954)
		(layer "B.Cu")
		(net "OCP_V3_2_PRSNT3_R_N")
	)
	(segment
		(start 28.29814 -19.903948)
		(end 30.15234 -21.758148)
		(width 0.12954)
		(layer "B.Cu")
		(net "OCP_V3_2_PRSNT3_R_N")
	)
	(segment
		(start 8.478012 -73.694798)
		(end 7.129272 -73.694798)
		(width 0.12954)
		(layer "F.Cu")
		(net "OCP_V3_2_PRSNT2_R_N")
	)
	(segment
		(start 19.98218 -71.683118)
		(end 10.489692 -71.683118)
		(width 0.12954)
		(layer "F.Cu")
		(net "OCP_V3_2_PRSNT2_R_N")
	)
	(segment
		(start 22.25548 -72.471534)
		(end 21.248624 -72.471534)
		(width 0.12954)
		(layer "F.Cu")
		(net "OCP_V3_2_PRSNT2_R_N")
	)
	(segment
		(start 23.7236 -72.471534)
		(end 22.25548 -72.471534)
		(width 0.12954)
		(layer "F.Cu")
		(net "OCP_V3_2_PRSNT2_R_N")
	)
	(segment
		(start 59.267344 -8.31977)
		(end 59.267344 -4.48691)
		(width 0.12954)
		(layer "F.Cu")
		(net "OCP_V3_2_PRSNT2_R_N")
	)
	(segment
		(start 21.248624 -72.471534)
		(end 21.00961 -72.710548)
		(width 0.12954)
		(layer "F.Cu")
		(net "OCP_V3_2_PRSNT2_R_N")
	)
	(segment
		(start 10.489692 -71.683118)
		(end 8.478012 -73.694798)
		(width 0.12954)
		(layer "F.Cu")
		(net "OCP_V3_2_PRSNT2_R_N")
	)
	(segment
		(start 59.26709 -8.320024)
		(end 59.267344 -8.31977)
		(width 0.12954)
		(layer "F.Cu")
		(net "OCP_V3_2_PRSNT2_R_N")
	)
	(segment
		(start 21.00961 -72.710548)
		(end 19.98218 -71.683118)
		(width 0.12954)
		(layer "F.Cu")
		(net "OCP_V3_2_PRSNT2_R_N")
	)
	(segment
		(start 59.267344 -4.48691)
		(end 59.268106 -4.486148)
		(width 0.12954)
		(layer "F.Cu")
		(net "OCP_V3_2_PRSNT2_R_N")
	)
	(via
		(at 22.25548 -72.471534)
		(size 0.508)
		(drill 0.254)
		(layers "F.Cu" "B.Cu")
		(net "OCP_V3_2_PRSNT2_R_N")
	)
	(via
		(at 59.268106 -4.486148)
		(size 0.508)
		(drill 0.254)
		(layers "F.Cu" "B.Cu")
		(net "OCP_V3_2_PRSNT2_R_N")
	)
	(segment
		(start 35.82162 -8.654288)
		(end 31.09468 -13.381228)
		(width 0.12954)
		(layer "B.Cu")
		(net "OCP_V3_2_PRSNT2_R_N")
	)
	(segment
		(start 49.07788 -4.486148)
		(end 46.91888 -4.486148)
		(width 0.12954)
		(layer "B.Cu")
		(net "OCP_V3_2_PRSNT2_R_N")
	)
	(segment
		(start 31.09468 -18.067528)
		(end 31.55188 -18.524728)
		(width 0.12954)
		(layer "B.Cu")
		(net "OCP_V3_2_PRSNT2_R_N")
	)
	(segment
		(start 46.91888 -4.486148)
		(end 45.92828 -3.495548)
		(width 0.12954)
		(layer "B.Cu")
		(net "OCP_V3_2_PRSNT2_R_N")
	)
	(segment
		(start 38.84168 -3.495548)
		(end 35.82162 -6.515608)
		(width 0.12954)
		(layer "B.Cu")
		(net "OCP_V3_2_PRSNT2_R_N")
	)
	(segment
		(start 31.55188 -18.524728)
		(end 31.55188 -39.629334)
		(width 0.12954)
		(layer "B.Cu")
		(net "OCP_V3_2_PRSNT2_R_N")
	)
	(segment
		(start 50.27168 -3.292348)
		(end 49.07788 -4.486148)
		(width 0.12954)
		(layer "B.Cu")
		(net "OCP_V3_2_PRSNT2_R_N")
	)
	(segment
		(start 23.179786 -48.001428)
		(end 23.179786 -70.922642)
		(width 0.12954)
		(layer "B.Cu")
		(net "OCP_V3_2_PRSNT2_R_N")
	)
	(segment
		(start 22.25548 -71.846948)
		(end 22.25548 -72.471534)
		(width 0.12954)
		(layer "B.Cu")
		(net "OCP_V3_2_PRSNT2_R_N")
	)
	(segment
		(start 45.92828 -3.495548)
		(end 38.84168 -3.495548)
		(width 0.12954)
		(layer "B.Cu")
		(net "OCP_V3_2_PRSNT2_R_N")
	)
	(segment
		(start 35.82162 -6.515608)
		(end 35.82162 -8.654288)
		(width 0.12954)
		(layer "B.Cu")
		(net "OCP_V3_2_PRSNT2_R_N")
	)
	(segment
		(start 59.268106 -4.486148)
		(end 58.074306 -3.292348)
		(width 0.12954)
		(layer "B.Cu")
		(net "OCP_V3_2_PRSNT2_R_N")
	)
	(segment
		(start 58.074306 -3.292348)
		(end 50.27168 -3.292348)
		(width 0.12954)
		(layer "B.Cu")
		(net "OCP_V3_2_PRSNT2_R_N")
	)
	(segment
		(start 23.179786 -70.922642)
		(end 22.25548 -71.846948)
		(width 0.12954)
		(layer "B.Cu")
		(net "OCP_V3_2_PRSNT2_R_N")
	)
	(segment
		(start 31.09468 -13.381228)
		(end 31.09468 -18.067528)
		(width 0.12954)
		(layer "B.Cu")
		(net "OCP_V3_2_PRSNT2_R_N")
	)
	(segment
		(start 31.55188 -39.629334)
		(end 23.179786 -48.001428)
		(width 0.12954)
		(layer "B.Cu")
		(net "OCP_V3_2_PRSNT2_R_N")
	)
	(segment
		(start 6.02488 -78.831948)
		(end 4.91744 -77.724508)
		(width 0.12954)
		(layer "F.Cu")
		(net "OCP_V3_2_PRSNT23_R_N")
	)
	(segment
		(start 14.22146 -74.521568)
		(end 13.31468 -75.428348)
		(width 0.12954)
		(layer "F.Cu")
		(net "OCP_V3_2_PRSNT23_R_N")
	)
	(segment
		(start 4.91744 -74.778108)
		(end 4.5339 -74.394568)
		(width 0.12954)
		(layer "F.Cu")
		(net "OCP_V3_2_PRSNT23_R_N")
	)
	(segment
		(start 4.5339 -74.394568)
		(end 3.579368 -74.394568)
		(width 0.12954)
		(layer "F.Cu")
		(net "OCP_V3_2_PRSNT23_R_N")
	)
	(segment
		(start 14.901672 -74.521568)
		(end 14.22146 -74.521568)
		(width 0.12954)
		(layer "F.Cu")
		(net "OCP_V3_2_PRSNT23_R_N")
	)
	(segment
		(start 13.31468 -75.428348)
		(end 13.31468 -77.587348)
		(width 0.12954)
		(layer "F.Cu")
		(net "OCP_V3_2_PRSNT23_R_N")
	)
	(segment
		(start 13.31468 -77.587348)
		(end 12.07008 -78.831948)
		(width 0.12954)
		(layer "F.Cu")
		(net "OCP_V3_2_PRSNT23_R_N")
	)
	(segment
		(start 4.91744 -77.254608)
		(end 4.91744 -74.778108)
		(width 0.12954)
		(layer "F.Cu")
		(net "OCP_V3_2_PRSNT23_R_N")
	)
	(segment
		(start 4.91744 -77.724508)
		(end 4.91744 -77.254608)
		(width 0.12954)
		(layer "F.Cu")
		(net "OCP_V3_2_PRSNT23_R_N")
	)
	(segment
		(start 12.07008 -78.831948)
		(end 6.02488 -78.831948)
		(width 0.12954)
		(layer "F.Cu")
		(net "OCP_V3_2_PRSNT23_R_N")
	)
	(via
		(at 4.91744 -77.254608)
		(size 0.762)
		(drill 0.381)
		(layers "F.Cu" "B.Cu")
		(net "OCP_V3_2_PRSNT23_R_N")
	)
	(segment
		(start 37.856922 -8.320024)
		(end 37.856922 -7.461758)
		(width 0.12954)
		(layer "F.Cu")
		(net "OCP_V3_2_PRSNT1_R_N")
	)
	(segment
		(start 21.00961 -75.132692)
		(end 22.31263 -75.132692)
		(width 0.12954)
		(layer "F.Cu")
		(net "OCP_V3_2_PRSNT1_R_N")
	)
	(segment
		(start 24.19604 -75.616562)
		(end 24.38908 -75.809602)
		(width 0.12954)
		(layer "F.Cu")
		(net "OCP_V3_2_PRSNT1_R_N")
	)
	(segment
		(start 1.71831 -75.97648)
		(end 2.649982 -75.044808)
		(width 0.12954)
		(layer "F.Cu")
		(net "OCP_V3_2_PRSNT1_R_N")
	)
	(segment
		(start 23.7236 -75.616562)
		(end 24.19604 -75.616562)
		(width 0.12954)
		(layer "F.Cu")
		(net "OCP_V3_2_PRSNT1_R_N")
	)
	(segment
		(start 37.856922 -7.461758)
		(end 37.572696 -7.177532)
		(width 0.12954)
		(layer "F.Cu")
		(net "OCP_V3_2_PRSNT1_R_N")
	)
	(segment
		(start 22.31263 -75.132692)
		(end 22.7965 -75.616562)
		(width 0.12954)
		(layer "F.Cu")
		(net "OCP_V3_2_PRSNT1_R_N")
	)
	(segment
		(start 2.649982 -75.044808)
		(end 3.579368 -75.044808)
		(width 0.12954)
		(layer "F.Cu")
		(net "OCP_V3_2_PRSNT1_R_N")
	)
	(segment
		(start 3.243834 -79.96174)
		(end 1.71831 -78.436216)
		(width 0.12954)
		(layer "F.Cu")
		(net "OCP_V3_2_PRSNT1_R_N")
	)
	(segment
		(start 24.38908 -77.663802)
		(end 22.091142 -79.96174)
		(width 0.12954)
		(layer "F.Cu")
		(net "OCP_V3_2_PRSNT1_R_N")
	)
	(segment
		(start 1.71831 -78.436216)
		(end 1.71831 -75.97648)
		(width 0.12954)
		(layer "F.Cu")
		(net "OCP_V3_2_PRSNT1_R_N")
	)
	(segment
		(start 22.091142 -79.96174)
		(end 3.243834 -79.96174)
		(width 0.12954)
		(layer "F.Cu")
		(net "OCP_V3_2_PRSNT1_R_N")
	)
	(segment
		(start 24.38908 -75.809602)
		(end 24.38908 -77.663802)
		(width 0.12954)
		(layer "F.Cu")
		(net "OCP_V3_2_PRSNT1_R_N")
	)
	(segment
		(start 22.7965 -75.616562)
		(end 23.7236 -75.616562)
		(width 0.12954)
		(layer "F.Cu")
		(net "OCP_V3_2_PRSNT1_R_N")
	)
	(via
		(at 37.572696 -7.177532)
		(size 0.508)
		(drill 0.254)
		(layers "F.Cu" "B.Cu")
		(net "OCP_V3_2_PRSNT1_R_N")
	)
	(via
		(at 22.31263 -75.132692)
		(size 0.508)
		(drill 0.254)
		(layers "F.Cu" "B.Cu")
		(net "OCP_V3_2_PRSNT1_R_N")
	)
	(segment
		(start 25.40508 -72.040242)
		(end 22.31263 -75.132692)
		(width 0.12954)
		(layer "B.Cu")
		(net "OCP_V3_2_PRSNT1_R_N")
	)
	(segment
		(start 33.89122 -43.881548)
		(end 25.40508 -52.367688)
		(width 0.12954)
		(layer "B.Cu")
		(net "OCP_V3_2_PRSNT1_R_N")
	)
	(segment
		(start 34.41954 -13.665708)
		(end 34.41954 -18.247868)
		(width 0.12954)
		(layer "B.Cu")
		(net "OCP_V3_2_PRSNT1_R_N")
	)
	(segment
		(start 34.41954 -18.247868)
		(end 33.89122 -18.776188)
		(width 0.12954)
		(layer "B.Cu")
		(net "OCP_V3_2_PRSNT1_R_N")
	)
	(segment
		(start 37.572696 -10.512552)
		(end 34.41954 -13.665708)
		(width 0.12954)
		(layer "B.Cu")
		(net "OCP_V3_2_PRSNT1_R_N")
	)
	(segment
		(start 25.40508 -52.367688)
		(end 25.40508 -72.040242)
		(width 0.12954)
		(layer "B.Cu")
		(net "OCP_V3_2_PRSNT1_R_N")
	)
	(segment
		(start 33.89122 -18.776188)
		(end 33.89122 -43.881548)
		(width 0.12954)
		(layer "B.Cu")
		(net "OCP_V3_2_PRSNT1_R_N")
	)
	(segment
		(start 37.572696 -7.177532)
		(end 37.572696 -10.512552)
		(width 0.12954)
		(layer "B.Cu")
		(net "OCP_V3_2_PRSNT1_R_N")
	)
	(segment
		(start 37.857938 -11.270996)
		(end 37.857938 -12.307316)
		(width 0.12954)
		(layer "F.Cu")
		(net "OCP_V3_2_PRSNT0_R_N")
	)
	(segment
		(start 2.36728 -78.095348)
		(end 2.36728 -76.291948)
		(width 0.12954)
		(layer "F.Cu")
		(net "OCP_V3_2_PRSNT0_R_N")
	)
	(segment
		(start 37.791136 -12.374118)
		(end 37.791136 -12.37488)
		(width 0.12954)
		(layer "F.Cu")
		(net "OCP_V3_2_PRSNT0_R_N")
	)
	(segment
		(start 21.121624 -76.916534)
		(end 21.00961 -77.028548)
		(width 0.12954)
		(layer "F.Cu")
		(net "OCP_V3_2_PRSNT0_R_N")
	)
	(segment
		(start 23.7236 -76.916534)
		(end 22.30628 -76.916534)
		(width 0.12954)
		(layer "F.Cu")
		(net "OCP_V3_2_PRSNT0_R_N")
	)
	(segment
		(start 21.00961 -78.219554)
		(end 19.762216 -79.466948)
		(width 0.12954)
		(layer "F.Cu")
		(net "OCP_V3_2_PRSNT0_R_N")
	)
	(segment
		(start 22.30628 -76.916534)
		(end 21.121624 -76.916534)
		(width 0.12954)
		(layer "F.Cu")
		(net "OCP_V3_2_PRSNT0_R_N")
	)
	(segment
		(start 3.73888 -79.466948)
		(end 2.36728 -78.095348)
		(width 0.12954)
		(layer "F.Cu")
		(net "OCP_V3_2_PRSNT0_R_N")
	)
	(segment
		(start 2.36728 -76.291948)
		(end 2.91465 -75.744578)
		(width 0.12954)
		(layer "F.Cu")
		(net "OCP_V3_2_PRSNT0_R_N")
	)
	(segment
		(start 37.857938 -12.307316)
		(end 37.791136 -12.374118)
		(width 0.12954)
		(layer "F.Cu")
		(net "OCP_V3_2_PRSNT0_R_N")
	)
	(segment
		(start 19.762216 -79.466948)
		(end 3.73888 -79.466948)
		(width 0.12954)
		(layer "F.Cu")
		(net "OCP_V3_2_PRSNT0_R_N")
	)
	(segment
		(start 37.856922 -11.26998)
		(end 37.857938 -11.270996)
		(width 0.12954)
		(layer "F.Cu")
		(net "OCP_V3_2_PRSNT0_R_N")
	)
	(segment
		(start 2.91465 -75.744578)
		(end 3.579368 -75.744578)
		(width 0.12954)
		(layer "F.Cu")
		(net "OCP_V3_2_PRSNT0_R_N")
	)
	(segment
		(start 21.00961 -77.028548)
		(end 21.00961 -78.219554)
		(width 0.12954)
		(layer "F.Cu")
		(net "OCP_V3_2_PRSNT0_R_N")
	)
	(via
		(at 37.791136 -12.37488)
		(size 0.508)
		(drill 0.254)
		(layers "F.Cu" "B.Cu")
		(net "OCP_V3_2_PRSNT0_R_N")
	)
	(via
		(at 22.30628 -76.916534)
		(size 0.508)
		(drill 0.254)
		(layers "F.Cu" "B.Cu")
		(net "OCP_V3_2_PRSNT0_R_N")
	)
	(segment
		(start 37.21354 -18.669508)
		(end 37.21354 -19.500088)
		(width 0.12954)
		(layer "B.Cu")
		(net "OCP_V3_2_PRSNT0_R_N")
	)
	(segment
		(start 36.98748 -19.726148)
		(end 36.98748 -42.156888)
		(width 0.12954)
		(layer "B.Cu")
		(net "OCP_V3_2_PRSNT0_R_N")
	)
	(segment
		(start 22.30628 -76.114148)
		(end 22.30628 -76.916534)
		(width 0.12954)
		(layer "B.Cu")
		(net "OCP_V3_2_PRSNT0_R_N")
	)
	(segment
		(start 37.21354 -19.500088)
		(end 36.98748 -19.726148)
		(width 0.12954)
		(layer "B.Cu")
		(net "OCP_V3_2_PRSNT0_R_N")
	)
	(segment
		(start 26.01468 -72.405748)
		(end 22.30628 -76.114148)
		(width 0.12954)
		(layer "B.Cu")
		(net "OCP_V3_2_PRSNT0_R_N")
	)
	(segment
		(start 36.98748 -42.156888)
		(end 26.01468 -53.129688)
		(width 0.12954)
		(layer "B.Cu")
		(net "OCP_V3_2_PRSNT0_R_N")
	)
	(segment
		(start 37.791136 -12.37488)
		(end 37.790374 -12.37488)
		(width 0.12954)
		(layer "B.Cu")
		(net "OCP_V3_2_PRSNT0_R_N")
	)
	(segment
		(start 36.63188 -13.533374)
		(end 36.63188 -18.087848)
		(width 0.12954)
		(layer "B.Cu")
		(net "OCP_V3_2_PRSNT0_R_N")
	)
	(segment
		(start 36.63188 -18.087848)
		(end 37.21354 -18.669508)
		(width 0.12954)
		(layer "B.Cu")
		(net "OCP_V3_2_PRSNT0_R_N")
	)
	(segment
		(start 26.01468 -53.129688)
		(end 26.01468 -72.405748)
		(width 0.12954)
		(layer "B.Cu")
		(net "OCP_V3_2_PRSNT0_R_N")
	)
	(segment
		(start 37.790374 -12.37488)
		(end 36.63188 -13.533374)
		(width 0.12954)
		(layer "B.Cu")
		(net "OCP_V3_2_PRSNT0_R_N")
	)
	(segment
		(start 14.31163 -73.821798)
		(end 14.901672 -73.821798)
		(width 0.12954)
		(layer "F.Cu")
		(net "OCP_V3_2_PRSNT01_R_N")
	)
	(segment
		(start 12.596876 -77.431392)
		(end 12.596876 -75.536552)
		(width 0.12954)
		(layer "F.Cu")
		(net "OCP_V3_2_PRSNT01_R_N")
	)
	(segment
		(start 12.596876 -75.536552)
		(end 14.31163 -73.821798)
		(width 0.12954)
		(layer "F.Cu")
		(net "OCP_V3_2_PRSNT01_R_N")
	)
	(segment
		(start 6.71068 -78.425548)
		(end 11.60272 -78.425548)
		(width 0.12954)
		(layer "F.Cu")
		(net "OCP_V3_2_PRSNT01_R_N")
	)
	(segment
		(start 5.51688 -77.231748)
		(end 6.71068 -78.425548)
		(width 0.12954)
		(layer "F.Cu")
		(net "OCP_V3_2_PRSNT01_R_N")
	)
	(segment
		(start 5.51688 -75.453748)
		(end 5.51688 -77.231748)
		(width 0.12954)
		(layer "F.Cu")
		(net "OCP_V3_2_PRSNT01_R_N")
	)
	(segment
		(start 11.60272 -78.425548)
		(end 12.596876 -77.431392)
		(width 0.12954)
		(layer "F.Cu")
		(net "OCP_V3_2_PRSNT01_R_N")
	)
	(segment
		(start 7.129272 -75.044808)
		(end 5.92582 -75.044808)
		(width 0.12954)
		(layer "F.Cu")
		(net "OCP_V3_2_PRSNT01_R_N")
	)
	(segment
		(start 5.92582 -75.044808)
		(end 5.51688 -75.453748)
		(width 0.12954)
		(layer "F.Cu")
		(net "OCP_V3_2_PRSNT01_R_N")
	)
	(via
		(at 12.596876 -77.431392)
		(size 0.762)
		(drill 0.381)
		(layers "F.Cu" "B.Cu")
		(net "OCP_V3_2_PRSNT01_R_N")
	)
	(segment
		(start 135.77951 -38.566852)
		(end 135.646668 -38.699694)
		(width 0.12954)
		(layer "F.Cu")
		(net "OCP_V3_2_NOT_PRSNT_RBT_ARB_IN")
	)
	(segment
		(start 135.77951 -34.248852)
		(end 135.77951 -35.524948)
		(width 0.12954)
		(layer "F.Cu")
		(net "OCP_V3_2_NOT_PRSNT_RBT_ARB_IN")
	)
	(segment
		(start 135.646668 -38.699694)
		(end 135.006842 -38.699694)
		(width 0.12954)
		(layer "F.Cu")
		(net "OCP_V3_2_NOT_PRSNT_RBT_ARB_IN")
	)
	(segment
		(start 135.006842 -34.127694)
		(end 135.658352 -34.127694)
		(width 0.12954)
		(layer "F.Cu")
		(net "OCP_V3_2_NOT_PRSNT_RBT_ARB_IN")
	)
	(segment
		(start 135.658352 -34.127694)
		(end 135.77951 -34.248852)
		(width 0.12954)
		(layer "F.Cu")
		(net "OCP_V3_2_NOT_PRSNT_RBT_ARB_IN")
	)
	(segment
		(start 135.77951 -35.524948)
		(end 135.77951 -38.566852)
		(width 0.12954)
		(layer "F.Cu")
		(net "OCP_V3_2_NOT_PRSNT_RBT_ARB_IN")
	)
	(via
		(at 135.77951 -35.524948)
		(size 0.762)
		(drill 0.381)
		(layers "F.Cu" "B.Cu")
		(net "OCP_V3_2_NOT_PRSNT_RBT_ARB_IN")
	)
	(segment
		(start 182.155592 -117.775482)
		(end 182.555642 -118.175532)
		(width 0.12954)
		(layer "F.Cu")
		(net "OCP_V3_2_MAIN_PWR_EN")
	)
	(via
		(at 203.69276 -123.426728)
		(size 0.508)
		(drill 0.254)
		(layers "F.Cu" "B.Cu")
		(net "OCP_V3_2_MAIN_PWR_EN")
	)
	(via
		(at 168.32072 -90.007948)
		(size 0.508)
		(drill 0.254)
		(layers "F.Cu" "B.Cu")
		(net "OCP_V3_2_MAIN_PWR_EN")
	)
	(via
		(at 120.95988 -40.328088)
		(size 0.508)
		(drill 0.254)
		(layers "F.Cu" "B.Cu")
		(net "OCP_V3_2_MAIN_PWR_EN")
	)
	(via
		(at 77.86878 -12.756388)
		(size 0.508)
		(drill 0.254)
		(layers "F.Cu" "B.Cu")
		(net "OCP_V3_2_MAIN_PWR_EN")
	)
	(via
		(at 182.555642 -118.175532)
		(size 0.4572)
		(drill 0.254)
		(layers "F.Cu" "B.Cu")
		(net "OCP_V3_2_MAIN_PWR_EN")
	)
	(segment
		(start 202.454764 -97.653094)
		(end 193.553842 -97.653094)
		(width 0.12954)
		(layer "B.Cu")
		(net "OCP_V3_2_MAIN_PWR_EN")
	)
	(segment
		(start 206.02448 -122.519948)
		(end 206.58836 -121.956068)
		(width 0.12954)
		(layer "B.Cu")
		(net "OCP_V3_2_MAIN_PWR_EN")
	)
	(segment
		(start 206.14386 -101.34219)
		(end 202.454764 -97.653094)
		(width 0.12954)
		(layer "B.Cu")
		(net "OCP_V3_2_MAIN_PWR_EN")
	)
	(segment
		(start 189.081918 -93.18117)
		(end 188.226192 -93.18117)
		(width 0.12954)
		(layer "B.Cu")
		(net "OCP_V3_2_MAIN_PWR_EN")
	)
	(segment
		(start 170.72356 -90.007948)
		(end 168.32072 -90.007948)
		(width 0.12954)
		(layer "B.Cu")
		(net "OCP_V3_2_MAIN_PWR_EN")
	)
	(segment
		(start 206.14386 -113.386108)
		(end 206.14386 -101.34219)
		(width 0.12954)
		(layer "B.Cu")
		(net "OCP_V3_2_MAIN_PWR_EN")
	)
	(segment
		(start 186.993022 -91.948)
		(end 184.6072 -91.948)
		(width 0.12954)
		(layer "B.Cu")
		(net "OCP_V3_2_MAIN_PWR_EN")
	)
	(segment
		(start 77.86878 -12.756388)
		(end 77.75702 -12.756388)
		(width 0.12954)
		(layer "B.Cu")
		(net "OCP_V3_2_MAIN_PWR_EN")
	)
	(segment
		(start 207.33258 -114.574828)
		(end 206.14386 -113.386108)
		(width 0.12954)
		(layer "B.Cu")
		(net "OCP_V3_2_MAIN_PWR_EN")
	)
	(segment
		(start 188.226192 -93.18117)
		(end 186.993022 -91.948)
		(width 0.12954)
		(layer "B.Cu")
		(net "OCP_V3_2_MAIN_PWR_EN")
	)
	(segment
		(start 206.58836 -121.956068)
		(end 206.58836 -117.838728)
		(width 0.12954)
		(layer "B.Cu")
		(net "OCP_V3_2_MAIN_PWR_EN")
	)
	(segment
		(start 203.69276 -123.426728)
		(end 204.59954 -122.519948)
		(width 0.12954)
		(layer "B.Cu")
		(net "OCP_V3_2_MAIN_PWR_EN")
	)
	(segment
		(start 184.6072 -91.948)
		(end 183.719978 -91.060778)
		(width 0.12954)
		(layer "B.Cu")
		(net "OCP_V3_2_MAIN_PWR_EN")
	)
	(segment
		(start 193.553842 -97.653094)
		(end 189.081918 -93.18117)
		(width 0.12954)
		(layer "B.Cu")
		(net "OCP_V3_2_MAIN_PWR_EN")
	)
	(segment
		(start 77.75702 -12.756388)
		(end 76.89088 -11.890248)
		(width 0.12954)
		(layer "B.Cu")
		(net "OCP_V3_2_MAIN_PWR_EN")
	)
	(segment
		(start 76.89088 -11.890248)
		(end 76.89088 -11.667998)
		(width 0.12954)
		(layer "B.Cu")
		(net "OCP_V3_2_MAIN_PWR_EN")
	)
	(segment
		(start 206.58836 -117.838728)
		(end 207.33258 -117.094508)
		(width 0.12954)
		(layer "B.Cu")
		(net "OCP_V3_2_MAIN_PWR_EN")
	)
	(segment
		(start 183.719978 -91.060778)
		(end 171.77639 -91.060778)
		(width 0.12954)
		(layer "B.Cu")
		(net "OCP_V3_2_MAIN_PWR_EN")
	)
	(segment
		(start 75.87488 -11.667998)
		(end 76.89088 -11.667998)
		(width 0.12954)
		(layer "B.Cu")
		(net "OCP_V3_2_MAIN_PWR_EN")
	)
	(segment
		(start 171.77639 -91.060778)
		(end 170.72356 -90.007948)
		(width 0.12954)
		(layer "B.Cu")
		(net "OCP_V3_2_MAIN_PWR_EN")
	)
	(segment
		(start 204.59954 -122.519948)
		(end 206.02448 -122.519948)
		(width 0.12954)
		(layer "B.Cu")
		(net "OCP_V3_2_MAIN_PWR_EN")
	)
	(segment
		(start 207.33258 -117.094508)
		(end 207.33258 -114.574828)
		(width 0.12954)
		(layer "B.Cu")
		(net "OCP_V3_2_MAIN_PWR_EN")
	)
	(segment
		(start 136.83996 -66.487548)
		(end 136.83996 -52.865528)
		(width 0.127)
		(layer "In4.Cu")
		(net "OCP_V3_2_MAIN_PWR_EN")
	)
	(segment
		(start 142.29842 -71.946008)
		(end 136.83996 -66.487548)
		(width 0.127)
		(layer "In4.Cu")
		(net "OCP_V3_2_MAIN_PWR_EN")
	)
	(segment
		(start 161.0995 -71.946008)
		(end 142.29842 -71.946008)
		(width 0.127)
		(layer "In4.Cu")
		(net "OCP_V3_2_MAIN_PWR_EN")
	)
	(segment
		(start 168.32072 -86.228174)
		(end 162.349688 -80.257142)
		(width 0.127)
		(layer "In4.Cu")
		(net "OCP_V3_2_MAIN_PWR_EN")
	)
	(segment
		(start 168.32072 -90.007948)
		(end 168.32072 -86.228174)
		(width 0.127)
		(layer "In4.Cu")
		(net "OCP_V3_2_MAIN_PWR_EN")
	)
	(segment
		(start 162.349688 -73.196196)
		(end 161.0995 -71.946008)
		(width 0.127)
		(layer "In4.Cu")
		(net "OCP_V3_2_MAIN_PWR_EN")
	)
	(segment
		(start 124.30252 -40.328088)
		(end 120.95988 -40.328088)
		(width 0.127)
		(layer "In4.Cu")
		(net "OCP_V3_2_MAIN_PWR_EN")
	)
	(segment
		(start 136.83996 -52.865528)
		(end 124.30252 -40.328088)
		(width 0.127)
		(layer "In4.Cu")
		(net "OCP_V3_2_MAIN_PWR_EN")
	)
	(segment
		(start 162.349688 -80.257142)
		(end 162.349688 -73.196196)
		(width 0.127)
		(layer "In4.Cu")
		(net "OCP_V3_2_MAIN_PWR_EN")
	)
	(segment
		(start 183.75122 -118.770908)
		(end 183.55818 -118.577868)
		(width 0.127)
		(layer "In6.Cu")
		(net "OCP_V3_2_MAIN_PWR_EN")
	)
	(segment
		(start 183.9595 -119.375428)
		(end 183.75122 -119.167148)
		(width 0.127)
		(layer "In6.Cu")
		(net "OCP_V3_2_MAIN_PWR_EN")
	)
	(segment
		(start 184.34304 -119.375428)
		(end 183.9595 -119.375428)
		(width 0.127)
		(layer "In6.Cu")
		(net "OCP_V3_2_MAIN_PWR_EN")
	)
	(segment
		(start 203.69276 -123.426728)
		(end 203.15682 -123.962668)
		(width 0.127)
		(layer "In6.Cu")
		(net "OCP_V3_2_MAIN_PWR_EN")
	)
	(segment
		(start 183.55818 -118.577868)
		(end 183.133746 -118.577868)
		(width 0.127)
		(layer "In6.Cu")
		(net "OCP_V3_2_MAIN_PWR_EN")
	)
	(segment
		(start 183.133746 -118.577868)
		(end 182.73141 -118.175532)
		(width 0.127)
		(layer "In6.Cu")
		(net "OCP_V3_2_MAIN_PWR_EN")
	)
	(segment
		(start 184.55132 -119.583708)
		(end 184.34304 -119.375428)
		(width 0.127)
		(layer "In6.Cu")
		(net "OCP_V3_2_MAIN_PWR_EN")
	)
	(segment
		(start 186.97956 -120.846088)
		(end 186.309 -120.175528)
		(width 0.127)
		(layer "In6.Cu")
		(net "OCP_V3_2_MAIN_PWR_EN")
	)
	(segment
		(start 186.309 -120.175528)
		(end 184.77738 -120.175528)
		(width 0.127)
		(layer "In6.Cu")
		(net "OCP_V3_2_MAIN_PWR_EN")
	)
	(segment
		(start 182.73141 -118.175532)
		(end 182.555642 -118.175532)
		(width 0.127)
		(layer "In6.Cu")
		(net "OCP_V3_2_MAIN_PWR_EN")
	)
	(segment
		(start 184.77738 -120.175528)
		(end 184.55132 -119.949468)
		(width 0.127)
		(layer "In6.Cu")
		(net "OCP_V3_2_MAIN_PWR_EN")
	)
	(segment
		(start 199.259952 -123.962668)
		(end 198.896732 -123.599448)
		(width 0.127)
		(layer "In6.Cu")
		(net "OCP_V3_2_MAIN_PWR_EN")
	)
	(segment
		(start 184.55132 -119.949468)
		(end 184.55132 -119.583708)
		(width 0.127)
		(layer "In6.Cu")
		(net "OCP_V3_2_MAIN_PWR_EN")
	)
	(segment
		(start 198.896732 -123.599448)
		(end 192.07734 -123.599448)
		(width 0.127)
		(layer "In6.Cu")
		(net "OCP_V3_2_MAIN_PWR_EN")
	)
	(segment
		(start 189.32398 -120.846088)
		(end 186.97956 -120.846088)
		(width 0.127)
		(layer "In6.Cu")
		(net "OCP_V3_2_MAIN_PWR_EN")
	)
	(segment
		(start 203.15682 -123.962668)
		(end 199.259952 -123.962668)
		(width 0.127)
		(layer "In6.Cu")
		(net "OCP_V3_2_MAIN_PWR_EN")
	)
	(segment
		(start 192.07734 -123.599448)
		(end 189.32398 -120.846088)
		(width 0.127)
		(layer "In6.Cu")
		(net "OCP_V3_2_MAIN_PWR_EN")
	)
	(segment
		(start 183.75122 -119.167148)
		(end 183.75122 -118.770908)
		(width 0.127)
		(layer "In6.Cu")
		(net "OCP_V3_2_MAIN_PWR_EN")
	)
	(segment
		(start 98.52406 -30.610048)
		(end 97.3328 -29.418788)
		(width 0.127)
		(layer "In13.Cu")
		(net "OCP_V3_2_MAIN_PWR_EN")
	)
	(segment
		(start 80.45196 -13.261848)
		(end 78.37424 -13.261848)
		(width 0.127)
		(layer "In13.Cu")
		(net "OCP_V3_2_MAIN_PWR_EN")
	)
	(segment
		(start 120.95988 -40.328088)
		(end 113.24336 -32.611568)
		(width 0.127)
		(layer "In13.Cu")
		(net "OCP_V3_2_MAIN_PWR_EN")
	)
	(segment
		(start 113.24336 -32.611568)
		(end 105.70464 -32.611568)
		(width 0.127)
		(layer "In13.Cu")
		(net "OCP_V3_2_MAIN_PWR_EN")
	)
	(segment
		(start 85.94852 -25.601168)
		(end 85.94852 -18.758408)
		(width 0.127)
		(layer "In13.Cu")
		(net "OCP_V3_2_MAIN_PWR_EN")
	)
	(segment
		(start 85.94852 -18.758408)
		(end 80.45196 -13.261848)
		(width 0.127)
		(layer "In13.Cu")
		(net "OCP_V3_2_MAIN_PWR_EN")
	)
	(segment
		(start 78.37424 -13.261848)
		(end 77.86878 -12.756388)
		(width 0.127)
		(layer "In13.Cu")
		(net "OCP_V3_2_MAIN_PWR_EN")
	)
	(segment
		(start 97.3328 -29.418788)
		(end 89.76614 -29.418788)
		(width 0.127)
		(layer "In13.Cu")
		(net "OCP_V3_2_MAIN_PWR_EN")
	)
	(segment
		(start 89.76614 -29.418788)
		(end 85.94852 -25.601168)
		(width 0.127)
		(layer "In13.Cu")
		(net "OCP_V3_2_MAIN_PWR_EN")
	)
	(segment
		(start 103.70312 -30.610048)
		(end 98.52406 -30.610048)
		(width 0.127)
		(layer "In13.Cu")
		(net "OCP_V3_2_MAIN_PWR_EN")
	)
	(segment
		(start 105.70464 -32.611568)
		(end 103.70312 -30.610048)
		(width 0.127)
		(layer "In13.Cu")
		(net "OCP_V3_2_MAIN_PWR_EN")
	)
	(segment
		(start 60.88888 -17.744694)
		(end 61.26988 -17.363694)
		(width 0.12954)
		(layer "F.Cu")
		(net "OCP_V3_2_ISO_BIF2_EN")
	)
	(segment
		(start 60.88888 -18.252948)
		(end 60.88888 -17.744694)
		(width 0.12954)
		(layer "F.Cu")
		(net "OCP_V3_2_ISO_BIF2_EN")
	)
	(segment
		(start 61.26988 -17.363694)
		(end 61.26988 -16.620998)
		(width 0.12954)
		(layer "F.Cu")
		(net "OCP_V3_2_ISO_BIF2_EN")
	)
	(segment
		(start 61.50483 -18.252948)
		(end 60.88888 -18.252948)
		(width 0.12954)
		(layer "F.Cu")
		(net "OCP_V3_2_ISO_BIF2_EN")
	)
	(via
		(at 60.88888 -18.252948)
		(size 0.508)
		(drill 0.254)
		(layers "F.Cu" "B.Cu")
		(net "OCP_V3_2_ISO_BIF2_EN")
	)
	(segment
		(start 62.28588 -16.620998)
		(end 62.28588 -17.236948)
		(width 0.12954)
		(layer "F.Cu")
		(net "OCP_V3_2_ISO_BIF1_EN")
	)
	(via
		(at 62.28588 -17.236948)
		(size 0.508)
		(drill 0.254)
		(layers "F.Cu" "B.Cu")
		(net "OCP_V3_2_ISO_BIF1_EN")
	)
	(segment
		(start 62.28588 -17.236948)
		(end 62.702186 -16.820642)
		(width 0.12954)
		(layer "B.Cu")
		(net "OCP_V3_2_ISO_BIF1_EN")
	)
	(segment
		(start 62.702186 -16.820642)
		(end 62.702186 -16.169894)
		(width 0.12954)
		(layer "B.Cu")
		(net "OCP_V3_2_ISO_BIF1_EN")
	)
	(segment
		(start 63.30188 -17.515332)
		(end 63.30188 -16.620998)
		(width 0.12954)
		(layer "F.Cu")
		(net "OCP_V3_2_ISO_BIF0_EN")
	)
	(segment
		(start 63.47079 -17.684242)
		(end 63.30188 -17.515332)
		(width 0.12954)
		(layer "F.Cu")
		(net "OCP_V3_2_ISO_BIF0_EN")
	)
	(via
		(at 63.47079 -17.684242)
		(size 0.508)
		(drill 0.254)
		(layers "F.Cu" "B.Cu")
		(net "OCP_V3_2_ISO_BIF0_EN")
	)
	(segment
		(start 63.718186 -16.990822)
		(end 63.718186 -16.172434)
		(width 0.12954)
		(layer "B.Cu")
		(net "OCP_V3_2_ISO_BIF0_EN")
	)
	(segment
		(start 63.47079 -17.684242)
		(end 63.47079 -17.238218)
		(width 0.12954)
		(layer "B.Cu")
		(net "OCP_V3_2_ISO_BIF0_EN")
	)
	(segment
		(start 63.47079 -17.238218)
		(end 63.718186 -16.990822)
		(width 0.12954)
		(layer "B.Cu")
		(net "OCP_V3_2_ISO_BIF0_EN")
	)
	(segment
		(start 75.662028 -8.320024)
		(end 75.662028 -6.21792)
		(width 0.12954)
		(layer "F.Cu")
		(net "OCP_V3_2_ISO2_RBT_ARB_OUT")
	)
	(segment
		(start 75.662028 -6.21792)
		(end 76.073 -5.806948)
		(width 0.12954)
		(layer "F.Cu")
		(net "OCP_V3_2_ISO2_RBT_ARB_OUT")
	)
	(via
		(at 197.46468 -70.602348)
		(size 0.508)
		(drill 0.254)
		(layers "F.Cu" "B.Cu")
		(net "OCP_V3_2_ISO2_RBT_ARB_OUT")
	)
	(via
		(at 76.073 -5.806948)
		(size 0.508)
		(drill 0.254)
		(layers "F.Cu" "B.Cu")
		(net "OCP_V3_2_ISO2_RBT_ARB_OUT")
	)
	(segment
		(start 197.163944 -70.903084)
		(end 195.55333 -70.903084)
		(width 0.12954)
		(layer "B.Cu")
		(net "OCP_V3_2_ISO2_RBT_ARB_OUT")
	)
	(segment
		(start 197.46468 -70.602348)
		(end 197.163944 -70.903084)
		(width 0.12954)
		(layer "B.Cu")
		(net "OCP_V3_2_ISO2_RBT_ARB_OUT")
	)
	(segment
		(start 76.073 -5.806948)
		(end 75.663044 -6.216904)
		(width 0.127)
		(layer "In11.Cu")
		(net "OCP_V3_2_ISO2_RBT_ARB_OUT")
	)
	(segment
		(start 87.952072 -17.763998)
		(end 87.952072 -24.706834)
		(width 0.127)
		(layer "In11.Cu")
		(net "OCP_V3_2_ISO2_RBT_ARB_OUT")
	)
	(segment
		(start 153.80208 -62.499748)
		(end 171.979844 -62.499748)
		(width 0.127)
		(layer "In11.Cu")
		(net "OCP_V3_2_ISO2_RBT_ARB_OUT")
	)
	(segment
		(start 78.64348 -9.947148)
		(end 78.64348 -11.090148)
		(width 0.127)
		(layer "In11.Cu")
		(net "OCP_V3_2_ISO2_RBT_ARB_OUT")
	)
	(segment
		(start 193.263012 -70.109588)
		(end 196.97192 -70.109588)
		(width 0.127)
		(layer "In11.Cu")
		(net "OCP_V3_2_ISO2_RBT_ARB_OUT")
	)
	(segment
		(start 146.523202 -61.97727)
		(end 149.40788 -64.861948)
		(width 0.127)
		(layer "In11.Cu")
		(net "OCP_V3_2_ISO2_RBT_ARB_OUT")
	)
	(segment
		(start 134.539228 -50.52187)
		(end 145.994628 -61.97727)
		(width 0.127)
		(layer "In11.Cu")
		(net "OCP_V3_2_ISO2_RBT_ARB_OUT")
	)
	(segment
		(start 101.70414 -37.507926)
		(end 114.718084 -50.52187)
		(width 0.127)
		(layer "In11.Cu")
		(net "OCP_V3_2_ISO2_RBT_ARB_OUT")
	)
	(segment
		(start 114.718084 -50.52187)
		(end 134.539228 -50.52187)
		(width 0.127)
		(layer "In11.Cu")
		(net "OCP_V3_2_ISO2_RBT_ARB_OUT")
	)
	(segment
		(start 101.70414 -30.615128)
		(end 101.70414 -37.507926)
		(width 0.127)
		(layer "In11.Cu")
		(net "OCP_V3_2_ISO2_RBT_ARB_OUT")
	)
	(segment
		(start 75.663044 -6.216904)
		(end 75.663044 -7.449312)
		(width 0.127)
		(layer "In11.Cu")
		(net "OCP_V3_2_ISO2_RBT_ARB_OUT")
	)
	(segment
		(start 149.40788 -64.861948)
		(end 151.43988 -64.861948)
		(width 0.127)
		(layer "In11.Cu")
		(net "OCP_V3_2_ISO2_RBT_ARB_OUT")
	)
	(segment
		(start 82.314288 -14.760956)
		(end 84.94903 -14.760956)
		(width 0.127)
		(layer "In11.Cu")
		(net "OCP_V3_2_ISO2_RBT_ARB_OUT")
	)
	(segment
		(start 171.979844 -62.499748)
		(end 174.692564 -59.787028)
		(width 0.127)
		(layer "In11.Cu")
		(net "OCP_V3_2_ISO2_RBT_ARB_OUT")
	)
	(segment
		(start 91.653106 -28.407868)
		(end 99.49688 -28.407868)
		(width 0.127)
		(layer "In11.Cu")
		(net "OCP_V3_2_ISO2_RBT_ARB_OUT")
	)
	(segment
		(start 84.94903 -14.760956)
		(end 87.952072 -17.763998)
		(width 0.127)
		(layer "In11.Cu")
		(net "OCP_V3_2_ISO2_RBT_ARB_OUT")
	)
	(segment
		(start 99.49688 -28.407868)
		(end 101.70414 -30.615128)
		(width 0.127)
		(layer "In11.Cu")
		(net "OCP_V3_2_ISO2_RBT_ARB_OUT")
	)
	(segment
		(start 174.692564 -59.787028)
		(end 182.940452 -59.787028)
		(width 0.127)
		(layer "In11.Cu")
		(net "OCP_V3_2_ISO2_RBT_ARB_OUT")
	)
	(segment
		(start 78.64348 -11.090148)
		(end 82.314288 -14.760956)
		(width 0.127)
		(layer "In11.Cu")
		(net "OCP_V3_2_ISO2_RBT_ARB_OUT")
	)
	(segment
		(start 145.994628 -61.97727)
		(end 146.523202 -61.97727)
		(width 0.127)
		(layer "In11.Cu")
		(net "OCP_V3_2_ISO2_RBT_ARB_OUT")
	)
	(segment
		(start 87.952072 -24.706834)
		(end 91.653106 -28.407868)
		(width 0.127)
		(layer "In11.Cu")
		(net "OCP_V3_2_ISO2_RBT_ARB_OUT")
	)
	(segment
		(start 151.43988 -64.861948)
		(end 153.80208 -62.499748)
		(width 0.127)
		(layer "In11.Cu")
		(net "OCP_V3_2_ISO2_RBT_ARB_OUT")
	)
	(segment
		(start 77.37348 -8.677148)
		(end 78.64348 -9.947148)
		(width 0.127)
		(layer "In11.Cu")
		(net "OCP_V3_2_ISO2_RBT_ARB_OUT")
	)
	(segment
		(start 182.940452 -59.787028)
		(end 193.263012 -70.109588)
		(width 0.127)
		(layer "In11.Cu")
		(net "OCP_V3_2_ISO2_RBT_ARB_OUT")
	)
	(segment
		(start 76.89088 -8.677148)
		(end 77.37348 -8.677148)
		(width 0.127)
		(layer "In11.Cu")
		(net "OCP_V3_2_ISO2_RBT_ARB_OUT")
	)
	(segment
		(start 196.97192 -70.109588)
		(end 197.46468 -70.602348)
		(width 0.127)
		(layer "In11.Cu")
		(net "OCP_V3_2_ISO2_RBT_ARB_OUT")
	)
	(segment
		(start 75.663044 -7.449312)
		(end 76.89088 -8.677148)
		(width 0.127)
		(layer "In11.Cu")
		(net "OCP_V3_2_ISO2_RBT_ARB_OUT")
	)
	(segment
		(start 76.26223 -8.31977)
		(end 76.26223 -7.20471)
		(width 0.12954)
		(layer "F.Cu")
		(net "OCP_V3_2_ISO1_RBT_ARB_IN")
	)
	(segment
		(start 76.26223 -7.20471)
		(end 76.262992 -7.203948)
		(width 0.12954)
		(layer "F.Cu")
		(net "OCP_V3_2_ISO1_RBT_ARB_IN")
	)
	(segment
		(start 76.261976 -8.320024)
		(end 76.26223 -8.31977)
		(width 0.12954)
		(layer "F.Cu")
		(net "OCP_V3_2_ISO1_RBT_ARB_IN")
	)
	(via
		(at 204.69098 -77.422248)
		(size 0.508)
		(drill 0.254)
		(layers "F.Cu" "B.Cu")
		(net "OCP_V3_2_ISO1_RBT_ARB_IN")
	)
	(via
		(at 76.262992 -7.203948)
		(size 0.508)
		(drill 0.254)
		(layers "F.Cu" "B.Cu")
		(net "OCP_V3_2_ISO1_RBT_ARB_IN")
	)
	(segment
		(start 204.849476 -77.263752)
		(end 206.374746 -77.263752)
		(width 0.12954)
		(layer "B.Cu")
		(net "OCP_V3_2_ISO1_RBT_ARB_IN")
	)
	(segment
		(start 204.69098 -77.422248)
		(end 204.849476 -77.263752)
		(width 0.12954)
		(layer "B.Cu")
		(net "OCP_V3_2_ISO1_RBT_ARB_IN")
	)
	(segment
		(start 91.785948 -28.07081)
		(end 99.736402 -28.07081)
		(width 0.127)
		(layer "In11.Cu")
		(net "OCP_V3_2_ISO1_RBT_ARB_IN")
	)
	(segment
		(start 79.15148 -9.743948)
		(end 79.15148 -10.912348)
		(width 0.127)
		(layer "In11.Cu")
		(net "OCP_V3_2_ISO1_RBT_ARB_IN")
	)
	(segment
		(start 174.555658 -59.456828)
		(end 183.077358 -59.456828)
		(width 0.127)
		(layer "In11.Cu")
		(net "OCP_V3_2_ISO1_RBT_ARB_IN")
	)
	(segment
		(start 88.436958 -24.72182)
		(end 91.785948 -28.07081)
		(width 0.127)
		(layer "In11.Cu")
		(net "OCP_V3_2_ISO1_RBT_ARB_IN")
	)
	(segment
		(start 77.228192 -8.169148)
		(end 77.57668 -8.169148)
		(width 0.127)
		(layer "In11.Cu")
		(net "OCP_V3_2_ISO1_RBT_ARB_IN")
	)
	(segment
		(start 82.515202 -14.27607)
		(end 85.149944 -14.27607)
		(width 0.127)
		(layer "In11.Cu")
		(net "OCP_V3_2_ISO1_RBT_ARB_IN")
	)
	(segment
		(start 183.077358 -59.456828)
		(end 193.399918 -69.779388)
		(width 0.127)
		(layer "In11.Cu")
		(net "OCP_V3_2_ISO1_RBT_ARB_IN")
	)
	(segment
		(start 76.262992 -7.203948)
		(end 77.228192 -8.169148)
		(width 0.127)
		(layer "In11.Cu")
		(net "OCP_V3_2_ISO1_RBT_ARB_IN")
	)
	(segment
		(start 193.399918 -69.779388)
		(end 198.39432 -69.779388)
		(width 0.127)
		(layer "In11.Cu")
		(net "OCP_V3_2_ISO1_RBT_ARB_IN")
	)
	(segment
		(start 204.70368 -77.409548)
		(end 204.69098 -77.422248)
		(width 0.127)
		(layer "In11.Cu")
		(net "OCP_V3_2_ISO1_RBT_ARB_IN")
	)
	(segment
		(start 204.70368 -76.088748)
		(end 204.70368 -77.409548)
		(width 0.127)
		(layer "In11.Cu")
		(net "OCP_V3_2_ISO1_RBT_ARB_IN")
	)
	(segment
		(start 151.302974 -64.531748)
		(end 153.665174 -62.169548)
		(width 0.127)
		(layer "In11.Cu")
		(net "OCP_V3_2_ISO1_RBT_ARB_IN")
	)
	(segment
		(start 77.57668 -8.169148)
		(end 79.15148 -9.743948)
		(width 0.127)
		(layer "In11.Cu")
		(net "OCP_V3_2_ISO1_RBT_ARB_IN")
	)
	(segment
		(start 115.325144 -50.19167)
		(end 134.676388 -50.19167)
		(width 0.127)
		(layer "In11.Cu")
		(net "OCP_V3_2_ISO1_RBT_ARB_IN")
	)
	(segment
		(start 99.736402 -28.07081)
		(end 102.28834 -30.622748)
		(width 0.127)
		(layer "In11.Cu")
		(net "OCP_V3_2_ISO1_RBT_ARB_IN")
	)
	(segment
		(start 134.676388 -50.19167)
		(end 146.131788 -61.64707)
		(width 0.127)
		(layer "In11.Cu")
		(net "OCP_V3_2_ISO1_RBT_ARB_IN")
	)
	(segment
		(start 146.131788 -61.64707)
		(end 146.660108 -61.64707)
		(width 0.127)
		(layer "In11.Cu")
		(net "OCP_V3_2_ISO1_RBT_ARB_IN")
	)
	(segment
		(start 102.28834 -37.154866)
		(end 115.325144 -50.19167)
		(width 0.127)
		(layer "In11.Cu")
		(net "OCP_V3_2_ISO1_RBT_ARB_IN")
	)
	(segment
		(start 88.436958 -17.563084)
		(end 88.436958 -24.72182)
		(width 0.127)
		(layer "In11.Cu")
		(net "OCP_V3_2_ISO1_RBT_ARB_IN")
	)
	(segment
		(start 102.28834 -30.622748)
		(end 102.28834 -37.154866)
		(width 0.127)
		(layer "In11.Cu")
		(net "OCP_V3_2_ISO1_RBT_ARB_IN")
	)
	(segment
		(start 198.39432 -69.779388)
		(end 204.70368 -76.088748)
		(width 0.127)
		(layer "In11.Cu")
		(net "OCP_V3_2_ISO1_RBT_ARB_IN")
	)
	(segment
		(start 79.15148 -10.912348)
		(end 82.515202 -14.27607)
		(width 0.127)
		(layer "In11.Cu")
		(net "OCP_V3_2_ISO1_RBT_ARB_IN")
	)
	(segment
		(start 171.842938 -62.169548)
		(end 174.555658 -59.456828)
		(width 0.127)
		(layer "In11.Cu")
		(net "OCP_V3_2_ISO1_RBT_ARB_IN")
	)
	(segment
		(start 85.149944 -14.27607)
		(end 88.436958 -17.563084)
		(width 0.127)
		(layer "In11.Cu")
		(net "OCP_V3_2_ISO1_RBT_ARB_IN")
	)
	(segment
		(start 153.665174 -62.169548)
		(end 171.842938 -62.169548)
		(width 0.127)
		(layer "In11.Cu")
		(net "OCP_V3_2_ISO1_RBT_ARB_IN")
	)
	(segment
		(start 146.660108 -61.64707)
		(end 149.544786 -64.531748)
		(width 0.127)
		(layer "In11.Cu")
		(net "OCP_V3_2_ISO1_RBT_ARB_IN")
	)
	(segment
		(start 149.544786 -64.531748)
		(end 151.302974 -64.531748)
		(width 0.127)
		(layer "In11.Cu")
		(net "OCP_V3_2_ISO1_RBT_ARB_IN")
	)
	(segment
		(start 75.06208 -8.320024)
		(end 75.06208 -6.695948)
		(width 0.12954)
		(layer "F.Cu")
		(net "OCP_V3_2_ID1")
	)
	(via
		(at 75.06208 -6.695948)
		(size 0.508)
		(drill 0.254)
		(layers "F.Cu" "B.Cu")
		(net "OCP_V3_2_ID1")
	)
	(segment
		(start 74.04608 -4.651248)
		(end 75.06208 -4.651248)
		(width 0.12954)
		(layer "B.Cu")
		(net "OCP_V3_2_ID1")
	)
	(segment
		(start 75.06208 -4.651248)
		(end 75.06208 -6.695948)
		(width 0.12954)
		(layer "B.Cu")
		(net "OCP_V3_2_ID1")
	)
	(segment
		(start 74.461878 -11.26998)
		(end 74.462894 -11.270996)
		(width 0.12954)
		(layer "F.Cu")
		(net "OCP_V3_2_ID0")
	)
	(segment
		(start 74.462894 -11.270996)
		(end 74.462894 -12.832588)
		(width 0.12954)
		(layer "F.Cu")
		(net "OCP_V3_2_ID0")
	)
	(via
		(at 74.462894 -12.832588)
		(size 0.508)
		(drill 0.254)
		(layers "F.Cu" "B.Cu")
		(net "OCP_V3_2_ID0")
	)
	(segment
		(start 72.82688 -11.667998)
		(end 73.84288 -11.667998)
		(width 0.12954)
		(layer "B.Cu")
		(net "OCP_V3_2_ID0")
	)
	(segment
		(start 74.462894 -12.832588)
		(end 73.84288 -12.212574)
		(width 0.12954)
		(layer "B.Cu")
		(net "OCP_V3_2_ID0")
	)
	(segment
		(start 73.84288 -12.212574)
		(end 73.84288 -11.667998)
		(width 0.12954)
		(layer "B.Cu")
		(net "OCP_V3_2_ID0")
	)
	(segment
		(start 61.26988 -14.823948)
		(end 61.26988 -15.820898)
		(width 0.12954)
		(layer "F.Cu")
		(net "OCP_V3_2_BIF2_R_N")
	)
	(segment
		(start 61.52388 -13.554202)
		(end 61.52388 -14.569948)
		(width 0.12954)
		(layer "F.Cu")
		(net "OCP_V3_2_BIF2_R_N")
	)
	(segment
		(start 61.52388 -14.569948)
		(end 61.26988 -14.823948)
		(width 0.12954)
		(layer "F.Cu")
		(net "OCP_V3_2_BIF2_R_N")
	)
	(segment
		(start 61.066934 -13.097256)
		(end 61.52388 -13.554202)
		(width 0.12954)
		(layer "F.Cu")
		(net "OCP_V3_2_BIF2_R_N")
	)
	(segment
		(start 61.066934 -11.26998)
		(end 61.066934 -13.097256)
		(width 0.12954)
		(layer "F.Cu")
		(net "OCP_V3_2_BIF2_R_N")
	)
	(via
		(at 61.52388 -14.569948)
		(size 0.762)
		(drill 0.381)
		(layers "F.Cu" "B.Cu")
		(net "OCP_V3_2_BIF2_R_N")
	)
	(segment
		(start 62.79388 -15.312898)
		(end 62.28588 -15.820898)
		(width 0.12954)
		(layer "F.Cu")
		(net "OCP_V3_2_BIF1_R_N")
	)
	(segment
		(start 61.666882 -11.26998)
		(end 61.666882 -12.876276)
		(width 0.12954)
		(layer "F.Cu")
		(net "OCP_V3_2_BIF1_R_N")
	)
	(segment
		(start 62.79388 -14.569948)
		(end 62.79388 -15.312898)
		(width 0.12954)
		(layer "F.Cu")
		(net "OCP_V3_2_BIF1_R_N")
	)
	(segment
		(start 62.79388 -14.003274)
		(end 62.79388 -14.569948)
		(width 0.12954)
		(layer "F.Cu")
		(net "OCP_V3_2_BIF1_R_N")
	)
	(segment
		(start 61.666882 -12.876276)
		(end 62.79388 -14.003274)
		(width 0.12954)
		(layer "F.Cu")
		(net "OCP_V3_2_BIF1_R_N")
	)
	(via
		(at 62.79388 -14.569948)
		(size 0.762)
		(drill 0.381)
		(layers "F.Cu" "B.Cu")
		(net "OCP_V3_2_BIF1_R_N")
	)
	(segment
		(start 62.267084 -11.26998)
		(end 62.267084 -12.773152)
		(width 0.12954)
		(layer "F.Cu")
		(net "OCP_V3_2_BIF0_R_N")
	)
	(segment
		(start 62.267084 -12.773152)
		(end 64.06388 -14.569948)
		(width 0.12954)
		(layer "F.Cu")
		(net "OCP_V3_2_BIF0_R_N")
	)
	(segment
		(start 63.30188 -15.331948)
		(end 64.06388 -14.569948)
		(width 0.12954)
		(layer "F.Cu")
		(net "OCP_V3_2_BIF0_R_N")
	)
	(segment
		(start 63.30188 -15.820898)
		(end 63.30188 -15.331948)
		(width 0.12954)
		(layer "F.Cu")
		(net "OCP_V3_2_BIF0_R_N")
	)
	(via
		(at 64.06388 -14.569948)
		(size 0.762)
		(drill 0.381)
		(layers "F.Cu" "B.Cu")
		(net "OCP_V3_2_BIF0_R_N")
	)
	(segment
		(start 457.34478 -95.016828)
		(end 458.084174 -94.277434)
		(width 0.12954)
		(layer "F.Cu")
		(net "OCP_SFF_AUX_PWR_EN_R4")
	)
	(segment
		(start 456.017884 -94.673928)
		(end 456.017884 -93.437964)
		(width 0.12954)
		(layer "F.Cu")
		(net "OCP_SFF_AUX_PWR_EN_R4")
	)
	(segment
		(start 458.084174 -94.277434)
		(end 458.487526 -94.277434)
		(width 0.12954)
		(layer "F.Cu")
		(net "OCP_SFF_AUX_PWR_EN_R4")
	)
	(segment
		(start 456.017884 -94.673928)
		(end 456.360784 -95.016828)
		(width 0.12954)
		(layer "F.Cu")
		(net "OCP_SFF_AUX_PWR_EN_R4")
	)
	(segment
		(start 456.360784 -95.016828)
		(end 457.34478 -95.016828)
		(width 0.12954)
		(layer "F.Cu")
		(net "OCP_SFF_AUX_PWR_EN_R4")
	)
	(via
		(at 456.017884 -94.673928)
		(size 0.762)
		(drill 0.381)
		(layers "F.Cu" "B.Cu")
		(net "OCP_SFF_AUX_PWR_EN_R4")
	)
	(segment
		(start 152.313894 -107.025948)
		(end 152.313894 -105.760012)
		(width 0.12954)
		(layer "F.Cu")
		(net "OCP_V3_2_AUX_PWR_EN_R3")
	)
	(segment
		(start 152.313894 -108.361988)
		(end 152.313894 -107.025948)
		(width 0.12954)
		(layer "F.Cu")
		(net "OCP_V3_2_AUX_PWR_EN_R3")
	)
	(segment
		(start 152.313894 -105.760012)
		(end 152.30983 -105.755948)
		(width 0.12954)
		(layer "F.Cu")
		(net "OCP_V3_2_AUX_PWR_EN_R3")
	)
	(via
		(at 152.313894 -107.025948)
		(size 0.762)
		(drill 0.381)
		(layers "F.Cu" "B.Cu")
		(net "OCP_V3_2_AUX_PWR_EN_R3")
	)
	(segment
		(start 152.059894 -124.363988)
		(end 152.059894 -123.678188)
		(width 0.12954)
		(layer "F.Cu")
		(net "OCP_V3_2_AUX_PWR_EN_R1")
	)
	(via
		(at 161.84753 -107.025948)
		(size 0.508)
		(drill 0.254)
		(layers "F.Cu" "B.Cu")
		(net "OCP_V3_2_AUX_PWR_EN_R1")
	)
	(via
		(at 152.059894 -123.678188)
		(size 0.508)
		(drill 0.254)
		(layers "F.Cu" "B.Cu")
		(net "OCP_V3_2_AUX_PWR_EN_R1")
	)
	(via
		(at 158.20644 -123.77674)
		(size 0.508)
		(drill 0.254)
		(layers "F.Cu" "B.Cu")
		(net "OCP_V3_2_AUX_PWR_EN_R1")
	)
	(segment
		(start 161.23793 -107.025948)
		(end 161.84753 -107.025948)
		(width 0.12954)
		(layer "B.Cu")
		(net "OCP_V3_2_AUX_PWR_EN_R1")
	)
	(segment
		(start 159.7152 -111.785908)
		(end 158.31058 -110.381288)
		(width 0.127)
		(layer "In11.Cu")
		(net "OCP_V3_2_AUX_PWR_EN_R1")
	)
	(segment
		(start 159.64154 -107.693968)
		(end 159.92856 -107.693968)
		(width 0.127)
		(layer "In11.Cu")
		(net "OCP_V3_2_AUX_PWR_EN_R1")
	)
	(segment
		(start 158.31058 -110.381288)
		(end 158.31058 -109.024928)
		(width 0.127)
		(layer "In11.Cu")
		(net "OCP_V3_2_AUX_PWR_EN_R1")
	)
	(segment
		(start 160.16224 -111.785908)
		(end 159.7152 -111.785908)
		(width 0.127)
		(layer "In11.Cu")
		(net "OCP_V3_2_AUX_PWR_EN_R1")
	)
	(segment
		(start 160.4899 -122.751088)
		(end 160.4899 -112.113568)
		(width 0.127)
		(layer "In11.Cu")
		(net "OCP_V3_2_AUX_PWR_EN_R1")
	)
	(segment
		(start 158.31058 -109.024928)
		(end 159.64154 -107.693968)
		(width 0.127)
		(layer "In11.Cu")
		(net "OCP_V3_2_AUX_PWR_EN_R1")
	)
	(segment
		(start 159.995108 -123.24588)
		(end 160.4899 -122.751088)
		(width 0.127)
		(layer "In11.Cu")
		(net "OCP_V3_2_AUX_PWR_EN_R1")
	)
	(segment
		(start 158.20644 -123.77674)
		(end 158.7373 -123.24588)
		(width 0.127)
		(layer "In11.Cu")
		(net "OCP_V3_2_AUX_PWR_EN_R1")
	)
	(segment
		(start 160.4899 -112.113568)
		(end 160.16224 -111.785908)
		(width 0.127)
		(layer "In11.Cu")
		(net "OCP_V3_2_AUX_PWR_EN_R1")
	)
	(segment
		(start 158.7373 -123.24588)
		(end 159.995108 -123.24588)
		(width 0.127)
		(layer "In11.Cu")
		(net "OCP_V3_2_AUX_PWR_EN_R1")
	)
	(segment
		(start 159.92856 -107.693968)
		(end 160.59658 -107.025948)
		(width 0.127)
		(layer "In11.Cu")
		(net "OCP_V3_2_AUX_PWR_EN_R1")
	)
	(segment
		(start 160.59658 -107.025948)
		(end 161.84753 -107.025948)
		(width 0.127)
		(layer "In11.Cu")
		(net "OCP_V3_2_AUX_PWR_EN_R1")
	)
	(segment
		(start 158.20644 -123.77674)
		(end 157.53588 -124.4473)
		(width 0.127)
		(layer "In13.Cu")
		(net "OCP_V3_2_AUX_PWR_EN_R1")
	)
	(segment
		(start 157.53588 -124.4473)
		(end 152.442672 -124.4473)
		(width 0.127)
		(layer "In13.Cu")
		(net "OCP_V3_2_AUX_PWR_EN_R1")
	)
	(segment
		(start 152.442672 -124.4473)
		(end 152.059894 -124.064522)
		(width 0.127)
		(layer "In13.Cu")
		(net "OCP_V3_2_AUX_PWR_EN_R1")
	)
	(segment
		(start 152.059894 -124.064522)
		(end 152.059894 -123.678188)
		(width 0.127)
		(layer "In13.Cu")
		(net "OCP_V3_2_AUX_PWR_EN_R1")
	)
	(segment
		(start 60.25388 -14.062202)
		(end 60.25388 -14.569948)
		(width 0.12954)
		(layer "F.Cu")
		(net "OCP_V3_2_AUX_PWR_EN_R")
	)
	(segment
		(start 60.25388 -15.820898)
		(end 60.25388 -14.569948)
		(width 0.12954)
		(layer "F.Cu")
		(net "OCP_V3_2_AUX_PWR_EN_R")
	)
	(segment
		(start 59.26709 -11.26998)
		(end 59.26709 -13.075412)
		(width 0.12954)
		(layer "F.Cu")
		(net "OCP_V3_2_AUX_PWR_EN_R")
	)
	(segment
		(start 59.26709 -13.075412)
		(end 60.25388 -14.062202)
		(width 0.12954)
		(layer "F.Cu")
		(net "OCP_V3_2_AUX_PWR_EN_R")
	)
	(via
		(at 60.25388 -14.569948)
		(size 0.762)
		(drill 0.381)
		(layers "F.Cu" "B.Cu")
		(net "OCP_V3_2_AUX_PWR_EN_R")
	)
	(segment
		(start 60.25388 -19.014948)
		(end 60.70854 -19.469608)
		(width 0.12954)
		(layer "F.Cu")
		(net "OCP_V3_2_AUX_PWR_EN")
	)
	(segment
		(start 60.70854 -19.469608)
		(end 60.70854 -19.949668)
		(width 0.12954)
		(layer "F.Cu")
		(net "OCP_V3_2_AUX_PWR_EN")
	)
	(segment
		(start 61.38926 -19.268948)
		(end 61.50483 -19.268948)
		(width 0.12954)
		(layer "F.Cu")
		(net "OCP_V3_2_AUX_PWR_EN")
	)
	(segment
		(start 153.10993 -105.755948)
		(end 153.72588 -105.755948)
		(width 0.12954)
		(layer "F.Cu")
		(net "OCP_V3_2_AUX_PWR_EN")
	)
	(segment
		(start 60.70854 -19.949668)
		(end 61.38926 -19.268948)
		(width 0.12954)
		(layer "F.Cu")
		(net "OCP_V3_2_AUX_PWR_EN")
	)
	(segment
		(start 144.30121 -112.434624)
		(end 145.06194 -112.434624)
		(width 0.12954)
		(layer "F.Cu")
		(net "OCP_V3_2_AUX_PWR_EN")
	)
	(segment
		(start 60.25388 -16.620998)
		(end 60.25388 -19.014948)
		(width 0.12954)
		(layer "F.Cu")
		(net "OCP_V3_2_AUX_PWR_EN")
	)
	(via
		(at 153.72588 -105.755948)
		(size 0.508)
		(drill 0.254)
		(layers "F.Cu" "B.Cu")
		(net "OCP_V3_2_AUX_PWR_EN")
	)
	(via
		(at 108.13288 -81.150968)
		(size 0.508)
		(drill 0.254)
		(layers "F.Cu" "B.Cu")
		(net "OCP_V3_2_AUX_PWR_EN")
	)
	(via
		(at 150.06828 -84.064348)
		(size 0.508)
		(drill 0.254)
		(layers "F.Cu" "B.Cu")
		(net "OCP_V3_2_AUX_PWR_EN")
	)
	(via
		(at 60.70854 -19.949668)
		(size 0.508)
		(drill 0.254)
		(layers "F.Cu" "B.Cu")
		(net "OCP_V3_2_AUX_PWR_EN")
	)
	(via
		(at 145.06194 -112.434624)
		(size 0.508)
		(drill 0.254)
		(layers "F.Cu" "B.Cu")
		(net "OCP_V3_2_AUX_PWR_EN")
	)
	(segment
		(start 160.20542 -106.525568)
		(end 160.43783 -106.757978)
		(width 0.12954)
		(layer "B.Cu")
		(net "OCP_V3_2_AUX_PWR_EN")
	)
	(segment
		(start 160.43783 -106.757978)
		(end 160.43783 -107.025948)
		(width 0.12954)
		(layer "B.Cu")
		(net "OCP_V3_2_AUX_PWR_EN")
	)
	(segment
		(start 154.4955 -106.525568)
		(end 160.20542 -106.525568)
		(width 0.12954)
		(layer "B.Cu")
		(net "OCP_V3_2_AUX_PWR_EN")
	)
	(segment
		(start 153.72588 -105.755948)
		(end 154.4955 -106.525568)
		(width 0.12954)
		(layer "B.Cu")
		(net "OCP_V3_2_AUX_PWR_EN")
	)
	(segment
		(start 110.1598 -57.633108)
		(end 109.347 -56.820308)
		(width 0.127)
		(layer "In2.Cu")
		(net "OCP_V3_2_AUX_PWR_EN")
	)
	(segment
		(start 149.81428 -87.127588)
		(end 149.81428 -84.318348)
		(width 0.127)
		(layer "In2.Cu")
		(net "OCP_V3_2_AUX_PWR_EN")
	)
	(segment
		(start 109.347 -50.612802)
		(end 101.993446 -43.259248)
		(width 0.127)
		(layer "In2.Cu")
		(net "OCP_V3_2_AUX_PWR_EN")
	)
	(segment
		(start 61.07176 -30.983174)
		(end 60.15228 -30.063694)
		(width 0.127)
		(layer "In2.Cu")
		(net "OCP_V3_2_AUX_PWR_EN")
	)
	(segment
		(start 153.72588 -105.755948)
		(end 153.23058 -105.260648)
		(width 0.127)
		(layer "In2.Cu")
		(net "OCP_V3_2_AUX_PWR_EN")
	)
	(segment
		(start 68.58 -36.083748)
		(end 67.9196 -36.744148)
		(width 0.127)
		(layer "In2.Cu")
		(net "OCP_V3_2_AUX_PWR_EN")
	)
	(segment
		(start 61.07176 -32.969454)
		(end 61.07176 -30.983174)
		(width 0.127)
		(layer "In2.Cu")
		(net "OCP_V3_2_AUX_PWR_EN")
	)
	(segment
		(start 60.15228 -30.063694)
		(end 60.15228 -27.244802)
		(width 0.127)
		(layer "In2.Cu")
		(net "OCP_V3_2_AUX_PWR_EN")
	)
	(segment
		(start 101.993446 -43.259248)
		(end 97.418906 -43.259248)
		(width 0.127)
		(layer "In2.Cu")
		(net "OCP_V3_2_AUX_PWR_EN")
	)
	(segment
		(start 60.0329 -20.625308)
		(end 60.70854 -19.949668)
		(width 0.127)
		(layer "In2.Cu")
		(net "OCP_V3_2_AUX_PWR_EN")
	)
	(segment
		(start 108.13288 -81.150968)
		(end 108.13288 -73.414128)
		(width 0.127)
		(layer "In2.Cu")
		(net "OCP_V3_2_AUX_PWR_EN")
	)
	(segment
		(start 149.81428 -84.318348)
		(end 150.06828 -84.064348)
		(width 0.127)
		(layer "In2.Cu")
		(net "OCP_V3_2_AUX_PWR_EN")
	)
	(segment
		(start 69.3674 -34.610548)
		(end 68.58 -35.397948)
		(width 0.127)
		(layer "In2.Cu")
		(net "OCP_V3_2_AUX_PWR_EN")
	)
	(segment
		(start 97.418906 -43.259248)
		(end 96.052386 -41.892728)
		(width 0.127)
		(layer "In2.Cu")
		(net "OCP_V3_2_AUX_PWR_EN")
	)
	(segment
		(start 108.13288 -73.414128)
		(end 110.1598 -71.387208)
		(width 0.127)
		(layer "In2.Cu")
		(net "OCP_V3_2_AUX_PWR_EN")
	)
	(segment
		(start 68.58 -35.397948)
		(end 68.58 -36.083748)
		(width 0.127)
		(layer "In2.Cu")
		(net "OCP_V3_2_AUX_PWR_EN")
	)
	(segment
		(start 67.9196 -36.744148)
		(end 64.846454 -36.744148)
		(width 0.127)
		(layer "In2.Cu")
		(net "OCP_V3_2_AUX_PWR_EN")
	)
	(segment
		(start 110.1598 -71.387208)
		(end 110.1598 -57.633108)
		(width 0.127)
		(layer "In2.Cu")
		(net "OCP_V3_2_AUX_PWR_EN")
	)
	(segment
		(start 96.052386 -41.892728)
		(end 90.94978 -41.892728)
		(width 0.127)
		(layer "In2.Cu")
		(net "OCP_V3_2_AUX_PWR_EN")
	)
	(segment
		(start 109.347 -56.820308)
		(end 109.347 -50.612802)
		(width 0.127)
		(layer "In2.Cu")
		(net "OCP_V3_2_AUX_PWR_EN")
	)
	(segment
		(start 90.94978 -41.892728)
		(end 83.6676 -34.610548)
		(width 0.127)
		(layer "In2.Cu")
		(net "OCP_V3_2_AUX_PWR_EN")
	)
	(segment
		(start 153.23058 -90.543888)
		(end 149.81428 -87.127588)
		(width 0.127)
		(layer "In2.Cu")
		(net "OCP_V3_2_AUX_PWR_EN")
	)
	(segment
		(start 60.0329 -27.125422)
		(end 60.0329 -20.625308)
		(width 0.127)
		(layer "In2.Cu")
		(net "OCP_V3_2_AUX_PWR_EN")
	)
	(segment
		(start 64.846454 -36.744148)
		(end 61.07176 -32.969454)
		(width 0.127)
		(layer "In2.Cu")
		(net "OCP_V3_2_AUX_PWR_EN")
	)
	(segment
		(start 153.23058 -105.260648)
		(end 153.23058 -90.543888)
		(width 0.127)
		(layer "In2.Cu")
		(net "OCP_V3_2_AUX_PWR_EN")
	)
	(segment
		(start 60.15228 -27.244802)
		(end 60.0329 -27.125422)
		(width 0.127)
		(layer "In2.Cu")
		(net "OCP_V3_2_AUX_PWR_EN")
	)
	(segment
		(start 83.6676 -34.610548)
		(end 69.3674 -34.610548)
		(width 0.127)
		(layer "In2.Cu")
		(net "OCP_V3_2_AUX_PWR_EN")
	)
	(segment
		(start 145.51152 -111.61776)
		(end 145.06194 -112.06734)
		(width 0.127)
		(layer "In4.Cu")
		(net "OCP_V3_2_AUX_PWR_EN")
	)
	(segment
		(start 150.350982 -105.022396)
		(end 145.51152 -109.861858)
		(width 0.127)
		(layer "In4.Cu")
		(net "OCP_V3_2_AUX_PWR_EN")
	)
	(segment
		(start 145.51152 -109.861858)
		(end 145.51152 -111.61776)
		(width 0.127)
		(layer "In4.Cu")
		(net "OCP_V3_2_AUX_PWR_EN")
	)
	(segment
		(start 145.06194 -112.06734)
		(end 145.06194 -112.434624)
		(width 0.127)
		(layer "In4.Cu")
		(net "OCP_V3_2_AUX_PWR_EN")
	)
	(segment
		(start 153.72588 -105.755948)
		(end 152.992328 -105.022396)
		(width 0.127)
		(layer "In4.Cu")
		(net "OCP_V3_2_AUX_PWR_EN")
	)
	(segment
		(start 152.992328 -105.022396)
		(end 150.350982 -105.022396)
		(width 0.127)
		(layer "In4.Cu")
		(net "OCP_V3_2_AUX_PWR_EN")
	)
	(segment
		(start 113.35766 -84.120228)
		(end 110.3884 -81.150968)
		(width 0.127)
		(layer "In6.Cu")
		(net "OCP_V3_2_AUX_PWR_EN")
	)
	(segment
		(start 150.06828 -84.064348)
		(end 149.635972 -83.63204)
		(width 0.127)
		(layer "In6.Cu")
		(net "OCP_V3_2_AUX_PWR_EN")
	)
	(segment
		(start 149.635972 -83.63204)
		(end 127.386588 -83.63204)
		(width 0.127)
		(layer "In6.Cu")
		(net "OCP_V3_2_AUX_PWR_EN")
	)
	(segment
		(start 126.8984 -84.120228)
		(end 113.35766 -84.120228)
		(width 0.127)
		(layer "In6.Cu")
		(net "OCP_V3_2_AUX_PWR_EN")
	)
	(segment
		(start 127.386588 -83.63204)
		(end 126.8984 -84.120228)
		(width 0.127)
		(layer "In6.Cu")
		(net "OCP_V3_2_AUX_PWR_EN")
	)
	(segment
		(start 110.3884 -81.150968)
		(end 108.13288 -81.150968)
		(width 0.127)
		(layer "In6.Cu")
		(net "OCP_V3_2_AUX_PWR_EN")
	)
	(segment
		(start 60.466986 -8.320024)
		(end 60.466986 -6.663944)
		(width 0.12954)
		(layer "F.Cu")
		(net "OCP_V3_1_PRSNTA_R_N")
	)
	(segment
		(start 60.466986 -6.663944)
		(end 60.468002 -6.662928)
		(width 0.12954)
		(layer "F.Cu")
		(net "OCP_V3_1_PRSNTA_R_N")
	)
	(via
		(at 60.468002 -6.662928)
		(size 0.508)
		(drill 0.254)
		(layers "F.Cu" "B.Cu")
		(net "OCP_V3_1_PRSNTA_R_N")
	)
	(segment
		(start 60.468002 -7.919212)
		(end 60.468002 -6.662928)
		(width 0.12954)
		(layer "B.Cu")
		(net "OCP_V3_1_PRSNTA_R_N")
	)
	(via
		(at 192.63106 -78.047088)
		(size 0.6604)
		(drill 0.3302)
		(layers "F.Cu" "B.Cu")
		(net "OCP_SFF_RBT_ARB_IN_R")
	)
	(segment
		(start 192.63106 -78.047088)
		(end 192.021968 -78.65618)
		(width 0.12954)
		(layer "B.Cu")
		(net "OCP_SFF_RBT_ARB_IN_R")
	)
	(segment
		(start 193.29908 -78.047088)
		(end 192.63106 -78.047088)
		(width 0.12954)
		(layer "B.Cu")
		(net "OCP_SFF_RBT_ARB_IN_R")
	)
	(segment
		(start 194.304158 -77.842618)
		(end 193.50355 -77.842618)
		(width 0.12954)
		(layer "B.Cu")
		(net "OCP_SFF_RBT_ARB_IN_R")
	)
	(segment
		(start 193.50355 -77.842618)
		(end 193.29908 -78.047088)
		(width 0.12954)
		(layer "B.Cu")
		(net "OCP_SFF_RBT_ARB_IN_R")
	)
	(segment
		(start 192.021968 -78.65618)
		(end 191.47409 -78.65618)
		(width 0.12954)
		(layer "B.Cu")
		(net "OCP_SFF_RBT_ARB_IN_R")
	)
	(segment
		(start 138.9126 -32.458152)
		(end 138.54303 -32.827722)
		(width 0.12954)
		(layer "F.Cu")
		(net "OCP_SFF_RBT_ARB_IN_MUX2_R")
	)
	(segment
		(start 138.54303 -32.827722)
		(end 137.006838 -32.827722)
		(width 0.12954)
		(layer "F.Cu")
		(net "OCP_SFF_RBT_ARB_IN_MUX2_R")
	)
	(segment
		(start 140.30833 -32.458152)
		(end 138.9126 -32.458152)
		(width 0.12954)
		(layer "F.Cu")
		(net "OCP_SFF_RBT_ARB_IN_MUX2_R")
	)
	(via
		(at 138.9126 -32.458152)
		(size 0.762)
		(drill 0.381)
		(layers "F.Cu" "B.Cu")
		(net "OCP_SFF_RBT_ARB_IN_MUX2_R")
	)
	(segment
		(start 143.61795 -31.774638)
		(end 142.934436 -32.458152)
		(width 0.12954)
		(layer "F.Cu")
		(net "OCP_SFF_RBT_ARB_IN_MUX2")
	)
	(segment
		(start 141.10843 -32.458152)
		(end 141.86281 -32.458152)
		(width 0.12954)
		(layer "F.Cu")
		(net "OCP_SFF_RBT_ARB_IN_MUX2")
	)
	(segment
		(start 142.934436 -32.458152)
		(end 141.86281 -32.458152)
		(width 0.12954)
		(layer "F.Cu")
		(net "OCP_SFF_RBT_ARB_IN_MUX2")
	)
	(segment
		(start 143.891 -31.774638)
		(end 143.61795 -31.774638)
		(width 0.12954)
		(layer "F.Cu")
		(net "OCP_SFF_RBT_ARB_IN_MUX2")
	)
	(segment
		(start 145.63344 -35.695128)
		(end 146.050254 -36.111942)
		(width 0.12954)
		(layer "F.Cu")
		(net "OCP_SFF_RBT_ARB_IN_MUX2")
	)
	(segment
		(start 146.050254 -36.111942)
		(end 146.595338 -36.111942)
		(width 0.12954)
		(layer "F.Cu")
		(net "OCP_SFF_RBT_ARB_IN_MUX2")
	)
	(via
		(at 143.891 -31.774638)
		(size 0.508)
		(drill 0.254)
		(layers "F.Cu" "B.Cu")
		(net "OCP_SFF_RBT_ARB_IN_MUX2")
	)
	(via
		(at 145.63344 -35.695128)
		(size 0.508)
		(drill 0.254)
		(layers "F.Cu" "B.Cu")
		(net "OCP_SFF_RBT_ARB_IN_MUX2")
	)
	(segment
		(start 146.0373 -35.291268)
		(end 146.0373 -33.579308)
		(width 0.127)
		(layer "In4.Cu")
		(net "OCP_SFF_RBT_ARB_IN_MUX2")
	)
	(segment
		(start 145.63344 -35.695128)
		(end 146.0373 -35.291268)
		(width 0.127)
		(layer "In4.Cu")
		(net "OCP_SFF_RBT_ARB_IN_MUX2")
	)
	(segment
		(start 144.23263 -31.774638)
		(end 143.891 -31.774638)
		(width 0.127)
		(layer "In4.Cu")
		(net "OCP_SFF_RBT_ARB_IN_MUX2")
	)
	(segment
		(start 146.0373 -33.579308)
		(end 144.23263 -31.774638)
		(width 0.127)
		(layer "In4.Cu")
		(net "OCP_SFF_RBT_ARB_IN_MUX2")
	)
	(segment
		(start 148.020278 -32.507682)
		(end 147.128738 -32.507682)
		(width 0.12954)
		(layer "F.Cu")
		(net "OCP_SFF_RBT_ARB_IN_MUX1_R")
	)
	(segment
		(start 150.43023 -31.829756)
		(end 148.982684 -31.829756)
		(width 0.12954)
		(layer "F.Cu")
		(net "OCP_SFF_RBT_ARB_IN_MUX1_R")
	)
	(segment
		(start 148.840444 -31.687516)
		(end 148.020278 -32.507682)
		(width 0.12954)
		(layer "F.Cu")
		(net "OCP_SFF_RBT_ARB_IN_MUX1_R")
	)
	(segment
		(start 148.982684 -31.829756)
		(end 148.840444 -31.687516)
		(width 0.12954)
		(layer "F.Cu")
		(net "OCP_SFF_RBT_ARB_IN_MUX1_R")
	)
	(via
		(at 148.840444 -31.687516)
		(size 0.762)
		(drill 0.381)
		(layers "F.Cu" "B.Cu")
		(net "OCP_SFF_RBT_ARB_IN_MUX1_R")
	)
	(segment
		(start 137.943082 -37.169852)
		(end 137.713212 -37.399722)
		(width 0.12954)
		(layer "F.Cu")
		(net "OCP_SFF_RBT_ARB_IN_MUX1")
	)
	(segment
		(start 151.99106 -32.207708)
		(end 151.613108 -31.829756)
		(width 0.12954)
		(layer "F.Cu")
		(net "OCP_SFF_RBT_ARB_IN_MUX1")
	)
	(segment
		(start 151.613108 -31.829756)
		(end 151.23033 -31.829756)
		(width 0.12954)
		(layer "F.Cu")
		(net "OCP_SFF_RBT_ARB_IN_MUX1")
	)
	(segment
		(start 137.713212 -37.399722)
		(end 137.006838 -37.399722)
		(width 0.12954)
		(layer "F.Cu")
		(net "OCP_SFF_RBT_ARB_IN_MUX1")
	)
	(via
		(at 151.99106 -32.207708)
		(size 0.508)
		(drill 0.254)
		(layers "F.Cu" "B.Cu")
		(net "OCP_SFF_RBT_ARB_IN_MUX1")
	)
	(via
		(at 137.943082 -37.169852)
		(size 0.508)
		(drill 0.254)
		(layers "F.Cu" "B.Cu")
		(net "OCP_SFF_RBT_ARB_IN_MUX1")
	)
	(segment
		(start 141.78788 -36.032948)
		(end 139.079986 -36.032948)
		(width 0.127)
		(layer "In4.Cu")
		(net "OCP_SFF_RBT_ARB_IN_MUX1")
	)
	(segment
		(start 142.72006 -32.233108)
		(end 142.72006 -35.100768)
		(width 0.127)
		(layer "In4.Cu")
		(net "OCP_SFF_RBT_ARB_IN_MUX1")
	)
	(segment
		(start 145.1102 -31.290768)
		(end 143.6624 -31.290768)
		(width 0.127)
		(layer "In4.Cu")
		(net "OCP_SFF_RBT_ARB_IN_MUX1")
	)
	(segment
		(start 151.99106 -32.207708)
		(end 151.613108 -31.829756)
		(width 0.127)
		(layer "In4.Cu")
		(net "OCP_SFF_RBT_ARB_IN_MUX1")
	)
	(segment
		(start 142.72006 -35.100768)
		(end 141.78788 -36.032948)
		(width 0.127)
		(layer "In4.Cu")
		(net "OCP_SFF_RBT_ARB_IN_MUX1")
	)
	(segment
		(start 143.6624 -31.290768)
		(end 142.72006 -32.233108)
		(width 0.127)
		(layer "In4.Cu")
		(net "OCP_SFF_RBT_ARB_IN_MUX1")
	)
	(segment
		(start 151.613108 -31.829756)
		(end 145.649188 -31.829756)
		(width 0.127)
		(layer "In4.Cu")
		(net "OCP_SFF_RBT_ARB_IN_MUX1")
	)
	(segment
		(start 139.079986 -36.032948)
		(end 137.943082 -37.169852)
		(width 0.127)
		(layer "In4.Cu")
		(net "OCP_SFF_RBT_ARB_IN_MUX1")
	)
	(segment
		(start 145.649188 -31.829756)
		(end 145.1102 -31.290768)
		(width 0.127)
		(layer "In4.Cu")
		(net "OCP_SFF_RBT_ARB_IN_MUX1")
	)
	(segment
		(start 147.93595 -40.051736)
		(end 147.93595 -39.717218)
		(width 0.12954)
		(layer "F.Cu")
		(net "OCP_SFF_PRSNT_ALL_R_N")
	)
	(segment
		(start 148.96084 -35.276028)
		(end 150.578058 -35.276028)
		(width 0.12954)
		(layer "F.Cu")
		(net "OCP_SFF_PRSNT_ALL_R_N")
	)
	(segment
		(start 147.93595 -39.717218)
		(end 147.60448 -39.385748)
		(width 0.12954)
		(layer "F.Cu")
		(net "OCP_SFF_PRSNT_ALL_R_N")
	)
	(segment
		(start 150.578058 -35.276028)
		(end 151.23033 -34.623756)
		(width 0.12954)
		(layer "F.Cu")
		(net "OCP_SFF_PRSNT_ALL_R_N")
	)
	(segment
		(start 14.901672 -75.171808)
		(end 15.75308 -75.171808)
		(width 0.12954)
		(layer "F.Cu")
		(net "OCP_SFF_PRSNT_ALL_R_N")
	)
	(segment
		(start 147.60448 -39.385748)
		(end 147.60448 -36.632388)
		(width 0.12954)
		(layer "F.Cu")
		(net "OCP_SFF_PRSNT_ALL_R_N")
	)
	(segment
		(start 147.60448 -36.632388)
		(end 148.96084 -35.276028)
		(width 0.12954)
		(layer "F.Cu")
		(net "OCP_SFF_PRSNT_ALL_R_N")
	)
	(via
		(at 147.60448 -39.385748)
		(size 0.508)
		(drill 0.254)
		(layers "F.Cu" "B.Cu")
		(net "OCP_SFF_PRSNT_ALL_R_N")
	)
	(via
		(at 15.75308 -75.171808)
		(size 0.508)
		(drill 0.254)
		(layers "F.Cu" "B.Cu")
		(net "OCP_SFF_PRSNT_ALL_R_N")
	)
	(segment
		(start 146.61388 -40.376348)
		(end 147.60448 -39.385748)
		(width 0.127)
		(layer "In15.Cu")
		(net "OCP_SFF_PRSNT_ALL_R_N")
	)
	(segment
		(start 119.35968 -36.510468)
		(end 122.94616 -40.096948)
		(width 0.127)
		(layer "In15.Cu")
		(net "OCP_SFF_PRSNT_ALL_R_N")
	)
	(segment
		(start 87.94115 -38.777926)
		(end 89.035128 -37.683948)
		(width 0.127)
		(layer "In15.Cu")
		(net "OCP_SFF_PRSNT_ALL_R_N")
	)
	(segment
		(start 64.36106 -37.457888)
		(end 65.1002 -36.718748)
		(width 0.127)
		(layer "In15.Cu")
		(net "OCP_SFF_PRSNT_ALL_R_N")
	)
	(segment
		(start 75.9714 -36.718748)
		(end 78.030578 -38.777926)
		(width 0.127)
		(layer "In15.Cu")
		(net "OCP_SFF_PRSNT_ALL_R_N")
	)
	(segment
		(start 7.79653 -50.880518)
		(end 8.4963 -50.180748)
		(width 0.127)
		(layer "In15.Cu")
		(net "OCP_SFF_PRSNT_ALL_R_N")
	)
	(segment
		(start 39.11092 -50.180748)
		(end 51.83378 -37.457888)
		(width 0.127)
		(layer "In15.Cu")
		(net "OCP_SFF_PRSNT_ALL_R_N")
	)
	(segment
		(start 89.035128 -37.683948)
		(end 90.424 -37.683948)
		(width 0.127)
		(layer "In15.Cu")
		(net "OCP_SFF_PRSNT_ALL_R_N")
	)
	(segment
		(start 139.4333 -40.096948)
		(end 139.7127 -40.376348)
		(width 0.127)
		(layer "In15.Cu")
		(net "OCP_SFF_PRSNT_ALL_R_N")
	)
	(segment
		(start 5.80898 -54.392068)
		(end 7.79653 -52.404518)
		(width 0.127)
		(layer "In15.Cu")
		(net "OCP_SFF_PRSNT_ALL_R_N")
	)
	(segment
		(start 51.83378 -37.457888)
		(end 64.36106 -37.457888)
		(width 0.127)
		(layer "In15.Cu")
		(net "OCP_SFF_PRSNT_ALL_R_N")
	)
	(segment
		(start 78.030578 -38.777926)
		(end 87.94115 -38.777926)
		(width 0.127)
		(layer "In15.Cu")
		(net "OCP_SFF_PRSNT_ALL_R_N")
	)
	(segment
		(start 139.7127 -40.376348)
		(end 146.61388 -40.376348)
		(width 0.127)
		(layer "In15.Cu")
		(net "OCP_SFF_PRSNT_ALL_R_N")
	)
	(segment
		(start 90.424 -37.683948)
		(end 90.9574 -38.217348)
		(width 0.127)
		(layer "In15.Cu")
		(net "OCP_SFF_PRSNT_ALL_R_N")
	)
	(segment
		(start 8.4963 -50.180748)
		(end 39.11092 -50.180748)
		(width 0.127)
		(layer "In15.Cu")
		(net "OCP_SFF_PRSNT_ALL_R_N")
	)
	(segment
		(start 5.80898 -65.227708)
		(end 5.80898 -54.392068)
		(width 0.127)
		(layer "In15.Cu")
		(net "OCP_SFF_PRSNT_ALL_R_N")
	)
	(segment
		(start 65.1002 -36.718748)
		(end 75.9714 -36.718748)
		(width 0.127)
		(layer "In15.Cu")
		(net "OCP_SFF_PRSNT_ALL_R_N")
	)
	(segment
		(start 15.75308 -75.171808)
		(end 5.80898 -65.227708)
		(width 0.127)
		(layer "In15.Cu")
		(net "OCP_SFF_PRSNT_ALL_R_N")
	)
	(segment
		(start 104.72928 -36.510468)
		(end 119.35968 -36.510468)
		(width 0.127)
		(layer "In15.Cu")
		(net "OCP_SFF_PRSNT_ALL_R_N")
	)
	(segment
		(start 122.94616 -40.096948)
		(end 139.4333 -40.096948)
		(width 0.127)
		(layer "In15.Cu")
		(net "OCP_SFF_PRSNT_ALL_R_N")
	)
	(segment
		(start 90.9574 -38.217348)
		(end 103.0224 -38.217348)
		(width 0.127)
		(layer "In15.Cu")
		(net "OCP_SFF_PRSNT_ALL_R_N")
	)
	(segment
		(start 103.0224 -38.217348)
		(end 104.72928 -36.510468)
		(width 0.127)
		(layer "In15.Cu")
		(net "OCP_SFF_PRSNT_ALL_R_N")
	)
	(segment
		(start 7.79653 -52.404518)
		(end 7.79653 -50.880518)
		(width 0.127)
		(layer "In15.Cu")
		(net "OCP_SFF_PRSNT_ALL_R_N")
	)
	(segment
		(start 147.128738 -33.807654)
		(end 148.498052 -33.807654)
		(width 0.12954)
		(layer "F.Cu")
		(net "OCP_SFF_PRSNT_ALL_R3_N")
	)
	(segment
		(start 149.314154 -34.623756)
		(end 150.43023 -34.623756)
		(width 0.12954)
		(layer "F.Cu")
		(net "OCP_SFF_PRSNT_ALL_R3_N")
	)
	(segment
		(start 148.498052 -33.807654)
		(end 148.861272 -34.170874)
		(width 0.12954)
		(layer "F.Cu")
		(net "OCP_SFF_PRSNT_ALL_R3_N")
	)
	(segment
		(start 148.861272 -34.170874)
		(end 149.314154 -34.623756)
		(width 0.12954)
		(layer "F.Cu")
		(net "OCP_SFF_PRSNT_ALL_R3_N")
	)
	(via
		(at 148.861272 -34.170874)
		(size 0.762)
		(drill 0.381)
		(layers "F.Cu" "B.Cu")
		(net "OCP_SFF_PRSNT_ALL_R3_N")
	)
	(segment
		(start 147.00631 -37.530278)
		(end 146.887946 -37.411914)
		(width 0.12954)
		(layer "F.Cu")
		(net "OCP_SFF_PRSNT_ALL_R1_N")
	)
	(segment
		(start 147.13585 -40.051736)
		(end 147.00631 -39.922196)
		(width 0.12954)
		(layer "F.Cu")
		(net "OCP_SFF_PRSNT_ALL_R1_N")
	)
	(segment
		(start 147.00631 -38.839648)
		(end 147.00631 -37.530278)
		(width 0.12954)
		(layer "F.Cu")
		(net "OCP_SFF_PRSNT_ALL_R1_N")
	)
	(segment
		(start 146.887946 -37.411914)
		(end 146.595338 -37.411914)
		(width 0.12954)
		(layer "F.Cu")
		(net "OCP_SFF_PRSNT_ALL_R1_N")
	)
	(segment
		(start 147.00631 -39.922196)
		(end 147.00631 -38.839648)
		(width 0.12954)
		(layer "F.Cu")
		(net "OCP_SFF_PRSNT_ALL_R1_N")
	)
	(via
		(at 147.00631 -38.839648)
		(size 0.762)
		(drill 0.381)
		(layers "F.Cu" "B.Cu")
		(net "OCP_SFF_PRSNT_ALL_R1_N")
	)
	(segment
		(start 444.73368 -41.773348)
		(end 444.27648 -41.316148)
		(width 0.12954)
		(layer "F.Cu")
		(net "OCP_SFF_PRSNT23_R_N")
	)
	(segment
		(start 362.46308 -77.053948)
		(end 360.65968 -78.857348)
		(width 0.12954)
		(layer "F.Cu")
		(net "OCP_SFF_PRSNT23_R_N")
	)
	(segment
		(start 333.81188 -78.857348)
		(end 331.85608 -80.813148)
		(width 0.12954)
		(layer "F.Cu")
		(net "OCP_SFF_PRSNT23_R_N")
	)
	(segment
		(start 364.82528 -77.053948)
		(end 362.46308 -77.053948)
		(width 0.12954)
		(layer "F.Cu")
		(net "OCP_SFF_PRSNT23_R_N")
	)
	(segment
		(start 443.84976 -39.187628)
		(end 443.083188 -39.187628)
		(width 0.12954)
		(layer "F.Cu")
		(net "OCP_SFF_PRSNT23_R_N")
	)
	(segment
		(start 11.351768 -75.171808)
		(end 9.144 -75.171808)
		(width 0.12954)
		(layer "F.Cu")
		(net "OCP_SFF_PRSNT23_R_N")
	)
	(segment
		(start 444.27648 -41.316148)
		(end 444.27648 -39.614348)
		(width 0.12954)
		(layer "F.Cu")
		(net "OCP_SFF_PRSNT23_R_N")
	)
	(segment
		(start 331.85608 -80.813148)
		(end 328.02068 -80.813148)
		(width 0.12954)
		(layer "F.Cu")
		(net "OCP_SFF_PRSNT23_R_N")
	)
	(segment
		(start 360.65968 -78.857348)
		(end 333.81188 -78.857348)
		(width 0.12954)
		(layer "F.Cu")
		(net "OCP_SFF_PRSNT23_R_N")
	)
	(segment
		(start 444.27648 -39.614348)
		(end 443.84976 -39.187628)
		(width 0.12954)
		(layer "F.Cu")
		(net "OCP_SFF_PRSNT23_R_N")
	)
	(segment
		(start 444.73368 -43.602148)
		(end 444.73368 -41.773348)
		(width 0.12954)
		(layer "F.Cu")
		(net "OCP_SFF_PRSNT23_R_N")
	)
	(via
		(at 444.73368 -43.602148)
		(size 0.508)
		(drill 0.254)
		(layers "F.Cu" "B.Cu")
		(net "OCP_SFF_PRSNT23_R_N")
	)
	(via
		(at 9.144 -75.171808)
		(size 0.762)
		(drill 0.254)
		(layers "F.Cu" "B.Cu")
		(net "OCP_SFF_PRSNT23_R_N")
	)
	(via
		(at 328.02068 -80.813148)
		(size 0.508)
		(drill 0.254)
		(layers "F.Cu" "B.Cu")
		(net "OCP_SFF_PRSNT23_R_N")
	)
	(via
		(at 364.82528 -77.053948)
		(size 0.508)
		(drill 0.254)
		(layers "F.Cu" "B.Cu")
		(net "OCP_SFF_PRSNT23_R_N")
	)
	(segment
		(start 175.134016 -84.070952)
		(end 192.228216 -84.070952)
		(width 0.127)
		(layer "In6.Cu")
		(net "OCP_SFF_PRSNT23_R_N")
	)
	(segment
		(start 145.014442 -69.191378)
		(end 149.908514 -69.191378)
		(width 0.127)
		(layer "In6.Cu")
		(net "OCP_SFF_PRSNT23_R_N")
	)
	(segment
		(start 363.35208 -81.752948)
		(end 363.35208 -78.130908)
		(width 0.127)
		(layer "In6.Cu")
		(net "OCP_SFF_PRSNT23_R_N")
	)
	(segment
		(start 366.90808 -85.308948)
		(end 363.35208 -81.752948)
		(width 0.127)
		(layer "In6.Cu")
		(net "OCP_SFF_PRSNT23_R_N")
	)
	(segment
		(start 444.14948 -43.017948)
		(end 442.28004 -43.017948)
		(width 0.127)
		(layer "In6.Cu")
		(net "OCP_SFF_PRSNT23_R_N")
	)
	(segment
		(start 302.093376 -80.813148)
		(end 328.02068 -80.813148)
		(width 0.127)
		(layer "In6.Cu")
		(net "OCP_SFF_PRSNT23_R_N")
	)
	(segment
		(start 53.918104 -81.774792)
		(end 66.335148 -69.357748)
		(width 0.127)
		(layer "In6.Cu")
		(net "OCP_SFF_PRSNT23_R_N")
	)
	(segment
		(start 144.103852 -68.280788)
		(end 145.014442 -69.191378)
		(width 0.127)
		(layer "In6.Cu")
		(net "OCP_SFF_PRSNT23_R_N")
	)
	(segment
		(start 438.77738 -46.520608)
		(end 435.51348 -46.520608)
		(width 0.127)
		(layer "In6.Cu")
		(net "OCP_SFF_PRSNT23_R_N")
	)
	(segment
		(start 135.3566 -69.357748)
		(end 136.43356 -68.280788)
		(width 0.127)
		(layer "In6.Cu")
		(net "OCP_SFF_PRSNT23_R_N")
	)
	(segment
		(start 246.374158 -85.432138)
		(end 297.474386 -85.432138)
		(width 0.127)
		(layer "In6.Cu")
		(net "OCP_SFF_PRSNT23_R_N")
	)
	(segment
		(start 66.335148 -69.357748)
		(end 135.3566 -69.357748)
		(width 0.127)
		(layer "In6.Cu")
		(net "OCP_SFF_PRSNT23_R_N")
	)
	(segment
		(start 163.505642 -72.442578)
		(end 175.134016 -84.070952)
		(width 0.127)
		(layer "In6.Cu")
		(net "OCP_SFF_PRSNT23_R_N")
	)
	(segment
		(start 9.144 -75.171808)
		(end 11.63574 -75.171808)
		(width 0.127)
		(layer "In6.Cu")
		(net "OCP_SFF_PRSNT23_R_N")
	)
	(segment
		(start 442.28004 -43.017948)
		(end 438.77738 -46.520608)
		(width 0.127)
		(layer "In6.Cu")
		(net "OCP_SFF_PRSNT23_R_N")
	)
	(segment
		(start 192.228216 -84.070952)
		(end 192.741042 -84.583778)
		(width 0.127)
		(layer "In6.Cu")
		(net "OCP_SFF_PRSNT23_R_N")
	)
	(segment
		(start 11.63574 -75.171808)
		(end 18.238724 -81.774792)
		(width 0.127)
		(layer "In6.Cu")
		(net "OCP_SFF_PRSNT23_R_N")
	)
	(segment
		(start 435.51348 -46.520608)
		(end 427.46676 -54.567328)
		(width 0.127)
		(layer "In6.Cu")
		(net "OCP_SFF_PRSNT23_R_N")
	)
	(segment
		(start 418.58946 -76.434188)
		(end 409.7147 -85.308948)
		(width 0.127)
		(layer "In6.Cu")
		(net "OCP_SFF_PRSNT23_R_N")
	)
	(segment
		(start 427.46676 -56.911748)
		(end 418.58946 -65.789048)
		(width 0.127)
		(layer "In6.Cu")
		(net "OCP_SFF_PRSNT23_R_N")
	)
	(segment
		(start 211.73313 -90.857578)
		(end 240.948718 -90.857578)
		(width 0.127)
		(layer "In6.Cu")
		(net "OCP_SFF_PRSNT23_R_N")
	)
	(segment
		(start 364.42904 -77.053948)
		(end 364.82528 -77.053948)
		(width 0.127)
		(layer "In6.Cu")
		(net "OCP_SFF_PRSNT23_R_N")
	)
	(segment
		(start 409.7147 -85.308948)
		(end 366.90808 -85.308948)
		(width 0.127)
		(layer "In6.Cu")
		(net "OCP_SFF_PRSNT23_R_N")
	)
	(segment
		(start 363.35208 -78.130908)
		(end 364.42904 -77.053948)
		(width 0.127)
		(layer "In6.Cu")
		(net "OCP_SFF_PRSNT23_R_N")
	)
	(segment
		(start 205.45933 -84.583778)
		(end 211.73313 -90.857578)
		(width 0.127)
		(layer "In6.Cu")
		(net "OCP_SFF_PRSNT23_R_N")
	)
	(segment
		(start 444.73368 -43.602148)
		(end 444.14948 -43.017948)
		(width 0.127)
		(layer "In6.Cu")
		(net "OCP_SFF_PRSNT23_R_N")
	)
	(segment
		(start 153.159714 -72.442578)
		(end 163.505642 -72.442578)
		(width 0.127)
		(layer "In6.Cu")
		(net "OCP_SFF_PRSNT23_R_N")
	)
	(segment
		(start 136.43356 -68.280788)
		(end 144.103852 -68.280788)
		(width 0.127)
		(layer "In6.Cu")
		(net "OCP_SFF_PRSNT23_R_N")
	)
	(segment
		(start 240.948718 -90.857578)
		(end 246.374158 -85.432138)
		(width 0.127)
		(layer "In6.Cu")
		(net "OCP_SFF_PRSNT23_R_N")
	)
	(segment
		(start 192.741042 -84.583778)
		(end 205.45933 -84.583778)
		(width 0.127)
		(layer "In6.Cu")
		(net "OCP_SFF_PRSNT23_R_N")
	)
	(segment
		(start 297.474386 -85.432138)
		(end 302.093376 -80.813148)
		(width 0.127)
		(layer "In6.Cu")
		(net "OCP_SFF_PRSNT23_R_N")
	)
	(segment
		(start 418.58946 -65.789048)
		(end 418.58946 -76.434188)
		(width 0.127)
		(layer "In6.Cu")
		(net "OCP_SFF_PRSNT23_R_N")
	)
	(segment
		(start 149.908514 -69.191378)
		(end 153.159714 -72.442578)
		(width 0.127)
		(layer "In6.Cu")
		(net "OCP_SFF_PRSNT23_R_N")
	)
	(segment
		(start 427.46676 -54.567328)
		(end 427.46676 -56.911748)
		(width 0.127)
		(layer "In6.Cu")
		(net "OCP_SFF_PRSNT23_R_N")
	)
	(segment
		(start 18.238724 -81.774792)
		(end 53.918104 -81.774792)
		(width 0.127)
		(layer "In6.Cu")
		(net "OCP_SFF_PRSNT23_R_N")
	)
	(segment
		(start 360.922824 -79.492348)
		(end 334.075024 -79.492348)
		(width 0.12954)
		(layer "F.Cu")
		(net "OCP_SFF_PRSNT01_R_N")
	)
	(segment
		(start 445.36868 -40.198548)
		(end 445.72936 -39.837868)
		(width 0.12954)
		(layer "F.Cu")
		(net "OCP_SFF_PRSNT01_R_N")
	)
	(segment
		(start 445.54648 -43.576748)
		(end 445.36868 -43.398948)
		(width 0.12954)
		(layer "F.Cu")
		(net "OCP_SFF_PRSNT01_R_N")
	)
	(segment
		(start 362.726224 -77.688948)
		(end 360.922824 -79.492348)
		(width 0.12954)
		(layer "F.Cu")
		(net "OCP_SFF_PRSNT01_R_N")
	)
	(segment
		(start 364.82528 -77.688948)
		(end 362.726224 -77.688948)
		(width 0.12954)
		(layer "F.Cu")
		(net "OCP_SFF_PRSNT01_R_N")
	)
	(segment
		(start 445.36868 -43.398948)
		(end 445.36868 -40.198548)
		(width 0.12954)
		(layer "F.Cu")
		(net "OCP_SFF_PRSNT01_R_N")
	)
	(segment
		(start 332.119224 -81.448148)
		(end 328.02068 -81.448148)
		(width 0.12954)
		(layer "F.Cu")
		(net "OCP_SFF_PRSNT01_R_N")
	)
	(segment
		(start 11.351768 -75.871578)
		(end 10.16 -75.871578)
		(width 0.12954)
		(layer "F.Cu")
		(net "OCP_SFF_PRSNT01_R_N")
	)
	(segment
		(start 334.075024 -79.492348)
		(end 332.119224 -81.448148)
		(width 0.12954)
		(layer "F.Cu")
		(net "OCP_SFF_PRSNT01_R_N")
	)
	(segment
		(start 445.72936 -39.837868)
		(end 446.633092 -39.837868)
		(width 0.12954)
		(layer "F.Cu")
		(net "OCP_SFF_PRSNT01_R_N")
	)
	(via
		(at 10.16 -75.871578)
		(size 0.508)
		(drill 0.254)
		(layers "F.Cu" "B.Cu")
		(net "OCP_SFF_PRSNT01_R_N")
	)
	(via
		(at 445.54648 -43.576748)
		(size 0.508)
		(drill 0.254)
		(layers "F.Cu" "B.Cu")
		(net "OCP_SFF_PRSNT01_R_N")
	)
	(via
		(at 328.02068 -81.448148)
		(size 0.508)
		(drill 0.254)
		(layers "F.Cu" "B.Cu")
		(net "OCP_SFF_PRSNT01_R_N")
	)
	(via
		(at 364.82528 -77.688948)
		(size 0.508)
		(drill 0.254)
		(layers "F.Cu" "B.Cu")
		(net "OCP_SFF_PRSNT01_R_N")
	)
	(segment
		(start 192.58788 -84.953348)
		(end 192.075054 -84.440522)
		(width 0.127)
		(layer "In6.Cu")
		(net "OCP_SFF_PRSNT01_R_N")
	)
	(segment
		(start 427.017942 -56.72582)
		(end 418.140642 -65.60312)
		(width 0.127)
		(layer "In6.Cu")
		(net "OCP_SFF_PRSNT01_R_N")
	)
	(segment
		(start 442.127894 -42.535348)
		(end 438.591452 -46.07179)
		(width 0.127)
		(layer "In6.Cu")
		(net "OCP_SFF_PRSNT01_R_N")
	)
	(segment
		(start 445.54648 -43.576748)
		(end 444.50508 -42.535348)
		(width 0.127)
		(layer "In6.Cu")
		(net "OCP_SFF_PRSNT01_R_N")
	)
	(segment
		(start 438.591452 -46.07179)
		(end 435.327552 -46.07179)
		(width 0.127)
		(layer "In6.Cu")
		(net "OCP_SFF_PRSNT01_R_N")
	)
	(segment
		(start 241.10188 -91.227148)
		(end 211.579968 -91.227148)
		(width 0.127)
		(layer "In6.Cu")
		(net "OCP_SFF_PRSNT01_R_N")
	)
	(segment
		(start 153.006552 -72.812148)
		(end 149.755352 -69.560948)
		(width 0.127)
		(layer "In6.Cu")
		(net "OCP_SFF_PRSNT01_R_N")
	)
	(segment
		(start 427.017942 -54.3814)
		(end 427.017942 -56.72582)
		(width 0.127)
		(layer "In6.Cu")
		(net "OCP_SFF_PRSNT01_R_N")
	)
	(segment
		(start 301.925482 -81.448148)
		(end 297.611292 -85.762338)
		(width 0.127)
		(layer "In6.Cu")
		(net "OCP_SFF_PRSNT01_R_N")
	)
	(segment
		(start 444.50508 -42.535348)
		(end 442.127894 -42.535348)
		(width 0.127)
		(layer "In6.Cu")
		(net "OCP_SFF_PRSNT01_R_N")
	)
	(segment
		(start 297.611292 -85.762338)
		(end 246.56669 -85.762338)
		(width 0.127)
		(layer "In6.Cu")
		(net "OCP_SFF_PRSNT01_R_N")
	)
	(segment
		(start 136.67486 -68.610988)
		(end 135.55218 -69.733668)
		(width 0.127)
		(layer "In6.Cu")
		(net "OCP_SFF_PRSNT01_R_N")
	)
	(segment
		(start 149.755352 -69.560948)
		(end 144.86128 -69.560948)
		(width 0.127)
		(layer "In6.Cu")
		(net "OCP_SFF_PRSNT01_R_N")
	)
	(segment
		(start 364.825026 -77.688948)
		(end 364.82528 -77.688948)
		(width 0.127)
		(layer "In6.Cu")
		(net "OCP_SFF_PRSNT01_R_N")
	)
	(segment
		(start 363.800898 -81.56702)
		(end 363.800898 -78.713076)
		(width 0.127)
		(layer "In6.Cu")
		(net "OCP_SFF_PRSNT01_R_N")
	)
	(segment
		(start 163.35248 -72.812148)
		(end 153.006552 -72.812148)
		(width 0.127)
		(layer "In6.Cu")
		(net "OCP_SFF_PRSNT01_R_N")
	)
	(segment
		(start 409.528772 -84.86013)
		(end 367.094008 -84.86013)
		(width 0.127)
		(layer "In6.Cu")
		(net "OCP_SFF_PRSNT01_R_N")
	)
	(segment
		(start 66.48196 -69.733668)
		(end 54.071266 -82.144362)
		(width 0.127)
		(layer "In6.Cu")
		(net "OCP_SFF_PRSNT01_R_N")
	)
	(segment
		(start 135.55218 -69.733668)
		(end 66.48196 -69.733668)
		(width 0.127)
		(layer "In6.Cu")
		(net "OCP_SFF_PRSNT01_R_N")
	)
	(segment
		(start 363.800898 -78.713076)
		(end 364.825026 -77.688948)
		(width 0.127)
		(layer "In6.Cu")
		(net "OCP_SFF_PRSNT01_R_N")
	)
	(segment
		(start 205.306168 -84.953348)
		(end 192.58788 -84.953348)
		(width 0.127)
		(layer "In6.Cu")
		(net "OCP_SFF_PRSNT01_R_N")
	)
	(segment
		(start 418.140642 -65.60312)
		(end 418.140642 -76.24826)
		(width 0.127)
		(layer "In6.Cu")
		(net "OCP_SFF_PRSNT01_R_N")
	)
	(segment
		(start 435.327552 -46.07179)
		(end 427.017942 -54.3814)
		(width 0.127)
		(layer "In6.Cu")
		(net "OCP_SFF_PRSNT01_R_N")
	)
	(segment
		(start 211.579968 -91.227148)
		(end 205.306168 -84.953348)
		(width 0.127)
		(layer "In6.Cu")
		(net "OCP_SFF_PRSNT01_R_N")
	)
	(segment
		(start 143.91132 -68.610988)
		(end 136.67486 -68.610988)
		(width 0.127)
		(layer "In6.Cu")
		(net "OCP_SFF_PRSNT01_R_N")
	)
	(segment
		(start 17.618456 -82.144362)
		(end 11.345672 -75.871578)
		(width 0.127)
		(layer "In6.Cu")
		(net "OCP_SFF_PRSNT01_R_N")
	)
	(segment
		(start 144.86128 -69.560948)
		(end 143.91132 -68.610988)
		(width 0.127)
		(layer "In6.Cu")
		(net "OCP_SFF_PRSNT01_R_N")
	)
	(segment
		(start 328.02068 -81.448148)
		(end 301.925482 -81.448148)
		(width 0.127)
		(layer "In6.Cu")
		(net "OCP_SFF_PRSNT01_R_N")
	)
	(segment
		(start 418.140642 -76.24826)
		(end 409.528772 -84.86013)
		(width 0.127)
		(layer "In6.Cu")
		(net "OCP_SFF_PRSNT01_R_N")
	)
	(segment
		(start 192.075054 -84.440522)
		(end 174.980854 -84.440522)
		(width 0.127)
		(layer "In6.Cu")
		(net "OCP_SFF_PRSNT01_R_N")
	)
	(segment
		(start 54.071266 -82.144362)
		(end 17.618456 -82.144362)
		(width 0.127)
		(layer "In6.Cu")
		(net "OCP_SFF_PRSNT01_R_N")
	)
	(segment
		(start 246.56669 -85.762338)
		(end 241.10188 -91.227148)
		(width 0.127)
		(layer "In6.Cu")
		(net "OCP_SFF_PRSNT01_R_N")
	)
	(segment
		(start 174.980854 -84.440522)
		(end 163.35248 -72.812148)
		(width 0.127)
		(layer "In6.Cu")
		(net "OCP_SFF_PRSNT01_R_N")
	)
	(segment
		(start 11.345672 -75.871578)
		(end 10.16 -75.871578)
		(width 0.127)
		(layer "In6.Cu")
		(net "OCP_SFF_PRSNT01_R_N")
	)
	(segment
		(start 367.094008 -84.86013)
		(end 363.800898 -81.56702)
		(width 0.127)
		(layer "In6.Cu")
		(net "OCP_SFF_PRSNT01_R_N")
	)
	(segment
		(start 145.128742 -33.807654)
		(end 143.931894 -33.807654)
		(width 0.12954)
		(layer "F.Cu")
		(net "OCP_SFF_NOT_PRSNT_RBT_ARB_IN")
	)
	(segment
		(start 142.7734 -37.046408)
		(end 143.138906 -37.411914)
		(width 0.12954)
		(layer "F.Cu")
		(net "OCP_SFF_NOT_PRSNT_RBT_ARB_IN")
	)
	(segment
		(start 143.138906 -37.411914)
		(end 144.595342 -37.411914)
		(width 0.12954)
		(layer "F.Cu")
		(net "OCP_SFF_NOT_PRSNT_RBT_ARB_IN")
	)
	(segment
		(start 143.931894 -33.807654)
		(end 143.3068 -34.432748)
		(width 0.12954)
		(layer "F.Cu")
		(net "OCP_SFF_NOT_PRSNT_RBT_ARB_IN")
	)
	(segment
		(start 142.7734 -34.966148)
		(end 142.7734 -37.046408)
		(width 0.12954)
		(layer "F.Cu")
		(net "OCP_SFF_NOT_PRSNT_RBT_ARB_IN")
	)
	(segment
		(start 143.3068 -34.432748)
		(end 142.7734 -34.966148)
		(width 0.12954)
		(layer "F.Cu")
		(net "OCP_SFF_NOT_PRSNT_RBT_ARB_IN")
	)
	(via
		(at 143.3068 -34.432748)
		(size 0.762)
		(drill 0.381)
		(layers "F.Cu" "B.Cu")
		(net "OCP_SFF_NOT_PRSNT_RBT_ARB_IN")
	)
	(segment
		(start 448.37604 -4.638548)
		(end 448.91198 -4.638548)
		(width 0.12954)
		(layer "F.Cu")
		(net "OCP_SFF_ISO2_RBT_ARB_OUT")
	)
	(segment
		(start 449.86956 -6.616954)
		(end 449.86956 -7.293102)
		(width 0.12954)
		(layer "F.Cu")
		(net "OCP_SFF_ISO2_RBT_ARB_OUT")
	)
	(segment
		(start 448.91198 -4.638548)
		(end 449.147692 -4.87426)
		(width 0.12954)
		(layer "F.Cu")
		(net "OCP_SFF_ISO2_RBT_ARB_OUT")
	)
	(segment
		(start 449.86956 -7.293102)
		(end 450.161914 -7.585456)
		(width 0.12954)
		(layer "F.Cu")
		(net "OCP_SFF_ISO2_RBT_ARB_OUT")
	)
	(segment
		(start 449.147692 -4.87426)
		(end 449.86956 -6.616954)
		(width 0.12954)
		(layer "F.Cu")
		(net "OCP_SFF_ISO2_RBT_ARB_OUT")
	)
	(segment
		(start 450.161914 -7.585456)
		(end 450.161914 -8.320024)
		(width 0.12954)
		(layer "F.Cu")
		(net "OCP_SFF_ISO2_RBT_ARB_OUT")
	)
	(via
		(at 213.5759 -70.852792)
		(size 0.762)
		(drill 0.254)
		(layers "F.Cu" "B.Cu")
		(net "OCP_SFF_ISO2_RBT_ARB_OUT")
	)
	(via
		(at 220.37548 -39.207948)
		(size 0.508)
		(drill 0.254)
		(layers "F.Cu" "B.Cu")
		(net "OCP_SFF_ISO2_RBT_ARB_OUT")
	)
	(via
		(at 196.44868 -36.439348)
		(size 0.508)
		(drill 0.254)
		(layers "F.Cu" "B.Cu")
		(net "OCP_SFF_ISO2_RBT_ARB_OUT")
	)
	(via
		(at 365.9632 -16.982948)
		(size 0.508)
		(drill 0.254)
		(layers "F.Cu" "B.Cu")
		(net "OCP_SFF_ISO2_RBT_ARB_OUT")
	)
	(via
		(at 448.37604 -4.638548)
		(size 0.508)
		(drill 0.254)
		(layers "F.Cu" "B.Cu")
		(net "OCP_SFF_ISO2_RBT_ARB_OUT")
	)
	(segment
		(start 214.757 -70.852792)
		(end 213.5759 -70.852792)
		(width 0.12954)
		(layer "B.Cu")
		(net "OCP_SFF_ISO2_RBT_ARB_OUT")
	)
	(segment
		(start 213.5759 -70.852792)
		(end 214.68588 -69.742812)
		(width 0.127)
		(layer "In2.Cu")
		(net "OCP_SFF_ISO2_RBT_ARB_OUT")
	)
	(segment
		(start 213.66988 -56.352948)
		(end 213.66988 -51.272948)
		(width 0.127)
		(layer "In2.Cu")
		(net "OCP_SFF_ISO2_RBT_ARB_OUT")
	)
	(segment
		(start 214.68588 -69.742812)
		(end 214.68588 -57.368948)
		(width 0.127)
		(layer "In2.Cu")
		(net "OCP_SFF_ISO2_RBT_ARB_OUT")
	)
	(segment
		(start 213.66988 -51.272948)
		(end 198.83628 -36.439348)
		(width 0.127)
		(layer "In2.Cu")
		(net "OCP_SFF_ISO2_RBT_ARB_OUT")
	)
	(segment
		(start 198.83628 -36.439348)
		(end 196.44868 -36.439348)
		(width 0.127)
		(layer "In2.Cu")
		(net "OCP_SFF_ISO2_RBT_ARB_OUT")
	)
	(segment
		(start 214.68588 -57.368948)
		(end 213.66988 -56.352948)
		(width 0.127)
		(layer "In2.Cu")
		(net "OCP_SFF_ISO2_RBT_ARB_OUT")
	)
	(segment
		(start 435.36108 -3.419348)
		(end 426.06976 -3.419348)
		(width 0.127)
		(layer "In4.Cu")
		(net "OCP_SFF_ISO2_RBT_ARB_OUT")
	)
	(segment
		(start 392.63828 -8.880348)
		(end 385.14528 -16.373348)
		(width 0.127)
		(layer "In4.Cu")
		(net "OCP_SFF_ISO2_RBT_ARB_OUT")
	)
	(segment
		(start 426.06976 -3.419348)
		(end 423.15384 -6.335268)
		(width 0.127)
		(layer "In4.Cu")
		(net "OCP_SFF_ISO2_RBT_ARB_OUT")
	)
	(segment
		(start 371.2845 -17.755108)
		(end 370.2812 -16.751808)
		(width 0.127)
		(layer "In4.Cu")
		(net "OCP_SFF_ISO2_RBT_ARB_OUT")
	)
	(segment
		(start 374.447816 -17.755108)
		(end 371.2845 -17.755108)
		(width 0.127)
		(layer "In4.Cu")
		(net "OCP_SFF_ISO2_RBT_ARB_OUT")
	)
	(segment
		(start 370.2812 -16.751808)
		(end 366.19434 -16.751808)
		(width 0.127)
		(layer "In4.Cu")
		(net "OCP_SFF_ISO2_RBT_ARB_OUT")
	)
	(segment
		(start 444.39078 -4.829048)
		(end 443.94628 -5.273548)
		(width 0.127)
		(layer "In4.Cu")
		(net "OCP_SFF_ISO2_RBT_ARB_OUT")
	)
	(segment
		(start 443.94628 -5.273548)
		(end 437.21528 -5.273548)
		(width 0.127)
		(layer "In4.Cu")
		(net "OCP_SFF_ISO2_RBT_ARB_OUT")
	)
	(segment
		(start 366.19434 -16.751808)
		(end 365.9632 -16.982948)
		(width 0.127)
		(layer "In4.Cu")
		(net "OCP_SFF_ISO2_RBT_ARB_OUT")
	)
	(segment
		(start 448.37604 -4.638548)
		(end 448.18554 -4.829048)
		(width 0.127)
		(layer "In4.Cu")
		(net "OCP_SFF_ISO2_RBT_ARB_OUT")
	)
	(segment
		(start 448.18554 -4.829048)
		(end 444.39078 -4.829048)
		(width 0.127)
		(layer "In4.Cu")
		(net "OCP_SFF_ISO2_RBT_ARB_OUT")
	)
	(segment
		(start 437.21528 -5.273548)
		(end 435.36108 -3.419348)
		(width 0.127)
		(layer "In4.Cu")
		(net "OCP_SFF_ISO2_RBT_ARB_OUT")
	)
	(segment
		(start 421.16248 -8.880348)
		(end 392.63828 -8.880348)
		(width 0.127)
		(layer "In4.Cu")
		(net "OCP_SFF_ISO2_RBT_ARB_OUT")
	)
	(segment
		(start 385.14528 -16.373348)
		(end 375.829576 -16.373348)
		(width 0.127)
		(layer "In4.Cu")
		(net "OCP_SFF_ISO2_RBT_ARB_OUT")
	)
	(segment
		(start 375.829576 -16.373348)
		(end 374.447816 -17.755108)
		(width 0.127)
		(layer "In4.Cu")
		(net "OCP_SFF_ISO2_RBT_ARB_OUT")
	)
	(segment
		(start 423.15384 -6.888988)
		(end 421.16248 -8.880348)
		(width 0.127)
		(layer "In4.Cu")
		(net "OCP_SFF_ISO2_RBT_ARB_OUT")
	)
	(segment
		(start 423.15384 -6.335268)
		(end 423.15384 -6.888988)
		(width 0.127)
		(layer "In4.Cu")
		(net "OCP_SFF_ISO2_RBT_ARB_OUT")
	)
	(segment
		(start 362.338112 -15.91818)
		(end 321.508628 -15.91818)
		(width 0.127)
		(layer "In11.Cu")
		(net "OCP_SFF_ISO2_RBT_ARB_OUT")
	)
	(segment
		(start 234.879134 -47.970948)
		(end 232.678986 -47.970948)
		(width 0.127)
		(layer "In11.Cu")
		(net "OCP_SFF_ISO2_RBT_ARB_OUT")
	)
	(segment
		(start 296.919396 -24.266144)
		(end 277.475188 -24.266144)
		(width 0.127)
		(layer "In11.Cu")
		(net "OCP_SFF_ISO2_RBT_ARB_OUT")
	)
	(segment
		(start 258.057396 -41.088564)
		(end 257.733038 -41.412922)
		(width 0.127)
		(layer "In11.Cu")
		(net "OCP_SFF_ISO2_RBT_ARB_OUT")
	)
	(segment
		(start 321.508628 -15.91818)
		(end 320.57086 -16.855948)
		(width 0.127)
		(layer "In11.Cu")
		(net "OCP_SFF_ISO2_RBT_ARB_OUT")
	)
	(segment
		(start 365.9632 -16.982948)
		(end 363.40288 -16.982948)
		(width 0.127)
		(layer "In11.Cu")
		(net "OCP_SFF_ISO2_RBT_ARB_OUT")
	)
	(segment
		(start 224.26803 -40.947848)
		(end 222.52813 -39.207948)
		(width 0.127)
		(layer "In11.Cu")
		(net "OCP_SFF_ISO2_RBT_ARB_OUT")
	)
	(segment
		(start 258.057396 -40.072564)
		(end 258.057396 -41.088564)
		(width 0.127)
		(layer "In11.Cu")
		(net "OCP_SFF_ISO2_RBT_ARB_OUT")
	)
	(segment
		(start 304.329592 -16.855948)
		(end 296.919396 -24.266144)
		(width 0.127)
		(layer "In11.Cu")
		(net "OCP_SFF_ISO2_RBT_ARB_OUT")
	)
	(segment
		(start 222.52813 -39.207948)
		(end 220.37548 -39.207948)
		(width 0.127)
		(layer "In11.Cu")
		(net "OCP_SFF_ISO2_RBT_ARB_OUT")
	)
	(segment
		(start 232.678986 -47.970948)
		(end 231.90708 -47.199042)
		(width 0.127)
		(layer "In11.Cu")
		(net "OCP_SFF_ISO2_RBT_ARB_OUT")
	)
	(segment
		(start 263.582912 -34.547048)
		(end 258.057396 -40.072564)
		(width 0.127)
		(layer "In11.Cu")
		(net "OCP_SFF_ISO2_RBT_ARB_OUT")
	)
	(segment
		(start 320.57086 -16.855948)
		(end 304.329592 -16.855948)
		(width 0.127)
		(layer "In11.Cu")
		(net "OCP_SFF_ISO2_RBT_ARB_OUT")
	)
	(segment
		(start 363.40288 -16.982948)
		(end 362.338112 -15.91818)
		(width 0.127)
		(layer "In11.Cu")
		(net "OCP_SFF_ISO2_RBT_ARB_OUT")
	)
	(segment
		(start 229.974648 -40.947848)
		(end 224.26803 -40.947848)
		(width 0.127)
		(layer "In11.Cu")
		(net "OCP_SFF_ISO2_RBT_ARB_OUT")
	)
	(segment
		(start 267.194284 -34.547048)
		(end 263.582912 -34.547048)
		(width 0.127)
		(layer "In11.Cu")
		(net "OCP_SFF_ISO2_RBT_ARB_OUT")
	)
	(segment
		(start 236.695234 -46.154848)
		(end 234.879134 -47.970948)
		(width 0.127)
		(layer "In11.Cu")
		(net "OCP_SFF_ISO2_RBT_ARB_OUT")
	)
	(segment
		(start 231.90708 -47.199042)
		(end 231.90708 -42.88028)
		(width 0.127)
		(layer "In11.Cu")
		(net "OCP_SFF_ISO2_RBT_ARB_OUT")
	)
	(segment
		(start 243.339112 -46.154848)
		(end 236.695234 -46.154848)
		(width 0.127)
		(layer "In11.Cu")
		(net "OCP_SFF_ISO2_RBT_ARB_OUT")
	)
	(segment
		(start 231.90708 -42.88028)
		(end 229.974648 -40.947848)
		(width 0.127)
		(layer "In11.Cu")
		(net "OCP_SFF_ISO2_RBT_ARB_OUT")
	)
	(segment
		(start 257.733038 -41.412922)
		(end 248.081038 -41.412922)
		(width 0.127)
		(layer "In11.Cu")
		(net "OCP_SFF_ISO2_RBT_ARB_OUT")
	)
	(segment
		(start 277.475188 -24.266144)
		(end 267.194284 -34.547048)
		(width 0.127)
		(layer "In11.Cu")
		(net "OCP_SFF_ISO2_RBT_ARB_OUT")
	)
	(segment
		(start 248.081038 -41.412922)
		(end 243.339112 -46.154848)
		(width 0.127)
		(layer "In11.Cu")
		(net "OCP_SFF_ISO2_RBT_ARB_OUT")
	)
	(segment
		(start 220.370654 -39.212774)
		(end 220.37548 -39.207948)
		(width 0.127)
		(layer "In13.Cu")
		(net "OCP_SFF_ISO2_RBT_ARB_OUT")
	)
	(segment
		(start 212.679534 -36.185348)
		(end 215.70696 -39.212774)
		(width 0.127)
		(layer "In13.Cu")
		(net "OCP_SFF_ISO2_RBT_ARB_OUT")
	)
	(segment
		(start 196.70268 -36.185348)
		(end 212.679534 -36.185348)
		(width 0.127)
		(layer "In13.Cu")
		(net "OCP_SFF_ISO2_RBT_ARB_OUT")
	)
	(segment
		(start 215.70696 -39.212774)
		(end 220.370654 -39.212774)
		(width 0.127)
		(layer "In13.Cu")
		(net "OCP_SFF_ISO2_RBT_ARB_OUT")
	)
	(segment
		(start 196.44868 -36.439348)
		(end 196.70268 -36.185348)
		(width 0.127)
		(layer "In13.Cu")
		(net "OCP_SFF_ISO2_RBT_ARB_OUT")
	)
	(segment
		(start 450.325236 -7.177278)
		(end 450.325236 -6.652006)
		(width 0.12954)
		(layer "F.Cu")
		(net "OCP_SFF_ISO1_RBT_ARB_IN")
	)
	(segment
		(start 450.770498 -7.62254)
		(end 450.325236 -7.177278)
		(width 0.12954)
		(layer "F.Cu")
		(net "OCP_SFF_ISO1_RBT_ARB_IN")
	)
	(segment
		(start 450.325236 -6.652006)
		(end 449.549774 -4.779518)
		(width 0.12954)
		(layer "F.Cu")
		(net "OCP_SFF_ISO1_RBT_ARB_IN")
	)
	(segment
		(start 450.761862 -8.320024)
		(end 450.770498 -8.311388)
		(width 0.12954)
		(layer "F.Cu")
		(net "OCP_SFF_ISO1_RBT_ARB_IN")
	)
	(segment
		(start 449.549774 -4.779518)
		(end 448.627754 -3.857498)
		(width 0.12954)
		(layer "F.Cu")
		(net "OCP_SFF_ISO1_RBT_ARB_IN")
	)
	(segment
		(start 448.627754 -3.857498)
		(end 447.547492 -3.857498)
		(width 0.12954)
		(layer "F.Cu")
		(net "OCP_SFF_ISO1_RBT_ARB_IN")
	)
	(segment
		(start 450.770498 -8.311388)
		(end 450.770498 -7.62254)
		(width 0.12954)
		(layer "F.Cu")
		(net "OCP_SFF_ISO1_RBT_ARB_IN")
	)
	(via
		(at 219.062808 -38.50386)
		(size 0.508)
		(drill 0.254)
		(layers "F.Cu" "B.Cu")
		(net "OCP_SFF_ISO1_RBT_ARB_IN")
	)
	(via
		(at 188.01588 -36.921948)
		(size 0.508)
		(drill 0.254)
		(layers "F.Cu" "B.Cu")
		(net "OCP_SFF_ISO1_RBT_ARB_IN")
	)
	(via
		(at 447.547492 -3.857498)
		(size 0.508)
		(drill 0.254)
		(layers "F.Cu" "B.Cu")
		(net "OCP_SFF_ISO1_RBT_ARB_IN")
	)
	(via
		(at 192.515744 -77.192632)
		(size 0.508)
		(drill 0.254)
		(layers "F.Cu" "B.Cu")
		(net "OCP_SFF_ISO1_RBT_ARB_IN")
	)
	(via
		(at 363.78388 -15.712948)
		(size 0.508)
		(drill 0.254)
		(layers "F.Cu" "B.Cu")
		(net "OCP_SFF_ISO1_RBT_ARB_IN")
	)
	(segment
		(start 194.304158 -77.192632)
		(end 192.515744 -77.192632)
		(width 0.12954)
		(layer "B.Cu")
		(net "OCP_SFF_ISO1_RBT_ARB_IN")
	)
	(segment
		(start 190.67018 -75.898248)
		(end 191.964564 -77.192632)
		(width 0.127)
		(layer "In2.Cu")
		(net "OCP_SFF_ISO1_RBT_ARB_IN")
	)
	(segment
		(start 188.4426 -37.348668)
		(end 188.4426 -43.801792)
		(width 0.127)
		(layer "In2.Cu")
		(net "OCP_SFF_ISO1_RBT_ARB_IN")
	)
	(segment
		(start 188.01588 -36.921948)
		(end 188.4426 -37.348668)
		(width 0.127)
		(layer "In2.Cu")
		(net "OCP_SFF_ISO1_RBT_ARB_IN")
	)
	(segment
		(start 190.67018 -46.029372)
		(end 190.67018 -75.898248)
		(width 0.127)
		(layer "In2.Cu")
		(net "OCP_SFF_ISO1_RBT_ARB_IN")
	)
	(segment
		(start 191.964564 -77.192632)
		(end 192.515744 -77.192632)
		(width 0.127)
		(layer "In2.Cu")
		(net "OCP_SFF_ISO1_RBT_ARB_IN")
	)
	(segment
		(start 188.4426 -43.801792)
		(end 190.67018 -46.029372)
		(width 0.127)
		(layer "In2.Cu")
		(net "OCP_SFF_ISO1_RBT_ARB_IN")
	)
	(segment
		(start 420.80434 -8.016748)
		(end 392.28014 -8.016748)
		(width 0.127)
		(layer "In4.Cu")
		(net "OCP_SFF_ISO1_RBT_ARB_IN")
	)
	(segment
		(start 443.48908 -4.333748)
		(end 437.604916 -4.333748)
		(width 0.127)
		(layer "In4.Cu")
		(net "OCP_SFF_ISO1_RBT_ARB_IN")
	)
	(segment
		(start 446.690242 -3.000248)
		(end 444.82258 -3.000248)
		(width 0.127)
		(layer "In4.Cu")
		(net "OCP_SFF_ISO1_RBT_ARB_IN")
	)
	(segment
		(start 392.28014 -8.016748)
		(end 385.30784 -14.989048)
		(width 0.127)
		(layer "In4.Cu")
		(net "OCP_SFF_ISO1_RBT_ARB_IN")
	)
	(segment
		(start 371.97538 -14.989048)
		(end 371.25148 -15.712948)
		(width 0.127)
		(layer "In4.Cu")
		(net "OCP_SFF_ISO1_RBT_ARB_IN")
	)
	(segment
		(start 444.82258 -3.000248)
		(end 443.48908 -4.333748)
		(width 0.127)
		(layer "In4.Cu")
		(net "OCP_SFF_ISO1_RBT_ARB_IN")
	)
	(segment
		(start 447.547492 -3.857498)
		(end 446.690242 -3.000248)
		(width 0.127)
		(layer "In4.Cu")
		(net "OCP_SFF_ISO1_RBT_ARB_IN")
	)
	(segment
		(start 422.28516 -6.535928)
		(end 420.80434 -8.016748)
		(width 0.127)
		(layer "In4.Cu")
		(net "OCP_SFF_ISO1_RBT_ARB_IN")
	)
	(segment
		(start 435.826916 -2.555748)
		(end 425.68114 -2.555748)
		(width 0.127)
		(layer "In4.Cu")
		(net "OCP_SFF_ISO1_RBT_ARB_IN")
	)
	(segment
		(start 425.68114 -2.555748)
		(end 422.28516 -5.951728)
		(width 0.127)
		(layer "In4.Cu")
		(net "OCP_SFF_ISO1_RBT_ARB_IN")
	)
	(segment
		(start 422.28516 -5.951728)
		(end 422.28516 -6.535928)
		(width 0.127)
		(layer "In4.Cu")
		(net "OCP_SFF_ISO1_RBT_ARB_IN")
	)
	(segment
		(start 385.30784 -14.989048)
		(end 371.97538 -14.989048)
		(width 0.127)
		(layer "In4.Cu")
		(net "OCP_SFF_ISO1_RBT_ARB_IN")
	)
	(segment
		(start 371.25148 -15.712948)
		(end 363.78388 -15.712948)
		(width 0.127)
		(layer "In4.Cu")
		(net "OCP_SFF_ISO1_RBT_ARB_IN")
	)
	(segment
		(start 437.604916 -4.333748)
		(end 435.826916 -2.555748)
		(width 0.127)
		(layer "In4.Cu")
		(net "OCP_SFF_ISO1_RBT_ARB_IN")
	)
	(segment
		(start 263.314942 -34.204148)
		(end 266.926314 -34.204148)
		(width 0.127)
		(layer "In11.Cu")
		(net "OCP_SFF_ISO1_RBT_ARB_IN")
	)
	(segment
		(start 247.87606 -40.943022)
		(end 253.287784 -40.943022)
		(width 0.127)
		(layer "In11.Cu")
		(net "OCP_SFF_ISO1_RBT_ARB_IN")
	)
	(segment
		(start 219.062808 -38.50386)
		(end 220.255592 -38.50386)
		(width 0.127)
		(layer "In11.Cu")
		(net "OCP_SFF_ISO1_RBT_ARB_IN")
	)
	(segment
		(start 253.287784 -40.943022)
		(end 254.138684 -40.092122)
		(width 0.127)
		(layer "In11.Cu")
		(net "OCP_SFF_ISO1_RBT_ARB_IN")
	)
	(segment
		(start 363.536992 -15.46606)
		(end 363.78388 -15.712948)
		(width 0.127)
		(layer "In11.Cu")
		(net "OCP_SFF_ISO1_RBT_ARB_IN")
	)
	(segment
		(start 254.138684 -40.092122)
		(end 256.13995 -40.092122)
		(width 0.127)
		(layer "In11.Cu")
		(net "OCP_SFF_ISO1_RBT_ARB_IN")
	)
	(segment
		(start 258.361688 -39.157402)
		(end 263.314942 -34.204148)
		(width 0.127)
		(layer "In11.Cu")
		(net "OCP_SFF_ISO1_RBT_ARB_IN")
	)
	(segment
		(start 220.255592 -38.50386)
		(end 220.32468 -38.572948)
		(width 0.127)
		(layer "In11.Cu")
		(net "OCP_SFF_ISO1_RBT_ARB_IN")
	)
	(segment
		(start 256.13995 -40.092122)
		(end 257.07467 -39.157402)
		(width 0.127)
		(layer "In11.Cu")
		(net "OCP_SFF_ISO1_RBT_ARB_IN")
	)
	(segment
		(start 304.119026 -16.347948)
		(end 319.89014 -16.347948)
		(width 0.127)
		(layer "In11.Cu")
		(net "OCP_SFF_ISO1_RBT_ARB_IN")
	)
	(segment
		(start 320.772028 -15.46606)
		(end 363.536992 -15.46606)
		(width 0.127)
		(layer "In11.Cu")
		(net "OCP_SFF_ISO1_RBT_ARB_IN")
	)
	(segment
		(start 232.33888 -47.019972)
		(end 232.781856 -47.462948)
		(width 0.127)
		(layer "In11.Cu")
		(net "OCP_SFF_ISO1_RBT_ARB_IN")
	)
	(segment
		(start 278.559514 -22.570948)
		(end 297.896026 -22.570948)
		(width 0.127)
		(layer "In11.Cu")
		(net "OCP_SFF_ISO1_RBT_ARB_IN")
	)
	(segment
		(start 266.926314 -34.204148)
		(end 278.559514 -22.570948)
		(width 0.127)
		(layer "In11.Cu")
		(net "OCP_SFF_ISO1_RBT_ARB_IN")
	)
	(segment
		(start 234.5944 -47.462948)
		(end 236.2327 -45.824648)
		(width 0.127)
		(layer "In11.Cu")
		(net "OCP_SFF_ISO1_RBT_ARB_IN")
	)
	(segment
		(start 242.994434 -45.824648)
		(end 247.87606 -40.943022)
		(width 0.127)
		(layer "In11.Cu")
		(net "OCP_SFF_ISO1_RBT_ARB_IN")
	)
	(segment
		(start 229.950518 -40.312848)
		(end 232.33888 -42.70121)
		(width 0.127)
		(layer "In11.Cu")
		(net "OCP_SFF_ISO1_RBT_ARB_IN")
	)
	(segment
		(start 236.2327 -45.824648)
		(end 242.994434 -45.824648)
		(width 0.127)
		(layer "In11.Cu")
		(net "OCP_SFF_ISO1_RBT_ARB_IN")
	)
	(segment
		(start 297.896026 -22.570948)
		(end 304.119026 -16.347948)
		(width 0.127)
		(layer "In11.Cu")
		(net "OCP_SFF_ISO1_RBT_ARB_IN")
	)
	(segment
		(start 232.33888 -42.70121)
		(end 232.33888 -47.019972)
		(width 0.127)
		(layer "In11.Cu")
		(net "OCP_SFF_ISO1_RBT_ARB_IN")
	)
	(segment
		(start 319.89014 -16.347948)
		(end 320.772028 -15.46606)
		(width 0.127)
		(layer "In11.Cu")
		(net "OCP_SFF_ISO1_RBT_ARB_IN")
	)
	(segment
		(start 257.07467 -39.157402)
		(end 258.361688 -39.157402)
		(width 0.127)
		(layer "In11.Cu")
		(net "OCP_SFF_ISO1_RBT_ARB_IN")
	)
	(segment
		(start 232.781856 -47.462948)
		(end 234.5944 -47.462948)
		(width 0.127)
		(layer "In11.Cu")
		(net "OCP_SFF_ISO1_RBT_ARB_IN")
	)
	(segment
		(start 220.32468 -38.572948)
		(end 222.791274 -38.572948)
		(width 0.127)
		(layer "In11.Cu")
		(net "OCP_SFF_ISO1_RBT_ARB_IN")
	)
	(segment
		(start 222.791274 -38.572948)
		(end 224.531174 -40.312848)
		(width 0.127)
		(layer "In11.Cu")
		(net "OCP_SFF_ISO1_RBT_ARB_IN")
	)
	(segment
		(start 224.531174 -40.312848)
		(end 229.950518 -40.312848)
		(width 0.127)
		(layer "In11.Cu")
		(net "OCP_SFF_ISO1_RBT_ARB_IN")
	)
	(segment
		(start 218.573096 -38.014148)
		(end 219.062808 -38.50386)
		(width 0.127)
		(layer "In13.Cu")
		(net "OCP_SFF_ISO1_RBT_ARB_IN")
	)
	(segment
		(start 188.62548 -37.531548)
		(end 194.36588 -37.531548)
		(width 0.127)
		(layer "In13.Cu")
		(net "OCP_SFF_ISO1_RBT_ARB_IN")
	)
	(segment
		(start 215.422226 -38.014148)
		(end 218.573096 -38.014148)
		(width 0.127)
		(layer "In13.Cu")
		(net "OCP_SFF_ISO1_RBT_ARB_IN")
	)
	(segment
		(start 197.089014 -34.808414)
		(end 212.216492 -34.808414)
		(width 0.127)
		(layer "In13.Cu")
		(net "OCP_SFF_ISO1_RBT_ARB_IN")
	)
	(segment
		(start 212.216492 -34.808414)
		(end 215.422226 -38.014148)
		(width 0.127)
		(layer "In13.Cu")
		(net "OCP_SFF_ISO1_RBT_ARB_IN")
	)
	(segment
		(start 194.36588 -37.531548)
		(end 197.089014 -34.808414)
		(width 0.127)
		(layer "In13.Cu")
		(net "OCP_SFF_ISO1_RBT_ARB_IN")
	)
	(segment
		(start 188.01588 -36.921948)
		(end 188.62548 -37.531548)
		(width 0.127)
		(layer "In13.Cu")
		(net "OCP_SFF_ISO1_RBT_ARB_IN")
	)
	(segment
		(start 273.53006 -16.043148)
		(end 274.12315 -16.043148)
		(width 0.12954)
		(layer "F.Cu")
		(net "NC_U219_NC1")
	)
	(segment
		(start 273.15922 -17.320768)
		(end 273.15922 -16.413988)
		(width 0.12954)
		(layer "F.Cu")
		(net "NC_U219_NC1")
	)
	(segment
		(start 273.15922 -16.413988)
		(end 273.53006 -16.043148)
		(width 0.12954)
		(layer "F.Cu")
		(net "NC_U219_NC1")
	)
	(via
		(at 273.15922 -17.320768)
		(size 0.762)
		(drill 0.381)
		(layers "F.Cu" "B.Cu")
		(net "NC_U219_NC1")
	)
	(segment
		(start 112.4966 -25.949148)
		(end 112.4966 -27.367738)
		(width 0.12954)
		(layer "F.Cu")
		(net "NC_U218_NC1")
	)
	(segment
		(start 112.4331 -25.885648)
		(end 112.4966 -25.949148)
		(width 0.12954)
		(layer "F.Cu")
		(net "NC_U218_NC1")
	)
	(via
		(at 112.4331 -25.885648)
		(size 0.762)
		(drill 0.381)
		(layers "F.Cu" "B.Cu")
		(net "NC_U218_NC1")
	)
	(segment
		(start 74.461878 -8.320024)
		(end 74.461878 -6.494526)
		(width 0.12954)
		(layer "F.Cu")
		(net "NCSI_OCP_V3_2_TX_EN")
	)
	(segment
		(start 74.461878 -6.494526)
		(end 74.18324 -6.215888)
		(width 0.12954)
		(layer "F.Cu")
		(net "NCSI_OCP_V3_2_TX_EN")
	)
	(via
		(at 74.18324 -6.215888)
		(size 0.508)
		(drill 0.254)
		(layers "F.Cu" "B.Cu")
		(net "NCSI_OCP_V3_2_TX_EN")
	)
	(via
		(at 102.84714 -15.890748)
		(size 0.508)
		(drill 0.254)
		(layers "F.Cu" "B.Cu")
		(net "NCSI_OCP_V3_2_TX_EN")
	)
	(segment
		(start 145.49755 -40.212518)
		(end 126.40691 -40.212518)
		(width 0.12954)
		(layer "B.Cu")
		(net "NCSI_OCP_V3_2_TX_EN")
	)
	(segment
		(start 102.84714 -17.139412)
		(end 102.84714 -15.890748)
		(width 0.12954)
		(layer "B.Cu")
		(net "NCSI_OCP_V3_2_TX_EN")
	)
	(segment
		(start 183.12638 -59.845448)
		(end 167.577516 -59.845448)
		(width 0.12954)
		(layer "B.Cu")
		(net "NCSI_OCP_V3_2_TX_EN")
	)
	(segment
		(start 153.35504 -49.251108)
		(end 153.35504 -46.641512)
		(width 0.12954)
		(layer "B.Cu")
		(net "NCSI_OCP_V3_2_TX_EN")
	)
	(segment
		(start 148.738336 -43.974004)
		(end 146.65325 -41.888918)
		(width 0.12954)
		(layer "B.Cu")
		(net "NCSI_OCP_V3_2_TX_EN")
	)
	(segment
		(start 108.945172 -19.49704)
		(end 105.204768 -19.49704)
		(width 0.12954)
		(layer "B.Cu")
		(net "NCSI_OCP_V3_2_TX_EN")
	)
	(segment
		(start 126.40691 -40.212518)
		(end 118.48719 -32.292798)
		(width 0.12954)
		(layer "B.Cu")
		(net "NCSI_OCP_V3_2_TX_EN")
	)
	(segment
		(start 195.55333 -68.953126)
		(end 192.234058 -68.953126)
		(width 0.12954)
		(layer "B.Cu")
		(net "NCSI_OCP_V3_2_TX_EN")
	)
	(segment
		(start 157.396688 -49.66462)
		(end 153.768552 -49.66462)
		(width 0.12954)
		(layer "B.Cu")
		(net "NCSI_OCP_V3_2_TX_EN")
	)
	(segment
		(start 167.577516 -59.845448)
		(end 157.396688 -49.66462)
		(width 0.12954)
		(layer "B.Cu")
		(net "NCSI_OCP_V3_2_TX_EN")
	)
	(segment
		(start 105.204768 -19.49704)
		(end 102.84714 -17.139412)
		(width 0.12954)
		(layer "B.Cu")
		(net "NCSI_OCP_V3_2_TX_EN")
	)
	(segment
		(start 151.529796 -44.816268)
		(end 150.771352 -44.816268)
		(width 0.12954)
		(layer "B.Cu")
		(net "NCSI_OCP_V3_2_TX_EN")
	)
	(segment
		(start 118.48719 -29.039058)
		(end 108.945172 -19.49704)
		(width 0.12954)
		(layer "B.Cu")
		(net "NCSI_OCP_V3_2_TX_EN")
	)
	(segment
		(start 153.35504 -46.641512)
		(end 151.529796 -44.816268)
		(width 0.12954)
		(layer "B.Cu")
		(net "NCSI_OCP_V3_2_TX_EN")
	)
	(segment
		(start 146.65325 -41.888918)
		(end 146.65325 -41.368218)
		(width 0.12954)
		(layer "B.Cu")
		(net "NCSI_OCP_V3_2_TX_EN")
	)
	(segment
		(start 192.234058 -68.953126)
		(end 183.12638 -59.845448)
		(width 0.12954)
		(layer "B.Cu")
		(net "NCSI_OCP_V3_2_TX_EN")
	)
	(segment
		(start 118.48719 -32.292798)
		(end 118.48719 -29.039058)
		(width 0.12954)
		(layer "B.Cu")
		(net "NCSI_OCP_V3_2_TX_EN")
	)
	(segment
		(start 146.65325 -41.368218)
		(end 145.49755 -40.212518)
		(width 0.12954)
		(layer "B.Cu")
		(net "NCSI_OCP_V3_2_TX_EN")
	)
	(segment
		(start 150.771352 -44.816268)
		(end 148.738336 -43.974004)
		(width 0.12954)
		(layer "B.Cu")
		(net "NCSI_OCP_V3_2_TX_EN")
	)
	(segment
		(start 153.768552 -49.66462)
		(end 153.35504 -49.251108)
		(width 0.12954)
		(layer "B.Cu")
		(net "NCSI_OCP_V3_2_TX_EN")
	)
	(segment
		(start 102.824534 -12.372848)
		(end 102.697534 -12.499848)
		(width 0.127)
		(layer "In6.Cu")
		(net "NCSI_OCP_V3_2_TX_EN")
	)
	(segment
		(start 74.73442 -8.047228)
		(end 74.42454 -7.737348)
		(width 0.127)
		(layer "In6.Cu")
		(net "NCSI_OCP_V3_2_TX_EN")
	)
	(segment
		(start 104.41432 -15.688056)
		(end 104.52608 -15.576296)
		(width 0.127)
		(layer "In6.Cu")
		(net "NCSI_OCP_V3_2_TX_EN")
	)
	(segment
		(start 92.623894 -12.372848)
		(end 92.496894 -12.499848)
		(width 0.127)
		(layer "In6.Cu")
		(net "NCSI_OCP_V3_2_TX_EN")
	)
	(segment
		(start 96.322134 -13.096748)
		(end 96.195134 -13.223748)
		(width 0.127)
		(layer "In6.Cu")
		(net "NCSI_OCP_V3_2_TX_EN")
	)
	(segment
		(start 100.020374 -13.223748)
		(end 99.636834 -13.223748)
		(width 0.127)
		(layer "In6.Cu")
		(net "NCSI_OCP_V3_2_TX_EN")
	)
	(segment
		(start 102.186994 -13.223748)
		(end 102.059994 -13.096748)
		(width 0.127)
		(layer "In6.Cu")
		(net "NCSI_OCP_V3_2_TX_EN")
	)
	(segment
		(start 95.684594 -12.499848)
		(end 95.557594 -12.372848)
		(width 0.127)
		(layer "In6.Cu")
		(net "NCSI_OCP_V3_2_TX_EN")
	)
	(segment
		(start 92.496894 -13.096748)
		(end 92.369894 -13.223748)
		(width 0.127)
		(layer "In6.Cu")
		(net "NCSI_OCP_V3_2_TX_EN")
	)
	(segment
		(start 96.959674 -13.096748)
		(end 96.959674 -12.499848)
		(width 0.127)
		(layer "In6.Cu")
		(net "NCSI_OCP_V3_2_TX_EN")
	)
	(segment
		(start 102.697534 -13.096748)
		(end 102.570534 -13.223748)
		(width 0.127)
		(layer "In6.Cu")
		(net "NCSI_OCP_V3_2_TX_EN")
	)
	(segment
		(start 93.261434 -13.223748)
		(end 93.134434 -13.096748)
		(width 0.127)
		(layer "In6.Cu")
		(net "NCSI_OCP_V3_2_TX_EN")
	)
	(segment
		(start 100.147374 -12.499848)
		(end 100.147374 -13.096748)
		(width 0.127)
		(layer "In6.Cu")
		(net "NCSI_OCP_V3_2_TX_EN")
	)
	(segment
		(start 102.059994 -13.096748)
		(end 102.059994 -12.499848)
		(width 0.127)
		(layer "In6.Cu")
		(net "NCSI_OCP_V3_2_TX_EN")
	)
	(segment
		(start 74.42454 -7.737348)
		(end 74.42454 -6.457188)
		(width 0.127)
		(layer "In6.Cu")
		(net "NCSI_OCP_V3_2_TX_EN")
	)
	(segment
		(start 96.322134 -12.499848)
		(end 96.322134 -13.096748)
		(width 0.127)
		(layer "In6.Cu")
		(net "NCSI_OCP_V3_2_TX_EN")
	)
	(segment
		(start 99.382834 -12.372848)
		(end 98.999294 -12.372848)
		(width 0.127)
		(layer "In6.Cu")
		(net "NCSI_OCP_V3_2_TX_EN")
	)
	(segment
		(start 95.811594 -13.223748)
		(end 95.684594 -13.096748)
		(width 0.127)
		(layer "In6.Cu")
		(net "NCSI_OCP_V3_2_TX_EN")
	)
	(segment
		(start 93.771974 -12.499848)
		(end 93.771974 -13.096748)
		(width 0.127)
		(layer "In6.Cu")
		(net "NCSI_OCP_V3_2_TX_EN")
	)
	(segment
		(start 103.15702 -16.383508)
		(end 104.16032 -16.383508)
		(width 0.127)
		(layer "In6.Cu")
		(net "NCSI_OCP_V3_2_TX_EN")
	)
	(segment
		(start 74.42454 -6.457188)
		(end 74.18324 -6.215888)
		(width 0.127)
		(layer "In6.Cu")
		(net "NCSI_OCP_V3_2_TX_EN")
	)
	(segment
		(start 96.449134 -12.372848)
		(end 96.322134 -12.499848)
		(width 0.127)
		(layer "In6.Cu")
		(net "NCSI_OCP_V3_2_TX_EN")
	)
	(segment
		(start 102.84714 -15.890748)
		(end 102.84714 -16.073628)
		(width 0.127)
		(layer "In6.Cu")
		(net "NCSI_OCP_V3_2_TX_EN")
	)
	(segment
		(start 100.784914 -12.499848)
		(end 100.657914 -12.372848)
		(width 0.127)
		(layer "In6.Cu")
		(net "NCSI_OCP_V3_2_TX_EN")
	)
	(segment
		(start 98.234754 -13.096748)
		(end 98.234754 -12.499848)
		(width 0.127)
		(layer "In6.Cu")
		(net "NCSI_OCP_V3_2_TX_EN")
	)
	(segment
		(start 94.282514 -12.372848)
		(end 93.898974 -12.372848)
		(width 0.127)
		(layer "In6.Cu")
		(net "NCSI_OCP_V3_2_TX_EN")
	)
	(segment
		(start 101.295454 -13.223748)
		(end 100.911914 -13.223748)
		(width 0.127)
		(layer "In6.Cu")
		(net "NCSI_OCP_V3_2_TX_EN")
	)
	(segment
		(start 104.41432 -16.129508)
		(end 104.41432 -15.688056)
		(width 0.127)
		(layer "In6.Cu")
		(net "NCSI_OCP_V3_2_TX_EN")
	)
	(segment
		(start 99.509834 -13.096748)
		(end 99.509834 -12.499848)
		(width 0.127)
		(layer "In6.Cu")
		(net "NCSI_OCP_V3_2_TX_EN")
	)
	(segment
		(start 98.234754 -12.499848)
		(end 98.107754 -12.372848)
		(width 0.127)
		(layer "In6.Cu")
		(net "NCSI_OCP_V3_2_TX_EN")
	)
	(segment
		(start 93.644974 -13.223748)
		(end 93.261434 -13.223748)
		(width 0.127)
		(layer "In6.Cu")
		(net "NCSI_OCP_V3_2_TX_EN")
	)
	(segment
		(start 93.771974 -13.096748)
		(end 93.644974 -13.223748)
		(width 0.127)
		(layer "In6.Cu")
		(net "NCSI_OCP_V3_2_TX_EN")
	)
	(segment
		(start 94.920054 -13.223748)
		(end 94.536514 -13.223748)
		(width 0.127)
		(layer "In6.Cu")
		(net "NCSI_OCP_V3_2_TX_EN")
	)
	(segment
		(start 94.409514 -12.499848)
		(end 94.282514 -12.372848)
		(width 0.127)
		(layer "In6.Cu")
		(net "NCSI_OCP_V3_2_TX_EN")
	)
	(segment
		(start 93.898974 -12.372848)
		(end 93.771974 -12.499848)
		(width 0.127)
		(layer "In6.Cu")
		(net "NCSI_OCP_V3_2_TX_EN")
	)
	(segment
		(start 104.16032 -16.383508)
		(end 104.41432 -16.129508)
		(width 0.127)
		(layer "In6.Cu")
		(net "NCSI_OCP_V3_2_TX_EN")
	)
	(segment
		(start 102.059994 -12.499848)
		(end 101.932994 -12.372848)
		(width 0.127)
		(layer "In6.Cu")
		(net "NCSI_OCP_V3_2_TX_EN")
	)
	(segment
		(start 103.335074 -13.096748)
		(end 103.335074 -12.499848)
		(width 0.127)
		(layer "In6.Cu")
		(net "NCSI_OCP_V3_2_TX_EN")
	)
	(segment
		(start 98.872294 -12.499848)
		(end 98.872294 -13.096748)
		(width 0.127)
		(layer "In6.Cu")
		(net "NCSI_OCP_V3_2_TX_EN")
	)
	(segment
		(start 97.724214 -12.372848)
		(end 97.597214 -12.499848)
		(width 0.127)
		(layer "In6.Cu")
		(net "NCSI_OCP_V3_2_TX_EN")
	)
	(segment
		(start 103.73868 -13.223748)
		(end 103.462074 -13.223748)
		(width 0.127)
		(layer "In6.Cu")
		(net "NCSI_OCP_V3_2_TX_EN")
	)
	(segment
		(start 100.784914 -13.096748)
		(end 100.784914 -12.499848)
		(width 0.127)
		(layer "In6.Cu")
		(net "NCSI_OCP_V3_2_TX_EN")
	)
	(segment
		(start 101.549454 -12.372848)
		(end 101.422454 -12.499848)
		(width 0.127)
		(layer "In6.Cu")
		(net "NCSI_OCP_V3_2_TX_EN")
	)
	(segment
		(start 92.369894 -13.223748)
		(end 82.04708 -13.223748)
		(width 0.127)
		(layer "In6.Cu")
		(net "NCSI_OCP_V3_2_TX_EN")
	)
	(segment
		(start 98.361754 -13.223748)
		(end 98.234754 -13.096748)
		(width 0.127)
		(layer "In6.Cu")
		(net "NCSI_OCP_V3_2_TX_EN")
	)
	(segment
		(start 100.147374 -13.096748)
		(end 100.020374 -13.223748)
		(width 0.127)
		(layer "In6.Cu")
		(net "NCSI_OCP_V3_2_TX_EN")
	)
	(segment
		(start 79.45628 -9.263888)
		(end 78.23962 -8.047228)
		(width 0.127)
		(layer "In6.Cu")
		(net "NCSI_OCP_V3_2_TX_EN")
	)
	(segment
		(start 102.84714 -16.073628)
		(end 103.15702 -16.383508)
		(width 0.127)
		(layer "In6.Cu")
		(net "NCSI_OCP_V3_2_TX_EN")
	)
	(segment
		(start 102.570534 -13.223748)
		(end 102.186994 -13.223748)
		(width 0.127)
		(layer "In6.Cu")
		(net "NCSI_OCP_V3_2_TX_EN")
	)
	(segment
		(start 95.684594 -13.096748)
		(end 95.684594 -12.499848)
		(width 0.127)
		(layer "In6.Cu")
		(net "NCSI_OCP_V3_2_TX_EN")
	)
	(segment
		(start 99.509834 -12.499848)
		(end 99.382834 -12.372848)
		(width 0.127)
		(layer "In6.Cu")
		(net "NCSI_OCP_V3_2_TX_EN")
	)
	(segment
		(start 97.597214 -13.096748)
		(end 97.470214 -13.223748)
		(width 0.127)
		(layer "In6.Cu")
		(net "NCSI_OCP_V3_2_TX_EN")
	)
	(segment
		(start 100.274374 -12.372848)
		(end 100.147374 -12.499848)
		(width 0.127)
		(layer "In6.Cu")
		(net "NCSI_OCP_V3_2_TX_EN")
	)
	(segment
		(start 100.911914 -13.223748)
		(end 100.784914 -13.096748)
		(width 0.127)
		(layer "In6.Cu")
		(net "NCSI_OCP_V3_2_TX_EN")
	)
	(segment
		(start 104.52608 -15.576296)
		(end 104.52608 -14.011148)
		(width 0.127)
		(layer "In6.Cu")
		(net "NCSI_OCP_V3_2_TX_EN")
	)
	(segment
		(start 98.872294 -13.096748)
		(end 98.745294 -13.223748)
		(width 0.127)
		(layer "In6.Cu")
		(net "NCSI_OCP_V3_2_TX_EN")
	)
	(segment
		(start 96.195134 -13.223748)
		(end 95.811594 -13.223748)
		(width 0.127)
		(layer "In6.Cu")
		(net "NCSI_OCP_V3_2_TX_EN")
	)
	(segment
		(start 79.45628 -10.632948)
		(end 79.45628 -9.263888)
		(width 0.127)
		(layer "In6.Cu")
		(net "NCSI_OCP_V3_2_TX_EN")
	)
	(segment
		(start 78.23962 -8.047228)
		(end 74.73442 -8.047228)
		(width 0.127)
		(layer "In6.Cu")
		(net "NCSI_OCP_V3_2_TX_EN")
	)
	(segment
		(start 96.832674 -12.372848)
		(end 96.449134 -12.372848)
		(width 0.127)
		(layer "In6.Cu")
		(net "NCSI_OCP_V3_2_TX_EN")
	)
	(segment
		(start 101.422454 -12.499848)
		(end 101.422454 -13.096748)
		(width 0.127)
		(layer "In6.Cu")
		(net "NCSI_OCP_V3_2_TX_EN")
	)
	(segment
		(start 104.52608 -14.011148)
		(end 103.73868 -13.223748)
		(width 0.127)
		(layer "In6.Cu")
		(net "NCSI_OCP_V3_2_TX_EN")
	)
	(segment
		(start 95.174054 -12.372848)
		(end 95.047054 -12.499848)
		(width 0.127)
		(layer "In6.Cu")
		(net "NCSI_OCP_V3_2_TX_EN")
	)
	(segment
		(start 93.134434 -13.096748)
		(end 93.134434 -12.499848)
		(width 0.127)
		(layer "In6.Cu")
		(net "NCSI_OCP_V3_2_TX_EN")
	)
	(segment
		(start 102.697534 -12.499848)
		(end 102.697534 -13.096748)
		(width 0.127)
		(layer "In6.Cu")
		(net "NCSI_OCP_V3_2_TX_EN")
	)
	(segment
		(start 93.007434 -12.372848)
		(end 92.623894 -12.372848)
		(width 0.127)
		(layer "In6.Cu")
		(net "NCSI_OCP_V3_2_TX_EN")
	)
	(segment
		(start 97.470214 -13.223748)
		(end 97.086674 -13.223748)
		(width 0.127)
		(layer "In6.Cu")
		(net "NCSI_OCP_V3_2_TX_EN")
	)
	(segment
		(start 100.657914 -12.372848)
		(end 100.274374 -12.372848)
		(width 0.127)
		(layer "In6.Cu")
		(net "NCSI_OCP_V3_2_TX_EN")
	)
	(segment
		(start 95.047054 -13.096748)
		(end 94.920054 -13.223748)
		(width 0.127)
		(layer "In6.Cu")
		(net "NCSI_OCP_V3_2_TX_EN")
	)
	(segment
		(start 101.932994 -12.372848)
		(end 101.549454 -12.372848)
		(width 0.127)
		(layer "In6.Cu")
		(net "NCSI_OCP_V3_2_TX_EN")
	)
	(segment
		(start 103.335074 -12.499848)
		(end 103.208074 -12.372848)
		(width 0.127)
		(layer "In6.Cu")
		(net "NCSI_OCP_V3_2_TX_EN")
	)
	(segment
		(start 97.597214 -12.499848)
		(end 97.597214 -13.096748)
		(width 0.127)
		(layer "In6.Cu")
		(net "NCSI_OCP_V3_2_TX_EN")
	)
	(segment
		(start 94.536514 -13.223748)
		(end 94.409514 -13.096748)
		(width 0.127)
		(layer "In6.Cu")
		(net "NCSI_OCP_V3_2_TX_EN")
	)
	(segment
		(start 98.745294 -13.223748)
		(end 98.361754 -13.223748)
		(width 0.127)
		(layer "In6.Cu")
		(net "NCSI_OCP_V3_2_TX_EN")
	)
	(segment
		(start 98.999294 -12.372848)
		(end 98.872294 -12.499848)
		(width 0.127)
		(layer "In6.Cu")
		(net "NCSI_OCP_V3_2_TX_EN")
	)
	(segment
		(start 98.107754 -12.372848)
		(end 97.724214 -12.372848)
		(width 0.127)
		(layer "In6.Cu")
		(net "NCSI_OCP_V3_2_TX_EN")
	)
	(segment
		(start 82.04708 -13.223748)
		(end 79.45628 -10.632948)
		(width 0.127)
		(layer "In6.Cu")
		(net "NCSI_OCP_V3_2_TX_EN")
	)
	(segment
		(start 103.462074 -13.223748)
		(end 103.335074 -13.096748)
		(width 0.127)
		(layer "In6.Cu")
		(net "NCSI_OCP_V3_2_TX_EN")
	)
	(segment
		(start 94.409514 -13.096748)
		(end 94.409514 -12.499848)
		(width 0.127)
		(layer "In6.Cu")
		(net "NCSI_OCP_V3_2_TX_EN")
	)
	(segment
		(start 99.636834 -13.223748)
		(end 99.509834 -13.096748)
		(width 0.127)
		(layer "In6.Cu")
		(net "NCSI_OCP_V3_2_TX_EN")
	)
	(segment
		(start 97.086674 -13.223748)
		(end 96.959674 -13.096748)
		(width 0.127)
		(layer "In6.Cu")
		(net "NCSI_OCP_V3_2_TX_EN")
	)
	(segment
		(start 95.047054 -12.499848)
		(end 95.047054 -13.096748)
		(width 0.127)
		(layer "In6.Cu")
		(net "NCSI_OCP_V3_2_TX_EN")
	)
	(segment
		(start 93.134434 -12.499848)
		(end 93.007434 -12.372848)
		(width 0.127)
		(layer "In6.Cu")
		(net "NCSI_OCP_V3_2_TX_EN")
	)
	(segment
		(start 101.422454 -13.096748)
		(end 101.295454 -13.223748)
		(width 0.127)
		(layer "In6.Cu")
		(net "NCSI_OCP_V3_2_TX_EN")
	)
	(segment
		(start 92.496894 -12.499848)
		(end 92.496894 -13.096748)
		(width 0.127)
		(layer "In6.Cu")
		(net "NCSI_OCP_V3_2_TX_EN")
	)
	(segment
		(start 95.557594 -12.372848)
		(end 95.174054 -12.372848)
		(width 0.127)
		(layer "In6.Cu")
		(net "NCSI_OCP_V3_2_TX_EN")
	)
	(segment
		(start 96.959674 -12.499848)
		(end 96.832674 -12.372848)
		(width 0.127)
		(layer "In6.Cu")
		(net "NCSI_OCP_V3_2_TX_EN")
	)
	(segment
		(start 103.208074 -12.372848)
		(end 102.824534 -12.372848)
		(width 0.127)
		(layer "In6.Cu")
		(net "NCSI_OCP_V3_2_TX_EN")
	)
	(segment
		(start 73.862184 -8.319262)
		(end 73.862946 -8.3185)
		(width 0.12954)
		(layer "F.Cu")
		(net "NCSI_OCP_V3_2_TXD1")
	)
	(segment
		(start 73.862184 -8.31977)
		(end 73.862184 -8.319262)
		(width 0.12954)
		(layer "F.Cu")
		(net "NCSI_OCP_V3_2_TXD1")
	)
	(segment
		(start 73.86193 -8.320024)
		(end 73.862184 -8.31977)
		(width 0.12954)
		(layer "F.Cu")
		(net "NCSI_OCP_V3_2_TXD1")
	)
	(segment
		(start 73.862946 -8.3185)
		(end 73.862946 -7.203948)
		(width 0.12954)
		(layer "F.Cu")
		(net "NCSI_OCP_V3_2_TXD1")
	)
	(via
		(at 103.57866 -15.913608)
		(size 0.508)
		(drill 0.254)
		(layers "F.Cu" "B.Cu")
		(net "NCSI_OCP_V3_2_TXD1")
	)
	(via
		(at 73.862946 -7.203948)
		(size 0.508)
		(drill 0.254)
		(layers "F.Cu" "B.Cu")
		(net "NCSI_OCP_V3_2_TXD1")
	)
	(segment
		(start 103.57866 -17.120362)
		(end 105.444798 -18.9865)
		(width 0.12954)
		(layer "B.Cu")
		(net "NCSI_OCP_V3_2_TXD1")
	)
	(segment
		(start 119.27459 -32.338518)
		(end 126.54026 -39.604188)
		(width 0.12954)
		(layer "B.Cu")
		(net "NCSI_OCP_V3_2_TXD1")
	)
	(segment
		(start 148.048472 -41.02862)
		(end 151.2824 -44.262548)
		(width 0.12954)
		(layer "B.Cu")
		(net "NCSI_OCP_V3_2_TXD1")
	)
	(segment
		(start 153.8986 -46.462696)
		(end 153.8986 -48.745648)
		(width 0.12954)
		(layer "B.Cu")
		(net "NCSI_OCP_V3_2_TXD1")
	)
	(segment
		(start 195.85432 -67.191128)
		(end 199.56272 -67.191128)
		(width 0.12954)
		(layer "B.Cu")
		(net "NCSI_OCP_V3_2_TXD1")
	)
	(segment
		(start 139.46632 -39.604188)
		(end 139.80033 -39.270178)
		(width 0.12954)
		(layer "B.Cu")
		(net "NCSI_OCP_V3_2_TXD1")
	)
	(segment
		(start 119.27459 -28.975558)
		(end 119.27459 -32.338518)
		(width 0.12954)
		(layer "B.Cu")
		(net "NCSI_OCP_V3_2_TXD1")
	)
	(segment
		(start 126.54026 -39.604188)
		(end 139.46632 -39.604188)
		(width 0.12954)
		(layer "B.Cu")
		(net "NCSI_OCP_V3_2_TXD1")
	)
	(segment
		(start 157.569662 -49.115472)
		(end 167.789098 -59.334908)
		(width 0.12954)
		(layer "B.Cu")
		(net "NCSI_OCP_V3_2_TXD1")
	)
	(segment
		(start 103.57866 -15.913608)
		(end 103.57866 -17.120362)
		(width 0.12954)
		(layer "B.Cu")
		(net "NCSI_OCP_V3_2_TXD1")
	)
	(segment
		(start 199.56272 -67.191128)
		(end 200.0885 -67.716908)
		(width 0.12954)
		(layer "B.Cu")
		(net "NCSI_OCP_V3_2_TXD1")
	)
	(segment
		(start 190.195962 -66.192908)
		(end 194.8561 -66.192908)
		(width 0.12954)
		(layer "B.Cu")
		(net "NCSI_OCP_V3_2_TXD1")
	)
	(segment
		(start 200.602342 -71.55307)
		(end 201.39533 -71.55307)
		(width 0.12954)
		(layer "B.Cu")
		(net "NCSI_OCP_V3_2_TXD1")
	)
	(segment
		(start 151.698452 -44.262548)
		(end 153.8986 -46.462696)
		(width 0.12954)
		(layer "B.Cu")
		(net "NCSI_OCP_V3_2_TXD1")
	)
	(segment
		(start 194.8561 -66.192908)
		(end 195.85432 -67.191128)
		(width 0.12954)
		(layer "B.Cu")
		(net "NCSI_OCP_V3_2_TXD1")
	)
	(segment
		(start 153.8986 -48.745648)
		(end 154.268424 -49.115472)
		(width 0.12954)
		(layer "B.Cu")
		(net "NCSI_OCP_V3_2_TXD1")
	)
	(segment
		(start 151.2824 -44.262548)
		(end 151.698452 -44.262548)
		(width 0.12954)
		(layer "B.Cu")
		(net "NCSI_OCP_V3_2_TXD1")
	)
	(segment
		(start 200.0885 -67.716908)
		(end 200.0885 -71.039228)
		(width 0.12954)
		(layer "B.Cu")
		(net "NCSI_OCP_V3_2_TXD1")
	)
	(segment
		(start 105.444798 -18.9865)
		(end 109.285532 -18.9865)
		(width 0.12954)
		(layer "B.Cu")
		(net "NCSI_OCP_V3_2_TXD1")
	)
	(segment
		(start 139.80033 -39.270178)
		(end 145.317464 -39.270178)
		(width 0.12954)
		(layer "B.Cu")
		(net "NCSI_OCP_V3_2_TXD1")
	)
	(segment
		(start 183.337962 -59.334908)
		(end 190.195962 -66.192908)
		(width 0.12954)
		(layer "B.Cu")
		(net "NCSI_OCP_V3_2_TXD1")
	)
	(segment
		(start 147.075906 -41.02862)
		(end 148.048472 -41.02862)
		(width 0.12954)
		(layer "B.Cu")
		(net "NCSI_OCP_V3_2_TXD1")
	)
	(segment
		(start 154.268424 -49.115472)
		(end 157.569662 -49.115472)
		(width 0.12954)
		(layer "B.Cu")
		(net "NCSI_OCP_V3_2_TXD1")
	)
	(segment
		(start 145.317464 -39.270178)
		(end 147.075906 -41.02862)
		(width 0.12954)
		(layer "B.Cu")
		(net "NCSI_OCP_V3_2_TXD1")
	)
	(segment
		(start 109.285532 -18.9865)
		(end 119.27459 -28.975558)
		(width 0.12954)
		(layer "B.Cu")
		(net "NCSI_OCP_V3_2_TXD1")
	)
	(segment
		(start 167.789098 -59.334908)
		(end 183.337962 -59.334908)
		(width 0.12954)
		(layer "B.Cu")
		(net "NCSI_OCP_V3_2_TXD1")
	)
	(segment
		(start 200.0885 -71.039228)
		(end 200.602342 -71.55307)
		(width 0.12954)
		(layer "B.Cu")
		(net "NCSI_OCP_V3_2_TXD1")
	)
	(segment
		(start 104.09428 -15.397988)
		(end 104.09428 -14.224762)
		(width 0.127)
		(layer "In6.Cu")
		(net "NCSI_OCP_V3_2_TXD1")
	)
	(segment
		(start 78.95336 -9.383522)
		(end 78.119986 -8.550148)
		(width 0.127)
		(layer "In6.Cu")
		(net "NCSI_OCP_V3_2_TXD1")
	)
	(segment
		(start 73.862946 -7.960614)
		(end 73.862946 -7.203948)
		(width 0.127)
		(layer "In6.Cu")
		(net "NCSI_OCP_V3_2_TXD1")
	)
	(segment
		(start 78.119986 -8.550148)
		(end 74.45248 -8.550148)
		(width 0.127)
		(layer "In6.Cu")
		(net "NCSI_OCP_V3_2_TXD1")
	)
	(segment
		(start 74.45248 -8.550148)
		(end 73.862946 -7.960614)
		(width 0.127)
		(layer "In6.Cu")
		(net "NCSI_OCP_V3_2_TXD1")
	)
	(segment
		(start 103.57866 -15.913608)
		(end 104.09428 -15.397988)
		(width 0.127)
		(layer "In6.Cu")
		(net "NCSI_OCP_V3_2_TXD1")
	)
	(segment
		(start 78.95336 -10.816082)
		(end 78.95336 -9.383522)
		(width 0.127)
		(layer "In6.Cu")
		(net "NCSI_OCP_V3_2_TXD1")
	)
	(segment
		(start 103.596186 -13.726668)
		(end 81.863946 -13.726668)
		(width 0.127)
		(layer "In6.Cu")
		(net "NCSI_OCP_V3_2_TXD1")
	)
	(segment
		(start 104.09428 -14.224762)
		(end 103.596186 -13.726668)
		(width 0.127)
		(layer "In6.Cu")
		(net "NCSI_OCP_V3_2_TXD1")
	)
	(segment
		(start 81.863946 -13.726668)
		(end 78.95336 -10.816082)
		(width 0.127)
		(layer "In6.Cu")
		(net "NCSI_OCP_V3_2_TXD1")
	)
	(segment
		(start 73.262236 -7.403846)
		(end 73.262236 -7.403338)
		(width 0.12954)
		(layer "F.Cu")
		(net "NCSI_OCP_V3_2_TXD0")
	)
	(segment
		(start 73.261982 -8.320024)
		(end 73.261982 -7.4041)
		(width 0.12954)
		(layer "F.Cu")
		(net "NCSI_OCP_V3_2_TXD0")
	)
	(segment
		(start 73.262998 -5.663946)
		(end 72.898 -5.298948)
		(width 0.12954)
		(layer "F.Cu")
		(net "NCSI_OCP_V3_2_TXD0")
	)
	(segment
		(start 73.262998 -7.402576)
		(end 73.262998 -5.663946)
		(width 0.12954)
		(layer "F.Cu")
		(net "NCSI_OCP_V3_2_TXD0")
	)
	(segment
		(start 73.261982 -7.4041)
		(end 73.262236 -7.403846)
		(width 0.12954)
		(layer "F.Cu")
		(net "NCSI_OCP_V3_2_TXD0")
	)
	(segment
		(start 73.262236 -7.403338)
		(end 73.262998 -7.402576)
		(width 0.12954)
		(layer "F.Cu")
		(net "NCSI_OCP_V3_2_TXD0")
	)
	(via
		(at 72.898 -5.298948)
		(size 0.508)
		(drill 0.254)
		(layers "F.Cu" "B.Cu")
		(net "NCSI_OCP_V3_2_TXD0")
	)
	(via
		(at 103.62438 -15.141448)
		(size 0.508)
		(drill 0.254)
		(layers "F.Cu" "B.Cu")
		(net "NCSI_OCP_V3_2_TXD0")
	)
	(segment
		(start 203.18476 -69.202808)
		(end 203.18476 -68.153788)
		(width 0.12954)
		(layer "B.Cu")
		(net "NCSI_OCP_V3_2_TXD0")
	)
	(segment
		(start 119.85879 -28.825698)
		(end 109.470952 -18.43786)
		(width 0.12954)
		(layer "B.Cu")
		(net "NCSI_OCP_V3_2_TXD0")
	)
	(segment
		(start 150.5712 -42.814748)
		(end 148.13788 -40.381428)
		(width 0.12954)
		(layer "B.Cu")
		(net "NCSI_OCP_V3_2_TXD0")
	)
	(segment
		(start 148.13788 -40.381428)
		(end 147.26285 -40.381428)
		(width 0.12954)
		(layer "B.Cu")
		(net "NCSI_OCP_V3_2_TXD0")
	)
	(segment
		(start 104.21366 -15.730728)
		(end 103.62438 -15.141448)
		(width 0.12954)
		(layer "B.Cu")
		(net "NCSI_OCP_V3_2_TXD0")
	)
	(segment
		(start 147.26285 -40.381428)
		(end 145.64106 -38.759638)
		(width 0.12954)
		(layer "B.Cu")
		(net "NCSI_OCP_V3_2_TXD0")
	)
	(segment
		(start 157.758384 -48.528224)
		(end 154.819096 -48.528224)
		(width 0.12954)
		(layer "B.Cu")
		(net "NCSI_OCP_V3_2_TXD0")
	)
	(segment
		(start 119.85879 -31.794958)
		(end 119.85879 -28.825698)
		(width 0.12954)
		(layer "B.Cu")
		(net "NCSI_OCP_V3_2_TXD0")
	)
	(segment
		(start 154.819096 -48.528224)
		(end 154.5463 -48.255428)
		(width 0.12954)
		(layer "B.Cu")
		(net "NCSI_OCP_V3_2_TXD0")
	)
	(segment
		(start 151.8793 -42.814748)
		(end 150.5712 -42.814748)
		(width 0.12954)
		(layer "B.Cu")
		(net "NCSI_OCP_V3_2_TXD0")
	)
	(segment
		(start 106.2482 -18.43786)
		(end 104.21366 -16.40332)
		(width 0.12954)
		(layer "B.Cu")
		(net "NCSI_OCP_V3_2_TXD0")
	)
	(segment
		(start 154.5463 -48.255428)
		(end 154.5463 -45.481748)
		(width 0.12954)
		(layer "B.Cu")
		(net "NCSI_OCP_V3_2_TXD0")
	)
	(segment
		(start 190.361824 -65.636648)
		(end 183.511444 -58.786268)
		(width 0.12954)
		(layer "B.Cu")
		(net "NCSI_OCP_V3_2_TXD0")
	)
	(segment
		(start 183.511444 -58.786268)
		(end 168.016428 -58.786268)
		(width 0.12954)
		(layer "B.Cu")
		(net "NCSI_OCP_V3_2_TXD0")
	)
	(segment
		(start 168.016428 -58.786268)
		(end 157.758384 -48.528224)
		(width 0.12954)
		(layer "B.Cu")
		(net "NCSI_OCP_V3_2_TXD0")
	)
	(segment
		(start 104.21366 -16.40332)
		(end 104.21366 -15.730728)
		(width 0.12954)
		(layer "B.Cu")
		(net "NCSI_OCP_V3_2_TXD0")
	)
	(segment
		(start 195.07708 -65.636648)
		(end 190.361824 -65.636648)
		(width 0.12954)
		(layer "B.Cu")
		(net "NCSI_OCP_V3_2_TXD0")
	)
	(segment
		(start 145.64106 -38.759638)
		(end 126.82347 -38.759638)
		(width 0.12954)
		(layer "B.Cu")
		(net "NCSI_OCP_V3_2_TXD0")
	)
	(segment
		(start 201.67346 -66.642488)
		(end 196.08292 -66.642488)
		(width 0.12954)
		(layer "B.Cu")
		(net "NCSI_OCP_V3_2_TXD0")
	)
	(segment
		(start 109.470952 -18.43786)
		(end 106.2482 -18.43786)
		(width 0.12954)
		(layer "B.Cu")
		(net "NCSI_OCP_V3_2_TXD0")
	)
	(segment
		(start 126.82347 -38.759638)
		(end 119.85879 -31.794958)
		(width 0.12954)
		(layer "B.Cu")
		(net "NCSI_OCP_V3_2_TXD0")
	)
	(segment
		(start 201.39533 -69.603112)
		(end 202.784456 -69.603112)
		(width 0.12954)
		(layer "B.Cu")
		(net "NCSI_OCP_V3_2_TXD0")
	)
	(segment
		(start 202.784456 -69.603112)
		(end 203.18476 -69.202808)
		(width 0.12954)
		(layer "B.Cu")
		(net "NCSI_OCP_V3_2_TXD0")
	)
	(segment
		(start 154.5463 -45.481748)
		(end 151.8793 -42.814748)
		(width 0.12954)
		(layer "B.Cu")
		(net "NCSI_OCP_V3_2_TXD0")
	)
	(segment
		(start 203.18476 -68.153788)
		(end 201.67346 -66.642488)
		(width 0.12954)
		(layer "B.Cu")
		(net "NCSI_OCP_V3_2_TXD0")
	)
	(segment
		(start 196.08292 -66.642488)
		(end 195.07708 -65.636648)
		(width 0.12954)
		(layer "B.Cu")
		(net "NCSI_OCP_V3_2_TXD0")
	)
	(segment
		(start 73.262998 -8.071866)
		(end 73.262998 -5.663946)
		(width 0.127)
		(layer "In6.Cu")
		(net "NCSI_OCP_V3_2_TXD0")
	)
	(segment
		(start 73.262998 -5.663946)
		(end 72.898 -5.298948)
		(width 0.127)
		(layer "In6.Cu")
		(net "NCSI_OCP_V3_2_TXD0")
	)
	(segment
		(start 81.787746 -14.285468)
		(end 78.39456 -10.892282)
		(width 0.127)
		(layer "In6.Cu")
		(net "NCSI_OCP_V3_2_TXD0")
	)
	(segment
		(start 78.39456 -9.75233)
		(end 77.751178 -9.108948)
		(width 0.127)
		(layer "In6.Cu")
		(net "NCSI_OCP_V3_2_TXD0")
	)
	(segment
		(start 74.30008 -9.108948)
		(end 73.262998 -8.071866)
		(width 0.127)
		(layer "In6.Cu")
		(net "NCSI_OCP_V3_2_TXD0")
	)
	(segment
		(start 77.751178 -9.108948)
		(end 74.30008 -9.108948)
		(width 0.127)
		(layer "In6.Cu")
		(net "NCSI_OCP_V3_2_TXD0")
	)
	(segment
		(start 103.62438 -15.141448)
		(end 102.7684 -14.285468)
		(width 0.127)
		(layer "In6.Cu")
		(net "NCSI_OCP_V3_2_TXD0")
	)
	(segment
		(start 102.7684 -14.285468)
		(end 81.787746 -14.285468)
		(width 0.127)
		(layer "In6.Cu")
		(net "NCSI_OCP_V3_2_TXD0")
	)
	(segment
		(start 78.39456 -10.892282)
		(end 78.39456 -9.75233)
		(width 0.127)
		(layer "In6.Cu")
		(net "NCSI_OCP_V3_2_TXD0")
	)
	(segment
		(start 73.86193 -11.26998)
		(end 73.86193 -12.935458)
		(width 0.12954)
		(layer "F.Cu")
		(net "NCSI_OCP_V3_2_RXD1")
	)
	(segment
		(start 74.31786 -13.391388)
		(end 74.31786 -13.711428)
		(width 0.12954)
		(layer "F.Cu")
		(net "NCSI_OCP_V3_2_RXD1")
	)
	(segment
		(start 73.86193 -12.935458)
		(end 74.31786 -13.391388)
		(width 0.12954)
		(layer "F.Cu")
		(net "NCSI_OCP_V3_2_RXD1")
	)
	(via
		(at 101.40696 -15.931388)
		(size 0.508)
		(drill 0.254)
		(layers "F.Cu" "B.Cu")
		(net "NCSI_OCP_V3_2_RXD1")
	)
	(via
		(at 74.31786 -13.711428)
		(size 0.508)
		(drill 0.254)
		(layers "F.Cu" "B.Cu")
		(net "NCSI_OCP_V3_2_RXD1")
	)
	(segment
		(start 101.40696 -15.931388)
		(end 101.40696 -17.14373)
		(width 0.12954)
		(layer "B.Cu")
		(net "NCSI_OCP_V3_2_RXD1")
	)
	(segment
		(start 153.63952 -52.230528)
		(end 154.05354 -52.644548)
		(width 0.12954)
		(layer "B.Cu")
		(net "NCSI_OCP_V3_2_RXD1")
	)
	(segment
		(start 210.31327 -77.913738)
		(end 212.216746 -77.913738)
		(width 0.12954)
		(layer "B.Cu")
		(net "NCSI_OCP_V3_2_RXD1")
	)
	(segment
		(start 164.617908 -58.330338)
		(end 172.900848 -78.326742)
		(width 0.12954)
		(layer "B.Cu")
		(net "NCSI_OCP_V3_2_RXD1")
	)
	(segment
		(start 101.40696 -17.14373)
		(end 104.78135 -20.51812)
		(width 0.12954)
		(layer "B.Cu")
		(net "NCSI_OCP_V3_2_RXD1")
	)
	(segment
		(start 150.14448 -52.230528)
		(end 153.63952 -52.230528)
		(width 0.12954)
		(layer "B.Cu")
		(net "NCSI_OCP_V3_2_RXD1")
	)
	(segment
		(start 128.263142 -44.751498)
		(end 146.696684 -44.751498)
		(width 0.12954)
		(layer "B.Cu")
		(net "NCSI_OCP_V3_2_RXD1")
	)
	(segment
		(start 156.77388 -52.644548)
		(end 157.915864 -53.786532)
		(width 0.12954)
		(layer "B.Cu")
		(net "NCSI_OCP_V3_2_RXD1")
	)
	(segment
		(start 146.696684 -44.751498)
		(end 149.78126 -47.836074)
		(width 0.12954)
		(layer "B.Cu")
		(net "NCSI_OCP_V3_2_RXD1")
	)
	(segment
		(start 205.708504 -74.803254)
		(end 207.202786 -74.803254)
		(width 0.12954)
		(layer "B.Cu")
		(net "NCSI_OCP_V3_2_RXD1")
	)
	(segment
		(start 149.78126 -51.867308)
		(end 150.14448 -52.230528)
		(width 0.12954)
		(layer "B.Cu")
		(net "NCSI_OCP_V3_2_RXD1")
	)
	(segment
		(start 176.02708 -81.452974)
		(end 182.205376 -81.452974)
		(width 0.12954)
		(layer "B.Cu")
		(net "NCSI_OCP_V3_2_RXD1")
	)
	(segment
		(start 112.85347 -24.952198)
		(end 112.85347 -29.341826)
		(width 0.12954)
		(layer "B.Cu")
		(net "NCSI_OCP_V3_2_RXD1")
	)
	(segment
		(start 189.647322 -74.011028)
		(end 204.916278 -74.011028)
		(width 0.12954)
		(layer "B.Cu")
		(net "NCSI_OCP_V3_2_RXD1")
	)
	(segment
		(start 112.85347 -29.341826)
		(end 128.263142 -44.751498)
		(width 0.12954)
		(layer "B.Cu")
		(net "NCSI_OCP_V3_2_RXD1")
	)
	(segment
		(start 207.202786 -74.803254)
		(end 210.31327 -77.913738)
		(width 0.12954)
		(layer "B.Cu")
		(net "NCSI_OCP_V3_2_RXD1")
	)
	(segment
		(start 149.78126 -47.836074)
		(end 149.78126 -51.867308)
		(width 0.12954)
		(layer "B.Cu")
		(net "NCSI_OCP_V3_2_RXD1")
	)
	(segment
		(start 172.900848 -78.326742)
		(end 176.02708 -81.452974)
		(width 0.12954)
		(layer "B.Cu")
		(net "NCSI_OCP_V3_2_RXD1")
	)
	(segment
		(start 154.05354 -52.644548)
		(end 156.77388 -52.644548)
		(width 0.12954)
		(layer "B.Cu")
		(net "NCSI_OCP_V3_2_RXD1")
	)
	(segment
		(start 108.419392 -20.51812)
		(end 112.85347 -24.952198)
		(width 0.12954)
		(layer "B.Cu")
		(net "NCSI_OCP_V3_2_RXD1")
	)
	(segment
		(start 157.915864 -53.786532)
		(end 160.074102 -53.786532)
		(width 0.12954)
		(layer "B.Cu")
		(net "NCSI_OCP_V3_2_RXD1")
	)
	(segment
		(start 204.916278 -74.011028)
		(end 205.708504 -74.803254)
		(width 0.12954)
		(layer "B.Cu")
		(net "NCSI_OCP_V3_2_RXD1")
	)
	(segment
		(start 104.78135 -20.51812)
		(end 108.419392 -20.51812)
		(width 0.12954)
		(layer "B.Cu")
		(net "NCSI_OCP_V3_2_RXD1")
	)
	(segment
		(start 160.074102 -53.786532)
		(end 164.617908 -58.330338)
		(width 0.12954)
		(layer "B.Cu")
		(net "NCSI_OCP_V3_2_RXD1")
	)
	(segment
		(start 182.205376 -81.452974)
		(end 189.647322 -74.011028)
		(width 0.12954)
		(layer "B.Cu")
		(net "NCSI_OCP_V3_2_RXD1")
	)
	(segment
		(start 98.8949 -16.406368)
		(end 98.651822 -16.16329)
		(width 0.127)
		(layer "In6.Cu")
		(net "NCSI_OCP_V3_2_RXD1")
	)
	(segment
		(start 98.651822 -15.983458)
		(end 98.87839 -15.75689)
		(width 0.127)
		(layer "In6.Cu")
		(net "NCSI_OCP_V3_2_RXD1")
	)
	(segment
		(start 98.200972 -15.532608)
		(end 98.02114 -15.532608)
		(width 0.127)
		(layer "In6.Cu")
		(net "NCSI_OCP_V3_2_RXD1")
	)
	(segment
		(start 98.02114 -15.532608)
		(end 97.76968 -15.281148)
		(width 0.127)
		(layer "In6.Cu")
		(net "NCSI_OCP_V3_2_RXD1")
	)
	(segment
		(start 98.607372 -15.30604)
		(end 98.42754 -15.30604)
		(width 0.127)
		(layer "In6.Cu")
		(net "NCSI_OCP_V3_2_RXD1")
	)
	(segment
		(start 98.87839 -15.75689)
		(end 98.87839 -15.577058)
		(width 0.127)
		(layer "In6.Cu")
		(net "NCSI_OCP_V3_2_RXD1")
	)
	(segment
		(start 74.45502 -13.848588)
		(end 74.31786 -13.711428)
		(width 0.127)
		(layer "In6.Cu")
		(net "NCSI_OCP_V3_2_RXD1")
	)
	(segment
		(start 98.87839 -15.577058)
		(end 98.607372 -15.30604)
		(width 0.127)
		(layer "In6.Cu")
		(net "NCSI_OCP_V3_2_RXD1")
	)
	(segment
		(start 80.03032 -13.848588)
		(end 74.45502 -13.848588)
		(width 0.127)
		(layer "In6.Cu")
		(net "NCSI_OCP_V3_2_RXD1")
	)
	(segment
		(start 100.961952 -16.406368)
		(end 98.8949 -16.406368)
		(width 0.127)
		(layer "In6.Cu")
		(net "NCSI_OCP_V3_2_RXD1")
	)
	(segment
		(start 97.76968 -15.281148)
		(end 81.46288 -15.281148)
		(width 0.127)
		(layer "In6.Cu")
		(net "NCSI_OCP_V3_2_RXD1")
	)
	(segment
		(start 101.40696 -15.96136)
		(end 100.961952 -16.406368)
		(width 0.127)
		(layer "In6.Cu")
		(net "NCSI_OCP_V3_2_RXD1")
	)
	(segment
		(start 81.46288 -15.281148)
		(end 80.03032 -13.848588)
		(width 0.127)
		(layer "In6.Cu")
		(net "NCSI_OCP_V3_2_RXD1")
	)
	(segment
		(start 101.40696 -15.931388)
		(end 101.40696 -15.96136)
		(width 0.127)
		(layer "In6.Cu")
		(net "NCSI_OCP_V3_2_RXD1")
	)
	(segment
		(start 98.651822 -16.16329)
		(end 98.651822 -15.983458)
		(width 0.127)
		(layer "In6.Cu")
		(net "NCSI_OCP_V3_2_RXD1")
	)
	(segment
		(start 98.42754 -15.30604)
		(end 98.200972 -15.532608)
		(width 0.127)
		(layer "In6.Cu")
		(net "NCSI_OCP_V3_2_RXD1")
	)
	(segment
		(start 73.261982 -13.074904)
		(end 73.5076 -13.320522)
		(width 0.12954)
		(layer "F.Cu")
		(net "NCSI_OCP_V3_2_RXD0")
	)
	(segment
		(start 73.5076 -13.320522)
		(end 73.5076 -13.772388)
		(width 0.12954)
		(layer "F.Cu")
		(net "NCSI_OCP_V3_2_RXD0")
	)
	(segment
		(start 73.261982 -11.26998)
		(end 73.261982 -13.074904)
		(width 0.12954)
		(layer "F.Cu")
		(net "NCSI_OCP_V3_2_RXD0")
	)
	(via
		(at 102.1334 -15.908528)
		(size 0.508)
		(drill 0.254)
		(layers "F.Cu" "B.Cu")
		(net "NCSI_OCP_V3_2_RXD0")
	)
	(via
		(at 73.5076 -13.772388)
		(size 0.508)
		(drill 0.254)
		(layers "F.Cu" "B.Cu")
		(net "NCSI_OCP_V3_2_RXD0")
	)
	(segment
		(start 173.552612 -78.256384)
		(end 176.238662 -80.942434)
		(width 0.12954)
		(layer "B.Cu")
		(net "NCSI_OCP_V3_2_RXD0")
	)
	(segment
		(start 176.238662 -80.942434)
		(end 181.993794 -80.942434)
		(width 0.12954)
		(layer "B.Cu")
		(net "NCSI_OCP_V3_2_RXD0")
	)
	(segment
		(start 128.53797 -44.240958)
		(end 146.908266 -44.240958)
		(width 0.12954)
		(layer "B.Cu")
		(net "NCSI_OCP_V3_2_RXD0")
	)
	(segment
		(start 117.97665 -29.257498)
		(end 117.97665 -33.679638)
		(width 0.12954)
		(layer "B.Cu")
		(net "NCSI_OCP_V3_2_RXD0")
	)
	(segment
		(start 102.1334 -17.148048)
		(end 104.992932 -20.00758)
		(width 0.12954)
		(layer "B.Cu")
		(net "NCSI_OCP_V3_2_RXD0")
	)
	(segment
		(start 104.992932 -20.00758)
		(end 108.726732 -20.00758)
		(width 0.12954)
		(layer "B.Cu")
		(net "NCSI_OCP_V3_2_RXD0")
	)
	(segment
		(start 117.97665 -33.679638)
		(end 128.53797 -44.240958)
		(width 0.12954)
		(layer "B.Cu")
		(net "NCSI_OCP_V3_2_RXD0")
	)
	(segment
		(start 207.53832 -73.800208)
		(end 209.701892 -75.96378)
		(width 0.12954)
		(layer "B.Cu")
		(net "NCSI_OCP_V3_2_RXD0")
	)
	(segment
		(start 152.850596 -50.183288)
		(end 157.19298 -50.183288)
		(width 0.12954)
		(layer "B.Cu")
		(net "NCSI_OCP_V3_2_RXD0")
	)
	(segment
		(start 108.726732 -20.00758)
		(end 117.97665 -29.257498)
		(width 0.12954)
		(layer "B.Cu")
		(net "NCSI_OCP_V3_2_RXD0")
	)
	(segment
		(start 205.42758 -73.800208)
		(end 207.53832 -73.800208)
		(width 0.12954)
		(layer "B.Cu")
		(net "NCSI_OCP_V3_2_RXD0")
	)
	(segment
		(start 146.908266 -44.240958)
		(end 152.850596 -50.183288)
		(width 0.12954)
		(layer "B.Cu")
		(net "NCSI_OCP_V3_2_RXD0")
	)
	(segment
		(start 165.27018 -58.260488)
		(end 173.552612 -78.256384)
		(width 0.12954)
		(layer "B.Cu")
		(net "NCSI_OCP_V3_2_RXD0")
	)
	(segment
		(start 102.1334 -15.908528)
		(end 102.1334 -17.148048)
		(width 0.12954)
		(layer "B.Cu")
		(net "NCSI_OCP_V3_2_RXD0")
	)
	(segment
		(start 205.12786 -73.500488)
		(end 205.42758 -73.800208)
		(width 0.12954)
		(layer "B.Cu")
		(net "NCSI_OCP_V3_2_RXD0")
	)
	(segment
		(start 157.19298 -50.183288)
		(end 165.27018 -58.260488)
		(width 0.12954)
		(layer "B.Cu")
		(net "NCSI_OCP_V3_2_RXD0")
	)
	(segment
		(start 189.43574 -73.500488)
		(end 205.12786 -73.500488)
		(width 0.12954)
		(layer "B.Cu")
		(net "NCSI_OCP_V3_2_RXD0")
	)
	(segment
		(start 209.701892 -75.96378)
		(end 212.216746 -75.96378)
		(width 0.12954)
		(layer "B.Cu")
		(net "NCSI_OCP_V3_2_RXD0")
	)
	(segment
		(start 181.993794 -80.942434)
		(end 189.43574 -73.500488)
		(width 0.12954)
		(layer "B.Cu")
		(net "NCSI_OCP_V3_2_RXD0")
	)
	(segment
		(start 98.498152 -16.838168)
		(end 101.233732 -16.838168)
		(width 0.127)
		(layer "In6.Cu")
		(net "NCSI_OCP_V3_2_RXD0")
	)
	(segment
		(start 97.54108 -15.881096)
		(end 98.498152 -16.838168)
		(width 0.127)
		(layer "In6.Cu")
		(net "NCSI_OCP_V3_2_RXD0")
	)
	(segment
		(start 101.233732 -16.838168)
		(end 102.1334 -15.9385)
		(width 0.127)
		(layer "In6.Cu")
		(net "NCSI_OCP_V3_2_RXD0")
	)
	(segment
		(start 73.5076 -13.772388)
		(end 74.0156 -14.280388)
		(width 0.127)
		(layer "In6.Cu")
		(net "NCSI_OCP_V3_2_RXD0")
	)
	(segment
		(start 81.402174 -15.881096)
		(end 97.54108 -15.881096)
		(width 0.127)
		(layer "In6.Cu")
		(net "NCSI_OCP_V3_2_RXD0")
	)
	(segment
		(start 102.1334 -15.9385)
		(end 102.1334 -15.908528)
		(width 0.127)
		(layer "In6.Cu")
		(net "NCSI_OCP_V3_2_RXD0")
	)
	(segment
		(start 74.0156 -14.280388)
		(end 79.801466 -14.280388)
		(width 0.127)
		(layer "In6.Cu")
		(net "NCSI_OCP_V3_2_RXD0")
	)
	(segment
		(start 79.801466 -14.280388)
		(end 81.402174 -15.881096)
		(width 0.127)
		(layer "In6.Cu")
		(net "NCSI_OCP_V3_2_RXD0")
	)
	(segment
		(start 70.261988 -12.2301)
		(end 70.0786 -12.413488)
		(width 0.12954)
		(layer "F.Cu")
		(net "NCSI_OCP_V3_2_CRS_DV")
	)
	(segment
		(start 70.261988 -11.26998)
		(end 70.261988 -12.2301)
		(width 0.12954)
		(layer "F.Cu")
		(net "NCSI_OCP_V3_2_CRS_DV")
	)
	(via
		(at 100.68052 -15.936468)
		(size 0.508)
		(drill 0.254)
		(layers "F.Cu" "B.Cu")
		(net "NCSI_OCP_V3_2_CRS_DV")
	)
	(via
		(at 70.0786 -12.413488)
		(size 0.508)
		(drill 0.254)
		(layers "F.Cu" "B.Cu")
		(net "NCSI_OCP_V3_2_CRS_DV")
	)
	(segment
		(start 167.36441 -67.18554)
		(end 167.533574 -67.255644)
		(width 0.12954)
		(layer "B.Cu")
		(net "NCSI_OCP_V3_2_CRS_DV")
	)
	(segment
		(start 169.80535 -73.0758)
		(end 169.974514 -73.145904)
		(width 0.12954)
		(layer "B.Cu")
		(net "NCSI_OCP_V3_2_CRS_DV")
	)
	(segment
		(start 100.68052 -17.139666)
		(end 104.569514 -21.02866)
		(width 0.12954)
		(layer "B.Cu")
		(net "NCSI_OCP_V3_2_CRS_DV")
	)
	(segment
		(start 167.280336 -69.290946)
		(end 167.210232 -69.46011)
		(width 0.12954)
		(layer "B.Cu")
		(net "NCSI_OCP_V3_2_CRS_DV")
	)
	(segment
		(start 167.210232 -69.46011)
		(end 167.355266 -69.809868)
		(width 0.12954)
		(layer "B.Cu")
		(net "NCSI_OCP_V3_2_CRS_DV")
	)
	(segment
		(start 168.340786 -69.541644)
		(end 168.50995 -69.611748)
		(width 0.12954)
		(layer "B.Cu")
		(net "NCSI_OCP_V3_2_CRS_DV")
	)
	(segment
		(start 170.607736 -74.673714)
		(end 170.537632 -74.842878)
		(width 0.12954)
		(layer "B.Cu")
		(net "NCSI_OCP_V3_2_CRS_DV")
	)
	(segment
		(start 100.68052 -15.936468)
		(end 100.68052 -17.139666)
		(width 0.12954)
		(layer "B.Cu")
		(net "NCSI_OCP_V3_2_CRS_DV")
	)
	(segment
		(start 171.095924 -75.851766)
		(end 171.02582 -76.02093)
		(width 0.12954)
		(layer "B.Cu")
		(net "NCSI_OCP_V3_2_CRS_DV")
	)
	(segment
		(start 166.702232 -65.249298)
		(end 166.632128 -65.418462)
		(width 0.12954)
		(layer "B.Cu")
		(net "NCSI_OCP_V3_2_CRS_DV")
	)
	(segment
		(start 168.021762 -68.433696)
		(end 168.166796 -68.783454)
		(width 0.12954)
		(layer "B.Cu")
		(net "NCSI_OCP_V3_2_CRS_DV")
	)
	(segment
		(start 166.792148 -68.112894)
		(end 166.722044 -68.282058)
		(width 0.12954)
		(layer "B.Cu")
		(net "NCSI_OCP_V3_2_CRS_DV")
	)
	(segment
		(start 166.37889 -67.453764)
		(end 166.548054 -67.523868)
		(width 0.12954)
		(layer "B.Cu")
		(net "NCSI_OCP_V3_2_CRS_DV")
	)
	(segment
		(start 169.486326 -71.967852)
		(end 169.63136 -72.31761)
		(width 0.12954)
		(layer "B.Cu")
		(net "NCSI_OCP_V3_2_CRS_DV")
	)
	(segment
		(start 170.462702 -74.323956)
		(end 170.607736 -74.673714)
		(width 0.12954)
		(layer "B.Cu")
		(net "NCSI_OCP_V3_2_CRS_DV")
	)
	(segment
		(start 165.402514 -65.09766)
		(end 165.571678 -65.167764)
		(width 0.12954)
		(layer "B.Cu")
		(net "NCSI_OCP_V3_2_CRS_DV")
	)
	(segment
		(start 167.852598 -68.363592)
		(end 168.021762 -68.433696)
		(width 0.12954)
		(layer "B.Cu")
		(net "NCSI_OCP_V3_2_CRS_DV")
	)
	(segment
		(start 104.569514 -21.02866)
		(end 107.944412 -21.02866)
		(width 0.12954)
		(layer "B.Cu")
		(net "NCSI_OCP_V3_2_CRS_DV")
	)
	(segment
		(start 165.815772 -65.75679)
		(end 165.745668 -65.925954)
		(width 0.12954)
		(layer "B.Cu")
		(net "NCSI_OCP_V3_2_CRS_DV")
	)
	(segment
		(start 165.745668 -65.925954)
		(end 165.890702 -66.275712)
		(width 0.12954)
		(layer "B.Cu")
		(net "NCSI_OCP_V3_2_CRS_DV")
	)
	(segment
		(start 168.998138 -70.7898)
		(end 169.143172 -71.139558)
		(width 0.12954)
		(layer "B.Cu")
		(net "NCSI_OCP_V3_2_CRS_DV")
	)
	(segment
		(start 168.828974 -70.719696)
		(end 168.998138 -70.7898)
		(width 0.12954)
		(layer "B.Cu")
		(net "NCSI_OCP_V3_2_CRS_DV")
	)
	(segment
		(start 167.533574 -67.255644)
		(end 167.678608 -67.605402)
		(width 0.12954)
		(layer "B.Cu")
		(net "NCSI_OCP_V3_2_CRS_DV")
	)
	(segment
		(start 165.890702 -66.275712)
		(end 166.059866 -66.345816)
		(width 0.12954)
		(layer "B.Cu")
		(net "NCSI_OCP_V3_2_CRS_DV")
	)
	(segment
		(start 169.721276 -75.181206)
		(end 169.651172 -75.35037)
		(width 0.12954)
		(layer "B.Cu")
		(net "NCSI_OCP_V3_2_CRS_DV")
	)
	(segment
		(start 166.388034 -64.829436)
		(end 166.557198 -64.89954)
		(width 0.12954)
		(layer "B.Cu")
		(net "NCSI_OCP_V3_2_CRS_DV")
	)
	(segment
		(start 146.445224 -45.262038)
		(end 149.10562 -47.922434)
		(width 0.12954)
		(layer "B.Cu")
		(net "NCSI_OCP_V3_2_CRS_DV")
	)
	(segment
		(start 157.01264 -57.559448)
		(end 162.659314 -57.559448)
		(width 0.12954)
		(layer "B.Cu")
		(net "NCSI_OCP_V3_2_CRS_DV")
	)
	(segment
		(start 170.537632 -74.842878)
		(end 169.721276 -75.181206)
		(width 0.12954)
		(layer "B.Cu")
		(net "NCSI_OCP_V3_2_CRS_DV")
	)
	(segment
		(start 112.34293 -29.553408)
		(end 128.05156 -45.262038)
		(width 0.12954)
		(layer "B.Cu")
		(net "NCSI_OCP_V3_2_CRS_DV")
	)
	(segment
		(start 168.58488 -70.13067)
		(end 167.768524 -70.468998)
		(width 0.12954)
		(layer "B.Cu")
		(net "NCSI_OCP_V3_2_CRS_DV")
	)
	(segment
		(start 170.13936 -76.528422)
		(end 170.284394 -76.87818)
		(width 0.12954)
		(layer "B.Cu")
		(net "NCSI_OCP_V3_2_CRS_DV")
	)
	(segment
		(start 167.120316 -66.596514)
		(end 166.30396 -66.934842)
		(width 0.12954)
		(layer "B.Cu")
		(net "NCSI_OCP_V3_2_CRS_DV")
	)
	(segment
		(start 167.355266 -69.809868)
		(end 167.52443 -69.879972)
		(width 0.12954)
		(layer "B.Cu")
		(net "NCSI_OCP_V3_2_CRS_DV")
	)
	(segment
		(start 167.608504 -67.774566)
		(end 166.792148 -68.112894)
		(width 0.12954)
		(layer "B.Cu")
		(net "NCSI_OCP_V3_2_CRS_DV")
	)
	(segment
		(start 204.52842 -74.536808)
		(end 205.305406 -75.313794)
		(width 0.12954)
		(layer "B.Cu")
		(net "NCSI_OCP_V3_2_CRS_DV")
	)
	(segment
		(start 169.63136 -72.31761)
		(end 169.561256 -72.486774)
		(width 0.12954)
		(layer "B.Cu")
		(net "NCSI_OCP_V3_2_CRS_DV")
	)
	(segment
		(start 167.843454 -70.98792)
		(end 168.012618 -71.058024)
		(width 0.12954)
		(layer "B.Cu")
		(net "NCSI_OCP_V3_2_CRS_DV")
	)
	(segment
		(start 170.95089 -75.502008)
		(end 171.095924 -75.851766)
		(width 0.12954)
		(layer "B.Cu")
		(net "NCSI_OCP_V3_2_CRS_DV")
	)
	(segment
		(start 168.500806 -72.236076)
		(end 169.317162 -71.897748)
		(width 0.12954)
		(layer "B.Cu")
		(net "NCSI_OCP_V3_2_CRS_DV")
	)
	(segment
		(start 166.059866 -66.345816)
		(end 166.876222 -66.007488)
		(width 0.12954)
		(layer "B.Cu")
		(net "NCSI_OCP_V3_2_CRS_DV")
	)
	(segment
		(start 169.317162 -71.897748)
		(end 169.486326 -71.967852)
		(width 0.12954)
		(layer "B.Cu")
		(net "NCSI_OCP_V3_2_CRS_DV")
	)
	(segment
		(start 170.049444 -73.664826)
		(end 169.233088 -74.003154)
		(width 0.12954)
		(layer "B.Cu")
		(net "NCSI_OCP_V3_2_CRS_DV")
	)
	(segment
		(start 170.284394 -76.87818)
		(end 170.453558 -76.948284)
		(width 0.12954)
		(layer "B.Cu")
		(net "NCSI_OCP_V3_2_CRS_DV")
	)
	(segment
		(start 166.30396 -66.934842)
		(end 166.233856 -67.104006)
		(width 0.12954)
		(layer "B.Cu")
		(net "NCSI_OCP_V3_2_CRS_DV")
	)
	(segment
		(start 168.331642 -72.165972)
		(end 168.500806 -72.236076)
		(width 0.12954)
		(layer "B.Cu")
		(net "NCSI_OCP_V3_2_CRS_DV")
	)
	(segment
		(start 168.988994 -73.414128)
		(end 169.80535 -73.0758)
		(width 0.12954)
		(layer "B.Cu")
		(net "NCSI_OCP_V3_2_CRS_DV")
	)
	(segment
		(start 169.073068 -71.308722)
		(end 168.256712 -71.64705)
		(width 0.12954)
		(layer "B.Cu")
		(net "NCSI_OCP_V3_2_CRS_DV")
	)
	(segment
		(start 112.34293 -25.427178)
		(end 112.34293 -29.553408)
		(width 0.12954)
		(layer "B.Cu")
		(net "NCSI_OCP_V3_2_CRS_DV")
	)
	(segment
		(start 167.036242 -68.70192)
		(end 167.852598 -68.363592)
		(width 0.12954)
		(layer "B.Cu")
		(net "NCSI_OCP_V3_2_CRS_DV")
	)
	(segment
		(start 175.809148 -81.978754)
		(end 182.423308 -81.978754)
		(width 0.12954)
		(layer "B.Cu")
		(net "NCSI_OCP_V3_2_CRS_DV")
	)
	(segment
		(start 162.659314 -57.559448)
		(end 164.1221 -59.022234)
		(width 0.12954)
		(layer "B.Cu")
		(net "NCSI_OCP_V3_2_CRS_DV")
	)
	(segment
		(start 107.944412 -21.02866)
		(end 112.34293 -25.427178)
		(width 0.12954)
		(layer "B.Cu")
		(net "NCSI_OCP_V3_2_CRS_DV")
	)
	(segment
		(start 166.632128 -65.418462)
		(end 165.815772 -65.75679)
		(width 0.12954)
		(layer "B.Cu")
		(net "NCSI_OCP_V3_2_CRS_DV")
	)
	(segment
		(start 166.548054 -67.523868)
		(end 167.36441 -67.18554)
		(width 0.12954)
		(layer "B.Cu")
		(net "NCSI_OCP_V3_2_CRS_DV")
	)
	(segment
		(start 167.19042 -66.42735)
		(end 167.120316 -66.596514)
		(width 0.12954)
		(layer "B.Cu")
		(net "NCSI_OCP_V3_2_CRS_DV")
	)
	(segment
		(start 168.7449 -72.825102)
		(end 168.674796 -72.994266)
		(width 0.12954)
		(layer "B.Cu")
		(net "NCSI_OCP_V3_2_CRS_DV")
	)
	(segment
		(start 165.25748 -64.747902)
		(end 165.402514 -65.09766)
		(width 0.12954)
		(layer "B.Cu")
		(net "NCSI_OCP_V3_2_CRS_DV")
	)
	(segment
		(start 168.256712 -71.64705)
		(end 168.186608 -71.816214)
		(width 0.12954)
		(layer "B.Cu")
		(net "NCSI_OCP_V3_2_CRS_DV")
	)
	(segment
		(start 170.209464 -76.359258)
		(end 170.13936 -76.528422)
		(width 0.12954)
		(layer "B.Cu")
		(net "NCSI_OCP_V3_2_CRS_DV")
	)
	(segment
		(start 171.02582 -76.02093)
		(end 170.209464 -76.359258)
		(width 0.12954)
		(layer "B.Cu")
		(net "NCSI_OCP_V3_2_CRS_DV")
	)
	(segment
		(start 169.308018 -74.522076)
		(end 169.477182 -74.59218)
		(width 0.12954)
		(layer "B.Cu")
		(net "NCSI_OCP_V3_2_CRS_DV")
	)
	(segment
		(start 169.162984 -74.172318)
		(end 169.308018 -74.522076)
		(width 0.12954)
		(layer "B.Cu")
		(net "NCSI_OCP_V3_2_CRS_DV")
	)
	(segment
		(start 168.81983 -73.344024)
		(end 168.988994 -73.414128)
		(width 0.12954)
		(layer "B.Cu")
		(net "NCSI_OCP_V3_2_CRS_DV")
	)
	(segment
		(start 164.1221 -59.022234)
		(end 166.214044 -64.071246)
		(width 0.12954)
		(layer "B.Cu")
		(net "NCSI_OCP_V3_2_CRS_DV")
	)
	(segment
		(start 168.186608 -71.816214)
		(end 168.331642 -72.165972)
		(width 0.12954)
		(layer "B.Cu")
		(net "NCSI_OCP_V3_2_CRS_DV")
	)
	(segment
		(start 169.974514 -73.145904)
		(end 170.119548 -73.495662)
		(width 0.12954)
		(layer "B.Cu")
		(net "NCSI_OCP_V3_2_CRS_DV")
	)
	(segment
		(start 166.233856 -67.104006)
		(end 166.37889 -67.453764)
		(width 0.12954)
		(layer "B.Cu")
		(net "NCSI_OCP_V3_2_CRS_DV")
	)
	(segment
		(start 171.438824 -76.68006)
		(end 172.091604 -78.26121)
		(width 0.12954)
		(layer "B.Cu")
		(net "NCSI_OCP_V3_2_CRS_DV")
	)
	(segment
		(start 169.796206 -75.700128)
		(end 169.96537 -75.770232)
		(width 0.12954)
		(layer "B.Cu")
		(net "NCSI_OCP_V3_2_CRS_DV")
	)
	(segment
		(start 165.327584 -64.578738)
		(end 165.25748 -64.747902)
		(width 0.12954)
		(layer "B.Cu")
		(net "NCSI_OCP_V3_2_CRS_DV")
	)
	(segment
		(start 169.651172 -75.35037)
		(end 169.796206 -75.700128)
		(width 0.12954)
		(layer "B.Cu")
		(net "NCSI_OCP_V3_2_CRS_DV")
	)
	(segment
		(start 205.305406 -75.313794)
		(end 206.374746 -75.313794)
		(width 0.12954)
		(layer "B.Cu")
		(net "NCSI_OCP_V3_2_CRS_DV")
	)
	(segment
		(start 171.270168 -76.609956)
		(end 171.438824 -76.68006)
		(width 0.12954)
		(layer "B.Cu")
		(net "NCSI_OCP_V3_2_CRS_DV")
	)
	(segment
		(start 149.10562 -47.922434)
		(end 149.10562 -53.137308)
		(width 0.12954)
		(layer "B.Cu")
		(net "NCSI_OCP_V3_2_CRS_DV")
	)
	(segment
		(start 167.52443 -69.879972)
		(end 168.340786 -69.541644)
		(width 0.12954)
		(layer "B.Cu")
		(net "NCSI_OCP_V3_2_CRS_DV")
	)
	(segment
		(start 170.453558 -76.948284)
		(end 171.270168 -76.609956)
		(width 0.12954)
		(layer "B.Cu")
		(net "NCSI_OCP_V3_2_CRS_DV")
	)
	(segment
		(start 150.40102 -54.432708)
		(end 153.8859 -54.432708)
		(width 0.12954)
		(layer "B.Cu")
		(net "NCSI_OCP_V3_2_CRS_DV")
	)
	(segment
		(start 169.143172 -71.139558)
		(end 169.073068 -71.308722)
		(width 0.12954)
		(layer "B.Cu")
		(net "NCSI_OCP_V3_2_CRS_DV")
	)
	(segment
		(start 166.867078 -68.631816)
		(end 167.036242 -68.70192)
		(width 0.12954)
		(layer "B.Cu")
		(net "NCSI_OCP_V3_2_CRS_DV")
	)
	(segment
		(start 169.233088 -74.003154)
		(end 169.162984 -74.172318)
		(width 0.12954)
		(layer "B.Cu")
		(net "NCSI_OCP_V3_2_CRS_DV")
	)
	(segment
		(start 182.423308 -81.978754)
		(end 189.865254 -74.536808)
		(width 0.12954)
		(layer "B.Cu")
		(net "NCSI_OCP_V3_2_CRS_DV")
	)
	(segment
		(start 166.722044 -68.282058)
		(end 166.867078 -68.631816)
		(width 0.12954)
		(layer "B.Cu")
		(net "NCSI_OCP_V3_2_CRS_DV")
	)
	(segment
		(start 172.091604 -78.26121)
		(end 175.809148 -81.978754)
		(width 0.12954)
		(layer "B.Cu")
		(net "NCSI_OCP_V3_2_CRS_DV")
	)
	(segment
		(start 168.654984 -69.961506)
		(end 168.58488 -70.13067)
		(width 0.12954)
		(layer "B.Cu")
		(net "NCSI_OCP_V3_2_CRS_DV")
	)
	(segment
		(start 169.96537 -75.770232)
		(end 170.781726 -75.431904)
		(width 0.12954)
		(layer "B.Cu")
		(net "NCSI_OCP_V3_2_CRS_DV")
	)
	(segment
		(start 169.561256 -72.486774)
		(end 168.7449 -72.825102)
		(width 0.12954)
		(layer "B.Cu")
		(net "NCSI_OCP_V3_2_CRS_DV")
	)
	(segment
		(start 166.214044 -64.071246)
		(end 166.14394 -64.24041)
		(width 0.12954)
		(layer "B.Cu")
		(net "NCSI_OCP_V3_2_CRS_DV")
	)
	(segment
		(start 166.14394 -64.24041)
		(end 165.327584 -64.578738)
		(width 0.12954)
		(layer "B.Cu")
		(net "NCSI_OCP_V3_2_CRS_DV")
	)
	(segment
		(start 166.876222 -66.007488)
		(end 167.045386 -66.077592)
		(width 0.12954)
		(layer "B.Cu")
		(net "NCSI_OCP_V3_2_CRS_DV")
	)
	(segment
		(start 165.571678 -65.167764)
		(end 166.388034 -64.829436)
		(width 0.12954)
		(layer "B.Cu")
		(net "NCSI_OCP_V3_2_CRS_DV")
	)
	(segment
		(start 168.096692 -68.952618)
		(end 167.280336 -69.290946)
		(width 0.12954)
		(layer "B.Cu")
		(net "NCSI_OCP_V3_2_CRS_DV")
	)
	(segment
		(start 170.781726 -75.431904)
		(end 170.95089 -75.502008)
		(width 0.12954)
		(layer "B.Cu")
		(net "NCSI_OCP_V3_2_CRS_DV")
	)
	(segment
		(start 189.865254 -74.536808)
		(end 204.52842 -74.536808)
		(width 0.12954)
		(layer "B.Cu")
		(net "NCSI_OCP_V3_2_CRS_DV")
	)
	(segment
		(start 168.674796 -72.994266)
		(end 168.81983 -73.344024)
		(width 0.12954)
		(layer "B.Cu")
		(net "NCSI_OCP_V3_2_CRS_DV")
	)
	(segment
		(start 168.50995 -69.611748)
		(end 168.654984 -69.961506)
		(width 0.12954)
		(layer "B.Cu")
		(net "NCSI_OCP_V3_2_CRS_DV")
	)
	(segment
		(start 170.293538 -74.253852)
		(end 170.462702 -74.323956)
		(width 0.12954)
		(layer "B.Cu")
		(net "NCSI_OCP_V3_2_CRS_DV")
	)
	(segment
		(start 149.10562 -53.137308)
		(end 150.40102 -54.432708)
		(width 0.12954)
		(layer "B.Cu")
		(net "NCSI_OCP_V3_2_CRS_DV")
	)
	(segment
		(start 128.05156 -45.262038)
		(end 146.445224 -45.262038)
		(width 0.12954)
		(layer "B.Cu")
		(net "NCSI_OCP_V3_2_CRS_DV")
	)
	(segment
		(start 169.477182 -74.59218)
		(end 170.293538 -74.253852)
		(width 0.12954)
		(layer "B.Cu")
		(net "NCSI_OCP_V3_2_CRS_DV")
	)
	(segment
		(start 168.166796 -68.783454)
		(end 168.096692 -68.952618)
		(width 0.12954)
		(layer "B.Cu")
		(net "NCSI_OCP_V3_2_CRS_DV")
	)
	(segment
		(start 167.678608 -67.605402)
		(end 167.608504 -67.774566)
		(width 0.12954)
		(layer "B.Cu")
		(net "NCSI_OCP_V3_2_CRS_DV")
	)
	(segment
		(start 170.119548 -73.495662)
		(end 170.049444 -73.664826)
		(width 0.12954)
		(layer "B.Cu")
		(net "NCSI_OCP_V3_2_CRS_DV")
	)
	(segment
		(start 168.012618 -71.058024)
		(end 168.828974 -70.719696)
		(width 0.12954)
		(layer "B.Cu")
		(net "NCSI_OCP_V3_2_CRS_DV")
	)
	(segment
		(start 167.69842 -70.638162)
		(end 167.843454 -70.98792)
		(width 0.12954)
		(layer "B.Cu")
		(net "NCSI_OCP_V3_2_CRS_DV")
	)
	(segment
		(start 166.557198 -64.89954)
		(end 166.702232 -65.249298)
		(width 0.12954)
		(layer "B.Cu")
		(net "NCSI_OCP_V3_2_CRS_DV")
	)
	(segment
		(start 167.045386 -66.077592)
		(end 167.19042 -66.42735)
		(width 0.12954)
		(layer "B.Cu")
		(net "NCSI_OCP_V3_2_CRS_DV")
	)
	(segment
		(start 153.8859 -54.432708)
		(end 157.01264 -57.559448)
		(width 0.12954)
		(layer "B.Cu")
		(net "NCSI_OCP_V3_2_CRS_DV")
	)
	(segment
		(start 167.768524 -70.468998)
		(end 167.69842 -70.638162)
		(width 0.12954)
		(layer "B.Cu")
		(net "NCSI_OCP_V3_2_CRS_DV")
	)
	(segment
		(start 70.38848 -11.725148)
		(end 70.0786 -12.035028)
		(width 0.127)
		(layer "In6.Cu")
		(net "NCSI_OCP_V3_2_CRS_DV")
	)
	(segment
		(start 100.68052 -15.936468)
		(end 100.68052 -15.746476)
		(width 0.127)
		(layer "In6.Cu")
		(net "NCSI_OCP_V3_2_CRS_DV")
	)
	(segment
		(start 100.68052 -15.746476)
		(end 99.694492 -14.760448)
		(width 0.127)
		(layer "In6.Cu")
		(net "NCSI_OCP_V3_2_CRS_DV")
	)
	(segment
		(start 70.0786 -12.035028)
		(end 70.0786 -12.413488)
		(width 0.127)
		(layer "In6.Cu")
		(net "NCSI_OCP_V3_2_CRS_DV")
	)
	(segment
		(start 78.59268 -11.725148)
		(end 70.38848 -11.725148)
		(width 0.127)
		(layer "In6.Cu")
		(net "NCSI_OCP_V3_2_CRS_DV")
	)
	(segment
		(start 81.62798 -14.760448)
		(end 78.59268 -11.725148)
		(width 0.127)
		(layer "In6.Cu")
		(net "NCSI_OCP_V3_2_CRS_DV")
	)
	(segment
		(start 99.694492 -14.760448)
		(end 81.62798 -14.760448)
		(width 0.127)
		(layer "In6.Cu")
		(net "NCSI_OCP_V3_2_CRS_DV")
	)
	(via
		(at 193.69786 -69.603112)
		(size 0.6604)
		(drill 0.3302)
		(layers "F.Cu" "B.Cu")
		(net "NCSI_BMC_TX_EN_R1")
	)
	(segment
		(start 195.55333 -69.603112)
		(end 193.69786 -69.603112)
		(width 0.12954)
		(layer "B.Cu")
		(net "NCSI_BMC_TX_EN_R1")
	)
	(segment
		(start 193.69786 -69.603112)
		(end 192.552574 -69.603112)
		(width 0.12954)
		(layer "B.Cu")
		(net "NCSI_BMC_TX_EN_R1")
	)
	(segment
		(start 192.552574 -69.603112)
		(end 192.392808 -69.443346)
		(width 0.12954)
		(layer "B.Cu")
		(net "NCSI_BMC_TX_EN_R1")
	)
	(via
		(at 203.72578 -72.159368)
		(size 0.6604)
		(drill 0.3302)
		(layers "F.Cu" "B.Cu")
		(net "NCSI_BMC_TXD1_R1")
	)
	(segment
		(start 203.72578 -72.159368)
		(end 205.720696 -72.159368)
		(width 0.12954)
		(layer "B.Cu")
		(net "NCSI_BMC_TXD1_R1")
	)
	(segment
		(start 201.439018 -72.159368)
		(end 203.72578 -72.159368)
		(width 0.12954)
		(layer "B.Cu")
		(net "NCSI_BMC_TXD1_R1")
	)
	(segment
		(start 201.39533 -72.203056)
		(end 201.439018 -72.159368)
		(width 0.12954)
		(layer "B.Cu")
		(net "NCSI_BMC_TXD1_R1")
	)
	(segment
		(start 205.720696 -72.159368)
		(end 205.776322 -72.214994)
		(width 0.12954)
		(layer "B.Cu")
		(net "NCSI_BMC_TXD1_R1")
	)
	(via
		(at 203.66736 -70.253098)
		(size 0.6604)
		(drill 0.3302)
		(layers "F.Cu" "B.Cu")
		(net "NCSI_BMC_TXD0_R1")
	)
	(segment
		(start 205.703424 -70.253098)
		(end 205.762606 -70.31228)
		(width 0.12954)
		(layer "B.Cu")
		(net "NCSI_BMC_TXD0_R1")
	)
	(segment
		(start 201.39533 -70.253098)
		(end 203.66736 -70.253098)
		(width 0.12954)
		(layer "B.Cu")
		(net "NCSI_BMC_TXD0_R1")
	)
	(segment
		(start 203.66736 -70.253098)
		(end 205.703424 -70.253098)
		(width 0.12954)
		(layer "B.Cu")
		(net "NCSI_BMC_TXD0_R1")
	)
	(via
		(at 214.4014 -78.563724)
		(size 0.6604)
		(drill 0.3302)
		(layers "F.Cu" "B.Cu")
		(net "NCSI_BMC_RXD1_R1")
	)
	(segment
		(start 215.737694 -78.563724)
		(end 215.85301 -78.448408)
		(width 0.12954)
		(layer "B.Cu")
		(net "NCSI_BMC_RXD1_R1")
	)
	(segment
		(start 214.4014 -78.563724)
		(end 215.737694 -78.563724)
		(width 0.12954)
		(layer "B.Cu")
		(net "NCSI_BMC_RXD1_R1")
	)
	(segment
		(start 212.216746 -78.563724)
		(end 214.4014 -78.563724)
		(width 0.12954)
		(layer "B.Cu")
		(net "NCSI_BMC_RXD1_R1")
	)
	(via
		(at 214.4395 -76.613766)
		(size 0.6604)
		(drill 0.3302)
		(layers "F.Cu" "B.Cu")
		(net "NCSI_BMC_RXD0_R1")
	)
	(segment
		(start 215.790526 -76.613766)
		(end 215.812624 -76.591668)
		(width 0.12954)
		(layer "B.Cu")
		(net "NCSI_BMC_RXD0_R1")
	)
	(segment
		(start 214.4395 -76.613766)
		(end 215.790526 -76.613766)
		(width 0.12954)
		(layer "B.Cu")
		(net "NCSI_BMC_RXD0_R1")
	)
	(segment
		(start 212.216746 -76.613766)
		(end 214.4395 -76.613766)
		(width 0.12954)
		(layer "B.Cu")
		(net "NCSI_BMC_RXD0_R1")
	)
	(via
		(at 204.66685 -75.439778)
		(size 0.6604)
		(drill 0.3302)
		(layers "F.Cu" "B.Cu")
		(net "NCSI_BMC_CRS_DV_R1")
	)
	(segment
		(start 206.374746 -75.96378)
		(end 205.190852 -75.96378)
		(width 0.12954)
		(layer "B.Cu")
		(net "NCSI_BMC_CRS_DV_R1")
	)
	(segment
		(start 204.66685 -75.439778)
		(end 204.281024 -75.053952)
		(width 0.12954)
		(layer "B.Cu")
		(net "NCSI_BMC_CRS_DV_R1")
	)
	(segment
		(start 205.190852 -75.96378)
		(end 204.66685 -75.439778)
		(width 0.12954)
		(layer "B.Cu")
		(net "NCSI_BMC_CRS_DV_R1")
	)
	(segment
		(start 204.281024 -75.053952)
		(end 203.472796 -75.053952)
		(width 0.12954)
		(layer "B.Cu")
		(net "NCSI_BMC_CRS_DV_R1")
	)
	(segment
		(start 167.636444 -43.049952)
		(end 166.23538 -41.648888)
		(width 0.12954)
		(layer "F.Cu")
		(net "M2_0_PEWAKE_N")
	)
	(segment
		(start 165.69944 -41.112948)
		(end 164.92093 -41.112948)
		(width 0.12954)
		(layer "F.Cu")
		(net "M2_0_PEWAKE_N")
	)
	(segment
		(start 166.23538 -41.648888)
		(end 165.69944 -41.112948)
		(width 0.12954)
		(layer "F.Cu")
		(net "M2_0_PEWAKE_N")
	)
	(segment
		(start 169.557954 -43.049952)
		(end 167.636444 -43.049952)
		(width 0.12954)
		(layer "F.Cu")
		(net "M2_0_PEWAKE_N")
	)
	(via
		(at 166.23538 -41.648888)
		(size 0.762)
		(drill 0.381)
		(layers "F.Cu" "B.Cu")
		(net "M2_0_PEWAKE_N")
	)
	(segment
		(start 83.313524 -86.627208)
		(end 78.59776 -81.911444)
		(width 0.12954)
		(layer "F.Cu")
		(net "LED_RST_PLD_CPU0_DRAM_GH_N_D")
	)
	(segment
		(start 78.59776 -73.475088)
		(end 78.06944 -72.946768)
		(width 0.12954)
		(layer "F.Cu")
		(net "LED_RST_PLD_CPU0_DRAM_GH_N_D")
	)
	(segment
		(start 88.769444 -90.50274)
		(end 84.893912 -86.627208)
		(width 0.12954)
		(layer "F.Cu")
		(net "LED_RST_PLD_CPU0_DRAM_GH_N_D")
	)
	(segment
		(start 93.06814 -95.349568)
		(end 91.47556 -95.349568)
		(width 0.12954)
		(layer "F.Cu")
		(net "LED_RST_PLD_CPU0_DRAM_GH_N_D")
	)
	(segment
		(start 90.856054 -95.349568)
		(end 88.769444 -93.262958)
		(width 0.12954)
		(layer "F.Cu")
		(net "LED_RST_PLD_CPU0_DRAM_GH_N_D")
	)
	(segment
		(start 78.59776 -81.911444)
		(end 78.59776 -73.475088)
		(width 0.12954)
		(layer "F.Cu")
		(net "LED_RST_PLD_CPU0_DRAM_GH_N_D")
	)
	(segment
		(start 84.893912 -86.627208)
		(end 83.313524 -86.627208)
		(width 0.12954)
		(layer "F.Cu")
		(net "LED_RST_PLD_CPU0_DRAM_GH_N_D")
	)
	(segment
		(start 91.47556 -95.349568)
		(end 90.856054 -95.349568)
		(width 0.12954)
		(layer "F.Cu")
		(net "LED_RST_PLD_CPU0_DRAM_GH_N_D")
	)
	(segment
		(start 88.769444 -93.262958)
		(end 88.769444 -90.50274)
		(width 0.12954)
		(layer "F.Cu")
		(net "LED_RST_PLD_CPU0_DRAM_GH_N_D")
	)
	(segment
		(start 72.368156 -72.946768)
		(end 71.855076 -72.433688)
		(width 0.12954)
		(layer "F.Cu")
		(net "LED_RST_PLD_CPU0_DRAM_GH_N_D")
	)
	(segment
		(start 78.06944 -72.946768)
		(end 72.368156 -72.946768)
		(width 0.12954)
		(layer "F.Cu")
		(net "LED_RST_PLD_CPU0_DRAM_GH_N_D")
	)
	(segment
		(start 93.145356 -95.426784)
		(end 93.06814 -95.349568)
		(width 0.12954)
		(layer "F.Cu")
		(net "LED_RST_PLD_CPU0_DRAM_GH_N_D")
	)
	(segment
		(start 71.855076 -72.433688)
		(end 71.855076 -70.78599)
		(width 0.12954)
		(layer "F.Cu")
		(net "LED_RST_PLD_CPU0_DRAM_GH_N_D")
	)
	(via
		(at 91.47556 -95.349568)
		(size 0.762)
		(drill 0.381)
		(layers "F.Cu" "B.Cu")
		(net "LED_RST_PLD_CPU0_DRAM_GH_N_D")
	)
	(segment
		(start 70.905116 -70.78599)
		(end 70.905116 -70.349872)
		(width 0.12954)
		(layer "F.Cu")
		(net "LED_RST_PLD_CPU0_DRAM_GH_N")
	)
	(segment
		(start 72.72528 -68.529708)
		(end 72.72528 -66.739008)
		(width 0.12954)
		(layer "F.Cu")
		(net "LED_RST_PLD_CPU0_DRAM_GH_N")
	)
	(segment
		(start 72.72528 -65.523618)
		(end 72.766174 -65.482724)
		(width 0.12954)
		(layer "F.Cu")
		(net "LED_RST_PLD_CPU0_DRAM_GH_N")
	)
	(segment
		(start 70.905116 -70.349872)
		(end 72.72528 -68.529708)
		(width 0.12954)
		(layer "F.Cu")
		(net "LED_RST_PLD_CPU0_DRAM_GH_N")
	)
	(segment
		(start 72.72528 -66.739008)
		(end 72.72528 -65.523618)
		(width 0.12954)
		(layer "F.Cu")
		(net "LED_RST_PLD_CPU0_DRAM_GH_N")
	)
	(via
		(at 72.72528 -66.739008)
		(size 0.762)
		(drill 0.381)
		(layers "F.Cu" "B.Cu")
		(net "LED_RST_PLD_CPU0_DRAM_GH_N")
	)
	(segment
		(start 143.18869 -43.612308)
		(end 142.02283 -42.446448)
		(width 0.12954)
		(layer "F.Cu")
		(net "LED_M2_SSD_0_ACT_N")
	)
	(segment
		(start 168.634918 -54.04993)
		(end 169.557954 -54.04993)
		(width 0.12954)
		(layer "F.Cu")
		(net "LED_M2_SSD_0_ACT_N")
	)
	(segment
		(start 144.64538 -43.612308)
		(end 143.18869 -43.612308)
		(width 0.12954)
		(layer "F.Cu")
		(net "LED_M2_SSD_0_ACT_N")
	)
	(segment
		(start 168.29024 -54.394608)
		(end 168.634918 -54.04993)
		(width 0.12954)
		(layer "F.Cu")
		(net "LED_M2_SSD_0_ACT_N")
	)
	(via
		(at 144.64538 -43.612308)
		(size 0.508)
		(drill 0.254)
		(layers "F.Cu" "B.Cu")
		(net "LED_M2_SSD_0_ACT_N")
	)
	(via
		(at 168.29024 -54.394608)
		(size 0.508)
		(drill 0.254)
		(layers "F.Cu" "B.Cu")
		(net "LED_M2_SSD_0_ACT_N")
	)
	(segment
		(start 154.65044 -51.168808)
		(end 152.20188 -51.168808)
		(width 0.127)
		(layer "In4.Cu")
		(net "LED_M2_SSD_0_ACT_N")
	)
	(segment
		(start 167.09898 -54.394608)
		(end 163.5633 -50.858928)
		(width 0.127)
		(layer "In4.Cu")
		(net "LED_M2_SSD_0_ACT_N")
	)
	(segment
		(start 152.20188 -51.168808)
		(end 144.64538 -43.612308)
		(width 0.127)
		(layer "In4.Cu")
		(net "LED_M2_SSD_0_ACT_N")
	)
	(segment
		(start 168.29024 -54.394608)
		(end 167.09898 -54.394608)
		(width 0.127)
		(layer "In4.Cu")
		(net "LED_M2_SSD_0_ACT_N")
	)
	(segment
		(start 155.1432 -51.661568)
		(end 154.65044 -51.168808)
		(width 0.127)
		(layer "In4.Cu")
		(net "LED_M2_SSD_0_ACT_N")
	)
	(segment
		(start 156.35986 -51.661568)
		(end 155.1432 -51.661568)
		(width 0.127)
		(layer "In4.Cu")
		(net "LED_M2_SSD_0_ACT_N")
	)
	(segment
		(start 157.1625 -50.858928)
		(end 156.35986 -51.661568)
		(width 0.127)
		(layer "In4.Cu")
		(net "LED_M2_SSD_0_ACT_N")
	)
	(segment
		(start 163.5633 -50.858928)
		(end 157.1625 -50.858928)
		(width 0.127)
		(layer "In4.Cu")
		(net "LED_M2_SSD_0_ACT_N")
	)
	(segment
		(start 143.37919 -43.002708)
		(end 142.82293 -42.446448)
		(width 0.12954)
		(layer "F.Cu")
		(net "LED_HDD_ACTIVITY_N")
	)
	(segment
		(start 145.74393 -42.446448)
		(end 145.18767 -43.002708)
		(width 0.12954)
		(layer "F.Cu")
		(net "LED_HDD_ACTIVITY_N")
	)
	(segment
		(start 146.99488 -42.446448)
		(end 148.262594 -42.446448)
		(width 0.12954)
		(layer "F.Cu")
		(net "LED_HDD_ACTIVITY_N")
	)
	(segment
		(start 145.74393 -42.446448)
		(end 146.99488 -42.446448)
		(width 0.12954)
		(layer "F.Cu")
		(net "LED_HDD_ACTIVITY_N")
	)
	(segment
		(start 145.18767 -43.002708)
		(end 143.37919 -43.002708)
		(width 0.12954)
		(layer "F.Cu")
		(net "LED_HDD_ACTIVITY_N")
	)
	(segment
		(start 148.262594 -42.446448)
		(end 148.30425 -42.488104)
		(width 0.12954)
		(layer "F.Cu")
		(net "LED_HDD_ACTIVITY_N")
	)
	(via
		(at 146.99488 -42.446448)
		(size 0.762)
		(drill 0.381)
		(layers "F.Cu" "B.Cu")
		(net "LED_HDD_ACTIVITY_N")
	)
	(segment
		(start 132.317744 -21.154898)
		(end 131.32308 -21.154898)
		(width 0.12954)
		(layer "F.Cu")
		(net "TP_PCIE_HPM_TXP<3>")
	)
	(segment
		(start 132.645912 -20.82673)
		(end 132.317744 -21.154898)
		(width 0.12954)
		(layer "F.Cu")
		(net "TP_PCIE_HPM_TXP<3>")
	)
	(segment
		(start 130.946906 -16.550132)
		(end 130.946906 -18.13306)
		(width 0.12954)
		(layer "F.Cu")
		(net "TP_PCIE_HPM_TXP<3>")
	)
	(segment
		(start 132.645912 -19.832066)
		(end 132.645912 -20.82673)
		(width 0.12954)
		(layer "F.Cu")
		(net "TP_PCIE_HPM_TXP<3>")
	)
	(segment
		(start 130.946906 -18.13306)
		(end 132.645912 -19.832066)
		(width 0.12954)
		(layer "F.Cu")
		(net "TP_PCIE_HPM_TXP<3>")
	)
	(via
		(at 132.645912 -19.832066)
		(size 0.762)
		(drill 0.381)
		(layers "F.Cu" "B.Cu")
		(net "TP_PCIE_HPM_TXP<3>")
	)
	(segment
		(start 149.78126 -41.079928)
		(end 150.20417 -41.502838)
		(width 0.12954)
		(layer "F.Cu")
		(net "LED_HDD_ACTIVITY_B_N")
	)
	(segment
		(start 193.4718 -130.019298)
		(end 193.4718 -128.727708)
		(width 0.12954)
		(layer "F.Cu")
		(net "LED_HDD_ACTIVITY_B_N")
	)
	(segment
		(start 131.32308 -23.332948)
		(end 131.32308 -21.954998)
		(width 0.12954)
		(layer "F.Cu")
		(net "LED_HDD_ACTIVITY_B_N")
	)
	(segment
		(start 193.4718 -128.727708)
		(end 192.187068 -127.442976)
		(width 0.12954)
		(layer "F.Cu")
		(net "LED_HDD_ACTIVITY_B_N")
	)
	(segment
		(start 151.56688 -41.838118)
		(end 152.79116 -41.838118)
		(width 0.12954)
		(layer "F.Cu")
		(net "LED_HDD_ACTIVITY_B_N")
	)
	(segment
		(start 150.20417 -41.502838)
		(end 150.20417 -41.838118)
		(width 0.12954)
		(layer "F.Cu")
		(net "LED_HDD_ACTIVITY_B_N")
	)
	(segment
		(start 150.20417 -41.838118)
		(end 151.56688 -41.838118)
		(width 0.12954)
		(layer "F.Cu")
		(net "LED_HDD_ACTIVITY_B_N")
	)
	(segment
		(start 131.123944 -23.608792)
		(end 131.123944 -23.532084)
		(width 0.12954)
		(layer "F.Cu")
		(net "LED_HDD_ACTIVITY_B_N")
	)
	(segment
		(start 131.123944 -23.532084)
		(end 131.32308 -23.332948)
		(width 0.12954)
		(layer "F.Cu")
		(net "LED_HDD_ACTIVITY_B_N")
	)
	(segment
		(start 152.79116 -41.838118)
		(end 152.81783 -41.811448)
		(width 0.12954)
		(layer "F.Cu")
		(net "LED_HDD_ACTIVITY_B_N")
	)
	(via
		(at 149.78126 -41.079928)
		(size 0.508)
		(drill 0.254)
		(layers "F.Cu" "B.Cu")
		(net "LED_HDD_ACTIVITY_B_N")
	)
	(via
		(at 192.187068 -127.442976)
		(size 0.508)
		(drill 0.254)
		(layers "F.Cu" "B.Cu")
		(net "LED_HDD_ACTIVITY_B_N")
	)
	(via
		(at 130.98526 -37.554408)
		(size 0.508)
		(drill 0.254)
		(layers "F.Cu" "B.Cu")
		(net "LED_HDD_ACTIVITY_B_N")
	)
	(via
		(at 131.123944 -23.608792)
		(size 0.508)
		(drill 0.254)
		(layers "F.Cu" "B.Cu")
		(net "LED_HDD_ACTIVITY_B_N")
	)
	(via
		(at 151.56688 -41.838118)
		(size 0.762)
		(drill 0.381)
		(layers "F.Cu" "B.Cu")
		(net "LED_HDD_ACTIVITY_B_N")
	)
	(segment
		(start 131.123944 -24.375364)
		(end 131.123944 -23.608792)
		(width 0.127)
		(layer "In2.Cu")
		(net "LED_HDD_ACTIVITY_B_N")
	)
	(segment
		(start 132.237226 -25.488646)
		(end 131.123944 -24.375364)
		(width 0.127)
		(layer "In2.Cu")
		(net "LED_HDD_ACTIVITY_B_N")
	)
	(segment
		(start 130.98526 -27.880564)
		(end 132.237226 -26.628598)
		(width 0.127)
		(layer "In2.Cu")
		(net "LED_HDD_ACTIVITY_B_N")
	)
	(segment
		(start 130.98526 -37.554408)
		(end 130.98526 -27.880564)
		(width 0.127)
		(layer "In2.Cu")
		(net "LED_HDD_ACTIVITY_B_N")
	)
	(segment
		(start 132.237226 -26.628598)
		(end 132.237226 -25.488646)
		(width 0.127)
		(layer "In2.Cu")
		(net "LED_HDD_ACTIVITY_B_N")
	)
	(segment
		(start 149.69617 -41.165018)
		(end 147.64131 -41.165018)
		(width 0.127)
		(layer "In4.Cu")
		(net "LED_HDD_ACTIVITY_B_N")
	)
	(segment
		(start 206.12608 -108.49356)
		(end 206.12608 -112.12576)
		(width 0.127)
		(layer "In4.Cu")
		(net "LED_HDD_ACTIVITY_B_N")
	)
	(segment
		(start 208.68386 -114.68354)
		(end 208.68386 -116.0653)
		(width 0.127)
		(layer "In4.Cu")
		(net "LED_HDD_ACTIVITY_B_N")
	)
	(segment
		(start 211.54136 -118.9228)
		(end 211.54136 -123.063508)
		(width 0.127)
		(layer "In4.Cu")
		(net "LED_HDD_ACTIVITY_B_N")
	)
	(segment
		(start 182.03672 -58.791348)
		(end 186.3852 -63.139828)
		(width 0.127)
		(layer "In4.Cu")
		(net "LED_HDD_ACTIVITY_B_N")
	)
	(segment
		(start 192.510156 -127.119888)
		(end 192.187068 -127.442976)
		(width 0.127)
		(layer "In4.Cu")
		(net "LED_HDD_ACTIVITY_B_N")
	)
	(segment
		(start 208.6483 -125.956568)
		(end 205.2066 -125.956568)
		(width 0.127)
		(layer "In4.Cu")
		(net "LED_HDD_ACTIVITY_B_N")
	)
	(segment
		(start 205.2066 -125.956568)
		(end 204.76718 -126.395988)
		(width 0.127)
		(layer "In4.Cu")
		(net "LED_HDD_ACTIVITY_B_N")
	)
	(segment
		(start 136.77138 -40.190928)
		(end 143.37284 -46.792388)
		(width 0.127)
		(layer "In4.Cu")
		(net "LED_HDD_ACTIVITY_B_N")
	)
	(segment
		(start 193.19494 -90.968322)
		(end 196.892418 -94.6658)
		(width 0.127)
		(layer "In4.Cu")
		(net "LED_HDD_ACTIVITY_B_N")
	)
	(segment
		(start 145.3261 -38.849808)
		(end 136.15416 -38.849808)
		(width 0.127)
		(layer "In4.Cu")
		(net "LED_HDD_ACTIVITY_B_N")
	)
	(segment
		(start 150.31466 -51.674268)
		(end 152.94864 -54.308248)
		(width 0.127)
		(layer "In4.Cu")
		(net "LED_HDD_ACTIVITY_B_N")
	)
	(segment
		(start 147.64131 -41.165018)
		(end 145.3261 -38.849808)
		(width 0.127)
		(layer "In4.Cu")
		(net "LED_HDD_ACTIVITY_B_N")
	)
	(segment
		(start 206.12608 -112.12576)
		(end 208.68386 -114.68354)
		(width 0.127)
		(layer "In4.Cu")
		(net "LED_HDD_ACTIVITY_B_N")
	)
	(segment
		(start 196.8627 -67.661028)
		(end 194.87896 -69.644768)
		(width 0.127)
		(layer "In4.Cu")
		(net "LED_HDD_ACTIVITY_B_N")
	)
	(segment
		(start 150.31466 -50.074068)
		(end 150.31466 -51.674268)
		(width 0.127)
		(layer "In4.Cu")
		(net "LED_HDD_ACTIVITY_B_N")
	)
	(segment
		(start 130.98526 -37.554408)
		(end 133.62178 -40.190928)
		(width 0.127)
		(layer "In4.Cu")
		(net "LED_HDD_ACTIVITY_B_N")
	)
	(segment
		(start 196.892418 -94.6658)
		(end 197.797674 -94.6658)
		(width 0.127)
		(layer "In4.Cu")
		(net "LED_HDD_ACTIVITY_B_N")
	)
	(segment
		(start 136.15416 -38.849808)
		(end 134.06882 -36.764468)
		(width 0.127)
		(layer "In4.Cu")
		(net "LED_HDD_ACTIVITY_B_N")
	)
	(segment
		(start 189.42304 -70.749668)
		(end 189.42304 -74.625708)
		(width 0.127)
		(layer "In4.Cu")
		(net "LED_HDD_ACTIVITY_B_N")
	)
	(segment
		(start 163.21278 -54.308248)
		(end 167.69588 -58.791348)
		(width 0.127)
		(layer "In4.Cu")
		(net "LED_HDD_ACTIVITY_B_N")
	)
	(segment
		(start 194.87896 -69.644768)
		(end 190.52794 -69.644768)
		(width 0.127)
		(layer "In4.Cu")
		(net "LED_HDD_ACTIVITY_B_N")
	)
	(segment
		(start 186.3852 -63.139828)
		(end 192.4558 -63.139828)
		(width 0.127)
		(layer "In4.Cu")
		(net "LED_HDD_ACTIVITY_B_N")
	)
	(segment
		(start 211.54136 -123.063508)
		(end 208.6483 -125.956568)
		(width 0.127)
		(layer "In4.Cu")
		(net "LED_HDD_ACTIVITY_B_N")
	)
	(segment
		(start 189.42304 -74.625708)
		(end 191.58966 -76.792328)
		(width 0.127)
		(layer "In4.Cu")
		(net "LED_HDD_ACTIVITY_B_N")
	)
	(segment
		(start 195.62826 -127.119888)
		(end 192.510156 -127.119888)
		(width 0.127)
		(layer "In4.Cu")
		(net "LED_HDD_ACTIVITY_B_N")
	)
	(segment
		(start 149.78126 -41.079928)
		(end 149.69617 -41.165018)
		(width 0.127)
		(layer "In4.Cu")
		(net "LED_HDD_ACTIVITY_B_N")
	)
	(segment
		(start 201.94778 -104.31526)
		(end 206.12608 -108.49356)
		(width 0.127)
		(layer "In4.Cu")
		(net "LED_HDD_ACTIVITY_B_N")
	)
	(segment
		(start 167.69588 -58.791348)
		(end 182.03672 -58.791348)
		(width 0.127)
		(layer "In4.Cu")
		(net "LED_HDD_ACTIVITY_B_N")
	)
	(segment
		(start 193.19494 -84.056728)
		(end 193.19494 -90.968322)
		(width 0.127)
		(layer "In4.Cu")
		(net "LED_HDD_ACTIVITY_B_N")
	)
	(segment
		(start 134.06882 -36.764468)
		(end 131.7752 -36.764468)
		(width 0.127)
		(layer "In4.Cu")
		(net "LED_HDD_ACTIVITY_B_N")
	)
	(segment
		(start 201.018394 -124.841508)
		(end 199.197214 -126.662688)
		(width 0.127)
		(layer "In4.Cu")
		(net "LED_HDD_ACTIVITY_B_N")
	)
	(segment
		(start 147.03298 -46.792388)
		(end 150.31466 -50.074068)
		(width 0.127)
		(layer "In4.Cu")
		(net "LED_HDD_ACTIVITY_B_N")
	)
	(segment
		(start 196.08546 -126.662688)
		(end 195.62826 -127.119888)
		(width 0.127)
		(layer "In4.Cu")
		(net "LED_HDD_ACTIVITY_B_N")
	)
	(segment
		(start 190.52794 -69.644768)
		(end 189.42304 -70.749668)
		(width 0.127)
		(layer "In4.Cu")
		(net "LED_HDD_ACTIVITY_B_N")
	)
	(segment
		(start 195.83146 -64.150748)
		(end 196.8627 -65.181988)
		(width 0.127)
		(layer "In4.Cu")
		(net "LED_HDD_ACTIVITY_B_N")
	)
	(segment
		(start 193.46672 -64.150748)
		(end 195.83146 -64.150748)
		(width 0.127)
		(layer "In4.Cu")
		(net "LED_HDD_ACTIVITY_B_N")
	)
	(segment
		(start 191.58966 -82.451448)
		(end 193.19494 -84.056728)
		(width 0.127)
		(layer "In4.Cu")
		(net "LED_HDD_ACTIVITY_B_N")
	)
	(segment
		(start 208.68386 -116.0653)
		(end 211.54136 -118.9228)
		(width 0.127)
		(layer "In4.Cu")
		(net "LED_HDD_ACTIVITY_B_N")
	)
	(segment
		(start 131.7752 -36.764468)
		(end 130.98526 -37.554408)
		(width 0.127)
		(layer "In4.Cu")
		(net "LED_HDD_ACTIVITY_B_N")
	)
	(segment
		(start 192.4558 -63.139828)
		(end 193.46672 -64.150748)
		(width 0.127)
		(layer "In4.Cu")
		(net "LED_HDD_ACTIVITY_B_N")
	)
	(segment
		(start 191.58966 -76.792328)
		(end 191.58966 -82.451448)
		(width 0.127)
		(layer "In4.Cu")
		(net "LED_HDD_ACTIVITY_B_N")
	)
	(segment
		(start 152.94864 -54.308248)
		(end 163.21278 -54.308248)
		(width 0.127)
		(layer "In4.Cu")
		(net "LED_HDD_ACTIVITY_B_N")
	)
	(segment
		(start 202.1713 -124.841508)
		(end 201.018394 -124.841508)
		(width 0.127)
		(layer "In4.Cu")
		(net "LED_HDD_ACTIVITY_B_N")
	)
	(segment
		(start 203.72578 -126.395988)
		(end 202.1713 -124.841508)
		(width 0.127)
		(layer "In4.Cu")
		(net "LED_HDD_ACTIVITY_B_N")
	)
	(segment
		(start 199.197214 -126.662688)
		(end 196.08546 -126.662688)
		(width 0.127)
		(layer "In4.Cu")
		(net "LED_HDD_ACTIVITY_B_N")
	)
	(segment
		(start 143.37284 -46.792388)
		(end 147.03298 -46.792388)
		(width 0.127)
		(layer "In4.Cu")
		(net "LED_HDD_ACTIVITY_B_N")
	)
	(segment
		(start 202.61834 -99.486466)
		(end 202.61834 -102.44328)
		(width 0.127)
		(layer "In4.Cu")
		(net "LED_HDD_ACTIVITY_B_N")
	)
	(segment
		(start 204.76718 -126.395988)
		(end 203.72578 -126.395988)
		(width 0.127)
		(layer "In4.Cu")
		(net "LED_HDD_ACTIVITY_B_N")
	)
	(segment
		(start 202.61834 -102.44328)
		(end 201.94778 -103.11384)
		(width 0.127)
		(layer "In4.Cu")
		(net "LED_HDD_ACTIVITY_B_N")
	)
	(segment
		(start 196.8627 -65.181988)
		(end 196.8627 -67.661028)
		(width 0.127)
		(layer "In4.Cu")
		(net "LED_HDD_ACTIVITY_B_N")
	)
	(segment
		(start 197.797674 -94.6658)
		(end 202.61834 -99.486466)
		(width 0.127)
		(layer "In4.Cu")
		(net "LED_HDD_ACTIVITY_B_N")
	)
	(segment
		(start 201.94778 -103.11384)
		(end 201.94778 -104.31526)
		(width 0.127)
		(layer "In4.Cu")
		(net "LED_HDD_ACTIVITY_B_N")
	)
	(segment
		(start 133.62178 -40.190928)
		(end 136.77138 -40.190928)
		(width 0.127)
		(layer "In4.Cu")
		(net "LED_HDD_ACTIVITY_B_N")
	)
	(segment
		(start 279.596088 -14.143228)
		(end 280.38552 -14.143228)
		(width 0.12954)
		(layer "F.Cu")
		(net "IRQ_LVC3_V3_2_WAKE_BUF_N")
	)
	(segment
		(start 278.453088 -15.286228)
		(end 279.596088 -14.143228)
		(width 0.12954)
		(layer "F.Cu")
		(net "IRQ_LVC3_V3_2_WAKE_BUF_N")
	)
	(segment
		(start 280.440638 -14.10843)
		(end 280.430478 -14.09827)
		(width 0.12954)
		(layer "F.Cu")
		(net "IRQ_LVC3_V3_2_WAKE_BUF_N")
	)
	(segment
		(start 276.522942 -14.143228)
		(end 277.310088 -14.143228)
		(width 0.12954)
		(layer "F.Cu")
		(net "IRQ_LVC3_V3_2_WAKE_BUF_N")
	)
	(segment
		(start 280.440638 -15.247112)
		(end 280.440638 -14.10843)
		(width 0.12954)
		(layer "F.Cu")
		(net "IRQ_LVC3_V3_2_WAKE_BUF_N")
	)
	(segment
		(start 277.310088 -14.143228)
		(end 278.453088 -15.286228)
		(width 0.12954)
		(layer "F.Cu")
		(net "IRQ_LVC3_V3_2_WAKE_BUF_N")
	)
	(segment
		(start 280.38552 -14.143228)
		(end 280.430478 -14.09827)
		(width 0.12954)
		(layer "F.Cu")
		(net "IRQ_LVC3_V3_2_WAKE_BUF_N")
	)
	(via
		(at 278.453088 -15.286228)
		(size 0.762)
		(drill 0.381)
		(layers "F.Cu" "B.Cu")
		(net "IRQ_LVC3_V3_2_WAKE_BUF_N")
	)
	(segment
		(start 281.73426 -20.470368)
		(end 282.052776 -20.151852)
		(width 0.12954)
		(layer "F.Cu")
		(net "IRQ_LVC3_OCP_V3_2_WAKE_N")
	)
	(segment
		(start 282.052776 -19.699986)
		(end 280.777442 -19.699986)
		(width 0.12954)
		(layer "F.Cu")
		(net "IRQ_LVC3_OCP_V3_2_WAKE_N")
	)
	(segment
		(start 76.861924 -6.696964)
		(end 76.86294 -6.695948)
		(width 0.12954)
		(layer "F.Cu")
		(net "IRQ_LVC3_OCP_V3_2_WAKE_N")
	)
	(segment
		(start 280.356564 -19.279108)
		(end 279.364694 -19.279108)
		(width 0.12954)
		(layer "F.Cu")
		(net "IRQ_LVC3_OCP_V3_2_WAKE_N")
	)
	(segment
		(start 281.69108 -20.470368)
		(end 281.73426 -20.470368)
		(width 0.12954)
		(layer "F.Cu")
		(net "IRQ_LVC3_OCP_V3_2_WAKE_N")
	)
	(segment
		(start 280.777442 -19.699986)
		(end 280.356564 -19.279108)
		(width 0.12954)
		(layer "F.Cu")
		(net "IRQ_LVC3_OCP_V3_2_WAKE_N")
	)
	(segment
		(start 76.861924 -8.320024)
		(end 76.861924 -6.696964)
		(width 0.12954)
		(layer "F.Cu")
		(net "IRQ_LVC3_OCP_V3_2_WAKE_N")
	)
	(segment
		(start 282.052776 -20.151852)
		(end 282.052776 -19.699986)
		(width 0.12954)
		(layer "F.Cu")
		(net "IRQ_LVC3_OCP_V3_2_WAKE_N")
	)
	(via
		(at 76.86294 -6.695948)
		(size 0.508)
		(drill 0.254)
		(layers "F.Cu" "B.Cu")
		(net "IRQ_LVC3_OCP_V3_2_WAKE_N")
	)
	(via
		(at 281.69108 -20.470368)
		(size 0.508)
		(drill 0.254)
		(layers "F.Cu" "B.Cu")
		(net "IRQ_LVC3_OCP_V3_2_WAKE_N")
	)
	(via
		(at 280.777442 -19.699986)
		(size 0.762)
		(drill 0.381)
		(layers "F.Cu" "B.Cu")
		(net "IRQ_LVC3_OCP_V3_2_WAKE_N")
	)
	(segment
		(start 103.8098 -13.376148)
		(end 82.17408 -13.376148)
		(width 0.127)
		(layer "In15.Cu")
		(net "IRQ_LVC3_OCP_V3_2_WAKE_N")
	)
	(segment
		(start 220.14688 -26.761948)
		(end 218.841574 -25.456642)
		(width 0.127)
		(layer "In15.Cu")
		(net "IRQ_LVC3_OCP_V3_2_WAKE_N")
	)
	(segment
		(start 193.75628 -10.988548)
		(end 192.0748 -9.307068)
		(width 0.127)
		(layer "In15.Cu")
		(net "IRQ_LVC3_OCP_V3_2_WAKE_N")
	)
	(segment
		(start 218.841574 -22.859746)
		(end 216.620852 -20.639024)
		(width 0.127)
		(layer "In15.Cu")
		(net "IRQ_LVC3_OCP_V3_2_WAKE_N")
	)
	(segment
		(start 193.75628 -11.877548)
		(end 193.75628 -10.988548)
		(width 0.127)
		(layer "In15.Cu")
		(net "IRQ_LVC3_OCP_V3_2_WAKE_N")
	)
	(segment
		(start 140.89888 -13.553948)
		(end 138.10488 -16.347948)
		(width 0.127)
		(layer "In15.Cu")
		(net "IRQ_LVC3_OCP_V3_2_WAKE_N")
	)
	(segment
		(start 179.84724 -9.464548)
		(end 179.84724 -9.441688)
		(width 0.127)
		(layer "In15.Cu")
		(net "IRQ_LVC3_OCP_V3_2_WAKE_N")
	)
	(segment
		(start 207.44688 -14.061948)
		(end 195.94068 -14.061948)
		(width 0.127)
		(layer "In15.Cu")
		(net "IRQ_LVC3_OCP_V3_2_WAKE_N")
	)
	(segment
		(start 214.023956 -20.639024)
		(end 207.44688 -14.061948)
		(width 0.127)
		(layer "In15.Cu")
		(net "IRQ_LVC3_OCP_V3_2_WAKE_N")
	)
	(segment
		(start 106.56824 -16.134588)
		(end 103.8098 -13.376148)
		(width 0.127)
		(layer "In15.Cu")
		(net "IRQ_LVC3_OCP_V3_2_WAKE_N")
	)
	(segment
		(start 269.718028 -29.80944)
		(end 262.171434 -34.851848)
		(width 0.127)
		(layer "In15.Cu")
		(net "IRQ_LVC3_OCP_V3_2_WAKE_N")
	)
	(segment
		(start 165.66896 -9.903968)
		(end 149.50186 -9.903968)
		(width 0.127)
		(layer "In15.Cu")
		(net "IRQ_LVC3_OCP_V3_2_WAKE_N")
	)
	(segment
		(start 179.84724 -9.441688)
		(end 177.87239 -7.466838)
		(width 0.127)
		(layer "In15.Cu")
		(net "IRQ_LVC3_OCP_V3_2_WAKE_N")
	)
	(segment
		(start 182.59298 -9.464548)
		(end 182.12054 -9.936988)
		(width 0.127)
		(layer "In15.Cu")
		(net "IRQ_LVC3_OCP_V3_2_WAKE_N")
	)
	(segment
		(start 281.69108 -20.470368)
		(end 281.4447 -20.716748)
		(width 0.127)
		(layer "In15.Cu")
		(net "IRQ_LVC3_OCP_V3_2_WAKE_N")
	)
	(segment
		(start 145.85188 -13.553948)
		(end 140.89888 -13.553948)
		(width 0.127)
		(layer "In15.Cu")
		(net "IRQ_LVC3_OCP_V3_2_WAKE_N")
	)
	(segment
		(start 218.841574 -25.456642)
		(end 218.841574 -22.859746)
		(width 0.127)
		(layer "In15.Cu")
		(net "IRQ_LVC3_OCP_V3_2_WAKE_N")
	)
	(segment
		(start 149.50186 -9.903968)
		(end 145.85188 -13.553948)
		(width 0.127)
		(layer "In15.Cu")
		(net "IRQ_LVC3_OCP_V3_2_WAKE_N")
	)
	(segment
		(start 262.171434 -34.851848)
		(end 257.480816 -36.794948)
		(width 0.127)
		(layer "In15.Cu")
		(net "IRQ_LVC3_OCP_V3_2_WAKE_N")
	)
	(segment
		(start 278.81072 -20.716748)
		(end 269.718028 -29.80944)
		(width 0.127)
		(layer "In15.Cu")
		(net "IRQ_LVC3_OCP_V3_2_WAKE_N")
	)
	(segment
		(start 184.02808 -9.464548)
		(end 182.59298 -9.464548)
		(width 0.127)
		(layer "In15.Cu")
		(net "IRQ_LVC3_OCP_V3_2_WAKE_N")
	)
	(segment
		(start 281.4447 -20.716748)
		(end 278.81072 -20.716748)
		(width 0.127)
		(layer "In15.Cu")
		(net "IRQ_LVC3_OCP_V3_2_WAKE_N")
	)
	(segment
		(start 184.18556 -9.307068)
		(end 184.02808 -9.464548)
		(width 0.127)
		(layer "In15.Cu")
		(net "IRQ_LVC3_OCP_V3_2_WAKE_N")
	)
	(segment
		(start 195.94068 -14.061948)
		(end 193.75628 -11.877548)
		(width 0.127)
		(layer "In15.Cu")
		(net "IRQ_LVC3_OCP_V3_2_WAKE_N")
	)
	(segment
		(start 257.480816 -36.794948)
		(end 222.55226 -36.794948)
		(width 0.127)
		(layer "In15.Cu")
		(net "IRQ_LVC3_OCP_V3_2_WAKE_N")
	)
	(segment
		(start 180.31968 -9.936988)
		(end 179.84724 -9.464548)
		(width 0.127)
		(layer "In15.Cu")
		(net "IRQ_LVC3_OCP_V3_2_WAKE_N")
	)
	(segment
		(start 220.14688 -34.389568)
		(end 220.14688 -26.761948)
		(width 0.127)
		(layer "In15.Cu")
		(net "IRQ_LVC3_OCP_V3_2_WAKE_N")
	)
	(segment
		(start 177.87239 -7.466838)
		(end 168.10609 -7.466838)
		(width 0.127)
		(layer "In15.Cu")
		(net "IRQ_LVC3_OCP_V3_2_WAKE_N")
	)
	(segment
		(start 120.99798 -18.976848)
		(end 108.81614 -18.976848)
		(width 0.127)
		(layer "In15.Cu")
		(net "IRQ_LVC3_OCP_V3_2_WAKE_N")
	)
	(segment
		(start 123.62688 -16.347948)
		(end 120.99798 -18.976848)
		(width 0.127)
		(layer "In15.Cu")
		(net "IRQ_LVC3_OCP_V3_2_WAKE_N")
	)
	(segment
		(start 76.86294 -8.065008)
		(end 76.86294 -6.695948)
		(width 0.127)
		(layer "In15.Cu")
		(net "IRQ_LVC3_OCP_V3_2_WAKE_N")
	)
	(segment
		(start 108.81614 -18.976848)
		(end 106.56824 -16.728948)
		(width 0.127)
		(layer "In15.Cu")
		(net "IRQ_LVC3_OCP_V3_2_WAKE_N")
	)
	(segment
		(start 216.620852 -20.639024)
		(end 214.023956 -20.639024)
		(width 0.127)
		(layer "In15.Cu")
		(net "IRQ_LVC3_OCP_V3_2_WAKE_N")
	)
	(segment
		(start 82.17408 -13.376148)
		(end 76.86294 -8.065008)
		(width 0.127)
		(layer "In15.Cu")
		(net "IRQ_LVC3_OCP_V3_2_WAKE_N")
	)
	(segment
		(start 182.12054 -9.936988)
		(end 180.31968 -9.936988)
		(width 0.127)
		(layer "In15.Cu")
		(net "IRQ_LVC3_OCP_V3_2_WAKE_N")
	)
	(segment
		(start 106.56824 -16.728948)
		(end 106.56824 -16.134588)
		(width 0.127)
		(layer "In15.Cu")
		(net "IRQ_LVC3_OCP_V3_2_WAKE_N")
	)
	(segment
		(start 168.10609 -7.466838)
		(end 165.66896 -9.903968)
		(width 0.127)
		(layer "In15.Cu")
		(net "IRQ_LVC3_OCP_V3_2_WAKE_N")
	)
	(segment
		(start 192.0748 -9.307068)
		(end 184.18556 -9.307068)
		(width 0.127)
		(layer "In15.Cu")
		(net "IRQ_LVC3_OCP_V3_2_WAKE_N")
	)
	(segment
		(start 138.10488 -16.347948)
		(end 123.62688 -16.347948)
		(width 0.127)
		(layer "In15.Cu")
		(net "IRQ_LVC3_OCP_V3_2_WAKE_N")
	)
	(segment
		(start 222.55226 -36.794948)
		(end 220.14688 -34.389568)
		(width 0.127)
		(layer "In15.Cu")
		(net "IRQ_LVC3_OCP_V3_2_WAKE_N")
	)
	(segment
		(start 451.81774 -115.62461)
		(end 451.81774 -115.89766)
		(width 0.12954)
		(layer "F.Cu")
		(net "HP_OCP_V3_1_EN")
	)
	(segment
		(start 450.62902 -116.14658)
		(end 450.3801 -115.89766)
		(width 0.12954)
		(layer "F.Cu")
		(net "HP_OCP_V3_1_EN")
	)
	(segment
		(start 450.3801 -115.89766)
		(end 450.3801 -115.312444)
		(width 0.12954)
		(layer "F.Cu")
		(net "HP_OCP_V3_1_EN")
	)
	(segment
		(start 454.798684 -115.291616)
		(end 453.13854 -115.291616)
		(width 0.12954)
		(layer "F.Cu")
		(net "HP_OCP_V3_1_EN")
	)
	(segment
		(start 451.81774 -115.62461)
		(end 452.805546 -115.62461)
		(width 0.12954)
		(layer "F.Cu")
		(net "HP_OCP_V3_1_EN")
	)
	(segment
		(start 451.56882 -116.14658)
		(end 450.62902 -116.14658)
		(width 0.12954)
		(layer "F.Cu")
		(net "HP_OCP_V3_1_EN")
	)
	(segment
		(start 452.805546 -115.62461)
		(end 453.13854 -115.291616)
		(width 0.12954)
		(layer "F.Cu")
		(net "HP_OCP_V3_1_EN")
	)
	(segment
		(start 451.81774 -115.89766)
		(end 451.56882 -116.14658)
		(width 0.12954)
		(layer "F.Cu")
		(net "HP_OCP_V3_1_EN")
	)
	(via
		(at 453.13854 -115.291616)
		(size 0.762)
		(drill 0.381)
		(layers "F.Cu" "B.Cu")
		(net "HP_OCP_V3_1_EN")
	)
	(segment
		(start 101.680518 -32.781494)
		(end 101.427534 -32.781494)
		(width 0.12954)
		(layer "F.Cu")
		(net "HP_LVC3_OCP_V3_2_R_EN")
	)
	(segment
		(start 98.953574 -33.889188)
		(end 98.801174 -33.736788)
		(width 0.12954)
		(layer "F.Cu")
		(net "HP_LVC3_OCP_V3_2_R_EN")
	)
	(segment
		(start 98.801174 -33.736788)
		(end 98.73869 -33.736788)
		(width 0.12954)
		(layer "F.Cu")
		(net "HP_LVC3_OCP_V3_2_R_EN")
	)
	(segment
		(start 101.427534 -32.781494)
		(end 100.31984 -33.889188)
		(width 0.12954)
		(layer "F.Cu")
		(net "HP_LVC3_OCP_V3_2_R_EN")
	)
	(segment
		(start 100.31984 -33.889188)
		(end 100.12934 -33.889188)
		(width 0.12954)
		(layer "F.Cu")
		(net "HP_LVC3_OCP_V3_2_R_EN")
	)
	(segment
		(start 100.12934 -33.889188)
		(end 98.953574 -33.889188)
		(width 0.12954)
		(layer "F.Cu")
		(net "HP_LVC3_OCP_V3_2_R_EN")
	)
	(via
		(at 100.12934 -33.889188)
		(size 0.762)
		(drill 0.381)
		(layers "F.Cu" "B.Cu")
		(net "HP_LVC3_OCP_V3_2_R_EN")
	)
	(segment
		(start 85.40496 -39.899844)
		(end 85.40496 -41.051988)
		(width 0.12954)
		(layer "F.Cu")
		(net "HP_LVC3_OCP_V3_2_PWRGD")
	)
	(segment
		(start 85.40496 -41.051988)
		(end 85.09 -41.366948)
		(width 0.12954)
		(layer "F.Cu")
		(net "HP_LVC3_OCP_V3_2_PWRGD")
	)
	(segment
		(start 86.08695 -41.366948)
		(end 86.34095 -41.112948)
		(width 0.12954)
		(layer "F.Cu")
		(net "HP_LVC3_OCP_V3_2_PWRGD")
	)
	(segment
		(start 85.09 -41.366948)
		(end 86.08695 -41.366948)
		(width 0.12954)
		(layer "F.Cu")
		(net "HP_LVC3_OCP_V3_2_PWRGD")
	)
	(via
		(at 85.09 -41.366948)
		(size 0.762)
		(drill 0.381)
		(layers "F.Cu" "B.Cu")
		(net "HP_LVC3_OCP_V3_2_PWRGD")
	)
	(segment
		(start 25.62352 -72.471534)
		(end 25.239472 -72.471534)
		(width 0.12954)
		(layer "F.Cu")
		(net "HP_LVC3_OCP_V3_2_PRSNT2_N_R")
	)
	(segment
		(start 27.554682 -77.783944)
		(end 26.93543 -77.164692)
		(width 0.12954)
		(layer "F.Cu")
		(net "HP_LVC3_OCP_V3_2_PRSNT2_N_R")
	)
	(segment
		(start 28.177998 -69.7992)
		(end 28.177998 -70.83425)
		(width 0.12954)
		(layer "F.Cu")
		(net "HP_LVC3_OCP_V3_2_PRSNT2_N_R")
	)
	(segment
		(start 26.687272 -76.916534)
		(end 25.62352 -76.916534)
		(width 0.12954)
		(layer "F.Cu")
		(net "HP_LVC3_OCP_V3_2_PRSNT2_N_R")
	)
	(segment
		(start 27.840686 -71.171562)
		(end 25.62352 -71.171562)
		(width 0.12954)
		(layer "F.Cu")
		(net "HP_LVC3_OCP_V3_2_PRSNT2_N_R")
	)
	(segment
		(start 25.62352 -75.616562)
		(end 25.62352 -72.471534)
		(width 0.12954)
		(layer "F.Cu")
		(net "HP_LVC3_OCP_V3_2_PRSNT2_N_R")
	)
	(segment
		(start 24.97963 -72.211692)
		(end 24.97963 -71.322692)
		(width 0.12954)
		(layer "F.Cu")
		(net "HP_LVC3_OCP_V3_2_PRSNT2_N_R")
	)
	(segment
		(start 26.93543 -77.164692)
		(end 26.687272 -76.916534)
		(width 0.12954)
		(layer "F.Cu")
		(net "HP_LVC3_OCP_V3_2_PRSNT2_N_R")
	)
	(segment
		(start 25.62352 -76.916534)
		(end 25.239472 -76.916534)
		(width 0.12954)
		(layer "F.Cu")
		(net "HP_LVC3_OCP_V3_2_PRSNT2_N_R")
	)
	(segment
		(start 25.13076 -75.616562)
		(end 25.62352 -75.616562)
		(width 0.12954)
		(layer "F.Cu")
		(net "HP_LVC3_OCP_V3_2_PRSNT2_N_R")
	)
	(segment
		(start 25.13076 -71.171562)
		(end 25.62352 -71.171562)
		(width 0.12954)
		(layer "F.Cu")
		(net "HP_LVC3_OCP_V3_2_PRSNT2_N_R")
	)
	(segment
		(start 24.85263 -75.894692)
		(end 25.13076 -75.616562)
		(width 0.12954)
		(layer "F.Cu")
		(net "HP_LVC3_OCP_V3_2_PRSNT2_N_R")
	)
	(segment
		(start 25.239472 -72.471534)
		(end 24.97963 -72.211692)
		(width 0.12954)
		(layer "F.Cu")
		(net "HP_LVC3_OCP_V3_2_PRSNT2_N_R")
	)
	(segment
		(start 24.85263 -76.529692)
		(end 24.85263 -75.894692)
		(width 0.12954)
		(layer "F.Cu")
		(net "HP_LVC3_OCP_V3_2_PRSNT2_N_R")
	)
	(segment
		(start 28.177998 -70.83425)
		(end 27.840686 -71.171562)
		(width 0.12954)
		(layer "F.Cu")
		(net "HP_LVC3_OCP_V3_2_PRSNT2_N_R")
	)
	(segment
		(start 25.239472 -76.916534)
		(end 24.85263 -76.529692)
		(width 0.12954)
		(layer "F.Cu")
		(net "HP_LVC3_OCP_V3_2_PRSNT2_N_R")
	)
	(segment
		(start 28.177998 -77.783944)
		(end 27.554682 -77.783944)
		(width 0.12954)
		(layer "F.Cu")
		(net "HP_LVC3_OCP_V3_2_PRSNT2_N_R")
	)
	(segment
		(start 24.97963 -71.322692)
		(end 25.13076 -71.171562)
		(width 0.12954)
		(layer "F.Cu")
		(net "HP_LVC3_OCP_V3_2_PRSNT2_N_R")
	)
	(via
		(at 26.93543 -77.164692)
		(size 0.762)
		(drill 0.381)
		(layers "F.Cu" "B.Cu")
		(net "HP_LVC3_OCP_V3_2_PRSNT2_N_R")
	)
	(segment
		(start 133.81736 -111.841788)
		(end 134.49808 -112.522508)
		(width 0.12954)
		(layer "F.Cu")
		(net "HP_LVC3_OCP_V3_2_PRSNT2_N")
	)
	(segment
		(start 134.622286 -120.236742)
		(end 134.39648 -120.462548)
		(width 0.12954)
		(layer "F.Cu")
		(net "HP_LVC3_OCP_V3_2_PRSNT2_N")
	)
	(segment
		(start 133.58368 -116.108988)
		(end 133.58368 -120.284748)
		(width 0.12954)
		(layer "F.Cu")
		(net "HP_LVC3_OCP_V3_2_PRSNT2_N")
	)
	(segment
		(start 28.978098 -70.83425)
		(end 30.20568 -70.83425)
		(width 0.12954)
		(layer "F.Cu")
		(net "HP_LVC3_OCP_V3_2_PRSNT2_N")
	)
	(segment
		(start 137.808716 -120.236742)
		(end 134.622286 -120.236742)
		(width 0.12954)
		(layer "F.Cu")
		(net "HP_LVC3_OCP_V3_2_PRSNT2_N")
	)
	(segment
		(start 134.49808 -112.522508)
		(end 134.49808 -115.194588)
		(width 0.12954)
		(layer "F.Cu")
		(net "HP_LVC3_OCP_V3_2_PRSNT2_N")
	)
	(segment
		(start 133.58368 -120.284748)
		(end 133.55828 -120.310148)
		(width 0.12954)
		(layer "F.Cu")
		(net "HP_LVC3_OCP_V3_2_PRSNT2_N")
	)
	(segment
		(start 134.39648 -120.462548)
		(end 133.71068 -120.462548)
		(width 0.12954)
		(layer "F.Cu")
		(net "HP_LVC3_OCP_V3_2_PRSNT2_N")
	)
	(segment
		(start 134.49808 -115.194588)
		(end 133.58368 -116.108988)
		(width 0.12954)
		(layer "F.Cu")
		(net "HP_LVC3_OCP_V3_2_PRSNT2_N")
	)
	(segment
		(start 30.20568 -70.83425)
		(end 31.456376 -70.83425)
		(width 0.12954)
		(layer "F.Cu")
		(net "HP_LVC3_OCP_V3_2_PRSNT2_N")
	)
	(segment
		(start 132.750814 -111.841788)
		(end 133.81736 -111.841788)
		(width 0.12954)
		(layer "F.Cu")
		(net "HP_LVC3_OCP_V3_2_PRSNT2_N")
	)
	(segment
		(start 133.71068 -120.462548)
		(end 133.55828 -120.310148)
		(width 0.12954)
		(layer "F.Cu")
		(net "HP_LVC3_OCP_V3_2_PRSNT2_N")
	)
	(via
		(at 133.55828 -120.310148)
		(size 0.508)
		(drill 0.254)
		(layers "F.Cu" "B.Cu")
		(net "HP_LVC3_OCP_V3_2_PRSNT2_N")
	)
	(via
		(at 30.20568 -70.83425)
		(size 0.508)
		(drill 0.254)
		(layers "F.Cu" "B.Cu")
		(net "HP_LVC3_OCP_V3_2_PRSNT2_N")
	)
	(segment
		(start 133.55828 -120.310148)
		(end 133.53288 -120.335548)
		(width 0.127)
		(layer "In15.Cu")
		(net "HP_LVC3_OCP_V3_2_PRSNT2_N")
	)
	(segment
		(start 133.53288 -120.335548)
		(end 133.20268 -120.335548)
		(width 0.127)
		(layer "In15.Cu")
		(net "HP_LVC3_OCP_V3_2_PRSNT2_N")
	)
	(segment
		(start 34.82848 -81.422748)
		(end 30.20568 -76.799948)
		(width 0.127)
		(layer "In15.Cu")
		(net "HP_LVC3_OCP_V3_2_PRSNT2_N")
	)
	(segment
		(start 100.233988 -118.99138)
		(end 99.088956 -117.846348)
		(width 0.127)
		(layer "In15.Cu")
		(net "HP_LVC3_OCP_V3_2_PRSNT2_N")
	)
	(segment
		(start 99.088956 -117.846348)
		(end 89.79408 -117.846348)
		(width 0.127)
		(layer "In15.Cu")
		(net "HP_LVC3_OCP_V3_2_PRSNT2_N")
	)
	(segment
		(start 89.79408 -117.846348)
		(end 53.37048 -81.422748)
		(width 0.127)
		(layer "In15.Cu")
		(net "HP_LVC3_OCP_V3_2_PRSNT2_N")
	)
	(segment
		(start 133.20268 -120.335548)
		(end 131.858512 -118.99138)
		(width 0.127)
		(layer "In15.Cu")
		(net "HP_LVC3_OCP_V3_2_PRSNT2_N")
	)
	(segment
		(start 53.37048 -81.422748)
		(end 34.82848 -81.422748)
		(width 0.127)
		(layer "In15.Cu")
		(net "HP_LVC3_OCP_V3_2_PRSNT2_N")
	)
	(segment
		(start 131.858512 -118.99138)
		(end 100.233988 -118.99138)
		(width 0.127)
		(layer "In15.Cu")
		(net "HP_LVC3_OCP_V3_2_PRSNT2_N")
	)
	(segment
		(start 30.20568 -76.799948)
		(end 30.20568 -70.83425)
		(width 0.127)
		(layer "In15.Cu")
		(net "HP_LVC3_OCP_V3_2_PRSNT2_N")
	)
	(segment
		(start 131.364736 -116.310664)
		(end 130.550666 -115.496594)
		(width 0.12954)
		(layer "F.Cu")
		(net "HP_LVC3_OCP_V3_2_PRSNT2")
	)
	(segment
		(start 130.550666 -115.496594)
		(end 130.550666 -112.791748)
		(width 0.12954)
		(layer "F.Cu")
		(net "HP_LVC3_OCP_V3_2_PRSNT2")
	)
	(segment
		(start 131.364736 -119.425974)
		(end 131.364736 -120.891808)
		(width 0.12954)
		(layer "F.Cu")
		(net "HP_LVC3_OCP_V3_2_PRSNT2")
	)
	(segment
		(start 131.364736 -119.425974)
		(end 131.364736 -116.310664)
		(width 0.12954)
		(layer "F.Cu")
		(net "HP_LVC3_OCP_V3_2_PRSNT2")
	)
	(segment
		(start 131.364736 -122.101102)
		(end 131.32308 -122.142758)
		(width 0.12954)
		(layer "F.Cu")
		(net "HP_LVC3_OCP_V3_2_PRSNT2")
	)
	(segment
		(start 131.364736 -120.891808)
		(end 131.364736 -122.101102)
		(width 0.12954)
		(layer "F.Cu")
		(net "HP_LVC3_OCP_V3_2_PRSNT2")
	)
	(via
		(at 131.364736 -120.891808)
		(size 0.762)
		(drill 0.381)
		(layers "F.Cu" "B.Cu")
		(net "HP_LVC3_OCP_V3_2_PRSNT2")
	)
	(segment
		(start 137.808716 -119.586756)
		(end 134.97052 -119.586756)
		(width 0.12954)
		(layer "F.Cu")
		(net "TP_PCA9555_U51_P05")
	)
	(via
		(at 134.97052 -119.586756)
		(size 0.762)
		(drill 0.381)
		(layers "F.Cu" "B.Cu")
		(net "TP_PCA9555_U51_P05")
	)
	(segment
		(start 58.366406 -39.148004)
		(end 57.785 -38.566598)
		(width 0.12954)
		(layer "F.Cu")
		(net "HP_LVC3_OCP_V3_2_EN")
	)
	(segment
		(start 66.022982 -36.506658)
		(end 66.022982 -35.844988)
		(width 0.12954)
		(layer "F.Cu")
		(net "HP_LVC3_OCP_V3_2_EN")
	)
	(segment
		(start 58.53303 -39.148004)
		(end 58.366406 -39.148004)
		(width 0.12954)
		(layer "F.Cu")
		(net "HP_LVC3_OCP_V3_2_EN")
	)
	(segment
		(start 70.052438 -32.287972)
		(end 70.052438 -32.916368)
		(width 0.12954)
		(layer "F.Cu")
		(net "HP_LVC3_OCP_V3_2_EN")
	)
	(segment
		(start 59.2836 -35.143948)
		(end 65.321942 -35.143948)
		(width 0.12954)
		(layer "F.Cu")
		(net "HP_LVC3_OCP_V3_2_EN")
	)
	(segment
		(start 57.785 -36.642548)
		(end 59.2836 -35.143948)
		(width 0.12954)
		(layer "F.Cu")
		(net "HP_LVC3_OCP_V3_2_EN")
	)
	(segment
		(start 92.97924 -34.013648)
		(end 97.66173 -34.013648)
		(width 0.12954)
		(layer "F.Cu")
		(net "HP_LVC3_OCP_V3_2_EN")
	)
	(segment
		(start 65.321942 -35.143948)
		(end 66.022982 -35.844988)
		(width 0.12954)
		(layer "F.Cu")
		(net "HP_LVC3_OCP_V3_2_EN")
	)
	(segment
		(start 97.66173 -34.013648)
		(end 97.93859 -33.736788)
		(width 0.12954)
		(layer "F.Cu")
		(net "HP_LVC3_OCP_V3_2_EN")
	)
	(segment
		(start 57.785 -38.566598)
		(end 57.785 -36.642548)
		(width 0.12954)
		(layer "F.Cu")
		(net "HP_LVC3_OCP_V3_2_EN")
	)
	(segment
		(start 68.64096 -61.558678)
		(end 68.64096 -62.314328)
		(width 0.12954)
		(layer "F.Cu")
		(net "HP_LVC3_OCP_V3_2_EN")
	)
	(segment
		(start 130.414776 -117.026182)
		(end 130.414776 -116.210588)
		(width 0.12954)
		(layer "F.Cu")
		(net "HP_LVC3_OCP_V3_2_EN")
	)
	(via
		(at 68.64096 -62.314328)
		(size 0.508)
		(drill 0.254)
		(layers "F.Cu" "B.Cu")
		(net "HP_LVC3_OCP_V3_2_EN")
	)
	(via
		(at 92.97924 -34.013648)
		(size 0.508)
		(drill 0.254)
		(layers "F.Cu" "B.Cu")
		(net "HP_LVC3_OCP_V3_2_EN")
	)
	(via
		(at 130.414776 -116.210588)
		(size 0.508)
		(drill 0.254)
		(layers "F.Cu" "B.Cu")
		(net "HP_LVC3_OCP_V3_2_EN")
	)
	(via
		(at 66.022982 -35.844988)
		(size 0.508)
		(drill 0.254)
		(layers "F.Cu" "B.Cu")
		(net "HP_LVC3_OCP_V3_2_EN")
	)
	(via
		(at 70.052438 -32.916368)
		(size 0.508)
		(drill 0.254)
		(layers "F.Cu" "B.Cu")
		(net "HP_LVC3_OCP_V3_2_EN")
	)
	(segment
		(start 70.052438 -32.916368)
		(end 68.951602 -32.916368)
		(width 0.12954)
		(layer "B.Cu")
		(net "HP_LVC3_OCP_V3_2_EN")
	)
	(segment
		(start 68.951602 -32.916368)
		(end 66.022982 -35.844988)
		(width 0.12954)
		(layer "B.Cu")
		(net "HP_LVC3_OCP_V3_2_EN")
	)
	(segment
		(start 114.38128 -72.827388)
		(end 114.38128 -78.854808)
		(width 0.127)
		(layer "In2.Cu")
		(net "HP_LVC3_OCP_V3_2_EN")
	)
	(segment
		(start 130.6957 -115.929664)
		(end 130.414776 -116.210588)
		(width 0.127)
		(layer "In2.Cu")
		(net "HP_LVC3_OCP_V3_2_EN")
	)
	(segment
		(start 92.97924 -34.013648)
		(end 99.30384 -40.338248)
		(width 0.127)
		(layer "In2.Cu")
		(net "HP_LVC3_OCP_V3_2_EN")
	)
	(segment
		(start 125.93066 -97.645728)
		(end 129.08788 -100.802948)
		(width 0.127)
		(layer "In2.Cu")
		(net "HP_LVC3_OCP_V3_2_EN")
	)
	(segment
		(start 129.08788 -100.802948)
		(end 129.08788 -104.968548)
		(width 0.127)
		(layer "In2.Cu")
		(net "HP_LVC3_OCP_V3_2_EN")
	)
	(segment
		(start 113.12398 -71.570088)
		(end 114.38128 -72.827388)
		(width 0.127)
		(layer "In2.Cu")
		(net "HP_LVC3_OCP_V3_2_EN")
	)
	(segment
		(start 129.08788 -104.968548)
		(end 130.08356 -105.964228)
		(width 0.127)
		(layer "In2.Cu")
		(net "HP_LVC3_OCP_V3_2_EN")
	)
	(segment
		(start 112.51946 -51.333908)
		(end 113.12398 -51.938428)
		(width 0.127)
		(layer "In2.Cu")
		(net "HP_LVC3_OCP_V3_2_EN")
	)
	(segment
		(start 114.38128 -78.854808)
		(end 114.71402 -79.187548)
		(width 0.127)
		(layer "In2.Cu")
		(net "HP_LVC3_OCP_V3_2_EN")
	)
	(segment
		(start 114.71402 -79.187548)
		(end 114.71402 -79.614268)
		(width 0.127)
		(layer "In2.Cu")
		(net "HP_LVC3_OCP_V3_2_EN")
	)
	(segment
		(start 130.6957 -107.318048)
		(end 130.6957 -115.929664)
		(width 0.127)
		(layer "In2.Cu")
		(net "HP_LVC3_OCP_V3_2_EN")
	)
	(segment
		(start 114.71402 -79.614268)
		(end 125.93066 -90.830908)
		(width 0.127)
		(layer "In2.Cu")
		(net "HP_LVC3_OCP_V3_2_EN")
	)
	(segment
		(start 125.93066 -90.830908)
		(end 125.93066 -97.645728)
		(width 0.127)
		(layer "In2.Cu")
		(net "HP_LVC3_OCP_V3_2_EN")
	)
	(segment
		(start 99.30384 -40.338248)
		(end 105.18902 -40.338248)
		(width 0.127)
		(layer "In2.Cu")
		(net "HP_LVC3_OCP_V3_2_EN")
	)
	(segment
		(start 113.12398 -51.938428)
		(end 113.12398 -71.570088)
		(width 0.127)
		(layer "In2.Cu")
		(net "HP_LVC3_OCP_V3_2_EN")
	)
	(segment
		(start 112.51946 -47.668688)
		(end 112.51946 -51.333908)
		(width 0.127)
		(layer "In2.Cu")
		(net "HP_LVC3_OCP_V3_2_EN")
	)
	(segment
		(start 130.08356 -105.964228)
		(end 130.08356 -106.705908)
		(width 0.127)
		(layer "In2.Cu")
		(net "HP_LVC3_OCP_V3_2_EN")
	)
	(segment
		(start 105.18902 -40.338248)
		(end 112.51946 -47.668688)
		(width 0.127)
		(layer "In2.Cu")
		(net "HP_LVC3_OCP_V3_2_EN")
	)
	(segment
		(start 130.08356 -106.705908)
		(end 130.6957 -107.318048)
		(width 0.127)
		(layer "In2.Cu")
		(net "HP_LVC3_OCP_V3_2_EN")
	)
	(segment
		(start 66.022982 -35.844988)
		(end 66.022982 -36.980876)
		(width 0.127)
		(layer "In11.Cu")
		(net "HP_LVC3_OCP_V3_2_EN")
	)
	(segment
		(start 66.022982 -36.980876)
		(end 66.954654 -37.912548)
		(width 0.127)
		(layer "In11.Cu")
		(net "HP_LVC3_OCP_V3_2_EN")
	)
	(segment
		(start 74.13244 -43.954446)
		(end 74.13244 -56.822848)
		(width 0.127)
		(layer "In11.Cu")
		(net "HP_LVC3_OCP_V3_2_EN")
	)
	(segment
		(start 68.090542 -37.912548)
		(end 74.13244 -43.954446)
		(width 0.127)
		(layer "In11.Cu")
		(net "HP_LVC3_OCP_V3_2_EN")
	)
	(segment
		(start 74.13244 -56.822848)
		(end 68.64096 -62.314328)
		(width 0.127)
		(layer "In11.Cu")
		(net "HP_LVC3_OCP_V3_2_EN")
	)
	(segment
		(start 66.954654 -37.912548)
		(end 68.090542 -37.912548)
		(width 0.127)
		(layer "In11.Cu")
		(net "HP_LVC3_OCP_V3_2_EN")
	)
	(segment
		(start 71.149718 -34.013648)
		(end 70.052438 -32.916368)
		(width 0.127)
		(layer "In15.Cu")
		(net "HP_LVC3_OCP_V3_2_EN")
	)
	(segment
		(start 92.97924 -34.013648)
		(end 71.149718 -34.013648)
		(width 0.127)
		(layer "In15.Cu")
		(net "HP_LVC3_OCP_V3_2_EN")
	)
	(segment
		(start 137.808716 -120.886728)
		(end 135.48614 -120.886728)
		(width 0.12954)
		(layer "F.Cu")
		(net "HP_LVC3_OCP_V3_2_ATTN_OUT_SW_N")
	)
	(segment
		(start 30.28188 -77.783944)
		(end 31.456376 -77.783944)
		(width 0.12954)
		(layer "F.Cu")
		(net "HP_LVC3_OCP_V3_2_ATTN_OUT_SW_N")
	)
	(segment
		(start 28.978098 -77.783944)
		(end 30.28188 -77.783944)
		(width 0.12954)
		(layer "F.Cu")
		(net "HP_LVC3_OCP_V3_2_ATTN_OUT_SW_N")
	)
	(via
		(at 30.28188 -77.783944)
		(size 0.508)
		(drill 0.254)
		(layers "F.Cu" "B.Cu")
		(net "HP_LVC3_OCP_V3_2_ATTN_OUT_SW_N")
	)
	(via
		(at 135.48614 -120.886728)
		(size 0.508)
		(drill 0.254)
		(layers "F.Cu" "B.Cu")
		(net "HP_LVC3_OCP_V3_2_ATTN_OUT_SW_N")
	)
	(segment
		(start 131.62788 -119.548148)
		(end 100.323396 -119.548148)
		(width 0.127)
		(layer "In15.Cu")
		(net "HP_LVC3_OCP_V3_2_ATTN_OUT_SW_N")
	)
	(segment
		(start 53.16728 -82.006948)
		(end 34.504884 -82.006948)
		(width 0.127)
		(layer "In15.Cu")
		(net "HP_LVC3_OCP_V3_2_ATTN_OUT_SW_N")
	)
	(segment
		(start 135.48614 -120.886728)
		(end 132.96646 -120.886728)
		(width 0.127)
		(layer "In15.Cu")
		(net "HP_LVC3_OCP_V3_2_ATTN_OUT_SW_N")
	)
	(segment
		(start 34.504884 -82.006948)
		(end 30.28188 -77.783944)
		(width 0.127)
		(layer "In15.Cu")
		(net "HP_LVC3_OCP_V3_2_ATTN_OUT_SW_N")
	)
	(segment
		(start 132.96646 -120.886728)
		(end 131.62788 -119.548148)
		(width 0.127)
		(layer "In15.Cu")
		(net "HP_LVC3_OCP_V3_2_ATTN_OUT_SW_N")
	)
	(segment
		(start 99.205796 -118.430548)
		(end 89.59088 -118.430548)
		(width 0.127)
		(layer "In15.Cu")
		(net "HP_LVC3_OCP_V3_2_ATTN_OUT_SW_N")
	)
	(segment
		(start 100.323396 -119.548148)
		(end 99.205796 -118.430548)
		(width 0.127)
		(layer "In15.Cu")
		(net "HP_LVC3_OCP_V3_2_ATTN_OUT_SW_N")
	)
	(segment
		(start 89.59088 -118.430548)
		(end 53.16728 -82.006948)
		(width 0.127)
		(layer "In15.Cu")
		(net "HP_LVC3_OCP_V3_2_ATTN_OUT_SW_N")
	)
	(segment
		(start 448.246246 -42.956988)
		(end 448.68846 -42.956988)
		(width 0.12954)
		(layer "F.Cu")
		(net "HP_LVC3_OCP_V3_1_R_EN")
	)
	(segment
		(start 447.048382 -43.620182)
		(end 447.583052 -43.620182)
		(width 0.12954)
		(layer "F.Cu")
		(net "HP_LVC3_OCP_V3_1_R_EN")
	)
	(segment
		(start 448.68846 -42.956988)
		(end 449.838826 -42.956988)
		(width 0.12954)
		(layer "F.Cu")
		(net "HP_LVC3_OCP_V3_1_R_EN")
	)
	(segment
		(start 449.838826 -42.956988)
		(end 450.0372 -43.155362)
		(width 0.12954)
		(layer "F.Cu")
		(net "HP_LVC3_OCP_V3_1_R_EN")
	)
	(segment
		(start 447.583052 -43.620182)
		(end 448.246246 -42.956988)
		(width 0.12954)
		(layer "F.Cu")
		(net "HP_LVC3_OCP_V3_1_R_EN")
	)
	(via
		(at 448.68846 -42.956988)
		(size 0.762)
		(drill 0.381)
		(layers "F.Cu" "B.Cu")
		(net "HP_LVC3_OCP_V3_1_R_EN")
	)
	(segment
		(start 137.02284 -46.715934)
		(end 138.35888 -46.715934)
		(width 0.12954)
		(layer "F.Cu")
		(net "HDD_ACTIVITY_BUF_N")
	)
	(segment
		(start 141.51483 -47.589948)
		(end 142.14983 -46.954948)
		(width 0.12954)
		(layer "F.Cu")
		(net "HDD_ACTIVITY_BUF_N")
	)
	(segment
		(start 139.370816 -46.715934)
		(end 139.60983 -46.954948)
		(width 0.12954)
		(layer "F.Cu")
		(net "HDD_ACTIVITY_BUF_N")
	)
	(segment
		(start 140.24483 -47.589948)
		(end 141.51483 -47.589948)
		(width 0.12954)
		(layer "F.Cu")
		(net "HDD_ACTIVITY_BUF_N")
	)
	(segment
		(start 138.35888 -46.715934)
		(end 139.370816 -46.715934)
		(width 0.12954)
		(layer "F.Cu")
		(net "HDD_ACTIVITY_BUF_N")
	)
	(segment
		(start 139.60983 -46.954948)
		(end 140.24483 -47.589948)
		(width 0.12954)
		(layer "F.Cu")
		(net "HDD_ACTIVITY_BUF_N")
	)
	(via
		(at 138.35888 -46.715934)
		(size 0.762)
		(drill 0.381)
		(layers "F.Cu" "B.Cu")
		(net "HDD_ACTIVITY_BUF_N")
	)
	(segment
		(start 136.01954 -45.880528)
		(end 135.83412 -46.065948)
		(width 0.12954)
		(layer "F.Cu")
		(net "HDD_ACTIVITY_BUF")
	)
	(segment
		(start 136.415018 -42.49039)
		(end 136.01954 -42.885868)
		(width 0.12954)
		(layer "F.Cu")
		(net "HDD_ACTIVITY_BUF")
	)
	(segment
		(start 138.48588 -43.652948)
		(end 138.35888 -43.525948)
		(width 0.12954)
		(layer "F.Cu")
		(net "HDD_ACTIVITY_BUF")
	)
	(segment
		(start 137.323322 -42.49039)
		(end 136.868408 -42.49039)
		(width 0.12954)
		(layer "F.Cu")
		(net "HDD_ACTIVITY_BUF")
	)
	(segment
		(start 138.35888 -43.525948)
		(end 137.323322 -42.49039)
		(width 0.12954)
		(layer "F.Cu")
		(net "HDD_ACTIVITY_BUF")
	)
	(segment
		(start 136.868408 -42.49039)
		(end 136.415018 -42.49039)
		(width 0.12954)
		(layer "F.Cu")
		(net "HDD_ACTIVITY_BUF")
	)
	(segment
		(start 135.83412 -46.065948)
		(end 135.12292 -46.065948)
		(width 0.12954)
		(layer "F.Cu")
		(net "HDD_ACTIVITY_BUF")
	)
	(segment
		(start 139.60983 -43.652948)
		(end 138.48588 -43.652948)
		(width 0.12954)
		(layer "F.Cu")
		(net "HDD_ACTIVITY_BUF")
	)
	(segment
		(start 136.01954 -42.885868)
		(end 136.01954 -45.880528)
		(width 0.12954)
		(layer "F.Cu")
		(net "HDD_ACTIVITY_BUF")
	)
	(via
		(at 138.35888 -43.525948)
		(size 0.762)
		(drill 0.381)
		(layers "F.Cu" "B.Cu")
		(net "HDD_ACTIVITY_BUF")
	)
	(segment
		(start 136.370314 -125.84938)
		(end 136.370314 -126.271274)
		(width 0.12954)
		(layer "F.Cu")
		(net "FM_SMB_CPU1_ALERT")
	)
	(segment
		(start 137.808716 -124.88672)
		(end 137.332974 -124.88672)
		(width 0.12954)
		(layer "F.Cu")
		(net "FM_SMB_CPU1_ALERT")
	)
	(segment
		(start 135.5852 -127.056388)
		(end 134.61111 -127.056388)
		(width 0.12954)
		(layer "F.Cu")
		(net "FM_SMB_CPU1_ALERT")
	)
	(segment
		(start 136.002776 -126.638812)
		(end 135.5852 -127.056388)
		(width 0.12954)
		(layer "F.Cu")
		(net "FM_SMB_CPU1_ALERT")
	)
	(segment
		(start 137.332974 -124.88672)
		(end 136.370314 -125.84938)
		(width 0.12954)
		(layer "F.Cu")
		(net "FM_SMB_CPU1_ALERT")
	)
	(segment
		(start 136.370314 -126.271274)
		(end 136.002776 -126.638812)
		(width 0.12954)
		(layer "F.Cu")
		(net "FM_SMB_CPU1_ALERT")
	)
	(via
		(at 136.002776 -126.638812)
		(size 0.762)
		(drill 0.381)
		(layers "F.Cu" "B.Cu")
		(net "FM_SMB_CPU1_ALERT")
	)
	(segment
		(start 113.28908 -397.474948)
		(end 114.30508 -397.474948)
		(width 0.12954)
		(layer "F.Cu")
		(net "FM_SMB_2_ALERT_GPU_N")
	)
	(segment
		(start 113.16208 -397.347948)
		(end 113.28908 -397.474948)
		(width 0.12954)
		(layer "F.Cu")
		(net "FM_SMB_2_ALERT_GPU_N")
	)
	(segment
		(start 113.16208 -396.157958)
		(end 113.16208 -397.347948)
		(width 0.12954)
		(layer "F.Cu")
		(net "FM_SMB_2_ALERT_GPU_N")
	)
	(segment
		(start 114.30508 -397.474948)
		(end 114.94008 -397.474948)
		(width 0.12954)
		(layer "F.Cu")
		(net "FM_SMB_2_ALERT_GPU_N")
	)
	(via
		(at 114.94008 -397.474948)
		(size 0.508)
		(drill 0.254)
		(layers "F.Cu" "B.Cu")
		(net "FM_SMB_2_ALERT_GPU_N")
	)
	(segment
		(start 116.65458 -399.93062)
		(end 114.94008 -398.21612)
		(width 0.12954)
		(layer "B.Cu")
		(net "FM_SMB_2_ALERT_GPU_N")
	)
	(segment
		(start 119.25046 -399.707608)
		(end 118.942612 -399.39976)
		(width 0.12954)
		(layer "B.Cu")
		(net "FM_SMB_2_ALERT_GPU_N")
	)
	(segment
		(start 114.94008 -398.21612)
		(end 114.94008 -397.474948)
		(width 0.12954)
		(layer "B.Cu")
		(net "FM_SMB_2_ALERT_GPU_N")
	)
	(segment
		(start 117.54104 -399.93062)
		(end 116.65458 -399.93062)
		(width 0.12954)
		(layer "B.Cu")
		(net "FM_SMB_2_ALERT_GPU_N")
	)
	(segment
		(start 134.488936 -424.689778)
		(end 119.90832 -410.109162)
		(width 0.12954)
		(layer "B.Cu")
		(net "FM_SMB_2_ALERT_GPU_N")
	)
	(segment
		(start 119.00408 -407.304748)
		(end 119.00408 -400.594068)
		(width 0.12954)
		(layer "B.Cu")
		(net "FM_SMB_2_ALERT_GPU_N")
	)
	(segment
		(start 118.942612 -399.39976)
		(end 118.0719 -399.39976)
		(width 0.12954)
		(layer "B.Cu")
		(net "FM_SMB_2_ALERT_GPU_N")
	)
	(segment
		(start 118.0719 -399.39976)
		(end 117.54104 -399.93062)
		(width 0.12954)
		(layer "B.Cu")
		(net "FM_SMB_2_ALERT_GPU_N")
	)
	(segment
		(start 119.90832 -408.208988)
		(end 119.00408 -407.304748)
		(width 0.12954)
		(layer "B.Cu")
		(net "FM_SMB_2_ALERT_GPU_N")
	)
	(segment
		(start 119.25046 -400.347688)
		(end 119.25046 -399.707608)
		(width 0.12954)
		(layer "B.Cu")
		(net "FM_SMB_2_ALERT_GPU_N")
	)
	(segment
		(start 135.750046 -424.689778)
		(end 134.488936 -424.689778)
		(width 0.12954)
		(layer "B.Cu")
		(net "FM_SMB_2_ALERT_GPU_N")
	)
	(segment
		(start 119.90832 -410.109162)
		(end 119.90832 -408.208988)
		(width 0.12954)
		(layer "B.Cu")
		(net "FM_SMB_2_ALERT_GPU_N")
	)
	(segment
		(start 119.00408 -400.594068)
		(end 119.25046 -400.347688)
		(width 0.12954)
		(layer "B.Cu")
		(net "FM_SMB_2_ALERT_GPU_N")
	)
	(segment
		(start 25.06472 -424.673268)
		(end 22.444964 -424.673268)
		(width 0.12954)
		(layer "F.Cu")
		(net "FM_SMB_2_ALERT_GPU_ISO_N")
	)
	(segment
		(start 22.444964 -424.673268)
		(end 21.801582 -424.029886)
		(width 0.12954)
		(layer "F.Cu")
		(net "FM_SMB_2_ALERT_GPU_ISO_N")
	)
	(segment
		(start 112.512094 -397.235934)
		(end 112.512094 -396.157958)
		(width 0.12954)
		(layer "F.Cu")
		(net "FM_SMB_2_ALERT_GPU_ISO_N")
	)
	(segment
		(start 25.30983 -422.457118)
		(end 25.84704 -422.994328)
		(width 0.12954)
		(layer "F.Cu")
		(net "FM_SMB_2_ALERT_GPU_ISO_N")
	)
	(segment
		(start 111.25708 -397.474948)
		(end 112.27308 -397.474948)
		(width 0.12954)
		(layer "F.Cu")
		(net "FM_SMB_2_ALERT_GPU_ISO_N")
	)
	(segment
		(start 111.16818 -397.474948)
		(end 111.25708 -397.474948)
		(width 0.12954)
		(layer "F.Cu")
		(net "FM_SMB_2_ALERT_GPU_ISO_N")
	)
	(segment
		(start 110.48238 -398.160748)
		(end 111.16818 -397.474948)
		(width 0.12954)
		(layer "F.Cu")
		(net "FM_SMB_2_ALERT_GPU_ISO_N")
	)
	(segment
		(start 112.27308 -397.474948)
		(end 112.512094 -397.235934)
		(width 0.12954)
		(layer "F.Cu")
		(net "FM_SMB_2_ALERT_GPU_ISO_N")
	)
	(segment
		(start 25.84704 -422.994328)
		(end 25.84704 -423.890948)
		(width 0.12954)
		(layer "F.Cu")
		(net "FM_SMB_2_ALERT_GPU_ISO_N")
	)
	(segment
		(start 110.34522 -398.160748)
		(end 110.48238 -398.160748)
		(width 0.12954)
		(layer "F.Cu")
		(net "FM_SMB_2_ALERT_GPU_ISO_N")
	)
	(segment
		(start 25.84704 -423.890948)
		(end 25.06472 -424.673268)
		(width 0.12954)
		(layer "F.Cu")
		(net "FM_SMB_2_ALERT_GPU_ISO_N")
	)
	(via
		(at 110.34522 -398.160748)
		(size 0.508)
		(drill 0.254)
		(layers "F.Cu" "B.Cu")
		(net "FM_SMB_2_ALERT_GPU_ISO_N")
	)
	(via
		(at 25.30983 -422.457118)
		(size 0.508)
		(drill 0.254)
		(layers "F.Cu" "B.Cu")
		(net "FM_SMB_2_ALERT_GPU_ISO_N")
	)
	(segment
		(start 25.30983 -420.539418)
		(end 25.30983 -422.457118)
		(width 0.127)
		(layer "In6.Cu")
		(net "FM_SMB_2_ALERT_GPU_ISO_N")
	)
	(segment
		(start 33.25368 -408.422348)
		(end 23.02002 -408.422348)
		(width 0.127)
		(layer "In6.Cu")
		(net "FM_SMB_2_ALERT_GPU_ISO_N")
	)
	(segment
		(start 45.16628 -399.0467)
		(end 40.40378 -403.8092)
		(width 0.127)
		(layer "In6.Cu")
		(net "FM_SMB_2_ALERT_GPU_ISO_N")
	)
	(segment
		(start 55.55996 -395.519148)
		(end 52.032408 -399.0467)
		(width 0.127)
		(layer "In6.Cu")
		(net "FM_SMB_2_ALERT_GPU_ISO_N")
	)
	(segment
		(start 22.4028 -409.039568)
		(end 22.4028 -417.632388)
		(width 0.127)
		(layer "In6.Cu")
		(net "FM_SMB_2_ALERT_GPU_ISO_N")
	)
	(segment
		(start 40.40378 -403.8092)
		(end 37.866828 -403.8092)
		(width 0.127)
		(layer "In6.Cu")
		(net "FM_SMB_2_ALERT_GPU_ISO_N")
	)
	(segment
		(start 23.02002 -408.422348)
		(end 22.4028 -409.039568)
		(width 0.127)
		(layer "In6.Cu")
		(net "FM_SMB_2_ALERT_GPU_ISO_N")
	)
	(segment
		(start 98.67392 -395.519148)
		(end 55.55996 -395.519148)
		(width 0.127)
		(layer "In6.Cu")
		(net "FM_SMB_2_ALERT_GPU_ISO_N")
	)
	(segment
		(start 22.4028 -417.632388)
		(end 25.30983 -420.539418)
		(width 0.127)
		(layer "In6.Cu")
		(net "FM_SMB_2_ALERT_GPU_ISO_N")
	)
	(segment
		(start 102.07244 -398.917668)
		(end 98.67392 -395.519148)
		(width 0.127)
		(layer "In6.Cu")
		(net "FM_SMB_2_ALERT_GPU_ISO_N")
	)
	(segment
		(start 52.032408 -399.0467)
		(end 45.16628 -399.0467)
		(width 0.127)
		(layer "In6.Cu")
		(net "FM_SMB_2_ALERT_GPU_ISO_N")
	)
	(segment
		(start 109.5883 -398.917668)
		(end 102.07244 -398.917668)
		(width 0.127)
		(layer "In6.Cu")
		(net "FM_SMB_2_ALERT_GPU_ISO_N")
	)
	(segment
		(start 37.866828 -403.8092)
		(end 33.25368 -408.422348)
		(width 0.127)
		(layer "In6.Cu")
		(net "FM_SMB_2_ALERT_GPU_ISO_N")
	)
	(segment
		(start 110.34522 -398.160748)
		(end 109.5883 -398.917668)
		(width 0.127)
		(layer "In6.Cu")
		(net "FM_SMB_2_ALERT_GPU_ISO_N")
	)
	(segment
		(start 117.86108 -400.014948)
		(end 118.49608 -400.014948)
		(width 0.12954)
		(layer "F.Cu")
		(net "FM_SMB_1_ALERT_GPU_N")
	)
	(segment
		(start 116.84508 -400.014948)
		(end 117.86108 -400.014948)
		(width 0.12954)
		(layer "F.Cu")
		(net "FM_SMB_1_ALERT_GPU_N")
	)
	(segment
		(start 116.71808 -399.887948)
		(end 116.84508 -400.014948)
		(width 0.12954)
		(layer "F.Cu")
		(net "FM_SMB_1_ALERT_GPU_N")
	)
	(segment
		(start 116.71808 -398.697958)
		(end 116.71808 -399.887948)
		(width 0.12954)
		(layer "F.Cu")
		(net "FM_SMB_1_ALERT_GPU_N")
	)
	(via
		(at 118.49608 -400.014948)
		(size 0.508)
		(drill 0.254)
		(layers "F.Cu" "B.Cu")
		(net "FM_SMB_1_ALERT_GPU_N")
	)
	(segment
		(start 131.750054 -424.689778)
		(end 131.7498 -424.689524)
		(width 0.12954)
		(layer "B.Cu")
		(net "FM_SMB_1_ALERT_GPU_N")
	)
	(segment
		(start 131.7498 -423.108882)
		(end 120.263666 -411.622748)
		(width 0.12954)
		(layer "B.Cu")
		(net "FM_SMB_1_ALERT_GPU_N")
	)
	(segment
		(start 120.263666 -411.622748)
		(end 119.507 -411.622748)
		(width 0.12954)
		(layer "B.Cu")
		(net "FM_SMB_1_ALERT_GPU_N")
	)
	(segment
		(start 119.507 -411.622748)
		(end 118.49608 -410.611828)
		(width 0.12954)
		(layer "B.Cu")
		(net "FM_SMB_1_ALERT_GPU_N")
	)
	(segment
		(start 118.49608 -410.611828)
		(end 118.49608 -400.014948)
		(width 0.12954)
		(layer "B.Cu")
		(net "FM_SMB_1_ALERT_GPU_N")
	)
	(segment
		(start 131.7498 -424.689524)
		(end 131.7498 -423.108882)
		(width 0.12954)
		(layer "B.Cu")
		(net "FM_SMB_1_ALERT_GPU_N")
	)
	(segment
		(start 114.81308 -400.014948)
		(end 113.97996 -400.014948)
		(width 0.12954)
		(layer "F.Cu")
		(net "FM_SMB_1_ALERT_GPU_ISO_N")
	)
	(segment
		(start 25.013158 -424.04157)
		(end 22.935438 -424.04157)
		(width 0.12954)
		(layer "F.Cu")
		(net "FM_SMB_1_ALERT_GPU_ISO_N")
	)
	(segment
		(start 116.068094 -399.775934)
		(end 115.82908 -400.014948)
		(width 0.12954)
		(layer "F.Cu")
		(net "FM_SMB_1_ALERT_GPU_ISO_N")
	)
	(segment
		(start 115.82908 -400.014948)
		(end 114.81308 -400.014948)
		(width 0.12954)
		(layer "F.Cu")
		(net "FM_SMB_1_ALERT_GPU_ISO_N")
	)
	(segment
		(start 116.068094 -398.697958)
		(end 116.068094 -399.775934)
		(width 0.12954)
		(layer "F.Cu")
		(net "FM_SMB_1_ALERT_GPU_ISO_N")
	)
	(segment
		(start 25.2984 -423.756328)
		(end 25.013158 -424.04157)
		(width 0.12954)
		(layer "F.Cu")
		(net "FM_SMB_1_ALERT_GPU_ISO_N")
	)
	(via
		(at 113.97996 -400.014948)
		(size 0.508)
		(drill 0.254)
		(layers "F.Cu" "B.Cu")
		(net "FM_SMB_1_ALERT_GPU_ISO_N")
	)
	(via
		(at 25.2984 -423.756328)
		(size 0.508)
		(drill 0.254)
		(layers "F.Cu" "B.Cu")
		(net "FM_SMB_1_ALERT_GPU_ISO_N")
	)
	(segment
		(start 46.68266 -399.56994)
		(end 52.166774 -399.56994)
		(width 0.127)
		(layer "In6.Cu")
		(net "FM_SMB_1_ALERT_GPU_ISO_N")
	)
	(segment
		(start 112.80394 -399.486628)
		(end 113.33226 -400.014948)
		(width 0.127)
		(layer "In6.Cu")
		(net "FM_SMB_1_ALERT_GPU_ISO_N")
	)
	(segment
		(start 109.79912 -400.116548)
		(end 111.18596 -400.116548)
		(width 0.127)
		(layer "In6.Cu")
		(net "FM_SMB_1_ALERT_GPU_ISO_N")
	)
	(segment
		(start 111.81588 -399.486628)
		(end 112.80394 -399.486628)
		(width 0.127)
		(layer "In6.Cu")
		(net "FM_SMB_1_ALERT_GPU_ISO_N")
	)
	(segment
		(start 55.785766 -395.950948)
		(end 98.494596 -395.950948)
		(width 0.127)
		(layer "In6.Cu")
		(net "FM_SMB_1_ALERT_GPU_ISO_N")
	)
	(segment
		(start 109.1692 -399.486628)
		(end 109.79912 -400.116548)
		(width 0.127)
		(layer "In6.Cu")
		(net "FM_SMB_1_ALERT_GPU_ISO_N")
	)
	(segment
		(start 98.494596 -395.950948)
		(end 102.030276 -399.486628)
		(width 0.127)
		(layer "In6.Cu")
		(net "FM_SMB_1_ALERT_GPU_ISO_N")
	)
	(segment
		(start 26.21788 -419.598348)
		(end 23.8506 -417.231068)
		(width 0.127)
		(layer "In6.Cu")
		(net "FM_SMB_1_ALERT_GPU_ISO_N")
	)
	(segment
		(start 113.33226 -400.014948)
		(end 113.97996 -400.014948)
		(width 0.127)
		(layer "In6.Cu")
		(net "FM_SMB_1_ALERT_GPU_ISO_N")
	)
	(segment
		(start 25.2603 -408.887168)
		(end 33.43148 -408.887168)
		(width 0.127)
		(layer "In6.Cu")
		(net "FM_SMB_1_ALERT_GPU_ISO_N")
	)
	(segment
		(start 25.2984 -423.756328)
		(end 26.21788 -422.836848)
		(width 0.127)
		(layer "In6.Cu")
		(net "FM_SMB_1_ALERT_GPU_ISO_N")
	)
	(segment
		(start 102.030276 -399.486628)
		(end 109.1692 -399.486628)
		(width 0.127)
		(layer "In6.Cu")
		(net "FM_SMB_1_ALERT_GPU_ISO_N")
	)
	(segment
		(start 111.18596 -400.116548)
		(end 111.81588 -399.486628)
		(width 0.127)
		(layer "In6.Cu")
		(net "FM_SMB_1_ALERT_GPU_ISO_N")
	)
	(segment
		(start 33.43148 -408.887168)
		(end 38.039548 -404.2791)
		(width 0.127)
		(layer "In6.Cu")
		(net "FM_SMB_1_ALERT_GPU_ISO_N")
	)
	(segment
		(start 23.8506 -417.231068)
		(end 23.8506 -410.296868)
		(width 0.127)
		(layer "In6.Cu")
		(net "FM_SMB_1_ALERT_GPU_ISO_N")
	)
	(segment
		(start 52.166774 -399.56994)
		(end 55.785766 -395.950948)
		(width 0.127)
		(layer "In6.Cu")
		(net "FM_SMB_1_ALERT_GPU_ISO_N")
	)
	(segment
		(start 23.8506 -410.296868)
		(end 25.2603 -408.887168)
		(width 0.127)
		(layer "In6.Cu")
		(net "FM_SMB_1_ALERT_GPU_ISO_N")
	)
	(segment
		(start 26.21788 -422.836848)
		(end 26.21788 -419.598348)
		(width 0.127)
		(layer "In6.Cu")
		(net "FM_SMB_1_ALERT_GPU_ISO_N")
	)
	(segment
		(start 38.039548 -404.2791)
		(end 41.9735 -404.2791)
		(width 0.127)
		(layer "In6.Cu")
		(net "FM_SMB_1_ALERT_GPU_ISO_N")
	)
	(segment
		(start 41.9735 -404.2791)
		(end 46.68266 -399.56994)
		(width 0.127)
		(layer "In6.Cu")
		(net "FM_SMB_1_ALERT_GPU_ISO_N")
	)
	(segment
		(start 162.46348 -108.905548)
		(end 165.91788 -108.905548)
		(width 0.12954)
		(layer "F.Cu")
		(net "FM_OCP_V3_2_PWR_GOOD_R")
	)
	(segment
		(start 166.04488 -108.778548)
		(end 167.5003 -108.778548)
		(width 0.12954)
		(layer "F.Cu")
		(net "FM_OCP_V3_2_PWR_GOOD_R")
	)
	(segment
		(start 170.555666 -108.575348)
		(end 170.955716 -108.975398)
		(width 0.12954)
		(layer "F.Cu")
		(net "FM_OCP_V3_2_PWR_GOOD_R")
	)
	(segment
		(start 161.23793 -108.295948)
		(end 161.85388 -108.295948)
		(width 0.12954)
		(layer "F.Cu")
		(net "FM_OCP_V3_2_PWR_GOOD_R")
	)
	(segment
		(start 167.7035 -108.575348)
		(end 170.555666 -108.575348)
		(width 0.12954)
		(layer "F.Cu")
		(net "FM_OCP_V3_2_PWR_GOOD_R")
	)
	(segment
		(start 165.91788 -108.905548)
		(end 166.04488 -108.778548)
		(width 0.12954)
		(layer "F.Cu")
		(net "FM_OCP_V3_2_PWR_GOOD_R")
	)
	(segment
		(start 161.85388 -108.295948)
		(end 162.46348 -108.905548)
		(width 0.12954)
		(layer "F.Cu")
		(net "FM_OCP_V3_2_PWR_GOOD_R")
	)
	(segment
		(start 167.5003 -108.778548)
		(end 167.7035 -108.575348)
		(width 0.12954)
		(layer "F.Cu")
		(net "FM_OCP_V3_2_PWR_GOOD_R")
	)
	(via
		(at 161.85388 -108.295948)
		(size 0.508)
		(drill 0.254)
		(layers "F.Cu" "B.Cu")
		(net "FM_OCP_V3_2_PWR_GOOD_R")
	)
	(segment
		(start 78.062074 -11.26998)
		(end 78.062074 -11.802364)
		(width 0.12954)
		(layer "F.Cu")
		(net "FM_OCP_V3_2_PWR_GOOD")
	)
	(segment
		(start 160.43783 -108.295948)
		(end 159.82188 -108.295948)
		(width 0.12954)
		(layer "F.Cu")
		(net "FM_OCP_V3_2_PWR_GOOD")
	)
	(segment
		(start 152.70988 -124.363988)
		(end 152.70988 -123.678188)
		(width 0.12954)
		(layer "F.Cu")
		(net "FM_OCP_V3_2_PWR_GOOD")
	)
	(segment
		(start 78.062074 -11.802364)
		(end 78.388718 -12.129008)
		(width 0.12954)
		(layer "F.Cu")
		(net "FM_OCP_V3_2_PWR_GOOD")
	)
	(segment
		(start 78.388718 -12.129008)
		(end 78.388718 -12.339066)
		(width 0.12954)
		(layer "F.Cu")
		(net "FM_OCP_V3_2_PWR_GOOD")
	)
	(segment
		(start 78.388718 -12.339066)
		(end 78.8416 -12.791948)
		(width 0.12954)
		(layer "F.Cu")
		(net "FM_OCP_V3_2_PWR_GOOD")
	)
	(via
		(at 127.57404 -101.026468)
		(size 0.508)
		(drill 0.254)
		(layers "F.Cu" "B.Cu")
		(net "FM_OCP_V3_2_PWR_GOOD")
	)
	(via
		(at 152.70988 -123.678188)
		(size 0.508)
		(drill 0.254)
		(layers "F.Cu" "B.Cu")
		(net "FM_OCP_V3_2_PWR_GOOD")
	)
	(via
		(at 78.8416 -12.791948)
		(size 0.508)
		(drill 0.254)
		(layers "F.Cu" "B.Cu")
		(net "FM_OCP_V3_2_PWR_GOOD")
	)
	(via
		(at 159.82188 -108.295948)
		(size 0.508)
		(drill 0.254)
		(layers "F.Cu" "B.Cu")
		(net "FM_OCP_V3_2_PWR_GOOD")
	)
	(segment
		(start 151.73325 -111.66475)
		(end 154.340052 -109.057948)
		(width 0.12954)
		(layer "B.Cu")
		(net "FM_OCP_V3_2_PWR_GOOD")
	)
	(segment
		(start 150.749 -122.8344)
		(end 149.606 -121.6914)
		(width 0.12954)
		(layer "B.Cu")
		(net "FM_OCP_V3_2_PWR_GOOD")
	)
	(segment
		(start 78.8416 -12.791948)
		(end 77.90688 -11.857228)
		(width 0.12954)
		(layer "B.Cu")
		(net "FM_OCP_V3_2_PWR_GOOD")
	)
	(segment
		(start 152.70988 -123.678188)
		(end 152.70988 -123.383548)
		(width 0.12954)
		(layer "B.Cu")
		(net "FM_OCP_V3_2_PWR_GOOD")
	)
	(segment
		(start 152.70988 -123.383548)
		(end 152.160732 -122.8344)
		(width 0.12954)
		(layer "B.Cu")
		(net "FM_OCP_V3_2_PWR_GOOD")
	)
	(segment
		(start 159.11068 -108.295948)
		(end 159.82188 -108.295948)
		(width 0.12954)
		(layer "B.Cu")
		(net "FM_OCP_V3_2_PWR_GOOD")
	)
	(segment
		(start 149.606 -121.6914)
		(end 149.606 -116.0018)
		(width 0.12954)
		(layer "B.Cu")
		(net "FM_OCP_V3_2_PWR_GOOD")
	)
	(segment
		(start 77.90688 -11.857228)
		(end 77.90688 -11.667998)
		(width 0.12954)
		(layer "B.Cu")
		(net "FM_OCP_V3_2_PWR_GOOD")
	)
	(segment
		(start 158.34868 -109.057948)
		(end 159.11068 -108.295948)
		(width 0.12954)
		(layer "B.Cu")
		(net "FM_OCP_V3_2_PWR_GOOD")
	)
	(segment
		(start 152.160732 -122.8344)
		(end 150.749 -122.8344)
		(width 0.12954)
		(layer "B.Cu")
		(net "FM_OCP_V3_2_PWR_GOOD")
	)
	(segment
		(start 149.606 -116.0018)
		(end 150.67788 -114.92992)
		(width 0.12954)
		(layer "B.Cu")
		(net "FM_OCP_V3_2_PWR_GOOD")
	)
	(segment
		(start 151.73325 -111.894874)
		(end 151.73325 -111.66475)
		(width 0.12954)
		(layer "B.Cu")
		(net "FM_OCP_V3_2_PWR_GOOD")
	)
	(segment
		(start 150.67788 -114.92992)
		(end 150.67788 -112.950244)
		(width 0.12954)
		(layer "B.Cu")
		(net "FM_OCP_V3_2_PWR_GOOD")
	)
	(segment
		(start 150.67788 -112.950244)
		(end 151.73325 -111.894874)
		(width 0.12954)
		(layer "B.Cu")
		(net "FM_OCP_V3_2_PWR_GOOD")
	)
	(segment
		(start 154.340052 -109.057948)
		(end 158.34868 -109.057948)
		(width 0.12954)
		(layer "B.Cu")
		(net "FM_OCP_V3_2_PWR_GOOD")
	)
	(segment
		(start 113.95964 -79.026004)
		(end 114.3 -79.366364)
		(width 0.127)
		(layer "In2.Cu")
		(net "FM_OCP_V3_2_PWR_GOOD")
	)
	(segment
		(start 114.3 -80.198468)
		(end 125.27026 -91.168728)
		(width 0.127)
		(layer "In2.Cu")
		(net "FM_OCP_V3_2_PWR_GOOD")
	)
	(segment
		(start 112.18926 -47.805848)
		(end 112.18926 -51.471068)
		(width 0.127)
		(layer "In2.Cu")
		(net "FM_OCP_V3_2_PWR_GOOD")
	)
	(segment
		(start 87.55888 -19.091148)
		(end 87.55888 -29.60243)
		(width 0.127)
		(layer "In2.Cu")
		(net "FM_OCP_V3_2_PWR_GOOD")
	)
	(segment
		(start 105.05186 -40.668448)
		(end 112.18926 -47.805848)
		(width 0.127)
		(layer "In2.Cu")
		(net "FM_OCP_V3_2_PWR_GOOD")
	)
	(segment
		(start 112.79378 -71.709788)
		(end 113.95964 -72.875648)
		(width 0.127)
		(layer "In2.Cu")
		(net "FM_OCP_V3_2_PWR_GOOD")
	)
	(segment
		(start 112.79378 -52.075588)
		(end 112.79378 -71.709788)
		(width 0.127)
		(layer "In2.Cu")
		(net "FM_OCP_V3_2_PWR_GOOD")
	)
	(segment
		(start 78.8416 -12.791948)
		(end 79.297276 -12.791948)
		(width 0.127)
		(layer "In2.Cu")
		(net "FM_OCP_V3_2_PWR_GOOD")
	)
	(segment
		(start 114.3 -79.366364)
		(end 114.3 -80.198468)
		(width 0.127)
		(layer "In2.Cu")
		(net "FM_OCP_V3_2_PWR_GOOD")
	)
	(segment
		(start 112.18926 -51.471068)
		(end 112.79378 -52.075588)
		(width 0.127)
		(layer "In2.Cu")
		(net "FM_OCP_V3_2_PWR_GOOD")
	)
	(segment
		(start 125.27026 -98.722688)
		(end 127.57404 -101.026468)
		(width 0.127)
		(layer "In2.Cu")
		(net "FM_OCP_V3_2_PWR_GOOD")
	)
	(segment
		(start 98.624898 -40.668448)
		(end 105.05186 -40.668448)
		(width 0.127)
		(layer "In2.Cu")
		(net "FM_OCP_V3_2_PWR_GOOD")
	)
	(segment
		(start 125.27026 -91.168728)
		(end 125.27026 -98.722688)
		(width 0.127)
		(layer "In2.Cu")
		(net "FM_OCP_V3_2_PWR_GOOD")
	)
	(segment
		(start 82.065876 -15.560548)
		(end 84.02828 -15.560548)
		(width 0.127)
		(layer "In2.Cu")
		(net "FM_OCP_V3_2_PWR_GOOD")
	)
	(segment
		(start 113.95964 -72.875648)
		(end 113.95964 -79.026004)
		(width 0.127)
		(layer "In2.Cu")
		(net "FM_OCP_V3_2_PWR_GOOD")
	)
	(segment
		(start 87.55888 -29.60243)
		(end 98.624898 -40.668448)
		(width 0.127)
		(layer "In2.Cu")
		(net "FM_OCP_V3_2_PWR_GOOD")
	)
	(segment
		(start 84.02828 -15.560548)
		(end 87.55888 -19.091148)
		(width 0.127)
		(layer "In2.Cu")
		(net "FM_OCP_V3_2_PWR_GOOD")
	)
	(segment
		(start 79.297276 -12.791948)
		(end 82.065876 -15.560548)
		(width 0.127)
		(layer "In2.Cu")
		(net "FM_OCP_V3_2_PWR_GOOD")
	)
	(segment
		(start 133.27126 -101.938328)
		(end 128.4859 -101.938328)
		(width 0.127)
		(layer "In6.Cu")
		(net "FM_OCP_V3_2_PWR_GOOD")
	)
	(segment
		(start 159.82188 -108.295948)
		(end 159.1818 -108.936028)
		(width 0.127)
		(layer "In6.Cu")
		(net "FM_OCP_V3_2_PWR_GOOD")
	)
	(segment
		(start 152.15108 -108.936028)
		(end 150.114 -106.898948)
		(width 0.127)
		(layer "In6.Cu")
		(net "FM_OCP_V3_2_PWR_GOOD")
	)
	(segment
		(start 128.4859 -101.938328)
		(end 127.57404 -101.026468)
		(width 0.127)
		(layer "In6.Cu")
		(net "FM_OCP_V3_2_PWR_GOOD")
	)
	(segment
		(start 150.114 -106.898948)
		(end 146.32432 -106.898948)
		(width 0.127)
		(layer "In6.Cu")
		(net "FM_OCP_V3_2_PWR_GOOD")
	)
	(segment
		(start 146.32432 -106.898948)
		(end 145.25752 -105.832148)
		(width 0.127)
		(layer "In6.Cu")
		(net "FM_OCP_V3_2_PWR_GOOD")
	)
	(segment
		(start 145.25752 -105.832148)
		(end 137.16508 -105.832148)
		(width 0.127)
		(layer "In6.Cu")
		(net "FM_OCP_V3_2_PWR_GOOD")
	)
	(segment
		(start 137.16508 -105.832148)
		(end 133.27126 -101.938328)
		(width 0.127)
		(layer "In6.Cu")
		(net "FM_OCP_V3_2_PWR_GOOD")
	)
	(segment
		(start 159.1818 -108.936028)
		(end 152.15108 -108.936028)
		(width 0.127)
		(layer "In6.Cu")
		(net "FM_OCP_V3_2_PWR_GOOD")
	)
	(segment
		(start 153.36393 -129.758948)
		(end 153.9748 -129.758948)
		(width 0.12954)
		(layer "F.Cu")
		(net "FM_NCSI_OCP_V3_2_R_OE")
	)
	(segment
		(start 170.955716 -115.375436)
		(end 170.555666 -115.775486)
		(width 0.12954)
		(layer "F.Cu")
		(net "FM_NCSI_OCP_V3_2_R_OE")
	)
	(via
		(at 153.9748 -129.758948)
		(size 0.508)
		(drill 0.254)
		(layers "F.Cu" "B.Cu")
		(net "FM_NCSI_OCP_V3_2_R_OE")
	)
	(via
		(at 170.555666 -115.775486)
		(size 0.4572)
		(drill 0.254)
		(layers "F.Cu" "B.Cu")
		(net "FM_NCSI_OCP_V3_2_R_OE")
	)
	(via
		(at 171.02836 -134.854188)
		(size 0.508)
		(drill 0.254)
		(layers "F.Cu" "B.Cu")
		(net "FM_NCSI_OCP_V3_2_R_OE")
	)
	(segment
		(start 170.1546 -122.332496)
		(end 170.1546 -116.176552)
		(width 0.127)
		(layer "In11.Cu")
		(net "FM_NCSI_OCP_V3_2_R_OE")
	)
	(segment
		(start 169.63136 -128.806448)
		(end 169.63136 -122.855736)
		(width 0.127)
		(layer "In11.Cu")
		(net "FM_NCSI_OCP_V3_2_R_OE")
	)
	(segment
		(start 171.02836 -134.854188)
		(end 171.02836 -130.203448)
		(width 0.127)
		(layer "In11.Cu")
		(net "FM_NCSI_OCP_V3_2_R_OE")
	)
	(segment
		(start 171.02836 -130.203448)
		(end 169.63136 -128.806448)
		(width 0.127)
		(layer "In11.Cu")
		(net "FM_NCSI_OCP_V3_2_R_OE")
	)
	(segment
		(start 169.63136 -122.855736)
		(end 170.1546 -122.332496)
		(width 0.127)
		(layer "In11.Cu")
		(net "FM_NCSI_OCP_V3_2_R_OE")
	)
	(segment
		(start 170.1546 -116.176552)
		(end 170.555666 -115.775486)
		(width 0.127)
		(layer "In11.Cu")
		(net "FM_NCSI_OCP_V3_2_R_OE")
	)
	(segment
		(start 153.26868 -131.661408)
		(end 153.26868 -130.465068)
		(width 0.127)
		(layer "In13.Cu")
		(net "FM_NCSI_OCP_V3_2_R_OE")
	)
	(segment
		(start 171.02836 -134.854188)
		(end 156.46146 -134.854188)
		(width 0.127)
		(layer "In13.Cu")
		(net "FM_NCSI_OCP_V3_2_R_OE")
	)
	(segment
		(start 156.46146 -134.854188)
		(end 153.26868 -131.661408)
		(width 0.127)
		(layer "In13.Cu")
		(net "FM_NCSI_OCP_V3_2_R_OE")
	)
	(segment
		(start 153.26868 -130.465068)
		(end 153.9748 -129.758948)
		(width 0.127)
		(layer "In13.Cu")
		(net "FM_NCSI_OCP_V3_2_R_OE")
	)
	(segment
		(start 120.77827 -421.447468)
		(end 121.38787 -421.447468)
		(width 0.12954)
		(layer "F.Cu")
		(net "FM_GPU_PWR_EN_R_BUF")
	)
	(via
		(at 121.38787 -421.447468)
		(size 0.508)
		(drill 0.254)
		(layers "F.Cu" "B.Cu")
		(net "FM_GPU_PWR_EN_R_BUF")
	)
	(segment
		(start 81.650078 -422.93667)
		(end 83.45678 -421.129968)
		(width 0.127)
		(layer "In15.Cu")
		(net "FM_GPU_PWR_EN_R_BUF")
	)
	(segment
		(start 121.69902 -421.136318)
		(end 121.38787 -421.447468)
		(width 0.127)
		(layer "In15.Cu")
		(net "FM_GPU_PWR_EN_R_BUF")
	)
	(segment
		(start 106.8959 -419.768528)
		(end 108.7882 -417.876228)
		(width 0.127)
		(layer "In15.Cu")
		(net "FM_GPU_PWR_EN_R_BUF")
	)
	(segment
		(start 98.37801 -420.135558)
		(end 101.96195 -420.135558)
		(width 0.127)
		(layer "In15.Cu")
		(net "FM_GPU_PWR_EN_R_BUF")
	)
	(segment
		(start 108.7882 -417.876228)
		(end 120.15978 -417.876228)
		(width 0.127)
		(layer "In15.Cu")
		(net "FM_GPU_PWR_EN_R_BUF")
	)
	(segment
		(start 81.650078 -424.689778)
		(end 81.650078 -422.93667)
		(width 0.127)
		(layer "In15.Cu")
		(net "FM_GPU_PWR_EN_R_BUF")
	)
	(segment
		(start 83.45678 -421.129968)
		(end 97.3836 -421.129968)
		(width 0.127)
		(layer "In15.Cu")
		(net "FM_GPU_PWR_EN_R_BUF")
	)
	(segment
		(start 97.3836 -421.129968)
		(end 98.37801 -420.135558)
		(width 0.127)
		(layer "In15.Cu")
		(net "FM_GPU_PWR_EN_R_BUF")
	)
	(segment
		(start 120.15978 -417.876228)
		(end 121.69902 -419.415468)
		(width 0.127)
		(layer "In15.Cu")
		(net "FM_GPU_PWR_EN_R_BUF")
	)
	(segment
		(start 101.96195 -420.135558)
		(end 102.32898 -419.768528)
		(width 0.127)
		(layer "In15.Cu")
		(net "FM_GPU_PWR_EN_R_BUF")
	)
	(segment
		(start 121.69902 -419.415468)
		(end 121.69902 -421.136318)
		(width 0.127)
		(layer "In15.Cu")
		(net "FM_GPU_PWR_EN_R_BUF")
	)
	(segment
		(start 102.32898 -419.768528)
		(end 106.8959 -419.768528)
		(width 0.127)
		(layer "In15.Cu")
		(net "FM_GPU_PWR_EN_R_BUF")
	)
	(segment
		(start 166.34968 -104.485948)
		(end 165.04793 -104.485948)
		(width 0.12954)
		(layer "F.Cu")
		(net "FM_GPU_PWR_EN")
	)
	(segment
		(start 166.52748 -104.308148)
		(end 166.34968 -104.485948)
		(width 0.12954)
		(layer "F.Cu")
		(net "FM_GPU_PWR_EN")
	)
	(segment
		(start 167.994838 -105.775506)
		(end 166.52748 -104.308148)
		(width 0.12954)
		(layer "F.Cu")
		(net "FM_GPU_PWR_EN")
	)
	(segment
		(start 170.155616 -105.775506)
		(end 167.994838 -105.775506)
		(width 0.12954)
		(layer "F.Cu")
		(net "FM_GPU_PWR_EN")
	)
	(via
		(at 166.52748 -104.308148)
		(size 0.762)
		(drill 0.381)
		(layers "F.Cu" "B.Cu")
		(net "FM_GPU_PWR_EN")
	)
	(segment
		(start 153.359866 -128.738884)
		(end 153.36393 -128.742948)
		(width 0.12954)
		(layer "F.Cu")
		(net "FB_BMC_ISOLATE_R2")
	)
	(segment
		(start 153.359866 -126.263908)
		(end 153.359866 -127.528828)
		(width 0.12954)
		(layer "F.Cu")
		(net "FB_BMC_ISOLATE_R2")
	)
	(segment
		(start 153.359866 -127.528828)
		(end 153.359866 -128.738884)
		(width 0.12954)
		(layer "F.Cu")
		(net "FB_BMC_ISOLATE_R2")
	)
	(via
		(at 153.359866 -127.528828)
		(size 0.762)
		(drill 0.381)
		(layers "F.Cu" "B.Cu")
		(net "FB_BMC_ISOLATE_R2")
	)
	(segment
		(start 90.760042 -31.120588)
		(end 91.8972 -31.120588)
		(width 0.12954)
		(layer "F.Cu")
		(net "FB_BMC_ISOLATE1")
	)
	(segment
		(start 202.743816 -70.903084)
		(end 201.317352 -72.329548)
		(width 0.12954)
		(layer "F.Cu")
		(net "FB_BMC_ISOLATE1")
	)
	(segment
		(start 152.56383 -128.742948)
		(end 152.56383 -128.107948)
		(width 0.12954)
		(layer "F.Cu")
		(net "FB_BMC_ISOLATE1")
	)
	(segment
		(start 152.56383 -129.758948)
		(end 152.56383 -130.774948)
		(width 0.12954)
		(layer "F.Cu")
		(net "FB_BMC_ISOLATE1")
	)
	(segment
		(start 201.317352 -72.329548)
		(end 199.44588 -72.329548)
		(width 0.12954)
		(layer "F.Cu")
		(net "FB_BMC_ISOLATE1")
	)
	(segment
		(start 152.56383 -128.742948)
		(end 152.56383 -129.758948)
		(width 0.12954)
		(layer "F.Cu")
		(net "FB_BMC_ISOLATE1")
	)
	(via
		(at 210.21548 -76.952348)
		(size 0.508)
		(drill 0.254)
		(layers "F.Cu" "B.Cu")
		(net "FB_BMC_ISOLATE1")
	)
	(via
		(at 165.27907 -68.820538)
		(size 0.508)
		(drill 0.254)
		(layers "F.Cu" "B.Cu")
		(net "FB_BMC_ISOLATE1")
	)
	(via
		(at 210.925918 -79.21371)
		(size 0.508)
		(drill 0.254)
		(layers "F.Cu" "B.Cu")
		(net "FB_BMC_ISOLATE1")
	)
	(via
		(at 180.086 -89.916)
		(size 0.508)
		(drill 0.254)
		(layers "F.Cu" "B.Cu")
		(net "FB_BMC_ISOLATE1")
	)
	(via
		(at 91.8972 -31.120588)
		(size 0.508)
		(drill 0.254)
		(layers "F.Cu" "B.Cu")
		(net "FB_BMC_ISOLATE1")
	)
	(via
		(at 202.743816 -70.903084)
		(size 0.762)
		(drill 0.254)
		(layers "F.Cu" "B.Cu")
		(net "FB_BMC_ISOLATE1")
	)
	(via
		(at 204.11948 -76.952348)
		(size 0.508)
		(drill 0.254)
		(layers "F.Cu" "B.Cu")
		(net "FB_BMC_ISOLATE1")
	)
	(via
		(at 152.56383 -128.107948)
		(size 0.508)
		(drill 0.254)
		(layers "F.Cu" "B.Cu")
		(net "FB_BMC_ISOLATE1")
	)
	(via
		(at 199.44588 -72.329548)
		(size 0.508)
		(drill 0.254)
		(layers "F.Cu" "B.Cu")
		(net "FB_BMC_ISOLATE1")
	)
	(segment
		(start 199.969374 -72.853042)
		(end 201.39533 -72.853042)
		(width 0.12954)
		(layer "B.Cu")
		(net "FB_BMC_ISOLATE1")
	)
	(segment
		(start 210.21548 -76.952348)
		(end 210.526884 -77.263752)
		(width 0.12954)
		(layer "B.Cu")
		(net "FB_BMC_ISOLATE1")
	)
	(segment
		(start 150.09114 -56.975248)
		(end 148.18106 -55.065168)
		(width 0.12954)
		(layer "B.Cu")
		(net "FB_BMC_ISOLATE1")
	)
	(segment
		(start 120.79478 -41.648888)
		(end 113.75136 -34.605468)
		(width 0.12954)
		(layer "B.Cu")
		(net "FB_BMC_ISOLATE1")
	)
	(segment
		(start 212.216746 -79.21371)
		(end 210.925918 -79.21371)
		(width 0.12954)
		(layer "B.Cu")
		(net "FB_BMC_ISOLATE1")
	)
	(segment
		(start 194.61353 -70.253098)
		(end 195.55333 -70.253098)
		(width 0.12954)
		(layer "B.Cu")
		(net "FB_BMC_ISOLATE1")
	)
	(segment
		(start 207.374744 -78.563724)
		(end 206.374746 -78.563724)
		(width 0.12954)
		(layer "B.Cu")
		(net "FB_BMC_ISOLATE1")
	)
	(segment
		(start 195.55333 -72.203056)
		(end 199.319388 -72.203056)
		(width 0.12954)
		(layer "B.Cu")
		(net "FB_BMC_ISOLATE1")
	)
	(segment
		(start 195.55333 -72.203056)
		(end 194.671442 -72.203056)
		(width 0.12954)
		(layer "B.Cu")
		(net "FB_BMC_ISOLATE1")
	)
	(segment
		(start 95.070422 -34.605468)
		(end 94.46641 -34.001456)
		(width 0.12954)
		(layer "B.Cu")
		(net "FB_BMC_ISOLATE1")
	)
	(segment
		(start 204.458062 -76.613766)
		(end 206.374746 -76.613766)
		(width 0.12954)
		(layer "B.Cu")
		(net "FB_BMC_ISOLATE1")
	)
	(segment
		(start 94.46641 -32.554418)
		(end 93.03258 -31.120588)
		(width 0.12954)
		(layer "B.Cu")
		(net "FB_BMC_ISOLATE1")
	)
	(segment
		(start 204.11948 -76.952348)
		(end 204.458062 -76.613766)
		(width 0.12954)
		(layer "B.Cu")
		(net "FB_BMC_ISOLATE1")
	)
	(segment
		(start 113.75136 -34.605468)
		(end 95.070422 -34.605468)
		(width 0.12954)
		(layer "B.Cu")
		(net "FB_BMC_ISOLATE1")
	)
	(segment
		(start 194.39128 -70.475348)
		(end 194.61353 -70.253098)
		(width 0.12954)
		(layer "B.Cu")
		(net "FB_BMC_ISOLATE1")
	)
	(segment
		(start 207.64754 -76.906628)
		(end 207.64754 -78.290928)
		(width 0.12954)
		(layer "B.Cu")
		(net "FB_BMC_ISOLATE1")
	)
	(segment
		(start 199.319388 -72.203056)
		(end 199.44588 -72.329548)
		(width 0.12954)
		(layer "B.Cu")
		(net "FB_BMC_ISOLATE1")
	)
	(segment
		(start 199.44588 -72.329548)
		(end 199.969374 -72.853042)
		(width 0.12954)
		(layer "B.Cu")
		(net "FB_BMC_ISOLATE1")
	)
	(segment
		(start 127.48514 -45.938948)
		(end 123.19508 -41.648888)
		(width 0.12954)
		(layer "B.Cu")
		(net "FB_BMC_ISOLATE1")
	)
	(segment
		(start 153.43378 -56.975248)
		(end 150.09114 -56.975248)
		(width 0.12954)
		(layer "B.Cu")
		(net "FB_BMC_ISOLATE1")
	)
	(segment
		(start 194.39128 -71.922894)
		(end 194.39128 -70.475348)
		(width 0.12954)
		(layer "B.Cu")
		(net "FB_BMC_ISOLATE1")
	)
	(segment
		(start 206.374746 -76.613766)
		(end 206.380588 -76.619608)
		(width 0.12954)
		(layer "B.Cu")
		(net "FB_BMC_ISOLATE1")
	)
	(segment
		(start 210.526884 -77.263752)
		(end 212.216746 -77.263752)
		(width 0.12954)
		(layer "B.Cu")
		(net "FB_BMC_ISOLATE1")
	)
	(segment
		(start 123.19508 -41.648888)
		(end 120.79478 -41.648888)
		(width 0.12954)
		(layer "B.Cu")
		(net "FB_BMC_ISOLATE1")
	)
	(segment
		(start 148.18106 -55.065168)
		(end 148.18106 -48.103028)
		(width 0.12954)
		(layer "B.Cu")
		(net "FB_BMC_ISOLATE1")
	)
	(segment
		(start 148.18106 -48.103028)
		(end 146.01698 -45.938948)
		(width 0.12954)
		(layer "B.Cu")
		(net "FB_BMC_ISOLATE1")
	)
	(segment
		(start 94.46641 -34.001456)
		(end 94.46641 -32.554418)
		(width 0.12954)
		(layer "B.Cu")
		(net "FB_BMC_ISOLATE1")
	)
	(segment
		(start 201.39533 -70.903084)
		(end 202.743816 -70.903084)
		(width 0.12954)
		(layer "B.Cu")
		(net "FB_BMC_ISOLATE1")
	)
	(segment
		(start 194.671442 -72.203056)
		(end 194.39128 -71.922894)
		(width 0.12954)
		(layer "B.Cu")
		(net "FB_BMC_ISOLATE1")
	)
	(segment
		(start 207.64754 -78.290928)
		(end 207.374744 -78.563724)
		(width 0.12954)
		(layer "B.Cu")
		(net "FB_BMC_ISOLATE1")
	)
	(segment
		(start 207.36052 -76.619608)
		(end 207.64754 -76.906628)
		(width 0.12954)
		(layer "B.Cu")
		(net "FB_BMC_ISOLATE1")
	)
	(segment
		(start 165.27907 -68.820538)
		(end 153.43378 -56.975248)
		(width 0.12954)
		(layer "B.Cu")
		(net "FB_BMC_ISOLATE1")
	)
	(segment
		(start 146.01698 -45.938948)
		(end 127.48514 -45.938948)
		(width 0.12954)
		(layer "B.Cu")
		(net "FB_BMC_ISOLATE1")
	)
	(segment
		(start 93.03258 -31.120588)
		(end 91.8972 -31.120588)
		(width 0.12954)
		(layer "B.Cu")
		(net "FB_BMC_ISOLATE1")
	)
	(segment
		(start 206.380588 -76.619608)
		(end 207.36052 -76.619608)
		(width 0.12954)
		(layer "B.Cu")
		(net "FB_BMC_ISOLATE1")
	)
	(segment
		(start 199.44588 -72.329548)
		(end 200.79208 -72.329548)
		(width 0.127)
		(layer "In6.Cu")
		(net "FB_BMC_ISOLATE1")
	)
	(segment
		(start 210.21548 -76.952348)
		(end 210.925918 -77.662786)
		(width 0.127)
		(layer "In6.Cu")
		(net "FB_BMC_ISOLATE1")
	)
	(segment
		(start 203.81468 -76.647548)
		(end 204.11948 -76.952348)
		(width 0.127)
		(layer "In6.Cu")
		(net "FB_BMC_ISOLATE1")
	)
	(segment
		(start 200.79208 -72.329548)
		(end 203.81468 -75.352148)
		(width 0.127)
		(layer "In6.Cu")
		(net "FB_BMC_ISOLATE1")
	)
	(segment
		(start 203.81468 -75.352148)
		(end 203.81468 -76.647548)
		(width 0.127)
		(layer "In6.Cu")
		(net "FB_BMC_ISOLATE1")
	)
	(segment
		(start 210.925918 -77.662786)
		(end 210.925918 -79.21371)
		(width 0.127)
		(layer "In6.Cu")
		(net "FB_BMC_ISOLATE1")
	)
	(segment
		(start 204.11948 -76.952348)
		(end 210.21548 -76.952348)
		(width 0.127)
		(layer "In6.Cu")
		(net "FB_BMC_ISOLATE1")
	)
	(segment
		(start 180.086 -89.916)
		(end 171.406566 -89.916)
		(width 0.127)
		(layer "In11.Cu")
		(net "FB_BMC_ISOLATE1")
	)
	(segment
		(start 152.04948 -103.261668)
		(end 152.04948 -112.169448)
		(width 0.127)
		(layer "In11.Cu")
		(net "FB_BMC_ISOLATE1")
	)
	(segment
		(start 151.2824 -117.264688)
		(end 151.2824 -123.848368)
		(width 0.127)
		(layer "In11.Cu")
		(net "FB_BMC_ISOLATE1")
	)
	(segment
		(start 150.84552 -116.827808)
		(end 151.2824 -117.264688)
		(width 0.127)
		(layer "In11.Cu")
		(net "FB_BMC_ISOLATE1")
	)
	(segment
		(start 165.95598 -95.366586)
		(end 165.95598 -96.374966)
		(width 0.127)
		(layer "In11.Cu")
		(net "FB_BMC_ISOLATE1")
	)
	(segment
		(start 195.1228 -80.406748)
		(end 194.7418 -80.025748)
		(width 0.127)
		(layer "In11.Cu")
		(net "FB_BMC_ISOLATE1")
	)
	(segment
		(start 155.6258 -99.685348)
		(end 152.04948 -103.261668)
		(width 0.127)
		(layer "In11.Cu")
		(net "FB_BMC_ISOLATE1")
	)
	(segment
		(start 161.934398 -99.685348)
		(end 155.6258 -99.685348)
		(width 0.127)
		(layer "In11.Cu")
		(net "FB_BMC_ISOLATE1")
	)
	(segment
		(start 192.89522 -80.025748)
		(end 191.9986 -80.922368)
		(width 0.127)
		(layer "In11.Cu")
		(net "FB_BMC_ISOLATE1")
	)
	(segment
		(start 198.94296 -72.832468)
		(end 198.94296 -78.776068)
		(width 0.127)
		(layer "In11.Cu")
		(net "FB_BMC_ISOLATE1")
	)
	(segment
		(start 199.44588 -72.329548)
		(end 198.94296 -72.832468)
		(width 0.127)
		(layer "In11.Cu")
		(net "FB_BMC_ISOLATE1")
	)
	(segment
		(start 151.2824 -123.848368)
		(end 152.56383 -125.129798)
		(width 0.127)
		(layer "In11.Cu")
		(net "FB_BMC_ISOLATE1")
	)
	(segment
		(start 165.680898 -96.650048)
		(end 164.969698 -96.650048)
		(width 0.127)
		(layer "In11.Cu")
		(net "FB_BMC_ISOLATE1")
	)
	(segment
		(start 171.406566 -89.916)
		(end 165.95598 -95.366586)
		(width 0.127)
		(layer "In11.Cu")
		(net "FB_BMC_ISOLATE1")
	)
	(segment
		(start 150.84552 -113.373408)
		(end 150.84552 -116.827808)
		(width 0.127)
		(layer "In11.Cu")
		(net "FB_BMC_ISOLATE1")
	)
	(segment
		(start 198.94296 -78.776068)
		(end 197.31228 -80.406748)
		(width 0.127)
		(layer "In11.Cu")
		(net "FB_BMC_ISOLATE1")
	)
	(segment
		(start 165.95598 -96.374966)
		(end 165.680898 -96.650048)
		(width 0.127)
		(layer "In11.Cu")
		(net "FB_BMC_ISOLATE1")
	)
	(segment
		(start 194.7418 -80.025748)
		(end 192.89522 -80.025748)
		(width 0.127)
		(layer "In11.Cu")
		(net "FB_BMC_ISOLATE1")
	)
	(segment
		(start 197.31228 -80.406748)
		(end 195.1228 -80.406748)
		(width 0.127)
		(layer "In11.Cu")
		(net "FB_BMC_ISOLATE1")
	)
	(segment
		(start 152.04948 -112.169448)
		(end 150.84552 -113.373408)
		(width 0.127)
		(layer "In11.Cu")
		(net "FB_BMC_ISOLATE1")
	)
	(segment
		(start 191.9986 -80.922368)
		(end 170.25874 -80.922368)
		(width 0.127)
		(layer "In11.Cu")
		(net "FB_BMC_ISOLATE1")
	)
	(segment
		(start 152.56383 -125.129798)
		(end 152.56383 -128.107948)
		(width 0.127)
		(layer "In11.Cu")
		(net "FB_BMC_ISOLATE1")
	)
	(segment
		(start 165.27907 -75.942698)
		(end 165.27907 -68.820538)
		(width 0.127)
		(layer "In11.Cu")
		(net "FB_BMC_ISOLATE1")
	)
	(segment
		(start 170.25874 -80.922368)
		(end 165.27907 -75.942698)
		(width 0.127)
		(layer "In11.Cu")
		(net "FB_BMC_ISOLATE1")
	)
	(segment
		(start 164.969698 -96.650048)
		(end 161.934398 -99.685348)
		(width 0.127)
		(layer "In11.Cu")
		(net "FB_BMC_ISOLATE1")
	)
	(segment
		(start 183.3118 -91.7194)
		(end 181.5084 -89.916)
		(width 0.127)
		(layer "In15.Cu")
		(net "FB_BMC_ISOLATE1")
	)
	(segment
		(start 196.64426 -80.65516)
		(end 196.64426 -84.91474)
		(width 0.127)
		(layer "In15.Cu")
		(net "FB_BMC_ISOLATE1")
	)
	(segment
		(start 196.64426 -84.91474)
		(end 193.4464 -88.1126)
		(width 0.127)
		(layer "In15.Cu")
		(net "FB_BMC_ISOLATE1")
	)
	(segment
		(start 192.7352 -94.757748)
		(end 189.696852 -91.7194)
		(width 0.127)
		(layer "In15.Cu")
		(net "FB_BMC_ISOLATE1")
	)
	(segment
		(start 181.5084 -89.916)
		(end 180.086 -89.916)
		(width 0.127)
		(layer "In15.Cu")
		(net "FB_BMC_ISOLATE1")
	)
	(segment
		(start 197.358 -91.582748)
		(end 198.12 -92.344748)
		(width 0.127)
		(layer "In15.Cu")
		(net "FB_BMC_ISOLATE1")
	)
	(segment
		(start 193.4464 -90.465148)
		(end 194.564 -91.582748)
		(width 0.127)
		(layer "In15.Cu")
		(net "FB_BMC_ISOLATE1")
	)
	(segment
		(start 204.11948 -76.952348)
		(end 203.06792 -78.003908)
		(width 0.127)
		(layer "In15.Cu")
		(net "FB_BMC_ISOLATE1")
	)
	(segment
		(start 198.12 -92.344748)
		(end 198.12 -94.097348)
		(width 0.127)
		(layer "In15.Cu")
		(net "FB_BMC_ISOLATE1")
	)
	(segment
		(start 193.4464 -88.1126)
		(end 193.4464 -90.465148)
		(width 0.127)
		(layer "In15.Cu")
		(net "FB_BMC_ISOLATE1")
	)
	(segment
		(start 198.12 -94.097348)
		(end 197.4596 -94.757748)
		(width 0.127)
		(layer "In15.Cu")
		(net "FB_BMC_ISOLATE1")
	)
	(segment
		(start 203.06792 -78.003908)
		(end 199.295512 -78.003908)
		(width 0.127)
		(layer "In15.Cu")
		(net "FB_BMC_ISOLATE1")
	)
	(segment
		(start 194.564 -91.582748)
		(end 197.358 -91.582748)
		(width 0.127)
		(layer "In15.Cu")
		(net "FB_BMC_ISOLATE1")
	)
	(segment
		(start 189.696852 -91.7194)
		(end 183.3118 -91.7194)
		(width 0.127)
		(layer "In15.Cu")
		(net "FB_BMC_ISOLATE1")
	)
	(segment
		(start 199.295512 -78.003908)
		(end 196.64426 -80.65516)
		(width 0.127)
		(layer "In15.Cu")
		(net "FB_BMC_ISOLATE1")
	)
	(segment
		(start 197.4596 -94.757748)
		(end 192.7352 -94.757748)
		(width 0.127)
		(layer "In15.Cu")
		(net "FB_BMC_ISOLATE1")
	)
	(segment
		(start 88.309958 -33.020508)
		(end 87.53221 -33.020508)
		(width 0.12954)
		(layer "F.Cu")
		(net "CLK_50M_NCSI_OCP_V3_2")
	)
	(segment
		(start 87.53221 -33.020508)
		(end 87.2363 -33.316418)
		(width 0.12954)
		(layer "F.Cu")
		(net "CLK_50M_NCSI_OCP_V3_2")
	)
	(segment
		(start 218.091766 -15.314422)
		(end 217.583766 -15.822422)
		(width 0.12954)
		(layer "F.Cu")
		(net "CLK_50M_NCSI_OCP_V3_2")
	)
	(segment
		(start 217.583766 -15.822422)
		(end 217.583766 -15.981172)
		(width 0.12954)
		(layer "F.Cu")
		(net "CLK_50M_NCSI_OCP_V3_2")
	)
	(via
		(at 87.2363 -33.316418)
		(size 0.508)
		(drill 0.254)
		(layers "F.Cu" "B.Cu")
		(net "CLK_50M_NCSI_OCP_V3_2")
	)
	(via
		(at 218.091766 -15.314422)
		(size 0.508)
		(drill 0.254)
		(layers "F.Cu" "B.Cu")
		(net "CLK_50M_NCSI_OCP_V3_2")
	)
	(segment
		(start 123.10491 -13.524738)
		(end 123.23191 -13.397738)
		(width 0.127)
		(layer "In6.Cu")
		(net "CLK_50M_NCSI_OCP_V3_2")
	)
	(segment
		(start 108.021628 -21.852128)
		(end 108.148628 -21.979128)
		(width 0.127)
		(layer "In6.Cu")
		(net "CLK_50M_NCSI_OCP_V3_2")
	)
	(segment
		(start 108.783628 -18.506948)
		(end 109.164628 -18.506948)
		(width 0.127)
		(layer "In6.Cu")
		(net "CLK_50M_NCSI_OCP_V3_2")
	)
	(segment
		(start 98.31324 -17.269968)
		(end 104.506776 -17.269968)
		(width 0.127)
		(layer "In6.Cu")
		(net "CLK_50M_NCSI_OCP_V3_2")
	)
	(segment
		(start 122.59691 -15.751048)
		(end 122.97791 -15.751048)
		(width 0.127)
		(layer "In6.Cu")
		(net "CLK_50M_NCSI_OCP_V3_2")
	)
	(segment
		(start 111.549688 -15.293848)
		(end 111.729012 -15.293848)
		(width 0.127)
		(layer "In6.Cu")
		(net "CLK_50M_NCSI_OCP_V3_2")
	)
	(segment
		(start 125.00991 -13.524738)
		(end 125.00991 -16.21028)
		(width 0.127)
		(layer "In6.Cu")
		(net "CLK_50M_NCSI_OCP_V3_2")
	)
	(segment
		(start 87.93734 -18.603468)
		(end 90.11158 -16.429228)
		(width 0.127)
		(layer "In6.Cu")
		(net "CLK_50M_NCSI_OCP_V3_2")
	)
	(segment
		(start 120.361202 -13.524738)
		(end 120.488202 -13.397738)
		(width 0.127)
		(layer "In6.Cu")
		(net "CLK_50M_NCSI_OCP_V3_2")
	)
	(segment
		(start 196.279262 -13.24864)
		(end 216.025984 -13.24864)
		(width 0.127)
		(layer "In6.Cu")
		(net "CLK_50M_NCSI_OCP_V3_2")
	)
	(segment
		(start 109.926628 -18.633948)
		(end 110.053628 -18.506948)
		(width 0.127)
		(layer "In6.Cu")
		(net "CLK_50M_NCSI_OCP_V3_2")
	)
	(segment
		(start 104.506776 -17.269968)
		(end 105.743756 -18.506948)
		(width 0.127)
		(layer "In6.Cu")
		(net "CLK_50M_NCSI_OCP_V3_2")
	)
	(segment
		(start 113.076228 -13.946632)
		(end 113.076228 -13.767308)
		(width 0.127)
		(layer "In6.Cu")
		(net "CLK_50M_NCSI_OCP_V3_2")
	)
	(segment
		(start 117.117876 -13.397738)
		(end 118.329202 -13.397738)
		(width 0.127)
		(layer "In6.Cu")
		(net "CLK_50M_NCSI_OCP_V3_2")
	)
	(segment
		(start 124.88291 -13.397738)
		(end 125.00991 -13.524738)
		(width 0.127)
		(layer "In6.Cu")
		(net "CLK_50M_NCSI_OCP_V3_2")
	)
	(segment
		(start 97.4725 -16.429228)
		(end 98.31324 -17.269968)
		(width 0.127)
		(layer "In6.Cu")
		(net "CLK_50M_NCSI_OCP_V3_2")
	)
	(segment
		(start 111.27994 -15.563596)
		(end 111.549688 -15.293848)
		(width 0.127)
		(layer "In6.Cu")
		(net "CLK_50M_NCSI_OCP_V3_2")
	)
	(segment
		(start 122.97791 -15.751048)
		(end 123.10491 -15.624048)
		(width 0.127)
		(layer "In6.Cu")
		(net "CLK_50M_NCSI_OCP_V3_2")
	)
	(segment
		(start 118.329202 -13.397738)
		(end 118.456202 -13.524738)
		(width 0.127)
		(layer "In6.Cu")
		(net "CLK_50M_NCSI_OCP_V3_2")
	)
	(segment
		(start 112.008666 -18.506948)
		(end 112.936782 -17.578832)
		(width 0.127)
		(layer "In6.Cu")
		(net "CLK_50M_NCSI_OCP_V3_2")
	)
	(segment
		(start 119.599202 -13.397738)
		(end 119.726202 -13.524738)
		(width 0.127)
		(layer "In6.Cu")
		(net "CLK_50M_NCSI_OCP_V3_2")
	)
	(segment
		(start 123.86691 -15.751048)
		(end 124.24791 -15.751048)
		(width 0.127)
		(layer "In6.Cu")
		(net "CLK_50M_NCSI_OCP_V3_2")
	)
	(segment
		(start 193.869818 -11.674094)
		(end 194.853814 -12.65809)
		(width 0.127)
		(layer "In6.Cu")
		(net "CLK_50M_NCSI_OCP_V3_2")
	)
	(segment
		(start 193.312796 -10.484866)
		(end 193.77406 -11.174984)
		(width 0.127)
		(layer "In6.Cu")
		(net "CLK_50M_NCSI_OCP_V3_2")
	)
	(segment
		(start 124.37491 -13.524738)
		(end 124.50191 -13.397738)
		(width 0.127)
		(layer "In6.Cu")
		(net "CLK_50M_NCSI_OCP_V3_2")
	)
	(segment
		(start 112.178084 -14.844776)
		(end 112.178084 -14.665452)
		(width 0.127)
		(layer "In6.Cu")
		(net "CLK_50M_NCSI_OCP_V3_2")
	)
	(segment
		(start 118.456202 -13.524738)
		(end 118.456202 -16.548608)
		(width 0.127)
		(layer "In6.Cu")
		(net "CLK_50M_NCSI_OCP_V3_2")
	)
	(segment
		(start 122.46991 -13.524738)
		(end 122.46991 -15.624048)
		(width 0.127)
		(layer "In6.Cu")
		(net "CLK_50M_NCSI_OCP_V3_2")
	)
	(segment
		(start 109.291628 -18.633948)
		(end 109.291628 -21.852128)
		(width 0.127)
		(layer "In6.Cu")
		(net "CLK_50M_NCSI_OCP_V3_2")
	)
	(segment
		(start 105.743756 -18.506948)
		(end 106.624628 -18.506948)
		(width 0.127)
		(layer "In6.Cu")
		(net "CLK_50M_NCSI_OCP_V3_2")
	)
	(segment
		(start 119.091202 -13.524738)
		(end 119.218202 -13.397738)
		(width 0.127)
		(layer "In6.Cu")
		(net "CLK_50M_NCSI_OCP_V3_2")
	)
	(segment
		(start 125.13691 -16.33728)
		(end 125.51791 -16.33728)
		(width 0.127)
		(layer "In6.Cu")
		(net "CLK_50M_NCSI_OCP_V3_2")
	)
	(segment
		(start 123.23191 -13.397738)
		(end 123.61291 -13.397738)
		(width 0.127)
		(layer "In6.Cu")
		(net "CLK_50M_NCSI_OCP_V3_2")
	)
	(segment
		(start 119.091202 -16.548608)
		(end 119.091202 -13.524738)
		(width 0.127)
		(layer "In6.Cu")
		(net "CLK_50M_NCSI_OCP_V3_2")
	)
	(segment
		(start 106.878628 -21.979128)
		(end 107.259628 -21.979128)
		(width 0.127)
		(layer "In6.Cu")
		(net "CLK_50M_NCSI_OCP_V3_2")
	)
	(segment
		(start 120.361202 -16.548608)
		(end 120.361202 -13.524738)
		(width 0.127)
		(layer "In6.Cu")
		(net "CLK_50M_NCSI_OCP_V3_2")
	)
	(segment
		(start 216.025984 -13.24864)
		(end 218.091766 -15.314422)
		(width 0.127)
		(layer "In6.Cu")
		(net "CLK_50M_NCSI_OCP_V3_2")
	)
	(segment
		(start 125.77191 -13.397738)
		(end 127.684022 -13.397738)
		(width 0.127)
		(layer "In6.Cu")
		(net "CLK_50M_NCSI_OCP_V3_2")
	)
	(segment
		(start 123.61291 -13.397738)
		(end 123.73991 -13.524738)
		(width 0.127)
		(layer "In6.Cu")
		(net "CLK_50M_NCSI_OCP_V3_2")
	)
	(segment
		(start 113.834926 -16.501364)
		(end 112.178084 -14.844776)
		(width 0.127)
		(layer "In6.Cu")
		(net "CLK_50M_NCSI_OCP_V3_2")
	)
	(segment
		(start 107.386628 -21.852128)
		(end 107.386628 -18.633948)
		(width 0.127)
		(layer "In6.Cu")
		(net "CLK_50M_NCSI_OCP_V3_2")
	)
	(segment
		(start 123.73991 -13.524738)
		(end 123.73991 -15.624048)
		(width 0.127)
		(layer "In6.Cu")
		(net "CLK_50M_NCSI_OCP_V3_2")
	)
	(segment
		(start 119.726202 -16.548608)
		(end 119.853202 -16.675608)
		(width 0.127)
		(layer "In6.Cu")
		(net "CLK_50M_NCSI_OCP_V3_2")
	)
	(segment
		(start 107.894628 -18.506948)
		(end 108.021628 -18.633948)
		(width 0.127)
		(layer "In6.Cu")
		(net "CLK_50M_NCSI_OCP_V3_2")
	)
	(segment
		(start 118.964202 -16.675608)
		(end 119.091202 -16.548608)
		(width 0.127)
		(layer "In6.Cu")
		(net "CLK_50M_NCSI_OCP_V3_2")
	)
	(segment
		(start 112.178084 -14.665452)
		(end 112.447832 -14.395704)
		(width 0.127)
		(layer "In6.Cu")
		(net "CLK_50M_NCSI_OCP_V3_2")
	)
	(segment
		(start 123.73991 -15.624048)
		(end 123.86691 -15.751048)
		(width 0.127)
		(layer "In6.Cu")
		(net "CLK_50M_NCSI_OCP_V3_2")
	)
	(segment
		(start 185.190638 -7.120636)
		(end 193.312796 -10.484866)
		(width 0.127)
		(layer "In6.Cu")
		(net "CLK_50M_NCSI_OCP_V3_2")
	)
	(segment
		(start 119.726202 -13.524738)
		(end 119.726202 -16.548608)
		(width 0.127)
		(layer "In6.Cu")
		(net "CLK_50M_NCSI_OCP_V3_2")
	)
	(segment
		(start 193.77406 -11.174984)
		(end 193.77406 -11.4427)
		(width 0.127)
		(layer "In6.Cu")
		(net "CLK_50M_NCSI_OCP_V3_2")
	)
	(segment
		(start 114.73307 -15.60322)
		(end 113.076228 -13.946632)
		(width 0.127)
		(layer "In6.Cu")
		(net "CLK_50M_NCSI_OCP_V3_2")
	)
	(segment
		(start 112.936782 -17.399508)
		(end 111.27994 -15.74292)
		(width 0.127)
		(layer "In6.Cu")
		(net "CLK_50M_NCSI_OCP_V3_2")
	)
	(segment
		(start 125.64491 -13.524738)
		(end 125.77191 -13.397738)
		(width 0.127)
		(layer "In6.Cu")
		(net "CLK_50M_NCSI_OCP_V3_2")
	)
	(segment
		(start 124.37491 -15.624048)
		(end 124.37491 -13.524738)
		(width 0.127)
		(layer "In6.Cu")
		(net "CLK_50M_NCSI_OCP_V3_2")
	)
	(segment
		(start 109.418628 -21.979128)
		(end 109.799628 -21.979128)
		(width 0.127)
		(layer "In6.Cu")
		(net "CLK_50M_NCSI_OCP_V3_2")
	)
	(segment
		(start 109.291628 -21.852128)
		(end 109.418628 -21.979128)
		(width 0.127)
		(layer "In6.Cu")
		(net "CLK_50M_NCSI_OCP_V3_2")
	)
	(segment
		(start 106.751628 -21.852128)
		(end 106.878628 -21.979128)
		(width 0.127)
		(layer "In6.Cu")
		(net "CLK_50M_NCSI_OCP_V3_2")
	)
	(segment
		(start 124.24791 -15.751048)
		(end 124.37491 -15.624048)
		(width 0.127)
		(layer "In6.Cu")
		(net "CLK_50M_NCSI_OCP_V3_2")
	)
	(segment
		(start 110.053628 -18.506948)
		(end 112.008666 -18.506948)
		(width 0.127)
		(layer "In6.Cu")
		(net "CLK_50M_NCSI_OCP_V3_2")
	)
	(segment
		(start 109.164628 -18.506948)
		(end 109.291628 -18.633948)
		(width 0.127)
		(layer "In6.Cu")
		(net "CLK_50M_NCSI_OCP_V3_2")
	)
	(segment
		(start 106.751628 -18.633948)
		(end 106.751628 -21.852128)
		(width 0.127)
		(layer "In6.Cu")
		(net "CLK_50M_NCSI_OCP_V3_2")
	)
	(segment
		(start 113.076228 -13.767308)
		(end 113.345976 -13.49756)
		(width 0.127)
		(layer "In6.Cu")
		(net "CLK_50M_NCSI_OCP_V3_2")
	)
	(segment
		(start 111.729012 -15.293848)
		(end 113.385854 -16.950436)
		(width 0.127)
		(layer "In6.Cu")
		(net "CLK_50M_NCSI_OCP_V3_2")
	)
	(segment
		(start 120.488202 -13.397738)
		(end 122.34291 -13.397738)
		(width 0.127)
		(layer "In6.Cu")
		(net "CLK_50M_NCSI_OCP_V3_2")
	)
	(segment
		(start 113.345976 -13.49756)
		(end 113.5253 -13.49756)
		(width 0.127)
		(layer "In6.Cu")
		(net "CLK_50M_NCSI_OCP_V3_2")
	)
	(segment
		(start 113.385854 -16.950436)
		(end 113.565178 -16.950436)
		(width 0.127)
		(layer "In6.Cu")
		(net "CLK_50M_NCSI_OCP_V3_2")
	)
	(segment
		(start 112.447832 -14.395704)
		(end 112.627156 -14.395704)
		(width 0.127)
		(layer "In6.Cu")
		(net "CLK_50M_NCSI_OCP_V3_2")
	)
	(segment
		(start 120.234202 -16.675608)
		(end 120.361202 -16.548608)
		(width 0.127)
		(layer "In6.Cu")
		(net "CLK_50M_NCSI_OCP_V3_2")
	)
	(segment
		(start 122.34291 -13.397738)
		(end 122.46991 -13.524738)
		(width 0.127)
		(layer "In6.Cu")
		(net "CLK_50M_NCSI_OCP_V3_2")
	)
	(segment
		(start 119.218202 -13.397738)
		(end 119.599202 -13.397738)
		(width 0.127)
		(layer "In6.Cu")
		(net "CLK_50M_NCSI_OCP_V3_2")
	)
	(segment
		(start 125.00991 -16.21028)
		(end 125.13691 -16.33728)
		(width 0.127)
		(layer "In6.Cu")
		(net "CLK_50M_NCSI_OCP_V3_2")
	)
	(segment
		(start 107.259628 -21.979128)
		(end 107.386628 -21.852128)
		(width 0.127)
		(layer "In6.Cu")
		(net "CLK_50M_NCSI_OCP_V3_2")
	)
	(segment
		(start 108.148628 -21.979128)
		(end 108.529628 -21.979128)
		(width 0.127)
		(layer "In6.Cu")
		(net "CLK_50M_NCSI_OCP_V3_2")
	)
	(segment
		(start 114.463322 -16.052292)
		(end 114.73307 -15.782544)
		(width 0.127)
		(layer "In6.Cu")
		(net "CLK_50M_NCSI_OCP_V3_2")
	)
	(segment
		(start 114.283998 -16.052292)
		(end 114.463322 -16.052292)
		(width 0.127)
		(layer "In6.Cu")
		(net "CLK_50M_NCSI_OCP_V3_2")
	)
	(segment
		(start 123.10491 -15.624048)
		(end 123.10491 -13.524738)
		(width 0.127)
		(layer "In6.Cu")
		(net "CLK_50M_NCSI_OCP_V3_2")
	)
	(segment
		(start 108.656628 -18.633948)
		(end 108.783628 -18.506948)
		(width 0.127)
		(layer "In6.Cu")
		(net "CLK_50M_NCSI_OCP_V3_2")
	)
	(segment
		(start 112.936782 -17.578832)
		(end 112.936782 -17.399508)
		(width 0.127)
		(layer "In6.Cu")
		(net "CLK_50M_NCSI_OCP_V3_2")
	)
	(segment
		(start 133.961124 -7.120636)
		(end 185.190638 -7.120636)
		(width 0.127)
		(layer "In6.Cu")
		(net "CLK_50M_NCSI_OCP_V3_2")
	)
	(segment
		(start 113.565178 -16.950436)
		(end 113.834926 -16.680688)
		(width 0.127)
		(layer "In6.Cu")
		(net "CLK_50M_NCSI_OCP_V3_2")
	)
	(segment
		(start 107.513628 -18.506948)
		(end 107.894628 -18.506948)
		(width 0.127)
		(layer "In6.Cu")
		(net "CLK_50M_NCSI_OCP_V3_2")
	)
	(segment
		(start 108.529628 -21.979128)
		(end 108.656628 -21.852128)
		(width 0.127)
		(layer "In6.Cu")
		(net "CLK_50M_NCSI_OCP_V3_2")
	)
	(segment
		(start 87.93734 -32.615378)
		(end 87.93734 -18.603468)
		(width 0.127)
		(layer "In6.Cu")
		(net "CLK_50M_NCSI_OCP_V3_2")
	)
	(segment
		(start 113.5253 -13.49756)
		(end 115.182142 -15.154148)
		(width 0.127)
		(layer "In6.Cu")
		(net "CLK_50M_NCSI_OCP_V3_2")
	)
	(segment
		(start 87.2363 -33.316418)
		(end 87.93734 -32.615378)
		(width 0.127)
		(layer "In6.Cu")
		(net "CLK_50M_NCSI_OCP_V3_2")
	)
	(segment
		(start 109.926628 -21.852128)
		(end 109.926628 -18.633948)
		(width 0.127)
		(layer "In6.Cu")
		(net "CLK_50M_NCSI_OCP_V3_2")
	)
	(segment
		(start 109.799628 -21.979128)
		(end 109.926628 -21.852128)
		(width 0.127)
		(layer "In6.Cu")
		(net "CLK_50M_NCSI_OCP_V3_2")
	)
	(segment
		(start 124.50191 -13.397738)
		(end 124.88291 -13.397738)
		(width 0.127)
		(layer "In6.Cu")
		(net "CLK_50M_NCSI_OCP_V3_2")
	)
	(segment
		(start 106.624628 -18.506948)
		(end 106.751628 -18.633948)
		(width 0.127)
		(layer "In6.Cu")
		(net "CLK_50M_NCSI_OCP_V3_2")
	)
	(segment
		(start 108.656628 -21.852128)
		(end 108.656628 -18.633948)
		(width 0.127)
		(layer "In6.Cu")
		(net "CLK_50M_NCSI_OCP_V3_2")
	)
	(segment
		(start 118.583202 -16.675608)
		(end 118.964202 -16.675608)
		(width 0.127)
		(layer "In6.Cu")
		(net "CLK_50M_NCSI_OCP_V3_2")
	)
	(segment
		(start 107.386628 -18.633948)
		(end 107.513628 -18.506948)
		(width 0.127)
		(layer "In6.Cu")
		(net "CLK_50M_NCSI_OCP_V3_2")
	)
	(segment
		(start 90.11158 -16.429228)
		(end 97.4725 -16.429228)
		(width 0.127)
		(layer "In6.Cu")
		(net "CLK_50M_NCSI_OCP_V3_2")
	)
	(segment
		(start 114.73307 -15.782544)
		(end 114.73307 -15.60322)
		(width 0.127)
		(layer "In6.Cu")
		(net "CLK_50M_NCSI_OCP_V3_2")
	)
	(segment
		(start 115.182142 -15.154148)
		(end 115.361466 -15.154148)
		(width 0.127)
		(layer "In6.Cu")
		(net "CLK_50M_NCSI_OCP_V3_2")
	)
	(segment
		(start 127.684022 -13.397738)
		(end 133.961124 -7.120636)
		(width 0.127)
		(layer "In6.Cu")
		(net "CLK_50M_NCSI_OCP_V3_2")
	)
	(segment
		(start 112.627156 -14.395704)
		(end 114.283998 -16.052292)
		(width 0.127)
		(layer "In6.Cu")
		(net "CLK_50M_NCSI_OCP_V3_2")
	)
	(segment
		(start 111.27994 -15.74292)
		(end 111.27994 -15.563596)
		(width 0.127)
		(layer "In6.Cu")
		(net "CLK_50M_NCSI_OCP_V3_2")
	)
	(segment
		(start 125.64491 -16.21028)
		(end 125.64491 -13.524738)
		(width 0.127)
		(layer "In6.Cu")
		(net "CLK_50M_NCSI_OCP_V3_2")
	)
	(segment
		(start 122.46991 -15.624048)
		(end 122.59691 -15.751048)
		(width 0.127)
		(layer "In6.Cu")
		(net "CLK_50M_NCSI_OCP_V3_2")
	)
	(segment
		(start 113.834926 -16.680688)
		(end 113.834926 -16.501364)
		(width 0.127)
		(layer "In6.Cu")
		(net "CLK_50M_NCSI_OCP_V3_2")
	)
	(segment
		(start 118.456202 -16.548608)
		(end 118.583202 -16.675608)
		(width 0.127)
		(layer "In6.Cu")
		(net "CLK_50M_NCSI_OCP_V3_2")
	)
	(segment
		(start 125.51791 -16.33728)
		(end 125.64491 -16.21028)
		(width 0.127)
		(layer "In6.Cu")
		(net "CLK_50M_NCSI_OCP_V3_2")
	)
	(segment
		(start 115.361466 -15.154148)
		(end 117.117876 -13.397738)
		(width 0.127)
		(layer "In6.Cu")
		(net "CLK_50M_NCSI_OCP_V3_2")
	)
	(segment
		(start 194.853814 -12.65809)
		(end 196.279262 -13.24864)
		(width 0.127)
		(layer "In6.Cu")
		(net "CLK_50M_NCSI_OCP_V3_2")
	)
	(segment
		(start 119.853202 -16.675608)
		(end 120.234202 -16.675608)
		(width 0.127)
		(layer "In6.Cu")
		(net "CLK_50M_NCSI_OCP_V3_2")
	)
	(segment
		(start 193.77406 -11.4427)
		(end 193.869818 -11.674094)
		(width 0.127)
		(layer "In6.Cu")
		(net "CLK_50M_NCSI_OCP_V3_2")
	)
	(segment
		(start 108.021628 -18.633948)
		(end 108.021628 -21.852128)
		(width 0.127)
		(layer "In6.Cu")
		(net "CLK_50M_NCSI_OCP_V3_2")
	)
	(segment
		(start 216.121234 -17.981422)
		(end 214.669624 -16.529812)
		(width 0.12954)
		(layer "F.Cu")
		(net "CLK_50M_NCSI_OCP_2")
	)
	(segment
		(start 217.583766 -17.981422)
		(end 216.121234 -17.981422)
		(width 0.12954)
		(layer "F.Cu")
		(net "CLK_50M_NCSI_OCP_2")
	)
	(segment
		(start 217.583766 -16.781272)
		(end 217.583766 -17.981422)
		(width 0.12954)
		(layer "F.Cu")
		(net "CLK_50M_NCSI_OCP_2")
	)
	(segment
		(start 214.669624 -16.529812)
		(end 214.669624 -14.845792)
		(width 0.12954)
		(layer "F.Cu")
		(net "CLK_50M_NCSI_OCP_2")
	)
	(via
		(at 217.583766 -17.981422)
		(size 0.762)
		(drill 0.381)
		(layers "F.Cu" "B.Cu")
		(net "CLK_50M_NCSI_OCP_2")
	)
	(segment
		(start 240.36782 -122.359928)
		(end 238.589312 -124.138436)
		(width 0.13208)
		(layer "F.Cu")
		(net "CLK_100M_OCP_V3_2_D_R_DP")
	)
	(segment
		(start 242.63223 -121.986548)
		(end 242.25885 -122.359928)
		(width 0.13208)
		(layer "F.Cu")
		(net "CLK_100M_OCP_V3_2_D_R_DP")
	)
	(segment
		(start 242.25885 -122.359928)
		(end 240.36782 -122.359928)
		(width 0.13208)
		(layer "F.Cu")
		(net "CLK_100M_OCP_V3_2_D_R_DP")
	)
	(segment
		(start 238.589312 -124.138436)
		(end 237.868714 -124.138436)
		(width 0.13208)
		(layer "F.Cu")
		(net "CLK_100M_OCP_V3_2_D_R_DP")
	)
	(segment
		(start 237.868714 -124.138436)
		(end 237.748064 -124.017786)
		(width 0.13208)
		(layer "F.Cu")
		(net "CLK_100M_OCP_V3_2_D_R_DP")
	)
	(segment
		(start 242.2779 -122.619008)
		(end 240.475262 -122.619008)
		(width 0.13208)
		(layer "F.Cu")
		(net "CLK_100M_OCP_V3_2_D_R_DN")
	)
	(segment
		(start 242.63858 -123.004834)
		(end 242.63858 -122.979434)
		(width 0.13208)
		(layer "F.Cu")
		(net "CLK_100M_OCP_V3_2_D_R_DN")
	)
	(segment
		(start 242.63858 -122.979434)
		(end 242.2779 -122.619008)
		(width 0.13208)
		(layer "F.Cu")
		(net "CLK_100M_OCP_V3_2_D_R_DN")
	)
	(segment
		(start 237.86846 -124.397516)
		(end 237.748064 -124.517912)
		(width 0.13208)
		(layer "F.Cu")
		(net "CLK_100M_OCP_V3_2_D_R_DN")
	)
	(segment
		(start 240.475262 -122.619008)
		(end 238.696754 -124.397516)
		(width 0.13208)
		(layer "F.Cu")
		(net "CLK_100M_OCP_V3_2_D_R_DN")
	)
	(segment
		(start 238.696754 -124.397516)
		(end 237.86846 -124.397516)
		(width 0.13208)
		(layer "F.Cu")
		(net "CLK_100M_OCP_V3_2_D_R_DN")
	)
	(segment
		(start 245.651528 -122.35053)
		(end 245.944644 -122.057414)
		(width 0.13208)
		(layer "F.Cu")
		(net "CLK_100M_OCP_V3_2_D_DP")
	)
	(segment
		(start 71.461884 -7.795514)
		(end 71.633842 -7.623556)
		(width 0.13208)
		(layer "F.Cu")
		(net "CLK_100M_OCP_V3_2_D_DP")
	)
	(segment
		(start 243.43233 -121.986548)
		(end 243.800884 -122.355102)
		(width 0.13208)
		(layer "F.Cu")
		(net "CLK_100M_OCP_V3_2_D_DP")
	)
	(segment
		(start 243.800884 -122.355102)
		(end 243.828824 -122.355102)
		(width 0.13208)
		(layer "F.Cu")
		(net "CLK_100M_OCP_V3_2_D_DP")
	)
	(segment
		(start 71.633842 -7.623556)
		(end 71.633842 -7.026656)
		(width 0.13208)
		(layer "F.Cu")
		(net "CLK_100M_OCP_V3_2_D_DP")
	)
	(segment
		(start 245.632732 -122.35053)
		(end 245.651528 -122.35053)
		(width 0.13208)
		(layer "F.Cu")
		(net "CLK_100M_OCP_V3_2_D_DP")
	)
	(segment
		(start 243.828824 -122.355102)
		(end 245.632732 -122.35053)
		(width 0.13208)
		(layer "F.Cu")
		(net "CLK_100M_OCP_V3_2_D_DP")
	)
	(segment
		(start 71.633842 -7.026656)
		(end 71.331582 -6.724396)
		(width 0.13208)
		(layer "F.Cu")
		(net "CLK_100M_OCP_V3_2_D_DP")
	)
	(segment
		(start 71.461884 -8.320024)
		(end 71.461884 -7.795514)
		(width 0.13208)
		(layer "F.Cu")
		(net "CLK_100M_OCP_V3_2_D_DP")
	)
	(via
		(at 71.331582 -6.724396)
		(size 0.508)
		(drill 0.254)
		(layers "F.Cu" "B.Cu")
		(net "CLK_100M_OCP_V3_2_D_DP")
	)
	(via
		(at 245.944644 -122.057414)
		(size 0.508)
		(drill 0.254)
		(layers "F.Cu" "B.Cu")
		(net "CLK_100M_OCP_V3_2_D_DP")
	)
	(segment
		(start 79.390748 -10.300716)
		(end 79.741522 -11.147552)
		(width 0.13208)
		(layer "B.Cu")
		(net "CLK_100M_OCP_V3_2_D_DP")
	)
	(segment
		(start 244.767608 -118.614698)
		(end 245.055136 -118.902226)
		(width 0.13208)
		(layer "B.Cu")
		(net "CLK_100M_OCP_V3_2_D_DP")
	)
	(segment
		(start 245.80596 -119.65305)
		(end 245.981982 -119.65305)
		(width 0.13208)
		(layer "B.Cu")
		(net "CLK_100M_OCP_V3_2_D_DP")
	)
	(segment
		(start 246.269256 -120.116346)
		(end 246.556784 -120.403874)
		(width 0.13208)
		(layer "B.Cu")
		(net "CLK_100M_OCP_V3_2_D_DP")
	)
	(segment
		(start 246.246904 -122.359674)
		(end 245.944644 -122.057414)
		(width 0.13208)
		(layer "B.Cu")
		(net "CLK_100M_OCP_V3_2_D_DP")
	)
	(segment
		(start 245.518432 -119.1895)
		(end 245.518432 -119.365522)
		(width 0.13208)
		(layer "B.Cu")
		(net "CLK_100M_OCP_V3_2_D_DP")
	)
	(segment
		(start 149.62886 -80.388968)
		(end 150.37054 -80.388968)
		(width 0.13208)
		(layer "B.Cu")
		(net "CLK_100M_OCP_V3_2_D_DP")
	)
	(segment
		(start 244.480334 -118.151402)
		(end 244.767608 -118.438676)
		(width 0.13208)
		(layer "B.Cu")
		(net "CLK_100M_OCP_V3_2_D_DP")
	)
	(segment
		(start 175.504856 -84.665566)
		(end 202.767184 -84.665566)
		(width 0.13208)
		(layer "B.Cu")
		(net "CLK_100M_OCP_V3_2_D_DP")
	)
	(segment
		(start 150.926038 -80.944466)
		(end 151.990806 -81.385664)
		(width 0.13208)
		(layer "B.Cu")
		(net "CLK_100M_OCP_V3_2_D_DP")
	)
	(segment
		(start 202.767184 -84.665566)
		(end 228.977952 -95.522288)
		(width 0.13208)
		(layer "B.Cu")
		(net "CLK_100M_OCP_V3_2_D_DP")
	)
	(segment
		(start 78.32344 -9.233408)
		(end 79.390748 -10.300716)
		(width 0.13208)
		(layer "B.Cu")
		(net "CLK_100M_OCP_V3_2_D_DP")
	)
	(segment
		(start 246.601234 -122.359674)
		(end 246.246904 -122.359674)
		(width 0.13208)
		(layer "B.Cu")
		(net "CLK_100M_OCP_V3_2_D_DP")
	)
	(segment
		(start 112.43056 -53.135784)
		(end 112.43056 -72.259444)
		(width 0.13208)
		(layer "B.Cu")
		(net "CLK_100M_OCP_V3_2_D_DP")
	)
	(segment
		(start 238.04118 -110.667038)
		(end 240.148364 -113.81994)
		(width 0.13208)
		(layer "B.Cu")
		(net "CLK_100M_OCP_V3_2_D_DP")
	)
	(segment
		(start 116.721128 -79.867252)
		(end 119.92483 -81.194148)
		(width 0.13208)
		(layer "B.Cu")
		(net "CLK_100M_OCP_V3_2_D_DP")
	)
	(segment
		(start 88.568276 -39.73957)
		(end 92.08008 -41.194228)
		(width 0.13208)
		(layer "B.Cu")
		(net "CLK_100M_OCP_V3_2_D_DP")
	)
	(segment
		(start 79.741522 -11.147552)
		(end 85.22208 -16.627094)
		(width 0.13208)
		(layer "B.Cu")
		(net "CLK_100M_OCP_V3_2_D_DP")
	)
	(segment
		(start 244.016784 -117.863874)
		(end 244.304312 -118.151402)
		(width 0.13208)
		(layer "B.Cu")
		(net "CLK_100M_OCP_V3_2_D_DP")
	)
	(segment
		(start 240.148364 -113.81994)
		(end 244.016784 -117.687852)
		(width 0.13208)
		(layer "B.Cu")
		(net "CLK_100M_OCP_V3_2_D_DP")
	)
	(segment
		(start 246.732806 -120.403874)
		(end 247.02008 -120.691148)
		(width 0.13208)
		(layer "B.Cu")
		(net "CLK_100M_OCP_V3_2_D_DP")
	)
	(segment
		(start 245.055136 -118.902226)
		(end 245.231158 -118.902226)
		(width 0.13208)
		(layer "B.Cu")
		(net "CLK_100M_OCP_V3_2_D_DP")
	)
	(segment
		(start 92.08008 -41.194228)
		(end 100.391468 -41.194228)
		(width 0.13208)
		(layer "B.Cu")
		(net "CLK_100M_OCP_V3_2_D_DP")
	)
	(segment
		(start 228.977952 -95.522288)
		(end 233.741722 -100.286058)
		(width 0.13208)
		(layer "B.Cu")
		(net "CLK_100M_OCP_V3_2_D_DP")
	)
	(segment
		(start 247.02008 -121.940828)
		(end 246.601234 -122.359674)
		(width 0.13208)
		(layer "B.Cu")
		(net "CLK_100M_OCP_V3_2_D_DP")
	)
	(segment
		(start 233.741722 -100.286058)
		(end 238.04118 -110.667038)
		(width 0.13208)
		(layer "B.Cu")
		(net "CLK_100M_OCP_V3_2_D_DP")
	)
	(segment
		(start 245.231158 -118.902226)
		(end 245.518432 -119.1895)
		(width 0.13208)
		(layer "B.Cu")
		(net "CLK_100M_OCP_V3_2_D_DP")
	)
	(segment
		(start 247.02008 -120.691148)
		(end 247.02008 -121.940828)
		(width 0.13208)
		(layer "B.Cu")
		(net "CLK_100M_OCP_V3_2_D_DP")
	)
	(segment
		(start 171.07281 -82.829908)
		(end 175.504856 -84.665566)
		(width 0.13208)
		(layer "B.Cu")
		(net "CLK_100M_OCP_V3_2_D_DP")
	)
	(segment
		(start 85.22208 -16.627094)
		(end 85.22208 -33.945068)
		(width 0.13208)
		(layer "B.Cu")
		(net "CLK_100M_OCP_V3_2_D_DP")
	)
	(segment
		(start 244.016784 -117.687852)
		(end 244.016784 -117.863874)
		(width 0.13208)
		(layer "B.Cu")
		(net "CLK_100M_OCP_V3_2_D_DP")
	)
	(segment
		(start 246.269256 -119.940324)
		(end 246.269256 -120.116346)
		(width 0.13208)
		(layer "B.Cu")
		(net "CLK_100M_OCP_V3_2_D_DP")
	)
	(segment
		(start 85.22208 -33.945068)
		(end 86.95309 -38.124384)
		(width 0.13208)
		(layer "B.Cu")
		(net "CLK_100M_OCP_V3_2_D_DP")
	)
	(segment
		(start 245.518432 -119.365522)
		(end 245.80596 -119.65305)
		(width 0.13208)
		(layer "B.Cu")
		(net "CLK_100M_OCP_V3_2_D_DP")
	)
	(segment
		(start 71.634096 -7.026656)
		(end 71.634096 -7.67842)
		(width 0.13208)
		(layer "B.Cu")
		(net "CLK_100M_OCP_V3_2_D_DP")
	)
	(segment
		(start 119.92483 -81.194148)
		(end 148.82368 -81.194148)
		(width 0.13208)
		(layer "B.Cu")
		(net "CLK_100M_OCP_V3_2_D_DP")
	)
	(segment
		(start 150.37054 -80.388968)
		(end 150.926038 -80.944466)
		(width 0.13208)
		(layer "B.Cu")
		(net "CLK_100M_OCP_V3_2_D_DP")
	)
	(segment
		(start 105.844086 -43.452796)
		(end 110.24108 -47.84979)
		(width 0.13208)
		(layer "B.Cu")
		(net "CLK_100M_OCP_V3_2_D_DP")
	)
	(segment
		(start 244.304312 -118.151402)
		(end 244.480334 -118.151402)
		(width 0.13208)
		(layer "B.Cu")
		(net "CLK_100M_OCP_V3_2_D_DP")
	)
	(segment
		(start 148.82368 -81.194148)
		(end 149.62886 -80.388968)
		(width 0.13208)
		(layer "B.Cu")
		(net "CLK_100M_OCP_V3_2_D_DP")
	)
	(segment
		(start 244.767608 -118.438676)
		(end 244.767608 -118.614698)
		(width 0.13208)
		(layer "B.Cu")
		(net "CLK_100M_OCP_V3_2_D_DP")
	)
	(segment
		(start 159.25165 -82.829908)
		(end 171.07281 -82.829908)
		(width 0.13208)
		(layer "B.Cu")
		(net "CLK_100M_OCP_V3_2_D_DP")
	)
	(segment
		(start 71.331582 -6.724396)
		(end 71.331836 -6.724396)
		(width 0.13208)
		(layer "B.Cu")
		(net "CLK_100M_OCP_V3_2_D_DP")
	)
	(segment
		(start 110.24108 -47.84979)
		(end 112.43056 -53.135784)
		(width 0.13208)
		(layer "B.Cu")
		(net "CLK_100M_OCP_V3_2_D_DP")
	)
	(segment
		(start 151.990806 -81.385664)
		(end 159.25165 -82.829908)
		(width 0.13208)
		(layer "B.Cu")
		(net "CLK_100M_OCP_V3_2_D_DP")
	)
	(segment
		(start 114.779044 -77.925168)
		(end 116.721128 -79.867252)
		(width 0.13208)
		(layer "B.Cu")
		(net "CLK_100M_OCP_V3_2_D_DP")
	)
	(segment
		(start 76.778104 -8.593328)
		(end 78.32344 -9.233408)
		(width 0.13208)
		(layer "B.Cu")
		(net "CLK_100M_OCP_V3_2_D_DP")
	)
	(segment
		(start 245.981982 -119.65305)
		(end 246.269256 -119.940324)
		(width 0.13208)
		(layer "B.Cu")
		(net "CLK_100M_OCP_V3_2_D_DP")
	)
	(segment
		(start 112.43056 -72.259444)
		(end 114.779044 -77.925168)
		(width 0.13208)
		(layer "B.Cu")
		(net "CLK_100M_OCP_V3_2_D_DP")
	)
	(segment
		(start 71.634096 -7.67842)
		(end 72.549004 -8.593328)
		(width 0.13208)
		(layer "B.Cu")
		(net "CLK_100M_OCP_V3_2_D_DP")
	)
	(segment
		(start 86.95309 -38.124384)
		(end 88.568276 -39.73957)
		(width 0.13208)
		(layer "B.Cu")
		(net "CLK_100M_OCP_V3_2_D_DP")
	)
	(segment
		(start 72.549004 -8.593328)
		(end 76.778104 -8.593328)
		(width 0.13208)
		(layer "B.Cu")
		(net "CLK_100M_OCP_V3_2_D_DP")
	)
	(segment
		(start 246.556784 -120.403874)
		(end 246.732806 -120.403874)
		(width 0.13208)
		(layer "B.Cu")
		(net "CLK_100M_OCP_V3_2_D_DP")
	)
	(segment
		(start 100.391468 -41.194228)
		(end 105.844086 -43.452796)
		(width 0.13208)
		(layer "B.Cu")
		(net "CLK_100M_OCP_V3_2_D_DP")
	)
	(segment
		(start 71.331836 -6.724396)
		(end 71.634096 -7.026656)
		(width 0.13208)
		(layer "B.Cu")
		(net "CLK_100M_OCP_V3_2_D_DP")
	)
	(segment
		(start 71.892922 -7.610856)
		(end 71.892922 -7.026656)
		(width 0.13208)
		(layer "F.Cu")
		(net "CLK_100M_OCP_V3_2_D_DN")
	)
	(segment
		(start 72.062086 -7.78002)
		(end 71.892922 -7.610856)
		(width 0.13208)
		(layer "F.Cu")
		(net "CLK_100M_OCP_V3_2_D_DN")
	)
	(segment
		(start 72.062086 -8.320024)
		(end 72.062086 -7.78002)
		(width 0.13208)
		(layer "F.Cu")
		(net "CLK_100M_OCP_V3_2_D_DN")
	)
	(segment
		(start 245.63324 -122.60961)
		(end 245.944644 -122.921014)
		(width 0.13208)
		(layer "F.Cu")
		(net "CLK_100M_OCP_V3_2_D_DN")
	)
	(segment
		(start 243.43868 -123.004834)
		(end 243.829332 -122.614182)
		(width 0.13208)
		(layer "F.Cu")
		(net "CLK_100M_OCP_V3_2_D_DN")
	)
	(segment
		(start 71.892922 -7.026656)
		(end 72.195182 -6.724396)
		(width 0.13208)
		(layer "F.Cu")
		(net "CLK_100M_OCP_V3_2_D_DN")
	)
	(segment
		(start 243.829332 -122.614182)
		(end 245.63324 -122.60961)
		(width 0.13208)
		(layer "F.Cu")
		(net "CLK_100M_OCP_V3_2_D_DN")
	)
	(via
		(at 72.195182 -6.724396)
		(size 0.508)
		(drill 0.254)
		(layers "F.Cu" "B.Cu")
		(net "CLK_100M_OCP_V3_2_D_DN")
	)
	(via
		(at 245.944644 -122.921014)
		(size 0.508)
		(drill 0.254)
		(layers "F.Cu" "B.Cu")
		(net "CLK_100M_OCP_V3_2_D_DN")
	)
	(segment
		(start 88.715088 -39.51986)
		(end 92.131642 -40.935148)
		(width 0.13208)
		(layer "B.Cu")
		(net "CLK_100M_OCP_V3_2_D_DN")
	)
	(segment
		(start 247.27916 -122.04827)
		(end 246.708676 -122.618754)
		(width 0.13208)
		(layer "B.Cu")
		(net "CLK_100M_OCP_V3_2_D_DN")
	)
	(segment
		(start 92.131642 -40.935148)
		(end 100.44303 -40.935148)
		(width 0.13208)
		(layer "B.Cu")
		(net "CLK_100M_OCP_V3_2_D_DN")
	)
	(segment
		(start 151.07285 -80.724756)
		(end 152.066498 -81.13649)
		(width 0.13208)
		(layer "B.Cu")
		(net "CLK_100M_OCP_V3_2_D_DN")
	)
	(segment
		(start 246.708676 -122.618754)
		(end 246.246904 -122.618754)
		(width 0.13208)
		(layer "B.Cu")
		(net "CLK_100M_OCP_V3_2_D_DN")
	)
	(segment
		(start 119.976392 -80.935068)
		(end 148.716238 -80.935068)
		(width 0.13208)
		(layer "B.Cu")
		(net "CLK_100M_OCP_V3_2_D_DN")
	)
	(segment
		(start 72.195182 -6.724396)
		(end 71.893176 -7.026402)
		(width 0.13208)
		(layer "B.Cu")
		(net "CLK_100M_OCP_V3_2_D_DN")
	)
	(segment
		(start 71.893176 -7.570978)
		(end 72.656446 -8.334248)
		(width 0.13208)
		(layer "B.Cu")
		(net "CLK_100M_OCP_V3_2_D_DN")
	)
	(segment
		(start 246.246904 -122.618754)
		(end 245.944644 -122.921014)
		(width 0.13208)
		(layer "B.Cu")
		(net "CLK_100M_OCP_V3_2_D_DN")
	)
	(segment
		(start 105.990898 -43.233086)
		(end 110.46079 -47.702978)
		(width 0.13208)
		(layer "B.Cu")
		(net "CLK_100M_OCP_V3_2_D_DN")
	)
	(segment
		(start 240.349786 -113.654586)
		(end 247.27916 -120.583706)
		(width 0.13208)
		(layer "B.Cu")
		(net "CLK_100M_OCP_V3_2_D_DN")
	)
	(segment
		(start 152.066498 -81.13649)
		(end 159.277304 -82.570828)
		(width 0.13208)
		(layer "B.Cu")
		(net "CLK_100M_OCP_V3_2_D_DN")
	)
	(segment
		(start 229.124764 -95.302578)
		(end 233.961432 -100.139246)
		(width 0.13208)
		(layer "B.Cu")
		(net "CLK_100M_OCP_V3_2_D_DN")
	)
	(segment
		(start 85.48116 -33.893506)
		(end 87.1728 -37.977572)
		(width 0.13208)
		(layer "B.Cu")
		(net "CLK_100M_OCP_V3_2_D_DN")
	)
	(segment
		(start 150.477982 -80.129888)
		(end 151.07285 -80.724756)
		(width 0.13208)
		(layer "B.Cu")
		(net "CLK_100M_OCP_V3_2_D_DN")
	)
	(segment
		(start 247.27916 -120.583706)
		(end 247.27916 -122.04827)
		(width 0.13208)
		(layer "B.Cu")
		(net "CLK_100M_OCP_V3_2_D_DN")
	)
	(segment
		(start 71.893176 -7.026402)
		(end 71.893176 -7.570978)
		(width 0.13208)
		(layer "B.Cu")
		(net "CLK_100M_OCP_V3_2_D_DN")
	)
	(segment
		(start 79.610458 -10.153904)
		(end 79.961232 -11.00074)
		(width 0.13208)
		(layer "B.Cu")
		(net "CLK_100M_OCP_V3_2_D_DN")
	)
	(segment
		(start 149.521418 -80.129888)
		(end 150.477982 -80.129888)
		(width 0.13208)
		(layer "B.Cu")
		(net "CLK_100M_OCP_V3_2_D_DN")
	)
	(segment
		(start 202.818746 -84.406486)
		(end 229.124764 -95.302578)
		(width 0.13208)
		(layer "B.Cu")
		(net "CLK_100M_OCP_V3_2_D_DN")
	)
	(segment
		(start 85.48116 -16.519652)
		(end 85.48116 -33.893506)
		(width 0.13208)
		(layer "B.Cu")
		(net "CLK_100M_OCP_V3_2_D_DN")
	)
	(segment
		(start 87.1728 -37.977572)
		(end 88.715088 -39.51986)
		(width 0.13208)
		(layer "B.Cu")
		(net "CLK_100M_OCP_V3_2_D_DN")
	)
	(segment
		(start 78.470252 -9.013698)
		(end 79.610458 -10.153904)
		(width 0.13208)
		(layer "B.Cu")
		(net "CLK_100M_OCP_V3_2_D_DN")
	)
	(segment
		(start 175.556418 -84.406486)
		(end 202.818746 -84.406486)
		(width 0.13208)
		(layer "B.Cu")
		(net "CLK_100M_OCP_V3_2_D_DN")
	)
	(segment
		(start 100.44303 -40.935148)
		(end 105.990898 -43.233086)
		(width 0.13208)
		(layer "B.Cu")
		(net "CLK_100M_OCP_V3_2_D_DN")
	)
	(segment
		(start 72.656446 -8.334248)
		(end 76.829666 -8.334248)
		(width 0.13208)
		(layer "B.Cu")
		(net "CLK_100M_OCP_V3_2_D_DN")
	)
	(segment
		(start 79.961232 -11.00074)
		(end 85.48116 -16.519652)
		(width 0.13208)
		(layer "B.Cu")
		(net "CLK_100M_OCP_V3_2_D_DN")
	)
	(segment
		(start 238.27105 -110.544102)
		(end 240.349786 -113.654586)
		(width 0.13208)
		(layer "B.Cu")
		(net "CLK_100M_OCP_V3_2_D_DN")
	)
	(segment
		(start 76.829666 -8.334248)
		(end 78.470252 -9.013698)
		(width 0.13208)
		(layer "B.Cu")
		(net "CLK_100M_OCP_V3_2_D_DN")
	)
	(segment
		(start 112.68964 -72.207628)
		(end 114.998754 -77.778356)
		(width 0.13208)
		(layer "B.Cu")
		(net "CLK_100M_OCP_V3_2_D_DN")
	)
	(segment
		(start 148.716238 -80.935068)
		(end 149.521418 -80.129888)
		(width 0.13208)
		(layer "B.Cu")
		(net "CLK_100M_OCP_V3_2_D_DN")
	)
	(segment
		(start 159.277304 -82.570828)
		(end 171.124372 -82.570828)
		(width 0.13208)
		(layer "B.Cu")
		(net "CLK_100M_OCP_V3_2_D_DN")
	)
	(segment
		(start 116.86794 -79.647542)
		(end 119.976392 -80.935068)
		(width 0.13208)
		(layer "B.Cu")
		(net "CLK_100M_OCP_V3_2_D_DN")
	)
	(segment
		(start 112.68964 -53.084222)
		(end 112.68964 -72.207628)
		(width 0.13208)
		(layer "B.Cu")
		(net "CLK_100M_OCP_V3_2_D_DN")
	)
	(segment
		(start 114.998754 -77.778356)
		(end 116.86794 -79.647542)
		(width 0.13208)
		(layer "B.Cu")
		(net "CLK_100M_OCP_V3_2_D_DN")
	)
	(segment
		(start 171.124372 -82.570828)
		(end 175.556418 -84.406486)
		(width 0.13208)
		(layer "B.Cu")
		(net "CLK_100M_OCP_V3_2_D_DN")
	)
	(segment
		(start 110.46079 -47.702978)
		(end 112.68964 -53.084222)
		(width 0.13208)
		(layer "B.Cu")
		(net "CLK_100M_OCP_V3_2_D_DN")
	)
	(segment
		(start 233.961432 -100.139246)
		(end 238.27105 -110.544102)
		(width 0.13208)
		(layer "B.Cu")
		(net "CLK_100M_OCP_V3_2_D_DN")
	)
	(segment
		(start 238.429038 -121.625868)
		(end 236.868462 -123.186444)
		(width 0.13208)
		(layer "F.Cu")
		(net "CLK_100M_OCP_V3_2_C_R_DP")
	)
	(segment
		(start 239.203738 -119.583708)
		(end 239.5982 -119.97817)
		(width 0.13208)
		(layer "F.Cu")
		(net "CLK_100M_OCP_V3_2_C_R_DP")
	)
	(segment
		(start 238.937038 -121.625868)
		(end 238.429038 -121.625868)
		(width 0.13208)
		(layer "F.Cu")
		(net "CLK_100M_OCP_V3_2_C_R_DP")
	)
	(segment
		(start 239.5982 -120.964706)
		(end 238.937038 -121.625868)
		(width 0.13208)
		(layer "F.Cu")
		(net "CLK_100M_OCP_V3_2_C_R_DP")
	)
	(segment
		(start 236.868462 -123.186444)
		(end 236.868462 -123.89739)
		(width 0.13208)
		(layer "F.Cu")
		(net "CLK_100M_OCP_V3_2_C_R_DP")
	)
	(segment
		(start 239.5982 -119.97817)
		(end 239.5982 -120.964706)
		(width 0.13208)
		(layer "F.Cu")
		(net "CLK_100M_OCP_V3_2_C_R_DP")
	)
	(segment
		(start 236.868462 -123.89739)
		(end 236.748066 -124.017786)
		(width 0.13208)
		(layer "F.Cu")
		(net "CLK_100M_OCP_V3_2_C_R_DP")
	)
	(segment
		(start 238.53648 -121.884948)
		(end 237.127542 -123.293886)
		(width 0.13208)
		(layer "F.Cu")
		(net "CLK_100M_OCP_V3_2_C_R_DN")
	)
	(segment
		(start 239.85728 -121.072148)
		(end 239.04448 -121.884948)
		(width 0.13208)
		(layer "F.Cu")
		(net "CLK_100M_OCP_V3_2_C_R_DN")
	)
	(segment
		(start 240.219738 -119.583708)
		(end 239.85728 -119.946166)
		(width 0.13208)
		(layer "F.Cu")
		(net "CLK_100M_OCP_V3_2_C_R_DN")
	)
	(segment
		(start 239.04448 -121.884948)
		(end 238.53648 -121.884948)
		(width 0.13208)
		(layer "F.Cu")
		(net "CLK_100M_OCP_V3_2_C_R_DN")
	)
	(segment
		(start 237.127542 -123.293886)
		(end 237.127542 -123.89739)
		(width 0.13208)
		(layer "F.Cu")
		(net "CLK_100M_OCP_V3_2_C_R_DN")
	)
	(segment
		(start 237.127542 -123.89739)
		(end 237.247938 -124.017786)
		(width 0.13208)
		(layer "F.Cu")
		(net "CLK_100M_OCP_V3_2_C_R_DN")
	)
	(segment
		(start 239.85728 -119.946166)
		(end 239.85728 -121.072148)
		(width 0.13208)
		(layer "F.Cu")
		(net "CLK_100M_OCP_V3_2_C_R_DN")
	)
	(segment
		(start 71.461884 -11.806428)
		(end 71.63308 -11.977624)
		(width 0.13208)
		(layer "F.Cu")
		(net "CLK_100M_OCP_V3_2_C_DP")
	)
	(segment
		(start 239.582198 -118.405148)
		(end 239.582198 -117.907308)
		(width 0.13208)
		(layer "F.Cu")
		(net "CLK_100M_OCP_V3_2_C_DP")
	)
	(segment
		(start 239.582198 -117.907308)
		(end 239.279938 -117.605048)
		(width 0.13208)
		(layer "F.Cu")
		(net "CLK_100M_OCP_V3_2_C_DP")
	)
	(segment
		(start 71.63308 -11.977624)
		(end 71.63308 -12.561824)
		(width 0.13208)
		(layer "F.Cu")
		(net "CLK_100M_OCP_V3_2_C_DP")
	)
	(segment
		(start 71.461884 -11.26998)
		(end 71.461884 -11.806428)
		(width 0.13208)
		(layer "F.Cu")
		(net "CLK_100M_OCP_V3_2_C_DP")
	)
	(segment
		(start 71.63308 -12.561824)
		(end 71.33082 -12.864084)
		(width 0.13208)
		(layer "F.Cu")
		(net "CLK_100M_OCP_V3_2_C_DP")
	)
	(segment
		(start 239.203738 -118.783608)
		(end 239.582198 -118.405148)
		(width 0.13208)
		(layer "F.Cu")
		(net "CLK_100M_OCP_V3_2_C_DP")
	)
	(via
		(at 239.279938 -117.605048)
		(size 0.508)
		(drill 0.254)
		(layers "F.Cu" "B.Cu")
		(net "CLK_100M_OCP_V3_2_C_DP")
	)
	(via
		(at 71.33082 -12.864084)
		(size 0.508)
		(drill 0.254)
		(layers "F.Cu" "B.Cu")
		(net "CLK_100M_OCP_V3_2_C_DP")
	)
	(segment
		(start 75.05954 -14.277848)
		(end 80.575658 -14.277848)
		(width 0.13208)
		(layer "B.Cu")
		(net "CLK_100M_OCP_V3_2_C_DP")
	)
	(segment
		(start 111.451136 -53.208936)
		(end 111.451136 -74.719688)
		(width 0.13208)
		(layer "B.Cu")
		(net "CLK_100M_OCP_V3_2_C_DP")
	)
	(segment
		(start 91.895422 -42.118788)
		(end 100.15982 -42.118788)
		(width 0.13208)
		(layer "B.Cu")
		(net "CLK_100M_OCP_V3_2_C_DP")
	)
	(segment
		(start 104.622854 -43.9674)
		(end 109.745272 -49.089818)
		(width 0.13208)
		(layer "B.Cu")
		(net "CLK_100M_OCP_V3_2_C_DP")
	)
	(segment
		(start 111.96447 -75.959462)
		(end 113.937288 -78.911704)
		(width 0.13208)
		(layer "B.Cu")
		(net "CLK_100M_OCP_V3_2_C_DP")
	)
	(segment
		(start 71.632826 -13.16609)
		(end 71.632826 -13.46073)
		(width 0.13208)
		(layer "B.Cu")
		(net "CLK_100M_OCP_V3_2_C_DP")
	)
	(segment
		(start 157.609032 -85.108288)
		(end 158.451804 -84.760308)
		(width 0.13208)
		(layer "B.Cu")
		(net "CLK_100M_OCP_V3_2_C_DP")
	)
	(segment
		(start 145.601182 -83.264248)
		(end 150.286974 -85.184488)
		(width 0.13208)
		(layer "B.Cu")
		(net "CLK_100M_OCP_V3_2_C_DP")
	)
	(segment
		(start 203.858114 -86.118446)
		(end 228.453442 -96.306132)
		(width 0.13208)
		(layer "B.Cu")
		(net "CLK_100M_OCP_V3_2_C_DP")
	)
	(segment
		(start 74.60488 -14.732508)
		(end 75.05954 -14.277848)
		(width 0.13208)
		(layer "B.Cu")
		(net "CLK_100M_OCP_V3_2_C_DP")
	)
	(segment
		(start 154.9781 -84.816188)
		(end 156.67228 -84.816188)
		(width 0.13208)
		(layer "B.Cu")
		(net "CLK_100M_OCP_V3_2_C_DP")
	)
	(segment
		(start 175.960278 -86.118446)
		(end 203.858114 -86.118446)
		(width 0.13208)
		(layer "B.Cu")
		(net "CLK_100M_OCP_V3_2_C_DP")
	)
	(segment
		(start 124.635514 -83.264248)
		(end 145.601182 -83.264248)
		(width 0.13208)
		(layer "B.Cu")
		(net "CLK_100M_OCP_V3_2_C_DP")
	)
	(segment
		(start 239.582198 -116.898928)
		(end 239.582198 -117.302788)
		(width 0.13208)
		(layer "B.Cu")
		(net "CLK_100M_OCP_V3_2_C_DP")
	)
	(segment
		(start 81.791048 -14.781276)
		(end 84.28228 -17.272508)
		(width 0.13208)
		(layer "B.Cu")
		(net "CLK_100M_OCP_V3_2_C_DP")
	)
	(segment
		(start 156.67228 -84.816188)
		(end 156.96438 -85.108288)
		(width 0.13208)
		(layer "B.Cu")
		(net "CLK_100M_OCP_V3_2_C_DP")
	)
	(segment
		(start 232.889806 -100.742496)
		(end 239.582198 -116.898928)
		(width 0.13208)
		(layer "B.Cu")
		(net "CLK_100M_OCP_V3_2_C_DP")
	)
	(segment
		(start 86.169246 -38.64864)
		(end 88.04402 -40.523414)
		(width 0.13208)
		(layer "B.Cu")
		(net "CLK_100M_OCP_V3_2_C_DP")
	)
	(segment
		(start 172.681138 -84.760308)
		(end 175.960278 -86.118446)
		(width 0.13208)
		(layer "B.Cu")
		(net "CLK_100M_OCP_V3_2_C_DP")
	)
	(segment
		(start 156.96438 -85.108288)
		(end 157.609032 -85.108288)
		(width 0.13208)
		(layer "B.Cu")
		(net "CLK_100M_OCP_V3_2_C_DP")
	)
	(segment
		(start 119.4181 -82.226404)
		(end 124.635514 -83.264248)
		(width 0.13208)
		(layer "B.Cu")
		(net "CLK_100M_OCP_V3_2_C_DP")
	)
	(segment
		(start 113.937288 -78.911704)
		(end 115.720368 -80.694784)
		(width 0.13208)
		(layer "B.Cu")
		(net "CLK_100M_OCP_V3_2_C_DP")
	)
	(segment
		(start 150.286974 -85.184488)
		(end 154.6098 -85.184488)
		(width 0.13208)
		(layer "B.Cu")
		(net "CLK_100M_OCP_V3_2_C_DP")
	)
	(segment
		(start 84.28228 -17.272508)
		(end 84.28228 -34.092896)
		(width 0.13208)
		(layer "B.Cu")
		(net "CLK_100M_OCP_V3_2_C_DP")
	)
	(segment
		(start 71.632826 -13.46073)
		(end 72.904604 -14.732508)
		(width 0.13208)
		(layer "B.Cu")
		(net "CLK_100M_OCP_V3_2_C_DP")
	)
	(segment
		(start 239.582198 -117.302788)
		(end 239.279938 -117.605048)
		(width 0.13208)
		(layer "B.Cu")
		(net "CLK_100M_OCP_V3_2_C_DP")
	)
	(segment
		(start 100.15982 -42.118788)
		(end 104.622854 -43.9674)
		(width 0.13208)
		(layer "B.Cu")
		(net "CLK_100M_OCP_V3_2_C_DP")
	)
	(segment
		(start 88.04402 -40.523414)
		(end 91.895422 -42.118788)
		(width 0.13208)
		(layer "B.Cu")
		(net "CLK_100M_OCP_V3_2_C_DP")
	)
	(segment
		(start 111.451136 -74.719688)
		(end 111.96447 -75.959462)
		(width 0.13208)
		(layer "B.Cu")
		(net "CLK_100M_OCP_V3_2_C_DP")
	)
	(segment
		(start 109.745272 -49.089818)
		(end 111.451136 -53.208936)
		(width 0.13208)
		(layer "B.Cu")
		(net "CLK_100M_OCP_V3_2_C_DP")
	)
	(segment
		(start 115.720368 -80.694784)
		(end 119.4181 -82.226404)
		(width 0.13208)
		(layer "B.Cu")
		(net "CLK_100M_OCP_V3_2_C_DP")
	)
	(segment
		(start 72.904604 -14.732508)
		(end 74.60488 -14.732508)
		(width 0.13208)
		(layer "B.Cu")
		(net "CLK_100M_OCP_V3_2_C_DP")
	)
	(segment
		(start 228.453442 -96.306132)
		(end 232.889806 -100.742496)
		(width 0.13208)
		(layer "B.Cu")
		(net "CLK_100M_OCP_V3_2_C_DP")
	)
	(segment
		(start 84.28228 -34.092896)
		(end 86.169246 -38.64864)
		(width 0.13208)
		(layer "B.Cu")
		(net "CLK_100M_OCP_V3_2_C_DP")
	)
	(segment
		(start 71.33082 -12.864084)
		(end 71.632826 -13.16609)
		(width 0.13208)
		(layer "B.Cu")
		(net "CLK_100M_OCP_V3_2_C_DP")
	)
	(segment
		(start 158.451804 -84.760308)
		(end 172.681138 -84.760308)
		(width 0.13208)
		(layer "B.Cu")
		(net "CLK_100M_OCP_V3_2_C_DP")
	)
	(segment
		(start 154.6098 -85.184488)
		(end 154.9781 -84.816188)
		(width 0.13208)
		(layer "B.Cu")
		(net "CLK_100M_OCP_V3_2_C_DP")
	)
	(segment
		(start 80.575658 -14.277848)
		(end 81.791048 -14.781276)
		(width 0.13208)
		(layer "B.Cu")
		(net "CLK_100M_OCP_V3_2_C_DP")
	)
	(segment
		(start 239.841278 -117.907308)
		(end 240.143538 -117.605048)
		(width 0.13208)
		(layer "F.Cu")
		(net "CLK_100M_OCP_V3_2_C_DN")
	)
	(segment
		(start 240.219738 -118.783608)
		(end 239.841278 -118.405148)
		(width 0.13208)
		(layer "F.Cu")
		(net "CLK_100M_OCP_V3_2_C_DN")
	)
	(segment
		(start 72.062086 -11.794998)
		(end 71.89216 -11.964924)
		(width 0.13208)
		(layer "F.Cu")
		(net "CLK_100M_OCP_V3_2_C_DN")
	)
	(segment
		(start 71.89216 -12.561824)
		(end 72.19442 -12.864084)
		(width 0.13208)
		(layer "F.Cu")
		(net "CLK_100M_OCP_V3_2_C_DN")
	)
	(segment
		(start 72.062086 -11.26998)
		(end 72.062086 -11.794998)
		(width 0.13208)
		(layer "F.Cu")
		(net "CLK_100M_OCP_V3_2_C_DN")
	)
	(segment
		(start 71.89216 -11.964924)
		(end 71.89216 -12.561824)
		(width 0.13208)
		(layer "F.Cu")
		(net "CLK_100M_OCP_V3_2_C_DN")
	)
	(segment
		(start 239.841278 -118.405148)
		(end 239.841278 -117.907308)
		(width 0.13208)
		(layer "F.Cu")
		(net "CLK_100M_OCP_V3_2_C_DN")
	)
	(via
		(at 240.143538 -117.605048)
		(size 0.508)
		(drill 0.254)
		(layers "F.Cu" "B.Cu")
		(net "CLK_100M_OCP_V3_2_C_DN")
	)
	(via
		(at 72.19442 -12.864084)
		(size 0.508)
		(drill 0.254)
		(layers "F.Cu" "B.Cu")
		(net "CLK_100M_OCP_V3_2_C_DN")
	)
	(segment
		(start 112.194848 -75.837542)
		(end 113.166652 -77.291946)
		(width 0.13208)
		(layer "B.Cu")
		(net "CLK_100M_OCP_V3_2_C_DN")
	)
	(segment
		(start 111.710216 -53.157374)
		(end 111.710216 -74.668126)
		(width 0.13208)
		(layer "B.Cu")
		(net "CLK_100M_OCP_V3_2_C_DN")
	)
	(segment
		(start 115.86718 -80.475074)
		(end 119.493792 -81.97723)
		(width 0.13208)
		(layer "B.Cu")
		(net "CLK_100M_OCP_V3_2_C_DN")
	)
	(segment
		(start 150.338028 -84.925408)
		(end 154.502358 -84.925408)
		(width 0.13208)
		(layer "B.Cu")
		(net "CLK_100M_OCP_V3_2_C_DN")
	)
	(segment
		(start 80.62722 -14.018768)
		(end 81.93786 -14.561566)
		(width 0.13208)
		(layer "B.Cu")
		(net "CLK_100M_OCP_V3_2_C_DN")
	)
	(segment
		(start 88.190832 -40.303704)
		(end 91.946984 -41.859708)
		(width 0.13208)
		(layer "B.Cu")
		(net "CLK_100M_OCP_V3_2_C_DN")
	)
	(segment
		(start 72.19442 -12.864084)
		(end 72.194166 -12.864084)
		(width 0.13208)
		(layer "B.Cu")
		(net "CLK_100M_OCP_V3_2_C_DN")
	)
	(segment
		(start 239.841278 -116.847366)
		(end 239.841278 -117.302788)
		(width 0.13208)
		(layer "B.Cu")
		(net "CLK_100M_OCP_V3_2_C_DN")
	)
	(segment
		(start 158.400242 -84.501228)
		(end 172.7327 -84.501228)
		(width 0.13208)
		(layer "B.Cu")
		(net "CLK_100M_OCP_V3_2_C_DN")
	)
	(segment
		(start 113.166398 -77.291946)
		(end 114.13871 -78.74635)
		(width 0.13208)
		(layer "B.Cu")
		(net "CLK_100M_OCP_V3_2_C_DN")
	)
	(segment
		(start 114.13871 -78.74635)
		(end 115.86718 -80.475074)
		(width 0.13208)
		(layer "B.Cu")
		(net "CLK_100M_OCP_V3_2_C_DN")
	)
	(segment
		(start 176.01184 -85.859366)
		(end 203.909676 -85.859366)
		(width 0.13208)
		(layer "B.Cu")
		(net "CLK_100M_OCP_V3_2_C_DN")
	)
	(segment
		(start 145.652236 -83.005168)
		(end 150.338028 -84.925408)
		(width 0.13208)
		(layer "B.Cu")
		(net "CLK_100M_OCP_V3_2_C_DN")
	)
	(segment
		(start 72.194166 -12.864084)
		(end 71.891906 -13.166344)
		(width 0.13208)
		(layer "B.Cu")
		(net "CLK_100M_OCP_V3_2_C_DN")
	)
	(segment
		(start 112.19434 -75.836526)
		(end 112.194848 -75.837542)
		(width 0.13208)
		(layer "B.Cu")
		(net "CLK_100M_OCP_V3_2_C_DN")
	)
	(segment
		(start 73.012046 -14.473428)
		(end 74.497438 -14.473428)
		(width 0.13208)
		(layer "B.Cu")
		(net "CLK_100M_OCP_V3_2_C_DN")
	)
	(segment
		(start 81.93786 -14.561566)
		(end 84.54136 -17.165066)
		(width 0.13208)
		(layer "B.Cu")
		(net "CLK_100M_OCP_V3_2_C_DN")
	)
	(segment
		(start 86.388956 -38.501828)
		(end 88.190832 -40.303704)
		(width 0.13208)
		(layer "B.Cu")
		(net "CLK_100M_OCP_V3_2_C_DN")
	)
	(segment
		(start 74.497438 -14.473428)
		(end 74.952098 -14.018768)
		(width 0.13208)
		(layer "B.Cu")
		(net "CLK_100M_OCP_V3_2_C_DN")
	)
	(segment
		(start 109.964982 -48.943006)
		(end 111.710216 -53.157374)
		(width 0.13208)
		(layer "B.Cu")
		(net "CLK_100M_OCP_V3_2_C_DN")
	)
	(segment
		(start 233.109516 -100.595684)
		(end 239.841278 -116.847366)
		(width 0.13208)
		(layer "B.Cu")
		(net "CLK_100M_OCP_V3_2_C_DN")
	)
	(segment
		(start 157.071822 -84.849208)
		(end 157.55747 -84.849208)
		(width 0.13208)
		(layer "B.Cu")
		(net "CLK_100M_OCP_V3_2_C_DN")
	)
	(segment
		(start 157.55747 -84.849208)
		(end 158.400242 -84.501228)
		(width 0.13208)
		(layer "B.Cu")
		(net "CLK_100M_OCP_V3_2_C_DN")
	)
	(segment
		(start 84.54136 -17.165066)
		(end 84.54136 -34.041334)
		(width 0.13208)
		(layer "B.Cu")
		(net "CLK_100M_OCP_V3_2_C_DN")
	)
	(segment
		(start 203.909676 -85.859366)
		(end 228.600254 -96.086422)
		(width 0.13208)
		(layer "B.Cu")
		(net "CLK_100M_OCP_V3_2_C_DN")
	)
	(segment
		(start 113.166652 -77.291946)
		(end 113.166398 -77.291946)
		(width 0.13208)
		(layer "B.Cu")
		(net "CLK_100M_OCP_V3_2_C_DN")
	)
	(segment
		(start 228.600254 -96.086422)
		(end 233.109516 -100.595684)
		(width 0.13208)
		(layer "B.Cu")
		(net "CLK_100M_OCP_V3_2_C_DN")
	)
	(segment
		(start 119.493792 -81.97723)
		(end 124.661168 -83.005168)
		(width 0.13208)
		(layer "B.Cu")
		(net "CLK_100M_OCP_V3_2_C_DN")
	)
	(segment
		(start 154.870658 -84.557108)
		(end 156.779722 -84.557108)
		(width 0.13208)
		(layer "B.Cu")
		(net "CLK_100M_OCP_V3_2_C_DN")
	)
	(segment
		(start 239.841278 -117.302788)
		(end 240.143538 -117.605048)
		(width 0.13208)
		(layer "B.Cu")
		(net "CLK_100M_OCP_V3_2_C_DN")
	)
	(segment
		(start 111.710216 -74.668126)
		(end 112.19434 -75.836526)
		(width 0.13208)
		(layer "B.Cu")
		(net "CLK_100M_OCP_V3_2_C_DN")
	)
	(segment
		(start 71.891906 -13.166344)
		(end 71.891906 -13.353288)
		(width 0.13208)
		(layer "B.Cu")
		(net "CLK_100M_OCP_V3_2_C_DN")
	)
	(segment
		(start 91.946984 -41.859708)
		(end 100.211382 -41.859708)
		(width 0.13208)
		(layer "B.Cu")
		(net "CLK_100M_OCP_V3_2_C_DN")
	)
	(segment
		(start 172.7327 -84.501228)
		(end 176.01184 -85.859366)
		(width 0.13208)
		(layer "B.Cu")
		(net "CLK_100M_OCP_V3_2_C_DN")
	)
	(segment
		(start 154.502358 -84.925408)
		(end 154.870658 -84.557108)
		(width 0.13208)
		(layer "B.Cu")
		(net "CLK_100M_OCP_V3_2_C_DN")
	)
	(segment
		(start 71.891906 -13.353288)
		(end 73.012046 -14.473428)
		(width 0.13208)
		(layer "B.Cu")
		(net "CLK_100M_OCP_V3_2_C_DN")
	)
	(segment
		(start 124.661168 -83.005168)
		(end 145.652236 -83.005168)
		(width 0.13208)
		(layer "B.Cu")
		(net "CLK_100M_OCP_V3_2_C_DN")
	)
	(segment
		(start 84.54136 -34.041334)
		(end 86.388956 -38.501828)
		(width 0.13208)
		(layer "B.Cu")
		(net "CLK_100M_OCP_V3_2_C_DN")
	)
	(segment
		(start 100.211382 -41.859708)
		(end 104.769666 -43.74769)
		(width 0.13208)
		(layer "B.Cu")
		(net "CLK_100M_OCP_V3_2_C_DN")
	)
	(segment
		(start 74.952098 -14.018768)
		(end 80.62722 -14.018768)
		(width 0.13208)
		(layer "B.Cu")
		(net "CLK_100M_OCP_V3_2_C_DN")
	)
	(segment
		(start 104.769666 -43.74769)
		(end 109.964982 -48.943006)
		(width 0.13208)
		(layer "B.Cu")
		(net "CLK_100M_OCP_V3_2_C_DN")
	)
	(segment
		(start 156.779722 -84.557108)
		(end 157.071822 -84.849208)
		(width 0.13208)
		(layer "B.Cu")
		(net "CLK_100M_OCP_V3_2_C_DN")
	)
	(segment
		(start 237.5408 -120.786906)
		(end 235.868464 -122.459242)
		(width 0.13208)
		(layer "F.Cu")
		(net "CLK_100M_OCP_V3_2_B_R_DP")
	)
	(segment
		(start 235.868464 -123.89739)
		(end 235.748068 -124.017786)
		(width 0.13208)
		(layer "F.Cu")
		(net "CLK_100M_OCP_V3_2_B_R_DP")
	)
	(segment
		(start 237.171738 -119.583708)
		(end 237.5408 -119.95277)
		(width 0.13208)
		(layer "F.Cu")
		(net "CLK_100M_OCP_V3_2_B_R_DP")
	)
	(segment
		(start 235.868464 -122.459242)
		(end 235.868464 -123.89739)
		(width 0.13208)
		(layer "F.Cu")
		(net "CLK_100M_OCP_V3_2_B_R_DP")
	)
	(segment
		(start 237.5408 -119.95277)
		(end 237.5408 -120.786906)
		(width 0.13208)
		(layer "F.Cu")
		(net "CLK_100M_OCP_V3_2_B_R_DP")
	)
	(segment
		(start 238.187738 -119.583708)
		(end 237.79988 -119.971566)
		(width 0.13208)
		(layer "F.Cu")
		(net "CLK_100M_OCP_V3_2_B_R_DN")
	)
	(segment
		(start 237.79988 -120.894348)
		(end 236.127544 -122.566684)
		(width 0.13208)
		(layer "F.Cu")
		(net "CLK_100M_OCP_V3_2_B_R_DN")
	)
	(segment
		(start 236.127544 -123.89739)
		(end 236.24794 -124.017786)
		(width 0.13208)
		(layer "F.Cu")
		(net "CLK_100M_OCP_V3_2_B_R_DN")
	)
	(segment
		(start 237.79988 -119.971566)
		(end 237.79988 -120.894348)
		(width 0.13208)
		(layer "F.Cu")
		(net "CLK_100M_OCP_V3_2_B_R_DN")
	)
	(segment
		(start 236.127544 -122.566684)
		(end 236.127544 -123.89739)
		(width 0.13208)
		(layer "F.Cu")
		(net "CLK_100M_OCP_V3_2_B_R_DN")
	)
	(segment
		(start 57.63895 -7.623556)
		(end 57.63895 -7.026656)
		(width 0.13208)
		(layer "F.Cu")
		(net "CLK_100M_OCP_V3_2_B_DP")
	)
	(segment
		(start 237.171738 -118.783608)
		(end 237.550198 -118.405148)
		(width 0.13208)
		(layer "F.Cu")
		(net "CLK_100M_OCP_V3_2_B_DP")
	)
	(segment
		(start 57.466992 -8.320024)
		(end 57.466992 -7.795514)
		(width 0.13208)
		(layer "F.Cu")
		(net "CLK_100M_OCP_V3_2_B_DP")
	)
	(segment
		(start 237.550198 -116.599208)
		(end 237.247938 -116.296948)
		(width 0.13208)
		(layer "F.Cu")
		(net "CLK_100M_OCP_V3_2_B_DP")
	)
	(segment
		(start 57.466992 -7.795514)
		(end 57.63895 -7.623556)
		(width 0.13208)
		(layer "F.Cu")
		(net "CLK_100M_OCP_V3_2_B_DP")
	)
	(segment
		(start 237.550198 -118.405148)
		(end 237.550198 -116.599208)
		(width 0.13208)
		(layer "F.Cu")
		(net "CLK_100M_OCP_V3_2_B_DP")
	)
	(segment
		(start 57.63895 -7.026656)
		(end 57.33669 -6.724396)
		(width 0.13208)
		(layer "F.Cu")
		(net "CLK_100M_OCP_V3_2_B_DP")
	)
	(via
		(at 237.247938 -116.296948)
		(size 0.508)
		(drill 0.254)
		(layers "F.Cu" "B.Cu")
		(net "CLK_100M_OCP_V3_2_B_DP")
	)
	(via
		(at 57.33669 -6.724396)
		(size 0.508)
		(drill 0.254)
		(layers "F.Cu" "B.Cu")
		(net "CLK_100M_OCP_V3_2_B_DP")
	)
	(segment
		(start 130.754882 -85.468968)
		(end 132.287772 -84.833968)
		(width 0.13208)
		(layer "B.Cu")
		(net "CLK_100M_OCP_V3_2_B_DP")
	)
	(segment
		(start 171.878752 -86.365588)
		(end 174.46117 -87.434928)
		(width 0.13208)
		(layer "B.Cu")
		(net "CLK_100M_OCP_V3_2_B_DP")
	)
	(segment
		(start 114.038634 -83.933538)
		(end 116.009928 -84.325968)
		(width 0.13208)
		(layer "B.Cu")
		(net "CLK_100M_OCP_V3_2_B_DP")
	)
	(segment
		(start 132.287772 -84.833968)
		(end 138.183112 -84.833968)
		(width 0.13208)
		(layer "B.Cu")
		(net "CLK_100M_OCP_V3_2_B_DP")
	)
	(segment
		(start 204.620114 -87.434928)
		(end 227.717604 -97.002346)
		(width 0.13208)
		(layer "B.Cu")
		(net "CLK_100M_OCP_V3_2_B_DP")
	)
	(segment
		(start 59.344814 -49.149508)
		(end 60.405518 -50.210212)
		(width 0.13208)
		(layer "B.Cu")
		(net "CLK_100M_OCP_V3_2_B_DP")
	)
	(segment
		(start 138.183112 -84.833968)
		(end 141.880844 -86.365588)
		(width 0.13208)
		(layer "B.Cu")
		(net "CLK_100M_OCP_V3_2_B_DP")
	)
	(segment
		(start 127.616966 -85.468968)
		(end 130.754882 -85.468968)
		(width 0.13208)
		(layer "B.Cu")
		(net "CLK_100M_OCP_V3_2_B_DP")
	)
	(segment
		(start 58.4708 -28.051252)
		(end 58.4708 -47.03953)
		(width 0.13208)
		(layer "B.Cu")
		(net "CLK_100M_OCP_V3_2_B_DP")
	)
	(segment
		(start 231.525826 -100.810568)
		(end 237.550198 -115.3541)
		(width 0.13208)
		(layer "B.Cu")
		(net "CLK_100M_OCP_V3_2_B_DP")
	)
	(segment
		(start 141.880844 -86.365588)
		(end 153.67 -86.365588)
		(width 0.13208)
		(layer "B.Cu")
		(net "CLK_100M_OCP_V3_2_B_DP")
	)
	(segment
		(start 60.405518 -50.210212)
		(end 70.531228 -54.404514)
		(width 0.13208)
		(layer "B.Cu")
		(net "CLK_100M_OCP_V3_2_B_DP")
	)
	(segment
		(start 111.854742 -83.029552)
		(end 114.038634 -83.933538)
		(width 0.13208)
		(layer "B.Cu")
		(net "CLK_100M_OCP_V3_2_B_DP")
	)
	(segment
		(start 59.121294 -12.126722)
		(end 61.6331 -18.19021)
		(width 0.13208)
		(layer "B.Cu")
		(net "CLK_100M_OCP_V3_2_B_DP")
	)
	(segment
		(start 106.014012 -65.51803)
		(end 106.014012 -69.471794)
		(width 0.13208)
		(layer "B.Cu")
		(net "CLK_100M_OCP_V3_2_B_DP")
	)
	(segment
		(start 57.33669 -6.724396)
		(end 57.63895 -7.026656)
		(width 0.13208)
		(layer "B.Cu")
		(net "CLK_100M_OCP_V3_2_B_DP")
	)
	(segment
		(start 174.46117 -87.434928)
		(end 204.620114 -87.434928)
		(width 0.13208)
		(layer "B.Cu")
		(net "CLK_100M_OCP_V3_2_B_DP")
	)
	(segment
		(start 106.014012 -69.471794)
		(end 111.47044 -82.64525)
		(width 0.13208)
		(layer "B.Cu")
		(net "CLK_100M_OCP_V3_2_B_DP")
	)
	(segment
		(start 237.550198 -115.3541)
		(end 237.550198 -115.994688)
		(width 0.13208)
		(layer "B.Cu")
		(net "CLK_100M_OCP_V3_2_B_DP")
	)
	(segment
		(start 237.550198 -115.994688)
		(end 237.247938 -116.296948)
		(width 0.13208)
		(layer "B.Cu")
		(net "CLK_100M_OCP_V3_2_B_DP")
	)
	(segment
		(start 57.63895 -7.026656)
		(end 57.63895 -10.644378)
		(width 0.13208)
		(layer "B.Cu")
		(net "CLK_100M_OCP_V3_2_B_DP")
	)
	(segment
		(start 154.14752 -86.843108)
		(end 157.55366 -86.843108)
		(width 0.13208)
		(layer "B.Cu")
		(net "CLK_100M_OCP_V3_2_B_DP")
	)
	(segment
		(start 111.47044 -82.64525)
		(end 111.854742 -83.029552)
		(width 0.13208)
		(layer "B.Cu")
		(net "CLK_100M_OCP_V3_2_B_DP")
	)
	(segment
		(start 58.4708 -47.03953)
		(end 59.344814 -49.149508)
		(width 0.13208)
		(layer "B.Cu")
		(net "CLK_100M_OCP_V3_2_B_DP")
	)
	(segment
		(start 57.63895 -10.644378)
		(end 59.121294 -12.126722)
		(width 0.13208)
		(layer "B.Cu")
		(net "CLK_100M_OCP_V3_2_B_DP")
	)
	(segment
		(start 124.857764 -84.325968)
		(end 127.616966 -85.468968)
		(width 0.13208)
		(layer "B.Cu")
		(net "CLK_100M_OCP_V3_2_B_DP")
	)
	(segment
		(start 103.995474 -62.496192)
		(end 106.014012 -65.51803)
		(width 0.13208)
		(layer "B.Cu")
		(net "CLK_100M_OCP_V3_2_B_DP")
	)
	(segment
		(start 153.67 -86.365588)
		(end 154.14752 -86.843108)
		(width 0.13208)
		(layer "B.Cu")
		(net "CLK_100M_OCP_V3_2_B_DP")
	)
	(segment
		(start 61.6331 -18.19021)
		(end 61.6331 -20.416774)
		(width 0.13208)
		(layer "B.Cu")
		(net "CLK_100M_OCP_V3_2_B_DP")
	)
	(segment
		(start 70.531228 -54.404514)
		(end 72.005952 -57.964324)
		(width 0.13208)
		(layer "B.Cu")
		(net "CLK_100M_OCP_V3_2_B_DP")
	)
	(segment
		(start 157.55366 -86.843108)
		(end 158.03118 -86.365588)
		(width 0.13208)
		(layer "B.Cu")
		(net "CLK_100M_OCP_V3_2_B_DP")
	)
	(segment
		(start 61.6331 -20.416774)
		(end 58.4708 -28.051252)
		(width 0.13208)
		(layer "B.Cu")
		(net "CLK_100M_OCP_V3_2_B_DP")
	)
	(segment
		(start 80.882744 -61.641228)
		(end 101.931978 -61.641228)
		(width 0.13208)
		(layer "B.Cu")
		(net "CLK_100M_OCP_V3_2_B_DP")
	)
	(segment
		(start 158.03118 -86.365588)
		(end 171.878752 -86.365588)
		(width 0.13208)
		(layer "B.Cu")
		(net "CLK_100M_OCP_V3_2_B_DP")
	)
	(segment
		(start 227.717604 -97.002346)
		(end 231.525826 -100.810568)
		(width 0.13208)
		(layer "B.Cu")
		(net "CLK_100M_OCP_V3_2_B_DP")
	)
	(segment
		(start 101.931978 -61.641228)
		(end 103.995474 -62.496192)
		(width 0.13208)
		(layer "B.Cu")
		(net "CLK_100M_OCP_V3_2_B_DP")
	)
	(segment
		(start 116.009928 -84.325968)
		(end 124.857764 -84.325968)
		(width 0.13208)
		(layer "B.Cu")
		(net "CLK_100M_OCP_V3_2_B_DP")
	)
	(segment
		(start 72.005952 -57.964324)
		(end 80.882744 -61.641228)
		(width 0.13208)
		(layer "B.Cu")
		(net "CLK_100M_OCP_V3_2_B_DP")
	)
	(segment
		(start 58.06694 -8.320024)
		(end 58.06694 -7.779766)
		(width 0.13208)
		(layer "F.Cu")
		(net "CLK_100M_OCP_V3_2_B_DN")
	)
	(segment
		(start 237.809278 -118.405148)
		(end 237.809278 -116.599208)
		(width 0.13208)
		(layer "F.Cu")
		(net "CLK_100M_OCP_V3_2_B_DN")
	)
	(segment
		(start 58.06694 -7.779766)
		(end 57.89803 -7.610856)
		(width 0.13208)
		(layer "F.Cu")
		(net "CLK_100M_OCP_V3_2_B_DN")
	)
	(segment
		(start 238.187738 -118.783608)
		(end 237.809278 -118.405148)
		(width 0.13208)
		(layer "F.Cu")
		(net "CLK_100M_OCP_V3_2_B_DN")
	)
	(segment
		(start 57.89803 -7.026656)
		(end 58.20029 -6.724396)
		(width 0.13208)
		(layer "F.Cu")
		(net "CLK_100M_OCP_V3_2_B_DN")
	)
	(segment
		(start 237.809278 -116.599208)
		(end 238.111538 -116.296948)
		(width 0.13208)
		(layer "F.Cu")
		(net "CLK_100M_OCP_V3_2_B_DN")
	)
	(segment
		(start 57.89803 -7.610856)
		(end 57.89803 -7.026656)
		(width 0.13208)
		(layer "F.Cu")
		(net "CLK_100M_OCP_V3_2_B_DN")
	)
	(via
		(at 58.20029 -6.724396)
		(size 0.508)
		(drill 0.254)
		(layers "F.Cu" "B.Cu")
		(net "CLK_100M_OCP_V3_2_B_DN")
	)
	(via
		(at 238.111538 -116.296948)
		(size 0.508)
		(drill 0.254)
		(layers "F.Cu" "B.Cu")
		(net "CLK_100M_OCP_V3_2_B_DN")
	)
	(segment
		(start 59.564524 -49.002696)
		(end 60.55233 -49.990502)
		(width 0.13208)
		(layer "B.Cu")
		(net "CLK_100M_OCP_V3_2_B_DN")
	)
	(segment
		(start 130.703066 -85.209888)
		(end 130.70332 -85.209634)
		(width 0.13208)
		(layer "B.Cu")
		(net "CLK_100M_OCP_V3_2_B_DN")
	)
	(segment
		(start 227.864416 -96.782636)
		(end 231.745536 -100.663756)
		(width 0.13208)
		(layer "B.Cu")
		(net "CLK_100M_OCP_V3_2_B_DN")
	)
	(segment
		(start 141.932406 -86.106508)
		(end 153.777442 -86.106508)
		(width 0.13208)
		(layer "B.Cu")
		(net "CLK_100M_OCP_V3_2_B_DN")
	)
	(segment
		(start 116.035582 -84.066888)
		(end 124.909326 -84.066888)
		(width 0.13208)
		(layer "B.Cu")
		(net "CLK_100M_OCP_V3_2_B_DN")
	)
	(segment
		(start 104.167432 -62.286642)
		(end 105.220008 -63.862712)
		(width 0.13208)
		(layer "B.Cu")
		(net "CLK_100M_OCP_V3_2_B_DN")
	)
	(segment
		(start 106.273092 -69.420232)
		(end 111.69015 -82.498438)
		(width 0.13208)
		(layer "B.Cu")
		(net "CLK_100M_OCP_V3_2_B_DN")
	)
	(segment
		(start 138.234674 -84.574888)
		(end 141.932406 -86.106508)
		(width 0.13208)
		(layer "B.Cu")
		(net "CLK_100M_OCP_V3_2_B_DN")
	)
	(segment
		(start 171.930314 -86.106508)
		(end 174.512732 -87.175848)
		(width 0.13208)
		(layer "B.Cu")
		(net "CLK_100M_OCP_V3_2_B_DN")
	)
	(segment
		(start 105.220008 -63.862966)
		(end 106.273092 -65.43929)
		(width 0.13208)
		(layer "B.Cu")
		(net "CLK_100M_OCP_V3_2_B_DN")
	)
	(segment
		(start 154.254962 -86.584028)
		(end 157.446218 -86.584028)
		(width 0.13208)
		(layer "B.Cu")
		(net "CLK_100M_OCP_V3_2_B_DN")
	)
	(segment
		(start 58.72988 -46.987968)
		(end 59.564524 -49.002696)
		(width 0.13208)
		(layer "B.Cu")
		(net "CLK_100M_OCP_V3_2_B_DN")
	)
	(segment
		(start 106.273092 -65.43929)
		(end 106.273092 -69.420232)
		(width 0.13208)
		(layer "B.Cu")
		(net "CLK_100M_OCP_V3_2_B_DN")
	)
	(segment
		(start 130.70332 -85.209634)
		(end 132.23621 -84.574888)
		(width 0.13208)
		(layer "B.Cu")
		(net "CLK_100M_OCP_V3_2_B_DN")
	)
	(segment
		(start 237.809278 -115.302538)
		(end 237.809278 -115.994688)
		(width 0.13208)
		(layer "B.Cu")
		(net "CLK_100M_OCP_V3_2_B_DN")
	)
	(segment
		(start 59.341004 -11.97991)
		(end 61.89218 -18.138648)
		(width 0.13208)
		(layer "B.Cu")
		(net "CLK_100M_OCP_V3_2_B_DN")
	)
	(segment
		(start 60.55233 -49.990502)
		(end 70.729602 -54.20614)
		(width 0.13208)
		(layer "B.Cu")
		(net "CLK_100M_OCP_V3_2_B_DN")
	)
	(segment
		(start 58.72988 -28.102814)
		(end 58.72988 -46.987968)
		(width 0.13208)
		(layer "B.Cu")
		(net "CLK_100M_OCP_V3_2_B_DN")
	)
	(segment
		(start 112.001554 -82.809842)
		(end 114.114072 -83.684364)
		(width 0.13208)
		(layer "B.Cu")
		(net "CLK_100M_OCP_V3_2_B_DN")
	)
	(segment
		(start 174.512732 -87.175848)
		(end 204.671676 -87.175848)
		(width 0.13208)
		(layer "B.Cu")
		(net "CLK_100M_OCP_V3_2_B_DN")
	)
	(segment
		(start 124.909326 -84.066888)
		(end 127.668528 -85.209888)
		(width 0.13208)
		(layer "B.Cu")
		(net "CLK_100M_OCP_V3_2_B_DN")
	)
	(segment
		(start 231.745536 -100.663756)
		(end 237.809278 -115.302538)
		(width 0.13208)
		(layer "B.Cu")
		(net "CLK_100M_OCP_V3_2_B_DN")
	)
	(segment
		(start 115.0747 -83.875626)
		(end 116.035582 -84.066888)
		(width 0.13208)
		(layer "B.Cu")
		(net "CLK_100M_OCP_V3_2_B_DN")
	)
	(segment
		(start 57.89803 -10.536936)
		(end 59.341004 -11.97991)
		(width 0.13208)
		(layer "B.Cu")
		(net "CLK_100M_OCP_V3_2_B_DN")
	)
	(segment
		(start 114.114072 -83.684364)
		(end 115.074446 -83.875372)
		(width 0.13208)
		(layer "B.Cu")
		(net "CLK_100M_OCP_V3_2_B_DN")
	)
	(segment
		(start 72.204326 -57.76595)
		(end 80.934306 -61.382148)
		(width 0.13208)
		(layer "B.Cu")
		(net "CLK_100M_OCP_V3_2_B_DN")
	)
	(segment
		(start 70.729602 -54.20614)
		(end 72.204326 -57.76595)
		(width 0.13208)
		(layer "B.Cu")
		(net "CLK_100M_OCP_V3_2_B_DN")
	)
	(segment
		(start 80.934306 -61.382148)
		(end 101.98354 -61.382148)
		(width 0.13208)
		(layer "B.Cu")
		(net "CLK_100M_OCP_V3_2_B_DN")
	)
	(segment
		(start 105.220008 -63.862712)
		(end 105.220008 -63.862966)
		(width 0.13208)
		(layer "B.Cu")
		(net "CLK_100M_OCP_V3_2_B_DN")
	)
	(segment
		(start 204.671676 -87.175848)
		(end 227.864416 -96.782636)
		(width 0.13208)
		(layer "B.Cu")
		(net "CLK_100M_OCP_V3_2_B_DN")
	)
	(segment
		(start 237.809278 -115.994688)
		(end 238.111538 -116.296948)
		(width 0.13208)
		(layer "B.Cu")
		(net "CLK_100M_OCP_V3_2_B_DN")
	)
	(segment
		(start 58.20029 -6.724396)
		(end 57.89803 -7.026656)
		(width 0.13208)
		(layer "B.Cu")
		(net "CLK_100M_OCP_V3_2_B_DN")
	)
	(segment
		(start 115.074446 -83.875372)
		(end 115.0747 -83.875626)
		(width 0.13208)
		(layer "B.Cu")
		(net "CLK_100M_OCP_V3_2_B_DN")
	)
	(segment
		(start 153.777442 -86.106508)
		(end 154.254962 -86.584028)
		(width 0.13208)
		(layer "B.Cu")
		(net "CLK_100M_OCP_V3_2_B_DN")
	)
	(segment
		(start 157.446218 -86.584028)
		(end 157.923738 -86.106508)
		(width 0.13208)
		(layer "B.Cu")
		(net "CLK_100M_OCP_V3_2_B_DN")
	)
	(segment
		(start 61.89218 -20.468336)
		(end 58.72988 -28.102814)
		(width 0.13208)
		(layer "B.Cu")
		(net "CLK_100M_OCP_V3_2_B_DN")
	)
	(segment
		(start 101.98354 -61.382148)
		(end 104.167432 -62.286642)
		(width 0.13208)
		(layer "B.Cu")
		(net "CLK_100M_OCP_V3_2_B_DN")
	)
	(segment
		(start 61.89218 -18.138648)
		(end 61.89218 -20.468336)
		(width 0.13208)
		(layer "B.Cu")
		(net "CLK_100M_OCP_V3_2_B_DN")
	)
	(segment
		(start 127.668528 -85.209888)
		(end 130.703066 -85.209888)
		(width 0.13208)
		(layer "B.Cu")
		(net "CLK_100M_OCP_V3_2_B_DN")
	)
	(segment
		(start 111.69015 -82.498438)
		(end 112.001554 -82.809842)
		(width 0.13208)
		(layer "B.Cu")
		(net "CLK_100M_OCP_V3_2_B_DN")
	)
	(segment
		(start 132.23621 -84.574888)
		(end 138.234674 -84.574888)
		(width 0.13208)
		(layer "B.Cu")
		(net "CLK_100M_OCP_V3_2_B_DN")
	)
	(segment
		(start 57.89803 -7.026656)
		(end 57.89803 -10.536936)
		(width 0.13208)
		(layer "B.Cu")
		(net "CLK_100M_OCP_V3_2_B_DN")
	)
	(segment
		(start 157.923738 -86.106508)
		(end 171.930314 -86.106508)
		(width 0.13208)
		(layer "B.Cu")
		(net "CLK_100M_OCP_V3_2_B_DN")
	)
	(segment
		(start 234.868466 -123.89739)
		(end 234.74807 -124.017786)
		(width 0.13208)
		(layer "F.Cu")
		(net "CLK_100M_OCP_V3_2_A_R_DP")
	)
	(segment
		(start 234.24388 -120.894348)
		(end 234.868466 -121.518934)
		(width 0.13208)
		(layer "F.Cu")
		(net "CLK_100M_OCP_V3_2_A_R_DP")
	)
	(segment
		(start 233.869738 -119.583708)
		(end 234.24388 -119.95785)
		(width 0.13208)
		(layer "F.Cu")
		(net "CLK_100M_OCP_V3_2_A_R_DP")
	)
	(segment
		(start 234.24388 -119.95785)
		(end 234.24388 -120.894348)
		(width 0.13208)
		(layer "F.Cu")
		(net "CLK_100M_OCP_V3_2_A_R_DP")
	)
	(segment
		(start 234.868466 -121.518934)
		(end 234.868466 -123.89739)
		(width 0.13208)
		(layer "F.Cu")
		(net "CLK_100M_OCP_V3_2_A_R_DP")
	)
	(segment
		(start 235.127546 -121.411492)
		(end 235.127546 -123.89739)
		(width 0.13208)
		(layer "F.Cu")
		(net "CLK_100M_OCP_V3_2_A_R_DN")
	)
	(segment
		(start 235.127546 -123.89739)
		(end 235.247942 -124.017786)
		(width 0.13208)
		(layer "F.Cu")
		(net "CLK_100M_OCP_V3_2_A_R_DN")
	)
	(segment
		(start 234.50296 -119.966486)
		(end 234.50296 -120.786906)
		(width 0.13208)
		(layer "F.Cu")
		(net "CLK_100M_OCP_V3_2_A_R_DN")
	)
	(segment
		(start 234.50296 -120.786906)
		(end 235.127546 -121.411492)
		(width 0.13208)
		(layer "F.Cu")
		(net "CLK_100M_OCP_V3_2_A_R_DN")
	)
	(segment
		(start 234.885738 -119.583708)
		(end 234.50296 -119.966486)
		(width 0.13208)
		(layer "F.Cu")
		(net "CLK_100M_OCP_V3_2_A_R_DN")
	)
	(segment
		(start 234.248198 -118.405148)
		(end 234.248198 -117.907308)
		(width 0.13208)
		(layer "F.Cu")
		(net "CLK_100M_OCP_V3_2_A_DP")
	)
	(segment
		(start 57.637934 -11.977624)
		(end 57.637934 -12.561824)
		(width 0.13208)
		(layer "F.Cu")
		(net "CLK_100M_OCP_V3_2_A_DP")
	)
	(segment
		(start 57.637934 -12.561824)
		(end 57.335674 -12.864084)
		(width 0.13208)
		(layer "F.Cu")
		(net "CLK_100M_OCP_V3_2_A_DP")
	)
	(segment
		(start 57.466992 -11.26998)
		(end 57.466992 -11.806682)
		(width 0.13208)
		(layer "F.Cu")
		(net "CLK_100M_OCP_V3_2_A_DP")
	)
	(segment
		(start 233.869738 -118.783608)
		(end 234.248198 -118.405148)
		(width 0.13208)
		(layer "F.Cu")
		(net "CLK_100M_OCP_V3_2_A_DP")
	)
	(segment
		(start 57.466992 -11.806682)
		(end 57.637934 -11.977624)
		(width 0.13208)
		(layer "F.Cu")
		(net "CLK_100M_OCP_V3_2_A_DP")
	)
	(segment
		(start 234.248198 -117.907308)
		(end 233.945938 -117.605048)
		(width 0.13208)
		(layer "F.Cu")
		(net "CLK_100M_OCP_V3_2_A_DP")
	)
	(via
		(at 233.945938 -117.605048)
		(size 0.508)
		(drill 0.254)
		(layers "F.Cu" "B.Cu")
		(net "CLK_100M_OCP_V3_2_A_DP")
	)
	(via
		(at 57.335674 -12.864084)
		(size 0.508)
		(drill 0.254)
		(layers "F.Cu" "B.Cu")
		(net "CLK_100M_OCP_V3_2_A_DP")
	)
	(segment
		(start 59.83986 -18.14449)
		(end 59.83986 -19.21764)
		(width 0.13208)
		(layer "B.Cu")
		(net "CLK_100M_OCP_V3_2_A_DP")
	)
	(segment
		(start 71.207122 -58.63463)
		(end 80.857598 -62.631828)
		(width 0.13208)
		(layer "B.Cu")
		(net "CLK_100M_OCP_V3_2_A_DP")
	)
	(segment
		(start 59.2455 -16.71066)
		(end 59.83986 -18.14449)
		(width 0.13208)
		(layer "B.Cu")
		(net "CLK_100M_OCP_V3_2_A_DP")
	)
	(segment
		(start 150.591774 -88.422226)
		(end 204.586586 -88.422226)
		(width 0.13208)
		(layer "B.Cu")
		(net "CLK_100M_OCP_V3_2_A_DP")
	)
	(segment
		(start 105.089452 -66.255392)
		(end 105.089452 -69.836538)
		(width 0.13208)
		(layer "B.Cu")
		(net "CLK_100M_OCP_V3_2_A_DP")
	)
	(segment
		(start 59.746388 -50.948336)
		(end 69.737478 -55.087012)
		(width 0.13208)
		(layer "B.Cu")
		(net "CLK_100M_OCP_V3_2_A_DP")
	)
	(segment
		(start 57.637934 -13.166344)
		(end 57.637934 -13.577062)
		(width 0.13208)
		(layer "B.Cu")
		(net "CLK_100M_OCP_V3_2_A_DP")
	)
	(segment
		(start 103.280718 -63.54445)
		(end 105.089452 -66.255392)
		(width 0.13208)
		(layer "B.Cu")
		(net "CLK_100M_OCP_V3_2_A_DP")
	)
	(segment
		(start 57.335674 -12.864084)
		(end 57.637934 -13.166344)
		(width 0.13208)
		(layer "B.Cu")
		(net "CLK_100M_OCP_V3_2_A_DP")
	)
	(segment
		(start 114.855752 -85.184742)
		(end 129.45745 -87.348568)
		(width 0.13208)
		(layer "B.Cu")
		(net "CLK_100M_OCP_V3_2_A_DP")
	)
	(segment
		(start 234.248198 -114.949478)
		(end 234.248198 -117.302788)
		(width 0.13208)
		(layer "B.Cu")
		(net "CLK_100M_OCP_V3_2_A_DP")
	)
	(segment
		(start 101.077268 -62.631828)
		(end 103.280718 -63.54445)
		(width 0.13208)
		(layer "B.Cu")
		(net "CLK_100M_OCP_V3_2_A_DP")
	)
	(segment
		(start 129.45745 -87.348568)
		(end 145.193766 -87.348568)
		(width 0.13208)
		(layer "B.Cu")
		(net "CLK_100M_OCP_V3_2_A_DP")
	)
	(segment
		(start 59.83986 -19.21764)
		(end 57.4802 -28.11653)
		(width 0.13208)
		(layer "B.Cu")
		(net "CLK_100M_OCP_V3_2_A_DP")
	)
	(segment
		(start 69.737478 -55.087012)
		(end 71.207122 -58.63463)
		(width 0.13208)
		(layer "B.Cu")
		(net "CLK_100M_OCP_V3_2_A_DP")
	)
	(segment
		(start 234.248198 -117.302788)
		(end 233.945938 -117.605048)
		(width 0.13208)
		(layer "B.Cu")
		(net "CLK_100M_OCP_V3_2_A_DP")
	)
	(segment
		(start 57.4802 -28.11653)
		(end 57.4802 -47.064676)
		(width 0.13208)
		(layer "B.Cu")
		(net "CLK_100M_OCP_V3_2_A_DP")
	)
	(segment
		(start 57.4802 -47.064676)
		(end 58.623708 -49.825656)
		(width 0.13208)
		(layer "B.Cu")
		(net "CLK_100M_OCP_V3_2_A_DP")
	)
	(segment
		(start 227.127562 -97.759012)
		(end 234.248198 -114.949478)
		(width 0.13208)
		(layer "B.Cu")
		(net "CLK_100M_OCP_V3_2_A_DP")
	)
	(segment
		(start 204.586586 -88.422226)
		(end 227.127562 -97.759012)
		(width 0.13208)
		(layer "B.Cu")
		(net "CLK_100M_OCP_V3_2_A_DP")
	)
	(segment
		(start 105.089452 -69.836538)
		(end 110.846108 -83.734148)
		(width 0.13208)
		(layer "B.Cu")
		(net "CLK_100M_OCP_V3_2_A_DP")
	)
	(segment
		(start 111.493046 -84.165948)
		(end 114.855752 -85.184742)
		(width 0.13208)
		(layer "B.Cu")
		(net "CLK_100M_OCP_V3_2_A_DP")
	)
	(segment
		(start 80.857598 -62.631828)
		(end 101.077268 -62.631828)
		(width 0.13208)
		(layer "B.Cu")
		(net "CLK_100M_OCP_V3_2_A_DP")
	)
	(segment
		(start 58.623708 -49.825656)
		(end 59.746388 -50.948336)
		(width 0.13208)
		(layer "B.Cu")
		(net "CLK_100M_OCP_V3_2_A_DP")
	)
	(segment
		(start 57.637934 -13.577062)
		(end 58.717688 -16.182848)
		(width 0.13208)
		(layer "B.Cu")
		(net "CLK_100M_OCP_V3_2_A_DP")
	)
	(segment
		(start 58.717688 -16.182848)
		(end 59.2455 -16.71066)
		(width 0.13208)
		(layer "B.Cu")
		(net "CLK_100M_OCP_V3_2_A_DP")
	)
	(segment
		(start 145.193766 -87.348568)
		(end 150.591774 -88.422226)
		(width 0.13208)
		(layer "B.Cu")
		(net "CLK_100M_OCP_V3_2_A_DP")
	)
	(segment
		(start 110.846108 -83.734148)
		(end 111.493046 -84.165948)
		(width 0.13208)
		(layer "B.Cu")
		(net "CLK_100M_OCP_V3_2_A_DP")
	)
	(segment
		(start 234.507278 -117.907308)
		(end 234.809538 -117.605048)
		(width 0.13208)
		(layer "F.Cu")
		(net "CLK_100M_OCP_V3_2_A_DN")
	)
	(segment
		(start 57.897014 -12.561824)
		(end 58.199274 -12.864084)
		(width 0.13208)
		(layer "F.Cu")
		(net "CLK_100M_OCP_V3_2_A_DN")
	)
	(segment
		(start 58.06694 -11.794998)
		(end 57.897014 -11.964924)
		(width 0.13208)
		(layer "F.Cu")
		(net "CLK_100M_OCP_V3_2_A_DN")
	)
	(segment
		(start 234.507278 -118.405148)
		(end 234.507278 -117.907308)
		(width 0.13208)
		(layer "F.Cu")
		(net "CLK_100M_OCP_V3_2_A_DN")
	)
	(segment
		(start 58.06694 -11.26998)
		(end 58.06694 -11.794998)
		(width 0.13208)
		(layer "F.Cu")
		(net "CLK_100M_OCP_V3_2_A_DN")
	)
	(segment
		(start 234.885738 -118.783608)
		(end 234.507278 -118.405148)
		(width 0.13208)
		(layer "F.Cu")
		(net "CLK_100M_OCP_V3_2_A_DN")
	)
	(segment
		(start 57.897014 -11.964924)
		(end 57.897014 -12.561824)
		(width 0.13208)
		(layer "F.Cu")
		(net "CLK_100M_OCP_V3_2_A_DN")
	)
	(via
		(at 234.809538 -117.605048)
		(size 0.508)
		(drill 0.254)
		(layers "F.Cu" "B.Cu")
		(net "CLK_100M_OCP_V3_2_A_DN")
	)
	(via
		(at 58.199274 -12.864084)
		(size 0.508)
		(drill 0.254)
		(layers "F.Cu" "B.Cu")
		(net "CLK_100M_OCP_V3_2_A_DN")
	)
	(segment
		(start 57.73928 -47.013114)
		(end 58.843418 -49.678844)
		(width 0.13208)
		(layer "B.Cu")
		(net "CLK_100M_OCP_V3_2_A_DN")
	)
	(segment
		(start 104.40035 -64.755776)
		(end 105.348532 -66.176652)
		(width 0.13208)
		(layer "B.Cu")
		(net "CLK_100M_OCP_V3_2_A_DN")
	)
	(segment
		(start 227.325936 -97.560638)
		(end 234.507278 -114.897916)
		(width 0.13208)
		(layer "B.Cu")
		(net "CLK_100M_OCP_V3_2_A_DN")
	)
	(segment
		(start 58.937398 -16.036036)
		(end 59.46521 -16.563848)
		(width 0.13208)
		(layer "B.Cu")
		(net "CLK_100M_OCP_V3_2_A_DN")
	)
	(segment
		(start 69.935852 -54.888638)
		(end 71.405496 -58.436256)
		(width 0.13208)
		(layer "B.Cu")
		(net "CLK_100M_OCP_V3_2_A_DN")
	)
	(segment
		(start 145.21942 -87.089488)
		(end 150.617428 -88.163146)
		(width 0.13208)
		(layer "B.Cu")
		(net "CLK_100M_OCP_V3_2_A_DN")
	)
	(segment
		(start 111.055404 -83.56219)
		(end 111.60506 -83.928966)
		(width 0.13208)
		(layer "B.Cu")
		(net "CLK_100M_OCP_V3_2_A_DN")
	)
	(segment
		(start 103.452676 -63.335154)
		(end 104.400604 -64.755776)
		(width 0.13208)
		(layer "B.Cu")
		(net "CLK_100M_OCP_V3_2_A_DN")
	)
	(segment
		(start 59.8932 -50.728626)
		(end 69.935852 -54.888638)
		(width 0.13208)
		(layer "B.Cu")
		(net "CLK_100M_OCP_V3_2_A_DN")
	)
	(segment
		(start 105.348532 -69.784976)
		(end 111.055404 -83.56219)
		(width 0.13208)
		(layer "B.Cu")
		(net "CLK_100M_OCP_V3_2_A_DN")
	)
	(segment
		(start 104.400604 -64.755776)
		(end 104.40035 -64.755776)
		(width 0.13208)
		(layer "B.Cu")
		(net "CLK_100M_OCP_V3_2_A_DN")
	)
	(segment
		(start 57.73928 -28.150312)
		(end 57.73928 -47.013114)
		(width 0.13208)
		(layer "B.Cu")
		(net "CLK_100M_OCP_V3_2_A_DN")
	)
	(segment
		(start 57.897014 -13.525246)
		(end 57.897268 -13.5255)
		(width 0.13208)
		(layer "B.Cu")
		(net "CLK_100M_OCP_V3_2_A_DN")
	)
	(segment
		(start 204.638148 -88.163146)
		(end 227.325936 -97.560638)
		(width 0.13208)
		(layer "B.Cu")
		(net "CLK_100M_OCP_V3_2_A_DN")
	)
	(segment
		(start 58.843418 -49.678844)
		(end 59.8932 -50.728626)
		(width 0.13208)
		(layer "B.Cu")
		(net "CLK_100M_OCP_V3_2_A_DN")
	)
	(segment
		(start 114.912648 -84.93125)
		(end 129.476754 -87.089488)
		(width 0.13208)
		(layer "B.Cu")
		(net "CLK_100M_OCP_V3_2_A_DN")
	)
	(segment
		(start 58.41746 -14.780768)
		(end 58.937398 -16.036036)
		(width 0.13208)
		(layer "B.Cu")
		(net "CLK_100M_OCP_V3_2_A_DN")
	)
	(segment
		(start 57.897014 -13.166344)
		(end 57.897014 -13.525246)
		(width 0.13208)
		(layer "B.Cu")
		(net "CLK_100M_OCP_V3_2_A_DN")
	)
	(segment
		(start 105.348532 -66.176652)
		(end 105.348532 -69.784976)
		(width 0.13208)
		(layer "B.Cu")
		(net "CLK_100M_OCP_V3_2_A_DN")
	)
	(segment
		(start 129.476754 -87.089488)
		(end 145.21942 -87.089488)
		(width 0.13208)
		(layer "B.Cu")
		(net "CLK_100M_OCP_V3_2_A_DN")
	)
	(segment
		(start 71.405496 -58.436256)
		(end 80.90916 -62.372748)
		(width 0.13208)
		(layer "B.Cu")
		(net "CLK_100M_OCP_V3_2_A_DN")
	)
	(segment
		(start 80.90916 -62.372748)
		(end 101.12883 -62.372748)
		(width 0.13208)
		(layer "B.Cu")
		(net "CLK_100M_OCP_V3_2_A_DN")
	)
	(segment
		(start 60.09894 -19.251422)
		(end 57.73928 -28.150312)
		(width 0.13208)
		(layer "B.Cu")
		(net "CLK_100M_OCP_V3_2_A_DN")
	)
	(segment
		(start 150.617428 -88.163146)
		(end 204.638148 -88.163146)
		(width 0.13208)
		(layer "B.Cu")
		(net "CLK_100M_OCP_V3_2_A_DN")
	)
	(segment
		(start 59.46521 -16.563848)
		(end 60.09894 -18.092674)
		(width 0.13208)
		(layer "B.Cu")
		(net "CLK_100M_OCP_V3_2_A_DN")
	)
	(segment
		(start 58.199274 -12.864084)
		(end 57.897014 -13.166344)
		(width 0.13208)
		(layer "B.Cu")
		(net "CLK_100M_OCP_V3_2_A_DN")
	)
	(segment
		(start 234.507278 -117.302788)
		(end 234.809538 -117.605048)
		(width 0.13208)
		(layer "B.Cu")
		(net "CLK_100M_OCP_V3_2_A_DN")
	)
	(segment
		(start 60.09894 -18.092674)
		(end 60.09894 -19.251422)
		(width 0.13208)
		(layer "B.Cu")
		(net "CLK_100M_OCP_V3_2_A_DN")
	)
	(segment
		(start 111.60506 -83.928966)
		(end 114.912648 -84.93125)
		(width 0.13208)
		(layer "B.Cu")
		(net "CLK_100M_OCP_V3_2_A_DN")
	)
	(segment
		(start 234.507278 -114.897916)
		(end 234.507278 -117.302788)
		(width 0.13208)
		(layer "B.Cu")
		(net "CLK_100M_OCP_V3_2_A_DN")
	)
	(segment
		(start 57.897268 -13.5255)
		(end 58.41746 -14.780768)
		(width 0.13208)
		(layer "B.Cu")
		(net "CLK_100M_OCP_V3_2_A_DN")
	)
	(segment
		(start 101.12883 -62.372748)
		(end 103.452676 -63.335154)
		(width 0.13208)
		(layer "B.Cu")
		(net "CLK_100M_OCP_V3_2_A_DN")
	)
	(segment
		(start 159.75838 -424.40352)
		(end 159.75838 -426.41774)
		(width 0.12954)
		(layer "F.Cu")
		(net "BMC_MONITER_BUF")
	)
	(segment
		(start 159.75838 -426.41774)
		(end 160.0327 -426.69206)
		(width 0.12954)
		(layer "F.Cu")
		(net "BMC_MONITER_BUF")
	)
	(segment
		(start 161.9377 -426.69206)
		(end 162.3695 -426.26026)
		(width 0.12954)
		(layer "F.Cu")
		(net "BMC_MONITER_BUF")
	)
	(segment
		(start 160.0327 -426.69206)
		(end 161.9377 -426.69206)
		(width 0.12954)
		(layer "F.Cu")
		(net "BMC_MONITER_BUF")
	)
	(segment
		(start 177.638202 -425.414948)
		(end 176.57953 -425.414948)
		(width 0.12954)
		(layer "F.Cu")
		(net "BMC_MONITER_BUF")
	)
	(segment
		(start 176.95926 -427.9265)
		(end 177.7365 -427.14926)
		(width 0.12954)
		(layer "F.Cu")
		(net "BMC_MONITER_BUF")
	)
	(segment
		(start 162.3695 -426.26026)
		(end 166.07028 -426.26026)
		(width 0.12954)
		(layer "F.Cu")
		(net "BMC_MONITER_BUF")
	)
	(segment
		(start 174.41418 -427.4185)
		(end 174.92218 -427.9265)
		(width 0.12954)
		(layer "F.Cu")
		(net "BMC_MONITER_BUF")
	)
	(segment
		(start 167.22852 -427.4185)
		(end 174.41418 -427.4185)
		(width 0.12954)
		(layer "F.Cu")
		(net "BMC_MONITER_BUF")
	)
	(segment
		(start 174.92218 -427.9265)
		(end 176.95926 -427.9265)
		(width 0.12954)
		(layer "F.Cu")
		(net "BMC_MONITER_BUF")
	)
	(segment
		(start 166.07028 -426.26026)
		(end 167.22852 -427.4185)
		(width 0.12954)
		(layer "F.Cu")
		(net "BMC_MONITER_BUF")
	)
	(segment
		(start 177.7365 -425.513246)
		(end 177.638202 -425.414948)
		(width 0.12954)
		(layer "F.Cu")
		(net "BMC_MONITER_BUF")
	)
	(segment
		(start 177.7365 -427.14926)
		(end 177.7365 -425.513246)
		(width 0.12954)
		(layer "F.Cu")
		(net "BMC_MONITER_BUF")
	)
	(via
		(at 159.75838 -424.40352)
		(size 0.508)
		(drill 0.254)
		(layers "F.Cu" "B.Cu")
		(net "BMC_MONITER_BUF")
	)
	(segment
		(start 142.750032 -440.489848)
		(end 142.072868 -440.489848)
		(width 0.127)
		(layer "In2.Cu")
		(net "BMC_MONITER_BUF")
	)
	(segment
		(start 142.072868 -440.489848)
		(end 141.38402 -439.801)
		(width 0.127)
		(layer "In2.Cu")
		(net "BMC_MONITER_BUF")
	)
	(segment
		(start 152.65654 -422.30294)
		(end 158.07944 -422.30294)
		(width 0.127)
		(layer "In2.Cu")
		(net "BMC_MONITER_BUF")
	)
	(segment
		(start 141.38402 -439.801)
		(end 141.38402 -424.71848)
		(width 0.127)
		(layer "In2.Cu")
		(net "BMC_MONITER_BUF")
	)
	(segment
		(start 159.75838 -423.98188)
		(end 159.75838 -424.40352)
		(width 0.127)
		(layer "In2.Cu")
		(net "BMC_MONITER_BUF")
	)
	(segment
		(start 152.20442 -422.75506)
		(end 152.65654 -422.30294)
		(width 0.127)
		(layer "In2.Cu")
		(net "BMC_MONITER_BUF")
	)
	(segment
		(start 158.07944 -422.30294)
		(end 159.75838 -423.98188)
		(width 0.127)
		(layer "In2.Cu")
		(net "BMC_MONITER_BUF")
	)
	(segment
		(start 143.34744 -422.75506)
		(end 152.20442 -422.75506)
		(width 0.127)
		(layer "In2.Cu")
		(net "BMC_MONITER_BUF")
	)
	(segment
		(start 141.38402 -424.71848)
		(end 143.34744 -422.75506)
		(width 0.127)
		(layer "In2.Cu")
		(net "BMC_MONITER_BUF")
	)
	(segment
		(start 161.23793 -105.755948)
		(end 161.85388 -105.755948)
		(width 0.12954)
		(layer "F.Cu")
		(net "BMC_MONITER")
	)
	(segment
		(start 171.755562 -107.375452)
		(end 171.355512 -106.975402)
		(width 0.12954)
		(layer "F.Cu")
		(net "BMC_MONITER")
	)
	(via
		(at 171.355512 -106.975402)
		(size 0.4572)
		(drill 0.254)
		(layers "F.Cu" "B.Cu")
		(net "BMC_MONITER")
	)
	(via
		(at 161.85388 -105.755948)
		(size 0.508)
		(drill 0.254)
		(layers "F.Cu" "B.Cu")
		(net "BMC_MONITER")
	)
	(segment
		(start 168.9481 -107.439968)
		(end 170.890946 -107.439968)
		(width 0.127)
		(layer "In6.Cu")
		(net "BMC_MONITER")
	)
	(segment
		(start 167.26408 -105.755948)
		(end 168.9481 -107.439968)
		(width 0.127)
		(layer "In6.Cu")
		(net "BMC_MONITER")
	)
	(segment
		(start 161.85388 -105.755948)
		(end 167.26408 -105.755948)
		(width 0.127)
		(layer "In6.Cu")
		(net "BMC_MONITER")
	)
	(segment
		(start 170.890946 -107.439968)
		(end 171.355512 -106.975402)
		(width 0.127)
		(layer "In6.Cu")
		(net "BMC_MONITER")
	)
	(segment
		(start 118.419372 -407.304748)
		(end 118.449852 -407.335228)
		(width 0.12954)
		(layer "F.Cu")
		(net "BIC_MONITER")
	)
	(segment
		(start 116.13388 -407.304748)
		(end 118.419372 -407.304748)
		(width 0.12954)
		(layer "F.Cu")
		(net "BIC_MONITER")
	)
	(segment
		(start 118.449852 -406.227788)
		(end 118.44528 -406.223216)
		(width 0.12954)
		(layer "F.Cu")
		(net "BIC_MONITER")
	)
	(segment
		(start 116.13388 -408.11069)
		(end 116.13388 -407.304748)
		(width 0.12954)
		(layer "F.Cu")
		(net "BIC_MONITER")
	)
	(segment
		(start 118.449852 -407.335228)
		(end 118.449852 -406.227788)
		(width 0.12954)
		(layer "F.Cu")
		(net "BIC_MONITER")
	)
	(via
		(at 116.13388 -407.304748)
		(size 0.508)
		(drill 0.254)
		(layers "F.Cu" "B.Cu")
		(net "BIC_MONITER")
	)
	(segment
		(start 146.750024 -440.489848)
		(end 146.85264 -440.489848)
		(width 0.127)
		(layer "In15.Cu")
		(net "BIC_MONITER")
	)
	(segment
		(start 145.78076 -422.554908)
		(end 127.8255 -422.554908)
		(width 0.127)
		(layer "In15.Cu")
		(net "BIC_MONITER")
	)
	(segment
		(start 146.85264 -440.489848)
		(end 147.97786 -439.364628)
		(width 0.127)
		(layer "In15.Cu")
		(net "BIC_MONITER")
	)
	(segment
		(start 117.74678 -412.476188)
		(end 117.74678 -410.642308)
		(width 0.127)
		(layer "In15.Cu")
		(net "BIC_MONITER")
	)
	(segment
		(start 147.97786 -439.364628)
		(end 147.97786 -424.752008)
		(width 0.127)
		(layer "In15.Cu")
		(net "BIC_MONITER")
	)
	(segment
		(start 147.97786 -424.752008)
		(end 145.78076 -422.554908)
		(width 0.127)
		(layer "In15.Cu")
		(net "BIC_MONITER")
	)
	(segment
		(start 127.8255 -422.554908)
		(end 117.74678 -412.476188)
		(width 0.127)
		(layer "In15.Cu")
		(net "BIC_MONITER")
	)
	(segment
		(start 117.74678 -410.642308)
		(end 116.13388 -409.029408)
		(width 0.127)
		(layer "In15.Cu")
		(net "BIC_MONITER")
	)
	(segment
		(start 116.13388 -409.029408)
		(end 116.13388 -407.304748)
		(width 0.127)
		(layer "In15.Cu")
		(net "BIC_MONITER")
	)
	(segment
		(start 11.160506 -99.136454)
		(end 11.652504 -99.136454)
		(width 0.12954)
		(layer "F.Cu")
		(net "USB_HUB_XTAL_OUT")
	)
	(segment
		(start 9.50468 -98.374708)
		(end 10.39876 -98.374708)
		(width 0.12954)
		(layer "F.Cu")
		(net "USB_HUB_XTAL_OUT")
	)
	(segment
		(start 9.29513 -98.584258)
		(end 9.50468 -98.374708)
		(width 0.12954)
		(layer "F.Cu")
		(net "USB_HUB_XTAL_OUT")
	)
	(segment
		(start 8.25246 -98.143568)
		(end 7.899146 -98.496882)
		(width 0.12954)
		(layer "F.Cu")
		(net "USB_HUB_XTAL_OUT")
	)
	(segment
		(start 9.29513 -98.584258)
		(end 8.85444 -98.143568)
		(width 0.12954)
		(layer "F.Cu")
		(net "USB_HUB_XTAL_OUT")
	)
	(segment
		(start 8.85444 -98.143568)
		(end 8.25246 -98.143568)
		(width 0.12954)
		(layer "F.Cu")
		(net "USB_HUB_XTAL_OUT")
	)
	(segment
		(start 10.39876 -98.374708)
		(end 11.160506 -99.136454)
		(width 0.12954)
		(layer "F.Cu")
		(net "USB_HUB_XTAL_OUT")
	)
	(via
		(at 10.39876 -98.374708)
		(size 0.508)
		(drill 0.254)
		(layers "F.Cu" "B.Cu")
		(net "USB_HUB_XTAL_OUT")
	)
	(segment
		(start 9.277096 -99.617784)
		(end 8.654796 -99.617784)
		(width 0.12954)
		(layer "F.Cu")
		(net "USB_HUB_XTAL_IN")
	)
	(segment
		(start 9.98728 -99.636326)
		(end 9.295638 -99.636326)
		(width 0.12954)
		(layer "F.Cu")
		(net "USB_HUB_XTAL_IN")
	)
	(segment
		(start 11.652504 -99.636326)
		(end 9.98728 -99.636326)
		(width 0.12954)
		(layer "F.Cu")
		(net "USB_HUB_XTAL_IN")
	)
	(segment
		(start 9.295638 -99.636326)
		(end 9.277096 -99.617784)
		(width 0.12954)
		(layer "F.Cu")
		(net "USB_HUB_XTAL_IN")
	)
	(segment
		(start 8.49884 -99.461828)
		(end 7.333996 -99.461828)
		(width 0.12954)
		(layer "F.Cu")
		(net "USB_HUB_XTAL_IN")
	)
	(segment
		(start 8.654796 -99.617784)
		(end 8.49884 -99.461828)
		(width 0.12954)
		(layer "F.Cu")
		(net "USB_HUB_XTAL_IN")
	)
	(segment
		(start 7.333996 -99.461828)
		(end 6.599174 -100.19665)
		(width 0.12954)
		(layer "F.Cu")
		(net "USB_HUB_XTAL_IN")
	)
	(via
		(at 9.98728 -99.636326)
		(size 0.508)
		(drill 0.254)
		(layers "F.Cu" "B.Cu")
		(net "USB_HUB_XTAL_IN")
	)
	(segment
		(start 15.372588 -103.055928)
		(end 15.801848 -102.626668)
		(width 0.13208)
		(layer "F.Cu")
		(net "USB2_P0_R_DP")
	)
	(segment
		(start 15.397734 -102.3366)
		(end 15.18158 -102.120446)
		(width 0.13208)
		(layer "F.Cu")
		(net "USB2_P0_R_DP")
	)
	(segment
		(start 15.288006 -104.13111)
		(end 15.801848 -103.617268)
		(width 0.13208)
		(layer "F.Cu")
		(net "USB2_P0_R_DP")
	)
	(segment
		(start 15.801848 -102.400862)
		(end 15.737586 -102.3366)
		(width 0.13208)
		(layer "F.Cu")
		(net "USB2_P0_R_DP")
	)
	(segment
		(start 15.801848 -102.626668)
		(end 15.801848 -102.400862)
		(width 0.13208)
		(layer "F.Cu")
		(net "USB2_P0_R_DP")
	)
	(segment
		(start 15.18158 -101.872288)
		(end 15.064994 -101.755702)
		(width 0.13208)
		(layer "F.Cu")
		(net "USB2_P0_R_DP")
	)
	(segment
		(start 15.801848 -103.617268)
		(end 15.801848 -103.485188)
		(width 0.13208)
		(layer "F.Cu")
		(net "USB2_P0_R_DP")
	)
	(segment
		(start 15.801848 -103.485188)
		(end 15.372588 -103.055928)
		(width 0.13208)
		(layer "F.Cu")
		(net "USB2_P0_R_DP")
	)
	(segment
		(start 15.737586 -102.3366)
		(end 15.397734 -102.3366)
		(width 0.13208)
		(layer "F.Cu")
		(net "USB2_P0_R_DP")
	)
	(segment
		(start 15.288006 -104.33558)
		(end 15.288006 -104.13111)
		(width 0.13208)
		(layer "F.Cu")
		(net "USB2_P0_R_DP")
	)
	(segment
		(start 15.18158 -102.120446)
		(end 15.18158 -101.872288)
		(width 0.13208)
		(layer "F.Cu")
		(net "USB2_P0_R_DP")
	)
	(segment
		(start 15.064994 -101.755702)
		(end 15.064994 -101.548946)
		(width 0.13208)
		(layer "F.Cu")
		(net "USB2_P0_R_DP")
	)
	(via
		(at 15.372588 -103.055928)
		(size 0.762)
		(drill 0.381)
		(layers "F.Cu" "B.Cu")
		(net "USB2_P0_R_DP")
	)
	(segment
		(start 15.44066 -101.872288)
		(end 15.56512 -101.747828)
		(width 0.13208)
		(layer "F.Cu")
		(net "USB2_P0_R_DN")
	)
	(segment
		(start 15.56512 -101.747828)
		(end 15.56512 -101.548946)
		(width 0.13208)
		(layer "F.Cu")
		(net "USB2_P0_R_DN")
	)
	(segment
		(start 16.645382 -104.23398)
		(end 16.060928 -103.649526)
		(width 0.13208)
		(layer "F.Cu")
		(net "USB2_P0_R_DN")
	)
	(segment
		(start 15.505176 -102.07752)
		(end 15.44066 -102.013004)
		(width 0.13208)
		(layer "F.Cu")
		(net "USB2_P0_R_DN")
	)
	(segment
		(start 16.645382 -104.36606)
		(end 16.645382 -104.23398)
		(width 0.13208)
		(layer "F.Cu")
		(net "USB2_P0_R_DN")
	)
	(segment
		(start 16.060928 -103.649526)
		(end 16.060928 -103.485188)
		(width 0.13208)
		(layer "F.Cu")
		(net "USB2_P0_R_DN")
	)
	(segment
		(start 16.490188 -103.055928)
		(end 16.060928 -102.626668)
		(width 0.13208)
		(layer "F.Cu")
		(net "USB2_P0_R_DN")
	)
	(segment
		(start 15.845028 -102.07752)
		(end 15.505176 -102.07752)
		(width 0.13208)
		(layer "F.Cu")
		(net "USB2_P0_R_DN")
	)
	(segment
		(start 16.060928 -103.485188)
		(end 16.490188 -103.055928)
		(width 0.13208)
		(layer "F.Cu")
		(net "USB2_P0_R_DN")
	)
	(segment
		(start 15.44066 -102.013004)
		(end 15.44066 -101.872288)
		(width 0.13208)
		(layer "F.Cu")
		(net "USB2_P0_R_DN")
	)
	(segment
		(start 16.060928 -102.626668)
		(end 16.060928 -102.29342)
		(width 0.13208)
		(layer "F.Cu")
		(net "USB2_P0_R_DN")
	)
	(segment
		(start 16.060928 -102.29342)
		(end 15.845028 -102.07752)
		(width 0.13208)
		(layer "F.Cu")
		(net "USB2_P0_R_DN")
	)
	(via
		(at 16.490188 -103.055928)
		(size 0.762)
		(drill 0.381)
		(layers "F.Cu" "B.Cu")
		(net "USB2_P0_R_DN")
	)
	(segment
		(start 14.185392 -101.866446)
		(end 14.185392 -102.40899)
		(width 0.13208)
		(layer "F.Cu")
		(net "USB2_HUB_SWB_DP")
	)
	(segment
		(start 11.421618 -104.998012)
		(end 12.020804 -104.398826)
		(width 0.13208)
		(layer "F.Cu")
		(net "USB2_HUB_SWB_DP")
	)
	(segment
		(start 13.072618 -103.19004)
		(end 12.536678 -103.19004)
		(width 0.13208)
		(layer "F.Cu")
		(net "USB2_HUB_SWB_DP")
	)
	(segment
		(start 12.020804 -104.398826)
		(end 12.020804 -104.2416)
		(width 0.13208)
		(layer "F.Cu")
		(net "USB2_HUB_SWB_DP")
	)
	(segment
		(start 13.37183 -102.88905)
		(end 13.072618 -103.188262)
		(width 0.13208)
		(layer "F.Cu")
		(net "USB2_HUB_SWB_DP")
	)
	(segment
		(start 12.536678 -103.724456)
		(end 12.536678 -103.19004)
		(width 0.13208)
		(layer "F.Cu")
		(net "USB2_HUB_SWB_DP")
	)
	(segment
		(start 13.705332 -102.88905)
		(end 13.37183 -102.88905)
		(width 0.13208)
		(layer "F.Cu")
		(net "USB2_HUB_SWB_DP")
	)
	(segment
		(start 14.064996 -101.74605)
		(end 14.185392 -101.866446)
		(width 0.13208)
		(layer "F.Cu")
		(net "USB2_HUB_SWB_DP")
	)
	(segment
		(start 14.185392 -102.40899)
		(end 13.705332 -102.88905)
		(width 0.13208)
		(layer "F.Cu")
		(net "USB2_HUB_SWB_DP")
	)
	(segment
		(start 11.421618 -105.08234)
		(end 11.421618 -104.998012)
		(width 0.13208)
		(layer "F.Cu")
		(net "USB2_HUB_SWB_DP")
	)
	(segment
		(start 12.020804 -104.2416)
		(end 12.536678 -103.724456)
		(width 0.13208)
		(layer "F.Cu")
		(net "USB2_HUB_SWB_DP")
	)
	(segment
		(start 13.072618 -103.188262)
		(end 13.072618 -103.19004)
		(width 0.13208)
		(layer "F.Cu")
		(net "USB2_HUB_SWB_DP")
	)
	(segment
		(start 14.064996 -101.548946)
		(end 14.064996 -101.74605)
		(width 0.13208)
		(layer "F.Cu")
		(net "USB2_HUB_SWB_DP")
	)
	(via
		(at 12.536678 -103.19004)
		(size 0.762)
		(drill 0.381)
		(layers "F.Cu" "B.Cu")
		(net "USB2_HUB_SWB_DP")
	)
	(segment
		(start 13.25499 -103.372412)
		(end 13.25499 -103.908352)
		(width 0.13208)
		(layer "F.Cu")
		(net "USB2_HUB_SWB_DN")
	)
	(segment
		(start 14.444472 -102.516432)
		(end 13.812774 -103.14813)
		(width 0.13208)
		(layer "F.Cu")
		(net "USB2_HUB_SWB_DN")
	)
	(segment
		(start 14.564868 -101.752146)
		(end 14.444472 -101.872542)
		(width 0.13208)
		(layer "F.Cu")
		(net "USB2_HUB_SWB_DN")
	)
	(segment
		(start 12.279884 -104.481122)
		(end 12.279884 -104.349042)
		(width 0.13208)
		(layer "F.Cu")
		(net "USB2_HUB_SWB_DN")
	)
	(segment
		(start 12.786106 -104.987344)
		(end 12.279884 -104.481122)
		(width 0.13208)
		(layer "F.Cu")
		(net "USB2_HUB_SWB_DN")
	)
	(segment
		(start 14.444472 -101.872542)
		(end 14.444472 -102.516432)
		(width 0.13208)
		(layer "F.Cu")
		(net "USB2_HUB_SWB_DN")
	)
	(segment
		(start 13.812774 -103.14813)
		(end 13.479272 -103.14813)
		(width 0.13208)
		(layer "F.Cu")
		(net "USB2_HUB_SWB_DN")
	)
	(segment
		(start 12.279884 -104.349042)
		(end 12.720574 -103.908352)
		(width 0.13208)
		(layer "F.Cu")
		(net "USB2_HUB_SWB_DN")
	)
	(segment
		(start 12.720574 -103.908352)
		(end 13.25499 -103.908352)
		(width 0.13208)
		(layer "F.Cu")
		(net "USB2_HUB_SWB_DN")
	)
	(segment
		(start 12.786106 -105.10393)
		(end 12.786106 -104.987344)
		(width 0.13208)
		(layer "F.Cu")
		(net "USB2_HUB_SWB_DN")
	)
	(segment
		(start 14.564868 -101.548946)
		(end 14.564868 -101.752146)
		(width 0.13208)
		(layer "F.Cu")
		(net "USB2_HUB_SWB_DN")
	)
	(segment
		(start 13.479272 -103.14813)
		(end 13.25499 -103.372412)
		(width 0.13208)
		(layer "F.Cu")
		(net "USB2_HUB_SWB_DN")
	)
	(via
		(at 13.25499 -103.908352)
		(size 0.762)
		(drill 0.381)
		(layers "F.Cu" "B.Cu")
		(net "USB2_HUB_SWB_DN")
	)
	(segment
		(start 11.421618 -105.88244)
		(end 11.778234 -105.88244)
		(width 0.13208)
		(layer "F.Cu")
		(net "USB2_HUB_BUF_SWB_R_DP")
	)
	(segment
		(start 11.778234 -105.88244)
		(end 12.094972 -105.565702)
		(width 0.13208)
		(layer "F.Cu")
		(net "USB2_HUB_BUF_SWB_R_DP")
	)
	(via
		(at 12.094972 -105.565702)
		(size 0.508)
		(drill 0.254)
		(layers "F.Cu" "B.Cu")
		(net "USB2_HUB_BUF_SWB_R_DP")
	)
	(via
		(at 34.676588 -405.99614)
		(size 0.6604)
		(drill 0.3302)
		(layers "F.Cu" "B.Cu")
		(net "USB2_HUB_BUF_SWB_R_DP")
	)
	(segment
		(start 36.088574 -405.932132)
		(end 35.653726 -406.36698)
		(width 0.13208)
		(layer "B.Cu")
		(net "USB2_HUB_BUF_SWB_R_DP")
	)
	(segment
		(start 30.070044 -408.537156)
		(end 32.2326 -406.3746)
		(width 0.13208)
		(layer "B.Cu")
		(net "USB2_HUB_BUF_SWB_R_DP")
	)
	(segment
		(start 11.95578 -110.95736)
		(end 11.95578 -111.181388)
		(width 0.13208)
		(layer "B.Cu")
		(net "USB2_HUB_BUF_SWB_R_DP")
	)
	(segment
		(start 35.047428 -406.36698)
		(end 34.676588 -405.99614)
		(width 0.13208)
		(layer "B.Cu")
		(net "USB2_HUB_BUF_SWB_R_DP")
	)
	(segment
		(start 10.357866 -105.807256)
		(end 10.02284 -106.142282)
		(width 0.13208)
		(layer "B.Cu")
		(net "USB2_HUB_BUF_SWB_R_DP")
	)
	(segment
		(start 16.36014 -406.171908)
		(end 16.637508 -406.449276)
		(width 0.13208)
		(layer "B.Cu")
		(net "USB2_HUB_BUF_SWB_R_DP")
	)
	(segment
		(start 19.794982 -408.537156)
		(end 30.070044 -408.537156)
		(width 0.13208)
		(layer "B.Cu")
		(net "USB2_HUB_BUF_SWB_R_DP")
	)
	(segment
		(start 35.653726 -406.36698)
		(end 35.047428 -406.36698)
		(width 0.13208)
		(layer "B.Cu")
		(net "USB2_HUB_BUF_SWB_R_DP")
	)
	(segment
		(start 11.876786 -113.019332)
		(end 11.876786 -113.400332)
		(width 0.13208)
		(layer "B.Cu")
		(net "USB2_HUB_BUF_SWB_R_DP")
	)
	(segment
		(start 11.95578 -111.181388)
		(end 11.876786 -111.260382)
		(width 0.13208)
		(layer "B.Cu")
		(net "USB2_HUB_BUF_SWB_R_DP")
	)
	(segment
		(start 10.27303 -109.963458)
		(end 11.622278 -110.521496)
		(width 0.13208)
		(layer "B.Cu")
		(net "USB2_HUB_BUF_SWB_R_DP")
	)
	(segment
		(start 10.02284 -106.142282)
		(end 10.02284 -109.589316)
		(width 0.13208)
		(layer "B.Cu")
		(net "USB2_HUB_BUF_SWB_R_DP")
	)
	(segment
		(start 11.88339 -110.782862)
		(end 11.955526 -110.957106)
		(width 0.13208)
		(layer "B.Cu")
		(net "USB2_HUB_BUF_SWB_R_DP")
	)
	(segment
		(start 11.876786 -111.260382)
		(end 11.876786 -111.619284)
		(width 0.13208)
		(layer "B.Cu")
		(net "USB2_HUB_BUF_SWB_R_DP")
	)
	(segment
		(start 11.622278 -110.521496)
		(end 11.88339 -110.782862)
		(width 0.13208)
		(layer "B.Cu")
		(net "USB2_HUB_BUF_SWB_R_DP")
	)
	(segment
		(start 11.938508 -114.404648)
		(end 11.636248 -114.706908)
		(width 0.13208)
		(layer "B.Cu")
		(net "USB2_HUB_BUF_SWB_R_DP")
	)
	(segment
		(start 11.938508 -113.462054)
		(end 11.938508 -114.404648)
		(width 0.13208)
		(layer "B.Cu")
		(net "USB2_HUB_BUF_SWB_R_DP")
	)
	(segment
		(start 12.094972 -105.565702)
		(end 11.853418 -105.807256)
		(width 0.13208)
		(layer "B.Cu")
		(net "USB2_HUB_BUF_SWB_R_DP")
	)
	(segment
		(start 36.088574 -405.93137)
		(end 36.088574 -405.932132)
		(width 0.13208)
		(layer "B.Cu")
		(net "USB2_HUB_BUF_SWB_R_DP")
	)
	(segment
		(start 34.298128 -406.3746)
		(end 34.676588 -405.99614)
		(width 0.13208)
		(layer "B.Cu")
		(net "USB2_HUB_BUF_SWB_R_DP")
	)
	(segment
		(start 11.853418 -105.807256)
		(end 10.357866 -105.807256)
		(width 0.13208)
		(layer "B.Cu")
		(net "USB2_HUB_BUF_SWB_R_DP")
	)
	(segment
		(start 11.876786 -113.400332)
		(end 11.938508 -113.462054)
		(width 0.13208)
		(layer "B.Cu")
		(net "USB2_HUB_BUF_SWB_R_DP")
	)
	(segment
		(start 11.955526 -110.957106)
		(end 11.95578 -110.95736)
		(width 0.13208)
		(layer "B.Cu")
		(net "USB2_HUB_BUF_SWB_R_DP")
	)
	(segment
		(start 32.2326 -406.3746)
		(end 34.298128 -406.3746)
		(width 0.13208)
		(layer "B.Cu")
		(net "USB2_HUB_BUF_SWB_R_DP")
	)
	(segment
		(start 10.02284 -109.589316)
		(end 10.27303 -109.963458)
		(width 0.13208)
		(layer "B.Cu")
		(net "USB2_HUB_BUF_SWB_R_DP")
	)
	(segment
		(start 17.707102 -406.449276)
		(end 19.794982 -408.537156)
		(width 0.13208)
		(layer "B.Cu")
		(net "USB2_HUB_BUF_SWB_R_DP")
	)
	(segment
		(start 16.637508 -406.449276)
		(end 17.707102 -406.449276)
		(width 0.13208)
		(layer "B.Cu")
		(net "USB2_HUB_BUF_SWB_R_DP")
	)
	(segment
		(start 17.41678 -400.978878)
		(end 17.50568 -400.889978)
		(width 0.14732)
		(layer "In15.Cu")
		(net "USB2_HUB_BUF_SWB_R_DP")
	)
	(segment
		(start 17.3609 -402.086318)
		(end 17.50568 -401.941538)
		(width 0.14732)
		(layer "In15.Cu")
		(net "USB2_HUB_BUF_SWB_R_DP")
	)
	(segment
		(start 17.3609 -402.454618)
		(end 17.3609 -402.086318)
		(width 0.14732)
		(layer "In15.Cu")
		(net "USB2_HUB_BUF_SWB_R_DP")
	)
	(segment
		(start 17.332706 -406.461468)
		(end 17.50568 -406.288494)
		(width 0.14732)
		(layer "In15.Cu")
		(net "USB2_HUB_BUF_SWB_R_DP")
	)
	(segment
		(start 17.41678 -401.415758)
		(end 17.41678 -400.978878)
		(width 0.14732)
		(layer "In15.Cu")
		(net "USB2_HUB_BUF_SWB_R_DP")
	)
	(segment
		(start 14.111478 -340.263226)
		(end 3.83667 -329.988418)
		(width 0.14732)
		(layer "In15.Cu")
		(net "USB2_HUB_BUF_SWB_R_DP")
	)
	(segment
		(start 16.69542 -398.792192)
		(end 16.69542 -346.501212)
		(width 0.14732)
		(layer "In15.Cu")
		(net "USB2_HUB_BUF_SWB_R_DP")
	)
	(segment
		(start 17.3609 -403.673818)
		(end 17.3609 -403.305518)
		(width 0.14732)
		(layer "In15.Cu")
		(net "USB2_HUB_BUF_SWB_R_DP")
	)
	(segment
		(start 17.3609 -404.699978)
		(end 17.3609 -404.331678)
		(width 0.14732)
		(layer "In15.Cu")
		(net "USB2_HUB_BUF_SWB_R_DP")
	)
	(segment
		(start 17.50568 -403.160738)
		(end 17.50568 -402.599398)
		(width 0.14732)
		(layer "In15.Cu")
		(net "USB2_HUB_BUF_SWB_R_DP")
	)
	(segment
		(start 17.50568 -406.288494)
		(end 17.50568 -404.844758)
		(width 0.14732)
		(layer "In15.Cu")
		(net "USB2_HUB_BUF_SWB_R_DP")
	)
	(segment
		(start 16.6497 -406.461468)
		(end 17.332706 -406.461468)
		(width 0.14732)
		(layer "In15.Cu")
		(net "USB2_HUB_BUF_SWB_R_DP")
	)
	(segment
		(start 17.50568 -400.889978)
		(end 17.50568 -399.602452)
		(width 0.14732)
		(layer "In15.Cu")
		(net "USB2_HUB_BUF_SWB_R_DP")
	)
	(segment
		(start 17.3609 -404.331678)
		(end 17.50568 -404.186898)
		(width 0.14732)
		(layer "In15.Cu")
		(net "USB2_HUB_BUF_SWB_R_DP")
	)
	(segment
		(start 10.018268 -137.830052)
		(end 10.018268 -121.636536)
		(width 0.14732)
		(layer "In15.Cu")
		(net "USB2_HUB_BUF_SWB_R_DP")
	)
	(segment
		(start 10.018268 -121.636536)
		(end 11.930888 -117.018816)
		(width 0.14732)
		(layer "In15.Cu")
		(net "USB2_HUB_BUF_SWB_R_DP")
	)
	(segment
		(start 16.36014 -406.171908)
		(end 16.6497 -406.461468)
		(width 0.14732)
		(layer "In15.Cu")
		(net "USB2_HUB_BUF_SWB_R_DP")
	)
	(segment
		(start 17.50568 -404.844758)
		(end 17.3609 -404.699978)
		(width 0.14732)
		(layer "In15.Cu")
		(net "USB2_HUB_BUF_SWB_R_DP")
	)
	(segment
		(start 11.930888 -115.001548)
		(end 11.636248 -114.706908)
		(width 0.14732)
		(layer "In15.Cu")
		(net "USB2_HUB_BUF_SWB_R_DP")
	)
	(segment
		(start 11.930888 -117.018816)
		(end 11.930888 -115.001548)
		(width 0.14732)
		(layer "In15.Cu")
		(net "USB2_HUB_BUF_SWB_R_DP")
	)
	(segment
		(start 17.50568 -399.602452)
		(end 16.69542 -398.792192)
		(width 0.14732)
		(layer "In15.Cu")
		(net "USB2_HUB_BUF_SWB_R_DP")
	)
	(segment
		(start 17.3609 -403.305518)
		(end 17.50568 -403.160738)
		(width 0.14732)
		(layer "In15.Cu")
		(net "USB2_HUB_BUF_SWB_R_DP")
	)
	(segment
		(start 16.69542 -346.501212)
		(end 15.403322 -343.381838)
		(width 0.14732)
		(layer "In15.Cu")
		(net "USB2_HUB_BUF_SWB_R_DP")
	)
	(segment
		(start 17.50568 -401.941538)
		(end 17.50568 -401.504658)
		(width 0.14732)
		(layer "In15.Cu")
		(net "USB2_HUB_BUF_SWB_R_DP")
	)
	(segment
		(start 3.83667 -329.988418)
		(end 3.83667 -152.753822)
		(width 0.14732)
		(layer "In15.Cu")
		(net "USB2_HUB_BUF_SWB_R_DP")
	)
	(segment
		(start 17.50568 -402.599398)
		(end 17.3609 -402.454618)
		(width 0.14732)
		(layer "In15.Cu")
		(net "USB2_HUB_BUF_SWB_R_DP")
	)
	(segment
		(start 17.50568 -403.818598)
		(end 17.3609 -403.673818)
		(width 0.14732)
		(layer "In15.Cu")
		(net "USB2_HUB_BUF_SWB_R_DP")
	)
	(segment
		(start 3.83667 -152.753822)
		(end 10.018268 -137.830052)
		(width 0.14732)
		(layer "In15.Cu")
		(net "USB2_HUB_BUF_SWB_R_DP")
	)
	(segment
		(start 15.403068 -343.381838)
		(end 14.111478 -340.263226)
		(width 0.14732)
		(layer "In15.Cu")
		(net "USB2_HUB_BUF_SWB_R_DP")
	)
	(segment
		(start 15.403322 -343.381838)
		(end 15.403068 -343.381838)
		(width 0.14732)
		(layer "In15.Cu")
		(net "USB2_HUB_BUF_SWB_R_DP")
	)
	(segment
		(start 17.50568 -404.186898)
		(end 17.50568 -403.818598)
		(width 0.14732)
		(layer "In15.Cu")
		(net "USB2_HUB_BUF_SWB_R_DP")
	)
	(segment
		(start 17.50568 -401.504658)
		(end 17.41678 -401.415758)
		(width 0.14732)
		(layer "In15.Cu")
		(net "USB2_HUB_BUF_SWB_R_DP")
	)
	(segment
		(start 12.786106 -105.90403)
		(end 12.529566 -105.90403)
		(width 0.13208)
		(layer "F.Cu")
		(net "USB2_HUB_BUF_SWB_R_DN")
	)
	(segment
		(start 12.529566 -105.90403)
		(end 12.095226 -106.33837)
		(width 0.13208)
		(layer "F.Cu")
		(net "USB2_HUB_BUF_SWB_R_DN")
	)
	(via
		(at 12.095226 -106.33837)
		(size 0.508)
		(drill 0.254)
		(layers "F.Cu" "B.Cu")
		(net "USB2_HUB_BUF_SWB_R_DN")
	)
	(via
		(at 34.675572 -407.01214)
		(size 0.6604)
		(drill 0.3302)
		(layers "F.Cu" "B.Cu")
		(net "USB2_HUB_BUF_SWB_R_DN")
	)
	(segment
		(start 12.197588 -113.457228)
		(end 12.197588 -114.404648)
		(width 0.13208)
		(layer "B.Cu")
		(net "USB2_HUB_BUF_SWB_R_DN")
	)
	(segment
		(start 12.1031 -110.635796)
		(end 12.21486 -110.905544)
		(width 0.13208)
		(layer "B.Cu")
		(net "USB2_HUB_BUF_SWB_R_DN")
	)
	(segment
		(start 16.687292 -406.708356)
		(end 17.59966 -406.708356)
		(width 0.13208)
		(layer "B.Cu")
		(net "USB2_HUB_BUF_SWB_R_DN")
	)
	(segment
		(start 12.276582 -113.378234)
		(end 12.197588 -113.457228)
		(width 0.13208)
		(layer "B.Cu")
		(net "USB2_HUB_BUF_SWB_R_DN")
	)
	(segment
		(start 35.046412 -406.6413)
		(end 34.675572 -407.01214)
		(width 0.13208)
		(layer "B.Cu")
		(net "USB2_HUB_BUF_SWB_R_DN")
	)
	(segment
		(start 10.444734 -109.753908)
		(end 11.76909 -110.301786)
		(width 0.13208)
		(layer "B.Cu")
		(net "USB2_HUB_BUF_SWB_R_DN")
	)
	(segment
		(start 11.077702 -106.190796)
		(end 10.953242 -106.066336)
		(width 0.13208)
		(layer "B.Cu")
		(net "USB2_HUB_BUF_SWB_R_DN")
	)
	(segment
		(start 10.465308 -106.066336)
		(end 10.28192 -106.249724)
		(width 0.13208)
		(layer "B.Cu")
		(net "USB2_HUB_BUF_SWB_R_DN")
	)
	(segment
		(start 10.40638 -109.005116)
		(end 10.28192 -109.129576)
		(width 0.13208)
		(layer "B.Cu")
		(net "USB2_HUB_BUF_SWB_R_DN")
	)
	(segment
		(start 34.297112 -406.63368)
		(end 34.675572 -407.01214)
		(width 0.13208)
		(layer "B.Cu")
		(net "USB2_HUB_BUF_SWB_R_DN")
	)
	(segment
		(start 10.28192 -109.129576)
		(end 10.28192 -109.510576)
		(width 0.13208)
		(layer "B.Cu")
		(net "USB2_HUB_BUF_SWB_R_DN")
	)
	(segment
		(start 10.40638 -106.61904)
		(end 10.40638 -107.00004)
		(width 0.13208)
		(layer "B.Cu")
		(net "USB2_HUB_BUF_SWB_R_DN")
	)
	(segment
		(start 10.40638 -107.613196)
		(end 10.40638 -107.994196)
		(width 0.13208)
		(layer "B.Cu")
		(net "USB2_HUB_BUF_SWB_R_DN")
	)
	(segment
		(start 12.21486 -110.905544)
		(end 12.21486 -111.176562)
		(width 0.13208)
		(layer "B.Cu")
		(net "USB2_HUB_BUF_SWB_R_DN")
	)
	(segment
		(start 35.65271 -406.6413)
		(end 35.046412 -406.6413)
		(width 0.13208)
		(layer "B.Cu")
		(net "USB2_HUB_BUF_SWB_R_DN")
	)
	(segment
		(start 10.40638 -107.994196)
		(end 10.28192 -108.118656)
		(width 0.13208)
		(layer "B.Cu")
		(net "USB2_HUB_BUF_SWB_R_DN")
	)
	(segment
		(start 10.28192 -108.118656)
		(end 10.28192 -108.499656)
		(width 0.13208)
		(layer "B.Cu")
		(net "USB2_HUB_BUF_SWB_R_DN")
	)
	(segment
		(start 12.21486 -111.176562)
		(end 12.276582 -111.238284)
		(width 0.13208)
		(layer "B.Cu")
		(net "USB2_HUB_BUF_SWB_R_DN")
	)
	(segment
		(start 11.76909 -110.301786)
		(end 12.1031 -110.635796)
		(width 0.13208)
		(layer "B.Cu")
		(net "USB2_HUB_BUF_SWB_R_DN")
	)
	(segment
		(start 12.095226 -106.33837)
		(end 11.823192 -106.066336)
		(width 0.13208)
		(layer "B.Cu")
		(net "USB2_HUB_BUF_SWB_R_DN")
	)
	(segment
		(start 19.68754 -408.796236)
		(end 30.177486 -408.796236)
		(width 0.13208)
		(layer "B.Cu")
		(net "USB2_HUB_BUF_SWB_R_DN")
	)
	(segment
		(start 10.953242 -106.066336)
		(end 10.465308 -106.066336)
		(width 0.13208)
		(layer "B.Cu")
		(net "USB2_HUB_BUF_SWB_R_DN")
	)
	(segment
		(start 10.28192 -108.499656)
		(end 10.40638 -108.624116)
		(width 0.13208)
		(layer "B.Cu")
		(net "USB2_HUB_BUF_SWB_R_DN")
	)
	(segment
		(start 32.340042 -406.63368)
		(end 34.297112 -406.63368)
		(width 0.13208)
		(layer "B.Cu")
		(net "USB2_HUB_BUF_SWB_R_DN")
	)
	(segment
		(start 12.276582 -111.238284)
		(end 12.276582 -111.619284)
		(width 0.13208)
		(layer "B.Cu")
		(net "USB2_HUB_BUF_SWB_R_DN")
	)
	(segment
		(start 10.40638 -107.00004)
		(end 10.28192 -107.1245)
		(width 0.13208)
		(layer "B.Cu")
		(net "USB2_HUB_BUF_SWB_R_DN")
	)
	(segment
		(start 11.823192 -106.066336)
		(end 11.583162 -106.066336)
		(width 0.13208)
		(layer "B.Cu")
		(net "USB2_HUB_BUF_SWB_R_DN")
	)
	(segment
		(start 11.458702 -106.190796)
		(end 11.077702 -106.190796)
		(width 0.13208)
		(layer "B.Cu")
		(net "USB2_HUB_BUF_SWB_R_DN")
	)
	(segment
		(start 10.40638 -108.624116)
		(end 10.40638 -109.005116)
		(width 0.13208)
		(layer "B.Cu")
		(net "USB2_HUB_BUF_SWB_R_DN")
	)
	(segment
		(start 30.177486 -408.796236)
		(end 32.340042 -406.63368)
		(width 0.13208)
		(layer "B.Cu")
		(net "USB2_HUB_BUF_SWB_R_DN")
	)
	(segment
		(start 10.28192 -107.488736)
		(end 10.40638 -107.613196)
		(width 0.13208)
		(layer "B.Cu")
		(net "USB2_HUB_BUF_SWB_R_DN")
	)
	(segment
		(start 10.28192 -107.1245)
		(end 10.28192 -107.488736)
		(width 0.13208)
		(layer "B.Cu")
		(net "USB2_HUB_BUF_SWB_R_DN")
	)
	(segment
		(start 17.59966 -406.708356)
		(end 19.68754 -408.796236)
		(width 0.13208)
		(layer "B.Cu")
		(net "USB2_HUB_BUF_SWB_R_DN")
	)
	(segment
		(start 16.36014 -407.035508)
		(end 16.687292 -406.708356)
		(width 0.13208)
		(layer "B.Cu")
		(net "USB2_HUB_BUF_SWB_R_DN")
	)
	(segment
		(start 12.197588 -114.404648)
		(end 12.499848 -114.706908)
		(width 0.13208)
		(layer "B.Cu")
		(net "USB2_HUB_BUF_SWB_R_DN")
	)
	(segment
		(start 12.276582 -113.019332)
		(end 12.276582 -113.378234)
		(width 0.13208)
		(layer "B.Cu")
		(net "USB2_HUB_BUF_SWB_R_DN")
	)
	(segment
		(start 11.583162 -106.066336)
		(end 11.458702 -106.190796)
		(width 0.13208)
		(layer "B.Cu")
		(net "USB2_HUB_BUF_SWB_R_DN")
	)
	(segment
		(start 10.28192 -109.510576)
		(end 10.444734 -109.753908)
		(width 0.13208)
		(layer "B.Cu")
		(net "USB2_HUB_BUF_SWB_R_DN")
	)
	(segment
		(start 36.088574 -407.077164)
		(end 35.65271 -406.6413)
		(width 0.13208)
		(layer "B.Cu")
		(net "USB2_HUB_BUF_SWB_R_DN")
	)
	(segment
		(start 10.28192 -106.49458)
		(end 10.40638 -106.61904)
		(width 0.13208)
		(layer "B.Cu")
		(net "USB2_HUB_BUF_SWB_R_DN")
	)
	(segment
		(start 10.28192 -106.249724)
		(end 10.28192 -106.49458)
		(width 0.13208)
		(layer "B.Cu")
		(net "USB2_HUB_BUF_SWB_R_DN")
	)
	(segment
		(start 4.11099 -329.874626)
		(end 4.11099 -152.808432)
		(width 0.14732)
		(layer "In15.Cu")
		(net "USB2_HUB_BUF_SWB_R_DN")
	)
	(segment
		(start 17.78 -399.48866)
		(end 16.96974 -398.6784)
		(width 0.14732)
		(layer "In15.Cu")
		(net "USB2_HUB_BUF_SWB_R_DN")
	)
	(segment
		(start 16.96974 -398.6784)
		(end 16.96974 -346.446602)
		(width 0.14732)
		(layer "In15.Cu")
		(net "USB2_HUB_BUF_SWB_R_DN")
	)
	(segment
		(start 17.446498 -406.735788)
		(end 17.78 -406.402286)
		(width 0.14732)
		(layer "In15.Cu")
		(net "USB2_HUB_BUF_SWB_R_DN")
	)
	(segment
		(start 12.205208 -115.001548)
		(end 12.499848 -114.706908)
		(width 0.14732)
		(layer "In15.Cu")
		(net "USB2_HUB_BUF_SWB_R_DN")
	)
	(segment
		(start 16.96974 -346.446602)
		(end 14.344142 -340.107778)
		(width 0.14732)
		(layer "In15.Cu")
		(net "USB2_HUB_BUF_SWB_R_DN")
	)
	(segment
		(start 10.292588 -137.884662)
		(end 10.292588 -121.691146)
		(width 0.14732)
		(layer "In15.Cu")
		(net "USB2_HUB_BUF_SWB_R_DN")
	)
	(segment
		(start 10.292588 -121.691146)
		(end 12.205208 -117.073426)
		(width 0.14732)
		(layer "In15.Cu")
		(net "USB2_HUB_BUF_SWB_R_DN")
	)
	(segment
		(start 17.78 -406.402286)
		(end 17.78 -399.48866)
		(width 0.14732)
		(layer "In15.Cu")
		(net "USB2_HUB_BUF_SWB_R_DN")
	)
	(segment
		(start 16.65986 -406.735788)
		(end 17.446498 -406.735788)
		(width 0.14732)
		(layer "In15.Cu")
		(net "USB2_HUB_BUF_SWB_R_DN")
	)
	(segment
		(start 16.36014 -407.035508)
		(end 16.65986 -406.735788)
		(width 0.14732)
		(layer "In15.Cu")
		(net "USB2_HUB_BUF_SWB_R_DN")
	)
	(segment
		(start 4.11099 -152.808432)
		(end 10.292588 -137.884662)
		(width 0.14732)
		(layer "In15.Cu")
		(net "USB2_HUB_BUF_SWB_R_DN")
	)
	(segment
		(start 12.205208 -117.073426)
		(end 12.205208 -115.001548)
		(width 0.14732)
		(layer "In15.Cu")
		(net "USB2_HUB_BUF_SWB_R_DN")
	)
	(segment
		(start 14.344142 -340.107778)
		(end 4.11099 -329.874626)
		(width 0.14732)
		(layer "In15.Cu")
		(net "USB2_HUB_BUF_SWB_R_DN")
	)
	(segment
		(start 15.288006 -105.93578)
		(end 15.279116 -106.282998)
		(width 0.13208)
		(layer "F.Cu")
		(net "USB2_HOST_BMC_B_BUF_DP")
	)
	(segment
		(start 15.70482 -107.123484)
		(end 15.286228 -107.123484)
		(width 0.13208)
		(layer "F.Cu")
		(net "USB2_HOST_BMC_B_BUF_DP")
	)
	(segment
		(start 15.286228 -107.14101)
		(end 15.286228 -107.123484)
		(width 0.13208)
		(layer "F.Cu")
		(net "USB2_HOST_BMC_B_BUF_DP")
	)
	(segment
		(start 11.421618 -106.68254)
		(end 11.421618 -107.096306)
		(width 0.13208)
		(layer "F.Cu")
		(net "USB2_HOST_BMC_B_BUF_DP")
	)
	(segment
		(start 11.9761 -108.614464)
		(end 11.67384 -108.916724)
		(width 0.13208)
		(layer "F.Cu")
		(net "USB2_HOST_BMC_B_BUF_DP")
	)
	(segment
		(start 15.537434 -108.916724)
		(end 15.839694 -108.614464)
		(width 0.13208)
		(layer "F.Cu")
		(net "USB2_HOST_BMC_B_BUF_DP")
	)
	(segment
		(start 15.839694 -108.614464)
		(end 15.839694 -107.694476)
		(width 0.13208)
		(layer "F.Cu")
		(net "USB2_HOST_BMC_B_BUF_DP")
	)
	(segment
		(start 15.279116 -106.282998)
		(end 15.588488 -106.60761)
		(width 0.13208)
		(layer "F.Cu")
		(net "USB2_HOST_BMC_B_BUF_DP")
	)
	(segment
		(start 11.421618 -107.096306)
		(end 11.9761 -107.650788)
		(width 0.13208)
		(layer "F.Cu")
		(net "USB2_HOST_BMC_B_BUF_DP")
	)
	(segment
		(start 15.839694 -107.694476)
		(end 15.286228 -107.14101)
		(width 0.13208)
		(layer "F.Cu")
		(net "USB2_HOST_BMC_B_BUF_DP")
	)
	(segment
		(start 11.9761 -107.650788)
		(end 11.9761 -108.614464)
		(width 0.13208)
		(layer "F.Cu")
		(net "USB2_HOST_BMC_B_BUF_DP")
	)
	(segment
		(start 15.836392 -106.855514)
		(end 15.836392 -106.991912)
		(width 0.13208)
		(layer "F.Cu")
		(net "USB2_HOST_BMC_B_BUF_DP")
	)
	(segment
		(start 15.836392 -106.991912)
		(end 15.70482 -107.123484)
		(width 0.13208)
		(layer "F.Cu")
		(net "USB2_HOST_BMC_B_BUF_DP")
	)
	(segment
		(start 15.588488 -106.60761)
		(end 15.836392 -106.855514)
		(width 0.13208)
		(layer "F.Cu")
		(net "USB2_HOST_BMC_B_BUF_DP")
	)
	(via
		(at 15.537434 -108.916724)
		(size 0.508)
		(drill 0.254)
		(layers "F.Cu" "B.Cu")
		(net "USB2_HOST_BMC_B_BUF_DP")
	)
	(via
		(at 11.67384 -108.916724)
		(size 0.508)
		(drill 0.254)
		(layers "F.Cu" "B.Cu")
		(net "USB2_HOST_BMC_B_BUF_DP")
	)
	(segment
		(start 11.9761 -109.5375)
		(end 12.130786 -109.692186)
		(width 0.13208)
		(layer "B.Cu")
		(net "USB2_HOST_BMC_B_BUF_DP")
	)
	(segment
		(start 13.03274 -109.80674)
		(end 15.253208 -107.586272)
		(width 0.13208)
		(layer "B.Cu")
		(net "USB2_HOST_BMC_B_BUF_DP")
	)
	(segment
		(start 15.839948 -108.61421)
		(end 15.537434 -108.916724)
		(width 0.13208)
		(layer "B.Cu")
		(net "USB2_HOST_BMC_B_BUF_DP")
	)
	(segment
		(start 12.407646 -109.80674)
		(end 13.03274 -109.80674)
		(width 0.13208)
		(layer "B.Cu")
		(net "USB2_HOST_BMC_B_BUF_DP")
	)
	(segment
		(start 11.67384 -108.916724)
		(end 11.9761 -109.218984)
		(width 0.13208)
		(layer "B.Cu")
		(net "USB2_HOST_BMC_B_BUF_DP")
	)
	(segment
		(start 15.752826 -107.586272)
		(end 15.839948 -107.673394)
		(width 0.13208)
		(layer "B.Cu")
		(net "USB2_HOST_BMC_B_BUF_DP")
	)
	(segment
		(start 11.9761 -109.218984)
		(end 11.9761 -109.5375)
		(width 0.13208)
		(layer "B.Cu")
		(net "USB2_HOST_BMC_B_BUF_DP")
	)
	(segment
		(start 15.253208 -107.586272)
		(end 15.752826 -107.586272)
		(width 0.13208)
		(layer "B.Cu")
		(net "USB2_HOST_BMC_B_BUF_DP")
	)
	(segment
		(start 15.839948 -107.673394)
		(end 15.839948 -108.61421)
		(width 0.13208)
		(layer "B.Cu")
		(net "USB2_HOST_BMC_B_BUF_DP")
	)
	(segment
		(start 12.130786 -109.692186)
		(end 12.407646 -109.80674)
		(width 0.13208)
		(layer "B.Cu")
		(net "USB2_HOST_BMC_B_BUF_DP")
	)
	(segment
		(start 16.645382 -105.96626)
		(end 16.637254 -106.315002)
		(width 0.13208)
		(layer "F.Cu")
		(net "USB2_HOST_BMC_B_BUF_DN")
	)
	(segment
		(start 16.098774 -108.614464)
		(end 16.098774 -107.694476)
		(width 0.13208)
		(layer "F.Cu")
		(net "USB2_HOST_BMC_B_BUF_DN")
	)
	(segment
		(start 12.786106 -107.099862)
		(end 12.23518 -107.650788)
		(width 0.13208)
		(layer "F.Cu")
		(net "USB2_HOST_BMC_B_BUF_DN")
	)
	(segment
		(start 16.196056 -107.123484)
		(end 16.645382 -107.123484)
		(width 0.13208)
		(layer "F.Cu")
		(net "USB2_HOST_BMC_B_BUF_DN")
	)
	(segment
		(start 16.095472 -106.833162)
		(end 16.095472 -107.0229)
		(width 0.13208)
		(layer "F.Cu")
		(net "USB2_HOST_BMC_B_BUF_DN")
	)
	(segment
		(start 16.637254 -106.315002)
		(end 16.095472 -106.833162)
		(width 0.13208)
		(layer "F.Cu")
		(net "USB2_HOST_BMC_B_BUF_DN")
	)
	(segment
		(start 16.645382 -107.147868)
		(end 16.645382 -107.123484)
		(width 0.13208)
		(layer "F.Cu")
		(net "USB2_HOST_BMC_B_BUF_DN")
	)
	(segment
		(start 12.786106 -106.70413)
		(end 12.786106 -107.099862)
		(width 0.13208)
		(layer "F.Cu")
		(net "USB2_HOST_BMC_B_BUF_DN")
	)
	(segment
		(start 12.23518 -107.650788)
		(end 12.23518 -108.614464)
		(width 0.13208)
		(layer "F.Cu")
		(net "USB2_HOST_BMC_B_BUF_DN")
	)
	(segment
		(start 16.401034 -108.916724)
		(end 16.098774 -108.614464)
		(width 0.13208)
		(layer "F.Cu")
		(net "USB2_HOST_BMC_B_BUF_DN")
	)
	(segment
		(start 16.098774 -107.694476)
		(end 16.645382 -107.147868)
		(width 0.13208)
		(layer "F.Cu")
		(net "USB2_HOST_BMC_B_BUF_DN")
	)
	(segment
		(start 12.23518 -108.614464)
		(end 12.53744 -108.916724)
		(width 0.13208)
		(layer "F.Cu")
		(net "USB2_HOST_BMC_B_BUF_DN")
	)
	(segment
		(start 16.095472 -107.0229)
		(end 16.196056 -107.123484)
		(width 0.13208)
		(layer "F.Cu")
		(net "USB2_HOST_BMC_B_BUF_DN")
	)
	(via
		(at 12.53744 -108.916724)
		(size 0.508)
		(drill 0.254)
		(layers "F.Cu" "B.Cu")
		(net "USB2_HOST_BMC_B_BUF_DN")
	)
	(via
		(at 16.401034 -108.916724)
		(size 0.508)
		(drill 0.254)
		(layers "F.Cu" "B.Cu")
		(net "USB2_HOST_BMC_B_BUF_DN")
	)
	(segment
		(start 12.23518 -109.18952)
		(end 12.23518 -109.430058)
		(width 0.13208)
		(layer "B.Cu")
		(net "USB2_HOST_BMC_B_BUF_DN")
	)
	(segment
		(start 15.145766 -107.327192)
		(end 15.860268 -107.327192)
		(width 0.13208)
		(layer "B.Cu")
		(net "USB2_HOST_BMC_B_BUF_DN")
	)
	(segment
		(start 12.925298 -109.54766)
		(end 15.145766 -107.327192)
		(width 0.13208)
		(layer "B.Cu")
		(net "USB2_HOST_BMC_B_BUF_DN")
	)
	(segment
		(start 12.53744 -108.916724)
		(end 12.507976 -108.916724)
		(width 0.13208)
		(layer "B.Cu")
		(net "USB2_HOST_BMC_B_BUF_DN")
	)
	(segment
		(start 12.459208 -109.54766)
		(end 12.925298 -109.54766)
		(width 0.13208)
		(layer "B.Cu")
		(net "USB2_HOST_BMC_B_BUF_DN")
	)
	(segment
		(start 16.099028 -107.565952)
		(end 16.099028 -108.614718)
		(width 0.13208)
		(layer "B.Cu")
		(net "USB2_HOST_BMC_B_BUF_DN")
	)
	(segment
		(start 15.860268 -107.327192)
		(end 16.099028 -107.565952)
		(width 0.13208)
		(layer "B.Cu")
		(net "USB2_HOST_BMC_B_BUF_DN")
	)
	(segment
		(start 12.23518 -109.430058)
		(end 12.277598 -109.472476)
		(width 0.13208)
		(layer "B.Cu")
		(net "USB2_HOST_BMC_B_BUF_DN")
	)
	(segment
		(start 12.277598 -109.472476)
		(end 12.459208 -109.54766)
		(width 0.13208)
		(layer "B.Cu")
		(net "USB2_HOST_BMC_B_BUF_DN")
	)
	(segment
		(start 12.507976 -108.916724)
		(end 12.23518 -109.18952)
		(width 0.13208)
		(layer "B.Cu")
		(net "USB2_HOST_BMC_B_BUF_DN")
	)
	(segment
		(start 16.099028 -108.614718)
		(end 16.401034 -108.916724)
		(width 0.13208)
		(layer "B.Cu")
		(net "USB2_HOST_BMC_B_BUF_DN")
	)
	(segment
		(start 372.011702 -412.6992)
		(end 372.83136 -413.518858)
		(width 0.12954)
		(layer "F.Cu")
		(net "UART_BMC_BIC_R_RX")
	)
	(segment
		(start 362.95076 -403.322028)
		(end 362.69676 -403.322028)
		(width 0.12954)
		(layer "F.Cu")
		(net "UART_BMC_BIC_R_RX")
	)
	(segment
		(start 364.29188 -404.663148)
		(end 362.95076 -403.322028)
		(width 0.12954)
		(layer "F.Cu")
		(net "UART_BMC_BIC_R_RX")
	)
	(segment
		(start 364.29188 -405.3586)
		(end 364.29188 -404.663148)
		(width 0.12954)
		(layer "F.Cu")
		(net "UART_BMC_BIC_R_RX")
	)
	(segment
		(start 364.29188 -408.91968)
		(end 368.0714 -412.6992)
		(width 0.12954)
		(layer "F.Cu")
		(net "UART_BMC_BIC_R_RX")
	)
	(segment
		(start 368.0714 -412.6992)
		(end 372.011702 -412.6992)
		(width 0.12954)
		(layer "F.Cu")
		(net "UART_BMC_BIC_R_RX")
	)
	(segment
		(start 364.29188 -405.3586)
		(end 364.29188 -408.91968)
		(width 0.12954)
		(layer "F.Cu")
		(net "UART_BMC_BIC_R_RX")
	)
	(via
		(at 364.29188 -405.3586)
		(size 0.762)
		(drill 0.381)
		(layers "F.Cu" "B.Cu")
		(net "UART_BMC_BIC_R_RX")
	)
	(segment
		(start 368.32159 -402.918168)
		(end 368.31397 -402.910548)
		(width 0.12954)
		(layer "F.Cu")
		(net "UART_BMC_BIC_R_BUF_RX")
	)
	(segment
		(start 366.394746 -402.672042)
		(end 368.075464 -402.672042)
		(width 0.12954)
		(layer "F.Cu")
		(net "UART_BMC_BIC_R_BUF_RX")
	)
	(segment
		(start 364.59668 -402.672042)
		(end 366.394746 -402.672042)
		(width 0.12954)
		(layer "F.Cu")
		(net "UART_BMC_BIC_R_BUF_RX")
	)
	(segment
		(start 368.32159 -403.936708)
		(end 368.32159 -402.918168)
		(width 0.12954)
		(layer "F.Cu")
		(net "UART_BMC_BIC_R_BUF_RX")
	)
	(segment
		(start 368.075464 -402.672042)
		(end 368.31397 -402.910548)
		(width 0.12954)
		(layer "F.Cu")
		(net "UART_BMC_BIC_R_BUF_RX")
	)
	(via
		(at 366.394746 -402.672042)
		(size 0.762)
		(drill 0.381)
		(layers "F.Cu" "B.Cu")
		(net "UART_BMC_BIC_R_BUF_RX")
	)
	(via
		(at 14.113256 -114.232436)
		(size 0.6604)
		(drill 0.3302)
		(layers "F.Cu" "B.Cu")
		(net "TP_USB2_ENA_HS")
	)
	(segment
		(start 14.113256 -114.232436)
		(end 13.74902 -113.8682)
		(width 0.12954)
		(layer "B.Cu")
		(net "TP_USB2_ENA_HS")
	)
	(segment
		(start 13.113766 -112.919256)
		(end 12.876784 -112.919256)
		(width 0.12954)
		(layer "B.Cu")
		(net "TP_USB2_ENA_HS")
	)
	(segment
		(start 13.74902 -113.55451)
		(end 13.113766 -112.919256)
		(width 0.12954)
		(layer "B.Cu")
		(net "TP_USB2_ENA_HS")
	)
	(segment
		(start 13.74902 -113.8682)
		(end 13.74902 -113.55451)
		(width 0.12954)
		(layer "B.Cu")
		(net "TP_USB2_ENA_HS")
	)
	(via
		(at 8.4709 -110.487968)
		(size 0.6604)
		(drill 0.3302)
		(layers "F.Cu" "B.Cu")
		(net "TP_USB2_CD")
	)
	(segment
		(start 10.783062 -112.11941)
		(end 11.276584 -112.11941)
		(width 0.12954)
		(layer "B.Cu")
		(net "TP_USB2_CD")
	)
	(segment
		(start 8.4709 -110.487968)
		(end 9.15162 -110.487968)
		(width 0.12954)
		(layer "B.Cu")
		(net "TP_USB2_CD")
	)
	(segment
		(start 9.15162 -110.487968)
		(end 10.783062 -112.11941)
		(width 0.12954)
		(layer "B.Cu")
		(net "TP_USB2_CD")
	)
	(segment
		(start 347.039692 -46.205648)
		(end 346.656152 -45.949108)
		(width 0.0889)
		(layer "F.Cu")
		(net "TP_USB2_9_DP")
	)
	(segment
		(start 346.656152 -45.949108)
		(end 346.384626 -45.949108)
		(width 0.0889)
		(layer "F.Cu")
		(net "TP_USB2_9_DP")
	)
	(segment
		(start 353.306126 -44.57446)
		(end 351.54997 -46.330616)
		(width 0.0889)
		(layer "F.Cu")
		(net "TP_USB2_9_DP")
	)
	(segment
		(start 347.879924 -46.330616)
		(end 347.039692 -46.205648)
		(width 0.0889)
		(layer "F.Cu")
		(net "TP_USB2_9_DP")
	)
	(segment
		(start 355.138228 -43.55338)
		(end 354.79355 -43.898058)
		(width 0.0889)
		(layer "F.Cu")
		(net "TP_USB2_9_DP")
	)
	(segment
		(start 354.488496 -44.394628)
		(end 353.74072 -44.394628)
		(width 0.0889)
		(layer "F.Cu")
		(net "TP_USB2_9_DP")
	)
	(segment
		(start 353.74072 -44.394628)
		(end 353.306126 -44.57446)
		(width 0.0889)
		(layer "F.Cu")
		(net "TP_USB2_9_DP")
	)
	(segment
		(start 354.79355 -44.089574)
		(end 354.488496 -44.394628)
		(width 0.0889)
		(layer "F.Cu")
		(net "TP_USB2_9_DP")
	)
	(segment
		(start 351.54997 -46.330616)
		(end 347.879924 -46.330616)
		(width 0.0889)
		(layer "F.Cu")
		(net "TP_USB2_9_DP")
	)
	(segment
		(start 354.79355 -43.898058)
		(end 354.79355 -44.089574)
		(width 0.0889)
		(layer "F.Cu")
		(net "TP_USB2_9_DP")
	)
	(via
		(at 355.138228 -43.55338)
		(size 0.508)
		(drill 0.254)
		(layers "F.Cu" "B.Cu")
		(net "TP_USB2_9_DP")
	)
	(segment
		(start 352.428048 -45.183044)
		(end 352.302572 -45.308774)
		(width 0.0889)
		(layer "F.Cu")
		(net "TP_USB2_9_DN")
	)
	(segment
		(start 352.162364 -45.308774)
		(end 352.036888 -45.434504)
		(width 0.0889)
		(layer "F.Cu")
		(net "TP_USB2_9_DN")
	)
	(segment
		(start 347.511116 -46.043342)
		(end 347.41612 -45.9486)
		(width 0.0889)
		(layer "F.Cu")
		(net "TP_USB2_9_DN")
	)
	(segment
		(start 353.66833 -44.196508)
		(end 353.23526 -44.375832)
		(width 0.0889)
		(layer "F.Cu")
		(net "TP_USB2_9_DN")
	)
	(segment
		(start 347.41612 -45.9486)
		(end 347.214698 -45.949108)
		(width 0.0889)
		(layer "F.Cu")
		(net "TP_USB2_9_DN")
	)
	(segment
		(start 352.693732 -44.91736)
		(end 352.553778 -44.91736)
		(width 0.0889)
		(layer "F.Cu")
		(net "TP_USB2_9_DN")
	)
	(segment
		(start 354.530914 -43.962066)
		(end 354.530914 -44.067476)
		(width 0.0889)
		(layer "F.Cu")
		(net "TP_USB2_9_DN")
	)
	(segment
		(start 352.819208 -44.791884)
		(end 352.693732 -44.91736)
		(width 0.0889)
		(layer "F.Cu")
		(net "TP_USB2_9_DN")
	)
	(segment
		(start 354.122228 -43.55338)
		(end 354.530914 -43.962066)
		(width 0.0889)
		(layer "F.Cu")
		(net "TP_USB2_9_DN")
	)
	(segment
		(start 352.553778 -44.91736)
		(end 352.428048 -45.04309)
		(width 0.0889)
		(layer "F.Cu")
		(net "TP_USB2_9_DN")
	)
	(segment
		(start 351.911412 -45.699934)
		(end 351.771204 -45.699934)
		(width 0.0889)
		(layer "F.Cu")
		(net "TP_USB2_9_DN")
	)
	(segment
		(start 351.645474 -45.825664)
		(end 351.645474 -45.965872)
		(width 0.0889)
		(layer "F.Cu")
		(net "TP_USB2_9_DN")
	)
	(segment
		(start 352.036888 -45.434504)
		(end 352.036888 -45.574458)
		(width 0.0889)
		(layer "F.Cu")
		(net "TP_USB2_9_DN")
	)
	(segment
		(start 351.470976 -46.14037)
		(end 347.894148 -46.14037)
		(width 0.0889)
		(layer "F.Cu")
		(net "TP_USB2_9_DN")
	)
	(segment
		(start 351.645474 -45.965872)
		(end 351.470976 -46.14037)
		(width 0.0889)
		(layer "F.Cu")
		(net "TP_USB2_9_DN")
	)
	(segment
		(start 347.659452 -46.105318)
		(end 347.511116 -46.043342)
		(width 0.0889)
		(layer "F.Cu")
		(net "TP_USB2_9_DN")
	)
	(segment
		(start 347.894148 -46.14037)
		(end 347.659452 -46.105318)
		(width 0.0889)
		(layer "F.Cu")
		(net "TP_USB2_9_DN")
	)
	(segment
		(start 352.819208 -44.651676)
		(end 352.819208 -44.791884)
		(width 0.0889)
		(layer "F.Cu")
		(net "TP_USB2_9_DN")
	)
	(segment
		(start 353.23526 -44.375832)
		(end 353.085146 -44.525946)
		(width 0.0889)
		(layer "F.Cu")
		(net "TP_USB2_9_DN")
	)
	(segment
		(start 352.302572 -45.308774)
		(end 352.162364 -45.308774)
		(width 0.0889)
		(layer "F.Cu")
		(net "TP_USB2_9_DN")
	)
	(segment
		(start 354.530914 -44.067476)
		(end 354.401882 -44.196508)
		(width 0.0889)
		(layer "F.Cu")
		(net "TP_USB2_9_DN")
	)
	(segment
		(start 352.944938 -44.525946)
		(end 352.819208 -44.651676)
		(width 0.0889)
		(layer "F.Cu")
		(net "TP_USB2_9_DN")
	)
	(segment
		(start 354.401882 -44.196508)
		(end 353.66833 -44.196508)
		(width 0.0889)
		(layer "F.Cu")
		(net "TP_USB2_9_DN")
	)
	(segment
		(start 352.428048 -45.04309)
		(end 352.428048 -45.183044)
		(width 0.0889)
		(layer "F.Cu")
		(net "TP_USB2_9_DN")
	)
	(segment
		(start 351.771204 -45.699934)
		(end 351.645474 -45.825664)
		(width 0.0889)
		(layer "F.Cu")
		(net "TP_USB2_9_DN")
	)
	(segment
		(start 352.036888 -45.574458)
		(end 351.911412 -45.699934)
		(width 0.0889)
		(layer "F.Cu")
		(net "TP_USB2_9_DN")
	)
	(segment
		(start 353.085146 -44.525946)
		(end 352.944938 -44.525946)
		(width 0.0889)
		(layer "F.Cu")
		(net "TP_USB2_9_DN")
	)
	(via
		(at 354.122228 -43.55338)
		(size 0.508)
		(drill 0.254)
		(layers "F.Cu" "B.Cu")
		(net "TP_USB2_9_DN")
	)
	(segment
		(start 137.808716 -118.93677)
		(end 136.09574 -118.93677)
		(width 0.12954)
		(layer "F.Cu")
		(net "TP_PCA9555_U51_P06")
	)
	(via
		(at 136.09574 -118.93677)
		(size 0.762)
		(drill 0.381)
		(layers "F.Cu" "B.Cu")
		(net "TP_PCA9555_U51_P06")
	)
	(segment
		(start 143.658844 -122.186954)
		(end 146.558 -122.186954)
		(width 0.12954)
		(layer "F.Cu")
		(net "TP_PCA9555_U51_P17")
	)
	(via
		(at 146.558 -122.186954)
		(size 0.762)
		(drill 0.381)
		(layers "F.Cu" "B.Cu")
		(net "TP_PCA9555_U51_P17")
	)
	(segment
		(start 143.658844 -121.536968)
		(end 145.42516 -121.536968)
		(width 0.12954)
		(layer "F.Cu")
		(net "TP_PCA9555_U51_P16")
	)
	(via
		(at 145.42516 -121.536968)
		(size 0.762)
		(drill 0.381)
		(layers "F.Cu" "B.Cu")
		(net "TP_PCA9555_U51_P16")
	)
	(segment
		(start 143.658844 -120.886728)
		(end 146.55038 -120.886728)
		(width 0.12954)
		(layer "F.Cu")
		(net "TP_PCA9555_U51_P15")
	)
	(via
		(at 146.55038 -120.886728)
		(size 0.762)
		(drill 0.381)
		(layers "F.Cu" "B.Cu")
		(net "TP_PCA9555_U51_P15")
	)
	(segment
		(start 143.658844 -120.236742)
		(end 145.384266 -120.236742)
		(width 0.12954)
		(layer "F.Cu")
		(net "TP_PCA9555_U51_P14")
	)
	(via
		(at 145.384266 -120.236742)
		(size 0.762)
		(drill 0.381)
		(layers "F.Cu" "B.Cu")
		(net "TP_PCA9555_U51_P14")
	)
	(segment
		(start 144.80032 -119.337328)
		(end 146.53768 -119.337328)
		(width 0.12954)
		(layer "F.Cu")
		(net "TP_PCA9555_U51_P13")
	)
	(segment
		(start 144.550892 -119.586756)
		(end 144.80032 -119.337328)
		(width 0.12954)
		(layer "F.Cu")
		(net "TP_PCA9555_U51_P13")
	)
	(segment
		(start 143.658844 -119.586756)
		(end 144.550892 -119.586756)
		(width 0.12954)
		(layer "F.Cu")
		(net "TP_PCA9555_U51_P13")
	)
	(via
		(at 146.53768 -119.337328)
		(size 0.762)
		(drill 0.381)
		(layers "F.Cu" "B.Cu")
		(net "TP_PCA9555_U51_P13")
	)
	(segment
		(start 144.446498 -118.93677)
		(end 144.9705 -118.412768)
		(width 0.12954)
		(layer "F.Cu")
		(net "TP_PCA9555_U51_P12")
	)
	(segment
		(start 144.9705 -118.412768)
		(end 145.3896 -118.412768)
		(width 0.12954)
		(layer "F.Cu")
		(net "TP_PCA9555_U51_P12")
	)
	(segment
		(start 143.658844 -118.93677)
		(end 144.446498 -118.93677)
		(width 0.12954)
		(layer "F.Cu")
		(net "TP_PCA9555_U51_P12")
	)
	(via
		(at 145.3896 -118.412768)
		(size 0.762)
		(drill 0.381)
		(layers "F.Cu" "B.Cu")
		(net "TP_PCA9555_U51_P12")
	)
	(segment
		(start 144.405604 -118.286784)
		(end 145.20418 -117.488208)
		(width 0.12954)
		(layer "F.Cu")
		(net "TP_PCA9555_U51_P11")
	)
	(segment
		(start 145.20418 -117.488208)
		(end 146.5453 -117.488208)
		(width 0.12954)
		(layer "F.Cu")
		(net "TP_PCA9555_U51_P11")
	)
	(segment
		(start 143.658844 -118.286784)
		(end 144.405604 -118.286784)
		(width 0.12954)
		(layer "F.Cu")
		(net "TP_PCA9555_U51_P11")
	)
	(via
		(at 146.5453 -117.488208)
		(size 0.762)
		(drill 0.381)
		(layers "F.Cu" "B.Cu")
		(net "TP_PCA9555_U51_P11")
	)
	(segment
		(start 143.658844 -117.536976)
		(end 144.505172 -117.536976)
		(width 0.12954)
		(layer "F.Cu")
		(net "TP_PCA9555_U51_P10")
	)
	(segment
		(start 144.505172 -117.536976)
		(end 145.39722 -116.644928)
		(width 0.12954)
		(layer "F.Cu")
		(net "TP_PCA9555_U51_P10")
	)
	(via
		(at 145.39722 -116.644928)
		(size 0.762)
		(drill 0.381)
		(layers "F.Cu" "B.Cu")
		(net "TP_PCA9555_U51_P10")
	)
	(segment
		(start 183.755538 -119.375428)
		(end 184.155588 -119.775478)
		(width 0.12954)
		(layer "F.Cu")
		(net "CLK_GEN2_GPU_FPGA_OE_R_N")
	)
	(segment
		(start 197.104 -90.538808)
		(end 197.104 -92.401898)
		(width 0.12954)
		(layer "F.Cu")
		(net "CLK_GEN2_GPU_FPGA_OE_R_N")
	)
	(segment
		(start 196.72046 -90.155268)
		(end 197.104 -90.538808)
		(width 0.12954)
		(layer "F.Cu")
		(net "CLK_GEN2_GPU_FPGA_OE_R_N")
	)
	(via
		(at 184.155588 -119.775478)
		(size 0.4572)
		(drill 0.254)
		(layers "F.Cu" "B.Cu")
		(net "CLK_GEN2_GPU_FPGA_OE_R_N")
	)
	(via
		(at 196.72046 -90.155268)
		(size 0.508)
		(drill 0.254)
		(layers "F.Cu" "B.Cu")
		(net "CLK_GEN2_GPU_FPGA_OE_R_N")
	)
	(segment
		(start 185.35904 -119.228108)
		(end 185.2168 -119.370348)
		(width 0.127)
		(layer "In13.Cu")
		(net "CLK_GEN2_GPU_FPGA_OE_R_N")
	)
	(segment
		(start 186.24042 -103.797608)
		(end 185.35904 -104.678988)
		(width 0.127)
		(layer "In13.Cu")
		(net "CLK_GEN2_GPU_FPGA_OE_R_N")
	)
	(segment
		(start 196.72046 -90.543888)
		(end 192.1256 -95.138748)
		(width 0.127)
		(layer "In13.Cu")
		(net "CLK_GEN2_GPU_FPGA_OE_R_N")
	)
	(segment
		(start 188.443616 -101.824028)
		(end 186.95162 -101.824028)
		(width 0.127)
		(layer "In13.Cu")
		(net "CLK_GEN2_GPU_FPGA_OE_R_N")
	)
	(segment
		(start 186.24042 -102.535228)
		(end 186.24042 -103.797608)
		(width 0.127)
		(layer "In13.Cu")
		(net "CLK_GEN2_GPU_FPGA_OE_R_N")
	)
	(segment
		(start 192.1256 -98.142044)
		(end 188.443616 -101.824028)
		(width 0.127)
		(layer "In13.Cu")
		(net "CLK_GEN2_GPU_FPGA_OE_R_N")
	)
	(segment
		(start 184.560718 -119.370348)
		(end 184.155588 -119.775478)
		(width 0.127)
		(layer "In13.Cu")
		(net "CLK_GEN2_GPU_FPGA_OE_R_N")
	)
	(segment
		(start 186.95162 -101.824028)
		(end 186.24042 -102.535228)
		(width 0.127)
		(layer "In13.Cu")
		(net "CLK_GEN2_GPU_FPGA_OE_R_N")
	)
	(segment
		(start 185.2168 -119.370348)
		(end 184.560718 -119.370348)
		(width 0.127)
		(layer "In13.Cu")
		(net "CLK_GEN2_GPU_FPGA_OE_R_N")
	)
	(segment
		(start 185.35904 -104.678988)
		(end 185.35904 -119.228108)
		(width 0.127)
		(layer "In13.Cu")
		(net "CLK_GEN2_GPU_FPGA_OE_R_N")
	)
	(segment
		(start 196.72046 -90.155268)
		(end 196.72046 -90.543888)
		(width 0.127)
		(layer "In13.Cu")
		(net "CLK_GEN2_GPU_FPGA_OE_R_N")
	)
	(segment
		(start 192.1256 -95.138748)
		(end 192.1256 -98.142044)
		(width 0.127)
		(layer "In13.Cu")
		(net "CLK_GEN2_GPU_FPGA_OE_R_N")
	)
	(segment
		(start 241.50828 -124.399548)
		(end 240.890044 -125.017784)
		(width 0.12954)
		(layer "F.Cu")
		(net "TP_CLK_100M_DIF18_DP")
	)
	(segment
		(start 240.890044 -125.017784)
		(end 237.748064 -125.017784)
		(width 0.12954)
		(layer "F.Cu")
		(net "TP_CLK_100M_DIF18_DP")
	)
	(via
		(at 241.50828 -124.399548)
		(size 0.762)
		(drill 0.381)
		(layers "F.Cu" "B.Cu")
		(net "TP_CLK_100M_DIF18_DP")
	)
	(segment
		(start 237.876334 -125.38964)
		(end 237.748064 -125.51791)
		(width 0.12954)
		(layer "F.Cu")
		(net "TP_CLK_100M_DIF18_DN")
	)
	(segment
		(start 242.245388 -125.38964)
		(end 237.876334 -125.38964)
		(width 0.12954)
		(layer "F.Cu")
		(net "TP_CLK_100M_DIF18_DN")
	)
	(segment
		(start 243.05768 -124.577348)
		(end 242.245388 -125.38964)
		(width 0.12954)
		(layer "F.Cu")
		(net "TP_CLK_100M_DIF18_DN")
	)
	(via
		(at 243.05768 -124.577348)
		(size 0.762)
		(drill 0.381)
		(layers "F.Cu" "B.Cu")
		(net "TP_CLK_100M_DIF18_DN")
	)
	(segment
		(start 13.819632 -408.916886)
		(end 13.800582 -408.916886)
		(width 0.12954)
		(layer "F.Cu")
		(net "TCA9539_0_ADD1")
	)
	(segment
		(start 13.800582 -411.202886)
		(end 14.435582 -410.567886)
		(width 0.12954)
		(layer "F.Cu")
		(net "TCA9539_0_ADD1")
	)
	(segment
		(start 14.054582 -411.456886)
		(end 14.054582 -412.453836)
		(width 0.12954)
		(layer "F.Cu")
		(net "TCA9539_0_ADD1")
	)
	(segment
		(start 14.389862 -413.424116)
		(end 14.389862 -414.277302)
		(width 0.12954)
		(layer "F.Cu")
		(net "TCA9539_0_ADD1")
	)
	(segment
		(start 14.054582 -413.088836)
		(end 14.389862 -413.424116)
		(width 0.12954)
		(layer "F.Cu")
		(net "TCA9539_0_ADD1")
	)
	(segment
		(start 14.054582 -412.453836)
		(end 14.054582 -413.088836)
		(width 0.12954)
		(layer "F.Cu")
		(net "TCA9539_0_ADD1")
	)
	(segment
		(start 13.800582 -411.202886)
		(end 14.054582 -411.456886)
		(width 0.12954)
		(layer "F.Cu")
		(net "TCA9539_0_ADD1")
	)
	(segment
		(start 14.435582 -409.532836)
		(end 13.819632 -408.916886)
		(width 0.12954)
		(layer "F.Cu")
		(net "TCA9539_0_ADD1")
	)
	(segment
		(start 14.435582 -410.567886)
		(end 14.435582 -409.532836)
		(width 0.12954)
		(layer "F.Cu")
		(net "TCA9539_0_ADD1")
	)
	(via
		(at 14.054582 -412.453836)
		(size 0.762)
		(drill 0.381)
		(layers "F.Cu" "B.Cu")
		(net "TCA9539_0_ADD1")
	)
	(segment
		(start 15.76705 -421.90162)
		(end 15.76705 -420.976044)
		(width 0.12954)
		(layer "F.Cu")
		(net "TCA9539_0_ADD0")
	)
	(segment
		(start 13.661136 -425.35475)
		(end 13.6398 -425.35475)
		(width 0.12954)
		(layer "F.Cu")
		(net "TCA9539_0_ADD0")
	)
	(segment
		(start 14.999716 -423.229786)
		(end 15.76705 -422.462452)
		(width 0.12954)
		(layer "F.Cu")
		(net "TCA9539_0_ADD0")
	)
	(segment
		(start 14.025626 -424.99026)
		(end 13.661136 -425.35475)
		(width 0.12954)
		(layer "F.Cu")
		(net "TCA9539_0_ADD0")
	)
	(segment
		(start 14.413992 -423.229786)
		(end 14.025626 -423.618152)
		(width 0.12954)
		(layer "F.Cu")
		(net "TCA9539_0_ADD0")
	)
	(segment
		(start 14.689582 -423.229786)
		(end 14.413992 -423.229786)
		(width 0.12954)
		(layer "F.Cu")
		(net "TCA9539_0_ADD0")
	)
	(segment
		(start 15.76705 -422.462452)
		(end 15.76705 -421.90162)
		(width 0.12954)
		(layer "F.Cu")
		(net "TCA9539_0_ADD0")
	)
	(segment
		(start 14.689582 -423.229786)
		(end 14.999716 -423.229786)
		(width 0.12954)
		(layer "F.Cu")
		(net "TCA9539_0_ADD0")
	)
	(segment
		(start 15.76705 -420.976044)
		(end 15.689834 -420.898828)
		(width 0.12954)
		(layer "F.Cu")
		(net "TCA9539_0_ADD0")
	)
	(segment
		(start 15.689834 -420.898828)
		(end 15.689834 -420.12743)
		(width 0.12954)
		(layer "F.Cu")
		(net "TCA9539_0_ADD0")
	)
	(segment
		(start 14.025626 -423.618152)
		(end 14.025626 -424.99026)
		(width 0.12954)
		(layer "F.Cu")
		(net "TCA9539_0_ADD0")
	)
	(via
		(at 15.76705 -421.90162)
		(size 0.762)
		(drill 0.381)
		(layers "F.Cu" "B.Cu")
		(net "TCA9539_0_ADD0")
	)
	(segment
		(start 116.13388 -406.21077)
		(end 116.13388 -405.00173)
		(width 0.12954)
		(layer "F.Cu")
		(net "BIC_MONITER_N")
	)
	(segment
		(start 116.13388 -405.00173)
		(end 116.13388 -403.75078)
		(width 0.12954)
		(layer "F.Cu")
		(net "BIC_MONITER_N")
	)
	(segment
		(start 116.783866 -406.21077)
		(end 116.13388 -406.21077)
		(width 0.12954)
		(layer "F.Cu")
		(net "BIC_MONITER_N")
	)
	(via
		(at 116.13388 -405.00173)
		(size 0.762)
		(drill 0.381)
		(layers "F.Cu" "B.Cu")
		(net "BIC_MONITER_N")
	)
	(segment
		(start 117.85346 -409.113228)
		(end 118.449852 -409.113228)
		(width 0.12954)
		(layer "F.Cu")
		(net "BIC_MONITER_ISO")
	)
	(segment
		(start 118.449852 -410.129228)
		(end 118.449852 -409.113228)
		(width 0.12954)
		(layer "F.Cu")
		(net "BIC_MONITER_ISO")
	)
	(segment
		(start 115.483894 -408.11069)
		(end 115.483894 -408.74569)
		(width 0.12954)
		(layer "F.Cu")
		(net "BIC_MONITER_ISO")
	)
	(segment
		(start 117.48008 -409.486608)
		(end 117.85346 -409.113228)
		(width 0.12954)
		(layer "F.Cu")
		(net "BIC_MONITER_ISO")
	)
	(segment
		(start 116.224812 -409.486608)
		(end 117.48008 -409.486608)
		(width 0.12954)
		(layer "F.Cu")
		(net "BIC_MONITER_ISO")
	)
	(segment
		(start 115.483894 -408.74569)
		(end 116.224812 -409.486608)
		(width 0.12954)
		(layer "F.Cu")
		(net "BIC_MONITER_ISO")
	)
	(segment
		(start 160.43783 -104.485948)
		(end 159.82188 -104.485948)
		(width 0.12954)
		(layer "F.Cu")
		(net "BIC_MONITER_ISO")
	)
	(via
		(at 159.82188 -104.485948)
		(size 0.508)
		(drill 0.254)
		(layers "F.Cu" "B.Cu")
		(net "BIC_MONITER_ISO")
	)
	(via
		(at 45.90796 -111.140748)
		(size 0.508)
		(drill 0.254)
		(layers "F.Cu" "B.Cu")
		(net "BIC_MONITER_ISO")
	)
	(via
		(at 9.77138 -173.512988)
		(size 0.508)
		(drill 0.254)
		(layers "F.Cu" "B.Cu")
		(net "BIC_MONITER_ISO")
	)
	(via
		(at 115.483894 -408.74569)
		(size 0.508)
		(drill 0.254)
		(layers "F.Cu" "B.Cu")
		(net "BIC_MONITER_ISO")
	)
	(segment
		(start 115.14074 -399.852388)
		(end 115.14074 -398.993868)
		(width 0.127)
		(layer "In6.Cu")
		(net "BIC_MONITER_ISO")
	)
	(segment
		(start 101.254306 -394.350748)
		(end 58.07329 -394.350748)
		(width 0.127)
		(layer "In6.Cu")
		(net "BIC_MONITER_ISO")
	)
	(segment
		(start 13.27912 -326.050148)
		(end 8.33628 -321.107308)
		(width 0.127)
		(layer "In6.Cu")
		(net "BIC_MONITER_ISO")
	)
	(segment
		(start 113.26114 -401.731988)
		(end 115.14074 -399.852388)
		(width 0.127)
		(layer "In6.Cu")
		(net "BIC_MONITER_ISO")
	)
	(segment
		(start 32.31388 -331.936344)
		(end 26.427684 -326.050148)
		(width 0.127)
		(layer "In6.Cu")
		(net "BIC_MONITER_ISO")
	)
	(segment
		(start 113.26114 -406.522936)
		(end 113.26114 -401.731988)
		(width 0.127)
		(layer "In6.Cu")
		(net "BIC_MONITER_ISO")
	)
	(segment
		(start 115.70208 -397.271748)
		(end 111.84128 -393.410948)
		(width 0.127)
		(layer "In6.Cu")
		(net "BIC_MONITER_ISO")
	)
	(segment
		(start 30.56128 -338.782152)
		(end 32.31388 -337.029552)
		(width 0.127)
		(layer "In6.Cu")
		(net "BIC_MONITER_ISO")
	)
	(segment
		(start 115.483894 -408.74569)
		(end 113.26114 -406.522936)
		(width 0.127)
		(layer "In6.Cu")
		(net "BIC_MONITER_ISO")
	)
	(segment
		(start 7.857744 -174.242984)
		(end 8.58774 -173.512988)
		(width 0.127)
		(layer "In6.Cu")
		(net "BIC_MONITER_ISO")
	)
	(segment
		(start 4.544314 -177.144934)
		(end 7.446264 -174.242984)
		(width 0.127)
		(layer "In6.Cu")
		(net "BIC_MONITER_ISO")
	)
	(segment
		(start 115.14074 -398.993868)
		(end 115.70208 -398.432528)
		(width 0.127)
		(layer "In6.Cu")
		(net "BIC_MONITER_ISO")
	)
	(segment
		(start 115.70208 -398.432528)
		(end 115.70208 -397.271748)
		(width 0.127)
		(layer "In6.Cu")
		(net "BIC_MONITER_ISO")
	)
	(segment
		(start 102.473506 -393.131548)
		(end 101.254306 -394.350748)
		(width 0.127)
		(layer "In6.Cu")
		(net "BIC_MONITER_ISO")
	)
	(segment
		(start 108.088938 -393.131548)
		(end 102.473506 -393.131548)
		(width 0.127)
		(layer "In6.Cu")
		(net "BIC_MONITER_ISO")
	)
	(segment
		(start 32.31388 -337.029552)
		(end 32.31388 -331.936344)
		(width 0.127)
		(layer "In6.Cu")
		(net "BIC_MONITER_ISO")
	)
	(segment
		(start 30.56128 -366.838738)
		(end 30.56128 -338.782152)
		(width 0.127)
		(layer "In6.Cu")
		(net "BIC_MONITER_ISO")
	)
	(segment
		(start 4.544314 -253.901702)
		(end 4.544314 -177.144934)
		(width 0.127)
		(layer "In6.Cu")
		(net "BIC_MONITER_ISO")
	)
	(segment
		(start 108.368338 -393.410948)
		(end 108.088938 -393.131548)
		(width 0.127)
		(layer "In6.Cu")
		(net "BIC_MONITER_ISO")
	)
	(segment
		(start 26.427684 -326.050148)
		(end 13.27912 -326.050148)
		(width 0.127)
		(layer "In6.Cu")
		(net "BIC_MONITER_ISO")
	)
	(segment
		(start 111.84128 -393.410948)
		(end 108.368338 -393.410948)
		(width 0.127)
		(layer "In6.Cu")
		(net "BIC_MONITER_ISO")
	)
	(segment
		(start 8.33628 -321.107308)
		(end 8.33628 -257.693668)
		(width 0.127)
		(layer "In6.Cu")
		(net "BIC_MONITER_ISO")
	)
	(segment
		(start 8.33628 -257.693668)
		(end 4.544314 -253.901702)
		(width 0.127)
		(layer "In6.Cu")
		(net "BIC_MONITER_ISO")
	)
	(segment
		(start 8.58774 -173.512988)
		(end 9.77138 -173.512988)
		(width 0.127)
		(layer "In6.Cu")
		(net "BIC_MONITER_ISO")
	)
	(segment
		(start 58.07329 -394.350748)
		(end 30.56128 -366.838738)
		(width 0.127)
		(layer "In6.Cu")
		(net "BIC_MONITER_ISO")
	)
	(segment
		(start 7.446264 -174.242984)
		(end 7.857744 -174.242984)
		(width 0.127)
		(layer "In6.Cu")
		(net "BIC_MONITER_ISO")
	)
	(segment
		(start 158.08198 -104.016048)
		(end 157.73908 -104.358948)
		(width 0.127)
		(layer "In13.Cu")
		(net "BIC_MONITER_ISO")
	)
	(segment
		(start 157.73908 -104.358948)
		(end 157.73908 -105.298748)
		(width 0.127)
		(layer "In13.Cu")
		(net "BIC_MONITER_ISO")
	)
	(segment
		(start 76.476606 -110.081568)
		(end 66.585846 -110.081568)
		(width 0.127)
		(layer "In13.Cu")
		(net "BIC_MONITER_ISO")
	)
	(segment
		(start 118.8847 -105.933748)
		(end 101.249226 -105.933748)
		(width 0.127)
		(layer "In13.Cu")
		(net "BIC_MONITER_ISO")
	)
	(segment
		(start 159.32658 -104.016048)
		(end 158.08198 -104.016048)
		(width 0.127)
		(layer "In13.Cu")
		(net "BIC_MONITER_ISO")
	)
	(segment
		(start 122.070114 -106.042968)
		(end 121.343674 -105.316528)
		(width 0.127)
		(layer "In13.Cu")
		(net "BIC_MONITER_ISO")
	)
	(segment
		(start 151.408892 -108.864908)
		(end 150.18004 -108.864908)
		(width 0.127)
		(layer "In13.Cu")
		(net "BIC_MONITER_ISO")
	)
	(segment
		(start 159.79648 -104.485948)
		(end 159.32658 -104.016048)
		(width 0.127)
		(layer "In13.Cu")
		(net "BIC_MONITER_ISO")
	)
	(segment
		(start 79.496666 -107.061508)
		(end 76.476606 -110.081568)
		(width 0.127)
		(layer "In13.Cu")
		(net "BIC_MONITER_ISO")
	)
	(segment
		(start 159.82188 -104.485948)
		(end 159.79648 -104.485948)
		(width 0.127)
		(layer "In13.Cu")
		(net "BIC_MONITER_ISO")
	)
	(segment
		(start 154.46248 -108.575348)
		(end 151.698452 -108.575348)
		(width 0.127)
		(layer "In13.Cu")
		(net "BIC_MONITER_ISO")
	)
	(segment
		(start 147.27428 -105.959148)
		(end 126.684786 -105.959148)
		(width 0.127)
		(layer "In13.Cu")
		(net "BIC_MONITER_ISO")
	)
	(segment
		(start 126.600966 -106.042968)
		(end 122.070114 -106.042968)
		(width 0.127)
		(layer "In13.Cu")
		(net "BIC_MONITER_ISO")
	)
	(segment
		(start 55.795926 -110.767876)
		(end 52.204112 -110.767876)
		(width 0.127)
		(layer "In13.Cu")
		(net "BIC_MONITER_ISO")
	)
	(segment
		(start 49.81448 -111.140748)
		(end 45.90796 -111.140748)
		(width 0.127)
		(layer "In13.Cu")
		(net "BIC_MONITER_ISO")
	)
	(segment
		(start 64.919606 -111.747808)
		(end 56.775858 -111.747808)
		(width 0.127)
		(layer "In13.Cu")
		(net "BIC_MONITER_ISO")
	)
	(segment
		(start 51.5239 -111.448088)
		(end 50.12182 -111.448088)
		(width 0.127)
		(layer "In13.Cu")
		(net "BIC_MONITER_ISO")
	)
	(segment
		(start 100.121466 -107.061508)
		(end 79.496666 -107.061508)
		(width 0.127)
		(layer "In13.Cu")
		(net "BIC_MONITER_ISO")
	)
	(segment
		(start 150.18004 -108.864908)
		(end 147.27428 -105.959148)
		(width 0.127)
		(layer "In13.Cu")
		(net "BIC_MONITER_ISO")
	)
	(segment
		(start 119.50192 -105.316528)
		(end 118.8847 -105.933748)
		(width 0.127)
		(layer "In13.Cu")
		(net "BIC_MONITER_ISO")
	)
	(segment
		(start 56.775858 -111.747808)
		(end 55.795926 -110.767876)
		(width 0.127)
		(layer "In13.Cu")
		(net "BIC_MONITER_ISO")
	)
	(segment
		(start 126.684786 -105.959148)
		(end 126.600966 -106.042968)
		(width 0.127)
		(layer "In13.Cu")
		(net "BIC_MONITER_ISO")
	)
	(segment
		(start 121.343674 -105.316528)
		(end 119.50192 -105.316528)
		(width 0.127)
		(layer "In13.Cu")
		(net "BIC_MONITER_ISO")
	)
	(segment
		(start 157.73908 -105.298748)
		(end 154.46248 -108.575348)
		(width 0.127)
		(layer "In13.Cu")
		(net "BIC_MONITER_ISO")
	)
	(segment
		(start 151.698452 -108.575348)
		(end 151.408892 -108.864908)
		(width 0.127)
		(layer "In13.Cu")
		(net "BIC_MONITER_ISO")
	)
	(segment
		(start 66.585846 -110.081568)
		(end 64.919606 -111.747808)
		(width 0.127)
		(layer "In13.Cu")
		(net "BIC_MONITER_ISO")
	)
	(segment
		(start 52.204112 -110.767876)
		(end 51.5239 -111.448088)
		(width 0.127)
		(layer "In13.Cu")
		(net "BIC_MONITER_ISO")
	)
	(segment
		(start 101.249226 -105.933748)
		(end 100.121466 -107.061508)
		(width 0.127)
		(layer "In13.Cu")
		(net "BIC_MONITER_ISO")
	)
	(segment
		(start 50.12182 -111.448088)
		(end 49.81448 -111.140748)
		(width 0.127)
		(layer "In13.Cu")
		(net "BIC_MONITER_ISO")
	)
	(segment
		(start 10.63752 -173.512988)
		(end 9.77138 -173.512988)
		(width 0.127)
		(layer "In15.Cu")
		(net "BIC_MONITER_ISO")
	)
	(segment
		(start 16.18488 -167.965628)
		(end 10.63752 -173.512988)
		(width 0.127)
		(layer "In15.Cu")
		(net "BIC_MONITER_ISO")
	)
	(segment
		(start 40.9194 -114.965988)
		(end 29.31541 -114.965988)
		(width 0.127)
		(layer "In15.Cu")
		(net "BIC_MONITER_ISO")
	)
	(segment
		(start 44.74464 -111.140748)
		(end 40.9194 -114.965988)
		(width 0.127)
		(layer "In15.Cu")
		(net "BIC_MONITER_ISO")
	)
	(segment
		(start 45.90796 -111.140748)
		(end 44.74464 -111.140748)
		(width 0.127)
		(layer "In15.Cu")
		(net "BIC_MONITER_ISO")
	)
	(segment
		(start 29.31541 -114.965988)
		(end 16.18488 -128.096518)
		(width 0.127)
		(layer "In15.Cu")
		(net "BIC_MONITER_ISO")
	)
	(segment
		(start 16.18488 -128.096518)
		(end 16.18488 -167.965628)
		(width 0.127)
		(layer "In15.Cu")
		(net "BIC_MONITER_ISO")
	)
	(segment
		(start 180.006244 -408.203908)
		(end 179.49037 -408.203908)
		(width 0.12954)
		(layer "F.Cu")
		(net "SMB_SML1_PMBUS_HSC_SDA")
	)
	(segment
		(start 180.133244 -408.330908)
		(end 180.006244 -408.203908)
		(width 0.12954)
		(layer "F.Cu")
		(net "SMB_SML1_PMBUS_HSC_SDA")
	)
	(segment
		(start 180.133244 -409.735782)
		(end 180.133244 -408.330908)
		(width 0.12954)
		(layer "F.Cu")
		(net "SMB_SML1_PMBUS_HSC_SDA")
	)
	(segment
		(start 180.049678 -409.819348)
		(end 180.133244 -409.735782)
		(width 0.12954)
		(layer "F.Cu")
		(net "SMB_SML1_PMBUS_HSC_SDA")
	)
	(via
		(at 180.049678 -409.819348)
		(size 0.508)
		(drill 0.254)
		(layers "F.Cu" "B.Cu")
		(net "SMB_SML1_PMBUS_HSC_SDA")
	)
	(segment
		(start 180.133244 -408.913838)
		(end 179.87645 -408.657044)
		(width 0.12954)
		(layer "B.Cu")
		(net "SMB_SML1_PMBUS_HSC_SDA")
	)
	(segment
		(start 180.921406 -408.657044)
		(end 180.923692 -408.654758)
		(width 0.12954)
		(layer "B.Cu")
		(net "SMB_SML1_PMBUS_HSC_SDA")
	)
	(segment
		(start 179.87645 -408.657044)
		(end 180.921406 -408.657044)
		(width 0.12954)
		(layer "B.Cu")
		(net "SMB_SML1_PMBUS_HSC_SDA")
	)
	(segment
		(start 180.049678 -409.819348)
		(end 180.133244 -409.735782)
		(width 0.12954)
		(layer "B.Cu")
		(net "SMB_SML1_PMBUS_HSC_SDA")
	)
	(segment
		(start 180.133244 -409.735782)
		(end 180.133244 -408.913838)
		(width 0.12954)
		(layer "B.Cu")
		(net "SMB_SML1_PMBUS_HSC_SDA")
	)
	(segment
		(start 179.49037 -409.450032)
		(end 179.49037 -409.199588)
		(width 0.12954)
		(layer "F.Cu")
		(net "SMB_SML1_PMBUS_HSC_SCL")
	)
	(segment
		(start 179.350162 -409.59024)
		(end 179.49037 -409.450032)
		(width 0.12954)
		(layer "F.Cu")
		(net "SMB_SML1_PMBUS_HSC_SCL")
	)
	(segment
		(start 179.350162 -410.745178)
		(end 179.350162 -409.59024)
		(width 0.12954)
		(layer "F.Cu")
		(net "SMB_SML1_PMBUS_HSC_SCL")
	)
	(via
		(at 179.350162 -410.745178)
		(size 0.508)
		(drill 0.254)
		(layers "F.Cu" "B.Cu")
		(net "SMB_SML1_PMBUS_HSC_SCL")
	)
	(segment
		(start 181.3052 -409.56738)
		(end 181.444392 -409.428188)
		(width 0.12954)
		(layer "B.Cu")
		(net "SMB_SML1_PMBUS_HSC_SCL")
	)
	(segment
		(start 182.908448 -408.256232)
		(end 182.712106 -408.256232)
		(width 0.12954)
		(layer "B.Cu")
		(net "SMB_SML1_PMBUS_HSC_SCL")
	)
	(segment
		(start 182.712106 -408.256232)
		(end 181.915308 -407.459434)
		(width 0.12954)
		(layer "B.Cu")
		(net "SMB_SML1_PMBUS_HSC_SCL")
	)
	(segment
		(start 181.3052 -410.45003)
		(end 181.3052 -409.56738)
		(width 0.12954)
		(layer "B.Cu")
		(net "SMB_SML1_PMBUS_HSC_SCL")
	)
	(segment
		(start 179.517294 -410.578046)
		(end 181.177184 -410.578046)
		(width 0.12954)
		(layer "B.Cu")
		(net "SMB_SML1_PMBUS_HSC_SCL")
	)
	(segment
		(start 181.444392 -407.93035)
		(end 181.915308 -407.459434)
		(width 0.12954)
		(layer "B.Cu")
		(net "SMB_SML1_PMBUS_HSC_SCL")
	)
	(segment
		(start 179.350162 -410.745178)
		(end 179.517294 -410.578046)
		(width 0.12954)
		(layer "B.Cu")
		(net "SMB_SML1_PMBUS_HSC_SCL")
	)
	(segment
		(start 181.444392 -409.428188)
		(end 181.444392 -407.93035)
		(width 0.12954)
		(layer "B.Cu")
		(net "SMB_SML1_PMBUS_HSC_SCL")
	)
	(segment
		(start 181.177184 -410.578046)
		(end 181.3052 -410.45003)
		(width 0.12954)
		(layer "B.Cu")
		(net "SMB_SML1_PMBUS_HSC_SCL")
	)
	(segment
		(start 181.80685 -406.152096)
		(end 182.264304 -405.694642)
		(width 0.12954)
		(layer "F.Cu")
		(net "SMB_SML1_PMBUS_HSC_R_SDA")
	)
	(segment
		(start 183.664098 -405.129492)
		(end 183.664098 -404.95982)
		(width 0.12954)
		(layer "F.Cu")
		(net "SMB_SML1_PMBUS_HSC_R_SDA")
	)
	(segment
		(start 183.098948 -405.694642)
		(end 183.664098 -405.129492)
		(width 0.12954)
		(layer "F.Cu")
		(net "SMB_SML1_PMBUS_HSC_R_SDA")
	)
	(segment
		(start 182.264304 -405.694642)
		(end 183.098948 -405.694642)
		(width 0.12954)
		(layer "F.Cu")
		(net "SMB_SML1_PMBUS_HSC_R_SDA")
	)
	(via
		(at 181.80685 -406.152096)
		(size 0.508)
		(drill 0.254)
		(layers "F.Cu" "B.Cu")
		(net "SMB_SML1_PMBUS_HSC_R_SDA")
	)
	(segment
		(start 180.923692 -407.60777)
		(end 181.80685 -406.724612)
		(width 0.12954)
		(layer "B.Cu")
		(net "SMB_SML1_PMBUS_HSC_R_SDA")
	)
	(segment
		(start 181.80685 -406.724612)
		(end 181.80685 -406.152096)
		(width 0.12954)
		(layer "B.Cu")
		(net "SMB_SML1_PMBUS_HSC_R_SDA")
	)
	(segment
		(start 180.923692 -407.854658)
		(end 180.923692 -407.60777)
		(width 0.12954)
		(layer "B.Cu")
		(net "SMB_SML1_PMBUS_HSC_R_SDA")
	)
	(segment
		(start 10.401554 -59.019948)
		(end 9.98093 -59.019948)
		(width 0.12954)
		(layer "F.Cu")
		(net "SMB_SML0_ME_SDA")
	)
	(segment
		(start 15.774924 -58.999882)
		(end 11.86688 -58.999882)
		(width 0.12954)
		(layer "F.Cu")
		(net "SMB_SML0_ME_SDA")
	)
	(segment
		(start 10.42162 -58.999882)
		(end 10.401554 -59.019948)
		(width 0.12954)
		(layer "F.Cu")
		(net "SMB_SML0_ME_SDA")
	)
	(segment
		(start 11.86688 -58.999882)
		(end 10.42162 -58.999882)
		(width 0.12954)
		(layer "F.Cu")
		(net "SMB_SML0_ME_SDA")
	)
	(via
		(at 11.86688 -58.999882)
		(size 0.762)
		(drill 0.381)
		(layers "F.Cu" "B.Cu")
		(net "SMB_SML0_ME_SDA")
	)
	(segment
		(start 10.453624 -60.999878)
		(end 10.401554 -61.051948)
		(width 0.12954)
		(layer "F.Cu")
		(net "SMB_SML0_ME_SCL")
	)
	(segment
		(start 10.401554 -61.051948)
		(end 9.98093 -61.051948)
		(width 0.12954)
		(layer "F.Cu")
		(net "SMB_SML0_ME_SCL")
	)
	(segment
		(start 11.775186 -60.999878)
		(end 10.453624 -60.999878)
		(width 0.12954)
		(layer "F.Cu")
		(net "SMB_SML0_ME_SCL")
	)
	(segment
		(start 15.774924 -60.999878)
		(end 11.775186 -60.999878)
		(width 0.12954)
		(layer "F.Cu")
		(net "SMB_SML0_ME_SCL")
	)
	(via
		(at 11.775186 -60.999878)
		(size 0.762)
		(drill 0.381)
		(layers "F.Cu" "B.Cu")
		(net "SMB_SML0_ME_SCL")
	)
	(segment
		(start 372.410228 -388.351268)
		(end 373.1006 -389.04164)
		(width 0.12954)
		(layer "F.Cu")
		(net "I3C_BMC_SWB_R_SDA")
	)
	(segment
		(start 372.232682 -391.641584)
		(end 372.103142 -391.771124)
		(width 0.12954)
		(layer "F.Cu")
		(net "I3C_BMC_SWB_R_SDA")
	)
	(segment
		(start 371.69344 -393.226544)
		(end 371.69344 -393.630404)
		(width 0.12954)
		(layer "F.Cu")
		(net "I3C_BMC_SWB_R_SDA")
	)
	(segment
		(start 372.103142 -393.097004)
		(end 371.82298 -393.097004)
		(width 0.12954)
		(layer "F.Cu")
		(net "I3C_BMC_SWB_R_SDA")
	)
	(segment
		(start 372.695724 -387.882384)
		(end 372.410228 -388.16788)
		(width 0.12954)
		(layer "F.Cu")
		(net "I3C_BMC_SWB_R_SDA")
	)
	(segment
		(start 367.876582 -397.265398)
		(end 368.892582 -396.249398)
		(width 0.12954)
		(layer "F.Cu")
		(net "I3C_BMC_SWB_R_SDA")
	)
	(segment
		(start 367.272316 -397.634714)
		(end 365.788448 -397.634714)
		(width 0.12954)
		(layer "F.Cu")
		(net "I3C_BMC_SWB_R_SDA")
	)
	(segment
		(start 370.839492 -396.842488)
		(end 369.485672 -396.842488)
		(width 0.12954)
		(layer "F.Cu")
		(net "I3C_BMC_SWB_R_SDA")
	)
	(segment
		(start 372.232682 -392.563604)
		(end 372.232682 -392.967464)
		(width 0.12954)
		(layer "F.Cu")
		(net "I3C_BMC_SWB_R_SDA")
	)
	(segment
		(start 372.232682 -395.449298)
		(end 371.432582 -396.249398)
		(width 0.12954)
		(layer "F.Cu")
		(net "I3C_BMC_SWB_R_SDA")
	)
	(segment
		(start 367.641632 -397.265398)
		(end 367.876582 -397.265398)
		(width 0.12954)
		(layer "F.Cu")
		(net "I3C_BMC_SWB_R_SDA")
	)
	(segment
		(start 372.410228 -388.16788)
		(end 372.410228 -388.351268)
		(width 0.12954)
		(layer "F.Cu")
		(net "I3C_BMC_SWB_R_SDA")
	)
	(segment
		(start 372.232682 -392.967464)
		(end 372.103142 -393.097004)
		(width 0.12954)
		(layer "F.Cu")
		(net "I3C_BMC_SWB_R_SDA")
	)
	(segment
		(start 371.69344 -393.630404)
		(end 371.82298 -393.759944)
		(width 0.12954)
		(layer "F.Cu")
		(net "I3C_BMC_SWB_R_SDA")
	)
	(segment
		(start 374.507252 -387.634988)
		(end 373.81688 -386.944616)
		(width 0.12954)
		(layer "F.Cu")
		(net "I3C_BMC_SWB_R_SDA")
	)
	(segment
		(start 374.69064 -387.634988)
		(end 374.507252 -387.634988)
		(width 0.12954)
		(layer "F.Cu")
		(net "I3C_BMC_SWB_R_SDA")
	)
	(segment
		(start 371.82298 -393.097004)
		(end 371.69344 -393.226544)
		(width 0.12954)
		(layer "F.Cu")
		(net "I3C_BMC_SWB_R_SDA")
	)
	(segment
		(start 372.103142 -391.771124)
		(end 371.82298 -391.771124)
		(width 0.12954)
		(layer "F.Cu")
		(net "I3C_BMC_SWB_R_SDA")
	)
	(segment
		(start 373.569484 -388.572756)
		(end 372.879112 -387.882384)
		(width 0.12954)
		(layer "F.Cu")
		(net "I3C_BMC_SWB_R_SDA")
	)
	(segment
		(start 371.69344 -392.304524)
		(end 371.82298 -392.434064)
		(width 0.12954)
		(layer "F.Cu")
		(net "I3C_BMC_SWB_R_SDA")
	)
	(segment
		(start 375.49328 -386.832348)
		(end 374.69064 -387.634988)
		(width 0.12954)
		(layer "F.Cu")
		(net "I3C_BMC_SWB_R_SDA")
	)
	(segment
		(start 374.038368 -388.103872)
		(end 374.038368 -388.28726)
		(width 0.12954)
		(layer "F.Cu")
		(net "I3C_BMC_SWB_R_SDA")
	)
	(segment
		(start 372.232682 -393.889484)
		(end 372.232682 -395.449298)
		(width 0.12954)
		(layer "F.Cu")
		(net "I3C_BMC_SWB_R_SDA")
	)
	(segment
		(start 373.1006 -389.225028)
		(end 372.232682 -390.092946)
		(width 0.12954)
		(layer "F.Cu")
		(net "I3C_BMC_SWB_R_SDA")
	)
	(segment
		(start 373.347996 -387.4135)
		(end 374.038368 -388.103872)
		(width 0.12954)
		(layer "F.Cu")
		(net "I3C_BMC_SWB_R_SDA")
	)
	(segment
		(start 372.103142 -392.434064)
		(end 372.232682 -392.563604)
		(width 0.12954)
		(layer "F.Cu")
		(net "I3C_BMC_SWB_R_SDA")
	)
	(segment
		(start 371.82298 -392.434064)
		(end 372.103142 -392.434064)
		(width 0.12954)
		(layer "F.Cu")
		(net "I3C_BMC_SWB_R_SDA")
	)
	(segment
		(start 373.81688 -386.944616)
		(end 373.633492 -386.944616)
		(width 0.12954)
		(layer "F.Cu")
		(net "I3C_BMC_SWB_R_SDA")
	)
	(segment
		(start 373.347996 -387.230112)
		(end 373.347996 -387.4135)
		(width 0.12954)
		(layer "F.Cu")
		(net "I3C_BMC_SWB_R_SDA")
	)
	(segment
		(start 371.432582 -396.249398)
		(end 370.839492 -396.842488)
		(width 0.12954)
		(layer "F.Cu")
		(net "I3C_BMC_SWB_R_SDA")
	)
	(segment
		(start 371.69344 -391.900664)
		(end 371.69344 -392.304524)
		(width 0.12954)
		(layer "F.Cu")
		(net "I3C_BMC_SWB_R_SDA")
	)
	(segment
		(start 373.1006 -389.04164)
		(end 373.1006 -389.225028)
		(width 0.12954)
		(layer "F.Cu")
		(net "I3C_BMC_SWB_R_SDA")
	)
	(segment
		(start 374.038368 -388.28726)
		(end 373.752872 -388.572756)
		(width 0.12954)
		(layer "F.Cu")
		(net "I3C_BMC_SWB_R_SDA")
	)
	(segment
		(start 369.485672 -396.842488)
		(end 368.892582 -396.249398)
		(width 0.12954)
		(layer "F.Cu")
		(net "I3C_BMC_SWB_R_SDA")
	)
	(segment
		(start 367.641632 -397.265398)
		(end 367.272316 -397.634714)
		(width 0.12954)
		(layer "F.Cu")
		(net "I3C_BMC_SWB_R_SDA")
	)
	(segment
		(start 372.232682 -390.092946)
		(end 372.232682 -391.641584)
		(width 0.12954)
		(layer "F.Cu")
		(net "I3C_BMC_SWB_R_SDA")
	)
	(segment
		(start 371.82298 -391.771124)
		(end 371.69344 -391.900664)
		(width 0.12954)
		(layer "F.Cu")
		(net "I3C_BMC_SWB_R_SDA")
	)
	(segment
		(start 371.82298 -393.759944)
		(end 372.103142 -393.759944)
		(width 0.12954)
		(layer "F.Cu")
		(net "I3C_BMC_SWB_R_SDA")
	)
	(segment
		(start 372.103142 -393.759944)
		(end 372.232682 -393.889484)
		(width 0.12954)
		(layer "F.Cu")
		(net "I3C_BMC_SWB_R_SDA")
	)
	(segment
		(start 373.752872 -388.572756)
		(end 373.569484 -388.572756)
		(width 0.12954)
		(layer "F.Cu")
		(net "I3C_BMC_SWB_R_SDA")
	)
	(segment
		(start 373.633492 -386.944616)
		(end 373.347996 -387.230112)
		(width 0.12954)
		(layer "F.Cu")
		(net "I3C_BMC_SWB_R_SDA")
	)
	(segment
		(start 372.879112 -387.882384)
		(end 372.695724 -387.882384)
		(width 0.12954)
		(layer "F.Cu")
		(net "I3C_BMC_SWB_R_SDA")
	)
	(via
		(at 375.49328 -386.832348)
		(size 0.508)
		(drill 0.254)
		(layers "F.Cu" "B.Cu")
		(net "I3C_BMC_SWB_R_SDA")
	)
	(via
		(at 436.95874 -48.578008)
		(size 0.508)
		(drill 0.254)
		(layers "F.Cu" "B.Cu")
		(net "I3C_BMC_SWB_R_SDA")
	)
	(via
		(at 448.57924 -136.916668)
		(size 0.508)
		(drill 0.254)
		(layers "F.Cu" "B.Cu")
		(net "I3C_BMC_SWB_R_SDA")
	)
	(via
		(at 367.641632 -397.265398)
		(size 0.762)
		(drill 0.381)
		(layers "F.Cu" "B.Cu")
		(net "I3C_BMC_SWB_R_SDA")
	)
	(via
		(at 172.7708 -9.921748)
		(size 0.508)
		(drill 0.254)
		(layers "F.Cu" "B.Cu")
		(net "I3C_BMC_SWB_R_SDA")
	)
	(segment
		(start 172.7708 -9.921748)
		(end 171.946062 -9.09701)
		(width 0.12954)
		(layer "B.Cu")
		(net "I3C_BMC_SWB_R_SDA")
	)
	(segment
		(start 171.946062 -9.09701)
		(end 171.946062 -8.907018)
		(width 0.12954)
		(layer "B.Cu")
		(net "I3C_BMC_SWB_R_SDA")
	)
	(segment
		(start 424.84802 -111.3028)
		(end 428.36338 -114.81816)
		(width 0.127)
		(layer "In2.Cu")
		(net "I3C_BMC_SWB_R_SDA")
	)
	(segment
		(start 436.81396 -58.20156)
		(end 433.00904 -62.00648)
		(width 0.127)
		(layer "In2.Cu")
		(net "I3C_BMC_SWB_R_SDA")
	)
	(segment
		(start 436.95874 -48.578008)
		(end 436.81396 -48.722788)
		(width 0.127)
		(layer "In2.Cu")
		(net "I3C_BMC_SWB_R_SDA")
	)
	(segment
		(start 426.77842 -85.24748)
		(end 426.77842 -105.142792)
		(width 0.127)
		(layer "In2.Cu")
		(net "I3C_BMC_SWB_R_SDA")
	)
	(segment
		(start 433.00904 -62.00648)
		(end 433.00904 -79.01686)
		(width 0.127)
		(layer "In2.Cu")
		(net "I3C_BMC_SWB_R_SDA")
	)
	(segment
		(start 438.63514 -114.81816)
		(end 448.57924 -124.76226)
		(width 0.127)
		(layer "In2.Cu")
		(net "I3C_BMC_SWB_R_SDA")
	)
	(segment
		(start 433.00904 -79.01686)
		(end 426.77842 -85.24748)
		(width 0.127)
		(layer "In2.Cu")
		(net "I3C_BMC_SWB_R_SDA")
	)
	(segment
		(start 436.81396 -48.722788)
		(end 436.81396 -58.20156)
		(width 0.127)
		(layer "In2.Cu")
		(net "I3C_BMC_SWB_R_SDA")
	)
	(segment
		(start 428.36338 -114.81816)
		(end 438.63514 -114.81816)
		(width 0.127)
		(layer "In2.Cu")
		(net "I3C_BMC_SWB_R_SDA")
	)
	(segment
		(start 424.84802 -107.073192)
		(end 424.84802 -111.3028)
		(width 0.127)
		(layer "In2.Cu")
		(net "I3C_BMC_SWB_R_SDA")
	)
	(segment
		(start 426.77842 -105.142792)
		(end 424.84802 -107.073192)
		(width 0.127)
		(layer "In2.Cu")
		(net "I3C_BMC_SWB_R_SDA")
	)
	(segment
		(start 448.57924 -124.76226)
		(end 448.57924 -136.916668)
		(width 0.127)
		(layer "In2.Cu")
		(net "I3C_BMC_SWB_R_SDA")
	)
	(segment
		(start 377.34494 -385.321048)
		(end 377.47194 -385.448048)
		(width 0.127)
		(layer "In6.Cu")
		(net "I3C_BMC_SWB_R_SDA")
	)
	(segment
		(start 408.468068 -383.37744)
		(end 427.007528 -383.37744)
		(width 0.127)
		(layer "In6.Cu")
		(net "I3C_BMC_SWB_R_SDA")
	)
	(segment
		(start 465.814664 -334.576928)
		(end 466.78596 -332.232)
		(width 0.127)
		(layer "In6.Cu")
		(net "I3C_BMC_SWB_R_SDA")
	)
	(segment
		(start 375.62282 -386.702808)
		(end 376.70994 -386.702808)
		(width 0.127)
		(layer "In6.Cu")
		(net "I3C_BMC_SWB_R_SDA")
	)
	(segment
		(start 377.47194 -386.575808)
		(end 377.59894 -386.702808)
		(width 0.127)
		(layer "In6.Cu")
		(net "I3C_BMC_SWB_R_SDA")
	)
	(segment
		(start 437.104282 -371.441726)
		(end 437.104282 -363.28731)
		(width 0.127)
		(layer "In6.Cu")
		(net "I3C_BMC_SWB_R_SDA")
	)
	(segment
		(start 427.007528 -383.37744)
		(end 428.19828 -382.186688)
		(width 0.127)
		(layer "In6.Cu")
		(net "I3C_BMC_SWB_R_SDA")
	)
	(segment
		(start 376.96394 -385.321048)
		(end 377.34494 -385.321048)
		(width 0.127)
		(layer "In6.Cu")
		(net "I3C_BMC_SWB_R_SDA")
	)
	(segment
		(start 466.78596 -332.232)
		(end 466.78596 -178.319938)
		(width 0.127)
		(layer "In6.Cu")
		(net "I3C_BMC_SWB_R_SDA")
	)
	(segment
		(start 377.59894 -386.702808)
		(end 405.1427 -386.702808)
		(width 0.127)
		(layer "In6.Cu")
		(net "I3C_BMC_SWB_R_SDA")
	)
	(segment
		(start 376.83694 -385.448048)
		(end 376.96394 -385.321048)
		(width 0.127)
		(layer "In6.Cu")
		(net "I3C_BMC_SWB_R_SDA")
	)
	(segment
		(start 448.57924 -139.174728)
		(end 448.57924 -136.916668)
		(width 0.127)
		(layer "In6.Cu")
		(net "I3C_BMC_SWB_R_SDA")
	)
	(segment
		(start 428.19828 -382.186688)
		(end 428.19828 -380.347728)
		(width 0.127)
		(layer "In6.Cu")
		(net "I3C_BMC_SWB_R_SDA")
	)
	(segment
		(start 376.70994 -386.702808)
		(end 376.83694 -386.575808)
		(width 0.127)
		(layer "In6.Cu")
		(net "I3C_BMC_SWB_R_SDA")
	)
	(segment
		(start 405.1427 -386.702808)
		(end 408.468068 -383.37744)
		(width 0.127)
		(layer "In6.Cu")
		(net "I3C_BMC_SWB_R_SDA")
	)
	(segment
		(start 375.49328 -386.832348)
		(end 375.62282 -386.702808)
		(width 0.127)
		(layer "In6.Cu")
		(net "I3C_BMC_SWB_R_SDA")
	)
	(segment
		(start 376.83694 -386.575808)
		(end 376.83694 -385.448048)
		(width 0.127)
		(layer "In6.Cu")
		(net "I3C_BMC_SWB_R_SDA")
	)
	(segment
		(start 437.104282 -363.28731)
		(end 465.814664 -334.576928)
		(width 0.127)
		(layer "In6.Cu")
		(net "I3C_BMC_SWB_R_SDA")
	)
	(segment
		(start 428.19828 -380.347728)
		(end 437.104282 -371.441726)
		(width 0.127)
		(layer "In6.Cu")
		(net "I3C_BMC_SWB_R_SDA")
	)
	(segment
		(start 450.12864 -140.724128)
		(end 448.57924 -139.174728)
		(width 0.127)
		(layer "In6.Cu")
		(net "I3C_BMC_SWB_R_SDA")
	)
	(segment
		(start 450.12864 -161.662618)
		(end 450.12864 -140.724128)
		(width 0.127)
		(layer "In6.Cu")
		(net "I3C_BMC_SWB_R_SDA")
	)
	(segment
		(start 377.47194 -385.448048)
		(end 377.47194 -386.575808)
		(width 0.127)
		(layer "In6.Cu")
		(net "I3C_BMC_SWB_R_SDA")
	)
	(segment
		(start 466.78596 -178.319938)
		(end 450.12864 -161.662618)
		(width 0.127)
		(layer "In6.Cu")
		(net "I3C_BMC_SWB_R_SDA")
	)
	(segment
		(start 174.1424 -13.180568)
		(end 174.1424 -13.000228)
		(width 0.127)
		(layer "In15.Cu")
		(net "I3C_BMC_SWB_R_SDA")
	)
	(segment
		(start 173.9265 -12.784328)
		(end 173.9265 -11.834368)
		(width 0.127)
		(layer "In15.Cu")
		(net "I3C_BMC_SWB_R_SDA")
	)
	(segment
		(start 212.318346 -37.65296)
		(end 211.064094 -36.398708)
		(width 0.127)
		(layer "In15.Cu")
		(net "I3C_BMC_SWB_R_SDA")
	)
	(segment
		(start 243.93144 -44.699428)
		(end 242.734592 -43.50258)
		(width 0.127)
		(layer "In15.Cu")
		(net "I3C_BMC_SWB_R_SDA")
	)
	(segment
		(start 255.561592 -46.00448)
		(end 254.25654 -44.699428)
		(width 0.127)
		(layer "In15.Cu")
		(net "I3C_BMC_SWB_R_SDA")
	)
	(segment
		(start 308.40426 -18.20926)
		(end 303.490122 -18.20926)
		(width 0.127)
		(layer "In15.Cu")
		(net "I3C_BMC_SWB_R_SDA")
	)
	(segment
		(start 179.26304 -16.332454)
		(end 180.45684 -15.138654)
		(width 0.127)
		(layer "In15.Cu")
		(net "I3C_BMC_SWB_R_SDA")
	)
	(segment
		(start 330.95946 -16.66494)
		(end 330.57592 -16.2814)
		(width 0.127)
		(layer "In15.Cu")
		(net "I3C_BMC_SWB_R_SDA")
	)
	(segment
		(start 211.064094 -36.398708)
		(end 208.494122 -36.398708)
		(width 0.127)
		(layer "In15.Cu")
		(net "I3C_BMC_SWB_R_SDA")
	)
	(segment
		(start 371.394736 -34.346388)
		(end 353.713288 -16.66494)
		(width 0.127)
		(layer "In15.Cu")
		(net "I3C_BMC_SWB_R_SDA")
	)
	(segment
		(start 196.47662 -34.74974)
		(end 195.0593 -36.16706)
		(width 0.127)
		(layer "In15.Cu")
		(net "I3C_BMC_SWB_R_SDA")
	)
	(segment
		(start 179.26304 -20.467066)
		(end 179.26304 -16.332454)
		(width 0.127)
		(layer "In15.Cu")
		(net "I3C_BMC_SWB_R_SDA")
	)
	(segment
		(start 174.1424 -13.000228)
		(end 173.9265 -12.784328)
		(width 0.127)
		(layer "In15.Cu")
		(net "I3C_BMC_SWB_R_SDA")
	)
	(segment
		(start 179.605686 -13.734288)
		(end 174.69612 -13.734288)
		(width 0.127)
		(layer "In15.Cu")
		(net "I3C_BMC_SWB_R_SDA")
	)
	(segment
		(start 430.23028 -27.36088)
		(end 402.34108 -27.36088)
		(width 0.127)
		(layer "In15.Cu")
		(net "I3C_BMC_SWB_R_SDA")
	)
	(segment
		(start 303.490122 -18.20926)
		(end 298.038266 -20.467574)
		(width 0.127)
		(layer "In15.Cu")
		(net "I3C_BMC_SWB_R_SDA")
	)
	(segment
		(start 173.31944 -11.359388)
		(end 172.7708 -10.810748)
		(width 0.127)
		(layer "In15.Cu")
		(net "I3C_BMC_SWB_R_SDA")
	)
	(segment
		(start 181.51602 -27.07894)
		(end 181.51602 -22.720046)
		(width 0.127)
		(layer "In15.Cu")
		(net "I3C_BMC_SWB_R_SDA")
	)
	(segment
		(start 254.25654 -44.699428)
		(end 243.93144 -44.699428)
		(width 0.127)
		(layer "In15.Cu")
		(net "I3C_BMC_SWB_R_SDA")
	)
	(segment
		(start 233.60888 -43.50258)
		(end 232.23982 -42.13352)
		(width 0.127)
		(layer "In15.Cu")
		(net "I3C_BMC_SWB_R_SDA")
	)
	(segment
		(start 195.0593 -36.16706)
		(end 190.60414 -36.16706)
		(width 0.127)
		(layer "In15.Cu")
		(net "I3C_BMC_SWB_R_SDA")
	)
	(segment
		(start 172.7708 -10.810748)
		(end 172.7708 -9.921748)
		(width 0.127)
		(layer "In15.Cu")
		(net "I3C_BMC_SWB_R_SDA")
	)
	(segment
		(start 298.038266 -20.467574)
		(end 273.51482 -44.99102)
		(width 0.127)
		(layer "In15.Cu")
		(net "I3C_BMC_SWB_R_SDA")
	)
	(segment
		(start 180.45684 -15.138654)
		(end 180.45684 -14.585442)
		(width 0.127)
		(layer "In15.Cu")
		(net "I3C_BMC_SWB_R_SDA")
	)
	(segment
		(start 273.51482 -44.99102)
		(end 263.827768 -44.99102)
		(width 0.127)
		(layer "In15.Cu")
		(net "I3C_BMC_SWB_R_SDA")
	)
	(segment
		(start 173.45152 -11.359388)
		(end 173.31944 -11.359388)
		(width 0.127)
		(layer "In15.Cu")
		(net "I3C_BMC_SWB_R_SDA")
	)
	(segment
		(start 263.827768 -44.99102)
		(end 262.814308 -46.00448)
		(width 0.127)
		(layer "In15.Cu")
		(net "I3C_BMC_SWB_R_SDA")
	)
	(segment
		(start 395.355572 -34.346388)
		(end 371.394736 -34.346388)
		(width 0.127)
		(layer "In15.Cu")
		(net "I3C_BMC_SWB_R_SDA")
	)
	(segment
		(start 242.734592 -43.50258)
		(end 233.60888 -43.50258)
		(width 0.127)
		(layer "In15.Cu")
		(net "I3C_BMC_SWB_R_SDA")
	)
	(segment
		(start 232.23982 -42.13352)
		(end 224.413826 -42.13352)
		(width 0.127)
		(layer "In15.Cu")
		(net "I3C_BMC_SWB_R_SDA")
	)
	(segment
		(start 174.69612 -13.734288)
		(end 174.1424 -13.180568)
		(width 0.127)
		(layer "In15.Cu")
		(net "I3C_BMC_SWB_R_SDA")
	)
	(segment
		(start 206.845154 -34.74974)
		(end 196.47662 -34.74974)
		(width 0.127)
		(layer "In15.Cu")
		(net "I3C_BMC_SWB_R_SDA")
	)
	(segment
		(start 431.48758 -43.106848)
		(end 431.48758 -28.61818)
		(width 0.127)
		(layer "In15.Cu")
		(net "I3C_BMC_SWB_R_SDA")
	)
	(segment
		(start 353.713288 -16.66494)
		(end 330.95946 -16.66494)
		(width 0.127)
		(layer "In15.Cu")
		(net "I3C_BMC_SWB_R_SDA")
	)
	(segment
		(start 208.494122 -36.398708)
		(end 206.845154 -34.74974)
		(width 0.127)
		(layer "In15.Cu")
		(net "I3C_BMC_SWB_R_SDA")
	)
	(segment
		(start 224.413826 -42.13352)
		(end 219.933266 -37.65296)
		(width 0.127)
		(layer "In15.Cu")
		(net "I3C_BMC_SWB_R_SDA")
	)
	(segment
		(start 402.34108 -27.36088)
		(end 395.355572 -34.346388)
		(width 0.127)
		(layer "In15.Cu")
		(net "I3C_BMC_SWB_R_SDA")
	)
	(segment
		(start 181.51602 -22.720046)
		(end 179.26304 -20.467066)
		(width 0.127)
		(layer "In15.Cu")
		(net "I3C_BMC_SWB_R_SDA")
	)
	(segment
		(start 431.48758 -28.61818)
		(end 430.23028 -27.36088)
		(width 0.127)
		(layer "In15.Cu")
		(net "I3C_BMC_SWB_R_SDA")
	)
	(segment
		(start 180.45684 -14.585442)
		(end 179.605686 -13.734288)
		(width 0.127)
		(layer "In15.Cu")
		(net "I3C_BMC_SWB_R_SDA")
	)
	(segment
		(start 436.95874 -48.578008)
		(end 431.48758 -43.106848)
		(width 0.127)
		(layer "In15.Cu")
		(net "I3C_BMC_SWB_R_SDA")
	)
	(segment
		(start 190.60414 -36.16706)
		(end 181.51602 -27.07894)
		(width 0.127)
		(layer "In15.Cu")
		(net "I3C_BMC_SWB_R_SDA")
	)
	(segment
		(start 330.57592 -16.2814)
		(end 310.33212 -16.2814)
		(width 0.127)
		(layer "In15.Cu")
		(net "I3C_BMC_SWB_R_SDA")
	)
	(segment
		(start 173.9265 -11.834368)
		(end 173.45152 -11.359388)
		(width 0.127)
		(layer "In15.Cu")
		(net "I3C_BMC_SWB_R_SDA")
	)
	(segment
		(start 262.814308 -46.00448)
		(end 255.561592 -46.00448)
		(width 0.127)
		(layer "In15.Cu")
		(net "I3C_BMC_SWB_R_SDA")
	)
	(segment
		(start 219.933266 -37.65296)
		(end 212.318346 -37.65296)
		(width 0.127)
		(layer "In15.Cu")
		(net "I3C_BMC_SWB_R_SDA")
	)
	(segment
		(start 310.33212 -16.2814)
		(end 308.40426 -18.20926)
		(width 0.127)
		(layer "In15.Cu")
		(net "I3C_BMC_SWB_R_SDA")
	)
	(segment
		(start 376.20448 -387.391148)
		(end 372.91518 -390.680448)
		(width 0.12954)
		(layer "F.Cu")
		(net "I3C_BMC_SWB_R_SCL")
	)
	(segment
		(start 361.323636 -397.634714)
		(end 361.38485 -397.695928)
		(width 0.12954)
		(layer "F.Cu")
		(net "I3C_BMC_SWB_R_SCL")
	)
	(segment
		(start 361.38485 -397.695928)
		(end 362.46562 -397.695928)
		(width 0.12954)
		(layer "F.Cu")
		(net "I3C_BMC_SWB_R_SCL")
	)
	(segment
		(start 370.654072 -398.297908)
		(end 369.671092 -398.297908)
		(width 0.12954)
		(layer "F.Cu")
		(net "I3C_BMC_SWB_R_SCL")
	)
	(segment
		(start 364.509812 -399.74012)
		(end 367.01222 -399.74012)
		(width 0.12954)
		(layer "F.Cu")
		(net "I3C_BMC_SWB_R_SCL")
	)
	(segment
		(start 367.641632 -398.535398)
		(end 368.657632 -397.519398)
		(width 0.12954)
		(layer "F.Cu")
		(net "I3C_BMC_SWB_R_SCL")
	)
	(segment
		(start 362.46562 -397.695928)
		(end 364.509812 -399.74012)
		(width 0.12954)
		(layer "F.Cu")
		(net "I3C_BMC_SWB_R_SCL")
	)
	(segment
		(start 376.63882 -387.391148)
		(end 376.20448 -387.391148)
		(width 0.12954)
		(layer "F.Cu")
		(net "I3C_BMC_SWB_R_SCL")
	)
	(segment
		(start 369.671092 -398.297908)
		(end 368.892582 -397.519398)
		(width 0.12954)
		(layer "F.Cu")
		(net "I3C_BMC_SWB_R_SCL")
	)
	(segment
		(start 367.49736 -399.25498)
		(end 367.49736 -398.67967)
		(width 0.12954)
		(layer "F.Cu")
		(net "I3C_BMC_SWB_R_SCL")
	)
	(segment
		(start 371.432582 -397.519398)
		(end 370.654072 -398.297908)
		(width 0.12954)
		(layer "F.Cu")
		(net "I3C_BMC_SWB_R_SCL")
	)
	(segment
		(start 372.91518 -396.0368)
		(end 371.432582 -397.519398)
		(width 0.12954)
		(layer "F.Cu")
		(net "I3C_BMC_SWB_R_SCL")
	)
	(segment
		(start 372.91518 -390.680448)
		(end 372.91518 -396.0368)
		(width 0.12954)
		(layer "F.Cu")
		(net "I3C_BMC_SWB_R_SCL")
	)
	(segment
		(start 367.01222 -399.74012)
		(end 367.49736 -399.25498)
		(width 0.12954)
		(layer "F.Cu")
		(net "I3C_BMC_SWB_R_SCL")
	)
	(segment
		(start 368.657632 -397.519398)
		(end 368.892582 -397.519398)
		(width 0.12954)
		(layer "F.Cu")
		(net "I3C_BMC_SWB_R_SCL")
	)
	(segment
		(start 367.49736 -398.67967)
		(end 367.641632 -398.535398)
		(width 0.12954)
		(layer "F.Cu")
		(net "I3C_BMC_SWB_R_SCL")
	)
	(via
		(at 449.21424 -136.916668)
		(size 0.508)
		(drill 0.254)
		(layers "F.Cu" "B.Cu")
		(net "I3C_BMC_SWB_R_SCL")
	)
	(via
		(at 367.641632 -398.535398)
		(size 0.762)
		(drill 0.381)
		(layers "F.Cu" "B.Cu")
		(net "I3C_BMC_SWB_R_SCL")
	)
	(via
		(at 175.24476 -9.893808)
		(size 0.508)
		(drill 0.254)
		(layers "F.Cu" "B.Cu")
		(net "I3C_BMC_SWB_R_SCL")
	)
	(via
		(at 376.63882 -387.391148)
		(size 0.508)
		(drill 0.254)
		(layers "F.Cu" "B.Cu")
		(net "I3C_BMC_SWB_R_SCL")
	)
	(via
		(at 437.407812 -48.128682)
		(size 0.508)
		(drill 0.254)
		(layers "F.Cu" "B.Cu")
		(net "I3C_BMC_SWB_R_SCL")
	)
	(segment
		(start 175.24476 -9.58596)
		(end 174.563278 -8.904478)
		(width 0.12954)
		(layer "B.Cu")
		(net "I3C_BMC_SWB_R_SCL")
	)
	(segment
		(start 175.24476 -9.893808)
		(end 175.24476 -9.58596)
		(width 0.12954)
		(layer "B.Cu")
		(net "I3C_BMC_SWB_R_SCL")
	)
	(segment
		(start 433.65039 -62.485524)
		(end 433.65039 -79.410306)
		(width 0.127)
		(layer "In2.Cu")
		(net "I3C_BMC_SWB_R_SCL")
	)
	(segment
		(start 433.65039 -79.410306)
		(end 427.482 -85.578696)
		(width 0.127)
		(layer "In2.Cu")
		(net "I3C_BMC_SWB_R_SCL")
	)
	(segment
		(start 428.735744 -114.163348)
		(end 438.893712 -114.163348)
		(width 0.127)
		(layer "In2.Cu")
		(net "I3C_BMC_SWB_R_SCL")
	)
	(segment
		(start 427.482 -85.578696)
		(end 427.482 -105.40746)
		(width 0.127)
		(layer "In2.Cu")
		(net "I3C_BMC_SWB_R_SCL")
	)
	(segment
		(start 427.482 -105.40746)
		(end 425.53636 -107.3531)
		(width 0.127)
		(layer "In2.Cu")
		(net "I3C_BMC_SWB_R_SCL")
	)
	(segment
		(start 425.53636 -110.963964)
		(end 428.735744 -114.163348)
		(width 0.127)
		(layer "In2.Cu")
		(net "I3C_BMC_SWB_R_SCL")
	)
	(segment
		(start 437.52516 -48.246284)
		(end 437.53532 -48.256444)
		(width 0.127)
		(layer "In2.Cu")
		(net "I3C_BMC_SWB_R_SCL")
	)
	(segment
		(start 437.53532 -58.378344)
		(end 437.52516 -58.388504)
		(width 0.127)
		(layer "In2.Cu")
		(net "I3C_BMC_SWB_R_SCL")
	)
	(segment
		(start 437.407812 -48.128682)
		(end 437.52516 -48.24603)
		(width 0.127)
		(layer "In2.Cu")
		(net "I3C_BMC_SWB_R_SCL")
	)
	(segment
		(start 437.52516 -58.388504)
		(end 437.52516 -58.610754)
		(width 0.127)
		(layer "In2.Cu")
		(net "I3C_BMC_SWB_R_SCL")
	)
	(segment
		(start 438.893712 -114.163348)
		(end 449.21424 -124.483876)
		(width 0.127)
		(layer "In2.Cu")
		(net "I3C_BMC_SWB_R_SCL")
	)
	(segment
		(start 437.52516 -48.24603)
		(end 437.52516 -48.246284)
		(width 0.127)
		(layer "In2.Cu")
		(net "I3C_BMC_SWB_R_SCL")
	)
	(segment
		(start 437.53532 -48.256444)
		(end 437.53532 -58.378344)
		(width 0.127)
		(layer "In2.Cu")
		(net "I3C_BMC_SWB_R_SCL")
	)
	(segment
		(start 425.53636 -107.3531)
		(end 425.53636 -110.963964)
		(width 0.127)
		(layer "In2.Cu")
		(net "I3C_BMC_SWB_R_SCL")
	)
	(segment
		(start 437.52516 -58.610754)
		(end 433.65039 -62.485524)
		(width 0.127)
		(layer "In2.Cu")
		(net "I3C_BMC_SWB_R_SCL")
	)
	(segment
		(start 449.21424 -124.483876)
		(end 449.21424 -136.916668)
		(width 0.127)
		(layer "In2.Cu")
		(net "I3C_BMC_SWB_R_SCL")
	)
	(segment
		(start 426.6438 -384.86588)
		(end 407.992834 -384.86588)
		(width 0.127)
		(layer "In6.Cu")
		(net "I3C_BMC_SWB_R_SCL")
	)
	(segment
		(start 407.992834 -384.86588)
		(end 405.249634 -387.60908)
		(width 0.127)
		(layer "In6.Cu")
		(net "I3C_BMC_SWB_R_SCL")
	)
	(segment
		(start 453.14616 -140.848588)
		(end 453.14616 -155.29052)
		(width 0.127)
		(layer "In6.Cu")
		(net "I3C_BMC_SWB_R_SCL")
	)
	(segment
		(start 449.21424 -136.916668)
		(end 453.14616 -140.848588)
		(width 0.127)
		(layer "In6.Cu")
		(net "I3C_BMC_SWB_R_SCL")
	)
	(segment
		(start 428.9171 -382.59258)
		(end 426.6438 -384.86588)
		(width 0.127)
		(layer "In6.Cu")
		(net "I3C_BMC_SWB_R_SCL")
	)
	(segment
		(start 428.9171 -380.611126)
		(end 428.9171 -382.59258)
		(width 0.127)
		(layer "In6.Cu")
		(net "I3C_BMC_SWB_R_SCL")
	)
	(segment
		(start 405.249634 -387.60908)
		(end 376.856752 -387.60908)
		(width 0.127)
		(layer "In6.Cu")
		(net "I3C_BMC_SWB_R_SCL")
	)
	(segment
		(start 453.14616 -155.29052)
		(end 452.84136 -155.59532)
		(width 0.127)
		(layer "In6.Cu")
		(net "I3C_BMC_SWB_R_SCL")
	)
	(segment
		(start 376.856752 -387.60908)
		(end 376.63882 -387.391148)
		(width 0.127)
		(layer "In6.Cu")
		(net "I3C_BMC_SWB_R_SCL")
	)
	(segment
		(start 437.74106 -363.550454)
		(end 437.74106 -371.787166)
		(width 0.127)
		(layer "In6.Cu")
		(net "I3C_BMC_SWB_R_SCL")
	)
	(segment
		(start 467.42858 -332.349602)
		(end 466.358478 -334.933036)
		(width 0.127)
		(layer "In6.Cu")
		(net "I3C_BMC_SWB_R_SCL")
	)
	(segment
		(start 452.84136 -155.59532)
		(end 452.84136 -163.337748)
		(width 0.127)
		(layer "In6.Cu")
		(net "I3C_BMC_SWB_R_SCL")
	)
	(segment
		(start 452.84136 -163.337748)
		(end 467.42858 -177.924968)
		(width 0.127)
		(layer "In6.Cu")
		(net "I3C_BMC_SWB_R_SCL")
	)
	(segment
		(start 466.358478 -334.933036)
		(end 437.74106 -363.550454)
		(width 0.127)
		(layer "In6.Cu")
		(net "I3C_BMC_SWB_R_SCL")
	)
	(segment
		(start 467.42858 -177.924968)
		(end 467.42858 -332.349602)
		(width 0.127)
		(layer "In6.Cu")
		(net "I3C_BMC_SWB_R_SCL")
	)
	(segment
		(start 437.74106 -371.787166)
		(end 428.9171 -380.611126)
		(width 0.127)
		(layer "In6.Cu")
		(net "I3C_BMC_SWB_R_SCL")
	)
	(segment
		(start 437.407812 -48.128682)
		(end 432.15814 -42.87901)
		(width 0.127)
		(layer "In15.Cu")
		(net "I3C_BMC_SWB_R_SCL")
	)
	(segment
		(start 207.761332 -34.7218)
		(end 207.10144 -34.061908)
		(width 0.127)
		(layer "In15.Cu")
		(net "I3C_BMC_SWB_R_SCL")
	)
	(segment
		(start 210.385152 -34.7218)
		(end 207.761332 -34.7218)
		(width 0.127)
		(layer "In15.Cu")
		(net "I3C_BMC_SWB_R_SCL")
	)
	(segment
		(start 273.30781 -44.287948)
		(end 263.534652 -44.287948)
		(width 0.127)
		(layer "In15.Cu")
		(net "I3C_BMC_SWB_R_SCL")
	)
	(segment
		(start 220.2942 -36.949888)
		(end 212.61324 -36.949888)
		(width 0.127)
		(layer "In15.Cu")
		(net "I3C_BMC_SWB_R_SCL")
	)
	(segment
		(start 233.926634 -42.86758)
		(end 232.512362 -41.453308)
		(width 0.127)
		(layer "In15.Cu")
		(net "I3C_BMC_SWB_R_SCL")
	)
	(segment
		(start 181.10962 -15.41272)
		(end 181.10962 -14.23924)
		(width 0.127)
		(layer "In15.Cu")
		(net "I3C_BMC_SWB_R_SCL")
	)
	(segment
		(start 194.388994 -34.51606)
		(end 189.897258 -34.51606)
		(width 0.127)
		(layer "In15.Cu")
		(net "I3C_BMC_SWB_R_SCL")
	)
	(segment
		(start 179.91328 -16.60906)
		(end 181.10962 -15.41272)
		(width 0.127)
		(layer "In15.Cu")
		(net "I3C_BMC_SWB_R_SCL")
	)
	(segment
		(start 182.19166 -26.810462)
		(end 182.19166 -22.390608)
		(width 0.127)
		(layer "In15.Cu")
		(net "I3C_BMC_SWB_R_SCL")
	)
	(segment
		(start 395.046454 -33.64484)
		(end 371.629178 -33.64484)
		(width 0.127)
		(layer "In15.Cu")
		(net "I3C_BMC_SWB_R_SCL")
	)
	(segment
		(start 181.10962 -14.23924)
		(end 179.92598 -13.0556)
		(width 0.127)
		(layer "In15.Cu")
		(net "I3C_BMC_SWB_R_SCL")
	)
	(segment
		(start 297.803062 -19.792696)
		(end 273.30781 -44.287948)
		(width 0.127)
		(layer "In15.Cu")
		(net "I3C_BMC_SWB_R_SCL")
	)
	(segment
		(start 194.843146 -34.061908)
		(end 194.388994 -34.51606)
		(width 0.127)
		(layer "In15.Cu")
		(net "I3C_BMC_SWB_R_SCL")
	)
	(segment
		(start 330.777088 -15.575788)
		(end 310.060594 -15.575788)
		(width 0.127)
		(layer "In15.Cu")
		(net "I3C_BMC_SWB_R_SCL")
	)
	(segment
		(start 182.19166 -22.390608)
		(end 179.91328 -20.112228)
		(width 0.127)
		(layer "In15.Cu")
		(net "I3C_BMC_SWB_R_SCL")
	)
	(segment
		(start 432.15814 -28.363418)
		(end 430.50079 -26.706068)
		(width 0.127)
		(layer "In15.Cu")
		(net "I3C_BMC_SWB_R_SCL")
	)
	(segment
		(start 189.897258 -34.51606)
		(end 182.19166 -26.810462)
		(width 0.127)
		(layer "In15.Cu")
		(net "I3C_BMC_SWB_R_SCL")
	)
	(segment
		(start 371.629178 -33.64484)
		(end 353.960938 -15.9766)
		(width 0.127)
		(layer "In15.Cu")
		(net "I3C_BMC_SWB_R_SCL")
	)
	(segment
		(start 430.50079 -26.706068)
		(end 401.985226 -26.706068)
		(width 0.127)
		(layer "In15.Cu")
		(net "I3C_BMC_SWB_R_SCL")
	)
	(segment
		(start 179.91328 -20.112228)
		(end 179.91328 -16.60906)
		(width 0.127)
		(layer "In15.Cu")
		(net "I3C_BMC_SWB_R_SCL")
	)
	(segment
		(start 331.1779 -15.9766)
		(end 330.777088 -15.575788)
		(width 0.127)
		(layer "In15.Cu")
		(net "I3C_BMC_SWB_R_SCL")
	)
	(segment
		(start 401.985226 -26.706068)
		(end 395.046454 -33.64484)
		(width 0.127)
		(layer "In15.Cu")
		(net "I3C_BMC_SWB_R_SCL")
	)
	(segment
		(start 262.518652 -45.303948)
		(end 256.313686 -45.303948)
		(width 0.127)
		(layer "In15.Cu")
		(net "I3C_BMC_SWB_R_SCL")
	)
	(segment
		(start 232.512362 -41.453308)
		(end 224.79762 -41.453308)
		(width 0.127)
		(layer "In15.Cu")
		(net "I3C_BMC_SWB_R_SCL")
	)
	(segment
		(start 212.61324 -36.949888)
		(end 210.385152 -34.7218)
		(width 0.127)
		(layer "In15.Cu")
		(net "I3C_BMC_SWB_R_SCL")
	)
	(segment
		(start 179.92598 -13.0556)
		(end 175.584612 -13.0556)
		(width 0.127)
		(layer "In15.Cu")
		(net "I3C_BMC_SWB_R_SCL")
	)
	(segment
		(start 251.40158 -42.931588)
		(end 250.70816 -43.625008)
		(width 0.127)
		(layer "In15.Cu")
		(net "I3C_BMC_SWB_R_SCL")
	)
	(segment
		(start 250.70816 -43.625008)
		(end 243.804694 -43.625008)
		(width 0.127)
		(layer "In15.Cu")
		(net "I3C_BMC_SWB_R_SCL")
	)
	(segment
		(start 310.060594 -15.575788)
		(end 308.084474 -17.551908)
		(width 0.127)
		(layer "In15.Cu")
		(net "I3C_BMC_SWB_R_SCL")
	)
	(segment
		(start 308.084474 -17.551908)
		(end 303.212754 -17.551908)
		(width 0.127)
		(layer "In15.Cu")
		(net "I3C_BMC_SWB_R_SCL")
	)
	(segment
		(start 175.24476 -12.715748)
		(end 175.24476 -9.893808)
		(width 0.127)
		(layer "In15.Cu")
		(net "I3C_BMC_SWB_R_SCL")
	)
	(segment
		(start 175.584612 -13.0556)
		(end 175.24476 -12.715748)
		(width 0.127)
		(layer "In15.Cu")
		(net "I3C_BMC_SWB_R_SCL")
	)
	(segment
		(start 252.479048 -42.931588)
		(end 251.40158 -42.931588)
		(width 0.127)
		(layer "In15.Cu")
		(net "I3C_BMC_SWB_R_SCL")
	)
	(segment
		(start 303.212754 -17.551908)
		(end 297.803062 -19.792696)
		(width 0.127)
		(layer "In15.Cu")
		(net "I3C_BMC_SWB_R_SCL")
	)
	(segment
		(start 263.534652 -44.287948)
		(end 262.518652 -45.303948)
		(width 0.127)
		(layer "In15.Cu")
		(net "I3C_BMC_SWB_R_SCL")
	)
	(segment
		(start 224.79762 -41.453308)
		(end 220.2942 -36.949888)
		(width 0.127)
		(layer "In15.Cu")
		(net "I3C_BMC_SWB_R_SCL")
	)
	(segment
		(start 207.10144 -34.061908)
		(end 194.843146 -34.061908)
		(width 0.127)
		(layer "In15.Cu")
		(net "I3C_BMC_SWB_R_SCL")
	)
	(segment
		(start 353.960938 -15.9766)
		(end 331.1779 -15.9766)
		(width 0.127)
		(layer "In15.Cu")
		(net "I3C_BMC_SWB_R_SCL")
	)
	(segment
		(start 243.804694 -43.625008)
		(end 243.047266 -42.86758)
		(width 0.127)
		(layer "In15.Cu")
		(net "I3C_BMC_SWB_R_SCL")
	)
	(segment
		(start 243.047266 -42.86758)
		(end 233.926634 -42.86758)
		(width 0.127)
		(layer "In15.Cu")
		(net "I3C_BMC_SWB_R_SCL")
	)
	(segment
		(start 254.97536 -43.965622)
		(end 252.479048 -42.931588)
		(width 0.127)
		(layer "In15.Cu")
		(net "I3C_BMC_SWB_R_SCL")
	)
	(segment
		(start 256.313686 -45.303948)
		(end 254.97536 -43.965622)
		(width 0.127)
		(layer "In15.Cu")
		(net "I3C_BMC_SWB_R_SCL")
	)
	(segment
		(start 432.15814 -42.87901)
		(end 432.15814 -28.363418)
		(width 0.127)
		(layer "In15.Cu")
		(net "I3C_BMC_SWB_R_SCL")
	)
	(segment
		(start 10.401554 -54.955948)
		(end 9.98093 -54.955948)
		(width 0.12954)
		(layer "F.Cu")
		(net "SMB_PMBUS_SML1_ME_SDA")
	)
	(segment
		(start 11.86688 -54.99989)
		(end 10.445496 -54.99989)
		(width 0.12954)
		(layer "F.Cu")
		(net "SMB_PMBUS_SML1_ME_SDA")
	)
	(segment
		(start 10.445496 -54.99989)
		(end 10.401554 -54.955948)
		(width 0.12954)
		(layer "F.Cu")
		(net "SMB_PMBUS_SML1_ME_SDA")
	)
	(segment
		(start 15.774924 -54.99989)
		(end 11.86688 -54.99989)
		(width 0.12954)
		(layer "F.Cu")
		(net "SMB_PMBUS_SML1_ME_SDA")
	)
	(via
		(at 11.86688 -54.99989)
		(size 0.762)
		(drill 0.381)
		(layers "F.Cu" "B.Cu")
		(net "SMB_PMBUS_SML1_ME_SDA")
	)
	(segment
		(start 10.795 -56.999886)
		(end 10.777982 -56.982868)
		(width 0.12954)
		(layer "F.Cu")
		(net "SMB_PMBUS_SML1_ME_SCL")
	)
	(segment
		(start 15.774924 -56.999886)
		(end 10.795 -56.999886)
		(width 0.12954)
		(layer "F.Cu")
		(net "SMB_PMBUS_SML1_ME_SCL")
	)
	(segment
		(start 10.777982 -56.982868)
		(end 9.98093 -56.982868)
		(width 0.12954)
		(layer "F.Cu")
		(net "SMB_PMBUS_SML1_ME_SCL")
	)
	(via
		(at 10.795 -56.999886)
		(size 0.508)
		(drill 0.254)
		(layers "F.Cu" "B.Cu")
		(net "SMB_PMBUS_SML1_ME_SCL")
	)
	(segment
		(start 48.996092 -434.090318)
		(end 49.78654 -434.090318)
		(width 0.12954)
		(layer "F.Cu")
		(net "SMB_1_BMC_GPU_R_SDA")
	)
	(segment
		(start 51.497484 -434.344318)
		(end 51.428904 -434.412898)
		(width 0.12954)
		(layer "F.Cu")
		(net "SMB_1_BMC_GPU_R_SDA")
	)
	(segment
		(start 50.703226 -434.090318)
		(end 50.98288 -434.369972)
		(width 0.12954)
		(layer "F.Cu")
		(net "SMB_1_BMC_GPU_R_SDA")
	)
	(segment
		(start 50.98288 -434.369972)
		(end 50.98288 -434.412898)
		(width 0.12954)
		(layer "F.Cu")
		(net "SMB_1_BMC_GPU_R_SDA")
	)
	(segment
		(start 48.686212 -434.400198)
		(end 48.996092 -434.090318)
		(width 0.12954)
		(layer "F.Cu")
		(net "SMB_1_BMC_GPU_R_SDA")
	)
	(segment
		(start 49.78654 -434.090318)
		(end 50.703226 -434.090318)
		(width 0.12954)
		(layer "F.Cu")
		(net "SMB_1_BMC_GPU_R_SDA")
	)
	(segment
		(start 51.686206 -434.304948)
		(end 51.646836 -434.344318)
		(width 0.12954)
		(layer "F.Cu")
		(net "SMB_1_BMC_GPU_R_SDA")
	)
	(segment
		(start 51.646836 -434.344318)
		(end 51.497484 -434.344318)
		(width 0.12954)
		(layer "F.Cu")
		(net "SMB_1_BMC_GPU_R_SDA")
	)
	(segment
		(start 51.428904 -434.412898)
		(end 50.98288 -434.412898)
		(width 0.12954)
		(layer "F.Cu")
		(net "SMB_1_BMC_GPU_R_SDA")
	)
	(segment
		(start 47.855378 -434.400198)
		(end 48.686212 -434.400198)
		(width 0.12954)
		(layer "F.Cu")
		(net "SMB_1_BMC_GPU_R_SDA")
	)
	(segment
		(start 52.10683 -434.304948)
		(end 51.686206 -434.304948)
		(width 0.12954)
		(layer "F.Cu")
		(net "SMB_1_BMC_GPU_R_SDA")
	)
	(via
		(at 49.78654 -434.090318)
		(size 0.508)
		(drill 0.254)
		(layers "F.Cu" "B.Cu")
		(net "SMB_1_BMC_GPU_R_SDA")
	)
	(segment
		(start 41.719246 -433.837588)
		(end 40.97274 -433.837588)
		(width 0.12954)
		(layer "F.Cu")
		(net "SMB_1_BMC_GPU_R_SCL")
	)
	(segment
		(start 40.268652 -433.837588)
		(end 40.161972 -433.944268)
		(width 0.12954)
		(layer "F.Cu")
		(net "SMB_1_BMC_GPU_R_SCL")
	)
	(segment
		(start 38.696646 -433.923948)
		(end 38.42893 -433.923948)
		(width 0.12954)
		(layer "F.Cu")
		(net "SMB_1_BMC_GPU_R_SCL")
	)
	(segment
		(start 40.161972 -433.944268)
		(end 39.602156 -433.384452)
		(width 0.12954)
		(layer "F.Cu")
		(net "SMB_1_BMC_GPU_R_SCL")
	)
	(segment
		(start 43.390566 -434.400198)
		(end 42.281856 -434.400198)
		(width 0.12954)
		(layer "F.Cu")
		(net "SMB_1_BMC_GPU_R_SCL")
	)
	(segment
		(start 39.602156 -433.384452)
		(end 39.236142 -433.384452)
		(width 0.12954)
		(layer "F.Cu")
		(net "SMB_1_BMC_GPU_R_SCL")
	)
	(segment
		(start 42.281856 -434.400198)
		(end 41.719246 -433.837588)
		(width 0.12954)
		(layer "F.Cu")
		(net "SMB_1_BMC_GPU_R_SCL")
	)
	(segment
		(start 40.97274 -433.837588)
		(end 40.268652 -433.837588)
		(width 0.12954)
		(layer "F.Cu")
		(net "SMB_1_BMC_GPU_R_SCL")
	)
	(segment
		(start 39.236142 -433.384452)
		(end 38.696646 -433.923948)
		(width 0.12954)
		(layer "F.Cu")
		(net "SMB_1_BMC_GPU_R_SCL")
	)
	(via
		(at 40.97274 -433.837588)
		(size 0.508)
		(drill 0.254)
		(layers "F.Cu" "B.Cu")
		(net "SMB_1_BMC_GPU_R_SCL")
	)
	(segment
		(start 35.014408 -438.549288)
		(end 35.014408 -439.302652)
		(width 0.12954)
		(layer "F.Cu")
		(net "SMB_2_BMC_GPU_R_SDA")
	)
	(segment
		(start 34.577782 -439.739278)
		(end 34.177478 -439.739278)
		(width 0.12954)
		(layer "F.Cu")
		(net "SMB_2_BMC_GPU_R_SDA")
	)
	(segment
		(start 35.014408 -439.302652)
		(end 34.577782 -439.739278)
		(width 0.12954)
		(layer "F.Cu")
		(net "SMB_2_BMC_GPU_R_SDA")
	)
	(segment
		(start 35.142932 -438.549288)
		(end 35.014408 -438.549288)
		(width 0.12954)
		(layer "F.Cu")
		(net "SMB_2_BMC_GPU_R_SDA")
	)
	(segment
		(start 36.800282 -439.523632)
		(end 36.117276 -439.523632)
		(width 0.12954)
		(layer "F.Cu")
		(net "SMB_2_BMC_GPU_R_SDA")
	)
	(segment
		(start 33.199578 -439.739278)
		(end 34.177478 -439.739278)
		(width 0.12954)
		(layer "F.Cu")
		(net "SMB_2_BMC_GPU_R_SDA")
	)
	(segment
		(start 36.117276 -439.523632)
		(end 35.142932 -438.549288)
		(width 0.12954)
		(layer "F.Cu")
		(net "SMB_2_BMC_GPU_R_SDA")
	)
	(segment
		(start 33.180528 -439.720228)
		(end 33.199578 -439.739278)
		(width 0.12954)
		(layer "F.Cu")
		(net "SMB_2_BMC_GPU_R_SDA")
	)
	(via
		(at 35.014408 -438.549288)
		(size 0.508)
		(drill 0.254)
		(layers "F.Cu" "B.Cu")
		(net "SMB_2_BMC_GPU_R_SDA")
	)
	(segment
		(start 46.206918 -440.224418)
		(end 44.467018 -440.224418)
		(width 0.12954)
		(layer "F.Cu")
		(net "SMB_2_BMC_GPU_R_SCL")
	)
	(segment
		(start 42.135044 -439.523632)
		(end 41.265094 -439.523632)
		(width 0.12954)
		(layer "F.Cu")
		(net "SMB_2_BMC_GPU_R_SCL")
	)
	(segment
		(start 44.467018 -440.224418)
		(end 43.123358 -438.880758)
		(width 0.12954)
		(layer "F.Cu")
		(net "SMB_2_BMC_GPU_R_SCL")
	)
	(segment
		(start 43.123358 -438.535318)
		(end 42.135044 -439.523632)
		(width 0.12954)
		(layer "F.Cu")
		(net "SMB_2_BMC_GPU_R_SCL")
	)
	(segment
		(start 43.123358 -438.880758)
		(end 43.123358 -438.535318)
		(width 0.12954)
		(layer "F.Cu")
		(net "SMB_2_BMC_GPU_R_SCL")
	)
	(segment
		(start 46.225968 -440.205368)
		(end 46.206918 -440.224418)
		(width 0.12954)
		(layer "F.Cu")
		(net "SMB_2_BMC_GPU_R_SCL")
	)
	(via
		(at 43.123358 -438.535318)
		(size 0.508)
		(drill 0.254)
		(layers "F.Cu" "B.Cu")
		(net "SMB_2_BMC_GPU_R_SCL")
	)
	(segment
		(start 10.472674 -48.986948)
		(end 10.05205 -48.986948)
		(width 0.12954)
		(layer "F.Cu")
		(net "SMB_HOST_ME_SDA")
	)
	(segment
		(start 15.774924 -48.999902)
		(end 11.86688 -48.999902)
		(width 0.12954)
		(layer "F.Cu")
		(net "SMB_HOST_ME_SDA")
	)
	(segment
		(start 11.86688 -48.999902)
		(end 10.485628 -48.999902)
		(width 0.12954)
		(layer "F.Cu")
		(net "SMB_HOST_ME_SDA")
	)
	(segment
		(start 10.485628 -48.999902)
		(end 10.472674 -48.986948)
		(width 0.12954)
		(layer "F.Cu")
		(net "SMB_HOST_ME_SDA")
	)
	(via
		(at 11.86688 -48.999902)
		(size 0.762)
		(drill 0.381)
		(layers "F.Cu" "B.Cu")
		(net "SMB_HOST_ME_SDA")
	)
	(segment
		(start 11.86688 -50.999898)
		(end 10.491724 -50.999898)
		(width 0.12954)
		(layer "F.Cu")
		(net "SMB_HOST_ME_SCL")
	)
	(segment
		(start 10.472674 -51.018948)
		(end 10.05205 -51.018948)
		(width 0.12954)
		(layer "F.Cu")
		(net "SMB_HOST_ME_SCL")
	)
	(segment
		(start 15.774924 -50.999898)
		(end 11.86688 -50.999898)
		(width 0.12954)
		(layer "F.Cu")
		(net "SMB_HOST_ME_SCL")
	)
	(segment
		(start 10.491724 -50.999898)
		(end 10.472674 -51.018948)
		(width 0.12954)
		(layer "F.Cu")
		(net "SMB_HOST_ME_SCL")
	)
	(via
		(at 11.86688 -50.999898)
		(size 0.762)
		(drill 0.381)
		(layers "F.Cu" "B.Cu")
		(net "SMB_HOST_ME_SCL")
	)
	(segment
		(start 178.44262 -416.456368)
		(end 178.44262 -417.063428)
		(width 0.12954)
		(layer "F.Cu")
		(net "SMB_FAN_3V3AUX_R_SDA")
	)
	(segment
		(start 179.15636 -416.197288)
		(end 179.02682 -416.326828)
		(width 0.12954)
		(layer "F.Cu")
		(net "SMB_FAN_3V3AUX_R_SDA")
	)
	(segment
		(start 173.22038 -412.36646)
		(end 174.26178 -413.40786)
		(width 0.12954)
		(layer "F.Cu")
		(net "SMB_FAN_3V3AUX_R_SDA")
	)
	(segment
		(start 178.57216 -417.192968)
		(end 179.02682 -417.192968)
		(width 0.12954)
		(layer "F.Cu")
		(net "SMB_FAN_3V3AUX_R_SDA")
	)
	(segment
		(start 179.15636 -417.867338)
		(end 178.744626 -418.279072)
		(width 0.12954)
		(layer "F.Cu")
		(net "SMB_FAN_3V3AUX_R_SDA")
	)
	(segment
		(start 178.3969 -413.40786)
		(end 179.15636 -414.16732)
		(width 0.12954)
		(layer "F.Cu")
		(net "SMB_FAN_3V3AUX_R_SDA")
	)
	(segment
		(start 179.15636 -414.16732)
		(end 179.15636 -416.197288)
		(width 0.12954)
		(layer "F.Cu")
		(net "SMB_FAN_3V3AUX_R_SDA")
	)
	(segment
		(start 171.45 -405.7142)
		(end 173.09338 -405.7142)
		(width 0.12954)
		(layer "F.Cu")
		(net "SMB_FAN_3V3AUX_R_SDA")
	)
	(segment
		(start 178.57216 -416.326828)
		(end 178.44262 -416.456368)
		(width 0.12954)
		(layer "F.Cu")
		(net "SMB_FAN_3V3AUX_R_SDA")
	)
	(segment
		(start 179.15636 -417.322508)
		(end 179.15636 -417.867338)
		(width 0.12954)
		(layer "F.Cu")
		(net "SMB_FAN_3V3AUX_R_SDA")
	)
	(segment
		(start 173.22038 -405.8412)
		(end 173.22038 -412.36646)
		(width 0.12954)
		(layer "F.Cu")
		(net "SMB_FAN_3V3AUX_R_SDA")
	)
	(segment
		(start 179.435506 -418.969952)
		(end 178.744626 -418.279072)
		(width 0.12954)
		(layer "F.Cu")
		(net "SMB_FAN_3V3AUX_R_SDA")
	)
	(segment
		(start 178.44262 -417.063428)
		(end 178.57216 -417.192968)
		(width 0.12954)
		(layer "F.Cu")
		(net "SMB_FAN_3V3AUX_R_SDA")
	)
	(segment
		(start 171.26966 -405.53386)
		(end 171.45 -405.7142)
		(width 0.12954)
		(layer "F.Cu")
		(net "SMB_FAN_3V3AUX_R_SDA")
	)
	(segment
		(start 179.02682 -416.326828)
		(end 178.57216 -416.326828)
		(width 0.12954)
		(layer "F.Cu")
		(net "SMB_FAN_3V3AUX_R_SDA")
	)
	(segment
		(start 179.435506 -419.496748)
		(end 179.435506 -418.969952)
		(width 0.12954)
		(layer "F.Cu")
		(net "SMB_FAN_3V3AUX_R_SDA")
	)
	(segment
		(start 179.02682 -417.192968)
		(end 179.15636 -417.322508)
		(width 0.12954)
		(layer "F.Cu")
		(net "SMB_FAN_3V3AUX_R_SDA")
	)
	(segment
		(start 172.434758 -397.966692)
		(end 171.26966 -399.13179)
		(width 0.12954)
		(layer "F.Cu")
		(net "SMB_FAN_3V3AUX_R_SDA")
	)
	(segment
		(start 173.09338 -405.7142)
		(end 173.22038 -405.8412)
		(width 0.12954)
		(layer "F.Cu")
		(net "SMB_FAN_3V3AUX_R_SDA")
	)
	(segment
		(start 174.26178 -413.40786)
		(end 178.3969 -413.40786)
		(width 0.12954)
		(layer "F.Cu")
		(net "SMB_FAN_3V3AUX_R_SDA")
	)
	(segment
		(start 171.26966 -399.13179)
		(end 171.26966 -405.53386)
		(width 0.12954)
		(layer "F.Cu")
		(net "SMB_FAN_3V3AUX_R_SDA")
	)
	(via
		(at 172.434758 -397.966692)
		(size 0.508)
		(drill 0.254)
		(layers "F.Cu" "B.Cu")
		(net "SMB_FAN_3V3AUX_R_SDA")
	)
	(via
		(at 178.744626 -418.279072)
		(size 0.508)
		(drill 0.254)
		(layers "F.Cu" "B.Cu")
		(net "SMB_FAN_3V3AUX_R_SDA")
	)
	(via
		(at 169.01414 -393.23772)
		(size 0.508)
		(drill 0.254)
		(layers "F.Cu" "B.Cu")
		(net "SMB_FAN_3V3AUX_R_SDA")
	)
	(via
		(at 158.056834 -11.374628)
		(size 0.508)
		(drill 0.254)
		(layers "F.Cu" "B.Cu")
		(net "SMB_FAN_3V3AUX_R_SDA")
	)
	(segment
		(start 169.826432 -393.778486)
		(end 169.428922 -393.778486)
		(width 0.12954)
		(layer "B.Cu")
		(net "SMB_FAN_3V3AUX_R_SDA")
	)
	(segment
		(start 171.96562 -397.839692)
		(end 171.96562 -395.917674)
		(width 0.12954)
		(layer "B.Cu")
		(net "SMB_FAN_3V3AUX_R_SDA")
	)
	(segment
		(start 172.434758 -397.966692)
		(end 172.09262 -397.966692)
		(width 0.12954)
		(layer "B.Cu")
		(net "SMB_FAN_3V3AUX_R_SDA")
	)
	(segment
		(start 172.09262 -397.966692)
		(end 171.96562 -397.839692)
		(width 0.12954)
		(layer "B.Cu")
		(net "SMB_FAN_3V3AUX_R_SDA")
	)
	(segment
		(start 158.056834 -11.374628)
		(end 157.532324 -10.850118)
		(width 0.12954)
		(layer "B.Cu")
		(net "SMB_FAN_3V3AUX_R_SDA")
	)
	(segment
		(start 171.96562 -395.917674)
		(end 169.826432 -393.778486)
		(width 0.12954)
		(layer "B.Cu")
		(net "SMB_FAN_3V3AUX_R_SDA")
	)
	(segment
		(start 169.428922 -393.778486)
		(end 169.01414 -393.363704)
		(width 0.12954)
		(layer "B.Cu")
		(net "SMB_FAN_3V3AUX_R_SDA")
	)
	(segment
		(start 179.106576 -417.917122)
		(end 179.106576 -417.030154)
		(width 0.12954)
		(layer "B.Cu")
		(net "SMB_FAN_3V3AUX_R_SDA")
	)
	(segment
		(start 178.744626 -418.279072)
		(end 179.106576 -417.917122)
		(width 0.12954)
		(layer "B.Cu")
		(net "SMB_FAN_3V3AUX_R_SDA")
	)
	(segment
		(start 157.532324 -10.850118)
		(end 157.24886 -10.850118)
		(width 0.12954)
		(layer "B.Cu")
		(net "SMB_FAN_3V3AUX_R_SDA")
	)
	(segment
		(start 169.01414 -393.363704)
		(end 169.01414 -393.23772)
		(width 0.12954)
		(layer "B.Cu")
		(net "SMB_FAN_3V3AUX_R_SDA")
	)
	(segment
		(start 199.873616 -82.133948)
		(end 206.098394 -88.358726)
		(width 0.127)
		(layer "In2.Cu")
		(net "SMB_FAN_3V3AUX_R_SDA")
	)
	(segment
		(start 161.72942 -18.087848)
		(end 161.72942 -19.388328)
		(width 0.127)
		(layer "In2.Cu")
		(net "SMB_FAN_3V3AUX_R_SDA")
	)
	(segment
		(start 217.22842 -131.740148)
		(end 217.22842 -137.33018)
		(width 0.127)
		(layer "In2.Cu")
		(net "SMB_FAN_3V3AUX_R_SDA")
	)
	(segment
		(start 190.04788 -366.564672)
		(end 169.01414 -387.598412)
		(width 0.127)
		(layer "In2.Cu")
		(net "SMB_FAN_3V3AUX_R_SDA")
	)
	(segment
		(start 216.8906 -99.150932)
		(end 216.8906 -112.282224)
		(width 0.127)
		(layer "In2.Cu")
		(net "SMB_FAN_3V3AUX_R_SDA")
	)
	(segment
		(start 182.479188 -41.196768)
		(end 187.452 -46.16958)
		(width 0.127)
		(layer "In2.Cu")
		(net "SMB_FAN_3V3AUX_R_SDA")
	)
	(segment
		(start 164.99713 -22.656038)
		(end 164.99713 -26.32329)
		(width 0.127)
		(layer "In2.Cu")
		(net "SMB_FAN_3V3AUX_R_SDA")
	)
	(segment
		(start 187.452 -78.623668)
		(end 190.96228 -82.133948)
		(width 0.127)
		(layer "In2.Cu")
		(net "SMB_FAN_3V3AUX_R_SDA")
	)
	(segment
		(start 158.150814 -11.280648)
		(end 158.86684 -11.280648)
		(width 0.127)
		(layer "In2.Cu")
		(net "SMB_FAN_3V3AUX_R_SDA")
	)
	(segment
		(start 160.72104 -17.079468)
		(end 161.72942 -18.087848)
		(width 0.127)
		(layer "In2.Cu")
		(net "SMB_FAN_3V3AUX_R_SDA")
	)
	(segment
		(start 158.056834 -11.374628)
		(end 158.150814 -11.280648)
		(width 0.127)
		(layer "In2.Cu")
		(net "SMB_FAN_3V3AUX_R_SDA")
	)
	(segment
		(start 190.96228 -82.133948)
		(end 199.873616 -82.133948)
		(width 0.127)
		(layer "In2.Cu")
		(net "SMB_FAN_3V3AUX_R_SDA")
	)
	(segment
		(start 217.5891 -127.467868)
		(end 217.5891 -131.379468)
		(width 0.127)
		(layer "In2.Cu")
		(net "SMB_FAN_3V3AUX_R_SDA")
	)
	(segment
		(start 216.6112 -123.1392)
		(end 217.22842 -123.75642)
		(width 0.127)
		(layer "In2.Cu")
		(net "SMB_FAN_3V3AUX_R_SDA")
	)
	(segment
		(start 217.22842 -112.620044)
		(end 217.22842 -114.7064)
		(width 0.127)
		(layer "In2.Cu")
		(net "SMB_FAN_3V3AUX_R_SDA")
	)
	(segment
		(start 180.816504 -41.196768)
		(end 182.479188 -41.196768)
		(width 0.127)
		(layer "In2.Cu")
		(net "SMB_FAN_3V3AUX_R_SDA")
	)
	(segment
		(start 175.152304 -35.532568)
		(end 180.816504 -41.196768)
		(width 0.127)
		(layer "In2.Cu")
		(net "SMB_FAN_3V3AUX_R_SDA")
	)
	(segment
		(start 227.03155 -147.13331)
		(end 227.03155 -215.558878)
		(width 0.127)
		(layer "In2.Cu")
		(net "SMB_FAN_3V3AUX_R_SDA")
	)
	(segment
		(start 169.01414 -387.598412)
		(end 169.01414 -393.23772)
		(width 0.127)
		(layer "In2.Cu")
		(net "SMB_FAN_3V3AUX_R_SDA")
	)
	(segment
		(start 187.452 -46.16958)
		(end 187.452 -78.623668)
		(width 0.127)
		(layer "In2.Cu")
		(net "SMB_FAN_3V3AUX_R_SDA")
	)
	(segment
		(start 216.8906 -112.282224)
		(end 217.22842 -112.620044)
		(width 0.127)
		(layer "In2.Cu")
		(net "SMB_FAN_3V3AUX_R_SDA")
	)
	(segment
		(start 229.0318 -217.559128)
		(end 229.0318 -233.602022)
		(width 0.127)
		(layer "In2.Cu")
		(net "SMB_FAN_3V3AUX_R_SDA")
	)
	(segment
		(start 209.354674 -91.615006)
		(end 216.8906 -99.150932)
		(width 0.127)
		(layer "In2.Cu")
		(net "SMB_FAN_3V3AUX_R_SDA")
	)
	(segment
		(start 207.354932 -88.358726)
		(end 209.354674 -90.358468)
		(width 0.127)
		(layer "In2.Cu")
		(net "SMB_FAN_3V3AUX_R_SDA")
	)
	(segment
		(start 158.86684 -11.280648)
		(end 160.72104 -13.134848)
		(width 0.127)
		(layer "In2.Cu")
		(net "SMB_FAN_3V3AUX_R_SDA")
	)
	(segment
		(start 209.354674 -90.358468)
		(end 209.354674 -91.615006)
		(width 0.127)
		(layer "In2.Cu")
		(net "SMB_FAN_3V3AUX_R_SDA")
	)
	(segment
		(start 224.7138 -237.920022)
		(end 224.7138 -331.363828)
		(width 0.127)
		(layer "In2.Cu")
		(net "SMB_FAN_3V3AUX_R_SDA")
	)
	(segment
		(start 160.72104 -13.134848)
		(end 160.72104 -17.079468)
		(width 0.127)
		(layer "In2.Cu")
		(net "SMB_FAN_3V3AUX_R_SDA")
	)
	(segment
		(start 224.7138 -331.363828)
		(end 190.04788 -366.029748)
		(width 0.127)
		(layer "In2.Cu")
		(net "SMB_FAN_3V3AUX_R_SDA")
	)
	(segment
		(start 174.206408 -35.532568)
		(end 175.152304 -35.532568)
		(width 0.127)
		(layer "In2.Cu")
		(net "SMB_FAN_3V3AUX_R_SDA")
	)
	(segment
		(start 206.098394 -88.358726)
		(end 207.354932 -88.358726)
		(width 0.127)
		(layer "In2.Cu")
		(net "SMB_FAN_3V3AUX_R_SDA")
	)
	(segment
		(start 227.03155 -215.558878)
		(end 229.0318 -217.559128)
		(width 0.127)
		(layer "In2.Cu")
		(net "SMB_FAN_3V3AUX_R_SDA")
	)
	(segment
		(start 217.22842 -127.107188)
		(end 217.5891 -127.467868)
		(width 0.127)
		(layer "In2.Cu")
		(net "SMB_FAN_3V3AUX_R_SDA")
	)
	(segment
		(start 217.5891 -131.379468)
		(end 217.22842 -131.740148)
		(width 0.127)
		(layer "In2.Cu")
		(net "SMB_FAN_3V3AUX_R_SDA")
	)
	(segment
		(start 216.6112 -115.32362)
		(end 216.6112 -123.1392)
		(width 0.127)
		(layer "In2.Cu")
		(net "SMB_FAN_3V3AUX_R_SDA")
	)
	(segment
		(start 217.22842 -137.33018)
		(end 227.03155 -147.13331)
		(width 0.127)
		(layer "In2.Cu")
		(net "SMB_FAN_3V3AUX_R_SDA")
	)
	(segment
		(start 164.99713 -26.32329)
		(end 174.206408 -35.532568)
		(width 0.127)
		(layer "In2.Cu")
		(net "SMB_FAN_3V3AUX_R_SDA")
	)
	(segment
		(start 217.22842 -114.7064)
		(end 216.6112 -115.32362)
		(width 0.127)
		(layer "In2.Cu")
		(net "SMB_FAN_3V3AUX_R_SDA")
	)
	(segment
		(start 190.04788 -366.029748)
		(end 190.04788 -366.564672)
		(width 0.127)
		(layer "In2.Cu")
		(net "SMB_FAN_3V3AUX_R_SDA")
	)
	(segment
		(start 161.72942 -19.388328)
		(end 164.99713 -22.656038)
		(width 0.127)
		(layer "In2.Cu")
		(net "SMB_FAN_3V3AUX_R_SDA")
	)
	(segment
		(start 229.0318 -233.602022)
		(end 224.7138 -237.920022)
		(width 0.127)
		(layer "In2.Cu")
		(net "SMB_FAN_3V3AUX_R_SDA")
	)
	(segment
		(start 217.22842 -123.75642)
		(end 217.22842 -127.107188)
		(width 0.127)
		(layer "In2.Cu")
		(net "SMB_FAN_3V3AUX_R_SDA")
	)
	(segment
		(start 179.008786 -425.415202)
		(end 179.435506 -424.988482)
		(width 0.12954)
		(layer "F.Cu")
		(net "SMB_FAN_3V3AUX_R_SCL")
	)
	(segment
		(start 179.008786 -425.958254)
		(end 179.008786 -425.415202)
		(width 0.12954)
		(layer "F.Cu")
		(net "SMB_FAN_3V3AUX_R_SCL")
	)
	(segment
		(start 179.435506 -424.988482)
		(end 179.435506 -423.96156)
		(width 0.12954)
		(layer "F.Cu")
		(net "SMB_FAN_3V3AUX_R_SCL")
	)
	(via
		(at 168.31564 -393.22248)
		(size 0.508)
		(drill 0.254)
		(layers "F.Cu" "B.Cu")
		(net "SMB_FAN_3V3AUX_R_SCL")
	)
	(via
		(at 179.008786 -425.958254)
		(size 0.508)
		(drill 0.254)
		(layers "F.Cu" "B.Cu")
		(net "SMB_FAN_3V3AUX_R_SCL")
	)
	(via
		(at 172.19676 -424.20794)
		(size 0.508)
		(drill 0.254)
		(layers "F.Cu" "B.Cu")
		(net "SMB_FAN_3V3AUX_R_SCL")
	)
	(via
		(at 158.53156 -11.854688)
		(size 0.508)
		(drill 0.254)
		(layers "F.Cu" "B.Cu")
		(net "SMB_FAN_3V3AUX_R_SCL")
	)
	(segment
		(start 169.646346 -394.212826)
		(end 169.248836 -394.212826)
		(width 0.12954)
		(layer "B.Cu")
		(net "SMB_FAN_3V3AUX_R_SCL")
	)
	(segment
		(start 172.19676 -422.6052)
		(end 171.3738 -421.78224)
		(width 0.12954)
		(layer "B.Cu")
		(net "SMB_FAN_3V3AUX_R_SCL")
	)
	(segment
		(start 172.1231 -419.85692)
		(end 172.1231 -412.27248)
		(width 0.12954)
		(layer "B.Cu")
		(net "SMB_FAN_3V3AUX_R_SCL")
	)
	(segment
		(start 179.008786 -425.958254)
		(end 180.767736 -424.199304)
		(width 0.12954)
		(layer "B.Cu")
		(net "SMB_FAN_3V3AUX_R_SCL")
	)
	(segment
		(start 158.53156 -11.854688)
		(end 159.49676 -11.854688)
		(width 0.12954)
		(layer "B.Cu")
		(net "SMB_FAN_3V3AUX_R_SCL")
	)
	(segment
		(start 169.248836 -394.212826)
		(end 168.31564 -393.27963)
		(width 0.12954)
		(layer "B.Cu")
		(net "SMB_FAN_3V3AUX_R_SCL")
	)
	(segment
		(start 171.3738 -420.60622)
		(end 172.1231 -419.85692)
		(width 0.12954)
		(layer "B.Cu")
		(net "SMB_FAN_3V3AUX_R_SCL")
	)
	(segment
		(start 160.039304 -12.397232)
		(end 160.266126 -12.397232)
		(width 0.12954)
		(layer "B.Cu")
		(net "SMB_FAN_3V3AUX_R_SCL")
	)
	(segment
		(start 172.1231 -412.27248)
		(end 173.25848 -411.1371)
		(width 0.12954)
		(layer "B.Cu")
		(net "SMB_FAN_3V3AUX_R_SCL")
	)
	(segment
		(start 173.25848 -411.1371)
		(end 173.25848 -398.97812)
		(width 0.12954)
		(layer "B.Cu")
		(net "SMB_FAN_3V3AUX_R_SCL")
	)
	(segment
		(start 171.3738 -421.78224)
		(end 171.3738 -420.60622)
		(width 0.12954)
		(layer "B.Cu")
		(net "SMB_FAN_3V3AUX_R_SCL")
	)
	(segment
		(start 171.63161 -398.47774)
		(end 171.50461 -398.35074)
		(width 0.12954)
		(layer "B.Cu")
		(net "SMB_FAN_3V3AUX_R_SCL")
	)
	(segment
		(start 171.50461 -398.35074)
		(end 171.50461 -396.07109)
		(width 0.12954)
		(layer "B.Cu")
		(net "SMB_FAN_3V3AUX_R_SCL")
	)
	(segment
		(start 160.266126 -12.397232)
		(end 160.28924 -12.374118)
		(width 0.12954)
		(layer "B.Cu")
		(net "SMB_FAN_3V3AUX_R_SCL")
	)
	(segment
		(start 173.25848 -398.97812)
		(end 172.7581 -398.47774)
		(width 0.12954)
		(layer "B.Cu")
		(net "SMB_FAN_3V3AUX_R_SCL")
	)
	(segment
		(start 172.7581 -398.47774)
		(end 171.63161 -398.47774)
		(width 0.12954)
		(layer "B.Cu")
		(net "SMB_FAN_3V3AUX_R_SCL")
	)
	(segment
		(start 171.50461 -396.07109)
		(end 169.646346 -394.212826)
		(width 0.12954)
		(layer "B.Cu")
		(net "SMB_FAN_3V3AUX_R_SCL")
	)
	(segment
		(start 159.49676 -11.854688)
		(end 160.039304 -12.397232)
		(width 0.12954)
		(layer "B.Cu")
		(net "SMB_FAN_3V3AUX_R_SCL")
	)
	(segment
		(start 168.31564 -393.27963)
		(end 168.31564 -393.22248)
		(width 0.12954)
		(layer "B.Cu")
		(net "SMB_FAN_3V3AUX_R_SCL")
	)
	(segment
		(start 180.767736 -424.199304)
		(end 180.767736 -423.631614)
		(width 0.12954)
		(layer "B.Cu")
		(net "SMB_FAN_3V3AUX_R_SCL")
	)
	(segment
		(start 172.19676 -424.20794)
		(end 172.19676 -422.6052)
		(width 0.12954)
		(layer "B.Cu")
		(net "SMB_FAN_3V3AUX_R_SCL")
	)
	(segment
		(start 216.79662 -127.323088)
		(end 217.14968 -127.676148)
		(width 0.127)
		(layer "In2.Cu")
		(net "SMB_FAN_3V3AUX_R_SCL")
	)
	(segment
		(start 189.43828 -365.699548)
		(end 189.43828 -366.563402)
		(width 0.127)
		(layer "In2.Cu")
		(net "SMB_FAN_3V3AUX_R_SCL")
	)
	(segment
		(start 173.25594 -425.55922)
		(end 172.19676 -424.50004)
		(width 0.127)
		(layer "In2.Cu")
		(net "SMB_FAN_3V3AUX_R_SCL")
	)
	(segment
		(start 228.6 -233.422952)
		(end 224.24517 -237.777782)
		(width 0.127)
		(layer "In2.Cu")
		(net "SMB_FAN_3V3AUX_R_SCL")
	)
	(segment
		(start 163.78428 -25.721564)
		(end 174.063914 -36.001198)
		(width 0.127)
		(layer "In2.Cu")
		(net "SMB_FAN_3V3AUX_R_SCL")
	)
	(segment
		(start 207.985614 -90.85707)
		(end 216.4588 -99.330256)
		(width 0.127)
		(layer "In2.Cu")
		(net "SMB_FAN_3V3AUX_R_SCL")
	)
	(segment
		(start 216.79662 -114.1984)
		(end 216.154 -114.84102)
		(width 0.127)
		(layer "In2.Cu")
		(net "SMB_FAN_3V3AUX_R_SCL")
	)
	(segment
		(start 216.79662 -131.491228)
		(end 216.79662 -137.509504)
		(width 0.127)
		(layer "In2.Cu")
		(net "SMB_FAN_3V3AUX_R_SCL")
	)
	(segment
		(start 224.24517 -330.892658)
		(end 189.43828 -365.699548)
		(width 0.127)
		(layer "In2.Cu")
		(net "SMB_FAN_3V3AUX_R_SCL")
	)
	(segment
		(start 217.14968 -127.676148)
		(end 217.14968 -131.138168)
		(width 0.127)
		(layer "In2.Cu")
		(net "SMB_FAN_3V3AUX_R_SCL")
	)
	(segment
		(start 217.14968 -131.138168)
		(end 216.79662 -131.491228)
		(width 0.127)
		(layer "In2.Cu")
		(net "SMB_FAN_3V3AUX_R_SCL")
	)
	(segment
		(start 216.4588 -112.461548)
		(end 216.79662 -112.799368)
		(width 0.127)
		(layer "In2.Cu")
		(net "SMB_FAN_3V3AUX_R_SCL")
	)
	(segment
		(start 207.985614 -89.733628)
		(end 207.985614 -90.85707)
		(width 0.127)
		(layer "In2.Cu")
		(net "SMB_FAN_3V3AUX_R_SCL")
	)
	(segment
		(start 226.59975 -147.312634)
		(end 226.59975 -215.737948)
		(width 0.127)
		(layer "In2.Cu")
		(net "SMB_FAN_3V3AUX_R_SCL")
	)
	(segment
		(start 199.694292 -82.565748)
		(end 205.983332 -88.854788)
		(width 0.127)
		(layer "In2.Cu")
		(net "SMB_FAN_3V3AUX_R_SCL")
	)
	(segment
		(start 172.19676 -424.50004)
		(end 172.19676 -424.20794)
		(width 0.127)
		(layer "In2.Cu")
		(net "SMB_FAN_3V3AUX_R_SCL")
	)
	(segment
		(start 216.79662 -112.799368)
		(end 216.79662 -114.1984)
		(width 0.127)
		(layer "In2.Cu")
		(net "SMB_FAN_3V3AUX_R_SCL")
	)
	(segment
		(start 224.24517 -237.777782)
		(end 224.24517 -330.892658)
		(width 0.127)
		(layer "In2.Cu")
		(net "SMB_FAN_3V3AUX_R_SCL")
	)
	(segment
		(start 187.0202 -46.348904)
		(end 187.0202 -78.802992)
		(width 0.127)
		(layer "In2.Cu")
		(net "SMB_FAN_3V3AUX_R_SCL")
	)
	(segment
		(start 216.79662 -124.08662)
		(end 216.79662 -127.323088)
		(width 0.127)
		(layer "In2.Cu")
		(net "SMB_FAN_3V3AUX_R_SCL")
	)
	(segment
		(start 182.336694 -41.665398)
		(end 187.0202 -46.348904)
		(width 0.127)
		(layer "In2.Cu")
		(net "SMB_FAN_3V3AUX_R_SCL")
	)
	(segment
		(start 180.67401 -41.665398)
		(end 182.336694 -41.665398)
		(width 0.127)
		(layer "In2.Cu")
		(net "SMB_FAN_3V3AUX_R_SCL")
	)
	(segment
		(start 226.59975 -215.737948)
		(end 228.6 -217.738198)
		(width 0.127)
		(layer "In2.Cu")
		(net "SMB_FAN_3V3AUX_R_SCL")
	)
	(segment
		(start 158.53156 -11.854688)
		(end 158.71698 -11.854688)
		(width 0.127)
		(layer "In2.Cu")
		(net "SMB_FAN_3V3AUX_R_SCL")
	)
	(segment
		(start 179.008786 -425.958254)
		(end 178.609752 -425.55922)
		(width 0.127)
		(layer "In2.Cu")
		(net "SMB_FAN_3V3AUX_R_SCL")
	)
	(segment
		(start 190.782956 -82.565748)
		(end 199.694292 -82.565748)
		(width 0.127)
		(layer "In2.Cu")
		(net "SMB_FAN_3V3AUX_R_SCL")
	)
	(segment
		(start 160.28416 -18.682208)
		(end 163.78428 -22.182328)
		(width 0.127)
		(layer "In2.Cu")
		(net "SMB_FAN_3V3AUX_R_SCL")
	)
	(segment
		(start 160.28416 -13.421868)
		(end 160.28416 -18.682208)
		(width 0.127)
		(layer "In2.Cu")
		(net "SMB_FAN_3V3AUX_R_SCL")
	)
	(segment
		(start 187.0202 -78.802992)
		(end 190.782956 -82.565748)
		(width 0.127)
		(layer "In2.Cu")
		(net "SMB_FAN_3V3AUX_R_SCL")
	)
	(segment
		(start 216.154 -114.84102)
		(end 216.154 -123.444)
		(width 0.127)
		(layer "In2.Cu")
		(net "SMB_FAN_3V3AUX_R_SCL")
	)
	(segment
		(start 174.063914 -36.001198)
		(end 175.00981 -36.001198)
		(width 0.127)
		(layer "In2.Cu")
		(net "SMB_FAN_3V3AUX_R_SCL")
	)
	(segment
		(start 189.43828 -366.563402)
		(end 168.31564 -387.686042)
		(width 0.127)
		(layer "In2.Cu")
		(net "SMB_FAN_3V3AUX_R_SCL")
	)
	(segment
		(start 158.71698 -11.854688)
		(end 160.28416 -13.421868)
		(width 0.127)
		(layer "In2.Cu")
		(net "SMB_FAN_3V3AUX_R_SCL")
	)
	(segment
		(start 216.154 -123.444)
		(end 216.79662 -124.08662)
		(width 0.127)
		(layer "In2.Cu")
		(net "SMB_FAN_3V3AUX_R_SCL")
	)
	(segment
		(start 228.6 -217.738198)
		(end 228.6 -233.422952)
		(width 0.127)
		(layer "In2.Cu")
		(net "SMB_FAN_3V3AUX_R_SCL")
	)
	(segment
		(start 163.78428 -22.182328)
		(end 163.78428 -25.721564)
		(width 0.127)
		(layer "In2.Cu")
		(net "SMB_FAN_3V3AUX_R_SCL")
	)
	(segment
		(start 207.106774 -88.854788)
		(end 207.985614 -89.733628)
		(width 0.127)
		(layer "In2.Cu")
		(net "SMB_FAN_3V3AUX_R_SCL")
	)
	(segment
		(start 168.31564 -387.686042)
		(end 168.31564 -393.22248)
		(width 0.127)
		(layer "In2.Cu")
		(net "SMB_FAN_3V3AUX_R_SCL")
	)
	(segment
		(start 175.00981 -36.001198)
		(end 180.67401 -41.665398)
		(width 0.127)
		(layer "In2.Cu")
		(net "SMB_FAN_3V3AUX_R_SCL")
	)
	(segment
		(start 205.983332 -88.854788)
		(end 207.106774 -88.854788)
		(width 0.127)
		(layer "In2.Cu")
		(net "SMB_FAN_3V3AUX_R_SCL")
	)
	(segment
		(start 216.79662 -137.509504)
		(end 226.59975 -147.312634)
		(width 0.127)
		(layer "In2.Cu")
		(net "SMB_FAN_3V3AUX_R_SCL")
	)
	(segment
		(start 216.4588 -99.330256)
		(end 216.4588 -112.461548)
		(width 0.127)
		(layer "In2.Cu")
		(net "SMB_FAN_3V3AUX_R_SCL")
	)
	(segment
		(start 178.609752 -425.55922)
		(end 173.25594 -425.55922)
		(width 0.127)
		(layer "In2.Cu")
		(net "SMB_FAN_3V3AUX_R_SCL")
	)
	(segment
		(start 180.085746 -419.496748)
		(end 180.085746 -418.277548)
		(width 0.12954)
		(layer "F.Cu")
		(net "SMB_FAN_3V3AUX_BUF_SDA")
	)
	(via
		(at 180.085746 -418.277548)
		(size 0.508)
		(drill 0.254)
		(layers "F.Cu" "B.Cu")
		(net "SMB_FAN_3V3AUX_BUF_SDA")
	)
	(segment
		(start 179.906676 -417.030154)
		(end 179.906676 -418.098478)
		(width 0.12954)
		(layer "B.Cu")
		(net "SMB_FAN_3V3AUX_BUF_SDA")
	)
	(segment
		(start 179.887626 -416.033204)
		(end 179.887626 -417.011104)
		(width 0.12954)
		(layer "B.Cu")
		(net "SMB_FAN_3V3AUX_BUF_SDA")
	)
	(segment
		(start 179.906676 -418.098478)
		(end 180.085746 -418.277548)
		(width 0.12954)
		(layer "B.Cu")
		(net "SMB_FAN_3V3AUX_BUF_SDA")
	)
	(segment
		(start 179.887626 -417.011104)
		(end 179.906676 -417.030154)
		(width 0.12954)
		(layer "B.Cu")
		(net "SMB_FAN_3V3AUX_BUF_SDA")
	)
	(segment
		(start 178.871626 -416.033204)
		(end 179.887626 -416.033204)
		(width 0.12954)
		(layer "B.Cu")
		(net "SMB_FAN_3V3AUX_BUF_SDA")
	)
	(segment
		(start 180.085746 -421.427656)
		(end 180.085746 -423.96156)
		(width 0.12954)
		(layer "F.Cu")
		(net "SMB_FAN_3V3AUX_BUF_SCL")
	)
	(segment
		(start 180.258212 -421.25519)
		(end 180.085746 -421.427656)
		(width 0.12954)
		(layer "F.Cu")
		(net "SMB_FAN_3V3AUX_BUF_SCL")
	)
	(via
		(at 180.258212 -421.25519)
		(size 0.508)
		(drill 0.254)
		(layers "F.Cu" "B.Cu")
		(net "SMB_FAN_3V3AUX_BUF_SCL")
	)
	(segment
		(start 179.964334 -422.615868)
		(end 179.964334 -421.549068)
		(width 0.12954)
		(layer "B.Cu")
		(net "SMB_FAN_3V3AUX_BUF_SCL")
	)
	(segment
		(start 179.964334 -423.628312)
		(end 179.522374 -423.628312)
		(width 0.12954)
		(layer "B.Cu")
		(net "SMB_FAN_3V3AUX_BUF_SCL")
	)
	(segment
		(start 179.964334 -422.615868)
		(end 179.964334 -423.628312)
		(width 0.12954)
		(layer "B.Cu")
		(net "SMB_FAN_3V3AUX_BUF_SCL")
	)
	(segment
		(start 179.522374 -423.628312)
		(end 179.091082 -423.19702)
		(width 0.12954)
		(layer "B.Cu")
		(net "SMB_FAN_3V3AUX_BUF_SCL")
	)
	(segment
		(start 179.964334 -421.549068)
		(end 180.258212 -421.25519)
		(width 0.12954)
		(layer "B.Cu")
		(net "SMB_FAN_3V3AUX_BUF_SCL")
	)
	(segment
		(start 179.964334 -423.628312)
		(end 179.967636 -423.631614)
		(width 0.12954)
		(layer "B.Cu")
		(net "SMB_FAN_3V3AUX_BUF_SCL")
	)
	(segment
		(start 179.091082 -423.19702)
		(end 179.091082 -422.673272)
		(width 0.12954)
		(layer "B.Cu")
		(net "SMB_FAN_3V3AUX_BUF_SCL")
	)
	(via
		(at 180.48478 -413.99206)
		(size 0.508)
		(drill 0.254)
		(layers "F.Cu" "B.Cu")
		(net "SMB_FAN_3V3AUX_BUF_R_SDA")
	)
	(segment
		(start 180.21046 -414.26638)
		(end 179.83835 -414.26638)
		(width 0.12954)
		(layer "B.Cu")
		(net "SMB_FAN_3V3AUX_BUF_R_SDA")
	)
	(segment
		(start 179.83835 -414.26638)
		(end 178.871626 -415.233104)
		(width 0.12954)
		(layer "B.Cu")
		(net "SMB_FAN_3V3AUX_BUF_R_SDA")
	)
	(segment
		(start 180.48478 -413.99206)
		(end 180.21046 -414.26638)
		(width 0.12954)
		(layer "B.Cu")
		(net "SMB_FAN_3V3AUX_BUF_R_SDA")
	)
	(segment
		(start 235.91012 -430.50206)
		(end 234.62742 -431.78476)
		(width 0.127)
		(layer "In6.Cu")
		(net "SMB_FAN_3V3AUX_BUF_R_SDA")
	)
	(segment
		(start 179.73294 -413.99206)
		(end 180.48478 -413.99206)
		(width 0.127)
		(layer "In6.Cu")
		(net "SMB_FAN_3V3AUX_BUF_R_SDA")
	)
	(segment
		(start 179.27574 -418.8079)
		(end 179.27574 -414.44926)
		(width 0.127)
		(layer "In6.Cu")
		(net "SMB_FAN_3V3AUX_BUF_R_SDA")
	)
	(segment
		(start 185.70194 -422.08704)
		(end 182.55488 -422.08704)
		(width 0.127)
		(layer "In6.Cu")
		(net "SMB_FAN_3V3AUX_BUF_R_SDA")
	)
	(segment
		(start 192.21958 -424.57624)
		(end 191.06134 -423.418)
		(width 0.127)
		(layer "In6.Cu")
		(net "SMB_FAN_3V3AUX_BUF_R_SDA")
	)
	(segment
		(start 187.12942 -421.87622)
		(end 185.91276 -421.87622)
		(width 0.127)
		(layer "In6.Cu")
		(net "SMB_FAN_3V3AUX_BUF_R_SDA")
	)
	(segment
		(start 179.27574 -414.44926)
		(end 179.73294 -413.99206)
		(width 0.127)
		(layer "In6.Cu")
		(net "SMB_FAN_3V3AUX_BUF_R_SDA")
	)
	(segment
		(start 188.6712 -423.418)
		(end 187.12942 -421.87622)
		(width 0.127)
		(layer "In6.Cu")
		(net "SMB_FAN_3V3AUX_BUF_R_SDA")
	)
	(segment
		(start 234.62742 -431.78476)
		(end 234.62742 -436.5752)
		(width 0.127)
		(layer "In6.Cu")
		(net "SMB_FAN_3V3AUX_BUF_R_SDA")
	)
	(segment
		(start 199.08139 -437.75884)
		(end 191.34074 -430.01819)
		(width 0.127)
		(layer "In6.Cu")
		(net "SMB_FAN_3V3AUX_BUF_R_SDA")
	)
	(segment
		(start 234.62742 -436.5752)
		(end 233.44378 -437.75884)
		(width 0.127)
		(layer "In6.Cu")
		(net "SMB_FAN_3V3AUX_BUF_R_SDA")
	)
	(segment
		(start 182.55488 -422.08704)
		(end 179.27574 -418.8079)
		(width 0.127)
		(layer "In6.Cu")
		(net "SMB_FAN_3V3AUX_BUF_R_SDA")
	)
	(segment
		(start 191.34074 -430.01819)
		(end 191.34074 -427.38929)
		(width 0.127)
		(layer "In6.Cu")
		(net "SMB_FAN_3V3AUX_BUF_R_SDA")
	)
	(segment
		(start 191.34074 -427.38929)
		(end 192.21958 -426.51045)
		(width 0.127)
		(layer "In6.Cu")
		(net "SMB_FAN_3V3AUX_BUF_R_SDA")
	)
	(segment
		(start 192.21958 -426.51045)
		(end 192.21958 -424.57624)
		(width 0.127)
		(layer "In6.Cu")
		(net "SMB_FAN_3V3AUX_BUF_R_SDA")
	)
	(segment
		(start 185.91276 -421.87622)
		(end 185.70194 -422.08704)
		(width 0.127)
		(layer "In6.Cu")
		(net "SMB_FAN_3V3AUX_BUF_R_SDA")
	)
	(segment
		(start 191.06134 -423.418)
		(end 188.6712 -423.418)
		(width 0.127)
		(layer "In6.Cu")
		(net "SMB_FAN_3V3AUX_BUF_R_SDA")
	)
	(segment
		(start 233.44378 -437.75884)
		(end 199.08139 -437.75884)
		(width 0.127)
		(layer "In6.Cu")
		(net "SMB_FAN_3V3AUX_BUF_R_SDA")
	)
	(via
		(at 177.91684 -421.873172)
		(size 0.508)
		(drill 0.254)
		(layers "F.Cu" "B.Cu")
		(net "SMB_FAN_3V3AUX_BUF_R_SCL")
	)
	(segment
		(start 177.91684 -421.873172)
		(end 179.091082 -421.873172)
		(width 0.12954)
		(layer "B.Cu")
		(net "SMB_FAN_3V3AUX_BUF_R_SCL")
	)
	(segment
		(start 237.22584 -436.53456)
		(end 235.39196 -438.36844)
		(width 0.127)
		(layer "In6.Cu")
		(net "SMB_FAN_3V3AUX_BUF_R_SCL")
	)
	(segment
		(start 191.60998 -425.24426)
		(end 190.2968 -423.93108)
		(width 0.127)
		(layer "In6.Cu")
		(net "SMB_FAN_3V3AUX_BUF_R_SCL")
	)
	(segment
		(start 191.60998 -426.25772)
		(end 191.60998 -425.24426)
		(width 0.127)
		(layer "In6.Cu")
		(net "SMB_FAN_3V3AUX_BUF_R_SCL")
	)
	(segment
		(start 182.284878 -422.90746)
		(end 182.10657 -423.085768)
		(width 0.127)
		(layer "In6.Cu")
		(net "SMB_FAN_3V3AUX_BUF_R_SCL")
	)
	(segment
		(start 186.54141 -422.90746)
		(end 182.284878 -422.90746)
		(width 0.127)
		(layer "In6.Cu")
		(net "SMB_FAN_3V3AUX_BUF_R_SCL")
	)
	(segment
		(start 179.129436 -423.085768)
		(end 177.91684 -421.873172)
		(width 0.127)
		(layer "In6.Cu")
		(net "SMB_FAN_3V3AUX_BUF_R_SCL")
	)
	(segment
		(start 190.73114 -427.13656)
		(end 191.60998 -426.25772)
		(width 0.127)
		(layer "In6.Cu")
		(net "SMB_FAN_3V3AUX_BUF_R_SCL")
	)
	(segment
		(start 187.56503 -423.93108)
		(end 186.54141 -422.90746)
		(width 0.127)
		(layer "In6.Cu")
		(net "SMB_FAN_3V3AUX_BUF_R_SCL")
	)
	(segment
		(start 198.82866 -438.36844)
		(end 190.73114 -430.27092)
		(width 0.127)
		(layer "In6.Cu")
		(net "SMB_FAN_3V3AUX_BUF_R_SCL")
	)
	(segment
		(start 190.2968 -423.93108)
		(end 187.56503 -423.93108)
		(width 0.127)
		(layer "In6.Cu")
		(net "SMB_FAN_3V3AUX_BUF_R_SCL")
	)
	(segment
		(start 237.22584 -431.72634)
		(end 237.22584 -436.53456)
		(width 0.127)
		(layer "In6.Cu")
		(net "SMB_FAN_3V3AUX_BUF_R_SCL")
	)
	(segment
		(start 182.10657 -423.085768)
		(end 179.129436 -423.085768)
		(width 0.127)
		(layer "In6.Cu")
		(net "SMB_FAN_3V3AUX_BUF_R_SCL")
	)
	(segment
		(start 190.73114 -430.27092)
		(end 190.73114 -427.13656)
		(width 0.127)
		(layer "In6.Cu")
		(net "SMB_FAN_3V3AUX_BUF_R_SCL")
	)
	(segment
		(start 235.39196 -438.36844)
		(end 198.82866 -438.36844)
		(width 0.127)
		(layer "In6.Cu")
		(net "SMB_FAN_3V3AUX_BUF_R_SCL")
	)
	(segment
		(start 238.45012 -430.50206)
		(end 237.22584 -431.72634)
		(width 0.127)
		(layer "In6.Cu")
		(net "SMB_FAN_3V3AUX_BUF_R_SCL")
	)
	(segment
		(start 43.932348 -437.193436)
		(end 43.932348 -437.192166)
		(width 0.12954)
		(layer "F.Cu")
		(net "SMB_BMC_GPU_EN_R3")
	)
	(segment
		(start 44.447968 -437.792368)
		(end 44.02709 -437.792368)
		(width 0.12954)
		(layer "F.Cu")
		(net "SMB_BMC_GPU_EN_R3")
	)
	(segment
		(start 41.971722 -438.223406)
		(end 41.265094 -438.223406)
		(width 0.12954)
		(layer "F.Cu")
		(net "SMB_BMC_GPU_EN_R3")
	)
	(segment
		(start 43.002962 -437.192166)
		(end 41.971722 -438.223406)
		(width 0.12954)
		(layer "F.Cu")
		(net "SMB_BMC_GPU_EN_R3")
	)
	(segment
		(start 44.02709 -437.792368)
		(end 43.932348 -437.697626)
		(width 0.12954)
		(layer "F.Cu")
		(net "SMB_BMC_GPU_EN_R3")
	)
	(segment
		(start 43.932348 -437.192166)
		(end 43.002962 -437.192166)
		(width 0.12954)
		(layer "F.Cu")
		(net "SMB_BMC_GPU_EN_R3")
	)
	(segment
		(start 43.932348 -437.697626)
		(end 43.932348 -437.193436)
		(width 0.12954)
		(layer "F.Cu")
		(net "SMB_BMC_GPU_EN_R3")
	)
	(via
		(at 43.932348 -437.193436)
		(size 0.508)
		(drill 0.254)
		(layers "F.Cu" "B.Cu")
		(net "SMB_BMC_GPU_EN_R3")
	)
	(segment
		(start 358.120442 -400.354038)
		(end 358.131872 -400.365468)
		(width 0.12954)
		(layer "F.Cu")
		(net "SMB_BMC_SWB_EN_R2")
	)
	(segment
		(start 359.67924 -400.030188)
		(end 360.70794 -399.001488)
		(width 0.12954)
		(layer "F.Cu")
		(net "SMB_BMC_SWB_EN_R2")
	)
	(segment
		(start 360.70794 -399.001488)
		(end 361.257088 -399.001488)
		(width 0.12954)
		(layer "F.Cu")
		(net "SMB_BMC_SWB_EN_R2")
	)
	(segment
		(start 361.257088 -399.001488)
		(end 361.323636 -398.93494)
		(width 0.12954)
		(layer "F.Cu")
		(net "SMB_BMC_SWB_EN_R2")
	)
	(segment
		(start 359.34396 -400.365468)
		(end 359.67924 -400.030188)
		(width 0.12954)
		(layer "F.Cu")
		(net "SMB_BMC_SWB_EN_R2")
	)
	(segment
		(start 358.131872 -400.365468)
		(end 359.34396 -400.365468)
		(width 0.12954)
		(layer "F.Cu")
		(net "SMB_BMC_SWB_EN_R2")
	)
	(via
		(at 359.67924 -400.030188)
		(size 0.508)
		(drill 0.254)
		(layers "F.Cu" "B.Cu")
		(net "SMB_BMC_SWB_EN_R2")
	)
	(segment
		(start 40.308022 -436.122318)
		(end 40.20693 -436.021226)
		(width 0.12954)
		(layer "F.Cu")
		(net "SMB_BMC_GPU_EN_R1")
	)
	(segment
		(start 41.41724 -436.122318)
		(end 40.308022 -436.122318)
		(width 0.12954)
		(layer "F.Cu")
		(net "SMB_BMC_GPU_EN_R1")
	)
	(segment
		(start 42.615866 -435.700424)
		(end 42.193972 -436.122318)
		(width 0.12954)
		(layer "F.Cu")
		(net "SMB_BMC_GPU_EN_R1")
	)
	(segment
		(start 40.20693 -436.021226)
		(end 40.20693 -435.955948)
		(width 0.12954)
		(layer "F.Cu")
		(net "SMB_BMC_GPU_EN_R1")
	)
	(segment
		(start 43.390566 -435.700424)
		(end 42.615866 -435.700424)
		(width 0.12954)
		(layer "F.Cu")
		(net "SMB_BMC_GPU_EN_R1")
	)
	(segment
		(start 42.193972 -436.122318)
		(end 41.41724 -436.122318)
		(width 0.12954)
		(layer "F.Cu")
		(net "SMB_BMC_GPU_EN_R1")
	)
	(via
		(at 41.41724 -436.122318)
		(size 0.508)
		(drill 0.254)
		(layers "F.Cu" "B.Cu")
		(net "SMB_BMC_GPU_EN_R1")
	)
	(segment
		(start 165.28415 -428.647098)
		(end 165.28415 -429.433228)
		(width 0.12954)
		(layer "F.Cu")
		(net "SMB_BMC_SWB_EN_R")
	)
	(segment
		(start 165.28415 -430.560226)
		(end 165.15715 -430.687226)
		(width 0.12954)
		(layer "F.Cu")
		(net "SMB_BMC_SWB_EN_R")
	)
	(segment
		(start 165.28415 -429.433228)
		(end 165.28415 -430.560226)
		(width 0.12954)
		(layer "F.Cu")
		(net "SMB_BMC_SWB_EN_R")
	)
	(segment
		(start 164.862256 -427.477682)
		(end 164.862256 -428.225204)
		(width 0.12954)
		(layer "F.Cu")
		(net "SMB_BMC_SWB_EN_R")
	)
	(segment
		(start 164.862256 -428.225204)
		(end 165.28415 -428.647098)
		(width 0.12954)
		(layer "F.Cu")
		(net "SMB_BMC_SWB_EN_R")
	)
	(via
		(at 165.28415 -429.433228)
		(size 0.508)
		(drill 0.254)
		(layers "F.Cu" "B.Cu")
		(net "SMB_BMC_SWB_EN_R")
	)
	(segment
		(start 49.010316 -435.487318)
		(end 49.67986 -435.487318)
		(width 0.12954)
		(layer "F.Cu")
		(net "SMB_1_BMC_GPU_BUF_R_SDA")
	)
	(segment
		(start 52.080922 -435.360318)
		(end 51.845972 -435.125368)
		(width 0.12954)
		(layer "F.Cu")
		(net "SMB_1_BMC_GPU_BUF_R_SDA")
	)
	(segment
		(start 50.262536 -435.487318)
		(end 50.536856 -435.212998)
		(width 0.12954)
		(layer "F.Cu")
		(net "SMB_1_BMC_GPU_BUF_R_SDA")
	)
	(segment
		(start 50.536856 -435.212998)
		(end 50.98288 -435.212998)
		(width 0.12954)
		(layer "F.Cu")
		(net "SMB_1_BMC_GPU_BUF_R_SDA")
	)
	(segment
		(start 47.855378 -435.050438)
		(end 48.573436 -435.050438)
		(width 0.12954)
		(layer "F.Cu")
		(net "SMB_1_BMC_GPU_BUF_R_SDA")
	)
	(segment
		(start 51.845972 -435.125368)
		(end 51.516534 -435.125368)
		(width 0.12954)
		(layer "F.Cu")
		(net "SMB_1_BMC_GPU_BUF_R_SDA")
	)
	(segment
		(start 51.428904 -435.212998)
		(end 50.98288 -435.212998)
		(width 0.12954)
		(layer "F.Cu")
		(net "SMB_1_BMC_GPU_BUF_R_SDA")
	)
	(segment
		(start 49.67986 -435.487318)
		(end 50.262536 -435.487318)
		(width 0.12954)
		(layer "F.Cu")
		(net "SMB_1_BMC_GPU_BUF_R_SDA")
	)
	(segment
		(start 48.573436 -435.050438)
		(end 49.010316 -435.487318)
		(width 0.12954)
		(layer "F.Cu")
		(net "SMB_1_BMC_GPU_BUF_R_SDA")
	)
	(segment
		(start 52.080922 -436.376318)
		(end 52.080922 -435.360318)
		(width 0.12954)
		(layer "F.Cu")
		(net "SMB_1_BMC_GPU_BUF_R_SDA")
	)
	(segment
		(start 51.516534 -435.125368)
		(end 51.428904 -435.212998)
		(width 0.12954)
		(layer "F.Cu")
		(net "SMB_1_BMC_GPU_BUF_R_SDA")
	)
	(via
		(at 49.67986 -435.487318)
		(size 0.508)
		(drill 0.254)
		(layers "F.Cu" "B.Cu")
		(net "SMB_1_BMC_GPU_BUF_R_SDA")
	)
	(segment
		(start 38.442392 -434.939948)
		(end 38.637972 -434.744368)
		(width 0.12954)
		(layer "F.Cu")
		(net "SMB_1_BMC_GPU_BUF_R_SCL")
	)
	(segment
		(start 38.42893 -434.939948)
		(end 38.442392 -434.939948)
		(width 0.12954)
		(layer "F.Cu")
		(net "SMB_1_BMC_GPU_BUF_R_SCL")
	)
	(segment
		(start 38.42893 -435.955948)
		(end 38.42893 -434.939948)
		(width 0.12954)
		(layer "F.Cu")
		(net "SMB_1_BMC_GPU_BUF_R_SCL")
	)
	(segment
		(start 41.88968 -434.852318)
		(end 40.269922 -434.852318)
		(width 0.12954)
		(layer "F.Cu")
		(net "SMB_1_BMC_GPU_BUF_R_SCL")
	)
	(segment
		(start 42.427652 -434.852318)
		(end 41.88968 -434.852318)
		(width 0.12954)
		(layer "F.Cu")
		(net "SMB_1_BMC_GPU_BUF_R_SCL")
	)
	(segment
		(start 38.637972 -434.744368)
		(end 40.161972 -434.744368)
		(width 0.12954)
		(layer "F.Cu")
		(net "SMB_1_BMC_GPU_BUF_R_SCL")
	)
	(segment
		(start 40.269922 -434.852318)
		(end 40.161972 -434.744368)
		(width 0.12954)
		(layer "F.Cu")
		(net "SMB_1_BMC_GPU_BUF_R_SCL")
	)
	(segment
		(start 42.625772 -435.050438)
		(end 42.427652 -434.852318)
		(width 0.12954)
		(layer "F.Cu")
		(net "SMB_1_BMC_GPU_BUF_R_SCL")
	)
	(segment
		(start 43.390566 -435.050438)
		(end 42.625772 -435.050438)
		(width 0.12954)
		(layer "F.Cu")
		(net "SMB_1_BMC_GPU_BUF_R_SCL")
	)
	(via
		(at 41.88968 -434.852318)
		(size 0.508)
		(drill 0.254)
		(layers "F.Cu" "B.Cu")
		(net "SMB_1_BMC_GPU_BUF_R_SCL")
	)
	(segment
		(start 33.180528 -438.704228)
		(end 33.477454 -438.704228)
		(width 0.12954)
		(layer "F.Cu")
		(net "SMB_2_BMC_GPU_BUF_R_SDA")
	)
	(segment
		(start 36.151566 -438.873392)
		(end 36.800282 -438.873392)
		(width 0.12954)
		(layer "F.Cu")
		(net "SMB_2_BMC_GPU_BUF_R_SDA")
	)
	(segment
		(start 34.177478 -437.585612)
		(end 34.863786 -437.585612)
		(width 0.12954)
		(layer "F.Cu")
		(net "SMB_2_BMC_GPU_BUF_R_SDA")
	)
	(segment
		(start 33.180528 -437.688228)
		(end 33.180528 -438.704228)
		(width 0.12954)
		(layer "F.Cu")
		(net "SMB_2_BMC_GPU_BUF_R_SDA")
	)
	(segment
		(start 34.177478 -438.939178)
		(end 34.177478 -437.585612)
		(width 0.12954)
		(layer "F.Cu")
		(net "SMB_2_BMC_GPU_BUF_R_SDA")
	)
	(segment
		(start 33.712404 -438.939178)
		(end 34.177478 -438.939178)
		(width 0.12954)
		(layer "F.Cu")
		(net "SMB_2_BMC_GPU_BUF_R_SDA")
	)
	(segment
		(start 33.477454 -438.704228)
		(end 33.712404 -438.939178)
		(width 0.12954)
		(layer "F.Cu")
		(net "SMB_2_BMC_GPU_BUF_R_SDA")
	)
	(segment
		(start 34.863786 -437.585612)
		(end 36.151566 -438.873392)
		(width 0.12954)
		(layer "F.Cu")
		(net "SMB_2_BMC_GPU_BUF_R_SDA")
	)
	(via
		(at 34.177478 -437.585612)
		(size 0.508)
		(drill 0.254)
		(layers "F.Cu" "B.Cu")
		(net "SMB_2_BMC_GPU_BUF_R_SDA")
	)
	(segment
		(start 42.828972 -437.980582)
		(end 41.936162 -438.873392)
		(width 0.12954)
		(layer "F.Cu")
		(net "SMB_2_BMC_GPU_BUF_R_SCL")
	)
	(segment
		(start 46.225968 -439.189368)
		(end 46.225968 -437.792368)
		(width 0.12954)
		(layer "F.Cu")
		(net "SMB_2_BMC_GPU_BUF_R_SCL")
	)
	(segment
		(start 45.269404 -439.302652)
		(end 45.147738 -439.424318)
		(width 0.12954)
		(layer "F.Cu")
		(net "SMB_2_BMC_GPU_BUF_R_SCL")
	)
	(segment
		(start 43.885358 -438.265062)
		(end 43.600878 -437.980582)
		(width 0.12954)
		(layer "F.Cu")
		(net "SMB_2_BMC_GPU_BUF_R_SCL")
	)
	(segment
		(start 45.269404 -438.535318)
		(end 45.269404 -439.302652)
		(width 0.12954)
		(layer "F.Cu")
		(net "SMB_2_BMC_GPU_BUF_R_SCL")
	)
	(segment
		(start 44.467018 -439.424318)
		(end 43.885358 -438.842658)
		(width 0.12954)
		(layer "F.Cu")
		(net "SMB_2_BMC_GPU_BUF_R_SCL")
	)
	(segment
		(start 41.936162 -438.873392)
		(end 41.265094 -438.873392)
		(width 0.12954)
		(layer "F.Cu")
		(net "SMB_2_BMC_GPU_BUF_R_SCL")
	)
	(segment
		(start 43.885358 -438.842658)
		(end 43.885358 -438.265062)
		(width 0.12954)
		(layer "F.Cu")
		(net "SMB_2_BMC_GPU_BUF_R_SCL")
	)
	(segment
		(start 43.600878 -437.980582)
		(end 42.828972 -437.980582)
		(width 0.12954)
		(layer "F.Cu")
		(net "SMB_2_BMC_GPU_BUF_R_SCL")
	)
	(segment
		(start 45.571918 -438.535318)
		(end 45.269404 -438.535318)
		(width 0.12954)
		(layer "F.Cu")
		(net "SMB_2_BMC_GPU_BUF_R_SCL")
	)
	(segment
		(start 45.147738 -439.424318)
		(end 44.467018 -439.424318)
		(width 0.12954)
		(layer "F.Cu")
		(net "SMB_2_BMC_GPU_BUF_R_SCL")
	)
	(segment
		(start 46.225968 -439.189368)
		(end 45.571918 -438.535318)
		(width 0.12954)
		(layer "F.Cu")
		(net "SMB_2_BMC_GPU_BUF_R_SCL")
	)
	(via
		(at 45.269404 -438.535318)
		(size 0.508)
		(drill 0.254)
		(layers "F.Cu" "B.Cu")
		(net "SMB_2_BMC_GPU_BUF_R_SCL")
	)
	(segment
		(start 11.895836 -93.087698)
		(end 10.873486 -93.087698)
		(width 0.12954)
		(layer "F.Cu")
		(net "RST_USB_HUB_R_N")
	)
	(segment
		(start 12.982956 -95.084392)
		(end 12.982956 -93.087698)
		(width 0.12954)
		(layer "F.Cu")
		(net "RST_USB_HUB_R_N")
	)
	(segment
		(start 13.565124 -96.130872)
		(end 12.7508 -95.316548)
		(width 0.12954)
		(layer "F.Cu")
		(net "RST_USB_HUB_R_N")
	)
	(segment
		(start 9.908032 -93.087698)
		(end 10.873486 -93.087698)
		(width 0.12954)
		(layer "F.Cu")
		(net "RST_USB_HUB_R_N")
	)
	(segment
		(start 12.982956 -93.087698)
		(end 11.895836 -93.087698)
		(width 0.12954)
		(layer "F.Cu")
		(net "RST_USB_HUB_R_N")
	)
	(segment
		(start 12.7508 -95.316548)
		(end 12.982956 -95.084392)
		(width 0.12954)
		(layer "F.Cu")
		(net "RST_USB_HUB_R_N")
	)
	(segment
		(start 13.565124 -96.723962)
		(end 13.565124 -96.130872)
		(width 0.12954)
		(layer "F.Cu")
		(net "RST_USB_HUB_R_N")
	)
	(via
		(at 12.7508 -95.316548)
		(size 0.762)
		(drill 0.381)
		(layers "F.Cu" "B.Cu")
		(net "RST_USB_HUB_R_N")
	)
	(segment
		(start 152.57653 -30.941518)
		(end 152.978612 -30.941518)
		(width 0.12954)
		(layer "F.Cu")
		(net "RST_USB_HUB_N")
	)
	(segment
		(start 15.689834 -413.514794)
		(end 15.689834 -414.277302)
		(width 0.12954)
		(layer "F.Cu")
		(net "RST_USB_HUB_N")
	)
	(segment
		(start 16.64208 -410.456888)
		(end 16.0782 -411.020768)
		(width 0.12954)
		(layer "F.Cu")
		(net "RST_USB_HUB_N")
	)
	(segment
		(start 16.0782 -413.126428)
		(end 15.689834 -413.514794)
		(width 0.12954)
		(layer "F.Cu")
		(net "RST_USB_HUB_N")
	)
	(segment
		(start 151.99614 -31.521908)
		(end 152.57653 -30.941518)
		(width 0.12954)
		(layer "F.Cu")
		(net "RST_USB_HUB_N")
	)
	(segment
		(start 16.0782 -411.020768)
		(end 16.0782 -413.126428)
		(width 0.12954)
		(layer "F.Cu")
		(net "RST_USB_HUB_N")
	)
	(segment
		(start 9.908032 -92.287598)
		(end 9.07796 -92.287598)
		(width 0.12954)
		(layer "F.Cu")
		(net "RST_USB_HUB_N")
	)
	(via
		(at 151.99614 -31.521908)
		(size 0.508)
		(drill 0.254)
		(layers "F.Cu" "B.Cu")
		(net "RST_USB_HUB_N")
	)
	(via
		(at 9.07796 -92.287598)
		(size 0.508)
		(drill 0.254)
		(layers "F.Cu" "B.Cu")
		(net "RST_USB_HUB_N")
	)
	(via
		(at 16.64208 -410.456888)
		(size 0.762)
		(drill 0.254)
		(layers "F.Cu" "B.Cu")
		(net "RST_USB_HUB_N")
	)
	(segment
		(start 4.74218 -157.813248)
		(end 4.74218 -191.03594)
		(width 0.127)
		(layer "In2.Cu")
		(net "RST_USB_HUB_N")
	)
	(segment
		(start 18.19148 -364.322614)
		(end 6.73862 -375.775474)
		(width 0.127)
		(layer "In2.Cu")
		(net "RST_USB_HUB_N")
	)
	(segment
		(start 18.19148 -402.861526)
		(end 18.19148 -408.907488)
		(width 0.127)
		(layer "In2.Cu")
		(net "RST_USB_HUB_N")
	)
	(segment
		(start 5.585714 -191.879474)
		(end 5.585714 -193.487802)
		(width 0.127)
		(layer "In2.Cu")
		(net "RST_USB_HUB_N")
	)
	(segment
		(start 8.36168 -154.193748)
		(end 4.74218 -157.813248)
		(width 0.127)
		(layer "In2.Cu")
		(net "RST_USB_HUB_N")
	)
	(segment
		(start 9.07796 -92.287598)
		(end 8.3058 -93.059758)
		(width 0.127)
		(layer "In2.Cu")
		(net "RST_USB_HUB_N")
	)
	(segment
		(start 6.73862 -391.408666)
		(end 18.19148 -402.861526)
		(width 0.127)
		(layer "In2.Cu")
		(net "RST_USB_HUB_N")
	)
	(segment
		(start 5.15874 -107.155488)
		(end 4.45008 -107.864148)
		(width 0.127)
		(layer "In2.Cu")
		(net "RST_USB_HUB_N")
	)
	(segment
		(start 6.73862 -375.775474)
		(end 6.73862 -391.408666)
		(width 0.127)
		(layer "In2.Cu")
		(net "RST_USB_HUB_N")
	)
	(segment
		(start 4.45008 -136.794748)
		(end 11.15568 -143.500348)
		(width 0.127)
		(layer "In2.Cu")
		(net "RST_USB_HUB_N")
	)
	(segment
		(start 8.3058 -93.059758)
		(end 6.81609 -93.059758)
		(width 0.127)
		(layer "In2.Cu")
		(net "RST_USB_HUB_N")
	)
	(segment
		(start 11.15568 -143.500348)
		(end 11.15568 -153.228548)
		(width 0.127)
		(layer "In2.Cu")
		(net "RST_USB_HUB_N")
	)
	(segment
		(start 4.74218 -194.331336)
		(end 4.74218 -332.487778)
		(width 0.127)
		(layer "In2.Cu")
		(net "RST_USB_HUB_N")
	)
	(segment
		(start 5.15874 -94.717108)
		(end 5.15874 -107.155488)
		(width 0.127)
		(layer "In2.Cu")
		(net "RST_USB_HUB_N")
	)
	(segment
		(start 4.74218 -332.487778)
		(end 18.19148 -345.937078)
		(width 0.127)
		(layer "In2.Cu")
		(net "RST_USB_HUB_N")
	)
	(segment
		(start 6.81609 -93.059758)
		(end 5.15874 -94.717108)
		(width 0.127)
		(layer "In2.Cu")
		(net "RST_USB_HUB_N")
	)
	(segment
		(start 11.15568 -153.228548)
		(end 10.19048 -154.193748)
		(width 0.127)
		(layer "In2.Cu")
		(net "RST_USB_HUB_N")
	)
	(segment
		(start 10.19048 -154.193748)
		(end 8.36168 -154.193748)
		(width 0.127)
		(layer "In2.Cu")
		(net "RST_USB_HUB_N")
	)
	(segment
		(start 18.19148 -408.907488)
		(end 16.64208 -410.456888)
		(width 0.127)
		(layer "In2.Cu")
		(net "RST_USB_HUB_N")
	)
	(segment
		(start 4.45008 -107.864148)
		(end 4.45008 -136.794748)
		(width 0.127)
		(layer "In2.Cu")
		(net "RST_USB_HUB_N")
	)
	(segment
		(start 5.585714 -193.487802)
		(end 4.74218 -194.331336)
		(width 0.127)
		(layer "In2.Cu")
		(net "RST_USB_HUB_N")
	)
	(segment
		(start 4.74218 -191.03594)
		(end 5.585714 -191.879474)
		(width 0.127)
		(layer "In2.Cu")
		(net "RST_USB_HUB_N")
	)
	(segment
		(start 18.19148 -345.937078)
		(end 18.19148 -364.322614)
		(width 0.127)
		(layer "In2.Cu")
		(net "RST_USB_HUB_N")
	)
	(segment
		(start 147.9296 -16.347948)
		(end 145.99412 -16.347948)
		(width 0.127)
		(layer "In15.Cu")
		(net "RST_USB_HUB_N")
	)
	(segment
		(start 137.275316 -27.818588)
		(end 130.884676 -34.209228)
		(width 0.127)
		(layer "In15.Cu")
		(net "RST_USB_HUB_N")
	)
	(segment
		(start 66.3194 -34.864548)
		(end 64.5922 -34.864548)
		(width 0.127)
		(layer "In15.Cu")
		(net "RST_USB_HUB_N")
	)
	(segment
		(start 7.16534 -72.692768)
		(end 7.16534 -90.374978)
		(width 0.127)
		(layer "In15.Cu")
		(net "RST_USB_HUB_N")
	)
	(segment
		(start 145.99412 -16.347948)
		(end 142.29588 -20.046188)
		(width 0.127)
		(layer "In15.Cu")
		(net "RST_USB_HUB_N")
	)
	(segment
		(start 94.042738 -34.209228)
		(end 93.204538 -33.371028)
		(width 0.127)
		(layer "In15.Cu")
		(net "RST_USB_HUB_N")
	)
	(segment
		(start 2.59969 -42.894758)
		(end 1.85801 -43.636438)
		(width 0.127)
		(layer "In15.Cu")
		(net "RST_USB_HUB_N")
	)
	(segment
		(start 149.26818 -28.793948)
		(end 149.26818 -17.686528)
		(width 0.127)
		(layer "In15.Cu")
		(net "RST_USB_HUB_N")
	)
	(segment
		(start 142.29588 -20.046188)
		(end 142.29588 -23.788624)
		(width 0.127)
		(layer "In15.Cu")
		(net "RST_USB_HUB_N")
	)
	(segment
		(start 44.343066 -42.894758)
		(end 2.59969 -42.894758)
		(width 0.127)
		(layer "In15.Cu")
		(net "RST_USB_HUB_N")
	)
	(segment
		(start 1.85801 -43.636438)
		(end 1.85801 -44.621958)
		(width 0.127)
		(layer "In15.Cu")
		(net "RST_USB_HUB_N")
	)
	(segment
		(start 86.016846 -33.581848)
		(end 71.519034 -33.581848)
		(width 0.127)
		(layer "In15.Cu")
		(net "RST_USB_HUB_N")
	)
	(segment
		(start 92.0242 -33.371028)
		(end 91.18092 -32.527748)
		(width 0.127)
		(layer "In15.Cu")
		(net "RST_USB_HUB_N")
	)
	(segment
		(start 93.204538 -33.371028)
		(end 92.0242 -33.371028)
		(width 0.127)
		(layer "In15.Cu")
		(net "RST_USB_HUB_N")
	)
	(segment
		(start 130.884676 -34.209228)
		(end 94.042738 -34.209228)
		(width 0.127)
		(layer "In15.Cu")
		(net "RST_USB_HUB_N")
	)
	(segment
		(start 52.779676 -34.458148)
		(end 44.343066 -42.894758)
		(width 0.127)
		(layer "In15.Cu")
		(net "RST_USB_HUB_N")
	)
	(segment
		(start 142.29588 -23.788624)
		(end 138.265916 -27.818588)
		(width 0.127)
		(layer "In15.Cu")
		(net "RST_USB_HUB_N")
	)
	(segment
		(start 151.99614 -31.521908)
		(end 149.26818 -28.793948)
		(width 0.127)
		(layer "In15.Cu")
		(net "RST_USB_HUB_N")
	)
	(segment
		(start 4.9784 -70.505828)
		(end 7.16534 -72.692768)
		(width 0.127)
		(layer "In15.Cu")
		(net "RST_USB_HUB_N")
	)
	(segment
		(start 71.519034 -33.581848)
		(end 70.337934 -32.400748)
		(width 0.127)
		(layer "In15.Cu")
		(net "RST_USB_HUB_N")
	)
	(segment
		(start 138.265916 -27.818588)
		(end 137.275316 -27.818588)
		(width 0.127)
		(layer "In15.Cu")
		(net "RST_USB_HUB_N")
	)
	(segment
		(start 91.18092 -32.527748)
		(end 87.070946 -32.527748)
		(width 0.127)
		(layer "In15.Cu")
		(net "RST_USB_HUB_N")
	)
	(segment
		(start 70.337934 -32.400748)
		(end 68.7832 -32.400748)
		(width 0.127)
		(layer "In15.Cu")
		(net "RST_USB_HUB_N")
	)
	(segment
		(start 1.85801 -44.621958)
		(end 4.9784 -47.742348)
		(width 0.127)
		(layer "In15.Cu")
		(net "RST_USB_HUB_N")
	)
	(segment
		(start 4.9784 -47.742348)
		(end 4.9784 -70.505828)
		(width 0.127)
		(layer "In15.Cu")
		(net "RST_USB_HUB_N")
	)
	(segment
		(start 64.1858 -34.458148)
		(end 52.779676 -34.458148)
		(width 0.127)
		(layer "In15.Cu")
		(net "RST_USB_HUB_N")
	)
	(segment
		(start 87.070946 -32.527748)
		(end 86.016846 -33.581848)
		(width 0.127)
		(layer "In15.Cu")
		(net "RST_USB_HUB_N")
	)
	(segment
		(start 64.5922 -34.864548)
		(end 64.1858 -34.458148)
		(width 0.127)
		(layer "In15.Cu")
		(net "RST_USB_HUB_N")
	)
	(segment
		(start 7.16534 -90.374978)
		(end 9.07796 -92.287598)
		(width 0.127)
		(layer "In15.Cu")
		(net "RST_USB_HUB_N")
	)
	(segment
		(start 149.26818 -17.686528)
		(end 147.9296 -16.347948)
		(width 0.127)
		(layer "In15.Cu")
		(net "RST_USB_HUB_N")
	)
	(segment
		(start 68.7832 -32.400748)
		(end 66.3194 -34.864548)
		(width 0.127)
		(layer "In15.Cu")
		(net "RST_USB_HUB_N")
	)
	(segment
		(start 160.43783 -110.093252)
		(end 160.43783 -109.565948)
		(width 0.12954)
		(layer "F.Cu")
		(net "RST_BMC_FROM_SWB_ISO_N")
	)
	(segment
		(start 158.9786 -109.4867)
		(end 158.9786 -109.611668)
		(width 0.12954)
		(layer "F.Cu")
		(net "RST_BMC_FROM_SWB_ISO_N")
	)
	(segment
		(start 426.595032 -380.568962)
		(end 424.843956 -380.568962)
		(width 0.12954)
		(layer "F.Cu")
		(net "RST_BMC_FROM_SWB_ISO_N")
	)
	(segment
		(start 158.9786 -109.611668)
		(end 159.69488 -110.327948)
		(width 0.12954)
		(layer "F.Cu")
		(net "RST_BMC_FROM_SWB_ISO_N")
	)
	(segment
		(start 159.69488 -110.327948)
		(end 160.203134 -110.327948)
		(width 0.12954)
		(layer "F.Cu")
		(net "RST_BMC_FROM_SWB_ISO_N")
	)
	(segment
		(start 160.203134 -110.327948)
		(end 160.43783 -110.093252)
		(width 0.12954)
		(layer "F.Cu")
		(net "RST_BMC_FROM_SWB_ISO_N")
	)
	(segment
		(start 427.230032 -380.568962)
		(end 426.595032 -380.568962)
		(width 0.12954)
		(layer "F.Cu")
		(net "RST_BMC_FROM_SWB_ISO_N")
	)
	(segment
		(start 424.843956 -380.568962)
		(end 424.604942 -380.329948)
		(width 0.12954)
		(layer "F.Cu")
		(net "RST_BMC_FROM_SWB_ISO_N")
	)
	(segment
		(start 424.604942 -379.313948)
		(end 424.604942 -380.329948)
		(width 0.12954)
		(layer "F.Cu")
		(net "RST_BMC_FROM_SWB_ISO_N")
	)
	(via
		(at 163.88588 -128.107948)
		(size 0.508)
		(drill 0.254)
		(layers "F.Cu" "B.Cu")
		(net "RST_BMC_FROM_SWB_ISO_N")
	)
	(via
		(at 426.595032 -380.568962)
		(size 0.508)
		(drill 0.254)
		(layers "F.Cu" "B.Cu")
		(net "RST_BMC_FROM_SWB_ISO_N")
	)
	(via
		(at 301.68088 -392.250168)
		(size 0.508)
		(drill 0.254)
		(layers "F.Cu" "B.Cu")
		(net "RST_BMC_FROM_SWB_ISO_N")
	)
	(via
		(at 201.47788 -125.313948)
		(size 0.508)
		(drill 0.254)
		(layers "F.Cu" "B.Cu")
		(net "RST_BMC_FROM_SWB_ISO_N")
	)
	(via
		(at 158.9786 -109.4867)
		(size 0.508)
		(drill 0.254)
		(layers "F.Cu" "B.Cu")
		(net "RST_BMC_FROM_SWB_ISO_N")
	)
	(via
		(at 238.346234 -205.564994)
		(size 0.508)
		(drill 0.254)
		(layers "F.Cu" "B.Cu")
		(net "RST_BMC_FROM_SWB_ISO_N")
	)
	(segment
		(start 281.5336 -380.9238)
		(end 280.543 -380.9238)
		(width 0.127)
		(layer "In4.Cu")
		(net "RST_BMC_FROM_SWB_ISO_N")
	)
	(segment
		(start 280.543 -380.9238)
		(end 276.969474 -377.350274)
		(width 0.127)
		(layer "In4.Cu")
		(net "RST_BMC_FROM_SWB_ISO_N")
	)
	(segment
		(start 297.303444 -392.033252)
		(end 295.012872 -389.74268)
		(width 0.127)
		(layer "In4.Cu")
		(net "RST_BMC_FROM_SWB_ISO_N")
	)
	(segment
		(start 199.68972 -127.102108)
		(end 196.78142 -127.102108)
		(width 0.127)
		(layer "In4.Cu")
		(net "RST_BMC_FROM_SWB_ISO_N")
	)
	(segment
		(start 244.663214 -279.817068)
		(end 248.46788 -276.012402)
		(width 0.127)
		(layer "In4.Cu")
		(net "RST_BMC_FROM_SWB_ISO_N")
	)
	(segment
		(start 194.08902 -128.130808)
		(end 193.93916 -127.980948)
		(width 0.127)
		(layer "In4.Cu")
		(net "RST_BMC_FROM_SWB_ISO_N")
	)
	(segment
		(start 170.24858 -127.000508)
		(end 169.756328 -127.49276)
		(width 0.127)
		(layer "In4.Cu")
		(net "RST_BMC_FROM_SWB_ISO_N")
	)
	(segment
		(start 180.4162 -125.547628)
		(end 179.487068 -126.47676)
		(width 0.127)
		(layer "In4.Cu")
		(net "RST_BMC_FROM_SWB_ISO_N")
	)
	(segment
		(start 244.663214 -328.315828)
		(end 244.663214 -279.817068)
		(width 0.127)
		(layer "In4.Cu")
		(net "RST_BMC_FROM_SWB_ISO_N")
	)
	(segment
		(start 301.68088 -392.250168)
		(end 301.463964 -392.033252)
		(width 0.127)
		(layer "In4.Cu")
		(net "RST_BMC_FROM_SWB_ISO_N")
	)
	(segment
		(start 291.561012 -389.74268)
		(end 289.445192 -387.62686)
		(width 0.127)
		(layer "In4.Cu")
		(net "RST_BMC_FROM_SWB_ISO_N")
	)
	(segment
		(start 169.756328 -127.49276)
		(end 164.501068 -127.49276)
		(width 0.127)
		(layer "In4.Cu")
		(net "RST_BMC_FROM_SWB_ISO_N")
	)
	(segment
		(start 184.60212 -124.948188)
		(end 184.00268 -125.547628)
		(width 0.127)
		(layer "In4.Cu")
		(net "RST_BMC_FROM_SWB_ISO_N")
	)
	(segment
		(start 248.46788 -276.012402)
		(end 248.46788 -215.819228)
		(width 0.127)
		(layer "In4.Cu")
		(net "RST_BMC_FROM_SWB_ISO_N")
	)
	(segment
		(start 276.969474 -360.622088)
		(end 244.663214 -328.315828)
		(width 0.127)
		(layer "In4.Cu")
		(net "RST_BMC_FROM_SWB_ISO_N")
	)
	(segment
		(start 276.969474 -377.350274)
		(end 276.969474 -360.622088)
		(width 0.127)
		(layer "In4.Cu")
		(net "RST_BMC_FROM_SWB_ISO_N")
	)
	(segment
		(start 188.756544 -124.948188)
		(end 184.60212 -124.948188)
		(width 0.127)
		(layer "In4.Cu")
		(net "RST_BMC_FROM_SWB_ISO_N")
	)
	(segment
		(start 174.877222 -126.47676)
		(end 174.353474 -127.000508)
		(width 0.127)
		(layer "In4.Cu")
		(net "RST_BMC_FROM_SWB_ISO_N")
	)
	(segment
		(start 201.47788 -125.313948)
		(end 199.68972 -127.102108)
		(width 0.127)
		(layer "In4.Cu")
		(net "RST_BMC_FROM_SWB_ISO_N")
	)
	(segment
		(start 193.93916 -127.980948)
		(end 191.789304 -127.980948)
		(width 0.127)
		(layer "In4.Cu")
		(net "RST_BMC_FROM_SWB_ISO_N")
	)
	(segment
		(start 164.501068 -127.49276)
		(end 163.88588 -128.107948)
		(width 0.127)
		(layer "In4.Cu")
		(net "RST_BMC_FROM_SWB_ISO_N")
	)
	(segment
		(start 301.463964 -392.033252)
		(end 297.303444 -392.033252)
		(width 0.127)
		(layer "In4.Cu")
		(net "RST_BMC_FROM_SWB_ISO_N")
	)
	(segment
		(start 238.346234 -205.697582)
		(end 238.346234 -205.564994)
		(width 0.127)
		(layer "In4.Cu")
		(net "RST_BMC_FROM_SWB_ISO_N")
	)
	(segment
		(start 179.487068 -126.47676)
		(end 174.877222 -126.47676)
		(width 0.127)
		(layer "In4.Cu")
		(net "RST_BMC_FROM_SWB_ISO_N")
	)
	(segment
		(start 288.23666 -387.62686)
		(end 281.5336 -380.9238)
		(width 0.127)
		(layer "In4.Cu")
		(net "RST_BMC_FROM_SWB_ISO_N")
	)
	(segment
		(start 174.353474 -127.000508)
		(end 170.24858 -127.000508)
		(width 0.127)
		(layer "In4.Cu")
		(net "RST_BMC_FROM_SWB_ISO_N")
	)
	(segment
		(start 196.78142 -127.102108)
		(end 195.75272 -128.130808)
		(width 0.127)
		(layer "In4.Cu")
		(net "RST_BMC_FROM_SWB_ISO_N")
	)
	(segment
		(start 248.46788 -215.819228)
		(end 238.346234 -205.697582)
		(width 0.127)
		(layer "In4.Cu")
		(net "RST_BMC_FROM_SWB_ISO_N")
	)
	(segment
		(start 184.00268 -125.547628)
		(end 180.4162 -125.547628)
		(width 0.127)
		(layer "In4.Cu")
		(net "RST_BMC_FROM_SWB_ISO_N")
	)
	(segment
		(start 191.789304 -127.980948)
		(end 188.756544 -124.948188)
		(width 0.127)
		(layer "In4.Cu")
		(net "RST_BMC_FROM_SWB_ISO_N")
	)
	(segment
		(start 195.75272 -128.130808)
		(end 194.08902 -128.130808)
		(width 0.127)
		(layer "In4.Cu")
		(net "RST_BMC_FROM_SWB_ISO_N")
	)
	(segment
		(start 295.012872 -389.74268)
		(end 291.561012 -389.74268)
		(width 0.127)
		(layer "In4.Cu")
		(net "RST_BMC_FROM_SWB_ISO_N")
	)
	(segment
		(start 289.445192 -387.62686)
		(end 288.23666 -387.62686)
		(width 0.127)
		(layer "In4.Cu")
		(net "RST_BMC_FROM_SWB_ISO_N")
	)
	(segment
		(start 228.74478 -195.645024)
		(end 228.74478 -172.532294)
		(width 0.127)
		(layer "In11.Cu")
		(net "RST_BMC_FROM_SWB_ISO_N")
	)
	(segment
		(start 355.521514 -389.862568)
		(end 353.133914 -392.250168)
		(width 0.127)
		(layer "In11.Cu")
		(net "RST_BMC_FROM_SWB_ISO_N")
	)
	(segment
		(start 160.96488 -110.708948)
		(end 160.96488 -125.186948)
		(width 0.127)
		(layer "In11.Cu")
		(net "RST_BMC_FROM_SWB_ISO_N")
	)
	(segment
		(start 353.133914 -392.250168)
		(end 301.68088 -392.250168)
		(width 0.127)
		(layer "In11.Cu")
		(net "RST_BMC_FROM_SWB_ISO_N")
	)
	(segment
		(start 228.74478 -172.532294)
		(end 214.929212 -158.716726)
		(width 0.127)
		(layer "In11.Cu")
		(net "RST_BMC_FROM_SWB_ISO_N")
	)
	(segment
		(start 158.9786 -109.611668)
		(end 159.56788 -110.200948)
		(width 0.127)
		(layer "In11.Cu")
		(net "RST_BMC_FROM_SWB_ISO_N")
	)
	(segment
		(start 414.35528 -392.115548)
		(end 376.395234 -392.115548)
		(width 0.127)
		(layer "In11.Cu")
		(net "RST_BMC_FROM_SWB_ISO_N")
	)
	(segment
		(start 238.346234 -205.564994)
		(end 238.346234 -205.246478)
		(width 0.127)
		(layer "In11.Cu")
		(net "RST_BMC_FROM_SWB_ISO_N")
	)
	(segment
		(start 160.45688 -110.200948)
		(end 160.96488 -110.708948)
		(width 0.127)
		(layer "In11.Cu")
		(net "RST_BMC_FROM_SWB_ISO_N")
	)
	(segment
		(start 421.49268 -384.978148)
		(end 414.35528 -392.115548)
		(width 0.127)
		(layer "In11.Cu")
		(net "RST_BMC_FROM_SWB_ISO_N")
	)
	(segment
		(start 158.9786 -109.4867)
		(end 158.9786 -109.611668)
		(width 0.127)
		(layer "In11.Cu")
		(net "RST_BMC_FROM_SWB_ISO_N")
	)
	(segment
		(start 424.99788 -384.978148)
		(end 421.49268 -384.978148)
		(width 0.127)
		(layer "In11.Cu")
		(net "RST_BMC_FROM_SWB_ISO_N")
	)
	(segment
		(start 426.269912 -380.568962)
		(end 425.60748 -381.231394)
		(width 0.127)
		(layer "In11.Cu")
		(net "RST_BMC_FROM_SWB_ISO_N")
	)
	(segment
		(start 200.637648 -129.71018)
		(end 201.47788 -128.869948)
		(width 0.127)
		(layer "In11.Cu")
		(net "RST_BMC_FROM_SWB_ISO_N")
	)
	(segment
		(start 159.56788 -110.200948)
		(end 160.45688 -110.200948)
		(width 0.127)
		(layer "In11.Cu")
		(net "RST_BMC_FROM_SWB_ISO_N")
	)
	(segment
		(start 425.60748 -381.231394)
		(end 425.60748 -384.368548)
		(width 0.127)
		(layer "In11.Cu")
		(net "RST_BMC_FROM_SWB_ISO_N")
	)
	(segment
		(start 201.47788 -128.869948)
		(end 201.47788 -125.313948)
		(width 0.127)
		(layer "In11.Cu")
		(net "RST_BMC_FROM_SWB_ISO_N")
	)
	(segment
		(start 200.637648 -134.403338)
		(end 200.637648 -129.71018)
		(width 0.127)
		(layer "In11.Cu")
		(net "RST_BMC_FROM_SWB_ISO_N")
	)
	(segment
		(start 214.929212 -148.694902)
		(end 200.637648 -134.403338)
		(width 0.127)
		(layer "In11.Cu")
		(net "RST_BMC_FROM_SWB_ISO_N")
	)
	(segment
		(start 376.395234 -392.115548)
		(end 374.142254 -389.862568)
		(width 0.127)
		(layer "In11.Cu")
		(net "RST_BMC_FROM_SWB_ISO_N")
	)
	(segment
		(start 425.60748 -384.368548)
		(end 424.99788 -384.978148)
		(width 0.127)
		(layer "In11.Cu")
		(net "RST_BMC_FROM_SWB_ISO_N")
	)
	(segment
		(start 160.96488 -125.186948)
		(end 163.88588 -128.107948)
		(width 0.127)
		(layer "In11.Cu")
		(net "RST_BMC_FROM_SWB_ISO_N")
	)
	(segment
		(start 374.142254 -389.862568)
		(end 355.521514 -389.862568)
		(width 0.127)
		(layer "In11.Cu")
		(net "RST_BMC_FROM_SWB_ISO_N")
	)
	(segment
		(start 214.929212 -158.716726)
		(end 214.929212 -148.694902)
		(width 0.127)
		(layer "In11.Cu")
		(net "RST_BMC_FROM_SWB_ISO_N")
	)
	(segment
		(start 426.595032 -380.568962)
		(end 426.269912 -380.568962)
		(width 0.127)
		(layer "In11.Cu")
		(net "RST_BMC_FROM_SWB_ISO_N")
	)
	(segment
		(start 238.346234 -205.246478)
		(end 228.74478 -195.645024)
		(width 0.127)
		(layer "In11.Cu")
		(net "RST_BMC_FROM_SWB_ISO_N")
	)
	(segment
		(start 429.129952 -381.218948)
		(end 430.338992 -381.218948)
		(width 0.12954)
		(layer "F.Cu")
		(net "RST_BMC_FROM_SWB")
	)
	(segment
		(start 430.338992 -381.218948)
		(end 431.589942 -381.218948)
		(width 0.12954)
		(layer "F.Cu")
		(net "RST_BMC_FROM_SWB")
	)
	(segment
		(start 429.129952 -381.868934)
		(end 429.129952 -381.218948)
		(width 0.12954)
		(layer "F.Cu")
		(net "RST_BMC_FROM_SWB")
	)
	(via
		(at 430.338992 -381.218948)
		(size 0.762)
		(drill 0.381)
		(layers "F.Cu" "B.Cu")
		(net "RST_BMC_FROM_SWB")
	)
	(segment
		(start 167.398446 -73.754234)
		(end 166.57828 -73.754234)
		(width 0.12954)
		(layer "F.Cu")
		(net "RST_SMB_SWITCH_R_N")
	)
	(segment
		(start 168.00576 -74.361548)
		(end 167.398446 -73.754234)
		(width 0.12954)
		(layer "F.Cu")
		(net "RST_SMB_SWITCH_R_N")
	)
	(segment
		(start 189.7634 -91.7702)
		(end 189.1792 -91.186)
		(width 0.12954)
		(layer "F.Cu")
		(net "RST_SMB_SWITCH_R_N")
	)
	(segment
		(start 180.34 -90.7288)
		(end 179.6542 -90.7288)
		(width 0.12954)
		(layer "F.Cu")
		(net "RST_SMB_SWITCH_R_N")
	)
	(segment
		(start 179.6542 -90.7288)
		(end 178.987196 -90.061796)
		(width 0.12954)
		(layer "F.Cu")
		(net "RST_SMB_SWITCH_R_N")
	)
	(segment
		(start 180.7972 -91.186)
		(end 180.34 -90.7288)
		(width 0.12954)
		(layer "F.Cu")
		(net "RST_SMB_SWITCH_R_N")
	)
	(segment
		(start 178.987196 -86.16315)
		(end 168.00576 -75.181714)
		(width 0.12954)
		(layer "F.Cu")
		(net "RST_SMB_SWITCH_R_N")
	)
	(segment
		(start 188.65088 -96.586548)
		(end 189.7634 -95.474028)
		(width 0.12954)
		(layer "F.Cu")
		(net "RST_SMB_SWITCH_R_N")
	)
	(segment
		(start 189.7634 -95.474028)
		(end 189.7634 -91.7702)
		(width 0.12954)
		(layer "F.Cu")
		(net "RST_SMB_SWITCH_R_N")
	)
	(segment
		(start 178.987196 -90.061796)
		(end 178.987196 -86.16315)
		(width 0.12954)
		(layer "F.Cu")
		(net "RST_SMB_SWITCH_R_N")
	)
	(segment
		(start 189.1792 -91.186)
		(end 180.7972 -91.186)
		(width 0.12954)
		(layer "F.Cu")
		(net "RST_SMB_SWITCH_R_N")
	)
	(segment
		(start 168.00576 -75.181714)
		(end 168.00576 -74.361548)
		(width 0.12954)
		(layer "F.Cu")
		(net "RST_SMB_SWITCH_R_N")
	)
	(via
		(at 188.65088 -96.586548)
		(size 0.508)
		(drill 0.254)
		(layers "F.Cu" "B.Cu")
		(net "RST_SMB_SWITCH_R_N")
	)
	(via
		(at 239.2934 -424.4594)
		(size 0.762)
		(drill 0.254)
		(layers "F.Cu" "B.Cu")
		(net "RST_SMB_SWITCH_R_N")
	)
	(via
		(at 249.05589 -135.291322)
		(size 0.508)
		(drill 0.254)
		(layers "F.Cu" "B.Cu")
		(net "RST_SMB_SWITCH_R_N")
	)
	(segment
		(start 237.2614 -425.41825)
		(end 237.2614 -431.85334)
		(width 0.12954)
		(layer "B.Cu")
		(net "RST_SMB_SWITCH_R_N")
	)
	(segment
		(start 237.2614 -431.85334)
		(end 238.45012 -433.04206)
		(width 0.12954)
		(layer "B.Cu")
		(net "RST_SMB_SWITCH_R_N")
	)
	(segment
		(start 239.2934 -424.4594)
		(end 239.2934 -423.38625)
		(width 0.12954)
		(layer "B.Cu")
		(net "RST_SMB_SWITCH_R_N")
	)
	(segment
		(start 239.2934 -423.38625)
		(end 237.2614 -425.41825)
		(width 0.12954)
		(layer "B.Cu")
		(net "RST_SMB_SWITCH_R_N")
	)
	(segment
		(start 272.22831 -387.71195)
		(end 273.66468 -386.27558)
		(width 0.127)
		(layer "In2.Cu")
		(net "RST_SMB_SWITCH_R_N")
	)
	(segment
		(start 287.01492 -411.55366)
		(end 283.52496 -411.55366)
		(width 0.127)
		(layer "In2.Cu")
		(net "RST_SMB_SWITCH_R_N")
	)
	(segment
		(start 268.406372 -360.6673)
		(end 268.406372 -385.988052)
		(width 0.127)
		(layer "In2.Cu")
		(net "RST_SMB_SWITCH_R_N")
	)
	(segment
		(start 296.9768 -385.36372)
		(end 298.04868 -386.4356)
		(width 0.127)
		(layer "In2.Cu")
		(net "RST_SMB_SWITCH_R_N")
	)
	(segment
		(start 252.55728 -324.8406)
		(end 252.55728 -328.056494)
		(width 0.127)
		(layer "In2.Cu")
		(net "RST_SMB_SWITCH_R_N")
	)
	(segment
		(start 284.80766 -385.36372)
		(end 296.9768 -385.36372)
		(width 0.127)
		(layer "In2.Cu")
		(net "RST_SMB_SWITCH_R_N")
	)
	(segment
		(start 291.51326 -406.21966)
		(end 291.02431 -406.70861)
		(width 0.127)
		(layer "In2.Cu")
		(net "RST_SMB_SWITCH_R_N")
	)
	(segment
		(start 247.759474 -136.587738)
		(end 247.759474 -136.983216)
		(width 0.127)
		(layer "In2.Cu")
		(net "RST_SMB_SWITCH_R_N")
	)
	(segment
		(start 246.68988 -148.506688)
		(end 253.6952 -155.512008)
		(width 0.127)
		(layer "In2.Cu")
		(net "RST_SMB_SWITCH_R_N")
	)
	(segment
		(start 296.94378 -399.67662)
		(end 296.94378 -404.36038)
		(width 0.127)
		(layer "In2.Cu")
		(net "RST_SMB_SWITCH_R_N")
	)
	(segment
		(start 254.24257 -329.741784)
		(end 254.24257 -346.503498)
		(width 0.127)
		(layer "In2.Cu")
		(net "RST_SMB_SWITCH_R_N")
	)
	(segment
		(start 291.02431 -407.54427)
		(end 287.01492 -411.55366)
		(width 0.127)
		(layer "In2.Cu")
		(net "RST_SMB_SWITCH_R_N")
	)
	(segment
		(start 252.55728 -328.056494)
		(end 254.24257 -329.741784)
		(width 0.127)
		(layer "In2.Cu")
		(net "RST_SMB_SWITCH_R_N")
	)
	(segment
		(start 280.10866 -420.01694)
		(end 277.57374 -420.01694)
		(width 0.127)
		(layer "In2.Cu")
		(net "RST_SMB_SWITCH_R_N")
	)
	(segment
		(start 277.57374 -420.01694)
		(end 273.6977 -423.89298)
		(width 0.127)
		(layer "In2.Cu")
		(net "RST_SMB_SWITCH_R_N")
	)
	(segment
		(start 283.52496 -411.55366)
		(end 282.23972 -412.8389)
		(width 0.127)
		(layer "In2.Cu")
		(net "RST_SMB_SWITCH_R_N")
	)
	(segment
		(start 291.02431 -406.70861)
		(end 291.02431 -407.54427)
		(width 0.127)
		(layer "In2.Cu")
		(net "RST_SMB_SWITCH_R_N")
	)
	(segment
		(start 283.8958 -386.27558)
		(end 284.80766 -385.36372)
		(width 0.127)
		(layer "In2.Cu")
		(net "RST_SMB_SWITCH_R_N")
	)
	(segment
		(start 273.6977 -423.89298)
		(end 239.85982 -423.89298)
		(width 0.127)
		(layer "In2.Cu")
		(net "RST_SMB_SWITCH_R_N")
	)
	(segment
		(start 282.23972 -412.8389)
		(end 282.23972 -417.88588)
		(width 0.127)
		(layer "In2.Cu")
		(net "RST_SMB_SWITCH_R_N")
	)
	(segment
		(start 253.6952 -155.512008)
		(end 253.6952 -323.70268)
		(width 0.127)
		(layer "In2.Cu")
		(net "RST_SMB_SWITCH_R_N")
	)
	(segment
		(start 270.13027 -387.71195)
		(end 272.22831 -387.71195)
		(width 0.127)
		(layer "In2.Cu")
		(net "RST_SMB_SWITCH_R_N")
	)
	(segment
		(start 239.85982 -423.89298)
		(end 239.2934 -424.4594)
		(width 0.127)
		(layer "In2.Cu")
		(net "RST_SMB_SWITCH_R_N")
	)
	(segment
		(start 254.24257 -346.503498)
		(end 268.406372 -360.6673)
		(width 0.127)
		(layer "In2.Cu")
		(net "RST_SMB_SWITCH_R_N")
	)
	(segment
		(start 273.66468 -386.27558)
		(end 283.8958 -386.27558)
		(width 0.127)
		(layer "In2.Cu")
		(net "RST_SMB_SWITCH_R_N")
	)
	(segment
		(start 295.0845 -406.21966)
		(end 291.51326 -406.21966)
		(width 0.127)
		(layer "In2.Cu")
		(net "RST_SMB_SWITCH_R_N")
	)
	(segment
		(start 282.23972 -417.88588)
		(end 280.10866 -420.01694)
		(width 0.127)
		(layer "In2.Cu")
		(net "RST_SMB_SWITCH_R_N")
	)
	(segment
		(start 298.04868 -387.28904)
		(end 296.98696 -388.35076)
		(width 0.127)
		(layer "In2.Cu")
		(net "RST_SMB_SWITCH_R_N")
	)
	(segment
		(start 246.68988 -138.05281)
		(end 246.68988 -148.506688)
		(width 0.127)
		(layer "In2.Cu")
		(net "RST_SMB_SWITCH_R_N")
	)
	(segment
		(start 298.1833 -391.37082)
		(end 298.1833 -398.4371)
		(width 0.127)
		(layer "In2.Cu")
		(net "RST_SMB_SWITCH_R_N")
	)
	(segment
		(start 296.94378 -404.36038)
		(end 295.0845 -406.21966)
		(width 0.127)
		(layer "In2.Cu")
		(net "RST_SMB_SWITCH_R_N")
	)
	(segment
		(start 268.406372 -385.988052)
		(end 270.13027 -387.71195)
		(width 0.127)
		(layer "In2.Cu")
		(net "RST_SMB_SWITCH_R_N")
	)
	(segment
		(start 249.05589 -135.291322)
		(end 247.759474 -136.587738)
		(width 0.127)
		(layer "In2.Cu")
		(net "RST_SMB_SWITCH_R_N")
	)
	(segment
		(start 247.759474 -136.983216)
		(end 246.68988 -138.05281)
		(width 0.127)
		(layer "In2.Cu")
		(net "RST_SMB_SWITCH_R_N")
	)
	(segment
		(start 296.98696 -388.35076)
		(end 296.98696 -390.17448)
		(width 0.127)
		(layer "In2.Cu")
		(net "RST_SMB_SWITCH_R_N")
	)
	(segment
		(start 298.04868 -386.4356)
		(end 298.04868 -387.28904)
		(width 0.127)
		(layer "In2.Cu")
		(net "RST_SMB_SWITCH_R_N")
	)
	(segment
		(start 298.1833 -398.4371)
		(end 296.94378 -399.67662)
		(width 0.127)
		(layer "In2.Cu")
		(net "RST_SMB_SWITCH_R_N")
	)
	(segment
		(start 253.6952 -323.70268)
		(end 252.55728 -324.8406)
		(width 0.127)
		(layer "In2.Cu")
		(net "RST_SMB_SWITCH_R_N")
	)
	(segment
		(start 296.98696 -390.17448)
		(end 298.1833 -391.37082)
		(width 0.127)
		(layer "In2.Cu")
		(net "RST_SMB_SWITCH_R_N")
	)
	(segment
		(start 212.74278 -114.430048)
		(end 212.74278 -112.52962)
		(width 0.127)
		(layer "In11.Cu")
		(net "RST_SMB_SWITCH_R_N")
	)
	(segment
		(start 210.21294 -105.664)
		(end 207.776572 -105.664)
		(width 0.127)
		(layer "In11.Cu")
		(net "RST_SMB_SWITCH_R_N")
	)
	(segment
		(start 202.03922 -105.428288)
		(end 200.96988 -104.358948)
		(width 0.127)
		(layer "In11.Cu")
		(net "RST_SMB_SWITCH_R_N")
	)
	(segment
		(start 249.05589 -135.291322)
		(end 249.091958 -135.255254)
		(width 0.127)
		(layer "In11.Cu")
		(net "RST_SMB_SWITCH_R_N")
	)
	(segment
		(start 215.98128 -106.364024)
		(end 215.045544 -105.428288)
		(width 0.127)
		(layer "In11.Cu")
		(net "RST_SMB_SWITCH_R_N")
	)
	(segment
		(start 189.05728 -96.992948)
		(end 188.65088 -96.586548)
		(width 0.127)
		(layer "In11.Cu")
		(net "RST_SMB_SWITCH_R_N")
	)
	(segment
		(start 215.98128 -109.29112)
		(end 215.98128 -106.364024)
		(width 0.127)
		(layer "In11.Cu")
		(net "RST_SMB_SWITCH_R_N")
	)
	(segment
		(start 215.045544 -105.428288)
		(end 210.448652 -105.428288)
		(width 0.127)
		(layer "In11.Cu")
		(net "RST_SMB_SWITCH_R_N")
	)
	(segment
		(start 249.091958 -132.336794)
		(end 247.969532 -131.214368)
		(width 0.127)
		(layer "In11.Cu")
		(net "RST_SMB_SWITCH_R_N")
	)
	(segment
		(start 247.969532 -131.214368)
		(end 247.969532 -129.540508)
		(width 0.127)
		(layer "In11.Cu")
		(net "RST_SMB_SWITCH_R_N")
	)
	(segment
		(start 191.31788 -96.992948)
		(end 189.05728 -96.992948)
		(width 0.127)
		(layer "In11.Cu")
		(net "RST_SMB_SWITCH_R_N")
	)
	(segment
		(start 192.71488 -98.389948)
		(end 191.31788 -96.992948)
		(width 0.127)
		(layer "In11.Cu")
		(net "RST_SMB_SWITCH_R_N")
	)
	(segment
		(start 193.97218 -101.818948)
		(end 192.71488 -100.561648)
		(width 0.127)
		(layer "In11.Cu")
		(net "RST_SMB_SWITCH_R_N")
	)
	(segment
		(start 192.71488 -100.561648)
		(end 192.71488 -98.389948)
		(width 0.127)
		(layer "In11.Cu")
		(net "RST_SMB_SWITCH_R_N")
	)
	(segment
		(start 248.24182 -122.293888)
		(end 241.02568 -115.077748)
		(width 0.127)
		(layer "In11.Cu")
		(net "RST_SMB_SWITCH_R_N")
	)
	(segment
		(start 241.02568 -115.077748)
		(end 215.42248 -115.077748)
		(width 0.127)
		(layer "In11.Cu")
		(net "RST_SMB_SWITCH_R_N")
	)
	(segment
		(start 213.75116 -114.785648)
		(end 213.09838 -114.785648)
		(width 0.127)
		(layer "In11.Cu")
		(net "RST_SMB_SWITCH_R_N")
	)
	(segment
		(start 247.969532 -129.540508)
		(end 248.24182 -129.26822)
		(width 0.127)
		(layer "In11.Cu")
		(net "RST_SMB_SWITCH_R_N")
	)
	(segment
		(start 207.54086 -105.428288)
		(end 202.03922 -105.428288)
		(width 0.127)
		(layer "In11.Cu")
		(net "RST_SMB_SWITCH_R_N")
	)
	(segment
		(start 212.74278 -112.52962)
		(end 215.98128 -109.29112)
		(width 0.127)
		(layer "In11.Cu")
		(net "RST_SMB_SWITCH_R_N")
	)
	(segment
		(start 248.24182 -129.26822)
		(end 248.24182 -122.293888)
		(width 0.127)
		(layer "In11.Cu")
		(net "RST_SMB_SWITCH_R_N")
	)
	(segment
		(start 213.09838 -114.785648)
		(end 212.74278 -114.430048)
		(width 0.127)
		(layer "In11.Cu")
		(net "RST_SMB_SWITCH_R_N")
	)
	(segment
		(start 199.57288 -104.358948)
		(end 197.03288 -101.818948)
		(width 0.127)
		(layer "In11.Cu")
		(net "RST_SMB_SWITCH_R_N")
	)
	(segment
		(start 214.9983 -114.653568)
		(end 213.88324 -114.653568)
		(width 0.127)
		(layer "In11.Cu")
		(net "RST_SMB_SWITCH_R_N")
	)
	(segment
		(start 197.03288 -101.818948)
		(end 193.97218 -101.818948)
		(width 0.127)
		(layer "In11.Cu")
		(net "RST_SMB_SWITCH_R_N")
	)
	(segment
		(start 249.091958 -135.255254)
		(end 249.091958 -132.336794)
		(width 0.127)
		(layer "In11.Cu")
		(net "RST_SMB_SWITCH_R_N")
	)
	(segment
		(start 200.96988 -104.358948)
		(end 199.57288 -104.358948)
		(width 0.127)
		(layer "In11.Cu")
		(net "RST_SMB_SWITCH_R_N")
	)
	(segment
		(start 215.42248 -115.077748)
		(end 214.9983 -114.653568)
		(width 0.127)
		(layer "In11.Cu")
		(net "RST_SMB_SWITCH_R_N")
	)
	(segment
		(start 213.88324 -114.653568)
		(end 213.75116 -114.785648)
		(width 0.127)
		(layer "In11.Cu")
		(net "RST_SMB_SWITCH_R_N")
	)
	(segment
		(start 207.776572 -105.664)
		(end 207.54086 -105.428288)
		(width 0.127)
		(layer "In11.Cu")
		(net "RST_SMB_SWITCH_R_N")
	)
	(segment
		(start 210.448652 -105.428288)
		(end 210.21294 -105.664)
		(width 0.127)
		(layer "In11.Cu")
		(net "RST_SMB_SWITCH_R_N")
	)
	(segment
		(start 11.87323 -52.999894)
		(end 10.4775 -52.999894)
		(width 0.12954)
		(layer "F.Cu")
		(net "RST_RSMRST_NM_HDR_N")
	)
	(segment
		(start 10.4775 -52.999894)
		(end 10.401554 -52.923948)
		(width 0.12954)
		(layer "F.Cu")
		(net "RST_RSMRST_NM_HDR_N")
	)
	(segment
		(start 10.401554 -52.923948)
		(end 9.98093 -52.923948)
		(width 0.12954)
		(layer "F.Cu")
		(net "RST_RSMRST_NM_HDR_N")
	)
	(segment
		(start 15.774924 -52.999894)
		(end 11.87323 -52.999894)
		(width 0.12954)
		(layer "F.Cu")
		(net "RST_RSMRST_NM_HDR_N")
	)
	(via
		(at 11.87323 -52.999894)
		(size 0.762)
		(drill 0.381)
		(layers "F.Cu" "B.Cu")
		(net "RST_RSMRST_NM_HDR_N")
	)
	(segment
		(start 170.59148 -423.748962)
		(end 169.990516 -423.748962)
		(width 0.12954)
		(layer "F.Cu")
		(net "RST_SWB_BIC_R_N")
	)
	(segment
		(start 169.84853 -422.874948)
		(end 169.84853 -422.20769)
		(width 0.12954)
		(layer "F.Cu")
		(net "RST_SWB_BIC_R_N")
	)
	(segment
		(start 169.84853 -422.874948)
		(end 169.84853 -423.890948)
		(width 0.12954)
		(layer "F.Cu")
		(net "RST_SWB_BIC_R_N")
	)
	(segment
		(start 17.864582 -407.153618)
		(end 17.864582 -410.402786)
		(width 0.12954)
		(layer "F.Cu")
		(net "RST_SWB_BIC_R_N")
	)
	(segment
		(start 169.990516 -423.748962)
		(end 169.84853 -423.890948)
		(width 0.12954)
		(layer "F.Cu")
		(net "RST_SWB_BIC_R_N")
	)
	(segment
		(start 171.41952 -423.748962)
		(end 170.59148 -423.748962)
		(width 0.12954)
		(layer "F.Cu")
		(net "RST_SWB_BIC_R_N")
	)
	(segment
		(start 18.338292 -406.679908)
		(end 17.864582 -407.153618)
		(width 0.12954)
		(layer "F.Cu")
		(net "RST_SWB_BIC_R_N")
	)
	(segment
		(start 19.56816 -406.679908)
		(end 18.338292 -406.679908)
		(width 0.12954)
		(layer "F.Cu")
		(net "RST_SWB_BIC_R_N")
	)
	(via
		(at 169.84853 -422.20769)
		(size 0.508)
		(drill 0.254)
		(layers "F.Cu" "B.Cu")
		(net "RST_SWB_BIC_R_N")
	)
	(via
		(at 19.56816 -406.679908)
		(size 0.762)
		(drill 0.254)
		(layers "F.Cu" "B.Cu")
		(net "RST_SWB_BIC_R_N")
	)
	(via
		(at 170.59148 -423.748962)
		(size 0.508)
		(drill 0.254)
		(layers "F.Cu" "B.Cu")
		(net "RST_SWB_BIC_R_N")
	)
	(segment
		(start 40.49776 -382.38684)
		(end 102.6668 -382.38684)
		(width 0.12954)
		(layer "B.Cu")
		(net "RST_SWB_BIC_R_N")
	)
	(segment
		(start 171.6532 -399.5166)
		(end 171.6532 -410.48432)
		(width 0.12954)
		(layer "B.Cu")
		(net "RST_SWB_BIC_R_N")
	)
	(segment
		(start 116.6114 -393.623546)
		(end 118.998746 -393.623546)
		(width 0.12954)
		(layer "B.Cu")
		(net "RST_SWB_BIC_R_N")
	)
	(segment
		(start 121.92 -396.5448)
		(end 170.18 -396.5448)
		(width 0.12954)
		(layer "B.Cu")
		(net "RST_SWB_BIC_R_N")
	)
	(segment
		(start 25.418034 -386.920994)
		(end 29.119068 -383.21996)
		(width 0.12954)
		(layer "B.Cu")
		(net "RST_SWB_BIC_R_N")
	)
	(segment
		(start 19.56816 -406.679908)
		(end 17.00276 -404.114508)
		(width 0.12954)
		(layer "B.Cu")
		(net "RST_SWB_BIC_R_N")
	)
	(segment
		(start 17.00276 -404.114508)
		(end 17.00276 -388.63778)
		(width 0.12954)
		(layer "B.Cu")
		(net "RST_SWB_BIC_R_N")
	)
	(segment
		(start 169.81932 -412.3182)
		(end 169.81932 -422.17848)
		(width 0.12954)
		(layer "B.Cu")
		(net "RST_SWB_BIC_R_N")
	)
	(segment
		(start 115.951254 -392.9634)
		(end 116.6114 -393.623546)
		(width 0.12954)
		(layer "B.Cu")
		(net "RST_SWB_BIC_R_N")
	)
	(segment
		(start 39.66464 -383.21996)
		(end 40.49776 -382.38684)
		(width 0.12954)
		(layer "B.Cu")
		(net "RST_SWB_BIC_R_N")
	)
	(segment
		(start 170.18 -396.5448)
		(end 171.0182 -397.383)
		(width 0.12954)
		(layer "B.Cu")
		(net "RST_SWB_BIC_R_N")
	)
	(segment
		(start 17.96542 -387.67512)
		(end 22.97176 -387.67512)
		(width 0.12954)
		(layer "B.Cu")
		(net "RST_SWB_BIC_R_N")
	)
	(segment
		(start 29.119068 -383.21996)
		(end 39.66464 -383.21996)
		(width 0.12954)
		(layer "B.Cu")
		(net "RST_SWB_BIC_R_N")
	)
	(segment
		(start 113.146332 -392.9634)
		(end 115.951254 -392.9634)
		(width 0.12954)
		(layer "B.Cu")
		(net "RST_SWB_BIC_R_N")
	)
	(segment
		(start 23.725886 -386.920994)
		(end 25.418034 -386.920994)
		(width 0.12954)
		(layer "B.Cu")
		(net "RST_SWB_BIC_R_N")
	)
	(segment
		(start 171.0182 -397.383)
		(end 171.0182 -398.8816)
		(width 0.12954)
		(layer "B.Cu")
		(net "RST_SWB_BIC_R_N")
	)
	(segment
		(start 169.81932 -422.17848)
		(end 169.84853 -422.20769)
		(width 0.12954)
		(layer "B.Cu")
		(net "RST_SWB_BIC_R_N")
	)
	(segment
		(start 109.83468 -389.651748)
		(end 113.146332 -392.9634)
		(width 0.12954)
		(layer "B.Cu")
		(net "RST_SWB_BIC_R_N")
	)
	(segment
		(start 22.97176 -387.67512)
		(end 23.725886 -386.920994)
		(width 0.12954)
		(layer "B.Cu")
		(net "RST_SWB_BIC_R_N")
	)
	(segment
		(start 171.6532 -410.48432)
		(end 169.81932 -412.3182)
		(width 0.12954)
		(layer "B.Cu")
		(net "RST_SWB_BIC_R_N")
	)
	(segment
		(start 171.0182 -398.8816)
		(end 171.6532 -399.5166)
		(width 0.12954)
		(layer "B.Cu")
		(net "RST_SWB_BIC_R_N")
	)
	(segment
		(start 109.83468 -389.55472)
		(end 109.83468 -389.651748)
		(width 0.12954)
		(layer "B.Cu")
		(net "RST_SWB_BIC_R_N")
	)
	(segment
		(start 102.6668 -382.38684)
		(end 109.83468 -389.55472)
		(width 0.12954)
		(layer "B.Cu")
		(net "RST_SWB_BIC_R_N")
	)
	(segment
		(start 118.998746 -393.623546)
		(end 121.92 -396.5448)
		(width 0.12954)
		(layer "B.Cu")
		(net "RST_SWB_BIC_R_N")
	)
	(segment
		(start 17.00276 -388.63778)
		(end 17.96542 -387.67512)
		(width 0.12954)
		(layer "B.Cu")
		(net "RST_SWB_BIC_R_N")
	)
	(segment
		(start 16.33982 -413.474408)
		(end 16.33982 -414.277302)
		(width 0.12954)
		(layer "F.Cu")
		(net "RST_SWB_BIC_N")
	)
	(segment
		(start 16.764 -412.4452)
		(end 16.764 -413.050228)
		(width 0.12954)
		(layer "F.Cu")
		(net "RST_SWB_BIC_N")
	)
	(segment
		(start 17.864582 -411.202886)
		(end 17.066514 -411.202886)
		(width 0.12954)
		(layer "F.Cu")
		(net "RST_SWB_BIC_N")
	)
	(segment
		(start 16.764 -413.050228)
		(end 16.33982 -413.474408)
		(width 0.12954)
		(layer "F.Cu")
		(net "RST_SWB_BIC_N")
	)
	(segment
		(start 16.764 -411.5054)
		(end 16.764 -412.4452)
		(width 0.12954)
		(layer "F.Cu")
		(net "RST_SWB_BIC_N")
	)
	(segment
		(start 17.066514 -411.202886)
		(end 16.764 -411.5054)
		(width 0.12954)
		(layer "F.Cu")
		(net "RST_SWB_BIC_N")
	)
	(via
		(at 16.764 -412.4452)
		(size 0.762)
		(drill 0.381)
		(layers "F.Cu" "B.Cu")
		(net "RST_SWB_BIC_N")
	)
	(segment
		(start 20.024852 -44.99991)
		(end 25.26792 -44.99991)
		(width 0.12954)
		(layer "F.Cu")
		(net "PWRGD_PS_PWROK_ME_CONN")
	)
	(segment
		(start 26.924 -47.335948)
		(end 27.686 -47.335948)
		(width 0.12954)
		(layer "F.Cu")
		(net "PWRGD_PS_PWROK_ME_CONN")
	)
	(segment
		(start 25.999694 -46.411642)
		(end 26.924 -47.335948)
		(width 0.12954)
		(layer "F.Cu")
		(net "PWRGD_PS_PWROK_ME_CONN")
	)
	(segment
		(start 25.26792 -44.99991)
		(end 25.999694 -45.731684)
		(width 0.12954)
		(layer "F.Cu")
		(net "PWRGD_PS_PWROK_ME_CONN")
	)
	(segment
		(start 25.999694 -45.731684)
		(end 25.999694 -46.411642)
		(width 0.12954)
		(layer "F.Cu")
		(net "PWRGD_PS_PWROK_ME_CONN")
	)
	(via
		(at 25.26792 -44.99991)
		(size 0.762)
		(drill 0.381)
		(layers "F.Cu" "B.Cu")
		(net "PWRGD_PS_PWROK_ME_CONN")
	)
	(segment
		(start 219.700602 -103.330248)
		(end 218.408504 -103.330248)
		(width 0.12954)
		(layer "F.Cu")
		(net "PWRGD_DSW_PWROK_R4")
	)
	(segment
		(start 218.355672 -103.38308)
		(end 218.408504 -103.330248)
		(width 0.12954)
		(layer "F.Cu")
		(net "PWRGD_DSW_PWROK_R4")
	)
	(segment
		(start 216.6874 -103.38308)
		(end 218.355672 -103.38308)
		(width 0.12954)
		(layer "F.Cu")
		(net "PWRGD_DSW_PWROK_R4")
	)
	(via
		(at 218.408504 -103.330248)
		(size 0.762)
		(drill 0.381)
		(layers "F.Cu" "B.Cu")
		(net "PWRGD_DSW_PWROK_R4")
	)
	(segment
		(start 123.473718 -358.860598)
		(end 123.169934 -358.964484)
		(width 0.1778)
		(layer "F.Cu")
		(net "PVPP_HBM_CPU1_MODE")
	)
	(segment
		(start 124.314966 -358.860598)
		(end 123.473718 -358.860598)
		(width 0.1778)
		(layer "F.Cu")
		(net "PVPP_HBM_CPU1_MODE")
	)
	(via
		(at 124.18568 -357.820468)
		(size 0.6604)
		(drill 0.3302)
		(layers "F.Cu" "B.Cu")
		(net "PVPP_HBM_CPU1_MODE")
	)
	(via
		(at 123.169934 -358.964484)
		(size 0.508)
		(drill 0.254)
		(layers "F.Cu" "B.Cu")
		(net "PVPP_HBM_CPU1_MODE")
	)
	(segment
		(start 124.18568 -357.820468)
		(end 123.491498 -358.51465)
		(width 0.12954)
		(layer "B.Cu")
		(net "PVPP_HBM_CPU1_MODE")
	)
	(segment
		(start 123.491498 -358.51465)
		(end 123.491498 -358.64292)
		(width 0.12954)
		(layer "B.Cu")
		(net "PVPP_HBM_CPU1_MODE")
	)
	(segment
		(start 124.18568 -358.875584)
		(end 124.18568 -357.820468)
		(width 0.12954)
		(layer "B.Cu")
		(net "PVPP_HBM_CPU1_MODE")
	)
	(segment
		(start 124.09678 -358.964484)
		(end 124.18568 -358.875584)
		(width 0.12954)
		(layer "B.Cu")
		(net "PVPP_HBM_CPU1_MODE")
	)
	(segment
		(start 123.491498 -358.64292)
		(end 123.169934 -358.964484)
		(width 0.12954)
		(layer "B.Cu")
		(net "PVPP_HBM_CPU1_MODE")
	)
	(segment
		(start 372.25478 -358.860598)
		(end 371.448838 -358.860598)
		(width 0.1778)
		(layer "F.Cu")
		(net "PVPP_HBM_CPU0_MODE")
	)
	(segment
		(start 371.448838 -358.860598)
		(end 371.109748 -358.964484)
		(width 0.1778)
		(layer "F.Cu")
		(net "PVPP_HBM_CPU0_MODE")
	)
	(via
		(at 371.109748 -358.964484)
		(size 0.508)
		(drill 0.254)
		(layers "F.Cu" "B.Cu")
		(net "PVPP_HBM_CPU0_MODE")
	)
	(segment
		(start 372.161562 -358.964484)
		(end 372.299738 -359.10266)
		(width 0.254)
		(layer "B.Cu")
		(net "PVPP_HBM_CPU0_MODE")
	)
	(segment
		(start 371.109748 -358.964484)
		(end 372.161562 -358.964484)
		(width 0.254)
		(layer "B.Cu")
		(net "PVPP_HBM_CPU0_MODE")
	)
	(segment
		(start 52.354226 -145.441924)
		(end 52.624482 -145.441924)
		(width 0.2286)
		(layer "F.Cu")
		(net "PVCCINFAON_CPU1_VOS2")
	)
	(segment
		(start 51.97094 -145.058638)
		(end 52.354226 -145.441924)
		(width 0.2286)
		(layer "F.Cu")
		(net "PVCCINFAON_CPU1_VOS2")
	)
	(via
		(at 51.97094 -145.058638)
		(size 0.508)
		(drill 0.254)
		(layers "F.Cu" "B.Cu")
		(net "PVCCINFAON_CPU1_VOS2")
	)
	(segment
		(start 52.752498 -144.812004)
		(end 52.752498 -144.180052)
		(width 0.2286)
		(layer "B.Cu")
		(net "PVCCINFAON_CPU1_VOS2")
	)
	(segment
		(start 52.752498 -144.180052)
		(end 52.35321 -143.780764)
		(width 0.2286)
		(layer "B.Cu")
		(net "PVCCINFAON_CPU1_VOS2")
	)
	(segment
		(start 52.35321 -143.780764)
		(end 52.35321 -143.759428)
		(width 0.2286)
		(layer "B.Cu")
		(net "PVCCINFAON_CPU1_VOS2")
	)
	(segment
		(start 52.505864 -145.058638)
		(end 52.752498 -144.812004)
		(width 0.2286)
		(layer "B.Cu")
		(net "PVCCINFAON_CPU1_VOS2")
	)
	(segment
		(start 51.97094 -145.058638)
		(end 52.505864 -145.058638)
		(width 0.2286)
		(layer "B.Cu")
		(net "PVCCINFAON_CPU1_VOS2")
	)
	(segment
		(start 52.354226 -154.077924)
		(end 51.97094 -153.694638)
		(width 0.2286)
		(layer "F.Cu")
		(net "PVCCINFAON_CPU1_VOS1")
	)
	(segment
		(start 52.624482 -154.077924)
		(end 52.354226 -154.077924)
		(width 0.2286)
		(layer "F.Cu")
		(net "PVCCINFAON_CPU1_VOS1")
	)
	(via
		(at 51.97094 -153.694638)
		(size 0.508)
		(drill 0.254)
		(layers "F.Cu" "B.Cu")
		(net "PVCCINFAON_CPU1_VOS1")
	)
	(segment
		(start 52.735226 -153.465276)
		(end 52.735226 -152.626822)
		(width 0.254)
		(layer "B.Cu")
		(net "PVCCINFAON_CPU1_VOS1")
	)
	(segment
		(start 52.735226 -152.626822)
		(end 52.758594 -152.603454)
		(width 0.254)
		(layer "B.Cu")
		(net "PVCCINFAON_CPU1_VOS1")
	)
	(segment
		(start 52.505864 -153.694638)
		(end 52.735226 -153.465276)
		(width 0.254)
		(layer "B.Cu")
		(net "PVCCINFAON_CPU1_VOS1")
	)
	(segment
		(start 51.97094 -153.694638)
		(end 52.505864 -153.694638)
		(width 0.254)
		(layer "B.Cu")
		(net "PVCCINFAON_CPU1_VOS1")
	)
	(segment
		(start 418.554916 -181.857904)
		(end 418.28466 -181.857904)
		(width 0.2286)
		(layer "F.Cu")
		(net "PVCCINFAON_CPU0_VOS2")
	)
	(segment
		(start 418.938202 -182.24119)
		(end 418.554916 -181.857904)
		(width 0.2286)
		(layer "F.Cu")
		(net "PVCCINFAON_CPU0_VOS2")
	)
	(via
		(at 418.938202 -182.24119)
		(size 0.508)
		(drill 0.254)
		(layers "F.Cu" "B.Cu")
		(net "PVCCINFAON_CPU0_VOS2")
	)
	(segment
		(start 418.170614 -182.473854)
		(end 418.170614 -183.327294)
		(width 0.2286)
		(layer "B.Cu")
		(net "PVCCINFAON_CPU0_VOS2")
	)
	(segment
		(start 418.938202 -182.24119)
		(end 418.403278 -182.24119)
		(width 0.2286)
		(layer "B.Cu")
		(net "PVCCINFAON_CPU0_VOS2")
	)
	(segment
		(start 418.403278 -182.24119)
		(end 418.170614 -182.473854)
		(width 0.2286)
		(layer "B.Cu")
		(net "PVCCINFAON_CPU0_VOS2")
	)
	(segment
		(start 418.554916 -173.221904)
		(end 418.28466 -173.221904)
		(width 0.2286)
		(layer "F.Cu")
		(net "PVCCINFAON_CPU0_VOS1")
	)
	(segment
		(start 418.938202 -173.60519)
		(end 418.554916 -173.221904)
		(width 0.2286)
		(layer "F.Cu")
		(net "PVCCINFAON_CPU0_VOS1")
	)
	(via
		(at 418.938202 -173.60519)
		(size 0.508)
		(drill 0.254)
		(layers "F.Cu" "B.Cu")
		(net "PVCCINFAON_CPU0_VOS1")
	)
	(segment
		(start 418.938202 -173.60519)
		(end 418.403278 -173.60519)
		(width 0.2286)
		(layer "B.Cu")
		(net "PVCCINFAON_CPU0_VOS1")
	)
	(segment
		(start 418.16401 -173.844458)
		(end 418.16401 -174.6631)
		(width 0.2286)
		(layer "B.Cu")
		(net "PVCCINFAON_CPU0_VOS1")
	)
	(segment
		(start 418.16401 -174.6631)
		(end 418.140642 -174.686468)
		(width 0.2286)
		(layer "B.Cu")
		(net "PVCCINFAON_CPU0_VOS1")
	)
	(segment
		(start 418.403278 -173.60519)
		(end 418.16401 -173.844458)
		(width 0.2286)
		(layer "B.Cu")
		(net "PVCCINFAON_CPU0_VOS1")
	)
	(segment
		(start 52.354226 -162.713924)
		(end 51.97094 -162.330638)
		(width 0.2286)
		(layer "F.Cu")
		(net "PVCCD_HV_CPU1_VOS")
	)
	(segment
		(start 52.624482 -162.713924)
		(end 52.354226 -162.713924)
		(width 0.2286)
		(layer "F.Cu")
		(net "PVCCD_HV_CPU1_VOS")
	)
	(via
		(at 51.97094 -162.330638)
		(size 0.508)
		(drill 0.254)
		(layers "F.Cu" "B.Cu")
		(net "PVCCD_HV_CPU1_VOS")
	)
	(segment
		(start 52.505864 -162.330638)
		(end 52.699666 -162.136836)
		(width 0.254)
		(layer "B.Cu")
		(net "PVCCD_HV_CPU1_VOS")
	)
	(segment
		(start 52.699666 -161.776664)
		(end 52.712366 -161.763964)
		(width 0.254)
		(layer "B.Cu")
		(net "PVCCD_HV_CPU1_VOS")
	)
	(segment
		(start 51.97094 -162.330638)
		(end 52.505864 -162.330638)
		(width 0.254)
		(layer "B.Cu")
		(net "PVCCD_HV_CPU1_VOS")
	)
	(segment
		(start 52.699666 -162.136836)
		(end 52.699666 -161.776664)
		(width 0.254)
		(layer "B.Cu")
		(net "PVCCD_HV_CPU1_VOS")
	)
	(segment
		(start 52.712366 -161.763964)
		(end 52.712366 -161.283396)
		(width 0.254)
		(layer "B.Cu")
		(net "PVCCD_HV_CPU1_VOS")
	)
	(segment
		(start 52.712366 -161.283396)
		(end 52.735734 -161.260028)
		(width 0.254)
		(layer "B.Cu")
		(net "PVCCD_HV_CPU1_VOS")
	)
	(segment
		(start 418.554916 -164.585904)
		(end 418.28466 -164.585904)
		(width 0.2286)
		(layer "F.Cu")
		(net "PVCCD_HV_CPU0_VOS")
	)
	(segment
		(start 418.938202 -164.96919)
		(end 418.554916 -164.585904)
		(width 0.2286)
		(layer "F.Cu")
		(net "PVCCD_HV_CPU0_VOS")
	)
	(via
		(at 418.938202 -164.96919)
		(size 0.508)
		(drill 0.254)
		(layers "F.Cu" "B.Cu")
		(net "PVCCD_HV_CPU0_VOS")
	)
	(segment
		(start 418.403278 -164.96919)
		(end 418.16401 -165.208458)
		(width 0.2286)
		(layer "B.Cu")
		(net "PVCCD_HV_CPU0_VOS")
	)
	(segment
		(start 418.16401 -166.026846)
		(end 418.140642 -166.050214)
		(width 0.2286)
		(layer "B.Cu")
		(net "PVCCD_HV_CPU0_VOS")
	)
	(segment
		(start 418.938202 -164.96919)
		(end 418.403278 -164.96919)
		(width 0.2286)
		(layer "B.Cu")
		(net "PVCCD_HV_CPU0_VOS")
	)
	(segment
		(start 418.16401 -165.208458)
		(end 418.16401 -166.026846)
		(width 0.2286)
		(layer "B.Cu")
		(net "PVCCD_HV_CPU0_VOS")
	)
	(segment
		(start 12.784582 -412.453836)
		(end 12.784582 -413.42183)
		(width 0.12954)
		(layer "F.Cu")
		(net "PU_U181_INT")
	)
	(segment
		(start 12.784582 -411.202886)
		(end 12.784582 -412.453836)
		(width 0.12954)
		(layer "F.Cu")
		(net "PU_U181_INT")
	)
	(segment
		(start 12.784582 -413.42183)
		(end 13.640054 -414.277302)
		(width 0.12954)
		(layer "F.Cu")
		(net "PU_U181_INT")
	)
	(via
		(at 12.784582 -412.453836)
		(size 0.762)
		(drill 0.381)
		(layers "F.Cu" "B.Cu")
		(net "PU_U181_INT")
	)
	(segment
		(start 15.324582 -411.329886)
		(end 15.197582 -411.202886)
		(width 0.12954)
		(layer "F.Cu")
		(net "PU_RST_SMB_U181_N")
	)
	(segment
		(start 15.039848 -413.50057)
		(end 15.324582 -413.215836)
		(width 0.12954)
		(layer "F.Cu")
		(net "PU_RST_SMB_U181_N")
	)
	(segment
		(start 15.324582 -413.215836)
		(end 15.324582 -412.453836)
		(width 0.12954)
		(layer "F.Cu")
		(net "PU_RST_SMB_U181_N")
	)
	(segment
		(start 15.039848 -414.277302)
		(end 15.039848 -413.50057)
		(width 0.12954)
		(layer "F.Cu")
		(net "PU_RST_SMB_U181_N")
	)
	(segment
		(start 15.324582 -412.453836)
		(end 15.324582 -411.329886)
		(width 0.12954)
		(layer "F.Cu")
		(net "PU_RST_SMB_U181_N")
	)
	(via
		(at 15.324582 -412.453836)
		(size 0.762)
		(drill 0.381)
		(layers "F.Cu" "B.Cu")
		(net "PU_RST_SMB_U181_N")
	)
	(segment
		(start 309.030624 -62.775592)
		(end 309.68188 -62.775592)
		(width 0.12954)
		(layer "F.Cu")
		(net "PECI_BMC_ME")
	)
	(segment
		(start 29.69768 -52.695348)
		(end 24.002238 -46.999906)
		(width 0.12954)
		(layer "F.Cu")
		(net "PECI_BMC_ME")
	)
	(segment
		(start 24.002238 -46.999906)
		(end 20.024852 -46.999906)
		(width 0.12954)
		(layer "F.Cu")
		(net "PECI_BMC_ME")
	)
	(via
		(at 309.68188 -62.775592)
		(size 0.508)
		(drill 0.254)
		(layers "F.Cu" "B.Cu")
		(net "PECI_BMC_ME")
	)
	(via
		(at 29.69768 -52.695348)
		(size 0.508)
		(drill 0.254)
		(layers "F.Cu" "B.Cu")
		(net "PECI_BMC_ME")
	)
	(segment
		(start 239.98047 -88.3539)
		(end 245.137432 -83.196938)
		(width 0.127)
		(layer "In6.Cu")
		(net "PECI_BMC_ME")
	)
	(segment
		(start 286.727646 -73.040494)
		(end 286.727646 -63.324994)
		(width 0.127)
		(layer "In6.Cu")
		(net "PECI_BMC_ME")
	)
	(segment
		(start 154.19324 -70.079108)
		(end 164.664898 -70.079108)
		(width 0.127)
		(layer "In6.Cu")
		(net "PECI_BMC_ME")
	)
	(segment
		(start 245.137432 -83.196938)
		(end 276.571202 -83.196938)
		(width 0.127)
		(layer "In6.Cu")
		(net "PECI_BMC_ME")
	)
	(segment
		(start 151.05888 -66.944748)
		(end 154.19324 -70.079108)
		(width 0.127)
		(layer "In6.Cu")
		(net "PECI_BMC_ME")
	)
	(segment
		(start 149.419056 -66.944748)
		(end 151.05888 -66.944748)
		(width 0.127)
		(layer "In6.Cu")
		(net "PECI_BMC_ME")
	)
	(segment
		(start 290.186872 -59.865768)
		(end 298.1325 -59.865768)
		(width 0.127)
		(layer "In6.Cu")
		(net "PECI_BMC_ME")
	)
	(segment
		(start 193.221864 -81.643474)
		(end 193.743834 -82.165444)
		(width 0.127)
		(layer "In6.Cu")
		(net "PECI_BMC_ME")
	)
	(segment
		(start 206.328518 -82.165444)
		(end 212.516974 -88.3539)
		(width 0.127)
		(layer "In6.Cu")
		(net "PECI_BMC_ME")
	)
	(segment
		(start 31.699708 -55.865776)
		(end 58.191908 -55.865776)
		(width 0.127)
		(layer "In6.Cu")
		(net "PECI_BMC_ME")
	)
	(segment
		(start 58.191908 -55.865776)
		(end 69.44868 -67.122548)
		(width 0.127)
		(layer "In6.Cu")
		(net "PECI_BMC_ME")
	)
	(segment
		(start 212.516974 -88.3539)
		(end 239.98047 -88.3539)
		(width 0.127)
		(layer "In6.Cu")
		(net "PECI_BMC_ME")
	)
	(segment
		(start 29.69768 -53.863748)
		(end 31.699708 -55.865776)
		(width 0.127)
		(layer "In6.Cu")
		(net "PECI_BMC_ME")
	)
	(segment
		(start 301.6377 -63.370968)
		(end 307.40096 -63.370968)
		(width 0.127)
		(layer "In6.Cu")
		(net "PECI_BMC_ME")
	)
	(segment
		(start 298.1325 -59.865768)
		(end 301.6377 -63.370968)
		(width 0.127)
		(layer "In6.Cu")
		(net "PECI_BMC_ME")
	)
	(segment
		(start 286.727646 -63.324994)
		(end 290.186872 -59.865768)
		(width 0.127)
		(layer "In6.Cu")
		(net "PECI_BMC_ME")
	)
	(segment
		(start 307.996336 -62.775592)
		(end 309.68188 -62.775592)
		(width 0.127)
		(layer "In6.Cu")
		(net "PECI_BMC_ME")
	)
	(segment
		(start 176.229264 -81.643474)
		(end 193.221864 -81.643474)
		(width 0.127)
		(layer "In6.Cu")
		(net "PECI_BMC_ME")
	)
	(segment
		(start 134.97052 -65.933828)
		(end 148.408136 -65.933828)
		(width 0.127)
		(layer "In6.Cu")
		(net "PECI_BMC_ME")
	)
	(segment
		(start 276.571202 -83.196938)
		(end 286.727646 -73.040494)
		(width 0.127)
		(layer "In6.Cu")
		(net "PECI_BMC_ME")
	)
	(segment
		(start 29.69768 -52.695348)
		(end 29.69768 -53.863748)
		(width 0.127)
		(layer "In6.Cu")
		(net "PECI_BMC_ME")
	)
	(segment
		(start 133.7818 -67.122548)
		(end 134.97052 -65.933828)
		(width 0.127)
		(layer "In6.Cu")
		(net "PECI_BMC_ME")
	)
	(segment
		(start 193.743834 -82.165444)
		(end 206.328518 -82.165444)
		(width 0.127)
		(layer "In6.Cu")
		(net "PECI_BMC_ME")
	)
	(segment
		(start 69.44868 -67.122548)
		(end 133.7818 -67.122548)
		(width 0.127)
		(layer "In6.Cu")
		(net "PECI_BMC_ME")
	)
	(segment
		(start 164.664898 -70.079108)
		(end 176.229264 -81.643474)
		(width 0.127)
		(layer "In6.Cu")
		(net "PECI_BMC_ME")
	)
	(segment
		(start 307.40096 -63.370968)
		(end 307.996336 -62.775592)
		(width 0.127)
		(layer "In6.Cu")
		(net "PECI_BMC_ME")
	)
	(segment
		(start 148.408136 -65.933828)
		(end 149.419056 -66.944748)
		(width 0.127)
		(layer "In6.Cu")
		(net "PECI_BMC_ME")
	)
	(via
		(at 14.71168 -112.700308)
		(size 0.6604)
		(drill 0.3302)
		(layers "F.Cu" "B.Cu")
		(net "PD_U5201_VREG")
	)
	(segment
		(start 14.71168 -112.700308)
		(end 15.831312 -112.700308)
		(width 0.12954)
		(layer "B.Cu")
		(net "PD_U5201_VREG")
	)
	(segment
		(start 13.754862 -112.11941)
		(end 14.33576 -112.700308)
		(width 0.12954)
		(layer "B.Cu")
		(net "PD_U5201_VREG")
	)
	(segment
		(start 15.831312 -112.700308)
		(end 15.837662 -112.693958)
		(width 0.12954)
		(layer "B.Cu")
		(net "PD_U5201_VREG")
	)
	(segment
		(start 14.33576 -112.700308)
		(end 14.71168 -112.700308)
		(width 0.12954)
		(layer "B.Cu")
		(net "PD_U5201_VREG")
	)
	(segment
		(start 12.876784 -112.11941)
		(end 13.754862 -112.11941)
		(width 0.12954)
		(layer "B.Cu")
		(net "PD_U5201_VREG")
	)
	(via
		(at 9.73836 -112.011968)
		(size 0.6604)
		(drill 0.3302)
		(layers "F.Cu" "B.Cu")
		(net "PD_U5201_RSTN")
	)
	(segment
		(start 8.59282 -112.04702)
		(end 9.065006 -112.519206)
		(width 0.12954)
		(layer "B.Cu")
		(net "PD_U5201_RSTN")
	)
	(segment
		(start 10.245598 -112.519206)
		(end 11.276584 -112.519206)
		(width 0.12954)
		(layer "B.Cu")
		(net "PD_U5201_RSTN")
	)
	(segment
		(start 9.73836 -112.011968)
		(end 10.245598 -112.519206)
		(width 0.12954)
		(layer "B.Cu")
		(net "PD_U5201_RSTN")
	)
	(segment
		(start 9.231122 -112.519206)
		(end 9.73836 -112.011968)
		(width 0.12954)
		(layer "B.Cu")
		(net "PD_U5201_RSTN")
	)
	(segment
		(start 9.065006 -112.519206)
		(end 9.231122 -112.519206)
		(width 0.12954)
		(layer "B.Cu")
		(net "PD_U5201_RSTN")
	)
	(via
		(at 9.80948 -113.589308)
		(size 0.6604)
		(drill 0.3302)
		(layers "F.Cu" "B.Cu")
		(net "PD_U5201_EQ")
	)
	(segment
		(start 8.83539 -112.919256)
		(end 9.139428 -112.919256)
		(width 0.12954)
		(layer "B.Cu")
		(net "PD_U5201_EQ")
	)
	(segment
		(start 9.139428 -112.919256)
		(end 9.80948 -113.589308)
		(width 0.12954)
		(layer "B.Cu")
		(net "PD_U5201_EQ")
	)
	(segment
		(start 9.80948 -113.589308)
		(end 10.479532 -112.919256)
		(width 0.12954)
		(layer "B.Cu")
		(net "PD_U5201_EQ")
	)
	(segment
		(start 10.479532 -112.919256)
		(end 11.276584 -112.919256)
		(width 0.12954)
		(layer "B.Cu")
		(net "PD_U5201_EQ")
	)
	(segment
		(start 8.59282 -113.161826)
		(end 8.83539 -112.919256)
		(width 0.12954)
		(layer "B.Cu")
		(net "PD_U5201_EQ")
	)
	(segment
		(start 379.863858 -103.17861)
		(end 380.335536 -103.650288)
		(width 0.12954)
		(layer "F.Cu")
		(net "PD_GTL2014_BMC_JTAG_DIR_2")
	)
	(segment
		(start 379.618494 -102.054152)
		(end 379.618494 -102.933246)
		(width 0.12954)
		(layer "F.Cu")
		(net "PD_GTL2014_BMC_JTAG_DIR_2")
	)
	(segment
		(start 380.335536 -103.650288)
		(end 380.335536 -105.083102)
		(width 0.12954)
		(layer "F.Cu")
		(net "PD_GTL2014_BMC_JTAG_DIR_2")
	)
	(segment
		(start 379.618494 -102.933246)
		(end 379.863858 -103.17861)
		(width 0.12954)
		(layer "F.Cu")
		(net "PD_GTL2014_BMC_JTAG_DIR_2")
	)
	(via
		(at 379.863858 -103.17861)
		(size 0.508)
		(drill 0.254)
		(layers "F.Cu" "B.Cu")
		(net "PD_GTL2014_BMC_JTAG_DIR_2")
	)
	(segment
		(start 67.685666 -112.70869)
		(end 67.693286 -112.70107)
		(width 0.12954)
		(layer "F.Cu")
		(net "PCA9548_PCIE0_ADDR2")
	)
	(segment
		(start 64.894968 -112.851438)
		(end 63.975742 -112.851438)
		(width 0.12954)
		(layer "F.Cu")
		(net "PCA9548_PCIE0_ADDR2")
	)
	(segment
		(start 67.693286 -112.70107)
		(end 67.693286 -111.65967)
		(width 0.12954)
		(layer "F.Cu")
		(net "PCA9548_PCIE0_ADDR2")
	)
	(segment
		(start 65.037716 -112.70869)
		(end 64.894968 -112.851438)
		(width 0.12954)
		(layer "F.Cu")
		(net "PCA9548_PCIE0_ADDR2")
	)
	(segment
		(start 66.792602 -112.70869)
		(end 65.037716 -112.70869)
		(width 0.12954)
		(layer "F.Cu")
		(net "PCA9548_PCIE0_ADDR2")
	)
	(segment
		(start 67.685666 -112.70869)
		(end 66.792602 -112.70869)
		(width 0.12954)
		(layer "F.Cu")
		(net "PCA9548_PCIE0_ADDR2")
	)
	(via
		(at 66.792602 -112.70869)
		(size 0.508)
		(drill 0.254)
		(layers "F.Cu" "B.Cu")
		(net "PCA9548_PCIE0_ADDR2")
	)
	(segment
		(start 57.625996 -114.15141)
		(end 58.37555 -114.15141)
		(width 0.12954)
		(layer "F.Cu")
		(net "PCA9548_PCIE0_ADDR1")
	)
	(segment
		(start 57.036716 -116.13769)
		(end 57.036716 -114.74069)
		(width 0.12954)
		(layer "F.Cu")
		(net "PCA9548_PCIE0_ADDR1")
	)
	(segment
		(start 54.642766 -116.134388)
		(end 53.966364 -116.81079)
		(width 0.12954)
		(layer "F.Cu")
		(net "PCA9548_PCIE0_ADDR1")
	)
	(segment
		(start 54.896766 -116.39169)
		(end 56.782716 -116.39169)
		(width 0.12954)
		(layer "F.Cu")
		(net "PCA9548_PCIE0_ADDR1")
	)
	(segment
		(start 56.782716 -116.39169)
		(end 57.036716 -116.13769)
		(width 0.12954)
		(layer "F.Cu")
		(net "PCA9548_PCIE0_ADDR1")
	)
	(segment
		(start 54.642766 -116.134388)
		(end 54.642766 -116.13769)
		(width 0.12954)
		(layer "F.Cu")
		(net "PCA9548_PCIE0_ADDR1")
	)
	(segment
		(start 57.036716 -114.74069)
		(end 57.625996 -114.15141)
		(width 0.12954)
		(layer "F.Cu")
		(net "PCA9548_PCIE0_ADDR1")
	)
	(segment
		(start 53.966364 -116.81079)
		(end 52.722526 -116.81079)
		(width 0.12954)
		(layer "F.Cu")
		(net "PCA9548_PCIE0_ADDR1")
	)
	(segment
		(start 54.642766 -116.13769)
		(end 54.896766 -116.39169)
		(width 0.12954)
		(layer "F.Cu")
		(net "PCA9548_PCIE0_ADDR1")
	)
	(segment
		(start 52.722526 -116.81079)
		(end 51.993546 -117.53977)
		(width 0.12954)
		(layer "F.Cu")
		(net "PCA9548_PCIE0_ADDR1")
	)
	(via
		(at 56.782716 -116.39169)
		(size 0.762)
		(drill 0.381)
		(layers "F.Cu" "B.Cu")
		(net "PCA9548_PCIE0_ADDR1")
	)
	(segment
		(start 457.44765 -382.46177)
		(end 457.3143 -382.32842)
		(width 0.2032)
		(layer "F.Cu")
		(net "P5V_AUX_MODE")
	)
	(segment
		(start 457.44765 -383.684272)
		(end 457.44765 -382.95707)
		(width 0.1778)
		(layer "F.Cu")
		(net "P5V_AUX_MODE")
	)
	(segment
		(start 457.44765 -382.95707)
		(end 457.44765 -382.46177)
		(width 0.2032)
		(layer "F.Cu")
		(net "P5V_AUX_MODE")
	)
	(via
		(at 457.3143 -382.32842)
		(size 0.508)
		(drill 0.254)
		(layers "F.Cu" "B.Cu")
		(net "P5V_AUX_MODE")
	)
	(segment
		(start 457.3143 -382.32842)
		(end 457.152756 -382.489964)
		(width 0.254)
		(layer "B.Cu")
		(net "P5V_AUX_MODE")
	)
	(segment
		(start 456.122786 -382.489964)
		(end 456.06843 -382.435608)
		(width 0.254)
		(layer "B.Cu")
		(net "P5V_AUX_MODE")
	)
	(segment
		(start 457.152756 -382.489964)
		(end 456.122786 -382.489964)
		(width 0.254)
		(layer "B.Cu")
		(net "P5V_AUX_MODE")
	)
	(via
		(at 44.064428 -103.015034)
		(size 0.762)
		(drill 0.381)
		(layers "F.Cu" "B.Cu")
		(net "P3V3_MAX11617_VDD")
	)
	(segment
		(start 451.447916 -75.054206)
		(end 451.17131 -74.7776)
		(width 0.12954)
		(layer "F.Cu")
		(net "P3V3_AUX_EN")
	)
	(segment
		(start 451.17131 -74.7776)
		(end 450.768974 -74.7776)
		(width 0.12954)
		(layer "F.Cu")
		(net "P3V3_AUX_EN")
	)
	(via
		(at 451.447916 -75.054206)
		(size 0.508)
		(drill 0.254)
		(layers "F.Cu" "B.Cu")
		(net "P3V3_AUX_EN")
	)
	(segment
		(start 449.503292 -77.738732)
		(end 448.251834 -77.738732)
		(width 0.12954)
		(layer "B.Cu")
		(net "P3V3_AUX_EN")
	)
	(segment
		(start 449.723764 -77.097636)
		(end 449.723764 -77.51826)
		(width 0.12954)
		(layer "B.Cu")
		(net "P3V3_AUX_EN")
	)
	(segment
		(start 448.826128 -82.172556)
		(end 448.826128 -78.313026)
		(width 0.12954)
		(layer "B.Cu")
		(net "P3V3_AUX_EN")
	)
	(segment
		(start 451.947026 -76.522834)
		(end 451.947026 -77.11567)
		(width 0.12954)
		(layer "B.Cu")
		(net "P3V3_AUX_EN")
	)
	(segment
		(start 452.247 -83.134962)
		(end 452.11746 -83.264502)
		(width 0.12954)
		(layer "B.Cu")
		(net "P3V3_AUX_EN")
	)
	(segment
		(start 449.723764 -77.51826)
		(end 449.503292 -77.738732)
		(width 0.12954)
		(layer "B.Cu")
		(net "P3V3_AUX_EN")
	)
	(segment
		(start 451.947026 -77.11567)
		(end 450.735954 -77.11567)
		(width 0.12954)
		(layer "B.Cu")
		(net "P3V3_AUX_EN")
	)
	(segment
		(start 450.732398 -77.119226)
		(end 450.710808 -77.097636)
		(width 0.12954)
		(layer "B.Cu")
		(net "P3V3_AUX_EN")
	)
	(segment
		(start 450.710808 -77.097636)
		(end 449.723764 -77.097636)
		(width 0.12954)
		(layer "B.Cu")
		(net "P3V3_AUX_EN")
	)
	(segment
		(start 448.251834 -77.738732)
		(end 448.22872 -77.715618)
		(width 0.12954)
		(layer "B.Cu")
		(net "P3V3_AUX_EN")
	)
	(segment
		(start 452.11746 -83.264502)
		(end 449.918074 -83.264502)
		(width 0.12954)
		(layer "B.Cu")
		(net "P3V3_AUX_EN")
	)
	(segment
		(start 451.447916 -75.054206)
		(end 451.447916 -76.023724)
		(width 0.12954)
		(layer "B.Cu")
		(net "P3V3_AUX_EN")
	)
	(segment
		(start 452.247 -82.231738)
		(end 452.247 -83.134962)
		(width 0.12954)
		(layer "B.Cu")
		(net "P3V3_AUX_EN")
	)
	(segment
		(start 451.447916 -76.023724)
		(end 451.947026 -76.522834)
		(width 0.12954)
		(layer "B.Cu")
		(net "P3V3_AUX_EN")
	)
	(segment
		(start 450.735954 -77.11567)
		(end 450.732398 -77.119226)
		(width 0.12954)
		(layer "B.Cu")
		(net "P3V3_AUX_EN")
	)
	(segment
		(start 448.826128 -78.313026)
		(end 448.251834 -77.738732)
		(width 0.12954)
		(layer "B.Cu")
		(net "P3V3_AUX_EN")
	)
	(segment
		(start 449.918074 -83.264502)
		(end 448.826128 -82.172556)
		(width 0.12954)
		(layer "B.Cu")
		(net "P3V3_AUX_EN")
	)
	(segment
		(start 262.104632 -72.841104)
		(end 262.104632 -73.88225)
		(width 0.1778)
		(layer "F.Cu")
		(net "P1V05_PCH_AUX_MODE")
	)
	(segment
		(start 262.104632 -73.88225)
		(end 262.208518 -73.986136)
		(width 0.1778)
		(layer "F.Cu")
		(net "P1V05_PCH_AUX_MODE")
	)
	(via
		(at 262.208518 -73.986136)
		(size 0.508)
		(drill 0.254)
		(layers "F.Cu" "B.Cu")
		(net "P1V05_PCH_AUX_MODE")
	)
	(via
		(at 262.19404 -74.811128)
		(size 0.6604)
		(drill 0.3302)
		(layers "F.Cu" "B.Cu")
		(net "P1V05_PCH_AUX_MODE")
	)
	(segment
		(start 262.71601 -75.333098)
		(end 263.398 -75.333098)
		(width 0.254)
		(layer "B.Cu")
		(net "P1V05_PCH_AUX_MODE")
	)
	(segment
		(start 262.208518 -74.79665)
		(end 262.19404 -74.811128)
		(width 0.254)
		(layer "B.Cu")
		(net "P1V05_PCH_AUX_MODE")
	)
	(segment
		(start 262.208518 -73.986136)
		(end 262.208518 -74.79665)
		(width 0.254)
		(layer "B.Cu")
		(net "P1V05_PCH_AUX_MODE")
	)
	(segment
		(start 262.19404 -74.811128)
		(end 262.71601 -75.333098)
		(width 0.254)
		(layer "B.Cu")
		(net "P1V05_PCH_AUX_MODE")
	)
	(segment
		(start 299.9232 -406.13076)
		(end 299.5168 -405.72436)
		(width 0.4572)
		(layer "F.Cu")
		(net "P12V_PSU")
	)
	(segment
		(start 290.72332 -415.798)
		(end 302.79848 -415.798)
		(width 0.4572)
		(layer "F.Cu")
		(net "P12V_PSU")
	)
	(segment
		(start 282.19654 -416.00628)
		(end 284.03804 -416.00628)
		(width 0.4572)
		(layer "F.Cu")
		(net "P12V_PSU")
	)
	(segment
		(start 299.5168 -405.72436)
		(end 299.5168 -396.939516)
		(width 0.4572)
		(layer "F.Cu")
		(net "P12V_PSU")
	)
	(segment
		(start 299.9232 -408.250644)
		(end 299.9232 -406.13076)
		(width 0.4572)
		(layer "F.Cu")
		(net "P12V_PSU")
	)
	(segment
		(start 284.88894 -415.15538)
		(end 290.0807 -415.15538)
		(width 0.4572)
		(layer "F.Cu")
		(net "P12V_PSU")
	)
	(segment
		(start 280.02484 -409.88488)
		(end 280.29916 -409.88488)
		(width 0.4572)
		(layer "F.Cu")
		(net "P12V_PSU")
	)
	(segment
		(start 280.29916 -409.88488)
		(end 281.46756 -411.05328)
		(width 0.4572)
		(layer "F.Cu")
		(net "P12V_PSU")
	)
	(segment
		(start 281.46756 -415.2773)
		(end 282.19654 -416.00628)
		(width 0.4572)
		(layer "F.Cu")
		(net "P12V_PSU")
	)
	(segment
		(start 298.0055 -395.428216)
		(end 298.0055 -392.595354)
		(width 0.4572)
		(layer "F.Cu")
		(net "P12V_PSU")
	)
	(segment
		(start 303.18456 -415.41192)
		(end 303.18456 -409.39212)
		(width 0.4572)
		(layer "F.Cu")
		(net "P12V_PSU")
	)
	(segment
		(start 303.18456 -409.39212)
		(end 302.6156 -408.82316)
		(width 0.4572)
		(layer "F.Cu")
		(net "P12V_PSU")
	)
	(segment
		(start 299.5168 -396.939516)
		(end 298.0055 -395.428216)
		(width 0.4572)
		(layer "F.Cu")
		(net "P12V_PSU")
	)
	(segment
		(start 300.495716 -408.82316)
		(end 299.9232 -408.250644)
		(width 0.4572)
		(layer "F.Cu")
		(net "P12V_PSU")
	)
	(segment
		(start 298.0055 -392.595354)
		(end 297.9801 -392.569954)
		(width 0.4572)
		(layer "F.Cu")
		(net "P12V_PSU")
	)
	(segment
		(start 290.0807 -415.15538)
		(end 290.72332 -415.798)
		(width 0.4572)
		(layer "F.Cu")
		(net "P12V_PSU")
	)
	(segment
		(start 302.6156 -408.82316)
		(end 300.495716 -408.82316)
		(width 0.4572)
		(layer "F.Cu")
		(net "P12V_PSU")
	)
	(segment
		(start 302.79848 -415.798)
		(end 303.18456 -415.41192)
		(width 0.4572)
		(layer "F.Cu")
		(net "P12V_PSU")
	)
	(segment
		(start 284.03804 -416.00628)
		(end 284.88894 -415.15538)
		(width 0.4572)
		(layer "F.Cu")
		(net "P12V_PSU")
	)
	(segment
		(start 281.46756 -411.05328)
		(end 281.46756 -415.2773)
		(width 0.4572)
		(layer "F.Cu")
		(net "P12V_PSU")
	)
	(via
		(at 253.152148 -413.22498)
		(size 0.508)
		(drill 0.254)
		(layers "F.Cu" "B.Cu")
		(net "P12V_PSU")
	)
	(via
		(at 242.067588 -413.18942)
		(size 0.508)
		(drill 0.254)
		(layers "F.Cu" "B.Cu")
		(net "P12V_PSU")
	)
	(via
		(at 220.739208 -406.576022)
		(size 0.508)
		(drill 0.254)
		(layers "F.Cu" "B.Cu")
		(net "P12V_PSU")
	)
	(via
		(at 253.152148 -412.46298)
		(size 0.508)
		(drill 0.254)
		(layers "F.Cu" "B.Cu")
		(net "P12V_PSU")
	)
	(via
		(at 266.883134 -412.506922)
		(size 0.508)
		(drill 0.254)
		(layers "F.Cu" "B.Cu")
		(net "P12V_PSU")
	)
	(via
		(at 269.169134 -411.744922)
		(size 0.508)
		(drill 0.254)
		(layers "F.Cu" "B.Cu")
		(net "P12V_PSU")
	)
	(via
		(at 261.176008 -412.46298)
		(size 0.508)
		(drill 0.254)
		(layers "F.Cu" "B.Cu")
		(net "P12V_PSU")
	)
	(via
		(at 269.169134 -414.030922)
		(size 0.508)
		(drill 0.254)
		(layers "F.Cu" "B.Cu")
		(net "P12V_PSU")
	)
	(via
		(at 186.818016 -408.005534)
		(size 0.508)
		(drill 0.254)
		(layers "F.Cu" "B.Cu")
		(net "P12V_PSU")
	)
	(via
		(at 242.829588 -412.42742)
		(size 0.508)
		(drill 0.254)
		(layers "F.Cu" "B.Cu")
		(net "P12V_PSU")
	)
	(via
		(at 208.547208 -408.379422)
		(size 0.508)
		(drill 0.254)
		(layers "F.Cu" "B.Cu")
		(net "P12V_PSU")
	)
	(via
		(at 261.938008 -411.70098)
		(size 0.508)
		(drill 0.254)
		(layers "F.Cu" "B.Cu")
		(net "P12V_PSU")
	)
	(via
		(at 245.877588 -411.66542)
		(size 0.508)
		(drill 0.254)
		(layers "F.Cu" "B.Cu")
		(net "P12V_PSU")
	)
	(via
		(at 260.414008 -411.70098)
		(size 0.508)
		(drill 0.254)
		(layers "F.Cu" "B.Cu")
		(net "P12V_PSU")
	)
	(via
		(at 270.693134 -414.030922)
		(size 0.508)
		(drill 0.254)
		(layers "F.Cu" "B.Cu")
		(net "P12V_PSU")
	)
	(via
		(at 209.309208 -409.420822)
		(size 0.508)
		(drill 0.254)
		(layers "F.Cu" "B.Cu")
		(net "P12V_PSU")
	)
	(via
		(at 279.374854 -411.785562)
		(size 0.508)
		(drill 0.254)
		(layers "F.Cu" "B.Cu")
		(net "P12V_PSU")
	)
	(via
		(at 242.829588 -413.95142)
		(size 0.508)
		(drill 0.254)
		(layers "F.Cu" "B.Cu")
		(net "P12V_PSU")
	)
	(via
		(at 269.931134 -411.744922)
		(size 0.508)
		(drill 0.254)
		(layers "F.Cu" "B.Cu")
		(net "P12V_PSU")
	)
	(via
		(at 200.172066 -401.419822)
		(size 0.508)
		(drill 0.254)
		(layers "F.Cu" "B.Cu")
		(net "P12V_PSU")
	)
	(via
		(at 200.165208 -405.814022)
		(size 0.508)
		(drill 0.254)
		(layers "F.Cu" "B.Cu")
		(net "P12V_PSU")
	)
	(via
		(at 229.883208 -408.379422)
		(size 0.508)
		(drill 0.254)
		(layers "F.Cu" "B.Cu")
		(net "P12V_PSU")
	)
	(via
		(at 277.088854 -414.071562)
		(size 0.508)
		(drill 0.254)
		(layers "F.Cu" "B.Cu")
		(net "P12V_PSU")
	)
	(via
		(at 199.403208 -409.420822)
		(size 0.508)
		(drill 0.254)
		(layers "F.Cu" "B.Cu")
		(net "P12V_PSU")
	)
	(via
		(at 276.326854 -414.833562)
		(size 0.508)
		(drill 0.254)
		(layers "F.Cu" "B.Cu")
		(net "P12V_PSU")
	)
	(via
		(at 251.628148 -413.22498)
		(size 0.508)
		(drill 0.254)
		(layers "F.Cu" "B.Cu")
		(net "P12V_PSU")
	)
	(via
		(at 187.580016 -409.580334)
		(size 0.508)
		(drill 0.254)
		(layers "F.Cu" "B.Cu")
		(net "P12V_PSU")
	)
	(via
		(at 198.749666 -401.419822)
		(size 0.508)
		(drill 0.254)
		(layers "F.Cu" "B.Cu")
		(net "P12V_PSU")
	)
	(via
		(at 222.263208 -408.379422)
		(size 0.508)
		(drill 0.254)
		(layers "F.Cu" "B.Cu")
		(net "P12V_PSU")
	)
	(via
		(at 190.628016 -408.818334)
		(size 0.508)
		(drill 0.254)
		(layers "F.Cu" "B.Cu")
		(net "P12V_PSU")
	)
	(via
		(at 221.501208 -406.576022)
		(size 0.508)
		(drill 0.254)
		(layers "F.Cu" "B.Cu")
		(net "P12V_PSU")
	)
	(via
		(at 185.491628 -401.419314)
		(size 0.508)
		(drill 0.254)
		(layers "F.Cu" "B.Cu")
		(net "P12V_PSU")
	)
	(via
		(at 279.374854 -414.833562)
		(size 0.508)
		(drill 0.254)
		(layers "F.Cu" "B.Cu")
		(net "P12V_PSU")
	)
	(via
		(at 278.612854 -412.547562)
		(size 0.508)
		(drill 0.254)
		(layers "F.Cu" "B.Cu")
		(net "P12V_PSU")
	)
	(via
		(at 242.829588 -413.18942)
		(size 0.508)
		(drill 0.254)
		(layers "F.Cu" "B.Cu")
		(net "P12V_PSU")
	)
	(via
		(at 268.407134 -413.268922)
		(size 0.508)
		(drill 0.254)
		(layers "F.Cu" "B.Cu")
		(net "P12V_PSU")
	)
	(via
		(at 200.172066 -404.025862)
		(size 0.508)
		(drill 0.254)
		(layers "F.Cu" "B.Cu")
		(net "P12V_PSU")
	)
	(via
		(at 258.890008 -411.70098)
		(size 0.508)
		(drill 0.254)
		(layers "F.Cu" "B.Cu")
		(net "P12V_PSU")
	)
	(via
		(at 209.417666 -402.722842)
		(size 0.508)
		(drill 0.254)
		(layers "F.Cu" "B.Cu")
		(net "P12V_PSU")
	)
	(via
		(at 209.309208 -405.814022)
		(size 0.508)
		(drill 0.254)
		(layers "F.Cu" "B.Cu")
		(net "P12V_PSU")
	)
	(via
		(at 270.693134 -414.792922)
		(size 0.508)
		(drill 0.254)
		(layers "F.Cu" "B.Cu")
		(net "P12V_PSU")
	)
	(via
		(at 245.877588 -412.42742)
		(size 0.508)
		(drill 0.254)
		(layers "F.Cu" "B.Cu")
		(net "P12V_PSU")
	)
	(via
		(at 186.818016 -409.580334)
		(size 0.508)
		(drill 0.254)
		(layers "F.Cu" "B.Cu")
		(net "P12V_PSU")
	)
	(via
		(at 220.085666 -401.419822)
		(size 0.508)
		(drill 0.254)
		(layers "F.Cu" "B.Cu")
		(net "P12V_PSU")
	)
	(via
		(at 212.237066 -402.722842)
		(size 0.508)
		(drill 0.254)
		(layers "F.Cu" "B.Cu")
		(net "P12V_PSU")
	)
	(via
		(at 232.176066 -404.025862)
		(size 0.508)
		(drill 0.254)
		(layers "F.Cu" "B.Cu")
		(net "P12V_PSU")
	)
	(via
		(at 186.818016 -405.719534)
		(size 0.508)
		(drill 0.254)
		(layers "F.Cu" "B.Cu")
		(net "P12V_PSU")
	)
	(via
		(at 250.866148 -412.46298)
		(size 0.508)
		(drill 0.254)
		(layers "F.Cu" "B.Cu")
		(net "P12V_PSU")
	)
	(via
		(at 277.088854 -412.547562)
		(size 0.508)
		(drill 0.254)
		(layers "F.Cu" "B.Cu")
		(net "P12V_PSU")
	)
	(via
		(at 233.573066 -402.722842)
		(size 0.508)
		(drill 0.254)
		(layers "F.Cu" "B.Cu")
		(net "P12V_PSU")
	)
	(via
		(at 250.866148 -413.98698)
		(size 0.508)
		(drill 0.254)
		(layers "F.Cu" "B.Cu")
		(net "P12V_PSU")
	)
	(via
		(at 250.866148 -413.22498)
		(size 0.508)
		(drill 0.254)
		(layers "F.Cu" "B.Cu")
		(net "P12V_PSU")
	)
	(via
		(at 245.877588 -413.18942)
		(size 0.508)
		(drill 0.254)
		(layers "F.Cu" "B.Cu")
		(net "P12V_PSU")
	)
	(via
		(at 209.417666 -404.025862)
		(size 0.508)
		(drill 0.254)
		(layers "F.Cu" "B.Cu")
		(net "P12V_PSU")
	)
	(via
		(at 230.753666 -401.419822)
		(size 0.508)
		(drill 0.254)
		(layers "F.Cu" "B.Cu")
		(net "P12V_PSU")
	)
	(via
		(at 234.455208 -408.379422)
		(size 0.508)
		(drill 0.254)
		(layers "F.Cu" "B.Cu")
		(net "P12V_PSU")
	)
	(via
		(at 279.374854 -412.547562)
		(size 0.508)
		(drill 0.254)
		(layers "F.Cu" "B.Cu")
		(net "P12V_PSU")
	)
	(via
		(at 251.628148 -412.46298)
		(size 0.508)
		(drill 0.254)
		(layers "F.Cu" "B.Cu")
		(net "P12V_PSU")
	)
	(via
		(at 222.263208 -409.420822)
		(size 0.508)
		(drill 0.254)
		(layers "F.Cu" "B.Cu")
		(net "P12V_PSU")
	)
	(via
		(at 201.569066 -401.419822)
		(size 0.508)
		(drill 0.254)
		(layers "F.Cu" "B.Cu")
		(net "P12V_PSU")
	)
	(via
		(at 271.455134 -411.744922)
		(size 0.508)
		(drill 0.254)
		(layers "F.Cu" "B.Cu")
		(net "P12V_PSU")
	)
	(via
		(at 230.645208 -409.420822)
		(size 0.508)
		(drill 0.254)
		(layers "F.Cu" "B.Cu")
		(net "P12V_PSU")
	)
	(via
		(at 222.263208 -406.576022)
		(size 0.508)
		(drill 0.254)
		(layers "F.Cu" "B.Cu")
		(net "P12V_PSU")
	)
	(via
		(at 266.883134 -411.744922)
		(size 0.508)
		(drill 0.254)
		(layers "F.Cu" "B.Cu")
		(net "P12V_PSU")
	)
	(via
		(at 261.176008 -411.70098)
		(size 0.508)
		(drill 0.254)
		(layers "F.Cu" "B.Cu")
		(net "P12V_PSU")
	)
	(via
		(at 253.152148 -414.74898)
		(size 0.508)
		(drill 0.254)
		(layers "F.Cu" "B.Cu")
		(net "P12V_PSU")
	)
	(via
		(at 260.414008 -413.22498)
		(size 0.508)
		(drill 0.254)
		(layers "F.Cu" "B.Cu")
		(net "P12V_PSU")
	)
	(via
		(at 270.693134 -411.744922)
		(size 0.508)
		(drill 0.254)
		(layers "F.Cu" "B.Cu")
		(net "P12V_PSU")
	)
	(via
		(at 271.455134 -412.506922)
		(size 0.508)
		(drill 0.254)
		(layers "F.Cu" "B.Cu")
		(net "P12V_PSU")
	)
	(via
		(at 210.833208 -409.420822)
		(size 0.508)
		(drill 0.254)
		(layers "F.Cu" "B.Cu")
		(net "P12V_PSU")
	)
	(via
		(at 232.931208 -406.576022)
		(size 0.508)
		(drill 0.254)
		(layers "F.Cu" "B.Cu")
		(net "P12V_PSU")
	)
	(via
		(at 271.455134 -414.792922)
		(size 0.508)
		(drill 0.254)
		(layers "F.Cu" "B.Cu")
		(net "P12V_PSU")
	)
	(via
		(at 267.645134 -413.268922)
		(size 0.508)
		(drill 0.254)
		(layers "F.Cu" "B.Cu")
		(net "P12V_PSU")
	)
	(via
		(at 269.169134 -413.268922)
		(size 0.508)
		(drill 0.254)
		(layers "F.Cu" "B.Cu")
		(net "P12V_PSU")
	)
	(via
		(at 230.645208 -408.379422)
		(size 0.508)
		(drill 0.254)
		(layers "F.Cu" "B.Cu")
		(net "P12V_PSU")
	)
	(via
		(at 259.652008 -413.22498)
		(size 0.508)
		(drill 0.254)
		(layers "F.Cu" "B.Cu")
		(net "P12V_PSU")
	)
	(via
		(at 185.491628 -404.025354)
		(size 0.508)
		(drill 0.254)
		(layers "F.Cu" "B.Cu")
		(net "P12V_PSU")
	)
	(via
		(at 189.866016 -408.818334)
		(size 0.508)
		(drill 0.254)
		(layers "F.Cu" "B.Cu")
		(net "P12V_PSU")
	)
	(via
		(at 234.455208 -409.420822)
		(size 0.508)
		(drill 0.254)
		(layers "F.Cu" "B.Cu")
		(net "P12V_PSU")
	)
	(via
		(at 244.353588 -413.95142)
		(size 0.508)
		(drill 0.254)
		(layers "F.Cu" "B.Cu")
		(net "P12V_PSU")
	)
	(via
		(at 220.739208 -407.338022)
		(size 0.508)
		(drill 0.254)
		(layers "F.Cu" "B.Cu")
		(net "P12V_PSU")
	)
	(via
		(at 198.641208 -405.814022)
		(size 0.508)
		(drill 0.254)
		(layers "F.Cu" "B.Cu")
		(net "P12V_PSU")
	)
	(via
		(at 267.645134 -411.744922)
		(size 0.508)
		(drill 0.254)
		(layers "F.Cu" "B.Cu")
		(net "P12V_PSU")
	)
	(via
		(at 232.169208 -406.576022)
		(size 0.508)
		(drill 0.254)
		(layers "F.Cu" "B.Cu")
		(net "P12V_PSU")
	)
	(via
		(at 250.866148 -411.70098)
		(size 0.508)
		(drill 0.254)
		(layers "F.Cu" "B.Cu")
		(net "P12V_PSU")
	)
	(via
		(at 230.645208 -407.338022)
		(size 0.508)
		(drill 0.254)
		(layers "F.Cu" "B.Cu")
		(net "P12V_PSU")
	)
	(via
		(at 209.309208 -406.576022)
		(size 0.508)
		(drill 0.254)
		(layers "F.Cu" "B.Cu")
		(net "P12V_PSU")
	)
	(via
		(at 221.501208 -409.420822)
		(size 0.508)
		(drill 0.254)
		(layers "F.Cu" "B.Cu")
		(net "P12V_PSU")
	)
	(via
		(at 243.591588 -413.95142)
		(size 0.508)
		(drill 0.254)
		(layers "F.Cu" "B.Cu")
		(net "P12V_PSU")
	)
	(via
		(at 233.693208 -406.576022)
		(size 0.508)
		(drill 0.254)
		(layers "F.Cu" "B.Cu")
		(net "P12V_PSU")
	)
	(via
		(at 187.580016 -408.005534)
		(size 0.508)
		(drill 0.254)
		(layers "F.Cu" "B.Cu")
		(net "P12V_PSU")
	)
	(via
		(at 262.700008 -413.22498)
		(size 0.508)
		(drill 0.254)
		(layers "F.Cu" "B.Cu")
		(net "P12V_PSU")
	)
	(via
		(at 253.152148 -411.70098)
		(size 0.508)
		(drill 0.254)
		(layers "F.Cu" "B.Cu")
		(net "P12V_PSU")
	)
	(via
		(at 220.739208 -405.814022)
		(size 0.508)
		(drill 0.254)
		(layers "F.Cu" "B.Cu")
		(net "P12V_PSU")
	)
	(via
		(at 242.829588 -411.66542)
		(size 0.508)
		(drill 0.254)
		(layers "F.Cu" "B.Cu")
		(net "P12V_PSU")
	)
	(via
		(at 208.547208 -409.420822)
		(size 0.508)
		(drill 0.254)
		(layers "F.Cu" "B.Cu")
		(net "P12V_PSU")
	)
	(via
		(at 245.115588 -411.66542)
		(size 0.508)
		(drill 0.254)
		(layers "F.Cu" "B.Cu")
		(net "P12V_PSU")
	)
	(via
		(at 254.676148 -412.46298)
		(size 0.508)
		(drill 0.254)
		(layers "F.Cu" "B.Cu")
		(net "P12V_PSU")
	)
	(via
		(at 210.833208 -405.814022)
		(size 0.508)
		(drill 0.254)
		(layers "F.Cu" "B.Cu")
		(net "P12V_PSU")
	)
	(via
		(at 258.890008 -413.22498)
		(size 0.508)
		(drill 0.254)
		(layers "F.Cu" "B.Cu")
		(net "P12V_PSU")
	)
	(via
		(at 269.169134 -414.792922)
		(size 0.508)
		(drill 0.254)
		(layers "F.Cu" "B.Cu")
		(net "P12V_PSU")
	)
	(via
		(at 244.353588 -413.18942)
		(size 0.508)
		(drill 0.254)
		(layers "F.Cu" "B.Cu")
		(net "P12V_PSU")
	)
	(via
		(at 212.357208 -405.814022)
		(size 0.508)
		(drill 0.254)
		(layers "F.Cu" "B.Cu")
		(net "P12V_PSU")
	)
	(via
		(at 267.645134 -414.792922)
		(size 0.508)
		(drill 0.254)
		(layers "F.Cu" "B.Cu")
		(net "P12V_PSU")
	)
	(via
		(at 189.104016 -405.719534)
		(size 0.508)
		(drill 0.254)
		(layers "F.Cu" "B.Cu")
		(net "P12V_PSU")
	)
	(via
		(at 232.169208 -407.338022)
		(size 0.508)
		(drill 0.254)
		(layers "F.Cu" "B.Cu")
		(net "P12V_PSU")
	)
	(via
		(at 278.612854 -411.785562)
		(size 0.508)
		(drill 0.254)
		(layers "F.Cu" "B.Cu")
		(net "P12V_PSU")
	)
	(via
		(at 186.818016 -408.818334)
		(size 0.508)
		(drill 0.254)
		(layers "F.Cu" "B.Cu")
		(net "P12V_PSU")
	)
	(via
		(at 201.689208 -408.379422)
		(size 0.508)
		(drill 0.254)
		(layers "F.Cu" "B.Cu")
		(net "P12V_PSU")
	)
	(via
		(at 197.879208 -408.379422)
		(size 0.508)
		(drill 0.254)
		(layers "F.Cu" "B.Cu")
		(net "P12V_PSU")
	)
	(via
		(at 269.931134 -414.792922)
		(size 0.508)
		(drill 0.254)
		(layers "F.Cu" "B.Cu")
		(net "P12V_PSU")
	)
	(via
		(at 268.407134 -411.744922)
		(size 0.508)
		(drill 0.254)
		(layers "F.Cu" "B.Cu")
		(net "P12V_PSU")
	)
	(via
		(at 253.152148 -413.98698)
		(size 0.508)
		(drill 0.254)
		(layers "F.Cu" "B.Cu")
		(net "P12V_PSU")
	)
	(via
		(at 261.938008 -413.22498)
		(size 0.508)
		(drill 0.254)
		(layers "F.Cu" "B.Cu")
		(net "P12V_PSU")
	)
	(via
		(at 245.115588 -412.42742)
		(size 0.508)
		(drill 0.254)
		(layers "F.Cu" "B.Cu")
		(net "P12V_PSU")
	)
	(via
		(at 188.342016 -407.243534)
		(size 0.508)
		(drill 0.254)
		(layers "F.Cu" "B.Cu")
		(net "P12V_PSU")
	)
	(via
		(at 277.088854 -411.785562)
		(size 0.508)
		(drill 0.254)
		(layers "F.Cu" "B.Cu")
		(net "P12V_PSU")
	)
	(via
		(at 242.067588 -413.95142)
		(size 0.508)
		(drill 0.254)
		(layers "F.Cu" "B.Cu")
		(net "P12V_PSU")
	)
	(via
		(at 201.569066 -404.025862)
		(size 0.508)
		(drill 0.254)
		(layers "F.Cu" "B.Cu")
		(net "P12V_PSU")
	)
	(via
		(at 252.390148 -414.74898)
		(size 0.508)
		(drill 0.254)
		(layers "F.Cu" "B.Cu")
		(net "P12V_PSU")
	)
	(via
		(at 243.591588 -412.42742)
		(size 0.508)
		(drill 0.254)
		(layers "F.Cu" "B.Cu")
		(net "P12V_PSU")
	)
	(via
		(at 198.641208 -406.576022)
		(size 0.508)
		(drill 0.254)
		(layers "F.Cu" "B.Cu")
		(net "P12V_PSU")
	)
	(via
		(at 210.833208 -406.576022)
		(size 0.508)
		(drill 0.254)
		(layers "F.Cu" "B.Cu")
		(net "P12V_PSU")
	)
	(via
		(at 261.176008 -413.22498)
		(size 0.508)
		(drill 0.254)
		(layers "F.Cu" "B.Cu")
		(net "P12V_PSU")
	)
	(via
		(at 186.818016 -406.481534)
		(size 0.508)
		(drill 0.254)
		(layers "F.Cu" "B.Cu")
		(net "P12V_PSU")
	)
	(via
		(at 210.840066 -404.025862)
		(size 0.508)
		(drill 0.254)
		(layers "F.Cu" "B.Cu")
		(net "P12V_PSU")
	)
	(via
		(at 218.453208 -409.420822)
		(size 0.508)
		(drill 0.254)
		(layers "F.Cu" "B.Cu")
		(net "P12V_PSU")
	)
	(via
		(at 199.403208 -407.338022)
		(size 0.508)
		(drill 0.254)
		(layers "F.Cu" "B.Cu")
		(net "P12V_PSU")
	)
	(via
		(at 269.931134 -414.030922)
		(size 0.508)
		(drill 0.254)
		(layers "F.Cu" "B.Cu")
		(net "P12V_PSU")
	)
	(via
		(at 231.407208 -406.576022)
		(size 0.508)
		(drill 0.254)
		(layers "F.Cu" "B.Cu")
		(net "P12V_PSU")
	)
	(via
		(at 246.639588 -413.18942)
		(size 0.508)
		(drill 0.254)
		(layers "F.Cu" "B.Cu")
		(net "P12V_PSU")
	)
	(via
		(at 233.573066 -404.025862)
		(size 0.508)
		(drill 0.254)
		(layers "F.Cu" "B.Cu")
		(net "P12V_PSU")
	)
	(via
		(at 223.025208 -407.338022)
		(size 0.508)
		(drill 0.254)
		(layers "F.Cu" "B.Cu")
		(net "P12V_PSU")
	)
	(via
		(at 198.749666 -402.722842)
		(size 0.508)
		(drill 0.254)
		(layers "F.Cu" "B.Cu")
		(net "P12V_PSU")
	)
	(via
		(at 211.595208 -405.814022)
		(size 0.508)
		(drill 0.254)
		(layers "F.Cu" "B.Cu")
		(net "P12V_PSU")
	)
	(via
		(at 223.787208 -408.379422)
		(size 0.508)
		(drill 0.254)
		(layers "F.Cu" "B.Cu")
		(net "P12V_PSU")
	)
	(via
		(at 200.927208 -405.814022)
		(size 0.508)
		(drill 0.254)
		(layers "F.Cu" "B.Cu")
		(net "P12V_PSU")
	)
	(via
		(at 277.850854 -414.071562)
		(size 0.508)
		(drill 0.254)
		(layers "F.Cu" "B.Cu")
		(net "P12V_PSU")
	)
	(via
		(at 209.309208 -407.338022)
		(size 0.508)
		(drill 0.254)
		(layers "F.Cu" "B.Cu")
		(net "P12V_PSU")
	)
	(via
		(at 233.693208 -409.420822)
		(size 0.508)
		(drill 0.254)
		(layers "F.Cu" "B.Cu")
		(net "P12V_PSU")
	)
	(via
		(at 254.676148 -411.70098)
		(size 0.508)
		(drill 0.254)
		(layers "F.Cu" "B.Cu")
		(net "P12V_PSU")
	)
	(via
		(at 200.927208 -408.379422)
		(size 0.508)
		(drill 0.254)
		(layers "F.Cu" "B.Cu")
		(net "P12V_PSU")
	)
	(via
		(at 245.115588 -414.71342)
		(size 0.508)
		(drill 0.254)
		(layers "F.Cu" "B.Cu")
		(net "P12V_PSU")
	)
	(via
		(at 188.311028 -401.350734)
		(size 0.508)
		(drill 0.254)
		(layers "F.Cu" "B.Cu")
		(net "P12V_PSU")
	)
	(via
		(at 186.818016 -407.243534)
		(size 0.508)
		(drill 0.254)
		(layers "F.Cu" "B.Cu")
		(net "P12V_PSU")
	)
	(via
		(at 233.693208 -405.814022)
		(size 0.508)
		(drill 0.254)
		(layers "F.Cu" "B.Cu")
		(net "P12V_PSU")
	)
	(via
		(at 189.866016 -407.243534)
		(size 0.508)
		(drill 0.254)
		(layers "F.Cu" "B.Cu")
		(net "P12V_PSU")
	)
	(via
		(at 211.595208 -407.338022)
		(size 0.508)
		(drill 0.254)
		(layers "F.Cu" "B.Cu")
		(net "P12V_PSU")
	)
	(via
		(at 219.977208 -406.576022)
		(size 0.508)
		(drill 0.254)
		(layers "F.Cu" "B.Cu")
		(net "P12V_PSU")
	)
	(via
		(at 210.071208 -408.379422)
		(size 0.508)
		(drill 0.254)
		(layers "F.Cu" "B.Cu")
		(net "P12V_PSU")
	)
	(via
		(at 188.342016 -405.719534)
		(size 0.508)
		(drill 0.254)
		(layers "F.Cu" "B.Cu")
		(net "P12V_PSU")
	)
	(via
		(at 259.652008 -412.46298)
		(size 0.508)
		(drill 0.254)
		(layers "F.Cu" "B.Cu")
		(net "P12V_PSU")
	)
	(via
		(at 269.169134 -412.506922)
		(size 0.508)
		(drill 0.254)
		(layers "F.Cu" "B.Cu")
		(net "P12V_PSU")
	)
	(via
		(at 242.067588 -411.66542)
		(size 0.508)
		(drill 0.254)
		(layers "F.Cu" "B.Cu")
		(net "P12V_PSU")
	)
	(via
		(at 232.931208 -405.814022)
		(size 0.508)
		(drill 0.254)
		(layers "F.Cu" "B.Cu")
		(net "P12V_PSU")
	)
	(via
		(at 219.977208 -408.379422)
		(size 0.508)
		(drill 0.254)
		(layers "F.Cu" "B.Cu")
		(net "P12V_PSU")
	)
	(via
		(at 186.914028 -401.419314)
		(size 0.508)
		(drill 0.254)
		(layers "F.Cu" "B.Cu")
		(net "P12V_PSU")
	)
	(via
		(at 267.645134 -414.030922)
		(size 0.508)
		(drill 0.254)
		(layers "F.Cu" "B.Cu")
		(net "P12V_PSU")
	)
	(via
		(at 269.931134 -413.268922)
		(size 0.508)
		(drill 0.254)
		(layers "F.Cu" "B.Cu")
		(net "P12V_PSU")
	)
	(via
		(at 268.407134 -414.030922)
		(size 0.508)
		(drill 0.254)
		(layers "F.Cu" "B.Cu")
		(net "P12V_PSU")
	)
	(via
		(at 187.580016 -406.481534)
		(size 0.508)
		(drill 0.254)
		(layers "F.Cu" "B.Cu")
		(net "P12V_PSU")
	)
	(via
		(at 278.612854 -413.309562)
		(size 0.508)
		(drill 0.254)
		(layers "F.Cu" "B.Cu")
		(net "P12V_PSU")
	)
	(via
		(at 187.580016 -407.243534)
		(size 0.508)
		(drill 0.254)
		(layers "F.Cu" "B.Cu")
		(net "P12V_PSU")
	)
	(via
		(at 276.326854 -412.547562)
		(size 0.508)
		(drill 0.254)
		(layers "F.Cu" "B.Cu")
		(net "P12V_PSU")
	)
	(via
		(at 211.595208 -406.576022)
		(size 0.508)
		(drill 0.254)
		(layers "F.Cu" "B.Cu")
		(net "P12V_PSU")
	)
	(via
		(at 197.879208 -409.420822)
		(size 0.508)
		(drill 0.254)
		(layers "F.Cu" "B.Cu")
		(net "P12V_PSU")
	)
	(via
		(at 277.850854 -413.309562)
		(size 0.508)
		(drill 0.254)
		(layers "F.Cu" "B.Cu")
		(net "P12V_PSU")
	)
	(via
		(at 277.088854 -414.833562)
		(size 0.508)
		(drill 0.254)
		(layers "F.Cu" "B.Cu")
		(net "P12V_PSU")
	)
	(via
		(at 210.833208 -407.338022)
		(size 0.508)
		(drill 0.254)
		(layers "F.Cu" "B.Cu")
		(net "P12V_PSU")
	)
	(via
		(at 221.501208 -405.814022)
		(size 0.508)
		(drill 0.254)
		(layers "F.Cu" "B.Cu")
		(net "P12V_PSU")
	)
	(via
		(at 262.700008 -412.46298)
		(size 0.508)
		(drill 0.254)
		(layers "F.Cu" "B.Cu")
		(net "P12V_PSU")
	)
	(via
		(at 266.883134 -413.268922)
		(size 0.508)
		(drill 0.254)
		(layers "F.Cu" "B.Cu")
		(net "P12V_PSU")
	)
	(via
		(at 222.905066 -402.722842)
		(size 0.508)
		(drill 0.254)
		(layers "F.Cu" "B.Cu")
		(net "P12V_PSU")
	)
	(via
		(at 279.374854 -413.309562)
		(size 0.508)
		(drill 0.254)
		(layers "F.Cu" "B.Cu")
		(net "P12V_PSU")
	)
	(via
		(at 188.342016 -409.580334)
		(size 0.508)
		(drill 0.254)
		(layers "F.Cu" "B.Cu")
		(net "P12V_PSU")
	)
	(via
		(at 231.407208 -409.420822)
		(size 0.508)
		(drill 0.254)
		(layers "F.Cu" "B.Cu")
		(net "P12V_PSU")
	)
	(via
		(at 200.165208 -408.379422)
		(size 0.508)
		(drill 0.254)
		(layers "F.Cu" "B.Cu")
		(net "P12V_PSU")
	)
	(via
		(at 230.753666 -402.722842)
		(size 0.508)
		(drill 0.254)
		(layers "F.Cu" "B.Cu")
		(net "P12V_PSU")
	)
	(via
		(at 261.938008 -412.46298)
		(size 0.508)
		(drill 0.254)
		(layers "F.Cu" "B.Cu")
		(net "P12V_PSU")
	)
	(via
		(at 188.311028 -404.035514)
		(size 0.508)
		(drill 0.254)
		(layers "F.Cu" "B.Cu")
		(net "P12V_PSU")
	)
	(via
		(at 187.580016 -408.818334)
		(size 0.508)
		(drill 0.254)
		(layers "F.Cu" "B.Cu")
		(net "P12V_PSU")
	)
	(via
		(at 212.357208 -409.420822)
		(size 0.508)
		(drill 0.254)
		(layers "F.Cu" "B.Cu")
		(net "P12V_PSU")
	)
	(via
		(at 221.508066 -401.419822)
		(size 0.508)
		(drill 0.254)
		(layers "F.Cu" "B.Cu")
		(net "P12V_PSU")
	)
	(via
		(at 245.115588 -413.18942)
		(size 0.508)
		(drill 0.254)
		(layers "F.Cu" "B.Cu")
		(net "P12V_PSU")
	)
	(via
		(at 233.693208 -407.338022)
		(size 0.508)
		(drill 0.254)
		(layers "F.Cu" "B.Cu")
		(net "P12V_PSU")
	)
	(via
		(at 210.071208 -409.420822)
		(size 0.508)
		(drill 0.254)
		(layers "F.Cu" "B.Cu")
		(net "P12V_PSU")
	)
	(via
		(at 201.689208 -407.338022)
		(size 0.508)
		(drill 0.254)
		(layers "F.Cu" "B.Cu")
		(net "P12V_PSU")
	)
	(via
		(at 186.914028 -404.025354)
		(size 0.508)
		(drill 0.254)
		(layers "F.Cu" "B.Cu")
		(net "P12V_PSU")
	)
	(via
		(at 242.829588 -414.71342)
		(size 0.508)
		(drill 0.254)
		(layers "F.Cu" "B.Cu")
		(net "P12V_PSU")
	)
	(via
		(at 232.169208 -409.420822)
		(size 0.508)
		(drill 0.254)
		(layers "F.Cu" "B.Cu")
		(net "P12V_PSU")
	)
	(via
		(at 259.652008 -411.70098)
		(size 0.508)
		(drill 0.254)
		(layers "F.Cu" "B.Cu")
		(net "P12V_PSU")
	)
	(via
		(at 188.342016 -408.005534)
		(size 0.508)
		(drill 0.254)
		(layers "F.Cu" "B.Cu")
		(net "P12V_PSU")
	)
	(via
		(at 201.689208 -405.814022)
		(size 0.508)
		(drill 0.254)
		(layers "F.Cu" "B.Cu")
		(net "P12V_PSU")
	)
	(via
		(at 251.628148 -413.98698)
		(size 0.508)
		(drill 0.254)
		(layers "F.Cu" "B.Cu")
		(net "P12V_PSU")
	)
	(via
		(at 212.357208 -406.576022)
		(size 0.508)
		(drill 0.254)
		(layers "F.Cu" "B.Cu")
		(net "P12V_PSU")
	)
	(via
		(at 186.056016 -408.005534)
		(size 0.508)
		(drill 0.254)
		(layers "F.Cu" "B.Cu")
		(net "P12V_PSU")
	)
	(via
		(at 232.931208 -408.379422)
		(size 0.508)
		(drill 0.254)
		(layers "F.Cu" "B.Cu")
		(net "P12V_PSU")
	)
	(via
		(at 268.407134 -412.506922)
		(size 0.508)
		(drill 0.254)
		(layers "F.Cu" "B.Cu")
		(net "P12V_PSU")
	)
	(via
		(at 267.645134 -412.506922)
		(size 0.508)
		(drill 0.254)
		(layers "F.Cu" "B.Cu")
		(net "P12V_PSU")
	)
	(via
		(at 229.883208 -409.420822)
		(size 0.508)
		(drill 0.254)
		(layers "F.Cu" "B.Cu")
		(net "P12V_PSU")
	)
	(via
		(at 277.088854 -413.309562)
		(size 0.508)
		(drill 0.254)
		(layers "F.Cu" "B.Cu")
		(net "P12V_PSU")
	)
	(via
		(at 242.067588 -412.42742)
		(size 0.508)
		(drill 0.254)
		(layers "F.Cu" "B.Cu")
		(net "P12V_PSU")
	)
	(via
		(at 243.591588 -411.66542)
		(size 0.508)
		(drill 0.254)
		(layers "F.Cu" "B.Cu")
		(net "P12V_PSU")
	)
	(via
		(at 260.414008 -412.46298)
		(size 0.508)
		(drill 0.254)
		(layers "F.Cu" "B.Cu")
		(net "P12V_PSU")
	)
	(via
		(at 189.104016 -408.818334)
		(size 0.508)
		(drill 0.254)
		(layers "F.Cu" "B.Cu")
		(net "P12V_PSU")
	)
	(via
		(at 266.883134 -414.792922)
		(size 0.508)
		(drill 0.254)
		(layers "F.Cu" "B.Cu")
		(net "P12V_PSU")
	)
	(via
		(at 270.693134 -412.506922)
		(size 0.508)
		(drill 0.254)
		(layers "F.Cu" "B.Cu")
		(net "P12V_PSU")
	)
	(via
		(at 231.407208 -408.379422)
		(size 0.508)
		(drill 0.254)
		(layers "F.Cu" "B.Cu")
		(net "P12V_PSU")
	)
	(via
		(at 210.840066 -401.419822)
		(size 0.508)
		(drill 0.254)
		(layers "F.Cu" "B.Cu")
		(net "P12V_PSU")
	)
	(via
		(at 270.693134 -413.268922)
		(size 0.508)
		(drill 0.254)
		(layers "F.Cu" "B.Cu")
		(net "P12V_PSU")
	)
	(via
		(at 271.455134 -414.030922)
		(size 0.508)
		(drill 0.254)
		(layers "F.Cu" "B.Cu")
		(net "P12V_PSU")
	)
	(via
		(at 220.739208 -408.379422)
		(size 0.508)
		(drill 0.254)
		(layers "F.Cu" "B.Cu")
		(net "P12V_PSU")
	)
	(via
		(at 269.931134 -412.506922)
		(size 0.508)
		(drill 0.254)
		(layers "F.Cu" "B.Cu")
		(net "P12V_PSU")
	)
	(via
		(at 201.569066 -402.722842)
		(size 0.508)
		(drill 0.254)
		(layers "F.Cu" "B.Cu")
		(net "P12V_PSU")
	)
	(via
		(at 186.056016 -407.243534)
		(size 0.508)
		(drill 0.254)
		(layers "F.Cu" "B.Cu")
		(net "P12V_PSU")
	)
	(via
		(at 232.931208 -409.420822)
		(size 0.508)
		(drill 0.254)
		(layers "F.Cu" "B.Cu")
		(net "P12V_PSU")
	)
	(via
		(at 277.850854 -414.833562)
		(size 0.508)
		(drill 0.254)
		(layers "F.Cu" "B.Cu")
		(net "P12V_PSU")
	)
	(via
		(at 276.326854 -413.309562)
		(size 0.508)
		(drill 0.254)
		(layers "F.Cu" "B.Cu")
		(net "P12V_PSU")
	)
	(via
		(at 223.025208 -408.379422)
		(size 0.508)
		(drill 0.254)
		(layers "F.Cu" "B.Cu")
		(net "P12V_PSU")
	)
	(via
		(at 202.451208 -409.420822)
		(size 0.508)
		(drill 0.254)
		(layers "F.Cu" "B.Cu")
		(net "P12V_PSU")
	)
	(via
		(at 222.905066 -404.025862)
		(size 0.508)
		(drill 0.254)
		(layers "F.Cu" "B.Cu")
		(net "P12V_PSU")
	)
	(via
		(at 244.353588 -412.42742)
		(size 0.508)
		(drill 0.254)
		(layers "F.Cu" "B.Cu")
		(net "P12V_PSU")
	)
	(via
		(at 244.353588 -414.71342)
		(size 0.508)
		(drill 0.254)
		(layers "F.Cu" "B.Cu")
		(net "P12V_PSU")
	)
	(via
		(at 222.263208 -407.338022)
		(size 0.508)
		(drill 0.254)
		(layers "F.Cu" "B.Cu")
		(net "P12V_PSU")
	)
	(via
		(at 198.749666 -404.025862)
		(size 0.508)
		(drill 0.254)
		(layers "F.Cu" "B.Cu")
		(net "P12V_PSU")
	)
	(via
		(at 253.914148 -411.70098)
		(size 0.508)
		(drill 0.254)
		(layers "F.Cu" "B.Cu")
		(net "P12V_PSU")
	)
	(via
		(at 262.700008 -411.70098)
		(size 0.508)
		(drill 0.254)
		(layers "F.Cu" "B.Cu")
		(net "P12V_PSU")
	)
	(via
		(at 221.508066 -404.025862)
		(size 0.508)
		(drill 0.254)
		(layers "F.Cu" "B.Cu")
		(net "P12V_PSU")
	)
	(via
		(at 200.165208 -406.576022)
		(size 0.508)
		(drill 0.254)
		(layers "F.Cu" "B.Cu")
		(net "P12V_PSU")
	)
	(via
		(at 219.977208 -407.338022)
		(size 0.508)
		(drill 0.254)
		(layers "F.Cu" "B.Cu")
		(net "P12V_PSU")
	)
	(via
		(at 198.641208 -408.379422)
		(size 0.508)
		(drill 0.254)
		(layers "F.Cu" "B.Cu")
		(net "P12V_PSU")
	)
	(via
		(at 219.215208 -408.379422)
		(size 0.508)
		(drill 0.254)
		(layers "F.Cu" "B.Cu")
		(net "P12V_PSU")
	)
	(via
		(at 189.866016 -409.580334)
		(size 0.508)
		(drill 0.254)
		(layers "F.Cu" "B.Cu")
		(net "P12V_PSU")
	)
	(via
		(at 230.645208 -406.576022)
		(size 0.508)
		(drill 0.254)
		(layers "F.Cu" "B.Cu")
		(net "P12V_PSU")
	)
	(via
		(at 198.641208 -407.338022)
		(size 0.508)
		(drill 0.254)
		(layers "F.Cu" "B.Cu")
		(net "P12V_PSU")
	)
	(via
		(at 246.639588 -414.71342)
		(size 0.508)
		(drill 0.254)
		(layers "F.Cu" "B.Cu")
		(net "P12V_PSU")
	)
	(via
		(at 232.169208 -408.379422)
		(size 0.508)
		(drill 0.254)
		(layers "F.Cu" "B.Cu")
		(net "P12V_PSU")
	)
	(via
		(at 223.025208 -406.576022)
		(size 0.508)
		(drill 0.254)
		(layers "F.Cu" "B.Cu")
		(net "P12V_PSU")
	)
	(via
		(at 246.639588 -411.66542)
		(size 0.508)
		(drill 0.254)
		(layers "F.Cu" "B.Cu")
		(net "P12V_PSU")
	)
	(via
		(at 244.353588 -411.66542)
		(size 0.508)
		(drill 0.254)
		(layers "F.Cu" "B.Cu")
		(net "P12V_PSU")
	)
	(via
		(at 199.403208 -405.814022)
		(size 0.508)
		(drill 0.254)
		(layers "F.Cu" "B.Cu")
		(net "P12V_PSU")
	)
	(via
		(at 201.689208 -409.420822)
		(size 0.508)
		(drill 0.254)
		(layers "F.Cu" "B.Cu")
		(net "P12V_PSU")
	)
	(via
		(at 232.176066 -401.419822)
		(size 0.508)
		(drill 0.254)
		(layers "F.Cu" "B.Cu")
		(net "P12V_PSU")
	)
	(via
		(at 213.119208 -408.379422)
		(size 0.508)
		(drill 0.254)
		(layers "F.Cu" "B.Cu")
		(net "P12V_PSU")
	)
	(via
		(at 219.977208 -405.814022)
		(size 0.508)
		(drill 0.254)
		(layers "F.Cu" "B.Cu")
		(net "P12V_PSU")
	)
	(via
		(at 197.117208 -409.420822)
		(size 0.508)
		(drill 0.254)
		(layers "F.Cu" "B.Cu")
		(net "P12V_PSU")
	)
	(via
		(at 221.501208 -407.338022)
		(size 0.508)
		(drill 0.254)
		(layers "F.Cu" "B.Cu")
		(net "P12V_PSU")
	)
	(via
		(at 220.085666 -404.025862)
		(size 0.508)
		(drill 0.254)
		(layers "F.Cu" "B.Cu")
		(net "P12V_PSU")
	)
	(via
		(at 212.237066 -404.025862)
		(size 0.508)
		(drill 0.254)
		(layers "F.Cu" "B.Cu")
		(net "P12V_PSU")
	)
	(via
		(at 230.645208 -405.814022)
		(size 0.508)
		(drill 0.254)
		(layers "F.Cu" "B.Cu")
		(net "P12V_PSU")
	)
	(via
		(at 229.121208 -409.420822)
		(size 0.508)
		(drill 0.254)
		(layers "F.Cu" "B.Cu")
		(net "P12V_PSU")
	)
	(via
		(at 209.309208 -408.379422)
		(size 0.508)
		(drill 0.254)
		(layers "F.Cu" "B.Cu")
		(net "P12V_PSU")
	)
	(via
		(at 200.165208 -409.420822)
		(size 0.508)
		(drill 0.254)
		(layers "F.Cu" "B.Cu")
		(net "P12V_PSU")
	)
	(via
		(at 210.071208 -407.338022)
		(size 0.508)
		(drill 0.254)
		(layers "F.Cu" "B.Cu")
		(net "P12V_PSU")
	)
	(via
		(at 190.628016 -409.580334)
		(size 0.508)
		(drill 0.254)
		(layers "F.Cu" "B.Cu")
		(net "P12V_PSU")
	)
	(via
		(at 199.403208 -408.379422)
		(size 0.508)
		(drill 0.254)
		(layers "F.Cu" "B.Cu")
		(net "P12V_PSU")
	)
	(via
		(at 223.025208 -409.420822)
		(size 0.508)
		(drill 0.254)
		(layers "F.Cu" "B.Cu")
		(net "P12V_PSU")
	)
	(via
		(at 254.676148 -413.22498)
		(size 0.508)
		(drill 0.254)
		(layers "F.Cu" "B.Cu")
		(net "P12V_PSU")
	)
	(via
		(at 223.025208 -405.814022)
		(size 0.508)
		(drill 0.254)
		(layers "F.Cu" "B.Cu")
		(net "P12V_PSU")
	)
	(via
		(at 212.357208 -407.338022)
		(size 0.508)
		(drill 0.254)
		(layers "F.Cu" "B.Cu")
		(net "P12V_PSU")
	)
	(via
		(at 186.056016 -406.481534)
		(size 0.508)
		(drill 0.254)
		(layers "F.Cu" "B.Cu")
		(net "P12V_PSU")
	)
	(via
		(at 212.357208 -408.379422)
		(size 0.508)
		(drill 0.254)
		(layers "F.Cu" "B.Cu")
		(net "P12V_PSU")
	)
	(via
		(at 200.927208 -409.420822)
		(size 0.508)
		(drill 0.254)
		(layers "F.Cu" "B.Cu")
		(net "P12V_PSU")
	)
	(via
		(at 268.407134 -414.792922)
		(size 0.508)
		(drill 0.254)
		(layers "F.Cu" "B.Cu")
		(net "P12V_PSU")
	)
	(via
		(at 252.390148 -412.46298)
		(size 0.508)
		(drill 0.254)
		(layers "F.Cu" "B.Cu")
		(net "P12V_PSU")
	)
	(via
		(at 258.890008 -412.46298)
		(size 0.508)
		(drill 0.254)
		(layers "F.Cu" "B.Cu")
		(net "P12V_PSU")
	)
	(via
		(at 271.455134 -413.268922)
		(size 0.508)
		(drill 0.254)
		(layers "F.Cu" "B.Cu")
		(net "P12V_PSU")
	)
	(via
		(at 221.501208 -408.379422)
		(size 0.508)
		(drill 0.254)
		(layers "F.Cu" "B.Cu")
		(net "P12V_PSU")
	)
	(via
		(at 209.417666 -401.419822)
		(size 0.508)
		(drill 0.254)
		(layers "F.Cu" "B.Cu")
		(net "P12V_PSU")
	)
	(via
		(at 250.866148 -414.74898)
		(size 0.508)
		(drill 0.254)
		(layers "F.Cu" "B.Cu")
		(net "P12V_PSU")
	)
	(via
		(at 200.927208 -406.576022)
		(size 0.508)
		(drill 0.254)
		(layers "F.Cu" "B.Cu")
		(net "P12V_PSU")
	)
	(via
		(at 276.326854 -414.071562)
		(size 0.508)
		(drill 0.254)
		(layers "F.Cu" "B.Cu")
		(net "P12V_PSU")
	)
	(via
		(at 222.263208 -405.814022)
		(size 0.508)
		(drill 0.254)
		(layers "F.Cu" "B.Cu")
		(net "P12V_PSU")
	)
	(via
		(at 251.628148 -414.74898)
		(size 0.508)
		(drill 0.254)
		(layers "F.Cu" "B.Cu")
		(net "P12V_PSU")
	)
	(via
		(at 188.311028 -402.653754)
		(size 0.508)
		(drill 0.254)
		(layers "F.Cu" "B.Cu")
		(net "P12V_PSU")
	)
	(via
		(at 188.342016 -406.481534)
		(size 0.508)
		(drill 0.254)
		(layers "F.Cu" "B.Cu")
		(net "P12V_PSU")
	)
	(via
		(at 187.580016 -405.719534)
		(size 0.508)
		(drill 0.254)
		(layers "F.Cu" "B.Cu")
		(net "P12V_PSU")
	)
	(via
		(at 246.639588 -412.42742)
		(size 0.508)
		(drill 0.254)
		(layers "F.Cu" "B.Cu")
		(net "P12V_PSU")
	)
	(via
		(at 243.591588 -414.71342)
		(size 0.508)
		(drill 0.254)
		(layers "F.Cu" "B.Cu")
		(net "P12V_PSU")
	)
	(via
		(at 219.215208 -409.420822)
		(size 0.508)
		(drill 0.254)
		(layers "F.Cu" "B.Cu")
		(net "P12V_PSU")
	)
	(via
		(at 277.850854 -411.785562)
		(size 0.508)
		(drill 0.254)
		(layers "F.Cu" "B.Cu")
		(net "P12V_PSU")
	)
	(via
		(at 202.451208 -408.379422)
		(size 0.508)
		(drill 0.254)
		(layers "F.Cu" "B.Cu")
		(net "P12V_PSU")
	)
	(via
		(at 211.595208 -408.379422)
		(size 0.508)
		(drill 0.254)
		(layers "F.Cu" "B.Cu")
		(net "P12V_PSU")
	)
	(via
		(at 276.326854 -411.785562)
		(size 0.508)
		(drill 0.254)
		(layers "F.Cu" "B.Cu")
		(net "P12V_PSU")
	)
	(via
		(at 253.914148 -413.22498)
		(size 0.508)
		(drill 0.254)
		(layers "F.Cu" "B.Cu")
		(net "P12V_PSU")
	)
	(via
		(at 198.641208 -409.420822)
		(size 0.508)
		(drill 0.254)
		(layers "F.Cu" "B.Cu")
		(net "P12V_PSU")
	)
	(via
		(at 266.883134 -414.030922)
		(size 0.508)
		(drill 0.254)
		(layers "F.Cu" "B.Cu")
		(net "P12V_PSU")
	)
	(via
		(at 189.104016 -408.005534)
		(size 0.508)
		(drill 0.254)
		(layers "F.Cu" "B.Cu")
		(net "P12V_PSU")
	)
	(via
		(at 223.787208 -409.420822)
		(size 0.508)
		(drill 0.254)
		(layers "F.Cu" "B.Cu")
		(net "P12V_PSU")
	)
	(via
		(at 245.877588 -413.95142)
		(size 0.508)
		(drill 0.254)
		(layers "F.Cu" "B.Cu")
		(net "P12V_PSU")
	)
	(via
		(at 245.115588 -413.95142)
		(size 0.508)
		(drill 0.254)
		(layers "F.Cu" "B.Cu")
		(net "P12V_PSU")
	)
	(via
		(at 251.628148 -411.70098)
		(size 0.508)
		(drill 0.254)
		(layers "F.Cu" "B.Cu")
		(net "P12V_PSU")
	)
	(via
		(at 201.689208 -406.576022)
		(size 0.508)
		(drill 0.254)
		(layers "F.Cu" "B.Cu")
		(net "P12V_PSU")
	)
	(via
		(at 252.390148 -413.22498)
		(size 0.508)
		(drill 0.254)
		(layers "F.Cu" "B.Cu")
		(net "P12V_PSU")
	)
	(via
		(at 233.693208 -408.379422)
		(size 0.508)
		(drill 0.254)
		(layers "F.Cu" "B.Cu")
		(net "P12V_PSU")
	)
	(via
		(at 233.573066 -401.419822)
		(size 0.508)
		(drill 0.254)
		(layers "F.Cu" "B.Cu")
		(net "P12V_PSU")
	)
	(via
		(at 220.085666 -402.722842)
		(size 0.508)
		(drill 0.254)
		(layers "F.Cu" "B.Cu")
		(net "P12V_PSU")
	)
	(via
		(at 278.612854 -414.833562)
		(size 0.508)
		(drill 0.254)
		(layers "F.Cu" "B.Cu")
		(net "P12V_PSU")
	)
	(via
		(at 186.056016 -405.719534)
		(size 0.508)
		(drill 0.254)
		(layers "F.Cu" "B.Cu")
		(net "P12V_PSU")
	)
	(via
		(at 232.931208 -407.338022)
		(size 0.508)
		(drill 0.254)
		(layers "F.Cu" "B.Cu")
		(net "P12V_PSU")
	)
	(via
		(at 185.491628 -402.722334)
		(size 0.508)
		(drill 0.254)
		(layers "F.Cu" "B.Cu")
		(net "P12V_PSU")
	)
	(via
		(at 210.071208 -405.814022)
		(size 0.508)
		(drill 0.254)
		(layers "F.Cu" "B.Cu")
		(net "P12V_PSU")
	)
	(via
		(at 230.753666 -404.025862)
		(size 0.508)
		(drill 0.254)
		(layers "F.Cu" "B.Cu")
		(net "P12V_PSU")
	)
	(via
		(at 231.407208 -405.814022)
		(size 0.508)
		(drill 0.254)
		(layers "F.Cu" "B.Cu")
		(net "P12V_PSU")
	)
	(via
		(at 252.390148 -413.98698)
		(size 0.508)
		(drill 0.254)
		(layers "F.Cu" "B.Cu")
		(net "P12V_PSU")
	)
	(via
		(at 279.374854 -414.071562)
		(size 0.508)
		(drill 0.254)
		(layers "F.Cu" "B.Cu")
		(net "P12V_PSU")
	)
	(via
		(at 189.104016 -409.580334)
		(size 0.508)
		(drill 0.254)
		(layers "F.Cu" "B.Cu")
		(net "P12V_PSU")
	)
	(via
		(at 246.639588 -413.95142)
		(size 0.508)
		(drill 0.254)
		(layers "F.Cu" "B.Cu")
		(net "P12V_PSU")
	)
	(via
		(at 211.595208 -409.420822)
		(size 0.508)
		(drill 0.254)
		(layers "F.Cu" "B.Cu")
		(net "P12V_PSU")
	)
	(via
		(at 189.866016 -408.005534)
		(size 0.508)
		(drill 0.254)
		(layers "F.Cu" "B.Cu")
		(net "P12V_PSU")
	)
	(via
		(at 213.119208 -409.420822)
		(size 0.508)
		(drill 0.254)
		(layers "F.Cu" "B.Cu")
		(net "P12V_PSU")
	)
	(via
		(at 231.407208 -407.338022)
		(size 0.508)
		(drill 0.254)
		(layers "F.Cu" "B.Cu")
		(net "P12V_PSU")
	)
	(via
		(at 243.591588 -413.18942)
		(size 0.508)
		(drill 0.254)
		(layers "F.Cu" "B.Cu")
		(net "P12V_PSU")
	)
	(via
		(at 200.165208 -407.338022)
		(size 0.508)
		(drill 0.254)
		(layers "F.Cu" "B.Cu")
		(net "P12V_PSU")
	)
	(via
		(at 219.977208 -409.420822)
		(size 0.508)
		(drill 0.254)
		(layers "F.Cu" "B.Cu")
		(net "P12V_PSU")
	)
	(via
		(at 200.927208 -407.338022)
		(size 0.508)
		(drill 0.254)
		(layers "F.Cu" "B.Cu")
		(net "P12V_PSU")
	)
	(via
		(at 210.071208 -406.576022)
		(size 0.508)
		(drill 0.254)
		(layers "F.Cu" "B.Cu")
		(net "P12V_PSU")
	)
	(via
		(at 245.877588 -414.71342)
		(size 0.508)
		(drill 0.254)
		(layers "F.Cu" "B.Cu")
		(net "P12V_PSU")
	)
	(via
		(at 188.342016 -408.818334)
		(size 0.508)
		(drill 0.254)
		(layers "F.Cu" "B.Cu")
		(net "P12V_PSU")
	)
	(via
		(at 199.403208 -406.576022)
		(size 0.508)
		(drill 0.254)
		(layers "F.Cu" "B.Cu")
		(net "P12V_PSU")
	)
	(via
		(at 252.390148 -411.70098)
		(size 0.508)
		(drill 0.254)
		(layers "F.Cu" "B.Cu")
		(net "P12V_PSU")
	)
	(via
		(at 210.833208 -408.379422)
		(size 0.508)
		(drill 0.254)
		(layers "F.Cu" "B.Cu")
		(net "P12V_PSU")
	)
	(via
		(at 242.067588 -414.71342)
		(size 0.508)
		(drill 0.254)
		(layers "F.Cu" "B.Cu")
		(net "P12V_PSU")
	)
	(via
		(at 278.612854 -414.071562)
		(size 0.508)
		(drill 0.254)
		(layers "F.Cu" "B.Cu")
		(net "P12V_PSU")
	)
	(via
		(at 253.914148 -412.46298)
		(size 0.508)
		(drill 0.254)
		(layers "F.Cu" "B.Cu")
		(net "P12V_PSU")
	)
	(via
		(at 207.785208 -409.420822)
		(size 0.508)
		(drill 0.254)
		(layers "F.Cu" "B.Cu")
		(net "P12V_PSU")
	)
	(via
		(at 212.237066 -401.419822)
		(size 0.508)
		(drill 0.254)
		(layers "F.Cu" "B.Cu")
		(net "P12V_PSU")
	)
	(via
		(at 220.739208 -409.420822)
		(size 0.508)
		(drill 0.254)
		(layers "F.Cu" "B.Cu")
		(net "P12V_PSU")
	)
	(via
		(at 222.905066 -401.419822)
		(size 0.508)
		(drill 0.254)
		(layers "F.Cu" "B.Cu")
		(net "P12V_PSU")
	)
	(via
		(at 189.866016 -406.481534)
		(size 0.508)
		(drill 0.254)
		(layers "F.Cu" "B.Cu")
		(net "P12V_PSU")
	)
	(via
		(at 189.104016 -406.481534)
		(size 0.508)
		(drill 0.254)
		(layers "F.Cu" "B.Cu")
		(net "P12V_PSU")
	)
	(via
		(at 277.850854 -412.547562)
		(size 0.508)
		(drill 0.254)
		(layers "F.Cu" "B.Cu")
		(net "P12V_PSU")
	)
	(via
		(at 232.169208 -405.814022)
		(size 0.508)
		(drill 0.254)
		(layers "F.Cu" "B.Cu")
		(net "P12V_PSU")
	)
	(via
		(at 189.104016 -407.243534)
		(size 0.508)
		(drill 0.254)
		(layers "F.Cu" "B.Cu")
		(net "P12V_PSU")
	)
	(segment
		(start 192.57391 -411.526228)
		(end 190.628016 -409.580334)
		(width 0.381)
		(layer "B.Cu")
		(net "P12V_PSU")
	)
	(segment
		(start 195.001642 -419.536372)
		(end 195.001642 -413.95396)
		(width 0.381)
		(layer "B.Cu")
		(net "P12V_PSU")
	)
	(segment
		(start 195.001642 -413.95396)
		(end 192.57391 -411.526228)
		(width 0.381)
		(layer "B.Cu")
		(net "P12V_PSU")
	)
	(segment
		(start 196.499734 -424.057064)
		(end 196.724524 -423.832274)
		(width 0.381)
		(layer "B.Cu")
		(net "P12V_PSU")
	)
	(segment
		(start 196.724524 -423.832274)
		(end 196.724524 -421.259254)
		(width 0.381)
		(layer "B.Cu")
		(net "P12V_PSU")
	)
	(segment
		(start 195.253356 -424.057064)
		(end 196.499734 -424.057064)
		(width 0.381)
		(layer "B.Cu")
		(net "P12V_PSU")
	)
	(segment
		(start 196.724524 -421.259254)
		(end 195.718176 -420.252906)
		(width 0.381)
		(layer "B.Cu")
		(net "P12V_PSU")
	)
	(segment
		(start 195.718176 -420.252906)
		(end 195.001642 -419.536372)
		(width 0.381)
		(layer "B.Cu")
		(net "P12V_PSU")
	)
	(segment
		(start 205.14056 -132.069078)
		(end 203.611988 -132.069078)
		(width 0.381)
		(layer "F.Cu")
		(net "P12V_AUX_BLEEDING")
	)
	(segment
		(start 206.45374 -132.069078)
		(end 205.14056 -132.069078)
		(width 0.381)
		(layer "F.Cu")
		(net "P12V_AUX_BLEEDING")
	)
	(segment
		(start 203.611988 -132.069078)
		(end 203.592938 -132.050028)
		(width 0.381)
		(layer "F.Cu")
		(net "P12V_AUX_BLEEDING")
	)
	(via
		(at 205.14056 -132.069078)
		(size 0.762)
		(drill 0.381)
		(layers "F.Cu" "B.Cu")
		(net "P12V_AUX_BLEEDING")
	)
	(segment
		(start 378.28474 -109.540548)
		(end 378.28474 -108.412788)
		(width 0.12954)
		(layer "F.Cu")
		(net "P0V7_JTAG_VREF_2")
	)
	(segment
		(start 378.28474 -107.306618)
		(end 378.16155 -107.183428)
		(width 0.12954)
		(layer "F.Cu")
		(net "P0V7_JTAG_VREF_2")
	)
	(segment
		(start 377.28525 -107.183428)
		(end 378.16155 -107.183428)
		(width 0.12954)
		(layer "F.Cu")
		(net "P0V7_JTAG_VREF_2")
	)
	(segment
		(start 377.06046 -106.581702)
		(end 377.06046 -106.958638)
		(width 0.12954)
		(layer "F.Cu")
		(net "P0V7_JTAG_VREF_2")
	)
	(segment
		(start 377.668536 -103.885492)
		(end 377.607576 -104.192324)
		(width 0.12954)
		(layer "F.Cu")
		(net "P0V7_JTAG_VREF_2")
	)
	(segment
		(start 377.266454 -105.016554)
		(end 376.80392 -105.479088)
		(width 0.12954)
		(layer "F.Cu")
		(net "P0V7_JTAG_VREF_2")
	)
	(segment
		(start 377.94057 -109.720888)
		(end 378.1044 -109.720888)
		(width 0.12954)
		(layer "F.Cu")
		(net "P0V7_JTAG_VREF_2")
	)
	(segment
		(start 377.06046 -106.958638)
		(end 377.28525 -107.183428)
		(width 0.12954)
		(layer "F.Cu")
		(net "P0V7_JTAG_VREF_2")
	)
	(segment
		(start 376.80392 -105.479088)
		(end 376.80392 -106.325162)
		(width 0.12954)
		(layer "F.Cu")
		(net "P0V7_JTAG_VREF_2")
	)
	(segment
		(start 378.1044 -109.720888)
		(end 378.28474 -109.540548)
		(width 0.12954)
		(layer "F.Cu")
		(net "P0V7_JTAG_VREF_2")
	)
	(segment
		(start 376.80392 -106.325162)
		(end 377.06046 -106.581702)
		(width 0.12954)
		(layer "F.Cu")
		(net "P0V7_JTAG_VREF_2")
	)
	(segment
		(start 377.668536 -102.054152)
		(end 377.668536 -103.885492)
		(width 0.12954)
		(layer "F.Cu")
		(net "P0V7_JTAG_VREF_2")
	)
	(segment
		(start 378.28474 -108.412788)
		(end 378.28474 -107.306618)
		(width 0.12954)
		(layer "F.Cu")
		(net "P0V7_JTAG_VREF_2")
	)
	(segment
		(start 377.607576 -104.192324)
		(end 377.266454 -105.016554)
		(width 0.12954)
		(layer "F.Cu")
		(net "P0V7_JTAG_VREF_2")
	)
	(via
		(at 378.28474 -108.412788)
		(size 0.508)
		(drill 0.254)
		(layers "F.Cu" "B.Cu")
		(net "P0V7_JTAG_VREF_2")
	)
	(segment
		(start 180.735732 -423.96156)
		(end 180.735732 -425.6278)
		(width 0.12954)
		(layer "F.Cu")
		(net "FM_MB_PDB_SMB9_R_EN")
	)
	(segment
		(start 180.735732 -425.6278)
		(end 180.735732 -426.8216)
		(width 0.12954)
		(layer "F.Cu")
		(net "FM_MB_PDB_SMB9_R_EN")
	)
	(via
		(at 180.735732 -425.6278)
		(size 0.762)
		(drill 0.381)
		(layers "F.Cu" "B.Cu")
		(net "FM_MB_PDB_SMB9_R_EN")
	)
	(segment
		(start 248.012712 -146.041364)
		(end 244.907054 -149.147022)
		(width 0.12954)
		(layer "F.Cu")
		(net "MB0_P12V_STBY_PWRGD")
	)
	(segment
		(start 172.77588 -134.711948)
		(end 172.77588 -134.095998)
		(width 0.12954)
		(layer "F.Cu")
		(net "MB0_P12V_STBY_PWRGD")
	)
	(segment
		(start 219.791788 -149.147022)
		(end 219.608654 -148.963888)
		(width 0.12954)
		(layer "F.Cu")
		(net "MB0_P12V_STBY_PWRGD")
	)
	(segment
		(start 248.012712 -137.881614)
		(end 248.012712 -146.041364)
		(width 0.12954)
		(layer "F.Cu")
		(net "MB0_P12V_STBY_PWRGD")
	)
	(segment
		(start 294.480234 -388.349998)
		(end 294.480234 -387.143498)
		(width 0.10668)
		(layer "F.Cu")
		(net "MB0_P12V_STBY_PWRGD")
	)
	(segment
		(start 181.127908 -406.14981)
		(end 182.017416 -405.260302)
		(width 0.12954)
		(layer "F.Cu")
		(net "MB0_P12V_STBY_PWRGD")
	)
	(segment
		(start 207.43418 -127.596138)
		(end 208.10728 -127.596138)
		(width 0.12954)
		(layer "F.Cu")
		(net "MB0_P12V_STBY_PWRGD")
	)
	(segment
		(start 219.608654 -148.963888)
		(end 218.890596 -148.963888)
		(width 0.12954)
		(layer "F.Cu")
		(net "MB0_P12V_STBY_PWRGD")
	)
	(segment
		(start 179.742338 -406.898602)
		(end 180.961284 -406.898602)
		(width 0.12954)
		(layer "F.Cu")
		(net "MB0_P12V_STBY_PWRGD")
	)
	(segment
		(start 181.127908 -406.731978)
		(end 181.127908 -406.14981)
		(width 0.12954)
		(layer "F.Cu")
		(net "MB0_P12V_STBY_PWRGD")
	)
	(segment
		(start 172.77588 -134.095998)
		(end 171.50588 -134.095998)
		(width 0.12954)
		(layer "F.Cu")
		(net "MB0_P12V_STBY_PWRGD")
	)
	(segment
		(start 250.513342 -135.380984)
		(end 248.012712 -137.881614)
		(width 0.12954)
		(layer "F.Cu")
		(net "MB0_P12V_STBY_PWRGD")
	)
	(segment
		(start 244.907054 -149.147022)
		(end 219.791788 -149.147022)
		(width 0.12954)
		(layer "F.Cu")
		(net "MB0_P12V_STBY_PWRGD")
	)
	(segment
		(start 180.961284 -406.898602)
		(end 181.127908 -406.731978)
		(width 0.12954)
		(layer "F.Cu")
		(net "MB0_P12V_STBY_PWRGD")
	)
	(segment
		(start 182.913528 -405.260302)
		(end 183.21401 -404.95982)
		(width 0.12954)
		(layer "F.Cu")
		(net "MB0_P12V_STBY_PWRGD")
	)
	(segment
		(start 182.017416 -405.260302)
		(end 182.913528 -405.260302)
		(width 0.12954)
		(layer "F.Cu")
		(net "MB0_P12V_STBY_PWRGD")
	)
	(segment
		(start 218.890596 -148.963888)
		(end 218.199716 -148.273008)
		(width 0.12954)
		(layer "F.Cu")
		(net "MB0_P12V_STBY_PWRGD")
	)
	(via
		(at 422.90238 -119.916448)
		(size 0.508)
		(drill 0.254)
		(layers "F.Cu" "B.Cu")
		(net "MB0_P12V_STBY_PWRGD")
	)
	(via
		(at 250.513342 -135.380984)
		(size 0.508)
		(drill 0.254)
		(layers "F.Cu" "B.Cu")
		(net "MB0_P12V_STBY_PWRGD")
	)
	(via
		(at 294.480234 -387.143498)
		(size 0.508)
		(drill 0.254)
		(layers "F.Cu" "B.Cu")
		(net "MB0_P12V_STBY_PWRGD")
	)
	(via
		(at 282.4988 -434.086)
		(size 0.508)
		(drill 0.254)
		(layers "F.Cu" "B.Cu")
		(net "MB0_P12V_STBY_PWRGD")
	)
	(via
		(at 172.77588 -134.711948)
		(size 0.508)
		(drill 0.254)
		(layers "F.Cu" "B.Cu")
		(net "MB0_P12V_STBY_PWRGD")
	)
	(via
		(at 208.10728 -127.596138)
		(size 0.508)
		(drill 0.254)
		(layers "F.Cu" "B.Cu")
		(net "MB0_P12V_STBY_PWRGD")
	)
	(via
		(at 218.199716 -148.273008)
		(size 0.508)
		(drill 0.254)
		(layers "F.Cu" "B.Cu")
		(net "MB0_P12V_STBY_PWRGD")
	)
	(via
		(at 177.444908 -147.456144)
		(size 0.508)
		(drill 0.254)
		(layers "F.Cu" "B.Cu")
		(net "MB0_P12V_STBY_PWRGD")
	)
	(via
		(at 181.127908 -406.731978)
		(size 0.762)
		(drill 0.254)
		(layers "F.Cu" "B.Cu")
		(net "MB0_P12V_STBY_PWRGD")
	)
	(via
		(at 250.27128 -327.345548)
		(size 0.508)
		(drill 0.254)
		(layers "F.Cu" "B.Cu")
		(net "MB0_P12V_STBY_PWRGD")
	)
	(segment
		(start 466.568028 -101.981762)
		(end 466.568028 -109.409738)
		(width 0.12954)
		(layer "B.Cu")
		(net "MB0_P12V_STBY_PWRGD")
	)
	(segment
		(start 453.195436 -111.40948)
		(end 451.94601 -112.658906)
		(width 0.12954)
		(layer "B.Cu")
		(net "MB0_P12V_STBY_PWRGD")
	)
	(segment
		(start 422.90238 -117.14734)
		(end 422.90238 -119.916448)
		(width 0.12954)
		(layer "B.Cu")
		(net "MB0_P12V_STBY_PWRGD")
	)
	(segment
		(start 451.947026 -77.91577)
		(end 451.947026 -78.589632)
		(width 0.12954)
		(layer "B.Cu")
		(net "MB0_P12V_STBY_PWRGD")
	)
	(segment
		(start 465.0486 -82.184748)
		(end 466.05444 -83.190588)
		(width 0.12954)
		(layer "B.Cu")
		(net "MB0_P12V_STBY_PWRGD")
	)
	(segment
		(start 466.05444 -96.937068)
		(end 465.77504 -97.216468)
		(width 0.12954)
		(layer "B.Cu")
		(net "MB0_P12V_STBY_PWRGD")
	)
	(segment
		(start 451.94601 -112.658906)
		(end 427.390814 -112.658906)
		(width 0.12954)
		(layer "B.Cu")
		(net "MB0_P12V_STBY_PWRGD")
	)
	(segment
		(start 427.390814 -112.658906)
		(end 422.90238 -117.14734)
		(width 0.12954)
		(layer "B.Cu")
		(net "MB0_P12V_STBY_PWRGD")
	)
	(segment
		(start 465.77504 -97.216468)
		(end 465.77504 -101.188774)
		(width 0.12954)
		(layer "B.Cu")
		(net "MB0_P12V_STBY_PWRGD")
	)
	(segment
		(start 465.77504 -101.188774)
		(end 466.568028 -101.981762)
		(width 0.12954)
		(layer "B.Cu")
		(net "MB0_P12V_STBY_PWRGD")
	)
	(segment
		(start 451.947026 -78.589632)
		(end 452.247 -78.889606)
		(width 0.12954)
		(layer "B.Cu")
		(net "MB0_P12V_STBY_PWRGD")
	)
	(segment
		(start 466.05444 -83.190588)
		(end 466.05444 -96.937068)
		(width 0.12954)
		(layer "B.Cu")
		(net "MB0_P12V_STBY_PWRGD")
	)
	(segment
		(start 453.863202 -79.831946)
		(end 456.216004 -82.184748)
		(width 0.12954)
		(layer "B.Cu")
		(net "MB0_P12V_STBY_PWRGD")
	)
	(segment
		(start 464.568286 -111.40948)
		(end 453.195436 -111.40948)
		(width 0.12954)
		(layer "B.Cu")
		(net "MB0_P12V_STBY_PWRGD")
	)
	(segment
		(start 181.127908 -406.731978)
		(end 180.330602 -406.731978)
		(width 0.12954)
		(layer "B.Cu")
		(net "MB0_P12V_STBY_PWRGD")
	)
	(segment
		(start 452.247 -79.831946)
		(end 453.863202 -79.831946)
		(width 0.12954)
		(layer "B.Cu")
		(net "MB0_P12V_STBY_PWRGD")
	)
	(segment
		(start 456.216004 -82.184748)
		(end 465.0486 -82.184748)
		(width 0.12954)
		(layer "B.Cu")
		(net "MB0_P12V_STBY_PWRGD")
	)
	(segment
		(start 466.568028 -109.409738)
		(end 464.568286 -111.40948)
		(width 0.12954)
		(layer "B.Cu")
		(net "MB0_P12V_STBY_PWRGD")
	)
	(segment
		(start 180.330602 -406.731978)
		(end 180.158898 -406.903682)
		(width 0.12954)
		(layer "B.Cu")
		(net "MB0_P12V_STBY_PWRGD")
	)
	(segment
		(start 452.247 -78.889606)
		(end 452.247 -79.831946)
		(width 0.12954)
		(layer "B.Cu")
		(net "MB0_P12V_STBY_PWRGD")
	)
	(segment
		(start 242.47348 -335.143348)
		(end 242.47348 -354.219764)
		(width 0.127)
		(layer "In2.Cu")
		(net "MB0_P12V_STBY_PWRGD")
	)
	(segment
		(start 182.45836 -398.388332)
		(end 182.804308 -398.73428)
		(width 0.127)
		(layer "In2.Cu")
		(net "MB0_P12V_STBY_PWRGD")
	)
	(segment
		(start 181.49062 -402.85416)
		(end 181.98846 -403.352)
		(width 0.127)
		(layer "In2.Cu")
		(net "MB0_P12V_STBY_PWRGD")
	)
	(segment
		(start 181.98846 -403.352)
		(end 181.98846 -405.29256)
		(width 0.127)
		(layer "In2.Cu")
		(net "MB0_P12V_STBY_PWRGD")
	)
	(segment
		(start 182.804308 -400.425412)
		(end 181.49062 -401.7391)
		(width 0.127)
		(layer "In2.Cu")
		(net "MB0_P12V_STBY_PWRGD")
	)
	(segment
		(start 177.444908 -147.456144)
		(end 172.77588 -142.787116)
		(width 0.127)
		(layer "In2.Cu")
		(net "MB0_P12V_STBY_PWRGD")
	)
	(segment
		(start 242.47348 -354.219764)
		(end 220.746066 -375.947178)
		(width 0.127)
		(layer "In2.Cu")
		(net "MB0_P12V_STBY_PWRGD")
	)
	(segment
		(start 181.127908 -406.153112)
		(end 181.127908 -406.731978)
		(width 0.127)
		(layer "In2.Cu")
		(net "MB0_P12V_STBY_PWRGD")
	)
	(segment
		(start 181.49062 -401.7391)
		(end 181.49062 -402.85416)
		(width 0.127)
		(layer "In2.Cu")
		(net "MB0_P12V_STBY_PWRGD")
	)
	(segment
		(start 182.804308 -393.306554)
		(end 182.804308 -397.19758)
		(width 0.127)
		(layer "In2.Cu")
		(net "MB0_P12V_STBY_PWRGD")
	)
	(segment
		(start 200.163684 -375.947178)
		(end 182.804308 -393.306554)
		(width 0.127)
		(layer "In2.Cu")
		(net "MB0_P12V_STBY_PWRGD")
	)
	(segment
		(start 250.27128 -327.345548)
		(end 242.47348 -335.143348)
		(width 0.127)
		(layer "In2.Cu")
		(net "MB0_P12V_STBY_PWRGD")
	)
	(segment
		(start 182.804308 -398.73428)
		(end 182.804308 -400.425412)
		(width 0.127)
		(layer "In2.Cu")
		(net "MB0_P12V_STBY_PWRGD")
	)
	(segment
		(start 182.45836 -397.543528)
		(end 182.45836 -398.388332)
		(width 0.127)
		(layer "In2.Cu")
		(net "MB0_P12V_STBY_PWRGD")
	)
	(segment
		(start 182.804308 -397.19758)
		(end 182.45836 -397.543528)
		(width 0.127)
		(layer "In2.Cu")
		(net "MB0_P12V_STBY_PWRGD")
	)
	(segment
		(start 172.77588 -142.787116)
		(end 172.77588 -134.711948)
		(width 0.127)
		(layer "In2.Cu")
		(net "MB0_P12V_STBY_PWRGD")
	)
	(segment
		(start 181.98846 -405.29256)
		(end 181.127908 -406.153112)
		(width 0.127)
		(layer "In2.Cu")
		(net "MB0_P12V_STBY_PWRGD")
	)
	(segment
		(start 220.746066 -375.947178)
		(end 200.163684 -375.947178)
		(width 0.127)
		(layer "In2.Cu")
		(net "MB0_P12V_STBY_PWRGD")
	)
	(segment
		(start 295.7703 -404.7871)
		(end 292.23208 -408.32532)
		(width 0.127)
		(layer "In6.Cu")
		(net "MB0_P12V_STBY_PWRGD")
	)
	(segment
		(start 291.08146 -408.32532)
		(end 289.504882 -409.901898)
		(width 0.127)
		(layer "In6.Cu")
		(net "MB0_P12V_STBY_PWRGD")
	)
	(segment
		(start 281.805634 -418.584126)
		(end 281.805634 -425.269914)
		(width 0.127)
		(layer "In6.Cu")
		(net "MB0_P12V_STBY_PWRGD")
	)
	(segment
		(start 289.504882 -409.901898)
		(end 288.954718 -409.901898)
		(width 0.127)
		(layer "In6.Cu")
		(net "MB0_P12V_STBY_PWRGD")
	)
	(segment
		(start 294.480234 -387.143498)
		(end 294.480234 -389.206994)
		(width 0.127)
		(layer "In6.Cu")
		(net "MB0_P12V_STBY_PWRGD")
	)
	(segment
		(start 296.642282 -404.270718)
		(end 296.1259 -404.7871)
		(width 0.127)
		(layer "In6.Cu")
		(net "MB0_P12V_STBY_PWRGD")
	)
	(segment
		(start 298.209462 -397.872458)
		(end 296.642282 -399.439638)
		(width 0.127)
		(layer "In6.Cu")
		(net "MB0_P12V_STBY_PWRGD")
	)
	(segment
		(start 292.23208 -408.32532)
		(end 291.08146 -408.32532)
		(width 0.127)
		(layer "In6.Cu")
		(net "MB0_P12V_STBY_PWRGD")
	)
	(segment
		(start 285.089854 -413.766762)
		(end 285.089854 -415.299906)
		(width 0.127)
		(layer "In6.Cu")
		(net "MB0_P12V_STBY_PWRGD")
	)
	(segment
		(start 288.954718 -409.901898)
		(end 285.089854 -413.766762)
		(width 0.127)
		(layer "In6.Cu")
		(net "MB0_P12V_STBY_PWRGD")
	)
	(segment
		(start 282.042108 -425.506388)
		(end 282.042108 -433.629308)
		(width 0.127)
		(layer "In6.Cu")
		(net "MB0_P12V_STBY_PWRGD")
	)
	(segment
		(start 296.642282 -399.439638)
		(end 296.642282 -404.270718)
		(width 0.127)
		(layer "In6.Cu")
		(net "MB0_P12V_STBY_PWRGD")
	)
	(segment
		(start 285.089854 -415.299906)
		(end 281.805634 -418.584126)
		(width 0.127)
		(layer "In6.Cu")
		(net "MB0_P12V_STBY_PWRGD")
	)
	(segment
		(start 281.805634 -425.269914)
		(end 282.042108 -425.506388)
		(width 0.127)
		(layer "In6.Cu")
		(net "MB0_P12V_STBY_PWRGD")
	)
	(segment
		(start 296.1259 -404.7871)
		(end 295.7703 -404.7871)
		(width 0.127)
		(layer "In6.Cu")
		(net "MB0_P12V_STBY_PWRGD")
	)
	(segment
		(start 298.209462 -392.936222)
		(end 298.209462 -397.872458)
		(width 0.127)
		(layer "In6.Cu")
		(net "MB0_P12V_STBY_PWRGD")
	)
	(segment
		(start 294.480234 -389.206994)
		(end 298.209462 -392.936222)
		(width 0.127)
		(layer "In6.Cu")
		(net "MB0_P12V_STBY_PWRGD")
	)
	(segment
		(start 282.042108 -433.629308)
		(end 282.4988 -434.086)
		(width 0.127)
		(layer "In6.Cu")
		(net "MB0_P12V_STBY_PWRGD")
	)
	(segment
		(start 207.363568 -129.352294)
		(end 208.10728 -128.608582)
		(width 0.127)
		(layer "In11.Cu")
		(net "MB0_P12V_STBY_PWRGD")
	)
	(segment
		(start 208.10728 -128.608582)
		(end 208.10728 -127.596138)
		(width 0.127)
		(layer "In11.Cu")
		(net "MB0_P12V_STBY_PWRGD")
	)
	(segment
		(start 249.83948 -201.854816)
		(end 249.83948 -326.913748)
		(width 0.127)
		(layer "In11.Cu")
		(net "MB0_P12V_STBY_PWRGD")
	)
	(segment
		(start 207.363568 -129.912618)
		(end 207.363568 -129.352294)
		(width 0.127)
		(layer "In11.Cu")
		(net "MB0_P12V_STBY_PWRGD")
	)
	(segment
		(start 249.83948 -326.913748)
		(end 250.27128 -327.345548)
		(width 0.127)
		(layer "In11.Cu")
		(net "MB0_P12V_STBY_PWRGD")
	)
	(segment
		(start 248.012712 -200.028048)
		(end 249.83948 -201.854816)
		(width 0.127)
		(layer "In11.Cu")
		(net "MB0_P12V_STBY_PWRGD")
	)
	(segment
		(start 208.214214 -135.719312)
		(end 208.214214 -130.763264)
		(width 0.127)
		(layer "In11.Cu")
		(net "MB0_P12V_STBY_PWRGD")
	)
	(segment
		(start 248.012712 -137.881614)
		(end 248.012712 -200.028048)
		(width 0.127)
		(layer "In11.Cu")
		(net "MB0_P12V_STBY_PWRGD")
	)
	(segment
		(start 218.199716 -145.704814)
		(end 208.214214 -135.719312)
		(width 0.127)
		(layer "In11.Cu")
		(net "MB0_P12V_STBY_PWRGD")
	)
	(segment
		(start 250.513342 -135.380984)
		(end 248.012712 -137.881614)
		(width 0.127)
		(layer "In11.Cu")
		(net "MB0_P12V_STBY_PWRGD")
	)
	(segment
		(start 218.199716 -148.273008)
		(end 218.199716 -145.704814)
		(width 0.127)
		(layer "In11.Cu")
		(net "MB0_P12V_STBY_PWRGD")
	)
	(segment
		(start 208.214214 -130.763264)
		(end 207.363568 -129.912618)
		(width 0.127)
		(layer "In11.Cu")
		(net "MB0_P12V_STBY_PWRGD")
	)
	(segment
		(start 225.37928 -118.608348)
		(end 217.09888 -126.888748)
		(width 0.127)
		(layer "In13.Cu")
		(net "MB0_P12V_STBY_PWRGD")
	)
	(segment
		(start 217.09888 -126.888748)
		(end 214.91448 -126.888748)
		(width 0.127)
		(layer "In13.Cu")
		(net "MB0_P12V_STBY_PWRGD")
	)
	(segment
		(start 251.78131 -125.166628)
		(end 251.277628 -124.662946)
		(width 0.127)
		(layer "In13.Cu")
		(net "MB0_P12V_STBY_PWRGD")
	)
	(segment
		(start 214.91448 -126.888748)
		(end 213.51748 -128.285748)
		(width 0.127)
		(layer "In13.Cu")
		(net "MB0_P12V_STBY_PWRGD")
	)
	(segment
		(start 213.51748 -128.285748)
		(end 210.24088 -128.285748)
		(width 0.127)
		(layer "In13.Cu")
		(net "MB0_P12V_STBY_PWRGD")
	)
	(segment
		(start 251.277628 -124.662946)
		(end 251.277628 -124.6632)
		(width 0.127)
		(layer "In13.Cu")
		(net "MB0_P12V_STBY_PWRGD")
	)
	(segment
		(start 209.55127 -127.596138)
		(end 208.10728 -127.596138)
		(width 0.127)
		(layer "In13.Cu")
		(net "MB0_P12V_STBY_PWRGD")
	)
	(segment
		(start 422.90238 -119.916448)
		(end 417.6522 -125.166628)
		(width 0.127)
		(layer "In13.Cu")
		(net "MB0_P12V_STBY_PWRGD")
	)
	(segment
		(start 210.24088 -128.285748)
		(end 209.55127 -127.596138)
		(width 0.127)
		(layer "In13.Cu")
		(net "MB0_P12V_STBY_PWRGD")
	)
	(segment
		(start 417.6522 -125.166628)
		(end 251.78131 -125.166628)
		(width 0.127)
		(layer "In13.Cu")
		(net "MB0_P12V_STBY_PWRGD")
	)
	(segment
		(start 251.277628 -124.6632)
		(end 246.035576 -119.421148)
		(width 0.127)
		(layer "In13.Cu")
		(net "MB0_P12V_STBY_PWRGD")
	)
	(segment
		(start 246.035576 -119.421148)
		(end 233.580432 -119.421148)
		(width 0.127)
		(layer "In13.Cu")
		(net "MB0_P12V_STBY_PWRGD")
	)
	(segment
		(start 232.767632 -118.608348)
		(end 225.37928 -118.608348)
		(width 0.127)
		(layer "In13.Cu")
		(net "MB0_P12V_STBY_PWRGD")
	)
	(segment
		(start 233.580432 -119.421148)
		(end 232.767632 -118.608348)
		(width 0.127)
		(layer "In13.Cu")
		(net "MB0_P12V_STBY_PWRGD")
	)
	(segment
		(start 184.2516 -148.026882)
		(end 182.786782 -148.026882)
		(width 0.127)
		(layer "In15.Cu")
		(net "MB0_P12V_STBY_PWRGD")
	)
	(segment
		(start 281.51709 -438.78627)
		(end 280.68778 -439.61558)
		(width 0.127)
		(layer "In15.Cu")
		(net "MB0_P12V_STBY_PWRGD")
	)
	(segment
		(start 181.29758 -411.84068)
		(end 181.29758 -406.90165)
		(width 0.127)
		(layer "In15.Cu")
		(net "MB0_P12V_STBY_PWRGD")
	)
	(segment
		(start 198.0946 -438.35574)
		(end 195.80098 -436.06212)
		(width 0.127)
		(layer "In15.Cu")
		(net "MB0_P12V_STBY_PWRGD")
	)
	(segment
		(start 282.98902 -435.022498)
		(end 281.51709 -436.494428)
		(width 0.127)
		(layer "In15.Cu")
		(net "MB0_P12V_STBY_PWRGD")
	)
	(segment
		(start 278.01316 -439.61558)
		(end 276.75332 -438.35574)
		(width 0.127)
		(layer "In15.Cu")
		(net "MB0_P12V_STBY_PWRGD")
	)
	(segment
		(start 216.591388 -148.273008)
		(end 215.009984 -146.691604)
		(width 0.127)
		(layer "In15.Cu")
		(net "MB0_P12V_STBY_PWRGD")
	)
	(segment
		(start 181.29758 -406.90165)
		(end 181.127908 -406.731978)
		(width 0.127)
		(layer "In15.Cu")
		(net "MB0_P12V_STBY_PWRGD")
	)
	(segment
		(start 195.80098 -436.06212)
		(end 195.80098 -426.34408)
		(width 0.127)
		(layer "In15.Cu")
		(net "MB0_P12V_STBY_PWRGD")
	)
	(segment
		(start 177.595784 -147.305268)
		(end 177.444908 -147.456144)
		(width 0.127)
		(layer "In15.Cu")
		(net "MB0_P12V_STBY_PWRGD")
	)
	(segment
		(start 218.199716 -148.273008)
		(end 216.591388 -148.273008)
		(width 0.127)
		(layer "In15.Cu")
		(net "MB0_P12V_STBY_PWRGD")
	)
	(segment
		(start 182.065168 -147.305268)
		(end 177.595784 -147.305268)
		(width 0.127)
		(layer "In15.Cu")
		(net "MB0_P12V_STBY_PWRGD")
	)
	(segment
		(start 282.4988 -434.086)
		(end 282.98902 -434.57622)
		(width 0.127)
		(layer "In15.Cu")
		(net "MB0_P12V_STBY_PWRGD")
	)
	(segment
		(start 280.68778 -439.61558)
		(end 278.01316 -439.61558)
		(width 0.127)
		(layer "In15.Cu")
		(net "MB0_P12V_STBY_PWRGD")
	)
	(segment
		(start 182.786782 -148.026882)
		(end 182.065168 -147.305268)
		(width 0.127)
		(layer "In15.Cu")
		(net "MB0_P12V_STBY_PWRGD")
	)
	(segment
		(start 195.80098 -426.34408)
		(end 181.29758 -411.84068)
		(width 0.127)
		(layer "In15.Cu")
		(net "MB0_P12V_STBY_PWRGD")
	)
	(segment
		(start 281.51709 -436.494428)
		(end 281.51709 -438.78627)
		(width 0.127)
		(layer "In15.Cu")
		(net "MB0_P12V_STBY_PWRGD")
	)
	(segment
		(start 282.98902 -434.57622)
		(end 282.98902 -435.022498)
		(width 0.127)
		(layer "In15.Cu")
		(net "MB0_P12V_STBY_PWRGD")
	)
	(segment
		(start 276.75332 -438.35574)
		(end 198.0946 -438.35574)
		(width 0.127)
		(layer "In15.Cu")
		(net "MB0_P12V_STBY_PWRGD")
	)
	(segment
		(start 215.009984 -146.691604)
		(end 185.586878 -146.691604)
		(width 0.127)
		(layer "In15.Cu")
		(net "MB0_P12V_STBY_PWRGD")
	)
	(segment
		(start 185.586878 -146.691604)
		(end 184.2516 -148.026882)
		(width 0.127)
		(layer "In15.Cu")
		(net "MB0_P12V_STBY_PWRGD")
	)
	(segment
		(start 34.412428 -102.71379)
		(end 33.208722 -102.71379)
		(width 0.12954)
		(layer "F.Cu")
		(net "MAX11617_VREF_R")
	)
	(segment
		(start 33.208722 -102.71379)
		(end 33.161478 -102.761034)
		(width 0.12954)
		(layer "F.Cu")
		(net "MAX11617_VREF_R")
	)
	(segment
		(start 36.988496 -102.71379)
		(end 34.412428 -102.71379)
		(width 0.12954)
		(layer "F.Cu")
		(net "MAX11617_VREF_R")
	)
	(via
		(at 34.412428 -102.71379)
		(size 0.762)
		(drill 0.381)
		(layers "F.Cu" "B.Cu")
		(net "MAX11617_VREF_R")
	)
	(segment
		(start 29.586428 -104.031034)
		(end 28.189428 -104.031034)
		(width 0.12954)
		(layer "F.Cu")
		(net "MAX11617_VREF")
	)
	(segment
		(start 30.494478 -102.761034)
		(end 30.494478 -103.757984)
		(width 0.12954)
		(layer "F.Cu")
		(net "MAX11617_VREF")
	)
	(segment
		(start 30.494478 -103.757984)
		(end 30.221428 -104.031034)
		(width 0.12954)
		(layer "F.Cu")
		(net "MAX11617_VREF")
	)
	(segment
		(start 27.935428 -103.777034)
		(end 27.935428 -102.888034)
		(width 0.12954)
		(layer "F.Cu")
		(net "MAX11617_VREF")
	)
	(segment
		(start 30.494478 -102.761034)
		(end 32.361378 -102.761034)
		(width 0.12954)
		(layer "F.Cu")
		(net "MAX11617_VREF")
	)
	(segment
		(start 28.189428 -104.031034)
		(end 27.935428 -103.777034)
		(width 0.12954)
		(layer "F.Cu")
		(net "MAX11617_VREF")
	)
	(segment
		(start 30.221428 -104.031034)
		(end 29.586428 -104.031034)
		(width 0.12954)
		(layer "F.Cu")
		(net "MAX11617_VREF")
	)
	(via
		(at 29.586428 -104.031034)
		(size 0.762)
		(drill 0.381)
		(layers "F.Cu" "B.Cu")
		(net "MAX11617_VREF")
	)
	(segment
		(start 106.55808 -101.559868)
		(end 107.65536 -101.559868)
		(width 0.12954)
		(layer "F.Cu")
		(net "LED_RST_RSMRST_PLD_R_N_D")
	)
	(segment
		(start 108.25353 -103.593138)
		(end 108.956348 -103.593138)
		(width 0.12954)
		(layer "F.Cu")
		(net "LED_RST_RSMRST_PLD_R_N_D")
	)
	(segment
		(start 107.98302 -101.887528)
		(end 107.98302 -103.322628)
		(width 0.12954)
		(layer "F.Cu")
		(net "LED_RST_RSMRST_PLD_R_N_D")
	)
	(segment
		(start 105.62082 -100.622608)
		(end 106.55808 -101.559868)
		(width 0.12954)
		(layer "F.Cu")
		(net "LED_RST_RSMRST_PLD_R_N_D")
	)
	(segment
		(start 103.673656 -79.078836)
		(end 103.673656 -98.675444)
		(width 0.12954)
		(layer "F.Cu")
		(net "LED_RST_RSMRST_PLD_R_N_D")
	)
	(segment
		(start 107.65536 -101.559868)
		(end 107.98302 -101.887528)
		(width 0.12954)
		(layer "F.Cu")
		(net "LED_RST_RSMRST_PLD_R_N_D")
	)
	(segment
		(start 107.98302 -103.322628)
		(end 108.25353 -103.593138)
		(width 0.12954)
		(layer "F.Cu")
		(net "LED_RST_RSMRST_PLD_R_N_D")
	)
	(segment
		(start 103.673656 -98.675444)
		(end 105.62082 -100.622608)
		(width 0.12954)
		(layer "F.Cu")
		(net "LED_RST_RSMRST_PLD_R_N_D")
	)
	(via
		(at 105.62082 -100.622608)
		(size 0.762)
		(drill 0.381)
		(layers "F.Cu" "B.Cu")
		(net "LED_RST_RSMRST_PLD_R_N_D")
	)
	(segment
		(start 102.723696 -77.686154)
		(end 102.723696 -79.078836)
		(width 0.12954)
		(layer "F.Cu")
		(net "LED_RST_RSMRST_PLD_R_N")
	)
	(segment
		(start 102.67061 -75.35926)
		(end 102.67061 -76.592176)
		(width 0.12954)
		(layer "F.Cu")
		(net "LED_RST_RSMRST_PLD_R_N")
	)
	(segment
		(start 102.67061 -77.633068)
		(end 102.723696 -77.686154)
		(width 0.12954)
		(layer "F.Cu")
		(net "LED_RST_RSMRST_PLD_R_N")
	)
	(segment
		(start 102.67061 -76.592176)
		(end 102.67061 -77.633068)
		(width 0.12954)
		(layer "F.Cu")
		(net "LED_RST_RSMRST_PLD_R_N")
	)
	(via
		(at 102.67061 -76.592176)
		(size 0.762)
		(drill 0.381)
		(layers "F.Cu" "B.Cu")
		(net "LED_RST_RSMRST_PLD_R_N")
	)
	(segment
		(start 98.73869 -98.775266)
		(end 99.97059 -98.775266)
		(width 0.12954)
		(layer "F.Cu")
		(net "LED_RST_PLTRST_N_D")
	)
	(segment
		(start 98.176588 -98.213164)
		(end 98.73869 -98.775266)
		(width 0.12954)
		(layer "F.Cu")
		(net "LED_RST_PLTRST_N_D")
	)
	(segment
		(start 84.656676 -70.78599)
		(end 85.37194 -71.501254)
		(width 0.12954)
		(layer "F.Cu")
		(net "LED_RST_PLTRST_N_D")
	)
	(segment
		(start 98.176588 -94.64802)
		(end 98.176588 -98.213164)
		(width 0.12954)
		(layer "F.Cu")
		(net "LED_RST_PLTRST_N_D")
	)
	(segment
		(start 85.37194 -80.239108)
		(end 90.0684 -84.935568)
		(width 0.12954)
		(layer "F.Cu")
		(net "LED_RST_PLTRST_N_D")
	)
	(segment
		(start 97.07626 -91.722448)
		(end 97.07626 -93.547692)
		(width 0.12954)
		(layer "F.Cu")
		(net "LED_RST_PLTRST_N_D")
	)
	(segment
		(start 90.0684 -84.935568)
		(end 92.86748 -84.935568)
		(width 0.12954)
		(layer "F.Cu")
		(net "LED_RST_PLTRST_N_D")
	)
	(segment
		(start 96.422718 -91.068906)
		(end 97.07626 -91.722448)
		(width 0.12954)
		(layer "F.Cu")
		(net "LED_RST_PLTRST_N_D")
	)
	(segment
		(start 85.37194 -71.501254)
		(end 85.37194 -80.239108)
		(width 0.12954)
		(layer "F.Cu")
		(net "LED_RST_PLTRST_N_D")
	)
	(segment
		(start 92.86748 -84.935568)
		(end 96.422718 -88.490806)
		(width 0.12954)
		(layer "F.Cu")
		(net "LED_RST_PLTRST_N_D")
	)
	(segment
		(start 96.422718 -88.490806)
		(end 96.422718 -91.068906)
		(width 0.12954)
		(layer "F.Cu")
		(net "LED_RST_PLTRST_N_D")
	)
	(segment
		(start 99.97059 -98.775266)
		(end 99.97186 -98.773996)
		(width 0.12954)
		(layer "F.Cu")
		(net "LED_RST_PLTRST_N_D")
	)
	(segment
		(start 97.07626 -93.547692)
		(end 98.176588 -94.64802)
		(width 0.12954)
		(layer "F.Cu")
		(net "LED_RST_PLTRST_N_D")
	)
	(via
		(at 98.73869 -98.775266)
		(size 0.762)
		(drill 0.381)
		(layers "F.Cu" "B.Cu")
		(net "LED_RST_PLTRST_N_D")
	)
	(segment
		(start 83.730592 -65.469008)
		(end 83.730592 -66.719958)
		(width 0.12954)
		(layer "F.Cu")
		(net "LED_RST_PLTRST_N")
	)
	(segment
		(start 83.730592 -66.719958)
		(end 83.730592 -67.734688)
		(width 0.12954)
		(layer "F.Cu")
		(net "LED_RST_PLTRST_N")
	)
	(segment
		(start 83.730592 -67.734688)
		(end 83.706716 -67.758564)
		(width 0.12954)
		(layer "F.Cu")
		(net "LED_RST_PLTRST_N")
	)
	(segment
		(start 83.706716 -67.758564)
		(end 83.706716 -70.78599)
		(width 0.12954)
		(layer "F.Cu")
		(net "LED_RST_PLTRST_N")
	)
	(via
		(at 83.730592 -66.719958)
		(size 0.762)
		(drill 0.381)
		(layers "F.Cu" "B.Cu")
		(net "LED_RST_PLTRST_N")
	)
	(segment
		(start 77.72146 -104.000808)
		(end 83.0961 -104.000808)
		(width 0.12954)
		(layer "F.Cu")
		(net "LED_RST_PLD_CPU1_DRAM_GH_N_D")
	)
	(segment
		(start 59.053476 -75.630278)
		(end 55.890668 -78.793086)
		(width 0.12954)
		(layer "F.Cu")
		(net "LED_RST_PLD_CPU1_DRAM_GH_N_D")
	)
	(segment
		(start 83.0961 -104.000808)
		(end 83.15198 -104.056688)
		(width 0.12954)
		(layer "F.Cu")
		(net "LED_RST_PLD_CPU1_DRAM_GH_N_D")
	)
	(segment
		(start 86.526116 -103.786432)
		(end 86.526116 -103.259636)
		(width 0.12954)
		(layer "F.Cu")
		(net "LED_RST_PLD_CPU1_DRAM_GH_N_D")
	)
	(segment
		(start 59.053476 -70.78599)
		(end 59.053476 -75.630278)
		(width 0.12954)
		(layer "F.Cu")
		(net "LED_RST_PLD_CPU1_DRAM_GH_N_D")
	)
	(segment
		(start 55.890668 -78.793086)
		(end 55.890668 -82.170016)
		(width 0.12954)
		(layer "F.Cu")
		(net "LED_RST_PLD_CPU1_DRAM_GH_N_D")
	)
	(segment
		(start 55.890668 -82.170016)
		(end 77.72146 -104.000808)
		(width 0.12954)
		(layer "F.Cu")
		(net "LED_RST_PLD_CPU1_DRAM_GH_N_D")
	)
	(segment
		(start 83.15198 -104.056688)
		(end 86.25586 -104.056688)
		(width 0.12954)
		(layer "F.Cu")
		(net "LED_RST_PLD_CPU1_DRAM_GH_N_D")
	)
	(segment
		(start 86.25586 -104.056688)
		(end 86.526116 -103.786432)
		(width 0.12954)
		(layer "F.Cu")
		(net "LED_RST_PLD_CPU1_DRAM_GH_N_D")
	)
	(via
		(at 83.0961 -104.000808)
		(size 0.762)
		(drill 0.381)
		(layers "F.Cu" "B.Cu")
		(net "LED_RST_PLD_CPU1_DRAM_GH_N_D")
	)
	(segment
		(start 58.103516 -69.826632)
		(end 58.103516 -70.78599)
		(width 0.12954)
		(layer "F.Cu")
		(net "LED_RST_PLD_CPU1_DRAM_GH_N")
	)
	(segment
		(start 68.010786 -66.718688)
		(end 67.327526 -67.401948)
		(width 0.12954)
		(layer "F.Cu")
		(net "LED_RST_PLD_CPU1_DRAM_GH_N")
	)
	(segment
		(start 68.010786 -65.482724)
		(end 68.010786 -66.718688)
		(width 0.12954)
		(layer "F.Cu")
		(net "LED_RST_PLD_CPU1_DRAM_GH_N")
	)
	(segment
		(start 67.327526 -67.401948)
		(end 60.5282 -67.401948)
		(width 0.12954)
		(layer "F.Cu")
		(net "LED_RST_PLD_CPU1_DRAM_GH_N")
	)
	(segment
		(start 60.5282 -67.401948)
		(end 58.103516 -69.826632)
		(width 0.12954)
		(layer "F.Cu")
		(net "LED_RST_PLD_CPU1_DRAM_GH_N")
	)
	(via
		(at 68.010786 -66.718688)
		(size 0.762)
		(drill 0.381)
		(layers "F.Cu" "B.Cu")
		(net "LED_RST_PLD_CPU1_DRAM_GH_N")
	)
	(segment
		(start 62.253876 -72.828658)
		(end 56.172608 -78.909926)
		(width 0.12954)
		(layer "F.Cu")
		(net "LED_RST_PLD_CPU1_DRAM_EF_N_D")
	)
	(segment
		(start 83.07324 -101.694234)
		(end 84.660994 -101.694234)
		(width 0.12954)
		(layer "F.Cu")
		(net "LED_RST_PLD_CPU1_DRAM_EF_N_D")
	)
	(segment
		(start 62.253876 -70.78599)
		(end 62.253876 -72.828658)
		(width 0.12954)
		(layer "F.Cu")
		(net "LED_RST_PLD_CPU1_DRAM_EF_N_D")
	)
	(segment
		(start 56.172608 -78.909926)
		(end 56.172608 -82.053176)
		(width 0.12954)
		(layer "F.Cu")
		(net "LED_RST_PLD_CPU1_DRAM_EF_N_D")
	)
	(segment
		(start 56.172608 -82.053176)
		(end 75.813666 -101.694234)
		(width 0.12954)
		(layer "F.Cu")
		(net "LED_RST_PLD_CPU1_DRAM_EF_N_D")
	)
	(segment
		(start 84.660994 -101.694234)
		(end 84.726272 -101.759512)
		(width 0.12954)
		(layer "F.Cu")
		(net "LED_RST_PLD_CPU1_DRAM_EF_N_D")
	)
	(segment
		(start 75.813666 -101.694234)
		(end 83.07324 -101.694234)
		(width 0.12954)
		(layer "F.Cu")
		(net "LED_RST_PLD_CPU1_DRAM_EF_N_D")
	)
	(via
		(at 83.07324 -101.694234)
		(size 0.762)
		(drill 0.381)
		(layers "F.Cu" "B.Cu")
		(net "LED_RST_PLD_CPU1_DRAM_EF_N_D")
	)
	(segment
		(start 68.99148 -65.533778)
		(end 69.042534 -65.482724)
		(width 0.12954)
		(layer "F.Cu")
		(net "LED_RST_PLD_CPU1_DRAM_EF_N")
	)
	(segment
		(start 61.303916 -70.365112)
		(end 62.91326 -68.755768)
		(width 0.12954)
		(layer "F.Cu")
		(net "LED_RST_PLD_CPU1_DRAM_EF_N")
	)
	(segment
		(start 62.91326 -68.755768)
		(end 67.95262 -68.755768)
		(width 0.12954)
		(layer "F.Cu")
		(net "LED_RST_PLD_CPU1_DRAM_EF_N")
	)
	(segment
		(start 67.95262 -68.755768)
		(end 68.99148 -67.716908)
		(width 0.12954)
		(layer "F.Cu")
		(net "LED_RST_PLD_CPU1_DRAM_EF_N")
	)
	(segment
		(start 61.303916 -70.78599)
		(end 61.303916 -70.365112)
		(width 0.12954)
		(layer "F.Cu")
		(net "LED_RST_PLD_CPU1_DRAM_EF_N")
	)
	(segment
		(start 68.99148 -67.716908)
		(end 68.99148 -65.533778)
		(width 0.12954)
		(layer "F.Cu")
		(net "LED_RST_PLD_CPU1_DRAM_EF_N")
	)
	(via
		(at 68.99148 -67.716908)
		(size 0.762)
		(drill 0.381)
		(layers "F.Cu" "B.Cu")
		(net "LED_RST_PLD_CPU1_DRAM_EF_N")
	)
	(segment
		(start 79.322422 -98.613722)
		(end 83.1977 -98.613722)
		(width 0.12954)
		(layer "F.Cu")
		(net "LED_RST_PLD_CPU1_DRAM_CD_N_D")
	)
	(segment
		(start 65.454276 -72.072246)
		(end 60.24626 -77.280262)
		(width 0.12954)
		(layer "F.Cu")
		(net "LED_RST_PLD_CPU1_DRAM_CD_N_D")
	)
	(segment
		(start 83.1977 -98.613722)
		(end 84.610448 -98.613722)
		(width 0.12954)
		(layer "F.Cu")
		(net "LED_RST_PLD_CPU1_DRAM_CD_N_D")
	)
	(segment
		(start 65.454276 -70.78599)
		(end 65.454276 -72.072246)
		(width 0.12954)
		(layer "F.Cu")
		(net "LED_RST_PLD_CPU1_DRAM_CD_N_D")
	)
	(segment
		(start 84.723986 -98.72726)
		(end 84.726272 -98.72726)
		(width 0.12954)
		(layer "F.Cu")
		(net "LED_RST_PLD_CPU1_DRAM_CD_N_D")
	)
	(segment
		(start 60.24626 -77.280262)
		(end 60.24626 -79.53756)
		(width 0.12954)
		(layer "F.Cu")
		(net "LED_RST_PLD_CPU1_DRAM_CD_N_D")
	)
	(segment
		(start 84.610448 -98.613722)
		(end 84.723986 -98.72726)
		(width 0.12954)
		(layer "F.Cu")
		(net "LED_RST_PLD_CPU1_DRAM_CD_N_D")
	)
	(segment
		(start 60.24626 -79.53756)
		(end 79.322422 -98.613722)
		(width 0.12954)
		(layer "F.Cu")
		(net "LED_RST_PLD_CPU1_DRAM_CD_N_D")
	)
	(via
		(at 83.1977 -98.613722)
		(size 0.762)
		(drill 0.381)
		(layers "F.Cu" "B.Cu")
		(net "LED_RST_PLD_CPU1_DRAM_CD_N_D")
	)
	(segment
		(start 70.26148 -67.953128)
		(end 70.26148 -66.693288)
		(width 0.12954)
		(layer "F.Cu")
		(net "LED_RST_PLD_CPU1_DRAM_CD_N")
	)
	(segment
		(start 70.26148 -65.51549)
		(end 70.228714 -65.482724)
		(width 0.12954)
		(layer "F.Cu")
		(net "LED_RST_PLD_CPU1_DRAM_CD_N")
	)
	(segment
		(start 65.18402 -69.406008)
		(end 68.8086 -69.406008)
		(width 0.12954)
		(layer "F.Cu")
		(net "LED_RST_PLD_CPU1_DRAM_CD_N")
	)
	(segment
		(start 64.504316 -70.085712)
		(end 65.18402 -69.406008)
		(width 0.12954)
		(layer "F.Cu")
		(net "LED_RST_PLD_CPU1_DRAM_CD_N")
	)
	(segment
		(start 64.504316 -70.78599)
		(end 64.504316 -70.085712)
		(width 0.12954)
		(layer "F.Cu")
		(net "LED_RST_PLD_CPU1_DRAM_CD_N")
	)
	(segment
		(start 68.8086 -69.406008)
		(end 70.26148 -67.953128)
		(width 0.12954)
		(layer "F.Cu")
		(net "LED_RST_PLD_CPU1_DRAM_CD_N")
	)
	(segment
		(start 70.26148 -66.693288)
		(end 70.26148 -65.51549)
		(width 0.12954)
		(layer "F.Cu")
		(net "LED_RST_PLD_CPU1_DRAM_CD_N")
	)
	(via
		(at 70.26148 -66.693288)
		(size 0.762)
		(drill 0.381)
		(layers "F.Cu" "B.Cu")
		(net "LED_RST_PLD_CPU1_DRAM_CD_N")
	)
	(segment
		(start 93.145356 -101.759512)
		(end 91.66352 -101.759512)
		(width 0.12954)
		(layer "F.Cu")
		(net "LED_RST_PLD_CPU1_DRAM_AB_N_D")
	)
	(segment
		(start 79.003398 -97.895664)
		(end 60.5282 -79.420466)
		(width 0.12954)
		(layer "F.Cu")
		(net "LED_RST_PLD_CPU1_DRAM_AB_N_D")
	)
	(segment
		(start 91.26474 -101.759512)
		(end 87.400892 -97.895664)
		(width 0.12954)
		(layer "F.Cu")
		(net "LED_RST_PLD_CPU1_DRAM_AB_N_D")
	)
	(segment
		(start 60.5282 -77.567028)
		(end 62.44082 -75.654408)
		(width 0.12954)
		(layer "F.Cu")
		(net "LED_RST_PLD_CPU1_DRAM_AB_N_D")
	)
	(segment
		(start 60.5282 -79.420466)
		(end 60.5282 -77.567028)
		(width 0.12954)
		(layer "F.Cu")
		(net "LED_RST_PLD_CPU1_DRAM_AB_N_D")
	)
	(segment
		(start 62.44082 -75.654408)
		(end 64.718946 -75.654408)
		(width 0.12954)
		(layer "F.Cu")
		(net "LED_RST_PLD_CPU1_DRAM_AB_N_D")
	)
	(segment
		(start 91.66352 -101.759512)
		(end 91.26474 -101.759512)
		(width 0.12954)
		(layer "F.Cu")
		(net "LED_RST_PLD_CPU1_DRAM_AB_N_D")
	)
	(segment
		(start 87.400892 -97.895664)
		(end 79.003398 -97.895664)
		(width 0.12954)
		(layer "F.Cu")
		(net "LED_RST_PLD_CPU1_DRAM_AB_N_D")
	)
	(segment
		(start 68.654676 -71.718678)
		(end 68.654676 -70.78599)
		(width 0.12954)
		(layer "F.Cu")
		(net "LED_RST_PLD_CPU1_DRAM_AB_N_D")
	)
	(segment
		(start 64.718946 -75.654408)
		(end 68.654676 -71.718678)
		(width 0.12954)
		(layer "F.Cu")
		(net "LED_RST_PLD_CPU1_DRAM_AB_N_D")
	)
	(via
		(at 91.66352 -101.759512)
		(size 0.762)
		(drill 0.381)
		(layers "F.Cu" "B.Cu")
		(net "LED_RST_PLD_CPU1_DRAM_AB_N_D")
	)
	(segment
		(start 67.704716 -70.136512)
		(end 67.9577 -69.883528)
		(width 0.12954)
		(layer "F.Cu")
		(net "LED_RST_PLD_CPU1_DRAM_AB_N")
	)
	(segment
		(start 71.40448 -67.818508)
		(end 71.40448 -65.493646)
		(width 0.12954)
		(layer "F.Cu")
		(net "LED_RST_PLD_CPU1_DRAM_AB_N")
	)
	(segment
		(start 71.40448 -65.493646)
		(end 71.393558 -65.482724)
		(width 0.12954)
		(layer "F.Cu")
		(net "LED_RST_PLD_CPU1_DRAM_AB_N")
	)
	(segment
		(start 67.704716 -70.78599)
		(end 67.704716 -70.136512)
		(width 0.12954)
		(layer "F.Cu")
		(net "LED_RST_PLD_CPU1_DRAM_AB_N")
	)
	(segment
		(start 67.9577 -69.883528)
		(end 69.33946 -69.883528)
		(width 0.12954)
		(layer "F.Cu")
		(net "LED_RST_PLD_CPU1_DRAM_AB_N")
	)
	(segment
		(start 69.33946 -69.883528)
		(end 71.40448 -67.818508)
		(width 0.12954)
		(layer "F.Cu")
		(net "LED_RST_PLD_CPU1_DRAM_AB_N")
	)
	(via
		(at 71.40448 -67.818508)
		(size 0.762)
		(drill 0.381)
		(layers "F.Cu" "B.Cu")
		(net "LED_RST_PLD_CPU1_DRAM_AB_N")
	)
	(segment
		(start 94.147132 -96.9899)
		(end 94.882208 -96.9899)
		(width 0.12954)
		(layer "F.Cu")
		(net "LED_RST_PLD_CPU0_DRAM_EF_N_D")
	)
	(segment
		(start 83.539584 -86.345268)
		(end 85.010752 -86.345268)
		(width 0.12954)
		(layer "F.Cu")
		(net "LED_RST_PLD_CPU0_DRAM_EF_N_D")
	)
	(segment
		(start 75.055476 -70.78599)
		(end 75.055476 -71.872856)
		(width 0.12954)
		(layer "F.Cu")
		(net "LED_RST_PLD_CPU0_DRAM_EF_N_D")
	)
	(segment
		(start 89.051384 -90.3859)
		(end 89.051384 -92.061792)
		(width 0.12954)
		(layer "F.Cu")
		(net "LED_RST_PLD_CPU0_DRAM_EF_N_D")
	)
	(segment
		(start 89.051384 -92.061792)
		(end 90.918284 -93.928692)
		(width 0.12954)
		(layer "F.Cu")
		(net "LED_RST_PLD_CPU0_DRAM_EF_N_D")
	)
	(segment
		(start 85.010752 -86.345268)
		(end 89.051384 -90.3859)
		(width 0.12954)
		(layer "F.Cu")
		(net "LED_RST_PLD_CPU0_DRAM_EF_N_D")
	)
	(segment
		(start 78.18628 -72.664828)
		(end 78.88478 -73.363328)
		(width 0.12954)
		(layer "F.Cu")
		(net "LED_RST_PLD_CPU0_DRAM_EF_N_D")
	)
	(segment
		(start 75.847448 -72.664828)
		(end 78.18628 -72.664828)
		(width 0.12954)
		(layer "F.Cu")
		(net "LED_RST_PLD_CPU0_DRAM_EF_N_D")
	)
	(segment
		(start 94.882208 -96.9899)
		(end 94.9452 -96.926908)
		(width 0.12954)
		(layer "F.Cu")
		(net "LED_RST_PLD_CPU0_DRAM_EF_N_D")
	)
	(segment
		(start 91.88958 -94.899988)
		(end 93.759528 -94.899988)
		(width 0.12954)
		(layer "F.Cu")
		(net "LED_RST_PLD_CPU0_DRAM_EF_N_D")
	)
	(segment
		(start 93.759528 -94.899988)
		(end 93.86062 -95.00108)
		(width 0.12954)
		(layer "F.Cu")
		(net "LED_RST_PLD_CPU0_DRAM_EF_N_D")
	)
	(segment
		(start 93.86062 -96.703388)
		(end 94.147132 -96.9899)
		(width 0.12954)
		(layer "F.Cu")
		(net "LED_RST_PLD_CPU0_DRAM_EF_N_D")
	)
	(segment
		(start 93.86062 -95.00108)
		(end 93.86062 -96.703388)
		(width 0.12954)
		(layer "F.Cu")
		(net "LED_RST_PLD_CPU0_DRAM_EF_N_D")
	)
	(segment
		(start 78.88478 -81.690464)
		(end 83.539584 -86.345268)
		(width 0.12954)
		(layer "F.Cu")
		(net "LED_RST_PLD_CPU0_DRAM_EF_N_D")
	)
	(segment
		(start 78.88478 -73.363328)
		(end 78.88478 -81.690464)
		(width 0.12954)
		(layer "F.Cu")
		(net "LED_RST_PLD_CPU0_DRAM_EF_N_D")
	)
	(segment
		(start 90.918284 -93.928692)
		(end 91.88958 -94.899988)
		(width 0.12954)
		(layer "F.Cu")
		(net "LED_RST_PLD_CPU0_DRAM_EF_N_D")
	)
	(segment
		(start 75.055476 -71.872856)
		(end 75.847448 -72.664828)
		(width 0.12954)
		(layer "F.Cu")
		(net "LED_RST_PLD_CPU0_DRAM_EF_N_D")
	)
	(via
		(at 90.918284 -93.928692)
		(size 0.762)
		(drill 0.381)
		(layers "F.Cu" "B.Cu")
		(net "LED_RST_PLD_CPU0_DRAM_EF_N_D")
	)
	(segment
		(start 74.105516 -67.808348)
		(end 74.105516 -65.483994)
		(width 0.12954)
		(layer "F.Cu")
		(net "LED_RST_PLD_CPU0_DRAM_EF_N")
	)
	(segment
		(start 74.105516 -70.78599)
		(end 74.105516 -67.808348)
		(width 0.12954)
		(layer "F.Cu")
		(net "LED_RST_PLD_CPU0_DRAM_EF_N")
	)
	(segment
		(start 74.105516 -65.483994)
		(end 74.106786 -65.482724)
		(width 0.12954)
		(layer "F.Cu")
		(net "LED_RST_PLD_CPU0_DRAM_EF_N")
	)
	(via
		(at 74.105516 -67.808348)
		(size 0.762)
		(drill 0.381)
		(layers "F.Cu" "B.Cu")
		(net "LED_RST_PLD_CPU0_DRAM_EF_N")
	)
	(segment
		(start 93.080078 -92.247974)
		(end 93.145356 -92.313252)
		(width 0.12954)
		(layer "F.Cu")
		(net "LED_RST_PLD_CPU0_DRAM_CD_N_D")
	)
	(segment
		(start 81.807812 -74.337926)
		(end 81.807812 -80.88884)
		(width 0.12954)
		(layer "F.Cu")
		(net "LED_RST_PLD_CPU0_DRAM_CD_N_D")
	)
	(segment
		(start 87.34552 -87.539068)
		(end 91.186 -91.379548)
		(width 0.12954)
		(layer "F.Cu")
		(net "LED_RST_PLD_CPU0_DRAM_CD_N_D")
	)
	(segment
		(start 92.054426 -92.247974)
		(end 93.080078 -92.247974)
		(width 0.12954)
		(layer "F.Cu")
		(net "LED_RST_PLD_CPU0_DRAM_CD_N_D")
	)
	(segment
		(start 81.807812 -80.88884)
		(end 87.34552 -86.426548)
		(width 0.12954)
		(layer "F.Cu")
		(net "LED_RST_PLD_CPU0_DRAM_CD_N_D")
	)
	(segment
		(start 91.186 -91.379548)
		(end 92.054426 -92.247974)
		(width 0.12954)
		(layer "F.Cu")
		(net "LED_RST_PLD_CPU0_DRAM_CD_N_D")
	)
	(segment
		(start 87.34552 -86.426548)
		(end 87.34552 -87.539068)
		(width 0.12954)
		(layer "F.Cu")
		(net "LED_RST_PLD_CPU0_DRAM_CD_N_D")
	)
	(segment
		(start 78.255876 -70.78599)
		(end 81.807812 -74.337926)
		(width 0.12954)
		(layer "F.Cu")
		(net "LED_RST_PLD_CPU0_DRAM_CD_N_D")
	)
	(via
		(at 91.186 -91.379548)
		(size 0.762)
		(drill 0.381)
		(layers "F.Cu" "B.Cu")
		(net "LED_RST_PLD_CPU0_DRAM_CD_N_D")
	)
	(segment
		(start 77.305916 -65.558162)
		(end 77.381354 -65.482724)
		(width 0.12954)
		(layer "F.Cu")
		(net "LED_RST_PLD_CPU0_DRAM_CD_N")
	)
	(segment
		(start 77.305916 -66.802508)
		(end 77.305916 -65.558162)
		(width 0.12954)
		(layer "F.Cu")
		(net "LED_RST_PLD_CPU0_DRAM_CD_N")
	)
	(segment
		(start 77.305916 -70.78599)
		(end 77.305916 -66.802508)
		(width 0.12954)
		(layer "F.Cu")
		(net "LED_RST_PLD_CPU0_DRAM_CD_N")
	)
	(via
		(at 77.305916 -66.802508)
		(size 0.762)
		(drill 0.381)
		(layers "F.Cu" "B.Cu")
		(net "LED_RST_PLD_CPU0_DRAM_CD_N")
	)
	(segment
		(start 93.933772 -92.220796)
		(end 93.933772 -93.5228)
		(width 0.12954)
		(layer "F.Cu")
		(net "LED_RST_PLD_CPU0_DRAM_AB_N_D")
	)
	(segment
		(start 82.34172 -81.023968)
		(end 90.4621 -89.144348)
		(width 0.12954)
		(layer "F.Cu")
		(net "LED_RST_PLD_CPU0_DRAM_AB_N_D")
	)
	(segment
		(start 90.4621 -89.144348)
		(end 90.857324 -89.144348)
		(width 0.12954)
		(layer "F.Cu")
		(net "LED_RST_PLD_CPU0_DRAM_AB_N_D")
	)
	(segment
		(start 94.2975 -93.886528)
		(end 94.872048 -93.886528)
		(width 0.12954)
		(layer "F.Cu")
		(net "LED_RST_PLD_CPU0_DRAM_AB_N_D")
	)
	(segment
		(start 92.625418 -90.912442)
		(end 93.933772 -92.220796)
		(width 0.12954)
		(layer "F.Cu")
		(net "LED_RST_PLD_CPU0_DRAM_AB_N_D")
	)
	(segment
		(start 94.872048 -93.886528)
		(end 94.9452 -93.813376)
		(width 0.12954)
		(layer "F.Cu")
		(net "LED_RST_PLD_CPU0_DRAM_AB_N_D")
	)
	(segment
		(start 90.857324 -89.144348)
		(end 92.625418 -90.912442)
		(width 0.12954)
		(layer "F.Cu")
		(net "LED_RST_PLD_CPU0_DRAM_AB_N_D")
	)
	(segment
		(start 81.456276 -70.78599)
		(end 81.456276 -72.731884)
		(width 0.12954)
		(layer "F.Cu")
		(net "LED_RST_PLD_CPU0_DRAM_AB_N_D")
	)
	(segment
		(start 93.933772 -93.5228)
		(end 94.2975 -93.886528)
		(width 0.12954)
		(layer "F.Cu")
		(net "LED_RST_PLD_CPU0_DRAM_AB_N_D")
	)
	(segment
		(start 82.34172 -73.617328)
		(end 82.34172 -81.023968)
		(width 0.12954)
		(layer "F.Cu")
		(net "LED_RST_PLD_CPU0_DRAM_AB_N_D")
	)
	(segment
		(start 81.456276 -72.731884)
		(end 82.34172 -73.617328)
		(width 0.12954)
		(layer "F.Cu")
		(net "LED_RST_PLD_CPU0_DRAM_AB_N_D")
	)
	(via
		(at 92.625418 -90.912442)
		(size 0.762)
		(drill 0.381)
		(layers "F.Cu" "B.Cu")
		(net "LED_RST_PLD_CPU0_DRAM_AB_N_D")
	)
	(segment
		(start 80.506316 -65.527174)
		(end 80.550766 -65.482724)
		(width 0.12954)
		(layer "F.Cu")
		(net "LED_RST_PLD_CPU0_DRAM_AB_N")
	)
	(segment
		(start 80.506316 -70.78599)
		(end 80.506316 -66.739008)
		(width 0.12954)
		(layer "F.Cu")
		(net "LED_RST_PLD_CPU0_DRAM_AB_N")
	)
	(segment
		(start 80.506316 -66.739008)
		(end 80.506316 -65.527174)
		(width 0.12954)
		(layer "F.Cu")
		(net "LED_RST_PLD_CPU0_DRAM_AB_N")
	)
	(via
		(at 80.506316 -66.739008)
		(size 0.762)
		(drill 0.381)
		(layers "F.Cu" "B.Cu")
		(net "LED_RST_PLD_CPU0_DRAM_AB_N")
	)
	(segment
		(start 91.057476 -70.78599)
		(end 91.55684 -71.285354)
		(width 0.12954)
		(layer "F.Cu")
		(net "LED_PWRGD_SYS_PWROK_R_D")
	)
	(segment
		(start 99.17176 -94.996762)
		(end 99.648518 -95.47352)
		(width 0.12954)
		(layer "F.Cu")
		(net "LED_PWRGD_SYS_PWROK_R_D")
	)
	(segment
		(start 99.648518 -95.47352)
		(end 99.974654 -95.47352)
		(width 0.12954)
		(layer "F.Cu")
		(net "LED_PWRGD_SYS_PWROK_R_D")
	)
	(segment
		(start 91.55684 -82.827368)
		(end 96.986598 -88.257126)
		(width 0.12954)
		(layer "F.Cu")
		(net "LED_PWRGD_SYS_PWROK_R_D")
	)
	(segment
		(start 98.18116 -93.591888)
		(end 99.17176 -94.582488)
		(width 0.12954)
		(layer "F.Cu")
		(net "LED_PWRGD_SYS_PWROK_R_D")
	)
	(segment
		(start 91.55684 -71.285354)
		(end 91.55684 -82.827368)
		(width 0.12954)
		(layer "F.Cu")
		(net "LED_PWRGD_SYS_PWROK_R_D")
	)
	(segment
		(start 96.986598 -90.835226)
		(end 98.18116 -92.029788)
		(width 0.12954)
		(layer "F.Cu")
		(net "LED_PWRGD_SYS_PWROK_R_D")
	)
	(segment
		(start 99.17176 -94.582488)
		(end 99.17176 -94.996762)
		(width 0.12954)
		(layer "F.Cu")
		(net "LED_PWRGD_SYS_PWROK_R_D")
	)
	(segment
		(start 96.986598 -88.257126)
		(end 96.986598 -90.835226)
		(width 0.12954)
		(layer "F.Cu")
		(net "LED_PWRGD_SYS_PWROK_R_D")
	)
	(segment
		(start 98.18116 -92.029788)
		(end 98.18116 -93.274388)
		(width 0.12954)
		(layer "F.Cu")
		(net "LED_PWRGD_SYS_PWROK_R_D")
	)
	(segment
		(start 98.18116 -93.274388)
		(end 98.18116 -93.591888)
		(width 0.12954)
		(layer "F.Cu")
		(net "LED_PWRGD_SYS_PWROK_R_D")
	)
	(via
		(at 98.18116 -93.274388)
		(size 0.762)
		(drill 0.381)
		(layers "F.Cu" "B.Cu")
		(net "LED_PWRGD_SYS_PWROK_R_D")
	)
	(segment
		(start 90.107516 -68.11772)
		(end 90.107516 -70.78599)
		(width 0.12954)
		(layer "F.Cu")
		(net "LED_PWRGD_SYS_PWROK_R")
	)
	(segment
		(start 90.086688 -66.819272)
		(end 90.086688 -68.096892)
		(width 0.12954)
		(layer "F.Cu")
		(net "LED_PWRGD_SYS_PWROK_R")
	)
	(segment
		(start 90.086688 -65.593722)
		(end 90.086688 -66.819272)
		(width 0.12954)
		(layer "F.Cu")
		(net "LED_PWRGD_SYS_PWROK_R")
	)
	(segment
		(start 90.086688 -68.096892)
		(end 90.107516 -68.11772)
		(width 0.12954)
		(layer "F.Cu")
		(net "LED_PWRGD_SYS_PWROK_R")
	)
	(via
		(at 90.086688 -66.819272)
		(size 0.762)
		(drill 0.381)
		(layers "F.Cu" "B.Cu")
		(net "LED_PWRGD_SYS_PWROK_R")
	)
	(segment
		(start 88.205564 -95.894652)
		(end 88.205564 -90.73642)
		(width 0.12954)
		(layer "F.Cu")
		(net "LED_PWRGD_PVPP_HBM_CPU1_D")
	)
	(segment
		(start 81.144364 -87.191088)
		(end 74.870056 -80.91678)
		(width 0.12954)
		(layer "F.Cu")
		(net "LED_PWRGD_PVPP_HBM_CPU1_D")
	)
	(segment
		(start 84.660232 -87.191088)
		(end 81.144364 -87.191088)
		(width 0.12954)
		(layer "F.Cu")
		(net "LED_PWRGD_PVPP_HBM_CPU1_D")
	)
	(segment
		(start 74.870056 -80.91678)
		(end 74.870056 -79.078836)
		(width 0.12954)
		(layer "F.Cu")
		(net "LED_PWRGD_PVPP_HBM_CPU1_D")
	)
	(segment
		(start 91.238324 -98.927412)
		(end 88.205564 -95.894652)
		(width 0.12954)
		(layer "F.Cu")
		(net "LED_PWRGD_PVPP_HBM_CPU1_D")
	)
	(segment
		(start 93.136466 -98.927412)
		(end 91.70416 -98.927412)
		(width 0.12954)
		(layer "F.Cu")
		(net "LED_PWRGD_PVPP_HBM_CPU1_D")
	)
	(segment
		(start 88.205564 -90.73642)
		(end 84.660232 -87.191088)
		(width 0.12954)
		(layer "F.Cu")
		(net "LED_PWRGD_PVPP_HBM_CPU1_D")
	)
	(segment
		(start 91.70416 -98.927412)
		(end 91.238324 -98.927412)
		(width 0.12954)
		(layer "F.Cu")
		(net "LED_PWRGD_PVPP_HBM_CPU1_D")
	)
	(via
		(at 91.70416 -98.927412)
		(size 0.762)
		(drill 0.381)
		(layers "F.Cu" "B.Cu")
		(net "LED_PWRGD_PVPP_HBM_CPU1_D")
	)
	(segment
		(start 75.97648 -76.736448)
		(end 76.90231 -75.810618)
		(width 0.12954)
		(layer "F.Cu")
		(net "LED_PWRGD_PVPP_HBM_CPU1")
	)
	(segment
		(start 73.920096 -78.653132)
		(end 74.40168 -78.171548)
		(width 0.12954)
		(layer "F.Cu")
		(net "LED_PWRGD_PVPP_HBM_CPU1")
	)
	(segment
		(start 73.920096 -79.078836)
		(end 73.920096 -78.653132)
		(width 0.12954)
		(layer "F.Cu")
		(net "LED_PWRGD_PVPP_HBM_CPU1")
	)
	(segment
		(start 74.54138 -78.171548)
		(end 75.97648 -76.736448)
		(width 0.12954)
		(layer "F.Cu")
		(net "LED_PWRGD_PVPP_HBM_CPU1")
	)
	(segment
		(start 74.40168 -78.171548)
		(end 74.54138 -78.171548)
		(width 0.12954)
		(layer "F.Cu")
		(net "LED_PWRGD_PVPP_HBM_CPU1")
	)
	(segment
		(start 76.90231 -75.810618)
		(end 76.90231 -75.301602)
		(width 0.12954)
		(layer "F.Cu")
		(net "LED_PWRGD_PVPP_HBM_CPU1")
	)
	(via
		(at 75.97648 -76.736448)
		(size 0.762)
		(drill 0.381)
		(layers "F.Cu" "B.Cu")
		(net "LED_PWRGD_PVPP_HBM_CPU1")
	)
	(segment
		(start 97.678494 -103.457248)
		(end 96.5708 -103.457248)
		(width 0.12954)
		(layer "F.Cu")
		(net "LED_PWRGD_PVPP_HBM_CPU0_D")
	)
	(segment
		(start 93.422216 -98.159824)
		(end 92.385896 -98.159824)
		(width 0.12954)
		(layer "F.Cu")
		(net "LED_PWRGD_PVPP_HBM_CPU0_D")
	)
	(segment
		(start 83.196684 -86.909148)
		(end 78.070456 -81.78292)
		(width 0.12954)
		(layer "F.Cu")
		(net "LED_PWRGD_PVPP_HBM_CPU0_D")
	)
	(segment
		(start 96.5708 -103.457248)
		(end 95.95866 -102.845108)
		(width 0.12954)
		(layer "F.Cu")
		(net "LED_PWRGD_PVPP_HBM_CPU0_D")
	)
	(segment
		(start 95.95866 -102.845108)
		(end 95.95866 -101.376734)
		(width 0.12954)
		(layer "F.Cu")
		(net "LED_PWRGD_PVPP_HBM_CPU0_D")
	)
	(segment
		(start 94.11208 -101.023928)
		(end 93.65488 -100.566728)
		(width 0.12954)
		(layer "F.Cu")
		(net "LED_PWRGD_PVPP_HBM_CPU0_D")
	)
	(segment
		(start 78.070456 -81.78292)
		(end 78.070456 -79.078836)
		(width 0.12954)
		(layer "F.Cu")
		(net "LED_PWRGD_PVPP_HBM_CPU0_D")
	)
	(segment
		(start 98.727768 -102.407974)
		(end 97.678494 -103.457248)
		(width 0.12954)
		(layer "F.Cu")
		(net "LED_PWRGD_PVPP_HBM_CPU0_D")
	)
	(segment
		(start 99.986846 -102.04323)
		(end 98.727768 -102.04323)
		(width 0.12954)
		(layer "F.Cu")
		(net "LED_PWRGD_PVPP_HBM_CPU0_D")
	)
	(segment
		(start 93.65488 -100.566728)
		(end 93.65488 -98.392488)
		(width 0.12954)
		(layer "F.Cu")
		(net "LED_PWRGD_PVPP_HBM_CPU0_D")
	)
	(segment
		(start 91.61272 -97.386648)
		(end 88.487504 -94.261432)
		(width 0.12954)
		(layer "F.Cu")
		(net "LED_PWRGD_PVPP_HBM_CPU0_D")
	)
	(segment
		(start 88.487504 -94.261432)
		(end 88.487504 -90.61958)
		(width 0.12954)
		(layer "F.Cu")
		(net "LED_PWRGD_PVPP_HBM_CPU0_D")
	)
	(segment
		(start 98.727768 -102.04323)
		(end 98.727768 -102.407974)
		(width 0.12954)
		(layer "F.Cu")
		(net "LED_PWRGD_PVPP_HBM_CPU0_D")
	)
	(segment
		(start 84.777072 -86.909148)
		(end 83.196684 -86.909148)
		(width 0.12954)
		(layer "F.Cu")
		(net "LED_PWRGD_PVPP_HBM_CPU0_D")
	)
	(segment
		(start 95.605854 -101.023928)
		(end 94.11208 -101.023928)
		(width 0.12954)
		(layer "F.Cu")
		(net "LED_PWRGD_PVPP_HBM_CPU0_D")
	)
	(segment
		(start 95.95866 -101.376734)
		(end 95.605854 -101.023928)
		(width 0.12954)
		(layer "F.Cu")
		(net "LED_PWRGD_PVPP_HBM_CPU0_D")
	)
	(segment
		(start 93.65488 -98.392488)
		(end 93.422216 -98.159824)
		(width 0.12954)
		(layer "F.Cu")
		(net "LED_PWRGD_PVPP_HBM_CPU0_D")
	)
	(segment
		(start 88.487504 -90.61958)
		(end 84.777072 -86.909148)
		(width 0.12954)
		(layer "F.Cu")
		(net "LED_PWRGD_PVPP_HBM_CPU0_D")
	)
	(segment
		(start 92.385896 -98.159824)
		(end 91.61272 -97.386648)
		(width 0.12954)
		(layer "F.Cu")
		(net "LED_PWRGD_PVPP_HBM_CPU0_D")
	)
	(via
		(at 91.61272 -97.386648)
		(size 0.762)
		(drill 0.381)
		(layers "F.Cu" "B.Cu")
		(net "LED_PWRGD_PVPP_HBM_CPU0_D")
	)
	(via
		(at 98.727768 -102.04323)
		(size 0.762)
		(drill 0.381)
		(layers "F.Cu" "B.Cu")
		(net "LED_PWRGD_PVPP_HBM_CPU0_D")
	)
	(segment
		(start 77.93228 -75.322938)
		(end 77.910944 -75.301602)
		(width 0.12954)
		(layer "F.Cu")
		(net "LED_PWRGD_PVPP_HBM_CPU0")
	)
	(segment
		(start 77.120496 -77.403452)
		(end 77.343 -77.180948)
		(width 0.12954)
		(layer "F.Cu")
		(net "LED_PWRGD_PVPP_HBM_CPU0")
	)
	(segment
		(start 77.93228 -76.591668)
		(end 77.93228 -75.322938)
		(width 0.12954)
		(layer "F.Cu")
		(net "LED_PWRGD_PVPP_HBM_CPU0")
	)
	(segment
		(start 77.120496 -79.078836)
		(end 77.120496 -77.403452)
		(width 0.12954)
		(layer "F.Cu")
		(net "LED_PWRGD_PVPP_HBM_CPU0")
	)
	(segment
		(start 77.343 -77.180948)
		(end 77.93228 -76.591668)
		(width 0.12954)
		(layer "F.Cu")
		(net "LED_PWRGD_PVPP_HBM_CPU0")
	)
	(via
		(at 77.343 -77.180948)
		(size 0.762)
		(drill 0.381)
		(layers "F.Cu" "B.Cu")
		(net "LED_PWRGD_PVPP_HBM_CPU0")
	)
	(segment
		(start 104.44988 -96.901508)
		(end 105.65638 -98.108008)
		(width 0.12954)
		(layer "F.Cu")
		(net "LED_PWRGD_PVNN_MAIN_CPU1_D")
	)
	(segment
		(start 104.44988 -71.376794)
		(end 104.44988 -96.901508)
		(width 0.12954)
		(layer "F.Cu")
		(net "LED_PWRGD_PVNN_MAIN_CPU1_D")
	)
	(segment
		(start 106.507788 -98.959416)
		(end 107.025186 -98.959416)
		(width 0.12954)
		(layer "F.Cu")
		(net "LED_PWRGD_PVNN_MAIN_CPU1_D")
	)
	(segment
		(start 105.65638 -98.108008)
		(end 106.507788 -98.959416)
		(width 0.12954)
		(layer "F.Cu")
		(net "LED_PWRGD_PVNN_MAIN_CPU1_D")
	)
	(segment
		(start 103.859076 -70.78599)
		(end 104.44988 -71.376794)
		(width 0.12954)
		(layer "F.Cu")
		(net "LED_PWRGD_PVNN_MAIN_CPU1_D")
	)
	(via
		(at 105.65638 -98.108008)
		(size 0.762)
		(drill 0.381)
		(layers "F.Cu" "B.Cu")
		(net "LED_PWRGD_PVNN_MAIN_CPU1_D")
	)
	(segment
		(start 102.909116 -66.921888)
		(end 102.909116 -65.566036)
		(width 0.12954)
		(layer "F.Cu")
		(net "LED_PWRGD_PVNN_MAIN_CPU1")
	)
	(segment
		(start 102.909116 -70.78599)
		(end 102.909116 -66.921888)
		(width 0.12954)
		(layer "F.Cu")
		(net "LED_PWRGD_PVNN_MAIN_CPU1")
	)
	(segment
		(start 102.909116 -65.566036)
		(end 102.86619 -65.52311)
		(width 0.12954)
		(layer "F.Cu")
		(net "LED_PWRGD_PVNN_MAIN_CPU1")
	)
	(via
		(at 102.909116 -66.921888)
		(size 0.762)
		(drill 0.381)
		(layers "F.Cu" "B.Cu")
		(net "LED_PWRGD_PVNN_MAIN_CPU1")
	)
	(segment
		(start 106.01706 -81.585308)
		(end 107.414822 -80.187546)
		(width 0.12954)
		(layer "F.Cu")
		(net "LED_PWRGD_PVNN_MAIN_CPU0_D")
	)
	(segment
		(start 107.129326 -92.365576)
		(end 106.581448 -92.365576)
		(width 0.12954)
		(layer "F.Cu")
		(net "LED_PWRGD_PVNN_MAIN_CPU0_D")
	)
	(segment
		(start 106.01706 -91.219528)
		(end 106.01706 -81.585308)
		(width 0.12954)
		(layer "F.Cu")
		(net "LED_PWRGD_PVNN_MAIN_CPU0_D")
	)
	(segment
		(start 106.581448 -92.365576)
		(end 106.01706 -91.801188)
		(width 0.12954)
		(layer "F.Cu")
		(net "LED_PWRGD_PVNN_MAIN_CPU0_D")
	)
	(segment
		(start 107.414822 -71.141336)
		(end 107.059476 -70.78599)
		(width 0.12954)
		(layer "F.Cu")
		(net "LED_PWRGD_PVNN_MAIN_CPU0_D")
	)
	(segment
		(start 106.01706 -91.801188)
		(end 106.01706 -91.219528)
		(width 0.12954)
		(layer "F.Cu")
		(net "LED_PWRGD_PVNN_MAIN_CPU0_D")
	)
	(segment
		(start 107.414822 -80.187546)
		(end 107.414822 -71.141336)
		(width 0.12954)
		(layer "F.Cu")
		(net "LED_PWRGD_PVNN_MAIN_CPU0_D")
	)
	(via
		(at 106.01706 -91.219528)
		(size 0.762)
		(drill 0.381)
		(layers "F.Cu" "B.Cu")
		(net "LED_PWRGD_PVNN_MAIN_CPU0_D")
	)
	(segment
		(start 106.109516 -65.624964)
		(end 106.11231 -65.62217)
		(width 0.12954)
		(layer "F.Cu")
		(net "LED_PWRGD_PVNN_MAIN_CPU0")
	)
	(segment
		(start 106.109516 -66.965068)
		(end 106.109516 -65.624964)
		(width 0.12954)
		(layer "F.Cu")
		(net "LED_PWRGD_PVNN_MAIN_CPU0")
	)
	(segment
		(start 106.109516 -70.78599)
		(end 106.109516 -66.965068)
		(width 0.12954)
		(layer "F.Cu")
		(net "LED_PWRGD_PVNN_MAIN_CPU0")
	)
	(via
		(at 106.109516 -66.965068)
		(size 0.762)
		(drill 0.381)
		(layers "F.Cu" "B.Cu")
		(net "LED_PWRGD_PVNN_MAIN_CPU0")
	)
	(segment
		(start 97.458276 -74.804524)
		(end 98.21418 -75.560428)
		(width 0.12954)
		(layer "F.Cu")
		(net "LED_PWRGD_PVCCIN_CPU1_D")
	)
	(segment
		(start 98.67392 -76.020168)
		(end 98.67392 -80.935322)
		(width 0.12954)
		(layer "F.Cu")
		(net "LED_PWRGD_PVCCIN_CPU1_D")
	)
	(segment
		(start 97.458276 -70.78599)
		(end 97.458276 -74.804524)
		(width 0.12954)
		(layer "F.Cu")
		(net "LED_PWRGD_PVCCIN_CPU1_D")
	)
	(segment
		(start 98.21418 -75.560428)
		(end 98.67392 -76.020168)
		(width 0.12954)
		(layer "F.Cu")
		(net "LED_PWRGD_PVCCIN_CPU1_D")
	)
	(via
		(at 98.21418 -75.560428)
		(size 0.762)
		(drill 0.381)
		(layers "F.Cu" "B.Cu")
		(net "LED_PWRGD_PVCCIN_CPU1_D")
	)
	(segment
		(start 96.508316 -66.860928)
		(end 96.508316 -65.56756)
		(width 0.12954)
		(layer "F.Cu")
		(net "LED_PWRGD_PVCCIN_CPU1")
	)
	(segment
		(start 96.508316 -65.56756)
		(end 96.48444 -65.543684)
		(width 0.12954)
		(layer "F.Cu")
		(net "LED_PWRGD_PVCCIN_CPU1")
	)
	(segment
		(start 96.508316 -70.78599)
		(end 96.508316 -66.860928)
		(width 0.12954)
		(layer "F.Cu")
		(net "LED_PWRGD_PVCCIN_CPU1")
	)
	(via
		(at 96.508316 -66.860928)
		(size 0.762)
		(drill 0.381)
		(layers "F.Cu" "B.Cu")
		(net "LED_PWRGD_PVCCIN_CPU1")
	)
	(segment
		(start 100.658676 -70.78599)
		(end 100.658676 -71.52259)
		(width 0.12954)
		(layer "F.Cu")
		(net "LED_PWRGD_PVCCIN_CPU0_D")
	)
	(segment
		(start 100.57384 -82.235294)
		(end 101.259894 -82.235294)
		(width 0.12954)
		(layer "F.Cu")
		(net "LED_PWRGD_PVCCIN_CPU0_D")
	)
	(via
		(at 100.658676 -71.52259)
		(size 0.508)
		(drill 0.254)
		(layers "F.Cu" "B.Cu")
		(net "LED_PWRGD_PVCCIN_CPU0_D")
	)
	(via
		(at 101.259894 -82.235294)
		(size 0.508)
		(drill 0.254)
		(layers "F.Cu" "B.Cu")
		(net "LED_PWRGD_PVCCIN_CPU0_D")
	)
	(segment
		(start 101.259894 -82.235294)
		(end 100.658676 -81.634076)
		(width 0.127)
		(layer "In2.Cu")
		(net "LED_PWRGD_PVCCIN_CPU0_D")
	)
	(segment
		(start 100.658676 -81.634076)
		(end 100.658676 -71.52259)
		(width 0.127)
		(layer "In2.Cu")
		(net "LED_PWRGD_PVCCIN_CPU0_D")
	)
	(segment
		(start 99.708716 -66.860928)
		(end 99.708716 -65.556892)
		(width 0.12954)
		(layer "F.Cu")
		(net "LED_PWRGD_PVCCIN_CPU0")
	)
	(segment
		(start 99.708716 -65.556892)
		(end 99.724464 -65.541144)
		(width 0.12954)
		(layer "F.Cu")
		(net "LED_PWRGD_PVCCIN_CPU0")
	)
	(segment
		(start 99.708716 -70.78599)
		(end 99.708716 -66.860928)
		(width 0.12954)
		(layer "F.Cu")
		(net "LED_PWRGD_PVCCIN_CPU0")
	)
	(via
		(at 99.708716 -66.860928)
		(size 0.762)
		(drill 0.381)
		(layers "F.Cu" "B.Cu")
		(net "LED_PWRGD_PVCCIN_CPU0")
	)
	(segment
		(start 110.096046 -100.398326)
		(end 110.234984 -100.259388)
		(width 0.12954)
		(layer "F.Cu")
		(net "LED_PWRGD_PVCCINFAON_CPU1_D")
	)
	(segment
		(start 111.4425 -81.567528)
		(end 112.49152 -80.518508)
		(width 0.12954)
		(layer "F.Cu")
		(net "LED_PWRGD_PVCCINFAON_CPU1_D")
	)
	(segment
		(start 110.945422 -70.79361)
		(end 110.656116 -70.79361)
		(width 0.12954)
		(layer "F.Cu")
		(net "LED_PWRGD_PVCCINFAON_CPU1_D")
	)
	(segment
		(start 108.925106 -100.259388)
		(end 109.064044 -100.398326)
		(width 0.12954)
		(layer "F.Cu")
		(net "LED_PWRGD_PVCCINFAON_CPU1_D")
	)
	(segment
		(start 115.80114 -74.214228)
		(end 115.6208 -74.033888)
		(width 0.12954)
		(layer "F.Cu")
		(net "LED_PWRGD_PVCCINFAON_CPU1_D")
	)
	(segment
		(start 109.064044 -100.398326)
		(end 110.096046 -100.398326)
		(width 0.12954)
		(layer "F.Cu")
		(net "LED_PWRGD_PVCCINFAON_CPU1_D")
	)
	(segment
		(start 110.234984 -100.259388)
		(end 111.4425 -99.051872)
		(width 0.12954)
		(layer "F.Cu")
		(net "LED_PWRGD_PVCCINFAON_CPU1_D")
	)
	(segment
		(start 112.49152 -80.518508)
		(end 115.517676 -80.518508)
		(width 0.12954)
		(layer "F.Cu")
		(net "LED_PWRGD_PVCCINFAON_CPU1_D")
	)
	(segment
		(start 115.517676 -80.518508)
		(end 116.061236 -79.974948)
		(width 0.12954)
		(layer "F.Cu")
		(net "LED_PWRGD_PVCCINFAON_CPU1_D")
	)
	(segment
		(start 111.4425 -99.051872)
		(end 111.4425 -81.567528)
		(width 0.12954)
		(layer "F.Cu")
		(net "LED_PWRGD_PVCCINFAON_CPU1_D")
	)
	(segment
		(start 115.6208 -74.033888)
		(end 114.1857 -74.033888)
		(width 0.12954)
		(layer "F.Cu")
		(net "LED_PWRGD_PVCCINFAON_CPU1_D")
	)
	(segment
		(start 114.1857 -74.033888)
		(end 110.945422 -70.79361)
		(width 0.12954)
		(layer "F.Cu")
		(net "LED_PWRGD_PVCCINFAON_CPU1_D")
	)
	(segment
		(start 116.061236 -79.06385)
		(end 115.80114 -78.803754)
		(width 0.12954)
		(layer "F.Cu")
		(net "LED_PWRGD_PVCCINFAON_CPU1_D")
	)
	(segment
		(start 116.061236 -79.974948)
		(end 116.061236 -79.06385)
		(width 0.12954)
		(layer "F.Cu")
		(net "LED_PWRGD_PVCCINFAON_CPU1_D")
	)
	(segment
		(start 115.80114 -78.803754)
		(end 115.80114 -74.214228)
		(width 0.12954)
		(layer "F.Cu")
		(net "LED_PWRGD_PVCCINFAON_CPU1_D")
	)
	(via
		(at 110.234984 -100.259388)
		(size 0.762)
		(drill 0.381)
		(layers "F.Cu" "B.Cu")
		(net "LED_PWRGD_PVCCINFAON_CPU1_D")
	)
	(segment
		(start 109.706156 -66.904616)
		(end 109.741716 -66.869056)
		(width 0.12954)
		(layer "F.Cu")
		(net "LED_PWRGD_PVCCINFAON_CPU1")
	)
	(segment
		(start 109.706156 -70.79361)
		(end 109.706156 -66.904616)
		(width 0.12954)
		(layer "F.Cu")
		(net "LED_PWRGD_PVCCINFAON_CPU1")
	)
	(segment
		(start 109.741716 -65.668144)
		(end 109.695742 -65.62217)
		(width 0.12954)
		(layer "F.Cu")
		(net "LED_PWRGD_PVCCINFAON_CPU1")
	)
	(segment
		(start 109.741716 -66.869056)
		(end 109.741716 -65.668144)
		(width 0.12954)
		(layer "F.Cu")
		(net "LED_PWRGD_PVCCINFAON_CPU1")
	)
	(via
		(at 109.741716 -66.869056)
		(size 0.762)
		(drill 0.381)
		(layers "F.Cu" "B.Cu")
		(net "LED_PWRGD_PVCCINFAON_CPU1")
	)
	(segment
		(start 58.868056 -80.748124)
		(end 79.2099 -101.089968)
		(width 0.12954)
		(layer "F.Cu")
		(net "LED_PWRGD_PVCCINFAON_CPU0_D")
	)
	(segment
		(start 110.25124 -103.909368)
		(end 110.25124 -102.159308)
		(width 0.12954)
		(layer "F.Cu")
		(net "LED_PWRGD_PVCCINFAON_CPU0_D")
	)
	(segment
		(start 105.59034 -104.894888)
		(end 109.26572 -104.894888)
		(width 0.12954)
		(layer "F.Cu")
		(net "LED_PWRGD_PVCCINFAON_CPU0_D")
	)
	(segment
		(start 109.22508 -101.133148)
		(end 108.59516 -101.133148)
		(width 0.12954)
		(layer "F.Cu")
		(net "LED_PWRGD_PVCCINFAON_CPU0_D")
	)
	(segment
		(start 109.029246 -94.636082)
		(end 109.029246 -93.665548)
		(width 0.12954)
		(layer "F.Cu")
		(net "LED_PWRGD_PVCCINFAON_CPU0_D")
	)
	(segment
		(start 110.25124 -102.159308)
		(end 109.22508 -101.133148)
		(width 0.12954)
		(layer "F.Cu")
		(net "LED_PWRGD_PVCCINFAON_CPU0_D")
	)
	(segment
		(start 87.85606 -101.089968)
		(end 91.66098 -104.894888)
		(width 0.12954)
		(layer "F.Cu")
		(net "LED_PWRGD_PVCCINFAON_CPU0_D")
	)
	(segment
		(start 107.94746 -95.717868)
		(end 109.029246 -94.636082)
		(width 0.12954)
		(layer "F.Cu")
		(net "LED_PWRGD_PVCCINFAON_CPU0_D")
	)
	(segment
		(start 109.26572 -104.894888)
		(end 110.25124 -103.909368)
		(width 0.12954)
		(layer "F.Cu")
		(net "LED_PWRGD_PVCCINFAON_CPU0_D")
	)
	(segment
		(start 91.66098 -104.894888)
		(end 105.59034 -104.894888)
		(width 0.12954)
		(layer "F.Cu")
		(net "LED_PWRGD_PVCCINFAON_CPU0_D")
	)
	(segment
		(start 79.2099 -101.089968)
		(end 87.85606 -101.089968)
		(width 0.12954)
		(layer "F.Cu")
		(net "LED_PWRGD_PVCCINFAON_CPU0_D")
	)
	(segment
		(start 58.868056 -79.078836)
		(end 58.868056 -80.748124)
		(width 0.12954)
		(layer "F.Cu")
		(net "LED_PWRGD_PVCCINFAON_CPU0_D")
	)
	(segment
		(start 107.94746 -100.485448)
		(end 107.94746 -95.717868)
		(width 0.12954)
		(layer "F.Cu")
		(net "LED_PWRGD_PVCCINFAON_CPU0_D")
	)
	(segment
		(start 108.59516 -101.133148)
		(end 107.94746 -100.485448)
		(width 0.12954)
		(layer "F.Cu")
		(net "LED_PWRGD_PVCCINFAON_CPU0_D")
	)
	(via
		(at 105.59034 -104.894888)
		(size 0.762)
		(drill 0.381)
		(layers "F.Cu" "B.Cu")
		(net "LED_PWRGD_PVCCINFAON_CPU0_D")
	)
	(segment
		(start 57.918096 -79.078836)
		(end 57.918096 -80.460088)
		(width 0.12954)
		(layer "F.Cu")
		(net "LED_PWRGD_PVCCINFAON_CPU0")
	)
	(segment
		(start 57.918096 -80.460088)
		(end 57.43321 -80.944974)
		(width 0.12954)
		(layer "F.Cu")
		(net "LED_PWRGD_PVCCINFAON_CPU0")
	)
	(segment
		(start 57.43321 -80.944974)
		(end 56.618378 -80.944974)
		(width 0.12954)
		(layer "F.Cu")
		(net "LED_PWRGD_PVCCINFAON_CPU0")
	)
	(via
		(at 57.918096 -80.460088)
		(size 0.762)
		(drill 0.381)
		(layers "F.Cu" "B.Cu")
		(net "LED_PWRGD_PVCCINFAON_CPU0")
	)
	(segment
		(start 78.218538 -95.228918)
		(end 83.17738 -95.228918)
		(width 0.12954)
		(layer "F.Cu")
		(net "LED_PWRGD_PVCCFA_EHV_FIVRA_CP_2")
	)
	(segment
		(start 62.068456 -79.078836)
		(end 78.218538 -95.228918)
		(width 0.12954)
		(layer "F.Cu")
		(net "LED_PWRGD_PVCCFA_EHV_FIVRA_CP_2")
	)
	(segment
		(start 83.17738 -95.228918)
		(end 84.512658 -95.228918)
		(width 0.12954)
		(layer "F.Cu")
		(net "LED_PWRGD_PVCCFA_EHV_FIVRA_CP_2")
	)
	(segment
		(start 84.512658 -95.228918)
		(end 84.626196 -95.342456)
		(width 0.12954)
		(layer "F.Cu")
		(net "LED_PWRGD_PVCCFA_EHV_FIVRA_CP_2")
	)
	(via
		(at 83.17738 -95.228918)
		(size 0.762)
		(drill 0.381)
		(layers "F.Cu" "B.Cu")
		(net "LED_PWRGD_PVCCFA_EHV_FIVRA_CP_2")
	)
	(segment
		(start 78.428342 -92.238322)
		(end 83.13674 -92.238322)
		(width 0.12954)
		(layer "F.Cu")
		(net "LED_PWRGD_PVCCFA_EHV_FIVRA_CP_1")
	)
	(segment
		(start 65.268856 -79.078836)
		(end 78.428342 -92.238322)
		(width 0.12954)
		(layer "F.Cu")
		(net "LED_PWRGD_PVCCFA_EHV_FIVRA_CP_1")
	)
	(segment
		(start 83.13674 -92.238322)
		(end 84.626196 -92.238322)
		(width 0.12954)
		(layer "F.Cu")
		(net "LED_PWRGD_PVCCFA_EHV_FIVRA_CP_1")
	)
	(via
		(at 83.13674 -92.238322)
		(size 0.762)
		(drill 0.381)
		(layers "F.Cu" "B.Cu")
		(net "LED_PWRGD_PVCCFA_EHV_FIVRA_CP_1")
	)
	(segment
		(start 72.26681 -75.301602)
		(end 70.9676 -75.301602)
		(width 0.12954)
		(layer "F.Cu")
		(net "LED_PWRGD_PVCCFA_EHV_FIVRA_CPU1")
	)
	(segment
		(start 70.9676 -75.301602)
		(end 70.025514 -76.243688)
		(width 0.12954)
		(layer "F.Cu")
		(net "LED_PWRGD_PVCCFA_EHV_FIVRA_CPU1")
	)
	(segment
		(start 70.025514 -76.243688)
		(end 63.07074 -76.243688)
		(width 0.12954)
		(layer "F.Cu")
		(net "LED_PWRGD_PVCCFA_EHV_FIVRA_CPU1")
	)
	(segment
		(start 61.118496 -78.195932)
		(end 61.118496 -79.078836)
		(width 0.12954)
		(layer "F.Cu")
		(net "LED_PWRGD_PVCCFA_EHV_FIVRA_CPU1")
	)
	(segment
		(start 63.07074 -76.243688)
		(end 61.118496 -78.195932)
		(width 0.12954)
		(layer "F.Cu")
		(net "LED_PWRGD_PVCCFA_EHV_FIVRA_CPU1")
	)
	(via
		(at 70.9676 -75.301602)
		(size 0.762)
		(drill 0.381)
		(layers "F.Cu" "B.Cu")
		(net "LED_PWRGD_PVCCFA_EHV_FIVRA_CPU1")
	)
	(segment
		(start 64.89954 -77.409548)
		(end 64.318896 -77.990192)
		(width 0.12954)
		(layer "F.Cu")
		(net "LED_PWRGD_PVCCFA_EHV_FIVRA_CPU0")
	)
	(segment
		(start 66.1162 -77.409548)
		(end 64.89954 -77.409548)
		(width 0.12954)
		(layer "F.Cu")
		(net "LED_PWRGD_PVCCFA_EHV_FIVRA_CPU0")
	)
	(segment
		(start 73.475596 -75.998832)
		(end 72.87514 -76.599288)
		(width 0.12954)
		(layer "F.Cu")
		(net "LED_PWRGD_PVCCFA_EHV_FIVRA_CPU0")
	)
	(segment
		(start 66.92646 -76.599288)
		(end 66.1162 -77.409548)
		(width 0.12954)
		(layer "F.Cu")
		(net "LED_PWRGD_PVCCFA_EHV_FIVRA_CPU0")
	)
	(segment
		(start 64.318896 -77.990192)
		(end 64.318896 -79.078836)
		(width 0.12954)
		(layer "F.Cu")
		(net "LED_PWRGD_PVCCFA_EHV_FIVRA_CPU0")
	)
	(segment
		(start 73.475596 -75.301602)
		(end 73.475596 -75.998832)
		(width 0.12954)
		(layer "F.Cu")
		(net "LED_PWRGD_PVCCFA_EHV_FIVRA_CPU0")
	)
	(segment
		(start 72.87514 -76.599288)
		(end 66.92646 -76.599288)
		(width 0.12954)
		(layer "F.Cu")
		(net "LED_PWRGD_PVCCFA_EHV_FIVRA_CPU0")
	)
	(via
		(at 66.1162 -77.409548)
		(size 0.762)
		(drill 0.381)
		(layers "F.Cu" "B.Cu")
		(net "LED_PWRGD_PVCCFA_EHV_FIVRA_CPU0")
	)
	(segment
		(start 68.469256 -81.259934)
		(end 78.75651 -91.547188)
		(width 0.12954)
		(layer "F.Cu")
		(net "LED_PWRGD_PVCCFA_EHV_CPU1_D")
	)
	(segment
		(start 85.1916 -91.858338)
		(end 85.1916 -95.829628)
		(width 0.12954)
		(layer "F.Cu")
		(net "LED_PWRGD_PVCCFA_EHV_CPU1_D")
	)
	(segment
		(start 84.88045 -91.547188)
		(end 85.1916 -91.858338)
		(width 0.12954)
		(layer "F.Cu")
		(net "LED_PWRGD_PVCCFA_EHV_CPU1_D")
	)
	(segment
		(start 68.469256 -79.078836)
		(end 68.469256 -81.259934)
		(width 0.12954)
		(layer "F.Cu")
		(net "LED_PWRGD_PVCCFA_EHV_CPU1_D")
	)
	(segment
		(start 85.1916 -95.829628)
		(end 86.0044 -96.642428)
		(width 0.12954)
		(layer "F.Cu")
		(net "LED_PWRGD_PVCCFA_EHV_CPU1_D")
	)
	(segment
		(start 86.0044 -96.642428)
		(end 86.526116 -96.642428)
		(width 0.12954)
		(layer "F.Cu")
		(net "LED_PWRGD_PVCCFA_EHV_CPU1_D")
	)
	(segment
		(start 78.75651 -91.547188)
		(end 81.5594 -91.547188)
		(width 0.12954)
		(layer "F.Cu")
		(net "LED_PWRGD_PVCCFA_EHV_CPU1_D")
	)
	(segment
		(start 81.5594 -91.547188)
		(end 84.88045 -91.547188)
		(width 0.12954)
		(layer "F.Cu")
		(net "LED_PWRGD_PVCCFA_EHV_CPU1_D")
	)
	(via
		(at 81.5594 -91.547188)
		(size 0.762)
		(drill 0.381)
		(layers "F.Cu" "B.Cu")
		(net "LED_PWRGD_PVCCFA_EHV_CPU1_D")
	)
	(segment
		(start 73.89114 -77.003148)
		(end 74.615802 -76.278486)
		(width 0.12954)
		(layer "F.Cu")
		(net "LED_PWRGD_PVCCFA_EHV_CPU1")
	)
	(segment
		(start 68.230496 -77.003148)
		(end 73.89114 -77.003148)
		(width 0.12954)
		(layer "F.Cu")
		(net "LED_PWRGD_PVCCFA_EHV_CPU1")
	)
	(segment
		(start 74.615802 -76.278486)
		(end 74.615802 -75.301602)
		(width 0.12954)
		(layer "F.Cu")
		(net "LED_PWRGD_PVCCFA_EHV_CPU1")
	)
	(segment
		(start 67.519296 -77.714348)
		(end 68.230496 -77.003148)
		(width 0.12954)
		(layer "F.Cu")
		(net "LED_PWRGD_PVCCFA_EHV_CPU1")
	)
	(segment
		(start 67.519296 -79.078836)
		(end 67.519296 -77.714348)
		(width 0.12954)
		(layer "F.Cu")
		(net "LED_PWRGD_PVCCFA_EHV_CPU1")
	)
	(via
		(at 67.519296 -77.714348)
		(size 0.762)
		(drill 0.381)
		(layers "F.Cu" "B.Cu")
		(net "LED_PWRGD_PVCCFA_EHV_CPU1")
	)
	(segment
		(start 71.669656 -82.180684)
		(end 79.9973 -90.508328)
		(width 0.12954)
		(layer "F.Cu")
		(net "LED_PWRGD_PVCCFA_EHV_CPU0_D")
	)
	(segment
		(start 85.81136 -92.079064)
		(end 85.81136 -93.225874)
		(width 0.12954)
		(layer "F.Cu")
		(net "LED_PWRGD_PVCCFA_EHV_CPU0_D")
	)
	(segment
		(start 84.533232 -90.800936)
		(end 85.81136 -92.079064)
		(width 0.12954)
		(layer "F.Cu")
		(net "LED_PWRGD_PVCCFA_EHV_CPU0_D")
	)
	(segment
		(start 71.669656 -79.078836)
		(end 71.669656 -82.180684)
		(width 0.12954)
		(layer "F.Cu")
		(net "LED_PWRGD_PVCCFA_EHV_CPU0_D")
	)
	(segment
		(start 86.12378 -93.538294)
		(end 86.526116 -93.538294)
		(width 0.12954)
		(layer "F.Cu")
		(net "LED_PWRGD_PVCCFA_EHV_CPU0_D")
	)
	(segment
		(start 84.240624 -90.508328)
		(end 84.533232 -90.800936)
		(width 0.12954)
		(layer "F.Cu")
		(net "LED_PWRGD_PVCCFA_EHV_CPU0_D")
	)
	(segment
		(start 85.81136 -93.225874)
		(end 86.12378 -93.538294)
		(width 0.12954)
		(layer "F.Cu")
		(net "LED_PWRGD_PVCCFA_EHV_CPU0_D")
	)
	(segment
		(start 79.9973 -90.508328)
		(end 84.240624 -90.508328)
		(width 0.12954)
		(layer "F.Cu")
		(net "LED_PWRGD_PVCCFA_EHV_CPU0_D")
	)
	(via
		(at 84.533232 -90.800936)
		(size 0.762)
		(drill 0.381)
		(layers "F.Cu" "B.Cu")
		(net "LED_PWRGD_PVCCFA_EHV_CPU0_D")
	)
	(segment
		(start 75.738736 -75.301602)
		(end 75.738736 -75.915012)
		(width 0.12954)
		(layer "F.Cu")
		(net "LED_PWRGD_PVCCFA_EHV_CPU0")
	)
	(segment
		(start 73.9902 -77.663548)
		(end 69.7484 -77.663548)
		(width 0.12954)
		(layer "F.Cu")
		(net "LED_PWRGD_PVCCFA_EHV_CPU0")
	)
	(segment
		(start 69.7484 -77.663548)
		(end 70.719696 -78.634844)
		(width 0.12954)
		(layer "F.Cu")
		(net "LED_PWRGD_PVCCFA_EHV_CPU0")
	)
	(segment
		(start 70.719696 -78.634844)
		(end 70.719696 -79.078836)
		(width 0.12954)
		(layer "F.Cu")
		(net "LED_PWRGD_PVCCFA_EHV_CPU0")
	)
	(segment
		(start 75.738736 -75.915012)
		(end 73.9902 -77.663548)
		(width 0.12954)
		(layer "F.Cu")
		(net "LED_PWRGD_PVCCFA_EHV_CPU0")
	)
	(via
		(at 69.7484 -77.663548)
		(size 0.762)
		(drill 0.381)
		(layers "F.Cu" "B.Cu")
		(net "LED_PWRGD_PVCCFA_EHV_CPU0")
	)
	(segment
		(start 87.06358 -86.543388)
		(end 87.06358 -87.999316)
		(width 0.12954)
		(layer "F.Cu")
		(net "LED_PWRGD_PVCCD_HV_CPU1_D")
	)
	(segment
		(start 94.26194 -100.002848)
		(end 94.486476 -100.227384)
		(width 0.12954)
		(layer "F.Cu")
		(net "LED_PWRGD_PVCCD_HV_CPU1_D")
	)
	(segment
		(start 96.122998 -96.85909)
		(end 94.26194 -98.720148)
		(width 0.12954)
		(layer "F.Cu")
		(net "LED_PWRGD_PVCCD_HV_CPU1_D")
	)
	(segment
		(start 96.122998 -95.414846)
		(end 96.122998 -96.85909)
		(width 0.12954)
		(layer "F.Cu")
		(net "LED_PWRGD_PVCCD_HV_CPU1_D")
	)
	(segment
		(start 89.42324 -90.358976)
		(end 89.42324 -91.572588)
		(width 0.12954)
		(layer "F.Cu")
		(net "LED_PWRGD_PVCCD_HV_CPU1_D")
	)
	(segment
		(start 87.06358 -87.999316)
		(end 89.42324 -90.358976)
		(width 0.12954)
		(layer "F.Cu")
		(net "LED_PWRGD_PVCCD_HV_CPU1_D")
	)
	(segment
		(start 90.340434 -92.489782)
		(end 92.2528 -94.402148)
		(width 0.12954)
		(layer "F.Cu")
		(net "LED_PWRGD_PVCCD_HV_CPU1_D")
	)
	(segment
		(start 94.26194 -98.720148)
		(end 94.26194 -100.002848)
		(width 0.12954)
		(layer "F.Cu")
		(net "LED_PWRGD_PVCCD_HV_CPU1_D")
	)
	(segment
		(start 81.270856 -79.078836)
		(end 81.270856 -80.750664)
		(width 0.12954)
		(layer "F.Cu")
		(net "LED_PWRGD_PVCCD_HV_CPU1_D")
	)
	(segment
		(start 92.2528 -94.402148)
		(end 95.1103 -94.402148)
		(width 0.12954)
		(layer "F.Cu")
		(net "LED_PWRGD_PVCCD_HV_CPU1_D")
	)
	(segment
		(start 89.42324 -91.572588)
		(end 90.340434 -92.489782)
		(width 0.12954)
		(layer "F.Cu")
		(net "LED_PWRGD_PVCCD_HV_CPU1_D")
	)
	(segment
		(start 81.270856 -80.750664)
		(end 87.06358 -86.543388)
		(width 0.12954)
		(layer "F.Cu")
		(net "LED_PWRGD_PVCCD_HV_CPU1_D")
	)
	(segment
		(start 95.1103 -94.402148)
		(end 96.122998 -95.414846)
		(width 0.12954)
		(layer "F.Cu")
		(net "LED_PWRGD_PVCCD_HV_CPU1_D")
	)
	(segment
		(start 94.486476 -100.227384)
		(end 95.036386 -100.227384)
		(width 0.12954)
		(layer "F.Cu")
		(net "LED_PWRGD_PVCCD_HV_CPU1_D")
	)
	(via
		(at 90.340434 -92.489782)
		(size 0.762)
		(drill 0.381)
		(layers "F.Cu" "B.Cu")
		(net "LED_PWRGD_PVCCD_HV_CPU1_D")
	)
	(segment
		(start 80.320896 -75.395328)
		(end 80.381602 -75.334622)
		(width 0.12954)
		(layer "F.Cu")
		(net "LED_PWRGD_PVCCD_HV_CPU1")
	)
	(segment
		(start 80.320896 -77.663548)
		(end 80.320896 -75.395328)
		(width 0.12954)
		(layer "F.Cu")
		(net "LED_PWRGD_PVCCD_HV_CPU1")
	)
	(segment
		(start 80.320896 -79.078836)
		(end 80.320896 -77.663548)
		(width 0.12954)
		(layer "F.Cu")
		(net "LED_PWRGD_PVCCD_HV_CPU1")
	)
	(segment
		(start 80.381602 -75.334622)
		(end 80.381602 -75.301602)
		(width 0.12954)
		(layer "F.Cu")
		(net "LED_PWRGD_PVCCD_HV_CPU1")
	)
	(via
		(at 80.320896 -77.663548)
		(size 0.762)
		(drill 0.381)
		(layers "F.Cu" "B.Cu")
		(net "LED_PWRGD_PVCCD_HV_CPU1")
	)
	(segment
		(start 84.471256 -80.389984)
		(end 89.29878 -85.217508)
		(width 0.12954)
		(layer "F.Cu")
		(net "LED_PWRGD_PVCCD_HV_CPU0_D")
	)
	(segment
		(start 99.02444 -100.792788)
		(end 99.72802 -101.496368)
		(width 0.12954)
		(layer "F.Cu")
		(net "LED_PWRGD_PVCCD_HV_CPU0_D")
	)
	(segment
		(start 98.73996 -100.792788)
		(end 99.02444 -100.792788)
		(width 0.12954)
		(layer "F.Cu")
		(net "LED_PWRGD_PVCCD_HV_CPU0_D")
	)
	(segment
		(start 89.29878 -85.217508)
		(end 92.7227 -85.217508)
		(width 0.12954)
		(layer "F.Cu")
		(net "LED_PWRGD_PVCCD_HV_CPU0_D")
	)
	(segment
		(start 101.480874 -103.343202)
		(end 101.886766 -103.343202)
		(width 0.12954)
		(layer "F.Cu")
		(net "LED_PWRGD_PVCCD_HV_CPU0_D")
	)
	(segment
		(start 97.861374 -99.914202)
		(end 98.2345 -100.287328)
		(width 0.12954)
		(layer "F.Cu")
		(net "LED_PWRGD_PVCCD_HV_CPU0_D")
	)
	(segment
		(start 98.2345 -100.287328)
		(end 98.73996 -100.792788)
		(width 0.12954)
		(layer "F.Cu")
		(net "LED_PWRGD_PVCCD_HV_CPU0_D")
	)
	(segment
		(start 96.12122 -88.616028)
		(end 96.12122 -91.194128)
		(width 0.12954)
		(layer "F.Cu")
		(net "LED_PWRGD_PVCCD_HV_CPU0_D")
	)
	(segment
		(start 99.72802 -101.496368)
		(end 100.53574 -101.496368)
		(width 0.12954)
		(layer "F.Cu")
		(net "LED_PWRGD_PVCCD_HV_CPU0_D")
	)
	(segment
		(start 96.79432 -91.867228)
		(end 96.79432 -93.68282)
		(width 0.12954)
		(layer "F.Cu")
		(net "LED_PWRGD_PVCCD_HV_CPU0_D")
	)
	(segment
		(start 100.53574 -101.496368)
		(end 101.0539 -102.014528)
		(width 0.12954)
		(layer "F.Cu")
		(net "LED_PWRGD_PVCCD_HV_CPU0_D")
	)
	(segment
		(start 96.79432 -93.68282)
		(end 97.861374 -94.749874)
		(width 0.12954)
		(layer "F.Cu")
		(net "LED_PWRGD_PVCCD_HV_CPU0_D")
	)
	(segment
		(start 97.861374 -94.749874)
		(end 97.861374 -99.914202)
		(width 0.12954)
		(layer "F.Cu")
		(net "LED_PWRGD_PVCCD_HV_CPU0_D")
	)
	(segment
		(start 92.7227 -85.217508)
		(end 96.12122 -88.616028)
		(width 0.12954)
		(layer "F.Cu")
		(net "LED_PWRGD_PVCCD_HV_CPU0_D")
	)
	(segment
		(start 101.0539 -102.014528)
		(end 101.0539 -102.916228)
		(width 0.12954)
		(layer "F.Cu")
		(net "LED_PWRGD_PVCCD_HV_CPU0_D")
	)
	(segment
		(start 84.471256 -79.078836)
		(end 84.471256 -80.389984)
		(width 0.12954)
		(layer "F.Cu")
		(net "LED_PWRGD_PVCCD_HV_CPU0_D")
	)
	(segment
		(start 96.12122 -91.194128)
		(end 96.79432 -91.867228)
		(width 0.12954)
		(layer "F.Cu")
		(net "LED_PWRGD_PVCCD_HV_CPU0_D")
	)
	(segment
		(start 101.0539 -102.916228)
		(end 101.480874 -103.343202)
		(width 0.12954)
		(layer "F.Cu")
		(net "LED_PWRGD_PVCCD_HV_CPU0_D")
	)
	(via
		(at 98.2345 -100.287328)
		(size 0.762)
		(drill 0.381)
		(layers "F.Cu" "B.Cu")
		(net "LED_PWRGD_PVCCD_HV_CPU0_D")
	)
	(segment
		(start 83.521296 -76.120244)
		(end 84.328 -76.926948)
		(width 0.12954)
		(layer "F.Cu")
		(net "LED_PWRGD_PVCCD_HV_CPU0")
	)
	(segment
		(start 83.521296 -75.346814)
		(end 83.521296 -76.120244)
		(width 0.12954)
		(layer "F.Cu")
		(net "LED_PWRGD_PVCCD_HV_CPU0")
	)
	(segment
		(start 83.521296 -77.733652)
		(end 83.521296 -79.078836)
		(width 0.12954)
		(layer "F.Cu")
		(net "LED_PWRGD_PVCCD_HV_CPU0")
	)
	(segment
		(start 84.328 -76.926948)
		(end 83.521296 -77.733652)
		(width 0.12954)
		(layer "F.Cu")
		(net "LED_PWRGD_PVCCD_HV_CPU0")
	)
	(segment
		(start 83.566508 -75.301602)
		(end 83.521296 -75.346814)
		(width 0.12954)
		(layer "F.Cu")
		(net "LED_PWRGD_PVCCD_HV_CPU0")
	)
	(via
		(at 84.328 -76.926948)
		(size 0.762)
		(drill 0.381)
		(layers "F.Cu" "B.Cu")
		(net "LED_PWRGD_PVCCD_HV_CPU0")
	)
	(segment
		(start 97.98812 -87.742268)
		(end 97.98812 -89.497408)
		(width 0.12954)
		(layer "F.Cu")
		(net "LED_PWRGD_PS_PWROK_PLD_D")
	)
	(segment
		(start 99.99853 -91.792298)
		(end 99.99853 -92.222574)
		(width 0.12954)
		(layer "F.Cu")
		(net "LED_PWRGD_PS_PWROK_PLD_D")
	)
	(segment
		(start 94.072456 -83.826604)
		(end 97.98812 -87.742268)
		(width 0.12954)
		(layer "F.Cu")
		(net "LED_PWRGD_PS_PWROK_PLD_D")
	)
	(segment
		(start 97.98812 -89.497408)
		(end 97.98812 -89.781888)
		(width 0.12954)
		(layer "F.Cu")
		(net "LED_PWRGD_PS_PWROK_PLD_D")
	)
	(segment
		(start 94.072456 -79.078836)
		(end 94.072456 -83.826604)
		(width 0.12954)
		(layer "F.Cu")
		(net "LED_PWRGD_PS_PWROK_PLD_D")
	)
	(segment
		(start 97.98812 -89.781888)
		(end 99.99853 -91.792298)
		(width 0.12954)
		(layer "F.Cu")
		(net "LED_PWRGD_PS_PWROK_PLD_D")
	)
	(via
		(at 97.98812 -89.497408)
		(size 0.762)
		(drill 0.381)
		(layers "F.Cu" "B.Cu")
		(net "LED_PWRGD_PS_PWROK_PLD_D")
	)
	(segment
		(start 93.089222 -76.957936)
		(end 93.089222 -77.473048)
		(width 0.12954)
		(layer "F.Cu")
		(net "LED_PWRGD_PS_PWROK_PLD")
	)
	(segment
		(start 93.090492 -75.136756)
		(end 93.090492 -76.383642)
		(width 0.12954)
		(layer "F.Cu")
		(net "LED_PWRGD_PS_PWROK_PLD")
	)
	(segment
		(start 93.089222 -77.473048)
		(end 93.122496 -77.506322)
		(width 0.12954)
		(layer "F.Cu")
		(net "LED_PWRGD_PS_PWROK_PLD")
	)
	(segment
		(start 93.090492 -76.383642)
		(end 93.090492 -76.956666)
		(width 0.12954)
		(layer "F.Cu")
		(net "LED_PWRGD_PS_PWROK_PLD")
	)
	(segment
		(start 93.122496 -77.506322)
		(end 93.122496 -79.078836)
		(width 0.12954)
		(layer "F.Cu")
		(net "LED_PWRGD_PS_PWROK_PLD")
	)
	(segment
		(start 93.090492 -76.956666)
		(end 93.089222 -76.957936)
		(width 0.12954)
		(layer "F.Cu")
		(net "LED_PWRGD_PS_PWROK_PLD")
	)
	(via
		(at 93.090492 -76.383642)
		(size 0.762)
		(drill 0.381)
		(layers "F.Cu" "B.Cu")
		(net "LED_PWRGD_PS_PWROK_PLD")
	)
	(segment
		(start 99.191064 -94.026228)
		(end 99.80168 -94.026228)
		(width 0.12954)
		(layer "F.Cu")
		(net "LED_PWRGD_PCH_PWROK_R_D")
	)
	(segment
		(start 94.257876 -70.78599)
		(end 94.257876 -71.373492)
		(width 0.12954)
		(layer "F.Cu")
		(net "LED_PWRGD_PCH_PWROK_R_D")
	)
	(segment
		(start 100.95992 -95.184468)
		(end 100.95992 -96.472502)
		(width 0.12954)
		(layer "F.Cu")
		(net "LED_PWRGD_PCH_PWROK_R_D")
	)
	(segment
		(start 101.26091 -96.773492)
		(end 101.874574 -96.773492)
		(width 0.12954)
		(layer "F.Cu")
		(net "LED_PWRGD_PCH_PWROK_R_D")
	)
	(segment
		(start 94.257876 -71.373492)
		(end 92.03182 -73.599548)
		(width 0.12954)
		(layer "F.Cu")
		(net "LED_PWRGD_PCH_PWROK_R_D")
	)
	(segment
		(start 97.268538 -88.140286)
		(end 97.268538 -90.169746)
		(width 0.12954)
		(layer "F.Cu")
		(net "LED_PWRGD_PCH_PWROK_R_D")
	)
	(segment
		(start 98.79076 -91.691968)
		(end 98.79076 -93.625924)
		(width 0.12954)
		(layer "F.Cu")
		(net "LED_PWRGD_PCH_PWROK_R_D")
	)
	(segment
		(start 92.03182 -73.599548)
		(end 92.03182 -82.903568)
		(width 0.12954)
		(layer "F.Cu")
		(net "LED_PWRGD_PCH_PWROK_R_D")
	)
	(segment
		(start 98.79076 -93.625924)
		(end 99.191064 -94.026228)
		(width 0.12954)
		(layer "F.Cu")
		(net "LED_PWRGD_PCH_PWROK_R_D")
	)
	(segment
		(start 92.03182 -82.903568)
		(end 97.268538 -88.140286)
		(width 0.12954)
		(layer "F.Cu")
		(net "LED_PWRGD_PCH_PWROK_R_D")
	)
	(segment
		(start 98.31578 -91.216988)
		(end 98.79076 -91.691968)
		(width 0.12954)
		(layer "F.Cu")
		(net "LED_PWRGD_PCH_PWROK_R_D")
	)
	(segment
		(start 99.80168 -94.026228)
		(end 100.95992 -95.184468)
		(width 0.12954)
		(layer "F.Cu")
		(net "LED_PWRGD_PCH_PWROK_R_D")
	)
	(segment
		(start 100.95992 -96.472502)
		(end 101.26091 -96.773492)
		(width 0.12954)
		(layer "F.Cu")
		(net "LED_PWRGD_PCH_PWROK_R_D")
	)
	(segment
		(start 97.268538 -90.169746)
		(end 98.31578 -91.216988)
		(width 0.12954)
		(layer "F.Cu")
		(net "LED_PWRGD_PCH_PWROK_R_D")
	)
	(via
		(at 98.31578 -91.216988)
		(size 0.762)
		(drill 0.381)
		(layers "F.Cu" "B.Cu")
		(net "LED_PWRGD_PCH_PWROK_R_D")
	)
	(segment
		(start 93.300804 -66.8147)
		(end 93.300804 -65.628774)
		(width 0.12954)
		(layer "F.Cu")
		(net "LED_PWRGD_PCH_PWROK_R")
	)
	(segment
		(start 93.300804 -68.133468)
		(end 93.300804 -66.8147)
		(width 0.12954)
		(layer "F.Cu")
		(net "LED_PWRGD_PCH_PWROK_R")
	)
	(segment
		(start 93.307916 -68.14058)
		(end 93.300804 -68.133468)
		(width 0.12954)
		(layer "F.Cu")
		(net "LED_PWRGD_PCH_PWROK_R")
	)
	(segment
		(start 93.300804 -65.628774)
		(end 93.295724 -65.623694)
		(width 0.12954)
		(layer "F.Cu")
		(net "LED_PWRGD_PCH_PWROK_R")
	)
	(segment
		(start 93.307916 -70.78599)
		(end 93.307916 -68.14058)
		(width 0.12954)
		(layer "F.Cu")
		(net "LED_PWRGD_PCH_PWROK_R")
	)
	(via
		(at 93.300804 -66.8147)
		(size 0.762)
		(drill 0.381)
		(layers "F.Cu" "B.Cu")
		(net "LED_PWRGD_PCH_PWROK_R")
	)
	(segment
		(start 110.73892 -96.455484)
		(end 110.224824 -96.96958)
		(width 0.12954)
		(layer "F.Cu")
		(net "LED_PWRGD_P1V8_PCH_AUX_D")
	)
	(segment
		(start 110.224824 -96.96958)
		(end 108.969302 -96.96958)
		(width 0.12954)
		(layer "F.Cu")
		(net "LED_PWRGD_P1V8_PCH_AUX_D")
	)
	(segment
		(start 110.73892 -79.7433)
		(end 110.73892 -96.455484)
		(width 0.12954)
		(layer "F.Cu")
		(net "LED_PWRGD_P1V8_PCH_AUX_D")
	)
	(segment
		(start 110.074456 -79.078836)
		(end 110.73892 -79.7433)
		(width 0.12954)
		(layer "F.Cu")
		(net "LED_PWRGD_P1V8_PCH_AUX_D")
	)
	(segment
		(start 108.969302 -96.96958)
		(end 108.966762 -96.96704)
		(width 0.12954)
		(layer "F.Cu")
		(net "LED_PWRGD_P1V8_PCH_AUX_D")
	)
	(via
		(at 110.224824 -96.96958)
		(size 0.762)
		(drill 0.381)
		(layers "F.Cu" "B.Cu")
		(net "LED_PWRGD_P1V8_PCH_AUX_D")
	)
	(segment
		(start 109.145832 -76.477368)
		(end 109.145832 -79.0575)
		(width 0.12954)
		(layer "F.Cu")
		(net "LED_PWRGD_P1V8_PCH_AUX")
	)
	(segment
		(start 109.144308 -76.475844)
		(end 109.145832 -76.477368)
		(width 0.12954)
		(layer "F.Cu")
		(net "LED_PWRGD_P1V8_PCH_AUX")
	)
	(segment
		(start 109.145832 -79.0575)
		(end 109.124496 -79.078836)
		(width 0.12954)
		(layer "F.Cu")
		(net "LED_PWRGD_P1V8_PCH_AUX")
	)
	(segment
		(start 109.144308 -75.263502)
		(end 109.144308 -76.475844)
		(width 0.12954)
		(layer "F.Cu")
		(net "LED_PWRGD_P1V8_PCH_AUX")
	)
	(via
		(at 109.145832 -76.477368)
		(size 0.762)
		(drill 0.381)
		(layers "F.Cu" "B.Cu")
		(net "LED_PWRGD_P1V8_PCH_AUX")
	)
	(segment
		(start 105.12552 -80.827372)
		(end 106.874056 -79.078836)
		(width 0.12954)
		(layer "F.Cu")
		(net "LED_PWRGD_P1V05_PCH_AUX_D")
	)
	(segment
		(start 107.066842 -95.667068)
		(end 106.007154 -95.667068)
		(width 0.12954)
		(layer "F.Cu")
		(net "LED_PWRGD_P1V05_PCH_AUX_D")
	)
	(segment
		(start 105.12552 -94.785434)
		(end 105.12552 -80.827372)
		(width 0.12954)
		(layer "F.Cu")
		(net "LED_PWRGD_P1V05_PCH_AUX_D")
	)
	(segment
		(start 105.57002 -95.229934)
		(end 105.12552 -94.785434)
		(width 0.12954)
		(layer "F.Cu")
		(net "LED_PWRGD_P1V05_PCH_AUX_D")
	)
	(segment
		(start 106.007154 -95.667068)
		(end 105.57002 -95.229934)
		(width 0.12954)
		(layer "F.Cu")
		(net "LED_PWRGD_P1V05_PCH_AUX_D")
	)
	(via
		(at 105.57002 -95.229934)
		(size 0.762)
		(drill 0.381)
		(layers "F.Cu" "B.Cu")
		(net "LED_PWRGD_P1V05_PCH_AUX_D")
	)
	(segment
		(start 105.973626 -77.96403)
		(end 105.973626 -76.615798)
		(width 0.12954)
		(layer "F.Cu")
		(net "LED_PWRGD_P1V05_PCH_AUX")
	)
	(segment
		(start 105.973626 -76.615798)
		(end 105.973626 -75.39355)
		(width 0.12954)
		(layer "F.Cu")
		(net "LED_PWRGD_P1V05_PCH_AUX")
	)
	(segment
		(start 105.924096 -78.01356)
		(end 105.973626 -77.96403)
		(width 0.12954)
		(layer "F.Cu")
		(net "LED_PWRGD_P1V05_PCH_AUX")
	)
	(segment
		(start 105.973626 -75.39355)
		(end 105.973372 -75.393296)
		(width 0.12954)
		(layer "F.Cu")
		(net "LED_PWRGD_P1V05_PCH_AUX")
	)
	(segment
		(start 105.924096 -79.078836)
		(end 105.924096 -78.01356)
		(width 0.12954)
		(layer "F.Cu")
		(net "LED_PWRGD_P1V05_PCH_AUX")
	)
	(via
		(at 105.973626 -76.615798)
		(size 0.762)
		(drill 0.381)
		(layers "F.Cu" "B.Cu")
		(net "LED_PWRGD_P1V05_PCH_AUX")
	)
	(segment
		(start 96.704658 -88.373966)
		(end 96.704658 -90.952066)
		(width 0.12954)
		(layer "F.Cu")
		(net "LED_PWRGD_CPUPWRGD_GTL_D")
	)
	(segment
		(start 100.92182 -99.700588)
		(end 101.2952 -100.073968)
		(width 0.12954)
		(layer "F.Cu")
		(net "LED_PWRGD_CPUPWRGD_GTL_D")
	)
	(segment
		(start 98.510852 -97.119948)
		(end 98.757994 -97.36709)
		(width 0.12954)
		(layer "F.Cu")
		(net "LED_PWRGD_CPUPWRGD_GTL_D")
	)
	(segment
		(start 98.510852 -94.56166)
		(end 98.510852 -97.119948)
		(width 0.12954)
		(layer "F.Cu")
		(net "LED_PWRGD_CPUPWRGD_GTL_D")
	)
	(segment
		(start 100.46208 -97.996248)
		(end 100.92182 -98.455988)
		(width 0.12954)
		(layer "F.Cu")
		(net "LED_PWRGD_CPUPWRGD_GTL_D")
	)
	(segment
		(start 98.757994 -97.36709)
		(end 99.387152 -97.996248)
		(width 0.12954)
		(layer "F.Cu")
		(net "LED_PWRGD_CPUPWRGD_GTL_D")
	)
	(segment
		(start 97.3582 -91.605608)
		(end 97.3582 -93.409008)
		(width 0.12954)
		(layer "F.Cu")
		(net "LED_PWRGD_CPUPWRGD_GTL_D")
	)
	(segment
		(start 99.387152 -97.996248)
		(end 100.46208 -97.996248)
		(width 0.12954)
		(layer "F.Cu")
		(net "LED_PWRGD_CPUPWRGD_GTL_D")
	)
	(segment
		(start 88.69172 -71.620634)
		(end 88.69172 -80.361028)
		(width 0.12954)
		(layer "F.Cu")
		(net "LED_PWRGD_CPUPWRGD_GTL_D")
	)
	(segment
		(start 88.69172 -80.361028)
		(end 96.704658 -88.373966)
		(width 0.12954)
		(layer "F.Cu")
		(net "LED_PWRGD_CPUPWRGD_GTL_D")
	)
	(segment
		(start 97.3582 -93.409008)
		(end 98.510852 -94.56166)
		(width 0.12954)
		(layer "F.Cu")
		(net "LED_PWRGD_CPUPWRGD_GTL_D")
	)
	(segment
		(start 96.704658 -90.952066)
		(end 97.3582 -91.605608)
		(width 0.12954)
		(layer "F.Cu")
		(net "LED_PWRGD_CPUPWRGD_GTL_D")
	)
	(segment
		(start 101.2952 -100.073968)
		(end 101.87178 -100.073968)
		(width 0.12954)
		(layer "F.Cu")
		(net "LED_PWRGD_CPUPWRGD_GTL_D")
	)
	(segment
		(start 87.857076 -70.78599)
		(end 88.69172 -71.620634)
		(width 0.12954)
		(layer "F.Cu")
		(net "LED_PWRGD_CPUPWRGD_GTL_D")
	)
	(segment
		(start 100.92182 -98.455988)
		(end 100.92182 -99.700588)
		(width 0.12954)
		(layer "F.Cu")
		(net "LED_PWRGD_CPUPWRGD_GTL_D")
	)
	(via
		(at 98.757994 -97.36709)
		(size 0.762)
		(drill 0.381)
		(layers "F.Cu" "B.Cu")
		(net "LED_PWRGD_CPUPWRGD_GTL_D")
	)
	(segment
		(start 86.907116 -68.166234)
		(end 86.907116 -70.78599)
		(width 0.12954)
		(layer "F.Cu")
		(net "LED_PWRGD_CPUPWRGD_GTL")
	)
	(segment
		(start 86.868 -66.824098)
		(end 86.868 -68.127118)
		(width 0.12954)
		(layer "F.Cu")
		(net "LED_PWRGD_CPUPWRGD_GTL")
	)
	(segment
		(start 86.868 -65.573148)
		(end 86.868 -66.824098)
		(width 0.12954)
		(layer "F.Cu")
		(net "LED_PWRGD_CPUPWRGD_GTL")
	)
	(segment
		(start 86.868 -68.127118)
		(end 86.907116 -68.166234)
		(width 0.12954)
		(layer "F.Cu")
		(net "LED_PWRGD_CPUPWRGD_GTL")
	)
	(via
		(at 86.868 -66.824098)
		(size 0.762)
		(drill 0.381)
		(layers "F.Cu" "B.Cu")
		(net "LED_PWRGD_CPUPWRGD_GTL")
	)
	(segment
		(start 112.324896 -79.078836)
		(end 112.324896 -76.490068)
		(width 0.12954)
		(layer "F.Cu")
		(net "LED_P5V_AUX")
	)
	(segment
		(start 112.324896 -75.31862)
		(end 112.33531 -75.308206)
		(width 0.12954)
		(layer "F.Cu")
		(net "LED_P5V_AUX")
	)
	(segment
		(start 112.324896 -76.490068)
		(end 112.324896 -75.31862)
		(width 0.12954)
		(layer "F.Cu")
		(net "LED_P5V_AUX")
	)
	(via
		(at 112.324896 -76.490068)
		(size 0.762)
		(drill 0.381)
		(layers "F.Cu" "B.Cu")
		(net "LED_P5V_AUX")
	)
	(segment
		(start 89.95283 -76.426568)
		(end 89.95283 -79.048102)
		(width 0.12954)
		(layer "F.Cu")
		(net "LED_P5V")
	)
	(segment
		(start 89.95283 -79.048102)
		(end 89.922096 -79.078836)
		(width 0.12954)
		(layer "F.Cu")
		(net "LED_P5V")
	)
	(segment
		(start 89.95283 -75.219814)
		(end 89.95283 -76.426568)
		(width 0.12954)
		(layer "F.Cu")
		(net "LED_P5V")
	)
	(via
		(at 89.95283 -76.426568)
		(size 0.762)
		(drill 0.381)
		(layers "F.Cu" "B.Cu")
		(net "LED_P5V")
	)
	(segment
		(start 86.68893 -76.314808)
		(end 86.68893 -79.04607)
		(width 0.12954)
		(layer "F.Cu")
		(net "LED_P3V3")
	)
	(segment
		(start 86.68893 -75.130406)
		(end 86.68893 -76.314808)
		(width 0.12954)
		(layer "F.Cu")
		(net "LED_P3V3")
	)
	(segment
		(start 86.68893 -79.04607)
		(end 86.721696 -79.078836)
		(width 0.12954)
		(layer "F.Cu")
		(net "LED_P3V3")
	)
	(via
		(at 86.68893 -76.314808)
		(size 0.762)
		(drill 0.381)
		(layers "F.Cu" "B.Cu")
		(net "LED_P3V3")
	)
	(segment
		(start 102.146608 -79.817976)
		(end 102.146608 -80.752188)
		(width 0.12954)
		(layer "F.Cu")
		(net "LED_FM_PCH_SLP_S4_N_D")
	)
	(segment
		(start 101.407468 -79.078836)
		(end 102.146608 -79.817976)
		(width 0.12954)
		(layer "F.Cu")
		(net "LED_FM_PCH_SLP_S4_N_D")
	)
	(segment
		(start 102.146608 -80.752188)
		(end 103.34244 -81.94802)
		(width 0.12954)
		(layer "F.Cu")
		(net "LED_FM_PCH_SLP_S4_N_D")
	)
	(segment
		(start 100.473256 -79.078836)
		(end 101.407468 -79.078836)
		(width 0.12954)
		(layer "F.Cu")
		(net "LED_FM_PCH_SLP_S4_N_D")
	)
	(segment
		(start 103.34244 -81.94802)
		(end 103.34244 -99.845114)
		(width 0.12954)
		(layer "F.Cu")
		(net "LED_FM_PCH_SLP_S4_N_D")
	)
	(segment
		(start 103.34244 -99.845114)
		(end 105.790492 -102.293166)
		(width 0.12954)
		(layer "F.Cu")
		(net "LED_FM_PCH_SLP_S4_N_D")
	)
	(segment
		(start 105.790492 -102.293166)
		(end 107.056428 -102.293166)
		(width 0.12954)
		(layer "F.Cu")
		(net "LED_FM_PCH_SLP_S4_N_D")
	)
	(via
		(at 105.790492 -102.293166)
		(size 0.762)
		(drill 0.381)
		(layers "F.Cu" "B.Cu")
		(net "LED_FM_PCH_SLP_S4_N_D")
	)
	(segment
		(start 99.589082 -75.312016)
		(end 99.589082 -76.49464)
		(width 0.12954)
		(layer "F.Cu")
		(net "LED_FM_PCH_SLP_S4_N")
	)
	(segment
		(start 99.589082 -76.49464)
		(end 99.589082 -77.756766)
		(width 0.12954)
		(layer "F.Cu")
		(net "LED_FM_PCH_SLP_S4_N")
	)
	(segment
		(start 99.589082 -77.756766)
		(end 99.523296 -77.822552)
		(width 0.12954)
		(layer "F.Cu")
		(net "LED_FM_PCH_SLP_S4_N")
	)
	(segment
		(start 99.523296 -77.822552)
		(end 99.523296 -79.078836)
		(width 0.12954)
		(layer "F.Cu")
		(net "LED_FM_PCH_SLP_S4_N")
	)
	(via
		(at 99.589082 -76.49464)
		(size 0.762)
		(drill 0.381)
		(layers "F.Cu" "B.Cu")
		(net "LED_FM_PCH_SLP_S4_N")
	)
	(segment
		(start 100.89261 -91.619578)
		(end 100.89261 -92.904056)
		(width 0.12954)
		(layer "F.Cu")
		(net "LED_FM_PCH_SLP_S3_N_D")
	)
	(segment
		(start 100.1014 -88.453468)
		(end 100.1014 -90.828368)
		(width 0.12954)
		(layer "F.Cu")
		(net "LED_FM_PCH_SLP_S3_N_D")
	)
	(segment
		(start 100.89261 -92.904056)
		(end 101.5111 -93.522546)
		(width 0.12954)
		(layer "F.Cu")
		(net "LED_FM_PCH_SLP_S3_N_D")
	)
	(segment
		(start 97.272856 -79.078836)
		(end 97.272856 -85.624924)
		(width 0.12954)
		(layer "F.Cu")
		(net "LED_FM_PCH_SLP_S3_N_D")
	)
	(segment
		(start 101.5111 -93.522546)
		(end 101.89845 -93.522546)
		(width 0.12954)
		(layer "F.Cu")
		(net "LED_FM_PCH_SLP_S3_N_D")
	)
	(segment
		(start 97.272856 -85.624924)
		(end 100.1014 -88.453468)
		(width 0.12954)
		(layer "F.Cu")
		(net "LED_FM_PCH_SLP_S3_N_D")
	)
	(segment
		(start 100.1014 -90.828368)
		(end 100.89261 -91.619578)
		(width 0.12954)
		(layer "F.Cu")
		(net "LED_FM_PCH_SLP_S3_N_D")
	)
	(via
		(at 100.1014 -90.828368)
		(size 0.762)
		(drill 0.381)
		(layers "F.Cu" "B.Cu")
		(net "LED_FM_PCH_SLP_S3_N_D")
	)
	(segment
		(start 96.293178 -77.673962)
		(end 96.293178 -76.380848)
		(width 0.12954)
		(layer "F.Cu")
		(net "LED_FM_PCH_SLP_S3_N")
	)
	(segment
		(start 96.293178 -75.807824)
		(end 96.294448 -75.806554)
		(width 0.12954)
		(layer "F.Cu")
		(net "LED_FM_PCH_SLP_S3_N")
	)
	(segment
		(start 96.322896 -77.70368)
		(end 96.293178 -77.673962)
		(width 0.12954)
		(layer "F.Cu")
		(net "LED_FM_PCH_SLP_S3_N")
	)
	(segment
		(start 96.294448 -75.806554)
		(end 96.294448 -75.167744)
		(width 0.12954)
		(layer "F.Cu")
		(net "LED_FM_PCH_SLP_S3_N")
	)
	(segment
		(start 96.293178 -76.380848)
		(end 96.293178 -75.807824)
		(width 0.12954)
		(layer "F.Cu")
		(net "LED_FM_PCH_SLP_S3_N")
	)
	(segment
		(start 96.322896 -79.078836)
		(end 96.322896 -77.70368)
		(width 0.12954)
		(layer "F.Cu")
		(net "LED_FM_PCH_SLP_S3_N")
	)
	(via
		(at 96.293178 -76.380848)
		(size 0.762)
		(drill 0.381)
		(layers "F.Cu" "B.Cu")
		(net "LED_FM_PCH_SLP_S3_N")
	)
	(segment
		(start 193.20383 -103.685848)
		(end 192.38722 -103.685848)
		(width 0.12954)
		(layer "F.Cu")
		(net "IRQ_UV_DETECT_R_N")
	)
	(segment
		(start 185.355738 -107.375452)
		(end 185.755788 -106.975402)
		(width 0.12954)
		(layer "F.Cu")
		(net "IRQ_UV_DETECT_R_N")
	)
	(via
		(at 192.38722 -103.685848)
		(size 0.508)
		(drill 0.254)
		(layers "F.Cu" "B.Cu")
		(net "IRQ_UV_DETECT_R_N")
	)
	(via
		(at 185.755788 -106.975402)
		(size 0.4572)
		(drill 0.254)
		(layers "F.Cu" "B.Cu")
		(net "IRQ_UV_DETECT_R_N")
	)
	(segment
		(start 186.154314 -107.373928)
		(end 185.755788 -106.975402)
		(width 0.127)
		(layer "In6.Cu")
		(net "IRQ_UV_DETECT_R_N")
	)
	(segment
		(start 189.057534 -107.373928)
		(end 186.154314 -107.373928)
		(width 0.127)
		(layer "In6.Cu")
		(net "IRQ_UV_DETECT_R_N")
	)
	(segment
		(start 192.38722 -103.685848)
		(end 192.38722 -104.044242)
		(width 0.127)
		(layer "In6.Cu")
		(net "IRQ_UV_DETECT_R_N")
	)
	(segment
		(start 192.38722 -104.044242)
		(end 189.057534 -107.373928)
		(width 0.127)
		(layer "In6.Cu")
		(net "IRQ_UV_DETECT_R_N")
	)
	(segment
		(start 27.35453 -58.999882)
		(end 27.3939 -58.960512)
		(width 0.12954)
		(layer "F.Cu")
		(net "IRQ_SML0_ALERT_R1_N")
	)
	(segment
		(start 20.024852 -58.999882)
		(end 24.52116 -58.999882)
		(width 0.12954)
		(layer "F.Cu")
		(net "IRQ_SML0_ALERT_R1_N")
	)
	(segment
		(start 24.52116 -58.999882)
		(end 27.35453 -58.999882)
		(width 0.12954)
		(layer "F.Cu")
		(net "IRQ_SML0_ALERT_R1_N")
	)
	(via
		(at 24.52116 -58.999882)
		(size 0.762)
		(drill 0.381)
		(layers "F.Cu" "B.Cu")
		(net "IRQ_SML0_ALERT_R1_N")
	)
	(segment
		(start 104.435148 -359.188004)
		(end 104.857804 -359.188004)
		(width 0.12954)
		(layer "F.Cu")
		(net "IRQ_PVCCIN_CPU1_VRHOT_N")
	)
	(segment
		(start 104.997504 -359.048304)
		(end 105.70337 -359.048304)
		(width 0.12954)
		(layer "F.Cu")
		(net "IRQ_PVCCIN_CPU1_VRHOT_N")
	)
	(segment
		(start 104.857804 -359.188004)
		(end 104.997504 -359.048304)
		(width 0.12954)
		(layer "F.Cu")
		(net "IRQ_PVCCIN_CPU1_VRHOT_N")
	)
	(via
		(at 104.435148 -359.188004)
		(size 0.6604)
		(drill 0.254)
		(layers "F.Cu" "B.Cu")
		(net "IRQ_PVCCIN_CPU1_VRHOT_N")
	)
	(segment
		(start 104.317292 -359.070148)
		(end 103.65613 -359.070148)
		(width 0.12954)
		(layer "B.Cu")
		(net "IRQ_PVCCIN_CPU1_VRHOT_N")
	)
	(segment
		(start 104.435148 -359.188004)
		(end 104.317292 -359.070148)
		(width 0.12954)
		(layer "B.Cu")
		(net "IRQ_PVCCIN_CPU1_VRHOT_N")
	)
	(segment
		(start 352.84029 -359.317798)
		(end 352.79711 -359.317798)
		(width 0.12954)
		(layer "F.Cu")
		(net "IRQ_PVCCIN_CPU0_VRHOT_N")
	)
	(segment
		(start 353.643184 -359.048304)
		(end 353.109784 -359.048304)
		(width 0.12954)
		(layer "F.Cu")
		(net "IRQ_PVCCIN_CPU0_VRHOT_N")
	)
	(segment
		(start 352.376994 -359.737914)
		(end 352.150426 -359.831894)
		(width 0.12954)
		(layer "F.Cu")
		(net "IRQ_PVCCIN_CPU0_VRHOT_N")
	)
	(segment
		(start 351.791778 -360.02341)
		(end 351.212658 -360.02341)
		(width 0.12954)
		(layer "F.Cu")
		(net "IRQ_PVCCIN_CPU0_VRHOT_N")
	)
	(segment
		(start 352.150426 -359.831894)
		(end 351.981262 -359.944924)
		(width 0.12954)
		(layer "F.Cu")
		(net "IRQ_PVCCIN_CPU0_VRHOT_N")
	)
	(segment
		(start 352.79711 -359.317798)
		(end 352.566224 -359.548684)
		(width 0.12954)
		(layer "F.Cu")
		(net "IRQ_PVCCIN_CPU0_VRHOT_N")
	)
	(segment
		(start 351.981262 -359.944924)
		(end 351.791778 -360.02341)
		(width 0.12954)
		(layer "F.Cu")
		(net "IRQ_PVCCIN_CPU0_VRHOT_N")
	)
	(segment
		(start 351.212658 -360.02341)
		(end 350.789748 -359.6005)
		(width 0.12954)
		(layer "F.Cu")
		(net "IRQ_PVCCIN_CPU0_VRHOT_N")
	)
	(segment
		(start 350.789748 -359.6005)
		(end 350.789748 -359.53573)
		(width 0.12954)
		(layer "F.Cu")
		(net "IRQ_PVCCIN_CPU0_VRHOT_N")
	)
	(segment
		(start 352.566224 -359.548684)
		(end 352.376994 -359.737914)
		(width 0.12954)
		(layer "F.Cu")
		(net "IRQ_PVCCIN_CPU0_VRHOT_N")
	)
	(segment
		(start 353.109784 -359.048304)
		(end 352.84029 -359.317798)
		(width 0.12954)
		(layer "F.Cu")
		(net "IRQ_PVCCIN_CPU0_VRHOT_N")
	)
	(via
		(at 352.566224 -359.548684)
		(size 0.4064)
		(drill 0.2032)
		(layers "F.Cu" "B.Cu")
		(net "IRQ_PVCCIN_CPU0_VRHOT_N")
	)
	(segment
		(start 35.155632 -128.870964)
		(end 34.993072 -129.033524)
		(width 0.12954)
		(layer "F.Cu")
		(net "IRQ_PVCCFA_CPU1_VRHOT_N")
	)
	(segment
		(start 36.547298 -128.659382)
		(end 36.31184 -128.423924)
		(width 0.12954)
		(layer "F.Cu")
		(net "IRQ_PVCCFA_CPU1_VRHOT_N")
	)
	(segment
		(start 35.602672 -128.423924)
		(end 35.155632 -128.870964)
		(width 0.12954)
		(layer "F.Cu")
		(net "IRQ_PVCCFA_CPU1_VRHOT_N")
	)
	(segment
		(start 36.31184 -128.423924)
		(end 35.602672 -128.423924)
		(width 0.12954)
		(layer "F.Cu")
		(net "IRQ_PVCCFA_CPU1_VRHOT_N")
	)
	(segment
		(start 34.993072 -129.033524)
		(end 34.461196 -129.033524)
		(width 0.12954)
		(layer "F.Cu")
		(net "IRQ_PVCCFA_CPU1_VRHOT_N")
	)
	(via
		(at 35.155632 -128.870964)
		(size 0.508)
		(drill 0.254)
		(layers "F.Cu" "B.Cu")
		(net "IRQ_PVCCFA_CPU1_VRHOT_N")
	)
	(segment
		(start 430.200054 -135.292846)
		(end 430.200054 -135.510778)
		(width 0.12954)
		(layer "F.Cu")
		(net "IRQ_PVCCFA_CPU0_VRHOT_N")
	)
	(segment
		(start 431.927 -134.973568)
		(end 430.519332 -134.973568)
		(width 0.12954)
		(layer "F.Cu")
		(net "IRQ_PVCCFA_CPU0_VRHOT_N")
	)
	(segment
		(start 430.519332 -134.973568)
		(end 430.200054 -135.292846)
		(width 0.12954)
		(layer "F.Cu")
		(net "IRQ_PVCCFA_CPU0_VRHOT_N")
	)
	(segment
		(start 433.759864 -133.140704)
		(end 431.927 -134.973568)
		(width 0.12954)
		(layer "F.Cu")
		(net "IRQ_PVCCFA_CPU0_VRHOT_N")
	)
	(segment
		(start 428.9933 -135.38835)
		(end 430.077626 -135.38835)
		(width 0.12954)
		(layer "F.Cu")
		(net "IRQ_PVCCFA_CPU0_VRHOT_N")
	)
	(segment
		(start 428.105062 -135.814562)
		(end 428.567088 -135.814562)
		(width 0.12954)
		(layer "F.Cu")
		(net "IRQ_PVCCFA_CPU0_VRHOT_N")
	)
	(segment
		(start 430.077626 -135.38835)
		(end 430.200054 -135.510778)
		(width 0.12954)
		(layer "F.Cu")
		(net "IRQ_PVCCFA_CPU0_VRHOT_N")
	)
	(segment
		(start 433.759864 -130.444748)
		(end 433.759864 -133.140704)
		(width 0.12954)
		(layer "F.Cu")
		(net "IRQ_PVCCFA_CPU0_VRHOT_N")
	)
	(segment
		(start 428.567088 -135.814562)
		(end 428.9933 -135.38835)
		(width 0.12954)
		(layer "F.Cu")
		(net "IRQ_PVCCFA_CPU0_VRHOT_N")
	)
	(via
		(at 433.759864 -130.444748)
		(size 0.508)
		(drill 0.254)
		(layers "F.Cu" "B.Cu")
		(net "IRQ_PVCCFA_CPU0_VRHOT_N")
	)
	(segment
		(start 24.483822 -165.427152)
		(end 23.84298 -166.067994)
		(width 0.12954)
		(layer "F.Cu")
		(net "IRQ_PVCCD_CPU1_VRHOT_LVC3_R_N")
	)
	(segment
		(start 22.723094 -167.781224)
		(end 23.257256 -167.781224)
		(width 0.12954)
		(layer "F.Cu")
		(net "IRQ_PVCCD_CPU1_VRHOT_LVC3_R_N")
	)
	(segment
		(start 23.257256 -167.781224)
		(end 23.91664 -167.12184)
		(width 0.12954)
		(layer "F.Cu")
		(net "IRQ_PVCCD_CPU1_VRHOT_LVC3_R_N")
	)
	(segment
		(start 23.84298 -166.83736)
		(end 23.91664 -166.91102)
		(width 0.12954)
		(layer "F.Cu")
		(net "IRQ_PVCCD_CPU1_VRHOT_LVC3_R_N")
	)
	(segment
		(start 23.84298 -166.067994)
		(end 23.84298 -166.83736)
		(width 0.12954)
		(layer "F.Cu")
		(net "IRQ_PVCCD_CPU1_VRHOT_LVC3_R_N")
	)
	(segment
		(start 25.26284 -165.427152)
		(end 24.483822 -165.427152)
		(width 0.12954)
		(layer "F.Cu")
		(net "IRQ_PVCCD_CPU1_VRHOT_LVC3_R_N")
	)
	(segment
		(start 23.91664 -167.12184)
		(end 23.91664 -166.91102)
		(width 0.12954)
		(layer "F.Cu")
		(net "IRQ_PVCCD_CPU1_VRHOT_LVC3_R_N")
	)
	(via
		(at 23.91664 -166.91102)
		(size 0.762)
		(drill 0.381)
		(layers "F.Cu" "B.Cu")
		(net "IRQ_PVCCD_CPU1_VRHOT_LVC3_R_N")
	)
	(segment
		(start 436.701438 -121.632726)
		(end 436.842916 -121.632726)
		(width 0.12954)
		(layer "F.Cu")
		(net "IRQ_PVCCD_CPU0_VRHOT_LVC3_R_N")
	)
	(segment
		(start 435.578758 -122.38863)
		(end 436.204868 -122.129296)
		(width 0.12954)
		(layer "F.Cu")
		(net "IRQ_PVCCD_CPU0_VRHOT_LVC3_R_N")
	)
	(segment
		(start 434.901086 -122.38863)
		(end 435.578758 -122.38863)
		(width 0.12954)
		(layer "F.Cu")
		(net "IRQ_PVCCD_CPU0_VRHOT_LVC3_R_N")
	)
	(segment
		(start 436.204868 -122.129296)
		(end 436.701438 -121.632726)
		(width 0.12954)
		(layer "F.Cu")
		(net "IRQ_PVCCD_CPU0_VRHOT_LVC3_R_N")
	)
	(segment
		(start 185.355738 -114.575336)
		(end 185.755788 -114.975386)
		(width 0.12954)
		(layer "F.Cu")
		(net "IRQ_PSU_ALERT_R_N")
	)
	(segment
		(start 192.98031 -116.804948)
		(end 192.37071 -116.804948)
		(width 0.12954)
		(layer "F.Cu")
		(net "IRQ_PSU_ALERT_R_N")
	)
	(via
		(at 185.755788 -114.975386)
		(size 0.4572)
		(drill 0.254)
		(layers "F.Cu" "B.Cu")
		(net "IRQ_PSU_ALERT_R_N")
	)
	(via
		(at 192.37071 -116.804948)
		(size 0.508)
		(drill 0.254)
		(layers "F.Cu" "B.Cu")
		(net "IRQ_PSU_ALERT_R_N")
	)
	(segment
		(start 185.954924 -114.975386)
		(end 185.755788 -114.975386)
		(width 0.127)
		(layer "In15.Cu")
		(net "IRQ_PSU_ALERT_R_N")
	)
	(segment
		(start 192.37071 -116.804948)
		(end 192.20688 -116.804948)
		(width 0.127)
		(layer "In15.Cu")
		(net "IRQ_PSU_ALERT_R_N")
	)
	(segment
		(start 192.20688 -116.804948)
		(end 190.40348 -115.001548)
		(width 0.127)
		(layer "In15.Cu")
		(net "IRQ_PSU_ALERT_R_N")
	)
	(segment
		(start 186.384946 -115.405408)
		(end 185.954924 -114.975386)
		(width 0.127)
		(layer "In15.Cu")
		(net "IRQ_PSU_ALERT_R_N")
	)
	(segment
		(start 187.409074 -115.001548)
		(end 187.005214 -115.405408)
		(width 0.127)
		(layer "In15.Cu")
		(net "IRQ_PSU_ALERT_R_N")
	)
	(segment
		(start 190.40348 -115.001548)
		(end 187.409074 -115.001548)
		(width 0.127)
		(layer "In15.Cu")
		(net "IRQ_PSU_ALERT_R_N")
	)
	(segment
		(start 187.005214 -115.405408)
		(end 186.384946 -115.405408)
		(width 0.127)
		(layer "In15.Cu")
		(net "IRQ_PSU_ALERT_R_N")
	)
	(segment
		(start 170.555666 -107.775502)
		(end 167.480234 -107.775502)
		(width 0.12954)
		(layer "F.Cu")
		(net "IRQ_HSC_FAULT_R1_N")
	)
	(segment
		(start 167.480234 -107.775502)
		(end 167.18788 -107.483148)
		(width 0.12954)
		(layer "F.Cu")
		(net "IRQ_HSC_FAULT_R1_N")
	)
	(segment
		(start 167.18788 -107.483148)
		(end 166.32428 -107.483148)
		(width 0.12954)
		(layer "F.Cu")
		(net "IRQ_HSC_FAULT_R1_N")
	)
	(segment
		(start 161.23793 -107.426252)
		(end 161.23793 -107.025948)
		(width 0.12954)
		(layer "F.Cu")
		(net "IRQ_HSC_FAULT_R1_N")
	)
	(segment
		(start 162.99688 -107.711748)
		(end 162.74288 -107.457748)
		(width 0.12954)
		(layer "F.Cu")
		(net "IRQ_HSC_FAULT_R1_N")
	)
	(segment
		(start 166.32428 -107.483148)
		(end 166.09568 -107.711748)
		(width 0.12954)
		(layer "F.Cu")
		(net "IRQ_HSC_FAULT_R1_N")
	)
	(segment
		(start 162.74288 -107.457748)
		(end 162.53968 -107.660948)
		(width 0.12954)
		(layer "F.Cu")
		(net "IRQ_HSC_FAULT_R1_N")
	)
	(segment
		(start 170.955716 -108.175552)
		(end 170.555666 -107.775502)
		(width 0.12954)
		(layer "F.Cu")
		(net "IRQ_HSC_FAULT_R1_N")
	)
	(segment
		(start 166.09568 -107.711748)
		(end 162.99688 -107.711748)
		(width 0.12954)
		(layer "F.Cu")
		(net "IRQ_HSC_FAULT_R1_N")
	)
	(segment
		(start 161.472626 -107.660948)
		(end 161.23793 -107.426252)
		(width 0.12954)
		(layer "F.Cu")
		(net "IRQ_HSC_FAULT_R1_N")
	)
	(segment
		(start 162.53968 -107.660948)
		(end 161.472626 -107.660948)
		(width 0.12954)
		(layer "F.Cu")
		(net "IRQ_HSC_FAULT_R1_N")
	)
	(via
		(at 162.74288 -107.457748)
		(size 0.762)
		(drill 0.381)
		(layers "F.Cu" "B.Cu")
		(net "IRQ_HSC_FAULT_R1_N")
	)
	(segment
		(start 160.43783 -107.025948)
		(end 159.82188 -107.025948)
		(width 0.12954)
		(layer "F.Cu")
		(net "IRQ_HSC_FAULT_N")
	)
	(segment
		(start 192.452498 -403.144482)
		(end 193.068448 -403.144482)
		(width 0.12954)
		(layer "F.Cu")
		(net "IRQ_HSC_FAULT_N")
	)
	(segment
		(start 296.48023 -388.349998)
		(end 296.48023 -387.143498)
		(width 0.10668)
		(layer "F.Cu")
		(net "IRQ_HSC_FAULT_N")
	)
	(via
		(at 296.48023 -387.143498)
		(size 0.508)
		(drill 0.254)
		(layers "F.Cu" "B.Cu")
		(net "IRQ_HSC_FAULT_N")
	)
	(via
		(at 193.068448 -403.144482)
		(size 0.508)
		(drill 0.254)
		(layers "F.Cu" "B.Cu")
		(net "IRQ_HSC_FAULT_N")
	)
	(via
		(at 252.045724 -328.942446)
		(size 0.508)
		(drill 0.254)
		(layers "F.Cu" "B.Cu")
		(net "IRQ_HSC_FAULT_N")
	)
	(via
		(at 251.774198 -135.392922)
		(size 0.508)
		(drill 0.254)
		(layers "F.Cu" "B.Cu")
		(net "IRQ_HSC_FAULT_N")
	)
	(via
		(at 154.36088 -139.918948)
		(size 0.508)
		(drill 0.254)
		(layers "F.Cu" "B.Cu")
		(net "IRQ_HSC_FAULT_N")
	)
	(via
		(at 159.82188 -107.025948)
		(size 0.508)
		(drill 0.254)
		(layers "F.Cu" "B.Cu")
		(net "IRQ_HSC_FAULT_N")
	)
	(via
		(at 282.512008 -433.36718)
		(size 0.508)
		(drill 0.254)
		(layers "F.Cu" "B.Cu")
		(net "IRQ_HSC_FAULT_N")
	)
	(segment
		(start 192.452498 -402.528532)
		(end 193.068448 -403.144482)
		(width 0.12954)
		(layer "B.Cu")
		(net "IRQ_HSC_FAULT_N")
	)
	(segment
		(start 192.452498 -401.772882)
		(end 192.452498 -402.528532)
		(width 0.12954)
		(layer "B.Cu")
		(net "IRQ_HSC_FAULT_N")
	)
	(segment
		(start 244.25656 -336.73161)
		(end 252.045724 -328.942446)
		(width 0.127)
		(layer "In2.Cu")
		(net "IRQ_HSC_FAULT_N")
	)
	(segment
		(start 295.627552 -386.29082)
		(end 286.30372 -386.29082)
		(width 0.127)
		(layer "In2.Cu")
		(net "IRQ_HSC_FAULT_N")
	)
	(segment
		(start 244.25656 -366.43818)
		(end 244.25656 -336.73161)
		(width 0.127)
		(layer "In2.Cu")
		(net "IRQ_HSC_FAULT_N")
	)
	(segment
		(start 267.18006 -389.36168)
		(end 244.25656 -366.43818)
		(width 0.127)
		(layer "In2.Cu")
		(net "IRQ_HSC_FAULT_N")
	)
	(segment
		(start 283.23286 -389.36168)
		(end 267.18006 -389.36168)
		(width 0.127)
		(layer "In2.Cu")
		(net "IRQ_HSC_FAULT_N")
	)
	(segment
		(start 296.48023 -387.143498)
		(end 295.627552 -386.29082)
		(width 0.127)
		(layer "In2.Cu")
		(net "IRQ_HSC_FAULT_N")
	)
	(segment
		(start 286.30372 -386.29082)
		(end 283.23286 -389.36168)
		(width 0.127)
		(layer "In2.Cu")
		(net "IRQ_HSC_FAULT_N")
	)
	(segment
		(start 282.22702 -425.10964)
		(end 282.22702 -418.7444)
		(width 0.127)
		(layer "In6.Cu")
		(net "IRQ_HSC_FAULT_N")
	)
	(segment
		(start 296.48023 -390.62533)
		(end 296.48023 -387.143498)
		(width 0.127)
		(layer "In6.Cu")
		(net "IRQ_HSC_FAULT_N")
	)
	(segment
		(start 285.50108 -415.47034)
		(end 285.50108 -413.822896)
		(width 0.127)
		(layer "In6.Cu")
		(net "IRQ_HSC_FAULT_N")
	)
	(segment
		(start 282.512008 -433.36718)
		(end 282.512008 -425.394628)
		(width 0.127)
		(layer "In6.Cu")
		(net "IRQ_HSC_FAULT_N")
	)
	(segment
		(start 297.053508 -404.326598)
		(end 297.053508 -399.610072)
		(width 0.127)
		(layer "In6.Cu")
		(net "IRQ_HSC_FAULT_N")
	)
	(segment
		(start 297.053508 -399.610072)
		(end 298.620688 -398.042892)
		(width 0.127)
		(layer "In6.Cu")
		(net "IRQ_HSC_FAULT_N")
	)
	(segment
		(start 291.19322 -408.68092)
		(end 292.38448 -408.68092)
		(width 0.127)
		(layer "In6.Cu")
		(net "IRQ_HSC_FAULT_N")
	)
	(segment
		(start 282.22702 -418.7444)
		(end 285.50108 -415.47034)
		(width 0.127)
		(layer "In6.Cu")
		(net "IRQ_HSC_FAULT_N")
	)
	(segment
		(start 289.091878 -410.232098)
		(end 289.642042 -410.232098)
		(width 0.127)
		(layer "In6.Cu")
		(net "IRQ_HSC_FAULT_N")
	)
	(segment
		(start 285.50108 -413.822896)
		(end 289.091878 -410.232098)
		(width 0.127)
		(layer "In6.Cu")
		(net "IRQ_HSC_FAULT_N")
	)
	(segment
		(start 298.620688 -392.765788)
		(end 296.48023 -390.62533)
		(width 0.127)
		(layer "In6.Cu")
		(net "IRQ_HSC_FAULT_N")
	)
	(segment
		(start 296.262806 -405.1173)
		(end 297.053508 -404.326598)
		(width 0.127)
		(layer "In6.Cu")
		(net "IRQ_HSC_FAULT_N")
	)
	(segment
		(start 282.512008 -425.394628)
		(end 282.22702 -425.10964)
		(width 0.127)
		(layer "In6.Cu")
		(net "IRQ_HSC_FAULT_N")
	)
	(segment
		(start 295.9481 -405.1173)
		(end 296.262806 -405.1173)
		(width 0.127)
		(layer "In6.Cu")
		(net "IRQ_HSC_FAULT_N")
	)
	(segment
		(start 289.642042 -410.232098)
		(end 291.19322 -408.68092)
		(width 0.127)
		(layer "In6.Cu")
		(net "IRQ_HSC_FAULT_N")
	)
	(segment
		(start 298.620688 -398.042892)
		(end 298.620688 -392.765788)
		(width 0.127)
		(layer "In6.Cu")
		(net "IRQ_HSC_FAULT_N")
	)
	(segment
		(start 292.38448 -408.68092)
		(end 295.9481 -405.1173)
		(width 0.127)
		(layer "In6.Cu")
		(net "IRQ_HSC_FAULT_N")
	)
	(segment
		(start 251.774198 -135.584438)
		(end 249.601736 -137.7569)
		(width 0.127)
		(layer "In11.Cu")
		(net "IRQ_HSC_FAULT_N")
	)
	(segment
		(start 153.97988 -127.980948)
		(end 153.97988 -120.868948)
		(width 0.127)
		(layer "In11.Cu")
		(net "IRQ_HSC_FAULT_N")
	)
	(segment
		(start 152.96388 -119.852948)
		(end 152.96388 -118.709948)
		(width 0.127)
		(layer "In11.Cu")
		(net "IRQ_HSC_FAULT_N")
	)
	(segment
		(start 159.05988 -107.787948)
		(end 159.82188 -107.025948)
		(width 0.127)
		(layer "In11.Cu")
		(net "IRQ_HSC_FAULT_N")
	)
	(segment
		(start 154.74188 -111.978948)
		(end 157.02788 -111.978948)
		(width 0.127)
		(layer "In11.Cu")
		(net "IRQ_HSC_FAULT_N")
	)
	(segment
		(start 152.96388 -118.709948)
		(end 154.32278 -117.351048)
		(width 0.127)
		(layer "In11.Cu")
		(net "IRQ_HSC_FAULT_N")
	)
	(segment
		(start 154.36088 -139.918948)
		(end 152.83688 -138.394948)
		(width 0.127)
		(layer "In11.Cu")
		(net "IRQ_HSC_FAULT_N")
	)
	(segment
		(start 154.32278 -112.398048)
		(end 154.74188 -111.978948)
		(width 0.127)
		(layer "In11.Cu")
		(net "IRQ_HSC_FAULT_N")
	)
	(segment
		(start 252.045724 -327.189592)
		(end 252.045724 -328.942446)
		(width 0.127)
		(layer "In11.Cu")
		(net "IRQ_HSC_FAULT_N")
	)
	(segment
		(start 251.245624 -326.389492)
		(end 252.045724 -327.189592)
		(width 0.127)
		(layer "In11.Cu")
		(net "IRQ_HSC_FAULT_N")
	)
	(segment
		(start 251.245624 -199.480932)
		(end 251.245624 -326.389492)
		(width 0.127)
		(layer "In11.Cu")
		(net "IRQ_HSC_FAULT_N")
	)
	(segment
		(start 249.601736 -137.7569)
		(end 249.601736 -197.837044)
		(width 0.127)
		(layer "In11.Cu")
		(net "IRQ_HSC_FAULT_N")
	)
	(segment
		(start 153.97988 -120.868948)
		(end 152.96388 -119.852948)
		(width 0.127)
		(layer "In11.Cu")
		(net "IRQ_HSC_FAULT_N")
	)
	(segment
		(start 152.83688 -138.394948)
		(end 152.83688 -129.123948)
		(width 0.127)
		(layer "In11.Cu")
		(net "IRQ_HSC_FAULT_N")
	)
	(segment
		(start 251.774198 -135.392922)
		(end 251.774198 -135.584438)
		(width 0.127)
		(layer "In11.Cu")
		(net "IRQ_HSC_FAULT_N")
	)
	(segment
		(start 157.78988 -108.041948)
		(end 158.04388 -107.787948)
		(width 0.127)
		(layer "In11.Cu")
		(net "IRQ_HSC_FAULT_N")
	)
	(segment
		(start 158.04388 -107.787948)
		(end 159.05988 -107.787948)
		(width 0.127)
		(layer "In11.Cu")
		(net "IRQ_HSC_FAULT_N")
	)
	(segment
		(start 249.601736 -197.837044)
		(end 251.245624 -199.480932)
		(width 0.127)
		(layer "In11.Cu")
		(net "IRQ_HSC_FAULT_N")
	)
	(segment
		(start 157.02788 -111.978948)
		(end 157.78988 -111.216948)
		(width 0.127)
		(layer "In11.Cu")
		(net "IRQ_HSC_FAULT_N")
	)
	(segment
		(start 154.32278 -117.351048)
		(end 154.32278 -112.398048)
		(width 0.127)
		(layer "In11.Cu")
		(net "IRQ_HSC_FAULT_N")
	)
	(segment
		(start 157.78988 -111.216948)
		(end 157.78988 -108.041948)
		(width 0.127)
		(layer "In11.Cu")
		(net "IRQ_HSC_FAULT_N")
	)
	(segment
		(start 152.83688 -129.123948)
		(end 153.97988 -127.980948)
		(width 0.127)
		(layer "In11.Cu")
		(net "IRQ_HSC_FAULT_N")
	)
	(segment
		(start 185.31586 -400.50212)
		(end 190.65748 -400.50212)
		(width 0.127)
		(layer "In15.Cu")
		(net "IRQ_HSC_FAULT_N")
	)
	(segment
		(start 280.617168 -438.403492)
		(end 280.31186 -438.7088)
		(width 0.127)
		(layer "In15.Cu")
		(net "IRQ_HSC_FAULT_N")
	)
	(segment
		(start 185.0263 -414.16986)
		(end 185.0263 -409.31846)
		(width 0.127)
		(layer "In15.Cu")
		(net "IRQ_HSC_FAULT_N")
	)
	(segment
		(start 184.74436 -403.062186)
		(end 184.74436 -402.330666)
		(width 0.127)
		(layer "In15.Cu")
		(net "IRQ_HSC_FAULT_N")
	)
	(segment
		(start 187.60821 -142.166848)
		(end 156.10078 -142.166848)
		(width 0.127)
		(layer "In15.Cu")
		(net "IRQ_HSC_FAULT_N")
	)
	(segment
		(start 277.12924 -437.44896)
		(end 198.47052 -437.44896)
		(width 0.127)
		(layer "In15.Cu")
		(net "IRQ_HSC_FAULT_N")
	)
	(segment
		(start 184.78246 -404.54707)
		(end 184.78246 -403.997922)
		(width 0.127)
		(layer "In15.Cu")
		(net "IRQ_HSC_FAULT_N")
	)
	(segment
		(start 184.87136 -401.536662)
		(end 184.87136 -400.94662)
		(width 0.127)
		(layer "In15.Cu")
		(net "IRQ_HSC_FAULT_N")
	)
	(segment
		(start 251.774198 -135.780526)
		(end 247.865392 -139.689332)
		(width 0.127)
		(layer "In15.Cu")
		(net "IRQ_HSC_FAULT_N")
	)
	(segment
		(start 184.99201 -401.657312)
		(end 184.87136 -401.536662)
		(width 0.127)
		(layer "In15.Cu")
		(net "IRQ_HSC_FAULT_N")
	)
	(segment
		(start 278.38908 -438.7088)
		(end 277.12924 -437.44896)
		(width 0.127)
		(layer "In15.Cu")
		(net "IRQ_HSC_FAULT_N")
	)
	(segment
		(start 280.31186 -438.7088)
		(end 278.38908 -438.7088)
		(width 0.127)
		(layer "In15.Cu")
		(net "IRQ_HSC_FAULT_N")
	)
	(segment
		(start 198.47052 -437.44896)
		(end 196.70776 -435.6862)
		(width 0.127)
		(layer "In15.Cu")
		(net "IRQ_HSC_FAULT_N")
	)
	(segment
		(start 184.99201 -403.788372)
		(end 184.99201 -403.309836)
		(width 0.127)
		(layer "In15.Cu")
		(net "IRQ_HSC_FAULT_N")
	)
	(segment
		(start 212.07476 -142.034514)
		(end 187.740544 -142.034514)
		(width 0.127)
		(layer "In15.Cu")
		(net "IRQ_HSC_FAULT_N")
	)
	(segment
		(start 251.774198 -135.392922)
		(end 251.774198 -135.780526)
		(width 0.127)
		(layer "In15.Cu")
		(net "IRQ_HSC_FAULT_N")
	)
	(segment
		(start 191.15532 -400.99996)
		(end 191.15532 -401.231354)
		(width 0.127)
		(layer "In15.Cu")
		(net "IRQ_HSC_FAULT_N")
	)
	(segment
		(start 280.617168 -435.26202)
		(end 280.617168 -438.403492)
		(width 0.127)
		(layer "In15.Cu")
		(net "IRQ_HSC_FAULT_N")
	)
	(segment
		(start 214.419942 -139.689332)
		(end 212.07476 -142.034514)
		(width 0.127)
		(layer "In15.Cu")
		(net "IRQ_HSC_FAULT_N")
	)
	(segment
		(start 184.99201 -402.083016)
		(end 184.99201 -401.657312)
		(width 0.127)
		(layer "In15.Cu")
		(net "IRQ_HSC_FAULT_N")
	)
	(segment
		(start 184.99201 -403.309836)
		(end 184.74436 -403.062186)
		(width 0.127)
		(layer "In15.Cu")
		(net "IRQ_HSC_FAULT_N")
	)
	(segment
		(start 184.41416 -408.70632)
		(end 184.41416 -407.00706)
		(width 0.127)
		(layer "In15.Cu")
		(net "IRQ_HSC_FAULT_N")
	)
	(segment
		(start 191.15532 -401.231354)
		(end 193.068448 -403.144482)
		(width 0.127)
		(layer "In15.Cu")
		(net "IRQ_HSC_FAULT_N")
	)
	(segment
		(start 184.74436 -402.330666)
		(end 184.99201 -402.083016)
		(width 0.127)
		(layer "In15.Cu")
		(net "IRQ_HSC_FAULT_N")
	)
	(segment
		(start 184.41416 -407.00706)
		(end 184.897268 -406.523952)
		(width 0.127)
		(layer "In15.Cu")
		(net "IRQ_HSC_FAULT_N")
	)
	(segment
		(start 196.70776 -425.85132)
		(end 185.0263 -414.16986)
		(width 0.127)
		(layer "In15.Cu")
		(net "IRQ_HSC_FAULT_N")
	)
	(segment
		(start 154.36088 -140.426948)
		(end 154.36088 -139.918948)
		(width 0.127)
		(layer "In15.Cu")
		(net "IRQ_HSC_FAULT_N")
	)
	(segment
		(start 196.70776 -435.6862)
		(end 196.70776 -425.85132)
		(width 0.127)
		(layer "In15.Cu")
		(net "IRQ_HSC_FAULT_N")
	)
	(segment
		(start 156.10078 -142.166848)
		(end 154.36088 -140.426948)
		(width 0.127)
		(layer "In15.Cu")
		(net "IRQ_HSC_FAULT_N")
	)
	(segment
		(start 187.740544 -142.034514)
		(end 187.60821 -142.166848)
		(width 0.127)
		(layer "In15.Cu")
		(net "IRQ_HSC_FAULT_N")
	)
	(segment
		(start 282.512008 -433.36718)
		(end 280.617168 -435.26202)
		(width 0.127)
		(layer "In15.Cu")
		(net "IRQ_HSC_FAULT_N")
	)
	(segment
		(start 185.0263 -409.31846)
		(end 184.41416 -408.70632)
		(width 0.127)
		(layer "In15.Cu")
		(net "IRQ_HSC_FAULT_N")
	)
	(segment
		(start 184.87136 -400.94662)
		(end 185.31586 -400.50212)
		(width 0.127)
		(layer "In15.Cu")
		(net "IRQ_HSC_FAULT_N")
	)
	(segment
		(start 184.897268 -406.523952)
		(end 184.897268 -404.661878)
		(width 0.127)
		(layer "In15.Cu")
		(net "IRQ_HSC_FAULT_N")
	)
	(segment
		(start 184.78246 -403.997922)
		(end 184.99201 -403.788372)
		(width 0.127)
		(layer "In15.Cu")
		(net "IRQ_HSC_FAULT_N")
	)
	(segment
		(start 247.865392 -139.689332)
		(end 214.419942 -139.689332)
		(width 0.127)
		(layer "In15.Cu")
		(net "IRQ_HSC_FAULT_N")
	)
	(segment
		(start 190.65748 -400.50212)
		(end 191.15532 -400.99996)
		(width 0.127)
		(layer "In15.Cu")
		(net "IRQ_HSC_FAULT_N")
	)
	(segment
		(start 184.897268 -404.661878)
		(end 184.78246 -404.54707)
		(width 0.127)
		(layer "In15.Cu")
		(net "IRQ_HSC_FAULT_N")
	)
	(segment
		(start 368.58702 -395.427708)
		(end 368.03076 -395.983968)
		(width 0.12954)
		(layer "F.Cu")
		(net "I3C_BMC_SWB_BUF_R_SDA")
	)
	(segment
		(start 364.744 -396.413228)
		(end 364.744 -398.008348)
		(width 0.12954)
		(layer "F.Cu")
		(net "I3C_BMC_SWB_BUF_R_SDA")
	)
	(segment
		(start 369.836192 -396.105888)
		(end 369.692682 -396.249398)
		(width 0.12954)
		(layer "F.Cu")
		(net "I3C_BMC_SWB_BUF_R_SDA")
	)
	(segment
		(start 369.692682 -396.249398)
		(end 369.692682 -395.65199)
		(width 0.12954)
		(layer "F.Cu")
		(net "I3C_BMC_SWB_BUF_R_SDA")
	)
	(segment
		(start 370.23929 -396.105888)
		(end 369.836192 -396.105888)
		(width 0.12954)
		(layer "F.Cu")
		(net "I3C_BMC_SWB_BUF_R_SDA")
	)
	(segment
		(start 368.03076 -395.983968)
		(end 365.17326 -395.983968)
		(width 0.12954)
		(layer "F.Cu")
		(net "I3C_BMC_SWB_BUF_R_SDA")
	)
	(segment
		(start 357.324152 -396.707868)
		(end 358.135682 -397.519398)
		(width 0.12954)
		(layer "F.Cu")
		(net "I3C_BMC_SWB_BUF_R_SDA")
	)
	(segment
		(start 369.692682 -395.65199)
		(end 369.4684 -395.427708)
		(width 0.12954)
		(layer "F.Cu")
		(net "I3C_BMC_SWB_BUF_R_SDA")
	)
	(segment
		(start 355.78161 -397.519398)
		(end 356.59314 -396.707868)
		(width 0.12954)
		(layer "F.Cu")
		(net "I3C_BMC_SWB_BUF_R_SDA")
	)
	(segment
		(start 356.59314 -396.707868)
		(end 357.324152 -396.707868)
		(width 0.12954)
		(layer "F.Cu")
		(net "I3C_BMC_SWB_BUF_R_SDA")
	)
	(segment
		(start 364.744 -398.008348)
		(end 365.020606 -398.284954)
		(width 0.12954)
		(layer "F.Cu")
		(net "I3C_BMC_SWB_BUF_R_SDA")
	)
	(segment
		(start 365.020606 -398.284954)
		(end 365.788448 -398.284954)
		(width 0.12954)
		(layer "F.Cu")
		(net "I3C_BMC_SWB_BUF_R_SDA")
	)
	(segment
		(start 369.4684 -395.427708)
		(end 368.58702 -395.427708)
		(width 0.12954)
		(layer "F.Cu")
		(net "I3C_BMC_SWB_BUF_R_SDA")
	)
	(segment
		(start 355.087682 -397.519398)
		(end 355.78161 -397.519398)
		(width 0.12954)
		(layer "F.Cu")
		(net "I3C_BMC_SWB_BUF_R_SDA")
	)
	(segment
		(start 365.17326 -395.983968)
		(end 364.744 -396.413228)
		(width 0.12954)
		(layer "F.Cu")
		(net "I3C_BMC_SWB_BUF_R_SDA")
	)
	(segment
		(start 370.3828 -396.249398)
		(end 370.23929 -396.105888)
		(width 0.12954)
		(layer "F.Cu")
		(net "I3C_BMC_SWB_BUF_R_SDA")
	)
	(via
		(at 355.78161 -397.519398)
		(size 0.508)
		(drill 0.254)
		(layers "F.Cu" "B.Cu")
		(net "I3C_BMC_SWB_BUF_R_SDA")
	)
	(via
		(at 370.3828 -396.249398)
		(size 0.508)
		(drill 0.254)
		(layers "F.Cu" "B.Cu")
		(net "I3C_BMC_SWB_BUF_R_SDA")
	)
	(segment
		(start 367.16462 -398.142968)
		(end 356.25024 -398.142968)
		(width 0.127)
		(layer "In4.Cu")
		(net "I3C_BMC_SWB_BUF_R_SDA")
	)
	(segment
		(start 368.99596 -396.311628)
		(end 367.16462 -398.142968)
		(width 0.127)
		(layer "In4.Cu")
		(net "I3C_BMC_SWB_BUF_R_SDA")
	)
	(segment
		(start 370.32057 -396.311628)
		(end 368.99596 -396.311628)
		(width 0.127)
		(layer "In4.Cu")
		(net "I3C_BMC_SWB_BUF_R_SDA")
	)
	(segment
		(start 355.78161 -397.674338)
		(end 355.78161 -397.519398)
		(width 0.127)
		(layer "In4.Cu")
		(net "I3C_BMC_SWB_BUF_R_SDA")
	)
	(segment
		(start 370.3828 -396.249398)
		(end 370.32057 -396.311628)
		(width 0.127)
		(layer "In4.Cu")
		(net "I3C_BMC_SWB_BUF_R_SDA")
	)
	(segment
		(start 356.25024 -398.142968)
		(end 355.78161 -397.674338)
		(width 0.127)
		(layer "In4.Cu")
		(net "I3C_BMC_SWB_BUF_R_SDA")
	)
	(segment
		(start 355.77653 -398.789398)
		(end 356.57536 -399.588228)
		(width 0.12954)
		(layer "F.Cu")
		(net "I3C_BMC_SWB_BUF_R_SCL")
	)
	(segment
		(start 359.777792 -398.284954)
		(end 361.323636 -398.284954)
		(width 0.12954)
		(layer "F.Cu")
		(net "I3C_BMC_SWB_BUF_R_SCL")
	)
	(segment
		(start 356.57536 -399.588228)
		(end 357.336852 -399.588228)
		(width 0.12954)
		(layer "F.Cu")
		(net "I3C_BMC_SWB_BUF_R_SCL")
	)
	(segment
		(start 359.169208 -398.559274)
		(end 358.939084 -398.789398)
		(width 0.12954)
		(layer "F.Cu")
		(net "I3C_BMC_SWB_BUF_R_SCL")
	)
	(segment
		(start 355.087682 -398.789398)
		(end 355.77653 -398.789398)
		(width 0.12954)
		(layer "F.Cu")
		(net "I3C_BMC_SWB_BUF_R_SCL")
	)
	(segment
		(start 369.692682 -397.519398)
		(end 370.3828 -397.519398)
		(width 0.12954)
		(layer "F.Cu")
		(net "I3C_BMC_SWB_BUF_R_SCL")
	)
	(segment
		(start 359.503472 -398.559274)
		(end 359.169208 -398.559274)
		(width 0.12954)
		(layer "F.Cu")
		(net "I3C_BMC_SWB_BUF_R_SCL")
	)
	(segment
		(start 359.503472 -398.559274)
		(end 359.777792 -398.284954)
		(width 0.12954)
		(layer "F.Cu")
		(net "I3C_BMC_SWB_BUF_R_SCL")
	)
	(segment
		(start 358.939084 -398.789398)
		(end 358.135682 -398.789398)
		(width 0.12954)
		(layer "F.Cu")
		(net "I3C_BMC_SWB_BUF_R_SCL")
	)
	(segment
		(start 357.336852 -399.588228)
		(end 358.135682 -398.789398)
		(width 0.12954)
		(layer "F.Cu")
		(net "I3C_BMC_SWB_BUF_R_SCL")
	)
	(via
		(at 355.77653 -398.789398)
		(size 0.508)
		(drill 0.254)
		(layers "F.Cu" "B.Cu")
		(net "I3C_BMC_SWB_BUF_R_SCL")
	)
	(via
		(at 370.3828 -397.519398)
		(size 0.508)
		(drill 0.254)
		(layers "F.Cu" "B.Cu")
		(net "I3C_BMC_SWB_BUF_R_SCL")
	)
	(via
		(at 359.503472 -398.559274)
		(size 0.762)
		(drill 0.381)
		(layers "F.Cu" "B.Cu")
		(net "I3C_BMC_SWB_BUF_R_SCL")
	)
	(segment
		(start 355.77653 -398.982438)
		(end 355.77653 -398.789398)
		(width 0.127)
		(layer "In4.Cu")
		(net "I3C_BMC_SWB_BUF_R_SCL")
	)
	(segment
		(start 370.36121 -397.540988)
		(end 369.28806 -397.540988)
		(width 0.127)
		(layer "In4.Cu")
		(net "I3C_BMC_SWB_BUF_R_SCL")
	)
	(segment
		(start 356.2604 -399.466308)
		(end 355.77653 -398.982438)
		(width 0.127)
		(layer "In4.Cu")
		(net "I3C_BMC_SWB_BUF_R_SCL")
	)
	(segment
		(start 367.36274 -399.466308)
		(end 356.2604 -399.466308)
		(width 0.127)
		(layer "In4.Cu")
		(net "I3C_BMC_SWB_BUF_R_SCL")
	)
	(segment
		(start 369.28806 -397.540988)
		(end 367.36274 -399.466308)
		(width 0.127)
		(layer "In4.Cu")
		(net "I3C_BMC_SWB_BUF_R_SCL")
	)
	(segment
		(start 370.3828 -397.519398)
		(end 370.36121 -397.540988)
		(width 0.127)
		(layer "In4.Cu")
		(net "I3C_BMC_SWB_BUF_R_SCL")
	)
	(segment
		(start 128.001522 -128.986026)
		(end 127.470662 -128.986026)
		(width 0.12954)
		(layer "F.Cu")
		(net "SMB_BMC_SWB_SDA_R4")
	)
	(segment
		(start 127.470662 -128.986026)
		(end 126.599442 -129.857246)
		(width 0.12954)
		(layer "F.Cu")
		(net "SMB_BMC_SWB_SDA_R4")
	)
	(segment
		(start 125.043438 -129.857246)
		(end 124.504196 -130.396488)
		(width 0.12954)
		(layer "F.Cu")
		(net "SMB_BMC_SWB_SDA_R4")
	)
	(segment
		(start 124.504196 -130.396488)
		(end 123.708668 -130.396488)
		(width 0.12954)
		(layer "F.Cu")
		(net "SMB_BMC_SWB_SDA_R4")
	)
	(segment
		(start 126.599442 -129.857246)
		(end 125.043438 -129.857246)
		(width 0.12954)
		(layer "F.Cu")
		(net "SMB_BMC_SWB_SDA_R4")
	)
	(via
		(at 126.599442 -129.857246)
		(size 0.762)
		(drill 0.381)
		(layers "F.Cu" "B.Cu")
		(net "SMB_BMC_SWB_SDA_R4")
	)
	(segment
		(start 245.11508 -168.214548)
		(end 245.36908 -168.468548)
		(width 0.12954)
		(layer "F.Cu")
		(net "SMB_BMC_SWB_SDA")
	)
	(segment
		(start 178.08448 -158.166816)
		(end 178.08448 -157.788356)
		(width 0.12954)
		(layer "F.Cu")
		(net "SMB_BMC_SWB_SDA")
	)
	(segment
		(start 178.21402 -160.208976)
		(end 178.874928 -160.208976)
		(width 0.12954)
		(layer "F.Cu")
		(net "SMB_BMC_SWB_SDA")
	)
	(segment
		(start 244.78488 -168.214548)
		(end 245.11508 -168.214548)
		(width 0.12954)
		(layer "F.Cu")
		(net "SMB_BMC_SWB_SDA")
	)
	(segment
		(start 179.004468 -159.700976)
		(end 178.874928 -159.571436)
		(width 0.12954)
		(layer "F.Cu")
		(net "SMB_BMC_SWB_SDA")
	)
	(segment
		(start 178.08448 -156.200348)
		(end 173.63948 -151.755348)
		(width 0.12954)
		(layer "F.Cu")
		(net "SMB_BMC_SWB_SDA")
	)
	(segment
		(start 178.08448 -159.441896)
		(end 178.08448 -159.063436)
		(width 0.12954)
		(layer "F.Cu")
		(net "SMB_BMC_SWB_SDA")
	)
	(segment
		(start 204.85608 -170.703748)
		(end 203.15428 -169.001948)
		(width 0.12954)
		(layer "F.Cu")
		(net "SMB_BMC_SWB_SDA")
	)
	(segment
		(start 173.63948 -151.755348)
		(end 146.56308 -151.755348)
		(width 0.12954)
		(layer "F.Cu")
		(net "SMB_BMC_SWB_SDA")
	)
	(segment
		(start 178.21402 -158.933896)
		(end 178.874928 -158.933896)
		(width 0.12954)
		(layer "F.Cu")
		(net "SMB_BMC_SWB_SDA")
	)
	(segment
		(start 178.08448 -157.788356)
		(end 178.21402 -157.658816)
		(width 0.12954)
		(layer "F.Cu")
		(net "SMB_BMC_SWB_SDA")
	)
	(segment
		(start 178.874928 -158.933896)
		(end 179.004468 -158.804356)
		(width 0.12954)
		(layer "F.Cu")
		(net "SMB_BMC_SWB_SDA")
	)
	(segment
		(start 178.21402 -159.571436)
		(end 178.08448 -159.441896)
		(width 0.12954)
		(layer "F.Cu")
		(net "SMB_BMC_SWB_SDA")
	)
	(segment
		(start 179.004468 -158.804356)
		(end 179.004468 -158.425896)
		(width 0.12954)
		(layer "F.Cu")
		(net "SMB_BMC_SWB_SDA")
	)
	(segment
		(start 133.15188 -126.710948)
		(end 132.948934 -126.508002)
		(width 0.12954)
		(layer "F.Cu")
		(net "SMB_BMC_SWB_SDA")
	)
	(segment
		(start 179.004468 -157.150816)
		(end 178.874928 -157.021276)
		(width 0.12954)
		(layer "F.Cu")
		(net "SMB_BMC_SWB_SDA")
	)
	(segment
		(start 178.874928 -160.208976)
		(end 179.004468 -160.079436)
		(width 0.12954)
		(layer "F.Cu")
		(net "SMB_BMC_SWB_SDA")
	)
	(segment
		(start 245.36908 -169.230548)
		(end 243.89588 -170.703748)
		(width 0.12954)
		(layer "F.Cu")
		(net "SMB_BMC_SWB_SDA")
	)
	(segment
		(start 179.004468 -157.529276)
		(end 179.004468 -157.150816)
		(width 0.12954)
		(layer "F.Cu")
		(net "SMB_BMC_SWB_SDA")
	)
	(segment
		(start 178.21402 -157.021276)
		(end 178.08448 -156.891736)
		(width 0.12954)
		(layer "F.Cu")
		(net "SMB_BMC_SWB_SDA")
	)
	(segment
		(start 178.08448 -160.338516)
		(end 178.21402 -160.208976)
		(width 0.12954)
		(layer "F.Cu")
		(net "SMB_BMC_SWB_SDA")
	)
	(segment
		(start 142.88008 -128.692148)
		(end 144.40408 -128.692148)
		(width 0.12954)
		(layer "F.Cu")
		(net "SMB_BMC_SWB_SDA")
	)
	(segment
		(start 132.948934 -126.508002)
		(end 131.677918 -126.508002)
		(width 0.12954)
		(layer "F.Cu")
		(net "SMB_BMC_SWB_SDA")
	)
	(segment
		(start 146.56308 -151.755348)
		(end 142.60068 -147.792948)
		(width 0.12954)
		(layer "F.Cu")
		(net "SMB_BMC_SWB_SDA")
	)
	(segment
		(start 163.50615 -418.114226)
		(end 163.50615 -417.440618)
		(width 0.12954)
		(layer "F.Cu")
		(net "SMB_BMC_SWB_SDA")
	)
	(segment
		(start 142.60068 -144.135348)
		(end 141.25448 -142.789148)
		(width 0.12954)
		(layer "F.Cu")
		(net "SMB_BMC_SWB_SDA")
	)
	(segment
		(start 178.21402 -157.658816)
		(end 178.874928 -157.658816)
		(width 0.12954)
		(layer "F.Cu")
		(net "SMB_BMC_SWB_SDA")
	)
	(segment
		(start 178.08448 -164.683948)
		(end 178.08448 -160.338516)
		(width 0.12954)
		(layer "F.Cu")
		(net "SMB_BMC_SWB_SDA")
	)
	(segment
		(start 142.60068 -147.792948)
		(end 142.60068 -144.135348)
		(width 0.12954)
		(layer "F.Cu")
		(net "SMB_BMC_SWB_SDA")
	)
	(segment
		(start 245.36908 -168.468548)
		(end 245.36908 -169.230548)
		(width 0.12954)
		(layer "F.Cu")
		(net "SMB_BMC_SWB_SDA")
	)
	(segment
		(start 131.677918 -126.508002)
		(end 131.066794 -127.119126)
		(width 0.12954)
		(layer "F.Cu")
		(net "SMB_BMC_SWB_SDA")
	)
	(segment
		(start 178.874928 -158.296356)
		(end 178.21402 -158.296356)
		(width 0.12954)
		(layer "F.Cu")
		(net "SMB_BMC_SWB_SDA")
	)
	(segment
		(start 203.15428 -169.001948)
		(end 182.40248 -169.001948)
		(width 0.12954)
		(layer "F.Cu")
		(net "SMB_BMC_SWB_SDA")
	)
	(segment
		(start 178.08448 -159.063436)
		(end 178.21402 -158.933896)
		(width 0.12954)
		(layer "F.Cu")
		(net "SMB_BMC_SWB_SDA")
	)
	(segment
		(start 141.25448 -142.789148)
		(end 141.25448 -130.317748)
		(width 0.12954)
		(layer "F.Cu")
		(net "SMB_BMC_SWB_SDA")
	)
	(segment
		(start 179.004468 -158.425896)
		(end 178.874928 -158.296356)
		(width 0.12954)
		(layer "F.Cu")
		(net "SMB_BMC_SWB_SDA")
	)
	(segment
		(start 178.874928 -157.658816)
		(end 179.004468 -157.529276)
		(width 0.12954)
		(layer "F.Cu")
		(net "SMB_BMC_SWB_SDA")
	)
	(segment
		(start 133.15188 -127.091948)
		(end 133.15188 -126.710948)
		(width 0.12954)
		(layer "F.Cu")
		(net "SMB_BMC_SWB_SDA")
	)
	(segment
		(start 182.40248 -169.001948)
		(end 178.08448 -164.683948)
		(width 0.12954)
		(layer "F.Cu")
		(net "SMB_BMC_SWB_SDA")
	)
	(segment
		(start 141.25448 -130.317748)
		(end 142.88008 -128.692148)
		(width 0.12954)
		(layer "F.Cu")
		(net "SMB_BMC_SWB_SDA")
	)
	(segment
		(start 178.21402 -158.296356)
		(end 178.08448 -158.166816)
		(width 0.12954)
		(layer "F.Cu")
		(net "SMB_BMC_SWB_SDA")
	)
	(segment
		(start 129.199894 -128.986026)
		(end 131.066794 -127.119126)
		(width 0.12954)
		(layer "F.Cu")
		(net "SMB_BMC_SWB_SDA")
	)
	(segment
		(start 128.801622 -128.986026)
		(end 129.199894 -128.986026)
		(width 0.12954)
		(layer "F.Cu")
		(net "SMB_BMC_SWB_SDA")
	)
	(segment
		(start 243.89588 -170.703748)
		(end 204.85608 -170.703748)
		(width 0.12954)
		(layer "F.Cu")
		(net "SMB_BMC_SWB_SDA")
	)
	(segment
		(start 178.874928 -159.571436)
		(end 178.21402 -159.571436)
		(width 0.12954)
		(layer "F.Cu")
		(net "SMB_BMC_SWB_SDA")
	)
	(segment
		(start 178.874928 -157.021276)
		(end 178.21402 -157.021276)
		(width 0.12954)
		(layer "F.Cu")
		(net "SMB_BMC_SWB_SDA")
	)
	(segment
		(start 179.004468 -160.079436)
		(end 179.004468 -159.700976)
		(width 0.12954)
		(layer "F.Cu")
		(net "SMB_BMC_SWB_SDA")
	)
	(segment
		(start 178.08448 -156.891736)
		(end 178.08448 -156.200348)
		(width 0.12954)
		(layer "F.Cu")
		(net "SMB_BMC_SWB_SDA")
	)
	(via
		(at 144.40408 -128.692148)
		(size 0.508)
		(drill 0.254)
		(layers "F.Cu" "B.Cu")
		(net "SMB_BMC_SWB_SDA")
	)
	(via
		(at 133.15188 -127.091948)
		(size 0.508)
		(drill 0.254)
		(layers "F.Cu" "B.Cu")
		(net "SMB_BMC_SWB_SDA")
	)
	(via
		(at 244.78488 -168.214548)
		(size 0.508)
		(drill 0.254)
		(layers "F.Cu" "B.Cu")
		(net "SMB_BMC_SWB_SDA")
	)
	(via
		(at 163.50615 -417.440618)
		(size 0.508)
		(drill 0.254)
		(layers "F.Cu" "B.Cu")
		(net "SMB_BMC_SWB_SDA")
	)
	(segment
		(start 163.50615 -417.41725)
		(end 164.02558 -416.89782)
		(width 0.127)
		(layer "In2.Cu")
		(net "SMB_BMC_SWB_SDA")
	)
	(segment
		(start 221.42196 -348.39656)
		(end 221.54896 -348.26956)
		(width 0.127)
		(layer "In2.Cu")
		(net "SMB_BMC_SWB_SDA")
	)
	(segment
		(start 176.48682 -406.386538)
		(end 174.29988 -404.199598)
		(width 0.127)
		(layer "In2.Cu")
		(net "SMB_BMC_SWB_SDA")
	)
	(segment
		(start 222.45828 -362.237274)
		(end 222.45828 -361.35056)
		(width 0.127)
		(layer "In2.Cu")
		(net "SMB_BMC_SWB_SDA")
	)
	(segment
		(start 221.42196 -355.30536)
		(end 221.54896 -355.17836)
		(width 0.127)
		(layer "In2.Cu")
		(net "SMB_BMC_SWB_SDA")
	)
	(segment
		(start 222.33128 -359.49636)
		(end 221.54896 -359.49636)
		(width 0.127)
		(layer "In2.Cu")
		(net "SMB_BMC_SWB_SDA")
	)
	(segment
		(start 176.2633 -396.04061)
		(end 176.2633 -391.823956)
		(width 0.127)
		(layer "In2.Cu")
		(net "SMB_BMC_SWB_SDA")
	)
	(segment
		(start 166.18712 -416.89782)
		(end 167.64508 -415.43986)
		(width 0.127)
		(layer "In2.Cu")
		(net "SMB_BMC_SWB_SDA")
	)
	(segment
		(start 221.54896 -356.90556)
		(end 222.33128 -356.90556)
		(width 0.127)
		(layer "In2.Cu")
		(net "SMB_BMC_SWB_SDA")
	)
	(segment
		(start 222.33128 -357.76916)
		(end 221.54896 -357.76916)
		(width 0.127)
		(layer "In2.Cu")
		(net "SMB_BMC_SWB_SDA")
	)
	(segment
		(start 222.45828 -350.98736)
		(end 222.33128 -350.86036)
		(width 0.127)
		(layer "In2.Cu")
		(net "SMB_BMC_SWB_SDA")
	)
	(segment
		(start 221.54896 -350.86036)
		(end 221.42196 -350.73336)
		(width 0.127)
		(layer "In2.Cu")
		(net "SMB_BMC_SWB_SDA")
	)
	(segment
		(start 175.20031 -413.81934)
		(end 176.48682 -412.53283)
		(width 0.127)
		(layer "In2.Cu")
		(net "SMB_BMC_SWB_SDA")
	)
	(segment
		(start 222.33128 -354.31476)
		(end 221.54896 -354.31476)
		(width 0.127)
		(layer "In2.Cu")
		(net "SMB_BMC_SWB_SDA")
	)
	(segment
		(start 222.45828 -356.16896)
		(end 222.33128 -356.04196)
		(width 0.127)
		(layer "In2.Cu")
		(net "SMB_BMC_SWB_SDA")
	)
	(segment
		(start 221.42196 -346.66936)
		(end 221.54896 -346.54236)
		(width 0.127)
		(layer "In2.Cu")
		(net "SMB_BMC_SWB_SDA")
	)
	(segment
		(start 221.42196 -355.91496)
		(end 221.42196 -355.30536)
		(width 0.127)
		(layer "In2.Cu")
		(net "SMB_BMC_SWB_SDA")
	)
	(segment
		(start 221.54896 -348.26956)
		(end 222.33128 -348.26956)
		(width 0.127)
		(layer "In2.Cu")
		(net "SMB_BMC_SWB_SDA")
	)
	(segment
		(start 221.42196 -354.18776)
		(end 221.42196 -353.57816)
		(width 0.127)
		(layer "In2.Cu")
		(net "SMB_BMC_SWB_SDA")
	)
	(segment
		(start 222.45828 -351.59696)
		(end 222.45828 -350.98736)
		(width 0.127)
		(layer "In2.Cu")
		(net "SMB_BMC_SWB_SDA")
	)
	(segment
		(start 222.45828 -346.41536)
		(end 222.45828 -344.612722)
		(width 0.127)
		(layer "In2.Cu")
		(net "SMB_BMC_SWB_SDA")
	)
	(segment
		(start 221.54896 -358.63276)
		(end 222.33128 -358.63276)
		(width 0.127)
		(layer "In2.Cu")
		(net "SMB_BMC_SWB_SDA")
	)
	(segment
		(start 222.33128 -356.90556)
		(end 222.45828 -356.77856)
		(width 0.127)
		(layer "In2.Cu")
		(net "SMB_BMC_SWB_SDA")
	)
	(segment
		(start 221.54896 -353.45116)
		(end 222.33128 -353.45116)
		(width 0.127)
		(layer "In2.Cu")
		(net "SMB_BMC_SWB_SDA")
	)
	(segment
		(start 171.585636 -413.81934)
		(end 175.20031 -413.81934)
		(width 0.127)
		(layer "In2.Cu")
		(net "SMB_BMC_SWB_SDA")
	)
	(segment
		(start 163.50615 -417.440618)
		(end 163.50615 -417.41725)
		(width 0.127)
		(layer "In2.Cu")
		(net "SMB_BMC_SWB_SDA")
	)
	(segment
		(start 221.54896 -357.76916)
		(end 221.42196 -357.64216)
		(width 0.127)
		(layer "In2.Cu")
		(net "SMB_BMC_SWB_SDA")
	)
	(segment
		(start 169.965116 -415.43986)
		(end 171.585636 -413.81934)
		(width 0.127)
		(layer "In2.Cu")
		(net "SMB_BMC_SWB_SDA")
	)
	(segment
		(start 221.42196 -351.85096)
		(end 221.54896 -351.72396)
		(width 0.127)
		(layer "In2.Cu")
		(net "SMB_BMC_SWB_SDA")
	)
	(segment
		(start 222.33128 -349.99676)
		(end 222.45828 -349.86976)
		(width 0.127)
		(layer "In2.Cu")
		(net "SMB_BMC_SWB_SDA")
	)
	(segment
		(start 222.33128 -350.86036)
		(end 221.54896 -350.86036)
		(width 0.127)
		(layer "In2.Cu")
		(net "SMB_BMC_SWB_SDA")
	)
	(segment
		(start 176.48682 -412.53283)
		(end 176.48682 -406.386538)
		(width 0.127)
		(layer "In2.Cu")
		(net "SMB_BMC_SWB_SDA")
	)
	(segment
		(start 221.42196 -353.57816)
		(end 221.54896 -353.45116)
		(width 0.127)
		(layer "In2.Cu")
		(net "SMB_BMC_SWB_SDA")
	)
	(segment
		(start 221.54896 -360.35996)
		(end 222.33128 -360.35996)
		(width 0.127)
		(layer "In2.Cu")
		(net "SMB_BMC_SWB_SDA")
	)
	(segment
		(start 221.54896 -346.54236)
		(end 222.33128 -346.54236)
		(width 0.127)
		(layer "In2.Cu")
		(net "SMB_BMC_SWB_SDA")
	)
	(segment
		(start 221.42196 -361.09656)
		(end 221.42196 -360.48696)
		(width 0.127)
		(layer "In2.Cu")
		(net "SMB_BMC_SWB_SDA")
	)
	(segment
		(start 246.9642 -320.106802)
		(end 246.9642 -241.696748)
		(width 0.127)
		(layer "In2.Cu")
		(net "SMB_BMC_SWB_SDA")
	)
	(segment
		(start 222.45828 -361.35056)
		(end 222.33128 -361.22356)
		(width 0.127)
		(layer "In2.Cu")
		(net "SMB_BMC_SWB_SDA")
	)
	(segment
		(start 221.54896 -352.58756)
		(end 221.42196 -352.46056)
		(width 0.127)
		(layer "In2.Cu")
		(net "SMB_BMC_SWB_SDA")
	)
	(segment
		(start 222.45828 -347.53296)
		(end 222.33128 -347.40596)
		(width 0.127)
		(layer "In2.Cu")
		(net "SMB_BMC_SWB_SDA")
	)
	(segment
		(start 174.29988 -404.199598)
		(end 174.29988 -398.00403)
		(width 0.127)
		(layer "In2.Cu")
		(net "SMB_BMC_SWB_SDA")
	)
	(segment
		(start 221.42196 -358.75976)
		(end 221.54896 -358.63276)
		(width 0.127)
		(layer "In2.Cu")
		(net "SMB_BMC_SWB_SDA")
	)
	(segment
		(start 222.33128 -360.35996)
		(end 222.45828 -360.23296)
		(width 0.127)
		(layer "In2.Cu")
		(net "SMB_BMC_SWB_SDA")
	)
	(segment
		(start 246.71274 -170.040046)
		(end 244.887242 -168.214548)
		(width 0.127)
		(layer "In2.Cu")
		(net "SMB_BMC_SWB_SDA")
	)
	(segment
		(start 222.45828 -353.32416)
		(end 222.45828 -352.71456)
		(width 0.127)
		(layer "In2.Cu")
		(net "SMB_BMC_SWB_SDA")
	)
	(segment
		(start 221.42196 -359.36936)
		(end 221.42196 -358.75976)
		(width 0.127)
		(layer "In2.Cu")
		(net "SMB_BMC_SWB_SDA")
	)
	(segment
		(start 244.887242 -168.214548)
		(end 244.78488 -168.214548)
		(width 0.127)
		(layer "In2.Cu")
		(net "SMB_BMC_SWB_SDA")
	)
	(segment
		(start 221.54896 -359.49636)
		(end 221.42196 -359.36936)
		(width 0.127)
		(layer "In2.Cu")
		(net "SMB_BMC_SWB_SDA")
	)
	(segment
		(start 222.33128 -353.45116)
		(end 222.45828 -353.32416)
		(width 0.127)
		(layer "In2.Cu")
		(net "SMB_BMC_SWB_SDA")
	)
	(segment
		(start 222.33128 -346.54236)
		(end 222.45828 -346.41536)
		(width 0.127)
		(layer "In2.Cu")
		(net "SMB_BMC_SWB_SDA")
	)
	(segment
		(start 222.45828 -360.23296)
		(end 222.45828 -359.62336)
		(width 0.127)
		(layer "In2.Cu")
		(net "SMB_BMC_SWB_SDA")
	)
	(segment
		(start 222.45828 -356.77856)
		(end 222.45828 -356.16896)
		(width 0.127)
		(layer "In2.Cu")
		(net "SMB_BMC_SWB_SDA")
	)
	(segment
		(start 222.45828 -349.26016)
		(end 222.33128 -349.13316)
		(width 0.127)
		(layer "In2.Cu")
		(net "SMB_BMC_SWB_SDA")
	)
	(segment
		(start 222.45828 -358.50576)
		(end 222.45828 -357.89616)
		(width 0.127)
		(layer "In2.Cu")
		(net "SMB_BMC_SWB_SDA")
	)
	(segment
		(start 222.45828 -349.86976)
		(end 222.45828 -349.26016)
		(width 0.127)
		(layer "In2.Cu")
		(net "SMB_BMC_SWB_SDA")
	)
	(segment
		(start 221.54896 -361.22356)
		(end 221.42196 -361.09656)
		(width 0.127)
		(layer "In2.Cu")
		(net "SMB_BMC_SWB_SDA")
	)
	(segment
		(start 222.33128 -352.58756)
		(end 221.54896 -352.58756)
		(width 0.127)
		(layer "In2.Cu")
		(net "SMB_BMC_SWB_SDA")
	)
	(segment
		(start 222.33128 -348.26956)
		(end 222.45828 -348.14256)
		(width 0.127)
		(layer "In2.Cu")
		(net "SMB_BMC_SWB_SDA")
	)
	(segment
		(start 246.9642 -241.696748)
		(end 246.71274 -241.445288)
		(width 0.127)
		(layer "In2.Cu")
		(net "SMB_BMC_SWB_SDA")
	)
	(segment
		(start 174.29988 -398.00403)
		(end 176.2633 -396.04061)
		(width 0.127)
		(layer "In2.Cu")
		(net "SMB_BMC_SWB_SDA")
	)
	(segment
		(start 221.42196 -360.48696)
		(end 221.54896 -360.35996)
		(width 0.127)
		(layer "In2.Cu")
		(net "SMB_BMC_SWB_SDA")
	)
	(segment
		(start 221.54896 -351.72396)
		(end 222.33128 -351.72396)
		(width 0.127)
		(layer "In2.Cu")
		(net "SMB_BMC_SWB_SDA")
	)
	(segment
		(start 222.45828 -348.14256)
		(end 222.45828 -347.53296)
		(width 0.127)
		(layer "In2.Cu")
		(net "SMB_BMC_SWB_SDA")
	)
	(segment
		(start 246.71274 -241.445288)
		(end 246.71274 -170.040046)
		(width 0.127)
		(layer "In2.Cu")
		(net "SMB_BMC_SWB_SDA")
	)
	(segment
		(start 222.45828 -354.44176)
		(end 222.33128 -354.31476)
		(width 0.127)
		(layer "In2.Cu")
		(net "SMB_BMC_SWB_SDA")
	)
	(segment
		(start 222.33128 -361.22356)
		(end 221.54896 -361.22356)
		(width 0.127)
		(layer "In2.Cu")
		(net "SMB_BMC_SWB_SDA")
	)
	(segment
		(start 221.42196 -350.12376)
		(end 221.54896 -349.99676)
		(width 0.127)
		(layer "In2.Cu")
		(net "SMB_BMC_SWB_SDA")
	)
	(segment
		(start 222.45828 -357.89616)
		(end 222.33128 -357.76916)
		(width 0.127)
		(layer "In2.Cu")
		(net "SMB_BMC_SWB_SDA")
	)
	(segment
		(start 222.45828 -355.05136)
		(end 222.45828 -354.44176)
		(width 0.127)
		(layer "In2.Cu")
		(net "SMB_BMC_SWB_SDA")
	)
	(segment
		(start 221.42196 -352.46056)
		(end 221.42196 -351.85096)
		(width 0.127)
		(layer "In2.Cu")
		(net "SMB_BMC_SWB_SDA")
	)
	(segment
		(start 222.33128 -349.13316)
		(end 221.54896 -349.13316)
		(width 0.127)
		(layer "In2.Cu")
		(net "SMB_BMC_SWB_SDA")
	)
	(segment
		(start 222.33128 -358.63276)
		(end 222.45828 -358.50576)
		(width 0.127)
		(layer "In2.Cu")
		(net "SMB_BMC_SWB_SDA")
	)
	(segment
		(start 221.54896 -356.04196)
		(end 221.42196 -355.91496)
		(width 0.127)
		(layer "In2.Cu")
		(net "SMB_BMC_SWB_SDA")
	)
	(segment
		(start 221.54896 -354.31476)
		(end 221.42196 -354.18776)
		(width 0.127)
		(layer "In2.Cu")
		(net "SMB_BMC_SWB_SDA")
	)
	(segment
		(start 221.42196 -357.03256)
		(end 221.54896 -356.90556)
		(width 0.127)
		(layer "In2.Cu")
		(net "SMB_BMC_SWB_SDA")
	)
	(segment
		(start 221.54896 -355.17836)
		(end 222.33128 -355.17836)
		(width 0.127)
		(layer "In2.Cu")
		(net "SMB_BMC_SWB_SDA")
	)
	(segment
		(start 221.42196 -350.73336)
		(end 221.42196 -350.12376)
		(width 0.127)
		(layer "In2.Cu")
		(net "SMB_BMC_SWB_SDA")
	)
	(segment
		(start 221.42196 -357.64216)
		(end 221.42196 -357.03256)
		(width 0.127)
		(layer "In2.Cu")
		(net "SMB_BMC_SWB_SDA")
	)
	(segment
		(start 222.45828 -344.612722)
		(end 246.9642 -320.106802)
		(width 0.127)
		(layer "In2.Cu")
		(net "SMB_BMC_SWB_SDA")
	)
	(segment
		(start 221.42196 -347.27896)
		(end 221.42196 -346.66936)
		(width 0.127)
		(layer "In2.Cu")
		(net "SMB_BMC_SWB_SDA")
	)
	(segment
		(start 222.33128 -355.17836)
		(end 222.45828 -355.05136)
		(width 0.127)
		(layer "In2.Cu")
		(net "SMB_BMC_SWB_SDA")
	)
	(segment
		(start 222.45828 -352.71456)
		(end 222.33128 -352.58756)
		(width 0.127)
		(layer "In2.Cu")
		(net "SMB_BMC_SWB_SDA")
	)
	(segment
		(start 222.45828 -359.62336)
		(end 222.33128 -359.49636)
		(width 0.127)
		(layer "In2.Cu")
		(net "SMB_BMC_SWB_SDA")
	)
	(segment
		(start 167.64508 -415.43986)
		(end 169.965116 -415.43986)
		(width 0.127)
		(layer "In2.Cu")
		(net "SMB_BMC_SWB_SDA")
	)
	(segment
		(start 221.54896 -349.99676)
		(end 222.33128 -349.99676)
		(width 0.127)
		(layer "In2.Cu")
		(net "SMB_BMC_SWB_SDA")
	)
	(segment
		(start 222.33128 -347.40596)
		(end 221.54896 -347.40596)
		(width 0.127)
		(layer "In2.Cu")
		(net "SMB_BMC_SWB_SDA")
	)
	(segment
		(start 222.33128 -356.04196)
		(end 221.54896 -356.04196)
		(width 0.127)
		(layer "In2.Cu")
		(net "SMB_BMC_SWB_SDA")
	)
	(segment
		(start 198.286116 -369.80114)
		(end 214.894414 -369.80114)
		(width 0.127)
		(layer "In2.Cu")
		(net "SMB_BMC_SWB_SDA")
	)
	(segment
		(start 221.54896 -349.13316)
		(end 221.42196 -349.00616)
		(width 0.127)
		(layer "In2.Cu")
		(net "SMB_BMC_SWB_SDA")
	)
	(segment
		(start 221.54896 -347.40596)
		(end 221.42196 -347.27896)
		(width 0.127)
		(layer "In2.Cu")
		(net "SMB_BMC_SWB_SDA")
	)
	(segment
		(start 164.02558 -416.89782)
		(end 166.18712 -416.89782)
		(width 0.127)
		(layer "In2.Cu")
		(net "SMB_BMC_SWB_SDA")
	)
	(segment
		(start 176.2633 -391.823956)
		(end 198.286116 -369.80114)
		(width 0.127)
		(layer "In2.Cu")
		(net "SMB_BMC_SWB_SDA")
	)
	(segment
		(start 214.894414 -369.80114)
		(end 222.45828 -362.237274)
		(width 0.127)
		(layer "In2.Cu")
		(net "SMB_BMC_SWB_SDA")
	)
	(segment
		(start 221.42196 -349.00616)
		(end 221.42196 -348.39656)
		(width 0.127)
		(layer "In2.Cu")
		(net "SMB_BMC_SWB_SDA")
	)
	(segment
		(start 222.33128 -351.72396)
		(end 222.45828 -351.59696)
		(width 0.127)
		(layer "In2.Cu")
		(net "SMB_BMC_SWB_SDA")
	)
	(segment
		(start 144.40408 -128.692148)
		(end 135.53948 -128.692148)
		(width 0.127)
		(layer "In4.Cu")
		(net "SMB_BMC_SWB_SDA")
	)
	(segment
		(start 132.13588 -127.701548)
		(end 132.94868 -127.701548)
		(width 0.127)
		(layer "In4.Cu")
		(net "SMB_BMC_SWB_SDA")
	)
	(segment
		(start 133.12648 -127.117348)
		(end 133.15188 -127.091948)
		(width 0.127)
		(layer "In4.Cu")
		(net "SMB_BMC_SWB_SDA")
	)
	(segment
		(start 131.90728 -128.717548)
		(end 131.90728 -127.930148)
		(width 0.127)
		(layer "In4.Cu")
		(net "SMB_BMC_SWB_SDA")
	)
	(segment
		(start 132.21208 -129.022348)
		(end 131.90728 -128.717548)
		(width 0.127)
		(layer "In4.Cu")
		(net "SMB_BMC_SWB_SDA")
	)
	(segment
		(start 133.12648 -127.523748)
		(end 133.12648 -127.117348)
		(width 0.127)
		(layer "In4.Cu")
		(net "SMB_BMC_SWB_SDA")
	)
	(segment
		(start 135.20928 -129.022348)
		(end 132.21208 -129.022348)
		(width 0.127)
		(layer "In4.Cu")
		(net "SMB_BMC_SWB_SDA")
	)
	(segment
		(start 131.90728 -127.930148)
		(end 132.13588 -127.701548)
		(width 0.127)
		(layer "In4.Cu")
		(net "SMB_BMC_SWB_SDA")
	)
	(segment
		(start 132.94868 -127.701548)
		(end 133.12648 -127.523748)
		(width 0.127)
		(layer "In4.Cu")
		(net "SMB_BMC_SWB_SDA")
	)
	(segment
		(start 135.53948 -128.692148)
		(end 135.20928 -129.022348)
		(width 0.127)
		(layer "In4.Cu")
		(net "SMB_BMC_SWB_SDA")
	)
	(segment
		(start 125.583442 -130.805682)
		(end 124.793756 -130.805682)
		(width 0.12954)
		(layer "F.Cu")
		(net "SMB_BMC_SWB_SCL_R4")
	)
	(segment
		(start 124.552964 -131.046474)
		(end 123.708668 -131.046474)
		(width 0.12954)
		(layer "F.Cu")
		(net "SMB_BMC_SWB_SCL_R4")
	)
	(segment
		(start 128.001522 -130.002026)
		(end 127.784098 -130.002026)
		(width 0.12954)
		(layer "F.Cu")
		(net "SMB_BMC_SWB_SCL_R4")
	)
	(segment
		(start 127.784098 -130.002026)
		(end 126.980442 -130.805682)
		(width 0.12954)
		(layer "F.Cu")
		(net "SMB_BMC_SWB_SCL_R4")
	)
	(segment
		(start 126.980442 -130.805682)
		(end 125.583442 -130.805682)
		(width 0.12954)
		(layer "F.Cu")
		(net "SMB_BMC_SWB_SCL_R4")
	)
	(segment
		(start 124.793756 -130.805682)
		(end 124.552964 -131.046474)
		(width 0.12954)
		(layer "F.Cu")
		(net "SMB_BMC_SWB_SCL_R4")
	)
	(via
		(at 125.583442 -130.805682)
		(size 0.762)
		(drill 0.381)
		(layers "F.Cu" "B.Cu")
		(net "SMB_BMC_SWB_SCL_R4")
	)
	(segment
		(start 129.580894 -130.002026)
		(end 131.066794 -128.516126)
		(width 0.12954)
		(layer "F.Cu")
		(net "SMB_BMC_SWB_SCL")
	)
	(segment
		(start 140.79728 -130.128264)
		(end 142.690596 -128.234948)
		(width 0.12954)
		(layer "F.Cu")
		(net "SMB_BMC_SWB_SCL")
	)
	(segment
		(start 244.07368 -167.579548)
		(end 245.19128 -167.579548)
		(width 0.12954)
		(layer "F.Cu")
		(net "SMB_BMC_SWB_SCL")
	)
	(segment
		(start 142.14348 -144.324832)
		(end 140.79728 -142.978632)
		(width 0.12954)
		(layer "F.Cu")
		(net "SMB_BMC_SWB_SCL")
	)
	(segment
		(start 142.690596 -128.234948)
		(end 143.754856 -128.234948)
		(width 0.12954)
		(layer "F.Cu")
		(net "SMB_BMC_SWB_SCL")
	)
	(segment
		(start 244.17528 -171.160948)
		(end 204.666596 -171.160948)
		(width 0.12954)
		(layer "F.Cu")
		(net "SMB_BMC_SWB_SCL")
	)
	(segment
		(start 133.15188 -128.107948)
		(end 132.847334 -127.803402)
		(width 0.12954)
		(layer "F.Cu")
		(net "SMB_BMC_SWB_SCL")
	)
	(segment
		(start 245.19128 -167.579548)
		(end 245.90248 -168.290748)
		(width 0.12954)
		(layer "F.Cu")
		(net "SMB_BMC_SWB_SCL")
	)
	(segment
		(start 204.666596 -171.160948)
		(end 202.964796 -169.459148)
		(width 0.12954)
		(layer "F.Cu")
		(net "SMB_BMC_SWB_SCL")
	)
	(segment
		(start 245.90248 -168.290748)
		(end 245.90248 -169.433748)
		(width 0.12954)
		(layer "F.Cu")
		(net "SMB_BMC_SWB_SCL")
	)
	(segment
		(start 142.14348 -147.982432)
		(end 142.14348 -144.324832)
		(width 0.12954)
		(layer "F.Cu")
		(net "SMB_BMC_SWB_SCL")
	)
	(segment
		(start 177.62728 -164.873432)
		(end 177.62728 -156.389832)
		(width 0.12954)
		(layer "F.Cu")
		(net "SMB_BMC_SWB_SCL")
	)
	(segment
		(start 133.15188 -128.488948)
		(end 133.15188 -128.107948)
		(width 0.12954)
		(layer "F.Cu")
		(net "SMB_BMC_SWB_SCL")
	)
	(segment
		(start 146.373596 -152.212548)
		(end 142.14348 -147.982432)
		(width 0.12954)
		(layer "F.Cu")
		(net "SMB_BMC_SWB_SCL")
	)
	(segment
		(start 173.449996 -152.212548)
		(end 146.373596 -152.212548)
		(width 0.12954)
		(layer "F.Cu")
		(net "SMB_BMC_SWB_SCL")
	)
	(segment
		(start 182.212996 -169.459148)
		(end 177.62728 -164.873432)
		(width 0.12954)
		(layer "F.Cu")
		(net "SMB_BMC_SWB_SCL")
	)
	(segment
		(start 177.62728 -156.389832)
		(end 173.449996 -152.212548)
		(width 0.12954)
		(layer "F.Cu")
		(net "SMB_BMC_SWB_SCL")
	)
	(segment
		(start 143.754856 -128.234948)
		(end 143.932656 -128.057148)
		(width 0.12954)
		(layer "F.Cu")
		(net "SMB_BMC_SWB_SCL")
	)
	(segment
		(start 140.79728 -142.978632)
		(end 140.79728 -130.128264)
		(width 0.12954)
		(layer "F.Cu")
		(net "SMB_BMC_SWB_SCL")
	)
	(segment
		(start 163.12515 -433.265326)
		(end 163.12515 -433.948078)
		(width 0.12954)
		(layer "F.Cu")
		(net "SMB_BMC_SWB_SCL")
	)
	(segment
		(start 131.779518 -127.803402)
		(end 131.066794 -128.516126)
		(width 0.12954)
		(layer "F.Cu")
		(net "SMB_BMC_SWB_SCL")
	)
	(segment
		(start 132.847334 -127.803402)
		(end 131.779518 -127.803402)
		(width 0.12954)
		(layer "F.Cu")
		(net "SMB_BMC_SWB_SCL")
	)
	(segment
		(start 245.90248 -169.433748)
		(end 244.17528 -171.160948)
		(width 0.12954)
		(layer "F.Cu")
		(net "SMB_BMC_SWB_SCL")
	)
	(segment
		(start 143.932656 -128.057148)
		(end 144.40408 -128.057148)
		(width 0.12954)
		(layer "F.Cu")
		(net "SMB_BMC_SWB_SCL")
	)
	(segment
		(start 202.964796 -169.459148)
		(end 182.212996 -169.459148)
		(width 0.12954)
		(layer "F.Cu")
		(net "SMB_BMC_SWB_SCL")
	)
	(segment
		(start 128.801622 -130.002026)
		(end 129.580894 -130.002026)
		(width 0.12954)
		(layer "F.Cu")
		(net "SMB_BMC_SWB_SCL")
	)
	(via
		(at 244.07368 -167.579548)
		(size 0.508)
		(drill 0.254)
		(layers "F.Cu" "B.Cu")
		(net "SMB_BMC_SWB_SCL")
	)
	(via
		(at 133.15188 -128.488948)
		(size 0.508)
		(drill 0.254)
		(layers "F.Cu" "B.Cu")
		(net "SMB_BMC_SWB_SCL")
	)
	(via
		(at 144.40408 -128.057148)
		(size 0.508)
		(drill 0.254)
		(layers "F.Cu" "B.Cu")
		(net "SMB_BMC_SWB_SCL")
	)
	(via
		(at 163.12515 -433.948078)
		(size 0.508)
		(drill 0.254)
		(layers "F.Cu" "B.Cu")
		(net "SMB_BMC_SWB_SCL")
	)
	(segment
		(start 198.4756 -370.25834)
		(end 215.083898 -370.25834)
		(width 0.127)
		(layer "In2.Cu")
		(net "SMB_BMC_SWB_SCL")
	)
	(segment
		(start 163.966652 -434.78958)
		(end 165.5191 -434.78958)
		(width 0.127)
		(layer "In2.Cu")
		(net "SMB_BMC_SWB_SCL")
	)
	(segment
		(start 222.91548 -362.426758)
		(end 222.91548 -344.790014)
		(width 0.127)
		(layer "In2.Cu")
		(net "SMB_BMC_SWB_SCL")
	)
	(segment
		(start 215.083898 -370.25834)
		(end 222.91548 -362.426758)
		(width 0.127)
		(layer "In2.Cu")
		(net "SMB_BMC_SWB_SCL")
	)
	(segment
		(start 167.71874 -432.58994)
		(end 167.71874 -418.37102)
		(width 0.127)
		(layer "In2.Cu")
		(net "SMB_BMC_SWB_SCL")
	)
	(segment
		(start 174.73168 -404.020528)
		(end 174.73168 -398.1831)
		(width 0.127)
		(layer "In2.Cu")
		(net "SMB_BMC_SWB_SCL")
	)
	(segment
		(start 247.16486 -169.578528)
		(end 245.16588 -167.579548)
		(width 0.127)
		(layer "In2.Cu")
		(net "SMB_BMC_SWB_SCL")
	)
	(segment
		(start 247.396 -241.50447)
		(end 247.16486 -241.27333)
		(width 0.127)
		(layer "In2.Cu")
		(net "SMB_BMC_SWB_SCL")
	)
	(segment
		(start 168.26738 -417.82238)
		(end 168.54424 -417.82238)
		(width 0.127)
		(layer "In2.Cu")
		(net "SMB_BMC_SWB_SCL")
	)
	(segment
		(start 176.91862 -406.207468)
		(end 174.73168 -404.020528)
		(width 0.127)
		(layer "In2.Cu")
		(net "SMB_BMC_SWB_SCL")
	)
	(segment
		(start 174.73168 -398.1831)
		(end 176.6951 -396.21968)
		(width 0.127)
		(layer "In2.Cu")
		(net "SMB_BMC_SWB_SCL")
	)
	(segment
		(start 176.6951 -396.21968)
		(end 176.6951 -392.03884)
		(width 0.127)
		(layer "In2.Cu")
		(net "SMB_BMC_SWB_SCL")
	)
	(segment
		(start 169.3291 -417.03752)
		(end 169.3291 -416.72256)
		(width 0.127)
		(layer "In2.Cu")
		(net "SMB_BMC_SWB_SCL")
	)
	(segment
		(start 176.91862 -412.7119)
		(end 176.91862 -406.207468)
		(width 0.127)
		(layer "In2.Cu")
		(net "SMB_BMC_SWB_SCL")
	)
	(segment
		(start 175.3743 -414.25622)
		(end 176.91862 -412.7119)
		(width 0.127)
		(layer "In2.Cu")
		(net "SMB_BMC_SWB_SCL")
	)
	(segment
		(start 163.12515 -433.948078)
		(end 163.966652 -434.78958)
		(width 0.127)
		(layer "In2.Cu")
		(net "SMB_BMC_SWB_SCL")
	)
	(segment
		(start 169.3291 -416.72256)
		(end 171.79544 -414.25622)
		(width 0.127)
		(layer "In2.Cu")
		(net "SMB_BMC_SWB_SCL")
	)
	(segment
		(start 247.16486 -241.27333)
		(end 247.16486 -169.578528)
		(width 0.127)
		(layer "In2.Cu")
		(net "SMB_BMC_SWB_SCL")
	)
	(segment
		(start 167.71874 -418.37102)
		(end 168.26738 -417.82238)
		(width 0.127)
		(layer "In2.Cu")
		(net "SMB_BMC_SWB_SCL")
	)
	(segment
		(start 168.54424 -417.82238)
		(end 169.3291 -417.03752)
		(width 0.127)
		(layer "In2.Cu")
		(net "SMB_BMC_SWB_SCL")
	)
	(segment
		(start 176.6951 -392.03884)
		(end 198.4756 -370.25834)
		(width 0.127)
		(layer "In2.Cu")
		(net "SMB_BMC_SWB_SCL")
	)
	(segment
		(start 222.91548 -344.790014)
		(end 247.396 -320.309494)
		(width 0.127)
		(layer "In2.Cu")
		(net "SMB_BMC_SWB_SCL")
	)
	(segment
		(start 171.79544 -414.25622)
		(end 175.3743 -414.25622)
		(width 0.127)
		(layer "In2.Cu")
		(net "SMB_BMC_SWB_SCL")
	)
	(segment
		(start 245.16588 -167.579548)
		(end 244.07368 -167.579548)
		(width 0.127)
		(layer "In2.Cu")
		(net "SMB_BMC_SWB_SCL")
	)
	(segment
		(start 165.5191 -434.78958)
		(end 167.71874 -432.58994)
		(width 0.127)
		(layer "In2.Cu")
		(net "SMB_BMC_SWB_SCL")
	)
	(segment
		(start 247.396 -320.309494)
		(end 247.396 -241.50447)
		(width 0.127)
		(layer "In2.Cu")
		(net "SMB_BMC_SWB_SCL")
	)
	(segment
		(start 140.200126 -128.057148)
		(end 140.581126 -128.057148)
		(width 0.127)
		(layer "In4.Cu")
		(net "SMB_BMC_SWB_SCL")
	)
	(segment
		(start 140.708126 -127.930148)
		(end 140.708126 -127.56007)
		(width 0.127)
		(layer "In4.Cu")
		(net "SMB_BMC_SWB_SCL")
	)
	(segment
		(start 141.978126 -127.56007)
		(end 142.105126 -127.43307)
		(width 0.127)
		(layer "In4.Cu")
		(net "SMB_BMC_SWB_SCL")
	)
	(segment
		(start 139.438126 -127.930148)
		(end 139.438126 -127.56007)
		(width 0.127)
		(layer "In4.Cu")
		(net "SMB_BMC_SWB_SCL")
	)
	(segment
		(start 141.343126 -127.930148)
		(end 141.470126 -128.057148)
		(width 0.127)
		(layer "In4.Cu")
		(net "SMB_BMC_SWB_SCL")
	)
	(segment
		(start 141.978126 -127.930148)
		(end 141.978126 -127.56007)
		(width 0.127)
		(layer "In4.Cu")
		(net "SMB_BMC_SWB_SCL")
	)
	(segment
		(start 138.168126 -127.56007)
		(end 138.295126 -127.43307)
		(width 0.127)
		(layer "In4.Cu")
		(net "SMB_BMC_SWB_SCL")
	)
	(segment
		(start 141.470126 -128.057148)
		(end 141.851126 -128.057148)
		(width 0.127)
		(layer "In4.Cu")
		(net "SMB_BMC_SWB_SCL")
	)
	(segment
		(start 138.295126 -127.43307)
		(end 138.676126 -127.43307)
		(width 0.127)
		(layer "In4.Cu")
		(net "SMB_BMC_SWB_SCL")
	)
	(segment
		(start 138.041126 -128.057148)
		(end 138.168126 -127.930148)
		(width 0.127)
		(layer "In4.Cu")
		(net "SMB_BMC_SWB_SCL")
	)
	(segment
		(start 138.803126 -127.930148)
		(end 138.930126 -128.057148)
		(width 0.127)
		(layer "In4.Cu")
		(net "SMB_BMC_SWB_SCL")
	)
	(segment
		(start 138.803126 -127.56007)
		(end 138.803126 -127.930148)
		(width 0.127)
		(layer "In4.Cu")
		(net "SMB_BMC_SWB_SCL")
	)
	(segment
		(start 140.708126 -127.56007)
		(end 140.835126 -127.43307)
		(width 0.127)
		(layer "In4.Cu")
		(net "SMB_BMC_SWB_SCL")
	)
	(segment
		(start 140.073126 -127.56007)
		(end 140.073126 -127.930148)
		(width 0.127)
		(layer "In4.Cu")
		(net "SMB_BMC_SWB_SCL")
	)
	(segment
		(start 142.486126 -127.43307)
		(end 142.613126 -127.56007)
		(width 0.127)
		(layer "In4.Cu")
		(net "SMB_BMC_SWB_SCL")
	)
	(segment
		(start 133.88848 -127.752348)
		(end 137.39368 -127.752348)
		(width 0.127)
		(layer "In4.Cu")
		(net "SMB_BMC_SWB_SCL")
	)
	(segment
		(start 138.168126 -127.930148)
		(end 138.168126 -127.56007)
		(width 0.127)
		(layer "In4.Cu")
		(net "SMB_BMC_SWB_SCL")
	)
	(segment
		(start 142.613126 -127.930148)
		(end 142.740126 -128.057148)
		(width 0.127)
		(layer "In4.Cu")
		(net "SMB_BMC_SWB_SCL")
	)
	(segment
		(start 139.438126 -127.56007)
		(end 139.565126 -127.43307)
		(width 0.127)
		(layer "In4.Cu")
		(net "SMB_BMC_SWB_SCL")
	)
	(segment
		(start 142.105126 -127.43307)
		(end 142.486126 -127.43307)
		(width 0.127)
		(layer "In4.Cu")
		(net "SMB_BMC_SWB_SCL")
	)
	(segment
		(start 139.946126 -127.43307)
		(end 140.073126 -127.56007)
		(width 0.127)
		(layer "In4.Cu")
		(net "SMB_BMC_SWB_SCL")
	)
	(segment
		(start 142.740126 -128.057148)
		(end 144.40408 -128.057148)
		(width 0.127)
		(layer "In4.Cu")
		(net "SMB_BMC_SWB_SCL")
	)
	(segment
		(start 139.565126 -127.43307)
		(end 139.946126 -127.43307)
		(width 0.127)
		(layer "In4.Cu")
		(net "SMB_BMC_SWB_SCL")
	)
	(segment
		(start 140.581126 -128.057148)
		(end 140.708126 -127.930148)
		(width 0.127)
		(layer "In4.Cu")
		(net "SMB_BMC_SWB_SCL")
	)
	(segment
		(start 141.851126 -128.057148)
		(end 141.978126 -127.930148)
		(width 0.127)
		(layer "In4.Cu")
		(net "SMB_BMC_SWB_SCL")
	)
	(segment
		(start 138.930126 -128.057148)
		(end 139.311126 -128.057148)
		(width 0.127)
		(layer "In4.Cu")
		(net "SMB_BMC_SWB_SCL")
	)
	(segment
		(start 138.676126 -127.43307)
		(end 138.803126 -127.56007)
		(width 0.127)
		(layer "In4.Cu")
		(net "SMB_BMC_SWB_SCL")
	)
	(segment
		(start 137.39368 -127.752348)
		(end 137.69848 -128.057148)
		(width 0.127)
		(layer "In4.Cu")
		(net "SMB_BMC_SWB_SCL")
	)
	(segment
		(start 137.69848 -128.057148)
		(end 138.041126 -128.057148)
		(width 0.127)
		(layer "In4.Cu")
		(net "SMB_BMC_SWB_SCL")
	)
	(segment
		(start 142.613126 -127.56007)
		(end 142.613126 -127.930148)
		(width 0.127)
		(layer "In4.Cu")
		(net "SMB_BMC_SWB_SCL")
	)
	(segment
		(start 140.835126 -127.43307)
		(end 141.216126 -127.43307)
		(width 0.127)
		(layer "In4.Cu")
		(net "SMB_BMC_SWB_SCL")
	)
	(segment
		(start 140.073126 -127.930148)
		(end 140.200126 -128.057148)
		(width 0.127)
		(layer "In4.Cu")
		(net "SMB_BMC_SWB_SCL")
	)
	(segment
		(start 141.216126 -127.43307)
		(end 141.343126 -127.56007)
		(width 0.127)
		(layer "In4.Cu")
		(net "SMB_BMC_SWB_SCL")
	)
	(segment
		(start 139.311126 -128.057148)
		(end 139.438126 -127.930148)
		(width 0.127)
		(layer "In4.Cu")
		(net "SMB_BMC_SWB_SCL")
	)
	(segment
		(start 141.343126 -127.56007)
		(end 141.343126 -127.930148)
		(width 0.127)
		(layer "In4.Cu")
		(net "SMB_BMC_SWB_SCL")
	)
	(segment
		(start 133.15188 -128.488948)
		(end 133.88848 -127.752348)
		(width 0.127)
		(layer "In4.Cu")
		(net "SMB_BMC_SWB_SCL")
	)
	(segment
		(start 163.25215 -421.968676)
		(end 163.56203 -422.278556)
		(width 0.12954)
		(layer "F.Cu")
		(net "SMB_BMC_SWB_R_SDA")
	)
	(segment
		(start 163.4871 -419.911276)
		(end 163.4871 -419.930072)
		(width 0.12954)
		(layer "F.Cu")
		(net "SMB_BMC_SWB_R_SDA")
	)
	(segment
		(start 163.4871 -419.930072)
		(end 163.25215 -420.165022)
		(width 0.12954)
		(layer "F.Cu")
		(net "SMB_BMC_SWB_R_SDA")
	)
	(segment
		(start 163.25215 -420.165022)
		(end 163.25215 -421.274748)
		(width 0.12954)
		(layer "F.Cu")
		(net "SMB_BMC_SWB_R_SDA")
	)
	(segment
		(start 163.4871 -418.933376)
		(end 163.4871 -419.911276)
		(width 0.12954)
		(layer "F.Cu")
		(net "SMB_BMC_SWB_R_SDA")
	)
	(segment
		(start 163.25215 -421.274748)
		(end 163.25215 -421.968676)
		(width 0.12954)
		(layer "F.Cu")
		(net "SMB_BMC_SWB_R_SDA")
	)
	(segment
		(start 163.56203 -422.278556)
		(end 163.56203 -423.01287)
		(width 0.12954)
		(layer "F.Cu")
		(net "SMB_BMC_SWB_R_SDA")
	)
	(segment
		(start 163.50615 -418.914326)
		(end 163.4871 -418.933376)
		(width 0.12954)
		(layer "F.Cu")
		(net "SMB_BMC_SWB_R_SDA")
	)
	(via
		(at 163.25215 -421.274748)
		(size 0.508)
		(drill 0.254)
		(layers "F.Cu" "B.Cu")
		(net "SMB_BMC_SWB_R_SDA")
	)
	(segment
		(start 162.74415 -430.344326)
		(end 163.1061 -430.706276)
		(width 0.12954)
		(layer "F.Cu")
		(net "SMB_BMC_SWB_R_SCL")
	)
	(segment
		(start 163.56203 -427.477682)
		(end 163.56203 -428.586392)
		(width 0.12954)
		(layer "F.Cu")
		(net "SMB_BMC_SWB_R_SCL")
	)
	(segment
		(start 163.56203 -428.586392)
		(end 162.74415 -429.404272)
		(width 0.12954)
		(layer "F.Cu")
		(net "SMB_BMC_SWB_R_SCL")
	)
	(segment
		(start 163.12515 -432.465226)
		(end 163.1061 -432.446176)
		(width 0.12954)
		(layer "F.Cu")
		(net "SMB_BMC_SWB_R_SCL")
	)
	(segment
		(start 162.74415 -429.628808)
		(end 162.74415 -430.344326)
		(width 0.12954)
		(layer "F.Cu")
		(net "SMB_BMC_SWB_R_SCL")
	)
	(segment
		(start 162.74415 -429.404272)
		(end 162.74415 -429.628808)
		(width 0.12954)
		(layer "F.Cu")
		(net "SMB_BMC_SWB_R_SCL")
	)
	(segment
		(start 163.1061 -432.446176)
		(end 163.1061 -430.706276)
		(width 0.12954)
		(layer "F.Cu")
		(net "SMB_BMC_SWB_R_SCL")
	)
	(via
		(at 162.74415 -429.628808)
		(size 0.508)
		(drill 0.254)
		(layers "F.Cu" "B.Cu")
		(net "SMB_BMC_SWB_R_SCL")
	)
	(segment
		(start 165.53815 -418.914326)
		(end 164.52215 -418.914326)
		(width 0.12954)
		(layer "F.Cu")
		(net "SMB_BMC_SWB_BUF_R_SDA")
	)
	(segment
		(start 164.64915 -420.273226)
		(end 164.64915 -421.254428)
		(width 0.12954)
		(layer "F.Cu")
		(net "SMB_BMC_SWB_BUF_R_SDA")
	)
	(segment
		(start 164.64915 -421.831516)
		(end 164.21227 -422.268396)
		(width 0.12954)
		(layer "F.Cu")
		(net "SMB_BMC_SWB_BUF_R_SDA")
	)
	(segment
		(start 164.64915 -421.254428)
		(end 164.64915 -421.831516)
		(width 0.12954)
		(layer "F.Cu")
		(net "SMB_BMC_SWB_BUF_R_SDA")
	)
	(segment
		(start 164.52215 -418.914326)
		(end 164.2872 -419.149276)
		(width 0.12954)
		(layer "F.Cu")
		(net "SMB_BMC_SWB_BUF_R_SDA")
	)
	(segment
		(start 164.2872 -419.911276)
		(end 164.64915 -420.273226)
		(width 0.12954)
		(layer "F.Cu")
		(net "SMB_BMC_SWB_BUF_R_SDA")
	)
	(segment
		(start 164.21227 -422.268396)
		(end 164.21227 -423.01287)
		(width 0.12954)
		(layer "F.Cu")
		(net "SMB_BMC_SWB_BUF_R_SDA")
	)
	(segment
		(start 164.2872 -419.149276)
		(end 164.2872 -419.911276)
		(width 0.12954)
		(layer "F.Cu")
		(net "SMB_BMC_SWB_BUF_R_SDA")
	)
	(via
		(at 164.64915 -421.254428)
		(size 0.508)
		(drill 0.254)
		(layers "F.Cu" "B.Cu")
		(net "SMB_BMC_SWB_BUF_R_SDA")
	)
	(segment
		(start 164.21227 -427.477682)
		(end 164.21227 -428.318676)
		(width 0.12954)
		(layer "F.Cu")
		(net "SMB_BMC_SWB_BUF_R_SCL")
	)
	(segment
		(start 164.14115 -432.465226)
		(end 165.15715 -432.465226)
		(width 0.12954)
		(layer "F.Cu")
		(net "SMB_BMC_SWB_BUF_R_SCL")
	)
	(segment
		(start 164.14115 -432.465226)
		(end 163.9062 -432.230276)
		(width 0.12954)
		(layer "F.Cu")
		(net "SMB_BMC_SWB_BUF_R_SCL")
	)
	(segment
		(start 164.01415 -429.560228)
		(end 164.01415 -430.598326)
		(width 0.12954)
		(layer "F.Cu")
		(net "SMB_BMC_SWB_BUF_R_SCL")
	)
	(segment
		(start 164.01415 -428.516796)
		(end 164.01415 -429.560228)
		(width 0.12954)
		(layer "F.Cu")
		(net "SMB_BMC_SWB_BUF_R_SCL")
	)
	(segment
		(start 164.01415 -430.598326)
		(end 163.9062 -430.706276)
		(width 0.12954)
		(layer "F.Cu")
		(net "SMB_BMC_SWB_BUF_R_SCL")
	)
	(segment
		(start 164.21227 -428.318676)
		(end 164.01415 -428.516796)
		(width 0.12954)
		(layer "F.Cu")
		(net "SMB_BMC_SWB_BUF_R_SCL")
	)
	(segment
		(start 163.9062 -432.230276)
		(end 163.9062 -430.706276)
		(width 0.12954)
		(layer "F.Cu")
		(net "SMB_BMC_SWB_BUF_R_SCL")
	)
	(via
		(at 164.01415 -429.560228)
		(size 0.508)
		(drill 0.254)
		(layers "F.Cu" "B.Cu")
		(net "SMB_BMC_SWB_BUF_R_SCL")
	)
	(segment
		(start 362.69676 -403.972014)
		(end 362.107734 -403.972014)
		(width 0.12954)
		(layer "F.Cu")
		(net "FM_UART_EN")
	)
	(segment
		(start 361.36072 -404.719028)
		(end 361.36072 -403.34565)
		(width 0.12954)
		(layer "F.Cu")
		(net "FM_UART_EN")
	)
	(segment
		(start 362.107734 -403.972014)
		(end 361.36072 -404.719028)
		(width 0.12954)
		(layer "F.Cu")
		(net "FM_UART_EN")
	)
	(via
		(at 361.36072 -404.719028)
		(size 0.762)
		(drill 0.381)
		(layers "F.Cu" "B.Cu")
		(net "FM_UART_EN")
	)
	(segment
		(start 429.129952 -386.821934)
		(end 429.129952 -386.171948)
		(width 0.12954)
		(layer "F.Cu")
		(net "FM_SWB_PWRGD_N")
	)
	(segment
		(start 429.129952 -386.171948)
		(end 430.338992 -386.171948)
		(width 0.12954)
		(layer "F.Cu")
		(net "FM_SWB_PWRGD_N")
	)
	(segment
		(start 430.338992 -386.171948)
		(end 431.589942 -386.171948)
		(width 0.12954)
		(layer "F.Cu")
		(net "FM_SWB_PWRGD_N")
	)
	(via
		(at 430.338992 -386.171948)
		(size 0.762)
		(drill 0.381)
		(layers "F.Cu" "B.Cu")
		(net "FM_SWB_PWRGD_N")
	)
	(segment
		(start 426.595032 -385.521962)
		(end 424.843956 -385.521962)
		(width 0.12954)
		(layer "F.Cu")
		(net "FM_SWB_PWRGD_ISO")
	)
	(segment
		(start 427.230032 -385.521962)
		(end 426.595032 -385.521962)
		(width 0.12954)
		(layer "F.Cu")
		(net "FM_SWB_PWRGD_ISO")
	)
	(segment
		(start 424.604942 -385.282948)
		(end 424.604942 -384.266948)
		(width 0.12954)
		(layer "F.Cu")
		(net "FM_SWB_PWRGD_ISO")
	)
	(segment
		(start 424.843956 -385.521962)
		(end 424.604942 -385.282948)
		(width 0.12954)
		(layer "F.Cu")
		(net "FM_SWB_PWRGD_ISO")
	)
	(via
		(at 201.58964 -107.401868)
		(size 0.508)
		(drill 0.254)
		(layers "F.Cu" "B.Cu")
		(net "FM_SWB_PWRGD_ISO")
	)
	(via
		(at 237.30204 -205.311248)
		(size 0.508)
		(drill 0.254)
		(layers "F.Cu" "B.Cu")
		(net "FM_SWB_PWRGD_ISO")
	)
	(via
		(at 426.595032 -385.521962)
		(size 0.508)
		(drill 0.254)
		(layers "F.Cu" "B.Cu")
		(net "FM_SWB_PWRGD_ISO")
	)
	(via
		(at 304.402744 -392.808968)
		(size 0.762)
		(drill 0.254)
		(layers "F.Cu" "B.Cu")
		(net "FM_SWB_PWRGD_ISO")
	)
	(segment
		(start 164.24783 -105.755948)
		(end 163.89858 -105.755948)
		(width 0.12954)
		(layer "B.Cu")
		(net "FM_SWB_PWRGD_ISO")
	)
	(segment
		(start 163.89858 -105.755948)
		(end 162.9029 -104.760268)
		(width 0.12954)
		(layer "B.Cu")
		(net "FM_SWB_PWRGD_ISO")
	)
	(segment
		(start 202.05446 -104.803448)
		(end 202.05446 -106.937048)
		(width 0.12954)
		(layer "B.Cu")
		(net "FM_SWB_PWRGD_ISO")
	)
	(segment
		(start 196.80936 -100.388928)
		(end 199.5424 -103.121968)
		(width 0.12954)
		(layer "B.Cu")
		(net "FM_SWB_PWRGD_ISO")
	)
	(segment
		(start 162.9029 -104.760268)
		(end 162.9029 -101.526848)
		(width 0.12954)
		(layer "B.Cu")
		(net "FM_SWB_PWRGD_ISO")
	)
	(segment
		(start 164.24275 -100.186998)
		(end 176.49571 -100.186998)
		(width 0.12954)
		(layer "B.Cu")
		(net "FM_SWB_PWRGD_ISO")
	)
	(segment
		(start 200.37298 -103.121968)
		(end 202.05446 -104.803448)
		(width 0.12954)
		(layer "B.Cu")
		(net "FM_SWB_PWRGD_ISO")
	)
	(segment
		(start 199.5424 -103.121968)
		(end 200.37298 -103.121968)
		(width 0.12954)
		(layer "B.Cu")
		(net "FM_SWB_PWRGD_ISO")
	)
	(segment
		(start 193.3702 -99.705668)
		(end 194.05346 -100.388928)
		(width 0.12954)
		(layer "B.Cu")
		(net "FM_SWB_PWRGD_ISO")
	)
	(segment
		(start 176.97704 -99.705668)
		(end 193.3702 -99.705668)
		(width 0.12954)
		(layer "B.Cu")
		(net "FM_SWB_PWRGD_ISO")
	)
	(segment
		(start 176.49571 -100.186998)
		(end 176.97704 -99.705668)
		(width 0.12954)
		(layer "B.Cu")
		(net "FM_SWB_PWRGD_ISO")
	)
	(segment
		(start 162.9029 -101.526848)
		(end 164.24275 -100.186998)
		(width 0.12954)
		(layer "B.Cu")
		(net "FM_SWB_PWRGD_ISO")
	)
	(segment
		(start 202.05446 -106.937048)
		(end 201.58964 -107.401868)
		(width 0.12954)
		(layer "B.Cu")
		(net "FM_SWB_PWRGD_ISO")
	)
	(segment
		(start 194.05346 -100.388928)
		(end 196.80936 -100.388928)
		(width 0.12954)
		(layer "B.Cu")
		(net "FM_SWB_PWRGD_ISO")
	)
	(segment
		(start 304.336196 -392.74242)
		(end 304.402744 -392.808968)
		(width 0.127)
		(layer "In4.Cu")
		(net "FM_SWB_PWRGD_ISO")
	)
	(segment
		(start 285.63062 -387.65734)
		(end 286.24784 -388.27456)
		(width 0.127)
		(layer "In4.Cu")
		(net "FM_SWB_PWRGD_ISO")
	)
	(segment
		(start 244.104414 -279.58542)
		(end 244.104414 -328.547476)
		(width 0.127)
		(layer "In4.Cu")
		(net "FM_SWB_PWRGD_ISO")
	)
	(segment
		(start 286.24784 -388.27456)
		(end 289.42284 -388.27456)
		(width 0.127)
		(layer "In4.Cu")
		(net "FM_SWB_PWRGD_ISO")
	)
	(segment
		(start 276.410674 -377.402344)
		(end 280.36393 -381.3556)
		(width 0.127)
		(layer "In4.Cu")
		(net "FM_SWB_PWRGD_ISO")
	)
	(segment
		(start 294.833548 -390.17448)
		(end 297.401488 -392.74242)
		(width 0.127)
		(layer "In4.Cu")
		(net "FM_SWB_PWRGD_ISO")
	)
	(segment
		(start 248.03608 -275.653754)
		(end 244.104414 -279.58542)
		(width 0.127)
		(layer "In4.Cu")
		(net "FM_SWB_PWRGD_ISO")
	)
	(segment
		(start 248.03608 -216.045288)
		(end 248.03608 -275.653754)
		(width 0.127)
		(layer "In4.Cu")
		(net "FM_SWB_PWRGD_ISO")
	)
	(segment
		(start 289.42284 -388.27456)
		(end 291.32276 -390.17448)
		(width 0.127)
		(layer "In4.Cu")
		(net "FM_SWB_PWRGD_ISO")
	)
	(segment
		(start 244.104414 -328.547476)
		(end 276.410674 -360.853736)
		(width 0.127)
		(layer "In4.Cu")
		(net "FM_SWB_PWRGD_ISO")
	)
	(segment
		(start 285.63062 -385.63169)
		(end 285.63062 -387.65734)
		(width 0.127)
		(layer "In4.Cu")
		(net "FM_SWB_PWRGD_ISO")
	)
	(segment
		(start 276.410674 -360.853736)
		(end 276.410674 -377.402344)
		(width 0.127)
		(layer "In4.Cu")
		(net "FM_SWB_PWRGD_ISO")
	)
	(segment
		(start 237.30204 -205.311248)
		(end 248.03608 -216.045288)
		(width 0.127)
		(layer "In4.Cu")
		(net "FM_SWB_PWRGD_ISO")
	)
	(segment
		(start 281.35453 -381.3556)
		(end 285.63062 -385.63169)
		(width 0.127)
		(layer "In4.Cu")
		(net "FM_SWB_PWRGD_ISO")
	)
	(segment
		(start 291.32276 -390.17448)
		(end 294.833548 -390.17448)
		(width 0.127)
		(layer "In4.Cu")
		(net "FM_SWB_PWRGD_ISO")
	)
	(segment
		(start 297.401488 -392.74242)
		(end 304.336196 -392.74242)
		(width 0.127)
		(layer "In4.Cu")
		(net "FM_SWB_PWRGD_ISO")
	)
	(segment
		(start 280.36393 -381.3556)
		(end 281.35453 -381.3556)
		(width 0.127)
		(layer "In4.Cu")
		(net "FM_SWB_PWRGD_ISO")
	)
	(segment
		(start 426.595032 -385.521962)
		(end 422.472866 -385.521962)
		(width 0.127)
		(layer "In11.Cu")
		(net "FM_SWB_PWRGD_ISO")
	)
	(segment
		(start 237.30204 -205.311248)
		(end 237.30204 -204.813408)
		(width 0.127)
		(layer "In11.Cu")
		(net "FM_SWB_PWRGD_ISO")
	)
	(segment
		(start 415.01568 -392.979148)
		(end 376.037348 -392.979148)
		(width 0.127)
		(layer "In11.Cu")
		(net "FM_SWB_PWRGD_ISO")
	)
	(segment
		(start 214.497412 -148.873972)
		(end 200.1774 -134.55396)
		(width 0.127)
		(layer "In11.Cu")
		(net "FM_SWB_PWRGD_ISO")
	)
	(segment
		(start 353.346766 -392.808968)
		(end 304.402744 -392.808968)
		(width 0.127)
		(layer "In11.Cu")
		(net "FM_SWB_PWRGD_ISO")
	)
	(segment
		(start 422.472866 -385.521962)
		(end 415.01568 -392.979148)
		(width 0.127)
		(layer "In11.Cu")
		(net "FM_SWB_PWRGD_ISO")
	)
	(segment
		(start 228.31298 -172.711364)
		(end 214.497412 -158.895796)
		(width 0.127)
		(layer "In11.Cu")
		(net "FM_SWB_PWRGD_ISO")
	)
	(segment
		(start 201.0156 -111.712248)
		(end 201.58964 -111.138208)
		(width 0.127)
		(layer "In11.Cu")
		(net "FM_SWB_PWRGD_ISO")
	)
	(segment
		(start 228.31298 -195.824348)
		(end 228.31298 -172.711364)
		(width 0.127)
		(layer "In11.Cu")
		(net "FM_SWB_PWRGD_ISO")
	)
	(segment
		(start 355.157786 -390.997948)
		(end 353.346766 -392.808968)
		(width 0.127)
		(layer "In11.Cu")
		(net "FM_SWB_PWRGD_ISO")
	)
	(segment
		(start 374.056148 -390.997948)
		(end 355.157786 -390.997948)
		(width 0.127)
		(layer "In11.Cu")
		(net "FM_SWB_PWRGD_ISO")
	)
	(segment
		(start 201.58964 -111.138208)
		(end 201.58964 -107.401868)
		(width 0.127)
		(layer "In11.Cu")
		(net "FM_SWB_PWRGD_ISO")
	)
	(segment
		(start 201.0156 -123.739148)
		(end 201.0156 -111.712248)
		(width 0.127)
		(layer "In11.Cu")
		(net "FM_SWB_PWRGD_ISO")
	)
	(segment
		(start 376.037348 -392.979148)
		(end 374.056148 -390.997948)
		(width 0.127)
		(layer "In11.Cu")
		(net "FM_SWB_PWRGD_ISO")
	)
	(segment
		(start 237.30204 -204.813408)
		(end 228.31298 -195.824348)
		(width 0.127)
		(layer "In11.Cu")
		(net "FM_SWB_PWRGD_ISO")
	)
	(segment
		(start 214.497412 -158.895796)
		(end 214.497412 -148.873972)
		(width 0.127)
		(layer "In11.Cu")
		(net "FM_SWB_PWRGD_ISO")
	)
	(segment
		(start 200.1774 -134.55396)
		(end 200.1774 -124.577348)
		(width 0.127)
		(layer "In11.Cu")
		(net "FM_SWB_PWRGD_ISO")
	)
	(segment
		(start 200.1774 -124.577348)
		(end 201.0156 -123.739148)
		(width 0.127)
		(layer "In11.Cu")
		(net "FM_SWB_PWRGD_ISO")
	)
	(segment
		(start 427.230032 -390.855962)
		(end 426.595032 -390.855962)
		(width 0.12954)
		(layer "F.Cu")
		(net "FM_SWB_BIC_READY_ISO_N")
	)
	(segment
		(start 424.843956 -390.855962)
		(end 424.604942 -390.616948)
		(width 0.12954)
		(layer "F.Cu")
		(net "FM_SWB_BIC_READY_ISO_N")
	)
	(segment
		(start 163.56076 -105.068878)
		(end 164.24783 -105.755948)
		(width 0.12954)
		(layer "F.Cu")
		(net "FM_SWB_BIC_READY_ISO_N")
	)
	(segment
		(start 426.595032 -390.855962)
		(end 424.843956 -390.855962)
		(width 0.12954)
		(layer "F.Cu")
		(net "FM_SWB_BIC_READY_ISO_N")
	)
	(segment
		(start 163.56076 -104.516428)
		(end 163.56076 -105.068878)
		(width 0.12954)
		(layer "F.Cu")
		(net "FM_SWB_BIC_READY_ISO_N")
	)
	(segment
		(start 424.604942 -389.600948)
		(end 424.604942 -390.616948)
		(width 0.12954)
		(layer "F.Cu")
		(net "FM_SWB_BIC_READY_ISO_N")
	)
	(via
		(at 301.68088 -393.388088)
		(size 0.508)
		(drill 0.254)
		(layers "F.Cu" "B.Cu")
		(net "FM_SWB_BIC_READY_ISO_N")
	)
	(via
		(at 200.92416 -107.414568)
		(size 0.508)
		(drill 0.254)
		(layers "F.Cu" "B.Cu")
		(net "FM_SWB_BIC_READY_ISO_N")
	)
	(via
		(at 237.503208 -206.40802)
		(size 0.508)
		(drill 0.254)
		(layers "F.Cu" "B.Cu")
		(net "FM_SWB_BIC_READY_ISO_N")
	)
	(via
		(at 163.56076 -104.516428)
		(size 0.508)
		(drill 0.254)
		(layers "F.Cu" "B.Cu")
		(net "FM_SWB_BIC_READY_ISO_N")
	)
	(via
		(at 426.595032 -390.855962)
		(size 0.508)
		(drill 0.254)
		(layers "F.Cu" "B.Cu")
		(net "FM_SWB_BIC_READY_ISO_N")
	)
	(segment
		(start 201.11847 -107.220258)
		(end 201.11847 -106.86669)
		(width 0.12954)
		(layer "B.Cu")
		(net "FM_SWB_BIC_READY_ISO_N")
	)
	(segment
		(start 192.47612 -100.024438)
		(end 177.353976 -100.024438)
		(width 0.12954)
		(layer "B.Cu")
		(net "FM_SWB_BIC_READY_ISO_N")
	)
	(segment
		(start 177.353976 -100.024438)
		(end 176.872646 -100.505768)
		(width 0.12954)
		(layer "B.Cu")
		(net "FM_SWB_BIC_READY_ISO_N")
	)
	(segment
		(start 201.11847 -106.86669)
		(end 201.59218 -106.39298)
		(width 0.12954)
		(layer "B.Cu")
		(net "FM_SWB_BIC_READY_ISO_N")
	)
	(segment
		(start 199.57034 -104.300528)
		(end 196.97954 -101.709728)
		(width 0.12954)
		(layer "B.Cu")
		(net "FM_SWB_BIC_READY_ISO_N")
	)
	(segment
		(start 166.31158 -100.505768)
		(end 163.56076 -103.256588)
		(width 0.12954)
		(layer "B.Cu")
		(net "FM_SWB_BIC_READY_ISO_N")
	)
	(segment
		(start 200.92416 -107.414568)
		(end 201.11847 -107.220258)
		(width 0.12954)
		(layer "B.Cu")
		(net "FM_SWB_BIC_READY_ISO_N")
	)
	(segment
		(start 163.56076 -103.256588)
		(end 163.56076 -104.516428)
		(width 0.12954)
		(layer "B.Cu")
		(net "FM_SWB_BIC_READY_ISO_N")
	)
	(segment
		(start 196.97954 -101.709728)
		(end 194.16141 -101.709728)
		(width 0.12954)
		(layer "B.Cu")
		(net "FM_SWB_BIC_READY_ISO_N")
	)
	(segment
		(start 201.59218 -106.39298)
		(end 201.59218 -105.453688)
		(width 0.12954)
		(layer "B.Cu")
		(net "FM_SWB_BIC_READY_ISO_N")
	)
	(segment
		(start 200.43902 -104.300528)
		(end 199.57034 -104.300528)
		(width 0.12954)
		(layer "B.Cu")
		(net "FM_SWB_BIC_READY_ISO_N")
	)
	(segment
		(start 194.16141 -101.709728)
		(end 192.47612 -100.024438)
		(width 0.12954)
		(layer "B.Cu")
		(net "FM_SWB_BIC_READY_ISO_N")
	)
	(segment
		(start 176.872646 -100.505768)
		(end 166.31158 -100.505768)
		(width 0.12954)
		(layer "B.Cu")
		(net "FM_SWB_BIC_READY_ISO_N")
	)
	(segment
		(start 201.59218 -105.453688)
		(end 200.43902 -104.300528)
		(width 0.12954)
		(layer "B.Cu")
		(net "FM_SWB_BIC_READY_ISO_N")
	)
	(segment
		(start 301.436532 -393.14374)
		(end 301.68088 -393.388088)
		(width 0.127)
		(layer "In4.Cu")
		(net "FM_SWB_BIC_READY_ISO_N")
	)
	(segment
		(start 281.178 -381.6858)
		(end 285.15818 -385.66598)
		(width 0.127)
		(layer "In4.Cu")
		(net "FM_SWB_BIC_READY_ISO_N")
	)
	(segment
		(start 285.15818 -385.66598)
		(end 285.15818 -388.53618)
		(width 0.127)
		(layer "In4.Cu")
		(net "FM_SWB_BIC_READY_ISO_N")
	)
	(segment
		(start 285.15818 -388.53618)
		(end 288.60877 -391.98677)
		(width 0.127)
		(layer "In4.Cu")
		(net "FM_SWB_BIC_READY_ISO_N")
	)
	(segment
		(start 275.831554 -377.29033)
		(end 280.227024 -381.6858)
		(width 0.127)
		(layer "In4.Cu")
		(net "FM_SWB_BIC_READY_ISO_N")
	)
	(segment
		(start 237.503208 -206.40802)
		(end 247.70588 -216.610692)
		(width 0.127)
		(layer "In4.Cu")
		(net "FM_SWB_BIC_READY_ISO_N")
	)
	(segment
		(start 247.70588 -216.610692)
		(end 247.70588 -275.164804)
		(width 0.127)
		(layer "In4.Cu")
		(net "FM_SWB_BIC_READY_ISO_N")
	)
	(segment
		(start 243.525294 -279.34539)
		(end 243.525294 -328.787506)
		(width 0.127)
		(layer "In4.Cu")
		(net "FM_SWB_BIC_READY_ISO_N")
	)
	(segment
		(start 280.227024 -381.6858)
		(end 281.178 -381.6858)
		(width 0.127)
		(layer "In4.Cu")
		(net "FM_SWB_BIC_READY_ISO_N")
	)
	(segment
		(start 297.335448 -393.14374)
		(end 301.436532 -393.14374)
		(width 0.127)
		(layer "In4.Cu")
		(net "FM_SWB_BIC_READY_ISO_N")
	)
	(segment
		(start 243.525294 -328.787506)
		(end 275.831554 -361.093766)
		(width 0.127)
		(layer "In4.Cu")
		(net "FM_SWB_BIC_READY_ISO_N")
	)
	(segment
		(start 275.831554 -361.093766)
		(end 275.831554 -377.29033)
		(width 0.127)
		(layer "In4.Cu")
		(net "FM_SWB_BIC_READY_ISO_N")
	)
	(segment
		(start 247.70588 -275.164804)
		(end 243.525294 -279.34539)
		(width 0.127)
		(layer "In4.Cu")
		(net "FM_SWB_BIC_READY_ISO_N")
	)
	(segment
		(start 296.178478 -391.98677)
		(end 297.335448 -393.14374)
		(width 0.127)
		(layer "In4.Cu")
		(net "FM_SWB_BIC_READY_ISO_N")
	)
	(segment
		(start 288.60877 -391.98677)
		(end 296.178478 -391.98677)
		(width 0.127)
		(layer "In4.Cu")
		(net "FM_SWB_BIC_READY_ISO_N")
	)
	(segment
		(start 200.92416 -110.015528)
		(end 200.92416 -107.414568)
		(width 0.127)
		(layer "In11.Cu")
		(net "FM_SWB_BIC_READY_ISO_N")
	)
	(segment
		(start 200.3933 -111.186468)
		(end 200.3933 -110.546388)
		(width 0.127)
		(layer "In11.Cu")
		(net "FM_SWB_BIC_READY_ISO_N")
	)
	(segment
		(start 419.68928 -393.969748)
		(end 422.53408 -391.124948)
		(width 0.127)
		(layer "In11.Cu")
		(net "FM_SWB_BIC_READY_ISO_N")
	)
	(segment
		(start 236.220508 -204.199744)
		(end 227.98278 -195.962016)
		(width 0.127)
		(layer "In11.Cu")
		(net "FM_SWB_BIC_READY_ISO_N")
	)
	(segment
		(start 214.167212 -159.032702)
		(end 214.167212 -149.010878)
		(width 0.127)
		(layer "In11.Cu")
		(net "FM_SWB_BIC_READY_ISO_N")
	)
	(segment
		(start 199.8472 -124.440188)
		(end 200.6854 -123.601988)
		(width 0.127)
		(layer "In11.Cu")
		(net "FM_SWB_BIC_READY_ISO_N")
	)
	(segment
		(start 425.734734 -391.124948)
		(end 426.00372 -390.855962)
		(width 0.127)
		(layer "In11.Cu")
		(net "FM_SWB_BIC_READY_ISO_N")
	)
	(segment
		(start 374.339104 -392.681968)
		(end 375.626884 -393.969748)
		(width 0.127)
		(layer "In11.Cu")
		(net "FM_SWB_BIC_READY_ISO_N")
	)
	(segment
		(start 237.503208 -206.40802)
		(end 236.220508 -205.12532)
		(width 0.127)
		(layer "In11.Cu")
		(net "FM_SWB_BIC_READY_ISO_N")
	)
	(segment
		(start 200.6854 -111.478568)
		(end 200.3933 -111.186468)
		(width 0.127)
		(layer "In11.Cu")
		(net "FM_SWB_BIC_READY_ISO_N")
	)
	(segment
		(start 227.98278 -195.962016)
		(end 227.98278 -172.84827)
		(width 0.127)
		(layer "In11.Cu")
		(net "FM_SWB_BIC_READY_ISO_N")
	)
	(segment
		(start 422.53408 -391.124948)
		(end 425.734734 -391.124948)
		(width 0.127)
		(layer "In11.Cu")
		(net "FM_SWB_BIC_READY_ISO_N")
	)
	(segment
		(start 301.68088 -393.388088)
		(end 353.73564 -393.388088)
		(width 0.127)
		(layer "In11.Cu")
		(net "FM_SWB_BIC_READY_ISO_N")
	)
	(segment
		(start 227.98278 -172.84827)
		(end 214.167212 -159.032702)
		(width 0.127)
		(layer "In11.Cu")
		(net "FM_SWB_BIC_READY_ISO_N")
	)
	(segment
		(start 200.6854 -123.601988)
		(end 200.6854 -111.478568)
		(width 0.127)
		(layer "In11.Cu")
		(net "FM_SWB_BIC_READY_ISO_N")
	)
	(segment
		(start 426.00372 -390.855962)
		(end 426.595032 -390.855962)
		(width 0.127)
		(layer "In11.Cu")
		(net "FM_SWB_BIC_READY_ISO_N")
	)
	(segment
		(start 375.626884 -393.969748)
		(end 419.68928 -393.969748)
		(width 0.127)
		(layer "In11.Cu")
		(net "FM_SWB_BIC_READY_ISO_N")
	)
	(segment
		(start 236.220508 -205.12532)
		(end 236.220508 -204.199744)
		(width 0.127)
		(layer "In11.Cu")
		(net "FM_SWB_BIC_READY_ISO_N")
	)
	(segment
		(start 199.8472 -134.690866)
		(end 199.8472 -124.440188)
		(width 0.127)
		(layer "In11.Cu")
		(net "FM_SWB_BIC_READY_ISO_N")
	)
	(segment
		(start 353.73564 -393.388088)
		(end 354.44176 -392.681968)
		(width 0.127)
		(layer "In11.Cu")
		(net "FM_SWB_BIC_READY_ISO_N")
	)
	(segment
		(start 200.3933 -110.546388)
		(end 200.92416 -110.015528)
		(width 0.127)
		(layer "In11.Cu")
		(net "FM_SWB_BIC_READY_ISO_N")
	)
	(segment
		(start 214.167212 -149.010878)
		(end 199.8472 -134.690866)
		(width 0.127)
		(layer "In11.Cu")
		(net "FM_SWB_BIC_READY_ISO_N")
	)
	(segment
		(start 354.44176 -392.681968)
		(end 374.339104 -392.681968)
		(width 0.127)
		(layer "In11.Cu")
		(net "FM_SWB_BIC_READY_ISO_N")
	)
	(segment
		(start 429.129952 -392.155934)
		(end 429.129952 -391.505948)
		(width 0.12954)
		(layer "F.Cu")
		(net "FM_SWB_BIC_READY")
	)
	(segment
		(start 430.338992 -391.505948)
		(end 431.589942 -391.505948)
		(width 0.12954)
		(layer "F.Cu")
		(net "FM_SWB_BIC_READY")
	)
	(segment
		(start 429.129952 -391.505948)
		(end 430.338992 -391.505948)
		(width 0.12954)
		(layer "F.Cu")
		(net "FM_SWB_BIC_READY")
	)
	(via
		(at 430.338992 -391.505948)
		(size 0.762)
		(drill 0.381)
		(layers "F.Cu" "B.Cu")
		(net "FM_SWB_BIC_READY")
	)
	(segment
		(start 201.293222 -133.299708)
		(end 201.592942 -132.999988)
		(width 0.12954)
		(layer "F.Cu")
		(net "FM_P12V_HSC_EN_R_N")
	)
	(segment
		(start 200.03008 -132.094478)
		(end 200.03008 -133.299708)
		(width 0.12954)
		(layer "F.Cu")
		(net "FM_P12V_HSC_EN_R_N")
	)
	(segment
		(start 200.03008 -133.299708)
		(end 201.293222 -133.299708)
		(width 0.12954)
		(layer "F.Cu")
		(net "FM_P12V_HSC_EN_R_N")
	)
	(via
		(at 200.03008 -133.299708)
		(size 0.762)
		(drill 0.381)
		(layers "F.Cu" "B.Cu")
		(net "FM_P12V_HSC_EN_R_N")
	)
	(segment
		(start 205.11262 -127.566928)
		(end 205.94193 -128.396238)
		(width 0.12954)
		(layer "F.Cu")
		(net "FM_P12V_HSC_EN_R")
	)
	(segment
		(start 205.94193 -128.396238)
		(end 207.43418 -128.396238)
		(width 0.12954)
		(layer "F.Cu")
		(net "FM_P12V_HSC_EN_R")
	)
	(segment
		(start 203.598018 -127.566928)
		(end 205.11262 -127.566928)
		(width 0.12954)
		(layer "F.Cu")
		(net "FM_P12V_HSC_EN_R")
	)
	(via
		(at 205.11262 -127.566928)
		(size 0.762)
		(drill 0.381)
		(layers "F.Cu" "B.Cu")
		(net "FM_P12V_HSC_EN_R")
	)
	(segment
		(start 200.03008 -128.953768)
		(end 200.03008 -129.670048)
		(width 0.12954)
		(layer "F.Cu")
		(net "FM_P12V_HSC_EN_N")
	)
	(segment
		(start 198.9963 -131.294378)
		(end 200.03008 -131.294378)
		(width 0.12954)
		(layer "F.Cu")
		(net "FM_P12V_HSC_EN_N")
	)
	(segment
		(start 200.03008 -129.670048)
		(end 200.03008 -131.294378)
		(width 0.12954)
		(layer "F.Cu")
		(net "FM_P12V_HSC_EN_N")
	)
	(segment
		(start 201.598022 -128.516888)
		(end 200.46696 -128.516888)
		(width 0.12954)
		(layer "F.Cu")
		(net "FM_P12V_HSC_EN_N")
	)
	(segment
		(start 200.46696 -128.516888)
		(end 200.03008 -128.953768)
		(width 0.12954)
		(layer "F.Cu")
		(net "FM_P12V_HSC_EN_N")
	)
	(via
		(at 200.03008 -129.670048)
		(size 0.762)
		(drill 0.381)
		(layers "F.Cu" "B.Cu")
		(net "FM_P12V_HSC_EN_N")
	)
	(segment
		(start 181.760368 -41.112948)
		(end 181.17693 -41.112948)
		(width 0.12954)
		(layer "F.Cu")
		(net "FM_M2_SSD0_E7_PEDET")
	)
	(segment
		(start 341.91956 -40.931846)
		(end 341.81669 -41.034716)
		(width 0.12954)
		(layer "F.Cu")
		(net "FM_M2_SSD0_E7_PEDET")
	)
	(segment
		(start 341.893398 -41.401746)
		(end 342.19134 -41.401746)
		(width 0.12954)
		(layer "F.Cu")
		(net "FM_M2_SSD0_E7_PEDET")
	)
	(segment
		(start 341.81669 -41.325038)
		(end 341.893398 -41.401746)
		(width 0.12954)
		(layer "F.Cu")
		(net "FM_M2_SSD0_E7_PEDET")
	)
	(segment
		(start 341.81669 -41.034716)
		(end 341.81669 -41.325038)
		(width 0.12954)
		(layer "F.Cu")
		(net "FM_M2_SSD0_E7_PEDET")
	)
	(segment
		(start 182.426102 -40.447214)
		(end 181.760368 -41.112948)
		(width 0.12954)
		(layer "F.Cu")
		(net "FM_M2_SSD0_E7_PEDET")
	)
	(via
		(at 368.48288 -43.144948)
		(size 0.508)
		(drill 0.254)
		(layers "F.Cu" "B.Cu")
		(net "FM_M2_SSD0_E7_PEDET")
	)
	(via
		(at 237.012988 -62.51321)
		(size 0.508)
		(drill 0.254)
		(layers "F.Cu" "B.Cu")
		(net "FM_M2_SSD0_E7_PEDET")
	)
	(via
		(at 341.91956 -40.931846)
		(size 0.4572)
		(drill 0.2032)
		(layers "F.Cu" "B.Cu")
		(net "FM_M2_SSD0_E7_PEDET")
	)
	(via
		(at 221.7928 -49.342548)
		(size 0.508)
		(drill 0.254)
		(layers "F.Cu" "B.Cu")
		(net "FM_M2_SSD0_E7_PEDET")
	)
	(via
		(at 182.426102 -40.447214)
		(size 0.508)
		(drill 0.254)
		(layers "F.Cu" "B.Cu")
		(net "FM_M2_SSD0_E7_PEDET")
	)
	(segment
		(start 222.181674 -49.731422)
		(end 221.7928 -49.342548)
		(width 0.12954)
		(layer "B.Cu")
		(net "FM_M2_SSD0_E7_PEDET")
	)
	(segment
		(start 372.01983 -43.144948)
		(end 371.51183 -42.636948)
		(width 0.12954)
		(layer "B.Cu")
		(net "FM_M2_SSD0_E7_PEDET")
	)
	(segment
		(start 231.648 -58.865008)
		(end 231.260904 -59.252104)
		(width 0.12954)
		(layer "B.Cu")
		(net "FM_M2_SSD0_E7_PEDET")
	)
	(segment
		(start 369.62588 -42.636948)
		(end 369.11788 -43.144948)
		(width 0.12954)
		(layer "B.Cu")
		(net "FM_M2_SSD0_E7_PEDET")
	)
	(segment
		(start 235.57484 -58.865008)
		(end 231.648 -58.865008)
		(width 0.12954)
		(layer "B.Cu")
		(net "FM_M2_SSD0_E7_PEDET")
	)
	(segment
		(start 368.48288 -43.144948)
		(end 369.09883 -43.144948)
		(width 0.12954)
		(layer "B.Cu")
		(net "FM_M2_SSD0_E7_PEDET")
	)
	(segment
		(start 231.260904 -59.252104)
		(end 229.819454 -59.252104)
		(width 0.12954)
		(layer "B.Cu")
		(net "FM_M2_SSD0_E7_PEDET")
	)
	(segment
		(start 236.571282 -59.86145)
		(end 235.57484 -58.865008)
		(width 0.12954)
		(layer "B.Cu")
		(net "FM_M2_SSD0_E7_PEDET")
	)
	(segment
		(start 369.11788 -43.144948)
		(end 369.09883 -43.144948)
		(width 0.12954)
		(layer "B.Cu")
		(net "FM_M2_SSD0_E7_PEDET")
	)
	(segment
		(start 236.571282 -62.071504)
		(end 236.571282 -59.86145)
		(width 0.12954)
		(layer "B.Cu")
		(net "FM_M2_SSD0_E7_PEDET")
	)
	(segment
		(start 237.012988 -62.51321)
		(end 236.571282 -62.071504)
		(width 0.12954)
		(layer "B.Cu")
		(net "FM_M2_SSD0_E7_PEDET")
	)
	(segment
		(start 371.51183 -42.636948)
		(end 369.62588 -42.636948)
		(width 0.12954)
		(layer "B.Cu")
		(net "FM_M2_SSD0_E7_PEDET")
	)
	(segment
		(start 229.819454 -59.252104)
		(end 222.181674 -51.614324)
		(width 0.12954)
		(layer "B.Cu")
		(net "FM_M2_SSD0_E7_PEDET")
	)
	(segment
		(start 222.181674 -51.614324)
		(end 222.181674 -49.731422)
		(width 0.12954)
		(layer "B.Cu")
		(net "FM_M2_SSD0_E7_PEDET")
	)
	(segment
		(start 368.22888 -43.144948)
		(end 366.531652 -41.44772)
		(width 0.127)
		(layer "In2.Cu")
		(net "FM_M2_SSD0_E7_PEDET")
	)
	(segment
		(start 366.531652 -41.44772)
		(end 352.52406 -41.44772)
		(width 0.127)
		(layer "In2.Cu")
		(net "FM_M2_SSD0_E7_PEDET")
	)
	(segment
		(start 351.736152 -42.235628)
		(end 347.672406 -42.235628)
		(width 0.127)
		(layer "In2.Cu")
		(net "FM_M2_SSD0_E7_PEDET")
	)
	(segment
		(start 352.52406 -41.44772)
		(end 351.736152 -42.235628)
		(width 0.127)
		(layer "In2.Cu")
		(net "FM_M2_SSD0_E7_PEDET")
	)
	(segment
		(start 343.68486 -40.480488)
		(end 343.3191 -40.480488)
		(width 0.127)
		(layer "In2.Cu")
		(net "FM_M2_SSD0_E7_PEDET")
	)
	(segment
		(start 344.26144 -39.903908)
		(end 343.68486 -40.480488)
		(width 0.127)
		(layer "In2.Cu")
		(net "FM_M2_SSD0_E7_PEDET")
	)
	(segment
		(start 345.340686 -39.903908)
		(end 344.26144 -39.903908)
		(width 0.127)
		(layer "In2.Cu")
		(net "FM_M2_SSD0_E7_PEDET")
	)
	(segment
		(start 368.48288 -43.144948)
		(end 368.22888 -43.144948)
		(width 0.127)
		(layer "In2.Cu")
		(net "FM_M2_SSD0_E7_PEDET")
	)
	(segment
		(start 343.3191 -40.480488)
		(end 342.867742 -40.931846)
		(width 0.127)
		(layer "In2.Cu")
		(net "FM_M2_SSD0_E7_PEDET")
	)
	(segment
		(start 342.867742 -40.931846)
		(end 341.91956 -40.931846)
		(width 0.127)
		(layer "In2.Cu")
		(net "FM_M2_SSD0_E7_PEDET")
	)
	(segment
		(start 347.672406 -42.235628)
		(end 345.340686 -39.903908)
		(width 0.127)
		(layer "In2.Cu")
		(net "FM_M2_SSD0_E7_PEDET")
	)
	(segment
		(start 306.07254 -38.031166)
		(end 309.148988 -34.954718)
		(width 0.127)
		(layer "In4.Cu")
		(net "FM_M2_SSD0_E7_PEDET")
	)
	(segment
		(start 195.193666 -43.645836)
		(end 191.489076 -39.941246)
		(width 0.127)
		(layer "In4.Cu")
		(net "FM_M2_SSD0_E7_PEDET")
	)
	(segment
		(start 293.342568 -38.031166)
		(end 306.07254 -38.031166)
		(width 0.127)
		(layer "In4.Cu")
		(net "FM_M2_SSD0_E7_PEDET")
	)
	(segment
		(start 342.99906 -40.060118)
		(end 343.214452 -40.27551)
		(width 0.127)
		(layer "In4.Cu")
		(net "FM_M2_SSD0_E7_PEDET")
	)
	(segment
		(start 343.214452 -40.620188)
		(end 342.902794 -40.931846)
		(width 0.127)
		(layer "In4.Cu")
		(net "FM_M2_SSD0_E7_PEDET")
	)
	(segment
		(start 278.374602 -57.73801)
		(end 281.725624 -49.64811)
		(width 0.127)
		(layer "In4.Cu")
		(net "FM_M2_SSD0_E7_PEDET")
	)
	(segment
		(start 220.392498 -49.159922)
		(end 217.821002 -49.159922)
		(width 0.127)
		(layer "In4.Cu")
		(net "FM_M2_SSD0_E7_PEDET")
	)
	(segment
		(start 237.012988 -62.51321)
		(end 237.32744 -62.827662)
		(width 0.127)
		(layer "In4.Cu")
		(net "FM_M2_SSD0_E7_PEDET")
	)
	(segment
		(start 213.405212 -42.48277)
		(end 199.070722 -42.48277)
		(width 0.127)
		(layer "In4.Cu")
		(net "FM_M2_SSD0_E7_PEDET")
	)
	(segment
		(start 342.99906 -39.435532)
		(end 342.99906 -40.060118)
		(width 0.127)
		(layer "In4.Cu")
		(net "FM_M2_SSD0_E7_PEDET")
	)
	(segment
		(start 182.45328 -40.447214)
		(end 182.426102 -40.447214)
		(width 0.127)
		(layer "In4.Cu")
		(net "FM_M2_SSD0_E7_PEDET")
	)
	(segment
		(start 217.821002 -49.159922)
		(end 215.979248 -47.318168)
		(width 0.127)
		(layer "In4.Cu")
		(net "FM_M2_SSD0_E7_PEDET")
	)
	(segment
		(start 309.148988 -34.954718)
		(end 312.347864 -34.954718)
		(width 0.127)
		(layer "In4.Cu")
		(net "FM_M2_SSD0_E7_PEDET")
	)
	(segment
		(start 322.815712 -38.756336)
		(end 327.339452 -38.756336)
		(width 0.127)
		(layer "In4.Cu")
		(net "FM_M2_SSD0_E7_PEDET")
	)
	(segment
		(start 321.038728 -36.979352)
		(end 322.815712 -38.756336)
		(width 0.127)
		(layer "In4.Cu")
		(net "FM_M2_SSD0_E7_PEDET")
	)
	(segment
		(start 312.347864 -34.954718)
		(end 313.187842 -35.794696)
		(width 0.127)
		(layer "In4.Cu")
		(net "FM_M2_SSD0_E7_PEDET")
	)
	(segment
		(start 276.540214 -59.572398)
		(end 278.374602 -57.73801)
		(width 0.127)
		(layer "In4.Cu")
		(net "FM_M2_SSD0_E7_PEDET")
	)
	(segment
		(start 318.794892 -36.979352)
		(end 321.038728 -36.979352)
		(width 0.127)
		(layer "In4.Cu")
		(net "FM_M2_SSD0_E7_PEDET")
	)
	(segment
		(start 215.979248 -45.056806)
		(end 213.405212 -42.48277)
		(width 0.127)
		(layer "In4.Cu")
		(net "FM_M2_SSD0_E7_PEDET")
	)
	(segment
		(start 268.854682 -64.01435)
		(end 271.585182 -62.883288)
		(width 0.127)
		(layer "In4.Cu")
		(net "FM_M2_SSD0_E7_PEDET")
	)
	(segment
		(start 271.585182 -62.883288)
		(end 276.540214 -59.572398)
		(width 0.127)
		(layer "In4.Cu")
		(net "FM_M2_SSD0_E7_PEDET")
	)
	(segment
		(start 237.32744 -62.827662)
		(end 237.32744 -62.843664)
		(width 0.127)
		(layer "In4.Cu")
		(net "FM_M2_SSD0_E7_PEDET")
	)
	(segment
		(start 341.222076 -37.658548)
		(end 342.99906 -39.435532)
		(width 0.127)
		(layer "In4.Cu")
		(net "FM_M2_SSD0_E7_PEDET")
	)
	(segment
		(start 327.339452 -38.756336)
		(end 327.598024 -38.497764)
		(width 0.127)
		(layer "In4.Cu")
		(net "FM_M2_SSD0_E7_PEDET")
	)
	(segment
		(start 182.959248 -39.941246)
		(end 182.45328 -40.447214)
		(width 0.127)
		(layer "In4.Cu")
		(net "FM_M2_SSD0_E7_PEDET")
	)
	(segment
		(start 342.902794 -40.931846)
		(end 341.91956 -40.931846)
		(width 0.127)
		(layer "In4.Cu")
		(net "FM_M2_SSD0_E7_PEDET")
	)
	(segment
		(start 317.610236 -35.794696)
		(end 318.794892 -36.979352)
		(width 0.127)
		(layer "In4.Cu")
		(net "FM_M2_SSD0_E7_PEDET")
	)
	(segment
		(start 313.187842 -35.794696)
		(end 317.610236 -35.794696)
		(width 0.127)
		(layer "In4.Cu")
		(net "FM_M2_SSD0_E7_PEDET")
	)
	(segment
		(start 237.32744 -62.843664)
		(end 238.498126 -64.01435)
		(width 0.127)
		(layer "In4.Cu")
		(net "FM_M2_SSD0_E7_PEDET")
	)
	(segment
		(start 199.070722 -42.48277)
		(end 197.907656 -43.645836)
		(width 0.127)
		(layer "In4.Cu")
		(net "FM_M2_SSD0_E7_PEDET")
	)
	(segment
		(start 220.575124 -49.342548)
		(end 220.392498 -49.159922)
		(width 0.127)
		(layer "In4.Cu")
		(net "FM_M2_SSD0_E7_PEDET")
	)
	(segment
		(start 215.979248 -47.318168)
		(end 215.979248 -45.056806)
		(width 0.127)
		(layer "In4.Cu")
		(net "FM_M2_SSD0_E7_PEDET")
	)
	(segment
		(start 327.598024 -38.497764)
		(end 335.728818 -38.497764)
		(width 0.127)
		(layer "In4.Cu")
		(net "FM_M2_SSD0_E7_PEDET")
	)
	(segment
		(start 221.7928 -49.342548)
		(end 220.575124 -49.342548)
		(width 0.127)
		(layer "In4.Cu")
		(net "FM_M2_SSD0_E7_PEDET")
	)
	(segment
		(start 197.907656 -43.645836)
		(end 195.193666 -43.645836)
		(width 0.127)
		(layer "In4.Cu")
		(net "FM_M2_SSD0_E7_PEDET")
	)
	(segment
		(start 238.498126 -64.01435)
		(end 268.854682 -64.01435)
		(width 0.127)
		(layer "In4.Cu")
		(net "FM_M2_SSD0_E7_PEDET")
	)
	(segment
		(start 343.214452 -40.27551)
		(end 343.214452 -40.620188)
		(width 0.127)
		(layer "In4.Cu")
		(net "FM_M2_SSD0_E7_PEDET")
	)
	(segment
		(start 336.568034 -37.658548)
		(end 341.222076 -37.658548)
		(width 0.127)
		(layer "In4.Cu")
		(net "FM_M2_SSD0_E7_PEDET")
	)
	(segment
		(start 335.728818 -38.497764)
		(end 336.568034 -37.658548)
		(width 0.127)
		(layer "In4.Cu")
		(net "FM_M2_SSD0_E7_PEDET")
	)
	(segment
		(start 191.489076 -39.941246)
		(end 182.959248 -39.941246)
		(width 0.127)
		(layer "In4.Cu")
		(net "FM_M2_SSD0_E7_PEDET")
	)
	(segment
		(start 281.725624 -49.64811)
		(end 293.342568 -38.031166)
		(width 0.127)
		(layer "In4.Cu")
		(net "FM_M2_SSD0_E7_PEDET")
	)
	(segment
		(start 22.436582 -422.594786)
		(end 21.801582 -423.229786)
		(width 0.12954)
		(layer "F.Cu")
		(net "FM_SMB_2_ALERT_GPU_ISO_R_N")
	)
	(segment
		(start 182.955692 -119.375428)
		(end 183.355742 -119.775478)
		(width 0.12954)
		(layer "F.Cu")
		(net "FM_SMB_2_ALERT_GPU_ISO_R_N")
	)
	(segment
		(start 22.436582 -421.978836)
		(end 22.436582 -422.594786)
		(width 0.12954)
		(layer "F.Cu")
		(net "FM_SMB_2_ALERT_GPU_ISO_R_N")
	)
	(via
		(at 183.355742 -119.775478)
		(size 0.4572)
		(drill 0.254)
		(layers "F.Cu" "B.Cu")
		(net "FM_SMB_2_ALERT_GPU_ISO_R_N")
	)
	(via
		(at 19.558 -123.281948)
		(size 0.508)
		(drill 0.254)
		(layers "F.Cu" "B.Cu")
		(net "FM_SMB_2_ALERT_GPU_ISO_R_N")
	)
	(via
		(at 162.87369 -121.253758)
		(size 0.508)
		(drill 0.254)
		(layers "F.Cu" "B.Cu")
		(net "FM_SMB_2_ALERT_GPU_ISO_R_N")
	)
	(via
		(at 22.48408 -377.947428)
		(size 0.508)
		(drill 0.254)
		(layers "F.Cu" "B.Cu")
		(net "FM_SMB_2_ALERT_GPU_ISO_R_N")
	)
	(via
		(at 22.436582 -421.978836)
		(size 0.508)
		(drill 0.254)
		(layers "F.Cu" "B.Cu")
		(net "FM_SMB_2_ALERT_GPU_ISO_R_N")
	)
	(segment
		(start 5.94614 -381.21209)
		(end 5.94614 -402.07565)
		(width 0.12954)
		(layer "B.Cu")
		(net "FM_SMB_2_ALERT_GPU_ISO_R_N")
	)
	(segment
		(start 8.83031 -378.32792)
		(end 5.94614 -381.21209)
		(width 0.12954)
		(layer "B.Cu")
		(net "FM_SMB_2_ALERT_GPU_ISO_R_N")
	)
	(segment
		(start 11.04392 -407.17343)
		(end 11.04392 -413.291528)
		(width 0.12954)
		(layer "B.Cu")
		(net "FM_SMB_2_ALERT_GPU_ISO_R_N")
	)
	(segment
		(start 19.731228 -421.978836)
		(end 22.436582 -421.978836)
		(width 0.12954)
		(layer "B.Cu")
		(net "FM_SMB_2_ALERT_GPU_ISO_R_N")
	)
	(segment
		(start 11.04392 -413.291528)
		(end 19.731228 -421.978836)
		(width 0.12954)
		(layer "B.Cu")
		(net "FM_SMB_2_ALERT_GPU_ISO_R_N")
	)
	(segment
		(start 5.94614 -402.07565)
		(end 11.04392 -407.17343)
		(width 0.12954)
		(layer "B.Cu")
		(net "FM_SMB_2_ALERT_GPU_ISO_R_N")
	)
	(segment
		(start 22.48408 -377.947428)
		(end 22.103588 -378.32792)
		(width 0.12954)
		(layer "B.Cu")
		(net "FM_SMB_2_ALERT_GPU_ISO_R_N")
	)
	(segment
		(start 22.103588 -378.32792)
		(end 8.83031 -378.32792)
		(width 0.12954)
		(layer "B.Cu")
		(net "FM_SMB_2_ALERT_GPU_ISO_R_N")
	)
	(segment
		(start 66.21653 -120.868948)
		(end 65.07353 -122.011948)
		(width 0.127)
		(layer "In6.Cu")
		(net "FM_SMB_2_ALERT_GPU_ISO_R_N")
	)
	(segment
		(start 23.139146 -118.887748)
		(end 19.558 -122.468894)
		(width 0.127)
		(layer "In6.Cu")
		(net "FM_SMB_2_ALERT_GPU_ISO_R_N")
	)
	(segment
		(start 149.7965 -118.95328)
		(end 147.911058 -118.95328)
		(width 0.127)
		(layer "In6.Cu")
		(net "FM_SMB_2_ALERT_GPU_ISO_R_N")
	)
	(segment
		(start 128.5367 -116.6368)
		(end 110.862364 -116.6368)
		(width 0.127)
		(layer "In6.Cu")
		(net "FM_SMB_2_ALERT_GPU_ISO_R_N")
	)
	(segment
		(start 133.731 -117.287548)
		(end 129.187448 -117.287548)
		(width 0.127)
		(layer "In6.Cu")
		(net "FM_SMB_2_ALERT_GPU_ISO_R_N")
	)
	(segment
		(start 147.911058 -118.95328)
		(end 147.27809 -119.586248)
		(width 0.127)
		(layer "In6.Cu")
		(net "FM_SMB_2_ALERT_GPU_ISO_R_N")
	)
	(segment
		(start 65.07353 -122.011948)
		(end 48.64227 -122.011948)
		(width 0.127)
		(layer "In6.Cu")
		(net "FM_SMB_2_ALERT_GPU_ISO_R_N")
	)
	(segment
		(start 147.27809 -119.586248)
		(end 139.9159 -119.586248)
		(width 0.127)
		(layer "In6.Cu")
		(net "FM_SMB_2_ALERT_GPU_ISO_R_N")
	)
	(segment
		(start 153.5938 -120.716548)
		(end 152.8826 -120.005348)
		(width 0.127)
		(layer "In6.Cu")
		(net "FM_SMB_2_ALERT_GPU_ISO_R_N")
	)
	(segment
		(start 157.6832 -120.868948)
		(end 157.5308 -120.716548)
		(width 0.127)
		(layer "In6.Cu")
		(net "FM_SMB_2_ALERT_GPU_ISO_R_N")
	)
	(segment
		(start 162.87369 -121.253758)
		(end 162.41141 -121.253758)
		(width 0.127)
		(layer "In6.Cu")
		(net "FM_SMB_2_ALERT_GPU_ISO_R_N")
	)
	(segment
		(start 162.41141 -121.253758)
		(end 162.0266 -120.868948)
		(width 0.127)
		(layer "In6.Cu")
		(net "FM_SMB_2_ALERT_GPU_ISO_R_N")
	)
	(segment
		(start 48.64227 -122.011948)
		(end 44.14647 -117.516148)
		(width 0.127)
		(layer "In6.Cu")
		(net "FM_SMB_2_ALERT_GPU_ISO_R_N")
	)
	(segment
		(start 140.081 -121.859548)
		(end 140.081 -122.316748)
		(width 0.127)
		(layer "In6.Cu")
		(net "FM_SMB_2_ALERT_GPU_ISO_R_N")
	)
	(segment
		(start 139.17549 -121.453148)
		(end 139.6746 -121.453148)
		(width 0.127)
		(layer "In6.Cu")
		(net "FM_SMB_2_ALERT_GPU_ISO_R_N")
	)
	(segment
		(start 139.9159 -119.586248)
		(end 138.8872 -120.614948)
		(width 0.127)
		(layer "In6.Cu")
		(net "FM_SMB_2_ALERT_GPU_ISO_R_N")
	)
	(segment
		(start 129.187448 -117.287548)
		(end 128.5367 -116.6368)
		(width 0.127)
		(layer "In6.Cu")
		(net "FM_SMB_2_ALERT_GPU_ISO_R_N")
	)
	(segment
		(start 152.8826 -120.005348)
		(end 150.848568 -120.005348)
		(width 0.127)
		(layer "In6.Cu")
		(net "FM_SMB_2_ALERT_GPU_ISO_R_N")
	)
	(segment
		(start 44.14647 -117.516148)
		(end 30.66034 -117.516148)
		(width 0.127)
		(layer "In6.Cu")
		(net "FM_SMB_2_ALERT_GPU_ISO_R_N")
	)
	(segment
		(start 162.0266 -120.868948)
		(end 157.6832 -120.868948)
		(width 0.127)
		(layer "In6.Cu")
		(net "FM_SMB_2_ALERT_GPU_ISO_R_N")
	)
	(segment
		(start 139.6746 -121.453148)
		(end 140.081 -121.859548)
		(width 0.127)
		(layer "In6.Cu")
		(net "FM_SMB_2_ALERT_GPU_ISO_R_N")
	)
	(segment
		(start 138.8872 -120.614948)
		(end 138.8872 -121.164858)
		(width 0.127)
		(layer "In6.Cu")
		(net "FM_SMB_2_ALERT_GPU_ISO_R_N")
	)
	(segment
		(start 106.630216 -120.868948)
		(end 66.21653 -120.868948)
		(width 0.127)
		(layer "In6.Cu")
		(net "FM_SMB_2_ALERT_GPU_ISO_R_N")
	)
	(segment
		(start 138.9634 -122.519948)
		(end 133.731 -117.287548)
		(width 0.127)
		(layer "In6.Cu")
		(net "FM_SMB_2_ALERT_GPU_ISO_R_N")
	)
	(segment
		(start 19.558 -122.468894)
		(end 19.558 -123.281948)
		(width 0.127)
		(layer "In6.Cu")
		(net "FM_SMB_2_ALERT_GPU_ISO_R_N")
	)
	(segment
		(start 150.848568 -120.005348)
		(end 149.7965 -118.95328)
		(width 0.127)
		(layer "In6.Cu")
		(net "FM_SMB_2_ALERT_GPU_ISO_R_N")
	)
	(segment
		(start 29.28874 -118.887748)
		(end 23.139146 -118.887748)
		(width 0.127)
		(layer "In6.Cu")
		(net "FM_SMB_2_ALERT_GPU_ISO_R_N")
	)
	(segment
		(start 138.8872 -121.164858)
		(end 139.17549 -121.453148)
		(width 0.127)
		(layer "In6.Cu")
		(net "FM_SMB_2_ALERT_GPU_ISO_R_N")
	)
	(segment
		(start 30.66034 -117.516148)
		(end 29.28874 -118.887748)
		(width 0.127)
		(layer "In6.Cu")
		(net "FM_SMB_2_ALERT_GPU_ISO_R_N")
	)
	(segment
		(start 139.8778 -122.519948)
		(end 138.9634 -122.519948)
		(width 0.127)
		(layer "In6.Cu")
		(net "FM_SMB_2_ALERT_GPU_ISO_R_N")
	)
	(segment
		(start 157.5308 -120.716548)
		(end 153.5938 -120.716548)
		(width 0.127)
		(layer "In6.Cu")
		(net "FM_SMB_2_ALERT_GPU_ISO_R_N")
	)
	(segment
		(start 140.081 -122.316748)
		(end 139.8778 -122.519948)
		(width 0.127)
		(layer "In6.Cu")
		(net "FM_SMB_2_ALERT_GPU_ISO_R_N")
	)
	(segment
		(start 110.862364 -116.6368)
		(end 106.630216 -120.868948)
		(width 0.127)
		(layer "In6.Cu")
		(net "FM_SMB_2_ALERT_GPU_ISO_R_N")
	)
	(segment
		(start 163.34486 -120.782588)
		(end 164.19576 -120.782588)
		(width 0.127)
		(layer "In13.Cu")
		(net "FM_SMB_2_ALERT_GPU_ISO_R_N")
	)
	(segment
		(start 21.92274 -377.386088)
		(end 21.92274 -348.339918)
		(width 0.127)
		(layer "In13.Cu")
		(net "FM_SMB_2_ALERT_GPU_ISO_R_N")
	)
	(segment
		(start 8.3566 -252.896878)
		(end 8.3566 -195.416678)
		(width 0.127)
		(layer "In13.Cu")
		(net "FM_SMB_2_ALERT_GPU_ISO_R_N")
	)
	(segment
		(start 176.56048 -120.795288)
		(end 176.56048 -120.386348)
		(width 0.127)
		(layer "In13.Cu")
		(net "FM_SMB_2_ALERT_GPU_ISO_R_N")
	)
	(segment
		(start 7.7724 -255.003808)
		(end 7.7724 -253.481078)
		(width 0.127)
		(layer "In13.Cu")
		(net "FM_SMB_2_ALERT_GPU_ISO_R_N")
	)
	(segment
		(start 7.747 -189.628018)
		(end 7.747 -173.420278)
		(width 0.127)
		(layer "In13.Cu")
		(net "FM_SMB_2_ALERT_GPU_ISO_R_N")
	)
	(segment
		(start 8.3566 -255.588008)
		(end 7.7724 -255.003808)
		(width 0.127)
		(layer "In13.Cu")
		(net "FM_SMB_2_ALERT_GPU_ISO_R_N")
	)
	(segment
		(start 164.39134 -120.978168)
		(end 176.3776 -120.978168)
		(width 0.127)
		(layer "In13.Cu")
		(net "FM_SMB_2_ALERT_GPU_ISO_R_N")
	)
	(segment
		(start 182.953152 -119.372888)
		(end 183.355742 -119.775478)
		(width 0.127)
		(layer "In13.Cu")
		(net "FM_SMB_2_ALERT_GPU_ISO_R_N")
	)
	(segment
		(start 22.48408 -377.947428)
		(end 21.92274 -377.386088)
		(width 0.127)
		(layer "In13.Cu")
		(net "FM_SMB_2_ALERT_GPU_ISO_R_N")
	)
	(segment
		(start 8.3566 -195.416678)
		(end 9.2456 -194.527678)
		(width 0.127)
		(layer "In13.Cu")
		(net "FM_SMB_2_ALERT_GPU_ISO_R_N")
	)
	(segment
		(start 10.0838 -324.249288)
		(end 10.0838 -321.755008)
		(width 0.127)
		(layer "In13.Cu")
		(net "FM_SMB_2_ALERT_GPU_ISO_R_N")
	)
	(segment
		(start 17.9832 -154.728418)
		(end 16.3068 -153.052018)
		(width 0.127)
		(layer "In13.Cu")
		(net "FM_SMB_2_ALERT_GPU_ISO_R_N")
	)
	(segment
		(start 164.19576 -120.782588)
		(end 164.39134 -120.978168)
		(width 0.127)
		(layer "In13.Cu")
		(net "FM_SMB_2_ALERT_GPU_ISO_R_N")
	)
	(segment
		(start 17.9832 -163.184078)
		(end 17.9832 -154.728418)
		(width 0.127)
		(layer "In13.Cu")
		(net "FM_SMB_2_ALERT_GPU_ISO_R_N")
	)
	(segment
		(start 7.7724 -253.481078)
		(end 8.3566 -252.896878)
		(width 0.127)
		(layer "In13.Cu")
		(net "FM_SMB_2_ALERT_GPU_ISO_R_N")
	)
	(segment
		(start 162.87369 -121.253758)
		(end 163.34486 -120.782588)
		(width 0.127)
		(layer "In13.Cu")
		(net "FM_SMB_2_ALERT_GPU_ISO_R_N")
	)
	(segment
		(start 178.76774 -119.372888)
		(end 182.953152 -119.372888)
		(width 0.127)
		(layer "In13.Cu")
		(net "FM_SMB_2_ALERT_GPU_ISO_R_N")
	)
	(segment
		(start 7.7724 -326.560688)
		(end 10.0838 -324.249288)
		(width 0.127)
		(layer "In13.Cu")
		(net "FM_SMB_2_ALERT_GPU_ISO_R_N")
	)
	(segment
		(start 10.0838 -321.755008)
		(end 8.3566 -320.027808)
		(width 0.127)
		(layer "In13.Cu")
		(net "FM_SMB_2_ALERT_GPU_ISO_R_N")
	)
	(segment
		(start 16.3068 -125.795278)
		(end 18.82013 -123.281948)
		(width 0.127)
		(layer "In13.Cu")
		(net "FM_SMB_2_ALERT_GPU_ISO_R_N")
	)
	(segment
		(start 21.92274 -348.339918)
		(end 7.7724 -334.189578)
		(width 0.127)
		(layer "In13.Cu")
		(net "FM_SMB_2_ALERT_GPU_ISO_R_N")
	)
	(segment
		(start 7.7724 -334.189578)
		(end 7.7724 -326.560688)
		(width 0.127)
		(layer "In13.Cu")
		(net "FM_SMB_2_ALERT_GPU_ISO_R_N")
	)
	(segment
		(start 7.747 -173.420278)
		(end 17.9832 -163.184078)
		(width 0.127)
		(layer "In13.Cu")
		(net "FM_SMB_2_ALERT_GPU_ISO_R_N")
	)
	(segment
		(start 16.3068 -153.052018)
		(end 16.3068 -125.795278)
		(width 0.127)
		(layer "In13.Cu")
		(net "FM_SMB_2_ALERT_GPU_ISO_R_N")
	)
	(segment
		(start 9.2456 -191.126618)
		(end 7.747 -189.628018)
		(width 0.127)
		(layer "In13.Cu")
		(net "FM_SMB_2_ALERT_GPU_ISO_R_N")
	)
	(segment
		(start 9.2456 -194.527678)
		(end 9.2456 -191.126618)
		(width 0.127)
		(layer "In13.Cu")
		(net "FM_SMB_2_ALERT_GPU_ISO_R_N")
	)
	(segment
		(start 176.3776 -120.978168)
		(end 176.56048 -120.795288)
		(width 0.127)
		(layer "In13.Cu")
		(net "FM_SMB_2_ALERT_GPU_ISO_R_N")
	)
	(segment
		(start 18.82013 -123.281948)
		(end 19.558 -123.281948)
		(width 0.127)
		(layer "In13.Cu")
		(net "FM_SMB_2_ALERT_GPU_ISO_R_N")
	)
	(segment
		(start 176.56048 -120.386348)
		(end 176.7713 -120.175528)
		(width 0.127)
		(layer "In13.Cu")
		(net "FM_SMB_2_ALERT_GPU_ISO_R_N")
	)
	(segment
		(start 177.9651 -120.175528)
		(end 178.76774 -119.372888)
		(width 0.127)
		(layer "In13.Cu")
		(net "FM_SMB_2_ALERT_GPU_ISO_R_N")
	)
	(segment
		(start 8.3566 -320.027808)
		(end 8.3566 -255.588008)
		(width 0.127)
		(layer "In13.Cu")
		(net "FM_SMB_2_ALERT_GPU_ISO_R_N")
	)
	(segment
		(start 176.7713 -120.175528)
		(end 177.9651 -120.175528)
		(width 0.127)
		(layer "In13.Cu")
		(net "FM_SMB_2_ALERT_GPU_ISO_R_N")
	)
	(segment
		(start 116.71808 -395.588998)
		(end 116.71808 -394.338048)
		(width 0.12954)
		(layer "F.Cu")
		(net "FM_SMB_1_ALERT_GPU")
	)
	(segment
		(start 117.368066 -396.798038)
		(end 116.71808 -396.798038)
		(width 0.12954)
		(layer "F.Cu")
		(net "FM_SMB_1_ALERT_GPU")
	)
	(segment
		(start 116.71808 -396.798038)
		(end 116.71808 -395.588998)
		(width 0.12954)
		(layer "F.Cu")
		(net "FM_SMB_1_ALERT_GPU")
	)
	(via
		(at 116.71808 -395.588998)
		(size 0.762)
		(drill 0.381)
		(layers "F.Cu" "B.Cu")
		(net "FM_SMB_1_ALERT_GPU")
	)
	(segment
		(start 184.555638 -120.975374)
		(end 184.955688 -121.375424)
		(width 0.12954)
		(layer "F.Cu")
		(net "FM_SMB_1_ALERT_GPU_ISO_R_N")
	)
	(segment
		(start 23.189438 -422.98747)
		(end 22.935438 -423.24147)
		(width 0.12954)
		(layer "F.Cu")
		(net "FM_SMB_1_ALERT_GPU_ISO_R_N")
	)
	(segment
		(start 22.963378 -420.794688)
		(end 23.189438 -421.020748)
		(width 0.12954)
		(layer "F.Cu")
		(net "FM_SMB_1_ALERT_GPU_ISO_R_N")
	)
	(segment
		(start 23.189438 -421.020748)
		(end 23.189438 -422.98747)
		(width 0.12954)
		(layer "F.Cu")
		(net "FM_SMB_1_ALERT_GPU_ISO_R_N")
	)
	(via
		(at 20.1676 -122.646948)
		(size 0.508)
		(drill 0.254)
		(layers "F.Cu" "B.Cu")
		(net "FM_SMB_1_ALERT_GPU_ISO_R_N")
	)
	(via
		(at 184.955688 -121.375424)
		(size 0.4572)
		(drill 0.254)
		(layers "F.Cu" "B.Cu")
		(net "FM_SMB_1_ALERT_GPU_ISO_R_N")
	)
	(via
		(at 22.48408 -378.836428)
		(size 0.508)
		(drill 0.254)
		(layers "F.Cu" "B.Cu")
		(net "FM_SMB_1_ALERT_GPU_ISO_R_N")
	)
	(via
		(at 162.71748 -122.789188)
		(size 0.508)
		(drill 0.254)
		(layers "F.Cu" "B.Cu")
		(net "FM_SMB_1_ALERT_GPU_ISO_R_N")
	)
	(via
		(at 22.963378 -420.794688)
		(size 0.508)
		(drill 0.254)
		(layers "F.Cu" "B.Cu")
		(net "FM_SMB_1_ALERT_GPU_ISO_R_N")
	)
	(segment
		(start 6.4897 -401.850352)
		(end 11.58748 -406.948132)
		(width 0.12954)
		(layer "B.Cu")
		(net "FM_SMB_1_ALERT_GPU_ISO_R_N")
	)
	(segment
		(start 22.48408 -378.836428)
		(end 22.449028 -378.87148)
		(width 0.12954)
		(layer "B.Cu")
		(net "FM_SMB_1_ALERT_GPU_ISO_R_N")
	)
	(segment
		(start 22.449028 -378.87148)
		(end 9.055608 -378.87148)
		(width 0.12954)
		(layer "B.Cu")
		(net "FM_SMB_1_ALERT_GPU_ISO_R_N")
	)
	(segment
		(start 11.58748 -412.915608)
		(end 19.46656 -420.794688)
		(width 0.12954)
		(layer "B.Cu")
		(net "FM_SMB_1_ALERT_GPU_ISO_R_N")
	)
	(segment
		(start 6.4897 -381.437388)
		(end 6.4897 -401.850352)
		(width 0.12954)
		(layer "B.Cu")
		(net "FM_SMB_1_ALERT_GPU_ISO_R_N")
	)
	(segment
		(start 19.46656 -420.794688)
		(end 22.963378 -420.794688)
		(width 0.12954)
		(layer "B.Cu")
		(net "FM_SMB_1_ALERT_GPU_ISO_R_N")
	)
	(segment
		(start 11.58748 -406.948132)
		(end 11.58748 -412.915608)
		(width 0.12954)
		(layer "B.Cu")
		(net "FM_SMB_1_ALERT_GPU_ISO_R_N")
	)
	(segment
		(start 9.055608 -378.87148)
		(end 6.4897 -381.437388)
		(width 0.12954)
		(layer "B.Cu")
		(net "FM_SMB_1_ALERT_GPU_ISO_R_N")
	)
	(segment
		(start 48.4632 -122.443748)
		(end 43.9674 -117.947948)
		(width 0.127)
		(layer "In6.Cu")
		(net "FM_SMB_1_ALERT_GPU_ISO_R_N")
	)
	(segment
		(start 128.727708 -117.719348)
		(end 128.19888 -117.19052)
		(width 0.127)
		(layer "In6.Cu")
		(net "FM_SMB_1_ALERT_GPU_ISO_R_N")
	)
	(segment
		(start 148.17598 -120.25122)
		(end 145.475452 -122.951748)
		(width 0.127)
		(layer "In6.Cu")
		(net "FM_SMB_1_ALERT_GPU_ISO_R_N")
	)
	(segment
		(start 128.19888 -117.19052)
		(end 110.919514 -117.19052)
		(width 0.127)
		(layer "In6.Cu")
		(net "FM_SMB_1_ALERT_GPU_ISO_R_N")
	)
	(segment
		(start 66.3956 -121.300748)
		(end 65.2526 -122.443748)
		(width 0.127)
		(layer "In6.Cu")
		(net "FM_SMB_1_ALERT_GPU_ISO_R_N")
	)
	(segment
		(start 160.3248 -121.986548)
		(end 157.629352 -121.986548)
		(width 0.127)
		(layer "In6.Cu")
		(net "FM_SMB_1_ALERT_GPU_ISO_R_N")
	)
	(segment
		(start 133.55193 -117.719348)
		(end 128.727708 -117.719348)
		(width 0.127)
		(layer "In6.Cu")
		(net "FM_SMB_1_ALERT_GPU_ISO_R_N")
	)
	(segment
		(start 43.9674 -117.947948)
		(end 30.83941 -117.947948)
		(width 0.127)
		(layer "In6.Cu")
		(net "FM_SMB_1_ALERT_GPU_ISO_R_N")
	)
	(segment
		(start 65.2526 -122.443748)
		(end 48.4632 -122.443748)
		(width 0.127)
		(layer "In6.Cu")
		(net "FM_SMB_1_ALERT_GPU_ISO_R_N")
	)
	(segment
		(start 138.78433 -122.951748)
		(end 133.55193 -117.719348)
		(width 0.127)
		(layer "In6.Cu")
		(net "FM_SMB_1_ALERT_GPU_ISO_R_N")
	)
	(segment
		(start 161.12744 -122.789188)
		(end 160.3248 -121.986548)
		(width 0.127)
		(layer "In6.Cu")
		(net "FM_SMB_1_ALERT_GPU_ISO_R_N")
	)
	(segment
		(start 29.46781 -119.319548)
		(end 23.495 -119.319548)
		(width 0.127)
		(layer "In6.Cu")
		(net "FM_SMB_1_ALERT_GPU_ISO_R_N")
	)
	(segment
		(start 157.629352 -121.986548)
		(end 157.197552 -122.418348)
		(width 0.127)
		(layer "In6.Cu")
		(net "FM_SMB_1_ALERT_GPU_ISO_R_N")
	)
	(segment
		(start 150.428198 -120.884188)
		(end 149.79523 -120.25122)
		(width 0.127)
		(layer "In6.Cu")
		(net "FM_SMB_1_ALERT_GPU_ISO_R_N")
	)
	(segment
		(start 106.809286 -121.300748)
		(end 66.3956 -121.300748)
		(width 0.127)
		(layer "In6.Cu")
		(net "FM_SMB_1_ALERT_GPU_ISO_R_N")
	)
	(segment
		(start 30.83941 -117.947948)
		(end 29.46781 -119.319548)
		(width 0.127)
		(layer "In6.Cu")
		(net "FM_SMB_1_ALERT_GPU_ISO_R_N")
	)
	(segment
		(start 145.475452 -122.951748)
		(end 138.78433 -122.951748)
		(width 0.127)
		(layer "In6.Cu")
		(net "FM_SMB_1_ALERT_GPU_ISO_R_N")
	)
	(segment
		(start 149.79523 -120.25122)
		(end 148.17598 -120.25122)
		(width 0.127)
		(layer "In6.Cu")
		(net "FM_SMB_1_ALERT_GPU_ISO_R_N")
	)
	(segment
		(start 162.71748 -122.789188)
		(end 161.12744 -122.789188)
		(width 0.127)
		(layer "In6.Cu")
		(net "FM_SMB_1_ALERT_GPU_ISO_R_N")
	)
	(segment
		(start 157.197552 -122.418348)
		(end 153.929588 -122.418348)
		(width 0.127)
		(layer "In6.Cu")
		(net "FM_SMB_1_ALERT_GPU_ISO_R_N")
	)
	(segment
		(start 153.929588 -122.418348)
		(end 152.395428 -120.884188)
		(width 0.127)
		(layer "In6.Cu")
		(net "FM_SMB_1_ALERT_GPU_ISO_R_N")
	)
	(segment
		(start 152.395428 -120.884188)
		(end 150.428198 -120.884188)
		(width 0.127)
		(layer "In6.Cu")
		(net "FM_SMB_1_ALERT_GPU_ISO_R_N")
	)
	(segment
		(start 110.919514 -117.19052)
		(end 106.809286 -121.300748)
		(width 0.127)
		(layer "In6.Cu")
		(net "FM_SMB_1_ALERT_GPU_ISO_R_N")
	)
	(segment
		(start 23.495 -119.319548)
		(end 20.1676 -122.646948)
		(width 0.127)
		(layer "In6.Cu")
		(net "FM_SMB_1_ALERT_GPU_ISO_R_N")
	)
	(segment
		(start 162.71748 -122.789188)
		(end 163.1569 -123.228608)
		(width 0.127)
		(layer "In13.Cu")
		(net "FM_SMB_1_ALERT_GPU_ISO_R_N")
	)
	(segment
		(start 7.9248 -195.237608)
		(end 8.8138 -194.348608)
		(width 0.127)
		(layer "In13.Cu")
		(net "FM_SMB_1_ALERT_GPU_ISO_R_N")
	)
	(segment
		(start 15.875 -153.231088)
		(end 15.875 -125.565408)
		(width 0.127)
		(layer "In13.Cu")
		(net "FM_SMB_1_ALERT_GPU_ISO_R_N")
	)
	(segment
		(start 17.5514 -154.907488)
		(end 15.875 -153.231088)
		(width 0.127)
		(layer "In13.Cu")
		(net "FM_SMB_1_ALERT_GPU_ISO_R_N")
	)
	(segment
		(start 171.57192 -122.32894)
		(end 171.811442 -122.568462)
		(width 0.127)
		(layer "In13.Cu")
		(net "FM_SMB_1_ALERT_GPU_ISO_R_N")
	)
	(segment
		(start 174.51324 -122.819668)
		(end 175.11014 -122.222768)
		(width 0.127)
		(layer "In13.Cu")
		(net "FM_SMB_1_ALERT_GPU_ISO_R_N")
	)
	(segment
		(start 173.571154 -122.568462)
		(end 173.82236 -122.819668)
		(width 0.127)
		(layer "In13.Cu")
		(net "FM_SMB_1_ALERT_GPU_ISO_R_N")
	)
	(segment
		(start 9.652 -324.070218)
		(end 9.652 -321.934078)
		(width 0.127)
		(layer "In13.Cu")
		(net "FM_SMB_1_ALERT_GPU_ISO_R_N")
	)
	(segment
		(start 164.40531 -123.228608)
		(end 165.065456 -122.568462)
		(width 0.127)
		(layer "In13.Cu")
		(net "FM_SMB_1_ALERT_GPU_ISO_R_N")
	)
	(segment
		(start 184.555384 -121.775728)
		(end 184.955688 -121.375424)
		(width 0.127)
		(layer "In13.Cu")
		(net "FM_SMB_1_ALERT_GPU_ISO_R_N")
	)
	(segment
		(start 7.3152 -173.241208)
		(end 17.5514 -163.005008)
		(width 0.127)
		(layer "In13.Cu")
		(net "FM_SMB_1_ALERT_GPU_ISO_R_N")
	)
	(segment
		(start 7.9248 -320.206878)
		(end 7.9248 -255.767078)
		(width 0.127)
		(layer "In13.Cu")
		(net "FM_SMB_1_ALERT_GPU_ISO_R_N")
	)
	(segment
		(start 7.3406 -326.381618)
		(end 9.652 -324.070218)
		(width 0.127)
		(layer "In13.Cu")
		(net "FM_SMB_1_ALERT_GPU_ISO_R_N")
	)
	(segment
		(start 171.811442 -122.568462)
		(end 173.571154 -122.568462)
		(width 0.127)
		(layer "In13.Cu")
		(net "FM_SMB_1_ALERT_GPU_ISO_R_N")
	)
	(segment
		(start 7.3406 -255.182878)
		(end 7.3406 -253.302008)
		(width 0.127)
		(layer "In13.Cu")
		(net "FM_SMB_1_ALERT_GPU_ISO_R_N")
	)
	(segment
		(start 177.75428 -122.222768)
		(end 178.20132 -121.775728)
		(width 0.127)
		(layer "In13.Cu")
		(net "FM_SMB_1_ALERT_GPU_ISO_R_N")
	)
	(segment
		(start 17.5514 -163.005008)
		(end 17.5514 -154.907488)
		(width 0.127)
		(layer "In13.Cu")
		(net "FM_SMB_1_ALERT_GPU_ISO_R_N")
	)
	(segment
		(start 21.49094 -348.518988)
		(end 7.3406 -334.368648)
		(width 0.127)
		(layer "In13.Cu")
		(net "FM_SMB_1_ALERT_GPU_ISO_R_N")
	)
	(segment
		(start 9.652 -321.934078)
		(end 7.9248 -320.206878)
		(width 0.127)
		(layer "In13.Cu")
		(net "FM_SMB_1_ALERT_GPU_ISO_R_N")
	)
	(segment
		(start 163.1569 -123.228608)
		(end 164.40531 -123.228608)
		(width 0.127)
		(layer "In13.Cu")
		(net "FM_SMB_1_ALERT_GPU_ISO_R_N")
	)
	(segment
		(start 8.8138 -191.305688)
		(end 7.3152 -189.807088)
		(width 0.127)
		(layer "In13.Cu")
		(net "FM_SMB_1_ALERT_GPU_ISO_R_N")
	)
	(segment
		(start 175.11014 -122.222768)
		(end 177.75428 -122.222768)
		(width 0.127)
		(layer "In13.Cu")
		(net "FM_SMB_1_ALERT_GPU_ISO_R_N")
	)
	(segment
		(start 7.3406 -334.368648)
		(end 7.3406 -326.381618)
		(width 0.127)
		(layer "In13.Cu")
		(net "FM_SMB_1_ALERT_GPU_ISO_R_N")
	)
	(segment
		(start 21.49094 -377.843288)
		(end 21.49094 -348.518988)
		(width 0.127)
		(layer "In13.Cu")
		(net "FM_SMB_1_ALERT_GPU_ISO_R_N")
	)
	(segment
		(start 18.79346 -122.646948)
		(end 20.1676 -122.646948)
		(width 0.127)
		(layer "In13.Cu")
		(net "FM_SMB_1_ALERT_GPU_ISO_R_N")
	)
	(segment
		(start 170.838876 -122.568462)
		(end 171.078398 -122.32894)
		(width 0.127)
		(layer "In13.Cu")
		(net "FM_SMB_1_ALERT_GPU_ISO_R_N")
	)
	(segment
		(start 173.82236 -122.819668)
		(end 174.51324 -122.819668)
		(width 0.127)
		(layer "In13.Cu")
		(net "FM_SMB_1_ALERT_GPU_ISO_R_N")
	)
	(segment
		(start 7.9248 -255.767078)
		(end 7.3406 -255.182878)
		(width 0.127)
		(layer "In13.Cu")
		(net "FM_SMB_1_ALERT_GPU_ISO_R_N")
	)
	(segment
		(start 8.8138 -194.348608)
		(end 8.8138 -191.305688)
		(width 0.127)
		(layer "In13.Cu")
		(net "FM_SMB_1_ALERT_GPU_ISO_R_N")
	)
	(segment
		(start 7.3406 -253.302008)
		(end 7.9248 -252.717808)
		(width 0.127)
		(layer "In13.Cu")
		(net "FM_SMB_1_ALERT_GPU_ISO_R_N")
	)
	(segment
		(start 171.078398 -122.32894)
		(end 171.57192 -122.32894)
		(width 0.127)
		(layer "In13.Cu")
		(net "FM_SMB_1_ALERT_GPU_ISO_R_N")
	)
	(segment
		(start 15.875 -125.565408)
		(end 18.79346 -122.646948)
		(width 0.127)
		(layer "In13.Cu")
		(net "FM_SMB_1_ALERT_GPU_ISO_R_N")
	)
	(segment
		(start 7.9248 -252.717808)
		(end 7.9248 -195.237608)
		(width 0.127)
		(layer "In13.Cu")
		(net "FM_SMB_1_ALERT_GPU_ISO_R_N")
	)
	(segment
		(start 165.065456 -122.568462)
		(end 170.838876 -122.568462)
		(width 0.127)
		(layer "In13.Cu")
		(net "FM_SMB_1_ALERT_GPU_ISO_R_N")
	)
	(segment
		(start 22.48408 -378.836428)
		(end 21.49094 -377.843288)
		(width 0.127)
		(layer "In13.Cu")
		(net "FM_SMB_1_ALERT_GPU_ISO_R_N")
	)
	(segment
		(start 7.3152 -189.807088)
		(end 7.3152 -173.241208)
		(width 0.127)
		(layer "In13.Cu")
		(net "FM_SMB_1_ALERT_GPU_ISO_R_N")
	)
	(segment
		(start 178.20132 -121.775728)
		(end 184.555384 -121.775728)
		(width 0.127)
		(layer "In13.Cu")
		(net "FM_SMB_1_ALERT_GPU_ISO_R_N")
	)
	(segment
		(start 113.16208 -393.048998)
		(end 113.16208 -394.258038)
		(width 0.12954)
		(layer "F.Cu")
		(net "FM_SMB_2_ALERT_GPU")
	)
	(segment
		(start 113.812066 -394.258038)
		(end 113.16208 -394.258038)
		(width 0.12954)
		(layer "F.Cu")
		(net "FM_SMB_2_ALERT_GPU")
	)
	(segment
		(start 114.41303 -393.048998)
		(end 113.16208 -393.048998)
		(width 0.12954)
		(layer "F.Cu")
		(net "FM_SMB_2_ALERT_GPU")
	)
	(via
		(at 113.16208 -393.048998)
		(size 0.762)
		(drill 0.381)
		(layers "F.Cu" "B.Cu")
		(net "FM_SMB_2_ALERT_GPU")
	)
	(segment
		(start 30.240732 -416.016948)
		(end 31.491682 -416.016948)
		(width 0.12954)
		(layer "F.Cu")
		(net "FM_GPU_PWRGD_N")
	)
	(segment
		(start 29.031692 -416.016948)
		(end 30.240732 -416.016948)
		(width 0.12954)
		(layer "F.Cu")
		(net "FM_GPU_PWRGD_N")
	)
	(segment
		(start 29.031692 -416.666934)
		(end 29.031692 -416.016948)
		(width 0.12954)
		(layer "F.Cu")
		(net "FM_GPU_PWRGD_N")
	)
	(via
		(at 30.240732 -416.016948)
		(size 0.762)
		(drill 0.381)
		(layers "F.Cu" "B.Cu")
		(net "FM_GPU_PWRGD_N")
	)
	(segment
		(start 26.5176 -414.62579)
		(end 26.015442 -415.127948)
		(width 0.12954)
		(layer "F.Cu")
		(net "FM_GPU_PWRGD_ISO")
	)
	(segment
		(start 26.015442 -415.127948)
		(end 24.446992 -415.127948)
		(width 0.12954)
		(layer "F.Cu")
		(net "FM_GPU_PWRGD_ISO")
	)
	(segment
		(start 24.446992 -414.111948)
		(end 24.446992 -415.127948)
		(width 0.12954)
		(layer "F.Cu")
		(net "FM_GPU_PWRGD_ISO")
	)
	(segment
		(start 27.131772 -414.929066)
		(end 27.131772 -415.366962)
		(width 0.12954)
		(layer "F.Cu")
		(net "FM_GPU_PWRGD_ISO")
	)
	(segment
		(start 26.828496 -414.62579)
		(end 27.131772 -414.929066)
		(width 0.12954)
		(layer "F.Cu")
		(net "FM_GPU_PWRGD_ISO")
	)
	(segment
		(start 26.5176 -414.62579)
		(end 26.828496 -414.62579)
		(width 0.12954)
		(layer "F.Cu")
		(net "FM_GPU_PWRGD_ISO")
	)
	(via
		(at 26.5176 -414.62579)
		(size 0.508)
		(drill 0.254)
		(layers "F.Cu" "B.Cu")
		(net "FM_GPU_PWRGD_ISO")
	)
	(via
		(at 144.09928 -115.560348)
		(size 0.508)
		(drill 0.254)
		(layers "F.Cu" "B.Cu")
		(net "FM_GPU_PWRGD_ISO")
	)
	(via
		(at 163.63188 -109.565948)
		(size 0.508)
		(drill 0.254)
		(layers "F.Cu" "B.Cu")
		(net "FM_GPU_PWRGD_ISO")
	)
	(segment
		(start 164.24783 -109.565948)
		(end 163.63188 -109.565948)
		(width 0.12954)
		(layer "B.Cu")
		(net "FM_GPU_PWRGD_ISO")
	)
	(segment
		(start 162.36188 -110.277148)
		(end 162.92068 -110.277148)
		(width 0.127)
		(layer "In4.Cu")
		(net "FM_GPU_PWRGD_ISO")
	)
	(segment
		(start 155.095448 -111.473488)
		(end 161.16554 -111.473488)
		(width 0.127)
		(layer "In4.Cu")
		(net "FM_GPU_PWRGD_ISO")
	)
	(segment
		(start 145.90776 -115.18138)
		(end 145.90776 -113.751868)
		(width 0.127)
		(layer "In4.Cu")
		(net "FM_GPU_PWRGD_ISO")
	)
	(segment
		(start 148.636228 -111.0234)
		(end 154.64536 -111.0234)
		(width 0.127)
		(layer "In4.Cu")
		(net "FM_GPU_PWRGD_ISO")
	)
	(segment
		(start 162.92068 -110.277148)
		(end 163.63188 -109.565948)
		(width 0.127)
		(layer "In4.Cu")
		(net "FM_GPU_PWRGD_ISO")
	)
	(segment
		(start 145.90776 -113.751868)
		(end 148.636228 -111.0234)
		(width 0.127)
		(layer "In4.Cu")
		(net "FM_GPU_PWRGD_ISO")
	)
	(segment
		(start 154.64536 -111.0234)
		(end 155.095448 -111.473488)
		(width 0.127)
		(layer "In4.Cu")
		(net "FM_GPU_PWRGD_ISO")
	)
	(segment
		(start 145.528792 -115.560348)
		(end 145.90776 -115.18138)
		(width 0.127)
		(layer "In4.Cu")
		(net "FM_GPU_PWRGD_ISO")
	)
	(segment
		(start 161.16554 -111.473488)
		(end 162.36188 -110.277148)
		(width 0.127)
		(layer "In4.Cu")
		(net "FM_GPU_PWRGD_ISO")
	)
	(segment
		(start 144.09928 -115.560348)
		(end 145.528792 -115.560348)
		(width 0.127)
		(layer "In4.Cu")
		(net "FM_GPU_PWRGD_ISO")
	)
	(segment
		(start 18.309844 -117.005608)
		(end 51.34356 -117.005608)
		(width 0.127)
		(layer "In13.Cu")
		(net "FM_GPU_PWRGD_ISO")
	)
	(segment
		(start 23.513542 -417.629848)
		(end 22.599904 -417.629848)
		(width 0.127)
		(layer "In13.Cu")
		(net "FM_GPU_PWRGD_ISO")
	)
	(segment
		(start 138.32586 -113.2078)
		(end 141.746732 -113.2078)
		(width 0.127)
		(layer "In13.Cu")
		(net "FM_GPU_PWRGD_ISO")
	)
	(segment
		(start 16.077692 -383.299208)
		(end 18.477992 -380.898908)
		(width 0.127)
		(layer "In13.Cu")
		(net "FM_GPU_PWRGD_ISO")
	)
	(segment
		(start 4.01193 -154.749246)
		(end 4.29133 -154.469846)
		(width 0.127)
		(layer "In13.Cu")
		(net "FM_GPU_PWRGD_ISO")
	)
	(segment
		(start 18.477992 -380.898908)
		(end 18.477992 -359.457752)
		(width 0.127)
		(layer "In13.Cu")
		(net "FM_GPU_PWRGD_ISO")
	)
	(segment
		(start 51.34356 -117.005608)
		(end 51.44516 -116.904008)
		(width 0.127)
		(layer "In13.Cu")
		(net "FM_GPU_PWRGD_ISO")
	)
	(segment
		(start 12.918948 -353.898708)
		(end 7.176008 -353.898708)
		(width 0.127)
		(layer "In13.Cu")
		(net "FM_GPU_PWRGD_ISO")
	)
	(segment
		(start 18.0086 -402.90496)
		(end 16.077692 -400.974052)
		(width 0.127)
		(layer "In13.Cu")
		(net "FM_GPU_PWRGD_ISO")
	)
	(segment
		(start 69.1896 -117.922548)
		(end 91.82608 -117.922548)
		(width 0.127)
		(layer "In13.Cu")
		(net "FM_GPU_PWRGD_ISO")
	)
	(segment
		(start 136.167368 -111.049308)
		(end 138.32586 -113.2078)
		(width 0.127)
		(layer "In13.Cu")
		(net "FM_GPU_PWRGD_ISO")
	)
	(segment
		(start 18.477992 -359.457752)
		(end 12.918948 -353.898708)
		(width 0.127)
		(layer "In13.Cu")
		(net "FM_GPU_PWRGD_ISO")
	)
	(segment
		(start 4.35864 -164.806884)
		(end 4.01193 -164.460174)
		(width 0.127)
		(layer "In13.Cu")
		(net "FM_GPU_PWRGD_ISO")
	)
	(segment
		(start 106.12628 -113.401348)
		(end 131.65328 -113.401348)
		(width 0.127)
		(layer "In13.Cu")
		(net "FM_GPU_PWRGD_ISO")
	)
	(segment
		(start 26.5176 -414.62579)
		(end 23.513542 -417.629848)
		(width 0.127)
		(layer "In13.Cu")
		(net "FM_GPU_PWRGD_ISO")
	)
	(segment
		(start 67.91198 -116.644928)
		(end 69.1896 -117.922548)
		(width 0.127)
		(layer "In13.Cu")
		(net "FM_GPU_PWRGD_ISO")
	)
	(segment
		(start 91.82608 -117.922548)
		(end 94.16288 -115.585748)
		(width 0.127)
		(layer "In13.Cu")
		(net "FM_GPU_PWRGD_ISO")
	)
	(segment
		(start 56.63692 -116.904008)
		(end 56.896 -116.644928)
		(width 0.127)
		(layer "In13.Cu")
		(net "FM_GPU_PWRGD_ISO")
	)
	(segment
		(start 16.077692 -400.974052)
		(end 16.077692 -383.299208)
		(width 0.127)
		(layer "In13.Cu")
		(net "FM_GPU_PWRGD_ISO")
	)
	(segment
		(start 131.65328 -113.401348)
		(end 134.00532 -111.049308)
		(width 0.127)
		(layer "In13.Cu")
		(net "FM_GPU_PWRGD_ISO")
	)
	(segment
		(start 7.176008 -353.898708)
		(end 4.35864 -351.08134)
		(width 0.127)
		(layer "In13.Cu")
		(net "FM_GPU_PWRGD_ISO")
	)
	(segment
		(start 94.16288 -115.585748)
		(end 103.94188 -115.585748)
		(width 0.127)
		(layer "In13.Cu")
		(net "FM_GPU_PWRGD_ISO")
	)
	(segment
		(start 56.896 -116.644928)
		(end 67.91198 -116.644928)
		(width 0.127)
		(layer "In13.Cu")
		(net "FM_GPU_PWRGD_ISO")
	)
	(segment
		(start 103.94188 -115.585748)
		(end 106.12628 -113.401348)
		(width 0.127)
		(layer "In13.Cu")
		(net "FM_GPU_PWRGD_ISO")
	)
	(segment
		(start 4.29133 -131.024122)
		(end 18.309844 -117.005608)
		(width 0.127)
		(layer "In13.Cu")
		(net "FM_GPU_PWRGD_ISO")
	)
	(segment
		(start 18.0086 -413.038544)
		(end 18.0086 -402.90496)
		(width 0.127)
		(layer "In13.Cu")
		(net "FM_GPU_PWRGD_ISO")
	)
	(segment
		(start 134.00532 -111.049308)
		(end 136.167368 -111.049308)
		(width 0.127)
		(layer "In13.Cu")
		(net "FM_GPU_PWRGD_ISO")
	)
	(segment
		(start 4.29133 -154.469846)
		(end 4.29133 -131.024122)
		(width 0.127)
		(layer "In13.Cu")
		(net "FM_GPU_PWRGD_ISO")
	)
	(segment
		(start 51.44516 -116.904008)
		(end 56.63692 -116.904008)
		(width 0.127)
		(layer "In13.Cu")
		(net "FM_GPU_PWRGD_ISO")
	)
	(segment
		(start 22.599904 -417.629848)
		(end 18.0086 -413.038544)
		(width 0.127)
		(layer "In13.Cu")
		(net "FM_GPU_PWRGD_ISO")
	)
	(segment
		(start 4.35864 -351.08134)
		(end 4.35864 -164.806884)
		(width 0.127)
		(layer "In13.Cu")
		(net "FM_GPU_PWRGD_ISO")
	)
	(segment
		(start 141.746732 -113.2078)
		(end 144.09928 -115.560348)
		(width 0.127)
		(layer "In13.Cu")
		(net "FM_GPU_PWRGD_ISO")
	)
	(segment
		(start 4.01193 -164.460174)
		(end 4.01193 -154.749246)
		(width 0.127)
		(layer "In13.Cu")
		(net "FM_GPU_PWRGD_ISO")
	)
	(segment
		(start 26.496772 -416.016948)
		(end 24.573992 -416.016948)
		(width 0.12954)
		(layer "F.Cu")
		(net "FM_GPU_PWRGD")
	)
	(segment
		(start 24.446992 -416.143948)
		(end 24.446992 -417.159948)
		(width 0.12954)
		(layer "F.Cu")
		(net "FM_GPU_PWRGD")
	)
	(segment
		(start 24.573992 -416.016948)
		(end 24.446992 -416.143948)
		(width 0.12954)
		(layer "F.Cu")
		(net "FM_GPU_PWRGD")
	)
	(segment
		(start 27.131772 -416.016948)
		(end 26.496772 -416.016948)
		(width 0.12954)
		(layer "F.Cu")
		(net "FM_GPU_PWRGD")
	)
	(via
		(at 96.56318 -421.640508)
		(size 0.508)
		(drill 0.254)
		(layers "F.Cu" "B.Cu")
		(net "FM_GPU_PWRGD")
	)
	(via
		(at 26.496772 -416.016948)
		(size 0.508)
		(drill 0.254)
		(layers "F.Cu" "B.Cu")
		(net "FM_GPU_PWRGD")
	)
	(segment
		(start 100.64242 -409.9687)
		(end 100.64242 -413.553148)
		(width 0.127)
		(layer "In6.Cu")
		(net "FM_GPU_PWRGD")
	)
	(segment
		(start 29.09824 -410.261308)
		(end 34.172652 -410.261308)
		(width 0.127)
		(layer "In6.Cu")
		(net "FM_GPU_PWRGD")
	)
	(segment
		(start 34.172652 -410.261308)
		(end 38.610032 -405.823928)
		(width 0.127)
		(layer "In6.Cu")
		(net "FM_GPU_PWRGD")
	)
	(segment
		(start 96.497648 -405.823928)
		(end 100.64242 -409.9687)
		(width 0.127)
		(layer "In6.Cu")
		(net "FM_GPU_PWRGD")
	)
	(segment
		(start 26.48204 -416.016948)
		(end 25.89022 -415.425128)
		(width 0.127)
		(layer "In6.Cu")
		(net "FM_GPU_PWRGD")
	)
	(segment
		(start 96.85782 -421.640508)
		(end 96.56318 -421.640508)
		(width 0.127)
		(layer "In6.Cu")
		(net "FM_GPU_PWRGD")
	)
	(segment
		(start 101.93274 -416.565588)
		(end 96.85782 -421.640508)
		(width 0.127)
		(layer "In6.Cu")
		(net "FM_GPU_PWRGD")
	)
	(segment
		(start 38.610032 -405.823928)
		(end 96.497648 -405.823928)
		(width 0.127)
		(layer "In6.Cu")
		(net "FM_GPU_PWRGD")
	)
	(segment
		(start 101.93274 -414.843468)
		(end 101.93274 -416.565588)
		(width 0.127)
		(layer "In6.Cu")
		(net "FM_GPU_PWRGD")
	)
	(segment
		(start 100.64242 -413.553148)
		(end 101.93274 -414.843468)
		(width 0.127)
		(layer "In6.Cu")
		(net "FM_GPU_PWRGD")
	)
	(segment
		(start 26.496772 -416.016948)
		(end 26.48204 -416.016948)
		(width 0.127)
		(layer "In6.Cu")
		(net "FM_GPU_PWRGD")
	)
	(segment
		(start 25.89022 -415.425128)
		(end 25.89022 -413.469328)
		(width 0.127)
		(layer "In6.Cu")
		(net "FM_GPU_PWRGD")
	)
	(segment
		(start 25.89022 -413.469328)
		(end 29.09824 -410.261308)
		(width 0.127)
		(layer "In6.Cu")
		(net "FM_GPU_PWRGD")
	)
	(segment
		(start 85.649816 -424.689524)
		(end 85.649816 -423.374312)
		(width 0.127)
		(layer "In15.Cu")
		(net "FM_GPU_PWRGD")
	)
	(segment
		(start 95.82912 -422.775888)
		(end 96.56318 -422.041828)
		(width 0.127)
		(layer "In15.Cu")
		(net "FM_GPU_PWRGD")
	)
	(segment
		(start 85.65007 -424.689778)
		(end 85.649816 -424.689524)
		(width 0.127)
		(layer "In15.Cu")
		(net "FM_GPU_PWRGD")
	)
	(segment
		(start 96.56318 -422.041828)
		(end 96.56318 -421.640508)
		(width 0.127)
		(layer "In15.Cu")
		(net "FM_GPU_PWRGD")
	)
	(segment
		(start 85.649816 -423.374312)
		(end 86.24824 -422.775888)
		(width 0.127)
		(layer "In15.Cu")
		(net "FM_GPU_PWRGD")
	)
	(segment
		(start 86.24824 -422.775888)
		(end 95.82912 -422.775888)
		(width 0.127)
		(layer "In15.Cu")
		(net "FM_GPU_PWRGD")
	)
	(segment
		(start 118.72722 -421.241728)
		(end 119.44604 -420.522908)
		(width 0.12954)
		(layer "F.Cu")
		(net "FM_GPU_PWR_EN_R1")
	)
	(segment
		(start 118.447566 -418.043614)
		(end 117.36324 -418.043614)
		(width 0.12954)
		(layer "F.Cu")
		(net "FM_GPU_PWR_EN_R1")
	)
	(segment
		(start 118.72722 -421.955468)
		(end 119.47017 -421.955468)
		(width 0.12954)
		(layer "F.Cu")
		(net "FM_GPU_PWR_EN_R1")
	)
	(segment
		(start 119.47017 -421.955468)
		(end 119.97817 -421.447468)
		(width 0.12954)
		(layer "F.Cu")
		(net "FM_GPU_PWR_EN_R1")
	)
	(segment
		(start 119.44604 -419.042088)
		(end 118.447566 -418.043614)
		(width 0.12954)
		(layer "F.Cu")
		(net "FM_GPU_PWR_EN_R1")
	)
	(segment
		(start 119.97817 -422.463468)
		(end 119.97817 -421.447468)
		(width 0.12954)
		(layer "F.Cu")
		(net "FM_GPU_PWR_EN_R1")
	)
	(segment
		(start 119.44604 -420.522908)
		(end 119.44604 -419.042088)
		(width 0.12954)
		(layer "F.Cu")
		(net "FM_GPU_PWR_EN_R1")
	)
	(segment
		(start 119.97817 -422.463468)
		(end 119.97817 -423.479468)
		(width 0.12954)
		(layer "F.Cu")
		(net "FM_GPU_PWR_EN_R1")
	)
	(segment
		(start 118.72722 -421.955468)
		(end 118.72722 -421.241728)
		(width 0.12954)
		(layer "F.Cu")
		(net "FM_GPU_PWR_EN_R1")
	)
	(via
		(at 118.72722 -421.955468)
		(size 0.762)
		(drill 0.381)
		(layers "F.Cu" "B.Cu")
		(net "FM_GPU_PWR_EN_R1")
	)
	(segment
		(start 119.78386 -426.075348)
		(end 119.96039 -426.075348)
		(width 0.12954)
		(layer "F.Cu")
		(net "FM_GPU_PWR_EN_R")
	)
	(segment
		(start 158.67888 -104.485948)
		(end 159.31388 -103.850948)
		(width 0.12954)
		(layer "F.Cu")
		(net "FM_GPU_PWR_EN_R")
	)
	(segment
		(start 114.28476 -418.442648)
		(end 114.683794 -418.043614)
		(width 0.12954)
		(layer "F.Cu")
		(net "FM_GPU_PWR_EN_R")
	)
	(segment
		(start 163.61283 -103.850948)
		(end 164.24783 -104.485948)
		(width 0.12954)
		(layer "F.Cu")
		(net "FM_GPU_PWR_EN_R")
	)
	(segment
		(start 159.31388 -103.850948)
		(end 163.61283 -103.850948)
		(width 0.12954)
		(layer "F.Cu")
		(net "FM_GPU_PWR_EN_R")
	)
	(segment
		(start 118.48084 -424.772328)
		(end 119.78386 -426.075348)
		(width 0.12954)
		(layer "F.Cu")
		(net "FM_GPU_PWR_EN_R")
	)
	(segment
		(start 114.683794 -418.043614)
		(end 115.46332 -418.043614)
		(width 0.12954)
		(layer "F.Cu")
		(net "FM_GPU_PWR_EN_R")
	)
	(segment
		(start 158.55188 -104.485948)
		(end 158.67888 -104.485948)
		(width 0.12954)
		(layer "F.Cu")
		(net "FM_GPU_PWR_EN_R")
	)
	(segment
		(start 119.96039 -425.059348)
		(end 119.96039 -426.075348)
		(width 0.12954)
		(layer "F.Cu")
		(net "FM_GPU_PWR_EN_R")
	)
	(via
		(at 45.179234 -113.581688)
		(size 0.508)
		(drill 0.254)
		(layers "F.Cu" "B.Cu")
		(net "FM_GPU_PWR_EN_R")
	)
	(via
		(at 114.28476 -418.442648)
		(size 0.508)
		(drill 0.254)
		(layers "F.Cu" "B.Cu")
		(net "FM_GPU_PWR_EN_R")
	)
	(via
		(at 118.48084 -424.772328)
		(size 0.508)
		(drill 0.254)
		(layers "F.Cu" "B.Cu")
		(net "FM_GPU_PWR_EN_R")
	)
	(via
		(at 9.77138 -174.782988)
		(size 0.508)
		(drill 0.254)
		(layers "F.Cu" "B.Cu")
		(net "FM_GPU_PWR_EN_R")
	)
	(via
		(at 158.55188 -104.485948)
		(size 0.508)
		(drill 0.254)
		(layers "F.Cu" "B.Cu")
		(net "FM_GPU_PWR_EN_R")
	)
	(segment
		(start 118.48084 -422.638728)
		(end 114.28476 -418.442648)
		(width 0.127)
		(layer "In4.Cu")
		(net "FM_GPU_PWR_EN_R")
	)
	(segment
		(start 118.48084 -424.772328)
		(end 118.48084 -422.638728)
		(width 0.127)
		(layer "In4.Cu")
		(net "FM_GPU_PWR_EN_R")
	)
	(segment
		(start 31.24708 -366.554258)
		(end 58.34888 -393.656058)
		(width 0.127)
		(layer "In6.Cu")
		(net "FM_GPU_PWR_EN_R")
	)
	(segment
		(start 11.773916 -321.984116)
		(end 12.63396 -322.84416)
		(width 0.127)
		(layer "In6.Cu")
		(net "FM_GPU_PWR_EN_R")
	)
	(segment
		(start 115.8494 -403.3774)
		(end 115.8494 -404.876)
		(width 0.127)
		(layer "In6.Cu")
		(net "FM_GPU_PWR_EN_R")
	)
	(segment
		(start 8.82269 -257.080512)
		(end 11.10869 -257.080512)
		(width 0.127)
		(layer "In6.Cu")
		(net "FM_GPU_PWR_EN_R")
	)
	(segment
		(start 8.58774 -174.782988)
		(end 8.441944 -174.928784)
		(width 0.127)
		(layer "In6.Cu")
		(net "FM_GPU_PWR_EN_R")
	)
	(segment
		(start 116.6876 -400.685)
		(end 116.332 -401.0406)
		(width 0.127)
		(layer "In6.Cu")
		(net "FM_GPU_PWR_EN_R")
	)
	(segment
		(start 116.262912 -395.561058)
		(end 116.6876 -395.985746)
		(width 0.127)
		(layer "In6.Cu")
		(net "FM_GPU_PWR_EN_R")
	)
	(segment
		(start 116.6876 -395.985746)
		(end 116.6876 -400.685)
		(width 0.127)
		(layer "In6.Cu")
		(net "FM_GPU_PWR_EN_R")
	)
	(segment
		(start 8.441944 -174.928784)
		(end 7.73049 -174.928784)
		(width 0.127)
		(layer "In6.Cu")
		(net "FM_GPU_PWR_EN_R")
	)
	(segment
		(start 12.63396 -322.84416)
		(end 12.634214 -322.84416)
		(width 0.127)
		(layer "In6.Cu")
		(net "FM_GPU_PWR_EN_R")
	)
	(segment
		(start 99.462844 -393.656058)
		(end 100.682044 -392.436858)
		(width 0.127)
		(layer "In6.Cu")
		(net "FM_GPU_PWR_EN_R")
	)
	(segment
		(start 26.778712 -325.203058)
		(end 33.16097 -331.585316)
		(width 0.127)
		(layer "In6.Cu")
		(net "FM_GPU_PWR_EN_R")
	)
	(segment
		(start 33.16097 -331.585316)
		(end 33.16097 -337.38058)
		(width 0.127)
		(layer "In6.Cu")
		(net "FM_GPU_PWR_EN_R")
	)
	(segment
		(start 5.525516 -195.975986)
		(end 5.525516 -253.783338)
		(width 0.127)
		(layer "In6.Cu")
		(net "FM_GPU_PWR_EN_R")
	)
	(segment
		(start 108.700316 -392.436858)
		(end 108.751116 -392.487658)
		(width 0.127)
		(layer "In6.Cu")
		(net "FM_GPU_PWR_EN_R")
	)
	(segment
		(start 6.74878 -194.752722)
		(end 5.525516 -195.975986)
		(width 0.127)
		(layer "In6.Cu")
		(net "FM_GPU_PWR_EN_R")
	)
	(segment
		(start 116.713 -402.5138)
		(end 115.8494 -403.3774)
		(width 0.127)
		(layer "In6.Cu")
		(net "FM_GPU_PWR_EN_R")
	)
	(segment
		(start 5.525516 -253.783338)
		(end 8.82269 -257.080512)
		(width 0.127)
		(layer "In6.Cu")
		(net "FM_GPU_PWR_EN_R")
	)
	(segment
		(start 11.773916 -257.745738)
		(end 11.773916 -321.984116)
		(width 0.127)
		(layer "In6.Cu")
		(net "FM_GPU_PWR_EN_R")
	)
	(segment
		(start 33.16097 -337.38058)
		(end 31.24708 -339.29447)
		(width 0.127)
		(layer "In6.Cu")
		(net "FM_GPU_PWR_EN_R")
	)
	(segment
		(start 115.126516 -395.561058)
		(end 116.262912 -395.561058)
		(width 0.127)
		(layer "In6.Cu")
		(net "FM_GPU_PWR_EN_R")
	)
	(segment
		(start 5.525516 -177.133758)
		(end 5.525516 -191.55918)
		(width 0.127)
		(layer "In6.Cu")
		(net "FM_GPU_PWR_EN_R")
	)
	(segment
		(start 114.28476 -416.867848)
		(end 114.28476 -418.442648)
		(width 0.127)
		(layer "In6.Cu")
		(net "FM_GPU_PWR_EN_R")
	)
	(segment
		(start 117.6528 -410.86786)
		(end 115.09248 -413.42818)
		(width 0.127)
		(layer "In6.Cu")
		(net "FM_GPU_PWR_EN_R")
	)
	(segment
		(start 14.993112 -325.203058)
		(end 26.778712 -325.203058)
		(width 0.127)
		(layer "In6.Cu")
		(net "FM_GPU_PWR_EN_R")
	)
	(segment
		(start 100.682044 -392.436858)
		(end 108.700316 -392.436858)
		(width 0.127)
		(layer "In6.Cu")
		(net "FM_GPU_PWR_EN_R")
	)
	(segment
		(start 7.73049 -174.928784)
		(end 5.525516 -177.133758)
		(width 0.127)
		(layer "In6.Cu")
		(net "FM_GPU_PWR_EN_R")
	)
	(segment
		(start 7.133336 -194.752722)
		(end 6.74878 -194.752722)
		(width 0.127)
		(layer "In6.Cu")
		(net "FM_GPU_PWR_EN_R")
	)
	(segment
		(start 5.525516 -191.55918)
		(end 7.443216 -193.47688)
		(width 0.127)
		(layer "In6.Cu")
		(net "FM_GPU_PWR_EN_R")
	)
	(segment
		(start 115.09248 -413.42818)
		(end 115.09248 -416.060128)
		(width 0.127)
		(layer "In6.Cu")
		(net "FM_GPU_PWR_EN_R")
	)
	(segment
		(start 116.332 -401.6502)
		(end 116.713 -402.0312)
		(width 0.127)
		(layer "In6.Cu")
		(net "FM_GPU_PWR_EN_R")
	)
	(segment
		(start 58.34888 -393.656058)
		(end 99.462844 -393.656058)
		(width 0.127)
		(layer "In6.Cu")
		(net "FM_GPU_PWR_EN_R")
	)
	(segment
		(start 117.6528 -406.6794)
		(end 117.6528 -410.86786)
		(width 0.127)
		(layer "In6.Cu")
		(net "FM_GPU_PWR_EN_R")
	)
	(segment
		(start 31.24708 -339.29447)
		(end 31.24708 -366.554258)
		(width 0.127)
		(layer "In6.Cu")
		(net "FM_GPU_PWR_EN_R")
	)
	(segment
		(start 108.751116 -392.487658)
		(end 112.053116 -392.487658)
		(width 0.127)
		(layer "In6.Cu")
		(net "FM_GPU_PWR_EN_R")
	)
	(segment
		(start 115.8494 -404.876)
		(end 117.6528 -406.6794)
		(width 0.127)
		(layer "In6.Cu")
		(net "FM_GPU_PWR_EN_R")
	)
	(segment
		(start 116.332 -401.0406)
		(end 116.332 -401.6502)
		(width 0.127)
		(layer "In6.Cu")
		(net "FM_GPU_PWR_EN_R")
	)
	(segment
		(start 11.10869 -257.080512)
		(end 11.773916 -257.745738)
		(width 0.127)
		(layer "In6.Cu")
		(net "FM_GPU_PWR_EN_R")
	)
	(segment
		(start 12.634214 -322.84416)
		(end 14.993112 -325.203058)
		(width 0.127)
		(layer "In6.Cu")
		(net "FM_GPU_PWR_EN_R")
	)
	(segment
		(start 7.443216 -193.47688)
		(end 7.443216 -194.442842)
		(width 0.127)
		(layer "In6.Cu")
		(net "FM_GPU_PWR_EN_R")
	)
	(segment
		(start 116.713 -402.0312)
		(end 116.713 -402.5138)
		(width 0.127)
		(layer "In6.Cu")
		(net "FM_GPU_PWR_EN_R")
	)
	(segment
		(start 112.053116 -392.487658)
		(end 115.126516 -395.561058)
		(width 0.127)
		(layer "In6.Cu")
		(net "FM_GPU_PWR_EN_R")
	)
	(segment
		(start 115.09248 -416.060128)
		(end 114.28476 -416.867848)
		(width 0.127)
		(layer "In6.Cu")
		(net "FM_GPU_PWR_EN_R")
	)
	(segment
		(start 9.77138 -174.782988)
		(end 8.58774 -174.782988)
		(width 0.127)
		(layer "In6.Cu")
		(net "FM_GPU_PWR_EN_R")
	)
	(segment
		(start 7.443216 -194.442842)
		(end 7.133336 -194.752722)
		(width 0.127)
		(layer "In6.Cu")
		(net "FM_GPU_PWR_EN_R")
	)
	(segment
		(start 144.70634 -108.092748)
		(end 147.50034 -110.886748)
		(width 0.127)
		(layer "In13.Cu")
		(net "FM_GPU_PWR_EN_R")
	)
	(segment
		(start 126.821692 -106.289348)
		(end 138.40206 -106.289348)
		(width 0.127)
		(layer "In13.Cu")
		(net "FM_GPU_PWR_EN_R")
	)
	(segment
		(start 47.8536 -111.470948)
		(end 48.54702 -112.164368)
		(width 0.127)
		(layer "In13.Cu")
		(net "FM_GPU_PWR_EN_R")
	)
	(segment
		(start 158.55188 -104.953054)
		(end 158.55188 -104.485948)
		(width 0.127)
		(layer "In13.Cu")
		(net "FM_GPU_PWR_EN_R")
	)
	(segment
		(start 138.40206 -106.289348)
		(end 140.20546 -108.092748)
		(width 0.127)
		(layer "In13.Cu")
		(net "FM_GPU_PWR_EN_R")
	)
	(segment
		(start 66.722752 -110.411768)
		(end 76.613512 -110.411768)
		(width 0.127)
		(layer "In13.Cu")
		(net "FM_GPU_PWR_EN_R")
	)
	(segment
		(start 49.8856 -112.164368)
		(end 50.21072 -111.839248)
		(width 0.127)
		(layer "In13.Cu")
		(net "FM_GPU_PWR_EN_R")
	)
	(segment
		(start 126.737872 -106.373168)
		(end 126.821692 -106.289348)
		(width 0.127)
		(layer "In13.Cu")
		(net "FM_GPU_PWR_EN_R")
	)
	(segment
		(start 55.65902 -111.098076)
		(end 56.638952 -112.078008)
		(width 0.127)
		(layer "In13.Cu")
		(net "FM_GPU_PWR_EN_R")
	)
	(segment
		(start 45.847 -112.321848)
		(end 46.6979 -111.470948)
		(width 0.127)
		(layer "In13.Cu")
		(net "FM_GPU_PWR_EN_R")
	)
	(segment
		(start 101.386132 -106.263948)
		(end 118.882668 -106.263948)
		(width 0.127)
		(layer "In13.Cu")
		(net "FM_GPU_PWR_EN_R")
	)
	(segment
		(start 140.20546 -108.092748)
		(end 144.70634 -108.092748)
		(width 0.127)
		(layer "In13.Cu")
		(net "FM_GPU_PWR_EN_R")
	)
	(segment
		(start 45.179234 -113.581688)
		(end 45.179234 -113.581434)
		(width 0.127)
		(layer "In13.Cu")
		(net "FM_GPU_PWR_EN_R")
	)
	(segment
		(start 50.21072 -111.839248)
		(end 51.71694 -111.839248)
		(width 0.127)
		(layer "In13.Cu")
		(net "FM_GPU_PWR_EN_R")
	)
	(segment
		(start 118.882668 -106.263948)
		(end 118.991888 -106.373168)
		(width 0.127)
		(layer "In13.Cu")
		(net "FM_GPU_PWR_EN_R")
	)
	(segment
		(start 76.613512 -110.411768)
		(end 79.633572 -107.391708)
		(width 0.127)
		(layer "In13.Cu")
		(net "FM_GPU_PWR_EN_R")
	)
	(segment
		(start 52.458112 -111.098076)
		(end 55.65902 -111.098076)
		(width 0.127)
		(layer "In13.Cu")
		(net "FM_GPU_PWR_EN_R")
	)
	(segment
		(start 56.638952 -112.078008)
		(end 65.056512 -112.078008)
		(width 0.127)
		(layer "In13.Cu")
		(net "FM_GPU_PWR_EN_R")
	)
	(segment
		(start 152.359106 -108.905548)
		(end 154.599386 -108.905548)
		(width 0.127)
		(layer "In13.Cu")
		(net "FM_GPU_PWR_EN_R")
	)
	(segment
		(start 100.258372 -107.391708)
		(end 101.386132 -106.263948)
		(width 0.127)
		(layer "In13.Cu")
		(net "FM_GPU_PWR_EN_R")
	)
	(segment
		(start 45.847 -112.913668)
		(end 45.847 -112.321848)
		(width 0.127)
		(layer "In13.Cu")
		(net "FM_GPU_PWR_EN_R")
	)
	(segment
		(start 65.056512 -112.078008)
		(end 66.722752 -110.411768)
		(width 0.127)
		(layer "In13.Cu")
		(net "FM_GPU_PWR_EN_R")
	)
	(segment
		(start 147.50034 -110.886748)
		(end 150.377906 -110.886748)
		(width 0.127)
		(layer "In13.Cu")
		(net "FM_GPU_PWR_EN_R")
	)
	(segment
		(start 45.179234 -113.581434)
		(end 45.847 -112.913668)
		(width 0.127)
		(layer "In13.Cu")
		(net "FM_GPU_PWR_EN_R")
	)
	(segment
		(start 118.991888 -106.373168)
		(end 126.737872 -106.373168)
		(width 0.127)
		(layer "In13.Cu")
		(net "FM_GPU_PWR_EN_R")
	)
	(segment
		(start 150.377906 -110.886748)
		(end 152.359106 -108.905548)
		(width 0.127)
		(layer "In13.Cu")
		(net "FM_GPU_PWR_EN_R")
	)
	(segment
		(start 79.633572 -107.391708)
		(end 100.258372 -107.391708)
		(width 0.127)
		(layer "In13.Cu")
		(net "FM_GPU_PWR_EN_R")
	)
	(segment
		(start 46.6979 -111.470948)
		(end 47.8536 -111.470948)
		(width 0.127)
		(layer "In13.Cu")
		(net "FM_GPU_PWR_EN_R")
	)
	(segment
		(start 48.54702 -112.164368)
		(end 49.8856 -112.164368)
		(width 0.127)
		(layer "In13.Cu")
		(net "FM_GPU_PWR_EN_R")
	)
	(segment
		(start 154.599386 -108.905548)
		(end 158.55188 -104.953054)
		(width 0.127)
		(layer "In13.Cu")
		(net "FM_GPU_PWR_EN_R")
	)
	(segment
		(start 51.71694 -111.839248)
		(end 52.458112 -111.098076)
		(width 0.127)
		(layer "In13.Cu")
		(net "FM_GPU_PWR_EN_R")
	)
	(segment
		(start 16.84528 -169.101516)
		(end 11.163808 -174.782988)
		(width 0.127)
		(layer "In15.Cu")
		(net "FM_GPU_PWR_EN_R")
	)
	(segment
		(start 29.340302 -115.875308)
		(end 16.84528 -128.37033)
		(width 0.127)
		(layer "In15.Cu")
		(net "FM_GPU_PWR_EN_R")
	)
	(segment
		(start 11.163808 -174.782988)
		(end 9.77138 -174.782988)
		(width 0.127)
		(layer "In15.Cu")
		(net "FM_GPU_PWR_EN_R")
	)
	(segment
		(start 16.84528 -128.37033)
		(end 16.84528 -169.101516)
		(width 0.127)
		(layer "In15.Cu")
		(net "FM_GPU_PWR_EN_R")
	)
	(segment
		(start 43.634914 -113.581688)
		(end 41.341294 -115.875308)
		(width 0.127)
		(layer "In15.Cu")
		(net "FM_GPU_PWR_EN_R")
	)
	(segment
		(start 41.341294 -115.875308)
		(end 29.340302 -115.875308)
		(width 0.127)
		(layer "In15.Cu")
		(net "FM_GPU_PWR_EN_R")
	)
	(segment
		(start 45.179234 -113.581688)
		(end 43.634914 -113.581688)
		(width 0.127)
		(layer "In15.Cu")
		(net "FM_GPU_PWR_EN_R")
	)
	(segment
		(start 166.800276 -106.575352)
		(end 170.155616 -106.575352)
		(width 0.12954)
		(layer "F.Cu")
		(net "FM_GPU_HSC_EN_R")
	)
	(segment
		(start 166.34968 -107.025948)
		(end 166.52748 -106.848148)
		(width 0.12954)
		(layer "F.Cu")
		(net "FM_GPU_HSC_EN_R")
	)
	(segment
		(start 166.52748 -106.848148)
		(end 166.800276 -106.575352)
		(width 0.12954)
		(layer "F.Cu")
		(net "FM_GPU_HSC_EN_R")
	)
	(segment
		(start 165.04793 -107.025948)
		(end 166.34968 -107.025948)
		(width 0.12954)
		(layer "F.Cu")
		(net "FM_GPU_HSC_EN_R")
	)
	(via
		(at 166.52748 -106.848148)
		(size 0.762)
		(drill 0.381)
		(layers "F.Cu" "B.Cu")
		(net "FM_GPU_HSC_EN_R")
	)
	(via
		(at 237.1598 -424.561)
		(size 0.6604)
		(drill 0.3302)
		(layers "F.Cu" "B.Cu")
		(net "FM_GPU_HSC_EN_BUF_R1")
	)
	(segment
		(start 237.1598 -424.561)
		(end 237.0836 -424.561)
		(width 0.12954)
		(layer "B.Cu")
		(net "FM_GPU_HSC_EN_BUF_R1")
	)
	(segment
		(start 237.1598 -423.463974)
		(end 237.1598 -424.561)
		(width 0.12954)
		(layer "B.Cu")
		(net "FM_GPU_HSC_EN_BUF_R1")
	)
	(segment
		(start 238.30788 -423.376598)
		(end 237.247176 -423.376598)
		(width 0.12954)
		(layer "B.Cu")
		(net "FM_GPU_HSC_EN_BUF_R1")
	)
	(segment
		(start 235.909866 -425.734734)
		(end 235.909866 -427.961806)
		(width 0.12954)
		(layer "B.Cu")
		(net "FM_GPU_HSC_EN_BUF_R1")
	)
	(segment
		(start 237.230666 -423.393108)
		(end 237.1598 -423.463974)
		(width 0.12954)
		(layer "B.Cu")
		(net "FM_GPU_HSC_EN_BUF_R1")
	)
	(segment
		(start 237.0836 -424.561)
		(end 235.909866 -425.734734)
		(width 0.12954)
		(layer "B.Cu")
		(net "FM_GPU_HSC_EN_BUF_R1")
	)
	(segment
		(start 235.909866 -427.961806)
		(end 235.91012 -427.96206)
		(width 0.12954)
		(layer "B.Cu")
		(net "FM_GPU_HSC_EN_BUF_R1")
	)
	(segment
		(start 237.247176 -423.376598)
		(end 237.230666 -423.393108)
		(width 0.12954)
		(layer "B.Cu")
		(net "FM_GPU_HSC_EN_BUF_R1")
	)
	(segment
		(start 191.988186 -431.12182)
		(end 191.639698 -431.470308)
		(width 0.12954)
		(layer "F.Cu")
		(net "FM_GPU_HSC_EN_BUF_R")
	)
	(segment
		(start 193.004186 -429.81118)
		(end 194.020186 -429.81118)
		(width 0.12954)
		(layer "F.Cu")
		(net "FM_GPU_HSC_EN_BUF_R")
	)
	(segment
		(start 193.004186 -429.81118)
		(end 191.988186 -429.81118)
		(width 0.12954)
		(layer "F.Cu")
		(net "FM_GPU_HSC_EN_BUF_R")
	)
	(segment
		(start 191.988186 -429.81118)
		(end 191.988186 -431.12182)
		(width 0.12954)
		(layer "F.Cu")
		(net "FM_GPU_HSC_EN_BUF_R")
	)
	(segment
		(start 191.639698 -431.470308)
		(end 191.639698 -432.75758)
		(width 0.12954)
		(layer "F.Cu")
		(net "FM_GPU_HSC_EN_BUF_R")
	)
	(segment
		(start 191.639698 -432.75758)
		(end 191.651382 -432.769264)
		(width 0.12954)
		(layer "F.Cu")
		(net "FM_GPU_HSC_EN_BUF_R")
	)
	(via
		(at 191.988186 -431.12182)
		(size 0.762)
		(drill 0.381)
		(layers "F.Cu" "B.Cu")
		(net "FM_GPU_HSC_EN_BUF_R")
	)
	(segment
		(start 194.78752 -429.01108)
		(end 194.020186 -429.01108)
		(width 0.12954)
		(layer "F.Cu")
		(net "FM_GPU_HSC_EN_BUF")
	)
	(via
		(at 194.78752 -429.01108)
		(size 0.508)
		(drill 0.254)
		(layers "F.Cu" "B.Cu")
		(net "FM_GPU_HSC_EN_BUF")
	)
	(via
		(at 237.230666 -421.977058)
		(size 0.762)
		(drill 0.254)
		(layers "F.Cu" "B.Cu")
		(net "FM_GPU_HSC_EN_BUF")
	)
	(segment
		(start 237.230666 -422.593008)
		(end 237.230666 -421.977058)
		(width 0.12954)
		(layer "B.Cu")
		(net "FM_GPU_HSC_EN_BUF")
	)
	(segment
		(start 196.10832 -433.92852)
		(end 196.10832 -430.33188)
		(width 0.127)
		(layer "In13.Cu")
		(net "FM_GPU_HSC_EN_BUF")
	)
	(segment
		(start 237.230666 -421.977058)
		(end 232.1052 -427.102524)
		(width 0.127)
		(layer "In13.Cu")
		(net "FM_GPU_HSC_EN_BUF")
	)
	(segment
		(start 232.1052 -436.73268)
		(end 231.22128 -437.6166)
		(width 0.127)
		(layer "In13.Cu")
		(net "FM_GPU_HSC_EN_BUF")
	)
	(segment
		(start 231.22128 -437.6166)
		(end 199.7964 -437.6166)
		(width 0.127)
		(layer "In13.Cu")
		(net "FM_GPU_HSC_EN_BUF")
	)
	(segment
		(start 199.7964 -437.6166)
		(end 196.10832 -433.92852)
		(width 0.127)
		(layer "In13.Cu")
		(net "FM_GPU_HSC_EN_BUF")
	)
	(segment
		(start 232.1052 -427.102524)
		(end 232.1052 -436.73268)
		(width 0.127)
		(layer "In13.Cu")
		(net "FM_GPU_HSC_EN_BUF")
	)
	(segment
		(start 196.10832 -430.33188)
		(end 194.78752 -429.01108)
		(width 0.127)
		(layer "In13.Cu")
		(net "FM_GPU_HSC_EN_BUF")
	)
	(segment
		(start 200.841356 -163.027868)
		(end 192.12052 -163.027868)
		(width 0.12954)
		(layer "F.Cu")
		(net "FM_GPU_HSC_EN")
	)
	(segment
		(start 244.07368 -163.769548)
		(end 244.07368 -160.892744)
		(width 0.12954)
		(layer "F.Cu")
		(net "FM_GPU_HSC_EN")
	)
	(segment
		(start 186.6519 -165.420548)
		(end 185.4073 -164.175948)
		(width 0.12954)
		(layer "F.Cu")
		(net "FM_GPU_HSC_EN")
	)
	(segment
		(start 189.72784 -165.420548)
		(end 186.6519 -165.420548)
		(width 0.12954)
		(layer "F.Cu")
		(net "FM_GPU_HSC_EN")
	)
	(segment
		(start 207.618076 -156.251148)
		(end 200.841356 -163.027868)
		(width 0.12954)
		(layer "F.Cu")
		(net "FM_GPU_HSC_EN")
	)
	(segment
		(start 192.12052 -163.027868)
		(end 189.72784 -165.420548)
		(width 0.12954)
		(layer "F.Cu")
		(net "FM_GPU_HSC_EN")
	)
	(segment
		(start 192.877186 -437.77408)
		(end 193.893186 -437.77408)
		(width 0.12954)
		(layer "F.Cu")
		(net "FM_GPU_HSC_EN")
	)
	(segment
		(start 193.551302 -435.169056)
		(end 193.551302 -436.924958)
		(width 0.12954)
		(layer "F.Cu")
		(net "FM_GPU_HSC_EN")
	)
	(segment
		(start 193.551302 -436.924958)
		(end 192.877186 -437.599074)
		(width 0.12954)
		(layer "F.Cu")
		(net "FM_GPU_HSC_EN")
	)
	(segment
		(start 193.893186 -437.77408)
		(end 194.27952 -437.77408)
		(width 0.12954)
		(layer "F.Cu")
		(net "FM_GPU_HSC_EN")
	)
	(segment
		(start 192.877186 -437.599074)
		(end 192.877186 -437.77408)
		(width 0.12954)
		(layer "F.Cu")
		(net "FM_GPU_HSC_EN")
	)
	(segment
		(start 194.27952 -437.77408)
		(end 194.717162 -437.336438)
		(width 0.12954)
		(layer "F.Cu")
		(net "FM_GPU_HSC_EN")
	)
	(segment
		(start 239.432084 -156.251148)
		(end 207.618076 -156.251148)
		(width 0.12954)
		(layer "F.Cu")
		(net "FM_GPU_HSC_EN")
	)
	(segment
		(start 183.90108 -164.175948)
		(end 182.07228 -162.347148)
		(width 0.12954)
		(layer "F.Cu")
		(net "FM_GPU_HSC_EN")
	)
	(segment
		(start 164.24783 -107.025948)
		(end 163.63188 -107.025948)
		(width 0.12954)
		(layer "F.Cu")
		(net "FM_GPU_HSC_EN")
	)
	(segment
		(start 244.07368 -160.892744)
		(end 239.432084 -156.251148)
		(width 0.12954)
		(layer "F.Cu")
		(net "FM_GPU_HSC_EN")
	)
	(segment
		(start 182.07228 -162.347148)
		(end 181.71668 -162.347148)
		(width 0.12954)
		(layer "F.Cu")
		(net "FM_GPU_HSC_EN")
	)
	(segment
		(start 185.4073 -164.175948)
		(end 183.90108 -164.175948)
		(width 0.12954)
		(layer "F.Cu")
		(net "FM_GPU_HSC_EN")
	)
	(via
		(at 194.717162 -437.336438)
		(size 0.508)
		(drill 0.254)
		(layers "F.Cu" "B.Cu")
		(net "FM_GPU_HSC_EN")
	)
	(via
		(at 244.07368 -163.769548)
		(size 0.508)
		(drill 0.254)
		(layers "F.Cu" "B.Cu")
		(net "FM_GPU_HSC_EN")
	)
	(via
		(at 163.63188 -107.025948)
		(size 0.508)
		(drill 0.254)
		(layers "F.Cu" "B.Cu")
		(net "FM_GPU_HSC_EN")
	)
	(via
		(at 181.71668 -162.347148)
		(size 0.508)
		(drill 0.254)
		(layers "F.Cu" "B.Cu")
		(net "FM_GPU_HSC_EN")
	)
	(segment
		(start 176.6443 -422.86936)
		(end 177.919126 -422.86936)
		(width 0.127)
		(layer "In2.Cu")
		(net "FM_GPU_HSC_EN")
	)
	(segment
		(start 181.2798 -408.0764)
		(end 181.2798 -411.09392)
		(width 0.127)
		(layer "In2.Cu")
		(net "FM_GPU_HSC_EN")
	)
	(segment
		(start 192.45326 -437.74868)
		(end 194.30492 -437.74868)
		(width 0.127)
		(layer "In2.Cu")
		(net "FM_GPU_HSC_EN")
	)
	(segment
		(start 180.072538 -393.464542)
		(end 180.072538 -406.869138)
		(width 0.127)
		(layer "In2.Cu")
		(net "FM_GPU_HSC_EN")
	)
	(segment
		(start 216.511378 -373.70258)
		(end 199.8345 -373.70258)
		(width 0.127)
		(layer "In2.Cu")
		(net "FM_GPU_HSC_EN")
	)
	(segment
		(start 184.9882 -425.1452)
		(end 184.9882 -427.0756)
		(width 0.127)
		(layer "In2.Cu")
		(net "FM_GPU_HSC_EN")
	)
	(segment
		(start 184.9882 -427.0756)
		(end 190.0936 -432.181)
		(width 0.127)
		(layer "In2.Cu")
		(net "FM_GPU_HSC_EN")
	)
	(segment
		(start 178.97602 -417.40074)
		(end 178.77028 -417.40074)
		(width 0.127)
		(layer "In2.Cu")
		(net "FM_GPU_HSC_EN")
	)
	(segment
		(start 226.34448 -363.869478)
		(end 216.511378 -373.70258)
		(width 0.127)
		(layer "In2.Cu")
		(net "FM_GPU_HSC_EN")
	)
	(segment
		(start 244.07368 -163.769548)
		(end 244.297708 -163.54552)
		(width 0.127)
		(layer "In2.Cu")
		(net "FM_GPU_HSC_EN")
	)
	(segment
		(start 180.645054 -411.728666)
		(end 179.753006 -411.728666)
		(width 0.127)
		(layer "In2.Cu")
		(net "FM_GPU_HSC_EN")
	)
	(segment
		(start 179.753006 -411.728666)
		(end 179.00142 -412.480252)
		(width 0.127)
		(layer "In2.Cu")
		(net "FM_GPU_HSC_EN")
	)
	(segment
		(start 190.0936 -435.38902)
		(end 192.45326 -437.74868)
		(width 0.127)
		(layer "In2.Cu")
		(net "FM_GPU_HSC_EN")
	)
	(segment
		(start 179.00142 -417.37534)
		(end 178.97602 -417.40074)
		(width 0.127)
		(layer "In2.Cu")
		(net "FM_GPU_HSC_EN")
	)
	(segment
		(start 190.0936 -432.181)
		(end 190.0936 -435.38902)
		(width 0.127)
		(layer "In2.Cu")
		(net "FM_GPU_HSC_EN")
	)
	(segment
		(start 226.34448 -346.238068)
		(end 226.34448 -363.869478)
		(width 0.127)
		(layer "In2.Cu")
		(net "FM_GPU_HSC_EN")
	)
	(segment
		(start 199.8345 -373.70258)
		(end 180.072538 -393.464542)
		(width 0.127)
		(layer "In2.Cu")
		(net "FM_GPU_HSC_EN")
	)
	(segment
		(start 244.297708 -163.54552)
		(end 245.830852 -163.54552)
		(width 0.127)
		(layer "In2.Cu")
		(net "FM_GPU_HSC_EN")
	)
	(segment
		(start 245.830852 -163.54552)
		(end 249.34926 -167.063928)
		(width 0.127)
		(layer "In2.Cu")
		(net "FM_GPU_HSC_EN")
	)
	(segment
		(start 194.30492 -437.74868)
		(end 194.717162 -437.336438)
		(width 0.127)
		(layer "In2.Cu")
		(net "FM_GPU_HSC_EN")
	)
	(segment
		(start 249.34926 -167.063928)
		(end 249.34926 -239.202468)
		(width 0.127)
		(layer "In2.Cu")
		(net "FM_GPU_HSC_EN")
	)
	(segment
		(start 178.77028 -417.40074)
		(end 176.38014 -419.79088)
		(width 0.127)
		(layer "In2.Cu")
		(net "FM_GPU_HSC_EN")
	)
	(segment
		(start 250.2662 -240.119408)
		(end 250.2662 -322.316348)
		(width 0.127)
		(layer "In2.Cu")
		(net "FM_GPU_HSC_EN")
	)
	(segment
		(start 184.3532 -424.5102)
		(end 184.9882 -425.1452)
		(width 0.127)
		(layer "In2.Cu")
		(net "FM_GPU_HSC_EN")
	)
	(segment
		(start 176.38014 -422.6052)
		(end 176.6443 -422.86936)
		(width 0.127)
		(layer "In2.Cu")
		(net "FM_GPU_HSC_EN")
	)
	(segment
		(start 249.34926 -239.202468)
		(end 250.2662 -240.119408)
		(width 0.127)
		(layer "In2.Cu")
		(net "FM_GPU_HSC_EN")
	)
	(segment
		(start 177.919126 -422.86936)
		(end 179.559966 -424.5102)
		(width 0.127)
		(layer "In2.Cu")
		(net "FM_GPU_HSC_EN")
	)
	(segment
		(start 176.38014 -419.79088)
		(end 176.38014 -422.6052)
		(width 0.127)
		(layer "In2.Cu")
		(net "FM_GPU_HSC_EN")
	)
	(segment
		(start 181.2798 -411.09392)
		(end 180.645054 -411.728666)
		(width 0.127)
		(layer "In2.Cu")
		(net "FM_GPU_HSC_EN")
	)
	(segment
		(start 180.072538 -406.869138)
		(end 181.2798 -408.0764)
		(width 0.127)
		(layer "In2.Cu")
		(net "FM_GPU_HSC_EN")
	)
	(segment
		(start 179.00142 -412.480252)
		(end 179.00142 -417.37534)
		(width 0.127)
		(layer "In2.Cu")
		(net "FM_GPU_HSC_EN")
	)
	(segment
		(start 250.2662 -322.316348)
		(end 226.34448 -346.238068)
		(width 0.127)
		(layer "In2.Cu")
		(net "FM_GPU_HSC_EN")
	)
	(segment
		(start 179.559966 -424.5102)
		(end 184.3532 -424.5102)
		(width 0.127)
		(layer "In2.Cu")
		(net "FM_GPU_HSC_EN")
	)
	(segment
		(start 177.32248 -159.832548)
		(end 177.32248 -163.337748)
		(width 0.127)
		(layer "In11.Cu")
		(net "FM_GPU_HSC_EN")
	)
	(segment
		(start 180.81752 -162.966908)
		(end 181.43728 -162.347148)
		(width 0.127)
		(layer "In11.Cu")
		(net "FM_GPU_HSC_EN")
	)
	(segment
		(start 177.32248 -163.337748)
		(end 178.74488 -164.760148)
		(width 0.127)
		(layer "In11.Cu")
		(net "FM_GPU_HSC_EN")
	)
	(segment
		(start 178.74488 -164.760148)
		(end 180.04028 -164.760148)
		(width 0.127)
		(layer "In11.Cu")
		(net "FM_GPU_HSC_EN")
	)
	(segment
		(start 165.81628 -128.1049)
		(end 165.81628 -148.326348)
		(width 0.127)
		(layer "In11.Cu")
		(net "FM_GPU_HSC_EN")
	)
	(segment
		(start 164.39388 -107.229148)
		(end 164.39388 -109.565948)
		(width 0.127)
		(layer "In11.Cu")
		(net "FM_GPU_HSC_EN")
	)
	(segment
		(start 163.88588 -110.708948)
		(end 164.39388 -111.216948)
		(width 0.127)
		(layer "In11.Cu")
		(net "FM_GPU_HSC_EN")
	)
	(segment
		(start 165.81628 -148.326348)
		(end 177.32248 -159.832548)
		(width 0.127)
		(layer "In11.Cu")
		(net "FM_GPU_HSC_EN")
	)
	(segment
		(start 164.39388 -109.565948)
		(end 163.88588 -110.073948)
		(width 0.127)
		(layer "In11.Cu")
		(net "FM_GPU_HSC_EN")
	)
	(segment
		(start 164.39388 -126.6825)
		(end 165.81628 -128.1049)
		(width 0.127)
		(layer "In11.Cu")
		(net "FM_GPU_HSC_EN")
	)
	(segment
		(start 164.39388 -111.216948)
		(end 164.39388 -126.6825)
		(width 0.127)
		(layer "In11.Cu")
		(net "FM_GPU_HSC_EN")
	)
	(segment
		(start 181.43728 -162.347148)
		(end 181.71668 -162.347148)
		(width 0.127)
		(layer "In11.Cu")
		(net "FM_GPU_HSC_EN")
	)
	(segment
		(start 163.63188 -107.025948)
		(end 164.19068 -107.025948)
		(width 0.127)
		(layer "In11.Cu")
		(net "FM_GPU_HSC_EN")
	)
	(segment
		(start 164.19068 -107.025948)
		(end 164.39388 -107.229148)
		(width 0.127)
		(layer "In11.Cu")
		(net "FM_GPU_HSC_EN")
	)
	(segment
		(start 180.81752 -163.982908)
		(end 180.81752 -162.966908)
		(width 0.127)
		(layer "In11.Cu")
		(net "FM_GPU_HSC_EN")
	)
	(segment
		(start 180.04028 -164.760148)
		(end 180.81752 -163.982908)
		(width 0.127)
		(layer "In11.Cu")
		(net "FM_GPU_HSC_EN")
	)
	(segment
		(start 163.88588 -110.073948)
		(end 163.88588 -110.708948)
		(width 0.127)
		(layer "In11.Cu")
		(net "FM_GPU_HSC_EN")
	)
	(via
		(at 240.3094 -424.6372)
		(size 0.6604)
		(drill 0.3302)
		(layers "F.Cu" "B.Cu")
		(net "FM_FAN_PWR_EN_R")
	)
	(segment
		(start 241.3254 -423.38625)
		(end 240.3094 -423.38625)
		(width 0.12954)
		(layer "B.Cu")
		(net "FM_FAN_PWR_EN_R")
	)
	(segment
		(start 240.3094 -424.6372)
		(end 240.3094 -426.10278)
		(width 0.12954)
		(layer "B.Cu")
		(net "FM_FAN_PWR_EN_R")
	)
	(segment
		(start 240.3094 -423.38625)
		(end 240.3094 -424.6372)
		(width 0.12954)
		(layer "B.Cu")
		(net "FM_FAN_PWR_EN_R")
	)
	(segment
		(start 240.3094 -426.10278)
		(end 238.45012 -427.96206)
		(width 0.12954)
		(layer "B.Cu")
		(net "FM_FAN_PWR_EN_R")
	)
	(segment
		(start 170.955716 -105.775506)
		(end 170.555666 -105.375456)
		(width 0.12954)
		(layer "F.Cu")
		(net "FM_FAN_PWR_EN")
	)
	(via
		(at 170.555666 -105.375456)
		(size 0.4572)
		(drill 0.254)
		(layers "F.Cu" "B.Cu")
		(net "FM_FAN_PWR_EN")
	)
	(via
		(at 243.0272 -422.58615)
		(size 0.6604)
		(drill 0.254)
		(layers "F.Cu" "B.Cu")
		(net "FM_FAN_PWR_EN")
	)
	(via
		(at 216.307924 -113.773458)
		(size 0.508)
		(drill 0.254)
		(layers "F.Cu" "B.Cu")
		(net "FM_FAN_PWR_EN")
	)
	(via
		(at 235.466636 -113.180876)
		(size 0.508)
		(drill 0.254)
		(layers "F.Cu" "B.Cu")
		(net "FM_FAN_PWR_EN")
	)
	(segment
		(start 242.2906 -422.58615)
		(end 243.0272 -422.58615)
		(width 0.12954)
		(layer "B.Cu")
		(net "FM_FAN_PWR_EN")
	)
	(segment
		(start 241.3254 -422.58615)
		(end 242.2906 -422.58615)
		(width 0.12954)
		(layer "B.Cu")
		(net "FM_FAN_PWR_EN")
	)
	(segment
		(start 239.192562 -136.363202)
		(end 240.33988 -137.51052)
		(width 0.127)
		(layer "In2.Cu")
		(net "FM_FAN_PWR_EN")
	)
	(segment
		(start 209.449416 -108.981748)
		(end 208.992216 -109.438948)
		(width 0.127)
		(layer "In2.Cu")
		(net "FM_FAN_PWR_EN")
	)
	(segment
		(start 272.65884 -388.18312)
		(end 273.86534 -386.97662)
		(width 0.127)
		(layer "In2.Cu")
		(net "FM_FAN_PWR_EN")
	)
	(segment
		(start 297.7515 -391.61974)
		(end 297.7515 -398.2212)
		(width 0.127)
		(layer "In2.Cu")
		(net "FM_FAN_PWR_EN")
	)
	(segment
		(start 296.50182 -390.37006)
		(end 297.7515 -391.61974)
		(width 0.127)
		(layer "In2.Cu")
		(net "FM_FAN_PWR_EN")
	)
	(segment
		(start 291.2237 -405.77262)
		(end 290.59251 -406.40381)
		(width 0.127)
		(layer "In2.Cu")
		(net "FM_FAN_PWR_EN")
	)
	(segment
		(start 235.466636 -114.334544)
		(end 230.51897 -119.28221)
		(width 0.127)
		(layer "In2.Cu")
		(net "FM_FAN_PWR_EN")
	)
	(segment
		(start 233.921808 -132.442966)
		(end 233.921808 -133.229096)
		(width 0.127)
		(layer "In2.Cu")
		(net "FM_FAN_PWR_EN")
	)
	(segment
		(start 176.79289 -108.16844)
		(end 176.562766 -107.938316)
		(width 0.127)
		(layer "In2.Cu")
		(net "FM_FAN_PWR_EN")
	)
	(segment
		(start 230.51897 -119.882158)
		(end 230.27132 -120.129808)
		(width 0.127)
		(layer "In2.Cu")
		(net "FM_FAN_PWR_EN")
	)
	(segment
		(start 266.12342 -387.21538)
		(end 267.09116 -388.18312)
		(width 0.127)
		(layer "In2.Cu")
		(net "FM_FAN_PWR_EN")
	)
	(segment
		(start 296.54754 -385.8006)
		(end 297.00982 -386.26288)
		(width 0.127)
		(layer "In2.Cu")
		(net "FM_FAN_PWR_EN")
	)
	(segment
		(start 234.721654 -136.363202)
		(end 239.192562 -136.363202)
		(width 0.127)
		(layer "In2.Cu")
		(net "FM_FAN_PWR_EN")
	)
	(segment
		(start 203.33208 -109.033564)
		(end 203.33208 -108.328968)
		(width 0.127)
		(layer "In2.Cu")
		(net "FM_FAN_PWR_EN")
	)
	(segment
		(start 253.2634 -155.712668)
		(end 253.2634 -323.523356)
		(width 0.127)
		(layer "In2.Cu")
		(net "FM_FAN_PWR_EN")
	)
	(segment
		(start 175.760634 -107.136438)
		(end 175.760634 -104.742742)
		(width 0.127)
		(layer "In2.Cu")
		(net "FM_FAN_PWR_EN")
	)
	(segment
		(start 290.59251 -406.40381)
		(end 290.59251 -407.34869)
		(width 0.127)
		(layer "In2.Cu")
		(net "FM_FAN_PWR_EN")
	)
	(segment
		(start 212.715348 -108.981748)
		(end 209.449416 -108.981748)
		(width 0.127)
		(layer "In2.Cu")
		(net "FM_FAN_PWR_EN")
	)
	(segment
		(start 203.737464 -109.438948)
		(end 203.33208 -109.033564)
		(width 0.127)
		(layer "In2.Cu")
		(net "FM_FAN_PWR_EN")
	)
	(segment
		(start 283.22778 -411.10662)
		(end 281.80792 -412.52648)
		(width 0.127)
		(layer "In2.Cu")
		(net "FM_FAN_PWR_EN")
	)
	(segment
		(start 297.00982 -387.70306)
		(end 296.50182 -388.21106)
		(width 0.127)
		(layer "In2.Cu")
		(net "FM_FAN_PWR_EN")
	)
	(segment
		(start 186.572652 -109.769148)
		(end 180.78704 -109.769148)
		(width 0.127)
		(layer "In2.Cu")
		(net "FM_FAN_PWR_EN")
	)
	(segment
		(start 273.86534 -386.97662)
		(end 283.99486 -386.97662)
		(width 0.127)
		(layer "In2.Cu")
		(net "FM_FAN_PWR_EN")
	)
	(segment
		(start 253.2634 -323.523356)
		(end 252.12548 -324.661276)
		(width 0.127)
		(layer "In2.Cu")
		(net "FM_FAN_PWR_EN")
	)
	(segment
		(start 253.71552 -329.947524)
		(end 253.71552 -346.721938)
		(width 0.127)
		(layer "In2.Cu")
		(net "FM_FAN_PWR_EN")
	)
	(segment
		(start 279.87752 -417.73348)
		(end 278.6507 -418.9603)
		(width 0.127)
		(layer "In2.Cu")
		(net "FM_FAN_PWR_EN")
	)
	(segment
		(start 179.186332 -108.16844)
		(end 176.79289 -108.16844)
		(width 0.127)
		(layer "In2.Cu")
		(net "FM_FAN_PWR_EN")
	)
	(segment
		(start 266.12342 -381.1905)
		(end 266.12342 -387.21538)
		(width 0.127)
		(layer "In2.Cu")
		(net "FM_FAN_PWR_EN")
	)
	(segment
		(start 252.12548 -328.357484)
		(end 253.71552 -329.947524)
		(width 0.127)
		(layer "In2.Cu")
		(net "FM_FAN_PWR_EN")
	)
	(segment
		(start 180.78704 -109.769148)
		(end 179.186332 -108.16844)
		(width 0.127)
		(layer "In2.Cu")
		(net "FM_FAN_PWR_EN")
	)
	(segment
		(start 281.80792 -412.52648)
		(end 281.80792 -415.16046)
		(width 0.127)
		(layer "In2.Cu")
		(net "FM_FAN_PWR_EN")
	)
	(segment
		(start 294.82034 -405.77262)
		(end 291.2237 -405.77262)
		(width 0.127)
		(layer "In2.Cu")
		(net "FM_FAN_PWR_EN")
	)
	(segment
		(start 252.12548 -324.661276)
		(end 252.12548 -328.357484)
		(width 0.127)
		(layer "In2.Cu")
		(net "FM_FAN_PWR_EN")
	)
	(segment
		(start 296.4434 -404.14956)
		(end 294.82034 -405.77262)
		(width 0.127)
		(layer "In2.Cu")
		(net "FM_FAN_PWR_EN")
	)
	(segment
		(start 233.415586 -133.735318)
		(end 233.415586 -135.057134)
		(width 0.127)
		(layer "In2.Cu")
		(net "FM_FAN_PWR_EN")
	)
	(segment
		(start 195.02882 -105.578148)
		(end 190.763652 -105.578148)
		(width 0.127)
		(layer "In2.Cu")
		(net "FM_FAN_PWR_EN")
	)
	(segment
		(start 267.95476 -379.35916)
		(end 266.12342 -381.1905)
		(width 0.127)
		(layer "In2.Cu")
		(net "FM_FAN_PWR_EN")
	)
	(segment
		(start 281.80792 -415.16046)
		(end 279.87752 -417.09086)
		(width 0.127)
		(layer "In2.Cu")
		(net "FM_FAN_PWR_EN")
	)
	(segment
		(start 203.33208 -108.328968)
		(end 201.81316 -106.810048)
		(width 0.127)
		(layer "In2.Cu")
		(net "FM_FAN_PWR_EN")
	)
	(segment
		(start 267.06322 -423.07002)
		(end 265.73988 -421.74668)
		(width 0.127)
		(layer "In2.Cu")
		(net "FM_FAN_PWR_EN")
	)
	(segment
		(start 290.59251 -407.34869)
		(end 286.83458 -411.10662)
		(width 0.127)
		(layer "In2.Cu")
		(net "FM_FAN_PWR_EN")
	)
	(segment
		(start 175.760634 -104.742742)
		(end 175.55718 -104.539288)
		(width 0.127)
		(layer "In2.Cu")
		(net "FM_FAN_PWR_EN")
	)
	(segment
		(start 195.40982 -105.197148)
		(end 195.02882 -105.578148)
		(width 0.127)
		(layer "In2.Cu")
		(net "FM_FAN_PWR_EN")
	)
	(segment
		(start 272.95094 -423.07002)
		(end 267.06322 -423.07002)
		(width 0.127)
		(layer "In2.Cu")
		(net "FM_FAN_PWR_EN")
	)
	(segment
		(start 170.555666 -104.935782)
		(end 170.555666 -105.375456)
		(width 0.127)
		(layer "In2.Cu")
		(net "FM_FAN_PWR_EN")
	)
	(segment
		(start 176.562766 -107.515914)
		(end 176.4284 -107.381548)
		(width 0.127)
		(layer "In2.Cu")
		(net "FM_FAN_PWR_EN")
	)
	(segment
		(start 201.81316 -106.810048)
		(end 200.95972 -106.810048)
		(width 0.127)
		(layer "In2.Cu")
		(net "FM_FAN_PWR_EN")
	)
	(segment
		(start 200.95972 -106.810048)
		(end 199.72782 -105.578148)
		(width 0.127)
		(layer "In2.Cu")
		(net "FM_FAN_PWR_EN")
	)
	(segment
		(start 233.695748 -132.216906)
		(end 233.921808 -132.442966)
		(width 0.127)
		(layer "In2.Cu")
		(net "FM_FAN_PWR_EN")
	)
	(segment
		(start 214.7443 -112.814608)
		(end 214.7443 -111.0107)
		(width 0.127)
		(layer "In2.Cu")
		(net "FM_FAN_PWR_EN")
	)
	(segment
		(start 197.44182 -105.578148)
		(end 197.06082 -105.197148)
		(width 0.127)
		(layer "In2.Cu")
		(net "FM_FAN_PWR_EN")
	)
	(segment
		(start 297.00982 -386.26288)
		(end 297.00982 -387.70306)
		(width 0.127)
		(layer "In2.Cu")
		(net "FM_FAN_PWR_EN")
	)
	(segment
		(start 296.4434 -399.5293)
		(end 296.4434 -404.14956)
		(width 0.127)
		(layer "In2.Cu")
		(net "FM_FAN_PWR_EN")
	)
	(segment
		(start 216.307924 -113.773458)
		(end 215.70315 -113.773458)
		(width 0.127)
		(layer "In2.Cu")
		(net "FM_FAN_PWR_EN")
	)
	(segment
		(start 278.6507 -418.9603)
		(end 277.06066 -418.9603)
		(width 0.127)
		(layer "In2.Cu")
		(net "FM_FAN_PWR_EN")
	)
	(segment
		(start 230.634286 -124.789438)
		(end 230.634286 -127.712216)
		(width 0.127)
		(layer "In2.Cu")
		(net "FM_FAN_PWR_EN")
	)
	(segment
		(start 230.634286 -127.712216)
		(end 233.695748 -130.773678)
		(width 0.127)
		(layer "In2.Cu")
		(net "FM_FAN_PWR_EN")
	)
	(segment
		(start 215.70315 -113.773458)
		(end 214.7443 -112.814608)
		(width 0.127)
		(layer "In2.Cu")
		(net "FM_FAN_PWR_EN")
	)
	(segment
		(start 240.33988 -142.789148)
		(end 253.2634 -155.712668)
		(width 0.127)
		(layer "In2.Cu")
		(net "FM_FAN_PWR_EN")
	)
	(segment
		(start 208.992216 -109.438948)
		(end 203.737464 -109.438948)
		(width 0.127)
		(layer "In2.Cu")
		(net "FM_FAN_PWR_EN")
	)
	(segment
		(start 240.33988 -137.51052)
		(end 240.33988 -142.789148)
		(width 0.127)
		(layer "In2.Cu")
		(net "FM_FAN_PWR_EN")
	)
	(segment
		(start 233.695748 -130.773678)
		(end 233.695748 -132.216906)
		(width 0.127)
		(layer "In2.Cu")
		(net "FM_FAN_PWR_EN")
	)
	(segment
		(start 230.27132 -122.071638)
		(end 230.51897 -122.319288)
		(width 0.127)
		(layer "In2.Cu")
		(net "FM_FAN_PWR_EN")
	)
	(segment
		(start 230.51897 -119.28221)
		(end 230.51897 -119.882158)
		(width 0.127)
		(layer "In2.Cu")
		(net "FM_FAN_PWR_EN")
	)
	(segment
		(start 176.4284 -107.381548)
		(end 176.005744 -107.381548)
		(width 0.127)
		(layer "In2.Cu")
		(net "FM_FAN_PWR_EN")
	)
	(segment
		(start 267.09116 -388.18312)
		(end 272.65884 -388.18312)
		(width 0.127)
		(layer "In2.Cu")
		(net "FM_FAN_PWR_EN")
	)
	(segment
		(start 214.7443 -111.0107)
		(end 212.715348 -108.981748)
		(width 0.127)
		(layer "In2.Cu")
		(net "FM_FAN_PWR_EN")
	)
	(segment
		(start 296.50182 -388.21106)
		(end 296.50182 -390.37006)
		(width 0.127)
		(layer "In2.Cu")
		(net "FM_FAN_PWR_EN")
	)
	(segment
		(start 277.06066 -418.9603)
		(end 272.95094 -423.07002)
		(width 0.127)
		(layer "In2.Cu")
		(net "FM_FAN_PWR_EN")
	)
	(segment
		(start 253.71552 -346.721938)
		(end 267.95476 -360.961178)
		(width 0.127)
		(layer "In2.Cu")
		(net "FM_FAN_PWR_EN")
	)
	(segment
		(start 175.55718 -104.539288)
		(end 170.95216 -104.539288)
		(width 0.127)
		(layer "In2.Cu")
		(net "FM_FAN_PWR_EN")
	)
	(segment
		(start 243.86667 -421.74668)
		(end 243.0272 -422.58615)
		(width 0.127)
		(layer "In2.Cu")
		(net "FM_FAN_PWR_EN")
	)
	(segment
		(start 231.078786 -123.794774)
		(end 231.078786 -124.344938)
		(width 0.127)
		(layer "In2.Cu")
		(net "FM_FAN_PWR_EN")
	)
	(segment
		(start 285.17088 -385.8006)
		(end 296.54754 -385.8006)
		(width 0.127)
		(layer "In2.Cu")
		(net "FM_FAN_PWR_EN")
	)
	(segment
		(start 176.562766 -107.938316)
		(end 176.562766 -107.515914)
		(width 0.127)
		(layer "In2.Cu")
		(net "FM_FAN_PWR_EN")
	)
	(segment
		(start 267.95476 -360.961178)
		(end 267.95476 -379.35916)
		(width 0.127)
		(layer "In2.Cu")
		(net "FM_FAN_PWR_EN")
	)
	(segment
		(start 170.95216 -104.539288)
		(end 170.555666 -104.935782)
		(width 0.127)
		(layer "In2.Cu")
		(net "FM_FAN_PWR_EN")
	)
	(segment
		(start 199.72782 -105.578148)
		(end 197.44182 -105.578148)
		(width 0.127)
		(layer "In2.Cu")
		(net "FM_FAN_PWR_EN")
	)
	(segment
		(start 283.99486 -386.97662)
		(end 285.17088 -385.8006)
		(width 0.127)
		(layer "In2.Cu")
		(net "FM_FAN_PWR_EN")
	)
	(segment
		(start 197.06082 -105.197148)
		(end 195.40982 -105.197148)
		(width 0.127)
		(layer "In2.Cu")
		(net "FM_FAN_PWR_EN")
	)
	(segment
		(start 279.87752 -417.09086)
		(end 279.87752 -417.73348)
		(width 0.127)
		(layer "In2.Cu")
		(net "FM_FAN_PWR_EN")
	)
	(segment
		(start 286.83458 -411.10662)
		(end 283.22778 -411.10662)
		(width 0.127)
		(layer "In2.Cu")
		(net "FM_FAN_PWR_EN")
	)
	(segment
		(start 297.7515 -398.2212)
		(end 296.4434 -399.5293)
		(width 0.127)
		(layer "In2.Cu")
		(net "FM_FAN_PWR_EN")
	)
	(segment
		(start 233.921808 -133.229096)
		(end 233.415586 -133.735318)
		(width 0.127)
		(layer "In2.Cu")
		(net "FM_FAN_PWR_EN")
	)
	(segment
		(start 231.078786 -124.344938)
		(end 230.634286 -124.789438)
		(width 0.127)
		(layer "In2.Cu")
		(net "FM_FAN_PWR_EN")
	)
	(segment
		(start 230.51897 -123.234958)
		(end 231.078786 -123.794774)
		(width 0.127)
		(layer "In2.Cu")
		(net "FM_FAN_PWR_EN")
	)
	(segment
		(start 230.27132 -120.129808)
		(end 230.27132 -122.071638)
		(width 0.127)
		(layer "In2.Cu")
		(net "FM_FAN_PWR_EN")
	)
	(segment
		(start 176.005744 -107.381548)
		(end 175.760634 -107.136438)
		(width 0.127)
		(layer "In2.Cu")
		(net "FM_FAN_PWR_EN")
	)
	(segment
		(start 235.466636 -113.180876)
		(end 235.466636 -114.334544)
		(width 0.127)
		(layer "In2.Cu")
		(net "FM_FAN_PWR_EN")
	)
	(segment
		(start 190.763652 -105.578148)
		(end 186.572652 -109.769148)
		(width 0.127)
		(layer "In2.Cu")
		(net "FM_FAN_PWR_EN")
	)
	(segment
		(start 233.415586 -135.057134)
		(end 234.721654 -136.363202)
		(width 0.127)
		(layer "In2.Cu")
		(net "FM_FAN_PWR_EN")
	)
	(segment
		(start 230.51897 -122.319288)
		(end 230.51897 -123.234958)
		(width 0.127)
		(layer "In2.Cu")
		(net "FM_FAN_PWR_EN")
	)
	(segment
		(start 265.73988 -421.74668)
		(end 243.86667 -421.74668)
		(width 0.127)
		(layer "In2.Cu")
		(net "FM_FAN_PWR_EN")
	)
	(segment
		(start 234.869482 -112.583722)
		(end 233.58221 -112.583722)
		(width 0.127)
		(layer "In6.Cu")
		(net "FM_FAN_PWR_EN")
	)
	(segment
		(start 216.55532 -113.773458)
		(end 216.307924 -113.773458)
		(width 0.127)
		(layer "In6.Cu")
		(net "FM_FAN_PWR_EN")
	)
	(segment
		(start 232.90403 -113.261902)
		(end 223.84131 -113.261902)
		(width 0.127)
		(layer "In6.Cu")
		(net "FM_FAN_PWR_EN")
	)
	(segment
		(start 222.376492 -114.72672)
		(end 217.508582 -114.72672)
		(width 0.127)
		(layer "In6.Cu")
		(net "FM_FAN_PWR_EN")
	)
	(segment
		(start 223.84131 -113.261902)
		(end 222.376492 -114.72672)
		(width 0.127)
		(layer "In6.Cu")
		(net "FM_FAN_PWR_EN")
	)
	(segment
		(start 233.58221 -112.583722)
		(end 232.90403 -113.261902)
		(width 0.127)
		(layer "In6.Cu")
		(net "FM_FAN_PWR_EN")
	)
	(segment
		(start 235.466636 -113.180876)
		(end 234.869482 -112.583722)
		(width 0.127)
		(layer "In6.Cu")
		(net "FM_FAN_PWR_EN")
	)
	(segment
		(start 217.508582 -114.72672)
		(end 216.55532 -113.773458)
		(width 0.127)
		(layer "In6.Cu")
		(net "FM_FAN_PWR_EN")
	)
	(via
		(at 235.23448 -424.561)
		(size 0.6604)
		(drill 0.3302)
		(layers "F.Cu" "B.Cu")
		(net "HPDB_HSC_PWRGD_R")
	)
	(segment
		(start 233.369866 -430.50206)
		(end 233.37012 -430.50206)
		(width 0.12954)
		(layer "B.Cu")
		(net "HPDB_HSC_PWRGD_R")
	)
	(segment
		(start 236.214666 -423.401998)
		(end 235.23448 -423.401998)
		(width 0.12954)
		(layer "B.Cu")
		(net "HPDB_HSC_PWRGD_R")
	)
	(segment
		(start 235.23448 -423.401998)
		(end 235.23448 -424.561)
		(width 0.12954)
		(layer "B.Cu")
		(net "HPDB_HSC_PWRGD_R")
	)
	(segment
		(start 235.23448 -424.561)
		(end 234.50296 -425.29252)
		(width 0.12954)
		(layer "B.Cu")
		(net "HPDB_HSC_PWRGD_R")
	)
	(segment
		(start 234.50296 -429.368966)
		(end 233.369866 -430.50206)
		(width 0.12954)
		(layer "B.Cu")
		(net "HPDB_HSC_PWRGD_R")
	)
	(segment
		(start 234.50296 -425.29252)
		(end 234.50296 -429.368966)
		(width 0.12954)
		(layer "B.Cu")
		(net "HPDB_HSC_PWRGD_R")
	)
	(segment
		(start 17.096994 -42.999914)
		(end 15.774924 -42.999914)
		(width 0.12954)
		(layer "F.Cu")
		(net "FM_BIOS_POST_CMPLT_HDR_N")
	)
	(segment
		(start 18.35785 -41.739058)
		(end 17.096994 -42.999914)
		(width 0.12954)
		(layer "F.Cu")
		(net "FM_BIOS_POST_CMPLT_HDR_N")
	)
	(segment
		(start 24.53132 -42.992802)
		(end 24.57196 -42.952162)
		(width 0.12954)
		(layer "F.Cu")
		(net "FM_BIOS_POST_CMPLT_HDR_N")
	)
	(segment
		(start 24.57196 -42.286428)
		(end 24.02459 -41.739058)
		(width 0.12954)
		(layer "F.Cu")
		(net "FM_BIOS_POST_CMPLT_HDR_N")
	)
	(segment
		(start 24.57196 -42.952162)
		(end 24.57196 -42.286428)
		(width 0.12954)
		(layer "F.Cu")
		(net "FM_BIOS_POST_CMPLT_HDR_N")
	)
	(segment
		(start 24.02459 -41.739058)
		(end 18.35785 -41.739058)
		(width 0.12954)
		(layer "F.Cu")
		(net "FM_BIOS_POST_CMPLT_HDR_N")
	)
	(via
		(at 24.02459 -41.739058)
		(size 0.762)
		(drill 0.381)
		(layers "F.Cu" "B.Cu")
		(net "FM_BIOS_POST_CMPLT_HDR_N")
	)
	(segment
		(start 243.61648 -169.357548)
		(end 205.03388 -169.357548)
		(width 0.12954)
		(layer "F.Cu")
		(net "BMC_MONITER_R")
	)
	(segment
		(start 171.325286 -425.143168)
		(end 170.58894 -425.143168)
		(width 0.12954)
		(layer "F.Cu")
		(net "BMC_MONITER_R")
	)
	(segment
		(start 170.08475 -425.143168)
		(end 169.84853 -424.906948)
		(width 0.12954)
		(layer "F.Cu")
		(net "BMC_MONITER_R")
	)
	(segment
		(start 158.877 -107.025948)
		(end 160.147 -105.755948)
		(width 0.12954)
		(layer "F.Cu")
		(net "BMC_MONITER_R")
	)
	(segment
		(start 160.147 -105.755948)
		(end 160.43783 -105.755948)
		(width 0.12954)
		(layer "F.Cu")
		(net "BMC_MONITER_R")
	)
	(segment
		(start 180.1876 -162.258248)
		(end 180.00472 -162.258248)
		(width 0.12954)
		(layer "F.Cu")
		(net "BMC_MONITER_R")
	)
	(segment
		(start 180.87848 -164.683948)
		(end 180.87848 -162.949128)
		(width 0.12954)
		(layer "F.Cu")
		(net "BMC_MONITER_R")
	)
	(segment
		(start 171.41952 -425.048934)
		(end 171.325286 -425.143168)
		(width 0.12954)
		(layer "F.Cu")
		(net "BMC_MONITER_R")
	)
	(segment
		(start 203.355194 -167.678862)
		(end 183.873394 -167.678862)
		(width 0.12954)
		(layer "F.Cu")
		(net "BMC_MONITER_R")
	)
	(segment
		(start 244.04828 -168.925748)
		(end 243.61648 -169.357548)
		(width 0.12954)
		(layer "F.Cu")
		(net "BMC_MONITER_R")
	)
	(segment
		(start 169.84853 -425.922948)
		(end 169.84853 -424.906948)
		(width 0.12954)
		(layer "F.Cu")
		(net "BMC_MONITER_R")
	)
	(segment
		(start 170.58894 -425.143168)
		(end 170.08475 -425.143168)
		(width 0.12954)
		(layer "F.Cu")
		(net "BMC_MONITER_R")
	)
	(segment
		(start 180.87848 -162.949128)
		(end 180.1876 -162.258248)
		(width 0.12954)
		(layer "F.Cu")
		(net "BMC_MONITER_R")
	)
	(segment
		(start 205.03388 -169.357548)
		(end 203.355194 -167.678862)
		(width 0.12954)
		(layer "F.Cu")
		(net "BMC_MONITER_R")
	)
	(segment
		(start 183.873394 -167.678862)
		(end 180.87848 -164.683948)
		(width 0.12954)
		(layer "F.Cu")
		(net "BMC_MONITER_R")
	)
	(via
		(at 244.04828 -168.925748)
		(size 0.508)
		(drill 0.254)
		(layers "F.Cu" "B.Cu")
		(net "BMC_MONITER_R")
	)
	(via
		(at 158.877 -107.025948)
		(size 0.508)
		(drill 0.254)
		(layers "F.Cu" "B.Cu")
		(net "BMC_MONITER_R")
	)
	(via
		(at 180.00472 -162.258248)
		(size 0.508)
		(drill 0.254)
		(layers "F.Cu" "B.Cu")
		(net "BMC_MONITER_R")
	)
	(via
		(at 170.58894 -425.143168)
		(size 0.508)
		(drill 0.254)
		(layers "F.Cu" "B.Cu")
		(net "BMC_MONITER_R")
	)
	(via
		(at 171.63034 -411.56128)
		(size 0.508)
		(drill 0.254)
		(layers "F.Cu" "B.Cu")
		(net "BMC_MONITER_R")
	)
	(segment
		(start 170.92168 -422.22166)
		(end 171.27728 -422.57726)
		(width 0.12954)
		(layer "B.Cu")
		(net "BMC_MONITER_R")
	)
	(segment
		(start 170.64482 -415.5059)
		(end 171.59478 -416.45586)
		(width 0.12954)
		(layer "B.Cu")
		(net "BMC_MONITER_R")
	)
	(segment
		(start 171.63034 -411.56128)
		(end 170.64482 -412.5468)
		(width 0.12954)
		(layer "B.Cu")
		(net "BMC_MONITER_R")
	)
	(segment
		(start 171.59478 -416.45586)
		(end 171.59478 -419.40988)
		(width 0.12954)
		(layer "B.Cu")
		(net "BMC_MONITER_R")
	)
	(segment
		(start 170.92168 -420.08298)
		(end 170.92168 -422.22166)
		(width 0.12954)
		(layer "B.Cu")
		(net "BMC_MONITER_R")
	)
	(segment
		(start 171.27728 -422.57726)
		(end 171.27728 -424.454828)
		(width 0.12954)
		(layer "B.Cu")
		(net "BMC_MONITER_R")
	)
	(segment
		(start 171.59478 -419.40988)
		(end 170.92168 -420.08298)
		(width 0.12954)
		(layer "B.Cu")
		(net "BMC_MONITER_R")
	)
	(segment
		(start 171.27728 -424.454828)
		(end 170.58894 -425.143168)
		(width 0.12954)
		(layer "B.Cu")
		(net "BMC_MONITER_R")
	)
	(segment
		(start 170.64482 -412.5468)
		(end 170.64482 -415.5059)
		(width 0.12954)
		(layer "B.Cu")
		(net "BMC_MONITER_R")
	)
	(segment
		(start 176.35728 -163.312348)
		(end 176.35728 -160.886648)
		(width 0.127)
		(layer "In2.Cu")
		(net "BMC_MONITER_R")
	)
	(segment
		(start 175.4251 -395.800326)
		(end 173.86808 -397.357346)
		(width 0.127)
		(layer "In2.Cu")
		(net "BMC_MONITER_R")
	)
	(segment
		(start 180.00472 -162.258248)
		(end 180.1876 -162.258248)
		(width 0.127)
		(layer "In2.Cu")
		(net "BMC_MONITER_R")
	)
	(segment
		(start 159.131 -126.258828)
		(end 161.1884 -124.201428)
		(width 0.127)
		(layer "In2.Cu")
		(net "BMC_MONITER_R")
	)
	(segment
		(start 172.62348 -411.56128)
		(end 171.63034 -411.56128)
		(width 0.127)
		(layer "In2.Cu")
		(net "BMC_MONITER_R")
	)
	(segment
		(start 180.85308 -162.923728)
		(end 180.85308 -165.090348)
		(width 0.127)
		(layer "In2.Cu")
		(net "BMC_MONITER_R")
	)
	(segment
		(start 180.1876 -162.258248)
		(end 180.85308 -162.923728)
		(width 0.127)
		(layer "In2.Cu")
		(net "BMC_MONITER_R")
	)
	(segment
		(start 157.73908 -108.163868)
		(end 158.877 -107.025948)
		(width 0.127)
		(layer "In2.Cu")
		(net "BMC_MONITER_R")
	)
	(segment
		(start 180.85308 -165.090348)
		(end 180.72608 -165.217348)
		(width 0.127)
		(layer "In2.Cu")
		(net "BMC_MONITER_R")
	)
	(segment
		(start 173.86808 -410.31668)
		(end 172.62348 -411.56128)
		(width 0.127)
		(layer "In2.Cu")
		(net "BMC_MONITER_R")
	)
	(segment
		(start 157.73908 -109.286548)
		(end 157.73908 -108.163868)
		(width 0.127)
		(layer "In2.Cu")
		(net "BMC_MONITER_R")
	)
	(segment
		(start 220.55074 -362.959142)
		(end 214.546942 -368.96294)
		(width 0.127)
		(layer "In2.Cu")
		(net "BMC_MONITER_R")
	)
	(segment
		(start 197.938644 -368.96294)
		(end 175.4251 -391.476484)
		(width 0.127)
		(layer "In2.Cu")
		(net "BMC_MONITER_R")
	)
	(segment
		(start 176.35728 -160.886648)
		(end 159.131 -143.660368)
		(width 0.127)
		(layer "In2.Cu")
		(net "BMC_MONITER_R")
	)
	(segment
		(start 246.1768 -319.207642)
		(end 220.55074 -344.833702)
		(width 0.127)
		(layer "In2.Cu")
		(net "BMC_MONITER_R")
	)
	(segment
		(start 173.86808 -397.357346)
		(end 173.86808 -410.31668)
		(width 0.127)
		(layer "In2.Cu")
		(net "BMC_MONITER_R")
	)
	(segment
		(start 245.87454 -170.752008)
		(end 245.87454 -241.851688)
		(width 0.127)
		(layer "In2.Cu")
		(net "BMC_MONITER_R")
	)
	(segment
		(start 214.546942 -368.96294)
		(end 197.938644 -368.96294)
		(width 0.127)
		(layer "In2.Cu")
		(net "BMC_MONITER_R")
	)
	(segment
		(start 159.131 -143.660368)
		(end 159.131 -126.258828)
		(width 0.127)
		(layer "In2.Cu")
		(net "BMC_MONITER_R")
	)
	(segment
		(start 158.70428 -110.251748)
		(end 157.73908 -109.286548)
		(width 0.127)
		(layer "In2.Cu")
		(net "BMC_MONITER_R")
	)
	(segment
		(start 161.1884 -111.389668)
		(end 160.05048 -110.251748)
		(width 0.127)
		(layer "In2.Cu")
		(net "BMC_MONITER_R")
	)
	(segment
		(start 246.1768 -242.153948)
		(end 246.1768 -319.207642)
		(width 0.127)
		(layer "In2.Cu")
		(net "BMC_MONITER_R")
	)
	(segment
		(start 178.26228 -165.217348)
		(end 176.35728 -163.312348)
		(width 0.127)
		(layer "In2.Cu")
		(net "BMC_MONITER_R")
	)
	(segment
		(start 180.72608 -165.217348)
		(end 178.26228 -165.217348)
		(width 0.127)
		(layer "In2.Cu")
		(net "BMC_MONITER_R")
	)
	(segment
		(start 175.4251 -391.476484)
		(end 175.4251 -395.800326)
		(width 0.127)
		(layer "In2.Cu")
		(net "BMC_MONITER_R")
	)
	(segment
		(start 161.1884 -124.201428)
		(end 161.1884 -111.389668)
		(width 0.127)
		(layer "In2.Cu")
		(net "BMC_MONITER_R")
	)
	(segment
		(start 244.04828 -168.925748)
		(end 245.87454 -170.752008)
		(width 0.127)
		(layer "In2.Cu")
		(net "BMC_MONITER_R")
	)
	(segment
		(start 220.55074 -344.833702)
		(end 220.55074 -362.959142)
		(width 0.127)
		(layer "In2.Cu")
		(net "BMC_MONITER_R")
	)
	(segment
		(start 245.87454 -241.851688)
		(end 246.1768 -242.153948)
		(width 0.127)
		(layer "In2.Cu")
		(net "BMC_MONITER_R")
	)
	(segment
		(start 160.05048 -110.251748)
		(end 158.70428 -110.251748)
		(width 0.127)
		(layer "In2.Cu")
		(net "BMC_MONITER_R")
	)
	(segment
		(start 174.193454 -425.922948)
		(end 173.31944 -425.048934)
		(width 0.12954)
		(layer "F.Cu")
		(net "BMC_MONITER_BUF_R")
	)
	(segment
		(start 175.77943 -426.430948)
		(end 175.77943 -427.446948)
		(width 0.12954)
		(layer "F.Cu")
		(net "BMC_MONITER_BUF_R")
	)
	(segment
		(start 175.77943 -425.414948)
		(end 175.77943 -426.430948)
		(width 0.12954)
		(layer "F.Cu")
		(net "BMC_MONITER_BUF_R")
	)
	(segment
		(start 174.52848 -425.922948)
		(end 174.193454 -425.922948)
		(width 0.12954)
		(layer "F.Cu")
		(net "BMC_MONITER_BUF_R")
	)
	(segment
		(start 175.77943 -425.414948)
		(end 175.27143 -425.922948)
		(width 0.12954)
		(layer "F.Cu")
		(net "BMC_MONITER_BUF_R")
	)
	(segment
		(start 175.27143 -425.922948)
		(end 174.52848 -425.922948)
		(width 0.12954)
		(layer "F.Cu")
		(net "BMC_MONITER_BUF_R")
	)
	(via
		(at 174.52848 -425.922948)
		(size 0.762)
		(drill 0.381)
		(layers "F.Cu" "B.Cu")
		(net "BMC_MONITER_BUF_R")
	)
	(segment
		(start 171.066968 -13.061696)
		(end 170.896788 -12.891516)
		(width 0.13208)
		(layer "F.Cu")
		(net "CLK_100M_BMC_P3E_DP_R")
	)
	(segment
		(start 170.896788 -12.891516)
		(end 170.896788 -12.307316)
		(width 0.13208)
		(layer "F.Cu")
		(net "CLK_100M_BMC_P3E_DP_R")
	)
	(segment
		(start 170.896788 -12.307316)
		(end 171.199048 -12.005056)
		(width 0.13208)
		(layer "F.Cu")
		(net "CLK_100M_BMC_P3E_DP_R")
	)
	(segment
		(start 171.066968 -13.600176)
		(end 171.066968 -13.061696)
		(width 0.13208)
		(layer "F.Cu")
		(net "CLK_100M_BMC_P3E_DP_R")
	)
	(via
		(at 171.199048 -12.005056)
		(size 0.508)
		(drill 0.254)
		(layers "F.Cu" "B.Cu")
		(net "CLK_100M_BMC_P3E_DP_R")
	)
	(segment
		(start 170.8658 -13.011658)
		(end 171.21632 -13.362178)
		(width 0.13208)
		(layer "B.Cu")
		(net "CLK_100M_BMC_P3E_DP_R")
	)
	(segment
		(start 170.8658 -12.338304)
		(end 170.8658 -13.011658)
		(width 0.13208)
		(layer "B.Cu")
		(net "CLK_100M_BMC_P3E_DP_R")
	)
	(segment
		(start 171.199048 -12.005056)
		(end 170.8658 -12.338304)
		(width 0.13208)
		(layer "B.Cu")
		(net "CLK_100M_BMC_P3E_DP_R")
	)
	(segment
		(start 170.46702 -13.074904)
		(end 170.637708 -12.904216)
		(width 0.13208)
		(layer "F.Cu")
		(net "CLK_100M_BMC_P3E_DN_R")
	)
	(segment
		(start 170.637708 -12.307316)
		(end 170.335448 -12.005056)
		(width 0.13208)
		(layer "F.Cu")
		(net "CLK_100M_BMC_P3E_DN_R")
	)
	(segment
		(start 170.46702 -13.600176)
		(end 170.46702 -13.074904)
		(width 0.13208)
		(layer "F.Cu")
		(net "CLK_100M_BMC_P3E_DN_R")
	)
	(segment
		(start 170.637708 -12.904216)
		(end 170.637708 -12.307316)
		(width 0.13208)
		(layer "F.Cu")
		(net "CLK_100M_BMC_P3E_DN_R")
	)
	(via
		(at 170.335448 -12.005056)
		(size 0.508)
		(drill 0.254)
		(layers "F.Cu" "B.Cu")
		(net "CLK_100M_BMC_P3E_DN_R")
	)
	(segment
		(start 170.60672 -12.955778)
		(end 170.20032 -13.362178)
		(width 0.13208)
		(layer "B.Cu")
		(net "CLK_100M_BMC_P3E_DN_R")
	)
	(segment
		(start 170.60672 -12.276328)
		(end 170.60672 -12.955778)
		(width 0.13208)
		(layer "B.Cu")
		(net "CLK_100M_BMC_P3E_DN_R")
	)
	(segment
		(start 170.335448 -12.005056)
		(end 170.60672 -12.276328)
		(width 0.13208)
		(layer "B.Cu")
		(net "CLK_100M_BMC_P3E_DN_R")
	)
	(segment
		(start 218.329256 -98.84156)
		(end 219.010738 -98.84156)
		(width 0.12954)
		(layer "F.Cu")
		(net "A_P12V_STBY_FP_TRIGGER")
	)
	(segment
		(start 219.010738 -98.84156)
		(end 219.687394 -98.164904)
		(width 0.12954)
		(layer "F.Cu")
		(net "A_P12V_STBY_FP_TRIGGER")
	)
	(segment
		(start 216.661492 -98.84156)
		(end 218.329256 -98.84156)
		(width 0.12954)
		(layer "F.Cu")
		(net "A_P12V_STBY_FP_TRIGGER")
	)
	(segment
		(start 219.687394 -98.164904)
		(end 219.687394 -97.13341)
		(width 0.12954)
		(layer "F.Cu")
		(net "A_P12V_STBY_FP_TRIGGER")
	)
	(via
		(at 218.329256 -98.84156)
		(size 0.762)
		(drill 0.381)
		(layers "F.Cu" "B.Cu")
		(net "A_P12V_STBY_FP_TRIGGER")
	)
	(segment
		(start 210.16595 -98.014536)
		(end 210.960462 -98.809048)
		(width 0.12954)
		(layer "F.Cu")
		(net "A_P12V_STBY_ADR_TRIGGER")
	)
	(segment
		(start 214.041736 -98.84156)
		(end 212.233256 -98.84156)
		(width 0.12954)
		(layer "F.Cu")
		(net "A_P12V_STBY_ADR_TRIGGER")
	)
	(segment
		(start 210.16595 -97.6376)
		(end 210.16595 -98.014536)
		(width 0.12954)
		(layer "F.Cu")
		(net "A_P12V_STBY_ADR_TRIGGER")
	)
	(segment
		(start 212.233256 -98.84156)
		(end 210.992974 -98.84156)
		(width 0.12954)
		(layer "F.Cu")
		(net "A_P12V_STBY_ADR_TRIGGER")
	)
	(segment
		(start 210.992974 -98.84156)
		(end 210.960462 -98.809048)
		(width 0.12954)
		(layer "F.Cu")
		(net "A_P12V_STBY_ADR_TRIGGER")
	)
	(via
		(at 212.233256 -98.84156)
		(size 0.762)
		(drill 0.381)
		(layers "F.Cu" "B.Cu")
		(net "A_P12V_STBY_ADR_TRIGGER")
	)
	(segment
		(start 219.700602 -106.384344)
		(end 219.700602 -105.226104)
		(width 0.12954)
		(layer "F.Cu")
		(net "A_HSC_INAP")
	)
	(segment
		(start 218.351608 -105.283)
		(end 218.408504 -105.226104)
		(width 0.12954)
		(layer "F.Cu")
		(net "A_HSC_INAP")
	)
	(segment
		(start 216.6874 -105.283)
		(end 218.351608 -105.283)
		(width 0.12954)
		(layer "F.Cu")
		(net "A_HSC_INAP")
	)
	(segment
		(start 218.408504 -105.226104)
		(end 219.700602 -105.226104)
		(width 0.12954)
		(layer "F.Cu")
		(net "A_HSC_INAP")
	)
	(via
		(at 218.408504 -105.226104)
		(size 0.762)
		(drill 0.381)
		(layers "F.Cu" "B.Cu")
		(net "A_HSC_INAP")
	)
	(segment
		(start 204.997558 -399.743422)
		(end 204.381608 -399.743422)
		(width 0.254)
		(layer "F.Cu")
		(net "AGND_HSC")
	)
	(segment
		(start 215.665558 -405.839422)
		(end 215.049608 -405.839422)
		(width 0.12954)
		(layer "F.Cu")
		(net "AGND_HSC")
	)
	(segment
		(start 182.309008 -398.651222)
		(end 182.797958 -398.651222)
		(width 0.3556)
		(layer "F.Cu")
		(net "AGND_HSC")
	)
	(segment
		(start 226.282758 -402.842222)
		(end 226.333558 -402.791422)
		(width 0.254)
		(layer "F.Cu")
		(net "AGND_HSC")
	)
	(segment
		(start 227.927408 -403.877272)
		(end 228.410008 -403.394672)
		(width 0.3556)
		(layer "F.Cu")
		(net "AGND_HSC")
	)
	(segment
		(start 227.133658 -407.871422)
		(end 227.749608 -407.871422)
		(width 0.254)
		(layer "F.Cu")
		(net "AGND_HSC")
	)
	(segment
		(start 182.676546 -402.49729)
		(end 182.019448 -402.49729)
		(width 0.254)
		(layer "F.Cu")
		(net "AGND_HSC")
	)
	(segment
		(start 182.97398 -397.278352)
		(end 182.97398 -397.99514)
		(width 0.3556)
		(layer "F.Cu")
		(net "AGND_HSC")
	)
	(segment
		(start 237.801658 -402.689822)
		(end 238.417608 -402.689822)
		(width 0.254)
		(layer "F.Cu")
		(net "AGND_HSC")
	)
	(segment
		(start 178.960018 -398.183862)
		(end 178.952398 -398.191482)
		(width 0.3556)
		(layer "F.Cu")
		(net "AGND_HSC")
	)
	(segment
		(start 225.717608 -402.842222)
		(end 226.282758 -402.842222)
		(width 0.254)
		(layer "F.Cu")
		(net "AGND_HSC")
	)
	(segment
		(start 180.354224 -401.955762)
		(end 181.47792 -401.955762)
		(width 0.3556)
		(layer "F.Cu")
		(net "AGND_HSC")
	)
	(segment
		(start 204.997558 -401.775422)
		(end 204.381608 -401.775422)
		(width 0.3556)
		(layer "F.Cu")
		(net "AGND_HSC")
	)
	(segment
		(start 196.523102 -402.972778)
		(end 196.329808 -403.166072)
		(width 0.254)
		(layer "F.Cu")
		(net "AGND_HSC")
	)
	(segment
		(start 226.333558 -399.743422)
		(end 225.717608 -399.743422)
		(width 0.254)
		(layer "F.Cu")
		(net "AGND_HSC")
	)
	(segment
		(start 207.232504 -403.394672)
		(end 207.074008 -403.394672)
		(width 0.254)
		(layer "F.Cu")
		(net "AGND_HSC")
	)
	(segment
		(start 180.054504 -402.255482)
		(end 180.354224 -401.955762)
		(width 0.3556)
		(layer "F.Cu")
		(net "AGND_HSC")
	)
	(segment
		(start 227.927408 -404.086822)
		(end 227.927408 -403.877272)
		(width 0.3556)
		(layer "F.Cu")
		(net "AGND_HSC")
	)
	(segment
		(start 215.614758 -402.842222)
		(end 215.665558 -402.791422)
		(width 0.254)
		(layer "F.Cu")
		(net "AGND_HSC")
	)
	(segment
		(start 237.801658 -404.721822)
		(end 238.417608 -404.721822)
		(width 0.254)
		(layer "F.Cu")
		(net "AGND_HSC")
	)
	(segment
		(start 182.156608 -398.803622)
		(end 182.309008 -398.651222)
		(width 0.3556)
		(layer "F.Cu")
		(net "AGND_HSC")
	)
	(segment
		(start 216.465658 -407.871422)
		(end 217.081608 -407.871422)
		(width 0.254)
		(layer "F.Cu")
		(net "AGND_HSC")
	)
	(segment
		(start 178.952398 -405.303482)
		(end 178.952398 -404.287482)
		(width 0.254)
		(layer "F.Cu")
		(net "AGND_HSC")
	)
	(segment
		(start 194.456558 -404.086822)
		(end 193.840608 -404.086822)
		(width 0.254)
		(layer "F.Cu")
		(net "AGND_HSC")
	)
	(segment
		(start 178.952398 -398.191482)
		(end 178.952398 -399.207482)
		(width 0.3556)
		(layer "F.Cu")
		(net "AGND_HSC")
	)
	(segment
		(start 178.960018 -397.188182)
		(end 178.960018 -398.183862)
		(width 0.3556)
		(layer "F.Cu")
		(net "AGND_HSC")
	)
	(segment
		(start 178.952398 -400.223482)
		(end 178.336448 -400.223482)
		(width 0.3556)
		(layer "F.Cu")
		(net "AGND_HSC")
	)
	(segment
		(start 206.591408 -404.086822)
		(end 206.591408 -403.877272)
		(width 0.3556)
		(layer "F.Cu")
		(net "AGND_HSC")
	)
	(segment
		(start 197.93458 -402.972778)
		(end 196.523102 -402.972778)
		(width 0.254)
		(layer "F.Cu")
		(net "AGND_HSC")
	)
	(segment
		(start 208.60258 -402.972778)
		(end 207.654398 -402.972778)
		(width 0.254)
		(layer "F.Cu")
		(net "AGND_HSC")
	)
	(segment
		(start 205.797658 -404.823422)
		(end 206.413608 -404.823422)
		(width 0.254)
		(layer "F.Cu")
		(net "AGND_HSC")
	)
	(segment
		(start 192.452498 -404.414482)
		(end 193.068448 -404.414482)
		(width 0.3556)
		(layer "F.Cu")
		(net "AGND_HSC")
	)
	(segment
		(start 217.259408 -403.877272)
		(end 217.742008 -403.394672)
		(width 0.3556)
		(layer "F.Cu")
		(net "AGND_HSC")
	)
	(segment
		(start 196.329808 -403.166072)
		(end 195.644008 -403.166072)
		(width 0.3556)
		(layer "F.Cu")
		(net "AGND_HSC")
	)
	(segment
		(start 194.456558 -401.800822)
		(end 193.840608 -401.800822)
		(width 0.254)
		(layer "F.Cu")
		(net "AGND_HSC")
	)
	(segment
		(start 228.568504 -403.394672)
		(end 228.990398 -402.972778)
		(width 0.254)
		(layer "F.Cu")
		(net "AGND_HSC")
	)
	(segment
		(start 206.591408 -403.877272)
		(end 207.074008 -403.394672)
		(width 0.3556)
		(layer "F.Cu")
		(net "AGND_HSC")
	)
	(segment
		(start 207.654398 -402.972778)
		(end 207.232504 -403.394672)
		(width 0.254)
		(layer "F.Cu")
		(net "AGND_HSC")
	)
	(segment
		(start 184.290208 -409.329382)
		(end 184.290208 -407.839672)
		(width 0.3556)
		(layer "F.Cu")
		(net "AGND_HSC")
	)
	(segment
		(start 217.259408 -404.086822)
		(end 217.259408 -403.877272)
		(width 0.3556)
		(layer "F.Cu")
		(net "AGND_HSC")
	)
	(segment
		(start 228.410008 -403.394672)
		(end 228.568504 -403.394672)
		(width 0.254)
		(layer "F.Cu")
		(net "AGND_HSC")
	)
	(segment
		(start 215.665558 -399.743422)
		(end 215.049608 -399.743422)
		(width 0.254)
		(layer "F.Cu")
		(net "AGND_HSC")
	)
	(segment
		(start 194.456558 -400.784822)
		(end 193.840608 -400.784822)
		(width 0.254)
		(layer "F.Cu")
		(net "AGND_HSC")
	)
	(segment
		(start 194.453256 -399.743422)
		(end 193.840608 -399.743422)
		(width 0.254)
		(layer "F.Cu")
		(net "AGND_HSC")
	)
	(segment
		(start 217.900504 -403.394672)
		(end 217.742008 -403.394672)
		(width 0.254)
		(layer "F.Cu")
		(net "AGND_HSC")
	)
	(segment
		(start 184.38114 -409.420314)
		(end 184.290208 -409.329382)
		(width 0.3556)
		(layer "F.Cu")
		(net "AGND_HSC")
	)
	(segment
		(start 228.990398 -402.972778)
		(end 229.93858 -402.972778)
		(width 0.254)
		(layer "F.Cu")
		(net "AGND_HSC")
	)
	(segment
		(start 204.997558 -405.839422)
		(end 204.381608 -405.839422)
		(width 0.12954)
		(layer "F.Cu")
		(net "AGND_HSC")
	)
	(segment
		(start 178.952398 -403.271482)
		(end 178.336448 -403.271482)
		(width 0.254)
		(layer "F.Cu")
		(net "AGND_HSC")
	)
	(segment
		(start 178.952398 -401.239482)
		(end 178.336448 -401.239482)
		(width 0.3556)
		(layer "F.Cu")
		(net "AGND_HSC")
	)
	(segment
		(start 215.049608 -402.842222)
		(end 215.614758 -402.842222)
		(width 0.254)
		(layer "F.Cu")
		(net "AGND_HSC")
	)
	(segment
		(start 184.38114 -409.4226)
		(end 184.38114 -409.420314)
		(width 0.3556)
		(layer "F.Cu")
		(net "AGND_HSC")
	)
	(segment
		(start 227.133658 -404.823422)
		(end 227.749608 -404.823422)
		(width 0.254)
		(layer "F.Cu")
		(net "AGND_HSC")
	)
	(segment
		(start 181.47792 -401.955762)
		(end 182.019448 -402.49729)
		(width 0.3556)
		(layer "F.Cu")
		(net "AGND_HSC")
	)
	(segment
		(start 178.952398 -404.287482)
		(end 178.336448 -404.287482)
		(width 0.254)
		(layer "F.Cu")
		(net "AGND_HSC")
	)
	(segment
		(start 226.333558 -405.839422)
		(end 225.717608 -405.839422)
		(width 0.12954)
		(layer "F.Cu")
		(net "AGND_HSC")
	)
	(segment
		(start 178.952398 -399.207482)
		(end 178.336448 -399.207482)
		(width 0.3556)
		(layer "F.Cu")
		(net "AGND_HSC")
	)
	(segment
		(start 204.381608 -402.842222)
		(end 204.946758 -402.842222)
		(width 0.254)
		(layer "F.Cu")
		(net "AGND_HSC")
	)
	(segment
		(start 204.946758 -402.842222)
		(end 204.997558 -402.791422)
		(width 0.254)
		(layer "F.Cu")
		(net "AGND_HSC")
	)
	(segment
		(start 218.322398 -402.972778)
		(end 217.900504 -403.394672)
		(width 0.254)
		(layer "F.Cu")
		(net "AGND_HSC")
	)
	(segment
		(start 215.665558 -401.775422)
		(end 215.049608 -401.775422)
		(width 0.3556)
		(layer "F.Cu")
		(net "AGND_HSC")
	)
	(segment
		(start 179.752498 -402.255482)
		(end 180.054504 -402.255482)
		(width 0.3556)
		(layer "F.Cu")
		(net "AGND_HSC")
	)
	(segment
		(start 219.27058 -402.972778)
		(end 218.322398 -402.972778)
		(width 0.254)
		(layer "F.Cu")
		(net "AGND_HSC")
	)
	(segment
		(start 226.333558 -401.775422)
		(end 225.717608 -401.775422)
		(width 0.3556)
		(layer "F.Cu")
		(net "AGND_HSC")
	)
	(segment
		(start 216.465658 -404.823422)
		(end 217.081608 -404.823422)
		(width 0.254)
		(layer "F.Cu")
		(net "AGND_HSC")
	)
	(segment
		(start 205.797658 -407.871422)
		(end 206.413608 -407.871422)
		(width 0.254)
		(layer "F.Cu")
		(net "AGND_HSC")
	)
	(via
		(at 225.717608 -402.842222)
		(size 0.508)
		(drill 0.254)
		(layers "F.Cu" "B.Cu")
		(net "AGND_HSC")
	)
	(via
		(at 215.049608 -402.842222)
		(size 0.508)
		(drill 0.254)
		(layers "F.Cu" "B.Cu")
		(net "AGND_HSC")
	)
	(via
		(at 225.717608 -405.839422)
		(size 0.508)
		(drill 0.254)
		(layers "F.Cu" "B.Cu")
		(net "AGND_HSC")
	)
	(via
		(at 195.644008 -403.166072)
		(size 0.508)
		(drill 0.254)
		(layers "F.Cu" "B.Cu")
		(net "AGND_HSC")
	)
	(via
		(at 184.52211 -403.5933)
		(size 0.508)
		(drill 0.254)
		(layers "F.Cu" "B.Cu")
		(net "AGND_HSC")
	)
	(via
		(at 204.381608 -399.743422)
		(size 0.508)
		(drill 0.254)
		(layers "F.Cu" "B.Cu")
		(net "AGND_HSC")
	)
	(via
		(at 206.413608 -407.871422)
		(size 0.508)
		(drill 0.254)
		(layers "F.Cu" "B.Cu")
		(net "AGND_HSC")
	)
	(via
		(at 215.049608 -399.743422)
		(size 0.508)
		(drill 0.254)
		(layers "F.Cu" "B.Cu")
		(net "AGND_HSC")
	)
	(via
		(at 206.591408 -404.086822)
		(size 0.508)
		(drill 0.254)
		(layers "F.Cu" "B.Cu")
		(net "AGND_HSC")
	)
	(via
		(at 183.50611 -403.5933)
		(size 0.508)
		(drill 0.254)
		(layers "F.Cu" "B.Cu")
		(net "AGND_HSC")
	)
	(via
		(at 178.336448 -399.207482)
		(size 0.508)
		(drill 0.254)
		(layers "F.Cu" "B.Cu")
		(net "AGND_HSC")
	)
	(via
		(at 225.717608 -399.743422)
		(size 0.508)
		(drill 0.254)
		(layers "F.Cu" "B.Cu")
		(net "AGND_HSC")
	)
	(via
		(at 217.081608 -404.823422)
		(size 0.508)
		(drill 0.254)
		(layers "F.Cu" "B.Cu")
		(net "AGND_HSC")
	)
	(via
		(at 204.381608 -405.839422)
		(size 0.508)
		(drill 0.254)
		(layers "F.Cu" "B.Cu")
		(net "AGND_HSC")
	)
	(via
		(at 193.840608 -401.800822)
		(size 0.508)
		(drill 0.254)
		(layers "F.Cu" "B.Cu")
		(net "AGND_HSC")
	)
	(via
		(at 215.049608 -401.775422)
		(size 0.508)
		(drill 0.254)
		(layers "F.Cu" "B.Cu")
		(net "AGND_HSC")
	)
	(via
		(at 178.90998 -407.56332)
		(size 0.508)
		(drill 0.254)
		(layers "F.Cu" "B.Cu")
		(net "AGND_HSC")
	)
	(via
		(at 184.01411 -404.1013)
		(size 0.508)
		(drill 0.254)
		(layers "F.Cu" "B.Cu")
		(net "AGND_HSC")
	)
	(via
		(at 193.840608 -399.743422)
		(size 0.508)
		(drill 0.254)
		(layers "F.Cu" "B.Cu")
		(net "AGND_HSC")
	)
	(via
		(at 178.336448 -404.287482)
		(size 0.508)
		(drill 0.254)
		(layers "F.Cu" "B.Cu")
		(net "AGND_HSC")
	)
	(via
		(at 206.413608 -404.823422)
		(size 0.508)
		(drill 0.254)
		(layers "F.Cu" "B.Cu")
		(net "AGND_HSC")
	)
	(via
		(at 215.049608 -405.839422)
		(size 0.508)
		(drill 0.254)
		(layers "F.Cu" "B.Cu")
		(net "AGND_HSC")
	)
	(via
		(at 182.156608 -398.803622)
		(size 0.508)
		(drill 0.254)
		(layers "F.Cu" "B.Cu")
		(net "AGND_HSC")
	)
	(via
		(at 227.749608 -404.823422)
		(size 0.508)
		(drill 0.254)
		(layers "F.Cu" "B.Cu")
		(net "AGND_HSC")
	)
	(via
		(at 238.417608 -402.689822)
		(size 0.508)
		(drill 0.254)
		(layers "F.Cu" "B.Cu")
		(net "AGND_HSC")
	)
	(via
		(at 204.381608 -401.775422)
		(size 0.508)
		(drill 0.254)
		(layers "F.Cu" "B.Cu")
		(net "AGND_HSC")
	)
	(via
		(at 227.927408 -404.086822)
		(size 0.508)
		(drill 0.254)
		(layers "F.Cu" "B.Cu")
		(net "AGND_HSC")
	)
	(via
		(at 238.417608 -404.721822)
		(size 0.508)
		(drill 0.254)
		(layers "F.Cu" "B.Cu")
		(net "AGND_HSC")
	)
	(via
		(at 184.38114 -409.4226)
		(size 0.508)
		(drill 0.254)
		(layers "F.Cu" "B.Cu")
		(net "AGND_HSC")
	)
	(via
		(at 225.717608 -401.775422)
		(size 0.508)
		(drill 0.254)
		(layers "F.Cu" "B.Cu")
		(net "AGND_HSC")
	)
	(via
		(at 217.081608 -407.871422)
		(size 0.508)
		(drill 0.254)
		(layers "F.Cu" "B.Cu")
		(net "AGND_HSC")
	)
	(via
		(at 178.336448 -400.223482)
		(size 0.508)
		(drill 0.254)
		(layers "F.Cu" "B.Cu")
		(net "AGND_HSC")
	)
	(via
		(at 193.068448 -404.414482)
		(size 0.508)
		(drill 0.254)
		(layers "F.Cu" "B.Cu")
		(net "AGND_HSC")
	)
	(via
		(at 182.019448 -402.49729)
		(size 0.508)
		(drill 0.254)
		(layers "F.Cu" "B.Cu")
		(net "AGND_HSC")
	)
	(via
		(at 193.840608 -404.086822)
		(size 0.508)
		(drill 0.254)
		(layers "F.Cu" "B.Cu")
		(net "AGND_HSC")
	)
	(via
		(at 204.381608 -402.842222)
		(size 0.508)
		(drill 0.254)
		(layers "F.Cu" "B.Cu")
		(net "AGND_HSC")
	)
	(via
		(at 178.336448 -401.239482)
		(size 0.508)
		(drill 0.254)
		(layers "F.Cu" "B.Cu")
		(net "AGND_HSC")
	)
	(via
		(at 227.749608 -407.871422)
		(size 0.508)
		(drill 0.254)
		(layers "F.Cu" "B.Cu")
		(net "AGND_HSC")
	)
	(via
		(at 182.97398 -397.99514)
		(size 0.508)
		(drill 0.254)
		(layers "F.Cu" "B.Cu")
		(net "AGND_HSC")
	)
	(via
		(at 178.336448 -403.271482)
		(size 0.508)
		(drill 0.254)
		(layers "F.Cu" "B.Cu")
		(net "AGND_HSC")
	)
	(via
		(at 217.259408 -404.086822)
		(size 0.508)
		(drill 0.254)
		(layers "F.Cu" "B.Cu")
		(net "AGND_HSC")
	)
	(via
		(at 193.840608 -400.784822)
		(size 0.508)
		(drill 0.254)
		(layers "F.Cu" "B.Cu")
		(net "AGND_HSC")
	)
	(segment
		(start 178.952398 -403.271482)
		(end 178.336448 -403.271482)
		(width 0.3556)
		(layer "B.Cu")
		(net "AGND_HSC")
	)
	(segment
		(start 182.156608 -398.803622)
		(end 182.309008 -398.651222)
		(width 0.3556)
		(layer "B.Cu")
		(net "AGND_HSC")
	)
	(segment
		(start 182.309008 -398.651222)
		(end 182.772558 -398.651222)
		(width 0.3556)
		(layer "B.Cu")
		(net "AGND_HSC")
	)
	(segment
		(start 184.38114 -409.4226)
		(end 184.38114 -408.649424)
		(width 0.254)
		(layer "B.Cu")
		(net "AGND_HSC")
	)
	(segment
		(start 178.90998 -407.3525)
		(end 178.90998 -407.56332)
		(width 0.254)
		(layer "B.Cu")
		(net "AGND_HSC")
	)
	(segment
		(start 184.38114 -408.649424)
		(end 183.995568 -408.263852)
		(width 0.254)
		(layer "B.Cu")
		(net "AGND_HSC")
	)
	(segment
		(start 179.358798 -406.903682)
		(end 178.90998 -407.3525)
		(width 0.254)
		(layer "B.Cu")
		(net "AGND_HSC")
	)
	(segment
		(start 325.45528 -31.22168)
		(end 325.45528 -31.835852)
		(width 0.12954)
		(layer "F.Cu")
		(net "XTAL_PCH_RTC2_R")
	)
	(segment
		(start 326.35571 -32.970978)
		(end 326.6821 -33.297368)
		(width 0.12954)
		(layer "F.Cu")
		(net "XTAL_PCH_RTC2_R")
	)
	(segment
		(start 324.22592 -30.18028)
		(end 324.41388 -30.18028)
		(width 0.12954)
		(layer "F.Cu")
		(net "XTAL_PCH_RTC2_R")
	)
	(segment
		(start 327.013824 -33.629092)
		(end 327.013824 -33.918652)
		(width 0.12954)
		(layer "F.Cu")
		(net "XTAL_PCH_RTC2_R")
	)
	(segment
		(start 326.040242 -32.970978)
		(end 326.35571 -32.970978)
		(width 0.12954)
		(layer "F.Cu")
		(net "XTAL_PCH_RTC2_R")
	)
	(segment
		(start 324.41388 -30.18028)
		(end 325.45528 -31.22168)
		(width 0.12954)
		(layer "F.Cu")
		(net "XTAL_PCH_RTC2_R")
	)
	(segment
		(start 326.040242 -32.970978)
		(end 326.040242 -32.76219)
		(width 0.12954)
		(layer "F.Cu")
		(net "XTAL_PCH_RTC2_R")
	)
	(segment
		(start 326.6821 -33.297368)
		(end 327.013824 -33.629092)
		(width 0.12954)
		(layer "F.Cu")
		(net "XTAL_PCH_RTC2_R")
	)
	(segment
		(start 325.45528 -31.835852)
		(end 325.440548 -31.850584)
		(width 0.12954)
		(layer "F.Cu")
		(net "XTAL_PCH_RTC2_R")
	)
	(segment
		(start 326.040242 -32.76219)
		(end 325.440548 -32.162496)
		(width 0.12954)
		(layer "F.Cu")
		(net "XTAL_PCH_RTC2_R")
	)
	(segment
		(start 325.440548 -32.162496)
		(end 325.440548 -31.850584)
		(width 0.12954)
		(layer "F.Cu")
		(net "XTAL_PCH_RTC2_R")
	)
	(via
		(at 326.6821 -33.297368)
		(size 0.508)
		(drill 0.254)
		(layers "F.Cu" "B.Cu")
		(net "XTAL_PCH_RTC2_R")
	)
	(segment
		(start 329.276456 -37.930582)
		(end 329.39609 -38.050216)
		(width 0.12954)
		(layer "F.Cu")
		(net "XTAL_PCH_RTC2")
	)
	(segment
		(start 328.763884 -36.259008)
		(end 329.276456 -37.495226)
		(width 0.12954)
		(layer "F.Cu")
		(net "XTAL_PCH_RTC2")
	)
	(segment
		(start 328.035412 -34.98723)
		(end 328.035412 -35.530536)
		(width 0.12954)
		(layer "F.Cu")
		(net "XTAL_PCH_RTC2")
	)
	(segment
		(start 327.579736 -34.484564)
		(end 328.035412 -34.94024)
		(width 0.12954)
		(layer "F.Cu")
		(net "XTAL_PCH_RTC2")
	)
	(segment
		(start 329.276456 -37.495226)
		(end 329.276456 -37.930582)
		(width 0.12954)
		(layer "F.Cu")
		(net "XTAL_PCH_RTC2")
	)
	(segment
		(start 328.035412 -35.530536)
		(end 328.763884 -36.259008)
		(width 0.12954)
		(layer "F.Cu")
		(net "XTAL_PCH_RTC2")
	)
	(segment
		(start 328.035412 -34.94024)
		(end 328.035412 -34.98723)
		(width 0.12954)
		(layer "F.Cu")
		(net "XTAL_PCH_RTC2")
	)
	(via
		(at 328.035412 -34.98723)
		(size 0.508)
		(drill 0.254)
		(layers "F.Cu" "B.Cu")
		(net "XTAL_PCH_RTC2")
	)
	(segment
		(start 328.586338 -37.443664)
		(end 328.586338 -37.759386)
		(width 0.0889)
		(layer "F.Cu")
		(net "XTAL_PCH_RTC1")
	)
	(segment
		(start 322.48348 -31.97352)
		(end 322.48348 -31.99892)
		(width 0.12954)
		(layer "F.Cu")
		(net "XTAL_PCH_RTC1")
	)
	(segment
		(start 327.803764 -36.28009)
		(end 327.803764 -36.66109)
		(width 0.0889)
		(layer "F.Cu")
		(net "XTAL_PCH_RTC1")
	)
	(segment
		(start 324.39864 -33.094676)
		(end 324.39864 -32.892492)
		(width 0.12954)
		(layer "F.Cu")
		(net "XTAL_PCH_RTC1")
	)
	(segment
		(start 323.783452 -32.3596)
		(end 324.316344 -32.892492)
		(width 0.12954)
		(layer "F.Cu")
		(net "XTAL_PCH_RTC1")
	)
	(segment
		(start 325.199756 -33.895792)
		(end 325.326756 -33.895792)
		(width 0.12954)
		(layer "F.Cu")
		(net "XTAL_PCH_RTC1")
	)
	(segment
		(start 327.803764 -36.66109)
		(end 328.586338 -37.443664)
		(width 0.0889)
		(layer "F.Cu")
		(net "XTAL_PCH_RTC1")
	)
	(segment
		(start 325.822056 -34.391092)
		(end 326.893936 -35.462972)
		(width 0.12954)
		(layer "F.Cu")
		(net "XTAL_PCH_RTC1")
	)
	(segment
		(start 326.986646 -35.462972)
		(end 327.803764 -36.28009)
		(width 0.12954)
		(layer "F.Cu")
		(net "XTAL_PCH_RTC1")
	)
	(segment
		(start 325.199756 -33.895792)
		(end 324.39864 -33.094676)
		(width 0.12954)
		(layer "F.Cu")
		(net "XTAL_PCH_RTC1")
	)
	(segment
		(start 328.586338 -37.759386)
		(end 328.895964 -38.069012)
		(width 0.0889)
		(layer "F.Cu")
		(net "XTAL_PCH_RTC1")
	)
	(segment
		(start 324.316344 -32.892492)
		(end 324.39864 -32.892492)
		(width 0.12954)
		(layer "F.Cu")
		(net "XTAL_PCH_RTC1")
	)
	(segment
		(start 322.45808 -31.94812)
		(end 322.48348 -31.97352)
		(width 0.12954)
		(layer "F.Cu")
		(net "XTAL_PCH_RTC1")
	)
	(segment
		(start 325.326756 -33.895792)
		(end 325.822056 -34.391092)
		(width 0.12954)
		(layer "F.Cu")
		(net "XTAL_PCH_RTC1")
	)
	(segment
		(start 322.84416 -32.3596)
		(end 323.783452 -32.3596)
		(width 0.12954)
		(layer "F.Cu")
		(net "XTAL_PCH_RTC1")
	)
	(segment
		(start 326.893936 -35.462972)
		(end 326.986646 -35.462972)
		(width 0.12954)
		(layer "F.Cu")
		(net "XTAL_PCH_RTC1")
	)
	(segment
		(start 328.895964 -38.069012)
		(end 328.895964 -38.465252)
		(width 0.0889)
		(layer "F.Cu")
		(net "XTAL_PCH_RTC1")
	)
	(segment
		(start 322.48348 -31.99892)
		(end 322.84416 -32.3596)
		(width 0.12954)
		(layer "F.Cu")
		(net "XTAL_PCH_RTC1")
	)
	(via
		(at 325.822056 -34.391092)
		(size 0.508)
		(drill 0.254)
		(layers "F.Cu" "B.Cu")
		(net "XTAL_PCH_RTC1")
	)
	(segment
		(start 337.394296 -62.997588)
		(end 337.613244 -62.77864)
		(width 0.12954)
		(layer "F.Cu")
		(net "XTAL_PCH_25M_OUT")
	)
	(segment
		(start 337.700874 -58.696606)
		(end 337.399884 -58.395616)
		(width 0.0889)
		(layer "F.Cu")
		(net "XTAL_PCH_25M_OUT")
	)
	(segment
		(start 336.745326 -66.226436)
		(end 336.547206 -66.424556)
		(width 0.12954)
		(layer "F.Cu")
		(net "XTAL_PCH_25M_OUT")
	)
	(segment
		(start 337.613244 -59.088782)
		(end 337.700874 -59.001152)
		(width 0.0889)
		(layer "F.Cu")
		(net "XTAL_PCH_25M_OUT")
	)
	(segment
		(start 335.65592 -67.512946)
		(end 335.65592 -69.039486)
		(width 0.12954)
		(layer "F.Cu")
		(net "XTAL_PCH_25M_OUT")
	)
	(segment
		(start 336.745326 -65.786254)
		(end 336.745326 -66.226436)
		(width 0.12954)
		(layer "F.Cu")
		(net "XTAL_PCH_25M_OUT")
	)
	(segment
		(start 337.143598 -65.015364)
		(end 337.143598 -64.266572)
		(width 0.12954)
		(layer "F.Cu")
		(net "XTAL_PCH_25M_OUT")
	)
	(segment
		(start 337.394296 -64.015874)
		(end 337.394296 -62.997588)
		(width 0.12954)
		(layer "F.Cu")
		(net "XTAL_PCH_25M_OUT")
	)
	(segment
		(start 337.613244 -62.77864)
		(end 337.613244 -61.011308)
		(width 0.12954)
		(layer "F.Cu")
		(net "XTAL_PCH_25M_OUT")
	)
	(segment
		(start 337.700874 -59.001152)
		(end 337.700874 -58.696606)
		(width 0.0889)
		(layer "F.Cu")
		(net "XTAL_PCH_25M_OUT")
	)
	(segment
		(start 336.547206 -66.424556)
		(end 336.547206 -66.62166)
		(width 0.12954)
		(layer "F.Cu")
		(net "XTAL_PCH_25M_OUT")
	)
	(segment
		(start 337.143598 -65.015364)
		(end 337.008216 -65.150746)
		(width 0.12954)
		(layer "F.Cu")
		(net "XTAL_PCH_25M_OUT")
	)
	(segment
		(start 337.143598 -64.266572)
		(end 337.394296 -64.015874)
		(width 0.12954)
		(layer "F.Cu")
		(net "XTAL_PCH_25M_OUT")
	)
	(segment
		(start 337.399884 -58.395616)
		(end 337.399884 -58.020204)
		(width 0.0889)
		(layer "F.Cu")
		(net "XTAL_PCH_25M_OUT")
	)
	(segment
		(start 337.613244 -61.011308)
		(end 337.613244 -59.088782)
		(width 0.0889)
		(layer "F.Cu")
		(net "XTAL_PCH_25M_OUT")
	)
	(segment
		(start 336.468466 -69.852032)
		(end 336.608674 -69.852032)
		(width 0.12954)
		(layer "F.Cu")
		(net "XTAL_PCH_25M_OUT")
	)
	(segment
		(start 337.008216 -65.523364)
		(end 336.745326 -65.786254)
		(width 0.12954)
		(layer "F.Cu")
		(net "XTAL_PCH_25M_OUT")
	)
	(segment
		(start 335.65592 -69.039486)
		(end 336.468466 -69.852032)
		(width 0.12954)
		(layer "F.Cu")
		(net "XTAL_PCH_25M_OUT")
	)
	(segment
		(start 337.008216 -65.150746)
		(end 337.008216 -65.523364)
		(width 0.12954)
		(layer "F.Cu")
		(net "XTAL_PCH_25M_OUT")
	)
	(segment
		(start 336.547206 -66.62166)
		(end 335.65592 -67.512946)
		(width 0.12954)
		(layer "F.Cu")
		(net "XTAL_PCH_25M_OUT")
	)
	(via
		(at 336.745326 -65.786254)
		(size 0.508)
		(drill 0.254)
		(layers "F.Cu" "B.Cu")
		(net "XTAL_PCH_25M_OUT")
	)
	(segment
		(start 333.82712 -66.99758)
		(end 333.94396 -66.88074)
		(width 0.12954)
		(layer "F.Cu")
		(net "XTAL_PCH_25M_IN_R")
	)
	(segment
		(start 335.936336 -64.749426)
		(end 335.670398 -65.015364)
		(width 0.12954)
		(layer "F.Cu")
		(net "XTAL_PCH_25M_IN_R")
	)
	(segment
		(start 336.319622 -63.763398)
		(end 335.936336 -64.146684)
		(width 0.12954)
		(layer "F.Cu")
		(net "XTAL_PCH_25M_IN_R")
	)
	(segment
		(start 335.378298 -65.760854)
		(end 335.24825 -65.890902)
		(width 0.12954)
		(layer "F.Cu")
		(net "XTAL_PCH_25M_IN_R")
	)
	(segment
		(start 335.936336 -64.146684)
		(end 335.936336 -64.749426)
		(width 0.12954)
		(layer "F.Cu")
		(net "XTAL_PCH_25M_IN_R")
	)
	(segment
		(start 334.702658 -66.88074)
		(end 335.12125 -66.462148)
		(width 0.12954)
		(layer "F.Cu")
		(net "XTAL_PCH_25M_IN_R")
	)
	(segment
		(start 333.94396 -66.88074)
		(end 334.702658 -66.88074)
		(width 0.12954)
		(layer "F.Cu")
		(net "XTAL_PCH_25M_IN_R")
	)
	(segment
		(start 335.24825 -65.890902)
		(end 335.24825 -66.335148)
		(width 0.12954)
		(layer "F.Cu")
		(net "XTAL_PCH_25M_IN_R")
	)
	(segment
		(start 335.378298 -65.760854)
		(end 335.670398 -65.468754)
		(width 0.12954)
		(layer "F.Cu")
		(net "XTAL_PCH_25M_IN_R")
	)
	(segment
		(start 333.82712 -67.570858)
		(end 333.82712 -66.99758)
		(width 0.12954)
		(layer "F.Cu")
		(net "XTAL_PCH_25M_IN_R")
	)
	(segment
		(start 335.24825 -66.335148)
		(end 335.12125 -66.462148)
		(width 0.12954)
		(layer "F.Cu")
		(net "XTAL_PCH_25M_IN_R")
	)
	(segment
		(start 334.408526 -68.152264)
		(end 333.82712 -67.570858)
		(width 0.12954)
		(layer "F.Cu")
		(net "XTAL_PCH_25M_IN_R")
	)
	(segment
		(start 335.670398 -65.468754)
		(end 335.670398 -65.015364)
		(width 0.12954)
		(layer "F.Cu")
		(net "XTAL_PCH_25M_IN_R")
	)
	(via
		(at 335.378298 -65.760854)
		(size 0.508)
		(drill 0.254)
		(layers "F.Cu" "B.Cu")
		(net "XTAL_PCH_25M_IN_R")
	)
	(segment
		(start 337.302602 -59.27471)
		(end 337.399884 -59.177428)
		(width 0.0889)
		(layer "F.Cu")
		(net "XTAL_PCH_25M_IN")
	)
	(segment
		(start 336.459322 -61.03874)
		(end 336.91703 -61.03874)
		(width 0.12954)
		(layer "F.Cu")
		(net "XTAL_PCH_25M_IN")
	)
	(segment
		(start 336.840322 -61.64834)
		(end 336.459322 -61.64834)
		(width 0.12954)
		(layer "F.Cu")
		(net "XTAL_PCH_25M_IN")
	)
	(segment
		(start 337.190842 -60.764928)
		(end 337.302602 -60.653168)
		(width 0.0889)
		(layer "F.Cu")
		(net "XTAL_PCH_25M_IN")
	)
	(segment
		(start 337.399884 -59.177428)
		(end 337.399884 -58.850276)
		(width 0.0889)
		(layer "F.Cu")
		(net "XTAL_PCH_25M_IN")
	)
	(segment
		(start 336.954622 -61.76264)
		(end 336.840322 -61.64834)
		(width 0.12954)
		(layer "F.Cu")
		(net "XTAL_PCH_25M_IN")
	)
	(segment
		(start 336.459322 -61.64834)
		(end 336.345022 -61.53404)
		(width 0.12954)
		(layer "F.Cu")
		(net "XTAL_PCH_25M_IN")
	)
	(segment
		(start 336.273648 -62.917324)
		(end 336.273648 -62.258194)
		(width 0.12954)
		(layer "F.Cu")
		(net "XTAL_PCH_25M_IN")
	)
	(segment
		(start 336.805016 -62.258194)
		(end 336.954622 -62.108588)
		(width 0.12954)
		(layer "F.Cu")
		(net "XTAL_PCH_25M_IN")
	)
	(segment
		(start 337.302602 -60.653168)
		(end 337.302602 -59.27471)
		(width 0.0889)
		(layer "F.Cu")
		(net "XTAL_PCH_25M_IN")
	)
	(segment
		(start 336.345022 -61.15304)
		(end 336.459322 -61.03874)
		(width 0.12954)
		(layer "F.Cu")
		(net "XTAL_PCH_25M_IN")
	)
	(segment
		(start 336.91703 -61.03874)
		(end 337.190842 -60.764928)
		(width 0.12954)
		(layer "F.Cu")
		(net "XTAL_PCH_25M_IN")
	)
	(segment
		(start 336.345022 -61.53404)
		(end 336.345022 -61.15304)
		(width 0.12954)
		(layer "F.Cu")
		(net "XTAL_PCH_25M_IN")
	)
	(segment
		(start 336.273648 -62.258194)
		(end 336.805016 -62.258194)
		(width 0.12954)
		(layer "F.Cu")
		(net "XTAL_PCH_25M_IN")
	)
	(segment
		(start 336.319622 -62.963298)
		(end 336.273648 -62.917324)
		(width 0.12954)
		(layer "F.Cu")
		(net "XTAL_PCH_25M_IN")
	)
	(segment
		(start 336.954622 -62.108588)
		(end 336.954622 -61.76264)
		(width 0.12954)
		(layer "F.Cu")
		(net "XTAL_PCH_25M_IN")
	)
	(via
		(at 336.273648 -62.258194)
		(size 0.508)
		(drill 0.254)
		(layers "F.Cu" "B.Cu")
		(net "XTAL_PCH_25M_IN")
	)
	(segment
		(start 247.621552 -94.647766)
		(end 247.184672 -93.593158)
		(width 0.12954)
		(layer "F.Cu")
		(net "XTAL_CLK_GEN1_25M_X2")
	)
	(segment
		(start 249.801126 -95.886778)
		(end 248.860564 -95.886778)
		(width 0.12954)
		(layer "F.Cu")
		(net "XTAL_CLK_GEN1_25M_X2")
	)
	(segment
		(start 247.184672 -90.397076)
		(end 247.184672 -90.651584)
		(width 0.12954)
		(layer "F.Cu")
		(net "XTAL_CLK_GEN1_25M_X2")
	)
	(segment
		(start 246.567452 -87.543386)
		(end 246.759984 -87.543386)
		(width 0.12954)
		(layer "F.Cu")
		(net "XTAL_CLK_GEN1_25M_X2")
	)
	(segment
		(start 247.184672 -93.593158)
		(end 247.184672 -90.651584)
		(width 0.12954)
		(layer "F.Cu")
		(net "XTAL_CLK_GEN1_25M_X2")
	)
	(segment
		(start 247.6246 -89.957148)
		(end 247.184672 -90.397076)
		(width 0.12954)
		(layer "F.Cu")
		(net "XTAL_CLK_GEN1_25M_X2")
	)
	(segment
		(start 250.9774 -97.063052)
		(end 250.697746 -96.783398)
		(width 0.0889)
		(layer "F.Cu")
		(net "XTAL_CLK_GEN1_25M_X2")
	)
	(segment
		(start 246.759984 -87.543386)
		(end 247.6246 -88.408002)
		(width 0.12954)
		(layer "F.Cu")
		(net "XTAL_CLK_GEN1_25M_X2")
	)
	(segment
		(start 248.860564 -95.886778)
		(end 247.621552 -94.647766)
		(width 0.12954)
		(layer "F.Cu")
		(net "XTAL_CLK_GEN1_25M_X2")
	)
	(segment
		(start 252.557788 -97.063052)
		(end 250.9774 -97.063052)
		(width 0.0889)
		(layer "F.Cu")
		(net "XTAL_CLK_GEN1_25M_X2")
	)
	(segment
		(start 247.6246 -88.408002)
		(end 247.6246 -89.957148)
		(width 0.12954)
		(layer "F.Cu")
		(net "XTAL_CLK_GEN1_25M_X2")
	)
	(segment
		(start 250.697746 -96.783398)
		(end 249.801126 -95.886778)
		(width 0.12954)
		(layer "F.Cu")
		(net "XTAL_CLK_GEN1_25M_X2")
	)
	(via
		(at 248.860564 -95.886778)
		(size 0.508)
		(drill 0.254)
		(layers "F.Cu" "B.Cu")
		(net "XTAL_CLK_GEN1_25M_X2")
	)
	(segment
		(start 249.74804 -94.051882)
		(end 248.66854 -94.051882)
		(width 0.12954)
		(layer "F.Cu")
		(net "XTAL_CLK_GEN1_25M_X1")
	)
	(segment
		(start 249.87758 -94.181422)
		(end 249.74804 -94.051882)
		(width 0.12954)
		(layer "F.Cu")
		(net "XTAL_CLK_GEN1_25M_X1")
	)
	(segment
		(start 248.66854 -94.051882)
		(end 248.539 -93.922342)
		(width 0.12954)
		(layer "F.Cu")
		(net "XTAL_CLK_GEN1_25M_X1")
	)
	(segment
		(start 249.87758 -94.986348)
		(end 249.87758 -94.181422)
		(width 0.12954)
		(layer "F.Cu")
		(net "XTAL_CLK_GEN1_25M_X1")
	)
	(segment
		(start 249.700542 -92.46489)
		(end 249.374406 -92.46489)
		(width 0.12954)
		(layer "F.Cu")
		(net "XTAL_CLK_GEN1_25M_X1")
	)
	(segment
		(start 248.66854 -93.185742)
		(end 249.74804 -93.185742)
		(width 0.12954)
		(layer "F.Cu")
		(net "XTAL_CLK_GEN1_25M_X1")
	)
	(segment
		(start 249.87758 -93.056202)
		(end 249.87758 -92.641928)
		(width 0.12954)
		(layer "F.Cu")
		(net "XTAL_CLK_GEN1_25M_X1")
	)
	(segment
		(start 251.598176 -96.813116)
		(end 249.87758 -95.09252)
		(width 0.12954)
		(layer "F.Cu")
		(net "XTAL_CLK_GEN1_25M_X1")
	)
	(segment
		(start 249.87758 -92.641928)
		(end 249.700542 -92.46489)
		(width 0.12954)
		(layer "F.Cu")
		(net "XTAL_CLK_GEN1_25M_X1")
	)
	(segment
		(start 248.539 -93.922342)
		(end 248.539 -93.315282)
		(width 0.12954)
		(layer "F.Cu")
		(net "XTAL_CLK_GEN1_25M_X1")
	)
	(segment
		(start 249.74804 -93.185742)
		(end 249.87758 -93.056202)
		(width 0.12954)
		(layer "F.Cu")
		(net "XTAL_CLK_GEN1_25M_X1")
	)
	(segment
		(start 249.87758 -95.09252)
		(end 249.87758 -94.986348)
		(width 0.12954)
		(layer "F.Cu")
		(net "XTAL_CLK_GEN1_25M_X1")
	)
	(segment
		(start 248.539 -93.315282)
		(end 248.66854 -93.185742)
		(width 0.12954)
		(layer "F.Cu")
		(net "XTAL_CLK_GEN1_25M_X1")
	)
	(segment
		(start 251.807726 -96.813116)
		(end 251.598176 -96.813116)
		(width 0.12954)
		(layer "F.Cu")
		(net "XTAL_CLK_GEN1_25M_X1")
	)
	(via
		(at 249.87758 -94.986348)
		(size 0.508)
		(drill 0.254)
		(layers "F.Cu" "B.Cu")
		(net "XTAL_CLK_GEN1_25M_X1")
	)
	(segment
		(start 104.056434 -352.02114)
		(end 103.568246 -352.02114)
		(width 0.254)
		(layer "F.Cu")
		(net "VSENSE_PVCCIN_CPU1_DP")
	)
	(segment
		(start 105.171494 -285.939484)
		(end 105.171494 -286.17545)
		(width 0.2032)
		(layer "F.Cu")
		(net "VSENSE_PVCCIN_CPU1_DP")
	)
	(segment
		(start 105.171494 -286.17545)
		(end 105.171748 -286.475424)
		(width 0.2032)
		(layer "F.Cu")
		(net "VSENSE_PVCCIN_CPU1_DP")
	)
	(segment
		(start 104.376982 -351.700592)
		(end 104.056434 -352.02114)
		(width 0.254)
		(layer "F.Cu")
		(net "VSENSE_PVCCIN_CPU1_DP")
	)
	(via
		(at 104.376982 -351.700592)
		(size 0.508)
		(drill 0.254)
		(layers "F.Cu" "B.Cu")
		(net "VSENSE_PVCCIN_CPU1_DP")
	)
	(via
		(at 105.171748 -286.475424)
		(size 0.4572)
		(drill 0.2032)
		(layers "F.Cu" "B.Cu")
		(net "VSENSE_PVCCIN_CPU1_DP")
	)
	(segment
		(start 104.376982 -351.41662)
		(end 104.61752 -351.176082)
		(width 0.254)
		(layer "B.Cu")
		(net "VSENSE_PVCCIN_CPU1_DP")
	)
	(segment
		(start 101.032818 -291.188394)
		(end 100.508562 -291.71265)
		(width 0.254)
		(layer "B.Cu")
		(net "VSENSE_PVCCIN_CPU1_DP")
	)
	(segment
		(start 76.034138 -333.406242)
		(end 76.413106 -333.027274)
		(width 0.254)
		(layer "B.Cu")
		(net "VSENSE_PVCCIN_CPU1_DP")
	)
	(segment
		(start 76.817474 -333.431642)
		(end 76.413106 -333.027274)
		(width 0.254)
		(layer "B.Cu")
		(net "VSENSE_PVCCIN_CPU1_DP")
	)
	(segment
		(start 77.551534 -333.431642)
		(end 76.817474 -333.431642)
		(width 0.254)
		(layer "B.Cu")
		(net "VSENSE_PVCCIN_CPU1_DP")
	)
	(segment
		(start 103.76281 -290.618418)
		(end 103.192834 -291.188394)
		(width 0.254)
		(layer "B.Cu")
		(net "VSENSE_PVCCIN_CPU1_DP")
	)
	(segment
		(start 105.171748 -286.475424)
		(end 105.171748 -287.28924)
		(width 0.254)
		(layer "B.Cu")
		(net "VSENSE_PVCCIN_CPU1_DP")
	)
	(segment
		(start 103.192834 -291.188394)
		(end 101.032818 -291.188394)
		(width 0.254)
		(layer "B.Cu")
		(net "VSENSE_PVCCIN_CPU1_DP")
	)
	(segment
		(start 76.491084 -352.331528)
		(end 78.523338 -350.299274)
		(width 0.254)
		(layer "B.Cu")
		(net "VSENSE_PVCCIN_CPU1_DP")
	)
	(segment
		(start 104.61752 -351.176082)
		(end 104.61752 -350.744536)
		(width 0.254)
		(layer "B.Cu")
		(net "VSENSE_PVCCIN_CPU1_DP")
	)
	(segment
		(start 78.055978 -332.927198)
		(end 77.551534 -333.431642)
		(width 0.254)
		(layer "B.Cu")
		(net "VSENSE_PVCCIN_CPU1_DP")
	)
	(segment
		(start 80.06969 -291.71265)
		(end 78.055978 -293.726362)
		(width 0.254)
		(layer "B.Cu")
		(net "VSENSE_PVCCIN_CPU1_DP")
	)
	(segment
		(start 81.601818 -362.142532)
		(end 76.491084 -357.031798)
		(width 0.254)
		(layer "B.Cu")
		(net "VSENSE_PVCCIN_CPU1_DP")
	)
	(segment
		(start 104.231948 -288.903664)
		(end 104.231948 -289.096958)
		(width 0.254)
		(layer "B.Cu")
		(net "VSENSE_PVCCIN_CPU1_DP")
	)
	(segment
		(start 77.57541 -348.71533)
		(end 75.75423 -348.71533)
		(width 0.254)
		(layer "B.Cu")
		(net "VSENSE_PVCCIN_CPU1_DP")
	)
	(segment
		(start 103.76281 -289.607752)
		(end 103.76281 -290.618418)
		(width 0.254)
		(layer "B.Cu")
		(net "VSENSE_PVCCIN_CPU1_DP")
	)
	(segment
		(start 97.807526 -360.242612)
		(end 95.907606 -362.142532)
		(width 0.254)
		(layer "B.Cu")
		(net "VSENSE_PVCCIN_CPU1_DP")
	)
	(segment
		(start 102.663752 -350.512888)
		(end 97.807526 -355.369114)
		(width 0.254)
		(layer "B.Cu")
		(net "VSENSE_PVCCIN_CPU1_DP")
	)
	(segment
		(start 103.996744 -289.362134)
		(end 103.996744 -289.373818)
		(width 0.254)
		(layer "B.Cu")
		(net "VSENSE_PVCCIN_CPU1_DP")
	)
	(segment
		(start 103.996744 -289.373818)
		(end 103.76281 -289.607752)
		(width 0.254)
		(layer "B.Cu")
		(net "VSENSE_PVCCIN_CPU1_DP")
	)
	(segment
		(start 75.75423 -348.71533)
		(end 73.970896 -346.931996)
		(width 0.254)
		(layer "B.Cu")
		(net "VSENSE_PVCCIN_CPU1_DP")
	)
	(segment
		(start 75.01255 -333.406242)
		(end 76.034138 -333.406242)
		(width 0.254)
		(layer "B.Cu")
		(net "VSENSE_PVCCIN_CPU1_DP")
	)
	(segment
		(start 104.471724 -288.50717)
		(end 104.466898 -288.509964)
		(width 0.254)
		(layer "B.Cu")
		(net "VSENSE_PVCCIN_CPU1_DP")
	)
	(segment
		(start 104.385872 -350.512888)
		(end 102.663752 -350.512888)
		(width 0.254)
		(layer "B.Cu")
		(net "VSENSE_PVCCIN_CPU1_DP")
	)
	(segment
		(start 78.523338 -350.299274)
		(end 78.523338 -349.663258)
		(width 0.254)
		(layer "B.Cu")
		(net "VSENSE_PVCCIN_CPU1_DP")
	)
	(segment
		(start 97.807526 -355.369114)
		(end 97.807526 -360.242612)
		(width 0.254)
		(layer "B.Cu")
		(net "VSENSE_PVCCIN_CPU1_DP")
	)
	(segment
		(start 73.970896 -334.447896)
		(end 75.01255 -333.406242)
		(width 0.254)
		(layer "B.Cu")
		(net "VSENSE_PVCCIN_CPU1_DP")
	)
	(segment
		(start 104.61752 -350.744536)
		(end 104.385872 -350.512888)
		(width 0.254)
		(layer "B.Cu")
		(net "VSENSE_PVCCIN_CPU1_DP")
	)
	(segment
		(start 76.491084 -357.031798)
		(end 76.491084 -352.331528)
		(width 0.254)
		(layer "B.Cu")
		(net "VSENSE_PVCCIN_CPU1_DP")
	)
	(segment
		(start 95.907606 -362.142532)
		(end 81.601818 -362.142532)
		(width 0.254)
		(layer "B.Cu")
		(net "VSENSE_PVCCIN_CPU1_DP")
	)
	(segment
		(start 78.523338 -349.663258)
		(end 77.57541 -348.71533)
		(width 0.254)
		(layer "B.Cu")
		(net "VSENSE_PVCCIN_CPU1_DP")
	)
	(segment
		(start 104.376982 -351.700592)
		(end 104.376982 -351.41662)
		(width 0.254)
		(layer "B.Cu")
		(net "VSENSE_PVCCIN_CPU1_DP")
	)
	(segment
		(start 78.055978 -293.726362)
		(end 78.055978 -332.927198)
		(width 0.254)
		(layer "B.Cu")
		(net "VSENSE_PVCCIN_CPU1_DP")
	)
	(segment
		(start 73.970896 -346.931996)
		(end 73.970896 -334.447896)
		(width 0.254)
		(layer "B.Cu")
		(net "VSENSE_PVCCIN_CPU1_DP")
	)
	(segment
		(start 104.941624 -287.693354)
		(end 104.931972 -287.698942)
		(width 0.254)
		(layer "B.Cu")
		(net "VSENSE_PVCCIN_CPU1_DP")
	)
	(segment
		(start 100.508562 -291.71265)
		(end 80.06969 -291.71265)
		(width 0.254)
		(layer "B.Cu")
		(net "VSENSE_PVCCIN_CPU1_DP")
	)
	(arc
		(start 104.701848 -288.103056)
		(mid 104.640285 -288.335579)
		(end 104.471724 -288.50717)
		(width 0.254)
		(layer "B.Cu")
		(net "VSENSE_PVCCIN_CPU1_DP")
	)
	(arc
		(start 104.231948 -289.096958)
		(mid 104.138482 -289.250957)
		(end 103.996744 -289.362134)
		(width 0.254)
		(layer "B.Cu")
		(net "VSENSE_PVCCIN_CPU1_DP")
	)
	(arc
		(start 104.931972 -287.698942)
		(mid 104.763416 -287.870536)
		(end 104.701848 -288.103056)
		(width 0.254)
		(layer "B.Cu")
		(net "VSENSE_PVCCIN_CPU1_DP")
	)
	(arc
		(start 105.171748 -287.28924)
		(mid 105.110185 -287.521763)
		(end 104.941624 -287.693354)
		(width 0.254)
		(layer "B.Cu")
		(net "VSENSE_PVCCIN_CPU1_DP")
	)
	(arc
		(start 104.466898 -288.509964)
		(mid 104.298175 -288.67623)
		(end 104.231948 -288.903664)
		(width 0.254)
		(layer "B.Cu")
		(net "VSENSE_PVCCIN_CPU1_DP")
	)
	(segment
		(start 106.778298 -355.97338)
		(end 106.778298 -353.603814)
		(width 0.1778)
		(layer "F.Cu")
		(net "VSENSE_PVCCIN_CPU1_DN")
	)
	(segment
		(start 105.911904 -352.42119)
		(end 106.312208 -352.821494)
		(width 0.254)
		(layer "F.Cu")
		(net "VSENSE_PVCCIN_CPU1_DN")
	)
	(segment
		(start 105.240582 -351.864168)
		(end 105.240582 -352.066098)
		(width 0.254)
		(layer "F.Cu")
		(net "VSENSE_PVCCIN_CPU1_DN")
	)
	(segment
		(start 104.701848 -288.381186)
		(end 104.701848 -288.917126)
		(width 0.2032)
		(layer "F.Cu")
		(net "VSENSE_PVCCIN_CPU1_DN")
	)
	(segment
		(start 106.778298 -353.603814)
		(end 106.312208 -353.137724)
		(width 0.1778)
		(layer "F.Cu")
		(net "VSENSE_PVCCIN_CPU1_DN")
	)
	(segment
		(start 105.240582 -352.066098)
		(end 105.595674 -352.42119)
		(width 0.254)
		(layer "F.Cu")
		(net "VSENSE_PVCCIN_CPU1_DN")
	)
	(segment
		(start 106.312208 -352.821494)
		(end 106.312208 -353.137724)
		(width 0.254)
		(layer "F.Cu")
		(net "VSENSE_PVCCIN_CPU1_DN")
	)
	(segment
		(start 105.595674 -352.42119)
		(end 105.911904 -352.42119)
		(width 0.254)
		(layer "F.Cu")
		(net "VSENSE_PVCCIN_CPU1_DN")
	)
	(via
		(at 105.240582 -351.864168)
		(size 0.762)
		(drill 0.254)
		(layers "F.Cu" "B.Cu")
		(net "VSENSE_PVCCIN_CPU1_DN")
	)
	(via
		(at 104.701848 -288.917126)
		(size 0.4572)
		(drill 0.2032)
		(layers "F.Cu" "B.Cu")
		(net "VSENSE_PVCCIN_CPU1_DN")
	)
	(segment
		(start 80.227678 -292.09365)
		(end 78.436978 -293.88435)
		(width 0.254)
		(layer "B.Cu")
		(net "VSENSE_PVCCIN_CPU1_DN")
	)
	(segment
		(start 76.033884 -333.787242)
		(end 76.413106 -334.166464)
		(width 0.254)
		(layer "B.Cu")
		(net "VSENSE_PVCCIN_CPU1_DN")
	)
	(segment
		(start 74.351896 -346.774008)
		(end 74.351896 -334.605884)
		(width 0.254)
		(layer "B.Cu")
		(net "VSENSE_PVCCIN_CPU1_DN")
	)
	(segment
		(start 81.759806 -361.761532)
		(end 76.872084 -356.87381)
		(width 0.254)
		(layer "B.Cu")
		(net "VSENSE_PVCCIN_CPU1_DN")
	)
	(segment
		(start 76.766928 -333.812642)
		(end 76.413106 -334.166464)
		(width 0.254)
		(layer "B.Cu")
		(net "VSENSE_PVCCIN_CPU1_DN")
	)
	(segment
		(start 76.872084 -352.489516)
		(end 78.904338 -350.457262)
		(width 0.254)
		(layer "B.Cu")
		(net "VSENSE_PVCCIN_CPU1_DN")
	)
	(segment
		(start 97.426526 -360.084624)
		(end 95.749618 -361.761532)
		(width 0.254)
		(layer "B.Cu")
		(net "VSENSE_PVCCIN_CPU1_DN")
	)
	(segment
		(start 78.436978 -333.161386)
		(end 77.785722 -333.812642)
		(width 0.254)
		(layer "B.Cu")
		(net "VSENSE_PVCCIN_CPU1_DN")
	)
	(segment
		(start 104.701848 -288.917126)
		(end 104.701848 -290.218368)
		(width 0.254)
		(layer "B.Cu")
		(net "VSENSE_PVCCIN_CPU1_DN")
	)
	(segment
		(start 77.785722 -333.812642)
		(end 76.766928 -333.812642)
		(width 0.254)
		(layer "B.Cu")
		(net "VSENSE_PVCCIN_CPU1_DN")
	)
	(segment
		(start 105.240582 -351.41662)
		(end 104.99852 -351.174558)
		(width 0.254)
		(layer "B.Cu")
		(net "VSENSE_PVCCIN_CPU1_DN")
	)
	(segment
		(start 104.99852 -351.174558)
		(end 104.99852 -350.586548)
		(width 0.254)
		(layer "B.Cu")
		(net "VSENSE_PVCCIN_CPU1_DN")
	)
	(segment
		(start 75.912218 -348.33433)
		(end 74.351896 -346.774008)
		(width 0.254)
		(layer "B.Cu")
		(net "VSENSE_PVCCIN_CPU1_DN")
	)
	(segment
		(start 103.350822 -291.569394)
		(end 101.159818 -291.569394)
		(width 0.254)
		(layer "B.Cu")
		(net "VSENSE_PVCCIN_CPU1_DN")
	)
	(segment
		(start 76.872084 -356.87381)
		(end 76.872084 -352.489516)
		(width 0.254)
		(layer "B.Cu")
		(net "VSENSE_PVCCIN_CPU1_DN")
	)
	(segment
		(start 78.904338 -350.457262)
		(end 78.904338 -349.50527)
		(width 0.254)
		(layer "B.Cu")
		(net "VSENSE_PVCCIN_CPU1_DN")
	)
	(segment
		(start 77.733398 -348.33433)
		(end 75.912218 -348.33433)
		(width 0.254)
		(layer "B.Cu")
		(net "VSENSE_PVCCIN_CPU1_DN")
	)
	(segment
		(start 104.701848 -290.218368)
		(end 103.350822 -291.569394)
		(width 0.254)
		(layer "B.Cu")
		(net "VSENSE_PVCCIN_CPU1_DN")
	)
	(segment
		(start 78.436978 -293.88435)
		(end 78.436978 -333.161386)
		(width 0.254)
		(layer "B.Cu")
		(net "VSENSE_PVCCIN_CPU1_DN")
	)
	(segment
		(start 74.351896 -334.605884)
		(end 75.170538 -333.787242)
		(width 0.254)
		(layer "B.Cu")
		(net "VSENSE_PVCCIN_CPU1_DN")
	)
	(segment
		(start 102.505764 -350.131888)
		(end 97.426526 -355.211126)
		(width 0.254)
		(layer "B.Cu")
		(net "VSENSE_PVCCIN_CPU1_DN")
	)
	(segment
		(start 101.159818 -291.569394)
		(end 100.635562 -292.09365)
		(width 0.254)
		(layer "B.Cu")
		(net "VSENSE_PVCCIN_CPU1_DN")
	)
	(segment
		(start 75.170538 -333.787242)
		(end 76.033884 -333.787242)
		(width 0.254)
		(layer "B.Cu")
		(net "VSENSE_PVCCIN_CPU1_DN")
	)
	(segment
		(start 105.240582 -351.864168)
		(end 105.240582 -351.41662)
		(width 0.254)
		(layer "B.Cu")
		(net "VSENSE_PVCCIN_CPU1_DN")
	)
	(segment
		(start 95.749618 -361.761532)
		(end 81.759806 -361.761532)
		(width 0.254)
		(layer "B.Cu")
		(net "VSENSE_PVCCIN_CPU1_DN")
	)
	(segment
		(start 104.99852 -350.586548)
		(end 104.54386 -350.131888)
		(width 0.254)
		(layer "B.Cu")
		(net "VSENSE_PVCCIN_CPU1_DN")
	)
	(segment
		(start 100.635562 -292.09365)
		(end 80.227678 -292.09365)
		(width 0.254)
		(layer "B.Cu")
		(net "VSENSE_PVCCIN_CPU1_DN")
	)
	(segment
		(start 78.904338 -349.50527)
		(end 77.733398 -348.33433)
		(width 0.254)
		(layer "B.Cu")
		(net "VSENSE_PVCCIN_CPU1_DN")
	)
	(segment
		(start 104.54386 -350.131888)
		(end 102.505764 -350.131888)
		(width 0.254)
		(layer "B.Cu")
		(net "VSENSE_PVCCIN_CPU1_DN")
	)
	(segment
		(start 97.426526 -355.211126)
		(end 97.426526 -360.084624)
		(width 0.254)
		(layer "B.Cu")
		(net "VSENSE_PVCCIN_CPU1_DN")
	)
	(segment
		(start 353.111562 -285.939484)
		(end 353.111816 -285.939738)
		(width 0.254)
		(layer "F.Cu")
		(net "VSENSE_PVCCIN_CPU0_DP")
	)
	(segment
		(start 351.900744 -352.02114)
		(end 351.50806 -352.02114)
		(width 0.254)
		(layer "F.Cu")
		(net "VSENSE_PVCCIN_CPU0_DP")
	)
	(segment
		(start 352.316796 -351.605088)
		(end 351.900744 -352.02114)
		(width 0.254)
		(layer "F.Cu")
		(net "VSENSE_PVCCIN_CPU0_DP")
	)
	(segment
		(start 353.111816 -285.939738)
		(end 353.111816 -286.475424)
		(width 0.254)
		(layer "F.Cu")
		(net "VSENSE_PVCCIN_CPU0_DP")
	)
	(via
		(at 352.316796 -351.605088)
		(size 0.508)
		(drill 0.254)
		(layers "F.Cu" "B.Cu")
		(net "VSENSE_PVCCIN_CPU0_DP")
	)
	(via
		(at 353.111816 -286.475424)
		(size 0.4572)
		(drill 0.2032)
		(layers "F.Cu" "B.Cu")
		(net "VSENSE_PVCCIN_CPU0_DP")
	)
	(segment
		(start 325.375016 -332.407006)
		(end 324.733158 -332.407006)
		(width 0.254)
		(layer "B.Cu")
		(net "VSENSE_PVCCIN_CPU0_DP")
	)
	(segment
		(start 321.687698 -345.502992)
		(end 321.687698 -339.97011)
		(width 0.254)
		(layer "B.Cu")
		(net "VSENSE_PVCCIN_CPU0_DP")
	)
	(segment
		(start 352.411792 -288.50717)
		(end 352.406966 -288.509964)
		(width 0.254)
		(layer "B.Cu")
		(net "VSENSE_PVCCIN_CPU0_DP")
	)
	(segment
		(start 343.450926 -364.447836)
		(end 331.743558 -364.447836)
		(width 0.254)
		(layer "B.Cu")
		(net "VSENSE_PVCCIN_CPU0_DP")
	)
	(segment
		(start 332.159356 -291.217096)
		(end 325.974964 -297.401488)
		(width 0.254)
		(layer "B.Cu")
		(net "VSENSE_PVCCIN_CPU0_DP")
	)
	(segment
		(start 352.316796 -351.605088)
		(end 352.316796 -351.41662)
		(width 0.254)
		(layer "B.Cu")
		(net "VSENSE_PVCCIN_CPU0_DP")
	)
	(segment
		(start 352.316796 -351.41662)
		(end 352.5647 -351.168716)
		(width 0.254)
		(layer "B.Cu")
		(net "VSENSE_PVCCIN_CPU0_DP")
	)
	(segment
		(start 352.5647 -350.650556)
		(end 352.281236 -350.367092)
		(width 0.254)
		(layer "B.Cu")
		(net "VSENSE_PVCCIN_CPU0_DP")
	)
	(segment
		(start 352.881692 -287.693354)
		(end 352.87204 -287.698942)
		(width 0.254)
		(layer "B.Cu")
		(net "VSENSE_PVCCIN_CPU0_DP")
	)
	(segment
		(start 352.5647 -351.168716)
		(end 352.5647 -350.650556)
		(width 0.254)
		(layer "B.Cu")
		(net "VSENSE_PVCCIN_CPU0_DP")
	)
	(segment
		(start 351.69729 -290.022534)
		(end 350.502728 -291.217096)
		(width 0.254)
		(layer "B.Cu")
		(net "VSENSE_PVCCIN_CPU0_DP")
	)
	(segment
		(start 351.936812 -289.373818)
		(end 351.69729 -289.61334)
		(width 0.254)
		(layer "B.Cu")
		(net "VSENSE_PVCCIN_CPU0_DP")
	)
	(segment
		(start 352.172016 -288.903664)
		(end 352.172016 -289.096958)
		(width 0.254)
		(layer "B.Cu")
		(net "VSENSE_PVCCIN_CPU0_DP")
	)
	(segment
		(start 351.69729 -289.61334)
		(end 351.69729 -290.022534)
		(width 0.254)
		(layer "B.Cu")
		(net "VSENSE_PVCCIN_CPU0_DP")
	)
	(segment
		(start 322.048124 -333.281528)
		(end 322.923916 -332.405736)
		(width 0.254)
		(layer "B.Cu")
		(net "VSENSE_PVCCIN_CPU0_DP")
	)
	(segment
		(start 324.746874 -357.451152)
		(end 324.746874 -348.562168)
		(width 0.254)
		(layer "B.Cu")
		(net "VSENSE_PVCCIN_CPU0_DP")
	)
	(segment
		(start 353.111816 -286.475424)
		(end 353.111816 -287.28924)
		(width 0.254)
		(layer "B.Cu")
		(net "VSENSE_PVCCIN_CPU0_DP")
	)
	(segment
		(start 331.743558 -364.447836)
		(end 324.746874 -357.451152)
		(width 0.254)
		(layer "B.Cu")
		(net "VSENSE_PVCCIN_CPU0_DP")
	)
	(segment
		(start 350.502728 -291.217096)
		(end 332.159356 -291.217096)
		(width 0.254)
		(layer "B.Cu")
		(net "VSENSE_PVCCIN_CPU0_DP")
	)
	(segment
		(start 323.973952 -332.405736)
		(end 324.35292 -332.026768)
		(width 0.254)
		(layer "B.Cu")
		(net "VSENSE_PVCCIN_CPU0_DP")
	)
	(segment
		(start 350.823784 -350.367092)
		(end 346.162884 -355.027992)
		(width 0.254)
		(layer "B.Cu")
		(net "VSENSE_PVCCIN_CPU0_DP")
	)
	(segment
		(start 324.746874 -348.562168)
		(end 321.687698 -345.502992)
		(width 0.254)
		(layer "B.Cu")
		(net "VSENSE_PVCCIN_CPU0_DP")
	)
	(segment
		(start 352.281236 -350.367092)
		(end 350.823784 -350.367092)
		(width 0.254)
		(layer "B.Cu")
		(net "VSENSE_PVCCIN_CPU0_DP")
	)
	(segment
		(start 321.687698 -339.97011)
		(end 322.048124 -339.609684)
		(width 0.254)
		(layer "B.Cu")
		(net "VSENSE_PVCCIN_CPU0_DP")
	)
	(segment
		(start 324.733158 -332.407006)
		(end 324.35292 -332.026768)
		(width 0.254)
		(layer "B.Cu")
		(net "VSENSE_PVCCIN_CPU0_DP")
	)
	(segment
		(start 322.048124 -339.609684)
		(end 322.048124 -333.281528)
		(width 0.254)
		(layer "B.Cu")
		(net "VSENSE_PVCCIN_CPU0_DP")
	)
	(segment
		(start 351.936812 -289.362134)
		(end 351.936812 -289.373818)
		(width 0.254)
		(layer "B.Cu")
		(net "VSENSE_PVCCIN_CPU0_DP")
	)
	(segment
		(start 325.974964 -331.807058)
		(end 325.375016 -332.407006)
		(width 0.254)
		(layer "B.Cu")
		(net "VSENSE_PVCCIN_CPU0_DP")
	)
	(segment
		(start 325.974964 -297.401488)
		(end 325.974964 -331.807058)
		(width 0.254)
		(layer "B.Cu")
		(net "VSENSE_PVCCIN_CPU0_DP")
	)
	(segment
		(start 346.162884 -355.027992)
		(end 346.162884 -361.735878)
		(width 0.254)
		(layer "B.Cu")
		(net "VSENSE_PVCCIN_CPU0_DP")
	)
	(segment
		(start 322.923916 -332.405736)
		(end 323.973952 -332.405736)
		(width 0.254)
		(layer "B.Cu")
		(net "VSENSE_PVCCIN_CPU0_DP")
	)
	(segment
		(start 346.162884 -361.735878)
		(end 343.450926 -364.447836)
		(width 0.254)
		(layer "B.Cu")
		(net "VSENSE_PVCCIN_CPU0_DP")
	)
	(arc
		(start 352.172016 -289.096958)
		(mid 352.07855 -289.250957)
		(end 351.936812 -289.362134)
		(width 0.254)
		(layer "B.Cu")
		(net "VSENSE_PVCCIN_CPU0_DP")
	)
	(arc
		(start 352.406966 -288.509964)
		(mid 352.238243 -288.67623)
		(end 352.172016 -288.903664)
		(width 0.254)
		(layer "B.Cu")
		(net "VSENSE_PVCCIN_CPU0_DP")
	)
	(arc
		(start 352.641916 -288.103056)
		(mid 352.580353 -288.335579)
		(end 352.411792 -288.50717)
		(width 0.254)
		(layer "B.Cu")
		(net "VSENSE_PVCCIN_CPU0_DP")
	)
	(arc
		(start 352.87204 -287.698942)
		(mid 352.703484 -287.870536)
		(end 352.641916 -288.103056)
		(width 0.254)
		(layer "B.Cu")
		(net "VSENSE_PVCCIN_CPU0_DP")
	)
	(arc
		(start 353.111816 -287.28924)
		(mid 353.050253 -287.521763)
		(end 352.881692 -287.693354)
		(width 0.254)
		(layer "B.Cu")
		(net "VSENSE_PVCCIN_CPU0_DP")
	)
	(segment
		(start 354.252022 -353.342956)
		(end 354.718112 -353.809046)
		(width 0.1778)
		(layer "F.Cu")
		(net "VSENSE_PVCCIN_CPU0_DN")
	)
	(segment
		(start 352.641916 -288.381186)
		(end 352.641916 -288.917126)
		(width 0.254)
		(layer "F.Cu")
		(net "VSENSE_PVCCIN_CPU0_DN")
	)
	(segment
		(start 353.535488 -352.42119)
		(end 353.851718 -352.42119)
		(width 0.254)
		(layer "F.Cu")
		(net "VSENSE_PVCCIN_CPU0_DN")
	)
	(segment
		(start 354.252022 -353.137724)
		(end 354.252022 -353.342956)
		(width 0.1778)
		(layer "F.Cu")
		(net "VSENSE_PVCCIN_CPU0_DN")
	)
	(segment
		(start 354.718112 -353.809046)
		(end 354.718112 -355.97338)
		(width 0.1778)
		(layer "F.Cu")
		(net "VSENSE_PVCCIN_CPU0_DN")
	)
	(segment
		(start 353.851718 -352.42119)
		(end 354.252022 -352.821494)
		(width 0.254)
		(layer "F.Cu")
		(net "VSENSE_PVCCIN_CPU0_DN")
	)
	(segment
		(start 354.252022 -352.821494)
		(end 354.252022 -353.137724)
		(width 0.254)
		(layer "F.Cu")
		(net "VSENSE_PVCCIN_CPU0_DN")
	)
	(segment
		(start 353.180396 -351.826068)
		(end 353.180396 -352.066098)
		(width 0.254)
		(layer "F.Cu")
		(net "VSENSE_PVCCIN_CPU0_DN")
	)
	(segment
		(start 353.180396 -352.066098)
		(end 353.535488 -352.42119)
		(width 0.254)
		(layer "F.Cu")
		(net "VSENSE_PVCCIN_CPU0_DN")
	)
	(via
		(at 352.641916 -288.917126)
		(size 0.4572)
		(drill 0.2032)
		(layers "F.Cu" "B.Cu")
		(net "VSENSE_PVCCIN_CPU0_DN")
	)
	(via
		(at 353.180396 -351.826068)
		(size 0.762)
		(drill 0.254)
		(layers "F.Cu" "B.Cu")
		(net "VSENSE_PVCCIN_CPU0_DN")
	)
	(segment
		(start 322.068698 -340.128098)
		(end 322.429124 -339.767672)
		(width 0.254)
		(layer "B.Cu")
		(net "VSENSE_PVCCIN_CPU0_DN")
	)
	(segment
		(start 322.068698 -345.345004)
		(end 322.068698 -340.128098)
		(width 0.254)
		(layer "B.Cu")
		(net "VSENSE_PVCCIN_CPU0_DN")
	)
	(segment
		(start 352.439224 -349.986092)
		(end 350.665796 -349.986092)
		(width 0.254)
		(layer "B.Cu")
		(net "VSENSE_PVCCIN_CPU0_DN")
	)
	(segment
		(start 326.355964 -331.965046)
		(end 325.533004 -332.788006)
		(width 0.254)
		(layer "B.Cu")
		(net "VSENSE_PVCCIN_CPU0_DN")
	)
	(segment
		(start 350.665796 -349.986092)
		(end 345.781884 -354.870004)
		(width 0.254)
		(layer "B.Cu")
		(net "VSENSE_PVCCIN_CPU0_DN")
	)
	(segment
		(start 352.9457 -351.178368)
		(end 352.9457 -350.492568)
		(width 0.254)
		(layer "B.Cu")
		(net "VSENSE_PVCCIN_CPU0_DN")
	)
	(segment
		(start 324.730872 -332.788006)
		(end 324.35292 -333.165958)
		(width 0.254)
		(layer "B.Cu")
		(net "VSENSE_PVCCIN_CPU0_DN")
	)
	(segment
		(start 332.317344 -291.598096)
		(end 326.355964 -297.559476)
		(width 0.254)
		(layer "B.Cu")
		(net "VSENSE_PVCCIN_CPU0_DN")
	)
	(segment
		(start 326.355964 -297.559476)
		(end 326.355964 -331.965046)
		(width 0.254)
		(layer "B.Cu")
		(net "VSENSE_PVCCIN_CPU0_DN")
	)
	(segment
		(start 352.510344 -290.34994)
		(end 351.908872 -290.34994)
		(width 0.254)
		(layer "B.Cu")
		(net "VSENSE_PVCCIN_CPU0_DN")
	)
	(segment
		(start 325.127874 -357.293164)
		(end 325.127874 -348.40418)
		(width 0.254)
		(layer "B.Cu")
		(net "VSENSE_PVCCIN_CPU0_DN")
	)
	(segment
		(start 322.429124 -339.767672)
		(end 322.429124 -333.439516)
		(width 0.254)
		(layer "B.Cu")
		(net "VSENSE_PVCCIN_CPU0_DN")
	)
	(segment
		(start 325.533004 -332.788006)
		(end 324.730872 -332.788006)
		(width 0.254)
		(layer "B.Cu")
		(net "VSENSE_PVCCIN_CPU0_DN")
	)
	(segment
		(start 351.908872 -290.34994)
		(end 350.660716 -291.598096)
		(width 0.254)
		(layer "B.Cu")
		(net "VSENSE_PVCCIN_CPU0_DN")
	)
	(segment
		(start 352.641916 -290.218368)
		(end 352.510344 -290.34994)
		(width 0.254)
		(layer "B.Cu")
		(net "VSENSE_PVCCIN_CPU0_DN")
	)
	(segment
		(start 350.660716 -291.598096)
		(end 332.317344 -291.598096)
		(width 0.254)
		(layer "B.Cu")
		(net "VSENSE_PVCCIN_CPU0_DN")
	)
	(segment
		(start 353.180396 -351.826068)
		(end 353.180396 -351.413064)
		(width 0.254)
		(layer "B.Cu")
		(net "VSENSE_PVCCIN_CPU0_DN")
	)
	(segment
		(start 322.429124 -333.439516)
		(end 323.081904 -332.786736)
		(width 0.254)
		(layer "B.Cu")
		(net "VSENSE_PVCCIN_CPU0_DN")
	)
	(segment
		(start 352.641916 -288.917126)
		(end 352.641916 -290.218368)
		(width 0.254)
		(layer "B.Cu")
		(net "VSENSE_PVCCIN_CPU0_DN")
	)
	(segment
		(start 345.781884 -361.57789)
		(end 343.292938 -364.066836)
		(width 0.254)
		(layer "B.Cu")
		(net "VSENSE_PVCCIN_CPU0_DN")
	)
	(segment
		(start 343.292938 -364.066836)
		(end 331.901546 -364.066836)
		(width 0.254)
		(layer "B.Cu")
		(net "VSENSE_PVCCIN_CPU0_DN")
	)
	(segment
		(start 353.180396 -351.413064)
		(end 352.9457 -351.178368)
		(width 0.254)
		(layer "B.Cu")
		(net "VSENSE_PVCCIN_CPU0_DN")
	)
	(segment
		(start 323.081904 -332.786736)
		(end 323.973698 -332.786736)
		(width 0.254)
		(layer "B.Cu")
		(net "VSENSE_PVCCIN_CPU0_DN")
	)
	(segment
		(start 345.781884 -354.870004)
		(end 345.781884 -361.57789)
		(width 0.254)
		(layer "B.Cu")
		(net "VSENSE_PVCCIN_CPU0_DN")
	)
	(segment
		(start 323.973698 -332.786736)
		(end 324.35292 -333.165958)
		(width 0.254)
		(layer "B.Cu")
		(net "VSENSE_PVCCIN_CPU0_DN")
	)
	(segment
		(start 331.901546 -364.066836)
		(end 325.127874 -357.293164)
		(width 0.254)
		(layer "B.Cu")
		(net "VSENSE_PVCCIN_CPU0_DN")
	)
	(segment
		(start 325.127874 -348.40418)
		(end 322.068698 -345.345004)
		(width 0.254)
		(layer "B.Cu")
		(net "VSENSE_PVCCIN_CPU0_DN")
	)
	(segment
		(start 352.9457 -350.492568)
		(end 352.439224 -349.986092)
		(width 0.254)
		(layer "B.Cu")
		(net "VSENSE_PVCCIN_CPU0_DN")
	)
	(segment
		(start 33.824926 -137.135362)
		(end 35.171126 -137.135362)
		(width 0.254)
		(layer "F.Cu")
		(net "VSENSE_PVCCINFAON_CPU1_DP")
	)
	(segment
		(start 113.050066 -221.947994)
		(end 113.049812 -221.94774)
		(width 0.254)
		(layer "F.Cu")
		(net "VSENSE_PVCCINFAON_CPU1_DP")
	)
	(segment
		(start 74.62012 -143.769588)
		(end 73.68413 -143.769588)
		(width 0.254)
		(layer "F.Cu")
		(net "VSENSE_PVCCINFAON_CPU1_DP")
	)
	(segment
		(start 113.050066 -222.48368)
		(end 113.050066 -221.947994)
		(width 0.254)
		(layer "F.Cu")
		(net "VSENSE_PVCCINFAON_CPU1_DP")
	)
	(segment
		(start 74.62647 -143.763238)
		(end 74.62012 -143.769588)
		(width 0.254)
		(layer "F.Cu")
		(net "VSENSE_PVCCINFAON_CPU1_DP")
	)
	(segment
		(start 33.6804 -137.279888)
		(end 33.824926 -137.135362)
		(width 0.254)
		(layer "F.Cu")
		(net "VSENSE_PVCCINFAON_CPU1_DP")
	)
	(via
		(at 74.62647 -143.763238)
		(size 0.508)
		(drill 0.254)
		(layers "F.Cu" "B.Cu")
		(net "VSENSE_PVCCINFAON_CPU1_DP")
	)
	(via
		(at 92.227654 -176.262792)
		(size 0.508)
		(drill 0.254)
		(layers "F.Cu" "B.Cu")
		(net "VSENSE_PVCCINFAON_CPU1_DP")
	)
	(via
		(at 113.049812 -221.94774)
		(size 0.4572)
		(drill 0.2032)
		(layers "F.Cu" "B.Cu")
		(net "VSENSE_PVCCINFAON_CPU1_DP")
	)
	(via
		(at 33.6804 -137.279888)
		(size 0.508)
		(drill 0.254)
		(layers "F.Cu" "B.Cu")
		(net "VSENSE_PVCCINFAON_CPU1_DP")
	)
	(segment
		(start 124.140976 -223.25076)
		(end 124.15266 -223.243648)
		(width 0.0889)
		(layer "B.Cu")
		(net "VSENSE_PVCCINFAON_CPU1_DP")
	)
	(segment
		(start 115.774216 -222.72244)
		(end 115.774216 -222.76181)
		(width 0.0889)
		(layer "B.Cu")
		(net "VSENSE_PVCCINFAON_CPU1_DP")
	)
	(segment
		(start 127.890778 -221.627954)
		(end 127.970026 -221.582234)
		(width 0.0889)
		(layer "B.Cu")
		(net "VSENSE_PVCCINFAON_CPU1_DP")
	)
	(segment
		(start 92.468954 -176.504092)
		(end 92.227654 -176.262792)
		(width 0.254)
		(layer "B.Cu")
		(net "VSENSE_PVCCINFAON_CPU1_DP")
	)
	(segment
		(start 116.622576 -223.25076)
		(end 116.63426 -223.243648)
		(width 0.0889)
		(layer "B.Cu")
		(net "VSENSE_PVCCINFAON_CPU1_DP")
	)
	(segment
		(start 128.36906 -219.181934)
		(end 128.379728 -219.175838)
		(width 0.0889)
		(layer "B.Cu")
		(net "VSENSE_PVCCINFAON_CPU1_DP")
	)
	(segment
		(start 128.182116 -221.213172)
		(end 128.182116 -221.12224)
		(width 0.0889)
		(layer "B.Cu")
		(net "VSENSE_PVCCINFAON_CPU1_DP")
	)
	(segment
		(start 118.502176 -223.25076)
		(end 118.51386 -223.243648)
		(width 0.0889)
		(layer "B.Cu")
		(net "VSENSE_PVCCINFAON_CPU1_DP")
	)
	(segment
		(start 122.261376 -223.25076)
		(end 122.27306 -223.243648)
		(width 0.0889)
		(layer "B.Cu")
		(net "VSENSE_PVCCINFAON_CPU1_DP")
	)
	(segment
		(start 127.242316 -222.761556)
		(end 127.242316 -222.74911)
		(width 0.0889)
		(layer "B.Cu")
		(net "VSENSE_PVCCINFAON_CPU1_DP")
	)
	(segment
		(start 127.902716 -219.993972)
		(end 127.939038 -219.972636)
		(width 0.0889)
		(layer "B.Cu")
		(net "VSENSE_PVCCINFAON_CPU1_DP")
	)
	(segment
		(start 127.856996 -215.138)
		(end 127.899414 -215.112346)
		(width 0.0889)
		(layer "B.Cu")
		(net "VSENSE_PVCCINFAON_CPU1_DP")
	)
	(segment
		(start 127.853948 -220.021912)
		(end 127.902716 -219.993718)
		(width 0.0889)
		(layer "B.Cu")
		(net "VSENSE_PVCCINFAON_CPU1_DP")
	)
	(segment
		(start 127.429006 -222.437452)
		(end 127.439928 -222.431356)
		(width 0.0889)
		(layer "B.Cu")
		(net "VSENSE_PVCCINFAON_CPU1_DP")
	)
	(segment
		(start 115.588288 -222.43796)
		(end 115.592606 -222.440246)
		(width 0.0889)
		(layer "B.Cu")
		(net "VSENSE_PVCCINFAON_CPU1_DP")
	)
	(segment
		(start 128.182116 -217.878406)
		(end 128.182116 -217.864182)
		(width 0.0889)
		(layer "B.Cu")
		(net "VSENSE_PVCCINFAON_CPU1_DP")
	)
	(segment
		(start 105.153968 -176.504092)
		(end 92.468954 -176.504092)
		(width 0.254)
		(layer "B.Cu")
		(net "VSENSE_PVCCINFAON_CPU1_DP")
	)
	(segment
		(start 127.712216 -213.191852)
		(end 127.807466 -213.096602)
		(width 0.0889)
		(layer "B.Cu")
		(net "VSENSE_PVCCINFAON_CPU1_DP")
	)
	(segment
		(start 127.712216 -217.072972)
		(end 127.712216 -217.05443)
		(width 0.0889)
		(layer "B.Cu")
		(net "VSENSE_PVCCINFAON_CPU1_DP")
	)
	(segment
		(start 126.020576 -223.25076)
		(end 126.03226 -223.243648)
		(width 0.0889)
		(layer "B.Cu")
		(net "VSENSE_PVCCINFAON_CPU1_DP")
	)
	(segment
		(start 127.711962 -220.331284)
		(end 127.711962 -220.269308)
		(width 0.0889)
		(layer "B.Cu")
		(net "VSENSE_PVCCINFAON_CPU1_DP")
	)
	(segment
		(start 127.712216 -213.893908)
		(end 127.712216 -213.191852)
		(width 0.0889)
		(layer "B.Cu")
		(net "VSENSE_PVCCINFAON_CPU1_DP")
	)
	(segment
		(start 115.592606 -222.440246)
		(end 115.624102 -222.458788)
		(width 0.0889)
		(layer "B.Cu")
		(net "VSENSE_PVCCINFAON_CPU1_DP")
	)
	(segment
		(start 126.95936 -223.251268)
		(end 126.970282 -223.245172)
		(width 0.0889)
		(layer "B.Cu")
		(net "VSENSE_PVCCINFAON_CPU1_DP")
	)
	(segment
		(start 127.242316 -216.258394)
		(end 127.242316 -216.257124)
		(width 0.0889)
		(layer "B.Cu")
		(net "VSENSE_PVCCINFAON_CPU1_DP")
	)
	(segment
		(start 127.807466 -199.15759)
		(end 105.153968 -176.504092)
		(width 0.254)
		(layer "B.Cu")
		(net "VSENSE_PVCCINFAON_CPU1_DP")
	)
	(segment
		(start 127.429768 -216.574878)
		(end 127.419608 -216.569036)
		(width 0.0889)
		(layer "B.Cu")
		(net "VSENSE_PVCCINFAON_CPU1_DP")
	)
	(segment
		(start 120.381776 -223.25076)
		(end 120.39346 -223.243648)
		(width 0.0889)
		(layer "B.Cu")
		(net "VSENSE_PVCCINFAON_CPU1_DP")
	)
	(segment
		(start 128.369568 -218.202764)
		(end 128.360678 -218.197684)
		(width 0.0889)
		(layer "B.Cu")
		(net "VSENSE_PVCCINFAON_CPU1_DP")
	)
	(segment
		(start 127.902716 -219.993718)
		(end 127.902716 -219.993972)
		(width 0.0889)
		(layer "B.Cu")
		(net "VSENSE_PVCCINFAON_CPU1_DP")
	)
	(segment
		(start 127.910082 -220.650308)
		(end 127.89916 -220.644212)
		(width 0.0889)
		(layer "B.Cu")
		(net "VSENSE_PVCCINFAON_CPU1_DP")
	)
	(segment
		(start 127.712216 -215.421972)
		(end 127.71374 -215.382602)
		(width 0.0889)
		(layer "B.Cu")
		(net "VSENSE_PVCCINFAON_CPU1_DP")
	)
	(segment
		(start 127.420878 -215.931242)
		(end 127.425704 -215.928448)
		(width 0.0889)
		(layer "B.Cu")
		(net "VSENSE_PVCCINFAON_CPU1_DP")
	)
	(segment
		(start 128.181608 -214.644732)
		(end 128.181608 -214.424768)
		(width 0.0889)
		(layer "B.Cu")
		(net "VSENSE_PVCCINFAON_CPU1_DP")
	)
	(segment
		(start 127.807466 -213.096602)
		(end 127.807466 -212.903562)
		(width 0.0889)
		(layer "B.Cu")
		(net "VSENSE_PVCCINFAON_CPU1_DP")
	)
	(segment
		(start 128.182116 -219.547694)
		(end 128.182116 -219.493592)
		(width 0.0889)
		(layer "B.Cu")
		(net "VSENSE_PVCCINFAON_CPU1_DP")
	)
	(segment
		(start 113.627916 -222.391478)
		(end 113.707164 -222.437198)
		(width 0.0889)
		(layer "B.Cu")
		(net "VSENSE_PVCCINFAON_CPU1_DP")
	)
	(segment
		(start 115.586764 -222.437198)
		(end 115.588288 -222.43796)
		(width 0.0889)
		(layer "B.Cu")
		(net "VSENSE_PVCCINFAON_CPU1_DP")
	)
	(segment
		(start 127.807466 -212.903562)
		(end 127.807466 -199.15759)
		(width 0.254)
		(layer "B.Cu")
		(net "VSENSE_PVCCINFAON_CPU1_DP")
	)
	(arc
		(start 113.707164 -222.437198)
		(mid 113.989866 -222.512974)
		(end 114.272568 -222.437198)
		(width 0.0889)
		(layer "B.Cu")
		(net "VSENSE_PVCCINFAON_CPU1_DP")
	)
	(arc
		(start 128.182116 -221.12224)
		(mid 128.106684 -220.851355)
		(end 127.910082 -220.650308)
		(width 0.0889)
		(layer "B.Cu")
		(net "VSENSE_PVCCINFAON_CPU1_DP")
	)
	(arc
		(start 118.876318 -223.251014)
		(mid 119.158766 -223.326663)
		(end 119.441214 -223.251014)
		(width 0.0889)
		(layer "B.Cu")
		(net "VSENSE_PVCCINFAON_CPU1_DP")
	)
	(arc
		(start 126.970282 -223.245172)
		(mid 127.169713 -223.039031)
		(end 127.242316 -222.761556)
		(width 0.0889)
		(layer "B.Cu")
		(net "VSENSE_PVCCINFAON_CPU1_DP")
	)
	(arc
		(start 117.936518 -223.251014)
		(mid 118.219394 -223.32679)
		(end 118.502176 -223.25076)
		(width 0.0889)
		(layer "B.Cu")
		(net "VSENSE_PVCCINFAON_CPU1_DP")
	)
	(arc
		(start 123.200414 -223.251014)
		(mid 123.387866 -223.200778)
		(end 123.575318 -223.251014)
		(width 0.0889)
		(layer "B.Cu")
		(net "VSENSE_PVCCINFAON_CPU1_DP")
	)
	(arc
		(start 127.899414 -217.388694)
		(mid 127.764481 -217.25534)
		(end 127.712216 -217.072972)
		(width 0.0889)
		(layer "B.Cu")
		(net "VSENSE_PVCCINFAON_CPU1_DP")
	)
	(arc
		(start 127.970026 -221.582234)
		(mid 128.12529 -221.425994)
		(end 128.182116 -221.213172)
		(width 0.0889)
		(layer "B.Cu")
		(net "VSENSE_PVCCINFAON_CPU1_DP")
	)
	(arc
		(start 125.080014 -223.251014)
		(mid 125.267466 -223.200778)
		(end 125.454918 -223.251014)
		(width 0.0889)
		(layer "B.Cu")
		(net "VSENSE_PVCCINFAON_CPU1_DP")
	)
	(arc
		(start 117.561614 -223.251014)
		(mid 117.749066 -223.200778)
		(end 117.936518 -223.251014)
		(width 0.0889)
		(layer "B.Cu")
		(net "VSENSE_PVCCINFAON_CPU1_DP")
	)
	(arc
		(start 120.39346 -223.243648)
		(mid 120.57563 -223.200659)
		(end 120.755918 -223.251014)
		(width 0.0889)
		(layer "B.Cu")
		(net "VSENSE_PVCCINFAON_CPU1_DP")
	)
	(arc
		(start 121.695718 -223.251014)
		(mid 121.978594 -223.32679)
		(end 122.261376 -223.25076)
		(width 0.0889)
		(layer "B.Cu")
		(net "VSENSE_PVCCINFAON_CPU1_DP")
	)
	(arc
		(start 115.212368 -222.437198)
		(mid 115.399566 -222.387055)
		(end 115.586764 -222.437198)
		(width 0.0889)
		(layer "B.Cu")
		(net "VSENSE_PVCCINFAON_CPU1_DP")
	)
	(arc
		(start 114.272568 -222.437198)
		(mid 114.459766 -222.387055)
		(end 114.646964 -222.437198)
		(width 0.0889)
		(layer "B.Cu")
		(net "VSENSE_PVCCINFAON_CPU1_DP")
	)
	(arc
		(start 123.575318 -223.251014)
		(mid 123.858194 -223.32679)
		(end 124.140976 -223.25076)
		(width 0.0889)
		(layer "B.Cu")
		(net "VSENSE_PVCCINFAON_CPU1_DP")
	)
	(arc
		(start 120.755918 -223.251014)
		(mid 121.038366 -223.326663)
		(end 121.320814 -223.251014)
		(width 0.0889)
		(layer "B.Cu")
		(net "VSENSE_PVCCINFAON_CPU1_DP")
	)
	(arc
		(start 127.712216 -221.94774)
		(mid 127.75975 -221.764524)
		(end 127.890778 -221.627954)
		(width 0.0889)
		(layer "B.Cu")
		(net "VSENSE_PVCCINFAON_CPU1_DP")
	)
	(arc
		(start 122.635518 -223.251014)
		(mid 122.917966 -223.326663)
		(end 123.200414 -223.251014)
		(width 0.0889)
		(layer "B.Cu")
		(net "VSENSE_PVCCINFAON_CPU1_DP")
	)
	(arc
		(start 124.15266 -223.243648)
		(mid 124.33483 -223.200659)
		(end 124.515118 -223.251014)
		(width 0.0889)
		(layer "B.Cu")
		(net "VSENSE_PVCCINFAON_CPU1_DP")
	)
	(arc
		(start 128.360678 -218.197684)
		(mid 128.229764 -218.061324)
		(end 128.182116 -217.878406)
		(width 0.0889)
		(layer "B.Cu")
		(net "VSENSE_PVCCINFAON_CPU1_DP")
	)
	(arc
		(start 121.320814 -223.251014)
		(mid 121.508266 -223.200778)
		(end 121.695718 -223.251014)
		(width 0.0889)
		(layer "B.Cu")
		(net "VSENSE_PVCCINFAON_CPU1_DP")
	)
	(arc
		(start 126.03226 -223.243648)
		(mid 126.21443 -223.200659)
		(end 126.394718 -223.251014)
		(width 0.0889)
		(layer "B.Cu")
		(net "VSENSE_PVCCINFAON_CPU1_DP")
	)
	(arc
		(start 118.51386 -223.243648)
		(mid 118.69603 -223.200659)
		(end 118.876318 -223.251014)
		(width 0.0889)
		(layer "B.Cu")
		(net "VSENSE_PVCCINFAON_CPU1_DP")
	)
	(arc
		(start 127.899414 -215.112346)
		(mid 128.100696 -214.914859)
		(end 128.181608 -214.644732)
		(width 0.0889)
		(layer "B.Cu")
		(net "VSENSE_PVCCINFAON_CPU1_DP")
	)
	(arc
		(start 128.382522 -218.210638)
		(mid 128.376071 -218.206658)
		(end 128.369568 -218.202764)
		(width 0.0889)
		(layer "B.Cu")
		(net "VSENSE_PVCCINFAON_CPU1_DP")
	)
	(arc
		(start 127.711962 -215.436704)
		(mid 127.712014 -215.429337)
		(end 127.712216 -215.421972)
		(width 0.0889)
		(layer "B.Cu")
		(net "VSENSE_PVCCINFAON_CPU1_DP")
	)
	(arc
		(start 128.182116 -217.864182)
		(mid 128.102897 -217.589497)
		(end 127.899414 -217.388694)
		(width 0.0889)
		(layer "B.Cu")
		(net "VSENSE_PVCCINFAON_CPU1_DP")
	)
	(arc
		(start 127.243078 -216.224358)
		(mid 127.296537 -216.056313)
		(end 127.420878 -215.931242)
		(width 0.0889)
		(layer "B.Cu")
		(net "VSENSE_PVCCINFAON_CPU1_DP")
	)
	(arc
		(start 125.454918 -223.251014)
		(mid 125.737794 -223.32679)
		(end 126.020576 -223.25076)
		(width 0.0889)
		(layer "B.Cu")
		(net "VSENSE_PVCCINFAON_CPU1_DP")
	)
	(arc
		(start 115.774216 -222.76181)
		(mid 116.057276 -223.251163)
		(end 116.622576 -223.25076)
		(width 0.0889)
		(layer "B.Cu")
		(net "VSENSE_PVCCINFAON_CPU1_DP")
	)
	(arc
		(start 116.63426 -223.243648)
		(mid 116.81643 -223.200659)
		(end 116.996718 -223.251014)
		(width 0.0889)
		(layer "B.Cu")
		(net "VSENSE_PVCCINFAON_CPU1_DP")
	)
	(arc
		(start 119.816118 -223.251014)
		(mid 120.098994 -223.32679)
		(end 120.381776 -223.25076)
		(width 0.0889)
		(layer "B.Cu")
		(net "VSENSE_PVCCINFAON_CPU1_DP")
	)
	(arc
		(start 122.27306 -223.243648)
		(mid 122.45523 -223.200659)
		(end 122.635518 -223.251014)
		(width 0.0889)
		(layer "B.Cu")
		(net "VSENSE_PVCCINFAON_CPU1_DP")
	)
	(arc
		(start 114.646964 -222.437198)
		(mid 114.929666 -222.512974)
		(end 115.212368 -222.437198)
		(width 0.0889)
		(layer "B.Cu")
		(net "VSENSE_PVCCINFAON_CPU1_DP")
	)
	(arc
		(start 127.939038 -219.972636)
		(mid 128.117032 -219.792476)
		(end 128.182116 -219.547694)
		(width 0.0889)
		(layer "B.Cu")
		(net "VSENSE_PVCCINFAON_CPU1_DP")
	)
	(arc
		(start 113.049812 -221.94774)
		(mid 113.324332 -222.188542)
		(end 113.627916 -222.391478)
		(width 0.0889)
		(layer "B.Cu")
		(net "VSENSE_PVCCINFAON_CPU1_DP")
	)
	(arc
		(start 115.624102 -222.458788)
		(mid 115.734061 -222.570743)
		(end 115.774216 -222.72244)
		(width 0.0889)
		(layer "B.Cu")
		(net "VSENSE_PVCCINFAON_CPU1_DP")
	)
	(arc
		(start 127.71374 -215.382602)
		(mid 127.754789 -215.242398)
		(end 127.856996 -215.138)
		(width 0.0889)
		(layer "B.Cu")
		(net "VSENSE_PVCCINFAON_CPU1_DP")
	)
	(arc
		(start 128.182116 -219.493592)
		(mid 128.235248 -219.313549)
		(end 128.36906 -219.181934)
		(width 0.0889)
		(layer "B.Cu")
		(net "VSENSE_PVCCINFAON_CPU1_DP")
	)
	(arc
		(start 127.242316 -222.74911)
		(mid 127.295391 -222.569161)
		(end 127.429006 -222.437452)
		(width 0.0889)
		(layer "B.Cu")
		(net "VSENSE_PVCCINFAON_CPU1_DP")
	)
	(arc
		(start 127.242316 -216.24036)
		(mid 127.242613 -216.232355)
		(end 127.243078 -216.224358)
		(width 0.0889)
		(layer "B.Cu")
		(net "VSENSE_PVCCINFAON_CPU1_DP")
	)
	(arc
		(start 127.711962 -220.269308)
		(mid 127.749982 -220.126687)
		(end 127.853948 -220.021912)
		(width 0.0889)
		(layer "B.Cu")
		(net "VSENSE_PVCCINFAON_CPU1_DP")
	)
	(arc
		(start 116.996718 -223.251014)
		(mid 117.279166 -223.326663)
		(end 117.561614 -223.251014)
		(width 0.0889)
		(layer "B.Cu")
		(net "VSENSE_PVCCINFAON_CPU1_DP")
	)
	(arc
		(start 127.419608 -216.569036)
		(mid 127.291146 -216.436422)
		(end 127.242316 -216.258394)
		(width 0.0889)
		(layer "B.Cu")
		(net "VSENSE_PVCCINFAON_CPU1_DP")
	)
	(arc
		(start 127.425704 -215.928448)
		(mid 127.632064 -215.719374)
		(end 127.711962 -215.436704)
		(width 0.0889)
		(layer "B.Cu")
		(net "VSENSE_PVCCINFAON_CPU1_DP")
	)
	(arc
		(start 127.439928 -222.431356)
		(mid 127.639454 -222.225236)
		(end 127.712216 -221.94774)
		(width 0.0889)
		(layer "B.Cu")
		(net "VSENSE_PVCCINFAON_CPU1_DP")
	)
	(arc
		(start 127.712216 -217.05443)
		(mid 127.634105 -216.777481)
		(end 127.429768 -216.574878)
		(width 0.0889)
		(layer "B.Cu")
		(net "VSENSE_PVCCINFAON_CPU1_DP")
	)
	(arc
		(start 124.515118 -223.251014)
		(mid 124.797566 -223.326663)
		(end 125.080014 -223.251014)
		(width 0.0889)
		(layer "B.Cu")
		(net "VSENSE_PVCCINFAON_CPU1_DP")
	)
	(arc
		(start 126.394718 -223.251014)
		(mid 126.676993 -223.326663)
		(end 126.95936 -223.251268)
		(width 0.0889)
		(layer "B.Cu")
		(net "VSENSE_PVCCINFAON_CPU1_DP")
	)
	(arc
		(start 127.89916 -220.644212)
		(mid 127.764937 -220.512048)
		(end 127.711962 -220.331284)
		(width 0.0889)
		(layer "B.Cu")
		(net "VSENSE_PVCCINFAON_CPU1_DP")
	)
	(arc
		(start 127.242316 -216.257124)
		(mid 127.242222 -216.248742)
		(end 127.242316 -216.24036)
		(width 0.0889)
		(layer "B.Cu")
		(net "VSENSE_PVCCINFAON_CPU1_DP")
	)
	(arc
		(start 119.441214 -223.251014)
		(mid 119.628666 -223.200778)
		(end 119.816118 -223.251014)
		(width 0.0889)
		(layer "B.Cu")
		(net "VSENSE_PVCCINFAON_CPU1_DP")
	)
	(arc
		(start 128.181608 -214.424768)
		(mid 128.070329 -214.232062)
		(end 127.896366 -214.093298)
		(width 0.0889)
		(layer "B.Cu")
		(net "VSENSE_PVCCINFAON_CPU1_DP")
	)
	(arc
		(start 128.379728 -219.175838)
		(mid 128.651902 -218.694065)
		(end 128.382522 -218.210638)
		(width 0.0889)
		(layer "B.Cu")
		(net "VSENSE_PVCCINFAON_CPU1_DP")
	)
	(arc
		(start 127.896366 -214.093298)
		(mid 127.787219 -214.00937)
		(end 127.712216 -213.893908)
		(width 0.0889)
		(layer "B.Cu")
		(net "VSENSE_PVCCINFAON_CPU1_DP")
	)
	(segment
		(start 74.62647 -143.763238)
		(end 74.86777 -144.004538)
		(width 0.254)
		(layer "In11.Cu")
		(net "VSENSE_PVCCINFAON_CPU1_DP")
	)
	(segment
		(start 76.81468 -150.55596)
		(end 76.35748 -151.01316)
		(width 0.254)
		(layer "In11.Cu")
		(net "VSENSE_PVCCINFAON_CPU1_DP")
	)
	(segment
		(start 76.35748 -151.01316)
		(end 76.35748 -155.547568)
		(width 0.254)
		(layer "In11.Cu")
		(net "VSENSE_PVCCINFAON_CPU1_DP")
	)
	(segment
		(start 79.33436 -159.078676)
		(end 93.082364 -172.82668)
		(width 0.254)
		(layer "In11.Cu")
		(net "VSENSE_PVCCINFAON_CPU1_DP")
	)
	(segment
		(start 73.700132 -144.004538)
		(end 73.18248 -144.52219)
		(width 0.254)
		(layer "In11.Cu")
		(net "VSENSE_PVCCINFAON_CPU1_DP")
	)
	(segment
		(start 74.38517 -144.004538)
		(end 73.700132 -144.004538)
		(width 0.254)
		(layer "In11.Cu")
		(net "VSENSE_PVCCINFAON_CPU1_DP")
	)
	(segment
		(start 73.18248 -144.52219)
		(end 73.18248 -145.964148)
		(width 0.254)
		(layer "In11.Cu")
		(net "VSENSE_PVCCINFAON_CPU1_DP")
	)
	(segment
		(start 76.35748 -155.547568)
		(end 79.33436 -158.524448)
		(width 0.254)
		(layer "In11.Cu")
		(net "VSENSE_PVCCINFAON_CPU1_DP")
	)
	(segment
		(start 74.86777 -144.004538)
		(end 75.68692 -144.004538)
		(width 0.254)
		(layer "In11.Cu")
		(net "VSENSE_PVCCINFAON_CPU1_DP")
	)
	(segment
		(start 79.33436 -158.524448)
		(end 79.33436 -159.078676)
		(width 0.254)
		(layer "In11.Cu")
		(net "VSENSE_PVCCINFAON_CPU1_DP")
	)
	(segment
		(start 35.712908 -140.688568)
		(end 34.50082 -139.47648)
		(width 0.254)
		(layer "In11.Cu")
		(net "VSENSE_PVCCINFAON_CPU1_DP")
	)
	(segment
		(start 75.94092 -143.750538)
		(end 75.94092 -143.253968)
		(width 0.254)
		(layer "In11.Cu")
		(net "VSENSE_PVCCINFAON_CPU1_DP")
	)
	(segment
		(start 75.29068 -147.157948)
		(end 76.81468 -148.681948)
		(width 0.254)
		(layer "In11.Cu")
		(net "VSENSE_PVCCINFAON_CPU1_DP")
	)
	(segment
		(start 73.18248 -145.964148)
		(end 74.37628 -147.157948)
		(width 0.254)
		(layer "In11.Cu")
		(net "VSENSE_PVCCINFAON_CPU1_DP")
	)
	(segment
		(start 93.082364 -172.82668)
		(end 93.082364 -176.250092)
		(width 0.254)
		(layer "In11.Cu")
		(net "VSENSE_PVCCINFAON_CPU1_DP")
	)
	(segment
		(start 73.37552 -140.688568)
		(end 35.712908 -140.688568)
		(width 0.254)
		(layer "In11.Cu")
		(net "VSENSE_PVCCINFAON_CPU1_DP")
	)
	(segment
		(start 34.50082 -137.133076)
		(end 34.439606 -137.071862)
		(width 0.254)
		(layer "In11.Cu")
		(net "VSENSE_PVCCINFAON_CPU1_DP")
	)
	(segment
		(start 75.68692 -144.004538)
		(end 75.94092 -143.750538)
		(width 0.254)
		(layer "In11.Cu")
		(net "VSENSE_PVCCINFAON_CPU1_DP")
	)
	(segment
		(start 76.81468 -148.681948)
		(end 76.81468 -150.55596)
		(width 0.254)
		(layer "In11.Cu")
		(net "VSENSE_PVCCINFAON_CPU1_DP")
	)
	(segment
		(start 92.828364 -176.504092)
		(end 92.468954 -176.504092)
		(width 0.254)
		(layer "In11.Cu")
		(net "VSENSE_PVCCINFAON_CPU1_DP")
	)
	(segment
		(start 74.37628 -147.157948)
		(end 75.29068 -147.157948)
		(width 0.254)
		(layer "In11.Cu")
		(net "VSENSE_PVCCINFAON_CPU1_DP")
	)
	(segment
		(start 75.94092 -143.253968)
		(end 73.37552 -140.688568)
		(width 0.254)
		(layer "In11.Cu")
		(net "VSENSE_PVCCINFAON_CPU1_DP")
	)
	(segment
		(start 74.62647 -143.763238)
		(end 74.38517 -144.004538)
		(width 0.254)
		(layer "In11.Cu")
		(net "VSENSE_PVCCINFAON_CPU1_DP")
	)
	(segment
		(start 34.439606 -137.071862)
		(end 33.888426 -137.071862)
		(width 0.254)
		(layer "In11.Cu")
		(net "VSENSE_PVCCINFAON_CPU1_DP")
	)
	(segment
		(start 34.50082 -139.47648)
		(end 34.50082 -137.133076)
		(width 0.254)
		(layer "In11.Cu")
		(net "VSENSE_PVCCINFAON_CPU1_DP")
	)
	(segment
		(start 33.888426 -137.071862)
		(end 33.6804 -137.279888)
		(width 0.254)
		(layer "In11.Cu")
		(net "VSENSE_PVCCINFAON_CPU1_DP")
	)
	(segment
		(start 92.468954 -176.504092)
		(end 92.227654 -176.262792)
		(width 0.254)
		(layer "In11.Cu")
		(net "VSENSE_PVCCINFAON_CPU1_DP")
	)
	(segment
		(start 93.082364 -176.250092)
		(end 92.828364 -176.504092)
		(width 0.254)
		(layer "In11.Cu")
		(net "VSENSE_PVCCINFAON_CPU1_DP")
	)
	(segment
		(start 33.461198 -132.033518)
		(end 33.461198 -132.633974)
		(width 0.1778)
		(layer "F.Cu")
		(net "VSENSE_PVCCINFAON_CPU1_DN")
	)
	(segment
		(start 74.62647 -144.626838)
		(end 74.588116 -144.665192)
		(width 0.254)
		(layer "F.Cu")
		(net "VSENSE_PVCCINFAON_CPU1_DN")
	)
	(segment
		(start 33.461198 -132.633974)
		(end 33.461198 -133.353048)
		(width 0.254)
		(layer "F.Cu")
		(net "VSENSE_PVCCINFAON_CPU1_DN")
	)
	(segment
		(start 33.6804 -136.416288)
		(end 33.9217 -136.657588)
		(width 0.254)
		(layer "F.Cu")
		(net "VSENSE_PVCCINFAON_CPU1_DN")
	)
	(segment
		(start 34.263838 -136.657588)
		(end 34.49193 -136.429496)
		(width 0.254)
		(layer "F.Cu")
		(net "VSENSE_PVCCINFAON_CPU1_DN")
	)
	(segment
		(start 34.49193 -136.429496)
		(end 34.49193 -134.707884)
		(width 0.254)
		(layer "F.Cu")
		(net "VSENSE_PVCCINFAON_CPU1_DN")
	)
	(segment
		(start 33.36925 -133.585204)
		(end 33.36925 -133.444996)
		(width 0.254)
		(layer "F.Cu")
		(net "VSENSE_PVCCINFAON_CPU1_DN")
	)
	(segment
		(start 33.9217 -136.657588)
		(end 34.263838 -136.657588)
		(width 0.254)
		(layer "F.Cu")
		(net "VSENSE_PVCCINFAON_CPU1_DN")
	)
	(segment
		(start 33.461198 -133.353048)
		(end 33.36925 -133.444996)
		(width 0.254)
		(layer "F.Cu")
		(net "VSENSE_PVCCINFAON_CPU1_DN")
	)
	(segment
		(start 114.929666 -222.48368)
		(end 114.929666 -221.94774)
		(width 0.254)
		(layer "F.Cu")
		(net "VSENSE_PVCCINFAON_CPU1_DN")
	)
	(segment
		(start 74.588116 -144.665192)
		(end 73.68413 -144.665192)
		(width 0.254)
		(layer "F.Cu")
		(net "VSENSE_PVCCINFAON_CPU1_DN")
	)
	(segment
		(start 34.49193 -134.707884)
		(end 33.36925 -133.585204)
		(width 0.254)
		(layer "F.Cu")
		(net "VSENSE_PVCCINFAON_CPU1_DN")
	)
	(via
		(at 114.929666 -221.94774)
		(size 0.4572)
		(drill 0.2032)
		(layers "F.Cu" "B.Cu")
		(net "VSENSE_PVCCINFAON_CPU1_DN")
	)
	(via
		(at 33.6804 -136.416288)
		(size 0.508)
		(drill 0.254)
		(layers "F.Cu" "B.Cu")
		(net "VSENSE_PVCCINFAON_CPU1_DN")
	)
	(via
		(at 74.62647 -144.626838)
		(size 0.508)
		(drill 0.254)
		(layers "F.Cu" "B.Cu")
		(net "VSENSE_PVCCINFAON_CPU1_DN")
	)
	(via
		(at 92.227654 -177.126392)
		(size 0.508)
		(drill 0.254)
		(layers "F.Cu" "B.Cu")
		(net "VSENSE_PVCCINFAON_CPU1_DN")
	)
	(segment
		(start 127.051816 -222.761556)
		(end 127.051816 -222.746062)
		(width 0.0889)
		(layer "B.Cu")
		(net "VSENSE_PVCCINFAON_CPU1_DN")
	)
	(segment
		(start 115.34902 -222.061532)
		(end 115.488466 -222.143066)
		(width 0.0889)
		(layer "B.Cu")
		(net "VSENSE_PVCCINFAON_CPU1_DN")
	)
	(segment
		(start 120.285764 -223.085914)
		(end 120.300496 -223.077278)
		(width 0.0889)
		(layer "B.Cu")
		(net "VSENSE_PVCCINFAON_CPU1_DN")
	)
	(segment
		(start 124.044964 -223.085914)
		(end 124.059696 -223.077278)
		(width 0.0889)
		(layer "B.Cu")
		(net "VSENSE_PVCCINFAON_CPU1_DN")
	)
	(segment
		(start 127.802386 -214.948262)
		(end 127.80391 -214.947246)
		(width 0.0889)
		(layer "B.Cu")
		(net "VSENSE_PVCCINFAON_CPU1_DN")
	)
	(segment
		(start 127.813054 -220.814646)
		(end 127.804164 -220.809566)
		(width 0.0889)
		(layer "B.Cu")
		(net "VSENSE_PVCCINFAON_CPU1_DN")
	)
	(segment
		(start 115.675156 -222.267526)
		(end 115.721384 -222.294958)
		(width 0.0889)
		(layer "B.Cu")
		(net "VSENSE_PVCCINFAON_CPU1_DN")
	)
	(segment
		(start 92.468954 -176.885092)
		(end 92.227654 -177.126392)
		(width 0.254)
		(layer "B.Cu")
		(net "VSENSE_PVCCINFAON_CPU1_DN")
	)
	(segment
		(start 127.521462 -220.334078)
		(end 127.521462 -220.269308)
		(width 0.0889)
		(layer "B.Cu")
		(net "VSENSE_PVCCINFAON_CPU1_DN")
	)
	(segment
		(start 127.521462 -217.07856)
		(end 127.521462 -217.0557)
		(width 0.0889)
		(layer "B.Cu")
		(net "VSENSE_PVCCINFAON_CPU1_DN")
	)
	(segment
		(start 127.991616 -219.547694)
		(end 127.991616 -219.490544)
		(width 0.0889)
		(layer "B.Cu")
		(net "VSENSE_PVCCINFAON_CPU1_DN")
	)
	(segment
		(start 125.924564 -223.085914)
		(end 125.939296 -223.077278)
		(width 0.0889)
		(layer "B.Cu")
		(net "VSENSE_PVCCINFAON_CPU1_DN")
	)
	(segment
		(start 127.334264 -216.739978)
		(end 127.322326 -216.73312)
		(width 0.0889)
		(layer "B.Cu")
		(net "VSENSE_PVCCINFAON_CPU1_DN")
	)
	(segment
		(start 127.800608 -214.949278)
		(end 127.802386 -214.948262)
		(width 0.0889)
		(layer "B.Cu")
		(net "VSENSE_PVCCINFAON_CPU1_DN")
	)
	(segment
		(start 104.99598 -176.885092)
		(end 92.468954 -176.885092)
		(width 0.254)
		(layer "B.Cu")
		(net "VSENSE_PVCCINFAON_CPU1_DN")
	)
	(segment
		(start 127.521716 -215.414606)
		(end 127.52324 -215.375236)
		(width 0.0889)
		(layer "B.Cu")
		(net "VSENSE_PVCCINFAON_CPU1_DN")
	)
	(segment
		(start 116.526564 -223.085914)
		(end 116.541296 -223.077278)
		(width 0.0889)
		(layer "B.Cu")
		(net "VSENSE_PVCCINFAON_CPU1_DN")
	)
	(segment
		(start 127.324358 -215.76665)
		(end 127.328676 -215.76411)
		(width 0.0889)
		(layer "B.Cu")
		(net "VSENSE_PVCCINFAON_CPU1_DN")
	)
	(segment
		(start 128.274826 -218.368372)
		(end 128.27381 -218.367864)
		(width 0.0889)
		(layer "B.Cu")
		(net "VSENSE_PVCCINFAON_CPU1_DN")
	)
	(segment
		(start 127.426466 -213.075774)
		(end 127.426466 -212.903562)
		(width 0.0889)
		(layer "B.Cu")
		(net "VSENSE_PVCCINFAON_CPU1_DN")
	)
	(segment
		(start 127.813054 -217.559128)
		(end 127.804164 -217.554048)
		(width 0.0889)
		(layer "B.Cu")
		(net "VSENSE_PVCCINFAON_CPU1_DN")
	)
	(segment
		(start 118.406164 -223.085914)
		(end 118.420896 -223.077278)
		(width 0.0889)
		(layer "B.Cu")
		(net "VSENSE_PVCCINFAON_CPU1_DN")
	)
	(segment
		(start 128.2827 -218.372944)
		(end 128.274826 -218.368372)
		(width 0.0889)
		(layer "B.Cu")
		(net "VSENSE_PVCCINFAON_CPU1_DN")
	)
	(segment
		(start 127.33401 -222.272098)
		(end 127.3429 -222.267018)
		(width 0.0889)
		(layer "B.Cu")
		(net "VSENSE_PVCCINFAON_CPU1_DN")
	)
	(segment
		(start 127.521716 -213.171024)
		(end 127.426466 -213.075774)
		(width 0.0889)
		(layer "B.Cu")
		(net "VSENSE_PVCCINFAON_CPU1_DN")
	)
	(segment
		(start 127.32385 -215.766904)
		(end 127.324358 -215.76665)
		(width 0.0889)
		(layer "B.Cu")
		(net "VSENSE_PVCCINFAON_CPU1_DN")
	)
	(segment
		(start 127.805688 -219.829634)
		(end 127.842518 -219.808044)
		(width 0.0889)
		(layer "B.Cu")
		(net "VSENSE_PVCCINFAON_CPU1_DN")
	)
	(segment
		(start 127.051816 -216.236296)
		(end 127.051816 -216.235026)
		(width 0.0889)
		(layer "B.Cu")
		(net "VSENSE_PVCCINFAON_CPU1_DN")
	)
	(segment
		(start 127.521462 -215.432386)
		(end 127.521462 -215.428322)
		(width 0.0889)
		(layer "B.Cu")
		(net "VSENSE_PVCCINFAON_CPU1_DN")
	)
	(segment
		(start 127.991108 -214.640414)
		(end 127.991108 -214.461344)
		(width 0.0889)
		(layer "B.Cu")
		(net "VSENSE_PVCCINFAON_CPU1_DN")
	)
	(segment
		(start 127.426466 -212.903562)
		(end 127.426466 -199.315578)
		(width 0.254)
		(layer "B.Cu")
		(net "VSENSE_PVCCINFAON_CPU1_DN")
	)
	(segment
		(start 127.521716 -213.930484)
		(end 127.521716 -213.171024)
		(width 0.0889)
		(layer "B.Cu")
		(net "VSENSE_PVCCINFAON_CPU1_DN")
	)
	(segment
		(start 127.426466 -199.315578)
		(end 104.99598 -176.885092)
		(width 0.254)
		(layer "B.Cu")
		(net "VSENSE_PVCCINFAON_CPU1_DN")
	)
	(segment
		(start 127.804164 -219.830396)
		(end 127.805688 -219.829634)
		(width 0.0889)
		(layer "B.Cu")
		(net "VSENSE_PVCCINFAON_CPU1_DN")
	)
	(segment
		(start 127.793496 -221.464124)
		(end 127.874268 -221.417388)
		(width 0.0889)
		(layer "B.Cu")
		(net "VSENSE_PVCCINFAON_CPU1_DN")
	)
	(segment
		(start 128.27381 -219.01658)
		(end 128.2827 -219.0115)
		(width 0.0889)
		(layer "B.Cu")
		(net "VSENSE_PVCCINFAON_CPU1_DN")
	)
	(segment
		(start 127.757936 -214.975186)
		(end 127.800608 -214.949278)
		(width 0.0889)
		(layer "B.Cu")
		(net "VSENSE_PVCCINFAON_CPU1_DN")
	)
	(segment
		(start 115.964716 -222.722186)
		(end 115.964716 -222.761556)
		(width 0.0889)
		(layer "B.Cu")
		(net "VSENSE_PVCCINFAON_CPU1_DN")
	)
	(segment
		(start 127.991616 -221.213172)
		(end 127.991616 -221.124526)
		(width 0.0889)
		(layer "B.Cu")
		(net "VSENSE_PVCCINFAON_CPU1_DN")
	)
	(segment
		(start 122.165364 -223.085914)
		(end 122.180096 -223.077278)
		(width 0.0889)
		(layer "B.Cu")
		(net "VSENSE_PVCCINFAON_CPU1_DN")
	)
	(segment
		(start 127.991616 -217.8939)
		(end 127.991616 -217.878406)
		(width 0.0889)
		(layer "B.Cu")
		(net "VSENSE_PVCCINFAON_CPU1_DN")
	)
	(segment
		(start 127.521716 -215.415114)
		(end 127.521716 -215.414606)
		(width 0.0889)
		(layer "B.Cu")
		(net "VSENSE_PVCCINFAON_CPU1_DN")
	)
	(segment
		(start 127.757936 -219.85732)
		(end 127.804164 -219.830396)
		(width 0.0889)
		(layer "B.Cu")
		(net "VSENSE_PVCCINFAON_CPU1_DN")
	)
	(segment
		(start 126.864364 -223.085914)
		(end 126.873254 -223.080834)
		(width 0.0889)
		(layer "B.Cu")
		(net "VSENSE_PVCCINFAON_CPU1_DN")
	)
	(segment
		(start 115.488466 -222.143066)
		(end 115.675156 -222.267526)
		(width 0.0889)
		(layer "B.Cu")
		(net "VSENSE_PVCCINFAON_CPU1_DN")
	)
	(arc
		(start 127.804164 -220.809566)
		(mid 127.600683 -220.608762)
		(end 127.521462 -220.334078)
		(width 0.0889)
		(layer "B.Cu")
		(net "VSENSE_PVCCINFAON_CPU1_DN")
	)
	(arc
		(start 124.059696 -223.077278)
		(mid 124.336137 -223.010112)
		(end 124.610368 -223.085914)
		(width 0.0889)
		(layer "B.Cu")
		(net "VSENSE_PVCCINFAON_CPU1_DN")
	)
	(arc
		(start 127.991616 -221.124526)
		(mid 127.94172 -220.946879)
		(end 127.813054 -220.814646)
		(width 0.0889)
		(layer "B.Cu")
		(net "VSENSE_PVCCINFAON_CPU1_DN")
	)
	(arc
		(start 117.466364 -223.085914)
		(mid 117.749066 -223.010172)
		(end 118.031768 -223.085914)
		(width 0.0889)
		(layer "B.Cu")
		(net "VSENSE_PVCCINFAON_CPU1_DN")
	)
	(arc
		(start 121.790968 -223.085914)
		(mid 121.978166 -223.136057)
		(end 122.165364 -223.085914)
		(width 0.0889)
		(layer "B.Cu")
		(net "VSENSE_PVCCINFAON_CPU1_DN")
	)
	(arc
		(start 127.521462 -221.94774)
		(mid 127.594083 -221.670275)
		(end 127.793496 -221.464124)
		(width 0.0889)
		(layer "B.Cu")
		(net "VSENSE_PVCCINFAON_CPU1_DN")
	)
	(arc
		(start 127.80391 -214.947246)
		(mid 127.936648 -214.817711)
		(end 127.991108 -214.640414)
		(width 0.0889)
		(layer "B.Cu")
		(net "VSENSE_PVCCINFAON_CPU1_DN")
	)
	(arc
		(start 128.2827 -219.0115)
		(mid 128.461176 -218.692222)
		(end 128.2827 -218.372944)
		(width 0.0889)
		(layer "B.Cu")
		(net "VSENSE_PVCCINFAON_CPU1_DN")
	)
	(arc
		(start 125.939296 -223.077278)
		(mid 126.215737 -223.010112)
		(end 126.489968 -223.085914)
		(width 0.0889)
		(layer "B.Cu")
		(net "VSENSE_PVCCINFAON_CPU1_DN")
	)
	(arc
		(start 125.550168 -223.085914)
		(mid 125.737366 -223.136057)
		(end 125.924564 -223.085914)
		(width 0.0889)
		(layer "B.Cu")
		(net "VSENSE_PVCCINFAON_CPU1_DN")
	)
	(arc
		(start 116.541296 -223.077278)
		(mid 116.817737 -223.010112)
		(end 117.091968 -223.085914)
		(width 0.0889)
		(layer "B.Cu")
		(net "VSENSE_PVCCINFAON_CPU1_DN")
	)
	(arc
		(start 117.091968 -223.085914)
		(mid 117.279166 -223.136057)
		(end 117.466364 -223.085914)
		(width 0.0889)
		(layer "B.Cu")
		(net "VSENSE_PVCCINFAON_CPU1_DN")
	)
	(arc
		(start 127.051816 -216.235026)
		(mid 127.052194 -216.222956)
		(end 127.052832 -216.210896)
		(width 0.0889)
		(layer "B.Cu")
		(net "VSENSE_PVCCINFAON_CPU1_DN")
	)
	(arc
		(start 127.051816 -216.261188)
		(mid 127.051679 -216.248742)
		(end 127.051816 -216.236296)
		(width 0.0889)
		(layer "B.Cu")
		(net "VSENSE_PVCCINFAON_CPU1_DN")
	)
	(arc
		(start 115.721384 -222.294958)
		(mid 115.899501 -222.476407)
		(end 115.964716 -222.722186)
		(width 0.0889)
		(layer "B.Cu")
		(net "VSENSE_PVCCINFAON_CPU1_DN")
	)
	(arc
		(start 127.051816 -222.746062)
		(mid 127.131186 -222.472328)
		(end 127.33401 -222.272098)
		(width 0.0889)
		(layer "B.Cu")
		(net "VSENSE_PVCCINFAON_CPU1_DN")
	)
	(arc
		(start 127.806958 -214.261954)
		(mid 127.632995 -214.12319)
		(end 127.521716 -213.930484)
		(width 0.0889)
		(layer "B.Cu")
		(net "VSENSE_PVCCINFAON_CPU1_DN")
	)
	(arc
		(start 128.27381 -218.367864)
		(mid 128.070987 -218.167633)
		(end 127.991616 -217.8939)
		(width 0.0889)
		(layer "B.Cu")
		(net "VSENSE_PVCCINFAON_CPU1_DN")
	)
	(arc
		(start 118.031768 -223.085914)
		(mid 118.218966 -223.136057)
		(end 118.406164 -223.085914)
		(width 0.0889)
		(layer "B.Cu")
		(net "VSENSE_PVCCINFAON_CPU1_DN")
	)
	(arc
		(start 118.971568 -223.085914)
		(mid 119.158766 -223.136057)
		(end 119.345964 -223.085914)
		(width 0.0889)
		(layer "B.Cu")
		(net "VSENSE_PVCCINFAON_CPU1_DN")
	)
	(arc
		(start 121.225564 -223.085914)
		(mid 121.508266 -223.010172)
		(end 121.790968 -223.085914)
		(width 0.0889)
		(layer "B.Cu")
		(net "VSENSE_PVCCINFAON_CPU1_DN")
	)
	(arc
		(start 122.730768 -223.085914)
		(mid 122.917966 -223.136057)
		(end 123.105164 -223.085914)
		(width 0.0889)
		(layer "B.Cu")
		(net "VSENSE_PVCCINFAON_CPU1_DN")
	)
	(arc
		(start 120.300496 -223.077278)
		(mid 120.576937 -223.010112)
		(end 120.851168 -223.085914)
		(width 0.0889)
		(layer "B.Cu")
		(net "VSENSE_PVCCINFAON_CPU1_DN")
	)
	(arc
		(start 127.991616 -219.490544)
		(mid 128.070986 -219.21681)
		(end 128.27381 -219.01658)
		(width 0.0889)
		(layer "B.Cu")
		(net "VSENSE_PVCCINFAON_CPU1_DN")
	)
	(arc
		(start 118.420896 -223.077278)
		(mid 118.697337 -223.010112)
		(end 118.971568 -223.085914)
		(width 0.0889)
		(layer "B.Cu")
		(net "VSENSE_PVCCINFAON_CPU1_DN")
	)
	(arc
		(start 126.489968 -223.085914)
		(mid 126.677166 -223.136057)
		(end 126.864364 -223.085914)
		(width 0.0889)
		(layer "B.Cu")
		(net "VSENSE_PVCCINFAON_CPU1_DN")
	)
	(arc
		(start 127.328676 -215.76411)
		(mid 127.467505 -215.622911)
		(end 127.521462 -215.432386)
		(width 0.0889)
		(layer "B.Cu")
		(net "VSENSE_PVCCINFAON_CPU1_DN")
	)
	(arc
		(start 114.929666 -221.94774)
		(mid 115.146929 -221.976687)
		(end 115.34902 -222.061532)
		(width 0.0889)
		(layer "B.Cu")
		(net "VSENSE_PVCCINFAON_CPU1_DN")
	)
	(arc
		(start 127.521462 -215.428322)
		(mid 127.521551 -215.421717)
		(end 127.521716 -215.415114)
		(width 0.0889)
		(layer "B.Cu")
		(net "VSENSE_PVCCINFAON_CPU1_DN")
	)
	(arc
		(start 126.873254 -223.080834)
		(mid 127.004168 -222.944474)
		(end 127.051816 -222.761556)
		(width 0.0889)
		(layer "B.Cu")
		(net "VSENSE_PVCCINFAON_CPU1_DN")
	)
	(arc
		(start 123.105164 -223.085914)
		(mid 123.387866 -223.010172)
		(end 123.670568 -223.085914)
		(width 0.0889)
		(layer "B.Cu")
		(net "VSENSE_PVCCINFAON_CPU1_DN")
	)
	(arc
		(start 115.964716 -222.761556)
		(mid 116.15207 -223.085775)
		(end 116.526564 -223.085914)
		(width 0.0889)
		(layer "B.Cu")
		(net "VSENSE_PVCCINFAON_CPU1_DN")
	)
	(arc
		(start 120.851168 -223.085914)
		(mid 121.038366 -223.136057)
		(end 121.225564 -223.085914)
		(width 0.0889)
		(layer "B.Cu")
		(net "VSENSE_PVCCINFAON_CPU1_DN")
	)
	(arc
		(start 127.842518 -219.808044)
		(mid 127.951739 -219.697717)
		(end 127.991616 -219.547694)
		(width 0.0889)
		(layer "B.Cu")
		(net "VSENSE_PVCCINFAON_CPU1_DN")
	)
	(arc
		(start 127.804164 -217.554048)
		(mid 127.600683 -217.353244)
		(end 127.521462 -217.07856)
		(width 0.0889)
		(layer "B.Cu")
		(net "VSENSE_PVCCINFAON_CPU1_DN")
	)
	(arc
		(start 119.345964 -223.085914)
		(mid 119.628666 -223.010172)
		(end 119.911368 -223.085914)
		(width 0.0889)
		(layer "B.Cu")
		(net "VSENSE_PVCCINFAON_CPU1_DN")
	)
	(arc
		(start 127.3429 -222.267018)
		(mid 127.473814 -222.130658)
		(end 127.521462 -221.94774)
		(width 0.0889)
		(layer "B.Cu")
		(net "VSENSE_PVCCINFAON_CPU1_DN")
	)
	(arc
		(start 127.052832 -216.210896)
		(mid 127.134258 -215.955885)
		(end 127.32385 -215.766904)
		(width 0.0889)
		(layer "B.Cu")
		(net "VSENSE_PVCCINFAON_CPU1_DN")
	)
	(arc
		(start 119.911368 -223.085914)
		(mid 120.098566 -223.136057)
		(end 120.285764 -223.085914)
		(width 0.0889)
		(layer "B.Cu")
		(net "VSENSE_PVCCINFAON_CPU1_DN")
	)
	(arc
		(start 124.984764 -223.085914)
		(mid 125.267466 -223.010172)
		(end 125.550168 -223.085914)
		(width 0.0889)
		(layer "B.Cu")
		(net "VSENSE_PVCCINFAON_CPU1_DN")
	)
	(arc
		(start 127.322326 -216.73312)
		(mid 127.126283 -216.531997)
		(end 127.051816 -216.261188)
		(width 0.0889)
		(layer "B.Cu")
		(net "VSENSE_PVCCINFAON_CPU1_DN")
	)
	(arc
		(start 122.180096 -223.077278)
		(mid 122.456537 -223.010112)
		(end 122.730768 -223.085914)
		(width 0.0889)
		(layer "B.Cu")
		(net "VSENSE_PVCCINFAON_CPU1_DN")
	)
	(arc
		(start 127.991108 -214.461344)
		(mid 127.916103 -214.345885)
		(end 127.806958 -214.261954)
		(width 0.0889)
		(layer "B.Cu")
		(net "VSENSE_PVCCINFAON_CPU1_DN")
	)
	(arc
		(start 127.52324 -215.375236)
		(mid 127.590439 -215.145788)
		(end 127.757936 -214.975186)
		(width 0.0889)
		(layer "B.Cu")
		(net "VSENSE_PVCCINFAON_CPU1_DN")
	)
	(arc
		(start 127.874268 -221.417388)
		(mid 127.960153 -221.330924)
		(end 127.991616 -221.213172)
		(width 0.0889)
		(layer "B.Cu")
		(net "VSENSE_PVCCINFAON_CPU1_DN")
	)
	(arc
		(start 123.670568 -223.085914)
		(mid 123.857766 -223.136057)
		(end 124.044964 -223.085914)
		(width 0.0889)
		(layer "B.Cu")
		(net "VSENSE_PVCCINFAON_CPU1_DN")
	)
	(arc
		(start 124.610368 -223.085914)
		(mid 124.797566 -223.136057)
		(end 124.984764 -223.085914)
		(width 0.0889)
		(layer "B.Cu")
		(net "VSENSE_PVCCINFAON_CPU1_DN")
	)
	(arc
		(start 127.991616 -217.878406)
		(mid 127.943937 -217.695506)
		(end 127.813054 -217.559128)
		(width 0.0889)
		(layer "B.Cu")
		(net "VSENSE_PVCCINFAON_CPU1_DN")
	)
	(arc
		(start 127.521462 -220.269308)
		(mid 127.584791 -220.031806)
		(end 127.757936 -219.85732)
		(width 0.0889)
		(layer "B.Cu")
		(net "VSENSE_PVCCINFAON_CPU1_DN")
	)
	(arc
		(start 127.521462 -217.0557)
		(mid 127.469192 -216.873335)
		(end 127.334264 -216.739978)
		(width 0.0889)
		(layer "B.Cu")
		(net "VSENSE_PVCCINFAON_CPU1_DN")
	)
	(segment
		(start 34.88182 -136.975088)
		(end 34.597594 -136.690862)
		(width 0.254)
		(layer "In11.Cu")
		(net "VSENSE_PVCCINFAON_CPU1_DN")
	)
	(segment
		(start 93.463364 -176.40808)
		(end 92.986352 -176.885092)
		(width 0.254)
		(layer "In11.Cu")
		(net "VSENSE_PVCCINFAON_CPU1_DN")
	)
	(segment
		(start 93.463364 -172.668692)
		(end 93.463364 -176.40808)
		(width 0.254)
		(layer "In11.Cu")
		(net "VSENSE_PVCCINFAON_CPU1_DN")
	)
	(segment
		(start 92.986352 -176.885092)
		(end 92.468954 -176.885092)
		(width 0.254)
		(layer "In11.Cu")
		(net "VSENSE_PVCCINFAON_CPU1_DN")
	)
	(segment
		(start 73.85812 -144.385538)
		(end 73.56348 -144.680178)
		(width 0.254)
		(layer "In11.Cu")
		(net "VSENSE_PVCCINFAON_CPU1_DN")
	)
	(segment
		(start 34.597594 -136.690862)
		(end 33.954974 -136.690862)
		(width 0.254)
		(layer "In11.Cu")
		(net "VSENSE_PVCCINFAON_CPU1_DN")
	)
	(segment
		(start 75.844908 -144.385538)
		(end 76.32192 -143.908526)
		(width 0.254)
		(layer "In11.Cu")
		(net "VSENSE_PVCCINFAON_CPU1_DN")
	)
	(segment
		(start 79.71536 -158.920688)
		(end 93.463364 -172.668692)
		(width 0.254)
		(layer "In11.Cu")
		(net "VSENSE_PVCCINFAON_CPU1_DN")
	)
	(segment
		(start 74.534268 -146.776948)
		(end 75.448668 -146.776948)
		(width 0.254)
		(layer "In11.Cu")
		(net "VSENSE_PVCCINFAON_CPU1_DN")
	)
	(segment
		(start 73.56348 -144.680178)
		(end 73.56348 -145.80616)
		(width 0.254)
		(layer "In11.Cu")
		(net "VSENSE_PVCCINFAON_CPU1_DN")
	)
	(segment
		(start 74.86777 -144.385538)
		(end 75.844908 -144.385538)
		(width 0.254)
		(layer "In11.Cu")
		(net "VSENSE_PVCCINFAON_CPU1_DN")
	)
	(segment
		(start 35.870896 -140.307568)
		(end 34.88182 -139.318492)
		(width 0.254)
		(layer "In11.Cu")
		(net "VSENSE_PVCCINFAON_CPU1_DN")
	)
	(segment
		(start 77.19568 -148.52396)
		(end 77.19568 -150.713948)
		(width 0.254)
		(layer "In11.Cu")
		(net "VSENSE_PVCCINFAON_CPU1_DN")
	)
	(segment
		(start 73.56348 -145.80616)
		(end 74.534268 -146.776948)
		(width 0.254)
		(layer "In11.Cu")
		(net "VSENSE_PVCCINFAON_CPU1_DN")
	)
	(segment
		(start 92.468954 -176.885092)
		(end 92.227654 -177.126392)
		(width 0.254)
		(layer "In11.Cu")
		(net "VSENSE_PVCCINFAON_CPU1_DN")
	)
	(segment
		(start 33.954974 -136.690862)
		(end 33.6804 -136.416288)
		(width 0.254)
		(layer "In11.Cu")
		(net "VSENSE_PVCCINFAON_CPU1_DN")
	)
	(segment
		(start 76.32192 -143.09598)
		(end 73.533508 -140.307568)
		(width 0.254)
		(layer "In11.Cu")
		(net "VSENSE_PVCCINFAON_CPU1_DN")
	)
	(segment
		(start 76.73848 -155.38958)
		(end 79.71536 -158.36646)
		(width 0.254)
		(layer "In11.Cu")
		(net "VSENSE_PVCCINFAON_CPU1_DN")
	)
	(segment
		(start 74.38517 -144.385538)
		(end 73.85812 -144.385538)
		(width 0.254)
		(layer "In11.Cu")
		(net "VSENSE_PVCCINFAON_CPU1_DN")
	)
	(segment
		(start 74.62647 -144.626838)
		(end 74.38517 -144.385538)
		(width 0.254)
		(layer "In11.Cu")
		(net "VSENSE_PVCCINFAON_CPU1_DN")
	)
	(segment
		(start 34.88182 -139.318492)
		(end 34.88182 -136.975088)
		(width 0.254)
		(layer "In11.Cu")
		(net "VSENSE_PVCCINFAON_CPU1_DN")
	)
	(segment
		(start 79.71536 -158.36646)
		(end 79.71536 -158.920688)
		(width 0.254)
		(layer "In11.Cu")
		(net "VSENSE_PVCCINFAON_CPU1_DN")
	)
	(segment
		(start 73.533508 -140.307568)
		(end 35.870896 -140.307568)
		(width 0.254)
		(layer "In11.Cu")
		(net "VSENSE_PVCCINFAON_CPU1_DN")
	)
	(segment
		(start 76.73848 -151.171148)
		(end 76.73848 -155.38958)
		(width 0.254)
		(layer "In11.Cu")
		(net "VSENSE_PVCCINFAON_CPU1_DN")
	)
	(segment
		(start 74.62647 -144.626838)
		(end 74.86777 -144.385538)
		(width 0.254)
		(layer "In11.Cu")
		(net "VSENSE_PVCCINFAON_CPU1_DN")
	)
	(segment
		(start 77.19568 -150.713948)
		(end 76.73848 -151.171148)
		(width 0.254)
		(layer "In11.Cu")
		(net "VSENSE_PVCCINFAON_CPU1_DN")
	)
	(segment
		(start 75.448668 -146.776948)
		(end 77.19568 -148.52396)
		(width 0.254)
		(layer "In11.Cu")
		(net "VSENSE_PVCCINFAON_CPU1_DN")
	)
	(segment
		(start 76.32192 -143.908526)
		(end 76.32192 -143.09598)
		(width 0.254)
		(layer "In11.Cu")
		(net "VSENSE_PVCCINFAON_CPU1_DN")
	)
	(segment
		(start 427.82363 -143.540988)
		(end 428.8917 -143.540988)
		(width 0.254)
		(layer "F.Cu")
		(net "VSENSE_PVCCINFAON_CPU0_DP")
	)
	(segment
		(start 396.6845 -186.58713)
		(end 396.969234 -186.871864)
		(width 0.254)
		(layer "F.Cu")
		(net "VSENSE_PVCCINFAON_CPU0_DP")
	)
	(segment
		(start 394.649198 -187.31357)
		(end 395.375638 -186.58713)
		(width 0.254)
		(layer "F.Cu")
		(net "VSENSE_PVCCINFAON_CPU0_DP")
	)
	(segment
		(start 428.8917 -143.540988)
		(end 429.267112 -143.9164)
		(width 0.254)
		(layer "F.Cu")
		(net "VSENSE_PVCCINFAON_CPU0_DP")
	)
	(segment
		(start 360.990134 -221.947994)
		(end 360.98988 -221.94774)
		(width 0.12954)
		(layer "F.Cu")
		(net "VSENSE_PVCCINFAON_CPU0_DP")
	)
	(segment
		(start 395.375638 -186.58713)
		(end 396.6845 -186.58713)
		(width 0.254)
		(layer "F.Cu")
		(net "VSENSE_PVCCINFAON_CPU0_DP")
	)
	(segment
		(start 394.649198 -194.231006)
		(end 394.649198 -187.31357)
		(width 0.254)
		(layer "F.Cu")
		(net "VSENSE_PVCCINFAON_CPU0_DP")
	)
	(segment
		(start 396.969234 -186.871864)
		(end 397.235934 -186.605164)
		(width 0.254)
		(layer "F.Cu")
		(net "VSENSE_PVCCINFAON_CPU0_DP")
	)
	(segment
		(start 385.29006 -202.75931)
		(end 386.120894 -202.75931)
		(width 0.254)
		(layer "F.Cu")
		(net "VSENSE_PVCCINFAON_CPU0_DP")
	)
	(segment
		(start 397.473424 -186.605164)
		(end 397.733774 -186.865514)
		(width 0.254)
		(layer "F.Cu")
		(net "VSENSE_PVCCINFAON_CPU0_DP")
	)
	(segment
		(start 397.235934 -186.605164)
		(end 397.473424 -186.605164)
		(width 0.254)
		(layer "F.Cu")
		(net "VSENSE_PVCCINFAON_CPU0_DP")
	)
	(segment
		(start 385.04876 -203.00061)
		(end 385.29006 -202.75931)
		(width 0.254)
		(layer "F.Cu")
		(net "VSENSE_PVCCINFAON_CPU0_DP")
	)
	(segment
		(start 360.990134 -222.48368)
		(end 360.990134 -221.947994)
		(width 0.12954)
		(layer "F.Cu")
		(net "VSENSE_PVCCINFAON_CPU0_DP")
	)
	(segment
		(start 427.575726 -143.788892)
		(end 427.82363 -143.540988)
		(width 0.254)
		(layer "F.Cu")
		(net "VSENSE_PVCCINFAON_CPU0_DP")
	)
	(segment
		(start 386.120894 -202.75931)
		(end 394.649198 -194.231006)
		(width 0.254)
		(layer "F.Cu")
		(net "VSENSE_PVCCINFAON_CPU0_DP")
	)
	(via
		(at 360.98988 -221.94774)
		(size 0.4572)
		(drill 0.2032)
		(layers "F.Cu" "B.Cu")
		(net "VSENSE_PVCCINFAON_CPU0_DP")
	)
	(via
		(at 385.04876 -203.00061)
		(size 0.508)
		(drill 0.254)
		(layers "F.Cu" "B.Cu")
		(net "VSENSE_PVCCINFAON_CPU0_DP")
	)
	(via
		(at 427.575726 -143.788892)
		(size 0.508)
		(drill 0.254)
		(layers "F.Cu" "B.Cu")
		(net "VSENSE_PVCCINFAON_CPU0_DP")
	)
	(via
		(at 396.969234 -186.871864)
		(size 0.508)
		(drill 0.254)
		(layers "F.Cu" "B.Cu")
		(net "VSENSE_PVCCINFAON_CPU0_DP")
	)
	(segment
		(start 375.65584 -215.329262)
		(end 375.652284 -215.421972)
		(width 0.0889)
		(layer "B.Cu")
		(net "VSENSE_PVCCINFAON_CPU0_DP")
	)
	(segment
		(start 375.747534 -212.903562)
		(end 375.747534 -213.085934)
		(width 0.0889)
		(layer "B.Cu")
		(net "VSENSE_PVCCINFAON_CPU0_DP")
	)
	(segment
		(start 369.180364 -222.445834)
		(end 369.165632 -222.437198)
		(width 0.0889)
		(layer "B.Cu")
		(net "VSENSE_PVCCINFAON_CPU0_DP")
	)
	(segment
		(start 376.300746 -218.197684)
		(end 376.309636 -218.202764)
		(width 0.0889)
		(layer "B.Cu")
		(net "VSENSE_PVCCINFAON_CPU0_DP")
	)
	(segment
		(start 376.121676 -214.424768)
		(end 376.121676 -214.644732)
		(width 0.0889)
		(layer "B.Cu")
		(net "VSENSE_PVCCINFAON_CPU0_DP")
	)
	(segment
		(start 361.302554 -221.94774)
		(end 360.98988 -221.94774)
		(width 0.0889)
		(layer "B.Cu")
		(net "VSENSE_PVCCINFAON_CPU0_DP")
	)
	(segment
		(start 371.059964 -222.445834)
		(end 371.045232 -222.437198)
		(width 0.0889)
		(layer "B.Cu")
		(net "VSENSE_PVCCINFAON_CPU0_DP")
	)
	(segment
		(start 384.103372 -202.75931)
		(end 382.69418 -201.350118)
		(width 0.254)
		(layer "B.Cu")
		(net "VSENSE_PVCCINFAON_CPU0_DP")
	)
	(segment
		(start 375.758964 -219.190316)
		(end 375.744232 -219.18168)
		(width 0.0889)
		(layer "B.Cu")
		(net "VSENSE_PVCCINFAON_CPU0_DP")
	)
	(segment
		(start 361.647232 -222.437198)
		(end 361.63504 -222.430086)
		(width 0.0889)
		(layer "B.Cu")
		(net "VSENSE_PVCCINFAON_CPU0_DP")
	)
	(segment
		(start 370.120164 -222.445834)
		(end 370.105432 -222.437198)
		(width 0.0889)
		(layer "B.Cu")
		(net "VSENSE_PVCCINFAON_CPU0_DP")
	)
	(segment
		(start 375.652284 -217.05443)
		(end 375.652284 -217.072972)
		(width 0.0889)
		(layer "B.Cu")
		(net "VSENSE_PVCCINFAON_CPU0_DP")
	)
	(segment
		(start 376.122184 -217.864182)
		(end 376.122184 -217.878406)
		(width 0.0889)
		(layer "B.Cu")
		(net "VSENSE_PVCCINFAON_CPU0_DP")
	)
	(segment
		(start 372.83263 -221.932246)
		(end 372.83263 -221.963234)
		(width 0.0889)
		(layer "B.Cu")
		(net "VSENSE_PVCCINFAON_CPU0_DP")
	)
	(segment
		(start 371.893084 -220.311218)
		(end 371.893084 -220.32849)
		(width 0.0889)
		(layer "B.Cu")
		(net "VSENSE_PVCCINFAON_CPU0_DP")
	)
	(segment
		(start 375.65203 -215.435688)
		(end 375.65203 -215.436958)
		(width 0.0889)
		(layer "B.Cu")
		(net "VSENSE_PVCCINFAON_CPU0_DP")
	)
	(segment
		(start 361.36834 -222.013526)
		(end 361.302554 -221.94774)
		(width 0.0889)
		(layer "B.Cu")
		(net "VSENSE_PVCCINFAON_CPU0_DP")
	)
	(segment
		(start 382.69418 -201.350118)
		(end 379.595634 -201.350118)
		(width 0.254)
		(layer "B.Cu")
		(net "VSENSE_PVCCINFAON_CPU0_DP")
	)
	(segment
		(start 375.747534 -213.085934)
		(end 375.652284 -213.181184)
		(width 0.0889)
		(layer "B.Cu")
		(net "VSENSE_PVCCINFAON_CPU0_DP")
	)
	(segment
		(start 379.595634 -201.350118)
		(end 375.747534 -205.198218)
		(width 0.254)
		(layer "B.Cu")
		(net "VSENSE_PVCCINFAON_CPU0_DP")
	)
	(segment
		(start 371.999764 -222.445834)
		(end 371.985032 -222.437198)
		(width 0.0889)
		(layer "B.Cu")
		(net "VSENSE_PVCCINFAON_CPU0_DP")
	)
	(segment
		(start 373.020336 -219.995496)
		(end 373.009922 -220.001592)
		(width 0.0889)
		(layer "B.Cu")
		(net "VSENSE_PVCCINFAON_CPU0_DP")
	)
	(segment
		(start 373.490236 -219.18168)
		(end 373.481346 -219.18676)
		(width 0.0889)
		(layer "B.Cu")
		(net "VSENSE_PVCCINFAON_CPU0_DP")
	)
	(segment
		(start 374.819164 -219.190316)
		(end 374.804432 -219.18168)
		(width 0.0889)
		(layer "B.Cu")
		(net "VSENSE_PVCCINFAON_CPU0_DP")
	)
	(segment
		(start 364.481364 -222.445834)
		(end 364.466632 -222.437198)
		(width 0.0889)
		(layer "B.Cu")
		(net "VSENSE_PVCCINFAON_CPU0_DP")
	)
	(segment
		(start 372.541546 -221.453202)
		(end 372.550436 -221.458282)
		(width 0.0889)
		(layer "B.Cu")
		(net "VSENSE_PVCCINFAON_CPU0_DP")
	)
	(segment
		(start 375.652284 -213.181184)
		(end 375.652284 -213.893908)
		(width 0.0889)
		(layer "B.Cu")
		(net "VSENSE_PVCCINFAON_CPU0_DP")
	)
	(segment
		(start 375.747534 -205.198218)
		(end 375.747534 -212.903562)
		(width 0.254)
		(layer "B.Cu")
		(net "VSENSE_PVCCINFAON_CPU0_DP")
	)
	(segment
		(start 366.360964 -222.445834)
		(end 366.346232 -222.437198)
		(width 0.0889)
		(layer "B.Cu")
		(net "VSENSE_PVCCINFAON_CPU0_DP")
	)
	(segment
		(start 376.59183 -218.676728)
		(end 376.59183 -218.707716)
		(width 0.0889)
		(layer "B.Cu")
		(net "VSENSE_PVCCINFAON_CPU0_DP")
	)
	(segment
		(start 375.839482 -215.112346)
		(end 375.751344 -215.16594)
		(width 0.0889)
		(layer "B.Cu")
		(net "VSENSE_PVCCINFAON_CPU0_DP")
	)
	(segment
		(start 363.541564 -222.445834)
		(end 363.526832 -222.437198)
		(width 0.0889)
		(layer "B.Cu")
		(net "VSENSE_PVCCINFAON_CPU0_DP")
	)
	(segment
		(start 385.04876 -203.00061)
		(end 384.80746 -202.75931)
		(width 0.254)
		(layer "B.Cu")
		(net "VSENSE_PVCCINFAON_CPU0_DP")
	)
	(segment
		(start 373.302784 -219.506038)
		(end 373.302784 -219.515944)
		(width 0.0889)
		(layer "B.Cu")
		(net "VSENSE_PVCCINFAON_CPU0_DP")
	)
	(segment
		(start 384.80746 -202.75931)
		(end 384.103372 -202.75931)
		(width 0.254)
		(layer "B.Cu")
		(net "VSENSE_PVCCINFAON_CPU0_DP")
	)
	(segment
		(start 365.421164 -222.445834)
		(end 365.406432 -222.437198)
		(width 0.0889)
		(layer "B.Cu")
		(net "VSENSE_PVCCINFAON_CPU0_DP")
	)
	(segment
		(start 368.240564 -222.445834)
		(end 368.225832 -222.437198)
		(width 0.0889)
		(layer "B.Cu")
		(net "VSENSE_PVCCINFAON_CPU0_DP")
	)
	(segment
		(start 373.879364 -219.190316)
		(end 373.864632 -219.18168)
		(width 0.0889)
		(layer "B.Cu")
		(net "VSENSE_PVCCINFAON_CPU0_DP")
	)
	(segment
		(start 372.362984 -221.1197)
		(end 372.362984 -221.133924)
		(width 0.0889)
		(layer "B.Cu")
		(net "VSENSE_PVCCINFAON_CPU0_DP")
	)
	(arc
		(start 371.610636 -222.437198)
		(mid 371.336437 -222.513033)
		(end 371.059964 -222.445834)
		(width 0.0889)
		(layer "B.Cu")
		(net "VSENSE_PVCCINFAON_CPU0_DP")
	)
	(arc
		(start 367.286032 -222.437198)
		(mid 367.098834 -222.387055)
		(end 366.911636 -222.437198)
		(width 0.0889)
		(layer "B.Cu")
		(net "VSENSE_PVCCINFAON_CPU0_DP")
	)
	(arc
		(start 368.791236 -222.437198)
		(mid 368.517037 -222.513033)
		(end 368.240564 -222.445834)
		(width 0.0889)
		(layer "B.Cu")
		(net "VSENSE_PVCCINFAON_CPU0_DP")
	)
	(arc
		(start 375.751344 -215.16594)
		(mid 375.68311 -215.235638)
		(end 375.65584 -215.329262)
		(width 0.0889)
		(layer "B.Cu")
		(net "VSENSE_PVCCINFAON_CPU0_DP")
	)
	(arc
		(start 371.893084 -220.32849)
		(mid 371.945354 -220.510855)
		(end 372.080282 -220.644212)
		(width 0.0889)
		(layer "B.Cu")
		(net "VSENSE_PVCCINFAON_CPU0_DP")
	)
	(arc
		(start 366.911636 -222.437198)
		(mid 366.637437 -222.513033)
		(end 366.360964 -222.445834)
		(width 0.0889)
		(layer "B.Cu")
		(net "VSENSE_PVCCINFAON_CPU0_DP")
	)
	(arc
		(start 370.670836 -222.437198)
		(mid 370.396637 -222.513033)
		(end 370.120164 -222.445834)
		(width 0.0889)
		(layer "B.Cu")
		(net "VSENSE_PVCCINFAON_CPU0_DP")
	)
	(arc
		(start 375.652284 -217.072972)
		(mid 375.704554 -217.255337)
		(end 375.839482 -217.388694)
		(width 0.0889)
		(layer "B.Cu")
		(net "VSENSE_PVCCINFAON_CPU0_DP")
	)
	(arc
		(start 375.369836 -219.18168)
		(mid 375.095637 -219.257515)
		(end 374.819164 -219.190316)
		(width 0.0889)
		(layer "B.Cu")
		(net "VSENSE_PVCCINFAON_CPU0_DP")
	)
	(arc
		(start 375.744232 -219.18168)
		(mid 375.557034 -219.131537)
		(end 375.369836 -219.18168)
		(width 0.0889)
		(layer "B.Cu")
		(net "VSENSE_PVCCINFAON_CPU0_DP")
	)
	(arc
		(start 373.009922 -220.001592)
		(mid 372.73149 -220.071438)
		(end 372.454678 -219.995496)
		(width 0.0889)
		(layer "B.Cu")
		(net "VSENSE_PVCCINFAON_CPU0_DP")
	)
	(arc
		(start 375.652284 -213.893908)
		(mid 375.727289 -214.009367)
		(end 375.836434 -214.093298)
		(width 0.0889)
		(layer "B.Cu")
		(net "VSENSE_PVCCINFAON_CPU0_DP")
	)
	(arc
		(start 375.836434 -214.093298)
		(mid 376.010397 -214.232062)
		(end 376.121676 -214.424768)
		(width 0.0889)
		(layer "B.Cu")
		(net "VSENSE_PVCCINFAON_CPU0_DP")
	)
	(arc
		(start 367.851436 -222.437198)
		(mid 367.568734 -222.512974)
		(end 367.286032 -222.437198)
		(width 0.0889)
		(layer "B.Cu")
		(net "VSENSE_PVCCINFAON_CPU0_DP")
	)
	(arc
		(start 364.466632 -222.437198)
		(mid 364.279434 -222.387055)
		(end 364.092236 -222.437198)
		(width 0.0889)
		(layer "B.Cu")
		(net "VSENSE_PVCCINFAON_CPU0_DP")
	)
	(arc
		(start 361.63504 -222.430086)
		(mid 361.453762 -222.252503)
		(end 361.36834 -222.013526)
		(width 0.0889)
		(layer "B.Cu")
		(net "VSENSE_PVCCINFAON_CPU0_DP")
	)
	(arc
		(start 375.369836 -215.926162)
		(mid 375.18266 -216.25063)
		(end 375.37009 -216.574878)
		(width 0.0889)
		(layer "B.Cu")
		(net "VSENSE_PVCCINFAON_CPU0_DP")
	)
	(arc
		(start 376.122184 -217.878406)
		(mid 376.169863 -218.061306)
		(end 376.300746 -218.197684)
		(width 0.0889)
		(layer "B.Cu")
		(net "VSENSE_PVCCINFAON_CPU0_DP")
	)
	(arc
		(start 372.362984 -221.133924)
		(mid 372.410663 -221.316824)
		(end 372.541546 -221.453202)
		(width 0.0889)
		(layer "B.Cu")
		(net "VSENSE_PVCCINFAON_CPU0_DP")
	)
	(arc
		(start 371.985032 -222.437198)
		(mid 371.797834 -222.387055)
		(end 371.610636 -222.437198)
		(width 0.0889)
		(layer "B.Cu")
		(net "VSENSE_PVCCINFAON_CPU0_DP")
	)
	(arc
		(start 375.37009 -216.574878)
		(mid 375.574336 -216.777513)
		(end 375.652284 -217.05443)
		(width 0.0889)
		(layer "B.Cu")
		(net "VSENSE_PVCCINFAON_CPU0_DP")
	)
	(arc
		(start 365.032036 -222.437198)
		(mid 364.757837 -222.513033)
		(end 364.481364 -222.445834)
		(width 0.0889)
		(layer "B.Cu")
		(net "VSENSE_PVCCINFAON_CPU0_DP")
	)
	(arc
		(start 362.212636 -222.437198)
		(mid 361.929934 -222.512974)
		(end 361.647232 -222.437198)
		(width 0.0889)
		(layer "B.Cu")
		(net "VSENSE_PVCCINFAON_CPU0_DP")
	)
	(arc
		(start 372.080282 -219.995496)
		(mid 371.945349 -220.12885)
		(end 371.893084 -220.311218)
		(width 0.0889)
		(layer "B.Cu")
		(net "VSENSE_PVCCINFAON_CPU0_DP")
	)
	(arc
		(start 373.302784 -219.515944)
		(mid 373.224673 -219.792893)
		(end 373.020336 -219.995496)
		(width 0.0889)
		(layer "B.Cu")
		(net "VSENSE_PVCCINFAON_CPU0_DP")
	)
	(arc
		(start 369.165632 -222.437198)
		(mid 368.978434 -222.387055)
		(end 368.791236 -222.437198)
		(width 0.0889)
		(layer "B.Cu")
		(net "VSENSE_PVCCINFAON_CPU0_DP")
	)
	(arc
		(start 375.652284 -215.421972)
		(mid 375.652095 -215.428829)
		(end 375.65203 -215.435688)
		(width 0.0889)
		(layer "B.Cu")
		(net "VSENSE_PVCCINFAON_CPU0_DP")
	)
	(arc
		(start 374.804432 -219.18168)
		(mid 374.617234 -219.131537)
		(end 374.430036 -219.18168)
		(width 0.0889)
		(layer "B.Cu")
		(net "VSENSE_PVCCINFAON_CPU0_DP")
	)
	(arc
		(start 365.406432 -222.437198)
		(mid 365.219234 -222.387055)
		(end 365.032036 -222.437198)
		(width 0.0889)
		(layer "B.Cu")
		(net "VSENSE_PVCCINFAON_CPU0_DP")
	)
	(arc
		(start 376.309636 -219.18168)
		(mid 376.035437 -219.257515)
		(end 375.758964 -219.190316)
		(width 0.0889)
		(layer "B.Cu")
		(net "VSENSE_PVCCINFAON_CPU0_DP")
	)
	(arc
		(start 372.080282 -220.644212)
		(mid 372.283763 -220.845016)
		(end 372.362984 -221.1197)
		(width 0.0889)
		(layer "B.Cu")
		(net "VSENSE_PVCCINFAON_CPU0_DP")
	)
	(arc
		(start 371.045232 -222.437198)
		(mid 370.858034 -222.387055)
		(end 370.670836 -222.437198)
		(width 0.0889)
		(layer "B.Cu")
		(net "VSENSE_PVCCINFAON_CPU0_DP")
	)
	(arc
		(start 372.550436 -221.458282)
		(mid 372.753259 -221.658513)
		(end 372.83263 -221.932246)
		(width 0.0889)
		(layer "B.Cu")
		(net "VSENSE_PVCCINFAON_CPU0_DP")
	)
	(arc
		(start 363.152436 -222.437198)
		(mid 362.869734 -222.512974)
		(end 362.587032 -222.437198)
		(width 0.0889)
		(layer "B.Cu")
		(net "VSENSE_PVCCINFAON_CPU0_DP")
	)
	(arc
		(start 376.309636 -218.202764)
		(mid 376.512459 -218.402995)
		(end 376.59183 -218.676728)
		(width 0.0889)
		(layer "B.Cu")
		(net "VSENSE_PVCCINFAON_CPU0_DP")
	)
	(arc
		(start 372.454678 -219.995496)
		(mid 372.26748 -219.945353)
		(end 372.080282 -219.995496)
		(width 0.0889)
		(layer "B.Cu")
		(net "VSENSE_PVCCINFAON_CPU0_DP")
	)
	(arc
		(start 373.864632 -219.18168)
		(mid 373.677434 -219.131537)
		(end 373.490236 -219.18168)
		(width 0.0889)
		(layer "B.Cu")
		(net "VSENSE_PVCCINFAON_CPU0_DP")
	)
	(arc
		(start 376.59183 -218.707716)
		(mid 376.51246 -218.98145)
		(end 376.309636 -219.18168)
		(width 0.0889)
		(layer "B.Cu")
		(net "VSENSE_PVCCINFAON_CPU0_DP")
	)
	(arc
		(start 365.971836 -222.437198)
		(mid 365.697637 -222.513033)
		(end 365.421164 -222.445834)
		(width 0.0889)
		(layer "B.Cu")
		(net "VSENSE_PVCCINFAON_CPU0_DP")
	)
	(arc
		(start 364.092236 -222.437198)
		(mid 363.818037 -222.513033)
		(end 363.541564 -222.445834)
		(width 0.0889)
		(layer "B.Cu")
		(net "VSENSE_PVCCINFAON_CPU0_DP")
	)
	(arc
		(start 374.430036 -219.18168)
		(mid 374.155837 -219.257515)
		(end 373.879364 -219.190316)
		(width 0.0889)
		(layer "B.Cu")
		(net "VSENSE_PVCCINFAON_CPU0_DP")
	)
	(arc
		(start 372.550436 -222.437198)
		(mid 372.276237 -222.513033)
		(end 371.999764 -222.445834)
		(width 0.0889)
		(layer "B.Cu")
		(net "VSENSE_PVCCINFAON_CPU0_DP")
	)
	(arc
		(start 370.105432 -222.437198)
		(mid 369.918234 -222.387055)
		(end 369.731036 -222.437198)
		(width 0.0889)
		(layer "B.Cu")
		(net "VSENSE_PVCCINFAON_CPU0_DP")
	)
	(arc
		(start 375.839482 -217.388694)
		(mid 376.042963 -217.589498)
		(end 376.122184 -217.864182)
		(width 0.0889)
		(layer "B.Cu")
		(net "VSENSE_PVCCINFAON_CPU0_DP")
	)
	(arc
		(start 368.225832 -222.437198)
		(mid 368.038634 -222.387055)
		(end 367.851436 -222.437198)
		(width 0.0889)
		(layer "B.Cu")
		(net "VSENSE_PVCCINFAON_CPU0_DP")
	)
	(arc
		(start 376.121676 -214.644732)
		(mid 376.040765 -214.91486)
		(end 375.839482 -215.112346)
		(width 0.0889)
		(layer "B.Cu")
		(net "VSENSE_PVCCINFAON_CPU0_DP")
	)
	(arc
		(start 375.65203 -215.436958)
		(mid 375.576405 -215.719309)
		(end 375.369836 -215.926162)
		(width 0.0889)
		(layer "B.Cu")
		(net "VSENSE_PVCCINFAON_CPU0_DP")
	)
	(arc
		(start 373.481346 -219.18676)
		(mid 373.350432 -219.32312)
		(end 373.302784 -219.506038)
		(width 0.0889)
		(layer "B.Cu")
		(net "VSENSE_PVCCINFAON_CPU0_DP")
	)
	(arc
		(start 366.346232 -222.437198)
		(mid 366.159034 -222.387055)
		(end 365.971836 -222.437198)
		(width 0.0889)
		(layer "B.Cu")
		(net "VSENSE_PVCCINFAON_CPU0_DP")
	)
	(arc
		(start 363.526832 -222.437198)
		(mid 363.339634 -222.387089)
		(end 363.152436 -222.437198)
		(width 0.0889)
		(layer "B.Cu")
		(net "VSENSE_PVCCINFAON_CPU0_DP")
	)
	(arc
		(start 369.731036 -222.437198)
		(mid 369.456837 -222.513033)
		(end 369.180364 -222.445834)
		(width 0.0889)
		(layer "B.Cu")
		(net "VSENSE_PVCCINFAON_CPU0_DP")
	)
	(arc
		(start 372.83263 -221.963234)
		(mid 372.75326 -222.236968)
		(end 372.550436 -222.437198)
		(width 0.0889)
		(layer "B.Cu")
		(net "VSENSE_PVCCINFAON_CPU0_DP")
	)
	(arc
		(start 362.587032 -222.437198)
		(mid 362.399834 -222.387055)
		(end 362.212636 -222.437198)
		(width 0.0889)
		(layer "B.Cu")
		(net "VSENSE_PVCCINFAON_CPU0_DP")
	)
	(segment
		(start 433.8574 -146.69516)
		(end 433.8574 -156.24556)
		(width 0.254)
		(layer "In2.Cu")
		(net "VSENSE_PVCCINFAON_CPU0_DP")
	)
	(segment
		(start 452.2343 -183.015636)
		(end 448.644772 -186.605164)
		(width 0.254)
		(layer "In2.Cu")
		(net "VSENSE_PVCCINFAON_CPU0_DP")
	)
	(segment
		(start 427.337982 -143.551148)
		(end 426.903388 -143.551148)
		(width 0.254)
		(layer "In2.Cu")
		(net "VSENSE_PVCCINFAON_CPU0_DP")
	)
	(segment
		(start 401.168108 -186.605164)
		(end 397.235934 -186.605164)
		(width 0.254)
		(layer "In2.Cu")
		(net "VSENSE_PVCCINFAON_CPU0_DP")
	)
	(segment
		(start 411.717236 -186.157108)
		(end 401.616164 -186.157108)
		(width 0.254)
		(layer "In2.Cu")
		(net "VSENSE_PVCCINFAON_CPU0_DP")
	)
	(segment
		(start 452.2343 -170.14698)
		(end 452.2343 -183.015636)
		(width 0.254)
		(layer "In2.Cu")
		(net "VSENSE_PVCCINFAON_CPU0_DP")
	)
	(segment
		(start 433.8574 -156.24556)
		(end 442.410088 -164.798248)
		(width 0.254)
		(layer "In2.Cu")
		(net "VSENSE_PVCCINFAON_CPU0_DP")
	)
	(segment
		(start 401.616164 -186.157108)
		(end 401.168108 -186.605164)
		(width 0.254)
		(layer "In2.Cu")
		(net "VSENSE_PVCCINFAON_CPU0_DP")
	)
	(segment
		(start 448.644772 -186.605164)
		(end 412.165292 -186.605164)
		(width 0.254)
		(layer "In2.Cu")
		(net "VSENSE_PVCCINFAON_CPU0_DP")
	)
	(segment
		(start 427.1264 -144.617948)
		(end 431.780188 -144.617948)
		(width 0.254)
		(layer "In2.Cu")
		(net "VSENSE_PVCCINFAON_CPU0_DP")
	)
	(segment
		(start 427.575726 -143.788892)
		(end 427.337982 -143.551148)
		(width 0.254)
		(layer "In2.Cu")
		(net "VSENSE_PVCCINFAON_CPU0_DP")
	)
	(segment
		(start 426.903388 -143.551148)
		(end 426.72 -143.734536)
		(width 0.254)
		(layer "In2.Cu")
		(net "VSENSE_PVCCINFAON_CPU0_DP")
	)
	(segment
		(start 426.72 -143.734536)
		(end 426.72 -144.211548)
		(width 0.254)
		(layer "In2.Cu")
		(net "VSENSE_PVCCINFAON_CPU0_DP")
	)
	(segment
		(start 431.780188 -144.617948)
		(end 433.8574 -146.69516)
		(width 0.254)
		(layer "In2.Cu")
		(net "VSENSE_PVCCINFAON_CPU0_DP")
	)
	(segment
		(start 442.410088 -164.798248)
		(end 446.885568 -164.798248)
		(width 0.254)
		(layer "In2.Cu")
		(net "VSENSE_PVCCINFAON_CPU0_DP")
	)
	(segment
		(start 412.165292 -186.605164)
		(end 411.717236 -186.157108)
		(width 0.254)
		(layer "In2.Cu")
		(net "VSENSE_PVCCINFAON_CPU0_DP")
	)
	(segment
		(start 446.885568 -164.798248)
		(end 452.2343 -170.14698)
		(width 0.254)
		(layer "In2.Cu")
		(net "VSENSE_PVCCINFAON_CPU0_DP")
	)
	(segment
		(start 397.235934 -186.605164)
		(end 396.969234 -186.871864)
		(width 0.254)
		(layer "In2.Cu")
		(net "VSENSE_PVCCINFAON_CPU0_DP")
	)
	(segment
		(start 426.72 -144.211548)
		(end 427.1264 -144.617948)
		(width 0.254)
		(layer "In2.Cu")
		(net "VSENSE_PVCCINFAON_CPU0_DP")
	)
	(segment
		(start 427.105064 -138.814556)
		(end 427.105064 -139.625578)
		(width 0.1778)
		(layer "F.Cu")
		(net "VSENSE_PVCCINFAON_CPU0_DN")
	)
	(segment
		(start 427.817026 -143.166592)
		(end 428.333916 -143.166592)
		(width 0.254)
		(layer "F.Cu")
		(net "VSENSE_PVCCINFAON_CPU0_DN")
	)
	(segment
		(start 427.575726 -142.925292)
		(end 427.817026 -143.166592)
		(width 0.254)
		(layer "F.Cu")
		(net "VSENSE_PVCCINFAON_CPU0_DN")
	)
	(segment
		(start 427.607476 -140.12799)
		(end 427.607476 -140.269214)
		(width 0.254)
		(layer "F.Cu")
		(net "VSENSE_PVCCINFAON_CPU0_DN")
	)
	(segment
		(start 427.607476 -140.670026)
		(end 427.607476 -140.269214)
		(width 0.254)
		(layer "F.Cu")
		(net "VSENSE_PVCCINFAON_CPU0_DN")
	)
	(segment
		(start 397.47952 -186.224164)
		(end 397.733774 -185.96991)
		(width 0.254)
		(layer "F.Cu")
		(net "VSENSE_PVCCINFAON_CPU0_DN")
	)
	(segment
		(start 428.333916 -143.166592)
		(end 428.47768 -143.022828)
		(width 0.254)
		(layer "F.Cu")
		(net "VSENSE_PVCCINFAON_CPU0_DN")
	)
	(segment
		(start 385.04876 -202.13701)
		(end 385.29006 -202.37831)
		(width 0.254)
		(layer "F.Cu")
		(net "VSENSE_PVCCINFAON_CPU0_DN")
	)
	(segment
		(start 394.268198 -187.155582)
		(end 395.19225 -186.23153)
		(width 0.254)
		(layer "F.Cu")
		(net "VSENSE_PVCCINFAON_CPU0_DN")
	)
	(segment
		(start 397.185134 -186.224164)
		(end 397.47952 -186.224164)
		(width 0.254)
		(layer "F.Cu")
		(net "VSENSE_PVCCINFAON_CPU0_DN")
	)
	(segment
		(start 428.47768 -141.54023)
		(end 427.607476 -140.670026)
		(width 0.254)
		(layer "F.Cu")
		(net "VSENSE_PVCCINFAON_CPU0_DN")
	)
	(segment
		(start 385.962906 -202.37831)
		(end 394.268198 -194.073018)
		(width 0.254)
		(layer "F.Cu")
		(net "VSENSE_PVCCINFAON_CPU0_DN")
	)
	(segment
		(start 427.105064 -139.625578)
		(end 427.607476 -140.12799)
		(width 0.254)
		(layer "F.Cu")
		(net "VSENSE_PVCCINFAON_CPU0_DN")
	)
	(segment
		(start 428.47768 -143.022828)
		(end 428.47768 -141.54023)
		(width 0.254)
		(layer "F.Cu")
		(net "VSENSE_PVCCINFAON_CPU0_DN")
	)
	(segment
		(start 362.869734 -222.48368)
		(end 362.869734 -221.94774)
		(width 0.12954)
		(layer "F.Cu")
		(net "VSENSE_PVCCINFAON_CPU0_DN")
	)
	(segment
		(start 396.745968 -186.23153)
		(end 396.969234 -186.008264)
		(width 0.254)
		(layer "F.Cu")
		(net "VSENSE_PVCCINFAON_CPU0_DN")
	)
	(segment
		(start 394.268198 -194.073018)
		(end 394.268198 -187.155582)
		(width 0.254)
		(layer "F.Cu")
		(net "VSENSE_PVCCINFAON_CPU0_DN")
	)
	(segment
		(start 395.19225 -186.23153)
		(end 396.745968 -186.23153)
		(width 0.254)
		(layer "F.Cu")
		(net "VSENSE_PVCCINFAON_CPU0_DN")
	)
	(segment
		(start 396.969234 -186.008264)
		(end 397.185134 -186.224164)
		(width 0.254)
		(layer "F.Cu")
		(net "VSENSE_PVCCINFAON_CPU0_DN")
	)
	(segment
		(start 385.29006 -202.37831)
		(end 385.962906 -202.37831)
		(width 0.254)
		(layer "F.Cu")
		(net "VSENSE_PVCCINFAON_CPU0_DN")
	)
	(via
		(at 427.575726 -142.925292)
		(size 0.508)
		(drill 0.254)
		(layers "F.Cu" "B.Cu")
		(net "VSENSE_PVCCINFAON_CPU0_DN")
	)
	(via
		(at 362.869734 -221.94774)
		(size 0.4572)
		(drill 0.2032)
		(layers "F.Cu" "B.Cu")
		(net "VSENSE_PVCCINFAON_CPU0_DN")
	)
	(via
		(at 385.04876 -202.13701)
		(size 0.508)
		(drill 0.254)
		(layers "F.Cu" "B.Cu")
		(net "VSENSE_PVCCINFAON_CPU0_DN")
	)
	(via
		(at 396.969234 -186.008264)
		(size 0.508)
		(drill 0.254)
		(layers "F.Cu" "B.Cu")
		(net "VSENSE_PVCCINFAON_CPU0_DN")
	)
	(segment
		(start 376.222768 -219.0115)
		(end 376.213878 -219.01658)
		(width 0.0889)
		(layer "B.Cu")
		(net "VSENSE_PVCCINFAON_CPU0_DN")
	)
	(segment
		(start 375.744232 -217.554048)
		(end 375.753122 -217.559128)
		(width 0.0889)
		(layer "B.Cu")
		(net "VSENSE_PVCCINFAON_CPU0_DN")
	)
	(segment
		(start 372.463568 -222.267018)
		(end 372.454678 -222.272098)
		(width 0.0889)
		(layer "B.Cu")
		(net "VSENSE_PVCCINFAON_CPU0_DN")
	)
	(segment
		(start 374.899682 -219.01658)
		(end 374.88495 -219.007944)
		(width 0.0889)
		(layer "B.Cu")
		(net "VSENSE_PVCCINFAON_CPU0_DN")
	)
	(segment
		(start 363.33176 -222.196406)
		(end 363.1184 -222.196406)
		(width 0.0889)
		(layer "B.Cu")
		(net "VSENSE_PVCCINFAON_CPU0_DN")
	)
	(segment
		(start 385.04876 -202.13701)
		(end 384.80746 -202.37831)
		(width 0.254)
		(layer "B.Cu")
		(net "VSENSE_PVCCINFAON_CPU0_DN")
	)
	(segment
		(start 384.26136 -202.37831)
		(end 382.852168 -200.969118)
		(width 0.254)
		(layer "B.Cu")
		(net "VSENSE_PVCCINFAON_CPU0_DN")
	)
	(segment
		(start 375.366534 -212.903562)
		(end 375.366534 -213.055962)
		(width 0.0889)
		(layer "B.Cu")
		(net "VSENSE_PVCCINFAON_CPU0_DN")
	)
	(segment
		(start 375.931684 -217.878406)
		(end 375.931684 -217.8939)
		(width 0.0889)
		(layer "B.Cu")
		(net "VSENSE_PVCCINFAON_CPU0_DN")
	)
	(segment
		(start 375.46534 -215.32215)
		(end 375.461784 -215.41486)
		(width 0.0889)
		(layer "B.Cu")
		(net "VSENSE_PVCCINFAON_CPU0_DN")
	)
	(segment
		(start 363.1184 -222.196406)
		(end 362.869734 -221.94774)
		(width 0.0889)
		(layer "B.Cu")
		(net "VSENSE_PVCCINFAON_CPU0_DN")
	)
	(segment
		(start 375.366534 -205.04023)
		(end 375.366534 -212.903562)
		(width 0.254)
		(layer "B.Cu")
		(net "VSENSE_PVCCINFAON_CPU0_DN")
	)
	(segment
		(start 372.455694 -221.62389)
		(end 372.463568 -221.628462)
		(width 0.0889)
		(layer "B.Cu")
		(net "VSENSE_PVCCINFAON_CPU0_DN")
	)
	(segment
		(start 365.501682 -222.272098)
		(end 365.48695 -222.263462)
		(width 0.0889)
		(layer "B.Cu")
		(net "VSENSE_PVCCINFAON_CPU0_DN")
	)
	(segment
		(start 375.740422 -214.949278)
		(end 375.651776 -215.003126)
		(width 0.0889)
		(layer "B.Cu")
		(net "VSENSE_PVCCINFAON_CPU0_DN")
	)
	(segment
		(start 367.381536 -222.272098)
		(end 367.371122 -222.266002)
		(width 0.0889)
		(layer "B.Cu")
		(net "VSENSE_PVCCINFAON_CPU0_DN")
	)
	(segment
		(start 371.140482 -222.272098)
		(end 371.12575 -222.263462)
		(width 0.0889)
		(layer "B.Cu")
		(net "VSENSE_PVCCINFAON_CPU0_DN")
	)
	(segment
		(start 375.282968 -215.755982)
		(end 375.274078 -215.761062)
		(width 0.0889)
		(layer "B.Cu")
		(net "VSENSE_PVCCINFAON_CPU0_DN")
	)
	(segment
		(start 375.46153 -215.428322)
		(end 375.46153 -215.436704)
		(width 0.0889)
		(layer "B.Cu")
		(net "VSENSE_PVCCINFAON_CPU0_DN")
	)
	(segment
		(start 372.080282 -222.272098)
		(end 372.06555 -222.263462)
		(width 0.0889)
		(layer "B.Cu")
		(net "VSENSE_PVCCINFAON_CPU0_DN")
	)
	(segment
		(start 372.933722 -219.825316)
		(end 372.924832 -219.830396)
		(width 0.0889)
		(layer "B.Cu")
		(net "VSENSE_PVCCINFAON_CPU0_DN")
	)
	(segment
		(start 371.70233 -220.319854)
		(end 371.70233 -220.334078)
		(width 0.0889)
		(layer "B.Cu")
		(net "VSENSE_PVCCINFAON_CPU0_DN")
	)
	(segment
		(start 376.214894 -218.368372)
		(end 376.222768 -218.372944)
		(width 0.0889)
		(layer "B.Cu")
		(net "VSENSE_PVCCINFAON_CPU0_DN")
	)
	(segment
		(start 379.437646 -200.969118)
		(end 375.366534 -205.04023)
		(width 0.254)
		(layer "B.Cu")
		(net "VSENSE_PVCCINFAON_CPU0_DN")
	)
	(segment
		(start 375.366534 -213.055962)
		(end 375.461784 -213.151212)
		(width 0.0889)
		(layer "B.Cu")
		(net "VSENSE_PVCCINFAON_CPU0_DN")
	)
	(segment
		(start 372.172484 -221.133924)
		(end 372.172484 -221.149418)
		(width 0.0889)
		(layer "B.Cu")
		(net "VSENSE_PVCCINFAON_CPU0_DN")
	)
	(segment
		(start 364.561882 -222.272098)
		(end 364.54715 -222.263462)
		(width 0.0889)
		(layer "B.Cu")
		(net "VSENSE_PVCCINFAON_CPU0_DN")
	)
	(segment
		(start 363.622082 -222.272098)
		(end 363.611668 -222.266002)
		(width 0.0889)
		(layer "B.Cu")
		(net "VSENSE_PVCCINFAON_CPU0_DN")
	)
	(segment
		(start 375.46534 -215.321896)
		(end 375.46534 -215.32215)
		(width 0.0889)
		(layer "B.Cu")
		(net "VSENSE_PVCCINFAON_CPU0_DN")
	)
	(segment
		(start 372.454678 -221.623382)
		(end 372.455694 -221.62389)
		(width 0.0889)
		(layer "B.Cu")
		(net "VSENSE_PVCCINFAON_CPU0_DN")
	)
	(segment
		(start 375.461784 -213.151212)
		(end 375.461784 -213.930484)
		(width 0.0889)
		(layer "B.Cu")
		(net "VSENSE_PVCCINFAON_CPU0_DN")
	)
	(segment
		(start 371.985032 -219.830396)
		(end 371.978936 -219.833952)
		(width 0.0889)
		(layer "B.Cu")
		(net "VSENSE_PVCCINFAON_CPU0_DN")
	)
	(segment
		(start 375.46153 -217.0557)
		(end 375.46153 -217.07856)
		(width 0.0889)
		(layer "B.Cu")
		(net "VSENSE_PVCCINFAON_CPU0_DN")
	)
	(segment
		(start 366.441482 -222.272098)
		(end 366.42675 -222.263462)
		(width 0.0889)
		(layer "B.Cu")
		(net "VSENSE_PVCCINFAON_CPU0_DN")
	)
	(segment
		(start 371.999764 -219.82176)
		(end 371.985032 -219.830396)
		(width 0.0889)
		(layer "B.Cu")
		(net "VSENSE_PVCCINFAON_CPU0_DN")
	)
	(segment
		(start 373.112284 -219.490544)
		(end 373.112284 -219.506038)
		(width 0.0889)
		(layer "B.Cu")
		(net "VSENSE_PVCCINFAON_CPU0_DN")
	)
	(segment
		(start 373.959882 -219.01658)
		(end 373.94515 -219.007944)
		(width 0.0889)
		(layer "B.Cu")
		(net "VSENSE_PVCCINFAON_CPU0_DN")
	)
	(segment
		(start 369.260882 -222.272098)
		(end 369.24615 -222.263462)
		(width 0.0889)
		(layer "B.Cu")
		(net "VSENSE_PVCCINFAON_CPU0_DN")
	)
	(segment
		(start 368.321082 -222.272098)
		(end 368.310668 -222.266002)
		(width 0.0889)
		(layer "B.Cu")
		(net "VSENSE_PVCCINFAON_CPU0_DN")
	)
	(segment
		(start 374.991884 -216.235026)
		(end 374.991884 -216.260426)
		(width 0.0889)
		(layer "B.Cu")
		(net "VSENSE_PVCCINFAON_CPU0_DN")
	)
	(segment
		(start 376.213878 -218.367864)
		(end 376.214894 -218.368372)
		(width 0.0889)
		(layer "B.Cu")
		(net "VSENSE_PVCCINFAON_CPU0_DN")
	)
	(segment
		(start 375.931176 -214.461344)
		(end 375.931176 -214.640414)
		(width 0.0889)
		(layer "B.Cu")
		(net "VSENSE_PVCCINFAON_CPU0_DN")
	)
	(segment
		(start 370.200682 -222.272098)
		(end 370.18595 -222.263462)
		(width 0.0889)
		(layer "B.Cu")
		(net "VSENSE_PVCCINFAON_CPU0_DN")
	)
	(segment
		(start 371.985032 -220.809566)
		(end 371.993922 -220.814646)
		(width 0.0889)
		(layer "B.Cu")
		(net "VSENSE_PVCCINFAON_CPU0_DN")
	)
	(segment
		(start 375.839482 -219.01658)
		(end 375.82475 -219.007944)
		(width 0.0889)
		(layer "B.Cu")
		(net "VSENSE_PVCCINFAON_CPU0_DN")
	)
	(segment
		(start 384.80746 -202.37831)
		(end 384.26136 -202.37831)
		(width 0.254)
		(layer "B.Cu")
		(net "VSENSE_PVCCINFAON_CPU0_DN")
	)
	(segment
		(start 375.461784 -215.41486)
		(end 375.461784 -215.415114)
		(width 0.0889)
		(layer "B.Cu")
		(net "VSENSE_PVCCINFAON_CPU0_DN")
	)
	(segment
		(start 375.743978 -214.947246)
		(end 375.740422 -214.949278)
		(width 0.0889)
		(layer "B.Cu")
		(net "VSENSE_PVCCINFAON_CPU0_DN")
	)
	(segment
		(start 382.852168 -200.969118)
		(end 379.437646 -200.969118)
		(width 0.254)
		(layer "B.Cu")
		(net "VSENSE_PVCCINFAON_CPU0_DN")
	)
	(arc
		(start 375.274332 -216.739978)
		(mid 375.409265 -216.873332)
		(end 375.46153 -217.0557)
		(width 0.0889)
		(layer "B.Cu")
		(net "VSENSE_PVCCINFAON_CPU0_DN")
	)
	(arc
		(start 371.978936 -219.833952)
		(mid 371.776349 -220.040303)
		(end 371.70233 -220.319854)
		(width 0.0889)
		(layer "B.Cu")
		(net "VSENSE_PVCCINFAON_CPU0_DN")
	)
	(arc
		(start 372.550436 -219.830396)
		(mid 372.276237 -219.754561)
		(end 371.999764 -219.82176)
		(width 0.0889)
		(layer "B.Cu")
		(net "VSENSE_PVCCINFAON_CPU0_DN")
	)
	(arc
		(start 371.514878 -222.272098)
		(mid 371.32768 -222.322241)
		(end 371.140482 -222.272098)
		(width 0.0889)
		(layer "B.Cu")
		(net "VSENSE_PVCCINFAON_CPU0_DN")
	)
	(arc
		(start 372.454678 -222.272098)
		(mid 372.26748 -222.322241)
		(end 372.080282 -222.272098)
		(width 0.0889)
		(layer "B.Cu")
		(net "VSENSE_PVCCINFAON_CPU0_DN")
	)
	(arc
		(start 363.996478 -222.272098)
		(mid 363.80928 -222.322241)
		(end 363.622082 -222.272098)
		(width 0.0889)
		(layer "B.Cu")
		(net "VSENSE_PVCCINFAON_CPU0_DN")
	)
	(arc
		(start 365.48695 -222.263462)
		(mid 365.210475 -222.196142)
		(end 364.936278 -222.272098)
		(width 0.0889)
		(layer "B.Cu")
		(net "VSENSE_PVCCINFAON_CPU0_DN")
	)
	(arc
		(start 366.815878 -222.272098)
		(mid 366.62868 -222.322241)
		(end 366.441482 -222.272098)
		(width 0.0889)
		(layer "B.Cu")
		(net "VSENSE_PVCCINFAON_CPU0_DN")
	)
	(arc
		(start 372.463568 -221.628462)
		(mid 372.642044 -221.94774)
		(end 372.463568 -222.267018)
		(width 0.0889)
		(layer "B.Cu")
		(net "VSENSE_PVCCINFAON_CPU0_DN")
	)
	(arc
		(start 376.213878 -219.01658)
		(mid 376.02668 -219.066723)
		(end 375.839482 -219.01658)
		(width 0.0889)
		(layer "B.Cu")
		(net "VSENSE_PVCCINFAON_CPU0_DN")
	)
	(arc
		(start 374.88495 -219.007944)
		(mid 374.608475 -218.940624)
		(end 374.334278 -219.01658)
		(width 0.0889)
		(layer "B.Cu")
		(net "VSENSE_PVCCINFAON_CPU0_DN")
	)
	(arc
		(start 373.94515 -219.007944)
		(mid 373.668675 -218.940624)
		(end 373.394478 -219.01658)
		(width 0.0889)
		(layer "B.Cu")
		(net "VSENSE_PVCCINFAON_CPU0_DN")
	)
	(arc
		(start 371.70233 -220.334078)
		(mid 371.781549 -220.608763)
		(end 371.985032 -220.809566)
		(width 0.0889)
		(layer "B.Cu")
		(net "VSENSE_PVCCINFAON_CPU0_DN")
	)
	(arc
		(start 369.24615 -222.263462)
		(mid 368.969675 -222.196142)
		(end 368.695478 -222.272098)
		(width 0.0889)
		(layer "B.Cu")
		(net "VSENSE_PVCCINFAON_CPU0_DN")
	)
	(arc
		(start 371.993922 -220.814646)
		(mid 372.124836 -220.951006)
		(end 372.172484 -221.133924)
		(width 0.0889)
		(layer "B.Cu")
		(net "VSENSE_PVCCINFAON_CPU0_DN")
	)
	(arc
		(start 371.12575 -222.263462)
		(mid 370.849275 -222.196142)
		(end 370.575078 -222.272098)
		(width 0.0889)
		(layer "B.Cu")
		(net "VSENSE_PVCCINFAON_CPU0_DN")
	)
	(arc
		(start 366.42675 -222.263462)
		(mid 366.150275 -222.196142)
		(end 365.876078 -222.272098)
		(width 0.0889)
		(layer "B.Cu")
		(net "VSENSE_PVCCINFAON_CPU0_DN")
	)
	(arc
		(start 373.112284 -219.506038)
		(mid 373.064605 -219.688938)
		(end 372.933722 -219.825316)
		(width 0.0889)
		(layer "B.Cu")
		(net "VSENSE_PVCCINFAON_CPU0_DN")
	)
	(arc
		(start 375.46153 -217.07856)
		(mid 375.540749 -217.353245)
		(end 375.744232 -217.554048)
		(width 0.0889)
		(layer "B.Cu")
		(net "VSENSE_PVCCINFAON_CPU0_DN")
	)
	(arc
		(start 364.54715 -222.263462)
		(mid 364.270675 -222.196142)
		(end 363.996478 -222.272098)
		(width 0.0889)
		(layer "B.Cu")
		(net "VSENSE_PVCCINFAON_CPU0_DN")
	)
	(arc
		(start 374.991884 -216.260426)
		(mid 375.069995 -216.537375)
		(end 375.274332 -216.739978)
		(width 0.0889)
		(layer "B.Cu")
		(net "VSENSE_PVCCINFAON_CPU0_DN")
	)
	(arc
		(start 376.222768 -218.372944)
		(mid 376.401244 -218.692222)
		(end 376.222768 -219.0115)
		(width 0.0889)
		(layer "B.Cu")
		(net "VSENSE_PVCCINFAON_CPU0_DN")
	)
	(arc
		(start 367.755932 -222.272098)
		(mid 367.568734 -222.322241)
		(end 367.381536 -222.272098)
		(width 0.0889)
		(layer "B.Cu")
		(net "VSENSE_PVCCINFAON_CPU0_DN")
	)
	(arc
		(start 375.931176 -214.640414)
		(mid 375.87673 -214.817719)
		(end 375.743978 -214.947246)
		(width 0.0889)
		(layer "B.Cu")
		(net "VSENSE_PVCCINFAON_CPU0_DN")
	)
	(arc
		(start 370.575078 -222.272098)
		(mid 370.38788 -222.322241)
		(end 370.200682 -222.272098)
		(width 0.0889)
		(layer "B.Cu")
		(net "VSENSE_PVCCINFAON_CPU0_DN")
	)
	(arc
		(start 368.695478 -222.272098)
		(mid 368.50828 -222.322241)
		(end 368.321082 -222.272098)
		(width 0.0889)
		(layer "B.Cu")
		(net "VSENSE_PVCCINFAON_CPU0_DN")
	)
	(arc
		(start 374.334278 -219.01658)
		(mid 374.14708 -219.066723)
		(end 373.959882 -219.01658)
		(width 0.0889)
		(layer "B.Cu")
		(net "VSENSE_PVCCINFAON_CPU0_DN")
	)
	(arc
		(start 373.394478 -219.01658)
		(mid 373.191655 -219.216811)
		(end 373.112284 -219.490544)
		(width 0.0889)
		(layer "B.Cu")
		(net "VSENSE_PVCCINFAON_CPU0_DN")
	)
	(arc
		(start 375.274078 -219.01658)
		(mid 375.08688 -219.066723)
		(end 374.899682 -219.01658)
		(width 0.0889)
		(layer "B.Cu")
		(net "VSENSE_PVCCINFAON_CPU0_DN")
	)
	(arc
		(start 365.876078 -222.272098)
		(mid 365.68888 -222.322241)
		(end 365.501682 -222.272098)
		(width 0.0889)
		(layer "B.Cu")
		(net "VSENSE_PVCCINFAON_CPU0_DN")
	)
	(arc
		(start 375.461784 -213.930484)
		(mid 375.573063 -214.12319)
		(end 375.747026 -214.261954)
		(width 0.0889)
		(layer "B.Cu")
		(net "VSENSE_PVCCINFAON_CPU0_DN")
	)
	(arc
		(start 372.924832 -219.830396)
		(mid 372.737634 -219.880539)
		(end 372.550436 -219.830396)
		(width 0.0889)
		(layer "B.Cu")
		(net "VSENSE_PVCCINFAON_CPU0_DN")
	)
	(arc
		(start 363.611668 -222.266002)
		(mid 363.476227 -222.213058)
		(end 363.33176 -222.196406)
		(width 0.0889)
		(layer "B.Cu")
		(net "VSENSE_PVCCINFAON_CPU0_DN")
	)
	(arc
		(start 367.371122 -222.266002)
		(mid 367.09269 -222.196156)
		(end 366.815878 -222.272098)
		(width 0.0889)
		(layer "B.Cu")
		(net "VSENSE_PVCCINFAON_CPU0_DN")
	)
	(arc
		(start 375.461784 -215.415114)
		(mid 375.461618 -215.421717)
		(end 375.46153 -215.428322)
		(width 0.0889)
		(layer "B.Cu")
		(net "VSENSE_PVCCINFAON_CPU0_DN")
	)
	(arc
		(start 369.635278 -222.272098)
		(mid 369.44808 -222.322241)
		(end 369.260882 -222.272098)
		(width 0.0889)
		(layer "B.Cu")
		(net "VSENSE_PVCCINFAON_CPU0_DN")
	)
	(arc
		(start 375.82475 -219.007944)
		(mid 375.548275 -218.940624)
		(end 375.274078 -219.01658)
		(width 0.0889)
		(layer "B.Cu")
		(net "VSENSE_PVCCINFAON_CPU0_DN")
	)
	(arc
		(start 368.310668 -222.266002)
		(mid 368.03249 -222.196279)
		(end 367.755932 -222.272098)
		(width 0.0889)
		(layer "B.Cu")
		(net "VSENSE_PVCCINFAON_CPU0_DN")
	)
	(arc
		(start 375.651776 -215.003126)
		(mid 375.518564 -215.139134)
		(end 375.46534 -215.321896)
		(width 0.0889)
		(layer "B.Cu")
		(net "VSENSE_PVCCINFAON_CPU0_DN")
	)
	(arc
		(start 375.931684 -217.8939)
		(mid 376.011054 -218.167634)
		(end 376.213878 -218.367864)
		(width 0.0889)
		(layer "B.Cu")
		(net "VSENSE_PVCCINFAON_CPU0_DN")
	)
	(arc
		(start 375.274078 -215.761062)
		(mid 375.071255 -215.961293)
		(end 374.991884 -216.235026)
		(width 0.0889)
		(layer "B.Cu")
		(net "VSENSE_PVCCINFAON_CPU0_DN")
	)
	(arc
		(start 375.747026 -214.261954)
		(mid 375.856173 -214.345882)
		(end 375.931176 -214.461344)
		(width 0.0889)
		(layer "B.Cu")
		(net "VSENSE_PVCCINFAON_CPU0_DN")
	)
	(arc
		(start 372.172484 -221.149418)
		(mid 372.251854 -221.423152)
		(end 372.454678 -221.623382)
		(width 0.0889)
		(layer "B.Cu")
		(net "VSENSE_PVCCINFAON_CPU0_DN")
	)
	(arc
		(start 375.46153 -215.436704)
		(mid 375.413851 -215.619604)
		(end 375.282968 -215.755982)
		(width 0.0889)
		(layer "B.Cu")
		(net "VSENSE_PVCCINFAON_CPU0_DN")
	)
	(arc
		(start 372.06555 -222.263462)
		(mid 371.789075 -222.196142)
		(end 371.514878 -222.272098)
		(width 0.0889)
		(layer "B.Cu")
		(net "VSENSE_PVCCINFAON_CPU0_DN")
	)
	(arc
		(start 370.18595 -222.263462)
		(mid 369.909475 -222.196142)
		(end 369.635278 -222.272098)
		(width 0.0889)
		(layer "B.Cu")
		(net "VSENSE_PVCCINFAON_CPU0_DN")
	)
	(arc
		(start 375.753122 -217.559128)
		(mid 375.884036 -217.695488)
		(end 375.931684 -217.878406)
		(width 0.0889)
		(layer "B.Cu")
		(net "VSENSE_PVCCINFAON_CPU0_DN")
	)
	(arc
		(start 364.936278 -222.272098)
		(mid 364.74908 -222.322241)
		(end 364.561882 -222.272098)
		(width 0.0889)
		(layer "B.Cu")
		(net "VSENSE_PVCCINFAON_CPU0_DN")
	)
	(segment
		(start 431.6222 -144.998948)
		(end 433.4764 -146.853148)
		(width 0.254)
		(layer "In2.Cu")
		(net "VSENSE_PVCCINFAON_CPU0_DN")
	)
	(segment
		(start 433.4764 -146.853148)
		(end 433.4764 -156.403548)
		(width 0.254)
		(layer "In2.Cu")
		(net "VSENSE_PVCCINFAON_CPU0_DN")
	)
	(segment
		(start 401.458176 -185.776108)
		(end 401.01012 -186.224164)
		(width 0.254)
		(layer "In2.Cu")
		(net "VSENSE_PVCCINFAON_CPU0_DN")
	)
	(segment
		(start 426.7454 -143.170148)
		(end 426.339 -143.576548)
		(width 0.254)
		(layer "In2.Cu")
		(net "VSENSE_PVCCINFAON_CPU0_DN")
	)
	(segment
		(start 426.339 -144.369536)
		(end 426.968412 -144.998948)
		(width 0.254)
		(layer "In2.Cu")
		(net "VSENSE_PVCCINFAON_CPU0_DN")
	)
	(segment
		(start 433.4764 -156.403548)
		(end 442.2521 -165.179248)
		(width 0.254)
		(layer "In2.Cu")
		(net "VSENSE_PVCCINFAON_CPU0_DN")
	)
	(segment
		(start 446.72758 -165.179248)
		(end 451.8533 -170.304968)
		(width 0.254)
		(layer "In2.Cu")
		(net "VSENSE_PVCCINFAON_CPU0_DN")
	)
	(segment
		(start 442.2521 -165.179248)
		(end 446.72758 -165.179248)
		(width 0.254)
		(layer "In2.Cu")
		(net "VSENSE_PVCCINFAON_CPU0_DN")
	)
	(segment
		(start 401.01012 -186.224164)
		(end 397.185134 -186.224164)
		(width 0.254)
		(layer "In2.Cu")
		(net "VSENSE_PVCCINFAON_CPU0_DN")
	)
	(segment
		(start 427.575726 -142.925292)
		(end 427.33087 -143.170148)
		(width 0.254)
		(layer "In2.Cu")
		(net "VSENSE_PVCCINFAON_CPU0_DN")
	)
	(segment
		(start 427.33087 -143.170148)
		(end 426.7454 -143.170148)
		(width 0.254)
		(layer "In2.Cu")
		(net "VSENSE_PVCCINFAON_CPU0_DN")
	)
	(segment
		(start 426.968412 -144.998948)
		(end 431.6222 -144.998948)
		(width 0.254)
		(layer "In2.Cu")
		(net "VSENSE_PVCCINFAON_CPU0_DN")
	)
	(segment
		(start 397.185134 -186.224164)
		(end 396.969234 -186.008264)
		(width 0.254)
		(layer "In2.Cu")
		(net "VSENSE_PVCCINFAON_CPU0_DN")
	)
	(segment
		(start 451.8533 -182.857648)
		(end 448.486784 -186.224164)
		(width 0.254)
		(layer "In2.Cu")
		(net "VSENSE_PVCCINFAON_CPU0_DN")
	)
	(segment
		(start 451.8533 -170.304968)
		(end 451.8533 -182.857648)
		(width 0.254)
		(layer "In2.Cu")
		(net "VSENSE_PVCCINFAON_CPU0_DN")
	)
	(segment
		(start 426.339 -143.576548)
		(end 426.339 -144.369536)
		(width 0.254)
		(layer "In2.Cu")
		(net "VSENSE_PVCCINFAON_CPU0_DN")
	)
	(segment
		(start 448.486784 -186.224164)
		(end 412.32328 -186.224164)
		(width 0.254)
		(layer "In2.Cu")
		(net "VSENSE_PVCCINFAON_CPU0_DN")
	)
	(segment
		(start 412.32328 -186.224164)
		(end 411.875224 -185.776108)
		(width 0.254)
		(layer "In2.Cu")
		(net "VSENSE_PVCCINFAON_CPU0_DN")
	)
	(segment
		(start 411.875224 -185.776108)
		(end 401.458176 -185.776108)
		(width 0.254)
		(layer "In2.Cu")
		(net "VSENSE_PVCCINFAON_CPU0_DN")
	)
	(segment
		(start 76.91247 -349.641414)
		(end 77.15504 -349.883984)
		(width 0.254)
		(layer "F.Cu")
		(net "VSENSE_PVCCFA_EHV_FIVRA_CPU1_DP")
	)
	(segment
		(start 77.768704 -349.62973)
		(end 77.768704 -349.270828)
		(width 0.254)
		(layer "F.Cu")
		(net "VSENSE_PVCCFA_EHV_FIVRA_CPU1_DP")
	)
	(segment
		(start 58.9026 -336.704686)
		(end 57.667652 -336.704686)
		(width 0.254)
		(layer "F.Cu")
		(net "VSENSE_PVCCFA_EHV_FIVRA_CPU1_DP")
	)
	(segment
		(start 77.492606 -348.99473)
		(end 71.192644 -348.99473)
		(width 0.254)
		(layer "F.Cu")
		(net "VSENSE_PVCCFA_EHV_FIVRA_CPU1_DP")
	)
	(segment
		(start 77.51445 -349.883984)
		(end 77.768704 -349.62973)
		(width 0.254)
		(layer "F.Cu")
		(net "VSENSE_PVCCFA_EHV_FIVRA_CPU1_DP")
	)
	(segment
		(start 57.667652 -336.704686)
		(end 57.350152 -337.022186)
		(width 0.254)
		(layer "F.Cu")
		(net "VSENSE_PVCCFA_EHV_FIVRA_CPU1_DP")
	)
	(segment
		(start 103.291894 -284.311598)
		(end 103.291894 -284.847538)
		(width 0.254)
		(layer "F.Cu")
		(net "VSENSE_PVCCFA_EHV_FIVRA_CPU1_DP")
	)
	(segment
		(start 115.990116 -354.44811)
		(end 115.680236 -354.75799)
		(width 0.254)
		(layer "F.Cu")
		(net "VSENSE_PVCCFA_EHV_FIVRA_CPU1_DP")
	)
	(segment
		(start 77.768704 -349.270828)
		(end 77.492606 -348.99473)
		(width 0.254)
		(layer "F.Cu")
		(net "VSENSE_PVCCFA_EHV_FIVRA_CPU1_DP")
	)
	(segment
		(start 77.15504 -349.883984)
		(end 77.51445 -349.883984)
		(width 0.254)
		(layer "F.Cu")
		(net "VSENSE_PVCCFA_EHV_FIVRA_CPU1_DP")
	)
	(segment
		(start 115.680236 -354.75799)
		(end 115.680236 -355.236526)
		(width 0.254)
		(layer "F.Cu")
		(net "VSENSE_PVCCFA_EHV_FIVRA_CPU1_DP")
	)
	(segment
		(start 71.192644 -348.99473)
		(end 58.9026 -336.704686)
		(width 0.254)
		(layer "F.Cu")
		(net "VSENSE_PVCCFA_EHV_FIVRA_CPU1_DP")
	)
	(segment
		(start 116.427758 -354.44811)
		(end 115.990116 -354.44811)
		(width 0.254)
		(layer "F.Cu")
		(net "VSENSE_PVCCFA_EHV_FIVRA_CPU1_DP")
	)
	(segment
		(start 116.667534 -354.687886)
		(end 116.427758 -354.44811)
		(width 0.254)
		(layer "F.Cu")
		(net "VSENSE_PVCCFA_EHV_FIVRA_CPU1_DP")
	)
	(via
		(at 116.667534 -354.687886)
		(size 0.508)
		(drill 0.254)
		(layers "F.Cu" "B.Cu")
		(net "VSENSE_PVCCFA_EHV_FIVRA_CPU1_DP")
	)
	(via
		(at 103.291894 -284.847538)
		(size 0.4572)
		(drill 0.2032)
		(layers "F.Cu" "B.Cu")
		(net "VSENSE_PVCCFA_EHV_FIVRA_CPU1_DP")
	)
	(via
		(at 76.91247 -349.641414)
		(size 0.508)
		(drill 0.254)
		(layers "F.Cu" "B.Cu")
		(net "VSENSE_PVCCFA_EHV_FIVRA_CPU1_DP")
	)
	(segment
		(start 103.857298 -288.103056)
		(end 103.857298 -288.121598)
		(width 0.0889)
		(layer "B.Cu")
		(net "VSENSE_PVCCFA_EHV_FIVRA_CPU1_DP")
	)
	(segment
		(start 100.541836 -290.563808)
		(end 100.446586 -290.659058)
		(width 0.0889)
		(layer "B.Cu")
		(net "VSENSE_PVCCFA_EHV_FIVRA_CPU1_DP")
	)
	(segment
		(start 100.446586 -290.659058)
		(end 78.909418 -290.659058)
		(width 0.254)
		(layer "B.Cu")
		(net "VSENSE_PVCCFA_EHV_FIVRA_CPU1_DP")
	)
	(segment
		(start 72.544178 -297.024298)
		(end 72.544178 -346.869004)
		(width 0.254)
		(layer "B.Cu")
		(net "VSENSE_PVCCFA_EHV_FIVRA_CPU1_DP")
	)
	(segment
		(start 104.04475 -287.778698)
		(end 104.03586 -287.783778)
		(width 0.0889)
		(layer "B.Cu")
		(net "VSENSE_PVCCFA_EHV_FIVRA_CPU1_DP")
	)
	(segment
		(start 75.557888 -349.882714)
		(end 76.67117 -349.882714)
		(width 0.254)
		(layer "B.Cu")
		(net "VSENSE_PVCCFA_EHV_FIVRA_CPU1_DP")
	)
	(segment
		(start 104.044496 -286.799782)
		(end 104.053894 -286.80537)
		(width 0.0889)
		(layer "B.Cu")
		(net "VSENSE_PVCCFA_EHV_FIVRA_CPU1_DP")
	)
	(segment
		(start 102.996746 -284.847538)
		(end 102.92461 -284.919674)
		(width 0.0889)
		(layer "B.Cu")
		(net "VSENSE_PVCCFA_EHV_FIVRA_CPU1_DP")
	)
	(segment
		(start 104.053894 -286.80537)
		(end 104.056688 -286.806894)
		(width 0.0889)
		(layer "B.Cu")
		(net "VSENSE_PVCCFA_EHV_FIVRA_CPU1_DP")
	)
	(segment
		(start 102.415086 -290.563808)
		(end 100.541836 -290.563808)
		(width 0.0889)
		(layer "B.Cu")
		(net "VSENSE_PVCCFA_EHV_FIVRA_CPU1_DP")
	)
	(segment
		(start 76.67117 -349.882714)
		(end 76.91247 -349.641414)
		(width 0.254)
		(layer "B.Cu")
		(net "VSENSE_PVCCFA_EHV_FIVRA_CPU1_DP")
	)
	(segment
		(start 103.565706 -285.980632)
		(end 103.574596 -285.985712)
		(width 0.0889)
		(layer "B.Cu")
		(net "VSENSE_PVCCFA_EHV_FIVRA_CPU1_DP")
	)
	(segment
		(start 103.387144 -285.651448)
		(end 103.387144 -285.661354)
		(width 0.0889)
		(layer "B.Cu")
		(net "VSENSE_PVCCFA_EHV_FIVRA_CPU1_DP")
	)
	(segment
		(start 104.050846 -287.775142)
		(end 104.04475 -287.778698)
		(width 0.0889)
		(layer "B.Cu")
		(net "VSENSE_PVCCFA_EHV_FIVRA_CPU1_DP")
	)
	(segment
		(start 72.544178 -346.869004)
		(end 75.557888 -349.882714)
		(width 0.254)
		(layer "B.Cu")
		(net "VSENSE_PVCCFA_EHV_FIVRA_CPU1_DP")
	)
	(segment
		(start 102.447598 -288.917126)
		(end 102.447598 -289.078416)
		(width 0.0889)
		(layer "B.Cu")
		(net "VSENSE_PVCCFA_EHV_FIVRA_CPU1_DP")
	)
	(segment
		(start 103.291894 -284.847538)
		(end 102.996746 -284.847538)
		(width 0.0889)
		(layer "B.Cu")
		(net "VSENSE_PVCCFA_EHV_FIVRA_CPU1_DP")
	)
	(segment
		(start 103.857298 -286.4612)
		(end 103.857298 -286.48406)
		(width 0.0889)
		(layer "B.Cu")
		(net "VSENSE_PVCCFA_EHV_FIVRA_CPU1_DP")
	)
	(segment
		(start 102.917244 -289.60953)
		(end 102.917244 -290.06165)
		(width 0.0889)
		(layer "B.Cu")
		(net "VSENSE_PVCCFA_EHV_FIVRA_CPU1_DP")
	)
	(segment
		(start 78.909418 -290.659058)
		(end 72.544178 -297.024298)
		(width 0.254)
		(layer "B.Cu")
		(net "VSENSE_PVCCFA_EHV_FIVRA_CPU1_DP")
	)
	(segment
		(start 102.917244 -290.06165)
		(end 102.415086 -290.563808)
		(width 0.0889)
		(layer "B.Cu")
		(net "VSENSE_PVCCFA_EHV_FIVRA_CPU1_DP")
	)
	(arc
		(start 102.631748 -289.277806)
		(mid 102.80588 -289.416653)
		(end 102.917244 -289.60953)
		(width 0.0889)
		(layer "B.Cu")
		(net "VSENSE_PVCCFA_EHV_FIVRA_CPU1_DP")
	)
	(arc
		(start 104.327198 -287.28924)
		(mid 104.253282 -287.568742)
		(end 104.050846 -287.775142)
		(width 0.0889)
		(layer "B.Cu")
		(net "VSENSE_PVCCFA_EHV_FIVRA_CPU1_DP")
	)
	(arc
		(start 103.104696 -285.171896)
		(mid 103.309031 -285.374501)
		(end 103.387144 -285.651448)
		(width 0.0889)
		(layer "B.Cu")
		(net "VSENSE_PVCCFA_EHV_FIVRA_CPU1_DP")
	)
	(arc
		(start 103.009446 -288.592768)
		(mid 102.634971 -288.592814)
		(end 102.447598 -288.917126)
		(width 0.0889)
		(layer "B.Cu")
		(net "VSENSE_PVCCFA_EHV_FIVRA_CPU1_DP")
	)
	(arc
		(start 104.056688 -286.806894)
		(mid 104.254916 -287.012742)
		(end 104.327198 -287.28924)
		(width 0.0889)
		(layer "B.Cu")
		(net "VSENSE_PVCCFA_EHV_FIVRA_CPU1_DP")
	)
	(arc
		(start 104.03586 -287.783778)
		(mid 103.904946 -287.920138)
		(end 103.857298 -288.103056)
		(width 0.0889)
		(layer "B.Cu")
		(net "VSENSE_PVCCFA_EHV_FIVRA_CPU1_DP")
	)
	(arc
		(start 103.857298 -288.121598)
		(mid 103.56682 -288.597317)
		(end 103.009446 -288.592768)
		(width 0.0889)
		(layer "B.Cu")
		(net "VSENSE_PVCCFA_EHV_FIVRA_CPU1_DP")
	)
	(arc
		(start 103.857298 -286.48406)
		(mid 103.909568 -286.666425)
		(end 104.044496 -286.799782)
		(width 0.0889)
		(layer "B.Cu")
		(net "VSENSE_PVCCFA_EHV_FIVRA_CPU1_DP")
	)
	(arc
		(start 102.447598 -289.078416)
		(mid 102.522603 -289.193875)
		(end 102.631748 -289.277806)
		(width 0.0889)
		(layer "B.Cu")
		(net "VSENSE_PVCCFA_EHV_FIVRA_CPU1_DP")
	)
	(arc
		(start 103.387144 -285.661354)
		(mid 103.434823 -285.844254)
		(end 103.565706 -285.980632)
		(width 0.0889)
		(layer "B.Cu")
		(net "VSENSE_PVCCFA_EHV_FIVRA_CPU1_DP")
	)
	(arc
		(start 102.92461 -284.919674)
		(mid 102.987303 -285.065325)
		(end 103.104696 -285.171896)
		(width 0.0889)
		(layer "B.Cu")
		(net "VSENSE_PVCCFA_EHV_FIVRA_CPU1_DP")
	)
	(arc
		(start 103.574596 -285.985712)
		(mid 103.778077 -286.186516)
		(end 103.857298 -286.4612)
		(width 0.0889)
		(layer "B.Cu")
		(net "VSENSE_PVCCFA_EHV_FIVRA_CPU1_DP")
	)
	(segment
		(start 99.039426 -347.791532)
		(end 97.289366 -346.041472)
		(width 0.254)
		(layer "In6.Cu")
		(net "VSENSE_PVCCFA_EHV_FIVRA_CPU1_DP")
	)
	(segment
		(start 83.338924 -349.894906)
		(end 77.165962 -349.894906)
		(width 0.254)
		(layer "In6.Cu")
		(net "VSENSE_PVCCFA_EHV_FIVRA_CPU1_DP")
	)
	(segment
		(start 116.906548 -354.448872)
		(end 117.434106 -354.448872)
		(width 0.254)
		(layer "In6.Cu")
		(net "VSENSE_PVCCFA_EHV_FIVRA_CPU1_DP")
	)
	(segment
		(start 118.015766 -353.867212)
		(end 118.015766 -352.721672)
		(width 0.254)
		(layer "In6.Cu")
		(net "VSENSE_PVCCFA_EHV_FIVRA_CPU1_DP")
	)
	(segment
		(start 115.0112 -352.135948)
		(end 110.666784 -347.791532)
		(width 0.254)
		(layer "In6.Cu")
		(net "VSENSE_PVCCFA_EHV_FIVRA_CPU1_DP")
	)
	(segment
		(start 110.666784 -347.791532)
		(end 99.039426 -347.791532)
		(width 0.254)
		(layer "In6.Cu")
		(net "VSENSE_PVCCFA_EHV_FIVRA_CPU1_DP")
	)
	(segment
		(start 117.430042 -352.135948)
		(end 115.0112 -352.135948)
		(width 0.254)
		(layer "In6.Cu")
		(net "VSENSE_PVCCFA_EHV_FIVRA_CPU1_DP")
	)
	(segment
		(start 116.667534 -354.687886)
		(end 116.906548 -354.448872)
		(width 0.254)
		(layer "In6.Cu")
		(net "VSENSE_PVCCFA_EHV_FIVRA_CPU1_DP")
	)
	(segment
		(start 117.434106 -354.448872)
		(end 118.015766 -353.867212)
		(width 0.254)
		(layer "In6.Cu")
		(net "VSENSE_PVCCFA_EHV_FIVRA_CPU1_DP")
	)
	(segment
		(start 118.015766 -352.721672)
		(end 117.430042 -352.135948)
		(width 0.254)
		(layer "In6.Cu")
		(net "VSENSE_PVCCFA_EHV_FIVRA_CPU1_DP")
	)
	(segment
		(start 77.165962 -349.894906)
		(end 76.91247 -349.641414)
		(width 0.254)
		(layer "In6.Cu")
		(net "VSENSE_PVCCFA_EHV_FIVRA_CPU1_DP")
	)
	(segment
		(start 87.192358 -346.041472)
		(end 83.338924 -349.894906)
		(width 0.254)
		(layer "In6.Cu")
		(net "VSENSE_PVCCFA_EHV_FIVRA_CPU1_DP")
	)
	(segment
		(start 97.289366 -346.041472)
		(end 87.192358 -346.041472)
		(width 0.254)
		(layer "In6.Cu")
		(net "VSENSE_PVCCFA_EHV_FIVRA_CPU1_DP")
	)
	(segment
		(start 115.357656 -353.801426)
		(end 115.357656 -354.065586)
		(width 0.254)
		(layer "F.Cu")
		(net "VSENSE_PVCCFA_EHV_FIVRA_CPU1_DN")
	)
	(segment
		(start 114.049048 -353.516946)
		(end 115.073176 -353.516946)
		(width 0.254)
		(layer "F.Cu")
		(net "VSENSE_PVCCFA_EHV_FIVRA_CPU1_DN")
	)
	(segment
		(start 78.149704 -349.11284)
		(end 77.650594 -348.61373)
		(width 0.254)
		(layer "F.Cu")
		(net "VSENSE_PVCCFA_EHV_FIVRA_CPU1_DN")
	)
	(segment
		(start 76.91247 -350.505014)
		(end 77.1525 -350.264984)
		(width 0.254)
		(layer "F.Cu")
		(net "VSENSE_PVCCFA_EHV_FIVRA_CPU1_DN")
	)
	(segment
		(start 112.34166 -356.410768)
		(end 113.3221 -355.430328)
		(width 0.1778)
		(layer "F.Cu")
		(net "VSENSE_PVCCFA_EHV_FIVRA_CPU1_DN")
	)
	(segment
		(start 111.453422 -357.448358)
		(end 111.87557 -357.448358)
		(width 0.1778)
		(layer "F.Cu")
		(net "VSENSE_PVCCFA_EHV_FIVRA_CPU1_DN")
	)
	(segment
		(start 116.667534 -353.824286)
		(end 116.426234 -354.065586)
		(width 0.254)
		(layer "F.Cu")
		(net "VSENSE_PVCCFA_EHV_FIVRA_CPU1_DN")
	)
	(segment
		(start 78.149704 -349.787718)
		(end 78.149704 -349.11284)
		(width 0.254)
		(layer "F.Cu")
		(net "VSENSE_PVCCFA_EHV_FIVRA_CPU1_DN")
	)
	(segment
		(start 59.060588 -336.323686)
		(end 57.667652 -336.323686)
		(width 0.254)
		(layer "F.Cu")
		(net "VSENSE_PVCCFA_EHV_FIVRA_CPU1_DN")
	)
	(segment
		(start 115.073176 -353.516946)
		(end 115.357656 -353.801426)
		(width 0.254)
		(layer "F.Cu")
		(net "VSENSE_PVCCFA_EHV_FIVRA_CPU1_DN")
	)
	(segment
		(start 57.667652 -336.323686)
		(end 57.350152 -336.006186)
		(width 0.254)
		(layer "F.Cu")
		(net "VSENSE_PVCCFA_EHV_FIVRA_CPU1_DN")
	)
	(segment
		(start 101.412294 -284.847284)
		(end 101.412548 -284.847538)
		(width 0.254)
		(layer "F.Cu")
		(net "VSENSE_PVCCFA_EHV_FIVRA_CPU1_DN")
	)
	(segment
		(start 77.1525 -350.264984)
		(end 77.672438 -350.264984)
		(width 0.254)
		(layer "F.Cu")
		(net "VSENSE_PVCCFA_EHV_FIVRA_CPU1_DN")
	)
	(segment
		(start 77.672438 -350.264984)
		(end 78.149704 -349.787718)
		(width 0.254)
		(layer "F.Cu")
		(net "VSENSE_PVCCFA_EHV_FIVRA_CPU1_DN")
	)
	(segment
		(start 101.412294 -284.311598)
		(end 101.412294 -284.847284)
		(width 0.254)
		(layer "F.Cu")
		(net "VSENSE_PVCCFA_EHV_FIVRA_CPU1_DN")
	)
	(segment
		(start 77.650594 -348.61373)
		(end 71.350632 -348.61373)
		(width 0.254)
		(layer "F.Cu")
		(net "VSENSE_PVCCFA_EHV_FIVRA_CPU1_DN")
	)
	(segment
		(start 71.350632 -348.61373)
		(end 59.060588 -336.323686)
		(width 0.254)
		(layer "F.Cu")
		(net "VSENSE_PVCCFA_EHV_FIVRA_CPU1_DN")
	)
	(segment
		(start 112.2299 -357.094028)
		(end 112.34166 -356.82428)
		(width 0.1778)
		(layer "F.Cu")
		(net "VSENSE_PVCCFA_EHV_FIVRA_CPU1_DN")
	)
	(segment
		(start 113.79708 -353.532948)
		(end 114.033046 -353.532948)
		(width 0.254)
		(layer "F.Cu")
		(net "VSENSE_PVCCFA_EHV_FIVRA_CPU1_DN")
	)
	(segment
		(start 114.033046 -353.532948)
		(end 114.049048 -353.516946)
		(width 0.254)
		(layer "F.Cu")
		(net "VSENSE_PVCCFA_EHV_FIVRA_CPU1_DN")
	)
	(segment
		(start 111.87557 -357.448358)
		(end 112.2299 -357.094028)
		(width 0.1778)
		(layer "F.Cu")
		(net "VSENSE_PVCCFA_EHV_FIVRA_CPU1_DN")
	)
	(segment
		(start 113.3221 -355.430328)
		(end 113.3221 -354.007928)
		(width 0.1778)
		(layer "F.Cu")
		(net "VSENSE_PVCCFA_EHV_FIVRA_CPU1_DN")
	)
	(segment
		(start 113.3221 -354.007928)
		(end 113.79708 -353.532948)
		(width 0.1778)
		(layer "F.Cu")
		(net "VSENSE_PVCCFA_EHV_FIVRA_CPU1_DN")
	)
	(segment
		(start 116.426234 -354.065586)
		(end 115.357656 -354.065586)
		(width 0.254)
		(layer "F.Cu")
		(net "VSENSE_PVCCFA_EHV_FIVRA_CPU1_DN")
	)
	(segment
		(start 112.34166 -356.82428)
		(end 112.34166 -356.410768)
		(width 0.1778)
		(layer "F.Cu")
		(net "VSENSE_PVCCFA_EHV_FIVRA_CPU1_DN")
	)
	(via
		(at 113.79708 -353.532948)
		(size 0.508)
		(drill 0.254)
		(layers "F.Cu" "B.Cu")
		(net "VSENSE_PVCCFA_EHV_FIVRA_CPU1_DN")
	)
	(via
		(at 101.412548 -284.847538)
		(size 0.4572)
		(drill 0.2032)
		(layers "F.Cu" "B.Cu")
		(net "VSENSE_PVCCFA_EHV_FIVRA_CPU1_DN")
	)
	(via
		(at 116.667534 -353.824286)
		(size 0.508)
		(drill 0.254)
		(layers "F.Cu" "B.Cu")
		(net "VSENSE_PVCCFA_EHV_FIVRA_CPU1_DN")
	)
	(via
		(at 76.91247 -350.505014)
		(size 0.508)
		(drill 0.254)
		(layers "F.Cu" "B.Cu")
		(net "VSENSE_PVCCFA_EHV_FIVRA_CPU1_DN")
	)
	(segment
		(start 72.163178 -347.026992)
		(end 75.3999 -350.263714)
		(width 0.254)
		(layer "B.Cu")
		(net "VSENSE_PVCCFA_EHV_FIVRA_CPU1_DN")
	)
	(segment
		(start 102.573582 -284.432756)
		(end 102.587044 -284.44063)
		(width 0.0889)
		(layer "B.Cu")
		(net "VSENSE_PVCCFA_EHV_FIVRA_CPU1_DN")
	)
	(segment
		(start 78.75143 -290.278058)
		(end 72.163178 -296.86631)
		(width 0.254)
		(layer "B.Cu")
		(net "VSENSE_PVCCFA_EHV_FIVRA_CPU1_DN")
	)
	(segment
		(start 103.957882 -287.608518)
		(end 103.950008 -287.61309)
		(width 0.0889)
		(layer "B.Cu")
		(net "VSENSE_PVCCFA_EHV_FIVRA_CPU1_DN")
	)
	(segment
		(start 103.196644 -285.661354)
		(end 103.196644 -285.675578)
		(width 0.0889)
		(layer "B.Cu")
		(net "VSENSE_PVCCFA_EHV_FIVRA_CPU1_DN")
	)
	(segment
		(start 103.948992 -286.964882)
		(end 103.957882 -286.969962)
		(width 0.0889)
		(layer "B.Cu")
		(net "VSENSE_PVCCFA_EHV_FIVRA_CPU1_DN")
	)
	(segment
		(start 101.412548 -284.847538)
		(end 102.117144 -284.44063)
		(width 0.0889)
		(layer "B.Cu")
		(net "VSENSE_PVCCFA_EHV_FIVRA_CPU1_DN")
	)
	(segment
		(start 76.67117 -350.263714)
		(end 76.91247 -350.505014)
		(width 0.254)
		(layer "B.Cu")
		(net "VSENSE_PVCCFA_EHV_FIVRA_CPU1_DN")
	)
	(segment
		(start 100.541836 -290.373308)
		(end 100.446586 -290.278058)
		(width 0.0889)
		(layer "B.Cu")
		(net "VSENSE_PVCCFA_EHV_FIVRA_CPU1_DN")
	)
	(segment
		(start 102.726744 -289.64509)
		(end 102.726744 -289.982656)
		(width 0.0889)
		(layer "B.Cu")
		(net "VSENSE_PVCCFA_EHV_FIVRA_CPU1_DN")
	)
	(segment
		(start 102.257098 -288.898584)
		(end 102.257098 -289.114738)
		(width 0.0889)
		(layer "B.Cu")
		(net "VSENSE_PVCCFA_EHV_FIVRA_CPU1_DN")
	)
	(segment
		(start 100.446586 -290.278058)
		(end 78.75143 -290.278058)
		(width 0.254)
		(layer "B.Cu")
		(net "VSENSE_PVCCFA_EHV_FIVRA_CPU1_DN")
	)
	(segment
		(start 103.009192 -285.336996)
		(end 103.018082 -285.342076)
		(width 0.0889)
		(layer "B.Cu")
		(net "VSENSE_PVCCFA_EHV_FIVRA_CPU1_DN")
	)
	(segment
		(start 72.163178 -296.86631)
		(end 72.163178 -347.026992)
		(width 0.254)
		(layer "B.Cu")
		(net "VSENSE_PVCCFA_EHV_FIVRA_CPU1_DN")
	)
	(segment
		(start 102.587044 -284.44063)
		(end 102.587298 -284.44063)
		(width 0.0889)
		(layer "B.Cu")
		(net "VSENSE_PVCCFA_EHV_FIVRA_CPU1_DN")
	)
	(segment
		(start 102.726744 -289.982656)
		(end 102.336092 -290.373308)
		(width 0.0889)
		(layer "B.Cu")
		(net "VSENSE_PVCCFA_EHV_FIVRA_CPU1_DN")
	)
	(segment
		(start 102.726744 -284.682184)
		(end 102.726744 -284.847792)
		(width 0.0889)
		(layer "B.Cu")
		(net "VSENSE_PVCCFA_EHV_FIVRA_CPU1_DN")
	)
	(segment
		(start 75.3999 -350.263714)
		(end 76.67117 -350.263714)
		(width 0.254)
		(layer "B.Cu")
		(net "VSENSE_PVCCFA_EHV_FIVRA_CPU1_DN")
	)
	(segment
		(start 102.336092 -290.373308)
		(end 100.541836 -290.373308)
		(width 0.0889)
		(layer "B.Cu")
		(net "VSENSE_PVCCFA_EHV_FIVRA_CPU1_DN")
	)
	(segment
		(start 103.950008 -287.61309)
		(end 103.948992 -287.613598)
		(width 0.0889)
		(layer "B.Cu")
		(net "VSENSE_PVCCFA_EHV_FIVRA_CPU1_DN")
	)
	(segment
		(start 103.666798 -288.087562)
		(end 103.666798 -288.103056)
		(width 0.0889)
		(layer "B.Cu")
		(net "VSENSE_PVCCFA_EHV_FIVRA_CPU1_DN")
	)
	(segment
		(start 103.666544 -286.466788)
		(end 103.666544 -286.48533)
		(width 0.0889)
		(layer "B.Cu")
		(net "VSENSE_PVCCFA_EHV_FIVRA_CPU1_DN")
	)
	(arc
		(start 102.257098 -289.114738)
		(mid 102.368436 -289.307638)
		(end 102.542594 -289.446462)
		(width 0.0889)
		(layer "B.Cu")
		(net "VSENSE_PVCCFA_EHV_FIVRA_CPU1_DN")
	)
	(arc
		(start 103.666544 -286.48533)
		(mid 103.744655 -286.762279)
		(end 103.948992 -286.964882)
		(width 0.0889)
		(layer "B.Cu")
		(net "VSENSE_PVCCFA_EHV_FIVRA_CPU1_DN")
	)
	(arc
		(start 103.018082 -285.342076)
		(mid 103.148996 -285.478436)
		(end 103.196644 -285.661354)
		(width 0.0889)
		(layer "B.Cu")
		(net "VSENSE_PVCCFA_EHV_FIVRA_CPU1_DN")
	)
	(arc
		(start 103.666798 -288.103056)
		(mid 103.479499 -288.427497)
		(end 103.10495 -288.427414)
		(width 0.0889)
		(layer "B.Cu")
		(net "VSENSE_PVCCFA_EHV_FIVRA_CPU1_DN")
	)
	(arc
		(start 102.726744 -284.847792)
		(mid 102.729328 -284.902273)
		(end 102.737158 -284.95625)
		(width 0.0889)
		(layer "B.Cu")
		(net "VSENSE_PVCCFA_EHV_FIVRA_CPU1_DN")
	)
	(arc
		(start 102.117144 -284.44063)
		(mid 102.344331 -284.377612)
		(end 102.573582 -284.432756)
		(width 0.0889)
		(layer "B.Cu")
		(net "VSENSE_PVCCFA_EHV_FIVRA_CPU1_DN")
	)
	(arc
		(start 103.957882 -286.969962)
		(mid 104.136479 -287.28924)
		(end 103.957882 -287.608518)
		(width 0.0889)
		(layer "B.Cu")
		(net "VSENSE_PVCCFA_EHV_FIVRA_CPU1_DN")
	)
	(arc
		(start 102.587298 -284.44063)
		(mid 102.689396 -284.542721)
		(end 102.726744 -284.682184)
		(width 0.0889)
		(layer "B.Cu")
		(net "VSENSE_PVCCFA_EHV_FIVRA_CPU1_DN")
	)
	(arc
		(start 103.196644 -285.675578)
		(mid 103.275863 -285.950263)
		(end 103.479346 -286.151066)
		(width 0.0889)
		(layer "B.Cu")
		(net "VSENSE_PVCCFA_EHV_FIVRA_CPU1_DN")
	)
	(arc
		(start 103.479346 -286.151066)
		(mid 103.614279 -286.28442)
		(end 103.666544 -286.466788)
		(width 0.0889)
		(layer "B.Cu")
		(net "VSENSE_PVCCFA_EHV_FIVRA_CPU1_DN")
	)
	(arc
		(start 102.737158 -284.95625)
		(mid 102.831892 -285.176116)
		(end 103.009192 -285.336996)
		(width 0.0889)
		(layer "B.Cu")
		(net "VSENSE_PVCCFA_EHV_FIVRA_CPU1_DN")
	)
	(arc
		(start 102.542594 -289.446462)
		(mid 102.651606 -289.530067)
		(end 102.726744 -289.64509)
		(width 0.0889)
		(layer "B.Cu")
		(net "VSENSE_PVCCFA_EHV_FIVRA_CPU1_DN")
	)
	(arc
		(start 103.948992 -287.613598)
		(mid 103.746169 -287.813829)
		(end 103.666798 -288.087562)
		(width 0.0889)
		(layer "B.Cu")
		(net "VSENSE_PVCCFA_EHV_FIVRA_CPU1_DN")
	)
	(arc
		(start 103.10495 -288.427414)
		(mid 102.547576 -288.422865)
		(end 102.257098 -288.898584)
		(width 0.0889)
		(layer "B.Cu")
		(net "VSENSE_PVCCFA_EHV_FIVRA_CPU1_DN")
	)
	(segment
		(start 83.496912 -350.275906)
		(end 77.141578 -350.275906)
		(width 0.254)
		(layer "In6.Cu")
		(net "VSENSE_PVCCFA_EHV_FIVRA_CPU1_DN")
	)
	(segment
		(start 110.508796 -348.172532)
		(end 98.881438 -348.172532)
		(width 0.254)
		(layer "In6.Cu")
		(net "VSENSE_PVCCFA_EHV_FIVRA_CPU1_DN")
	)
	(segment
		(start 98.881438 -348.172532)
		(end 97.131378 -346.422472)
		(width 0.254)
		(layer "In6.Cu")
		(net "VSENSE_PVCCFA_EHV_FIVRA_CPU1_DN")
	)
	(segment
		(start 116.667534 -353.824286)
		(end 116.91112 -354.067872)
		(width 0.254)
		(layer "In6.Cu")
		(net "VSENSE_PVCCFA_EHV_FIVRA_CPU1_DN")
	)
	(segment
		(start 87.350346 -346.422472)
		(end 83.496912 -350.275906)
		(width 0.254)
		(layer "In6.Cu")
		(net "VSENSE_PVCCFA_EHV_FIVRA_CPU1_DN")
	)
	(segment
		(start 117.276118 -354.067872)
		(end 117.634766 -353.709224)
		(width 0.254)
		(layer "In6.Cu")
		(net "VSENSE_PVCCFA_EHV_FIVRA_CPU1_DN")
	)
	(segment
		(start 114.853212 -352.516948)
		(end 110.508796 -348.172532)
		(width 0.254)
		(layer "In6.Cu")
		(net "VSENSE_PVCCFA_EHV_FIVRA_CPU1_DN")
	)
	(segment
		(start 116.91112 -354.067872)
		(end 117.276118 -354.067872)
		(width 0.254)
		(layer "In6.Cu")
		(net "VSENSE_PVCCFA_EHV_FIVRA_CPU1_DN")
	)
	(segment
		(start 97.131378 -346.422472)
		(end 87.350346 -346.422472)
		(width 0.254)
		(layer "In6.Cu")
		(net "VSENSE_PVCCFA_EHV_FIVRA_CPU1_DN")
	)
	(segment
		(start 117.634766 -352.87966)
		(end 117.272054 -352.516948)
		(width 0.254)
		(layer "In6.Cu")
		(net "VSENSE_PVCCFA_EHV_FIVRA_CPU1_DN")
	)
	(segment
		(start 77.141578 -350.275906)
		(end 76.91247 -350.505014)
		(width 0.254)
		(layer "In6.Cu")
		(net "VSENSE_PVCCFA_EHV_FIVRA_CPU1_DN")
	)
	(segment
		(start 117.272054 -352.516948)
		(end 114.853212 -352.516948)
		(width 0.254)
		(layer "In6.Cu")
		(net "VSENSE_PVCCFA_EHV_FIVRA_CPU1_DN")
	)
	(segment
		(start 117.634766 -353.709224)
		(end 117.634766 -352.87966)
		(width 0.254)
		(layer "In6.Cu")
		(net "VSENSE_PVCCFA_EHV_FIVRA_CPU1_DN")
	)
	(segment
		(start 363.874304 -354.47986)
		(end 363.62005 -354.734114)
		(width 0.254)
		(layer "F.Cu")
		(net "VSENSE_PVCCFA_EHV_FIVRA_CPU0_DP")
	)
	(segment
		(start 364.607348 -354.687886)
		(end 364.399322 -354.47986)
		(width 0.254)
		(layer "F.Cu")
		(net "VSENSE_PVCCFA_EHV_FIVRA_CPU0_DP")
	)
	(segment
		(start 322.329048 -347.546422)
		(end 322.514214 -347.731588)
		(width 0.254)
		(layer "F.Cu")
		(net "VSENSE_PVCCFA_EHV_FIVRA_CPU0_DP")
	)
	(segment
		(start 304.31105 -345.983814)
		(end 304.05578 -346.239084)
		(width 0.254)
		(layer "F.Cu")
		(net "VSENSE_PVCCFA_EHV_FIVRA_CPU0_DP")
	)
	(segment
		(start 322.276978 -345.983814)
		(end 304.31105 -345.983814)
		(width 0.254)
		(layer "F.Cu")
		(net "VSENSE_PVCCFA_EHV_FIVRA_CPU0_DP")
	)
	(segment
		(start 323.31914 -347.43136)
		(end 323.31914 -347.025976)
		(width 0.254)
		(layer "F.Cu")
		(net "VSENSE_PVCCFA_EHV_FIVRA_CPU0_DP")
	)
	(segment
		(start 323.018912 -347.731588)
		(end 323.31914 -347.43136)
		(width 0.254)
		(layer "F.Cu")
		(net "VSENSE_PVCCFA_EHV_FIVRA_CPU0_DP")
	)
	(segment
		(start 363.62005 -354.734114)
		(end 363.62005 -355.236526)
		(width 0.254)
		(layer "F.Cu")
		(net "VSENSE_PVCCFA_EHV_FIVRA_CPU0_DP")
	)
	(segment
		(start 364.399322 -354.47986)
		(end 363.874304 -354.47986)
		(width 0.254)
		(layer "F.Cu")
		(net "VSENSE_PVCCFA_EHV_FIVRA_CPU0_DP")
	)
	(segment
		(start 322.514214 -347.731588)
		(end 323.018912 -347.731588)
		(width 0.254)
		(layer "F.Cu")
		(net "VSENSE_PVCCFA_EHV_FIVRA_CPU0_DP")
	)
	(segment
		(start 351.231962 -284.311598)
		(end 351.231962 -284.847538)
		(width 0.254)
		(layer "F.Cu")
		(net "VSENSE_PVCCFA_EHV_FIVRA_CPU0_DP")
	)
	(segment
		(start 323.31914 -347.025976)
		(end 322.276978 -345.983814)
		(width 0.254)
		(layer "F.Cu")
		(net "VSENSE_PVCCFA_EHV_FIVRA_CPU0_DP")
	)
	(via
		(at 351.231962 -284.847538)
		(size 0.4572)
		(drill 0.2032)
		(layers "F.Cu" "B.Cu")
		(net "VSENSE_PVCCFA_EHV_FIVRA_CPU0_DP")
	)
	(via
		(at 364.607348 -354.687886)
		(size 0.508)
		(drill 0.254)
		(layers "F.Cu" "B.Cu")
		(net "VSENSE_PVCCFA_EHV_FIVRA_CPU0_DP")
	)
	(via
		(at 322.329048 -347.546422)
		(size 0.508)
		(drill 0.254)
		(layers "F.Cu" "B.Cu")
		(net "VSENSE_PVCCFA_EHV_FIVRA_CPU0_DP")
	)
	(segment
		(start 351.984564 -286.799782)
		(end 351.993962 -286.80537)
		(width 0.0889)
		(layer "B.Cu")
		(net "VSENSE_PVCCFA_EHV_FIVRA_CPU0_DP")
	)
	(segment
		(start 351.993962 -286.80537)
		(end 351.996756 -286.806894)
		(width 0.0889)
		(layer "B.Cu")
		(net "VSENSE_PVCCFA_EHV_FIVRA_CPU0_DP")
	)
	(segment
		(start 350.857312 -290.06165)
		(end 350.30537 -290.613592)
		(width 0.0889)
		(layer "B.Cu")
		(net "VSENSE_PVCCFA_EHV_FIVRA_CPU0_DP")
	)
	(segment
		(start 321.250564 -300.493684)
		(end 321.250564 -339.000338)
		(width 0.254)
		(layer "B.Cu")
		(net "VSENSE_PVCCFA_EHV_FIVRA_CPU0_DP")
	)
	(segment
		(start 349.27794 -290.708842)
		(end 349.10776 -290.708842)
		(width 0.0889)
		(layer "B.Cu")
		(net "VSENSE_PVCCFA_EHV_FIVRA_CPU0_DP")
	)
	(segment
		(start 350.857312 -289.60953)
		(end 350.857312 -290.06165)
		(width 0.0889)
		(layer "B.Cu")
		(net "VSENSE_PVCCFA_EHV_FIVRA_CPU0_DP")
	)
	(segment
		(start 321.591432 -347.812106)
		(end 322.063364 -347.812106)
		(width 0.254)
		(layer "B.Cu")
		(net "VSENSE_PVCCFA_EHV_FIVRA_CPU0_DP")
	)
	(segment
		(start 320.735198 -339.515704)
		(end 320.735198 -346.955872)
		(width 0.254)
		(layer "B.Cu")
		(net "VSENSE_PVCCFA_EHV_FIVRA_CPU0_DP")
	)
	(segment
		(start 322.063364 -347.812106)
		(end 322.329048 -347.546422)
		(width 0.254)
		(layer "B.Cu")
		(net "VSENSE_PVCCFA_EHV_FIVRA_CPU0_DP")
	)
	(segment
		(start 351.327212 -285.651448)
		(end 351.327212 -285.661354)
		(width 0.0889)
		(layer "B.Cu")
		(net "VSENSE_PVCCFA_EHV_FIVRA_CPU0_DP")
	)
	(segment
		(start 349.37319 -290.613592)
		(end 349.27794 -290.708842)
		(width 0.0889)
		(layer "B.Cu")
		(net "VSENSE_PVCCFA_EHV_FIVRA_CPU0_DP")
	)
	(segment
		(start 351.797366 -288.103056)
		(end 351.797366 -288.121598)
		(width 0.0889)
		(layer "B.Cu")
		(net "VSENSE_PVCCFA_EHV_FIVRA_CPU0_DP")
	)
	(segment
		(start 350.30537 -290.613592)
		(end 349.37319 -290.613592)
		(width 0.0889)
		(layer "B.Cu")
		(net "VSENSE_PVCCFA_EHV_FIVRA_CPU0_DP")
	)
	(segment
		(start 349.10776 -290.708842)
		(end 331.035406 -290.708842)
		(width 0.254)
		(layer "B.Cu")
		(net "VSENSE_PVCCFA_EHV_FIVRA_CPU0_DP")
	)
	(segment
		(start 351.797366 -286.4612)
		(end 351.797366 -286.48406)
		(width 0.0889)
		(layer "B.Cu")
		(net "VSENSE_PVCCFA_EHV_FIVRA_CPU0_DP")
	)
	(segment
		(start 351.505774 -285.980632)
		(end 351.514664 -285.985712)
		(width 0.0889)
		(layer "B.Cu")
		(net "VSENSE_PVCCFA_EHV_FIVRA_CPU0_DP")
	)
	(segment
		(start 321.250564 -339.000338)
		(end 320.735198 -339.515704)
		(width 0.254)
		(layer "B.Cu")
		(net "VSENSE_PVCCFA_EHV_FIVRA_CPU0_DP")
	)
	(segment
		(start 320.735198 -346.955872)
		(end 321.591432 -347.812106)
		(width 0.254)
		(layer "B.Cu")
		(net "VSENSE_PVCCFA_EHV_FIVRA_CPU0_DP")
	)
	(segment
		(start 351.984818 -287.778698)
		(end 351.975928 -287.783778)
		(width 0.0889)
		(layer "B.Cu")
		(net "VSENSE_PVCCFA_EHV_FIVRA_CPU0_DP")
	)
	(segment
		(start 351.990914 -287.775142)
		(end 351.984818 -287.778698)
		(width 0.0889)
		(layer "B.Cu")
		(net "VSENSE_PVCCFA_EHV_FIVRA_CPU0_DP")
	)
	(segment
		(start 351.231962 -284.847538)
		(end 350.936814 -284.847538)
		(width 0.0889)
		(layer "B.Cu")
		(net "VSENSE_PVCCFA_EHV_FIVRA_CPU0_DP")
	)
	(segment
		(start 350.936814 -284.847538)
		(end 350.864678 -284.919674)
		(width 0.0889)
		(layer "B.Cu")
		(net "VSENSE_PVCCFA_EHV_FIVRA_CPU0_DP")
	)
	(segment
		(start 350.387666 -288.917126)
		(end 350.387666 -289.078416)
		(width 0.0889)
		(layer "B.Cu")
		(net "VSENSE_PVCCFA_EHV_FIVRA_CPU0_DP")
	)
	(segment
		(start 331.035406 -290.708842)
		(end 321.250564 -300.493684)
		(width 0.254)
		(layer "B.Cu")
		(net "VSENSE_PVCCFA_EHV_FIVRA_CPU0_DP")
	)
	(arc
		(start 350.387666 -289.078416)
		(mid 350.462671 -289.193875)
		(end 350.571816 -289.277806)
		(width 0.0889)
		(layer "B.Cu")
		(net "VSENSE_PVCCFA_EHV_FIVRA_CPU0_DP")
	)
	(arc
		(start 350.864678 -284.919674)
		(mid 350.927371 -285.065325)
		(end 351.044764 -285.171896)
		(width 0.0889)
		(layer "B.Cu")
		(net "VSENSE_PVCCFA_EHV_FIVRA_CPU0_DP")
	)
	(arc
		(start 352.267266 -287.28924)
		(mid 352.19335 -287.568742)
		(end 351.990914 -287.775142)
		(width 0.0889)
		(layer "B.Cu")
		(net "VSENSE_PVCCFA_EHV_FIVRA_CPU0_DP")
	)
	(arc
		(start 351.514664 -285.985712)
		(mid 351.718145 -286.186516)
		(end 351.797366 -286.4612)
		(width 0.0889)
		(layer "B.Cu")
		(net "VSENSE_PVCCFA_EHV_FIVRA_CPU0_DP")
	)
	(arc
		(start 351.797366 -288.121598)
		(mid 351.506888 -288.597317)
		(end 350.949514 -288.592768)
		(width 0.0889)
		(layer "B.Cu")
		(net "VSENSE_PVCCFA_EHV_FIVRA_CPU0_DP")
	)
	(arc
		(start 350.949514 -288.592768)
		(mid 350.575039 -288.592814)
		(end 350.387666 -288.917126)
		(width 0.0889)
		(layer "B.Cu")
		(net "VSENSE_PVCCFA_EHV_FIVRA_CPU0_DP")
	)
	(arc
		(start 351.797366 -286.48406)
		(mid 351.849636 -286.666425)
		(end 351.984564 -286.799782)
		(width 0.0889)
		(layer "B.Cu")
		(net "VSENSE_PVCCFA_EHV_FIVRA_CPU0_DP")
	)
	(arc
		(start 350.571816 -289.277806)
		(mid 350.745948 -289.416653)
		(end 350.857312 -289.60953)
		(width 0.0889)
		(layer "B.Cu")
		(net "VSENSE_PVCCFA_EHV_FIVRA_CPU0_DP")
	)
	(arc
		(start 351.327212 -285.661354)
		(mid 351.374891 -285.844254)
		(end 351.505774 -285.980632)
		(width 0.0889)
		(layer "B.Cu")
		(net "VSENSE_PVCCFA_EHV_FIVRA_CPU0_DP")
	)
	(arc
		(start 351.975928 -287.783778)
		(mid 351.845014 -287.920138)
		(end 351.797366 -288.103056)
		(width 0.0889)
		(layer "B.Cu")
		(net "VSENSE_PVCCFA_EHV_FIVRA_CPU0_DP")
	)
	(arc
		(start 351.044764 -285.171896)
		(mid 351.249099 -285.374501)
		(end 351.327212 -285.651448)
		(width 0.0889)
		(layer "B.Cu")
		(net "VSENSE_PVCCFA_EHV_FIVRA_CPU0_DP")
	)
	(arc
		(start 351.996756 -286.806894)
		(mid 352.194984 -287.012742)
		(end 352.267266 -287.28924)
		(width 0.0889)
		(layer "B.Cu")
		(net "VSENSE_PVCCFA_EHV_FIVRA_CPU0_DP")
	)
	(segment
		(start 362.712 -351.119948)
		(end 362.712 -349.524828)
		(width 0.254)
		(layer "In4.Cu")
		(net "VSENSE_PVCCFA_EHV_FIVRA_CPU0_DP")
	)
	(segment
		(start 322.603114 -347.820488)
		(end 322.329048 -347.546422)
		(width 0.254)
		(layer "In4.Cu")
		(net "VSENSE_PVCCFA_EHV_FIVRA_CPU0_DP")
	)
	(segment
		(start 364.607348 -354.687886)
		(end 364.804706 -354.490528)
		(width 0.254)
		(layer "In4.Cu")
		(net "VSENSE_PVCCFA_EHV_FIVRA_CPU0_DP")
	)
	(segment
		(start 363.474 -351.881948)
		(end 362.712 -351.119948)
		(width 0.254)
		(layer "In4.Cu")
		(net "VSENSE_PVCCFA_EHV_FIVRA_CPU0_DP")
	)
	(segment
		(start 326.43064 -349.974408)
		(end 324.27672 -347.820488)
		(width 0.254)
		(layer "In4.Cu")
		(net "VSENSE_PVCCFA_EHV_FIVRA_CPU0_DP")
	)
	(segment
		(start 365.3917 -354.490528)
		(end 366.06734 -353.814888)
		(width 0.254)
		(layer "In4.Cu")
		(net "VSENSE_PVCCFA_EHV_FIVRA_CPU0_DP")
	)
	(segment
		(start 336.56016 -346.700348)
		(end 333.2861 -349.974408)
		(width 0.254)
		(layer "In4.Cu")
		(net "VSENSE_PVCCFA_EHV_FIVRA_CPU0_DP")
	)
	(segment
		(start 366.06734 -353.814888)
		(end 366.06734 -352.880168)
		(width 0.254)
		(layer "In4.Cu")
		(net "VSENSE_PVCCFA_EHV_FIVRA_CPU0_DP")
	)
	(segment
		(start 359.88752 -346.700348)
		(end 336.56016 -346.700348)
		(width 0.254)
		(layer "In4.Cu")
		(net "VSENSE_PVCCFA_EHV_FIVRA_CPU0_DP")
	)
	(segment
		(start 364.804706 -354.490528)
		(end 365.3917 -354.490528)
		(width 0.254)
		(layer "In4.Cu")
		(net "VSENSE_PVCCFA_EHV_FIVRA_CPU0_DP")
	)
	(segment
		(start 365.06912 -351.881948)
		(end 363.474 -351.881948)
		(width 0.254)
		(layer "In4.Cu")
		(net "VSENSE_PVCCFA_EHV_FIVRA_CPU0_DP")
	)
	(segment
		(start 362.712 -349.524828)
		(end 359.88752 -346.700348)
		(width 0.254)
		(layer "In4.Cu")
		(net "VSENSE_PVCCFA_EHV_FIVRA_CPU0_DP")
	)
	(segment
		(start 366.06734 -352.880168)
		(end 365.06912 -351.881948)
		(width 0.254)
		(layer "In4.Cu")
		(net "VSENSE_PVCCFA_EHV_FIVRA_CPU0_DP")
	)
	(segment
		(start 324.27672 -347.820488)
		(end 322.603114 -347.820488)
		(width 0.254)
		(layer "In4.Cu")
		(net "VSENSE_PVCCFA_EHV_FIVRA_CPU0_DP")
	)
	(segment
		(start 333.2861 -349.974408)
		(end 326.43064 -349.974408)
		(width 0.254)
		(layer "In4.Cu")
		(net "VSENSE_PVCCFA_EHV_FIVRA_CPU0_DP")
	)
	(segment
		(start 304.31105 -345.602814)
		(end 304.05578 -345.347544)
		(width 0.254)
		(layer "F.Cu")
		(net "VSENSE_PVCCFA_EHV_FIVRA_CPU0_DN")
	)
	(segment
		(start 363.069124 -353.532948)
		(end 363.29747 -353.761294)
		(width 0.254)
		(layer "F.Cu")
		(net "VSENSE_PVCCFA_EHV_FIVRA_CPU0_DN")
	)
	(segment
		(start 360.281474 -356.324408)
		(end 361.27944 -355.326442)
		(width 0.1778)
		(layer "F.Cu")
		(net "VSENSE_PVCCFA_EHV_FIVRA_CPU0_DN")
	)
	(segment
		(start 360.281474 -356.82428)
		(end 360.281474 -356.324408)
		(width 0.1778)
		(layer "F.Cu")
		(net "VSENSE_PVCCFA_EHV_FIVRA_CPU0_DN")
	)
	(segment
		(start 360.169714 -357.094028)
		(end 360.281474 -356.82428)
		(width 0.1778)
		(layer "F.Cu")
		(net "VSENSE_PVCCFA_EHV_FIVRA_CPU0_DN")
	)
	(segment
		(start 323.1769 -348.112588)
		(end 323.70014 -347.589348)
		(width 0.254)
		(layer "F.Cu")
		(net "VSENSE_PVCCFA_EHV_FIVRA_CPU0_DN")
	)
	(segment
		(start 361.27944 -353.990402)
		(end 361.736894 -353.532948)
		(width 0.1778)
		(layer "F.Cu")
		(net "VSENSE_PVCCFA_EHV_FIVRA_CPU0_DN")
	)
	(segment
		(start 323.70014 -347.589348)
		(end 323.70014 -346.867988)
		(width 0.254)
		(layer "F.Cu")
		(net "VSENSE_PVCCFA_EHV_FIVRA_CPU0_DN")
	)
	(segment
		(start 363.29747 -353.761294)
		(end 363.29747 -354.065586)
		(width 0.254)
		(layer "F.Cu")
		(net "VSENSE_PVCCFA_EHV_FIVRA_CPU0_DN")
	)
	(segment
		(start 323.70014 -346.867988)
		(end 322.434966 -345.602814)
		(width 0.254)
		(layer "F.Cu")
		(net "VSENSE_PVCCFA_EHV_FIVRA_CPU0_DN")
	)
	(segment
		(start 349.352362 -284.847284)
		(end 349.352616 -284.847538)
		(width 0.12954)
		(layer "F.Cu")
		(net "VSENSE_PVCCFA_EHV_FIVRA_CPU0_DN")
	)
	(segment
		(start 361.27944 -355.326442)
		(end 361.27944 -353.990402)
		(width 0.1778)
		(layer "F.Cu")
		(net "VSENSE_PVCCFA_EHV_FIVRA_CPU0_DN")
	)
	(segment
		(start 364.607348 -353.824286)
		(end 364.366048 -354.065586)
		(width 0.254)
		(layer "F.Cu")
		(net "VSENSE_PVCCFA_EHV_FIVRA_CPU0_DN")
	)
	(segment
		(start 364.366048 -354.065586)
		(end 363.29747 -354.065586)
		(width 0.254)
		(layer "F.Cu")
		(net "VSENSE_PVCCFA_EHV_FIVRA_CPU0_DN")
	)
	(segment
		(start 359.393236 -357.448358)
		(end 359.815384 -357.448358)
		(width 0.1778)
		(layer "F.Cu")
		(net "VSENSE_PVCCFA_EHV_FIVRA_CPU0_DN")
	)
	(segment
		(start 322.626482 -348.112588)
		(end 323.1769 -348.112588)
		(width 0.254)
		(layer "F.Cu")
		(net "VSENSE_PVCCFA_EHV_FIVRA_CPU0_DN")
	)
	(segment
		(start 349.352362 -284.311598)
		(end 349.352362 -284.847284)
		(width 0.12954)
		(layer "F.Cu")
		(net "VSENSE_PVCCFA_EHV_FIVRA_CPU0_DN")
	)
	(segment
		(start 361.736894 -353.532948)
		(end 363.069124 -353.532948)
		(width 0.254)
		(layer "F.Cu")
		(net "VSENSE_PVCCFA_EHV_FIVRA_CPU0_DN")
	)
	(segment
		(start 322.329048 -348.410022)
		(end 322.626482 -348.112588)
		(width 0.254)
		(layer "F.Cu")
		(net "VSENSE_PVCCFA_EHV_FIVRA_CPU0_DN")
	)
	(segment
		(start 359.815384 -357.448358)
		(end 360.169714 -357.094028)
		(width 0.1778)
		(layer "F.Cu")
		(net "VSENSE_PVCCFA_EHV_FIVRA_CPU0_DN")
	)
	(segment
		(start 322.434966 -345.602814)
		(end 304.31105 -345.602814)
		(width 0.254)
		(layer "F.Cu")
		(net "VSENSE_PVCCFA_EHV_FIVRA_CPU0_DN")
	)
	(via
		(at 364.607348 -353.824286)
		(size 0.508)
		(drill 0.254)
		(layers "F.Cu" "B.Cu")
		(net "VSENSE_PVCCFA_EHV_FIVRA_CPU0_DN")
	)
	(via
		(at 349.352616 -284.847538)
		(size 0.4572)
		(drill 0.2032)
		(layers "F.Cu" "B.Cu")
		(net "VSENSE_PVCCFA_EHV_FIVRA_CPU0_DN")
	)
	(via
		(at 322.329048 -348.410022)
		(size 0.508)
		(drill 0.254)
		(layers "F.Cu" "B.Cu")
		(net "VSENSE_PVCCFA_EHV_FIVRA_CPU0_DN")
	)
	(segment
		(start 351.136712 -285.675578)
		(end 351.136712 -285.661354)
		(width 0.0889)
		(layer "B.Cu")
		(net "VSENSE_PVCCFA_EHV_FIVRA_CPU0_DN")
	)
	(segment
		(start 350.527112 -284.44063)
		(end 350.51365 -284.432756)
		(width 0.0889)
		(layer "B.Cu")
		(net "VSENSE_PVCCFA_EHV_FIVRA_CPU0_DN")
	)
	(segment
		(start 350.527366 -284.44063)
		(end 350.527112 -284.44063)
		(width 0.0889)
		(layer "B.Cu")
		(net "VSENSE_PVCCFA_EHV_FIVRA_CPU0_DN")
	)
	(segment
		(start 320.869564 -300.335696)
		(end 330.877418 -290.327842)
		(width 0.254)
		(layer "B.Cu")
		(net "VSENSE_PVCCFA_EHV_FIVRA_CPU0_DN")
	)
	(segment
		(start 349.286068 -290.327842)
		(end 349.381318 -290.423092)
		(width 0.0889)
		(layer "B.Cu")
		(net "VSENSE_PVCCFA_EHV_FIVRA_CPU0_DN")
	)
	(segment
		(start 350.226376 -290.423092)
		(end 350.666812 -289.982656)
		(width 0.0889)
		(layer "B.Cu")
		(net "VSENSE_PVCCFA_EHV_FIVRA_CPU0_DN")
	)
	(segment
		(start 351.89795 -286.969962)
		(end 351.88906 -286.964882)
		(width 0.0889)
		(layer "B.Cu")
		(net "VSENSE_PVCCFA_EHV_FIVRA_CPU0_DN")
	)
	(segment
		(start 320.354198 -339.357716)
		(end 320.869564 -338.84235)
		(width 0.254)
		(layer "B.Cu")
		(net "VSENSE_PVCCFA_EHV_FIVRA_CPU0_DN")
	)
	(segment
		(start 321.433444 -348.193106)
		(end 320.354198 -347.11386)
		(width 0.254)
		(layer "B.Cu")
		(net "VSENSE_PVCCFA_EHV_FIVRA_CPU0_DN")
	)
	(segment
		(start 351.606866 -288.103056)
		(end 351.606866 -288.087562)
		(width 0.0889)
		(layer "B.Cu")
		(net "VSENSE_PVCCFA_EHV_FIVRA_CPU0_DN")
	)
	(segment
		(start 351.88906 -287.613598)
		(end 351.890076 -287.61309)
		(width 0.0889)
		(layer "B.Cu")
		(net "VSENSE_PVCCFA_EHV_FIVRA_CPU0_DN")
	)
	(segment
		(start 349.10776 -290.327842)
		(end 349.286068 -290.327842)
		(width 0.0889)
		(layer "B.Cu")
		(net "VSENSE_PVCCFA_EHV_FIVRA_CPU0_DN")
	)
	(segment
		(start 350.197166 -289.114738)
		(end 350.197166 -288.898584)
		(width 0.0889)
		(layer "B.Cu")
		(net "VSENSE_PVCCFA_EHV_FIVRA_CPU0_DN")
	)
	(segment
		(start 320.869564 -338.84235)
		(end 320.869564 -300.335696)
		(width 0.254)
		(layer "B.Cu")
		(net "VSENSE_PVCCFA_EHV_FIVRA_CPU0_DN")
	)
	(segment
		(start 350.057212 -284.44063)
		(end 349.352616 -284.847538)
		(width 0.0889)
		(layer "B.Cu")
		(net "VSENSE_PVCCFA_EHV_FIVRA_CPU0_DN")
	)
	(segment
		(start 320.354198 -347.11386)
		(end 320.354198 -339.357716)
		(width 0.254)
		(layer "B.Cu")
		(net "VSENSE_PVCCFA_EHV_FIVRA_CPU0_DN")
	)
	(segment
		(start 351.606612 -286.48533)
		(end 351.606612 -286.466788)
		(width 0.0889)
		(layer "B.Cu")
		(net "VSENSE_PVCCFA_EHV_FIVRA_CPU0_DN")
	)
	(segment
		(start 350.666812 -289.982656)
		(end 350.666812 -289.64509)
		(width 0.0889)
		(layer "B.Cu")
		(net "VSENSE_PVCCFA_EHV_FIVRA_CPU0_DN")
	)
	(segment
		(start 322.329048 -348.410022)
		(end 322.112132 -348.193106)
		(width 0.254)
		(layer "B.Cu")
		(net "VSENSE_PVCCFA_EHV_FIVRA_CPU0_DN")
	)
	(segment
		(start 330.877418 -290.327842)
		(end 349.10776 -290.327842)
		(width 0.254)
		(layer "B.Cu")
		(net "VSENSE_PVCCFA_EHV_FIVRA_CPU0_DN")
	)
	(segment
		(start 349.381318 -290.423092)
		(end 350.226376 -290.423092)
		(width 0.0889)
		(layer "B.Cu")
		(net "VSENSE_PVCCFA_EHV_FIVRA_CPU0_DN")
	)
	(segment
		(start 322.112132 -348.193106)
		(end 321.433444 -348.193106)
		(width 0.254)
		(layer "B.Cu")
		(net "VSENSE_PVCCFA_EHV_FIVRA_CPU0_DN")
	)
	(segment
		(start 350.95815 -285.342076)
		(end 350.94926 -285.336996)
		(width 0.0889)
		(layer "B.Cu")
		(net "VSENSE_PVCCFA_EHV_FIVRA_CPU0_DN")
	)
	(segment
		(start 350.666812 -284.847792)
		(end 350.666812 -284.682184)
		(width 0.0889)
		(layer "B.Cu")
		(net "VSENSE_PVCCFA_EHV_FIVRA_CPU0_DN")
	)
	(segment
		(start 351.890076 -287.61309)
		(end 351.89795 -287.608518)
		(width 0.0889)
		(layer "B.Cu")
		(net "VSENSE_PVCCFA_EHV_FIVRA_CPU0_DN")
	)
	(arc
		(start 351.89795 -287.608518)
		(mid 352.076547 -287.28924)
		(end 351.89795 -286.969962)
		(width 0.0889)
		(layer "B.Cu")
		(net "VSENSE_PVCCFA_EHV_FIVRA_CPU0_DN")
	)
	(arc
		(start 350.677226 -284.95625)
		(mid 350.6694 -284.902273)
		(end 350.666812 -284.847792)
		(width 0.0889)
		(layer "B.Cu")
		(net "VSENSE_PVCCFA_EHV_FIVRA_CPU0_DN")
	)
	(arc
		(start 351.606866 -288.087562)
		(mid 351.686236 -287.813828)
		(end 351.88906 -287.613598)
		(width 0.0889)
		(layer "B.Cu")
		(net "VSENSE_PVCCFA_EHV_FIVRA_CPU0_DN")
	)
	(arc
		(start 350.666812 -284.682184)
		(mid 350.629444 -284.542732)
		(end 350.527366 -284.44063)
		(width 0.0889)
		(layer "B.Cu")
		(net "VSENSE_PVCCFA_EHV_FIVRA_CPU0_DN")
	)
	(arc
		(start 351.136712 -285.661354)
		(mid 351.089033 -285.478454)
		(end 350.95815 -285.342076)
		(width 0.0889)
		(layer "B.Cu")
		(net "VSENSE_PVCCFA_EHV_FIVRA_CPU0_DN")
	)
	(arc
		(start 350.51365 -284.432756)
		(mid 350.284397 -284.377512)
		(end 350.057212 -284.44063)
		(width 0.0889)
		(layer "B.Cu")
		(net "VSENSE_PVCCFA_EHV_FIVRA_CPU0_DN")
	)
	(arc
		(start 350.197166 -288.898584)
		(mid 350.487644 -288.422865)
		(end 351.045018 -288.427414)
		(width 0.0889)
		(layer "B.Cu")
		(net "VSENSE_PVCCFA_EHV_FIVRA_CPU0_DN")
	)
	(arc
		(start 350.666812 -289.64509)
		(mid 350.591718 -289.530026)
		(end 350.482662 -289.446462)
		(width 0.0889)
		(layer "B.Cu")
		(net "VSENSE_PVCCFA_EHV_FIVRA_CPU0_DN")
	)
	(arc
		(start 350.94926 -285.336996)
		(mid 350.771944 -285.176128)
		(end 350.677226 -284.95625)
		(width 0.0889)
		(layer "B.Cu")
		(net "VSENSE_PVCCFA_EHV_FIVRA_CPU0_DN")
	)
	(arc
		(start 350.482662 -289.446462)
		(mid 350.30853 -289.307615)
		(end 350.197166 -289.114738)
		(width 0.0889)
		(layer "B.Cu")
		(net "VSENSE_PVCCFA_EHV_FIVRA_CPU0_DN")
	)
	(arc
		(start 351.045018 -288.427414)
		(mid 351.419493 -288.427368)
		(end 351.606866 -288.103056)
		(width 0.0889)
		(layer "B.Cu")
		(net "VSENSE_PVCCFA_EHV_FIVRA_CPU0_DN")
	)
	(arc
		(start 351.606612 -286.466788)
		(mid 351.554342 -286.284423)
		(end 351.419414 -286.151066)
		(width 0.0889)
		(layer "B.Cu")
		(net "VSENSE_PVCCFA_EHV_FIVRA_CPU0_DN")
	)
	(arc
		(start 351.419414 -286.151066)
		(mid 351.215933 -285.950262)
		(end 351.136712 -285.675578)
		(width 0.0889)
		(layer "B.Cu")
		(net "VSENSE_PVCCFA_EHV_FIVRA_CPU0_DN")
	)
	(arc
		(start 351.88906 -286.964882)
		(mid 351.684725 -286.762277)
		(end 351.606612 -286.48533)
		(width 0.0889)
		(layer "B.Cu")
		(net "VSENSE_PVCCFA_EHV_FIVRA_CPU0_DN")
	)
	(segment
		(start 365.68634 -353.038156)
		(end 364.911132 -352.262948)
		(width 0.254)
		(layer "In4.Cu")
		(net "VSENSE_PVCCFA_EHV_FIVRA_CPU0_DN")
	)
	(segment
		(start 364.911132 -352.262948)
		(end 363.316012 -352.262948)
		(width 0.254)
		(layer "In4.Cu")
		(net "VSENSE_PVCCFA_EHV_FIVRA_CPU0_DN")
	)
	(segment
		(start 364.89259 -354.109528)
		(end 365.233712 -354.109528)
		(width 0.254)
		(layer "In4.Cu")
		(net "VSENSE_PVCCFA_EHV_FIVRA_CPU0_DN")
	)
	(segment
		(start 365.233712 -354.109528)
		(end 365.68634 -353.6569)
		(width 0.254)
		(layer "In4.Cu")
		(net "VSENSE_PVCCFA_EHV_FIVRA_CPU0_DN")
	)
	(segment
		(start 322.537582 -348.201488)
		(end 322.329048 -348.410022)
		(width 0.254)
		(layer "In4.Cu")
		(net "VSENSE_PVCCFA_EHV_FIVRA_CPU0_DN")
	)
	(segment
		(start 359.729532 -347.081348)
		(end 336.718148 -347.081348)
		(width 0.254)
		(layer "In4.Cu")
		(net "VSENSE_PVCCFA_EHV_FIVRA_CPU0_DN")
	)
	(segment
		(start 363.316012 -352.262948)
		(end 362.331 -351.277936)
		(width 0.254)
		(layer "In4.Cu")
		(net "VSENSE_PVCCFA_EHV_FIVRA_CPU0_DN")
	)
	(segment
		(start 362.331 -351.277936)
		(end 362.331 -349.682816)
		(width 0.254)
		(layer "In4.Cu")
		(net "VSENSE_PVCCFA_EHV_FIVRA_CPU0_DN")
	)
	(segment
		(start 333.444088 -350.355408)
		(end 326.272652 -350.355408)
		(width 0.254)
		(layer "In4.Cu")
		(net "VSENSE_PVCCFA_EHV_FIVRA_CPU0_DN")
	)
	(segment
		(start 365.68634 -353.6569)
		(end 365.68634 -353.038156)
		(width 0.254)
		(layer "In4.Cu")
		(net "VSENSE_PVCCFA_EHV_FIVRA_CPU0_DN")
	)
	(segment
		(start 324.118732 -348.201488)
		(end 322.537582 -348.201488)
		(width 0.254)
		(layer "In4.Cu")
		(net "VSENSE_PVCCFA_EHV_FIVRA_CPU0_DN")
	)
	(segment
		(start 336.718148 -347.081348)
		(end 333.444088 -350.355408)
		(width 0.254)
		(layer "In4.Cu")
		(net "VSENSE_PVCCFA_EHV_FIVRA_CPU0_DN")
	)
	(segment
		(start 326.272652 -350.355408)
		(end 324.118732 -348.201488)
		(width 0.254)
		(layer "In4.Cu")
		(net "VSENSE_PVCCFA_EHV_FIVRA_CPU0_DN")
	)
	(segment
		(start 362.331 -349.682816)
		(end 359.729532 -347.081348)
		(width 0.254)
		(layer "In4.Cu")
		(net "VSENSE_PVCCFA_EHV_FIVRA_CPU0_DN")
	)
	(segment
		(start 364.607348 -353.824286)
		(end 364.89259 -354.109528)
		(width 0.254)
		(layer "In4.Cu")
		(net "VSENSE_PVCCFA_EHV_FIVRA_CPU0_DN")
	)
	(segment
		(start 74.607166 -174.242984)
		(end 74.141076 -174.242984)
		(width 0.254)
		(layer "F.Cu")
		(net "VSENSE_PVCCFA_EHV_CPU1_DP")
	)
	(segment
		(start 28.547822 -134.46252)
		(end 29.086302 -135.001)
		(width 0.254)
		(layer "F.Cu")
		(net "VSENSE_PVCCFA_EHV_CPU1_DP")
	)
	(segment
		(start 74.141076 -174.242984)
		(end 73.906126 -174.008034)
		(width 0.254)
		(layer "F.Cu")
		(net "VSENSE_PVCCFA_EHV_CPU1_DP")
	)
	(segment
		(start 28.547822 -134.159752)
		(end 28.547822 -134.46252)
		(width 0.254)
		(layer "F.Cu")
		(net "VSENSE_PVCCFA_EHV_CPU1_DP")
	)
	(segment
		(start 101.772466 -222.48368)
		(end 101.772466 -221.947994)
		(width 0.2032)
		(layer "F.Cu")
		(net "VSENSE_PVCCFA_EHV_CPU1_DP")
	)
	(segment
		(start 101.772466 -221.947994)
		(end 101.772212 -221.94774)
		(width 0.2032)
		(layer "F.Cu")
		(net "VSENSE_PVCCFA_EHV_CPU1_DP")
	)
	(segment
		(start 74.848466 -174.001684)
		(end 74.607166 -174.242984)
		(width 0.254)
		(layer "F.Cu")
		(net "VSENSE_PVCCFA_EHV_CPU1_DP")
	)
	(via
		(at 74.848466 -174.001684)
		(size 0.508)
		(drill 0.254)
		(layers "F.Cu" "B.Cu")
		(net "VSENSE_PVCCFA_EHV_CPU1_DP")
	)
	(via
		(at 101.772212 -221.94774)
		(size 0.4572)
		(drill 0.2032)
		(layers "F.Cu" "B.Cu")
		(net "VSENSE_PVCCFA_EHV_CPU1_DP")
	)
	(via
		(at 88.57742 -185.851292)
		(size 0.508)
		(drill 0.254)
		(layers "F.Cu" "B.Cu")
		(net "VSENSE_PVCCFA_EHV_CPU1_DP")
	)
	(via
		(at 28.547822 -134.159752)
		(size 0.508)
		(drill 0.254)
		(layers "F.Cu" "B.Cu")
		(net "VSENSE_PVCCFA_EHV_CPU1_DP")
	)
	(segment
		(start 101.772212 -221.94774)
		(end 102.084886 -221.94774)
		(width 0.0889)
		(layer "B.Cu")
		(net "VSENSE_PVCCFA_EHV_CPU1_DP")
	)
	(segment
		(start 95.006414 -222.272098)
		(end 94.991682 -222.263462)
		(width 0.0889)
		(layer "B.Cu")
		(net "VSENSE_PVCCFA_EHV_CPU1_DP")
	)
	(segment
		(start 96.886014 -222.272098)
		(end 96.871282 -222.263462)
		(width 0.0889)
		(layer "B.Cu")
		(net "VSENSE_PVCCFA_EHV_CPU1_DP")
	)
	(segment
		(start 88.821768 -186.09564)
		(end 88.57742 -185.851292)
		(width 0.254)
		(layer "B.Cu")
		(net "VSENSE_PVCCFA_EHV_CPU1_DP")
	)
	(segment
		(start 83.979258 -218.481656)
		(end 83.979258 -210.34629)
		(width 0.254)
		(layer "B.Cu")
		(net "VSENSE_PVCCFA_EHV_CPU1_DP")
	)
	(segment
		(start 102.084886 -221.94774)
		(end 102.14229 -222.005144)
		(width 0.0889)
		(layer "B.Cu")
		(net "VSENSE_PVCCFA_EHV_CPU1_DP")
	)
	(segment
		(start 101.585014 -222.272098)
		(end 101.570282 -222.263462)
		(width 0.0889)
		(layer "B.Cu")
		(net "VSENSE_PVCCFA_EHV_CPU1_DP")
	)
	(segment
		(start 86.378288 -220.88094)
		(end 86.378288 -220.880686)
		(width 0.254)
		(layer "B.Cu")
		(net "VSENSE_PVCCFA_EHV_CPU1_DP")
	)
	(segment
		(start 100.645214 -222.272098)
		(end 100.630482 -222.263462)
		(width 0.0889)
		(layer "B.Cu")
		(net "VSENSE_PVCCFA_EHV_CPU1_DP")
	)
	(segment
		(start 91.247214 -222.272098)
		(end 91.232482 -222.263462)
		(width 0.0889)
		(layer "B.Cu")
		(net "VSENSE_PVCCFA_EHV_CPU1_DP")
	)
	(segment
		(start 87.676228 -221.38259)
		(end 86.739222 -221.38259)
		(width 0.0889)
		(layer "B.Cu")
		(net "VSENSE_PVCCFA_EHV_CPU1_DP")
	)
	(segment
		(start 89.180416 -221.956376)
		(end 89.180416 -221.937834)
		(width 0.0889)
		(layer "B.Cu")
		(net "VSENSE_PVCCFA_EHV_CPU1_DP")
	)
	(segment
		(start 94.066614 -222.272098)
		(end 94.051882 -222.263462)
		(width 0.0889)
		(layer "B.Cu")
		(net "VSENSE_PVCCFA_EHV_CPU1_DP")
	)
	(segment
		(start 89.602818 -200.471024)
		(end 89.602818 -192.370456)
		(width 0.254)
		(layer "B.Cu")
		(net "VSENSE_PVCCFA_EHV_CPU1_DP")
	)
	(segment
		(start 86.316058 -203.757784)
		(end 89.602818 -200.471024)
		(width 0.254)
		(layer "B.Cu")
		(net "VSENSE_PVCCFA_EHV_CPU1_DP")
	)
	(segment
		(start 97.825814 -222.272098)
		(end 97.811082 -222.263462)
		(width 0.0889)
		(layer "B.Cu")
		(net "VSENSE_PVCCFA_EHV_CPU1_DP")
	)
	(segment
		(start 89.742518 -186.572652)
		(end 89.265506 -186.09564)
		(width 0.254)
		(layer "B.Cu")
		(net "VSENSE_PVCCFA_EHV_CPU1_DP")
	)
	(segment
		(start 86.316058 -208.00949)
		(end 86.316058 -203.757784)
		(width 0.254)
		(layer "B.Cu")
		(net "VSENSE_PVCCFA_EHV_CPU1_DP")
	)
	(segment
		(start 86.378288 -220.880686)
		(end 83.979258 -218.481656)
		(width 0.254)
		(layer "B.Cu")
		(net "VSENSE_PVCCFA_EHV_CPU1_DP")
	)
	(segment
		(start 86.468204 -220.970856)
		(end 86.378288 -220.88094)
		(width 0.254)
		(layer "B.Cu")
		(net "VSENSE_PVCCFA_EHV_CPU1_DP")
	)
	(segment
		(start 86.739222 -221.38259)
		(end 86.468204 -221.111572)
		(width 0.0889)
		(layer "B.Cu")
		(net "VSENSE_PVCCFA_EHV_CPU1_DP")
	)
	(segment
		(start 89.742518 -192.230756)
		(end 89.742518 -186.572652)
		(width 0.254)
		(layer "B.Cu")
		(net "VSENSE_PVCCFA_EHV_CPU1_DP")
	)
	(segment
		(start 101.9683 -222.267018)
		(end 101.95941 -222.272098)
		(width 0.0889)
		(layer "B.Cu")
		(net "VSENSE_PVCCFA_EHV_CPU1_DP")
	)
	(segment
		(start 98.765614 -222.272098)
		(end 98.750882 -222.263462)
		(width 0.0889)
		(layer "B.Cu")
		(net "VSENSE_PVCCFA_EHV_CPU1_DP")
	)
	(segment
		(start 92.187014 -222.272098)
		(end 92.172282 -222.263462)
		(width 0.0889)
		(layer "B.Cu")
		(net "VSENSE_PVCCFA_EHV_CPU1_DP")
	)
	(segment
		(start 90.307414 -222.272098)
		(end 90.292682 -222.263462)
		(width 0.0889)
		(layer "B.Cu")
		(net "VSENSE_PVCCFA_EHV_CPU1_DP")
	)
	(segment
		(start 86.468204 -221.111572)
		(end 86.468204 -220.970856)
		(width 0.0889)
		(layer "B.Cu")
		(net "VSENSE_PVCCFA_EHV_CPU1_DP")
	)
	(segment
		(start 99.705414 -222.272098)
		(end 99.690682 -222.263462)
		(width 0.0889)
		(layer "B.Cu")
		(net "VSENSE_PVCCFA_EHV_CPU1_DP")
	)
	(segment
		(start 89.602818 -192.370456)
		(end 89.742518 -192.230756)
		(width 0.254)
		(layer "B.Cu")
		(net "VSENSE_PVCCFA_EHV_CPU1_DP")
	)
	(segment
		(start 83.979258 -210.34629)
		(end 86.316058 -208.00949)
		(width 0.254)
		(layer "B.Cu")
		(net "VSENSE_PVCCFA_EHV_CPU1_DP")
	)
	(segment
		(start 95.946214 -222.272098)
		(end 95.931482 -222.263462)
		(width 0.0889)
		(layer "B.Cu")
		(net "VSENSE_PVCCFA_EHV_CPU1_DP")
	)
	(segment
		(start 89.265506 -186.09564)
		(end 88.821768 -186.09564)
		(width 0.254)
		(layer "B.Cu")
		(net "VSENSE_PVCCFA_EHV_CPU1_DP")
	)
	(segment
		(start 93.126814 -222.272098)
		(end 93.112082 -222.263462)
		(width 0.0889)
		(layer "B.Cu")
		(net "VSENSE_PVCCFA_EHV_CPU1_DP")
	)
	(arc
		(start 88.332564 -221.458282)
		(mid 88.145366 -221.508425)
		(end 87.958168 -221.458282)
		(width 0.0889)
		(layer "B.Cu")
		(net "VSENSE_PVCCFA_EHV_CPU1_DP")
	)
	(arc
		(start 92.56141 -222.272098)
		(mid 92.374212 -222.322241)
		(end 92.187014 -222.272098)
		(width 0.0889)
		(layer "B.Cu")
		(net "VSENSE_PVCCFA_EHV_CPU1_DP")
	)
	(arc
		(start 92.172282 -222.263462)
		(mid 91.895807 -222.196142)
		(end 91.62161 -222.272098)
		(width 0.0889)
		(layer "B.Cu")
		(net "VSENSE_PVCCFA_EHV_CPU1_DP")
	)
	(arc
		(start 98.20021 -222.272098)
		(mid 98.013012 -222.322241)
		(end 97.825814 -222.272098)
		(width 0.0889)
		(layer "B.Cu")
		(net "VSENSE_PVCCFA_EHV_CPU1_DP")
	)
	(arc
		(start 88.897968 -221.458282)
		(mid 88.615266 -221.382506)
		(end 88.332564 -221.458282)
		(width 0.0889)
		(layer "B.Cu")
		(net "VSENSE_PVCCFA_EHV_CPU1_DP")
	)
	(arc
		(start 98.750882 -222.263462)
		(mid 98.474407 -222.196142)
		(end 98.20021 -222.272098)
		(width 0.0889)
		(layer "B.Cu")
		(net "VSENSE_PVCCFA_EHV_CPU1_DP")
	)
	(arc
		(start 93.50121 -222.272098)
		(mid 93.314012 -222.322241)
		(end 93.126814 -222.272098)
		(width 0.0889)
		(layer "B.Cu")
		(net "VSENSE_PVCCFA_EHV_CPU1_DP")
	)
	(arc
		(start 89.74201 -222.272098)
		(mid 89.554812 -222.322241)
		(end 89.367614 -222.272098)
		(width 0.0889)
		(layer "B.Cu")
		(net "VSENSE_PVCCFA_EHV_CPU1_DP")
	)
	(arc
		(start 96.871282 -222.263462)
		(mid 96.594807 -222.196142)
		(end 96.32061 -222.272098)
		(width 0.0889)
		(layer "B.Cu")
		(net "VSENSE_PVCCFA_EHV_CPU1_DP")
	)
	(arc
		(start 97.26041 -222.272098)
		(mid 97.073212 -222.322241)
		(end 96.886014 -222.272098)
		(width 0.0889)
		(layer "B.Cu")
		(net "VSENSE_PVCCFA_EHV_CPU1_DP")
	)
	(arc
		(start 100.630482 -222.263462)
		(mid 100.354007 -222.196142)
		(end 100.07981 -222.272098)
		(width 0.0889)
		(layer "B.Cu")
		(net "VSENSE_PVCCFA_EHV_CPU1_DP")
	)
	(arc
		(start 89.367614 -222.272098)
		(mid 89.232681 -222.138744)
		(end 89.180416 -221.956376)
		(width 0.0889)
		(layer "B.Cu")
		(net "VSENSE_PVCCFA_EHV_CPU1_DP")
	)
	(arc
		(start 87.958168 -221.458282)
		(mid 87.822167 -221.401938)
		(end 87.676228 -221.38259)
		(width 0.0889)
		(layer "B.Cu")
		(net "VSENSE_PVCCFA_EHV_CPU1_DP")
	)
	(arc
		(start 97.811082 -222.263462)
		(mid 97.534607 -222.196142)
		(end 97.26041 -222.272098)
		(width 0.0889)
		(layer "B.Cu")
		(net "VSENSE_PVCCFA_EHV_CPU1_DP")
	)
	(arc
		(start 91.232482 -222.263462)
		(mid 90.956007 -222.196142)
		(end 90.68181 -222.272098)
		(width 0.0889)
		(layer "B.Cu")
		(net "VSENSE_PVCCFA_EHV_CPU1_DP")
	)
	(arc
		(start 89.180416 -221.937834)
		(mid 89.102305 -221.660885)
		(end 88.897968 -221.458282)
		(width 0.0889)
		(layer "B.Cu")
		(net "VSENSE_PVCCFA_EHV_CPU1_DP")
	)
	(arc
		(start 96.32061 -222.272098)
		(mid 96.133412 -222.322241)
		(end 95.946214 -222.272098)
		(width 0.0889)
		(layer "B.Cu")
		(net "VSENSE_PVCCFA_EHV_CPU1_DP")
	)
	(arc
		(start 101.01961 -222.272098)
		(mid 100.832412 -222.322241)
		(end 100.645214 -222.272098)
		(width 0.0889)
		(layer "B.Cu")
		(net "VSENSE_PVCCFA_EHV_CPU1_DP")
	)
	(arc
		(start 101.570282 -222.263462)
		(mid 101.293807 -222.196142)
		(end 101.01961 -222.272098)
		(width 0.0889)
		(layer "B.Cu")
		(net "VSENSE_PVCCFA_EHV_CPU1_DP")
	)
	(arc
		(start 99.690682 -222.263462)
		(mid 99.414207 -222.196142)
		(end 99.14001 -222.272098)
		(width 0.0889)
		(layer "B.Cu")
		(net "VSENSE_PVCCFA_EHV_CPU1_DP")
	)
	(arc
		(start 94.051882 -222.263462)
		(mid 93.775407 -222.196142)
		(end 93.50121 -222.272098)
		(width 0.0889)
		(layer "B.Cu")
		(net "VSENSE_PVCCFA_EHV_CPU1_DP")
	)
	(arc
		(start 100.07981 -222.272098)
		(mid 99.892612 -222.322241)
		(end 99.705414 -222.272098)
		(width 0.0889)
		(layer "B.Cu")
		(net "VSENSE_PVCCFA_EHV_CPU1_DP")
	)
	(arc
		(start 102.14229 -222.005144)
		(mid 102.084134 -222.155257)
		(end 101.9683 -222.267018)
		(width 0.0889)
		(layer "B.Cu")
		(net "VSENSE_PVCCFA_EHV_CPU1_DP")
	)
	(arc
		(start 94.991682 -222.263462)
		(mid 94.715207 -222.196142)
		(end 94.44101 -222.272098)
		(width 0.0889)
		(layer "B.Cu")
		(net "VSENSE_PVCCFA_EHV_CPU1_DP")
	)
	(arc
		(start 90.292682 -222.263462)
		(mid 90.016207 -222.196142)
		(end 89.74201 -222.272098)
		(width 0.0889)
		(layer "B.Cu")
		(net "VSENSE_PVCCFA_EHV_CPU1_DP")
	)
	(arc
		(start 95.38081 -222.272098)
		(mid 95.193612 -222.322241)
		(end 95.006414 -222.272098)
		(width 0.0889)
		(layer "B.Cu")
		(net "VSENSE_PVCCFA_EHV_CPU1_DP")
	)
	(arc
		(start 93.112082 -222.263462)
		(mid 92.835607 -222.196142)
		(end 92.56141 -222.272098)
		(width 0.0889)
		(layer "B.Cu")
		(net "VSENSE_PVCCFA_EHV_CPU1_DP")
	)
	(arc
		(start 99.14001 -222.272098)
		(mid 98.952812 -222.322241)
		(end 98.765614 -222.272098)
		(width 0.0889)
		(layer "B.Cu")
		(net "VSENSE_PVCCFA_EHV_CPU1_DP")
	)
	(arc
		(start 95.931482 -222.263462)
		(mid 95.655007 -222.196142)
		(end 95.38081 -222.272098)
		(width 0.0889)
		(layer "B.Cu")
		(net "VSENSE_PVCCFA_EHV_CPU1_DP")
	)
	(arc
		(start 90.68181 -222.272098)
		(mid 90.494612 -222.322241)
		(end 90.307414 -222.272098)
		(width 0.0889)
		(layer "B.Cu")
		(net "VSENSE_PVCCFA_EHV_CPU1_DP")
	)
	(arc
		(start 91.62161 -222.272098)
		(mid 91.434412 -222.322241)
		(end 91.247214 -222.272098)
		(width 0.0889)
		(layer "B.Cu")
		(net "VSENSE_PVCCFA_EHV_CPU1_DP")
	)
	(arc
		(start 101.95941 -222.272098)
		(mid 101.772212 -222.322241)
		(end 101.585014 -222.272098)
		(width 0.0889)
		(layer "B.Cu")
		(net "VSENSE_PVCCFA_EHV_CPU1_DP")
	)
	(arc
		(start 94.44101 -222.272098)
		(mid 94.253812 -222.322241)
		(end 94.066614 -222.272098)
		(width 0.0889)
		(layer "B.Cu")
		(net "VSENSE_PVCCFA_EHV_CPU1_DP")
	)
	(segment
		(start 88.33612 -186.092592)
		(end 87.474298 -186.092592)
		(width 0.254)
		(layer "In11.Cu")
		(net "VSENSE_PVCCFA_EHV_CPU1_DP")
	)
	(segment
		(start 86.639146 -180.256942)
		(end 80.616552 -174.234348)
		(width 0.254)
		(layer "In11.Cu")
		(net "VSENSE_PVCCFA_EHV_CPU1_DP")
	)
	(segment
		(start 15.728188 -184.184036)
		(end 12.6873 -181.143148)
		(width 0.254)
		(layer "In11.Cu")
		(net "VSENSE_PVCCFA_EHV_CPU1_DP")
	)
	(segment
		(start 22.755098 -185.226706)
		(end 21.656802 -184.771792)
		(width 0.254)
		(layer "In11.Cu")
		(net "VSENSE_PVCCFA_EHV_CPU1_DP")
	)
	(segment
		(start 28.789122 -133.918452)
		(end 28.547822 -134.159752)
		(width 0.254)
		(layer "In11.Cu")
		(net "VSENSE_PVCCFA_EHV_CPU1_DP")
	)
	(segment
		(start 71.76262 -175.05934)
		(end 71.76262 -179.232814)
		(width 0.254)
		(layer "In11.Cu")
		(net "VSENSE_PVCCFA_EHV_CPU1_DP")
	)
	(segment
		(start 74.848466 -174.001684)
		(end 74.539602 -174.310548)
		(width 0.254)
		(layer "In11.Cu")
		(net "VSENSE_PVCCFA_EHV_CPU1_DP")
	)
	(segment
		(start 27.940762 -133.680962)
		(end 28.455874 -133.16585)
		(width 0.254)
		(layer "In11.Cu")
		(net "VSENSE_PVCCFA_EHV_CPU1_DP")
	)
	(segment
		(start 74.539602 -174.310548)
		(end 72.511412 -174.310548)
		(width 0.254)
		(layer "In11.Cu")
		(net "VSENSE_PVCCFA_EHV_CPU1_DP")
	)
	(segment
		(start 88.57742 -185.851292)
		(end 88.33612 -186.092592)
		(width 0.254)
		(layer "In11.Cu")
		(net "VSENSE_PVCCFA_EHV_CPU1_DP")
	)
	(segment
		(start 17.98828 -170.398948)
		(end 17.98828 -154.839416)
		(width 0.254)
		(layer "In11.Cu")
		(net "VSENSE_PVCCFA_EHV_CPU1_DP")
	)
	(segment
		(start 87.474298 -186.092592)
		(end 86.639146 -185.25744)
		(width 0.254)
		(layer "In11.Cu")
		(net "VSENSE_PVCCFA_EHV_CPU1_DP")
	)
	(segment
		(start 67.292982 -180.533548)
		(end 63.642494 -184.184036)
		(width 0.254)
		(layer "In11.Cu")
		(net "VSENSE_PVCCFA_EHV_CPU1_DP")
	)
	(segment
		(start 28.784042 -133.16585)
		(end 28.789122 -133.17093)
		(width 0.254)
		(layer "In11.Cu")
		(net "VSENSE_PVCCFA_EHV_CPU1_DP")
	)
	(segment
		(start 27.940762 -144.886934)
		(end 27.940762 -133.680962)
		(width 0.254)
		(layer "In11.Cu")
		(net "VSENSE_PVCCFA_EHV_CPU1_DP")
	)
	(segment
		(start 71.76262 -179.232814)
		(end 70.461886 -180.533548)
		(width 0.254)
		(layer "In11.Cu")
		(net "VSENSE_PVCCFA_EHV_CPU1_DP")
	)
	(segment
		(start 80.616552 -174.234348)
		(end 75.08113 -174.234348)
		(width 0.254)
		(layer "In11.Cu")
		(net "VSENSE_PVCCFA_EHV_CPU1_DP")
	)
	(segment
		(start 17.98828 -154.839416)
		(end 27.940762 -144.886934)
		(width 0.254)
		(layer "In11.Cu")
		(net "VSENSE_PVCCFA_EHV_CPU1_DP")
	)
	(segment
		(start 12.6873 -175.699928)
		(end 17.98828 -170.398948)
		(width 0.254)
		(layer "In11.Cu")
		(net "VSENSE_PVCCFA_EHV_CPU1_DP")
	)
	(segment
		(start 28.789122 -133.17093)
		(end 28.789122 -133.918452)
		(width 0.254)
		(layer "In11.Cu")
		(net "VSENSE_PVCCFA_EHV_CPU1_DP")
	)
	(segment
		(start 75.08113 -174.234348)
		(end 74.848466 -174.001684)
		(width 0.254)
		(layer "In11.Cu")
		(net "VSENSE_PVCCFA_EHV_CPU1_DP")
	)
	(segment
		(start 21.656802 -184.771792)
		(end 21.069046 -184.184036)
		(width 0.254)
		(layer "In11.Cu")
		(net "VSENSE_PVCCFA_EHV_CPU1_DP")
	)
	(segment
		(start 21.069046 -184.184036)
		(end 15.728188 -184.184036)
		(width 0.254)
		(layer "In11.Cu")
		(net "VSENSE_PVCCFA_EHV_CPU1_DP")
	)
	(segment
		(start 12.6873 -181.143148)
		(end 12.6873 -175.699928)
		(width 0.254)
		(layer "In11.Cu")
		(net "VSENSE_PVCCFA_EHV_CPU1_DP")
	)
	(segment
		(start 28.455874 -133.16585)
		(end 28.784042 -133.16585)
		(width 0.254)
		(layer "In11.Cu")
		(net "VSENSE_PVCCFA_EHV_CPU1_DP")
	)
	(segment
		(start 72.511412 -174.310548)
		(end 71.76262 -175.05934)
		(width 0.254)
		(layer "In11.Cu")
		(net "VSENSE_PVCCFA_EHV_CPU1_DP")
	)
	(segment
		(start 70.461886 -180.533548)
		(end 67.292982 -180.533548)
		(width 0.254)
		(layer "In11.Cu")
		(net "VSENSE_PVCCFA_EHV_CPU1_DP")
	)
	(segment
		(start 63.642494 -184.184036)
		(end 48.83404 -184.184036)
		(width 0.254)
		(layer "In11.Cu")
		(net "VSENSE_PVCCFA_EHV_CPU1_DP")
	)
	(segment
		(start 48.83404 -184.184036)
		(end 47.79137 -185.226706)
		(width 0.254)
		(layer "In11.Cu")
		(net "VSENSE_PVCCFA_EHV_CPU1_DP")
	)
	(segment
		(start 47.79137 -185.226706)
		(end 22.755098 -185.226706)
		(width 0.254)
		(layer "In11.Cu")
		(net "VSENSE_PVCCFA_EHV_CPU1_DP")
	)
	(segment
		(start 86.639146 -185.25744)
		(end 86.639146 -180.256942)
		(width 0.254)
		(layer "In11.Cu")
		(net "VSENSE_PVCCFA_EHV_CPU1_DP")
	)
	(segment
		(start 29.661104 -131.43357)
		(end 29.661104 -132.236464)
		(width 0.254)
		(layer "F.Cu")
		(net "VSENSE_PVCCFA_EHV_CPU1_DN")
	)
	(segment
		(start 29.412692 -133.018276)
		(end 29.435806 -133.04139)
		(width 0.254)
		(layer "F.Cu")
		(net "VSENSE_PVCCFA_EHV_CPU1_DN")
	)
	(segment
		(start 74.607166 -174.623984)
		(end 74.18578 -174.623984)
		(width 0.254)
		(layer "F.Cu")
		(net "VSENSE_PVCCFA_EHV_CPU1_DN")
	)
	(segment
		(start 29.412692 -133.545326)
		(end 29.411422 -133.546596)
		(width 0.254)
		(layer "F.Cu")
		(net "VSENSE_PVCCFA_EHV_CPU1_DN")
	)
	(segment
		(start 29.435806 -133.04139)
		(end 29.412692 -133.064504)
		(width 0.254)
		(layer "F.Cu")
		(net "VSENSE_PVCCFA_EHV_CPU1_DN")
	)
	(segment
		(start 103.652066 -221.947994)
		(end 103.651812 -221.94774)
		(width 0.2032)
		(layer "F.Cu")
		(net "VSENSE_PVCCFA_EHV_CPU1_DN")
	)
	(segment
		(start 29.411422 -133.546596)
		(end 29.411422 -134.159752)
		(width 0.254)
		(layer "F.Cu")
		(net "VSENSE_PVCCFA_EHV_CPU1_DN")
	)
	(segment
		(start 29.412692 -133.064504)
		(end 29.412692 -133.545326)
		(width 0.254)
		(layer "F.Cu")
		(net "VSENSE_PVCCFA_EHV_CPU1_DN")
	)
	(segment
		(start 74.18578 -174.623984)
		(end 73.906126 -174.903638)
		(width 0.254)
		(layer "F.Cu")
		(net "VSENSE_PVCCFA_EHV_CPU1_DN")
	)
	(segment
		(start 29.412692 -132.484876)
		(end 29.412692 -133.018276)
		(width 0.254)
		(layer "F.Cu")
		(net "VSENSE_PVCCFA_EHV_CPU1_DN")
	)
	(segment
		(start 29.661104 -132.236464)
		(end 29.412692 -132.484876)
		(width 0.254)
		(layer "F.Cu")
		(net "VSENSE_PVCCFA_EHV_CPU1_DN")
	)
	(segment
		(start 103.652066 -222.48368)
		(end 103.652066 -221.947994)
		(width 0.2032)
		(layer "F.Cu")
		(net "VSENSE_PVCCFA_EHV_CPU1_DN")
	)
	(segment
		(start 74.848466 -174.865284)
		(end 74.607166 -174.623984)
		(width 0.254)
		(layer "F.Cu")
		(net "VSENSE_PVCCFA_EHV_CPU1_DN")
	)
	(via
		(at 88.57742 -186.714892)
		(size 0.508)
		(drill 0.254)
		(layers "F.Cu" "B.Cu")
		(net "VSENSE_PVCCFA_EHV_CPU1_DN")
	)
	(via
		(at 29.411422 -134.159752)
		(size 0.508)
		(drill 0.254)
		(layers "F.Cu" "B.Cu")
		(net "VSENSE_PVCCFA_EHV_CPU1_DN")
	)
	(via
		(at 103.651812 -221.94774)
		(size 0.4572)
		(drill 0.2032)
		(layers "F.Cu" "B.Cu")
		(net "VSENSE_PVCCFA_EHV_CPU1_DN")
	)
	(via
		(at 74.848466 -174.865284)
		(size 0.508)
		(drill 0.254)
		(layers "F.Cu" "B.Cu")
		(net "VSENSE_PVCCFA_EHV_CPU1_DN")
	)
	(segment
		(start 101.504496 -222.445834)
		(end 101.489764 -222.437198)
		(width 0.0889)
		(layer "B.Cu")
		(net "VSENSE_PVCCFA_EHV_CPU1_DN")
	)
	(segment
		(start 83.598258 -218.639644)
		(end 83.598258 -210.188302)
		(width 0.254)
		(layer "B.Cu")
		(net "VSENSE_PVCCFA_EHV_CPU1_DN")
	)
	(segment
		(start 93.986096 -222.445834)
		(end 93.971364 -222.437198)
		(width 0.0889)
		(layer "B.Cu")
		(net "VSENSE_PVCCFA_EHV_CPU1_DN")
	)
	(segment
		(start 100.564696 -222.445834)
		(end 100.549964 -222.437198)
		(width 0.0889)
		(layer "B.Cu")
		(net "VSENSE_PVCCFA_EHV_CPU1_DN")
	)
	(segment
		(start 99.624896 -222.445834)
		(end 99.610164 -222.437198)
		(width 0.0889)
		(layer "B.Cu")
		(net "VSENSE_PVCCFA_EHV_CPU1_DN")
	)
	(segment
		(start 97.745296 -222.445834)
		(end 97.730564 -222.437198)
		(width 0.0889)
		(layer "B.Cu")
		(net "VSENSE_PVCCFA_EHV_CPU1_DN")
	)
	(segment
		(start 102.429564 -222.437198)
		(end 102.42931 -222.437198)
		(width 0.0889)
		(layer "B.Cu")
		(net "VSENSE_PVCCFA_EHV_CPU1_DN")
	)
	(segment
		(start 83.598258 -210.188302)
		(end 85.935058 -207.851502)
		(width 0.254)
		(layer "B.Cu")
		(net "VSENSE_PVCCFA_EHV_CPU1_DN")
	)
	(segment
		(start 85.935058 -207.851502)
		(end 85.935058 -203.599796)
		(width 0.254)
		(layer "B.Cu")
		(net "VSENSE_PVCCFA_EHV_CPU1_DN")
	)
	(segment
		(start 87.675974 -221.57309)
		(end 86.660228 -221.57309)
		(width 0.0889)
		(layer "B.Cu")
		(net "VSENSE_PVCCFA_EHV_CPU1_DN")
	)
	(segment
		(start 88.989662 -221.94774)
		(end 88.989662 -221.939104)
		(width 0.0889)
		(layer "B.Cu")
		(net "VSENSE_PVCCFA_EHV_CPU1_DN")
	)
	(segment
		(start 98.678238 -222.44177)
		(end 98.670364 -222.437198)
		(width 0.0889)
		(layer "B.Cu")
		(net "VSENSE_PVCCFA_EHV_CPU1_DN")
	)
	(segment
		(start 87.862664 -221.623382)
		(end 87.862918 -221.623382)
		(width 0.0889)
		(layer "B.Cu")
		(net "VSENSE_PVCCFA_EHV_CPU1_DN")
	)
	(segment
		(start 89.221818 -192.212468)
		(end 89.361518 -192.072768)
		(width 0.254)
		(layer "B.Cu")
		(net "VSENSE_PVCCFA_EHV_CPU1_DN")
	)
	(segment
		(start 91.166696 -222.445834)
		(end 91.151964 -222.437198)
		(width 0.0889)
		(layer "B.Cu")
		(net "VSENSE_PVCCFA_EHV_CPU1_DN")
	)
	(segment
		(start 88.815672 -186.47664)
		(end 88.57742 -186.714892)
		(width 0.254)
		(layer "B.Cu")
		(net "VSENSE_PVCCFA_EHV_CPU1_DN")
	)
	(segment
		(start 85.935058 -203.599796)
		(end 89.221818 -200.313036)
		(width 0.254)
		(layer "B.Cu")
		(net "VSENSE_PVCCFA_EHV_CPU1_DN")
	)
	(segment
		(start 102.444296 -222.445834)
		(end 102.429564 -222.437198)
		(width 0.0889)
		(layer "B.Cu")
		(net "VSENSE_PVCCFA_EHV_CPU1_DN")
	)
	(segment
		(start 94.925896 -222.445834)
		(end 94.911164 -222.437198)
		(width 0.0889)
		(layer "B.Cu")
		(net "VSENSE_PVCCFA_EHV_CPU1_DN")
	)
	(segment
		(start 93.046296 -222.445834)
		(end 93.031564 -222.437198)
		(width 0.0889)
		(layer "B.Cu")
		(net "VSENSE_PVCCFA_EHV_CPU1_DN")
	)
	(segment
		(start 86.660228 -221.57309)
		(end 86.327488 -221.24035)
		(width 0.0889)
		(layer "B.Cu")
		(net "VSENSE_PVCCFA_EHV_CPU1_DN")
	)
	(segment
		(start 89.107518 -186.47664)
		(end 88.815672 -186.47664)
		(width 0.254)
		(layer "B.Cu")
		(net "VSENSE_PVCCFA_EHV_CPU1_DN")
	)
	(segment
		(start 86.198964 -221.24035)
		(end 83.598258 -218.639644)
		(width 0.254)
		(layer "B.Cu")
		(net "VSENSE_PVCCFA_EHV_CPU1_DN")
	)
	(segment
		(start 89.287096 -222.445834)
		(end 89.272364 -222.437198)
		(width 0.0889)
		(layer "B.Cu")
		(net "VSENSE_PVCCFA_EHV_CPU1_DN")
	)
	(segment
		(start 92.106496 -222.445834)
		(end 92.091764 -222.437198)
		(width 0.0889)
		(layer "B.Cu")
		(net "VSENSE_PVCCFA_EHV_CPU1_DN")
	)
	(segment
		(start 98.685096 -222.445834)
		(end 98.678238 -222.44177)
		(width 0.0889)
		(layer "B.Cu")
		(net "VSENSE_PVCCFA_EHV_CPU1_DN")
	)
	(segment
		(start 90.226896 -222.445834)
		(end 90.212164 -222.437198)
		(width 0.0889)
		(layer "B.Cu")
		(net "VSENSE_PVCCFA_EHV_CPU1_DN")
	)
	(segment
		(start 96.805496 -222.445834)
		(end 96.790764 -222.437198)
		(width 0.0889)
		(layer "B.Cu")
		(net "VSENSE_PVCCFA_EHV_CPU1_DN")
	)
	(segment
		(start 89.361518 -192.072768)
		(end 89.361518 -186.73064)
		(width 0.254)
		(layer "B.Cu")
		(net "VSENSE_PVCCFA_EHV_CPU1_DN")
	)
	(segment
		(start 95.865696 -222.445834)
		(end 95.850964 -222.437198)
		(width 0.0889)
		(layer "B.Cu")
		(net "VSENSE_PVCCFA_EHV_CPU1_DN")
	)
	(segment
		(start 86.327488 -221.24035)
		(end 86.198964 -221.24035)
		(width 0.0889)
		(layer "B.Cu")
		(net "VSENSE_PVCCFA_EHV_CPU1_DN")
	)
	(segment
		(start 103.651812 -221.94774)
		(end 102.994968 -222.437198)
		(width 0.0889)
		(layer "B.Cu")
		(net "VSENSE_PVCCFA_EHV_CPU1_DN")
	)
	(segment
		(start 89.361518 -186.73064)
		(end 89.107518 -186.47664)
		(width 0.254)
		(layer "B.Cu")
		(net "VSENSE_PVCCFA_EHV_CPU1_DN")
	)
	(segment
		(start 89.272364 -222.437198)
		(end 89.266268 -222.433642)
		(width 0.0889)
		(layer "B.Cu")
		(net "VSENSE_PVCCFA_EHV_CPU1_DN")
	)
	(segment
		(start 89.221818 -200.313036)
		(end 89.221818 -192.212468)
		(width 0.254)
		(layer "B.Cu")
		(net "VSENSE_PVCCFA_EHV_CPU1_DN")
	)
	(arc
		(start 93.031564 -222.437198)
		(mid 92.844366 -222.387055)
		(end 92.657168 -222.437198)
		(width 0.0889)
		(layer "B.Cu")
		(net "VSENSE_PVCCFA_EHV_CPU1_DN")
	)
	(arc
		(start 89.837768 -222.437198)
		(mid 89.563569 -222.513033)
		(end 89.287096 -222.445834)
		(width 0.0889)
		(layer "B.Cu")
		(net "VSENSE_PVCCFA_EHV_CPU1_DN")
	)
	(arc
		(start 99.610164 -222.437198)
		(mid 99.422966 -222.387055)
		(end 99.235768 -222.437198)
		(width 0.0889)
		(layer "B.Cu")
		(net "VSENSE_PVCCFA_EHV_CPU1_DN")
	)
	(arc
		(start 97.730564 -222.437198)
		(mid 97.543366 -222.387055)
		(end 97.356168 -222.437198)
		(width 0.0889)
		(layer "B.Cu")
		(net "VSENSE_PVCCFA_EHV_CPU1_DN")
	)
	(arc
		(start 92.657168 -222.437198)
		(mid 92.382969 -222.513033)
		(end 92.106496 -222.445834)
		(width 0.0889)
		(layer "B.Cu")
		(net "VSENSE_PVCCFA_EHV_CPU1_DN")
	)
	(arc
		(start 99.235768 -222.437198)
		(mid 98.961569 -222.513033)
		(end 98.685096 -222.445834)
		(width 0.0889)
		(layer "B.Cu")
		(net "VSENSE_PVCCFA_EHV_CPU1_DN")
	)
	(arc
		(start 100.175568 -222.437198)
		(mid 99.901369 -222.513033)
		(end 99.624896 -222.445834)
		(width 0.0889)
		(layer "B.Cu")
		(net "VSENSE_PVCCFA_EHV_CPU1_DN")
	)
	(arc
		(start 101.489764 -222.437198)
		(mid 101.302566 -222.387055)
		(end 101.115368 -222.437198)
		(width 0.0889)
		(layer "B.Cu")
		(net "VSENSE_PVCCFA_EHV_CPU1_DN")
	)
	(arc
		(start 96.416368 -222.437198)
		(mid 96.142169 -222.513033)
		(end 95.865696 -222.445834)
		(width 0.0889)
		(layer "B.Cu")
		(net "VSENSE_PVCCFA_EHV_CPU1_DN")
	)
	(arc
		(start 93.971364 -222.437198)
		(mid 93.784166 -222.387055)
		(end 93.596968 -222.437198)
		(width 0.0889)
		(layer "B.Cu")
		(net "VSENSE_PVCCFA_EHV_CPU1_DN")
	)
	(arc
		(start 93.596968 -222.437198)
		(mid 93.322769 -222.513033)
		(end 93.046296 -222.445834)
		(width 0.0889)
		(layer "B.Cu")
		(net "VSENSE_PVCCFA_EHV_CPU1_DN")
	)
	(arc
		(start 91.151964 -222.437198)
		(mid 90.964766 -222.387055)
		(end 90.777568 -222.437198)
		(width 0.0889)
		(layer "B.Cu")
		(net "VSENSE_PVCCFA_EHV_CPU1_DN")
	)
	(arc
		(start 101.115368 -222.437198)
		(mid 100.841169 -222.513033)
		(end 100.564696 -222.445834)
		(width 0.0889)
		(layer "B.Cu")
		(net "VSENSE_PVCCFA_EHV_CPU1_DN")
	)
	(arc
		(start 97.356168 -222.437198)
		(mid 97.081969 -222.513033)
		(end 96.805496 -222.445834)
		(width 0.0889)
		(layer "B.Cu")
		(net "VSENSE_PVCCFA_EHV_CPU1_DN")
	)
	(arc
		(start 95.850964 -222.437198)
		(mid 95.663766 -222.387055)
		(end 95.476568 -222.437198)
		(width 0.0889)
		(layer "B.Cu")
		(net "VSENSE_PVCCFA_EHV_CPU1_DN")
	)
	(arc
		(start 98.670364 -222.437198)
		(mid 98.483166 -222.387055)
		(end 98.295968 -222.437198)
		(width 0.0889)
		(layer "B.Cu")
		(net "VSENSE_PVCCFA_EHV_CPU1_DN")
	)
	(arc
		(start 90.212164 -222.437198)
		(mid 90.024966 -222.387055)
		(end 89.837768 -222.437198)
		(width 0.0889)
		(layer "B.Cu")
		(net "VSENSE_PVCCFA_EHV_CPU1_DN")
	)
	(arc
		(start 102.994968 -222.437198)
		(mid 102.720769 -222.513033)
		(end 102.444296 -222.445834)
		(width 0.0889)
		(layer "B.Cu")
		(net "VSENSE_PVCCFA_EHV_CPU1_DN")
	)
	(arc
		(start 102.42931 -222.437198)
		(mid 102.242256 -222.387148)
		(end 102.055168 -222.437198)
		(width 0.0889)
		(layer "B.Cu")
		(net "VSENSE_PVCCFA_EHV_CPU1_DN")
	)
	(arc
		(start 91.717368 -222.437198)
		(mid 91.443169 -222.513033)
		(end 91.166696 -222.445834)
		(width 0.0889)
		(layer "B.Cu")
		(net "VSENSE_PVCCFA_EHV_CPU1_DN")
	)
	(arc
		(start 87.862918 -221.623382)
		(mid 87.772749 -221.585963)
		(end 87.675974 -221.57309)
		(width 0.0889)
		(layer "B.Cu")
		(net "VSENSE_PVCCFA_EHV_CPU1_DN")
	)
	(arc
		(start 96.790764 -222.437198)
		(mid 96.603566 -222.387055)
		(end 96.416368 -222.437198)
		(width 0.0889)
		(layer "B.Cu")
		(net "VSENSE_PVCCFA_EHV_CPU1_DN")
	)
	(arc
		(start 89.266268 -222.433642)
		(mid 89.063681 -222.227291)
		(end 88.989662 -221.94774)
		(width 0.0889)
		(layer "B.Cu")
		(net "VSENSE_PVCCFA_EHV_CPU1_DN")
	)
	(arc
		(start 88.428068 -221.623382)
		(mid 88.145366 -221.699158)
		(end 87.862664 -221.623382)
		(width 0.0889)
		(layer "B.Cu")
		(net "VSENSE_PVCCFA_EHV_CPU1_DN")
	)
	(arc
		(start 95.476568 -222.437198)
		(mid 95.202369 -222.513033)
		(end 94.925896 -222.445834)
		(width 0.0889)
		(layer "B.Cu")
		(net "VSENSE_PVCCFA_EHV_CPU1_DN")
	)
	(arc
		(start 92.091764 -222.437198)
		(mid 91.904566 -222.387055)
		(end 91.717368 -222.437198)
		(width 0.0889)
		(layer "B.Cu")
		(net "VSENSE_PVCCFA_EHV_CPU1_DN")
	)
	(arc
		(start 100.549964 -222.437198)
		(mid 100.362766 -222.387055)
		(end 100.175568 -222.437198)
		(width 0.0889)
		(layer "B.Cu")
		(net "VSENSE_PVCCFA_EHV_CPU1_DN")
	)
	(arc
		(start 102.055168 -222.437198)
		(mid 101.780969 -222.513033)
		(end 101.504496 -222.445834)
		(width 0.0889)
		(layer "B.Cu")
		(net "VSENSE_PVCCFA_EHV_CPU1_DN")
	)
	(arc
		(start 94.536768 -222.437198)
		(mid 94.262569 -222.513033)
		(end 93.986096 -222.445834)
		(width 0.0889)
		(layer "B.Cu")
		(net "VSENSE_PVCCFA_EHV_CPU1_DN")
	)
	(arc
		(start 90.777568 -222.437198)
		(mid 90.503369 -222.513033)
		(end 90.226896 -222.445834)
		(width 0.0889)
		(layer "B.Cu")
		(net "VSENSE_PVCCFA_EHV_CPU1_DN")
	)
	(arc
		(start 88.802464 -221.623382)
		(mid 88.615266 -221.573239)
		(end 88.428068 -221.623382)
		(width 0.0889)
		(layer "B.Cu")
		(net "VSENSE_PVCCFA_EHV_CPU1_DN")
	)
	(arc
		(start 94.911164 -222.437198)
		(mid 94.723966 -222.387055)
		(end 94.536768 -222.437198)
		(width 0.0889)
		(layer "B.Cu")
		(net "VSENSE_PVCCFA_EHV_CPU1_DN")
	)
	(arc
		(start 98.295968 -222.437198)
		(mid 98.021769 -222.513033)
		(end 97.745296 -222.445834)
		(width 0.0889)
		(layer "B.Cu")
		(net "VSENSE_PVCCFA_EHV_CPU1_DN")
	)
	(arc
		(start 88.989662 -221.939104)
		(mid 88.937392 -221.756739)
		(end 88.802464 -221.623382)
		(width 0.0889)
		(layer "B.Cu")
		(net "VSENSE_PVCCFA_EHV_CPU1_DN")
	)
	(segment
		(start 21.440902 -185.09488)
		(end 20.911058 -184.565036)
		(width 0.254)
		(layer "In11.Cu")
		(net "VSENSE_PVCCFA_EHV_CPU1_DN")
	)
	(segment
		(start 63.800482 -184.565036)
		(end 48.992028 -184.565036)
		(width 0.254)
		(layer "In11.Cu")
		(net "VSENSE_PVCCFA_EHV_CPU1_DN")
	)
	(segment
		(start 74.67473 -174.691548)
		(end 72.6694 -174.691548)
		(width 0.254)
		(layer "In11.Cu")
		(net "VSENSE_PVCCFA_EHV_CPU1_DN")
	)
	(segment
		(start 22.679152 -185.607706)
		(end 21.440902 -185.09488)
		(width 0.254)
		(layer "In11.Cu")
		(net "VSENSE_PVCCFA_EHV_CPU1_DN")
	)
	(segment
		(start 67.45097 -180.914548)
		(end 63.800482 -184.565036)
		(width 0.254)
		(layer "In11.Cu")
		(net "VSENSE_PVCCFA_EHV_CPU1_DN")
	)
	(segment
		(start 72.6694 -174.691548)
		(end 72.14362 -175.217328)
		(width 0.254)
		(layer "In11.Cu")
		(net "VSENSE_PVCCFA_EHV_CPU1_DN")
	)
	(segment
		(start 12.3063 -175.54194)
		(end 17.60728 -170.24096)
		(width 0.254)
		(layer "In11.Cu")
		(net "VSENSE_PVCCFA_EHV_CPU1_DN")
	)
	(segment
		(start 28.297886 -132.78485)
		(end 28.94203 -132.78485)
		(width 0.254)
		(layer "In11.Cu")
		(net "VSENSE_PVCCFA_EHV_CPU1_DN")
	)
	(segment
		(start 28.94203 -132.78485)
		(end 29.170122 -133.012942)
		(width 0.254)
		(layer "In11.Cu")
		(net "VSENSE_PVCCFA_EHV_CPU1_DN")
	)
	(segment
		(start 70.619874 -180.914548)
		(end 67.45097 -180.914548)
		(width 0.254)
		(layer "In11.Cu")
		(net "VSENSE_PVCCFA_EHV_CPU1_DN")
	)
	(segment
		(start 17.60728 -154.681428)
		(end 27.559762 -144.728946)
		(width 0.254)
		(layer "In11.Cu")
		(net "VSENSE_PVCCFA_EHV_CPU1_DN")
	)
	(segment
		(start 48.992028 -184.565036)
		(end 47.949358 -185.607706)
		(width 0.254)
		(layer "In11.Cu")
		(net "VSENSE_PVCCFA_EHV_CPU1_DN")
	)
	(segment
		(start 80.458564 -174.615348)
		(end 75.098402 -174.615348)
		(width 0.254)
		(layer "In11.Cu")
		(net "VSENSE_PVCCFA_EHV_CPU1_DN")
	)
	(segment
		(start 72.14362 -175.217328)
		(end 72.14362 -179.390802)
		(width 0.254)
		(layer "In11.Cu")
		(net "VSENSE_PVCCFA_EHV_CPU1_DN")
	)
	(segment
		(start 87.31631 -186.473592)
		(end 86.258146 -185.415428)
		(width 0.254)
		(layer "In11.Cu")
		(net "VSENSE_PVCCFA_EHV_CPU1_DN")
	)
	(segment
		(start 27.559762 -133.522974)
		(end 28.297886 -132.78485)
		(width 0.254)
		(layer "In11.Cu")
		(net "VSENSE_PVCCFA_EHV_CPU1_DN")
	)
	(segment
		(start 74.848466 -174.865284)
		(end 74.67473 -174.691548)
		(width 0.254)
		(layer "In11.Cu")
		(net "VSENSE_PVCCFA_EHV_CPU1_DN")
	)
	(segment
		(start 86.258146 -180.41493)
		(end 80.458564 -174.615348)
		(width 0.254)
		(layer "In11.Cu")
		(net "VSENSE_PVCCFA_EHV_CPU1_DN")
	)
	(segment
		(start 75.098402 -174.615348)
		(end 74.848466 -174.865284)
		(width 0.254)
		(layer "In11.Cu")
		(net "VSENSE_PVCCFA_EHV_CPU1_DN")
	)
	(segment
		(start 27.559762 -144.728946)
		(end 27.559762 -133.522974)
		(width 0.254)
		(layer "In11.Cu")
		(net "VSENSE_PVCCFA_EHV_CPU1_DN")
	)
	(segment
		(start 29.170122 -133.918452)
		(end 29.411422 -134.159752)
		(width 0.254)
		(layer "In11.Cu")
		(net "VSENSE_PVCCFA_EHV_CPU1_DN")
	)
	(segment
		(start 29.170122 -133.012942)
		(end 29.170122 -133.918452)
		(width 0.254)
		(layer "In11.Cu")
		(net "VSENSE_PVCCFA_EHV_CPU1_DN")
	)
	(segment
		(start 12.3063 -181.301136)
		(end 12.3063 -175.54194)
		(width 0.254)
		(layer "In11.Cu")
		(net "VSENSE_PVCCFA_EHV_CPU1_DN")
	)
	(segment
		(start 88.33612 -186.473592)
		(end 87.31631 -186.473592)
		(width 0.254)
		(layer "In11.Cu")
		(net "VSENSE_PVCCFA_EHV_CPU1_DN")
	)
	(segment
		(start 47.949358 -185.607706)
		(end 22.679152 -185.607706)
		(width 0.254)
		(layer "In11.Cu")
		(net "VSENSE_PVCCFA_EHV_CPU1_DN")
	)
	(segment
		(start 15.5702 -184.565036)
		(end 12.3063 -181.301136)
		(width 0.254)
		(layer "In11.Cu")
		(net "VSENSE_PVCCFA_EHV_CPU1_DN")
	)
	(segment
		(start 20.911058 -184.565036)
		(end 15.5702 -184.565036)
		(width 0.254)
		(layer "In11.Cu")
		(net "VSENSE_PVCCFA_EHV_CPU1_DN")
	)
	(segment
		(start 86.258146 -185.415428)
		(end 86.258146 -180.41493)
		(width 0.254)
		(layer "In11.Cu")
		(net "VSENSE_PVCCFA_EHV_CPU1_DN")
	)
	(segment
		(start 17.60728 -170.24096)
		(end 17.60728 -154.681428)
		(width 0.254)
		(layer "In11.Cu")
		(net "VSENSE_PVCCFA_EHV_CPU1_DN")
	)
	(segment
		(start 72.14362 -179.390802)
		(end 70.619874 -180.914548)
		(width 0.254)
		(layer "In11.Cu")
		(net "VSENSE_PVCCFA_EHV_CPU1_DN")
	)
	(segment
		(start 88.57742 -186.714892)
		(end 88.33612 -186.473592)
		(width 0.254)
		(layer "In11.Cu")
		(net "VSENSE_PVCCFA_EHV_CPU1_DN")
	)
	(segment
		(start 397.952976 -145.583148)
		(end 397.952976 -147.292568)
		(width 0.254)
		(layer "F.Cu")
		(net "VSENSE_PVCCFA_EHV_CPU0_DP")
	)
	(segment
		(start 422.529508 -140.99921)
		(end 422.529508 -141.756638)
		(width 0.254)
		(layer "F.Cu")
		(net "VSENSE_PVCCFA_EHV_CPU0_DP")
	)
	(segment
		(start 349.712534 -222.48368)
		(end 349.712534 -221.947994)
		(width 0.2032)
		(layer "F.Cu")
		(net "VSENSE_PVCCFA_EHV_CPU0_DP")
	)
	(segment
		(start 398.046956 -145.489168)
		(end 397.952976 -145.583148)
		(width 0.254)
		(layer "F.Cu")
		(net "VSENSE_PVCCFA_EHV_CPU0_DP")
	)
	(segment
		(start 397.952976 -147.292568)
		(end 398.270476 -147.610068)
		(width 0.254)
		(layer "F.Cu")
		(net "VSENSE_PVCCFA_EHV_CPU0_DP")
	)
	(segment
		(start 349.712534 -221.947994)
		(end 349.71228 -221.94774)
		(width 0.2032)
		(layer "F.Cu")
		(net "VSENSE_PVCCFA_EHV_CPU0_DP")
	)
	(via
		(at 422.529508 -140.99921)
		(size 0.508)
		(drill 0.254)
		(layers "F.Cu" "B.Cu")
		(net "VSENSE_PVCCFA_EHV_CPU0_DP")
	)
	(via
		(at 349.71228 -221.94774)
		(size 0.4572)
		(drill 0.2032)
		(layers "F.Cu" "B.Cu")
		(net "VSENSE_PVCCFA_EHV_CPU0_DP")
	)
	(via
		(at 398.046956 -145.489168)
		(size 0.508)
		(drill 0.254)
		(layers "F.Cu" "B.Cu")
		(net "VSENSE_PVCCFA_EHV_CPU0_DP")
	)
	(segment
		(start 386.072634 -211.318602)
		(end 386.072634 -214.754968)
		(width 0.254)
		(layer "In4.Cu")
		(net "VSENSE_PVCCFA_EHV_CPU0_DP")
	)
	(segment
		(start 386.072634 -214.754968)
		(end 386.072634 -214.796116)
		(width 0.0889)
		(layer "In4.Cu")
		(net "VSENSE_PVCCFA_EHV_CPU0_DP")
	)
	(segment
		(start 375.758964 -219.190316)
		(end 375.744232 -219.18168)
		(width 0.0889)
		(layer "In4.Cu")
		(net "VSENSE_PVCCFA_EHV_CPU0_DP")
	)
	(segment
		(start 377.638564 -219.190316)
		(end 377.623832 -219.18168)
		(width 0.0889)
		(layer "In4.Cu")
		(net "VSENSE_PVCCFA_EHV_CPU0_DP")
	)
	(segment
		(start 398.046956 -145.489168)
		(end 397.805656 -145.730468)
		(width 0.254)
		(layer "In4.Cu")
		(net "VSENSE_PVCCFA_EHV_CPU0_DP")
	)
	(segment
		(start 350.384364 -222.445834)
		(end 350.369632 -222.437198)
		(width 0.0889)
		(layer "In4.Cu")
		(net "VSENSE_PVCCFA_EHV_CPU0_DP")
	)
	(segment
		(start 385.520184 -216.25052)
		(end 385.520184 -216.260426)
		(width 0.0889)
		(layer "In4.Cu")
		(net "VSENSE_PVCCFA_EHV_CPU0_DP")
	)
	(segment
		(start 393.363958 -159.460438)
		(end 393.363958 -170.78071)
		(width 0.254)
		(layer "In4.Cu")
		(net "VSENSE_PVCCFA_EHV_CPU0_DP")
	)
	(segment
		(start 359.863136 -219.995496)
		(end 359.862374 -219.996004)
		(width 0.0889)
		(layer "In4.Cu")
		(net "VSENSE_PVCCFA_EHV_CPU0_DP")
	)
	(segment
		(start 359.863644 -221.622874)
		(end 359.862882 -221.623382)
		(width 0.0889)
		(layer "In4.Cu")
		(net "VSENSE_PVCCFA_EHV_CPU0_DP")
	)
	(segment
		(start 364.481364 -219.190316)
		(end 364.466632 -219.18168)
		(width 0.0889)
		(layer "In4.Cu")
		(net "VSENSE_PVCCFA_EHV_CPU0_DP")
	)
	(segment
		(start 360.145584 -219.506038)
		(end 360.145584 -219.515944)
		(width 0.0889)
		(layer "In4.Cu")
		(net "VSENSE_PVCCFA_EHV_CPU0_DP")
	)
	(segment
		(start 369.180364 -219.190316)
		(end 369.165632 -219.18168)
		(width 0.0889)
		(layer "In4.Cu")
		(net "VSENSE_PVCCFA_EHV_CPU0_DP")
	)
	(segment
		(start 351.324164 -222.445834)
		(end 351.309432 -222.437198)
		(width 0.0889)
		(layer "In4.Cu")
		(net "VSENSE_PVCCFA_EHV_CPU0_DP")
	)
	(segment
		(start 360.145584 -221.115382)
		(end 360.145584 -221.133924)
		(width 0.0889)
		(layer "In4.Cu")
		(net "VSENSE_PVCCFA_EHV_CPU0_DP")
	)
	(segment
		(start 382.230884 -218.692222)
		(end 382.230884 -218.702128)
		(width 0.0889)
		(layer "In4.Cu")
		(net "VSENSE_PVCCFA_EHV_CPU0_DP")
	)
	(segment
		(start 378.578364 -219.190316)
		(end 378.563632 -219.18168)
		(width 0.0889)
		(layer "In4.Cu")
		(net "VSENSE_PVCCFA_EHV_CPU0_DP")
	)
	(segment
		(start 383.170684 -217.064336)
		(end 383.170684 -217.07856)
		(width 0.0889)
		(layer "In4.Cu")
		(net "VSENSE_PVCCFA_EHV_CPU0_DP")
	)
	(segment
		(start 371.059964 -219.190316)
		(end 371.045232 -219.18168)
		(width 0.0889)
		(layer "In4.Cu")
		(net "VSENSE_PVCCFA_EHV_CPU0_DP")
	)
	(segment
		(start 397.52524 -147.750276)
		(end 397.52524 -155.299156)
		(width 0.254)
		(layer "In4.Cu")
		(net "VSENSE_PVCCFA_EHV_CPU0_DP")
	)
	(segment
		(start 397.52524 -155.299156)
		(end 393.363958 -159.460438)
		(width 0.254)
		(layer "In4.Cu")
		(net "VSENSE_PVCCFA_EHV_CPU0_DP")
	)
	(segment
		(start 376.698764 -219.190316)
		(end 376.684032 -219.18168)
		(width 0.0889)
		(layer "In4.Cu")
		(net "VSENSE_PVCCFA_EHV_CPU0_DP")
	)
	(segment
		(start 374.819164 -219.190316)
		(end 374.804432 -219.18168)
		(width 0.0889)
		(layer "In4.Cu")
		(net "VSENSE_PVCCFA_EHV_CPU0_DP")
	)
	(segment
		(start 350.369632 -222.437198)
		(end 350.363536 -222.433642)
		(width 0.0889)
		(layer "In4.Cu")
		(net "VSENSE_PVCCFA_EHV_CPU0_DP")
	)
	(segment
		(start 397.805656 -147.46986)
		(end 397.52524 -147.750276)
		(width 0.254)
		(layer "In4.Cu")
		(net "VSENSE_PVCCFA_EHV_CPU0_DP")
	)
	(segment
		(start 391.972038 -172.17263)
		(end 391.972038 -205.419198)
		(width 0.254)
		(layer "In4.Cu")
		(net "VSENSE_PVCCFA_EHV_CPU0_DP")
	)
	(segment
		(start 360.722164 -219.190316)
		(end 360.707432 -219.18168)
		(width 0.0889)
		(layer "In4.Cu")
		(net "VSENSE_PVCCFA_EHV_CPU0_DP")
	)
	(segment
		(start 385.707636 -215.926162)
		(end 385.698746 -215.931242)
		(width 0.0889)
		(layer "In4.Cu")
		(net "VSENSE_PVCCFA_EHV_CPU0_DP")
	)
	(segment
		(start 355.083364 -222.445834)
		(end 355.068632 -222.437198)
		(width 0.0889)
		(layer "In4.Cu")
		(net "VSENSE_PVCCFA_EHV_CPU0_DP")
	)
	(segment
		(start 366.360964 -219.190316)
		(end 366.346232 -219.18168)
		(width 0.0889)
		(layer "In4.Cu")
		(net "VSENSE_PVCCFA_EHV_CPU0_DP")
	)
	(segment
		(start 356.023164 -222.445834)
		(end 356.008432 -222.437198)
		(width 0.0889)
		(layer "In4.Cu")
		(net "VSENSE_PVCCFA_EHV_CPU0_DP")
	)
	(segment
		(start 350.024954 -221.94774)
		(end 349.71228 -221.94774)
		(width 0.0889)
		(layer "In4.Cu")
		(net "VSENSE_PVCCFA_EHV_CPU0_DP")
	)
	(segment
		(start 371.999764 -219.190316)
		(end 371.985032 -219.18168)
		(width 0.0889)
		(layer "In4.Cu")
		(net "VSENSE_PVCCFA_EHV_CPU0_DP")
	)
	(segment
		(start 372.939564 -219.190316)
		(end 372.924832 -219.18168)
		(width 0.0889)
		(layer "In4.Cu")
		(net "VSENSE_PVCCFA_EHV_CPU0_DP")
	)
	(segment
		(start 352.263964 -222.445834)
		(end 352.249232 -222.437198)
		(width 0.0889)
		(layer "In4.Cu")
		(net "VSENSE_PVCCFA_EHV_CPU0_DP")
	)
	(segment
		(start 360.333036 -219.18168)
		(end 360.324146 -219.18676)
		(width 0.0889)
		(layer "In4.Cu")
		(net "VSENSE_PVCCFA_EHV_CPU0_DP")
	)
	(segment
		(start 356.962964 -222.445834)
		(end 356.948232 -222.437198)
		(width 0.0889)
		(layer "In4.Cu")
		(net "VSENSE_PVCCFA_EHV_CPU0_DP")
	)
	(segment
		(start 397.805656 -145.730468)
		(end 397.805656 -147.46986)
		(width 0.254)
		(layer "In4.Cu")
		(net "VSENSE_PVCCFA_EHV_CPU0_DP")
	)
	(segment
		(start 380.457964 -219.190316)
		(end 380.443232 -219.18168)
		(width 0.0889)
		(layer "In4.Cu")
		(net "VSENSE_PVCCFA_EHV_CPU0_DP")
	)
	(segment
		(start 350.09074 -222.013526)
		(end 350.024954 -221.94774)
		(width 0.0889)
		(layer "In4.Cu")
		(net "VSENSE_PVCCFA_EHV_CPU0_DP")
	)
	(segment
		(start 382.700784 -217.86977)
		(end 382.700784 -217.888312)
		(width 0.0889)
		(layer "In4.Cu")
		(net "VSENSE_PVCCFA_EHV_CPU0_DP")
	)
	(segment
		(start 367.300764 -219.190316)
		(end 367.286032 -219.18168)
		(width 0.0889)
		(layer "In4.Cu")
		(net "VSENSE_PVCCFA_EHV_CPU0_DP")
	)
	(segment
		(start 358.735884 -221.94774)
		(end 358.735884 -221.957646)
		(width 0.0889)
		(layer "In4.Cu")
		(net "VSENSE_PVCCFA_EHV_CPU0_DP")
	)
	(segment
		(start 386.072634 -214.796116)
		(end 385.990084 -214.878666)
		(width 0.0889)
		(layer "In4.Cu")
		(net "VSENSE_PVCCFA_EHV_CPU0_DP")
	)
	(segment
		(start 359.868978 -221.619826)
		(end 359.863644 -221.622874)
		(width 0.0889)
		(layer "In4.Cu")
		(net "VSENSE_PVCCFA_EHV_CPU0_DP")
	)
	(segment
		(start 354.143564 -222.445834)
		(end 354.128832 -222.437198)
		(width 0.0889)
		(layer "In4.Cu")
		(net "VSENSE_PVCCFA_EHV_CPU0_DP")
	)
	(segment
		(start 358.923336 -221.623382)
		(end 358.914446 -221.628462)
		(width 0.0889)
		(layer "In4.Cu")
		(net "VSENSE_PVCCFA_EHV_CPU0_DP")
	)
	(segment
		(start 370.120164 -219.190316)
		(end 370.105432 -219.18168)
		(width 0.0889)
		(layer "In4.Cu")
		(net "VSENSE_PVCCFA_EHV_CPU0_DP")
	)
	(segment
		(start 385.990084 -214.878666)
		(end 385.990084 -215.44661)
		(width 0.0889)
		(layer "In4.Cu")
		(net "VSENSE_PVCCFA_EHV_CPU0_DP")
	)
	(segment
		(start 359.862374 -219.996004)
		(end 359.854246 -220.000576)
		(width 0.0889)
		(layer "In4.Cu")
		(net "VSENSE_PVCCFA_EHV_CPU0_DP")
	)
	(segment
		(start 363.541564 -219.190316)
		(end 363.526832 -219.18168)
		(width 0.0889)
		(layer "In4.Cu")
		(net "VSENSE_PVCCFA_EHV_CPU0_DP")
	)
	(segment
		(start 353.203764 -222.445834)
		(end 353.189032 -222.437198)
		(width 0.0889)
		(layer "In4.Cu")
		(net "VSENSE_PVCCFA_EHV_CPU0_DP")
	)
	(segment
		(start 359.862882 -221.623382)
		(end 359.852468 -221.629478)
		(width 0.0889)
		(layer "In4.Cu")
		(net "VSENSE_PVCCFA_EHV_CPU0_DP")
	)
	(segment
		(start 365.421164 -219.190316)
		(end 365.406432 -219.18168)
		(width 0.0889)
		(layer "In4.Cu")
		(net "VSENSE_PVCCFA_EHV_CPU0_DP")
	)
	(segment
		(start 391.972038 -205.419198)
		(end 386.072634 -211.318602)
		(width 0.254)
		(layer "In4.Cu")
		(net "VSENSE_PVCCFA_EHV_CPU0_DP")
	)
	(segment
		(start 383.358136 -216.739978)
		(end 383.349246 -216.745058)
		(width 0.0889)
		(layer "In4.Cu")
		(net "VSENSE_PVCCFA_EHV_CPU0_DP")
	)
	(segment
		(start 359.854246 -220.639132)
		(end 359.863136 -220.644212)
		(width 0.0889)
		(layer "In4.Cu")
		(net "VSENSE_PVCCFA_EHV_CPU0_DP")
	)
	(segment
		(start 379.518164 -219.190316)
		(end 379.503432 -219.18168)
		(width 0.0889)
		(layer "In4.Cu")
		(net "VSENSE_PVCCFA_EHV_CPU0_DP")
	)
	(segment
		(start 393.363958 -170.78071)
		(end 391.972038 -172.17263)
		(width 0.254)
		(layer "In4.Cu")
		(net "VSENSE_PVCCFA_EHV_CPU0_DP")
	)
	(segment
		(start 368.240564 -219.190316)
		(end 368.225832 -219.18168)
		(width 0.0889)
		(layer "In4.Cu")
		(net "VSENSE_PVCCFA_EHV_CPU0_DP")
	)
	(segment
		(start 382.418336 -218.367864)
		(end 382.409446 -218.372944)
		(width 0.0889)
		(layer "In4.Cu")
		(net "VSENSE_PVCCFA_EHV_CPU0_DP")
	)
	(segment
		(start 373.879364 -219.190316)
		(end 373.864632 -219.18168)
		(width 0.0889)
		(layer "In4.Cu")
		(net "VSENSE_PVCCFA_EHV_CPU0_DP")
	)
	(arc
		(start 350.363536 -222.433642)
		(mid 350.178081 -222.255447)
		(end 350.09074 -222.013526)
		(width 0.0889)
		(layer "In4.Cu")
		(net "VSENSE_PVCCFA_EHV_CPU0_DP")
	)
	(arc
		(start 353.754436 -222.437198)
		(mid 353.480237 -222.513033)
		(end 353.203764 -222.445834)
		(width 0.0889)
		(layer "In4.Cu")
		(net "VSENSE_PVCCFA_EHV_CPU0_DP")
	)
	(arc
		(start 359.863136 -220.644212)
		(mid 360.065422 -220.843193)
		(end 360.145584 -221.115382)
		(width 0.0889)
		(layer "In4.Cu")
		(net "VSENSE_PVCCFA_EHV_CPU0_DP")
	)
	(arc
		(start 352.814636 -222.437198)
		(mid 352.540437 -222.513033)
		(end 352.263964 -222.445834)
		(width 0.0889)
		(layer "In4.Cu")
		(net "VSENSE_PVCCFA_EHV_CPU0_DP")
	)
	(arc
		(start 385.990084 -215.44661)
		(mid 385.911973 -215.723559)
		(end 385.707636 -215.926162)
		(width 0.0889)
		(layer "In4.Cu")
		(net "VSENSE_PVCCFA_EHV_CPU0_DP")
	)
	(arc
		(start 362.587032 -219.18168)
		(mid 362.399834 -219.131537)
		(end 362.212636 -219.18168)
		(width 0.0889)
		(layer "In4.Cu")
		(net "VSENSE_PVCCFA_EHV_CPU0_DP")
	)
	(arc
		(start 383.349246 -216.745058)
		(mid 383.218332 -216.881418)
		(end 383.170684 -217.064336)
		(width 0.0889)
		(layer "In4.Cu")
		(net "VSENSE_PVCCFA_EHV_CPU0_DP")
	)
	(arc
		(start 355.634036 -222.437198)
		(mid 355.359837 -222.513033)
		(end 355.083364 -222.445834)
		(width 0.0889)
		(layer "In4.Cu")
		(net "VSENSE_PVCCFA_EHV_CPU0_DP")
	)
	(arc
		(start 353.189032 -222.437198)
		(mid 353.001834 -222.387055)
		(end 352.814636 -222.437198)
		(width 0.0889)
		(layer "In4.Cu")
		(net "VSENSE_PVCCFA_EHV_CPU0_DP")
	)
	(arc
		(start 358.453436 -222.437198)
		(mid 358.170734 -222.512974)
		(end 357.888032 -222.437198)
		(width 0.0889)
		(layer "In4.Cu")
		(net "VSENSE_PVCCFA_EHV_CPU0_DP")
	)
	(arc
		(start 380.068836 -219.18168)
		(mid 379.794637 -219.257515)
		(end 379.518164 -219.190316)
		(width 0.0889)
		(layer "In4.Cu")
		(net "VSENSE_PVCCFA_EHV_CPU0_DP")
	)
	(arc
		(start 383.170684 -217.07856)
		(mid 383.091465 -217.353245)
		(end 382.887982 -217.554048)
		(width 0.0889)
		(layer "In4.Cu")
		(net "VSENSE_PVCCFA_EHV_CPU0_DP")
	)
	(arc
		(start 372.924832 -219.18168)
		(mid 372.737634 -219.131537)
		(end 372.550436 -219.18168)
		(width 0.0889)
		(layer "In4.Cu")
		(net "VSENSE_PVCCFA_EHV_CPU0_DP")
	)
	(arc
		(start 368.791236 -219.18168)
		(mid 368.517037 -219.257515)
		(end 368.240564 -219.190316)
		(width 0.0889)
		(layer "In4.Cu")
		(net "VSENSE_PVCCFA_EHV_CPU0_DP")
	)
	(arc
		(start 360.145584 -221.133924)
		(mid 360.071593 -221.41349)
		(end 359.868978 -221.619826)
		(width 0.0889)
		(layer "In4.Cu")
		(net "VSENSE_PVCCFA_EHV_CPU0_DP")
	)
	(arc
		(start 379.129036 -219.18168)
		(mid 378.854837 -219.257515)
		(end 378.578364 -219.190316)
		(width 0.0889)
		(layer "In4.Cu")
		(net "VSENSE_PVCCFA_EHV_CPU0_DP")
	)
	(arc
		(start 363.152436 -219.18168)
		(mid 362.869734 -219.257456)
		(end 362.587032 -219.18168)
		(width 0.0889)
		(layer "In4.Cu")
		(net "VSENSE_PVCCFA_EHV_CPU0_DP")
	)
	(arc
		(start 360.707432 -219.18168)
		(mid 360.520234 -219.131537)
		(end 360.333036 -219.18168)
		(width 0.0889)
		(layer "In4.Cu")
		(net "VSENSE_PVCCFA_EHV_CPU0_DP")
	)
	(arc
		(start 366.346232 -219.18168)
		(mid 366.159034 -219.131537)
		(end 365.971836 -219.18168)
		(width 0.0889)
		(layer "In4.Cu")
		(net "VSENSE_PVCCFA_EHV_CPU0_DP")
	)
	(arc
		(start 381.948436 -219.18168)
		(mid 381.665734 -219.257456)
		(end 381.383032 -219.18168)
		(width 0.0889)
		(layer "In4.Cu")
		(net "VSENSE_PVCCFA_EHV_CPU0_DP")
	)
	(arc
		(start 372.550436 -219.18168)
		(mid 372.276237 -219.257515)
		(end 371.999764 -219.190316)
		(width 0.0889)
		(layer "In4.Cu")
		(net "VSENSE_PVCCFA_EHV_CPU0_DP")
	)
	(arc
		(start 358.914446 -221.628462)
		(mid 358.783532 -221.764822)
		(end 358.735884 -221.94774)
		(width 0.0889)
		(layer "In4.Cu")
		(net "VSENSE_PVCCFA_EHV_CPU0_DP")
	)
	(arc
		(start 374.804432 -219.18168)
		(mid 374.617234 -219.131537)
		(end 374.430036 -219.18168)
		(width 0.0889)
		(layer "In4.Cu")
		(net "VSENSE_PVCCFA_EHV_CPU0_DP")
	)
	(arc
		(start 379.503432 -219.18168)
		(mid 379.316234 -219.131537)
		(end 379.129036 -219.18168)
		(width 0.0889)
		(layer "In4.Cu")
		(net "VSENSE_PVCCFA_EHV_CPU0_DP")
	)
	(arc
		(start 385.698746 -215.931242)
		(mid 385.567832 -216.067602)
		(end 385.520184 -216.25052)
		(width 0.0889)
		(layer "In4.Cu")
		(net "VSENSE_PVCCFA_EHV_CPU0_DP")
	)
	(arc
		(start 376.309636 -219.18168)
		(mid 376.035437 -219.257515)
		(end 375.758964 -219.190316)
		(width 0.0889)
		(layer "In4.Cu")
		(net "VSENSE_PVCCFA_EHV_CPU0_DP")
	)
	(arc
		(start 373.864632 -219.18168)
		(mid 373.677434 -219.131537)
		(end 373.490236 -219.18168)
		(width 0.0889)
		(layer "In4.Cu")
		(net "VSENSE_PVCCFA_EHV_CPU0_DP")
	)
	(arc
		(start 360.324146 -219.18676)
		(mid 360.193232 -219.32312)
		(end 360.145584 -219.506038)
		(width 0.0889)
		(layer "In4.Cu")
		(net "VSENSE_PVCCFA_EHV_CPU0_DP")
	)
	(arc
		(start 364.466632 -219.18168)
		(mid 364.279434 -219.131537)
		(end 364.092236 -219.18168)
		(width 0.0889)
		(layer "In4.Cu")
		(net "VSENSE_PVCCFA_EHV_CPU0_DP")
	)
	(arc
		(start 356.573836 -222.437198)
		(mid 356.299637 -222.513033)
		(end 356.023164 -222.445834)
		(width 0.0889)
		(layer "In4.Cu")
		(net "VSENSE_PVCCFA_EHV_CPU0_DP")
	)
	(arc
		(start 377.249436 -219.18168)
		(mid 376.975237 -219.257515)
		(end 376.698764 -219.190316)
		(width 0.0889)
		(layer "In4.Cu")
		(net "VSENSE_PVCCFA_EHV_CPU0_DP")
	)
	(arc
		(start 385.520184 -216.260426)
		(mid 385.442073 -216.537375)
		(end 385.237736 -216.739978)
		(width 0.0889)
		(layer "In4.Cu")
		(net "VSENSE_PVCCFA_EHV_CPU0_DP")
	)
	(arc
		(start 354.694236 -222.437198)
		(mid 354.420037 -222.513033)
		(end 354.143564 -222.445834)
		(width 0.0889)
		(layer "In4.Cu")
		(net "VSENSE_PVCCFA_EHV_CPU0_DP")
	)
	(arc
		(start 369.165632 -219.18168)
		(mid 368.978434 -219.131537)
		(end 368.791236 -219.18168)
		(width 0.0889)
		(layer "In4.Cu")
		(net "VSENSE_PVCCFA_EHV_CPU0_DP")
	)
	(arc
		(start 357.513636 -222.437198)
		(mid 357.239437 -222.513033)
		(end 356.962964 -222.445834)
		(width 0.0889)
		(layer "In4.Cu")
		(net "VSENSE_PVCCFA_EHV_CPU0_DP")
	)
	(arc
		(start 364.092236 -219.18168)
		(mid 363.818037 -219.257515)
		(end 363.541564 -219.190316)
		(width 0.0889)
		(layer "In4.Cu")
		(net "VSENSE_PVCCFA_EHV_CPU0_DP")
	)
	(arc
		(start 371.610636 -219.18168)
		(mid 371.336437 -219.257515)
		(end 371.059964 -219.190316)
		(width 0.0889)
		(layer "In4.Cu")
		(net "VSENSE_PVCCFA_EHV_CPU0_DP")
	)
	(arc
		(start 367.851436 -219.18168)
		(mid 367.577237 -219.257515)
		(end 367.300764 -219.190316)
		(width 0.0889)
		(layer "In4.Cu")
		(net "VSENSE_PVCCFA_EHV_CPU0_DP")
	)
	(arc
		(start 361.647232 -219.18168)
		(mid 361.460034 -219.131537)
		(end 361.272836 -219.18168)
		(width 0.0889)
		(layer "In4.Cu")
		(net "VSENSE_PVCCFA_EHV_CPU0_DP")
	)
	(arc
		(start 382.409446 -218.372944)
		(mid 382.278532 -218.509304)
		(end 382.230884 -218.692222)
		(width 0.0889)
		(layer "In4.Cu")
		(net "VSENSE_PVCCFA_EHV_CPU0_DP")
	)
	(arc
		(start 384.672332 -216.739978)
		(mid 384.485134 -216.689835)
		(end 384.297936 -216.739978)
		(width 0.0889)
		(layer "In4.Cu")
		(net "VSENSE_PVCCFA_EHV_CPU0_DP")
	)
	(arc
		(start 357.888032 -222.437198)
		(mid 357.700834 -222.387055)
		(end 357.513636 -222.437198)
		(width 0.0889)
		(layer "In4.Cu")
		(net "VSENSE_PVCCFA_EHV_CPU0_DP")
	)
	(arc
		(start 350.935036 -222.437198)
		(mid 350.660837 -222.513033)
		(end 350.384364 -222.445834)
		(width 0.0889)
		(layer "In4.Cu")
		(net "VSENSE_PVCCFA_EHV_CPU0_DP")
	)
	(arc
		(start 382.887982 -217.554048)
		(mid 382.753049 -217.687402)
		(end 382.700784 -217.86977)
		(width 0.0889)
		(layer "In4.Cu")
		(net "VSENSE_PVCCFA_EHV_CPU0_DP")
	)
	(arc
		(start 383.732532 -216.739978)
		(mid 383.545334 -216.689835)
		(end 383.358136 -216.739978)
		(width 0.0889)
		(layer "In4.Cu")
		(net "VSENSE_PVCCFA_EHV_CPU0_DP")
	)
	(arc
		(start 377.623832 -219.18168)
		(mid 377.436634 -219.131537)
		(end 377.249436 -219.18168)
		(width 0.0889)
		(layer "In4.Cu")
		(net "VSENSE_PVCCFA_EHV_CPU0_DP")
	)
	(arc
		(start 368.225832 -219.18168)
		(mid 368.038634 -219.131537)
		(end 367.851436 -219.18168)
		(width 0.0889)
		(layer "In4.Cu")
		(net "VSENSE_PVCCFA_EHV_CPU0_DP")
	)
	(arc
		(start 373.490236 -219.18168)
		(mid 373.216037 -219.257515)
		(end 372.939564 -219.190316)
		(width 0.0889)
		(layer "In4.Cu")
		(net "VSENSE_PVCCFA_EHV_CPU0_DP")
	)
	(arc
		(start 358.735884 -221.957646)
		(mid 358.657773 -222.234595)
		(end 358.453436 -222.437198)
		(width 0.0889)
		(layer "In4.Cu")
		(net "VSENSE_PVCCFA_EHV_CPU0_DP")
	)
	(arc
		(start 361.272836 -219.18168)
		(mid 360.998637 -219.257515)
		(end 360.722164 -219.190316)
		(width 0.0889)
		(layer "In4.Cu")
		(net "VSENSE_PVCCFA_EHV_CPU0_DP")
	)
	(arc
		(start 375.369836 -219.18168)
		(mid 375.095637 -219.257515)
		(end 374.819164 -219.190316)
		(width 0.0889)
		(layer "In4.Cu")
		(net "VSENSE_PVCCFA_EHV_CPU0_DP")
	)
	(arc
		(start 367.286032 -219.18168)
		(mid 367.098834 -219.131537)
		(end 366.911636 -219.18168)
		(width 0.0889)
		(layer "In4.Cu")
		(net "VSENSE_PVCCFA_EHV_CPU0_DP")
	)
	(arc
		(start 371.985032 -219.18168)
		(mid 371.797834 -219.131537)
		(end 371.610636 -219.18168)
		(width 0.0889)
		(layer "In4.Cu")
		(net "VSENSE_PVCCFA_EHV_CPU0_DP")
	)
	(arc
		(start 359.297732 -221.623382)
		(mid 359.110534 -221.573239)
		(end 358.923336 -221.623382)
		(width 0.0889)
		(layer "In4.Cu")
		(net "VSENSE_PVCCFA_EHV_CPU0_DP")
	)
	(arc
		(start 356.008432 -222.437198)
		(mid 355.821234 -222.387055)
		(end 355.634036 -222.437198)
		(width 0.0889)
		(layer "In4.Cu")
		(net "VSENSE_PVCCFA_EHV_CPU0_DP")
	)
	(arc
		(start 365.971836 -219.18168)
		(mid 365.697637 -219.257515)
		(end 365.421164 -219.190316)
		(width 0.0889)
		(layer "In4.Cu")
		(net "VSENSE_PVCCFA_EHV_CPU0_DP")
	)
	(arc
		(start 365.406432 -219.18168)
		(mid 365.219234 -219.131537)
		(end 365.032036 -219.18168)
		(width 0.0889)
		(layer "In4.Cu")
		(net "VSENSE_PVCCFA_EHV_CPU0_DP")
	)
	(arc
		(start 369.731036 -219.18168)
		(mid 369.456837 -219.257515)
		(end 369.180364 -219.190316)
		(width 0.0889)
		(layer "In4.Cu")
		(net "VSENSE_PVCCFA_EHV_CPU0_DP")
	)
	(arc
		(start 381.008636 -219.18168)
		(mid 380.734437 -219.257515)
		(end 380.457964 -219.190316)
		(width 0.0889)
		(layer "In4.Cu")
		(net "VSENSE_PVCCFA_EHV_CPU0_DP")
	)
	(arc
		(start 375.744232 -219.18168)
		(mid 375.557034 -219.131537)
		(end 375.369836 -219.18168)
		(width 0.0889)
		(layer "In4.Cu")
		(net "VSENSE_PVCCFA_EHV_CPU0_DP")
	)
	(arc
		(start 359.852468 -221.629478)
		(mid 359.57429 -221.699201)
		(end 359.297732 -221.623382)
		(width 0.0889)
		(layer "In4.Cu")
		(net "VSENSE_PVCCFA_EHV_CPU0_DP")
	)
	(arc
		(start 362.212636 -219.18168)
		(mid 361.929934 -219.257456)
		(end 361.647232 -219.18168)
		(width 0.0889)
		(layer "In4.Cu")
		(net "VSENSE_PVCCFA_EHV_CPU0_DP")
	)
	(arc
		(start 370.105432 -219.18168)
		(mid 369.918234 -219.131537)
		(end 369.731036 -219.18168)
		(width 0.0889)
		(layer "In4.Cu")
		(net "VSENSE_PVCCFA_EHV_CPU0_DP")
	)
	(arc
		(start 351.874836 -222.437198)
		(mid 351.600637 -222.513033)
		(end 351.324164 -222.445834)
		(width 0.0889)
		(layer "In4.Cu")
		(net "VSENSE_PVCCFA_EHV_CPU0_DP")
	)
	(arc
		(start 370.670836 -219.18168)
		(mid 370.396637 -219.257515)
		(end 370.120164 -219.190316)
		(width 0.0889)
		(layer "In4.Cu")
		(net "VSENSE_PVCCFA_EHV_CPU0_DP")
	)
	(arc
		(start 382.700784 -217.888312)
		(mid 382.622673 -218.165261)
		(end 382.418336 -218.367864)
		(width 0.0889)
		(layer "In4.Cu")
		(net "VSENSE_PVCCFA_EHV_CPU0_DP")
	)
	(arc
		(start 376.684032 -219.18168)
		(mid 376.496834 -219.131537)
		(end 376.309636 -219.18168)
		(width 0.0889)
		(layer "In4.Cu")
		(net "VSENSE_PVCCFA_EHV_CPU0_DP")
	)
	(arc
		(start 354.128832 -222.437198)
		(mid 353.941634 -222.387055)
		(end 353.754436 -222.437198)
		(width 0.0889)
		(layer "In4.Cu")
		(net "VSENSE_PVCCFA_EHV_CPU0_DP")
	)
	(arc
		(start 371.045232 -219.18168)
		(mid 370.858034 -219.131537)
		(end 370.670836 -219.18168)
		(width 0.0889)
		(layer "In4.Cu")
		(net "VSENSE_PVCCFA_EHV_CPU0_DP")
	)
	(arc
		(start 381.383032 -219.18168)
		(mid 381.195834 -219.131537)
		(end 381.008636 -219.18168)
		(width 0.0889)
		(layer "In4.Cu")
		(net "VSENSE_PVCCFA_EHV_CPU0_DP")
	)
	(arc
		(start 356.948232 -222.437198)
		(mid 356.761034 -222.387055)
		(end 356.573836 -222.437198)
		(width 0.0889)
		(layer "In4.Cu")
		(net "VSENSE_PVCCFA_EHV_CPU0_DP")
	)
	(arc
		(start 360.145584 -219.515944)
		(mid 360.067473 -219.792893)
		(end 359.863136 -219.995496)
		(width 0.0889)
		(layer "In4.Cu")
		(net "VSENSE_PVCCFA_EHV_CPU0_DP")
	)
	(arc
		(start 365.032036 -219.18168)
		(mid 364.757837 -219.257515)
		(end 364.481364 -219.190316)
		(width 0.0889)
		(layer "In4.Cu")
		(net "VSENSE_PVCCFA_EHV_CPU0_DP")
	)
	(arc
		(start 355.068632 -222.437198)
		(mid 354.881434 -222.387055)
		(end 354.694236 -222.437198)
		(width 0.0889)
		(layer "In4.Cu")
		(net "VSENSE_PVCCFA_EHV_CPU0_DP")
	)
	(arc
		(start 359.854246 -220.000576)
		(mid 359.675649 -220.319854)
		(end 359.854246 -220.639132)
		(width 0.0889)
		(layer "In4.Cu")
		(net "VSENSE_PVCCFA_EHV_CPU0_DP")
	)
	(arc
		(start 378.189236 -219.18168)
		(mid 377.915037 -219.257515)
		(end 377.638564 -219.190316)
		(width 0.0889)
		(layer "In4.Cu")
		(net "VSENSE_PVCCFA_EHV_CPU0_DP")
	)
	(arc
		(start 363.526832 -219.18168)
		(mid 363.339634 -219.131537)
		(end 363.152436 -219.18168)
		(width 0.0889)
		(layer "In4.Cu")
		(net "VSENSE_PVCCFA_EHV_CPU0_DP")
	)
	(arc
		(start 384.297936 -216.739978)
		(mid 384.015234 -216.815754)
		(end 383.732532 -216.739978)
		(width 0.0889)
		(layer "In4.Cu")
		(net "VSENSE_PVCCFA_EHV_CPU0_DP")
	)
	(arc
		(start 374.430036 -219.18168)
		(mid 374.155837 -219.257515)
		(end 373.879364 -219.190316)
		(width 0.0889)
		(layer "In4.Cu")
		(net "VSENSE_PVCCFA_EHV_CPU0_DP")
	)
	(arc
		(start 385.237736 -216.739978)
		(mid 384.955034 -216.815754)
		(end 384.672332 -216.739978)
		(width 0.0889)
		(layer "In4.Cu")
		(net "VSENSE_PVCCFA_EHV_CPU0_DP")
	)
	(arc
		(start 366.911636 -219.18168)
		(mid 366.637437 -219.257515)
		(end 366.360964 -219.190316)
		(width 0.0889)
		(layer "In4.Cu")
		(net "VSENSE_PVCCFA_EHV_CPU0_DP")
	)
	(arc
		(start 352.249232 -222.437198)
		(mid 352.062034 -222.387089)
		(end 351.874836 -222.437198)
		(width 0.0889)
		(layer "In4.Cu")
		(net "VSENSE_PVCCFA_EHV_CPU0_DP")
	)
	(arc
		(start 380.443232 -219.18168)
		(mid 380.256034 -219.131537)
		(end 380.068836 -219.18168)
		(width 0.0889)
		(layer "In4.Cu")
		(net "VSENSE_PVCCFA_EHV_CPU0_DP")
	)
	(arc
		(start 351.309432 -222.437198)
		(mid 351.122234 -222.387055)
		(end 350.935036 -222.437198)
		(width 0.0889)
		(layer "In4.Cu")
		(net "VSENSE_PVCCFA_EHV_CPU0_DP")
	)
	(arc
		(start 378.563632 -219.18168)
		(mid 378.376434 -219.131537)
		(end 378.189236 -219.18168)
		(width 0.0889)
		(layer "In4.Cu")
		(net "VSENSE_PVCCFA_EHV_CPU0_DP")
	)
	(arc
		(start 382.230884 -218.702128)
		(mid 382.152773 -218.979077)
		(end 381.948436 -219.18168)
		(width 0.0889)
		(layer "In4.Cu")
		(net "VSENSE_PVCCFA_EHV_CPU0_DP")
	)
	(segment
		(start 422.529508 -140.99921)
		(end 422.770808 -141.24051)
		(width 0.254)
		(layer "In13.Cu")
		(net "VSENSE_PVCCFA_EHV_CPU0_DP")
	)
	(segment
		(start 397.8783 -145.93062)
		(end 397.8783 -145.657824)
		(width 0.254)
		(layer "In13.Cu")
		(net "VSENSE_PVCCFA_EHV_CPU0_DP")
	)
	(segment
		(start 397.955008 -146.007328)
		(end 397.8783 -145.93062)
		(width 0.254)
		(layer "In13.Cu")
		(net "VSENSE_PVCCFA_EHV_CPU0_DP")
	)
	(segment
		(start 420.864792 -143.431768)
		(end 401.037552 -143.431768)
		(width 0.254)
		(layer "In13.Cu")
		(net "VSENSE_PVCCFA_EHV_CPU0_DP")
	)
	(segment
		(start 401.037552 -143.431768)
		(end 398.461992 -146.007328)
		(width 0.254)
		(layer "In13.Cu")
		(net "VSENSE_PVCCFA_EHV_CPU0_DP")
	)
	(segment
		(start 397.8783 -145.657824)
		(end 398.046956 -145.489168)
		(width 0.254)
		(layer "In13.Cu")
		(net "VSENSE_PVCCFA_EHV_CPU0_DP")
	)
	(segment
		(start 398.461992 -146.007328)
		(end 397.955008 -146.007328)
		(width 0.254)
		(layer "In13.Cu")
		(net "VSENSE_PVCCFA_EHV_CPU0_DP")
	)
	(segment
		(start 422.770808 -141.24051)
		(end 422.770808 -141.525752)
		(width 0.254)
		(layer "In13.Cu")
		(net "VSENSE_PVCCFA_EHV_CPU0_DP")
	)
	(segment
		(start 422.770808 -141.525752)
		(end 420.864792 -143.431768)
		(width 0.254)
		(layer "In13.Cu")
		(net "VSENSE_PVCCFA_EHV_CPU0_DP")
	)
	(segment
		(start 397.183356 -145.489168)
		(end 397.571976 -145.877788)
		(width 0.254)
		(layer "F.Cu")
		(net "VSENSE_PVCCFA_EHV_CPU0_DN")
	)
	(segment
		(start 423.30497 -139.37107)
		(end 422.879012 -139.797028)
		(width 0.254)
		(layer "F.Cu")
		(net "VSENSE_PVCCFA_EHV_CPU0_DN")
	)
	(segment
		(start 423.393108 -140.311124)
		(end 422.879012 -139.797028)
		(width 0.254)
		(layer "F.Cu")
		(net "VSENSE_PVCCFA_EHV_CPU0_DN")
	)
	(segment
		(start 397.571976 -147.292568)
		(end 397.254476 -147.610068)
		(width 0.254)
		(layer "F.Cu")
		(net "VSENSE_PVCCFA_EHV_CPU0_DN")
	)
	(segment
		(start 397.571976 -145.877788)
		(end 397.571976 -147.292568)
		(width 0.254)
		(layer "F.Cu")
		(net "VSENSE_PVCCFA_EHV_CPU0_DN")
	)
	(segment
		(start 351.592134 -222.48368)
		(end 351.592134 -221.947994)
		(width 0.2032)
		(layer "F.Cu")
		(net "VSENSE_PVCCFA_EHV_CPU0_DN")
	)
	(segment
		(start 423.30497 -138.214608)
		(end 423.30497 -139.37107)
		(width 0.254)
		(layer "F.Cu")
		(net "VSENSE_PVCCFA_EHV_CPU0_DN")
	)
	(segment
		(start 351.592134 -221.947994)
		(end 351.59188 -221.94774)
		(width 0.2032)
		(layer "F.Cu")
		(net "VSENSE_PVCCFA_EHV_CPU0_DN")
	)
	(segment
		(start 423.393108 -140.99921)
		(end 423.393108 -140.311124)
		(width 0.254)
		(layer "F.Cu")
		(net "VSENSE_PVCCFA_EHV_CPU0_DN")
	)
	(via
		(at 351.59188 -221.94774)
		(size 0.4572)
		(drill 0.2032)
		(layers "F.Cu" "B.Cu")
		(net "VSENSE_PVCCFA_EHV_CPU0_DN")
	)
	(via
		(at 397.183356 -145.489168)
		(size 0.508)
		(drill 0.254)
		(layers "F.Cu" "B.Cu")
		(net "VSENSE_PVCCFA_EHV_CPU0_DN")
	)
	(via
		(at 423.393108 -140.99921)
		(size 0.508)
		(drill 0.254)
		(layers "F.Cu" "B.Cu")
		(net "VSENSE_PVCCFA_EHV_CPU0_DN")
	)
	(segment
		(start 382.51003 -217.864182)
		(end 382.51003 -217.887042)
		(width 0.0889)
		(layer "In4.Cu")
		(net "VSENSE_PVCCFA_EHV_CPU0_DN")
	)
	(segment
		(start 353.284282 -222.272098)
		(end 353.26955 -222.263462)
		(width 0.0889)
		(layer "In4.Cu")
		(net "VSENSE_PVCCFA_EHV_CPU0_DN")
	)
	(segment
		(start 386.092192 -210.760056)
		(end 386.092192 -210.796124)
		(width 0.254)
		(layer "In4.Cu")
		(net "VSENSE_PVCCFA_EHV_CPU0_DN")
	)
	(segment
		(start 385.717034 -214.796116)
		(end 385.799584 -214.878666)
		(width 0.0889)
		(layer "In4.Cu")
		(net "VSENSE_PVCCFA_EHV_CPU0_DN")
	)
	(segment
		(start 352.068384 -222.196152)
		(end 351.840292 -222.196152)
		(width 0.0889)
		(layer "In4.Cu")
		(net "VSENSE_PVCCFA_EHV_CPU0_DN")
	)
	(segment
		(start 397.14424 -155.141168)
		(end 392.982958 -159.30245)
		(width 0.254)
		(layer "In4.Cu")
		(net "VSENSE_PVCCFA_EHV_CPU0_DN")
	)
	(segment
		(start 359.776522 -219.825316)
		(end 359.767632 -219.830396)
		(width 0.0889)
		(layer "In4.Cu")
		(net "VSENSE_PVCCFA_EHV_CPU0_DN")
	)
	(segment
		(start 382.801622 -217.383614)
		(end 382.792732 -217.388694)
		(width 0.0889)
		(layer "In4.Cu")
		(net "VSENSE_PVCCFA_EHV_CPU0_DN")
	)
	(segment
		(start 365.501682 -219.01658)
		(end 365.48695 -219.007944)
		(width 0.0889)
		(layer "In4.Cu")
		(net "VSENSE_PVCCFA_EHV_CPU0_DN")
	)
	(segment
		(start 359.955084 -219.490544)
		(end 359.955084 -219.506038)
		(width 0.0889)
		(layer "In4.Cu")
		(net "VSENSE_PVCCFA_EHV_CPU0_DN")
	)
	(segment
		(start 359.767632 -220.809566)
		(end 359.768394 -220.810074)
		(width 0.0889)
		(layer "In4.Cu")
		(net "VSENSE_PVCCFA_EHV_CPU0_DN")
	)
	(segment
		(start 378.658882 -219.01658)
		(end 378.64415 -219.007944)
		(width 0.0889)
		(layer "In4.Cu")
		(net "VSENSE_PVCCFA_EHV_CPU0_DN")
	)
	(segment
		(start 368.321082 -219.01658)
		(end 368.30635 -219.007944)
		(width 0.0889)
		(layer "In4.Cu")
		(net "VSENSE_PVCCFA_EHV_CPU0_DN")
	)
	(segment
		(start 380.538482 -219.01658)
		(end 380.52375 -219.007944)
		(width 0.0889)
		(layer "In4.Cu")
		(net "VSENSE_PVCCFA_EHV_CPU0_DN")
	)
	(segment
		(start 385.621022 -215.755982)
		(end 385.612132 -215.761062)
		(width 0.0889)
		(layer "In4.Cu")
		(net "VSENSE_PVCCFA_EHV_CPU0_DN")
	)
	(segment
		(start 391.591038 -205.26121)
		(end 386.092192 -210.760056)
		(width 0.254)
		(layer "In4.Cu")
		(net "VSENSE_PVCCFA_EHV_CPU0_DN")
	)
	(segment
		(start 359.768394 -220.810074)
		(end 359.776522 -220.814646)
		(width 0.0889)
		(layer "In4.Cu")
		(net "VSENSE_PVCCFA_EHV_CPU0_DN")
	)
	(segment
		(start 351.840292 -222.196152)
		(end 351.59188 -221.94774)
		(width 0.0889)
		(layer "In4.Cu")
		(net "VSENSE_PVCCFA_EHV_CPU0_DN")
	)
	(segment
		(start 358.545384 -221.937834)
		(end 358.545384 -221.94774)
		(width 0.0889)
		(layer "In4.Cu")
		(net "VSENSE_PVCCFA_EHV_CPU0_DN")
	)
	(segment
		(start 359.776522 -221.453202)
		(end 359.769156 -221.45752)
		(width 0.0889)
		(layer "In4.Cu")
		(net "VSENSE_PVCCFA_EHV_CPU0_DN")
	)
	(segment
		(start 392.982958 -159.30245)
		(end 392.982958 -170.622722)
		(width 0.254)
		(layer "In4.Cu")
		(net "VSENSE_PVCCFA_EHV_CPU0_DN")
	)
	(segment
		(start 381.861822 -219.0115)
		(end 381.852932 -219.01658)
		(width 0.0889)
		(layer "In4.Cu")
		(net "VSENSE_PVCCFA_EHV_CPU0_DN")
	)
	(segment
		(start 372.080282 -219.01658)
		(end 372.06555 -219.007944)
		(width 0.0889)
		(layer "In4.Cu")
		(net "VSENSE_PVCCFA_EHV_CPU0_DN")
	)
	(segment
		(start 357.983536 -222.272098)
		(end 357.973122 -222.266002)
		(width 0.0889)
		(layer "In4.Cu")
		(net "VSENSE_PVCCFA_EHV_CPU0_DN")
	)
	(segment
		(start 355.163882 -222.272098)
		(end 355.14915 -222.263462)
		(width 0.0889)
		(layer "In4.Cu")
		(net "VSENSE_PVCCFA_EHV_CPU0_DN")
	)
	(segment
		(start 374.899682 -219.01658)
		(end 374.88495 -219.007944)
		(width 0.0889)
		(layer "In4.Cu")
		(net "VSENSE_PVCCFA_EHV_CPU0_DN")
	)
	(segment
		(start 385.329684 -216.240614)
		(end 385.329684 -216.25052)
		(width 0.0889)
		(layer "In4.Cu")
		(net "VSENSE_PVCCFA_EHV_CPU0_DN")
	)
	(segment
		(start 359.767632 -219.830396)
		(end 359.75544 -219.837508)
		(width 0.0889)
		(layer "In4.Cu")
		(net "VSENSE_PVCCFA_EHV_CPU0_DN")
	)
	(segment
		(start 370.200682 -219.01658)
		(end 370.18595 -219.007944)
		(width 0.0889)
		(layer "In4.Cu")
		(net "VSENSE_PVCCFA_EHV_CPU0_DN")
	)
	(segment
		(start 369.260882 -219.01658)
		(end 369.24615 -219.007944)
		(width 0.0889)
		(layer "In4.Cu")
		(net "VSENSE_PVCCFA_EHV_CPU0_DN")
	)
	(segment
		(start 356.103682 -222.272098)
		(end 356.08895 -222.263462)
		(width 0.0889)
		(layer "In4.Cu")
		(net "VSENSE_PVCCFA_EHV_CPU0_DN")
	)
	(segment
		(start 397.183356 -145.489168)
		(end 397.424656 -145.730468)
		(width 0.254)
		(layer "In4.Cu")
		(net "VSENSE_PVCCFA_EHV_CPU0_DN")
	)
	(segment
		(start 375.839482 -219.01658)
		(end 375.82475 -219.007944)
		(width 0.0889)
		(layer "In4.Cu")
		(net "VSENSE_PVCCFA_EHV_CPU0_DN")
	)
	(segment
		(start 392.982958 -170.622722)
		(end 391.591038 -172.014642)
		(width 0.254)
		(layer "In4.Cu")
		(net "VSENSE_PVCCFA_EHV_CPU0_DN")
	)
	(segment
		(start 357.043482 -222.272098)
		(end 357.02875 -222.263462)
		(width 0.0889)
		(layer "In4.Cu")
		(net "VSENSE_PVCCFA_EHV_CPU0_DN")
	)
	(segment
		(start 385.799584 -214.878666)
		(end 385.799584 -215.436704)
		(width 0.0889)
		(layer "In4.Cu")
		(net "VSENSE_PVCCFA_EHV_CPU0_DN")
	)
	(segment
		(start 385.717034 -211.171282)
		(end 385.717034 -214.754968)
		(width 0.254)
		(layer "In4.Cu")
		(net "VSENSE_PVCCFA_EHV_CPU0_DN")
	)
	(segment
		(start 358.366822 -222.267018)
		(end 358.357932 -222.272098)
		(width 0.0889)
		(layer "In4.Cu")
		(net "VSENSE_PVCCFA_EHV_CPU0_DN")
	)
	(segment
		(start 359.769156 -221.45752)
		(end 359.767632 -221.458282)
		(width 0.0889)
		(layer "In4.Cu")
		(net "VSENSE_PVCCFA_EHV_CPU0_DN")
	)
	(segment
		(start 397.424656 -145.730468)
		(end 397.424656 -147.311872)
		(width 0.254)
		(layer "In4.Cu")
		(net "VSENSE_PVCCFA_EHV_CPU0_DN")
	)
	(segment
		(start 360.802682 -219.01658)
		(end 360.78795 -219.007944)
		(width 0.0889)
		(layer "In4.Cu")
		(net "VSENSE_PVCCFA_EHV_CPU0_DN")
	)
	(segment
		(start 354.224082 -222.272098)
		(end 354.20935 -222.263462)
		(width 0.0889)
		(layer "In4.Cu")
		(net "VSENSE_PVCCFA_EHV_CPU0_DN")
	)
	(segment
		(start 379.598682 -219.01658)
		(end 379.58395 -219.007944)
		(width 0.0889)
		(layer "In4.Cu")
		(net "VSENSE_PVCCFA_EHV_CPU0_DN")
	)
	(segment
		(start 382.040384 -218.682316)
		(end 382.040384 -218.692222)
		(width 0.0889)
		(layer "In4.Cu")
		(net "VSENSE_PVCCFA_EHV_CPU0_DN")
	)
	(segment
		(start 373.959882 -219.01658)
		(end 373.94515 -219.007944)
		(width 0.0889)
		(layer "In4.Cu")
		(net "VSENSE_PVCCFA_EHV_CPU0_DN")
	)
	(segment
		(start 371.140482 -219.01658)
		(end 371.12575 -219.007944)
		(width 0.0889)
		(layer "In4.Cu")
		(net "VSENSE_PVCCFA_EHV_CPU0_DN")
	)
	(segment
		(start 385.717034 -214.754968)
		(end 385.717034 -214.796116)
		(width 0.0889)
		(layer "In4.Cu")
		(net "VSENSE_PVCCFA_EHV_CPU0_DN")
	)
	(segment
		(start 364.561882 -219.01658)
		(end 364.54715 -219.007944)
		(width 0.0889)
		(layer "In4.Cu")
		(net "VSENSE_PVCCFA_EHV_CPU0_DN")
	)
	(segment
		(start 376.779282 -219.01658)
		(end 376.76455 -219.007944)
		(width 0.0889)
		(layer "In4.Cu")
		(net "VSENSE_PVCCFA_EHV_CPU0_DN")
	)
	(segment
		(start 367.381282 -219.01658)
		(end 367.36655 -219.007944)
		(width 0.0889)
		(layer "In4.Cu")
		(net "VSENSE_PVCCFA_EHV_CPU0_DN")
	)
	(segment
		(start 382.980184 -217.05443)
		(end 382.980184 -217.064336)
		(width 0.0889)
		(layer "In4.Cu")
		(net "VSENSE_PVCCFA_EHV_CPU0_DN")
	)
	(segment
		(start 385.151122 -216.569798)
		(end 385.142232 -216.574878)
		(width 0.0889)
		(layer "In4.Cu")
		(net "VSENSE_PVCCFA_EHV_CPU0_DN")
	)
	(segment
		(start 397.14424 -147.592288)
		(end 397.14424 -155.141168)
		(width 0.254)
		(layer "In4.Cu")
		(net "VSENSE_PVCCFA_EHV_CPU0_DN")
	)
	(segment
		(start 363.622082 -219.01658)
		(end 363.611668 -219.010484)
		(width 0.0889)
		(layer "In4.Cu")
		(net "VSENSE_PVCCFA_EHV_CPU0_DN")
	)
	(segment
		(start 377.719082 -219.01658)
		(end 377.70435 -219.007944)
		(width 0.0889)
		(layer "In4.Cu")
		(net "VSENSE_PVCCFA_EHV_CPU0_DN")
	)
	(segment
		(start 359.48493 -220.319854)
		(end 359.48493 -220.327474)
		(width 0.0889)
		(layer "In4.Cu")
		(net "VSENSE_PVCCFA_EHV_CPU0_DN")
	)
	(segment
		(start 381.478536 -219.01658)
		(end 381.468122 -219.010484)
		(width 0.0889)
		(layer "In4.Cu")
		(net "VSENSE_PVCCFA_EHV_CPU0_DN")
	)
	(segment
		(start 397.424656 -147.311872)
		(end 397.14424 -147.592288)
		(width 0.254)
		(layer "In4.Cu")
		(net "VSENSE_PVCCFA_EHV_CPU0_DN")
	)
	(segment
		(start 391.591038 -172.014642)
		(end 391.591038 -205.26121)
		(width 0.254)
		(layer "In4.Cu")
		(net "VSENSE_PVCCFA_EHV_CPU0_DN")
	)
	(segment
		(start 361.742736 -219.01658)
		(end 361.732322 -219.010484)
		(width 0.0889)
		(layer "In4.Cu")
		(net "VSENSE_PVCCFA_EHV_CPU0_DN")
	)
	(segment
		(start 373.020082 -219.01658)
		(end 373.00535 -219.007944)
		(width 0.0889)
		(layer "In4.Cu")
		(net "VSENSE_PVCCFA_EHV_CPU0_DN")
	)
	(segment
		(start 386.092192 -210.796124)
		(end 385.717034 -211.171282)
		(width 0.254)
		(layer "In4.Cu")
		(net "VSENSE_PVCCFA_EHV_CPU0_DN")
	)
	(segment
		(start 352.344482 -222.272098)
		(end 352.32975 -222.263462)
		(width 0.0889)
		(layer "In4.Cu")
		(net "VSENSE_PVCCFA_EHV_CPU0_DN")
	)
	(segment
		(start 366.441482 -219.01658)
		(end 366.42675 -219.007944)
		(width 0.0889)
		(layer "In4.Cu")
		(net "VSENSE_PVCCFA_EHV_CPU0_DN")
	)
	(arc
		(start 357.973122 -222.266002)
		(mid 357.69469 -222.196156)
		(end 357.417878 -222.272098)
		(width 0.0889)
		(layer "In4.Cu")
		(net "VSENSE_PVCCFA_EHV_CPU0_DN")
	)
	(arc
		(start 361.732322 -219.010484)
		(mid 361.45389 -218.940638)
		(end 361.177078 -219.01658)
		(width 0.0889)
		(layer "In4.Cu")
		(net "VSENSE_PVCCFA_EHV_CPU0_DN")
	)
	(arc
		(start 353.658678 -222.272098)
		(mid 353.47148 -222.322241)
		(end 353.284282 -222.272098)
		(width 0.0889)
		(layer "In4.Cu")
		(net "VSENSE_PVCCFA_EHV_CPU0_DN")
	)
	(arc
		(start 373.94515 -219.007944)
		(mid 373.668675 -218.940624)
		(end 373.394478 -219.01658)
		(width 0.0889)
		(layer "In4.Cu")
		(net "VSENSE_PVCCFA_EHV_CPU0_DN")
	)
	(arc
		(start 385.799584 -215.436704)
		(mid 385.751905 -215.619604)
		(end 385.621022 -215.755982)
		(width 0.0889)
		(layer "In4.Cu")
		(net "VSENSE_PVCCFA_EHV_CPU0_DN")
	)
	(arc
		(start 370.575078 -219.01658)
		(mid 370.38788 -219.066723)
		(end 370.200682 -219.01658)
		(width 0.0889)
		(layer "In4.Cu")
		(net "VSENSE_PVCCFA_EHV_CPU0_DN")
	)
	(arc
		(start 381.852932 -219.01658)
		(mid 381.665734 -219.066723)
		(end 381.478536 -219.01658)
		(width 0.0889)
		(layer "In4.Cu")
		(net "VSENSE_PVCCFA_EHV_CPU0_DN")
	)
	(arc
		(start 379.973078 -219.01658)
		(mid 379.78588 -219.066723)
		(end 379.598682 -219.01658)
		(width 0.0889)
		(layer "In4.Cu")
		(net "VSENSE_PVCCFA_EHV_CPU0_DN")
	)
	(arc
		(start 359.393236 -221.458282)
		(mid 359.110534 -221.382506)
		(end 358.827832 -221.458282)
		(width 0.0889)
		(layer "In4.Cu")
		(net "VSENSE_PVCCFA_EHV_CPU0_DN")
	)
	(arc
		(start 374.334278 -219.01658)
		(mid 374.14708 -219.066723)
		(end 373.959882 -219.01658)
		(width 0.0889)
		(layer "In4.Cu")
		(net "VSENSE_PVCCFA_EHV_CPU0_DN")
	)
	(arc
		(start 373.00535 -219.007944)
		(mid 372.728875 -218.940624)
		(end 372.454678 -219.01658)
		(width 0.0889)
		(layer "In4.Cu")
		(net "VSENSE_PVCCFA_EHV_CPU0_DN")
	)
	(arc
		(start 354.20935 -222.263462)
		(mid 353.932875 -222.196142)
		(end 353.658678 -222.272098)
		(width 0.0889)
		(layer "In4.Cu")
		(net "VSENSE_PVCCFA_EHV_CPU0_DN")
	)
	(arc
		(start 382.322832 -218.202764)
		(mid 382.118497 -218.405369)
		(end 382.040384 -218.682316)
		(width 0.0889)
		(layer "In4.Cu")
		(net "VSENSE_PVCCFA_EHV_CPU0_DN")
	)
	(arc
		(start 356.478078 -222.272098)
		(mid 356.29088 -222.322241)
		(end 356.103682 -222.272098)
		(width 0.0889)
		(layer "In4.Cu")
		(net "VSENSE_PVCCFA_EHV_CPU0_DN")
	)
	(arc
		(start 358.357932 -222.272098)
		(mid 358.170734 -222.322241)
		(end 357.983536 -222.272098)
		(width 0.0889)
		(layer "In4.Cu")
		(net "VSENSE_PVCCFA_EHV_CPU0_DN")
	)
	(arc
		(start 376.213878 -219.01658)
		(mid 376.02668 -219.066723)
		(end 375.839482 -219.01658)
		(width 0.0889)
		(layer "In4.Cu")
		(net "VSENSE_PVCCFA_EHV_CPU0_DN")
	)
	(arc
		(start 377.70435 -219.007944)
		(mid 377.427875 -218.940624)
		(end 377.153678 -219.01658)
		(width 0.0889)
		(layer "In4.Cu")
		(net "VSENSE_PVCCFA_EHV_CPU0_DN")
	)
	(arc
		(start 376.76455 -219.007944)
		(mid 376.488075 -218.940624)
		(end 376.213878 -219.01658)
		(width 0.0889)
		(layer "In4.Cu")
		(net "VSENSE_PVCCFA_EHV_CPU0_DN")
	)
	(arc
		(start 364.54715 -219.007944)
		(mid 364.270675 -218.940624)
		(end 363.996478 -219.01658)
		(width 0.0889)
		(layer "In4.Cu")
		(net "VSENSE_PVCCFA_EHV_CPU0_DN")
	)
	(arc
		(start 359.48493 -220.327474)
		(mid 359.562559 -220.605887)
		(end 359.767632 -220.809566)
		(width 0.0889)
		(layer "In4.Cu")
		(net "VSENSE_PVCCFA_EHV_CPU0_DN")
	)
	(arc
		(start 360.78795 -219.007944)
		(mid 360.511475 -218.940624)
		(end 360.237278 -219.01658)
		(width 0.0889)
		(layer "In4.Cu")
		(net "VSENSE_PVCCFA_EHV_CPU0_DN")
	)
	(arc
		(start 368.30635 -219.007944)
		(mid 368.029875 -218.940624)
		(end 367.755678 -219.01658)
		(width 0.0889)
		(layer "In4.Cu")
		(net "VSENSE_PVCCFA_EHV_CPU0_DN")
	)
	(arc
		(start 373.394478 -219.01658)
		(mid 373.20728 -219.066723)
		(end 373.020082 -219.01658)
		(width 0.0889)
		(layer "In4.Cu")
		(net "VSENSE_PVCCFA_EHV_CPU0_DN")
	)
	(arc
		(start 381.468122 -219.010484)
		(mid 381.18969 -218.940638)
		(end 380.912878 -219.01658)
		(width 0.0889)
		(layer "In4.Cu")
		(net "VSENSE_PVCCFA_EHV_CPU0_DN")
	)
	(arc
		(start 372.06555 -219.007944)
		(mid 371.789075 -218.940624)
		(end 371.514878 -219.01658)
		(width 0.0889)
		(layer "In4.Cu")
		(net "VSENSE_PVCCFA_EHV_CPU0_DN")
	)
	(arc
		(start 358.545384 -221.94774)
		(mid 358.497705 -222.13064)
		(end 358.366822 -222.267018)
		(width 0.0889)
		(layer "In4.Cu")
		(net "VSENSE_PVCCFA_EHV_CPU0_DN")
	)
	(arc
		(start 352.32975 -222.263462)
		(mid 352.203145 -222.213964)
		(end 352.068384 -222.196152)
		(width 0.0889)
		(layer "In4.Cu")
		(net "VSENSE_PVCCFA_EHV_CPU0_DN")
	)
	(arc
		(start 366.42675 -219.007944)
		(mid 366.150275 -218.940624)
		(end 365.876078 -219.01658)
		(width 0.0889)
		(layer "In4.Cu")
		(net "VSENSE_PVCCFA_EHV_CPU0_DN")
	)
	(arc
		(start 371.12575 -219.007944)
		(mid 370.849275 -218.940624)
		(end 370.575078 -219.01658)
		(width 0.0889)
		(layer "In4.Cu")
		(net "VSENSE_PVCCFA_EHV_CPU0_DN")
	)
	(arc
		(start 362.682536 -219.01658)
		(mid 362.399834 -218.940804)
		(end 362.117132 -219.01658)
		(width 0.0889)
		(layer "In4.Cu")
		(net "VSENSE_PVCCFA_EHV_CPU0_DN")
	)
	(arc
		(start 364.936278 -219.01658)
		(mid 364.74908 -219.066723)
		(end 364.561882 -219.01658)
		(width 0.0889)
		(layer "In4.Cu")
		(net "VSENSE_PVCCFA_EHV_CPU0_DN")
	)
	(arc
		(start 368.695478 -219.01658)
		(mid 368.50828 -219.066723)
		(end 368.321082 -219.01658)
		(width 0.0889)
		(layer "In4.Cu")
		(net "VSENSE_PVCCFA_EHV_CPU0_DN")
	)
	(arc
		(start 370.18595 -219.007944)
		(mid 369.909475 -218.940624)
		(end 369.635278 -219.01658)
		(width 0.0889)
		(layer "In4.Cu")
		(net "VSENSE_PVCCFA_EHV_CPU0_DN")
	)
	(arc
		(start 374.88495 -219.007944)
		(mid 374.608475 -218.940624)
		(end 374.334278 -219.01658)
		(width 0.0889)
		(layer "In4.Cu")
		(net "VSENSE_PVCCFA_EHV_CPU0_DN")
	)
	(arc
		(start 375.82475 -219.007944)
		(mid 375.548275 -218.940624)
		(end 375.274078 -219.01658)
		(width 0.0889)
		(layer "In4.Cu")
		(net "VSENSE_PVCCFA_EHV_CPU0_DN")
	)
	(arc
		(start 371.514878 -219.01658)
		(mid 371.32768 -219.066723)
		(end 371.140482 -219.01658)
		(width 0.0889)
		(layer "In4.Cu")
		(net "VSENSE_PVCCFA_EHV_CPU0_DN")
	)
	(arc
		(start 352.718878 -222.272098)
		(mid 352.53168 -222.322241)
		(end 352.344482 -222.272098)
		(width 0.0889)
		(layer "In4.Cu")
		(net "VSENSE_PVCCFA_EHV_CPU0_DN")
	)
	(arc
		(start 367.755678 -219.01658)
		(mid 367.56848 -219.066723)
		(end 367.381282 -219.01658)
		(width 0.0889)
		(layer "In4.Cu")
		(net "VSENSE_PVCCFA_EHV_CPU0_DN")
	)
	(arc
		(start 361.177078 -219.01658)
		(mid 360.98988 -219.066723)
		(end 360.802682 -219.01658)
		(width 0.0889)
		(layer "In4.Cu")
		(net "VSENSE_PVCCFA_EHV_CPU0_DN")
	)
	(arc
		(start 375.274078 -219.01658)
		(mid 375.08688 -219.066723)
		(end 374.899682 -219.01658)
		(width 0.0889)
		(layer "In4.Cu")
		(net "VSENSE_PVCCFA_EHV_CPU0_DN")
	)
	(arc
		(start 384.767836 -216.574878)
		(mid 384.485134 -216.499102)
		(end 384.202432 -216.574878)
		(width 0.0889)
		(layer "In4.Cu")
		(net "VSENSE_PVCCFA_EHV_CPU0_DN")
	)
	(arc
		(start 357.02875 -222.263462)
		(mid 356.752275 -222.196142)
		(end 356.478078 -222.272098)
		(width 0.0889)
		(layer "In4.Cu")
		(net "VSENSE_PVCCFA_EHV_CPU0_DN")
	)
	(arc
		(start 369.635278 -219.01658)
		(mid 369.44808 -219.066723)
		(end 369.260882 -219.01658)
		(width 0.0889)
		(layer "In4.Cu")
		(net "VSENSE_PVCCFA_EHV_CPU0_DN")
	)
	(arc
		(start 366.815878 -219.01658)
		(mid 366.62868 -219.066723)
		(end 366.441482 -219.01658)
		(width 0.0889)
		(layer "In4.Cu")
		(net "VSENSE_PVCCFA_EHV_CPU0_DN")
	)
	(arc
		(start 365.876078 -219.01658)
		(mid 365.68888 -219.066723)
		(end 365.501682 -219.01658)
		(width 0.0889)
		(layer "In4.Cu")
		(net "VSENSE_PVCCFA_EHV_CPU0_DN")
	)
	(arc
		(start 354.598478 -222.272098)
		(mid 354.41128 -222.322241)
		(end 354.224082 -222.272098)
		(width 0.0889)
		(layer "In4.Cu")
		(net "VSENSE_PVCCFA_EHV_CPU0_DN")
	)
	(arc
		(start 378.64415 -219.007944)
		(mid 378.367675 -218.940624)
		(end 378.093478 -219.01658)
		(width 0.0889)
		(layer "In4.Cu")
		(net "VSENSE_PVCCFA_EHV_CPU0_DN")
	)
	(arc
		(start 359.767632 -221.458282)
		(mid 359.580434 -221.508425)
		(end 359.393236 -221.458282)
		(width 0.0889)
		(layer "In4.Cu")
		(net "VSENSE_PVCCFA_EHV_CPU0_DN")
	)
	(arc
		(start 358.827832 -221.458282)
		(mid 358.623497 -221.660887)
		(end 358.545384 -221.937834)
		(width 0.0889)
		(layer "In4.Cu")
		(net "VSENSE_PVCCFA_EHV_CPU0_DN")
	)
	(arc
		(start 363.996478 -219.01658)
		(mid 363.80928 -219.066723)
		(end 363.622082 -219.01658)
		(width 0.0889)
		(layer "In4.Cu")
		(net "VSENSE_PVCCFA_EHV_CPU0_DN")
	)
	(arc
		(start 359.75544 -219.837508)
		(mid 359.557212 -220.043356)
		(end 359.48493 -220.319854)
		(width 0.0889)
		(layer "In4.Cu")
		(net "VSENSE_PVCCFA_EHV_CPU0_DN")
	)
	(arc
		(start 383.828036 -216.574878)
		(mid 383.545334 -216.499102)
		(end 383.262632 -216.574878)
		(width 0.0889)
		(layer "In4.Cu")
		(net "VSENSE_PVCCFA_EHV_CPU0_DN")
	)
	(arc
		(start 379.58395 -219.007944)
		(mid 379.307475 -218.940624)
		(end 379.033278 -219.01658)
		(width 0.0889)
		(layer "In4.Cu")
		(net "VSENSE_PVCCFA_EHV_CPU0_DN")
	)
	(arc
		(start 355.14915 -222.263462)
		(mid 354.872675 -222.196142)
		(end 354.598478 -222.272098)
		(width 0.0889)
		(layer "In4.Cu")
		(net "VSENSE_PVCCFA_EHV_CPU0_DN")
	)
	(arc
		(start 385.142232 -216.574878)
		(mid 384.955034 -216.625021)
		(end 384.767836 -216.574878)
		(width 0.0889)
		(layer "In4.Cu")
		(net "VSENSE_PVCCFA_EHV_CPU0_DN")
	)
	(arc
		(start 369.24615 -219.007944)
		(mid 368.969675 -218.940624)
		(end 368.695478 -219.01658)
		(width 0.0889)
		(layer "In4.Cu")
		(net "VSENSE_PVCCFA_EHV_CPU0_DN")
	)
	(arc
		(start 377.153678 -219.01658)
		(mid 376.96648 -219.066723)
		(end 376.779282 -219.01658)
		(width 0.0889)
		(layer "In4.Cu")
		(net "VSENSE_PVCCFA_EHV_CPU0_DN")
	)
	(arc
		(start 365.48695 -219.007944)
		(mid 365.210475 -218.940624)
		(end 364.936278 -219.01658)
		(width 0.0889)
		(layer "In4.Cu")
		(net "VSENSE_PVCCFA_EHV_CPU0_DN")
	)
	(arc
		(start 385.329684 -216.25052)
		(mid 385.282005 -216.43342)
		(end 385.151122 -216.569798)
		(width 0.0889)
		(layer "In4.Cu")
		(net "VSENSE_PVCCFA_EHV_CPU0_DN")
	)
	(arc
		(start 363.611668 -219.010484)
		(mid 363.33349 -218.940761)
		(end 363.056932 -219.01658)
		(width 0.0889)
		(layer "In4.Cu")
		(net "VSENSE_PVCCFA_EHV_CPU0_DN")
	)
	(arc
		(start 359.776522 -220.814646)
		(mid 359.955119 -221.133924)
		(end 359.776522 -221.453202)
		(width 0.0889)
		(layer "In4.Cu")
		(net "VSENSE_PVCCFA_EHV_CPU0_DN")
	)
	(arc
		(start 380.912878 -219.01658)
		(mid 380.72568 -219.066723)
		(end 380.538482 -219.01658)
		(width 0.0889)
		(layer "In4.Cu")
		(net "VSENSE_PVCCFA_EHV_CPU0_DN")
	)
	(arc
		(start 380.52375 -219.007944)
		(mid 380.247275 -218.940624)
		(end 379.973078 -219.01658)
		(width 0.0889)
		(layer "In4.Cu")
		(net "VSENSE_PVCCFA_EHV_CPU0_DN")
	)
	(arc
		(start 363.056932 -219.01658)
		(mid 362.869734 -219.066723)
		(end 362.682536 -219.01658)
		(width 0.0889)
		(layer "In4.Cu")
		(net "VSENSE_PVCCFA_EHV_CPU0_DN")
	)
	(arc
		(start 359.955084 -219.506038)
		(mid 359.907405 -219.688938)
		(end 359.776522 -219.825316)
		(width 0.0889)
		(layer "In4.Cu")
		(net "VSENSE_PVCCFA_EHV_CPU0_DN")
	)
	(arc
		(start 360.237278 -219.01658)
		(mid 360.034455 -219.216811)
		(end 359.955084 -219.490544)
		(width 0.0889)
		(layer "In4.Cu")
		(net "VSENSE_PVCCFA_EHV_CPU0_DN")
	)
	(arc
		(start 372.454678 -219.01658)
		(mid 372.26748 -219.066723)
		(end 372.080282 -219.01658)
		(width 0.0889)
		(layer "In4.Cu")
		(net "VSENSE_PVCCFA_EHV_CPU0_DN")
	)
	(arc
		(start 382.51003 -217.887042)
		(mid 382.45776 -218.069407)
		(end 382.322832 -218.202764)
		(width 0.0889)
		(layer "In4.Cu")
		(net "VSENSE_PVCCFA_EHV_CPU0_DN")
	)
	(arc
		(start 382.792732 -217.388694)
		(mid 382.589251 -217.589498)
		(end 382.51003 -217.864182)
		(width 0.0889)
		(layer "In4.Cu")
		(net "VSENSE_PVCCFA_EHV_CPU0_DN")
	)
	(arc
		(start 355.538278 -222.272098)
		(mid 355.35108 -222.322241)
		(end 355.163882 -222.272098)
		(width 0.0889)
		(layer "In4.Cu")
		(net "VSENSE_PVCCFA_EHV_CPU0_DN")
	)
	(arc
		(start 353.26955 -222.263462)
		(mid 352.993075 -222.196142)
		(end 352.718878 -222.272098)
		(width 0.0889)
		(layer "In4.Cu")
		(net "VSENSE_PVCCFA_EHV_CPU0_DN")
	)
	(arc
		(start 385.612132 -215.761062)
		(mid 385.407797 -215.963667)
		(end 385.329684 -216.240614)
		(width 0.0889)
		(layer "In4.Cu")
		(net "VSENSE_PVCCFA_EHV_CPU0_DN")
	)
	(arc
		(start 382.040384 -218.692222)
		(mid 381.992705 -218.875122)
		(end 381.861822 -219.0115)
		(width 0.0889)
		(layer "In4.Cu")
		(net "VSENSE_PVCCFA_EHV_CPU0_DN")
	)
	(arc
		(start 379.033278 -219.01658)
		(mid 378.84608 -219.066723)
		(end 378.658882 -219.01658)
		(width 0.0889)
		(layer "In4.Cu")
		(net "VSENSE_PVCCFA_EHV_CPU0_DN")
	)
	(arc
		(start 384.202432 -216.574878)
		(mid 384.015234 -216.625021)
		(end 383.828036 -216.574878)
		(width 0.0889)
		(layer "In4.Cu")
		(net "VSENSE_PVCCFA_EHV_CPU0_DN")
	)
	(arc
		(start 382.980184 -217.064336)
		(mid 382.932505 -217.247236)
		(end 382.801622 -217.383614)
		(width 0.0889)
		(layer "In4.Cu")
		(net "VSENSE_PVCCFA_EHV_CPU0_DN")
	)
	(arc
		(start 356.08895 -222.263462)
		(mid 355.812475 -222.196142)
		(end 355.538278 -222.272098)
		(width 0.0889)
		(layer "In4.Cu")
		(net "VSENSE_PVCCFA_EHV_CPU0_DN")
	)
	(arc
		(start 357.417878 -222.272098)
		(mid 357.23068 -222.322241)
		(end 357.043482 -222.272098)
		(width 0.0889)
		(layer "In4.Cu")
		(net "VSENSE_PVCCFA_EHV_CPU0_DN")
	)
	(arc
		(start 367.36655 -219.007944)
		(mid 367.090075 -218.940624)
		(end 366.815878 -219.01658)
		(width 0.0889)
		(layer "In4.Cu")
		(net "VSENSE_PVCCFA_EHV_CPU0_DN")
	)
	(arc
		(start 362.117132 -219.01658)
		(mid 361.929934 -219.066723)
		(end 361.742736 -219.01658)
		(width 0.0889)
		(layer "In4.Cu")
		(net "VSENSE_PVCCFA_EHV_CPU0_DN")
	)
	(arc
		(start 378.093478 -219.01658)
		(mid 377.90628 -219.066723)
		(end 377.719082 -219.01658)
		(width 0.0889)
		(layer "In4.Cu")
		(net "VSENSE_PVCCFA_EHV_CPU0_DN")
	)
	(arc
		(start 383.262632 -216.574878)
		(mid 383.058297 -216.777483)
		(end 382.980184 -217.05443)
		(width 0.0889)
		(layer "In4.Cu")
		(net "VSENSE_PVCCFA_EHV_CPU0_DN")
	)
	(segment
		(start 423.393108 -140.99921)
		(end 423.151808 -141.24051)
		(width 0.254)
		(layer "In13.Cu")
		(net "VSENSE_PVCCFA_EHV_CPU0_DN")
	)
	(segment
		(start 397.4973 -146.088608)
		(end 397.4973 -145.803112)
		(width 0.254)
		(layer "In13.Cu")
		(net "VSENSE_PVCCFA_EHV_CPU0_DN")
	)
	(segment
		(start 423.151808 -141.24051)
		(end 423.151808 -141.68374)
		(width 0.254)
		(layer "In13.Cu")
		(net "VSENSE_PVCCFA_EHV_CPU0_DN")
	)
	(segment
		(start 423.151808 -141.68374)
		(end 421.02278 -143.812768)
		(width 0.254)
		(layer "In13.Cu")
		(net "VSENSE_PVCCFA_EHV_CPU0_DN")
	)
	(segment
		(start 397.4973 -145.803112)
		(end 397.183356 -145.489168)
		(width 0.254)
		(layer "In13.Cu")
		(net "VSENSE_PVCCFA_EHV_CPU0_DN")
	)
	(segment
		(start 401.19554 -143.812768)
		(end 398.61998 -146.388328)
		(width 0.254)
		(layer "In13.Cu")
		(net "VSENSE_PVCCFA_EHV_CPU0_DN")
	)
	(segment
		(start 421.02278 -143.812768)
		(end 401.19554 -143.812768)
		(width 0.254)
		(layer "In13.Cu")
		(net "VSENSE_PVCCFA_EHV_CPU0_DN")
	)
	(segment
		(start 398.61998 -146.388328)
		(end 397.79702 -146.388328)
		(width 0.254)
		(layer "In13.Cu")
		(net "VSENSE_PVCCFA_EHV_CPU0_DN")
	)
	(segment
		(start 397.79702 -146.388328)
		(end 397.4973 -146.088608)
		(width 0.254)
		(layer "In13.Cu")
		(net "VSENSE_PVCCFA_EHV_CPU0_DN")
	)
	(segment
		(start 75.04557 -160.828228)
		(end 74.624184 -160.828228)
		(width 0.254)
		(layer "F.Cu")
		(net "VSENSE_PVCCD_HV_CPU1_DP")
	)
	(segment
		(start 22.098 -160.1978)
		(end 22.098 -159.711898)
		(width 0.254)
		(layer "F.Cu")
		(net "VSENSE_PVCCD_HV_CPU1_DP")
	)
	(segment
		(start 74.624184 -160.828228)
		(end 74.34453 -161.107882)
		(width 0.254)
		(layer "F.Cu")
		(net "VSENSE_PVCCD_HV_CPU1_DP")
	)
	(segment
		(start 20.802346 -160.31464)
		(end 21.98116 -160.31464)
		(width 0.254)
		(layer "F.Cu")
		(net "VSENSE_PVCCD_HV_CPU1_DP")
	)
	(segment
		(start 22.098 -159.711898)
		(end 21.960586 -159.574484)
		(width 0.254)
		(layer "F.Cu")
		(net "VSENSE_PVCCD_HV_CPU1_DP")
	)
	(segment
		(start 21.98116 -160.31464)
		(end 22.098 -160.1978)
		(width 0.254)
		(layer "F.Cu")
		(net "VSENSE_PVCCD_HV_CPU1_DP")
	)
	(segment
		(start 111.170466 -222.48368)
		(end 111.170466 -221.94774)
		(width 0.254)
		(layer "F.Cu")
		(net "VSENSE_PVCCD_HV_CPU1_DP")
	)
	(segment
		(start 75.28687 -161.069528)
		(end 75.04557 -160.828228)
		(width 0.254)
		(layer "F.Cu")
		(net "VSENSE_PVCCD_HV_CPU1_DP")
	)
	(via
		(at 91.348306 -175.288956)
		(size 0.508)
		(drill 0.254)
		(layers "F.Cu" "B.Cu")
		(net "VSENSE_PVCCD_HV_CPU1_DP")
	)
	(via
		(at 21.960586 -159.574484)
		(size 0.508)
		(drill 0.254)
		(layers "F.Cu" "B.Cu")
		(net "VSENSE_PVCCD_HV_CPU1_DP")
	)
	(via
		(at 75.28687 -161.069528)
		(size 0.508)
		(drill 0.254)
		(layers "F.Cu" "B.Cu")
		(net "VSENSE_PVCCD_HV_CPU1_DP")
	)
	(via
		(at 111.170466 -221.94774)
		(size 0.4572)
		(drill 0.2032)
		(layers "F.Cu" "B.Cu")
		(net "VSENSE_PVCCD_HV_CPU1_DP")
	)
	(segment
		(start 117.546882 -225.51898)
		(end 117.561614 -225.527616)
		(width 0.0889)
		(layer "B.Cu")
		(net "VSENSE_PVCCD_HV_CPU1_DP")
	)
	(segment
		(start 114.727482 -225.51898)
		(end 114.742214 -225.527616)
		(width 0.0889)
		(layer "B.Cu")
		(net "VSENSE_PVCCD_HV_CPU1_DP")
	)
	(segment
		(start 112.675416 -223.557084)
		(end 112.675416 -223.576388)
		(width 0.0889)
		(layer "B.Cu")
		(net "VSENSE_PVCCD_HV_CPU1_DP")
	)
	(segment
		(start 111.466122 -222.196406)
		(end 111.58982 -222.196406)
		(width 0.0889)
		(layer "B.Cu")
		(net "VSENSE_PVCCD_HV_CPU1_DP")
	)
	(segment
		(start 129.401316 -215.414606)
		(end 129.40411 -215.343232)
		(width 0.0889)
		(layer "B.Cu")
		(net "VSENSE_PVCCD_HV_CPU1_DP")
	)
	(segment
		(start 112.767364 -224.7138)
		(end 112.782096 -224.705164)
		(width 0.0889)
		(layer "B.Cu")
		(net "VSENSE_PVCCD_HV_CPU1_DP")
	)
	(segment
		(start 127.884682 -225.51898)
		(end 127.899414 -225.527616)
		(width 0.0889)
		(layer "B.Cu")
		(net "VSENSE_PVCCD_HV_CPU1_DP")
	)
	(segment
		(start 130.15341 -219.01658)
		(end 130.157982 -219.01404)
		(width 0.0889)
		(layer "B.Cu")
		(net "VSENSE_PVCCD_HV_CPU1_DP")
	)
	(segment
		(start 128.278382 -222.269558)
		(end 128.279144 -222.26905)
		(width 0.0889)
		(layer "B.Cu")
		(net "VSENSE_PVCCD_HV_CPU1_DP")
	)
	(segment
		(start 129.871216 -217.8939)
		(end 129.871216 -217.878406)
		(width 0.0889)
		(layer "B.Cu")
		(net "VSENSE_PVCCD_HV_CPU1_DP")
	)
	(segment
		(start 129.20345 -220.650308)
		(end 129.214118 -220.644466)
		(width 0.0889)
		(layer "B.Cu")
		(net "VSENSE_PVCCD_HV_CPU1_DP")
	)
	(segment
		(start 129.401316 -215.415114)
		(end 129.401316 -215.414606)
		(width 0.0889)
		(layer "B.Cu")
		(net "VSENSE_PVCCD_HV_CPU1_DP")
	)
	(segment
		(start 128.274572 -223.251268)
		(end 128.26365 -223.244918)
		(width 0.0889)
		(layer "B.Cu")
		(net "VSENSE_PVCCD_HV_CPU1_DP")
	)
	(segment
		(start 111.904018 -222.259398)
		(end 112.000284 -222.315786)
		(width 0.0889)
		(layer "B.Cu")
		(net "VSENSE_PVCCD_HV_CPU1_DP")
	)
	(segment
		(start 128.276858 -222.27032)
		(end 128.278382 -222.269558)
		(width 0.0889)
		(layer "B.Cu")
		(net "VSENSE_PVCCD_HV_CPU1_DP")
	)
	(segment
		(start 120.366282 -225.51898)
		(end 120.381014 -225.527616)
		(width 0.0889)
		(layer "B.Cu")
		(net "VSENSE_PVCCD_HV_CPU1_DP")
	)
	(segment
		(start 124.125482 -225.51898)
		(end 124.140214 -225.527616)
		(width 0.0889)
		(layer "B.Cu")
		(net "VSENSE_PVCCD_HV_CPU1_DP")
	)
	(segment
		(start 119.426482 -225.51898)
		(end 119.441214 -225.527616)
		(width 0.0889)
		(layer "B.Cu")
		(net "VSENSE_PVCCD_HV_CPU1_DP")
	)
	(segment
		(start 112.392714 -224.713546)
		(end 112.392968 -224.7138)
		(width 0.0889)
		(layer "B.Cu")
		(net "VSENSE_PVCCD_HV_CPU1_DP")
	)
	(segment
		(start 112.390682 -224.06737)
		(end 112.382554 -224.071942)
		(width 0.0889)
		(layer "B.Cu")
		(net "VSENSE_PVCCD_HV_CPU1_DP")
	)
	(segment
		(start 111.667798 -222.193104)
		(end 111.668306 -222.193104)
		(width 0.0889)
		(layer "B.Cu")
		(net "VSENSE_PVCCD_HV_CPU1_DP")
	)
	(segment
		(start 128.461262 -221.960186)
		(end 128.461262 -221.911164)
		(width 0.0889)
		(layer "B.Cu")
		(net "VSENSE_PVCCD_HV_CPU1_DP")
	)
	(segment
		(start 128.931416 -216.238328)
		(end 128.931416 -216.232994)
		(width 0.0889)
		(layer "B.Cu")
		(net "VSENSE_PVCCD_HV_CPU1_DP")
	)
	(segment
		(start 125.065282 -225.51898)
		(end 125.080014 -225.527616)
		(width 0.0889)
		(layer "B.Cu")
		(net "VSENSE_PVCCD_HV_CPU1_DP")
	)
	(segment
		(start 91.581986 -175.055276)
		(end 91.348306 -175.288956)
		(width 0.254)
		(layer "B.Cu")
		(net "VSENSE_PVCCD_HV_CPU1_DP")
	)
	(segment
		(start 121.306082 -225.51898)
		(end 121.320814 -225.527616)
		(width 0.0889)
		(layer "B.Cu")
		(net "VSENSE_PVCCD_HV_CPU1_DP")
	)
	(segment
		(start 130.154426 -218.368372)
		(end 130.15341 -218.367864)
		(width 0.0889)
		(layer "B.Cu")
		(net "VSENSE_PVCCD_HV_CPU1_DP")
	)
	(segment
		(start 130.153156 -219.017088)
		(end 130.15341 -219.01658)
		(width 0.0889)
		(layer "B.Cu")
		(net "VSENSE_PVCCD_HV_CPU1_DP")
	)
	(segment
		(start 116.607082 -225.51898)
		(end 116.621814 -225.527616)
		(width 0.0889)
		(layer "B.Cu")
		(net "VSENSE_PVCCD_HV_CPU1_DP")
	)
	(segment
		(start 129.306066 -213.207854)
		(end 129.306066 -213.015322)
		(width 0.0889)
		(layer "B.Cu")
		(net "VSENSE_PVCCD_HV_CPU1_DP")
	)
	(segment
		(start 129.60985 -214.99195)
		(end 129.681732 -214.948516)
		(width 0.0889)
		(layer "B.Cu")
		(net "VSENSE_PVCCD_HV_CPU1_DP")
	)
	(segment
		(start 128.931416 -221.161356)
		(end 128.931416 -221.133924)
		(width 0.0889)
		(layer "B.Cu")
		(net "VSENSE_PVCCD_HV_CPU1_DP")
	)
	(segment
		(start 128.743964 -224.065084)
		(end 128.7399 -224.062798)
		(width 0.0889)
		(layer "B.Cu")
		(net "VSENSE_PVCCD_HV_CPU1_DP")
	)
	(segment
		(start 126.005082 -225.51898)
		(end 126.019814 -225.527616)
		(width 0.0889)
		(layer "B.Cu")
		(net "VSENSE_PVCCD_HV_CPU1_DP")
	)
	(segment
		(start 126.944882 -225.51898)
		(end 126.959614 -225.527616)
		(width 0.0889)
		(layer "B.Cu")
		(net "VSENSE_PVCCD_HV_CPU1_DP")
	)
	(segment
		(start 129.306066 -213.015322)
		(end 129.306066 -199.224138)
		(width 0.254)
		(layer "B.Cu")
		(net "VSENSE_PVCCD_HV_CPU1_DP")
	)
	(segment
		(start 129.68351 -219.830396)
		(end 129.735072 -219.799916)
		(width 0.0889)
		(layer "B.Cu")
		(net "VSENSE_PVCCD_HV_CPU1_DP")
	)
	(segment
		(start 129.401062 -217.07856)
		(end 129.401062 -217.0557)
		(width 0.0889)
		(layer "B.Cu")
		(net "VSENSE_PVCCD_HV_CPU1_DP")
	)
	(segment
		(start 128.931416 -224.404936)
		(end 128.931416 -224.389442)
		(width 0.0889)
		(layer "B.Cu")
		(net "VSENSE_PVCCD_HV_CPU1_DP")
	)
	(segment
		(start 129.401062 -220.32849)
		(end 129.401062 -220.319854)
		(width 0.0889)
		(layer "B.Cu")
		(net "VSENSE_PVCCD_HV_CPU1_DP")
	)
	(segment
		(start 129.401316 -213.303104)
		(end 129.306066 -213.207854)
		(width 0.0889)
		(layer "B.Cu")
		(net "VSENSE_PVCCD_HV_CPU1_DP")
	)
	(segment
		(start 130.157982 -219.01404)
		(end 130.1623 -219.0115)
		(width 0.0889)
		(layer "B.Cu")
		(net "VSENSE_PVCCD_HV_CPU1_DP")
	)
	(segment
		(start 128.824482 -225.51898)
		(end 128.839214 -225.527616)
		(width 0.0889)
		(layer "B.Cu")
		(net "VSENSE_PVCCD_HV_CPU1_DP")
	)
	(segment
		(start 115.667282 -225.51898)
		(end 115.682014 -225.527616)
		(width 0.0889)
		(layer "B.Cu")
		(net "VSENSE_PVCCD_HV_CPU1_DP")
	)
	(segment
		(start 129.871216 -219.560902)
		(end 129.871216 -219.506038)
		(width 0.0889)
		(layer "B.Cu")
		(net "VSENSE_PVCCD_HV_CPU1_DP")
	)
	(segment
		(start 129.692654 -217.559128)
		(end 129.683764 -217.554048)
		(width 0.0889)
		(layer "B.Cu")
		(net "VSENSE_PVCCD_HV_CPU1_DP")
	)
	(segment
		(start 111.170466 -221.94774)
		(end 111.385858 -222.163132)
		(width 0.0889)
		(layer "B.Cu")
		(net "VSENSE_PVCCD_HV_CPU1_DP")
	)
	(segment
		(start 123.185682 -225.51898)
		(end 123.200414 -225.527616)
		(width 0.0889)
		(layer "B.Cu")
		(net "VSENSE_PVCCD_HV_CPU1_DP")
	)
	(segment
		(start 112.384078 -223.080834)
		(end 112.392968 -223.085914)
		(width 0.0889)
		(layer "B.Cu")
		(net "VSENSE_PVCCD_HV_CPU1_DP")
	)
	(segment
		(start 129.681732 -214.948516)
		(end 129.68351 -214.947246)
		(width 0.0889)
		(layer "B.Cu")
		(net "VSENSE_PVCCD_HV_CPU1_DP")
	)
	(segment
		(start 130.150108 -219.018612)
		(end 130.153156 -219.017088)
		(width 0.0889)
		(layer "B.Cu")
		(net "VSENSE_PVCCD_HV_CPU1_DP")
	)
	(segment
		(start 129.683764 -219.830396)
		(end 129.68351 -219.830396)
		(width 0.0889)
		(layer "B.Cu")
		(net "VSENSE_PVCCD_HV_CPU1_DP")
	)
	(segment
		(start 129.306066 -199.224138)
		(end 105.137204 -175.055276)
		(width 0.254)
		(layer "B.Cu")
		(net "VSENSE_PVCCD_HV_CPU1_DP")
	)
	(segment
		(start 129.401316 -213.930484)
		(end 129.401316 -213.303104)
		(width 0.0889)
		(layer "B.Cu")
		(net "VSENSE_PVCCD_HV_CPU1_DP")
	)
	(segment
		(start 113.793524 -225.522536)
		(end 113.802414 -225.527616)
		(width 0.0889)
		(layer "B.Cu")
		(net "VSENSE_PVCCD_HV_CPU1_DP")
	)
	(segment
		(start 128.757426 -221.450154)
		(end 128.77165 -221.441772)
		(width 0.0889)
		(layer "B.Cu")
		(net "VSENSE_PVCCD_HV_CPU1_DP")
	)
	(segment
		(start 113.614962 -225.187764)
		(end 113.614962 -225.203258)
		(width 0.0889)
		(layer "B.Cu")
		(net "VSENSE_PVCCD_HV_CPU1_DP")
	)
	(segment
		(start 130.144266 -219.021914)
		(end 130.150108 -219.018612)
		(width 0.0889)
		(layer "B.Cu")
		(net "VSENSE_PVCCD_HV_CPU1_DP")
	)
	(segment
		(start 128.73863 -224.062036)
		(end 128.731772 -224.057972)
		(width 0.0889)
		(layer "B.Cu")
		(net "VSENSE_PVCCD_HV_CPU1_DP")
	)
	(segment
		(start 122.245882 -225.51898)
		(end 122.260614 -225.527616)
		(width 0.0889)
		(layer "B.Cu")
		(net "VSENSE_PVCCD_HV_CPU1_DP")
	)
	(segment
		(start 129.870708 -214.640414)
		(end 129.870708 -214.461344)
		(width 0.0889)
		(layer "B.Cu")
		(net "VSENSE_PVCCD_HV_CPU1_DP")
	)
	(segment
		(start 129.401062 -225.193098)
		(end 129.399538 -225.136202)
		(width 0.0889)
		(layer "B.Cu")
		(net "VSENSE_PVCCD_HV_CPU1_DP")
	)
	(segment
		(start 129.677668 -219.833952)
		(end 129.683764 -219.830396)
		(width 0.0889)
		(layer "B.Cu")
		(net "VSENSE_PVCCD_HV_CPU1_DP")
	)
	(segment
		(start 130.1623 -218.372944)
		(end 130.154426 -218.368372)
		(width 0.0889)
		(layer "B.Cu")
		(net "VSENSE_PVCCD_HV_CPU1_DP")
	)
	(segment
		(start 129.214118 -220.644466)
		(end 129.213864 -220.644212)
		(width 0.0889)
		(layer "B.Cu")
		(net "VSENSE_PVCCD_HV_CPU1_DP")
	)
	(segment
		(start 112.205516 -222.674942)
		(end 112.205516 -222.761556)
		(width 0.0889)
		(layer "B.Cu")
		(net "VSENSE_PVCCD_HV_CPU1_DP")
	)
	(segment
		(start 129.21361 -225.527616)
		(end 129.2225 -225.522536)
		(width 0.0889)
		(layer "B.Cu")
		(net "VSENSE_PVCCD_HV_CPU1_DP")
	)
	(segment
		(start 105.137204 -175.055276)
		(end 91.581986 -175.055276)
		(width 0.254)
		(layer "B.Cu")
		(net "VSENSE_PVCCD_HV_CPU1_DP")
	)
	(segment
		(start 129.198878 -215.769952)
		(end 129.28092 -215.722454)
		(width 0.0889)
		(layer "B.Cu")
		(net "VSENSE_PVCCD_HV_CPU1_DP")
	)
	(segment
		(start 128.713992 -221.4753)
		(end 128.757426 -221.450154)
		(width 0.0889)
		(layer "B.Cu")
		(net "VSENSE_PVCCD_HV_CPU1_DP")
	)
	(segment
		(start 129.271014 -224.913698)
		(end 129.21361 -224.8789)
		(width 0.0889)
		(layer "B.Cu")
		(net "VSENSE_PVCCD_HV_CPU1_DP")
	)
	(segment
		(start 118.486682 -225.51898)
		(end 118.501414 -225.527616)
		(width 0.0889)
		(layer "B.Cu")
		(net "VSENSE_PVCCD_HV_CPU1_DP")
	)
	(segment
		(start 128.7399 -224.062798)
		(end 128.73863 -224.062036)
		(width 0.0889)
		(layer "B.Cu")
		(net "VSENSE_PVCCD_HV_CPU1_DP")
	)
	(segment
		(start 128.27381 -222.272098)
		(end 128.276858 -222.27032)
		(width 0.0889)
		(layer "B.Cu")
		(net "VSENSE_PVCCD_HV_CPU1_DP")
	)
	(segment
		(start 128.752854 -224.070164)
		(end 128.743964 -224.065084)
		(width 0.0889)
		(layer "B.Cu")
		(net "VSENSE_PVCCD_HV_CPU1_DP")
	)
	(arc
		(start 115.682014 -225.527616)
		(mid 115.869212 -225.577759)
		(end 116.05641 -225.527616)
		(width 0.0889)
		(layer "B.Cu")
		(net "VSENSE_PVCCD_HV_CPU1_DP")
	)
	(arc
		(start 122.63501 -225.527616)
		(mid 122.909239 -225.451691)
		(end 123.185682 -225.51898)
		(width 0.0889)
		(layer "B.Cu")
		(net "VSENSE_PVCCD_HV_CPU1_DP")
	)
	(arc
		(start 124.140214 -225.527616)
		(mid 124.327412 -225.577759)
		(end 124.51461 -225.527616)
		(width 0.0889)
		(layer "B.Cu")
		(net "VSENSE_PVCCD_HV_CPU1_DP")
	)
	(arc
		(start 111.385858 -222.163132)
		(mid 111.422669 -222.187792)
		(end 111.466122 -222.196406)
		(width 0.0889)
		(layer "B.Cu")
		(net "VSENSE_PVCCD_HV_CPU1_DP")
	)
	(arc
		(start 129.38125 -215.609678)
		(mid 129.394874 -215.566925)
		(end 129.399538 -215.522302)
		(width 0.0889)
		(layer "B.Cu")
		(net "VSENSE_PVCCD_HV_CPU1_DP")
	)
	(arc
		(start 127.994918 -222.698818)
		(mid 128.079466 -222.458652)
		(end 128.260856 -222.279972)
		(width 0.0889)
		(layer "B.Cu")
		(net "VSENSE_PVCCD_HV_CPU1_DP")
	)
	(arc
		(start 128.26365 -223.244918)
		(mid 128.104436 -223.100376)
		(end 128.010666 -222.906844)
		(width 0.0889)
		(layer "B.Cu")
		(net "VSENSE_PVCCD_HV_CPU1_DP")
	)
	(arc
		(start 129.2225 -225.522536)
		(mid 129.349754 -225.39257)
		(end 129.400808 -225.21799)
		(width 0.0889)
		(layer "B.Cu")
		(net "VSENSE_PVCCD_HV_CPU1_DP")
	)
	(arc
		(start 114.742214 -225.527616)
		(mid 114.929412 -225.577759)
		(end 115.11661 -225.527616)
		(width 0.0889)
		(layer "B.Cu")
		(net "VSENSE_PVCCD_HV_CPU1_DP")
	)
	(arc
		(start 130.1623 -219.0115)
		(mid 130.340776 -218.692222)
		(end 130.1623 -218.372944)
		(width 0.0889)
		(layer "B.Cu")
		(net "VSENSE_PVCCD_HV_CPU1_DP")
	)
	(arc
		(start 122.260614 -225.527616)
		(mid 122.447812 -225.577759)
		(end 122.63501 -225.527616)
		(width 0.0889)
		(layer "B.Cu")
		(net "VSENSE_PVCCD_HV_CPU1_DP")
	)
	(arc
		(start 116.05641 -225.527616)
		(mid 116.330639 -225.451691)
		(end 116.607082 -225.51898)
		(width 0.0889)
		(layer "B.Cu")
		(net "VSENSE_PVCCD_HV_CPU1_DP")
	)
	(arc
		(start 112.675416 -223.576388)
		(mid 112.599155 -223.860228)
		(end 112.390682 -224.06737)
		(width 0.0889)
		(layer "B.Cu")
		(net "VSENSE_PVCCD_HV_CPU1_DP")
	)
	(arc
		(start 112.000284 -222.315786)
		(mid 112.150766 -222.468012)
		(end 112.205516 -222.674942)
		(width 0.0889)
		(layer "B.Cu")
		(net "VSENSE_PVCCD_HV_CPU1_DP")
	)
	(arc
		(start 128.461262 -221.911164)
		(mid 128.529019 -221.659254)
		(end 128.713992 -221.4753)
		(width 0.0889)
		(layer "B.Cu")
		(net "VSENSE_PVCCD_HV_CPU1_DP")
	)
	(arc
		(start 129.870708 -214.461344)
		(mid 129.795703 -214.345885)
		(end 129.686558 -214.261954)
		(width 0.0889)
		(layer "B.Cu")
		(net "VSENSE_PVCCD_HV_CPU1_DP")
	)
	(arc
		(start 126.39421 -225.527616)
		(mid 126.668439 -225.451691)
		(end 126.944882 -225.51898)
		(width 0.0889)
		(layer "B.Cu")
		(net "VSENSE_PVCCD_HV_CPU1_DP")
	)
	(arc
		(start 126.019814 -225.527616)
		(mid 126.207012 -225.577759)
		(end 126.39421 -225.527616)
		(width 0.0889)
		(layer "B.Cu")
		(net "VSENSE_PVCCD_HV_CPU1_DP")
	)
	(arc
		(start 121.69521 -225.527616)
		(mid 121.969439 -225.451691)
		(end 122.245882 -225.51898)
		(width 0.0889)
		(layer "B.Cu")
		(net "VSENSE_PVCCD_HV_CPU1_DP")
	)
	(arc
		(start 125.080014 -225.527616)
		(mid 125.267212 -225.577759)
		(end 125.45441 -225.527616)
		(width 0.0889)
		(layer "B.Cu")
		(net "VSENSE_PVCCD_HV_CPU1_DP")
	)
	(arc
		(start 117.561614 -225.527616)
		(mid 117.748812 -225.577759)
		(end 117.93601 -225.527616)
		(width 0.0889)
		(layer "B.Cu")
		(net "VSENSE_PVCCD_HV_CPU1_DP")
	)
	(arc
		(start 129.683764 -217.554048)
		(mid 129.480283 -217.353244)
		(end 129.401062 -217.07856)
		(width 0.0889)
		(layer "B.Cu")
		(net "VSENSE_PVCCD_HV_CPU1_DP")
	)
	(arc
		(start 128.931416 -216.260934)
		(mid 128.931306 -216.249631)
		(end 128.931416 -216.238328)
		(width 0.0889)
		(layer "B.Cu")
		(net "VSENSE_PVCCD_HV_CPU1_DP")
	)
	(arc
		(start 128.010666 -222.906844)
		(mid 127.993124 -222.803565)
		(end 127.994918 -222.698818)
		(width 0.0889)
		(layer "B.Cu")
		(net "VSENSE_PVCCD_HV_CPU1_DP")
	)
	(arc
		(start 129.213864 -216.739978)
		(mid 129.009658 -216.537592)
		(end 128.931416 -216.260934)
		(width 0.0889)
		(layer "B.Cu")
		(net "VSENSE_PVCCD_HV_CPU1_DP")
	)
	(arc
		(start 118.501414 -225.527616)
		(mid 118.688612 -225.577759)
		(end 118.87581 -225.527616)
		(width 0.0889)
		(layer "B.Cu")
		(net "VSENSE_PVCCD_HV_CPU1_DP")
	)
	(arc
		(start 129.68351 -214.947246)
		(mid 129.816248 -214.817711)
		(end 129.870708 -214.640414)
		(width 0.0889)
		(layer "B.Cu")
		(net "VSENSE_PVCCD_HV_CPU1_DP")
	)
	(arc
		(start 129.40411 -215.343232)
		(mid 129.463049 -215.14188)
		(end 129.60985 -214.99195)
		(width 0.0889)
		(layer "B.Cu")
		(net "VSENSE_PVCCD_HV_CPU1_DP")
	)
	(arc
		(start 112.782096 -224.705164)
		(mid 113.058571 -224.637844)
		(end 113.332768 -224.7138)
		(width 0.0889)
		(layer "B.Cu")
		(net "VSENSE_PVCCD_HV_CPU1_DP")
	)
	(arc
		(start 128.279144 -222.26905)
		(mid 128.409496 -222.137797)
		(end 128.461262 -221.960186)
		(width 0.0889)
		(layer "B.Cu")
		(net "VSENSE_PVCCD_HV_CPU1_DP")
	)
	(arc
		(start 129.871216 -217.878406)
		(mid 129.823537 -217.695506)
		(end 129.692654 -217.559128)
		(width 0.0889)
		(layer "B.Cu")
		(net "VSENSE_PVCCD_HV_CPU1_DP")
	)
	(arc
		(start 129.400808 -225.21799)
		(mid 129.401141 -225.205546)
		(end 129.401062 -225.193098)
		(width 0.0889)
		(layer "B.Cu")
		(net "VSENSE_PVCCD_HV_CPU1_DP")
	)
	(arc
		(start 129.871216 -219.506038)
		(mid 129.944114 -219.228079)
		(end 130.144266 -219.021914)
		(width 0.0889)
		(layer "B.Cu")
		(net "VSENSE_PVCCD_HV_CPU1_DP")
	)
	(arc
		(start 118.87581 -225.527616)
		(mid 119.150039 -225.451691)
		(end 119.426482 -225.51898)
		(width 0.0889)
		(layer "B.Cu")
		(net "VSENSE_PVCCD_HV_CPU1_DP")
	)
	(arc
		(start 112.382554 -224.071942)
		(mid 112.204784 -224.386667)
		(end 112.377474 -224.704148)
		(width 0.0889)
		(layer "B.Cu")
		(net "VSENSE_PVCCD_HV_CPU1_DP")
	)
	(arc
		(start 120.381014 -225.527616)
		(mid 120.568212 -225.577759)
		(end 120.75541 -225.527616)
		(width 0.0889)
		(layer "B.Cu")
		(net "VSENSE_PVCCD_HV_CPU1_DP")
	)
	(arc
		(start 111.58982 -222.196406)
		(mid 111.628755 -222.193468)
		(end 111.667798 -222.193104)
		(width 0.0889)
		(layer "B.Cu")
		(net "VSENSE_PVCCD_HV_CPU1_DP")
	)
	(arc
		(start 129.401062 -220.319854)
		(mid 129.475053 -220.040288)
		(end 129.677668 -219.833952)
		(width 0.0889)
		(layer "B.Cu")
		(net "VSENSE_PVCCD_HV_CPU1_DP")
	)
	(arc
		(start 128.731772 -224.057972)
		(mid 128.533544 -223.852124)
		(end 128.461262 -223.575626)
		(width 0.0889)
		(layer "B.Cu")
		(net "VSENSE_PVCCD_HV_CPU1_DP")
	)
	(arc
		(start 128.931416 -216.232994)
		(mid 129.005862 -215.967235)
		(end 129.198878 -215.769952)
		(width 0.0889)
		(layer "B.Cu")
		(net "VSENSE_PVCCD_HV_CPU1_DP")
	)
	(arc
		(start 129.686558 -214.261954)
		(mid 129.512595 -214.12319)
		(end 129.401316 -213.930484)
		(width 0.0889)
		(layer "B.Cu")
		(net "VSENSE_PVCCD_HV_CPU1_DP")
	)
	(arc
		(start 112.205516 -222.761556)
		(mid 112.253195 -222.944456)
		(end 112.384078 -223.080834)
		(width 0.0889)
		(layer "B.Cu")
		(net "VSENSE_PVCCD_HV_CPU1_DP")
	)
	(arc
		(start 117.93601 -225.527616)
		(mid 118.210239 -225.451691)
		(end 118.486682 -225.51898)
		(width 0.0889)
		(layer "B.Cu")
		(net "VSENSE_PVCCD_HV_CPU1_DP")
	)
	(arc
		(start 120.75541 -225.527616)
		(mid 121.029639 -225.451691)
		(end 121.306082 -225.51898)
		(width 0.0889)
		(layer "B.Cu")
		(net "VSENSE_PVCCD_HV_CPU1_DP")
	)
	(arc
		(start 128.461516 -223.565974)
		(mid 128.409017 -223.384292)
		(end 128.274572 -223.251268)
		(width 0.0889)
		(layer "B.Cu")
		(net "VSENSE_PVCCD_HV_CPU1_DP")
	)
	(arc
		(start 112.392968 -223.085914)
		(mid 112.595254 -223.284895)
		(end 112.675416 -223.557084)
		(width 0.0889)
		(layer "B.Cu")
		(net "VSENSE_PVCCD_HV_CPU1_DP")
	)
	(arc
		(start 129.28092 -215.722454)
		(mid 129.340163 -215.67415)
		(end 129.38125 -215.609678)
		(width 0.0889)
		(layer "B.Cu")
		(net "VSENSE_PVCCD_HV_CPU1_DP")
	)
	(arc
		(start 116.99621 -225.527616)
		(mid 117.270439 -225.451691)
		(end 117.546882 -225.51898)
		(width 0.0889)
		(layer "B.Cu")
		(net "VSENSE_PVCCD_HV_CPU1_DP")
	)
	(arc
		(start 114.17681 -225.527616)
		(mid 114.451039 -225.451691)
		(end 114.727482 -225.51898)
		(width 0.0889)
		(layer "B.Cu")
		(net "VSENSE_PVCCD_HV_CPU1_DP")
	)
	(arc
		(start 113.614962 -225.203258)
		(mid 113.662641 -225.386158)
		(end 113.793524 -225.522536)
		(width 0.0889)
		(layer "B.Cu")
		(net "VSENSE_PVCCD_HV_CPU1_DP")
	)
	(arc
		(start 128.77165 -221.441772)
		(mid 128.888623 -221.322694)
		(end 128.931416 -221.161356)
		(width 0.0889)
		(layer "B.Cu")
		(net "VSENSE_PVCCD_HV_CPU1_DP")
	)
	(arc
		(start 119.441214 -225.527616)
		(mid 119.628412 -225.577759)
		(end 119.81561 -225.527616)
		(width 0.0889)
		(layer "B.Cu")
		(net "VSENSE_PVCCD_HV_CPU1_DP")
	)
	(arc
		(start 128.461262 -223.575626)
		(mid 128.461421 -223.570801)
		(end 128.461516 -223.565974)
		(width 0.0889)
		(layer "B.Cu")
		(net "VSENSE_PVCCD_HV_CPU1_DP")
	)
	(arc
		(start 121.320814 -225.527616)
		(mid 121.508012 -225.577759)
		(end 121.69521 -225.527616)
		(width 0.0889)
		(layer "B.Cu")
		(net "VSENSE_PVCCD_HV_CPU1_DP")
	)
	(arc
		(start 128.839214 -225.527616)
		(mid 129.026412 -225.577759)
		(end 129.21361 -225.527616)
		(width 0.0889)
		(layer "B.Cu")
		(net "VSENSE_PVCCD_HV_CPU1_DP")
	)
	(arc
		(start 123.200414 -225.527616)
		(mid 123.387612 -225.577759)
		(end 123.57481 -225.527616)
		(width 0.0889)
		(layer "B.Cu")
		(net "VSENSE_PVCCD_HV_CPU1_DP")
	)
	(arc
		(start 129.401062 -217.0557)
		(mid 129.348792 -216.873335)
		(end 129.213864 -216.739978)
		(width 0.0889)
		(layer "B.Cu")
		(net "VSENSE_PVCCD_HV_CPU1_DP")
	)
	(arc
		(start 125.45441 -225.527616)
		(mid 125.728639 -225.451691)
		(end 126.005082 -225.51898)
		(width 0.0889)
		(layer "B.Cu")
		(net "VSENSE_PVCCD_HV_CPU1_DP")
	)
	(arc
		(start 124.51461 -225.527616)
		(mid 124.788839 -225.451691)
		(end 125.065282 -225.51898)
		(width 0.0889)
		(layer "B.Cu")
		(net "VSENSE_PVCCD_HV_CPU1_DP")
	)
	(arc
		(start 127.899414 -225.527616)
		(mid 128.086612 -225.577759)
		(end 128.27381 -225.527616)
		(width 0.0889)
		(layer "B.Cu")
		(net "VSENSE_PVCCD_HV_CPU1_DP")
	)
	(arc
		(start 123.57481 -225.527616)
		(mid 123.849039 -225.451691)
		(end 124.125482 -225.51898)
		(width 0.0889)
		(layer "B.Cu")
		(net "VSENSE_PVCCD_HV_CPU1_DP")
	)
	(arc
		(start 111.668306 -222.193104)
		(mid 111.79042 -222.211118)
		(end 111.904018 -222.259398)
		(width 0.0889)
		(layer "B.Cu")
		(net "VSENSE_PVCCD_HV_CPU1_DP")
	)
	(arc
		(start 128.27381 -225.527616)
		(mid 128.548039 -225.451691)
		(end 128.824482 -225.51898)
		(width 0.0889)
		(layer "B.Cu")
		(net "VSENSE_PVCCD_HV_CPU1_DP")
	)
	(arc
		(start 126.959614 -225.527616)
		(mid 127.146812 -225.577759)
		(end 127.33401 -225.527616)
		(width 0.0889)
		(layer "B.Cu")
		(net "VSENSE_PVCCD_HV_CPU1_DP")
	)
	(arc
		(start 112.377474 -224.704148)
		(mid 112.385037 -224.708939)
		(end 112.392714 -224.713546)
		(width 0.0889)
		(layer "B.Cu")
		(net "VSENSE_PVCCD_HV_CPU1_DP")
	)
	(arc
		(start 129.399538 -215.522302)
		(mid 129.400041 -215.468702)
		(end 129.401316 -215.415114)
		(width 0.0889)
		(layer "B.Cu")
		(net "VSENSE_PVCCD_HV_CPU1_DP")
	)
	(arc
		(start 128.931416 -221.133924)
		(mid 129.004037 -220.856459)
		(end 129.20345 -220.650308)
		(width 0.0889)
		(layer "B.Cu")
		(net "VSENSE_PVCCD_HV_CPU1_DP")
	)
	(arc
		(start 113.332768 -224.7138)
		(mid 113.535591 -224.914031)
		(end 113.614962 -225.187764)
		(width 0.0889)
		(layer "B.Cu")
		(net "VSENSE_PVCCD_HV_CPU1_DP")
	)
	(arc
		(start 128.931416 -224.389442)
		(mid 128.883737 -224.206542)
		(end 128.752854 -224.070164)
		(width 0.0889)
		(layer "B.Cu")
		(net "VSENSE_PVCCD_HV_CPU1_DP")
	)
	(arc
		(start 116.621814 -225.527616)
		(mid 116.809012 -225.577759)
		(end 116.99621 -225.527616)
		(width 0.0889)
		(layer "B.Cu")
		(net "VSENSE_PVCCD_HV_CPU1_DP")
	)
	(arc
		(start 130.15341 -218.367864)
		(mid 129.950587 -218.167633)
		(end 129.871216 -217.8939)
		(width 0.0889)
		(layer "B.Cu")
		(net "VSENSE_PVCCD_HV_CPU1_DP")
	)
	(arc
		(start 129.213864 -220.644212)
		(mid 129.348797 -220.510858)
		(end 129.401062 -220.32849)
		(width 0.0889)
		(layer "B.Cu")
		(net "VSENSE_PVCCD_HV_CPU1_DP")
	)
	(arc
		(start 129.399538 -225.136202)
		(mid 129.363465 -225.008676)
		(end 129.271014 -224.913698)
		(width 0.0889)
		(layer "B.Cu")
		(net "VSENSE_PVCCD_HV_CPU1_DP")
	)
	(arc
		(start 119.81561 -225.527616)
		(mid 120.089839 -225.451691)
		(end 120.366282 -225.51898)
		(width 0.0889)
		(layer "B.Cu")
		(net "VSENSE_PVCCD_HV_CPU1_DP")
	)
	(arc
		(start 128.260856 -222.279972)
		(mid 128.267307 -222.275992)
		(end 128.27381 -222.272098)
		(width 0.0889)
		(layer "B.Cu")
		(net "VSENSE_PVCCD_HV_CPU1_DP")
	)
	(arc
		(start 129.21361 -224.8789)
		(mid 129.010787 -224.678669)
		(end 128.931416 -224.404936)
		(width 0.0889)
		(layer "B.Cu")
		(net "VSENSE_PVCCD_HV_CPU1_DP")
	)
	(arc
		(start 112.392968 -224.7138)
		(mid 112.580166 -224.763943)
		(end 112.767364 -224.7138)
		(width 0.0889)
		(layer "B.Cu")
		(net "VSENSE_PVCCD_HV_CPU1_DP")
	)
	(arc
		(start 127.33401 -225.527616)
		(mid 127.608239 -225.451691)
		(end 127.884682 -225.51898)
		(width 0.0889)
		(layer "B.Cu")
		(net "VSENSE_PVCCD_HV_CPU1_DP")
	)
	(arc
		(start 115.11661 -225.527616)
		(mid 115.390839 -225.451691)
		(end 115.667282 -225.51898)
		(width 0.0889)
		(layer "B.Cu")
		(net "VSENSE_PVCCD_HV_CPU1_DP")
	)
	(arc
		(start 129.735072 -219.799916)
		(mid 129.834714 -219.698396)
		(end 129.871216 -219.560902)
		(width 0.0889)
		(layer "B.Cu")
		(net "VSENSE_PVCCD_HV_CPU1_DP")
	)
	(arc
		(start 113.802414 -225.527616)
		(mid 113.989612 -225.577759)
		(end 114.17681 -225.527616)
		(width 0.0889)
		(layer "B.Cu")
		(net "VSENSE_PVCCD_HV_CPU1_DP")
	)
	(segment
		(start 75.28687 -161.069528)
		(end 75.53071 -160.825688)
		(width 0.254)
		(layer "In11.Cu")
		(net "VSENSE_PVCCD_HV_CPU1_DP")
	)
	(segment
		(start 22.201886 -160.328102)
		(end 22.201886 -159.815784)
		(width 0.254)
		(layer "In11.Cu")
		(net "VSENSE_PVCCD_HV_CPU1_DP")
	)
	(segment
		(start 75.53071 -160.825688)
		(end 76.903072 -160.825688)
		(width 0.254)
		(layer "In11.Cu")
		(net "VSENSE_PVCCD_HV_CPU1_DP")
	)
	(segment
		(start 70.96506 -143.976344)
		(end 69.117972 -142.129256)
		(width 0.254)
		(layer "In11.Cu")
		(net "VSENSE_PVCCD_HV_CPU1_DP")
	)
	(segment
		(start 21.316188 -160.645348)
		(end 21.88464 -160.645348)
		(width 0.254)
		(layer "In11.Cu")
		(net "VSENSE_PVCCD_HV_CPU1_DP")
	)
	(segment
		(start 88.961976 -175.055276)
		(end 91.114626 -175.055276)
		(width 0.254)
		(layer "In11.Cu")
		(net "VSENSE_PVCCD_HV_CPU1_DP")
	)
	(segment
		(start 75.28687 -161.069528)
		(end 75.05573 -160.838388)
		(width 0.254)
		(layer "In11.Cu")
		(net "VSENSE_PVCCD_HV_CPU1_DP")
	)
	(segment
		(start 74.23658 -160.838388)
		(end 73.09612 -159.697928)
		(width 0.254)
		(layer "In11.Cu")
		(net "VSENSE_PVCCD_HV_CPU1_DP")
	)
	(segment
		(start 85.35416 -169.276776)
		(end 85.35416 -171.44746)
		(width 0.254)
		(layer "In11.Cu")
		(net "VSENSE_PVCCD_HV_CPU1_DP")
	)
	(segment
		(start 33.612582 -142.129256)
		(end 20.865084 -154.876754)
		(width 0.254)
		(layer "In11.Cu")
		(net "VSENSE_PVCCD_HV_CPU1_DP")
	)
	(segment
		(start 73.09612 -159.697928)
		(end 73.09612 -148.315426)
		(width 0.254)
		(layer "In11.Cu")
		(net "VSENSE_PVCCD_HV_CPU1_DP")
	)
	(segment
		(start 73.09612 -148.315426)
		(end 70.96506 -146.184366)
		(width 0.254)
		(layer "In11.Cu")
		(net "VSENSE_PVCCD_HV_CPU1_DP")
	)
	(segment
		(start 91.114626 -175.055276)
		(end 91.348306 -175.288956)
		(width 0.254)
		(layer "In11.Cu")
		(net "VSENSE_PVCCD_HV_CPU1_DP")
	)
	(segment
		(start 85.35416 -171.44746)
		(end 88.961976 -175.055276)
		(width 0.254)
		(layer "In11.Cu")
		(net "VSENSE_PVCCD_HV_CPU1_DP")
	)
	(segment
		(start 75.05573 -160.838388)
		(end 74.23658 -160.838388)
		(width 0.254)
		(layer "In11.Cu")
		(net "VSENSE_PVCCD_HV_CPU1_DP")
	)
	(segment
		(start 20.865084 -154.876754)
		(end 20.865084 -160.194244)
		(width 0.254)
		(layer "In11.Cu")
		(net "VSENSE_PVCCD_HV_CPU1_DP")
	)
	(segment
		(start 70.96506 -146.184366)
		(end 70.96506 -143.976344)
		(width 0.254)
		(layer "In11.Cu")
		(net "VSENSE_PVCCD_HV_CPU1_DP")
	)
	(segment
		(start 76.903072 -160.825688)
		(end 85.35416 -169.276776)
		(width 0.254)
		(layer "In11.Cu")
		(net "VSENSE_PVCCD_HV_CPU1_DP")
	)
	(segment
		(start 69.117972 -142.129256)
		(end 33.612582 -142.129256)
		(width 0.254)
		(layer "In11.Cu")
		(net "VSENSE_PVCCD_HV_CPU1_DP")
	)
	(segment
		(start 20.865084 -160.194244)
		(end 21.316188 -160.645348)
		(width 0.254)
		(layer "In11.Cu")
		(net "VSENSE_PVCCD_HV_CPU1_DP")
	)
	(segment
		(start 21.88464 -160.645348)
		(end 22.201886 -160.328102)
		(width 0.254)
		(layer "In11.Cu")
		(net "VSENSE_PVCCD_HV_CPU1_DP")
	)
	(segment
		(start 22.201886 -159.815784)
		(end 21.960586 -159.574484)
		(width 0.254)
		(layer "In11.Cu")
		(net "VSENSE_PVCCD_HV_CPU1_DP")
	)
	(segment
		(start 75.28687 -160.205928)
		(end 75.04557 -160.447228)
		(width 0.254)
		(layer "F.Cu")
		(net "VSENSE_PVCCD_HV_CPU1_DN")
	)
	(segment
		(start 74.57948 -160.447228)
		(end 74.34453 -160.212278)
		(width 0.254)
		(layer "F.Cu")
		(net "VSENSE_PVCCD_HV_CPU1_DN")
	)
	(segment
		(start 109.290866 -222.48368)
		(end 109.290866 -221.947994)
		(width 0.254)
		(layer "F.Cu")
		(net "VSENSE_PVCCD_HV_CPU1_DN")
	)
	(segment
		(start 26.262838 -162.427158)
		(end 26.262838 -162.106102)
		(width 0.1778)
		(layer "F.Cu")
		(net "VSENSE_PVCCD_HV_CPU1_DN")
	)
	(segment
		(start 26.010108 -161.853372)
		(end 25.287224 -161.853372)
		(width 0.1778)
		(layer "F.Cu")
		(net "VSENSE_PVCCD_HV_CPU1_DN")
	)
	(segment
		(start 23.426928 -161.80562)
		(end 22.991572 -161.80562)
		(width 0.254)
		(layer "F.Cu")
		(net "VSENSE_PVCCD_HV_CPU1_DN")
	)
	(segment
		(start 23.863808 -161.36874)
		(end 23.426928 -161.80562)
		(width 0.254)
		(layer "F.Cu")
		(net "VSENSE_PVCCD_HV_CPU1_DN")
	)
	(segment
		(start 75.04557 -160.447228)
		(end 74.57948 -160.447228)
		(width 0.254)
		(layer "F.Cu")
		(net "VSENSE_PVCCD_HV_CPU1_DN")
	)
	(segment
		(start 22.59076 -159.80791)
		(end 22.59076 -161.404808)
		(width 0.254)
		(layer "F.Cu")
		(net "VSENSE_PVCCD_HV_CPU1_DN")
	)
	(segment
		(start 25.0444 -161.610548)
		(end 24.802592 -161.36874)
		(width 0.254)
		(layer "F.Cu")
		(net "VSENSE_PVCCD_HV_CPU1_DN")
	)
	(segment
		(start 22.59076 -161.404808)
		(end 22.991572 -161.80562)
		(width 0.254)
		(layer "F.Cu")
		(net "VSENSE_PVCCD_HV_CPU1_DN")
	)
	(segment
		(start 26.262838 -162.106102)
		(end 26.010108 -161.853372)
		(width 0.1778)
		(layer "F.Cu")
		(net "VSENSE_PVCCD_HV_CPU1_DN")
	)
	(segment
		(start 24.802592 -161.36874)
		(end 23.863808 -161.36874)
		(width 0.254)
		(layer "F.Cu")
		(net "VSENSE_PVCCD_HV_CPU1_DN")
	)
	(segment
		(start 109.290866 -221.947994)
		(end 109.290612 -221.94774)
		(width 0.254)
		(layer "F.Cu")
		(net "VSENSE_PVCCD_HV_CPU1_DN")
	)
	(segment
		(start 25.287224 -161.853372)
		(end 25.0444 -161.610548)
		(width 0.1778)
		(layer "F.Cu")
		(net "VSENSE_PVCCD_HV_CPU1_DN")
	)
	(segment
		(start 22.824186 -159.574484)
		(end 22.59076 -159.80791)
		(width 0.254)
		(layer "F.Cu")
		(net "VSENSE_PVCCD_HV_CPU1_DN")
	)
	(via
		(at 109.290612 -221.94774)
		(size 0.4572)
		(drill 0.2032)
		(layers "F.Cu" "B.Cu")
		(net "VSENSE_PVCCD_HV_CPU1_DN")
	)
	(via
		(at 75.28687 -160.205928)
		(size 0.508)
		(drill 0.254)
		(layers "F.Cu" "B.Cu")
		(net "VSENSE_PVCCD_HV_CPU1_DN")
	)
	(via
		(at 22.824186 -159.574484)
		(size 0.508)
		(drill 0.254)
		(layers "F.Cu" "B.Cu")
		(net "VSENSE_PVCCD_HV_CPU1_DN")
	)
	(via
		(at 91.355926 -174.432976)
		(size 0.762)
		(drill 0.254)
		(layers "F.Cu" "B.Cu")
		(net "VSENSE_PVCCD_HV_CPU1_DN")
	)
	(segment
		(start 112.015016 -222.674688)
		(end 112.015016 -222.780098)
		(width 0.0889)
		(layer "B.Cu")
		(net "VSENSE_PVCCD_HV_CPU1_DN")
	)
	(segment
		(start 128.80848 -221.640908)
		(end 128.868932 -221.605856)
		(width 0.0889)
		(layer "B.Cu")
		(net "VSENSE_PVCCD_HV_CPU1_DN")
	)
	(segment
		(start 112.484916 -223.56064)
		(end 112.484916 -223.576642)
		(width 0.0889)
		(layer "B.Cu")
		(net "VSENSE_PVCCD_HV_CPU1_DN")
	)
	(segment
		(start 122.165364 -225.69297)
		(end 122.180096 -225.701606)
		(width 0.0889)
		(layer "B.Cu")
		(net "VSENSE_PVCCD_HV_CPU1_DN")
	)
	(segment
		(start 130.531362 -218.707716)
		(end 130.531362 -218.676728)
		(width 0.0889)
		(layer "B.Cu")
		(net "VSENSE_PVCCD_HV_CPU1_DN")
	)
	(segment
		(start 130.061208 -214.644732)
		(end 130.061208 -214.424768)
		(width 0.0889)
		(layer "B.Cu")
		(net "VSENSE_PVCCD_HV_CPU1_DN")
	)
	(segment
		(start 124.984764 -225.69297)
		(end 124.999496 -225.701606)
		(width 0.0889)
		(layer "B.Cu")
		(net "VSENSE_PVCCD_HV_CPU1_DN")
	)
	(segment
		(start 128.360678 -222.442278)
		(end 128.369568 -222.437198)
		(width 0.0889)
		(layer "B.Cu")
		(net "VSENSE_PVCCD_HV_CPU1_DN")
	)
	(segment
		(start 112.297464 -223.251268)
		(end 112.297718 -223.251014)
		(width 0.0889)
		(layer "B.Cu")
		(net "VSENSE_PVCCD_HV_CPU1_DN")
	)
	(segment
		(start 129.779014 -219.995496)
		(end 129.779776 -219.994988)
		(width 0.0889)
		(layer "B.Cu")
		(net "VSENSE_PVCCD_HV_CPU1_DN")
	)
	(segment
		(start 117.466364 -225.69297)
		(end 117.481096 -225.701606)
		(width 0.0889)
		(layer "B.Cu")
		(net "VSENSE_PVCCD_HV_CPU1_DN")
	)
	(segment
		(start 128.838706 -223.899476)
		(end 128.836928 -223.89846)
		(width 0.0889)
		(layer "B.Cu")
		(net "VSENSE_PVCCD_HV_CPU1_DN")
	)
	(segment
		(start 113.707164 -225.69297)
		(end 113.721896 -225.701606)
		(width 0.0889)
		(layer "B.Cu")
		(net "VSENSE_PVCCD_HV_CPU1_DN")
	)
	(segment
		(start 114.646964 -225.69297)
		(end 114.661696 -225.701606)
		(width 0.0889)
		(layer "B.Cu")
		(net "VSENSE_PVCCD_HV_CPU1_DN")
	)
	(segment
		(start 111.665258 -222.383604)
		(end 111.66602 -222.383604)
		(width 0.0889)
		(layer "B.Cu")
		(net "VSENSE_PVCCD_HV_CPU1_DN")
	)
	(segment
		(start 112.853724 -224.884234)
		(end 112.862614 -224.8789)
		(width 0.0889)
		(layer "B.Cu")
		(net "VSENSE_PVCCD_HV_CPU1_DN")
	)
	(segment
		(start 105.295192 -174.674276)
		(end 91.597226 -174.674276)
		(width 0.254)
		(layer "B.Cu")
		(net "VSENSE_PVCCD_HV_CPU1_DN")
	)
	(segment
		(start 116.526564 -225.69297)
		(end 116.541296 -225.701606)
		(width 0.0889)
		(layer "B.Cu")
		(net "VSENSE_PVCCD_HV_CPU1_DN")
	)
	(segment
		(start 129.29616 -215.933782)
		(end 129.37617 -215.887554)
		(width 0.0889)
		(layer "B.Cu")
		(net "VSENSE_PVCCD_HV_CPU1_DN")
	)
	(segment
		(start 129.591816 -213.893908)
		(end 129.591816 -213.298532)
		(width 0.0889)
		(layer "B.Cu")
		(net "VSENSE_PVCCD_HV_CPU1_DN")
	)
	(segment
		(start 129.591816 -213.298532)
		(end 129.687066 -213.203282)
		(width 0.0889)
		(layer "B.Cu")
		(net "VSENSE_PVCCD_HV_CPU1_DN")
	)
	(segment
		(start 129.779776 -219.994988)
		(end 129.832354 -219.964)
		(width 0.0889)
		(layer "B.Cu")
		(net "VSENSE_PVCCD_HV_CPU1_DN")
	)
	(segment
		(start 129.590038 -215.52281)
		(end 129.590038 -215.522556)
		(width 0.0889)
		(layer "B.Cu")
		(net "VSENSE_PVCCD_HV_CPU1_DN")
	)
	(segment
		(start 112.484916 -223.576642)
		(end 112.484662 -223.576388)
		(width 0.0889)
		(layer "B.Cu")
		(net "VSENSE_PVCCD_HV_CPU1_DN")
	)
	(segment
		(start 130.061716 -217.878406)
		(end 130.061716 -217.864182)
		(width 0.0889)
		(layer "B.Cu")
		(net "VSENSE_PVCCD_HV_CPU1_DN")
	)
	(segment
		(start 113.23701 -224.8789)
		(end 113.2459 -224.88398)
		(width 0.0889)
		(layer "B.Cu")
		(net "VSENSE_PVCCD_HV_CPU1_DN")
	)
	(segment
		(start 121.225564 -225.69297)
		(end 121.240296 -225.701606)
		(width 0.0889)
		(layer "B.Cu")
		(net "VSENSE_PVCCD_HV_CPU1_DN")
	)
	(segment
		(start 129.687066 -199.06615)
		(end 105.295192 -174.674276)
		(width 0.254)
		(layer "B.Cu")
		(net "VSENSE_PVCCD_HV_CPU1_DN")
	)
	(segment
		(start 115.586764 -225.69297)
		(end 115.601496 -225.701606)
		(width 0.0889)
		(layer "B.Cu")
		(net "VSENSE_PVCCD_HV_CPU1_DN")
	)
	(segment
		(start 130.249168 -218.202764)
		(end 130.240278 -218.197684)
		(width 0.0889)
		(layer "B.Cu")
		(net "VSENSE_PVCCD_HV_CPU1_DN")
	)
	(segment
		(start 128.839468 -223.899984)
		(end 128.838706 -223.899476)
		(width 0.0889)
		(layer "B.Cu")
		(net "VSENSE_PVCCD_HV_CPU1_DN")
	)
	(segment
		(start 130.061716 -219.560902)
		(end 130.061716 -219.506038)
		(width 0.0889)
		(layer "B.Cu")
		(net "VSENSE_PVCCD_HV_CPU1_DN")
	)
	(segment
		(start 129.300478 -220.814646)
		(end 129.309368 -220.809566)
		(width 0.0889)
		(layer "B.Cu")
		(net "VSENSE_PVCCD_HV_CPU1_DN")
	)
	(segment
		(start 129.309368 -216.574878)
		(end 129.300478 -216.569798)
		(width 0.0889)
		(layer "B.Cu")
		(net "VSENSE_PVCCD_HV_CPU1_DN")
	)
	(segment
		(start 129.121916 -216.24036)
		(end 129.121916 -216.235534)
		(width 0.0889)
		(layer "B.Cu")
		(net "VSENSE_PVCCD_HV_CPU1_DN")
	)
	(segment
		(start 126.864364 -225.69297)
		(end 126.879096 -225.701606)
		(width 0.0889)
		(layer "B.Cu")
		(net "VSENSE_PVCCD_HV_CPU1_DN")
	)
	(segment
		(start 111.807498 -222.42399)
		(end 111.903764 -222.480378)
		(width 0.0889)
		(layer "B.Cu")
		(net "VSENSE_PVCCD_HV_CPU1_DN")
	)
	(segment
		(start 129.121916 -224.401888)
		(end 129.121916 -224.379536)
		(width 0.0889)
		(layer "B.Cu")
		(net "VSENSE_PVCCD_HV_CPU1_DN")
	)
	(segment
		(start 119.345964 -225.69297)
		(end 119.360696 -225.701606)
		(width 0.0889)
		(layer "B.Cu")
		(net "VSENSE_PVCCD_HV_CPU1_DN")
	)
	(segment
		(start 123.105164 -225.69297)
		(end 123.119896 -225.701606)
		(width 0.0889)
		(layer "B.Cu")
		(net "VSENSE_PVCCD_HV_CPU1_DN")
	)
	(segment
		(start 128.652016 -223.575626)
		(end 128.652016 -223.561402)
		(width 0.0889)
		(layer "B.Cu")
		(net "VSENSE_PVCCD_HV_CPU1_DN")
	)
	(segment
		(start 128.369568 -223.085914)
		(end 128.360678 -223.080834)
		(width 0.0889)
		(layer "B.Cu")
		(net "VSENSE_PVCCD_HV_CPU1_DN")
	)
	(segment
		(start 118.406164 -225.69297)
		(end 118.420896 -225.701606)
		(width 0.0889)
		(layer "B.Cu")
		(net "VSENSE_PVCCD_HV_CPU1_DN")
	)
	(segment
		(start 128.651762 -221.963234)
		(end 128.651762 -221.911164)
		(width 0.0889)
		(layer "B.Cu")
		(net "VSENSE_PVCCD_HV_CPU1_DN")
	)
	(segment
		(start 127.804164 -225.69297)
		(end 127.818896 -225.701606)
		(width 0.0889)
		(layer "B.Cu")
		(net "VSENSE_PVCCD_HV_CPU1_DN")
	)
	(segment
		(start 129.591816 -215.421972)
		(end 129.59461 -215.350852)
		(width 0.0889)
		(layer "B.Cu")
		(net "VSENSE_PVCCD_HV_CPU1_DN")
	)
	(segment
		(start 128.836166 -223.897952)
		(end 128.83134 -223.895412)
		(width 0.0889)
		(layer "B.Cu")
		(net "VSENSE_PVCCD_HV_CPU1_DN")
	)
	(segment
		(start 129.310892 -224.714816)
		(end 129.309114 -224.7138)
		(width 0.0889)
		(layer "B.Cu")
		(net "VSENSE_PVCCD_HV_CPU1_DN")
	)
	(segment
		(start 113.424462 -225.203258)
		(end 113.424462 -225.217482)
		(width 0.0889)
		(layer "B.Cu")
		(net "VSENSE_PVCCD_HV_CPU1_DN")
	)
	(segment
		(start 128.83134 -223.895412)
		(end 128.830578 -223.894904)
		(width 0.0889)
		(layer "B.Cu")
		(net "VSENSE_PVCCD_HV_CPU1_DN")
	)
	(segment
		(start 109.290612 -221.94774)
		(end 109.603286 -221.94774)
		(width 0.0889)
		(layer "B.Cu")
		(net "VSENSE_PVCCD_HV_CPU1_DN")
	)
	(segment
		(start 130.240278 -219.18676)
		(end 130.242818 -219.185236)
		(width 0.0889)
		(layer "B.Cu")
		(net "VSENSE_PVCCD_HV_CPU1_DN")
	)
	(segment
		(start 91.597226 -174.674276)
		(end 91.355926 -174.432976)
		(width 0.254)
		(layer "B.Cu")
		(net "VSENSE_PVCCD_HV_CPU1_DN")
	)
	(segment
		(start 125.924564 -225.69297)
		(end 125.939296 -225.701606)
		(width 0.0889)
		(layer "B.Cu")
		(net "VSENSE_PVCCD_HV_CPU1_DN")
	)
	(segment
		(start 128.743964 -225.69297)
		(end 128.758696 -225.701606)
		(width 0.0889)
		(layer "B.Cu")
		(net "VSENSE_PVCCD_HV_CPU1_DN")
	)
	(segment
		(start 128.836928 -223.89846)
		(end 128.836166 -223.897952)
		(width 0.0889)
		(layer "B.Cu")
		(net "VSENSE_PVCCD_HV_CPU1_DN")
	)
	(segment
		(start 130.242818 -219.185236)
		(end 130.24485 -219.18422)
		(width 0.0889)
		(layer "B.Cu")
		(net "VSENSE_PVCCD_HV_CPU1_DN")
	)
	(segment
		(start 129.709418 -215.154764)
		(end 129.779014 -215.112346)
		(width 0.0889)
		(layer "B.Cu")
		(net "VSENSE_PVCCD_HV_CPU1_DN")
	)
	(segment
		(start 124.044964 -225.69297)
		(end 124.059696 -225.701606)
		(width 0.0889)
		(layer "B.Cu")
		(net "VSENSE_PVCCD_HV_CPU1_DN")
	)
	(segment
		(start 130.24485 -219.18422)
		(end 130.249168 -219.18168)
		(width 0.0889)
		(layer "B.Cu")
		(net "VSENSE_PVCCD_HV_CPU1_DN")
	)
	(segment
		(start 129.591816 -220.338396)
		(end 129.591816 -220.311218)
		(width 0.0889)
		(layer "B.Cu")
		(net "VSENSE_PVCCD_HV_CPU1_DN")
	)
	(segment
		(start 109.603286 -221.94774)
		(end 109.669072 -222.013526)
		(width 0.0889)
		(layer "B.Cu")
		(net "VSENSE_PVCCD_HV_CPU1_DN")
	)
	(segment
		(start 120.285764 -225.69297)
		(end 120.300496 -225.701606)
		(width 0.0889)
		(layer "B.Cu")
		(net "VSENSE_PVCCD_HV_CPU1_DN")
	)
	(segment
		(start 129.370328 -224.750884)
		(end 129.310892 -224.714816)
		(width 0.0889)
		(layer "B.Cu")
		(net "VSENSE_PVCCD_HV_CPU1_DN")
	)
	(segment
		(start 129.687066 -213.203282)
		(end 129.687066 -213.015322)
		(width 0.0889)
		(layer "B.Cu")
		(net "VSENSE_PVCCD_HV_CPU1_DN")
	)
	(segment
		(start 129.591562 -225.188272)
		(end 129.590038 -225.131122)
		(width 0.0889)
		(layer "B.Cu")
		(net "VSENSE_PVCCD_HV_CPU1_DN")
	)
	(segment
		(start 129.591816 -215.424258)
		(end 129.591816 -215.421972)
		(width 0.0889)
		(layer "B.Cu")
		(net "VSENSE_PVCCD_HV_CPU1_DN")
	)
	(segment
		(start 129.687066 -213.015322)
		(end 129.687066 -199.06615)
		(width 0.254)
		(layer "B.Cu")
		(net "VSENSE_PVCCD_HV_CPU1_DN")
	)
	(segment
		(start 129.121916 -221.161356)
		(end 129.121916 -221.133924)
		(width 0.0889)
		(layer "B.Cu")
		(net "VSENSE_PVCCD_HV_CPU1_DN")
	)
	(segment
		(start 129.591816 -217.072972)
		(end 129.591816 -217.05443)
		(width 0.0889)
		(layer "B.Cu")
		(net "VSENSE_PVCCD_HV_CPU1_DN")
	)
	(segment
		(start 112.296448 -223.901508)
		(end 112.286034 -223.90735)
		(width 0.0889)
		(layer "B.Cu")
		(net "VSENSE_PVCCD_HV_CPU1_DN")
	)
	(arc
		(start 129.121916 -221.133924)
		(mid 129.169595 -220.951024)
		(end 129.300478 -220.814646)
		(width 0.0889)
		(layer "B.Cu")
		(net "VSENSE_PVCCD_HV_CPU1_DN")
	)
	(arc
		(start 128.868932 -221.605856)
		(mid 129.054275 -221.417093)
		(end 129.121916 -221.161356)
		(width 0.0889)
		(layer "B.Cu")
		(net "VSENSE_PVCCD_HV_CPU1_DN")
	)
	(arc
		(start 129.779014 -215.112346)
		(mid 129.980296 -214.914859)
		(end 130.061208 -214.644732)
		(width 0.0889)
		(layer "B.Cu")
		(net "VSENSE_PVCCD_HV_CPU1_DN")
	)
	(arc
		(start 124.059696 -225.701606)
		(mid 124.336137 -225.768772)
		(end 124.610368 -225.69297)
		(width 0.0889)
		(layer "B.Cu")
		(net "VSENSE_PVCCD_HV_CPU1_DN")
	)
	(arc
		(start 129.37617 -215.887554)
		(mid 129.482521 -215.800991)
		(end 129.556256 -215.68537)
		(width 0.0889)
		(layer "B.Cu")
		(net "VSENSE_PVCCD_HV_CPU1_DN")
	)
	(arc
		(start 130.061716 -217.864182)
		(mid 129.982497 -217.589497)
		(end 129.779014 -217.388694)
		(width 0.0889)
		(layer "B.Cu")
		(net "VSENSE_PVCCD_HV_CPU1_DN")
	)
	(arc
		(start 128.651762 -221.911164)
		(mid 128.693774 -221.754957)
		(end 128.80848 -221.640908)
		(width 0.0889)
		(layer "B.Cu")
		(net "VSENSE_PVCCD_HV_CPU1_DN")
	)
	(arc
		(start 128.830578 -223.894904)
		(mid 128.699664 -223.758544)
		(end 128.652016 -223.575626)
		(width 0.0889)
		(layer "B.Cu")
		(net "VSENSE_PVCCD_HV_CPU1_DN")
	)
	(arc
		(start 128.369568 -222.437198)
		(mid 128.572391 -222.236967)
		(end 128.651762 -221.963234)
		(width 0.0889)
		(layer "B.Cu")
		(net "VSENSE_PVCCD_HV_CPU1_DN")
	)
	(arc
		(start 118.031768 -225.69297)
		(mid 118.218966 -225.642827)
		(end 118.406164 -225.69297)
		(width 0.0889)
		(layer "B.Cu")
		(net "VSENSE_PVCCD_HV_CPU1_DN")
	)
	(arc
		(start 128.369568 -225.69297)
		(mid 128.556766 -225.642827)
		(end 128.743964 -225.69297)
		(width 0.0889)
		(layer "B.Cu")
		(net "VSENSE_PVCCD_HV_CPU1_DN")
	)
	(arc
		(start 127.818896 -225.701606)
		(mid 128.095337 -225.768772)
		(end 128.369568 -225.69297)
		(width 0.0889)
		(layer "B.Cu")
		(net "VSENSE_PVCCD_HV_CPU1_DN")
	)
	(arc
		(start 125.939296 -225.701606)
		(mid 126.215737 -225.768772)
		(end 126.489968 -225.69297)
		(width 0.0889)
		(layer "B.Cu")
		(net "VSENSE_PVCCD_HV_CPU1_DN")
	)
	(arc
		(start 128.652016 -223.561402)
		(mid 128.572875 -223.286779)
		(end 128.369568 -223.085914)
		(width 0.0889)
		(layer "B.Cu")
		(net "VSENSE_PVCCD_HV_CPU1_DN")
	)
	(arc
		(start 112.484662 -223.576388)
		(mid 112.434193 -223.76419)
		(end 112.296448 -223.901508)
		(width 0.0889)
		(layer "B.Cu")
		(net "VSENSE_PVCCD_HV_CPU1_DN")
	)
	(arc
		(start 113.2459 -224.88398)
		(mid 113.376814 -225.02034)
		(end 113.424462 -225.203258)
		(width 0.0889)
		(layer "B.Cu")
		(net "VSENSE_PVCCD_HV_CPU1_DN")
	)
	(arc
		(start 130.061716 -219.506038)
		(mid 130.109395 -219.323138)
		(end 130.240278 -219.18676)
		(width 0.0889)
		(layer "B.Cu")
		(net "VSENSE_PVCCD_HV_CPU1_DN")
	)
	(arc
		(start 129.775966 -214.093298)
		(mid 129.666819 -214.00937)
		(end 129.591816 -213.893908)
		(width 0.0889)
		(layer "B.Cu")
		(net "VSENSE_PVCCD_HV_CPU1_DN")
	)
	(arc
		(start 129.309114 -224.7138)
		(mid 129.175152 -224.582071)
		(end 129.121916 -224.401888)
		(width 0.0889)
		(layer "B.Cu")
		(net "VSENSE_PVCCD_HV_CPU1_DN")
	)
	(arc
		(start 129.309368 -225.69297)
		(mid 129.315873 -225.68895)
		(end 129.322322 -225.684842)
		(width 0.0889)
		(layer "B.Cu")
		(net "VSENSE_PVCCD_HV_CPU1_DN")
	)
	(arc
		(start 129.832354 -219.964)
		(mid 130.000366 -219.792795)
		(end 130.061716 -219.560902)
		(width 0.0889)
		(layer "B.Cu")
		(net "VSENSE_PVCCD_HV_CPU1_DN")
	)
	(arc
		(start 117.091968 -225.69297)
		(mid 117.279166 -225.642827)
		(end 117.466364 -225.69297)
		(width 0.0889)
		(layer "B.Cu")
		(net "VSENSE_PVCCD_HV_CPU1_DN")
	)
	(arc
		(start 111.66602 -222.383604)
		(mid 111.739313 -222.394839)
		(end 111.807498 -222.42399)
		(width 0.0889)
		(layer "B.Cu")
		(net "VSENSE_PVCCD_HV_CPU1_DN")
	)
	(arc
		(start 129.591816 -217.05443)
		(mid 129.513705 -216.777481)
		(end 129.309368 -216.574878)
		(width 0.0889)
		(layer "B.Cu")
		(net "VSENSE_PVCCD_HV_CPU1_DN")
	)
	(arc
		(start 127.429768 -225.69297)
		(mid 127.616966 -225.642827)
		(end 127.804164 -225.69297)
		(width 0.0889)
		(layer "B.Cu")
		(net "VSENSE_PVCCD_HV_CPU1_DN")
	)
	(arc
		(start 121.790968 -225.69297)
		(mid 121.978166 -225.642827)
		(end 122.165364 -225.69297)
		(width 0.0889)
		(layer "B.Cu")
		(net "VSENSE_PVCCD_HV_CPU1_DN")
	)
	(arc
		(start 129.59461 -215.350852)
		(mid 129.627453 -215.238418)
		(end 129.709418 -215.154764)
		(width 0.0889)
		(layer "B.Cu")
		(net "VSENSE_PVCCD_HV_CPU1_DN")
	)
	(arc
		(start 126.489968 -225.69297)
		(mid 126.677166 -225.642827)
		(end 126.864364 -225.69297)
		(width 0.0889)
		(layer "B.Cu")
		(net "VSENSE_PVCCD_HV_CPU1_DN")
	)
	(arc
		(start 130.061208 -214.424768)
		(mid 129.949929 -214.232062)
		(end 129.775966 -214.093298)
		(width 0.0889)
		(layer "B.Cu")
		(net "VSENSE_PVCCD_HV_CPU1_DN")
	)
	(arc
		(start 116.541296 -225.701606)
		(mid 116.817737 -225.768772)
		(end 117.091968 -225.69297)
		(width 0.0889)
		(layer "B.Cu")
		(net "VSENSE_PVCCD_HV_CPU1_DN")
	)
	(arc
		(start 129.121916 -216.235534)
		(mid 129.170793 -216.062577)
		(end 129.29616 -215.933782)
		(width 0.0889)
		(layer "B.Cu")
		(net "VSENSE_PVCCD_HV_CPU1_DN")
	)
	(arc
		(start 129.591816 -220.311218)
		(mid 129.644086 -220.128853)
		(end 129.779014 -219.995496)
		(width 0.0889)
		(layer "B.Cu")
		(net "VSENSE_PVCCD_HV_CPU1_DN")
	)
	(arc
		(start 119.911368 -225.69297)
		(mid 120.098566 -225.642827)
		(end 120.285764 -225.69297)
		(width 0.0889)
		(layer "B.Cu")
		(net "VSENSE_PVCCD_HV_CPU1_DN")
	)
	(arc
		(start 124.610368 -225.69297)
		(mid 124.797566 -225.642827)
		(end 124.984764 -225.69297)
		(width 0.0889)
		(layer "B.Cu")
		(net "VSENSE_PVCCD_HV_CPU1_DN")
	)
	(arc
		(start 115.212368 -225.69297)
		(mid 115.399566 -225.642827)
		(end 115.586764 -225.69297)
		(width 0.0889)
		(layer "B.Cu")
		(net "VSENSE_PVCCD_HV_CPU1_DN")
	)
	(arc
		(start 129.779014 -217.388694)
		(mid 129.644081 -217.25534)
		(end 129.591816 -217.072972)
		(width 0.0889)
		(layer "B.Cu")
		(net "VSENSE_PVCCD_HV_CPU1_DN")
	)
	(arc
		(start 113.721896 -225.701606)
		(mid 113.998337 -225.768772)
		(end 114.272568 -225.69297)
		(width 0.0889)
		(layer "B.Cu")
		(net "VSENSE_PVCCD_HV_CPU1_DN")
	)
	(arc
		(start 128.184402 -222.7199)
		(mid 128.240454 -222.560716)
		(end 128.360678 -222.442278)
		(width 0.0889)
		(layer "B.Cu")
		(net "VSENSE_PVCCD_HV_CPU1_DN")
	)
	(arc
		(start 128.194816 -222.857822)
		(mid 128.183156 -222.789346)
		(end 128.184402 -222.7199)
		(width 0.0889)
		(layer "B.Cu")
		(net "VSENSE_PVCCD_HV_CPU1_DN")
	)
	(arc
		(start 122.730768 -225.69297)
		(mid 122.917966 -225.642827)
		(end 123.105164 -225.69297)
		(width 0.0889)
		(layer "B.Cu")
		(net "VSENSE_PVCCD_HV_CPU1_DN")
	)
	(arc
		(start 124.999496 -225.701606)
		(mid 125.275937 -225.768772)
		(end 125.550168 -225.69297)
		(width 0.0889)
		(layer "B.Cu")
		(net "VSENSE_PVCCD_HV_CPU1_DN")
	)
	(arc
		(start 129.121916 -216.257124)
		(mid 129.121822 -216.248742)
		(end 129.121916 -216.24036)
		(width 0.0889)
		(layer "B.Cu")
		(net "VSENSE_PVCCD_HV_CPU1_DN")
	)
	(arc
		(start 129.590038 -225.131122)
		(mid 129.528472 -224.9131)
		(end 129.370328 -224.750884)
		(width 0.0889)
		(layer "B.Cu")
		(net "VSENSE_PVCCD_HV_CPU1_DN")
	)
	(arc
		(start 110.513368 -222.437198)
		(mid 110.700566 -222.387055)
		(end 110.887764 -222.437198)
		(width 0.0889)
		(layer "B.Cu")
		(net "VSENSE_PVCCD_HV_CPU1_DN")
	)
	(arc
		(start 128.360678 -223.080834)
		(mid 128.256354 -222.985252)
		(end 128.194816 -222.857822)
		(width 0.0889)
		(layer "B.Cu")
		(net "VSENSE_PVCCD_HV_CPU1_DN")
	)
	(arc
		(start 111.903764 -222.480378)
		(mid 111.985233 -222.562723)
		(end 112.015016 -222.674688)
		(width 0.0889)
		(layer "B.Cu")
		(net "VSENSE_PVCCD_HV_CPU1_DN")
	)
	(arc
		(start 114.272568 -225.69297)
		(mid 114.459766 -225.642827)
		(end 114.646964 -225.69297)
		(width 0.0889)
		(layer "B.Cu")
		(net "VSENSE_PVCCD_HV_CPU1_DN")
	)
	(arc
		(start 122.180096 -225.701606)
		(mid 122.456537 -225.768772)
		(end 122.730768 -225.69297)
		(width 0.0889)
		(layer "B.Cu")
		(net "VSENSE_PVCCD_HV_CPU1_DN")
	)
	(arc
		(start 130.249168 -219.18168)
		(mid 130.451991 -218.981449)
		(end 130.531362 -218.707716)
		(width 0.0889)
		(layer "B.Cu")
		(net "VSENSE_PVCCD_HV_CPU1_DN")
	)
	(arc
		(start 118.420896 -225.701606)
		(mid 118.697337 -225.768772)
		(end 118.971568 -225.69297)
		(width 0.0889)
		(layer "B.Cu")
		(net "VSENSE_PVCCD_HV_CPU1_DN")
	)
	(arc
		(start 119.360696 -225.701606)
		(mid 119.637137 -225.768772)
		(end 119.911368 -225.69297)
		(width 0.0889)
		(layer "B.Cu")
		(net "VSENSE_PVCCD_HV_CPU1_DN")
	)
	(arc
		(start 130.531362 -218.676728)
		(mid 130.451992 -218.402994)
		(end 130.249168 -218.202764)
		(width 0.0889)
		(layer "B.Cu")
		(net "VSENSE_PVCCD_HV_CPU1_DN")
	)
	(arc
		(start 123.670568 -225.69297)
		(mid 123.857766 -225.642827)
		(end 124.044964 -225.69297)
		(width 0.0889)
		(layer "B.Cu")
		(net "VSENSE_PVCCD_HV_CPU1_DN")
	)
	(arc
		(start 120.300496 -225.701606)
		(mid 120.576937 -225.768772)
		(end 120.851168 -225.69297)
		(width 0.0889)
		(layer "B.Cu")
		(net "VSENSE_PVCCD_HV_CPU1_DN")
	)
	(arc
		(start 114.661696 -225.701606)
		(mid 114.938137 -225.768772)
		(end 115.212368 -225.69297)
		(width 0.0889)
		(layer "B.Cu")
		(net "VSENSE_PVCCD_HV_CPU1_DN")
	)
	(arc
		(start 126.879096 -225.701606)
		(mid 127.155537 -225.768772)
		(end 127.429768 -225.69297)
		(width 0.0889)
		(layer "B.Cu")
		(net "VSENSE_PVCCD_HV_CPU1_DN")
	)
	(arc
		(start 129.121916 -224.379536)
		(mid 129.043805 -224.102587)
		(end 128.839468 -223.899984)
		(width 0.0889)
		(layer "B.Cu")
		(net "VSENSE_PVCCD_HV_CPU1_DN")
	)
	(arc
		(start 128.758696 -225.701606)
		(mid 129.035137 -225.768772)
		(end 129.309368 -225.69297)
		(width 0.0889)
		(layer "B.Cu")
		(net "VSENSE_PVCCD_HV_CPU1_DN")
	)
	(arc
		(start 113.424462 -225.217482)
		(mid 113.503681 -225.492167)
		(end 113.707164 -225.69297)
		(width 0.0889)
		(layer "B.Cu")
		(net "VSENSE_PVCCD_HV_CPU1_DN")
	)
	(arc
		(start 109.669072 -222.013526)
		(mid 109.977051 -222.452885)
		(end 110.513368 -222.437198)
		(width 0.0889)
		(layer "B.Cu")
		(net "VSENSE_PVCCD_HV_CPU1_DN")
	)
	(arc
		(start 112.297464 -224.8789)
		(mid 112.574906 -224.954776)
		(end 112.853724 -224.884234)
		(width 0.0889)
		(layer "B.Cu")
		(net "VSENSE_PVCCD_HV_CPU1_DN")
	)
	(arc
		(start 123.119896 -225.701606)
		(mid 123.396337 -225.768772)
		(end 123.670568 -225.69297)
		(width 0.0889)
		(layer "B.Cu")
		(net "VSENSE_PVCCD_HV_CPU1_DN")
	)
	(arc
		(start 129.300478 -216.569798)
		(mid 129.171189 -216.436312)
		(end 129.121916 -216.257124)
		(width 0.0889)
		(layer "B.Cu")
		(net "VSENSE_PVCCD_HV_CPU1_DN")
	)
	(arc
		(start 116.152168 -225.69297)
		(mid 116.339366 -225.642827)
		(end 116.526564 -225.69297)
		(width 0.0889)
		(layer "B.Cu")
		(net "VSENSE_PVCCD_HV_CPU1_DN")
	)
	(arc
		(start 117.481096 -225.701606)
		(mid 117.757537 -225.768772)
		(end 118.031768 -225.69297)
		(width 0.0889)
		(layer "B.Cu")
		(net "VSENSE_PVCCD_HV_CPU1_DN")
	)
	(arc
		(start 112.274858 -224.865184)
		(mid 112.286082 -224.872172)
		(end 112.297464 -224.8789)
		(width 0.0889)
		(layer "B.Cu")
		(net "VSENSE_PVCCD_HV_CPU1_DN")
	)
	(arc
		(start 110.887764 -222.437198)
		(mid 111.170466 -222.512974)
		(end 111.453168 -222.437198)
		(width 0.0889)
		(layer "B.Cu")
		(net "VSENSE_PVCCD_HV_CPU1_DN")
	)
	(arc
		(start 112.015016 -222.780098)
		(mid 112.095178 -223.052287)
		(end 112.297464 -223.251268)
		(width 0.0889)
		(layer "B.Cu")
		(net "VSENSE_PVCCD_HV_CPU1_DN")
	)
	(arc
		(start 130.240278 -218.197684)
		(mid 130.109364 -218.061324)
		(end 130.061716 -217.878406)
		(width 0.0889)
		(layer "B.Cu")
		(net "VSENSE_PVCCD_HV_CPU1_DN")
	)
	(arc
		(start 121.240296 -225.701606)
		(mid 121.516737 -225.768772)
		(end 121.790968 -225.69297)
		(width 0.0889)
		(layer "B.Cu")
		(net "VSENSE_PVCCD_HV_CPU1_DN")
	)
	(arc
		(start 118.971568 -225.69297)
		(mid 119.158766 -225.642827)
		(end 119.345964 -225.69297)
		(width 0.0889)
		(layer "B.Cu")
		(net "VSENSE_PVCCD_HV_CPU1_DN")
	)
	(arc
		(start 111.610394 -222.38589)
		(mid 111.637787 -222.383803)
		(end 111.665258 -222.383604)
		(width 0.0889)
		(layer "B.Cu")
		(net "VSENSE_PVCCD_HV_CPU1_DN")
	)
	(arc
		(start 120.851168 -225.69297)
		(mid 121.038366 -225.642827)
		(end 121.225564 -225.69297)
		(width 0.0889)
		(layer "B.Cu")
		(net "VSENSE_PVCCD_HV_CPU1_DN")
	)
	(arc
		(start 111.453168 -222.437198)
		(mid 111.529107 -222.403341)
		(end 111.610394 -222.38589)
		(width 0.0889)
		(layer "B.Cu")
		(net "VSENSE_PVCCD_HV_CPU1_DN")
	)
	(arc
		(start 112.286034 -223.90735)
		(mid 112.01403 -224.38314)
		(end 112.274858 -224.865184)
		(width 0.0889)
		(layer "B.Cu")
		(net "VSENSE_PVCCD_HV_CPU1_DN")
	)
	(arc
		(start 129.590038 -215.522556)
		(mid 129.590585 -215.473401)
		(end 129.591816 -215.424258)
		(width 0.0889)
		(layer "B.Cu")
		(net "VSENSE_PVCCD_HV_CPU1_DN")
	)
	(arc
		(start 115.601496 -225.701606)
		(mid 115.877937 -225.768772)
		(end 116.152168 -225.69297)
		(width 0.0889)
		(layer "B.Cu")
		(net "VSENSE_PVCCD_HV_CPU1_DN")
	)
	(arc
		(start 129.556256 -215.68537)
		(mid 129.581424 -215.60581)
		(end 129.590038 -215.52281)
		(width 0.0889)
		(layer "B.Cu")
		(net "VSENSE_PVCCD_HV_CPU1_DN")
	)
	(arc
		(start 129.322322 -225.684842)
		(mid 129.52344 -225.472612)
		(end 129.591562 -225.188272)
		(width 0.0889)
		(layer "B.Cu")
		(net "VSENSE_PVCCD_HV_CPU1_DN")
	)
	(arc
		(start 112.862614 -224.8789)
		(mid 113.049812 -224.828757)
		(end 113.23701 -224.8789)
		(width 0.0889)
		(layer "B.Cu")
		(net "VSENSE_PVCCD_HV_CPU1_DN")
	)
	(arc
		(start 125.550168 -225.69297)
		(mid 125.737366 -225.642827)
		(end 125.924564 -225.69297)
		(width 0.0889)
		(layer "B.Cu")
		(net "VSENSE_PVCCD_HV_CPU1_DN")
	)
	(arc
		(start 112.297718 -223.251014)
		(mid 112.431091 -223.381764)
		(end 112.484916 -223.56064)
		(width 0.0889)
		(layer "B.Cu")
		(net "VSENSE_PVCCD_HV_CPU1_DN")
	)
	(arc
		(start 129.309368 -220.809566)
		(mid 129.511654 -220.610585)
		(end 129.591816 -220.338396)
		(width 0.0889)
		(layer "B.Cu")
		(net "VSENSE_PVCCD_HV_CPU1_DN")
	)
	(segment
		(start 20.484084 -154.718766)
		(end 20.484084 -160.352232)
		(width 0.254)
		(layer "In11.Cu")
		(net "VSENSE_PVCCD_HV_CPU1_DN")
	)
	(segment
		(start 20.484084 -160.352232)
		(end 21.1582 -161.026348)
		(width 0.254)
		(layer "In11.Cu")
		(net "VSENSE_PVCCD_HV_CPU1_DN")
	)
	(segment
		(start 22.582886 -160.48609)
		(end 22.582886 -159.815784)
		(width 0.254)
		(layer "In11.Cu")
		(net "VSENSE_PVCCD_HV_CPU1_DN")
	)
	(segment
		(start 85.73516 -171.289472)
		(end 89.119964 -174.674276)
		(width 0.254)
		(layer "In11.Cu")
		(net "VSENSE_PVCCD_HV_CPU1_DN")
	)
	(segment
		(start 71.34606 -146.026378)
		(end 71.34606 -143.818356)
		(width 0.254)
		(layer "In11.Cu")
		(net "VSENSE_PVCCD_HV_CPU1_DN")
	)
	(segment
		(start 75.52563 -160.444688)
		(end 77.06106 -160.444688)
		(width 0.254)
		(layer "In11.Cu")
		(net "VSENSE_PVCCD_HV_CPU1_DN")
	)
	(segment
		(start 75.28687 -160.205928)
		(end 75.52563 -160.444688)
		(width 0.254)
		(layer "In11.Cu")
		(net "VSENSE_PVCCD_HV_CPU1_DN")
	)
	(segment
		(start 75.03541 -160.457388)
		(end 74.394568 -160.457388)
		(width 0.254)
		(layer "In11.Cu")
		(net "VSENSE_PVCCD_HV_CPU1_DN")
	)
	(segment
		(start 22.582886 -159.815784)
		(end 22.824186 -159.574484)
		(width 0.254)
		(layer "In11.Cu")
		(net "VSENSE_PVCCD_HV_CPU1_DN")
	)
	(segment
		(start 85.73516 -169.118788)
		(end 85.73516 -171.289472)
		(width 0.254)
		(layer "In11.Cu")
		(net "VSENSE_PVCCD_HV_CPU1_DN")
	)
	(segment
		(start 33.454594 -141.748256)
		(end 20.484084 -154.718766)
		(width 0.254)
		(layer "In11.Cu")
		(net "VSENSE_PVCCD_HV_CPU1_DN")
	)
	(segment
		(start 73.47712 -159.53994)
		(end 73.47712 -148.157438)
		(width 0.254)
		(layer "In11.Cu")
		(net "VSENSE_PVCCD_HV_CPU1_DN")
	)
	(segment
		(start 73.47712 -148.157438)
		(end 71.34606 -146.026378)
		(width 0.254)
		(layer "In11.Cu")
		(net "VSENSE_PVCCD_HV_CPU1_DN")
	)
	(segment
		(start 77.06106 -160.444688)
		(end 85.73516 -169.118788)
		(width 0.254)
		(layer "In11.Cu")
		(net "VSENSE_PVCCD_HV_CPU1_DN")
	)
	(segment
		(start 71.34606 -143.818356)
		(end 69.27596 -141.748256)
		(width 0.254)
		(layer "In11.Cu")
		(net "VSENSE_PVCCD_HV_CPU1_DN")
	)
	(segment
		(start 69.27596 -141.748256)
		(end 33.454594 -141.748256)
		(width 0.254)
		(layer "In11.Cu")
		(net "VSENSE_PVCCD_HV_CPU1_DN")
	)
	(segment
		(start 75.28687 -160.205928)
		(end 75.03541 -160.457388)
		(width 0.254)
		(layer "In11.Cu")
		(net "VSENSE_PVCCD_HV_CPU1_DN")
	)
	(segment
		(start 22.042628 -161.026348)
		(end 22.582886 -160.48609)
		(width 0.254)
		(layer "In11.Cu")
		(net "VSENSE_PVCCD_HV_CPU1_DN")
	)
	(segment
		(start 91.114626 -174.674276)
		(end 91.355926 -174.432976)
		(width 0.254)
		(layer "In11.Cu")
		(net "VSENSE_PVCCD_HV_CPU1_DN")
	)
	(segment
		(start 89.119964 -174.674276)
		(end 91.114626 -174.674276)
		(width 0.254)
		(layer "In11.Cu")
		(net "VSENSE_PVCCD_HV_CPU1_DN")
	)
	(segment
		(start 21.1582 -161.026348)
		(end 22.042628 -161.026348)
		(width 0.254)
		(layer "In11.Cu")
		(net "VSENSE_PVCCD_HV_CPU1_DN")
	)
	(segment
		(start 74.394568 -160.457388)
		(end 73.47712 -159.53994)
		(width 0.254)
		(layer "In11.Cu")
		(net "VSENSE_PVCCD_HV_CPU1_DN")
	)
	(segment
		(start 382.50241 -202.923394)
		(end 382.873758 -202.552046)
		(width 0.254)
		(layer "F.Cu")
		(net "VSENSE_PVCCD_HV_CPU0_DP")
	)
	(segment
		(start 433.959508 -128.468374)
		(end 434.430424 -128.468374)
		(width 0.254)
		(layer "F.Cu")
		(net "VSENSE_PVCCD_HV_CPU0_DP")
	)
	(segment
		(start 396.075916 -166.551864)
		(end 396.317216 -166.793164)
		(width 0.254)
		(layer "F.Cu")
		(net "VSENSE_PVCCD_HV_CPU0_DP")
	)
	(segment
		(start 387.19633 -198.39305)
		(end 392.533378 -193.056002)
		(width 0.254)
		(layer "F.Cu")
		(net "VSENSE_PVCCD_HV_CPU0_DP")
	)
	(segment
		(start 381.892556 -202.682094)
		(end 382.133856 -202.923394)
		(width 0.254)
		(layer "F.Cu")
		(net "VSENSE_PVCCD_HV_CPU0_DP")
	)
	(segment
		(start 434.430424 -128.468374)
		(end 434.839364 -128.877314)
		(width 0.254)
		(layer "F.Cu")
		(net "VSENSE_PVCCD_HV_CPU0_DP")
	)
	(segment
		(start 396.685516 -166.793164)
		(end 397.003016 -166.475664)
		(width 0.254)
		(layer "F.Cu")
		(net "VSENSE_PVCCD_HV_CPU0_DP")
	)
	(segment
		(start 395.444218 -171.296076)
		(end 394.702792 -170.55465)
		(width 0.254)
		(layer "F.Cu")
		(net "VSENSE_PVCCD_HV_CPU0_DP")
	)
	(segment
		(start 359.110534 -222.48368)
		(end 359.110534 -221.94774)
		(width 0.12954)
		(layer "F.Cu")
		(net "VSENSE_PVCCD_HV_CPU0_DP")
	)
	(segment
		(start 395.307312 -166.793164)
		(end 395.834616 -166.793164)
		(width 0.254)
		(layer "F.Cu")
		(net "VSENSE_PVCCD_HV_CPU0_DP")
	)
	(segment
		(start 394.702792 -170.55465)
		(end 394.702792 -167.397684)
		(width 0.254)
		(layer "F.Cu")
		(net "VSENSE_PVCCD_HV_CPU0_DP")
	)
	(segment
		(start 392.533378 -193.056002)
		(end 392.533378 -186.302142)
		(width 0.254)
		(layer "F.Cu")
		(net "VSENSE_PVCCD_HV_CPU0_DP")
	)
	(segment
		(start 396.317216 -166.793164)
		(end 396.685516 -166.793164)
		(width 0.254)
		(layer "F.Cu")
		(net "VSENSE_PVCCD_HV_CPU0_DP")
	)
	(segment
		(start 394.702792 -167.397684)
		(end 395.307312 -166.793164)
		(width 0.254)
		(layer "F.Cu")
		(net "VSENSE_PVCCD_HV_CPU0_DP")
	)
	(segment
		(start 395.444218 -183.391302)
		(end 395.444218 -171.296076)
		(width 0.254)
		(layer "F.Cu")
		(net "VSENSE_PVCCD_HV_CPU0_DP")
	)
	(segment
		(start 382.873758 -200.54697)
		(end 385.027678 -198.39305)
		(width 0.254)
		(layer "F.Cu")
		(net "VSENSE_PVCCD_HV_CPU0_DP")
	)
	(segment
		(start 395.834616 -166.793164)
		(end 396.075916 -166.551864)
		(width 0.254)
		(layer "F.Cu")
		(net "VSENSE_PVCCD_HV_CPU0_DP")
	)
	(segment
		(start 382.133856 -202.923394)
		(end 382.50241 -202.923394)
		(width 0.254)
		(layer "F.Cu")
		(net "VSENSE_PVCCD_HV_CPU0_DP")
	)
	(segment
		(start 382.873758 -202.552046)
		(end 382.873758 -200.54697)
		(width 0.254)
		(layer "F.Cu")
		(net "VSENSE_PVCCD_HV_CPU0_DP")
	)
	(segment
		(start 392.533378 -186.302142)
		(end 395.444218 -183.391302)
		(width 0.254)
		(layer "F.Cu")
		(net "VSENSE_PVCCD_HV_CPU0_DP")
	)
	(segment
		(start 433.718208 -128.709674)
		(end 433.959508 -128.468374)
		(width 0.254)
		(layer "F.Cu")
		(net "VSENSE_PVCCD_HV_CPU0_DP")
	)
	(segment
		(start 385.027678 -198.39305)
		(end 387.19633 -198.39305)
		(width 0.254)
		(layer "F.Cu")
		(net "VSENSE_PVCCD_HV_CPU0_DP")
	)
	(via
		(at 433.718208 -128.709674)
		(size 0.508)
		(drill 0.254)
		(layers "F.Cu" "B.Cu")
		(net "VSENSE_PVCCD_HV_CPU0_DP")
	)
	(via
		(at 396.075916 -166.551864)
		(size 0.508)
		(drill 0.254)
		(layers "F.Cu" "B.Cu")
		(net "VSENSE_PVCCD_HV_CPU0_DP")
	)
	(via
		(at 359.110534 -221.94774)
		(size 0.4572)
		(drill 0.2032)
		(layers "F.Cu" "B.Cu")
		(net "VSENSE_PVCCD_HV_CPU0_DP")
	)
	(via
		(at 381.892556 -202.682094)
		(size 0.508)
		(drill 0.254)
		(layers "F.Cu" "B.Cu")
		(net "VSENSE_PVCCD_HV_CPU0_DP")
	)
	(segment
		(start 360.145584 -222.776542)
		(end 360.145584 -222.761556)
		(width 0.0889)
		(layer "B.Cu")
		(net "VSENSE_PVCCD_HV_CPU0_DP")
	)
	(segment
		(start 364.466124 -223.086422)
		(end 364.457742 -223.091248)
		(width 0.0889)
		(layer "B.Cu")
		(net "VSENSE_PVCCD_HV_CPU0_DP")
	)
	(segment
		(start 367.285778 -223.086422)
		(end 367.277142 -223.091248)
		(width 0.0889)
		(layer "B.Cu")
		(net "VSENSE_PVCCD_HV_CPU0_DP")
	)
	(segment
		(start 377.632214 -214.941912)
		(end 377.623324 -214.946992)
		(width 0.0889)
		(layer "B.Cu")
		(net "VSENSE_PVCCD_HV_CPU0_DP")
	)
	(segment
		(start 360.706924 -223.086422)
		(end 360.698542 -223.091248)
		(width 0.0889)
		(layer "B.Cu")
		(net "VSENSE_PVCCD_HV_CPU0_DP")
	)
	(segment
		(start 377.143518 -216.733882)
		(end 377.15444 -216.740232)
		(width 0.0889)
		(layer "B.Cu")
		(net "VSENSE_PVCCD_HV_CPU0_DP")
	)
	(segment
		(start 377.34113 -215.414606)
		(end 377.34113 -215.447118)
		(width 0.0889)
		(layer "B.Cu")
		(net "VSENSE_PVCCD_HV_CPU0_DP")
	)
	(segment
		(start 373.112284 -222.761556)
		(end 373.112284 -222.776542)
		(width 0.0889)
		(layer "B.Cu")
		(net "VSENSE_PVCCD_HV_CPU0_DP")
	)
	(segment
		(start 377.246134 -206.177134)
		(end 377.246134 -212.87105)
		(width 0.254)
		(layer "B.Cu")
		(net "VSENSE_PVCCD_HV_CPU0_DP")
	)
	(segment
		(start 369.165378 -223.086422)
		(end 369.156742 -223.091248)
		(width 0.0889)
		(layer "B.Cu")
		(net "VSENSE_PVCCD_HV_CPU0_DP")
	)
	(segment
		(start 361.646978 -223.086422)
		(end 361.638342 -223.091248)
		(width 0.0889)
		(layer "B.Cu")
		(net "VSENSE_PVCCD_HV_CPU0_DP")
	)
	(segment
		(start 377.246134 -213.035642)
		(end 377.341384 -213.130892)
		(width 0.0889)
		(layer "B.Cu")
		(net "VSENSE_PVCCD_HV_CPU0_DP")
	)
	(segment
		(start 377.154186 -215.760808)
		(end 377.143518 -215.766904)
		(width 0.0889)
		(layer "B.Cu")
		(net "VSENSE_PVCCD_HV_CPU0_DP")
	)
	(segment
		(start 374.797574 -220.805248)
		(end 374.805702 -220.80982)
		(width 0.0889)
		(layer "B.Cu")
		(net "VSENSE_PVCCD_HV_CPU0_DP")
	)
	(segment
		(start 377.810776 -214.461344)
		(end 377.810776 -214.622634)
		(width 0.0889)
		(layer "B.Cu")
		(net "VSENSE_PVCCD_HV_CPU0_DP")
	)
	(segment
		(start 365.406178 -223.086422)
		(end 365.397542 -223.091248)
		(width 0.0889)
		(layer "B.Cu")
		(net "VSENSE_PVCCD_HV_CPU0_DP")
	)
	(segment
		(start 366.345724 -223.086422)
		(end 366.337342 -223.091248)
		(width 0.0889)
		(layer "B.Cu")
		(net "VSENSE_PVCCD_HV_CPU0_DP")
	)
	(segment
		(start 377.341384 -217.056462)
		(end 377.341384 -217.075004)
		(width 0.0889)
		(layer "B.Cu")
		(net "VSENSE_PVCCD_HV_CPU0_DP")
	)
	(segment
		(start 359.3592 -222.196406)
		(end 359.110534 -221.94774)
		(width 0.0889)
		(layer "B.Cu")
		(net "VSENSE_PVCCD_HV_CPU0_DP")
	)
	(segment
		(start 377.341384 -213.130892)
		(end 377.341384 -213.930484)
		(width 0.0889)
		(layer "B.Cu")
		(net "VSENSE_PVCCD_HV_CPU0_DP")
	)
	(segment
		(start 376.683524 -219.83065)
		(end 376.675142 -219.835476)
		(width 0.0889)
		(layer "B.Cu")
		(net "VSENSE_PVCCD_HV_CPU0_DP")
	)
	(segment
		(start 377.811284 -217.866976)
		(end 377.811284 -217.878406)
		(width 0.0889)
		(layer "B.Cu")
		(net "VSENSE_PVCCD_HV_CPU0_DP")
	)
	(segment
		(start 370.104924 -223.086422)
		(end 370.096542 -223.091248)
		(width 0.0889)
		(layer "B.Cu")
		(net "VSENSE_PVCCD_HV_CPU0_DP")
	)
	(segment
		(start 377.731528 -219.023946)
		(end 377.719844 -219.016834)
		(width 0.0889)
		(layer "B.Cu")
		(net "VSENSE_PVCCD_HV_CPU0_DP")
	)
	(segment
		(start 377.246134 -212.87105)
		(end 377.246134 -213.035642)
		(width 0.0889)
		(layer "B.Cu")
		(net "VSENSE_PVCCD_HV_CPU0_DP")
	)
	(segment
		(start 376.871484 -219.506038)
		(end 376.871484 -219.513912)
		(width 0.0889)
		(layer "B.Cu")
		(net "VSENSE_PVCCD_HV_CPU0_DP")
	)
	(segment
		(start 373.58193 -221.947486)
		(end 373.58193 -221.960186)
		(width 0.0889)
		(layer "B.Cu")
		(net "VSENSE_PVCCD_HV_CPU0_DP")
	)
	(segment
		(start 381.651256 -202.923394)
		(end 380.499874 -202.923394)
		(width 0.254)
		(layer "B.Cu")
		(net "VSENSE_PVCCD_HV_CPU0_DP")
	)
	(segment
		(start 376.684032 -219.830396)
		(end 376.683524 -219.83065)
		(width 0.0889)
		(layer "B.Cu")
		(net "VSENSE_PVCCD_HV_CPU0_DP")
	)
	(segment
		(start 378.28093 -218.679776)
		(end 378.28093 -218.704668)
		(width 0.0889)
		(layer "B.Cu")
		(net "VSENSE_PVCCD_HV_CPU0_DP")
	)
	(segment
		(start 375.743724 -219.83065)
		(end 375.735088 -219.835476)
		(width 0.0889)
		(layer "B.Cu")
		(net "VSENSE_PVCCD_HV_CPU0_DP")
	)
	(segment
		(start 359.57764 -222.196406)
		(end 359.3592 -222.196406)
		(width 0.0889)
		(layer "B.Cu")
		(net "VSENSE_PVCCD_HV_CPU0_DP")
	)
	(segment
		(start 371.044978 -223.086422)
		(end 371.036342 -223.091248)
		(width 0.0889)
		(layer "B.Cu")
		(net "VSENSE_PVCCD_HV_CPU0_DP")
	)
	(segment
		(start 371.984524 -223.086422)
		(end 371.976142 -223.091248)
		(width 0.0889)
		(layer "B.Cu")
		(net "VSENSE_PVCCD_HV_CPU0_DP")
	)
	(segment
		(start 380.499874 -202.923394)
		(end 377.246134 -206.177134)
		(width 0.254)
		(layer "B.Cu")
		(net "VSENSE_PVCCD_HV_CPU0_DP")
	)
	(segment
		(start 368.225324 -223.086422)
		(end 368.216942 -223.091248)
		(width 0.0889)
		(layer "B.Cu")
		(net "VSENSE_PVCCD_HV_CPU0_DP")
	)
	(segment
		(start 381.892556 -202.682094)
		(end 381.651256 -202.923394)
		(width 0.254)
		(layer "B.Cu")
		(net "VSENSE_PVCCD_HV_CPU0_DP")
	)
	(segment
		(start 374.791224 -220.801438)
		(end 374.797574 -220.805248)
		(width 0.0889)
		(layer "B.Cu")
		(net "VSENSE_PVCCD_HV_CPU0_DP")
	)
	(segment
		(start 373.394986 -222.271844)
		(end 373.384318 -222.27794)
		(width 0.0889)
		(layer "B.Cu")
		(net "VSENSE_PVCCD_HV_CPU0_DP")
	)
	(segment
		(start 378.083318 -218.362022)
		(end 378.09424 -218.368118)
		(width 0.0889)
		(layer "B.Cu")
		(net "VSENSE_PVCCD_HV_CPU0_DP")
	)
	(arc
		(start 369.730782 -223.086168)
		(mid 369.448051 -223.010519)
		(end 369.165378 -223.086422)
		(width 0.0889)
		(layer "B.Cu")
		(net "VSENSE_PVCCD_HV_CPU0_DP")
	)
	(arc
		(start 374.805702 -220.80982)
		(mid 374.941346 -221.321688)
		(end 374.429528 -221.458282)
		(width 0.0889)
		(layer "B.Cu")
		(net "VSENSE_PVCCD_HV_CPU0_DP")
	)
	(arc
		(start 360.698542 -223.091248)
		(mid 360.3348 -223.087293)
		(end 360.145584 -222.776542)
		(width 0.0889)
		(layer "B.Cu")
		(net "VSENSE_PVCCD_HV_CPU0_DP")
	)
	(arc
		(start 362.587286 -223.086168)
		(mid 362.399834 -223.136404)
		(end 362.212382 -223.086168)
		(width 0.0889)
		(layer "B.Cu")
		(net "VSENSE_PVCCD_HV_CPU0_DP")
	)
	(arc
		(start 366.911128 -223.086168)
		(mid 366.628397 -223.010519)
		(end 366.345724 -223.086422)
		(width 0.0889)
		(layer "B.Cu")
		(net "VSENSE_PVCCD_HV_CPU0_DP")
	)
	(arc
		(start 370.096542 -223.091248)
		(mid 369.913004 -223.13634)
		(end 369.730782 -223.086168)
		(width 0.0889)
		(layer "B.Cu")
		(net "VSENSE_PVCCD_HV_CPU0_DP")
	)
	(arc
		(start 362.212382 -223.086168)
		(mid 361.929651 -223.010519)
		(end 361.646978 -223.086422)
		(width 0.0889)
		(layer "B.Cu")
		(net "VSENSE_PVCCD_HV_CPU0_DP")
	)
	(arc
		(start 376.871484 -219.513912)
		(mid 376.819268 -219.696743)
		(end 376.684032 -219.830396)
		(width 0.0889)
		(layer "B.Cu")
		(net "VSENSE_PVCCD_HV_CPU0_DP")
	)
	(arc
		(start 367.277142 -223.091248)
		(mid 367.09346 -223.136463)
		(end 366.911128 -223.086168)
		(width 0.0889)
		(layer "B.Cu")
		(net "VSENSE_PVCCD_HV_CPU0_DP")
	)
	(arc
		(start 366.337342 -223.091248)
		(mid 366.153804 -223.13634)
		(end 365.971582 -223.086168)
		(width 0.0889)
		(layer "B.Cu")
		(net "VSENSE_PVCCD_HV_CPU0_DP")
	)
	(arc
		(start 373.384318 -222.27794)
		(mid 373.184887 -222.484081)
		(end 373.112284 -222.761556)
		(width 0.0889)
		(layer "B.Cu")
		(net "VSENSE_PVCCD_HV_CPU0_DP")
	)
	(arc
		(start 365.031528 -223.086168)
		(mid 364.748797 -223.010519)
		(end 364.466124 -223.086422)
		(width 0.0889)
		(layer "B.Cu")
		(net "VSENSE_PVCCD_HV_CPU0_DP")
	)
	(arc
		(start 368.790728 -223.086168)
		(mid 368.507997 -223.010519)
		(end 368.225324 -223.086422)
		(width 0.0889)
		(layer "B.Cu")
		(net "VSENSE_PVCCD_HV_CPU0_DP")
	)
	(arc
		(start 378.09424 -218.368118)
		(mid 378.22787 -218.499818)
		(end 378.28093 -218.679776)
		(width 0.0889)
		(layer "B.Cu")
		(net "VSENSE_PVCCD_HV_CPU0_DP")
	)
	(arc
		(start 376.309128 -219.830396)
		(mid 376.026397 -219.754747)
		(end 375.743724 -219.83065)
		(width 0.0889)
		(layer "B.Cu")
		(net "VSENSE_PVCCD_HV_CPU0_DP")
	)
	(arc
		(start 378.093732 -219.01658)
		(mid 377.913587 -219.066901)
		(end 377.731528 -219.023946)
		(width 0.0889)
		(layer "B.Cu")
		(net "VSENSE_PVCCD_HV_CPU0_DP")
	)
	(arc
		(start 364.091982 -223.086168)
		(mid 363.809534 -223.010519)
		(end 363.527086 -223.086168)
		(width 0.0889)
		(layer "B.Cu")
		(net "VSENSE_PVCCD_HV_CPU0_DP")
	)
	(arc
		(start 377.143518 -215.766904)
		(mid 376.871124 -216.250454)
		(end 377.143518 -216.733882)
		(width 0.0889)
		(layer "B.Cu")
		(net "VSENSE_PVCCD_HV_CPU0_DP")
	)
	(arc
		(start 365.971582 -223.086168)
		(mid 365.688851 -223.010519)
		(end 365.406178 -223.086422)
		(width 0.0889)
		(layer "B.Cu")
		(net "VSENSE_PVCCD_HV_CPU0_DP")
	)
	(arc
		(start 367.851182 -223.086168)
		(mid 367.568451 -223.010519)
		(end 367.285778 -223.086422)
		(width 0.0889)
		(layer "B.Cu")
		(net "VSENSE_PVCCD_HV_CPU0_DP")
	)
	(arc
		(start 374.429528 -221.458282)
		(mid 373.864584 -221.45831)
		(end 373.58193 -221.947486)
		(width 0.0889)
		(layer "B.Cu")
		(net "VSENSE_PVCCD_HV_CPU0_DP")
	)
	(arc
		(start 377.623832 -217.553794)
		(mid 377.758209 -217.686038)
		(end 377.811284 -217.866976)
		(width 0.0889)
		(layer "B.Cu")
		(net "VSENSE_PVCCD_HV_CPU0_DP")
	)
	(arc
		(start 373.58193 -221.960186)
		(mid 373.528798 -222.140229)
		(end 373.394986 -222.271844)
		(width 0.0889)
		(layer "B.Cu")
		(net "VSENSE_PVCCD_HV_CPU0_DP")
	)
	(arc
		(start 377.15444 -216.740232)
		(mid 377.289327 -216.873867)
		(end 377.341384 -217.056462)
		(width 0.0889)
		(layer "B.Cu")
		(net "VSENSE_PVCCD_HV_CPU0_DP")
	)
	(arc
		(start 377.810776 -214.622634)
		(mid 377.763097 -214.805534)
		(end 377.632214 -214.941912)
		(width 0.0889)
		(layer "B.Cu")
		(net "VSENSE_PVCCD_HV_CPU0_DP")
	)
	(arc
		(start 377.34113 -215.447118)
		(mid 377.288465 -215.628289)
		(end 377.154186 -215.760808)
		(width 0.0889)
		(layer "B.Cu")
		(net "VSENSE_PVCCD_HV_CPU0_DP")
	)
	(arc
		(start 363.527086 -223.086168)
		(mid 363.339634 -223.136404)
		(end 363.152182 -223.086168)
		(width 0.0889)
		(layer "B.Cu")
		(net "VSENSE_PVCCD_HV_CPU0_DP")
	)
	(arc
		(start 378.28093 -218.704668)
		(mid 378.227709 -218.88486)
		(end 378.093732 -219.01658)
		(width 0.0889)
		(layer "B.Cu")
		(net "VSENSE_PVCCD_HV_CPU0_DP")
	)
	(arc
		(start 370.670328 -223.086168)
		(mid 370.387597 -223.010519)
		(end 370.104924 -223.086422)
		(width 0.0889)
		(layer "B.Cu")
		(net "VSENSE_PVCCD_HV_CPU0_DP")
	)
	(arc
		(start 361.638342 -223.091248)
		(mid 361.45466 -223.136463)
		(end 361.272328 -223.086168)
		(width 0.0889)
		(layer "B.Cu")
		(net "VSENSE_PVCCD_HV_CPU0_DP")
	)
	(arc
		(start 368.216942 -223.091248)
		(mid 368.033404 -223.13634)
		(end 367.851182 -223.086168)
		(width 0.0889)
		(layer "B.Cu")
		(net "VSENSE_PVCCD_HV_CPU0_DP")
	)
	(arc
		(start 369.156742 -223.091248)
		(mid 368.97306 -223.136463)
		(end 368.790728 -223.086168)
		(width 0.0889)
		(layer "B.Cu")
		(net "VSENSE_PVCCD_HV_CPU0_DP")
	)
	(arc
		(start 371.976142 -223.091248)
		(mid 371.792604 -223.13634)
		(end 371.610382 -223.086168)
		(width 0.0889)
		(layer "B.Cu")
		(net "VSENSE_PVCCD_HV_CPU0_DP")
	)
	(arc
		(start 363.152182 -223.086168)
		(mid 362.869734 -223.010519)
		(end 362.587286 -223.086168)
		(width 0.0889)
		(layer "B.Cu")
		(net "VSENSE_PVCCD_HV_CPU0_DP")
	)
	(arc
		(start 361.272328 -223.086168)
		(mid 360.989597 -223.010519)
		(end 360.706924 -223.086422)
		(width 0.0889)
		(layer "B.Cu")
		(net "VSENSE_PVCCD_HV_CPU0_DP")
	)
	(arc
		(start 360.145584 -222.761556)
		(mid 359.979066 -222.360948)
		(end 359.57764 -222.196406)
		(width 0.0889)
		(layer "B.Cu")
		(net "VSENSE_PVCCD_HV_CPU0_DP")
	)
	(arc
		(start 377.626626 -214.261954)
		(mid 377.735773 -214.345882)
		(end 377.810776 -214.461344)
		(width 0.0889)
		(layer "B.Cu")
		(net "VSENSE_PVCCD_HV_CPU0_DP")
	)
	(arc
		(start 372.549928 -223.086168)
		(mid 372.267197 -223.010519)
		(end 371.984524 -223.086422)
		(width 0.0889)
		(layer "B.Cu")
		(net "VSENSE_PVCCD_HV_CPU0_DP")
	)
	(arc
		(start 375.369582 -219.830396)
		(mid 374.60162 -220.03068)
		(end 374.791224 -220.801438)
		(width 0.0889)
		(layer "B.Cu")
		(net "VSENSE_PVCCD_HV_CPU0_DP")
	)
	(arc
		(start 364.457742 -223.091248)
		(mid 364.274204 -223.13634)
		(end 364.091982 -223.086168)
		(width 0.0889)
		(layer "B.Cu")
		(net "VSENSE_PVCCD_HV_CPU0_DP")
	)
	(arc
		(start 371.036342 -223.091248)
		(mid 370.85266 -223.136463)
		(end 370.670328 -223.086168)
		(width 0.0889)
		(layer "B.Cu")
		(net "VSENSE_PVCCD_HV_CPU0_DP")
	)
	(arc
		(start 365.397542 -223.091248)
		(mid 365.21386 -223.136463)
		(end 365.031528 -223.086168)
		(width 0.0889)
		(layer "B.Cu")
		(net "VSENSE_PVCCD_HV_CPU0_DP")
	)
	(arc
		(start 376.675142 -219.835476)
		(mid 376.49146 -219.880721)
		(end 376.309128 -219.830396)
		(width 0.0889)
		(layer "B.Cu")
		(net "VSENSE_PVCCD_HV_CPU0_DP")
	)
	(arc
		(start 377.811284 -217.878406)
		(mid 377.883905 -218.155871)
		(end 378.083318 -218.362022)
		(width 0.0889)
		(layer "B.Cu")
		(net "VSENSE_PVCCD_HV_CPU0_DP")
	)
	(arc
		(start 377.719844 -219.016834)
		(mid 377.154288 -219.016335)
		(end 376.871484 -219.506038)
		(width 0.0889)
		(layer "B.Cu")
		(net "VSENSE_PVCCD_HV_CPU0_DP")
	)
	(arc
		(start 371.610382 -223.086168)
		(mid 371.327651 -223.010519)
		(end 371.044978 -223.086422)
		(width 0.0889)
		(layer "B.Cu")
		(net "VSENSE_PVCCD_HV_CPU0_DP")
	)
	(arc
		(start 377.341384 -213.930484)
		(mid 377.452663 -214.12319)
		(end 377.626626 -214.261954)
		(width 0.0889)
		(layer "B.Cu")
		(net "VSENSE_PVCCD_HV_CPU0_DP")
	)
	(arc
		(start 375.735088 -219.835476)
		(mid 375.55166 -219.8806)
		(end 375.369582 -219.830396)
		(width 0.0889)
		(layer "B.Cu")
		(net "VSENSE_PVCCD_HV_CPU0_DP")
	)
	(arc
		(start 377.341384 -217.075004)
		(mid 377.419698 -217.351494)
		(end 377.623832 -217.553794)
		(width 0.0889)
		(layer "B.Cu")
		(net "VSENSE_PVCCD_HV_CPU0_DP")
	)
	(arc
		(start 373.112284 -222.776542)
		(mid 372.91847 -223.090015)
		(end 372.549928 -223.086168)
		(width 0.0889)
		(layer "B.Cu")
		(net "VSENSE_PVCCD_HV_CPU0_DP")
	)
	(arc
		(start 377.623324 -214.946992)
		(mid 377.422042 -215.144479)
		(end 377.34113 -215.414606)
		(width 0.0889)
		(layer "B.Cu")
		(net "VSENSE_PVCCD_HV_CPU0_DP")
	)
	(segment
		(start 398.67078 -148.987256)
		(end 398.67078 -156.155136)
		(width 0.254)
		(layer "In4.Cu")
		(net "VSENSE_PVCCD_HV_CPU0_DP")
	)
	(segment
		(start 431.858674 -129.294128)
		(end 430.981866 -129.657348)
		(width 0.254)
		(layer "In4.Cu")
		(net "VSENSE_PVCCD_HV_CPU0_DP")
	)
	(segment
		(start 418.330888 -129.327148)
		(end 398.67078 -148.987256)
		(width 0.254)
		(layer "In4.Cu")
		(net "VSENSE_PVCCD_HV_CPU0_DP")
	)
	(segment
		(start 398.67078 -156.155136)
		(end 396.30096 -158.524956)
		(width 0.254)
		(layer "In4.Cu")
		(net "VSENSE_PVCCD_HV_CPU0_DP")
	)
	(segment
		(start 430.403 -129.657348)
		(end 430.0728 -129.327148)
		(width 0.254)
		(layer "In4.Cu")
		(net "VSENSE_PVCCD_HV_CPU0_DP")
	)
	(segment
		(start 395.43736 -166.852346)
		(end 395.775434 -166.852346)
		(width 0.254)
		(layer "In4.Cu")
		(net "VSENSE_PVCCD_HV_CPU0_DP")
	)
	(segment
		(start 396.30096 -162.847528)
		(end 395.18336 -163.965128)
		(width 0.254)
		(layer "In4.Cu")
		(net "VSENSE_PVCCD_HV_CPU0_DP")
	)
	(segment
		(start 430.981866 -129.657348)
		(end 430.403 -129.657348)
		(width 0.254)
		(layer "In4.Cu")
		(net "VSENSE_PVCCD_HV_CPU0_DP")
	)
	(segment
		(start 432.981354 -128.440688)
		(end 432.521614 -128.631188)
		(width 0.254)
		(layer "In4.Cu")
		(net "VSENSE_PVCCD_HV_CPU0_DP")
	)
	(segment
		(start 433.718208 -128.709674)
		(end 433.449222 -128.440688)
		(width 0.254)
		(layer "In4.Cu")
		(net "VSENSE_PVCCD_HV_CPU0_DP")
	)
	(segment
		(start 433.449222 -128.440688)
		(end 432.981354 -128.440688)
		(width 0.254)
		(layer "In4.Cu")
		(net "VSENSE_PVCCD_HV_CPU0_DP")
	)
	(segment
		(start 396.30096 -158.524956)
		(end 396.30096 -162.847528)
		(width 0.254)
		(layer "In4.Cu")
		(net "VSENSE_PVCCD_HV_CPU0_DP")
	)
	(segment
		(start 432.521614 -128.631188)
		(end 431.858674 -129.294128)
		(width 0.254)
		(layer "In4.Cu")
		(net "VSENSE_PVCCD_HV_CPU0_DP")
	)
	(segment
		(start 395.775434 -166.852346)
		(end 396.075916 -166.551864)
		(width 0.254)
		(layer "In4.Cu")
		(net "VSENSE_PVCCD_HV_CPU0_DP")
	)
	(segment
		(start 395.18336 -163.965128)
		(end 395.18336 -166.598346)
		(width 0.254)
		(layer "In4.Cu")
		(net "VSENSE_PVCCD_HV_CPU0_DP")
	)
	(segment
		(start 430.0728 -129.327148)
		(end 418.330888 -129.327148)
		(width 0.254)
		(layer "In4.Cu")
		(net "VSENSE_PVCCD_HV_CPU0_DP")
	)
	(segment
		(start 395.18336 -166.598346)
		(end 395.43736 -166.852346)
		(width 0.254)
		(layer "In4.Cu")
		(net "VSENSE_PVCCD_HV_CPU0_DP")
	)
	(segment
		(start 392.914378 -186.46013)
		(end 395.825218 -183.54929)
		(width 0.254)
		(layer "F.Cu")
		(net "VSENSE_PVCCD_HV_CPU0_DN")
	)
	(segment
		(start 357.230934 -221.947994)
		(end 357.23068 -221.94774)
		(width 0.12954)
		(layer "F.Cu")
		(net "VSENSE_PVCCD_HV_CPU0_DN")
	)
	(segment
		(start 434.46827 -126.829566)
		(end 433.901088 -126.262384)
		(width 0.1778)
		(layer "F.Cu")
		(net "VSENSE_PVCCD_HV_CPU0_DN")
	)
	(segment
		(start 382.133856 -203.304394)
		(end 382.660398 -203.304394)
		(width 0.254)
		(layer "F.Cu")
		(net "VSENSE_PVCCD_HV_CPU0_DN")
	)
	(segment
		(start 395.083792 -167.555672)
		(end 395.4653 -167.174164)
		(width 0.254)
		(layer "F.Cu")
		(net "VSENSE_PVCCD_HV_CPU0_DN")
	)
	(segment
		(start 395.825218 -183.54929)
		(end 395.825218 -171.138088)
		(width 0.254)
		(layer "F.Cu")
		(net "VSENSE_PVCCD_HV_CPU0_DN")
	)
	(segment
		(start 434.491384 -126.873762)
		(end 434.46827 -126.850648)
		(width 0.254)
		(layer "F.Cu")
		(net "VSENSE_PVCCD_HV_CPU0_DN")
	)
	(segment
		(start 383.254758 -202.710034)
		(end 383.254758 -200.704958)
		(width 0.254)
		(layer "F.Cu")
		(net "VSENSE_PVCCD_HV_CPU0_DN")
	)
	(segment
		(start 395.083792 -170.396662)
		(end 395.083792 -167.555672)
		(width 0.254)
		(layer "F.Cu")
		(net "VSENSE_PVCCD_HV_CPU0_DN")
	)
	(segment
		(start 433.718208 -127.846074)
		(end 433.959508 -128.087374)
		(width 0.254)
		(layer "F.Cu")
		(net "VSENSE_PVCCD_HV_CPU0_DN")
	)
	(segment
		(start 381.892556 -203.545694)
		(end 382.133856 -203.304394)
		(width 0.254)
		(layer "F.Cu")
		(net "VSENSE_PVCCD_HV_CPU0_DN")
	)
	(segment
		(start 396.317216 -167.174164)
		(end 396.075916 -167.415464)
		(width 0.254)
		(layer "F.Cu")
		(net "VSENSE_PVCCD_HV_CPU0_DN")
	)
	(segment
		(start 434.64988 -127.868172)
		(end 434.64988 -127.51308)
		(width 0.254)
		(layer "F.Cu")
		(net "VSENSE_PVCCD_HV_CPU0_DN")
	)
	(segment
		(start 383.254758 -200.704958)
		(end 385.185666 -198.77405)
		(width 0.254)
		(layer "F.Cu")
		(net "VSENSE_PVCCD_HV_CPU0_DN")
	)
	(segment
		(start 397.003016 -167.491664)
		(end 396.685516 -167.174164)
		(width 0.254)
		(layer "F.Cu")
		(net "VSENSE_PVCCD_HV_CPU0_DN")
	)
	(segment
		(start 395.834616 -167.174164)
		(end 396.075916 -167.415464)
		(width 0.254)
		(layer "F.Cu")
		(net "VSENSE_PVCCD_HV_CPU0_DN")
	)
	(segment
		(start 433.901088 -126.262384)
		(end 433.901088 -125.388624)
		(width 0.1778)
		(layer "F.Cu")
		(net "VSENSE_PVCCD_HV_CPU0_DN")
	)
	(segment
		(start 385.185666 -198.77405)
		(end 387.354318 -198.77405)
		(width 0.254)
		(layer "F.Cu")
		(net "VSENSE_PVCCD_HV_CPU0_DN")
	)
	(segment
		(start 395.825218 -171.138088)
		(end 395.083792 -170.396662)
		(width 0.254)
		(layer "F.Cu")
		(net "VSENSE_PVCCD_HV_CPU0_DN")
	)
	(segment
		(start 382.660398 -203.304394)
		(end 383.254758 -202.710034)
		(width 0.254)
		(layer "F.Cu")
		(net "VSENSE_PVCCD_HV_CPU0_DN")
	)
	(segment
		(start 396.685516 -167.174164)
		(end 396.317216 -167.174164)
		(width 0.254)
		(layer "F.Cu")
		(net "VSENSE_PVCCD_HV_CPU0_DN")
	)
	(segment
		(start 434.430678 -128.087374)
		(end 434.64988 -127.868172)
		(width 0.254)
		(layer "F.Cu")
		(net "VSENSE_PVCCD_HV_CPU0_DN")
	)
	(segment
		(start 433.959508 -128.087374)
		(end 434.430678 -128.087374)
		(width 0.254)
		(layer "F.Cu")
		(net "VSENSE_PVCCD_HV_CPU0_DN")
	)
	(segment
		(start 434.46827 -126.850648)
		(end 434.46827 -126.829566)
		(width 0.1778)
		(layer "F.Cu")
		(net "VSENSE_PVCCD_HV_CPU0_DN")
	)
	(segment
		(start 434.491384 -127.354584)
		(end 434.491384 -126.873762)
		(width 0.254)
		(layer "F.Cu")
		(net "VSENSE_PVCCD_HV_CPU0_DN")
	)
	(segment
		(start 357.230934 -222.48368)
		(end 357.230934 -221.947994)
		(width 0.12954)
		(layer "F.Cu")
		(net "VSENSE_PVCCD_HV_CPU0_DN")
	)
	(segment
		(start 387.354318 -198.77405)
		(end 392.914378 -193.21399)
		(width 0.254)
		(layer "F.Cu")
		(net "VSENSE_PVCCD_HV_CPU0_DN")
	)
	(segment
		(start 392.914378 -193.21399)
		(end 392.914378 -186.46013)
		(width 0.254)
		(layer "F.Cu")
		(net "VSENSE_PVCCD_HV_CPU0_DN")
	)
	(segment
		(start 434.64988 -127.51308)
		(end 434.491384 -127.354584)
		(width 0.254)
		(layer "F.Cu")
		(net "VSENSE_PVCCD_HV_CPU0_DN")
	)
	(segment
		(start 395.4653 -167.174164)
		(end 395.834616 -167.174164)
		(width 0.254)
		(layer "F.Cu")
		(net "VSENSE_PVCCD_HV_CPU0_DN")
	)
	(via
		(at 396.075916 -167.415464)
		(size 0.508)
		(drill 0.254)
		(layers "F.Cu" "B.Cu")
		(net "VSENSE_PVCCD_HV_CPU0_DN")
	)
	(via
		(at 357.23068 -221.94774)
		(size 0.4572)
		(drill 0.2032)
		(layers "F.Cu" "B.Cu")
		(net "VSENSE_PVCCD_HV_CPU0_DN")
	)
	(via
		(at 433.718208 -127.846074)
		(size 0.508)
		(drill 0.254)
		(layers "F.Cu" "B.Cu")
		(net "VSENSE_PVCCD_HV_CPU0_DN")
	)
	(via
		(at 381.892556 -203.545694)
		(size 0.508)
		(drill 0.254)
		(layers "F.Cu" "B.Cu")
		(net "VSENSE_PVCCD_HV_CPU0_DN")
	)
	(segment
		(start 367.381536 -223.251268)
		(end 367.371122 -223.257364)
		(width 0.0889)
		(layer "B.Cu")
		(net "VSENSE_PVCCD_HV_CPU0_DN")
	)
	(segment
		(start 359.955084 -222.780098)
		(end 359.955084 -222.761556)
		(width 0.0889)
		(layer "B.Cu")
		(net "VSENSE_PVCCD_HV_CPU0_DN")
	)
	(segment
		(start 377.240546 -216.569798)
		(end 377.249436 -216.574878)
		(width 0.0889)
		(layer "B.Cu")
		(net "VSENSE_PVCCD_HV_CPU0_DN")
	)
	(segment
		(start 373.490236 -222.437198)
		(end 373.481346 -222.442278)
		(width 0.0889)
		(layer "B.Cu")
		(net "VSENSE_PVCCD_HV_CPU0_DN")
	)
	(segment
		(start 365.501936 -223.251268)
		(end 365.491522 -223.257364)
		(width 0.0889)
		(layer "B.Cu")
		(net "VSENSE_PVCCD_HV_CPU0_DN")
	)
	(segment
		(start 372.080282 -223.251268)
		(end 372.069868 -223.257364)
		(width 0.0889)
		(layer "B.Cu")
		(net "VSENSE_PVCCD_HV_CPU0_DN")
	)
	(segment
		(start 373.302784 -222.761556)
		(end 373.302784 -222.780098)
		(width 0.0889)
		(layer "B.Cu")
		(net "VSENSE_PVCCD_HV_CPU0_DN")
	)
	(segment
		(start 377.531884 -215.421972)
		(end 377.531884 -215.42756)
		(width 0.0889)
		(layer "B.Cu")
		(net "VSENSE_PVCCD_HV_CPU0_DN")
	)
	(segment
		(start 369.261136 -223.251268)
		(end 369.250722 -223.257364)
		(width 0.0889)
		(layer "B.Cu")
		(net "VSENSE_PVCCD_HV_CPU0_DN")
	)
	(segment
		(start 377.719082 -215.112346)
		(end 377.710192 -215.117426)
		(width 0.0889)
		(layer "B.Cu")
		(net "VSENSE_PVCCD_HV_CPU0_DN")
	)
	(segment
		(start 374.899174 -220.643704)
		(end 374.899936 -220.644212)
		(width 0.0889)
		(layer "B.Cu")
		(net "VSENSE_PVCCD_HV_CPU0_DN")
	)
	(segment
		(start 374.899174 -219.996004)
		(end 374.891046 -220.000576)
		(width 0.0889)
		(layer "B.Cu")
		(net "VSENSE_PVCCD_HV_CPU0_DN")
	)
	(segment
		(start 364.561882 -223.251268)
		(end 364.551468 -223.257364)
		(width 0.0889)
		(layer "B.Cu")
		(net "VSENSE_PVCCD_HV_CPU0_DN")
	)
	(segment
		(start 375.839482 -219.995496)
		(end 375.829068 -220.001592)
		(width 0.0889)
		(layer "B.Cu")
		(net "VSENSE_PVCCD_HV_CPU0_DN")
	)
	(segment
		(start 377.531884 -213.127844)
		(end 377.531884 -213.893908)
		(width 0.0889)
		(layer "B.Cu")
		(net "VSENSE_PVCCD_HV_CPU0_DN")
	)
	(segment
		(start 370.200682 -223.251268)
		(end 370.190268 -223.257364)
		(width 0.0889)
		(layer "B.Cu")
		(net "VSENSE_PVCCD_HV_CPU0_DN")
	)
	(segment
		(start 360.802682 -223.251268)
		(end 360.792268 -223.257364)
		(width 0.0889)
		(layer "B.Cu")
		(net "VSENSE_PVCCD_HV_CPU0_DN")
	)
	(segment
		(start 378.47143 -218.676728)
		(end 378.47143 -218.707716)
		(width 0.0889)
		(layer "B.Cu")
		(net "VSENSE_PVCCD_HV_CPU0_DN")
	)
	(segment
		(start 378.001276 -214.424768)
		(end 378.001276 -214.644732)
		(width 0.0889)
		(layer "B.Cu")
		(net "VSENSE_PVCCD_HV_CPU0_DN")
	)
	(segment
		(start 376.779536 -219.995496)
		(end 376.769122 -220.001592)
		(width 0.0889)
		(layer "B.Cu")
		(net "VSENSE_PVCCD_HV_CPU0_DN")
	)
	(segment
		(start 377.627134 -206.335122)
		(end 377.627134 -212.87105)
		(width 0.254)
		(layer "B.Cu")
		(net "VSENSE_PVCCD_HV_CPU0_DN")
	)
	(segment
		(start 368.321082 -223.251268)
		(end 368.310668 -223.257364)
		(width 0.0889)
		(layer "B.Cu")
		(net "VSENSE_PVCCD_HV_CPU0_DN")
	)
	(segment
		(start 377.627134 -212.87105)
		(end 377.627134 -213.032594)
		(width 0.0889)
		(layer "B.Cu")
		(net "VSENSE_PVCCD_HV_CPU0_DN")
	)
	(segment
		(start 380.657862 -203.304394)
		(end 377.627134 -206.335122)
		(width 0.254)
		(layer "B.Cu")
		(net "VSENSE_PVCCD_HV_CPU0_DN")
	)
	(segment
		(start 366.441482 -223.251268)
		(end 366.431068 -223.257364)
		(width 0.0889)
		(layer "B.Cu")
		(net "VSENSE_PVCCD_HV_CPU0_DN")
	)
	(segment
		(start 361.742736 -223.251268)
		(end 361.732322 -223.257364)
		(width 0.0889)
		(layer "B.Cu")
		(net "VSENSE_PVCCD_HV_CPU0_DN")
	)
	(segment
		(start 377.531884 -217.05443)
		(end 377.531884 -217.072972)
		(width 0.0889)
		(layer "B.Cu")
		(net "VSENSE_PVCCD_HV_CPU0_DN")
	)
	(segment
		(start 378.001784 -217.864182)
		(end 378.001784 -217.878406)
		(width 0.0889)
		(layer "B.Cu")
		(net "VSENSE_PVCCD_HV_CPU0_DN")
	)
	(segment
		(start 377.249436 -219.18168)
		(end 377.240546 -219.18676)
		(width 0.0889)
		(layer "B.Cu")
		(net "VSENSE_PVCCD_HV_CPU0_DN")
	)
	(segment
		(start 357.543354 -221.94774)
		(end 357.23068 -221.94774)
		(width 0.0889)
		(layer "B.Cu")
		(net "VSENSE_PVCCD_HV_CPU0_DN")
	)
	(segment
		(start 377.638564 -219.190316)
		(end 377.623832 -219.18168)
		(width 0.0889)
		(layer "B.Cu")
		(net "VSENSE_PVCCD_HV_CPU0_DN")
	)
	(segment
		(start 377.249436 -215.926162)
		(end 377.240546 -215.931242)
		(width 0.0889)
		(layer "B.Cu")
		(net "VSENSE_PVCCD_HV_CPU0_DN")
	)
	(segment
		(start 377.627134 -213.032594)
		(end 377.531884 -213.127844)
		(width 0.0889)
		(layer "B.Cu")
		(net "VSENSE_PVCCD_HV_CPU0_DN")
	)
	(segment
		(start 381.651256 -203.304394)
		(end 380.657862 -203.304394)
		(width 0.254)
		(layer "B.Cu")
		(net "VSENSE_PVCCD_HV_CPU0_DN")
	)
	(segment
		(start 377.061984 -219.506038)
		(end 377.061984 -219.515944)
		(width 0.0889)
		(layer "B.Cu")
		(net "VSENSE_PVCCD_HV_CPU0_DN")
	)
	(segment
		(start 357.60914 -222.013526)
		(end 357.543354 -221.94774)
		(width 0.0889)
		(layer "B.Cu")
		(net "VSENSE_PVCCD_HV_CPU0_DN")
	)
	(segment
		(start 374.899936 -219.995496)
		(end 374.899174 -219.996004)
		(width 0.0889)
		(layer "B.Cu")
		(net "VSENSE_PVCCD_HV_CPU0_DN")
	)
	(segment
		(start 373.77243 -221.94774)
		(end 373.77243 -221.963234)
		(width 0.0889)
		(layer "B.Cu")
		(net "VSENSE_PVCCD_HV_CPU0_DN")
	)
	(segment
		(start 377.53163 -215.431116)
		(end 377.53163 -215.452198)
		(width 0.0889)
		(layer "B.Cu")
		(net "VSENSE_PVCCD_HV_CPU0_DN")
	)
	(segment
		(start 378.180346 -218.197684)
		(end 378.189236 -218.202764)
		(width 0.0889)
		(layer "B.Cu")
		(net "VSENSE_PVCCD_HV_CPU0_DN")
	)
	(segment
		(start 371.140736 -223.251268)
		(end 371.130322 -223.257364)
		(width 0.0889)
		(layer "B.Cu")
		(net "VSENSE_PVCCD_HV_CPU0_DN")
	)
	(segment
		(start 374.891046 -220.639132)
		(end 374.899174 -220.643704)
		(width 0.0889)
		(layer "B.Cu")
		(net "VSENSE_PVCCD_HV_CPU0_DN")
	)
	(segment
		(start 381.892556 -203.545694)
		(end 381.651256 -203.304394)
		(width 0.254)
		(layer "B.Cu")
		(net "VSENSE_PVCCD_HV_CPU0_DN")
	)
	(arc
		(start 364.936278 -223.251268)
		(mid 364.74908 -223.201125)
		(end 364.561882 -223.251268)
		(width 0.0889)
		(layer "B.Cu")
		(net "VSENSE_PVCCD_HV_CPU0_DN")
	)
	(arc
		(start 359.955084 -222.761556)
		(mid 359.767785 -222.437115)
		(end 359.393236 -222.437198)
		(width 0.0889)
		(layer "B.Cu")
		(net "VSENSE_PVCCD_HV_CPU0_DN")
	)
	(arc
		(start 369.250722 -223.257364)
		(mid 368.97229 -223.327178)
		(end 368.695478 -223.251268)
		(width 0.0889)
		(layer "B.Cu")
		(net "VSENSE_PVCCD_HV_CPU0_DN")
	)
	(arc
		(start 373.302784 -222.780098)
		(mid 373.01221 -223.25587)
		(end 372.454678 -223.251268)
		(width 0.0889)
		(layer "B.Cu")
		(net "VSENSE_PVCCD_HV_CPU0_DN")
	)
	(arc
		(start 375.829068 -220.001592)
		(mid 375.55089 -220.071315)
		(end 375.274332 -219.995496)
		(width 0.0889)
		(layer "B.Cu")
		(net "VSENSE_PVCCD_HV_CPU0_DN")
	)
	(arc
		(start 371.130322 -223.257364)
		(mid 370.85189 -223.327178)
		(end 370.575078 -223.251268)
		(width 0.0889)
		(layer "B.Cu")
		(net "VSENSE_PVCCD_HV_CPU0_DN")
	)
	(arc
		(start 371.515132 -223.251268)
		(mid 371.327934 -223.201125)
		(end 371.140736 -223.251268)
		(width 0.0889)
		(layer "B.Cu")
		(net "VSENSE_PVCCD_HV_CPU0_DN")
	)
	(arc
		(start 363.056932 -223.251268)
		(mid 362.869734 -223.201125)
		(end 362.682536 -223.251268)
		(width 0.0889)
		(layer "B.Cu")
		(net "VSENSE_PVCCD_HV_CPU0_DN")
	)
	(arc
		(start 374.899936 -220.644212)
		(mid 375.106859 -221.416776)
		(end 374.334278 -221.623382)
		(width 0.0889)
		(layer "B.Cu")
		(net "VSENSE_PVCCD_HV_CPU0_DN")
	)
	(arc
		(start 375.274332 -219.995496)
		(mid 375.087134 -219.945353)
		(end 374.899936 -219.995496)
		(width 0.0889)
		(layer "B.Cu")
		(net "VSENSE_PVCCD_HV_CPU0_DN")
	)
	(arc
		(start 370.575078 -223.251268)
		(mid 370.38788 -223.201125)
		(end 370.200682 -223.251268)
		(width 0.0889)
		(layer "B.Cu")
		(net "VSENSE_PVCCD_HV_CPU0_DN")
	)
	(arc
		(start 374.891046 -220.000576)
		(mid 374.712449 -220.319854)
		(end 374.891046 -220.639132)
		(width 0.0889)
		(layer "B.Cu")
		(net "VSENSE_PVCCD_HV_CPU0_DN")
	)
	(arc
		(start 376.769122 -220.001592)
		(mid 376.49069 -220.071438)
		(end 376.213878 -219.995496)
		(width 0.0889)
		(layer "B.Cu")
		(net "VSENSE_PVCCD_HV_CPU0_DN")
	)
	(arc
		(start 378.189236 -219.18168)
		(mid 377.915037 -219.257515)
		(end 377.638564 -219.190316)
		(width 0.0889)
		(layer "B.Cu")
		(net "VSENSE_PVCCD_HV_CPU0_DN")
	)
	(arc
		(start 377.719082 -217.388694)
		(mid 377.922563 -217.589498)
		(end 378.001784 -217.864182)
		(width 0.0889)
		(layer "B.Cu")
		(net "VSENSE_PVCCD_HV_CPU0_DN")
	)
	(arc
		(start 366.431068 -223.257364)
		(mid 366.15289 -223.327056)
		(end 365.876332 -223.251268)
		(width 0.0889)
		(layer "B.Cu")
		(net "VSENSE_PVCCD_HV_CPU0_DN")
	)
	(arc
		(start 377.716034 -214.093298)
		(mid 377.889997 -214.232062)
		(end 378.001276 -214.424768)
		(width 0.0889)
		(layer "B.Cu")
		(net "VSENSE_PVCCD_HV_CPU0_DN")
	)
	(arc
		(start 369.635532 -223.251268)
		(mid 369.448334 -223.201125)
		(end 369.261136 -223.251268)
		(width 0.0889)
		(layer "B.Cu")
		(net "VSENSE_PVCCD_HV_CPU0_DN")
	)
	(arc
		(start 370.190268 -223.257364)
		(mid 369.91209 -223.327056)
		(end 369.635532 -223.251268)
		(width 0.0889)
		(layer "B.Cu")
		(net "VSENSE_PVCCD_HV_CPU0_DN")
	)
	(arc
		(start 373.481346 -222.442278)
		(mid 373.350432 -222.578638)
		(end 373.302784 -222.761556)
		(width 0.0889)
		(layer "B.Cu")
		(net "VSENSE_PVCCD_HV_CPU0_DN")
	)
	(arc
		(start 377.240546 -219.18676)
		(mid 377.109632 -219.32312)
		(end 377.061984 -219.506038)
		(width 0.0889)
		(layer "B.Cu")
		(net "VSENSE_PVCCD_HV_CPU0_DN")
	)
	(arc
		(start 365.876332 -223.251268)
		(mid 365.689134 -223.201125)
		(end 365.501936 -223.251268)
		(width 0.0889)
		(layer "B.Cu")
		(net "VSENSE_PVCCD_HV_CPU0_DN")
	)
	(arc
		(start 377.240546 -215.931242)
		(mid 377.061949 -216.25052)
		(end 377.240546 -216.569798)
		(width 0.0889)
		(layer "B.Cu")
		(net "VSENSE_PVCCD_HV_CPU0_DN")
	)
	(arc
		(start 362.117132 -223.251268)
		(mid 361.929934 -223.201125)
		(end 361.742736 -223.251268)
		(width 0.0889)
		(layer "B.Cu")
		(net "VSENSE_PVCCD_HV_CPU0_DN")
	)
	(arc
		(start 363.622336 -223.251268)
		(mid 363.339634 -223.32701)
		(end 363.056932 -223.251268)
		(width 0.0889)
		(layer "B.Cu")
		(net "VSENSE_PVCCD_HV_CPU0_DN")
	)
	(arc
		(start 377.53163 -215.452198)
		(mid 377.45226 -215.725932)
		(end 377.249436 -215.926162)
		(width 0.0889)
		(layer "B.Cu")
		(net "VSENSE_PVCCD_HV_CPU0_DN")
	)
	(arc
		(start 376.213878 -219.995496)
		(mid 376.02668 -219.945353)
		(end 375.839482 -219.995496)
		(width 0.0889)
		(layer "B.Cu")
		(net "VSENSE_PVCCD_HV_CPU0_DN")
	)
	(arc
		(start 377.623832 -219.18168)
		(mid 377.436634 -219.131537)
		(end 377.249436 -219.18168)
		(width 0.0889)
		(layer "B.Cu")
		(net "VSENSE_PVCCD_HV_CPU0_DN")
	)
	(arc
		(start 378.189236 -218.202764)
		(mid 378.392059 -218.402995)
		(end 378.47143 -218.676728)
		(width 0.0889)
		(layer "B.Cu")
		(net "VSENSE_PVCCD_HV_CPU0_DN")
	)
	(arc
		(start 377.531884 -213.893908)
		(mid 377.606889 -214.009367)
		(end 377.716034 -214.093298)
		(width 0.0889)
		(layer "B.Cu")
		(net "VSENSE_PVCCD_HV_CPU0_DN")
	)
	(arc
		(start 378.47143 -218.707716)
		(mid 378.39206 -218.98145)
		(end 378.189236 -219.18168)
		(width 0.0889)
		(layer "B.Cu")
		(net "VSENSE_PVCCD_HV_CPU0_DN")
	)
	(arc
		(start 377.061984 -219.515944)
		(mid 376.983873 -219.792893)
		(end 376.779536 -219.995496)
		(width 0.0889)
		(layer "B.Cu")
		(net "VSENSE_PVCCD_HV_CPU0_DN")
	)
	(arc
		(start 365.491522 -223.257364)
		(mid 365.21309 -223.327178)
		(end 364.936278 -223.251268)
		(width 0.0889)
		(layer "B.Cu")
		(net "VSENSE_PVCCD_HV_CPU0_DN")
	)
	(arc
		(start 377.531884 -215.42756)
		(mid 377.531741 -215.429337)
		(end 377.53163 -215.431116)
		(width 0.0889)
		(layer "B.Cu")
		(net "VSENSE_PVCCD_HV_CPU0_DN")
	)
	(arc
		(start 367.371122 -223.257364)
		(mid 367.09269 -223.327178)
		(end 366.815878 -223.251268)
		(width 0.0889)
		(layer "B.Cu")
		(net "VSENSE_PVCCD_HV_CPU0_DN")
	)
	(arc
		(start 378.001276 -214.644732)
		(mid 377.920365 -214.91486)
		(end 377.719082 -215.112346)
		(width 0.0889)
		(layer "B.Cu")
		(net "VSENSE_PVCCD_HV_CPU0_DN")
	)
	(arc
		(start 377.710192 -215.117426)
		(mid 377.582938 -215.247392)
		(end 377.531884 -215.421972)
		(width 0.0889)
		(layer "B.Cu")
		(net "VSENSE_PVCCD_HV_CPU0_DN")
	)
	(arc
		(start 359.393236 -222.437198)
		(mid 359.110534 -222.512974)
		(end 358.827832 -222.437198)
		(width 0.0889)
		(layer "B.Cu")
		(net "VSENSE_PVCCD_HV_CPU0_DN")
	)
	(arc
		(start 358.827832 -222.437198)
		(mid 358.640634 -222.387055)
		(end 358.453436 -222.437198)
		(width 0.0889)
		(layer "B.Cu")
		(net "VSENSE_PVCCD_HV_CPU0_DN")
	)
	(arc
		(start 363.996732 -223.251268)
		(mid 363.809534 -223.201125)
		(end 363.622336 -223.251268)
		(width 0.0889)
		(layer "B.Cu")
		(net "VSENSE_PVCCD_HV_CPU0_DN")
	)
	(arc
		(start 374.334278 -221.623382)
		(mid 373.959803 -221.623428)
		(end 373.77243 -221.94774)
		(width 0.0889)
		(layer "B.Cu")
		(net "VSENSE_PVCCD_HV_CPU0_DN")
	)
	(arc
		(start 368.310668 -223.257364)
		(mid 368.03249 -223.327056)
		(end 367.755932 -223.251268)
		(width 0.0889)
		(layer "B.Cu")
		(net "VSENSE_PVCCD_HV_CPU0_DN")
	)
	(arc
		(start 373.77243 -221.963234)
		(mid 373.69306 -222.236968)
		(end 373.490236 -222.437198)
		(width 0.0889)
		(layer "B.Cu")
		(net "VSENSE_PVCCD_HV_CPU0_DN")
	)
	(arc
		(start 368.695478 -223.251268)
		(mid 368.50828 -223.201125)
		(end 368.321082 -223.251268)
		(width 0.0889)
		(layer "B.Cu")
		(net "VSENSE_PVCCD_HV_CPU0_DN")
	)
	(arc
		(start 377.249436 -216.574878)
		(mid 377.453771 -216.777483)
		(end 377.531884 -217.05443)
		(width 0.0889)
		(layer "B.Cu")
		(net "VSENSE_PVCCD_HV_CPU0_DN")
	)
	(arc
		(start 378.001784 -217.878406)
		(mid 378.049463 -218.061306)
		(end 378.180346 -218.197684)
		(width 0.0889)
		(layer "B.Cu")
		(net "VSENSE_PVCCD_HV_CPU0_DN")
	)
	(arc
		(start 367.755932 -223.251268)
		(mid 367.568734 -223.201125)
		(end 367.381536 -223.251268)
		(width 0.0889)
		(layer "B.Cu")
		(net "VSENSE_PVCCD_HV_CPU0_DN")
	)
	(arc
		(start 366.815878 -223.251268)
		(mid 366.62868 -223.201125)
		(end 366.441482 -223.251268)
		(width 0.0889)
		(layer "B.Cu")
		(net "VSENSE_PVCCD_HV_CPU0_DN")
	)
	(arc
		(start 377.531884 -217.072972)
		(mid 377.584154 -217.255337)
		(end 377.719082 -217.388694)
		(width 0.0889)
		(layer "B.Cu")
		(net "VSENSE_PVCCD_HV_CPU0_DN")
	)
	(arc
		(start 360.792268 -223.257364)
		(mid 360.24017 -223.252873)
		(end 359.955084 -222.780098)
		(width 0.0889)
		(layer "B.Cu")
		(net "VSENSE_PVCCD_HV_CPU0_DN")
	)
	(arc
		(start 358.453436 -222.437198)
		(mid 357.917123 -222.452877)
		(end 357.60914 -222.013526)
		(width 0.0889)
		(layer "B.Cu")
		(net "VSENSE_PVCCD_HV_CPU0_DN")
	)
	(arc
		(start 364.551468 -223.257364)
		(mid 364.27329 -223.327056)
		(end 363.996732 -223.251268)
		(width 0.0889)
		(layer "B.Cu")
		(net "VSENSE_PVCCD_HV_CPU0_DN")
	)
	(arc
		(start 372.454678 -223.251268)
		(mid 372.26748 -223.201125)
		(end 372.080282 -223.251268)
		(width 0.0889)
		(layer "B.Cu")
		(net "VSENSE_PVCCD_HV_CPU0_DN")
	)
	(arc
		(start 362.682536 -223.251268)
		(mid 362.399834 -223.32701)
		(end 362.117132 -223.251268)
		(width 0.0889)
		(layer "B.Cu")
		(net "VSENSE_PVCCD_HV_CPU0_DN")
	)
	(arc
		(start 361.177078 -223.251268)
		(mid 360.98988 -223.201125)
		(end 360.802682 -223.251268)
		(width 0.0889)
		(layer "B.Cu")
		(net "VSENSE_PVCCD_HV_CPU0_DN")
	)
	(arc
		(start 372.069868 -223.257364)
		(mid 371.79169 -223.327056)
		(end 371.515132 -223.251268)
		(width 0.0889)
		(layer "B.Cu")
		(net "VSENSE_PVCCD_HV_CPU0_DN")
	)
	(arc
		(start 361.732322 -223.257364)
		(mid 361.45389 -223.327178)
		(end 361.177078 -223.251268)
		(width 0.0889)
		(layer "B.Cu")
		(net "VSENSE_PVCCD_HV_CPU0_DN")
	)
	(segment
		(start 430.560988 -129.276348)
		(end 430.230788 -128.946148)
		(width 0.254)
		(layer "In4.Cu")
		(net "VSENSE_PVCCD_HV_CPU0_DN")
	)
	(segment
		(start 433.504594 -128.059688)
		(end 432.905408 -128.059688)
		(width 0.254)
		(layer "In4.Cu")
		(net "VSENSE_PVCCD_HV_CPU0_DN")
	)
	(segment
		(start 432.305714 -128.3081)
		(end 431.642774 -128.97104)
		(width 0.254)
		(layer "In4.Cu")
		(net "VSENSE_PVCCD_HV_CPU0_DN")
	)
	(segment
		(start 431.642774 -128.97104)
		(end 430.90592 -129.276348)
		(width 0.254)
		(layer "In4.Cu")
		(net "VSENSE_PVCCD_HV_CPU0_DN")
	)
	(segment
		(start 398.28978 -148.829268)
		(end 398.28978 -155.997148)
		(width 0.254)
		(layer "In4.Cu")
		(net "VSENSE_PVCCD_HV_CPU0_DN")
	)
	(segment
		(start 395.279372 -167.233346)
		(end 395.893798 -167.233346)
		(width 0.254)
		(layer "In4.Cu")
		(net "VSENSE_PVCCD_HV_CPU0_DN")
	)
	(segment
		(start 398.28978 -155.997148)
		(end 395.91996 -158.366968)
		(width 0.254)
		(layer "In4.Cu")
		(net "VSENSE_PVCCD_HV_CPU0_DN")
	)
	(segment
		(start 395.91996 -162.68954)
		(end 394.80236 -163.80714)
		(width 0.254)
		(layer "In4.Cu")
		(net "VSENSE_PVCCD_HV_CPU0_DN")
	)
	(segment
		(start 394.80236 -166.756334)
		(end 395.279372 -167.233346)
		(width 0.254)
		(layer "In4.Cu")
		(net "VSENSE_PVCCD_HV_CPU0_DN")
	)
	(segment
		(start 430.90592 -129.276348)
		(end 430.560988 -129.276348)
		(width 0.254)
		(layer "In4.Cu")
		(net "VSENSE_PVCCD_HV_CPU0_DN")
	)
	(segment
		(start 433.718208 -127.846074)
		(end 433.504594 -128.059688)
		(width 0.254)
		(layer "In4.Cu")
		(net "VSENSE_PVCCD_HV_CPU0_DN")
	)
	(segment
		(start 394.80236 -163.80714)
		(end 394.80236 -166.756334)
		(width 0.254)
		(layer "In4.Cu")
		(net "VSENSE_PVCCD_HV_CPU0_DN")
	)
	(segment
		(start 432.905408 -128.059688)
		(end 432.305714 -128.3081)
		(width 0.254)
		(layer "In4.Cu")
		(net "VSENSE_PVCCD_HV_CPU0_DN")
	)
	(segment
		(start 418.1729 -128.946148)
		(end 398.28978 -148.829268)
		(width 0.254)
		(layer "In4.Cu")
		(net "VSENSE_PVCCD_HV_CPU0_DN")
	)
	(segment
		(start 395.893798 -167.233346)
		(end 396.075916 -167.415464)
		(width 0.254)
		(layer "In4.Cu")
		(net "VSENSE_PVCCD_HV_CPU0_DN")
	)
	(segment
		(start 395.91996 -158.366968)
		(end 395.91996 -162.68954)
		(width 0.254)
		(layer "In4.Cu")
		(net "VSENSE_PVCCD_HV_CPU0_DN")
	)
	(segment
		(start 430.230788 -128.946148)
		(end 418.1729 -128.946148)
		(width 0.254)
		(layer "In4.Cu")
		(net "VSENSE_PVCCD_HV_CPU0_DN")
	)
	(segment
		(start 166.196772 -128.539494)
		(end 165.660578 -129.075688)
		(width 0.12954)
		(layer "F.Cu")
		(net "VR_P5V_EN_N")
	)
	(segment
		(start 166.196772 -127.655828)
		(end 166.196772 -128.086358)
		(width 0.12954)
		(layer "F.Cu")
		(net "VR_P5V_EN_N")
	)
	(segment
		(start 167.6146 -127.82296)
		(end 167.351202 -128.086358)
		(width 0.12954)
		(layer "F.Cu")
		(net "VR_P5V_EN_N")
	)
	(segment
		(start 165.210998 -124.78004)
		(end 166.3954 -124.78004)
		(width 0.12954)
		(layer "F.Cu")
		(net "VR_P5V_EN_N")
	)
	(segment
		(start 167.351202 -128.086358)
		(end 166.846758 -128.086358)
		(width 0.12954)
		(layer "F.Cu")
		(net "VR_P5V_EN_N")
	)
	(segment
		(start 163.661598 -130.126486)
		(end 164.29101 -130.126486)
		(width 0.12954)
		(layer "F.Cu")
		(net "VR_P5V_EN_N")
	)
	(segment
		(start 167.6146 -125.99924)
		(end 167.6146 -127.82296)
		(width 0.12954)
		(layer "F.Cu")
		(net "VR_P5V_EN_N")
	)
	(segment
		(start 163.21532 -129.075688)
		(end 163.21532 -129.680208)
		(width 0.12954)
		(layer "F.Cu")
		(net "VR_P5V_EN_N")
	)
	(segment
		(start 163.21532 -129.680208)
		(end 163.661598 -130.126486)
		(width 0.12954)
		(layer "F.Cu")
		(net "VR_P5V_EN_N")
	)
	(segment
		(start 166.3065 -127.5461)
		(end 166.196772 -127.655828)
		(width 0.12954)
		(layer "F.Cu")
		(net "VR_P5V_EN_N")
	)
	(segment
		(start 165.660578 -129.075688)
		(end 163.21532 -129.075688)
		(width 0.12954)
		(layer "F.Cu")
		(net "VR_P5V_EN_N")
	)
	(segment
		(start 166.3954 -124.78004)
		(end 167.6146 -125.99924)
		(width 0.12954)
		(layer "F.Cu")
		(net "VR_P5V_EN_N")
	)
	(segment
		(start 166.846758 -128.086358)
		(end 166.846758 -127.695198)
		(width 0.12954)
		(layer "F.Cu")
		(net "VR_P5V_EN_N")
	)
	(segment
		(start 166.846758 -127.695198)
		(end 166.69766 -127.5461)
		(width 0.12954)
		(layer "F.Cu")
		(net "VR_P5V_EN_N")
	)
	(segment
		(start 166.196772 -128.086358)
		(end 166.196772 -128.539494)
		(width 0.12954)
		(layer "F.Cu")
		(net "VR_P5V_EN_N")
	)
	(segment
		(start 166.69766 -127.5461)
		(end 166.3065 -127.5461)
		(width 0.12954)
		(layer "F.Cu")
		(net "VR_P5V_EN_N")
	)
	(via
		(at 163.21532 -129.075688)
		(size 0.508)
		(drill 0.254)
		(layers "F.Cu" "B.Cu")
		(net "VR_P5V_EN_N")
	)
	(segment
		(start 165.546786 -129.986278)
		(end 165.546786 -130.574796)
		(width 0.12954)
		(layer "F.Cu")
		(net "VR_P5V_EN_D_R1")
	)
	(segment
		(start 165.546786 -130.574796)
		(end 165.301676 -130.819906)
		(width 0.12954)
		(layer "F.Cu")
		(net "VR_P5V_EN_D_R1")
	)
	(segment
		(start 165.301676 -130.819906)
		(end 165.301676 -131.580128)
		(width 0.12954)
		(layer "F.Cu")
		(net "VR_P5V_EN_D_R1")
	)
	(via
		(at 165.301676 -130.819906)
		(size 0.508)
		(drill 0.254)
		(layers "F.Cu" "B.Cu")
		(net "VR_P5V_EN_D_R1")
	)
	(segment
		(start 167.94988 -133.822948)
		(end 167.625268 -133.822948)
		(width 0.12954)
		(layer "F.Cu")
		(net "VR_P5V_EN_D_R")
	)
	(segment
		(start 167.420544 -133.618224)
		(end 166.593012 -133.618224)
		(width 0.12954)
		(layer "F.Cu")
		(net "VR_P5V_EN_D_R")
	)
	(segment
		(start 166.351458 -133.37667)
		(end 165.31463 -133.37667)
		(width 0.12954)
		(layer "F.Cu")
		(net "VR_P5V_EN_D_R")
	)
	(segment
		(start 166.593012 -133.618224)
		(end 166.351458 -133.37667)
		(width 0.12954)
		(layer "F.Cu")
		(net "VR_P5V_EN_D_R")
	)
	(segment
		(start 167.625268 -133.822948)
		(end 167.420544 -133.618224)
		(width 0.12954)
		(layer "F.Cu")
		(net "VR_P5V_EN_D_R")
	)
	(segment
		(start 443.258194 -372.662704)
		(end 443.258194 -371.668548)
		(width 0.12954)
		(layer "F.Cu")
		(net "VR_P5V_EN_D_R")
	)
	(segment
		(start 165.31463 -132.393182)
		(end 165.31463 -133.37667)
		(width 0.12954)
		(layer "F.Cu")
		(net "VR_P5V_EN_D_R")
	)
	(segment
		(start 165.301676 -132.380228)
		(end 165.31463 -132.393182)
		(width 0.12954)
		(layer "F.Cu")
		(net "VR_P5V_EN_D_R")
	)
	(via
		(at 206.83347 -126.873762)
		(size 0.508)
		(drill 0.254)
		(layers "F.Cu" "B.Cu")
		(net "VR_P5V_EN_D_R")
	)
	(via
		(at 239.614964 -202.871578)
		(size 0.508)
		(drill 0.254)
		(layers "F.Cu" "B.Cu")
		(net "VR_P5V_EN_D_R")
	)
	(via
		(at 304.41519 -389.715502)
		(size 0.508)
		(drill 0.254)
		(layers "F.Cu" "B.Cu")
		(net "VR_P5V_EN_D_R")
	)
	(via
		(at 443.258194 -371.668548)
		(size 0.508)
		(drill 0.254)
		(layers "F.Cu" "B.Cu")
		(net "VR_P5V_EN_D_R")
	)
	(via
		(at 194.442334 -133.442456)
		(size 0.508)
		(drill 0.254)
		(layers "F.Cu" "B.Cu")
		(net "VR_P5V_EN_D_R")
	)
	(via
		(at 167.94988 -133.822948)
		(size 0.508)
		(drill 0.254)
		(layers "F.Cu" "B.Cu")
		(net "VR_P5V_EN_D_R")
	)
	(segment
		(start 194.442334 -133.442456)
		(end 202.345798 -133.442456)
		(width 0.12954)
		(layer "B.Cu")
		(net "VR_P5V_EN_D_R")
	)
	(segment
		(start 206.840836 -128.947418)
		(end 206.840836 -126.881128)
		(width 0.12954)
		(layer "B.Cu")
		(net "VR_P5V_EN_D_R")
	)
	(segment
		(start 202.345798 -133.442456)
		(end 206.840836 -128.947418)
		(width 0.12954)
		(layer "B.Cu")
		(net "VR_P5V_EN_D_R")
	)
	(segment
		(start 206.840836 -126.881128)
		(end 206.83347 -126.873762)
		(width 0.12954)
		(layer "B.Cu")
		(net "VR_P5V_EN_D_R")
	)
	(segment
		(start 246.94388 -327.370948)
		(end 246.94388 -280.761948)
		(width 0.127)
		(layer "In4.Cu")
		(net "VR_P5V_EN_D_R")
	)
	(segment
		(start 250.49988 -277.205948)
		(end 250.49988 -213.756494)
		(width 0.127)
		(layer "In4.Cu")
		(net "VR_P5V_EN_D_R")
	)
	(segment
		(start 250.49988 -213.756494)
		(end 239.614964 -202.871578)
		(width 0.127)
		(layer "In4.Cu")
		(net "VR_P5V_EN_D_R")
	)
	(segment
		(start 246.94388 -280.761948)
		(end 250.49988 -277.205948)
		(width 0.127)
		(layer "In4.Cu")
		(net "VR_P5V_EN_D_R")
	)
	(segment
		(start 298.59224 -387.71068)
		(end 294.26154 -387.71068)
		(width 0.127)
		(layer "In4.Cu")
		(net "VR_P5V_EN_D_R")
	)
	(segment
		(start 279.30856 -359.735628)
		(end 246.94388 -327.370948)
		(width 0.127)
		(layer "In4.Cu")
		(net "VR_P5V_EN_D_R")
	)
	(segment
		(start 293.17188 -384.393948)
		(end 289.67684 -384.393948)
		(width 0.127)
		(layer "In4.Cu")
		(net "VR_P5V_EN_D_R")
	)
	(segment
		(start 289.67684 -384.393948)
		(end 279.30856 -374.025668)
		(width 0.127)
		(layer "In4.Cu")
		(net "VR_P5V_EN_D_R")
	)
	(segment
		(start 294.26154 -387.71068)
		(end 293.95928 -387.40842)
		(width 0.127)
		(layer "In4.Cu")
		(net "VR_P5V_EN_D_R")
	)
	(segment
		(start 304.41519 -389.715502)
		(end 300.597062 -389.715502)
		(width 0.127)
		(layer "In4.Cu")
		(net "VR_P5V_EN_D_R")
	)
	(segment
		(start 293.95928 -387.40842)
		(end 293.95928 -385.181348)
		(width 0.127)
		(layer "In4.Cu")
		(net "VR_P5V_EN_D_R")
	)
	(segment
		(start 293.95928 -385.181348)
		(end 293.17188 -384.393948)
		(width 0.127)
		(layer "In4.Cu")
		(net "VR_P5V_EN_D_R")
	)
	(segment
		(start 300.597062 -389.715502)
		(end 298.59224 -387.71068)
		(width 0.127)
		(layer "In4.Cu")
		(net "VR_P5V_EN_D_R")
	)
	(segment
		(start 279.30856 -374.025668)
		(end 279.30856 -359.735628)
		(width 0.127)
		(layer "In4.Cu")
		(net "VR_P5V_EN_D_R")
	)
	(segment
		(start 304.420524 -389.727948)
		(end 304.41519 -389.722614)
		(width 0.127)
		(layer "In11.Cu")
		(net "VR_P5V_EN_D_R")
	)
	(segment
		(start 422.96842 -379.821948)
		(end 418.718238 -384.07213)
		(width 0.127)
		(layer "In11.Cu")
		(net "VR_P5V_EN_D_R")
	)
	(segment
		(start 443.258194 -371.668548)
		(end 442.750194 -372.176548)
		(width 0.127)
		(layer "In11.Cu")
		(net "VR_P5V_EN_D_R")
	)
	(segment
		(start 442.750194 -372.176548)
		(end 442.750194 -375.404634)
		(width 0.127)
		(layer "In11.Cu")
		(net "VR_P5V_EN_D_R")
	)
	(segment
		(start 442.01588 -376.138948)
		(end 431.917856 -376.138948)
		(width 0.127)
		(layer "In11.Cu")
		(net "VR_P5V_EN_D_R")
	)
	(segment
		(start 239.614964 -202.871578)
		(end 239.411764 -202.871578)
		(width 0.127)
		(layer "In11.Cu")
		(net "VR_P5V_EN_D_R")
	)
	(segment
		(start 217.029792 -157.943296)
		(end 217.029792 -145.876264)
		(width 0.127)
		(layer "In11.Cu")
		(net "VR_P5V_EN_D_R")
	)
	(segment
		(start 426.39361 -377.029218)
		(end 423.60088 -379.821948)
		(width 0.127)
		(layer "In11.Cu")
		(net "VR_P5V_EN_D_R")
	)
	(segment
		(start 206.275432 -135.121904)
		(end 206.275432 -127.4318)
		(width 0.127)
		(layer "In11.Cu")
		(net "VR_P5V_EN_D_R")
	)
	(segment
		(start 442.750194 -375.404634)
		(end 442.01588 -376.138948)
		(width 0.127)
		(layer "In11.Cu")
		(net "VR_P5V_EN_D_R")
	)
	(segment
		(start 423.60088 -379.821948)
		(end 422.96842 -379.821948)
		(width 0.127)
		(layer "In11.Cu")
		(net "VR_P5V_EN_D_R")
	)
	(segment
		(start 217.029792 -145.876264)
		(end 206.275432 -135.121904)
		(width 0.127)
		(layer "In11.Cu")
		(net "VR_P5V_EN_D_R")
	)
	(segment
		(start 230.77678 -194.236594)
		(end 230.77678 -171.690284)
		(width 0.127)
		(layer "In11.Cu")
		(net "VR_P5V_EN_D_R")
	)
	(segment
		(start 239.411764 -202.871578)
		(end 230.77678 -194.236594)
		(width 0.127)
		(layer "In11.Cu")
		(net "VR_P5V_EN_D_R")
	)
	(segment
		(start 355.215952 -384.07213)
		(end 349.560134 -389.727948)
		(width 0.127)
		(layer "In11.Cu")
		(net "VR_P5V_EN_D_R")
	)
	(segment
		(start 431.917856 -376.138948)
		(end 431.027586 -377.029218)
		(width 0.127)
		(layer "In11.Cu")
		(net "VR_P5V_EN_D_R")
	)
	(segment
		(start 206.275432 -127.4318)
		(end 206.83347 -126.873762)
		(width 0.127)
		(layer "In11.Cu")
		(net "VR_P5V_EN_D_R")
	)
	(segment
		(start 230.77678 -171.690284)
		(end 217.029792 -157.943296)
		(width 0.127)
		(layer "In11.Cu")
		(net "VR_P5V_EN_D_R")
	)
	(segment
		(start 418.718238 -384.07213)
		(end 355.215952 -384.07213)
		(width 0.127)
		(layer "In11.Cu")
		(net "VR_P5V_EN_D_R")
	)
	(segment
		(start 304.41519 -389.722614)
		(end 304.41519 -389.715502)
		(width 0.127)
		(layer "In11.Cu")
		(net "VR_P5V_EN_D_R")
	)
	(segment
		(start 431.027586 -377.029218)
		(end 426.39361 -377.029218)
		(width 0.127)
		(layer "In11.Cu")
		(net "VR_P5V_EN_D_R")
	)
	(segment
		(start 349.560134 -389.727948)
		(end 304.420524 -389.727948)
		(width 0.127)
		(layer "In11.Cu")
		(net "VR_P5V_EN_D_R")
	)
	(segment
		(start 187.227464 -130.537966)
		(end 186.638184 -130.537966)
		(width 0.127)
		(layer "In15.Cu")
		(net "VR_P5V_EN_D_R")
	)
	(segment
		(start 176.950624 -133.708394)
		(end 176.535334 -133.293104)
		(width 0.127)
		(layer "In15.Cu")
		(net "VR_P5V_EN_D_R")
	)
	(segment
		(start 170.207178 -133.293104)
		(end 168.637966 -131.723892)
		(width 0.127)
		(layer "In15.Cu")
		(net "VR_P5V_EN_D_R")
	)
	(segment
		(start 167.94988 -133.23824)
		(end 167.94988 -133.822948)
		(width 0.127)
		(layer "In15.Cu")
		(net "VR_P5V_EN_D_R")
	)
	(segment
		(start 167.54348 -132.164328)
		(end 167.54348 -132.83184)
		(width 0.127)
		(layer "In15.Cu")
		(net "VR_P5V_EN_D_R")
	)
	(segment
		(start 187.70346 -131.013962)
		(end 187.227464 -130.537966)
		(width 0.127)
		(layer "In15.Cu")
		(net "VR_P5V_EN_D_R")
	)
	(segment
		(start 187.70346 -132.804408)
		(end 187.70346 -131.013962)
		(width 0.127)
		(layer "In15.Cu")
		(net "VR_P5V_EN_D_R")
	)
	(segment
		(start 176.535334 -133.293104)
		(end 170.207178 -133.293104)
		(width 0.127)
		(layer "In15.Cu")
		(net "VR_P5V_EN_D_R")
	)
	(segment
		(start 167.54348 -132.83184)
		(end 167.94988 -133.23824)
		(width 0.127)
		(layer "In15.Cu")
		(net "VR_P5V_EN_D_R")
	)
	(segment
		(start 185.071766 -134.003034)
		(end 181.132734 -134.003034)
		(width 0.127)
		(layer "In15.Cu")
		(net "VR_P5V_EN_D_R")
	)
	(segment
		(start 186.214766 -130.961384)
		(end 186.214766 -132.860034)
		(width 0.127)
		(layer "In15.Cu")
		(net "VR_P5V_EN_D_R")
	)
	(segment
		(start 186.214766 -132.860034)
		(end 185.071766 -134.003034)
		(width 0.127)
		(layer "In15.Cu")
		(net "VR_P5V_EN_D_R")
	)
	(segment
		(start 186.638184 -130.537966)
		(end 186.214766 -130.961384)
		(width 0.127)
		(layer "In15.Cu")
		(net "VR_P5V_EN_D_R")
	)
	(segment
		(start 167.983916 -131.723892)
		(end 167.54348 -132.164328)
		(width 0.127)
		(layer "In15.Cu")
		(net "VR_P5V_EN_D_R")
	)
	(segment
		(start 181.132734 -134.003034)
		(end 180.838094 -133.708394)
		(width 0.127)
		(layer "In15.Cu")
		(net "VR_P5V_EN_D_R")
	)
	(segment
		(start 193.680842 -134.203948)
		(end 189.103 -134.203948)
		(width 0.127)
		(layer "In15.Cu")
		(net "VR_P5V_EN_D_R")
	)
	(segment
		(start 180.838094 -133.708394)
		(end 176.950624 -133.708394)
		(width 0.127)
		(layer "In15.Cu")
		(net "VR_P5V_EN_D_R")
	)
	(segment
		(start 189.103 -134.203948)
		(end 187.70346 -132.804408)
		(width 0.127)
		(layer "In15.Cu")
		(net "VR_P5V_EN_D_R")
	)
	(segment
		(start 168.637966 -131.723892)
		(end 167.983916 -131.723892)
		(width 0.127)
		(layer "In15.Cu")
		(net "VR_P5V_EN_D_R")
	)
	(segment
		(start 194.442334 -133.442456)
		(end 193.680842 -134.203948)
		(width 0.127)
		(layer "In15.Cu")
		(net "VR_P5V_EN_D_R")
	)
	(segment
		(start 167.395906 -131.576064)
		(end 168.93667 -131.576064)
		(width 0.12954)
		(layer "F.Cu")
		(net "VR_P5V_EN")
	)
	(segment
		(start 169.16146 -131.001516)
		(end 168.11371 -129.953766)
		(width 0.12954)
		(layer "F.Cu")
		(net "VR_P5V_EN")
	)
	(segment
		(start 167.395144 -131.576826)
		(end 167.395906 -131.576064)
		(width 0.12954)
		(layer "F.Cu")
		(net "VR_P5V_EN")
	)
	(segment
		(start 166.196772 -131.430268)
		(end 166.34333 -131.576826)
		(width 0.12954)
		(layer "F.Cu")
		(net "VR_P5V_EN")
	)
	(segment
		(start 169.16146 -131.351274)
		(end 169.16146 -131.001516)
		(width 0.12954)
		(layer "F.Cu")
		(net "VR_P5V_EN")
	)
	(segment
		(start 166.196772 -129.986278)
		(end 166.196772 -131.430268)
		(width 0.12954)
		(layer "F.Cu")
		(net "VR_P5V_EN")
	)
	(segment
		(start 166.34333 -131.576826)
		(end 167.395144 -131.576826)
		(width 0.12954)
		(layer "F.Cu")
		(net "VR_P5V_EN")
	)
	(segment
		(start 168.93667 -131.576064)
		(end 169.16146 -131.351274)
		(width 0.12954)
		(layer "F.Cu")
		(net "VR_P5V_EN")
	)
	(via
		(at 169.16146 -131.351274)
		(size 0.508)
		(drill 0.254)
		(layers "F.Cu" "B.Cu")
		(net "VR_P5V_EN")
	)
	(segment
		(start 172.555662 -108.175552)
		(end 172.155612 -107.775502)
		(width 0.12954)
		(layer "F.Cu")
		(net "VIRTUAL_RESEAT_FPGA_R_N")
	)
	(via
		(at 172.155612 -107.775502)
		(size 0.4572)
		(drill 0.254)
		(layers "F.Cu" "B.Cu")
		(net "VIRTUAL_RESEAT_FPGA_R_N")
	)
	(via
		(at 166.31412 -107.371388)
		(size 0.6604)
		(drill 0.3302)
		(layers "F.Cu" "B.Cu")
		(net "VIRTUAL_RESEAT_FPGA_R_N")
	)
	(segment
		(start 172.155612 -107.775502)
		(end 171.751498 -107.371388)
		(width 0.12954)
		(layer "B.Cu")
		(net "VIRTUAL_RESEAT_FPGA_R_N")
	)
	(segment
		(start 165.755066 -107.371388)
		(end 165.409626 -107.025948)
		(width 0.12954)
		(layer "B.Cu")
		(net "VIRTUAL_RESEAT_FPGA_R_N")
	)
	(segment
		(start 166.31412 -107.371388)
		(end 165.755066 -107.371388)
		(width 0.12954)
		(layer "B.Cu")
		(net "VIRTUAL_RESEAT_FPGA_R_N")
	)
	(segment
		(start 165.409626 -107.025948)
		(end 165.04793 -107.025948)
		(width 0.12954)
		(layer "B.Cu")
		(net "VIRTUAL_RESEAT_FPGA_R_N")
	)
	(segment
		(start 171.751498 -107.371388)
		(end 166.31412 -107.371388)
		(width 0.12954)
		(layer "B.Cu")
		(net "VIRTUAL_RESEAT_FPGA_R_N")
	)
	(segment
		(start 196.777356 -40.138604)
		(end 195.942204 -40.138604)
		(width 0.12954)
		(layer "F.Cu")
		(net "VIRTUAL_RESEAT_FPGA_N")
	)
	(via
		(at 162.74288 -106.390948)
		(size 0.508)
		(drill 0.254)
		(layers "F.Cu" "B.Cu")
		(net "VIRTUAL_RESEAT_FPGA_N")
	)
	(via
		(at 174.558452 -43.452034)
		(size 0.508)
		(drill 0.254)
		(layers "F.Cu" "B.Cu")
		(net "VIRTUAL_RESEAT_FPGA_N")
	)
	(via
		(at 195.942204 -40.138604)
		(size 0.508)
		(drill 0.254)
		(layers "F.Cu" "B.Cu")
		(net "VIRTUAL_RESEAT_FPGA_N")
	)
	(segment
		(start 162.74288 -106.390948)
		(end 163.93668 -106.390948)
		(width 0.12954)
		(layer "B.Cu")
		(net "VIRTUAL_RESEAT_FPGA_N")
	)
	(segment
		(start 163.93668 -106.390948)
		(end 164.24783 -106.702098)
		(width 0.12954)
		(layer "B.Cu")
		(net "VIRTUAL_RESEAT_FPGA_N")
	)
	(segment
		(start 164.24783 -106.702098)
		(end 164.24783 -107.025948)
		(width 0.12954)
		(layer "B.Cu")
		(net "VIRTUAL_RESEAT_FPGA_N")
	)
	(segment
		(start 194.753738 -38.950138)
		(end 178.328066 -38.950138)
		(width 0.127)
		(layer "In6.Cu")
		(net "VIRTUAL_RESEAT_FPGA_N")
	)
	(segment
		(start 178.328066 -38.950138)
		(end 174.558452 -42.719752)
		(width 0.127)
		(layer "In6.Cu")
		(net "VIRTUAL_RESEAT_FPGA_N")
	)
	(segment
		(start 174.558452 -42.719752)
		(end 174.558452 -43.452034)
		(width 0.127)
		(layer "In6.Cu")
		(net "VIRTUAL_RESEAT_FPGA_N")
	)
	(segment
		(start 195.942204 -40.138604)
		(end 194.753738 -38.950138)
		(width 0.127)
		(layer "In6.Cu")
		(net "VIRTUAL_RESEAT_FPGA_N")
	)
	(segment
		(start 160.69818 -101.120702)
		(end 160.69818 -102.522274)
		(width 0.127)
		(layer "In13.Cu")
		(net "VIRTUAL_RESEAT_FPGA_N")
	)
	(segment
		(start 170.649392 -81.115408)
		(end 162.094926 -89.669874)
		(width 0.127)
		(layer "In13.Cu")
		(net "VIRTUAL_RESEAT_FPGA_N")
	)
	(segment
		(start 170.649392 -60.155836)
		(end 170.649392 -81.115408)
		(width 0.127)
		(layer "In13.Cu")
		(net "VIRTUAL_RESEAT_FPGA_N")
	)
	(segment
		(start 162.094926 -99.723956)
		(end 160.69818 -101.120702)
		(width 0.127)
		(layer "In13.Cu")
		(net "VIRTUAL_RESEAT_FPGA_N")
	)
	(segment
		(start 174.558452 -43.452034)
		(end 173.740318 -44.270168)
		(width 0.127)
		(layer "In13.Cu")
		(net "VIRTUAL_RESEAT_FPGA_N")
	)
	(segment
		(start 162.74288 -105.258616)
		(end 162.74288 -106.390948)
		(width 0.127)
		(layer "In13.Cu")
		(net "VIRTUAL_RESEAT_FPGA_N")
	)
	(segment
		(start 162.399726 -104.915462)
		(end 162.74288 -105.258616)
		(width 0.127)
		(layer "In13.Cu")
		(net "VIRTUAL_RESEAT_FPGA_N")
	)
	(segment
		(start 162.094926 -89.669874)
		(end 162.094926 -99.723956)
		(width 0.127)
		(layer "In13.Cu")
		(net "VIRTUAL_RESEAT_FPGA_N")
	)
	(segment
		(start 162.399726 -104.22382)
		(end 162.399726 -104.915462)
		(width 0.127)
		(layer "In13.Cu")
		(net "VIRTUAL_RESEAT_FPGA_N")
	)
	(segment
		(start 173.740318 -44.270168)
		(end 173.740318 -57.06491)
		(width 0.127)
		(layer "In13.Cu")
		(net "VIRTUAL_RESEAT_FPGA_N")
	)
	(segment
		(start 160.69818 -102.522274)
		(end 162.399726 -104.22382)
		(width 0.127)
		(layer "In13.Cu")
		(net "VIRTUAL_RESEAT_FPGA_N")
	)
	(segment
		(start 173.740318 -57.06491)
		(end 170.649392 -60.155836)
		(width 0.127)
		(layer "In13.Cu")
		(net "VIRTUAL_RESEAT_FPGA_N")
	)
	(segment
		(start 183.261762 -13.599668)
		(end 183.261762 -13.14323)
		(width 0.12954)
		(layer "F.Cu")
		(net "VIRTUAL_RESEAT")
	)
	(segment
		(start 190.93688 -118.074948)
		(end 190.30188 -118.074948)
		(width 0.12954)
		(layer "F.Cu")
		(net "VIRTUAL_RESEAT")
	)
	(segment
		(start 198.96836 -120.599708)
		(end 198.41718 -120.048528)
		(width 0.12954)
		(layer "F.Cu")
		(net "VIRTUAL_RESEAT")
	)
	(segment
		(start 189.202314 -116.975382)
		(end 186.955684 -116.975382)
		(width 0.12954)
		(layer "F.Cu")
		(net "VIRTUAL_RESEAT")
	)
	(segment
		(start 190.30188 -118.074948)
		(end 189.202314 -116.975382)
		(width 0.12954)
		(layer "F.Cu")
		(net "VIRTUAL_RESEAT")
	)
	(segment
		(start 182.04688 -11.928348)
		(end 182.04688 -11.344148)
		(width 0.12954)
		(layer "F.Cu")
		(net "VIRTUAL_RESEAT")
	)
	(segment
		(start 182.04688 -11.344148)
		(end 182.19928 -11.191748)
		(width 0.12954)
		(layer "F.Cu")
		(net "VIRTUAL_RESEAT")
	)
	(segment
		(start 183.261762 -13.14323)
		(end 182.04688 -11.928348)
		(width 0.12954)
		(layer "F.Cu")
		(net "VIRTUAL_RESEAT")
	)
	(segment
		(start 192.91046 -120.048528)
		(end 190.93688 -118.074948)
		(width 0.12954)
		(layer "F.Cu")
		(net "VIRTUAL_RESEAT")
	)
	(segment
		(start 183.262016 -13.599922)
		(end 183.261762 -13.599668)
		(width 0.12954)
		(layer "F.Cu")
		(net "VIRTUAL_RESEAT")
	)
	(segment
		(start 198.41718 -120.048528)
		(end 192.91046 -120.048528)
		(width 0.12954)
		(layer "F.Cu")
		(net "VIRTUAL_RESEAT")
	)
	(segment
		(start 183.262016 -13.600176)
		(end 183.262016 -13.599922)
		(width 0.12954)
		(layer "F.Cu")
		(net "VIRTUAL_RESEAT")
	)
	(via
		(at 168.274492 -31.73984)
		(size 0.508)
		(drill 0.254)
		(layers "F.Cu" "B.Cu")
		(net "VIRTUAL_RESEAT")
	)
	(via
		(at 189.878716 -97.780348)
		(size 0.508)
		(drill 0.254)
		(layers "F.Cu" "B.Cu")
		(net "VIRTUAL_RESEAT")
	)
	(via
		(at 182.19928 -11.191748)
		(size 0.508)
		(drill 0.254)
		(layers "F.Cu" "B.Cu")
		(net "VIRTUAL_RESEAT")
	)
	(via
		(at 198.96836 -120.599708)
		(size 0.508)
		(drill 0.254)
		(layers "F.Cu" "B.Cu")
		(net "VIRTUAL_RESEAT")
	)
	(segment
		(start 189.878716 -97.780348)
		(end 189.878716 -82.739484)
		(width 0.127)
		(layer "In2.Cu")
		(net "VIRTUAL_RESEAT")
	)
	(segment
		(start 180.541168 -42.143426)
		(end 174.83074 -36.432998)
		(width 0.127)
		(layer "In2.Cu")
		(net "VIRTUAL_RESEAT")
	)
	(segment
		(start 173.884844 -36.432998)
		(end 169.191686 -31.73984)
		(width 0.127)
		(layer "In2.Cu")
		(net "VIRTUAL_RESEAT")
	)
	(segment
		(start 186.006994 -78.867762)
		(end 186.006994 -60.188348)
		(width 0.127)
		(layer "In2.Cu")
		(net "VIRTUAL_RESEAT")
	)
	(segment
		(start 186.5884 -59.606942)
		(end 186.5884 -46.527974)
		(width 0.127)
		(layer "In2.Cu")
		(net "VIRTUAL_RESEAT")
	)
	(segment
		(start 169.191686 -31.73984)
		(end 168.274492 -31.73984)
		(width 0.127)
		(layer "In2.Cu")
		(net "VIRTUAL_RESEAT")
	)
	(segment
		(start 174.83074 -36.432998)
		(end 173.884844 -36.432998)
		(width 0.127)
		(layer "In2.Cu")
		(net "VIRTUAL_RESEAT")
	)
	(segment
		(start 186.006994 -60.188348)
		(end 186.5884 -59.606942)
		(width 0.127)
		(layer "In2.Cu")
		(net "VIRTUAL_RESEAT")
	)
	(segment
		(start 189.878716 -82.739484)
		(end 186.006994 -78.867762)
		(width 0.127)
		(layer "In2.Cu")
		(net "VIRTUAL_RESEAT")
	)
	(segment
		(start 182.203852 -42.143426)
		(end 180.541168 -42.143426)
		(width 0.127)
		(layer "In2.Cu")
		(net "VIRTUAL_RESEAT")
	)
	(segment
		(start 186.5884 -46.527974)
		(end 182.203852 -42.143426)
		(width 0.127)
		(layer "In2.Cu")
		(net "VIRTUAL_RESEAT")
	)
	(segment
		(start 194.170046 -103.073708)
		(end 191.87668 -100.780342)
		(width 0.127)
		(layer "In11.Cu")
		(net "VIRTUAL_RESEAT")
	)
	(segment
		(start 198.96836 -120.599708)
		(end 198.96836 -111.509048)
		(width 0.127)
		(layer "In11.Cu")
		(net "VIRTUAL_RESEAT")
	)
	(segment
		(start 200.10374 -108.379768)
		(end 198.96836 -107.244388)
		(width 0.127)
		(layer "In11.Cu")
		(net "VIRTUAL_RESEAT")
	)
	(segment
		(start 197.390766 -103.073708)
		(end 194.170046 -103.073708)
		(width 0.127)
		(layer "In11.Cu")
		(net "VIRTUAL_RESEAT")
	)
	(segment
		(start 198.96836 -107.244388)
		(end 198.96836 -104.651302)
		(width 0.127)
		(layer "In11.Cu")
		(net "VIRTUAL_RESEAT")
	)
	(segment
		(start 191.87668 -98.518218)
		(end 191.13881 -97.780348)
		(width 0.127)
		(layer "In11.Cu")
		(net "VIRTUAL_RESEAT")
	)
	(segment
		(start 191.87668 -100.780342)
		(end 191.87668 -98.518218)
		(width 0.127)
		(layer "In11.Cu")
		(net "VIRTUAL_RESEAT")
	)
	(segment
		(start 198.96836 -111.509048)
		(end 200.10374 -110.373668)
		(width 0.127)
		(layer "In11.Cu")
		(net "VIRTUAL_RESEAT")
	)
	(segment
		(start 191.13881 -97.780348)
		(end 189.878716 -97.780348)
		(width 0.127)
		(layer "In11.Cu")
		(net "VIRTUAL_RESEAT")
	)
	(segment
		(start 198.96836 -104.651302)
		(end 197.390766 -103.073708)
		(width 0.127)
		(layer "In11.Cu")
		(net "VIRTUAL_RESEAT")
	)
	(segment
		(start 200.10374 -110.373668)
		(end 200.10374 -108.379768)
		(width 0.127)
		(layer "In11.Cu")
		(net "VIRTUAL_RESEAT")
	)
	(segment
		(start 177.4952 -9.921748)
		(end 176.412652 -8.8392)
		(width 0.127)
		(layer "In15.Cu")
		(net "VIRTUAL_RESEAT")
	)
	(segment
		(start 182.19928 -11.191748)
		(end 179.426362 -11.191748)
		(width 0.127)
		(layer "In15.Cu")
		(net "VIRTUAL_RESEAT")
	)
	(segment
		(start 179.426362 -11.191748)
		(end 178.156362 -9.921748)
		(width 0.127)
		(layer "In15.Cu")
		(net "VIRTUAL_RESEAT")
	)
	(segment
		(start 176.412652 -8.8392)
		(end 172.20184 -8.8392)
		(width 0.127)
		(layer "In15.Cu")
		(net "VIRTUAL_RESEAT")
	)
	(segment
		(start 172.556424 -12.698476)
		(end 170.293792 -14.961108)
		(width 0.127)
		(layer "In15.Cu")
		(net "VIRTUAL_RESEAT")
	)
	(segment
		(start 172.20184 -8.8392)
		(end 171.43222 -9.60882)
		(width 0.127)
		(layer "In15.Cu")
		(net "VIRTUAL_RESEAT")
	)
	(segment
		(start 178.156362 -9.921748)
		(end 177.4952 -9.921748)
		(width 0.127)
		(layer "In15.Cu")
		(net "VIRTUAL_RESEAT")
	)
	(segment
		(start 170.293792 -14.961108)
		(end 170.293792 -17.949164)
		(width 0.127)
		(layer "In15.Cu")
		(net "VIRTUAL_RESEAT")
	)
	(segment
		(start 172.556424 -12.518644)
		(end 172.556424 -12.698476)
		(width 0.127)
		(layer "In15.Cu")
		(net "VIRTUAL_RESEAT")
	)
	(segment
		(start 168.247568 -19.995388)
		(end 168.247568 -31.712916)
		(width 0.127)
		(layer "In15.Cu")
		(net "VIRTUAL_RESEAT")
	)
	(segment
		(start 168.247568 -31.712916)
		(end 168.274492 -31.73984)
		(width 0.127)
		(layer "In15.Cu")
		(net "VIRTUAL_RESEAT")
	)
	(segment
		(start 170.293792 -17.949164)
		(end 168.247568 -19.995388)
		(width 0.127)
		(layer "In15.Cu")
		(net "VIRTUAL_RESEAT")
	)
	(segment
		(start 171.43222 -10.846308)
		(end 172.15358 -11.567668)
		(width 0.127)
		(layer "In15.Cu")
		(net "VIRTUAL_RESEAT")
	)
	(segment
		(start 171.43222 -9.60882)
		(end 171.43222 -10.846308)
		(width 0.127)
		(layer "In15.Cu")
		(net "VIRTUAL_RESEAT")
	)
	(segment
		(start 172.15358 -12.1158)
		(end 172.556424 -12.518644)
		(width 0.127)
		(layer "In15.Cu")
		(net "VIRTUAL_RESEAT")
	)
	(segment
		(start 172.15358 -11.567668)
		(end 172.15358 -12.1158)
		(width 0.127)
		(layer "In15.Cu")
		(net "VIRTUAL_RESEAT")
	)
	(segment
		(start 347.057726 -21.29028)
		(end 347.643958 -20.704048)
		(width 0.127)
		(layer "F.Cu")
		(net "USB_OC1_REAR_R_N")
	)
	(segment
		(start 342.54948 -34.585148)
		(end 342.44788 -34.686748)
		(width 0.127)
		(layer "F.Cu")
		(net "USB_OC1_REAR_R_N")
	)
	(segment
		(start 342.170512 -35.290252)
		(end 342.170512 -36.423092)
		(width 0.0889)
		(layer "F.Cu")
		(net "USB_OC1_REAR_R_N")
	)
	(segment
		(start 347.057726 -21.96973)
		(end 347.057726 -21.29028)
		(width 0.127)
		(layer "F.Cu")
		(net "USB_OC1_REAR_R_N")
	)
	(segment
		(start 342.44788 -35.012884)
		(end 342.301576 -35.159188)
		(width 0.127)
		(layer "F.Cu")
		(net "USB_OC1_REAR_R_N")
	)
	(segment
		(start 347.643958 -20.704048)
		(end 347.643958 -20.602194)
		(width 0.127)
		(layer "F.Cu")
		(net "USB_OC1_REAR_R_N")
	)
	(segment
		(start 342.301576 -35.159188)
		(end 342.170512 -35.290252)
		(width 0.0889)
		(layer "F.Cu")
		(net "USB_OC1_REAR_R_N")
	)
	(segment
		(start 342.44788 -34.686748)
		(end 342.44788 -35.012884)
		(width 0.127)
		(layer "F.Cu")
		(net "USB_OC1_REAR_R_N")
	)
	(segment
		(start 342.170512 -36.423092)
		(end 341.902288 -36.691316)
		(width 0.0889)
		(layer "F.Cu")
		(net "USB_OC1_REAR_R_N")
	)
	(segment
		(start 341.902288 -37.634926)
		(end 341.902034 -37.63518)
		(width 0.0889)
		(layer "F.Cu")
		(net "USB_OC1_REAR_R_N")
	)
	(segment
		(start 341.902288 -36.691316)
		(end 341.902288 -37.634926)
		(width 0.0889)
		(layer "F.Cu")
		(net "USB_OC1_REAR_R_N")
	)
	(via
		(at 342.54948 -34.585148)
		(size 0.508)
		(drill 0.254)
		(layers "F.Cu" "B.Cu")
		(net "USB_OC1_REAR_R_N")
	)
	(via
		(at 347.057726 -21.29028)
		(size 0.508)
		(drill 0.254)
		(layers "F.Cu" "B.Cu")
		(net "USB_OC1_REAR_R_N")
	)
	(segment
		(start 342.54948 -34.585148)
		(end 342.54948 -30.343348)
		(width 0.127)
		(layer "In2.Cu")
		(net "USB_OC1_REAR_R_N")
	)
	(segment
		(start 345.95308 -26.939748)
		(end 345.95308 -22.394926)
		(width 0.127)
		(layer "In2.Cu")
		(net "USB_OC1_REAR_R_N")
	)
	(segment
		(start 345.95308 -22.394926)
		(end 347.057726 -21.29028)
		(width 0.127)
		(layer "In2.Cu")
		(net "USB_OC1_REAR_R_N")
	)
	(segment
		(start 342.54948 -30.343348)
		(end 345.95308 -26.939748)
		(width 0.127)
		(layer "In2.Cu")
		(net "USB_OC1_REAR_R_N")
	)
	(segment
		(start 355.597968 -20.183348)
		(end 349.17888 -20.183348)
		(width 0.127)
		(layer "F.Cu")
		(net "USB_OC1_REAR_N")
	)
	(segment
		(start 374.36552 -39.324788)
		(end 372.01348 -36.972748)
		(width 0.127)
		(layer "F.Cu")
		(net "USB_OC1_REAR_N")
	)
	(segment
		(start 184.555638 -111.375444)
		(end 184.955688 -110.975394)
		(width 0.127)
		(layer "F.Cu")
		(net "USB_OC1_REAR_N")
	)
	(segment
		(start 374.16486 -51.943508)
		(end 374.36552 -51.742848)
		(width 0.127)
		(layer "F.Cu")
		(net "USB_OC1_REAR_N")
	)
	(segment
		(start 372.01348 -36.972748)
		(end 372.01348 -36.59886)
		(width 0.127)
		(layer "F.Cu")
		(net "USB_OC1_REAR_N")
	)
	(segment
		(start 348.760034 -20.602194)
		(end 348.444058 -20.602194)
		(width 0.127)
		(layer "F.Cu")
		(net "USB_OC1_REAR_N")
	)
	(segment
		(start 372.01348 -36.59886)
		(end 355.597968 -20.183348)
		(width 0.127)
		(layer "F.Cu")
		(net "USB_OC1_REAR_N")
	)
	(segment
		(start 374.36552 -51.742848)
		(end 374.36552 -39.324788)
		(width 0.127)
		(layer "F.Cu")
		(net "USB_OC1_REAR_N")
	)
	(segment
		(start 349.17888 -20.183348)
		(end 348.760034 -20.602194)
		(width 0.127)
		(layer "F.Cu")
		(net "USB_OC1_REAR_N")
	)
	(via
		(at 184.955688 -110.975394)
		(size 0.4572)
		(drill 0.254)
		(layers "F.Cu" "B.Cu")
		(net "USB_OC1_REAR_N")
	)
	(via
		(at 374.16486 -51.943508)
		(size 0.508)
		(drill 0.254)
		(layers "F.Cu" "B.Cu")
		(net "USB_OC1_REAR_N")
	)
	(segment
		(start 233.204004 -106.771948)
		(end 220.7387 -106.771948)
		(width 0.127)
		(layer "In15.Cu")
		(net "USB_OC1_REAR_N")
	)
	(segment
		(start 203.946252 -109.380528)
		(end 203.274168 -110.052612)
		(width 0.127)
		(layer "In15.Cu")
		(net "USB_OC1_REAR_N")
	)
	(segment
		(start 199.13854 -109.090968)
		(end 195.681092 -109.090968)
		(width 0.127)
		(layer "In15.Cu")
		(net "USB_OC1_REAR_N")
	)
	(segment
		(start 220.7387 -106.771948)
		(end 219.2274 -105.260648)
		(width 0.127)
		(layer "In15.Cu")
		(net "USB_OC1_REAR_N")
	)
	(segment
		(start 375.801636 -68.83527)
		(end 372.550182 -72.086724)
		(width 0.127)
		(layer "In15.Cu")
		(net "USB_OC1_REAR_N")
	)
	(segment
		(start 199.4281 -109.380528)
		(end 199.13854 -109.090968)
		(width 0.127)
		(layer "In15.Cu")
		(net "USB_OC1_REAR_N")
	)
	(segment
		(start 195.391532 -109.380528)
		(end 191.721486 -109.380528)
		(width 0.127)
		(layer "In15.Cu")
		(net "USB_OC1_REAR_N")
	)
	(segment
		(start 195.681092 -109.090968)
		(end 195.391532 -109.380528)
		(width 0.127)
		(layer "In15.Cu")
		(net "USB_OC1_REAR_N")
	)
	(segment
		(start 376.381772 -113.429288)
		(end 283.841698 -113.429288)
		(width 0.127)
		(layer "In15.Cu")
		(net "USB_OC1_REAR_N")
	)
	(segment
		(start 191.721486 -109.380528)
		(end 189.882526 -111.219488)
		(width 0.127)
		(layer "In15.Cu")
		(net "USB_OC1_REAR_N")
	)
	(segment
		(start 211.70392 -105.260648)
		(end 210.705954 -106.258614)
		(width 0.127)
		(layer "In15.Cu")
		(net "USB_OC1_REAR_N")
	)
	(segment
		(start 385.90347 -68.83527)
		(end 375.801636 -68.83527)
		(width 0.127)
		(layer "In15.Cu")
		(net "USB_OC1_REAR_N")
	)
	(segment
		(start 385.36372 -94.638368)
		(end 385.36372 -104.44734)
		(width 0.127)
		(layer "In15.Cu")
		(net "USB_OC1_REAR_N")
	)
	(segment
		(start 189.882526 -111.219488)
		(end 187.39104 -111.219488)
		(width 0.127)
		(layer "In15.Cu")
		(net "USB_OC1_REAR_N")
	)
	(segment
		(start 240.252504 -113.820448)
		(end 233.204004 -106.771948)
		(width 0.127)
		(layer "In15.Cu")
		(net "USB_OC1_REAR_N")
	)
	(segment
		(start 269.332456 -116.017548)
		(end 267.643356 -117.706648)
		(width 0.127)
		(layer "In15.Cu")
		(net "USB_OC1_REAR_N")
	)
	(segment
		(start 385.36372 -104.44734)
		(end 376.381772 -113.429288)
		(width 0.127)
		(layer "In15.Cu")
		(net "USB_OC1_REAR_N")
	)
	(segment
		(start 187.229496 -111.381032)
		(end 185.361326 -111.381032)
		(width 0.127)
		(layer "In15.Cu")
		(net "USB_OC1_REAR_N")
	)
	(segment
		(start 201.532744 -109.380528)
		(end 199.4281 -109.380528)
		(width 0.127)
		(layer "In15.Cu")
		(net "USB_OC1_REAR_N")
	)
	(segment
		(start 219.2274 -105.260648)
		(end 211.70392 -105.260648)
		(width 0.127)
		(layer "In15.Cu")
		(net "USB_OC1_REAR_N")
	)
	(segment
		(start 203.274168 -110.052612)
		(end 202.204828 -110.052612)
		(width 0.127)
		(layer "In15.Cu")
		(net "USB_OC1_REAR_N")
	)
	(segment
		(start 387.704838 -60.088526)
		(end 387.704838 -67.033902)
		(width 0.127)
		(layer "In15.Cu")
		(net "USB_OC1_REAR_N")
	)
	(segment
		(start 210.705954 -106.258614)
		(end 209.024474 -106.258614)
		(width 0.127)
		(layer "In15.Cu")
		(net "USB_OC1_REAR_N")
	)
	(segment
		(start 246.32285 -113.820448)
		(end 240.252504 -113.820448)
		(width 0.127)
		(layer "In15.Cu")
		(net "USB_OC1_REAR_N")
	)
	(segment
		(start 267.643356 -117.706648)
		(end 250.20905 -117.706648)
		(width 0.127)
		(layer "In15.Cu")
		(net "USB_OC1_REAR_N")
	)
	(segment
		(start 374.16486 -52.205128)
		(end 378.28474 -56.325008)
		(width 0.127)
		(layer "In15.Cu")
		(net "USB_OC1_REAR_N")
	)
	(segment
		(start 383.94132 -56.325008)
		(end 387.704838 -60.088526)
		(width 0.127)
		(layer "In15.Cu")
		(net "USB_OC1_REAR_N")
	)
	(segment
		(start 374.16486 -51.943508)
		(end 374.16486 -52.205128)
		(width 0.127)
		(layer "In15.Cu")
		(net "USB_OC1_REAR_N")
	)
	(segment
		(start 378.28474 -56.325008)
		(end 383.94132 -56.325008)
		(width 0.127)
		(layer "In15.Cu")
		(net "USB_OC1_REAR_N")
	)
	(segment
		(start 283.841698 -113.429288)
		(end 281.253438 -116.017548)
		(width 0.127)
		(layer "In15.Cu")
		(net "USB_OC1_REAR_N")
	)
	(segment
		(start 281.253438 -116.017548)
		(end 269.332456 -116.017548)
		(width 0.127)
		(layer "In15.Cu")
		(net "USB_OC1_REAR_N")
	)
	(segment
		(start 387.704838 -67.033902)
		(end 385.90347 -68.83527)
		(width 0.127)
		(layer "In15.Cu")
		(net "USB_OC1_REAR_N")
	)
	(segment
		(start 202.204828 -110.052612)
		(end 201.532744 -109.380528)
		(width 0.127)
		(layer "In15.Cu")
		(net "USB_OC1_REAR_N")
	)
	(segment
		(start 185.361326 -111.381032)
		(end 184.955688 -110.975394)
		(width 0.127)
		(layer "In15.Cu")
		(net "USB_OC1_REAR_N")
	)
	(segment
		(start 372.550182 -81.82483)
		(end 385.36372 -94.638368)
		(width 0.127)
		(layer "In15.Cu")
		(net "USB_OC1_REAR_N")
	)
	(segment
		(start 250.20905 -117.706648)
		(end 246.32285 -113.820448)
		(width 0.127)
		(layer "In15.Cu")
		(net "USB_OC1_REAR_N")
	)
	(segment
		(start 209.024474 -106.258614)
		(end 205.90256 -109.380528)
		(width 0.127)
		(layer "In15.Cu")
		(net "USB_OC1_REAR_N")
	)
	(segment
		(start 205.90256 -109.380528)
		(end 203.946252 -109.380528)
		(width 0.127)
		(layer "In15.Cu")
		(net "USB_OC1_REAR_N")
	)
	(segment
		(start 187.39104 -111.219488)
		(end 187.229496 -111.381032)
		(width 0.127)
		(layer "In15.Cu")
		(net "USB_OC1_REAR_N")
	)
	(segment
		(start 372.550182 -72.086724)
		(end 372.550182 -81.82483)
		(width 0.127)
		(layer "In15.Cu")
		(net "USB_OC1_REAR_N")
	)
	(segment
		(start 342.190578 -47.040546)
		(end 342.19134 -47.040546)
		(width 0.13208)
		(layer "F.Cu")
		(net "USB3_PCH_TX_DP<4>")
	)
	(segment
		(start 341.918798 -46.570646)
		(end 342.190578 -47.040546)
		(width 0.13208)
		(layer "F.Cu")
		(net "USB3_PCH_TX_DP<4>")
	)
	(via
		(at 341.918798 -46.570646)
		(size 0.4572)
		(drill 0.2032)
		(layers "F.Cu" "B.Cu")
		(net "USB3_PCH_TX_DP<4>")
	)
	(segment
		(start 355.720904 -80.601566)
		(end 359.112312 -72.41413)
		(width 0.13208)
		(layer "B.Cu")
		(net "USB3_PCH_TX_DP<4>")
	)
	(segment
		(start 346.341954 -89.980516)
		(end 355.720904 -80.601566)
		(width 0.13208)
		(layer "B.Cu")
		(net "USB3_PCH_TX_DP<4>")
	)
	(segment
		(start 359.112312 -72.41413)
		(end 359.112312 -63.456312)
		(width 0.13208)
		(layer "B.Cu")
		(net "USB3_PCH_TX_DP<4>")
	)
	(segment
		(start 124.03328 -22.49805)
		(end 124.179076 -22.14626)
		(width 0.13208)
		(layer "B.Cu")
		(net "USB3_PCH_TX_DP<4>")
	)
	(segment
		(start 124.1552 -23.970488)
		(end 124.03328 -23.848568)
		(width 0.13208)
		(layer "B.Cu")
		(net "USB3_PCH_TX_DP<4>")
	)
	(segment
		(start 346.283026 -48.041814)
		(end 345.55938 -47.318168)
		(width 0.0889)
		(layer "B.Cu")
		(net "USB3_PCH_TX_DP<4>")
	)
	(segment
		(start 147.946364 -26.391108)
		(end 154.20848 -28.986988)
		(width 0.13208)
		(layer "B.Cu")
		(net "USB3_PCH_TX_DP<4>")
	)
	(segment
		(start 124.03328 -22.842728)
		(end 124.03328 -22.49805)
		(width 0.13208)
		(layer "B.Cu")
		(net "USB3_PCH_TX_DP<4>")
	)
	(segment
		(start 281.817826 -83.167728)
		(end 286.944308 -85.291168)
		(width 0.13208)
		(layer "B.Cu")
		(net "USB3_PCH_TX_DP<4>")
	)
	(segment
		(start 138.302492 -14.999208)
		(end 139.53871 -17.983454)
		(width 0.13208)
		(layer "B.Cu")
		(net "USB3_PCH_TX_DP<4>")
	)
	(segment
		(start 362.01223 -58.870088)
		(end 362.66374 -57.297066)
		(width 0.13208)
		(layer "B.Cu")
		(net "USB3_PCH_TX_DP<4>")
	)
	(segment
		(start 342.7349 -47.415196)
		(end 342.706452 -47.414942)
		(width 0.0889)
		(layer "B.Cu")
		(net "USB3_PCH_TX_DP<4>")
	)
	(segment
		(start 362.66374 -55.107586)
		(end 358.412542 -50.856388)
		(width 0.13208)
		(layer "B.Cu")
		(net "USB3_PCH_TX_DP<4>")
	)
	(segment
		(start 190.40475 -57.207658)
		(end 190.813182 -57.413144)
		(width 0.13208)
		(layer "B.Cu")
		(net "USB3_PCH_TX_DP<4>")
	)
	(segment
		(start 162.13074 -32.957008)
		(end 164.530786 -38.751764)
		(width 0.13208)
		(layer "B.Cu")
		(net "USB3_PCH_TX_DP<4>")
	)
	(segment
		(start 329.680824 -85.291168)
		(end 341.926672 -90.363548)
		(width 0.13208)
		(layer "B.Cu")
		(net "USB3_PCH_TX_DP<4>")
	)
	(segment
		(start 161.736024 -30.970474)
		(end 162.13074 -32.957008)
		(width 0.13208)
		(layer "B.Cu")
		(net "USB3_PCH_TX_DP<4>")
	)
	(segment
		(start 124.869448 -20.798536)
		(end 124.803408 -20.639278)
		(width 0.13208)
		(layer "B.Cu")
		(net "USB3_PCH_TX_DP<4>")
	)
	(segment
		(start 344.705686 -47.414942)
		(end 344.343736 -47.414942)
		(width 0.0889)
		(layer "B.Cu")
		(net "USB3_PCH_TX_DP<4>")
	)
	(segment
		(start 182.63362 -54.884066)
		(end 186.792362 -55.711344)
		(width 0.13208)
		(layer "B.Cu")
		(net "USB3_PCH_TX_DP<4>")
	)
	(segment
		(start 216.019634 -63.279528)
		(end 226.12096 -67.46367)
		(width 0.13208)
		(layer "B.Cu")
		(net "USB3_PCH_TX_DP<4>")
	)
	(segment
		(start 199.477122 -62.607444)
		(end 201.905108 -63.279528)
		(width 0.13208)
		(layer "B.Cu")
		(net "USB3_PCH_TX_DP<4>")
	)
	(segment
		(start 126.082044 -17.553686)
		(end 127.963168 -15.672562)
		(width 0.13208)
		(layer "B.Cu")
		(net "USB3_PCH_TX_DP<4>")
	)
	(segment
		(start 124.786136 -24.986742)
		(end 124.521976 -25.250902)
		(width 0.13208)
		(layer "B.Cu")
		(net "USB3_PCH_TX_DP<4>")
	)
	(segment
		(start 360.304588 -60.57773)
		(end 362.01223 -58.870088)
		(width 0.13208)
		(layer "B.Cu")
		(net "USB3_PCH_TX_DP<4>")
	)
	(segment
		(start 344.80246 -47.318168)
		(end 344.705686 -47.414942)
		(width 0.0889)
		(layer "B.Cu")
		(net "USB3_PCH_TX_DP<4>")
	)
	(segment
		(start 137.497312 -14.194028)
		(end 138.302492 -14.999208)
		(width 0.13208)
		(layer "B.Cu")
		(net "USB3_PCH_TX_DP<4>")
	)
	(segment
		(start 124.1552 -22.964648)
		(end 124.03328 -22.842728)
		(width 0.13208)
		(layer "B.Cu")
		(net "USB3_PCH_TX_DP<4>")
	)
	(segment
		(start 177.23358 -53.261768)
		(end 181.06771 -54.85003)
		(width 0.13208)
		(layer "B.Cu")
		(net "USB3_PCH_TX_DP<4>")
	)
	(segment
		(start 124.803408 -20.639278)
		(end 126.082044 -17.553686)
		(width 0.13208)
		(layer "B.Cu")
		(net "USB3_PCH_TX_DP<4>")
	)
	(segment
		(start 181.06771 -54.85003)
		(end 181.238398 -54.884066)
		(width 0.13208)
		(layer "B.Cu")
		(net "USB3_PCH_TX_DP<4>")
	)
	(segment
		(start 132.286756 -13.881608)
		(end 136.742932 -13.881608)
		(width 0.13208)
		(layer "B.Cu")
		(net "USB3_PCH_TX_DP<4>")
	)
	(segment
		(start 124.179076 -22.14626)
		(end 124.338588 -22.08022)
		(width 0.13208)
		(layer "B.Cu")
		(net "USB3_PCH_TX_DP<4>")
	)
	(segment
		(start 124.338588 -22.08022)
		(end 124.484384 -21.727922)
		(width 0.13208)
		(layer "B.Cu")
		(net "USB3_PCH_TX_DP<4>")
	)
	(segment
		(start 154.20848 -28.986988)
		(end 158.617666 -28.986988)
		(width 0.13208)
		(layer "B.Cu")
		(net "USB3_PCH_TX_DP<4>")
	)
	(segment
		(start 201.905108 -63.279528)
		(end 216.019634 -63.279528)
		(width 0.13208)
		(layer "B.Cu")
		(net "USB3_PCH_TX_DP<4>")
	)
	(segment
		(start 124.1552 -24.351488)
		(end 124.1552 -23.970488)
		(width 0.13208)
		(layer "B.Cu")
		(net "USB3_PCH_TX_DP<4>")
	)
	(segment
		(start 136.742932 -13.881608)
		(end 137.497312 -14.194028)
		(width 0.13208)
		(layer "B.Cu")
		(net "USB3_PCH_TX_DP<4>")
	)
	(segment
		(start 250.519438 -83.167728)
		(end 281.817826 -83.167728)
		(width 0.13208)
		(layer "B.Cu")
		(net "USB3_PCH_TX_DP<4>")
	)
	(segment
		(start 124.247656 -25.250902)
		(end 124.03328 -25.036526)
		(width 0.13208)
		(layer "B.Cu")
		(net "USB3_PCH_TX_DP<4>")
	)
	(segment
		(start 241.266726 -73.915016)
		(end 250.519438 -83.167728)
		(width 0.13208)
		(layer "B.Cu")
		(net "USB3_PCH_TX_DP<4>")
	)
	(segment
		(start 124.03328 -23.467568)
		(end 124.1552 -23.345648)
		(width 0.13208)
		(layer "B.Cu")
		(net "USB3_PCH_TX_DP<4>")
	)
	(segment
		(start 343.572846 -46.945296)
		(end 343.504012 -46.945296)
		(width 0.0889)
		(layer "B.Cu")
		(net "USB3_PCH_TX_DP<4>")
	)
	(segment
		(start 341.926672 -90.363548)
		(end 345.41714 -90.363548)
		(width 0.13208)
		(layer "B.Cu")
		(net "USB3_PCH_TX_DP<4>")
	)
	(segment
		(start 358.412542 -50.856388)
		(end 349.146368 -50.856388)
		(width 0.13208)
		(layer "B.Cu")
		(net "USB3_PCH_TX_DP<4>")
	)
	(segment
		(start 139.53871 -17.983454)
		(end 147.946364 -26.391108)
		(width 0.13208)
		(layer "B.Cu")
		(net "USB3_PCH_TX_DP<4>")
	)
	(segment
		(start 124.484384 -21.727922)
		(end 124.418344 -21.568664)
		(width 0.13208)
		(layer "B.Cu")
		(net "USB3_PCH_TX_DP<4>")
	)
	(segment
		(start 160.555178 -29.789374)
		(end 161.736024 -30.970474)
		(width 0.13208)
		(layer "B.Cu")
		(net "USB3_PCH_TX_DP<4>")
	)
	(segment
		(start 186.792362 -55.711344)
		(end 190.40475 -57.207658)
		(width 0.13208)
		(layer "B.Cu")
		(net "USB3_PCH_TX_DP<4>")
	)
	(segment
		(start 190.813182 -57.413144)
		(end 199.477122 -62.607444)
		(width 0.13208)
		(layer "B.Cu")
		(net "USB3_PCH_TX_DP<4>")
	)
	(segment
		(start 343.57818 -46.945296)
		(end 343.57818 -46.94555)
		(width 0.0889)
		(layer "B.Cu")
		(net "USB3_PCH_TX_DP<4>")
	)
	(segment
		(start 341.918798 -46.88332)
		(end 341.918798 -46.570646)
		(width 0.0889)
		(layer "B.Cu")
		(net "USB3_PCH_TX_DP<4>")
	)
	(segment
		(start 124.03328 -25.036526)
		(end 124.03328 -24.473408)
		(width 0.13208)
		(layer "B.Cu")
		(net "USB3_PCH_TX_DP<4>")
	)
	(segment
		(start 181.238398 -54.884066)
		(end 182.63362 -54.884066)
		(width 0.13208)
		(layer "B.Cu")
		(net "USB3_PCH_TX_DP<4>")
	)
	(segment
		(start 345.55938 -47.318168)
		(end 344.80246 -47.318168)
		(width 0.0889)
		(layer "B.Cu")
		(net "USB3_PCH_TX_DP<4>")
	)
	(segment
		(start 158.617666 -28.986988)
		(end 160.555178 -29.789374)
		(width 0.13208)
		(layer "B.Cu")
		(net "USB3_PCH_TX_DP<4>")
	)
	(segment
		(start 124.03328 -24.473408)
		(end 124.1552 -24.351488)
		(width 0.13208)
		(layer "B.Cu")
		(net "USB3_PCH_TX_DP<4>")
	)
	(segment
		(start 286.944308 -85.291168)
		(end 329.680824 -85.291168)
		(width 0.13208)
		(layer "B.Cu")
		(net "USB3_PCH_TX_DP<4>")
	)
	(segment
		(start 124.723652 -21.150834)
		(end 124.869448 -20.798536)
		(width 0.13208)
		(layer "B.Cu")
		(net "USB3_PCH_TX_DP<4>")
	)
	(segment
		(start 349.146368 -50.856388)
		(end 346.347288 -48.057308)
		(width 0.13208)
		(layer "B.Cu")
		(net "USB3_PCH_TX_DP<4>")
	)
	(segment
		(start 124.1552 -23.345648)
		(end 124.1552 -22.964648)
		(width 0.13208)
		(layer "B.Cu")
		(net "USB3_PCH_TX_DP<4>")
	)
	(segment
		(start 359.112312 -63.456312)
		(end 360.304588 -60.57773)
		(width 0.13208)
		(layer "B.Cu")
		(net "USB3_PCH_TX_DP<4>")
	)
	(segment
		(start 346.331794 -48.041814)
		(end 346.283026 -48.041814)
		(width 0.0889)
		(layer "B.Cu")
		(net "USB3_PCH_TX_DP<4>")
	)
	(segment
		(start 124.418344 -21.568664)
		(end 124.56414 -21.216874)
		(width 0.13208)
		(layer "B.Cu")
		(net "USB3_PCH_TX_DP<4>")
	)
	(segment
		(start 226.12096 -67.46367)
		(end 228.744018 -70.086728)
		(width 0.13208)
		(layer "B.Cu")
		(net "USB3_PCH_TX_DP<4>")
	)
	(segment
		(start 175.955452 -50.17643)
		(end 177.23358 -53.261768)
		(width 0.13208)
		(layer "B.Cu")
		(net "USB3_PCH_TX_DP<4>")
	)
	(segment
		(start 228.744018 -70.086728)
		(end 231.659938 -71.294498)
		(width 0.13208)
		(layer "B.Cu")
		(net "USB3_PCH_TX_DP<4>")
	)
	(segment
		(start 124.03328 -23.848568)
		(end 124.03328 -23.467568)
		(width 0.13208)
		(layer "B.Cu")
		(net "USB3_PCH_TX_DP<4>")
	)
	(segment
		(start 341.98306 -46.947582)
		(end 341.918798 -46.88332)
		(width 0.0889)
		(layer "B.Cu")
		(net "USB3_PCH_TX_DP<4>")
	)
	(segment
		(start 124.521976 -25.250902)
		(end 124.247656 -25.250902)
		(width 0.13208)
		(layer "B.Cu")
		(net "USB3_PCH_TX_DP<4>")
	)
	(segment
		(start 127.963168 -15.672562)
		(end 132.286756 -13.881608)
		(width 0.13208)
		(layer "B.Cu")
		(net "USB3_PCH_TX_DP<4>")
	)
	(segment
		(start 231.659938 -71.294498)
		(end 237.972092 -72.550274)
		(width 0.13208)
		(layer "B.Cu")
		(net "USB3_PCH_TX_DP<4>")
	)
	(segment
		(start 164.530786 -38.751764)
		(end 175.955452 -50.17643)
		(width 0.13208)
		(layer "B.Cu")
		(net "USB3_PCH_TX_DP<4>")
	)
	(segment
		(start 237.972092 -72.550274)
		(end 241.266726 -73.915016)
		(width 0.13208)
		(layer "B.Cu")
		(net "USB3_PCH_TX_DP<4>")
	)
	(segment
		(start 346.347288 -48.057308)
		(end 346.331794 -48.041814)
		(width 0.0889)
		(layer "B.Cu")
		(net "USB3_PCH_TX_DP<4>")
	)
	(segment
		(start 362.66374 -57.297066)
		(end 362.66374 -55.107586)
		(width 0.13208)
		(layer "B.Cu")
		(net "USB3_PCH_TX_DP<4>")
	)
	(segment
		(start 345.41714 -90.363548)
		(end 346.341954 -89.980516)
		(width 0.13208)
		(layer "B.Cu")
		(net "USB3_PCH_TX_DP<4>")
	)
	(segment
		(start 343.074752 -47.198788)
		(end 343.058496 -47.22876)
		(width 0.0889)
		(layer "B.Cu")
		(net "USB3_PCH_TX_DP<4>")
	)
	(segment
		(start 124.56414 -21.216874)
		(end 124.723652 -21.150834)
		(width 0.13208)
		(layer "B.Cu")
		(net "USB3_PCH_TX_DP<4>")
	)
	(arc
		(start 343.058496 -47.22876)
		(mid 342.921661 -47.365303)
		(end 342.7349 -47.415196)
		(width 0.0889)
		(layer "B.Cu")
		(net "USB3_PCH_TX_DP<4>")
	)
	(arc
		(start 342.706452 -47.414942)
		(mid 342.534779 -47.358154)
		(end 342.409526 -47.227744)
		(width 0.0889)
		(layer "B.Cu")
		(net "USB3_PCH_TX_DP<4>")
	)
	(arc
		(start 343.57818 -46.94555)
		(mid 343.575513 -46.945417)
		(end 343.572846 -46.945296)
		(width 0.0889)
		(layer "B.Cu")
		(net "USB3_PCH_TX_DP<4>")
	)
	(arc
		(start 342.006936 -46.950884)
		(mid 341.995015 -46.949108)
		(end 341.98306 -46.947582)
		(width 0.0889)
		(layer "B.Cu")
		(net "USB3_PCH_TX_DP<4>")
	)
	(arc
		(start 342.409526 -47.227744)
		(mid 342.239631 -47.043655)
		(end 342.006936 -46.950884)
		(width 0.0889)
		(layer "B.Cu")
		(net "USB3_PCH_TX_DP<4>")
	)
	(arc
		(start 343.504012 -46.945296)
		(mid 343.254749 -47.013398)
		(end 343.074752 -47.198788)
		(width 0.0889)
		(layer "B.Cu")
		(net "USB3_PCH_TX_DP<4>")
	)
	(arc
		(start 344.343736 -47.414942)
		(mid 344.167118 -47.360073)
		(end 344.038174 -47.22749)
		(width 0.0889)
		(layer "B.Cu")
		(net "USB3_PCH_TX_DP<4>")
	)
	(arc
		(start 344.038174 -47.22749)
		(mid 343.843961 -47.028097)
		(end 343.57818 -46.945296)
		(width 0.0889)
		(layer "B.Cu")
		(net "USB3_PCH_TX_DP<4>")
	)
	(segment
		(start 341.918798 -47.510446)
		(end 342.190578 -47.980346)
		(width 0.13208)
		(layer "F.Cu")
		(net "USB3_PCH_TX_DN<4>")
	)
	(segment
		(start 342.190578 -47.980346)
		(end 342.19134 -47.980346)
		(width 0.13208)
		(layer "F.Cu")
		(net "USB3_PCH_TX_DN<4>")
	)
	(via
		(at 341.918798 -47.510446)
		(size 0.4572)
		(drill 0.2032)
		(layers "F.Cu" "B.Cu")
		(net "USB3_PCH_TX_DN<4>")
	)
	(segment
		(start 138.522202 -14.852396)
		(end 139.75842 -17.836642)
		(width 0.13208)
		(layer "B.Cu")
		(net "USB3_PCH_TX_DN<4>")
	)
	(segment
		(start 176.175162 -50.029618)
		(end 177.431954 -53.063394)
		(width 0.13208)
		(layer "B.Cu")
		(net "USB3_PCH_TX_DN<4>")
	)
	(segment
		(start 342.734138 -47.605442)
		(end 342.697308 -47.605188)
		(width 0.0889)
		(layer "B.Cu")
		(net "USB3_PCH_TX_DN<4>")
	)
	(segment
		(start 190.5127 -56.971946)
		(end 190.938404 -57.185814)
		(width 0.13208)
		(layer "B.Cu")
		(net "USB3_PCH_TX_DN<4>")
	)
	(segment
		(start 355.501194 -80.454754)
		(end 358.853232 -72.362568)
		(width 0.13208)
		(layer "B.Cu")
		(net "USB3_PCH_TX_DN<4>")
	)
	(segment
		(start 358.853232 -72.362568)
		(end 358.853232 -63.40475)
		(width 0.13208)
		(layer "B.Cu")
		(net "USB3_PCH_TX_DN<4>")
	)
	(segment
		(start 286.99587 -85.032088)
		(end 329.732386 -85.032088)
		(width 0.13208)
		(layer "B.Cu")
		(net "USB3_PCH_TX_DN<4>")
	)
	(segment
		(start 357.21036 -51.237388)
		(end 356.8192 -51.237388)
		(width 0.13208)
		(layer "B.Cu")
		(net "USB3_PCH_TX_DN<4>")
	)
	(segment
		(start 136.794748 -13.622528)
		(end 137.644124 -13.974318)
		(width 0.13208)
		(layer "B.Cu")
		(net "USB3_PCH_TX_DN<4>")
	)
	(segment
		(start 158.669228 -28.727908)
		(end 160.70199 -29.569664)
		(width 0.13208)
		(layer "B.Cu")
		(net "USB3_PCH_TX_DN<4>")
	)
	(segment
		(start 357.33228 -51.115468)
		(end 357.21036 -51.237388)
		(width 0.13208)
		(layer "B.Cu")
		(net "USB3_PCH_TX_DN<4>")
	)
	(segment
		(start 344.78468 -47.605188)
		(end 344.339164 -47.605188)
		(width 0.0889)
		(layer "B.Cu")
		(net "USB3_PCH_TX_DN<4>")
	)
	(segment
		(start 344.33891 -47.605442)
		(end 344.334084 -47.605442)
		(width 0.0889)
		(layer "B.Cu")
		(net "USB3_PCH_TX_DN<4>")
	)
	(segment
		(start 127.816356 -15.452852)
		(end 132.235194 -13.622528)
		(width 0.13208)
		(layer "B.Cu")
		(net "USB3_PCH_TX_DN<4>")
	)
	(segment
		(start 329.732386 -85.032088)
		(end 341.978234 -90.104468)
		(width 0.13208)
		(layer "B.Cu")
		(net "USB3_PCH_TX_DN<4>")
	)
	(segment
		(start 201.940414 -63.020448)
		(end 216.071196 -63.020448)
		(width 0.13208)
		(layer "B.Cu")
		(net "USB3_PCH_TX_DN<4>")
	)
	(segment
		(start 182.659274 -54.624986)
		(end 186.868054 -55.46217)
		(width 0.13208)
		(layer "B.Cu")
		(net "USB3_PCH_TX_DN<4>")
	)
	(segment
		(start 345.480386 -47.508414)
		(end 344.881454 -47.508414)
		(width 0.0889)
		(layer "B.Cu")
		(net "USB3_PCH_TX_DN<4>")
	)
	(segment
		(start 226.267772 -67.24396)
		(end 228.89083 -69.867018)
		(width 0.13208)
		(layer "B.Cu")
		(net "USB3_PCH_TX_DN<4>")
	)
	(segment
		(start 186.868054 -55.46217)
		(end 190.5127 -56.971946)
		(width 0.13208)
		(layer "B.Cu")
		(net "USB3_PCH_TX_DN<4>")
	)
	(segment
		(start 354.61702 -51.115468)
		(end 349.038672 -51.115468)
		(width 0.13208)
		(layer "B.Cu")
		(net "USB3_PCH_TX_DN<4>")
	)
	(segment
		(start 349.038672 -51.115468)
		(end 346.1639 -48.240696)
		(width 0.13208)
		(layer "B.Cu")
		(net "USB3_PCH_TX_DN<4>")
	)
	(segment
		(start 231.73563 -71.045324)
		(end 238.047784 -72.3011)
		(width 0.13208)
		(layer "B.Cu")
		(net "USB3_PCH_TX_DN<4>")
	)
	(segment
		(start 344.339164 -47.605188)
		(end 344.33891 -47.605442)
		(width 0.0889)
		(layer "B.Cu")
		(net "USB3_PCH_TX_DN<4>")
	)
	(segment
		(start 181.143402 -54.600856)
		(end 181.264052 -54.624986)
		(width 0.13208)
		(layer "B.Cu")
		(net "USB3_PCH_TX_DN<4>")
	)
	(segment
		(start 164.750496 -38.604952)
		(end 176.175162 -50.029618)
		(width 0.13208)
		(layer "B.Cu")
		(net "USB3_PCH_TX_DN<4>")
	)
	(segment
		(start 341.977218 -47.139352)
		(end 341.918798 -47.197772)
		(width 0.0889)
		(layer "B.Cu")
		(net "USB3_PCH_TX_DN<4>")
	)
	(segment
		(start 137.644124 -13.974318)
		(end 138.522202 -14.852396)
		(width 0.13208)
		(layer "B.Cu")
		(net "USB3_PCH_TX_DN<4>")
	)
	(segment
		(start 228.89083 -69.867018)
		(end 231.73563 -71.045324)
		(width 0.13208)
		(layer "B.Cu")
		(net "USB3_PCH_TX_DN<4>")
	)
	(segment
		(start 345.365578 -90.104468)
		(end 346.195142 -89.760806)
		(width 0.13208)
		(layer "B.Cu")
		(net "USB3_PCH_TX_DN<4>")
	)
	(segment
		(start 124.521976 -25.509982)
		(end 124.140214 -25.509982)
		(width 0.13208)
		(layer "B.Cu")
		(net "USB3_PCH_TX_DN<4>")
	)
	(segment
		(start 190.938404 -57.185814)
		(end 199.580246 -62.36716)
		(width 0.13208)
		(layer "B.Cu")
		(net "USB3_PCH_TX_DN<4>")
	)
	(segment
		(start 355.79304 -51.237388)
		(end 355.67112 -51.115468)
		(width 0.13208)
		(layer "B.Cu")
		(net "USB3_PCH_TX_DN<4>")
	)
	(segment
		(start 123.7742 -25.143968)
		(end 123.7742 -22.446488)
		(width 0.13208)
		(layer "B.Cu")
		(net "USB3_PCH_TX_DN<4>")
	)
	(segment
		(start 355.67112 -51.115468)
		(end 355.25202 -51.115468)
		(width 0.13208)
		(layer "B.Cu")
		(net "USB3_PCH_TX_DN<4>")
	)
	(segment
		(start 358.829864 -51.640232)
		(end 358.3051 -51.115468)
		(width 0.13208)
		(layer "B.Cu")
		(net "USB3_PCH_TX_DN<4>")
	)
	(segment
		(start 358.829864 -51.812444)
		(end 358.829864 -51.640232)
		(width 0.13208)
		(layer "B.Cu")
		(net "USB3_PCH_TX_DN<4>")
	)
	(segment
		(start 346.148406 -48.225202)
		(end 346.148406 -48.176434)
		(width 0.0889)
		(layer "B.Cu")
		(net "USB3_PCH_TX_DN<4>")
	)
	(segment
		(start 360.084878 -60.430918)
		(end 361.79252 -58.723276)
		(width 0.13208)
		(layer "B.Cu")
		(net "USB3_PCH_TX_DN<4>")
	)
	(segment
		(start 362.40466 -55.215028)
		(end 359.278936 -52.089304)
		(width 0.13208)
		(layer "B.Cu")
		(net "USB3_PCH_TX_DN<4>")
	)
	(segment
		(start 343.56802 -47.135542)
		(end 343.504012 -47.135542)
		(width 0.0889)
		(layer "B.Cu")
		(net "USB3_PCH_TX_DN<4>")
	)
	(segment
		(start 125.862334 -17.406874)
		(end 127.816356 -15.452852)
		(width 0.13208)
		(layer "B.Cu")
		(net "USB3_PCH_TX_DN<4>")
	)
	(segment
		(start 123.939554 -22.0472)
		(end 123.939808 -22.046692)
		(width 0.13208)
		(layer "B.Cu")
		(net "USB3_PCH_TX_DN<4>")
	)
	(segment
		(start 123.7742 -22.446488)
		(end 123.939554 -22.0472)
		(width 0.13208)
		(layer "B.Cu")
		(net "USB3_PCH_TX_DN<4>")
	)
	(segment
		(start 355.25202 -51.115468)
		(end 355.1301 -51.237388)
		(width 0.13208)
		(layer "B.Cu")
		(net "USB3_PCH_TX_DN<4>")
	)
	(segment
		(start 361.79252 -58.723276)
		(end 362.40466 -57.245504)
		(width 0.13208)
		(layer "B.Cu")
		(net "USB3_PCH_TX_DN<4>")
	)
	(segment
		(start 359.278936 -52.089304)
		(end 359.106724 -52.089304)
		(width 0.13208)
		(layer "B.Cu")
		(net "USB3_PCH_TX_DN<4>")
	)
	(segment
		(start 356.1842 -51.237388)
		(end 355.79304 -51.237388)
		(width 0.13208)
		(layer "B.Cu")
		(net "USB3_PCH_TX_DN<4>")
	)
	(segment
		(start 362.40466 -57.245504)
		(end 362.40466 -55.215028)
		(width 0.13208)
		(layer "B.Cu")
		(net "USB3_PCH_TX_DN<4>")
	)
	(segment
		(start 356.8192 -51.237388)
		(end 356.69728 -51.115468)
		(width 0.13208)
		(layer "B.Cu")
		(net "USB3_PCH_TX_DN<4>")
	)
	(segment
		(start 199.580246 -62.36716)
		(end 201.940414 -63.020448)
		(width 0.13208)
		(layer "B.Cu")
		(net "USB3_PCH_TX_DN<4>")
	)
	(segment
		(start 139.75842 -17.836642)
		(end 148.093176 -26.171398)
		(width 0.13208)
		(layer "B.Cu")
		(net "USB3_PCH_TX_DN<4>")
	)
	(segment
		(start 181.264052 -54.624986)
		(end 182.659274 -54.624986)
		(width 0.13208)
		(layer "B.Cu")
		(net "USB3_PCH_TX_DN<4>")
	)
	(segment
		(start 346.148406 -48.176434)
		(end 345.480386 -47.508414)
		(width 0.0889)
		(layer "B.Cu")
		(net "USB3_PCH_TX_DN<4>")
	)
	(segment
		(start 124.140214 -25.509982)
		(end 123.7742 -25.143968)
		(width 0.13208)
		(layer "B.Cu")
		(net "USB3_PCH_TX_DN<4>")
	)
	(segment
		(start 177.431954 -53.063394)
		(end 181.143402 -54.600856)
		(width 0.13208)
		(layer "B.Cu")
		(net "USB3_PCH_TX_DN<4>")
	)
	(segment
		(start 238.047784 -72.3011)
		(end 241.413538 -73.695306)
		(width 0.13208)
		(layer "B.Cu")
		(net "USB3_PCH_TX_DN<4>")
	)
	(segment
		(start 354.73894 -51.237388)
		(end 354.61702 -51.115468)
		(width 0.13208)
		(layer "B.Cu")
		(net "USB3_PCH_TX_DN<4>")
	)
	(segment
		(start 160.70199 -29.569664)
		(end 161.975038 -30.842712)
		(width 0.13208)
		(layer "B.Cu")
		(net "USB3_PCH_TX_DN<4>")
	)
	(segment
		(start 344.881454 -47.508414)
		(end 344.78468 -47.605188)
		(width 0.0889)
		(layer "B.Cu")
		(net "USB3_PCH_TX_DN<4>")
	)
	(segment
		(start 241.413538 -73.695306)
		(end 250.62688 -82.908648)
		(width 0.13208)
		(layer "B.Cu")
		(net "USB3_PCH_TX_DN<4>")
	)
	(segment
		(start 356.30612 -51.115468)
		(end 356.1842 -51.237388)
		(width 0.13208)
		(layer "B.Cu")
		(net "USB3_PCH_TX_DN<4>")
	)
	(segment
		(start 343.24163 -47.290482)
		(end 343.22385 -47.322994)
		(width 0.0889)
		(layer "B.Cu")
		(net "USB3_PCH_TX_DN<4>")
	)
	(segment
		(start 355.1301 -51.237388)
		(end 354.73894 -51.237388)
		(width 0.13208)
		(layer "B.Cu")
		(net "USB3_PCH_TX_DN<4>")
	)
	(segment
		(start 281.869388 -82.908648)
		(end 286.99587 -85.032088)
		(width 0.13208)
		(layer "B.Cu")
		(net "USB3_PCH_TX_DN<4>")
	)
	(segment
		(start 356.69728 -51.115468)
		(end 356.30612 -51.115468)
		(width 0.13208)
		(layer "B.Cu")
		(net "USB3_PCH_TX_DN<4>")
	)
	(segment
		(start 341.978234 -90.104468)
		(end 345.365578 -90.104468)
		(width 0.13208)
		(layer "B.Cu")
		(net "USB3_PCH_TX_DN<4>")
	)
	(segment
		(start 341.918798 -47.197772)
		(end 341.918798 -47.510446)
		(width 0.0889)
		(layer "B.Cu")
		(net "USB3_PCH_TX_DN<4>")
	)
	(segment
		(start 346.1639 -48.240696)
		(end 346.148406 -48.225202)
		(width 0.0889)
		(layer "B.Cu")
		(net "USB3_PCH_TX_DN<4>")
	)
	(segment
		(start 123.939808 -22.046692)
		(end 125.862334 -17.406874)
		(width 0.13208)
		(layer "B.Cu")
		(net "USB3_PCH_TX_DN<4>")
	)
	(segment
		(start 216.071196 -63.020448)
		(end 226.267772 -67.24396)
		(width 0.13208)
		(layer "B.Cu")
		(net "USB3_PCH_TX_DN<4>")
	)
	(segment
		(start 343.22385 -47.322994)
		(end 343.223088 -47.324264)
		(width 0.0889)
		(layer "B.Cu")
		(net "USB3_PCH_TX_DN<4>")
	)
	(segment
		(start 148.093176 -26.171398)
		(end 154.260296 -28.727908)
		(width 0.13208)
		(layer "B.Cu")
		(net "USB3_PCH_TX_DN<4>")
	)
	(segment
		(start 358.3051 -51.115468)
		(end 357.33228 -51.115468)
		(width 0.13208)
		(layer "B.Cu")
		(net "USB3_PCH_TX_DN<4>")
	)
	(segment
		(start 162.380168 -32.881316)
		(end 164.750496 -38.604952)
		(width 0.13208)
		(layer "B.Cu")
		(net "USB3_PCH_TX_DN<4>")
	)
	(segment
		(start 346.195142 -89.760806)
		(end 355.501194 -80.454754)
		(width 0.13208)
		(layer "B.Cu")
		(net "USB3_PCH_TX_DN<4>")
	)
	(segment
		(start 359.106724 -52.089304)
		(end 358.829864 -51.812444)
		(width 0.13208)
		(layer "B.Cu")
		(net "USB3_PCH_TX_DN<4>")
	)
	(segment
		(start 124.786136 -25.774142)
		(end 124.521976 -25.509982)
		(width 0.13208)
		(layer "B.Cu")
		(net "USB3_PCH_TX_DN<4>")
	)
	(segment
		(start 161.975038 -30.842712)
		(end 162.380168 -32.881316)
		(width 0.13208)
		(layer "B.Cu")
		(net "USB3_PCH_TX_DN<4>")
	)
	(segment
		(start 154.260296 -28.727908)
		(end 158.669228 -28.727908)
		(width 0.13208)
		(layer "B.Cu")
		(net "USB3_PCH_TX_DN<4>")
	)
	(segment
		(start 358.853232 -63.40475)
		(end 360.084878 -60.430918)
		(width 0.13208)
		(layer "B.Cu")
		(net "USB3_PCH_TX_DN<4>")
	)
	(segment
		(start 132.235194 -13.622528)
		(end 136.794748 -13.622528)
		(width 0.13208)
		(layer "B.Cu")
		(net "USB3_PCH_TX_DN<4>")
	)
	(segment
		(start 250.62688 -82.908648)
		(end 281.869388 -82.908648)
		(width 0.13208)
		(layer "B.Cu")
		(net "USB3_PCH_TX_DN<4>")
	)
	(arc
		(start 342.697308 -47.605188)
		(mid 342.435523 -47.520806)
		(end 342.244426 -47.322994)
		(width 0.0889)
		(layer "B.Cu")
		(net "USB3_PCH_TX_DN<4>")
	)
	(arc
		(start 343.504012 -47.135542)
		(mid 343.351644 -47.177161)
		(end 343.24163 -47.290482)
		(width 0.0889)
		(layer "B.Cu")
		(net "USB3_PCH_TX_DN<4>")
	)
	(arc
		(start 342.244426 -47.322994)
		(mid 342.131664 -47.200834)
		(end 341.977218 -47.139352)
		(width 0.0889)
		(layer "B.Cu")
		(net "USB3_PCH_TX_DN<4>")
	)
	(arc
		(start 343.223088 -47.324264)
		(mid 343.016267 -47.530306)
		(end 342.734138 -47.605442)
		(width 0.0889)
		(layer "B.Cu")
		(net "USB3_PCH_TX_DN<4>")
	)
	(arc
		(start 343.873074 -47.322994)
		(mid 343.744347 -47.190542)
		(end 343.56802 -47.135542)
		(width 0.0889)
		(layer "B.Cu")
		(net "USB3_PCH_TX_DN<4>")
	)
	(arc
		(start 344.334084 -47.605442)
		(mid 344.067663 -47.522837)
		(end 343.873074 -47.322994)
		(width 0.0889)
		(layer "B.Cu")
		(net "USB3_PCH_TX_DN<4>")
	)
	(segment
		(start 126.38659 -25.269698)
		(end 126.429516 -25.226772)
		(width 0.13208)
		(layer "B.Cu")
		(net "USB3_PCH_TX_C_DP<4>")
	)
	(segment
		(start 126.429516 -25.226772)
		(end 126.615698 -25.226772)
		(width 0.13208)
		(layer "B.Cu")
		(net "USB3_PCH_TX_C_DP<4>")
	)
	(segment
		(start 125.319536 -24.986742)
		(end 125.602492 -25.269698)
		(width 0.13208)
		(layer "B.Cu")
		(net "USB3_PCH_TX_C_DP<4>")
	)
	(segment
		(start 125.602492 -25.269698)
		(end 126.38659 -25.269698)
		(width 0.13208)
		(layer "B.Cu")
		(net "USB3_PCH_TX_C_DP<4>")
	)
	(segment
		(start 126.38659 -25.528778)
		(end 126.434596 -25.576784)
		(width 0.13208)
		(layer "B.Cu")
		(net "USB3_PCH_TX_C_DN<4>")
	)
	(segment
		(start 125.5649 -25.528778)
		(end 126.38659 -25.528778)
		(width 0.13208)
		(layer "B.Cu")
		(net "USB3_PCH_TX_C_DN<4>")
	)
	(segment
		(start 126.434596 -25.576784)
		(end 126.615698 -25.576784)
		(width 0.13208)
		(layer "B.Cu")
		(net "USB3_PCH_TX_C_DN<4>")
	)
	(segment
		(start 125.319536 -25.774142)
		(end 125.5649 -25.528778)
		(width 0.13208)
		(layer "B.Cu")
		(net "USB3_PCH_TX_C_DN<4>")
	)
	(segment
		(start 136.17575 -14.892528)
		(end 136.47801 -15.194788)
		(width 0.13208)
		(layer "F.Cu")
		(net "USB3_PCH_RX_DP<4>")
	)
	(segment
		(start 136.346946 -13.600176)
		(end 136.346946 -14.139672)
		(width 0.13208)
		(layer "F.Cu")
		(net "USB3_PCH_RX_DP<4>")
	)
	(segment
		(start 136.346946 -14.139672)
		(end 136.17575 -14.310868)
		(width 0.13208)
		(layer "F.Cu")
		(net "USB3_PCH_RX_DP<4>")
	)
	(segment
		(start 136.17575 -14.310868)
		(end 136.17575 -14.892528)
		(width 0.13208)
		(layer "F.Cu")
		(net "USB3_PCH_RX_DP<4>")
	)
	(via
		(at 136.47801 -15.194788)
		(size 0.508)
		(drill 0.254)
		(layers "F.Cu" "B.Cu")
		(net "USB3_PCH_RX_DP<4>")
	)
	(segment
		(start 132.46354 -27.89301)
		(end 132.14731 -28.20924)
		(width 0.13208)
		(layer "B.Cu")
		(net "USB3_PCH_RX_DP<4>")
	)
	(segment
		(start 133.24586 -27.89301)
		(end 132.46354 -27.89301)
		(width 0.13208)
		(layer "B.Cu")
		(net "USB3_PCH_RX_DP<4>")
	)
	(segment
		(start 133.5786 -28.22575)
		(end 133.24586 -27.89301)
		(width 0.13208)
		(layer "B.Cu")
		(net "USB3_PCH_RX_DP<4>")
	)
	(segment
		(start 133.5786 -28.22575)
		(end 133.92023 -27.88412)
		(width 0.13208)
		(layer "B.Cu")
		(net "USB3_PCH_RX_DP<4>")
	)
	(segment
		(start 133.92023 -27.88412)
		(end 134.70763 -27.88412)
		(width 0.13208)
		(layer "B.Cu")
		(net "USB3_PCH_RX_DP<4>")
	)
	(segment
		(start 136.17575 -17.953736)
		(end 136.17575 -15.497048)
		(width 0.13208)
		(layer "B.Cu")
		(net "USB3_PCH_RX_DP<4>")
	)
	(segment
		(start 136.17575 -15.497048)
		(end 136.47801 -15.194788)
		(width 0.13208)
		(layer "B.Cu")
		(net "USB3_PCH_RX_DP<4>")
	)
	(segment
		(start 135.73506 -19.017742)
		(end 136.17575 -17.953736)
		(width 0.13208)
		(layer "B.Cu")
		(net "USB3_PCH_RX_DP<4>")
	)
	(segment
		(start 135.73506 -26.85669)
		(end 135.73506 -19.017742)
		(width 0.13208)
		(layer "B.Cu")
		(net "USB3_PCH_RX_DP<4>")
	)
	(segment
		(start 134.70763 -27.88412)
		(end 135.73506 -26.85669)
		(width 0.13208)
		(layer "B.Cu")
		(net "USB3_PCH_RX_DP<4>")
	)
	(segment
		(start 135.91667 -14.892528)
		(end 135.61441 -15.194788)
		(width 0.13208)
		(layer "F.Cu")
		(net "USB3_PCH_RX_DN<4>")
	)
	(segment
		(start 135.746998 -14.138656)
		(end 135.91667 -14.308328)
		(width 0.13208)
		(layer "F.Cu")
		(net "USB3_PCH_RX_DN<4>")
	)
	(segment
		(start 135.91667 -14.308328)
		(end 135.91667 -14.892528)
		(width 0.13208)
		(layer "F.Cu")
		(net "USB3_PCH_RX_DN<4>")
	)
	(segment
		(start 135.746998 -13.600176)
		(end 135.746998 -14.138656)
		(width 0.13208)
		(layer "F.Cu")
		(net "USB3_PCH_RX_DN<4>")
	)
	(via
		(at 135.61441 -15.194788)
		(size 0.508)
		(drill 0.254)
		(layers "F.Cu" "B.Cu")
		(net "USB3_PCH_RX_DN<4>")
	)
	(segment
		(start 135.47598 -23.07082)
		(end 135.35406 -22.9489)
		(width 0.13208)
		(layer "B.Cu")
		(net "USB3_PCH_RX_DN<4>")
	)
	(segment
		(start 135.35406 -21.92274)
		(end 135.35406 -21.53158)
		(width 0.13208)
		(layer "B.Cu")
		(net "USB3_PCH_RX_DN<4>")
	)
	(segment
		(start 135.47598 -22.04466)
		(end 135.35406 -21.92274)
		(width 0.13208)
		(layer "B.Cu")
		(net "USB3_PCH_RX_DN<4>")
	)
	(segment
		(start 135.91667 -15.497048)
		(end 135.61441 -15.194788)
		(width 0.13208)
		(layer "B.Cu")
		(net "USB3_PCH_RX_DN<4>")
	)
	(segment
		(start 133.21792 -27.63393)
		(end 133.5786 -27.27325)
		(width 0.13208)
		(layer "B.Cu")
		(net "USB3_PCH_RX_DN<4>")
	)
	(segment
		(start 135.47598 -18.96618)
		(end 135.91667 -17.902174)
		(width 0.13208)
		(layer "B.Cu")
		(net "USB3_PCH_RX_DN<4>")
	)
	(segment
		(start 135.35406 -20.89658)
		(end 135.35406 -20.50542)
		(width 0.13208)
		(layer "B.Cu")
		(net "USB3_PCH_RX_DN<4>")
	)
	(segment
		(start 135.47598 -19.99234)
		(end 135.35406 -19.87042)
		(width 0.13208)
		(layer "B.Cu")
		(net "USB3_PCH_RX_DN<4>")
	)
	(segment
		(start 135.91667 -17.902174)
		(end 135.91667 -15.497048)
		(width 0.13208)
		(layer "B.Cu")
		(net "USB3_PCH_RX_DN<4>")
	)
	(segment
		(start 135.35406 -20.50542)
		(end 135.47598 -20.3835)
		(width 0.13208)
		(layer "B.Cu")
		(net "USB3_PCH_RX_DN<4>")
	)
	(segment
		(start 135.35406 -22.9489)
		(end 135.35406 -22.55774)
		(width 0.13208)
		(layer "B.Cu")
		(net "USB3_PCH_RX_DN<4>")
	)
	(segment
		(start 132.14731 -27.3177)
		(end 132.46354 -27.63393)
		(width 0.13208)
		(layer "B.Cu")
		(net "USB3_PCH_RX_DN<4>")
	)
	(segment
		(start 135.47598 -21.0185)
		(end 135.35406 -20.89658)
		(width 0.13208)
		(layer "B.Cu")
		(net "USB3_PCH_RX_DN<4>")
	)
	(segment
		(start 134.600188 -27.62504)
		(end 135.47598 -26.749248)
		(width 0.13208)
		(layer "B.Cu")
		(net "USB3_PCH_RX_DN<4>")
	)
	(segment
		(start 135.35406 -19.47926)
		(end 135.47598 -19.35734)
		(width 0.13208)
		(layer "B.Cu")
		(net "USB3_PCH_RX_DN<4>")
	)
	(segment
		(start 135.47598 -26.749248)
		(end 135.47598 -23.07082)
		(width 0.13208)
		(layer "B.Cu")
		(net "USB3_PCH_RX_DN<4>")
	)
	(segment
		(start 132.46354 -27.63393)
		(end 133.21792 -27.63393)
		(width 0.13208)
		(layer "B.Cu")
		(net "USB3_PCH_RX_DN<4>")
	)
	(segment
		(start 133.93039 -27.62504)
		(end 134.600188 -27.62504)
		(width 0.13208)
		(layer "B.Cu")
		(net "USB3_PCH_RX_DN<4>")
	)
	(segment
		(start 135.47598 -22.43582)
		(end 135.47598 -22.04466)
		(width 0.13208)
		(layer "B.Cu")
		(net "USB3_PCH_RX_DN<4>")
	)
	(segment
		(start 135.35406 -21.53158)
		(end 135.47598 -21.40966)
		(width 0.13208)
		(layer "B.Cu")
		(net "USB3_PCH_RX_DN<4>")
	)
	(segment
		(start 135.35406 -22.55774)
		(end 135.47598 -22.43582)
		(width 0.13208)
		(layer "B.Cu")
		(net "USB3_PCH_RX_DN<4>")
	)
	(segment
		(start 135.47598 -19.35734)
		(end 135.47598 -18.96618)
		(width 0.13208)
		(layer "B.Cu")
		(net "USB3_PCH_RX_DN<4>")
	)
	(segment
		(start 133.5786 -27.27325)
		(end 133.93039 -27.62504)
		(width 0.13208)
		(layer "B.Cu")
		(net "USB3_PCH_RX_DN<4>")
	)
	(segment
		(start 135.47598 -20.3835)
		(end 135.47598 -19.99234)
		(width 0.13208)
		(layer "B.Cu")
		(net "USB3_PCH_RX_DN<4>")
	)
	(segment
		(start 135.47598 -21.40966)
		(end 135.47598 -21.0185)
		(width 0.13208)
		(layer "B.Cu")
		(net "USB3_PCH_RX_DN<4>")
	)
	(segment
		(start 135.35406 -19.87042)
		(end 135.35406 -19.47926)
		(width 0.13208)
		(layer "B.Cu")
		(net "USB3_PCH_RX_DN<4>")
	)
	(segment
		(start 14.838934 -105.137712)
		(end 14.265402 -105.137712)
		(width 0.13208)
		(layer "F.Cu")
		(net "USB2_HOST_BMC_B_DP")
	)
	(segment
		(start 141.746986 -16.550132)
		(end 141.746986 -17.074388)
		(width 0.13208)
		(layer "F.Cu")
		(net "USB2_HOST_BMC_B_DP")
	)
	(segment
		(start 15.288006 -105.13568)
		(end 15.441422 -105.13568)
		(width 0.13208)
		(layer "F.Cu")
		(net "USB2_HOST_BMC_B_DP")
	)
	(segment
		(start 141.746986 -17.074388)
		(end 141.57579 -17.245584)
		(width 0.13208)
		(layer "F.Cu")
		(net "USB2_HOST_BMC_B_DP")
	)
	(segment
		(start 15.906242 -105.6005)
		(end 15.954502 -105.6005)
		(width 0.13208)
		(layer "F.Cu")
		(net "USB2_HOST_BMC_B_DP")
	)
	(segment
		(start 141.57579 -17.245584)
		(end 141.57579 -17.842484)
		(width 0.13208)
		(layer "F.Cu")
		(net "USB2_HOST_BMC_B_DP")
	)
	(segment
		(start 15.441422 -105.13568)
		(end 15.906242 -105.6005)
		(width 0.13208)
		(layer "F.Cu")
		(net "USB2_HOST_BMC_B_DP")
	)
	(segment
		(start 14.840966 -105.13568)
		(end 14.838934 -105.137712)
		(width 0.13208)
		(layer "F.Cu")
		(net "USB2_HOST_BMC_B_DP")
	)
	(segment
		(start 141.57579 -17.842484)
		(end 141.87805 -18.144744)
		(width 0.13208)
		(layer "F.Cu")
		(net "USB2_HOST_BMC_B_DP")
	)
	(segment
		(start 15.288006 -105.13568)
		(end 14.840966 -105.13568)
		(width 0.13208)
		(layer "F.Cu")
		(net "USB2_HOST_BMC_B_DP")
	)
	(segment
		(start 12.758166 -45.990764)
		(end 12.758166 -44.865544)
		(width 0.14732)
		(layer "In6.Cu")
		(net "USB2_HOST_BMC_B_DP")
	)
	(segment
		(start 18.24228 -104.284526)
		(end 18.24228 -97.948496)
		(width 0.14732)
		(layer "In6.Cu")
		(net "USB2_HOST_BMC_B_DP")
	)
	(segment
		(start 92.735908 -30.571948)
		(end 99.100132 -27.935936)
		(width 0.14732)
		(layer "In6.Cu")
		(net "USB2_HOST_BMC_B_DP")
	)
	(segment
		(start 141.58341 -18.439384)
		(end 141.87805 -18.144744)
		(width 0.14732)
		(layer "In6.Cu")
		(net "USB2_HOST_BMC_B_DP")
	)
	(segment
		(start 103.37292 -23.663148)
		(end 109.55528 -23.663148)
		(width 0.14732)
		(layer "In6.Cu")
		(net "USB2_HOST_BMC_B_DP")
	)
	(segment
		(start 99.100132 -27.935936)
		(end 103.37292 -23.663148)
		(width 0.14732)
		(layer "In6.Cu")
		(net "USB2_HOST_BMC_B_DP")
	)
	(segment
		(start 130.806698 -19.907504)
		(end 136.955784 -19.907504)
		(width 0.14732)
		(layer "In6.Cu")
		(net "USB2_HOST_BMC_B_DP")
	)
	(segment
		(start 109.55528 -23.663148)
		(end 115.4049 -17.813528)
		(width 0.14732)
		(layer "In6.Cu")
		(net "USB2_HOST_BMC_B_DP")
	)
	(segment
		(start 138.651488 -21.603208)
		(end 140.740892 -21.603208)
		(width 0.14732)
		(layer "In6.Cu")
		(net "USB2_HOST_BMC_B_DP")
	)
	(segment
		(start 16.241522 -41.382188)
		(end 39.037514 -41.382188)
		(width 0.14732)
		(layer "In6.Cu")
		(net "USB2_HOST_BMC_B_DP")
	)
	(segment
		(start 16.20393 -105.351072)
		(end 16.97863 -105.351072)
		(width 0.14732)
		(layer "In6.Cu")
		(net "USB2_HOST_BMC_B_DP")
	)
	(segment
		(start 2.21488 -71.70547)
		(end 2.21488 -49.657508)
		(width 0.14732)
		(layer "In6.Cu")
		(net "USB2_HOST_BMC_B_DP")
	)
	(segment
		(start 126.93396 -17.813528)
		(end 129.97053 -19.071336)
		(width 0.14732)
		(layer "In6.Cu")
		(net "USB2_HOST_BMC_B_DP")
	)
	(segment
		(start 91.48572 -30.571948)
		(end 92.735908 -30.571948)
		(width 0.14732)
		(layer "In6.Cu")
		(net "USB2_HOST_BMC_B_DP")
	)
	(segment
		(start 140.740892 -21.603208)
		(end 141.58341 -20.76069)
		(width 0.14732)
		(layer "In6.Cu")
		(net "USB2_HOST_BMC_B_DP")
	)
	(segment
		(start 129.97053 -19.071336)
		(end 130.806698 -19.907504)
		(width 0.14732)
		(layer "In6.Cu")
		(net "USB2_HOST_BMC_B_DP")
	)
	(segment
		(start 11.708892 -93.19768)
		(end 9.188704 -90.677492)
		(width 0.14732)
		(layer "In6.Cu")
		(net "USB2_HOST_BMC_B_DP")
	)
	(segment
		(start 2.33934 -72.26935)
		(end 2.33934 -71.82993)
		(width 0.14732)
		(layer "In6.Cu")
		(net "USB2_HOST_BMC_B_DP")
	)
	(segment
		(start 12.758166 -44.865544)
		(end 16.241522 -41.382188)
		(width 0.14732)
		(layer "In6.Cu")
		(net "USB2_HOST_BMC_B_DP")
	)
	(segment
		(start 2.21488 -73.841864)
		(end 2.21488 -72.39381)
		(width 0.14732)
		(layer "In6.Cu")
		(net "USB2_HOST_BMC_B_DP")
	)
	(segment
		(start 141.58341 -20.76069)
		(end 141.58341 -18.439384)
		(width 0.14732)
		(layer "In6.Cu")
		(net "USB2_HOST_BMC_B_DP")
	)
	(segment
		(start 14.41196 -93.19768)
		(end 11.708892 -93.19768)
		(width 0.14732)
		(layer "In6.Cu")
		(net "USB2_HOST_BMC_B_DP")
	)
	(segment
		(start 4.213606 -47.658782)
		(end 11.090148 -47.658782)
		(width 0.14732)
		(layer "In6.Cu")
		(net "USB2_HOST_BMC_B_DP")
	)
	(segment
		(start 15.02664 -94.732856)
		(end 15.02664 -93.81236)
		(width 0.14732)
		(layer "In6.Cu")
		(net "USB2_HOST_BMC_B_DP")
	)
	(segment
		(start 2.33934 -71.82993)
		(end 2.21488 -71.70547)
		(width 0.14732)
		(layer "In6.Cu")
		(net "USB2_HOST_BMC_B_DP")
	)
	(segment
		(start 9.188704 -90.677492)
		(end 2.21488 -73.841864)
		(width 0.14732)
		(layer "In6.Cu")
		(net "USB2_HOST_BMC_B_DP")
	)
	(segment
		(start 16.97863 -105.351072)
		(end 17.175988 -105.350818)
		(width 0.14732)
		(layer "In6.Cu")
		(net "USB2_HOST_BMC_B_DP")
	)
	(segment
		(start 17.175988 -105.350818)
		(end 18.24228 -104.284526)
		(width 0.14732)
		(layer "In6.Cu")
		(net "USB2_HOST_BMC_B_DP")
	)
	(segment
		(start 54.4195 -35.010852)
		(end 80.188308 -35.010852)
		(width 0.14732)
		(layer "In6.Cu")
		(net "USB2_HOST_BMC_B_DP")
	)
	(segment
		(start 136.955784 -19.907504)
		(end 138.651488 -21.603208)
		(width 0.14732)
		(layer "In6.Cu")
		(net "USB2_HOST_BMC_B_DP")
	)
	(segment
		(start 15.02664 -93.81236)
		(end 14.41196 -93.19768)
		(width 0.14732)
		(layer "In6.Cu")
		(net "USB2_HOST_BMC_B_DP")
	)
	(segment
		(start 11.090148 -47.658782)
		(end 12.758166 -45.990764)
		(width 0.14732)
		(layer "In6.Cu")
		(net "USB2_HOST_BMC_B_DP")
	)
	(segment
		(start 18.24228 -97.948496)
		(end 15.02664 -94.732856)
		(width 0.14732)
		(layer "In6.Cu")
		(net "USB2_HOST_BMC_B_DP")
	)
	(segment
		(start 115.4049 -17.813528)
		(end 126.93396 -17.813528)
		(width 0.14732)
		(layer "In6.Cu")
		(net "USB2_HOST_BMC_B_DP")
	)
	(segment
		(start 87.82812 -34.229548)
		(end 91.48572 -30.571948)
		(width 0.14732)
		(layer "In6.Cu")
		(net "USB2_HOST_BMC_B_DP")
	)
	(segment
		(start 39.037514 -41.382188)
		(end 54.4195 -35.010852)
		(width 0.14732)
		(layer "In6.Cu")
		(net "USB2_HOST_BMC_B_DP")
	)
	(segment
		(start 2.21488 -72.39381)
		(end 2.33934 -72.26935)
		(width 0.14732)
		(layer "In6.Cu")
		(net "USB2_HOST_BMC_B_DP")
	)
	(segment
		(start 15.954502 -105.6005)
		(end 16.20393 -105.351072)
		(width 0.14732)
		(layer "In6.Cu")
		(net "USB2_HOST_BMC_B_DP")
	)
	(segment
		(start 80.969612 -34.229548)
		(end 87.82812 -34.229548)
		(width 0.14732)
		(layer "In6.Cu")
		(net "USB2_HOST_BMC_B_DP")
	)
	(segment
		(start 2.21488 -49.657508)
		(end 4.213606 -47.658782)
		(width 0.14732)
		(layer "In6.Cu")
		(net "USB2_HOST_BMC_B_DP")
	)
	(segment
		(start 80.188308 -35.010852)
		(end 80.969612 -34.229548)
		(width 0.14732)
		(layer "In6.Cu")
		(net "USB2_HOST_BMC_B_DP")
	)
	(segment
		(start 17.092422 -105.16616)
		(end 17.097502 -105.16108)
		(width 0.13208)
		(layer "F.Cu")
		(net "USB2_HOST_BMC_B_DN")
	)
	(segment
		(start 16.292576 -105.16616)
		(end 15.954248 -104.827832)
		(width 0.13208)
		(layer "F.Cu")
		(net "USB2_HOST_BMC_B_DN")
	)
	(segment
		(start 17.635474 -105.16108)
		(end 17.658842 -105.137712)
		(width 0.13208)
		(layer "F.Cu")
		(net "USB2_HOST_BMC_B_DN")
	)
	(segment
		(start 16.645382 -105.16616)
		(end 17.092422 -105.16616)
		(width 0.13208)
		(layer "F.Cu")
		(net "USB2_HOST_BMC_B_DN")
	)
	(segment
		(start 141.31671 -17.258284)
		(end 141.31671 -17.842484)
		(width 0.13208)
		(layer "F.Cu")
		(net "USB2_HOST_BMC_B_DN")
	)
	(segment
		(start 141.31671 -17.842484)
		(end 141.01445 -18.144744)
		(width 0.13208)
		(layer "F.Cu")
		(net "USB2_HOST_BMC_B_DN")
	)
	(segment
		(start 17.097502 -105.16108)
		(end 17.635474 -105.16108)
		(width 0.13208)
		(layer "F.Cu")
		(net "USB2_HOST_BMC_B_DN")
	)
	(segment
		(start 141.147038 -16.550132)
		(end 141.147038 -17.088612)
		(width 0.13208)
		(layer "F.Cu")
		(net "USB2_HOST_BMC_B_DN")
	)
	(segment
		(start 141.147038 -17.088612)
		(end 141.31671 -17.258284)
		(width 0.13208)
		(layer "F.Cu")
		(net "USB2_HOST_BMC_B_DN")
	)
	(segment
		(start 16.645382 -105.16616)
		(end 16.292576 -105.16616)
		(width 0.13208)
		(layer "F.Cu")
		(net "USB2_HOST_BMC_B_DN")
	)
	(segment
		(start 38.982904 -41.107868)
		(end 16.12773 -41.107868)
		(width 0.14732)
		(layer "In6.Cu")
		(net "USB2_HOST_BMC_B_DN")
	)
	(segment
		(start 137.069576 -19.633184)
		(end 135.23341 -19.633184)
		(width 0.14732)
		(layer "In6.Cu")
		(net "USB2_HOST_BMC_B_DN")
	)
	(segment
		(start 130.92049 -19.633184)
		(end 130.125978 -18.838672)
		(width 0.14732)
		(layer "In6.Cu")
		(net "USB2_HOST_BMC_B_DN")
	)
	(segment
		(start 17.96796 -98.062288)
		(end 17.96796 -102.118414)
		(width 0.14732)
		(layer "In6.Cu")
		(net "USB2_HOST_BMC_B_DN")
	)
	(segment
		(start 12.483846 -44.751752)
		(end 12.483846 -45.876972)
		(width 0.14732)
		(layer "In6.Cu")
		(net "USB2_HOST_BMC_B_DN")
	)
	(segment
		(start 135.08863 -19.488404)
		(end 134.72033 -19.488404)
		(width 0.14732)
		(layer "In6.Cu")
		(net "USB2_HOST_BMC_B_DN")
	)
	(segment
		(start 16.978376 -105.076752)
		(end 16.203168 -105.076752)
		(width 0.14732)
		(layer "In6.Cu")
		(net "USB2_HOST_BMC_B_DN")
	)
	(segment
		(start 141.30909 -18.439384)
		(end 141.30909 -20.646898)
		(width 0.14732)
		(layer "In6.Cu")
		(net "USB2_HOST_BMC_B_DN")
	)
	(segment
		(start 14.75232 -94.846648)
		(end 17.96796 -98.062288)
		(width 0.14732)
		(layer "In6.Cu")
		(net "USB2_HOST_BMC_B_DN")
	)
	(segment
		(start 138.76528 -21.328888)
		(end 137.069576 -19.633184)
		(width 0.14732)
		(layer "In6.Cu")
		(net "USB2_HOST_BMC_B_DN")
	)
	(segment
		(start 132.11175 -19.488404)
		(end 131.96697 -19.633184)
		(width 0.14732)
		(layer "In6.Cu")
		(net "USB2_HOST_BMC_B_DN")
	)
	(segment
		(start 10.976356 -47.384462)
		(end 4.099814 -47.384462)
		(width 0.14732)
		(layer "In6.Cu")
		(net "USB2_HOST_BMC_B_DN")
	)
	(segment
		(start 126.98857 -17.539208)
		(end 115.291108 -17.539208)
		(width 0.14732)
		(layer "In6.Cu")
		(net "USB2_HOST_BMC_B_DN")
	)
	(segment
		(start 133.64845 -19.488404)
		(end 133.28015 -19.488404)
		(width 0.14732)
		(layer "In6.Cu")
		(net "USB2_HOST_BMC_B_DN")
	)
	(segment
		(start 11.5951 -93.472)
		(end 14.298168 -93.472)
		(width 0.14732)
		(layer "In6.Cu")
		(net "USB2_HOST_BMC_B_DN")
	)
	(segment
		(start 134.57555 -19.633184)
		(end 133.79323 -19.633184)
		(width 0.14732)
		(layer "In6.Cu")
		(net "USB2_HOST_BMC_B_DN")
	)
	(segment
		(start 135.23341 -19.633184)
		(end 135.08863 -19.488404)
		(width 0.14732)
		(layer "In6.Cu")
		(net "USB2_HOST_BMC_B_DN")
	)
	(segment
		(start 98.944684 -27.703272)
		(end 92.681298 -30.297628)
		(width 0.14732)
		(layer "In6.Cu")
		(net "USB2_HOST_BMC_B_DN")
	)
	(segment
		(start 8.95604 -90.83294)
		(end 11.5951 -93.472)
		(width 0.14732)
		(layer "In6.Cu")
		(net "USB2_HOST_BMC_B_DN")
	)
	(segment
		(start 1.94056 -73.896474)
		(end 8.95604 -90.83294)
		(width 0.14732)
		(layer "In6.Cu")
		(net "USB2_HOST_BMC_B_DN")
	)
	(segment
		(start 134.72033 -19.488404)
		(end 134.57555 -19.633184)
		(width 0.14732)
		(layer "In6.Cu")
		(net "USB2_HOST_BMC_B_DN")
	)
	(segment
		(start 80.85582 -33.955228)
		(end 80.074516 -34.736532)
		(width 0.14732)
		(layer "In6.Cu")
		(net "USB2_HOST_BMC_B_DN")
	)
	(segment
		(start 17.96796 -102.118414)
		(end 17.82318 -102.263194)
		(width 0.14732)
		(layer "In6.Cu")
		(net "USB2_HOST_BMC_B_DN")
	)
	(segment
		(start 17.82318 -102.631494)
		(end 17.96796 -102.776274)
		(width 0.14732)
		(layer "In6.Cu")
		(net "USB2_HOST_BMC_B_DN")
	)
	(segment
		(start 17.96796 -102.776274)
		(end 17.96796 -103.144574)
		(width 0.14732)
		(layer "In6.Cu")
		(net "USB2_HOST_BMC_B_DN")
	)
	(segment
		(start 17.82318 -103.657654)
		(end 17.96796 -103.802434)
		(width 0.14732)
		(layer "In6.Cu")
		(net "USB2_HOST_BMC_B_DN")
	)
	(segment
		(start 133.13537 -19.633184)
		(end 132.62483 -19.633184)
		(width 0.14732)
		(layer "In6.Cu")
		(net "USB2_HOST_BMC_B_DN")
	)
	(segment
		(start 91.371928 -30.297628)
		(end 87.714328 -33.955228)
		(width 0.14732)
		(layer "In6.Cu")
		(net "USB2_HOST_BMC_B_DN")
	)
	(segment
		(start 80.074516 -34.736532)
		(end 54.36489 -34.736532)
		(width 0.14732)
		(layer "In6.Cu")
		(net "USB2_HOST_BMC_B_DN")
	)
	(segment
		(start 16.12773 -41.107868)
		(end 12.483846 -44.751752)
		(width 0.14732)
		(layer "In6.Cu")
		(net "USB2_HOST_BMC_B_DN")
	)
	(segment
		(start 130.125978 -18.838672)
		(end 126.98857 -17.539208)
		(width 0.14732)
		(layer "In6.Cu")
		(net "USB2_HOST_BMC_B_DN")
	)
	(segment
		(start 17.96796 -103.144574)
		(end 17.82318 -103.289354)
		(width 0.14732)
		(layer "In6.Cu")
		(net "USB2_HOST_BMC_B_DN")
	)
	(segment
		(start 132.62483 -19.633184)
		(end 132.48005 -19.488404)
		(width 0.14732)
		(layer "In6.Cu")
		(net "USB2_HOST_BMC_B_DN")
	)
	(segment
		(start 17.96796 -103.802434)
		(end 17.96796 -104.170734)
		(width 0.14732)
		(layer "In6.Cu")
		(net "USB2_HOST_BMC_B_DN")
	)
	(segment
		(start 14.75232 -93.926152)
		(end 14.75232 -94.846648)
		(width 0.14732)
		(layer "In6.Cu")
		(net "USB2_HOST_BMC_B_DN")
	)
	(segment
		(start 133.79323 -19.633184)
		(end 133.64845 -19.488404)
		(width 0.14732)
		(layer "In6.Cu")
		(net "USB2_HOST_BMC_B_DN")
	)
	(segment
		(start 1.94056 -49.543716)
		(end 1.94056 -73.896474)
		(width 0.14732)
		(layer "In6.Cu")
		(net "USB2_HOST_BMC_B_DN")
	)
	(segment
		(start 141.30909 -20.646898)
		(end 140.6271 -21.328888)
		(width 0.14732)
		(layer "In6.Cu")
		(net "USB2_HOST_BMC_B_DN")
	)
	(segment
		(start 141.01445 -18.144744)
		(end 141.30909 -18.439384)
		(width 0.14732)
		(layer "In6.Cu")
		(net "USB2_HOST_BMC_B_DN")
	)
	(segment
		(start 109.441488 -23.388828)
		(end 103.259128 -23.388828)
		(width 0.14732)
		(layer "In6.Cu")
		(net "USB2_HOST_BMC_B_DN")
	)
	(segment
		(start 14.298168 -93.472)
		(end 14.75232 -93.926152)
		(width 0.14732)
		(layer "In6.Cu")
		(net "USB2_HOST_BMC_B_DN")
	)
	(segment
		(start 4.099814 -47.384462)
		(end 1.94056 -49.543716)
		(width 0.14732)
		(layer "In6.Cu")
		(net "USB2_HOST_BMC_B_DN")
	)
	(segment
		(start 131.96697 -19.633184)
		(end 130.92049 -19.633184)
		(width 0.14732)
		(layer "In6.Cu")
		(net "USB2_HOST_BMC_B_DN")
	)
	(segment
		(start 133.28015 -19.488404)
		(end 133.13537 -19.633184)
		(width 0.14732)
		(layer "In6.Cu")
		(net "USB2_HOST_BMC_B_DN")
	)
	(segment
		(start 54.36489 -34.736532)
		(end 38.982904 -41.107868)
		(width 0.14732)
		(layer "In6.Cu")
		(net "USB2_HOST_BMC_B_DN")
	)
	(segment
		(start 92.681298 -30.297628)
		(end 91.371928 -30.297628)
		(width 0.14732)
		(layer "In6.Cu")
		(net "USB2_HOST_BMC_B_DN")
	)
	(segment
		(start 17.062196 -105.076498)
		(end 16.978376 -105.076752)
		(width 0.14732)
		(layer "In6.Cu")
		(net "USB2_HOST_BMC_B_DN")
	)
	(segment
		(start 17.96796 -104.170734)
		(end 17.062196 -105.076498)
		(width 0.14732)
		(layer "In6.Cu")
		(net "USB2_HOST_BMC_B_DN")
	)
	(segment
		(start 87.714328 -33.955228)
		(end 80.85582 -33.955228)
		(width 0.14732)
		(layer "In6.Cu")
		(net "USB2_HOST_BMC_B_DN")
	)
	(segment
		(start 16.203168 -105.076752)
		(end 15.954248 -104.827832)
		(width 0.14732)
		(layer "In6.Cu")
		(net "USB2_HOST_BMC_B_DN")
	)
	(segment
		(start 17.82318 -103.289354)
		(end 17.82318 -103.657654)
		(width 0.14732)
		(layer "In6.Cu")
		(net "USB2_HOST_BMC_B_DN")
	)
	(segment
		(start 140.6271 -21.328888)
		(end 138.76528 -21.328888)
		(width 0.14732)
		(layer "In6.Cu")
		(net "USB2_HOST_BMC_B_DN")
	)
	(segment
		(start 17.82318 -102.263194)
		(end 17.82318 -102.631494)
		(width 0.14732)
		(layer "In6.Cu")
		(net "USB2_HOST_BMC_B_DN")
	)
	(segment
		(start 132.48005 -19.488404)
		(end 132.11175 -19.488404)
		(width 0.14732)
		(layer "In6.Cu")
		(net "USB2_HOST_BMC_B_DN")
	)
	(segment
		(start 115.291108 -17.539208)
		(end 109.441488 -23.388828)
		(width 0.14732)
		(layer "In6.Cu")
		(net "USB2_HOST_BMC_B_DN")
	)
	(segment
		(start 103.259128 -23.388828)
		(end 98.944684 -27.703272)
		(width 0.14732)
		(layer "In6.Cu")
		(net "USB2_HOST_BMC_B_DN")
	)
	(segment
		(start 12.483846 -45.876972)
		(end 10.976356 -47.384462)
		(width 0.14732)
		(layer "In6.Cu")
		(net "USB2_HOST_BMC_B_DN")
	)
	(segment
		(start 357.454454 -34.456624)
		(end 354.795328 -34.456624)
		(width 0.13208)
		(layer "F.Cu")
		(net "USB2_8_DP")
	)
	(segment
		(start 350.644714 -38.304216)
		(end 350.644714 -38.326314)
		(width 0.0889)
		(layer "F.Cu")
		(net "USB2_8_DP")
	)
	(segment
		(start 350.610424 -38.977824)
		(end 350.61017 -38.978078)
		(width 0.0889)
		(layer "F.Cu")
		(net "USB2_8_DP")
	)
	(segment
		(start 348.096078 -41.439846)
		(end 347.897704 -41.63822)
		(width 0.0889)
		(layer "F.Cu")
		(net "USB2_8_DP")
	)
	(segment
		(start 357.67264 -34.938208)
		(end 357.67264 -34.67481)
		(width 0.13208)
		(layer "F.Cu")
		(net "USB2_8_DP")
	)
	(segment
		(start 346.509086 -41.623488)
		(end 346.244672 -41.446958)
		(width 0.0889)
		(layer "F.Cu")
		(net "USB2_8_DP")
	)
	(segment
		(start 350.61017 -38.978078)
		(end 350.61017 -39.674546)
		(width 0.0889)
		(layer "F.Cu")
		(net "USB2_8_DP")
	)
	(segment
		(start 139.946888 -16.550132)
		(end 139.946888 -17.074642)
		(width 0.12954)
		(layer "F.Cu")
		(net "USB2_8_DP")
	)
	(segment
		(start 350.644714 -37.415978)
		(end 350.644714 -38.304216)
		(width 0.13208)
		(layer "F.Cu")
		(net "USB2_8_DP")
	)
	(segment
		(start 354.795328 -34.456624)
		(end 353.13112 -36.120832)
		(width 0.13208)
		(layer "F.Cu")
		(net "USB2_8_DP")
	)
	(segment
		(start 346.655136 -41.749726)
		(end 346.509086 -41.623488)
		(width 0.0889)
		(layer "F.Cu")
		(net "USB2_8_DP")
	)
	(segment
		(start 357.67264 -34.67481)
		(end 357.454454 -34.456624)
		(width 0.13208)
		(layer "F.Cu")
		(net "USB2_8_DP")
	)
	(segment
		(start 347.14688 -41.63822)
		(end 346.87764 -41.749726)
		(width 0.0889)
		(layer "F.Cu")
		(net "USB2_8_DP")
	)
	(segment
		(start 346.244672 -41.446958)
		(end 345.96959 -41.446958)
		(width 0.0889)
		(layer "F.Cu")
		(net "USB2_8_DP")
	)
	(segment
		(start 353.13112 -36.120832)
		(end 351.93986 -36.120832)
		(width 0.13208)
		(layer "F.Cu")
		(net "USB2_8_DP")
	)
	(segment
		(start 347.897704 -41.63822)
		(end 347.14688 -41.63822)
		(width 0.0889)
		(layer "F.Cu")
		(net "USB2_8_DP")
	)
	(segment
		(start 348.84487 -41.439846)
		(end 348.096078 -41.439846)
		(width 0.0889)
		(layer "F.Cu")
		(net "USB2_8_DP")
	)
	(segment
		(start 350.644714 -38.326314)
		(end 350.610424 -38.360604)
		(width 0.0889)
		(layer "F.Cu")
		(net "USB2_8_DP")
	)
	(segment
		(start 139.946888 -17.074642)
		(end 139.772136 -17.249394)
		(width 0.12954)
		(layer "F.Cu")
		(net "USB2_8_DP")
	)
	(segment
		(start 350.610424 -38.360604)
		(end 350.610424 -38.977824)
		(width 0.0889)
		(layer "F.Cu")
		(net "USB2_8_DP")
	)
	(segment
		(start 139.772136 -17.249394)
		(end 139.772136 -17.254474)
		(width 0.12954)
		(layer "F.Cu")
		(net "USB2_8_DP")
	)
	(segment
		(start 346.87764 -41.749726)
		(end 346.655136 -41.749726)
		(width 0.0889)
		(layer "F.Cu")
		(net "USB2_8_DP")
	)
	(segment
		(start 139.772136 -17.254474)
		(end 139.772136 -19.859244)
		(width 0.13208)
		(layer "F.Cu")
		(net "USB2_8_DP")
	)
	(segment
		(start 139.772136 -19.859244)
		(end 140.07338 -20.160488)
		(width 0.13208)
		(layer "F.Cu")
		(net "USB2_8_DP")
	)
	(segment
		(start 350.61017 -39.674546)
		(end 348.84487 -41.439846)
		(width 0.0889)
		(layer "F.Cu")
		(net "USB2_8_DP")
	)
	(segment
		(start 351.93986 -36.120832)
		(end 350.644714 -37.415978)
		(width 0.13208)
		(layer "F.Cu")
		(net "USB2_8_DP")
	)
	(segment
		(start 357.37038 -35.240468)
		(end 357.67264 -34.938208)
		(width 0.13208)
		(layer "F.Cu")
		(net "USB2_8_DP")
	)
	(via
		(at 140.07338 -20.160488)
		(size 0.508)
		(drill 0.254)
		(layers "F.Cu" "B.Cu")
		(net "USB2_8_DP")
	)
	(via
		(at 357.37038 -35.240468)
		(size 0.508)
		(drill 0.254)
		(layers "F.Cu" "B.Cu")
		(net "USB2_8_DP")
	)
	(segment
		(start 353.40925 -38.335458)
		(end 352.304858 -38.792658)
		(width 0.13208)
		(layer "B.Cu")
		(net "USB2_8_DP")
	)
	(segment
		(start 161.760916 -34.512504)
		(end 160.715706 -33.467294)
		(width 0.13208)
		(layer "B.Cu")
		(net "USB2_8_DP")
	)
	(segment
		(start 141.121638 -22.063964)
		(end 139.77112 -20.713446)
		(width 0.13208)
		(layer "B.Cu")
		(net "USB2_8_DP")
	)
	(segment
		(start 144.200626 -24.433022)
		(end 144.029176 -24.45004)
		(width 0.13208)
		(layer "B.Cu")
		(net "USB2_8_DP")
	)
	(segment
		(start 144.029176 -24.45004)
		(end 144.029176 -24.449786)
		(width 0.13208)
		(layer "B.Cu")
		(net "USB2_8_DP")
	)
	(segment
		(start 281.676348 -84.077048)
		(end 250.127262 -84.077048)
		(width 0.13208)
		(layer "B.Cu")
		(net "USB2_8_DP")
	)
	(segment
		(start 356.433628 -81.24952)
		(end 346.909898 -90.77325)
		(width 0.13208)
		(layer "B.Cu")
		(net "USB2_8_DP")
	)
	(segment
		(start 143.27378 -23.672292)
		(end 143.10233 -23.68931)
		(width 0.13208)
		(layer "B.Cu")
		(net "USB2_8_DP")
	)
	(segment
		(start 354.991416 -37.547804)
		(end 354.62972 -37.697664)
		(width 0.13208)
		(layer "B.Cu")
		(net "USB2_8_DP")
	)
	(segment
		(start 143.593312 -24.092408)
		(end 143.576548 -23.920704)
		(width 0.13208)
		(layer "B.Cu")
		(net "USB2_8_DP")
	)
	(segment
		(start 329.539346 -86.200488)
		(end 286.80283 -86.200488)
		(width 0.13208)
		(layer "B.Cu")
		(net "USB2_8_DP")
	)
	(segment
		(start 144.503394 -24.681434)
		(end 144.200626 -24.433022)
		(width 0.13208)
		(layer "B.Cu")
		(net "USB2_8_DP")
	)
	(segment
		(start 145.465546 -25.628854)
		(end 145.448528 -25.45715)
		(width 0.13208)
		(layer "B.Cu")
		(net "USB2_8_DP")
	)
	(segment
		(start 220.524324 -66.11366)
		(end 220.52407 -66.113406)
		(width 0.13208)
		(layer "B.Cu")
		(net "USB2_8_DP")
	)
	(segment
		(start 348.929452 -49.345088)
		(end 360.75874 -49.345088)
		(width 0.13208)
		(layer "B.Cu")
		(net "USB2_8_DP")
	)
	(segment
		(start 145.14576 -25.208738)
		(end 144.97431 -25.225756)
		(width 0.13208)
		(layer "B.Cu")
		(net "USB2_8_DP")
	)
	(segment
		(start 175.519842 -53.860446)
		(end 173.50105 -48.986694)
		(width 0.13208)
		(layer "B.Cu")
		(net "USB2_8_DP")
	)
	(segment
		(start 360.006392 -64.551052)
		(end 360.006392 -72.624442)
		(width 0.13208)
		(layer "B.Cu")
		(net "USB2_8_DP")
	)
	(segment
		(start 151.120602 -29.357574)
		(end 150.721314 -29.19222)
		(width 0.13208)
		(layer "B.Cu")
		(net "USB2_8_DP")
	)
	(segment
		(start 142.691612 -23.194518)
		(end 142.388844 -22.946106)
		(width 0.13208)
		(layer "B.Cu")
		(net "USB2_8_DP")
	)
	(segment
		(start 346.38488 -46.800516)
		(end 348.929452 -49.345088)
		(width 0.13208)
		(layer "B.Cu")
		(net "USB2_8_DP")
	)
	(segment
		(start 224.970594 -67.95516)
		(end 220.524324 -66.11366)
		(width 0.13208)
		(layer "B.Cu")
		(net "USB2_8_DP")
	)
	(segment
		(start 354.563934 -37.857176)
		(end 353.996244 -38.092126)
		(width 0.13208)
		(layer "B.Cu")
		(net "USB2_8_DP")
	)
	(segment
		(start 142.217394 -22.96287)
		(end 141.121638 -22.063964)
		(width 0.13208)
		(layer "B.Cu")
		(net "USB2_8_DP")
	)
	(segment
		(start 173.50105 -48.986694)
		(end 163.69411 -39.179754)
		(width 0.13208)
		(layer "B.Cu")
		(net "USB2_8_DP")
	)
	(segment
		(start 139.77112 -20.462748)
		(end 140.07338 -20.160488)
		(width 0.13208)
		(layer "B.Cu")
		(net "USB2_8_DP")
	)
	(segment
		(start 354.62972 -37.697664)
		(end 354.563934 -37.857176)
		(width 0.13208)
		(layer "B.Cu")
		(net "USB2_8_DP")
	)
	(segment
		(start 143.593312 -24.092154)
		(end 143.593312 -24.092408)
		(width 0.13208)
		(layer "B.Cu")
		(net "USB2_8_DP")
	)
	(segment
		(start 220.52407 -66.113406)
		(end 215.982042 -64.232028)
		(width 0.13208)
		(layer "B.Cu")
		(net "USB2_8_DP")
	)
	(segment
		(start 160.715706 -33.467294)
		(end 151.187912 -29.520388)
		(width 0.13208)
		(layer "B.Cu")
		(net "USB2_8_DP")
	)
	(segment
		(start 353.996244 -38.092126)
		(end 353.836986 -38.026086)
		(width 0.13208)
		(layer "B.Cu")
		(net "USB2_8_DP")
	)
	(segment
		(start 345.703652 -91.272868)
		(end 341.784686 -91.272868)
		(width 0.13208)
		(layer "B.Cu")
		(net "USB2_8_DP")
	)
	(segment
		(start 366.492028 -57.233312)
		(end 363.337602 -59.822334)
		(width 0.13208)
		(layer "B.Cu")
		(net "USB2_8_DP")
	)
	(segment
		(start 351.783904 -38.876478)
		(end 351.717864 -39.03599)
		(width 0.13208)
		(layer "B.Cu")
		(net "USB2_8_DP")
	)
	(segment
		(start 231.39908 -72.154288)
		(end 227.593652 -70.578218)
		(width 0.13208)
		(layer "B.Cu")
		(net "USB2_8_DP")
	)
	(segment
		(start 142.708376 -23.365968)
		(end 142.691612 -23.194518)
		(width 0.13208)
		(layer "B.Cu")
		(net "USB2_8_DP")
	)
	(segment
		(start 148.413978 -28.04795)
		(end 145.465546 -25.628854)
		(width 0.13208)
		(layer "B.Cu")
		(net "USB2_8_DP")
	)
	(segment
		(start 250.127262 -84.077048)
		(end 240.697258 -74.647044)
		(width 0.13208)
		(layer "B.Cu")
		(net "USB2_8_DP")
	)
	(segment
		(start 355.577902 -37.304726)
		(end 355.511862 -37.464238)
		(width 0.13208)
		(layer "B.Cu")
		(net "USB2_8_DP")
	)
	(segment
		(start 357.67264 -36.129976)
		(end 356.922578 -36.880038)
		(width 0.13208)
		(layer "B.Cu")
		(net "USB2_8_DP")
	)
	(segment
		(start 355.939598 -37.15512)
		(end 355.577902 -37.304726)
		(width 0.13208)
		(layer "B.Cu")
		(net "USB2_8_DP")
	)
	(segment
		(start 351.717864 -39.03599)
		(end 349.527368 -39.943278)
		(width 0.13208)
		(layer "B.Cu")
		(net "USB2_8_DP")
	)
	(segment
		(start 360.006392 -72.624442)
		(end 356.433628 -81.24952)
		(width 0.13208)
		(layer "B.Cu")
		(net "USB2_8_DP")
	)
	(segment
		(start 357.37038 -35.240468)
		(end 357.67264 -35.542728)
		(width 0.13208)
		(layer "B.Cu")
		(net "USB2_8_DP")
	)
	(segment
		(start 178.642772 -56.571388)
		(end 177.939446 -56.28005)
		(width 0.13208)
		(layer "B.Cu")
		(net "USB2_8_DP")
	)
	(segment
		(start 215.982042 -64.232028)
		(end 201.751692 -64.232028)
		(width 0.13208)
		(layer "B.Cu")
		(net "USB2_8_DP")
	)
	(segment
		(start 201.751692 -64.232028)
		(end 197.43801 -62.92342)
		(width 0.13208)
		(layer "B.Cu")
		(net "USB2_8_DP")
	)
	(segment
		(start 353.836986 -38.026086)
		(end 353.47529 -38.175946)
		(width 0.13208)
		(layer "B.Cu")
		(net "USB2_8_DP")
	)
	(segment
		(start 360.75874 -49.345088)
		(end 366.84204 -55.428388)
		(width 0.13208)
		(layer "B.Cu")
		(net "USB2_8_DP")
	)
	(segment
		(start 237.710726 -73.410064)
		(end 231.39908 -72.154288)
		(width 0.13208)
		(layer "B.Cu")
		(net "USB2_8_DP")
	)
	(segment
		(start 353.47529 -38.175946)
		(end 353.40925 -38.335458)
		(width 0.13208)
		(layer "B.Cu")
		(net "USB2_8_DP")
	)
	(segment
		(start 355.511862 -37.464238)
		(end 355.150674 -37.613844)
		(width 0.13208)
		(layer "B.Cu")
		(net "USB2_8_DP")
	)
	(segment
		(start 363.337602 -59.822334)
		(end 360.994706 -62.16523)
		(width 0.13208)
		(layer "B.Cu")
		(net "USB2_8_DP")
	)
	(segment
		(start 286.80283 -86.200488)
		(end 281.676348 -84.077048)
		(width 0.13208)
		(layer "B.Cu")
		(net "USB2_8_DP")
	)
	(segment
		(start 150.558754 -29.25953)
		(end 150.159974 -29.09443)
		(width 0.13208)
		(layer "B.Cu")
		(net "USB2_8_DP")
	)
	(segment
		(start 240.697258 -74.647044)
		(end 237.710726 -73.410064)
		(width 0.13208)
		(layer "B.Cu")
		(net "USB2_8_DP")
	)
	(segment
		(start 142.388844 -22.946106)
		(end 142.217394 -22.96287)
		(width 0.13208)
		(layer "B.Cu")
		(net "USB2_8_DP")
	)
	(segment
		(start 227.593652 -70.578218)
		(end 224.970594 -67.95516)
		(width 0.13208)
		(layer "B.Cu")
		(net "USB2_8_DP")
	)
	(segment
		(start 145.448528 -25.45715)
		(end 145.14576 -25.208738)
		(width 0.13208)
		(layer "B.Cu")
		(net "USB2_8_DP")
	)
	(segment
		(start 355.150674 -37.613844)
		(end 354.991416 -37.547804)
		(width 0.13208)
		(layer "B.Cu")
		(net "USB2_8_DP")
	)
	(segment
		(start 190.71971 -58.434732)
		(end 189.651894 -57.86374)
		(width 0.13208)
		(layer "B.Cu")
		(net "USB2_8_DP")
	)
	(segment
		(start 144.974564 -25.225502)
		(end 144.520412 -24.852884)
		(width 0.13208)
		(layer "B.Cu")
		(net "USB2_8_DP")
	)
	(segment
		(start 139.77112 -20.713446)
		(end 139.77112 -20.462748)
		(width 0.13208)
		(layer "B.Cu")
		(net "USB2_8_DP")
	)
	(segment
		(start 144.029176 -24.449786)
		(end 143.593312 -24.092154)
		(width 0.13208)
		(layer "B.Cu")
		(net "USB2_8_DP")
	)
	(segment
		(start 349.527368 -39.943278)
		(end 346.38488 -43.085766)
		(width 0.13208)
		(layer "B.Cu")
		(net "USB2_8_DP")
	)
	(segment
		(start 356.098856 -37.22116)
		(end 355.939598 -37.15512)
		(width 0.13208)
		(layer "B.Cu")
		(net "USB2_8_DP")
	)
	(segment
		(start 144.520158 -24.853138)
		(end 144.503394 -24.681434)
		(width 0.13208)
		(layer "B.Cu")
		(net "USB2_8_DP")
	)
	(segment
		(start 197.43801 -62.92342)
		(end 190.71971 -58.434732)
		(width 0.13208)
		(layer "B.Cu")
		(net "USB2_8_DP")
	)
	(segment
		(start 150.721314 -29.19222)
		(end 150.558754 -29.25953)
		(width 0.13208)
		(layer "B.Cu")
		(net "USB2_8_DP")
	)
	(segment
		(start 143.576548 -23.920704)
		(end 143.27378 -23.672292)
		(width 0.13208)
		(layer "B.Cu")
		(net "USB2_8_DP")
	)
	(segment
		(start 366.84204 -56.709564)
		(end 366.492028 -57.233312)
		(width 0.13208)
		(layer "B.Cu")
		(net "USB2_8_DP")
	)
	(segment
		(start 366.84204 -55.428388)
		(end 366.84204 -56.709564)
		(width 0.13208)
		(layer "B.Cu")
		(net "USB2_8_DP")
	)
	(segment
		(start 352.1456 -38.726872)
		(end 351.783904 -38.876478)
		(width 0.13208)
		(layer "B.Cu")
		(net "USB2_8_DP")
	)
	(segment
		(start 151.187912 -29.520388)
		(end 151.120602 -29.357574)
		(width 0.13208)
		(layer "B.Cu")
		(net "USB2_8_DP")
	)
	(segment
		(start 144.97431 -25.225756)
		(end 144.974564 -25.225502)
		(width 0.13208)
		(layer "B.Cu")
		(net "USB2_8_DP")
	)
	(segment
		(start 150.159974 -29.09443)
		(end 148.413978 -28.04795)
		(width 0.13208)
		(layer "B.Cu")
		(net "USB2_8_DP")
	)
	(segment
		(start 341.784686 -91.272868)
		(end 329.539346 -86.200488)
		(width 0.13208)
		(layer "B.Cu")
		(net "USB2_8_DP")
	)
	(segment
		(start 186.532266 -56.571388)
		(end 178.642772 -56.571388)
		(width 0.13208)
		(layer "B.Cu")
		(net "USB2_8_DP")
	)
	(segment
		(start 144.520412 -24.852884)
		(end 144.520158 -24.853138)
		(width 0.13208)
		(layer "B.Cu")
		(net "USB2_8_DP")
	)
	(segment
		(start 346.909898 -90.77325)
		(end 345.703652 -91.272868)
		(width 0.13208)
		(layer "B.Cu")
		(net "USB2_8_DP")
	)
	(segment
		(start 346.38488 -43.085766)
		(end 346.38488 -46.800516)
		(width 0.13208)
		(layer "B.Cu")
		(net "USB2_8_DP")
	)
	(segment
		(start 352.304858 -38.792658)
		(end 352.1456 -38.726872)
		(width 0.13208)
		(layer "B.Cu")
		(net "USB2_8_DP")
	)
	(segment
		(start 360.994706 -62.16523)
		(end 360.006392 -64.551052)
		(width 0.13208)
		(layer "B.Cu")
		(net "USB2_8_DP")
	)
	(segment
		(start 143.10233 -23.68931)
		(end 142.708376 -23.365968)
		(width 0.13208)
		(layer "B.Cu")
		(net "USB2_8_DP")
	)
	(segment
		(start 357.67264 -35.542728)
		(end 357.67264 -36.129976)
		(width 0.13208)
		(layer "B.Cu")
		(net "USB2_8_DP")
	)
	(segment
		(start 189.651894 -57.86374)
		(end 186.532266 -56.571388)
		(width 0.13208)
		(layer "B.Cu")
		(net "USB2_8_DP")
	)
	(segment
		(start 356.922578 -36.880038)
		(end 356.098856 -37.22116)
		(width 0.13208)
		(layer "B.Cu")
		(net "USB2_8_DP")
	)
	(segment
		(start 163.69411 -39.179754)
		(end 161.760916 -34.512504)
		(width 0.13208)
		(layer "B.Cu")
		(net "USB2_8_DP")
	)
	(segment
		(start 177.939446 -56.28005)
		(end 175.519842 -53.860446)
		(width 0.13208)
		(layer "B.Cu")
		(net "USB2_8_DP")
	)
	(segment
		(start 139.513056 -19.857212)
		(end 139.20978 -20.160488)
		(width 0.13208)
		(layer "F.Cu")
		(net "USB2_8_DN")
	)
	(segment
		(start 347.14688 -41.446704)
		(end 346.799662 -41.446958)
		(width 0.0889)
		(layer "F.Cu")
		(net "USB2_8_DN")
	)
	(segment
		(start 347.323664 -41.447974)
		(end 347.322394 -41.446704)
		(width 0.0889)
		(layer "F.Cu")
		(net "USB2_8_DN")
	)
	(segment
		(start 348.891352 -40.983916)
		(end 348.891352 -41.124124)
		(width 0.0889)
		(layer "F.Cu")
		(net "USB2_8_DN")
	)
	(segment
		(start 348.570296 -41.2496)
		(end 348.47149 -41.150794)
		(width 0.0889)
		(layer "F.Cu")
		(net "USB2_8_DN")
	)
	(segment
		(start 350.385634 -38.304216)
		(end 350.385634 -38.326314)
		(width 0.0889)
		(layer "F.Cu")
		(net "USB2_8_DN")
	)
	(segment
		(start 350.419924 -38.360604)
		(end 350.419924 -39.04234)
		(width 0.0889)
		(layer "F.Cu")
		(net "USB2_8_DN")
	)
	(segment
		(start 349.017082 -40.858186)
		(end 348.891352 -40.983916)
		(width 0.0889)
		(layer "F.Cu")
		(net "USB2_8_DN")
	)
	(segment
		(start 139.34694 -16.550132)
		(end 139.34694 -17.088358)
		(width 0.13208)
		(layer "F.Cu")
		(net "USB2_8_DN")
	)
	(segment
		(start 348.017084 -41.2496)
		(end 347.81871 -41.447974)
		(width 0.0889)
		(layer "F.Cu")
		(net "USB2_8_DN")
	)
	(segment
		(start 349.67418 -40.341296)
		(end 349.548704 -40.466772)
		(width 0.0889)
		(layer "F.Cu")
		(net "USB2_8_DN")
	)
	(segment
		(start 350.321118 -39.318946)
		(end 350.419924 -39.417752)
		(width 0.0889)
		(layer "F.Cu")
		(net "USB2_8_DN")
	)
	(segment
		(start 350.385634 -37.308536)
		(end 350.385634 -38.304216)
		(width 0.13208)
		(layer "F.Cu")
		(net "USB2_8_DN")
	)
	(segment
		(start 350.419924 -39.595552)
		(end 349.940118 -40.075358)
		(width 0.0889)
		(layer "F.Cu")
		(net "USB2_8_DN")
	)
	(segment
		(start 353.023678 -35.861752)
		(end 351.832418 -35.861752)
		(width 0.13208)
		(layer "F.Cu")
		(net "USB2_8_DN")
	)
	(segment
		(start 349.282766 -40.73271)
		(end 349.15729 -40.858186)
		(width 0.0889)
		(layer "F.Cu")
		(net "USB2_8_DN")
	)
	(segment
		(start 349.282766 -40.592502)
		(end 349.282766 -40.73271)
		(width 0.0889)
		(layer "F.Cu")
		(net "USB2_8_DN")
	)
	(segment
		(start 348.194884 -41.2496)
		(end 348.017084 -41.2496)
		(width 0.0889)
		(layer "F.Cu")
		(net "USB2_8_DN")
	)
	(segment
		(start 348.891352 -41.124124)
		(end 348.765876 -41.2496)
		(width 0.0889)
		(layer "F.Cu")
		(net "USB2_8_DN")
	)
	(segment
		(start 350.321118 -39.141146)
		(end 350.321118 -39.318946)
		(width 0.0889)
		(layer "F.Cu")
		(net "USB2_8_DN")
	)
	(segment
		(start 347.322394 -41.446704)
		(end 347.14688 -41.446704)
		(width 0.0889)
		(layer "F.Cu")
		(net "USB2_8_DN")
	)
	(segment
		(start 349.408496 -40.466772)
		(end 349.282766 -40.592502)
		(width 0.0889)
		(layer "F.Cu")
		(net "USB2_8_DN")
	)
	(segment
		(start 354.687886 -34.197544)
		(end 353.023678 -35.861752)
		(width 0.13208)
		(layer "F.Cu")
		(net "USB2_8_DN")
	)
	(segment
		(start 357.93172 -34.938208)
		(end 357.93172 -34.567368)
		(width 0.13208)
		(layer "F.Cu")
		(net "USB2_8_DN")
	)
	(segment
		(start 349.79991 -40.075358)
		(end 349.67418 -40.201088)
		(width 0.0889)
		(layer "F.Cu")
		(net "USB2_8_DN")
	)
	(segment
		(start 139.34694 -17.088358)
		(end 139.513056 -17.254474)
		(width 0.12954)
		(layer "F.Cu")
		(net "USB2_8_DN")
	)
	(segment
		(start 139.513056 -17.254474)
		(end 139.513056 -19.857212)
		(width 0.13208)
		(layer "F.Cu")
		(net "USB2_8_DN")
	)
	(segment
		(start 349.940118 -40.075358)
		(end 349.79991 -40.075358)
		(width 0.0889)
		(layer "F.Cu")
		(net "USB2_8_DN")
	)
	(segment
		(start 347.81871 -41.447974)
		(end 347.323664 -41.447974)
		(width 0.0889)
		(layer "F.Cu")
		(net "USB2_8_DN")
	)
	(segment
		(start 350.419924 -39.04234)
		(end 350.321118 -39.141146)
		(width 0.0889)
		(layer "F.Cu")
		(net "USB2_8_DN")
	)
	(segment
		(start 357.93172 -34.567368)
		(end 357.561896 -34.197544)
		(width 0.13208)
		(layer "F.Cu")
		(net "USB2_8_DN")
	)
	(segment
		(start 349.67418 -40.201088)
		(end 349.67418 -40.341296)
		(width 0.0889)
		(layer "F.Cu")
		(net "USB2_8_DN")
	)
	(segment
		(start 350.385634 -38.326314)
		(end 350.419924 -38.360604)
		(width 0.0889)
		(layer "F.Cu")
		(net "USB2_8_DN")
	)
	(segment
		(start 349.548704 -40.466772)
		(end 349.408496 -40.466772)
		(width 0.0889)
		(layer "F.Cu")
		(net "USB2_8_DN")
	)
	(segment
		(start 350.419924 -39.417752)
		(end 350.419924 -39.595552)
		(width 0.0889)
		(layer "F.Cu")
		(net "USB2_8_DN")
	)
	(segment
		(start 348.765876 -41.2496)
		(end 348.570296 -41.2496)
		(width 0.0889)
		(layer "F.Cu")
		(net "USB2_8_DN")
	)
	(segment
		(start 351.832418 -35.861752)
		(end 350.385634 -37.308536)
		(width 0.13208)
		(layer "F.Cu")
		(net "USB2_8_DN")
	)
	(segment
		(start 348.47149 -41.150794)
		(end 348.29369 -41.150794)
		(width 0.0889)
		(layer "F.Cu")
		(net "USB2_8_DN")
	)
	(segment
		(start 349.15729 -40.858186)
		(end 349.017082 -40.858186)
		(width 0.0889)
		(layer "F.Cu")
		(net "USB2_8_DN")
	)
	(segment
		(start 348.29369 -41.150794)
		(end 348.194884 -41.2496)
		(width 0.0889)
		(layer "F.Cu")
		(net "USB2_8_DN")
	)
	(segment
		(start 357.561896 -34.197544)
		(end 354.687886 -34.197544)
		(width 0.13208)
		(layer "F.Cu")
		(net "USB2_8_DN")
	)
	(segment
		(start 358.23398 -35.240468)
		(end 357.93172 -34.938208)
		(width 0.13208)
		(layer "F.Cu")
		(net "USB2_8_DN")
	)
	(via
		(at 139.20978 -20.160488)
		(size 0.508)
		(drill 0.254)
		(layers "F.Cu" "B.Cu")
		(net "USB2_8_DN")
	)
	(via
		(at 358.23398 -35.240468)
		(size 0.508)
		(drill 0.254)
		(layers "F.Cu" "B.Cu")
		(net "USB2_8_DN")
	)
	(segment
		(start 346.64396 -43.193208)
		(end 346.64396 -46.693074)
		(width 0.13208)
		(layer "B.Cu")
		(net "USB2_8_DN")
	)
	(segment
		(start 237.635034 -73.659238)
		(end 231.323388 -72.403462)
		(width 0.13208)
		(layer "B.Cu")
		(net "USB2_8_DN")
	)
	(segment
		(start 140.947394 -22.256242)
		(end 139.51204 -20.820888)
		(width 0.13208)
		(layer "B.Cu")
		(net "USB2_8_DN")
	)
	(segment
		(start 161.541206 -34.659316)
		(end 160.568894 -33.687004)
		(width 0.13208)
		(layer "B.Cu")
		(net "USB2_8_DN")
	)
	(segment
		(start 220.377258 -66.333116)
		(end 215.93048 -64.491108)
		(width 0.13208)
		(layer "B.Cu")
		(net "USB2_8_DN")
	)
	(segment
		(start 356.653338 -81.396332)
		(end 347.05671 -90.99296)
		(width 0.13208)
		(layer "B.Cu")
		(net "USB2_8_DN")
	)
	(segment
		(start 341.733124 -91.531948)
		(end 329.487784 -86.459568)
		(width 0.13208)
		(layer "B.Cu")
		(net "USB2_8_DN")
	)
	(segment
		(start 224.823782 -68.17487)
		(end 220.377512 -66.33337)
		(width 0.13208)
		(layer "B.Cu")
		(net "USB2_8_DN")
	)
	(segment
		(start 173.28134 -49.133506)
		(end 163.4744 -39.326566)
		(width 0.13208)
		(layer "B.Cu")
		(net "USB2_8_DN")
	)
	(segment
		(start 139.51204 -20.820888)
		(end 139.51204 -20.462748)
		(width 0.13208)
		(layer "B.Cu")
		(net "USB2_8_DN")
	)
	(segment
		(start 150.043134 -29.326586)
		(end 148.264372 -28.260548)
		(width 0.13208)
		(layer "B.Cu")
		(net "USB2_8_DN")
	)
	(segment
		(start 160.568894 -33.687004)
		(end 150.043134 -29.326586)
		(width 0.13208)
		(layer "B.Cu")
		(net "USB2_8_DN")
	)
	(segment
		(start 346.64396 -46.693074)
		(end 349.036894 -49.086008)
		(width 0.13208)
		(layer "B.Cu")
		(net "USB2_8_DN")
	)
	(segment
		(start 358.23398 -35.240468)
		(end 357.93172 -35.542728)
		(width 0.13208)
		(layer "B.Cu")
		(net "USB2_8_DN")
	)
	(segment
		(start 175.300132 -54.007258)
		(end 173.28134 -49.133506)
		(width 0.13208)
		(layer "B.Cu")
		(net "USB2_8_DN")
	)
	(segment
		(start 215.93048 -64.491108)
		(end 201.713084 -64.491108)
		(width 0.13208)
		(layer "B.Cu")
		(net "USB2_8_DN")
	)
	(segment
		(start 186.480704 -56.830468)
		(end 178.590956 -56.830468)
		(width 0.13208)
		(layer "B.Cu")
		(net "USB2_8_DN")
	)
	(segment
		(start 220.377512 -66.33337)
		(end 220.377258 -66.333116)
		(width 0.13208)
		(layer "B.Cu")
		(net "USB2_8_DN")
	)
	(segment
		(start 250.01982 -84.336128)
		(end 240.550446 -74.866754)
		(width 0.13208)
		(layer "B.Cu")
		(net "USB2_8_DN")
	)
	(segment
		(start 240.550446 -74.866754)
		(end 237.635034 -73.659238)
		(width 0.13208)
		(layer "B.Cu")
		(net "USB2_8_DN")
	)
	(segment
		(start 356.197916 -37.460936)
		(end 354.663248 -38.096444)
		(width 0.13208)
		(layer "B.Cu")
		(net "USB2_8_DN")
	)
	(segment
		(start 178.590956 -56.830468)
		(end 177.792634 -56.49976)
		(width 0.13208)
		(layer "B.Cu")
		(net "USB2_8_DN")
	)
	(segment
		(start 367.10112 -55.320946)
		(end 367.10112 -56.788304)
		(width 0.13208)
		(layer "B.Cu")
		(net "USB2_8_DN")
	)
	(segment
		(start 329.487784 -86.459568)
		(end 286.751268 -86.459568)
		(width 0.13208)
		(layer "B.Cu")
		(net "USB2_8_DN")
	)
	(segment
		(start 197.325996 -63.160402)
		(end 190.58636 -58.657236)
		(width 0.13208)
		(layer "B.Cu")
		(net "USB2_8_DN")
	)
	(segment
		(start 361.214416 -62.312042)
		(end 360.265472 -64.602614)
		(width 0.13208)
		(layer "B.Cu")
		(net "USB2_8_DN")
	)
	(segment
		(start 347.05671 -90.99296)
		(end 345.755214 -91.531948)
		(width 0.13208)
		(layer "B.Cu")
		(net "USB2_8_DN")
	)
	(segment
		(start 145.21815 -25.760426)
		(end 140.947394 -22.256242)
		(width 0.13208)
		(layer "B.Cu")
		(net "USB2_8_DN")
	)
	(segment
		(start 354.663248 -38.096444)
		(end 354.66274 -38.096698)
		(width 0.13208)
		(layer "B.Cu")
		(net "USB2_8_DN")
	)
	(segment
		(start 360.265472 -72.676004)
		(end 356.653338 -81.396332)
		(width 0.13208)
		(layer "B.Cu")
		(net "USB2_8_DN")
	)
	(segment
		(start 227.44684 -70.797928)
		(end 224.823782 -68.17487)
		(width 0.13208)
		(layer "B.Cu")
		(net "USB2_8_DN")
	)
	(segment
		(start 148.264372 -28.260548)
		(end 145.21815 -25.761188)
		(width 0.13208)
		(layer "B.Cu")
		(net "USB2_8_DN")
	)
	(segment
		(start 190.58636 -58.657236)
		(end 189.540896 -58.098436)
		(width 0.13208)
		(layer "B.Cu")
		(net "USB2_8_DN")
	)
	(segment
		(start 139.51204 -20.462748)
		(end 139.20978 -20.160488)
		(width 0.13208)
		(layer "B.Cu")
		(net "USB2_8_DN")
	)
	(segment
		(start 345.755214 -91.531948)
		(end 341.733124 -91.531948)
		(width 0.13208)
		(layer "B.Cu")
		(net "USB2_8_DN")
	)
	(segment
		(start 360.265472 -64.602614)
		(end 360.265472 -72.676004)
		(width 0.13208)
		(layer "B.Cu")
		(net "USB2_8_DN")
	)
	(segment
		(start 177.792634 -56.49976)
		(end 175.300132 -54.007258)
		(width 0.13208)
		(layer "B.Cu")
		(net "USB2_8_DN")
	)
	(segment
		(start 366.686338 -57.409334)
		(end 363.511846 -60.014612)
		(width 0.13208)
		(layer "B.Cu")
		(net "USB2_8_DN")
	)
	(segment
		(start 357.06939 -37.099748)
		(end 356.197916 -37.460682)
		(width 0.13208)
		(layer "B.Cu")
		(net "USB2_8_DN")
	)
	(segment
		(start 231.323388 -72.403462)
		(end 227.44684 -70.797928)
		(width 0.13208)
		(layer "B.Cu")
		(net "USB2_8_DN")
	)
	(segment
		(start 363.511846 -60.014612)
		(end 361.214416 -62.312042)
		(width 0.13208)
		(layer "B.Cu")
		(net "USB2_8_DN")
	)
	(segment
		(start 201.713084 -64.491108)
		(end 197.325996 -63.160402)
		(width 0.13208)
		(layer "B.Cu")
		(net "USB2_8_DN")
	)
	(segment
		(start 356.197916 -37.460682)
		(end 356.197916 -37.460936)
		(width 0.13208)
		(layer "B.Cu")
		(net "USB2_8_DN")
	)
	(segment
		(start 189.540896 -58.098436)
		(end 186.480704 -56.830468)
		(width 0.13208)
		(layer "B.Cu")
		(net "USB2_8_DN")
	)
	(segment
		(start 145.21815 -25.761188)
		(end 145.21815 -25.760426)
		(width 0.13208)
		(layer "B.Cu")
		(net "USB2_8_DN")
	)
	(segment
		(start 281.624786 -84.336128)
		(end 250.01982 -84.336128)
		(width 0.13208)
		(layer "B.Cu")
		(net "USB2_8_DN")
	)
	(segment
		(start 357.93172 -36.237418)
		(end 357.06939 -37.099748)
		(width 0.13208)
		(layer "B.Cu")
		(net "USB2_8_DN")
	)
	(segment
		(start 349.036894 -49.086008)
		(end 360.866182 -49.086008)
		(width 0.13208)
		(layer "B.Cu")
		(net "USB2_8_DN")
	)
	(segment
		(start 163.4744 -39.326566)
		(end 161.541206 -34.659316)
		(width 0.13208)
		(layer "B.Cu")
		(net "USB2_8_DN")
	)
	(segment
		(start 357.93172 -35.542728)
		(end 357.93172 -36.237418)
		(width 0.13208)
		(layer "B.Cu")
		(net "USB2_8_DN")
	)
	(segment
		(start 360.866182 -49.086008)
		(end 367.10112 -55.320946)
		(width 0.13208)
		(layer "B.Cu")
		(net "USB2_8_DN")
	)
	(segment
		(start 286.751268 -86.459568)
		(end 281.624786 -84.336128)
		(width 0.13208)
		(layer "B.Cu")
		(net "USB2_8_DN")
	)
	(segment
		(start 349.67418 -40.162988)
		(end 346.64396 -43.193208)
		(width 0.13208)
		(layer "B.Cu")
		(net "USB2_8_DN")
	)
	(segment
		(start 367.10112 -56.788304)
		(end 366.686338 -57.409334)
		(width 0.13208)
		(layer "B.Cu")
		(net "USB2_8_DN")
	)
	(segment
		(start 354.66274 -38.096698)
		(end 349.67418 -40.162988)
		(width 0.13208)
		(layer "B.Cu")
		(net "USB2_8_DN")
	)
	(segment
		(start 354.013516 -42.951654)
		(end 354.868988 -42.951654)
		(width 0.0889)
		(layer "F.Cu")
		(net "USB2_7_DP")
	)
	(segment
		(start 345.96959 -45.448728)
		(end 346.241116 -45.448728)
		(width 0.0889)
		(layer "F.Cu")
		(net "USB2_7_DP")
	)
	(segment
		(start 347.599254 -45.811948)
		(end 347.831918 -45.908214)
		(width 0.0889)
		(layer "F.Cu")
		(net "USB2_7_DP")
	)
	(segment
		(start 354.868988 -42.951654)
		(end 354.903278 -42.985944)
		(width 0.0889)
		(layer "F.Cu")
		(net "USB2_7_DP")
	)
	(segment
		(start 346.670122 -45.735748)
		(end 346.903802 -45.770546)
		(width 0.0889)
		(layer "F.Cu")
		(net "USB2_7_DP")
	)
	(segment
		(start 354.925376 -42.985944)
		(end 356.72014 -42.985944)
		(width 0.13208)
		(layer "F.Cu")
		(net "USB2_7_DP")
	)
	(segment
		(start 347.082872 -45.638466)
		(end 347.424248 -45.63745)
		(width 0.0889)
		(layer "F.Cu")
		(net "USB2_7_DP")
	)
	(segment
		(start 346.241116 -45.448728)
		(end 346.670122 -45.735748)
		(width 0.0889)
		(layer "F.Cu")
		(net "USB2_7_DP")
	)
	(segment
		(start 347.831918 -45.908214)
		(end 351.056956 -45.908214)
		(width 0.0889)
		(layer "F.Cu")
		(net "USB2_7_DP")
	)
	(segment
		(start 346.903802 -45.770546)
		(end 347.082872 -45.638466)
		(width 0.0889)
		(layer "F.Cu")
		(net "USB2_7_DP")
	)
	(segment
		(start 351.056956 -45.908214)
		(end 354.013516 -42.951654)
		(width 0.0889)
		(layer "F.Cu")
		(net "USB2_7_DP")
	)
	(segment
		(start 356.858062 -43.123866)
		(end 356.858062 -43.309286)
		(width 0.13208)
		(layer "F.Cu")
		(net "USB2_7_DP")
	)
	(segment
		(start 356.72014 -42.985944)
		(end 356.858062 -43.123866)
		(width 0.13208)
		(layer "F.Cu")
		(net "USB2_7_DP")
	)
	(segment
		(start 356.858062 -43.309286)
		(end 356.559612 -43.607736)
		(width 0.13208)
		(layer "F.Cu")
		(net "USB2_7_DP")
	)
	(segment
		(start 354.903278 -42.985944)
		(end 354.925376 -42.985944)
		(width 0.0889)
		(layer "F.Cu")
		(net "USB2_7_DP")
	)
	(segment
		(start 347.424248 -45.63745)
		(end 347.599254 -45.811948)
		(width 0.0889)
		(layer "F.Cu")
		(net "USB2_7_DP")
	)
	(via
		(at 356.559612 -43.607736)
		(size 0.508)
		(drill 0.254)
		(layers "F.Cu" "B.Cu")
		(net "USB2_7_DP")
	)
	(via
		(at 187.433966 -21.263356)
		(size 0.6604)
		(drill 0.3302)
		(layers "F.Cu" "B.Cu")
		(net "USB2_7_DP")
	)
	(segment
		(start 187.096654 -19.817842)
		(end 186.883294 -19.817842)
		(width 0.13208)
		(layer "B.Cu")
		(net "USB2_7_DP")
	)
	(segment
		(start 357.14559 -44.4881)
		(end 356.861872 -44.204382)
		(width 0.13208)
		(layer "B.Cu")
		(net "USB2_7_DP")
	)
	(segment
		(start 258.84759 -36.14039)
		(end 261.172706 -33.815274)
		(width 0.13208)
		(layer "B.Cu")
		(net "USB2_7_DP")
	)
	(segment
		(start 300.515528 -14.211554)
		(end 301.796704 -13.680948)
		(width 0.13208)
		(layer "B.Cu")
		(net "USB2_7_DP")
	)
	(segment
		(start 190.76543 -20.460716)
		(end 192.608454 -19.697192)
		(width 0.13208)
		(layer "B.Cu")
		(net "USB2_7_DP")
	)
	(segment
		(start 319.598548 -13.680948)
		(end 320.221102 -13.938758)
		(width 0.13208)
		(layer "B.Cu")
		(net "USB2_7_DP")
	)
	(segment
		(start 262.761476 -31.61665)
		(end 292.013386 -19.500088)
		(width 0.13208)
		(layer "B.Cu")
		(net "USB2_7_DP")
	)
	(segment
		(start 322.426076 -13.938758)
		(end 324.363842 -13.136118)
		(width 0.13208)
		(layer "B.Cu")
		(net "USB2_7_DP")
	)
	(segment
		(start 187.176156 -21.85162)
		(end 188.495686 -21.85162)
		(width 0.13208)
		(layer "B.Cu")
		(net "USB2_7_DP")
	)
	(segment
		(start 188.495686 -21.85162)
		(end 189.996064 -21.230082)
		(width 0.13208)
		(layer "B.Cu")
		(net "USB2_7_DP")
	)
	(segment
		(start 197.248018 -15.057628)
		(end 206.042514 -15.057628)
		(width 0.13208)
		(layer "B.Cu")
		(net "USB2_7_DP")
	)
	(segment
		(start 341.486236 -13.136118)
		(end 350.103694 -16.70558)
		(width 0.13208)
		(layer "B.Cu")
		(net "USB2_7_DP")
	)
	(segment
		(start 187.049156 -20.760182)
		(end 187.049156 -20.878546)
		(width 0.13208)
		(layer "B.Cu")
		(net "USB2_7_DP")
	)
	(segment
		(start 324.363842 -13.136118)
		(end 341.486236 -13.136118)
		(width 0.13208)
		(layer "B.Cu")
		(net "USB2_7_DP")
	)
	(segment
		(start 206.042514 -15.057628)
		(end 214.982298 -19.835876)
		(width 0.13208)
		(layer "B.Cu")
		(net "USB2_7_DP")
	)
	(segment
		(start 223.171004 -36.28517)
		(end 224.285048 -36.746688)
		(width 0.13208)
		(layer "B.Cu")
		(net "USB2_7_DP")
	)
	(segment
		(start 361.63504 -30.607762)
		(end 361.63504 -43.65371)
		(width 0.13208)
		(layer "B.Cu")
		(net "USB2_7_DP")
	)
	(segment
		(start 187.049156 -20.878546)
		(end 187.433966 -21.263356)
		(width 0.13208)
		(layer "B.Cu")
		(net "USB2_7_DP")
	)
	(segment
		(start 296.88155 -17.845532)
		(end 300.515528 -14.211554)
		(width 0.13208)
		(layer "B.Cu")
		(net "USB2_7_DP")
	)
	(segment
		(start 301.796704 -13.680948)
		(end 319.598548 -13.680948)
		(width 0.13208)
		(layer "B.Cu")
		(net "USB2_7_DP")
	)
	(segment
		(start 292.8874 -19.500088)
		(end 296.88155 -17.845532)
		(width 0.13208)
		(layer "B.Cu")
		(net "USB2_7_DP")
	)
	(segment
		(start 217.822018 -22.67585)
		(end 220.7768 -29.809694)
		(width 0.13208)
		(layer "B.Cu")
		(net "USB2_7_DP")
	)
	(segment
		(start 224.285048 -36.746688)
		(end 257.384804 -36.746688)
		(width 0.13208)
		(layer "B.Cu")
		(net "USB2_7_DP")
	)
	(segment
		(start 187.049156 -21.648166)
		(end 187.049156 -21.72462)
		(width 0.13208)
		(layer "B.Cu")
		(net "USB2_7_DP")
	)
	(segment
		(start 187.049156 -21.72462)
		(end 187.176156 -21.85162)
		(width 0.13208)
		(layer "B.Cu")
		(net "USB2_7_DP")
	)
	(segment
		(start 261.172706 -33.815274)
		(end 261.603744 -32.774382)
		(width 0.13208)
		(layer "B.Cu")
		(net "USB2_7_DP")
	)
	(segment
		(start 320.221102 -13.938758)
		(end 322.426076 -13.938758)
		(width 0.13208)
		(layer "B.Cu")
		(net "USB2_7_DP")
	)
	(segment
		(start 356.861872 -43.909996)
		(end 356.559612 -43.607736)
		(width 0.13208)
		(layer "B.Cu")
		(net "USB2_7_DP")
	)
	(segment
		(start 356.861872 -44.204382)
		(end 356.861872 -43.909996)
		(width 0.13208)
		(layer "B.Cu")
		(net "USB2_7_DP")
	)
	(segment
		(start 189.996064 -21.230082)
		(end 190.76543 -20.460716)
		(width 0.13208)
		(layer "B.Cu")
		(net "USB2_7_DP")
	)
	(segment
		(start 350.103694 -16.70558)
		(end 359.958386 -26.560272)
		(width 0.13208)
		(layer "B.Cu")
		(net "USB2_7_DP")
	)
	(segment
		(start 261.603744 -32.774382)
		(end 262.761476 -31.61665)
		(width 0.13208)
		(layer "B.Cu")
		(net "USB2_7_DP")
	)
	(segment
		(start 361.63504 -43.65371)
		(end 360.80065 -44.4881)
		(width 0.13208)
		(layer "B.Cu")
		(net "USB2_7_DP")
	)
	(segment
		(start 186.854338 -20.289774)
		(end 187.049156 -20.760182)
		(width 0.13208)
		(layer "B.Cu")
		(net "USB2_7_DP")
	)
	(segment
		(start 359.958386 -26.560272)
		(end 361.63504 -30.607762)
		(width 0.13208)
		(layer "B.Cu")
		(net "USB2_7_DP")
	)
	(segment
		(start 220.7768 -29.809694)
		(end 220.7768 -32.81172)
		(width 0.13208)
		(layer "B.Cu")
		(net "USB2_7_DP")
	)
	(segment
		(start 214.982298 -19.835876)
		(end 217.822018 -22.67585)
		(width 0.13208)
		(layer "B.Cu")
		(net "USB2_7_DP")
	)
	(segment
		(start 220.7768 -32.81172)
		(end 221.539816 -34.653982)
		(width 0.13208)
		(layer "B.Cu")
		(net "USB2_7_DP")
	)
	(segment
		(start 292.013386 -19.500088)
		(end 292.8874 -19.500088)
		(width 0.13208)
		(layer "B.Cu")
		(net "USB2_7_DP")
	)
	(segment
		(start 186.883294 -19.817842)
		(end 186.720226 -19.98091)
		(width 0.13208)
		(layer "B.Cu")
		(net "USB2_7_DP")
	)
	(segment
		(start 221.539816 -34.653982)
		(end 223.171004 -36.28517)
		(width 0.13208)
		(layer "B.Cu")
		(net "USB2_7_DP")
	)
	(segment
		(start 186.720226 -19.98091)
		(end 186.720226 -20.155662)
		(width 0.13208)
		(layer "B.Cu")
		(net "USB2_7_DP")
	)
	(segment
		(start 192.608454 -19.697192)
		(end 197.248018 -15.057628)
		(width 0.13208)
		(layer "B.Cu")
		(net "USB2_7_DP")
	)
	(segment
		(start 257.384804 -36.746688)
		(end 258.84759 -36.14039)
		(width 0.13208)
		(layer "B.Cu")
		(net "USB2_7_DP")
	)
	(segment
		(start 187.433966 -21.263356)
		(end 187.049156 -21.648166)
		(width 0.13208)
		(layer "B.Cu")
		(net "USB2_7_DP")
	)
	(segment
		(start 186.720226 -20.155662)
		(end 186.854338 -20.289774)
		(width 0.13208)
		(layer "B.Cu")
		(net "USB2_7_DP")
	)
	(segment
		(start 360.80065 -44.4881)
		(end 357.14559 -44.4881)
		(width 0.13208)
		(layer "B.Cu")
		(net "USB2_7_DP")
	)
	(segment
		(start 351.230438 -45.325284)
		(end 351.356168 -45.199554)
		(width 0.0889)
		(layer "F.Cu")
		(net "USB2_7_DN")
	)
	(segment
		(start 352.67011 -44.025566)
		(end 352.795586 -43.90009)
		(width 0.0889)
		(layer "F.Cu")
		(net "USB2_7_DN")
	)
	(segment
		(start 351.496376 -45.199554)
		(end 351.621852 -45.074078)
		(width 0.0889)
		(layer "F.Cu")
		(net "USB2_7_DN")
	)
	(segment
		(start 352.921316 -43.634152)
		(end 353.061778 -43.634152)
		(width 0.0889)
		(layer "F.Cu")
		(net "USB2_7_DN")
	)
	(segment
		(start 352.529902 -44.025566)
		(end 352.67011 -44.025566)
		(width 0.0889)
		(layer "F.Cu")
		(net "USB2_7_DN")
	)
	(segment
		(start 356.827582 -42.726864)
		(end 357.117142 -43.016424)
		(width 0.13208)
		(layer "F.Cu")
		(net "USB2_7_DN")
	)
	(segment
		(start 346.799662 -45.448728)
		(end 347.502988 -45.44695)
		(width 0.0889)
		(layer "F.Cu")
		(net "USB2_7_DN")
	)
	(segment
		(start 347.707712 -45.650658)
		(end 347.869764 -45.717968)
		(width 0.0889)
		(layer "F.Cu")
		(net "USB2_7_DN")
	)
	(segment
		(start 357.117142 -43.301666)
		(end 357.423212 -43.607736)
		(width 0.13208)
		(layer "F.Cu")
		(net "USB2_7_DN")
	)
	(segment
		(start 353.564698 -43.131232)
		(end 353.934522 -42.761408)
		(width 0.0889)
		(layer "F.Cu")
		(net "USB2_7_DN")
	)
	(segment
		(start 351.356168 -45.199554)
		(end 351.496376 -45.199554)
		(width 0.0889)
		(layer "F.Cu")
		(net "USB2_7_DN")
	)
	(segment
		(start 351.230438 -45.465492)
		(end 351.230438 -45.325284)
		(width 0.0889)
		(layer "F.Cu")
		(net "USB2_7_DN")
	)
	(segment
		(start 354.868734 -42.761408)
		(end 354.903278 -42.726864)
		(width 0.0889)
		(layer "F.Cu")
		(net "USB2_7_DN")
	)
	(segment
		(start 353.24669 -43.316398)
		(end 353.431856 -43.131232)
		(width 0.0889)
		(layer "F.Cu")
		(net "USB2_7_DN")
	)
	(segment
		(start 354.925376 -42.726864)
		(end 356.827582 -42.726864)
		(width 0.13208)
		(layer "F.Cu")
		(net "USB2_7_DN")
	)
	(segment
		(start 351.621852 -45.074078)
		(end 351.621852 -44.934124)
		(width 0.0889)
		(layer "F.Cu")
		(net "USB2_7_DN")
	)
	(segment
		(start 352.795586 -43.759882)
		(end 352.921316 -43.634152)
		(width 0.0889)
		(layer "F.Cu")
		(net "USB2_7_DN")
	)
	(segment
		(start 357.117142 -43.016424)
		(end 357.117142 -43.301666)
		(width 0.13208)
		(layer "F.Cu")
		(net "USB2_7_DN")
	)
	(segment
		(start 351.747328 -44.808394)
		(end 351.887536 -44.808394)
		(width 0.0889)
		(layer "F.Cu")
		(net "USB2_7_DN")
	)
	(segment
		(start 347.502988 -45.44695)
		(end 347.707712 -45.650658)
		(width 0.0889)
		(layer "F.Cu")
		(net "USB2_7_DN")
	)
	(segment
		(start 352.404172 -44.291504)
		(end 352.404172 -44.151296)
		(width 0.0889)
		(layer "F.Cu")
		(net "USB2_7_DN")
	)
	(segment
		(start 353.061778 -43.634152)
		(end 353.24669 -43.44924)
		(width 0.0889)
		(layer "F.Cu")
		(net "USB2_7_DN")
	)
	(segment
		(start 352.795586 -43.90009)
		(end 352.795586 -43.759882)
		(width 0.0889)
		(layer "F.Cu")
		(net "USB2_7_DN")
	)
	(segment
		(start 352.013012 -44.54271)
		(end 352.138742 -44.41698)
		(width 0.0889)
		(layer "F.Cu")
		(net "USB2_7_DN")
	)
	(segment
		(start 353.431856 -43.131232)
		(end 353.564698 -43.131232)
		(width 0.0889)
		(layer "F.Cu")
		(net "USB2_7_DN")
	)
	(segment
		(start 352.404172 -44.151296)
		(end 352.529902 -44.025566)
		(width 0.0889)
		(layer "F.Cu")
		(net "USB2_7_DN")
	)
	(segment
		(start 353.24669 -43.44924)
		(end 353.24669 -43.316398)
		(width 0.0889)
		(layer "F.Cu")
		(net "USB2_7_DN")
	)
	(segment
		(start 351.887536 -44.808394)
		(end 352.013012 -44.682664)
		(width 0.0889)
		(layer "F.Cu")
		(net "USB2_7_DN")
	)
	(segment
		(start 354.903278 -42.726864)
		(end 354.925376 -42.726864)
		(width 0.0889)
		(layer "F.Cu")
		(net "USB2_7_DN")
	)
	(segment
		(start 352.138742 -44.41698)
		(end 352.278696 -44.41698)
		(width 0.0889)
		(layer "F.Cu")
		(net "USB2_7_DN")
	)
	(segment
		(start 352.278696 -44.41698)
		(end 352.404172 -44.291504)
		(width 0.0889)
		(layer "F.Cu")
		(net "USB2_7_DN")
	)
	(segment
		(start 350.977962 -45.717968)
		(end 351.230438 -45.465492)
		(width 0.0889)
		(layer "F.Cu")
		(net "USB2_7_DN")
	)
	(segment
		(start 351.621852 -44.934124)
		(end 351.747328 -44.808394)
		(width 0.0889)
		(layer "F.Cu")
		(net "USB2_7_DN")
	)
	(segment
		(start 347.869764 -45.717968)
		(end 350.977962 -45.717968)
		(width 0.0889)
		(layer "F.Cu")
		(net "USB2_7_DN")
	)
	(segment
		(start 352.013012 -44.682664)
		(end 352.013012 -44.54271)
		(width 0.0889)
		(layer "F.Cu")
		(net "USB2_7_DN")
	)
	(segment
		(start 353.934522 -42.761408)
		(end 354.868734 -42.761408)
		(width 0.0889)
		(layer "F.Cu")
		(net "USB2_7_DN")
	)
	(via
		(at 186.405266 -21.250656)
		(size 0.6604)
		(drill 0.3302)
		(layers "F.Cu" "B.Cu")
		(net "USB2_7_DN")
	)
	(via
		(at 357.423212 -43.607736)
		(size 0.508)
		(drill 0.254)
		(layers "F.Cu" "B.Cu")
		(net "USB2_7_DN")
	)
	(segment
		(start 361.37596 -33.294828)
		(end 361.37596 -34.346388)
		(width 0.13208)
		(layer "B.Cu")
		(net "USB2_7_DN")
	)
	(segment
		(start 361.37596 -30.659578)
		(end 361.37596 -32.659828)
		(width 0.13208)
		(layer "B.Cu")
		(net "USB2_7_DN")
	)
	(segment
		(start 361.25404 -36.525708)
		(end 361.37596 -36.647628)
		(width 0.13208)
		(layer "B.Cu")
		(net "USB2_7_DN")
	)
	(segment
		(start 220.51772 -32.863282)
		(end 221.320106 -34.800794)
		(width 0.13208)
		(layer "B.Cu")
		(net "USB2_7_DN")
	)
	(segment
		(start 361.37596 -40.927528)
		(end 361.25404 -41.049448)
		(width 0.13208)
		(layer "B.Cu")
		(net "USB2_7_DN")
	)
	(segment
		(start 186.461146 -20.263104)
		(end 186.461146 -19.98091)
		(width 0.13208)
		(layer "B.Cu")
		(net "USB2_7_DN")
	)
	(segment
		(start 361.37596 -34.346388)
		(end 361.25404 -34.468308)
		(width 0.13208)
		(layer "B.Cu")
		(net "USB2_7_DN")
	)
	(segment
		(start 301.848266 -13.940028)
		(end 319.546986 -13.940028)
		(width 0.13208)
		(layer "B.Cu")
		(net "USB2_7_DN")
	)
	(segment
		(start 205.97749 -15.316708)
		(end 214.826088 -20.046442)
		(width 0.13208)
		(layer "B.Cu")
		(net "USB2_7_DN")
	)
	(segment
		(start 349.956882 -16.92529)
		(end 359.738676 -26.707084)
		(width 0.13208)
		(layer "B.Cu")
		(net "USB2_7_DN")
	)
	(segment
		(start 186.405266 -21.250656)
		(end 186.790076 -21.635466)
		(width 0.13208)
		(layer "B.Cu")
		(net "USB2_7_DN")
	)
	(segment
		(start 257.43662 -37.005768)
		(end 258.994402 -36.3601)
		(width 0.13208)
		(layer "B.Cu")
		(net "USB2_7_DN")
	)
	(segment
		(start 359.738676 -26.707084)
		(end 360.373168 -28.238958)
		(width 0.13208)
		(layer "B.Cu")
		(net "USB2_7_DN")
	)
	(segment
		(start 186.461146 -19.98091)
		(end 186.298078 -19.817842)
		(width 0.13208)
		(layer "B.Cu")
		(net "USB2_7_DN")
	)
	(segment
		(start 188.547248 -22.1107)
		(end 190.142876 -21.449792)
		(width 0.13208)
		(layer "B.Cu")
		(net "USB2_7_DN")
	)
	(segment
		(start 186.790076 -20.865846)
		(end 186.790076 -20.811744)
		(width 0.13208)
		(layer "B.Cu")
		(net "USB2_7_DN")
	)
	(segment
		(start 361.073954 -29.930344)
		(end 361.37596 -30.659578)
		(width 0.13208)
		(layer "B.Cu")
		(net "USB2_7_DN")
	)
	(segment
		(start 361.37596 -43.155108)
		(end 361.37596 -43.546268)
		(width 0.13208)
		(layer "B.Cu")
		(net "USB2_7_DN")
	)
	(segment
		(start 360.373168 -28.238958)
		(end 360.307128 -28.398216)
		(width 0.13208)
		(layer "B.Cu")
		(net "USB2_7_DN")
	)
	(segment
		(start 361.37596 -36.647628)
		(end 361.37596 -37.785548)
		(width 0.13208)
		(layer "B.Cu")
		(net "USB2_7_DN")
	)
	(segment
		(start 361.25404 -41.049448)
		(end 361.25404 -41.440608)
		(width 0.13208)
		(layer "B.Cu")
		(net "USB2_7_DN")
	)
	(segment
		(start 300.66234 -14.431264)
		(end 301.848266 -13.940028)
		(width 0.13208)
		(layer "B.Cu")
		(net "USB2_7_DN")
	)
	(segment
		(start 361.25404 -37.907468)
		(end 361.25404 -38.298628)
		(width 0.13208)
		(layer "B.Cu")
		(net "USB2_7_DN")
	)
	(segment
		(start 360.456734 -28.759912)
		(end 360.6165 -28.825952)
		(width 0.13208)
		(layer "B.Cu")
		(net "USB2_7_DN")
	)
	(segment
		(start 357.120952 -43.909996)
		(end 357.423212 -43.607736)
		(width 0.13208)
		(layer "B.Cu")
		(net "USB2_7_DN")
	)
	(segment
		(start 341.434674 -13.395198)
		(end 349.956882 -16.92529)
		(width 0.13208)
		(layer "B.Cu")
		(net "USB2_7_DN")
	)
	(segment
		(start 221.320106 -34.800794)
		(end 223.024192 -36.50488)
		(width 0.13208)
		(layer "B.Cu")
		(net "USB2_7_DN")
	)
	(segment
		(start 361.25404 -41.440608)
		(end 361.37596 -41.562528)
		(width 0.13208)
		(layer "B.Cu")
		(net "USB2_7_DN")
	)
	(segment
		(start 186.790076 -21.832062)
		(end 187.068714 -22.1107)
		(width 0.13208)
		(layer "B.Cu")
		(net "USB2_7_DN")
	)
	(segment
		(start 361.25404 -34.859468)
		(end 361.37596 -34.981388)
		(width 0.13208)
		(layer "B.Cu")
		(net "USB2_7_DN")
	)
	(segment
		(start 361.25404 -33.172908)
		(end 361.37596 -33.294828)
		(width 0.13208)
		(layer "B.Cu")
		(net "USB2_7_DN")
	)
	(segment
		(start 360.764836 -29.502608)
		(end 360.914442 -29.864304)
		(width 0.13208)
		(layer "B.Cu")
		(net "USB2_7_DN")
	)
	(segment
		(start 357.253032 -44.22902)
		(end 357.120952 -44.09694)
		(width 0.13208)
		(layer "B.Cu")
		(net "USB2_7_DN")
	)
	(segment
		(start 197.35546 -15.316708)
		(end 205.97749 -15.316708)
		(width 0.13208)
		(layer "B.Cu")
		(net "USB2_7_DN")
	)
	(segment
		(start 319.546986 -13.940028)
		(end 320.16954 -14.197838)
		(width 0.13208)
		(layer "B.Cu")
		(net "USB2_7_DN")
	)
	(segment
		(start 322.477638 -14.197838)
		(end 324.415404 -13.395198)
		(width 0.13208)
		(layer "B.Cu")
		(net "USB2_7_DN")
	)
	(segment
		(start 297.028362 -18.065242)
		(end 300.66234 -14.431264)
		(width 0.13208)
		(layer "B.Cu")
		(net "USB2_7_DN")
	)
	(segment
		(start 190.142876 -21.449792)
		(end 190.912242 -20.680426)
		(width 0.13208)
		(layer "B.Cu")
		(net "USB2_7_DN")
	)
	(segment
		(start 186.634628 -20.436586)
		(end 186.461146 -20.263104)
		(width 0.13208)
		(layer "B.Cu")
		(net "USB2_7_DN")
	)
	(segment
		(start 292.064948 -19.759168)
		(end 292.938962 -19.759168)
		(width 0.13208)
		(layer "B.Cu")
		(net "USB2_7_DN")
	)
	(segment
		(start 357.120952 -44.09694)
		(end 357.120952 -43.909996)
		(width 0.13208)
		(layer "B.Cu")
		(net "USB2_7_DN")
	)
	(segment
		(start 220.51772 -29.861256)
		(end 220.51772 -32.863282)
		(width 0.13208)
		(layer "B.Cu")
		(net "USB2_7_DN")
	)
	(segment
		(start 262.908288 -31.83636)
		(end 292.064948 -19.759168)
		(width 0.13208)
		(layer "B.Cu")
		(net "USB2_7_DN")
	)
	(segment
		(start 361.37596 -36.012628)
		(end 361.25404 -36.134548)
		(width 0.13208)
		(layer "B.Cu")
		(net "USB2_7_DN")
	)
	(segment
		(start 361.37596 -40.150288)
		(end 361.37596 -40.927528)
		(width 0.13208)
		(layer "B.Cu")
		(net "USB2_7_DN")
	)
	(segment
		(start 187.068714 -22.1107)
		(end 188.547248 -22.1107)
		(width 0.13208)
		(layer "B.Cu")
		(net "USB2_7_DN")
	)
	(segment
		(start 361.25404 -42.642028)
		(end 361.25404 -43.033188)
		(width 0.13208)
		(layer "B.Cu")
		(net "USB2_7_DN")
	)
	(segment
		(start 261.823454 -32.921194)
		(end 262.908288 -31.83636)
		(width 0.13208)
		(layer "B.Cu")
		(net "USB2_7_DN")
	)
	(segment
		(start 186.790076 -21.635466)
		(end 186.790076 -21.832062)
		(width 0.13208)
		(layer "B.Cu")
		(net "USB2_7_DN")
	)
	(segment
		(start 223.024192 -36.50488)
		(end 224.233486 -37.005768)
		(width 0.13208)
		(layer "B.Cu")
		(net "USB2_7_DN")
	)
	(segment
		(start 361.37596 -34.981388)
		(end 361.37596 -36.012628)
		(width 0.13208)
		(layer "B.Cu")
		(net "USB2_7_DN")
	)
	(segment
		(start 224.233486 -37.005768)
		(end 257.43662 -37.005768)
		(width 0.13208)
		(layer "B.Cu")
		(net "USB2_7_DN")
	)
	(segment
		(start 361.37596 -41.562528)
		(end 361.37596 -42.520108)
		(width 0.13208)
		(layer "B.Cu")
		(net "USB2_7_DN")
	)
	(segment
		(start 292.938962 -19.759168)
		(end 297.028362 -18.065242)
		(width 0.13208)
		(layer "B.Cu")
		(net "USB2_7_DN")
	)
	(segment
		(start 261.392416 -33.962086)
		(end 261.823454 -32.921194)
		(width 0.13208)
		(layer "B.Cu")
		(net "USB2_7_DN")
	)
	(segment
		(start 361.25404 -43.033188)
		(end 361.37596 -43.155108)
		(width 0.13208)
		(layer "B.Cu")
		(net "USB2_7_DN")
	)
	(segment
		(start 360.307128 -28.398216)
		(end 360.456734 -28.759912)
		(width 0.13208)
		(layer "B.Cu")
		(net "USB2_7_DN")
	)
	(segment
		(start 361.25404 -38.298628)
		(end 361.37596 -38.420548)
		(width 0.13208)
		(layer "B.Cu")
		(net "USB2_7_DN")
	)
	(segment
		(start 217.602308 -22.822662)
		(end 220.51772 -29.861256)
		(width 0.13208)
		(layer "B.Cu")
		(net "USB2_7_DN")
	)
	(segment
		(start 360.830622 -29.34335)
		(end 360.764836 -29.502608)
		(width 0.13208)
		(layer "B.Cu")
		(net "USB2_7_DN")
	)
	(segment
		(start 320.16954 -14.197838)
		(end 322.477638 -14.197838)
		(width 0.13208)
		(layer "B.Cu")
		(net "USB2_7_DN")
	)
	(segment
		(start 361.25404 -34.468308)
		(end 361.25404 -34.859468)
		(width 0.13208)
		(layer "B.Cu")
		(net "USB2_7_DN")
	)
	(segment
		(start 361.37596 -32.659828)
		(end 361.25404 -32.781748)
		(width 0.13208)
		(layer "B.Cu")
		(net "USB2_7_DN")
	)
	(segment
		(start 186.298078 -19.817842)
		(end 186.055254 -19.817842)
		(width 0.13208)
		(layer "B.Cu")
		(net "USB2_7_DN")
	)
	(segment
		(start 361.37596 -43.546268)
		(end 360.693208 -44.22902)
		(width 0.13208)
		(layer "B.Cu")
		(net "USB2_7_DN")
	)
	(segment
		(start 360.914442 -29.864304)
		(end 361.073954 -29.930344)
		(width 0.13208)
		(layer "B.Cu")
		(net "USB2_7_DN")
	)
	(segment
		(start 324.415404 -13.395198)
		(end 341.434674 -13.395198)
		(width 0.13208)
		(layer "B.Cu")
		(net "USB2_7_DN")
	)
	(segment
		(start 186.790076 -20.811744)
		(end 186.634628 -20.436586)
		(width 0.13208)
		(layer "B.Cu")
		(net "USB2_7_DN")
	)
	(segment
		(start 258.994402 -36.3601)
		(end 261.392416 -33.962086)
		(width 0.13208)
		(layer "B.Cu")
		(net "USB2_7_DN")
	)
	(segment
		(start 360.693208 -44.22902)
		(end 357.253032 -44.22902)
		(width 0.13208)
		(layer "B.Cu")
		(net "USB2_7_DN")
	)
	(segment
		(start 361.25404 -32.781748)
		(end 361.25404 -33.172908)
		(width 0.13208)
		(layer "B.Cu")
		(net "USB2_7_DN")
	)
	(segment
		(start 361.25404 -36.134548)
		(end 361.25404 -36.525708)
		(width 0.13208)
		(layer "B.Cu")
		(net "USB2_7_DN")
	)
	(segment
		(start 214.826088 -20.046442)
		(end 217.602308 -22.822662)
		(width 0.13208)
		(layer "B.Cu")
		(net "USB2_7_DN")
	)
	(segment
		(start 192.755266 -19.916902)
		(end 197.35546 -15.316708)
		(width 0.13208)
		(layer "B.Cu")
		(net "USB2_7_DN")
	)
	(segment
		(start 361.37596 -39.515288)
		(end 361.25404 -39.637208)
		(width 0.13208)
		(layer "B.Cu")
		(net "USB2_7_DN")
	)
	(segment
		(start 361.25404 -40.028368)
		(end 361.37596 -40.150288)
		(width 0.13208)
		(layer "B.Cu")
		(net "USB2_7_DN")
	)
	(segment
		(start 186.405266 -21.250656)
		(end 186.790076 -20.865846)
		(width 0.13208)
		(layer "B.Cu")
		(net "USB2_7_DN")
	)
	(segment
		(start 361.37596 -38.420548)
		(end 361.37596 -39.515288)
		(width 0.13208)
		(layer "B.Cu")
		(net "USB2_7_DN")
	)
	(segment
		(start 361.37596 -37.785548)
		(end 361.25404 -37.907468)
		(width 0.13208)
		(layer "B.Cu")
		(net "USB2_7_DN")
	)
	(segment
		(start 361.25404 -39.637208)
		(end 361.25404 -40.028368)
		(width 0.13208)
		(layer "B.Cu")
		(net "USB2_7_DN")
	)
	(segment
		(start 361.37596 -42.520108)
		(end 361.25404 -42.642028)
		(width 0.13208)
		(layer "B.Cu")
		(net "USB2_7_DN")
	)
	(segment
		(start 360.6165 -28.825952)
		(end 360.830622 -29.34335)
		(width 0.13208)
		(layer "B.Cu")
		(net "USB2_7_DN")
	)
	(segment
		(start 190.912242 -20.680426)
		(end 192.755266 -19.916902)
		(width 0.13208)
		(layer "B.Cu")
		(net "USB2_7_DN")
	)
	(segment
		(start 347.421962 -42.225468)
		(end 347.041978 -42.225468)
		(width 0.0889)
		(layer "F.Cu")
		(net "TP_USB2_6_DP")
	)
	(segment
		(start 352.048826 -37.529008)
		(end 351.597976 -37.529008)
		(width 0.12192)
		(layer "F.Cu")
		(net "TP_USB2_6_DP")
	)
	(segment
		(start 346.641166 -41.947084)
		(end 346.384626 -41.947084)
		(width 0.0889)
		(layer "F.Cu")
		(net "TP_USB2_6_DP")
	)
	(segment
		(start 351.597976 -37.529008)
		(end 351.390966 -37.736018)
		(width 0.12192)
		(layer "F.Cu")
		(net "TP_USB2_6_DP")
	)
	(segment
		(start 351.356676 -38.101016)
		(end 351.356676 -39.627302)
		(width 0.0889)
		(layer "F.Cu")
		(net "TP_USB2_6_DP")
	)
	(segment
		(start 347.041978 -42.225468)
		(end 346.779088 -41.998392)
		(width 0.0889)
		(layer "F.Cu")
		(net "TP_USB2_6_DP")
	)
	(segment
		(start 348.20352 -42.13733)
		(end 347.5101 -42.13733)
		(width 0.0889)
		(layer "F.Cu")
		(net "TP_USB2_6_DP")
	)
	(segment
		(start 351.390966 -38.044628)
		(end 351.390966 -38.066726)
		(width 0.0889)
		(layer "F.Cu")
		(net "TP_USB2_6_DP")
	)
	(segment
		(start 351.390966 -38.066726)
		(end 351.356676 -38.101016)
		(width 0.0889)
		(layer "F.Cu")
		(net "TP_USB2_6_DP")
	)
	(segment
		(start 351.390966 -37.736018)
		(end 351.390966 -38.044628)
		(width 0.12192)
		(layer "F.Cu")
		(net "TP_USB2_6_DP")
	)
	(segment
		(start 346.779088 -41.998392)
		(end 346.641166 -41.947084)
		(width 0.0889)
		(layer "F.Cu")
		(net "TP_USB2_6_DP")
	)
	(segment
		(start 349.043752 -41.940226)
		(end 348.400624 -41.940226)
		(width 0.0889)
		(layer "F.Cu")
		(net "TP_USB2_6_DP")
	)
	(segment
		(start 352.146616 -37.626798)
		(end 352.048826 -37.529008)
		(width 0.12192)
		(layer "F.Cu")
		(net "TP_USB2_6_DP")
	)
	(segment
		(start 352.146616 -37.848032)
		(end 352.146616 -37.626798)
		(width 0.12192)
		(layer "F.Cu")
		(net "TP_USB2_6_DP")
	)
	(segment
		(start 348.400624 -41.940226)
		(end 348.20352 -42.13733)
		(width 0.0889)
		(layer "F.Cu")
		(net "TP_USB2_6_DP")
	)
	(segment
		(start 347.5101 -42.13733)
		(end 347.421962 -42.225468)
		(width 0.0889)
		(layer "F.Cu")
		(net "TP_USB2_6_DP")
	)
	(segment
		(start 351.356676 -39.627302)
		(end 349.043752 -41.940226)
		(width 0.0889)
		(layer "F.Cu")
		(net "TP_USB2_6_DP")
	)
	(via
		(at 352.146616 -37.848032)
		(size 0.508)
		(drill 0.254)
		(layers "F.Cu" "B.Cu")
		(net "TP_USB2_6_DP")
	)
	(segment
		(start 349.090234 -41.484296)
		(end 349.090234 -41.624504)
		(width 0.0889)
		(layer "F.Cu")
		(net "TP_USB2_6_DN")
	)
	(segment
		(start 349.481648 -41.23309)
		(end 349.356172 -41.358566)
		(width 0.0889)
		(layer "F.Cu")
		(net "TP_USB2_6_DN")
	)
	(segment
		(start 349.747586 -40.967152)
		(end 349.607378 -40.967152)
		(width 0.0889)
		(layer "F.Cu")
		(net "TP_USB2_6_DN")
	)
	(segment
		(start 348.124526 -41.947084)
		(end 347.899482 -41.947084)
		(width 0.0889)
		(layer "F.Cu")
		(net "TP_USB2_6_DN")
	)
	(segment
		(start 349.356172 -41.358566)
		(end 349.215964 -41.358566)
		(width 0.0889)
		(layer "F.Cu")
		(net "TP_USB2_6_DN")
	)
	(segment
		(start 350.390206 -40.184324)
		(end 350.264476 -40.310054)
		(width 0.0889)
		(layer "F.Cu")
		(net "TP_USB2_6_DN")
	)
	(segment
		(start 352.103436 -37.244528)
		(end 351.515934 -37.244528)
		(width 0.12192)
		(layer "F.Cu")
		(net "TP_USB2_6_DN")
	)
	(segment
		(start 349.090234 -41.624504)
		(end 348.964758 -41.74998)
		(width 0.0889)
		(layer "F.Cu")
		(net "TP_USB2_6_DN")
	)
	(segment
		(start 351.16643 -39.299134)
		(end 351.16643 -39.548308)
		(width 0.0889)
		(layer "F.Cu")
		(net "TP_USB2_6_DN")
	)
	(segment
		(start 351.16643 -38.923722)
		(end 351.067624 -39.022528)
		(width 0.0889)
		(layer "F.Cu")
		(net "TP_USB2_6_DN")
	)
	(segment
		(start 352.217736 -37.130228)
		(end 352.103436 -37.244528)
		(width 0.12192)
		(layer "F.Cu")
		(net "TP_USB2_6_DN")
	)
	(segment
		(start 351.067624 -39.200328)
		(end 351.16643 -39.299134)
		(width 0.0889)
		(layer "F.Cu")
		(net "TP_USB2_6_DN")
	)
	(segment
		(start 347.800676 -41.848278)
		(end 347.622876 -41.848278)
		(width 0.0889)
		(layer "F.Cu")
		(net "TP_USB2_6_DN")
	)
	(segment
		(start 349.873062 -40.841676)
		(end 349.747586 -40.967152)
		(width 0.0889)
		(layer "F.Cu")
		(net "TP_USB2_6_DN")
	)
	(segment
		(start 348.964758 -41.74998)
		(end 348.32163 -41.74998)
		(width 0.0889)
		(layer "F.Cu")
		(net "TP_USB2_6_DN")
	)
	(segment
		(start 349.481648 -41.092882)
		(end 349.481648 -41.23309)
		(width 0.0889)
		(layer "F.Cu")
		(net "TP_USB2_6_DN")
	)
	(segment
		(start 349.873062 -40.701468)
		(end 349.873062 -40.841676)
		(width 0.0889)
		(layer "F.Cu")
		(net "TP_USB2_6_DN")
	)
	(segment
		(start 351.131886 -38.044628)
		(end 351.131886 -38.066726)
		(width 0.0889)
		(layer "F.Cu")
		(net "TP_USB2_6_DN")
	)
	(segment
		(start 352.217736 -36.834318)
		(end 352.217736 -37.130228)
		(width 0.12192)
		(layer "F.Cu")
		(net "TP_USB2_6_DN")
	)
	(segment
		(start 351.515934 -37.244528)
		(end 351.131886 -37.628576)
		(width 0.12192)
		(layer "F.Cu")
		(net "TP_USB2_6_DN")
	)
	(segment
		(start 350.65589 -39.91864)
		(end 350.65589 -40.058848)
		(width 0.0889)
		(layer "F.Cu")
		(net "TP_USB2_6_DN")
	)
	(segment
		(start 347.899482 -41.947084)
		(end 347.800676 -41.848278)
		(width 0.0889)
		(layer "F.Cu")
		(net "TP_USB2_6_DN")
	)
	(segment
		(start 350.530414 -40.184324)
		(end 350.390206 -40.184324)
		(width 0.0889)
		(layer "F.Cu")
		(net "TP_USB2_6_DN")
	)
	(segment
		(start 351.16643 -38.10127)
		(end 351.16643 -38.923722)
		(width 0.0889)
		(layer "F.Cu")
		(net "TP_USB2_6_DN")
	)
	(segment
		(start 349.607378 -40.967152)
		(end 349.481648 -41.092882)
		(width 0.0889)
		(layer "F.Cu")
		(net "TP_USB2_6_DN")
	)
	(segment
		(start 348.32163 -41.74998)
		(end 348.124526 -41.947084)
		(width 0.0889)
		(layer "F.Cu")
		(net "TP_USB2_6_DN")
	)
	(segment
		(start 351.16643 -39.548308)
		(end 350.921828 -39.79291)
		(width 0.0889)
		(layer "F.Cu")
		(net "TP_USB2_6_DN")
	)
	(segment
		(start 351.131886 -37.628576)
		(end 351.131886 -38.044628)
		(width 0.12192)
		(layer "F.Cu")
		(net "TP_USB2_6_DN")
	)
	(segment
		(start 349.215964 -41.358566)
		(end 349.090234 -41.484296)
		(width 0.0889)
		(layer "F.Cu")
		(net "TP_USB2_6_DN")
	)
	(segment
		(start 350.264476 -40.450262)
		(end 350.139 -40.575738)
		(width 0.0889)
		(layer "F.Cu")
		(net "TP_USB2_6_DN")
	)
	(segment
		(start 350.78162 -39.79291)
		(end 350.65589 -39.91864)
		(width 0.0889)
		(layer "F.Cu")
		(net "TP_USB2_6_DN")
	)
	(segment
		(start 351.067624 -39.022528)
		(end 351.067624 -39.200328)
		(width 0.0889)
		(layer "F.Cu")
		(net "TP_USB2_6_DN")
	)
	(segment
		(start 347.52407 -41.947084)
		(end 347.214698 -41.947084)
		(width 0.0889)
		(layer "F.Cu")
		(net "TP_USB2_6_DN")
	)
	(segment
		(start 350.65589 -40.058848)
		(end 350.530414 -40.184324)
		(width 0.0889)
		(layer "F.Cu")
		(net "TP_USB2_6_DN")
	)
	(segment
		(start 349.998792 -40.575738)
		(end 349.873062 -40.701468)
		(width 0.0889)
		(layer "F.Cu")
		(net "TP_USB2_6_DN")
	)
	(segment
		(start 347.622876 -41.848278)
		(end 347.52407 -41.947084)
		(width 0.0889)
		(layer "F.Cu")
		(net "TP_USB2_6_DN")
	)
	(segment
		(start 350.921828 -39.79291)
		(end 350.78162 -39.79291)
		(width 0.0889)
		(layer "F.Cu")
		(net "TP_USB2_6_DN")
	)
	(segment
		(start 350.264476 -40.310054)
		(end 350.264476 -40.450262)
		(width 0.0889)
		(layer "F.Cu")
		(net "TP_USB2_6_DN")
	)
	(segment
		(start 350.139 -40.575738)
		(end 349.998792 -40.575738)
		(width 0.0889)
		(layer "F.Cu")
		(net "TP_USB2_6_DN")
	)
	(segment
		(start 351.131886 -38.066726)
		(end 351.16643 -38.10127)
		(width 0.0889)
		(layer "F.Cu")
		(net "TP_USB2_6_DN")
	)
	(via
		(at 352.217736 -36.834318)
		(size 0.508)
		(drill 0.254)
		(layers "F.Cu" "B.Cu")
		(net "TP_USB2_6_DN")
	)
	(segment
		(start 16.014192 -19.819874)
		(end 16.014192 -20.354544)
		(width 0.13208)
		(layer "F.Cu")
		(net "USB2_5_DP")
	)
	(segment
		(start 16.17472 -21.191728)
		(end 16.47698 -21.493988)
		(width 0.13208)
		(layer "F.Cu")
		(net "USB2_5_DP")
	)
	(segment
		(start 347.082872 -45.22724)
		(end 346.666058 -44.948602)
		(width 0.0889)
		(layer "F.Cu")
		(net "USB2_5_DP")
	)
	(segment
		(start 359.02646 -43.30446)
		(end 359.02646 -42.43959)
		(width 0.13208)
		(layer "F.Cu")
		(net "USB2_5_DP")
	)
	(segment
		(start 15.478252 -19.819874)
		(end 15.478252 -19.81835)
		(width 0.13208)
		(layer "F.Cu")
		(net "USB2_5_DP")
	)
	(segment
		(start 16.014192 -20.354544)
		(end 16.2941 -20.634452)
		(width 0.13208)
		(layer "F.Cu")
		(net "USB2_5_DP")
	)
	(segment
		(start 351.289366 -44.985686)
		(end 350.80448 -45.470572)
		(width 0.0889)
		(layer "F.Cu")
		(net "USB2_5_DP")
	)
	(segment
		(start 358.720136 -43.610784)
		(end 359.02646 -43.30446)
		(width 0.13208)
		(layer "F.Cu")
		(net "USB2_5_DP")
	)
	(segment
		(start 351.289366 -44.463462)
		(end 351.289366 -44.985686)
		(width 0.0889)
		(layer "F.Cu")
		(net "USB2_5_DP")
	)
	(segment
		(start 353.873054 -41.879774)
		(end 351.289366 -44.463462)
		(width 0.0889)
		(layer "F.Cu")
		(net "USB2_5_DP")
	)
	(segment
		(start 13.455396 -16.138652)
		(end 13.87348 -15.720568)
		(width 0.13208)
		(layer "F.Cu")
		(net "USB2_5_DP")
	)
	(segment
		(start 347.609922 -45.22724)
		(end 347.082872 -45.22724)
		(width 0.0889)
		(layer "F.Cu")
		(net "USB2_5_DP")
	)
	(segment
		(start 350.80448 -45.470572)
		(end 347.853254 -45.470572)
		(width 0.0889)
		(layer "F.Cu")
		(net "USB2_5_DP")
	)
	(segment
		(start 354.443538 -41.914064)
		(end 354.42144 -41.914064)
		(width 0.0889)
		(layer "F.Cu")
		(net "USB2_5_DP")
	)
	(segment
		(start 347.853254 -45.470572)
		(end 347.609922 -45.22724)
		(width 0.0889)
		(layer "F.Cu")
		(net "USB2_5_DP")
	)
	(segment
		(start 16.014192 -19.819874)
		(end 15.478252 -19.819874)
		(width 0.13208)
		(layer "F.Cu")
		(net "USB2_5_DP")
	)
	(segment
		(start 359.02646 -42.43959)
		(end 358.500934 -41.914064)
		(width 0.13208)
		(layer "F.Cu")
		(net "USB2_5_DP")
	)
	(segment
		(start 16.2941 -20.975828)
		(end 16.17472 -21.095208)
		(width 0.13208)
		(layer "F.Cu")
		(net "USB2_5_DP")
	)
	(segment
		(start 346.666058 -44.948602)
		(end 346.384626 -44.948602)
		(width 0.0889)
		(layer "F.Cu")
		(net "USB2_5_DP")
	)
	(segment
		(start 16.2941 -20.634452)
		(end 16.2941 -20.975828)
		(width 0.13208)
		(layer "F.Cu")
		(net "USB2_5_DP")
	)
	(segment
		(start 354.42144 -41.914064)
		(end 354.38715 -41.879774)
		(width 0.0889)
		(layer "F.Cu")
		(net "USB2_5_DP")
	)
	(segment
		(start 358.500934 -41.914064)
		(end 354.443538 -41.914064)
		(width 0.13208)
		(layer "F.Cu")
		(net "USB2_5_DP")
	)
	(segment
		(start 16.17472 -21.095208)
		(end 16.17472 -21.191728)
		(width 0.13208)
		(layer "F.Cu")
		(net "USB2_5_DP")
	)
	(segment
		(start 354.38715 -41.879774)
		(end 353.873054 -41.879774)
		(width 0.0889)
		(layer "F.Cu")
		(net "USB2_5_DP")
	)
	(segment
		(start 15.478252 -19.81835)
		(end 14.837664 -19.177762)
		(width 0.13208)
		(layer "F.Cu")
		(net "USB2_5_DP")
	)
	(segment
		(start 14.837664 -18.345658)
		(end 13.455396 -16.96339)
		(width 0.13208)
		(layer "F.Cu")
		(net "USB2_5_DP")
	)
	(segment
		(start 14.837664 -19.177762)
		(end 14.837664 -18.345658)
		(width 0.13208)
		(layer "F.Cu")
		(net "USB2_5_DP")
	)
	(segment
		(start 13.455396 -16.96339)
		(end 13.455396 -16.138652)
		(width 0.13208)
		(layer "F.Cu")
		(net "USB2_5_DP")
	)
	(via
		(at 16.014192 -19.819874)
		(size 0.762)
		(drill 0.381)
		(layers "F.Cu" "B.Cu")
		(net "USB2_5_DP")
	)
	(segment
		(start 218.11996 -13.980668)
		(end 221.0943 -16.955008)
		(width 0.14732)
		(layer "In4.Cu")
		(net "USB2_5_DP")
	)
	(segment
		(start 83.409282 -13.957808)
		(end 117.275102 -13.957808)
		(width 0.14732)
		(layer "In4.Cu")
		(net "USB2_5_DP")
	)
	(segment
		(start 81.873344 -13.321792)
		(end 83.409282 -13.957808)
		(width 0.14732)
		(layer "In4.Cu")
		(net "USB2_5_DP")
	)
	(segment
		(start 354.1649 -36.270184)
		(end 354.327968 -36.337494)
		(width 0.14732)
		(layer "In4.Cu")
		(net "USB2_5_DP")
	)
	(segment
		(start 180.02377 -9.63295)
		(end 183.202834 -10.950194)
		(width 0.14732)
		(layer "In4.Cu")
		(net "USB2_5_DP")
	)
	(segment
		(start 354.327968 -36.337494)
		(end 354.494846 -36.7411)
		(width 0.14732)
		(layer "In4.Cu")
		(net "USB2_5_DP")
	)
	(segment
		(start 339.166962 -16.4338)
		(end 344.720672 -20.144994)
		(width 0.14732)
		(layer "In4.Cu")
		(net "USB2_5_DP")
	)
	(segment
		(start 18.729706 -15.998952)
		(end 19.096228 -15.964662)
		(width 0.14732)
		(layer "In4.Cu")
		(net "USB2_5_DP")
	)
	(segment
		(start 46.64075 -13.082524)
		(end 47.219362 -12.503912)
		(width 0.14732)
		(layer "In4.Cu")
		(net "USB2_5_DP")
	)
	(segment
		(start 189.441836 -13.980668)
		(end 218.11996 -13.980668)
		(width 0.14732)
		(layer "In4.Cu")
		(net "USB2_5_DP")
	)
	(segment
		(start 354.857304 -37.940996)
		(end 355.024436 -38.344856)
		(width 0.14732)
		(layer "In4.Cu")
		(net "USB2_5_DP")
	)
	(segment
		(start 355.454204 -39.382192)
		(end 355.617018 -39.449502)
		(width 0.14732)
		(layer "In4.Cu")
		(net "USB2_5_DP")
	)
	(segment
		(start 321.19189 -15.812008)
		(end 337.116928 -15.812008)
		(width 0.14732)
		(layer "In4.Cu")
		(net "USB2_5_DP")
	)
	(segment
		(start 254.558038 -40.147748)
		(end 259.38099 -38.150038)
		(width 0.14732)
		(layer "In4.Cu")
		(net "USB2_5_DP")
	)
	(segment
		(start 137.739628 -9.525508)
		(end 145.796 -9.525508)
		(width 0.14732)
		(layer "In4.Cu")
		(net "USB2_5_DP")
	)
	(segment
		(start 17.052544 -16.156432)
		(end 17.210278 -16.286988)
		(width 0.14732)
		(layer "In4.Cu")
		(net "USB2_5_DP")
	)
	(segment
		(start 353.998022 -35.866324)
		(end 354.1649 -36.270184)
		(width 0.14732)
		(layer "In4.Cu")
		(net "USB2_5_DP")
	)
	(segment
		(start 359.008426 -43.10126)
		(end 359.008426 -43.322494)
		(width 0.14732)
		(layer "In4.Cu")
		(net "USB2_5_DP")
	)
	(segment
		(start 78.759304 -11.676888)
		(end 81.267554 -12.716002)
		(width 0.14732)
		(layer "In4.Cu")
		(net "USB2_5_DP")
	)
	(segment
		(start 221.0943 -34.694876)
		(end 221.487492 -35.644582)
		(width 0.14732)
		(layer "In4.Cu")
		(net "USB2_5_DP")
	)
	(segment
		(start 50.085244 -11.31697)
		(end 77.30744 -11.676888)
		(width 0.14732)
		(layer "In4.Cu")
		(net "USB2_5_DP")
	)
	(segment
		(start 344.720672 -20.144994)
		(end 346.368624 -21.792946)
		(width 0.14732)
		(layer "In4.Cu")
		(net "USB2_5_DP")
	)
	(segment
		(start 119.703596 -14.963648)
		(end 124.433838 -14.963648)
		(width 0.14732)
		(layer "In4.Cu")
		(net "USB2_5_DP")
	)
	(segment
		(start 161.46526 -9.995408)
		(end 163.42614 -8.034528)
		(width 0.14732)
		(layer "In4.Cu")
		(net "USB2_5_DP")
	)
	(segment
		(start 19.253962 -16.095472)
		(end 19.620992 -16.061182)
		(width 0.14732)
		(layer "In4.Cu")
		(net "USB2_5_DP")
	)
	(segment
		(start 253.747016 -40.147748)
		(end 254.558038 -40.147748)
		(width 0.14732)
		(layer "In4.Cu")
		(net "USB2_5_DP")
	)
	(segment
		(start 355.78415 -39.853108)
		(end 355.71684 -40.015922)
		(width 0.14732)
		(layer "In4.Cu")
		(net "USB2_5_DP")
	)
	(segment
		(start 354.594668 -37.30752)
		(end 354.757482 -37.37483)
		(width 0.14732)
		(layer "In4.Cu")
		(net "USB2_5_DP")
	)
	(segment
		(start 14.32814 -18.402808)
		(end 14.32814 -17.099788)
		(width 0.14732)
		(layer "In4.Cu")
		(net "USB2_5_DP")
	)
	(segment
		(start 16.47698 -21.493988)
		(end 16.16456 -21.181568)
		(width 0.14732)
		(layer "In4.Cu")
		(net "USB2_5_DP")
	)
	(segment
		(start 353.314508 -28.014676)
		(end 353.75088 -29.068014)
		(width 0.14732)
		(layer "In4.Cu")
		(net "USB2_5_DP")
	)
	(segment
		(start 221.0943 -16.955008)
		(end 221.0943 -34.694876)
		(width 0.14732)
		(layer "In4.Cu")
		(net "USB2_5_DP")
	)
	(segment
		(start 355.354382 -38.815772)
		(end 355.287072 -38.978332)
		(width 0.14732)
		(layer "In4.Cu")
		(net "USB2_5_DP")
	)
	(segment
		(start 19.751548 -15.903194)
		(end 45.836332 -13.46073)
		(width 0.14732)
		(layer "In4.Cu")
		(net "USB2_5_DP")
	)
	(segment
		(start 18.074386 -16.06042)
		(end 18.23212 -16.19123)
		(width 0.14732)
		(layer "In4.Cu")
		(net "USB2_5_DP")
	)
	(segment
		(start 354.494846 -36.7411)
		(end 354.427536 -36.90366)
		(width 0.14732)
		(layer "In4.Cu")
		(net "USB2_5_DP")
	)
	(segment
		(start 19.620992 -16.061182)
		(end 19.751548 -15.903194)
		(width 0.14732)
		(layer "In4.Cu")
		(net "USB2_5_DP")
	)
	(segment
		(start 355.024436 -38.344856)
		(end 355.18725 -38.412166)
		(width 0.14732)
		(layer "In4.Cu")
		(net "USB2_5_DP")
	)
	(segment
		(start 77.30744 -11.676888)
		(end 78.759304 -11.676888)
		(width 0.14732)
		(layer "In4.Cu")
		(net "USB2_5_DP")
	)
	(segment
		(start 346.368624 -21.792946)
		(end 348.5515 -23.251922)
		(width 0.14732)
		(layer "In4.Cu")
		(net "USB2_5_DP")
	)
	(segment
		(start 355.617018 -39.449502)
		(end 355.78415 -39.853108)
		(width 0.14732)
		(layer "In4.Cu")
		(net "USB2_5_DP")
	)
	(segment
		(start 17.577054 -16.252698)
		(end 17.707864 -16.09471)
		(width 0.14732)
		(layer "In4.Cu")
		(net "USB2_5_DP")
	)
	(segment
		(start 124.433838 -14.963648)
		(end 127.123444 -13.849604)
		(width 0.14732)
		(layer "In4.Cu")
		(net "USB2_5_DP")
	)
	(segment
		(start 358.45242 -42.545254)
		(end 359.008426 -43.10126)
		(width 0.14732)
		(layer "In4.Cu")
		(net "USB2_5_DP")
	)
	(segment
		(start 354.757482 -37.37483)
		(end 354.924614 -37.778436)
		(width 0.14732)
		(layer "In4.Cu")
		(net "USB2_5_DP")
	)
	(segment
		(start 246.939816 -42.967148)
		(end 253.747016 -40.147748)
		(width 0.14732)
		(layer "In4.Cu")
		(net "USB2_5_DP")
	)
	(segment
		(start 117.275102 -13.957808)
		(end 119.703596 -14.963648)
		(width 0.14732)
		(layer "In4.Cu")
		(net "USB2_5_DP")
	)
	(segment
		(start 355.883972 -40.419782)
		(end 356.04704 -40.487092)
		(width 0.14732)
		(layer "In4.Cu")
		(net "USB2_5_DP")
	)
	(segment
		(start 354.065332 -35.703764)
		(end 353.998022 -35.866324)
		(width 0.14732)
		(layer "In4.Cu")
		(net "USB2_5_DP")
	)
	(segment
		(start 353.75088 -34.94405)
		(end 354.065332 -35.703764)
		(width 0.14732)
		(layer "In4.Cu")
		(net "USB2_5_DP")
	)
	(segment
		(start 137.272268 -9.058148)
		(end 137.739628 -9.525508)
		(width 0.14732)
		(layer "In4.Cu")
		(net "USB2_5_DP")
	)
	(segment
		(start 355.18725 -38.412166)
		(end 355.354382 -38.815772)
		(width 0.14732)
		(layer "In4.Cu")
		(net "USB2_5_DP")
	)
	(segment
		(start 178.425348 -8.034528)
		(end 180.02377 -9.63295)
		(width 0.14732)
		(layer "In4.Cu")
		(net "USB2_5_DP")
	)
	(segment
		(start 163.42614 -8.034528)
		(end 178.425348 -8.034528)
		(width 0.14732)
		(layer "In4.Cu")
		(net "USB2_5_DP")
	)
	(segment
		(start 16.16456 -21.181568)
		(end 16.16456 -20.239228)
		(width 0.14732)
		(layer "In4.Cu")
		(net "USB2_5_DP")
	)
	(segment
		(start 261.115302 -36.415726)
		(end 301.309278 -19.767042)
		(width 0.14732)
		(layer "In4.Cu")
		(net "USB2_5_DP")
	)
	(segment
		(start 17.210278 -16.286988)
		(end 17.577054 -16.252698)
		(width 0.14732)
		(layer "In4.Cu")
		(net "USB2_5_DP")
	)
	(segment
		(start 353.75088 -29.068014)
		(end 353.75088 -34.94405)
		(width 0.14732)
		(layer "In4.Cu")
		(net "USB2_5_DP")
	)
	(segment
		(start 17.707864 -16.09471)
		(end 18.074386 -16.06042)
		(width 0.14732)
		(layer "In4.Cu")
		(net "USB2_5_DP")
	)
	(segment
		(start 348.5515 -23.251922)
		(end 353.314508 -28.014676)
		(width 0.14732)
		(layer "In4.Cu")
		(net "USB2_5_DP")
	)
	(segment
		(start 354.427536 -36.90366)
		(end 354.594668 -37.30752)
		(width 0.14732)
		(layer "In4.Cu")
		(net "USB2_5_DP")
	)
	(segment
		(start 19.096228 -15.964662)
		(end 19.253962 -16.095472)
		(width 0.14732)
		(layer "In4.Cu")
		(net "USB2_5_DP")
	)
	(segment
		(start 15.0876 -16.340328)
		(end 17.052544 -16.156432)
		(width 0.14732)
		(layer "In4.Cu")
		(net "USB2_5_DP")
	)
	(segment
		(start 145.796 -9.525508)
		(end 146.2659 -9.995408)
		(width 0.14732)
		(layer "In4.Cu")
		(net "USB2_5_DP")
	)
	(segment
		(start 223.241616 -37.398706)
		(end 236.68482 -42.967148)
		(width 0.14732)
		(layer "In4.Cu")
		(net "USB2_5_DP")
	)
	(segment
		(start 45.836332 -13.46073)
		(end 46.64075 -13.082524)
		(width 0.14732)
		(layer "In4.Cu")
		(net "USB2_5_DP")
	)
	(segment
		(start 301.309278 -19.767042)
		(end 321.19189 -15.812008)
		(width 0.14732)
		(layer "In4.Cu")
		(net "USB2_5_DP")
	)
	(segment
		(start 355.71684 -40.015922)
		(end 355.883972 -40.419782)
		(width 0.14732)
		(layer "In4.Cu")
		(net "USB2_5_DP")
	)
	(segment
		(start 356.04704 -40.487092)
		(end 356.234238 -40.939466)
		(width 0.14732)
		(layer "In4.Cu")
		(net "USB2_5_DP")
	)
	(segment
		(start 183.202834 -10.950194)
		(end 183.964326 -11.711686)
		(width 0.14732)
		(layer "In4.Cu")
		(net "USB2_5_DP")
	)
	(segment
		(start 221.487492 -35.644582)
		(end 223.241616 -37.398706)
		(width 0.14732)
		(layer "In4.Cu")
		(net "USB2_5_DP")
	)
	(segment
		(start 236.68482 -42.967148)
		(end 246.939816 -42.967148)
		(width 0.14732)
		(layer "In4.Cu")
		(net "USB2_5_DP")
	)
	(segment
		(start 337.116928 -15.812008)
		(end 339.166962 -16.4338)
		(width 0.14732)
		(layer "In4.Cu")
		(net "USB2_5_DP")
	)
	(segment
		(start 359.008426 -43.322494)
		(end 358.720136 -43.610784)
		(width 0.14732)
		(layer "In4.Cu")
		(net "USB2_5_DP")
	)
	(segment
		(start 81.267554 -12.716002)
		(end 81.873344 -13.321792)
		(width 0.14732)
		(layer "In4.Cu")
		(net "USB2_5_DP")
	)
	(segment
		(start 355.287072 -38.978332)
		(end 355.454204 -39.382192)
		(width 0.14732)
		(layer "In4.Cu")
		(net "USB2_5_DP")
	)
	(segment
		(start 127.123444 -13.849604)
		(end 131.9149 -9.058148)
		(width 0.14732)
		(layer "In4.Cu")
		(net "USB2_5_DP")
	)
	(segment
		(start 183.964326 -11.711686)
		(end 189.441836 -13.980668)
		(width 0.14732)
		(layer "In4.Cu")
		(net "USB2_5_DP")
	)
	(segment
		(start 357.406956 -42.112184)
		(end 358.45242 -42.545254)
		(width 0.14732)
		(layer "In4.Cu")
		(net "USB2_5_DP")
	)
	(segment
		(start 18.23212 -16.19123)
		(end 18.59915 -16.156686)
		(width 0.14732)
		(layer "In4.Cu")
		(net "USB2_5_DP")
	)
	(segment
		(start 354.924614 -37.778436)
		(end 354.857304 -37.940996)
		(width 0.14732)
		(layer "In4.Cu")
		(net "USB2_5_DP")
	)
	(segment
		(start 47.219362 -12.503912)
		(end 50.085244 -11.31697)
		(width 0.14732)
		(layer "In4.Cu")
		(net "USB2_5_DP")
	)
	(segment
		(start 16.16456 -20.239228)
		(end 14.32814 -18.402808)
		(width 0.14732)
		(layer "In4.Cu")
		(net "USB2_5_DP")
	)
	(segment
		(start 14.32814 -17.099788)
		(end 15.0876 -16.340328)
		(width 0.14732)
		(layer "In4.Cu")
		(net "USB2_5_DP")
	)
	(segment
		(start 146.2659 -9.995408)
		(end 161.46526 -9.995408)
		(width 0.14732)
		(layer "In4.Cu")
		(net "USB2_5_DP")
	)
	(segment
		(start 356.234238 -40.939466)
		(end 357.406956 -42.112184)
		(width 0.14732)
		(layer "In4.Cu")
		(net "USB2_5_DP")
	)
	(segment
		(start 18.59915 -16.156686)
		(end 18.729706 -15.998952)
		(width 0.14732)
		(layer "In4.Cu")
		(net "USB2_5_DP")
	)
	(segment
		(start 131.9149 -9.058148)
		(end 137.272268 -9.058148)
		(width 0.14732)
		(layer "In4.Cu")
		(net "USB2_5_DP")
	)
	(segment
		(start 259.38099 -38.150038)
		(end 261.115302 -36.415726)
		(width 0.14732)
		(layer "In4.Cu")
		(net "USB2_5_DP")
	)
	(segment
		(start 15.91564 -20.987766)
		(end 15.91564 -21.191728)
		(width 0.13208)
		(layer "F.Cu")
		(net "USB2_5_DN")
	)
	(segment
		(start 351.09912 -44.384468)
		(end 351.09912 -44.906692)
		(width 0.0889)
		(layer "F.Cu")
		(net "USB2_5_DN")
	)
	(segment
		(start 14.578584 -19.285204)
		(end 14.578584 -18.4531)
		(width 0.13208)
		(layer "F.Cu")
		(net "USB2_5_DN")
	)
	(segment
		(start 347.40215 -44.948602)
		(end 347.214698 -44.948602)
		(width 0.0889)
		(layer "F.Cu")
		(net "USB2_5_DN")
	)
	(segment
		(start 348.704662 -45.280326)
		(end 348.605856 -45.18152)
		(width 0.0889)
		(layer "F.Cu")
		(net "USB2_5_DN")
	)
	(segment
		(start 352.289872 -43.193716)
		(end 352.10496 -43.378628)
		(width 0.0889)
		(layer "F.Cu")
		(net "USB2_5_DN")
	)
	(segment
		(start 14.578584 -18.4531)
		(end 13.196316 -17.070832)
		(width 0.13208)
		(layer "F.Cu")
		(net "USB2_5_DN")
	)
	(segment
		(start 15.29588 -20.0025)
		(end 14.578584 -19.285204)
		(width 0.13208)
		(layer "F.Cu")
		(net "USB2_5_DN")
	)
	(segment
		(start 350.180656 -45.18152)
		(end 350.08185 -45.280326)
		(width 0.0889)
		(layer "F.Cu")
		(net "USB2_5_DN")
	)
	(segment
		(start 358.608376 -41.654984)
		(end 354.443538 -41.654984)
		(width 0.13208)
		(layer "F.Cu")
		(net "USB2_5_DN")
	)
	(segment
		(start 347.932248 -45.280326)
		(end 347.688916 -45.036994)
		(width 0.0889)
		(layer "F.Cu")
		(net "USB2_5_DN")
	)
	(segment
		(start 16.03502 -20.741894)
		(end 16.03502 -20.868386)
		(width 0.13208)
		(layer "F.Cu")
		(net "USB2_5_DN")
	)
	(segment
		(start 348.32925 -45.280326)
		(end 347.932248 -45.280326)
		(width 0.0889)
		(layer "F.Cu")
		(net "USB2_5_DN")
	)
	(segment
		(start 15.29588 -20.53844)
		(end 15.29588 -20.0025)
		(width 0.13208)
		(layer "F.Cu")
		(net "USB2_5_DN")
	)
	(segment
		(start 352.792792 -42.690796)
		(end 352.60788 -42.875708)
		(width 0.0889)
		(layer "F.Cu")
		(net "USB2_5_DN")
	)
	(segment
		(start 348.605856 -45.18152)
		(end 348.428056 -45.18152)
		(width 0.0889)
		(layer "F.Cu")
		(net "USB2_5_DN")
	)
	(segment
		(start 15.91564 -21.191728)
		(end 15.61338 -21.493988)
		(width 0.13208)
		(layer "F.Cu")
		(net "USB2_5_DN")
	)
	(segment
		(start 354.386896 -41.689528)
		(end 353.79406 -41.689528)
		(width 0.0889)
		(layer "F.Cu")
		(net "USB2_5_DN")
	)
	(segment
		(start 16.03502 -20.868386)
		(end 15.91564 -20.987766)
		(width 0.13208)
		(layer "F.Cu")
		(net "USB2_5_DN")
	)
	(segment
		(start 359.28554 -43.312588)
		(end 359.28554 -42.332148)
		(width 0.13208)
		(layer "F.Cu")
		(net "USB2_5_DN")
	)
	(segment
		(start 347.490542 -45.036994)
		(end 347.40215 -44.948602)
		(width 0.0889)
		(layer "F.Cu")
		(net "USB2_5_DN")
	)
	(segment
		(start 352.475038 -42.875708)
		(end 352.289872 -43.060874)
		(width 0.0889)
		(layer "F.Cu")
		(net "USB2_5_DN")
	)
	(segment
		(start 350.358456 -45.18152)
		(end 350.180656 -45.18152)
		(width 0.0889)
		(layer "F.Cu")
		(net "USB2_5_DN")
	)
	(segment
		(start 351.972118 -43.378628)
		(end 351.786952 -43.563794)
		(width 0.0889)
		(layer "F.Cu")
		(net "USB2_5_DN")
	)
	(segment
		(start 347.688916 -45.036994)
		(end 347.490542 -45.036994)
		(width 0.0889)
		(layer "F.Cu")
		(net "USB2_5_DN")
	)
	(segment
		(start 16.034004 -20.741894)
		(end 16.03502 -20.741894)
		(width 0.13208)
		(layer "F.Cu")
		(net "USB2_5_DN")
	)
	(segment
		(start 359.583736 -43.610784)
		(end 359.28554 -43.312588)
		(width 0.13208)
		(layer "F.Cu")
		(net "USB2_5_DN")
	)
	(segment
		(start 351.09912 -44.906692)
		(end 350.725486 -45.280326)
		(width 0.0889)
		(layer "F.Cu")
		(net "USB2_5_DN")
	)
	(segment
		(start 351.284032 -44.066714)
		(end 351.284032 -44.199556)
		(width 0.0889)
		(layer "F.Cu")
		(net "USB2_5_DN")
	)
	(segment
		(start 352.10496 -43.378628)
		(end 351.972118 -43.378628)
		(width 0.0889)
		(layer "F.Cu")
		(net "USB2_5_DN")
	)
	(segment
		(start 15.29588 -20.53844)
		(end 15.83055 -20.53844)
		(width 0.13208)
		(layer "F.Cu")
		(net "USB2_5_DN")
	)
	(segment
		(start 352.289872 -43.060874)
		(end 352.289872 -43.193716)
		(width 0.0889)
		(layer "F.Cu")
		(net "USB2_5_DN")
	)
	(segment
		(start 359.28554 -42.332148)
		(end 358.608376 -41.654984)
		(width 0.13208)
		(layer "F.Cu")
		(net "USB2_5_DN")
	)
	(segment
		(start 350.08185 -45.280326)
		(end 348.704662 -45.280326)
		(width 0.0889)
		(layer "F.Cu")
		(net "USB2_5_DN")
	)
	(segment
		(start 352.60788 -42.875708)
		(end 352.475038 -42.875708)
		(width 0.0889)
		(layer "F.Cu")
		(net "USB2_5_DN")
	)
	(segment
		(start 350.725486 -45.280326)
		(end 350.457262 -45.280326)
		(width 0.0889)
		(layer "F.Cu")
		(net "USB2_5_DN")
	)
	(segment
		(start 352.977958 -42.372788)
		(end 352.792792 -42.557954)
		(width 0.0889)
		(layer "F.Cu")
		(net "USB2_5_DN")
	)
	(segment
		(start 351.60204 -43.881548)
		(end 351.469198 -43.881548)
		(width 0.0889)
		(layer "F.Cu")
		(net "USB2_5_DN")
	)
	(segment
		(start 351.469198 -43.881548)
		(end 351.284032 -44.066714)
		(width 0.0889)
		(layer "F.Cu")
		(net "USB2_5_DN")
	)
	(segment
		(start 13.196316 -17.070832)
		(end 13.196316 -16.138652)
		(width 0.13208)
		(layer "F.Cu")
		(net "USB2_5_DN")
	)
	(segment
		(start 15.83055 -20.53844)
		(end 16.034004 -20.741894)
		(width 0.13208)
		(layer "F.Cu")
		(net "USB2_5_DN")
	)
	(segment
		(start 353.79406 -41.689528)
		(end 353.1108 -42.372788)
		(width 0.0889)
		(layer "F.Cu")
		(net "USB2_5_DN")
	)
	(segment
		(start 350.457262 -45.280326)
		(end 350.358456 -45.18152)
		(width 0.0889)
		(layer "F.Cu")
		(net "USB2_5_DN")
	)
	(segment
		(start 351.786952 -43.696636)
		(end 351.60204 -43.881548)
		(width 0.0889)
		(layer "F.Cu")
		(net "USB2_5_DN")
	)
	(segment
		(start 348.428056 -45.18152)
		(end 348.32925 -45.280326)
		(width 0.0889)
		(layer "F.Cu")
		(net "USB2_5_DN")
	)
	(segment
		(start 13.196316 -16.138652)
		(end 12.778232 -15.720568)
		(width 0.13208)
		(layer "F.Cu")
		(net "USB2_5_DN")
	)
	(segment
		(start 354.443538 -41.654984)
		(end 354.42144 -41.654984)
		(width 0.0889)
		(layer "F.Cu")
		(net "USB2_5_DN")
	)
	(segment
		(start 351.786952 -43.563794)
		(end 351.786952 -43.696636)
		(width 0.0889)
		(layer "F.Cu")
		(net "USB2_5_DN")
	)
	(segment
		(start 354.42144 -41.654984)
		(end 354.386896 -41.689528)
		(width 0.0889)
		(layer "F.Cu")
		(net "USB2_5_DN")
	)
	(segment
		(start 353.1108 -42.372788)
		(end 352.977958 -42.372788)
		(width 0.0889)
		(layer "F.Cu")
		(net "USB2_5_DN")
	)
	(segment
		(start 351.284032 -44.199556)
		(end 351.09912 -44.384468)
		(width 0.0889)
		(layer "F.Cu")
		(net "USB2_5_DN")
	)
	(segment
		(start 352.792792 -42.557954)
		(end 352.792792 -42.690796)
		(width 0.0889)
		(layer "F.Cu")
		(net "USB2_5_DN")
	)
	(via
		(at 15.29588 -20.53844)
		(size 0.762)
		(drill 0.381)
		(layers "F.Cu" "B.Cu")
		(net "USB2_5_DN")
	)
	(segment
		(start 359.282746 -43.309794)
		(end 359.583736 -43.610784)
		(width 0.14732)
		(layer "In4.Cu")
		(net "USB2_5_DN")
	)
	(segment
		(start 348.726506 -23.038562)
		(end 353.547172 -27.859228)
		(width 0.14732)
		(layer "In4.Cu")
		(net "USB2_5_DN")
	)
	(segment
		(start 47.063914 -12.271248)
		(end 50.032412 -11.041888)
		(width 0.14732)
		(layer "In4.Cu")
		(net "USB2_5_DN")
	)
	(segment
		(start 321.164712 -15.537688)
		(end 337.157822 -15.537688)
		(width 0.14732)
		(layer "In4.Cu")
		(net "USB2_5_DN")
	)
	(segment
		(start 119.758206 -14.689328)
		(end 124.379228 -14.689328)
		(width 0.14732)
		(layer "In4.Cu")
		(net "USB2_5_DN")
	)
	(segment
		(start 146.379692 -9.721088)
		(end 161.351468 -9.721088)
		(width 0.14732)
		(layer "In4.Cu")
		(net "USB2_5_DN")
	)
	(segment
		(start 357.562404 -41.87952)
		(end 358.607868 -42.31259)
		(width 0.14732)
		(layer "In4.Cu")
		(net "USB2_5_DN")
	)
	(segment
		(start 359.282746 -42.987468)
		(end 359.282746 -43.309794)
		(width 0.14732)
		(layer "In4.Cu")
		(net "USB2_5_DN")
	)
	(segment
		(start 358.607868 -42.31259)
		(end 359.282746 -42.987468)
		(width 0.14732)
		(layer "In4.Cu")
		(net "USB2_5_DN")
	)
	(segment
		(start 81.423002 -12.483338)
		(end 82.028792 -13.089128)
		(width 0.14732)
		(layer "In4.Cu")
		(net "USB2_5_DN")
	)
	(segment
		(start 77.309472 -11.402568)
		(end 78.813914 -11.402568)
		(width 0.14732)
		(layer "In4.Cu")
		(net "USB2_5_DN")
	)
	(segment
		(start 254.503428 -39.873428)
		(end 259.225542 -37.917374)
		(width 0.14732)
		(layer "In4.Cu")
		(net "USB2_5_DN")
	)
	(segment
		(start 356.466902 -40.784018)
		(end 357.562404 -41.87952)
		(width 0.14732)
		(layer "In4.Cu")
		(net "USB2_5_DN")
	)
	(segment
		(start 15.89024 -20.35302)
		(end 14.05382 -18.5166)
		(width 0.14732)
		(layer "In4.Cu")
		(net "USB2_5_DN")
	)
	(segment
		(start 354.0252 -34.88944)
		(end 356.466902 -40.784018)
		(width 0.14732)
		(layer "In4.Cu")
		(net "USB2_5_DN")
	)
	(segment
		(start 46.480476 -12.854432)
		(end 47.063914 -12.271248)
		(width 0.14732)
		(layer "In4.Cu")
		(net "USB2_5_DN")
	)
	(segment
		(start 353.547172 -27.859228)
		(end 354.0252 -29.013404)
		(width 0.14732)
		(layer "In4.Cu")
		(net "USB2_5_DN")
	)
	(segment
		(start 14.05382 -18.5166)
		(end 14.05382 -16.985996)
		(width 0.14732)
		(layer "In4.Cu")
		(net "USB2_5_DN")
	)
	(segment
		(start 163.312348 -7.760208)
		(end 178.53914 -7.760208)
		(width 0.14732)
		(layer "In4.Cu")
		(net "USB2_5_DN")
	)
	(segment
		(start 260.959854 -36.183062)
		(end 301.229268 -19.503136)
		(width 0.14732)
		(layer "In4.Cu")
		(net "USB2_5_DN")
	)
	(segment
		(start 83.463892 -13.683488)
		(end 117.329712 -13.683488)
		(width 0.14732)
		(layer "In4.Cu")
		(net "USB2_5_DN")
	)
	(segment
		(start 218.233752 -13.706348)
		(end 221.36862 -16.841216)
		(width 0.14732)
		(layer "In4.Cu")
		(net "USB2_5_DN")
	)
	(segment
		(start 137.85342 -9.251188)
		(end 145.909792 -9.251188)
		(width 0.14732)
		(layer "In4.Cu")
		(net "USB2_5_DN")
	)
	(segment
		(start 78.813914 -11.402568)
		(end 81.423002 -12.483338)
		(width 0.14732)
		(layer "In4.Cu")
		(net "USB2_5_DN")
	)
	(segment
		(start 354.0252 -29.013404)
		(end 354.0252 -34.88944)
		(width 0.14732)
		(layer "In4.Cu")
		(net "USB2_5_DN")
	)
	(segment
		(start 117.329712 -13.683488)
		(end 119.758206 -14.689328)
		(width 0.14732)
		(layer "In4.Cu")
		(net "USB2_5_DN")
	)
	(segment
		(start 221.36862 -16.841216)
		(end 221.36862 -34.640266)
		(width 0.14732)
		(layer "In4.Cu")
		(net "USB2_5_DN")
	)
	(segment
		(start 82.028792 -13.089128)
		(end 83.463892 -13.683488)
		(width 0.14732)
		(layer "In4.Cu")
		(net "USB2_5_DN")
	)
	(segment
		(start 339.28558 -16.183102)
		(end 344.895678 -19.931634)
		(width 0.14732)
		(layer "In4.Cu")
		(net "USB2_5_DN")
	)
	(segment
		(start 161.351468 -9.721088)
		(end 163.312348 -7.760208)
		(width 0.14732)
		(layer "In4.Cu")
		(net "USB2_5_DN")
	)
	(segment
		(start 15.61338 -21.493988)
		(end 15.89024 -21.217128)
		(width 0.14732)
		(layer "In4.Cu")
		(net "USB2_5_DN")
	)
	(segment
		(start 236.73943 -42.692828)
		(end 246.885206 -42.692828)
		(width 0.14732)
		(layer "In4.Cu")
		(net "USB2_5_DN")
	)
	(segment
		(start 180.179218 -9.400286)
		(end 183.358282 -10.71753)
		(width 0.14732)
		(layer "In4.Cu")
		(net "USB2_5_DN")
	)
	(segment
		(start 337.157822 -15.537688)
		(end 339.28558 -16.183102)
		(width 0.14732)
		(layer "In4.Cu")
		(net "USB2_5_DN")
	)
	(segment
		(start 183.358282 -10.71753)
		(end 184.119774 -11.479022)
		(width 0.14732)
		(layer "In4.Cu")
		(net "USB2_5_DN")
	)
	(segment
		(start 344.895678 -19.931634)
		(end 346.54363 -21.57984)
		(width 0.14732)
		(layer "In4.Cu")
		(net "USB2_5_DN")
	)
	(segment
		(start 14.05382 -16.985996)
		(end 14.963394 -16.076168)
		(width 0.14732)
		(layer "In4.Cu")
		(net "USB2_5_DN")
	)
	(segment
		(start 259.225542 -37.917374)
		(end 260.959854 -36.183062)
		(width 0.14732)
		(layer "In4.Cu")
		(net "USB2_5_DN")
	)
	(segment
		(start 45.762926 -13.191998)
		(end 46.480476 -12.854432)
		(width 0.14732)
		(layer "In4.Cu")
		(net "USB2_5_DN")
	)
	(segment
		(start 221.36862 -34.640266)
		(end 221.720156 -35.489134)
		(width 0.14732)
		(layer "In4.Cu")
		(net "USB2_5_DN")
	)
	(segment
		(start 253.692406 -39.873428)
		(end 254.503428 -39.873428)
		(width 0.14732)
		(layer "In4.Cu")
		(net "USB2_5_DN")
	)
	(segment
		(start 20.075398 -15.597378)
		(end 20.075398 -15.597124)
		(width 0.14732)
		(layer "In4.Cu")
		(net "USB2_5_DN")
	)
	(segment
		(start 184.119774 -11.479022)
		(end 189.496446 -13.706348)
		(width 0.14732)
		(layer "In4.Cu")
		(net "USB2_5_DN")
	)
	(segment
		(start 15.89024 -21.217128)
		(end 15.89024 -20.35302)
		(width 0.14732)
		(layer "In4.Cu")
		(net "USB2_5_DN")
	)
	(segment
		(start 221.720156 -35.489134)
		(end 223.397064 -37.166042)
		(width 0.14732)
		(layer "In4.Cu")
		(net "USB2_5_DN")
	)
	(segment
		(start 124.379228 -14.689328)
		(end 126.967996 -13.61694)
		(width 0.14732)
		(layer "In4.Cu")
		(net "USB2_5_DN")
	)
	(segment
		(start 131.801108 -8.783828)
		(end 137.38606 -8.783828)
		(width 0.14732)
		(layer "In4.Cu")
		(net "USB2_5_DN")
	)
	(segment
		(start 145.909792 -9.251188)
		(end 146.379692 -9.721088)
		(width 0.14732)
		(layer "In4.Cu")
		(net "USB2_5_DN")
	)
	(segment
		(start 346.54363 -21.57984)
		(end 348.726506 -23.038562)
		(width 0.14732)
		(layer "In4.Cu")
		(net "USB2_5_DN")
	)
	(segment
		(start 126.967996 -13.61694)
		(end 131.801108 -8.783828)
		(width 0.14732)
		(layer "In4.Cu")
		(net "USB2_5_DN")
	)
	(segment
		(start 14.963394 -16.076168)
		(end 20.075398 -15.597378)
		(width 0.14732)
		(layer "In4.Cu")
		(net "USB2_5_DN")
	)
	(segment
		(start 301.229268 -19.503136)
		(end 321.164712 -15.537688)
		(width 0.14732)
		(layer "In4.Cu")
		(net "USB2_5_DN")
	)
	(segment
		(start 223.397064 -37.166042)
		(end 236.73943 -42.692828)
		(width 0.14732)
		(layer "In4.Cu")
		(net "USB2_5_DN")
	)
	(segment
		(start 189.496446 -13.706348)
		(end 218.233752 -13.706348)
		(width 0.14732)
		(layer "In4.Cu")
		(net "USB2_5_DN")
	)
	(segment
		(start 137.38606 -8.783828)
		(end 137.85342 -9.251188)
		(width 0.14732)
		(layer "In4.Cu")
		(net "USB2_5_DN")
	)
	(segment
		(start 178.53914 -7.760208)
		(end 180.179218 -9.400286)
		(width 0.14732)
		(layer "In4.Cu")
		(net "USB2_5_DN")
	)
	(segment
		(start 246.885206 -42.692828)
		(end 253.692406 -39.873428)
		(width 0.14732)
		(layer "In4.Cu")
		(net "USB2_5_DN")
	)
	(segment
		(start 20.075398 -15.597124)
		(end 45.762926 -13.191998)
		(width 0.14732)
		(layer "In4.Cu")
		(net "USB2_5_DN")
	)
	(segment
		(start 50.032412 -11.041888)
		(end 77.309472 -11.402568)
		(width 0.14732)
		(layer "In4.Cu")
		(net "USB2_5_DN")
	)
	(segment
		(start 346.402406 -42.518076)
		(end 346.231718 -42.447464)
		(width 0.0889)
		(layer "F.Cu")
		(net "TP_USB2_4_DP")
	)
	(segment
		(start 348.429834 -42.642028)
		(end 347.090746 -42.642028)
		(width 0.0889)
		(layer "F.Cu")
		(net "TP_USB2_4_DP")
	)
	(segment
		(start 346.655898 -42.750994)
		(end 346.53855 -42.649648)
		(width 0.0889)
		(layer "F.Cu")
		(net "TP_USB2_4_DP")
	)
	(segment
		(start 353.599496 -37.495988)
		(end 353.599496 -38.306248)
		(width 0.0889)
		(layer "F.Cu")
		(net "TP_USB2_4_DP")
	)
	(segment
		(start 364.191042 -37.197284)
		(end 361.155488 -37.197284)
		(width 0.13208)
		(layer "F.Cu")
		(net "TP_USB2_4_DP")
	)
	(segment
		(start 361.13593 -37.177726)
		(end 360.622596 -36.965128)
		(width 0.13208)
		(layer "F.Cu")
		(net "TP_USB2_4_DP")
	)
	(segment
		(start 347.028516 -42.704258)
		(end 346.915486 -42.750994)
		(width 0.0889)
		(layer "F.Cu")
		(net "TP_USB2_4_DP")
	)
	(segment
		(start 358.90581 -36.253928)
		(end 354.890324 -36.253928)
		(width 0.13208)
		(layer "F.Cu")
		(net "TP_USB2_4_DP")
	)
	(segment
		(start 360.622596 -36.965128)
		(end 358.90581 -36.253928)
		(width 0.13208)
		(layer "F.Cu")
		(net "TP_USB2_4_DP")
	)
	(segment
		(start 353.599496 -38.306248)
		(end 349.70466 -42.201084)
		(width 0.0889)
		(layer "F.Cu")
		(net "TP_USB2_4_DP")
	)
	(segment
		(start 349.500952 -42.397934)
		(end 348.673928 -42.397934)
		(width 0.0889)
		(layer "F.Cu")
		(net "TP_USB2_4_DP")
	)
	(segment
		(start 346.53855 -42.649648)
		(end 346.50426 -42.61993)
		(width 0.0889)
		(layer "F.Cu")
		(net "TP_USB2_4_DP")
	)
	(segment
		(start 349.70466 -42.201084)
		(end 349.697802 -42.201084)
		(width 0.0889)
		(layer "F.Cu")
		(net "TP_USB2_4_DP")
	)
	(segment
		(start 347.090746 -42.642028)
		(end 347.028516 -42.704258)
		(width 0.0889)
		(layer "F.Cu")
		(net "TP_USB2_4_DP")
	)
	(segment
		(start 349.697802 -42.201084)
		(end 349.500952 -42.397934)
		(width 0.0889)
		(layer "F.Cu")
		(net "TP_USB2_4_DP")
	)
	(segment
		(start 364.493302 -37.499544)
		(end 364.191042 -37.197284)
		(width 0.13208)
		(layer "F.Cu")
		(net "TP_USB2_4_DP")
	)
	(segment
		(start 353.880166 -37.215318)
		(end 353.599496 -37.495988)
		(width 0.0889)
		(layer "F.Cu")
		(net "TP_USB2_4_DP")
	)
	(segment
		(start 353.944428 -37.199824)
		(end 353.928934 -37.215318)
		(width 0.0889)
		(layer "F.Cu")
		(net "TP_USB2_4_DP")
	)
	(segment
		(start 354.890324 -36.253928)
		(end 353.944428 -37.199824)
		(width 0.13208)
		(layer "F.Cu")
		(net "TP_USB2_4_DP")
	)
	(segment
		(start 346.915486 -42.750994)
		(end 346.655898 -42.750994)
		(width 0.0889)
		(layer "F.Cu")
		(net "TP_USB2_4_DP")
	)
	(segment
		(start 346.231718 -42.447464)
		(end 345.96959 -42.447464)
		(width 0.0889)
		(layer "F.Cu")
		(net "TP_USB2_4_DP")
	)
	(segment
		(start 361.155488 -37.197284)
		(end 361.13593 -37.177726)
		(width 0.13208)
		(layer "F.Cu")
		(net "TP_USB2_4_DP")
	)
	(segment
		(start 353.928934 -37.215318)
		(end 353.880166 -37.215318)
		(width 0.0889)
		(layer "F.Cu")
		(net "TP_USB2_4_DP")
	)
	(segment
		(start 346.50426 -42.61993)
		(end 346.402406 -42.518076)
		(width 0.0889)
		(layer "F.Cu")
		(net "TP_USB2_4_DP")
	)
	(segment
		(start 348.673928 -42.397934)
		(end 348.429834 -42.642028)
		(width 0.0889)
		(layer "F.Cu")
		(net "TP_USB2_4_DP")
	)
	(via
		(at 364.493302 -37.499544)
		(size 0.762)
		(drill 0.381)
		(layers "F.Cu" "B.Cu")
		(net "TP_USB2_4_DP")
	)
	(segment
		(start 361.23499 -36.938204)
		(end 360.622596 -36.684458)
		(width 0.13208)
		(layer "F.Cu")
		(net "TP_USB2_4_DN")
	)
	(segment
		(start 350.293686 -41.342818)
		(end 350.16821 -41.468294)
		(width 0.0889)
		(layer "F.Cu")
		(net "TP_USB2_4_DN")
	)
	(segment
		(start 353.40925 -37.416994)
		(end 353.40925 -37.674042)
		(width 0.0889)
		(layer "F.Cu")
		(net "TP_USB2_4_DN")
	)
	(segment
		(start 353.76104 -37.016436)
		(end 353.745546 -37.03193)
		(width 0.0889)
		(layer "F.Cu")
		(net "TP_USB2_4_DN")
	)
	(segment
		(start 353.745546 -37.080698)
		(end 353.40925 -37.416994)
		(width 0.0889)
		(layer "F.Cu")
		(net "TP_USB2_4_DN")
	)
	(segment
		(start 352.402902 -39.093394)
		(end 352.277172 -39.219124)
		(width 0.0889)
		(layer "F.Cu")
		(net "TP_USB2_4_DN")
	)
	(segment
		(start 353.310444 -37.950648)
		(end 353.40925 -38.049454)
		(width 0.0889)
		(layer "F.Cu")
		(net "TP_USB2_4_DN")
	)
	(segment
		(start 352.668586 -38.82771)
		(end 352.668586 -38.967918)
		(width 0.0889)
		(layer "F.Cu")
		(net "TP_USB2_4_DN")
	)
	(segment
		(start 347.086428 -42.451782)
		(end 347.08211 -42.447464)
		(width 0.0889)
		(layer "F.Cu")
		(net "TP_USB2_4_DN")
	)
	(segment
		(start 349.510858 -41.985438)
		(end 349.510858 -42.118788)
		(width 0.0889)
		(layer "F.Cu")
		(net "TP_USB2_4_DN")
	)
	(segment
		(start 352.668586 -38.967918)
		(end 352.54311 -39.093394)
		(width 0.0889)
		(layer "F.Cu")
		(net "TP_USB2_4_DN")
	)
	(segment
		(start 352.011488 -39.484808)
		(end 351.885758 -39.610538)
		(width 0.0889)
		(layer "F.Cu")
		(net "TP_USB2_4_DN")
	)
	(segment
		(start 349.421958 -42.207688)
		(end 348.594934 -42.207688)
		(width 0.0889)
		(layer "F.Cu")
		(net "TP_USB2_4_DN")
	)
	(segment
		(start 354.041202 -36.736274)
		(end 353.76104 -37.016436)
		(width 0.13208)
		(layer "F.Cu")
		(net "TP_USB2_4_DN")
	)
	(segment
		(start 352.54311 -39.093394)
		(end 352.402902 -39.093394)
		(width 0.0889)
		(layer "F.Cu")
		(net "TP_USB2_4_DN")
	)
	(segment
		(start 351.885758 -39.610538)
		(end 351.885758 -39.750746)
		(width 0.0889)
		(layer "F.Cu")
		(net "TP_USB2_4_DN")
	)
	(segment
		(start 351.103184 -40.53332)
		(end 350.951038 -40.685466)
		(width 0.0889)
		(layer "F.Cu")
		(net "TP_USB2_4_DN")
	)
	(segment
		(start 350.951038 -40.685466)
		(end 350.81083 -40.685466)
		(width 0.0889)
		(layer "F.Cu")
		(net "TP_USB2_4_DN")
	)
	(segment
		(start 350.16821 -41.468294)
		(end 350.028002 -41.468294)
		(width 0.0889)
		(layer "F.Cu")
		(net "TP_USB2_4_DN")
	)
	(segment
		(start 349.510858 -42.118788)
		(end 349.421958 -42.207688)
		(width 0.0889)
		(layer "F.Cu")
		(net "TP_USB2_4_DN")
	)
	(segment
		(start 364.54588 -36.583366)
		(end 364.191042 -36.938204)
		(width 0.13208)
		(layer "F.Cu")
		(net "TP_USB2_4_DN")
	)
	(segment
		(start 353.310444 -37.772848)
		(end 353.310444 -37.950648)
		(width 0.0889)
		(layer "F.Cu")
		(net "TP_USB2_4_DN")
	)
	(segment
		(start 352.151696 -39.484808)
		(end 352.011488 -39.484808)
		(width 0.0889)
		(layer "F.Cu")
		(net "TP_USB2_4_DN")
	)
	(segment
		(start 358.957372 -35.994848)
		(end 354.782628 -35.994848)
		(width 0.13208)
		(layer "F.Cu")
		(net "TP_USB2_4_DN")
	)
	(segment
		(start 360.622596 -36.684458)
		(end 358.957372 -35.994848)
		(width 0.13208)
		(layer "F.Cu")
		(net "TP_USB2_4_DN")
	)
	(segment
		(start 350.028002 -41.468294)
		(end 349.902272 -41.594024)
		(width 0.0889)
		(layer "F.Cu")
		(net "TP_USB2_4_DN")
	)
	(segment
		(start 350.293686 -41.20261)
		(end 350.293686 -41.342818)
		(width 0.0889)
		(layer "F.Cu")
		(net "TP_USB2_4_DN")
	)
	(segment
		(start 353.40925 -38.227254)
		(end 352.934524 -38.70198)
		(width 0.0889)
		(layer "F.Cu")
		(net "TP_USB2_4_DN")
	)
	(segment
		(start 348.35084 -42.451782)
		(end 347.086428 -42.451782)
		(width 0.0889)
		(layer "F.Cu")
		(net "TP_USB2_4_DN")
	)
	(segment
		(start 351.368868 -40.267636)
		(end 351.228914 -40.267636)
		(width 0.0889)
		(layer "F.Cu")
		(net "TP_USB2_4_DN")
	)
	(segment
		(start 351.494344 -40.14216)
		(end 351.368868 -40.267636)
		(width 0.0889)
		(layer "F.Cu")
		(net "TP_USB2_4_DN")
	)
	(segment
		(start 353.745546 -37.03193)
		(end 353.745546 -37.080698)
		(width 0.0889)
		(layer "F.Cu")
		(net "TP_USB2_4_DN")
	)
	(segment
		(start 350.6851 -40.951404)
		(end 350.559624 -41.07688)
		(width 0.0889)
		(layer "F.Cu")
		(net "TP_USB2_4_DN")
	)
	(segment
		(start 351.103184 -40.393366)
		(end 351.103184 -40.53332)
		(width 0.0889)
		(layer "F.Cu")
		(net "TP_USB2_4_DN")
	)
	(segment
		(start 352.277172 -39.359332)
		(end 352.151696 -39.484808)
		(width 0.0889)
		(layer "F.Cu")
		(net "TP_USB2_4_DN")
	)
	(segment
		(start 349.776796 -41.859708)
		(end 349.636588 -41.859708)
		(width 0.0889)
		(layer "F.Cu")
		(net "TP_USB2_4_DN")
	)
	(segment
		(start 352.934524 -38.70198)
		(end 352.794316 -38.70198)
		(width 0.0889)
		(layer "F.Cu")
		(net "TP_USB2_4_DN")
	)
	(segment
		(start 351.885758 -39.750746)
		(end 351.760282 -39.876222)
		(width 0.0889)
		(layer "F.Cu")
		(net "TP_USB2_4_DN")
	)
	(segment
		(start 354.782628 -35.994848)
		(end 354.49764 -36.279836)
		(width 0.13208)
		(layer "F.Cu")
		(net "TP_USB2_4_DN")
	)
	(segment
		(start 352.277172 -39.219124)
		(end 352.277172 -39.359332)
		(width 0.0889)
		(layer "F.Cu")
		(net "TP_USB2_4_DN")
	)
	(segment
		(start 349.902272 -41.734232)
		(end 349.776796 -41.859708)
		(width 0.0889)
		(layer "F.Cu")
		(net "TP_USB2_4_DN")
	)
	(segment
		(start 364.54588 -36.053268)
		(end 364.54588 -36.583366)
		(width 0.13208)
		(layer "F.Cu")
		(net "TP_USB2_4_DN")
	)
	(segment
		(start 352.794316 -38.70198)
		(end 352.668586 -38.82771)
		(width 0.0889)
		(layer "F.Cu")
		(net "TP_USB2_4_DN")
	)
	(segment
		(start 351.228914 -40.267636)
		(end 351.103184 -40.393366)
		(width 0.0889)
		(layer "F.Cu")
		(net "TP_USB2_4_DN")
	)
	(segment
		(start 354.49764 -36.279836)
		(end 354.321618 -36.279836)
		(width 0.13208)
		(layer "F.Cu")
		(net "TP_USB2_4_DN")
	)
	(segment
		(start 354.321618 -36.279836)
		(end 354.041202 -36.560252)
		(width 0.13208)
		(layer "F.Cu")
		(net "TP_USB2_4_DN")
	)
	(segment
		(start 354.041202 -36.560252)
		(end 354.041202 -36.736274)
		(width 0.13208)
		(layer "F.Cu")
		(net "TP_USB2_4_DN")
	)
	(segment
		(start 350.419416 -41.07688)
		(end 350.293686 -41.20261)
		(width 0.0889)
		(layer "F.Cu")
		(net "TP_USB2_4_DN")
	)
	(segment
		(start 350.6851 -40.811196)
		(end 350.6851 -40.951404)
		(width 0.0889)
		(layer "F.Cu")
		(net "TP_USB2_4_DN")
	)
	(segment
		(start 351.620074 -39.876222)
		(end 351.494344 -40.001952)
		(width 0.0889)
		(layer "F.Cu")
		(net "TP_USB2_4_DN")
	)
	(segment
		(start 351.494344 -40.001952)
		(end 351.494344 -40.14216)
		(width 0.0889)
		(layer "F.Cu")
		(net "TP_USB2_4_DN")
	)
	(segment
		(start 349.902272 -41.594024)
		(end 349.902272 -41.734232)
		(width 0.0889)
		(layer "F.Cu")
		(net "TP_USB2_4_DN")
	)
	(segment
		(start 364.191042 -36.938204)
		(end 361.23499 -36.938204)
		(width 0.13208)
		(layer "F.Cu")
		(net "TP_USB2_4_DN")
	)
	(segment
		(start 349.636588 -41.859708)
		(end 349.510858 -41.985438)
		(width 0.0889)
		(layer "F.Cu")
		(net "TP_USB2_4_DN")
	)
	(segment
		(start 347.08211 -42.447464)
		(end 346.799662 -42.447464)
		(width 0.0889)
		(layer "F.Cu")
		(net "TP_USB2_4_DN")
	)
	(segment
		(start 350.559624 -41.07688)
		(end 350.419416 -41.07688)
		(width 0.0889)
		(layer "F.Cu")
		(net "TP_USB2_4_DN")
	)
	(segment
		(start 348.594934 -42.207688)
		(end 348.35084 -42.451782)
		(width 0.0889)
		(layer "F.Cu")
		(net "TP_USB2_4_DN")
	)
	(segment
		(start 353.40925 -38.049454)
		(end 353.40925 -38.227254)
		(width 0.0889)
		(layer "F.Cu")
		(net "TP_USB2_4_DN")
	)
	(segment
		(start 353.40925 -37.674042)
		(end 353.310444 -37.772848)
		(width 0.0889)
		(layer "F.Cu")
		(net "TP_USB2_4_DN")
	)
	(segment
		(start 350.81083 -40.685466)
		(end 350.6851 -40.811196)
		(width 0.0889)
		(layer "F.Cu")
		(net "TP_USB2_4_DN")
	)
	(segment
		(start 351.760282 -39.876222)
		(end 351.620074 -39.876222)
		(width 0.0889)
		(layer "F.Cu")
		(net "TP_USB2_4_DN")
	)
	(via
		(at 364.54588 -36.053268)
		(size 0.762)
		(drill 0.381)
		(layers "F.Cu" "B.Cu")
		(net "TP_USB2_4_DN")
	)
	(segment
		(start 389.0899 -25.138888)
		(end 388.78764 -25.441148)
		(width 0.13208)
		(layer "F.Cu")
		(net "USB2_3_DP")
	)
	(segment
		(start 389.532114 -19.769328)
		(end 389.98779 -20.225004)
		(width 0.13208)
		(layer "F.Cu")
		(net "USB2_3_DP")
	)
	(segment
		(start 349.13443 -44.570904)
		(end 349.13443 -44.402248)
		(width 0.0889)
		(layer "F.Cu")
		(net "USB2_3_DP")
	)
	(segment
		(start 346.85859 -44.750736)
		(end 346.679266 -44.750736)
		(width 0.0889)
		(layer "F.Cu")
		(net "USB2_3_DP")
	)
	(segment
		(start 347.704156 -44.64431)
		(end 347.115638 -44.64431)
		(width 0.0889)
		(layer "F.Cu")
		(net "USB2_3_DP")
	)
	(segment
		(start 389.98779 -21.35124)
		(end 389.0899 -22.24913)
		(width 0.13208)
		(layer "F.Cu")
		(net "USB2_3_DP")
	)
	(segment
		(start 346.593922 -44.676822)
		(end 346.251784 -44.448222)
		(width 0.0889)
		(layer "F.Cu")
		(net "USB2_3_DP")
	)
	(segment
		(start 388.982966 -19.769328)
		(end 389.532114 -19.769328)
		(width 0.13208)
		(layer "F.Cu")
		(net "USB2_3_DP")
	)
	(segment
		(start 348.892114 -44.81322)
		(end 349.13443 -44.570904)
		(width 0.0889)
		(layer "F.Cu")
		(net "USB2_3_DP")
	)
	(segment
		(start 388.982966 -19.769328)
		(end 388.982966 -19.22018)
		(width 0.13208)
		(layer "F.Cu")
		(net "USB2_3_DP")
	)
	(segment
		(start 388.403338 -18.640552)
		(end 387.640576 -16.798798)
		(width 0.13208)
		(layer "F.Cu")
		(net "USB2_3_DP")
	)
	(segment
		(start 389.98779 -20.225004)
		(end 389.98779 -21.35124)
		(width 0.13208)
		(layer "F.Cu")
		(net "USB2_3_DP")
	)
	(segment
		(start 349.13443 -44.402248)
		(end 348.98711 -44.254928)
		(width 0.0889)
		(layer "F.Cu")
		(net "USB2_3_DP")
	)
	(segment
		(start 346.251784 -44.448222)
		(end 345.96959 -44.448222)
		(width 0.0889)
		(layer "F.Cu")
		(net "USB2_3_DP")
	)
	(segment
		(start 387.640576 -16.798798)
		(end 387.640576 -15.03172)
		(width 0.13208)
		(layer "F.Cu")
		(net "USB2_3_DP")
	)
	(segment
		(start 387.640576 -15.03172)
		(end 387.262116 -14.65326)
		(width 0.13208)
		(layer "F.Cu")
		(net "USB2_3_DP")
	)
	(segment
		(start 388.982966 -19.22018)
		(end 388.403338 -18.640552)
		(width 0.13208)
		(layer "F.Cu")
		(net "USB2_3_DP")
	)
	(segment
		(start 389.0899 -22.24913)
		(end 389.0899 -25.138888)
		(width 0.13208)
		(layer "F.Cu")
		(net "USB2_3_DP")
	)
	(segment
		(start 348.093538 -44.254928)
		(end 347.704156 -44.64431)
		(width 0.0889)
		(layer "F.Cu")
		(net "USB2_3_DP")
	)
	(segment
		(start 348.98711 -44.254928)
		(end 348.093538 -44.254928)
		(width 0.0889)
		(layer "F.Cu")
		(net "USB2_3_DP")
	)
	(segment
		(start 347.115638 -44.64431)
		(end 346.85859 -44.750736)
		(width 0.0889)
		(layer "F.Cu")
		(net "USB2_3_DP")
	)
	(segment
		(start 346.679266 -44.750736)
		(end 346.593922 -44.676822)
		(width 0.0889)
		(layer "F.Cu")
		(net "USB2_3_DP")
	)
	(via
		(at 388.78764 -25.441148)
		(size 0.508)
		(drill 0.254)
		(layers "F.Cu" "B.Cu")
		(net "USB2_3_DP")
	)
	(via
		(at 388.982966 -19.769328)
		(size 0.762)
		(drill 0.381)
		(layers "F.Cu" "B.Cu")
		(net "USB2_3_DP")
	)
	(via
		(at 348.892114 -44.81322)
		(size 0.508)
		(drill 0.254)
		(layers "F.Cu" "B.Cu")
		(net "USB2_3_DP")
	)
	(segment
		(start 387.221476 -25.458928)
		(end 388.006336 -24.674068)
		(width 0.13208)
		(layer "B.Cu")
		(net "USB2_3_DP")
	)
	(segment
		(start 349.194374 -45.409866)
		(end 349.771716 -45.987208)
		(width 0.13208)
		(layer "B.Cu")
		(net "USB2_3_DP")
	)
	(segment
		(start 367.359438 -47.394368)
		(end 371.590824 -47.394368)
		(width 0.13208)
		(layer "B.Cu")
		(net "USB2_3_DP")
	)
	(segment
		(start 386.948426 -25.904444)
		(end 387.221476 -25.631394)
		(width 0.13208)
		(layer "B.Cu")
		(net "USB2_3_DP")
	)
	(segment
		(start 388.8994 -24.674068)
		(end 389.0899 -24.864568)
		(width 0.13208)
		(layer "B.Cu")
		(net "USB2_3_DP")
	)
	(segment
		(start 349.771716 -45.987208)
		(end 365.952278 -45.987208)
		(width 0.13208)
		(layer "B.Cu")
		(net "USB2_3_DP")
	)
	(segment
		(start 371.590824 -47.394368)
		(end 373.5705 -46.071536)
		(width 0.13208)
		(layer "B.Cu")
		(net "USB2_3_DP")
	)
	(segment
		(start 349.194374 -45.11548)
		(end 349.194374 -45.409866)
		(width 0.13208)
		(layer "B.Cu")
		(net "USB2_3_DP")
	)
	(segment
		(start 387.221476 -25.631394)
		(end 387.221476 -25.458928)
		(width 0.13208)
		(layer "B.Cu")
		(net "USB2_3_DP")
	)
	(segment
		(start 377.61672 -36.30168)
		(end 378.492004 -34.1884)
		(width 0.13208)
		(layer "B.Cu")
		(net "USB2_3_DP")
	)
	(segment
		(start 389.0899 -25.138888)
		(end 388.78764 -25.441148)
		(width 0.13208)
		(layer "B.Cu")
		(net "USB2_3_DP")
	)
	(segment
		(start 378.492004 -34.1884)
		(end 386.77596 -25.904444)
		(width 0.13208)
		(layer "B.Cu")
		(net "USB2_3_DP")
	)
	(segment
		(start 388.006336 -24.674068)
		(end 388.8994 -24.674068)
		(width 0.13208)
		(layer "B.Cu")
		(net "USB2_3_DP")
	)
	(segment
		(start 373.5705 -46.071536)
		(end 377.61672 -36.30168)
		(width 0.13208)
		(layer "B.Cu")
		(net "USB2_3_DP")
	)
	(segment
		(start 389.0899 -24.864568)
		(end 389.0899 -25.138888)
		(width 0.13208)
		(layer "B.Cu")
		(net "USB2_3_DP")
	)
	(segment
		(start 365.952278 -45.987208)
		(end 367.359438 -47.394368)
		(width 0.13208)
		(layer "B.Cu")
		(net "USB2_3_DP")
	)
	(segment
		(start 348.892114 -44.81322)
		(end 349.194374 -45.11548)
		(width 0.13208)
		(layer "B.Cu")
		(net "USB2_3_DP")
	)
	(segment
		(start 386.77596 -25.904444)
		(end 386.948426 -25.904444)
		(width 0.13208)
		(layer "B.Cu")
		(net "USB2_3_DP")
	)
	(segment
		(start 388.623048 -18.49374)
		(end 389.18007 -19.050762)
		(width 0.13208)
		(layer "F.Cu")
		(net "USB2_3_DN")
	)
	(segment
		(start 349.42272 -45.044868)
		(end 349.618554 -45.044868)
		(width 0.0889)
		(layer "F.Cu")
		(net "USB2_3_DN")
	)
	(segment
		(start 349.618554 -45.044868)
		(end 349.755714 -44.907708)
		(width 0.0889)
		(layer "F.Cu")
		(net "USB2_3_DN")
	)
	(segment
		(start 389.729218 -19.59991)
		(end 390.24687 -20.117562)
		(width 0.13208)
		(layer "F.Cu")
		(net "USB2_3_DN")
	)
	(segment
		(start 390.24687 -20.117562)
		(end 390.24687 -21.458682)
		(width 0.13208)
		(layer "F.Cu")
		(net "USB2_3_DN")
	)
	(segment
		(start 389.34898 -22.356572)
		(end 389.34898 -25.138888)
		(width 0.13208)
		(layer "F.Cu")
		(net "USB2_3_DN")
	)
	(segment
		(start 348.014544 -44.064682)
		(end 349.066104 -44.064682)
		(width 0.0889)
		(layer "F.Cu")
		(net "USB2_3_DN")
	)
	(segment
		(start 387.899656 -16.747236)
		(end 388.623048 -18.49374)
		(width 0.13208)
		(layer "F.Cu")
		(net "USB2_3_DN")
	)
	(segment
		(start 387.899656 -15.03172)
		(end 387.899656 -16.747236)
		(width 0.13208)
		(layer "F.Cu")
		(net "USB2_3_DN")
	)
	(segment
		(start 349.324676 -44.323254)
		(end 349.324676 -44.946824)
		(width 0.0889)
		(layer "F.Cu")
		(net "USB2_3_DN")
	)
	(segment
		(start 349.324676 -44.946824)
		(end 349.42272 -45.044868)
		(width 0.0889)
		(layer "F.Cu")
		(net "USB2_3_DN")
	)
	(segment
		(start 389.18007 -19.050762)
		(end 389.729218 -19.050762)
		(width 0.13208)
		(layer "F.Cu")
		(net "USB2_3_DN")
	)
	(segment
		(start 389.729218 -19.050762)
		(end 389.729218 -19.59991)
		(width 0.13208)
		(layer "F.Cu")
		(net "USB2_3_DN")
	)
	(segment
		(start 347.631004 -44.448222)
		(end 348.014544 -44.064682)
		(width 0.0889)
		(layer "F.Cu")
		(net "USB2_3_DN")
	)
	(segment
		(start 346.799662 -44.448222)
		(end 347.631004 -44.448222)
		(width 0.0889)
		(layer "F.Cu")
		(net "USB2_3_DN")
	)
	(segment
		(start 389.34898 -25.138888)
		(end 389.65124 -25.441148)
		(width 0.13208)
		(layer "F.Cu")
		(net "USB2_3_DN")
	)
	(segment
		(start 349.066104 -44.064682)
		(end 349.324676 -44.323254)
		(width 0.0889)
		(layer "F.Cu")
		(net "USB2_3_DN")
	)
	(segment
		(start 349.755714 -44.907708)
		(end 349.755714 -44.81322)
		(width 0.0889)
		(layer "F.Cu")
		(net "USB2_3_DN")
	)
	(segment
		(start 388.278116 -14.65326)
		(end 387.899656 -15.03172)
		(width 0.13208)
		(layer "F.Cu")
		(net "USB2_3_DN")
	)
	(segment
		(start 390.24687 -21.458682)
		(end 389.34898 -22.356572)
		(width 0.13208)
		(layer "F.Cu")
		(net "USB2_3_DN")
	)
	(via
		(at 349.755714 -44.81322)
		(size 0.508)
		(drill 0.254)
		(layers "F.Cu" "B.Cu")
		(net "USB2_3_DN")
	)
	(via
		(at 389.729218 -19.050762)
		(size 0.762)
		(drill 0.381)
		(layers "F.Cu" "B.Cu")
		(net "USB2_3_DN")
	)
	(via
		(at 389.65124 -25.441148)
		(size 0.508)
		(drill 0.254)
		(layers "F.Cu" "B.Cu")
		(net "USB2_3_DN")
	)
	(segment
		(start 349.879158 -45.728128)
		(end 366.05972 -45.728128)
		(width 0.13208)
		(layer "B.Cu")
		(net "USB2_3_DN")
	)
	(segment
		(start 378.272294 -34.041588)
		(end 387.898894 -24.414988)
		(width 0.13208)
		(layer "B.Cu")
		(net "USB2_3_DN")
	)
	(segment
		(start 366.05972 -45.728128)
		(end 367.46688 -47.135288)
		(width 0.13208)
		(layer "B.Cu")
		(net "USB2_3_DN")
	)
	(segment
		(start 349.453454 -45.302424)
		(end 349.879158 -45.728128)
		(width 0.13208)
		(layer "B.Cu")
		(net "USB2_3_DN")
	)
	(segment
		(start 387.898894 -24.414988)
		(end 389.006842 -24.414988)
		(width 0.13208)
		(layer "B.Cu")
		(net "USB2_3_DN")
	)
	(segment
		(start 389.006842 -24.414988)
		(end 389.34898 -24.757126)
		(width 0.13208)
		(layer "B.Cu")
		(net "USB2_3_DN")
	)
	(segment
		(start 389.34898 -24.757126)
		(end 389.34898 -25.138888)
		(width 0.13208)
		(layer "B.Cu")
		(net "USB2_3_DN")
	)
	(segment
		(start 371.512084 -47.135288)
		(end 373.36095 -45.899578)
		(width 0.13208)
		(layer "B.Cu")
		(net "USB2_3_DN")
	)
	(segment
		(start 349.453454 -45.11548)
		(end 349.453454 -45.302424)
		(width 0.13208)
		(layer "B.Cu")
		(net "USB2_3_DN")
	)
	(segment
		(start 389.34898 -25.138888)
		(end 389.65124 -25.441148)
		(width 0.13208)
		(layer "B.Cu")
		(net "USB2_3_DN")
	)
	(segment
		(start 373.36095 -45.899578)
		(end 378.272294 -34.041588)
		(width 0.13208)
		(layer "B.Cu")
		(net "USB2_3_DN")
	)
	(segment
		(start 367.46688 -47.135288)
		(end 371.512084 -47.135288)
		(width 0.13208)
		(layer "B.Cu")
		(net "USB2_3_DN")
	)
	(segment
		(start 349.755714 -44.81322)
		(end 349.453454 -45.11548)
		(width 0.13208)
		(layer "B.Cu")
		(net "USB2_3_DN")
	)
	(segment
		(start 347.362526 -43.223688)
		(end 347.039184 -43.223688)
		(width 0.0889)
		(layer "F.Cu")
		(net "TP_USB2_2_DP")
	)
	(segment
		(start 348.702376 -42.984928)
		(end 348.57563 -43.111674)
		(width 0.0889)
		(layer "F.Cu")
		(net "TP_USB2_2_DP")
	)
	(segment
		(start 354.848414 -38.076124)
		(end 354.811838 -38.039548)
		(width 0.0889)
		(layer "F.Cu")
		(net "TP_USB2_2_DP")
	)
	(segment
		(start 346.919296 -43.120056)
		(end 346.74683 -42.94759)
		(width 0.0889)
		(layer "F.Cu")
		(net "TP_USB2_2_DP")
	)
	(segment
		(start 364.50524 -40.439848)
		(end 364.50524 -39.961566)
		(width 0.13208)
		(layer "F.Cu")
		(net "TP_USB2_2_DP")
	)
	(segment
		(start 347.039184 -43.223688)
		(end 346.919296 -43.120056)
		(width 0.0889)
		(layer "F.Cu")
		(net "TP_USB2_2_DP")
	)
	(segment
		(start 354.811838 -38.039548)
		(end 354.663502 -38.039548)
		(width 0.0889)
		(layer "F.Cu")
		(net "TP_USB2_2_DP")
	)
	(segment
		(start 360.68254 -38.678104)
		(end 360.115104 -38.4429)
		(width 0.13208)
		(layer "F.Cu")
		(net "TP_USB2_2_DP")
	)
	(segment
		(start 349.91421 -42.784776)
		(end 349.714058 -42.984928)
		(width 0.0889)
		(layer "F.Cu")
		(net "TP_USB2_2_DP")
	)
	(segment
		(start 348.57563 -43.111674)
		(end 347.47454 -43.111674)
		(width 0.0889)
		(layer "F.Cu")
		(net "TP_USB2_2_DP")
	)
	(segment
		(start 364.191042 -39.647368)
		(end 363.022896 -39.647368)
		(width 0.13208)
		(layer "F.Cu")
		(net "TP_USB2_2_DP")
	)
	(segment
		(start 354.663502 -38.039548)
		(end 349.918274 -42.784776)
		(width 0.0889)
		(layer "F.Cu")
		(net "TP_USB2_2_DP")
	)
	(segment
		(start 363.022896 -39.647368)
		(end 360.68254 -38.678104)
		(width 0.13208)
		(layer "F.Cu")
		(net "TP_USB2_2_DP")
	)
	(segment
		(start 349.918274 -42.784776)
		(end 349.91421 -42.784776)
		(width 0.0889)
		(layer "F.Cu")
		(net "TP_USB2_2_DP")
	)
	(segment
		(start 359.229406 -38.076124)
		(end 354.870512 -38.076124)
		(width 0.13208)
		(layer "F.Cu")
		(net "TP_USB2_2_DP")
	)
	(segment
		(start 346.74683 -42.94759)
		(end 346.384626 -42.94759)
		(width 0.0889)
		(layer "F.Cu")
		(net "TP_USB2_2_DP")
	)
	(segment
		(start 360.115104 -38.4429)
		(end 359.229406 -38.076124)
		(width 0.13208)
		(layer "F.Cu")
		(net "TP_USB2_2_DP")
	)
	(segment
		(start 349.714058 -42.984928)
		(end 348.702376 -42.984928)
		(width 0.0889)
		(layer "F.Cu")
		(net "TP_USB2_2_DP")
	)
	(segment
		(start 347.47454 -43.111674)
		(end 347.362526 -43.223688)
		(width 0.0889)
		(layer "F.Cu")
		(net "TP_USB2_2_DP")
	)
	(segment
		(start 354.870512 -38.076124)
		(end 354.848414 -38.076124)
		(width 0.0889)
		(layer "F.Cu")
		(net "TP_USB2_2_DP")
	)
	(segment
		(start 364.50524 -39.961566)
		(end 364.191042 -39.647368)
		(width 0.13208)
		(layer "F.Cu")
		(net "TP_USB2_2_DP")
	)
	(via
		(at 364.50524 -40.439848)
		(size 0.762)
		(drill 0.381)
		(layers "F.Cu" "B.Cu")
		(net "TP_USB2_2_DP")
	)
	(segment
		(start 347.24086 -42.921428)
		(end 347.214698 -42.94759)
		(width 0.0889)
		(layer "F.Cu")
		(net "TP_USB2_2_DN")
	)
	(segment
		(start 348.86773 -42.794682)
		(end 348.623382 -42.794682)
		(width 0.0889)
		(layer "F.Cu")
		(net "TP_USB2_2_DN")
	)
	(segment
		(start 353.904042 -38.529768)
		(end 353.763834 -38.529768)
		(width 0.0889)
		(layer "F.Cu")
		(net "TP_USB2_2_DN")
	)
	(segment
		(start 351.681034 -40.612568)
		(end 351.681034 -40.752776)
		(width 0.0889)
		(layer "F.Cu")
		(net "TP_USB2_2_DN")
	)
	(segment
		(start 349.144336 -42.695876)
		(end 348.966536 -42.695876)
		(width 0.0889)
		(layer "F.Cu")
		(net "TP_USB2_2_DN")
	)
	(segment
		(start 351.023936 -41.269666)
		(end 350.898206 -41.395396)
		(width 0.0889)
		(layer "F.Cu")
		(net "TP_USB2_2_DN")
	)
	(segment
		(start 351.946972 -40.486838)
		(end 351.806764 -40.486838)
		(width 0.0889)
		(layer "F.Cu")
		(net "TP_USB2_2_DN")
	)
	(segment
		(start 352.463862 -39.82974)
		(end 352.463862 -39.969948)
		(width 0.0889)
		(layer "F.Cu")
		(net "TP_USB2_2_DN")
	)
	(segment
		(start 349.849694 -42.443908)
		(end 349.723964 -42.569638)
		(width 0.0889)
		(layer "F.Cu")
		(net "TP_USB2_2_DN")
	)
	(segment
		(start 353.763834 -38.529768)
		(end 353.638104 -38.655498)
		(width 0.0889)
		(layer "F.Cu")
		(net "TP_USB2_2_DN")
	)
	(segment
		(start 351.555558 -40.878252)
		(end 351.41535 -40.878252)
		(width 0.0889)
		(layer "F.Cu")
		(net "TP_USB2_2_DN")
	)
	(segment
		(start 349.989902 -42.443908)
		(end 349.849694 -42.443908)
		(width 0.0889)
		(layer "F.Cu")
		(net "TP_USB2_2_DN")
	)
	(segment
		(start 349.723964 -42.705782)
		(end 349.635064 -42.794682)
		(width 0.0889)
		(layer "F.Cu")
		(net "TP_USB2_2_DN")
	)
	(segment
		(start 352.7298 -39.70401)
		(end 352.589592 -39.70401)
		(width 0.0889)
		(layer "F.Cu")
		(net "TP_USB2_2_DN")
	)
	(segment
		(start 352.072448 -40.361362)
		(end 351.946972 -40.486838)
		(width 0.0889)
		(layer "F.Cu")
		(net "TP_USB2_2_DN")
	)
	(segment
		(start 351.164144 -41.269666)
		(end 351.023936 -41.269666)
		(width 0.0889)
		(layer "F.Cu")
		(net "TP_USB2_2_DN")
	)
	(segment
		(start 351.681034 -40.752776)
		(end 351.555558 -40.878252)
		(width 0.0889)
		(layer "F.Cu")
		(net "TP_USB2_2_DN")
	)
	(segment
		(start 352.981006 -39.312596)
		(end 352.855276 -39.438326)
		(width 0.0889)
		(layer "F.Cu")
		(net "TP_USB2_2_DN")
	)
	(segment
		(start 354.816156 -37.849302)
		(end 354.584508 -37.849302)
		(width 0.0889)
		(layer "F.Cu")
		(net "TP_USB2_2_DN")
	)
	(segment
		(start 353.638104 -38.655498)
		(end 353.638104 -38.795706)
		(width 0.0889)
		(layer "F.Cu")
		(net "TP_USB2_2_DN")
	)
	(segment
		(start 350.115378 -42.178224)
		(end 350.115378 -42.318432)
		(width 0.0889)
		(layer "F.Cu")
		(net "TP_USB2_2_DN")
	)
	(segment
		(start 353.121214 -39.312596)
		(end 352.981006 -39.312596)
		(width 0.0889)
		(layer "F.Cu")
		(net "TP_USB2_2_DN")
	)
	(segment
		(start 352.463862 -39.969948)
		(end 352.338386 -40.095424)
		(width 0.0889)
		(layer "F.Cu")
		(net "TP_USB2_2_DN")
	)
	(segment
		(start 348.623382 -42.794682)
		(end 348.496636 -42.921428)
		(width 0.0889)
		(layer "F.Cu")
		(net "TP_USB2_2_DN")
	)
	(segment
		(start 350.115378 -42.318432)
		(end 349.989902 -42.443908)
		(width 0.0889)
		(layer "F.Cu")
		(net "TP_USB2_2_DN")
	)
	(segment
		(start 350.241108 -42.052494)
		(end 350.115378 -42.178224)
		(width 0.0889)
		(layer "F.Cu")
		(net "TP_USB2_2_DN")
	)
	(segment
		(start 360.880914 -38.47973)
		(end 360.313478 -38.244526)
		(width 0.13208)
		(layer "F.Cu")
		(net "TP_USB2_2_DN")
	)
	(segment
		(start 352.338386 -40.095424)
		(end 352.198178 -40.095424)
		(width 0.0889)
		(layer "F.Cu")
		(net "TP_USB2_2_DN")
	)
	(segment
		(start 349.723964 -42.569638)
		(end 349.723964 -42.705782)
		(width 0.0889)
		(layer "F.Cu")
		(net "TP_USB2_2_DN")
	)
	(segment
		(start 354.848414 -37.817044)
		(end 354.816156 -37.849302)
		(width 0.0889)
		(layer "F.Cu")
		(net "TP_USB2_2_DN")
	)
	(segment
		(start 359.280968 -37.817044)
		(end 354.870512 -37.817044)
		(width 0.13208)
		(layer "F.Cu")
		(net "TP_USB2_2_DN")
	)
	(segment
		(start 351.28962 -41.003982)
		(end 351.28962 -41.14419)
		(width 0.0889)
		(layer "F.Cu")
		(net "TP_USB2_2_DN")
	)
	(segment
		(start 351.28962 -41.14419)
		(end 351.164144 -41.269666)
		(width 0.0889)
		(layer "F.Cu")
		(net "TP_USB2_2_DN")
	)
	(segment
		(start 352.198178 -40.095424)
		(end 352.072448 -40.221154)
		(width 0.0889)
		(layer "F.Cu")
		(net "TP_USB2_2_DN")
	)
	(segment
		(start 348.496636 -42.921428)
		(end 347.24086 -42.921428)
		(width 0.0889)
		(layer "F.Cu")
		(net "TP_USB2_2_DN")
	)
	(segment
		(start 353.512628 -38.921182)
		(end 353.37242 -38.921182)
		(width 0.0889)
		(layer "F.Cu")
		(net "TP_USB2_2_DN")
	)
	(segment
		(start 353.638104 -38.795706)
		(end 353.512628 -38.921182)
		(width 0.0889)
		(layer "F.Cu")
		(net "TP_USB2_2_DN")
	)
	(segment
		(start 349.635064 -42.794682)
		(end 349.243142 -42.794682)
		(width 0.0889)
		(layer "F.Cu")
		(net "TP_USB2_2_DN")
	)
	(segment
		(start 352.072448 -40.221154)
		(end 352.072448 -40.361362)
		(width 0.0889)
		(layer "F.Cu")
		(net "TP_USB2_2_DN")
	)
	(segment
		(start 350.898206 -41.395396)
		(end 350.898206 -41.535604)
		(width 0.0889)
		(layer "F.Cu")
		(net "TP_USB2_2_DN")
	)
	(segment
		(start 352.855276 -39.578534)
		(end 352.7298 -39.70401)
		(width 0.0889)
		(layer "F.Cu")
		(net "TP_USB2_2_DN")
	)
	(segment
		(start 351.806764 -40.486838)
		(end 351.681034 -40.612568)
		(width 0.0889)
		(layer "F.Cu")
		(net "TP_USB2_2_DN")
	)
	(segment
		(start 353.24669 -39.18712)
		(end 353.121214 -39.312596)
		(width 0.0889)
		(layer "F.Cu")
		(net "TP_USB2_2_DN")
	)
	(segment
		(start 353.37242 -38.921182)
		(end 353.24669 -39.046912)
		(width 0.0889)
		(layer "F.Cu")
		(net "TP_USB2_2_DN")
	)
	(segment
		(start 364.191042 -39.388288)
		(end 363.074458 -39.388288)
		(width 0.13208)
		(layer "F.Cu")
		(net "TP_USB2_2_DN")
	)
	(segment
		(start 352.855276 -39.438326)
		(end 352.855276 -39.578534)
		(width 0.0889)
		(layer "F.Cu")
		(net "TP_USB2_2_DN")
	)
	(segment
		(start 350.77273 -41.66108)
		(end 350.632522 -41.66108)
		(width 0.0889)
		(layer "F.Cu")
		(net "TP_USB2_2_DN")
	)
	(segment
		(start 350.632522 -41.66108)
		(end 350.506792 -41.78681)
		(width 0.0889)
		(layer "F.Cu")
		(net "TP_USB2_2_DN")
	)
	(segment
		(start 364.493302 -39.086028)
		(end 364.191042 -39.388288)
		(width 0.13208)
		(layer "F.Cu")
		(net "TP_USB2_2_DN")
	)
	(segment
		(start 353.24669 -39.046912)
		(end 353.24669 -39.18712)
		(width 0.0889)
		(layer "F.Cu")
		(net "TP_USB2_2_DN")
	)
	(segment
		(start 352.589592 -39.70401)
		(end 352.463862 -39.82974)
		(width 0.0889)
		(layer "F.Cu")
		(net "TP_USB2_2_DN")
	)
	(segment
		(start 354.870512 -37.817044)
		(end 354.848414 -37.817044)
		(width 0.0889)
		(layer "F.Cu")
		(net "TP_USB2_2_DN")
	)
	(segment
		(start 350.506792 -41.78681)
		(end 350.506792 -41.927018)
		(width 0.0889)
		(layer "F.Cu")
		(net "TP_USB2_2_DN")
	)
	(segment
		(start 350.506792 -41.927018)
		(end 350.381316 -42.052494)
		(width 0.0889)
		(layer "F.Cu")
		(net "TP_USB2_2_DN")
	)
	(segment
		(start 363.074458 -39.388288)
		(end 360.880914 -38.47973)
		(width 0.13208)
		(layer "F.Cu")
		(net "TP_USB2_2_DN")
	)
	(segment
		(start 351.41535 -40.878252)
		(end 351.28962 -41.003982)
		(width 0.0889)
		(layer "F.Cu")
		(net "TP_USB2_2_DN")
	)
	(segment
		(start 349.243142 -42.794682)
		(end 349.144336 -42.695876)
		(width 0.0889)
		(layer "F.Cu")
		(net "TP_USB2_2_DN")
	)
	(segment
		(start 360.313478 -38.244526)
		(end 359.280968 -37.817044)
		(width 0.13208)
		(layer "F.Cu")
		(net "TP_USB2_2_DN")
	)
	(segment
		(start 350.381316 -42.052494)
		(end 350.241108 -42.052494)
		(width 0.0889)
		(layer "F.Cu")
		(net "TP_USB2_2_DN")
	)
	(segment
		(start 354.584508 -37.849302)
		(end 353.904042 -38.529768)
		(width 0.0889)
		(layer "F.Cu")
		(net "TP_USB2_2_DN")
	)
	(segment
		(start 348.966536 -42.695876)
		(end 348.86773 -42.794682)
		(width 0.0889)
		(layer "F.Cu")
		(net "TP_USB2_2_DN")
	)
	(segment
		(start 350.898206 -41.535604)
		(end 350.77273 -41.66108)
		(width 0.0889)
		(layer "F.Cu")
		(net "TP_USB2_2_DN")
	)
	(via
		(at 364.493302 -39.086028)
		(size 0.762)
		(drill 0.381)
		(layers "F.Cu" "B.Cu")
		(net "TP_USB2_2_DN")
	)
	(segment
		(start 350.096074 -43.492928)
		(end 354.268024 -39.320978)
		(width 0.0889)
		(layer "F.Cu")
		(net "USB2_0_DP")
	)
	(segment
		(start 347.721428 -43.492928)
		(end 350.096074 -43.492928)
		(width 0.0889)
		(layer "F.Cu")
		(net "USB2_0_DP")
	)
	(segment
		(start 354.268024 -39.320978)
		(end 354.785168 -39.320978)
		(width 0.0889)
		(layer "F.Cu")
		(net "USB2_0_DP")
	)
	(segment
		(start 347.371416 -43.637962)
		(end 347.721428 -43.492928)
		(width 0.0889)
		(layer "F.Cu")
		(net "USB2_0_DP")
	)
	(segment
		(start 354.785168 -39.320978)
		(end 354.819458 -39.355268)
		(width 0.0889)
		(layer "F.Cu")
		(net "USB2_0_DP")
	)
	(segment
		(start 354.841556 -39.355268)
		(end 357.083106 -39.355268)
		(width 0.13208)
		(layer "F.Cu")
		(net "USB2_0_DP")
	)
	(segment
		(start 346.232226 -43.44797)
		(end 346.551758 -43.66133)
		(width 0.0889)
		(layer "F.Cu")
		(net "USB2_0_DP")
	)
	(segment
		(start 346.85986 -43.752516)
		(end 347.13672 -43.637962)
		(width 0.0889)
		(layer "F.Cu")
		(net "USB2_0_DP")
	)
	(segment
		(start 345.96959 -43.44797)
		(end 346.232226 -43.44797)
		(width 0.0889)
		(layer "F.Cu")
		(net "USB2_0_DP")
	)
	(segment
		(start 357.083106 -39.355268)
		(end 357.385366 -39.657528)
		(width 0.13208)
		(layer "F.Cu")
		(net "USB2_0_DP")
	)
	(segment
		(start 346.551758 -43.66133)
		(end 346.657168 -43.752516)
		(width 0.0889)
		(layer "F.Cu")
		(net "USB2_0_DP")
	)
	(segment
		(start 159.238188 -44.232576)
		(end 159.561276 -43.909488)
		(width 0.13208)
		(layer "F.Cu")
		(net "USB2_0_DP")
	)
	(segment
		(start 354.819458 -39.355268)
		(end 354.841556 -39.355268)
		(width 0.0889)
		(layer "F.Cu")
		(net "USB2_0_DP")
	)
	(segment
		(start 346.657168 -43.752516)
		(end 346.85986 -43.752516)
		(width 0.0889)
		(layer "F.Cu")
		(net "USB2_0_DP")
	)
	(segment
		(start 158.901384 -44.232576)
		(end 159.238188 -44.232576)
		(width 0.13208)
		(layer "F.Cu")
		(net "USB2_0_DP")
	)
	(segment
		(start 347.13672 -43.637962)
		(end 347.371416 -43.637962)
		(width 0.0889)
		(layer "F.Cu")
		(net "USB2_0_DP")
	)
	(via
		(at 167.607234 -48.862488)
		(size 0.6604)
		(drill 0.3302)
		(layers "F.Cu" "B.Cu")
		(net "USB2_0_DP")
	)
	(via
		(at 357.385366 -39.657528)
		(size 0.508)
		(drill 0.254)
		(layers "F.Cu" "B.Cu")
		(net "USB2_0_DP")
	)
	(via
		(at 159.561276 -43.909488)
		(size 0.508)
		(drill 0.254)
		(layers "F.Cu" "B.Cu")
		(net "USB2_0_DP")
	)
	(segment
		(start 216.040716 -65.659508)
		(end 202.028806 -65.659508)
		(width 0.13208)
		(layer "B.Cu")
		(net "USB2_0_DP")
	)
	(segment
		(start 159.561276 -43.913552)
		(end 159.561276 -43.909488)
		(width 0.13208)
		(layer "B.Cu")
		(net "USB2_0_DP")
	)
	(segment
		(start 237.59668 -90.198448)
		(end 234.662218 -90.198448)
		(width 0.13208)
		(layer "B.Cu")
		(net "USB2_0_DP")
	)
	(segment
		(start 186.27598 -57.856628)
		(end 178.38674 -57.856628)
		(width 0.13208)
		(layer "B.Cu")
		(net "USB2_0_DP")
	)
	(segment
		(start 355.346762 -39.74211)
		(end 349.268034 -42.25925)
		(width 0.13208)
		(layer "B.Cu")
		(net "USB2_0_DP")
	)
	(segment
		(start 234.662218 -90.198448)
		(end 230.989886 -88.677496)
		(width 0.13208)
		(layer "B.Cu")
		(net "USB2_0_DP")
	)
	(segment
		(start 355.509322 -39.80942)
		(end 355.346762 -39.74211)
		(width 0.13208)
		(layer "B.Cu")
		(net "USB2_0_DP")
	)
	(segment
		(start 347.6879 -45.237908)
		(end 350.33204 -47.882048)
		(width 0.13208)
		(layer "B.Cu")
		(net "USB2_0_DP")
	)
	(segment
		(start 202.028806 -65.659508)
		(end 196.841618 -64.086232)
		(width 0.13208)
		(layer "B.Cu")
		(net "USB2_0_DP")
	)
	(segment
		(start 351.14738 -47.882048)
		(end 351.27184 -47.757588)
		(width 0.13208)
		(layer "B.Cu")
		(net "USB2_0_DP")
	)
	(segment
		(start 361.291632 -66.350896)
		(end 361.291632 -73.135744)
		(width 0.13208)
		(layer "B.Cu")
		(net "USB2_0_DP")
	)
	(segment
		(start 196.841618 -64.086232)
		(end 190.953136 -60.151264)
		(width 0.13208)
		(layer "B.Cu")
		(net "USB2_0_DP")
	)
	(segment
		(start 230.989886 -88.677496)
		(end 228.110542 -85.798152)
		(width 0.13208)
		(layer "B.Cu")
		(net "USB2_0_DP")
	)
	(segment
		(start 178.38674 -57.856628)
		(end 176.672748 -57.146698)
		(width 0.13208)
		(layer "B.Cu")
		(net "USB2_0_DP")
	)
	(segment
		(start 357.385366 -39.657528)
		(end 357.083106 -39.355268)
		(width 0.13208)
		(layer "B.Cu")
		(net "USB2_0_DP")
	)
	(segment
		(start 158.5341 -44.665646)
		(end 158.980378 -44.219368)
		(width 0.13208)
		(layer "B.Cu")
		(net "USB2_0_DP")
	)
	(segment
		(start 176.672748 -57.146698)
		(end 174.375064 -54.849014)
		(width 0.13208)
		(layer "B.Cu")
		(net "USB2_0_DP")
	)
	(segment
		(start 158.5341 -45.99813)
		(end 158.5341 -44.665646)
		(width 0.13208)
		(layer "B.Cu")
		(net "USB2_0_DP")
	)
	(segment
		(start 167.607234 -48.862488)
		(end 167.228774 -48.484028)
		(width 0.13208)
		(layer "B.Cu")
		(net "USB2_0_DP")
	)
	(segment
		(start 362.461302 -47.882048)
		(end 367.192306 -52.613052)
		(width 0.13208)
		(layer "B.Cu")
		(net "USB2_0_DP")
	)
	(segment
		(start 221.904052 -70.830186)
		(end 221.253304 -68.264278)
		(width 0.13208)
		(layer "B.Cu")
		(net "USB2_0_DP")
	)
	(segment
		(start 351.7773 -47.882048)
		(end 362.461302 -47.882048)
		(width 0.13208)
		(layer "B.Cu")
		(net "USB2_0_DP")
	)
	(segment
		(start 221.253304 -68.264278)
		(end 220.947996 -67.69227)
		(width 0.13208)
		(layer "B.Cu")
		(net "USB2_0_DP")
	)
	(segment
		(start 347.6879 -44.25823)
		(end 347.6879 -45.237908)
		(width 0.13208)
		(layer "B.Cu")
		(net "USB2_0_DP")
	)
	(segment
		(start 228.110542 -85.798152)
		(end 223.609408 -74.931524)
		(width 0.13208)
		(layer "B.Cu")
		(net "USB2_0_DP")
	)
	(segment
		(start 367.192306 -52.613052)
		(end 368.17046 -54.97449)
		(width 0.13208)
		(layer "B.Cu")
		(net "USB2_0_DP")
	)
	(segment
		(start 347.984318 -43.542966)
		(end 347.6879 -44.25823)
		(width 0.13208)
		(layer "B.Cu")
		(net "USB2_0_DP")
	)
	(segment
		(start 223.601534 -74.928222)
		(end 221.904052 -70.830186)
		(width 0.13208)
		(layer "B.Cu")
		(net "USB2_0_DP")
	)
	(segment
		(start 281.634692 -85.451188)
		(end 246.457724 -85.451188)
		(width 0.13208)
		(layer "B.Cu")
		(net "USB2_0_DP")
	)
	(segment
		(start 355.86162 -39.663878)
		(end 355.509322 -39.80942)
		(width 0.13208)
		(layer "B.Cu")
		(net "USB2_0_DP")
	)
	(segment
		(start 356.280974 -39.355268)
		(end 355.929184 -39.50081)
		(width 0.13208)
		(layer "B.Cu")
		(net "USB2_0_DP")
	)
	(segment
		(start 220.947996 -67.69227)
		(end 216.040716 -65.659508)
		(width 0.13208)
		(layer "B.Cu")
		(net "USB2_0_DP")
	)
	(segment
		(start 361.291632 -73.135744)
		(end 357.652828 -81.920842)
		(width 0.13208)
		(layer "B.Cu")
		(net "USB2_0_DP")
	)
	(segment
		(start 158.980378 -44.219368)
		(end 159.25546 -44.219368)
		(width 0.13208)
		(layer "B.Cu")
		(net "USB2_0_DP")
	)
	(segment
		(start 368.17046 -56.88838)
		(end 367.063274 -59.561476)
		(width 0.13208)
		(layer "B.Cu")
		(net "USB2_0_DP")
	)
	(segment
		(start 167.985694 -48.484028)
		(end 167.607234 -48.862488)
		(width 0.13208)
		(layer "B.Cu")
		(net "USB2_0_DP")
	)
	(segment
		(start 159.25546 -44.219368)
		(end 159.561276 -43.913552)
		(width 0.13208)
		(layer "B.Cu")
		(net "USB2_0_DP")
	)
	(segment
		(start 187.980574 -58.563002)
		(end 186.27598 -57.856628)
		(width 0.13208)
		(layer "B.Cu")
		(net "USB2_0_DP")
	)
	(segment
		(start 329.527916 -87.587328)
		(end 286.791908 -87.587328)
		(width 0.13208)
		(layer "B.Cu")
		(net "USB2_0_DP")
	)
	(segment
		(start 240.90249 -88.829134)
		(end 237.59668 -90.198448)
		(width 0.13208)
		(layer "B.Cu")
		(net "USB2_0_DP")
	)
	(segment
		(start 357.652828 -81.920842)
		(end 347.599508 -91.974162)
		(width 0.13208)
		(layer "B.Cu")
		(net "USB2_0_DP")
	)
	(segment
		(start 347.599508 -91.974162)
		(end 346.171266 -92.565728)
		(width 0.13208)
		(layer "B.Cu")
		(net "USB2_0_DP")
	)
	(segment
		(start 346.171266 -92.565728)
		(end 341.546942 -92.565728)
		(width 0.13208)
		(layer "B.Cu")
		(net "USB2_0_DP")
	)
	(segment
		(start 242.740688 -86.990936)
		(end 240.90249 -88.829134)
		(width 0.13208)
		(layer "B.Cu")
		(net "USB2_0_DP")
	)
	(segment
		(start 286.791908 -87.587328)
		(end 281.634692 -85.451188)
		(width 0.13208)
		(layer "B.Cu")
		(net "USB2_0_DP")
	)
	(segment
		(start 357.083106 -39.355268)
		(end 356.280974 -39.355268)
		(width 0.13208)
		(layer "B.Cu")
		(net "USB2_0_DP")
	)
	(segment
		(start 161.697416 -47.776384)
		(end 159.33293 -46.79696)
		(width 0.13208)
		(layer "B.Cu")
		(net "USB2_0_DP")
	)
	(segment
		(start 171.162726 -48.872394)
		(end 170.225466 -48.484028)
		(width 0.13208)
		(layer "B.Cu")
		(net "USB2_0_DP")
	)
	(segment
		(start 159.33293 -46.79696)
		(end 158.5341 -45.99813)
		(width 0.13208)
		(layer "B.Cu")
		(net "USB2_0_DP")
	)
	(segment
		(start 351.27184 -47.757588)
		(end 351.65284 -47.757588)
		(width 0.13208)
		(layer "B.Cu")
		(net "USB2_0_DP")
	)
	(segment
		(start 367.063274 -59.561476)
		(end 362.011468 -64.613282)
		(width 0.13208)
		(layer "B.Cu")
		(net "USB2_0_DP")
	)
	(segment
		(start 172.42028 -50.129948)
		(end 171.162726 -48.872394)
		(width 0.13208)
		(layer "B.Cu")
		(net "USB2_0_DP")
	)
	(segment
		(start 351.65284 -47.757588)
		(end 351.7773 -47.882048)
		(width 0.13208)
		(layer "B.Cu")
		(net "USB2_0_DP")
	)
	(segment
		(start 341.546942 -92.565728)
		(end 329.527916 -87.587328)
		(width 0.13208)
		(layer "B.Cu")
		(net "USB2_0_DP")
	)
	(segment
		(start 174.375064 -54.849014)
		(end 172.42028 -50.129948)
		(width 0.13208)
		(layer "B.Cu")
		(net "USB2_0_DP")
	)
	(segment
		(start 349.268034 -42.25925)
		(end 347.984318 -43.542966)
		(width 0.13208)
		(layer "B.Cu")
		(net "USB2_0_DP")
	)
	(segment
		(start 355.929184 -39.50081)
		(end 355.86162 -39.663878)
		(width 0.13208)
		(layer "B.Cu")
		(net "USB2_0_DP")
	)
	(segment
		(start 246.457724 -85.451188)
		(end 242.740688 -86.990936)
		(width 0.13208)
		(layer "B.Cu")
		(net "USB2_0_DP")
	)
	(segment
		(start 170.225466 -48.484028)
		(end 167.985694 -48.484028)
		(width 0.13208)
		(layer "B.Cu")
		(net "USB2_0_DP")
	)
	(segment
		(start 350.33204 -47.882048)
		(end 351.14738 -47.882048)
		(width 0.13208)
		(layer "B.Cu")
		(net "USB2_0_DP")
	)
	(segment
		(start 190.953136 -60.151264)
		(end 187.980574 -58.563002)
		(width 0.13208)
		(layer "B.Cu")
		(net "USB2_0_DP")
	)
	(segment
		(start 167.228774 -48.484028)
		(end 165.255448 -48.484028)
		(width 0.13208)
		(layer "B.Cu")
		(net "USB2_0_DP")
	)
	(segment
		(start 165.255448 -48.484028)
		(end 161.697416 -47.776384)
		(width 0.13208)
		(layer "B.Cu")
		(net "USB2_0_DP")
	)
	(segment
		(start 368.17046 -54.97449)
		(end 368.17046 -56.88838)
		(width 0.13208)
		(layer "B.Cu")
		(net "USB2_0_DP")
	)
	(segment
		(start 362.011468 -64.613282)
		(end 361.291632 -66.350896)
		(width 0.13208)
		(layer "B.Cu")
		(net "USB2_0_DP")
	)
	(segment
		(start 223.609408 -74.931524)
		(end 223.601534 -74.928222)
		(width 0.13208)
		(layer "B.Cu")
		(net "USB2_0_DP")
	)
	(segment
		(start 353.508056 -39.811706)
		(end 353.633532 -39.68623)
		(width 0.0889)
		(layer "F.Cu")
		(net "USB2_0_DN")
	)
	(segment
		(start 351.9424 -41.377362)
		(end 352.067876 -41.251886)
		(width 0.0889)
		(layer "F.Cu")
		(net "USB2_0_DN")
	)
	(segment
		(start 351.802192 -41.377362)
		(end 351.9424 -41.377362)
		(width 0.0889)
		(layer "F.Cu")
		(net "USB2_0_DN")
	)
	(segment
		(start 346.799662 -43.44797)
		(end 347.08719 -43.447716)
		(width 0.0889)
		(layer "F.Cu")
		(net "USB2_0_DN")
	)
	(segment
		(start 353.89947 -39.420292)
		(end 354.18903 -39.130732)
		(width 0.0889)
		(layer "F.Cu")
		(net "USB2_0_DN")
	)
	(segment
		(start 354.18903 -39.130732)
		(end 354.784914 -39.130732)
		(width 0.0889)
		(layer "F.Cu")
		(net "USB2_0_DN")
	)
	(segment
		(start 357.083106 -39.096188)
		(end 357.385366 -38.793928)
		(width 0.13208)
		(layer "F.Cu")
		(net "USB2_0_DN")
	)
	(segment
		(start 348.76359 -43.302682)
		(end 348.862396 -43.203876)
		(width 0.0889)
		(layer "F.Cu")
		(net "USB2_0_DN")
	)
	(segment
		(start 352.45929 -40.860472)
		(end 352.45929 -40.720264)
		(width 0.0889)
		(layer "F.Cu")
		(net "USB2_0_DN")
	)
	(segment
		(start 352.333814 -40.985948)
		(end 352.45929 -40.860472)
		(width 0.0889)
		(layer "F.Cu")
		(net "USB2_0_DN")
	)
	(segment
		(start 351.285048 -42.034714)
		(end 351.285048 -41.894506)
		(width 0.0889)
		(layer "F.Cu")
		(net "USB2_0_DN")
	)
	(segment
		(start 352.976434 -40.20312)
		(end 353.116642 -40.20312)
		(width 0.0889)
		(layer "F.Cu")
		(net "USB2_0_DN")
	)
	(segment
		(start 351.410778 -41.768776)
		(end 351.550986 -41.768776)
		(width 0.0889)
		(layer "F.Cu")
		(net "USB2_0_DN")
	)
	(segment
		(start 351.285048 -41.894506)
		(end 351.410778 -41.768776)
		(width 0.0889)
		(layer "F.Cu")
		(net "USB2_0_DN")
	)
	(segment
		(start 353.242118 -39.937436)
		(end 353.367848 -39.811706)
		(width 0.0889)
		(layer "F.Cu")
		(net "USB2_0_DN")
	)
	(segment
		(start 352.193606 -40.985948)
		(end 352.333814 -40.985948)
		(width 0.0889)
		(layer "F.Cu")
		(net "USB2_0_DN")
	)
	(segment
		(start 349.139002 -43.302682)
		(end 349.316802 -43.302682)
		(width 0.0889)
		(layer "F.Cu")
		(net "USB2_0_DN")
	)
	(segment
		(start 347.333316 -43.447716)
		(end 347.683328 -43.302682)
		(width 0.0889)
		(layer "F.Cu")
		(net "USB2_0_DN")
	)
	(segment
		(start 349.316802 -43.302682)
		(end 349.415608 -43.203876)
		(width 0.0889)
		(layer "F.Cu")
		(net "USB2_0_DN")
	)
	(segment
		(start 349.593408 -43.203876)
		(end 349.692214 -43.302682)
		(width 0.0889)
		(layer "F.Cu")
		(net "USB2_0_DN")
	)
	(segment
		(start 349.692214 -43.302682)
		(end 350.01708 -43.302682)
		(width 0.0889)
		(layer "F.Cu")
		(net "USB2_0_DN")
	)
	(segment
		(start 348.862396 -43.203876)
		(end 349.040196 -43.203876)
		(width 0.0889)
		(layer "F.Cu")
		(net "USB2_0_DN")
	)
	(segment
		(start 160.28035 -44.232576)
		(end 160.01111 -44.232576)
		(width 0.13208)
		(layer "F.Cu")
		(net "USB2_0_DN")
	)
	(segment
		(start 354.819458 -39.096188)
		(end 354.841556 -39.096188)
		(width 0.0889)
		(layer "F.Cu")
		(net "USB2_0_DN")
	)
	(segment
		(start 352.58502 -40.594534)
		(end 352.725228 -40.594534)
		(width 0.0889)
		(layer "F.Cu")
		(net "USB2_0_DN")
	)
	(segment
		(start 353.116642 -40.20312)
		(end 353.242118 -40.077644)
		(width 0.0889)
		(layer "F.Cu")
		(net "USB2_0_DN")
	)
	(segment
		(start 160.01111 -44.232576)
		(end 159.56153 -44.682156)
		(width 0.13208)
		(layer "F.Cu")
		(net "USB2_0_DN")
	)
	(segment
		(start 350.62795 -42.551604)
		(end 350.768158 -42.551604)
		(width 0.0889)
		(layer "F.Cu")
		(net "USB2_0_DN")
	)
	(segment
		(start 350.893634 -42.426128)
		(end 350.893634 -42.28592)
		(width 0.0889)
		(layer "F.Cu")
		(net "USB2_0_DN")
	)
	(segment
		(start 352.850704 -40.469058)
		(end 352.850704 -40.32885)
		(width 0.0889)
		(layer "F.Cu")
		(net "USB2_0_DN")
	)
	(segment
		(start 353.367848 -39.811706)
		(end 353.508056 -39.811706)
		(width 0.0889)
		(layer "F.Cu")
		(net "USB2_0_DN")
	)
	(segment
		(start 353.633532 -39.68623)
		(end 353.633532 -39.546022)
		(width 0.0889)
		(layer "F.Cu")
		(net "USB2_0_DN")
	)
	(segment
		(start 347.683328 -43.302682)
		(end 348.76359 -43.302682)
		(width 0.0889)
		(layer "F.Cu")
		(net "USB2_0_DN")
	)
	(segment
		(start 350.376744 -42.943018)
		(end 350.50222 -42.817542)
		(width 0.0889)
		(layer "F.Cu")
		(net "USB2_0_DN")
	)
	(segment
		(start 352.850704 -40.32885)
		(end 352.976434 -40.20312)
		(width 0.0889)
		(layer "F.Cu")
		(net "USB2_0_DN")
	)
	(segment
		(start 349.415608 -43.203876)
		(end 349.593408 -43.203876)
		(width 0.0889)
		(layer "F.Cu")
		(net "USB2_0_DN")
	)
	(segment
		(start 353.633532 -39.546022)
		(end 353.759262 -39.420292)
		(width 0.0889)
		(layer "F.Cu")
		(net "USB2_0_DN")
	)
	(segment
		(start 350.01708 -43.302682)
		(end 350.110806 -43.208956)
		(width 0.0889)
		(layer "F.Cu")
		(net "USB2_0_DN")
	)
	(segment
		(start 354.841556 -39.096188)
		(end 357.083106 -39.096188)
		(width 0.13208)
		(layer "F.Cu")
		(net "USB2_0_DN")
	)
	(segment
		(start 352.067876 -41.111678)
		(end 352.193606 -40.985948)
		(width 0.0889)
		(layer "F.Cu")
		(net "USB2_0_DN")
	)
	(segment
		(start 350.50222 -42.817542)
		(end 350.50222 -42.677334)
		(width 0.0889)
		(layer "F.Cu")
		(net "USB2_0_DN")
	)
	(segment
		(start 351.019364 -42.16019)
		(end 351.159572 -42.16019)
		(width 0.0889)
		(layer "F.Cu")
		(net "USB2_0_DN")
	)
	(segment
		(start 351.676462 -41.6433)
		(end 351.676462 -41.503092)
		(width 0.0889)
		(layer "F.Cu")
		(net "USB2_0_DN")
	)
	(segment
		(start 353.242118 -40.077644)
		(end 353.242118 -39.937436)
		(width 0.0889)
		(layer "F.Cu")
		(net "USB2_0_DN")
	)
	(segment
		(start 352.725228 -40.594534)
		(end 352.850704 -40.469058)
		(width 0.0889)
		(layer "F.Cu")
		(net "USB2_0_DN")
	)
	(segment
		(start 350.110806 -43.068748)
		(end 350.236536 -42.943018)
		(width 0.0889)
		(layer "F.Cu")
		(net "USB2_0_DN")
	)
	(segment
		(start 351.550986 -41.768776)
		(end 351.676462 -41.6433)
		(width 0.0889)
		(layer "F.Cu")
		(net "USB2_0_DN")
	)
	(segment
		(start 350.110806 -43.208956)
		(end 350.110806 -43.068748)
		(width 0.0889)
		(layer "F.Cu")
		(net "USB2_0_DN")
	)
	(segment
		(start 350.768158 -42.551604)
		(end 350.893634 -42.426128)
		(width 0.0889)
		(layer "F.Cu")
		(net "USB2_0_DN")
	)
	(segment
		(start 354.784914 -39.130732)
		(end 354.819458 -39.096188)
		(width 0.0889)
		(layer "F.Cu")
		(net "USB2_0_DN")
	)
	(segment
		(start 352.45929 -40.720264)
		(end 352.58502 -40.594534)
		(width 0.0889)
		(layer "F.Cu")
		(net "USB2_0_DN")
	)
	(segment
		(start 350.236536 -42.943018)
		(end 350.376744 -42.943018)
		(width 0.0889)
		(layer "F.Cu")
		(net "USB2_0_DN")
	)
	(segment
		(start 350.893634 -42.28592)
		(end 351.019364 -42.16019)
		(width 0.0889)
		(layer "F.Cu")
		(net "USB2_0_DN")
	)
	(segment
		(start 351.159572 -42.16019)
		(end 351.285048 -42.034714)
		(width 0.0889)
		(layer "F.Cu")
		(net "USB2_0_DN")
	)
	(segment
		(start 349.040196 -43.203876)
		(end 349.139002 -43.302682)
		(width 0.0889)
		(layer "F.Cu")
		(net "USB2_0_DN")
	)
	(segment
		(start 347.08719 -43.447716)
		(end 347.333316 -43.447716)
		(width 0.0889)
		(layer "F.Cu")
		(net "USB2_0_DN")
	)
	(segment
		(start 352.067876 -41.251886)
		(end 352.067876 -41.111678)
		(width 0.0889)
		(layer "F.Cu")
		(net "USB2_0_DN")
	)
	(segment
		(start 350.50222 -42.677334)
		(end 350.62795 -42.551604)
		(width 0.0889)
		(layer "F.Cu")
		(net "USB2_0_DN")
	)
	(segment
		(start 353.759262 -39.420292)
		(end 353.89947 -39.420292)
		(width 0.0889)
		(layer "F.Cu")
		(net "USB2_0_DN")
	)
	(segment
		(start 351.676462 -41.503092)
		(end 351.802192 -41.377362)
		(width 0.0889)
		(layer "F.Cu")
		(net "USB2_0_DN")
	)
	(via
		(at 167.608758 -47.846488)
		(size 0.6604)
		(drill 0.3302)
		(layers "F.Cu" "B.Cu")
		(net "USB2_0_DN")
	)
	(via
		(at 357.385366 -38.793928)
		(size 0.508)
		(drill 0.254)
		(layers "F.Cu" "B.Cu")
		(net "USB2_0_DN")
	)
	(via
		(at 159.56153 -44.682156)
		(size 0.508)
		(drill 0.254)
		(layers "F.Cu" "B.Cu")
		(net "USB2_0_DN")
	)
	(segment
		(start 167.608758 -47.846488)
		(end 167.230298 -48.224948)
		(width 0.13208)
		(layer "B.Cu")
		(net "USB2_0_DN")
	)
	(segment
		(start 159.84093 -46.726856)
		(end 159.479742 -46.57725)
		(width 0.13208)
		(layer "B.Cu")
		(net "USB2_0_DN")
	)
	(segment
		(start 224.365058 -75.752706)
		(end 224.514664 -76.114402)
		(width 0.13208)
		(layer "B.Cu")
		(net "USB2_0_DN")
	)
	(segment
		(start 176.81956 -56.926988)
		(end 178.438302 -57.597548)
		(width 0.13208)
		(layer "B.Cu")
		(net "USB2_0_DN")
	)
	(segment
		(start 347.764608 -43.396154)
		(end 349.121222 -42.03954)
		(width 0.13208)
		(layer "B.Cu")
		(net "USB2_0_DN")
	)
	(segment
		(start 242.593876 -86.771226)
		(end 246.406162 -85.192108)
		(width 0.13208)
		(layer "B.Cu")
		(net "USB2_0_DN")
	)
	(segment
		(start 223.654112 -74.377804)
		(end 223.799908 -74.729594)
		(width 0.13208)
		(layer "B.Cu")
		(net "USB2_0_DN")
	)
	(segment
		(start 162.606736 -47.692818)
		(end 162.606736 -47.693072)
		(width 0.13208)
		(layer "B.Cu")
		(net "USB2_0_DN")
	)
	(segment
		(start 361.032552 -73.084182)
		(end 361.032552 -66.299334)
		(width 0.13208)
		(layer "B.Cu")
		(net "USB2_0_DN")
	)
	(segment
		(start 159.357822 -44.478448)
		(end 159.56153 -44.682156)
		(width 0.13208)
		(layer "B.Cu")
		(net "USB2_0_DN")
	)
	(segment
		(start 158.79318 -44.773088)
		(end 159.08782 -44.478448)
		(width 0.13208)
		(layer "B.Cu")
		(net "USB2_0_DN")
	)
	(segment
		(start 221.132908 -67.488308)
		(end 221.49689 -68.170044)
		(width 0.13208)
		(layer "B.Cu")
		(net "USB2_0_DN")
	)
	(segment
		(start 188.091572 -58.328306)
		(end 191.086486 -59.92876)
		(width 0.13208)
		(layer "B.Cu")
		(net "USB2_0_DN")
	)
	(segment
		(start 363.257338 -49.220628)
		(end 362.98759 -48.95088)
		(width 0.13208)
		(layer "B.Cu")
		(net "USB2_0_DN")
	)
	(segment
		(start 362.35386 -48.141128)
		(end 361.96524 -48.141128)
		(width 0.13208)
		(layer "B.Cu")
		(net "USB2_0_DN")
	)
	(segment
		(start 246.406162 -85.192108)
		(end 281.686254 -85.192108)
		(width 0.13208)
		(layer "B.Cu")
		(net "USB2_0_DN")
	)
	(segment
		(start 223.412812 -73.795636)
		(end 223.57588 -73.862946)
		(width 0.13208)
		(layer "B.Cu")
		(net "USB2_0_DN")
	)
	(segment
		(start 237.545118 -89.939368)
		(end 240.755678 -88.609424)
		(width 0.13208)
		(layer "B.Cu")
		(net "USB2_0_DN")
	)
	(segment
		(start 361.791758 -64.46647)
		(end 366.843564 -59.414664)
		(width 0.13208)
		(layer "B.Cu")
		(net "USB2_0_DN")
	)
	(segment
		(start 341.598504 -92.306648)
		(end 346.119704 -92.306648)
		(width 0.13208)
		(layer "B.Cu")
		(net "USB2_0_DN")
	)
	(segment
		(start 225.484436 -78.780894)
		(end 228.330252 -85.65134)
		(width 0.13208)
		(layer "B.Cu")
		(net "USB2_0_DN")
	)
	(segment
		(start 347.596968 -43.801284)
		(end 347.764608 -43.396154)
		(width 0.13208)
		(layer "B.Cu")
		(net "USB2_0_DN")
	)
	(segment
		(start 164.586412 -47.962312)
		(end 164.202618 -47.886112)
		(width 0.13208)
		(layer "B.Cu")
		(net "USB2_0_DN")
	)
	(segment
		(start 196.953632 -63.84925)
		(end 202.067414 -65.400428)
		(width 0.13208)
		(layer "B.Cu")
		(net "USB2_0_DN")
	)
	(segment
		(start 362.98759 -48.95088)
		(end 362.98759 -48.774858)
		(width 0.13208)
		(layer "B.Cu")
		(net "USB2_0_DN")
	)
	(segment
		(start 170.277028 -48.224948)
		(end 171.309538 -48.652684)
		(width 0.13208)
		(layer "B.Cu")
		(net "USB2_0_DN")
	)
	(segment
		(start 158.79318 -45.890688)
		(end 158.79318 -44.773088)
		(width 0.13208)
		(layer "B.Cu")
		(net "USB2_0_DN")
	)
	(segment
		(start 286.84347 -87.328248)
		(end 329.579478 -87.328248)
		(width 0.13208)
		(layer "B.Cu")
		(net "USB2_0_DN")
	)
	(segment
		(start 178.438302 -57.597548)
		(end 186.327542 -57.597548)
		(width 0.13208)
		(layer "B.Cu")
		(net "USB2_0_DN")
	)
	(segment
		(start 347.42882 -44.206414)
		(end 347.596714 -43.801538)
		(width 0.13208)
		(layer "B.Cu")
		(net "USB2_0_DN")
	)
	(segment
		(start 362.98759 -48.774858)
		(end 362.35386 -48.141128)
		(width 0.13208)
		(layer "B.Cu")
		(net "USB2_0_DN")
	)
	(segment
		(start 222.150686 -70.748398)
		(end 223.413066 -73.795636)
		(width 0.13208)
		(layer "B.Cu")
		(net "USB2_0_DN")
	)
	(segment
		(start 224.052638 -75.324208)
		(end 224.202244 -75.685396)
		(width 0.13208)
		(layer "B.Cu")
		(net "USB2_0_DN")
	)
	(segment
		(start 161.772854 -47.526956)
		(end 160.427924 -46.969934)
		(width 0.13208)
		(layer "B.Cu")
		(net "USB2_0_DN")
	)
	(segment
		(start 224.447354 -76.276962)
		(end 224.719642 -76.934568)
		(width 0.13208)
		(layer "B.Cu")
		(net "USB2_0_DN")
	)
	(segment
		(start 224.964752 -77.526134)
		(end 225.226626 -78.15834)
		(width 0.13208)
		(layer "B.Cu")
		(net "USB2_0_DN")
	)
	(segment
		(start 165.281102 -48.224948)
		(end 164.68217 -48.105822)
		(width 0.13208)
		(layer "B.Cu")
		(net "USB2_0_DN")
	)
	(segment
		(start 347.452696 -91.754452)
		(end 357.433118 -81.77403)
		(width 0.13208)
		(layer "B.Cu")
		(net "USB2_0_DN")
	)
	(segment
		(start 161.983674 -47.568866)
		(end 161.772854 -47.526956)
		(width 0.13208)
		(layer "B.Cu")
		(net "USB2_0_DN")
	)
	(segment
		(start 224.202244 -75.685396)
		(end 224.365058 -75.752706)
		(width 0.13208)
		(layer "B.Cu")
		(net "USB2_0_DN")
	)
	(segment
		(start 366.843564 -59.414664)
		(end 367.91138 -56.836818)
		(width 0.13208)
		(layer "B.Cu")
		(net "USB2_0_DN")
	)
	(segment
		(start 186.327542 -57.597548)
		(end 188.091572 -58.328306)
		(width 0.13208)
		(layer "B.Cu")
		(net "USB2_0_DN")
	)
	(segment
		(start 234.71378 -89.939368)
		(end 237.545118 -89.939368)
		(width 0.13208)
		(layer "B.Cu")
		(net "USB2_0_DN")
	)
	(segment
		(start 361.84078 -48.265588)
		(end 361.45978 -48.265588)
		(width 0.13208)
		(layer "B.Cu")
		(net "USB2_0_DN")
	)
	(segment
		(start 160.000188 -46.660816)
		(end 159.84093 -46.726856)
		(width 0.13208)
		(layer "B.Cu")
		(net "USB2_0_DN")
	)
	(segment
		(start 366.972596 -52.759864)
		(end 363.43336 -49.220628)
		(width 0.13208)
		(layer "B.Cu")
		(net "USB2_0_DN")
	)
	(segment
		(start 228.330252 -85.65134)
		(end 231.136698 -88.457786)
		(width 0.13208)
		(layer "B.Cu")
		(net "USB2_0_DN")
	)
	(segment
		(start 160.361884 -46.810422)
		(end 160.000188 -46.660816)
		(width 0.13208)
		(layer "B.Cu")
		(net "USB2_0_DN")
	)
	(segment
		(start 221.49689 -68.170044)
		(end 222.150686 -70.748398)
		(width 0.13208)
		(layer "B.Cu")
		(net "USB2_0_DN")
	)
	(segment
		(start 367.91138 -55.026052)
		(end 366.972596 -52.759864)
		(width 0.13208)
		(layer "B.Cu")
		(net "USB2_0_DN")
	)
	(segment
		(start 164.202618 -47.886112)
		(end 164.059108 -47.98187)
		(width 0.13208)
		(layer "B.Cu")
		(net "USB2_0_DN")
	)
	(segment
		(start 225.226626 -78.15834)
		(end 225.239326 -78.189328)
		(width 0.13208)
		(layer "B.Cu")
		(net "USB2_0_DN")
	)
	(segment
		(start 357.083106 -39.096188)
		(end 357.385366 -38.793928)
		(width 0.13208)
		(layer "B.Cu")
		(net "USB2_0_DN")
	)
	(segment
		(start 356.229412 -39.096188)
		(end 357.083106 -39.096188)
		(width 0.13208)
		(layer "B.Cu")
		(net "USB2_0_DN")
	)
	(segment
		(start 361.032552 -66.299334)
		(end 361.791758 -64.46647)
		(width 0.13208)
		(layer "B.Cu")
		(net "USB2_0_DN")
	)
	(segment
		(start 240.755678 -88.609424)
		(end 242.593876 -86.771226)
		(width 0.13208)
		(layer "B.Cu")
		(net "USB2_0_DN")
	)
	(segment
		(start 162.12693 -47.473108)
		(end 161.983674 -47.568866)
		(width 0.13208)
		(layer "B.Cu")
		(net "USB2_0_DN")
	)
	(segment
		(start 347.42882 -45.34535)
		(end 347.42882 -44.206414)
		(width 0.13208)
		(layer "B.Cu")
		(net "USB2_0_DN")
	)
	(segment
		(start 361.96524 -48.141128)
		(end 361.84078 -48.265588)
		(width 0.13208)
		(layer "B.Cu")
		(net "USB2_0_DN")
	)
	(segment
		(start 224.514664 -76.114402)
		(end 224.447354 -76.276962)
		(width 0.13208)
		(layer "B.Cu")
		(net "USB2_0_DN")
	)
	(segment
		(start 225.239326 -78.189328)
		(end 225.40214 -78.256638)
		(width 0.13208)
		(layer "B.Cu")
		(net "USB2_0_DN")
	)
	(segment
		(start 191.086486 -59.92876)
		(end 196.953632 -63.84925)
		(width 0.13208)
		(layer "B.Cu")
		(net "USB2_0_DN")
	)
	(segment
		(start 159.479742 -46.57725)
		(end 158.79318 -45.890688)
		(width 0.13208)
		(layer "B.Cu")
		(net "USB2_0_DN")
	)
	(segment
		(start 223.721676 -74.21499)
		(end 223.654112 -74.377804)
		(width 0.13208)
		(layer "B.Cu")
		(net "USB2_0_DN")
	)
	(segment
		(start 160.427924 -46.969934)
		(end 160.361884 -46.810422)
		(width 0.13208)
		(layer "B.Cu")
		(net "USB2_0_DN")
	)
	(segment
		(start 347.596714 -43.801538)
		(end 347.596968 -43.801284)
		(width 0.13208)
		(layer "B.Cu")
		(net "USB2_0_DN")
	)
	(segment
		(start 361.33532 -48.141128)
		(end 350.224598 -48.141128)
		(width 0.13208)
		(layer "B.Cu")
		(net "USB2_0_DN")
	)
	(segment
		(start 164.68217 -48.105822)
		(end 164.68217 -48.106076)
		(width 0.13208)
		(layer "B.Cu")
		(net "USB2_0_DN")
	)
	(segment
		(start 367.91138 -56.836818)
		(end 367.91138 -55.026052)
		(width 0.13208)
		(layer "B.Cu")
		(net "USB2_0_DN")
	)
	(segment
		(start 162.510978 -47.549308)
		(end 162.12693 -47.473108)
		(width 0.13208)
		(layer "B.Cu")
		(net "USB2_0_DN")
	)
	(segment
		(start 357.433118 -81.77403)
		(end 361.032552 -73.084182)
		(width 0.13208)
		(layer "B.Cu")
		(net "USB2_0_DN")
	)
	(segment
		(start 346.119704 -92.306648)
		(end 347.452696 -91.754452)
		(width 0.13208)
		(layer "B.Cu")
		(net "USB2_0_DN")
	)
	(segment
		(start 216.092278 -65.400428)
		(end 221.132908 -67.488308)
		(width 0.13208)
		(layer "B.Cu")
		(net "USB2_0_DN")
	)
	(segment
		(start 281.686254 -85.192108)
		(end 286.84347 -87.328248)
		(width 0.13208)
		(layer "B.Cu")
		(net "USB2_0_DN")
	)
	(segment
		(start 329.579478 -87.328248)
		(end 341.598504 -92.306648)
		(width 0.13208)
		(layer "B.Cu")
		(net "USB2_0_DN")
	)
	(segment
		(start 171.309538 -48.652684)
		(end 172.63999 -49.983136)
		(width 0.13208)
		(layer "B.Cu")
		(net "USB2_0_DN")
	)
	(segment
		(start 167.987218 -48.224948)
		(end 170.277028 -48.224948)
		(width 0.13208)
		(layer "B.Cu")
		(net "USB2_0_DN")
	)
	(segment
		(start 350.224598 -48.141128)
		(end 347.42882 -45.34535)
		(width 0.13208)
		(layer "B.Cu")
		(net "USB2_0_DN")
	)
	(segment
		(start 174.594774 -54.702202)
		(end 176.81956 -56.926988)
		(width 0.13208)
		(layer "B.Cu")
		(net "USB2_0_DN")
	)
	(segment
		(start 223.799908 -74.729594)
		(end 223.970342 -74.799952)
		(width 0.13208)
		(layer "B.Cu")
		(net "USB2_0_DN")
	)
	(segment
		(start 223.413066 -73.795636)
		(end 223.412812 -73.795636)
		(width 0.13208)
		(layer "B.Cu")
		(net "USB2_0_DN")
	)
	(segment
		(start 225.032062 -77.363574)
		(end 224.964752 -77.526134)
		(width 0.13208)
		(layer "B.Cu")
		(net "USB2_0_DN")
	)
	(segment
		(start 162.606736 -47.693072)
		(end 162.510978 -47.549308)
		(width 0.13208)
		(layer "B.Cu")
		(net "USB2_0_DN")
	)
	(segment
		(start 164.059108 -47.98187)
		(end 162.606736 -47.692818)
		(width 0.13208)
		(layer "B.Cu")
		(net "USB2_0_DN")
	)
	(segment
		(start 361.45978 -48.265588)
		(end 361.33532 -48.141128)
		(width 0.13208)
		(layer "B.Cu")
		(net "USB2_0_DN")
	)
	(segment
		(start 223.970342 -74.799952)
		(end 224.119948 -75.161648)
		(width 0.13208)
		(layer "B.Cu")
		(net "USB2_0_DN")
	)
	(segment
		(start 224.119948 -75.161648)
		(end 224.052638 -75.324208)
		(width 0.13208)
		(layer "B.Cu")
		(net "USB2_0_DN")
	)
	(segment
		(start 159.08782 -44.478448)
		(end 159.357822 -44.478448)
		(width 0.13208)
		(layer "B.Cu")
		(net "USB2_0_DN")
	)
	(segment
		(start 167.608758 -47.846488)
		(end 167.987218 -48.224948)
		(width 0.13208)
		(layer "B.Cu")
		(net "USB2_0_DN")
	)
	(segment
		(start 231.136698 -88.457786)
		(end 234.71378 -89.939368)
		(width 0.13208)
		(layer "B.Cu")
		(net "USB2_0_DN")
	)
	(segment
		(start 202.067414 -65.400428)
		(end 216.092278 -65.400428)
		(width 0.13208)
		(layer "B.Cu")
		(net "USB2_0_DN")
	)
	(segment
		(start 172.63999 -49.983136)
		(end 174.594774 -54.702202)
		(width 0.13208)
		(layer "B.Cu")
		(net "USB2_0_DN")
	)
	(segment
		(start 225.40214 -78.256638)
		(end 225.551746 -78.618334)
		(width 0.13208)
		(layer "B.Cu")
		(net "USB2_0_DN")
	)
	(segment
		(start 223.57588 -73.862946)
		(end 223.721676 -74.21499)
		(width 0.13208)
		(layer "B.Cu")
		(net "USB2_0_DN")
	)
	(segment
		(start 363.43336 -49.220628)
		(end 363.257338 -49.220628)
		(width 0.13208)
		(layer "B.Cu")
		(net "USB2_0_DN")
	)
	(segment
		(start 164.68217 -48.106076)
		(end 164.586412 -47.962312)
		(width 0.13208)
		(layer "B.Cu")
		(net "USB2_0_DN")
	)
	(segment
		(start 225.551746 -78.618334)
		(end 225.484436 -78.780894)
		(width 0.13208)
		(layer "B.Cu")
		(net "USB2_0_DN")
	)
	(segment
		(start 349.121222 -42.03954)
		(end 356.229412 -39.096188)
		(width 0.13208)
		(layer "B.Cu")
		(net "USB2_0_DN")
	)
	(segment
		(start 224.719642 -76.934568)
		(end 224.882456 -77.002132)
		(width 0.13208)
		(layer "B.Cu")
		(net "USB2_0_DN")
	)
	(segment
		(start 167.230298 -48.224948)
		(end 165.281102 -48.224948)
		(width 0.13208)
		(layer "B.Cu")
		(net "USB2_0_DN")
	)
	(segment
		(start 224.882456 -77.002132)
		(end 225.032062 -77.363574)
		(width 0.13208)
		(layer "B.Cu")
		(net "USB2_0_DN")
	)
	(segment
		(start 93.424502 -281.87015)
		(end 93.424502 -282.405582)
		(width 0.13208)
		(layer "F.Cu")
		(net "UPI_CPU1_CPU0_P2P2_DP<9>")
	)
	(segment
		(start 93.424502 -282.405582)
		(end 93.424248 -282.405836)
		(width 0.13208)
		(layer "F.Cu")
		(net "UPI_CPU1_CPU0_P2P2_DP<9>")
	)
	(segment
		(start 351.701862 -277.522178)
		(end 351.701862 -277.522432)
		(width 0.13208)
		(layer "F.Cu")
		(net "UPI_CPU1_CPU0_P2P2_DP<9>")
	)
	(segment
		(start 351.702116 -276.986492)
		(end 351.702116 -277.521924)
		(width 0.13208)
		(layer "F.Cu")
		(net "UPI_CPU1_CPU0_P2P2_DP<9>")
	)
	(segment
		(start 351.702116 -277.521924)
		(end 351.701862 -277.522178)
		(width 0.13208)
		(layer "F.Cu")
		(net "UPI_CPU1_CPU0_P2P2_DP<9>")
	)
	(segment
		(start 93.424248 -281.869896)
		(end 93.424502 -281.87015)
		(width 0.13208)
		(layer "F.Cu")
		(net "UPI_CPU1_CPU0_P2P2_DP<9>")
	)
	(segment
		(start 64.221106 -329.126088)
		(end 63.931038 -332.050644)
		(width 0.14732)
		(layer "In11.Cu")
		(net "UPI_CPU1_CPU0_P2P2_DP<9>")
	)
	(segment
		(start 92.389198 -291.432742)
		(end 92.347288 -291.474652)
		(width 0.0889)
		(layer "In11.Cu")
		(net "UPI_CPU1_CPU0_P2P2_DP<9>")
	)
	(segment
		(start 92.347288 -291.478208)
		(end 92.347288 -291.71392)
		(width 0.14732)
		(layer "In11.Cu")
		(net "UPI_CPU1_CPU0_P2P2_DP<9>")
	)
	(segment
		(start 347.746574 -286.970216)
		(end 347.76156 -286.961326)
		(width 0.0889)
		(layer "In11.Cu")
		(net "UPI_CPU1_CPU0_P2P2_DP<9>")
	)
	(segment
		(start 92.210636 -288.422334)
		(end 92.201746 -288.427414)
		(width 0.0889)
		(layer "In11.Cu")
		(net "UPI_CPU1_CPU0_P2P2_DP<9>")
	)
	(segment
		(start 350.857566 -279.982676)
		(end 350.857566 -279.964134)
		(width 0.0889)
		(layer "In11.Cu")
		(net "UPI_CPU1_CPU0_P2P2_DP<9>")
	)
	(segment
		(start 345.900502 -291.512244)
		(end 345.900502 -291.376608)
		(width 0.0889)
		(layer "In11.Cu")
		(net "UPI_CPU1_CPU0_P2P2_DP<9>")
	)
	(segment
		(start 348.686374 -283.714444)
		(end 348.695264 -283.709364)
		(width 0.0889)
		(layer "In11.Cu")
		(net "UPI_CPU1_CPU0_P2P2_DP<9>")
	)
	(segment
		(start 346.476828 -290.800282)
		(end 346.61729 -290.800282)
		(width 0.0889)
		(layer "In11.Cu")
		(net "UPI_CPU1_CPU0_P2P2_DP<9>")
	)
	(segment
		(start 350.566228 -280.458926)
		(end 350.575118 -280.453846)
		(width 0.0889)
		(layer "In11.Cu")
		(net "UPI_CPU1_CPU0_P2P2_DP<9>")
	)
	(segment
		(start 347.755464 -285.985712)
		(end 347.746574 -285.980632)
		(width 0.0889)
		(layer "In11.Cu")
		(net "UPI_CPU1_CPU0_P2P2_DP<9>")
	)
	(segment
		(start 65.681098 -323.864732)
		(end 64.221106 -329.126088)
		(width 0.14732)
		(layer "In11.Cu")
		(net "UPI_CPU1_CPU0_P2P2_DP<9>")
	)
	(segment
		(start 63.931038 -354.69322)
		(end 68.875656 -366.631474)
		(width 0.14732)
		(layer "In11.Cu")
		(net "UPI_CPU1_CPU0_P2P2_DP<9>")
	)
	(segment
		(start 348.216728 -284.52826)
		(end 348.225618 -284.52318)
		(width 0.0889)
		(layer "In11.Cu")
		(net "UPI_CPU1_CPU0_P2P2_DP<9>")
	)
	(segment
		(start 93.798644 -284.023816)
		(end 93.798644 -284.033722)
		(width 0.0889)
		(layer "In11.Cu")
		(net "UPI_CPU1_CPU0_P2P2_DP<9>")
	)
	(segment
		(start 347.755464 -285.336996)
		(end 347.76156 -285.33344)
		(width 0.0889)
		(layer "In11.Cu")
		(net "UPI_CPU1_CPU0_P2P2_DP<9>")
	)
	(segment
		(start 63.931038 -332.050644)
		(end 63.931038 -354.69322)
		(width 0.14732)
		(layer "In11.Cu")
		(net "UPI_CPU1_CPU0_P2P2_DP<9>")
	)
	(segment
		(start 351.467166 -277.230586)
		(end 351.545398 -277.251414)
		(width 0.0889)
		(layer "In11.Cu")
		(net "UPI_CPU1_CPU0_P2P2_DP<9>")
	)
	(segment
		(start 349.635064 -282.081478)
		(end 349.64116 -282.077922)
		(width 0.0889)
		(layer "In11.Cu")
		(net "UPI_CPU1_CPU0_P2P2_DP<9>")
	)
	(segment
		(start 93.620082 -284.353)
		(end 93.611192 -284.35808)
		(width 0.0889)
		(layer "In11.Cu")
		(net "UPI_CPU1_CPU0_P2P2_DP<9>")
	)
	(segment
		(start 347.746574 -286.969962)
		(end 347.746574 -286.970216)
		(width 0.0889)
		(layer "In11.Cu")
		(net "UPI_CPU1_CPU0_P2P2_DP<9>")
	)
	(segment
		(start 346.74302 -290.674552)
		(end 346.74302 -290.53409)
		(width 0.0889)
		(layer "In11.Cu")
		(net "UPI_CPU1_CPU0_P2P2_DP<9>")
	)
	(segment
		(start 346.628466 -289.078416)
		(end 346.628466 -288.917126)
		(width 0.0889)
		(layer "In11.Cu")
		(net "UPI_CPU1_CPU0_P2P2_DP<9>")
	)
	(segment
		(start 338.02828 -304.522632)
		(end 341.458296 -303.10201)
		(width 0.14732)
		(layer "In11.Cu")
		(net "UPI_CPU1_CPU0_P2P2_DP<9>")
	)
	(segment
		(start 348.699074 -283.707078)
		(end 348.707456 -283.702252)
		(width 0.0889)
		(layer "In11.Cu")
		(net "UPI_CPU1_CPU0_P2P2_DP<9>")
	)
	(segment
		(start 350.57334 -279.473914)
		(end 350.565974 -279.469596)
		(width 0.0889)
		(layer "In11.Cu")
		(net "UPI_CPU1_CPU0_P2P2_DP<9>")
	)
	(segment
		(start 348.695264 -283.709364)
		(end 348.699074 -283.707078)
		(width 0.0889)
		(layer "In11.Cu")
		(net "UPI_CPU1_CPU0_P2P2_DP<9>")
	)
	(segment
		(start 347.098112 -290.178998)
		(end 347.098112 -289.60953)
		(width 0.0889)
		(layer "In11.Cu")
		(net "UPI_CPU1_CPU0_P2P2_DP<9>")
	)
	(segment
		(start 92.290138 -290.95827)
		(end 92.389198 -291.05733)
		(width 0.0889)
		(layer "In11.Cu")
		(net "UPI_CPU1_CPU0_P2P2_DP<9>")
	)
	(segment
		(start 350.581214 -279.478486)
		(end 350.574864 -279.474676)
		(width 0.0889)
		(layer "In11.Cu")
		(net "UPI_CPU1_CPU0_P2P2_DP<9>")
	)
	(segment
		(start 350.565974 -278.83104)
		(end 350.574864 -278.82596)
		(width 0.0889)
		(layer "In11.Cu")
		(net "UPI_CPU1_CPU0_P2P2_DP<9>")
	)
	(segment
		(start 347.568012 -287.304734)
		(end 347.568012 -287.28924)
		(width 0.0889)
		(layer "In11.Cu")
		(net "UPI_CPU1_CPU0_P2P2_DP<9>")
	)
	(segment
		(start 262.12419 -376.776996)
		(end 271.96796 -366.933226)
		(width 0.14732)
		(layer "In11.Cu")
		(net "UPI_CPU1_CPU0_P2P2_DP<9>")
	)
	(segment
		(start 349.447612 -282.427934)
		(end 349.447612 -282.405836)
		(width 0.0889)
		(layer "In11.Cu")
		(net "UPI_CPU1_CPU0_P2P2_DP<9>")
	)
	(segment
		(start 346.74302 -290.53409)
		(end 347.098112 -290.178998)
		(width 0.0889)
		(layer "In11.Cu")
		(net "UPI_CPU1_CPU0_P2P2_DP<9>")
	)
	(segment
		(start 92.389198 -289.64636)
		(end 92.389198 -290.12769)
		(width 0.0889)
		(layer "In11.Cu")
		(net "UPI_CPU1_CPU0_P2P2_DP<9>")
	)
	(segment
		(start 93.150436 -285.166816)
		(end 93.141546 -285.171896)
		(width 0.0889)
		(layer "In11.Cu")
		(net "UPI_CPU1_CPU0_P2P2_DP<9>")
	)
	(segment
		(start 92.858844 -285.661354)
		(end 92.858844 -285.675578)
		(width 0.0889)
		(layer "In11.Cu")
		(net "UPI_CPU1_CPU0_P2P2_DP<9>")
	)
	(segment
		(start 68.875656 -366.631474)
		(end 73.863962 -371.61978)
		(width 0.14732)
		(layer "In11.Cu")
		(net "UPI_CPU1_CPU0_P2P2_DP<9>")
	)
	(segment
		(start 351.327212 -277.54453)
		(end 351.327212 -277.522432)
		(width 0.0889)
		(layer "In11.Cu")
		(net "UPI_CPU1_CPU0_P2P2_DP<9>")
	)
	(segment
		(start 345.942666 -291.576506)
		(end 345.942666 -291.554408)
		(width 0.0889)
		(layer "In11.Cu")
		(net "UPI_CPU1_CPU0_P2P2_DP<9>")
	)
	(segment
		(start 349.156528 -282.900628)
		(end 349.165418 -282.895548)
		(width 0.0889)
		(layer "In11.Cu")
		(net "UPI_CPU1_CPU0_P2P2_DP<9>")
	)
	(segment
		(start 346.61729 -290.800282)
		(end 346.74302 -290.674552)
		(width 0.0889)
		(layer "In11.Cu")
		(net "UPI_CPU1_CPU0_P2P2_DP<9>")
	)
	(segment
		(start 126.477776 -385.32943)
		(end 161.33953 -385.32943)
		(width 0.14732)
		(layer "In11.Cu")
		(net "UPI_CPU1_CPU0_P2P2_DP<9>")
	)
	(segment
		(start 348.038166 -286.475424)
		(end 348.038166 -286.4612)
		(width 0.0889)
		(layer "In11.Cu")
		(net "UPI_CPU1_CPU0_P2P2_DP<9>")
	)
	(segment
		(start 271.96796 -366.933226)
		(end 271.96796 -346.819474)
		(width 0.14732)
		(layer "In11.Cu")
		(net "UPI_CPU1_CPU0_P2P2_DP<9>")
	)
	(segment
		(start 347.276928 -287.783778)
		(end 347.285818 -287.778698)
		(width 0.0889)
		(layer "In11.Cu")
		(net "UPI_CPU1_CPU0_P2P2_DP<9>")
	)
	(segment
		(start 92.290138 -290.40455)
		(end 92.389198 -290.50361)
		(width 0.0889)
		(layer "In11.Cu")
		(net "UPI_CPU1_CPU0_P2P2_DP<9>")
	)
	(segment
		(start 88.186006 -295.875202)
		(end 85.695536 -301.888652)
		(width 0.14732)
		(layer "In11.Cu")
		(net "UPI_CPU1_CPU0_P2P2_DP<9>")
	)
	(segment
		(start 92.388944 -289.645852)
		(end 92.389198 -289.64636)
		(width 0.0889)
		(layer "In11.Cu")
		(net "UPI_CPU1_CPU0_P2P2_DP<9>")
	)
	(segment
		(start 346.351352 -290.925758)
		(end 346.476828 -290.800282)
		(width 0.0889)
		(layer "In11.Cu")
		(net "UPI_CPU1_CPU0_P2P2_DP<9>")
	)
	(segment
		(start 93.424248 -282.405836)
		(end 93.580712 -282.134818)
		(width 0.0889)
		(layer "In11.Cu")
		(net "UPI_CPU1_CPU0_P2P2_DP<9>")
	)
	(segment
		(start 350.096328 -281.272742)
		(end 350.105218 -281.267662)
		(width 0.0889)
		(layer "In11.Cu")
		(net "UPI_CPU1_CPU0_P2P2_DP<9>")
	)
	(segment
		(start 308.696614 -335.40827)
		(end 316.146688 -327.958196)
		(width 0.14732)
		(layer "In11.Cu")
		(net "UPI_CPU1_CPU0_P2P2_DP<9>")
	)
	(segment
		(start 73.863962 -371.61978)
		(end 96.07423 -380.81966)
		(width 0.14732)
		(layer "In11.Cu")
		(net "UPI_CPU1_CPU0_P2P2_DP<9>")
	)
	(segment
		(start 345.942666 -294.065706)
		(end 345.942666 -291.576506)
		(width 0.14732)
		(layer "In11.Cu")
		(net "UPI_CPU1_CPU0_P2P2_DP<9>")
	)
	(segment
		(start 349.626174 -282.086558)
		(end 349.635064 -282.081478)
		(width 0.0889)
		(layer "In11.Cu")
		(net "UPI_CPU1_CPU0_P2P2_DP<9>")
	)
	(segment
		(start 93.141546 -285.171896)
		(end 93.13545 -285.175452)
		(width 0.0889)
		(layer "In11.Cu")
		(net "UPI_CPU1_CPU0_P2P2_DP<9>")
	)
	(segment
		(start 317.245492 -325.30542)
		(end 338.02828 -304.522632)
		(width 0.14732)
		(layer "In11.Cu")
		(net "UPI_CPU1_CPU0_P2P2_DP<9>")
	)
	(segment
		(start 345.900502 -291.376608)
		(end 346.085414 -291.191696)
		(width 0.0889)
		(layer "In11.Cu")
		(net "UPI_CPU1_CPU0_P2P2_DP<9>")
	)
	(segment
		(start 92.290138 -290.22675)
		(end 92.290138 -290.40455)
		(width 0.0889)
		(layer "In11.Cu")
		(net "UPI_CPU1_CPU0_P2P2_DP<9>")
	)
	(segment
		(start 348.507812 -284.049216)
		(end 348.507812 -284.033722)
		(width 0.0889)
		(layer "In11.Cu")
		(net "UPI_CPU1_CPU0_P2P2_DP<9>")
	)
	(segment
		(start 96.07423 -380.81966)
		(end 126.477776 -385.32943)
		(width 0.14732)
		(layer "In11.Cu")
		(net "UPI_CPU1_CPU0_P2P2_DP<9>")
	)
	(segment
		(start 92.389198 -290.68141)
		(end 92.290138 -290.78047)
		(width 0.0889)
		(layer "In11.Cu")
		(net "UPI_CPU1_CPU0_P2P2_DP<9>")
	)
	(segment
		(start 350.58096 -279.478232)
		(end 350.581214 -279.478486)
		(width 0.0889)
		(layer "In11.Cu")
		(net "UPI_CPU1_CPU0_P2P2_DP<9>")
	)
	(segment
		(start 316.146688 -327.958196)
		(end 317.245492 -325.30542)
		(width 0.14732)
		(layer "In11.Cu")
		(net "UPI_CPU1_CPU0_P2P2_DP<9>")
	)
	(segment
		(start 92.347288 -291.71392)
		(end 88.186006 -295.875202)
		(width 0.14732)
		(layer "In11.Cu")
		(net "UPI_CPU1_CPU0_P2P2_DP<9>")
	)
	(segment
		(start 91.919298 -288.898584)
		(end 91.919298 -289.114738)
		(width 0.0889)
		(layer "In11.Cu")
		(net "UPI_CPU1_CPU0_P2P2_DP<9>")
	)
	(segment
		(start 271.96796 -346.819474)
		(end 281.50058 -337.286854)
		(width 0.14732)
		(layer "In11.Cu")
		(net "UPI_CPU1_CPU0_P2P2_DP<9>")
	)
	(segment
		(start 286.03575 -335.40827)
		(end 308.696614 -335.40827)
		(width 0.14732)
		(layer "In11.Cu")
		(net "UPI_CPU1_CPU0_P2P2_DP<9>")
	)
	(segment
		(start 94.081092 -282.895548)
		(end 94.089982 -282.900628)
		(width 0.0889)
		(layer "In11.Cu")
		(net "UPI_CPU1_CPU0_P2P2_DP<9>")
	)
	(segment
		(start 350.574864 -278.82596)
		(end 350.58096 -278.822404)
		(width 0.0889)
		(layer "In11.Cu")
		(net "UPI_CPU1_CPU0_P2P2_DP<9>")
	)
	(segment
		(start 92.290138 -290.78047)
		(end 92.290138 -290.95827)
		(width 0.0889)
		(layer "In11.Cu")
		(net "UPI_CPU1_CPU0_P2P2_DP<9>")
	)
	(segment
		(start 93.580712 -282.134818)
		(end 93.658944 -282.11399)
		(width 0.0889)
		(layer "In11.Cu")
		(net "UPI_CPU1_CPU0_P2P2_DP<9>")
	)
	(segment
		(start 161.33953 -385.32943)
		(end 262.12419 -376.776996)
		(width 0.14732)
		(layer "In11.Cu")
		(net "UPI_CPU1_CPU0_P2P2_DP<9>")
	)
	(segment
		(start 93.150436 -286.794702)
		(end 93.13545 -286.803338)
		(width 0.0889)
		(layer "In11.Cu")
		(net "UPI_CPU1_CPU0_P2P2_DP<9>")
	)
	(segment
		(start 351.036128 -278.017224)
		(end 351.045018 -278.012144)
		(width 0.0889)
		(layer "In11.Cu")
		(net "UPI_CPU1_CPU0_P2P2_DP<9>")
	)
	(segment
		(start 93.798898 -282.405836)
		(end 93.798898 -282.427934)
		(width 0.0889)
		(layer "In11.Cu")
		(net "UPI_CPU1_CPU0_P2P2_DP<9>")
	)
	(segment
		(start 347.098366 -288.121598)
		(end 347.098366 -288.103056)
		(width 0.0889)
		(layer "In11.Cu")
		(net "UPI_CPU1_CPU0_P2P2_DP<9>")
	)
	(segment
		(start 92.389198 -290.50361)
		(end 92.389198 -290.68141)
		(width 0.0889)
		(layer "In11.Cu")
		(net "UPI_CPU1_CPU0_P2P2_DP<9>")
	)
	(segment
		(start 92.389198 -288.09315)
		(end 92.389198 -288.103056)
		(width 0.0889)
		(layer "In11.Cu")
		(net "UPI_CPU1_CPU0_P2P2_DP<9>")
	)
	(segment
		(start 92.389198 -291.05733)
		(end 92.389198 -291.432742)
		(width 0.0889)
		(layer "In11.Cu")
		(net "UPI_CPU1_CPU0_P2P2_DP<9>")
	)
	(segment
		(start 351.545398 -277.251414)
		(end 351.701862 -277.522432)
		(width 0.0889)
		(layer "In11.Cu")
		(net "UPI_CPU1_CPU0_P2P2_DP<9>")
	)
	(segment
		(start 94.089982 -283.539184)
		(end 94.081092 -283.544264)
		(width 0.0889)
		(layer "In11.Cu")
		(net "UPI_CPU1_CPU0_P2P2_DP<9>")
	)
	(segment
		(start 345.114118 -298.230798)
		(end 345.942666 -294.065706)
		(width 0.14732)
		(layer "In11.Cu")
		(net "UPI_CPU1_CPU0_P2P2_DP<9>")
	)
	(segment
		(start 346.807028 -288.597848)
		(end 346.815918 -288.592768)
		(width 0.0889)
		(layer "In11.Cu")
		(net "UPI_CPU1_CPU0_P2P2_DP<9>")
	)
	(segment
		(start 93.328998 -284.832044)
		(end 93.328998 -284.847538)
		(width 0.0889)
		(layer "In11.Cu")
		(net "UPI_CPU1_CPU0_P2P2_DP<9>")
	)
	(segment
		(start 346.225622 -291.191696)
		(end 346.351352 -291.065966)
		(width 0.0889)
		(layer "In11.Cu")
		(net "UPI_CPU1_CPU0_P2P2_DP<9>")
	)
	(segment
		(start 85.695536 -301.888652)
		(end 67.442842 -320.141346)
		(width 0.14732)
		(layer "In11.Cu")
		(net "UPI_CPU1_CPU0_P2P2_DP<9>")
	)
	(segment
		(start 92.347288 -291.474652)
		(end 92.347288 -291.478208)
		(width 0.0889)
		(layer "In11.Cu")
		(net "UPI_CPU1_CPU0_P2P2_DP<9>")
	)
	(segment
		(start 347.746574 -285.342076)
		(end 347.755464 -285.336996)
		(width 0.0889)
		(layer "In11.Cu")
		(net "UPI_CPU1_CPU0_P2P2_DP<9>")
	)
	(segment
		(start 67.442842 -320.141346)
		(end 65.681098 -323.864732)
		(width 0.14732)
		(layer "In11.Cu")
		(net "UPI_CPU1_CPU0_P2P2_DP<9>")
	)
	(segment
		(start 350.574864 -279.474676)
		(end 350.57334 -279.473914)
		(width 0.0889)
		(layer "In11.Cu")
		(net "UPI_CPU1_CPU0_P2P2_DP<9>")
	)
	(segment
		(start 93.141546 -286.151066)
		(end 93.150436 -286.156146)
		(width 0.0889)
		(layer "In11.Cu")
		(net "UPI_CPU1_CPU0_P2P2_DP<9>")
	)
	(segment
		(start 344.255344 -300.304962)
		(end 345.114118 -298.230798)
		(width 0.14732)
		(layer "In11.Cu")
		(net "UPI_CPU1_CPU0_P2P2_DP<9>")
	)
	(segment
		(start 346.351352 -291.065966)
		(end 346.351352 -290.925758)
		(width 0.0889)
		(layer "In11.Cu")
		(net "UPI_CPU1_CPU0_P2P2_DP<9>")
	)
	(segment
		(start 345.942666 -291.554408)
		(end 345.900502 -291.512244)
		(width 0.0889)
		(layer "In11.Cu")
		(net "UPI_CPU1_CPU0_P2P2_DP<9>")
	)
	(segment
		(start 281.50058 -337.286854)
		(end 286.03575 -335.40827)
		(width 0.14732)
		(layer "In11.Cu")
		(net "UPI_CPU1_CPU0_P2P2_DP<9>")
	)
	(segment
		(start 350.105218 -281.267662)
		(end 350.111314 -281.264106)
		(width 0.0889)
		(layer "In11.Cu")
		(net "UPI_CPU1_CPU0_P2P2_DP<9>")
	)
	(segment
		(start 92.858844 -287.28924)
		(end 92.858844 -287.297876)
		(width 0.0889)
		(layer "In11.Cu")
		(net "UPI_CPU1_CPU0_P2P2_DP<9>")
	)
	(segment
		(start 92.389198 -290.12769)
		(end 92.290138 -290.22675)
		(width 0.0889)
		(layer "In11.Cu")
		(net "UPI_CPU1_CPU0_P2P2_DP<9>")
	)
	(segment
		(start 341.458296 -303.10201)
		(end 344.255344 -300.304962)
		(width 0.14732)
		(layer "In11.Cu")
		(net "UPI_CPU1_CPU0_P2P2_DP<9>")
	)
	(segment
		(start 346.085414 -291.191696)
		(end 346.225622 -291.191696)
		(width 0.0889)
		(layer "In11.Cu")
		(net "UPI_CPU1_CPU0_P2P2_DP<9>")
	)
	(arc
		(start 347.098366 -288.103056)
		(mid 347.146045 -287.920156)
		(end 347.276928 -287.783778)
		(width 0.0889)
		(layer "In11.Cu")
		(net "UPI_CPU1_CPU0_P2P2_DP<9>")
	)
	(arc
		(start 346.815918 -288.592768)
		(mid 347.018204 -288.393787)
		(end 347.098366 -288.121598)
		(width 0.0889)
		(layer "In11.Cu")
		(net "UPI_CPU1_CPU0_P2P2_DP<9>")
	)
	(arc
		(start 348.707456 -283.702252)
		(mid 348.905684 -283.496404)
		(end 348.977966 -283.219906)
		(width 0.0889)
		(layer "In11.Cu")
		(net "UPI_CPU1_CPU0_P2P2_DP<9>")
	)
	(arc
		(start 347.76156 -286.961326)
		(mid 347.964147 -286.754975)
		(end 348.038166 -286.475424)
		(width 0.0889)
		(layer "In11.Cu")
		(net "UPI_CPU1_CPU0_P2P2_DP<9>")
	)
	(arc
		(start 350.111314 -281.264106)
		(mid 350.313727 -281.057693)
		(end 350.387666 -280.778204)
		(width 0.0889)
		(layer "In11.Cu")
		(net "UPI_CPU1_CPU0_P2P2_DP<9>")
	)
	(arc
		(start 93.611192 -284.35808)
		(mid 93.408369 -284.558311)
		(end 93.328998 -284.832044)
		(width 0.0889)
		(layer "In11.Cu")
		(net "UPI_CPU1_CPU0_P2P2_DP<9>")
	)
	(arc
		(start 348.038166 -284.847538)
		(mid 348.085845 -284.664638)
		(end 348.216728 -284.52826)
		(width 0.0889)
		(layer "In11.Cu")
		(net "UPI_CPU1_CPU0_P2P2_DP<9>")
	)
	(arc
		(start 92.858844 -287.297876)
		(mid 92.806574 -287.480241)
		(end 92.671646 -287.613598)
		(width 0.0889)
		(layer "In11.Cu")
		(net "UPI_CPU1_CPU0_P2P2_DP<9>")
	)
	(arc
		(start 92.671646 -287.613598)
		(mid 92.467311 -287.816203)
		(end 92.389198 -288.09315)
		(width 0.0889)
		(layer "In11.Cu")
		(net "UPI_CPU1_CPU0_P2P2_DP<9>")
	)
	(arc
		(start 348.225618 -284.52318)
		(mid 348.428441 -284.322949)
		(end 348.507812 -284.049216)
		(width 0.0889)
		(layer "In11.Cu")
		(net "UPI_CPU1_CPU0_P2P2_DP<9>")
	)
	(arc
		(start 91.919298 -289.114738)
		(mid 92.030636 -289.307638)
		(end 92.204794 -289.446462)
		(width 0.0889)
		(layer "In11.Cu")
		(net "UPI_CPU1_CPU0_P2P2_DP<9>")
	)
	(arc
		(start 348.038166 -286.4612)
		(mid 347.958947 -286.186515)
		(end 347.755464 -285.985712)
		(width 0.0889)
		(layer "In11.Cu")
		(net "UPI_CPU1_CPU0_P2P2_DP<9>")
	)
	(arc
		(start 350.575118 -280.453846)
		(mid 350.777404 -280.254865)
		(end 350.857566 -279.982676)
		(width 0.0889)
		(layer "In11.Cu")
		(net "UPI_CPU1_CPU0_P2P2_DP<9>")
	)
	(arc
		(start 93.658944 -282.11399)
		(mid 93.762089 -282.244015)
		(end 93.798898 -282.405836)
		(width 0.0889)
		(layer "In11.Cu")
		(net "UPI_CPU1_CPU0_P2P2_DP<9>")
	)
	(arc
		(start 350.857566 -279.964134)
		(mid 350.783575 -279.684568)
		(end 350.58096 -279.478232)
		(width 0.0889)
		(layer "In11.Cu")
		(net "UPI_CPU1_CPU0_P2P2_DP<9>")
	)
	(arc
		(start 92.201746 -288.427414)
		(mid 91.99946 -288.626395)
		(end 91.919298 -288.898584)
		(width 0.0889)
		(layer "In11.Cu")
		(net "UPI_CPU1_CPU0_P2P2_DP<9>")
	)
	(arc
		(start 94.081092 -283.544264)
		(mid 93.876757 -283.746869)
		(end 93.798644 -284.023816)
		(width 0.0889)
		(layer "In11.Cu")
		(net "UPI_CPU1_CPU0_P2P2_DP<9>")
	)
	(arc
		(start 93.328998 -284.847538)
		(mid 93.281319 -285.030438)
		(end 93.150436 -285.166816)
		(width 0.0889)
		(layer "In11.Cu")
		(net "UPI_CPU1_CPU0_P2P2_DP<9>")
	)
	(arc
		(start 348.977966 -283.219906)
		(mid 349.025645 -283.037006)
		(end 349.156528 -282.900628)
		(width 0.0889)
		(layer "In11.Cu")
		(net "UPI_CPU1_CPU0_P2P2_DP<9>")
	)
	(arc
		(start 93.13545 -286.803338)
		(mid 92.932863 -287.009689)
		(end 92.858844 -287.28924)
		(width 0.0889)
		(layer "In11.Cu")
		(net "UPI_CPU1_CPU0_P2P2_DP<9>")
	)
	(arc
		(start 349.447612 -282.405836)
		(mid 349.495291 -282.222936)
		(end 349.626174 -282.086558)
		(width 0.0889)
		(layer "In11.Cu")
		(net "UPI_CPU1_CPU0_P2P2_DP<9>")
	)
	(arc
		(start 346.628466 -288.917126)
		(mid 346.676145 -288.734226)
		(end 346.807028 -288.597848)
		(width 0.0889)
		(layer "In11.Cu")
		(net "UPI_CPU1_CPU0_P2P2_DP<9>")
	)
	(arc
		(start 93.798898 -282.427934)
		(mid 93.879809 -282.698062)
		(end 94.081092 -282.895548)
		(width 0.0889)
		(layer "In11.Cu")
		(net "UPI_CPU1_CPU0_P2P2_DP<9>")
	)
	(arc
		(start 351.045018 -278.012144)
		(mid 351.2463 -277.814657)
		(end 351.327212 -277.54453)
		(width 0.0889)
		(layer "In11.Cu")
		(net "UPI_CPU1_CPU0_P2P2_DP<9>")
	)
	(arc
		(start 351.327212 -277.522432)
		(mid 351.364072 -277.360635)
		(end 351.467166 -277.230586)
		(width 0.0889)
		(layer "In11.Cu")
		(net "UPI_CPU1_CPU0_P2P2_DP<9>")
	)
	(arc
		(start 350.85782 -278.32177)
		(mid 350.908874 -278.14719)
		(end 351.036128 -278.017224)
		(width 0.0889)
		(layer "In11.Cu")
		(net "UPI_CPU1_CPU0_P2P2_DP<9>")
	)
	(arc
		(start 349.917766 -281.59202)
		(mid 349.965445 -281.40912)
		(end 350.096328 -281.272742)
		(width 0.0889)
		(layer "In11.Cu")
		(net "UPI_CPU1_CPU0_P2P2_DP<9>")
	)
	(arc
		(start 92.389198 -288.103056)
		(mid 92.341519 -288.285956)
		(end 92.210636 -288.422334)
		(width 0.0889)
		(layer "In11.Cu")
		(net "UPI_CPU1_CPU0_P2P2_DP<9>")
	)
	(arc
		(start 350.387666 -280.778204)
		(mid 350.435345 -280.595304)
		(end 350.566228 -280.458926)
		(width 0.0889)
		(layer "In11.Cu")
		(net "UPI_CPU1_CPU0_P2P2_DP<9>")
	)
	(arc
		(start 93.150436 -286.156146)
		(mid 93.329154 -286.475424)
		(end 93.150436 -286.794702)
		(width 0.0889)
		(layer "In11.Cu")
		(net "UPI_CPU1_CPU0_P2P2_DP<9>")
	)
	(arc
		(start 347.568012 -287.28924)
		(mid 347.615691 -287.10634)
		(end 347.746574 -286.969962)
		(width 0.0889)
		(layer "In11.Cu")
		(net "UPI_CPU1_CPU0_P2P2_DP<9>")
	)
	(arc
		(start 348.507812 -284.033722)
		(mid 348.555491 -283.850822)
		(end 348.686374 -283.714444)
		(width 0.0889)
		(layer "In11.Cu")
		(net "UPI_CPU1_CPU0_P2P2_DP<9>")
	)
	(arc
		(start 93.13545 -285.175452)
		(mid 92.932863 -285.381803)
		(end 92.858844 -285.661354)
		(width 0.0889)
		(layer "In11.Cu")
		(net "UPI_CPU1_CPU0_P2P2_DP<9>")
	)
	(arc
		(start 347.098112 -289.60953)
		(mid 346.986774 -289.41663)
		(end 346.812616 -289.277806)
		(width 0.0889)
		(layer "In11.Cu")
		(net "UPI_CPU1_CPU0_P2P2_DP<9>")
	)
	(arc
		(start 92.858844 -285.675578)
		(mid 92.938063 -285.950263)
		(end 93.141546 -286.151066)
		(width 0.0889)
		(layer "In11.Cu")
		(net "UPI_CPU1_CPU0_P2P2_DP<9>")
	)
	(arc
		(start 347.746574 -285.980632)
		(mid 347.567856 -285.661354)
		(end 347.746574 -285.342076)
		(width 0.0889)
		(layer "In11.Cu")
		(net "UPI_CPU1_CPU0_P2P2_DP<9>")
	)
	(arc
		(start 346.812616 -289.277806)
		(mid 346.703469 -289.193878)
		(end 346.628466 -289.078416)
		(width 0.0889)
		(layer "In11.Cu")
		(net "UPI_CPU1_CPU0_P2P2_DP<9>")
	)
	(arc
		(start 92.204794 -289.446462)
		(mid 92.313941 -289.53039)
		(end 92.388944 -289.645852)
		(width 0.0889)
		(layer "In11.Cu")
		(net "UPI_CPU1_CPU0_P2P2_DP<9>")
	)
	(arc
		(start 350.857566 -278.336502)
		(mid 350.857618 -278.329135)
		(end 350.85782 -278.32177)
		(width 0.0889)
		(layer "In11.Cu")
		(net "UPI_CPU1_CPU0_P2P2_DP<9>")
	)
	(arc
		(start 94.089982 -282.900628)
		(mid 94.217236 -283.030594)
		(end 94.26829 -283.205174)
		(width 0.0889)
		(layer "In11.Cu")
		(net "UPI_CPU1_CPU0_P2P2_DP<9>")
	)
	(arc
		(start 347.285818 -287.778698)
		(mid 347.488641 -287.578467)
		(end 347.568012 -287.304734)
		(width 0.0889)
		(layer "In11.Cu")
		(net "UPI_CPU1_CPU0_P2P2_DP<9>")
	)
	(arc
		(start 349.165418 -282.895548)
		(mid 349.3667 -282.698061)
		(end 349.447612 -282.427934)
		(width 0.0889)
		(layer "In11.Cu")
		(net "UPI_CPU1_CPU0_P2P2_DP<9>")
	)
	(arc
		(start 350.565974 -279.469596)
		(mid 350.387377 -279.150318)
		(end 350.565974 -278.83104)
		(width 0.0889)
		(layer "In11.Cu")
		(net "UPI_CPU1_CPU0_P2P2_DP<9>")
	)
	(arc
		(start 93.798644 -284.033722)
		(mid 93.750965 -284.216622)
		(end 93.620082 -284.353)
		(width 0.0889)
		(layer "In11.Cu")
		(net "UPI_CPU1_CPU0_P2P2_DP<9>")
	)
	(arc
		(start 94.26829 -283.205174)
		(mid 94.268487 -283.212539)
		(end 94.268544 -283.219906)
		(width 0.0889)
		(layer "In11.Cu")
		(net "UPI_CPU1_CPU0_P2P2_DP<9>")
	)
	(arc
		(start 347.76156 -285.33344)
		(mid 347.964147 -285.127089)
		(end 348.038166 -284.847538)
		(width 0.0889)
		(layer "In11.Cu")
		(net "UPI_CPU1_CPU0_P2P2_DP<9>")
	)
	(arc
		(start 349.64116 -282.077922)
		(mid 349.843747 -281.871571)
		(end 349.917766 -281.59202)
		(width 0.0889)
		(layer "In11.Cu")
		(net "UPI_CPU1_CPU0_P2P2_DP<9>")
	)
	(arc
		(start 94.268544 -283.219906)
		(mid 94.220865 -283.402806)
		(end 94.089982 -283.539184)
		(width 0.0889)
		(layer "In11.Cu")
		(net "UPI_CPU1_CPU0_P2P2_DP<9>")
	)
	(arc
		(start 350.58096 -278.822404)
		(mid 350.783547 -278.616053)
		(end 350.857566 -278.336502)
		(width 0.0889)
		(layer "In11.Cu")
		(net "UPI_CPU1_CPU0_P2P2_DP<9>")
	)
	(segment
		(start 352.171762 -276.708362)
		(end 352.172016 -276.708616)
		(width 0.13208)
		(layer "F.Cu")
		(net "UPI_CPU1_CPU0_P2P2_DP<8>")
	)
	(segment
		(start 352.171762 -276.172676)
		(end 352.171762 -276.708362)
		(width 0.13208)
		(layer "F.Cu")
		(net "UPI_CPU1_CPU0_P2P2_DP<8>")
	)
	(segment
		(start 93.893894 -282.683966)
		(end 93.893894 -283.219906)
		(width 0.13208)
		(layer "F.Cu")
		(net "UPI_CPU1_CPU0_P2P2_DP<8>")
	)
	(segment
		(start 342.180926 -303.242472)
		(end 342.180926 -303.447196)
		(width 0.14732)
		(layer "In11.Cu")
		(net "UPI_CPU1_CPU0_P2P2_DP<8>")
	)
	(segment
		(start 340.376256 -304.334926)
		(end 340.29777 -304.52441)
		(width 0.14732)
		(layer "In11.Cu")
		(net "UPI_CPU1_CPU0_P2P2_DP<8>")
	)
	(segment
		(start 73.570084 -372.112794)
		(end 68.39458 -366.93729)
		(width 0.14732)
		(layer "In11.Cu")
		(net "UPI_CPU1_CPU0_P2P2_DP<8>")
	)
	(segment
		(start 126.436374 -385.89077)
		(end 95.894144 -381.359918)
		(width 0.14732)
		(layer "In11.Cu")
		(net "UPI_CPU1_CPU0_P2P2_DP<8>")
	)
	(segment
		(start 90.71737 -292.5572)
		(end 90.71737 -290.344606)
		(width 0.14732)
		(layer "In11.Cu")
		(net "UPI_CPU1_CPU0_P2P2_DP<8>")
	)
	(segment
		(start 308.977538 -335.96199)
		(end 286.176466 -335.96199)
		(width 0.14732)
		(layer "In11.Cu")
		(net "UPI_CPU1_CPU0_P2P2_DP<8>")
	)
	(segment
		(start 63.377318 -354.824792)
		(end 63.377318 -335.030826)
		(width 0.14732)
		(layer "In11.Cu")
		(net "UPI_CPU1_CPU0_P2P2_DP<8>")
	)
	(segment
		(start 65.886076 -360.881168)
		(end 63.377318 -354.824792)
		(width 0.14732)
		(layer "In11.Cu")
		(net "UPI_CPU1_CPU0_P2P2_DP<8>")
	)
	(segment
		(start 351.88906 -278.82596)
		(end 351.890076 -278.826468)
		(width 0.0889)
		(layer "In11.Cu")
		(net "UPI_CPU1_CPU0_P2P2_DP<8>")
	)
	(segment
		(start 92.109798 -285.66999)
		(end 92.109798 -285.652718)
		(width 0.0889)
		(layer "In11.Cu")
		(net "UPI_CPU1_CPU0_P2P2_DP<8>")
	)
	(segment
		(start 92.579698 -286.48533)
		(end 92.579698 -286.4612)
		(width 0.0889)
		(layer "In11.Cu")
		(net "UPI_CPU1_CPU0_P2P2_DP<8>")
	)
	(segment
		(start 343.372186 -302.255936)
		(end 343.167462 -302.255936)
		(width 0.14732)
		(layer "In11.Cu")
		(net "UPI_CPU1_CPU0_P2P2_DP<8>")
	)
	(segment
		(start 92.298266 -285.336234)
		(end 92.309188 -285.329884)
		(width 0.0889)
		(layer "In11.Cu")
		(net "UPI_CPU1_CPU0_P2P2_DP<8>")
	)
	(segment
		(start 82.686652 -304.058574)
		(end 82.963766 -303.781714)
		(width 0.14732)
		(layer "In11.Cu")
		(net "UPI_CPU1_CPU0_P2P2_DP<8>")
	)
	(segment
		(start 343.167462 -302.255936)
		(end 342.906858 -302.51654)
		(width 0.14732)
		(layer "In11.Cu")
		(net "UPI_CPU1_CPU0_P2P2_DP<8>")
	)
	(segment
		(start 91.819222 -287.78327)
		(end 91.824048 -287.78073)
		(width 0.0889)
		(layer "In11.Cu")
		(net "UPI_CPU1_CPU0_P2P2_DP<8>")
	)
	(segment
		(start 344.551508 -301.076614)
		(end 344.097864 -301.530258)
		(width 0.14732)
		(layer "In11.Cu")
		(net "UPI_CPU1_CPU0_P2P2_DP<8>")
	)
	(segment
		(start 348.787466 -284.832044)
		(end 348.787466 -284.847538)
		(width 0.0889)
		(layer "In11.Cu")
		(net "UPI_CPU1_CPU0_P2P2_DP<8>")
	)
	(segment
		(start 341.673688 -303.954434)
		(end 340.905846 -304.272442)
		(width 0.14732)
		(layer "In11.Cu")
		(net "UPI_CPU1_CPU0_P2P2_DP<8>")
	)
	(segment
		(start 61.310266 -326.195182)
		(end 62.793372 -325.580756)
		(width 0.14732)
		(layer "In11.Cu")
		(net "UPI_CPU1_CPU0_P2P2_DP<8>")
	)
	(segment
		(start 90.675206 -289.724592)
		(end 90.67546 -289.723322)
		(width 0.0889)
		(layer "In11.Cu")
		(net "UPI_CPU1_CPU0_P2P2_DP<8>")
	)
	(segment
		(start 348.317312 -287.279334)
		(end 348.317312 -287.28924)
		(width 0.0889)
		(layer "In11.Cu")
		(net "UPI_CPU1_CPU0_P2P2_DP<8>")
	)
	(segment
		(start 348.60865 -286.794702)
		(end 348.603062 -286.79775)
		(width 0.0889)
		(layer "In11.Cu")
		(net "UPI_CPU1_CPU0_P2P2_DP<8>")
	)
	(segment
		(start 92.296996 -285.336996)
		(end 92.298266 -285.336234)
		(width 0.0889)
		(layer "In11.Cu")
		(net "UPI_CPU1_CPU0_P2P2_DP<8>")
	)
	(segment
		(start 92.75826 -284.52826)
		(end 92.766134 -284.523688)
		(width 0.0889)
		(layer "In11.Cu")
		(net "UPI_CPU1_CPU0_P2P2_DP<8>")
	)
	(segment
		(start 161.479738 -385.89077)
		(end 126.436374 -385.89077)
		(width 0.14732)
		(layer "In11.Cu")
		(net "UPI_CPU1_CPU0_P2P2_DP<8>")
	)
	(segment
		(start 346.502736 -291.699188)
		(end 346.502736 -294.149018)
		(width 0.14732)
		(layer "In11.Cu")
		(net "UPI_CPU1_CPU0_P2P2_DP<8>")
	)
	(segment
		(start 62.187328 -330.283058)
		(end 61.1632 -328.368152)
		(width 0.14732)
		(layer "In11.Cu")
		(net "UPI_CPU1_CPU0_P2P2_DP<8>")
	)
	(segment
		(start 348.603062 -286.79775)
		(end 348.6023 -286.798258)
		(width 0.0889)
		(layer "In11.Cu")
		(net "UPI_CPU1_CPU0_P2P2_DP<8>")
	)
	(segment
		(start 348.600014 -285.171896)
		(end 348.593918 -285.175452)
		(width 0.0889)
		(layer "In11.Cu")
		(net "UPI_CPU1_CPU0_P2P2_DP<8>")
	)
	(segment
		(start 347.377766 -288.898584)
		(end 347.377766 -289.114738)
		(width 0.0889)
		(layer "In11.Cu")
		(net "UPI_CPU1_CPU0_P2P2_DP<8>")
	)
	(segment
		(start 347.847666 -289.64636)
		(end 347.847666 -290.156138)
		(width 0.0889)
		(layer "In11.Cu")
		(net "UPI_CPU1_CPU0_P2P2_DP<8>")
	)
	(segment
		(start 352.359214 -277.032974)
		(end 352.353118 -277.03653)
		(width 0.0889)
		(layer "In11.Cu")
		(net "UPI_CPU1_CPU0_P2P2_DP<8>")
	)
	(segment
		(start 272.52168 -367.162588)
		(end 262.353806 -377.330462)
		(width 0.14732)
		(layer "In11.Cu")
		(net "UPI_CPU1_CPU0_P2P2_DP<8>")
	)
	(segment
		(start 342.906858 -302.51654)
		(end 342.906858 -302.721264)
		(width 0.14732)
		(layer "In11.Cu")
		(net "UPI_CPU1_CPU0_P2P2_DP<8>")
	)
	(segment
		(start 351.136712 -280.759662)
		(end 351.136712 -280.78684)
		(width 0.0889)
		(layer "In11.Cu")
		(net "UPI_CPU1_CPU0_P2P2_DP<8>")
	)
	(segment
		(start 286.176466 -335.96199)
		(end 281.792934 -337.777582)
		(width 0.14732)
		(layer "In11.Cu")
		(net "UPI_CPU1_CPU0_P2P2_DP<8>")
	)
	(segment
		(start 344.097864 -301.530258)
		(end 343.89314 -301.530258)
		(width 0.14732)
		(layer "In11.Cu")
		(net "UPI_CPU1_CPU0_P2P2_DP<8>")
	)
	(segment
		(start 84.21243 -302.549306)
		(end 84.473288 -302.288702)
		(width 0.14732)
		(layer "In11.Cu")
		(net "UPI_CPU1_CPU0_P2P2_DP<8>")
	)
	(segment
		(start 93.515688 -283.285438)
		(end 93.58122 -283.219906)
		(width 0.0889)
		(layer "In11.Cu")
		(net "UPI_CPU1_CPU0_P2P2_DP<8>")
	)
	(segment
		(start 337.763866 -305.573938)
		(end 317.747142 -325.590662)
		(width 0.14732)
		(layer "In11.Cu")
		(net "UPI_CPU1_CPU0_P2P2_DP<8>")
	)
	(segment
		(start 348.600522 -286.799274)
		(end 348.59976 -286.799782)
		(width 0.0889)
		(layer "In11.Cu")
		(net "UPI_CPU1_CPU0_P2P2_DP<8>")
	)
	(segment
		(start 92.109798 -287.299146)
		(end 92.109798 -287.28924)
		(width 0.0889)
		(layer "In11.Cu")
		(net "UPI_CPU1_CPU0_P2P2_DP<8>")
	)
	(segment
		(start 351.890076 -278.826468)
		(end 351.89795 -278.83104)
		(width 0.0889)
		(layer "In11.Cu")
		(net "UPI_CPU1_CPU0_P2P2_DP<8>")
	)
	(segment
		(start 62.793372 -325.580756)
		(end 63.651892 -324.722236)
		(width 0.14732)
		(layer "In11.Cu")
		(net "UPI_CPU1_CPU0_P2P2_DP<8>")
	)
	(segment
		(start 63.651892 -324.722236)
		(end 64.194436 -323.412866)
		(width 0.14732)
		(layer "In11.Cu")
		(net "UPI_CPU1_CPU0_P2P2_DP<8>")
	)
	(segment
		(start 347.805756 -290.220146)
		(end 347.805756 -290.396168)
		(width 0.14732)
		(layer "In11.Cu")
		(net "UPI_CPU1_CPU0_P2P2_DP<8>")
	)
	(segment
		(start 61.1632 -326.450198)
		(end 61.239654 -326.265794)
		(width 0.14732)
		(layer "In11.Cu")
		(net "UPI_CPU1_CPU0_P2P2_DP<8>")
	)
	(segment
		(start 91.169998 -289.114484)
		(end 91.169998 -288.908744)
		(width 0.0889)
		(layer "In11.Cu")
		(net "UPI_CPU1_CPU0_P2P2_DP<8>")
	)
	(segment
		(start 83.747356 -302.809656)
		(end 84.007706 -302.549306)
		(width 0.14732)
		(layer "In11.Cu")
		(net "UPI_CPU1_CPU0_P2P2_DP<8>")
	)
	(segment
		(start 340.716616 -304.193956)
		(end 340.376256 -304.334926)
		(width 0.14732)
		(layer "In11.Cu")
		(net "UPI_CPU1_CPU0_P2P2_DP<8>")
	)
	(segment
		(start 91.826588 -287.779206)
		(end 91.82735 -287.778698)
		(width 0.0889)
		(layer "In11.Cu")
		(net "UPI_CPU1_CPU0_P2P2_DP<8>")
	)
	(segment
		(start 350.666812 -283.21127)
		(end 350.666812 -283.228542)
		(width 0.0889)
		(layer "In11.Cu")
		(net "UPI_CPU1_CPU0_P2P2_DP<8>")
	)
	(segment
		(start 63.377318 -335.030826)
		(end 62.187328 -330.283058)
		(width 0.14732)
		(layer "In11.Cu")
		(net "UPI_CPU1_CPU0_P2P2_DP<8>")
	)
	(segment
		(start 90.675206 -290.280344)
		(end 90.675206 -289.724592)
		(width 0.0889)
		(layer "In11.Cu")
		(net "UPI_CPU1_CPU0_P2P2_DP<8>")
	)
	(segment
		(start 91.82481 -287.780222)
		(end 91.826588 -287.779206)
		(width 0.0889)
		(layer "In11.Cu")
		(net "UPI_CPU1_CPU0_P2P2_DP<8>")
	)
	(segment
		(start 84.473288 -302.288702)
		(end 84.473288 -302.083978)
		(width 0.14732)
		(layer "In11.Cu")
		(net "UPI_CPU1_CPU0_P2P2_DP<8>")
	)
	(segment
		(start 340.29777 -304.52441)
		(end 339.349842 -304.91684)
		(width 0.14732)
		(layer "In11.Cu")
		(net "UPI_CPU1_CPU0_P2P2_DP<8>")
	)
	(segment
		(start 84.473288 -302.083978)
		(end 85.357716 -301.199804)
		(width 0.14732)
		(layer "In11.Cu")
		(net "UPI_CPU1_CPU0_P2P2_DP<8>")
	)
	(segment
		(start 85.357716 -301.199804)
		(end 87.678514 -295.596056)
		(width 0.14732)
		(layer "In11.Cu")
		(net "UPI_CPU1_CPU0_P2P2_DP<8>")
	)
	(segment
		(start 350.949514 -281.102562)
		(end 350.943418 -281.106118)
		(width 0.0889)
		(layer "In11.Cu")
		(net "UPI_CPU1_CPU0_P2P2_DP<8>")
	)
	(segment
		(start 91.34856 -288.597848)
		(end 91.35745 -288.592768)
		(width 0.0889)
		(layer "In11.Cu")
		(net "UPI_CPU1_CPU0_P2P2_DP<8>")
	)
	(segment
		(start 66.439542 -320.619374)
		(end 66.762376 -320.03365)
		(width 0.14732)
		(layer "In11.Cu")
		(net "UPI_CPU1_CPU0_P2P2_DP<8>")
	)
	(segment
		(start 342.180926 -303.447196)
		(end 341.673688 -303.954434)
		(width 0.14732)
		(layer "In11.Cu")
		(net "UPI_CPU1_CPU0_P2P2_DP<8>")
	)
	(segment
		(start 87.678514 -295.596056)
		(end 90.71737 -292.5572)
		(width 0.14732)
		(layer "In11.Cu")
		(net "UPI_CPU1_CPU0_P2P2_DP<8>")
	)
	(segment
		(start 95.894144 -381.359918)
		(end 73.570084 -372.112794)
		(width 0.14732)
		(layer "In11.Cu")
		(net "UPI_CPU1_CPU0_P2P2_DP<8>")
	)
	(segment
		(start 347.669104 -288.422334)
		(end 347.660214 -288.427414)
		(width 0.0889)
		(layer "In11.Cu")
		(net "UPI_CPU1_CPU0_P2P2_DP<8>")
	)
	(segment
		(start 343.632536 -301.790862)
		(end 343.632536 -301.995586)
		(width 0.14732)
		(layer "In11.Cu")
		(net "UPI_CPU1_CPU0_P2P2_DP<8>")
	)
	(segment
		(start 92.766134 -284.523688)
		(end 92.76715 -284.52318)
		(width 0.0889)
		(layer "In11.Cu")
		(net "UPI_CPU1_CPU0_P2P2_DP<8>")
	)
	(segment
		(start 348.600522 -286.151574)
		(end 348.60865 -286.156146)
		(width 0.0889)
		(layer "In11.Cu")
		(net "UPI_CPU1_CPU0_P2P2_DP<8>")
	)
	(segment
		(start 83.486752 -303.274984)
		(end 83.747356 -303.01438)
		(width 0.14732)
		(layer "In11.Cu")
		(net "UPI_CPU1_CPU0_P2P2_DP<8>")
	)
	(segment
		(start 272.52168 -347.048836)
		(end 272.52168 -367.162588)
		(width 0.14732)
		(layer "In11.Cu")
		(net "UPI_CPU1_CPU0_P2P2_DP<8>")
	)
	(segment
		(start 65.931796 -321.860926)
		(end 65.931796 -321.86118)
		(width 0.14732)
		(layer "In11.Cu")
		(net "UPI_CPU1_CPU0_P2P2_DP<8>")
	)
	(segment
		(start 82.498184 -304.058574)
		(end 82.686652 -304.058574)
		(width 0.14732)
		(layer "In11.Cu")
		(net "UPI_CPU1_CPU0_P2P2_DP<8>")
	)
	(segment
		(start 349.07855 -284.353)
		(end 349.06966 -284.35808)
		(width 0.0889)
		(layer "In11.Cu")
		(net "UPI_CPU1_CPU0_P2P2_DP<8>")
	)
	(segment
		(start 64.194436 -323.412866)
		(end 64.511428 -323.097144)
		(width 0.14732)
		(layer "In11.Cu")
		(net "UPI_CPU1_CPU0_P2P2_DP<8>")
	)
	(segment
		(start 339.349842 -304.91684)
		(end 339.349588 -304.917348)
		(width 0.14732)
		(layer "In11.Cu")
		(net "UPI_CPU1_CPU0_P2P2_DP<8>")
	)
	(segment
		(start 348.59976 -286.151066)
		(end 348.600522 -286.151574)
		(width 0.0889)
		(layer "In11.Cu")
		(net "UPI_CPU1_CPU0_P2P2_DP<8>")
	)
	(segment
		(start 91.81846 -287.783778)
		(end 91.819222 -287.78327)
		(width 0.0889)
		(layer "In11.Cu")
		(net "UPI_CPU1_CPU0_P2P2_DP<8>")
	)
	(segment
		(start 347.847666 -290.156138)
		(end 347.805756 -290.198048)
		(width 0.0889)
		(layer "In11.Cu")
		(net "UPI_CPU1_CPU0_P2P2_DP<8>")
	)
	(segment
		(start 66.200782 -321.372484)
		(end 66.439542 -320.619374)
		(width 0.14732)
		(layer "In11.Cu")
		(net "UPI_CPU1_CPU0_P2P2_DP<8>")
	)
	(segment
		(start 351.89795 -277.84171)
		(end 351.88906 -277.84679)
		(width 0.0889)
		(layer "In11.Cu")
		(net "UPI_CPU1_CPU0_P2P2_DP<8>")
	)
	(segment
		(start 348.6023 -286.798258)
		(end 348.600522 -286.799274)
		(width 0.0889)
		(layer "In11.Cu")
		(net "UPI_CPU1_CPU0_P2P2_DP<8>")
	)
	(segment
		(start 340.905846 -304.272442)
		(end 340.716616 -304.193956)
		(width 0.14732)
		(layer "In11.Cu")
		(net "UPI_CPU1_CPU0_P2P2_DP<8>")
	)
	(segment
		(start 83.282028 -303.274984)
		(end 83.486752 -303.274984)
		(width 0.14732)
		(layer "In11.Cu")
		(net "UPI_CPU1_CPU0_P2P2_DP<8>")
	)
	(segment
		(start 90.71737 -290.344606)
		(end 90.71737 -290.322508)
		(width 0.0889)
		(layer "In11.Cu")
		(net "UPI_CPU1_CPU0_P2P2_DP<8>")
	)
	(segment
		(start 65.886076 -360.881422)
		(end 65.886076 -360.881168)
		(width 0.14732)
		(layer "In11.Cu")
		(net "UPI_CPU1_CPU0_P2P2_DP<8>")
	)
	(segment
		(start 93.227906 -283.714444)
		(end 93.236796 -283.709364)
		(width 0.0889)
		(layer "In11.Cu")
		(net "UPI_CPU1_CPU0_P2P2_DP<8>")
	)
	(segment
		(start 61.1632 -328.368152)
		(end 61.1632 -326.450198)
		(width 0.14732)
		(layer "In11.Cu")
		(net "UPI_CPU1_CPU0_P2P2_DP<8>")
	)
	(segment
		(start 348.608904 -285.166816)
		(end 348.600014 -285.171896)
		(width 0.0889)
		(layer "In11.Cu")
		(net "UPI_CPU1_CPU0_P2P2_DP<8>")
	)
	(segment
		(start 91.169998 -288.908744)
		(end 91.170252 -288.902394)
		(width 0.0889)
		(layer "In11.Cu")
		(net "UPI_CPU1_CPU0_P2P2_DP<8>")
	)
	(segment
		(start 82.963766 -303.593246)
		(end 83.282028 -303.274984)
		(width 0.14732)
		(layer "In11.Cu")
		(net "UPI_CPU1_CPU0_P2P2_DP<8>")
	)
	(segment
		(start 351.89795 -279.469596)
		(end 351.88906 -279.474676)
		(width 0.0889)
		(layer "In11.Cu")
		(net "UPI_CPU1_CPU0_P2P2_DP<8>")
	)
	(segment
		(start 345.65463 -298.41317)
		(end 344.551508 -301.076614)
		(width 0.14732)
		(layer "In11.Cu")
		(net "UPI_CPU1_CPU0_P2P2_DP<8>")
	)
	(segment
		(start 347.847666 -288.087562)
		(end 347.847666 -288.103056)
		(width 0.0889)
		(layer "In11.Cu")
		(net "UPI_CPU1_CPU0_P2P2_DP<8>")
	)
	(segment
		(start 93.049344 -284.049216)
		(end 93.049344 -284.033722)
		(width 0.0889)
		(layer "In11.Cu")
		(net "UPI_CPU1_CPU0_P2P2_DP<8>")
	)
	(segment
		(start 281.792934 -337.777582)
		(end 272.52168 -347.048836)
		(width 0.14732)
		(layer "In11.Cu")
		(net "UPI_CPU1_CPU0_P2P2_DP<8>")
	)
	(segment
		(start 346.502736 -294.149018)
		(end 345.65463 -298.41317)
		(width 0.14732)
		(layer "In11.Cu")
		(net "UPI_CPU1_CPU0_P2P2_DP<8>")
	)
	(segment
		(start 93.58122 -283.219906)
		(end 93.893894 -283.219906)
		(width 0.0889)
		(layer "In11.Cu")
		(net "UPI_CPU1_CPU0_P2P2_DP<8>")
	)
	(segment
		(start 351.606866 -278.314404)
		(end 351.606866 -278.351996)
		(width 0.0889)
		(layer "In11.Cu")
		(net "UPI_CPU1_CPU0_P2P2_DP<8>")
	)
	(segment
		(start 316.61481 -328.324718)
		(end 308.977538 -335.96199)
		(width 0.14732)
		(layer "In11.Cu")
		(net "UPI_CPU1_CPU0_P2P2_DP<8>")
	)
	(segment
		(start 92.28836 -286.969962)
		(end 92.29725 -286.964882)
		(width 0.0889)
		(layer "In11.Cu")
		(net "UPI_CPU1_CPU0_P2P2_DP<8>")
	)
	(segment
		(start 65.657222 -322.359528)
		(end 65.931796 -321.860926)
		(width 0.14732)
		(layer "In11.Cu")
		(net "UPI_CPU1_CPU0_P2P2_DP<8>")
	)
	(segment
		(start 347.805756 -290.198048)
		(end 347.805756 -290.220146)
		(width 0.0889)
		(layer "In11.Cu")
		(net "UPI_CPU1_CPU0_P2P2_DP<8>")
	)
	(segment
		(start 350.666812 -281.59202)
		(end 350.666812 -281.600656)
		(width 0.0889)
		(layer "In11.Cu")
		(net "UPI_CPU1_CPU0_P2P2_DP<8>")
	)
	(segment
		(start 352.48469 -276.708616)
		(end 352.542094 -276.76602)
		(width 0.0889)
		(layer "In11.Cu")
		(net "UPI_CPU1_CPU0_P2P2_DP<8>")
	)
	(segment
		(start 69.138546 -317.657988)
		(end 69.138546 -317.414402)
		(width 0.14732)
		(layer "In11.Cu")
		(net "UPI_CPU1_CPU0_P2P2_DP<8>")
	)
	(segment
		(start 69.138546 -317.414402)
		(end 82.498184 -304.058574)
		(width 0.14732)
		(layer "In11.Cu")
		(net "UPI_CPU1_CPU0_P2P2_DP<8>")
	)
	(segment
		(start 65.931796 -321.86118)
		(end 66.200782 -321.372484)
		(width 0.14732)
		(layer "In11.Cu")
		(net "UPI_CPU1_CPU0_P2P2_DP<8>")
	)
	(segment
		(start 343.89314 -301.530258)
		(end 343.632536 -301.790862)
		(width 0.14732)
		(layer "In11.Cu")
		(net "UPI_CPU1_CPU0_P2P2_DP<8>")
	)
	(segment
		(start 91.639898 -288.11728)
		(end 91.639898 -288.103056)
		(width 0.0889)
		(layer "In11.Cu")
		(net "UPI_CPU1_CPU0_P2P2_DP<8>")
	)
	(segment
		(start 351.42805 -280.283412)
		(end 351.41916 -280.288492)
		(width 0.0889)
		(layer "In11.Cu")
		(net "UPI_CPU1_CPU0_P2P2_DP<8>")
	)
	(segment
		(start 349.554546 -283.535628)
		(end 349.533718 -283.54782)
		(width 0.0889)
		(layer "In11.Cu")
		(net "UPI_CPU1_CPU0_P2P2_DP<8>")
	)
	(segment
		(start 82.963766 -303.781714)
		(end 82.963766 -303.593246)
		(width 0.14732)
		(layer "In11.Cu")
		(net "UPI_CPU1_CPU0_P2P2_DP<8>")
	)
	(segment
		(start 352.172016 -276.708616)
		(end 352.48469 -276.708616)
		(width 0.0889)
		(layer "In11.Cu")
		(net "UPI_CPU1_CPU0_P2P2_DP<8>")
	)
	(segment
		(start 84.007706 -302.549306)
		(end 84.21243 -302.549306)
		(width 0.14732)
		(layer "In11.Cu")
		(net "UPI_CPU1_CPU0_P2P2_DP<8>")
	)
	(segment
		(start 348.13875 -287.608518)
		(end 348.12986 -287.613598)
		(width 0.0889)
		(layer "In11.Cu")
		(net "UPI_CPU1_CPU0_P2P2_DP<8>")
	)
	(segment
		(start 347.847412 -289.645852)
		(end 347.847666 -289.64636)
		(width 0.0889)
		(layer "In11.Cu")
		(net "UPI_CPU1_CPU0_P2P2_DP<8>")
	)
	(segment
		(start 83.747356 -303.01438)
		(end 83.747356 -302.809656)
		(width 0.14732)
		(layer "In11.Cu")
		(net "UPI_CPU1_CPU0_P2P2_DP<8>")
	)
	(segment
		(start 351.88906 -279.474676)
		(end 351.882964 -279.478232)
		(width 0.0889)
		(layer "In11.Cu")
		(net "UPI_CPU1_CPU0_P2P2_DP<8>")
	)
	(segment
		(start 262.353806 -377.330462)
		(end 161.479738 -385.89077)
		(width 0.14732)
		(layer "In11.Cu")
		(net "UPI_CPU1_CPU0_P2P2_DP<8>")
	)
	(segment
		(start 342.646508 -302.981614)
		(end 342.441784 -302.981614)
		(width 0.14732)
		(layer "In11.Cu")
		(net "UPI_CPU1_CPU0_P2P2_DP<8>")
	)
	(segment
		(start 66.762376 -320.03365)
		(end 69.138546 -317.657988)
		(width 0.14732)
		(layer "In11.Cu")
		(net "UPI_CPU1_CPU0_P2P2_DP<8>")
	)
	(segment
		(start 348.317312 -285.661354)
		(end 348.317312 -285.679896)
		(width 0.0889)
		(layer "In11.Cu")
		(net "UPI_CPU1_CPU0_P2P2_DP<8>")
	)
	(segment
		(start 343.632536 -301.995586)
		(end 343.372186 -302.255936)
		(width 0.14732)
		(layer "In11.Cu")
		(net "UPI_CPU1_CPU0_P2P2_DP<8>")
	)
	(segment
		(start 342.441784 -302.981614)
		(end 342.180926 -303.242472)
		(width 0.14732)
		(layer "In11.Cu")
		(net "UPI_CPU1_CPU0_P2P2_DP<8>")
	)
	(segment
		(start 65.202054 -322.813426)
		(end 65.657222 -322.359528)
		(width 0.14732)
		(layer "In11.Cu")
		(net "UPI_CPU1_CPU0_P2P2_DP<8>")
	)
	(segment
		(start 91.824048 -287.78073)
		(end 91.82481 -287.780222)
		(width 0.0889)
		(layer "In11.Cu")
		(net "UPI_CPU1_CPU0_P2P2_DP<8>")
	)
	(segment
		(start 350.196912 -282.405836)
		(end 350.196912 -282.413456)
		(width 0.0889)
		(layer "In11.Cu")
		(net "UPI_CPU1_CPU0_P2P2_DP<8>")
	)
	(segment
		(start 64.511428 -323.097144)
		(end 65.202054 -322.813426)
		(width 0.14732)
		(layer "In11.Cu")
		(net "UPI_CPU1_CPU0_P2P2_DP<8>")
	)
	(segment
		(start 61.239654 -326.265794)
		(end 61.310266 -326.195182)
		(width 0.14732)
		(layer "In11.Cu")
		(net "UPI_CPU1_CPU0_P2P2_DP<8>")
	)
	(segment
		(start 352.368104 -277.027894)
		(end 352.359214 -277.032974)
		(width 0.0889)
		(layer "In11.Cu")
		(net "UPI_CPU1_CPU0_P2P2_DP<8>")
	)
	(segment
		(start 68.39458 -366.93729)
		(end 65.886076 -360.881422)
		(width 0.14732)
		(layer "In11.Cu")
		(net "UPI_CPU1_CPU0_P2P2_DP<8>")
	)
	(segment
		(start 342.906858 -302.721264)
		(end 342.646508 -302.981614)
		(width 0.14732)
		(layer "In11.Cu")
		(net "UPI_CPU1_CPU0_P2P2_DP<8>")
	)
	(segment
		(start 347.805756 -290.396168)
		(end 346.502736 -291.699188)
		(width 0.14732)
		(layer "In11.Cu")
		(net "UPI_CPU1_CPU0_P2P2_DP<8>")
	)
	(segment
		(start 90.71737 -290.322508)
		(end 90.675206 -290.280344)
		(width 0.0889)
		(layer "In11.Cu")
		(net "UPI_CPU1_CPU0_P2P2_DP<8>")
	)
	(segment
		(start 350.479614 -281.916378)
		(end 350.467422 -281.92349)
		(width 0.0889)
		(layer "In11.Cu")
		(net "UPI_CPU1_CPU0_P2P2_DP<8>")
	)
	(segment
		(start 339.349588 -304.917348)
		(end 337.763866 -305.573938)
		(width 0.14732)
		(layer "In11.Cu")
		(net "UPI_CPU1_CPU0_P2P2_DP<8>")
	)
	(segment
		(start 317.747142 -325.590662)
		(end 316.61481 -328.324718)
		(width 0.14732)
		(layer "In11.Cu")
		(net "UPI_CPU1_CPU0_P2P2_DP<8>")
	)
	(arc
		(start 349.257112 -284.033722)
		(mid 349.209433 -284.216622)
		(end 349.07855 -284.353)
		(width 0.0889)
		(layer "In11.Cu")
		(net "UPI_CPU1_CPU0_P2P2_DP<8>")
	)
	(arc
		(start 90.884248 -289.446462)
		(mid 91.058549 -289.307532)
		(end 91.169998 -289.114484)
		(width 0.0889)
		(layer "In11.Cu")
		(net "UPI_CPU1_CPU0_P2P2_DP<8>")
	)
	(arc
		(start 348.593918 -285.175452)
		(mid 348.391331 -285.381803)
		(end 348.317312 -285.661354)
		(width 0.0889)
		(layer "In11.Cu")
		(net "UPI_CPU1_CPU0_P2P2_DP<8>")
	)
	(arc
		(start 351.41916 -280.288492)
		(mid 351.216874 -280.487473)
		(end 351.136712 -280.759662)
		(width 0.0889)
		(layer "In11.Cu")
		(net "UPI_CPU1_CPU0_P2P2_DP<8>")
	)
	(arc
		(start 351.882964 -279.478232)
		(mid 351.680551 -279.684645)
		(end 351.606612 -279.964134)
		(width 0.0889)
		(layer "In11.Cu")
		(net "UPI_CPU1_CPU0_P2P2_DP<8>")
	)
	(arc
		(start 92.109798 -285.652718)
		(mid 92.162068 -285.470353)
		(end 92.296996 -285.336996)
		(width 0.0889)
		(layer "In11.Cu")
		(net "UPI_CPU1_CPU0_P2P2_DP<8>")
	)
	(arc
		(start 352.542094 -276.76602)
		(mid 352.483938 -276.916133)
		(end 352.368104 -277.027894)
		(width 0.0889)
		(layer "In11.Cu")
		(net "UPI_CPU1_CPU0_P2P2_DP<8>")
	)
	(arc
		(start 350.467422 -281.92349)
		(mid 350.269194 -282.129338)
		(end 350.196912 -282.405836)
		(width 0.0889)
		(layer "In11.Cu")
		(net "UPI_CPU1_CPU0_P2P2_DP<8>")
	)
	(arc
		(start 90.67546 -289.723322)
		(mid 90.74897 -289.561606)
		(end 90.884248 -289.446462)
		(width 0.0889)
		(layer "In11.Cu")
		(net "UPI_CPU1_CPU0_P2P2_DP<8>")
	)
	(arc
		(start 93.236796 -283.709364)
		(mid 93.420625 -283.539309)
		(end 93.512894 -283.30652)
		(width 0.0889)
		(layer "In11.Cu")
		(net "UPI_CPU1_CPU0_P2P2_DP<8>")
	)
	(arc
		(start 347.663262 -289.446462)
		(mid 347.772409 -289.53039)
		(end 347.847412 -289.645852)
		(width 0.0889)
		(layer "In11.Cu")
		(net "UPI_CPU1_CPU0_P2P2_DP<8>")
	)
	(arc
		(start 350.479614 -282.895548)
		(mid 350.614547 -283.028902)
		(end 350.666812 -283.21127)
		(width 0.0889)
		(layer "In11.Cu")
		(net "UPI_CPU1_CPU0_P2P2_DP<8>")
	)
	(arc
		(start 352.353118 -277.03653)
		(mid 352.150531 -277.242881)
		(end 352.076512 -277.522432)
		(width 0.0889)
		(layer "In11.Cu")
		(net "UPI_CPU1_CPU0_P2P2_DP<8>")
	)
	(arc
		(start 351.606612 -279.964134)
		(mid 351.558933 -280.147034)
		(end 351.42805 -280.283412)
		(width 0.0889)
		(layer "In11.Cu")
		(net "UPI_CPU1_CPU0_P2P2_DP<8>")
	)
	(arc
		(start 351.136712 -280.78684)
		(mid 351.084442 -280.969205)
		(end 350.949514 -281.102562)
		(width 0.0889)
		(layer "In11.Cu")
		(net "UPI_CPU1_CPU0_P2P2_DP<8>")
	)
	(arc
		(start 92.109798 -287.28924)
		(mid 92.157477 -287.10634)
		(end 92.28836 -286.969962)
		(width 0.0889)
		(layer "In11.Cu")
		(net "UPI_CPU1_CPU0_P2P2_DP<8>")
	)
	(arc
		(start 92.29725 -286.964882)
		(mid 92.501585 -286.762277)
		(end 92.579698 -286.48533)
		(width 0.0889)
		(layer "In11.Cu")
		(net "UPI_CPU1_CPU0_P2P2_DP<8>")
	)
	(arc
		(start 352.076258 -277.537164)
		(mid 352.025204 -277.711744)
		(end 351.89795 -277.84171)
		(width 0.0889)
		(layer "In11.Cu")
		(net "UPI_CPU1_CPU0_P2P2_DP<8>")
	)
	(arc
		(start 93.512894 -283.30652)
		(mid 93.514391 -283.295992)
		(end 93.515688 -283.285438)
		(width 0.0889)
		(layer "In11.Cu")
		(net "UPI_CPU1_CPU0_P2P2_DP<8>")
	)
	(arc
		(start 347.377766 -289.114738)
		(mid 347.489104 -289.307638)
		(end 347.663262 -289.446462)
		(width 0.0889)
		(layer "In11.Cu")
		(net "UPI_CPU1_CPU0_P2P2_DP<8>")
	)
	(arc
		(start 348.60865 -286.156146)
		(mid 348.787247 -286.475424)
		(end 348.60865 -286.794702)
		(width 0.0889)
		(layer "In11.Cu")
		(net "UPI_CPU1_CPU0_P2P2_DP<8>")
	)
	(arc
		(start 351.606866 -278.351996)
		(mid 351.686236 -278.62573)
		(end 351.88906 -278.82596)
		(width 0.0889)
		(layer "In11.Cu")
		(net "UPI_CPU1_CPU0_P2P2_DP<8>")
	)
	(arc
		(start 350.666812 -283.228542)
		(mid 350.614542 -283.410907)
		(end 350.479614 -283.544264)
		(width 0.0889)
		(layer "In11.Cu")
		(net "UPI_CPU1_CPU0_P2P2_DP<8>")
	)
	(arc
		(start 351.88906 -277.84679)
		(mid 351.687778 -278.044277)
		(end 351.606866 -278.314404)
		(width 0.0889)
		(layer "In11.Cu")
		(net "UPI_CPU1_CPU0_P2P2_DP<8>")
	)
	(arc
		(start 347.660214 -288.427414)
		(mid 347.457928 -288.626395)
		(end 347.377766 -288.898584)
		(width 0.0889)
		(layer "In11.Cu")
		(net "UPI_CPU1_CPU0_P2P2_DP<8>")
	)
	(arc
		(start 348.12986 -287.613598)
		(mid 347.927037 -287.813829)
		(end 347.847666 -288.087562)
		(width 0.0889)
		(layer "In11.Cu")
		(net "UPI_CPU1_CPU0_P2P2_DP<8>")
	)
	(arc
		(start 347.847666 -288.103056)
		(mid 347.799987 -288.285956)
		(end 347.669104 -288.422334)
		(width 0.0889)
		(layer "In11.Cu")
		(net "UPI_CPU1_CPU0_P2P2_DP<8>")
	)
	(arc
		(start 348.317312 -285.679896)
		(mid 348.397474 -285.952085)
		(end 348.59976 -286.151066)
		(width 0.0889)
		(layer "In11.Cu")
		(net "UPI_CPU1_CPU0_P2P2_DP<8>")
	)
	(arc
		(start 93.049344 -284.033722)
		(mid 93.097023 -283.850822)
		(end 93.227906 -283.714444)
		(width 0.0889)
		(layer "In11.Cu")
		(net "UPI_CPU1_CPU0_P2P2_DP<8>")
	)
	(arc
		(start 349.06966 -284.35808)
		(mid 348.866837 -284.558311)
		(end 348.787466 -284.832044)
		(width 0.0889)
		(layer "In11.Cu")
		(net "UPI_CPU1_CPU0_P2P2_DP<8>")
	)
	(arc
		(start 92.76715 -284.52318)
		(mid 92.969973 -284.322949)
		(end 93.049344 -284.049216)
		(width 0.0889)
		(layer "In11.Cu")
		(net "UPI_CPU1_CPU0_P2P2_DP<8>")
	)
	(arc
		(start 91.170252 -288.902394)
		(mid 91.221306 -288.727814)
		(end 91.34856 -288.597848)
		(width 0.0889)
		(layer "In11.Cu")
		(net "UPI_CPU1_CPU0_P2P2_DP<8>")
	)
	(arc
		(start 350.943418 -281.106118)
		(mid 350.740831 -281.312469)
		(end 350.666812 -281.59202)
		(width 0.0889)
		(layer "In11.Cu")
		(net "UPI_CPU1_CPU0_P2P2_DP<8>")
	)
	(arc
		(start 352.076512 -277.522432)
		(mid 352.07646 -277.529799)
		(end 352.076258 -277.537164)
		(width 0.0889)
		(layer "In11.Cu")
		(net "UPI_CPU1_CPU0_P2P2_DP<8>")
	)
	(arc
		(start 350.105218 -283.544264)
		(mid 349.831019 -283.468429)
		(end 349.554546 -283.535628)
		(width 0.0889)
		(layer "In11.Cu")
		(net "UPI_CPU1_CPU0_P2P2_DP<8>")
	)
	(arc
		(start 92.579698 -284.847538)
		(mid 92.627377 -284.664638)
		(end 92.75826 -284.52826)
		(width 0.0889)
		(layer "In11.Cu")
		(net "UPI_CPU1_CPU0_P2P2_DP<8>")
	)
	(arc
		(start 92.579698 -286.4612)
		(mid 92.500479 -286.186515)
		(end 92.296996 -285.985712)
		(width 0.0889)
		(layer "In11.Cu")
		(net "UPI_CPU1_CPU0_P2P2_DP<8>")
	)
	(arc
		(start 91.35745 -288.592768)
		(mid 91.560755 -288.391902)
		(end 91.639898 -288.11728)
		(width 0.0889)
		(layer "In11.Cu")
		(net "UPI_CPU1_CPU0_P2P2_DP<8>")
	)
	(arc
		(start 348.317312 -287.28924)
		(mid 348.269633 -287.47214)
		(end 348.13875 -287.608518)
		(width 0.0889)
		(layer "In11.Cu")
		(net "UPI_CPU1_CPU0_P2P2_DP<8>")
	)
	(arc
		(start 350.666812 -281.600656)
		(mid 350.614542 -281.783021)
		(end 350.479614 -281.916378)
		(width 0.0889)
		(layer "In11.Cu")
		(net "UPI_CPU1_CPU0_P2P2_DP<8>")
	)
	(arc
		(start 91.82735 -287.778698)
		(mid 92.031685 -287.576093)
		(end 92.109798 -287.299146)
		(width 0.0889)
		(layer "In11.Cu")
		(net "UPI_CPU1_CPU0_P2P2_DP<8>")
	)
	(arc
		(start 92.309188 -285.329884)
		(mid 92.507416 -285.124036)
		(end 92.579698 -284.847538)
		(width 0.0889)
		(layer "In11.Cu")
		(net "UPI_CPU1_CPU0_P2P2_DP<8>")
	)
	(arc
		(start 348.787466 -284.847538)
		(mid 348.739787 -285.030438)
		(end 348.608904 -285.166816)
		(width 0.0889)
		(layer "In11.Cu")
		(net "UPI_CPU1_CPU0_P2P2_DP<8>")
	)
	(arc
		(start 92.296996 -285.985712)
		(mid 92.162063 -285.852358)
		(end 92.109798 -285.66999)
		(width 0.0889)
		(layer "In11.Cu")
		(net "UPI_CPU1_CPU0_P2P2_DP<8>")
	)
	(arc
		(start 91.639898 -288.103056)
		(mid 91.687577 -287.920156)
		(end 91.81846 -287.783778)
		(width 0.0889)
		(layer "In11.Cu")
		(net "UPI_CPU1_CPU0_P2P2_DP<8>")
	)
	(arc
		(start 351.89795 -278.83104)
		(mid 352.076426 -279.150318)
		(end 351.89795 -279.469596)
		(width 0.0889)
		(layer "In11.Cu")
		(net "UPI_CPU1_CPU0_P2P2_DP<8>")
	)
	(arc
		(start 348.59976 -286.799782)
		(mid 348.395425 -287.002387)
		(end 348.317312 -287.279334)
		(width 0.0889)
		(layer "In11.Cu")
		(net "UPI_CPU1_CPU0_P2P2_DP<8>")
	)
	(arc
		(start 350.196912 -282.413456)
		(mid 350.274541 -282.691869)
		(end 350.479614 -282.895548)
		(width 0.0889)
		(layer "In11.Cu")
		(net "UPI_CPU1_CPU0_P2P2_DP<8>")
	)
	(arc
		(start 349.533718 -283.54782)
		(mid 349.331131 -283.754171)
		(end 349.257112 -284.033722)
		(width 0.0889)
		(layer "In11.Cu")
		(net "UPI_CPU1_CPU0_P2P2_DP<8>")
	)
	(arc
		(start 350.479614 -283.544264)
		(mid 350.292416 -283.594407)
		(end 350.105218 -283.544264)
		(width 0.0889)
		(layer "In11.Cu")
		(net "UPI_CPU1_CPU0_P2P2_DP<8>")
	)
	(segment
		(start 350.762316 -275.894546)
		(end 350.762062 -275.8948)
		(width 0.13208)
		(layer "F.Cu")
		(net "UPI_CPU1_CPU0_P2P2_DP<7>")
	)
	(segment
		(start 92.954348 -281.591766)
		(end 92.954094 -281.59202)
		(width 0.13208)
		(layer "F.Cu")
		(net "UPI_CPU1_CPU0_P2P2_DP<7>")
	)
	(segment
		(start 92.954094 -281.05608)
		(end 92.954348 -281.056334)
		(width 0.13208)
		(layer "F.Cu")
		(net "UPI_CPU1_CPU0_P2P2_DP<7>")
	)
	(segment
		(start 350.762316 -275.35886)
		(end 350.762316 -275.894546)
		(width 0.13208)
		(layer "F.Cu")
		(net "UPI_CPU1_CPU0_P2P2_DP<7>")
	)
	(segment
		(start 92.954348 -281.056334)
		(end 92.954348 -281.591766)
		(width 0.13208)
		(layer "F.Cu")
		(net "UPI_CPU1_CPU0_P2P2_DP<7>")
	)
	(segment
		(start 92.79763 -281.321002)
		(end 92.818712 -281.243024)
		(width 0.0889)
		(layer "In11.Cu")
		(net "UPI_CPU1_CPU0_P2P2_DP<7>")
	)
	(segment
		(start 90.800936 -287.608264)
		(end 90.796872 -287.61055)
		(width 0.0889)
		(layer "In11.Cu")
		(net "UPI_CPU1_CPU0_P2P2_DP<7>")
	)
	(segment
		(start 273.62404 -347.505782)
		(end 282.35148 -338.778342)
		(width 0.14732)
		(layer "In11.Cu")
		(net "UPI_CPU1_CPU0_P2P2_DP<7>")
	)
	(segment
		(start 92.388944 -283.205682)
		(end 92.388944 -283.219906)
		(width 0.0889)
		(layer "In11.Cu")
		(net "UPI_CPU1_CPU0_P2P2_DP<7>")
	)
	(segment
		(start 347.638624 -294.848534)
		(end 347.644212 -294.842946)
		(width 0.14732)
		(layer "In11.Cu")
		(net "UPI_CPU1_CPU0_P2P2_DP<7>")
	)
	(segment
		(start 92.859098 -282.390342)
		(end 92.859098 -282.405836)
		(width 0.0889)
		(layer "In11.Cu")
		(net "UPI_CPU1_CPU0_P2P2_DP<7>")
	)
	(segment
		(start 350.565974 -285.342076)
		(end 350.57334 -285.337758)
		(width 0.0889)
		(layer "In11.Cu")
		(net "UPI_CPU1_CPU0_P2P2_DP<7>")
	)
	(segment
		(start 349.635064 -286.964882)
		(end 349.64116 -286.961326)
		(width 0.0889)
		(layer "In11.Cu")
		(net "UPI_CPU1_CPU0_P2P2_DP<7>")
	)
	(segment
		(start 64.926972 -321.370198)
		(end 64.31915 -321.97802)
		(width 0.14732)
		(layer "In11.Cu")
		(net "UPI_CPU1_CPU0_P2P2_DP<7>")
	)
	(segment
		(start 62.274958 -335.364836)
		(end 62.274958 -355.04882)
		(width 0.14732)
		(layer "In11.Cu")
		(net "UPI_CPU1_CPU0_P2P2_DP<7>")
	)
	(segment
		(start 90.979498 -287.273746)
		(end 90.979498 -287.28924)
		(width 0.0889)
		(layer "In11.Cu")
		(net "UPI_CPU1_CPU0_P2P2_DP<7>")
	)
	(segment
		(start 352.449892 -281.100022)
		(end 352.445574 -281.097482)
		(width 0.0889)
		(layer "In11.Cu")
		(net "UPI_CPU1_CPU0_P2P2_DP<7>")
	)
	(segment
		(start 348.977966 -288.121598)
		(end 348.977966 -288.103056)
		(width 0.0889)
		(layer "In11.Cu")
		(net "UPI_CPU1_CPU0_P2P2_DP<7>")
	)
	(segment
		(start 93.141292 -281.267662)
		(end 93.150182 -281.272742)
		(width 0.0889)
		(layer "In11.Cu")
		(net "UPI_CPU1_CPU0_P2P2_DP<7>")
	)
	(segment
		(start 84.536788 -300.258734)
		(end 67.735196 -317.060326)
		(width 0.14732)
		(layer "In11.Cu")
		(net "UPI_CPU1_CPU0_P2P2_DP<7>")
	)
	(segment
		(start 64.31915 -321.97802)
		(end 63.84925 -322.172838)
		(width 0.14732)
		(layer "In11.Cu")
		(net "UPI_CPU1_CPU0_P2P2_DP<7>")
	)
	(segment
		(start 353.393756 -276.21865)
		(end 353.384104 -276.213062)
		(width 0.0889)
		(layer "In11.Cu")
		(net "UPI_CPU1_CPU0_P2P2_DP<7>")
	)
	(segment
		(start 309.435246 -337.06435)
		(end 317.556388 -328.943208)
		(width 0.14732)
		(layer "In11.Cu")
		(net "UPI_CPU1_CPU0_P2P2_DP<7>")
	)
	(segment
		(start 62.032388 -324.688708)
		(end 60.679584 -325.249032)
		(width 0.14732)
		(layer "In11.Cu")
		(net "UPI_CPU1_CPU0_P2P2_DP<7>")
	)
	(segment
		(start 60.05068 -326.212962)
		(end 60.05068 -328.9173)
		(width 0.14732)
		(layer "In11.Cu")
		(net "UPI_CPU1_CPU0_P2P2_DP<7>")
	)
	(segment
		(start 347.602048 -292.001194)
		(end 348.977712 -290.627054)
		(width 0.0889)
		(layer "In11.Cu")
		(net "UPI_CPU1_CPU0_P2P2_DP<7>")
	)
	(segment
		(start 89.65438 -290.813998)
		(end 89.55532 -290.913058)
		(width 0.0889)
		(layer "In11.Cu")
		(net "UPI_CPU1_CPU0_P2P2_DP<7>")
	)
	(segment
		(start 347.644212 -292.389306)
		(end 347.644212 -292.367208)
		(width 0.0889)
		(layer "In11.Cu")
		(net "UPI_CPU1_CPU0_P2P2_DP<7>")
	)
	(segment
		(start 349.63354 -286.965644)
		(end 349.635064 -286.964882)
		(width 0.0889)
		(layer "In11.Cu")
		(net "UPI_CPU1_CPU0_P2P2_DP<7>")
	)
	(segment
		(start 60.679584 -325.249032)
		(end 60.287408 -325.641208)
		(width 0.14732)
		(layer "In11.Cu")
		(net "UPI_CPU1_CPU0_P2P2_DP<7>")
	)
	(segment
		(start 350.62668 -276.243796)
		(end 350.605598 -276.165818)
		(width 0.0889)
		(layer "In11.Cu")
		(net "UPI_CPU1_CPU0_P2P2_DP<7>")
	)
	(segment
		(start 89.55532 -289.805618)
		(end 89.55532 -289.983418)
		(width 0.0889)
		(layer "In11.Cu")
		(net "UPI_CPU1_CPU0_P2P2_DP<7>")
	)
	(segment
		(start 90.039698 -288.917126)
		(end 90.039698 -289.086544)
		(width 0.0889)
		(layer "In11.Cu")
		(net "UPI_CPU1_CPU0_P2P2_DP<7>")
	)
	(segment
		(start 90.795348 -287.611566)
		(end 90.79357 -287.612582)
		(width 0.0889)
		(layer "In11.Cu")
		(net "UPI_CPU1_CPU0_P2P2_DP<7>")
	)
	(segment
		(start 351.797112 -283.229812)
		(end 351.797112 -283.201364)
		(width 0.0889)
		(layer "In11.Cu")
		(net "UPI_CPU1_CPU0_P2P2_DP<7>")
	)
	(segment
		(start 352.454464 -281.102562)
		(end 352.449892 -281.100022)
		(width 0.0889)
		(layer "In11.Cu")
		(net "UPI_CPU1_CPU0_P2P2_DP<7>")
	)
	(segment
		(start 347.644212 -294.842946)
		(end 347.644212 -292.389306)
		(width 0.14732)
		(layer "In11.Cu")
		(net "UPI_CPU1_CPU0_P2P2_DP<7>")
	)
	(segment
		(start 89.55532 -291.466778)
		(end 89.55532 -291.644578)
		(width 0.0889)
		(layer "In11.Cu")
		(net "UPI_CPU1_CPU0_P2P2_DP<7>")
	)
	(segment
		(start 89.55532 -289.983418)
		(end 89.65438 -290.082478)
		(width 0.0889)
		(layer "In11.Cu")
		(net "UPI_CPU1_CPU0_P2P2_DP<7>")
	)
	(segment
		(start 351.327212 -284.043628)
		(end 351.327212 -284.033722)
		(width 0.0889)
		(layer "In11.Cu")
		(net "UPI_CPU1_CPU0_P2P2_DP<7>")
	)
	(segment
		(start 350.857566 -284.847538)
		(end 350.857566 -284.838902)
		(width 0.0889)
		(layer "In11.Cu")
		(net "UPI_CPU1_CPU0_P2P2_DP<7>")
	)
	(segment
		(start 317.556388 -328.943208)
		(end 318.686688 -326.214232)
		(width 0.14732)
		(layer "In11.Cu")
		(net "UPI_CPU1_CPU0_P2P2_DP<7>")
	)
	(segment
		(start 350.605598 -276.165818)
		(end 350.762062 -275.8948)
		(width 0.0889)
		(layer "In11.Cu")
		(net "UPI_CPU1_CPU0_P2P2_DP<7>")
	)
	(segment
		(start 353.394518 -276.219158)
		(end 353.393756 -276.21865)
		(width 0.0889)
		(layer "In11.Cu")
		(net "UPI_CPU1_CPU0_P2P2_DP<7>")
	)
	(segment
		(start 352.455226 -281.10307)
		(end 352.454464 -281.102562)
		(width 0.0889)
		(layer "In11.Cu")
		(net "UPI_CPU1_CPU0_P2P2_DP<7>")
	)
	(segment
		(start 91.270582 -286.794702)
		(end 91.262708 -286.799274)
		(width 0.0889)
		(layer "In11.Cu")
		(net "UPI_CPU1_CPU0_P2P2_DP<7>")
	)
	(segment
		(start 352.933762 -278.666448)
		(end 352.924364 -278.66086)
		(width 0.0889)
		(layer "In11.Cu")
		(net "UPI_CPU1_CPU0_P2P2_DP<7>")
	)
	(segment
		(start 90.796872 -287.61055)
		(end 90.795348 -287.611566)
		(width 0.0889)
		(layer "In11.Cu")
		(net "UPI_CPU1_CPU0_P2P2_DP<7>")
	)
	(segment
		(start 353.39274 -277.198836)
		(end 353.394264 -277.198074)
		(width 0.0889)
		(layer "In11.Cu")
		(net "UPI_CPU1_CPU0_P2P2_DP<7>")
	)
	(segment
		(start 286.489394 -337.06435)
		(end 309.435246 -337.06435)
		(width 0.14732)
		(layer "In11.Cu")
		(net "UPI_CPU1_CPU0_P2P2_DP<7>")
	)
	(segment
		(start 90.79357 -287.612582)
		(end 90.78595 -287.617154)
		(width 0.0889)
		(layer "In11.Cu")
		(net "UPI_CPU1_CPU0_P2P2_DP<7>")
	)
	(segment
		(start 89.612216 -292.10254)
		(end 86.714584 -295.000172)
		(width 0.14732)
		(layer "In11.Cu")
		(net "UPI_CPU1_CPU0_P2P2_DP<7>")
	)
	(segment
		(start 91.262708 -286.799274)
		(end 91.261692 -286.799782)
		(width 0.0889)
		(layer "In11.Cu")
		(net "UPI_CPU1_CPU0_P2P2_DP<7>")
	)
	(segment
		(start 92.954094 -281.59202)
		(end 92.79763 -281.321002)
		(width 0.0889)
		(layer "In11.Cu")
		(net "UPI_CPU1_CPU0_P2P2_DP<7>")
	)
	(segment
		(start 338.392008 -306.508912)
		(end 342.311736 -304.88509)
		(width 0.14732)
		(layer "In11.Cu")
		(net "UPI_CPU1_CPU0_P2P2_DP<7>")
	)
	(segment
		(start 61.196474 -331.061568)
		(end 62.274958 -335.364836)
		(width 0.14732)
		(layer "In11.Cu")
		(net "UPI_CPU1_CPU0_P2P2_DP<7>")
	)
	(segment
		(start 91.261692 -286.151066)
		(end 91.270582 -286.156146)
		(width 0.0889)
		(layer "In11.Cu")
		(net "UPI_CPU1_CPU0_P2P2_DP<7>")
	)
	(segment
		(start 91.449144 -284.837632)
		(end 91.449144 -284.847538)
		(width 0.0889)
		(layer "In11.Cu")
		(net "UPI_CPU1_CPU0_P2P2_DP<7>")
	)
	(segment
		(start 89.65438 -291.367718)
		(end 89.55532 -291.466778)
		(width 0.0889)
		(layer "In11.Cu")
		(net "UPI_CPU1_CPU0_P2P2_DP<7>")
	)
	(segment
		(start 65.68567 -319.538858)
		(end 64.926972 -321.370198)
		(width 0.14732)
		(layer "In11.Cu")
		(net "UPI_CPU1_CPU0_P2P2_DP<7>")
	)
	(segment
		(start 92.210382 -283.539184)
		(end 92.201492 -283.544264)
		(width 0.0889)
		(layer "In11.Cu")
		(net "UPI_CPU1_CPU0_P2P2_DP<7>")
	)
	(segment
		(start 350.57334 -285.337758)
		(end 350.574864 -285.336996)
		(width 0.0889)
		(layer "In11.Cu")
		(net "UPI_CPU1_CPU0_P2P2_DP<7>")
	)
	(segment
		(start 351.514664 -276.219158)
		(end 351.499932 -276.210522)
		(width 0.0889)
		(layer "In11.Cu")
		(net "UPI_CPU1_CPU0_P2P2_DP<7>")
	)
	(segment
		(start 352.927412 -279.638252)
		(end 352.928936 -279.637236)
		(width 0.0889)
		(layer "In11.Cu")
		(net "UPI_CPU1_CPU0_P2P2_DP<7>")
	)
	(segment
		(start 89.612216 -291.921438)
		(end 89.612216 -291.943536)
		(width 0.0889)
		(layer "In11.Cu")
		(net "UPI_CPU1_CPU0_P2P2_DP<7>")
	)
	(segment
		(start 352.445574 -280.458926)
		(end 352.454464 -280.453846)
		(width 0.0889)
		(layer "In11.Cu")
		(net "UPI_CPU1_CPU0_P2P2_DP<7>")
	)
	(segment
		(start 348.508066 -289.078416)
		(end 348.508066 -288.917126)
		(width 0.0889)
		(layer "In11.Cu")
		(net "UPI_CPU1_CPU0_P2P2_DP<7>")
	)
	(segment
		(start 352.737166 -279.978358)
		(end 352.737166 -279.964134)
		(width 0.0889)
		(layer "In11.Cu")
		(net "UPI_CPU1_CPU0_P2P2_DP<7>")
	)
	(segment
		(start 89.65438 -291.189918)
		(end 89.65438 -291.367718)
		(width 0.0889)
		(layer "In11.Cu")
		(net "UPI_CPU1_CPU0_P2P2_DP<7>")
	)
	(segment
		(start 352.737166 -278.345138)
		(end 352.737166 -278.327866)
		(width 0.0889)
		(layer "In11.Cu")
		(net "UPI_CPU1_CPU0_P2P2_DP<7>")
	)
	(segment
		(start 89.65438 -291.743638)
		(end 89.65438 -291.879274)
		(width 0.0889)
		(layer "In11.Cu")
		(net "UPI_CPU1_CPU0_P2P2_DP<7>")
	)
	(segment
		(start 89.65438 -289.706558)
		(end 89.55532 -289.805618)
		(width 0.0889)
		(layer "In11.Cu")
		(net "UPI_CPU1_CPU0_P2P2_DP<7>")
	)
	(segment
		(start 63.84925 -322.172838)
		(end 63.20028 -322.821808)
		(width 0.14732)
		(layer "In11.Cu")
		(net "UPI_CPU1_CPU0_P2P2_DP<7>")
	)
	(segment
		(start 282.35148 -338.778342)
		(end 286.489394 -337.06435)
		(width 0.14732)
		(layer "In11.Cu")
		(net "UPI_CPU1_CPU0_P2P2_DP<7>")
	)
	(segment
		(start 349.626174 -286.969962)
		(end 349.63354 -286.965644)
		(width 0.0889)
		(layer "In11.Cu")
		(net "UPI_CPU1_CPU0_P2P2_DP<7>")
	)
	(segment
		(start 67.735196 -317.489332)
		(end 65.68567 -319.538858)
		(width 0.14732)
		(layer "In11.Cu")
		(net "UPI_CPU1_CPU0_P2P2_DP<7>")
	)
	(segment
		(start 262.805926 -378.437648)
		(end 273.62404 -367.619534)
		(width 0.14732)
		(layer "In11.Cu")
		(net "UPI_CPU1_CPU0_P2P2_DP<7>")
	)
	(segment
		(start 348.977712 -290.627054)
		(end 348.977712 -289.60953)
		(width 0.0889)
		(layer "In11.Cu")
		(net "UPI_CPU1_CPU0_P2P2_DP<7>")
	)
	(segment
		(start 349.156528 -287.783778)
		(end 349.165418 -287.778698)
		(width 0.0889)
		(layer "In11.Cu")
		(net "UPI_CPU1_CPU0_P2P2_DP<7>")
	)
	(segment
		(start 60.05068 -328.9173)
		(end 61.196474 -331.061568)
		(width 0.14732)
		(layer "In11.Cu")
		(net "UPI_CPU1_CPU0_P2P2_DP<7>")
	)
	(segment
		(start 93.150182 -281.911298)
		(end 93.141292 -281.916378)
		(width 0.0889)
		(layer "In11.Cu")
		(net "UPI_CPU1_CPU0_P2P2_DP<7>")
	)
	(segment
		(start 342.311736 -304.88509)
		(end 345.744546 -301.45228)
		(width 0.14732)
		(layer "In11.Cu")
		(net "UPI_CPU1_CPU0_P2P2_DP<7>")
	)
	(segment
		(start 91.270582 -285.166816)
		(end 91.261692 -285.171896)
		(width 0.0889)
		(layer "In11.Cu")
		(net "UPI_CPU1_CPU0_P2P2_DP<7>")
	)
	(segment
		(start 350.387412 -285.679896)
		(end 350.387412 -285.661354)
		(width 0.0889)
		(layer "In11.Cu")
		(net "UPI_CPU1_CPU0_P2P2_DP<7>")
	)
	(segment
		(start 352.46056 -281.106118)
		(end 352.455226 -281.10307)
		(width 0.0889)
		(layer "In11.Cu")
		(net "UPI_CPU1_CPU0_P2P2_DP<7>")
	)
	(segment
		(start 62.274958 -355.04882)
		(end 67.458336 -367.564162)
		(width 0.14732)
		(layer "In11.Cu")
		(net "UPI_CPU1_CPU0_P2P2_DP<7>")
	)
	(segment
		(start 89.65438 -290.260278)
		(end 89.55532 -290.359338)
		(width 0.0889)
		(layer "In11.Cu")
		(net "UPI_CPU1_CPU0_P2P2_DP<7>")
	)
	(segment
		(start 352.928936 -279.637236)
		(end 352.930714 -279.63622)
		(width 0.0889)
		(layer "In11.Cu")
		(net "UPI_CPU1_CPU0_P2P2_DP<7>")
	)
	(segment
		(start 60.287408 -325.641208)
		(end 60.05068 -326.212962)
		(width 0.14732)
		(layer "In11.Cu")
		(net "UPI_CPU1_CPU0_P2P2_DP<7>")
	)
	(segment
		(start 62.70625 -324.014846)
		(end 62.032388 -324.688708)
		(width 0.14732)
		(layer "In11.Cu")
		(net "UPI_CPU1_CPU0_P2P2_DP<7>")
	)
	(segment
		(start 86.714584 -295.000172)
		(end 84.536788 -300.258734)
		(width 0.14732)
		(layer "In11.Cu")
		(net "UPI_CPU1_CPU0_P2P2_DP<7>")
	)
	(segment
		(start 349.917766 -286.475424)
		(end 349.917766 -286.466788)
		(width 0.0889)
		(layer "In11.Cu")
		(net "UPI_CPU1_CPU0_P2P2_DP<7>")
	)
	(segment
		(start 347.602048 -292.325044)
		(end 347.602048 -292.001194)
		(width 0.0889)
		(layer "In11.Cu")
		(net "UPI_CPU1_CPU0_P2P2_DP<7>")
	)
	(segment
		(start 352.915728 -279.644856)
		(end 352.927412 -279.638252)
		(width 0.0889)
		(layer "In11.Cu")
		(net "UPI_CPU1_CPU0_P2P2_DP<7>")
	)
	(segment
		(start 353.385374 -277.203154)
		(end 353.39274 -277.198836)
		(width 0.0889)
		(layer "In11.Cu")
		(net "UPI_CPU1_CPU0_P2P2_DP<7>")
	)
	(segment
		(start 89.55532 -290.359338)
		(end 89.55532 -290.537138)
		(width 0.0889)
		(layer "In11.Cu")
		(net "UPI_CPU1_CPU0_P2P2_DP<7>")
	)
	(segment
		(start 351.327466 -282.414472)
		(end 351.327466 -282.3972)
		(width 0.0889)
		(layer "In11.Cu")
		(net "UPI_CPU1_CPU0_P2P2_DP<7>")
	)
	(segment
		(start 348.686628 -288.597848)
		(end 348.695518 -288.592768)
		(width 0.0889)
		(layer "In11.Cu")
		(net "UPI_CPU1_CPU0_P2P2_DP<7>")
	)
	(segment
		(start 318.686688 -326.214232)
		(end 338.392008 -306.508912)
		(width 0.14732)
		(layer "In11.Cu")
		(net "UPI_CPU1_CPU0_P2P2_DP<7>")
	)
	(segment
		(start 72.944228 -373.050054)
		(end 95.594932 -382.432052)
		(width 0.14732)
		(layer "In11.Cu")
		(net "UPI_CPU1_CPU0_P2P2_DP<7>")
	)
	(segment
		(start 89.65438 -289.471862)
		(end 89.65438 -289.706558)
		(width 0.0889)
		(layer "In11.Cu")
		(net "UPI_CPU1_CPU0_P2P2_DP<7>")
	)
	(segment
		(start 350.574864 -285.336996)
		(end 350.58096 -285.33344)
		(width 0.0889)
		(layer "In11.Cu")
		(net "UPI_CPU1_CPU0_P2P2_DP<7>")
	)
	(segment
		(start 92.680536 -282.725114)
		(end 92.671646 -282.730194)
		(width 0.0889)
		(layer "In11.Cu")
		(net "UPI_CPU1_CPU0_P2P2_DP<7>")
	)
	(segment
		(start 95.594932 -382.432052)
		(end 126.42215 -387.005068)
		(width 0.14732)
		(layer "In11.Cu")
		(net "UPI_CPU1_CPU0_P2P2_DP<7>")
	)
	(segment
		(start 345.744546 -301.45228)
		(end 346.77731 -299.043598)
		(width 0.14732)
		(layer "In11.Cu")
		(net "UPI_CPU1_CPU0_P2P2_DP<7>")
	)
	(segment
		(start 63.20028 -322.821808)
		(end 62.70625 -324.014846)
		(width 0.14732)
		(layer "In11.Cu")
		(net "UPI_CPU1_CPU0_P2P2_DP<7>")
	)
	(segment
		(start 352.455226 -282.08097)
		(end 352.46056 -282.077922)
		(width 0.0889)
		(layer "In11.Cu")
		(net "UPI_CPU1_CPU0_P2P2_DP<7>")
	)
	(segment
		(start 353.394264 -277.198074)
		(end 353.40036 -277.194518)
		(width 0.0889)
		(layer "In11.Cu")
		(net "UPI_CPU1_CPU0_P2P2_DP<7>")
	)
	(segment
		(start 89.55532 -290.913058)
		(end 89.55532 -291.090858)
		(width 0.0889)
		(layer "In11.Cu")
		(net "UPI_CPU1_CPU0_P2P2_DP<7>")
	)
	(segment
		(start 347.644212 -292.367208)
		(end 347.602048 -292.325044)
		(width 0.0889)
		(layer "In11.Cu")
		(net "UPI_CPU1_CPU0_P2P2_DP<7>")
	)
	(segment
		(start 89.612216 -291.943536)
		(end 89.612216 -292.10254)
		(width 0.14732)
		(layer "In11.Cu")
		(net "UPI_CPU1_CPU0_P2P2_DP<7>")
	)
	(segment
		(start 67.735196 -317.060326)
		(end 67.735196 -317.489332)
		(width 0.14732)
		(layer "In11.Cu")
		(net "UPI_CPU1_CPU0_P2P2_DP<7>")
	)
	(segment
		(start 353.676966 -276.708616)
		(end 353.676966 -276.69871)
		(width 0.0889)
		(layer "In11.Cu")
		(net "UPI_CPU1_CPU0_P2P2_DP<7>")
	)
	(segment
		(start 349.447612 -287.304734)
		(end 349.447612 -287.28924)
		(width 0.0889)
		(layer "In11.Cu")
		(net "UPI_CPU1_CPU0_P2P2_DP<7>")
	)
	(segment
		(start 90.039698 -289.086544)
		(end 89.65438 -289.471862)
		(width 0.0889)
		(layer "In11.Cu")
		(net "UPI_CPU1_CPU0_P2P2_DP<7>")
	)
	(segment
		(start 352.454464 -276.219158)
		(end 352.439732 -276.210522)
		(width 0.0889)
		(layer "In11.Cu")
		(net "UPI_CPU1_CPU0_P2P2_DP<7>")
	)
	(segment
		(start 90.299794 -288.440876)
		(end 90.300048 -288.44113)
		(width 0.0889)
		(layer "In11.Cu")
		(net "UPI_CPU1_CPU0_P2P2_DP<7>")
	)
	(segment
		(start 89.65438 -290.636198)
		(end 89.65438 -290.813998)
		(width 0.0889)
		(layer "In11.Cu")
		(net "UPI_CPU1_CPU0_P2P2_DP<7>")
	)
	(segment
		(start 89.55532 -291.644578)
		(end 89.65438 -291.743638)
		(width 0.0889)
		(layer "In11.Cu")
		(net "UPI_CPU1_CPU0_P2P2_DP<7>")
	)
	(segment
		(start 353.206812 -277.540974)
		(end 353.206812 -277.522432)
		(width 0.0889)
		(layer "In11.Cu")
		(net "UPI_CPU1_CPU0_P2P2_DP<7>")
	)
	(segment
		(start 273.62404 -367.619534)
		(end 273.62404 -347.505782)
		(width 0.14732)
		(layer "In11.Cu")
		(net "UPI_CPU1_CPU0_P2P2_DP<7>")
	)
	(segment
		(start 89.65438 -291.879274)
		(end 89.612216 -291.921438)
		(width 0.0889)
		(layer "In11.Cu")
		(net "UPI_CPU1_CPU0_P2P2_DP<7>")
	)
	(segment
		(start 352.454464 -282.081478)
		(end 352.455226 -282.08097)
		(width 0.0889)
		(layer "In11.Cu")
		(net "UPI_CPU1_CPU0_P2P2_DP<7>")
	)
	(segment
		(start 90.330782 -288.422334)
		(end 90.321892 -288.427414)
		(width 0.0889)
		(layer "In11.Cu")
		(net "UPI_CPU1_CPU0_P2P2_DP<7>")
	)
	(segment
		(start 67.458336 -367.564162)
		(end 72.944228 -373.050054)
		(width 0.14732)
		(layer "In11.Cu")
		(net "UPI_CPU1_CPU0_P2P2_DP<7>")
	)
	(segment
		(start 352.936556 -278.667972)
		(end 352.933762 -278.666448)
		(width 0.0889)
		(layer "In11.Cu")
		(net "UPI_CPU1_CPU0_P2P2_DP<7>")
	)
	(segment
		(start 161.849054 -387.005068)
		(end 262.805926 -378.437648)
		(width 0.14732)
		(layer "In11.Cu")
		(net "UPI_CPU1_CPU0_P2P2_DP<7>")
	)
	(segment
		(start 351.505774 -283.714444)
		(end 351.514664 -283.709364)
		(width 0.0889)
		(layer "In11.Cu")
		(net "UPI_CPU1_CPU0_P2P2_DP<7>")
	)
	(segment
		(start 91.919044 -284.023816)
		(end 91.919044 -284.033722)
		(width 0.0889)
		(layer "In11.Cu")
		(net "UPI_CPU1_CPU0_P2P2_DP<7>")
	)
	(segment
		(start 90.800936 -287.608518)
		(end 90.800936 -287.608264)
		(width 0.0889)
		(layer "In11.Cu")
		(net "UPI_CPU1_CPU0_P2P2_DP<7>")
	)
	(segment
		(start 89.55532 -291.090858)
		(end 89.65438 -291.189918)
		(width 0.0889)
		(layer "In11.Cu")
		(net "UPI_CPU1_CPU0_P2P2_DP<7>")
	)
	(segment
		(start 91.740482 -284.353)
		(end 91.731592 -284.35808)
		(width 0.0889)
		(layer "In11.Cu")
		(net "UPI_CPU1_CPU0_P2P2_DP<7>")
	)
	(segment
		(start 89.55532 -290.537138)
		(end 89.65438 -290.636198)
		(width 0.0889)
		(layer "In11.Cu")
		(net "UPI_CPU1_CPU0_P2P2_DP<7>")
	)
	(segment
		(start 90.979498 -285.64586)
		(end 90.979498 -285.683452)
		(width 0.0889)
		(layer "In11.Cu")
		(net "UPI_CPU1_CPU0_P2P2_DP<7>")
	)
	(segment
		(start 346.77731 -299.043598)
		(end 347.638624 -294.848534)
		(width 0.14732)
		(layer "In11.Cu")
		(net "UPI_CPU1_CPU0_P2P2_DP<7>")
	)
	(segment
		(start 89.65438 -290.082478)
		(end 89.65438 -290.260278)
		(width 0.0889)
		(layer "In11.Cu")
		(net "UPI_CPU1_CPU0_P2P2_DP<7>")
	)
	(segment
		(start 352.439732 -282.090114)
		(end 352.454464 -282.081478)
		(width 0.0889)
		(layer "In11.Cu")
		(net "UPI_CPU1_CPU0_P2P2_DP<7>")
	)
	(segment
		(start 126.42215 -387.005068)
		(end 161.849054 -387.005068)
		(width 0.14732)
		(layer "In11.Cu")
		(net "UPI_CPU1_CPU0_P2P2_DP<7>")
	)
	(arc
		(start 91.261692 -285.171896)
		(mid 91.058869 -285.372127)
		(end 90.979498 -285.64586)
		(width 0.0889)
		(layer "In11.Cu")
		(net "UPI_CPU1_CPU0_P2P2_DP<7>")
	)
	(arc
		(start 348.977966 -288.103056)
		(mid 349.025645 -287.920156)
		(end 349.156528 -287.783778)
		(width 0.0889)
		(layer "In11.Cu")
		(net "UPI_CPU1_CPU0_P2P2_DP<7>")
	)
	(arc
		(start 351.327212 -284.033722)
		(mid 351.374891 -283.850822)
		(end 351.505774 -283.714444)
		(width 0.0889)
		(layer "In11.Cu")
		(net "UPI_CPU1_CPU0_P2P2_DP<7>")
	)
	(arc
		(start 353.206812 -277.522432)
		(mid 353.254491 -277.339532)
		(end 353.385374 -277.203154)
		(width 0.0889)
		(layer "In11.Cu")
		(net "UPI_CPU1_CPU0_P2P2_DP<7>")
	)
	(arc
		(start 352.82886 -276.219158)
		(mid 352.641662 -276.269301)
		(end 352.454464 -276.219158)
		(width 0.0889)
		(layer "In11.Cu")
		(net "UPI_CPU1_CPU0_P2P2_DP<7>")
	)
	(arc
		(start 352.454464 -280.453846)
		(mid 352.657945 -280.253042)
		(end 352.737166 -279.978358)
		(width 0.0889)
		(layer "In11.Cu")
		(net "UPI_CPU1_CPU0_P2P2_DP<7>")
	)
	(arc
		(start 352.737166 -278.327866)
		(mid 352.789436 -278.145501)
		(end 352.924364 -278.012144)
		(width 0.0889)
		(layer "In11.Cu")
		(net "UPI_CPU1_CPU0_P2P2_DP<7>")
	)
	(arc
		(start 348.692216 -289.277806)
		(mid 348.583069 -289.193878)
		(end 348.508066 -289.078416)
		(width 0.0889)
		(layer "In11.Cu")
		(net "UPI_CPU1_CPU0_P2P2_DP<7>")
	)
	(arc
		(start 348.695518 -288.592768)
		(mid 348.897804 -288.393787)
		(end 348.977966 -288.121598)
		(width 0.0889)
		(layer "In11.Cu")
		(net "UPI_CPU1_CPU0_P2P2_DP<7>")
	)
	(arc
		(start 350.94926 -276.219158)
		(mid 350.790772 -276.268091)
		(end 350.62668 -276.243796)
		(width 0.0889)
		(layer "In11.Cu")
		(net "UPI_CPU1_CPU0_P2P2_DP<7>")
	)
	(arc
		(start 349.64116 -286.961326)
		(mid 349.843747 -286.754975)
		(end 349.917766 -286.475424)
		(width 0.0889)
		(layer "In11.Cu")
		(net "UPI_CPU1_CPU0_P2P2_DP<7>")
	)
	(arc
		(start 92.818712 -281.243024)
		(mid 92.982808 -281.218677)
		(end 93.141292 -281.267662)
		(width 0.0889)
		(layer "In11.Cu")
		(net "UPI_CPU1_CPU0_P2P2_DP<7>")
	)
	(arc
		(start 349.917766 -286.466788)
		(mid 349.970036 -286.284423)
		(end 350.104964 -286.151066)
		(width 0.0889)
		(layer "In11.Cu")
		(net "UPI_CPU1_CPU0_P2P2_DP<7>")
	)
	(arc
		(start 353.676966 -276.69871)
		(mid 353.598855 -276.421761)
		(end 353.394518 -276.219158)
		(width 0.0889)
		(layer "In11.Cu")
		(net "UPI_CPU1_CPU0_P2P2_DP<7>")
	)
	(arc
		(start 92.859098 -282.405836)
		(mid 92.811419 -282.588736)
		(end 92.680536 -282.725114)
		(width 0.0889)
		(layer "In11.Cu")
		(net "UPI_CPU1_CPU0_P2P2_DP<7>")
	)
	(arc
		(start 351.88906 -276.219158)
		(mid 351.701862 -276.269301)
		(end 351.514664 -276.219158)
		(width 0.0889)
		(layer "In11.Cu")
		(net "UPI_CPU1_CPU0_P2P2_DP<7>")
	)
	(arc
		(start 352.46056 -282.077922)
		(mid 352.737134 -281.59202)
		(end 352.46056 -281.106118)
		(width 0.0889)
		(layer "In11.Cu")
		(net "UPI_CPU1_CPU0_P2P2_DP<7>")
	)
	(arc
		(start 353.207066 -279.150318)
		(mid 353.134831 -278.873794)
		(end 352.936556 -278.667972)
		(width 0.0889)
		(layer "In11.Cu")
		(net "UPI_CPU1_CPU0_P2P2_DP<7>")
	)
	(arc
		(start 92.388944 -283.219906)
		(mid 92.341265 -283.402806)
		(end 92.210382 -283.539184)
		(width 0.0889)
		(layer "In11.Cu")
		(net "UPI_CPU1_CPU0_P2P2_DP<7>")
	)
	(arc
		(start 91.449144 -284.847538)
		(mid 91.401465 -285.030438)
		(end 91.270582 -285.166816)
		(width 0.0889)
		(layer "In11.Cu")
		(net "UPI_CPU1_CPU0_P2P2_DP<7>")
	)
	(arc
		(start 351.88906 -282.081478)
		(mid 352.163259 -282.157313)
		(end 352.439732 -282.090114)
		(width 0.0889)
		(layer "In11.Cu")
		(net "UPI_CPU1_CPU0_P2P2_DP<7>")
	)
	(arc
		(start 351.797112 -283.201364)
		(mid 351.71695 -282.929175)
		(end 351.514664 -282.730194)
		(width 0.0889)
		(layer "In11.Cu")
		(net "UPI_CPU1_CPU0_P2P2_DP<7>")
	)
	(arc
		(start 90.50909 -288.117788)
		(mid 90.458036 -288.292368)
		(end 90.330782 -288.422334)
		(width 0.0889)
		(layer "In11.Cu")
		(net "UPI_CPU1_CPU0_P2P2_DP<7>")
	)
	(arc
		(start 91.731592 -284.35808)
		(mid 91.527257 -284.560685)
		(end 91.449144 -284.837632)
		(width 0.0889)
		(layer "In11.Cu")
		(net "UPI_CPU1_CPU0_P2P2_DP<7>")
	)
	(arc
		(start 93.141292 -281.916378)
		(mid 92.938469 -282.116609)
		(end 92.859098 -282.390342)
		(width 0.0889)
		(layer "In11.Cu")
		(net "UPI_CPU1_CPU0_P2P2_DP<7>")
	)
	(arc
		(start 91.261692 -286.799782)
		(mid 91.058869 -287.000013)
		(end 90.979498 -287.273746)
		(width 0.0889)
		(layer "In11.Cu")
		(net "UPI_CPU1_CPU0_P2P2_DP<7>")
	)
	(arc
		(start 93.328744 -281.585416)
		(mid 93.328838 -281.593798)
		(end 93.328744 -281.60218)
		(width 0.0889)
		(layer "In11.Cu")
		(net "UPI_CPU1_CPU0_P2P2_DP<7>")
	)
	(arc
		(start 351.514664 -282.081478)
		(mid 351.701862 -282.031335)
		(end 351.88906 -282.081478)
		(width 0.0889)
		(layer "In11.Cu")
		(net "UPI_CPU1_CPU0_P2P2_DP<7>")
	)
	(arc
		(start 353.384104 -276.213062)
		(mid 353.105672 -276.143216)
		(end 352.82886 -276.219158)
		(width 0.0889)
		(layer "In11.Cu")
		(net "UPI_CPU1_CPU0_P2P2_DP<7>")
	)
	(arc
		(start 351.499932 -276.210522)
		(mid 351.223457 -276.143202)
		(end 350.94926 -276.219158)
		(width 0.0889)
		(layer "In11.Cu")
		(net "UPI_CPU1_CPU0_P2P2_DP<7>")
	)
	(arc
		(start 90.300048 -288.44113)
		(mid 90.10907 -288.645865)
		(end 90.039698 -288.917126)
		(width 0.0889)
		(layer "In11.Cu")
		(net "UPI_CPU1_CPU0_P2P2_DP<7>")
	)
	(arc
		(start 348.508066 -288.917126)
		(mid 348.555745 -288.734226)
		(end 348.686628 -288.597848)
		(width 0.0889)
		(layer "In11.Cu")
		(net "UPI_CPU1_CPU0_P2P2_DP<7>")
	)
	(arc
		(start 352.924364 -278.012144)
		(mid 353.12665 -277.813163)
		(end 353.206812 -277.540974)
		(width 0.0889)
		(layer "In11.Cu")
		(net "UPI_CPU1_CPU0_P2P2_DP<7>")
	)
	(arc
		(start 352.445574 -281.097482)
		(mid 352.266977 -280.778204)
		(end 352.445574 -280.458926)
		(width 0.0889)
		(layer "In11.Cu")
		(net "UPI_CPU1_CPU0_P2P2_DP<7>")
	)
	(arc
		(start 348.977712 -289.60953)
		(mid 348.866374 -289.41663)
		(end 348.692216 -289.277806)
		(width 0.0889)
		(layer "In11.Cu")
		(net "UPI_CPU1_CPU0_P2P2_DP<7>")
	)
	(arc
		(start 91.270582 -286.156146)
		(mid 91.4493 -286.475424)
		(end 91.270582 -286.794702)
		(width 0.0889)
		(layer "In11.Cu")
		(net "UPI_CPU1_CPU0_P2P2_DP<7>")
	)
	(arc
		(start 351.514664 -283.709364)
		(mid 351.718999 -283.506759)
		(end 351.797112 -283.229812)
		(width 0.0889)
		(layer "In11.Cu")
		(net "UPI_CPU1_CPU0_P2P2_DP<7>")
	)
	(arc
		(start 349.447612 -287.28924)
		(mid 349.495291 -287.10634)
		(end 349.626174 -286.969962)
		(width 0.0889)
		(layer "In11.Cu")
		(net "UPI_CPU1_CPU0_P2P2_DP<7>")
	)
	(arc
		(start 351.327466 -282.3972)
		(mid 351.379736 -282.214835)
		(end 351.514664 -282.081478)
		(width 0.0889)
		(layer "In11.Cu")
		(net "UPI_CPU1_CPU0_P2P2_DP<7>")
	)
	(arc
		(start 350.104964 -286.151066)
		(mid 350.30725 -285.952085)
		(end 350.387412 -285.679896)
		(width 0.0889)
		(layer "In11.Cu")
		(net "UPI_CPU1_CPU0_P2P2_DP<7>")
	)
	(arc
		(start 92.671646 -282.730194)
		(mid 92.468165 -282.930998)
		(end 92.388944 -283.205682)
		(width 0.0889)
		(layer "In11.Cu")
		(net "UPI_CPU1_CPU0_P2P2_DP<7>")
	)
	(arc
		(start 90.979498 -285.683452)
		(mid 91.060409 -285.95358)
		(end 91.261692 -286.151066)
		(width 0.0889)
		(layer "In11.Cu")
		(net "UPI_CPU1_CPU0_P2P2_DP<7>")
	)
	(arc
		(start 90.321892 -288.427414)
		(mid 90.310765 -288.434017)
		(end 90.299794 -288.440876)
		(width 0.0889)
		(layer "In11.Cu")
		(net "UPI_CPU1_CPU0_P2P2_DP<7>")
	)
	(arc
		(start 90.509344 -288.103056)
		(mid 90.509292 -288.110423)
		(end 90.50909 -288.117788)
		(width 0.0889)
		(layer "In11.Cu")
		(net "UPI_CPU1_CPU0_P2P2_DP<7>")
	)
	(arc
		(start 90.979498 -287.28924)
		(mid 90.931819 -287.47214)
		(end 90.800936 -287.608518)
		(width 0.0889)
		(layer "In11.Cu")
		(net "UPI_CPU1_CPU0_P2P2_DP<7>")
	)
	(arc
		(start 93.150182 -281.272742)
		(mid 93.279471 -281.406228)
		(end 93.328744 -281.585416)
		(width 0.0889)
		(layer "In11.Cu")
		(net "UPI_CPU1_CPU0_P2P2_DP<7>")
	)
	(arc
		(start 90.78595 -287.617154)
		(mid 90.583363 -287.823505)
		(end 90.509344 -288.103056)
		(width 0.0889)
		(layer "In11.Cu")
		(net "UPI_CPU1_CPU0_P2P2_DP<7>")
	)
	(arc
		(start 350.857566 -284.838902)
		(mid 350.909836 -284.656537)
		(end 351.044764 -284.52318)
		(width 0.0889)
		(layer "In11.Cu")
		(net "UPI_CPU1_CPU0_P2P2_DP<7>")
	)
	(arc
		(start 350.387412 -285.661354)
		(mid 350.435091 -285.478454)
		(end 350.565974 -285.342076)
		(width 0.0889)
		(layer "In11.Cu")
		(net "UPI_CPU1_CPU0_P2P2_DP<7>")
	)
	(arc
		(start 91.919044 -284.033722)
		(mid 91.871365 -284.216622)
		(end 91.740482 -284.353)
		(width 0.0889)
		(layer "In11.Cu")
		(net "UPI_CPU1_CPU0_P2P2_DP<7>")
	)
	(arc
		(start 352.930714 -279.63622)
		(mid 353.133127 -279.429807)
		(end 353.207066 -279.150318)
		(width 0.0889)
		(layer "In11.Cu")
		(net "UPI_CPU1_CPU0_P2P2_DP<7>")
	)
	(arc
		(start 93.328744 -281.60218)
		(mid 93.278675 -281.779405)
		(end 93.150182 -281.911298)
		(width 0.0889)
		(layer "In11.Cu")
		(net "UPI_CPU1_CPU0_P2P2_DP<7>")
	)
	(arc
		(start 92.201492 -283.544264)
		(mid 91.997157 -283.746869)
		(end 91.919044 -284.023816)
		(width 0.0889)
		(layer "In11.Cu")
		(net "UPI_CPU1_CPU0_P2P2_DP<7>")
	)
	(arc
		(start 351.514664 -282.730194)
		(mid 351.379731 -282.59684)
		(end 351.327466 -282.414472)
		(width 0.0889)
		(layer "In11.Cu")
		(net "UPI_CPU1_CPU0_P2P2_DP<7>")
	)
	(arc
		(start 350.58096 -285.33344)
		(mid 350.783547 -285.127089)
		(end 350.857566 -284.847538)
		(width 0.0889)
		(layer "In11.Cu")
		(net "UPI_CPU1_CPU0_P2P2_DP<7>")
	)
	(arc
		(start 351.044764 -284.52318)
		(mid 351.249099 -284.320575)
		(end 351.327212 -284.043628)
		(width 0.0889)
		(layer "In11.Cu")
		(net "UPI_CPU1_CPU0_P2P2_DP<7>")
	)
	(arc
		(start 352.924364 -278.66086)
		(mid 352.789431 -278.527506)
		(end 352.737166 -278.345138)
		(width 0.0889)
		(layer "In11.Cu")
		(net "UPI_CPU1_CPU0_P2P2_DP<7>")
	)
	(arc
		(start 349.165418 -287.778698)
		(mid 349.368241 -287.578467)
		(end 349.447612 -287.304734)
		(width 0.0889)
		(layer "In11.Cu")
		(net "UPI_CPU1_CPU0_P2P2_DP<7>")
	)
	(arc
		(start 353.40036 -277.194518)
		(mid 353.602947 -276.988167)
		(end 353.676966 -276.708616)
		(width 0.0889)
		(layer "In11.Cu")
		(net "UPI_CPU1_CPU0_P2P2_DP<7>")
	)
	(arc
		(start 352.737166 -279.964134)
		(mid 352.784845 -279.781234)
		(end 352.915728 -279.644856)
		(width 0.0889)
		(layer "In11.Cu")
		(net "UPI_CPU1_CPU0_P2P2_DP<7>")
	)
	(arc
		(start 352.439732 -276.210522)
		(mid 352.163257 -276.143202)
		(end 351.88906 -276.219158)
		(width 0.0889)
		(layer "In11.Cu")
		(net "UPI_CPU1_CPU0_P2P2_DP<7>")
	)
	(segment
		(start 354.521516 -276.986492)
		(end 354.521516 -277.521924)
		(width 0.13208)
		(layer "F.Cu")
		(net "UPI_CPU1_CPU0_P2P2_DP<6>")
	)
	(segment
		(start 354.521262 -277.522178)
		(end 354.521262 -277.522432)
		(width 0.13208)
		(layer "F.Cu")
		(net "UPI_CPU1_CPU0_P2P2_DP<6>")
	)
	(segment
		(start 354.521516 -277.521924)
		(end 354.521262 -277.522178)
		(width 0.13208)
		(layer "F.Cu")
		(net "UPI_CPU1_CPU0_P2P2_DP<6>")
	)
	(segment
		(start 91.074494 -282.683966)
		(end 91.074494 -283.219906)
		(width 0.13208)
		(layer "F.Cu")
		(net "UPI_CPU1_CPU0_P2P2_DP<6>")
	)
	(segment
		(start 83.939634 -299.506894)
		(end 66.750184 -316.699646)
		(width 0.14732)
		(layer "In11.Cu")
		(net "UPI_CPU1_CPU0_P2P2_DP<6>")
	)
	(segment
		(start 342.778334 -305.590194)
		(end 346.489528 -301.879254)
		(width 0.14732)
		(layer "In11.Cu")
		(net "UPI_CPU1_CPU0_P2P2_DP<6>")
	)
	(segment
		(start 353.863656 -278.660352)
		(end 353.861116 -278.658828)
		(width 0.0889)
		(layer "In11.Cu")
		(net "UPI_CPU1_CPU0_P2P2_DP<6>")
	)
	(segment
		(start 346.489528 -301.879254)
		(end 348.483936 -298.147232)
		(width 0.14732)
		(layer "In11.Cu")
		(net "UPI_CPU1_CPU0_P2P2_DP<6>")
	)
	(segment
		(start 282.825952 -339.478874)
		(end 286.649922 -337.89493)
		(width 0.14732)
		(layer "In11.Cu")
		(net "UPI_CPU1_CPU0_P2P2_DP<6>")
	)
	(segment
		(start 88.686894 -290.6903)
		(end 88.785954 -290.78936)
		(width 0.0889)
		(layer "In11.Cu")
		(net "UPI_CPU1_CPU0_P2P2_DP<6>")
	)
	(segment
		(start 349.792036 -291.044884)
		(end 349.792036 -290.904422)
		(width 0.0889)
		(layer "In11.Cu")
		(net "UPI_CPU1_CPU0_P2P2_DP<6>")
	)
	(segment
		(start 286.649922 -337.89493)
		(end 309.77713 -337.89493)
		(width 0.14732)
		(layer "In11.Cu")
		(net "UPI_CPU1_CPU0_P2P2_DP<6>")
	)
	(segment
		(start 353.40036 -281.106118)
		(end 353.394264 -281.102562)
		(width 0.0889)
		(layer "In11.Cu")
		(net "UPI_CPU1_CPU0_P2P2_DP<6>")
	)
	(segment
		(start 62.169548 -322.63461)
		(end 61.73343 -323.687186)
		(width 0.14732)
		(layer "In11.Cu")
		(net "UPI_CPU1_CPU0_P2P2_DP<6>")
	)
	(segment
		(start 349.274384 -291.422074)
		(end 349.525844 -291.170614)
		(width 0.0889)
		(layer "In11.Cu")
		(net "UPI_CPU1_CPU0_P2P2_DP<6>")
	)
	(segment
		(start 90.321892 -286.799782)
		(end 90.315796 -286.803338)
		(width 0.0889)
		(layer "In11.Cu")
		(net "UPI_CPU1_CPU0_P2P2_DP<6>")
	)
	(segment
		(start 59.422538 -325.312278)
		(end 59.21248 -325.819516)
		(width 0.14732)
		(layer "In11.Cu")
		(net "UPI_CPU1_CPU0_P2P2_DP<6>")
	)
	(segment
		(start 353.864418 -278.66086)
		(end 353.863656 -278.660352)
		(width 0.0889)
		(layer "In11.Cu")
		(net "UPI_CPU1_CPU0_P2P2_DP<6>")
	)
	(segment
		(start 351.514664 -285.985712)
		(end 351.505774 -285.980632)
		(width 0.0889)
		(layer "In11.Cu")
		(net "UPI_CPU1_CPU0_P2P2_DP<6>")
	)
	(segment
		(start 89.569544 -288.09315)
		(end 89.569544 -288.103056)
		(width 0.0889)
		(layer "In11.Cu")
		(net "UPI_CPU1_CPU0_P2P2_DP<6>")
	)
	(segment
		(start 88.785954 -291.144198)
		(end 88.744044 -291.186108)
		(width 0.0889)
		(layer "In11.Cu")
		(net "UPI_CPU1_CPU0_P2P2_DP<6>")
	)
	(segment
		(start 89.099644 -289.249866)
		(end 88.785954 -289.563556)
		(width 0.0889)
		(layer "In11.Cu")
		(net "UPI_CPU1_CPU0_P2P2_DP<6>")
	)
	(segment
		(start 349.917512 -290.520374)
		(end 350.016572 -290.421314)
		(width 0.0889)
		(layer "In11.Cu")
		(net "UPI_CPU1_CPU0_P2P2_DP<6>")
	)
	(segment
		(start 340.770972 -306.421536)
		(end 340.771226 -306.421536)
		(width 0.14732)
		(layer "In11.Cu")
		(net "UPI_CPU1_CPU0_P2P2_DP<6>")
	)
	(segment
		(start 66.750184 -317.29045)
		(end 64.765428 -319.275714)
		(width 0.14732)
		(layer "In11.Cu")
		(net "UPI_CPU1_CPU0_P2P2_DP<6>")
	)
	(segment
		(start 89.099644 -288.903156)
		(end 89.099644 -289.249866)
		(width 0.0889)
		(layer "In11.Cu")
		(net "UPI_CPU1_CPU0_P2P2_DP<6>")
	)
	(segment
		(start 349.666306 -291.170614)
		(end 349.792036 -291.044884)
		(width 0.0889)
		(layer "In11.Cu")
		(net "UPI_CPU1_CPU0_P2P2_DP<6>")
	)
	(segment
		(start 88.744044 -291.186108)
		(end 88.744044 -291.208206)
		(width 0.0889)
		(layer "In11.Cu")
		(net "UPI_CPU1_CPU0_P2P2_DP<6>")
	)
	(segment
		(start 353.385374 -282.086558)
		(end 353.394264 -282.081478)
		(width 0.0889)
		(layer "In11.Cu")
		(net "UPI_CPU1_CPU0_P2P2_DP<6>")
	)
	(segment
		(start 353.861116 -278.658828)
		(end 353.855528 -278.65578)
		(width 0.0889)
		(layer "In11.Cu")
		(net "UPI_CPU1_CPU0_P2P2_DP<6>")
	)
	(segment
		(start 90.330782 -286.794702)
		(end 90.321892 -286.799782)
		(width 0.0889)
		(layer "In11.Cu")
		(net "UPI_CPU1_CPU0_P2P2_DP<6>")
	)
	(segment
		(start 89.860882 -287.608518)
		(end 89.852754 -287.61309)
		(width 0.0889)
		(layer "In11.Cu")
		(net "UPI_CPU1_CPU0_P2P2_DP<6>")
	)
	(segment
		(start 274.691094 -367.888012)
		(end 274.691094 -347.613732)
		(width 0.14732)
		(layer "In11.Cu")
		(net "UPI_CPU1_CPU0_P2P2_DP<6>")
	)
	(segment
		(start 351.983802 -284.523688)
		(end 351.984818 -284.52318)
		(width 0.0889)
		(layer "In11.Cu")
		(net "UPI_CPU1_CPU0_P2P2_DP<6>")
	)
	(segment
		(start 85.993224 -294.548306)
		(end 83.939634 -299.506894)
		(width 0.14732)
		(layer "In11.Cu")
		(net "UPI_CPU1_CPU0_P2P2_DP<6>")
	)
	(segment
		(start 351.505774 -286.969962)
		(end 351.505774 -286.970216)
		(width 0.0889)
		(layer "In11.Cu")
		(net "UPI_CPU1_CPU0_P2P2_DP<6>")
	)
	(segment
		(start 350.857566 -288.121598)
		(end 350.857566 -288.103056)
		(width 0.0889)
		(layer "In11.Cu")
		(net "UPI_CPU1_CPU0_P2P2_DP<6>")
	)
	(segment
		(start 90.039444 -285.661354)
		(end 90.039444 -285.675578)
		(width 0.0889)
		(layer "In11.Cu")
		(net "UPI_CPU1_CPU0_P2P2_DP<6>")
	)
	(segment
		(start 61.444378 -355.220016)
		(end 66.750692 -368.031522)
		(width 0.14732)
		(layer "In11.Cu")
		(net "UPI_CPU1_CPU0_P2P2_DP<6>")
	)
	(segment
		(start 64.098932 -320.254376)
		(end 62.886336 -320.756534)
		(width 0.14732)
		(layer "In11.Cu")
		(net "UPI_CPU1_CPU0_P2P2_DP<6>")
	)
	(segment
		(start 90.979244 -284.023816)
		(end 90.979244 -284.033722)
		(width 0.0889)
		(layer "In11.Cu")
		(net "UPI_CPU1_CPU0_P2P2_DP<6>")
	)
	(segment
		(start 274.691094 -347.613732)
		(end 282.825952 -339.478874)
		(width 0.14732)
		(layer "In11.Cu")
		(net "UPI_CPU1_CPU0_P2P2_DP<6>")
	)
	(segment
		(start 59.21248 -329.133962)
		(end 60.403486 -331.362558)
		(width 0.14732)
		(layer "In11.Cu")
		(net "UPI_CPU1_CPU0_P2P2_DP<6>")
	)
	(segment
		(start 66.750692 -368.031522)
		(end 72.499474 -373.780304)
		(width 0.14732)
		(layer "In11.Cu")
		(net "UPI_CPU1_CPU0_P2P2_DP<6>")
	)
	(segment
		(start 353.394264 -281.102562)
		(end 353.385374 -281.097482)
		(width 0.0889)
		(layer "In11.Cu")
		(net "UPI_CPU1_CPU0_P2P2_DP<6>")
	)
	(segment
		(start 88.686894 -290.5125)
		(end 88.686894 -290.6903)
		(width 0.0889)
		(layer "In11.Cu")
		(net "UPI_CPU1_CPU0_P2P2_DP<6>")
	)
	(segment
		(start 64.544702 -319.808606)
		(end 64.098932 -320.254376)
		(width 0.14732)
		(layer "In11.Cu")
		(net "UPI_CPU1_CPU0_P2P2_DP<6>")
	)
	(segment
		(start 90.509344 -284.837632)
		(end 90.509344 -284.847538)
		(width 0.0889)
		(layer "In11.Cu")
		(net "UPI_CPU1_CPU0_P2P2_DP<6>")
	)
	(segment
		(start 350.016572 -290.421314)
		(end 350.016572 -290.243514)
		(width 0.0889)
		(layer "In11.Cu")
		(net "UPI_CPU1_CPU0_P2P2_DP<6>")
	)
	(segment
		(start 61.73343 -323.687186)
		(end 61.392054 -324.028562)
		(width 0.14732)
		(layer "In11.Cu")
		(net "UPI_CPU1_CPU0_P2P2_DP<6>")
	)
	(segment
		(start 340.771226 -306.421536)
		(end 342.778334 -305.590194)
		(width 0.14732)
		(layer "In11.Cu")
		(net "UPI_CPU1_CPU0_P2P2_DP<6>")
	)
	(segment
		(start 61.444378 -335.516982)
		(end 61.444378 -355.220016)
		(width 0.14732)
		(layer "In11.Cu")
		(net "UPI_CPU1_CPU0_P2P2_DP<6>")
	)
	(segment
		(start 353.855528 -278.017224)
		(end 353.864418 -278.012144)
		(width 0.0889)
		(layer "In11.Cu")
		(net "UPI_CPU1_CPU0_P2P2_DP<6>")
	)
	(segment
		(start 88.785954 -290.23564)
		(end 88.785954 -290.41344)
		(width 0.0889)
		(layer "In11.Cu")
		(net "UPI_CPU1_CPU0_P2P2_DP<6>")
	)
	(segment
		(start 91.270582 -283.539184)
		(end 91.261692 -283.544264)
		(width 0.0889)
		(layer "In11.Cu")
		(net "UPI_CPU1_CPU0_P2P2_DP<6>")
	)
	(segment
		(start 349.917512 -290.144454)
		(end 349.917512 -289.64636)
		(width 0.0889)
		(layer "In11.Cu")
		(net "UPI_CPU1_CPU0_P2P2_DP<6>")
	)
	(segment
		(start 349.274384 -291.481002)
		(end 349.274384 -291.422074)
		(width 0.0889)
		(layer "In11.Cu")
		(net "UPI_CPU1_CPU0_P2P2_DP<6>")
	)
	(segment
		(start 90.321892 -285.171896)
		(end 90.315796 -285.175452)
		(width 0.0889)
		(layer "In11.Cu")
		(net "UPI_CPU1_CPU0_P2P2_DP<6>")
	)
	(segment
		(start 354.146612 -277.54453)
		(end 354.146612 -277.522432)
		(width 0.0889)
		(layer "In11.Cu")
		(net "UPI_CPU1_CPU0_P2P2_DP<6>")
	)
	(segment
		(start 353.385374 -280.458926)
		(end 353.394264 -280.453846)
		(width 0.0889)
		(layer "In11.Cu")
		(net "UPI_CPU1_CPU0_P2P2_DP<6>")
	)
	(segment
		(start 90.330782 -285.166816)
		(end 90.321892 -285.171896)
		(width 0.0889)
		(layer "In11.Cu")
		(net "UPI_CPU1_CPU0_P2P2_DP<6>")
	)
	(segment
		(start 351.797366 -286.475424)
		(end 351.797366 -286.4612)
		(width 0.0889)
		(layer "In11.Cu")
		(net "UPI_CPU1_CPU0_P2P2_DP<6>")
	)
	(segment
		(start 62.229238 -322.490338)
		(end 62.169548 -322.63461)
		(width 0.14732)
		(layer "In11.Cu")
		(net "UPI_CPU1_CPU0_P2P2_DP<6>")
	)
	(segment
		(start 91.230958 -282.948888)
		(end 91.30919 -282.92806)
		(width 0.0889)
		(layer "In11.Cu")
		(net "UPI_CPU1_CPU0_P2P2_DP<6>")
	)
	(segment
		(start 89.09939 -288.902902)
		(end 89.099644 -288.903156)
		(width 0.0889)
		(layer "In11.Cu")
		(net "UPI_CPU1_CPU0_P2P2_DP<6>")
	)
	(segment
		(start 350.016572 -290.243514)
		(end 349.917512 -290.144454)
		(width 0.0889)
		(layer "In11.Cu")
		(net "UPI_CPU1_CPU0_P2P2_DP<6>")
	)
	(segment
		(start 350.566228 -288.597848)
		(end 350.575118 -288.592768)
		(width 0.0889)
		(layer "In11.Cu")
		(net "UPI_CPU1_CPU0_P2P2_DP<6>")
	)
	(segment
		(start 89.852754 -287.61309)
		(end 89.851992 -287.613598)
		(width 0.0889)
		(layer "In11.Cu")
		(net "UPI_CPU1_CPU0_P2P2_DP<6>")
	)
	(segment
		(start 62.886336 -320.756534)
		(end 62.496446 -321.146424)
		(width 0.14732)
		(layer "In11.Cu")
		(net "UPI_CPU1_CPU0_P2P2_DP<6>")
	)
	(segment
		(start 352.915728 -282.900628)
		(end 352.924618 -282.895548)
		(width 0.0889)
		(layer "In11.Cu")
		(net "UPI_CPU1_CPU0_P2P2_DP<6>")
	)
	(segment
		(start 352.454464 -283.709364)
		(end 352.466656 -283.702252)
		(width 0.0889)
		(layer "In11.Cu")
		(net "UPI_CPU1_CPU0_P2P2_DP<6>")
	)
	(segment
		(start 72.499474 -373.780304)
		(end 95.31858 -383.232152)
		(width 0.14732)
		(layer "In11.Cu")
		(net "UPI_CPU1_CPU0_P2P2_DP<6>")
	)
	(segment
		(start 354.656644 -277.173436)
		(end 354.677726 -277.251414)
		(width 0.0889)
		(layer "In11.Cu")
		(net "UPI_CPU1_CPU0_P2P2_DP<6>")
	)
	(segment
		(start 351.036128 -287.783778)
		(end 351.045018 -287.778698)
		(width 0.0889)
		(layer "In11.Cu")
		(net "UPI_CPU1_CPU0_P2P2_DP<6>")
	)
	(segment
		(start 88.785954 -290.41344)
		(end 88.686894 -290.5125)
		(width 0.0889)
		(layer "In11.Cu")
		(net "UPI_CPU1_CPU0_P2P2_DP<6>")
	)
	(segment
		(start 126.335028 -387.833108)
		(end 162.17011 -387.833108)
		(width 0.14732)
		(layer "In11.Cu")
		(net "UPI_CPU1_CPU0_P2P2_DP<6>")
	)
	(segment
		(start 338.864448 -307.211476)
		(end 340.770972 -306.421536)
		(width 0.14732)
		(layer "In11.Cu")
		(net "UPI_CPU1_CPU0_P2P2_DP<6>")
	)
	(segment
		(start 354.677726 -277.251414)
		(end 354.521262 -277.522432)
		(width 0.0889)
		(layer "In11.Cu")
		(net "UPI_CPU1_CPU0_P2P2_DP<6>")
	)
	(segment
		(start 353.676966 -279.978358)
		(end 353.676966 -279.964134)
		(width 0.0889)
		(layer "In11.Cu")
		(net "UPI_CPU1_CPU0_P2P2_DP<6>")
	)
	(segment
		(start 319.455038 -326.620886)
		(end 338.864448 -307.211476)
		(width 0.14732)
		(layer "In11.Cu")
		(net "UPI_CPU1_CPU0_P2P2_DP<6>")
	)
	(segment
		(start 351.505774 -285.342076)
		(end 351.514664 -285.336996)
		(width 0.0889)
		(layer "In11.Cu")
		(net "UPI_CPU1_CPU0_P2P2_DP<6>")
	)
	(segment
		(start 90.321892 -286.151066)
		(end 90.330782 -286.156146)
		(width 0.0889)
		(layer "In11.Cu")
		(net "UPI_CPU1_CPU0_P2P2_DP<6>")
	)
	(segment
		(start 60.221114 -324.513702)
		(end 59.422538 -325.312278)
		(width 0.14732)
		(layer "In11.Cu")
		(net "UPI_CPU1_CPU0_P2P2_DP<6>")
	)
	(segment
		(start 348.483936 -298.147232)
		(end 348.483936 -292.27145)
		(width 0.14732)
		(layer "In11.Cu")
		(net "UPI_CPU1_CPU0_P2P2_DP<6>")
	)
	(segment
		(start 353.206812 -282.427934)
		(end 353.206812 -282.405836)
		(width 0.0889)
		(layer "In11.Cu")
		(net "UPI_CPU1_CPU0_P2P2_DP<6>")
	)
	(segment
		(start 351.975928 -284.52826)
		(end 351.983802 -284.523688)
		(width 0.0889)
		(layer "In11.Cu")
		(net "UPI_CPU1_CPU0_P2P2_DP<6>")
	)
	(segment
		(start 318.326516 -329.345544)
		(end 319.455038 -326.620886)
		(width 0.14732)
		(layer "In11.Cu")
		(net "UPI_CPU1_CPU0_P2P2_DP<6>")
	)
	(segment
		(start 353.855528 -279.644856)
		(end 353.864418 -279.639776)
		(width 0.0889)
		(layer "In11.Cu")
		(net "UPI_CPU1_CPU0_P2P2_DP<6>")
	)
	(segment
		(start 162.17011 -387.833108)
		(end 263.2837 -379.29566)
		(width 0.14732)
		(layer "In11.Cu")
		(net "UPI_CPU1_CPU0_P2P2_DP<6>")
	)
	(segment
		(start 351.514664 -285.336996)
		(end 351.526856 -285.329884)
		(width 0.0889)
		(layer "In11.Cu")
		(net "UPI_CPU1_CPU0_P2P2_DP<6>")
	)
	(segment
		(start 353.394264 -282.081478)
		(end 353.40036 -282.077922)
		(width 0.0889)
		(layer "In11.Cu")
		(net "UPI_CPU1_CPU0_P2P2_DP<6>")
	)
	(segment
		(start 88.785954 -289.563556)
		(end 88.785954 -289.85972)
		(width 0.0889)
		(layer "In11.Cu")
		(net "UPI_CPU1_CPU0_P2P2_DP<6>")
	)
	(segment
		(start 349.25889 -291.496496)
		(end 349.274384 -291.481002)
		(width 0.0889)
		(layer "In11.Cu")
		(net "UPI_CPU1_CPU0_P2P2_DP<6>")
	)
	(segment
		(start 88.744044 -291.208206)
		(end 88.744044 -291.797486)
		(width 0.14732)
		(layer "In11.Cu")
		(net "UPI_CPU1_CPU0_P2P2_DP<6>")
	)
	(segment
		(start 60.403486 -331.362558)
		(end 61.444378 -335.516982)
		(width 0.14732)
		(layer "In11.Cu")
		(net "UPI_CPU1_CPU0_P2P2_DP<6>")
	)
	(segment
		(start 352.445574 -283.714444)
		(end 352.454464 -283.709364)
		(width 0.0889)
		(layer "In11.Cu")
		(net "UPI_CPU1_CPU0_P2P2_DP<6>")
	)
	(segment
		(start 349.917512 -290.778946)
		(end 349.917512 -290.520374)
		(width 0.0889)
		(layer "In11.Cu")
		(net "UPI_CPU1_CPU0_P2P2_DP<6>")
	)
	(segment
		(start 349.792036 -290.904422)
		(end 349.917512 -290.778946)
		(width 0.0889)
		(layer "In11.Cu")
		(net "UPI_CPU1_CPU0_P2P2_DP<6>")
	)
	(segment
		(start 350.387666 -289.114484)
		(end 350.387666 -288.917126)
		(width 0.0889)
		(layer "In11.Cu")
		(net "UPI_CPU1_CPU0_P2P2_DP<6>")
	)
	(segment
		(start 349.525844 -291.170614)
		(end 349.666306 -291.170614)
		(width 0.0889)
		(layer "In11.Cu")
		(net "UPI_CPU1_CPU0_P2P2_DP<6>")
	)
	(segment
		(start 348.483936 -292.27145)
		(end 349.25889 -291.496496)
		(width 0.14732)
		(layer "In11.Cu")
		(net "UPI_CPU1_CPU0_P2P2_DP<6>")
	)
	(segment
		(start 88.744044 -291.797486)
		(end 85.993224 -294.548306)
		(width 0.14732)
		(layer "In11.Cu")
		(net "UPI_CPU1_CPU0_P2P2_DP<6>")
	)
	(segment
		(start 62.496446 -321.146424)
		(end 62.229238 -322.490338)
		(width 0.14732)
		(layer "In11.Cu")
		(net "UPI_CPU1_CPU0_P2P2_DP<6>")
	)
	(segment
		(start 354.325174 -277.203154)
		(end 354.334064 -277.198074)
		(width 0.0889)
		(layer "In11.Cu")
		(net "UPI_CPU1_CPU0_P2P2_DP<6>")
	)
	(segment
		(start 354.146866 -279.160224)
		(end 354.146866 -279.140412)
		(width 0.0889)
		(layer "In11.Cu")
		(net "UPI_CPU1_CPU0_P2P2_DP<6>")
	)
	(segment
		(start 351.327212 -287.304734)
		(end 351.327212 -287.28924)
		(width 0.0889)
		(layer "In11.Cu")
		(net "UPI_CPU1_CPU0_P2P2_DP<6>")
	)
	(segment
		(start 351.505774 -286.970216)
		(end 351.52076 -286.961326)
		(width 0.0889)
		(layer "In11.Cu")
		(net "UPI_CPU1_CPU0_P2P2_DP<6>")
	)
	(segment
		(start 88.686894 -290.13658)
		(end 88.785954 -290.23564)
		(width 0.0889)
		(layer "In11.Cu")
		(net "UPI_CPU1_CPU0_P2P2_DP<6>")
	)
	(segment
		(start 309.77713 -337.89493)
		(end 318.326516 -329.345544)
		(width 0.14732)
		(layer "In11.Cu")
		(net "UPI_CPU1_CPU0_P2P2_DP<6>")
	)
	(segment
		(start 88.785954 -290.78936)
		(end 88.785954 -291.144198)
		(width 0.0889)
		(layer "In11.Cu")
		(net "UPI_CPU1_CPU0_P2P2_DP<6>")
	)
	(segment
		(start 90.800682 -284.353)
		(end 90.791792 -284.35808)
		(width 0.0889)
		(layer "In11.Cu")
		(net "UPI_CPU1_CPU0_P2P2_DP<6>")
	)
	(segment
		(start 89.390982 -288.422334)
		(end 89.382092 -288.427414)
		(width 0.0889)
		(layer "In11.Cu")
		(net "UPI_CPU1_CPU0_P2P2_DP<6>")
	)
	(segment
		(start 64.765428 -319.275714)
		(end 64.544702 -319.808606)
		(width 0.14732)
		(layer "In11.Cu")
		(net "UPI_CPU1_CPU0_P2P2_DP<6>")
	)
	(segment
		(start 88.785954 -289.85972)
		(end 88.686894 -289.95878)
		(width 0.0889)
		(layer "In11.Cu")
		(net "UPI_CPU1_CPU0_P2P2_DP<6>")
	)
	(segment
		(start 352.267012 -284.049216)
		(end 352.267012 -284.033722)
		(width 0.0889)
		(layer "In11.Cu")
		(net "UPI_CPU1_CPU0_P2P2_DP<6>")
	)
	(segment
		(start 61.392054 -324.028562)
		(end 60.221114 -324.513702)
		(width 0.14732)
		(layer "In11.Cu")
		(net "UPI_CPU1_CPU0_P2P2_DP<6>")
	)
	(segment
		(start 95.31858 -383.232152)
		(end 126.335028 -387.833108)
		(width 0.14732)
		(layer "In11.Cu")
		(net "UPI_CPU1_CPU0_P2P2_DP<6>")
	)
	(segment
		(start 91.074494 -283.219906)
		(end 91.230958 -282.948888)
		(width 0.0889)
		(layer "In11.Cu")
		(net "UPI_CPU1_CPU0_P2P2_DP<6>")
	)
	(segment
		(start 88.686894 -289.95878)
		(end 88.686894 -290.13658)
		(width 0.0889)
		(layer "In11.Cu")
		(net "UPI_CPU1_CPU0_P2P2_DP<6>")
	)
	(segment
		(start 66.750184 -316.699646)
		(end 66.750184 -317.29045)
		(width 0.14732)
		(layer "In11.Cu")
		(net "UPI_CPU1_CPU0_P2P2_DP<6>")
	)
	(segment
		(start 59.21248 -325.819516)
		(end 59.21248 -329.133962)
		(width 0.14732)
		(layer "In11.Cu")
		(net "UPI_CPU1_CPU0_P2P2_DP<6>")
	)
	(segment
		(start 263.2837 -379.29566)
		(end 274.691094 -367.888012)
		(width 0.14732)
		(layer "In11.Cu")
		(net "UPI_CPU1_CPU0_P2P2_DP<6>")
	)
	(arc
		(start 353.864418 -278.012144)
		(mid 354.0657 -277.814657)
		(end 354.146612 -277.54453)
		(width 0.0889)
		(layer "In11.Cu")
		(net "UPI_CPU1_CPU0_P2P2_DP<6>")
	)
	(arc
		(start 352.267012 -284.033722)
		(mid 352.314691 -283.850822)
		(end 352.445574 -283.714444)
		(width 0.0889)
		(layer "In11.Cu")
		(net "UPI_CPU1_CPU0_P2P2_DP<6>")
	)
	(arc
		(start 350.387666 -288.917126)
		(mid 350.435345 -288.734226)
		(end 350.566228 -288.597848)
		(width 0.0889)
		(layer "In11.Cu")
		(net "UPI_CPU1_CPU0_P2P2_DP<6>")
	)
	(arc
		(start 351.327212 -285.670752)
		(mid 351.327129 -285.662751)
		(end 351.327212 -285.65475)
		(width 0.0889)
		(layer "In11.Cu")
		(net "UPI_CPU1_CPU0_P2P2_DP<6>")
	)
	(arc
		(start 351.984818 -284.52318)
		(mid 352.187641 -284.322949)
		(end 352.267012 -284.049216)
		(width 0.0889)
		(layer "In11.Cu")
		(net "UPI_CPU1_CPU0_P2P2_DP<6>")
	)
	(arc
		(start 91.30919 -282.92806)
		(mid 91.409139 -283.051586)
		(end 91.44889 -283.205428)
		(width 0.0889)
		(layer "In11.Cu")
		(net "UPI_CPU1_CPU0_P2P2_DP<6>")
	)
	(arc
		(start 351.526856 -285.329884)
		(mid 351.725084 -285.124036)
		(end 351.797366 -284.847538)
		(width 0.0889)
		(layer "In11.Cu")
		(net "UPI_CPU1_CPU0_P2P2_DP<6>")
	)
	(arc
		(start 351.505774 -285.980632)
		(mid 351.37718 -285.848358)
		(end 351.327212 -285.670752)
		(width 0.0889)
		(layer "In11.Cu")
		(net "UPI_CPU1_CPU0_P2P2_DP<6>")
	)
	(arc
		(start 351.327212 -285.65475)
		(mid 351.376465 -285.47555)
		(end 351.505774 -285.342076)
		(width 0.0889)
		(layer "In11.Cu")
		(net "UPI_CPU1_CPU0_P2P2_DP<6>")
	)
	(arc
		(start 353.385374 -281.097482)
		(mid 353.206777 -280.778204)
		(end 353.385374 -280.458926)
		(width 0.0889)
		(layer "In11.Cu")
		(net "UPI_CPU1_CPU0_P2P2_DP<6>")
	)
	(arc
		(start 351.797366 -286.4612)
		(mid 351.718147 -286.186515)
		(end 351.514664 -285.985712)
		(width 0.0889)
		(layer "In11.Cu")
		(net "UPI_CPU1_CPU0_P2P2_DP<6>")
	)
	(arc
		(start 350.575118 -288.592768)
		(mid 350.777404 -288.393787)
		(end 350.857566 -288.121598)
		(width 0.0889)
		(layer "In11.Cu")
		(net "UPI_CPU1_CPU0_P2P2_DP<6>")
	)
	(arc
		(start 90.509344 -284.847538)
		(mid 90.461665 -285.030438)
		(end 90.330782 -285.166816)
		(width 0.0889)
		(layer "In11.Cu")
		(net "UPI_CPU1_CPU0_P2P2_DP<6>")
	)
	(arc
		(start 91.449144 -283.219906)
		(mid 91.401465 -283.402806)
		(end 91.270582 -283.539184)
		(width 0.0889)
		(layer "In11.Cu")
		(net "UPI_CPU1_CPU0_P2P2_DP<6>")
	)
	(arc
		(start 352.924618 -282.895548)
		(mid 353.1259 -282.698061)
		(end 353.206812 -282.427934)
		(width 0.0889)
		(layer "In11.Cu")
		(net "UPI_CPU1_CPU0_P2P2_DP<6>")
	)
	(arc
		(start 350.101916 -289.446462)
		(mid 350.276217 -289.307532)
		(end 350.387666 -289.114484)
		(width 0.0889)
		(layer "In11.Cu")
		(net "UPI_CPU1_CPU0_P2P2_DP<6>")
	)
	(arc
		(start 353.855528 -278.65578)
		(mid 353.676931 -278.336502)
		(end 353.855528 -278.017224)
		(width 0.0889)
		(layer "In11.Cu")
		(net "UPI_CPU1_CPU0_P2P2_DP<6>")
	)
	(arc
		(start 351.52076 -286.961326)
		(mid 351.723347 -286.754975)
		(end 351.797366 -286.475424)
		(width 0.0889)
		(layer "In11.Cu")
		(net "UPI_CPU1_CPU0_P2P2_DP<6>")
	)
	(arc
		(start 90.315796 -285.175452)
		(mid 90.113383 -285.381865)
		(end 90.039444 -285.661354)
		(width 0.0889)
		(layer "In11.Cu")
		(net "UPI_CPU1_CPU0_P2P2_DP<6>")
	)
	(arc
		(start 89.569544 -288.103056)
		(mid 89.521865 -288.285956)
		(end 89.390982 -288.422334)
		(width 0.0889)
		(layer "In11.Cu")
		(net "UPI_CPU1_CPU0_P2P2_DP<6>")
	)
	(arc
		(start 353.676966 -279.964134)
		(mid 353.724645 -279.781234)
		(end 353.855528 -279.644856)
		(width 0.0889)
		(layer "In11.Cu")
		(net "UPI_CPU1_CPU0_P2P2_DP<6>")
	)
	(arc
		(start 353.864418 -279.639776)
		(mid 354.068753 -279.437171)
		(end 354.146866 -279.160224)
		(width 0.0889)
		(layer "In11.Cu")
		(net "UPI_CPU1_CPU0_P2P2_DP<6>")
	)
	(arc
		(start 354.146612 -277.522432)
		(mid 354.194291 -277.339532)
		(end 354.325174 -277.203154)
		(width 0.0889)
		(layer "In11.Cu")
		(net "UPI_CPU1_CPU0_P2P2_DP<6>")
	)
	(arc
		(start 90.330782 -286.156146)
		(mid 90.458036 -286.286112)
		(end 90.50909 -286.460692)
		(width 0.0889)
		(layer "In11.Cu")
		(net "UPI_CPU1_CPU0_P2P2_DP<6>")
	)
	(arc
		(start 349.917512 -289.64636)
		(mid 349.992583 -289.530618)
		(end 350.101916 -289.446462)
		(width 0.0889)
		(layer "In11.Cu")
		(net "UPI_CPU1_CPU0_P2P2_DP<6>")
	)
	(arc
		(start 89.851992 -287.613598)
		(mid 89.647657 -287.816203)
		(end 89.569544 -288.09315)
		(width 0.0889)
		(layer "In11.Cu")
		(net "UPI_CPU1_CPU0_P2P2_DP<6>")
	)
	(arc
		(start 353.206812 -282.405836)
		(mid 353.254491 -282.222936)
		(end 353.385374 -282.086558)
		(width 0.0889)
		(layer "In11.Cu")
		(net "UPI_CPU1_CPU0_P2P2_DP<6>")
	)
	(arc
		(start 354.146866 -279.140412)
		(mid 354.068755 -278.863463)
		(end 353.864418 -278.66086)
		(width 0.0889)
		(layer "In11.Cu")
		(net "UPI_CPU1_CPU0_P2P2_DP<6>")
	)
	(arc
		(start 90.039444 -287.28924)
		(mid 89.991765 -287.47214)
		(end 89.860882 -287.608518)
		(width 0.0889)
		(layer "In11.Cu")
		(net "UPI_CPU1_CPU0_P2P2_DP<6>")
	)
	(arc
		(start 91.44889 -283.205428)
		(mid 91.449085 -283.212666)
		(end 91.449144 -283.219906)
		(width 0.0889)
		(layer "In11.Cu")
		(net "UPI_CPU1_CPU0_P2P2_DP<6>")
	)
	(arc
		(start 354.334064 -277.198074)
		(mid 354.492552 -277.149141)
		(end 354.656644 -277.173436)
		(width 0.0889)
		(layer "In11.Cu")
		(net "UPI_CPU1_CPU0_P2P2_DP<6>")
	)
	(arc
		(start 351.045018 -287.778698)
		(mid 351.247841 -287.578467)
		(end 351.327212 -287.304734)
		(width 0.0889)
		(layer "In11.Cu")
		(net "UPI_CPU1_CPU0_P2P2_DP<6>")
	)
	(arc
		(start 90.315796 -286.803338)
		(mid 90.113383 -287.009751)
		(end 90.039444 -287.28924)
		(width 0.0889)
		(layer "In11.Cu")
		(net "UPI_CPU1_CPU0_P2P2_DP<6>")
	)
	(arc
		(start 90.509344 -286.485584)
		(mid 90.459275 -286.662809)
		(end 90.330782 -286.794702)
		(width 0.0889)
		(layer "In11.Cu")
		(net "UPI_CPU1_CPU0_P2P2_DP<6>")
	)
	(arc
		(start 350.857566 -288.103056)
		(mid 350.905245 -287.920156)
		(end 351.036128 -287.783778)
		(width 0.0889)
		(layer "In11.Cu")
		(net "UPI_CPU1_CPU0_P2P2_DP<6>")
	)
	(arc
		(start 353.394264 -280.453846)
		(mid 353.597745 -280.253042)
		(end 353.676966 -279.978358)
		(width 0.0889)
		(layer "In11.Cu")
		(net "UPI_CPU1_CPU0_P2P2_DP<6>")
	)
	(arc
		(start 90.791792 -284.35808)
		(mid 90.587457 -284.560685)
		(end 90.509344 -284.837632)
		(width 0.0889)
		(layer "In11.Cu")
		(net "UPI_CPU1_CPU0_P2P2_DP<6>")
	)
	(arc
		(start 351.797366 -284.847538)
		(mid 351.845045 -284.664638)
		(end 351.975928 -284.52826)
		(width 0.0889)
		(layer "In11.Cu")
		(net "UPI_CPU1_CPU0_P2P2_DP<6>")
	)
	(arc
		(start 352.737166 -283.219906)
		(mid 352.784845 -283.037006)
		(end 352.915728 -282.900628)
		(width 0.0889)
		(layer "In11.Cu")
		(net "UPI_CPU1_CPU0_P2P2_DP<6>")
	)
	(arc
		(start 351.327212 -287.28924)
		(mid 351.374891 -287.10634)
		(end 351.505774 -286.969962)
		(width 0.0889)
		(layer "In11.Cu")
		(net "UPI_CPU1_CPU0_P2P2_DP<6>")
	)
	(arc
		(start 352.466656 -283.702252)
		(mid 352.664884 -283.496404)
		(end 352.737166 -283.219906)
		(width 0.0889)
		(layer "In11.Cu")
		(net "UPI_CPU1_CPU0_P2P2_DP<6>")
	)
	(arc
		(start 90.50909 -286.460692)
		(mid 90.509423 -286.473136)
		(end 90.509344 -286.485584)
		(width 0.0889)
		(layer "In11.Cu")
		(net "UPI_CPU1_CPU0_P2P2_DP<6>")
	)
	(arc
		(start 91.261692 -283.544264)
		(mid 91.057357 -283.746869)
		(end 90.979244 -284.023816)
		(width 0.0889)
		(layer "In11.Cu")
		(net "UPI_CPU1_CPU0_P2P2_DP<6>")
	)
	(arc
		(start 89.382092 -288.427414)
		(mid 89.178611 -288.628218)
		(end 89.09939 -288.902902)
		(width 0.0889)
		(layer "In11.Cu")
		(net "UPI_CPU1_CPU0_P2P2_DP<6>")
	)
	(arc
		(start 90.979244 -284.033722)
		(mid 90.931565 -284.216622)
		(end 90.800682 -284.353)
		(width 0.0889)
		(layer "In11.Cu")
		(net "UPI_CPU1_CPU0_P2P2_DP<6>")
	)
	(arc
		(start 353.40036 -282.077922)
		(mid 353.676934 -281.59202)
		(end 353.40036 -281.106118)
		(width 0.0889)
		(layer "In11.Cu")
		(net "UPI_CPU1_CPU0_P2P2_DP<6>")
	)
	(arc
		(start 90.039444 -285.675578)
		(mid 90.118585 -285.950201)
		(end 90.321892 -286.151066)
		(width 0.0889)
		(layer "In11.Cu")
		(net "UPI_CPU1_CPU0_P2P2_DP<6>")
	)
	(segment
		(start 92.014294 -281.05608)
		(end 92.014548 -281.056334)
		(width 0.13208)
		(layer "F.Cu")
		(net "UPI_CPU1_CPU0_P2P2_DP<5>")
	)
	(segment
		(start 92.014548 -281.591766)
		(end 92.014294 -281.59202)
		(width 0.13208)
		(layer "F.Cu")
		(net "UPI_CPU1_CPU0_P2P2_DP<5>")
	)
	(segment
		(start 355.930962 -277.800562)
		(end 355.930962 -278.336248)
		(width 0.13208)
		(layer "F.Cu")
		(net "UPI_CPU1_CPU0_P2P2_DP<5>")
	)
	(segment
		(start 92.014548 -281.056334)
		(end 92.014548 -281.591766)
		(width 0.13208)
		(layer "F.Cu")
		(net "UPI_CPU1_CPU0_P2P2_DP<5>")
	)
	(segment
		(start 355.930962 -278.336248)
		(end 355.931216 -278.336502)
		(width 0.13208)
		(layer "F.Cu")
		(net "UPI_CPU1_CPU0_P2P2_DP<5>")
	)
	(segment
		(start 87.951818 -291.436044)
		(end 87.052404 -292.335458)
		(width 0.0889)
		(layer "In11.Cu")
		(net "UPI_CPU1_CPU0_P2P2_DP<5>")
	)
	(segment
		(start 351.1169 -290.797234)
		(end 351.1169 -290.73729)
		(width 0.0889)
		(layer "In11.Cu")
		(net "UPI_CPU1_CPU0_P2P2_DP<5>")
	)
	(segment
		(start 355.69652 -278.044656)
		(end 355.774752 -278.065484)
		(width 0.0889)
		(layer "In11.Cu")
		(net "UPI_CPU1_CPU0_P2P2_DP<5>")
	)
	(segment
		(start 355.086666 -279.160224)
		(end 355.086666 -279.141682)
		(width 0.0889)
		(layer "In11.Cu")
		(net "UPI_CPU1_CPU0_P2P2_DP<5>")
	)
	(segment
		(start 269.70101 -374.265444)
		(end 275.52904 -368.43716)
		(width 0.14732)
		(layer "In11.Cu")
		(net "UPI_CPU1_CPU0_P2P2_DP<5>")
	)
	(segment
		(start 88.160352 -288.917126)
		(end 88.160352 -289.08883)
		(width 0.0889)
		(layer "In11.Cu")
		(net "UPI_CPU1_CPU0_P2P2_DP<5>")
	)
	(segment
		(start 90.509344 -281.582114)
		(end 90.509344 -281.59202)
		(width 0.0889)
		(layer "In11.Cu")
		(net "UPI_CPU1_CPU0_P2P2_DP<5>")
	)
	(segment
		(start 91.70162 -281.59202)
		(end 91.636088 -281.526488)
		(width 0.0889)
		(layer "In11.Cu")
		(net "UPI_CPU1_CPU0_P2P2_DP<5>")
	)
	(segment
		(start 351.511362 -289.27806)
		(end 351.511616 -289.277806)
		(width 0.0889)
		(layer "In11.Cu")
		(net "UPI_CPU1_CPU0_P2P2_DP<5>")
	)
	(segment
		(start 90.330782 -283.539184)
		(end 90.321892 -283.544264)
		(width 0.0889)
		(layer "In11.Cu")
		(net "UPI_CPU1_CPU0_P2P2_DP<5>")
	)
	(segment
		(start 86.977982 -292.350952)
		(end 85.314536 -294.014398)
		(width 0.14732)
		(layer "In11.Cu")
		(net "UPI_CPU1_CPU0_P2P2_DP<5>")
	)
	(segment
		(start 90.509344 -283.205682)
		(end 90.509344 -283.219906)
		(width 0.0889)
		(layer "In11.Cu")
		(net "UPI_CPU1_CPU0_P2P2_DP<5>")
	)
	(segment
		(start 58.924952 -324.298564)
		(end 58.369708 -325.63943)
		(width 0.14732)
		(layer "In11.Cu")
		(net "UPI_CPU1_CPU0_P2P2_DP<5>")
	)
	(segment
		(start 347.166946 -302.374554)
		(end 350.162622 -297.890946)
		(width 0.14732)
		(layer "In11.Cu")
		(net "UPI_CPU1_CPU0_P2P2_DP<5>")
	)
	(segment
		(start 162.19805 -388.66953)
		(end 263.882886 -380.083822)
		(width 0.14732)
		(layer "In11.Cu")
		(net "UPI_CPU1_CPU0_P2P2_DP<5>")
	)
	(segment
		(start 350.162622 -297.890946)
		(end 350.20885 -297.844718)
		(width 0.14732)
		(layer "In11.Cu")
		(net "UPI_CPU1_CPU0_P2P2_DP<5>")
	)
	(segment
		(start 310.067706 -338.77885)
		(end 319.067942 -329.778614)
		(width 0.14732)
		(layer "In11.Cu")
		(net "UPI_CPU1_CPU0_P2P2_DP<5>")
	)
	(segment
		(start 60.6044 -355.41712)
		(end 66.019172 -368.4905)
		(width 0.14732)
		(layer "In11.Cu")
		(net "UPI_CPU1_CPU0_P2P2_DP<5>")
	)
	(segment
		(start 59.651138 -331.792326)
		(end 60.6044 -335.596484)
		(width 0.14732)
		(layer "In11.Cu")
		(net "UPI_CPU1_CPU0_P2P2_DP<5>")
	)
	(segment
		(start 88.451182 -288.422334)
		(end 88.442292 -288.427414)
		(width 0.0889)
		(layer "In11.Cu")
		(net "UPI_CPU1_CPU0_P2P2_DP<5>")
	)
	(segment
		(start 354.795328 -281.272742)
		(end 354.804218 -281.267662)
		(width 0.0889)
		(layer "In11.Cu")
		(net "UPI_CPU1_CPU0_P2P2_DP<5>")
	)
	(segment
		(start 351.797366 -288.121598)
		(end 351.797366 -288.103056)
		(width 0.0889)
		(layer "In11.Cu")
		(net "UPI_CPU1_CPU0_P2P2_DP<5>")
	)
	(segment
		(start 351.327466 -289.078416)
		(end 351.327466 -288.917126)
		(width 0.0889)
		(layer "In11.Cu")
		(net "UPI_CPU1_CPU0_P2P2_DP<5>")
	)
	(segment
		(start 319.067942 -329.778614)
		(end 320.196464 -327.054464)
		(width 0.14732)
		(layer "In11.Cu")
		(net "UPI_CPU1_CPU0_P2P2_DP<5>")
	)
	(segment
		(start 355.086412 -280.793698)
		(end 355.086412 -280.756106)
		(width 0.0889)
		(layer "In11.Cu")
		(net "UPI_CPU1_CPU0_P2P2_DP<5>")
	)
	(segment
		(start 339.278722 -307.972206)
		(end 343.188798 -306.352448)
		(width 0.14732)
		(layer "In11.Cu")
		(net "UPI_CPU1_CPU0_P2P2_DP<5>")
	)
	(segment
		(start 95.043498 -384.033268)
		(end 126.297182 -388.66953)
		(width 0.14732)
		(layer "In11.Cu")
		(net "UPI_CPU1_CPU0_P2P2_DP<5>")
	)
	(segment
		(start 263.882886 -380.083822)
		(end 269.70101 -374.265698)
		(width 0.14732)
		(layer "In11.Cu")
		(net "UPI_CPU1_CPU0_P2P2_DP<5>")
	)
	(segment
		(start 350.20885 -297.844718)
		(end 350.20885 -291.704268)
		(width 0.14732)
		(layer "In11.Cu")
		(net "UPI_CPU1_CPU0_P2P2_DP<5>")
	)
	(segment
		(start 87.052404 -292.335458)
		(end 86.993476 -292.335458)
		(width 0.0889)
		(layer "In11.Cu")
		(net "UPI_CPU1_CPU0_P2P2_DP<5>")
	)
	(segment
		(start 66.019172 -368.4905)
		(end 72.029828 -374.501156)
		(width 0.14732)
		(layer "In11.Cu")
		(net "UPI_CPU1_CPU0_P2P2_DP<5>")
	)
	(segment
		(start 61.33338 -321.363086)
		(end 60.960508 -322.263008)
		(width 0.14732)
		(layer "In11.Cu")
		(net "UPI_CPU1_CPU0_P2P2_DP<5>")
	)
	(segment
		(start 90.800936 -282.725114)
		(end 90.792046 -282.730194)
		(width 0.0889)
		(layer "In11.Cu")
		(net "UPI_CPU1_CPU0_P2P2_DP<5>")
	)
	(segment
		(start 58.34888 -329.355704)
		(end 59.651138 -331.792326)
		(width 0.14732)
		(layer "In11.Cu")
		(net "UPI_CPU1_CPU0_P2P2_DP<5>")
	)
	(segment
		(start 355.273864 -278.82596)
		(end 355.274626 -278.825452)
		(width 0.0889)
		(layer "In11.Cu")
		(net "UPI_CPU1_CPU0_P2P2_DP<5>")
	)
	(segment
		(start 352.454718 -286.964882)
		(end 352.460814 -286.961326)
		(width 0.0889)
		(layer "In11.Cu")
		(net "UPI_CPU1_CPU0_P2P2_DP<5>")
	)
	(segment
		(start 90.78595 -282.077922)
		(end 90.792046 -282.081478)
		(width 0.0889)
		(layer "In11.Cu")
		(net "UPI_CPU1_CPU0_P2P2_DP<5>")
	)
	(segment
		(start 65.268348 -315.64199)
		(end 63.905892 -317.004446)
		(width 0.14732)
		(layer "In11.Cu")
		(net "UPI_CPU1_CPU0_P2P2_DP<5>")
	)
	(segment
		(start 88.921082 -287.608518)
		(end 88.912192 -287.613598)
		(width 0.0889)
		(layer "In11.Cu")
		(net "UPI_CPU1_CPU0_P2P2_DP<5>")
	)
	(segment
		(start 355.086412 -282.427934)
		(end 355.086412 -282.390342)
		(width 0.0889)
		(layer "In11.Cu")
		(net "UPI_CPU1_CPU0_P2P2_DP<5>")
	)
	(segment
		(start 89.390982 -285.166816)
		(end 89.382092 -285.171896)
		(width 0.0889)
		(layer "In11.Cu")
		(net "UPI_CPU1_CPU0_P2P2_DP<5>")
	)
	(segment
		(start 58.34888 -325.689722)
		(end 58.34888 -329.355704)
		(width 0.14732)
		(layer "In11.Cu")
		(net "UPI_CPU1_CPU0_P2P2_DP<5>")
	)
	(segment
		(start 63.905892 -317.004446)
		(end 63.640462 -317.114428)
		(width 0.14732)
		(layer "In11.Cu")
		(net "UPI_CPU1_CPU0_P2P2_DP<5>")
	)
	(segment
		(start 283.688282 -340.02599)
		(end 286.698944 -338.77885)
		(width 0.14732)
		(layer "In11.Cu")
		(net "UPI_CPU1_CPU0_P2P2_DP<5>")
	)
	(segment
		(start 60.6044 -335.596484)
		(end 60.6044 -355.41712)
		(width 0.14732)
		(layer "In11.Cu")
		(net "UPI_CPU1_CPU0_P2P2_DP<5>")
	)
	(segment
		(start 90.802206 -281.096466)
		(end 90.791792 -281.102562)
		(width 0.0889)
		(layer "In11.Cu")
		(net "UPI_CPU1_CPU0_P2P2_DP<5>")
	)
	(segment
		(start 353.676712 -284.863032)
		(end 353.676712 -284.847538)
		(width 0.0889)
		(layer "In11.Cu")
		(net "UPI_CPU1_CPU0_P2P2_DP<5>")
	)
	(segment
		(start 350.20885 -291.704268)
		(end 350.78543 -291.127688)
		(width 0.14732)
		(layer "In11.Cu")
		(net "UPI_CPU1_CPU0_P2P2_DP<5>")
	)
	(segment
		(start 83.35899 -298.736258)
		(end 67.291204 -314.804044)
		(width 0.14732)
		(layer "In11.Cu")
		(net "UPI_CPU1_CPU0_P2P2_DP<5>")
	)
	(segment
		(start 89.381584 -286.80029)
		(end 89.37625 -286.803338)
		(width 0.0889)
		(layer "In11.Cu")
		(net "UPI_CPU1_CPU0_P2P2_DP<5>")
	)
	(segment
		(start 89.382346 -286.799782)
		(end 89.381584 -286.80029)
		(width 0.0889)
		(layer "In11.Cu")
		(net "UPI_CPU1_CPU0_P2P2_DP<5>")
	)
	(segment
		(start 352.445828 -286.969962)
		(end 352.454718 -286.964882)
		(width 0.0889)
		(layer "In11.Cu")
		(net "UPI_CPU1_CPU0_P2P2_DP<5>")
	)
	(segment
		(start 85.314536 -294.014398)
		(end 83.35899 -298.736258)
		(width 0.14732)
		(layer "In11.Cu")
		(net "UPI_CPU1_CPU0_P2P2_DP<5>")
	)
	(segment
		(start 60.960508 -322.263008)
		(end 58.924952 -324.298564)
		(width 0.14732)
		(layer "In11.Cu")
		(net "UPI_CPU1_CPU0_P2P2_DP<5>")
	)
	(segment
		(start 67.291204 -314.804044)
		(end 65.268348 -315.64199)
		(width 0.14732)
		(layer "In11.Cu")
		(net "UPI_CPU1_CPU0_P2P2_DP<5>")
	)
	(segment
		(start 275.52904 -368.43716)
		(end 275.52904 -348.185232)
		(width 0.14732)
		(layer "In11.Cu")
		(net "UPI_CPU1_CPU0_P2P2_DP<5>")
	)
	(segment
		(start 343.188798 -306.352448)
		(end 347.166946 -302.374554)
		(width 0.14732)
		(layer "In11.Cu")
		(net "UPI_CPU1_CPU0_P2P2_DP<5>")
	)
	(segment
		(start 88.160352 -289.08883)
		(end 87.955882 -289.2933)
		(width 0.0889)
		(layer "In11.Cu")
		(net "UPI_CPU1_CPU0_P2P2_DP<5>")
	)
	(segment
		(start 354.804218 -281.916378)
		(end 354.795328 -281.911298)
		(width 0.0889)
		(layer "In11.Cu")
		(net "UPI_CPU1_CPU0_P2P2_DP<5>")
	)
	(segment
		(start 351.975928 -287.783778)
		(end 351.984818 -287.778698)
		(width 0.0889)
		(layer "In11.Cu")
		(net "UPI_CPU1_CPU0_P2P2_DP<5>")
	)
	(segment
		(start 354.795328 -279.644856)
		(end 354.804218 -279.639776)
		(width 0.0889)
		(layer "In11.Cu")
		(net "UPI_CPU1_CPU0_P2P2_DP<5>")
	)
	(segment
		(start 63.640462 -317.114428)
		(end 61.81852 -318.93637)
		(width 0.14732)
		(layer "In11.Cu")
		(net "UPI_CPU1_CPU0_P2P2_DP<5>")
	)
	(segment
		(start 350.78543 -291.127688)
		(end 350.786446 -291.127688)
		(width 0.14732)
		(layer "In11.Cu")
		(net "UPI_CPU1_CPU0_P2P2_DP<5>")
	)
	(segment
		(start 353.207066 -285.675578)
		(end 353.207066 -285.661354)
		(width 0.0889)
		(layer "In11.Cu")
		(net "UPI_CPU1_CPU0_P2P2_DP<5>")
	)
	(segment
		(start 61.81852 -318.93637)
		(end 61.33338 -320.107056)
		(width 0.14732)
		(layer "In11.Cu")
		(net "UPI_CPU1_CPU0_P2P2_DP<5>")
	)
	(segment
		(start 88.629744 -288.09315)
		(end 88.629744 -288.103056)
		(width 0.0889)
		(layer "In11.Cu")
		(net "UPI_CPU1_CPU0_P2P2_DP<5>")
	)
	(segment
		(start 58.369708 -325.63943)
		(end 58.369454 -325.63943)
		(width 0.14732)
		(layer "In11.Cu")
		(net "UPI_CPU1_CPU0_P2P2_DP<5>")
	)
	(segment
		(start 90.039444 -284.023816)
		(end 90.039444 -284.033722)
		(width 0.0889)
		(layer "In11.Cu")
		(net "UPI_CPU1_CPU0_P2P2_DP<5>")
	)
	(segment
		(start 90.792046 -282.081478)
		(end 90.800936 -282.086558)
		(width 0.0889)
		(layer "In11.Cu")
		(net "UPI_CPU1_CPU0_P2P2_DP<5>")
	)
	(segment
		(start 353.855274 -284.52826)
		(end 353.864164 -284.52318)
		(width 0.0889)
		(layer "In11.Cu")
		(net "UPI_CPU1_CPU0_P2P2_DP<5>")
	)
	(segment
		(start 58.369454 -325.63943)
		(end 58.34888 -325.689722)
		(width 0.14732)
		(layer "In11.Cu")
		(net "UPI_CPU1_CPU0_P2P2_DP<5>")
	)
	(segment
		(start 351.506028 -288.597848)
		(end 351.514918 -288.592768)
		(width 0.0889)
		(layer "In11.Cu")
		(net "UPI_CPU1_CPU0_P2P2_DP<5>")
	)
	(segment
		(start 92.014294 -281.59202)
		(end 91.70162 -281.59202)
		(width 0.0889)
		(layer "In11.Cu")
		(net "UPI_CPU1_CPU0_P2P2_DP<5>")
	)
	(segment
		(start 286.698944 -338.77885)
		(end 310.067706 -338.77885)
		(width 0.14732)
		(layer "In11.Cu")
		(net "UPI_CPU1_CPU0_P2P2_DP<5>")
	)
	(segment
		(start 350.786446 -291.127688)
		(end 351.101406 -290.812728)
		(width 0.14732)
		(layer "In11.Cu")
		(net "UPI_CPU1_CPU0_P2P2_DP<5>")
	)
	(segment
		(start 354.325428 -283.714444)
		(end 354.334318 -283.709364)
		(width 0.0889)
		(layer "In11.Cu")
		(net "UPI_CPU1_CPU0_P2P2_DP<5>")
	)
	(segment
		(start 126.297182 -388.66953)
		(end 162.19805 -388.66953)
		(width 0.14732)
		(layer "In11.Cu")
		(net "UPI_CPU1_CPU0_P2P2_DP<5>")
	)
	(segment
		(start 351.796858 -290.057332)
		(end 351.796858 -289.610292)
		(width 0.0889)
		(layer "In11.Cu")
		(net "UPI_CPU1_CPU0_P2P2_DP<5>")
	)
	(segment
		(start 61.33338 -320.107056)
		(end 61.33338 -321.363086)
		(width 0.14732)
		(layer "In11.Cu")
		(net "UPI_CPU1_CPU0_P2P2_DP<5>")
	)
	(segment
		(start 351.1169 -290.73729)
		(end 351.796858 -290.057332)
		(width 0.0889)
		(layer "In11.Cu")
		(net "UPI_CPU1_CPU0_P2P2_DP<5>")
	)
	(segment
		(start 87.955882 -289.2933)
		(end 87.955882 -289.626548)
		(width 0.0889)
		(layer "In11.Cu")
		(net "UPI_CPU1_CPU0_P2P2_DP<5>")
	)
	(segment
		(start 351.101406 -290.812728)
		(end 351.1169 -290.797234)
		(width 0.0889)
		(layer "In11.Cu")
		(net "UPI_CPU1_CPU0_P2P2_DP<5>")
	)
	(segment
		(start 89.569544 -284.837632)
		(end 89.569544 -284.847538)
		(width 0.0889)
		(layer "In11.Cu")
		(net "UPI_CPU1_CPU0_P2P2_DP<5>")
	)
	(segment
		(start 355.774752 -278.065484)
		(end 355.931216 -278.336502)
		(width 0.0889)
		(layer "In11.Cu")
		(net "UPI_CPU1_CPU0_P2P2_DP<5>")
	)
	(segment
		(start 351.984818 -287.778698)
		(end 351.990914 -287.775142)
		(width 0.0889)
		(layer "In11.Cu")
		(net "UPI_CPU1_CPU0_P2P2_DP<5>")
	)
	(segment
		(start 320.196464 -327.054464)
		(end 339.278722 -307.972206)
		(width 0.14732)
		(layer "In11.Cu")
		(net "UPI_CPU1_CPU0_P2P2_DP<5>")
	)
	(segment
		(start 354.804218 -280.288492)
		(end 354.795328 -280.283412)
		(width 0.0889)
		(layer "In11.Cu")
		(net "UPI_CPU1_CPU0_P2P2_DP<5>")
	)
	(segment
		(start 353.864164 -284.52318)
		(end 353.867974 -284.520894)
		(width 0.0889)
		(layer "In11.Cu")
		(net "UPI_CPU1_CPU0_P2P2_DP<5>")
	)
	(segment
		(start 353.393502 -285.337504)
		(end 353.394518 -285.336996)
		(width 0.0889)
		(layer "In11.Cu")
		(net "UPI_CPU1_CPU0_P2P2_DP<5>")
	)
	(segment
		(start 275.52904 -348.185232)
		(end 283.688282 -340.02599)
		(width 0.14732)
		(layer "In11.Cu")
		(net "UPI_CPU1_CPU0_P2P2_DP<5>")
	)
	(segment
		(start 87.951818 -289.630612)
		(end 87.951818 -291.436044)
		(width 0.0889)
		(layer "In11.Cu")
		(net "UPI_CPU1_CPU0_P2P2_DP<5>")
	)
	(segment
		(start 89.099644 -285.651448)
		(end 89.099644 -285.675578)
		(width 0.0889)
		(layer "In11.Cu")
		(net "UPI_CPU1_CPU0_P2P2_DP<5>")
	)
	(segment
		(start 353.385628 -285.342076)
		(end 353.393502 -285.337504)
		(width 0.0889)
		(layer "In11.Cu")
		(net "UPI_CPU1_CPU0_P2P2_DP<5>")
	)
	(segment
		(start 354.334318 -283.709364)
		(end 354.340414 -283.705808)
		(width 0.0889)
		(layer "In11.Cu")
		(net "UPI_CPU1_CPU0_P2P2_DP<5>")
	)
	(segment
		(start 353.867974 -284.520894)
		(end 353.876356 -284.516068)
		(width 0.0889)
		(layer "In11.Cu")
		(net "UPI_CPU1_CPU0_P2P2_DP<5>")
	)
	(segment
		(start 355.274626 -278.825452)
		(end 355.27996 -278.822404)
		(width 0.0889)
		(layer "In11.Cu")
		(net "UPI_CPU1_CPU0_P2P2_DP<5>")
	)
	(segment
		(start 89.569544 -286.466788)
		(end 89.569544 -286.48406)
		(width 0.0889)
		(layer "In11.Cu")
		(net "UPI_CPU1_CPU0_P2P2_DP<5>")
	)
	(segment
		(start 89.860882 -284.353)
		(end 89.851992 -284.35808)
		(width 0.0889)
		(layer "In11.Cu")
		(net "UPI_CPU1_CPU0_P2P2_DP<5>")
	)
	(segment
		(start 86.993476 -292.335458)
		(end 86.977982 -292.350952)
		(width 0.0889)
		(layer "In11.Cu")
		(net "UPI_CPU1_CPU0_P2P2_DP<5>")
	)
	(segment
		(start 87.955882 -289.626548)
		(end 87.951818 -289.630612)
		(width 0.0889)
		(layer "In11.Cu")
		(net "UPI_CPU1_CPU0_P2P2_DP<5>")
	)
	(segment
		(start 354.795328 -282.900628)
		(end 354.804218 -282.895548)
		(width 0.0889)
		(layer "In11.Cu")
		(net "UPI_CPU1_CPU0_P2P2_DP<5>")
	)
	(segment
		(start 269.70101 -374.265698)
		(end 269.70101 -374.265444)
		(width 0.14732)
		(layer "In11.Cu")
		(net "UPI_CPU1_CPU0_P2P2_DP<5>")
	)
	(segment
		(start 72.029828 -374.501156)
		(end 95.043498 -384.033268)
		(width 0.14732)
		(layer "In11.Cu")
		(net "UPI_CPU1_CPU0_P2P2_DP<5>")
	)
	(segment
		(start 352.915728 -286.156146)
		(end 352.924618 -286.151066)
		(width 0.0889)
		(layer "In11.Cu")
		(net "UPI_CPU1_CPU0_P2P2_DP<5>")
	)
	(arc
		(start 89.382346 -286.151066)
		(mid 89.517279 -286.28442)
		(end 89.569544 -286.466788)
		(width 0.0889)
		(layer "In11.Cu")
		(net "UPI_CPU1_CPU0_P2P2_DP<5>")
	)
	(arc
		(start 353.876356 -284.516068)
		(mid 354.074584 -284.31022)
		(end 354.146866 -284.033722)
		(width 0.0889)
		(layer "In11.Cu")
		(net "UPI_CPU1_CPU0_P2P2_DP<5>")
	)
	(arc
		(start 354.146866 -284.033722)
		(mid 354.194545 -283.850822)
		(end 354.325428 -283.714444)
		(width 0.0889)
		(layer "In11.Cu")
		(net "UPI_CPU1_CPU0_P2P2_DP<5>")
	)
	(arc
		(start 353.394518 -285.336996)
		(mid 353.597341 -285.136765)
		(end 353.676712 -284.863032)
		(width 0.0889)
		(layer "In11.Cu")
		(net "UPI_CPU1_CPU0_P2P2_DP<5>")
	)
	(arc
		(start 354.804218 -281.267662)
		(mid 355.007041 -281.067431)
		(end 355.086412 -280.793698)
		(width 0.0889)
		(layer "In11.Cu")
		(net "UPI_CPU1_CPU0_P2P2_DP<5>")
	)
	(arc
		(start 90.509344 -281.59202)
		(mid 90.583335 -281.871586)
		(end 90.78595 -282.077922)
		(width 0.0889)
		(layer "In11.Cu")
		(net "UPI_CPU1_CPU0_P2P2_DP<5>")
	)
	(arc
		(start 88.912192 -287.613598)
		(mid 88.707857 -287.816203)
		(end 88.629744 -288.09315)
		(width 0.0889)
		(layer "In11.Cu")
		(net "UPI_CPU1_CPU0_P2P2_DP<5>")
	)
	(arc
		(start 354.616766 -283.219906)
		(mid 354.664445 -283.037006)
		(end 354.795328 -282.900628)
		(width 0.0889)
		(layer "In11.Cu")
		(net "UPI_CPU1_CPU0_P2P2_DP<5>")
	)
	(arc
		(start 351.797366 -288.103056)
		(mid 351.845045 -287.920156)
		(end 351.975928 -287.783778)
		(width 0.0889)
		(layer "In11.Cu")
		(net "UPI_CPU1_CPU0_P2P2_DP<5>")
	)
	(arc
		(start 352.460814 -286.961326)
		(mid 352.663227 -286.754913)
		(end 352.737166 -286.475424)
		(width 0.0889)
		(layer "In11.Cu")
		(net "UPI_CPU1_CPU0_P2P2_DP<5>")
	)
	(arc
		(start 90.039444 -284.033722)
		(mid 89.991765 -284.216622)
		(end 89.860882 -284.353)
		(width 0.0889)
		(layer "In11.Cu")
		(net "UPI_CPU1_CPU0_P2P2_DP<5>")
	)
	(arc
		(start 353.676712 -284.847538)
		(mid 353.724391 -284.664638)
		(end 353.855274 -284.52826)
		(width 0.0889)
		(layer "In11.Cu")
		(net "UPI_CPU1_CPU0_P2P2_DP<5>")
	)
	(arc
		(start 354.804218 -282.895548)
		(mid 355.0055 -282.698061)
		(end 355.086412 -282.427934)
		(width 0.0889)
		(layer "In11.Cu")
		(net "UPI_CPU1_CPU0_P2P2_DP<5>")
	)
	(arc
		(start 351.514918 -288.592768)
		(mid 351.717204 -288.393787)
		(end 351.797366 -288.121598)
		(width 0.0889)
		(layer "In11.Cu")
		(net "UPI_CPU1_CPU0_P2P2_DP<5>")
	)
	(arc
		(start 355.086666 -279.141682)
		(mid 355.138936 -278.959317)
		(end 355.273864 -278.82596)
		(width 0.0889)
		(layer "In11.Cu")
		(net "UPI_CPU1_CPU0_P2P2_DP<5>")
	)
	(arc
		(start 90.791792 -281.102562)
		(mid 90.587457 -281.305167)
		(end 90.509344 -281.582114)
		(width 0.0889)
		(layer "In11.Cu")
		(net "UPI_CPU1_CPU0_P2P2_DP<5>")
	)
	(arc
		(start 354.795328 -281.911298)
		(mid 354.616852 -281.59202)
		(end 354.795328 -281.272742)
		(width 0.0889)
		(layer "In11.Cu")
		(net "UPI_CPU1_CPU0_P2P2_DP<5>")
	)
	(arc
		(start 354.804218 -279.639776)
		(mid 355.008553 -279.437171)
		(end 355.086666 -279.160224)
		(width 0.0889)
		(layer "In11.Cu")
		(net "UPI_CPU1_CPU0_P2P2_DP<5>")
	)
	(arc
		(start 354.340414 -283.705808)
		(mid 354.542827 -283.499395)
		(end 354.616766 -283.219906)
		(width 0.0889)
		(layer "In11.Cu")
		(net "UPI_CPU1_CPU0_P2P2_DP<5>")
	)
	(arc
		(start 355.086412 -282.390342)
		(mid 355.007042 -282.116608)
		(end 354.804218 -281.916378)
		(width 0.0889)
		(layer "In11.Cu")
		(net "UPI_CPU1_CPU0_P2P2_DP<5>")
	)
	(arc
		(start 90.509344 -283.219906)
		(mid 90.461665 -283.402806)
		(end 90.330782 -283.539184)
		(width 0.0889)
		(layer "In11.Cu")
		(net "UPI_CPU1_CPU0_P2P2_DP<5>")
	)
	(arc
		(start 89.382092 -285.171896)
		(mid 89.177757 -285.374501)
		(end 89.099644 -285.651448)
		(width 0.0889)
		(layer "In11.Cu")
		(net "UPI_CPU1_CPU0_P2P2_DP<5>")
	)
	(arc
		(start 352.924618 -286.151066)
		(mid 353.127923 -285.9502)
		(end 353.207066 -285.675578)
		(width 0.0889)
		(layer "In11.Cu")
		(net "UPI_CPU1_CPU0_P2P2_DP<5>")
	)
	(arc
		(start 88.629744 -288.103056)
		(mid 88.629692 -288.110423)
		(end 88.62949 -288.117788)
		(width 0.0889)
		(layer "In11.Cu")
		(net "UPI_CPU1_CPU0_P2P2_DP<5>")
	)
	(arc
		(start 91.636088 -281.526488)
		(mid 91.63479 -281.515934)
		(end 91.633294 -281.505406)
		(width 0.0889)
		(layer "In11.Cu")
		(net "UPI_CPU1_CPU0_P2P2_DP<5>")
	)
	(arc
		(start 352.737166 -286.475424)
		(mid 352.784845 -286.292524)
		(end 352.915728 -286.156146)
		(width 0.0889)
		(layer "In11.Cu")
		(net "UPI_CPU1_CPU0_P2P2_DP<5>")
	)
	(arc
		(start 351.990914 -287.775142)
		(mid 352.193327 -287.568729)
		(end 352.267266 -287.28924)
		(width 0.0889)
		(layer "In11.Cu")
		(net "UPI_CPU1_CPU0_P2P2_DP<5>")
	)
	(arc
		(start 88.62949 -288.117788)
		(mid 88.578436 -288.292368)
		(end 88.451182 -288.422334)
		(width 0.0889)
		(layer "In11.Cu")
		(net "UPI_CPU1_CPU0_P2P2_DP<5>")
	)
	(arc
		(start 355.556566 -278.336502)
		(mid 355.556621 -278.329262)
		(end 355.55682 -278.322024)
		(width 0.0889)
		(layer "In11.Cu")
		(net "UPI_CPU1_CPU0_P2P2_DP<5>")
	)
	(arc
		(start 89.099644 -285.675578)
		(mid 89.178863 -285.950263)
		(end 89.382346 -286.151066)
		(width 0.0889)
		(layer "In11.Cu")
		(net "UPI_CPU1_CPU0_P2P2_DP<5>")
	)
	(arc
		(start 351.796858 -289.610292)
		(mid 351.685628 -289.417088)
		(end 351.511362 -289.27806)
		(width 0.0889)
		(layer "In11.Cu")
		(net "UPI_CPU1_CPU0_P2P2_DP<5>")
	)
	(arc
		(start 89.569544 -286.48406)
		(mid 89.517274 -286.666425)
		(end 89.382346 -286.799782)
		(width 0.0889)
		(layer "In11.Cu")
		(net "UPI_CPU1_CPU0_P2P2_DP<5>")
	)
	(arc
		(start 89.851992 -284.35808)
		(mid 89.647657 -284.560685)
		(end 89.569544 -284.837632)
		(width 0.0889)
		(layer "In11.Cu")
		(net "UPI_CPU1_CPU0_P2P2_DP<5>")
	)
	(arc
		(start 351.327466 -288.917126)
		(mid 351.375145 -288.734226)
		(end 351.506028 -288.597848)
		(width 0.0889)
		(layer "In11.Cu")
		(net "UPI_CPU1_CPU0_P2P2_DP<5>")
	)
	(arc
		(start 355.27996 -278.822404)
		(mid 355.482547 -278.616053)
		(end 355.556566 -278.336502)
		(width 0.0889)
		(layer "In11.Cu")
		(net "UPI_CPU1_CPU0_P2P2_DP<5>")
	)
	(arc
		(start 352.267266 -287.28924)
		(mid 352.314945 -287.10634)
		(end 352.445828 -286.969962)
		(width 0.0889)
		(layer "In11.Cu")
		(net "UPI_CPU1_CPU0_P2P2_DP<5>")
	)
	(arc
		(start 354.61702 -279.978866)
		(mid 354.616823 -279.971501)
		(end 354.616766 -279.964134)
		(width 0.0889)
		(layer "In11.Cu")
		(net "UPI_CPU1_CPU0_P2P2_DP<5>")
	)
	(arc
		(start 354.616766 -279.964134)
		(mid 354.664445 -279.781234)
		(end 354.795328 -279.644856)
		(width 0.0889)
		(layer "In11.Cu")
		(net "UPI_CPU1_CPU0_P2P2_DP<5>")
	)
	(arc
		(start 355.55682 -278.322024)
		(mid 355.596589 -278.168192)
		(end 355.69652 -278.044656)
		(width 0.0889)
		(layer "In11.Cu")
		(net "UPI_CPU1_CPU0_P2P2_DP<5>")
	)
	(arc
		(start 90.800936 -282.086558)
		(mid 90.979533 -282.405836)
		(end 90.800936 -282.725114)
		(width 0.0889)
		(layer "In11.Cu")
		(net "UPI_CPU1_CPU0_P2P2_DP<5>")
	)
	(arc
		(start 89.37625 -286.803338)
		(mid 89.173663 -287.009689)
		(end 89.099644 -287.28924)
		(width 0.0889)
		(layer "In11.Cu")
		(net "UPI_CPU1_CPU0_P2P2_DP<5>")
	)
	(arc
		(start 90.792046 -282.730194)
		(mid 90.588565 -282.930998)
		(end 90.509344 -283.205682)
		(width 0.0889)
		(layer "In11.Cu")
		(net "UPI_CPU1_CPU0_P2P2_DP<5>")
	)
	(arc
		(start 355.086412 -280.756106)
		(mid 355.005501 -280.485978)
		(end 354.804218 -280.288492)
		(width 0.0889)
		(layer "In11.Cu")
		(net "UPI_CPU1_CPU0_P2P2_DP<5>")
	)
	(arc
		(start 91.633294 -281.505406)
		(mid 91.541133 -281.272634)
		(end 91.35745 -281.102562)
		(width 0.0889)
		(layer "In11.Cu")
		(net "UPI_CPU1_CPU0_P2P2_DP<5>")
	)
	(arc
		(start 89.569544 -284.847538)
		(mid 89.521865 -285.030438)
		(end 89.390982 -285.166816)
		(width 0.0889)
		(layer "In11.Cu")
		(net "UPI_CPU1_CPU0_P2P2_DP<5>")
	)
	(arc
		(start 353.207066 -285.661354)
		(mid 353.254745 -285.478454)
		(end 353.385628 -285.342076)
		(width 0.0889)
		(layer "In11.Cu")
		(net "UPI_CPU1_CPU0_P2P2_DP<5>")
	)
	(arc
		(start 88.429338 -288.435796)
		(mid 88.232162 -288.641431)
		(end 88.160352 -288.917126)
		(width 0.0889)
		(layer "In11.Cu")
		(net "UPI_CPU1_CPU0_P2P2_DP<5>")
	)
	(arc
		(start 90.321892 -283.544264)
		(mid 90.117557 -283.746869)
		(end 90.039444 -284.023816)
		(width 0.0889)
		(layer "In11.Cu")
		(net "UPI_CPU1_CPU0_P2P2_DP<5>")
	)
	(arc
		(start 89.099644 -287.28924)
		(mid 89.051965 -287.47214)
		(end 88.921082 -287.608518)
		(width 0.0889)
		(layer "In11.Cu")
		(net "UPI_CPU1_CPU0_P2P2_DP<5>")
	)
	(arc
		(start 354.795328 -280.283412)
		(mid 354.668074 -280.153446)
		(end 354.61702 -279.978866)
		(width 0.0889)
		(layer "In11.Cu")
		(net "UPI_CPU1_CPU0_P2P2_DP<5>")
	)
	(arc
		(start 91.35745 -281.102562)
		(mid 91.080637 -281.026692)
		(end 90.802206 -281.096466)
		(width 0.0889)
		(layer "In11.Cu")
		(net "UPI_CPU1_CPU0_P2P2_DP<5>")
	)
	(arc
		(start 88.442292 -288.427414)
		(mid 88.435787 -288.431561)
		(end 88.429338 -288.435796)
		(width 0.0889)
		(layer "In11.Cu")
		(net "UPI_CPU1_CPU0_P2P2_DP<5>")
	)
	(arc
		(start 351.511616 -289.277806)
		(mid 351.402469 -289.193878)
		(end 351.327466 -289.078416)
		(width 0.0889)
		(layer "In11.Cu")
		(net "UPI_CPU1_CPU0_P2P2_DP<5>")
	)
	(segment
		(start 356.401116 -276.986492)
		(end 356.400862 -276.986746)
		(width 0.13208)
		(layer "F.Cu")
		(net "UPI_CPU1_CPU0_P2P2_DP<4>")
	)
	(segment
		(start 87.785194 -285.125414)
		(end 87.785194 -285.661354)
		(width 0.13208)
		(layer "F.Cu")
		(net "UPI_CPU1_CPU0_P2P2_DP<4>")
	)
	(segment
		(start 356.400862 -276.986746)
		(end 356.400862 -277.522432)
		(width 0.13208)
		(layer "F.Cu")
		(net "UPI_CPU1_CPU0_P2P2_DP<4>")
	)
	(segment
		(start 58.551064 -320.198242)
		(end 58.551064 -323.574918)
		(width 0.14732)
		(layer "In11.Cu")
		(net "UPI_CPU1_CPU0_P2P2_DP<4>")
	)
	(segment
		(start 352.546666 -288.103056)
		(end 352.546666 -288.09315)
		(width 0.0889)
		(layer "In11.Cu")
		(net "UPI_CPU1_CPU0_P2P2_DP<4>")
	)
	(segment
		(start 79.197962 -301.92853)
		(end 67.902328 -313.224164)
		(width 0.14732)
		(layer "In11.Cu")
		(net "UPI_CPU1_CPU0_P2P2_DP<4>")
	)
	(segment
		(start 87.941658 -285.390336)
		(end 87.920576 -285.312358)
		(width 0.0889)
		(layer "In11.Cu")
		(net "UPI_CPU1_CPU0_P2P2_DP<4>")
	)
	(segment
		(start 286.809942 -339.33257)
		(end 310.298846 -339.33257)
		(width 0.14732)
		(layer "In11.Cu")
		(net "UPI_CPU1_CPU0_P2P2_DP<4>")
	)
	(segment
		(start 58.551064 -323.574918)
		(end 58.389774 -323.964554)
		(width 0.14732)
		(layer "In11.Cu")
		(net "UPI_CPU1_CPU0_P2P2_DP<4>")
	)
	(segment
		(start 60.486544 -317.915544)
		(end 60.226194 -318.175894)
		(width 0.14732)
		(layer "In11.Cu")
		(net "UPI_CPU1_CPU0_P2P2_DP<4>")
	)
	(segment
		(start 145.23974 -389.35533)
		(end 161.167318 -389.35533)
		(width 0.14732)
		(layer "In11.Cu")
		(net "UPI_CPU1_CPU0_P2P2_DP<4>")
	)
	(segment
		(start 343.504266 -306.822094)
		(end 348.063566 -302.26254)
		(width 0.14732)
		(layer "In11.Cu")
		(net "UPI_CPU1_CPU0_P2P2_DP<4>")
	)
	(segment
		(start 144.12214 -389.35533)
		(end 144.55902 -389.35533)
		(width 0.14732)
		(layer "In11.Cu")
		(net "UPI_CPU1_CPU0_P2P2_DP<4>")
	)
	(segment
		(start 352.546412 -290.166298)
		(end 352.546412 -289.645852)
		(width 0.0889)
		(layer "In11.Cu")
		(net "UPI_CPU1_CPU0_P2P2_DP<4>")
	)
	(segment
		(start 79.679546 -301.446946)
		(end 79.679546 -301.619412)
		(width 0.14732)
		(layer "In11.Cu")
		(net "UPI_CPU1_CPU0_P2P2_DP<4>")
	)
	(segment
		(start 352.829114 -287.613598)
		(end 352.838004 -287.608518)
		(width 0.0889)
		(layer "In11.Cu")
		(net "UPI_CPU1_CPU0_P2P2_DP<4>")
	)
	(segment
		(start 80.160876 -301.138082)
		(end 79.98841 -301.138082)
		(width 0.14732)
		(layer "In11.Cu")
		(net "UPI_CPU1_CPU0_P2P2_DP<4>")
	)
	(segment
		(start 355.64826 -279.474676)
		(end 355.65715 -279.469596)
		(width 0.0889)
		(layer "In11.Cu")
		(net "UPI_CPU1_CPU0_P2P2_DP<4>")
	)
	(segment
		(start 355.172518 -283.54782)
		(end 355.172264 -283.548074)
		(width 0.0889)
		(layer "In11.Cu")
		(net "UPI_CPU1_CPU0_P2P2_DP<4>")
	)
	(segment
		(start 356.77094 -277.579836)
		(end 356.713536 -277.522432)
		(width 0.0889)
		(layer "In11.Cu")
		(net "UPI_CPU1_CPU0_P2P2_DP<4>")
	)
	(segment
		(start 356.114858 -278.662892)
		(end 356.117652 -278.661368)
		(width 0.0889)
		(layer "In11.Cu")
		(net "UPI_CPU1_CPU0_P2P2_DP<4>")
	)
	(segment
		(start 87.41029 -290.603686)
		(end 87.41029 -291.07003)
		(width 0.0889)
		(layer "In11.Cu")
		(net "UPI_CPU1_CPU0_P2P2_DP<4>")
	)
	(segment
		(start 60.034678 -335.789524)
		(end 60.034678 -355.529134)
		(width 0.14732)
		(layer "In11.Cu")
		(net "UPI_CPU1_CPU0_P2P2_DP<4>")
	)
	(segment
		(start 59.760866 -318.641222)
		(end 58.796428 -319.60566)
		(width 0.14732)
		(layer "In11.Cu")
		(net "UPI_CPU1_CPU0_P2P2_DP<4>")
	)
	(segment
		(start 354.895912 -284.042358)
		(end 354.895912 -284.033722)
		(width 0.0889)
		(layer "In11.Cu")
		(net "UPI_CPU1_CPU0_P2P2_DP<4>")
	)
	(segment
		(start 355.65715 -282.086558)
		(end 355.649276 -282.081986)
		(width 0.0889)
		(layer "In11.Cu")
		(net "UPI_CPU1_CPU0_P2P2_DP<4>")
	)
	(segment
		(start 87.584534 -288.600642)
		(end 87.58301 -288.601404)
		(width 0.0889)
		(layer "In11.Cu")
		(net "UPI_CPU1_CPU0_P2P2_DP<4>")
	)
	(segment
		(start 352.504502 -290.397184)
		(end 352.504502 -290.230306)
		(width 0.14732)
		(layer "In11.Cu")
		(net "UPI_CPU1_CPU0_P2P2_DP<4>")
	)
	(segment
		(start 352.359214 -288.427414)
		(end 352.368104 -288.422334)
		(width 0.0889)
		(layer "In11.Cu")
		(net "UPI_CPU1_CPU0_P2P2_DP<4>")
	)
	(segment
		(start 355.65715 -280.458926)
		(end 355.64826 -280.453846)
		(width 0.0889)
		(layer "In11.Cu")
		(net "UPI_CPU1_CPU0_P2P2_DP<4>")
	)
	(segment
		(start 349.507048 -299.882814)
		(end 349.750126 -299.51934)
		(width 0.14732)
		(layer "In11.Cu")
		(net "UPI_CPU1_CPU0_P2P2_DP<4>")
	)
	(segment
		(start 87.41029 -290.049966)
		(end 87.41029 -290.227766)
		(width 0.0889)
		(layer "In11.Cu")
		(net "UPI_CPU1_CPU0_P2P2_DP<4>")
	)
	(segment
		(start 87.41029 -289.120326)
		(end 87.50935 -289.219386)
		(width 0.0889)
		(layer "In11.Cu")
		(net "UPI_CPU1_CPU0_P2P2_DP<4>")
	)
	(segment
		(start 79.370428 -301.92853)
		(end 79.197962 -301.92853)
		(width 0.14732)
		(layer "In11.Cu")
		(net "UPI_CPU1_CPU0_P2P2_DP<4>")
	)
	(segment
		(start 87.41029 -289.674046)
		(end 87.50935 -289.773106)
		(width 0.0889)
		(layer "In11.Cu")
		(net "UPI_CPU1_CPU0_P2P2_DP<4>")
	)
	(segment
		(start 350.816164 -292.085522)
		(end 352.504502 -290.397184)
		(width 0.14732)
		(layer "In11.Cu")
		(net "UPI_CPU1_CPU0_P2P2_DP<4>")
	)
	(segment
		(start 71.745348 -375.005854)
		(end 94.8309 -384.568192)
		(width 0.14732)
		(layer "In11.Cu")
		(net "UPI_CPU1_CPU0_P2P2_DP<4>")
	)
	(segment
		(start 87.50935 -289.950906)
		(end 87.41029 -290.049966)
		(width 0.0889)
		(layer "In11.Cu")
		(net "UPI_CPU1_CPU0_P2P2_DP<4>")
	)
	(segment
		(start 88.067896 -287.778698)
		(end 88.059006 -287.783778)
		(width 0.0889)
		(layer "In11.Cu")
		(net "UPI_CPU1_CPU0_P2P2_DP<4>")
	)
	(segment
		(start 349.29826 -300.415198)
		(end 349.54083 -300.051978)
		(width 0.14732)
		(layer "In11.Cu")
		(net "UPI_CPU1_CPU0_P2P2_DP<4>")
	)
	(segment
		(start 59.96559 -318.641222)
		(end 59.760866 -318.641222)
		(width 0.14732)
		(layer "In11.Cu")
		(net "UPI_CPU1_CPU0_P2P2_DP<4>")
	)
	(segment
		(start 87.50935 -289.773106)
		(end 87.50935 -289.950906)
		(width 0.0889)
		(layer "In11.Cu")
		(net "UPI_CPU1_CPU0_P2P2_DP<4>")
	)
	(segment
		(start 144.68094 -389.23341)
		(end 145.11782 -389.23341)
		(width 0.14732)
		(layer "In11.Cu")
		(net "UPI_CPU1_CPU0_P2P2_DP<4>")
	)
	(segment
		(start 61.468762 -316.933072)
		(end 60.951872 -317.449962)
		(width 0.14732)
		(layer "In11.Cu")
		(net "UPI_CPU1_CPU0_P2P2_DP<4>")
	)
	(segment
		(start 356.305612 -278.345138)
		(end 356.305612 -278.31796)
		(width 0.0889)
		(layer "In11.Cu")
		(net "UPI_CPU1_CPU0_P2P2_DP<4>")
	)
	(segment
		(start 356.114096 -278.6634)
		(end 356.114858 -278.662892)
		(width 0.0889)
		(layer "In11.Cu")
		(net "UPI_CPU1_CPU0_P2P2_DP<4>")
	)
	(segment
		(start 87.597996 -288.592768)
		(end 87.584534 -288.600642)
		(width 0.0889)
		(layer "In11.Cu")
		(net "UPI_CPU1_CPU0_P2P2_DP<4>")
	)
	(segment
		(start 87.50935 -289.397186)
		(end 87.41029 -289.496246)
		(width 0.0889)
		(layer "In11.Cu")
		(net "UPI_CPU1_CPU0_P2P2_DP<4>")
	)
	(segment
		(start 82.999834 -298.126658)
		(end 80.469994 -300.656498)
		(width 0.14732)
		(layer "In11.Cu")
		(net "UPI_CPU1_CPU0_P2P2_DP<4>")
	)
	(segment
		(start 350.40443 -298.54017)
		(end 350.573594 -298.506642)
		(width 0.14732)
		(layer "In11.Cu")
		(net "UPI_CPU1_CPU0_P2P2_DP<4>")
	)
	(segment
		(start 339.597238 -308.440582)
		(end 343.504266 -306.822094)
		(width 0.14732)
		(layer "In11.Cu")
		(net "UPI_CPU1_CPU0_P2P2_DP<4>")
	)
	(segment
		(start 87.41029 -288.917126)
		(end 87.41029 -289.120326)
		(width 0.0889)
		(layer "In11.Cu")
		(net "UPI_CPU1_CPU0_P2P2_DP<4>")
	)
	(segment
		(start 87.50935 -289.219386)
		(end 87.50935 -289.397186)
		(width 0.0889)
		(layer "In11.Cu")
		(net "UPI_CPU1_CPU0_P2P2_DP<4>")
	)
	(segment
		(start 84.828126 -293.712138)
		(end 82.999834 -298.126658)
		(width 0.14732)
		(layer "In11.Cu")
		(net "UPI_CPU1_CPU0_P2P2_DP<4>")
	)
	(segment
		(start 127.100838 -389.35533)
		(end 142.32382 -389.35533)
		(width 0.14732)
		(layer "In11.Cu")
		(net "UPI_CPU1_CPU0_P2P2_DP<4>")
	)
	(segment
		(start 276.08276 -369.089178)
		(end 276.08276 -348.414594)
		(width 0.14732)
		(layer "In11.Cu")
		(net "UPI_CPU1_CPU0_P2P2_DP<4>")
	)
	(segment
		(start 61.46927 -316.932818)
		(end 61.468762 -316.933072)
		(width 0.14732)
		(layer "In11.Cu")
		(net "UPI_CPU1_CPU0_P2P2_DP<4>")
	)
	(segment
		(start 67.902328 -313.224164)
		(end 65.471548 -314.230766)
		(width 0.14732)
		(layer "In11.Cu")
		(net "UPI_CPU1_CPU0_P2P2_DP<4>")
	)
	(segment
		(start 355.366066 -283.219906)
		(end 355.366066 -283.197808)
		(width 0.0889)
		(layer "In11.Cu")
		(net "UPI_CPU1_CPU0_P2P2_DP<4>")
	)
	(segment
		(start 62.780672 -362.158026)
		(end 62.780672 -362.15828)
		(width 0.14732)
		(layer "In11.Cu")
		(net "UPI_CPU1_CPU0_P2P2_DP<4>")
	)
	(segment
		(start 145.11782 -389.23341)
		(end 145.23974 -389.35533)
		(width 0.14732)
		(layer "In11.Cu")
		(net "UPI_CPU1_CPU0_P2P2_DP<4>")
	)
	(segment
		(start 65.526412 -368.786918)
		(end 71.745348 -375.005854)
		(width 0.14732)
		(layer "In11.Cu")
		(net "UPI_CPU1_CPU0_P2P2_DP<4>")
	)
	(segment
		(start 355.649276 -281.102054)
		(end 355.65715 -281.097482)
		(width 0.0889)
		(layer "In11.Cu")
		(net "UPI_CPU1_CPU0_P2P2_DP<4>")
	)
	(segment
		(start 356.112318 -278.664416)
		(end 356.11308 -278.663908)
		(width 0.0889)
		(layer "In11.Cu")
		(net "UPI_CPU1_CPU0_P2P2_DP<4>")
	)
	(segment
		(start 310.298846 -339.33257)
		(end 319.630298 -330.001118)
		(width 0.14732)
		(layer "In11.Cu")
		(net "UPI_CPU1_CPU0_P2P2_DP<4>")
	)
	(segment
		(start 354.704396 -284.36062)
		(end 354.705158 -284.360112)
		(width 0.0889)
		(layer "In11.Cu")
		(net "UPI_CPU1_CPU0_P2P2_DP<4>")
	)
	(segment
		(start 354.70338 -284.361128)
		(end 354.704396 -284.36062)
		(width 0.0889)
		(layer "In11.Cu")
		(net "UPI_CPU1_CPU0_P2P2_DP<4>")
	)
	(segment
		(start 142.88262 -389.23341)
		(end 143.00454 -389.35533)
		(width 0.14732)
		(layer "In11.Cu")
		(net "UPI_CPU1_CPU0_P2P2_DP<4>")
	)
	(segment
		(start 57.71388 -324.640448)
		(end 57.71388 -330.182982)
		(width 0.14732)
		(layer "In11.Cu")
		(net "UPI_CPU1_CPU0_P2P2_DP<4>")
	)
	(segment
		(start 264.545826 -380.626112)
		(end 276.08276 -369.089178)
		(width 0.14732)
		(layer "In11.Cu")
		(net "UPI_CPU1_CPU0_P2P2_DP<4>")
	)
	(segment
		(start 64.262762 -315.439552)
		(end 62.830202 -316.205362)
		(width 0.14732)
		(layer "In11.Cu")
		(net "UPI_CPU1_CPU0_P2P2_DP<4>")
	)
	(segment
		(start 88.350344 -287.28924)
		(end 88.350344 -287.299146)
		(width 0.0889)
		(layer "In11.Cu")
		(net "UPI_CPU1_CPU0_P2P2_DP<4>")
	)
	(segment
		(start 356.58806 -277.84679)
		(end 356.59695 -277.84171)
		(width 0.0889)
		(layer "In11.Cu")
		(net "UPI_CPU1_CPU0_P2P2_DP<4>")
	)
	(segment
		(start 352.076766 -289.114738)
		(end 352.076766 -288.898584)
		(width 0.0889)
		(layer "In11.Cu")
		(net "UPI_CPU1_CPU0_P2P2_DP<4>")
	)
	(segment
		(start 87.41029 -291.07003)
		(end 87.059008 -291.421312)
		(width 0.0889)
		(layer "In11.Cu")
		(net "UPI_CPU1_CPU0_P2P2_DP<4>")
	)
	(segment
		(start 354.707952 -284.358588)
		(end 354.708714 -284.35808)
		(width 0.0889)
		(layer "In11.Cu")
		(net "UPI_CPU1_CPU0_P2P2_DP<4>")
	)
	(segment
		(start 62.780672 -362.15828)
		(end 65.526412 -368.786918)
		(width 0.14732)
		(layer "In11.Cu")
		(net "UPI_CPU1_CPU0_P2P2_DP<4>")
	)
	(segment
		(start 87.043514 -291.49675)
		(end 84.828126 -293.712138)
		(width 0.14732)
		(layer "In11.Cu")
		(net "UPI_CPU1_CPU0_P2P2_DP<4>")
	)
	(segment
		(start 87.880444 -288.103056)
		(end 87.880444 -288.121598)
		(width 0.0889)
		(layer "In11.Cu")
		(net "UPI_CPU1_CPU0_P2P2_DP<4>")
	)
	(segment
		(start 87.50935 -290.326826)
		(end 87.50935 -290.504626)
		(width 0.0889)
		(layer "In11.Cu")
		(net "UPI_CPU1_CPU0_P2P2_DP<4>")
	)
	(segment
		(start 80.469994 -300.656498)
		(end 80.469994 -300.828964)
		(width 0.14732)
		(layer "In11.Cu")
		(net "UPI_CPU1_CPU0_P2P2_DP<4>")
	)
	(segment
		(start 353.956366 -285.661354)
		(end 353.956366 -285.64586)
		(width 0.0889)
		(layer "In11.Cu")
		(net "UPI_CPU1_CPU0_P2P2_DP<4>")
	)
	(segment
		(start 161.167318 -389.35533)
		(end 264.545826 -380.626112)
		(width 0.14732)
		(layer "In11.Cu")
		(net "UPI_CPU1_CPU0_P2P2_DP<4>")
	)
	(segment
		(start 355.649276 -282.081986)
		(end 355.64826 -282.081478)
		(width 0.0889)
		(layer "In11.Cu")
		(net "UPI_CPU1_CPU0_P2P2_DP<4>")
	)
	(segment
		(start 353.768914 -285.985712)
		(end 353.777804 -285.980632)
		(width 0.0889)
		(layer "In11.Cu")
		(net "UPI_CPU1_CPU0_P2P2_DP<4>")
	)
	(segment
		(start 142.32382 -389.35533)
		(end 142.44574 -389.23341)
		(width 0.14732)
		(layer "In11.Cu")
		(net "UPI_CPU1_CPU0_P2P2_DP<4>")
	)
	(segment
		(start 58.796428 -319.60566)
		(end 58.551064 -320.198242)
		(width 0.14732)
		(layer "In11.Cu")
		(net "UPI_CPU1_CPU0_P2P2_DP<4>")
	)
	(segment
		(start 355.64826 -282.730194)
		(end 355.65715 -282.725114)
		(width 0.0889)
		(layer "In11.Cu")
		(net "UPI_CPU1_CPU0_P2P2_DP<4>")
	)
	(segment
		(start 355.366066 -281.607514)
		(end 355.366066 -281.576526)
		(width 0.0889)
		(layer "In11.Cu")
		(net "UPI_CPU1_CPU0_P2P2_DP<4>")
	)
	(segment
		(start 94.8309 -384.568192)
		(end 127.100838 -389.35533)
		(width 0.14732)
		(layer "In11.Cu")
		(net "UPI_CPU1_CPU0_P2P2_DP<4>")
	)
	(segment
		(start 353.016566 -287.28924)
		(end 353.016566 -287.279334)
		(width 0.0889)
		(layer "In11.Cu")
		(net "UPI_CPU1_CPU0_P2P2_DP<4>")
	)
	(segment
		(start 79.679546 -301.619412)
		(end 79.370428 -301.92853)
		(width 0.14732)
		(layer "In11.Cu")
		(net "UPI_CPU1_CPU0_P2P2_DP<4>")
	)
	(segment
		(start 349.91929 -299.485558)
		(end 350.195134 -299.072808)
		(width 0.14732)
		(layer "In11.Cu")
		(net "UPI_CPU1_CPU0_P2P2_DP<4>")
	)
	(segment
		(start 355.64826 -281.102562)
		(end 355.649276 -281.102054)
		(width 0.0889)
		(layer "In11.Cu")
		(net "UPI_CPU1_CPU0_P2P2_DP<4>")
	)
	(segment
		(start 355.180138 -283.543502)
		(end 355.187504 -283.539184)
		(width 0.0889)
		(layer "In11.Cu")
		(net "UPI_CPU1_CPU0_P2P2_DP<4>")
	)
	(segment
		(start 356.11308 -278.663908)
		(end 356.114096 -278.6634)
		(width 0.0889)
		(layer "In11.Cu")
		(net "UPI_CPU1_CPU0_P2P2_DP<4>")
	)
	(segment
		(start 57.71388 -330.182982)
		(end 60.034678 -335.789524)
		(width 0.14732)
		(layer "In11.Cu")
		(net "UPI_CPU1_CPU0_P2P2_DP<4>")
	)
	(segment
		(start 319.630298 -330.001118)
		(end 320.756788 -327.281032)
		(width 0.14732)
		(layer "In11.Cu")
		(net "UPI_CPU1_CPU0_P2P2_DP<4>")
	)
	(segment
		(start 87.059008 -291.481256)
		(end 87.043514 -291.49675)
		(width 0.0889)
		(layer "In11.Cu")
		(net "UPI_CPU1_CPU0_P2P2_DP<4>")
	)
	(segment
		(start 87.50935 -290.504626)
		(end 87.41029 -290.603686)
		(width 0.0889)
		(layer "In11.Cu")
		(net "UPI_CPU1_CPU0_P2P2_DP<4>")
	)
	(segment
		(start 349.129096 -300.448726)
		(end 349.29826 -300.415198)
		(width 0.14732)
		(layer "In11.Cu")
		(net "UPI_CPU1_CPU0_P2P2_DP<4>")
	)
	(segment
		(start 62.830202 -316.205362)
		(end 62.829948 -316.205616)
		(width 0.14732)
		(layer "In11.Cu")
		(net "UPI_CPU1_CPU0_P2P2_DP<4>")
	)
	(segment
		(start 276.08276 -348.414594)
		(end 284.001464 -340.49589)
		(width 0.14732)
		(layer "In11.Cu")
		(net "UPI_CPU1_CPU0_P2P2_DP<4>")
	)
	(segment
		(start 355.178614 -283.544264)
		(end 355.180138 -283.543502)
		(width 0.0889)
		(layer "In11.Cu")
		(net "UPI_CPU1_CPU0_P2P2_DP<4>")
	)
	(segment
		(start 320.756788 -327.281032)
		(end 339.597238 -308.440582)
		(width 0.14732)
		(layer "In11.Cu")
		(net "UPI_CPU1_CPU0_P2P2_DP<4>")
	)
	(segment
		(start 144.55902 -389.35533)
		(end 144.68094 -389.23341)
		(width 0.14732)
		(layer "In11.Cu")
		(net "UPI_CPU1_CPU0_P2P2_DP<4>")
	)
	(segment
		(start 352.504502 -290.230306)
		(end 352.504502 -290.208208)
		(width 0.0889)
		(layer "In11.Cu")
		(net "UPI_CPU1_CPU0_P2P2_DP<4>")
	)
	(segment
		(start 60.951872 -317.449962)
		(end 60.951872 -317.65494)
		(width 0.14732)
		(layer "In11.Cu")
		(net "UPI_CPU1_CPU0_P2P2_DP<4>")
	)
	(segment
		(start 60.226194 -318.380618)
		(end 59.96559 -318.641222)
		(width 0.14732)
		(layer "In11.Cu")
		(net "UPI_CPU1_CPU0_P2P2_DP<4>")
	)
	(segment
		(start 87.597996 -285.336996)
		(end 87.589106 -285.342076)
		(width 0.0889)
		(layer "In11.Cu")
		(net "UPI_CPU1_CPU0_P2P2_DP<4>")
	)
	(segment
		(start 354.705158 -284.360112)
		(end 354.707952 -284.358588)
		(width 0.0889)
		(layer "In11.Cu")
		(net "UPI_CPU1_CPU0_P2P2_DP<4>")
	)
	(segment
		(start 87.785194 -285.661354)
		(end 87.941658 -285.390336)
		(width 0.0889)
		(layer "In11.Cu")
		(net "UPI_CPU1_CPU0_P2P2_DP<4>")
	)
	(segment
		(start 87.589106 -285.980632)
		(end 87.597996 -285.985712)
		(width 0.0889)
		(layer "In11.Cu")
		(net "UPI_CPU1_CPU0_P2P2_DP<4>")
	)
	(segment
		(start 87.41029 -290.227766)
		(end 87.50935 -290.326826)
		(width 0.0889)
		(layer "In11.Cu")
		(net "UPI_CPU1_CPU0_P2P2_DP<4>")
	)
	(segment
		(start 58.389774 -323.964554)
		(end 57.71388 -324.640448)
		(width 0.14732)
		(layer "In11.Cu")
		(net "UPI_CPU1_CPU0_P2P2_DP<4>")
	)
	(segment
		(start 143.56334 -389.23341)
		(end 144.00022 -389.23341)
		(width 0.14732)
		(layer "In11.Cu")
		(net "UPI_CPU1_CPU0_P2P2_DP<4>")
	)
	(segment
		(start 356.713536 -277.522432)
		(end 356.400862 -277.522432)
		(width 0.0889)
		(layer "In11.Cu")
		(net "UPI_CPU1_CPU0_P2P2_DP<4>")
	)
	(segment
		(start 87.059008 -291.421312)
		(end 87.059008 -291.481256)
		(width 0.0889)
		(layer "In11.Cu")
		(net "UPI_CPU1_CPU0_P2P2_DP<4>")
	)
	(segment
		(start 142.44574 -389.23341)
		(end 142.88262 -389.23341)
		(width 0.14732)
		(layer "In11.Cu")
		(net "UPI_CPU1_CPU0_P2P2_DP<4>")
	)
	(segment
		(start 60.226194 -318.175894)
		(end 60.226194 -318.380618)
		(width 0.14732)
		(layer "In11.Cu")
		(net "UPI_CPU1_CPU0_P2P2_DP<4>")
	)
	(segment
		(start 350.195134 -299.072808)
		(end 350.161352 -298.903644)
		(width 0.14732)
		(layer "In11.Cu")
		(net "UPI_CPU1_CPU0_P2P2_DP<4>")
	)
	(segment
		(start 348.9198 -300.981364)
		(end 348.886018 -300.8122)
		(width 0.14732)
		(layer "In11.Cu")
		(net "UPI_CPU1_CPU0_P2P2_DP<4>")
	)
	(segment
		(start 88.549988 -286.95777)
		(end 88.537796 -286.964882)
		(width 0.0889)
		(layer "In11.Cu")
		(net "UPI_CPU1_CPU0_P2P2_DP<4>")
	)
	(segment
		(start 60.951872 -317.65494)
		(end 60.691268 -317.915544)
		(width 0.14732)
		(layer "In11.Cu")
		(net "UPI_CPU1_CPU0_P2P2_DP<4>")
	)
	(segment
		(start 355.172264 -283.548074)
		(end 355.178614 -283.544264)
		(width 0.0889)
		(layer "In11.Cu")
		(net "UPI_CPU1_CPU0_P2P2_DP<4>")
	)
	(segment
		(start 88.820498 -286.467804)
		(end 88.820498 -286.475424)
		(width 0.0889)
		(layer "In11.Cu")
		(net "UPI_CPU1_CPU0_P2P2_DP<4>")
	)
	(segment
		(start 354.702618 -284.361636)
		(end 354.70338 -284.361128)
		(width 0.0889)
		(layer "In11.Cu")
		(net "UPI_CPU1_CPU0_P2P2_DP<4>")
	)
	(segment
		(start 62.829948 -316.205616)
		(end 61.46927 -316.932818)
		(width 0.14732)
		(layer "In11.Cu")
		(net "UPI_CPU1_CPU0_P2P2_DP<4>")
	)
	(segment
		(start 79.98841 -301.138082)
		(end 79.679546 -301.446946)
		(width 0.14732)
		(layer "In11.Cu")
		(net "UPI_CPU1_CPU0_P2P2_DP<4>")
	)
	(segment
		(start 284.001464 -340.49589)
		(end 286.809942 -339.33257)
		(width 0.14732)
		(layer "In11.Cu")
		(net "UPI_CPU1_CPU0_P2P2_DP<4>")
	)
	(segment
		(start 350.573594 -298.506642)
		(end 350.816164 -298.143422)
		(width 0.14732)
		(layer "In11.Cu")
		(net "UPI_CPU1_CPU0_P2P2_DP<4>")
	)
	(segment
		(start 349.54083 -300.051978)
		(end 349.507048 -299.882814)
		(width 0.14732)
		(layer "In11.Cu")
		(net "UPI_CPU1_CPU0_P2P2_DP<4>")
	)
	(segment
		(start 352.504502 -290.208208)
		(end 352.546412 -290.166298)
		(width 0.0889)
		(layer "In11.Cu")
		(net "UPI_CPU1_CPU0_P2P2_DP<4>")
	)
	(segment
		(start 60.691268 -317.915544)
		(end 60.486544 -317.915544)
		(width 0.14732)
		(layer "In11.Cu")
		(net "UPI_CPU1_CPU0_P2P2_DP<4>")
	)
	(segment
		(start 348.886018 -300.8122)
		(end 349.129096 -300.448726)
		(width 0.14732)
		(layer "In11.Cu")
		(net "UPI_CPU1_CPU0_P2P2_DP<4>")
	)
	(segment
		(start 65.471548 -314.230766)
		(end 64.262762 -315.439552)
		(width 0.14732)
		(layer "In11.Cu")
		(net "UPI_CPU1_CPU0_P2P2_DP<4>")
	)
	(segment
		(start 88.537796 -286.964882)
		(end 88.528906 -286.969962)
		(width 0.0889)
		(layer "In11.Cu")
		(net "UPI_CPU1_CPU0_P2P2_DP<4>")
	)
	(segment
		(start 87.41029 -289.496246)
		(end 87.41029 -289.674046)
		(width 0.0889)
		(layer "In11.Cu")
		(net "UPI_CPU1_CPU0_P2P2_DP<4>")
	)
	(segment
		(start 350.816164 -298.143422)
		(end 350.816164 -292.085522)
		(width 0.14732)
		(layer "In11.Cu")
		(net "UPI_CPU1_CPU0_P2P2_DP<4>")
	)
	(segment
		(start 348.063566 -302.26254)
		(end 348.9198 -300.981364)
		(width 0.14732)
		(layer "In11.Cu")
		(net "UPI_CPU1_CPU0_P2P2_DP<4>")
	)
	(segment
		(start 80.469994 -300.828964)
		(end 80.160876 -301.138082)
		(width 0.14732)
		(layer "In11.Cu")
		(net "UPI_CPU1_CPU0_P2P2_DP<4>")
	)
	(segment
		(start 350.161352 -298.903644)
		(end 350.40443 -298.54017)
		(width 0.14732)
		(layer "In11.Cu")
		(net "UPI_CPU1_CPU0_P2P2_DP<4>")
	)
	(segment
		(start 356.117652 -278.661368)
		(end 356.118414 -278.66086)
		(width 0.0889)
		(layer "In11.Cu")
		(net "UPI_CPU1_CPU0_P2P2_DP<4>")
	)
	(segment
		(start 60.034678 -355.529134)
		(end 62.780672 -362.158026)
		(width 0.14732)
		(layer "In11.Cu")
		(net "UPI_CPU1_CPU0_P2P2_DP<4>")
	)
	(segment
		(start 144.00022 -389.23341)
		(end 144.12214 -389.35533)
		(width 0.14732)
		(layer "In11.Cu")
		(net "UPI_CPU1_CPU0_P2P2_DP<4>")
	)
	(segment
		(start 349.750126 -299.51934)
		(end 349.91929 -299.485558)
		(width 0.14732)
		(layer "In11.Cu")
		(net "UPI_CPU1_CPU0_P2P2_DP<4>")
	)
	(segment
		(start 353.486212 -286.48406)
		(end 353.486212 -286.4612)
		(width 0.0889)
		(layer "In11.Cu")
		(net "UPI_CPU1_CPU0_P2P2_DP<4>")
	)
	(segment
		(start 143.44142 -389.35533)
		(end 143.56334 -389.23341)
		(width 0.14732)
		(layer "In11.Cu")
		(net "UPI_CPU1_CPU0_P2P2_DP<4>")
	)
	(segment
		(start 143.00454 -389.35533)
		(end 143.44142 -389.35533)
		(width 0.14732)
		(layer "In11.Cu")
		(net "UPI_CPU1_CPU0_P2P2_DP<4>")
	)
	(segment
		(start 354.23856 -285.171896)
		(end 354.24745 -285.166816)
		(width 0.0889)
		(layer "In11.Cu")
		(net "UPI_CPU1_CPU0_P2P2_DP<4>")
	)
	(arc
		(start 87.589106 -285.342076)
		(mid 87.459817 -285.475562)
		(end 87.410544 -285.65475)
		(width 0.0889)
		(layer "In11.Cu")
		(net "UPI_CPU1_CPU0_P2P2_DP<4>")
	)
	(arc
		(start 354.708714 -284.35808)
		(mid 354.843647 -284.224726)
		(end 354.895912 -284.042358)
		(width 0.0889)
		(layer "In11.Cu")
		(net "UPI_CPU1_CPU0_P2P2_DP<4>")
	)
	(arc
		(start 88.059006 -287.783778)
		(mid 87.928092 -287.920138)
		(end 87.880444 -288.103056)
		(width 0.0889)
		(layer "In11.Cu")
		(net "UPI_CPU1_CPU0_P2P2_DP<4>")
	)
	(arc
		(start 352.368104 -288.422334)
		(mid 352.499018 -288.285974)
		(end 352.546666 -288.103056)
		(width 0.0889)
		(layer "In11.Cu")
		(net "UPI_CPU1_CPU0_P2P2_DP<4>")
	)
	(arc
		(start 355.187504 -283.539184)
		(mid 355.318418 -283.402824)
		(end 355.366066 -283.219906)
		(width 0.0889)
		(layer "In11.Cu")
		(net "UPI_CPU1_CPU0_P2P2_DP<4>")
	)
	(arc
		(start 87.597996 -285.985712)
		(mid 87.785194 -286.035855)
		(end 87.972392 -285.985712)
		(width 0.0889)
		(layer "In11.Cu")
		(net "UPI_CPU1_CPU0_P2P2_DP<4>")
	)
	(arc
		(start 356.305612 -278.31796)
		(mid 356.385774 -278.045771)
		(end 356.58806 -277.84679)
		(width 0.0889)
		(layer "In11.Cu")
		(net "UPI_CPU1_CPU0_P2P2_DP<4>")
	)
	(arc
		(start 352.546666 -288.09315)
		(mid 352.624777 -287.816201)
		(end 352.829114 -287.613598)
		(width 0.0889)
		(layer "In11.Cu")
		(net "UPI_CPU1_CPU0_P2P2_DP<4>")
	)
	(arc
		(start 87.880444 -288.121598)
		(mid 87.800282 -288.393787)
		(end 87.597996 -288.592768)
		(width 0.0889)
		(layer "In11.Cu")
		(net "UPI_CPU1_CPU0_P2P2_DP<4>")
	)
	(arc
		(start 355.65715 -281.097482)
		(mid 355.835747 -280.778204)
		(end 355.65715 -280.458926)
		(width 0.0889)
		(layer "In11.Cu")
		(net "UPI_CPU1_CPU0_P2P2_DP<4>")
	)
	(arc
		(start 355.835712 -279.150318)
		(mid 355.909703 -278.870752)
		(end 356.112318 -278.664416)
		(width 0.0889)
		(layer "In11.Cu")
		(net "UPI_CPU1_CPU0_P2P2_DP<4>")
	)
	(arc
		(start 87.410798 -285.673546)
		(mid 87.461291 -285.849524)
		(end 87.589106 -285.980632)
		(width 0.0889)
		(layer "In11.Cu")
		(net "UPI_CPU1_CPU0_P2P2_DP<4>")
	)
	(arc
		(start 353.777804 -285.980632)
		(mid 353.908718 -285.844272)
		(end 353.956366 -285.661354)
		(width 0.0889)
		(layer "In11.Cu")
		(net "UPI_CPU1_CPU0_P2P2_DP<4>")
	)
	(arc
		(start 87.972392 -285.985712)
		(mid 88.255094 -285.90997)
		(end 88.537796 -285.985712)
		(width 0.0889)
		(layer "In11.Cu")
		(net "UPI_CPU1_CPU0_P2P2_DP<4>")
	)
	(arc
		(start 353.486212 -286.4612)
		(mid 353.565431 -286.186515)
		(end 353.768914 -285.985712)
		(width 0.0889)
		(layer "In11.Cu")
		(net "UPI_CPU1_CPU0_P2P2_DP<4>")
	)
	(arc
		(start 354.895912 -284.033722)
		(mid 354.969903 -283.754156)
		(end 355.172518 -283.54782)
		(width 0.0889)
		(layer "In11.Cu")
		(net "UPI_CPU1_CPU0_P2P2_DP<4>")
	)
	(arc
		(start 352.546412 -289.645852)
		(mid 352.471407 -289.530393)
		(end 352.362262 -289.446462)
		(width 0.0889)
		(layer "In11.Cu")
		(net "UPI_CPU1_CPU0_P2P2_DP<4>")
	)
	(arc
		(start 356.59695 -277.84171)
		(mid 356.712689 -277.729886)
		(end 356.77094 -277.579836)
		(width 0.0889)
		(layer "In11.Cu")
		(net "UPI_CPU1_CPU0_P2P2_DP<4>")
	)
	(arc
		(start 356.118414 -278.66086)
		(mid 356.253347 -278.527506)
		(end 356.305612 -278.345138)
		(width 0.0889)
		(layer "In11.Cu")
		(net "UPI_CPU1_CPU0_P2P2_DP<4>")
	)
	(arc
		(start 87.58301 -288.601404)
		(mid 87.456287 -288.737185)
		(end 87.41029 -288.917126)
		(width 0.0889)
		(layer "In11.Cu")
		(net "UPI_CPU1_CPU0_P2P2_DP<4>")
	)
	(arc
		(start 352.076766 -288.898584)
		(mid 352.156928 -288.626395)
		(end 352.359214 -288.427414)
		(width 0.0889)
		(layer "In11.Cu")
		(net "UPI_CPU1_CPU0_P2P2_DP<4>")
	)
	(arc
		(start 353.299014 -286.799782)
		(mid 353.433947 -286.666428)
		(end 353.486212 -286.48406)
		(width 0.0889)
		(layer "In11.Cu")
		(net "UPI_CPU1_CPU0_P2P2_DP<4>")
	)
	(arc
		(start 354.426012 -284.847538)
		(mid 354.500003 -284.567972)
		(end 354.702618 -284.361636)
		(width 0.0889)
		(layer "In11.Cu")
		(net "UPI_CPU1_CPU0_P2P2_DP<4>")
	)
	(arc
		(start 352.838004 -287.608518)
		(mid 352.968918 -287.472158)
		(end 353.016566 -287.28924)
		(width 0.0889)
		(layer "In11.Cu")
		(net "UPI_CPU1_CPU0_P2P2_DP<4>")
	)
	(arc
		(start 88.537796 -285.985712)
		(mid 88.742868 -286.189391)
		(end 88.820498 -286.467804)
		(width 0.0889)
		(layer "In11.Cu")
		(net "UPI_CPU1_CPU0_P2P2_DP<4>")
	)
	(arc
		(start 353.956366 -285.64586)
		(mid 354.035736 -285.372126)
		(end 354.23856 -285.171896)
		(width 0.0889)
		(layer "In11.Cu")
		(net "UPI_CPU1_CPU0_P2P2_DP<4>")
	)
	(arc
		(start 355.65715 -282.725114)
		(mid 355.835868 -282.405836)
		(end 355.65715 -282.086558)
		(width 0.0889)
		(layer "In11.Cu")
		(net "UPI_CPU1_CPU0_P2P2_DP<4>")
	)
	(arc
		(start 88.820498 -286.475424)
		(mid 88.748263 -286.751948)
		(end 88.549988 -286.95777)
		(width 0.0889)
		(layer "In11.Cu")
		(net "UPI_CPU1_CPU0_P2P2_DP<4>")
	)
	(arc
		(start 88.528906 -286.969962)
		(mid 88.397992 -287.106322)
		(end 88.350344 -287.28924)
		(width 0.0889)
		(layer "In11.Cu")
		(net "UPI_CPU1_CPU0_P2P2_DP<4>")
	)
	(arc
		(start 355.64826 -280.453846)
		(mid 355.365728 -279.964325)
		(end 355.64826 -279.474676)
		(width 0.0889)
		(layer "In11.Cu")
		(net "UPI_CPU1_CPU0_P2P2_DP<4>")
	)
	(arc
		(start 355.64826 -282.081478)
		(mid 355.445437 -281.881247)
		(end 355.366066 -281.607514)
		(width 0.0889)
		(layer "In11.Cu")
		(net "UPI_CPU1_CPU0_P2P2_DP<4>")
	)
	(arc
		(start 88.350344 -287.299146)
		(mid 88.272233 -287.576095)
		(end 88.067896 -287.778698)
		(width 0.0889)
		(layer "In11.Cu")
		(net "UPI_CPU1_CPU0_P2P2_DP<4>")
	)
	(arc
		(start 87.920576 -285.312358)
		(mid 87.75648 -285.288011)
		(end 87.597996 -285.336996)
		(width 0.0889)
		(layer "In11.Cu")
		(net "UPI_CPU1_CPU0_P2P2_DP<4>")
	)
	(arc
		(start 353.016566 -287.279334)
		(mid 353.094677 -287.002385)
		(end 353.299014 -286.799782)
		(width 0.0889)
		(layer "In11.Cu")
		(net "UPI_CPU1_CPU0_P2P2_DP<4>")
	)
	(arc
		(start 355.366066 -281.576526)
		(mid 355.445436 -281.302792)
		(end 355.64826 -281.102562)
		(width 0.0889)
		(layer "In11.Cu")
		(net "UPI_CPU1_CPU0_P2P2_DP<4>")
	)
	(arc
		(start 355.65715 -279.469596)
		(mid 355.788064 -279.333236)
		(end 355.835712 -279.150318)
		(width 0.0889)
		(layer "In11.Cu")
		(net "UPI_CPU1_CPU0_P2P2_DP<4>")
	)
	(arc
		(start 354.24745 -285.166816)
		(mid 354.378364 -285.030456)
		(end 354.426012 -284.847538)
		(width 0.0889)
		(layer "In11.Cu")
		(net "UPI_CPU1_CPU0_P2P2_DP<4>")
	)
	(arc
		(start 87.410544 -285.65475)
		(mid 87.410554 -285.66415)
		(end 87.410798 -285.673546)
		(width 0.0889)
		(layer "In11.Cu")
		(net "UPI_CPU1_CPU0_P2P2_DP<4>")
	)
	(arc
		(start 355.366066 -283.197808)
		(mid 355.446977 -282.92768)
		(end 355.64826 -282.730194)
		(width 0.0889)
		(layer "In11.Cu")
		(net "UPI_CPU1_CPU0_P2P2_DP<4>")
	)
	(arc
		(start 352.362262 -289.446462)
		(mid 352.18813 -289.307615)
		(end 352.076766 -289.114738)
		(width 0.0889)
		(layer "In11.Cu")
		(net "UPI_CPU1_CPU0_P2P2_DP<4>")
	)
	(segment
		(start 354.521516 -275.894546)
		(end 354.521262 -275.8948)
		(width 0.13208)
		(layer "F.Cu")
		(net "UPI_CPU1_CPU0_P2P2_DP<3>")
	)
	(segment
		(start 88.255094 -285.939484)
		(end 88.255094 -286.475424)
		(width 0.13208)
		(layer "F.Cu")
		(net "UPI_CPU1_CPU0_P2P2_DP<3>")
	)
	(segment
		(start 354.521516 -275.35886)
		(end 354.521516 -275.894546)
		(width 0.13208)
		(layer "F.Cu")
		(net "UPI_CPU1_CPU0_P2P2_DP<3>")
	)
	(segment
		(start 127.128016 -390.19861)
		(end 161.074862 -390.19861)
		(width 0.14732)
		(layer "In11.Cu")
		(net "UPI_CPU1_CPU0_P2P2_DP<3>")
	)
	(segment
		(start 264.913618 -381.430022)
		(end 276.91588 -369.42776)
		(width 0.14732)
		(layer "In11.Cu")
		(net "UPI_CPU1_CPU0_P2P2_DP<3>")
	)
	(segment
		(start 349.823786 -301.481236)
		(end 350.02851 -301.481236)
		(width 0.14732)
		(layer "In11.Cu")
		(net "UPI_CPU1_CPU0_P2P2_DP<3>")
	)
	(segment
		(start 82.529426 -296.756328)
		(end 82.080354 -297.840908)
		(width 0.14732)
		(layer "In11.Cu")
		(net "UPI_CPU1_CPU0_P2P2_DP<3>")
	)
	(segment
		(start 161.074862 -390.19861)
		(end 264.913618 -381.430022)
		(width 0.14732)
		(layer "In11.Cu")
		(net "UPI_CPU1_CPU0_P2P2_DP<3>")
	)
	(segment
		(start 53.59908 -328.073766)
		(end 58.262266 -333.87284)
		(width 0.14732)
		(layer "In11.Cu")
		(net "UPI_CPU1_CPU0_P2P2_DP<3>")
	)
	(segment
		(start 58.202576 -317.996062)
		(end 57.629298 -318.56934)
		(width 0.14732)
		(layer "In11.Cu")
		(net "UPI_CPU1_CPU0_P2P2_DP<3>")
	)
	(segment
		(start 354.23856 -286.799782)
		(end 354.24745 -286.794702)
		(width 0.0889)
		(layer "In11.Cu")
		(net "UPI_CPU1_CPU0_P2P2_DP<3>")
	)
	(segment
		(start 356.588314 -282.081478)
		(end 356.582218 -282.077922)
		(width 0.0889)
		(layer "In11.Cu")
		(net "UPI_CPU1_CPU0_P2P2_DP<3>")
	)
	(segment
		(start 353.486466 -289.64636)
		(end 353.486212 -289.645852)
		(width 0.0889)
		(layer "In11.Cu")
		(net "UPI_CPU1_CPU0_P2P2_DP<3>")
	)
	(segment
		(start 356.775512 -280.78684)
		(end 356.775512 -280.769568)
		(width 0.0889)
		(layer "In11.Cu")
		(net "UPI_CPU1_CPU0_P2P2_DP<3>")
	)
	(segment
		(start 354.426012 -286.475424)
		(end 354.426012 -286.4612)
		(width 0.0889)
		(layer "In11.Cu")
		(net "UPI_CPU1_CPU0_P2P2_DP<3>")
	)
	(segment
		(start 352.709226 -294.128698)
		(end 352.564446 -293.983918)
		(width 0.14732)
		(layer "In11.Cu")
		(net "UPI_CPU1_CPU0_P2P2_DP<3>")
	)
	(segment
		(start 83.886548 -293.480236)
		(end 83.812888 -293.65829)
		(width 0.14732)
		(layer "In11.Cu")
		(net "UPI_CPU1_CPU0_P2P2_DP<3>")
	)
	(segment
		(start 350.623378 -300.681644)
		(end 350.884236 -300.420786)
		(width 0.14732)
		(layer "In11.Cu")
		(net "UPI_CPU1_CPU0_P2P2_DP<3>")
	)
	(segment
		(start 87.128096 -287.778698)
		(end 87.127334 -287.779206)
		(width 0.0889)
		(layer "In11.Cu")
		(net "UPI_CPU1_CPU0_P2P2_DP<3>")
	)
	(segment
		(start 286.97555 -340.16061)
		(end 310.642762 -340.16061)
		(width 0.14732)
		(layer "In11.Cu")
		(net "UPI_CPU1_CPU0_P2P2_DP<3>")
	)
	(segment
		(start 354.833936 -275.8948)
		(end 354.521262 -275.8948)
		(width 0.0889)
		(layer "In11.Cu")
		(net "UPI_CPU1_CPU0_P2P2_DP<3>")
	)
	(segment
		(start 352.709226 -297.18254)
		(end 352.709226 -296.442638)
		(width 0.14732)
		(layer "In11.Cu")
		(net "UPI_CPU1_CPU0_P2P2_DP<3>")
	)
	(segment
		(start 353.444556 -290.344606)
		(end 353.444556 -290.322508)
		(width 0.0889)
		(layer "In11.Cu")
		(net "UPI_CPU1_CPU0_P2P2_DP<3>")
	)
	(segment
		(start 63.512192 -314.201302)
		(end 62.385702 -314.668408)
		(width 0.14732)
		(layer "In11.Cu")
		(net "UPI_CPU1_CPU0_P2P2_DP<3>")
	)
	(segment
		(start 59.40298 -317.475108)
		(end 58.882026 -317.996062)
		(width 0.14732)
		(layer "In11.Cu")
		(net "UPI_CPU1_CPU0_P2P2_DP<3>")
	)
	(segment
		(start 320.416682 -330.38669)
		(end 321.541648 -327.671176)
		(width 0.14732)
		(layer "In11.Cu")
		(net "UPI_CPU1_CPU0_P2P2_DP<3>")
	)
	(segment
		(start 62.385702 -314.668408)
		(end 59.655964 -316.492636)
		(width 0.14732)
		(layer "In11.Cu")
		(net "UPI_CPU1_CPU0_P2P2_DP<3>")
	)
	(segment
		(start 351.56521 -299.944536)
		(end 352.04019 -298.797472)
		(width 0.14732)
		(layer "In11.Cu")
		(net "UPI_CPU1_CPU0_P2P2_DP<3>")
	)
	(segment
		(start 352.432874 -297.84929)
		(end 352.433128 -297.849036)
		(width 0.14732)
		(layer "In11.Cu")
		(net "UPI_CPU1_CPU0_P2P2_DP<3>")
	)
	(segment
		(start 82.856324 -296.286682)
		(end 82.689192 -296.690542)
		(width 0.14732)
		(layer "In11.Cu")
		(net "UPI_CPU1_CPU0_P2P2_DP<3>")
	)
	(segment
		(start 352.709226 -293.470838)
		(end 352.709226 -291.93871)
		(width 0.14732)
		(layer "In11.Cu")
		(net "UPI_CPU1_CPU0_P2P2_DP<3>")
	)
	(segment
		(start 353.762564 -287.617408)
		(end 353.768914 -287.613598)
		(width 0.0889)
		(layer "In11.Cu")
		(net "UPI_CPU1_CPU0_P2P2_DP<3>")
	)
	(segment
		(start 54.780942 -324.091046)
		(end 53.59908 -325.272908)
		(width 0.14732)
		(layer "In11.Cu")
		(net "UPI_CPU1_CPU0_P2P2_DP<3>")
	)
	(segment
		(start 62.00394 -362.480606)
		(end 64.803274 -369.238784)
		(width 0.14732)
		(layer "In11.Cu")
		(net "UPI_CPU1_CPU0_P2P2_DP<3>")
	)
	(segment
		(start 353.444556 -291.20338)
		(end 353.444556 -290.344606)
		(width 0.14732)
		(layer "In11.Cu")
		(net "UPI_CPU1_CPU0_P2P2_DP<3>")
	)
	(segment
		(start 355.64826 -284.35808)
		(end 355.65715 -284.353)
		(width 0.0889)
		(layer "In11.Cu")
		(net "UPI_CPU1_CPU0_P2P2_DP<3>")
	)
	(segment
		(start 349.562928 -301.946818)
		(end 349.562928 -301.742094)
		(width 0.14732)
		(layer "In11.Cu")
		(net "UPI_CPU1_CPU0_P2P2_DP<3>")
	)
	(segment
		(start 82.957416 -295.723818)
		(end 82.790284 -296.127424)
		(width 0.14732)
		(layer "In11.Cu")
		(net "UPI_CPU1_CPU0_P2P2_DP<3>")
	)
	(segment
		(start 87.410544 -287.28924)
		(end 87.410544 -287.299146)
		(width 0.0889)
		(layer "In11.Cu")
		(net "UPI_CPU1_CPU0_P2P2_DP<3>")
	)
	(segment
		(start 62.003686 -362.480352)
		(end 62.00394 -362.480606)
		(width 0.14732)
		(layer "In11.Cu")
		(net "UPI_CPU1_CPU0_P2P2_DP<3>")
	)
	(segment
		(start 53.59908 -325.272908)
		(end 53.59908 -328.073766)
		(width 0.14732)
		(layer "In11.Cu")
		(net "UPI_CPU1_CPU0_P2P2_DP<3>")
	)
	(segment
		(start 353.486466 -290.280598)
		(end 353.486466 -289.64636)
		(width 0.0889)
		(layer "In11.Cu")
		(net "UPI_CPU1_CPU0_P2P2_DP<3>")
	)
	(segment
		(start 82.790284 -296.127424)
		(end 82.856324 -296.286682)
		(width 0.14732)
		(layer "In11.Cu")
		(net "UPI_CPU1_CPU0_P2P2_DP<3>")
	)
	(segment
		(start 321.541648 -327.671176)
		(end 339.960966 -309.251858)
		(width 0.14732)
		(layer "In11.Cu")
		(net "UPI_CPU1_CPU0_P2P2_DP<3>")
	)
	(segment
		(start 353.486212 -288.111692)
		(end 353.486212 -288.103056)
		(width 0.0889)
		(layer "In11.Cu")
		(net "UPI_CPU1_CPU0_P2P2_DP<3>")
	)
	(segment
		(start 86.691724 -290.67506)
		(end 83.886548 -293.480236)
		(width 0.14732)
		(layer "In11.Cu")
		(net "UPI_CPU1_CPU0_P2P2_DP<3>")
	)
	(segment
		(start 357.52786 -277.84679)
		(end 357.53675 -277.84171)
		(width 0.0889)
		(layer "In11.Cu")
		(net "UPI_CPU1_CPU0_P2P2_DP<3>")
	)
	(segment
		(start 357.245412 -278.336502)
		(end 357.245412 -278.31796)
		(width 0.0889)
		(layer "In11.Cu")
		(net "UPI_CPU1_CPU0_P2P2_DP<3>")
	)
	(segment
		(start 352.564446 -293.615618)
		(end 352.709226 -293.470838)
		(width 0.14732)
		(layer "In11.Cu")
		(net "UPI_CPU1_CPU0_P2P2_DP<3>")
	)
	(segment
		(start 82.080354 -297.840908)
		(end 68.307966 -311.613296)
		(width 0.14732)
		(layer "In11.Cu")
		(net "UPI_CPU1_CPU0_P2P2_DP<3>")
	)
	(segment
		(start 343.882218 -307.627528)
		(end 349.562928 -301.946818)
		(width 0.14732)
		(layer "In11.Cu")
		(net "UPI_CPU1_CPU0_P2P2_DP<3>")
	)
	(segment
		(start 352.102928 -298.267882)
		(end 352.292158 -298.189396)
		(width 0.14732)
		(layer "In11.Cu")
		(net "UPI_CPU1_CPU0_P2P2_DP<3>")
	)
	(segment
		(start 86.940644 -288.103056)
		(end 86.940644 -288.400998)
		(width 0.0889)
		(layer "In11.Cu")
		(net "UPI_CPU1_CPU0_P2P2_DP<3>")
	)
	(segment
		(start 64.539114 -313.17438)
		(end 63.512192 -314.201302)
		(width 0.14732)
		(layer "In11.Cu")
		(net "UPI_CPU1_CPU0_P2P2_DP<3>")
	)
	(segment
		(start 356.775512 -282.414472)
		(end 356.775512 -282.3972)
		(width 0.0889)
		(layer "In11.Cu")
		(net "UPI_CPU1_CPU0_P2P2_DP<3>")
	)
	(segment
		(start 356.305612 -283.228542)
		(end 356.305612 -283.205682)
		(width 0.0889)
		(layer "In11.Cu")
		(net "UPI_CPU1_CPU0_P2P2_DP<3>")
	)
	(segment
		(start 353.956366 -287.28924)
		(end 353.956366 -287.273746)
		(width 0.0889)
		(layer "In11.Cu")
		(net "UPI_CPU1_CPU0_P2P2_DP<3>")
	)
	(segment
		(start 339.960966 -309.251858)
		(end 343.882218 -307.627528)
		(width 0.14732)
		(layer "In11.Cu")
		(net "UPI_CPU1_CPU0_P2P2_DP<3>")
	)
	(segment
		(start 83.21802 -295.09466)
		(end 83.28406 -295.253918)
		(width 0.14732)
		(layer "In11.Cu")
		(net "UPI_CPU1_CPU0_P2P2_DP<3>")
	)
	(segment
		(start 355.642164 -284.361636)
		(end 355.64826 -284.35808)
		(width 0.0889)
		(layer "In11.Cu")
		(net "UPI_CPU1_CPU0_P2P2_DP<3>")
	)
	(segment
		(start 58.882026 -317.996062)
		(end 58.202576 -317.996062)
		(width 0.14732)
		(layer "In11.Cu")
		(net "UPI_CPU1_CPU0_P2P2_DP<3>")
	)
	(segment
		(start 356.775512 -279.150318)
		(end 356.775512 -279.140412)
		(width 0.0889)
		(layer "In11.Cu")
		(net "UPI_CPU1_CPU0_P2P2_DP<3>")
	)
	(segment
		(start 353.770438 -287.612836)
		(end 353.777804 -287.608518)
		(width 0.0889)
		(layer "In11.Cu")
		(net "UPI_CPU1_CPU0_P2P2_DP<3>")
	)
	(segment
		(start 83.116928 -295.657778)
		(end 82.957416 -295.723818)
		(width 0.14732)
		(layer "In11.Cu")
		(net "UPI_CPU1_CPU0_P2P2_DP<3>")
	)
	(segment
		(start 86.691724 -289.242246)
		(end 86.691724 -290.67506)
		(width 0.14732)
		(layer "In11.Cu")
		(net "UPI_CPU1_CPU0_P2P2_DP<3>")
	)
	(segment
		(start 86.64956 -288.692082)
		(end 86.64956 -289.177984)
		(width 0.0889)
		(layer "In11.Cu")
		(net "UPI_CPU1_CPU0_P2P2_DP<3>")
	)
	(segment
		(start 64.803274 -369.238784)
		(end 71.312278 -375.747788)
		(width 0.14732)
		(layer "In11.Cu")
		(net "UPI_CPU1_CPU0_P2P2_DP<3>")
	)
	(segment
		(start 88.255094 -286.475424)
		(end 87.94242 -286.475424)
		(width 0.0889)
		(layer "In11.Cu")
		(net "UPI_CPU1_CPU0_P2P2_DP<3>")
	)
	(segment
		(start 355.187504 -276.389338)
		(end 355.178614 -276.384258)
		(width 0.0889)
		(layer "In11.Cu")
		(net "UPI_CPU1_CPU0_P2P2_DP<3>")
	)
	(segment
		(start 57.629298 -321.73799)
		(end 56.2737 -323.093588)
		(width 0.14732)
		(layer "In11.Cu")
		(net "UPI_CPU1_CPU0_P2P2_DP<3>")
	)
	(segment
		(start 356.58806 -279.474676)
		(end 356.59695 -279.469596)
		(width 0.0889)
		(layer "In11.Cu")
		(net "UPI_CPU1_CPU0_P2P2_DP<3>")
	)
	(segment
		(start 353.768914 -287.613598)
		(end 353.770438 -287.612836)
		(width 0.0889)
		(layer "In11.Cu")
		(net "UPI_CPU1_CPU0_P2P2_DP<3>")
	)
	(segment
		(start 82.689192 -296.690542)
		(end 82.529426 -296.756328)
		(width 0.14732)
		(layer "In11.Cu")
		(net "UPI_CPU1_CPU0_P2P2_DP<3>")
	)
	(segment
		(start 350.884236 -300.420786)
		(end 351.08896 -300.420786)
		(width 0.14732)
		(layer "In11.Cu")
		(net "UPI_CPU1_CPU0_P2P2_DP<3>")
	)
	(segment
		(start 352.292158 -298.189396)
		(end 352.432874 -297.84929)
		(width 0.14732)
		(layer "In11.Cu")
		(net "UPI_CPU1_CPU0_P2P2_DP<3>")
	)
	(segment
		(start 352.564446 -295.929558)
		(end 352.709226 -295.784778)
		(width 0.14732)
		(layer "In11.Cu")
		(net "UPI_CPU1_CPU0_P2P2_DP<3>")
	)
	(segment
		(start 87.94242 -286.475424)
		(end 87.876888 -286.540956)
		(width 0.0889)
		(layer "In11.Cu")
		(net "UPI_CPU1_CPU0_P2P2_DP<3>")
	)
	(segment
		(start 350.02851 -301.481236)
		(end 350.623378 -300.886368)
		(width 0.14732)
		(layer "In11.Cu")
		(net "UPI_CPU1_CPU0_P2P2_DP<3>")
	)
	(segment
		(start 87.127334 -287.779206)
		(end 87.119206 -287.783778)
		(width 0.0889)
		(layer "In11.Cu")
		(net "UPI_CPU1_CPU0_P2P2_DP<3>")
	)
	(segment
		(start 356.106222 -283.551376)
		(end 356.118414 -283.544264)
		(width 0.0889)
		(layer "In11.Cu")
		(net "UPI_CPU1_CPU0_P2P2_DP<3>")
	)
	(segment
		(start 83.645756 -294.061896)
		(end 83.711796 -294.221154)
		(width 0.14732)
		(layer "In11.Cu")
		(net "UPI_CPU1_CPU0_P2P2_DP<3>")
	)
	(segment
		(start 357.53675 -277.203154)
		(end 357.52786 -277.198074)
		(width 0.0889)
		(layer "In11.Cu")
		(net "UPI_CPU1_CPU0_P2P2_DP<3>")
	)
	(segment
		(start 352.709226 -291.93871)
		(end 353.444556 -291.20338)
		(width 0.14732)
		(layer "In11.Cu")
		(net "UPI_CPU1_CPU0_P2P2_DP<3>")
	)
	(segment
		(start 276.91588 -369.42776)
		(end 276.91588 -348.752668)
		(width 0.14732)
		(layer "In11.Cu")
		(net "UPI_CPU1_CPU0_P2P2_DP<3>")
	)
	(segment
		(start 356.582218 -281.106118)
		(end 356.588314 -281.102562)
		(width 0.0889)
		(layer "In11.Cu")
		(net "UPI_CPU1_CPU0_P2P2_DP<3>")
	)
	(segment
		(start 59.204098 -355.721666)
		(end 62.003686 -362.480352)
		(width 0.14732)
		(layer "In11.Cu")
		(net "UPI_CPU1_CPU0_P2P2_DP<3>")
	)
	(segment
		(start 351.08896 -300.420786)
		(end 351.56521 -299.944536)
		(width 0.14732)
		(layer "In11.Cu")
		(net "UPI_CPU1_CPU0_P2P2_DP<3>")
	)
	(segment
		(start 357.05796 -278.66086)
		(end 357.06685 -278.65578)
		(width 0.0889)
		(layer "In11.Cu")
		(net "UPI_CPU1_CPU0_P2P2_DP<3>")
	)
	(segment
		(start 68.307966 -311.613296)
		(end 64.539114 -313.17438)
		(width 0.14732)
		(layer "In11.Cu")
		(net "UPI_CPU1_CPU0_P2P2_DP<3>")
	)
	(segment
		(start 352.564446 -296.297858)
		(end 352.564446 -295.929558)
		(width 0.14732)
		(layer "In11.Cu")
		(net "UPI_CPU1_CPU0_P2P2_DP<3>")
	)
	(segment
		(start 354.899722 -275.960586)
		(end 354.833936 -275.8948)
		(width 0.0889)
		(layer "In11.Cu")
		(net "UPI_CPU1_CPU0_P2P2_DP<3>")
	)
	(segment
		(start 351.961958 -298.608242)
		(end 352.102928 -298.267882)
		(width 0.14732)
		(layer "In11.Cu")
		(net "UPI_CPU1_CPU0_P2P2_DP<3>")
	)
	(segment
		(start 354.895912 -285.66999)
		(end 354.895912 -285.651448)
		(width 0.0889)
		(layer "In11.Cu")
		(net "UPI_CPU1_CPU0_P2P2_DP<3>")
	)
	(segment
		(start 352.564446 -293.983918)
		(end 352.564446 -293.615618)
		(width 0.14732)
		(layer "In11.Cu")
		(net "UPI_CPU1_CPU0_P2P2_DP<3>")
	)
	(segment
		(start 349.562928 -301.742094)
		(end 349.823786 -301.481236)
		(width 0.14732)
		(layer "In11.Cu")
		(net "UPI_CPU1_CPU0_P2P2_DP<3>")
	)
	(segment
		(start 352.04019 -298.797472)
		(end 351.961958 -298.608242)
		(width 0.14732)
		(layer "In11.Cu")
		(net "UPI_CPU1_CPU0_P2P2_DP<3>")
	)
	(segment
		(start 87.597996 -286.964882)
		(end 87.589106 -286.969962)
		(width 0.0889)
		(layer "In11.Cu")
		(net "UPI_CPU1_CPU0_P2P2_DP<3>")
	)
	(segment
		(start 352.433128 -297.849036)
		(end 352.709226 -297.18254)
		(width 0.14732)
		(layer "In11.Cu")
		(net "UPI_CPU1_CPU0_P2P2_DP<3>")
	)
	(segment
		(start 276.91588 -348.752668)
		(end 284.470094 -341.198454)
		(width 0.14732)
		(layer "In11.Cu")
		(net "UPI_CPU1_CPU0_P2P2_DP<3>")
	)
	(segment
		(start 350.623378 -300.886368)
		(end 350.623378 -300.681644)
		(width 0.14732)
		(layer "In11.Cu")
		(net "UPI_CPU1_CPU0_P2P2_DP<3>")
	)
	(segment
		(start 352.709226 -296.442638)
		(end 352.564446 -296.297858)
		(width 0.14732)
		(layer "In11.Cu")
		(net "UPI_CPU1_CPU0_P2P2_DP<3>")
	)
	(segment
		(start 94.522036 -385.361942)
		(end 127.128016 -390.19861)
		(width 0.14732)
		(layer "In11.Cu")
		(net "UPI_CPU1_CPU0_P2P2_DP<3>")
	)
	(segment
		(start 59.40298 -316.74562)
		(end 59.40298 -317.475108)
		(width 0.14732)
		(layer "In11.Cu")
		(net "UPI_CPU1_CPU0_P2P2_DP<3>")
	)
	(segment
		(start 86.691724 -289.220148)
		(end 86.691724 -289.242246)
		(width 0.0889)
		(layer "In11.Cu")
		(net "UPI_CPU1_CPU0_P2P2_DP<3>")
	)
	(segment
		(start 58.262266 -333.87284)
		(end 59.204098 -336.146902)
		(width 0.14732)
		(layer "In11.Cu")
		(net "UPI_CPU1_CPU0_P2P2_DP<3>")
	)
	(segment
		(start 355.366066 -276.72411)
		(end 355.366066 -276.708616)
		(width 0.0889)
		(layer "In11.Cu")
		(net "UPI_CPU1_CPU0_P2P2_DP<3>")
	)
	(segment
		(start 57.629298 -318.56934)
		(end 57.629298 -321.73799)
		(width 0.14732)
		(layer "In11.Cu")
		(net "UPI_CPU1_CPU0_P2P2_DP<3>")
	)
	(segment
		(start 83.385152 -294.691054)
		(end 83.21802 -295.09466)
		(width 0.14732)
		(layer "In11.Cu")
		(net "UPI_CPU1_CPU0_P2P2_DP<3>")
	)
	(segment
		(start 56.2737 -323.093588)
		(end 54.780942 -324.091046)
		(width 0.14732)
		(layer "In11.Cu")
		(net "UPI_CPU1_CPU0_P2P2_DP<3>")
	)
	(segment
		(start 86.940644 -288.400998)
		(end 86.64956 -288.692082)
		(width 0.0889)
		(layer "In11.Cu")
		(net "UPI_CPU1_CPU0_P2P2_DP<3>")
	)
	(segment
		(start 352.709226 -295.784778)
		(end 352.709226 -294.128698)
		(width 0.14732)
		(layer "In11.Cu")
		(net "UPI_CPU1_CPU0_P2P2_DP<3>")
	)
	(segment
		(start 83.711796 -294.221154)
		(end 83.544664 -294.625014)
		(width 0.14732)
		(layer "In11.Cu")
		(net "UPI_CPU1_CPU0_P2P2_DP<3>")
	)
	(segment
		(start 355.17836 -285.171896)
		(end 355.18725 -285.166816)
		(width 0.0889)
		(layer "In11.Cu")
		(net "UPI_CPU1_CPU0_P2P2_DP<3>")
	)
	(segment
		(start 59.204098 -336.146902)
		(end 59.204098 -355.721666)
		(width 0.14732)
		(layer "In11.Cu")
		(net "UPI_CPU1_CPU0_P2P2_DP<3>")
	)
	(segment
		(start 356.305612 -279.978358)
		(end 356.305612 -279.954228)
		(width 0.0889)
		(layer "In11.Cu")
		(net "UPI_CPU1_CPU0_P2P2_DP<3>")
	)
	(segment
		(start 83.544664 -294.625014)
		(end 83.385152 -294.691054)
		(width 0.14732)
		(layer "In11.Cu")
		(net "UPI_CPU1_CPU0_P2P2_DP<3>")
	)
	(segment
		(start 310.642762 -340.16061)
		(end 320.416682 -330.38669)
		(width 0.14732)
		(layer "In11.Cu")
		(net "UPI_CPU1_CPU0_P2P2_DP<3>")
	)
	(segment
		(start 356.213664 -277.198074)
		(end 356.198932 -277.20671)
		(width 0.0889)
		(layer "In11.Cu")
		(net "UPI_CPU1_CPU0_P2P2_DP<3>")
	)
	(segment
		(start 353.016566 -289.114738)
		(end 353.016566 -288.898584)
		(width 0.0889)
		(layer "In11.Cu")
		(net "UPI_CPU1_CPU0_P2P2_DP<3>")
	)
	(segment
		(start 71.312278 -375.747788)
		(end 94.522036 -385.361942)
		(width 0.14732)
		(layer "In11.Cu")
		(net "UPI_CPU1_CPU0_P2P2_DP<3>")
	)
	(segment
		(start 86.64956 -289.177984)
		(end 86.691724 -289.220148)
		(width 0.0889)
		(layer "In11.Cu")
		(net "UPI_CPU1_CPU0_P2P2_DP<3>")
	)
	(segment
		(start 83.812888 -293.65829)
		(end 83.645756 -294.061896)
		(width 0.14732)
		(layer "In11.Cu")
		(net "UPI_CPU1_CPU0_P2P2_DP<3>")
	)
	(segment
		(start 355.178614 -276.384258)
		(end 355.172518 -276.380702)
		(width 0.0889)
		(layer "In11.Cu")
		(net "UPI_CPU1_CPU0_P2P2_DP<3>")
	)
	(segment
		(start 353.762818 -287.617154)
		(end 353.762564 -287.617408)
		(width 0.0889)
		(layer "In11.Cu")
		(net "UPI_CPU1_CPU0_P2P2_DP<3>")
	)
	(segment
		(start 59.655964 -316.492636)
		(end 59.40298 -316.74562)
		(width 0.14732)
		(layer "In11.Cu")
		(net "UPI_CPU1_CPU0_P2P2_DP<3>")
	)
	(segment
		(start 83.28406 -295.253918)
		(end 83.116928 -295.657778)
		(width 0.14732)
		(layer "In11.Cu")
		(net "UPI_CPU1_CPU0_P2P2_DP<3>")
	)
	(segment
		(start 284.470094 -341.198454)
		(end 286.97555 -340.16061)
		(width 0.14732)
		(layer "In11.Cu")
		(net "UPI_CPU1_CPU0_P2P2_DP<3>")
	)
	(segment
		(start 353.444556 -290.322508)
		(end 353.486466 -290.280598)
		(width 0.0889)
		(layer "In11.Cu")
		(net "UPI_CPU1_CPU0_P2P2_DP<3>")
	)
	(arc
		(start 355.64826 -277.198074)
		(mid 355.445437 -276.997843)
		(end 355.366066 -276.72411)
		(width 0.0889)
		(layer "In11.Cu")
		(net "UPI_CPU1_CPU0_P2P2_DP<3>")
	)
	(arc
		(start 354.895912 -285.651448)
		(mid 354.974023 -285.374499)
		(end 355.17836 -285.171896)
		(width 0.0889)
		(layer "In11.Cu")
		(net "UPI_CPU1_CPU0_P2P2_DP<3>")
	)
	(arc
		(start 357.715058 -277.534624)
		(mid 357.715303 -277.525228)
		(end 357.715312 -277.515828)
		(width 0.0889)
		(layer "In11.Cu")
		(net "UPI_CPU1_CPU0_P2P2_DP<3>")
	)
	(arc
		(start 353.486212 -288.103056)
		(mid 353.560203 -287.82349)
		(end 353.762818 -287.617154)
		(width 0.0889)
		(layer "In11.Cu")
		(net "UPI_CPU1_CPU0_P2P2_DP<3>")
	)
	(arc
		(start 355.172518 -276.380702)
		(mid 354.992866 -276.211266)
		(end 354.902516 -275.981414)
		(width 0.0889)
		(layer "In11.Cu")
		(net "UPI_CPU1_CPU0_P2P2_DP<3>")
	)
	(arc
		(start 356.775512 -280.769568)
		(mid 356.723242 -280.587203)
		(end 356.588314 -280.453846)
		(width 0.0889)
		(layer "In11.Cu")
		(net "UPI_CPU1_CPU0_P2P2_DP<3>")
	)
	(arc
		(start 356.58806 -277.198074)
		(mid 356.400862 -277.147931)
		(end 356.213664 -277.198074)
		(width 0.0889)
		(layer "In11.Cu")
		(net "UPI_CPU1_CPU0_P2P2_DP<3>")
	)
	(arc
		(start 356.305612 -283.205682)
		(mid 356.384831 -282.930997)
		(end 356.588314 -282.730194)
		(width 0.0889)
		(layer "In11.Cu")
		(net "UPI_CPU1_CPU0_P2P2_DP<3>")
	)
	(arc
		(start 355.835712 -284.033722)
		(mid 355.907947 -283.757198)
		(end 356.106222 -283.551376)
		(width 0.0889)
		(layer "In11.Cu")
		(net "UPI_CPU1_CPU0_P2P2_DP<3>")
	)
	(arc
		(start 357.52786 -277.198074)
		(mid 357.340662 -277.147931)
		(end 357.153464 -277.198074)
		(width 0.0889)
		(layer "In11.Cu")
		(net "UPI_CPU1_CPU0_P2P2_DP<3>")
	)
	(arc
		(start 353.486212 -289.645852)
		(mid 353.411207 -289.530393)
		(end 353.302062 -289.446462)
		(width 0.0889)
		(layer "In11.Cu")
		(net "UPI_CPU1_CPU0_P2P2_DP<3>")
	)
	(arc
		(start 354.902516 -275.981414)
		(mid 354.901021 -275.971013)
		(end 354.899722 -275.960586)
		(width 0.0889)
		(layer "In11.Cu")
		(net "UPI_CPU1_CPU0_P2P2_DP<3>")
	)
	(arc
		(start 353.777804 -287.608518)
		(mid 353.908718 -287.472158)
		(end 353.956366 -287.28924)
		(width 0.0889)
		(layer "In11.Cu")
		(net "UPI_CPU1_CPU0_P2P2_DP<3>")
	)
	(arc
		(start 353.956366 -287.273746)
		(mid 354.035736 -287.000012)
		(end 354.23856 -286.799782)
		(width 0.0889)
		(layer "In11.Cu")
		(net "UPI_CPU1_CPU0_P2P2_DP<3>")
	)
	(arc
		(start 354.426012 -286.4612)
		(mid 354.505231 -286.186515)
		(end 354.708714 -285.985712)
		(width 0.0889)
		(layer "In11.Cu")
		(net "UPI_CPU1_CPU0_P2P2_DP<3>")
	)
	(arc
		(start 357.53675 -277.84171)
		(mid 357.664643 -277.710648)
		(end 357.715058 -277.534624)
		(width 0.0889)
		(layer "In11.Cu")
		(net "UPI_CPU1_CPU0_P2P2_DP<3>")
	)
	(arc
		(start 355.18725 -285.166816)
		(mid 355.318164 -285.030456)
		(end 355.365812 -284.847538)
		(width 0.0889)
		(layer "In11.Cu")
		(net "UPI_CPU1_CPU0_P2P2_DP<3>")
	)
	(arc
		(start 356.118414 -283.544264)
		(mid 356.253347 -283.41091)
		(end 356.305612 -283.228542)
		(width 0.0889)
		(layer "In11.Cu")
		(net "UPI_CPU1_CPU0_P2P2_DP<3>")
	)
	(arc
		(start 356.305612 -279.954228)
		(mid 356.383723 -279.677279)
		(end 356.58806 -279.474676)
		(width 0.0889)
		(layer "In11.Cu")
		(net "UPI_CPU1_CPU0_P2P2_DP<3>")
	)
	(arc
		(start 353.302062 -289.446462)
		(mid 353.12793 -289.307615)
		(end 353.016566 -289.114738)
		(width 0.0889)
		(layer "In11.Cu")
		(net "UPI_CPU1_CPU0_P2P2_DP<3>")
	)
	(arc
		(start 87.589106 -286.969962)
		(mid 87.458192 -287.106322)
		(end 87.410544 -287.28924)
		(width 0.0889)
		(layer "In11.Cu")
		(net "UPI_CPU1_CPU0_P2P2_DP<3>")
	)
	(arc
		(start 357.06685 -278.65578)
		(mid 357.197764 -278.51942)
		(end 357.245412 -278.336502)
		(width 0.0889)
		(layer "In11.Cu")
		(net "UPI_CPU1_CPU0_P2P2_DP<3>")
	)
	(arc
		(start 87.410544 -287.299146)
		(mid 87.332433 -287.576095)
		(end 87.128096 -287.778698)
		(width 0.0889)
		(layer "In11.Cu")
		(net "UPI_CPU1_CPU0_P2P2_DP<3>")
	)
	(arc
		(start 354.708714 -285.985712)
		(mid 354.843647 -285.852358)
		(end 354.895912 -285.66999)
		(width 0.0889)
		(layer "In11.Cu")
		(net "UPI_CPU1_CPU0_P2P2_DP<3>")
	)
	(arc
		(start 355.366066 -276.708616)
		(mid 355.318387 -276.525716)
		(end 355.187504 -276.389338)
		(width 0.0889)
		(layer "In11.Cu")
		(net "UPI_CPU1_CPU0_P2P2_DP<3>")
	)
	(arc
		(start 357.715312 -277.515828)
		(mid 357.666059 -277.336628)
		(end 357.53675 -277.203154)
		(width 0.0889)
		(layer "In11.Cu")
		(net "UPI_CPU1_CPU0_P2P2_DP<3>")
	)
	(arc
		(start 355.365812 -284.847538)
		(mid 355.439728 -284.568036)
		(end 355.642164 -284.361636)
		(width 0.0889)
		(layer "In11.Cu")
		(net "UPI_CPU1_CPU0_P2P2_DP<3>")
	)
	(arc
		(start 356.588314 -282.730194)
		(mid 356.723247 -282.59684)
		(end 356.775512 -282.414472)
		(width 0.0889)
		(layer "In11.Cu")
		(net "UPI_CPU1_CPU0_P2P2_DP<3>")
	)
	(arc
		(start 357.245412 -278.31796)
		(mid 357.325574 -278.045771)
		(end 357.52786 -277.84679)
		(width 0.0889)
		(layer "In11.Cu")
		(net "UPI_CPU1_CPU0_P2P2_DP<3>")
	)
	(arc
		(start 354.24745 -286.794702)
		(mid 354.378364 -286.658342)
		(end 354.426012 -286.475424)
		(width 0.0889)
		(layer "In11.Cu")
		(net "UPI_CPU1_CPU0_P2P2_DP<3>")
	)
	(arc
		(start 356.775512 -279.140412)
		(mid 356.853623 -278.863463)
		(end 357.05796 -278.66086)
		(width 0.0889)
		(layer "In11.Cu")
		(net "UPI_CPU1_CPU0_P2P2_DP<3>")
	)
	(arc
		(start 353.016566 -288.898584)
		(mid 353.096728 -288.626395)
		(end 353.299014 -288.427414)
		(width 0.0889)
		(layer "In11.Cu")
		(net "UPI_CPU1_CPU0_P2P2_DP<3>")
	)
	(arc
		(start 87.874094 -286.562038)
		(mid 87.78177 -286.79479)
		(end 87.597996 -286.964882)
		(width 0.0889)
		(layer "In11.Cu")
		(net "UPI_CPU1_CPU0_P2P2_DP<3>")
	)
	(arc
		(start 353.299014 -288.427414)
		(mid 353.433947 -288.29406)
		(end 353.486212 -288.111692)
		(width 0.0889)
		(layer "In11.Cu")
		(net "UPI_CPU1_CPU0_P2P2_DP<3>")
	)
	(arc
		(start 87.119206 -287.783778)
		(mid 86.988292 -287.920138)
		(end 86.940644 -288.103056)
		(width 0.0889)
		(layer "In11.Cu")
		(net "UPI_CPU1_CPU0_P2P2_DP<3>")
	)
	(arc
		(start 356.775512 -282.3972)
		(mid 356.723242 -282.214835)
		(end 356.588314 -282.081478)
		(width 0.0889)
		(layer "In11.Cu")
		(net "UPI_CPU1_CPU0_P2P2_DP<3>")
	)
	(arc
		(start 356.59695 -279.469596)
		(mid 356.727864 -279.333236)
		(end 356.775512 -279.150318)
		(width 0.0889)
		(layer "In11.Cu")
		(net "UPI_CPU1_CPU0_P2P2_DP<3>")
	)
	(arc
		(start 357.153464 -277.198074)
		(mid 356.870762 -277.27385)
		(end 356.58806 -277.198074)
		(width 0.0889)
		(layer "In11.Cu")
		(net "UPI_CPU1_CPU0_P2P2_DP<3>")
	)
	(arc
		(start 355.65715 -284.353)
		(mid 355.788064 -284.21664)
		(end 355.835712 -284.033722)
		(width 0.0889)
		(layer "In11.Cu")
		(net "UPI_CPU1_CPU0_P2P2_DP<3>")
	)
	(arc
		(start 356.588314 -281.102562)
		(mid 356.723247 -280.969208)
		(end 356.775512 -280.78684)
		(width 0.0889)
		(layer "In11.Cu")
		(net "UPI_CPU1_CPU0_P2P2_DP<3>")
	)
	(arc
		(start 356.582218 -282.077922)
		(mid 356.305768 -281.59202)
		(end 356.582218 -281.106118)
		(width 0.0889)
		(layer "In11.Cu")
		(net "UPI_CPU1_CPU0_P2P2_DP<3>")
	)
	(arc
		(start 356.588314 -280.453846)
		(mid 356.384833 -280.253042)
		(end 356.305612 -279.978358)
		(width 0.0889)
		(layer "In11.Cu")
		(net "UPI_CPU1_CPU0_P2P2_DP<3>")
	)
	(arc
		(start 356.198932 -277.20671)
		(mid 355.922457 -277.27403)
		(end 355.64826 -277.198074)
		(width 0.0889)
		(layer "In11.Cu")
		(net "UPI_CPU1_CPU0_P2P2_DP<3>")
	)
	(arc
		(start 87.876888 -286.540956)
		(mid 87.875589 -286.55151)
		(end 87.874094 -286.562038)
		(width 0.0889)
		(layer "In11.Cu")
		(net "UPI_CPU1_CPU0_P2P2_DP<3>")
	)
	(segment
		(start 357.340662 -275.894546)
		(end 357.340408 -275.8948)
		(width 0.13208)
		(layer "F.Cu")
		(net "UPI_CPU1_CPU0_P2P2_DP<2>")
	)
	(segment
		(start 357.340662 -275.35886)
		(end 357.340662 -275.894546)
		(width 0.13208)
		(layer "F.Cu")
		(net "UPI_CPU1_CPU0_P2P2_DP<2>")
	)
	(segment
		(start 86.845648 -286.7533)
		(end 86.845648 -287.288986)
		(width 0.13208)
		(layer "F.Cu")
		(net "UPI_CPU1_CPU0_P2P2_DP<2>")
	)
	(segment
		(start 86.845648 -287.288986)
		(end 86.845394 -287.28924)
		(width 0.13208)
		(layer "F.Cu")
		(net "UPI_CPU1_CPU0_P2P2_DP<2>")
	)
	(segment
		(start 354.344224 -288.586164)
		(end 354.333556 -288.592514)
		(width 0.0889)
		(layer "In11.Cu")
		(net "UPI_CPU1_CPU0_P2P2_DP<2>")
	)
	(segment
		(start 358.08285 -276.213062)
		(end 358.093264 -276.219158)
		(width 0.0889)
		(layer "In11.Cu")
		(net "UPI_CPU1_CPU0_P2P2_DP<2>")
	)
	(segment
		(start 354.81006 -287.775142)
		(end 354.806758 -287.777174)
		(width 0.0889)
		(layer "In11.Cu")
		(net "UPI_CPU1_CPU0_P2P2_DP<2>")
	)
	(segment
		(start 55.756556 -317.537846)
		(end 55.931054 -317.363348)
		(width 0.14732)
		(layer "In11.Cu")
		(net "UPI_CPU1_CPU0_P2P2_DP<2>")
	)
	(segment
		(start 58.101738 -356.295706)
		(end 58.101738 -336.446114)
		(width 0.14732)
		(layer "In11.Cu")
		(net "UPI_CPU1_CPU0_P2P2_DP<2>")
	)
	(segment
		(start 358.572308 -278.006302)
		(end 358.571546 -278.00681)
		(width 0.0889)
		(layer "In11.Cu")
		(net "UPI_CPU1_CPU0_P2P2_DP<2>")
	)
	(segment
		(start 278.01824 -369.885214)
		(end 265.362944 -382.540764)
		(width 0.14732)
		(layer "In11.Cu")
		(net "UPI_CPU1_CPU0_P2P2_DP<2>")
	)
	(segment
		(start 84.575904 -291.290502)
		(end 85.404706 -290.4617)
		(width 0.0889)
		(layer "In11.Cu")
		(net "UPI_CPU1_CPU0_P2P2_DP<2>")
	)
	(segment
		(start 354.80244 -287.77946)
		(end 354.795074 -287.783778)
		(width 0.0889)
		(layer "In11.Cu")
		(net "UPI_CPU1_CPU0_P2P2_DP<2>")
	)
	(segment
		(start 86.101682 -286.969962)
		(end 86.092792 -286.964882)
		(width 0.0889)
		(layer "In11.Cu")
		(net "UPI_CPU1_CPU0_P2P2_DP<2>")
	)
	(segment
		(start 356.213918 -285.336488)
		(end 356.204012 -285.34233)
		(width 0.0889)
		(layer "In11.Cu")
		(net "UPI_CPU1_CPU0_P2P2_DP<2>")
	)
	(segment
		(start 356.683818 -284.522672)
		(end 356.678992 -284.52572)
		(width 0.0889)
		(layer "In11.Cu")
		(net "UPI_CPU1_CPU0_P2P2_DP<2>")
	)
	(segment
		(start 127.078232 -391.31367)
		(end 93.657928 -386.355844)
		(width 0.14732)
		(layer "In11.Cu")
		(net "UPI_CPU1_CPU0_P2P2_DP<2>")
	)
	(segment
		(start 354.598478 -289.56508)
		(end 354.616512 -289.601402)
		(width 0.0889)
		(layer "In11.Cu")
		(net "UPI_CPU1_CPU0_P2P2_DP<2>")
	)
	(segment
		(start 358.571546 -278.00681)
		(end 358.563164 -278.012144)
		(width 0.0889)
		(layer "In11.Cu")
		(net "UPI_CPU1_CPU0_P2P2_DP<2>")
	)
	(segment
		(start 322.51015 -328.26579)
		(end 321.3862 -330.979272)
		(width 0.14732)
		(layer "In11.Cu")
		(net "UPI_CPU1_CPU0_P2P2_DP<2>")
	)
	(segment
		(start 55.931054 -317.363348)
		(end 57.341008 -316.206124)
		(width 0.14732)
		(layer "In11.Cu")
		(net "UPI_CPU1_CPU0_P2P2_DP<2>")
	)
	(segment
		(start 85.810344 -286.48533)
		(end 85.810344 -286.456882)
		(width 0.0889)
		(layer "In11.Cu")
		(net "UPI_CPU1_CPU0_P2P2_DP<2>")
	)
	(segment
		(start 357.163624 -283.703014)
		(end 357.152956 -283.709364)
		(width 0.0889)
		(layer "In11.Cu")
		(net "UPI_CPU1_CPU0_P2P2_DP<2>")
	)
	(segment
		(start 287.005268 -341.34171)
		(end 285.284926 -342.054434)
		(width 0.14732)
		(layer "In11.Cu")
		(net "UPI_CPU1_CPU0_P2P2_DP<2>")
	)
	(segment
		(start 344.518996 -308.560724)
		(end 340.586314 -310.189626)
		(width 0.14732)
		(layer "In11.Cu")
		(net "UPI_CPU1_CPU0_P2P2_DP<2>")
	)
	(segment
		(start 357.435658 -281.584146)
		(end 357.435658 -281.599894)
		(width 0.0889)
		(layer "In11.Cu")
		(net "UPI_CPU1_CPU0_P2P2_DP<2>")
	)
	(segment
		(start 81.310226 -296.797476)
		(end 82.937858 -292.868604)
		(width 0.14732)
		(layer "In11.Cu")
		(net "UPI_CPU1_CPU0_P2P2_DP<2>")
	)
	(segment
		(start 285.284926 -342.054434)
		(end 278.01824 -349.32112)
		(width 0.14732)
		(layer "In11.Cu")
		(net "UPI_CPU1_CPU0_P2P2_DP<2>")
	)
	(segment
		(start 358.375712 -278.336502)
		(end 358.375712 -278.33701)
		(width 0.0889)
		(layer "In11.Cu")
		(net "UPI_CPU1_CPU0_P2P2_DP<2>")
	)
	(segment
		(start 265.36269 -382.541018)
		(end 161.475674 -391.31367)
		(width 0.14732)
		(layer "In11.Cu")
		(net "UPI_CPU1_CPU0_P2P2_DP<2>")
	)
	(segment
		(start 354.806758 -287.777174)
		(end 354.803964 -287.778698)
		(width 0.0889)
		(layer "In11.Cu")
		(net "UPI_CPU1_CPU0_P2P2_DP<2>")
	)
	(segment
		(start 354.616512 -289.601402)
		(end 354.616512 -291.419534)
		(width 0.0889)
		(layer "In11.Cu")
		(net "UPI_CPU1_CPU0_P2P2_DP<2>")
	)
	(segment
		(start 358.554528 -277.027894)
		(end 358.558846 -277.030688)
		(width 0.0889)
		(layer "In11.Cu")
		(net "UPI_CPU1_CPU0_P2P2_DP<2>")
	)
	(segment
		(start 86.280498 -287.28924)
		(end 86.280244 -287.28924)
		(width 0.0889)
		(layer "In11.Cu")
		(net "UPI_CPU1_CPU0_P2P2_DP<2>")
	)
	(segment
		(start 311.023762 -341.34171)
		(end 287.005268 -341.34171)
		(width 0.14732)
		(layer "In11.Cu")
		(net "UPI_CPU1_CPU0_P2P2_DP<2>")
	)
	(segment
		(start 84.500466 -291.305996)
		(end 84.51596 -291.290502)
		(width 0.0889)
		(layer "In11.Cu")
		(net "UPI_CPU1_CPU0_P2P2_DP<2>")
	)
	(segment
		(start 355.753924 -286.144462)
		(end 355.743256 -286.150812)
		(width 0.0889)
		(layer "In11.Cu")
		(net "UPI_CPU1_CPU0_P2P2_DP<2>")
	)
	(segment
		(start 354.803964 -287.778698)
		(end 354.80244 -287.77946)
		(width 0.0889)
		(layer "In11.Cu")
		(net "UPI_CPU1_CPU0_P2P2_DP<2>")
	)
	(segment
		(start 357.633524 -282.888944)
		(end 357.622856 -282.895294)
		(width 0.0889)
		(layer "In11.Cu")
		(net "UPI_CPU1_CPU0_P2P2_DP<2>")
	)
	(segment
		(start 353.856036 -297.701462)
		(end 352.780092 -300.299628)
		(width 0.14732)
		(layer "In11.Cu")
		(net "UPI_CPU1_CPU0_P2P2_DP<2>")
	)
	(segment
		(start 67.588384 -310.519318)
		(end 81.310226 -296.797476)
		(width 0.14732)
		(layer "In11.Cu")
		(net "UPI_CPU1_CPU0_P2P2_DP<2>")
	)
	(segment
		(start 55.333646 -332.13802)
		(end 55.318152 -332.119478)
		(width 0.14732)
		(layer "In11.Cu")
		(net "UPI_CPU1_CPU0_P2P2_DP<2>")
	)
	(segment
		(start 357.340408 -275.8948)
		(end 357.183944 -276.165818)
		(width 0.0889)
		(layer "In11.Cu")
		(net "UPI_CPU1_CPU0_P2P2_DP<2>")
	)
	(segment
		(start 52.43576 -324.816216)
		(end 54.396386 -322.85559)
		(width 0.14732)
		(layer "In11.Cu")
		(net "UPI_CPU1_CPU0_P2P2_DP<2>")
	)
	(segment
		(start 357.435658 -283.20492)
		(end 357.435658 -283.219906)
		(width 0.0889)
		(layer "In11.Cu")
		(net "UPI_CPU1_CPU0_P2P2_DP<2>")
	)
	(segment
		(start 55.275226 -318.43853)
		(end 55.756556 -317.537846)
		(width 0.14732)
		(layer "In11.Cu")
		(net "UPI_CPU1_CPU0_P2P2_DP<2>")
	)
	(segment
		(start 70.93458 -376.943366)
		(end 63.627762 -369.636548)
		(width 0.14732)
		(layer "In11.Cu")
		(net "UPI_CPU1_CPU0_P2P2_DP<2>")
	)
	(segment
		(start 357.635556 -279.632664)
		(end 357.614474 -279.64511)
		(width 0.0889)
		(layer "In11.Cu")
		(net "UPI_CPU1_CPU0_P2P2_DP<2>")
	)
	(segment
		(start 357.435912 -279.964134)
		(end 357.435912 -279.976326)
		(width 0.0889)
		(layer "In11.Cu")
		(net "UPI_CPU1_CPU0_P2P2_DP<2>")
	)
	(segment
		(start 56.30799 -333.30134)
		(end 56.307736 -333.301086)
		(width 0.14732)
		(layer "In11.Cu")
		(net "UPI_CPU1_CPU0_P2P2_DP<2>")
	)
	(segment
		(start 357.622856 -281.916378)
		(end 357.633524 -281.922728)
		(width 0.0889)
		(layer "In11.Cu")
		(net "UPI_CPU1_CPU0_P2P2_DP<2>")
	)
	(segment
		(start 55.334408 -332.139036)
		(end 55.333646 -332.13802)
		(width 0.14732)
		(layer "In11.Cu")
		(net "UPI_CPU1_CPU0_P2P2_DP<2>")
	)
	(segment
		(start 63.627762 -369.636548)
		(end 58.101738 -356.295706)
		(width 0.14732)
		(layer "In11.Cu")
		(net "UPI_CPU1_CPU0_P2P2_DP<2>")
	)
	(segment
		(start 354.658676 -291.461698)
		(end 354.658676 -291.483796)
		(width 0.0889)
		(layer "In11.Cu")
		(net "UPI_CPU1_CPU0_P2P2_DP<2>")
	)
	(segment
		(start 357.614474 -279.64511)
		(end 357.614474 -279.644856)
		(width 0.0889)
		(layer "In11.Cu")
		(net "UPI_CPU1_CPU0_P2P2_DP<2>")
	)
	(segment
		(start 61.57595 -313.009788)
		(end 67.588384 -310.519318)
		(width 0.14732)
		(layer "In11.Cu")
		(net "UPI_CPU1_CPU0_P2P2_DP<2>")
	)
	(segment
		(start 58.101738 -336.446114)
		(end 57.279794 -334.46212)
		(width 0.14732)
		(layer "In11.Cu")
		(net "UPI_CPU1_CPU0_P2P2_DP<2>")
	)
	(segment
		(start 354.616512 -288.1122)
		(end 354.616004 -288.125154)
		(width 0.0889)
		(layer "In11.Cu")
		(net "UPI_CPU1_CPU0_P2P2_DP<2>")
	)
	(segment
		(start 86.71306 -286.929068)
		(end 86.68893 -287.018222)
		(width 0.0889)
		(layer "In11.Cu")
		(net "UPI_CPU1_CPU0_P2P2_DP<2>")
	)
	(segment
		(start 358.563164 -278.012144)
		(end 358.554274 -278.017224)
		(width 0.0889)
		(layer "In11.Cu")
		(net "UPI_CPU1_CPU0_P2P2_DP<2>")
	)
	(segment
		(start 357.622856 -280.288746)
		(end 357.633524 -280.295096)
		(width 0.0889)
		(layer "In11.Cu")
		(net "UPI_CPU1_CPU0_P2P2_DP<2>")
	)
	(segment
		(start 358.093264 -276.219158)
		(end 358.097074 -276.221444)
		(width 0.0889)
		(layer "In11.Cu")
		(net "UPI_CPU1_CPU0_P2P2_DP<2>")
	)
	(segment
		(start 358.558846 -277.030688)
		(end 358.573324 -277.039324)
		(width 0.0889)
		(layer "In11.Cu")
		(net "UPI_CPU1_CPU0_P2P2_DP<2>")
	)
	(segment
		(start 55.335424 -332.140306)
		(end 55.334408 -332.139036)
		(width 0.14732)
		(layer "In11.Cu")
		(net "UPI_CPU1_CPU0_P2P2_DP<2>")
	)
	(segment
		(start 354.616512 -288.103056)
		(end 354.616512 -288.1122)
		(width 0.0889)
		(layer "In11.Cu")
		(net "UPI_CPU1_CPU0_P2P2_DP<2>")
	)
	(segment
		(start 354.146612 -288.899346)
		(end 354.146612 -289.079178)
		(width 0.0889)
		(layer "In11.Cu")
		(net "UPI_CPU1_CPU0_P2P2_DP<2>")
	)
	(segment
		(start 358.093518 -278.82596)
		(end 358.092502 -278.826468)
		(width 0.0889)
		(layer "In11.Cu")
		(net "UPI_CPU1_CPU0_P2P2_DP<2>")
	)
	(segment
		(start 85.404706 -290.4617)
		(end 85.404706 -288.327592)
		(width 0.0889)
		(layer "In11.Cu")
		(net "UPI_CPU1_CPU0_P2P2_DP<2>")
	)
	(segment
		(start 60.471304 -314.114688)
		(end 61.57595 -313.009788)
		(width 0.14732)
		(layer "In11.Cu")
		(net "UPI_CPU1_CPU0_P2P2_DP<2>")
	)
	(segment
		(start 356.495858 -284.847538)
		(end 356.495858 -284.858206)
		(width 0.0889)
		(layer "In11.Cu")
		(net "UPI_CPU1_CPU0_P2P2_DP<2>")
	)
	(segment
		(start 55.335678 -332.140052)
		(end 55.335424 -332.140306)
		(width 0.14732)
		(layer "In11.Cu")
		(net "UPI_CPU1_CPU0_P2P2_DP<2>")
	)
	(segment
		(start 82.937858 -292.868604)
		(end 84.500466 -291.305996)
		(width 0.14732)
		(layer "In11.Cu")
		(net "UPI_CPU1_CPU0_P2P2_DP<2>")
	)
	(segment
		(start 84.51596 -291.290502)
		(end 84.575904 -291.290502)
		(width 0.0889)
		(layer "In11.Cu")
		(net "UPI_CPU1_CPU0_P2P2_DP<2>")
	)
	(segment
		(start 54.396386 -322.85559)
		(end 55.275226 -318.43853)
		(width 0.14732)
		(layer "In11.Cu")
		(net "UPI_CPU1_CPU0_P2P2_DP<2>")
	)
	(segment
		(start 265.362944 -382.540764)
		(end 265.36269 -382.541018)
		(width 0.14732)
		(layer "In11.Cu")
		(net "UPI_CPU1_CPU0_P2P2_DP<2>")
	)
	(segment
		(start 52.43576 -329.236832)
		(end 52.43576 -324.816216)
		(width 0.14732)
		(layer "In11.Cu")
		(net "UPI_CPU1_CPU0_P2P2_DP<2>")
	)
	(segment
		(start 340.586314 -310.189626)
		(end 322.51015 -328.26579)
		(width 0.14732)
		(layer "In11.Cu")
		(net "UPI_CPU1_CPU0_P2P2_DP<2>")
	)
	(segment
		(start 57.341008 -316.206124)
		(end 60.471304 -314.114688)
		(width 0.14732)
		(layer "In11.Cu")
		(net "UPI_CPU1_CPU0_P2P2_DP<2>")
	)
	(segment
		(start 56.307736 -333.301086)
		(end 55.335678 -332.140052)
		(width 0.14732)
		(layer "In11.Cu")
		(net "UPI_CPU1_CPU0_P2P2_DP<2>")
	)
	(segment
		(start 357.183944 -276.165818)
		(end 357.205026 -276.243796)
		(width 0.0889)
		(layer "In11.Cu")
		(net "UPI_CPU1_CPU0_P2P2_DP<2>")
	)
	(segment
		(start 355.556058 -286.463994)
		(end 355.556058 -286.475424)
		(width 0.0889)
		(layer "In11.Cu")
		(net "UPI_CPU1_CPU0_P2P2_DP<2>")
	)
	(segment
		(start 354.616512 -291.419534)
		(end 354.658676 -291.461698)
		(width 0.0889)
		(layer "In11.Cu")
		(net "UPI_CPU1_CPU0_P2P2_DP<2>")
	)
	(segment
		(start 55.318152 -332.119478)
		(end 52.43576 -329.236832)
		(width 0.14732)
		(layer "In11.Cu")
		(net "UPI_CPU1_CPU0_P2P2_DP<2>")
	)
	(segment
		(start 86.940644 -286.456882)
		(end 86.940644 -286.48533)
		(width 0.0889)
		(layer "In11.Cu")
		(net "UPI_CPU1_CPU0_P2P2_DP<2>")
	)
	(segment
		(start 354.658676 -291.483796)
		(end 354.658676 -291.862002)
		(width 0.14732)
		(layer "In11.Cu")
		(net "UPI_CPU1_CPU0_P2P2_DP<2>")
	)
	(segment
		(start 161.475674 -391.31367)
		(end 127.078232 -391.31367)
		(width 0.14732)
		(layer "In11.Cu")
		(net "UPI_CPU1_CPU0_P2P2_DP<2>")
	)
	(segment
		(start 358.097074 -276.221444)
		(end 358.105456 -276.22627)
		(width 0.0889)
		(layer "In11.Cu")
		(net "UPI_CPU1_CPU0_P2P2_DP<2>")
	)
	(segment
		(start 358.573324 -278.00554)
		(end 358.572308 -278.006302)
		(width 0.0889)
		(layer "In11.Cu")
		(net "UPI_CPU1_CPU0_P2P2_DP<2>")
	)
	(segment
		(start 278.01824 -349.32112)
		(end 278.01824 -369.885214)
		(width 0.14732)
		(layer "In11.Cu")
		(net "UPI_CPU1_CPU0_P2P2_DP<2>")
	)
	(segment
		(start 86.280498 -287.4518)
		(end 86.280498 -287.28924)
		(width 0.0889)
		(layer "In11.Cu")
		(net "UPI_CPU1_CPU0_P2P2_DP<2>")
	)
	(segment
		(start 358.092502 -278.826468)
		(end 358.084628 -278.83104)
		(width 0.0889)
		(layer "In11.Cu")
		(net "UPI_CPU1_CPU0_P2P2_DP<2>")
	)
	(segment
		(start 355.284024 -286.958532)
		(end 355.273356 -286.964882)
		(width 0.0889)
		(layer "In11.Cu")
		(net "UPI_CPU1_CPU0_P2P2_DP<2>")
	)
	(segment
		(start 93.657928 -386.355844)
		(end 70.93458 -376.943366)
		(width 0.14732)
		(layer "In11.Cu")
		(net "UPI_CPU1_CPU0_P2P2_DP<2>")
	)
	(segment
		(start 57.279794 -334.46212)
		(end 56.30799 -333.30134)
		(width 0.14732)
		(layer "In11.Cu")
		(net "UPI_CPU1_CPU0_P2P2_DP<2>")
	)
	(segment
		(start 321.3862 -330.979272)
		(end 311.023762 -341.34171)
		(width 0.14732)
		(layer "In11.Cu")
		(net "UPI_CPU1_CPU0_P2P2_DP<2>")
	)
	(segment
		(start 352.780092 -300.299628)
		(end 344.518996 -308.560724)
		(width 0.14732)
		(layer "In11.Cu")
		(net "UPI_CPU1_CPU0_P2P2_DP<2>")
	)
	(segment
		(start 354.658676 -291.862002)
		(end 353.856036 -292.664642)
		(width 0.14732)
		(layer "In11.Cu")
		(net "UPI_CPU1_CPU0_P2P2_DP<2>")
	)
	(segment
		(start 353.856036 -292.664642)
		(end 353.856036 -297.701462)
		(width 0.14732)
		(layer "In11.Cu")
		(net "UPI_CPU1_CPU0_P2P2_DP<2>")
	)
	(segment
		(start 86.68893 -287.018222)
		(end 86.845394 -287.28924)
		(width 0.0889)
		(layer "In11.Cu")
		(net "UPI_CPU1_CPU0_P2P2_DP<2>")
	)
	(segment
		(start 357.633524 -281.261312)
		(end 357.622856 -281.267662)
		(width 0.0889)
		(layer "In11.Cu")
		(net "UPI_CPU1_CPU0_P2P2_DP<2>")
	)
	(segment
		(start 356.965758 -284.025848)
		(end 356.965758 -284.04439)
		(width 0.0889)
		(layer "In11.Cu")
		(net "UPI_CPU1_CPU0_P2P2_DP<2>")
	)
	(segment
		(start 355.086158 -287.281366)
		(end 355.086666 -287.28924)
		(width 0.0889)
		(layer "In11.Cu")
		(net "UPI_CPU1_CPU0_P2P2_DP<2>")
	)
	(segment
		(start 85.404706 -288.327592)
		(end 86.280498 -287.4518)
		(width 0.0889)
		(layer "In11.Cu")
		(net "UPI_CPU1_CPU0_P2P2_DP<2>")
	)
	(arc
		(start 354.795074 -287.783778)
		(mid 354.66416 -287.920138)
		(end 354.616512 -288.103056)
		(width 0.0889)
		(layer "In11.Cu")
		(net "UPI_CPU1_CPU0_P2P2_DP<2>")
	)
	(arc
		(start 86.092792 -285.985712)
		(mid 86.375494 -285.90997)
		(end 86.658196 -285.985712)
		(width 0.0889)
		(layer "In11.Cu")
		(net "UPI_CPU1_CPU0_P2P2_DP<2>")
	)
	(arc
		(start 358.084628 -278.83104)
		(mid 357.953714 -278.9674)
		(end 357.906066 -279.150318)
		(width 0.0889)
		(layer "In11.Cu")
		(net "UPI_CPU1_CPU0_P2P2_DP<2>")
	)
	(arc
		(start 355.086666 -287.28924)
		(mid 355.012675 -287.568806)
		(end 354.81006 -287.775142)
		(width 0.0889)
		(layer "In11.Cu")
		(net "UPI_CPU1_CPU0_P2P2_DP<2>")
	)
	(arc
		(start 357.435658 -281.599894)
		(mid 357.487796 -281.782662)
		(end 357.622856 -281.916378)
		(width 0.0889)
		(layer "In11.Cu")
		(net "UPI_CPU1_CPU0_P2P2_DP<2>")
	)
	(arc
		(start 356.204012 -285.34233)
		(mid 356.07351 -285.478688)
		(end 356.025958 -285.661354)
		(width 0.0889)
		(layer "In11.Cu")
		(net "UPI_CPU1_CPU0_P2P2_DP<2>")
	)
	(arc
		(start 358.573324 -277.039324)
		(mid 358.845406 -277.522432)
		(end 358.573324 -278.00554)
		(width 0.0889)
		(layer "In11.Cu")
		(net "UPI_CPU1_CPU0_P2P2_DP<2>")
	)
	(arc
		(start 357.905558 -280.78811)
		(mid 357.830492 -281.059756)
		(end 357.633524 -281.261312)
		(width 0.0889)
		(layer "In11.Cu")
		(net "UPI_CPU1_CPU0_P2P2_DP<2>")
	)
	(arc
		(start 357.906066 -279.150318)
		(mid 357.833831 -279.426842)
		(end 357.635556 -279.632664)
		(width 0.0889)
		(layer "In11.Cu")
		(net "UPI_CPU1_CPU0_P2P2_DP<2>")
	)
	(arc
		(start 86.280244 -287.28924)
		(mid 86.232565 -287.10634)
		(end 86.101682 -286.969962)
		(width 0.0889)
		(layer "In11.Cu")
		(net "UPI_CPU1_CPU0_P2P2_DP<2>")
	)
	(arc
		(start 358.375712 -278.33701)
		(mid 358.300097 -278.619274)
		(end 358.093518 -278.82596)
		(width 0.0889)
		(layer "In11.Cu")
		(net "UPI_CPU1_CPU0_P2P2_DP<2>")
	)
	(arc
		(start 355.743256 -286.150812)
		(mid 355.609049 -286.283128)
		(end 355.556058 -286.463994)
		(width 0.0889)
		(layer "In11.Cu")
		(net "UPI_CPU1_CPU0_P2P2_DP<2>")
	)
	(arc
		(start 357.152956 -283.709364)
		(mid 357.017911 -283.843088)
		(end 356.965758 -284.025848)
		(width 0.0889)
		(layer "In11.Cu")
		(net "UPI_CPU1_CPU0_P2P2_DP<2>")
	)
	(arc
		(start 357.905304 -280.759916)
		(mid 357.90561 -280.774011)
		(end 357.905558 -280.78811)
		(width 0.0889)
		(layer "In11.Cu")
		(net "UPI_CPU1_CPU0_P2P2_DP<2>")
	)
	(arc
		(start 357.435658 -283.219906)
		(mid 357.362966 -283.497111)
		(end 357.163624 -283.703014)
		(width 0.0889)
		(layer "In11.Cu")
		(net "UPI_CPU1_CPU0_P2P2_DP<2>")
	)
	(arc
		(start 357.435912 -279.976326)
		(mid 357.48896 -280.156705)
		(end 357.622856 -280.288746)
		(width 0.0889)
		(layer "In11.Cu")
		(net "UPI_CPU1_CPU0_P2P2_DP<2>")
	)
	(arc
		(start 357.622856 -282.895294)
		(mid 357.489479 -283.026054)
		(end 357.435658 -283.20492)
		(width 0.0889)
		(layer "In11.Cu")
		(net "UPI_CPU1_CPU0_P2P2_DP<2>")
	)
	(arc
		(start 354.146612 -289.079178)
		(mid 354.221719 -289.194324)
		(end 354.330762 -289.27806)
		(width 0.0889)
		(layer "In11.Cu")
		(net "UPI_CPU1_CPU0_P2P2_DP<2>")
	)
	(arc
		(start 356.025958 -285.661354)
		(mid 355.953266 -285.938559)
		(end 355.753924 -286.144462)
		(width 0.0889)
		(layer "In11.Cu")
		(net "UPI_CPU1_CPU0_P2P2_DP<2>")
	)
	(arc
		(start 357.633524 -281.922728)
		(mid 357.830459 -282.124303)
		(end 357.905558 -282.39593)
		(width 0.0889)
		(layer "In11.Cu")
		(net "UPI_CPU1_CPU0_P2P2_DP<2>")
	)
	(arc
		(start 85.810344 -286.456882)
		(mid 85.890506 -286.184693)
		(end 86.092792 -285.985712)
		(width 0.0889)
		(layer "In11.Cu")
		(net "UPI_CPU1_CPU0_P2P2_DP<2>")
	)
	(arc
		(start 86.658196 -285.985712)
		(mid 86.860482 -286.184693)
		(end 86.940644 -286.456882)
		(width 0.0889)
		(layer "In11.Cu")
		(net "UPI_CPU1_CPU0_P2P2_DP<2>")
	)
	(arc
		(start 357.905558 -282.39593)
		(mid 357.905604 -282.410029)
		(end 357.905304 -282.424124)
		(width 0.0889)
		(layer "In11.Cu")
		(net "UPI_CPU1_CPU0_P2P2_DP<2>")
	)
	(arc
		(start 357.905304 -282.424124)
		(mid 357.828351 -282.690993)
		(end 357.633524 -282.888944)
		(width 0.0889)
		(layer "In11.Cu")
		(net "UPI_CPU1_CPU0_P2P2_DP<2>")
	)
	(arc
		(start 86.092792 -286.964882)
		(mid 85.888457 -286.762277)
		(end 85.810344 -286.48533)
		(width 0.0889)
		(layer "In11.Cu")
		(net "UPI_CPU1_CPU0_P2P2_DP<2>")
	)
	(arc
		(start 357.633524 -280.295096)
		(mid 357.828356 -280.493044)
		(end 357.905304 -280.759916)
		(width 0.0889)
		(layer "In11.Cu")
		(net "UPI_CPU1_CPU0_P2P2_DP<2>")
	)
	(arc
		(start 354.333556 -288.592514)
		(mid 354.200991 -288.722109)
		(end 354.146612 -288.899346)
		(width 0.0889)
		(layer "In11.Cu")
		(net "UPI_CPU1_CPU0_P2P2_DP<2>")
	)
	(arc
		(start 357.205026 -276.243796)
		(mid 357.369122 -276.268143)
		(end 357.527606 -276.219158)
		(width 0.0889)
		(layer "In11.Cu")
		(net "UPI_CPU1_CPU0_P2P2_DP<2>")
	)
	(arc
		(start 356.495858 -284.858206)
		(mid 356.417698 -285.134365)
		(end 356.213918 -285.336488)
		(width 0.0889)
		(layer "In11.Cu")
		(net "UPI_CPU1_CPU0_P2P2_DP<2>")
	)
	(arc
		(start 355.556058 -286.475424)
		(mid 355.483366 -286.752629)
		(end 355.284024 -286.958532)
		(width 0.0889)
		(layer "In11.Cu")
		(net "UPI_CPU1_CPU0_P2P2_DP<2>")
	)
	(arc
		(start 358.105456 -276.22627)
		(mid 358.303684 -276.432118)
		(end 358.375966 -276.708616)
		(width 0.0889)
		(layer "In11.Cu")
		(net "UPI_CPU1_CPU0_P2P2_DP<2>")
	)
	(arc
		(start 356.678992 -284.52572)
		(mid 356.544862 -284.662418)
		(end 356.495858 -284.847538)
		(width 0.0889)
		(layer "In11.Cu")
		(net "UPI_CPU1_CPU0_P2P2_DP<2>")
	)
	(arc
		(start 356.965758 -284.04439)
		(mid 356.887598 -284.320549)
		(end 356.683818 -284.522672)
		(width 0.0889)
		(layer "In11.Cu")
		(net "UPI_CPU1_CPU0_P2P2_DP<2>")
	)
	(arc
		(start 358.554274 -278.017224)
		(mid 358.42336 -278.153584)
		(end 358.375712 -278.336502)
		(width 0.0889)
		(layer "In11.Cu")
		(net "UPI_CPU1_CPU0_P2P2_DP<2>")
	)
	(arc
		(start 357.622856 -281.267662)
		(mid 357.487811 -281.401386)
		(end 357.435658 -281.584146)
		(width 0.0889)
		(layer "In11.Cu")
		(net "UPI_CPU1_CPU0_P2P2_DP<2>")
	)
	(arc
		(start 357.527606 -276.219158)
		(mid 357.804419 -276.143288)
		(end 358.08285 -276.213062)
		(width 0.0889)
		(layer "In11.Cu")
		(net "UPI_CPU1_CPU0_P2P2_DP<2>")
	)
	(arc
		(start 86.940644 -286.48533)
		(mid 86.878425 -286.733647)
		(end 86.71306 -286.929068)
		(width 0.0889)
		(layer "In11.Cu")
		(net "UPI_CPU1_CPU0_P2P2_DP<2>")
	)
	(arc
		(start 355.273356 -286.964882)
		(mid 355.138311 -287.098606)
		(end 355.086158 -287.281366)
		(width 0.0889)
		(layer "In11.Cu")
		(net "UPI_CPU1_CPU0_P2P2_DP<2>")
	)
	(arc
		(start 358.375966 -276.708616)
		(mid 358.423645 -276.891516)
		(end 358.554528 -277.027894)
		(width 0.0889)
		(layer "In11.Cu")
		(net "UPI_CPU1_CPU0_P2P2_DP<2>")
	)
	(arc
		(start 357.614474 -279.644856)
		(mid 357.48356 -279.781216)
		(end 357.435912 -279.964134)
		(width 0.0889)
		(layer "In11.Cu")
		(net "UPI_CPU1_CPU0_P2P2_DP<2>")
	)
	(arc
		(start 354.330762 -289.27806)
		(mid 354.488848 -289.398978)
		(end 354.598478 -289.56508)
		(width 0.0889)
		(layer "In11.Cu")
		(net "UPI_CPU1_CPU0_P2P2_DP<2>")
	)
	(arc
		(start 354.616004 -288.125154)
		(mid 354.538115 -288.389841)
		(end 354.344224 -288.586164)
		(width 0.0889)
		(layer "In11.Cu")
		(net "UPI_CPU1_CPU0_P2P2_DP<2>")
	)
	(segment
		(start 335.725262 -280.242264)
		(end 335.725262 -280.778204)
		(width 0.13208)
		(layer "F.Cu")
		(net "UPI_CPU1_CPU0_P2P2_DP<23>")
	)
	(segment
		(start 109.400594 -273.730974)
		(end 109.400594 -274.266914)
		(width 0.13208)
		(layer "F.Cu")
		(net "UPI_CPU1_CPU0_P2P2_DP<23>")
	)
	(segment
		(start 310.332628 -308.560216)
		(end 308.97322 -309.46852)
		(width 0.14732)
		(layer "In11.Cu")
		(net "UPI_CPU1_CPU0_P2P2_DP<23>")
	)
	(segment
		(start 108.647992 -279.474676)
		(end 108.656882 -279.469596)
		(width 0.0889)
		(layer "In11.Cu")
		(net "UPI_CPU1_CPU0_P2P2_DP<23>")
	)
	(segment
		(start 334.411066 -282.405836)
		(end 334.411066 -282.413456)
		(width 0.0889)
		(layer "In11.Cu")
		(net "UPI_CPU1_CPU0_P2P2_DP<23>")
	)
	(segment
		(start 286.069024 -317.021972)
		(end 286.069024 -317.503048)
		(width 0.14732)
		(layer "In11.Cu")
		(net "UPI_CPU1_CPU0_P2P2_DP<23>")
	)
	(segment
		(start 288.604198 -315.62421)
		(end 287.635442 -316.592966)
		(width 0.14732)
		(layer "In11.Cu")
		(net "UPI_CPU1_CPU0_P2P2_DP<23>")
	)
	(segment
		(start 249.10669 -351.301304)
		(end 248.677684 -351.225358)
		(width 0.14732)
		(layer "In11.Cu")
		(net "UPI_CPU1_CPU0_P2P2_DP<23>")
	)
	(segment
		(start 108.178092 -280.288492)
		(end 108.179108 -280.287984)
		(width 0.0889)
		(layer "In11.Cu")
		(net "UPI_CPU1_CPU0_P2P2_DP<23>")
	)
	(segment
		(start 112.124744 -288.264346)
		(end 112.124744 -288.103056)
		(width 0.0889)
		(layer "In11.Cu")
		(net "UPI_CPU1_CPU0_P2P2_DP<23>")
	)
	(segment
		(start 299.8089 -315.398658)
		(end 299.8089 -317.58636)
		(width 0.14732)
		(layer "In11.Cu")
		(net "UPI_CPU1_CPU0_P2P2_DP<23>")
	)
	(segment
		(start 109.587792 -274.591272)
		(end 109.596682 -274.586192)
		(width 0.0889)
		(layer "In11.Cu")
		(net "UPI_CPU1_CPU0_P2P2_DP<23>")
	)
	(segment
		(start 329.573636 -292.045898)
		(end 327.612248 -298.489116)
		(width 0.14732)
		(layer "In11.Cu")
		(net "UPI_CPU1_CPU0_P2P2_DP<23>")
	)
	(segment
		(start 333.511906 -287.672526)
		(end 333.511906 -287.880806)
		(width 0.14732)
		(layer "In11.Cu")
		(net "UPI_CPU1_CPU0_P2P2_DP<23>")
	)
	(segment
		(start 251.158248 -342.3412)
		(end 250.285758 -342.3412)
		(width 0.14732)
		(layer "In11.Cu")
		(net "UPI_CPU1_CPU0_P2P2_DP<23>")
	)
	(segment
		(start 251.466096 -346.666312)
		(end 251.158248 -346.97416)
		(width 0.14732)
		(layer "In11.Cu")
		(net "UPI_CPU1_CPU0_P2P2_DP<23>")
	)
	(segment
		(start 110.066582 -284.52826)
		(end 110.06582 -284.527752)
		(width 0.0889)
		(layer "In11.Cu")
		(net "UPI_CPU1_CPU0_P2P2_DP<23>")
	)
	(segment
		(start 107.832652 -298.873672)
		(end 108.573062 -297.875198)
		(width 0.14732)
		(layer "In11.Cu")
		(net "UPI_CPU1_CPU0_P2P2_DP<23>")
	)
	(segment
		(start 199.94626 -366.589818)
		(end 160.765236 -373.498364)
		(width 0.14732)
		(layer "In11.Cu")
		(net "UPI_CPU1_CPU0_P2P2_DP<23>")
	)
	(segment
		(start 334.597502 -284.357572)
		(end 334.598518 -284.35808)
		(width 0.0889)
		(layer "In11.Cu")
		(net "UPI_CPU1_CPU0_P2P2_DP<23>")
	)
	(segment
		(start 109.11967 -290.341812)
		(end 109.406944 -290.054538)
		(width 0.0889)
		(layer "In11.Cu")
		(net "UPI_CPU1_CPU0_P2P2_DP<23>")
	)
	(segment
		(start 109.117892 -278.66086)
		(end 109.126782 -278.65578)
		(width 0.0889)
		(layer "In11.Cu")
		(net "UPI_CPU1_CPU0_P2P2_DP<23>")
	)
	(segment
		(start 110.057692 -277.032974)
		(end 110.058454 -277.032466)
		(width 0.0889)
		(layer "In11.Cu")
		(net "UPI_CPU1_CPU0_P2P2_DP<23>")
	)
	(segment
		(start 77.071728 -326.993758)
		(end 84.50707 -319.557654)
		(width 0.14732)
		(layer "In11.Cu")
		(net "UPI_CPU1_CPU0_P2P2_DP<23>")
	)
	(segment
		(start 110.06582 -284.527752)
		(end 110.060994 -284.525212)
		(width 0.0889)
		(layer "In11.Cu")
		(net "UPI_CPU1_CPU0_P2P2_DP<23>")
	)
	(segment
		(start 111.184944 -286.475424)
		(end 111.184944 -286.466788)
		(width 0.0889)
		(layer "In11.Cu")
		(net "UPI_CPU1_CPU0_P2P2_DP<23>")
	)
	(segment
		(start 262.21944 -323.681852)
		(end 262.744458 -324.20687)
		(width 0.14732)
		(layer "In11.Cu")
		(net "UPI_CPU1_CPU0_P2P2_DP<23>")
	)
	(segment
		(start 299.869352 -315.087762)
		(end 299.8089 -315.398658)
		(width 0.14732)
		(layer "In11.Cu")
		(net "UPI_CPU1_CPU0_P2P2_DP<23>")
	)
	(segment
		(start 250.138438 -344.805)
		(end 250.138438 -345.39428)
		(width 0.14732)
		(layer "In11.Cu")
		(net "UPI_CPU1_CPU0_P2P2_DP<23>")
	)
	(segment
		(start 109.126782 -282.900628)
		(end 109.117892 -282.895548)
		(width 0.0889)
		(layer "In11.Cu")
		(net "UPI_CPU1_CPU0_P2P2_DP<23>")
	)
	(segment
		(start 333.940912 -286.475424)
		(end 333.940912 -286.48533)
		(width 0.0889)
		(layer "In11.Cu")
		(net "UPI_CPU1_CPU0_P2P2_DP<23>")
	)
	(segment
		(start 251.158248 -349.29064)
		(end 250.285758 -349.29064)
		(width 0.14732)
		(layer "In11.Cu")
		(net "UPI_CPU1_CPU0_P2P2_DP<23>")
	)
	(segment
		(start 333.511906 -287.650428)
		(end 333.511906 -287.672526)
		(width 0.0889)
		(layer "In11.Cu")
		(net "UPI_CPU1_CPU0_P2P2_DP<23>")
	)
	(segment
		(start 78.723236 -359.899966)
		(end 75.604878 -352.367596)
		(width 0.14732)
		(layer "In11.Cu")
		(net "UPI_CPU1_CPU0_P2P2_DP<23>")
	)
	(segment
		(start 111.655098 -289.323526)
		(end 111.655098 -288.794952)
		(width 0.0889)
		(layer "In11.Cu")
		(net "UPI_CPU1_CPU0_P2P2_DP<23>")
	)
	(segment
		(start 334.598264 -285.336996)
		(end 334.589374 -285.342076)
		(width 0.0889)
		(layer "In11.Cu")
		(net "UPI_CPU1_CPU0_P2P2_DP<23>")
	)
	(segment
		(start 291.127434 -317.955168)
		(end 290.637468 -317.465202)
		(width 0.14732)
		(layer "In11.Cu")
		(net "UPI_CPU1_CPU0_P2P2_DP<23>")
	)
	(segment
		(start 251.466096 -341.216488)
		(end 251.466096 -342.033352)
		(width 0.14732)
		(layer "In11.Cu")
		(net "UPI_CPU1_CPU0_P2P2_DP<23>")
	)
	(segment
		(start 105.298494 -301.535592)
		(end 107.832652 -298.873672)
		(width 0.14732)
		(layer "In11.Cu")
		(net "UPI_CPU1_CPU0_P2P2_DP<23>")
	)
	(segment
		(start 251.466096 -342.033352)
		(end 251.158248 -342.3412)
		(width 0.14732)
		(layer "In11.Cu")
		(net "UPI_CPU1_CPU0_P2P2_DP<23>")
	)
	(segment
		(start 263.187942 -322.552822)
		(end 262.21944 -323.521324)
		(width 0.14732)
		(layer "In11.Cu")
		(net "UPI_CPU1_CPU0_P2P2_DP<23>")
	)
	(segment
		(start 250.285758 -345.5416)
		(end 251.158248 -345.5416)
		(width 0.14732)
		(layer "In11.Cu")
		(net "UPI_CPU1_CPU0_P2P2_DP<23>")
	)
	(segment
		(start 250.285758 -347.85808)
		(end 251.158248 -347.85808)
		(width 0.14732)
		(layer "In11.Cu")
		(net "UPI_CPU1_CPU0_P2P2_DP<23>")
	)
	(segment
		(start 109.11967 -290.60775)
		(end 109.11967 -290.341812)
		(width 0.0889)
		(layer "In11.Cu")
		(net "UPI_CPU1_CPU0_P2P2_DP<23>")
	)
	(segment
		(start 108.881164 -292.775132)
		(end 109.07776 -292.30066)
		(width 0.14732)
		(layer "In11.Cu")
		(net "UPI_CPU1_CPU0_P2P2_DP<23>")
	)
	(segment
		(start 333.658464 -286.964882)
		(end 333.65694 -286.965898)
		(width 0.0889)
		(layer "In11.Cu")
		(net "UPI_CPU1_CPU0_P2P2_DP<23>")
	)
	(segment
		(start 333.65694 -286.965898)
		(end 333.65567 -286.96666)
		(width 0.0889)
		(layer "In11.Cu")
		(net "UPI_CPU1_CPU0_P2P2_DP<23>")
	)
	(segment
		(start 250.285758 -349.29064)
		(end 250.138438 -349.43796)
		(width 0.14732)
		(layer "In11.Cu")
		(net "UPI_CPU1_CPU0_P2P2_DP<23>")
	)
	(segment
		(start 262.21944 -323.521324)
		(end 262.21944 -323.681852)
		(width 0.14732)
		(layer "In11.Cu")
		(net "UPI_CPU1_CPU0_P2P2_DP<23>")
	)
	(segment
		(start 290.637468 -316.474602)
		(end 289.787076 -315.62421)
		(width 0.14732)
		(layer "In11.Cu")
		(net "UPI_CPU1_CPU0_P2P2_DP<23>")
	)
	(segment
		(start 247.87733 -352.161602)
		(end 247.208294 -352.63074)
		(width 0.14732)
		(layer "In11.Cu")
		(net "UPI_CPU1_CPU0_P2P2_DP<23>")
	)
	(segment
		(start 251.158248 -343.22512)
		(end 251.466096 -343.532968)
		(width 0.14732)
		(layer "In11.Cu")
		(net "UPI_CPU1_CPU0_P2P2_DP<23>")
	)
	(segment
		(start 99.787456 -369.546886)
		(end 80.297782 -361.474512)
		(width 0.14732)
		(layer "In11.Cu")
		(net "UPI_CPU1_CPU0_P2P2_DP<23>")
	)
	(segment
		(start 275.403056 -320.233802)
		(end 275.403056 -321.939666)
		(width 0.14732)
		(layer "In11.Cu")
		(net "UPI_CPU1_CPU0_P2P2_DP<23>")
	)
	(segment
		(start 109.596682 -283.714444)
		(end 109.587792 -283.709364)
		(width 0.0889)
		(layer "In11.Cu")
		(net "UPI_CPU1_CPU0_P2P2_DP<23>")
	)
	(segment
		(start 251.158248 -346.97416)
		(end 250.285758 -346.97416)
		(width 0.14732)
		(layer "In11.Cu")
		(net "UPI_CPU1_CPU0_P2P2_DP<23>")
	)
	(segment
		(start 109.596428 -275.575522)
		(end 109.587538 -275.570442)
		(width 0.0889)
		(layer "In11.Cu")
		(net "UPI_CPU1_CPU0_P2P2_DP<23>")
	)
	(segment
		(start 333.469742 -287.608264)
		(end 333.511906 -287.650428)
		(width 0.0889)
		(layer "In11.Cu")
		(net "UPI_CPU1_CPU0_P2P2_DP<23>")
	)
	(segment
		(start 261.045198 -324.695566)
		(end 260.408674 -325.33209)
		(width 0.14732)
		(layer "In11.Cu")
		(net "UPI_CPU1_CPU0_P2P2_DP<23>")
	)
	(segment
		(start 250.285758 -346.97416)
		(end 250.138438 -347.12148)
		(width 0.14732)
		(layer "In11.Cu")
		(net "UPI_CPU1_CPU0_P2P2_DP<23>")
	)
	(segment
		(start 334.128364 -282.895548)
		(end 334.119474 -282.900628)
		(width 0.0889)
		(layer "In11.Cu")
		(net "UPI_CPU1_CPU0_P2P2_DP<23>")
	)
	(segment
		(start 246.05488 -353.062286)
		(end 245.978934 -353.491038)
		(width 0.14732)
		(layer "In11.Cu")
		(net "UPI_CPU1_CPU0_P2P2_DP<23>")
	)
	(segment
		(start 333.65567 -286.96666)
		(end 333.652114 -286.968438)
		(width 0.0889)
		(layer "In11.Cu")
		(net "UPI_CPU1_CPU0_P2P2_DP<23>")
	)
	(segment
		(start 286.069024 -317.503048)
		(end 285.57347 -317.998602)
		(width 0.14732)
		(layer "In11.Cu")
		(net "UPI_CPU1_CPU0_P2P2_DP<23>")
	)
	(segment
		(start 247.208294 -352.63074)
		(end 246.779288 -352.554794)
		(width 0.14732)
		(layer "In11.Cu")
		(net "UPI_CPU1_CPU0_P2P2_DP<23>")
	)
	(segment
		(start 76.599288 -327.992486)
		(end 77.071728 -326.993758)
		(width 0.14732)
		(layer "In11.Cu")
		(net "UPI_CPU1_CPU0_P2P2_DP<23>")
	)
	(segment
		(start 250.138438 -338.124292)
		(end 250.138438 -340.76132)
		(width 0.14732)
		(layer "In11.Cu")
		(net "UPI_CPU1_CPU0_P2P2_DP<23>")
	)
	(segment
		(start 109.673136 -289.788346)
		(end 109.87151 -289.589972)
		(width 0.0889)
		(layer "In11.Cu")
		(net "UPI_CPU1_CPU0_P2P2_DP<23>")
	)
	(segment
		(start 109.305344 -278.336502)
		(end 109.305344 -278.31796)
		(width 0.0889)
		(layer "In11.Cu")
		(net "UPI_CPU1_CPU0_P2P2_DP<23>")
	)
	(segment
		(start 126.425706 -373.498364)
		(end 99.787456 -369.546886)
		(width 0.14732)
		(layer "In11.Cu")
		(net "UPI_CPU1_CPU0_P2P2_DP<23>")
	)
	(segment
		(start 333.652114 -286.968438)
		(end 333.649574 -286.969962)
		(width 0.0889)
		(layer "In11.Cu")
		(net "UPI_CPU1_CPU0_P2P2_DP<23>")
	)
	(segment
		(start 334.598518 -282.081478)
		(end 334.589628 -282.086558)
		(width 0.0889)
		(layer "In11.Cu")
		(net "UPI_CPU1_CPU0_P2P2_DP<23>")
	)
	(segment
		(start 111.476536 -286.969962)
		(end 111.461296 -286.961072)
		(width 0.0889)
		(layer "In11.Cu")
		(net "UPI_CPU1_CPU0_P2P2_DP<23>")
	)
	(segment
		(start 108.177076 -281.2669)
		(end 108.166154 -281.26055)
		(width 0.0889)
		(layer "In11.Cu")
		(net "UPI_CPU1_CPU0_P2P2_DP<23>")
	)
	(segment
		(start 297.968162 -318.084708)
		(end 297.304206 -317.420752)
		(width 0.14732)
		(layer "In11.Cu")
		(net "UPI_CPU1_CPU0_P2P2_DP<23>")
	)
	(segment
		(start 251.466096 -344.349832)
		(end 251.158248 -344.65768)
		(width 0.14732)
		(layer "In11.Cu")
		(net "UPI_CPU1_CPU0_P2P2_DP<23>")
	)
	(segment
		(start 111.04499 -289.490912)
		(end 111.14405 -289.589972)
		(width 0.0889)
		(layer "In11.Cu")
		(net "UPI_CPU1_CPU0_P2P2_DP<23>")
	)
	(segment
		(start 282.965906 -317.998602)
		(end 282.423362 -318.541146)
		(width 0.14732)
		(layer "In11.Cu")
		(net "UPI_CPU1_CPU0_P2P2_DP<23>")
	)
	(segment
		(start 111.388652 -289.589972)
		(end 111.655098 -289.323526)
		(width 0.0889)
		(layer "In11.Cu")
		(net "UPI_CPU1_CPU0_P2P2_DP<23>")
	)
	(segment
		(start 260.408674 -325.33209)
		(end 260.408674 -327.854056)
		(width 0.14732)
		(layer "In11.Cu")
		(net "UPI_CPU1_CPU0_P2P2_DP<23>")
	)
	(segment
		(start 80.297782 -361.474512)
		(end 78.723236 -359.899966)
		(width 0.14732)
		(layer "In11.Cu")
		(net "UPI_CPU1_CPU0_P2P2_DP<23>")
	)
	(segment
		(start 282.423362 -318.541146)
		(end 277.095712 -318.541146)
		(width 0.14732)
		(layer "In11.Cu")
		(net "UPI_CPU1_CPU0_P2P2_DP<23>")
	)
	(segment
		(start 335.067402 -281.26817)
		(end 335.059528 -281.272742)
		(width 0.0889)
		(layer "In11.Cu")
		(net "UPI_CPU1_CPU0_P2P2_DP<23>")
	)
	(segment
		(start 108.881164 -297.131486)
		(end 108.881164 -292.775132)
		(width 0.14732)
		(layer "In11.Cu")
		(net "UPI_CPU1_CPU0_P2P2_DP<23>")
	)
	(segment
		(start 109.11967 -291.384228)
		(end 109.11967 -290.98367)
		(width 0.0889)
		(layer "In11.Cu")
		(net "UPI_CPU1_CPU0_P2P2_DP<23>")
	)
	(segment
		(start 251.158248 -344.65768)
		(end 250.285758 -344.65768)
		(width 0.14732)
		(layer "In11.Cu")
		(net "UPI_CPU1_CPU0_P2P2_DP<23>")
	)
	(segment
		(start 251.466096 -348.982792)
		(end 251.158248 -349.29064)
		(width 0.14732)
		(layer "In11.Cu")
		(net "UPI_CPU1_CPU0_P2P2_DP<23>")
	)
	(segment
		(start 250.138438 -347.12148)
		(end 250.138438 -347.71076)
		(width 0.14732)
		(layer "In11.Cu")
		(net "UPI_CPU1_CPU0_P2P2_DP<23>")
	)
	(segment
		(start 262.744458 -324.642226)
		(end 262.1661 -325.220584)
		(width 0.14732)
		(layer "In11.Cu")
		(net "UPI_CPU1_CPU0_P2P2_DP<23>")
	)
	(segment
		(start 243.295424 -353.162362)
		(end 244.156484 -354.391722)
		(width 0.14732)
		(layer "In11.Cu")
		(net "UPI_CPU1_CPU0_P2P2_DP<23>")
	)
	(segment
		(start 110.21441 -289.589972)
		(end 110.31347 -289.490912)
		(width 0.0889)
		(layer "In11.Cu")
		(net "UPI_CPU1_CPU0_P2P2_DP<23>")
	)
	(segment
		(start 287.635442 -316.592966)
		(end 286.49803 -316.592966)
		(width 0.14732)
		(layer "In11.Cu")
		(net "UPI_CPU1_CPU0_P2P2_DP<23>")
	)
	(segment
		(start 244.156484 -354.391722)
		(end 244.080538 -354.820728)
		(width 0.14732)
		(layer "In11.Cu")
		(net "UPI_CPU1_CPU0_P2P2_DP<23>")
	)
	(segment
		(start 318.216788 -307.884576)
		(end 314.11545 -307.884576)
		(width 0.14732)
		(layer "In11.Cu")
		(net "UPI_CPU1_CPU0_P2P2_DP<23>")
	)
	(segment
		(start 109.87151 -289.589972)
		(end 110.21441 -289.589972)
		(width 0.0889)
		(layer "In11.Cu")
		(net "UPI_CPU1_CPU0_P2P2_DP<23>")
	)
	(segment
		(start 299.8089 -317.58636)
		(end 299.39742 -318.084708)
		(width 0.14732)
		(layer "In11.Cu")
		(net "UPI_CPU1_CPU0_P2P2_DP<23>")
	)
	(segment
		(start 101.120194 -305.92395)
		(end 105.29824 -301.535592)
		(width 0.14732)
		(layer "In11.Cu")
		(net "UPI_CPU1_CPU0_P2P2_DP<23>")
	)
	(segment
		(start 110.76813 -289.589972)
		(end 110.86719 -289.490912)
		(width 0.0889)
		(layer "In11.Cu")
		(net "UPI_CPU1_CPU0_P2P2_DP<23>")
	)
	(segment
		(start 308.97322 -309.46852)
		(end 308.19852 -310.24322)
		(width 0.14732)
		(layer "In11.Cu")
		(net "UPI_CPU1_CPU0_P2P2_DP<23>")
	)
	(segment
		(start 274.7899 -322.552822)
		(end 263.187942 -322.552822)
		(width 0.14732)
		(layer "In11.Cu")
		(net "UPI_CPU1_CPU0_P2P2_DP<23>")
	)
	(segment
		(start 108.835444 -279.150318)
		(end 108.835444 -279.140412)
		(width 0.0889)
		(layer "In11.Cu")
		(net "UPI_CPU1_CPU0_P2P2_DP<23>")
	)
	(segment
		(start 250.138438 -349.43796)
		(end 250.138438 -350.399604)
		(width 0.14732)
		(layer "In11.Cu")
		(net "UPI_CPU1_CPU0_P2P2_DP<23>")
	)
	(segment
		(start 245.229888 -351.628456)
		(end 245.19382 -351.832926)
		(width 0.14732)
		(layer "In11.Cu")
		(net "UPI_CPU1_CPU0_P2P2_DP<23>")
	)
	(segment
		(start 251.466096 -348.165928)
		(end 251.466096 -348.982792)
		(width 0.14732)
		(layer "In11.Cu")
		(net "UPI_CPU1_CPU0_P2P2_DP<23>")
	)
	(segment
		(start 251.158248 -340.90864)
		(end 251.466096 -341.216488)
		(width 0.14732)
		(layer "In11.Cu")
		(net "UPI_CPU1_CPU0_P2P2_DP<23>")
	)
	(segment
		(start 331.802994 -289.589972)
		(end 330.03617 -291.356796)
		(width 0.14732)
		(layer "In11.Cu")
		(net "UPI_CPU1_CPU0_P2P2_DP<23>")
	)
	(segment
		(start 250.138438 -342.48852)
		(end 250.138438 -343.0778)
		(width 0.14732)
		(layer "In11.Cu")
		(net "UPI_CPU1_CPU0_P2P2_DP<23>")
	)
	(segment
		(start 247.816878 -349.996252)
		(end 247.612154 -349.960184)
		(width 0.14732)
		(layer "In11.Cu")
		(net "UPI_CPU1_CPU0_P2P2_DP<23>")
	)
	(segment
		(start 260.408674 -327.854056)
		(end 250.138438 -338.124292)
		(width 0.14732)
		(layer "In11.Cu")
		(net "UPI_CPU1_CPU0_P2P2_DP<23>")
	)
	(segment
		(start 75.604878 -335.260442)
		(end 76.166218 -329.554332)
		(width 0.14732)
		(layer "In11.Cu")
		(net "UPI_CPU1_CPU0_P2P2_DP<23>")
	)
	(segment
		(start 212.261704 -368.761264)
		(end 199.94626 -366.589818)
		(width 0.14732)
		(layer "In11.Cu")
		(net "UPI_CPU1_CPU0_P2P2_DP<23>")
	)
	(segment
		(start 247.128284 -350.29902)
		(end 247.092216 -350.50349)
		(width 0.14732)
		(layer "In11.Cu")
		(net "UPI_CPU1_CPU0_P2P2_DP<23>")
	)
	(segment
		(start 335.412588 -280.778204)
		(end 335.347056 -280.843736)
		(width 0.0889)
		(layer "In11.Cu")
		(net "UPI_CPU1_CPU0_P2P2_DP<23>")
	)
	(segment
		(start 110.060994 -284.525212)
		(end 110.060232 -284.524704)
		(width 0.0889)
		(layer "In11.Cu")
		(net "UPI_CPU1_CPU0_P2P2_DP<23>")
	)
	(segment
		(start 250.138438 -347.71076)
		(end 250.285758 -347.85808)
		(width 0.14732)
		(layer "In11.Cu")
		(net "UPI_CPU1_CPU0_P2P2_DP<23>")
	)
	(segment
		(start 308.19852 -310.24322)
		(end 306.963826 -311.068466)
		(width 0.14732)
		(layer "In11.Cu")
		(net "UPI_CPU1_CPU0_P2P2_DP<23>")
	)
	(segment
		(start 250.138438 -343.0778)
		(end 250.285758 -343.22512)
		(width 0.14732)
		(layer "In11.Cu")
		(net "UPI_CPU1_CPU0_P2P2_DP<23>")
	)
	(segment
		(start 277.095712 -318.541146)
		(end 275.403056 -320.233802)
		(width 0.14732)
		(layer "In11.Cu")
		(net "UPI_CPU1_CPU0_P2P2_DP<23>")
	)
	(segment
		(start 109.305344 -283.229812)
		(end 109.305344 -283.219906)
		(width 0.0889)
		(layer "In11.Cu")
		(net "UPI_CPU1_CPU0_P2P2_DP<23>")
	)
	(segment
		(start 333.511906 -287.880806)
		(end 331.802994 -289.589718)
		(width 0.14732)
		(layer "In11.Cu")
		(net "UPI_CPU1_CPU0_P2P2_DP<23>")
	)
	(segment
		(start 250.138438 -345.39428)
		(end 250.285758 -345.5416)
		(width 0.14732)
		(layer "In11.Cu")
		(net "UPI_CPU1_CPU0_P2P2_DP<23>")
	)
	(segment
		(start 160.765236 -373.498364)
		(end 126.425706 -373.498364)
		(width 0.14732)
		(layer "In11.Cu")
		(net "UPI_CPU1_CPU0_P2P2_DP<23>")
	)
	(segment
		(start 334.133444 -283.547312)
		(end 334.140556 -283.551376)
		(width 0.0889)
		(layer "In11.Cu")
		(net "UPI_CPU1_CPU0_P2P2_DP<23>")
	)
	(segment
		(start 245.918482 -351.325688)
		(end 245.713758 -351.28962)
		(width 0.14732)
		(layer "In11.Cu")
		(net "UPI_CPU1_CPU0_P2P2_DP<23>")
	)
	(segment
		(start 249.540268 -350.997774)
		(end 249.10669 -351.301304)
		(width 0.14732)
		(layer "In11.Cu")
		(net "UPI_CPU1_CPU0_P2P2_DP<23>")
	)
	(segment
		(start 251.158248 -345.5416)
		(end 251.466096 -345.849448)
		(width 0.14732)
		(layer "In11.Cu")
		(net "UPI_CPU1_CPU0_P2P2_DP<23>")
	)
	(segment
		(start 261.205726 -324.695566)
		(end 261.045198 -324.695566)
		(width 0.14732)
		(layer "In11.Cu")
		(net "UPI_CPU1_CPU0_P2P2_DP<23>")
	)
	(segment
		(start 250.285758 -340.90864)
		(end 251.158248 -340.90864)
		(width 0.14732)
		(layer "In11.Cu")
		(net "UPI_CPU1_CPU0_P2P2_DP<23>")
	)
	(segment
		(start 108.365544 -281.59202)
		(end 108.365544 -281.583384)
		(width 0.0889)
		(layer "In11.Cu")
		(net "UPI_CPU1_CPU0_P2P2_DP<23>")
	)
	(segment
		(start 244.080538 -354.820728)
		(end 228.181408 -365.95431)
		(width 0.14732)
		(layer "In11.Cu")
		(net "UPI_CPU1_CPU0_P2P2_DP<23>")
	)
	(segment
		(start 285.57347 -317.998602)
		(end 282.965906 -317.998602)
		(width 0.14732)
		(layer "In11.Cu")
		(net "UPI_CPU1_CPU0_P2P2_DP<23>")
	)
	(segment
		(start 243.815362 -352.619056)
		(end 243.331492 -352.957892)
		(width 0.14732)
		(layer "In11.Cu")
		(net "UPI_CPU1_CPU0_P2P2_DP<23>")
	)
	(segment
		(start 248.677684 -351.225358)
		(end 247.816878 -349.996252)
		(width 0.14732)
		(layer "In11.Cu")
		(net "UPI_CPU1_CPU0_P2P2_DP<23>")
	)
	(segment
		(start 289.787076 -315.62421)
		(end 288.604198 -315.62421)
		(width 0.14732)
		(layer "In11.Cu")
		(net "UPI_CPU1_CPU0_P2P2_DP<23>")
	)
	(segment
		(start 228.181408 -365.95431)
		(end 212.261704 -368.761264)
		(width 0.14732)
		(layer "In11.Cu")
		(net "UPI_CPU1_CPU0_P2P2_DP<23>")
	)
	(segment
		(start 335.068418 -281.267662)
		(end 335.067402 -281.26817)
		(width 0.0889)
		(layer "In11.Cu")
		(net "UPI_CPU1_CPU0_P2P2_DP<23>")
	)
	(segment
		(start 247.953276 -351.73285)
		(end 247.87733 -352.161602)
		(width 0.14732)
		(layer "In11.Cu")
		(net "UPI_CPU1_CPU0_P2P2_DP<23>")
	)
	(segment
		(start 250.285758 -344.65768)
		(end 250.138438 -344.805)
		(width 0.14732)
		(layer "In11.Cu")
		(net "UPI_CPU1_CPU0_P2P2_DP<23>")
	)
	(segment
		(start 105.29824 -301.535592)
		(end 105.298494 -301.535592)
		(width 0.14732)
		(layer "In11.Cu")
		(net "UPI_CPU1_CPU0_P2P2_DP<23>")
	)
	(segment
		(start 262.744458 -324.20687)
		(end 262.744458 -324.642226)
		(width 0.14732)
		(layer "In11.Cu")
		(net "UPI_CPU1_CPU0_P2P2_DP<23>")
	)
	(segment
		(start 110.057692 -276.384258)
		(end 110.0455 -276.377146)
		(width 0.0889)
		(layer "In11.Cu")
		(net "UPI_CPU1_CPU0_P2P2_DP<23>")
	)
	(segment
		(start 313.9313 -307.9623)
		(end 311.775348 -307.9623)
		(width 0.14732)
		(layer "In11.Cu")
		(net "UPI_CPU1_CPU0_P2P2_DP<23>")
	)
	(segment
		(start 251.158248 -347.85808)
		(end 251.466096 -348.165928)
		(width 0.14732)
		(layer "In11.Cu")
		(net "UPI_CPU1_CPU0_P2P2_DP<23>")
	)
	(segment
		(start 261.730744 -325.220584)
		(end 261.205726 -324.695566)
		(width 0.14732)
		(layer "In11.Cu")
		(net "UPI_CPU1_CPU0_P2P2_DP<23>")
	)
	(segment
		(start 245.19382 -351.832926)
		(end 246.05488 -353.062286)
		(width 0.14732)
		(layer "In11.Cu")
		(net "UPI_CPU1_CPU0_P2P2_DP<23>")
	)
	(segment
		(start 333.469742 -287.19399)
		(end 333.469742 -287.608264)
		(width 0.0889)
		(layer "In11.Cu")
		(net "UPI_CPU1_CPU0_P2P2_DP<23>")
	)
	(segment
		(start 110.536482 -285.342076)
		(end 110.527592 -285.336996)
		(width 0.0889)
		(layer "In11.Cu")
		(net "UPI_CPU1_CPU0_P2P2_DP<23>")
	)
	(segment
		(start 299.39742 -318.084708)
		(end 297.968162 -318.084708)
		(width 0.14732)
		(layer "In11.Cu")
		(net "UPI_CPU1_CPU0_P2P2_DP<23>")
	)
	(segment
		(start 109.24413 -273.995896)
		(end 109.400594 -274.266914)
		(width 0.0889)
		(layer "In11.Cu")
		(net "UPI_CPU1_CPU0_P2P2_DP<23>")
	)
	(segment
		(start 302.064928 -313.09818)
		(end 299.869352 -315.087762)
		(width 0.14732)
		(layer "In11.Cu")
		(net "UPI_CPU1_CPU0_P2P2_DP<23>")
	)
	(segment
		(start 109.596682 -273.947636)
		(end 109.587792 -273.942556)
		(width 0.0889)
		(layer "In11.Cu")
		(net "UPI_CPU1_CPU0_P2P2_DP<23>")
	)
	(segment
		(start 335.725262 -280.778204)
		(end 335.412588 -280.778204)
		(width 0.0889)
		(layer "In11.Cu")
		(net "UPI_CPU1_CPU0_P2P2_DP<23>")
	)
	(segment
		(start 110.86719 -289.490912)
		(end 111.04499 -289.490912)
		(width 0.0889)
		(layer "In11.Cu")
		(net "UPI_CPU1_CPU0_P2P2_DP<23>")
	)
	(segment
		(start 334.410812 -285.661354)
		(end 334.410812 -285.679896)
		(width 0.0889)
		(layer "In11.Cu")
		(net "UPI_CPU1_CPU0_P2P2_DP<23>")
	)
	(segment
		(start 109.11967 -290.98367)
		(end 109.02061 -290.88461)
		(width 0.0889)
		(layer "In11.Cu")
		(net "UPI_CPU1_CPU0_P2P2_DP<23>")
	)
	(segment
		(start 110.715044 -285.668974)
		(end 110.715044 -285.661354)
		(width 0.0889)
		(layer "In11.Cu")
		(net "UPI_CPU1_CPU0_P2P2_DP<23>")
	)
	(segment
		(start 109.02061 -290.88461)
		(end 109.02061 -290.70681)
		(width 0.0889)
		(layer "In11.Cu")
		(net "UPI_CPU1_CPU0_P2P2_DP<23>")
	)
	(segment
		(start 109.532674 -289.788346)
		(end 109.673136 -289.788346)
		(width 0.0889)
		(layer "In11.Cu")
		(net "UPI_CPU1_CPU0_P2P2_DP<23>")
	)
	(segment
		(start 275.403056 -321.939666)
		(end 274.7899 -322.552822)
		(width 0.14732)
		(layer "In11.Cu")
		(net "UPI_CPU1_CPU0_P2P2_DP<23>")
	)
	(segment
		(start 107.895644 -280.778204)
		(end 107.895644 -280.76398)
		(width 0.0889)
		(layer "In11.Cu")
		(net "UPI_CPU1_CPU0_P2P2_DP<23>")
	)
	(segment
		(start 76.166218 -329.554332)
		(end 76.599288 -327.992486)
		(width 0.14732)
		(layer "In11.Cu")
		(net "UPI_CPU1_CPU0_P2P2_DP<23>")
	)
	(segment
		(start 245.309898 -353.960176)
		(end 244.880892 -353.88423)
		(width 0.14732)
		(layer "In11.Cu")
		(net "UPI_CPU1_CPU0_P2P2_DP<23>")
	)
	(segment
		(start 331.802994 -289.589718)
		(end 331.802994 -289.589972)
		(width 0.14732)
		(layer "In11.Cu")
		(net "UPI_CPU1_CPU0_P2P2_DP<23>")
	)
	(segment
		(start 306.963826 -311.068466)
		(end 302.064928 -313.09818)
		(width 0.14732)
		(layer "In11.Cu")
		(net "UPI_CPU1_CPU0_P2P2_DP<23>")
	)
	(segment
		(start 247.612154 -349.960184)
		(end 247.128284 -350.29902)
		(width 0.14732)
		(layer "In11.Cu")
		(net "UPI_CPU1_CPU0_P2P2_DP<23>")
	)
	(segment
		(start 250.138438 -350.399604)
		(end 249.540268 -350.997774)
		(width 0.14732)
		(layer "In11.Cu")
		(net "UPI_CPU1_CPU0_P2P2_DP<23>")
	)
	(segment
		(start 334.128364 -286.151066)
		(end 334.119474 -286.156146)
		(width 0.0889)
		(layer "In11.Cu")
		(net "UPI_CPU1_CPU0_P2P2_DP<23>")
	)
	(segment
		(start 109.406944 -289.914076)
		(end 109.532674 -289.788346)
		(width 0.0889)
		(layer "In11.Cu")
		(net "UPI_CPU1_CPU0_P2P2_DP<23>")
	)
	(segment
		(start 250.285758 -342.3412)
		(end 250.138438 -342.48852)
		(width 0.14732)
		(layer "In11.Cu")
		(net "UPI_CPU1_CPU0_P2P2_DP<23>")
	)
	(segment
		(start 246.779288 -352.554794)
		(end 245.918482 -351.325688)
		(width 0.14732)
		(layer "In11.Cu")
		(net "UPI_CPU1_CPU0_P2P2_DP<23>")
	)
	(segment
		(start 109.265212 -273.917918)
		(end 109.24413 -273.995896)
		(width 0.0889)
		(layer "In11.Cu")
		(net "UPI_CPU1_CPU0_P2P2_DP<23>")
	)
	(segment
		(start 296.43578 -317.420752)
		(end 295.901364 -317.955168)
		(width 0.14732)
		(layer "In11.Cu")
		(net "UPI_CPU1_CPU0_P2P2_DP<23>")
	)
	(segment
		(start 109.02061 -290.70681)
		(end 109.11967 -290.60775)
		(width 0.0889)
		(layer "In11.Cu")
		(net "UPI_CPU1_CPU0_P2P2_DP<23>")
	)
	(segment
		(start 334.128364 -283.544264)
		(end 334.133444 -283.547312)
		(width 0.0889)
		(layer "In11.Cu")
		(net "UPI_CPU1_CPU0_P2P2_DP<23>")
	)
	(segment
		(start 101.119178 -305.924966)
		(end 101.120194 -305.92395)
		(width 0.14732)
		(layer "In11.Cu")
		(net "UPI_CPU1_CPU0_P2P2_DP<23>")
	)
	(segment
		(start 262.1661 -325.220584)
		(end 261.730744 -325.220584)
		(width 0.14732)
		(layer "In11.Cu")
		(net "UPI_CPU1_CPU0_P2P2_DP<23>")
	)
	(segment
		(start 245.713758 -351.28962)
		(end 245.229888 -351.628456)
		(width 0.14732)
		(layer "In11.Cu")
		(net "UPI_CPU1_CPU0_P2P2_DP<23>")
	)
	(segment
		(start 108.178346 -281.267662)
		(end 108.177076 -281.2669)
		(width 0.0889)
		(layer "In11.Cu")
		(net "UPI_CPU1_CPU0_P2P2_DP<23>")
	)
	(segment
		(start 334.589628 -284.353)
		(end 334.597502 -284.357572)
		(width 0.0889)
		(layer "In11.Cu")
		(net "UPI_CPU1_CPU0_P2P2_DP<23>")
	)
	(segment
		(start 334.604614 -282.077922)
		(end 334.598518 -282.081478)
		(width 0.0889)
		(layer "In11.Cu")
		(net "UPI_CPU1_CPU0_P2P2_DP<23>")
	)
	(segment
		(start 314.11545 -307.884576)
		(end 313.9313 -307.9623)
		(width 0.14732)
		(layer "In11.Cu")
		(net "UPI_CPU1_CPU0_P2P2_DP<23>")
	)
	(segment
		(start 327.612248 -298.489116)
		(end 318.216788 -307.884576)
		(width 0.14732)
		(layer "In11.Cu")
		(net "UPI_CPU1_CPU0_P2P2_DP<23>")
	)
	(segment
		(start 295.901364 -317.955168)
		(end 291.127434 -317.955168)
		(width 0.14732)
		(layer "In11.Cu")
		(net "UPI_CPU1_CPU0_P2P2_DP<23>")
	)
	(segment
		(start 109.07776 -291.426138)
		(end 109.11967 -291.384228)
		(width 0.0889)
		(layer "In11.Cu")
		(net "UPI_CPU1_CPU0_P2P2_DP<23>")
	)
	(segment
		(start 109.775244 -277.522432)
		(end 109.775244 -277.512526)
		(width 0.0889)
		(layer "In11.Cu")
		(net "UPI_CPU1_CPU0_P2P2_DP<23>")
	)
	(segment
		(start 108.835444 -282.424378)
		(end 108.835444 -282.3972)
		(width 0.0889)
		(layer "In11.Cu")
		(net "UPI_CPU1_CPU0_P2P2_DP<23>")
	)
	(segment
		(start 334.119474 -283.539184)
		(end 334.128364 -283.544264)
		(width 0.0889)
		(layer "In11.Cu")
		(net "UPI_CPU1_CPU0_P2P2_DP<23>")
	)
	(segment
		(start 110.59033 -289.589972)
		(end 110.76813 -289.589972)
		(width 0.0889)
		(layer "In11.Cu")
		(net "UPI_CPU1_CPU0_P2P2_DP<23>")
	)
	(segment
		(start 110.058454 -284.523688)
		(end 110.057692 -284.52318)
		(width 0.0889)
		(layer "In11.Cu")
		(net "UPI_CPU1_CPU0_P2P2_DP<23>")
	)
	(segment
		(start 109.775244 -284.043628)
		(end 109.775244 -284.033722)
		(width 0.0889)
		(layer "In11.Cu")
		(net "UPI_CPU1_CPU0_P2P2_DP<23>")
	)
	(segment
		(start 109.587792 -277.84679)
		(end 109.596682 -277.84171)
		(width 0.0889)
		(layer "In11.Cu")
		(net "UPI_CPU1_CPU0_P2P2_DP<23>")
	)
	(segment
		(start 110.527592 -285.336996)
		(end 110.521496 -285.33344)
		(width 0.0889)
		(layer "In11.Cu")
		(net "UPI_CPU1_CPU0_P2P2_DP<23>")
	)
	(segment
		(start 111.655098 -287.304734)
		(end 111.655098 -287.28924)
		(width 0.0889)
		(layer "In11.Cu")
		(net "UPI_CPU1_CPU0_P2P2_DP<23>")
	)
	(segment
		(start 108.648246 -282.081478)
		(end 108.64215 -282.077922)
		(width 0.0889)
		(layer "In11.Cu")
		(net "UPI_CPU1_CPU0_P2P2_DP<23>")
	)
	(segment
		(start 243.331492 -352.957892)
		(end 243.295424 -353.162362)
		(width 0.14732)
		(layer "In11.Cu")
		(net "UPI_CPU1_CPU0_P2P2_DP<23>")
	)
	(segment
		(start 111.461296 -286.961072)
		(end 111.46155 -286.961326)
		(width 0.0889)
		(layer "In11.Cu")
		(net "UPI_CPU1_CPU0_P2P2_DP<23>")
	)
	(segment
		(start 111.14405 -289.589972)
		(end 111.388652 -289.589972)
		(width 0.0889)
		(layer "In11.Cu")
		(net "UPI_CPU1_CPU0_P2P2_DP<23>")
	)
	(segment
		(start 286.49803 -316.592966)
		(end 286.069024 -317.021972)
		(width 0.14732)
		(layer "In11.Cu")
		(net "UPI_CPU1_CPU0_P2P2_DP<23>")
	)
	(segment
		(start 110.066582 -276.389338)
		(end 110.057692 -276.384258)
		(width 0.0889)
		(layer "In11.Cu")
		(net "UPI_CPU1_CPU0_P2P2_DP<23>")
	)
	(segment
		(start 244.020086 -352.655124)
		(end 243.815362 -352.619056)
		(width 0.14732)
		(layer "In11.Cu")
		(net "UPI_CPU1_CPU0_P2P2_DP<23>")
	)
	(segment
		(start 250.138438 -340.76132)
		(end 250.285758 -340.90864)
		(width 0.14732)
		(layer "In11.Cu")
		(net "UPI_CPU1_CPU0_P2P2_DP<23>")
	)
	(segment
		(start 250.285758 -343.22512)
		(end 251.158248 -343.22512)
		(width 0.14732)
		(layer "In11.Cu")
		(net "UPI_CPU1_CPU0_P2P2_DP<23>")
	)
	(segment
		(start 109.07776 -292.30066)
		(end 109.07776 -291.448236)
		(width 0.14732)
		(layer "In11.Cu")
		(net "UPI_CPU1_CPU0_P2P2_DP<23>")
	)
	(segment
		(start 251.466096 -345.849448)
		(end 251.466096 -346.666312)
		(width 0.14732)
		(layer "In11.Cu")
		(net "UPI_CPU1_CPU0_P2P2_DP<23>")
	)
	(segment
		(start 110.058454 -277.032466)
		(end 110.066582 -277.027894)
		(width 0.0889)
		(layer "In11.Cu")
		(net "UPI_CPU1_CPU0_P2P2_DP<23>")
	)
	(segment
		(start 110.060232 -284.524704)
		(end 110.058454 -284.523688)
		(width 0.0889)
		(layer "In11.Cu")
		(net "UPI_CPU1_CPU0_P2P2_DP<23>")
	)
	(segment
		(start 247.092216 -350.50349)
		(end 247.953276 -351.73285)
		(width 0.14732)
		(layer "In11.Cu")
		(net "UPI_CPU1_CPU0_P2P2_DP<23>")
	)
	(segment
		(start 245.978934 -353.491038)
		(end 245.309898 -353.960176)
		(width 0.14732)
		(layer "In11.Cu")
		(net "UPI_CPU1_CPU0_P2P2_DP<23>")
	)
	(segment
		(start 290.637468 -317.465202)
		(end 290.637468 -316.474602)
		(width 0.14732)
		(layer "In11.Cu")
		(net "UPI_CPU1_CPU0_P2P2_DP<23>")
	)
	(segment
		(start 109.305344 -275.102828)
		(end 109.305344 -275.070824)
		(width 0.0889)
		(layer "In11.Cu")
		(net "UPI_CPU1_CPU0_P2P2_DP<23>")
	)
	(segment
		(start 311.775348 -307.9623)
		(end 310.332628 -308.560216)
		(width 0.14732)
		(layer "In11.Cu")
		(net "UPI_CPU1_CPU0_P2P2_DP<23>")
	)
	(segment
		(start 109.07776 -291.448236)
		(end 109.07776 -291.426138)
		(width 0.0889)
		(layer "In11.Cu")
		(net "UPI_CPU1_CPU0_P2P2_DP<23>")
	)
	(segment
		(start 108.365544 -279.964134)
		(end 108.365544 -279.954228)
		(width 0.0889)
		(layer "In11.Cu")
		(net "UPI_CPU1_CPU0_P2P2_DP<23>")
	)
	(segment
		(start 330.03617 -291.356796)
		(end 329.573636 -292.045898)
		(width 0.14732)
		(layer "In11.Cu")
		(net "UPI_CPU1_CPU0_P2P2_DP<23>")
	)
	(segment
		(start 244.880892 -353.88423)
		(end 244.020086 -352.655124)
		(width 0.14732)
		(layer "In11.Cu")
		(net "UPI_CPU1_CPU0_P2P2_DP<23>")
	)
	(segment
		(start 111.946182 -287.783778)
		(end 111.937292 -287.778698)
		(width 0.0889)
		(layer "In11.Cu")
		(net "UPI_CPU1_CPU0_P2P2_DP<23>")
	)
	(segment
		(start 110.31347 -289.490912)
		(end 110.49127 -289.490912)
		(width 0.0889)
		(layer "In11.Cu")
		(net "UPI_CPU1_CPU0_P2P2_DP<23>")
	)
	(segment
		(start 110.49127 -289.490912)
		(end 110.59033 -289.589972)
		(width 0.0889)
		(layer "In11.Cu")
		(net "UPI_CPU1_CPU0_P2P2_DP<23>")
	)
	(segment
		(start 108.573062 -297.875198)
		(end 108.881164 -297.131486)
		(width 0.14732)
		(layer "In11.Cu")
		(net "UPI_CPU1_CPU0_P2P2_DP<23>")
	)
	(segment
		(start 108.179108 -280.287984)
		(end 108.186982 -280.283412)
		(width 0.0889)
		(layer "In11.Cu")
		(net "UPI_CPU1_CPU0_P2P2_DP<23>")
	)
	(segment
		(start 251.466096 -343.532968)
		(end 251.466096 -344.349832)
		(width 0.14732)
		(layer "In11.Cu")
		(net "UPI_CPU1_CPU0_P2P2_DP<23>")
	)
	(segment
		(start 84.50707 -319.557654)
		(end 101.119178 -305.924966)
		(width 0.14732)
		(layer "In11.Cu")
		(net "UPI_CPU1_CPU0_P2P2_DP<23>")
	)
	(segment
		(start 109.406944 -290.054538)
		(end 109.406944 -289.914076)
		(width 0.0889)
		(layer "In11.Cu")
		(net "UPI_CPU1_CPU0_P2P2_DP<23>")
	)
	(segment
		(start 297.304206 -317.420752)
		(end 296.43578 -317.420752)
		(width 0.14732)
		(layer "In11.Cu")
		(net "UPI_CPU1_CPU0_P2P2_DP<23>")
	)
	(segment
		(start 75.604878 -352.367596)
		(end 75.604878 -335.260442)
		(width 0.14732)
		(layer "In11.Cu")
		(net "UPI_CPU1_CPU0_P2P2_DP<23>")
	)
	(segment
		(start 334.880712 -284.832044)
		(end 334.880712 -284.857444)
		(width 0.0889)
		(layer "In11.Cu")
		(net "UPI_CPU1_CPU0_P2P2_DP<23>")
	)
	(arc
		(start 334.598518 -284.35808)
		(mid 334.801341 -284.558311)
		(end 334.880712 -284.832044)
		(width 0.0889)
		(layer "In11.Cu")
		(net "UPI_CPU1_CPU0_P2P2_DP<23>")
	)
	(arc
		(start 333.940912 -286.48533)
		(mid 333.862801 -286.762279)
		(end 333.658464 -286.964882)
		(width 0.0889)
		(layer "In11.Cu")
		(net "UPI_CPU1_CPU0_P2P2_DP<23>")
	)
	(arc
		(start 111.46155 -286.961326)
		(mid 111.258963 -286.754975)
		(end 111.184944 -286.475424)
		(width 0.0889)
		(layer "In11.Cu")
		(net "UPI_CPU1_CPU0_P2P2_DP<23>")
	)
	(arc
		(start 111.940594 -288.463736)
		(mid 112.049741 -288.379808)
		(end 112.124744 -288.264346)
		(width 0.0889)
		(layer "In11.Cu")
		(net "UPI_CPU1_CPU0_P2P2_DP<23>")
	)
	(arc
		(start 108.365544 -281.583384)
		(mid 108.313274 -281.401019)
		(end 108.178346 -281.267662)
		(width 0.0889)
		(layer "In11.Cu")
		(net "UPI_CPU1_CPU0_P2P2_DP<23>")
	)
	(arc
		(start 111.937292 -287.778698)
		(mid 111.734469 -287.578467)
		(end 111.655098 -287.304734)
		(width 0.0889)
		(layer "In11.Cu")
		(net "UPI_CPU1_CPU0_P2P2_DP<23>")
	)
	(arc
		(start 111.670084 -288.756344)
		(mid 111.780321 -288.586923)
		(end 111.940594 -288.463736)
		(width 0.0889)
		(layer "In11.Cu")
		(net "UPI_CPU1_CPU0_P2P2_DP<23>")
	)
	(arc
		(start 108.36529 -279.978866)
		(mid 108.365487 -279.971501)
		(end 108.365544 -279.964134)
		(width 0.0889)
		(layer "In11.Cu")
		(net "UPI_CPU1_CPU0_P2P2_DP<23>")
	)
	(arc
		(start 334.411066 -282.413456)
		(mid 334.333437 -282.691869)
		(end 334.128364 -282.895548)
		(width 0.0889)
		(layer "In11.Cu")
		(net "UPI_CPU1_CPU0_P2P2_DP<23>")
	)
	(arc
		(start 109.587792 -283.709364)
		(mid 109.383457 -283.506759)
		(end 109.305344 -283.229812)
		(width 0.0889)
		(layer "In11.Cu")
		(net "UPI_CPU1_CPU0_P2P2_DP<23>")
	)
	(arc
		(start 333.941166 -283.207714)
		(mid 333.940921 -283.21711)
		(end 333.940912 -283.22651)
		(width 0.0889)
		(layer "In11.Cu")
		(net "UPI_CPU1_CPU0_P2P2_DP<23>")
	)
	(arc
		(start 334.119474 -282.900628)
		(mid 333.991581 -283.03169)
		(end 333.941166 -283.207714)
		(width 0.0889)
		(layer "In11.Cu")
		(net "UPI_CPU1_CPU0_P2P2_DP<23>")
	)
	(arc
		(start 109.117892 -282.895548)
		(mid 108.915606 -282.696567)
		(end 108.835444 -282.424378)
		(width 0.0889)
		(layer "In11.Cu")
		(net "UPI_CPU1_CPU0_P2P2_DP<23>")
	)
	(arc
		(start 109.775244 -277.512526)
		(mid 109.853355 -277.235577)
		(end 110.057692 -277.032974)
		(width 0.0889)
		(layer "In11.Cu")
		(net "UPI_CPU1_CPU0_P2P2_DP<23>")
	)
	(arc
		(start 110.997746 -286.151066)
		(mid 110.792674 -285.947387)
		(end 110.715044 -285.668974)
		(width 0.0889)
		(layer "In11.Cu")
		(net "UPI_CPU1_CPU0_P2P2_DP<23>")
	)
	(arc
		(start 335.344262 -280.864818)
		(mid 335.252101 -281.09759)
		(end 335.068418 -281.267662)
		(width 0.0889)
		(layer "In11.Cu")
		(net "UPI_CPU1_CPU0_P2P2_DP<23>")
	)
	(arc
		(start 109.587792 -273.942556)
		(mid 109.429304 -273.893623)
		(end 109.265212 -273.917918)
		(width 0.0889)
		(layer "In11.Cu")
		(net "UPI_CPU1_CPU0_P2P2_DP<23>")
	)
	(arc
		(start 334.589374 -285.342076)
		(mid 334.45846 -285.478436)
		(end 334.410812 -285.661354)
		(width 0.0889)
		(layer "In11.Cu")
		(net "UPI_CPU1_CPU0_P2P2_DP<23>")
	)
	(arc
		(start 334.880712 -284.857444)
		(mid 334.802601 -285.134393)
		(end 334.598264 -285.336996)
		(width 0.0889)
		(layer "In11.Cu")
		(net "UPI_CPU1_CPU0_P2P2_DP<23>")
	)
	(arc
		(start 111.655098 -287.28924)
		(mid 111.607419 -287.10634)
		(end 111.476536 -286.969962)
		(width 0.0889)
		(layer "In11.Cu")
		(net "UPI_CPU1_CPU0_P2P2_DP<23>")
	)
	(arc
		(start 107.895644 -280.76398)
		(mid 107.974785 -280.489357)
		(end 108.178092 -280.288492)
		(width 0.0889)
		(layer "In11.Cu")
		(net "UPI_CPU1_CPU0_P2P2_DP<23>")
	)
	(arc
		(start 109.77499 -275.8948)
		(mid 109.727311 -275.7119)
		(end 109.596428 -275.575522)
		(width 0.0889)
		(layer "In11.Cu")
		(net "UPI_CPU1_CPU0_P2P2_DP<23>")
	)
	(arc
		(start 109.305344 -275.070824)
		(mid 109.383455 -274.793875)
		(end 109.587792 -274.591272)
		(width 0.0889)
		(layer "In11.Cu")
		(net "UPI_CPU1_CPU0_P2P2_DP<23>")
	)
	(arc
		(start 110.066582 -277.027894)
		(mid 110.245179 -276.708616)
		(end 110.066582 -276.389338)
		(width 0.0889)
		(layer "In11.Cu")
		(net "UPI_CPU1_CPU0_P2P2_DP<23>")
	)
	(arc
		(start 334.880966 -281.59202)
		(mid 334.80705 -281.871522)
		(end 334.604614 -282.077922)
		(width 0.0889)
		(layer "In11.Cu")
		(net "UPI_CPU1_CPU0_P2P2_DP<23>")
	)
	(arc
		(start 110.521496 -285.33344)
		(mid 110.319083 -285.127027)
		(end 110.245144 -284.847538)
		(width 0.0889)
		(layer "In11.Cu")
		(net "UPI_CPU1_CPU0_P2P2_DP<23>")
	)
	(arc
		(start 110.0455 -276.377146)
		(mid 109.847272 -276.171298)
		(end 109.77499 -275.8948)
		(width 0.0889)
		(layer "In11.Cu")
		(net "UPI_CPU1_CPU0_P2P2_DP<23>")
	)
	(arc
		(start 108.656882 -279.469596)
		(mid 108.787796 -279.333236)
		(end 108.835444 -279.150318)
		(width 0.0889)
		(layer "In11.Cu")
		(net "UPI_CPU1_CPU0_P2P2_DP<23>")
	)
	(arc
		(start 335.059528 -281.272742)
		(mid 334.928614 -281.409102)
		(end 334.880966 -281.59202)
		(width 0.0889)
		(layer "In11.Cu")
		(net "UPI_CPU1_CPU0_P2P2_DP<23>")
	)
	(arc
		(start 109.305344 -283.219906)
		(mid 109.257665 -283.037006)
		(end 109.126782 -282.900628)
		(width 0.0889)
		(layer "In11.Cu")
		(net "UPI_CPU1_CPU0_P2P2_DP<23>")
	)
	(arc
		(start 111.184944 -286.466788)
		(mid 111.132674 -286.284423)
		(end 110.997746 -286.151066)
		(width 0.0889)
		(layer "In11.Cu")
		(net "UPI_CPU1_CPU0_P2P2_DP<23>")
	)
	(arc
		(start 334.411066 -284.033722)
		(mid 334.458745 -284.216622)
		(end 334.589628 -284.353)
		(width 0.0889)
		(layer "In11.Cu")
		(net "UPI_CPU1_CPU0_P2P2_DP<23>")
	)
	(arc
		(start 109.587538 -275.570442)
		(mid 109.386256 -275.372955)
		(end 109.305344 -275.102828)
		(width 0.0889)
		(layer "In11.Cu")
		(net "UPI_CPU1_CPU0_P2P2_DP<23>")
	)
	(arc
		(start 108.835444 -282.3972)
		(mid 108.783174 -282.214835)
		(end 108.648246 -282.081478)
		(width 0.0889)
		(layer "In11.Cu")
		(net "UPI_CPU1_CPU0_P2P2_DP<23>")
	)
	(arc
		(start 111.655098 -288.794952)
		(mid 111.66226 -288.77552)
		(end 111.670084 -288.756344)
		(width 0.0889)
		(layer "In11.Cu")
		(net "UPI_CPU1_CPU0_P2P2_DP<23>")
	)
	(arc
		(start 108.365544 -279.954228)
		(mid 108.443655 -279.677279)
		(end 108.647992 -279.474676)
		(width 0.0889)
		(layer "In11.Cu")
		(net "UPI_CPU1_CPU0_P2P2_DP<23>")
	)
	(arc
		(start 334.140556 -283.551376)
		(mid 334.338784 -283.757224)
		(end 334.411066 -284.033722)
		(width 0.0889)
		(layer "In11.Cu")
		(net "UPI_CPU1_CPU0_P2P2_DP<23>")
	)
	(arc
		(start 109.126782 -278.65578)
		(mid 109.257696 -278.51942)
		(end 109.305344 -278.336502)
		(width 0.0889)
		(layer "In11.Cu")
		(net "UPI_CPU1_CPU0_P2P2_DP<23>")
	)
	(arc
		(start 110.715044 -285.661354)
		(mid 110.667365 -285.478454)
		(end 110.536482 -285.342076)
		(width 0.0889)
		(layer "In11.Cu")
		(net "UPI_CPU1_CPU0_P2P2_DP<23>")
	)
	(arc
		(start 334.119474 -286.156146)
		(mid 333.98856 -286.292506)
		(end 333.940912 -286.475424)
		(width 0.0889)
		(layer "In11.Cu")
		(net "UPI_CPU1_CPU0_P2P2_DP<23>")
	)
	(arc
		(start 108.186982 -280.283412)
		(mid 108.314236 -280.153446)
		(end 108.36529 -279.978866)
		(width 0.0889)
		(layer "In11.Cu")
		(net "UPI_CPU1_CPU0_P2P2_DP<23>")
	)
	(arc
		(start 109.596682 -274.586192)
		(mid 109.775279 -274.266914)
		(end 109.596682 -273.947636)
		(width 0.0889)
		(layer "In11.Cu")
		(net "UPI_CPU1_CPU0_P2P2_DP<23>")
	)
	(arc
		(start 335.347056 -280.843736)
		(mid 335.345758 -280.85429)
		(end 335.344262 -280.864818)
		(width 0.0889)
		(layer "In11.Cu")
		(net "UPI_CPU1_CPU0_P2P2_DP<23>")
	)
	(arc
		(start 108.835444 -279.140412)
		(mid 108.913555 -278.863463)
		(end 109.117892 -278.66086)
		(width 0.0889)
		(layer "In11.Cu")
		(net "UPI_CPU1_CPU0_P2P2_DP<23>")
	)
	(arc
		(start 108.166154 -281.26055)
		(mid 107.967926 -281.054702)
		(end 107.895644 -280.778204)
		(width 0.0889)
		(layer "In11.Cu")
		(net "UPI_CPU1_CPU0_P2P2_DP<23>")
	)
	(arc
		(start 108.64215 -282.077922)
		(mid 108.439563 -281.871571)
		(end 108.365544 -281.59202)
		(width 0.0889)
		(layer "In11.Cu")
		(net "UPI_CPU1_CPU0_P2P2_DP<23>")
	)
	(arc
		(start 109.305344 -278.31796)
		(mid 109.385506 -278.045771)
		(end 109.587792 -277.84679)
		(width 0.0889)
		(layer "In11.Cu")
		(net "UPI_CPU1_CPU0_P2P2_DP<23>")
	)
	(arc
		(start 109.596682 -277.84171)
		(mid 109.727596 -277.70535)
		(end 109.775244 -277.522432)
		(width 0.0889)
		(layer "In11.Cu")
		(net "UPI_CPU1_CPU0_P2P2_DP<23>")
	)
	(arc
		(start 333.649574 -286.969962)
		(mid 333.537862 -287.064484)
		(end 333.469742 -287.19399)
		(width 0.0889)
		(layer "In11.Cu")
		(net "UPI_CPU1_CPU0_P2P2_DP<23>")
	)
	(arc
		(start 110.057692 -284.52318)
		(mid 109.853357 -284.320575)
		(end 109.775244 -284.043628)
		(width 0.0889)
		(layer "In11.Cu")
		(net "UPI_CPU1_CPU0_P2P2_DP<23>")
	)
	(arc
		(start 110.245144 -284.847538)
		(mid 110.197465 -284.664638)
		(end 110.066582 -284.52826)
		(width 0.0889)
		(layer "In11.Cu")
		(net "UPI_CPU1_CPU0_P2P2_DP<23>")
	)
	(arc
		(start 334.410812 -285.679896)
		(mid 334.33065 -285.952085)
		(end 334.128364 -286.151066)
		(width 0.0889)
		(layer "In11.Cu")
		(net "UPI_CPU1_CPU0_P2P2_DP<23>")
	)
	(arc
		(start 112.124744 -288.103056)
		(mid 112.077065 -287.920156)
		(end 111.946182 -287.783778)
		(width 0.0889)
		(layer "In11.Cu")
		(net "UPI_CPU1_CPU0_P2P2_DP<23>")
	)
	(arc
		(start 109.775244 -284.033722)
		(mid 109.727565 -283.850822)
		(end 109.596682 -283.714444)
		(width 0.0889)
		(layer "In11.Cu")
		(net "UPI_CPU1_CPU0_P2P2_DP<23>")
	)
	(arc
		(start 333.940912 -283.22651)
		(mid 333.990165 -283.40571)
		(end 334.119474 -283.539184)
		(width 0.0889)
		(layer "In11.Cu")
		(net "UPI_CPU1_CPU0_P2P2_DP<23>")
	)
	(arc
		(start 334.589628 -282.086558)
		(mid 334.458714 -282.222918)
		(end 334.411066 -282.405836)
		(width 0.0889)
		(layer "In11.Cu")
		(net "UPI_CPU1_CPU0_P2P2_DP<23>")
	)
	(segment
		(start 105.641648 -280.242264)
		(end 105.641648 -280.77795)
		(width 0.13208)
		(layer "F.Cu")
		(net "UPI_CPU1_CPU0_P2P2_DP<22>")
	)
	(segment
		(start 335.255362 -281.591766)
		(end 335.255616 -281.59202)
		(width 0.13208)
		(layer "F.Cu")
		(net "UPI_CPU1_CPU0_P2P2_DP<22>")
	)
	(segment
		(start 335.255362 -281.05608)
		(end 335.255362 -281.591766)
		(width 0.13208)
		(layer "F.Cu")
		(net "UPI_CPU1_CPU0_P2P2_DP<22>")
	)
	(segment
		(start 105.641648 -280.77795)
		(end 105.641394 -280.778204)
		(width 0.13208)
		(layer "F.Cu")
		(net "UPI_CPU1_CPU0_P2P2_DP<22>")
	)
	(segment
		(start 254.575818 -336.660744)
		(end 253.967996 -336.052922)
		(width 0.14732)
		(layer "In11.Cu")
		(net "UPI_CPU1_CPU0_P2P2_DP<22>")
	)
	(segment
		(start 252.320806 -344.45448)
		(end 252.320806 -345.04376)
		(width 0.14732)
		(layer "In11.Cu")
		(net "UPI_CPU1_CPU0_P2P2_DP<22>")
	)
	(segment
		(start 256.789682 -338.439252)
		(end 256.354326 -338.439252)
		(width 0.14732)
		(layer "In11.Cu")
		(net "UPI_CPU1_CPU0_P2P2_DP<22>")
	)
	(segment
		(start 301.834804 -315.414152)
		(end 301.199042 -316.676024)
		(width 0.14732)
		(layer "In11.Cu")
		(net "UPI_CPU1_CPU0_P2P2_DP<22>")
	)
	(segment
		(start 287.005268 -318.888364)
		(end 283.920692 -318.888364)
		(width 0.14732)
		(layer "In11.Cu")
		(net "UPI_CPU1_CPU0_P2P2_DP<22>")
	)
	(segment
		(start 257.36804 -337.860894)
		(end 256.789682 -338.439252)
		(width 0.14732)
		(layer "In11.Cu")
		(net "UPI_CPU1_CPU0_P2P2_DP<22>")
	)
	(segment
		(start 259.1943 -330.618338)
		(end 254.98171 -334.830928)
		(width 0.14732)
		(layer "In11.Cu")
		(net "UPI_CPU1_CPU0_P2P2_DP<22>")
	)
	(segment
		(start 252.468126 -344.30716)
		(end 252.320806 -344.45448)
		(width 0.14732)
		(layer "In11.Cu")
		(net "UPI_CPU1_CPU0_P2P2_DP<22>")
	)
	(segment
		(start 335.059274 -283.539184)
		(end 335.074514 -283.548074)
		(width 0.0889)
		(layer "In11.Cu")
		(net "UPI_CPU1_CPU0_P2P2_DP<22>")
	)
	(segment
		(start 252.468126 -341.99068)
		(end 252.320806 -342.138)
		(width 0.14732)
		(layer "In11.Cu")
		(net "UPI_CPU1_CPU0_P2P2_DP<22>")
	)
	(segment
		(start 79.837026 -362.18876)
		(end 78.00594 -360.357674)
		(width 0.14732)
		(layer "In11.Cu")
		(net "UPI_CPU1_CPU0_P2P2_DP<22>")
	)
	(segment
		(start 254.19304 -339.27923)
		(end 253.758192 -339.279484)
		(width 0.14732)
		(layer "In11.Cu")
		(net "UPI_CPU1_CPU0_P2P2_DP<22>")
	)
	(segment
		(start 301.199042 -316.676024)
		(end 301.06747 -317.443358)
		(width 0.14732)
		(layer "In11.Cu")
		(net "UPI_CPU1_CPU0_P2P2_DP<22>")
	)
	(segment
		(start 108.365544 -290.311078)
		(end 108.365544 -289.646868)
		(width 0.0889)
		(layer "In11.Cu")
		(net "UPI_CPU1_CPU0_P2P2_DP<22>")
	)
	(segment
		(start 106.297984 -281.267154)
		(end 106.29265 -281.264106)
		(width 0.0889)
		(layer "In11.Cu")
		(net "UPI_CPU1_CPU0_P2P2_DP<22>")
	)
	(segment
		(start 252.320806 -340.4108)
		(end 252.468126 -340.55812)
		(width 0.14732)
		(layer "In11.Cu")
		(net "UPI_CPU1_CPU0_P2P2_DP<22>")
	)
	(segment
		(start 333.190088 -289.378898)
		(end 330.792074 -291.776912)
		(width 0.14732)
		(layer "In11.Cu")
		(net "UPI_CPU1_CPU0_P2P2_DP<22>")
	)
	(segment
		(start 289.78479 -318.065404)
		(end 289.78479 -317.65621)
		(width 0.14732)
		(layer "In11.Cu")
		(net "UPI_CPU1_CPU0_P2P2_DP<22>")
	)
	(segment
		(start 330.792074 -291.776912)
		(end 330.323952 -292.47719)
		(width 0.14732)
		(layer "In11.Cu")
		(net "UPI_CPU1_CPU0_P2P2_DP<22>")
	)
	(segment
		(start 254.688594 -346.315792)
		(end 254.380746 -346.62364)
		(width 0.14732)
		(layer "In11.Cu")
		(net "UPI_CPU1_CPU0_P2P2_DP<22>")
	)
	(segment
		(start 100.461826 -305.389788)
		(end 107.21467 -298.297092)
		(width 0.14732)
		(layer "In11.Cu")
		(net "UPI_CPU1_CPU0_P2P2_DP<22>")
	)
	(segment
		(start 255.589532 -337.882738)
		(end 254.19304 -339.27923)
		(width 0.14732)
		(layer "In11.Cu")
		(net "UPI_CPU1_CPU0_P2P2_DP<22>")
	)
	(segment
		(start 296.28465 -322.534788)
		(end 293.994078 -320.244216)
		(width 0.14732)
		(layer "In11.Cu")
		(net "UPI_CPU1_CPU0_P2P2_DP<22>")
	)
	(segment
		(start 261.716266 -330.904596)
		(end 261.716266 -331.339952)
		(width 0.14732)
		(layer "In11.Cu")
		(net "UPI_CPU1_CPU0_P2P2_DP<22>")
	)
	(segment
		(start 251.25299 -350.822514)
		(end 228.509322 -366.747806)
		(width 0.14732)
		(layer "In11.Cu")
		(net "UPI_CPU1_CPU0_P2P2_DP<22>")
	)
	(segment
		(start 335.350866 -284.033722)
		(end 335.350866 -284.042358)
		(width 0.0889)
		(layer "In11.Cu")
		(net "UPI_CPU1_CPU0_P2P2_DP<22>")
	)
	(segment
		(start 301.06747 -317.443358)
		(end 300.663356 -318.418972)
		(width 0.14732)
		(layer "In11.Cu")
		(net "UPI_CPU1_CPU0_P2P2_DP<22>")
	)
	(segment
		(start 107.717082 -285.342076)
		(end 107.702096 -285.33344)
		(width 0.0889)
		(layer "In11.Cu")
		(net "UPI_CPU1_CPU0_P2P2_DP<22>")
	)
	(segment
		(start 252.468126 -345.19108)
		(end 254.380746 -345.19108)
		(width 0.14732)
		(layer "In11.Cu")
		(net "UPI_CPU1_CPU0_P2P2_DP<22>")
	)
	(segment
		(start 256.354326 -338.439252)
		(end 255.797812 -337.882738)
		(width 0.14732)
		(layer "In11.Cu")
		(net "UPI_CPU1_CPU0_P2P2_DP<22>")
	)
	(segment
		(start 302.311308 -314.915804)
		(end 301.834804 -315.414152)
		(width 0.14732)
		(layer "In11.Cu")
		(net "UPI_CPU1_CPU0_P2P2_DP<22>")
	)
	(segment
		(start 105.954068 -280.778204)
		(end 105.641394 -280.778204)
		(width 0.0889)
		(layer "In11.Cu")
		(net "UPI_CPU1_CPU0_P2P2_DP<22>")
	)
	(segment
		(start 108.365544 -286.475424)
		(end 108.365544 -286.466788)
		(width 0.0889)
		(layer "In11.Cu")
		(net "UPI_CPU1_CPU0_P2P2_DP<22>")
	)
	(segment
		(start 333.205582 -289.30346)
		(end 333.205582 -289.363404)
		(width 0.0889)
		(layer "In11.Cu")
		(net "UPI_CPU1_CPU0_P2P2_DP<22>")
	)
	(segment
		(start 261.137908 -331.91831)
		(end 260.702552 -331.91831)
		(width 0.14732)
		(layer "In11.Cu")
		(net "UPI_CPU1_CPU0_P2P2_DP<22>")
	)
	(segment
		(start 107.895644 -285.668974)
		(end 107.895644 -285.661354)
		(width 0.0889)
		(layer "In11.Cu")
		(net "UPI_CPU1_CPU0_P2P2_DP<22>")
	)
	(segment
		(start 107.425998 -281.601926)
		(end 107.425998 -281.59202)
		(width 0.0889)
		(layer "In11.Cu")
		(net "UPI_CPU1_CPU0_P2P2_DP<22>")
	)
	(segment
		(start 107.24007 -281.268424)
		(end 107.238546 -281.267662)
		(width 0.0889)
		(layer "In11.Cu")
		(net "UPI_CPU1_CPU0_P2P2_DP<22>")
	)
	(segment
		(start 107.717336 -282.086558)
		(end 107.708446 -282.081478)
		(width 0.0889)
		(layer "In11.Cu")
		(net "UPI_CPU1_CPU0_P2P2_DP<22>")
	)
	(segment
		(start 300.663356 -318.418972)
		(end 299.293788 -319.78854)
		(width 0.14732)
		(layer "In11.Cu")
		(net "UPI_CPU1_CPU0_P2P2_DP<22>")
	)
	(segment
		(start 311.70118 -309.755286)
		(end 309.986172 -310.59247)
		(width 0.14732)
		(layer "In11.Cu")
		(net "UPI_CPU1_CPU0_P2P2_DP<22>")
	)
	(segment
		(start 106.298746 -281.267662)
		(end 106.297984 -281.267154)
		(width 0.0889)
		(layer "In11.Cu")
		(net "UPI_CPU1_CPU0_P2P2_DP<22>")
	)
	(segment
		(start 255.797812 -337.882738)
		(end 255.589532 -337.882738)
		(width 0.14732)
		(layer "In11.Cu")
		(net "UPI_CPU1_CPU0_P2P2_DP<22>")
	)
	(segment
		(start 107.890564 -291.380164)
		(end 108.323634 -290.947094)
		(width 0.14732)
		(layer "In11.Cu")
		(net "UPI_CPU1_CPU0_P2P2_DP<22>")
	)
	(segment
		(start 78.00594 -360.357674)
		(end 74.774298 -352.553524)
		(width 0.14732)
		(layer "In11.Cu")
		(net "UPI_CPU1_CPU0_P2P2_DP<22>")
	)
	(segment
		(start 108.323634 -290.375086)
		(end 108.323634 -290.352988)
		(width 0.0889)
		(layer "In11.Cu")
		(net "UPI_CPU1_CPU0_P2P2_DP<22>")
	)
	(segment
		(start 75.810618 -327.72223)
		(end 76.39812 -326.480678)
		(width 0.14732)
		(layer "In11.Cu")
		(net "UPI_CPU1_CPU0_P2P2_DP<22>")
	)
	(segment
		(start 76.39812 -326.480678)
		(end 83.882992 -318.995298)
		(width 0.14732)
		(layer "In11.Cu")
		(net "UPI_CPU1_CPU0_P2P2_DP<22>")
	)
	(segment
		(start 334.654652 -287.85439)
		(end 333.205582 -289.30346)
		(width 0.0889)
		(layer "In11.Cu")
		(net "UPI_CPU1_CPU0_P2P2_DP<22>")
	)
	(segment
		(start 309.0164 -311.493916)
		(end 307.694076 -312.11774)
		(width 0.14732)
		(layer "In11.Cu")
		(net "UPI_CPU1_CPU0_P2P2_DP<22>")
	)
	(segment
		(start 283.351986 -321.49923)
		(end 282.009088 -322.842128)
		(width 0.14732)
		(layer "In11.Cu")
		(net "UPI_CPU1_CPU0_P2P2_DP<22>")
	)
	(segment
		(start 335.538064 -285.336996)
		(end 335.529174 -285.342076)
		(width 0.0889)
		(layer "In11.Cu")
		(net "UPI_CPU1_CPU0_P2P2_DP<22>")
	)
	(segment
		(start 107.247436 -281.272742)
		(end 107.24007 -281.268424)
		(width 0.0889)
		(layer "In11.Cu")
		(net "UPI_CPU1_CPU0_P2P2_DP<22>")
	)
	(segment
		(start 260.416294 -329.396344)
		(end 260.416294 -329.604624)
		(width 0.14732)
		(layer "In11.Cu")
		(net "UPI_CPU1_CPU0_P2P2_DP<22>")
	)
	(segment
		(start 335.350612 -287.279334)
		(end 335.350612 -287.299146)
		(width 0.0889)
		(layer "In11.Cu")
		(net "UPI_CPU1_CPU0_P2P2_DP<22>")
	)
	(segment
		(start 317.776352 -309.500016)
		(end 314.277756 -309.500016)
		(width 0.14732)
		(layer "In11.Cu")
		(net "UPI_CPU1_CPU0_P2P2_DP<22>")
	)
	(segment
		(start 106.313478 -281.276298)
		(end 106.298746 -281.267662)
		(width 0.0889)
		(layer "In11.Cu")
		(net "UPI_CPU1_CPU0_P2P2_DP<22>")
	)
	(segment
		(start 254.575818 -336.869024)
		(end 254.575818 -336.660744)
		(width 0.14732)
		(layer "In11.Cu")
		(net "UPI_CPU1_CPU0_P2P2_DP<22>")
	)
	(segment
		(start 260.702552 -331.91831)
		(end 259.40258 -330.618338)
		(width 0.14732)
		(layer "In11.Cu")
		(net "UPI_CPU1_CPU0_P2P2_DP<22>")
	)
	(segment
		(start 252.468126 -342.8746)
		(end 254.380746 -342.8746)
		(width 0.14732)
		(layer "In11.Cu")
		(net "UPI_CPU1_CPU0_P2P2_DP<22>")
	)
	(segment
		(start 289.3949 -317.26632)
		(end 288.627312 -317.26632)
		(width 0.14732)
		(layer "In11.Cu")
		(net "UPI_CPU1_CPU0_P2P2_DP<22>")
	)
	(segment
		(start 108.82884 -289.090608)
		(end 108.84027 -288.873946)
		(width 0.0889)
		(layer "In11.Cu")
		(net "UPI_CPU1_CPU0_P2P2_DP<22>")
	)
	(segment
		(start 108.64215 -287.617154)
		(end 108.648246 -287.613598)
		(width 0.0889)
		(layer "In11.Cu")
		(net "UPI_CPU1_CPU0_P2P2_DP<22>")
	)
	(segment
		(start 293.994078 -320.244216)
		(end 293.994078 -319.25895)
		(width 0.14732)
		(layer "In11.Cu")
		(net "UPI_CPU1_CPU0_P2P2_DP<22>")
	)
	(segment
		(start 212.290914 -369.607592)
		(end 199.94626 -367.430812)
		(width 0.14732)
		(layer "In11.Cu")
		(net "UPI_CPU1_CPU0_P2P2_DP<22>")
	)
	(segment
		(start 335.068164 -286.151066)
		(end 335.059274 -286.156146)
		(width 0.0889)
		(layer "In11.Cu")
		(net "UPI_CPU1_CPU0_P2P2_DP<22>")
	)
	(segment
		(start 283.920692 -318.888364)
		(end 283.351986 -319.45707)
		(width 0.14732)
		(layer "In11.Cu")
		(net "UPI_CPU1_CPU0_P2P2_DP<22>")
	)
	(segment
		(start 254.688594 -343.182448)
		(end 254.688594 -343.999312)
		(width 0.14732)
		(layer "In11.Cu")
		(net "UPI_CPU1_CPU0_P2P2_DP<22>")
	)
	(segment
		(start 333.205582 -289.363404)
		(end 333.190088 -289.378898)
		(width 0.0889)
		(layer "In11.Cu")
		(net "UPI_CPU1_CPU0_P2P2_DP<22>")
	)
	(segment
		(start 254.688594 -345.498928)
		(end 254.688594 -346.315792)
		(width 0.14732)
		(layer "In11.Cu")
		(net "UPI_CPU1_CPU0_P2P2_DP<22>")
	)
	(segment
		(start 261.50443 -328.308208)
		(end 260.416294 -329.396344)
		(width 0.14732)
		(layer "In11.Cu")
		(net "UPI_CPU1_CPU0_P2P2_DP<22>")
	)
	(segment
		(start 254.380746 -342.8746)
		(end 254.688594 -343.182448)
		(width 0.14732)
		(layer "In11.Cu")
		(net "UPI_CPU1_CPU0_P2P2_DP<22>")
	)
	(segment
		(start 328.374756 -298.901866)
		(end 317.776352 -309.500016)
		(width 0.14732)
		(layer "In11.Cu")
		(net "UPI_CPU1_CPU0_P2P2_DP<22>")
	)
	(segment
		(start 254.98171 -334.830928)
		(end 254.98171 -335.039208)
		(width 0.14732)
		(layer "In11.Cu")
		(net "UPI_CPU1_CPU0_P2P2_DP<22>")
	)
	(segment
		(start 108.166154 -283.551376)
		(end 108.178346 -283.544264)
		(width 0.0889)
		(layer "In11.Cu")
		(net "UPI_CPU1_CPU0_P2P2_DP<22>")
	)
	(segment
		(start 260.416294 -329.604624)
		(end 261.716266 -330.904596)
		(width 0.14732)
		(layer "In11.Cu")
		(net "UPI_CPU1_CPU0_P2P2_DP<22>")
	)
	(segment
		(start 264.829544 -324.205346)
		(end 261.50443 -327.53046)
		(width 0.14732)
		(layer "In11.Cu")
		(net "UPI_CPU1_CPU0_P2P2_DP<22>")
	)
	(segment
		(start 261.50443 -327.53046)
		(end 261.50443 -328.308208)
		(width 0.14732)
		(layer "In11.Cu")
		(net "UPI_CPU1_CPU0_P2P2_DP<22>")
	)
	(segment
		(start 108.365544 -288.216086)
		(end 108.365544 -288.103056)
		(width 0.0889)
		(layer "In11.Cu")
		(net "UPI_CPU1_CPU0_P2P2_DP<22>")
	)
	(segment
		(start 252.468126 -346.62364)
		(end 252.320806 -346.77096)
		(width 0.14732)
		(layer "In11.Cu")
		(net "UPI_CPU1_CPU0_P2P2_DP<22>")
	)
	(segment
		(start 107.895898 -282.424378)
		(end 107.895898 -282.405836)
		(width 0.0889)
		(layer "In11.Cu")
		(net "UPI_CPU1_CPU0_P2P2_DP<22>")
	)
	(segment
		(start 107.21467 -298.297092)
		(end 107.788202 -297.523916)
		(width 0.14732)
		(layer "In11.Cu")
		(net "UPI_CPU1_CPU0_P2P2_DP<22>")
	)
	(segment
		(start 289.78479 -317.65621)
		(end 289.3949 -317.26632)
		(width 0.14732)
		(layer "In11.Cu")
		(net "UPI_CPU1_CPU0_P2P2_DP<22>")
	)
	(segment
		(start 330.323952 -292.47719)
		(end 328.374756 -298.901866)
		(width 0.14732)
		(layer "In11.Cu")
		(net "UPI_CPU1_CPU0_P2P2_DP<22>")
	)
	(segment
		(start 252.320806 -346.77096)
		(end 252.320806 -349.754698)
		(width 0.14732)
		(layer "In11.Cu")
		(net "UPI_CPU1_CPU0_P2P2_DP<22>")
	)
	(segment
		(start 160.780984 -374.336564)
		(end 126.407672 -374.336564)
		(width 0.14732)
		(layer "In11.Cu")
		(net "UPI_CPU1_CPU0_P2P2_DP<22>")
	)
	(segment
		(start 259.40258 -330.618338)
		(end 259.1943 -330.618338)
		(width 0.14732)
		(layer "In11.Cu")
		(net "UPI_CPU1_CPU0_P2P2_DP<22>")
	)
	(segment
		(start 335.059274 -286.794702)
		(end 335.068164 -286.799782)
		(width 0.0889)
		(layer "In11.Cu")
		(net "UPI_CPU1_CPU0_P2P2_DP<22>")
	)
	(segment
		(start 106.019854 -280.84399)
		(end 105.954068 -280.778204)
		(width 0.0889)
		(layer "In11.Cu")
		(net "UPI_CPU1_CPU0_P2P2_DP<22>")
	)
	(segment
		(start 75.348338 -329.39482)
		(end 75.810618 -327.72223)
		(width 0.14732)
		(layer "In11.Cu")
		(net "UPI_CPU1_CPU0_P2P2_DP<22>")
	)
	(segment
		(start 335.099152 -281.863038)
		(end 335.123282 -281.952192)
		(width 0.0889)
		(layer "In11.Cu")
		(net "UPI_CPU1_CPU0_P2P2_DP<22>")
	)
	(segment
		(start 288.627312 -317.26632)
		(end 287.005268 -318.888364)
		(width 0.14732)
		(layer "In11.Cu")
		(net "UPI_CPU1_CPU0_P2P2_DP<22>")
	)
	(segment
		(start 253.967996 -336.052922)
		(end 253.759716 -336.052922)
		(width 0.14732)
		(layer "In11.Cu")
		(net "UPI_CPU1_CPU0_P2P2_DP<22>")
	)
	(segment
		(start 108.323634 -290.947094)
		(end 108.323634 -290.375086)
		(width 0.14732)
		(layer "In11.Cu")
		(net "UPI_CPU1_CPU0_P2P2_DP<22>")
	)
	(segment
		(start 252.320806 -342.72728)
		(end 252.468126 -342.8746)
		(width 0.14732)
		(layer "In11.Cu")
		(net "UPI_CPU1_CPU0_P2P2_DP<22>")
	)
	(segment
		(start 282.009088 -322.842128)
		(end 277.333964 -322.842128)
		(width 0.14732)
		(layer "In11.Cu")
		(net "UPI_CPU1_CPU0_P2P2_DP<22>")
	)
	(segment
		(start 335.350612 -285.661354)
		(end 335.350612 -285.679896)
		(width 0.0889)
		(layer "In11.Cu")
		(net "UPI_CPU1_CPU0_P2P2_DP<22>")
	)
	(segment
		(start 306.579016 -312.409078)
		(end 302.311308 -314.915804)
		(width 0.14732)
		(layer "In11.Cu")
		(net "UPI_CPU1_CPU0_P2P2_DP<22>")
	)
	(segment
		(start 254.380746 -341.99068)
		(end 252.468126 -341.99068)
		(width 0.14732)
		(layer "In11.Cu")
		(net "UPI_CPU1_CPU0_P2P2_DP<22>")
	)
	(segment
		(start 283.351986 -319.45707)
		(end 283.351986 -321.49923)
		(width 0.14732)
		(layer "In11.Cu")
		(net "UPI_CPU1_CPU0_P2P2_DP<22>")
	)
	(segment
		(start 74.774298 -352.553524)
		(end 74.774298 -335.226914)
		(width 0.14732)
		(layer "In11.Cu")
		(net "UPI_CPU1_CPU0_P2P2_DP<22>")
	)
	(segment
		(start 74.774298 -335.226914)
		(end 75.348338 -329.39482)
		(width 0.14732)
		(layer "In11.Cu")
		(net "UPI_CPU1_CPU0_P2P2_DP<22>")
	)
	(segment
		(start 314.277756 -309.500016)
		(end 314.277502 -309.50027)
		(width 0.14732)
		(layer "In11.Cu")
		(net "UPI_CPU1_CPU0_P2P2_DP<22>")
	)
	(segment
		(start 252.468126 -340.55812)
		(end 254.380746 -340.55812)
		(width 0.14732)
		(layer "In11.Cu")
		(net "UPI_CPU1_CPU0_P2P2_DP<22>")
	)
	(segment
		(start 108.323634 -290.352988)
		(end 108.365544 -290.311078)
		(width 0.0889)
		(layer "In11.Cu")
		(net "UPI_CPU1_CPU0_P2P2_DP<22>")
	)
	(segment
		(start 299.293788 -320.991738)
		(end 297.750738 -322.534788)
		(width 0.14732)
		(layer "In11.Cu")
		(net "UPI_CPU1_CPU0_P2P2_DP<22>")
	)
	(segment
		(start 277.333964 -322.842128)
		(end 275.970746 -324.205346)
		(width 0.14732)
		(layer "In11.Cu")
		(net "UPI_CPU1_CPU0_P2P2_DP<22>")
	)
	(segment
		(start 335.820512 -284.837632)
		(end 335.820512 -284.857444)
		(width 0.0889)
		(layer "In11.Cu")
		(net "UPI_CPU1_CPU0_P2P2_DP<22>")
	)
	(segment
		(start 335.255616 -281.59202)
		(end 335.099152 -281.863038)
		(width 0.0889)
		(layer "In11.Cu")
		(net "UPI_CPU1_CPU0_P2P2_DP<22>")
	)
	(segment
		(start 306.971192 -312.214006)
		(end 306.579016 -312.409078)
		(width 0.14732)
		(layer "In11.Cu")
		(net "UPI_CPU1_CPU0_P2P2_DP<22>")
	)
	(segment
		(start 254.380746 -346.62364)
		(end 252.468126 -346.62364)
		(width 0.14732)
		(layer "In11.Cu")
		(net "UPI_CPU1_CPU0_P2P2_DP<22>")
	)
	(segment
		(start 126.407672 -374.336564)
		(end 99.544378 -370.351558)
		(width 0.14732)
		(layer "In11.Cu")
		(net "UPI_CPU1_CPU0_P2P2_DP<22>")
	)
	(segment
		(start 107.788202 -297.523916)
		(end 107.890564 -297.277282)
		(width 0.14732)
		(layer "In11.Cu")
		(net "UPI_CPU1_CPU0_P2P2_DP<22>")
	)
	(segment
		(start 253.17958 -338.700872)
		(end 253.179326 -338.265516)
		(width 0.14732)
		(layer "In11.Cu")
		(net "UPI_CPU1_CPU0_P2P2_DP<22>")
	)
	(segment
		(start 199.94626 -367.430812)
		(end 160.780984 -374.336564)
		(width 0.14732)
		(layer "In11.Cu")
		(net "UPI_CPU1_CPU0_P2P2_DP<22>")
	)
	(segment
		(start 228.509322 -366.747806)
		(end 212.290914 -369.607592)
		(width 0.14732)
		(layer "In11.Cu")
		(net "UPI_CPU1_CPU0_P2P2_DP<22>")
	)
	(segment
		(start 290.502594 -318.783208)
		(end 289.78479 -318.065404)
		(width 0.14732)
		(layer "In11.Cu")
		(net "UPI_CPU1_CPU0_P2P2_DP<22>")
	)
	(segment
		(start 335.350866 -282.39593)
		(end 335.350866 -282.42006)
		(width 0.0889)
		(layer "In11.Cu")
		(net "UPI_CPU1_CPU0_P2P2_DP<22>")
	)
	(segment
		(start 254.688594 -341.682832)
		(end 254.380746 -341.99068)
		(width 0.14732)
		(layer "In11.Cu")
		(net "UPI_CPU1_CPU0_P2P2_DP<22>")
	)
	(segment
		(start 253.759716 -336.052922)
		(end 252.320806 -337.491832)
		(width 0.14732)
		(layer "In11.Cu")
		(net "UPI_CPU1_CPU0_P2P2_DP<22>")
	)
	(segment
		(start 252.320806 -345.04376)
		(end 252.468126 -345.19108)
		(width 0.14732)
		(layer "In11.Cu")
		(net "UPI_CPU1_CPU0_P2P2_DP<22>")
	)
	(segment
		(start 297.750738 -322.534788)
		(end 296.28465 -322.534788)
		(width 0.14732)
		(layer "In11.Cu")
		(net "UPI_CPU1_CPU0_P2P2_DP<22>")
	)
	(segment
		(start 83.882992 -318.995298)
		(end 100.461826 -305.389788)
		(width 0.14732)
		(layer "In11.Cu")
		(net "UPI_CPU1_CPU0_P2P2_DP<22>")
	)
	(segment
		(start 254.380746 -340.55812)
		(end 254.688594 -340.865968)
		(width 0.14732)
		(layer "In11.Cu")
		(net "UPI_CPU1_CPU0_P2P2_DP<22>")
	)
	(segment
		(start 254.688594 -340.865968)
		(end 254.688594 -341.682832)
		(width 0.14732)
		(layer "In11.Cu")
		(net "UPI_CPU1_CPU0_P2P2_DP<22>")
	)
	(segment
		(start 99.544378 -370.351558)
		(end 79.837026 -362.18876)
		(width 0.14732)
		(layer "In11.Cu")
		(net "UPI_CPU1_CPU0_P2P2_DP<22>")
	)
	(segment
		(start 254.98171 -335.039208)
		(end 257.36804 -337.425538)
		(width 0.14732)
		(layer "In11.Cu")
		(net "UPI_CPU1_CPU0_P2P2_DP<22>")
	)
	(segment
		(start 307.694076 -312.11774)
		(end 306.971192 -312.214006)
		(width 0.14732)
		(layer "In11.Cu")
		(net "UPI_CPU1_CPU0_P2P2_DP<22>")
	)
	(segment
		(start 252.320806 -337.491832)
		(end 252.320806 -340.4108)
		(width 0.14732)
		(layer "In11.Cu")
		(net "UPI_CPU1_CPU0_P2P2_DP<22>")
	)
	(segment
		(start 299.293788 -319.78854)
		(end 299.293788 -320.991738)
		(width 0.14732)
		(layer "In11.Cu")
		(net "UPI_CPU1_CPU0_P2P2_DP<22>")
	)
	(segment
		(start 254.380746 -345.19108)
		(end 254.688594 -345.498928)
		(width 0.14732)
		(layer "In11.Cu")
		(net "UPI_CPU1_CPU0_P2P2_DP<22>")
	)
	(segment
		(start 253.758192 -339.279484)
		(end 253.17958 -338.700872)
		(width 0.14732)
		(layer "In11.Cu")
		(net "UPI_CPU1_CPU0_P2P2_DP<22>")
	)
	(segment
		(start 252.320806 -349.754698)
		(end 251.25299 -350.822514)
		(width 0.14732)
		(layer "In11.Cu")
		(net "UPI_CPU1_CPU0_P2P2_DP<22>")
	)
	(segment
		(start 108.648246 -286.964882)
		(end 108.64215 -286.961326)
		(width 0.0889)
		(layer "In11.Cu")
		(net "UPI_CPU1_CPU0_P2P2_DP<22>")
	)
	(segment
		(start 334.785462 -287.85439)
		(end 334.654652 -287.85439)
		(width 0.0889)
		(layer "In11.Cu")
		(net "UPI_CPU1_CPU0_P2P2_DP<22>")
	)
	(segment
		(start 275.970746 -324.205346)
		(end 264.829544 -324.205346)
		(width 0.14732)
		(layer "In11.Cu")
		(net "UPI_CPU1_CPU0_P2P2_DP<22>")
	)
	(segment
		(start 314.277502 -309.50027)
		(end 311.70118 -309.755286)
		(width 0.14732)
		(layer "In11.Cu")
		(net "UPI_CPU1_CPU0_P2P2_DP<22>")
	)
	(segment
		(start 261.716266 -331.339952)
		(end 261.137908 -331.91831)
		(width 0.14732)
		(layer "In11.Cu")
		(net "UPI_CPU1_CPU0_P2P2_DP<22>")
	)
	(segment
		(start 254.688594 -343.999312)
		(end 254.380746 -344.30716)
		(width 0.14732)
		(layer "In11.Cu")
		(net "UPI_CPU1_CPU0_P2P2_DP<22>")
	)
	(segment
		(start 293.518336 -318.783208)
		(end 290.502594 -318.783208)
		(width 0.14732)
		(layer "In11.Cu")
		(net "UPI_CPU1_CPU0_P2P2_DP<22>")
	)
	(segment
		(start 257.36804 -337.425538)
		(end 257.36804 -337.860894)
		(width 0.14732)
		(layer "In11.Cu")
		(net "UPI_CPU1_CPU0_P2P2_DP<22>")
	)
	(segment
		(start 335.074514 -283.548074)
		(end 335.07426 -283.54782)
		(width 0.0889)
		(layer "In11.Cu")
		(net "UPI_CPU1_CPU0_P2P2_DP<22>")
	)
	(segment
		(start 107.702096 -284.361636)
		(end 107.717082 -284.353)
		(width 0.0889)
		(layer "In11.Cu")
		(net "UPI_CPU1_CPU0_P2P2_DP<22>")
	)
	(segment
		(start 293.994078 -319.25895)
		(end 293.518336 -318.783208)
		(width 0.14732)
		(layer "In11.Cu")
		(net "UPI_CPU1_CPU0_P2P2_DP<22>")
	)
	(segment
		(start 252.320806 -342.138)
		(end 252.320806 -342.72728)
		(width 0.14732)
		(layer "In11.Cu")
		(net "UPI_CPU1_CPU0_P2P2_DP<22>")
	)
	(segment
		(start 107.890564 -297.277282)
		(end 107.890564 -291.380164)
		(width 0.14732)
		(layer "In11.Cu")
		(net "UPI_CPU1_CPU0_P2P2_DP<22>")
	)
	(segment
		(start 254.380746 -344.30716)
		(end 252.468126 -344.30716)
		(width 0.14732)
		(layer "In11.Cu")
		(net "UPI_CPU1_CPU0_P2P2_DP<22>")
	)
	(segment
		(start 253.179326 -338.265516)
		(end 254.575818 -336.869024)
		(width 0.14732)
		(layer "In11.Cu")
		(net "UPI_CPU1_CPU0_P2P2_DP<22>")
	)
	(segment
		(start 335.068164 -282.895548)
		(end 335.059274 -282.900628)
		(width 0.0889)
		(layer "In11.Cu")
		(net "UPI_CPU1_CPU0_P2P2_DP<22>")
	)
	(segment
		(start 309.986172 -310.59247)
		(end 309.0164 -311.493916)
		(width 0.14732)
		(layer "In11.Cu")
		(net "UPI_CPU1_CPU0_P2P2_DP<22>")
	)
	(arc
		(start 335.059274 -286.156146)
		(mid 334.931381 -286.287208)
		(end 334.880966 -286.463232)
		(width 0.0889)
		(layer "In11.Cu")
		(net "UPI_CPU1_CPU0_P2P2_DP<22>")
	)
	(arc
		(start 108.649262 -288.605976)
		(mid 108.464683 -288.442122)
		(end 108.365544 -288.216086)
		(width 0.0889)
		(layer "In11.Cu")
		(net "UPI_CPU1_CPU0_P2P2_DP<22>")
	)
	(arc
		(start 108.365544 -288.103056)
		(mid 108.439535 -287.82349)
		(end 108.64215 -287.617154)
		(width 0.0889)
		(layer "In11.Cu")
		(net "UPI_CPU1_CPU0_P2P2_DP<22>")
	)
	(arc
		(start 107.895644 -284.033722)
		(mid 107.967879 -283.757198)
		(end 108.166154 -283.551376)
		(width 0.0889)
		(layer "In11.Cu")
		(net "UPI_CPU1_CPU0_P2P2_DP<22>")
	)
	(arc
		(start 334.880966 -286.463232)
		(mid 334.880721 -286.472628)
		(end 334.880712 -286.482028)
		(width 0.0889)
		(layer "In11.Cu")
		(net "UPI_CPU1_CPU0_P2P2_DP<22>")
	)
	(arc
		(start 108.648246 -287.613598)
		(mid 108.835549 -287.28924)
		(end 108.648246 -286.964882)
		(width 0.0889)
		(layer "In11.Cu")
		(net "UPI_CPU1_CPU0_P2P2_DP<22>")
	)
	(arc
		(start 107.238546 -281.267662)
		(mid 107.051348 -281.217519)
		(end 106.86415 -281.267662)
		(width 0.0889)
		(layer "In11.Cu")
		(net "UPI_CPU1_CPU0_P2P2_DP<22>")
	)
	(arc
		(start 107.708446 -282.081478)
		(mid 107.504111 -281.878873)
		(end 107.425998 -281.601926)
		(width 0.0889)
		(layer "In11.Cu")
		(net "UPI_CPU1_CPU0_P2P2_DP<22>")
	)
	(arc
		(start 335.059274 -282.900628)
		(mid 334.880677 -283.219906)
		(end 335.059274 -283.539184)
		(width 0.0889)
		(layer "In11.Cu")
		(net "UPI_CPU1_CPU0_P2P2_DP<22>")
	)
	(arc
		(start 107.702096 -285.33344)
		(mid 107.42577 -284.847538)
		(end 107.702096 -284.361636)
		(width 0.0889)
		(layer "In11.Cu")
		(net "UPI_CPU1_CPU0_P2P2_DP<22>")
	)
	(arc
		(start 106.29265 -281.264106)
		(mid 106.112998 -281.09467)
		(end 106.022648 -280.864818)
		(width 0.0889)
		(layer "In11.Cu")
		(net "UPI_CPU1_CPU0_P2P2_DP<22>")
	)
	(arc
		(start 108.84027 -288.873946)
		(mid 108.774817 -288.718531)
		(end 108.649262 -288.605976)
		(width 0.0889)
		(layer "In11.Cu")
		(net "UPI_CPU1_CPU0_P2P2_DP<22>")
	)
	(arc
		(start 107.717082 -284.353)
		(mid 107.847996 -284.21664)
		(end 107.895644 -284.033722)
		(width 0.0889)
		(layer "In11.Cu")
		(net "UPI_CPU1_CPU0_P2P2_DP<22>")
	)
	(arc
		(start 335.350866 -284.042358)
		(mid 335.403136 -284.224723)
		(end 335.538064 -284.35808)
		(width 0.0889)
		(layer "In11.Cu")
		(net "UPI_CPU1_CPU0_P2P2_DP<22>")
	)
	(arc
		(start 108.365544 -289.646868)
		(mid 108.471976 -289.440181)
		(end 108.650278 -289.291014)
		(width 0.0889)
		(layer "In11.Cu")
		(net "UPI_CPU1_CPU0_P2P2_DP<22>")
	)
	(arc
		(start 106.86415 -281.267662)
		(mid 106.589951 -281.343497)
		(end 106.313478 -281.276298)
		(width 0.0889)
		(layer "In11.Cu")
		(net "UPI_CPU1_CPU0_P2P2_DP<22>")
	)
	(arc
		(start 335.350612 -285.679896)
		(mid 335.27045 -285.952085)
		(end 335.068164 -286.151066)
		(width 0.0889)
		(layer "In11.Cu")
		(net "UPI_CPU1_CPU0_P2P2_DP<22>")
	)
	(arc
		(start 335.123282 -281.952192)
		(mid 335.131597 -281.958592)
		(end 335.139792 -281.965146)
		(width 0.0889)
		(layer "In11.Cu")
		(net "UPI_CPU1_CPU0_P2P2_DP<22>")
	)
	(arc
		(start 335.350612 -287.299146)
		(mid 335.272501 -287.576095)
		(end 335.068164 -287.778698)
		(width 0.0889)
		(layer "In11.Cu")
		(net "UPI_CPU1_CPU0_P2P2_DP<22>")
	)
	(arc
		(start 335.068164 -286.799782)
		(mid 335.272499 -287.002387)
		(end 335.350612 -287.279334)
		(width 0.0889)
		(layer "In11.Cu")
		(net "UPI_CPU1_CPU0_P2P2_DP<22>")
	)
	(arc
		(start 108.64215 -286.961326)
		(mid 108.439563 -286.754975)
		(end 108.365544 -286.475424)
		(width 0.0889)
		(layer "In11.Cu")
		(net "UPI_CPU1_CPU0_P2P2_DP<22>")
	)
	(arc
		(start 335.139792 -281.965146)
		(mid 335.29333 -282.157028)
		(end 335.350866 -282.39593)
		(width 0.0889)
		(layer "In11.Cu")
		(net "UPI_CPU1_CPU0_P2P2_DP<22>")
	)
	(arc
		(start 334.880712 -286.482028)
		(mid 334.929965 -286.661228)
		(end 335.059274 -286.794702)
		(width 0.0889)
		(layer "In11.Cu")
		(net "UPI_CPU1_CPU0_P2P2_DP<22>")
	)
	(arc
		(start 107.425998 -281.59202)
		(mid 107.378319 -281.40912)
		(end 107.247436 -281.272742)
		(width 0.0889)
		(layer "In11.Cu")
		(net "UPI_CPU1_CPU0_P2P2_DP<22>")
	)
	(arc
		(start 108.650278 -289.291014)
		(mid 108.757061 -289.206398)
		(end 108.82884 -289.090608)
		(width 0.0889)
		(layer "In11.Cu")
		(net "UPI_CPU1_CPU0_P2P2_DP<22>")
	)
	(arc
		(start 108.365544 -286.466788)
		(mid 108.313274 -286.284423)
		(end 108.178346 -286.151066)
		(width 0.0889)
		(layer "In11.Cu")
		(net "UPI_CPU1_CPU0_P2P2_DP<22>")
	)
	(arc
		(start 108.178346 -282.895548)
		(mid 107.97606 -282.696567)
		(end 107.895898 -282.424378)
		(width 0.0889)
		(layer "In11.Cu")
		(net "UPI_CPU1_CPU0_P2P2_DP<22>")
	)
	(arc
		(start 335.538064 -284.35808)
		(mid 335.742399 -284.560685)
		(end 335.820512 -284.837632)
		(width 0.0889)
		(layer "In11.Cu")
		(net "UPI_CPU1_CPU0_P2P2_DP<22>")
	)
	(arc
		(start 335.068164 -287.778698)
		(mid 334.931795 -287.83514)
		(end 334.785462 -287.85439)
		(width 0.0889)
		(layer "In11.Cu")
		(net "UPI_CPU1_CPU0_P2P2_DP<22>")
	)
	(arc
		(start 108.178346 -283.544264)
		(mid 108.365649 -283.219906)
		(end 108.178346 -282.895548)
		(width 0.0889)
		(layer "In11.Cu")
		(net "UPI_CPU1_CPU0_P2P2_DP<22>")
	)
	(arc
		(start 106.022648 -280.864818)
		(mid 106.021153 -280.854417)
		(end 106.019854 -280.84399)
		(width 0.0889)
		(layer "In11.Cu")
		(net "UPI_CPU1_CPU0_P2P2_DP<22>")
	)
	(arc
		(start 107.895898 -282.405836)
		(mid 107.848219 -282.222936)
		(end 107.717336 -282.086558)
		(width 0.0889)
		(layer "In11.Cu")
		(net "UPI_CPU1_CPU0_P2P2_DP<22>")
	)
	(arc
		(start 107.895644 -285.661354)
		(mid 107.847965 -285.478454)
		(end 107.717082 -285.342076)
		(width 0.0889)
		(layer "In11.Cu")
		(net "UPI_CPU1_CPU0_P2P2_DP<22>")
	)
	(arc
		(start 335.07426 -283.54782)
		(mid 335.276847 -283.754171)
		(end 335.350866 -284.033722)
		(width 0.0889)
		(layer "In11.Cu")
		(net "UPI_CPU1_CPU0_P2P2_DP<22>")
	)
	(arc
		(start 335.529174 -285.342076)
		(mid 335.39826 -285.478436)
		(end 335.350612 -285.661354)
		(width 0.0889)
		(layer "In11.Cu")
		(net "UPI_CPU1_CPU0_P2P2_DP<22>")
	)
	(arc
		(start 108.178346 -286.151066)
		(mid 107.973274 -285.947387)
		(end 107.895644 -285.668974)
		(width 0.0889)
		(layer "In11.Cu")
		(net "UPI_CPU1_CPU0_P2P2_DP<22>")
	)
	(arc
		(start 335.820512 -284.857444)
		(mid 335.742401 -285.134393)
		(end 335.538064 -285.336996)
		(width 0.0889)
		(layer "In11.Cu")
		(net "UPI_CPU1_CPU0_P2P2_DP<22>")
	)
	(arc
		(start 335.350866 -282.42006)
		(mid 335.271647 -282.694745)
		(end 335.068164 -282.895548)
		(width 0.0889)
		(layer "In11.Cu")
		(net "UPI_CPU1_CPU0_P2P2_DP<22>")
	)
	(segment
		(start 106.581448 -281.869896)
		(end 106.581448 -282.405582)
		(width 0.13208)
		(layer "F.Cu")
		(net "UPI_CPU1_CPU0_P2P2_DP<21>")
	)
	(segment
		(start 106.581448 -282.405582)
		(end 106.581194 -282.405836)
		(width 0.13208)
		(layer "F.Cu")
		(net "UPI_CPU1_CPU0_P2P2_DP<21>")
	)
	(segment
		(start 336.195162 -282.683966)
		(end 336.195162 -283.219906)
		(width 0.13208)
		(layer "F.Cu")
		(net "UPI_CPU1_CPU0_P2P2_DP<21>")
	)
	(segment
		(start 107.425744 -290.072064)
		(end 107.198414 -290.299394)
		(width 0.0889)
		(layer "In11.Cu")
		(net "UPI_CPU1_CPU0_P2P2_DP<21>")
	)
	(segment
		(start 301.35322 -321.836542)
		(end 301.35322 -320.663316)
		(width 0.14732)
		(layer "In11.Cu")
		(net "UPI_CPU1_CPU0_P2P2_DP<21>")
	)
	(segment
		(start 336.468974 -285.342076)
		(end 336.477864 -285.336996)
		(width 0.0889)
		(layer "In11.Cu")
		(net "UPI_CPU1_CPU0_P2P2_DP<21>")
	)
	(segment
		(start 106.768392 -282.081478)
		(end 106.777282 -282.086558)
		(width 0.0889)
		(layer "In11.Cu")
		(net "UPI_CPU1_CPU0_P2P2_DP<21>")
	)
	(segment
		(start 262.72236 -331.653896)
		(end 266.938252 -331.653896)
		(width 0.14732)
		(layer "In11.Cu")
		(net "UPI_CPU1_CPU0_P2P2_DP<21>")
	)
	(segment
		(start 306.264564 -314.150248)
		(end 306.562506 -314.150248)
		(width 0.14732)
		(layer "In11.Cu")
		(net "UPI_CPU1_CPU0_P2P2_DP<21>")
	)
	(segment
		(start 272.046446 -325.374508)
		(end 272.193766 -325.227188)
		(width 0.14732)
		(layer "In11.Cu")
		(net "UPI_CPU1_CPU0_P2P2_DP<21>")
	)
	(segment
		(start 301.96917 -317.099188)
		(end 302.095154 -316.840108)
		(width 0.14732)
		(layer "In11.Cu")
		(net "UPI_CPU1_CPU0_P2P2_DP<21>")
	)
	(segment
		(start 257.179826 -342.82634)
		(end 257.487674 -342.518492)
		(width 0.14732)
		(layer "In11.Cu")
		(net "UPI_CPU1_CPU0_P2P2_DP<21>")
	)
	(segment
		(start 74.524362 -329.261216)
		(end 73.938638 -335.207864)
		(width 0.14732)
		(layer "In11.Cu")
		(net "UPI_CPU1_CPU0_P2P2_DP<21>")
	)
	(segment
		(start 261.748778 -334.652366)
		(end 262.526272 -333.874872)
		(width 0.14732)
		(layer "In11.Cu")
		(net "UPI_CPU1_CPU0_P2P2_DP<21>")
	)
	(segment
		(start 106.767884 -284.358588)
		(end 106.76255 -284.361636)
		(width 0.0889)
		(layer "In11.Cu")
		(net "UPI_CPU1_CPU0_P2P2_DP<21>")
	)
	(segment
		(start 257.032506 -339.576918)
		(end 258.854448 -341.39886)
		(width 0.14732)
		(layer "In11.Cu")
		(net "UPI_CPU1_CPU0_P2P2_DP<21>")
	)
	(segment
		(start 106.415332 -291.082476)
		(end 106.27487 -291.082476)
		(width 0.0889)
		(layer "In11.Cu")
		(net "UPI_CPU1_CPU0_P2P2_DP<21>")
	)
	(segment
		(start 304.624486 -315.485526)
		(end 306.264564 -314.150248)
		(width 0.14732)
		(layer "In11.Cu")
		(net "UPI_CPU1_CPU0_P2P2_DP<21>")
	)
	(segment
		(start 283.974032 -323.866256)
		(end 283.974032 -323.171566)
		(width 0.14732)
		(layer "In11.Cu")
		(net "UPI_CPU1_CPU0_P2P2_DP<21>")
	)
	(segment
		(start 331.554582 -292.188646)
		(end 334.147414 -289.595814)
		(width 0.14732)
		(layer "In11.Cu")
		(net "UPI_CPU1_CPU0_P2P2_DP<21>")
	)
	(segment
		(start 268.150086 -325.227188)
		(end 268.297406 -325.374508)
		(width 0.14732)
		(layer "In11.Cu")
		(net "UPI_CPU1_CPU0_P2P2_DP<21>")
	)
	(segment
		(start 105.757472 -291.740336)
		(end 105.60177 -291.896038)
		(width 0.0889)
		(layer "In11.Cu")
		(net "UPI_CPU1_CPU0_P2P2_DP<21>")
	)
	(segment
		(start 256.824226 -339.576918)
		(end 257.032506 -339.576918)
		(width 0.14732)
		(layer "In11.Cu")
		(net "UPI_CPU1_CPU0_P2P2_DP<21>")
	)
	(segment
		(start 106.023664 -291.474144)
		(end 105.883202 -291.474144)
		(width 0.0889)
		(layer "In11.Cu")
		(net "UPI_CPU1_CPU0_P2P2_DP<21>")
	)
	(segment
		(start 277.53818 -324.174104)
		(end 283.666184 -324.174104)
		(width 0.14732)
		(layer "In11.Cu")
		(net "UPI_CPU1_CPU0_P2P2_DP<21>")
	)
	(segment
		(start 259.715508 -336.685636)
		(end 260.687312 -335.713832)
		(width 0.14732)
		(layer "In11.Cu")
		(net "UPI_CPU1_CPU0_P2P2_DP<21>")
	)
	(segment
		(start 336.038698 -282.948888)
		(end 336.195162 -283.219906)
		(width 0.0889)
		(layer "In11.Cu")
		(net "UPI_CPU1_CPU0_P2P2_DP<21>")
	)
	(segment
		(start 302.095154 -316.840108)
		(end 302.095154 -316.839854)
		(width 0.14732)
		(layer "In11.Cu")
		(net "UPI_CPU1_CPU0_P2P2_DP<21>")
	)
	(segment
		(start 259.279644 -336.685636)
		(end 259.715508 -336.685636)
		(width 0.14732)
		(layer "In11.Cu")
		(net "UPI_CPU1_CPU0_P2P2_DP<21>")
	)
	(segment
		(start 75.029314 -327.437242)
		(end 74.524362 -329.261216)
		(width 0.14732)
		(layer "In11.Cu")
		(net "UPI_CPU1_CPU0_P2P2_DP<21>")
	)
	(segment
		(start 335.960466 -282.92806)
		(end 336.038698 -282.948888)
		(width 0.0889)
		(layer "In11.Cu")
		(net "UPI_CPU1_CPU0_P2P2_DP<21>")
	)
	(segment
		(start 256.267712 -334.717136)
		(end 256.685542 -334.299306)
		(width 0.14732)
		(layer "In11.Cu")
		(net "UPI_CPU1_CPU0_P2P2_DP<21>")
	)
	(segment
		(start 300.427898 -322.761864)
		(end 301.35322 -321.836542)
		(width 0.14732)
		(layer "In11.Cu")
		(net "UPI_CPU1_CPU0_P2P2_DP<21>")
	)
	(segment
		(start 228.837236 -367.53927)
		(end 252.78588 -350.767396)
		(width 0.14732)
		(layer "In11.Cu")
		(net "UPI_CPU1_CPU0_P2P2_DP<21>")
	)
	(segment
		(start 335.820512 -288.11728)
		(end 335.820512 -288.103056)
		(width 0.0889)
		(layer "In11.Cu")
		(net "UPI_CPU1_CPU0_P2P2_DP<21>")
	)
	(segment
		(start 262.526272 -333.874872)
		(end 262.526272 -331.849984)
		(width 0.14732)
		(layer "In11.Cu")
		(net "UPI_CPU1_CPU0_P2P2_DP<21>")
	)
	(segment
		(start 335.999074 -287.783778)
		(end 336.007964 -287.778698)
		(width 0.0889)
		(layer "In11.Cu")
		(net "UPI_CPU1_CPU0_P2P2_DP<21>")
	)
	(segment
		(start 258.04622 -338.563204)
		(end 258.04622 -338.354924)
		(width 0.14732)
		(layer "In11.Cu")
		(net "UPI_CPU1_CPU0_P2P2_DP<21>")
	)
	(segment
		(start 310.02986 -313.156854)
		(end 311.216294 -311.97042)
		(width 0.14732)
		(layer "In11.Cu")
		(net "UPI_CPU1_CPU0_P2P2_DP<21>")
	)
	(segment
		(start 258.301236 -332.683866)
		(end 258.719066 -332.266036)
		(width 0.14732)
		(layer "In11.Cu")
		(net "UPI_CPU1_CPU0_P2P2_DP<21>")
	)
	(segment
		(start 107.238546 -282.895548)
		(end 107.247436 -282.900628)
		(width 0.0889)
		(layer "In11.Cu")
		(net "UPI_CPU1_CPU0_P2P2_DP<21>")
	)
	(segment
		(start 270.613886 -325.374508)
		(end 270.613886 -325.540116)
		(width 0.14732)
		(layer "In11.Cu")
		(net "UPI_CPU1_CPU0_P2P2_DP<21>")
	)
	(segment
		(start 306.562506 -314.150248)
		(end 307.5559 -313.156854)
		(width 0.14732)
		(layer "In11.Cu")
		(net "UPI_CPU1_CPU0_P2P2_DP<21>")
	)
	(segment
		(start 105.469182 -297.667934)
		(end 103.681784 -300.077632)
		(width 0.14732)
		(layer "In11.Cu")
		(net "UPI_CPU1_CPU0_P2P2_DP<21>")
	)
	(segment
		(start 256.216404 -347.336618)
		(end 256.216404 -342.97366)
		(width 0.14732)
		(layer "In11.Cu")
		(net "UPI_CPU1_CPU0_P2P2_DP<21>")
	)
	(segment
		(start 256.216404 -340.18474)
		(end 256.824226 -339.576918)
		(width 0.14732)
		(layer "In11.Cu")
		(net "UPI_CPU1_CPU0_P2P2_DP<21>")
	)
	(segment
		(start 260.687312 -335.277968)
		(end 258.301236 -332.891892)
		(width 0.14732)
		(layer "In11.Cu")
		(net "UPI_CPU1_CPU0_P2P2_DP<21>")
	)
	(segment
		(start 256.893314 -334.299306)
		(end 259.279644 -336.685636)
		(width 0.14732)
		(layer "In11.Cu")
		(net "UPI_CPU1_CPU0_P2P2_DP<21>")
	)
	(segment
		(start 99.322636 -371.16639)
		(end 126.327408 -375.172224)
		(width 0.14732)
		(layer "In11.Cu")
		(net "UPI_CPU1_CPU0_P2P2_DP<21>")
	)
	(segment
		(start 334.511396 -289.231578)
		(end 334.511396 -289.171634)
		(width 0.0889)
		(layer "In11.Cu")
		(net "UPI_CPU1_CPU0_P2P2_DP<21>")
	)
	(segment
		(start 334.495902 -289.247072)
		(end 334.511396 -289.231578)
		(width 0.0889)
		(layer "In11.Cu")
		(net "UPI_CPU1_CPU0_P2P2_DP<21>")
	)
	(segment
		(start 258.926584 -332.266036)
		(end 261.312914 -334.652366)
		(width 0.14732)
		(layer "In11.Cu")
		(net "UPI_CPU1_CPU0_P2P2_DP<21>")
	)
	(segment
		(start 107.238292 -286.151066)
		(end 107.247182 -286.156146)
		(width 0.0889)
		(layer "In11.Cu")
		(net "UPI_CPU1_CPU0_P2P2_DP<21>")
	)
	(segment
		(start 105.55986 -292.442646)
		(end 105.55986 -297.448986)
		(width 0.14732)
		(layer "In11.Cu")
		(net "UPI_CPU1_CPU0_P2P2_DP<21>")
	)
	(segment
		(start 336.481674 -286.962596)
		(end 336.490056 -286.95777)
		(width 0.0889)
		(layer "In11.Cu")
		(net "UPI_CPU1_CPU0_P2P2_DP<21>")
	)
	(segment
		(start 256.685542 -334.299306)
		(end 256.893314 -334.299306)
		(width 0.14732)
		(layer "In11.Cu")
		(net "UPI_CPU1_CPU0_P2P2_DP<21>")
	)
	(segment
		(start 107.425744 -289.54984)
		(end 107.425744 -290.072064)
		(width 0.0889)
		(layer "In11.Cu")
		(net "UPI_CPU1_CPU0_P2P2_DP<21>")
	)
	(segment
		(start 269.729966 -325.540116)
		(end 269.729966 -325.374508)
		(width 0.14732)
		(layer "In11.Cu")
		(net "UPI_CPU1_CPU0_P2P2_DP<21>")
	)
	(segment
		(start 107.708446 -288.592768)
		(end 107.720892 -288.59988)
		(width 0.0889)
		(layer "In11.Cu")
		(net "UPI_CPU1_CPU0_P2P2_DP<21>")
	)
	(segment
		(start 336.760566 -286.475424)
		(end 336.760566 -286.467804)
		(width 0.0889)
		(layer "In11.Cu")
		(net "UPI_CPU1_CPU0_P2P2_DP<21>")
	)
	(segment
		(start 106.666538 -290.690808)
		(end 106.540808 -290.816538)
		(width 0.0889)
		(layer "In11.Cu")
		(net "UPI_CPU1_CPU0_P2P2_DP<21>")
	)
	(segment
		(start 106.807 -290.690808)
		(end 106.666538 -290.690808)
		(width 0.0889)
		(layer "In11.Cu")
		(net "UPI_CPU1_CPU0_P2P2_DP<21>")
	)
	(segment
		(start 107.425744 -288.103056)
		(end 107.425744 -288.110676)
		(width 0.0889)
		(layer "In11.Cu")
		(net "UPI_CPU1_CPU0_P2P2_DP<21>")
	)
	(segment
		(start 106.14914 -291.348668)
		(end 106.023664 -291.474144)
		(width 0.0889)
		(layer "In11.Cu")
		(net "UPI_CPU1_CPU0_P2P2_DP<21>")
	)
	(segment
		(start 272.193766 -325.227188)
		(end 276.485096 -325.227188)
		(width 0.14732)
		(layer "In11.Cu")
		(net "UPI_CPU1_CPU0_P2P2_DP<21>")
	)
	(segment
		(start 307.5559 -313.156854)
		(end 310.02986 -313.156854)
		(width 0.14732)
		(layer "In11.Cu")
		(net "UPI_CPU1_CPU0_P2P2_DP<21>")
	)
	(segment
		(start 259.289804 -341.39886)
		(end 259.868162 -340.820502)
		(width 0.14732)
		(layer "In11.Cu")
		(net "UPI_CPU1_CPU0_P2P2_DP<21>")
	)
	(segment
		(start 79.377794 -362.904278)
		(end 99.322636 -371.16639)
		(width 0.14732)
		(layer "In11.Cu")
		(net "UPI_CPU1_CPU0_P2P2_DP<21>")
	)
	(segment
		(start 258.654042 -337.747102)
		(end 258.654042 -337.311238)
		(width 0.14732)
		(layer "In11.Cu")
		(net "UPI_CPU1_CPU0_P2P2_DP<21>")
	)
	(segment
		(start 256.267712 -334.924908)
		(end 256.267712 -334.717136)
		(width 0.14732)
		(layer "In11.Cu")
		(net "UPI_CPU1_CPU0_P2P2_DP<21>")
	)
	(segment
		(start 105.55986 -297.448986)
		(end 105.469182 -297.667934)
		(width 0.14732)
		(layer "In11.Cu")
		(net "UPI_CPU1_CPU0_P2P2_DP<21>")
	)
	(segment
		(start 106.42473 -282.134818)
		(end 106.445812 -282.05684)
		(width 0.0889)
		(layer "In11.Cu")
		(net "UPI_CPU1_CPU0_P2P2_DP<21>")
	)
	(segment
		(start 266.938252 -331.653896)
		(end 267.2461 -331.346048)
		(width 0.14732)
		(layer "In11.Cu")
		(net "UPI_CPU1_CPU0_P2P2_DP<21>")
	)
	(segment
		(start 256.363724 -341.39378)
		(end 256.216404 -341.24646)
		(width 0.14732)
		(layer "In11.Cu")
		(net "UPI_CPU1_CPU0_P2P2_DP<21>")
	)
	(segment
		(start 262.526272 -327.954132)
		(end 265.253216 -325.227188)
		(width 0.14732)
		(layer "In11.Cu")
		(net "UPI_CPU1_CPU0_P2P2_DP<21>")
	)
	(segment
		(start 268.297406 -325.540116)
		(end 268.605254 -325.847964)
		(width 0.14732)
		(layer "In11.Cu")
		(net "UPI_CPU1_CPU0_P2P2_DP<21>")
	)
	(segment
		(start 287.481772 -322.78447)
		(end 288.07664 -323.379338)
		(width 0.14732)
		(layer "In11.Cu")
		(net "UPI_CPU1_CPU0_P2P2_DP<21>")
	)
	(segment
		(start 336.290412 -287.299146)
		(end 336.290412 -287.28924)
		(width 0.0889)
		(layer "In11.Cu")
		(net "UPI_CPU1_CPU0_P2P2_DP<21>")
	)
	(segment
		(start 106.14914 -291.208206)
		(end 106.14914 -291.348668)
		(width 0.0889)
		(layer "In11.Cu")
		(net "UPI_CPU1_CPU0_P2P2_DP<21>")
	)
	(segment
		(start 331.070204 -292.913562)
		(end 331.554582 -292.188646)
		(width 0.14732)
		(layer "In11.Cu")
		(net "UPI_CPU1_CPU0_P2P2_DP<21>")
	)
	(segment
		(start 276.485096 -325.227188)
		(end 277.53818 -324.174104)
		(width 0.14732)
		(layer "In11.Cu")
		(net "UPI_CPU1_CPU0_P2P2_DP<21>")
	)
	(segment
		(start 269.729966 -325.374508)
		(end 269.877286 -325.227188)
		(width 0.14732)
		(layer "In11.Cu")
		(net "UPI_CPU1_CPU0_P2P2_DP<21>")
	)
	(segment
		(start 199.946514 -368.27206)
		(end 212.312504 -370.45265)
		(width 0.14732)
		(layer "In11.Cu")
		(net "UPI_CPU1_CPU0_P2P2_DP<21>")
	)
	(segment
		(start 260.687312 -335.713832)
		(end 260.687312 -335.277968)
		(width 0.14732)
		(layer "In11.Cu")
		(net "UPI_CPU1_CPU0_P2P2_DP<21>")
	)
	(segment
		(start 336.011774 -283.54655)
		(end 336.007964 -283.544264)
		(width 0.0889)
		(layer "In11.Cu")
		(net "UPI_CPU1_CPU0_P2P2_DP<21>")
	)
	(segment
		(start 301.35322 -320.663316)
		(end 301.686468 -318.904366)
		(width 0.14732)
		(layer "In11.Cu")
		(net "UPI_CPU1_CPU0_P2P2_DP<21>")
	)
	(segment
		(start 107.247182 -286.794702)
		(end 107.238292 -286.799782)
		(width 0.0889)
		(layer "In11.Cu")
		(net "UPI_CPU1_CPU0_P2P2_DP<21>")
	)
	(segment
		(start 288.07664 -323.379338)
		(end 298.937426 -323.379338)
		(width 0.14732)
		(layer "In11.Cu")
		(net "UPI_CPU1_CPU0_P2P2_DP<21>")
	)
	(segment
		(start 317.167514 -311.283858)
		(end 329.124818 -299.326554)
		(width 0.14732)
		(layer "In11.Cu")
		(net "UPI_CPU1_CPU0_P2P2_DP<21>")
	)
	(segment
		(start 262.526272 -330.025248)
		(end 262.526272 -327.954132)
		(width 0.14732)
		(layer "In11.Cu")
		(net "UPI_CPU1_CPU0_P2P2_DP<21>")
	)
	(segment
		(start 107.247436 -283.539184)
		(end 107.23245 -283.54782)
		(width 0.0889)
		(layer "In11.Cu")
		(net "UPI_CPU1_CPU0_P2P2_DP<21>")
	)
	(segment
		(start 107.816396 -289.159188)
		(end 107.425744 -289.54984)
		(width 0.0889)
		(layer "In11.Cu")
		(net "UPI_CPU1_CPU0_P2P2_DP<21>")
	)
	(segment
		(start 259.868162 -340.385146)
		(end 258.04622 -338.563204)
		(width 0.14732)
		(layer "In11.Cu")
		(net "UPI_CPU1_CPU0_P2P2_DP<21>")
	)
	(segment
		(start 106.955844 -284.033722)
		(end 106.955844 -284.042358)
		(width 0.0889)
		(layer "In11.Cu")
		(net "UPI_CPU1_CPU0_P2P2_DP<21>")
	)
	(segment
		(start 335.01457 -288.66846)
		(end 335.255362 -288.66846)
		(width 0.0889)
		(layer "In11.Cu")
		(net "UPI_CPU1_CPU0_P2P2_DP<21>")
	)
	(segment
		(start 270.921734 -325.847964)
		(end 271.738598 -325.847964)
		(width 0.14732)
		(layer "In11.Cu")
		(net "UPI_CPU1_CPU0_P2P2_DP<21>")
	)
	(segment
		(start 106.932476 -290.425124)
		(end 106.932476 -290.565332)
		(width 0.0889)
		(layer "In11.Cu")
		(net "UPI_CPU1_CPU0_P2P2_DP<21>")
	)
	(segment
		(start 272.046446 -325.540116)
		(end 272.046446 -325.374508)
		(width 0.14732)
		(layer "In11.Cu")
		(net "UPI_CPU1_CPU0_P2P2_DP<21>")
	)
	(segment
		(start 336.760312 -284.857444)
		(end 336.760312 -284.832044)
		(width 0.0889)
		(layer "In11.Cu")
		(net "UPI_CPU1_CPU0_P2P2_DP<21>")
	)
	(segment
		(start 107.238292 -287.778698)
		(end 107.247182 -287.783778)
		(width 0.0889)
		(layer "In11.Cu")
		(net "UPI_CPU1_CPU0_P2P2_DP<21>")
	)
	(segment
		(start 106.27487 -291.082476)
		(end 106.14914 -291.208206)
		(width 0.0889)
		(layer "In11.Cu")
		(net "UPI_CPU1_CPU0_P2P2_DP<21>")
	)
	(segment
		(start 334.147414 -289.59556)
		(end 334.495902 -289.247072)
		(width 0.14732)
		(layer "In11.Cu")
		(net "UPI_CPU1_CPU0_P2P2_DP<21>")
	)
	(segment
		(start 302.483774 -316.56528)
		(end 304.624486 -315.485526)
		(width 0.14732)
		(layer "In11.Cu")
		(net "UPI_CPU1_CPU0_P2P2_DP<21>")
	)
	(segment
		(start 258.301236 -332.891892)
		(end 258.301236 -332.683866)
		(width 0.14732)
		(layer "In11.Cu")
		(net "UPI_CPU1_CPU0_P2P2_DP<21>")
	)
	(segment
		(start 283.974032 -323.171566)
		(end 284.361128 -322.78447)
		(width 0.14732)
		(layer "In11.Cu")
		(net "UPI_CPU1_CPU0_P2P2_DP<21>")
	)
	(segment
		(start 266.938252 -330.221336)
		(end 262.72236 -330.221336)
		(width 0.14732)
		(layer "In11.Cu")
		(net "UPI_CPU1_CPU0_P2P2_DP<21>")
	)
	(segment
		(start 336.477102 -284.357572)
		(end 336.469228 -284.353)
		(width 0.0889)
		(layer "In11.Cu")
		(net "UPI_CPU1_CPU0_P2P2_DP<21>")
	)
	(segment
		(start 257.487674 -342.518492)
		(end 257.487674 -341.701628)
		(width 0.14732)
		(layer "In11.Cu")
		(net "UPI_CPU1_CPU0_P2P2_DP<21>")
	)
	(segment
		(start 103.681784 -300.077632)
		(end 99.337622 -305.239674)
		(width 0.14732)
		(layer "In11.Cu")
		(net "UPI_CPU1_CPU0_P2P2_DP<21>")
	)
	(segment
		(start 336.477864 -286.964882)
		(end 336.481674 -286.962596)
		(width 0.0889)
		(layer "In11.Cu")
		(net "UPI_CPU1_CPU0_P2P2_DP<21>")
	)
	(segment
		(start 99.337622 -305.239674)
		(end 83.291426 -318.405764)
		(width 0.14732)
		(layer "In11.Cu")
		(net "UPI_CPU1_CPU0_P2P2_DP<21>")
	)
	(segment
		(start 334.511396 -289.171634)
		(end 335.01457 -288.66846)
		(width 0.0889)
		(layer "In11.Cu")
		(net "UPI_CPU1_CPU0_P2P2_DP<21>")
	)
	(segment
		(start 106.955844 -282.405836)
		(end 106.955844 -282.42006)
		(width 0.0889)
		(layer "In11.Cu")
		(net "UPI_CPU1_CPU0_P2P2_DP<21>")
	)
	(segment
		(start 269.877286 -325.227188)
		(end 270.466566 -325.227188)
		(width 0.14732)
		(layer "In11.Cu")
		(net "UPI_CPU1_CPU0_P2P2_DP<21>")
	)
	(segment
		(start 83.291426 -318.405764)
		(end 75.719686 -325.977504)
		(width 0.14732)
		(layer "In11.Cu")
		(net "UPI_CPU1_CPU0_P2P2_DP<21>")
	)
	(segment
		(start 261.312914 -334.652366)
		(end 261.748778 -334.652366)
		(width 0.14732)
		(layer "In11.Cu")
		(net "UPI_CPU1_CPU0_P2P2_DP<21>")
	)
	(segment
		(start 336.007964 -283.544264)
		(end 335.999074 -283.539184)
		(width 0.0889)
		(layer "In11.Cu")
		(net "UPI_CPU1_CPU0_P2P2_DP<21>")
	)
	(segment
		(start 256.216404 -342.97366)
		(end 256.363724 -342.82634)
		(width 0.14732)
		(layer "In11.Cu")
		(net "UPI_CPU1_CPU0_P2P2_DP<21>")
	)
	(segment
		(start 329.124818 -299.326554)
		(end 331.070204 -292.913562)
		(width 0.14732)
		(layer "In11.Cu")
		(net "UPI_CPU1_CPU0_P2P2_DP<21>")
	)
	(segment
		(start 106.76255 -285.33344)
		(end 106.764836 -285.33471)
		(width 0.0889)
		(layer "In11.Cu")
		(net "UPI_CPU1_CPU0_P2P2_DP<21>")
	)
	(segment
		(start 126.327408 -375.172224)
		(end 160.81121 -375.172224)
		(width 0.14732)
		(layer "In11.Cu")
		(net "UPI_CPU1_CPU0_P2P2_DP<21>")
	)
	(segment
		(start 105.55986 -292.420548)
		(end 105.55986 -292.442646)
		(width 0.0889)
		(layer "In11.Cu")
		(net "UPI_CPU1_CPU0_P2P2_DP<21>")
	)
	(segment
		(start 284.361128 -322.78447)
		(end 287.481772 -322.78447)
		(width 0.14732)
		(layer "In11.Cu")
		(net "UPI_CPU1_CPU0_P2P2_DP<21>")
	)
	(segment
		(start 336.468974 -286.969962)
		(end 336.477864 -286.964882)
		(width 0.0889)
		(layer "In11.Cu")
		(net "UPI_CPU1_CPU0_P2P2_DP<21>")
	)
	(segment
		(start 105.883202 -291.474144)
		(end 105.757472 -291.599874)
		(width 0.0889)
		(layer "In11.Cu")
		(net "UPI_CPU1_CPU0_P2P2_DP<21>")
	)
	(segment
		(start 302.095154 -316.839854)
		(end 302.483774 -316.56528)
		(width 0.14732)
		(layer "In11.Cu")
		(net "UPI_CPU1_CPU0_P2P2_DP<21>")
	)
	(segment
		(start 107.058206 -290.299394)
		(end 106.932476 -290.425124)
		(width 0.0889)
		(layer "In11.Cu")
		(net "UPI_CPU1_CPU0_P2P2_DP<21>")
	)
	(segment
		(start 73.938638 -352.713544)
		(end 77.305154 -360.831892)
		(width 0.14732)
		(layer "In11.Cu")
		(net "UPI_CPU1_CPU0_P2P2_DP<21>")
	)
	(segment
		(start 336.478118 -284.35808)
		(end 336.477102 -284.357572)
		(width 0.0889)
		(layer "In11.Cu")
		(net "UPI_CPU1_CPU0_P2P2_DP<21>")
	)
	(segment
		(start 314.550044 -311.283858)
		(end 317.167514 -311.283858)
		(width 0.14732)
		(layer "In11.Cu")
		(net "UPI_CPU1_CPU0_P2P2_DP<21>")
	)
	(segment
		(start 258.04622 -338.354924)
		(end 258.654042 -337.747102)
		(width 0.14732)
		(layer "In11.Cu")
		(net "UPI_CPU1_CPU0_P2P2_DP<21>")
	)
	(segment
		(start 270.466566 -325.227188)
		(end 270.613886 -325.374508)
		(width 0.14732)
		(layer "In11.Cu")
		(net "UPI_CPU1_CPU0_P2P2_DP<21>")
	)
	(segment
		(start 258.854448 -341.39886)
		(end 259.289804 -341.39886)
		(width 0.14732)
		(layer "In11.Cu")
		(net "UPI_CPU1_CPU0_P2P2_DP<21>")
	)
	(segment
		(start 336.020156 -283.551376)
		(end 336.011774 -283.54655)
		(width 0.0889)
		(layer "In11.Cu")
		(net "UPI_CPU1_CPU0_P2P2_DP<21>")
	)
	(segment
		(start 105.60177 -292.378638)
		(end 105.55986 -292.420548)
		(width 0.0889)
		(layer "In11.Cu")
		(net "UPI_CPU1_CPU0_P2P2_DP<21>")
	)
	(segment
		(start 283.666184 -324.174104)
		(end 283.974032 -323.866256)
		(width 0.14732)
		(layer "In11.Cu")
		(net "UPI_CPU1_CPU0_P2P2_DP<21>")
	)
	(segment
		(start 256.363724 -342.82634)
		(end 257.179826 -342.82634)
		(width 0.14732)
		(layer "In11.Cu")
		(net "UPI_CPU1_CPU0_P2P2_DP<21>")
	)
	(segment
		(start 106.581194 -282.405836)
		(end 106.42473 -282.134818)
		(width 0.0889)
		(layer "In11.Cu")
		(net "UPI_CPU1_CPU0_P2P2_DP<21>")
	)
	(segment
		(start 334.147414 -289.595814)
		(end 334.147414 -289.59556)
		(width 0.14732)
		(layer "In11.Cu")
		(net "UPI_CPU1_CPU0_P2P2_DP<21>")
	)
	(segment
		(start 105.757472 -291.599874)
		(end 105.757472 -291.740336)
		(width 0.0889)
		(layer "In11.Cu")
		(net "UPI_CPU1_CPU0_P2P2_DP<21>")
	)
	(segment
		(start 258.719066 -332.266036)
		(end 258.926584 -332.266036)
		(width 0.14732)
		(layer "In11.Cu")
		(net "UPI_CPU1_CPU0_P2P2_DP<21>")
	)
	(segment
		(start 265.253216 -325.227188)
		(end 268.150086 -325.227188)
		(width 0.14732)
		(layer "In11.Cu")
		(net "UPI_CPU1_CPU0_P2P2_DP<21>")
	)
	(segment
		(start 268.297406 -325.374508)
		(end 268.297406 -325.540116)
		(width 0.14732)
		(layer "In11.Cu")
		(net "UPI_CPU1_CPU0_P2P2_DP<21>")
	)
	(segment
		(start 262.72236 -330.221336)
		(end 262.526272 -330.025248)
		(width 0.14732)
		(layer "In11.Cu")
		(net "UPI_CPU1_CPU0_P2P2_DP<21>")
	)
	(segment
		(start 269.422118 -325.847964)
		(end 269.729966 -325.540116)
		(width 0.14732)
		(layer "In11.Cu")
		(net "UPI_CPU1_CPU0_P2P2_DP<21>")
	)
	(segment
		(start 259.868162 -340.820502)
		(end 259.868162 -340.385146)
		(width 0.14732)
		(layer "In11.Cu")
		(net "UPI_CPU1_CPU0_P2P2_DP<21>")
	)
	(segment
		(start 270.613886 -325.540116)
		(end 270.921734 -325.847964)
		(width 0.14732)
		(layer "In11.Cu")
		(net "UPI_CPU1_CPU0_P2P2_DP<21>")
	)
	(segment
		(start 256.216404 -341.24646)
		(end 256.216404 -340.18474)
		(width 0.14732)
		(layer "In11.Cu")
		(net "UPI_CPU1_CPU0_P2P2_DP<21>")
	)
	(segment
		(start 212.312504 -370.45265)
		(end 228.837236 -367.53927)
		(width 0.14732)
		(layer "In11.Cu")
		(net "UPI_CPU1_CPU0_P2P2_DP<21>")
	)
	(segment
		(start 160.81121 -375.172224)
		(end 199.946514 -368.27206)
		(width 0.14732)
		(layer "In11.Cu")
		(net "UPI_CPU1_CPU0_P2P2_DP<21>")
	)
	(segment
		(start 268.605254 -325.847964)
		(end 269.422118 -325.847964)
		(width 0.14732)
		(layer "In11.Cu")
		(net "UPI_CPU1_CPU0_P2P2_DP<21>")
	)
	(segment
		(start 252.78588 -350.767396)
		(end 256.216404 -347.336618)
		(width 0.14732)
		(layer "In11.Cu")
		(net "UPI_CPU1_CPU0_P2P2_DP<21>")
	)
	(segment
		(start 106.768646 -284.35808)
		(end 106.767884 -284.358588)
		(width 0.0889)
		(layer "In11.Cu")
		(net "UPI_CPU1_CPU0_P2P2_DP<21>")
	)
	(segment
		(start 257.487674 -341.701628)
		(end 257.179826 -341.39378)
		(width 0.14732)
		(layer "In11.Cu")
		(net "UPI_CPU1_CPU0_P2P2_DP<21>")
	)
	(segment
		(start 107.198414 -290.299394)
		(end 107.058206 -290.299394)
		(width 0.0889)
		(layer "In11.Cu")
		(net "UPI_CPU1_CPU0_P2P2_DP<21>")
	)
	(segment
		(start 106.765852 -285.335218)
		(end 106.768646 -285.336996)
		(width 0.0889)
		(layer "In11.Cu")
		(net "UPI_CPU1_CPU0_P2P2_DP<21>")
	)
	(segment
		(start 298.937426 -323.379338)
		(end 300.427898 -322.761864)
		(width 0.14732)
		(layer "In11.Cu")
		(net "UPI_CPU1_CPU0_P2P2_DP<21>")
	)
	(segment
		(start 311.216294 -311.97042)
		(end 314.550044 -311.283858)
		(width 0.14732)
		(layer "In11.Cu")
		(net "UPI_CPU1_CPU0_P2P2_DP<21>")
	)
	(segment
		(start 106.540808 -290.957)
		(end 106.415332 -291.082476)
		(width 0.0889)
		(layer "In11.Cu")
		(net "UPI_CPU1_CPU0_P2P2_DP<21>")
	)
	(segment
		(start 106.932476 -290.565332)
		(end 106.807 -290.690808)
		(width 0.0889)
		(layer "In11.Cu")
		(net "UPI_CPU1_CPU0_P2P2_DP<21>")
	)
	(segment
		(start 106.955844 -285.652718)
		(end 106.955844 -285.679896)
		(width 0.0889)
		(layer "In11.Cu")
		(net "UPI_CPU1_CPU0_P2P2_DP<21>")
	)
	(segment
		(start 267.2461 -331.346048)
		(end 267.2461 -330.529184)
		(width 0.14732)
		(layer "In11.Cu")
		(net "UPI_CPU1_CPU0_P2P2_DP<21>")
	)
	(segment
		(start 73.938638 -335.207864)
		(end 73.938638 -352.713544)
		(width 0.14732)
		(layer "In11.Cu")
		(net "UPI_CPU1_CPU0_P2P2_DP<21>")
	)
	(segment
		(start 105.60177 -291.896038)
		(end 105.60177 -292.378638)
		(width 0.0889)
		(layer "In11.Cu")
		(net "UPI_CPU1_CPU0_P2P2_DP<21>")
	)
	(segment
		(start 106.540808 -290.816538)
		(end 106.540808 -290.957)
		(width 0.0889)
		(layer "In11.Cu")
		(net "UPI_CPU1_CPU0_P2P2_DP<21>")
	)
	(segment
		(start 106.764836 -285.33471)
		(end 106.765852 -285.335218)
		(width 0.0889)
		(layer "In11.Cu")
		(net "UPI_CPU1_CPU0_P2P2_DP<21>")
	)
	(segment
		(start 262.526272 -331.849984)
		(end 262.72236 -331.653896)
		(width 0.14732)
		(layer "In11.Cu")
		(net "UPI_CPU1_CPU0_P2P2_DP<21>")
	)
	(segment
		(start 301.686468 -318.904366)
		(end 301.96917 -317.099188)
		(width 0.14732)
		(layer "In11.Cu")
		(net "UPI_CPU1_CPU0_P2P2_DP<21>")
	)
	(segment
		(start 75.719686 -325.977504)
		(end 75.029314 -327.437242)
		(width 0.14732)
		(layer "In11.Cu")
		(net "UPI_CPU1_CPU0_P2P2_DP<21>")
	)
	(segment
		(start 336.477864 -285.985712)
		(end 336.468974 -285.980632)
		(width 0.0889)
		(layer "In11.Cu")
		(net "UPI_CPU1_CPU0_P2P2_DP<21>")
	)
	(segment
		(start 257.179826 -341.39378)
		(end 256.363724 -341.39378)
		(width 0.14732)
		(layer "In11.Cu")
		(net "UPI_CPU1_CPU0_P2P2_DP<21>")
	)
	(segment
		(start 258.654042 -337.311238)
		(end 256.267712 -334.924908)
		(width 0.14732)
		(layer "In11.Cu")
		(net "UPI_CPU1_CPU0_P2P2_DP<21>")
	)
	(segment
		(start 77.305154 -360.831892)
		(end 79.377794 -362.904278)
		(width 0.14732)
		(layer "In11.Cu")
		(net "UPI_CPU1_CPU0_P2P2_DP<21>")
	)
	(segment
		(start 267.2461 -330.529184)
		(end 266.938252 -330.221336)
		(width 0.14732)
		(layer "In11.Cu")
		(net "UPI_CPU1_CPU0_P2P2_DP<21>")
	)
	(segment
		(start 271.738598 -325.847964)
		(end 272.046446 -325.540116)
		(width 0.14732)
		(layer "In11.Cu")
		(net "UPI_CPU1_CPU0_P2P2_DP<21>")
	)
	(arc
		(start 336.760312 -284.832044)
		(mid 336.680942 -284.55831)
		(end 336.478118 -284.35808)
		(width 0.0889)
		(layer "In11.Cu")
		(net "UPI_CPU1_CPU0_P2P2_DP<21>")
	)
	(arc
		(start 107.425744 -288.110676)
		(mid 107.503373 -288.389089)
		(end 107.708446 -288.592768)
		(width 0.0889)
		(layer "In11.Cu")
		(net "UPI_CPU1_CPU0_P2P2_DP<21>")
	)
	(arc
		(start 335.255362 -288.66846)
		(mid 335.401554 -288.649165)
		(end 335.53781 -288.592768)
		(width 0.0889)
		(layer "In11.Cu")
		(net "UPI_CPU1_CPU0_P2P2_DP<21>")
	)
	(arc
		(start 335.999074 -283.539184)
		(mid 335.86816 -283.402824)
		(end 335.820512 -283.219906)
		(width 0.0889)
		(layer "In11.Cu")
		(net "UPI_CPU1_CPU0_P2P2_DP<21>")
	)
	(arc
		(start 107.247436 -282.900628)
		(mid 107.426154 -283.219906)
		(end 107.247436 -283.539184)
		(width 0.0889)
		(layer "In11.Cu")
		(net "UPI_CPU1_CPU0_P2P2_DP<21>")
	)
	(arc
		(start 106.955844 -285.679896)
		(mid 107.036006 -285.952085)
		(end 107.238292 -286.151066)
		(width 0.0889)
		(layer "In11.Cu")
		(net "UPI_CPU1_CPU0_P2P2_DP<21>")
	)
	(arc
		(start 107.894628 -288.955226)
		(mid 107.877214 -289.065533)
		(end 107.816396 -289.159188)
		(width 0.0889)
		(layer "In11.Cu")
		(net "UPI_CPU1_CPU0_P2P2_DP<21>")
	)
	(arc
		(start 106.445812 -282.05684)
		(mid 106.609908 -282.032493)
		(end 106.768392 -282.081478)
		(width 0.0889)
		(layer "In11.Cu")
		(net "UPI_CPU1_CPU0_P2P2_DP<21>")
	)
	(arc
		(start 336.290666 -284.033722)
		(mid 336.218431 -283.757198)
		(end 336.020156 -283.551376)
		(width 0.0889)
		(layer "In11.Cu")
		(net "UPI_CPU1_CPU0_P2P2_DP<21>")
	)
	(arc
		(start 336.290412 -287.28924)
		(mid 336.338091 -287.10634)
		(end 336.468974 -286.969962)
		(width 0.0889)
		(layer "In11.Cu")
		(net "UPI_CPU1_CPU0_P2P2_DP<21>")
	)
	(arc
		(start 107.247182 -286.156146)
		(mid 107.425779 -286.475424)
		(end 107.247182 -286.794702)
		(width 0.0889)
		(layer "In11.Cu")
		(net "UPI_CPU1_CPU0_P2P2_DP<21>")
	)
	(arc
		(start 336.290666 -285.673546)
		(mid 336.290421 -285.66415)
		(end 336.290412 -285.65475)
		(width 0.0889)
		(layer "In11.Cu")
		(net "UPI_CPU1_CPU0_P2P2_DP<21>")
	)
	(arc
		(start 106.955844 -284.042358)
		(mid 106.903574 -284.224723)
		(end 106.768646 -284.35808)
		(width 0.0889)
		(layer "In11.Cu")
		(net "UPI_CPU1_CPU0_P2P2_DP<21>")
	)
	(arc
		(start 335.820512 -283.219906)
		(mid 335.857372 -283.058109)
		(end 335.960466 -282.92806)
		(width 0.0889)
		(layer "In11.Cu")
		(net "UPI_CPU1_CPU0_P2P2_DP<21>")
	)
	(arc
		(start 106.76255 -284.361636)
		(mid 106.485976 -284.847538)
		(end 106.76255 -285.33344)
		(width 0.0889)
		(layer "In11.Cu")
		(net "UPI_CPU1_CPU0_P2P2_DP<21>")
	)
	(arc
		(start 336.007964 -287.778698)
		(mid 336.212299 -287.576093)
		(end 336.290412 -287.299146)
		(width 0.0889)
		(layer "In11.Cu")
		(net "UPI_CPU1_CPU0_P2P2_DP<21>")
	)
	(arc
		(start 336.760566 -286.467804)
		(mid 336.682937 -286.189391)
		(end 336.477864 -285.985712)
		(width 0.0889)
		(layer "In11.Cu")
		(net "UPI_CPU1_CPU0_P2P2_DP<21>")
	)
	(arc
		(start 336.468974 -285.980632)
		(mid 336.341081 -285.84957)
		(end 336.290666 -285.673546)
		(width 0.0889)
		(layer "In11.Cu")
		(net "UPI_CPU1_CPU0_P2P2_DP<21>")
	)
	(arc
		(start 107.23245 -283.54782)
		(mid 107.029863 -283.754171)
		(end 106.955844 -284.033722)
		(width 0.0889)
		(layer "In11.Cu")
		(net "UPI_CPU1_CPU0_P2P2_DP<21>")
	)
	(arc
		(start 336.469228 -284.353)
		(mid 336.338314 -284.21664)
		(end 336.290666 -284.033722)
		(width 0.0889)
		(layer "In11.Cu")
		(net "UPI_CPU1_CPU0_P2P2_DP<21>")
	)
	(arc
		(start 106.768646 -285.336996)
		(mid 106.903579 -285.47035)
		(end 106.955844 -285.652718)
		(width 0.0889)
		(layer "In11.Cu")
		(net "UPI_CPU1_CPU0_P2P2_DP<21>")
	)
	(arc
		(start 335.53781 -288.592768)
		(mid 335.741291 -288.391964)
		(end 335.820512 -288.11728)
		(width 0.0889)
		(layer "In11.Cu")
		(net "UPI_CPU1_CPU0_P2P2_DP<21>")
	)
	(arc
		(start 107.720892 -288.59988)
		(mid 107.858304 -288.752842)
		(end 107.894628 -288.955226)
		(width 0.0889)
		(layer "In11.Cu")
		(net "UPI_CPU1_CPU0_P2P2_DP<21>")
	)
	(arc
		(start 336.477864 -285.336996)
		(mid 336.682199 -285.134391)
		(end 336.760312 -284.857444)
		(width 0.0889)
		(layer "In11.Cu")
		(net "UPI_CPU1_CPU0_P2P2_DP<21>")
	)
	(arc
		(start 336.290412 -285.65475)
		(mid 336.339665 -285.47555)
		(end 336.468974 -285.342076)
		(width 0.0889)
		(layer "In11.Cu")
		(net "UPI_CPU1_CPU0_P2P2_DP<21>")
	)
	(arc
		(start 107.238292 -286.799782)
		(mid 106.95576 -287.28924)
		(end 107.238292 -287.778698)
		(width 0.0889)
		(layer "In11.Cu")
		(net "UPI_CPU1_CPU0_P2P2_DP<21>")
	)
	(arc
		(start 106.777282 -282.086558)
		(mid 106.908196 -282.222918)
		(end 106.955844 -282.405836)
		(width 0.0889)
		(layer "In11.Cu")
		(net "UPI_CPU1_CPU0_P2P2_DP<21>")
	)
	(arc
		(start 107.247182 -287.783778)
		(mid 107.378096 -287.920138)
		(end 107.425744 -288.103056)
		(width 0.0889)
		(layer "In11.Cu")
		(net "UPI_CPU1_CPU0_P2P2_DP<21>")
	)
	(arc
		(start 106.955844 -282.42006)
		(mid 107.035063 -282.694745)
		(end 107.238546 -282.895548)
		(width 0.0889)
		(layer "In11.Cu")
		(net "UPI_CPU1_CPU0_P2P2_DP<21>")
	)
	(arc
		(start 335.820512 -288.103056)
		(mid 335.868191 -287.920156)
		(end 335.999074 -287.783778)
		(width 0.0889)
		(layer "In11.Cu")
		(net "UPI_CPU1_CPU0_P2P2_DP<21>")
	)
	(arc
		(start 336.490056 -286.95777)
		(mid 336.688284 -286.751922)
		(end 336.760566 -286.475424)
		(width 0.0889)
		(layer "In11.Cu")
		(net "UPI_CPU1_CPU0_P2P2_DP<21>")
	)
	(segment
		(start 104.701848 -280.77795)
		(end 104.701594 -280.778204)
		(width 0.13208)
		(layer "F.Cu")
		(net "UPI_CPU1_CPU0_P2P2_DP<20>")
	)
	(segment
		(start 104.701848 -280.242264)
		(end 104.701848 -280.77795)
		(width 0.13208)
		(layer "F.Cu")
		(net "UPI_CPU1_CPU0_P2P2_DP<20>")
	)
	(segment
		(start 338.074762 -279.428194)
		(end 338.074762 -279.964134)
		(width 0.13208)
		(layer "F.Cu")
		(net "UPI_CPU1_CPU0_P2P2_DP<20>")
	)
	(segment
		(start 336.938874 -287.783778)
		(end 336.947764 -287.778698)
		(width 0.0889)
		(layer "In11.Cu")
		(net "UPI_CPU1_CPU0_P2P2_DP<20>")
	)
	(segment
		(start 105.546144 -284.837632)
		(end 105.546144 -284.847538)
		(width 0.0889)
		(layer "In11.Cu")
		(net "UPI_CPU1_CPU0_P2P2_DP<20>")
	)
	(segment
		(start 262.730234 -339.13064)
		(end 262.730234 -338.694776)
		(width 0.14732)
		(layer "In11.Cu")
		(net "UPI_CPU1_CPU0_P2P2_DP<20>")
	)
	(segment
		(start 270.36395 -331.496924)
		(end 271.663922 -330.196952)
		(width 0.14732)
		(layer "In11.Cu")
		(net "UPI_CPU1_CPU0_P2P2_DP<20>")
	)
	(segment
		(start 260.95579 -343.649808)
		(end 261.534148 -343.07145)
		(width 0.14732)
		(layer "In11.Cu")
		(net "UPI_CPU1_CPU0_P2P2_DP<20>")
	)
	(segment
		(start 275.368766 -330.196952)
		(end 277.961598 -327.60412)
		(width 0.14732)
		(layer "In11.Cu")
		(net "UPI_CPU1_CPU0_P2P2_DP<20>")
	)
	(segment
		(start 267.680948 -334.388206)
		(end 268.731492 -335.43875)
		(width 0.14732)
		(layer "In11.Cu")
		(net "UPI_CPU1_CPU0_P2P2_DP<20>")
	)
	(segment
		(start 262.159242 -342.011)
		(end 262.594598 -342.011)
		(width 0.14732)
		(layer "In11.Cu")
		(net "UPI_CPU1_CPU0_P2P2_DP<20>")
	)
	(segment
		(start 306.17033 -315.90488)
		(end 307.05425 -315.419232)
		(width 0.14732)
		(layer "In11.Cu")
		(net "UPI_CPU1_CPU0_P2P2_DP<20>")
	)
	(segment
		(start 337.700112 -284.857444)
		(end 337.700112 -284.837632)
		(width 0.0889)
		(layer "In11.Cu")
		(net "UPI_CPU1_CPU0_P2P2_DP<20>")
	)
	(segment
		(start 260.907784 -336.664554)
		(end 261.325614 -336.246724)
		(width 0.14732)
		(layer "In11.Cu")
		(net "UPI_CPU1_CPU0_P2P2_DP<20>")
	)
	(segment
		(start 106.307382 -283.539184)
		(end 106.298492 -283.544264)
		(width 0.0889)
		(layer "In11.Cu")
		(net "UPI_CPU1_CPU0_P2P2_DP<20>")
	)
	(segment
		(start 311.824116 -313.971178)
		(end 312.340498 -313.75731)
		(width 0.14732)
		(layer "In11.Cu")
		(net "UPI_CPU1_CPU0_P2P2_DP<20>")
	)
	(segment
		(start 75.028044 -325.493634)
		(end 74.254614 -327.127616)
		(width 0.14732)
		(layer "In11.Cu")
		(net "UPI_CPU1_CPU0_P2P2_DP<20>")
	)
	(segment
		(start 104.606598 -290.581334)
		(end 104.507538 -290.680394)
		(width 0.0889)
		(layer "In11.Cu")
		(net "UPI_CPU1_CPU0_P2P2_DP<20>")
	)
	(segment
		(start 105.35285 -281.264106)
		(end 105.358184 -281.267154)
		(width 0.0889)
		(layer "In11.Cu")
		(net "UPI_CPU1_CPU0_P2P2_DP<20>")
	)
	(segment
		(start 337.762088 -279.964134)
		(end 338.074762 -279.964134)
		(width 0.0889)
		(layer "In11.Cu")
		(net "UPI_CPU1_CPU0_P2P2_DP<20>")
	)
	(segment
		(start 263.172956 -341.432642)
		(end 263.172956 -340.997286)
		(width 0.14732)
		(layer "In11.Cu")
		(net "UPI_CPU1_CPU0_P2P2_DP<20>")
	)
	(segment
		(start 337.230466 -284.042358)
		(end 337.230466 -284.033722)
		(width 0.0889)
		(layer "In11.Cu")
		(net "UPI_CPU1_CPU0_P2P2_DP<20>")
	)
	(segment
		(start 262.122412 -339.946742)
		(end 262.122412 -339.738462)
		(width 0.14732)
		(layer "In11.Cu")
		(net "UPI_CPU1_CPU0_P2P2_DP<20>")
	)
	(segment
		(start 303.832514 -317.856616)
		(end 303.898554 -317.728346)
		(width 0.14732)
		(layer "In11.Cu")
		(net "UPI_CPU1_CPU0_P2P2_DP<20>")
	)
	(segment
		(start 269.302484 -332.55839)
		(end 269.302484 -332.122526)
		(width 0.14732)
		(layer "In11.Cu")
		(net "UPI_CPU1_CPU0_P2P2_DP<20>")
	)
	(segment
		(start 310.123078 -314.676028)
		(end 311.824116 -313.971178)
		(width 0.14732)
		(layer "In11.Cu")
		(net "UPI_CPU1_CPU0_P2P2_DP<20>")
	)
	(segment
		(start 312.340498 -313.75731)
		(end 313.325764 -312.772044)
		(width 0.14732)
		(layer "In11.Cu")
		(net "UPI_CPU1_CPU0_P2P2_DP<20>")
	)
	(segment
		(start 303.898554 -317.728092)
		(end 303.964594 -317.599822)
		(width 0.14732)
		(layer "In11.Cu")
		(net "UPI_CPU1_CPU0_P2P2_DP<20>")
	)
	(segment
		(start 105.358946 -281.267662)
		(end 105.364534 -281.270964)
		(width 0.0889)
		(layer "In11.Cu")
		(net "UPI_CPU1_CPU0_P2P2_DP<20>")
	)
	(segment
		(start 336.760312 -283.219906)
		(end 336.760312 -283.197808)
		(width 0.0889)
		(layer "In11.Cu")
		(net "UPI_CPU1_CPU0_P2P2_DP<20>")
	)
	(segment
		(start 73.700894 -329.131422)
		(end 73.102978 -335.200752)
		(width 0.14732)
		(layer "In11.Cu")
		(net "UPI_CPU1_CPU0_P2P2_DP<20>")
	)
	(segment
		(start 264.116058 -332.481936)
		(end 264.32383 -332.481936)
		(width 0.14732)
		(layer "In11.Cu")
		(net "UPI_CPU1_CPU0_P2P2_DP<20>")
	)
	(segment
		(start 260.520434 -343.649808)
		(end 260.95579 -343.649808)
		(width 0.14732)
		(layer "In11.Cu")
		(net "UPI_CPU1_CPU0_P2P2_DP<20>")
	)
	(segment
		(start 317.173102 -312.453528)
		(end 329.863958 -299.762672)
		(width 0.14732)
		(layer "In11.Cu")
		(net "UPI_CPU1_CPU0_P2P2_DP<20>")
	)
	(segment
		(start 257.166364 -344.69451)
		(end 259.26161 -342.599264)
		(width 0.14732)
		(layer "In11.Cu")
		(net "UPI_CPU1_CPU0_P2P2_DP<20>")
	)
	(segment
		(start 336.939128 -281.272742)
		(end 336.947002 -281.26817)
		(width 0.0889)
		(layer "In11.Cu")
		(net "UPI_CPU1_CPU0_P2P2_DP<20>")
	)
	(segment
		(start 104.73182 -292.761416)
		(end 104.73182 -297.236134)
		(width 0.14732)
		(layer "In11.Cu")
		(net "UPI_CPU1_CPU0_P2P2_DP<20>")
	)
	(segment
		(start 104.136698 -288.898584)
		(end 104.136952 -288.898076)
		(width 0.0889)
		(layer "In11.Cu")
		(net "UPI_CPU1_CPU0_P2P2_DP<20>")
	)
	(segment
		(start 260.907784 -336.872326)
		(end 260.907784 -336.664554)
		(width 0.14732)
		(layer "In11.Cu")
		(net "UPI_CPU1_CPU0_P2P2_DP<20>")
	)
	(segment
		(start 269.928086 -331.496924)
		(end 270.36395 -331.496924)
		(width 0.14732)
		(layer "In11.Cu")
		(net "UPI_CPU1_CPU0_P2P2_DP<20>")
	)
	(segment
		(start 269.745206 -334.860392)
		(end 269.745206 -334.425036)
		(width 0.14732)
		(layer "In11.Cu")
		(net "UPI_CPU1_CPU0_P2P2_DP<20>")
	)
	(segment
		(start 105.837482 -284.353)
		(end 105.829354 -284.357572)
		(width 0.0889)
		(layer "In11.Cu")
		(net "UPI_CPU1_CPU0_P2P2_DP<20>")
	)
	(segment
		(start 259.26161 -342.599264)
		(end 259.46989 -342.599264)
		(width 0.14732)
		(layer "In11.Cu")
		(net "UPI_CPU1_CPU0_P2P2_DP<20>")
	)
	(segment
		(start 268.62278 -330.398882)
		(end 268.830044 -330.398882)
		(width 0.14732)
		(layer "In11.Cu")
		(net "UPI_CPU1_CPU0_P2P2_DP<20>")
	)
	(segment
		(start 337.700366 -286.475424)
		(end 337.700366 -286.4612)
		(width 0.0889)
		(layer "In11.Cu")
		(net "UPI_CPU1_CPU0_P2P2_DP<20>")
	)
	(segment
		(start 337.408774 -286.970216)
		(end 337.42376 -286.961326)
		(width 0.0889)
		(layer "In11.Cu")
		(net "UPI_CPU1_CPU0_P2P2_DP<20>")
	)
	(segment
		(start 104.136952 -288.898076)
		(end 104.136952 -289.113976)
		(width 0.0889)
		(layer "In11.Cu")
		(net "UPI_CPU1_CPU0_P2P2_DP<20>")
	)
	(segment
		(start 262.546592 -335.025746)
		(end 262.964422 -334.607916)
		(width 0.14732)
		(layer "In11.Cu")
		(net "UPI_CPU1_CPU0_P2P2_DP<20>")
	)
	(segment
		(start 335.489296 -290.163758)
		(end 335.489296 -290.103814)
		(width 0.0889)
		(layer "In11.Cu")
		(net "UPI_CPU1_CPU0_P2P2_DP<20>")
	)
	(segment
		(start 105.366566 -281.27198)
		(end 105.367836 -281.272742)
		(width 0.0889)
		(layer "In11.Cu")
		(net "UPI_CPU1_CPU0_P2P2_DP<20>")
	)
	(segment
		(start 104.606344 -289.751516)
		(end 104.606598 -289.751262)
		(width 0.0889)
		(layer "In11.Cu")
		(net "UPI_CPU1_CPU0_P2P2_DP<20>")
	)
	(segment
		(start 271.663922 -330.196952)
		(end 275.368766 -330.196952)
		(width 0.14732)
		(layer "In11.Cu")
		(net "UPI_CPU1_CPU0_P2P2_DP<20>")
	)
	(segment
		(start 104.507538 -290.858194)
		(end 104.606598 -290.957254)
		(width 0.0889)
		(layer "In11.Cu")
		(net "UPI_CPU1_CPU0_P2P2_DP<20>")
	)
	(segment
		(start 329.863958 -299.762672)
		(end 331.821028 -293.311326)
		(width 0.14732)
		(layer "In11.Cu")
		(net "UPI_CPU1_CPU0_P2P2_DP<20>")
	)
	(segment
		(start 263.172194 -334.607916)
		(end 264.994644 -336.430366)
		(width 0.14732)
		(layer "In11.Cu")
		(net "UPI_CPU1_CPU0_P2P2_DP<20>")
	)
	(segment
		(start 104.606598 -290.027614)
		(end 104.507538 -290.126674)
		(width 0.0889)
		(layer "In11.Cu")
		(net "UPI_CPU1_CPU0_P2P2_DP<20>")
	)
	(segment
		(start 337.408774 -285.342076)
		(end 337.417664 -285.336996)
		(width 0.0889)
		(layer "In11.Cu")
		(net "UPI_CPU1_CPU0_P2P2_DP<20>")
	)
	(segment
		(start 264.32383 -332.481936)
		(end 266.633452 -334.791558)
		(width 0.14732)
		(layer "In11.Cu")
		(net "UPI_CPU1_CPU0_P2P2_DP<20>")
	)
	(segment
		(start 104.606598 -290.957254)
		(end 104.606598 -291.432488)
		(width 0.0889)
		(layer "In11.Cu")
		(net "UPI_CPU1_CPU0_P2P2_DP<20>")
	)
	(segment
		(start 337.408774 -280.458926)
		(end 337.417664 -280.453846)
		(width 0.0889)
		(layer "In11.Cu")
		(net "UPI_CPU1_CPU0_P2P2_DP<20>")
	)
	(segment
		(start 104.507538 -290.304474)
		(end 104.606598 -290.403534)
		(width 0.0889)
		(layer "In11.Cu")
		(net "UPI_CPU1_CPU0_P2P2_DP<20>")
	)
	(segment
		(start 104.428036 -288.422334)
		(end 104.419146 -288.427414)
		(width 0.0889)
		(layer "In11.Cu")
		(net "UPI_CPU1_CPU0_P2P2_DP<20>")
	)
	(segment
		(start 268.20495 -330.816712)
		(end 268.62278 -330.398882)
		(width 0.14732)
		(layer "In11.Cu")
		(net "UPI_CPU1_CPU0_P2P2_DP<20>")
	)
	(segment
		(start 336.478118 -282.081478)
		(end 336.484214 -282.077922)
		(width 0.0889)
		(layer "In11.Cu")
		(net "UPI_CPU1_CPU0_P2P2_DP<20>")
	)
	(segment
		(start 284.002988 -325.037704)
		(end 284.832298 -324.208394)
		(width 0.14732)
		(layer "In11.Cu")
		(net "UPI_CPU1_CPU0_P2P2_DP<20>")
	)
	(segment
		(start 262.730234 -338.694776)
		(end 260.907784 -336.872326)
		(width 0.14732)
		(layer "In11.Cu")
		(net "UPI_CPU1_CPU0_P2P2_DP<20>")
	)
	(segment
		(start 336.478118 -282.730194)
		(end 336.469228 -282.725114)
		(width 0.0889)
		(layer "In11.Cu")
		(net "UPI_CPU1_CPU0_P2P2_DP<20>")
	)
	(segment
		(start 336.469228 -282.086558)
		(end 336.478118 -282.081478)
		(width 0.0889)
		(layer "In11.Cu")
		(net "UPI_CPU1_CPU0_P2P2_DP<20>")
	)
	(segment
		(start 261.534148 -342.636094)
		(end 260.483604 -341.58555)
		(width 0.14732)
		(layer "In11.Cu")
		(net "UPI_CPU1_CPU0_P2P2_DP<20>")
	)
	(segment
		(start 263.698228 -332.899766)
		(end 264.116058 -332.481936)
		(width 0.14732)
		(layer "In11.Cu")
		(net "UPI_CPU1_CPU0_P2P2_DP<20>")
	)
	(segment
		(start 336.95386 -283.54782)
		(end 336.954114 -283.548074)
		(width 0.0889)
		(layer "In11.Cu")
		(net "UPI_CPU1_CPU0_P2P2_DP<20>")
	)
	(segment
		(start 105.076244 -285.661354)
		(end 105.076244 -285.668974)
		(width 0.0889)
		(layer "In11.Cu")
		(net "UPI_CPU1_CPU0_P2P2_DP<20>")
	)
	(segment
		(start 337.408774 -286.969962)
		(end 337.408774 -286.970216)
		(width 0.0889)
		(layer "In11.Cu")
		(net "UPI_CPU1_CPU0_P2P2_DP<20>")
	)
	(segment
		(start 263.172956 -340.997286)
		(end 262.122412 -339.946742)
		(width 0.14732)
		(layer "In11.Cu")
		(net "UPI_CPU1_CPU0_P2P2_DP<20>")
	)
	(segment
		(start 336.760312 -288.11728)
		(end 336.760312 -288.103056)
		(width 0.0889)
		(layer "In11.Cu")
		(net "UPI_CPU1_CPU0_P2P2_DP<20>")
	)
	(segment
		(start 106.016044 -282.405836)
		(end 106.016044 -282.424378)
		(width 0.0889)
		(layer "In11.Cu")
		(net "UPI_CPU1_CPU0_P2P2_DP<20>")
	)
	(segment
		(start 269.745206 -334.425036)
		(end 268.694662 -333.374492)
		(width 0.14732)
		(layer "In11.Cu")
		(net "UPI_CPU1_CPU0_P2P2_DP<20>")
	)
	(segment
		(start 303.898554 -317.728346)
		(end 303.898554 -317.728092)
		(width 0.14732)
		(layer "In11.Cu")
		(net "UPI_CPU1_CPU0_P2P2_DP<20>")
	)
	(segment
		(start 284.832298 -324.208394)
		(end 299.151548 -324.208394)
		(width 0.14732)
		(layer "In11.Cu")
		(net "UPI_CPU1_CPU0_P2P2_DP<20>")
	)
	(segment
		(start 269.302484 -332.122526)
		(end 268.20495 -331.024992)
		(width 0.14732)
		(layer "In11.Cu")
		(net "UPI_CPU1_CPU0_P2P2_DP<20>")
	)
	(segment
		(start 105.076498 -287.279334)
		(end 105.076498 -287.28924)
		(width 0.0889)
		(layer "In11.Cu")
		(net "UPI_CPU1_CPU0_P2P2_DP<20>")
	)
	(segment
		(start 262.964422 -334.607916)
		(end 263.172194 -334.607916)
		(width 0.14732)
		(layer "In11.Cu")
		(net "UPI_CPU1_CPU0_P2P2_DP<20>")
	)
	(segment
		(start 336.954114 -283.548074)
		(end 336.947764 -283.544264)
		(width 0.0889)
		(layer "In11.Cu")
		(net "UPI_CPU1_CPU0_P2P2_DP<20>")
	)
	(segment
		(start 333.831946 -291.08781)
		(end 335.084674 -290.56838)
		(width 0.14732)
		(layer "In11.Cu")
		(net "UPI_CPU1_CPU0_P2P2_DP<20>")
	)
	(segment
		(start 261.325614 -336.246724)
		(end 261.533386 -336.246724)
		(width 0.14732)
		(layer "In11.Cu")
		(net "UPI_CPU1_CPU0_P2P2_DP<20>")
	)
	(segment
		(start 199.930258 -369.12296)
		(end 212.312504 -371.306344)
		(width 0.14732)
		(layer "In11.Cu")
		(net "UPI_CPU1_CPU0_P2P2_DP<20>")
	)
	(segment
		(start 104.701594 -280.778204)
		(end 104.858058 -280.507186)
		(width 0.0889)
		(layer "In11.Cu")
		(net "UPI_CPU1_CPU0_P2P2_DP<20>")
	)
	(segment
		(start 105.829354 -284.357572)
		(end 105.828592 -284.35808)
		(width 0.0889)
		(layer "In11.Cu")
		(net "UPI_CPU1_CPU0_P2P2_DP<20>")
	)
	(segment
		(start 104.507538 -290.126674)
		(end 104.507538 -290.304474)
		(width 0.0889)
		(layer "In11.Cu")
		(net "UPI_CPU1_CPU0_P2P2_DP<20>")
	)
	(segment
		(start 98.657918 -304.721006)
		(end 82.72272 -317.798704)
		(width 0.14732)
		(layer "In11.Cu")
		(net "UPI_CPU1_CPU0_P2P2_DP<20>")
	)
	(segment
		(start 336.94624 -283.543502)
		(end 336.938874 -283.539184)
		(width 0.0889)
		(layer "In11.Cu")
		(net "UPI_CPU1_CPU0_P2P2_DP<20>")
	)
	(segment
		(start 105.358184 -281.267154)
		(end 105.358946 -281.267662)
		(width 0.0889)
		(layer "In11.Cu")
		(net "UPI_CPU1_CPU0_P2P2_DP<20>")
	)
	(segment
		(start 307.05425 -315.419232)
		(end 307.7972 -314.676028)
		(width 0.14732)
		(layer "In11.Cu")
		(net "UPI_CPU1_CPU0_P2P2_DP<20>")
	)
	(segment
		(start 261.533386 -336.246724)
		(end 263.355836 -338.069174)
		(width 0.14732)
		(layer "In11.Cu")
		(net "UPI_CPU1_CPU0_P2P2_DP<20>")
	)
	(segment
		(start 73.102978 -335.200752)
		(end 73.102978 -352.87712)
		(width 0.14732)
		(layer "In11.Cu")
		(net "UPI_CPU1_CPU0_P2P2_DP<20>")
	)
	(segment
		(start 126.251716 -376.01271)
		(end 160.852358 -376.01271)
		(width 0.14732)
		(layer "In11.Cu")
		(net "UPI_CPU1_CPU0_P2P2_DP<20>")
	)
	(segment
		(start 302.636936 -321.776852)
		(end 303.6951 -319.02781)
		(width 0.14732)
		(layer "In11.Cu")
		(net "UPI_CPU1_CPU0_P2P2_DP<20>")
	)
	(segment
		(start 105.358692 -285.171896)
		(end 105.352596 -285.175452)
		(width 0.0889)
		(layer "In11.Cu")
		(net "UPI_CPU1_CPU0_P2P2_DP<20>")
	)
	(segment
		(start 263.7917 -338.069174)
		(end 264.369042 -337.491832)
		(width 0.14732)
		(layer "In11.Cu")
		(net "UPI_CPU1_CPU0_P2P2_DP<20>")
	)
	(segment
		(start 262.122412 -339.738462)
		(end 262.730234 -339.13064)
		(width 0.14732)
		(layer "In11.Cu")
		(net "UPI_CPU1_CPU0_P2P2_DP<20>")
	)
	(segment
		(start 337.230212 -280.793698)
		(end 337.230212 -280.778204)
		(width 0.0889)
		(layer "In11.Cu")
		(net "UPI_CPU1_CPU0_P2P2_DP<20>")
	)
	(segment
		(start 99.11842 -371.986302)
		(end 126.251716 -376.01271)
		(width 0.14732)
		(layer "In11.Cu")
		(net "UPI_CPU1_CPU0_P2P2_DP<20>")
	)
	(segment
		(start 104.564688 -291.496496)
		(end 104.564688 -292.594284)
		(width 0.14732)
		(layer "In11.Cu")
		(net "UPI_CPU1_CPU0_P2P2_DP<20>")
	)
	(segment
		(start 263.355836 -338.069174)
		(end 263.7917 -338.069174)
		(width 0.14732)
		(layer "In11.Cu")
		(net "UPI_CPU1_CPU0_P2P2_DP<20>")
	)
	(segment
		(start 336.46872 -288.597848)
		(end 336.47761 -288.592768)
		(width 0.0889)
		(layer "In11.Cu")
		(net "UPI_CPU1_CPU0_P2P2_DP<20>")
	)
	(segment
		(start 278.48179 -325.037704)
		(end 284.002988 -325.037704)
		(width 0.14732)
		(layer "In11.Cu")
		(net "UPI_CPU1_CPU0_P2P2_DP<20>")
	)
	(segment
		(start 105.546144 -286.466788)
		(end 105.546144 -286.48406)
		(width 0.0889)
		(layer "In11.Cu")
		(net "UPI_CPU1_CPU0_P2P2_DP<20>")
	)
	(segment
		(start 104.606598 -290.403534)
		(end 104.606598 -290.581334)
		(width 0.0889)
		(layer "In11.Cu")
		(net "UPI_CPU1_CPU0_P2P2_DP<20>")
	)
	(segment
		(start 105.364534 -281.270964)
		(end 105.366566 -281.27198)
		(width 0.0889)
		(layer "In11.Cu")
		(net "UPI_CPU1_CPU0_P2P2_DP<20>")
	)
	(segment
		(start 266.633452 -334.791558)
		(end 267.069316 -334.791558)
		(width 0.14732)
		(layer "In11.Cu")
		(net "UPI_CPU1_CPU0_P2P2_DP<20>")
	)
	(segment
		(start 78.9178 -363.619034)
		(end 99.11842 -371.986302)
		(width 0.14732)
		(layer "In11.Cu")
		(net "UPI_CPU1_CPU0_P2P2_DP<20>")
	)
	(segment
		(start 253.493778 -351.298256)
		(end 257.166364 -347.625416)
		(width 0.14732)
		(layer "In11.Cu")
		(net "UPI_CPU1_CPU0_P2P2_DP<20>")
	)
	(segment
		(start 337.417664 -285.985712)
		(end 337.408774 -285.980632)
		(width 0.0889)
		(layer "In11.Cu")
		(net "UPI_CPU1_CPU0_P2P2_DP<20>")
	)
	(segment
		(start 104.564688 -291.474398)
		(end 104.564688 -291.496496)
		(width 0.0889)
		(layer "In11.Cu")
		(net "UPI_CPU1_CPU0_P2P2_DP<20>")
	)
	(segment
		(start 264.994644 -336.430366)
		(end 265.430508 -336.430366)
		(width 0.14732)
		(layer "In11.Cu")
		(net "UPI_CPU1_CPU0_P2P2_DP<20>")
	)
	(segment
		(start 265.430508 -336.430366)
		(end 266.00785 -335.853024)
		(width 0.14732)
		(layer "In11.Cu")
		(net "UPI_CPU1_CPU0_P2P2_DP<20>")
	)
	(segment
		(start 268.694662 -333.166212)
		(end 269.302484 -332.55839)
		(width 0.14732)
		(layer "In11.Cu")
		(net "UPI_CPU1_CPU0_P2P2_DP<20>")
	)
	(segment
		(start 105.828592 -282.081478)
		(end 105.837482 -282.086558)
		(width 0.0889)
		(layer "In11.Cu")
		(net "UPI_CPU1_CPU0_P2P2_DP<20>")
	)
	(segment
		(start 299.151548 -324.208394)
		(end 300.951392 -323.462142)
		(width 0.14732)
		(layer "In11.Cu")
		(net "UPI_CPU1_CPU0_P2P2_DP<20>")
	)
	(segment
		(start 264.369042 -337.491832)
		(end 264.369042 -337.055968)
		(width 0.14732)
		(layer "In11.Cu")
		(net "UPI_CPU1_CPU0_P2P2_DP<20>")
	)
	(segment
		(start 261.534148 -343.07145)
		(end 261.534148 -342.636094)
		(width 0.14732)
		(layer "In11.Cu")
		(net "UPI_CPU1_CPU0_P2P2_DP<20>")
	)
	(segment
		(start 332.248764 -292.670992)
		(end 333.831946 -291.08781)
		(width 0.14732)
		(layer "In11.Cu")
		(net "UPI_CPU1_CPU0_P2P2_DP<20>")
	)
	(segment
		(start 73.102978 -352.87712)
		(end 76.593192 -361.294934)
		(width 0.14732)
		(layer "In11.Cu")
		(net "UPI_CPU1_CPU0_P2P2_DP<20>")
	)
	(segment
		(start 336.290158 -289.302952)
		(end 336.290158 -288.917126)
		(width 0.0889)
		(layer "In11.Cu")
		(net "UPI_CPU1_CPU0_P2P2_DP<20>")
	)
	(segment
		(start 336.947002 -281.26817)
		(end 336.948018 -281.267662)
		(width 0.0889)
		(layer "In11.Cu")
		(net "UPI_CPU1_CPU0_P2P2_DP<20>")
	)
	(segment
		(start 106.298492 -282.895548)
		(end 106.307382 -282.900628)
		(width 0.0889)
		(layer "In11.Cu")
		(net "UPI_CPU1_CPU0_P2P2_DP<20>")
	)
	(segment
		(start 268.830044 -330.398882)
		(end 269.928086 -331.496924)
		(width 0.14732)
		(layer "In11.Cu")
		(net "UPI_CPU1_CPU0_P2P2_DP<20>")
	)
	(segment
		(start 104.564688 -292.594284)
		(end 104.73182 -292.761416)
		(width 0.14732)
		(layer "In11.Cu")
		(net "UPI_CPU1_CPU0_P2P2_DP<20>")
	)
	(segment
		(start 106.298492 -283.544264)
		(end 106.292396 -283.54782)
		(width 0.0889)
		(layer "In11.Cu")
		(net "UPI_CPU1_CPU0_P2P2_DP<20>")
	)
	(segment
		(start 300.951392 -323.462142)
		(end 302.636936 -321.776852)
		(width 0.14732)
		(layer "In11.Cu")
		(net "UPI_CPU1_CPU0_P2P2_DP<20>")
	)
	(segment
		(start 160.852358 -376.01271)
		(end 199.930258 -369.12296)
		(width 0.14732)
		(layer "In11.Cu")
		(net "UPI_CPU1_CPU0_P2P2_DP<20>")
	)
	(segment
		(start 262.594598 -342.011)
		(end 263.172956 -341.432642)
		(width 0.14732)
		(layer "In11.Cu")
		(net "UPI_CPU1_CPU0_P2P2_DP<20>")
	)
	(segment
		(start 307.7972 -314.676028)
		(end 310.123078 -314.676028)
		(width 0.14732)
		(layer "In11.Cu")
		(net "UPI_CPU1_CPU0_P2P2_DP<20>")
	)
	(segment
		(start 76.593192 -361.294934)
		(end 78.9178 -363.619034)
		(width 0.14732)
		(layer "In11.Cu")
		(net "UPI_CPU1_CPU0_P2P2_DP<20>")
	)
	(segment
		(start 267.069316 -334.791558)
		(end 267.472668 -334.388206)
		(width 0.14732)
		(layer "In11.Cu")
		(net "UPI_CPU1_CPU0_P2P2_DP<20>")
	)
	(segment
		(start 331.821028 -293.311326)
		(end 332.248764 -292.670992)
		(width 0.14732)
		(layer "In11.Cu")
		(net "UPI_CPU1_CPU0_P2P2_DP<20>")
	)
	(segment
		(start 336.947764 -283.544264)
		(end 336.94624 -283.543502)
		(width 0.0889)
		(layer "In11.Cu")
		(net "UPI_CPU1_CPU0_P2P2_DP<20>")
	)
	(segment
		(start 337.230212 -287.299146)
		(end 337.230212 -287.28924)
		(width 0.0889)
		(layer "In11.Cu")
		(net "UPI_CPU1_CPU0_P2P2_DP<20>")
	)
	(segment
		(start 105.546398 -281.59202)
		(end 105.546398 -281.607514)
		(width 0.0889)
		(layer "In11.Cu")
		(net "UPI_CPU1_CPU0_P2P2_DP<20>")
	)
	(segment
		(start 104.606598 -291.432488)
		(end 104.564688 -291.474398)
		(width 0.0889)
		(layer "In11.Cu")
		(net "UPI_CPU1_CPU0_P2P2_DP<20>")
	)
	(segment
		(start 260.483604 -341.37727)
		(end 260.900418 -340.960456)
		(width 0.14732)
		(layer "In11.Cu")
		(net "UPI_CPU1_CPU0_P2P2_DP<20>")
	)
	(segment
		(start 260.900418 -340.960456)
		(end 261.108698 -340.960456)
		(width 0.14732)
		(layer "In11.Cu")
		(net "UPI_CPU1_CPU0_P2P2_DP<20>")
	)
	(segment
		(start 268.694662 -333.374492)
		(end 268.694662 -333.166212)
		(width 0.14732)
		(layer "In11.Cu")
		(net "UPI_CPU1_CPU0_P2P2_DP<20>")
	)
	(segment
		(start 303.6951 -319.02781)
		(end 303.832514 -317.856616)
		(width 0.14732)
		(layer "In11.Cu")
		(net "UPI_CPU1_CPU0_P2P2_DP<20>")
	)
	(segment
		(start 277.961598 -327.60412)
		(end 277.961598 -325.557896)
		(width 0.14732)
		(layer "In11.Cu")
		(net "UPI_CPU1_CPU0_P2P2_DP<20>")
	)
	(segment
		(start 277.961598 -325.557896)
		(end 278.48179 -325.037704)
		(width 0.14732)
		(layer "In11.Cu")
		(net "UPI_CPU1_CPU0_P2P2_DP<20>")
	)
	(segment
		(start 259.46989 -342.599264)
		(end 260.520434 -343.649808)
		(width 0.14732)
		(layer "In11.Cu")
		(net "UPI_CPU1_CPU0_P2P2_DP<20>")
	)
	(segment
		(start 261.108698 -340.960456)
		(end 262.159242 -342.011)
		(width 0.14732)
		(layer "In11.Cu")
		(net "UPI_CPU1_CPU0_P2P2_DP<20>")
	)
	(segment
		(start 82.72272 -317.798704)
		(end 75.028044 -325.493634)
		(width 0.14732)
		(layer "In11.Cu")
		(net "UPI_CPU1_CPU0_P2P2_DP<20>")
	)
	(segment
		(start 74.254614 -327.127616)
		(end 73.700894 -329.131422)
		(width 0.14732)
		(layer "In11.Cu")
		(net "UPI_CPU1_CPU0_P2P2_DP<20>")
	)
	(segment
		(start 335.473802 -290.179252)
		(end 335.489296 -290.163758)
		(width 0.0889)
		(layer "In11.Cu")
		(net "UPI_CPU1_CPU0_P2P2_DP<20>")
	)
	(segment
		(start 104.507538 -290.680394)
		(end 104.507538 -290.858194)
		(width 0.0889)
		(layer "In11.Cu")
		(net "UPI_CPU1_CPU0_P2P2_DP<20>")
	)
	(segment
		(start 263.698228 -333.107538)
		(end 263.698228 -332.899766)
		(width 0.14732)
		(layer "In11.Cu")
		(net "UPI_CPU1_CPU0_P2P2_DP<20>")
	)
	(segment
		(start 268.731492 -335.43875)
		(end 269.166848 -335.43875)
		(width 0.14732)
		(layer "In11.Cu")
		(net "UPI_CPU1_CPU0_P2P2_DP<20>")
	)
	(segment
		(start 266.00785 -335.853024)
		(end 266.00785 -335.41716)
		(width 0.14732)
		(layer "In11.Cu")
		(net "UPI_CPU1_CPU0_P2P2_DP<20>")
	)
	(segment
		(start 104.606598 -289.751262)
		(end 104.606598 -290.027614)
		(width 0.0889)
		(layer "In11.Cu")
		(net "UPI_CPU1_CPU0_P2P2_DP<20>")
	)
	(segment
		(start 303.964594 -317.599822)
		(end 304.57013 -317.048642)
		(width 0.14732)
		(layer "In11.Cu")
		(net "UPI_CPU1_CPU0_P2P2_DP<20>")
	)
	(segment
		(start 257.166364 -347.625416)
		(end 257.166364 -344.69451)
		(width 0.14732)
		(layer "In11.Cu")
		(net "UPI_CPU1_CPU0_P2P2_DP<20>")
	)
	(segment
		(start 267.472668 -334.388206)
		(end 267.680948 -334.388206)
		(width 0.14732)
		(layer "In11.Cu")
		(net "UPI_CPU1_CPU0_P2P2_DP<20>")
	)
	(segment
		(start 337.69681 -280.029412)
		(end 337.762088 -279.964134)
		(width 0.0889)
		(layer "In11.Cu")
		(net "UPI_CPU1_CPU0_P2P2_DP<20>")
	)
	(segment
		(start 314.094622 -312.453528)
		(end 317.173102 -312.453528)
		(width 0.14732)
		(layer "In11.Cu")
		(net "UPI_CPU1_CPU0_P2P2_DP<20>")
	)
	(segment
		(start 266.00785 -335.41716)
		(end 263.698228 -333.107538)
		(width 0.14732)
		(layer "In11.Cu")
		(net "UPI_CPU1_CPU0_P2P2_DP<20>")
	)
	(segment
		(start 262.546592 -335.233518)
		(end 262.546592 -335.025746)
		(width 0.14732)
		(layer "In11.Cu")
		(net "UPI_CPU1_CPU0_P2P2_DP<20>")
	)
	(segment
		(start 212.312504 -371.306344)
		(end 229.166928 -368.335052)
		(width 0.14732)
		(layer "In11.Cu")
		(net "UPI_CPU1_CPU0_P2P2_DP<20>")
	)
	(segment
		(start 264.369042 -337.055968)
		(end 262.546592 -335.233518)
		(width 0.14732)
		(layer "In11.Cu")
		(net "UPI_CPU1_CPU0_P2P2_DP<20>")
	)
	(segment
		(start 103.064818 -299.48378)
		(end 98.657918 -304.721006)
		(width 0.14732)
		(layer "In11.Cu")
		(net "UPI_CPU1_CPU0_P2P2_DP<20>")
	)
	(segment
		(start 313.325764 -312.772044)
		(end 314.094622 -312.453528)
		(width 0.14732)
		(layer "In11.Cu")
		(net "UPI_CPU1_CPU0_P2P2_DP<20>")
	)
	(segment
		(start 269.166848 -335.43875)
		(end 269.745206 -334.860392)
		(width 0.14732)
		(layer "In11.Cu")
		(net "UPI_CPU1_CPU0_P2P2_DP<20>")
	)
	(segment
		(start 104.73182 -297.236134)
		(end 103.064818 -299.48378)
		(width 0.14732)
		(layer "In11.Cu")
		(net "UPI_CPU1_CPU0_P2P2_DP<20>")
	)
	(segment
		(start 104.606598 -288.09315)
		(end 104.606598 -288.103056)
		(width 0.0889)
		(layer "In11.Cu")
		(net "UPI_CPU1_CPU0_P2P2_DP<20>")
	)
	(segment
		(start 268.20495 -331.024992)
		(end 268.20495 -330.816712)
		(width 0.14732)
		(layer "In11.Cu")
		(net "UPI_CPU1_CPU0_P2P2_DP<20>")
	)
	(segment
		(start 335.084674 -290.56838)
		(end 335.473802 -290.179252)
		(width 0.14732)
		(layer "In11.Cu")
		(net "UPI_CPU1_CPU0_P2P2_DP<20>")
	)
	(segment
		(start 260.483604 -341.58555)
		(end 260.483604 -341.37727)
		(width 0.14732)
		(layer "In11.Cu")
		(net "UPI_CPU1_CPU0_P2P2_DP<20>")
	)
	(segment
		(start 104.858058 -280.507186)
		(end 104.93629 -280.486358)
		(width 0.0889)
		(layer "In11.Cu")
		(net "UPI_CPU1_CPU0_P2P2_DP<20>")
	)
	(segment
		(start 304.57013 -317.048642)
		(end 306.17033 -315.90488)
		(width 0.14732)
		(layer "In11.Cu")
		(net "UPI_CPU1_CPU0_P2P2_DP<20>")
	)
	(segment
		(start 105.367582 -285.166816)
		(end 105.358692 -285.171896)
		(width 0.0889)
		(layer "In11.Cu")
		(net "UPI_CPU1_CPU0_P2P2_DP<20>")
	)
	(segment
		(start 229.166928 -368.335052)
		(end 253.493778 -351.298256)
		(width 0.14732)
		(layer "In11.Cu")
		(net "UPI_CPU1_CPU0_P2P2_DP<20>")
	)
	(segment
		(start 104.897936 -287.608518)
		(end 104.889046 -287.613598)
		(width 0.0889)
		(layer "In11.Cu")
		(net "UPI_CPU1_CPU0_P2P2_DP<20>")
	)
	(segment
		(start 335.489296 -290.103814)
		(end 336.290158 -289.302952)
		(width 0.0889)
		(layer "In11.Cu")
		(net "UPI_CPU1_CPU0_P2P2_DP<20>")
	)
	(arc
		(start 105.076244 -285.668974)
		(mid 105.153873 -285.947387)
		(end 105.358946 -286.151066)
		(width 0.0889)
		(layer "In11.Cu")
		(net "UPI_CPU1_CPU0_P2P2_DP<20>")
	)
	(arc
		(start 336.760566 -281.59202)
		(mid 336.808245 -281.40912)
		(end 336.939128 -281.272742)
		(width 0.0889)
		(layer "In11.Cu")
		(net "UPI_CPU1_CPU0_P2P2_DP<20>")
	)
	(arc
		(start 105.358946 -286.799782)
		(mid 105.154611 -287.002387)
		(end 105.076498 -287.279334)
		(width 0.0889)
		(layer "In11.Cu")
		(net "UPI_CPU1_CPU0_P2P2_DP<20>")
	)
	(arc
		(start 105.546144 -284.847538)
		(mid 105.498465 -285.030438)
		(end 105.367582 -285.166816)
		(width 0.0889)
		(layer "In11.Cu")
		(net "UPI_CPU1_CPU0_P2P2_DP<20>")
	)
	(arc
		(start 104.419146 -288.427414)
		(mid 104.21686 -288.626395)
		(end 104.136698 -288.898584)
		(width 0.0889)
		(layer "In11.Cu")
		(net "UPI_CPU1_CPU0_P2P2_DP<20>")
	)
	(arc
		(start 337.230466 -284.033722)
		(mid 337.156475 -283.754156)
		(end 336.95386 -283.54782)
		(width 0.0889)
		(layer "In11.Cu")
		(net "UPI_CPU1_CPU0_P2P2_DP<20>")
	)
	(arc
		(start 105.546144 -286.48406)
		(mid 105.493874 -286.666425)
		(end 105.358946 -286.799782)
		(width 0.0889)
		(layer "In11.Cu")
		(net "UPI_CPU1_CPU0_P2P2_DP<20>")
	)
	(arc
		(start 337.417664 -284.35808)
		(mid 337.282731 -284.224726)
		(end 337.230466 -284.042358)
		(width 0.0889)
		(layer "In11.Cu")
		(net "UPI_CPU1_CPU0_P2P2_DP<20>")
	)
	(arc
		(start 337.417664 -280.453846)
		(mid 337.601578 -280.283801)
		(end 337.694016 -280.051002)
		(width 0.0889)
		(layer "In11.Cu")
		(net "UPI_CPU1_CPU0_P2P2_DP<20>")
	)
	(arc
		(start 105.07599 -280.763726)
		(mid 105.076185 -280.770964)
		(end 105.076244 -280.778204)
		(width 0.0889)
		(layer "In11.Cu")
		(net "UPI_CPU1_CPU0_P2P2_DP<20>")
	)
	(arc
		(start 337.230212 -285.65475)
		(mid 337.279465 -285.47555)
		(end 337.408774 -285.342076)
		(width 0.0889)
		(layer "In11.Cu")
		(net "UPI_CPU1_CPU0_P2P2_DP<20>")
	)
	(arc
		(start 106.307382 -282.900628)
		(mid 106.485979 -283.219906)
		(end 106.307382 -283.539184)
		(width 0.0889)
		(layer "In11.Cu")
		(net "UPI_CPU1_CPU0_P2P2_DP<20>")
	)
	(arc
		(start 104.889046 -287.613598)
		(mid 104.684711 -287.816203)
		(end 104.606598 -288.09315)
		(width 0.0889)
		(layer "In11.Cu")
		(net "UPI_CPU1_CPU0_P2P2_DP<20>")
	)
	(arc
		(start 337.700112 -284.837632)
		(mid 337.622001 -284.560683)
		(end 337.417664 -284.35808)
		(width 0.0889)
		(layer "In11.Cu")
		(net "UPI_CPU1_CPU0_P2P2_DP<20>")
	)
	(arc
		(start 337.694016 -280.051002)
		(mid 337.695516 -280.04022)
		(end 337.69681 -280.029412)
		(width 0.0889)
		(layer "In11.Cu")
		(net "UPI_CPU1_CPU0_P2P2_DP<20>")
	)
	(arc
		(start 105.546398 -281.607514)
		(mid 105.625768 -281.881248)
		(end 105.828592 -282.081478)
		(width 0.0889)
		(layer "In11.Cu")
		(net "UPI_CPU1_CPU0_P2P2_DP<20>")
	)
	(arc
		(start 337.408774 -285.980632)
		(mid 337.28018 -285.848358)
		(end 337.230212 -285.670752)
		(width 0.0889)
		(layer "In11.Cu")
		(net "UPI_CPU1_CPU0_P2P2_DP<20>")
	)
	(arc
		(start 337.700366 -286.4612)
		(mid 337.621147 -286.186515)
		(end 337.417664 -285.985712)
		(width 0.0889)
		(layer "In11.Cu")
		(net "UPI_CPU1_CPU0_P2P2_DP<20>")
	)
	(arc
		(start 336.938874 -283.539184)
		(mid 336.80796 -283.402824)
		(end 336.760312 -283.219906)
		(width 0.0889)
		(layer "In11.Cu")
		(net "UPI_CPU1_CPU0_P2P2_DP<20>")
	)
	(arc
		(start 104.606598 -288.103056)
		(mid 104.558919 -288.285956)
		(end 104.428036 -288.422334)
		(width 0.0889)
		(layer "In11.Cu")
		(net "UPI_CPU1_CPU0_P2P2_DP<20>")
	)
	(arc
		(start 337.417664 -285.336996)
		(mid 337.621999 -285.134391)
		(end 337.700112 -284.857444)
		(width 0.0889)
		(layer "In11.Cu")
		(net "UPI_CPU1_CPU0_P2P2_DP<20>")
	)
	(arc
		(start 104.136952 -289.113976)
		(mid 104.24808 -289.307135)
		(end 104.422194 -289.446208)
		(width 0.0889)
		(layer "In11.Cu")
		(net "UPI_CPU1_CPU0_P2P2_DP<20>")
	)
	(arc
		(start 336.760312 -288.103056)
		(mid 336.807991 -287.920156)
		(end 336.938874 -287.783778)
		(width 0.0889)
		(layer "In11.Cu")
		(net "UPI_CPU1_CPU0_P2P2_DP<20>")
	)
	(arc
		(start 337.230212 -285.670752)
		(mid 337.230129 -285.662751)
		(end 337.230212 -285.65475)
		(width 0.0889)
		(layer "In11.Cu")
		(net "UPI_CPU1_CPU0_P2P2_DP<20>")
	)
	(arc
		(start 336.947764 -287.778698)
		(mid 337.152099 -287.576093)
		(end 337.230212 -287.299146)
		(width 0.0889)
		(layer "In11.Cu")
		(net "UPI_CPU1_CPU0_P2P2_DP<20>")
	)
	(arc
		(start 337.42376 -286.961326)
		(mid 337.626347 -286.754975)
		(end 337.700366 -286.475424)
		(width 0.0889)
		(layer "In11.Cu")
		(net "UPI_CPU1_CPU0_P2P2_DP<20>")
	)
	(arc
		(start 336.290158 -288.917126)
		(mid 336.337837 -288.734226)
		(end 336.46872 -288.597848)
		(width 0.0889)
		(layer "In11.Cu")
		(net "UPI_CPU1_CPU0_P2P2_DP<20>")
	)
	(arc
		(start 105.352596 -285.175452)
		(mid 105.150183 -285.381865)
		(end 105.076244 -285.661354)
		(width 0.0889)
		(layer "In11.Cu")
		(net "UPI_CPU1_CPU0_P2P2_DP<20>")
	)
	(arc
		(start 105.367836 -281.272742)
		(mid 105.49875 -281.409102)
		(end 105.546398 -281.59202)
		(width 0.0889)
		(layer "In11.Cu")
		(net "UPI_CPU1_CPU0_P2P2_DP<20>")
	)
	(arc
		(start 336.469228 -282.725114)
		(mid 336.29051 -282.405836)
		(end 336.469228 -282.086558)
		(width 0.0889)
		(layer "In11.Cu")
		(net "UPI_CPU1_CPU0_P2P2_DP<20>")
	)
	(arc
		(start 336.948018 -281.267662)
		(mid 337.150841 -281.067431)
		(end 337.230212 -280.793698)
		(width 0.0889)
		(layer "In11.Cu")
		(net "UPI_CPU1_CPU0_P2P2_DP<20>")
	)
	(arc
		(start 104.93629 -280.486358)
		(mid 105.036239 -280.609884)
		(end 105.07599 -280.763726)
		(width 0.0889)
		(layer "In11.Cu")
		(net "UPI_CPU1_CPU0_P2P2_DP<20>")
	)
	(arc
		(start 106.292396 -283.54782)
		(mid 106.089983 -283.754233)
		(end 106.016044 -284.033722)
		(width 0.0889)
		(layer "In11.Cu")
		(net "UPI_CPU1_CPU0_P2P2_DP<20>")
	)
	(arc
		(start 336.484214 -282.077922)
		(mid 336.686627 -281.871509)
		(end 336.760566 -281.59202)
		(width 0.0889)
		(layer "In11.Cu")
		(net "UPI_CPU1_CPU0_P2P2_DP<20>")
	)
	(arc
		(start 336.760312 -283.197808)
		(mid 336.679401 -282.92768)
		(end 336.478118 -282.730194)
		(width 0.0889)
		(layer "In11.Cu")
		(net "UPI_CPU1_CPU0_P2P2_DP<20>")
	)
	(arc
		(start 105.828592 -284.35808)
		(mid 105.624257 -284.560685)
		(end 105.546144 -284.837632)
		(width 0.0889)
		(layer "In11.Cu")
		(net "UPI_CPU1_CPU0_P2P2_DP<20>")
	)
	(arc
		(start 337.230212 -280.778204)
		(mid 337.277891 -280.595304)
		(end 337.408774 -280.458926)
		(width 0.0889)
		(layer "In11.Cu")
		(net "UPI_CPU1_CPU0_P2P2_DP<20>")
	)
	(arc
		(start 105.076498 -287.28924)
		(mid 105.028819 -287.47214)
		(end 104.897936 -287.608518)
		(width 0.0889)
		(layer "In11.Cu")
		(net "UPI_CPU1_CPU0_P2P2_DP<20>")
	)
	(arc
		(start 106.016044 -282.424378)
		(mid 106.096206 -282.696567)
		(end 106.298492 -282.895548)
		(width 0.0889)
		(layer "In11.Cu")
		(net "UPI_CPU1_CPU0_P2P2_DP<20>")
	)
	(arc
		(start 106.016044 -284.033722)
		(mid 105.968365 -284.216622)
		(end 105.837482 -284.353)
		(width 0.0889)
		(layer "In11.Cu")
		(net "UPI_CPU1_CPU0_P2P2_DP<20>")
	)
	(arc
		(start 337.230212 -287.28924)
		(mid 337.277891 -287.10634)
		(end 337.408774 -286.969962)
		(width 0.0889)
		(layer "In11.Cu")
		(net "UPI_CPU1_CPU0_P2P2_DP<20>")
	)
	(arc
		(start 336.47761 -288.592768)
		(mid 336.681091 -288.391964)
		(end 336.760312 -288.11728)
		(width 0.0889)
		(layer "In11.Cu")
		(net "UPI_CPU1_CPU0_P2P2_DP<20>")
	)
	(arc
		(start 105.358946 -286.151066)
		(mid 105.493879 -286.28442)
		(end 105.546144 -286.466788)
		(width 0.0889)
		(layer "In11.Cu")
		(net "UPI_CPU1_CPU0_P2P2_DP<20>")
	)
	(arc
		(start 104.422194 -289.446208)
		(mid 104.556644 -289.573308)
		(end 104.606344 -289.751516)
		(width 0.0889)
		(layer "In11.Cu")
		(net "UPI_CPU1_CPU0_P2P2_DP<20>")
	)
	(arc
		(start 105.837482 -282.086558)
		(mid 105.968396 -282.222918)
		(end 106.016044 -282.405836)
		(width 0.0889)
		(layer "In11.Cu")
		(net "UPI_CPU1_CPU0_P2P2_DP<20>")
	)
	(arc
		(start 105.076244 -280.778204)
		(mid 105.150235 -281.05777)
		(end 105.35285 -281.264106)
		(width 0.0889)
		(layer "In11.Cu")
		(net "UPI_CPU1_CPU0_P2P2_DP<20>")
	)
	(segment
		(start 356.401116 -275.8948)
		(end 356.401116 -275.35886)
		(width 0.13208)
		(layer "F.Cu")
		(net "UPI_CPU1_CPU0_P2P2_DP<1>")
	)
	(segment
		(start 87.315294 -284.311598)
		(end 87.315294 -284.847538)
		(width 0.13208)
		(layer "F.Cu")
		(net "UPI_CPU1_CPU0_P2P2_DP<1>")
	)
	(segment
		(start 52.700174 -323.677788)
		(end 52.205128 -323.882766)
		(width 0.14732)
		(layer "In11.Cu")
		(net "UPI_CPU1_CPU0_P2P2_DP<1>")
	)
	(segment
		(start 87.15883 -284.57652)
		(end 87.080598 -284.555692)
		(width 0.0889)
		(layer "In11.Cu")
		(net "UPI_CPU1_CPU0_P2P2_DP<1>")
	)
	(segment
		(start 84.559394 -290.395406)
		(end 84.5566 -290.45408)
		(width 0.0889)
		(layer "In11.Cu")
		(net "UPI_CPU1_CPU0_P2P2_DP<1>")
	)
	(segment
		(start 84.93379 -290.03117)
		(end 84.660994 -290.303966)
		(width 0.0889)
		(layer "In11.Cu")
		(net "UPI_CPU1_CPU0_P2P2_DP<1>")
	)
	(segment
		(start 355.387148 -298.46016)
		(end 355.73716 -298.107608)
		(width 0.14732)
		(layer "In11.Cu")
		(net "UPI_CPU1_CPU0_P2P2_DP<1>")
	)
	(segment
		(start 355.366066 -289.630866)
		(end 354.896166 -289.160966)
		(width 0.0889)
		(layer "In11.Cu")
		(net "UPI_CPU1_CPU0_P2P2_DP<1>")
	)
	(segment
		(start 342.917272 -309.825898)
		(end 344.932254 -308.991508)
		(width 0.14732)
		(layer "In11.Cu")
		(net "UPI_CPU1_CPU0_P2P2_DP<1>")
	)
	(segment
		(start 278.57196 -370.115084)
		(end 278.57196 -349.550482)
		(width 0.14732)
		(layer "In11.Cu")
		(net "UPI_CPU1_CPU0_P2P2_DP<1>")
	)
	(segment
		(start 73.389998 -378.575824)
		(end 73.456038 -378.735336)
		(width 0.14732)
		(layer "In11.Cu")
		(net "UPI_CPU1_CPU0_P2P2_DP<1>")
	)
	(segment
		(start 356.019862 -293.002208)
		(end 355.653594 -292.118034)
		(width 0.14732)
		(layer "In11.Cu")
		(net "UPI_CPU1_CPU0_P2P2_DP<1>")
	)
	(segment
		(start 87.080598 -284.555692)
		(end 87.080852 -284.555184)
		(width 0.0889)
		(layer "In11.Cu")
		(net "UPI_CPU1_CPU0_P2P2_DP<1>")
	)
	(segment
		(start 77.747114 -299.387006)
		(end 77.43825 -299.69587)
		(width 0.14732)
		(layer "In11.Cu")
		(net "UPI_CPU1_CPU0_P2P2_DP<1>")
	)
	(segment
		(start 84.660994 -290.303966)
		(end 84.559394 -290.395406)
		(width 0.0889)
		(layer "In11.Cu")
		(net "UPI_CPU1_CPU0_P2P2_DP<1>")
	)
	(segment
		(start 357.998522 -283.543756)
		(end 358.001062 -283.542232)
		(width 0.0889)
		(layer "In11.Cu")
		(net "UPI_CPU1_CPU0_P2P2_DP<1>")
	)
	(segment
		(start 355.51745 -291.98189)
		(end 355.51745 -291.921946)
		(width 0.0889)
		(layer "In11.Cu")
		(net "UPI_CPU1_CPU0_P2P2_DP<1>")
	)
	(segment
		(start 79.398114 -297.736006)
		(end 79.022448 -298.111672)
		(width 0.14732)
		(layer "In11.Cu")
		(net "UPI_CPU1_CPU0_P2P2_DP<1>")
	)
	(segment
		(start 358.47655 -280.458926)
		(end 358.468676 -280.454354)
		(width 0.0889)
		(layer "In11.Cu")
		(net "UPI_CPU1_CPU0_P2P2_DP<1>")
	)
	(segment
		(start 51.78298 -325.614538)
		(end 51.6382 -325.759318)
		(width 0.14732)
		(layer "In11.Cu")
		(net "UPI_CPU1_CPU0_P2P2_DP<1>")
	)
	(segment
		(start 92.96527 -386.815076)
		(end 127.023114 -391.86739)
		(width 0.14732)
		(layer "In11.Cu")
		(net "UPI_CPU1_CPU0_P2P2_DP<1>")
	)
	(segment
		(start 77.129132 -300.177454)
		(end 76.956666 -300.177454)
		(width 0.14732)
		(layer "In11.Cu")
		(net "UPI_CPU1_CPU0_P2P2_DP<1>")
	)
	(segment
		(start 358.093264 -275.570442)
		(end 358.08285 -275.576538)
		(width 0.0889)
		(layer "In11.Cu")
		(net "UPI_CPU1_CPU0_P2P2_DP<1>")
	)
	(segment
		(start 55.8419 -333.686404)
		(end 55.842154 -333.686658)
		(width 0.14732)
		(layer "In11.Cu")
		(net "UPI_CPU1_CPU0_P2P2_DP<1>")
	)
	(segment
		(start 78.228698 -298.905422)
		(end 78.228698 -299.077888)
		(width 0.14732)
		(layer "In11.Cu")
		(net "UPI_CPU1_CPU0_P2P2_DP<1>")
	)
	(segment
		(start 354.094542 -299.762164)
		(end 354.09378 -299.55744)
		(width 0.14732)
		(layer "In11.Cu")
		(net "UPI_CPU1_CPU0_P2P2_DP<1>")
	)
	(segment
		(start 51.78298 -328.405998)
		(end 51.78298 -328.774298)
		(width 0.14732)
		(layer "In11.Cu")
		(net "UPI_CPU1_CPU0_P2P2_DP<1>")
	)
	(segment
		(start 355.366066 -291.039042)
		(end 355.267006 -290.939982)
		(width 0.0889)
		(layer "In11.Cu")
		(net "UPI_CPU1_CPU0_P2P2_DP<1>")
	)
	(segment
		(start 55.955946 -315.894466)
		(end 54.212744 -316.616588)
		(width 0.14732)
		(layer "In11.Cu")
		(net "UPI_CPU1_CPU0_P2P2_DP<1>")
	)
	(segment
		(start 85.171534 -286.20974)
		(end 85.171026 -286.209994)
		(width 0.0889)
		(layer "In11.Cu")
		(net "UPI_CPU1_CPU0_P2P2_DP<1>")
	)
	(segment
		(start 340.901782 -310.66105)
		(end 342.917272 -309.826152)
		(width 0.14732)
		(layer "In11.Cu")
		(net "UPI_CPU1_CPU0_P2P2_DP<1>")
	)
	(segment
		(start 356.244652 -275.623782)
		(end 356.401116 -275.8948)
		(width 0.0889)
		(layer "In11.Cu")
		(net "UPI_CPU1_CPU0_P2P2_DP<1>")
	)
	(segment
		(start 355.366066 -291.770562)
		(end 355.366066 -291.592762)
		(width 0.0889)
		(layer "In11.Cu")
		(net "UPI_CPU1_CPU0_P2P2_DP<1>")
	)
	(segment
		(start 56.829198 -334.846422)
		(end 57.542938 -336.567526)
		(width 0.14732)
		(layer "In11.Cu")
		(net "UPI_CPU1_CPU0_P2P2_DP<1>")
	)
	(segment
		(start 51.6382 -328.919078)
		(end 51.6382 -329.314048)
		(width 0.14732)
		(layer "In11.Cu")
		(net "UPI_CPU1_CPU0_P2P2_DP<1>")
	)
	(segment
		(start 70.845172 -377.654058)
		(end 72.826626 -378.474732)
		(width 0.14732)
		(layer "In11.Cu")
		(net "UPI_CPU1_CPU0_P2P2_DP<1>")
	)
	(segment
		(start 357.05796 -285.171896)
		(end 357.06685 -285.166816)
		(width 0.0889)
		(layer "In11.Cu")
		(net "UPI_CPU1_CPU0_P2P2_DP<1>")
	)
	(segment
		(start 51.78298 -325.246238)
		(end 51.78298 -325.614538)
		(width 0.14732)
		(layer "In11.Cu")
		(net "UPI_CPU1_CPU0_P2P2_DP<1>")
	)
	(segment
		(start 356.106222 -286.806894)
		(end 356.118414 -286.799782)
		(width 0.0889)
		(layer "In11.Cu")
		(net "UPI_CPU1_CPU0_P2P2_DP<1>")
	)
	(segment
		(start 161.799524 -391.86739)
		(end 265.584178 -383.102866)
		(width 0.14732)
		(layer "In11.Cu")
		(net "UPI_CPU1_CPU0_P2P2_DP<1>")
	)
	(segment
		(start 78.228698 -299.077888)
		(end 77.91958 -299.387006)
		(width 0.14732)
		(layer "In11.Cu")
		(net "UPI_CPU1_CPU0_P2P2_DP<1>")
	)
	(segment
		(start 51.78298 -328.774298)
		(end 51.6382 -328.919078)
		(width 0.14732)
		(layer "In11.Cu")
		(net "UPI_CPU1_CPU0_P2P2_DP<1>")
	)
	(segment
		(start 359.407714 -277.84679)
		(end 359.416604 -277.84171)
		(width 0.0889)
		(layer "In11.Cu")
		(net "UPI_CPU1_CPU0_P2P2_DP<1>")
	)
	(segment
		(start 358.937814 -276.384258)
		(end 358.925622 -276.377146)
		(width 0.0889)
		(layer "In11.Cu")
		(net "UPI_CPU1_CPU0_P2P2_DP<1>")
	)
	(segment
		(start 53.917596 -321.639438)
		(end 53.713888 -322.664328)
		(width 0.14732)
		(layer "In11.Cu")
		(net "UPI_CPU1_CPU0_P2P2_DP<1>")
	)
	(segment
		(start 53.917596 -317.0809)
		(end 53.917596 -321.639438)
		(width 0.14732)
		(layer "In11.Cu")
		(net "UPI_CPU1_CPU0_P2P2_DP<1>")
	)
	(segment
		(start 80.950054 -296.184066)
		(end 79.879698 -297.254422)
		(width 0.14732)
		(layer "In11.Cu")
		(net "UPI_CPU1_CPU0_P2P2_DP<1>")
	)
	(segment
		(start 78.540864 -298.593256)
		(end 78.228698 -298.905422)
		(width 0.14732)
		(layer "In11.Cu")
		(net "UPI_CPU1_CPU0_P2P2_DP<1>")
	)
	(segment
		(start 278.57196 -349.550482)
		(end 285.598108 -342.524334)
		(width 0.14732)
		(layer "In11.Cu")
		(net "UPI_CPU1_CPU0_P2P2_DP<1>")
	)
	(segment
		(start 357.245412 -284.847538)
		(end 357.245412 -284.837632)
		(width 0.0889)
		(layer "In11.Cu")
		(net "UPI_CPU1_CPU0_P2P2_DP<1>")
	)
	(segment
		(start 51.6382 -325.759318)
		(end 51.6382 -328.261218)
		(width 0.14732)
		(layer "In11.Cu")
		(net "UPI_CPU1_CPU0_P2P2_DP<1>")
	)
	(segment
		(start 354.558346 -299.295058)
		(end 354.923344 -298.92752)
		(width 0.14732)
		(layer "In11.Cu")
		(net "UPI_CPU1_CPU0_P2P2_DP<1>")
	)
	(segment
		(start 85.53069 -285.65348)
		(end 85.53069 -285.661608)
		(width 0.0889)
		(layer "In11.Cu")
		(net "UPI_CPU1_CPU0_P2P2_DP<1>")
	)
	(segment
		(start 76.166218 -300.967902)
		(end 67.911726 -309.222394)
		(width 0.14732)
		(layer "In11.Cu")
		(net "UPI_CPU1_CPU0_P2P2_DP<1>")
	)
	(segment
		(start 355.875082 -296.274998)
		(end 355.875082 -295.906698)
		(width 0.14732)
		(layer "In11.Cu")
		(net "UPI_CPU1_CPU0_P2P2_DP<1>")
	)
	(segment
		(start 356.019862 -293.680388)
		(end 356.019862 -293.002208)
		(width 0.14732)
		(layer "In11.Cu")
		(net "UPI_CPU1_CPU0_P2P2_DP<1>")
	)
	(segment
		(start 358.46766 -282.730194)
		(end 358.47655 -282.725114)
		(width 0.0889)
		(layer "In11.Cu")
		(net "UPI_CPU1_CPU0_P2P2_DP<1>")
	)
	(segment
		(start 79.022448 -298.284138)
		(end 78.71333 -298.593256)
		(width 0.14732)
		(layer "In11.Cu")
		(net "UPI_CPU1_CPU0_P2P2_DP<1>")
	)
	(segment
		(start 355.532944 -291.997384)
		(end 355.51745 -291.98189)
		(width 0.0889)
		(layer "In11.Cu")
		(net "UPI_CPU1_CPU0_P2P2_DP<1>")
	)
	(segment
		(start 355.875082 -295.906698)
		(end 356.019862 -295.761918)
		(width 0.14732)
		(layer "In11.Cu")
		(net "UPI_CPU1_CPU0_P2P2_DP<1>")
	)
	(segment
		(start 79.879698 -297.254422)
		(end 79.879698 -297.426888)
		(width 0.14732)
		(layer "In11.Cu")
		(net "UPI_CPU1_CPU0_P2P2_DP<1>")
	)
	(segment
		(start 358.47655 -282.086558)
		(end 358.461564 -282.077922)
		(width 0.0889)
		(layer "In11.Cu")
		(net "UPI_CPU1_CPU0_P2P2_DP<1>")
	)
	(segment
		(start 358.185212 -283.219906)
		(end 358.185212 -283.205682)
		(width 0.0889)
		(layer "In11.Cu")
		(net "UPI_CPU1_CPU0_P2P2_DP<1>")
	)
	(segment
		(start 358.001062 -283.542232)
		(end 358.00665 -283.539184)
		(width 0.0889)
		(layer "In11.Cu")
		(net "UPI_CPU1_CPU0_P2P2_DP<1>")
	)
	(segment
		(start 358.455722 -279.481788)
		(end 358.476804 -279.469596)
		(width 0.0889)
		(layer "In11.Cu")
		(net "UPI_CPU1_CPU0_P2P2_DP<1>")
	)
	(segment
		(start 63.767208 -311.388506)
		(end 59.700668 -313.073034)
		(width 0.14732)
		(layer "In11.Cu")
		(net "UPI_CPU1_CPU0_P2P2_DP<1>")
	)
	(segment
		(start 356.019862 -297.424602)
		(end 356.019862 -296.419778)
		(width 0.14732)
		(layer "In11.Cu")
		(net "UPI_CPU1_CPU0_P2P2_DP<1>")
	)
	(segment
		(start 51.6382 -329.314048)
		(end 54.875176 -332.55077)
		(width 0.14732)
		(layer "In11.Cu")
		(net "UPI_CPU1_CPU0_P2P2_DP<1>")
	)
	(segment
		(start 287.11652 -341.89543)
		(end 311.255918 -341.89543)
		(width 0.14732)
		(layer "In11.Cu")
		(net "UPI_CPU1_CPU0_P2P2_DP<1>")
	)
	(segment
		(start 76.647802 -300.486318)
		(end 76.647802 -300.658784)
		(width 0.14732)
		(layer "In11.Cu")
		(net "UPI_CPU1_CPU0_P2P2_DP<1>")
	)
	(segment
		(start 357.715312 -284.033722)
		(end 357.715312 -284.023816)
		(width 0.0889)
		(layer "In11.Cu")
		(net "UPI_CPU1_CPU0_P2P2_DP<1>")
	)
	(segment
		(start 355.267006 -290.208462)
		(end 355.366066 -290.109402)
		(width 0.0889)
		(layer "In11.Cu")
		(net "UPI_CPU1_CPU0_P2P2_DP<1>")
	)
	(segment
		(start 54.03723 -316.792102)
		(end 53.917596 -317.0809)
		(width 0.14732)
		(layer "In11.Cu")
		(net "UPI_CPU1_CPU0_P2P2_DP<1>")
	)
	(segment
		(start 358.655366 -279.150318)
		(end 358.655366 -279.134824)
		(width 0.0889)
		(layer "In11.Cu")
		(net "UPI_CPU1_CPU0_P2P2_DP<1>")
	)
	(segment
		(start 357.99776 -283.544264)
		(end 357.998522 -283.543756)
		(width 0.0889)
		(layer "In11.Cu")
		(net "UPI_CPU1_CPU0_P2P2_DP<1>")
	)
	(segment
		(start 76.338684 -300.967902)
		(end 76.166218 -300.967902)
		(width 0.14732)
		(layer "In11.Cu")
		(net "UPI_CPU1_CPU0_P2P2_DP<1>")
	)
	(segment
		(start 77.43825 -299.69587)
		(end 77.43825 -299.868336)
		(width 0.14732)
		(layer "In11.Cu")
		(net "UPI_CPU1_CPU0_P2P2_DP<1>")
	)
	(segment
		(start 355.73716 -298.107608)
		(end 355.737414 -298.1071)
		(width 0.14732)
		(layer "In11.Cu")
		(net "UPI_CPU1_CPU0_P2P2_DP<1>")
	)
	(segment
		(start 82.452464 -292.556946)
		(end 80.950054 -296.184066)
		(width 0.14732)
		(layer "In11.Cu")
		(net "UPI_CPU1_CPU0_P2P2_DP<1>")
	)
	(segment
		(start 59.700668 -313.073034)
		(end 58.739024 -314.034678)
		(width 0.14732)
		(layer "In11.Cu")
		(net "UPI_CPU1_CPU0_P2P2_DP<1>")
	)
	(segment
		(start 55.842154 -333.686658)
		(end 56.829198 -334.846422)
		(width 0.14732)
		(layer "In11.Cu")
		(net "UPI_CPU1_CPU0_P2P2_DP<1>")
	)
	(segment
		(start 355.366066 -291.216842)
		(end 355.366066 -291.039042)
		(width 0.0889)
		(layer "In11.Cu")
		(net "UPI_CPU1_CPU0_P2P2_DP<1>")
	)
	(segment
		(start 359.125012 -276.708616)
		(end 359.125012 -276.69998)
		(width 0.0889)
		(layer "In11.Cu")
		(net "UPI_CPU1_CPU0_P2P2_DP<1>")
	)
	(segment
		(start 72.986138 -378.408692)
		(end 73.389998 -378.575824)
		(width 0.14732)
		(layer "In11.Cu")
		(net "UPI_CPU1_CPU0_P2P2_DP<1>")
	)
	(segment
		(start 51.6382 -324.449694)
		(end 51.6382 -325.101458)
		(width 0.14732)
		(layer "In11.Cu")
		(net "UPI_CPU1_CPU0_P2P2_DP<1>")
	)
	(segment
		(start 72.826626 -378.474732)
		(end 72.986138 -378.408692)
		(width 0.14732)
		(layer "In11.Cu")
		(net "UPI_CPU1_CPU0_P2P2_DP<1>")
	)
	(segment
		(start 357.52786 -284.35808)
		(end 357.53675 -284.353)
		(width 0.0889)
		(layer "In11.Cu")
		(net "UPI_CPU1_CPU0_P2P2_DP<1>")
	)
	(segment
		(start 358.461564 -281.106118)
		(end 358.47655 -281.097482)
		(width 0.0889)
		(layer "In11.Cu")
		(net "UPI_CPU1_CPU0_P2P2_DP<1>")
	)
	(segment
		(start 356.775512 -285.66999)
		(end 356.775512 -285.651448)
		(width 0.0889)
		(layer "In11.Cu")
		(net "UPI_CPU1_CPU0_P2P2_DP<1>")
	)
	(segment
		(start 77.43825 -299.868336)
		(end 77.129132 -300.177454)
		(width 0.14732)
		(layer "In11.Cu")
		(net "UPI_CPU1_CPU0_P2P2_DP<1>")
	)
	(segment
		(start 356.265734 -275.545804)
		(end 356.244652 -275.623782)
		(width 0.0889)
		(layer "In11.Cu")
		(net "UPI_CPU1_CPU0_P2P2_DP<1>")
	)
	(segment
		(start 311.255918 -341.89543)
		(end 321.867276 -331.284072)
		(width 0.14732)
		(layer "In11.Cu")
		(net "UPI_CPU1_CPU0_P2P2_DP<1>")
	)
	(segment
		(start 355.267006 -291.315902)
		(end 355.366066 -291.216842)
		(width 0.0889)
		(layer "In11.Cu")
		(net "UPI_CPU1_CPU0_P2P2_DP<1>")
	)
	(segment
		(start 73.456038 -378.735336)
		(end 92.96527 -386.815076)
		(width 0.14732)
		(layer "In11.Cu")
		(net "UPI_CPU1_CPU0_P2P2_DP<1>")
	)
	(segment
		(start 84.544916 -290.464748)
		(end 82.452464 -292.556946)
		(width 0.14732)
		(layer "In11.Cu")
		(net "UPI_CPU1_CPU0_P2P2_DP<1>")
	)
	(segment
		(start 354.896166 -289.160966)
		(end 354.896166 -288.895028)
		(width 0.0889)
		(layer "In11.Cu")
		(net "UPI_CPU1_CPU0_P2P2_DP<1>")
	)
	(segment
		(start 285.598108 -342.524334)
		(end 287.11652 -341.89543)
		(width 0.14732)
		(layer "In11.Cu")
		(net "UPI_CPU1_CPU0_P2P2_DP<1>")
	)
	(segment
		(start 354.923344 -298.92752)
		(end 354.922582 -298.722542)
		(width 0.14732)
		(layer "In11.Cu")
		(net "UPI_CPU1_CPU0_P2P2_DP<1>")
	)
	(segment
		(start 322.990718 -328.572114)
		(end 340.901782 -310.66105)
		(width 0.14732)
		(layer "In11.Cu")
		(net "UPI_CPU1_CPU0_P2P2_DP<1>")
	)
	(segment
		(start 354.353622 -299.29582)
		(end 354.558346 -299.295058)
		(width 0.14732)
		(layer "In11.Cu")
		(net "UPI_CPU1_CPU0_P2P2_DP<1>")
	)
	(segment
		(start 57.542938 -336.567526)
		(end 57.542938 -356.406196)
		(width 0.14732)
		(layer "In11.Cu")
		(net "UPI_CPU1_CPU0_P2P2_DP<1>")
	)
	(segment
		(start 76.956666 -300.177454)
		(end 76.647802 -300.486318)
		(width 0.14732)
		(layer "In11.Cu")
		(net "UPI_CPU1_CPU0_P2P2_DP<1>")
	)
	(segment
		(start 67.911726 -309.222394)
		(end 64.534542 -310.621172)
		(width 0.14732)
		(layer "In11.Cu")
		(net "UPI_CPU1_CPU0_P2P2_DP<1>")
	)
	(segment
		(start 355.366066 -290.663122)
		(end 355.366066 -290.485322)
		(width 0.0889)
		(layer "In11.Cu")
		(net "UPI_CPU1_CPU0_P2P2_DP<1>")
	)
	(segment
		(start 355.17836 -288.427414)
		(end 355.18725 -288.422334)
		(width 0.0889)
		(layer "In11.Cu")
		(net "UPI_CPU1_CPU0_P2P2_DP<1>")
	)
	(segment
		(start 53.713888 -322.664328)
		(end 52.700174 -323.677788)
		(width 0.14732)
		(layer "In11.Cu")
		(net "UPI_CPU1_CPU0_P2P2_DP<1>")
	)
	(segment
		(start 358.468676 -280.454354)
		(end 358.46766 -280.453846)
		(width 0.0889)
		(layer "In11.Cu")
		(net "UPI_CPU1_CPU0_P2P2_DP<1>")
	)
	(segment
		(start 355.897942 -294.239188)
		(end 355.897942 -293.802308)
		(width 0.14732)
		(layer "In11.Cu")
		(net "UPI_CPU1_CPU0_P2P2_DP<1>")
	)
	(segment
		(start 52.205128 -323.882766)
		(end 51.6382 -324.449694)
		(width 0.14732)
		(layer "In11.Cu")
		(net "UPI_CPU1_CPU0_P2P2_DP<1>")
	)
	(segment
		(start 359.125012 -278.336502)
		(end 359.125012 -278.322278)
		(width 0.0889)
		(layer "In11.Cu")
		(net "UPI_CPU1_CPU0_P2P2_DP<1>")
	)
	(segment
		(start 87.315294 -284.847538)
		(end 87.15883 -284.57652)
		(width 0.0889)
		(layer "In11.Cu")
		(net "UPI_CPU1_CPU0_P2P2_DP<1>")
	)
	(segment
		(start 356.019862 -294.361108)
		(end 355.897942 -294.239188)
		(width 0.14732)
		(layer "In11.Cu")
		(net "UPI_CPU1_CPU0_P2P2_DP<1>")
	)
	(segment
		(start 355.642164 -287.617154)
		(end 355.65715 -287.608518)
		(width 0.0889)
		(layer "In11.Cu")
		(net "UPI_CPU1_CPU0_P2P2_DP<1>")
	)
	(segment
		(start 57.542938 -356.406196)
		(end 63.161164 -369.97005)
		(width 0.14732)
		(layer "In11.Cu")
		(net "UPI_CPU1_CPU0_P2P2_DP<1>")
	)
	(segment
		(start 78.71333 -298.593256)
		(end 78.540864 -298.593256)
		(width 0.14732)
		(layer "In11.Cu")
		(net "UPI_CPU1_CPU0_P2P2_DP<1>")
	)
	(segment
		(start 55.362348 -333.123032)
		(end 55.8419 -333.686404)
		(width 0.14732)
		(layer "In11.Cu")
		(net "UPI_CPU1_CPU0_P2P2_DP<1>")
	)
	(segment
		(start 355.366066 -290.485322)
		(end 355.267006 -290.386262)
		(width 0.0889)
		(layer "In11.Cu")
		(net "UPI_CPU1_CPU0_P2P2_DP<1>")
	)
	(segment
		(start 344.932254 -308.991508)
		(end 354.094542 -299.762164)
		(width 0.14732)
		(layer "In11.Cu")
		(net "UPI_CPU1_CPU0_P2P2_DP<1>")
	)
	(segment
		(start 76.647802 -300.658784)
		(end 76.338684 -300.967902)
		(width 0.14732)
		(layer "In11.Cu")
		(net "UPI_CPU1_CPU0_P2P2_DP<1>")
	)
	(segment
		(start 359.416604 -277.203154)
		(end 359.409238 -277.198836)
		(width 0.0889)
		(layer "In11.Cu")
		(net "UPI_CPU1_CPU0_P2P2_DP<1>")
	)
	(segment
		(start 355.51745 -291.921946)
		(end 355.366066 -291.770562)
		(width 0.0889)
		(layer "In11.Cu")
		(net "UPI_CPU1_CPU0_P2P2_DP<1>")
	)
	(segment
		(start 355.267006 -291.493702)
		(end 355.267006 -291.315902)
		(width 0.0889)
		(layer "In11.Cu")
		(net "UPI_CPU1_CPU0_P2P2_DP<1>")
	)
	(segment
		(start 63.161164 -369.97005)
		(end 70.845172 -377.654058)
		(width 0.14732)
		(layer "In11.Cu")
		(net "UPI_CPU1_CPU0_P2P2_DP<1>")
	)
	(segment
		(start 355.366066 -291.592762)
		(end 355.267006 -291.493702)
		(width 0.0889)
		(layer "In11.Cu")
		(net "UPI_CPU1_CPU0_P2P2_DP<1>")
	)
	(segment
		(start 355.737414 -298.1071)
		(end 356.019862 -297.424602)
		(width 0.14732)
		(layer "In11.Cu")
		(net "UPI_CPU1_CPU0_P2P2_DP<1>")
	)
	(segment
		(start 85.171026 -286.209994)
		(end 85.061298 -286.319722)
		(width 0.0889)
		(layer "In11.Cu")
		(net "UPI_CPU1_CPU0_P2P2_DP<1>")
	)
	(segment
		(start 356.305612 -286.48406)
		(end 356.305612 -286.4612)
		(width 0.0889)
		(layer "In11.Cu")
		(net "UPI_CPU1_CPU0_P2P2_DP<1>")
	)
	(segment
		(start 127.023114 -391.86739)
		(end 161.799524 -391.86739)
		(width 0.14732)
		(layer "In11.Cu")
		(net "UPI_CPU1_CPU0_P2P2_DP<1>")
	)
	(segment
		(start 354.09378 -299.55744)
		(end 354.353622 -299.29582)
		(width 0.14732)
		(layer "In11.Cu")
		(net "UPI_CPU1_CPU0_P2P2_DP<1>")
	)
	(segment
		(start 321.867276 -331.284072)
		(end 322.990718 -328.572114)
		(width 0.14732)
		(layer "In11.Cu")
		(net "UPI_CPU1_CPU0_P2P2_DP<1>")
	)
	(segment
		(start 79.022448 -298.111672)
		(end 79.022448 -298.284138)
		(width 0.14732)
		(layer "In11.Cu")
		(net "UPI_CPU1_CPU0_P2P2_DP<1>")
	)
	(segment
		(start 355.182424 -298.460922)
		(end 355.387148 -298.46016)
		(width 0.14732)
		(layer "In11.Cu")
		(net "UPI_CPU1_CPU0_P2P2_DP<1>")
	)
	(segment
		(start 355.267006 -290.762182)
		(end 355.366066 -290.663122)
		(width 0.0889)
		(layer "In11.Cu")
		(net "UPI_CPU1_CPU0_P2P2_DP<1>")
	)
	(segment
		(start 85.061298 -286.319722)
		(end 84.93379 -290.03117)
		(width 0.0889)
		(layer "In11.Cu")
		(net "UPI_CPU1_CPU0_P2P2_DP<1>")
	)
	(segment
		(start 84.5566 -290.45408)
		(end 84.544916 -290.464748)
		(width 0.0889)
		(layer "In11.Cu")
		(net "UPI_CPU1_CPU0_P2P2_DP<1>")
	)
	(segment
		(start 265.584178 -383.102866)
		(end 278.57196 -370.115084)
		(width 0.14732)
		(layer "In11.Cu")
		(net "UPI_CPU1_CPU0_P2P2_DP<1>")
	)
	(segment
		(start 51.6382 -328.261218)
		(end 51.78298 -328.405998)
		(width 0.14732)
		(layer "In11.Cu")
		(net "UPI_CPU1_CPU0_P2P2_DP<1>")
	)
	(segment
		(start 355.267006 -290.939982)
		(end 355.267006 -290.762182)
		(width 0.0889)
		(layer "In11.Cu")
		(net "UPI_CPU1_CPU0_P2P2_DP<1>")
	)
	(segment
		(start 355.653594 -292.118034)
		(end 355.532944 -291.997384)
		(width 0.14732)
		(layer "In11.Cu")
		(net "UPI_CPU1_CPU0_P2P2_DP<1>")
	)
	(segment
		(start 79.879698 -297.426888)
		(end 79.57058 -297.736006)
		(width 0.14732)
		(layer "In11.Cu")
		(net "UPI_CPU1_CPU0_P2P2_DP<1>")
	)
	(segment
		(start 64.534542 -310.621172)
		(end 63.767208 -311.388506)
		(width 0.14732)
		(layer "In11.Cu")
		(net "UPI_CPU1_CPU0_P2P2_DP<1>")
	)
	(segment
		(start 85.258656 -286.144716)
		(end 85.247734 -286.151066)
		(width 0.0889)
		(layer "In11.Cu")
		(net "UPI_CPU1_CPU0_P2P2_DP<1>")
	)
	(segment
		(start 356.019862 -296.419778)
		(end 355.875082 -296.274998)
		(width 0.14732)
		(layer "In11.Cu")
		(net "UPI_CPU1_CPU0_P2P2_DP<1>")
	)
	(segment
		(start 354.922582 -298.722542)
		(end 355.182424 -298.460922)
		(width 0.14732)
		(layer "In11.Cu")
		(net "UPI_CPU1_CPU0_P2P2_DP<1>")
	)
	(segment
		(start 54.875176 -332.55077)
		(end 55.362094 -333.122778)
		(width 0.14732)
		(layer "In11.Cu")
		(net "UPI_CPU1_CPU0_P2P2_DP<1>")
	)
	(segment
		(start 79.57058 -297.736006)
		(end 79.398114 -297.736006)
		(width 0.14732)
		(layer "In11.Cu")
		(net "UPI_CPU1_CPU0_P2P2_DP<1>")
	)
	(segment
		(start 51.6382 -325.101458)
		(end 51.78298 -325.246238)
		(width 0.14732)
		(layer "In11.Cu")
		(net "UPI_CPU1_CPU0_P2P2_DP<1>")
	)
	(segment
		(start 58.739024 -314.034678)
		(end 55.955946 -315.894466)
		(width 0.14732)
		(layer "In11.Cu")
		(net "UPI_CPU1_CPU0_P2P2_DP<1>")
	)
	(segment
		(start 356.019862 -295.761918)
		(end 356.019862 -294.361108)
		(width 0.14732)
		(layer "In11.Cu")
		(net "UPI_CPU1_CPU0_P2P2_DP<1>")
	)
	(segment
		(start 54.212744 -316.616588)
		(end 54.03723 -316.792102)
		(width 0.14732)
		(layer "In11.Cu")
		(net "UPI_CPU1_CPU0_P2P2_DP<1>")
	)
	(segment
		(start 358.93756 -278.66086)
		(end 358.94645 -278.65578)
		(width 0.0889)
		(layer "In11.Cu")
		(net "UPI_CPU1_CPU0_P2P2_DP<1>")
	)
	(segment
		(start 77.91958 -299.387006)
		(end 77.747114 -299.387006)
		(width 0.14732)
		(layer "In11.Cu")
		(net "UPI_CPU1_CPU0_P2P2_DP<1>")
	)
	(segment
		(start 342.917272 -309.826152)
		(end 342.917272 -309.825898)
		(width 0.14732)
		(layer "In11.Cu")
		(net "UPI_CPU1_CPU0_P2P2_DP<1>")
	)
	(segment
		(start 55.362094 -333.122778)
		(end 55.362348 -333.123032)
		(width 0.14732)
		(layer "In11.Cu")
		(net "UPI_CPU1_CPU0_P2P2_DP<1>")
	)
	(segment
		(start 355.897942 -293.802308)
		(end 356.019862 -293.680388)
		(width 0.14732)
		(layer "In11.Cu")
		(net "UPI_CPU1_CPU0_P2P2_DP<1>")
	)
	(segment
		(start 355.366066 -290.109402)
		(end 355.366066 -289.630866)
		(width 0.0889)
		(layer "In11.Cu")
		(net "UPI_CPU1_CPU0_P2P2_DP<1>")
	)
	(segment
		(start 359.409238 -277.198836)
		(end 359.401618 -277.194518)
		(width 0.0889)
		(layer "In11.Cu")
		(net "UPI_CPU1_CPU0_P2P2_DP<1>")
	)
	(segment
		(start 355.267006 -290.386262)
		(end 355.267006 -290.208462)
		(width 0.0889)
		(layer "In11.Cu")
		(net "UPI_CPU1_CPU0_P2P2_DP<1>")
	)
	(arc
		(start 357.06685 -285.166816)
		(mid 357.197764 -285.030456)
		(end 357.245412 -284.847538)
		(width 0.0889)
		(layer "In11.Cu")
		(net "UPI_CPU1_CPU0_P2P2_DP<1>")
	)
	(arc
		(start 358.47655 -282.725114)
		(mid 358.655268 -282.405836)
		(end 358.47655 -282.086558)
		(width 0.0889)
		(layer "In11.Cu")
		(net "UPI_CPU1_CPU0_P2P2_DP<1>")
	)
	(arc
		(start 356.118414 -286.799782)
		(mid 356.253347 -286.666428)
		(end 356.305612 -286.48406)
		(width 0.0889)
		(layer "In11.Cu")
		(net "UPI_CPU1_CPU0_P2P2_DP<1>")
	)
	(arc
		(start 357.53675 -284.353)
		(mid 357.667664 -284.21664)
		(end 357.715312 -284.033722)
		(width 0.0889)
		(layer "In11.Cu")
		(net "UPI_CPU1_CPU0_P2P2_DP<1>")
	)
	(arc
		(start 86.093046 -285.336742)
		(mid 85.905738 -285.286633)
		(end 85.718396 -285.336742)
		(width 0.0889)
		(layer "In11.Cu")
		(net "UPI_CPU1_CPU0_P2P2_DP<1>")
	)
	(arc
		(start 85.247734 -286.151066)
		(mid 85.213389 -286.173519)
		(end 85.181694 -286.19958)
		(width 0.0889)
		(layer "In11.Cu")
		(net "UPI_CPU1_CPU0_P2P2_DP<1>")
	)
	(arc
		(start 355.835712 -287.28924)
		(mid 355.907947 -287.012716)
		(end 356.106222 -286.806894)
		(width 0.0889)
		(layer "In11.Cu")
		(net "UPI_CPU1_CPU0_P2P2_DP<1>")
	)
	(arc
		(start 356.775512 -285.651448)
		(mid 356.853623 -285.374499)
		(end 357.05796 -285.171896)
		(width 0.0889)
		(layer "In11.Cu")
		(net "UPI_CPU1_CPU0_P2P2_DP<1>")
	)
	(arc
		(start 357.245412 -284.837632)
		(mid 357.323523 -284.560683)
		(end 357.52786 -284.35808)
		(width 0.0889)
		(layer "In11.Cu")
		(net "UPI_CPU1_CPU0_P2P2_DP<1>")
	)
	(arc
		(start 358.655366 -279.134824)
		(mid 358.734736 -278.86109)
		(end 358.93756 -278.66086)
		(width 0.0889)
		(layer "In11.Cu")
		(net "UPI_CPU1_CPU0_P2P2_DP<1>")
	)
	(arc
		(start 358.925622 -276.377146)
		(mid 358.727394 -276.171298)
		(end 358.655112 -275.8948)
		(width 0.0889)
		(layer "In11.Cu")
		(net "UPI_CPU1_CPU0_P2P2_DP<1>")
	)
	(arc
		(start 354.896166 -288.895028)
		(mid 354.977077 -288.6249)
		(end 355.17836 -288.427414)
		(width 0.0889)
		(layer "In11.Cu")
		(net "UPI_CPU1_CPU0_P2P2_DP<1>")
	)
	(arc
		(start 85.53069 -285.661608)
		(mid 85.457998 -285.938813)
		(end 85.258656 -286.144716)
		(width 0.0889)
		(layer "In11.Cu")
		(net "UPI_CPU1_CPU0_P2P2_DP<1>")
	)
	(arc
		(start 359.416604 -277.84171)
		(mid 359.595322 -277.522432)
		(end 359.416604 -277.203154)
		(width 0.0889)
		(layer "In11.Cu")
		(net "UPI_CPU1_CPU0_P2P2_DP<1>")
	)
	(arc
		(start 85.181694 -286.19958)
		(mid 85.176565 -286.204611)
		(end 85.171534 -286.20974)
		(width 0.0889)
		(layer "In11.Cu")
		(net "UPI_CPU1_CPU0_P2P2_DP<1>")
	)
	(arc
		(start 356.305612 -286.4612)
		(mid 356.384831 -286.186515)
		(end 356.588314 -285.985712)
		(width 0.0889)
		(layer "In11.Cu")
		(net "UPI_CPU1_CPU0_P2P2_DP<1>")
	)
	(arc
		(start 87.080852 -284.555184)
		(mid 86.977441 -284.685399)
		(end 86.940644 -284.847538)
		(width 0.0889)
		(layer "In11.Cu")
		(net "UPI_CPU1_CPU0_P2P2_DP<1>")
	)
	(arc
		(start 356.588314 -285.985712)
		(mid 356.723247 -285.852358)
		(end 356.775512 -285.66999)
		(width 0.0889)
		(layer "In11.Cu")
		(net "UPI_CPU1_CPU0_P2P2_DP<1>")
	)
	(arc
		(start 358.476804 -279.469596)
		(mid 358.607718 -279.333236)
		(end 358.655366 -279.150318)
		(width 0.0889)
		(layer "In11.Cu")
		(net "UPI_CPU1_CPU0_P2P2_DP<1>")
	)
	(arc
		(start 358.46766 -280.453846)
		(mid 358.18517 -279.97127)
		(end 358.455722 -279.481788)
		(width 0.0889)
		(layer "In11.Cu")
		(net "UPI_CPU1_CPU0_P2P2_DP<1>")
	)
	(arc
		(start 357.15321 -275.570442)
		(mid 356.870762 -275.646057)
		(end 356.588314 -275.570442)
		(width 0.0889)
		(layer "In11.Cu")
		(net "UPI_CPU1_CPU0_P2P2_DP<1>")
	)
	(arc
		(start 359.125012 -276.69998)
		(mid 359.072742 -276.517615)
		(end 358.937814 -276.384258)
		(width 0.0889)
		(layer "In11.Cu")
		(net "UPI_CPU1_CPU0_P2P2_DP<1>")
	)
	(arc
		(start 355.18725 -288.422334)
		(mid 355.318164 -288.285974)
		(end 355.365812 -288.103056)
		(width 0.0889)
		(layer "In11.Cu")
		(net "UPI_CPU1_CPU0_P2P2_DP<1>")
	)
	(arc
		(start 85.718396 -285.336742)
		(mid 85.583016 -285.470494)
		(end 85.53069 -285.65348)
		(width 0.0889)
		(layer "In11.Cu")
		(net "UPI_CPU1_CPU0_P2P2_DP<1>")
	)
	(arc
		(start 357.715312 -284.023816)
		(mid 357.793423 -283.746867)
		(end 357.99776 -283.544264)
		(width 0.0889)
		(layer "In11.Cu")
		(net "UPI_CPU1_CPU0_P2P2_DP<1>")
	)
	(arc
		(start 356.588314 -275.570442)
		(mid 356.429826 -275.521509)
		(end 356.265734 -275.545804)
		(width 0.0889)
		(layer "In11.Cu")
		(net "UPI_CPU1_CPU0_P2P2_DP<1>")
	)
	(arc
		(start 358.00665 -283.539184)
		(mid 358.137564 -283.402824)
		(end 358.185212 -283.219906)
		(width 0.0889)
		(layer "In11.Cu")
		(net "UPI_CPU1_CPU0_P2P2_DP<1>")
	)
	(arc
		(start 358.461564 -282.077922)
		(mid 358.185238 -281.59202)
		(end 358.461564 -281.106118)
		(width 0.0889)
		(layer "In11.Cu")
		(net "UPI_CPU1_CPU0_P2P2_DP<1>")
	)
	(arc
		(start 86.940644 -284.847538)
		(mid 86.864964 -285.129984)
		(end 86.658196 -285.336742)
		(width 0.0889)
		(layer "In11.Cu")
		(net "UPI_CPU1_CPU0_P2P2_DP<1>")
	)
	(arc
		(start 359.401618 -277.194518)
		(mid 359.199031 -276.988167)
		(end 359.125012 -276.708616)
		(width 0.0889)
		(layer "In11.Cu")
		(net "UPI_CPU1_CPU0_P2P2_DP<1>")
	)
	(arc
		(start 358.185212 -283.205682)
		(mid 358.264353 -282.931059)
		(end 358.46766 -282.730194)
		(width 0.0889)
		(layer "In11.Cu")
		(net "UPI_CPU1_CPU0_P2P2_DP<1>")
	)
	(arc
		(start 359.125012 -278.322278)
		(mid 359.204231 -278.047593)
		(end 359.407714 -277.84679)
		(width 0.0889)
		(layer "In11.Cu")
		(net "UPI_CPU1_CPU0_P2P2_DP<1>")
	)
	(arc
		(start 86.658196 -285.336742)
		(mid 86.375638 -285.412425)
		(end 86.093046 -285.336742)
		(width 0.0889)
		(layer "In11.Cu")
		(net "UPI_CPU1_CPU0_P2P2_DP<1>")
	)
	(arc
		(start 355.365812 -288.103056)
		(mid 355.439728 -287.823554)
		(end 355.642164 -287.617154)
		(width 0.0889)
		(layer "In11.Cu")
		(net "UPI_CPU1_CPU0_P2P2_DP<1>")
	)
	(arc
		(start 358.08285 -275.576538)
		(mid 357.804418 -275.646352)
		(end 357.527606 -275.570442)
		(width 0.0889)
		(layer "In11.Cu")
		(net "UPI_CPU1_CPU0_P2P2_DP<1>")
	)
	(arc
		(start 358.94645 -278.65578)
		(mid 359.077364 -278.51942)
		(end 359.125012 -278.336502)
		(width 0.0889)
		(layer "In11.Cu")
		(net "UPI_CPU1_CPU0_P2P2_DP<1>")
	)
	(arc
		(start 355.65715 -287.608518)
		(mid 355.788064 -287.472158)
		(end 355.835712 -287.28924)
		(width 0.0889)
		(layer "In11.Cu")
		(net "UPI_CPU1_CPU0_P2P2_DP<1>")
	)
	(arc
		(start 357.527606 -275.570442)
		(mid 357.340408 -275.520299)
		(end 357.15321 -275.570442)
		(width 0.0889)
		(layer "In11.Cu")
		(net "UPI_CPU1_CPU0_P2P2_DP<1>")
	)
	(arc
		(start 358.47655 -281.097482)
		(mid 358.655147 -280.778204)
		(end 358.47655 -280.458926)
		(width 0.0889)
		(layer "In11.Cu")
		(net "UPI_CPU1_CPU0_P2P2_DP<1>")
	)
	(arc
		(start 358.655112 -275.8948)
		(mid 358.467813 -275.570359)
		(end 358.093264 -275.570442)
		(width 0.0889)
		(layer "In11.Cu")
		(net "UPI_CPU1_CPU0_P2P2_DP<1>")
	)
	(segment
		(start 105.171494 -282.683966)
		(end 105.171494 -283.219652)
		(width 0.13208)
		(layer "F.Cu")
		(net "UPI_CPU1_CPU0_P2P2_DP<19>")
	)
	(segment
		(start 337.604862 -281.869896)
		(end 337.605116 -281.87015)
		(width 0.13208)
		(layer "F.Cu")
		(net "UPI_CPU1_CPU0_P2P2_DP<19>")
	)
	(segment
		(start 337.605116 -281.87015)
		(end 337.605116 -282.405836)
		(width 0.13208)
		(layer "F.Cu")
		(net "UPI_CPU1_CPU0_P2P2_DP<19>")
	)
	(segment
		(start 105.171494 -283.219652)
		(end 105.171748 -283.219906)
		(width 0.13208)
		(layer "F.Cu")
		(net "UPI_CPU1_CPU0_P2P2_DP<19>")
	)
	(segment
		(start 263.610598 -339.629496)
		(end 264.661142 -340.68004)
		(width 0.14732)
		(layer "In11.Cu")
		(net "UPI_CPU1_CPU0_P2P2_DP<19>")
	)
	(segment
		(start 259.25272 -347.315282)
		(end 258.961382 -347.023944)
		(width 0.14732)
		(layer "In11.Cu")
		(net "UPI_CPU1_CPU0_P2P2_DP<19>")
	)
	(segment
		(start 267.513816 -335.726278)
		(end 267.306044 -335.726278)
		(width 0.14732)
		(layer "In11.Cu")
		(net "UPI_CPU1_CPU0_P2P2_DP<19>")
	)
	(segment
		(start 103.624888 -291.474398)
		(end 103.666798 -291.432488)
		(width 0.0889)
		(layer "In11.Cu")
		(net "UPI_CPU1_CPU0_P2P2_DP<19>")
	)
	(segment
		(start 240.624868 -362.552488)
		(end 239.954562 -363.02188)
		(width 0.14732)
		(layer "In11.Cu")
		(net "UPI_CPU1_CPU0_P2P2_DP<19>")
	)
	(segment
		(start 248.503186 -355.818948)
		(end 248.020078 -356.15753)
		(width 0.14732)
		(layer "In11.Cu")
		(net "UPI_CPU1_CPU0_P2P2_DP<19>")
	)
	(segment
		(start 246.809514 -357.18496)
		(end 246.60479 -357.148638)
		(width 0.14732)
		(layer "In11.Cu")
		(net "UPI_CPU1_CPU0_P2P2_DP<19>")
	)
	(segment
		(start 269.831058 -335.945988)
		(end 269.000224 -336.776822)
		(width 0.14732)
		(layer "In11.Cu")
		(net "UPI_CPU1_CPU0_P2P2_DP<19>")
	)
	(segment
		(start 82.15757 -317.190374)
		(end 98.022664 -304.170588)
		(width 0.14732)
		(layer "In11.Cu")
		(net "UPI_CPU1_CPU0_P2P2_DP<19>")
	)
	(segment
		(start 104.888792 -284.35808)
		(end 104.897682 -284.353)
		(width 0.0889)
		(layer "In11.Cu")
		(net "UPI_CPU1_CPU0_P2P2_DP<19>")
	)
	(segment
		(start 262.965692 -344.037666)
		(end 262.530336 -344.037666)
		(width 0.14732)
		(layer "In11.Cu")
		(net "UPI_CPU1_CPU0_P2P2_DP<19>")
	)
	(segment
		(start 103.196898 -289.114738)
		(end 103.196898 -288.898584)
		(width 0.0889)
		(layer "In11.Cu")
		(net "UPI_CPU1_CPU0_P2P2_DP<19>")
	)
	(segment
		(start 244.706394 -358.478328)
		(end 244.223286 -358.81691)
		(width 0.14732)
		(layer "In11.Cu")
		(net "UPI_CPU1_CPU0_P2P2_DP<19>")
	)
	(segment
		(start 239.011206 -362.467398)
		(end 238.528098 -362.80598)
		(width 0.14732)
		(layer "In11.Cu")
		(net "UPI_CPU1_CPU0_P2P2_DP<19>")
	)
	(segment
		(start 238.528098 -362.80598)
		(end 238.491776 -363.010958)
		(width 0.14732)
		(layer "In11.Cu")
		(net "UPI_CPU1_CPU0_P2P2_DP<19>")
	)
	(segment
		(start 104.427782 -286.156146)
		(end 104.418892 -286.151066)
		(width 0.0889)
		(layer "In11.Cu")
		(net "UPI_CPU1_CPU0_P2P2_DP<19>")
	)
	(segment
		(start 255.939036 -350.4565)
		(end 255.939036 -350.891856)
		(width 0.14732)
		(layer "In11.Cu")
		(net "UPI_CPU1_CPU0_P2P2_DP<19>")
	)
	(segment
		(start 257.577844 -349.253048)
		(end 256.999486 -349.831406)
		(width 0.14732)
		(layer "In11.Cu")
		(net "UPI_CPU1_CPU0_P2P2_DP<19>")
	)
	(segment
		(start 254.817372 -351.362264)
		(end 254.609092 -351.362264)
		(width 0.14732)
		(layer "In11.Cu")
		(net "UPI_CPU1_CPU0_P2P2_DP<19>")
	)
	(segment
		(start 72.274938 -335.157064)
		(end 72.886062 -328.949558)
		(width 0.14732)
		(layer "In11.Cu")
		(net "UPI_CPU1_CPU0_P2P2_DP<19>")
	)
	(segment
		(start 261.326884 -345.676474)
		(end 260.891528 -345.676474)
		(width 0.14732)
		(layer "In11.Cu")
		(net "UPI_CPU1_CPU0_P2P2_DP<19>")
	)
	(segment
		(start 255.939036 -350.891856)
		(end 255.360678 -351.470214)
		(width 0.14732)
		(layer "In11.Cu")
		(net "UPI_CPU1_CPU0_P2P2_DP<19>")
	)
	(segment
		(start 250.606306 -354.52558)
		(end 250.401582 -354.489258)
		(width 0.14732)
		(layer "In11.Cu")
		(net "UPI_CPU1_CPU0_P2P2_DP<19>")
	)
	(segment
		(start 233.830876 -366.935512)
		(end 233.520742 -366.49279)
		(width 0.14732)
		(layer "In11.Cu")
		(net "UPI_CPU1_CPU0_P2P2_DP<19>")
	)
	(segment
		(start 264.661142 -341.115904)
		(end 263.252712 -342.524334)
		(width 0.14732)
		(layer "In11.Cu")
		(net "UPI_CPU1_CPU0_P2P2_DP<19>")
	)
	(segment
		(start 246.121682 -357.48722)
		(end 246.08536 -357.692198)
		(width 0.14732)
		(layer "In11.Cu")
		(net "UPI_CPU1_CPU0_P2P2_DP<19>")
	)
	(segment
		(start 284.23489 -326.059038)
		(end 279.603708 -326.059038)
		(width 0.14732)
		(layer "In11.Cu")
		(net "UPI_CPU1_CPU0_P2P2_DP<19>")
	)
	(segment
		(start 270.14805 -333.280512)
		(end 271.609312 -334.741774)
		(width 0.14732)
		(layer "In11.Cu")
		(net "UPI_CPU1_CPU0_P2P2_DP<19>")
	)
	(segment
		(start 316.95644 -313.84494)
		(end 313.994038 -313.84494)
		(width 0.14732)
		(layer "In11.Cu")
		(net "UPI_CPU1_CPU0_P2P2_DP<19>")
	)
	(segment
		(start 105.40619 -282.92806)
		(end 105.328212 -282.948888)
		(width 0.0889)
		(layer "In11.Cu")
		(net "UPI_CPU1_CPU0_P2P2_DP<19>")
	)
	(segment
		(start 256.45618 -349.723456)
		(end 256.2479 -349.723456)
		(width 0.14732)
		(layer "In11.Cu")
		(net "UPI_CPU1_CPU0_P2P2_DP<19>")
	)
	(segment
		(start 257.577844 -348.817692)
		(end 257.577844 -349.253048)
		(width 0.14732)
		(layer "In11.Cu")
		(net "UPI_CPU1_CPU0_P2P2_DP<19>")
	)
	(segment
		(start 237.11281 -363.797088)
		(end 236.629702 -364.13567)
		(width 0.14732)
		(layer "In11.Cu")
		(net "UPI_CPU1_CPU0_P2P2_DP<19>")
	)
	(segment
		(start 161.10331 -376.85345)
		(end 126.214886 -376.85345)
		(width 0.14732)
		(layer "In11.Cu")
		(net "UPI_CPU1_CPU0_P2P2_DP<19>")
	)
	(segment
		(start 306.450746 -318.160908)
		(end 306.06111 -318.550544)
		(width 0.14732)
		(layer "In11.Cu")
		(net "UPI_CPU1_CPU0_P2P2_DP<19>")
	)
	(segment
		(start 74.341228 -325.006716)
		(end 82.15757 -317.190374)
		(width 0.14732)
		(layer "In11.Cu")
		(net "UPI_CPU1_CPU0_P2P2_DP<19>")
	)
	(segment
		(start 336.048858 -290.889182)
		(end 334.603852 -291.48786)
		(width 0.14732)
		(layer "In11.Cu")
		(net "UPI_CPU1_CPU0_P2P2_DP<19>")
	)
	(segment
		(start 338.348828 -285.980632)
		(end 338.357718 -285.985712)
		(width 0.0889)
		(layer "In11.Cu")
		(net "UPI_CPU1_CPU0_P2P2_DP<19>")
	)
	(segment
		(start 337.271868 -289.326066)
		(end 337.271868 -289.666172)
		(width 0.14732)
		(layer "In11.Cu")
		(net "UPI_CPU1_CPU0_P2P2_DP<19>")
	)
	(segment
		(start 236.59338 -364.340648)
		(end 236.903514 -364.78337)
		(width 0.14732)
		(layer "In11.Cu")
		(net "UPI_CPU1_CPU0_P2P2_DP<19>")
	)
	(segment
		(start 337.229958 -289.262058)
		(end 337.271868 -289.303968)
		(width 0.0889)
		(layer "In11.Cu")
		(net "UPI_CPU1_CPU0_P2P2_DP<19>")
	)
	(segment
		(start 337.878674 -283.539184)
		(end 337.887564 -283.544264)
		(width 0.0889)
		(layer "In11.Cu")
		(net "UPI_CPU1_CPU0_P2P2_DP<19>")
	)
	(segment
		(start 73.463912 -326.862694)
		(end 74.341228 -325.006716)
		(width 0.14732)
		(layer "In11.Cu")
		(net "UPI_CPU1_CPU0_P2P2_DP<19>")
	)
	(segment
		(start 243.012722 -359.84434)
		(end 242.807998 -359.808018)
		(width 0.14732)
		(layer "In11.Cu")
		(net "UPI_CPU1_CPU0_P2P2_DP<19>")
	)
	(segment
		(start 259.688076 -347.315282)
		(end 259.25272 -347.315282)
		(width 0.14732)
		(layer "In11.Cu")
		(net "UPI_CPU1_CPU0_P2P2_DP<19>")
	)
	(segment
		(start 278.982932 -327.804018)
		(end 274.696682 -332.090268)
		(width 0.14732)
		(layer "In11.Cu")
		(net "UPI_CPU1_CPU0_P2P2_DP<19>")
	)
	(segment
		(start 236.903514 -364.78337)
		(end 236.828076 -365.211868)
		(width 0.14732)
		(layer "In11.Cu")
		(net "UPI_CPU1_CPU0_P2P2_DP<19>")
	)
	(segment
		(start 245.64975 -359.03281)
		(end 245.221252 -358.957372)
		(width 0.14732)
		(layer "In11.Cu")
		(net "UPI_CPU1_CPU0_P2P2_DP<19>")
	)
	(segment
		(start 263.252712 -342.732614)
		(end 263.54405 -343.023952)
		(width 0.14732)
		(layer "In11.Cu")
		(net "UPI_CPU1_CPU0_P2P2_DP<19>")
	)
	(segment
		(start 241.42446 -361.616752)
		(end 241.114326 -361.17403)
		(width 0.14732)
		(layer "In11.Cu")
		(net "UPI_CPU1_CPU0_P2P2_DP<19>")
	)
	(segment
		(start 248.29389 -356.80523)
		(end 248.218452 -357.233728)
		(width 0.14732)
		(layer "In11.Cu")
		(net "UPI_CPU1_CPU0_P2P2_DP<19>")
	)
	(segment
		(start 255.831086 -350.14027)
		(end 255.831086 -350.34855)
		(width 0.14732)
		(layer "In11.Cu")
		(net "UPI_CPU1_CPU0_P2P2_DP<19>")
	)
	(segment
		(start 248.218452 -357.233728)
		(end 247.548146 -357.70312)
		(width 0.14732)
		(layer "In11.Cu")
		(net "UPI_CPU1_CPU0_P2P2_DP<19>")
	)
	(segment
		(start 248.70791 -355.85527)
		(end 248.503186 -355.818948)
		(width 0.14732)
		(layer "In11.Cu")
		(net "UPI_CPU1_CPU0_P2P2_DP<19>")
	)
	(segment
		(start 263.610598 -339.421724)
		(end 263.610598 -339.629496)
		(width 0.14732)
		(layer "In11.Cu")
		(net "UPI_CPU1_CPU0_P2P2_DP<19>")
	)
	(segment
		(start 242.523264 -361.222798)
		(end 241.852958 -361.69219)
		(width 0.14732)
		(layer "In11.Cu")
		(net "UPI_CPU1_CPU0_P2P2_DP<19>")
	)
	(segment
		(start 244.186964 -359.021888)
		(end 244.497098 -359.46461)
		(width 0.14732)
		(layer "In11.Cu")
		(net "UPI_CPU1_CPU0_P2P2_DP<19>")
	)
	(segment
		(start 272.905474 -331.986128)
		(end 273.635216 -332.71587)
		(width 0.14732)
		(layer "In11.Cu")
		(net "UPI_CPU1_CPU0_P2P2_DP<19>")
	)
	(segment
		(start 247.119648 -357.627682)
		(end 246.809514 -357.18496)
		(width 0.14732)
		(layer "In11.Cu")
		(net "UPI_CPU1_CPU0_P2P2_DP<19>")
	)
	(segment
		(start 250.401582 -354.489258)
		(end 249.918474 -354.82784)
		(width 0.14732)
		(layer "In11.Cu")
		(net "UPI_CPU1_CPU0_P2P2_DP<19>")
	)
	(segment
		(start 200.018396 -369.992402)
		(end 161.10331 -376.85345)
		(width 0.14732)
		(layer "In11.Cu")
		(net "UPI_CPU1_CPU0_P2P2_DP<19>")
	)
	(segment
		(start 267.306044 -335.726278)
		(end 266.888214 -336.144108)
		(width 0.14732)
		(layer "In11.Cu")
		(net "UPI_CPU1_CPU0_P2P2_DP<19>")
	)
	(segment
		(start 258.145026 -347.825822)
		(end 257.469894 -348.501462)
		(width 0.14732)
		(layer "In11.Cu")
		(net "UPI_CPU1_CPU0_P2P2_DP<19>")
	)
	(segment
		(start 235.419138 -365.1631)
		(end 235.214414 -365.126778)
		(width 0.14732)
		(layer "In11.Cu")
		(net "UPI_CPU1_CPU0_P2P2_DP<19>")
	)
	(segment
		(start 338.357718 -286.964882)
		(end 338.356702 -286.96539)
		(width 0.0889)
		(layer "In11.Cu")
		(net "UPI_CPU1_CPU0_P2P2_DP<19>")
	)
	(segment
		(start 266.888214 -336.144108)
		(end 266.888214 -336.35188)
		(width 0.14732)
		(layer "In11.Cu")
		(net "UPI_CPU1_CPU0_P2P2_DP<19>")
	)
	(segment
		(start 251.81687 -353.49815)
		(end 251.780548 -353.703128)
		(width 0.14732)
		(layer "In11.Cu")
		(net "UPI_CPU1_CPU0_P2P2_DP<19>")
	)
	(segment
		(start 261.613904 -344.371422)
		(end 261.905242 -344.66276)
		(width 0.14732)
		(layer "In11.Cu")
		(net "UPI_CPU1_CPU0_P2P2_DP<19>")
	)
	(segment
		(start 102.697534 -297.867832)
		(end 102.858824 -297.478958)
		(width 0.14732)
		(layer "In11.Cu")
		(net "UPI_CPU1_CPU0_P2P2_DP<19>")
	)
	(segment
		(start 105.358184 -283.544772)
		(end 105.358946 -283.544264)
		(width 0.0889)
		(layer "In11.Cu")
		(net "UPI_CPU1_CPU0_P2P2_DP<19>")
	)
	(segment
		(start 330.608178 -300.193202)
		(end 316.95644 -313.84494)
		(width 0.14732)
		(layer "In11.Cu")
		(net "UPI_CPU1_CPU0_P2P2_DP<19>")
	)
	(segment
		(start 248.020078 -356.15753)
		(end 247.983756 -356.362508)
		(width 0.14732)
		(layer "In11.Cu")
		(net "UPI_CPU1_CPU0_P2P2_DP<19>")
	)
	(segment
		(start 265.875008 -337.365086)
		(end 265.667236 -337.365086)
		(width 0.14732)
		(layer "In11.Cu")
		(net "UPI_CPU1_CPU0_P2P2_DP<19>")
	)
	(segment
		(start 103.483664 -288.424874)
		(end 103.488236 -288.422334)
		(width 0.0889)
		(layer "In11.Cu")
		(net "UPI_CPU1_CPU0_P2P2_DP<19>")
	)
	(segment
		(start 306.06111 -318.550544)
		(end 305.850798 -318.962024)
		(width 0.14732)
		(layer "In11.Cu")
		(net "UPI_CPU1_CPU0_P2P2_DP<19>")
	)
	(segment
		(start 305.850798 -320.601594)
		(end 305.48834 -321.47637)
		(width 0.14732)
		(layer "In11.Cu")
		(net "UPI_CPU1_CPU0_P2P2_DP<19>")
	)
	(segment
		(start 242.32489 -360.1466)
		(end 242.288568 -360.351578)
		(width 0.14732)
		(layer "In11.Cu")
		(net "UPI_CPU1_CPU0_P2P2_DP<19>")
	)
	(segment
		(start 103.666798 -290.711128)
		(end 103.666798 -290.533328)
		(width 0.0889)
		(layer "In11.Cu")
		(net "UPI_CPU1_CPU0_P2P2_DP<19>")
	)
	(segment
		(start 254.609092 -351.362264)
		(end 254.00127 -351.970086)
		(width 0.14732)
		(layer "In11.Cu")
		(net "UPI_CPU1_CPU0_P2P2_DP<19>")
	)
	(segment
		(start 256.2479 -349.723456)
		(end 255.831086 -350.14027)
		(width 0.14732)
		(layer "In11.Cu")
		(net "UPI_CPU1_CPU0_P2P2_DP<19>")
	)
	(segment
		(start 244.497098 -359.46461)
		(end 244.42166 -359.893108)
		(width 0.14732)
		(layer "In11.Cu")
		(net "UPI_CPU1_CPU0_P2P2_DP<19>")
	)
	(segment
		(start 244.223286 -358.81691)
		(end 244.186964 -359.021888)
		(width 0.14732)
		(layer "In11.Cu")
		(net "UPI_CPU1_CPU0_P2P2_DP<19>")
	)
	(segment
		(start 266.888214 -336.35188)
		(end 267.938758 -337.402424)
		(width 0.14732)
		(layer "In11.Cu")
		(net "UPI_CPU1_CPU0_P2P2_DP<19>")
	)
	(segment
		(start 257.469894 -348.501462)
		(end 257.469894 -348.709742)
		(width 0.14732)
		(layer "In11.Cu")
		(net "UPI_CPU1_CPU0_P2P2_DP<19>")
	)
	(segment
		(start 262.030718 -343.746328)
		(end 261.613904 -344.163142)
		(width 0.14732)
		(layer "In11.Cu")
		(net "UPI_CPU1_CPU0_P2P2_DP<19>")
	)
	(segment
		(start 98.022664 -304.170588)
		(end 102.697534 -297.867832)
		(width 0.14732)
		(layer "In11.Cu")
		(net "UPI_CPU1_CPU0_P2P2_DP<19>")
	)
	(segment
		(start 265.667236 -337.365086)
		(end 265.249406 -337.782916)
		(width 0.14732)
		(layer "In11.Cu")
		(net "UPI_CPU1_CPU0_P2P2_DP<19>")
	)
	(segment
		(start 104.412796 -286.803338)
		(end 104.427782 -286.794702)
		(width 0.0889)
		(layer "In11.Cu")
		(net "UPI_CPU1_CPU0_P2P2_DP<19>")
	)
	(segment
		(start 251.780548 -353.703128)
		(end 252.090682 -354.14585)
		(width 0.14732)
		(layer "In11.Cu")
		(net "UPI_CPU1_CPU0_P2P2_DP<19>")
	)
	(segment
		(start 102.858824 -297.478958)
		(end 102.858824 -292.683692)
		(width 0.14732)
		(layer "In11.Cu")
		(net "UPI_CPU1_CPU0_P2P2_DP<19>")
	)
	(segment
		(start 244.42166 -359.893108)
		(end 243.751354 -360.3625)
		(width 0.14732)
		(layer "In11.Cu")
		(net "UPI_CPU1_CPU0_P2P2_DP<19>")
	)
	(segment
		(start 337.700112 -288.103056)
		(end 337.700112 -288.11728)
		(width 0.0889)
		(layer "In11.Cu")
		(net "UPI_CPU1_CPU0_P2P2_DP<19>")
	)
	(segment
		(start 240.700306 -362.12399)
		(end 240.624868 -362.552488)
		(width 0.14732)
		(layer "In11.Cu")
		(net "UPI_CPU1_CPU0_P2P2_DP<19>")
	)
	(segment
		(start 258.753102 -347.023944)
		(end 258.145026 -347.63202)
		(width 0.14732)
		(layer "In11.Cu")
		(net "UPI_CPU1_CPU0_P2P2_DP<19>")
	)
	(segment
		(start 265.286744 -340.054438)
		(end 264.2362 -339.003894)
		(width 0.14732)
		(layer "In11.Cu")
		(net "UPI_CPU1_CPU0_P2P2_DP<19>")
	)
	(segment
		(start 304.883312 -322.081398)
		(end 302.592232 -323.744082)
		(width 0.14732)
		(layer "In11.Cu")
		(net "UPI_CPU1_CPU0_P2P2_DP<19>")
	)
	(segment
		(start 337.605116 -282.405836)
		(end 337.292442 -282.405836)
		(width 0.0889)
		(layer "In11.Cu")
		(net "UPI_CPU1_CPU0_P2P2_DP<19>")
	)
	(segment
		(start 103.624888 -291.917628)
		(end 103.624888 -291.496496)
		(width 0.14732)
		(layer "In11.Cu")
		(net "UPI_CPU1_CPU0_P2P2_DP<19>")
	)
	(segment
		(start 337.89493 -287.77438)
		(end 337.890358 -287.77692)
		(width 0.0889)
		(layer "In11.Cu")
		(net "UPI_CPU1_CPU0_P2P2_DP<19>")
	)
	(segment
		(start 234.259374 -367.01095)
		(end 233.830876 -366.935512)
		(width 0.14732)
		(layer "In11.Cu")
		(net "UPI_CPU1_CPU0_P2P2_DP<19>")
	)
	(segment
		(start 239.21593 -362.50372)
		(end 239.011206 -362.467398)
		(width 0.14732)
		(layer "In11.Cu")
		(net "UPI_CPU1_CPU0_P2P2_DP<19>")
	)
	(segment
		(start 103.666798 -290.533328)
		(end 103.567738 -290.434268)
		(width 0.0889)
		(layer "In11.Cu")
		(net "UPI_CPU1_CPU0_P2P2_DP<19>")
	)
	(segment
		(start 250.116848 -355.904038)
		(end 249.446542 -356.37343)
		(width 0.14732)
		(layer "In11.Cu")
		(net "UPI_CPU1_CPU0_P2P2_DP<19>")
	)
	(segment
		(start 274.260818 -332.090268)
		(end 273.53133 -331.36078)
		(width 0.14732)
		(layer "In11.Cu")
		(net "UPI_CPU1_CPU0_P2P2_DP<19>")
	)
	(segment
		(start 265.722608 -340.054438)
		(end 265.286744 -340.054438)
		(width 0.14732)
		(layer "In11.Cu")
		(net "UPI_CPU1_CPU0_P2P2_DP<19>")
	)
	(segment
		(start 309.761128 -316.382654)
		(end 307.982874 -318.160908)
		(width 0.14732)
		(layer "In11.Cu")
		(net "UPI_CPU1_CPU0_P2P2_DP<19>")
	)
	(segment
		(start 300.5074 -324.607936)
		(end 299.439584 -325.050658)
		(width 0.14732)
		(layer "In11.Cu")
		(net "UPI_CPU1_CPU0_P2P2_DP<19>")
	)
	(segment
		(start 264.2362 -339.003894)
		(end 264.028428 -339.003894)
		(width 0.14732)
		(layer "In11.Cu")
		(net "UPI_CPU1_CPU0_P2P2_DP<19>")
	)
	(segment
		(start 103.666798 -290.157408)
		(end 103.666798 -289.752532)
		(width 0.0889)
		(layer "In11.Cu")
		(net "UPI_CPU1_CPU0_P2P2_DP<19>")
	)
	(segment
		(start 265.249406 -337.990688)
		(end 266.29995 -339.041232)
		(width 0.14732)
		(layer "In11.Cu")
		(net "UPI_CPU1_CPU0_P2P2_DP<19>")
	)
	(segment
		(start 271.609312 -334.741774)
		(end 271.609312 -335.177638)
		(width 0.14732)
		(layer "In11.Cu")
		(net "UPI_CPU1_CPU0_P2P2_DP<19>")
	)
	(segment
		(start 126.214886 -376.85345)
		(end 98.923094 -372.805198)
		(width 0.14732)
		(layer "In11.Cu")
		(net "UPI_CPU1_CPU0_P2P2_DP<19>")
	)
	(segment
		(start 235.214414 -365.126778)
		(end 234.731306 -365.46536)
		(width 0.14732)
		(layer "In11.Cu")
		(net "UPI_CPU1_CPU0_P2P2_DP<19>")
	)
	(segment
		(start 312.352182 -315.486796)
		(end 311.571132 -315.486796)
		(width 0.14732)
		(layer "In11.Cu")
		(net "UPI_CPU1_CPU0_P2P2_DP<19>")
	)
	(segment
		(start 238.726472 -363.882178)
		(end 238.056166 -364.35157)
		(width 0.14732)
		(layer "In11.Cu")
		(net "UPI_CPU1_CPU0_P2P2_DP<19>")
	)
	(segment
		(start 334.603852 -291.48786)
		(end 332.96987 -293.121842)
		(width 0.14732)
		(layer "In11.Cu")
		(net "UPI_CPU1_CPU0_P2P2_DP<19>")
	)
	(segment
		(start 337.700112 -283.197808)
		(end 337.700112 -283.219906)
		(width 0.0889)
		(layer "In11.Cu")
		(net "UPI_CPU1_CPU0_P2P2_DP<19>")
	)
	(segment
		(start 269.000224 -336.776822)
		(end 268.56436 -336.776822)
		(width 0.14732)
		(layer "In11.Cu")
		(net "UPI_CPU1_CPU0_P2P2_DP<19>")
	)
	(segment
		(start 337.899756 -287.771586)
		(end 337.895692 -287.773872)
		(width 0.0889)
		(layer "In11.Cu")
		(net "UPI_CPU1_CPU0_P2P2_DP<19>")
	)
	(segment
		(start 233.106722 -367.44275)
		(end 233.031284 -367.871248)
		(width 0.14732)
		(layer "In11.Cu")
		(net "UPI_CPU1_CPU0_P2P2_DP<19>")
	)
	(segment
		(start 337.271868 -289.666172)
		(end 336.048858 -290.889182)
		(width 0.14732)
		(layer "In11.Cu")
		(net "UPI_CPU1_CPU0_P2P2_DP<19>")
	)
	(segment
		(start 249.018044 -356.297992)
		(end 248.70791 -355.85527)
		(width 0.14732)
		(layer "In11.Cu")
		(net "UPI_CPU1_CPU0_P2P2_DP<19>")
	)
	(segment
		(start 238.491776 -363.010958)
		(end 238.80191 -363.45368)
		(width 0.14732)
		(layer "In11.Cu")
		(net "UPI_CPU1_CPU0_P2P2_DP<19>")
	)
	(segment
		(start 273.323304 -331.36078)
		(end 272.905474 -331.77861)
		(width 0.14732)
		(layer "In11.Cu")
		(net "UPI_CPU1_CPU0_P2P2_DP<19>")
	)
	(segment
		(start 338.639912 -286.453326)
		(end 338.639912 -286.490918)
		(width 0.0889)
		(layer "In11.Cu")
		(net "UPI_CPU1_CPU0_P2P2_DP<19>")
	)
	(segment
		(start 255.360678 -351.470214)
		(end 254.925322 -351.470214)
		(width 0.14732)
		(layer "In11.Cu")
		(net "UPI_CPU1_CPU0_P2P2_DP<19>")
	)
	(segment
		(start 254.925322 -351.470214)
		(end 254.817372 -351.362264)
		(width 0.14732)
		(layer "In11.Cu")
		(net "UPI_CPU1_CPU0_P2P2_DP<19>")
	)
	(segment
		(start 266.29995 -339.477096)
		(end 265.722608 -340.054438)
		(width 0.14732)
		(layer "In11.Cu")
		(net "UPI_CPU1_CPU0_P2P2_DP<19>")
	)
	(segment
		(start 240.909602 -361.137708)
		(end 240.426494 -361.47629)
		(width 0.14732)
		(layer "In11.Cu")
		(net "UPI_CPU1_CPU0_P2P2_DP<19>")
	)
	(segment
		(start 245.221252 -358.957372)
		(end 244.911118 -358.51465)
		(width 0.14732)
		(layer "In11.Cu")
		(net "UPI_CPU1_CPU0_P2P2_DP<19>")
	)
	(segment
		(start 263.54405 -343.459308)
		(end 262.965692 -344.037666)
		(width 0.14732)
		(layer "In11.Cu")
		(net "UPI_CPU1_CPU0_P2P2_DP<19>")
	)
	(segment
		(start 236.828076 -365.211868)
		(end 236.15777 -365.68126)
		(width 0.14732)
		(layer "In11.Cu")
		(net "UPI_CPU1_CPU0_P2P2_DP<19>")
	)
	(segment
		(start 262.238998 -343.746328)
		(end 262.030718 -343.746328)
		(width 0.14732)
		(layer "In11.Cu")
		(net "UPI_CPU1_CPU0_P2P2_DP<19>")
	)
	(segment
		(start 103.567738 -290.810188)
		(end 103.666798 -290.711128)
		(width 0.0889)
		(layer "In11.Cu")
		(net "UPI_CPU1_CPU0_P2P2_DP<19>")
	)
	(segment
		(start 250.91644 -354.968302)
		(end 250.606306 -354.52558)
		(width 0.14732)
		(layer "In11.Cu")
		(net "UPI_CPU1_CPU0_P2P2_DP<19>")
	)
	(segment
		(start 240.426494 -361.47629)
		(end 240.390172 -361.681268)
		(width 0.14732)
		(layer "In11.Cu")
		(net "UPI_CPU1_CPU0_P2P2_DP<19>")
	)
	(segment
		(start 78.44536 -364.322106)
		(end 75.887072 -361.763818)
		(width 0.14732)
		(layer "In11.Cu")
		(net "UPI_CPU1_CPU0_P2P2_DP<19>")
	)
	(segment
		(start 332.96987 -293.121842)
		(end 332.573122 -293.715694)
		(width 0.14732)
		(layer "In11.Cu")
		(net "UPI_CPU1_CPU0_P2P2_DP<19>")
	)
	(segment
		(start 259.975096 -345.80195)
		(end 259.975096 -346.01023)
		(width 0.14732)
		(layer "In11.Cu")
		(net "UPI_CPU1_CPU0_P2P2_DP<19>")
	)
	(segment
		(start 299.439584 -325.050658)
		(end 285.24327 -325.050658)
		(width 0.14732)
		(layer "In11.Cu")
		(net "UPI_CPU1_CPU0_P2P2_DP<19>")
	)
	(segment
		(start 337.890358 -287.77692)
		(end 337.878674 -287.783778)
		(width 0.0889)
		(layer "In11.Cu")
		(net "UPI_CPU1_CPU0_P2P2_DP<19>")
	)
	(segment
		(start 273.635216 -333.151734)
		(end 272.670778 -334.116172)
		(width 0.14732)
		(layer "In11.Cu")
		(net "UPI_CPU1_CPU0_P2P2_DP<19>")
	)
	(segment
		(start 249.882152 -355.032818)
		(end 250.192286 -355.47554)
		(width 0.14732)
		(layer "In11.Cu")
		(net "UPI_CPU1_CPU0_P2P2_DP<19>")
	)
	(segment
		(start 241.852958 -361.69219)
		(end 241.42446 -361.616752)
		(width 0.14732)
		(layer "In11.Cu")
		(net "UPI_CPU1_CPU0_P2P2_DP<19>")
	)
	(segment
		(start 103.666798 -291.087048)
		(end 103.567738 -290.987988)
		(width 0.0889)
		(layer "In11.Cu")
		(net "UPI_CPU1_CPU0_P2P2_DP<19>")
	)
	(segment
		(start 244.911118 -358.51465)
		(end 244.706394 -358.478328)
		(width 0.14732)
		(layer "In11.Cu")
		(net "UPI_CPU1_CPU0_P2P2_DP<19>")
	)
	(segment
		(start 72.886062 -328.949558)
		(end 73.463912 -326.862694)
		(width 0.14732)
		(layer "In11.Cu")
		(net "UPI_CPU1_CPU0_P2P2_DP<19>")
	)
	(segment
		(start 260.266434 -346.301568)
		(end 260.266434 -346.736924)
		(width 0.14732)
		(layer "In11.Cu")
		(net "UPI_CPU1_CPU0_P2P2_DP<19>")
	)
	(segment
		(start 260.60019 -345.385136)
		(end 260.39191 -345.385136)
		(width 0.14732)
		(layer "In11.Cu")
		(net "UPI_CPU1_CPU0_P2P2_DP<19>")
	)
	(segment
		(start 270.773652 -332.65491)
		(end 270.56588 -332.65491)
		(width 0.14732)
		(layer "In11.Cu")
		(net "UPI_CPU1_CPU0_P2P2_DP<19>")
	)
	(segment
		(start 232.83291 -366.79505)
		(end 232.796588 -367.000028)
		(width 0.14732)
		(layer "In11.Cu")
		(net "UPI_CPU1_CPU0_P2P2_DP<19>")
	)
	(segment
		(start 247.983756 -356.362508)
		(end 248.29389 -356.80523)
		(width 0.14732)
		(layer "In11.Cu")
		(net "UPI_CPU1_CPU0_P2P2_DP<19>")
	)
	(segment
		(start 332.573122 -293.715694)
		(end 330.608178 -300.193202)
		(width 0.14732)
		(layer "In11.Cu")
		(net "UPI_CPU1_CPU0_P2P2_DP<19>")
	)
	(segment
		(start 234.731306 -365.46536)
		(end 234.694984 -365.670338)
		(width 0.14732)
		(layer "In11.Cu")
		(net "UPI_CPU1_CPU0_P2P2_DP<19>")
	)
	(segment
		(start 103.624888 -291.496496)
		(end 103.624888 -291.474398)
		(width 0.0889)
		(layer "In11.Cu")
		(net "UPI_CPU1_CPU0_P2P2_DP<19>")
	)
	(segment
		(start 247.548146 -357.70312)
		(end 247.119648 -357.627682)
		(width 0.14732)
		(layer "In11.Cu")
		(net "UPI_CPU1_CPU0_P2P2_DP<19>")
	)
	(segment
		(start 258.145026 -347.63202)
		(end 258.145026 -347.825822)
		(width 0.14732)
		(layer "In11.Cu")
		(net "UPI_CPU1_CPU0_P2P2_DP<19>")
	)
	(segment
		(start 338.348574 -284.353)
		(end 338.357464 -284.35808)
		(width 0.0889)
		(layer "In11.Cu")
		(net "UPI_CPU1_CPU0_P2P2_DP<19>")
	)
	(segment
		(start 267.361416 -338.41563)
		(end 266.925552 -338.41563)
		(width 0.14732)
		(layer "In11.Cu")
		(net "UPI_CPU1_CPU0_P2P2_DP<19>")
	)
	(segment
		(start 236.15777 -365.68126)
		(end 235.729272 -365.605822)
		(width 0.14732)
		(layer "In11.Cu")
		(net "UPI_CPU1_CPU0_P2P2_DP<19>")
	)
	(segment
		(start 273.635216 -332.71587)
		(end 273.635216 -333.151734)
		(width 0.14732)
		(layer "In11.Cu")
		(net "UPI_CPU1_CPU0_P2P2_DP<19>")
	)
	(segment
		(start 264.661142 -340.68004)
		(end 264.661142 -341.115904)
		(width 0.14732)
		(layer "In11.Cu")
		(net "UPI_CPU1_CPU0_P2P2_DP<19>")
	)
	(segment
		(start 252.015244 -354.574348)
		(end 251.344938 -355.04374)
		(width 0.14732)
		(layer "In11.Cu")
		(net "UPI_CPU1_CPU0_P2P2_DP<19>")
	)
	(segment
		(start 212.31225 -372.160292)
		(end 200.018396 -369.992402)
		(width 0.14732)
		(layer "In11.Cu")
		(net "UPI_CPU1_CPU0_P2P2_DP<19>")
	)
	(segment
		(start 267.938758 -337.402424)
		(end 267.938758 -337.838288)
		(width 0.14732)
		(layer "In11.Cu")
		(net "UPI_CPU1_CPU0_P2P2_DP<19>")
	)
	(segment
		(start 103.948992 -287.613598)
		(end 103.950008 -287.61309)
		(width 0.0889)
		(layer "In11.Cu")
		(net "UPI_CPU1_CPU0_P2P2_DP<19>")
	)
	(segment
		(start 337.229958 -288.917126)
		(end 337.229958 -289.262058)
		(width 0.0889)
		(layer "In11.Cu")
		(net "UPI_CPU1_CPU0_P2P2_DP<19>")
	)
	(segment
		(start 256.999486 -349.831406)
		(end 256.56413 -349.831406)
		(width 0.14732)
		(layer "In11.Cu")
		(net "UPI_CPU1_CPU0_P2P2_DP<19>")
	)
	(segment
		(start 261.905242 -344.66276)
		(end 261.905242 -345.098116)
		(width 0.14732)
		(layer "In11.Cu")
		(net "UPI_CPU1_CPU0_P2P2_DP<19>")
	)
	(segment
		(start 233.520742 -366.49279)
		(end 233.316018 -366.456468)
		(width 0.14732)
		(layer "In11.Cu")
		(net "UPI_CPU1_CPU0_P2P2_DP<19>")
	)
	(segment
		(start 104.418384 -285.172404)
		(end 104.419146 -285.171896)
		(width 0.0889)
		(layer "In11.Cu")
		(net "UPI_CPU1_CPU0_P2P2_DP<19>")
	)
	(segment
		(start 105.328212 -282.948888)
		(end 105.171748 -283.219906)
		(width 0.0889)
		(layer "In11.Cu")
		(net "UPI_CPU1_CPU0_P2P2_DP<19>")
	)
	(segment
		(start 251.344938 -355.04374)
		(end 250.91644 -354.968302)
		(width 0.14732)
		(layer "In11.Cu")
		(net "UPI_CPU1_CPU0_P2P2_DP<19>")
	)
	(segment
		(start 229.497128 -369.131088)
		(end 212.31225 -372.160292)
		(width 0.14732)
		(layer "In11.Cu")
		(net "UPI_CPU1_CPU0_P2P2_DP<19>")
	)
	(segment
		(start 338.356702 -286.96539)
		(end 338.348828 -286.969962)
		(width 0.0889)
		(layer "In11.Cu")
		(net "UPI_CPU1_CPU0_P2P2_DP<19>")
	)
	(segment
		(start 238.80191 -363.45368)
		(end 238.726472 -363.882178)
		(width 0.14732)
		(layer "In11.Cu")
		(net "UPI_CPU1_CPU0_P2P2_DP<19>")
	)
	(segment
		(start 264.028428 -339.003894)
		(end 263.610598 -339.421724)
		(width 0.14732)
		(layer "In11.Cu")
		(net "UPI_CPU1_CPU0_P2P2_DP<19>")
	)
	(segment
		(start 279.603708 -326.059038)
		(end 278.982932 -326.679814)
		(width 0.14732)
		(layer "In11.Cu")
		(net "UPI_CPU1_CPU0_P2P2_DP<19>")
	)
	(segment
		(start 75.887072 -361.763818)
		(end 72.274938 -353.051872)
		(width 0.14732)
		(layer "In11.Cu")
		(net "UPI_CPU1_CPU0_P2P2_DP<19>")
	)
	(segment
		(start 246.08536 -357.692198)
		(end 246.395494 -358.13492)
		(width 0.14732)
		(layer "In11.Cu")
		(net "UPI_CPU1_CPU0_P2P2_DP<19>")
	)
	(segment
		(start 235.729272 -365.605822)
		(end 235.419138 -365.1631)
		(width 0.14732)
		(layer "In11.Cu")
		(net "UPI_CPU1_CPU0_P2P2_DP<19>")
	)
	(segment
		(start 305.48834 -321.47637)
		(end 304.883312 -322.081398)
		(width 0.14732)
		(layer "In11.Cu")
		(net "UPI_CPU1_CPU0_P2P2_DP<19>")
	)
	(segment
		(start 232.796588 -367.000028)
		(end 233.106722 -367.44275)
		(width 0.14732)
		(layer "In11.Cu")
		(net "UPI_CPU1_CPU0_P2P2_DP<19>")
	)
	(segment
		(start 98.923094 -372.805198)
		(end 78.44536 -364.322106)
		(width 0.14732)
		(layer "In11.Cu")
		(net "UPI_CPU1_CPU0_P2P2_DP<19>")
	)
	(segment
		(start 232.360978 -368.34064)
		(end 231.93248 -368.265202)
		(width 0.14732)
		(layer "In11.Cu")
		(net "UPI_CPU1_CPU0_P2P2_DP<19>")
	)
	(segment
		(start 103.666798 -288.103056)
		(end 103.666798 -288.087562)
		(width 0.0889)
		(layer "In11.Cu")
		(net "UPI_CPU1_CPU0_P2P2_DP<19>")
	)
	(segment
		(start 104.606344 -284.856174)
		(end 104.606344 -284.837632)
		(width 0.0889)
		(layer "In11.Cu")
		(net "UPI_CPU1_CPU0_P2P2_DP<19>")
	)
	(segment
		(start 252.090682 -354.14585)
		(end 252.015244 -354.574348)
		(width 0.14732)
		(layer "In11.Cu")
		(net "UPI_CPU1_CPU0_P2P2_DP<19>")
	)
	(segment
		(start 256.56413 -349.831406)
		(end 256.45618 -349.723456)
		(width 0.14732)
		(layer "In11.Cu")
		(net "UPI_CPU1_CPU0_P2P2_DP<19>")
	)
	(segment
		(start 274.696682 -332.090268)
		(end 274.260818 -332.090268)
		(width 0.14732)
		(layer "In11.Cu")
		(net "UPI_CPU1_CPU0_P2P2_DP<19>")
	)
	(segment
		(start 249.918474 -354.82784)
		(end 249.882152 -355.032818)
		(width 0.14732)
		(layer "In11.Cu")
		(net "UPI_CPU1_CPU0_P2P2_DP<19>")
	)
	(segment
		(start 305.850798 -318.962024)
		(end 305.850798 -320.601594)
		(width 0.14732)
		(layer "In11.Cu")
		(net "UPI_CPU1_CPU0_P2P2_DP<19>")
	)
	(segment
		(start 243.322856 -360.287062)
		(end 243.012722 -359.84434)
		(width 0.14732)
		(layer "In11.Cu")
		(net "UPI_CPU1_CPU0_P2P2_DP<19>")
	)
	(segment
		(start 250.192286 -355.47554)
		(end 250.116848 -355.904038)
		(width 0.14732)
		(layer "In11.Cu")
		(net "UPI_CPU1_CPU0_P2P2_DP<19>")
	)
	(segment
		(start 260.39191 -345.385136)
		(end 259.975096 -345.80195)
		(width 0.14732)
		(layer "In11.Cu")
		(net "UPI_CPU1_CPU0_P2P2_DP<19>")
	)
	(segment
		(start 260.891528 -345.676474)
		(end 260.60019 -345.385136)
		(width 0.14732)
		(layer "In11.Cu")
		(net "UPI_CPU1_CPU0_P2P2_DP<19>")
	)
	(segment
		(start 337.292442 -282.405836)
		(end 337.235038 -282.46324)
		(width 0.0889)
		(layer "In11.Cu")
		(net "UPI_CPU1_CPU0_P2P2_DP<19>")
	)
	(segment
		(start 237.317534 -363.83341)
		(end 237.11281 -363.797088)
		(width 0.14732)
		(layer "In11.Cu")
		(net "UPI_CPU1_CPU0_P2P2_DP<19>")
	)
	(segment
		(start 338.356702 -285.337504)
		(end 338.348828 -285.342076)
		(width 0.0889)
		(layer "In11.Cu")
		(net "UPI_CPU1_CPU0_P2P2_DP<19>")
	)
	(segment
		(start 231.622346 -367.82248)
		(end 231.417368 -367.786158)
		(width 0.14732)
		(layer "In11.Cu")
		(net "UPI_CPU1_CPU0_P2P2_DP<19>")
	)
	(segment
		(start 243.751354 -360.3625)
		(end 243.322856 -360.287062)
		(width 0.14732)
		(layer "In11.Cu")
		(net "UPI_CPU1_CPU0_P2P2_DP<19>")
	)
	(segment
		(start 103.567738 -290.256468)
		(end 103.666798 -290.157408)
		(width 0.0889)
		(layer "In11.Cu")
		(net "UPI_CPU1_CPU0_P2P2_DP<19>")
	)
	(segment
		(start 234.694984 -365.670338)
		(end 235.005118 -366.11306)
		(width 0.14732)
		(layer "In11.Cu")
		(net "UPI_CPU1_CPU0_P2P2_DP<19>")
	)
	(segment
		(start 313.994038 -313.84494)
		(end 312.352182 -315.486796)
		(width 0.14732)
		(layer "In11.Cu")
		(net "UPI_CPU1_CPU0_P2P2_DP<19>")
	)
	(segment
		(start 259.975096 -346.01023)
		(end 260.266434 -346.301568)
		(width 0.14732)
		(layer "In11.Cu")
		(net "UPI_CPU1_CPU0_P2P2_DP<19>")
	)
	(segment
		(start 338.357718 -285.336996)
		(end 338.356702 -285.337504)
		(width 0.0889)
		(layer "In11.Cu")
		(net "UPI_CPU1_CPU0_P2P2_DP<19>")
	)
	(segment
		(start 102.858824 -292.683692)
		(end 103.624888 -291.917628)
		(width 0.14732)
		(layer "In11.Cu")
		(net "UPI_CPU1_CPU0_P2P2_DP<19>")
	)
	(segment
		(start 262.530336 -344.037666)
		(end 262.238998 -343.746328)
		(width 0.14732)
		(layer "In11.Cu")
		(net "UPI_CPU1_CPU0_P2P2_DP<19>")
	)
	(segment
		(start 242.598702 -360.7943)
		(end 242.523264 -361.222798)
		(width 0.14732)
		(layer "In11.Cu")
		(net "UPI_CPU1_CPU0_P2P2_DP<19>")
	)
	(segment
		(start 238.056166 -364.35157)
		(end 237.627668 -364.276132)
		(width 0.14732)
		(layer "In11.Cu")
		(net "UPI_CPU1_CPU0_P2P2_DP<19>")
	)
	(segment
		(start 263.252712 -342.524334)
		(end 263.252712 -342.732614)
		(width 0.14732)
		(layer "In11.Cu")
		(net "UPI_CPU1_CPU0_P2P2_DP<19>")
	)
	(segment
		(start 103.567738 -290.434268)
		(end 103.567738 -290.256468)
		(width 0.0889)
		(layer "In11.Cu")
		(net "UPI_CPU1_CPU0_P2P2_DP<19>")
	)
	(segment
		(start 233.031284 -367.871248)
		(end 232.360978 -368.34064)
		(width 0.14732)
		(layer "In11.Cu")
		(net "UPI_CPU1_CPU0_P2P2_DP<19>")
	)
	(segment
		(start 72.274938 -353.051872)
		(end 72.274938 -335.157064)
		(width 0.14732)
		(layer "In11.Cu")
		(net "UPI_CPU1_CPU0_P2P2_DP<19>")
	)
	(segment
		(start 302.592232 -323.744082)
		(end 300.5074 -324.607936)
		(width 0.14732)
		(layer "In11.Cu")
		(net "UPI_CPU1_CPU0_P2P2_DP<19>")
	)
	(segment
		(start 261.905242 -345.098116)
		(end 261.326884 -345.676474)
		(width 0.14732)
		(layer "In11.Cu")
		(net "UPI_CPU1_CPU0_P2P2_DP<19>")
	)
	(segment
		(start 273.53133 -331.36078)
		(end 273.323304 -331.36078)
		(width 0.14732)
		(layer "In11.Cu")
		(net "UPI_CPU1_CPU0_P2P2_DP<19>")
	)
	(segment
		(start 270.840962 -335.945988)
		(end 269.831058 -335.945988)
		(width 0.14732)
		(layer "In11.Cu")
		(net "UPI_CPU1_CPU0_P2P2_DP<19>")
	)
	(segment
		(start 266.29995 -339.041232)
		(end 266.29995 -339.477096)
		(width 0.14732)
		(layer "In11.Cu")
		(net "UPI_CPU1_CPU0_P2P2_DP<19>")
	)
	(segment
		(start 103.950008 -287.61309)
		(end 103.957882 -287.608518)
		(width 0.0889)
		(layer "In11.Cu")
		(net "UPI_CPU1_CPU0_P2P2_DP<19>")
	)
	(segment
		(start 258.961382 -347.023944)
		(end 258.753102 -347.023944)
		(width 0.14732)
		(layer "In11.Cu")
		(net "UPI_CPU1_CPU0_P2P2_DP<19>")
	)
	(segment
		(start 105.35285 -283.54782)
		(end 105.358184 -283.544772)
		(width 0.0889)
		(layer "In11.Cu")
		(net "UPI_CPU1_CPU0_P2P2_DP<19>")
	)
	(segment
		(start 307.982874 -318.160908)
		(end 306.450746 -318.160908)
		(width 0.14732)
		(layer "In11.Cu")
		(net "UPI_CPU1_CPU0_P2P2_DP<19>")
	)
	(segment
		(start 249.446542 -356.37343)
		(end 249.018044 -356.297992)
		(width 0.14732)
		(layer "In11.Cu")
		(net "UPI_CPU1_CPU0_P2P2_DP<19>")
	)
	(segment
		(start 263.54405 -343.023952)
		(end 263.54405 -343.459308)
		(width 0.14732)
		(layer "In11.Cu")
		(net "UPI_CPU1_CPU0_P2P2_DP<19>")
	)
	(segment
		(start 337.895692 -287.773872)
		(end 337.89493 -287.77438)
		(width 0.0889)
		(layer "In11.Cu")
		(net "UPI_CPU1_CPU0_P2P2_DP<19>")
	)
	(segment
		(start 246.60479 -357.148638)
		(end 246.121682 -357.48722)
		(width 0.14732)
		(layer "In11.Cu")
		(net "UPI_CPU1_CPU0_P2P2_DP<19>")
	)
	(segment
		(start 268.56436 -336.776822)
		(end 267.513816 -335.726278)
		(width 0.14732)
		(layer "In11.Cu")
		(net "UPI_CPU1_CPU0_P2P2_DP<19>")
	)
	(segment
		(start 261.613904 -344.163142)
		(end 261.613904 -344.371422)
		(width 0.14732)
		(layer "In11.Cu")
		(net "UPI_CPU1_CPU0_P2P2_DP<19>")
	)
	(segment
		(start 311.571132 -315.486796)
		(end 310.675274 -316.382654)
		(width 0.14732)
		(layer "In11.Cu")
		(net "UPI_CPU1_CPU0_P2P2_DP<19>")
	)
	(segment
		(start 235.005118 -366.11306)
		(end 234.92968 -366.541558)
		(width 0.14732)
		(layer "In11.Cu")
		(net "UPI_CPU1_CPU0_P2P2_DP<19>")
	)
	(segment
		(start 241.114326 -361.17403)
		(end 240.909602 -361.137708)
		(width 0.14732)
		(layer "In11.Cu")
		(net "UPI_CPU1_CPU0_P2P2_DP<19>")
	)
	(segment
		(start 239.526064 -362.946442)
		(end 239.21593 -362.50372)
		(width 0.14732)
		(layer "In11.Cu")
		(net "UPI_CPU1_CPU0_P2P2_DP<19>")
	)
	(segment
		(start 254.00127 -351.970086)
		(end 251.81687 -353.49815)
		(width 0.14732)
		(layer "In11.Cu")
		(net "UPI_CPU1_CPU0_P2P2_DP<19>")
	)
	(segment
		(start 260.266434 -346.736924)
		(end 259.688076 -347.315282)
		(width 0.14732)
		(layer "In11.Cu")
		(net "UPI_CPU1_CPU0_P2P2_DP<19>")
	)
	(segment
		(start 236.629702 -364.13567)
		(end 236.59338 -364.340648)
		(width 0.14732)
		(layer "In11.Cu")
		(net "UPI_CPU1_CPU0_P2P2_DP<19>")
	)
	(segment
		(start 267.938758 -337.838288)
		(end 267.361416 -338.41563)
		(width 0.14732)
		(layer "In11.Cu")
		(net "UPI_CPU1_CPU0_P2P2_DP<19>")
	)
	(segment
		(start 242.288568 -360.351578)
		(end 242.598702 -360.7943)
		(width 0.14732)
		(layer "In11.Cu")
		(net "UPI_CPU1_CPU0_P2P2_DP<19>")
	)
	(segment
		(start 337.271868 -289.303968)
		(end 337.271868 -289.326066)
		(width 0.0889)
		(layer "In11.Cu")
		(net "UPI_CPU1_CPU0_P2P2_DP<19>")
	)
	(segment
		(start 338.170012 -284.023816)
		(end 338.170012 -284.033722)
		(width 0.0889)
		(layer "In11.Cu")
		(net "UPI_CPU1_CPU0_P2P2_DP<19>")
	)
	(segment
		(start 231.417368 -367.786158)
		(end 229.497128 -369.131088)
		(width 0.14732)
		(layer "In11.Cu")
		(net "UPI_CPU1_CPU0_P2P2_DP<19>")
	)
	(segment
		(start 310.675274 -316.382654)
		(end 309.761128 -316.382654)
		(width 0.14732)
		(layer "In11.Cu")
		(net "UPI_CPU1_CPU0_P2P2_DP<19>")
	)
	(segment
		(start 239.954562 -363.02188)
		(end 239.526064 -362.946442)
		(width 0.14732)
		(layer "In11.Cu")
		(net "UPI_CPU1_CPU0_P2P2_DP<19>")
	)
	(segment
		(start 246.395494 -358.13492)
		(end 246.320056 -358.563418)
		(width 0.14732)
		(layer "In11.Cu")
		(net "UPI_CPU1_CPU0_P2P2_DP<19>")
	)
	(segment
		(start 103.567738 -290.987988)
		(end 103.567738 -290.810188)
		(width 0.0889)
		(layer "In11.Cu")
		(net "UPI_CPU1_CPU0_P2P2_DP<19>")
	)
	(segment
		(start 278.982932 -326.679814)
		(end 278.982932 -327.804018)
		(width 0.14732)
		(layer "In11.Cu")
		(net "UPI_CPU1_CPU0_P2P2_DP<19>")
	)
	(segment
		(start 271.609312 -335.177638)
		(end 270.840962 -335.945988)
		(width 0.14732)
		(layer "In11.Cu")
		(net "UPI_CPU1_CPU0_P2P2_DP<19>")
	)
	(segment
		(start 337.409028 -282.725114)
		(end 337.417918 -282.730194)
		(width 0.0889)
		(layer "In11.Cu")
		(net "UPI_CPU1_CPU0_P2P2_DP<19>")
	)
	(segment
		(start 257.469894 -348.709742)
		(end 257.577844 -348.817692)
		(width 0.14732)
		(layer "In11.Cu")
		(net "UPI_CPU1_CPU0_P2P2_DP<19>")
	)
	(segment
		(start 246.320056 -358.563418)
		(end 245.64975 -359.03281)
		(width 0.14732)
		(layer "In11.Cu")
		(net "UPI_CPU1_CPU0_P2P2_DP<19>")
	)
	(segment
		(start 237.627668 -364.276132)
		(end 237.317534 -363.83341)
		(width 0.14732)
		(layer "In11.Cu")
		(net "UPI_CPU1_CPU0_P2P2_DP<19>")
	)
	(segment
		(start 240.390172 -361.681268)
		(end 240.700306 -362.12399)
		(width 0.14732)
		(layer "In11.Cu")
		(net "UPI_CPU1_CPU0_P2P2_DP<19>")
	)
	(segment
		(start 233.316018 -366.456468)
		(end 232.83291 -366.79505)
		(width 0.14732)
		(layer "In11.Cu")
		(net "UPI_CPU1_CPU0_P2P2_DP<19>")
	)
	(segment
		(start 270.14805 -333.07274)
		(end 270.14805 -333.280512)
		(width 0.14732)
		(layer "In11.Cu")
		(net "UPI_CPU1_CPU0_P2P2_DP<19>")
	)
	(segment
		(start 272.670778 -334.116172)
		(end 272.234914 -334.116172)
		(width 0.14732)
		(layer "In11.Cu")
		(net "UPI_CPU1_CPU0_P2P2_DP<19>")
	)
	(segment
		(start 103.666798 -291.432488)
		(end 103.666798 -291.087048)
		(width 0.0889)
		(layer "In11.Cu")
		(net "UPI_CPU1_CPU0_P2P2_DP<19>")
	)
	(segment
		(start 270.56588 -332.65491)
		(end 270.14805 -333.07274)
		(width 0.14732)
		(layer "In11.Cu")
		(net "UPI_CPU1_CPU0_P2P2_DP<19>")
	)
	(segment
		(start 104.41305 -285.175452)
		(end 104.418384 -285.172404)
		(width 0.0889)
		(layer "In11.Cu")
		(net "UPI_CPU1_CPU0_P2P2_DP<19>")
	)
	(segment
		(start 265.249406 -337.782916)
		(end 265.249406 -337.990688)
		(width 0.14732)
		(layer "In11.Cu")
		(net "UPI_CPU1_CPU0_P2P2_DP<19>")
	)
	(segment
		(start 272.905474 -331.77861)
		(end 272.905474 -331.986128)
		(width 0.14732)
		(layer "In11.Cu")
		(net "UPI_CPU1_CPU0_P2P2_DP<19>")
	)
	(segment
		(start 234.92968 -366.541558)
		(end 234.259374 -367.01095)
		(width 0.14732)
		(layer "In11.Cu")
		(net "UPI_CPU1_CPU0_P2P2_DP<19>")
	)
	(segment
		(start 285.24327 -325.050658)
		(end 284.23489 -326.059038)
		(width 0.14732)
		(layer "In11.Cu")
		(net "UPI_CPU1_CPU0_P2P2_DP<19>")
	)
	(segment
		(start 231.93248 -368.265202)
		(end 231.622346 -367.82248)
		(width 0.14732)
		(layer "In11.Cu")
		(net "UPI_CPU1_CPU0_P2P2_DP<19>")
	)
	(segment
		(start 337.41741 -288.592768)
		(end 337.40852 -288.597848)
		(width 0.0889)
		(layer "In11.Cu")
		(net "UPI_CPU1_CPU0_P2P2_DP<19>")
	)
	(segment
		(start 272.234914 -334.116172)
		(end 270.773652 -332.65491)
		(width 0.14732)
		(layer "In11.Cu")
		(net "UPI_CPU1_CPU0_P2P2_DP<19>")
	)
	(segment
		(start 242.807998 -359.808018)
		(end 242.32489 -360.1466)
		(width 0.14732)
		(layer "In11.Cu")
		(net "UPI_CPU1_CPU0_P2P2_DP<19>")
	)
	(segment
		(start 266.925552 -338.41563)
		(end 265.875008 -337.365086)
		(width 0.14732)
		(layer "In11.Cu")
		(net "UPI_CPU1_CPU0_P2P2_DP<19>")
	)
	(segment
		(start 103.479346 -288.427414)
		(end 103.483664 -288.424874)
		(width 0.0889)
		(layer "In11.Cu")
		(net "UPI_CPU1_CPU0_P2P2_DP<19>")
	)
	(segment
		(start 255.831086 -350.34855)
		(end 255.939036 -350.4565)
		(width 0.14732)
		(layer "In11.Cu")
		(net "UPI_CPU1_CPU0_P2P2_DP<19>")
	)
	(arc
		(start 338.348828 -285.342076)
		(mid 338.170231 -285.661354)
		(end 338.348828 -285.980632)
		(width 0.0889)
		(layer "In11.Cu")
		(net "UPI_CPU1_CPU0_P2P2_DP<19>")
	)
	(arc
		(start 338.348828 -286.969962)
		(mid 338.217914 -287.106322)
		(end 338.170266 -287.28924)
		(width 0.0889)
		(layer "In11.Cu")
		(net "UPI_CPU1_CPU0_P2P2_DP<19>")
	)
	(arc
		(start 104.427782 -286.794702)
		(mid 104.606379 -286.475424)
		(end 104.427782 -286.156146)
		(width 0.0889)
		(layer "In11.Cu")
		(net "UPI_CPU1_CPU0_P2P2_DP<19>")
	)
	(arc
		(start 337.417918 -282.730194)
		(mid 337.6192 -282.927681)
		(end 337.700112 -283.197808)
		(width 0.0889)
		(layer "In11.Cu")
		(net "UPI_CPU1_CPU0_P2P2_DP<19>")
	)
	(arc
		(start 103.666798 -289.752532)
		(mid 103.617113 -289.573903)
		(end 103.482394 -289.446462)
		(width 0.0889)
		(layer "In11.Cu")
		(net "UPI_CPU1_CPU0_P2P2_DP<19>")
	)
	(arc
		(start 338.357718 -285.985712)
		(mid 338.559 -286.183199)
		(end 338.639912 -286.453326)
		(width 0.0889)
		(layer "In11.Cu")
		(net "UPI_CPU1_CPU0_P2P2_DP<19>")
	)
	(arc
		(start 337.878674 -287.783778)
		(mid 337.74776 -287.920138)
		(end 337.700112 -288.103056)
		(width 0.0889)
		(layer "In11.Cu")
		(net "UPI_CPU1_CPU0_P2P2_DP<19>")
	)
	(arc
		(start 104.606344 -284.837632)
		(mid 104.684455 -284.560683)
		(end 104.888792 -284.35808)
		(width 0.0889)
		(layer "In11.Cu")
		(net "UPI_CPU1_CPU0_P2P2_DP<19>")
	)
	(arc
		(start 104.136444 -287.28924)
		(mid 104.21036 -287.009738)
		(end 104.412796 -286.803338)
		(width 0.0889)
		(layer "In11.Cu")
		(net "UPI_CPU1_CPU0_P2P2_DP<19>")
	)
	(arc
		(start 103.666798 -288.087562)
		(mid 103.746168 -287.813828)
		(end 103.948992 -287.613598)
		(width 0.0889)
		(layer "In11.Cu")
		(net "UPI_CPU1_CPU0_P2P2_DP<19>")
	)
	(arc
		(start 103.957882 -287.608518)
		(mid 104.088796 -287.472158)
		(end 104.136444 -287.28924)
		(width 0.0889)
		(layer "In11.Cu")
		(net "UPI_CPU1_CPU0_P2P2_DP<19>")
	)
	(arc
		(start 104.897682 -284.353)
		(mid 105.028596 -284.21664)
		(end 105.076244 -284.033722)
		(width 0.0889)
		(layer "In11.Cu")
		(net "UPI_CPU1_CPU0_P2P2_DP<19>")
	)
	(arc
		(start 103.482394 -289.446462)
		(mid 103.308262 -289.307615)
		(end 103.196898 -289.114738)
		(width 0.0889)
		(layer "In11.Cu")
		(net "UPI_CPU1_CPU0_P2P2_DP<19>")
	)
	(arc
		(start 338.170012 -284.033722)
		(mid 338.217691 -284.216622)
		(end 338.348574 -284.353)
		(width 0.0889)
		(layer "In11.Cu")
		(net "UPI_CPU1_CPU0_P2P2_DP<19>")
	)
	(arc
		(start 337.235038 -282.46324)
		(mid 337.293194 -282.613353)
		(end 337.409028 -282.725114)
		(width 0.0889)
		(layer "In11.Cu")
		(net "UPI_CPU1_CPU0_P2P2_DP<19>")
	)
	(arc
		(start 338.170266 -287.28924)
		(mid 338.098031 -287.565764)
		(end 337.899756 -287.771586)
		(width 0.0889)
		(layer "In11.Cu")
		(net "UPI_CPU1_CPU0_P2P2_DP<19>")
	)
	(arc
		(start 103.196898 -288.898584)
		(mid 103.27706 -288.626395)
		(end 103.479346 -288.427414)
		(width 0.0889)
		(layer "In11.Cu")
		(net "UPI_CPU1_CPU0_P2P2_DP<19>")
	)
	(arc
		(start 337.40852 -288.597848)
		(mid 337.277606 -288.734208)
		(end 337.229958 -288.917126)
		(width 0.0889)
		(layer "In11.Cu")
		(net "UPI_CPU1_CPU0_P2P2_DP<19>")
	)
	(arc
		(start 104.418892 -286.151066)
		(mid 104.136243 -285.664963)
		(end 104.41305 -285.175452)
		(width 0.0889)
		(layer "In11.Cu")
		(net "UPI_CPU1_CPU0_P2P2_DP<19>")
	)
	(arc
		(start 105.076244 -284.033722)
		(mid 105.150235 -283.754156)
		(end 105.35285 -283.54782)
		(width 0.0889)
		(layer "In11.Cu")
		(net "UPI_CPU1_CPU0_P2P2_DP<19>")
	)
	(arc
		(start 103.488236 -288.422334)
		(mid 103.61915 -288.285974)
		(end 103.666798 -288.103056)
		(width 0.0889)
		(layer "In11.Cu")
		(net "UPI_CPU1_CPU0_P2P2_DP<19>")
	)
	(arc
		(start 337.700112 -288.11728)
		(mid 337.620893 -288.391965)
		(end 337.41741 -288.592768)
		(width 0.0889)
		(layer "In11.Cu")
		(net "UPI_CPU1_CPU0_P2P2_DP<19>")
	)
	(arc
		(start 337.887564 -283.544264)
		(mid 338.091899 -283.746869)
		(end 338.170012 -284.023816)
		(width 0.0889)
		(layer "In11.Cu")
		(net "UPI_CPU1_CPU0_P2P2_DP<19>")
	)
	(arc
		(start 338.357464 -284.35808)
		(mid 338.639996 -284.847428)
		(end 338.357718 -285.336996)
		(width 0.0889)
		(layer "In11.Cu")
		(net "UPI_CPU1_CPU0_P2P2_DP<19>")
	)
	(arc
		(start 104.419146 -285.171896)
		(mid 104.554079 -285.038542)
		(end 104.606344 -284.856174)
		(width 0.0889)
		(layer "In11.Cu")
		(net "UPI_CPU1_CPU0_P2P2_DP<19>")
	)
	(arc
		(start 337.700112 -283.219906)
		(mid 337.747791 -283.402806)
		(end 337.878674 -283.539184)
		(width 0.0889)
		(layer "In11.Cu")
		(net "UPI_CPU1_CPU0_P2P2_DP<19>")
	)
	(arc
		(start 105.358946 -283.544264)
		(mid 105.545276 -283.248588)
		(end 105.40619 -282.92806)
		(width 0.0889)
		(layer "In11.Cu")
		(net "UPI_CPU1_CPU0_P2P2_DP<19>")
	)
	(arc
		(start 338.639912 -286.490918)
		(mid 338.560542 -286.764652)
		(end 338.357718 -286.964882)
		(width 0.0889)
		(layer "In11.Cu")
		(net "UPI_CPU1_CPU0_P2P2_DP<19>")
	)
	(segment
		(start 337.134962 -281.591766)
		(end 337.135216 -281.59202)
		(width 0.13208)
		(layer "F.Cu")
		(net "UPI_CPU1_CPU0_P2P2_DP<18>")
	)
	(segment
		(start 103.762048 -281.869896)
		(end 103.762048 -282.405582)
		(width 0.13208)
		(layer "F.Cu")
		(net "UPI_CPU1_CPU0_P2P2_DP<18>")
	)
	(segment
		(start 103.762048 -282.405582)
		(end 103.761794 -282.405836)
		(width 0.13208)
		(layer "F.Cu")
		(net "UPI_CPU1_CPU0_P2P2_DP<18>")
	)
	(segment
		(start 337.134962 -281.05608)
		(end 337.134962 -281.591766)
		(width 0.13208)
		(layer "F.Cu")
		(net "UPI_CPU1_CPU0_P2P2_DP<18>")
	)
	(segment
		(start 244.739414 -362.760006)
		(end 244.77599 -362.555282)
		(width 0.14732)
		(layer "In11.Cu")
		(net "UPI_CPU1_CPU0_P2P2_DP<18>")
	)
	(segment
		(start 312.4581 -316.738254)
		(end 312.752486 -316.443868)
		(width 0.14732)
		(layer "In11.Cu")
		(net "UPI_CPU1_CPU0_P2P2_DP<18>")
	)
	(segment
		(start 339.20176 -285.171896)
		(end 339.21065 -285.166816)
		(width 0.0889)
		(layer "In11.Cu")
		(net "UPI_CPU1_CPU0_P2P2_DP<18>")
	)
	(segment
		(start 337.979766 -289.622738)
		(end 337.880706 -289.523678)
		(width 0.0889)
		(layer "In11.Cu")
		(net "UPI_CPU1_CPU0_P2P2_DP<18>")
	)
	(segment
		(start 309.824374 -317.828676)
		(end 312.4581 -316.738254)
		(width 0.14732)
		(layer "In11.Cu")
		(net "UPI_CPU1_CPU0_P2P2_DP<18>")
	)
	(segment
		(start 284.52191 -327.434702)
		(end 284.918912 -327.27011)
		(width 0.14732)
		(layer "In11.Cu")
		(net "UPI_CPU1_CPU0_P2P2_DP<18>")
	)
	(segment
		(start 234.251246 -368.616738)
		(end 234.287568 -368.412522)
		(width 0.14732)
		(layer "In11.Cu")
		(net "UPI_CPU1_CPU0_P2P2_DP<18>")
	)
	(segment
		(start 337.880706 -289.523678)
		(end 337.880706 -289.345878)
		(width 0.0889)
		(layer "In11.Cu")
		(net "UPI_CPU1_CPU0_P2P2_DP<18>")
	)
	(segment
		(start 236.352842 -368.231166)
		(end 236.557566 -368.267742)
		(width 0.14732)
		(layer "In11.Cu")
		(net "UPI_CPU1_CPU0_P2P2_DP<18>")
	)
	(segment
		(start 253.519686 -354.267262)
		(end 258.412996 -349.373952)
		(width 0.14732)
		(layer "In11.Cu")
		(net "UPI_CPU1_CPU0_P2P2_DP<18>")
	)
	(segment
		(start 334.915002 -291.9603)
		(end 336.300572 -291.38626)
		(width 0.14732)
		(layer "In11.Cu")
		(net "UPI_CPU1_CPU0_P2P2_DP<18>")
	)
	(segment
		(start 243.999258 -360.903012)
		(end 244.669564 -360.435398)
		(width 0.14732)
		(layer "In11.Cu")
		(net "UPI_CPU1_CPU0_P2P2_DP<18>")
	)
	(segment
		(start 126.307596 -377.43003)
		(end 161.425636 -377.43003)
		(width 0.14732)
		(layer "In11.Cu")
		(net "UPI_CPU1_CPU0_P2P2_DP<18>")
	)
	(segment
		(start 339.202776 -286.151574)
		(end 339.20176 -286.151066)
		(width 0.0889)
		(layer "In11.Cu")
		(net "UPI_CPU1_CPU0_P2P2_DP<18>")
	)
	(segment
		(start 337.19643 -290.408868)
		(end 337.32216 -290.283138)
		(width 0.0889)
		(layer "In11.Cu")
		(net "UPI_CPU1_CPU0_P2P2_DP<18>")
	)
	(segment
		(start 239.394492 -364.48873)
		(end 240.155222 -365.579914)
		(width 0.14732)
		(layer "In11.Cu")
		(net "UPI_CPU1_CPU0_P2P2_DP<18>")
	)
	(segment
		(start 244.050058 -363.06125)
		(end 244.254782 -363.097826)
		(width 0.14732)
		(layer "In11.Cu")
		(net "UPI_CPU1_CPU0_P2P2_DP<18>")
	)
	(segment
		(start 242.098068 -362.228638)
		(end 242.768374 -361.761024)
		(width 0.14732)
		(layer "In11.Cu")
		(net "UPI_CPU1_CPU0_P2P2_DP<18>")
	)
	(segment
		(start 73.587356 -357.691182)
		(end 73.587356 -357.69169)
		(width 0.14732)
		(layer "In11.Cu")
		(net "UPI_CPU1_CPU0_P2P2_DP<18>")
	)
	(segment
		(start 332.970886 -294.337232)
		(end 333.84109 -293.033958)
		(width 0.14732)
		(layer "In11.Cu")
		(net "UPI_CPU1_CPU0_P2P2_DP<18>")
	)
	(segment
		(start 102.1842 -297.62577)
		(end 97.612708 -303.789334)
		(width 0.14732)
		(layer "In11.Cu")
		(net "UPI_CPU1_CPU0_P2P2_DP<18>")
	)
	(segment
		(start 250.687586 -357.71836)
		(end 250.170442 -356.976172)
		(width 0.14732)
		(layer "In11.Cu")
		(net "UPI_CPU1_CPU0_P2P2_DP<18>")
	)
	(segment
		(start 238.219234 -365.308388)
		(end 238.295688 -364.87989)
		(width 0.14732)
		(layer "In11.Cu")
		(net "UPI_CPU1_CPU0_P2P2_DP<18>")
	)
	(segment
		(start 235.163614 -367.063528)
		(end 235.592112 -367.139982)
		(width 0.14732)
		(layer "In11.Cu")
		(net "UPI_CPU1_CPU0_P2P2_DP<18>")
	)
	(segment
		(start 243.922804 -361.33151)
		(end 243.999258 -360.903012)
		(width 0.14732)
		(layer "In11.Cu")
		(net "UPI_CPU1_CPU0_P2P2_DP<18>")
	)
	(segment
		(start 292.266116 -327.50506)
		(end 292.266116 -325.91375)
		(width 0.14732)
		(layer "In11.Cu")
		(net "UPI_CPU1_CPU0_P2P2_DP<18>")
	)
	(segment
		(start 283.769816 -326.807322)
		(end 284.171898 -326.973946)
		(width 0.14732)
		(layer "In11.Cu")
		(net "UPI_CPU1_CPU0_P2P2_DP<18>")
	)
	(segment
		(start 246.063516 -361.639612)
		(end 246.548148 -361.301792)
		(width 0.14732)
		(layer "In11.Cu")
		(net "UPI_CPU1_CPU0_P2P2_DP<18>")
	)
	(segment
		(start 337.979766 -289.246818)
		(end 337.979766 -288.917126)
		(width 0.0889)
		(layer "In11.Cu")
		(net "UPI_CPU1_CPU0_P2P2_DP<18>")
	)
	(segment
		(start 292.563804 -325.616062)
		(end 299.55363 -325.616062)
		(width 0.14732)
		(layer "In11.Cu")
		(net "UPI_CPU1_CPU0_P2P2_DP<18>")
	)
	(segment
		(start 247.801638 -358.251506)
		(end 249.016266 -357.405178)
		(width 0.14732)
		(layer "In11.Cu")
		(net "UPI_CPU1_CPU0_P2P2_DP<18>")
	)
	(segment
		(start 305.939952 -321.811904)
		(end 306.526438 -320.639186)
		(width 0.14732)
		(layer "In11.Cu")
		(net "UPI_CPU1_CPU0_P2P2_DP<18>")
	)
	(segment
		(start 337.462622 -290.283138)
		(end 337.588098 -290.157662)
		(width 0.0889)
		(layer "In11.Cu")
		(net "UPI_CPU1_CPU0_P2P2_DP<18>")
	)
	(segment
		(start 291.529516 -327.65238)
		(end 292.118796 -327.65238)
		(width 0.14732)
		(layer "In11.Cu")
		(net "UPI_CPU1_CPU0_P2P2_DP<18>")
	)
	(segment
		(start 200.154286 -370.602002)
		(end 212.31225 -372.746016)
		(width 0.14732)
		(layer "In11.Cu")
		(net "UPI_CPU1_CPU0_P2P2_DP<18>")
	)
	(segment
		(start 337.801204 -282.086812)
		(end 337.79714 -282.084526)
		(width 0.0889)
		(layer "In11.Cu")
		(net "UPI_CPU1_CPU0_P2P2_DP<18>")
	)
	(segment
		(start 250.170442 -356.976172)
		(end 250.24715 -356.54742)
		(width 0.14732)
		(layer "In11.Cu")
		(net "UPI_CPU1_CPU0_P2P2_DP<18>")
	)
	(segment
		(start 270.248126 -337.330542)
		(end 270.456406 -337.330542)
		(width 0.14732)
		(layer "In11.Cu")
		(net "UPI_CPU1_CPU0_P2P2_DP<18>")
	)
	(segment
		(start 282.847288 -327.522586)
		(end 283.013912 -327.120504)
		(width 0.14732)
		(layer "In11.Cu")
		(net "UPI_CPU1_CPU0_P2P2_DP<18>")
	)
	(segment
		(start 305.099212 -322.652136)
		(end 305.939952 -321.811904)
		(width 0.14732)
		(layer "In11.Cu")
		(net "UPI_CPU1_CPU0_P2P2_DP<18>")
	)
	(segment
		(start 336.399632 -291.2872)
		(end 336.45856 -291.2872)
		(width 0.0889)
		(layer "In11.Cu")
		(net "UPI_CPU1_CPU0_P2P2_DP<18>")
	)
	(segment
		(start 73.883774 -324.678548)
		(end 72.92721 -326.701658)
		(width 0.14732)
		(layer "In11.Cu")
		(net "UPI_CPU1_CPU0_P2P2_DP<18>")
	)
	(segment
		(start 316.481968 -314.90158)
		(end 316.742572 -314.640976)
		(width 0.14732)
		(layer "In11.Cu")
		(net "UPI_CPU1_CPU0_P2P2_DP<18>")
	)
	(segment
		(start 304.929286 -322.743322)
		(end 305.099212 -322.652136)
		(width 0.14732)
		(layer "In11.Cu")
		(net "UPI_CPU1_CPU0_P2P2_DP<18>")
	)
	(segment
		(start 242.745768 -363.953044)
		(end 242.782344 -363.74832)
		(width 0.14732)
		(layer "In11.Cu")
		(net "UPI_CPU1_CPU0_P2P2_DP<18>")
	)
	(segment
		(start 339.202776 -286.799274)
		(end 339.21065 -286.794702)
		(width 0.0889)
		(layer "In11.Cu")
		(net "UPI_CPU1_CPU0_P2P2_DP<18>")
	)
	(segment
		(start 245.900448 -359.577386)
		(end 246.570754 -359.109772)
		(width 0.14732)
		(layer "In11.Cu")
		(net "UPI_CPU1_CPU0_P2P2_DP<18>")
	)
	(segment
		(start 299.55363 -325.616062)
		(end 303.827688 -323.845428)
		(width 0.14732)
		(layer "In11.Cu")
		(net "UPI_CPU1_CPU0_P2P2_DP<18>")
	)
	(segment
		(start 234.117642 -368.16792)
		(end 234.194096 -367.739676)
		(width 0.14732)
		(layer "In11.Cu")
		(net "UPI_CPU1_CPU0_P2P2_DP<18>")
	)
	(segment
		(start 232.963212 -368.597688)
		(end 233.39171 -368.674142)
		(width 0.14732)
		(layer "In11.Cu")
		(net "UPI_CPU1_CPU0_P2P2_DP<18>")
	)
	(segment
		(start 268.817598 -338.96935)
		(end 269.234412 -338.552536)
		(width 0.14732)
		(layer "In11.Cu")
		(net "UPI_CPU1_CPU0_P2P2_DP<18>")
	)
	(segment
		(start 308.485794 -319.07607)
		(end 308.492906 -318.8716)
		(width 0.14732)
		(layer "In11.Cu")
		(net "UPI_CPU1_CPU0_P2P2_DP<18>")
	)
	(segment
		(start 248.485914 -359.771442)
		(end 247.725184 -358.680258)
		(width 0.14732)
		(layer "In11.Cu")
		(net "UPI_CPU1_CPU0_P2P2_DP<18>")
	)
	(segment
		(start 338.726018 -287.617154)
		(end 338.732114 -287.613598)
		(width 0.0889)
		(layer "In11.Cu")
		(net "UPI_CPU1_CPU0_P2P2_DP<18>")
	)
	(segment
		(start 240.844578 -365.27867)
		(end 240.881154 -365.073946)
		(width 0.14732)
		(layer "In11.Cu")
		(net "UPI_CPU1_CPU0_P2P2_DP<18>")
	)
	(segment
		(start 98.666046 -373.3292)
		(end 126.307596 -377.43003)
		(width 0.14732)
		(layer "In11.Cu")
		(net "UPI_CPU1_CPU0_P2P2_DP<18>")
	)
	(segment
		(start 238.979964 -366.399572)
		(end 238.219234 -365.308388)
		(width 0.14732)
		(layer "In11.Cu")
		(net "UPI_CPU1_CPU0_P2P2_DP<18>")
	)
	(segment
		(start 336.300572 -291.38626)
		(end 336.384138 -291.302694)
		(width 0.14732)
		(layer "In11.Cu")
		(net "UPI_CPU1_CPU0_P2P2_DP<18>")
	)
	(segment
		(start 336.384138 -291.302694)
		(end 336.399632 -291.2872)
		(width 0.0889)
		(layer "In11.Cu")
		(net "UPI_CPU1_CPU0_P2P2_DP<18>")
	)
	(segment
		(start 237.078774 -367.725198)
		(end 236.318044 -366.634014)
		(width 0.14732)
		(layer "In11.Cu")
		(net "UPI_CPU1_CPU0_P2P2_DP<18>")
	)
	(segment
		(start 308.48554 -319.07607)
		(end 308.485794 -319.07607)
		(width 0.14732)
		(layer "In11.Cu")
		(net "UPI_CPU1_CPU0_P2P2_DP<18>")
	)
	(segment
		(start 236.318044 -366.634014)
		(end 236.394498 -366.205516)
		(width 0.14732)
		(layer "In11.Cu")
		(net "UPI_CPU1_CPU0_P2P2_DP<18>")
	)
	(segment
		(start 104.514396 -283.709364)
		(end 104.505506 -283.714444)
		(width 0.0889)
		(layer "In11.Cu")
		(net "UPI_CPU1_CPU0_P2P2_DP<18>")
	)
	(segment
		(start 284.171898 -326.973946)
		(end 284.329886 -327.3552)
		(width 0.14732)
		(layer "In11.Cu")
		(net "UPI_CPU1_CPU0_P2P2_DP<18>")
	)
	(segment
		(start 103.10495 -287.778698)
		(end 103.09606 -287.783778)
		(width 0.0889)
		(layer "In11.Cu")
		(net "UPI_CPU1_CPU0_P2P2_DP<18>")
	)
	(segment
		(start 269.234412 -338.552536)
		(end 269.234412 -338.344256)
		(width 0.14732)
		(layer "In11.Cu")
		(net "UPI_CPU1_CPU0_P2P2_DP<18>")
	)
	(segment
		(start 71.713598 -335.156556)
		(end 71.713598 -353.1743)
		(width 0.14732)
		(layer "In11.Cu")
		(net "UPI_CPU1_CPU0_P2P2_DP<18>")
	)
	(segment
		(start 258.6736 -348.908624)
		(end 258.878324 -348.908624)
		(width 0.14732)
		(layer "In11.Cu")
		(net "UPI_CPU1_CPU0_P2P2_DP<18>")
	)
	(segment
		(start 103.580946 -286.961072)
		(end 103.574596 -286.964882)
		(width 0.0889)
		(layer "In11.Cu")
		(net "UPI_CPU1_CPU0_P2P2_DP<18>")
	)
	(segment
		(start 337.85429 -289.89147)
		(end 337.979766 -289.765994)
		(width 0.0889)
		(layer "In11.Cu")
		(net "UPI_CPU1_CPU0_P2P2_DP<18>")
	)
	(segment
		(start 103.857298 -286.4612)
		(end 103.857298 -286.475424)
		(width 0.0889)
		(layer "In11.Cu")
		(net "UPI_CPU1_CPU0_P2P2_DP<18>")
	)
	(segment
		(start 338.74075 -283.714444)
		(end 338.73186 -283.709364)
		(width 0.0889)
		(layer "In11.Cu")
		(net "UPI_CPU1_CPU0_P2P2_DP<18>")
	)
	(segment
		(start 103.586788 -285.329884)
		(end 103.574596 -285.336996)
		(width 0.0889)
		(layer "In11.Cu")
		(net "UPI_CPU1_CPU0_P2P2_DP<18>")
	)
	(segment
		(start 315.47435 -315.434472)
		(end 316.1538 -315.434472)
		(width 0.14732)
		(layer "In11.Cu")
		(net "UPI_CPU1_CPU0_P2P2_DP<18>")
	)
	(segment
		(start 238.965994 -364.412276)
		(end 239.394492 -364.48873)
		(width 0.14732)
		(layer "In11.Cu")
		(net "UPI_CPU1_CPU0_P2P2_DP<18>")
	)
	(segment
		(start 307.179218 -320.03111)
		(end 307.666136 -319.839594)
		(width 0.14732)
		(layer "In11.Cu")
		(net "UPI_CPU1_CPU0_P2P2_DP<18>")
	)
	(segment
		(start 234.194096 -367.739676)
		(end 235.163614 -367.063528)
		(width 0.14732)
		(layer "In11.Cu")
		(net "UPI_CPU1_CPU0_P2P2_DP<18>")
	)
	(segment
		(start 238.295688 -364.87989)
		(end 238.965994 -364.412276)
		(width 0.14732)
		(layer "In11.Cu")
		(net "UPI_CPU1_CPU0_P2P2_DP<18>")
	)
	(segment
		(start 337.979766 -289.765994)
		(end 337.979766 -289.622738)
		(width 0.0889)
		(layer "In11.Cu")
		(net "UPI_CPU1_CPU0_P2P2_DP<18>")
	)
	(segment
		(start 339.20176 -286.799782)
		(end 339.202776 -286.799274)
		(width 0.0889)
		(layer "In11.Cu")
		(net "UPI_CPU1_CPU0_P2P2_DP<18>")
	)
	(segment
		(start 104.98455 -282.895548)
		(end 104.97566 -282.900628)
		(width 0.0889)
		(layer "In11.Cu")
		(net "UPI_CPU1_CPU0_P2P2_DP<18>")
	)
	(segment
		(start 337.588098 -290.0172)
		(end 337.713828 -289.89147)
		(width 0.0889)
		(layer "In11.Cu")
		(net "UPI_CPU1_CPU0_P2P2_DP<18>")
	)
	(segment
		(start 337.979766 -282.427934)
		(end 337.979766 -282.405836)
		(width 0.0889)
		(layer "In11.Cu")
		(net "UPI_CPU1_CPU0_P2P2_DP<18>")
	)
	(segment
		(start 267.88237 -338.677758)
		(end 268.317726 -338.677758)
		(width 0.14732)
		(layer "In11.Cu")
		(net "UPI_CPU1_CPU0_P2P2_DP<18>")
	)
	(segment
		(start 280.503376 -329.099418)
		(end 282.925774 -328.095864)
		(width 0.14732)
		(layer "In11.Cu")
		(net "UPI_CPU1_CPU0_P2P2_DP<18>")
	)
	(segment
		(start 212.31225 -372.746016)
		(end 231.987852 -369.277392)
		(width 0.14732)
		(layer "In11.Cu")
		(net "UPI_CPU1_CPU0_P2P2_DP<18>")
	)
	(segment
		(start 308.762654 -318.62014)
		(end 308.967378 -318.627252)
		(width 0.14732)
		(layer "In11.Cu")
		(net "UPI_CPU1_CPU0_P2P2_DP<18>")
	)
	(segment
		(start 336.45856 -291.2872)
		(end 336.804762 -290.940998)
		(width 0.0889)
		(layer "In11.Cu")
		(net "UPI_CPU1_CPU0_P2P2_DP<18>")
	)
	(segment
		(start 245.098062 -360.511852)
		(end 245.858792 -361.603036)
		(width 0.14732)
		(layer "In11.Cu")
		(net "UPI_CPU1_CPU0_P2P2_DP<18>")
	)
	(segment
		(start 268.94282 -337.617308)
		(end 269.521178 -337.03895)
		(width 0.14732)
		(layer "In11.Cu")
		(net "UPI_CPU1_CPU0_P2P2_DP<18>")
	)
	(segment
		(start 259.138674 -348.648274)
		(end 259.138674 -348.44355)
		(width 0.14732)
		(layer "In11.Cu")
		(net "UPI_CPU1_CPU0_P2P2_DP<18>")
	)
	(segment
		(start 102.252272 -292.3413)
		(end 102.252272 -293.798244)
		(width 0.0889)
		(layer "In11.Cu")
		(net "UPI_CPU1_CPU0_P2P2_DP<18>")
	)
	(segment
		(start 314.81649 -315.434472)
		(end 314.96127 -315.289692)
		(width 0.14732)
		(layer "In11.Cu")
		(net "UPI_CPU1_CPU0_P2P2_DP<18>")
	)
	(segment
		(start 291.382196 -325.91375)
		(end 291.382196 -327.50506)
		(width 0.14732)
		(layer "In11.Cu")
		(net "UPI_CPU1_CPU0_P2P2_DP<18>")
	)
	(segment
		(start 259.399278 -348.182946)
		(end 259.604002 -348.182946)
		(width 0.14732)
		(layer "In11.Cu")
		(net "UPI_CPU1_CPU0_P2P2_DP<18>")
	)
	(segment
		(start 284.919166 -327.27011)
		(end 285.315914 -327.105772)
		(width 0.14732)
		(layer "In11.Cu")
		(net "UPI_CPU1_CPU0_P2P2_DP<18>")
	)
	(segment
		(start 244.669564 -360.435398)
		(end 245.098062 -360.511852)
		(width 0.14732)
		(layer "In11.Cu")
		(net "UPI_CPU1_CPU0_P2P2_DP<18>")
	)
	(segment
		(start 246.548148 -361.301792)
		(end 246.584724 -361.097068)
		(width 0.14732)
		(layer "In11.Cu")
		(net "UPI_CPU1_CPU0_P2P2_DP<18>")
	)
	(segment
		(start 308.967378 -318.627252)
		(end 309.824374 -317.828676)
		(width 0.14732)
		(layer "In11.Cu")
		(net "UPI_CPU1_CPU0_P2P2_DP<18>")
	)
	(segment
		(start 249.016266 -357.405178)
		(end 249.445018 -357.481886)
		(width 0.14732)
		(layer "In11.Cu")
		(net "UPI_CPU1_CPU0_P2P2_DP<18>")
	)
	(segment
		(start 81.777332 -316.784482)
		(end 73.883774 -324.678548)
		(width 0.14732)
		(layer "In11.Cu")
		(net "UPI_CPU1_CPU0_P2P2_DP<18>")
	)
	(segment
		(start 243.196872 -361.837478)
		(end 244.050058 -363.06125)
		(width 0.14732)
		(layer "In11.Cu")
		(net "UPI_CPU1_CPU0_P2P2_DP<18>")
	)
	(segment
		(start 338.919566 -287.28924)
		(end 338.919566 -287.273746)
		(width 0.0889)
		(layer "In11.Cu")
		(net "UPI_CPU1_CPU0_P2P2_DP<18>")
	)
	(segment
		(start 259.604002 -348.182946)
		(end 267.595604 -340.191344)
		(width 0.14732)
		(layer "In11.Cu")
		(net "UPI_CPU1_CPU0_P2P2_DP<18>")
	)
	(segment
		(start 337.19643 -290.54933)
		(end 337.19643 -290.408868)
		(width 0.0889)
		(layer "In11.Cu")
		(net "UPI_CPU1_CPU0_P2P2_DP<18>")
	)
	(segment
		(start 103.573072 -286.965644)
		(end 103.565706 -286.969962)
		(width 0.0889)
		(layer "In11.Cu")
		(net "UPI_CPU1_CPU0_P2P2_DP<18>")
	)
	(segment
		(start 240.867184 -363.08665)
		(end 241.295682 -363.163104)
		(width 0.14732)
		(layer "In11.Cu")
		(net "UPI_CPU1_CPU0_P2P2_DP<18>")
	)
	(segment
		(start 338.919312 -284.043628)
		(end 338.919312 -284.033722)
		(width 0.0889)
		(layer "In11.Cu")
		(net "UPI_CPU1_CPU0_P2P2_DP<18>")
	)
	(segment
		(start 269.521178 -337.03895)
		(end 269.956534 -337.03895)
		(width 0.14732)
		(layer "In11.Cu")
		(net "UPI_CPU1_CPU0_P2P2_DP<18>")
	)
	(segment
		(start 267.304012 -339.256116)
		(end 267.88237 -338.677758)
		(width 0.14732)
		(layer "In11.Cu")
		(net "UPI_CPU1_CPU0_P2P2_DP<18>")
	)
	(segment
		(start 337.79714 -282.084526)
		(end 337.795616 -282.08351)
		(width 0.0889)
		(layer "In11.Cu")
		(net "UPI_CPU1_CPU0_P2P2_DP<18>")
	)
	(segment
		(start 268.94282 -338.052664)
		(end 268.94282 -337.617308)
		(width 0.14732)
		(layer "In11.Cu")
		(net "UPI_CPU1_CPU0_P2P2_DP<18>")
	)
	(segment
		(start 278.90724 -329.760326)
		(end 278.986742 -329.568302)
		(width 0.14732)
		(layer "In11.Cu")
		(net "UPI_CPU1_CPU0_P2P2_DP<18>")
	)
	(segment
		(start 234.165648 -368.237516)
		(end 234.165902 -368.237262)
		(width 0.14732)
		(layer "In11.Cu")
		(net "UPI_CPU1_CPU0_P2P2_DP<18>")
	)
	(segment
		(start 245.823994 -360.005884)
		(end 245.900448 -359.577386)
		(width 0.14732)
		(layer "In11.Cu")
		(net "UPI_CPU1_CPU0_P2P2_DP<18>")
	)
	(segment
		(start 258.412996 -349.169228)
		(end 258.6736 -348.908624)
		(width 0.14732)
		(layer "In11.Cu")
		(net "UPI_CPU1_CPU0_P2P2_DP<18>")
	)
	(segment
		(start 312.752486 -316.431168)
		(end 313.54776 -315.63564)
		(width 0.14732)
		(layer "In11.Cu")
		(net "UPI_CPU1_CPU0_P2P2_DP<18>")
	)
	(segment
		(start 250.24715 -356.54742)
		(end 253.519686 -354.267262)
		(width 0.14732)
		(layer "In11.Cu")
		(net "UPI_CPU1_CPU0_P2P2_DP<18>")
	)
	(segment
		(start 333.84109 -293.033958)
		(end 334.915002 -291.9603)
		(width 0.14732)
		(layer "In11.Cu")
		(net "UPI_CPU1_CPU0_P2P2_DP<18>")
	)
	(segment
		(start 267.595604 -339.983064)
		(end 267.304012 -339.691472)
		(width 0.14732)
		(layer "In11.Cu")
		(net "UPI_CPU1_CPU0_P2P2_DP<18>")
	)
	(segment
		(start 337.509612 -281.59202)
		(end 337.509612 -281.583384)
		(width 0.0889)
		(layer "In11.Cu")
		(net "UPI_CPU1_CPU0_P2P2_DP<18>")
	)
	(segment
		(start 282.925774 -328.095864)
		(end 283.005276 -327.90384)
		(width 0.14732)
		(layer "In11.Cu")
		(net "UPI_CPU1_CPU0_P2P2_DP<18>")
	)
	(segment
		(start 338.26196 -288.427414)
		(end 338.27085 -288.422334)
		(width 0.0889)
		(layer "In11.Cu")
		(net "UPI_CPU1_CPU0_P2P2_DP<18>")
	)
	(segment
		(start 233.766614 -368.954558)
		(end 234.251246 -368.616738)
		(width 0.14732)
		(layer "In11.Cu")
		(net "UPI_CPU1_CPU0_P2P2_DP<18>")
	)
	(segment
		(start 242.768374 -361.761024)
		(end 243.196872 -361.837478)
		(width 0.14732)
		(layer "In11.Cu")
		(net "UPI_CPU1_CPU0_P2P2_DP<18>")
	)
	(segment
		(start 338.919566 -285.683452)
		(end 338.919566 -285.64586)
		(width 0.0889)
		(layer "In11.Cu")
		(net "UPI_CPU1_CPU0_P2P2_DP<18>")
	)
	(segment
		(start 245.858792 -361.603036)
		(end 246.063516 -361.639612)
		(width 0.14732)
		(layer "In11.Cu")
		(net "UPI_CPU1_CPU0_P2P2_DP<18>")
	)
	(segment
		(start 314.96127 -315.289692)
		(end 315.32957 -315.289692)
		(width 0.14732)
		(layer "In11.Cu")
		(net "UPI_CPU1_CPU0_P2P2_DP<18>")
	)
	(segment
		(start 105.266744 -282.390342)
		(end 105.266744 -282.427934)
		(width 0.0889)
		(layer "In11.Cu")
		(net "UPI_CPU1_CPU0_P2P2_DP<18>")
	)
	(segment
		(start 337.793076 -282.081986)
		(end 337.786218 -282.077922)
		(width 0.0889)
		(layer "In11.Cu")
		(net "UPI_CPU1_CPU0_P2P2_DP<18>")
	)
	(segment
		(start 339.21065 -286.156146)
		(end 339.202776 -286.151574)
		(width 0.0889)
		(layer "In11.Cu")
		(net "UPI_CPU1_CPU0_P2P2_DP<18>")
	)
	(segment
		(start 102.294436 -297.359324)
		(end 102.1842 -297.62577)
		(width 0.14732)
		(layer "In11.Cu")
		(net "UPI_CPU1_CPU0_P2P2_DP<18>")
	)
	(segment
		(start 267.304012 -339.691472)
		(end 267.304012 -339.256116)
		(width 0.14732)
		(layer "In11.Cu")
		(net "UPI_CPU1_CPU0_P2P2_DP<18>")
	)
	(segment
		(start 104.043734 -284.523688)
		(end 104.03586 -284.52826)
		(width 0.0889)
		(layer "In11.Cu")
		(net "UPI_CPU1_CPU0_P2P2_DP<18>")
	)
	(segment
		(start 240.196878 -363.554264)
		(end 240.867184 -363.08665)
		(width 0.14732)
		(layer "In11.Cu")
		(net "UPI_CPU1_CPU0_P2P2_DP<18>")
	)
	(segment
		(start 250.65101 -357.92283)
		(end 250.687586 -357.71836)
		(width 0.14732)
		(layer "In11.Cu")
		(net "UPI_CPU1_CPU0_P2P2_DP<18>")
	)
	(segment
		(start 284.329886 -327.3552)
		(end 284.52191 -327.434702)
		(width 0.14732)
		(layer "In11.Cu")
		(net "UPI_CPU1_CPU0_P2P2_DP<18>")
	)
	(segment
		(start 279.761696 -328.497692)
		(end 280.163778 -328.664062)
		(width 0.14732)
		(layer "In11.Cu")
		(net "UPI_CPU1_CPU0_P2P2_DP<18>")
	)
	(segment
		(start 249.445018 -357.481886)
		(end 249.961908 -358.224074)
		(width 0.14732)
		(layer "In11.Cu")
		(net "UPI_CPU1_CPU0_P2P2_DP<18>")
	)
	(segment
		(start 244.77599 -362.555282)
		(end 243.922804 -361.33151)
		(width 0.14732)
		(layer "In11.Cu")
		(net "UPI_CPU1_CPU0_P2P2_DP<18>")
	)
	(segment
		(start 72.92721 -326.701658)
		(end 72.335644 -328.839068)
		(width 0.14732)
		(layer "In11.Cu")
		(net "UPI_CPU1_CPU0_P2P2_DP<18>")
	)
	(segment
		(start 280.311098 -329.019662)
		(end 280.503376 -329.099418)
		(width 0.14732)
		(layer "In11.Cu")
		(net "UPI_CPU1_CPU0_P2P2_DP<18>")
	)
	(segment
		(start 292.118796 -327.65238)
		(end 292.266116 -327.50506)
		(width 0.14732)
		(layer "In11.Cu")
		(net "UPI_CPU1_CPU0_P2P2_DP<18>")
	)
	(segment
		(start 283.013912 -327.120504)
		(end 283.769816 -326.807322)
		(width 0.14732)
		(layer "In11.Cu")
		(net "UPI_CPU1_CPU0_P2P2_DP<18>")
	)
	(segment
		(start 73.587356 -357.69169)
		(end 75.46086 -362.208064)
		(width 0.14732)
		(layer "In11.Cu")
		(net "UPI_CPU1_CPU0_P2P2_DP<18>")
	)
	(segment
		(start 102.917498 -288.103056)
		(end 102.917498 -288.121598)
		(width 0.0889)
		(layer "In11.Cu")
		(net "UPI_CPU1_CPU0_P2P2_DP<18>")
	)
	(segment
		(start 316.481968 -315.106304)
		(end 316.481968 -314.90158)
		(width 0.14732)
		(layer "In11.Cu")
		(net "UPI_CPU1_CPU0_P2P2_DP<18>")
	)
	(segment
		(start 336.804762 -290.800536)
		(end 336.930492 -290.674806)
		(width 0.0889)
		(layer "In11.Cu")
		(net "UPI_CPU1_CPU0_P2P2_DP<18>")
	)
	(segment
		(start 247.725184 -358.680258)
		(end 247.801638 -358.251506)
		(width 0.14732)
		(layer "In11.Cu")
		(net "UPI_CPU1_CPU0_P2P2_DP<18>")
	)
	(segment
		(start 249.961908 -358.224074)
		(end 250.166378 -358.26065)
		(width 0.14732)
		(layer "In11.Cu")
		(net "UPI_CPU1_CPU0_P2P2_DP<18>")
	)
	(segment
		(start 316.1538 -315.434472)
		(end 316.481968 -315.106304)
		(width 0.14732)
		(layer "In11.Cu")
		(net "UPI_CPU1_CPU0_P2P2_DP<18>")
	)
	(segment
		(start 237.493302 -365.814356)
		(end 238.254032 -366.90554)
		(width 0.14732)
		(layer "In11.Cu")
		(net "UPI_CPU1_CPU0_P2P2_DP<18>")
	)
	(segment
		(start 104.074468 -282.405836)
		(end 104.140254 -282.34005)
		(width 0.0889)
		(layer "In11.Cu")
		(net "UPI_CPU1_CPU0_P2P2_DP<18>")
	)
	(segment
		(start 278.839422 -329.212702)
		(end 279.005792 -328.810874)
		(width 0.14732)
		(layer "In11.Cu")
		(net "UPI_CPU1_CPU0_P2P2_DP<18>")
	)
	(segment
		(start 102.294436 -293.862506)
		(end 102.294436 -297.359324)
		(width 0.14732)
		(layer "In11.Cu")
		(net "UPI_CPU1_CPU0_P2P2_DP<18>")
	)
	(segment
		(start 75.46086 -362.208064)
		(end 78.03769 -364.785402)
		(width 0.14732)
		(layer "In11.Cu")
		(net "UPI_CPU1_CPU0_P2P2_DP<18>")
	)
	(segment
		(start 337.880706 -289.345878)
		(end 337.979766 -289.246818)
		(width 0.0889)
		(layer "In11.Cu")
		(net "UPI_CPU1_CPU0_P2P2_DP<18>")
	)
	(segment
		(start 238.458756 -366.942116)
		(end 238.943388 -366.604296)
		(width 0.14732)
		(layer "In11.Cu")
		(net "UPI_CPU1_CPU0_P2P2_DP<18>")
	)
	(segment
		(start 242.056412 -364.254288)
		(end 242.261136 -364.290864)
		(width 0.14732)
		(layer "In11.Cu")
		(net "UPI_CPU1_CPU0_P2P2_DP<18>")
	)
	(segment
		(start 102.252272 -293.798244)
		(end 102.294436 -293.840408)
		(width 0.0889)
		(layer "In11.Cu")
		(net "UPI_CPU1_CPU0_P2P2_DP<18>")
	)
	(segment
		(start 337.801204 -282.086558)
		(end 337.801204 -282.086812)
		(width 0.0889)
		(layer "In11.Cu")
		(net "UPI_CPU1_CPU0_P2P2_DP<18>")
	)
	(segment
		(start 247.759982 -360.27741)
		(end 247.964706 -360.313986)
		(width 0.14732)
		(layer "In11.Cu")
		(net "UPI_CPU1_CPU0_P2P2_DP<18>")
	)
	(segment
		(start 283.005276 -327.90384)
		(end 282.847288 -327.522586)
		(width 0.14732)
		(layer "In11.Cu")
		(net "UPI_CPU1_CPU0_P2P2_DP<18>")
	)
	(segment
		(start 337.793838 -282.082494)
		(end 337.793076 -282.081986)
		(width 0.0889)
		(layer "In11.Cu")
		(net "UPI_CPU1_CPU0_P2P2_DP<18>")
	)
	(segment
		(start 303.827688 -323.845428)
		(end 304.929286 -322.743322)
		(width 0.14732)
		(layer "In11.Cu")
		(net "UPI_CPU1_CPU0_P2P2_DP<18>")
	)
	(segment
		(start 246.570754 -359.109772)
		(end 246.999252 -359.186226)
		(width 0.14732)
		(layer "In11.Cu")
		(net "UPI_CPU1_CPU0_P2P2_DP<18>")
	)
	(segment
		(start 312.752486 -316.443868)
		(end 312.752486 -316.431168)
		(width 0.14732)
		(layer "In11.Cu")
		(net "UPI_CPU1_CPU0_P2P2_DP<18>")
	)
	(segment
		(start 102.447598 -288.917126)
		(end 102.447598 -289.078416)
		(width 0.0889)
		(layer "In11.Cu")
		(net "UPI_CPU1_CPU0_P2P2_DP<18>")
	)
	(segment
		(start 231.987852 -369.277392)
		(end 232.963212 -368.597688)
		(width 0.14732)
		(layer "In11.Cu")
		(net "UPI_CPU1_CPU0_P2P2_DP<18>")
	)
	(segment
		(start 246.999252 -359.186226)
		(end 247.759982 -360.27741)
		(width 0.14732)
		(layer "In11.Cu")
		(net "UPI_CPU1_CPU0_P2P2_DP<18>")
	)
	(segment
		(start 284.918912 -327.27011)
		(end 284.919166 -327.27011)
		(width 0.14732)
		(layer "In11.Cu")
		(net "UPI_CPU1_CPU0_P2P2_DP<18>")
	)
	(segment
		(start 291.382196 -327.50506)
		(end 291.529516 -327.65238)
		(width 0.14732)
		(layer "In11.Cu")
		(net "UPI_CPU1_CPU0_P2P2_DP<18>")
	)
	(segment
		(start 277.40356 -330.383388)
		(end 278.90724 -329.760326)
		(width 0.14732)
		(layer "In11.Cu")
		(net "UPI_CPU1_CPU0_P2P2_DP<18>")
	)
	(segment
		(start 331.106526 -300.481746)
		(end 332.970886 -294.337232)
		(width 0.14732)
		(layer "In11.Cu")
		(net "UPI_CPU1_CPU0_P2P2_DP<18>")
	)
	(segment
		(start 103.565706 -285.980632)
		(end 103.574596 -285.985712)
		(width 0.0889)
		(layer "In11.Cu")
		(net "UPI_CPU1_CPU0_P2P2_DP<18>")
	)
	(segment
		(start 240.120424 -363.982762)
		(end 240.196878 -363.554264)
		(width 0.14732)
		(layer "In11.Cu")
		(net "UPI_CPU1_CPU0_P2P2_DP<18>")
	)
	(segment
		(start 246.584724 -361.097068)
		(end 245.823994 -360.005884)
		(width 0.14732)
		(layer "In11.Cu")
		(net "UPI_CPU1_CPU0_P2P2_DP<18>")
	)
	(segment
		(start 268.609318 -338.96935)
		(end 268.817598 -338.96935)
		(width 0.14732)
		(layer "In11.Cu")
		(net "UPI_CPU1_CPU0_P2P2_DP<18>")
	)
	(segment
		(start 236.557566 -368.267742)
		(end 237.042198 -367.929922)
		(width 0.14732)
		(layer "In11.Cu")
		(net "UPI_CPU1_CPU0_P2P2_DP<18>")
	)
	(segment
		(start 337.32216 -290.283138)
		(end 337.462622 -290.283138)
		(width 0.0889)
		(layer "In11.Cu")
		(net "UPI_CPU1_CPU0_P2P2_DP<18>")
	)
	(segment
		(start 242.782344 -363.74832)
		(end 242.021614 -362.657136)
		(width 0.14732)
		(layer "In11.Cu")
		(net "UPI_CPU1_CPU0_P2P2_DP<18>")
	)
	(segment
		(start 233.39171 -368.674142)
		(end 233.562144 -368.917728)
		(width 0.14732)
		(layer "In11.Cu")
		(net "UPI_CPU1_CPU0_P2P2_DP<18>")
	)
	(segment
		(start 316.947296 -314.640976)
		(end 331.106526 -300.481746)
		(width 0.14732)
		(layer "In11.Cu")
		(net "UPI_CPU1_CPU0_P2P2_DP<18>")
	)
	(segment
		(start 269.234412 -338.344256)
		(end 268.94282 -338.052664)
		(width 0.14732)
		(layer "In11.Cu")
		(net "UPI_CPU1_CPU0_P2P2_DP<18>")
	)
	(segment
		(start 247.964706 -360.313986)
		(end 248.449338 -359.976166)
		(width 0.14732)
		(layer "In11.Cu")
		(net "UPI_CPU1_CPU0_P2P2_DP<18>")
	)
	(segment
		(start 280.163778 -328.664062)
		(end 280.311098 -329.019662)
		(width 0.14732)
		(layer "In11.Cu")
		(net "UPI_CPU1_CPU0_P2P2_DP<18>")
	)
	(segment
		(start 238.254032 -366.90554)
		(end 238.458756 -366.942116)
		(width 0.14732)
		(layer "In11.Cu")
		(net "UPI_CPU1_CPU0_P2P2_DP<18>")
	)
	(segment
		(start 78.03769 -364.785402)
		(end 98.666046 -373.3292)
		(width 0.14732)
		(layer "In11.Cu")
		(net "UPI_CPU1_CPU0_P2P2_DP<18>")
	)
	(segment
		(start 314.033154 -315.434472)
		(end 314.81649 -315.434472)
		(width 0.14732)
		(layer "In11.Cu")
		(net "UPI_CPU1_CPU0_P2P2_DP<18>")
	)
	(segment
		(start 72.335644 -328.839068)
		(end 71.713598 -335.156556)
		(width 0.14732)
		(layer "In11.Cu")
		(net "UPI_CPU1_CPU0_P2P2_DP<18>")
	)
	(segment
		(start 234.165902 -368.237262)
		(end 234.117642 -368.16792)
		(width 0.14732)
		(layer "In11.Cu")
		(net "UPI_CPU1_CPU0_P2P2_DP<18>")
	)
	(segment
		(start 233.562144 -368.917728)
		(end 233.766614 -368.954558)
		(width 0.14732)
		(layer "In11.Cu")
		(net "UPI_CPU1_CPU0_P2P2_DP<18>")
	)
	(segment
		(start 291.084508 -325.616062)
		(end 291.382196 -325.91375)
		(width 0.14732)
		(layer "In11.Cu")
		(net "UPI_CPU1_CPU0_P2P2_DP<18>")
	)
	(segment
		(start 269.956534 -337.03895)
		(end 270.248126 -337.330542)
		(width 0.14732)
		(layer "In11.Cu")
		(net "UPI_CPU1_CPU0_P2P2_DP<18>")
	)
	(segment
		(start 336.804762 -290.940998)
		(end 336.804762 -290.800536)
		(width 0.0889)
		(layer "In11.Cu")
		(net "UPI_CPU1_CPU0_P2P2_DP<18>")
	)
	(segment
		(start 103.580692 -286.961326)
		(end 103.580946 -286.961072)
		(width 0.0889)
		(layer "In11.Cu")
		(net "UPI_CPU1_CPU0_P2P2_DP<18>")
	)
	(segment
		(start 338.245196 -288.437828)
		(end 338.244942 -288.437574)
		(width 0.0889)
		(layer "In11.Cu")
		(net "UPI_CPU1_CPU0_P2P2_DP<18>")
	)
	(segment
		(start 337.070954 -290.674806)
		(end 337.19643 -290.54933)
		(width 0.0889)
		(layer "In11.Cu")
		(net "UPI_CPU1_CPU0_P2P2_DP<18>")
	)
	(segment
		(start 337.29168 -281.321002)
		(end 337.135216 -281.59202)
		(width 0.0889)
		(layer "In11.Cu")
		(net "UPI_CPU1_CPU0_P2P2_DP<18>")
	)
	(segment
		(start 270.456406 -337.330542)
		(end 277.40356 -330.383388)
		(width 0.14732)
		(layer "In11.Cu")
		(net "UPI_CPU1_CPU0_P2P2_DP<18>")
	)
	(segment
		(start 103.574596 -286.964882)
		(end 103.573072 -286.965644)
		(width 0.0889)
		(layer "In11.Cu")
		(net "UPI_CPU1_CPU0_P2P2_DP<18>")
	)
	(segment
		(start 244.254782 -363.097826)
		(end 244.739414 -362.760006)
		(width 0.14732)
		(layer "In11.Cu")
		(net "UPI_CPU1_CPU0_P2P2_DP<18>")
	)
	(segment
		(start 71.713598 -353.1743)
		(end 73.587356 -357.691182)
		(width 0.14732)
		(layer "In11.Cu")
		(net "UPI_CPU1_CPU0_P2P2_DP<18>")
	)
	(segment
		(start 267.595604 -340.191344)
		(end 267.595604 -339.983064)
		(width 0.14732)
		(layer "In11.Cu")
		(net "UPI_CPU1_CPU0_P2P2_DP<18>")
	)
	(segment
		(start 238.943388 -366.604296)
		(end 238.979964 -366.399572)
		(width 0.14732)
		(layer "In11.Cu")
		(net "UPI_CPU1_CPU0_P2P2_DP<18>")
	)
	(segment
		(start 237.042198 -367.929922)
		(end 237.078774 -367.725198)
		(width 0.14732)
		(layer "In11.Cu")
		(net "UPI_CPU1_CPU0_P2P2_DP<18>")
	)
	(segment
		(start 259.138674 -348.44355)
		(end 259.399278 -348.182946)
		(width 0.14732)
		(layer "In11.Cu")
		(net "UPI_CPU1_CPU0_P2P2_DP<18>")
	)
	(segment
		(start 235.592112 -367.139982)
		(end 236.352842 -368.231166)
		(width 0.14732)
		(layer "In11.Cu")
		(net "UPI_CPU1_CPU0_P2P2_DP<18>")
	)
	(segment
		(start 308.492906 -318.8716)
		(end 308.762654 -318.62014)
		(width 0.14732)
		(layer "In11.Cu")
		(net "UPI_CPU1_CPU0_P2P2_DP<18>")
	)
	(segment
		(start 306.526438 -320.639186)
		(end 307.179218 -320.03111)
		(width 0.14732)
		(layer "In11.Cu")
		(net "UPI_CPU1_CPU0_P2P2_DP<18>")
	)
	(segment
		(start 103.761794 -282.405836)
		(end 104.074468 -282.405836)
		(width 0.0889)
		(layer "In11.Cu")
		(net "UPI_CPU1_CPU0_P2P2_DP<18>")
	)
	(segment
		(start 242.021614 -362.657136)
		(end 242.098068 -362.228638)
		(width 0.14732)
		(layer "In11.Cu")
		(net "UPI_CPU1_CPU0_P2P2_DP<18>")
	)
	(segment
		(start 237.064804 -365.737902)
		(end 237.493302 -365.814356)
		(width 0.14732)
		(layer "In11.Cu")
		(net "UPI_CPU1_CPU0_P2P2_DP<18>")
	)
	(segment
		(start 338.732114 -287.613598)
		(end 338.741004 -287.608518)
		(width 0.0889)
		(layer "In11.Cu")
		(net "UPI_CPU1_CPU0_P2P2_DP<18>")
	)
	(segment
		(start 241.295682 -363.163104)
		(end 242.056412 -364.254288)
		(width 0.14732)
		(layer "In11.Cu")
		(net "UPI_CPU1_CPU0_P2P2_DP<18>")
	)
	(segment
		(start 338.449412 -283.229812)
		(end 338.449412 -283.219906)
		(width 0.0889)
		(layer "In11.Cu")
		(net "UPI_CPU1_CPU0_P2P2_DP<18>")
	)
	(segment
		(start 102.917244 -289.60953)
		(end 102.917244 -291.676328)
		(width 0.0889)
		(layer "In11.Cu")
		(net "UPI_CPU1_CPU0_P2P2_DP<18>")
	)
	(segment
		(start 337.713828 -289.89147)
		(end 337.85429 -289.89147)
		(width 0.0889)
		(layer "In11.Cu")
		(net "UPI_CPU1_CPU0_P2P2_DP<18>")
	)
	(segment
		(start 279.005792 -328.810874)
		(end 279.761696 -328.497692)
		(width 0.14732)
		(layer "In11.Cu")
		(net "UPI_CPU1_CPU0_P2P2_DP<18>")
	)
	(segment
		(start 292.266116 -325.91375)
		(end 292.563804 -325.616062)
		(width 0.14732)
		(layer "In11.Cu")
		(net "UPI_CPU1_CPU0_P2P2_DP<18>")
	)
	(segment
		(start 286.805624 -325.616062)
		(end 291.084508 -325.616062)
		(width 0.14732)
		(layer "In11.Cu")
		(net "UPI_CPU1_CPU0_P2P2_DP<18>")
	)
	(segment
		(start 240.155222 -365.579914)
		(end 240.359946 -365.61649)
		(width 0.14732)
		(layer "In11.Cu")
		(net "UPI_CPU1_CPU0_P2P2_DP<18>")
	)
	(segment
		(start 313.54776 -315.63564)
		(end 314.033154 -315.434472)
		(width 0.14732)
		(layer "In11.Cu")
		(net "UPI_CPU1_CPU0_P2P2_DP<18>")
	)
	(segment
		(start 336.930492 -290.674806)
		(end 337.070954 -290.674806)
		(width 0.0889)
		(layer "In11.Cu")
		(net "UPI_CPU1_CPU0_P2P2_DP<18>")
	)
	(segment
		(start 337.369658 -281.300174)
		(end 337.29168 -281.321002)
		(width 0.0889)
		(layer "In11.Cu")
		(net "UPI_CPU1_CPU0_P2P2_DP<18>")
	)
	(segment
		(start 97.612708 -303.789334)
		(end 81.777332 -316.784482)
		(width 0.14732)
		(layer "In11.Cu")
		(net "UPI_CPU1_CPU0_P2P2_DP<18>")
	)
	(segment
		(start 337.795616 -282.08351)
		(end 337.793838 -282.082494)
		(width 0.0889)
		(layer "In11.Cu")
		(net "UPI_CPU1_CPU0_P2P2_DP<18>")
	)
	(segment
		(start 104.326944 -284.033722)
		(end 104.326944 -284.049216)
		(width 0.0889)
		(layer "In11.Cu")
		(net "UPI_CPU1_CPU0_P2P2_DP<18>")
	)
	(segment
		(start 104.41305 -281.919934)
		(end 104.433878 -281.907742)
		(width 0.0889)
		(layer "In11.Cu")
		(net "UPI_CPU1_CPU0_P2P2_DP<18>")
	)
	(segment
		(start 104.526588 -283.702252)
		(end 104.514396 -283.709364)
		(width 0.0889)
		(layer "In11.Cu")
		(net "UPI_CPU1_CPU0_P2P2_DP<18>")
	)
	(segment
		(start 102.294436 -293.840408)
		(end 102.294436 -293.862506)
		(width 0.0889)
		(layer "In11.Cu")
		(net "UPI_CPU1_CPU0_P2P2_DP<18>")
	)
	(segment
		(start 250.166378 -358.26065)
		(end 250.65101 -357.92283)
		(width 0.14732)
		(layer "In11.Cu")
		(net "UPI_CPU1_CPU0_P2P2_DP<18>")
	)
	(segment
		(start 248.449338 -359.976166)
		(end 248.485914 -359.771442)
		(width 0.14732)
		(layer "In11.Cu")
		(net "UPI_CPU1_CPU0_P2P2_DP<18>")
	)
	(segment
		(start 339.21065 -284.52826)
		(end 339.20176 -284.52318)
		(width 0.0889)
		(layer "In11.Cu")
		(net "UPI_CPU1_CPU0_P2P2_DP<18>")
	)
	(segment
		(start 316.742572 -314.640976)
		(end 316.947296 -314.640976)
		(width 0.14732)
		(layer "In11.Cu")
		(net "UPI_CPU1_CPU0_P2P2_DP<18>")
	)
	(segment
		(start 103.574596 -285.336996)
		(end 103.565706 -285.342076)
		(width 0.0889)
		(layer "In11.Cu")
		(net "UPI_CPU1_CPU0_P2P2_DP<18>")
	)
	(segment
		(start 103.387144 -287.28924)
		(end 103.387144 -287.304734)
		(width 0.0889)
		(layer "In11.Cu")
		(net "UPI_CPU1_CPU0_P2P2_DP<18>")
	)
	(segment
		(start 236.394498 -366.205516)
		(end 237.064804 -365.737902)
		(width 0.14732)
		(layer "In11.Cu")
		(net "UPI_CPU1_CPU0_P2P2_DP<18>")
	)
	(segment
		(start 234.287568 -368.412522)
		(end 234.165648 -368.237516)
		(width 0.14732)
		(layer "In11.Cu")
		(net "UPI_CPU1_CPU0_P2P2_DP<18>")
	)
	(segment
		(start 240.881154 -365.073946)
		(end 240.120424 -363.982762)
		(width 0.14732)
		(layer "In11.Cu")
		(net "UPI_CPU1_CPU0_P2P2_DP<18>")
	)
	(segment
		(start 315.32957 -315.289692)
		(end 315.47435 -315.434472)
		(width 0.14732)
		(layer "In11.Cu")
		(net "UPI_CPU1_CPU0_P2P2_DP<18>")
	)
	(segment
		(start 285.315914 -327.105772)
		(end 286.805624 -325.616062)
		(width 0.14732)
		(layer "In11.Cu")
		(net "UPI_CPU1_CPU0_P2P2_DP<18>")
	)
	(segment
		(start 161.425636 -377.43003)
		(end 200.154286 -370.602002)
		(width 0.14732)
		(layer "In11.Cu")
		(net "UPI_CPU1_CPU0_P2P2_DP<18>")
	)
	(segment
		(start 102.917244 -291.676328)
		(end 102.252272 -292.3413)
		(width 0.0889)
		(layer "In11.Cu")
		(net "UPI_CPU1_CPU0_P2P2_DP<18>")
	)
	(segment
		(start 104.04475 -284.52318)
		(end 104.043734 -284.523688)
		(width 0.0889)
		(layer "In11.Cu")
		(net "UPI_CPU1_CPU0_P2P2_DP<18>")
	)
	(segment
		(start 102.63505 -288.592768)
		(end 102.62616 -288.597848)
		(width 0.0889)
		(layer "In11.Cu")
		(net "UPI_CPU1_CPU0_P2P2_DP<18>")
	)
	(segment
		(start 240.359946 -365.61649)
		(end 240.844578 -365.27867)
		(width 0.14732)
		(layer "In11.Cu")
		(net "UPI_CPU1_CPU0_P2P2_DP<18>")
	)
	(segment
		(start 337.588098 -290.157662)
		(end 337.588098 -290.0172)
		(width 0.0889)
		(layer "In11.Cu")
		(net "UPI_CPU1_CPU0_P2P2_DP<18>")
	)
	(segment
		(start 258.878324 -348.908624)
		(end 259.138674 -348.648274)
		(width 0.14732)
		(layer "In11.Cu")
		(net "UPI_CPU1_CPU0_P2P2_DP<18>")
	)
	(segment
		(start 307.666136 -319.839594)
		(end 308.48554 -319.07607)
		(width 0.14732)
		(layer "In11.Cu")
		(net "UPI_CPU1_CPU0_P2P2_DP<18>")
	)
	(segment
		(start 268.317726 -338.677758)
		(end 268.609318 -338.96935)
		(width 0.14732)
		(layer "In11.Cu")
		(net "UPI_CPU1_CPU0_P2P2_DP<18>")
	)
	(segment
		(start 258.412996 -349.373952)
		(end 258.412996 -349.169228)
		(width 0.14732)
		(layer "In11.Cu")
		(net "UPI_CPU1_CPU0_P2P2_DP<18>")
	)
	(segment
		(start 242.261136 -364.290864)
		(end 242.745768 -363.953044)
		(width 0.14732)
		(layer "In11.Cu")
		(net "UPI_CPU1_CPU0_P2P2_DP<18>")
	)
	(segment
		(start 278.986742 -329.568302)
		(end 278.839422 -329.212702)
		(width 0.14732)
		(layer "In11.Cu")
		(net "UPI_CPU1_CPU0_P2P2_DP<18>")
	)
	(segment
		(start 338.27085 -282.900628)
		(end 338.26196 -282.895548)
		(width 0.0889)
		(layer "In11.Cu")
		(net "UPI_CPU1_CPU0_P2P2_DP<18>")
	)
	(arc
		(start 338.244942 -288.437574)
		(mid 338.253406 -288.432419)
		(end 338.26196 -288.427414)
		(width 0.0889)
		(layer "In11.Cu")
		(net "UPI_CPU1_CPU0_P2P2_DP<18>")
	)
	(arc
		(start 104.143048 -282.319222)
		(mid 104.233312 -282.089312)
		(end 104.41305 -281.919934)
		(width 0.0889)
		(layer "In11.Cu")
		(net "UPI_CPU1_CPU0_P2P2_DP<18>")
	)
	(arc
		(start 103.857298 -286.475424)
		(mid 103.783307 -286.75499)
		(end 103.580692 -286.961326)
		(width 0.0889)
		(layer "In11.Cu")
		(net "UPI_CPU1_CPU0_P2P2_DP<18>")
	)
	(arc
		(start 338.26196 -282.895548)
		(mid 338.060678 -282.698061)
		(end 337.979766 -282.427934)
		(width 0.0889)
		(layer "In11.Cu")
		(net "UPI_CPU1_CPU0_P2P2_DP<18>")
	)
	(arc
		(start 338.27085 -288.422334)
		(mid 338.398104 -288.292368)
		(end 338.449158 -288.117788)
		(width 0.0889)
		(layer "In11.Cu")
		(net "UPI_CPU1_CPU0_P2P2_DP<18>")
	)
	(arc
		(start 104.97566 -282.900628)
		(mid 104.844746 -283.036988)
		(end 104.797098 -283.219906)
		(width 0.0889)
		(layer "In11.Cu")
		(net "UPI_CPU1_CPU0_P2P2_DP<18>")
	)
	(arc
		(start 105.266744 -282.427934)
		(mid 105.185833 -282.698062)
		(end 104.98455 -282.895548)
		(width 0.0889)
		(layer "In11.Cu")
		(net "UPI_CPU1_CPU0_P2P2_DP<18>")
	)
	(arc
		(start 338.919566 -287.273746)
		(mid 338.998936 -287.000012)
		(end 339.20176 -286.799782)
		(width 0.0889)
		(layer "In11.Cu")
		(net "UPI_CPU1_CPU0_P2P2_DP<18>")
	)
	(arc
		(start 104.797098 -283.219906)
		(mid 104.724863 -283.49643)
		(end 104.526588 -283.702252)
		(width 0.0889)
		(layer "In11.Cu")
		(net "UPI_CPU1_CPU0_P2P2_DP<18>")
	)
	(arc
		(start 337.786218 -282.077922)
		(mid 337.583631 -281.871571)
		(end 337.509612 -281.59202)
		(width 0.0889)
		(layer "In11.Cu")
		(net "UPI_CPU1_CPU0_P2P2_DP<18>")
	)
	(arc
		(start 337.509612 -281.583384)
		(mid 337.470938 -281.426316)
		(end 337.369658 -281.300174)
		(width 0.0889)
		(layer "In11.Cu")
		(net "UPI_CPU1_CPU0_P2P2_DP<18>")
	)
	(arc
		(start 103.09606 -287.783778)
		(mid 102.965146 -287.920138)
		(end 102.917498 -288.103056)
		(width 0.0889)
		(layer "In11.Cu")
		(net "UPI_CPU1_CPU0_P2P2_DP<18>")
	)
	(arc
		(start 103.574596 -285.985712)
		(mid 103.778077 -286.186516)
		(end 103.857298 -286.4612)
		(width 0.0889)
		(layer "In11.Cu")
		(net "UPI_CPU1_CPU0_P2P2_DP<18>")
	)
	(arc
		(start 103.857298 -284.847538)
		(mid 103.785063 -285.124062)
		(end 103.586788 -285.329884)
		(width 0.0889)
		(layer "In11.Cu")
		(net "UPI_CPU1_CPU0_P2P2_DP<18>")
	)
	(arc
		(start 104.140254 -282.34005)
		(mid 104.141555 -282.329623)
		(end 104.143048 -282.319222)
		(width 0.0889)
		(layer "In11.Cu")
		(net "UPI_CPU1_CPU0_P2P2_DP<18>")
	)
	(arc
		(start 102.631748 -289.277806)
		(mid 102.80588 -289.416653)
		(end 102.917244 -289.60953)
		(width 0.0889)
		(layer "In11.Cu")
		(net "UPI_CPU1_CPU0_P2P2_DP<18>")
	)
	(arc
		(start 104.326944 -284.049216)
		(mid 104.247574 -284.32295)
		(end 104.04475 -284.52318)
		(width 0.0889)
		(layer "In11.Cu")
		(net "UPI_CPU1_CPU0_P2P2_DP<18>")
	)
	(arc
		(start 103.387144 -287.304734)
		(mid 103.307774 -287.578468)
		(end 103.10495 -287.778698)
		(width 0.0889)
		(layer "In11.Cu")
		(net "UPI_CPU1_CPU0_P2P2_DP<18>")
	)
	(arc
		(start 338.73186 -283.709364)
		(mid 338.527525 -283.506759)
		(end 338.449412 -283.229812)
		(width 0.0889)
		(layer "In11.Cu")
		(net "UPI_CPU1_CPU0_P2P2_DP<18>")
	)
	(arc
		(start 104.98455 -281.916378)
		(mid 105.187373 -282.116609)
		(end 105.266744 -282.390342)
		(width 0.0889)
		(layer "In11.Cu")
		(net "UPI_CPU1_CPU0_P2P2_DP<18>")
	)
	(arc
		(start 103.565706 -286.969962)
		(mid 103.434792 -287.106322)
		(end 103.387144 -287.28924)
		(width 0.0889)
		(layer "In11.Cu")
		(net "UPI_CPU1_CPU0_P2P2_DP<18>")
	)
	(arc
		(start 103.387144 -285.65475)
		(mid 103.387056 -285.662751)
		(end 103.387144 -285.670752)
		(width 0.0889)
		(layer "In11.Cu")
		(net "UPI_CPU1_CPU0_P2P2_DP<18>")
	)
	(arc
		(start 103.387144 -285.670752)
		(mid 103.43704 -285.848399)
		(end 103.565706 -285.980632)
		(width 0.0889)
		(layer "In11.Cu")
		(net "UPI_CPU1_CPU0_P2P2_DP<18>")
	)
	(arc
		(start 339.20176 -286.151066)
		(mid 339.000478 -285.953579)
		(end 338.919566 -285.683452)
		(width 0.0889)
		(layer "In11.Cu")
		(net "UPI_CPU1_CPU0_P2P2_DP<18>")
	)
	(arc
		(start 338.919312 -284.033722)
		(mid 338.871633 -283.850822)
		(end 338.74075 -283.714444)
		(width 0.0889)
		(layer "In11.Cu")
		(net "UPI_CPU1_CPU0_P2P2_DP<18>")
	)
	(arc
		(start 104.433878 -281.907742)
		(mid 104.710353 -281.840422)
		(end 104.98455 -281.916378)
		(width 0.0889)
		(layer "In11.Cu")
		(net "UPI_CPU1_CPU0_P2P2_DP<18>")
	)
	(arc
		(start 102.62616 -288.597848)
		(mid 102.495246 -288.734208)
		(end 102.447598 -288.917126)
		(width 0.0889)
		(layer "In11.Cu")
		(net "UPI_CPU1_CPU0_P2P2_DP<18>")
	)
	(arc
		(start 338.741004 -287.608518)
		(mid 338.871918 -287.472158)
		(end 338.919566 -287.28924)
		(width 0.0889)
		(layer "In11.Cu")
		(net "UPI_CPU1_CPU0_P2P2_DP<18>")
	)
	(arc
		(start 102.917498 -288.121598)
		(mid 102.837336 -288.393787)
		(end 102.63505 -288.592768)
		(width 0.0889)
		(layer "In11.Cu")
		(net "UPI_CPU1_CPU0_P2P2_DP<18>")
	)
	(arc
		(start 337.979766 -288.917126)
		(mid 338.050559 -288.643189)
		(end 338.245196 -288.437828)
		(width 0.0889)
		(layer "In11.Cu")
		(net "UPI_CPU1_CPU0_P2P2_DP<18>")
	)
	(arc
		(start 339.388958 -284.840934)
		(mid 339.339851 -284.661745)
		(end 339.21065 -284.52826)
		(width 0.0889)
		(layer "In11.Cu")
		(net "UPI_CPU1_CPU0_P2P2_DP<18>")
	)
	(arc
		(start 104.505506 -283.714444)
		(mid 104.374592 -283.850804)
		(end 104.326944 -284.033722)
		(width 0.0889)
		(layer "In11.Cu")
		(net "UPI_CPU1_CPU0_P2P2_DP<18>")
	)
	(arc
		(start 338.919566 -285.64586)
		(mid 338.998936 -285.372126)
		(end 339.20176 -285.171896)
		(width 0.0889)
		(layer "In11.Cu")
		(net "UPI_CPU1_CPU0_P2P2_DP<18>")
	)
	(arc
		(start 103.565706 -285.342076)
		(mid 103.436417 -285.475562)
		(end 103.387144 -285.65475)
		(width 0.0889)
		(layer "In11.Cu")
		(net "UPI_CPU1_CPU0_P2P2_DP<18>")
	)
	(arc
		(start 339.21065 -286.794702)
		(mid 339.389247 -286.475424)
		(end 339.21065 -286.156146)
		(width 0.0889)
		(layer "In11.Cu")
		(net "UPI_CPU1_CPU0_P2P2_DP<18>")
	)
	(arc
		(start 104.03586 -284.52826)
		(mid 103.904946 -284.66462)
		(end 103.857298 -284.847538)
		(width 0.0889)
		(layer "In11.Cu")
		(net "UPI_CPU1_CPU0_P2P2_DP<18>")
	)
	(arc
		(start 338.449412 -283.219906)
		(mid 338.44936 -283.212539)
		(end 338.449158 -283.205174)
		(width 0.0889)
		(layer "In11.Cu")
		(net "UPI_CPU1_CPU0_P2P2_DP<18>")
	)
	(arc
		(start 338.449158 -288.117788)
		(mid 338.449355 -288.110423)
		(end 338.449412 -288.103056)
		(width 0.0889)
		(layer "In11.Cu")
		(net "UPI_CPU1_CPU0_P2P2_DP<18>")
	)
	(arc
		(start 339.388958 -284.857698)
		(mid 339.389052 -284.849316)
		(end 339.388958 -284.840934)
		(width 0.0889)
		(layer "In11.Cu")
		(net "UPI_CPU1_CPU0_P2P2_DP<18>")
	)
	(arc
		(start 102.447598 -289.078416)
		(mid 102.522603 -289.193875)
		(end 102.631748 -289.277806)
		(width 0.0889)
		(layer "In11.Cu")
		(net "UPI_CPU1_CPU0_P2P2_DP<18>")
	)
	(arc
		(start 337.979766 -282.405836)
		(mid 337.932087 -282.222936)
		(end 337.801204 -282.086558)
		(width 0.0889)
		(layer "In11.Cu")
		(net "UPI_CPU1_CPU0_P2P2_DP<18>")
	)
	(arc
		(start 338.449158 -283.205174)
		(mid 338.398104 -283.030594)
		(end 338.27085 -282.900628)
		(width 0.0889)
		(layer "In11.Cu")
		(net "UPI_CPU1_CPU0_P2P2_DP<18>")
	)
	(arc
		(start 339.21065 -285.166816)
		(mid 339.338969 -285.034844)
		(end 339.388958 -284.857698)
		(width 0.0889)
		(layer "In11.Cu")
		(net "UPI_CPU1_CPU0_P2P2_DP<18>")
	)
	(arc
		(start 338.449412 -288.103056)
		(mid 338.523403 -287.82349)
		(end 338.726018 -287.617154)
		(width 0.0889)
		(layer "In11.Cu")
		(net "UPI_CPU1_CPU0_P2P2_DP<18>")
	)
	(arc
		(start 339.20176 -284.52318)
		(mid 338.997425 -284.320575)
		(end 338.919312 -284.043628)
		(width 0.0889)
		(layer "In11.Cu")
		(net "UPI_CPU1_CPU0_P2P2_DP<18>")
	)
	(segment
		(start 344.183716 -280.778204)
		(end 344.183716 -280.242264)
		(width 0.13208)
		(layer "F.Cu")
		(net "UPI_CPU1_CPU0_P2P2_DP<17>")
	)
	(segment
		(start 104.231694 -281.05608)
		(end 104.231694 -281.591766)
		(width 0.13208)
		(layer "F.Cu")
		(net "UPI_CPU1_CPU0_P2P2_DP<17>")
	)
	(segment
		(start 104.231694 -281.591766)
		(end 104.231948 -281.59202)
		(width 0.13208)
		(layer "F.Cu")
		(net "UPI_CPU1_CPU0_P2P2_DP<17>")
	)
	(segment
		(start 71.887842 -326.319134)
		(end 72.976994 -324.015862)
		(width 0.14732)
		(layer "In11.Cu")
		(net "UPI_CPU1_CPU0_P2P2_DP<17>")
	)
	(segment
		(start 308.824884 -321.687698)
		(end 308.022498 -322.770754)
		(width 0.14732)
		(layer "In11.Cu")
		(net "UPI_CPU1_CPU0_P2P2_DP<17>")
	)
	(segment
		(start 342.971374 -281.273758)
		(end 342.96096 -281.267662)
		(width 0.0889)
		(layer "In11.Cu")
		(net "UPI_CPU1_CPU0_P2P2_DP<17>")
	)
	(segment
		(start 339.766656 -287.779206)
		(end 339.764116 -287.78073)
		(width 0.0889)
		(layer "In11.Cu")
		(net "UPI_CPU1_CPU0_P2P2_DP<17>")
	)
	(segment
		(start 102.069392 -287.613598)
		(end 102.078282 -287.608518)
		(width 0.0889)
		(layer "In11.Cu")
		(net "UPI_CPU1_CPU0_P2P2_DP<17>")
	)
	(segment
		(start 103.009192 -284.35808)
		(end 103.018082 -284.353)
		(width 0.0889)
		(layer "In11.Cu")
		(net "UPI_CPU1_CPU0_P2P2_DP<17>")
	)
	(segment
		(start 126.261368 -378.54509)
		(end 98.339148 -374.403112)
		(width 0.14732)
		(layer "In11.Cu")
		(net "UPI_CPU1_CPU0_P2P2_DP<17>")
	)
	(segment
		(start 104.075484 -281.321002)
		(end 104.231948 -281.59202)
		(width 0.0889)
		(layer "In11.Cu")
		(net "UPI_CPU1_CPU0_P2P2_DP<17>")
	)
	(segment
		(start 100.254816 -295.290748)
		(end 100.296726 -295.248838)
		(width 0.0889)
		(layer "In11.Cu")
		(net "UPI_CPU1_CPU0_P2P2_DP<17>")
	)
	(segment
		(start 104.099614 -281.231848)
		(end 104.075484 -281.321002)
		(width 0.0889)
		(layer "In11.Cu")
		(net "UPI_CPU1_CPU0_P2P2_DP<17>")
	)
	(segment
		(start 100.296726 -295.248838)
		(end 100.296726 -291.492432)
		(width 0.0889)
		(layer "In11.Cu")
		(net "UPI_CPU1_CPU0_P2P2_DP<17>")
	)
	(segment
		(start 100.296726 -291.492432)
		(end 101.786944 -290.002214)
		(width 0.0889)
		(layer "In11.Cu")
		(net "UPI_CPU1_CPU0_P2P2_DP<17>")
	)
	(segment
		(start 102.539292 -286.799782)
		(end 102.540054 -286.799274)
		(width 0.0889)
		(layer "In11.Cu")
		(net "UPI_CPU1_CPU0_P2P2_DP<17>")
	)
	(segment
		(start 252.647704 -366.77981)
		(end 252.219206 -366.704372)
		(width 0.14732)
		(layer "In11.Cu")
		(net "UPI_CPU1_CPU0_P2P2_DP<17>")
	)
	(segment
		(start 298.770548 -328.7649)
		(end 284.363668 -328.7649)
		(width 0.14732)
		(layer "In11.Cu")
		(net "UPI_CPU1_CPU0_P2P2_DP<17>")
	)
	(segment
		(start 246.518938 -362.86059)
		(end 236.99724 -369.527582)
		(width 0.14732)
		(layer "In11.Cu")
		(net "UPI_CPU1_CPU0_P2P2_DP<17>")
	)
	(segment
		(start 336.607404 -292.860476)
		(end 336.577686 -292.860476)
		(width 0.14732)
		(layer "In11.Cu")
		(net "UPI_CPU1_CPU0_P2P2_DP<17>")
	)
	(segment
		(start 70.603618 -335.176368)
		(end 71.248524 -328.628248)
		(width 0.14732)
		(layer "In11.Cu")
		(net "UPI_CPU1_CPU0_P2P2_DP<17>")
	)
	(segment
		(start 200.171558 -371.737636)
		(end 161.55797 -378.54509)
		(width 0.14732)
		(layer "In11.Cu")
		(net "UPI_CPU1_CPU0_P2P2_DP<17>")
	)
	(segment
		(start 341.929466 -282.405836)
		(end 341.929466 -282.42006)
		(width 0.0889)
		(layer "In11.Cu")
		(net "UPI_CPU1_CPU0_P2P2_DP<17>")
	)
	(segment
		(start 80.98536 -316.007242)
		(end 96.520508 -303.257966)
		(width 0.14732)
		(layer "In11.Cu")
		(net "UPI_CPU1_CPU0_P2P2_DP<17>")
	)
	(segment
		(start 340.249256 -285.329884)
		(end 340.237064 -285.336996)
		(width 0.0889)
		(layer "In11.Cu")
		(net "UPI_CPU1_CPU0_P2P2_DP<17>")
	)
	(segment
		(start 102.726744 -284.856174)
		(end 102.726744 -284.837632)
		(width 0.0889)
		(layer "In11.Cu")
		(net "UPI_CPU1_CPU0_P2P2_DP<17>")
	)
	(segment
		(start 339.767418 -287.778698)
		(end 339.766656 -287.779206)
		(width 0.0889)
		(layer "In11.Cu")
		(net "UPI_CPU1_CPU0_P2P2_DP<17>")
	)
	(segment
		(start 236.99724 -369.527582)
		(end 212.31225 -373.878602)
		(width 0.14732)
		(layer "In11.Cu")
		(net "UPI_CPU1_CPU0_P2P2_DP<17>")
	)
	(segment
		(start 103.006652 -282.0797)
		(end 103.005636 -282.079192)
		(width 0.0889)
		(layer "In11.Cu")
		(net "UPI_CPU1_CPU0_P2P2_DP<17>")
	)
	(segment
		(start 100.254816 -295.785286)
		(end 100.254816 -295.312846)
		(width 0.14732)
		(layer "In11.Cu")
		(net "UPI_CPU1_CPU0_P2P2_DP<17>")
	)
	(segment
		(start 306.802028 -323.991224)
		(end 301.240698 -326.294496)
		(width 0.14732)
		(layer "In11.Cu")
		(net "UPI_CPU1_CPU0_P2P2_DP<17>")
	)
	(segment
		(start 212.31225 -373.878602)
		(end 200.171558 -371.737636)
		(width 0.14732)
		(layer "In11.Cu")
		(net "UPI_CPU1_CPU0_P2P2_DP<17>")
	)
	(segment
		(start 312.47842 -318.719708)
		(end 310.181752 -319.358264)
		(width 0.14732)
		(layer "In11.Cu")
		(net "UPI_CPU1_CPU0_P2P2_DP<17>")
	)
	(segment
		(start 103.479092 -280.288492)
		(end 103.489506 -280.282396)
		(width 0.0889)
		(layer "In11.Cu")
		(net "UPI_CPU1_CPU0_P2P2_DP<17>")
	)
	(segment
		(start 102.540054 -286.799274)
		(end 102.548182 -286.794702)
		(width 0.0889)
		(layer "In11.Cu")
		(net "UPI_CPU1_CPU0_P2P2_DP<17>")
	)
	(segment
		(start 101.787198 -288.103056)
		(end 101.787198 -288.087562)
		(width 0.0889)
		(layer "In11.Cu")
		(net "UPI_CPU1_CPU0_P2P2_DP<17>")
	)
	(segment
		(start 334.876394 -293.565326)
		(end 333.92745 -294.985694)
		(width 0.14732)
		(layer "In11.Cu")
		(net "UPI_CPU1_CPU0_P2P2_DP<17>")
	)
	(segment
		(start 251.495052 -367.21161)
		(end 251.419614 -367.640108)
		(width 0.14732)
		(layer "In11.Cu")
		(net "UPI_CPU1_CPU0_P2P2_DP<17>")
	)
	(segment
		(start 101.603048 -289.446462)
		(end 101.602794 -289.446462)
		(width 0.0889)
		(layer "In11.Cu")
		(net "UPI_CPU1_CPU0_P2P2_DP<17>")
	)
	(segment
		(start 77.432154 -365.742728)
		(end 74.514964 -362.825538)
		(width 0.14732)
		(layer "In11.Cu")
		(net "UPI_CPU1_CPU0_P2P2_DP<17>")
	)
	(segment
		(start 342.58504 -281.268424)
		(end 342.577674 -281.272742)
		(width 0.0889)
		(layer "In11.Cu")
		(net "UPI_CPU1_CPU0_P2P2_DP<17>")
	)
	(segment
		(start 253.393448 -365.882174)
		(end 253.31801 -366.310672)
		(width 0.14732)
		(layer "In11.Cu")
		(net "UPI_CPU1_CPU0_P2P2_DP<17>")
	)
	(segment
		(start 333.92745 -294.985694)
		(end 332.08087 -301.070772)
		(width 0.14732)
		(layer "In11.Cu")
		(net "UPI_CPU1_CPU0_P2P2_DP<17>")
	)
	(segment
		(start 310.181752 -319.358518)
		(end 309.336948 -320.138298)
		(width 0.14732)
		(layer "In11.Cu")
		(net "UPI_CPU1_CPU0_P2P2_DP<17>")
	)
	(segment
		(start 252.219206 -366.704372)
		(end 248.622312 -361.567476)
		(width 0.14732)
		(layer "In11.Cu")
		(net "UPI_CPU1_CPU0_P2P2_DP<17>")
	)
	(segment
		(start 301.240698 -326.294496)
		(end 298.770548 -328.7649)
		(width 0.14732)
		(layer "In11.Cu")
		(net "UPI_CPU1_CPU0_P2P2_DP<17>")
	)
	(segment
		(start 101.786944 -290.002214)
		(end 101.786944 -289.645852)
		(width 0.0889)
		(layer "In11.Cu")
		(net "UPI_CPU1_CPU0_P2P2_DP<17>")
	)
	(segment
		(start 340.519512 -283.219906)
		(end 340.519512 -283.229812)
		(width 0.0889)
		(layer "In11.Cu")
		(net "UPI_CPU1_CPU0_P2P2_DP<17>")
	)
	(segment
		(start 253.31801 -366.310672)
		(end 252.647704 -366.77981)
		(width 0.14732)
		(layer "In11.Cu")
		(net "UPI_CPU1_CPU0_P2P2_DP<17>")
	)
	(segment
		(start 97.96653 -301.30877)
		(end 100.254816 -295.785286)
		(width 0.14732)
		(layer "In11.Cu")
		(net "UPI_CPU1_CPU0_P2P2_DP<17>")
	)
	(segment
		(start 71.248524 -328.628248)
		(end 71.887842 -326.319134)
		(width 0.14732)
		(layer "In11.Cu")
		(net "UPI_CPU1_CPU0_P2P2_DP<17>")
	)
	(segment
		(start 70.603618 -353.382072)
		(end 70.603618 -335.176368)
		(width 0.14732)
		(layer "In11.Cu")
		(net "UPI_CPU1_CPU0_P2P2_DP<17>")
	)
	(segment
		(start 101.599746 -288.427414)
		(end 101.608636 -288.422334)
		(width 0.0889)
		(layer "In11.Cu")
		(net "UPI_CPU1_CPU0_P2P2_DP<17>")
	)
	(segment
		(start 250.749308 -368.109246)
		(end 250.32081 -368.033808)
		(width 0.14732)
		(layer "In11.Cu")
		(net "UPI_CPU1_CPU0_P2P2_DP<17>")
	)
	(segment
		(start 103.487982 -282.900628)
		(end 103.479092 -282.895548)
		(width 0.0889)
		(layer "In11.Cu")
		(net "UPI_CPU1_CPU0_P2P2_DP<17>")
	)
	(segment
		(start 250.537218 -360.047032)
		(end 249.832876 -360.5403)
		(width 0.14732)
		(layer "In11.Cu")
		(net "UPI_CPU1_CPU0_P2P2_DP<17>")
	)
	(segment
		(start 103.005636 -282.079192)
		(end 103.00335 -282.077922)
		(width 0.0889)
		(layer "In11.Cu")
		(net "UPI_CPU1_CPU0_P2P2_DP<17>")
	)
	(segment
		(start 248.622312 -361.567476)
		(end 248.417334 -361.531154)
		(width 0.14732)
		(layer "In11.Cu")
		(net "UPI_CPU1_CPU0_P2P2_DP<17>")
	)
	(segment
		(start 332.08087 -301.070772)
		(end 315.809884 -317.341504)
		(width 0.14732)
		(layer "In11.Cu")
		(net "UPI_CPU1_CPU0_P2P2_DP<17>")
	)
	(segment
		(start 339.110066 -288.917126)
		(end 339.110066 -289.114484)
		(width 0.0889)
		(layer "In11.Cu")
		(net "UPI_CPU1_CPU0_P2P2_DP<17>")
	)
	(segment
		(start 339.579966 -288.103056)
		(end 339.579966 -288.11728)
		(width 0.0889)
		(layer "In11.Cu")
		(net "UPI_CPU1_CPU0_P2P2_DP<17>")
	)
	(segment
		(start 344.183716 -280.778204)
		(end 343.871042 -280.778204)
		(width 0.0889)
		(layer "In11.Cu")
		(net "UPI_CPU1_CPU0_P2P2_DP<17>")
	)
	(segment
		(start 315.809884 -317.341504)
		(end 312.47842 -318.719708)
		(width 0.14732)
		(layer "In11.Cu")
		(net "UPI_CPU1_CPU0_P2P2_DP<17>")
	)
	(segment
		(start 340.049866 -285.652718)
		(end 340.049866 -285.66999)
		(width 0.0889)
		(layer "In11.Cu")
		(net "UPI_CPU1_CPU0_P2P2_DP<17>")
	)
	(segment
		(start 284.363668 -328.7649)
		(end 277.923752 -331.432408)
		(width 0.14732)
		(layer "In11.Cu")
		(net "UPI_CPU1_CPU0_P2P2_DP<17>")
	)
	(segment
		(start 103.196644 -280.78684)
		(end 103.196644 -280.759662)
		(width 0.0889)
		(layer "In11.Cu")
		(net "UPI_CPU1_CPU0_P2P2_DP<17>")
	)
	(segment
		(start 338.639912 -290.275264)
		(end 338.682076 -290.317428)
		(width 0.0889)
		(layer "In11.Cu")
		(net "UPI_CPU1_CPU0_P2P2_DP<17>")
	)
	(segment
		(start 339.297518 -288.592768)
		(end 339.288628 -288.597848)
		(width 0.0889)
		(layer "In11.Cu")
		(net "UPI_CPU1_CPU0_P2P2_DP<17>")
	)
	(segment
		(start 101.317298 -289.114738)
		(end 101.317298 -288.898584)
		(width 0.0889)
		(layer "In11.Cu")
		(net "UPI_CPU1_CPU0_P2P2_DP<17>")
	)
	(segment
		(start 340.237318 -286.964882)
		(end 340.228428 -286.969962)
		(width 0.0889)
		(layer "In11.Cu")
		(net "UPI_CPU1_CPU0_P2P2_DP<17>")
	)
	(segment
		(start 342.586564 -281.267662)
		(end 342.58504 -281.268424)
		(width 0.0889)
		(layer "In11.Cu")
		(net "UPI_CPU1_CPU0_P2P2_DP<17>")
	)
	(segment
		(start 102.53345 -285.175452)
		(end 102.538784 -285.172404)
		(width 0.0889)
		(layer "In11.Cu")
		(net "UPI_CPU1_CPU0_P2P2_DP<17>")
	)
	(segment
		(start 340.519766 -286.4612)
		(end 340.519766 -286.48533)
		(width 0.0889)
		(layer "In11.Cu")
		(net "UPI_CPU1_CPU0_P2P2_DP<17>")
	)
	(segment
		(start 342.116918 -282.081478)
		(end 342.108028 -282.086558)
		(width 0.0889)
		(layer "In11.Cu")
		(net "UPI_CPU1_CPU0_P2P2_DP<17>")
	)
	(segment
		(start 103.479854 -283.543756)
		(end 103.487982 -283.539184)
		(width 0.0889)
		(layer "In11.Cu")
		(net "UPI_CPU1_CPU0_P2P2_DP<17>")
	)
	(segment
		(start 336.577686 -292.860476)
		(end 334.876394 -293.565326)
		(width 0.14732)
		(layer "In11.Cu")
		(net "UPI_CPU1_CPU0_P2P2_DP<17>")
	)
	(segment
		(start 342.399112 -281.59202)
		(end 342.399112 -281.607514)
		(width 0.0889)
		(layer "In11.Cu")
		(net "UPI_CPU1_CPU0_P2P2_DP<17>")
	)
	(segment
		(start 74.514964 -362.825538)
		(end 70.603618 -353.382072)
		(width 0.14732)
		(layer "In11.Cu")
		(net "UPI_CPU1_CPU0_P2P2_DP<17>")
	)
	(segment
		(start 247.898158 -362.074714)
		(end 251.495052 -367.21161)
		(width 0.14732)
		(layer "In11.Cu")
		(net "UPI_CPU1_CPU0_P2P2_DP<17>")
	)
	(segment
		(start 102.538784 -285.172404)
		(end 102.539546 -285.171896)
		(width 0.0889)
		(layer "In11.Cu")
		(net "UPI_CPU1_CPU0_P2P2_DP<17>")
	)
	(segment
		(start 308.022498 -322.770754)
		(end 306.802028 -323.991224)
		(width 0.14732)
		(layer "In11.Cu")
		(net "UPI_CPU1_CPU0_P2P2_DP<17>")
	)
	(segment
		(start 309.336948 -320.138298)
		(end 308.824884 -321.687698)
		(width 0.14732)
		(layer "In11.Cu")
		(net "UPI_CPU1_CPU0_P2P2_DP<17>")
	)
	(segment
		(start 338.682076 -290.317428)
		(end 338.682076 -290.339526)
		(width 0.0889)
		(layer "In11.Cu")
		(net "UPI_CPU1_CPU0_P2P2_DP<17>")
	)
	(segment
		(start 338.682076 -290.785804)
		(end 336.607404 -292.860476)
		(width 0.14732)
		(layer "In11.Cu")
		(net "UPI_CPU1_CPU0_P2P2_DP<17>")
	)
	(segment
		(start 100.254816 -295.312846)
		(end 100.254816 -295.290748)
		(width 0.0889)
		(layer "In11.Cu")
		(net "UPI_CPU1_CPU0_P2P2_DP<17>")
	)
	(segment
		(start 102.256844 -285.679896)
		(end 102.256844 -285.661354)
		(width 0.0889)
		(layer "In11.Cu")
		(net "UPI_CPU1_CPU0_P2P2_DP<17>")
	)
	(segment
		(start 340.706964 -282.895548)
		(end 340.698074 -282.900628)
		(width 0.0889)
		(layer "In11.Cu")
		(net "UPI_CPU1_CPU0_P2P2_DP<17>")
	)
	(segment
		(start 253.653798 -355.595936)
		(end 250.537218 -360.047032)
		(width 0.14732)
		(layer "In11.Cu")
		(net "UPI_CPU1_CPU0_P2P2_DP<17>")
	)
	(segment
		(start 72.976994 -324.015862)
		(end 80.98536 -316.007242)
		(width 0.14732)
		(layer "In11.Cu")
		(net "UPI_CPU1_CPU0_P2P2_DP<17>")
	)
	(segment
		(start 343.532714 -281.264106)
		(end 343.526618 -281.267662)
		(width 0.0889)
		(layer "In11.Cu")
		(net "UPI_CPU1_CPU0_P2P2_DP<17>")
	)
	(segment
		(start 246.723916 -362.896912)
		(end 246.518938 -362.86059)
		(width 0.14732)
		(layer "In11.Cu")
		(net "UPI_CPU1_CPU0_P2P2_DP<17>")
	)
	(segment
		(start 343.871042 -280.778204)
		(end 343.805256 -280.84399)
		(width 0.0889)
		(layer "In11.Cu")
		(net "UPI_CPU1_CPU0_P2P2_DP<17>")
	)
	(segment
		(start 103.009446 -282.081478)
		(end 103.006652 -282.0797)
		(width 0.0889)
		(layer "In11.Cu")
		(net "UPI_CPU1_CPU0_P2P2_DP<17>")
	)
	(segment
		(start 339.764116 -287.78073)
		(end 339.758528 -287.783778)
		(width 0.0889)
		(layer "In11.Cu")
		(net "UPI_CPU1_CPU0_P2P2_DP<17>")
	)
	(segment
		(start 97.243392 -302.283622)
		(end 97.96653 -301.30877)
		(width 0.14732)
		(layer "In11.Cu")
		(net "UPI_CPU1_CPU0_P2P2_DP<17>")
	)
	(segment
		(start 253.990348 -355.360478)
		(end 253.653798 -355.595936)
		(width 0.14732)
		(layer "In11.Cu")
		(net "UPI_CPU1_CPU0_P2P2_DP<17>")
	)
	(segment
		(start 96.520508 -303.257966)
		(end 97.243392 -302.283368)
		(width 0.14732)
		(layer "In11.Cu")
		(net "UPI_CPU1_CPU0_P2P2_DP<17>")
	)
	(segment
		(start 277.923752 -331.432408)
		(end 253.990348 -355.360478)
		(width 0.14732)
		(layer "In11.Cu")
		(net "UPI_CPU1_CPU0_P2P2_DP<17>")
	)
	(segment
		(start 338.639912 -289.776662)
		(end 338.639912 -290.275264)
		(width 0.0889)
		(layer "In11.Cu")
		(net "UPI_CPU1_CPU0_P2P2_DP<17>")
	)
	(segment
		(start 250.32081 -368.033808)
		(end 246.723916 -362.896912)
		(width 0.14732)
		(layer "In11.Cu")
		(net "UPI_CPU1_CPU0_P2P2_DP<17>")
	)
	(segment
		(start 340.237064 -284.35808)
		(end 340.240874 -284.360366)
		(width 0.0889)
		(layer "In11.Cu")
		(net "UPI_CPU1_CPU0_P2P2_DP<17>")
	)
	(segment
		(start 340.237064 -283.709364)
		(end 340.228174 -283.714444)
		(width 0.0889)
		(layer "In11.Cu")
		(net "UPI_CPU1_CPU0_P2P2_DP<17>")
	)
	(segment
		(start 97.243392 -302.283368)
		(end 97.243392 -302.283622)
		(width 0.14732)
		(layer "In11.Cu")
		(net "UPI_CPU1_CPU0_P2P2_DP<17>")
	)
	(segment
		(start 103.479092 -283.544264)
		(end 103.479854 -283.543756)
		(width 0.0889)
		(layer "In11.Cu")
		(net "UPI_CPU1_CPU0_P2P2_DP<17>")
	)
	(segment
		(start 102.256844 -287.28924)
		(end 102.256844 -287.279334)
		(width 0.0889)
		(layer "In11.Cu")
		(net "UPI_CPU1_CPU0_P2P2_DP<17>")
	)
	(segment
		(start 247.93448 -361.869736)
		(end 247.898158 -362.074714)
		(width 0.14732)
		(layer "In11.Cu")
		(net "UPI_CPU1_CPU0_P2P2_DP<17>")
	)
	(segment
		(start 103.196644 -282.424378)
		(end 103.196644 -282.3972)
		(width 0.0889)
		(layer "In11.Cu")
		(net "UPI_CPU1_CPU0_P2P2_DP<17>")
	)
	(segment
		(start 161.55797 -378.54509)
		(end 126.261368 -378.54509)
		(width 0.14732)
		(layer "In11.Cu")
		(net "UPI_CPU1_CPU0_P2P2_DP<17>")
	)
	(segment
		(start 338.682076 -290.339526)
		(end 338.682076 -290.785804)
		(width 0.14732)
		(layer "In11.Cu")
		(net "UPI_CPU1_CPU0_P2P2_DP<17>")
	)
	(segment
		(start 103.196644 -284.033722)
		(end 103.196644 -284.023816)
		(width 0.0889)
		(layer "In11.Cu")
		(net "UPI_CPU1_CPU0_P2P2_DP<17>")
	)
	(segment
		(start 103.00335 -281.106118)
		(end 103.009446 -281.102562)
		(width 0.0889)
		(layer "In11.Cu")
		(net "UPI_CPU1_CPU0_P2P2_DP<17>")
	)
	(segment
		(start 102.548182 -286.156146)
		(end 102.539292 -286.151066)
		(width 0.0889)
		(layer "In11.Cu")
		(net "UPI_CPU1_CPU0_P2P2_DP<17>")
	)
	(segment
		(start 98.339148 -374.403112)
		(end 77.432154 -365.742728)
		(width 0.14732)
		(layer "In11.Cu")
		(net "UPI_CPU1_CPU0_P2P2_DP<17>")
	)
	(segment
		(start 340.240874 -284.360366)
		(end 340.249256 -284.365192)
		(width 0.0889)
		(layer "In11.Cu")
		(net "UPI_CPU1_CPU0_P2P2_DP<17>")
	)
	(segment
		(start 248.417334 -361.531154)
		(end 247.93448 -361.869736)
		(width 0.14732)
		(layer "In11.Cu")
		(net "UPI_CPU1_CPU0_P2P2_DP<17>")
	)
	(segment
		(start 251.419614 -367.640108)
		(end 250.749308 -368.109246)
		(width 0.14732)
		(layer "In11.Cu")
		(net "UPI_CPU1_CPU0_P2P2_DP<17>")
	)
	(segment
		(start 341.646764 -282.895548)
		(end 341.632032 -282.904184)
		(width 0.0889)
		(layer "In11.Cu")
		(net "UPI_CPU1_CPU0_P2P2_DP<17>")
	)
	(segment
		(start 104.326944 -280.756106)
		(end 104.326944 -280.793698)
		(width 0.0889)
		(layer "In11.Cu")
		(net "UPI_CPU1_CPU0_P2P2_DP<17>")
	)
	(segment
		(start 310.181752 -319.358264)
		(end 310.181752 -319.358518)
		(width 0.14732)
		(layer "In11.Cu")
		(net "UPI_CPU1_CPU0_P2P2_DP<17>")
	)
	(segment
		(start 340.049866 -287.28924)
		(end 340.049866 -287.299146)
		(width 0.0889)
		(layer "In11.Cu")
		(net "UPI_CPU1_CPU0_P2P2_DP<17>")
	)
	(segment
		(start 249.796554 -360.745278)
		(end 253.393448 -365.882174)
		(width 0.14732)
		(layer "In11.Cu")
		(net "UPI_CPU1_CPU0_P2P2_DP<17>")
	)
	(segment
		(start 249.832876 -360.5403)
		(end 249.796554 -360.745278)
		(width 0.14732)
		(layer "In11.Cu")
		(net "UPI_CPU1_CPU0_P2P2_DP<17>")
	)
	(segment
		(start 340.228174 -284.353)
		(end 340.237064 -284.35808)
		(width 0.0889)
		(layer "In11.Cu")
		(net "UPI_CPU1_CPU0_P2P2_DP<17>")
	)
	(segment
		(start 338.652612 -289.619182)
		(end 338.639912 -289.776662)
		(width 0.0889)
		(layer "In11.Cu")
		(net "UPI_CPU1_CPU0_P2P2_DP<17>")
	)
	(arc
		(start 343.805256 -280.84399)
		(mid 343.803955 -280.854417)
		(end 343.802462 -280.864818)
		(width 0.0889)
		(layer "In11.Cu")
		(net "UPI_CPU1_CPU0_P2P2_DP<17>")
	)
	(arc
		(start 340.237064 -285.336996)
		(mid 340.102131 -285.47035)
		(end 340.049866 -285.652718)
		(width 0.0889)
		(layer "In11.Cu")
		(net "UPI_CPU1_CPU0_P2P2_DP<17>")
	)
	(arc
		(start 103.00335 -282.077922)
		(mid 102.7269 -281.59202)
		(end 103.00335 -281.106118)
		(width 0.0889)
		(layer "In11.Cu")
		(net "UPI_CPU1_CPU0_P2P2_DP<17>")
	)
	(arc
		(start 103.196644 -284.023816)
		(mid 103.274755 -283.746867)
		(end 103.479092 -283.544264)
		(width 0.0889)
		(layer "In11.Cu")
		(net "UPI_CPU1_CPU0_P2P2_DP<17>")
	)
	(arc
		(start 340.228174 -283.714444)
		(mid 340.049577 -284.033722)
		(end 340.228174 -284.353)
		(width 0.0889)
		(layer "In11.Cu")
		(net "UPI_CPU1_CPU0_P2P2_DP<17>")
	)
	(arc
		(start 343.526618 -281.267662)
		(mid 343.249805 -281.343532)
		(end 342.971374 -281.273758)
		(width 0.0889)
		(layer "In11.Cu")
		(net "UPI_CPU1_CPU0_P2P2_DP<17>")
	)
	(arc
		(start 101.786944 -289.645852)
		(mid 101.71206 -289.530419)
		(end 101.603048 -289.446462)
		(width 0.0889)
		(layer "In11.Cu")
		(net "UPI_CPU1_CPU0_P2P2_DP<17>")
	)
	(arc
		(start 340.698074 -282.900628)
		(mid 340.56716 -283.036988)
		(end 340.519512 -283.219906)
		(width 0.0889)
		(layer "In11.Cu")
		(net "UPI_CPU1_CPU0_P2P2_DP<17>")
	)
	(arc
		(start 340.237064 -285.985712)
		(mid 340.440545 -286.186516)
		(end 340.519766 -286.4612)
		(width 0.0889)
		(layer "In11.Cu")
		(net "UPI_CPU1_CPU0_P2P2_DP<17>")
	)
	(arc
		(start 342.399112 -281.607514)
		(mid 342.319742 -281.881248)
		(end 342.116918 -282.081478)
		(width 0.0889)
		(layer "In11.Cu")
		(net "UPI_CPU1_CPU0_P2P2_DP<17>")
	)
	(arc
		(start 342.577674 -281.272742)
		(mid 342.44676 -281.409102)
		(end 342.399112 -281.59202)
		(width 0.0889)
		(layer "In11.Cu")
		(net "UPI_CPU1_CPU0_P2P2_DP<17>")
	)
	(arc
		(start 102.078282 -287.608518)
		(mid 102.209196 -287.472158)
		(end 102.256844 -287.28924)
		(width 0.0889)
		(layer "In11.Cu")
		(net "UPI_CPU1_CPU0_P2P2_DP<17>")
	)
	(arc
		(start 341.08136 -282.895548)
		(mid 340.894162 -282.845405)
		(end 340.706964 -282.895548)
		(width 0.0889)
		(layer "In11.Cu")
		(net "UPI_CPU1_CPU0_P2P2_DP<17>")
	)
	(arc
		(start 342.108028 -282.086558)
		(mid 341.977114 -282.222918)
		(end 341.929466 -282.405836)
		(width 0.0889)
		(layer "In11.Cu")
		(net "UPI_CPU1_CPU0_P2P2_DP<17>")
	)
	(arc
		(start 102.726744 -284.837632)
		(mid 102.804855 -284.560683)
		(end 103.009192 -284.35808)
		(width 0.0889)
		(layer "In11.Cu")
		(net "UPI_CPU1_CPU0_P2P2_DP<17>")
	)
	(arc
		(start 101.608636 -288.422334)
		(mid 101.73955 -288.285974)
		(end 101.787198 -288.103056)
		(width 0.0889)
		(layer "In11.Cu")
		(net "UPI_CPU1_CPU0_P2P2_DP<17>")
	)
	(arc
		(start 102.548182 -286.794702)
		(mid 102.726779 -286.475424)
		(end 102.548182 -286.156146)
		(width 0.0889)
		(layer "In11.Cu")
		(net "UPI_CPU1_CPU0_P2P2_DP<17>")
	)
	(arc
		(start 103.666544 -283.22651)
		(mid 103.666534 -283.21711)
		(end 103.66629 -283.207714)
		(width 0.0889)
		(layer "In11.Cu")
		(net "UPI_CPU1_CPU0_P2P2_DP<17>")
	)
	(arc
		(start 104.04475 -280.288492)
		(mid 104.246032 -280.485979)
		(end 104.326944 -280.756106)
		(width 0.0889)
		(layer "In11.Cu")
		(net "UPI_CPU1_CPU0_P2P2_DP<17>")
	)
	(arc
		(start 341.929466 -282.42006)
		(mid 341.850247 -282.694745)
		(end 341.646764 -282.895548)
		(width 0.0889)
		(layer "In11.Cu")
		(net "UPI_CPU1_CPU0_P2P2_DP<17>")
	)
	(arc
		(start 339.579966 -288.11728)
		(mid 339.500825 -288.391903)
		(end 339.297518 -288.592768)
		(width 0.0889)
		(layer "In11.Cu")
		(net "UPI_CPU1_CPU0_P2P2_DP<17>")
	)
	(arc
		(start 103.196644 -280.759662)
		(mid 103.276806 -280.487473)
		(end 103.479092 -280.288492)
		(width 0.0889)
		(layer "In11.Cu")
		(net "UPI_CPU1_CPU0_P2P2_DP<17>")
	)
	(arc
		(start 339.110066 -289.114484)
		(mid 338.99867 -289.307577)
		(end 338.824316 -289.446462)
		(width 0.0889)
		(layer "In11.Cu")
		(net "UPI_CPU1_CPU0_P2P2_DP<17>")
	)
	(arc
		(start 103.479092 -282.895548)
		(mid 103.276806 -282.696567)
		(end 103.196644 -282.424378)
		(width 0.0889)
		(layer "In11.Cu")
		(net "UPI_CPU1_CPU0_P2P2_DP<17>")
	)
	(arc
		(start 340.228428 -286.969962)
		(mid 340.097514 -287.106322)
		(end 340.049866 -287.28924)
		(width 0.0889)
		(layer "In11.Cu")
		(net "UPI_CPU1_CPU0_P2P2_DP<17>")
	)
	(arc
		(start 340.049866 -285.66999)
		(mid 340.102136 -285.852355)
		(end 340.237064 -285.985712)
		(width 0.0889)
		(layer "In11.Cu")
		(net "UPI_CPU1_CPU0_P2P2_DP<17>")
	)
	(arc
		(start 340.049866 -287.299146)
		(mid 339.971755 -287.576095)
		(end 339.767418 -287.778698)
		(width 0.0889)
		(layer "In11.Cu")
		(net "UPI_CPU1_CPU0_P2P2_DP<17>")
	)
	(arc
		(start 341.632032 -282.904184)
		(mid 341.355591 -282.97135)
		(end 341.08136 -282.895548)
		(width 0.0889)
		(layer "In11.Cu")
		(net "UPI_CPU1_CPU0_P2P2_DP<17>")
	)
	(arc
		(start 104.116378 -281.218894)
		(mid 104.108058 -281.225451)
		(end 104.099614 -281.231848)
		(width 0.0889)
		(layer "In11.Cu")
		(net "UPI_CPU1_CPU0_P2P2_DP<17>")
	)
	(arc
		(start 102.539292 -286.151066)
		(mid 102.337006 -285.952085)
		(end 102.256844 -285.679896)
		(width 0.0889)
		(layer "In11.Cu")
		(net "UPI_CPU1_CPU0_P2P2_DP<17>")
	)
	(arc
		(start 102.539546 -285.171896)
		(mid 102.674479 -285.038542)
		(end 102.726744 -284.856174)
		(width 0.0889)
		(layer "In11.Cu")
		(net "UPI_CPU1_CPU0_P2P2_DP<17>")
	)
	(arc
		(start 101.602794 -289.446462)
		(mid 101.428662 -289.307615)
		(end 101.317298 -289.114738)
		(width 0.0889)
		(layer "In11.Cu")
		(net "UPI_CPU1_CPU0_P2P2_DP<17>")
	)
	(arc
		(start 339.758528 -287.783778)
		(mid 339.627614 -287.920138)
		(end 339.579966 -288.103056)
		(width 0.0889)
		(layer "In11.Cu")
		(net "UPI_CPU1_CPU0_P2P2_DP<17>")
	)
	(arc
		(start 103.487982 -283.539184)
		(mid 103.617271 -283.405698)
		(end 103.666544 -283.22651)
		(width 0.0889)
		(layer "In11.Cu")
		(net "UPI_CPU1_CPU0_P2P2_DP<17>")
	)
	(arc
		(start 103.196644 -282.3972)
		(mid 103.144374 -282.214835)
		(end 103.009446 -282.081478)
		(width 0.0889)
		(layer "In11.Cu")
		(net "UPI_CPU1_CPU0_P2P2_DP<17>")
	)
	(arc
		(start 104.326944 -280.793698)
		(mid 104.268391 -281.029428)
		(end 104.116378 -281.218894)
		(width 0.0889)
		(layer "In11.Cu")
		(net "UPI_CPU1_CPU0_P2P2_DP<17>")
	)
	(arc
		(start 342.96096 -281.267662)
		(mid 342.773762 -281.217519)
		(end 342.586564 -281.267662)
		(width 0.0889)
		(layer "In11.Cu")
		(net "UPI_CPU1_CPU0_P2P2_DP<17>")
	)
	(arc
		(start 340.519766 -286.48533)
		(mid 340.441655 -286.762279)
		(end 340.237318 -286.964882)
		(width 0.0889)
		(layer "In11.Cu")
		(net "UPI_CPU1_CPU0_P2P2_DP<17>")
	)
	(arc
		(start 340.519512 -283.229812)
		(mid 340.441401 -283.506761)
		(end 340.237064 -283.709364)
		(width 0.0889)
		(layer "In11.Cu")
		(net "UPI_CPU1_CPU0_P2P2_DP<17>")
	)
	(arc
		(start 103.009446 -281.102562)
		(mid 103.144379 -280.969208)
		(end 103.196644 -280.78684)
		(width 0.0889)
		(layer "In11.Cu")
		(net "UPI_CPU1_CPU0_P2P2_DP<17>")
	)
	(arc
		(start 338.824316 -289.446462)
		(mid 338.725296 -289.519724)
		(end 338.652612 -289.619182)
		(width 0.0889)
		(layer "In11.Cu")
		(net "UPI_CPU1_CPU0_P2P2_DP<17>")
	)
	(arc
		(start 103.018082 -284.353)
		(mid 103.148996 -284.21664)
		(end 103.196644 -284.033722)
		(width 0.0889)
		(layer "In11.Cu")
		(net "UPI_CPU1_CPU0_P2P2_DP<17>")
	)
	(arc
		(start 102.256844 -287.279334)
		(mid 102.334955 -287.002385)
		(end 102.539292 -286.799782)
		(width 0.0889)
		(layer "In11.Cu")
		(net "UPI_CPU1_CPU0_P2P2_DP<17>")
	)
	(arc
		(start 340.249256 -284.365192)
		(mid 340.519712 -284.847538)
		(end 340.249256 -285.329884)
		(width 0.0889)
		(layer "In11.Cu")
		(net "UPI_CPU1_CPU0_P2P2_DP<17>")
	)
	(arc
		(start 343.802462 -280.864818)
		(mid 343.712285 -281.094671)
		(end 343.532714 -281.264106)
		(width 0.0889)
		(layer "In11.Cu")
		(net "UPI_CPU1_CPU0_P2P2_DP<17>")
	)
	(arc
		(start 103.489506 -280.282396)
		(mid 103.767938 -280.212582)
		(end 104.04475 -280.288492)
		(width 0.0889)
		(layer "In11.Cu")
		(net "UPI_CPU1_CPU0_P2P2_DP<17>")
	)
	(arc
		(start 103.66629 -283.207714)
		(mid 103.615797 -283.031736)
		(end 103.487982 -282.900628)
		(width 0.0889)
		(layer "In11.Cu")
		(net "UPI_CPU1_CPU0_P2P2_DP<17>")
	)
	(arc
		(start 102.256844 -285.661354)
		(mid 102.330835 -285.381788)
		(end 102.53345 -285.175452)
		(width 0.0889)
		(layer "In11.Cu")
		(net "UPI_CPU1_CPU0_P2P2_DP<17>")
	)
	(arc
		(start 339.288628 -288.597848)
		(mid 339.157714 -288.734208)
		(end 339.110066 -288.917126)
		(width 0.0889)
		(layer "In11.Cu")
		(net "UPI_CPU1_CPU0_P2P2_DP<17>")
	)
	(arc
		(start 101.317298 -288.898584)
		(mid 101.39746 -288.626395)
		(end 101.599746 -288.427414)
		(width 0.0889)
		(layer "In11.Cu")
		(net "UPI_CPU1_CPU0_P2P2_DP<17>")
	)
	(arc
		(start 101.787198 -288.087562)
		(mid 101.866568 -287.813828)
		(end 102.069392 -287.613598)
		(width 0.0889)
		(layer "In11.Cu")
		(net "UPI_CPU1_CPU0_P2P2_DP<17>")
	)
	(segment
		(start 343.713562 -281.591766)
		(end 343.713816 -281.59202)
		(width 0.13208)
		(layer "F.Cu")
		(net "UPI_CPU1_CPU0_P2P2_DP<16>")
	)
	(segment
		(start 101.882448 -281.869896)
		(end 101.882448 -282.405582)
		(width 0.13208)
		(layer "F.Cu")
		(net "UPI_CPU1_CPU0_P2P2_DP<16>")
	)
	(segment
		(start 101.882448 -282.405582)
		(end 101.882194 -282.405836)
		(width 0.13208)
		(layer "F.Cu")
		(net "UPI_CPU1_CPU0_P2P2_DP<16>")
	)
	(segment
		(start 343.713562 -281.05608)
		(end 343.713562 -281.591766)
		(width 0.13208)
		(layer "F.Cu")
		(net "UPI_CPU1_CPU0_P2P2_DP<16>")
	)
	(segment
		(start 309.587138 -321.616832)
		(end 308.835044 -322.80987)
		(width 0.14732)
		(layer "In11.Cu")
		(net "UPI_CPU1_CPU0_P2P2_DP<16>")
	)
	(segment
		(start 246.936514 -368.085116)
		(end 246.130826 -367.942876)
		(width 0.14732)
		(layer "In11.Cu")
		(net "UPI_CPU1_CPU0_P2P2_DP<16>")
	)
	(segment
		(start 70.047358 -353.502722)
		(end 70.047358 -335.013808)
		(width 0.14732)
		(layer "In11.Cu")
		(net "UPI_CPU1_CPU0_P2P2_DP<16>")
	)
	(segment
		(start 284.445964 -329.33767)
		(end 278.271224 -331.895196)
		(width 0.14732)
		(layer "In11.Cu")
		(net "UPI_CPU1_CPU0_P2P2_DP<16>")
	)
	(segment
		(start 312.466228 -319.738248)
		(end 312.387996 -319.927478)
		(width 0.14732)
		(layer "In11.Cu")
		(net "UPI_CPU1_CPU0_P2P2_DP<16>")
	)
	(segment
		(start 242.624102 -367.620296)
		(end 242.387628 -367.28273)
		(width 0.14732)
		(layer "In11.Cu")
		(net "UPI_CPU1_CPU0_P2P2_DP<16>")
	)
	(segment
		(start 70.67804 -328.607166)
		(end 71.374762 -326.089772)
		(width 0.14732)
		(layer "In11.Cu")
		(net "UPI_CPU1_CPU0_P2P2_DP<16>")
	)
	(segment
		(start 341.090504 -286.794702)
		(end 341.075264 -286.803592)
		(width 0.0889)
		(layer "In11.Cu")
		(net "UPI_CPU1_CPU0_P2P2_DP<16>")
	)
	(segment
		(start 312.995818 -319.67551)
		(end 312.806842 -319.597278)
		(width 0.14732)
		(layer "In11.Cu")
		(net "UPI_CPU1_CPU0_P2P2_DP<16>")
	)
	(segment
		(start 310.823102 -320.575686)
		(end 309.587138 -321.616832)
		(width 0.14732)
		(layer "In11.Cu")
		(net "UPI_CPU1_CPU0_P2P2_DP<16>")
	)
	(segment
		(start 240.81359 -369.631976)
		(end 240.643156 -369.75161)
		(width 0.14732)
		(layer "In11.Cu")
		(net "UPI_CPU1_CPU0_P2P2_DP<16>")
	)
	(segment
		(start 313.567064 -319.282064)
		(end 313.488832 -319.471294)
		(width 0.14732)
		(layer "In11.Cu")
		(net "UPI_CPU1_CPU0_P2P2_DP<16>")
	)
	(segment
		(start 100.567744 -287.304734)
		(end 100.567744 -287.28924)
		(width 0.0889)
		(layer "In11.Cu")
		(net "UPI_CPU1_CPU0_P2P2_DP<16>")
	)
	(segment
		(start 341.269066 -284.832044)
		(end 341.269066 -284.847538)
		(width 0.0889)
		(layer "In11.Cu")
		(net "UPI_CPU1_CPU0_P2P2_DP<16>")
	)
	(segment
		(start 315.418724 -318.519556)
		(end 315.158374 -318.779906)
		(width 0.14732)
		(layer "In11.Cu")
		(net "UPI_CPU1_CPU0_P2P2_DP<16>")
	)
	(segment
		(start 264.915142 -345.251278)
		(end 264.915142 -363.616494)
		(width 0.14732)
		(layer "In11.Cu")
		(net "UPI_CPU1_CPU0_P2P2_DP<16>")
	)
	(segment
		(start 244.6274 -370.45392)
		(end 244.507766 -370.283486)
		(width 0.14732)
		(layer "In11.Cu")
		(net "UPI_CPU1_CPU0_P2P2_DP<16>")
	)
	(segment
		(start 101.694234 -285.337504)
		(end 101.694996 -285.336996)
		(width 0.0889)
		(layer "In11.Cu")
		(net "UPI_CPU1_CPU0_P2P2_DP<16>")
	)
	(segment
		(start 70.047358 -335.013808)
		(end 70.67804 -328.607166)
		(width 0.14732)
		(layer "In11.Cu")
		(net "UPI_CPU1_CPU0_P2P2_DP<16>")
	)
	(segment
		(start 241.209576 -367.387378)
		(end 240.81359 -369.631976)
		(width 0.14732)
		(layer "In11.Cu")
		(net "UPI_CPU1_CPU0_P2P2_DP<16>")
	)
	(segment
		(start 99.611942 -291.827204)
		(end 99.611942 -291.649404)
		(width 0.0889)
		(layer "In11.Cu")
		(net "UPI_CPU1_CPU0_P2P2_DP<16>")
	)
	(segment
		(start 315.418724 -318.314832)
		(end 315.418724 -318.519556)
		(width 0.14732)
		(layer "In11.Cu")
		(net "UPI_CPU1_CPU0_P2P2_DP<16>")
	)
	(segment
		(start 101.686106 -282.086558)
		(end 101.693472 -282.08224)
		(width 0.0889)
		(layer "In11.Cu")
		(net "UPI_CPU1_CPU0_P2P2_DP<16>")
	)
	(segment
		(start 243.49202 -367.789968)
		(end 243.096034 -370.034566)
		(width 0.14732)
		(layer "In11.Cu")
		(net "UPI_CPU1_CPU0_P2P2_DP<16>")
	)
	(segment
		(start 99.711002 -291.926264)
		(end 99.611942 -291.827204)
		(width 0.0889)
		(layer "In11.Cu")
		(net "UPI_CPU1_CPU0_P2P2_DP<16>")
	)
	(segment
		(start 303.541938 -329.33767)
		(end 284.445964 -329.33767)
		(width 0.14732)
		(layer "In11.Cu")
		(net "UPI_CPU1_CPU0_P2P2_DP<16>")
	)
	(segment
		(start 255.83261 -369.791742)
		(end 255.66497 -369.67414)
		(width 0.14732)
		(layer "In11.Cu")
		(net "UPI_CPU1_CPU0_P2P2_DP<16>")
	)
	(segment
		(start 252.465586 -370.385594)
		(end 251.633736 -370.532152)
		(width 0.14732)
		(layer "In11.Cu")
		(net "UPI_CPU1_CPU0_P2P2_DP<16>")
	)
	(segment
		(start 246.130826 -367.942876)
		(end 245.774464 -368.192558)
		(width 0.14732)
		(layer "In11.Cu")
		(net "UPI_CPU1_CPU0_P2P2_DP<16>")
	)
	(segment
		(start 102.625906 -283.714444)
		(end 102.634796 -283.709364)
		(width 0.0889)
		(layer "In11.Cu")
		(net "UPI_CPU1_CPU0_P2P2_DP<16>")
	)
	(segment
		(start 200.152254 -372.303802)
		(end 161.568638 -379.105668)
		(width 0.14732)
		(layer "In11.Cu")
		(net "UPI_CPU1_CPU0_P2P2_DP<16>")
	)
	(segment
		(start 71.374762 -326.089772)
		(end 72.50303 -323.704458)
		(width 0.14732)
		(layer "In11.Cu")
		(net "UPI_CPU1_CPU0_P2P2_DP<16>")
	)
	(segment
		(start 264.915142 -363.616494)
		(end 264.19937 -364.332266)
		(width 0.14732)
		(layer "In11.Cu")
		(net "UPI_CPU1_CPU0_P2P2_DP<16>")
	)
	(segment
		(start 99.711002 -290.818824)
		(end 99.611942 -290.719764)
		(width 0.0889)
		(layer "In11.Cu")
		(net "UPI_CPU1_CPU0_P2P2_DP<16>")
	)
	(segment
		(start 308.835044 -322.80987)
		(end 307.409088 -324.307454)
		(width 0.14732)
		(layer "In11.Cu")
		(net "UPI_CPU1_CPU0_P2P2_DP<16>")
	)
	(segment
		(start 99.611942 -291.095684)
		(end 99.711002 -290.996624)
		(width 0.0889)
		(layer "In11.Cu")
		(net "UPI_CPU1_CPU0_P2P2_DP<16>")
	)
	(segment
		(start 99.628198 -289.078416)
		(end 99.628198 -288.917126)
		(width 0.0889)
		(layer "In11.Cu")
		(net "UPI_CPU1_CPU0_P2P2_DP<16>")
	)
	(segment
		(start 339.859366 -288.898584)
		(end 339.859366 -289.113722)
		(width 0.0889)
		(layer "In11.Cu")
		(net "UPI_CPU1_CPU0_P2P2_DP<16>")
	)
	(segment
		(start 244.507766 -370.283486)
		(end 244.903752 -368.038888)
		(width 0.14732)
		(layer "In11.Cu")
		(net "UPI_CPU1_CPU0_P2P2_DP<16>")
	)
	(segment
		(start 313.488832 -319.471294)
		(end 312.995818 -319.67551)
		(width 0.14732)
		(layer "In11.Cu")
		(net "UPI_CPU1_CPU0_P2P2_DP<16>")
	)
	(segment
		(start 244.65407 -367.682526)
		(end 243.848382 -367.540286)
		(width 0.14732)
		(layer "In11.Cu")
		(net "UPI_CPU1_CPU0_P2P2_DP<16>")
	)
	(segment
		(start 245.378478 -370.437156)
		(end 245.208044 -370.55679)
		(width 0.14732)
		(layer "In11.Cu")
		(net "UPI_CPU1_CPU0_P2P2_DP<16>")
	)
	(segment
		(start 255.302004 -369.738148)
		(end 255.184656 -369.906042)
		(width 0.14732)
		(layer "In11.Cu")
		(net "UPI_CPU1_CPU0_P2P2_DP<16>")
	)
	(segment
		(start 336.885534 -293.379398)
		(end 335.372964 -294.006016)
		(width 0.14732)
		(layer "In11.Cu")
		(net "UPI_CPU1_CPU0_P2P2_DP<16>")
	)
	(segment
		(start 340.150704 -288.422334)
		(end 340.141814 -288.427414)
		(width 0.0889)
		(layer "In11.Cu")
		(net "UPI_CPU1_CPU0_P2P2_DP<16>")
	)
	(segment
		(start 313.907678 -319.141094)
		(end 313.567064 -319.282064)
		(width 0.14732)
		(layer "In11.Cu")
		(net "UPI_CPU1_CPU0_P2P2_DP<16>")
	)
	(segment
		(start 212.31225 -374.44807)
		(end 200.152254 -372.303802)
		(width 0.14732)
		(layer "In11.Cu")
		(net "UPI_CPU1_CPU0_P2P2_DP<16>")
	)
	(segment
		(start 341.090504 -285.166816)
		(end 341.075518 -285.175452)
		(width 0.0889)
		(layer "In11.Cu")
		(net "UPI_CPU1_CPU0_P2P2_DP<16>")
	)
	(segment
		(start 253.745238 -370.012722)
		(end 253.627636 -370.180616)
		(width 0.14732)
		(layer "In11.Cu")
		(net "UPI_CPU1_CPU0_P2P2_DP<16>")
	)
	(segment
		(start 101.694996 -285.985712)
		(end 101.686106 -285.980632)
		(width 0.0889)
		(layer "In11.Cu")
		(net "UPI_CPU1_CPU0_P2P2_DP<16>")
	)
	(segment
		(start 340.329266 -288.09315)
		(end 340.329266 -288.103056)
		(width 0.0889)
		(layer "In11.Cu")
		(net "UPI_CPU1_CPU0_P2P2_DP<16>")
	)
	(segment
		(start 255.184656 -369.906042)
		(end 254.275844 -370.066062)
		(width 0.14732)
		(layer "In11.Cu")
		(net "UPI_CPU1_CPU0_P2P2_DP<16>")
	)
	(segment
		(start 342.208612 -283.205682)
		(end 342.208612 -283.219906)
		(width 0.0889)
		(layer "In11.Cu")
		(net "UPI_CPU1_CPU0_P2P2_DP<16>")
	)
	(segment
		(start 241.565938 -367.137696)
		(end 241.209576 -367.387378)
		(width 0.14732)
		(layer "In11.Cu")
		(net "UPI_CPU1_CPU0_P2P2_DP<16>")
	)
	(segment
		(start 102.017576 -282.05684)
		(end 102.038658 -282.134818)
		(width 0.0889)
		(layer "In11.Cu")
		(net "UPI_CPU1_CPU0_P2P2_DP<16>")
	)
	(segment
		(start 240.643156 -369.75161)
		(end 239.796574 -369.602004)
		(width 0.14732)
		(layer "In11.Cu")
		(net "UPI_CPU1_CPU0_P2P2_DP<16>")
	)
	(segment
		(start 102.15626 -284.52826)
		(end 102.16515 -284.52318)
		(width 0.0889)
		(layer "In11.Cu")
		(net "UPI_CPU1_CPU0_P2P2_DP<16>")
	)
	(segment
		(start 304.851562 -328.028554)
		(end 304.481992 -328.39787)
		(width 0.14732)
		(layer "In11.Cu")
		(net "UPI_CPU1_CPU0_P2P2_DP<16>")
	)
	(segment
		(start 339.037422 -291.2872)
		(end 338.977478 -291.2872)
		(width 0.0889)
		(layer "In11.Cu")
		(net "UPI_CPU1_CPU0_P2P2_DP<16>")
	)
	(segment
		(start 245.774464 -368.192558)
		(end 245.378478 -370.437156)
		(width 0.14732)
		(layer "In11.Cu")
		(net "UPI_CPU1_CPU0_P2P2_DP<16>")
	)
	(segment
		(start 264.19937 -364.332266)
		(end 256.594102 -369.65763)
		(width 0.14732)
		(layer "In11.Cu")
		(net "UPI_CPU1_CPU0_P2P2_DP<16>")
	)
	(segment
		(start 306.208176 -325.148194)
		(end 305.47691 -326.192642)
		(width 0.14732)
		(layer "In11.Cu")
		(net "UPI_CPU1_CPU0_P2P2_DP<16>")
	)
	(segment
		(start 340.798912 -287.28924)
		(end 340.798912 -287.297876)
		(width 0.0889)
		(layer "In11.Cu")
		(net "UPI_CPU1_CPU0_P2P2_DP<16>")
	)
	(segment
		(start 161.568638 -379.105668)
		(end 126.084838 -379.105668)
		(width 0.14732)
		(layer "In11.Cu")
		(net "UPI_CPU1_CPU0_P2P2_DP<16>")
	)
	(segment
		(start 74.036174 -363.131354)
		(end 70.047358 -353.502722)
		(width 0.14732)
		(layer "In11.Cu")
		(net "UPI_CPU1_CPU0_P2P2_DP<16>")
	)
	(segment
		(start 246.909844 -370.85651)
		(end 246.79021 -370.686076)
		(width 0.14732)
		(layer "In11.Cu")
		(net "UPI_CPU1_CPU0_P2P2_DP<16>")
	)
	(segment
		(start 77.146658 -366.241838)
		(end 74.036174 -363.131354)
		(width 0.14732)
		(layer "In11.Cu")
		(net "UPI_CPU1_CPU0_P2P2_DP<16>")
	)
	(segment
		(start 246.79021 -370.686076)
		(end 247.186196 -368.441478)
		(width 0.14732)
		(layer "In11.Cu")
		(net "UPI_CPU1_CPU0_P2P2_DP<16>")
	)
	(segment
		(start 99.711002 -292.479984)
		(end 99.611942 -292.380924)
		(width 0.0889)
		(layer "In11.Cu")
		(net "UPI_CPU1_CPU0_P2P2_DP<16>")
	)
	(segment
		(start 314.096908 -319.219326)
		(end 313.907678 -319.141094)
		(width 0.14732)
		(layer "In11.Cu")
		(net "UPI_CPU1_CPU0_P2P2_DP<16>")
	)
	(segment
		(start 80.625188 -315.5823)
		(end 96.11233 -302.87214)
		(width 0.14732)
		(layer "In11.Cu")
		(net "UPI_CPU1_CPU0_P2P2_DP<16>")
	)
	(segment
		(start 253.627636 -370.180616)
		(end 253.113794 -370.27104)
		(width 0.14732)
		(layer "In11.Cu")
		(net "UPI_CPU1_CPU0_P2P2_DP<16>")
	)
	(segment
		(start 247.186196 -368.441478)
		(end 246.936514 -368.085116)
		(width 0.14732)
		(layer "In11.Cu")
		(net "UPI_CPU1_CPU0_P2P2_DP<16>")
	)
	(segment
		(start 335.372964 -294.006016)
		(end 334.34782 -295.540684)
		(width 0.14732)
		(layer "In11.Cu")
		(net "UPI_CPU1_CPU0_P2P2_DP<16>")
	)
	(segment
		(start 97.424748 -301.102522)
		(end 99.654106 -295.720008)
		(width 0.14732)
		(layer "In11.Cu")
		(net "UPI_CPU1_CPU0_P2P2_DP<16>")
	)
	(segment
		(start 342.678512 -282.39593)
		(end 342.678512 -282.414472)
		(width 0.0889)
		(layer "In11.Cu")
		(net "UPI_CPU1_CPU0_P2P2_DP<16>")
	)
	(segment
		(start 254.275844 -370.066062)
		(end 254.108204 -369.948714)
		(width 0.14732)
		(layer "In11.Cu")
		(net "UPI_CPU1_CPU0_P2P2_DP<16>")
	)
	(segment
		(start 253.113794 -370.27104)
		(end 252.9459 -370.153692)
		(width 0.14732)
		(layer "In11.Cu")
		(net "UPI_CPU1_CPU0_P2P2_DP<16>")
	)
	(segment
		(start 334.34782 -295.540684)
		(end 332.583282 -301.354998)
		(width 0.14732)
		(layer "In11.Cu")
		(net "UPI_CPU1_CPU0_P2P2_DP<16>")
	)
	(segment
		(start 312.387996 -319.927478)
		(end 310.823102 -320.575686)
		(width 0.14732)
		(layer "In11.Cu")
		(net "UPI_CPU1_CPU0_P2P2_DP<16>")
	)
	(segment
		(start 341.081614 -286.151066)
		(end 341.090504 -286.156146)
		(width 0.0889)
		(layer "In11.Cu")
		(net "UPI_CPU1_CPU0_P2P2_DP<16>")
	)
	(segment
		(start 98.213164 -374.968008)
		(end 77.146658 -366.241838)
		(width 0.14732)
		(layer "In11.Cu")
		(net "UPI_CPU1_CPU0_P2P2_DP<16>")
	)
	(segment
		(start 242.387628 -367.28273)
		(end 241.565938 -367.137696)
		(width 0.14732)
		(layer "In11.Cu")
		(net "UPI_CPU1_CPU0_P2P2_DP<16>")
	)
	(segment
		(start 250.985528 -370.646706)
		(end 248.352818 -371.110764)
		(width 0.14732)
		(layer "In11.Cu")
		(net "UPI_CPU1_CPU0_P2P2_DP<16>")
	)
	(segment
		(start 339.859366 -289.113722)
		(end 339.85962 -289.113976)
		(width 0.0889)
		(layer "In11.Cu")
		(net "UPI_CPU1_CPU0_P2P2_DP<16>")
	)
	(segment
		(start 338.977478 -291.2872)
		(end 338.961984 -291.302694)
		(width 0.0889)
		(layer "In11.Cu")
		(net "UPI_CPU1_CPU0_P2P2_DP<16>")
	)
	(segment
		(start 242.9256 -370.1542)
		(end 242.344956 -370.05133)
		(width 0.14732)
		(layer "In11.Cu")
		(net "UPI_CPU1_CPU0_P2P2_DP<16>")
	)
	(segment
		(start 99.611942 -292.756844)
		(end 99.711002 -292.657784)
		(width 0.0889)
		(layer "In11.Cu")
		(net "UPI_CPU1_CPU0_P2P2_DP<16>")
	)
	(segment
		(start 99.611942 -293.137844)
		(end 99.611942 -292.756844)
		(width 0.0889)
		(layer "In11.Cu")
		(net "UPI_CPU1_CPU0_P2P2_DP<16>")
	)
	(segment
		(start 312.806842 -319.597278)
		(end 312.466228 -319.738248)
		(width 0.14732)
		(layer "In11.Cu")
		(net "UPI_CPU1_CPU0_P2P2_DP<16>")
	)
	(segment
		(start 245.208044 -370.55679)
		(end 244.6274 -370.45392)
		(width 0.14732)
		(layer "In11.Cu")
		(net "UPI_CPU1_CPU0_P2P2_DP<16>")
	)
	(segment
		(start 102.634796 -283.709364)
		(end 102.640892 -283.705808)
		(width 0.0889)
		(layer "In11.Cu")
		(net "UPI_CPU1_CPU0_P2P2_DP<16>")
	)
	(segment
		(start 305.237896 -327.54697)
		(end 304.851562 -328.028554)
		(width 0.14732)
		(layer "In11.Cu")
		(net "UPI_CPU1_CPU0_P2P2_DP<16>")
	)
	(segment
		(start 255.66497 -369.67414)
		(end 255.302004 -369.738148)
		(width 0.14732)
		(layer "In11.Cu")
		(net "UPI_CPU1_CPU0_P2P2_DP<16>")
	)
	(segment
		(start 251.465842 -370.414804)
		(end 251.102876 -370.478558)
		(width 0.14732)
		(layer "In11.Cu")
		(net "UPI_CPU1_CPU0_P2P2_DP<16>")
	)
	(segment
		(start 102.447344 -284.049216)
		(end 102.447344 -284.033722)
		(width 0.0889)
		(layer "In11.Cu")
		(net "UPI_CPU1_CPU0_P2P2_DP<16>")
	)
	(segment
		(start 99.711002 -292.657784)
		(end 99.711002 -292.479984)
		(width 0.0889)
		(layer "In11.Cu")
		(net "UPI_CPU1_CPU0_P2P2_DP<16>")
	)
	(segment
		(start 248.352818 -371.110764)
		(end 246.909844 -370.85651)
		(width 0.14732)
		(layer "In11.Cu")
		(net "UPI_CPU1_CPU0_P2P2_DP<16>")
	)
	(segment
		(start 243.848382 -367.540286)
		(end 243.49202 -367.789968)
		(width 0.14732)
		(layer "In11.Cu")
		(net "UPI_CPU1_CPU0_P2P2_DP<16>")
	)
	(segment
		(start 341.56015 -284.353)
		(end 341.55126 -284.35808)
		(width 0.0889)
		(layer "In11.Cu")
		(net "UPI_CPU1_CPU0_P2P2_DP<16>")
	)
	(segment
		(start 101.686106 -285.342076)
		(end 101.693218 -285.338012)
		(width 0.0889)
		(layer "In11.Cu")
		(net "UPI_CPU1_CPU0_P2P2_DP<16>")
	)
	(segment
		(start 101.694996 -282.730194)
		(end 101.686106 -282.725114)
		(width 0.0889)
		(layer "In11.Cu")
		(net "UPI_CPU1_CPU0_P2P2_DP<16>")
	)
	(segment
		(start 251.633736 -370.532152)
		(end 251.465842 -370.414804)
		(width 0.14732)
		(layer "In11.Cu")
		(net "UPI_CPU1_CPU0_P2P2_DP<16>")
	)
	(segment
		(start 242.344956 -370.05133)
		(end 242.225322 -369.880896)
		(width 0.14732)
		(layer "In11.Cu")
		(net "UPI_CPU1_CPU0_P2P2_DP<16>")
	)
	(segment
		(start 338.248752 -292.015926)
		(end 338.248752 -292.016688)
		(width 0.14732)
		(layer "In11.Cu")
		(net "UPI_CPU1_CPU0_P2P2_DP<16>")
	)
	(segment
		(start 100.097844 -290.056062)
		(end 100.097844 -289.60953)
		(width 0.0889)
		(layer "In11.Cu")
		(net "UPI_CPU1_CPU0_P2P2_DP<16>")
	)
	(segment
		(start 338.248752 -292.016688)
		(end 336.885534 -293.379398)
		(width 0.14732)
		(layer "In11.Cu")
		(net "UPI_CPU1_CPU0_P2P2_DP<16>")
	)
	(segment
		(start 102.917498 -283.219906)
		(end 102.917498 -283.201364)
		(width 0.0889)
		(layer "In11.Cu")
		(net "UPI_CPU1_CPU0_P2P2_DP<16>")
	)
	(segment
		(start 305.47691 -326.192642)
		(end 305.237896 -327.54697)
		(width 0.14732)
		(layer "In11.Cu")
		(net "UPI_CPU1_CPU0_P2P2_DP<16>")
	)
	(segment
		(start 99.654106 -293.180008)
		(end 99.611942 -293.137844)
		(width 0.0889)
		(layer "In11.Cu")
		(net "UPI_CPU1_CPU0_P2P2_DP<16>")
	)
	(segment
		(start 102.038658 -282.134818)
		(end 101.882194 -282.405836)
		(width 0.0889)
		(layer "In11.Cu")
		(net "UPI_CPU1_CPU0_P2P2_DP<16>")
	)
	(segment
		(start 101.693472 -282.08224)
		(end 101.694996 -282.081478)
		(width 0.0889)
		(layer "In11.Cu")
		(net "UPI_CPU1_CPU0_P2P2_DP<16>")
	)
	(segment
		(start 252.9459 -370.153692)
		(end 252.582934 -370.2177)
		(width 0.14732)
		(layer "In11.Cu")
		(net "UPI_CPU1_CPU0_P2P2_DP<16>")
	)
	(segment
		(start 244.903752 -368.038888)
		(end 244.65407 -367.682526)
		(width 0.14732)
		(layer "In11.Cu")
		(net "UPI_CPU1_CPU0_P2P2_DP<16>")
	)
	(segment
		(start 254.108204 -369.948714)
		(end 253.745238 -370.012722)
		(width 0.14732)
		(layer "In11.Cu")
		(net "UPI_CPU1_CPU0_P2P2_DP<16>")
	)
	(segment
		(start 99.711002 -292.104064)
		(end 99.711002 -291.926264)
		(width 0.0889)
		(layer "In11.Cu")
		(net "UPI_CPU1_CPU0_P2P2_DP<16>")
	)
	(segment
		(start 99.711002 -290.996624)
		(end 99.711002 -290.818824)
		(width 0.0889)
		(layer "In11.Cu")
		(net "UPI_CPU1_CPU0_P2P2_DP<16>")
	)
	(segment
		(start 243.096034 -370.034566)
		(end 242.9256 -370.1542)
		(width 0.14732)
		(layer "In11.Cu")
		(net "UPI_CPU1_CPU0_P2P2_DP<16>")
	)
	(segment
		(start 315.158374 -318.779906)
		(end 314.096908 -319.219326)
		(width 0.14732)
		(layer "In11.Cu")
		(net "UPI_CPU1_CPU0_P2P2_DP<16>")
	)
	(segment
		(start 99.611942 -292.203124)
		(end 99.711002 -292.104064)
		(width 0.0889)
		(layer "In11.Cu")
		(net "UPI_CPU1_CPU0_P2P2_DP<16>")
	)
	(segment
		(start 101.694996 -285.336996)
		(end 101.701092 -285.33344)
		(width 0.0889)
		(layer "In11.Cu")
		(net "UPI_CPU1_CPU0_P2P2_DP<16>")
	)
	(segment
		(start 239.796574 -369.602004)
		(end 212.31225 -374.44807)
		(width 0.14732)
		(layer "In11.Cu")
		(net "UPI_CPU1_CPU0_P2P2_DP<16>")
	)
	(segment
		(start 96.11233 -302.87214)
		(end 97.424748 -301.102522)
		(width 0.14732)
		(layer "In11.Cu")
		(net "UPI_CPU1_CPU0_P2P2_DP<16>")
	)
	(segment
		(start 343.557352 -281.863038)
		(end 343.468198 -281.886914)
		(width 0.0889)
		(layer "In11.Cu")
		(net "UPI_CPU1_CPU0_P2P2_DP<16>")
	)
	(segment
		(start 252.582934 -370.2177)
		(end 252.465586 -370.385594)
		(width 0.14732)
		(layer "In11.Cu")
		(net "UPI_CPU1_CPU0_P2P2_DP<16>")
	)
	(segment
		(start 332.583282 -301.354998)
		(end 315.884052 -318.054228)
		(width 0.14732)
		(layer "In11.Cu")
		(net "UPI_CPU1_CPU0_P2P2_DP<16>")
	)
	(segment
		(start 101.680264 -286.973518)
		(end 101.701092 -286.961326)
		(width 0.0889)
		(layer "In11.Cu")
		(net "UPI_CPU1_CPU0_P2P2_DP<16>")
	)
	(segment
		(start 99.654106 -293.202106)
		(end 99.654106 -293.180008)
		(width 0.0889)
		(layer "In11.Cu")
		(net "UPI_CPU1_CPU0_P2P2_DP<16>")
	)
	(segment
		(start 342.03005 -283.539184)
		(end 342.02116 -283.544264)
		(width 0.0889)
		(layer "In11.Cu")
		(net "UPI_CPU1_CPU0_P2P2_DP<16>")
	)
	(segment
		(start 343.713816 -281.59202)
		(end 343.557352 -281.863038)
		(width 0.0889)
		(layer "In11.Cu")
		(net "UPI_CPU1_CPU0_P2P2_DP<16>")
	)
	(segment
		(start 315.679328 -318.054228)
		(end 315.418724 -318.314832)
		(width 0.14732)
		(layer "In11.Cu")
		(net "UPI_CPU1_CPU0_P2P2_DP<16>")
	)
	(segment
		(start 99.611942 -292.380924)
		(end 99.611942 -292.203124)
		(width 0.0889)
		(layer "In11.Cu")
		(net "UPI_CPU1_CPU0_P2P2_DP<16>")
	)
	(segment
		(start 72.50303 -323.704458)
		(end 80.625188 -315.5823)
		(width 0.14732)
		(layer "In11.Cu")
		(net "UPI_CPU1_CPU0_P2P2_DP<16>")
	)
	(segment
		(start 99.611942 -290.719764)
		(end 99.611942 -290.541964)
		(width 0.0889)
		(layer "In11.Cu")
		(net "UPI_CPU1_CPU0_P2P2_DP<16>")
	)
	(segment
		(start 99.611942 -291.273484)
		(end 99.611942 -291.095684)
		(width 0.0889)
		(layer "In11.Cu")
		(net "UPI_CPU1_CPU0_P2P2_DP<16>")
	)
	(segment
		(start 126.084838 -379.105668)
		(end 98.213164 -374.968008)
		(width 0.14732)
		(layer "In11.Cu")
		(net "UPI_CPU1_CPU0_P2P2_DP<16>")
	)
	(segment
		(start 338.961984 -291.302694)
		(end 338.248752 -292.015926)
		(width 0.14732)
		(layer "In11.Cu")
		(net "UPI_CPU1_CPU0_P2P2_DP<16>")
	)
	(segment
		(start 315.884052 -318.054228)
		(end 315.679328 -318.054228)
		(width 0.14732)
		(layer "In11.Cu")
		(net "UPI_CPU1_CPU0_P2P2_DP<16>")
	)
	(segment
		(start 101.977698 -286.475424)
		(end 101.977698 -286.4612)
		(width 0.0889)
		(layer "In11.Cu")
		(net "UPI_CPU1_CPU0_P2P2_DP<16>")
	)
	(segment
		(start 100.098098 -288.121598)
		(end 100.098098 -288.103056)
		(width 0.0889)
		(layer "In11.Cu")
		(net "UPI_CPU1_CPU0_P2P2_DP<16>")
	)
	(segment
		(start 341.075264 -286.803592)
		(end 341.075518 -286.803338)
		(width 0.0889)
		(layer "In11.Cu")
		(net "UPI_CPU1_CPU0_P2P2_DP<16>")
	)
	(segment
		(start 251.102876 -370.478558)
		(end 250.985528 -370.646706)
		(width 0.14732)
		(layer "In11.Cu")
		(net "UPI_CPU1_CPU0_P2P2_DP<16>")
	)
	(segment
		(start 99.711002 -291.372544)
		(end 99.611942 -291.273484)
		(width 0.0889)
		(layer "In11.Cu")
		(net "UPI_CPU1_CPU0_P2P2_DP<16>")
	)
	(segment
		(start 99.611942 -290.541964)
		(end 100.097844 -290.056062)
		(width 0.0889)
		(layer "In11.Cu")
		(net "UPI_CPU1_CPU0_P2P2_DP<16>")
	)
	(segment
		(start 242.225322 -369.880896)
		(end 242.624102 -367.620296)
		(width 0.14732)
		(layer "In11.Cu")
		(net "UPI_CPU1_CPU0_P2P2_DP<16>")
	)
	(segment
		(start 304.481992 -328.39787)
		(end 304.482246 -328.39787)
		(width 0.14732)
		(layer "In11.Cu")
		(net "UPI_CPU1_CPU0_P2P2_DP<16>")
	)
	(segment
		(start 102.63505 -282.730194)
		(end 102.624636 -282.724098)
		(width 0.0889)
		(layer "In11.Cu")
		(net "UPI_CPU1_CPU0_P2P2_DP<16>")
	)
	(segment
		(start 99.711002 -291.550344)
		(end 99.711002 -291.372544)
		(width 0.0889)
		(layer "In11.Cu")
		(net "UPI_CPU1_CPU0_P2P2_DP<16>")
	)
	(segment
		(start 101.693218 -285.338012)
		(end 101.694234 -285.337504)
		(width 0.0889)
		(layer "In11.Cu")
		(net "UPI_CPU1_CPU0_P2P2_DP<16>")
	)
	(segment
		(start 99.611942 -291.649404)
		(end 99.711002 -291.550344)
		(width 0.0889)
		(layer "In11.Cu")
		(net "UPI_CPU1_CPU0_P2P2_DP<16>")
	)
	(segment
		(start 304.482246 -328.39787)
		(end 303.541938 -329.33767)
		(width 0.14732)
		(layer "In11.Cu")
		(net "UPI_CPU1_CPU0_P2P2_DP<16>")
	)
	(segment
		(start 100.27666 -287.783778)
		(end 100.28555 -287.778698)
		(width 0.0889)
		(layer "In11.Cu")
		(net "UPI_CPU1_CPU0_P2P2_DP<16>")
	)
	(segment
		(start 256.594102 -369.65763)
		(end 255.83261 -369.791742)
		(width 0.14732)
		(layer "In11.Cu")
		(net "UPI_CPU1_CPU0_P2P2_DP<16>")
	)
	(segment
		(start 278.271224 -331.895196)
		(end 264.915142 -345.251278)
		(width 0.14732)
		(layer "In11.Cu")
		(net "UPI_CPU1_CPU0_P2P2_DP<16>")
	)
	(segment
		(start 307.409088 -324.307454)
		(end 306.208176 -325.148194)
		(width 0.14732)
		(layer "In11.Cu")
		(net "UPI_CPU1_CPU0_P2P2_DP<16>")
	)
	(segment
		(start 340.329266 -289.995356)
		(end 339.037422 -291.2872)
		(width 0.0889)
		(layer "In11.Cu")
		(net "UPI_CPU1_CPU0_P2P2_DP<16>")
	)
	(segment
		(start 99.654106 -295.720008)
		(end 99.654106 -293.202106)
		(width 0.14732)
		(layer "In11.Cu")
		(net "UPI_CPU1_CPU0_P2P2_DP<16>")
	)
	(segment
		(start 99.80676 -288.597848)
		(end 99.81565 -288.592768)
		(width 0.0889)
		(layer "In11.Cu")
		(net "UPI_CPU1_CPU0_P2P2_DP<16>")
	)
	(segment
		(start 340.329266 -289.64509)
		(end 340.329266 -289.995356)
		(width 0.0889)
		(layer "In11.Cu")
		(net "UPI_CPU1_CPU0_P2P2_DP<16>")
	)
	(segment
		(start 341.738712 -284.023816)
		(end 341.738712 -284.033722)
		(width 0.0889)
		(layer "In11.Cu")
		(net "UPI_CPU1_CPU0_P2P2_DP<16>")
	)
	(arc
		(start 100.28555 -287.778698)
		(mid 100.488373 -287.578467)
		(end 100.567744 -287.304734)
		(width 0.0889)
		(layer "In11.Cu")
		(net "UPI_CPU1_CPU0_P2P2_DP<16>")
	)
	(arc
		(start 340.141814 -288.427414)
		(mid 339.939528 -288.626395)
		(end 339.859366 -288.898584)
		(width 0.0889)
		(layer "In11.Cu")
		(net "UPI_CPU1_CPU0_P2P2_DP<16>")
	)
	(arc
		(start 101.701092 -286.961326)
		(mid 101.903679 -286.754975)
		(end 101.977698 -286.475424)
		(width 0.0889)
		(layer "In11.Cu")
		(net "UPI_CPU1_CPU0_P2P2_DP<16>")
	)
	(arc
		(start 343.468198 -281.886914)
		(mid 343.458204 -281.882753)
		(end 343.448132 -281.878786)
		(width 0.0889)
		(layer "In11.Cu")
		(net "UPI_CPU1_CPU0_P2P2_DP<16>")
	)
	(arc
		(start 100.097844 -289.60953)
		(mid 99.986506 -289.41663)
		(end 99.812348 -289.277806)
		(width 0.0889)
		(layer "In11.Cu")
		(net "UPI_CPU1_CPU0_P2P2_DP<16>")
	)
	(arc
		(start 342.02116 -283.544264)
		(mid 341.816825 -283.746869)
		(end 341.738712 -284.023816)
		(width 0.0889)
		(layer "In11.Cu")
		(net "UPI_CPU1_CPU0_P2P2_DP<16>")
	)
	(arc
		(start 340.611714 -287.613598)
		(mid 340.407379 -287.816203)
		(end 340.329266 -288.09315)
		(width 0.0889)
		(layer "In11.Cu")
		(net "UPI_CPU1_CPU0_P2P2_DP<16>")
	)
	(arc
		(start 101.977698 -286.4612)
		(mid 101.898479 -286.186515)
		(end 101.694996 -285.985712)
		(width 0.0889)
		(layer "In11.Cu")
		(net "UPI_CPU1_CPU0_P2P2_DP<16>")
	)
	(arc
		(start 341.090504 -286.156146)
		(mid 341.269101 -286.475424)
		(end 341.090504 -286.794702)
		(width 0.0889)
		(layer "In11.Cu")
		(net "UPI_CPU1_CPU0_P2P2_DP<16>")
	)
	(arc
		(start 99.628198 -288.917126)
		(mid 99.675877 -288.734226)
		(end 99.80676 -288.597848)
		(width 0.0889)
		(layer "In11.Cu")
		(net "UPI_CPU1_CPU0_P2P2_DP<16>")
	)
	(arc
		(start 100.567744 -287.28924)
		(mid 100.755043 -286.964799)
		(end 101.129592 -286.964882)
		(width 0.0889)
		(layer "In11.Cu")
		(net "UPI_CPU1_CPU0_P2P2_DP<16>")
	)
	(arc
		(start 101.977698 -284.847538)
		(mid 102.025377 -284.664638)
		(end 102.15626 -284.52826)
		(width 0.0889)
		(layer "In11.Cu")
		(net "UPI_CPU1_CPU0_P2P2_DP<16>")
	)
	(arc
		(start 102.447344 -284.033722)
		(mid 102.495023 -283.850822)
		(end 102.625906 -283.714444)
		(width 0.0889)
		(layer "In11.Cu")
		(net "UPI_CPU1_CPU0_P2P2_DP<16>")
	)
	(arc
		(start 341.075518 -285.175452)
		(mid 340.798831 -285.664946)
		(end 341.081614 -286.151066)
		(width 0.0889)
		(layer "In11.Cu")
		(net "UPI_CPU1_CPU0_P2P2_DP<16>")
	)
	(arc
		(start 341.738712 -284.033722)
		(mid 341.691033 -284.216622)
		(end 341.56015 -284.353)
		(width 0.0889)
		(layer "In11.Cu")
		(net "UPI_CPU1_CPU0_P2P2_DP<16>")
	)
	(arc
		(start 102.624636 -282.724098)
		(mid 102.346204 -282.654284)
		(end 102.069392 -282.730194)
		(width 0.0889)
		(layer "In11.Cu")
		(net "UPI_CPU1_CPU0_P2P2_DP<16>")
	)
	(arc
		(start 99.81565 -288.592768)
		(mid 100.017936 -288.393787)
		(end 100.098098 -288.121598)
		(width 0.0889)
		(layer "In11.Cu")
		(net "UPI_CPU1_CPU0_P2P2_DP<16>")
	)
	(arc
		(start 340.329266 -288.103056)
		(mid 340.281587 -288.285956)
		(end 340.150704 -288.422334)
		(width 0.0889)
		(layer "In11.Cu")
		(net "UPI_CPU1_CPU0_P2P2_DP<16>")
	)
	(arc
		(start 101.701092 -285.33344)
		(mid 101.903679 -285.127089)
		(end 101.977698 -284.847538)
		(width 0.0889)
		(layer "In11.Cu")
		(net "UPI_CPU1_CPU0_P2P2_DP<16>")
	)
	(arc
		(start 101.686106 -285.980632)
		(mid 101.507509 -285.661354)
		(end 101.686106 -285.342076)
		(width 0.0889)
		(layer "In11.Cu")
		(net "UPI_CPU1_CPU0_P2P2_DP<16>")
	)
	(arc
		(start 99.812348 -289.277806)
		(mid 99.703201 -289.193878)
		(end 99.628198 -289.078416)
		(width 0.0889)
		(layer "In11.Cu")
		(net "UPI_CPU1_CPU0_P2P2_DP<16>")
	)
	(arc
		(start 102.069392 -282.730194)
		(mid 101.882194 -282.780337)
		(end 101.694996 -282.730194)
		(width 0.0889)
		(layer "In11.Cu")
		(net "UPI_CPU1_CPU0_P2P2_DP<16>")
	)
	(arc
		(start 102.640892 -283.705808)
		(mid 102.843479 -283.499457)
		(end 102.917498 -283.219906)
		(width 0.0889)
		(layer "In11.Cu")
		(net "UPI_CPU1_CPU0_P2P2_DP<16>")
	)
	(arc
		(start 102.917498 -283.201364)
		(mid 102.837336 -282.929175)
		(end 102.63505 -282.730194)
		(width 0.0889)
		(layer "In11.Cu")
		(net "UPI_CPU1_CPU0_P2P2_DP<16>")
	)
	(arc
		(start 100.098098 -288.103056)
		(mid 100.145777 -287.920156)
		(end 100.27666 -287.783778)
		(width 0.0889)
		(layer "In11.Cu")
		(net "UPI_CPU1_CPU0_P2P2_DP<16>")
	)
	(arc
		(start 339.85962 -289.113976)
		(mid 339.97085 -289.30718)
		(end 340.145116 -289.446208)
		(width 0.0889)
		(layer "In11.Cu")
		(net "UPI_CPU1_CPU0_P2P2_DP<16>")
	)
	(arc
		(start 342.208612 -283.219906)
		(mid 342.160933 -283.402806)
		(end 342.03005 -283.539184)
		(width 0.0889)
		(layer "In11.Cu")
		(net "UPI_CPU1_CPU0_P2P2_DP<16>")
	)
	(arc
		(start 101.686106 -282.725114)
		(mid 101.507509 -282.405836)
		(end 101.686106 -282.086558)
		(width 0.0889)
		(layer "In11.Cu")
		(net "UPI_CPU1_CPU0_P2P2_DP<16>")
	)
	(arc
		(start 341.075518 -286.803338)
		(mid 340.872931 -287.009689)
		(end 340.798912 -287.28924)
		(width 0.0889)
		(layer "In11.Cu")
		(net "UPI_CPU1_CPU0_P2P2_DP<16>")
	)
	(arc
		(start 342.678512 -282.414472)
		(mid 342.626242 -282.596837)
		(end 342.491314 -282.730194)
		(width 0.0889)
		(layer "In11.Cu")
		(net "UPI_CPU1_CPU0_P2P2_DP<16>")
	)
	(arc
		(start 340.798912 -287.297876)
		(mid 340.746642 -287.480241)
		(end 340.611714 -287.613598)
		(width 0.0889)
		(layer "In11.Cu")
		(net "UPI_CPU1_CPU0_P2P2_DP<16>")
	)
	(arc
		(start 101.129592 -286.964882)
		(mid 101.403791 -287.040717)
		(end 101.680264 -286.973518)
		(width 0.0889)
		(layer "In11.Cu")
		(net "UPI_CPU1_CPU0_P2P2_DP<16>")
	)
	(arc
		(start 102.16515 -284.52318)
		(mid 102.367973 -284.322949)
		(end 102.447344 -284.049216)
		(width 0.0889)
		(layer "In11.Cu")
		(net "UPI_CPU1_CPU0_P2P2_DP<16>")
	)
	(arc
		(start 340.145116 -289.446208)
		(mid 340.254196 -289.529909)
		(end 340.329266 -289.64509)
		(width 0.0889)
		(layer "In11.Cu")
		(net "UPI_CPU1_CPU0_P2P2_DP<16>")
	)
	(arc
		(start 341.269066 -284.847538)
		(mid 341.221387 -285.030438)
		(end 341.090504 -285.166816)
		(width 0.0889)
		(layer "In11.Cu")
		(net "UPI_CPU1_CPU0_P2P2_DP<16>")
	)
	(arc
		(start 341.55126 -284.35808)
		(mid 341.348437 -284.558311)
		(end 341.269066 -284.832044)
		(width 0.0889)
		(layer "In11.Cu")
		(net "UPI_CPU1_CPU0_P2P2_DP<16>")
	)
	(arc
		(start 101.694996 -282.081478)
		(mid 101.853484 -282.032545)
		(end 102.017576 -282.05684)
		(width 0.0889)
		(layer "In11.Cu")
		(net "UPI_CPU1_CPU0_P2P2_DP<16>")
	)
	(arc
		(start 342.491314 -282.730194)
		(mid 342.287833 -282.930998)
		(end 342.208612 -283.205682)
		(width 0.0889)
		(layer "In11.Cu")
		(net "UPI_CPU1_CPU0_P2P2_DP<16>")
	)
	(arc
		(start 343.448132 -281.878786)
		(mid 342.928389 -281.936589)
		(end 342.678512 -282.39593)
		(width 0.0889)
		(layer "In11.Cu")
		(net "UPI_CPU1_CPU0_P2P2_DP<16>")
	)
	(segment
		(start 344.653362 -279.96388)
		(end 344.653616 -279.964134)
		(width 0.13208)
		(layer "F.Cu")
		(net "UPI_CPU1_CPU0_P2P2_DP<15>")
	)
	(segment
		(start 344.653362 -279.428194)
		(end 344.653362 -279.96388)
		(width 0.13208)
		(layer "F.Cu")
		(net "UPI_CPU1_CPU0_P2P2_DP<15>")
	)
	(segment
		(start 102.352094 -282.683966)
		(end 102.352094 -283.219652)
		(width 0.13208)
		(layer "F.Cu")
		(net "UPI_CPU1_CPU0_P2P2_DP<15>")
	)
	(segment
		(start 102.352094 -283.219652)
		(end 102.352348 -283.219906)
		(width 0.13208)
		(layer "F.Cu")
		(net "UPI_CPU1_CPU0_P2P2_DP<15>")
	)
	(segment
		(start 227.548694 -373.123968)
		(end 226.733862 -373.195596)
		(width 0.14732)
		(layer "In11.Cu")
		(net "UPI_CPU1_CPU0_P2P2_DP<15>")
	)
	(segment
		(start 241.926872 -372.704106)
		(end 241.767614 -372.570248)
		(width 0.14732)
		(layer "In11.Cu")
		(net "UPI_CPU1_CPU0_P2P2_DP<15>")
	)
	(segment
		(start 240.305844 -372.311422)
		(end 240.339626 -372.695724)
		(width 0.14732)
		(layer "In11.Cu")
		(net "UPI_CPU1_CPU0_P2P2_DP<15>")
	)
	(segment
		(start 240.205768 -372.854982)
		(end 239.618266 -372.907052)
		(width 0.14732)
		(layer "In11.Cu")
		(net "UPI_CPU1_CPU0_P2P2_DP<15>")
	)
	(segment
		(start 101.686106 -283.714444)
		(end 101.688138 -283.713174)
		(width 0.0889)
		(layer "In11.Cu")
		(net "UPI_CPU1_CPU0_P2P2_DP<15>")
	)
	(segment
		(start 125.987048 -379.93447)
		(end 97.93732 -375.773188)
		(width 0.14732)
		(layer "In11.Cu")
		(net "UPI_CPU1_CPU0_P2P2_DP<15>")
	)
	(segment
		(start 161.638234 -379.93447)
		(end 125.987048 -379.93447)
		(width 0.14732)
		(layer "In11.Cu")
		(net "UPI_CPU1_CPU0_P2P2_DP<15>")
	)
	(segment
		(start 235.688632 -372.717314)
		(end 235.722414 -373.101616)
		(width 0.14732)
		(layer "In11.Cu")
		(net "UPI_CPU1_CPU0_P2P2_DP<15>")
	)
	(segment
		(start 234.841796 -373.179086)
		(end 234.80776 -372.794784)
		(width 0.14732)
		(layer "In11.Cu")
		(net "UPI_CPU1_CPU0_P2P2_DP<15>")
	)
	(segment
		(start 259.341366 -370.532152)
		(end 258.891024 -369.889024)
		(width 0.14732)
		(layer "In11.Cu")
		(net "UPI_CPU1_CPU0_P2P2_DP<15>")
	)
	(segment
		(start 98.260154 -290.383468)
		(end 98.218244 -290.341558)
		(width 0.0889)
		(layer "In11.Cu")
		(net "UPI_CPU1_CPU0_P2P2_DP<15>")
	)
	(segment
		(start 221.836996 -373.93499)
		(end 221.870778 -374.319292)
		(width 0.14732)
		(layer "In11.Cu")
		(net "UPI_CPU1_CPU0_P2P2_DP<15>")
	)
	(segment
		(start 101.694996 -283.709364)
		(end 101.695758 -283.708856)
		(width 0.0889)
		(layer "In11.Cu")
		(net "UPI_CPU1_CPU0_P2P2_DP<15>")
	)
	(segment
		(start 344.653616 -279.964134)
		(end 344.81008 -280.235152)
		(width 0.0889)
		(layer "In11.Cu")
		(net "UPI_CPU1_CPU0_P2P2_DP<15>")
	)
	(segment
		(start 248.852944 -372.08841)
		(end 244.223794 -372.491254)
		(width 0.14732)
		(layer "In11.Cu")
		(net "UPI_CPU1_CPU0_P2P2_DP<15>")
	)
	(segment
		(start 305.749198 -328.699368)
		(end 304.282348 -330.16571)
		(width 0.14732)
		(layer "In11.Cu")
		(net "UPI_CPU1_CPU0_P2P2_DP<15>")
	)
	(segment
		(start 223.298766 -374.193816)
		(end 223.26473 -373.809514)
		(width 0.14732)
		(layer "In11.Cu")
		(net "UPI_CPU1_CPU0_P2P2_DP<15>")
	)
	(segment
		(start 261.513828 -368.051842)
		(end 261.96417 -368.695478)
		(width 0.14732)
		(layer "In11.Cu")
		(net "UPI_CPU1_CPU0_P2P2_DP<15>")
	)
	(segment
		(start 343.148412 -283.201364)
		(end 343.148412 -283.219906)
		(width 0.0889)
		(layer "In11.Cu")
		(net "UPI_CPU1_CPU0_P2P2_DP<15>")
	)
	(segment
		(start 342.49995 -284.353)
		(end 342.49106 -284.35808)
		(width 0.0889)
		(layer "In11.Cu")
		(net "UPI_CPU1_CPU0_P2P2_DP<15>")
	)
	(segment
		(start 221.73692 -374.47855)
		(end 212.373464 -375.300494)
		(width 0.14732)
		(layer "In11.Cu")
		(net "UPI_CPU1_CPU0_P2P2_DP<15>")
	)
	(segment
		(start 258.462018 -369.813078)
		(end 257.352546 -370.58981)
		(width 0.14732)
		(layer "In11.Cu")
		(net "UPI_CPU1_CPU0_P2P2_DP<15>")
	)
	(segment
		(start 70.592442 -325.801228)
		(end 71.81215 -323.22262)
		(width 0.14732)
		(layer "In11.Cu")
		(net "UPI_CPU1_CPU0_P2P2_DP<15>")
	)
	(segment
		(start 260.360668 -368.483642)
		(end 259.691378 -368.95278)
		(width 0.14732)
		(layer "In11.Cu")
		(net "UPI_CPU1_CPU0_P2P2_DP<15>")
	)
	(segment
		(start 76.707238 -366.979962)
		(end 73.321164 -363.593634)
		(width 0.14732)
		(layer "In11.Cu")
		(net "UPI_CPU1_CPU0_P2P2_DP<15>")
	)
	(segment
		(start 261.96417 -368.695478)
		(end 261.928102 -368.899948)
		(width 0.14732)
		(layer "In11.Cu")
		(net "UPI_CPU1_CPU0_P2P2_DP<15>")
	)
	(segment
		(start 244.07622 -372.367048)
		(end 244.042184 -371.983)
		(width 0.14732)
		(layer "In11.Cu")
		(net "UPI_CPU1_CPU0_P2P2_DP<15>")
	)
	(segment
		(start 237.997238 -372.514368)
		(end 238.03102 -372.89867)
		(width 0.14732)
		(layer "In11.Cu")
		(net "UPI_CPU1_CPU0_P2P2_DP<15>")
	)
	(segment
		(start 278.643334 -332.69428)
		(end 266.010136 -345.327478)
		(width 0.14732)
		(layer "In11.Cu")
		(net "UPI_CPU1_CPU0_P2P2_DP<15>")
	)
	(segment
		(start 264.082022 -365.877856)
		(end 263.880346 -365.842296)
		(width 0.14732)
		(layer "In11.Cu")
		(net "UPI_CPU1_CPU0_P2P2_DP<15>")
	)
	(segment
		(start 259.545836 -370.56822)
		(end 259.341366 -370.532152)
		(width 0.14732)
		(layer "In11.Cu")
		(net "UPI_CPU1_CPU0_P2P2_DP<15>")
	)
	(segment
		(start 263.57834 -366.053624)
		(end 263.54278 -366.2553)
		(width 0.14732)
		(layer "In11.Cu")
		(net "UPI_CPU1_CPU0_P2P2_DP<15>")
	)
	(segment
		(start 259.615432 -369.381278)
		(end 260.065774 -370.024914)
		(width 0.14732)
		(layer "In11.Cu")
		(net "UPI_CPU1_CPU0_P2P2_DP<15>")
	)
	(segment
		(start 238.276892 -372.180866)
		(end 237.997238 -372.514368)
		(width 0.14732)
		(layer "In11.Cu")
		(net "UPI_CPU1_CPU0_P2P2_DP<15>")
	)
	(segment
		(start 232.499154 -372.99773)
		(end 232.165906 -372.718076)
		(width 0.14732)
		(layer "In11.Cu")
		(net "UPI_CPU1_CPU0_P2P2_DP<15>")
	)
	(segment
		(start 239.618266 -372.907052)
		(end 239.459008 -372.773194)
		(width 0.14732)
		(layer "In11.Cu")
		(net "UPI_CPU1_CPU0_P2P2_DP<15>")
	)
	(segment
		(start 234.474512 -372.51513)
		(end 233.65968 -372.586758)
		(width 0.14732)
		(layer "In11.Cu")
		(net "UPI_CPU1_CPU0_P2P2_DP<15>")
	)
	(segment
		(start 221.870778 -374.319292)
		(end 221.73692 -374.47855)
		(width 0.14732)
		(layer "In11.Cu")
		(net "UPI_CPU1_CPU0_P2P2_DP<15>")
	)
	(segment
		(start 226.48799 -373.9134)
		(end 226.354132 -374.072658)
		(width 0.14732)
		(layer "In11.Cu")
		(net "UPI_CPU1_CPU0_P2P2_DP<15>")
	)
	(segment
		(start 230.971344 -373.666766)
		(end 230.383842 -373.718836)
		(width 0.14732)
		(layer "In11.Cu")
		(net "UPI_CPU1_CPU0_P2P2_DP<15>")
	)
	(segment
		(start 259.691378 -368.95278)
		(end 259.615432 -369.381278)
		(width 0.14732)
		(layer "In11.Cu")
		(net "UPI_CPU1_CPU0_P2P2_DP<15>")
	)
	(segment
		(start 339.859874 -291.447728)
		(end 339.859874 -291.882068)
		(width 0.14732)
		(layer "In11.Cu")
		(net "UPI_CPU1_CPU0_P2P2_DP<15>")
	)
	(segment
		(start 224.425256 -373.398542)
		(end 224.145602 -373.732044)
		(width 0.14732)
		(layer "In11.Cu")
		(net "UPI_CPU1_CPU0_P2P2_DP<15>")
	)
	(segment
		(start 100.746306 -285.342076)
		(end 100.748338 -285.340806)
		(width 0.0889)
		(layer "In11.Cu")
		(net "UPI_CPU1_CPU0_P2P2_DP<15>")
	)
	(segment
		(start 260.065774 -370.024914)
		(end 260.029706 -370.229384)
		(width 0.14732)
		(layer "In11.Cu")
		(net "UPI_CPU1_CPU0_P2P2_DP<15>")
	)
	(segment
		(start 229.042468 -372.99265)
		(end 228.762814 -373.326152)
		(width 0.14732)
		(layer "In11.Cu")
		(net "UPI_CPU1_CPU0_P2P2_DP<15>")
	)
	(segment
		(start 235.001054 -373.312944)
		(end 234.841796 -373.179086)
		(width 0.14732)
		(layer "In11.Cu")
		(net "UPI_CPU1_CPU0_P2P2_DP<15>")
	)
	(segment
		(start 224.179384 -374.116346)
		(end 224.045526 -374.275604)
		(width 0.14732)
		(layer "In11.Cu")
		(net "UPI_CPU1_CPU0_P2P2_DP<15>")
	)
	(segment
		(start 266.010136 -364.142782)
		(end 265.715496 -364.437422)
		(width 0.14732)
		(layer "In11.Cu")
		(net "UPI_CPU1_CPU0_P2P2_DP<15>")
	)
	(segment
		(start 263.54278 -366.2553)
		(end 261.589774 -367.62309)
		(width 0.14732)
		(layer "In11.Cu")
		(net "UPI_CPU1_CPU0_P2P2_DP<15>")
	)
	(segment
		(start 265.865356 -362.271818)
		(end 266.010136 -362.416598)
		(width 0.14732)
		(layer "In11.Cu")
		(net "UPI_CPU1_CPU0_P2P2_DP<15>")
	)
	(segment
		(start 71.81215 -323.22262)
		(end 80.071214 -314.963302)
		(width 0.14732)
		(layer "In11.Cu")
		(net "UPI_CPU1_CPU0_P2P2_DP<15>")
	)
	(segment
		(start 260.029706 -370.229384)
		(end 259.545836 -370.56822)
		(width 0.14732)
		(layer "In11.Cu")
		(net "UPI_CPU1_CPU0_P2P2_DP<15>")
	)
	(segment
		(start 236.783118 -372.312184)
		(end 235.968286 -372.383812)
		(width 0.14732)
		(layer "In11.Cu")
		(net "UPI_CPU1_CPU0_P2P2_DP<15>")
	)
	(segment
		(start 226.733862 -373.195596)
		(end 226.454208 -373.529098)
		(width 0.14732)
		(layer "In11.Cu")
		(net "UPI_CPU1_CPU0_P2P2_DP<15>")
	)
	(segment
		(start 80.071214 -314.963302)
		(end 95.476822 -302.320706)
		(width 0.14732)
		(layer "In11.Cu")
		(net "UPI_CPU1_CPU0_P2P2_DP<15>")
	)
	(segment
		(start 307.335936 -325.480426)
		(end 306.995576 -325.718678)
		(width 0.14732)
		(layer "In11.Cu")
		(net "UPI_CPU1_CPU0_P2P2_DP<15>")
	)
	(segment
		(start 242.514374 -372.652036)
		(end 241.926872 -372.704106)
		(width 0.14732)
		(layer "In11.Cu")
		(net "UPI_CPU1_CPU0_P2P2_DP<15>")
	)
	(segment
		(start 265.249914 -364.903004)
		(end 264.725658 -365.42726)
		(width 0.14732)
		(layer "In11.Cu")
		(net "UPI_CPU1_CPU0_P2P2_DP<15>")
	)
	(segment
		(start 310.02732 -323.152008)
		(end 309.624984 -323.554344)
		(width 0.14732)
		(layer "In11.Cu")
		(net "UPI_CPU1_CPU0_P2P2_DP<15>")
	)
	(segment
		(start 240.339626 -372.695724)
		(end 240.205768 -372.854982)
		(width 0.14732)
		(layer "In11.Cu")
		(net "UPI_CPU1_CPU0_P2P2_DP<15>")
	)
	(segment
		(start 235.588556 -373.260874)
		(end 235.001054 -373.312944)
		(width 0.14732)
		(layer "In11.Cu")
		(net "UPI_CPU1_CPU0_P2P2_DP<15>")
	)
	(segment
		(start 100.755196 -285.336996)
		(end 100.755958 -285.336488)
		(width 0.0889)
		(layer "In11.Cu")
		(net "UPI_CPU1_CPU0_P2P2_DP<15>")
	)
	(segment
		(start 73.321164 -363.593634)
		(end 71.270368 -358.642666)
		(width 0.14732)
		(layer "In11.Cu")
		(net "UPI_CPU1_CPU0_P2P2_DP<15>")
	)
	(segment
		(start 304.282348 -330.16571)
		(end 284.748224 -330.16571)
		(width 0.14732)
		(layer "In11.Cu")
		(net "UPI_CPU1_CPU0_P2P2_DP<15>")
	)
	(segment
		(start 69.219318 -353.69119)
		(end 69.219318 -334.936338)
		(width 0.14732)
		(layer "In11.Cu")
		(net "UPI_CPU1_CPU0_P2P2_DP<15>")
	)
	(segment
		(start 340.6902 -290.617402)
		(end 340.674706 -290.632896)
		(width 0.0889)
		(layer "In11.Cu")
		(net "UPI_CPU1_CPU0_P2P2_DP<15>")
	)
	(segment
		(start 226.454208 -373.529098)
		(end 226.48799 -373.9134)
		(width 0.14732)
		(layer "In11.Cu")
		(net "UPI_CPU1_CPU0_P2P2_DP<15>")
	)
	(segment
		(start 237.150402 -372.97614)
		(end 237.116366 -372.591838)
		(width 0.14732)
		(layer "In11.Cu")
		(net "UPI_CPU1_CPU0_P2P2_DP<15>")
	)
	(segment
		(start 232.53319 -373.382032)
		(end 232.499154 -372.99773)
		(width 0.14732)
		(layer "In11.Cu")
		(net "UPI_CPU1_CPU0_P2P2_DP<15>")
	)
	(segment
		(start 342.020652 -286.80029)
		(end 342.015318 -286.803338)
		(width 0.0889)
		(layer "In11.Cu")
		(net "UPI_CPU1_CPU0_P2P2_DP<15>")
	)
	(segment
		(start 341.268812 -289.645852)
		(end 341.269066 -289.64636)
		(width 0.0889)
		(layer "In11.Cu")
		(net "UPI_CPU1_CPU0_P2P2_DP<15>")
	)
	(segment
		(start 98.86696 -288.597848)
		(end 98.87585 -288.592768)
		(width 0.0889)
		(layer "In11.Cu")
		(net "UPI_CPU1_CPU0_P2P2_DP<15>")
	)
	(segment
		(start 99.33686 -287.783778)
		(end 99.34575 -287.778698)
		(width 0.0889)
		(layer "In11.Cu")
		(net "UPI_CPU1_CPU0_P2P2_DP<15>")
	)
	(segment
		(start 263.880346 -365.842296)
		(end 263.57834 -366.053624)
		(width 0.14732)
		(layer "In11.Cu")
		(net "UPI_CPU1_CPU0_P2P2_DP<15>")
	)
	(segment
		(start 98.260154 -296.882312)
		(end 98.260154 -290.405566)
		(width 0.14732)
		(layer "In11.Cu")
		(net "UPI_CPU1_CPU0_P2P2_DP<15>")
	)
	(segment
		(start 101.695758 -283.708856)
		(end 101.701092 -283.705808)
		(width 0.0889)
		(layer "In11.Cu")
		(net "UPI_CPU1_CPU0_P2P2_DP<15>")
	)
	(segment
		(start 102.039674 -283.219906)
		(end 102.352348 -283.219906)
		(width 0.0889)
		(layer "In11.Cu")
		(net "UPI_CPU1_CPU0_P2P2_DP<15>")
	)
	(segment
		(start 342.96985 -283.539184)
		(end 342.96096 -283.544264)
		(width 0.0889)
		(layer "In11.Cu")
		(net "UPI_CPU1_CPU0_P2P2_DP<15>")
	)
	(segment
		(start 233.27995 -373.46382)
		(end 232.692448 -373.51589)
		(width 0.14732)
		(layer "In11.Cu")
		(net "UPI_CPU1_CPU0_P2P2_DP<15>")
	)
	(segment
		(start 314.75426 -320.35877)
		(end 314.247276 -320.865754)
		(width 0.14732)
		(layer "In11.Cu")
		(net "UPI_CPU1_CPU0_P2P2_DP<15>")
	)
	(segment
		(start 341.269066 -288.087562)
		(end 341.269066 -288.103056)
		(width 0.0889)
		(layer "In11.Cu")
		(net "UPI_CPU1_CPU0_P2P2_DP<15>")
	)
	(segment
		(start 341.269066 -290.097464)
		(end 340.749128 -290.617402)
		(width 0.0889)
		(layer "In11.Cu")
		(net "UPI_CPU1_CPU0_P2P2_DP<15>")
	)
	(segment
		(start 98.260154 -290.405566)
		(end 98.260154 -290.383468)
		(width 0.0889)
		(layer "In11.Cu")
		(net "UPI_CPU1_CPU0_P2P2_DP<15>")
	)
	(segment
		(start 264.725404 -365.42726)
		(end 264.082022 -365.877856)
		(width 0.14732)
		(layer "In11.Cu")
		(net "UPI_CPU1_CPU0_P2P2_DP<15>")
	)
	(segment
		(start 264.725658 -365.42726)
		(end 264.725404 -365.42726)
		(width 0.14732)
		(layer "In11.Cu")
		(net "UPI_CPU1_CPU0_P2P2_DP<15>")
	)
	(segment
		(start 225.607372 -373.99087)
		(end 225.573336 -373.606568)
		(width 0.14732)
		(layer "In11.Cu")
		(net "UPI_CPU1_CPU0_P2P2_DP<15>")
	)
	(segment
		(start 342.030304 -285.166816)
		(end 342.015318 -285.175452)
		(width 0.0889)
		(layer "In11.Cu")
		(net "UPI_CPU1_CPU0_P2P2_DP<15>")
	)
	(segment
		(start 237.116366 -372.591838)
		(end 236.783118 -372.312184)
		(width 0.14732)
		(layer "In11.Cu")
		(net "UPI_CPU1_CPU0_P2P2_DP<15>")
	)
	(segment
		(start 242.61445 -372.108476)
		(end 242.648232 -372.492778)
		(width 0.14732)
		(layer "In11.Cu")
		(net "UPI_CPU1_CPU0_P2P2_DP<15>")
	)
	(segment
		(start 314.247276 -320.865754)
		(end 311.303416 -322.926964)
		(width 0.14732)
		(layer "In11.Cu")
		(net "UPI_CPU1_CPU0_P2P2_DP<15>")
	)
	(segment
		(start 241.733578 -372.185946)
		(end 241.40033 -371.906292)
		(width 0.14732)
		(layer "In11.Cu")
		(net "UPI_CPU1_CPU0_P2P2_DP<15>")
	)
	(segment
		(start 266.010136 -362.929678)
		(end 265.865356 -363.074458)
		(width 0.14732)
		(layer "In11.Cu")
		(net "UPI_CPU1_CPU0_P2P2_DP<15>")
	)
	(segment
		(start 341.269066 -289.64636)
		(end 341.269066 -290.097464)
		(width 0.0889)
		(layer "In11.Cu")
		(net "UPI_CPU1_CPU0_P2P2_DP<15>")
	)
	(segment
		(start 265.249914 -364.69828)
		(end 265.249914 -364.903004)
		(width 0.14732)
		(layer "In11.Cu")
		(net "UPI_CPU1_CPU0_P2P2_DP<15>")
	)
	(segment
		(start 231.105202 -373.507508)
		(end 230.971344 -373.666766)
		(width 0.14732)
		(layer "In11.Cu")
		(net "UPI_CPU1_CPU0_P2P2_DP<15>")
	)
	(segment
		(start 335.103978 -295.909238)
		(end 333.31785 -301.795434)
		(width 0.14732)
		(layer "In11.Cu")
		(net "UPI_CPU1_CPU0_P2P2_DP<15>")
	)
	(segment
		(start 266.010136 -361.758738)
		(end 265.865356 -361.903518)
		(width 0.14732)
		(layer "In11.Cu")
		(net "UPI_CPU1_CPU0_P2P2_DP<15>")
	)
	(segment
		(start 101.507544 -284.049216)
		(end 101.507544 -284.033722)
		(width 0.0889)
		(layer "In11.Cu")
		(net "UPI_CPU1_CPU0_P2P2_DP<15>")
	)
	(segment
		(start 228.662738 -373.869712)
		(end 228.075236 -373.921782)
		(width 0.14732)
		(layer "In11.Cu")
		(net "UPI_CPU1_CPU0_P2P2_DP<15>")
	)
	(segment
		(start 69.219318 -334.936338)
		(end 69.857112 -328.45883)
		(width 0.14732)
		(layer "In11.Cu")
		(net "UPI_CPU1_CPU0_P2P2_DP<15>")
	)
	(segment
		(start 306.249324 -327.985374)
		(end 305.749198 -328.699368)
		(width 0.14732)
		(layer "In11.Cu")
		(net "UPI_CPU1_CPU0_P2P2_DP<15>")
	)
	(segment
		(start 315.219842 -319.893188)
		(end 315.015118 -319.893188)
		(width 0.14732)
		(layer "In11.Cu")
		(net "UPI_CPU1_CPU0_P2P2_DP<15>")
	)
	(segment
		(start 97.93732 -375.773188)
		(end 76.707238 -366.979962)
		(width 0.14732)
		(layer "In11.Cu")
		(net "UPI_CPU1_CPU0_P2P2_DP<15>")
	)
	(segment
		(start 342.208612 -286.466788)
		(end 342.208612 -286.48406)
		(width 0.0889)
		(layer "In11.Cu")
		(net "UPI_CPU1_CPU0_P2P2_DP<15>")
	)
	(segment
		(start 339.859874 -291.882068)
		(end 337.869022 -293.87292)
		(width 0.14732)
		(layer "In11.Cu")
		(net "UPI_CPU1_CPU0_P2P2_DP<15>")
	)
	(segment
		(start 266.010136 -345.327478)
		(end 266.010136 -361.758738)
		(width 0.14732)
		(layer "In11.Cu")
		(net "UPI_CPU1_CPU0_P2P2_DP<15>")
	)
	(segment
		(start 315.015118 -319.893188)
		(end 314.75426 -320.154046)
		(width 0.14732)
		(layer "In11.Cu")
		(net "UPI_CPU1_CPU0_P2P2_DP<15>")
	)
	(segment
		(start 340.799166 -288.898584)
		(end 340.799166 -289.114738)
		(width 0.0889)
		(layer "In11.Cu")
		(net "UPI_CPU1_CPU0_P2P2_DP<15>")
	)
	(segment
		(start 99.806506 -286.969962)
		(end 99.821746 -286.961072)
		(width 0.0889)
		(layer "In11.Cu")
		(net "UPI_CPU1_CPU0_P2P2_DP<15>")
	)
	(segment
		(start 239.091724 -372.109238)
		(end 238.276892 -372.180866)
		(width 0.14732)
		(layer "In11.Cu")
		(net "UPI_CPU1_CPU0_P2P2_DP<15>")
	)
	(segment
		(start 100.098098 -286.475424)
		(end 100.098098 -286.466788)
		(width 0.0889)
		(layer "In11.Cu")
		(net "UPI_CPU1_CPU0_P2P2_DP<15>")
	)
	(segment
		(start 69.857112 -328.45883)
		(end 70.592442 -325.801228)
		(width 0.14732)
		(layer "In11.Cu")
		(net "UPI_CPU1_CPU0_P2P2_DP<15>")
	)
	(segment
		(start 100.567744 -285.679896)
		(end 100.567744 -285.661354)
		(width 0.0889)
		(layer "In11.Cu")
		(net "UPI_CPU1_CPU0_P2P2_DP<15>")
	)
	(segment
		(start 231.07142 -373.123206)
		(end 231.105202 -373.507508)
		(width 0.14732)
		(layer "In11.Cu")
		(net "UPI_CPU1_CPU0_P2P2_DP<15>")
	)
	(segment
		(start 284.748224 -330.16571)
		(end 278.643334 -332.69428)
		(width 0.14732)
		(layer "In11.Cu")
		(net "UPI_CPU1_CPU0_P2P2_DP<15>")
	)
	(segment
		(start 101.688138 -283.713174)
		(end 101.694996 -283.709364)
		(width 0.0889)
		(layer "In11.Cu")
		(net "UPI_CPU1_CPU0_P2P2_DP<15>")
	)
	(segment
		(start 99.158298 -288.121598)
		(end 99.158298 -288.103056)
		(width 0.0889)
		(layer "In11.Cu")
		(net "UPI_CPU1_CPU0_P2P2_DP<15>")
	)
	(segment
		(start 257.352546 -370.58981)
		(end 248.852944 -372.08841)
		(width 0.14732)
		(layer "In11.Cu")
		(net "UPI_CPU1_CPU0_P2P2_DP<15>")
	)
	(segment
		(start 228.075236 -373.921782)
		(end 227.915978 -373.787924)
		(width 0.14732)
		(layer "In11.Cu")
		(net "UPI_CPU1_CPU0_P2P2_DP<15>")
	)
	(segment
		(start 228.762814 -373.326152)
		(end 228.796596 -373.710454)
		(width 0.14732)
		(layer "In11.Cu")
		(net "UPI_CPU1_CPU0_P2P2_DP<15>")
	)
	(segment
		(start 222.931482 -373.52986)
		(end 222.11665 -373.601488)
		(width 0.14732)
		(layer "In11.Cu")
		(net "UPI_CPU1_CPU0_P2P2_DP<15>")
	)
	(segment
		(start 261.444232 -369.238784)
		(end 261.239762 -369.202716)
		(width 0.14732)
		(layer "In11.Cu")
		(net "UPI_CPU1_CPU0_P2P2_DP<15>")
	)
	(segment
		(start 233.380026 -372.92026)
		(end 233.413808 -373.304562)
		(width 0.14732)
		(layer "In11.Cu")
		(net "UPI_CPU1_CPU0_P2P2_DP<15>")
	)
	(segment
		(start 266.010136 -362.416598)
		(end 266.010136 -362.929678)
		(width 0.14732)
		(layer "In11.Cu")
		(net "UPI_CPU1_CPU0_P2P2_DP<15>")
	)
	(segment
		(start 240.585498 -371.97792)
		(end 240.305844 -372.311422)
		(width 0.14732)
		(layer "In11.Cu")
		(net "UPI_CPU1_CPU0_P2P2_DP<15>")
	)
	(segment
		(start 222.11665 -373.601488)
		(end 221.836996 -373.93499)
		(width 0.14732)
		(layer "In11.Cu")
		(net "UPI_CPU1_CPU0_P2P2_DP<15>")
	)
	(segment
		(start 235.722414 -373.101616)
		(end 235.588556 -373.260874)
		(width 0.14732)
		(layer "In11.Cu")
		(net "UPI_CPU1_CPU0_P2P2_DP<15>")
	)
	(segment
		(start 340.674706 -290.632896)
		(end 339.859874 -291.447728)
		(width 0.14732)
		(layer "In11.Cu")
		(net "UPI_CPU1_CPU0_P2P2_DP<15>")
	)
	(segment
		(start 230.383842 -373.718836)
		(end 230.224584 -373.584978)
		(width 0.14732)
		(layer "In11.Cu")
		(net "UPI_CPU1_CPU0_P2P2_DP<15>")
	)
	(segment
		(start 333.31785 -301.795434)
		(end 315.219842 -319.893188)
		(width 0.14732)
		(layer "In11.Cu")
		(net "UPI_CPU1_CPU0_P2P2_DP<15>")
	)
	(segment
		(start 232.692448 -373.51589)
		(end 232.53319 -373.382032)
		(width 0.14732)
		(layer "In11.Cu")
		(net "UPI_CPU1_CPU0_P2P2_DP<15>")
	)
	(segment
		(start 244.223794 -372.491254)
		(end 244.07622 -372.367048)
		(width 0.14732)
		(layer "In11.Cu")
		(net "UPI_CPU1_CPU0_P2P2_DP<15>")
	)
	(segment
		(start 225.573336 -373.606568)
		(end 225.240088 -373.326914)
		(width 0.14732)
		(layer "In11.Cu")
		(net "UPI_CPU1_CPU0_P2P2_DP<15>")
	)
	(segment
		(start 71.270368 -358.642412)
		(end 69.219318 -353.69119)
		(width 0.14732)
		(layer "In11.Cu")
		(net "UPI_CPU1_CPU0_P2P2_DP<15>")
	)
	(segment
		(start 95.476822 -302.320706)
		(end 96.679258 -300.699424)
		(width 0.14732)
		(layer "In11.Cu")
		(net "UPI_CPU1_CPU0_P2P2_DP<15>")
	)
	(segment
		(start 343.909904 -281.911298)
		(end 343.894918 -281.919934)
		(width 0.0889)
		(layer "In11.Cu")
		(net "UPI_CPU1_CPU0_P2P2_DP<15>")
	)
	(segment
		(start 314.75426 -320.154046)
		(end 314.75426 -320.35877)
		(width 0.14732)
		(layer "In11.Cu")
		(net "UPI_CPU1_CPU0_P2P2_DP<15>")
	)
	(segment
		(start 230.224584 -373.584978)
		(end 230.190548 -373.200676)
		(width 0.14732)
		(layer "In11.Cu")
		(net "UPI_CPU1_CPU0_P2P2_DP<15>")
	)
	(segment
		(start 344.558112 -280.76398)
		(end 344.558112 -280.78684)
		(width 0.0889)
		(layer "In11.Cu")
		(net "UPI_CPU1_CPU0_P2P2_DP<15>")
	)
	(segment
		(start 230.190548 -373.200676)
		(end 229.8573 -372.921022)
		(width 0.14732)
		(layer "In11.Cu")
		(net "UPI_CPU1_CPU0_P2P2_DP<15>")
	)
	(segment
		(start 241.40033 -371.906292)
		(end 240.585498 -371.97792)
		(width 0.14732)
		(layer "In11.Cu")
		(net "UPI_CPU1_CPU0_P2P2_DP<15>")
	)
	(segment
		(start 244.042184 -371.983)
		(end 243.708936 -371.703346)
		(width 0.14732)
		(layer "In11.Cu")
		(net "UPI_CPU1_CPU0_P2P2_DP<15>")
	)
	(segment
		(start 223.26473 -373.809514)
		(end 222.931482 -373.52986)
		(width 0.14732)
		(layer "In11.Cu")
		(net "UPI_CPU1_CPU0_P2P2_DP<15>")
	)
	(segment
		(start 344.81008 -280.235152)
		(end 344.78595 -280.324306)
		(width 0.0889)
		(layer "In11.Cu")
		(net "UPI_CPU1_CPU0_P2P2_DP<15>")
	)
	(segment
		(start 224.045526 -374.275604)
		(end 223.458024 -374.327674)
		(width 0.14732)
		(layer "In11.Cu")
		(net "UPI_CPU1_CPU0_P2P2_DP<15>")
	)
	(segment
		(start 71.270368 -358.642666)
		(end 71.270368 -358.642412)
		(width 0.14732)
		(layer "In11.Cu")
		(net "UPI_CPU1_CPU0_P2P2_DP<15>")
	)
	(segment
		(start 265.865356 -363.074458)
		(end 265.865356 -363.442758)
		(width 0.14732)
		(layer "In11.Cu")
		(net "UPI_CPU1_CPU0_P2P2_DP<15>")
	)
	(segment
		(start 341.090504 -288.422334)
		(end 341.081614 -288.427414)
		(width 0.0889)
		(layer "In11.Cu")
		(net "UPI_CPU1_CPU0_P2P2_DP<15>")
	)
	(segment
		(start 227.881942 -373.403622)
		(end 227.548694 -373.123968)
		(width 0.14732)
		(layer "In11.Cu")
		(net "UPI_CPU1_CPU0_P2P2_DP<15>")
	)
	(segment
		(start 306.53228 -326.380348)
		(end 306.249324 -327.985374)
		(width 0.14732)
		(layer "In11.Cu")
		(net "UPI_CPU1_CPU0_P2P2_DP<15>")
	)
	(segment
		(start 233.413808 -373.304562)
		(end 233.27995 -373.46382)
		(width 0.14732)
		(layer "In11.Cu")
		(net "UPI_CPU1_CPU0_P2P2_DP<15>")
	)
	(segment
		(start 200.15073 -373.145304)
		(end 161.638234 -379.93447)
		(width 0.14732)
		(layer "In11.Cu")
		(net "UPI_CPU1_CPU0_P2P2_DP<15>")
	)
	(segment
		(start 265.865356 -361.903518)
		(end 265.865356 -362.271818)
		(width 0.14732)
		(layer "In11.Cu")
		(net "UPI_CPU1_CPU0_P2P2_DP<15>")
	)
	(segment
		(start 306.995576 -325.718678)
		(end 306.53228 -326.380348)
		(width 0.14732)
		(layer "In11.Cu")
		(net "UPI_CPU1_CPU0_P2P2_DP<15>")
	)
	(segment
		(start 342.678512 -284.023816)
		(end 342.678512 -284.033722)
		(width 0.0889)
		(layer "In11.Cu")
		(net "UPI_CPU1_CPU0_P2P2_DP<15>")
	)
	(segment
		(start 224.145602 -373.732044)
		(end 224.179384 -374.116346)
		(width 0.14732)
		(layer "In11.Cu")
		(net "UPI_CPU1_CPU0_P2P2_DP<15>")
	)
	(segment
		(start 238.03102 -372.89867)
		(end 237.897162 -373.057928)
		(width 0.14732)
		(layer "In11.Cu")
		(net "UPI_CPU1_CPU0_P2P2_DP<15>")
	)
	(segment
		(start 96.679258 -300.699424)
		(end 98.260154 -296.882312)
		(width 0.14732)
		(layer "In11.Cu")
		(net "UPI_CPU1_CPU0_P2P2_DP<15>")
	)
	(segment
		(start 98.688398 -289.114484)
		(end 98.688398 -288.917126)
		(width 0.0889)
		(layer "In11.Cu")
		(net "UPI_CPU1_CPU0_P2P2_DP<15>")
	)
	(segment
		(start 261.239762 -369.202716)
		(end 260.78942 -368.559588)
		(width 0.14732)
		(layer "In11.Cu")
		(net "UPI_CPU1_CPU0_P2P2_DP<15>")
	)
	(segment
		(start 98.218244 -290.341558)
		(end 98.218244 -289.64636)
		(width 0.0889)
		(layer "In11.Cu")
		(net "UPI_CPU1_CPU0_P2P2_DP<15>")
	)
	(segment
		(start 343.43975 -282.725114)
		(end 343.43086 -282.730194)
		(width 0.0889)
		(layer "In11.Cu")
		(net "UPI_CPU1_CPU0_P2P2_DP<15>")
	)
	(segment
		(start 311.303416 -322.926964)
		(end 310.02732 -323.152008)
		(width 0.14732)
		(layer "In11.Cu")
		(net "UPI_CPU1_CPU0_P2P2_DP<15>")
	)
	(segment
		(start 231.351074 -372.789704)
		(end 231.07142 -373.123206)
		(width 0.14732)
		(layer "In11.Cu")
		(net "UPI_CPU1_CPU0_P2P2_DP<15>")
	)
	(segment
		(start 226.354132 -374.072658)
		(end 225.76663 -374.124728)
		(width 0.14732)
		(layer "In11.Cu")
		(net "UPI_CPU1_CPU0_P2P2_DP<15>")
	)
	(segment
		(start 239.424972 -372.388892)
		(end 239.091724 -372.109238)
		(width 0.14732)
		(layer "In11.Cu")
		(net "UPI_CPU1_CPU0_P2P2_DP<15>")
	)
	(segment
		(start 342.021414 -286.799782)
		(end 342.020652 -286.80029)
		(width 0.0889)
		(layer "In11.Cu")
		(net "UPI_CPU1_CPU0_P2P2_DP<15>")
	)
	(segment
		(start 223.458024 -374.327674)
		(end 223.298766 -374.193816)
		(width 0.14732)
		(layer "In11.Cu")
		(net "UPI_CPU1_CPU0_P2P2_DP<15>")
	)
	(segment
		(start 232.165906 -372.718076)
		(end 231.351074 -372.789704)
		(width 0.14732)
		(layer "In11.Cu")
		(net "UPI_CPU1_CPU0_P2P2_DP<15>")
	)
	(segment
		(start 101.21646 -284.52826)
		(end 101.22535 -284.52318)
		(width 0.0889)
		(layer "In11.Cu")
		(net "UPI_CPU1_CPU0_P2P2_DP<15>")
	)
	(segment
		(start 225.76663 -374.124728)
		(end 225.607372 -373.99087)
		(width 0.14732)
		(layer "In11.Cu")
		(net "UPI_CPU1_CPU0_P2P2_DP<15>")
	)
	(segment
		(start 243.708936 -371.703346)
		(end 242.894104 -371.774974)
		(width 0.14732)
		(layer "In11.Cu")
		(net "UPI_CPU1_CPU0_P2P2_DP<15>")
	)
	(segment
		(start 340.749128 -290.617402)
		(end 340.6902 -290.617402)
		(width 0.0889)
		(layer "In11.Cu")
		(net "UPI_CPU1_CPU0_P2P2_DP<15>")
	)
	(segment
		(start 235.968286 -372.383812)
		(end 235.688632 -372.717314)
		(width 0.14732)
		(layer "In11.Cu")
		(net "UPI_CPU1_CPU0_P2P2_DP<15>")
	)
	(segment
		(start 258.891024 -369.889024)
		(end 258.462018 -369.813078)
		(width 0.14732)
		(layer "In11.Cu")
		(net "UPI_CPU1_CPU0_P2P2_DP<15>")
	)
	(segment
		(start 237.30966 -373.109998)
		(end 237.150402 -372.97614)
		(width 0.14732)
		(layer "In11.Cu")
		(net "UPI_CPU1_CPU0_P2P2_DP<15>")
	)
	(segment
		(start 265.865356 -363.442758)
		(end 266.010136 -363.587538)
		(width 0.14732)
		(layer "In11.Cu")
		(net "UPI_CPU1_CPU0_P2P2_DP<15>")
	)
	(segment
		(start 261.928102 -368.899948)
		(end 261.444232 -369.238784)
		(width 0.14732)
		(layer "In11.Cu")
		(net "UPI_CPU1_CPU0_P2P2_DP<15>")
	)
	(segment
		(start 265.510772 -364.437422)
		(end 265.249914 -364.69828)
		(width 0.14732)
		(layer "In11.Cu")
		(net "UPI_CPU1_CPU0_P2P2_DP<15>")
	)
	(segment
		(start 337.869022 -293.87292)
		(end 335.926938 -294.677338)
		(width 0.14732)
		(layer "In11.Cu")
		(net "UPI_CPU1_CPU0_P2P2_DP<15>")
	)
	(segment
		(start 225.240088 -373.326914)
		(end 224.425256 -373.398542)
		(width 0.14732)
		(layer "In11.Cu")
		(net "UPI_CPU1_CPU0_P2P2_DP<15>")
	)
	(segment
		(start 265.715496 -364.437422)
		(end 265.510772 -364.437422)
		(width 0.14732)
		(layer "In11.Cu")
		(net "UPI_CPU1_CPU0_P2P2_DP<15>")
	)
	(segment
		(start 234.80776 -372.794784)
		(end 234.474512 -372.51513)
		(width 0.14732)
		(layer "In11.Cu")
		(net "UPI_CPU1_CPU0_P2P2_DP<15>")
	)
	(segment
		(start 239.459008 -372.773194)
		(end 239.424972 -372.388892)
		(width 0.14732)
		(layer "In11.Cu")
		(net "UPI_CPU1_CPU0_P2P2_DP<15>")
	)
	(segment
		(start 212.373464 -375.300494)
		(end 200.15073 -373.145304)
		(width 0.14732)
		(layer "In11.Cu")
		(net "UPI_CPU1_CPU0_P2P2_DP<15>")
	)
	(segment
		(start 228.796596 -373.710454)
		(end 228.662738 -373.869712)
		(width 0.14732)
		(layer "In11.Cu")
		(net "UPI_CPU1_CPU0_P2P2_DP<15>")
	)
	(segment
		(start 237.897162 -373.057928)
		(end 237.30966 -373.109998)
		(width 0.14732)
		(layer "In11.Cu")
		(net "UPI_CPU1_CPU0_P2P2_DP<15>")
	)
	(segment
		(start 335.926938 -294.677338)
		(end 335.103978 -295.909238)
		(width 0.14732)
		(layer "In11.Cu")
		(net "UPI_CPU1_CPU0_P2P2_DP<15>")
	)
	(segment
		(start 100.748338 -285.340806)
		(end 100.755196 -285.336996)
		(width 0.0889)
		(layer "In11.Cu")
		(net "UPI_CPU1_CPU0_P2P2_DP<15>")
	)
	(segment
		(start 242.648232 -372.492778)
		(end 242.514374 -372.652036)
		(width 0.14732)
		(layer "In11.Cu")
		(net "UPI_CPU1_CPU0_P2P2_DP<15>")
	)
	(segment
		(start 344.088466 -281.582114)
		(end 344.088466 -281.59202)
		(width 0.0889)
		(layer "In11.Cu")
		(net "UPI_CPU1_CPU0_P2P2_DP<15>")
	)
	(segment
		(start 342.208866 -284.832044)
		(end 342.208866 -284.847538)
		(width 0.0889)
		(layer "In11.Cu")
		(net "UPI_CPU1_CPU0_P2P2_DP<15>")
	)
	(segment
		(start 241.767614 -372.570248)
		(end 241.733578 -372.185946)
		(width 0.14732)
		(layer "In11.Cu")
		(net "UPI_CPU1_CPU0_P2P2_DP<15>")
	)
	(segment
		(start 99.821746 -286.961072)
		(end 99.821492 -286.961326)
		(width 0.0889)
		(layer "In11.Cu")
		(net "UPI_CPU1_CPU0_P2P2_DP<15>")
	)
	(segment
		(start 341.56015 -287.608518)
		(end 341.55126 -287.613598)
		(width 0.0889)
		(layer "In11.Cu")
		(net "UPI_CPU1_CPU0_P2P2_DP<15>")
	)
	(segment
		(start 229.8573 -372.921022)
		(end 229.042468 -372.99265)
		(width 0.14732)
		(layer "In11.Cu")
		(net "UPI_CPU1_CPU0_P2P2_DP<15>")
	)
	(segment
		(start 261.589774 -367.62309)
		(end 261.513828 -368.051842)
		(width 0.14732)
		(layer "In11.Cu")
		(net "UPI_CPU1_CPU0_P2P2_DP<15>")
	)
	(segment
		(start 309.624984 -323.554344)
		(end 307.335936 -325.480426)
		(width 0.14732)
		(layer "In11.Cu")
		(net "UPI_CPU1_CPU0_P2P2_DP<15>")
	)
	(segment
		(start 99.627944 -287.304734)
		(end 99.627944 -287.28924)
		(width 0.0889)
		(layer "In11.Cu")
		(net "UPI_CPU1_CPU0_P2P2_DP<15>")
	)
	(segment
		(start 100.755958 -285.336488)
		(end 100.761292 -285.33344)
		(width 0.0889)
		(layer "In11.Cu")
		(net "UPI_CPU1_CPU0_P2P2_DP<15>")
	)
	(segment
		(start 233.65968 -372.586758)
		(end 233.380026 -372.92026)
		(width 0.14732)
		(layer "In11.Cu")
		(net "UPI_CPU1_CPU0_P2P2_DP<15>")
	)
	(segment
		(start 266.010136 -363.587538)
		(end 266.010136 -364.142782)
		(width 0.14732)
		(layer "In11.Cu")
		(net "UPI_CPU1_CPU0_P2P2_DP<15>")
	)
	(segment
		(start 242.894104 -371.774974)
		(end 242.61445 -372.108476)
		(width 0.14732)
		(layer "In11.Cu")
		(net "UPI_CPU1_CPU0_P2P2_DP<15>")
	)
	(segment
		(start 260.78942 -368.559588)
		(end 260.360668 -368.483642)
		(width 0.14732)
		(layer "In11.Cu")
		(net "UPI_CPU1_CPU0_P2P2_DP<15>")
	)
	(segment
		(start 227.915978 -373.787924)
		(end 227.881942 -373.403622)
		(width 0.14732)
		(layer "In11.Cu")
		(net "UPI_CPU1_CPU0_P2P2_DP<15>")
	)
	(segment
		(start 101.973888 -283.285692)
		(end 102.039674 -283.219906)
		(width 0.0889)
		(layer "In11.Cu")
		(net "UPI_CPU1_CPU0_P2P2_DP<15>")
	)
	(arc
		(start 342.015318 -286.803338)
		(mid 341.812731 -287.009689)
		(end 341.738712 -287.28924)
		(width 0.0889)
		(layer "In11.Cu")
		(net "UPI_CPU1_CPU0_P2P2_DP<15>")
	)
	(arc
		(start 344.370914 -281.102562)
		(mid 344.166579 -281.305167)
		(end 344.088466 -281.582114)
		(width 0.0889)
		(layer "In11.Cu")
		(net "UPI_CPU1_CPU0_P2P2_DP<15>")
	)
	(arc
		(start 342.678512 -284.033722)
		(mid 342.630833 -284.216622)
		(end 342.49995 -284.353)
		(width 0.0889)
		(layer "In11.Cu")
		(net "UPI_CPU1_CPU0_P2P2_DP<15>")
	)
	(arc
		(start 344.78595 -280.324306)
		(mid 344.777379 -280.330702)
		(end 344.768932 -280.33726)
		(width 0.0889)
		(layer "In11.Cu")
		(net "UPI_CPU1_CPU0_P2P2_DP<15>")
	)
	(arc
		(start 344.088466 -281.59202)
		(mid 344.040787 -281.77492)
		(end 343.909904 -281.911298)
		(width 0.0889)
		(layer "In11.Cu")
		(net "UPI_CPU1_CPU0_P2P2_DP<15>")
	)
	(arc
		(start 343.618312 -282.405836)
		(mid 343.570633 -282.588736)
		(end 343.43975 -282.725114)
		(width 0.0889)
		(layer "In11.Cu")
		(net "UPI_CPU1_CPU0_P2P2_DP<15>")
	)
	(arc
		(start 341.55126 -287.613598)
		(mid 341.348437 -287.813829)
		(end 341.269066 -288.087562)
		(width 0.0889)
		(layer "In11.Cu")
		(net "UPI_CPU1_CPU0_P2P2_DP<15>")
	)
	(arc
		(start 341.738712 -287.28924)
		(mid 341.691033 -287.47214)
		(end 341.56015 -287.608518)
		(width 0.0889)
		(layer "In11.Cu")
		(net "UPI_CPU1_CPU0_P2P2_DP<15>")
	)
	(arc
		(start 341.269066 -288.103056)
		(mid 341.221387 -288.285956)
		(end 341.090504 -288.422334)
		(width 0.0889)
		(layer "In11.Cu")
		(net "UPI_CPU1_CPU0_P2P2_DP<15>")
	)
	(arc
		(start 100.098098 -286.466788)
		(mid 100.150368 -286.284423)
		(end 100.285296 -286.151066)
		(width 0.0889)
		(layer "In11.Cu")
		(net "UPI_CPU1_CPU0_P2P2_DP<15>")
	)
	(arc
		(start 343.894918 -281.919934)
		(mid 343.692331 -282.126285)
		(end 343.618312 -282.405836)
		(width 0.0889)
		(layer "In11.Cu")
		(net "UPI_CPU1_CPU0_P2P2_DP<15>")
	)
	(arc
		(start 342.021414 -286.151066)
		(mid 342.156347 -286.28442)
		(end 342.208612 -286.466788)
		(width 0.0889)
		(layer "In11.Cu")
		(net "UPI_CPU1_CPU0_P2P2_DP<15>")
	)
	(arc
		(start 100.567744 -285.661354)
		(mid 100.615423 -285.478454)
		(end 100.746306 -285.342076)
		(width 0.0889)
		(layer "In11.Cu")
		(net "UPI_CPU1_CPU0_P2P2_DP<15>")
	)
	(arc
		(start 99.627944 -287.28924)
		(mid 99.675623 -287.10634)
		(end 99.806506 -286.969962)
		(width 0.0889)
		(layer "In11.Cu")
		(net "UPI_CPU1_CPU0_P2P2_DP<15>")
	)
	(arc
		(start 101.507544 -284.033722)
		(mid 101.555223 -283.850822)
		(end 101.686106 -283.714444)
		(width 0.0889)
		(layer "In11.Cu")
		(net "UPI_CPU1_CPU0_P2P2_DP<15>")
	)
	(arc
		(start 99.821492 -286.961326)
		(mid 100.024079 -286.754975)
		(end 100.098098 -286.475424)
		(width 0.0889)
		(layer "In11.Cu")
		(net "UPI_CPU1_CPU0_P2P2_DP<15>")
	)
	(arc
		(start 343.43086 -282.730194)
		(mid 343.228574 -282.929175)
		(end 343.148412 -283.201364)
		(width 0.0889)
		(layer "In11.Cu")
		(net "UPI_CPU1_CPU0_P2P2_DP<15>")
	)
	(arc
		(start 98.402648 -289.446462)
		(mid 98.576949 -289.307532)
		(end 98.688398 -289.114484)
		(width 0.0889)
		(layer "In11.Cu")
		(net "UPI_CPU1_CPU0_P2P2_DP<15>")
	)
	(arc
		(start 98.688398 -288.917126)
		(mid 98.736077 -288.734226)
		(end 98.86696 -288.597848)
		(width 0.0889)
		(layer "In11.Cu")
		(net "UPI_CPU1_CPU0_P2P2_DP<15>")
	)
	(arc
		(start 101.971094 -283.30652)
		(mid 101.972589 -283.296119)
		(end 101.973888 -283.285692)
		(width 0.0889)
		(layer "In11.Cu")
		(net "UPI_CPU1_CPU0_P2P2_DP<15>")
	)
	(arc
		(start 342.49106 -284.35808)
		(mid 342.288237 -284.558311)
		(end 342.208866 -284.832044)
		(width 0.0889)
		(layer "In11.Cu")
		(net "UPI_CPU1_CPU0_P2P2_DP<15>")
	)
	(arc
		(start 340.799166 -289.114738)
		(mid 340.910504 -289.307638)
		(end 341.084662 -289.446462)
		(width 0.0889)
		(layer "In11.Cu")
		(net "UPI_CPU1_CPU0_P2P2_DP<15>")
	)
	(arc
		(start 343.148412 -283.219906)
		(mid 343.100733 -283.402806)
		(end 342.96985 -283.539184)
		(width 0.0889)
		(layer "In11.Cu")
		(net "UPI_CPU1_CPU0_P2P2_DP<15>")
	)
	(arc
		(start 342.96096 -283.544264)
		(mid 342.756625 -283.746869)
		(end 342.678512 -284.023816)
		(width 0.0889)
		(layer "In11.Cu")
		(net "UPI_CPU1_CPU0_P2P2_DP<15>")
	)
	(arc
		(start 101.701092 -283.705808)
		(mid 101.880744 -283.536372)
		(end 101.971094 -283.30652)
		(width 0.0889)
		(layer "In11.Cu")
		(net "UPI_CPU1_CPU0_P2P2_DP<15>")
	)
	(arc
		(start 99.158298 -288.103056)
		(mid 99.205977 -287.920156)
		(end 99.33686 -287.783778)
		(width 0.0889)
		(layer "In11.Cu")
		(net "UPI_CPU1_CPU0_P2P2_DP<15>")
	)
	(arc
		(start 98.218244 -289.64636)
		(mid 98.293315 -289.530618)
		(end 98.402648 -289.446462)
		(width 0.0889)
		(layer "In11.Cu")
		(net "UPI_CPU1_CPU0_P2P2_DP<15>")
	)
	(arc
		(start 342.208866 -284.847538)
		(mid 342.161187 -285.030438)
		(end 342.030304 -285.166816)
		(width 0.0889)
		(layer "In11.Cu")
		(net "UPI_CPU1_CPU0_P2P2_DP<15>")
	)
	(arc
		(start 99.34575 -287.778698)
		(mid 99.548573 -287.578467)
		(end 99.627944 -287.304734)
		(width 0.0889)
		(layer "In11.Cu")
		(net "UPI_CPU1_CPU0_P2P2_DP<15>")
	)
	(arc
		(start 100.285296 -286.151066)
		(mid 100.487582 -285.952085)
		(end 100.567744 -285.679896)
		(width 0.0889)
		(layer "In11.Cu")
		(net "UPI_CPU1_CPU0_P2P2_DP<15>")
	)
	(arc
		(start 341.081614 -288.427414)
		(mid 340.879328 -288.626395)
		(end 340.799166 -288.898584)
		(width 0.0889)
		(layer "In11.Cu")
		(net "UPI_CPU1_CPU0_P2P2_DP<15>")
	)
	(arc
		(start 101.22535 -284.52318)
		(mid 101.428173 -284.322949)
		(end 101.507544 -284.049216)
		(width 0.0889)
		(layer "In11.Cu")
		(net "UPI_CPU1_CPU0_P2P2_DP<15>")
	)
	(arc
		(start 101.037898 -284.847538)
		(mid 101.085577 -284.664638)
		(end 101.21646 -284.52826)
		(width 0.0889)
		(layer "In11.Cu")
		(net "UPI_CPU1_CPU0_P2P2_DP<15>")
	)
	(arc
		(start 100.761292 -285.33344)
		(mid 100.963879 -285.127089)
		(end 101.037898 -284.847538)
		(width 0.0889)
		(layer "In11.Cu")
		(net "UPI_CPU1_CPU0_P2P2_DP<15>")
	)
	(arc
		(start 98.87585 -288.592768)
		(mid 99.078136 -288.393787)
		(end 99.158298 -288.121598)
		(width 0.0889)
		(layer "In11.Cu")
		(net "UPI_CPU1_CPU0_P2P2_DP<15>")
	)
	(arc
		(start 342.015318 -285.175452)
		(mid 341.738631 -285.664946)
		(end 342.021414 -286.151066)
		(width 0.0889)
		(layer "In11.Cu")
		(net "UPI_CPU1_CPU0_P2P2_DP<15>")
	)
	(arc
		(start 344.558112 -280.78684)
		(mid 344.505842 -280.969205)
		(end 344.370914 -281.102562)
		(width 0.0889)
		(layer "In11.Cu")
		(net "UPI_CPU1_CPU0_P2P2_DP<15>")
	)
	(arc
		(start 342.208612 -286.48406)
		(mid 342.156342 -286.666425)
		(end 342.021414 -286.799782)
		(width 0.0889)
		(layer "In11.Cu")
		(net "UPI_CPU1_CPU0_P2P2_DP<15>")
	)
	(arc
		(start 344.768932 -280.33726)
		(mid 344.616445 -280.527356)
		(end 344.558112 -280.76398)
		(width 0.0889)
		(layer "In11.Cu")
		(net "UPI_CPU1_CPU0_P2P2_DP<15>")
	)
	(arc
		(start 341.084662 -289.446462)
		(mid 341.193809 -289.53039)
		(end 341.268812 -289.645852)
		(width 0.0889)
		(layer "In11.Cu")
		(net "UPI_CPU1_CPU0_P2P2_DP<15>")
	)
	(segment
		(start 101.412294 -281.591766)
		(end 101.412548 -281.59202)
		(width 0.13208)
		(layer "F.Cu")
		(net "UPI_CPU1_CPU0_P2P2_DP<14>")
	)
	(segment
		(start 101.412294 -281.05608)
		(end 101.412294 -281.591766)
		(width 0.13208)
		(layer "F.Cu")
		(net "UPI_CPU1_CPU0_P2P2_DP<14>")
	)
	(segment
		(start 344.183716 -282.405582)
		(end 344.183462 -282.405836)
		(width 0.13208)
		(layer "F.Cu")
		(net "UPI_CPU1_CPU0_P2P2_DP<14>")
	)
	(segment
		(start 344.183716 -281.869896)
		(end 344.183716 -282.405582)
		(width 0.13208)
		(layer "F.Cu")
		(net "UPI_CPU1_CPU0_P2P2_DP<14>")
	)
	(segment
		(start 264.10158 -367.827306)
		(end 264.362438 -367.566448)
		(width 0.14732)
		(layer "In11.Cu")
		(net "UPI_CPU1_CPU0_P2P2_DP<14>")
	)
	(segment
		(start 174.107856 -378.605796)
		(end 174.912782 -378.465588)
		(width 0.14732)
		(layer "In11.Cu")
		(net "UPI_CPU1_CPU0_P2P2_DP<14>")
	)
	(segment
		(start 96.808798 -288.917126)
		(end 96.808798 -289.078416)
		(width 0.0889)
		(layer "In11.Cu")
		(net "UPI_CPU1_CPU0_P2P2_DP<14>")
	)
	(segment
		(start 341.73922 -289.113976)
		(end 341.738966 -289.113722)
		(width 0.0889)
		(layer "In11.Cu")
		(net "UPI_CPU1_CPU0_P2P2_DP<14>")
	)
	(segment
		(start 177.787808 -378.817378)
		(end 178.369722 -378.715778)
		(width 0.14732)
		(layer "In11.Cu")
		(net "UPI_CPU1_CPU0_P2P2_DP<14>")
	)
	(segment
		(start 336.467704 -295.383458)
		(end 338.830158 -294.40505)
		(width 0.14732)
		(layer "In11.Cu")
		(net "UPI_CPU1_CPU0_P2P2_DP<14>")
	)
	(segment
		(start 196.63537 -375.535698)
		(end 196.755258 -375.365518)
		(width 0.14732)
		(layer "In11.Cu")
		(net "UPI_CPU1_CPU0_P2P2_DP<14>")
	)
	(segment
		(start 187.502546 -377.125738)
		(end 187.622434 -376.955558)
		(width 0.14732)
		(layer "In11.Cu")
		(net "UPI_CPU1_CPU0_P2P2_DP<14>")
	)
	(segment
		(start 264.10158 -368.03203)
		(end 264.10158 -367.827306)
		(width 0.14732)
		(layer "In11.Cu")
		(net "UPI_CPU1_CPU0_P2P2_DP<14>")
	)
	(segment
		(start 98.875596 -285.336996)
		(end 98.874072 -285.337758)
		(width 0.0889)
		(layer "In11.Cu")
		(net "UPI_CPU1_CPU0_P2P2_DP<14>")
	)
	(segment
		(start 180.966618 -377.400312)
		(end 181.749446 -377.263914)
		(width 0.14732)
		(layer "In11.Cu")
		(net "UPI_CPU1_CPU0_P2P2_DP<14>")
	)
	(segment
		(start 212.603842 -376.210322)
		(end 260.129528 -372.004082)
		(width 0.14732)
		(layer "In11.Cu")
		(net "UPI_CPU1_CPU0_P2P2_DP<14>")
	)
	(segment
		(start 343.43086 -284.35808)
		(end 343.43975 -284.353)
		(width 0.0889)
		(layer "In11.Cu")
		(net "UPI_CPU1_CPU0_P2P2_DP<14>")
	)
	(segment
		(start 312.189622 -323.339206)
		(end 312.490866 -323.12737)
		(width 0.14732)
		(layer "In11.Cu")
		(net "UPI_CPU1_CPU0_P2P2_DP<14>")
	)
	(segment
		(start 192.373504 -375.425716)
		(end 193.17843 -375.285508)
		(width 0.14732)
		(layer "In11.Cu")
		(net "UPI_CPU1_CPU0_P2P2_DP<14>")
	)
	(segment
		(start 184.637426 -377.624848)
		(end 185.21934 -377.523248)
		(width 0.14732)
		(layer "In11.Cu")
		(net "UPI_CPU1_CPU0_P2P2_DP<14>")
	)
	(segment
		(start 100.746306 -282.725114)
		(end 100.754434 -282.729686)
		(width 0.0889)
		(layer "In11.Cu")
		(net "UPI_CPU1_CPU0_P2P2_DP<14>")
	)
	(segment
		(start 312.692796 -323.162422)
		(end 312.999628 -322.946522)
		(width 0.14732)
		(layer "In11.Cu")
		(net "UPI_CPU1_CPU0_P2P2_DP<14>")
	)
	(segment
		(start 182.936134 -377.920758)
		(end 183.056022 -377.750578)
		(width 0.14732)
		(layer "In11.Cu")
		(net "UPI_CPU1_CPU0_P2P2_DP<14>")
	)
	(segment
		(start 97.377504 -291.155374)
		(end 97.278444 -291.254434)
		(width 0.0889)
		(layer "In11.Cu")
		(net "UPI_CPU1_CPU0_P2P2_DP<14>")
	)
	(segment
		(start 340.88324 -291.49167)
		(end 341.072216 -291.302694)
		(width 0.14732)
		(layer "In11.Cu")
		(net "UPI_CPU1_CPU0_P2P2_DP<14>")
	)
	(segment
		(start 339.751416 -293.483792)
		(end 339.751416 -293.279068)
		(width 0.14732)
		(layer "In11.Cu")
		(net "UPI_CPU1_CPU0_P2P2_DP<14>")
	)
	(segment
		(start 70.503796 -358.971088)
		(end 72.6313 -364.101634)
		(width 0.14732)
		(layer "In11.Cu")
		(net "UPI_CPU1_CPU0_P2P2_DP<14>")
	)
	(segment
		(start 344.088212 -283.219906)
		(end 344.088212 -283.205682)
		(width 0.0889)
		(layer "In11.Cu")
		(net "UPI_CPU1_CPU0_P2P2_DP<14>")
	)
	(segment
		(start 173.051724 -379.492764)
		(end 173.221396 -379.612398)
		(width 0.14732)
		(layer "In11.Cu")
		(net "UPI_CPU1_CPU0_P2P2_DP<14>")
	)
	(segment
		(start 263.375902 -368.757708)
		(end 263.375902 -368.552984)
		(width 0.14732)
		(layer "In11.Cu")
		(net "UPI_CPU1_CPU0_P2P2_DP<14>")
	)
	(segment
		(start 96.99625 -288.592768)
		(end 96.98736 -288.597848)
		(width 0.0889)
		(layer "In11.Cu")
		(net "UPI_CPU1_CPU0_P2P2_DP<14>")
	)
	(segment
		(start 161.71164 -380.76251)
		(end 172.629576 -378.863098)
		(width 0.14732)
		(layer "In11.Cu")
		(net "UPI_CPU1_CPU0_P2P2_DP<14>")
	)
	(segment
		(start 193.77025 -376.034808)
		(end 194.352164 -375.933208)
		(width 0.14732)
		(layer "In11.Cu")
		(net "UPI_CPU1_CPU0_P2P2_DP<14>")
	)
	(segment
		(start 180.772816 -378.148088)
		(end 180.706776 -377.769374)
		(width 0.14732)
		(layer "In11.Cu")
		(net "UPI_CPU1_CPU0_P2P2_DP<14>")
	)
	(segment
		(start 98.218498 -286.466788)
		(end 98.218498 -286.475424)
		(width 0.0889)
		(layer "In11.Cu")
		(net "UPI_CPU1_CPU0_P2P2_DP<14>")
	)
	(segment
		(start 97.278444 -291.432234)
		(end 97.320608 -291.474398)
		(width 0.0889)
		(layer "In11.Cu")
		(net "UPI_CPU1_CPU0_P2P2_DP<14>")
	)
	(segment
		(start 173.221396 -379.612398)
		(end 173.80331 -379.510798)
		(width 0.14732)
		(layer "In11.Cu")
		(net "UPI_CPU1_CPU0_P2P2_DP<14>")
	)
	(segment
		(start 343.618312 -284.033722)
		(end 343.618312 -284.023816)
		(width 0.0889)
		(layer "In11.Cu")
		(net "UPI_CPU1_CPU0_P2P2_DP<14>")
	)
	(segment
		(start 312.154316 -323.541136)
		(end 312.189622 -323.339206)
		(width 0.14732)
		(layer "In11.Cu")
		(net "UPI_CPU1_CPU0_P2P2_DP<14>")
	)
	(segment
		(start 338.830158 -294.40505)
		(end 339.751416 -293.483792)
		(width 0.14732)
		(layer "In11.Cu")
		(net "UPI_CPU1_CPU0_P2P2_DP<14>")
	)
	(segment
		(start 341.300054 -291.133784)
		(end 341.300054 -290.92144)
		(width 0.0889)
		(layer "In11.Cu")
		(net "UPI_CPU1_CPU0_P2P2_DP<14>")
	)
	(segment
		(start 100.767388 -283.702252)
		(end 100.755196 -283.709364)
		(width 0.0889)
		(layer "In11.Cu")
		(net "UPI_CPU1_CPU0_P2P2_DP<14>")
	)
	(segment
		(start 182.184548 -377.902724)
		(end 182.35422 -378.022358)
		(width 0.14732)
		(layer "In11.Cu")
		(net "UPI_CPU1_CPU0_P2P2_DP<14>")
	)
	(segment
		(start 194.65671 -375.028206)
		(end 195.461636 -374.887998)
		(width 0.14732)
		(layer "In11.Cu")
		(net "UPI_CPU1_CPU0_P2P2_DP<14>")
	)
	(segment
		(start 72.6313 -364.101634)
		(end 76.264262 -367.734596)
		(width 0.14732)
		(layer "In11.Cu")
		(net "UPI_CPU1_CPU0_P2P2_DP<14>")
	)
	(segment
		(start 193.17843 -375.285508)
		(end 193.534538 -375.536206)
		(width 0.14732)
		(layer "In11.Cu")
		(net "UPI_CPU1_CPU0_P2P2_DP<14>")
	)
	(segment
		(start 178.674268 -377.810776)
		(end 179.479194 -377.670568)
		(width 0.14732)
		(layer "In11.Cu")
		(net "UPI_CPU1_CPU0_P2P2_DP<14>")
	)
	(segment
		(start 196.688964 -374.986296)
		(end 196.94017 -374.630696)
		(width 0.14732)
		(layer "In11.Cu")
		(net "UPI_CPU1_CPU0_P2P2_DP<14>")
	)
	(segment
		(start 97.278444 -290.700714)
		(end 97.278444 -290.878514)
		(width 0.0889)
		(layer "In11.Cu")
		(net "UPI_CPU1_CPU0_P2P2_DP<14>")
	)
	(segment
		(start 342.678512 -287.28924)
		(end 342.678512 -287.279334)
		(width 0.0889)
		(layer "In11.Cu")
		(net "UPI_CPU1_CPU0_P2P2_DP<14>")
	)
	(segment
		(start 180.652928 -378.318268)
		(end 180.772816 -378.148088)
		(width 0.14732)
		(layer "In11.Cu")
		(net "UPI_CPU1_CPU0_P2P2_DP<14>")
	)
	(segment
		(start 184.401714 -377.126246)
		(end 184.467754 -377.505214)
		(width 0.14732)
		(layer "In11.Cu")
		(net "UPI_CPU1_CPU0_P2P2_DP<14>")
	)
	(segment
		(start 265.55319 -366.375696)
		(end 265.813794 -366.115092)
		(width 0.14732)
		(layer "In11.Cu")
		(net "UPI_CPU1_CPU0_P2P2_DP<14>")
	)
	(segment
		(start 101.256084 -281.321002)
		(end 101.177852 -281.300174)
		(width 0.0889)
		(layer "In11.Cu")
		(net "UPI_CPU1_CPU0_P2P2_DP<14>")
	)
	(segment
		(start 125.896116 -380.76251)
		(end 161.71164 -380.76251)
		(width 0.14732)
		(layer "In11.Cu")
		(net "UPI_CPU1_CPU0_P2P2_DP<14>")
	)
	(segment
		(start 191.487044 -376.432318)
		(end 192.068958 -376.330718)
		(width 0.14732)
		(layer "In11.Cu")
		(net "UPI_CPU1_CPU0_P2P2_DP<14>")
	)
	(segment
		(start 97.574354 -376.56135)
		(end 125.896116 -380.76251)
		(width 0.14732)
		(layer "In11.Cu")
		(net "UPI_CPU1_CPU0_P2P2_DP<14>")
	)
	(segment
		(start 182.118508 -377.523756)
		(end 182.184548 -377.902724)
		(width 0.14732)
		(layer "In11.Cu")
		(net "UPI_CPU1_CPU0_P2P2_DP<14>")
	)
	(segment
		(start 174.912782 -378.465588)
		(end 175.26889 -378.716286)
		(width 0.14732)
		(layer "In11.Cu")
		(net "UPI_CPU1_CPU0_P2P2_DP<14>")
	)
	(segment
		(start 98.688144 -285.661354)
		(end 98.688144 -285.679896)
		(width 0.0889)
		(layer "In11.Cu")
		(net "UPI_CPU1_CPU0_P2P2_DP<14>")
	)
	(segment
		(start 195.883784 -375.517664)
		(end 196.053456 -375.637298)
		(width 0.14732)
		(layer "In11.Cu")
		(net "UPI_CPU1_CPU0_P2P2_DP<14>")
	)
	(segment
		(start 339.751416 -293.279068)
		(end 340.01202 -293.018464)
		(width 0.14732)
		(layer "In11.Cu")
		(net "UPI_CPU1_CPU0_P2P2_DP<14>")
	)
	(segment
		(start 173.923198 -379.340618)
		(end 173.857158 -378.961904)
		(width 0.14732)
		(layer "In11.Cu")
		(net "UPI_CPU1_CPU0_P2P2_DP<14>")
	)
	(segment
		(start 178.42357 -378.166884)
		(end 178.674268 -377.810776)
		(width 0.14732)
		(layer "In11.Cu")
		(net "UPI_CPU1_CPU0_P2P2_DP<14>")
	)
	(segment
		(start 176.391062 -378.208286)
		(end 177.195988 -378.068078)
		(width 0.14732)
		(layer "In11.Cu")
		(net "UPI_CPU1_CPU0_P2P2_DP<14>")
	)
	(segment
		(start 264.362438 -367.566448)
		(end 264.567162 -367.566448)
		(width 0.14732)
		(layer "In11.Cu")
		(net "UPI_CPU1_CPU0_P2P2_DP<14>")
	)
	(segment
		(start 97.377504 -290.423854)
		(end 97.377504 -290.601654)
		(width 0.0889)
		(layer "In11.Cu")
		(net "UPI_CPU1_CPU0_P2P2_DP<14>")
	)
	(segment
		(start 340.216744 -293.018464)
		(end 340.796626 -292.438582)
		(width 0.14732)
		(layer "In11.Cu")
		(net "UPI_CPU1_CPU0_P2P2_DP<14>")
	)
	(segment
		(start 177.552096 -378.318776)
		(end 177.618136 -378.697744)
		(width 0.14732)
		(layer "In11.Cu")
		(net "UPI_CPU1_CPU0_P2P2_DP<14>")
	)
	(segment
		(start 187.807092 -376.220736)
		(end 188.612018 -376.080528)
		(width 0.14732)
		(layer "In11.Cu")
		(net "UPI_CPU1_CPU0_P2P2_DP<14>")
	)
	(segment
		(start 335.855056 -296.300906)
		(end 336.467704 -295.383458)
		(width 0.14732)
		(layer "In11.Cu")
		(net "UPI_CPU1_CPU0_P2P2_DP<14>")
	)
	(segment
		(start 265.813794 -366.115092)
		(end 266.018518 -366.115092)
		(width 0.14732)
		(layer "In11.Cu")
		(net "UPI_CPU1_CPU0_P2P2_DP<14>")
	)
	(segment
		(start 308.17693 -325.869808)
		(end 310.36387 -324.338188)
		(width 0.14732)
		(layer "In11.Cu")
		(net "UPI_CPU1_CPU0_P2P2_DP<14>")
	)
	(segment
		(start 312.490866 -323.12737)
		(end 312.692796 -323.162422)
		(width 0.14732)
		(layer "In11.Cu")
		(net "UPI_CPU1_CPU0_P2P2_DP<14>")
	)
	(segment
		(start 97.748344 -287.28924)
		(end 97.748344 -287.304734)
		(width 0.0889)
		(layer "In11.Cu")
		(net "UPI_CPU1_CPU0_P2P2_DP<14>")
	)
	(segment
		(start 196.755258 -375.365518)
		(end 196.688964 -374.986296)
		(width 0.14732)
		(layer "In11.Cu")
		(net "UPI_CPU1_CPU0_P2P2_DP<14>")
	)
	(segment
		(start 194.472052 -375.763028)
		(end 194.406012 -375.384314)
		(width 0.14732)
		(layer "In11.Cu")
		(net "UPI_CPU1_CPU0_P2P2_DP<14>")
	)
	(segment
		(start 263.84123 -368.29238)
		(end 264.10158 -368.03203)
		(width 0.14732)
		(layer "In11.Cu")
		(net "UPI_CPU1_CPU0_P2P2_DP<14>")
	)
	(segment
		(start 334.053942 -302.234346)
		(end 335.855056 -296.300906)
		(width 0.14732)
		(layer "In11.Cu")
		(net "UPI_CPU1_CPU0_P2P2_DP<14>")
	)
	(segment
		(start 342.955118 -285.175452)
		(end 342.970104 -285.166816)
		(width 0.0889)
		(layer "In11.Cu")
		(net "UPI_CPU1_CPU0_P2P2_DP<14>")
	)
	(segment
		(start 186.75096 -377.107704)
		(end 186.920632 -377.227338)
		(width 0.14732)
		(layer "In11.Cu")
		(net "UPI_CPU1_CPU0_P2P2_DP<14>")
	)
	(segment
		(start 176.086516 -379.113288)
		(end 176.206404 -378.943108)
		(width 0.14732)
		(layer "In11.Cu")
		(net "UPI_CPU1_CPU0_P2P2_DP<14>")
	)
	(segment
		(start 97.278444 -290.878514)
		(end 97.377504 -290.977574)
		(width 0.0889)
		(layer "In11.Cu")
		(net "UPI_CPU1_CPU0_P2P2_DP<14>")
	)
	(segment
		(start 97.278444 -290.324794)
		(end 97.377504 -290.423854)
		(width 0.0889)
		(layer "In11.Cu")
		(net "UPI_CPU1_CPU0_P2P2_DP<14>")
	)
	(segment
		(start 97.278444 -291.254434)
		(end 97.278444 -291.432234)
		(width 0.0889)
		(layer "In11.Cu")
		(net "UPI_CPU1_CPU0_P2P2_DP<14>")
	)
	(segment
		(start 194.406012 -375.384314)
		(end 194.65671 -375.028206)
		(width 0.14732)
		(layer "In11.Cu")
		(net "UPI_CPU1_CPU0_P2P2_DP<14>")
	)
	(segment
		(start 191.251332 -375.933716)
		(end 191.317372 -376.312684)
		(width 0.14732)
		(layer "In11.Cu")
		(net "UPI_CPU1_CPU0_P2P2_DP<14>")
	)
	(segment
		(start 175.504602 -379.214888)
		(end 176.086516 -379.113288)
		(width 0.14732)
		(layer "In11.Cu")
		(net "UPI_CPU1_CPU0_P2P2_DP<14>")
	)
	(segment
		(start 342.961722 -286.799274)
		(end 342.964262 -286.79775)
		(width 0.0889)
		(layer "In11.Cu")
		(net "UPI_CPU1_CPU0_P2P2_DP<14>")
	)
	(segment
		(start 179.901342 -378.300234)
		(end 180.071014 -378.419868)
		(width 0.14732)
		(layer "In11.Cu")
		(net "UPI_CPU1_CPU0_P2P2_DP<14>")
	)
	(segment
		(start 340.88324 -292.229794)
		(end 340.88324 -291.49167)
		(width 0.14732)
		(layer "In11.Cu")
		(net "UPI_CPU1_CPU0_P2P2_DP<14>")
	)
	(segment
		(start 184.045606 -376.875548)
		(end 184.401714 -377.126246)
		(width 0.14732)
		(layer "In11.Cu")
		(net "UPI_CPU1_CPU0_P2P2_DP<14>")
	)
	(segment
		(start 314.03036 -322.257674)
		(end 334.053942 -302.234346)
		(width 0.14732)
		(layer "In11.Cu")
		(net "UPI_CPU1_CPU0_P2P2_DP<14>")
	)
	(segment
		(start 173.80331 -379.510798)
		(end 173.923198 -379.340618)
		(width 0.14732)
		(layer "In11.Cu")
		(net "UPI_CPU1_CPU0_P2P2_DP<14>")
	)
	(segment
		(start 305.002946 -330.99375)
		(end 305.997356 -329.99934)
		(width 0.14732)
		(layer "In11.Cu")
		(net "UPI_CPU1_CPU0_P2P2_DP<14>")
	)
	(segment
		(start 100.748338 -282.085288)
		(end 100.746306 -282.086558)
		(width 0.0889)
		(layer "In11.Cu")
		(net "UPI_CPU1_CPU0_P2P2_DP<14>")
	)
	(segment
		(start 100.755196 -283.709364)
		(end 100.746306 -283.714444)
		(width 0.0889)
		(layer "In11.Cu")
		(net "UPI_CPU1_CPU0_P2P2_DP<14>")
	)
	(segment
		(start 343.90076 -283.544264)
		(end 343.901522 -283.543756)
		(width 0.0889)
		(layer "In11.Cu")
		(net "UPI_CPU1_CPU0_P2P2_DP<14>")
	)
	(segment
		(start 79.515208 -314.34532)
		(end 71.124064 -322.736464)
		(width 0.14732)
		(layer "In11.Cu")
		(net "UPI_CPU1_CPU0_P2P2_DP<14>")
	)
	(segment
		(start 189.785752 -376.728228)
		(end 189.90564 -376.558048)
		(width 0.14732)
		(layer "In11.Cu")
		(net "UPI_CPU1_CPU0_P2P2_DP<14>")
	)
	(segment
		(start 312.999628 -322.946522)
		(end 314.03036 -322.257674)
		(width 0.14732)
		(layer "In11.Cu")
		(net "UPI_CPU1_CPU0_P2P2_DP<14>")
	)
	(segment
		(start 341.08771 -291.2872)
		(end 341.146638 -291.2872)
		(width 0.0889)
		(layer "In11.Cu")
		(net "UPI_CPU1_CPU0_P2P2_DP<14>")
	)
	(segment
		(start 192.188846 -376.160538)
		(end 192.122806 -375.781824)
		(width 0.14732)
		(layer "In11.Cu")
		(net "UPI_CPU1_CPU0_P2P2_DP<14>")
	)
	(segment
		(start 100.567744 -284.033722)
		(end 100.567744 -284.049216)
		(width 0.0889)
		(layer "In11.Cu")
		(net "UPI_CPU1_CPU0_P2P2_DP<14>")
	)
	(segment
		(start 344.339926 -282.676854)
		(end 344.183462 -282.405836)
		(width 0.0889)
		(layer "In11.Cu")
		(net "UPI_CPU1_CPU0_P2P2_DP<14>")
	)
	(segment
		(start 311.301384 -324.141338)
		(end 312.154316 -323.541136)
		(width 0.14732)
		(layer "In11.Cu")
		(net "UPI_CPU1_CPU0_P2P2_DP<14>")
	)
	(segment
		(start 101.037898 -283.212286)
		(end 101.037898 -283.219906)
		(width 0.0889)
		(layer "In11.Cu")
		(net "UPI_CPU1_CPU0_P2P2_DP<14>")
	)
	(segment
		(start 100.755196 -282.081478)
		(end 100.748338 -282.085288)
		(width 0.0889)
		(layer "In11.Cu")
		(net "UPI_CPU1_CPU0_P2P2_DP<14>")
	)
	(segment
		(start 188.612018 -376.080528)
		(end 188.968126 -376.331226)
		(width 0.14732)
		(layer "In11.Cu")
		(net "UPI_CPU1_CPU0_P2P2_DP<14>")
	)
	(segment
		(start 190.895224 -375.683018)
		(end 191.251332 -375.933716)
		(width 0.14732)
		(layer "In11.Cu")
		(net "UPI_CPU1_CPU0_P2P2_DP<14>")
	)
	(segment
		(start 340.796626 -292.438582)
		(end 340.88324 -292.229794)
		(width 0.14732)
		(layer "In11.Cu")
		(net "UPI_CPU1_CPU0_P2P2_DP<14>")
	)
	(segment
		(start 188.968126 -376.331226)
		(end 189.034166 -376.710194)
		(width 0.14732)
		(layer "In11.Cu")
		(net "UPI_CPU1_CPU0_P2P2_DP<14>")
	)
	(segment
		(start 181.749446 -377.263914)
		(end 182.118508 -377.523756)
		(width 0.14732)
		(layer "In11.Cu")
		(net "UPI_CPU1_CPU0_P2P2_DP<14>")
	)
	(segment
		(start 100.755958 -282.08097)
		(end 100.755196 -282.081478)
		(width 0.0889)
		(layer "In11.Cu")
		(net "UPI_CPU1_CPU0_P2P2_DP<14>")
	)
	(segment
		(start 97.278444 -289.60953)
		(end 97.278444 -290.324794)
		(width 0.0889)
		(layer "In11.Cu")
		(net "UPI_CPU1_CPU0_P2P2_DP<14>")
	)
	(segment
		(start 97.935796 -286.964882)
		(end 97.934272 -286.965644)
		(width 0.0889)
		(layer "In11.Cu")
		(net "UPI_CPU1_CPU0_P2P2_DP<14>")
	)
	(segment
		(start 190.090298 -375.823226)
		(end 190.895224 -375.683018)
		(width 0.14732)
		(layer "In11.Cu")
		(net "UPI_CPU1_CPU0_P2P2_DP<14>")
	)
	(segment
		(start 205.631288 -375.1326)
		(end 212.603842 -376.210322)
		(width 0.14732)
		(layer "In11.Cu")
		(net "UPI_CPU1_CPU0_P2P2_DP<14>")
	)
	(segment
		(start 97.941892 -286.961326)
		(end 97.942146 -286.961072)
		(width 0.0889)
		(layer "In11.Cu")
		(net "UPI_CPU1_CPU0_P2P2_DP<14>")
	)
	(segment
		(start 193.534538 -375.536206)
		(end 193.600578 -375.915174)
		(width 0.14732)
		(layer "In11.Cu")
		(net "UPI_CPU1_CPU0_P2P2_DP<14>")
	)
	(segment
		(start 264.827512 -367.101374)
		(end 265.088116 -366.84077)
		(width 0.14732)
		(layer "In11.Cu")
		(net "UPI_CPU1_CPU0_P2P2_DP<14>")
	)
	(segment
		(start 97.934272 -286.965644)
		(end 97.926906 -286.969962)
		(width 0.0889)
		(layer "In11.Cu")
		(net "UPI_CPU1_CPU0_P2P2_DP<14>")
	)
	(segment
		(start 189.90564 -376.558048)
		(end 189.8396 -376.179334)
		(width 0.14732)
		(layer "In11.Cu")
		(net "UPI_CPU1_CPU0_P2P2_DP<14>")
	)
	(segment
		(start 342.96985 -286.156146)
		(end 342.96096 -286.151066)
		(width 0.0889)
		(layer "In11.Cu")
		(net "UPI_CPU1_CPU0_P2P2_DP<14>")
	)
	(segment
		(start 186.920632 -377.227338)
		(end 187.502546 -377.125738)
		(width 0.14732)
		(layer "In11.Cu")
		(net "UPI_CPU1_CPU0_P2P2_DP<14>")
	)
	(segment
		(start 205.631288 -375.132854)
		(end 205.631288 -375.1326)
		(width 0.14732)
		(layer "In11.Cu")
		(net "UPI_CPU1_CPU0_P2P2_DP<14>")
	)
	(segment
		(start 185.273188 -376.974354)
		(end 185.523886 -376.618246)
		(width 0.14732)
		(layer "In11.Cu")
		(net "UPI_CPU1_CPU0_P2P2_DP<14>")
	)
	(segment
		(start 260.129528 -372.004082)
		(end 263.375902 -368.757708)
		(width 0.14732)
		(layer "In11.Cu")
		(net "UPI_CPU1_CPU0_P2P2_DP<14>")
	)
	(segment
		(start 176.206404 -378.943108)
		(end 176.140364 -378.564394)
		(width 0.14732)
		(layer "In11.Cu")
		(net "UPI_CPU1_CPU0_P2P2_DP<14>")
	)
	(segment
		(start 175.33493 -379.095254)
		(end 175.504602 -379.214888)
		(width 0.14732)
		(layer "In11.Cu")
		(net "UPI_CPU1_CPU0_P2P2_DP<14>")
	)
	(segment
		(start 305.997356 -329.99934)
		(end 307.239924 -328.224896)
		(width 0.14732)
		(layer "In11.Cu")
		(net "UPI_CPU1_CPU0_P2P2_DP<14>")
	)
	(segment
		(start 343.148666 -284.847538)
		(end 343.148666 -284.832044)
		(width 0.0889)
		(layer "In11.Cu")
		(net "UPI_CPU1_CPU0_P2P2_DP<14>")
	)
	(segment
		(start 264.827512 -367.306098)
		(end 264.827512 -367.101374)
		(width 0.14732)
		(layer "In11.Cu")
		(net "UPI_CPU1_CPU0_P2P2_DP<14>")
	)
	(segment
		(start 99.821492 -285.33344)
		(end 99.800664 -285.345632)
		(width 0.0889)
		(layer "In11.Cu")
		(net "UPI_CPU1_CPU0_P2P2_DP<14>")
	)
	(segment
		(start 266.018518 -366.115092)
		(end 266.98702 -365.14659)
		(width 0.14732)
		(layer "In11.Cu")
		(net "UPI_CPU1_CPU0_P2P2_DP<14>")
	)
	(segment
		(start 307.4797 -326.865742)
		(end 308.17693 -325.869808)
		(width 0.14732)
		(layer "In11.Cu")
		(net "UPI_CPU1_CPU0_P2P2_DP<14>")
	)
	(segment
		(start 97.942146 -286.961072)
		(end 97.935796 -286.964882)
		(width 0.0889)
		(layer "In11.Cu")
		(net "UPI_CPU1_CPU0_P2P2_DP<14>")
	)
	(segment
		(start 70.503796 -358.970834)
		(end 70.503796 -358.971088)
		(width 0.14732)
		(layer "In11.Cu")
		(net "UPI_CPU1_CPU0_P2P2_DP<14>")
	)
	(segment
		(start 284.979872 -330.99375)
		(end 305.002946 -330.99375)
		(width 0.14732)
		(layer "In11.Cu")
		(net "UPI_CPU1_CPU0_P2P2_DP<14>")
	)
	(segment
		(start 97.377504 -290.601654)
		(end 97.278444 -290.700714)
		(width 0.0889)
		(layer "In11.Cu")
		(net "UPI_CPU1_CPU0_P2P2_DP<14>")
	)
	(segment
		(start 340.01202 -293.018464)
		(end 340.216744 -293.018464)
		(width 0.14732)
		(layer "In11.Cu")
		(net "UPI_CPU1_CPU0_P2P2_DP<14>")
	)
	(segment
		(start 264.567162 -367.566448)
		(end 264.827512 -367.306098)
		(width 0.14732)
		(layer "In11.Cu")
		(net "UPI_CPU1_CPU0_P2P2_DP<14>")
	)
	(segment
		(start 180.071014 -378.419868)
		(end 180.652928 -378.318268)
		(width 0.14732)
		(layer "In11.Cu")
		(net "UPI_CPU1_CPU0_P2P2_DP<14>")
	)
	(segment
		(start 344.315796 -282.766008)
		(end 344.339926 -282.676854)
		(width 0.0889)
		(layer "In11.Cu")
		(net "UPI_CPU1_CPU0_P2P2_DP<14>")
	)
	(segment
		(start 341.738966 -289.113722)
		(end 341.738966 -288.898584)
		(width 0.0889)
		(layer "In11.Cu")
		(net "UPI_CPU1_CPU0_P2P2_DP<14>")
	)
	(segment
		(start 341.300054 -290.92144)
		(end 342.208866 -290.012628)
		(width 0.0889)
		(layer "In11.Cu")
		(net "UPI_CPU1_CPU0_P2P2_DP<14>")
	)
	(segment
		(start 342.021414 -288.427414)
		(end 342.030304 -288.422334)
		(width 0.0889)
		(layer "In11.Cu")
		(net "UPI_CPU1_CPU0_P2P2_DP<14>")
	)
	(segment
		(start 183.24068 -377.015756)
		(end 184.045606 -376.875548)
		(width 0.14732)
		(layer "In11.Cu")
		(net "UPI_CPU1_CPU0_P2P2_DP<14>")
	)
	(segment
		(start 343.901522 -283.543756)
		(end 343.904062 -283.542232)
		(width 0.0889)
		(layer "In11.Cu")
		(net "UPI_CPU1_CPU0_P2P2_DP<14>")
	)
	(segment
		(start 186.328812 -376.478038)
		(end 186.68492 -376.728736)
		(width 0.14732)
		(layer "In11.Cu")
		(net "UPI_CPU1_CPU0_P2P2_DP<14>")
	)
	(segment
		(start 95.957898 -300.271942)
		(end 94.859602 -301.752508)
		(width 0.14732)
		(layer "In11.Cu")
		(net "UPI_CPU1_CPU0_P2P2_DP<14>")
	)
	(segment
		(start 185.339228 -377.353068)
		(end 185.273188 -376.974354)
		(width 0.14732)
		(layer "In11.Cu")
		(net "UPI_CPU1_CPU0_P2P2_DP<14>")
	)
	(segment
		(start 189.8396 -376.179334)
		(end 190.090298 -375.823226)
		(width 0.14732)
		(layer "In11.Cu")
		(net "UPI_CPU1_CPU0_P2P2_DP<14>")
	)
	(segment
		(start 189.203838 -376.829828)
		(end 189.785752 -376.728228)
		(width 0.14732)
		(layer "In11.Cu")
		(net "UPI_CPU1_CPU0_P2P2_DP<14>")
	)
	(segment
		(start 279.065228 -333.44358)
		(end 284.979872 -330.99375)
		(width 0.14732)
		(layer "In11.Cu")
		(net "UPI_CPU1_CPU0_P2P2_DP<14>")
	)
	(segment
		(start 195.461636 -374.887998)
		(end 195.817744 -375.138696)
		(width 0.14732)
		(layer "In11.Cu")
		(net "UPI_CPU1_CPU0_P2P2_DP<14>")
	)
	(segment
		(start 97.278698 -288.103056)
		(end 97.278698 -288.121598)
		(width 0.0889)
		(layer "In11.Cu")
		(net "UPI_CPU1_CPU0_P2P2_DP<14>")
	)
	(segment
		(start 71.124064 -322.736464)
		(end 69.81317 -325.508366)
		(width 0.14732)
		(layer "In11.Cu")
		(net "UPI_CPU1_CPU0_P2P2_DP<14>")
	)
	(segment
		(start 187.556394 -376.576844)
		(end 187.807092 -376.220736)
		(width 0.14732)
		(layer "In11.Cu")
		(net "UPI_CPU1_CPU0_P2P2_DP<14>")
	)
	(segment
		(start 76.264262 -367.734596)
		(end 97.574354 -376.56135)
		(width 0.14732)
		(layer "In11.Cu")
		(net "UPI_CPU1_CPU0_P2P2_DP<14>")
	)
	(segment
		(start 341.072216 -291.302694)
		(end 341.08771 -291.2872)
		(width 0.0889)
		(layer "In11.Cu")
		(net "UPI_CPU1_CPU0_P2P2_DP<14>")
	)
	(segment
		(start 343.904062 -283.542232)
		(end 343.90965 -283.539184)
		(width 0.0889)
		(layer "In11.Cu")
		(net "UPI_CPU1_CPU0_P2P2_DP<14>")
	)
	(segment
		(start 342.964262 -286.79775)
		(end 342.96985 -286.794702)
		(width 0.0889)
		(layer "In11.Cu")
		(net "UPI_CPU1_CPU0_P2P2_DP<14>")
	)
	(segment
		(start 97.320608 -291.496496)
		(end 97.320608 -296.980864)
		(width 0.14732)
		(layer "In11.Cu")
		(net "UPI_CPU1_CPU0_P2P2_DP<14>")
	)
	(segment
		(start 68.376038 -353.83978)
		(end 70.503796 -358.970834)
		(width 0.14732)
		(layer "In11.Cu")
		(net "UPI_CPU1_CPU0_P2P2_DP<14>")
	)
	(segment
		(start 192.068958 -376.330718)
		(end 192.188846 -376.160538)
		(width 0.14732)
		(layer "In11.Cu")
		(net "UPI_CPU1_CPU0_P2P2_DP<14>")
	)
	(segment
		(start 263.636506 -368.29238)
		(end 263.84123 -368.29238)
		(width 0.14732)
		(layer "In11.Cu")
		(net "UPI_CPU1_CPU0_P2P2_DP<14>")
	)
	(segment
		(start 311.236614 -324.184772)
		(end 311.301384 -324.141338)
		(width 0.14732)
		(layer "In11.Cu")
		(net "UPI_CPU1_CPU0_P2P2_DP<14>")
	)
	(segment
		(start 97.46615 -287.778698)
		(end 97.45726 -287.783778)
		(width 0.0889)
		(layer "In11.Cu")
		(net "UPI_CPU1_CPU0_P2P2_DP<14>")
	)
	(segment
		(start 94.859602 -301.752508)
		(end 79.515208 -314.34532)
		(width 0.14732)
		(layer "In11.Cu")
		(net "UPI_CPU1_CPU0_P2P2_DP<14>")
	)
	(segment
		(start 342.208866 -288.103056)
		(end 342.208866 -288.087562)
		(width 0.0889)
		(layer "In11.Cu")
		(net "UPI_CPU1_CPU0_P2P2_DP<14>")
	)
	(segment
		(start 178.48961 -378.545598)
		(end 178.42357 -378.166884)
		(width 0.14732)
		(layer "In11.Cu")
		(net "UPI_CPU1_CPU0_P2P2_DP<14>")
	)
	(segment
		(start 265.55319 -366.58042)
		(end 265.55319 -366.375696)
		(width 0.14732)
		(layer "In11.Cu")
		(net "UPI_CPU1_CPU0_P2P2_DP<14>")
	)
	(segment
		(start 100.754434 -282.729686)
		(end 100.755196 -282.730194)
		(width 0.0889)
		(layer "In11.Cu")
		(net "UPI_CPU1_CPU0_P2P2_DP<14>")
	)
	(segment
		(start 100.758752 -282.079446)
		(end 100.755958 -282.08097)
		(width 0.0889)
		(layer "In11.Cu")
		(net "UPI_CPU1_CPU0_P2P2_DP<14>")
	)
	(segment
		(start 172.985684 -379.113796)
		(end 173.051724 -379.492764)
		(width 0.14732)
		(layer "In11.Cu")
		(net "UPI_CPU1_CPU0_P2P2_DP<14>")
	)
	(segment
		(start 182.35422 -378.022358)
		(end 182.936134 -377.920758)
		(width 0.14732)
		(layer "In11.Cu")
		(net "UPI_CPU1_CPU0_P2P2_DP<14>")
	)
	(segment
		(start 341.146638 -291.2872)
		(end 341.300054 -291.133784)
		(width 0.0889)
		(layer "In11.Cu")
		(net "UPI_CPU1_CPU0_P2P2_DP<14>")
	)
	(segment
		(start 342.96096 -286.799782)
		(end 342.961722 -286.799274)
		(width 0.0889)
		(layer "In11.Cu")
		(net "UPI_CPU1_CPU0_P2P2_DP<14>")
	)
	(segment
		(start 69.81317 -325.508366)
		(end 69.01307 -328.399394)
		(width 0.14732)
		(layer "In11.Cu")
		(net "UPI_CPU1_CPU0_P2P2_DP<14>")
	)
	(segment
		(start 185.21934 -377.523248)
		(end 185.339228 -377.353068)
		(width 0.14732)
		(layer "In11.Cu")
		(net "UPI_CPU1_CPU0_P2P2_DP<14>")
	)
	(segment
		(start 310.36387 -324.338188)
		(end 311.236614 -324.184772)
		(width 0.14732)
		(layer "In11.Cu")
		(net "UPI_CPU1_CPU0_P2P2_DP<14>")
	)
	(segment
		(start 179.835302 -377.921266)
		(end 179.901342 -378.300234)
		(width 0.14732)
		(layer "In11.Cu")
		(net "UPI_CPU1_CPU0_P2P2_DP<14>")
	)
	(segment
		(start 266.98702 -345.521788)
		(end 279.065228 -333.44358)
		(width 0.14732)
		(layer "In11.Cu")
		(net "UPI_CPU1_CPU0_P2P2_DP<14>")
	)
	(segment
		(start 97.320608 -291.474398)
		(end 97.320608 -291.496496)
		(width 0.0889)
		(layer "In11.Cu")
		(net "UPI_CPU1_CPU0_P2P2_DP<14>")
	)
	(segment
		(start 186.68492 -376.728736)
		(end 186.75096 -377.107704)
		(width 0.14732)
		(layer "In11.Cu")
		(net "UPI_CPU1_CPU0_P2P2_DP<14>")
	)
	(segment
		(start 189.034166 -376.710194)
		(end 189.203838 -376.829828)
		(width 0.14732)
		(layer "In11.Cu")
		(net "UPI_CPU1_CPU0_P2P2_DP<14>")
	)
	(segment
		(start 176.140364 -378.564394)
		(end 176.391062 -378.208286)
		(width 0.14732)
		(layer "In11.Cu")
		(net "UPI_CPU1_CPU0_P2P2_DP<14>")
	)
	(segment
		(start 180.706776 -377.769374)
		(end 180.966618 -377.400312)
		(width 0.14732)
		(layer "In11.Cu")
		(net "UPI_CPU1_CPU0_P2P2_DP<14>")
	)
	(segment
		(start 342.49106 -287.613598)
		(end 342.49995 -287.608518)
		(width 0.0889)
		(layer "In11.Cu")
		(net "UPI_CPU1_CPU0_P2P2_DP<14>")
	)
	(segment
		(start 184.467754 -377.505214)
		(end 184.637426 -377.624848)
		(width 0.14732)
		(layer "In11.Cu")
		(net "UPI_CPU1_CPU0_P2P2_DP<14>")
	)
	(segment
		(start 183.056022 -377.750578)
		(end 182.989982 -377.371864)
		(width 0.14732)
		(layer "In11.Cu")
		(net "UPI_CPU1_CPU0_P2P2_DP<14>")
	)
	(segment
		(start 68.376038 -334.869028)
		(end 68.376038 -353.83978)
		(width 0.14732)
		(layer "In11.Cu")
		(net "UPI_CPU1_CPU0_P2P2_DP<14>")
	)
	(segment
		(start 98.874072 -285.337758)
		(end 98.866706 -285.342076)
		(width 0.0889)
		(layer "In11.Cu")
		(net "UPI_CPU1_CPU0_P2P2_DP<14>")
	)
	(segment
		(start 172.629576 -378.863098)
		(end 172.985684 -379.113796)
		(width 0.14732)
		(layer "In11.Cu")
		(net "UPI_CPU1_CPU0_P2P2_DP<14>")
	)
	(segment
		(start 97.377504 -290.977574)
		(end 97.377504 -291.155374)
		(width 0.0889)
		(layer "In11.Cu")
		(net "UPI_CPU1_CPU0_P2P2_DP<14>")
	)
	(segment
		(start 179.479194 -377.670568)
		(end 179.835302 -377.921266)
		(width 0.14732)
		(layer "In11.Cu")
		(net "UPI_CPU1_CPU0_P2P2_DP<14>")
	)
	(segment
		(start 101.412548 -281.59202)
		(end 101.256084 -281.321002)
		(width 0.0889)
		(layer "In11.Cu")
		(net "UPI_CPU1_CPU0_P2P2_DP<14>")
	)
	(segment
		(start 177.618136 -378.697744)
		(end 177.787808 -378.817378)
		(width 0.14732)
		(layer "In11.Cu")
		(net "UPI_CPU1_CPU0_P2P2_DP<14>")
	)
	(segment
		(start 191.317372 -376.312684)
		(end 191.487044 -376.432318)
		(width 0.14732)
		(layer "In11.Cu")
		(net "UPI_CPU1_CPU0_P2P2_DP<14>")
	)
	(segment
		(start 182.989982 -377.371864)
		(end 183.24068 -377.015756)
		(width 0.14732)
		(layer "In11.Cu")
		(net "UPI_CPU1_CPU0_P2P2_DP<14>")
	)
	(segment
		(start 193.600578 -375.915174)
		(end 193.77025 -376.034808)
		(width 0.14732)
		(layer "In11.Cu")
		(net "UPI_CPU1_CPU0_P2P2_DP<14>")
	)
	(segment
		(start 263.375902 -368.552984)
		(end 263.636506 -368.29238)
		(width 0.14732)
		(layer "In11.Cu")
		(net "UPI_CPU1_CPU0_P2P2_DP<14>")
	)
	(segment
		(start 187.622434 -376.955558)
		(end 187.556394 -376.576844)
		(width 0.14732)
		(layer "In11.Cu")
		(net "UPI_CPU1_CPU0_P2P2_DP<14>")
	)
	(segment
		(start 177.195988 -378.068078)
		(end 177.552096 -378.318776)
		(width 0.14732)
		(layer "In11.Cu")
		(net "UPI_CPU1_CPU0_P2P2_DP<14>")
	)
	(segment
		(start 175.26889 -378.716286)
		(end 175.33493 -379.095254)
		(width 0.14732)
		(layer "In11.Cu")
		(net "UPI_CPU1_CPU0_P2P2_DP<14>")
	)
	(segment
		(start 173.857158 -378.961904)
		(end 174.107856 -378.605796)
		(width 0.14732)
		(layer "In11.Cu")
		(net "UPI_CPU1_CPU0_P2P2_DP<14>")
	)
	(segment
		(start 192.122806 -375.781824)
		(end 192.373504 -375.425716)
		(width 0.14732)
		(layer "In11.Cu")
		(net "UPI_CPU1_CPU0_P2P2_DP<14>")
	)
	(segment
		(start 342.208866 -290.012628)
		(end 342.208866 -289.64509)
		(width 0.0889)
		(layer "In11.Cu")
		(net "UPI_CPU1_CPU0_P2P2_DP<14>")
	)
	(segment
		(start 178.369722 -378.715778)
		(end 178.48961 -378.545598)
		(width 0.14732)
		(layer "In11.Cu")
		(net "UPI_CPU1_CPU0_P2P2_DP<14>")
	)
	(segment
		(start 69.01307 -328.399394)
		(end 68.376038 -334.869028)
		(width 0.14732)
		(layer "In11.Cu")
		(net "UPI_CPU1_CPU0_P2P2_DP<14>")
	)
	(segment
		(start 266.98702 -365.14659)
		(end 266.98702 -345.521788)
		(width 0.14732)
		(layer "In11.Cu")
		(net "UPI_CPU1_CPU0_P2P2_DP<14>")
	)
	(segment
		(start 185.523886 -376.618246)
		(end 186.328812 -376.478038)
		(width 0.14732)
		(layer "In11.Cu")
		(net "UPI_CPU1_CPU0_P2P2_DP<14>")
	)
	(segment
		(start 196.94017 -374.630696)
		(end 199.511158 -374.186958)
		(width 0.14732)
		(layer "In11.Cu")
		(net "UPI_CPU1_CPU0_P2P2_DP<14>")
	)
	(segment
		(start 194.352164 -375.933208)
		(end 194.472052 -375.763028)
		(width 0.14732)
		(layer "In11.Cu")
		(net "UPI_CPU1_CPU0_P2P2_DP<14>")
	)
	(segment
		(start 100.761292 -282.077922)
		(end 100.758752 -282.079446)
		(width 0.0889)
		(layer "In11.Cu")
		(net "UPI_CPU1_CPU0_P2P2_DP<14>")
	)
	(segment
		(start 307.239924 -328.224896)
		(end 307.4797 -326.865742)
		(width 0.14732)
		(layer "In11.Cu")
		(net "UPI_CPU1_CPU0_P2P2_DP<14>")
	)
	(segment
		(start 100.28555 -284.52318)
		(end 100.27666 -284.52826)
		(width 0.0889)
		(layer "In11.Cu")
		(net "UPI_CPU1_CPU0_P2P2_DP<14>")
	)
	(segment
		(start 97.320608 -296.980864)
		(end 95.957898 -300.271942)
		(width 0.14732)
		(layer "In11.Cu")
		(net "UPI_CPU1_CPU0_P2P2_DP<14>")
	)
	(segment
		(start 195.817744 -375.138696)
		(end 195.883784 -375.517664)
		(width 0.14732)
		(layer "In11.Cu")
		(net "UPI_CPU1_CPU0_P2P2_DP<14>")
	)
	(segment
		(start 199.511158 -374.186958)
		(end 205.631288 -375.132854)
		(width 0.14732)
		(layer "In11.Cu")
		(net "UPI_CPU1_CPU0_P2P2_DP<14>")
	)
	(segment
		(start 265.088116 -366.84077)
		(end 265.29284 -366.84077)
		(width 0.14732)
		(layer "In11.Cu")
		(net "UPI_CPU1_CPU0_P2P2_DP<14>")
	)
	(segment
		(start 196.053456 -375.637298)
		(end 196.63537 -375.535698)
		(width 0.14732)
		(layer "In11.Cu")
		(net "UPI_CPU1_CPU0_P2P2_DP<14>")
	)
	(segment
		(start 265.29284 -366.84077)
		(end 265.55319 -366.58042)
		(width 0.14732)
		(layer "In11.Cu")
		(net "UPI_CPU1_CPU0_P2P2_DP<14>")
	)
	(arc
		(start 344.299032 -282.778962)
		(mid 344.307354 -282.772407)
		(end 344.315796 -282.766008)
		(width 0.0889)
		(layer "In11.Cu")
		(net "UPI_CPU1_CPU0_P2P2_DP<14>")
	)
	(arc
		(start 101.037898 -281.59202)
		(mid 100.963907 -281.871586)
		(end 100.761292 -282.077922)
		(width 0.0889)
		(layer "In11.Cu")
		(net "UPI_CPU1_CPU0_P2P2_DP<14>")
	)
	(arc
		(start 99.249992 -285.336996)
		(mid 99.062794 -285.286853)
		(end 98.875596 -285.336996)
		(width 0.0889)
		(layer "In11.Cu")
		(net "UPI_CPU1_CPU0_P2P2_DP<14>")
	)
	(arc
		(start 342.024716 -289.446208)
		(mid 341.864679 -289.323012)
		(end 341.754714 -289.1536)
		(width 0.0889)
		(layer "In11.Cu")
		(net "UPI_CPU1_CPU0_P2P2_DP<14>")
	)
	(arc
		(start 343.148666 -284.832044)
		(mid 343.228036 -284.55831)
		(end 343.43086 -284.35808)
		(width 0.0889)
		(layer "In11.Cu")
		(net "UPI_CPU1_CPU0_P2P2_DP<14>")
	)
	(arc
		(start 97.748344 -287.304734)
		(mid 97.668974 -287.578468)
		(end 97.46615 -287.778698)
		(width 0.0889)
		(layer "In11.Cu")
		(net "UPI_CPU1_CPU0_P2P2_DP<14>")
	)
	(arc
		(start 100.755196 -282.730194)
		(mid 100.960268 -282.933873)
		(end 101.037898 -283.212286)
		(width 0.0889)
		(layer "In11.Cu")
		(net "UPI_CPU1_CPU0_P2P2_DP<14>")
	)
	(arc
		(start 343.90965 -283.539184)
		(mid 344.040564 -283.402824)
		(end 344.088212 -283.219906)
		(width 0.0889)
		(layer "In11.Cu")
		(net "UPI_CPU1_CPU0_P2P2_DP<14>")
	)
	(arc
		(start 341.738966 -288.898584)
		(mid 341.819128 -288.626395)
		(end 342.021414 -288.427414)
		(width 0.0889)
		(layer "In11.Cu")
		(net "UPI_CPU1_CPU0_P2P2_DP<14>")
	)
	(arc
		(start 99.800664 -285.345632)
		(mid 99.524189 -285.412952)
		(end 99.249992 -285.336996)
		(width 0.0889)
		(layer "In11.Cu")
		(net "UPI_CPU1_CPU0_P2P2_DP<14>")
	)
	(arc
		(start 344.088212 -283.205682)
		(mid 344.146573 -282.969084)
		(end 344.299032 -282.778962)
		(width 0.0889)
		(layer "In11.Cu")
		(net "UPI_CPU1_CPU0_P2P2_DP<14>")
	)
	(arc
		(start 342.96985 -286.794702)
		(mid 343.148447 -286.475424)
		(end 342.96985 -286.156146)
		(width 0.0889)
		(layer "In11.Cu")
		(net "UPI_CPU1_CPU0_P2P2_DP<14>")
	)
	(arc
		(start 97.926906 -286.969962)
		(mid 97.795992 -287.106322)
		(end 97.748344 -287.28924)
		(width 0.0889)
		(layer "In11.Cu")
		(net "UPI_CPU1_CPU0_P2P2_DP<14>")
	)
	(arc
		(start 342.970104 -285.166816)
		(mid 343.101018 -285.030456)
		(end 343.148666 -284.847538)
		(width 0.0889)
		(layer "In11.Cu")
		(net "UPI_CPU1_CPU0_P2P2_DP<14>")
	)
	(arc
		(start 342.208866 -288.087562)
		(mid 342.288236 -287.813828)
		(end 342.49106 -287.613598)
		(width 0.0889)
		(layer "In11.Cu")
		(net "UPI_CPU1_CPU0_P2P2_DP<14>")
	)
	(arc
		(start 98.218498 -286.475424)
		(mid 98.144507 -286.75499)
		(end 97.941892 -286.961326)
		(width 0.0889)
		(layer "In11.Cu")
		(net "UPI_CPU1_CPU0_P2P2_DP<14>")
	)
	(arc
		(start 341.754714 -289.1536)
		(mid 341.746614 -289.133926)
		(end 341.73922 -289.113976)
		(width 0.0889)
		(layer "In11.Cu")
		(net "UPI_CPU1_CPU0_P2P2_DP<14>")
	)
	(arc
		(start 343.43975 -284.353)
		(mid 343.570664 -284.21664)
		(end 343.618312 -284.033722)
		(width 0.0889)
		(layer "In11.Cu")
		(net "UPI_CPU1_CPU0_P2P2_DP<14>")
	)
	(arc
		(start 343.618312 -284.023816)
		(mid 343.696423 -283.746867)
		(end 343.90076 -283.544264)
		(width 0.0889)
		(layer "In11.Cu")
		(net "UPI_CPU1_CPU0_P2P2_DP<14>")
	)
	(arc
		(start 100.567744 -284.049216)
		(mid 100.488374 -284.32295)
		(end 100.28555 -284.52318)
		(width 0.0889)
		(layer "In11.Cu")
		(net "UPI_CPU1_CPU0_P2P2_DP<14>")
	)
	(arc
		(start 97.262696 -289.569398)
		(mid 97.270927 -289.589324)
		(end 97.278444 -289.60953)
		(width 0.0889)
		(layer "In11.Cu")
		(net "UPI_CPU1_CPU0_P2P2_DP<14>")
	)
	(arc
		(start 101.177852 -281.300174)
		(mid 101.074707 -281.430199)
		(end 101.037898 -281.59202)
		(width 0.0889)
		(layer "In11.Cu")
		(net "UPI_CPU1_CPU0_P2P2_DP<14>")
	)
	(arc
		(start 96.808798 -289.078416)
		(mid 96.883803 -289.193875)
		(end 96.992948 -289.277806)
		(width 0.0889)
		(layer "In11.Cu")
		(net "UPI_CPU1_CPU0_P2P2_DP<14>")
	)
	(arc
		(start 342.96096 -286.151066)
		(mid 342.678311 -285.664963)
		(end 342.955118 -285.175452)
		(width 0.0889)
		(layer "In11.Cu")
		(net "UPI_CPU1_CPU0_P2P2_DP<14>")
	)
	(arc
		(start 100.27666 -284.52826)
		(mid 100.145746 -284.66462)
		(end 100.098098 -284.847538)
		(width 0.0889)
		(layer "In11.Cu")
		(net "UPI_CPU1_CPU0_P2P2_DP<14>")
	)
	(arc
		(start 100.746306 -283.714444)
		(mid 100.615392 -283.850804)
		(end 100.567744 -284.033722)
		(width 0.0889)
		(layer "In11.Cu")
		(net "UPI_CPU1_CPU0_P2P2_DP<14>")
	)
	(arc
		(start 97.278698 -288.121598)
		(mid 97.198536 -288.393787)
		(end 96.99625 -288.592768)
		(width 0.0889)
		(layer "In11.Cu")
		(net "UPI_CPU1_CPU0_P2P2_DP<14>")
	)
	(arc
		(start 96.992948 -289.277806)
		(mid 97.152726 -289.400568)
		(end 97.262696 -289.569398)
		(width 0.0889)
		(layer "In11.Cu")
		(net "UPI_CPU1_CPU0_P2P2_DP<14>")
	)
	(arc
		(start 98.688144 -285.679896)
		(mid 98.607982 -285.952085)
		(end 98.405696 -286.151066)
		(width 0.0889)
		(layer "In11.Cu")
		(net "UPI_CPU1_CPU0_P2P2_DP<14>")
	)
	(arc
		(start 100.746306 -282.086558)
		(mid 100.567709 -282.405836)
		(end 100.746306 -282.725114)
		(width 0.0889)
		(layer "In11.Cu")
		(net "UPI_CPU1_CPU0_P2P2_DP<14>")
	)
	(arc
		(start 97.45726 -287.783778)
		(mid 97.326346 -287.920138)
		(end 97.278698 -288.103056)
		(width 0.0889)
		(layer "In11.Cu")
		(net "UPI_CPU1_CPU0_P2P2_DP<14>")
	)
	(arc
		(start 96.98736 -288.597848)
		(mid 96.856446 -288.734208)
		(end 96.808798 -288.917126)
		(width 0.0889)
		(layer "In11.Cu")
		(net "UPI_CPU1_CPU0_P2P2_DP<14>")
	)
	(arc
		(start 101.037898 -283.219906)
		(mid 100.965663 -283.49643)
		(end 100.767388 -283.702252)
		(width 0.0889)
		(layer "In11.Cu")
		(net "UPI_CPU1_CPU0_P2P2_DP<14>")
	)
	(arc
		(start 98.866706 -285.342076)
		(mid 98.735792 -285.478436)
		(end 98.688144 -285.661354)
		(width 0.0889)
		(layer "In11.Cu")
		(net "UPI_CPU1_CPU0_P2P2_DP<14>")
	)
	(arc
		(start 100.098098 -284.847538)
		(mid 100.024107 -285.127104)
		(end 99.821492 -285.33344)
		(width 0.0889)
		(layer "In11.Cu")
		(net "UPI_CPU1_CPU0_P2P2_DP<14>")
	)
	(arc
		(start 342.208866 -289.64509)
		(mid 342.133759 -289.529944)
		(end 342.024716 -289.446208)
		(width 0.0889)
		(layer "In11.Cu")
		(net "UPI_CPU1_CPU0_P2P2_DP<14>")
	)
	(arc
		(start 342.49995 -287.608518)
		(mid 342.630864 -287.472158)
		(end 342.678512 -287.28924)
		(width 0.0889)
		(layer "In11.Cu")
		(net "UPI_CPU1_CPU0_P2P2_DP<14>")
	)
	(arc
		(start 342.030304 -288.422334)
		(mid 342.161218 -288.285974)
		(end 342.208866 -288.103056)
		(width 0.0889)
		(layer "In11.Cu")
		(net "UPI_CPU1_CPU0_P2P2_DP<14>")
	)
	(arc
		(start 98.405696 -286.151066)
		(mid 98.270763 -286.28442)
		(end 98.218498 -286.466788)
		(width 0.0889)
		(layer "In11.Cu")
		(net "UPI_CPU1_CPU0_P2P2_DP<14>")
	)
	(arc
		(start 342.678512 -287.279334)
		(mid 342.756623 -287.002385)
		(end 342.96096 -286.799782)
		(width 0.0889)
		(layer "In11.Cu")
		(net "UPI_CPU1_CPU0_P2P2_DP<14>")
	)
	(segment
		(start 345.593162 -281.591766)
		(end 345.593416 -281.59202)
		(width 0.13208)
		(layer "F.Cu")
		(net "UPI_CPU1_CPU0_P2P2_DP<13>")
	)
	(segment
		(start 99.532694 -282.683966)
		(end 99.532694 -283.219652)
		(width 0.13208)
		(layer "F.Cu")
		(net "UPI_CPU1_CPU0_P2P2_DP<13>")
	)
	(segment
		(start 345.593162 -281.05608)
		(end 345.593162 -281.591766)
		(width 0.13208)
		(layer "F.Cu")
		(net "UPI_CPU1_CPU0_P2P2_DP<13>")
	)
	(segment
		(start 99.532694 -283.219652)
		(end 99.532948 -283.219906)
		(width 0.13208)
		(layer "F.Cu")
		(net "UPI_CPU1_CPU0_P2P2_DP<13>")
	)
	(segment
		(start 344.927174 -282.725114)
		(end 344.936064 -282.730194)
		(width 0.0889)
		(layer "In11.Cu")
		(net "UPI_CPU1_CPU0_P2P2_DP<13>")
	)
	(segment
		(start 96.618044 -285.679896)
		(end 96.618044 -285.661354)
		(width 0.0889)
		(layer "In11.Cu")
		(net "UPI_CPU1_CPU0_P2P2_DP<13>")
	)
	(segment
		(start 98.027998 -284.847538)
		(end 98.027998 -284.832044)
		(width 0.0889)
		(layer "In11.Cu")
		(net "UPI_CPU1_CPU0_P2P2_DP<13>")
	)
	(segment
		(start 268.21384 -345.854274)
		(end 268.21384 -365.822738)
		(width 0.14732)
		(layer "In11.Cu")
		(net "UPI_CPU1_CPU0_P2P2_DP<13>")
	)
	(segment
		(start 202.792076 -376.296936)
		(end 201.919586 -376.202702)
		(width 0.14732)
		(layer "In11.Cu")
		(net "UPI_CPU1_CPU0_P2P2_DP<13>")
	)
	(segment
		(start 343.216738 -290.463986)
		(end 343.091008 -290.589716)
		(width 0.0889)
		(layer "In11.Cu")
		(net "UPI_CPU1_CPU0_P2P2_DP<13>")
	)
	(segment
		(start 96.915986 -285.16326)
		(end 96.915478 -285.16326)
		(width 0.0889)
		(layer "In11.Cu")
		(net "UPI_CPU1_CPU0_P2P2_DP<13>")
	)
	(segment
		(start 344.466418 -284.52318)
		(end 344.457528 -284.52826)
		(width 0.0889)
		(layer "In11.Cu")
		(net "UPI_CPU1_CPU0_P2P2_DP<13>")
	)
	(segment
		(start 70.219062 -322.060316)
		(end 78.030578 -314.249054)
		(width 0.14732)
		(layer "In11.Cu")
		(net "UPI_CPU1_CPU0_P2P2_DP<13>")
	)
	(segment
		(start 96.430592 -287.613598)
		(end 96.439482 -287.608518)
		(width 0.0889)
		(layer "In11.Cu")
		(net "UPI_CPU1_CPU0_P2P2_DP<13>")
	)
	(segment
		(start 279.681686 -334.386428)
		(end 268.21384 -345.854274)
		(width 0.14732)
		(layer "In11.Cu")
		(net "UPI_CPU1_CPU0_P2P2_DP<13>")
	)
	(segment
		(start 342.558878 -290.981384)
		(end 342.268302 -291.27196)
		(width 0.0889)
		(layer "In11.Cu")
		(net "UPI_CPU1_CPU0_P2P2_DP<13>")
	)
	(segment
		(start 285.211012 -332.09611)
		(end 279.681686 -334.386428)
		(width 0.14732)
		(layer "In11.Cu")
		(net "UPI_CPU1_CPU0_P2P2_DP<13>")
	)
	(segment
		(start 96.049338 -290.875466)
		(end 96.148398 -290.776406)
		(width 0.0889)
		(layer "In11.Cu")
		(net "UPI_CPU1_CPU0_P2P2_DP<13>")
	)
	(segment
		(start 94.04477 -300.993048)
		(end 94.992444 -299.715428)
		(width 0.14732)
		(layer "In11.Cu")
		(net "UPI_CPU1_CPU0_P2P2_DP<13>")
	)
	(segment
		(start 199.897238 -377.826016)
		(end 199.545194 -377.569984)
		(width 0.14732)
		(layer "In11.Cu")
		(net "UPI_CPU1_CPU0_P2P2_DP<13>")
	)
	(segment
		(start 78.343506 -313.935872)
		(end 78.343506 -313.935618)
		(width 0.14732)
		(layer "In11.Cu")
		(net "UPI_CPU1_CPU0_P2P2_DP<13>")
	)
	(segment
		(start 99.249992 -284.35808)
		(end 99.258882 -284.353)
		(width 0.0889)
		(layer "In11.Cu")
		(net "UPI_CPU1_CPU0_P2P2_DP<13>")
	)
	(segment
		(start 96.106488 -297.026076)
		(end 96.106488 -291.547042)
		(width 0.14732)
		(layer "In11.Cu")
		(net "UPI_CPU1_CPU0_P2P2_DP<13>")
	)
	(segment
		(start 161.713672 -381.86995)
		(end 125.80112 -381.86995)
		(width 0.14732)
		(layer "In11.Cu")
		(net "UPI_CPU1_CPU0_P2P2_DP<13>")
	)
	(segment
		(start 344.936064 -282.081478)
		(end 344.927174 -282.086558)
		(width 0.0889)
		(layer "In11.Cu")
		(net "UPI_CPU1_CPU0_P2P2_DP<13>")
	)
	(segment
		(start 343.216738 -290.323524)
		(end 343.216738 -290.463986)
		(width 0.0889)
		(layer "In11.Cu")
		(net "UPI_CPU1_CPU0_P2P2_DP<13>")
	)
	(segment
		(start 343.339166 -288.103056)
		(end 343.339166 -288.121598)
		(width 0.0889)
		(layer "In11.Cu")
		(net "UPI_CPU1_CPU0_P2P2_DP<13>")
	)
	(segment
		(start 342.268302 -291.331904)
		(end 342.252808 -291.347398)
		(width 0.0889)
		(layer "In11.Cu")
		(net "UPI_CPU1_CPU0_P2P2_DP<13>")
	)
	(segment
		(start 344.94216 -283.705808)
		(end 344.927174 -283.714698)
		(width 0.0889)
		(layer "In11.Cu")
		(net "UPI_CPU1_CPU0_P2P2_DP<13>")
	)
	(segment
		(start 306.34178 -332.09611)
		(end 285.211012 -332.09611)
		(width 0.14732)
		(layer "In11.Cu")
		(net "UPI_CPU1_CPU0_P2P2_DP<13>")
	)
	(segment
		(start 200.830942 -376.523758)
		(end 200.96099 -377.34621)
		(width 0.14732)
		(layer "In11.Cu")
		(net "UPI_CPU1_CPU0_P2P2_DP<13>")
	)
	(segment
		(start 340.819232 -299.042836)
		(end 339.956648 -299.90542)
		(width 0.14732)
		(layer "In11.Cu")
		(net "UPI_CPU1_CPU0_P2P2_DP<13>")
	)
	(segment
		(start 200.96099 -377.34621)
		(end 200.704958 -377.698254)
		(width 0.14732)
		(layer "In11.Cu")
		(net "UPI_CPU1_CPU0_P2P2_DP<13>")
	)
	(segment
		(start 201.919586 -376.202702)
		(end 200.95337 -376.35561)
		(width 0.14732)
		(layer "In11.Cu")
		(net "UPI_CPU1_CPU0_P2P2_DP<13>")
	)
	(segment
		(start 97.84207 -285.171134)
		(end 97.849436 -285.166816)
		(width 0.0889)
		(layer "In11.Cu")
		(net "UPI_CPU1_CPU0_P2P2_DP<13>")
	)
	(segment
		(start 96.909382 -286.156146)
		(end 96.900492 -286.151066)
		(width 0.0889)
		(layer "In11.Cu")
		(net "UPI_CPU1_CPU0_P2P2_DP<13>")
	)
	(segment
		(start 96.900492 -286.799782)
		(end 96.909382 -286.794702)
		(width 0.0889)
		(layer "In11.Cu")
		(net "UPI_CPU1_CPU0_P2P2_DP<13>")
	)
	(segment
		(start 308.697122 -327.402444)
		(end 308.460394 -328.745088)
		(width 0.14732)
		(layer "In11.Cu")
		(net "UPI_CPU1_CPU0_P2P2_DP<13>")
	)
	(segment
		(start 200.704958 -377.698254)
		(end 199.897238 -377.826016)
		(width 0.14732)
		(layer "In11.Cu")
		(net "UPI_CPU1_CPU0_P2P2_DP<13>")
	)
	(segment
		(start 94.992444 -299.715428)
		(end 96.106488 -297.026076)
		(width 0.14732)
		(layer "In11.Cu")
		(net "UPI_CPU1_CPU0_P2P2_DP<13>")
	)
	(segment
		(start 96.148398 -291.432234)
		(end 96.148398 -291.152326)
		(width 0.0889)
		(layer "In11.Cu")
		(net "UPI_CPU1_CPU0_P2P2_DP<13>")
	)
	(segment
		(start 96.89465 -285.175452)
		(end 96.915986 -285.16326)
		(width 0.0889)
		(layer "In11.Cu")
		(net "UPI_CPU1_CPU0_P2P2_DP<13>")
	)
	(segment
		(start 78.030324 -314.249054)
		(end 78.343506 -313.935872)
		(width 0.14732)
		(layer "In11.Cu")
		(net "UPI_CPU1_CPU0_P2P2_DP<13>")
	)
	(segment
		(start 96.148398 -290.598606)
		(end 96.049338 -290.499546)
		(width 0.0889)
		(layer "In11.Cu")
		(net "UPI_CPU1_CPU0_P2P2_DP<13>")
	)
	(segment
		(start 312.26125 -325.647304)
		(end 310.902604 -325.647304)
		(width 0.14732)
		(layer "In11.Cu")
		(net "UPI_CPU1_CPU0_P2P2_DP<13>")
	)
	(segment
		(start 308.464204 -328.748898)
		(end 308.464204 -329.973686)
		(width 0.14732)
		(layer "In11.Cu")
		(net "UPI_CPU1_CPU0_P2P2_DP<13>")
	)
	(segment
		(start 78.676754 -313.604148)
		(end 78.677008 -313.604402)
		(width 0.14732)
		(layer "In11.Cu")
		(net "UPI_CPU1_CPU0_P2P2_DP<13>")
	)
	(segment
		(start 339.906102 -299.926502)
		(end 336.525362 -301.326042)
		(width 0.14732)
		(layer "In11.Cu")
		(net "UPI_CPU1_CPU0_P2P2_DP<13>")
	)
	(segment
		(start 96.148398 -288.103056)
		(end 96.148398 -288.087562)
		(width 0.0889)
		(layer "In11.Cu")
		(net "UPI_CPU1_CPU0_P2P2_DP<13>")
	)
	(segment
		(start 310.902604 -325.647304)
		(end 310.009794 -326.017128)
		(width 0.14732)
		(layer "In11.Cu")
		(net "UPI_CPU1_CPU0_P2P2_DP<13>")
	)
	(segment
		(start 96.618044 -287.28924)
		(end 96.618044 -287.279334)
		(width 0.0889)
		(layer "In11.Cu")
		(net "UPI_CPU1_CPU0_P2P2_DP<13>")
	)
	(segment
		(start 205.424024 -377.75388)
		(end 205.15072 -377.415044)
		(width 0.14732)
		(layer "In11.Cu")
		(net "UPI_CPU1_CPU0_P2P2_DP<13>")
	)
	(segment
		(start 342.82507 -290.855654)
		(end 342.69934 -290.981384)
		(width 0.0889)
		(layer "In11.Cu")
		(net "UPI_CPU1_CPU0_P2P2_DP<13>")
	)
	(segment
		(start 199.246998 -376.625104)
		(end 171.399708 -381.025654)
		(width 0.14732)
		(layer "In11.Cu")
		(net "UPI_CPU1_CPU0_P2P2_DP<13>")
	)
	(segment
		(start 206.237332 -377.841764)
		(end 205.424024 -377.75388)
		(width 0.14732)
		(layer "In11.Cu")
		(net "UPI_CPU1_CPU0_P2P2_DP<13>")
	)
	(segment
		(start 96.106488 -291.547042)
		(end 96.106234 -291.546788)
		(width 0.14732)
		(layer "In11.Cu")
		(net "UPI_CPU1_CPU0_P2P2_DP<13>")
	)
	(segment
		(start 336.525362 -301.326042)
		(end 315.213746 -322.637912)
		(width 0.14732)
		(layer "In11.Cu")
		(net "UPI_CPU1_CPU0_P2P2_DP<13>")
	)
	(segment
		(start 99.689412 -282.948888)
		(end 99.532948 -283.219906)
		(width 0.0889)
		(layer "In11.Cu")
		(net "UPI_CPU1_CPU0_P2P2_DP<13>")
	)
	(segment
		(start 202.846432 -377.166632)
		(end 202.922632 -376.458988)
		(width 0.14732)
		(layer "In11.Cu")
		(net "UPI_CPU1_CPU0_P2P2_DP<13>")
	)
	(segment
		(start 345.74988 -281.321002)
		(end 345.728798 -281.243024)
		(width 0.0889)
		(layer "In11.Cu")
		(net "UPI_CPU1_CPU0_P2P2_DP<13>")
	)
	(segment
		(start 98.860864 -284.349444)
		(end 98.875596 -284.35808)
		(width 0.0889)
		(layer "In11.Cu")
		(net "UPI_CPU1_CPU0_P2P2_DP<13>")
	)
	(segment
		(start 342.69934 -290.981384)
		(end 342.558878 -290.981384)
		(width 0.0889)
		(layer "In11.Cu")
		(net "UPI_CPU1_CPU0_P2P2_DP<13>")
	)
	(segment
		(start 67.268598 -354.067364)
		(end 67.268598 -334.801972)
		(width 0.14732)
		(layer "In11.Cu")
		(net "UPI_CPU1_CPU0_P2P2_DP<13>")
	)
	(segment
		(start 344.748612 -284.033722)
		(end 344.748612 -284.049216)
		(width 0.0889)
		(layer "In11.Cu")
		(net "UPI_CPU1_CPU0_P2P2_DP<13>")
	)
	(segment
		(start 205.22692 -376.7074)
		(end 205.096364 -376.545348)
		(width 0.14732)
		(layer "In11.Cu")
		(net "UPI_CPU1_CPU0_P2P2_DP<13>")
	)
	(segment
		(start 204.509878 -376.482102)
		(end 204.347826 -376.612658)
		(width 0.14732)
		(layer "In11.Cu")
		(net "UPI_CPU1_CPU0_P2P2_DP<13>")
	)
	(segment
		(start 339.956648 -299.90542)
		(end 339.906102 -299.926502)
		(width 0.14732)
		(layer "In11.Cu")
		(net "UPI_CPU1_CPU0_P2P2_DP<13>")
	)
	(segment
		(start 96.106234 -291.546788)
		(end 96.106234 -291.496496)
		(width 0.14732)
		(layer "In11.Cu")
		(net "UPI_CPU1_CPU0_P2P2_DP<13>")
	)
	(segment
		(start 342.869266 -288.917126)
		(end 342.869266 -289.078416)
		(width 0.0889)
		(layer "In11.Cu")
		(net "UPI_CPU1_CPU0_P2P2_DP<13>")
	)
	(segment
		(start 344.927174 -283.714698)
		(end 344.927174 -283.714444)
		(width 0.0889)
		(layer "In11.Cu")
		(net "UPI_CPU1_CPU0_P2P2_DP<13>")
	)
	(segment
		(start 67.268598 -334.801972)
		(end 67.916298 -328.228706)
		(width 0.14732)
		(layer "In11.Cu")
		(net "UPI_CPU1_CPU0_P2P2_DP<13>")
	)
	(segment
		(start 95.678498 -289.114738)
		(end 95.678498 -288.898584)
		(width 0.0889)
		(layer "In11.Cu")
		(net "UPI_CPU1_CPU0_P2P2_DP<13>")
	)
	(segment
		(start 308.460394 -328.745088)
		(end 308.464204 -328.748898)
		(width 0.14732)
		(layer "In11.Cu")
		(net "UPI_CPU1_CPU0_P2P2_DP<13>")
	)
	(segment
		(start 96.148398 -290.222686)
		(end 96.148398 -289.64636)
		(width 0.0889)
		(layer "In11.Cu")
		(net "UPI_CPU1_CPU0_P2P2_DP<13>")
	)
	(segment
		(start 96.106234 -291.474398)
		(end 96.148398 -291.432234)
		(width 0.0889)
		(layer "In11.Cu")
		(net "UPI_CPU1_CPU0_P2P2_DP<13>")
	)
	(segment
		(start 206.814166 -376.730514)
		(end 206.652114 -376.86107)
		(width 0.14732)
		(layer "In11.Cu")
		(net "UPI_CPU1_CPU0_P2P2_DP<13>")
	)
	(segment
		(start 75.666092 -368.699542)
		(end 71.677022 -364.710472)
		(width 0.14732)
		(layer "In11.Cu")
		(net "UPI_CPU1_CPU0_P2P2_DP<13>")
	)
	(segment
		(start 343.338912 -290.20135)
		(end 343.216738 -290.323524)
		(width 0.0889)
		(layer "In11.Cu")
		(net "UPI_CPU1_CPU0_P2P2_DP<13>")
	)
	(segment
		(start 343.996264 -285.336996)
		(end 343.987374 -285.342076)
		(width 0.0889)
		(layer "In11.Cu")
		(net "UPI_CPU1_CPU0_P2P2_DP<13>")
	)
	(segment
		(start 268.21384 -365.822738)
		(end 260.843268 -373.19331)
		(width 0.14732)
		(layer "In11.Cu")
		(net "UPI_CPU1_CPU0_P2P2_DP<13>")
	)
	(segment
		(start 202.922632 -376.458988)
		(end 202.792076 -376.296936)
		(width 0.14732)
		(layer "In11.Cu")
		(net "UPI_CPU1_CPU0_P2P2_DP<13>")
	)
	(segment
		(start 315.212984 -322.63842)
		(end 314.35421 -323.497194)
		(width 0.14732)
		(layer "In11.Cu")
		(net "UPI_CPU1_CPU0_P2P2_DP<13>")
	)
	(segment
		(start 95.960946 -288.427414)
		(end 95.969836 -288.422334)
		(width 0.0889)
		(layer "In11.Cu")
		(net "UPI_CPU1_CPU0_P2P2_DP<13>")
	)
	(segment
		(start 200.95337 -376.35561)
		(end 200.830942 -376.523758)
		(width 0.14732)
		(layer "In11.Cu")
		(net "UPI_CPU1_CPU0_P2P2_DP<13>")
	)
	(segment
		(start 314.35421 -323.497194)
		(end 313.413648 -324.840854)
		(width 0.14732)
		(layer "In11.Cu")
		(net "UPI_CPU1_CPU0_P2P2_DP<13>")
	)
	(segment
		(start 99.907344 -283.228542)
		(end 99.907344 -283.21127)
		(width 0.0889)
		(layer "In11.Cu")
		(net "UPI_CPU1_CPU0_P2P2_DP<13>")
	)
	(segment
		(start 343.808812 -287.28924)
		(end 343.808812 -287.304734)
		(width 0.0889)
		(layer "In11.Cu")
		(net "UPI_CPU1_CPU0_P2P2_DP<13>")
	)
	(segment
		(start 212.924898 -377.387612)
		(end 206.814166 -376.730514)
		(width 0.14732)
		(layer "In11.Cu")
		(net "UPI_CPU1_CPU0_P2P2_DP<13>")
	)
	(segment
		(start 99.719384 -283.544772)
		(end 99.720146 -283.544264)
		(width 0.0889)
		(layer "In11.Cu")
		(net "UPI_CPU1_CPU0_P2P2_DP<13>")
	)
	(segment
		(start 99.71405 -283.54782)
		(end 99.719384 -283.544772)
		(width 0.0889)
		(layer "In11.Cu")
		(net "UPI_CPU1_CPU0_P2P2_DP<13>")
	)
	(segment
		(start 71.677022 -364.710472)
		(end 67.268598 -354.067364)
		(width 0.14732)
		(layer "In11.Cu")
		(net "UPI_CPU1_CPU0_P2P2_DP<13>")
	)
	(segment
		(start 78.677008 -313.604402)
		(end 94.04477 -300.993048)
		(width 0.14732)
		(layer "In11.Cu")
		(net "UPI_CPU1_CPU0_P2P2_DP<13>")
	)
	(segment
		(start 344.94216 -282.077922)
		(end 344.936064 -282.081478)
		(width 0.0889)
		(layer "In11.Cu")
		(net "UPI_CPU1_CPU0_P2P2_DP<13>")
	)
	(segment
		(start 96.148398 -291.152326)
		(end 96.049338 -291.053266)
		(width 0.0889)
		(layer "In11.Cu")
		(net "UPI_CPU1_CPU0_P2P2_DP<13>")
	)
	(segment
		(start 96.049338 -290.321746)
		(end 96.148398 -290.222686)
		(width 0.0889)
		(layer "In11.Cu")
		(net "UPI_CPU1_CPU0_P2P2_DP<13>")
	)
	(segment
		(start 343.987374 -285.980632)
		(end 343.996264 -285.985712)
		(width 0.0889)
		(layer "In11.Cu")
		(net "UPI_CPU1_CPU0_P2P2_DP<13>")
	)
	(segment
		(start 341.175594 -298.182792)
		(end 340.819232 -299.042836)
		(width 0.14732)
		(layer "In11.Cu")
		(net "UPI_CPU1_CPU0_P2P2_DP<13>")
	)
	(segment
		(start 199.545194 -377.569984)
		(end 199.415146 -376.747532)
		(width 0.14732)
		(layer "In11.Cu")
		(net "UPI_CPU1_CPU0_P2P2_DP<13>")
	)
	(segment
		(start 345.218766 -283.205682)
		(end 345.218766 -283.219906)
		(width 0.0889)
		(layer "In11.Cu")
		(net "UPI_CPU1_CPU0_P2P2_DP<13>")
	)
	(segment
		(start 125.80112 -381.86995)
		(end 97.230692 -377.631706)
		(width 0.14732)
		(layer "In11.Cu")
		(net "UPI_CPU1_CPU0_P2P2_DP<13>")
	)
	(segment
		(start 309.60187 -326.289924)
		(end 309.181754 -326.709786)
		(width 0.14732)
		(layer "In11.Cu")
		(net "UPI_CPU1_CPU0_P2P2_DP<13>")
	)
	(segment
		(start 206.652114 -376.86107)
		(end 206.575914 -377.568968)
		(width 0.14732)
		(layer "In11.Cu")
		(net "UPI_CPU1_CPU0_P2P2_DP<13>")
	)
	(segment
		(start 204.271626 -377.320556)
		(end 203.933044 -377.593352)
		(width 0.14732)
		(layer "In11.Cu")
		(net "UPI_CPU1_CPU0_P2P2_DP<13>")
	)
	(segment
		(start 343.526618 -287.778698)
		(end 343.517728 -287.783778)
		(width 0.0889)
		(layer "In11.Cu")
		(net "UPI_CPU1_CPU0_P2P2_DP<13>")
	)
	(segment
		(start 205.096364 -376.545348)
		(end 204.509878 -376.482102)
		(width 0.14732)
		(layer "In11.Cu")
		(net "UPI_CPU1_CPU0_P2P2_DP<13>")
	)
	(segment
		(start 96.049338 -290.499546)
		(end 96.049338 -290.321746)
		(width 0.0889)
		(layer "In11.Cu")
		(net "UPI_CPU1_CPU0_P2P2_DP<13>")
	)
	(segment
		(start 171.399708 -381.025654)
		(end 161.713672 -381.86995)
		(width 0.14732)
		(layer "In11.Cu")
		(net "UPI_CPU1_CPU0_P2P2_DP<13>")
	)
	(segment
		(start 345.593416 -281.59202)
		(end 345.74988 -281.321002)
		(width 0.0889)
		(layer "In11.Cu")
		(net "UPI_CPU1_CPU0_P2P2_DP<13>")
	)
	(segment
		(start 203.933044 -377.593352)
		(end 203.119736 -377.505468)
		(width 0.14732)
		(layer "In11.Cu")
		(net "UPI_CPU1_CPU0_P2P2_DP<13>")
	)
	(segment
		(start 341.939626 -294.340026)
		(end 341.175594 -298.182792)
		(width 0.14732)
		(layer "In11.Cu")
		(net "UPI_CPU1_CPU0_P2P2_DP<13>")
	)
	(segment
		(start 342.252808 -291.347398)
		(end 342.102694 -291.497512)
		(width 0.14732)
		(layer "In11.Cu")
		(net "UPI_CPU1_CPU0_P2P2_DP<13>")
	)
	(segment
		(start 96.148398 -289.64636)
		(end 96.148144 -289.645852)
		(width 0.0889)
		(layer "In11.Cu")
		(net "UPI_CPU1_CPU0_P2P2_DP<13>")
	)
	(segment
		(start 96.106234 -291.496496)
		(end 96.106234 -291.474398)
		(width 0.0889)
		(layer "In11.Cu")
		(net "UPI_CPU1_CPU0_P2P2_DP<13>")
	)
	(segment
		(start 206.575914 -377.568968)
		(end 206.237332 -377.841764)
		(width 0.14732)
		(layer "In11.Cu")
		(net "UPI_CPU1_CPU0_P2P2_DP<13>")
	)
	(segment
		(start 342.268302 -291.27196)
		(end 342.268302 -291.331904)
		(width 0.0889)
		(layer "In11.Cu")
		(net "UPI_CPU1_CPU0_P2P2_DP<13>")
	)
	(segment
		(start 313.413648 -324.840854)
		(end 312.26125 -325.647304)
		(width 0.14732)
		(layer "In11.Cu")
		(net "UPI_CPU1_CPU0_P2P2_DP<13>")
	)
	(segment
		(start 315.213746 -322.637912)
		(end 315.212984 -322.63842)
		(width 0.14732)
		(layer "In11.Cu")
		(net "UPI_CPU1_CPU0_P2P2_DP<13>")
	)
	(segment
		(start 342.950546 -290.589716)
		(end 342.82507 -290.715192)
		(width 0.0889)
		(layer "In11.Cu")
		(net "UPI_CPU1_CPU0_P2P2_DP<13>")
	)
	(segment
		(start 96.148398 -290.776406)
		(end 96.148398 -290.598606)
		(width 0.0889)
		(layer "In11.Cu")
		(net "UPI_CPU1_CPU0_P2P2_DP<13>")
	)
	(segment
		(start 78.66634 -313.612784)
		(end 78.676754 -313.604148)
		(width 0.14732)
		(layer "In11.Cu")
		(net "UPI_CPU1_CPU0_P2P2_DP<13>")
	)
	(segment
		(start 78.343506 -313.935618)
		(end 78.66634 -313.612784)
		(width 0.14732)
		(layer "In11.Cu")
		(net "UPI_CPU1_CPU0_P2P2_DP<13>")
	)
	(segment
		(start 205.15072 -377.415044)
		(end 205.22692 -376.7074)
		(width 0.14732)
		(layer "In11.Cu")
		(net "UPI_CPU1_CPU0_P2P2_DP<13>")
	)
	(segment
		(start 203.119736 -377.505468)
		(end 202.846432 -377.166632)
		(width 0.14732)
		(layer "In11.Cu")
		(net "UPI_CPU1_CPU0_P2P2_DP<13>")
	)
	(segment
		(start 68.782692 -325.097648)
		(end 70.219062 -322.060316)
		(width 0.14732)
		(layer "In11.Cu")
		(net "UPI_CPU1_CPU0_P2P2_DP<13>")
	)
	(segment
		(start 344.00236 -285.33344)
		(end 343.996264 -285.336996)
		(width 0.0889)
		(layer "In11.Cu")
		(net "UPI_CPU1_CPU0_P2P2_DP<13>")
	)
	(segment
		(start 78.030578 -314.249054)
		(end 78.030324 -314.249054)
		(width 0.14732)
		(layer "In11.Cu")
		(net "UPI_CPU1_CPU0_P2P2_DP<13>")
	)
	(segment
		(start 97.840546 -285.171896)
		(end 97.84207 -285.171134)
		(width 0.0889)
		(layer "In11.Cu")
		(net "UPI_CPU1_CPU0_P2P2_DP<13>")
	)
	(segment
		(start 310.009794 -326.017128)
		(end 309.60187 -326.289924)
		(width 0.14732)
		(layer "In11.Cu")
		(net "UPI_CPU1_CPU0_P2P2_DP<13>")
	)
	(segment
		(start 99.76739 -282.92806)
		(end 99.689412 -282.948888)
		(width 0.0889)
		(layer "In11.Cu")
		(net "UPI_CPU1_CPU0_P2P2_DP<13>")
	)
	(segment
		(start 204.347826 -376.612658)
		(end 204.271626 -377.320556)
		(width 0.14732)
		(layer "In11.Cu")
		(net "UPI_CPU1_CPU0_P2P2_DP<13>")
	)
	(segment
		(start 344.00236 -286.961326)
		(end 343.987374 -286.970216)
		(width 0.0889)
		(layer "In11.Cu")
		(net "UPI_CPU1_CPU0_P2P2_DP<13>")
	)
	(segment
		(start 97.230692 -377.631706)
		(end 75.666092 -368.699542)
		(width 0.14732)
		(layer "In11.Cu")
		(net "UPI_CPU1_CPU0_P2P2_DP<13>")
	)
	(segment
		(start 343.338912 -289.60953)
		(end 343.338912 -290.20135)
		(width 0.0889)
		(layer "In11.Cu")
		(net "UPI_CPU1_CPU0_P2P2_DP<13>")
	)
	(segment
		(start 341.939626 -294.339772)
		(end 341.939626 -294.340026)
		(width 0.14732)
		(layer "In11.Cu")
		(net "UPI_CPU1_CPU0_P2P2_DP<13>")
	)
	(segment
		(start 343.056718 -288.592768)
		(end 343.047828 -288.597848)
		(width 0.0889)
		(layer "In11.Cu")
		(net "UPI_CPU1_CPU0_P2P2_DP<13>")
	)
	(segment
		(start 342.82507 -290.715192)
		(end 342.82507 -290.855654)
		(width 0.0889)
		(layer "In11.Cu")
		(net "UPI_CPU1_CPU0_P2P2_DP<13>")
	)
	(segment
		(start 342.102694 -293.519352)
		(end 341.939626 -294.339772)
		(width 0.14732)
		(layer "In11.Cu")
		(net "UPI_CPU1_CPU0_P2P2_DP<13>")
	)
	(segment
		(start 260.843268 -373.19331)
		(end 212.924898 -377.387612)
		(width 0.14732)
		(layer "In11.Cu")
		(net "UPI_CPU1_CPU0_P2P2_DP<13>")
	)
	(segment
		(start 308.464204 -329.973686)
		(end 306.34178 -332.09611)
		(width 0.14732)
		(layer "In11.Cu")
		(net "UPI_CPU1_CPU0_P2P2_DP<13>")
	)
	(segment
		(start 67.916298 -328.228706)
		(end 68.782692 -325.097648)
		(width 0.14732)
		(layer "In11.Cu")
		(net "UPI_CPU1_CPU0_P2P2_DP<13>")
	)
	(segment
		(start 343.091008 -290.589716)
		(end 342.950546 -290.589716)
		(width 0.0889)
		(layer "In11.Cu")
		(net "UPI_CPU1_CPU0_P2P2_DP<13>")
	)
	(segment
		(start 199.415146 -376.747532)
		(end 199.246998 -376.625104)
		(width 0.14732)
		(layer "In11.Cu")
		(net "UPI_CPU1_CPU0_P2P2_DP<13>")
	)
	(segment
		(start 343.987374 -286.970216)
		(end 343.987374 -286.969962)
		(width 0.0889)
		(layer "In11.Cu")
		(net "UPI_CPU1_CPU0_P2P2_DP<13>")
	)
	(segment
		(start 345.406218 -281.267662)
		(end 345.397328 -281.272742)
		(width 0.0889)
		(layer "In11.Cu")
		(net "UPI_CPU1_CPU0_P2P2_DP<13>")
	)
	(segment
		(start 344.278966 -286.4612)
		(end 344.278966 -286.475424)
		(width 0.0889)
		(layer "In11.Cu")
		(net "UPI_CPU1_CPU0_P2P2_DP<13>")
	)
	(segment
		(start 342.102694 -291.497512)
		(end 342.102694 -293.519352)
		(width 0.14732)
		(layer "In11.Cu")
		(net "UPI_CPU1_CPU0_P2P2_DP<13>")
	)
	(segment
		(start 309.181754 -326.709786)
		(end 308.697122 -327.402444)
		(width 0.14732)
		(layer "In11.Cu")
		(net "UPI_CPU1_CPU0_P2P2_DP<13>")
	)
	(segment
		(start 96.049338 -291.053266)
		(end 96.049338 -290.875466)
		(width 0.0889)
		(layer "In11.Cu")
		(net "UPI_CPU1_CPU0_P2P2_DP<13>")
	)
	(arc
		(start 344.278966 -284.847538)
		(mid 344.204975 -285.127104)
		(end 344.00236 -285.33344)
		(width 0.0889)
		(layer "In11.Cu")
		(net "UPI_CPU1_CPU0_P2P2_DP<13>")
	)
	(arc
		(start 98.310192 -284.35808)
		(mid 98.584391 -284.282245)
		(end 98.860864 -284.349444)
		(width 0.0889)
		(layer "In11.Cu")
		(net "UPI_CPU1_CPU0_P2P2_DP<13>")
	)
	(arc
		(start 344.278966 -286.475424)
		(mid 344.204975 -286.75499)
		(end 344.00236 -286.961326)
		(width 0.0889)
		(layer "In11.Cu")
		(net "UPI_CPU1_CPU0_P2P2_DP<13>")
	)
	(arc
		(start 343.808812 -287.304734)
		(mid 343.729442 -287.578468)
		(end 343.526618 -287.778698)
		(width 0.0889)
		(layer "In11.Cu")
		(net "UPI_CPU1_CPU0_P2P2_DP<13>")
	)
	(arc
		(start 96.915478 -285.16326)
		(mid 97.191953 -285.09594)
		(end 97.46615 -285.171896)
		(width 0.0889)
		(layer "In11.Cu")
		(net "UPI_CPU1_CPU0_P2P2_DP<13>")
	)
	(arc
		(start 345.218766 -283.219906)
		(mid 345.144775 -283.499472)
		(end 344.94216 -283.705808)
		(width 0.0889)
		(layer "In11.Cu")
		(net "UPI_CPU1_CPU0_P2P2_DP<13>")
	)
	(arc
		(start 343.339166 -288.121598)
		(mid 343.259004 -288.393787)
		(end 343.056718 -288.592768)
		(width 0.0889)
		(layer "In11.Cu")
		(net "UPI_CPU1_CPU0_P2P2_DP<13>")
	)
	(arc
		(start 96.148398 -288.087562)
		(mid 96.227768 -287.813828)
		(end 96.430592 -287.613598)
		(width 0.0889)
		(layer "In11.Cu")
		(net "UPI_CPU1_CPU0_P2P2_DP<13>")
	)
	(arc
		(start 343.987374 -285.342076)
		(mid 343.808656 -285.661354)
		(end 343.987374 -285.980632)
		(width 0.0889)
		(layer "In11.Cu")
		(net "UPI_CPU1_CPU0_P2P2_DP<13>")
	)
	(arc
		(start 98.027998 -284.832044)
		(mid 98.107368 -284.55831)
		(end 98.310192 -284.35808)
		(width 0.0889)
		(layer "In11.Cu")
		(net "UPI_CPU1_CPU0_P2P2_DP<13>")
	)
	(arc
		(start 99.907344 -283.21127)
		(mid 99.86867 -283.054202)
		(end 99.76739 -282.92806)
		(width 0.0889)
		(layer "In11.Cu")
		(net "UPI_CPU1_CPU0_P2P2_DP<13>")
	)
	(arc
		(start 344.936064 -282.730194)
		(mid 345.139545 -282.930998)
		(end 345.218766 -283.205682)
		(width 0.0889)
		(layer "In11.Cu")
		(net "UPI_CPU1_CPU0_P2P2_DP<13>")
	)
	(arc
		(start 342.869266 -289.078416)
		(mid 342.944271 -289.193875)
		(end 343.053416 -289.277806)
		(width 0.0889)
		(layer "In11.Cu")
		(net "UPI_CPU1_CPU0_P2P2_DP<13>")
	)
	(arc
		(start 97.849436 -285.166816)
		(mid 97.98035 -285.030456)
		(end 98.027998 -284.847538)
		(width 0.0889)
		(layer "In11.Cu")
		(net "UPI_CPU1_CPU0_P2P2_DP<13>")
	)
	(arc
		(start 345.397328 -281.272742)
		(mid 345.266414 -281.409102)
		(end 345.218766 -281.59202)
		(width 0.0889)
		(layer "In11.Cu")
		(net "UPI_CPU1_CPU0_P2P2_DP<13>")
	)
	(arc
		(start 99.720146 -283.544264)
		(mid 99.855079 -283.41091)
		(end 99.907344 -283.228542)
		(width 0.0889)
		(layer "In11.Cu")
		(net "UPI_CPU1_CPU0_P2P2_DP<13>")
	)
	(arc
		(start 99.437444 -284.033722)
		(mid 99.511435 -283.754156)
		(end 99.71405 -283.54782)
		(width 0.0889)
		(layer "In11.Cu")
		(net "UPI_CPU1_CPU0_P2P2_DP<13>")
	)
	(arc
		(start 344.457528 -284.52826)
		(mid 344.326614 -284.66462)
		(end 344.278966 -284.847538)
		(width 0.0889)
		(layer "In11.Cu")
		(net "UPI_CPU1_CPU0_P2P2_DP<13>")
	)
	(arc
		(start 96.148144 -289.645852)
		(mid 96.073139 -289.530393)
		(end 95.963994 -289.446462)
		(width 0.0889)
		(layer "In11.Cu")
		(net "UPI_CPU1_CPU0_P2P2_DP<13>")
	)
	(arc
		(start 98.875596 -284.35808)
		(mid 99.062794 -284.408223)
		(end 99.249992 -284.35808)
		(width 0.0889)
		(layer "In11.Cu")
		(net "UPI_CPU1_CPU0_P2P2_DP<13>")
	)
	(arc
		(start 99.258882 -284.353)
		(mid 99.389796 -284.21664)
		(end 99.437444 -284.033722)
		(width 0.0889)
		(layer "In11.Cu")
		(net "UPI_CPU1_CPU0_P2P2_DP<13>")
	)
	(arc
		(start 344.927174 -283.714444)
		(mid 344.79626 -283.850804)
		(end 344.748612 -284.033722)
		(width 0.0889)
		(layer "In11.Cu")
		(net "UPI_CPU1_CPU0_P2P2_DP<13>")
	)
	(arc
		(start 345.218766 -281.59202)
		(mid 345.144775 -281.871586)
		(end 344.94216 -282.077922)
		(width 0.0889)
		(layer "In11.Cu")
		(net "UPI_CPU1_CPU0_P2P2_DP<13>")
	)
	(arc
		(start 343.053416 -289.277806)
		(mid 343.227548 -289.416653)
		(end 343.338912 -289.60953)
		(width 0.0889)
		(layer "In11.Cu")
		(net "UPI_CPU1_CPU0_P2P2_DP<13>")
	)
	(arc
		(start 343.987374 -286.969962)
		(mid 343.85646 -287.106322)
		(end 343.808812 -287.28924)
		(width 0.0889)
		(layer "In11.Cu")
		(net "UPI_CPU1_CPU0_P2P2_DP<13>")
	)
	(arc
		(start 343.996264 -285.985712)
		(mid 344.199745 -286.186516)
		(end 344.278966 -286.4612)
		(width 0.0889)
		(layer "In11.Cu")
		(net "UPI_CPU1_CPU0_P2P2_DP<13>")
	)
	(arc
		(start 96.909382 -286.794702)
		(mid 97.087979 -286.475424)
		(end 96.909382 -286.156146)
		(width 0.0889)
		(layer "In11.Cu")
		(net "UPI_CPU1_CPU0_P2P2_DP<13>")
	)
	(arc
		(start 95.678498 -288.898584)
		(mid 95.75866 -288.626395)
		(end 95.960946 -288.427414)
		(width 0.0889)
		(layer "In11.Cu")
		(net "UPI_CPU1_CPU0_P2P2_DP<13>")
	)
	(arc
		(start 96.439482 -287.608518)
		(mid 96.570396 -287.472158)
		(end 96.618044 -287.28924)
		(width 0.0889)
		(layer "In11.Cu")
		(net "UPI_CPU1_CPU0_P2P2_DP<13>")
	)
	(arc
		(start 96.618044 -285.661354)
		(mid 96.692035 -285.381788)
		(end 96.89465 -285.175452)
		(width 0.0889)
		(layer "In11.Cu")
		(net "UPI_CPU1_CPU0_P2P2_DP<13>")
	)
	(arc
		(start 345.728798 -281.243024)
		(mid 345.564702 -281.218677)
		(end 345.406218 -281.267662)
		(width 0.0889)
		(layer "In11.Cu")
		(net "UPI_CPU1_CPU0_P2P2_DP<13>")
	)
	(arc
		(start 96.900492 -286.151066)
		(mid 96.698206 -285.952085)
		(end 96.618044 -285.679896)
		(width 0.0889)
		(layer "In11.Cu")
		(net "UPI_CPU1_CPU0_P2P2_DP<13>")
	)
	(arc
		(start 96.618044 -287.279334)
		(mid 96.696155 -287.002385)
		(end 96.900492 -286.799782)
		(width 0.0889)
		(layer "In11.Cu")
		(net "UPI_CPU1_CPU0_P2P2_DP<13>")
	)
	(arc
		(start 344.927174 -282.086558)
		(mid 344.748456 -282.405836)
		(end 344.927174 -282.725114)
		(width 0.0889)
		(layer "In11.Cu")
		(net "UPI_CPU1_CPU0_P2P2_DP<13>")
	)
	(arc
		(start 343.517728 -287.783778)
		(mid 343.386814 -287.920138)
		(end 343.339166 -288.103056)
		(width 0.0889)
		(layer "In11.Cu")
		(net "UPI_CPU1_CPU0_P2P2_DP<13>")
	)
	(arc
		(start 344.748612 -284.049216)
		(mid 344.669242 -284.32295)
		(end 344.466418 -284.52318)
		(width 0.0889)
		(layer "In11.Cu")
		(net "UPI_CPU1_CPU0_P2P2_DP<13>")
	)
	(arc
		(start 97.46615 -285.171896)
		(mid 97.653348 -285.222039)
		(end 97.840546 -285.171896)
		(width 0.0889)
		(layer "In11.Cu")
		(net "UPI_CPU1_CPU0_P2P2_DP<13>")
	)
	(arc
		(start 95.969836 -288.422334)
		(mid 96.10075 -288.285974)
		(end 96.148398 -288.103056)
		(width 0.0889)
		(layer "In11.Cu")
		(net "UPI_CPU1_CPU0_P2P2_DP<13>")
	)
	(arc
		(start 343.047828 -288.597848)
		(mid 342.916914 -288.734208)
		(end 342.869266 -288.917126)
		(width 0.0889)
		(layer "In11.Cu")
		(net "UPI_CPU1_CPU0_P2P2_DP<13>")
	)
	(arc
		(start 95.963994 -289.446462)
		(mid 95.789862 -289.307615)
		(end 95.678498 -289.114738)
		(width 0.0889)
		(layer "In11.Cu")
		(net "UPI_CPU1_CPU0_P2P2_DP<13>")
	)
	(segment
		(start 345.123516 -281.869896)
		(end 345.123516 -282.405582)
		(width 0.13208)
		(layer "F.Cu")
		(net "UPI_CPU1_CPU0_P2P2_DP<12>")
	)
	(segment
		(start 345.123516 -282.405582)
		(end 345.123262 -282.405836)
		(width 0.13208)
		(layer "F.Cu")
		(net "UPI_CPU1_CPU0_P2P2_DP<12>")
	)
	(segment
		(start 100.472494 -281.591766)
		(end 100.472748 -281.59202)
		(width 0.13208)
		(layer "F.Cu")
		(net "UPI_CPU1_CPU0_P2P2_DP<12>")
	)
	(segment
		(start 100.472494 -281.05608)
		(end 100.472494 -281.591766)
		(width 0.13208)
		(layer "F.Cu")
		(net "UPI_CPU1_CPU0_P2P2_DP<12>")
	)
	(segment
		(start 199.25411 -378.58827)
		(end 199.586596 -378.86894)
		(width 0.14732)
		(layer "In11.Cu")
		(net "UPI_CPU1_CPU0_P2P2_DP<12>")
	)
	(segment
		(start 180.781198 -380.16307)
		(end 181.113684 -380.44374)
		(width 0.14732)
		(layer "In11.Cu")
		(net "UPI_CPU1_CPU0_P2P2_DP<12>")
	)
	(segment
		(start 342.49741 -294.595804)
		(end 342.569292 -294.234362)
		(width 0.14732)
		(layer "In11.Cu")
		(net "UPI_CPU1_CPU0_P2P2_DP<12>")
	)
	(segment
		(start 344.834718 -285.175452)
		(end 344.840814 -285.171896)
		(width 0.0889)
		(layer "In11.Cu")
		(net "UPI_CPU1_CPU0_P2P2_DP<12>")
	)
	(segment
		(start 342.96858 -291.442648)
		(end 342.96858 -291.227764)
		(width 0.0889)
		(layer "In11.Cu")
		(net "UPI_CPU1_CPU0_P2P2_DP<12>")
	)
	(segment
		(start 96.062292 -286.961326)
		(end 96.062546 -286.961072)
		(width 0.0889)
		(layer "In11.Cu")
		(net "UPI_CPU1_CPU0_P2P2_DP<12>")
	)
	(segment
		(start 93.641164 -300.607476)
		(end 78.280514 -313.212734)
		(width 0.14732)
		(layer "In11.Cu")
		(net "UPI_CPU1_CPU0_P2P2_DP<12>")
	)
	(segment
		(start 341.895938 -297.61561)
		(end 341.96782 -297.254168)
		(width 0.14732)
		(layer "In11.Cu")
		(net "UPI_CPU1_CPU0_P2P2_DP<12>")
	)
	(segment
		(start 183.090312 -379.96622)
		(end 183.422798 -380.24689)
		(width 0.14732)
		(layer "In11.Cu")
		(net "UPI_CPU1_CPU0_P2P2_DP<12>")
	)
	(segment
		(start 94.402656 -299.357796)
		(end 94.193614 -299.862748)
		(width 0.14732)
		(layer "In11.Cu")
		(net "UPI_CPU1_CPU0_P2P2_DP<12>")
	)
	(segment
		(start 269.10538 -345.78036)
		(end 280.00452 -334.88122)
		(width 0.14732)
		(layer "In11.Cu")
		(net "UPI_CPU1_CPU0_P2P2_DP<12>")
	)
	(segment
		(start 191.511682 -379.248416)
		(end 192.326768 -379.17882)
		(width 0.14732)
		(layer "In11.Cu")
		(net "UPI_CPU1_CPU0_P2P2_DP<12>")
	)
	(segment
		(start 188.805566 -380.14402)
		(end 188.939678 -379.985016)
		(width 0.14732)
		(layer "In11.Cu")
		(net "UPI_CPU1_CPU0_P2P2_DP<12>")
	)
	(segment
		(start 68.275454 -324.847966)
		(end 67.36588 -328.13371)
		(width 0.14732)
		(layer "In11.Cu")
		(net "UPI_CPU1_CPU0_P2P2_DP<12>")
	)
	(segment
		(start 96.062292 -285.33344)
		(end 96.06153 -285.333948)
		(width 0.0889)
		(layer "In11.Cu")
		(net "UPI_CPU1_CPU0_P2P2_DP<12>")
	)
	(segment
		(start 190.36792 -379.86335)
		(end 190.526924 -379.997462)
		(width 0.14732)
		(layer "In11.Cu")
		(net "UPI_CPU1_CPU0_P2P2_DP<12>")
	)
	(segment
		(start 190.526924 -379.997462)
		(end 191.11468 -379.94717)
		(width 0.14732)
		(layer "In11.Cu")
		(net "UPI_CPU1_CPU0_P2P2_DP<12>")
	)
	(segment
		(start 185.731912 -380.05004)
		(end 185.749692 -380.25705)
		(width 0.14732)
		(layer "In11.Cu")
		(net "UPI_CPU1_CPU0_P2P2_DP<12>")
	)
	(segment
		(start 343.901014 -288.427414)
		(end 343.909904 -288.422334)
		(width 0.0889)
		(layer "In11.Cu")
		(net "UPI_CPU1_CPU0_P2P2_DP<12>")
	)
	(segment
		(start 96.059752 -285.334964)
		(end 96.056958 -285.336488)
		(width 0.0889)
		(layer "In11.Cu")
		(net "UPI_CPU1_CPU0_P2P2_DP<12>")
	)
	(segment
		(start 94.562168 -299.291756)
		(end 94.402656 -299.357796)
		(width 0.14732)
		(layer "In11.Cu")
		(net "UPI_CPU1_CPU0_P2P2_DP<12>")
	)
	(segment
		(start 96.054672 -286.965644)
		(end 96.047306 -286.969962)
		(width 0.0889)
		(layer "In11.Cu")
		(net "UPI_CPU1_CPU0_P2P2_DP<12>")
	)
	(segment
		(start 336.836766 -301.80153)
		(end 340.26221 -300.383448)
		(width 0.14732)
		(layer "In11.Cu")
		(net "UPI_CPU1_CPU0_P2P2_DP<12>")
	)
	(segment
		(start 192.326768 -379.17882)
		(end 192.659254 -379.45949)
		(width 0.14732)
		(layer "In11.Cu")
		(net "UPI_CPU1_CPU0_P2P2_DP<12>")
	)
	(segment
		(start 342.781636 -292.476682)
		(end 342.781636 -292.108382)
		(width 0.14732)
		(layer "In11.Cu")
		(net "UPI_CPU1_CPU0_P2P2_DP<12>")
	)
	(segment
		(start 195.86702 -379.394466)
		(end 195.84924 -379.187456)
		(width 0.14732)
		(layer "In11.Cu")
		(net "UPI_CPU1_CPU0_P2P2_DP<12>")
	)
	(segment
		(start 341.541354 -299.104304)
		(end 341.937848 -298.146978)
		(width 0.14732)
		(layer "In11.Cu")
		(net "UPI_CPU1_CPU0_P2P2_DP<12>")
	)
	(segment
		(start 99.627944 -282.405836)
		(end 99.627944 -282.427934)
		(width 0.0889)
		(layer "In11.Cu")
		(net "UPI_CPU1_CPU0_P2P2_DP<12>")
	)
	(segment
		(start 100.472748 -281.59202)
		(end 100.160074 -281.59202)
		(width 0.0889)
		(layer "In11.Cu")
		(net "UPI_CPU1_CPU0_P2P2_DP<12>")
	)
	(segment
		(start 99.82073 -282.07843)
		(end 99.819714 -282.078938)
		(width 0.0889)
		(layer "In11.Cu")
		(net "UPI_CPU1_CPU0_P2P2_DP<12>")
	)
	(segment
		(start 344.8431 -286.798258)
		(end 344.843862 -286.79775)
		(width 0.0889)
		(layer "In11.Cu")
		(net "UPI_CPU1_CPU0_P2P2_DP<12>")
	)
	(segment
		(start 179.56911 -380.93142)
		(end 179.703222 -380.772416)
		(width 0.14732)
		(layer "In11.Cu")
		(net "UPI_CPU1_CPU0_P2P2_DP<12>")
	)
	(segment
		(start 280.00452 -334.88122)
		(end 285.39186 -332.64983)
		(width 0.14732)
		(layer "In11.Cu")
		(net "UPI_CPU1_CPU0_P2P2_DP<12>")
	)
	(segment
		(start 179.685442 -380.565406)
		(end 179.966112 -380.232666)
		(width 0.14732)
		(layer "In11.Cu")
		(net "UPI_CPU1_CPU0_P2P2_DP<12>")
	)
	(segment
		(start 198.158354 -378.990606)
		(end 198.439024 -378.657866)
		(width 0.14732)
		(layer "In11.Cu")
		(net "UPI_CPU1_CPU0_P2P2_DP<12>")
	)
	(segment
		(start 96.915478 -284.531816)
		(end 96.900746 -284.52318)
		(width 0.0889)
		(layer "In11.Cu")
		(net "UPI_CPU1_CPU0_P2P2_DP<12>")
	)
	(segment
		(start 186.630564 -380.181866)
		(end 186.612784 -379.974856)
		(width 0.14732)
		(layer "In11.Cu")
		(net "UPI_CPU1_CPU0_P2P2_DP<12>")
	)
	(segment
		(start 342.168226 -296.247566)
		(end 342.338914 -296.133774)
		(width 0.14732)
		(layer "In11.Cu")
		(net "UPI_CPU1_CPU0_P2P2_DP<12>")
	)
	(segment
		(start 187.70854 -379.57252)
		(end 188.041026 -379.85319)
		(width 0.14732)
		(layer "In11.Cu")
		(net "UPI_CPU1_CPU0_P2P2_DP<12>")
	)
	(segment
		(start 96.06153 -285.333948)
		(end 96.060514 -285.334456)
		(width 0.0889)
		(layer "In11.Cu")
		(net "UPI_CPU1_CPU0_P2P2_DP<12>")
	)
	(segment
		(start 342.338914 -296.133774)
		(end 342.410796 -295.772586)
		(width 0.14732)
		(layer "In11.Cu")
		(net "UPI_CPU1_CPU0_P2P2_DP<12>")
	)
	(segment
		(start 186.496452 -380.34087)
		(end 186.630564 -380.181866)
		(width 0.14732)
		(layer "In11.Cu")
		(net "UPI_CPU1_CPU0_P2P2_DP<12>")
	)
	(segment
		(start 181.113684 -380.44374)
		(end 181.131464 -380.65075)
		(width 0.14732)
		(layer "In11.Cu")
		(net "UPI_CPU1_CPU0_P2P2_DP<12>")
	)
	(segment
		(start 345.497912 -284.033722)
		(end 345.497912 -284.023816)
		(width 0.0889)
		(layer "In11.Cu")
		(net "UPI_CPU1_CPU0_P2P2_DP<12>")
	)
	(segment
		(start 183.422798 -380.24689)
		(end 183.440578 -380.4539)
		(width 0.14732)
		(layer "In11.Cu")
		(net "UPI_CPU1_CPU0_P2P2_DP<12>")
	)
	(segment
		(start 182.275226 -380.035816)
		(end 183.090312 -379.96622)
		(width 0.14732)
		(layer "In11.Cu")
		(net "UPI_CPU1_CPU0_P2P2_DP<12>")
	)
	(segment
		(start 181.878224 -380.73457)
		(end 182.012336 -380.575566)
		(width 0.14732)
		(layer "In11.Cu")
		(net "UPI_CPU1_CPU0_P2P2_DP<12>")
	)
	(segment
		(start 96.975676 -378.155454)
		(end 125.76302 -382.425448)
		(width 0.14732)
		(layer "In11.Cu")
		(net "UPI_CPU1_CPU0_P2P2_DP<12>")
	)
	(segment
		(start 191.248792 -379.788166)
		(end 191.231012 -379.581156)
		(width 0.14732)
		(layer "In11.Cu")
		(net "UPI_CPU1_CPU0_P2P2_DP<12>")
	)
	(segment
		(start 185.749692 -380.25705)
		(end 185.908696 -380.391162)
		(width 0.14732)
		(layer "In11.Cu")
		(net "UPI_CPU1_CPU0_P2P2_DP<12>")
	)
	(segment
		(start 96.056958 -285.336488)
		(end 96.056196 -285.336996)
		(width 0.0889)
		(layer "In11.Cu")
		(net "UPI_CPU1_CPU0_P2P2_DP<12>")
	)
	(segment
		(start 267.98016 -367.019332)
		(end 267.98016 -366.846866)
		(width 0.14732)
		(layer "In11.Cu")
		(net "UPI_CPU1_CPU0_P2P2_DP<12>")
	)
	(segment
		(start 188.21781 -380.194312)
		(end 188.805566 -380.14402)
		(width 0.14732)
		(layer "In11.Cu")
		(net "UPI_CPU1_CPU0_P2P2_DP<12>")
	)
	(segment
		(start 342.96858 -291.227764)
		(end 344.088466 -290.107878)
		(width 0.0889)
		(layer "In11.Cu")
		(net "UPI_CPU1_CPU0_P2P2_DP<12>")
	)
	(segment
		(start 344.841322 -286.799274)
		(end 344.8431 -286.798258)
		(width 0.0889)
		(layer "In11.Cu")
		(net "UPI_CPU1_CPU0_P2P2_DP<12>")
	)
	(segment
		(start 188.939678 -379.985016)
		(end 188.921898 -379.778006)
		(width 0.14732)
		(layer "In11.Cu")
		(net "UPI_CPU1_CPU0_P2P2_DP<12>")
	)
	(segment
		(start 193.540126 -379.384306)
		(end 193.820796 -379.051566)
		(width 0.14732)
		(layer "In11.Cu")
		(net "UPI_CPU1_CPU0_P2P2_DP<12>")
	)
	(segment
		(start 340.26221 -300.383448)
		(end 341.541354 -299.104304)
		(width 0.14732)
		(layer "In11.Cu")
		(net "UPI_CPU1_CPU0_P2P2_DP<12>")
	)
	(segment
		(start 195.145152 -379.603762)
		(end 195.732908 -379.55347)
		(width 0.14732)
		(layer "In11.Cu")
		(net "UPI_CPU1_CPU0_P2P2_DP<12>")
	)
	(segment
		(start 94.7293 -298.887896)
		(end 94.562168 -299.291756)
		(width 0.14732)
		(layer "In11.Cu")
		(net "UPI_CPU1_CPU0_P2P2_DP<12>")
	)
	(segment
		(start 344.558112 -287.28924)
		(end 344.558112 -287.279334)
		(width 0.0889)
		(layer "In11.Cu")
		(net "UPI_CPU1_CPU0_P2P2_DP<12>")
	)
	(segment
		(start 99.816158 -282.08097)
		(end 99.815396 -282.081478)
		(width 0.0889)
		(layer "In11.Cu")
		(net "UPI_CPU1_CPU0_P2P2_DP<12>")
	)
	(segment
		(start 197.454266 -379.406912)
		(end 198.042022 -379.35662)
		(width 0.14732)
		(layer "In11.Cu")
		(net "UPI_CPU1_CPU0_P2P2_DP<12>")
	)
	(segment
		(start 197.277482 -379.06579)
		(end 197.295262 -379.2728)
		(width 0.14732)
		(layer "In11.Cu")
		(net "UPI_CPU1_CPU0_P2P2_DP<12>")
	)
	(segment
		(start 99.818952 -282.079446)
		(end 99.816158 -282.08097)
		(width 0.0889)
		(layer "In11.Cu")
		(net "UPI_CPU1_CPU0_P2P2_DP<12>")
	)
	(segment
		(start 196.12991 -378.854716)
		(end 196.944996 -378.78512)
		(width 0.14732)
		(layer "In11.Cu")
		(net "UPI_CPU1_CPU0_P2P2_DP<12>")
	)
	(segment
		(start 342.368886 -295.240964)
		(end 342.53932 -295.127172)
		(width 0.14732)
		(layer "In11.Cu")
		(net "UPI_CPU1_CPU0_P2P2_DP<12>")
	)
	(segment
		(start 95.399098 -288.103056)
		(end 95.399098 -288.121598)
		(width 0.0889)
		(layer "In11.Cu")
		(net "UPI_CPU1_CPU0_P2P2_DP<12>")
	)
	(segment
		(start 314.807092 -323.831204)
		(end 336.836766 -301.80153)
		(width 0.14732)
		(layer "In11.Cu")
		(net "UPI_CPU1_CPU0_P2P2_DP<12>")
	)
	(segment
		(start 184.58434 -379.838966)
		(end 185.399426 -379.76937)
		(width 0.14732)
		(layer "In11.Cu")
		(net "UPI_CPU1_CPU0_P2P2_DP<12>")
	)
	(segment
		(start 342.297004 -295.602406)
		(end 342.368886 -295.240964)
		(width 0.14732)
		(layer "In11.Cu")
		(net "UPI_CPU1_CPU0_P2P2_DP<12>")
	)
	(segment
		(start 100.160074 -281.59202)
		(end 100.094288 -281.657806)
		(width 0.0889)
		(layer "In11.Cu")
		(net "UPI_CPU1_CPU0_P2P2_DP<12>")
	)
	(segment
		(start 99.808538 -282.085288)
		(end 99.806506 -282.086558)
		(width 0.0889)
		(layer "In11.Cu")
		(net "UPI_CPU1_CPU0_P2P2_DP<12>")
	)
	(segment
		(start 96.056196 -285.336996)
		(end 96.049338 -285.340806)
		(width 0.0889)
		(layer "In11.Cu")
		(net "UPI_CPU1_CPU0_P2P2_DP<12>")
	)
	(segment
		(start 344.840814 -285.171896)
		(end 344.849704 -285.166816)
		(width 0.0889)
		(layer "In11.Cu")
		(net "UPI_CPU1_CPU0_P2P2_DP<12>")
	)
	(segment
		(start 345.31046 -284.35808)
		(end 345.31935 -284.353)
		(width 0.0889)
		(layer "In11.Cu")
		(net "UPI_CPU1_CPU0_P2P2_DP<12>")
	)
	(segment
		(start 95.440754 -290.796726)
		(end 95.440754 -296.880026)
		(width 0.14732)
		(layer "In11.Cu")
		(net "UPI_CPU1_CPU0_P2P2_DP<12>")
	)
	(segment
		(start 95.440754 -296.880026)
		(end 95.419926 -296.900854)
		(width 0.14732)
		(layer "In11.Cu")
		(net "UPI_CPU1_CPU0_P2P2_DP<12>")
	)
	(segment
		(start 190.017654 -379.37567)
		(end 190.35014 -379.65634)
		(width 0.14732)
		(layer "In11.Cu")
		(net "UPI_CPU1_CPU0_P2P2_DP<12>")
	)
	(segment
		(start 95.398844 -290.732718)
		(end 95.440754 -290.774628)
		(width 0.0889)
		(layer "In11.Cu")
		(net "UPI_CPU1_CPU0_P2P2_DP<12>")
	)
	(segment
		(start 198.176134 -379.197616)
		(end 198.158354 -378.990606)
		(width 0.14732)
		(layer "In11.Cu")
		(net "UPI_CPU1_CPU0_P2P2_DP<12>")
	)
	(segment
		(start 344.088466 -290.107878)
		(end 344.088466 -289.64509)
		(width 0.0889)
		(layer "In11.Cu")
		(net "UPI_CPU1_CPU0_P2P2_DP<12>")
	)
	(segment
		(start 344.37066 -287.613598)
		(end 344.37955 -287.608518)
		(width 0.0889)
		(layer "In11.Cu")
		(net "UPI_CPU1_CPU0_P2P2_DP<12>")
	)
	(segment
		(start 195.732908 -379.55347)
		(end 195.86702 -379.394466)
		(width 0.14732)
		(layer "In11.Cu")
		(net "UPI_CPU1_CPU0_P2P2_DP<12>")
	)
	(segment
		(start 342.00973 -297.78579)
		(end 341.895938 -297.61561)
		(width 0.14732)
		(layer "In11.Cu")
		(net "UPI_CPU1_CPU0_P2P2_DP<12>")
	)
	(segment
		(start 96.060514 -285.334456)
		(end 96.059752 -285.334964)
		(width 0.0889)
		(layer "In11.Cu")
		(net "UPI_CPU1_CPU0_P2P2_DP<12>")
	)
	(segment
		(start 341.96782 -297.254168)
		(end 342.138254 -297.140376)
		(width 0.14732)
		(layer "In11.Cu")
		(net "UPI_CPU1_CPU0_P2P2_DP<12>")
	)
	(segment
		(start 268.289278 -366.537748)
		(end 268.461744 -366.537748)
		(width 0.14732)
		(layer "In11.Cu")
		(net "UPI_CPU1_CPU0_P2P2_DP<12>")
	)
	(segment
		(start 179.703222 -380.772416)
		(end 179.685442 -380.565406)
		(width 0.14732)
		(layer "In11.Cu")
		(net "UPI_CPU1_CPU0_P2P2_DP<12>")
	)
	(segment
		(start 345.78925 -282.900628)
		(end 345.78036 -282.895548)
		(width 0.0889)
		(layer "In11.Cu")
		(net "UPI_CPU1_CPU0_P2P2_DP<12>")
	)
	(segment
		(start 96.338898 -286.4612)
		(end 96.338898 -286.475424)
		(width 0.0889)
		(layer "In11.Cu")
		(net "UPI_CPU1_CPU0_P2P2_DP<12>")
	)
	(segment
		(start 189.202568 -379.445266)
		(end 190.017654 -379.37567)
		(width 0.14732)
		(layer "In11.Cu")
		(net "UPI_CPU1_CPU0_P2P2_DP<12>")
	)
	(segment
		(start 199.586596 -378.86894)
		(end 199.604376 -379.07595)
		(width 0.14732)
		(layer "In11.Cu")
		(net "UPI_CPU1_CPU0_P2P2_DP<12>")
	)
	(segment
		(start 342.611202 -294.765984)
		(end 342.49741 -294.595804)
		(width 0.14732)
		(layer "In11.Cu")
		(net "UPI_CPU1_CPU0_P2P2_DP<12>")
	)
	(segment
		(start 342.410796 -295.772586)
		(end 342.297004 -295.602406)
		(width 0.14732)
		(layer "In11.Cu")
		(net "UPI_CPU1_CPU0_P2P2_DP<12>")
	)
	(segment
		(start 96.062546 -286.961072)
		(end 96.056196 -286.964882)
		(width 0.0889)
		(layer "In11.Cu")
		(net "UPI_CPU1_CPU0_P2P2_DP<12>")
	)
	(segment
		(start 341.937848 -298.146978)
		(end 342.00973 -297.78579)
		(width 0.14732)
		(layer "In11.Cu")
		(net "UPI_CPU1_CPU0_P2P2_DP<12>")
	)
	(segment
		(start 342.926416 -291.595302)
		(end 342.92667 -291.595048)
		(width 0.14732)
		(layer "In11.Cu")
		(net "UPI_CPU1_CPU0_P2P2_DP<12>")
	)
	(segment
		(start 184.187338 -380.53772)
		(end 184.32145 -380.378716)
		(width 0.14732)
		(layer "In11.Cu")
		(net "UPI_CPU1_CPU0_P2P2_DP<12>")
	)
	(segment
		(start 193.557906 -379.591316)
		(end 193.540126 -379.384306)
		(width 0.14732)
		(layer "In11.Cu")
		(net "UPI_CPU1_CPU0_P2P2_DP<12>")
	)
	(segment
		(start 96.049338 -285.340806)
		(end 96.047306 -285.342076)
		(width 0.0889)
		(layer "In11.Cu")
		(net "UPI_CPU1_CPU0_P2P2_DP<12>")
	)
	(segment
		(start 95.019876 -298.186348)
		(end 94.860364 -298.252388)
		(width 0.14732)
		(layer "In11.Cu")
		(net "UPI_CPU1_CPU0_P2P2_DP<12>")
	)
	(segment
		(start 192.659254 -379.45949)
		(end 192.677034 -379.6665)
		(width 0.14732)
		(layer "In11.Cu")
		(net "UPI_CPU1_CPU0_P2P2_DP<12>")
	)
	(segment
		(start 95.11665 -288.592768)
		(end 95.10776 -288.597848)
		(width 0.0889)
		(layer "In11.Cu")
		(net "UPI_CPU1_CPU0_P2P2_DP<12>")
	)
	(segment
		(start 95.419926 -296.900854)
		(end 95.120968 -297.62323)
		(width 0.14732)
		(layer "In11.Cu")
		(net "UPI_CPU1_CPU0_P2P2_DP<12>")
	)
	(segment
		(start 188.921898 -379.778006)
		(end 189.202568 -379.445266)
		(width 0.14732)
		(layer "In11.Cu")
		(net "UPI_CPU1_CPU0_P2P2_DP<12>")
	)
	(segment
		(start 66.709798 -334.797146)
		(end 66.709798 -354.174552)
		(width 0.14732)
		(layer "In11.Cu")
		(net "UPI_CPU1_CPU0_P2P2_DP<12>")
	)
	(segment
		(start 192.677034 -379.6665)
		(end 192.836038 -379.800612)
		(width 0.14732)
		(layer "In11.Cu")
		(net "UPI_CPU1_CPU0_P2P2_DP<12>")
	)
	(segment
		(start 342.739726 -294.12057)
		(end 342.926416 -293.182548)
		(width 0.14732)
		(layer "In11.Cu")
		(net "UPI_CPU1_CPU0_P2P2_DP<12>")
	)
	(segment
		(start 95.398844 -289.609276)
		(end 95.398844 -290.732718)
		(width 0.0889)
		(layer "In11.Cu")
		(net "UPI_CPU1_CPU0_P2P2_DP<12>")
	)
	(segment
		(start 192.836038 -379.800612)
		(end 193.423794 -379.75032)
		(width 0.14732)
		(layer "In11.Cu")
		(net "UPI_CPU1_CPU0_P2P2_DP<12>")
	)
	(segment
		(start 342.926416 -292.621462)
		(end 342.781636 -292.476682)
		(width 0.14732)
		(layer "In11.Cu")
		(net "UPI_CPU1_CPU0_P2P2_DP<12>")
	)
	(segment
		(start 66.709798 -354.174552)
		(end 71.203566 -365.023908)
		(width 0.14732)
		(layer "In11.Cu")
		(net "UPI_CPU1_CPU0_P2P2_DP<12>")
	)
	(segment
		(start 344.088466 -288.103056)
		(end 344.088466 -288.087562)
		(width 0.0889)
		(layer "In11.Cu")
		(net "UPI_CPU1_CPU0_P2P2_DP<12>")
	)
	(segment
		(start 98.887788 -283.702252)
		(end 98.875596 -283.709364)
		(width 0.0889)
		(layer "In11.Cu")
		(net "UPI_CPU1_CPU0_P2P2_DP<12>")
	)
	(segment
		(start 313.70778 -326.484996)
		(end 314.807092 -323.831204)
		(width 0.14732)
		(layer "In11.Cu")
		(net "UPI_CPU1_CPU0_P2P2_DP<12>")
	)
	(segment
		(start 267.98016 -366.846866)
		(end 268.289278 -366.537748)
		(width 0.14732)
		(layer "In11.Cu")
		(net "UPI_CPU1_CPU0_P2P2_DP<12>")
	)
	(segment
		(start 95.120968 -297.62323)
		(end 95.187008 -297.782488)
		(width 0.14732)
		(layer "In11.Cu")
		(net "UPI_CPU1_CPU0_P2P2_DP<12>")
	)
	(segment
		(start 342.781636 -292.108382)
		(end 342.926416 -291.963602)
		(width 0.14732)
		(layer "In11.Cu")
		(net "UPI_CPU1_CPU0_P2P2_DP<12>")
	)
	(segment
		(start 191.11468 -379.94717)
		(end 191.248792 -379.788166)
		(width 0.14732)
		(layer "In11.Cu")
		(net "UPI_CPU1_CPU0_P2P2_DP<12>")
	)
	(segment
		(start 342.926416 -291.963602)
		(end 342.926416 -291.595302)
		(width 0.14732)
		(layer "In11.Cu")
		(net "UPI_CPU1_CPU0_P2P2_DP<12>")
	)
	(segment
		(start 96.047306 -285.980632)
		(end 96.056196 -285.985712)
		(width 0.0889)
		(layer "In11.Cu")
		(net "UPI_CPU1_CPU0_P2P2_DP<12>")
	)
	(segment
		(start 199.76338 -379.210062)
		(end 261.005828 -373.993664)
		(width 0.14732)
		(layer "In11.Cu")
		(net "UPI_CPU1_CPU0_P2P2_DP<12>")
	)
	(segment
		(start 94.860364 -298.252388)
		(end 94.66326 -298.728638)
		(width 0.14732)
		(layer "In11.Cu")
		(net "UPI_CPU1_CPU0_P2P2_DP<12>")
	)
	(segment
		(start 345.028266 -284.847538)
		(end 345.028266 -284.832044)
		(width 0.0889)
		(layer "In11.Cu")
		(net "UPI_CPU1_CPU0_P2P2_DP<12>")
	)
	(segment
		(start 75.397614 -369.217956)
		(end 96.975676 -378.155454)
		(width 0.14732)
		(layer "In11.Cu")
		(net "UPI_CPU1_CPU0_P2P2_DP<12>")
	)
	(segment
		(start 345.78036 -283.544264)
		(end 345.78925 -283.539184)
		(width 0.0889)
		(layer "In11.Cu")
		(net "UPI_CPU1_CPU0_P2P2_DP<12>")
	)
	(segment
		(start 186.893454 -379.642116)
		(end 187.70854 -379.57252)
		(width 0.14732)
		(layer "In11.Cu")
		(net "UPI_CPU1_CPU0_P2P2_DP<12>")
	)
	(segment
		(start 195.84924 -379.187456)
		(end 196.12991 -378.854716)
		(width 0.14732)
		(layer "In11.Cu")
		(net "UPI_CPU1_CPU0_P2P2_DP<12>")
	)
	(segment
		(start 162.008058 -382.425448)
		(end 179.56911 -380.93142)
		(width 0.14732)
		(layer "In11.Cu")
		(net "UPI_CPU1_CPU0_P2P2_DP<12>")
	)
	(segment
		(start 181.290468 -380.784862)
		(end 181.878224 -380.73457)
		(width 0.14732)
		(layer "In11.Cu")
		(net "UPI_CPU1_CPU0_P2P2_DP<12>")
	)
	(segment
		(start 342.138254 -297.140376)
		(end 342.210136 -296.779188)
		(width 0.14732)
		(layer "In11.Cu")
		(net "UPI_CPU1_CPU0_P2P2_DP<12>")
	)
	(segment
		(start 344.84945 -286.156146)
		(end 344.841322 -286.151574)
		(width 0.0889)
		(layer "In11.Cu")
		(net "UPI_CPU1_CPU0_P2P2_DP<12>")
	)
	(segment
		(start 194.968368 -379.26264)
		(end 194.986148 -379.46965)
		(width 0.14732)
		(layer "In11.Cu")
		(net "UPI_CPU1_CPU0_P2P2_DP<12>")
	)
	(segment
		(start 199.604376 -379.07595)
		(end 199.76338 -379.210062)
		(width 0.14732)
		(layer "In11.Cu")
		(net "UPI_CPU1_CPU0_P2P2_DP<12>")
	)
	(segment
		(start 342.569292 -294.234362)
		(end 342.739726 -294.12057)
		(width 0.14732)
		(layer "In11.Cu")
		(net "UPI_CPU1_CPU0_P2P2_DP<12>")
	)
	(segment
		(start 69.737478 -321.756024)
		(end 68.275454 -324.847966)
		(width 0.14732)
		(layer "In11.Cu")
		(net "UPI_CPU1_CPU0_P2P2_DP<12>")
	)
	(segment
		(start 268.461744 -366.537748)
		(end 269.10538 -365.894112)
		(width 0.14732)
		(layer "In11.Cu")
		(net "UPI_CPU1_CPU0_P2P2_DP<12>")
	)
	(segment
		(start 343.618566 -289.113722)
		(end 343.618566 -288.898584)
		(width 0.0889)
		(layer "In11.Cu")
		(net "UPI_CPU1_CPU0_P2P2_DP<12>")
	)
	(segment
		(start 342.53932 -295.127172)
		(end 342.611202 -294.765984)
		(width 0.14732)
		(layer "In11.Cu")
		(net "UPI_CPU1_CPU0_P2P2_DP<12>")
	)
	(segment
		(start 94.193614 -299.862748)
		(end 93.641164 -300.607476)
		(width 0.14732)
		(layer "In11.Cu")
		(net "UPI_CPU1_CPU0_P2P2_DP<12>")
	)
	(segment
		(start 96.056196 -286.964882)
		(end 96.054672 -286.965644)
		(width 0.0889)
		(layer "In11.Cu")
		(net "UPI_CPU1_CPU0_P2P2_DP<12>")
	)
	(segment
		(start 96.52635 -284.52318)
		(end 96.51746 -284.52826)
		(width 0.0889)
		(layer "In11.Cu")
		(net "UPI_CPU1_CPU0_P2P2_DP<12>")
	)
	(segment
		(start 307.542946 -332.64983)
		(end 313.70778 -326.484996)
		(width 0.14732)
		(layer "In11.Cu")
		(net "UPI_CPU1_CPU0_P2P2_DP<12>")
	)
	(segment
		(start 344.841322 -286.151574)
		(end 344.84056 -286.151066)
		(width 0.0889)
		(layer "In11.Cu")
		(net "UPI_CPU1_CPU0_P2P2_DP<12>")
	)
	(segment
		(start 342.210136 -296.779188)
		(end 342.096344 -296.609008)
		(width 0.14732)
		(layer "In11.Cu")
		(net "UPI_CPU1_CPU0_P2P2_DP<12>")
	)
	(segment
		(start 342.096344 -296.609008)
		(end 342.168226 -296.247566)
		(width 0.14732)
		(layer "In11.Cu")
		(net "UPI_CPU1_CPU0_P2P2_DP<12>")
	)
	(segment
		(start 344.558112 -285.679896)
		(end 344.558112 -285.661354)
		(width 0.0889)
		(layer "In11.Cu")
		(net "UPI_CPU1_CPU0_P2P2_DP<12>")
	)
	(segment
		(start 197.295262 -379.2728)
		(end 197.454266 -379.406912)
		(width 0.14732)
		(layer "In11.Cu")
		(net "UPI_CPU1_CPU0_P2P2_DP<12>")
	)
	(segment
		(start 182.012336 -380.575566)
		(end 181.994556 -380.368556)
		(width 0.14732)
		(layer "In11.Cu")
		(net "UPI_CPU1_CPU0_P2P2_DP<12>")
	)
	(segment
		(start 99.821492 -282.077922)
		(end 99.82073 -282.07843)
		(width 0.0889)
		(layer "In11.Cu")
		(net "UPI_CPU1_CPU0_P2P2_DP<12>")
	)
	(segment
		(start 97.748344 -284.033722)
		(end 97.748344 -284.049216)
		(width 0.0889)
		(layer "In11.Cu")
		(net "UPI_CPU1_CPU0_P2P2_DP<12>")
	)
	(segment
		(start 186.612784 -379.974856)
		(end 186.893454 -379.642116)
		(width 0.14732)
		(layer "In11.Cu")
		(net "UPI_CPU1_CPU0_P2P2_DP<12>")
	)
	(segment
		(start 71.203566 -365.023908)
		(end 75.397614 -369.217956)
		(width 0.14732)
		(layer "In11.Cu")
		(net "UPI_CPU1_CPU0_P2P2_DP<12>")
	)
	(segment
		(start 285.39186 -332.64983)
		(end 307.542946 -332.64983)
		(width 0.14732)
		(layer "In11.Cu")
		(net "UPI_CPU1_CPU0_P2P2_DP<12>")
	)
	(segment
		(start 184.32145 -380.378716)
		(end 184.30367 -380.171706)
		(width 0.14732)
		(layer "In11.Cu")
		(net "UPI_CPU1_CPU0_P2P2_DP<12>")
	)
	(segment
		(start 194.635882 -378.98197)
		(end 194.968368 -379.26264)
		(width 0.14732)
		(layer "In11.Cu")
		(net "UPI_CPU1_CPU0_P2P2_DP<12>")
	)
	(segment
		(start 185.399426 -379.76937)
		(end 185.731912 -380.05004)
		(width 0.14732)
		(layer "In11.Cu")
		(net "UPI_CPU1_CPU0_P2P2_DP<12>")
	)
	(segment
		(start 343.61882 -289.113976)
		(end 343.618566 -289.113722)
		(width 0.0889)
		(layer "In11.Cu")
		(net "UPI_CPU1_CPU0_P2P2_DP<12>")
	)
	(segment
		(start 188.041026 -379.85319)
		(end 188.058806 -380.0602)
		(width 0.14732)
		(layer "In11.Cu")
		(net "UPI_CPU1_CPU0_P2P2_DP<12>")
	)
	(segment
		(start 95.187008 -297.782488)
		(end 95.019876 -298.186348)
		(width 0.14732)
		(layer "In11.Cu")
		(net "UPI_CPU1_CPU0_P2P2_DP<12>")
	)
	(segment
		(start 342.92667 -291.595048)
		(end 342.92667 -291.506656)
		(width 0.14732)
		(layer "In11.Cu")
		(net "UPI_CPU1_CPU0_P2P2_DP<12>")
	)
	(segment
		(start 181.994556 -380.368556)
		(end 182.275226 -380.035816)
		(width 0.14732)
		(layer "In11.Cu")
		(net "UPI_CPU1_CPU0_P2P2_DP<12>")
	)
	(segment
		(start 194.986148 -379.46965)
		(end 195.145152 -379.603762)
		(width 0.14732)
		(layer "In11.Cu")
		(net "UPI_CPU1_CPU0_P2P2_DP<12>")
	)
	(segment
		(start 193.423794 -379.75032)
		(end 193.557906 -379.591316)
		(width 0.14732)
		(layer "In11.Cu")
		(net "UPI_CPU1_CPU0_P2P2_DP<12>")
	)
	(segment
		(start 97.935796 -283.709364)
		(end 97.926906 -283.714444)
		(width 0.0889)
		(layer "In11.Cu")
		(net "UPI_CPU1_CPU0_P2P2_DP<12>")
	)
	(segment
		(start 344.84056 -286.799782)
		(end 344.841322 -286.799274)
		(width 0.0889)
		(layer "In11.Cu")
		(net "UPI_CPU1_CPU0_P2P2_DP<12>")
	)
	(segment
		(start 342.926416 -293.182548)
		(end 342.926416 -292.621462)
		(width 0.14732)
		(layer "In11.Cu")
		(net "UPI_CPU1_CPU0_P2P2_DP<12>")
	)
	(segment
		(start 198.439024 -378.657866)
		(end 199.25411 -378.58827)
		(width 0.14732)
		(layer "In11.Cu")
		(net "UPI_CPU1_CPU0_P2P2_DP<12>")
	)
	(segment
		(start 198.042022 -379.35662)
		(end 198.176134 -379.197616)
		(width 0.14732)
		(layer "In11.Cu")
		(net "UPI_CPU1_CPU0_P2P2_DP<12>")
	)
	(segment
		(start 99.815396 -282.081478)
		(end 99.808538 -282.085288)
		(width 0.0889)
		(layer "In11.Cu")
		(net "UPI_CPU1_CPU0_P2P2_DP<12>")
	)
	(segment
		(start 345.501214 -282.471114)
		(end 345.435936 -282.405836)
		(width 0.0889)
		(layer "In11.Cu")
		(net "UPI_CPU1_CPU0_P2P2_DP<12>")
	)
	(segment
		(start 95.440754 -290.774628)
		(end 95.440754 -290.796726)
		(width 0.0889)
		(layer "In11.Cu")
		(net "UPI_CPU1_CPU0_P2P2_DP<12>")
	)
	(segment
		(start 99.34575 -282.895548)
		(end 99.33686 -282.900628)
		(width 0.0889)
		(layer "In11.Cu")
		(net "UPI_CPU1_CPU0_P2P2_DP<12>")
	)
	(segment
		(start 191.231012 -379.581156)
		(end 191.511682 -379.248416)
		(width 0.14732)
		(layer "In11.Cu")
		(net "UPI_CPU1_CPU0_P2P2_DP<12>")
	)
	(segment
		(start 190.35014 -379.65634)
		(end 190.36792 -379.86335)
		(width 0.14732)
		(layer "In11.Cu")
		(net "UPI_CPU1_CPU0_P2P2_DP<12>")
	)
	(segment
		(start 95.58655 -287.778698)
		(end 95.57766 -287.783778)
		(width 0.0889)
		(layer "In11.Cu")
		(net "UPI_CPU1_CPU0_P2P2_DP<12>")
	)
	(segment
		(start 342.92667 -291.506656)
		(end 342.92667 -291.484558)
		(width 0.0889)
		(layer "In11.Cu")
		(net "UPI_CPU1_CPU0_P2P2_DP<12>")
	)
	(segment
		(start 196.944996 -378.78512)
		(end 197.277482 -379.06579)
		(width 0.14732)
		(layer "In11.Cu")
		(net "UPI_CPU1_CPU0_P2P2_DP<12>")
	)
	(segment
		(start 67.36588 -328.13371)
		(end 66.709798 -334.797146)
		(width 0.14732)
		(layer "In11.Cu")
		(net "UPI_CPU1_CPU0_P2P2_DP<12>")
	)
	(segment
		(start 342.92667 -291.484558)
		(end 342.96858 -291.442648)
		(width 0.0889)
		(layer "In11.Cu")
		(net "UPI_CPU1_CPU0_P2P2_DP<12>")
	)
	(segment
		(start 193.820796 -379.051566)
		(end 194.635882 -378.98197)
		(width 0.14732)
		(layer "In11.Cu")
		(net "UPI_CPU1_CPU0_P2P2_DP<12>")
	)
	(segment
		(start 95.868744 -287.28924)
		(end 95.868744 -287.304734)
		(width 0.0889)
		(layer "In11.Cu")
		(net "UPI_CPU1_CPU0_P2P2_DP<12>")
	)
	(segment
		(start 344.843862 -286.79775)
		(end 344.84945 -286.794702)
		(width 0.0889)
		(layer "In11.Cu")
		(net "UPI_CPU1_CPU0_P2P2_DP<12>")
	)
	(segment
		(start 261.005828 -373.993664)
		(end 267.98016 -367.019332)
		(width 0.14732)
		(layer "In11.Cu")
		(net "UPI_CPU1_CPU0_P2P2_DP<12>")
	)
	(segment
		(start 269.10538 -365.894112)
		(end 269.10538 -345.78036)
		(width 0.14732)
		(layer "In11.Cu")
		(net "UPI_CPU1_CPU0_P2P2_DP<12>")
	)
	(segment
		(start 179.966112 -380.232666)
		(end 180.781198 -380.16307)
		(width 0.14732)
		(layer "In11.Cu")
		(net "UPI_CPU1_CPU0_P2P2_DP<12>")
	)
	(segment
		(start 181.131464 -380.65075)
		(end 181.290468 -380.784862)
		(width 0.14732)
		(layer "In11.Cu")
		(net "UPI_CPU1_CPU0_P2P2_DP<12>")
	)
	(segment
		(start 94.66326 -298.728638)
		(end 94.7293 -298.887896)
		(width 0.14732)
		(layer "In11.Cu")
		(net "UPI_CPU1_CPU0_P2P2_DP<12>")
	)
	(segment
		(start 78.280514 -313.212734)
		(end 69.737478 -321.756024)
		(width 0.14732)
		(layer "In11.Cu")
		(net "UPI_CPU1_CPU0_P2P2_DP<12>")
	)
	(segment
		(start 183.599582 -380.588012)
		(end 184.187338 -380.53772)
		(width 0.14732)
		(layer "In11.Cu")
		(net "UPI_CPU1_CPU0_P2P2_DP<12>")
	)
	(segment
		(start 184.30367 -380.171706)
		(end 184.58434 -379.838966)
		(width 0.14732)
		(layer "In11.Cu")
		(net "UPI_CPU1_CPU0_P2P2_DP<12>")
	)
	(segment
		(start 94.929198 -288.917126)
		(end 94.929198 -289.078416)
		(width 0.0889)
		(layer "In11.Cu")
		(net "UPI_CPU1_CPU0_P2P2_DP<12>")
	)
	(segment
		(start 185.908696 -380.391162)
		(end 186.496452 -380.34087)
		(width 0.14732)
		(layer "In11.Cu")
		(net "UPI_CPU1_CPU0_P2P2_DP<12>")
	)
	(segment
		(start 125.76302 -382.425448)
		(end 162.008058 -382.425448)
		(width 0.14732)
		(layer "In11.Cu")
		(net "UPI_CPU1_CPU0_P2P2_DP<12>")
	)
	(segment
		(start 183.440578 -380.4539)
		(end 183.599582 -380.588012)
		(width 0.14732)
		(layer "In11.Cu")
		(net "UPI_CPU1_CPU0_P2P2_DP<12>")
	)
	(segment
		(start 188.058806 -380.0602)
		(end 188.21781 -380.194312)
		(width 0.14732)
		(layer "In11.Cu")
		(net "UPI_CPU1_CPU0_P2P2_DP<12>")
	)
	(segment
		(start 99.819714 -282.078938)
		(end 99.818952 -282.079446)
		(width 0.0889)
		(layer "In11.Cu")
		(net "UPI_CPU1_CPU0_P2P2_DP<12>")
	)
	(segment
		(start 345.435936 -282.405836)
		(end 345.123262 -282.405836)
		(width 0.0889)
		(layer "In11.Cu")
		(net "UPI_CPU1_CPU0_P2P2_DP<12>")
	)
	(arc
		(start 95.399098 -288.121598)
		(mid 95.318936 -288.393787)
		(end 95.11665 -288.592768)
		(width 0.0889)
		(layer "In11.Cu")
		(net "UPI_CPU1_CPU0_P2P2_DP<12>")
	)
	(arc
		(start 344.37955 -287.608518)
		(mid 344.510464 -287.472158)
		(end 344.558112 -287.28924)
		(width 0.0889)
		(layer "In11.Cu")
		(net "UPI_CPU1_CPU0_P2P2_DP<12>")
	)
	(arc
		(start 99.158298 -283.219906)
		(mid 99.086063 -283.49643)
		(end 98.887788 -283.702252)
		(width 0.0889)
		(layer "In11.Cu")
		(net "UPI_CPU1_CPU0_P2P2_DP<12>")
	)
	(arc
		(start 345.78036 -282.895548)
		(mid 345.596446 -282.725503)
		(end 345.504008 -282.492704)
		(width 0.0889)
		(layer "In11.Cu")
		(net "UPI_CPU1_CPU0_P2P2_DP<12>")
	)
	(arc
		(start 345.967558 -283.207714)
		(mid 345.917065 -283.031736)
		(end 345.78925 -282.900628)
		(width 0.0889)
		(layer "In11.Cu")
		(net "UPI_CPU1_CPU0_P2P2_DP<12>")
	)
	(arc
		(start 95.113348 -289.277806)
		(mid 95.287402 -289.416562)
		(end 95.398844 -289.609276)
		(width 0.0889)
		(layer "In11.Cu")
		(net "UPI_CPU1_CPU0_P2P2_DP<12>")
	)
	(arc
		(start 98.310192 -283.709364)
		(mid 98.122994 -283.659221)
		(end 97.935796 -283.709364)
		(width 0.0889)
		(layer "In11.Cu")
		(net "UPI_CPU1_CPU0_P2P2_DP<12>")
	)
	(arc
		(start 97.46615 -284.52318)
		(mid 97.191951 -284.599015)
		(end 96.915478 -284.531816)
		(width 0.0889)
		(layer "In11.Cu")
		(net "UPI_CPU1_CPU0_P2P2_DP<12>")
	)
	(arc
		(start 343.634314 -289.1536)
		(mid 343.626214 -289.133926)
		(end 343.61882 -289.113976)
		(width 0.0889)
		(layer "In11.Cu")
		(net "UPI_CPU1_CPU0_P2P2_DP<12>")
	)
	(arc
		(start 96.51746 -284.52826)
		(mid 96.386546 -284.66462)
		(end 96.338898 -284.847538)
		(width 0.0889)
		(layer "In11.Cu")
		(net "UPI_CPU1_CPU0_P2P2_DP<12>")
	)
	(arc
		(start 345.967812 -283.22651)
		(mid 345.967802 -283.21711)
		(end 345.967558 -283.207714)
		(width 0.0889)
		(layer "In11.Cu")
		(net "UPI_CPU1_CPU0_P2P2_DP<12>")
	)
	(arc
		(start 344.088466 -289.64509)
		(mid 344.013359 -289.529944)
		(end 343.904316 -289.446208)
		(width 0.0889)
		(layer "In11.Cu")
		(net "UPI_CPU1_CPU0_P2P2_DP<12>")
	)
	(arc
		(start 343.904316 -289.446208)
		(mid 343.744279 -289.323012)
		(end 343.634314 -289.1536)
		(width 0.0889)
		(layer "In11.Cu")
		(net "UPI_CPU1_CPU0_P2P2_DP<12>")
	)
	(arc
		(start 345.78925 -283.539184)
		(mid 345.918539 -283.405698)
		(end 345.967812 -283.22651)
		(width 0.0889)
		(layer "In11.Cu")
		(net "UPI_CPU1_CPU0_P2P2_DP<12>")
	)
	(arc
		(start 343.909904 -288.422334)
		(mid 344.040818 -288.285974)
		(end 344.088466 -288.103056)
		(width 0.0889)
		(layer "In11.Cu")
		(net "UPI_CPU1_CPU0_P2P2_DP<12>")
	)
	(arc
		(start 344.84056 -286.151066)
		(mid 344.638274 -285.952085)
		(end 344.558112 -285.679896)
		(width 0.0889)
		(layer "In11.Cu")
		(net "UPI_CPU1_CPU0_P2P2_DP<12>")
	)
	(arc
		(start 96.047306 -285.342076)
		(mid 95.868709 -285.661354)
		(end 96.047306 -285.980632)
		(width 0.0889)
		(layer "In11.Cu")
		(net "UPI_CPU1_CPU0_P2P2_DP<12>")
	)
	(arc
		(start 99.33686 -282.900628)
		(mid 99.205946 -283.036988)
		(end 99.158298 -283.219906)
		(width 0.0889)
		(layer "In11.Cu")
		(net "UPI_CPU1_CPU0_P2P2_DP<12>")
	)
	(arc
		(start 100.094288 -281.657806)
		(mid 100.092987 -281.668233)
		(end 100.091494 -281.678634)
		(width 0.0889)
		(layer "In11.Cu")
		(net "UPI_CPU1_CPU0_P2P2_DP<12>")
	)
	(arc
		(start 95.868744 -287.304734)
		(mid 95.789374 -287.578468)
		(end 95.58655 -287.778698)
		(width 0.0889)
		(layer "In11.Cu")
		(net "UPI_CPU1_CPU0_P2P2_DP<12>")
	)
	(arc
		(start 94.929198 -289.078416)
		(mid 95.004203 -289.193875)
		(end 95.113348 -289.277806)
		(width 0.0889)
		(layer "In11.Cu")
		(net "UPI_CPU1_CPU0_P2P2_DP<12>")
	)
	(arc
		(start 345.028266 -284.832044)
		(mid 345.107636 -284.55831)
		(end 345.31046 -284.35808)
		(width 0.0889)
		(layer "In11.Cu")
		(net "UPI_CPU1_CPU0_P2P2_DP<12>")
	)
	(arc
		(start 344.84945 -286.794702)
		(mid 345.028047 -286.475424)
		(end 344.84945 -286.156146)
		(width 0.0889)
		(layer "In11.Cu")
		(net "UPI_CPU1_CPU0_P2P2_DP<12>")
	)
	(arc
		(start 344.558112 -287.279334)
		(mid 344.636223 -287.002385)
		(end 344.84056 -286.799782)
		(width 0.0889)
		(layer "In11.Cu")
		(net "UPI_CPU1_CPU0_P2P2_DP<12>")
	)
	(arc
		(start 95.57766 -287.783778)
		(mid 95.446746 -287.920138)
		(end 95.399098 -288.103056)
		(width 0.0889)
		(layer "In11.Cu")
		(net "UPI_CPU1_CPU0_P2P2_DP<12>")
	)
	(arc
		(start 95.10776 -288.597848)
		(mid 94.976846 -288.734208)
		(end 94.929198 -288.917126)
		(width 0.0889)
		(layer "In11.Cu")
		(net "UPI_CPU1_CPU0_P2P2_DP<12>")
	)
	(arc
		(start 99.806506 -282.086558)
		(mid 99.675592 -282.222918)
		(end 99.627944 -282.405836)
		(width 0.0889)
		(layer "In11.Cu")
		(net "UPI_CPU1_CPU0_P2P2_DP<12>")
	)
	(arc
		(start 344.849704 -285.166816)
		(mid 344.980618 -285.030456)
		(end 345.028266 -284.847538)
		(width 0.0889)
		(layer "In11.Cu")
		(net "UPI_CPU1_CPU0_P2P2_DP<12>")
	)
	(arc
		(start 344.558112 -285.661354)
		(mid 344.632103 -285.381788)
		(end 344.834718 -285.175452)
		(width 0.0889)
		(layer "In11.Cu")
		(net "UPI_CPU1_CPU0_P2P2_DP<12>")
	)
	(arc
		(start 345.31935 -284.353)
		(mid 345.450264 -284.21664)
		(end 345.497912 -284.033722)
		(width 0.0889)
		(layer "In11.Cu")
		(net "UPI_CPU1_CPU0_P2P2_DP<12>")
	)
	(arc
		(start 99.627944 -282.427934)
		(mid 99.547033 -282.698062)
		(end 99.34575 -282.895548)
		(width 0.0889)
		(layer "In11.Cu")
		(net "UPI_CPU1_CPU0_P2P2_DP<12>")
	)
	(arc
		(start 96.056196 -285.985712)
		(mid 96.259677 -286.186516)
		(end 96.338898 -286.4612)
		(width 0.0889)
		(layer "In11.Cu")
		(net "UPI_CPU1_CPU0_P2P2_DP<12>")
	)
	(arc
		(start 96.338898 -284.847538)
		(mid 96.264907 -285.127104)
		(end 96.062292 -285.33344)
		(width 0.0889)
		(layer "In11.Cu")
		(net "UPI_CPU1_CPU0_P2P2_DP<12>")
	)
	(arc
		(start 343.618566 -288.898584)
		(mid 343.698728 -288.626395)
		(end 343.901014 -288.427414)
		(width 0.0889)
		(layer "In11.Cu")
		(net "UPI_CPU1_CPU0_P2P2_DP<12>")
	)
	(arc
		(start 345.504008 -282.492704)
		(mid 345.502508 -282.481922)
		(end 345.501214 -282.471114)
		(width 0.0889)
		(layer "In11.Cu")
		(net "UPI_CPU1_CPU0_P2P2_DP<12>")
	)
	(arc
		(start 98.875596 -283.709364)
		(mid 98.592894 -283.78514)
		(end 98.310192 -283.709364)
		(width 0.0889)
		(layer "In11.Cu")
		(net "UPI_CPU1_CPU0_P2P2_DP<12>")
	)
	(arc
		(start 97.926906 -283.714444)
		(mid 97.795992 -283.850804)
		(end 97.748344 -284.033722)
		(width 0.0889)
		(layer "In11.Cu")
		(net "UPI_CPU1_CPU0_P2P2_DP<12>")
	)
	(arc
		(start 345.497912 -284.023816)
		(mid 345.576023 -283.746867)
		(end 345.78036 -283.544264)
		(width 0.0889)
		(layer "In11.Cu")
		(net "UPI_CPU1_CPU0_P2P2_DP<12>")
	)
	(arc
		(start 96.900746 -284.52318)
		(mid 96.713548 -284.473037)
		(end 96.52635 -284.52318)
		(width 0.0889)
		(layer "In11.Cu")
		(net "UPI_CPU1_CPU0_P2P2_DP<12>")
	)
	(arc
		(start 96.338898 -286.475424)
		(mid 96.264907 -286.75499)
		(end 96.062292 -286.961326)
		(width 0.0889)
		(layer "In11.Cu")
		(net "UPI_CPU1_CPU0_P2P2_DP<12>")
	)
	(arc
		(start 97.748344 -284.049216)
		(mid 97.668974 -284.32295)
		(end 97.46615 -284.52318)
		(width 0.0889)
		(layer "In11.Cu")
		(net "UPI_CPU1_CPU0_P2P2_DP<12>")
	)
	(arc
		(start 100.091494 -281.678634)
		(mid 100.00123 -281.908544)
		(end 99.821492 -282.077922)
		(width 0.0889)
		(layer "In11.Cu")
		(net "UPI_CPU1_CPU0_P2P2_DP<12>")
	)
	(arc
		(start 344.088466 -288.087562)
		(mid 344.167836 -287.813828)
		(end 344.37066 -287.613598)
		(width 0.0889)
		(layer "In11.Cu")
		(net "UPI_CPU1_CPU0_P2P2_DP<12>")
	)
	(arc
		(start 96.047306 -286.969962)
		(mid 95.916392 -287.106322)
		(end 95.868744 -287.28924)
		(width 0.0889)
		(layer "In11.Cu")
		(net "UPI_CPU1_CPU0_P2P2_DP<12>")
	)
	(segment
		(start 102.352348 -279.428448)
		(end 102.352348 -279.964134)
		(width 0.13208)
		(layer "F.Cu")
		(net "UPI_CPU1_CPU0_P2P2_DP<11>")
	)
	(segment
		(start 102.352094 -279.428194)
		(end 102.352348 -279.428448)
		(width 0.13208)
		(layer "F.Cu")
		(net "UPI_CPU1_CPU0_P2P2_DP<11>")
	)
	(segment
		(start 351.702116 -273.730974)
		(end 351.701862 -273.731228)
		(width 0.13208)
		(layer "F.Cu")
		(net "UPI_CPU1_CPU0_P2P2_DP<11>")
	)
	(segment
		(start 351.701862 -273.731228)
		(end 351.701862 -274.266914)
		(width 0.13208)
		(layer "F.Cu")
		(net "UPI_CPU1_CPU0_P2P2_DP<11>")
	)
	(segment
		(start 345.776296 -286.802322)
		(end 345.777058 -286.801814)
		(width 0.0889)
		(layer "In11.Cu")
		(net "UPI_CPU1_CPU0_P2P2_DP<11>")
	)
	(segment
		(start 342.914478 -297.680634)
		(end 342.98636 -297.319192)
		(width 0.14732)
		(layer "In11.Cu")
		(net "UPI_CPU1_CPU0_P2P2_DP<11>")
	)
	(segment
		(start 94.45879 -290.24453)
		(end 94.55785 -290.34359)
		(width 0.0889)
		(layer "In11.Cu")
		(net "UPI_CPU1_CPU0_P2P2_DP<11>")
	)
	(segment
		(start 351.858326 -274.537932)
		(end 351.701862 -274.266914)
		(width 0.0889)
		(layer "In11.Cu")
		(net "UPI_CPU1_CPU0_P2P2_DP<11>")
	)
	(segment
		(start 349.07855 -277.203154)
		(end 349.070676 -277.198582)
		(width 0.0889)
		(layer "In11.Cu")
		(net "UPI_CPU1_CPU0_P2P2_DP<11>")
	)
	(segment
		(start 343.315036 -295.66743)
		(end 343.386918 -295.305988)
		(width 0.14732)
		(layer "In11.Cu")
		(net "UPI_CPU1_CPU0_P2P2_DP<11>")
	)
	(segment
		(start 67.496944 -324.54977)
		(end 66.537078 -328.016616)
		(width 0.14732)
		(layer "In11.Cu")
		(net "UPI_CPU1_CPU0_P2P2_DP<11>")
	)
	(segment
		(start 343.556844 -295.192196)
		(end 343.66962 -294.625014)
		(width 0.14732)
		(layer "In11.Cu")
		(net "UPI_CPU1_CPU0_P2P2_DP<11>")
	)
	(segment
		(start 91.383104 -301.387764)
		(end 91.042236 -301.491142)
		(width 0.14732)
		(layer "In11.Cu")
		(net "UPI_CPU1_CPU0_P2P2_DP<11>")
	)
	(segment
		(start 95.128588 -286.95777)
		(end 95.116396 -286.964882)
		(width 0.0889)
		(layer "In11.Cu")
		(net "UPI_CPU1_CPU0_P2P2_DP<11>")
	)
	(segment
		(start 70.501764 -365.496602)
		(end 74.94397 -369.938808)
		(width 0.14732)
		(layer "In11.Cu")
		(net "UPI_CPU1_CPU0_P2P2_DP<11>")
	)
	(segment
		(start 89.62517 -302.654208)
		(end 89.287604 -302.931322)
		(width 0.14732)
		(layer "In11.Cu")
		(net "UPI_CPU1_CPU0_P2P2_DP<11>")
	)
	(segment
		(start 94.55785 -291.07511)
		(end 94.45879 -291.17417)
		(width 0.0889)
		(layer "In11.Cu")
		(net "UPI_CPU1_CPU0_P2P2_DP<11>")
	)
	(segment
		(start 94.459044 -289.60953)
		(end 94.45879 -289.609784)
		(width 0.0889)
		(layer "In11.Cu")
		(net "UPI_CPU1_CPU0_P2P2_DP<11>")
	)
	(segment
		(start 347.19895 -282.086558)
		(end 347.19006 -282.081478)
		(width 0.0889)
		(layer "In11.Cu")
		(net "UPI_CPU1_CPU0_P2P2_DP<11>")
	)
	(segment
		(start 348.787466 -276.72411)
		(end 348.787466 -276.69871)
		(width 0.0889)
		(layer "In11.Cu")
		(net "UPI_CPU1_CPU0_P2P2_DP<11>")
	)
	(segment
		(start 351.499932 -274.582636)
		(end 351.542604 -274.607528)
		(width 0.0889)
		(layer "In11.Cu")
		(net "UPI_CPU1_CPU0_P2P2_DP<11>")
	)
	(segment
		(start 349.727266 -275.08073)
		(end 349.727266 -275.065236)
		(width 0.0889)
		(layer "In11.Cu")
		(net "UPI_CPU1_CPU0_P2P2_DP<11>")
	)
	(segment
		(start 96.995996 -283.709364)
		(end 96.981264 -283.718)
		(width 0.0889)
		(layer "In11.Cu")
		(net "UPI_CPU1_CPU0_P2P2_DP<11>")
	)
	(segment
		(start 270.03756 -346.019374)
		(end 280.473404 -335.58353)
		(width 0.14732)
		(layer "In11.Cu")
		(net "UPI_CPU1_CPU0_P2P2_DP<11>")
	)
	(segment
		(start 88.932766 -303.38014)
		(end 88.761062 -303.363376)
		(width 0.14732)
		(layer "In11.Cu")
		(net "UPI_CPU1_CPU0_P2P2_DP<11>")
	)
	(segment
		(start 101.97846 -279.929082)
		(end 101.977698 -279.966166)
		(width 0.0889)
		(layer "In11.Cu")
		(net "UPI_CPU1_CPU0_P2P2_DP<11>")
	)
	(segment
		(start 88.068658 -304.089308)
		(end 87.896954 -304.072544)
		(width 0.14732)
		(layer "In11.Cu")
		(net "UPI_CPU1_CPU0_P2P2_DP<11>")
	)
	(segment
		(start 95.399098 -286.467804)
		(end 95.399098 -286.475424)
		(width 0.0889)
		(layer "In11.Cu")
		(net "UPI_CPU1_CPU0_P2P2_DP<11>")
	)
	(segment
		(start 92.999306 -300.061376)
		(end 91.383104 -301.387764)
		(width 0.14732)
		(layer "In11.Cu")
		(net "UPI_CPU1_CPU0_P2P2_DP<11>")
	)
	(segment
		(start 344.840814 -288.427414)
		(end 344.849704 -288.422334)
		(width 0.0889)
		(layer "In11.Cu")
		(net "UPI_CPU1_CPU0_P2P2_DP<11>")
	)
	(segment
		(start 343.66962 -294.625014)
		(end 343.556082 -294.455088)
		(width 0.14732)
		(layer "In11.Cu")
		(net "UPI_CPU1_CPU0_P2P2_DP<11>")
	)
	(segment
		(start 101.698806 -280.45156)
		(end 101.698552 -280.451814)
		(width 0.0889)
		(layer "In11.Cu")
		(net "UPI_CPU1_CPU0_P2P2_DP<11>")
	)
	(segment
		(start 96.70669 -378.953268)
		(end 125.70968 -383.25552)
		(width 0.14732)
		(layer "In11.Cu")
		(net "UPI_CPU1_CPU0_P2P2_DP<11>")
	)
	(segment
		(start 346.907866 -281.607514)
		(end 346.907866 -281.576526)
		(width 0.0889)
		(layer "In11.Cu")
		(net "UPI_CPU1_CPU0_P2P2_DP<11>")
	)
	(segment
		(start 94.45879 -291.432234)
		(end 94.500954 -291.474398)
		(width 0.0889)
		(layer "In11.Cu")
		(net "UPI_CPU1_CPU0_P2P2_DP<11>")
	)
	(segment
		(start 95.117158 -285.336488)
		(end 95.116396 -285.336996)
		(width 0.0889)
		(layer "In11.Cu")
		(net "UPI_CPU1_CPU0_P2P2_DP<11>")
	)
	(segment
		(start 343.02827 -297.850814)
		(end 342.914478 -297.680634)
		(width 0.14732)
		(layer "In11.Cu")
		(net "UPI_CPU1_CPU0_P2P2_DP<11>")
	)
	(segment
		(start 98.876358 -282.08097)
		(end 98.875596 -282.081478)
		(width 0.0889)
		(layer "In11.Cu")
		(net "UPI_CPU1_CPU0_P2P2_DP<11>")
	)
	(segment
		(start 345.497912 -285.675578)
		(end 345.497912 -285.661354)
		(width 0.0889)
		(layer "In11.Cu")
		(net "UPI_CPU1_CPU0_P2P2_DP<11>")
	)
	(segment
		(start 349.257112 -275.903436)
		(end 349.257112 -275.880576)
		(width 0.0889)
		(layer "In11.Cu")
		(net "UPI_CPU1_CPU0_P2P2_DP<11>")
	)
	(segment
		(start 94.459298 -288.103056)
		(end 94.459298 -288.121598)
		(width 0.0889)
		(layer "In11.Cu")
		(net "UPI_CPU1_CPU0_P2P2_DP<11>")
	)
	(segment
		(start 98.875596 -282.081478)
		(end 98.868738 -282.085288)
		(width 0.0889)
		(layer "In11.Cu")
		(net "UPI_CPU1_CPU0_P2P2_DP<11>")
	)
	(segment
		(start 346.907612 -283.219906)
		(end 346.907612 -283.205682)
		(width 0.0889)
		(layer "In11.Cu")
		(net "UPI_CPU1_CPU0_P2P2_DP<11>")
	)
	(segment
		(start 343.228422 -296.844212)
		(end 343.11463 -296.674032)
		(width 0.14732)
		(layer "In11.Cu")
		(net "UPI_CPU1_CPU0_P2P2_DP<11>")
	)
	(segment
		(start 95.120714 -285.334456)
		(end 95.119952 -285.334964)
		(width 0.0889)
		(layer "In11.Cu")
		(net "UPI_CPU1_CPU0_P2P2_DP<11>")
	)
	(segment
		(start 95.12173 -285.333948)
		(end 95.120714 -285.334456)
		(width 0.0889)
		(layer "In11.Cu")
		(net "UPI_CPU1_CPU0_P2P2_DP<11>")
	)
	(segment
		(start 93.989398 -288.917126)
		(end 93.989398 -289.078416)
		(width 0.0889)
		(layer "In11.Cu")
		(net "UPI_CPU1_CPU0_P2P2_DP<11>")
	)
	(segment
		(start 95.116396 -285.336996)
		(end 95.109538 -285.340806)
		(width 0.0889)
		(layer "In11.Cu")
		(net "UPI_CPU1_CPU0_P2P2_DP<11>")
	)
	(segment
		(start 346.72016 -283.544264)
		(end 346.720922 -283.543756)
		(width 0.0889)
		(layer "In11.Cu")
		(net "UPI_CPU1_CPU0_P2P2_DP<11>")
	)
	(segment
		(start 98.879914 -282.078938)
		(end 98.879152 -282.079446)
		(width 0.0889)
		(layer "In11.Cu")
		(net "UPI_CPU1_CPU0_P2P2_DP<11>")
	)
	(segment
		(start 98.879152 -282.079446)
		(end 98.876358 -282.08097)
		(width 0.0889)
		(layer "In11.Cu")
		(net "UPI_CPU1_CPU0_P2P2_DP<11>")
	)
	(segment
		(start 343.890854 -293.514272)
		(end 343.890854 -291.496496)
		(width 0.14732)
		(layer "In11.Cu")
		(net "UPI_CPU1_CPU0_P2P2_DP<11>")
	)
	(segment
		(start 270.03756 -366.133126)
		(end 270.03756 -346.019374)
		(width 0.14732)
		(layer "In11.Cu")
		(net "UPI_CPU1_CPU0_P2P2_DP<11>")
	)
	(segment
		(start 99.34575 -281.267662)
		(end 99.33686 -281.272742)
		(width 0.0889)
		(layer "In11.Cu")
		(net "UPI_CPU1_CPU0_P2P2_DP<11>")
	)
	(segment
		(start 345.967812 -286.48406)
		(end 345.967812 -286.466788)
		(width 0.0889)
		(layer "In11.Cu")
		(net "UPI_CPU1_CPU0_P2P2_DP<11>")
	)
	(segment
		(start 94.55785 -290.89731)
		(end 94.55785 -291.07511)
		(width 0.0889)
		(layer "In11.Cu")
		(net "UPI_CPU1_CPU0_P2P2_DP<11>")
	)
	(segment
		(start 74.94397 -369.938808)
		(end 96.70669 -378.953268)
		(width 0.14732)
		(layer "In11.Cu")
		(net "UPI_CPU1_CPU0_P2P2_DP<11>")
	)
	(segment
		(start 343.890854 -291.496496)
		(end 343.890854 -291.474398)
		(width 0.0889)
		(layer "In11.Cu")
		(net "UPI_CPU1_CPU0_P2P2_DP<11>")
	)
	(segment
		(start 348.12986 -279.474676)
		(end 348.130876 -279.474168)
		(width 0.0889)
		(layer "In11.Cu")
		(net "UPI_CPU1_CPU0_P2P2_DP<11>")
	)
	(segment
		(start 344.558366 -289.114738)
		(end 344.558366 -288.898584)
		(width 0.0889)
		(layer "In11.Cu")
		(net "UPI_CPU1_CPU0_P2P2_DP<11>")
	)
	(segment
		(start 351.837244 -274.61591)
		(end 351.858326 -274.537932)
		(width 0.0889)
		(layer "In11.Cu")
		(net "UPI_CPU1_CPU0_P2P2_DP<11>")
	)
	(segment
		(start 343.3572 -296.198798)
		(end 343.428828 -295.83761)
		(width 0.14732)
		(layer "In11.Cu")
		(net "UPI_CPU1_CPU0_P2P2_DP<11>")
	)
	(segment
		(start 342.955372 -298.211494)
		(end 342.956642 -298.211748)
		(width 0.14732)
		(layer "In11.Cu")
		(net "UPI_CPU1_CPU0_P2P2_DP<11>")
	)
	(segment
		(start 101.698552 -280.451814)
		(end 101.694996 -280.453846)
		(width 0.0889)
		(layer "In11.Cu")
		(net "UPI_CPU1_CPU0_P2P2_DP<11>")
	)
	(segment
		(start 307.888386 -333.47787)
		(end 314.45835 -326.907906)
		(width 0.14732)
		(layer "In11.Cu")
		(net "UPI_CPU1_CPU0_P2P2_DP<11>")
	)
	(segment
		(start 94.45879 -290.62045)
		(end 94.45879 -290.79825)
		(width 0.0889)
		(layer "In11.Cu")
		(net "UPI_CPU1_CPU0_P2P2_DP<11>")
	)
	(segment
		(start 346.720922 -283.543756)
		(end 346.7227 -283.54274)
		(width 0.0889)
		(layer "In11.Cu")
		(net "UPI_CPU1_CPU0_P2P2_DP<11>")
	)
	(segment
		(start 98.88093 -282.07843)
		(end 98.879914 -282.078938)
		(width 0.0889)
		(layer "In11.Cu")
		(net "UPI_CPU1_CPU0_P2P2_DP<11>")
	)
	(segment
		(start 345.780614 -285.171896)
		(end 345.789504 -285.166816)
		(width 0.0889)
		(layer "In11.Cu")
		(net "UPI_CPU1_CPU0_P2P2_DP<11>")
	)
	(segment
		(start 348.130876 -279.474168)
		(end 348.13875 -279.469596)
		(width 0.0889)
		(layer "In11.Cu")
		(net "UPI_CPU1_CPU0_P2P2_DP<11>")
	)
	(segment
		(start 95.107506 -285.980632)
		(end 95.115634 -285.985204)
		(width 0.0889)
		(layer "In11.Cu")
		(net "UPI_CPU1_CPU0_P2P2_DP<11>")
	)
	(segment
		(start 345.028266 -289.977068)
		(end 345.028266 -289.64636)
		(width 0.0889)
		(layer "In11.Cu")
		(net "UPI_CPU1_CPU0_P2P2_DP<11>")
	)
	(segment
		(start 343.932764 -291.432488)
		(end 343.932764 -291.07257)
		(width 0.0889)
		(layer "In11.Cu")
		(net "UPI_CPU1_CPU0_P2P2_DP<11>")
	)
	(segment
		(start 98.868738 -282.085288)
		(end 98.866706 -282.086558)
		(width 0.0889)
		(layer "In11.Cu")
		(net "UPI_CPU1_CPU0_P2P2_DP<11>")
	)
	(segment
		(start 94.928944 -287.28924)
		(end 94.928944 -287.304734)
		(width 0.0889)
		(layer "In11.Cu")
		(net "UPI_CPU1_CPU0_P2P2_DP<11>")
	)
	(segment
		(start 94.500954 -296.94378)
		(end 93.476826 -299.417232)
		(width 0.14732)
		(layer "In11.Cu")
		(net "UPI_CPU1_CPU0_P2P2_DP<11>")
	)
	(segment
		(start 101.704648 -280.448258)
		(end 101.698806 -280.45156)
		(width 0.0889)
		(layer "In11.Cu")
		(net "UPI_CPU1_CPU0_P2P2_DP<11>")
	)
	(segment
		(start 100.755196 -280.453846)
		(end 100.740464 -280.462482)
		(width 0.0889)
		(layer "In11.Cu")
		(net "UPI_CPU1_CPU0_P2P2_DP<11>")
	)
	(segment
		(start 161.281364 -383.25552)
		(end 161.28238 -383.254504)
		(width 0.14732)
		(layer "In11.Cu")
		(net "UPI_CPU1_CPU0_P2P2_DP<11>")
	)
	(segment
		(start 94.64675 -287.778698)
		(end 94.63786 -287.783778)
		(width 0.0889)
		(layer "In11.Cu")
		(net "UPI_CPU1_CPU0_P2P2_DP<11>")
	)
	(segment
		(start 97.002092 -283.705808)
		(end 96.995996 -283.709364)
		(width 0.0889)
		(layer "In11.Cu")
		(net "UPI_CPU1_CPU0_P2P2_DP<11>")
	)
	(segment
		(start 345.779852 -286.80029)
		(end 345.780614 -286.799782)
		(width 0.0889)
		(layer "In11.Cu")
		(net "UPI_CPU1_CPU0_P2P2_DP<11>")
	)
	(segment
		(start 125.70968 -383.25552)
		(end 161.281364 -383.25552)
		(width 0.14732)
		(layer "In11.Cu")
		(net "UPI_CPU1_CPU0_P2P2_DP<11>")
	)
	(segment
		(start 347.847666 -279.964134)
		(end 347.847666 -279.94864)
		(width 0.0889)
		(layer "In11.Cu")
		(net "UPI_CPU1_CPU0_P2P2_DP<11>")
	)
	(segment
		(start 89.287604 -302.931322)
		(end 89.270586 -303.102772)
		(width 0.14732)
		(layer "In11.Cu")
		(net "UPI_CPU1_CPU0_P2P2_DP<11>")
	)
	(segment
		(start 91.042236 -301.491142)
		(end 90.151458 -302.222154)
		(width 0.14732)
		(layer "In11.Cu")
		(net "UPI_CPU1_CPU0_P2P2_DP<11>")
	)
	(segment
		(start 88.406478 -303.81194)
		(end 88.068658 -304.089308)
		(width 0.14732)
		(layer "In11.Cu")
		(net "UPI_CPU1_CPU0_P2P2_DP<11>")
	)
	(segment
		(start 346.437712 -284.033722)
		(end 346.437712 -284.023816)
		(width 0.0889)
		(layer "In11.Cu")
		(net "UPI_CPU1_CPU0_P2P2_DP<11>")
	)
	(segment
		(start 280.473404 -335.58353)
		(end 285.557214 -333.47787)
		(width 0.14732)
		(layer "In11.Cu")
		(net "UPI_CPU1_CPU0_P2P2_DP<11>")
	)
	(segment
		(start 88.761062 -303.363376)
		(end 88.423496 -303.64049)
		(width 0.14732)
		(layer "In11.Cu")
		(net "UPI_CPU1_CPU0_P2P2_DP<11>")
	)
	(segment
		(start 90.134694 -302.393604)
		(end 89.79662 -302.670972)
		(width 0.14732)
		(layer "In11.Cu")
		(net "UPI_CPU1_CPU0_P2P2_DP<11>")
	)
	(segment
		(start 94.55785 -290.52139)
		(end 94.45879 -290.62045)
		(width 0.0889)
		(layer "In11.Cu")
		(net "UPI_CPU1_CPU0_P2P2_DP<11>")
	)
	(segment
		(start 337.309714 -302.503078)
		(end 340.737444 -301.083218)
		(width 0.14732)
		(layer "In11.Cu")
		(net "UPI_CPU1_CPU0_P2P2_DP<11>")
	)
	(segment
		(start 345.028266 -288.103056)
		(end 345.028266 -288.087562)
		(width 0.0889)
		(layer "In11.Cu")
		(net "UPI_CPU1_CPU0_P2P2_DP<11>")
	)
	(segment
		(start 95.122492 -285.33344)
		(end 95.12173 -285.333948)
		(width 0.0889)
		(layer "In11.Cu")
		(net "UPI_CPU1_CPU0_P2P2_DP<11>")
	)
	(segment
		(start 347.19006 -282.730194)
		(end 347.19895 -282.725114)
		(width 0.0889)
		(layer "In11.Cu")
		(net "UPI_CPU1_CPU0_P2P2_DP<11>")
	)
	(segment
		(start 102.11689 -279.672288)
		(end 102.098348 -279.687274)
		(width 0.0889)
		(layer "In11.Cu")
		(net "UPI_CPU1_CPU0_P2P2_DP<11>")
	)
	(segment
		(start 68.189348 -359.913428)
		(end 70.501764 -365.496602)
		(width 0.14732)
		(layer "In11.Cu")
		(net "UPI_CPU1_CPU0_P2P2_DP<11>")
	)
	(segment
		(start 94.17685 -288.592768)
		(end 94.16796 -288.597848)
		(width 0.0889)
		(layer "In11.Cu")
		(net "UPI_CPU1_CPU0_P2P2_DP<11>")
	)
	(segment
		(start 95.868744 -284.033722)
		(end 95.868744 -284.049216)
		(width 0.0889)
		(layer "In11.Cu")
		(net "UPI_CPU1_CPU0_P2P2_DP<11>")
	)
	(segment
		(start 94.500954 -291.474398)
		(end 94.500954 -291.496496)
		(width 0.0889)
		(layer "In11.Cu")
		(net "UPI_CPU1_CPU0_P2P2_DP<11>")
	)
	(segment
		(start 93.476826 -299.417232)
		(end 92.999306 -300.061376)
		(width 0.14732)
		(layer "In11.Cu")
		(net "UPI_CPU1_CPU0_P2P2_DP<11>")
	)
	(segment
		(start 351.807018 -274.627594)
		(end 351.837244 -274.61591)
		(width 0.0889)
		(layer "In11.Cu")
		(net "UPI_CPU1_CPU0_P2P2_DP<11>")
	)
	(segment
		(start 343.556082 -294.455088)
		(end 343.627964 -294.093646)
		(width 0.14732)
		(layer "In11.Cu")
		(net "UPI_CPU1_CPU0_P2P2_DP<11>")
	)
	(segment
		(start 347.377512 -280.778204)
		(end 347.377512 -280.76398)
		(width 0.0889)
		(layer "In11.Cu")
		(net "UPI_CPU1_CPU0_P2P2_DP<11>")
	)
	(segment
		(start 343.428828 -295.83761)
		(end 343.315036 -295.66743)
		(width 0.14732)
		(layer "In11.Cu")
		(net "UPI_CPU1_CPU0_P2P2_DP<11>")
	)
	(segment
		(start 345.968066 -284.847538)
		(end 345.968066 -284.832044)
		(width 0.0889)
		(layer "In11.Cu")
		(net "UPI_CPU1_CPU0_P2P2_DP<11>")
	)
	(segment
		(start 65.876678 -334.72501)
		(end 65.876678 -354.329746)
		(width 0.14732)
		(layer "In11.Cu")
		(net "UPI_CPU1_CPU0_P2P2_DP<11>")
	)
	(segment
		(start 98.688144 -282.405836)
		(end 98.688144 -282.424378)
		(width 0.0889)
		(layer "In11.Cu")
		(net "UPI_CPU1_CPU0_P2P2_DP<11>")
	)
	(segment
		(start 315.556392 -324.2564)
		(end 337.309714 -302.503078)
		(width 0.14732)
		(layer "In11.Cu")
		(net "UPI_CPU1_CPU0_P2P2_DP<11>")
	)
	(segment
		(start 94.45879 -290.79825)
		(end 94.55785 -290.89731)
		(width 0.0889)
		(layer "In11.Cu")
		(net "UPI_CPU1_CPU0_P2P2_DP<11>")
	)
	(segment
		(start 99.815396 -280.453846)
		(end 99.806506 -280.458926)
		(width 0.0889)
		(layer "In11.Cu")
		(net "UPI_CPU1_CPU0_P2P2_DP<11>")
	)
	(segment
		(start 98.881692 -282.077922)
		(end 98.88093 -282.07843)
		(width 0.0889)
		(layer "In11.Cu")
		(net "UPI_CPU1_CPU0_P2P2_DP<11>")
	)
	(segment
		(start 102.352348 -279.964134)
		(end 102.195884 -279.693116)
		(width 0.0889)
		(layer "In11.Cu")
		(net "UPI_CPU1_CPU0_P2P2_DP<11>")
	)
	(segment
		(start 346.7227 -283.54274)
		(end 346.723462 -283.542232)
		(width 0.0889)
		(layer "In11.Cu")
		(net "UPI_CPU1_CPU0_P2P2_DP<11>")
	)
	(segment
		(start 65.876678 -354.329746)
		(end 68.189348 -359.913174)
		(width 0.14732)
		(layer "In11.Cu")
		(net "UPI_CPU1_CPU0_P2P2_DP<11>")
	)
	(segment
		(start 349.539814 -275.405088)
		(end 349.548704 -275.400008)
		(width 0.0889)
		(layer "In11.Cu")
		(net "UPI_CPU1_CPU0_P2P2_DP<11>")
	)
	(segment
		(start 163.168584 -383.178558)
		(end 261.304024 -374.866662)
		(width 0.14732)
		(layer "In11.Cu")
		(net "UPI_CPU1_CPU0_P2P2_DP<11>")
	)
	(segment
		(start 102.195884 -279.693116)
		(end 102.117652 -279.672288)
		(width 0.0889)
		(layer "In11.Cu")
		(net "UPI_CPU1_CPU0_P2P2_DP<11>")
	)
	(segment
		(start 343.186512 -296.31259)
		(end 343.3572 -296.198798)
		(width 0.14732)
		(layer "In11.Cu")
		(net "UPI_CPU1_CPU0_P2P2_DP<11>")
	)
	(segment
		(start 343.932764 -291.07257)
		(end 345.028266 -289.977068)
		(width 0.0889)
		(layer "In11.Cu")
		(net "UPI_CPU1_CPU0_P2P2_DP<11>")
	)
	(segment
		(start 343.798398 -293.979854)
		(end 343.890854 -293.514272)
		(width 0.14732)
		(layer "In11.Cu")
		(net "UPI_CPU1_CPU0_P2P2_DP<11>")
	)
	(segment
		(start 97.278698 -283.21127)
		(end 97.278698 -283.219906)
		(width 0.0889)
		(layer "In11.Cu")
		(net "UPI_CPU1_CPU0_P2P2_DP<11>")
	)
	(segment
		(start 347.19006 -281.102562)
		(end 347.19895 -281.097482)
		(width 0.0889)
		(layer "In11.Cu")
		(net "UPI_CPU1_CPU0_P2P2_DP<11>")
	)
	(segment
		(start 95.115634 -285.985204)
		(end 95.116396 -285.985712)
		(width 0.0889)
		(layer "In11.Cu")
		(net "UPI_CPU1_CPU0_P2P2_DP<11>")
	)
	(segment
		(start 102.117144 -279.672034)
		(end 102.11689 -279.672288)
		(width 0.0889)
		(layer "In11.Cu")
		(net "UPI_CPU1_CPU0_P2P2_DP<11>")
	)
	(segment
		(start 349.06966 -277.84679)
		(end 349.07855 -277.84171)
		(width 0.0889)
		(layer "In11.Cu")
		(net "UPI_CPU1_CPU0_P2P2_DP<11>")
	)
	(segment
		(start 94.500954 -291.496496)
		(end 94.500954 -296.94378)
		(width 0.14732)
		(layer "In11.Cu")
		(net "UPI_CPU1_CPU0_P2P2_DP<11>")
	)
	(segment
		(start 78.699868 -311.620154)
		(end 69.04609 -321.273932)
		(width 0.14732)
		(layer "In11.Cu")
		(net "UPI_CPU1_CPU0_P2P2_DP<11>")
	)
	(segment
		(start 94.45879 -291.17417)
		(end 94.45879 -291.432234)
		(width 0.0889)
		(layer "In11.Cu")
		(net "UPI_CPU1_CPU0_P2P2_DP<11>")
	)
	(segment
		(start 95.119952 -285.334964)
		(end 95.117158 -285.336488)
		(width 0.0889)
		(layer "In11.Cu")
		(net "UPI_CPU1_CPU0_P2P2_DP<11>")
	)
	(segment
		(start 66.537078 -328.016616)
		(end 65.876678 -334.72501)
		(width 0.14732)
		(layer "In11.Cu")
		(net "UPI_CPU1_CPU0_P2P2_DP<11>")
	)
	(segment
		(start 343.890854 -291.474398)
		(end 343.932764 -291.432488)
		(width 0.0889)
		(layer "In11.Cu")
		(net "UPI_CPU1_CPU0_P2P2_DP<11>")
	)
	(segment
		(start 343.156794 -297.2054)
		(end 343.228422 -296.844212)
		(width 0.14732)
		(layer "In11.Cu")
		(net "UPI_CPU1_CPU0_P2P2_DP<11>")
	)
	(segment
		(start 89.270586 -303.102772)
		(end 88.932766 -303.38014)
		(width 0.14732)
		(layer "In11.Cu")
		(net "UPI_CPU1_CPU0_P2P2_DP<11>")
	)
	(segment
		(start 343.11463 -296.674032)
		(end 343.186512 -296.31259)
		(width 0.14732)
		(layer "In11.Cu")
		(net "UPI_CPU1_CPU0_P2P2_DP<11>")
	)
	(segment
		(start 68.189348 -359.913174)
		(end 68.189348 -359.913428)
		(width 0.14732)
		(layer "In11.Cu")
		(net "UPI_CPU1_CPU0_P2P2_DP<11>")
	)
	(segment
		(start 101.690424 -280.45664)
		(end 101.680264 -280.462482)
		(width 0.0889)
		(layer "In11.Cu")
		(net "UPI_CPU1_CPU0_P2P2_DP<11>")
	)
	(segment
		(start 101.694996 -280.453846)
		(end 101.690424 -280.45664)
		(width 0.0889)
		(layer "In11.Cu")
		(net "UPI_CPU1_CPU0_P2P2_DP<11>")
	)
	(segment
		(start 94.55785 -290.34359)
		(end 94.55785 -290.52139)
		(width 0.0889)
		(layer "In11.Cu")
		(net "UPI_CPU1_CPU0_P2P2_DP<11>")
	)
	(segment
		(start 343.386918 -295.305988)
		(end 343.557352 -295.192196)
		(width 0.14732)
		(layer "In11.Cu")
		(net "UPI_CPU1_CPU0_P2P2_DP<11>")
	)
	(segment
		(start 342.98636 -297.319192)
		(end 343.156794 -297.2054)
		(width 0.14732)
		(layer "In11.Cu")
		(net "UPI_CPU1_CPU0_P2P2_DP<11>")
	)
	(segment
		(start 314.45835 -326.907906)
		(end 315.556392 -324.2564)
		(width 0.14732)
		(layer "In11.Cu")
		(net "UPI_CPU1_CPU0_P2P2_DP<11>")
	)
	(segment
		(start 345.777058 -286.801814)
		(end 345.779852 -286.80029)
		(width 0.0889)
		(layer "In11.Cu")
		(net "UPI_CPU1_CPU0_P2P2_DP<11>")
	)
	(segment
		(start 87.896954 -304.072544)
		(end 78.699868 -311.620154)
		(width 0.14732)
		(layer "In11.Cu")
		(net "UPI_CPU1_CPU0_P2P2_DP<11>")
	)
	(segment
		(start 346.25026 -284.35808)
		(end 346.25915 -284.353)
		(width 0.0889)
		(layer "In11.Cu")
		(net "UPI_CPU1_CPU0_P2P2_DP<11>")
	)
	(segment
		(start 161.28238 -383.254504)
		(end 162.712908 -383.254504)
		(width 0.14732)
		(layer "In11.Cu")
		(net "UPI_CPU1_CPU0_P2P2_DP<11>")
	)
	(segment
		(start 348.587822 -278.667972)
		(end 348.600014 -278.66086)
		(width 0.0889)
		(layer "In11.Cu")
		(net "UPI_CPU1_CPU0_P2P2_DP<11>")
	)
	(segment
		(start 95.109538 -285.340806)
		(end 95.107506 -285.342076)
		(width 0.0889)
		(layer "In11.Cu")
		(net "UPI_CPU1_CPU0_P2P2_DP<11>")
	)
	(segment
		(start 340.737444 -301.083218)
		(end 342.495886 -299.324776)
		(width 0.14732)
		(layer "In11.Cu")
		(net "UPI_CPU1_CPU0_P2P2_DP<11>")
	)
	(segment
		(start 345.31046 -287.613598)
		(end 345.31935 -287.608518)
		(width 0.0889)
		(layer "In11.Cu")
		(net "UPI_CPU1_CPU0_P2P2_DP<11>")
	)
	(segment
		(start 342.956642 -298.211748)
		(end 343.02827 -297.850814)
		(width 0.14732)
		(layer "In11.Cu")
		(net "UPI_CPU1_CPU0_P2P2_DP<11>")
	)
	(segment
		(start 69.04609 -321.273932)
		(end 67.496944 -324.54977)
		(width 0.14732)
		(layer "In11.Cu")
		(net "UPI_CPU1_CPU0_P2P2_DP<11>")
	)
	(segment
		(start 343.557352 -295.192196)
		(end 343.556844 -295.192196)
		(width 0.14732)
		(layer "In11.Cu")
		(net "UPI_CPU1_CPU0_P2P2_DP<11>")
	)
	(segment
		(start 347.660214 -280.288492)
		(end 347.669104 -280.283412)
		(width 0.0889)
		(layer "In11.Cu")
		(net "UPI_CPU1_CPU0_P2P2_DP<11>")
	)
	(segment
		(start 99.627944 -280.778204)
		(end 99.627944 -280.793698)
		(width 0.0889)
		(layer "In11.Cu")
		(net "UPI_CPU1_CPU0_P2P2_DP<11>")
	)
	(segment
		(start 90.151458 -302.222154)
		(end 90.134694 -302.393604)
		(width 0.14732)
		(layer "In11.Cu")
		(net "UPI_CPU1_CPU0_P2P2_DP<11>")
	)
	(segment
		(start 345.774518 -285.175452)
		(end 345.780614 -285.171896)
		(width 0.0889)
		(layer "In11.Cu")
		(net "UPI_CPU1_CPU0_P2P2_DP<11>")
	)
	(segment
		(start 349.070676 -277.198582)
		(end 349.06966 -277.198074)
		(width 0.0889)
		(layer "In11.Cu")
		(net "UPI_CPU1_CPU0_P2P2_DP<11>")
	)
	(segment
		(start 350.560132 -274.582636)
		(end 350.574864 -274.591272)
		(width 0.0889)
		(layer "In11.Cu")
		(net "UPI_CPU1_CPU0_P2P2_DP<11>")
	)
	(segment
		(start 345.77528 -286.80283)
		(end 345.776296 -286.802322)
		(width 0.0889)
		(layer "In11.Cu")
		(net "UPI_CPU1_CPU0_P2P2_DP<11>")
	)
	(segment
		(start 89.79662 -302.670972)
		(end 89.62517 -302.654208)
		(width 0.14732)
		(layer "In11.Cu")
		(net "UPI_CPU1_CPU0_P2P2_DP<11>")
	)
	(segment
		(start 348.787212 -278.345138)
		(end 348.787212 -278.31796)
		(width 0.0889)
		(layer "In11.Cu")
		(net "UPI_CPU1_CPU0_P2P2_DP<11>")
	)
	(segment
		(start 346.723462 -283.542232)
		(end 346.72905 -283.539184)
		(width 0.0889)
		(layer "In11.Cu")
		(net "UPI_CPU1_CPU0_P2P2_DP<11>")
	)
	(segment
		(start 285.557214 -333.47787)
		(end 307.888386 -333.47787)
		(width 0.14732)
		(layer "In11.Cu")
		(net "UPI_CPU1_CPU0_P2P2_DP<11>")
	)
	(segment
		(start 345.028266 -289.64636)
		(end 345.028012 -289.645852)
		(width 0.0889)
		(layer "In11.Cu")
		(net "UPI_CPU1_CPU0_P2P2_DP<11>")
	)
	(segment
		(start 95.116396 -286.964882)
		(end 95.107506 -286.969962)
		(width 0.0889)
		(layer "In11.Cu")
		(net "UPI_CPU1_CPU0_P2P2_DP<11>")
	)
	(segment
		(start 261.304024 -374.866662)
		(end 270.03756 -366.133126)
		(width 0.14732)
		(layer "In11.Cu")
		(net "UPI_CPU1_CPU0_P2P2_DP<11>")
	)
	(segment
		(start 345.774518 -286.803338)
		(end 345.77528 -286.80283)
		(width 0.0889)
		(layer "In11.Cu")
		(net "UPI_CPU1_CPU0_P2P2_DP<11>")
	)
	(segment
		(start 95.58655 -284.52318)
		(end 95.57766 -284.52826)
		(width 0.0889)
		(layer "In11.Cu")
		(net "UPI_CPU1_CPU0_P2P2_DP<11>")
	)
	(segment
		(start 96.056196 -283.709364)
		(end 96.047306 -283.714444)
		(width 0.0889)
		(layer "In11.Cu")
		(net "UPI_CPU1_CPU0_P2P2_DP<11>")
	)
	(segment
		(start 88.423496 -303.64049)
		(end 88.406478 -303.81194)
		(width 0.14732)
		(layer "In11.Cu")
		(net "UPI_CPU1_CPU0_P2P2_DP<11>")
	)
	(segment
		(start 94.45879 -289.609784)
		(end 94.45879 -290.24453)
		(width 0.0889)
		(layer "In11.Cu")
		(net "UPI_CPU1_CPU0_P2P2_DP<11>")
	)
	(segment
		(start 102.117652 -279.672288)
		(end 102.117144 -279.672034)
		(width 0.0889)
		(layer "In11.Cu")
		(net "UPI_CPU1_CPU0_P2P2_DP<11>")
	)
	(segment
		(start 162.712908 -383.254504)
		(end 163.168584 -383.178558)
		(width 0.14732)
		(layer "In11.Cu")
		(net "UPI_CPU1_CPU0_P2P2_DP<11>")
	)
	(segment
		(start 342.495886 -299.324776)
		(end 342.955372 -298.211494)
		(width 0.14732)
		(layer "In11.Cu")
		(net "UPI_CPU1_CPU0_P2P2_DP<11>")
	)
	(segment
		(start 343.627964 -294.093646)
		(end 343.798398 -293.979854)
		(width 0.14732)
		(layer "In11.Cu")
		(net "UPI_CPU1_CPU0_P2P2_DP<11>")
	)
	(arc
		(start 347.377512 -282.405836)
		(mid 347.329833 -282.222936)
		(end 347.19895 -282.086558)
		(width 0.0889)
		(layer "In11.Cu")
		(net "UPI_CPU1_CPU0_P2P2_DP<11>")
	)
	(arc
		(start 345.780614 -286.799782)
		(mid 345.915547 -286.666428)
		(end 345.967812 -286.48406)
		(width 0.0889)
		(layer "In11.Cu")
		(net "UPI_CPU1_CPU0_P2P2_DP<11>")
	)
	(arc
		(start 345.028012 -289.645852)
		(mid 344.953007 -289.530393)
		(end 344.843862 -289.446462)
		(width 0.0889)
		(layer "In11.Cu")
		(net "UPI_CPU1_CPU0_P2P2_DP<11>")
	)
	(arc
		(start 101.977698 -279.966166)
		(mid 101.904302 -280.242979)
		(end 101.704648 -280.448258)
		(width 0.0889)
		(layer "In11.Cu")
		(net "UPI_CPU1_CPU0_P2P2_DP<11>")
	)
	(arc
		(start 94.459298 -288.121598)
		(mid 94.379136 -288.393787)
		(end 94.17685 -288.592768)
		(width 0.0889)
		(layer "In11.Cu")
		(net "UPI_CPU1_CPU0_P2P2_DP<11>")
	)
	(arc
		(start 97.278698 -283.219906)
		(mid 97.204707 -283.499472)
		(end 97.002092 -283.705808)
		(width 0.0889)
		(layer "In11.Cu")
		(net "UPI_CPU1_CPU0_P2P2_DP<11>")
	)
	(arc
		(start 95.116396 -285.985712)
		(mid 95.321468 -286.189391)
		(end 95.399098 -286.467804)
		(width 0.0889)
		(layer "In11.Cu")
		(net "UPI_CPU1_CPU0_P2P2_DP<11>")
	)
	(arc
		(start 348.787466 -276.69871)
		(mid 348.865577 -276.421761)
		(end 349.069914 -276.219158)
		(width 0.0889)
		(layer "In11.Cu")
		(net "UPI_CPU1_CPU0_P2P2_DP<11>")
	)
	(arc
		(start 348.317312 -279.150318)
		(mid 348.389547 -278.873794)
		(end 348.587822 -278.667972)
		(width 0.0889)
		(layer "In11.Cu")
		(net "UPI_CPU1_CPU0_P2P2_DP<11>")
	)
	(arc
		(start 345.780614 -286.151066)
		(mid 345.577133 -285.950262)
		(end 345.497912 -285.675578)
		(width 0.0889)
		(layer "In11.Cu")
		(net "UPI_CPU1_CPU0_P2P2_DP<11>")
	)
	(arc
		(start 346.72905 -283.539184)
		(mid 346.859964 -283.402824)
		(end 346.907612 -283.219906)
		(width 0.0889)
		(layer "In11.Cu")
		(net "UPI_CPU1_CPU0_P2P2_DP<11>")
	)
	(arc
		(start 96.981264 -283.718)
		(mid 96.704789 -283.78532)
		(end 96.430592 -283.709364)
		(width 0.0889)
		(layer "In11.Cu")
		(net "UPI_CPU1_CPU0_P2P2_DP<11>")
	)
	(arc
		(start 99.627944 -280.793698)
		(mid 99.548574 -281.067432)
		(end 99.34575 -281.267662)
		(width 0.0889)
		(layer "In11.Cu")
		(net "UPI_CPU1_CPU0_P2P2_DP<11>")
	)
	(arc
		(start 347.19006 -282.081478)
		(mid 346.987237 -281.881247)
		(end 346.907866 -281.607514)
		(width 0.0889)
		(layer "In11.Cu")
		(net "UPI_CPU1_CPU0_P2P2_DP<11>")
	)
	(arc
		(start 99.158298 -281.59202)
		(mid 99.084307 -281.871586)
		(end 98.881692 -282.077922)
		(width 0.0889)
		(layer "In11.Cu")
		(net "UPI_CPU1_CPU0_P2P2_DP<11>")
	)
	(arc
		(start 347.19895 -281.097482)
		(mid 347.329864 -280.961122)
		(end 347.377512 -280.778204)
		(width 0.0889)
		(layer "In11.Cu")
		(net "UPI_CPU1_CPU0_P2P2_DP<11>")
	)
	(arc
		(start 345.497912 -287.28924)
		(mid 345.571903 -287.009674)
		(end 345.774518 -286.803338)
		(width 0.0889)
		(layer "In11.Cu")
		(net "UPI_CPU1_CPU0_P2P2_DP<11>")
	)
	(arc
		(start 347.669104 -280.283412)
		(mid 347.800018 -280.147052)
		(end 347.847666 -279.964134)
		(width 0.0889)
		(layer "In11.Cu")
		(net "UPI_CPU1_CPU0_P2P2_DP<11>")
	)
	(arc
		(start 95.107506 -286.969962)
		(mid 94.976592 -287.106322)
		(end 94.928944 -287.28924)
		(width 0.0889)
		(layer "In11.Cu")
		(net "UPI_CPU1_CPU0_P2P2_DP<11>")
	)
	(arc
		(start 345.31935 -287.608518)
		(mid 345.450264 -287.472158)
		(end 345.497912 -287.28924)
		(width 0.0889)
		(layer "In11.Cu")
		(net "UPI_CPU1_CPU0_P2P2_DP<11>")
	)
	(arc
		(start 98.405696 -282.895548)
		(mid 98.122994 -282.97129)
		(end 97.840292 -282.895548)
		(width 0.0889)
		(layer "In11.Cu")
		(net "UPI_CPU1_CPU0_P2P2_DP<11>")
	)
	(arc
		(start 349.727266 -275.065236)
		(mid 349.806636 -274.791502)
		(end 350.00946 -274.591272)
		(width 0.0889)
		(layer "In11.Cu")
		(net "UPI_CPU1_CPU0_P2P2_DP<11>")
	)
	(arc
		(start 351.542604 -274.607528)
		(mid 351.672533 -274.6476)
		(end 351.807018 -274.627594)
		(width 0.0889)
		(layer "In11.Cu")
		(net "UPI_CPU1_CPU0_P2P2_DP<11>")
	)
	(arc
		(start 348.600014 -278.66086)
		(mid 348.734947 -278.527506)
		(end 348.787212 -278.345138)
		(width 0.0889)
		(layer "In11.Cu")
		(net "UPI_CPU1_CPU0_P2P2_DP<11>")
	)
	(arc
		(start 350.574864 -274.591272)
		(mid 350.762062 -274.641415)
		(end 350.94926 -274.591272)
		(width 0.0889)
		(layer "In11.Cu")
		(net "UPI_CPU1_CPU0_P2P2_DP<11>")
	)
	(arc
		(start 345.968066 -284.832044)
		(mid 346.047436 -284.55831)
		(end 346.25026 -284.35808)
		(width 0.0889)
		(layer "In11.Cu")
		(net "UPI_CPU1_CPU0_P2P2_DP<11>")
	)
	(arc
		(start 97.465896 -282.895548)
		(mid 97.330963 -283.028902)
		(end 97.278698 -283.21127)
		(width 0.0889)
		(layer "In11.Cu")
		(net "UPI_CPU1_CPU0_P2P2_DP<11>")
	)
	(arc
		(start 346.25915 -284.353)
		(mid 346.390064 -284.21664)
		(end 346.437712 -284.033722)
		(width 0.0889)
		(layer "In11.Cu")
		(net "UPI_CPU1_CPU0_P2P2_DP<11>")
	)
	(arc
		(start 94.928944 -287.304734)
		(mid 94.849574 -287.578468)
		(end 94.64675 -287.778698)
		(width 0.0889)
		(layer "In11.Cu")
		(net "UPI_CPU1_CPU0_P2P2_DP<11>")
	)
	(arc
		(start 95.868744 -284.049216)
		(mid 95.789374 -284.32295)
		(end 95.58655 -284.52318)
		(width 0.0889)
		(layer "In11.Cu")
		(net "UPI_CPU1_CPU0_P2P2_DP<11>")
	)
	(arc
		(start 347.19895 -282.725114)
		(mid 347.326204 -282.595148)
		(end 347.377258 -282.420568)
		(width 0.0889)
		(layer "In11.Cu")
		(net "UPI_CPU1_CPU0_P2P2_DP<11>")
	)
	(arc
		(start 347.377512 -280.76398)
		(mid 347.456731 -280.489295)
		(end 347.660214 -280.288492)
		(width 0.0889)
		(layer "In11.Cu")
		(net "UPI_CPU1_CPU0_P2P2_DP<11>")
	)
	(arc
		(start 344.558366 -288.898584)
		(mid 344.638528 -288.626395)
		(end 344.840814 -288.427414)
		(width 0.0889)
		(layer "In11.Cu")
		(net "UPI_CPU1_CPU0_P2P2_DP<11>")
	)
	(arc
		(start 94.16796 -288.597848)
		(mid 94.037046 -288.734208)
		(end 93.989398 -288.917126)
		(width 0.0889)
		(layer "In11.Cu")
		(net "UPI_CPU1_CPU0_P2P2_DP<11>")
	)
	(arc
		(start 346.437712 -284.023816)
		(mid 346.515823 -283.746867)
		(end 346.72016 -283.544264)
		(width 0.0889)
		(layer "In11.Cu")
		(net "UPI_CPU1_CPU0_P2P2_DP<11>")
	)
	(arc
		(start 94.443296 -289.569398)
		(mid 94.451527 -289.589324)
		(end 94.459044 -289.60953)
		(width 0.0889)
		(layer "In11.Cu")
		(net "UPI_CPU1_CPU0_P2P2_DP<11>")
	)
	(arc
		(start 349.07855 -277.84171)
		(mid 349.257147 -277.522432)
		(end 349.07855 -277.203154)
		(width 0.0889)
		(layer "In11.Cu")
		(net "UPI_CPU1_CPU0_P2P2_DP<11>")
	)
	(arc
		(start 350.00946 -274.591272)
		(mid 350.283659 -274.515437)
		(end 350.560132 -274.582636)
		(width 0.0889)
		(layer "In11.Cu")
		(net "UPI_CPU1_CPU0_P2P2_DP<11>")
	)
	(arc
		(start 94.63786 -287.783778)
		(mid 94.506946 -287.920138)
		(end 94.459298 -288.103056)
		(width 0.0889)
		(layer "In11.Cu")
		(net "UPI_CPU1_CPU0_P2P2_DP<11>")
	)
	(arc
		(start 98.866706 -282.086558)
		(mid 98.735792 -282.222918)
		(end 98.688144 -282.405836)
		(width 0.0889)
		(layer "In11.Cu")
		(net "UPI_CPU1_CPU0_P2P2_DP<11>")
	)
	(arc
		(start 101.129592 -280.453846)
		(mid 100.942394 -280.403703)
		(end 100.755196 -280.453846)
		(width 0.0889)
		(layer "In11.Cu")
		(net "UPI_CPU1_CPU0_P2P2_DP<11>")
	)
	(arc
		(start 349.069914 -276.219158)
		(mid 349.204847 -276.085804)
		(end 349.257112 -275.903436)
		(width 0.0889)
		(layer "In11.Cu")
		(net "UPI_CPU1_CPU0_P2P2_DP<11>")
	)
	(arc
		(start 347.377258 -282.420568)
		(mid 347.377455 -282.413203)
		(end 347.377512 -282.405836)
		(width 0.0889)
		(layer "In11.Cu")
		(net "UPI_CPU1_CPU0_P2P2_DP<11>")
	)
	(arc
		(start 98.688144 -282.424378)
		(mid 98.607982 -282.696567)
		(end 98.405696 -282.895548)
		(width 0.0889)
		(layer "In11.Cu")
		(net "UPI_CPU1_CPU0_P2P2_DP<11>")
	)
	(arc
		(start 95.57766 -284.52826)
		(mid 95.446746 -284.66462)
		(end 95.399098 -284.847538)
		(width 0.0889)
		(layer "In11.Cu")
		(net "UPI_CPU1_CPU0_P2P2_DP<11>")
	)
	(arc
		(start 345.497912 -285.661354)
		(mid 345.571903 -285.381788)
		(end 345.774518 -285.175452)
		(width 0.0889)
		(layer "In11.Cu")
		(net "UPI_CPU1_CPU0_P2P2_DP<11>")
	)
	(arc
		(start 349.548704 -275.400008)
		(mid 349.679618 -275.263648)
		(end 349.727266 -275.08073)
		(width 0.0889)
		(layer "In11.Cu")
		(net "UPI_CPU1_CPU0_P2P2_DP<11>")
	)
	(arc
		(start 97.840292 -282.895548)
		(mid 97.653094 -282.845405)
		(end 97.465896 -282.895548)
		(width 0.0889)
		(layer "In11.Cu")
		(net "UPI_CPU1_CPU0_P2P2_DP<11>")
	)
	(arc
		(start 100.740464 -280.462482)
		(mid 100.464023 -280.529648)
		(end 100.189792 -280.453846)
		(width 0.0889)
		(layer "In11.Cu")
		(net "UPI_CPU1_CPU0_P2P2_DP<11>")
	)
	(arc
		(start 96.047306 -283.714444)
		(mid 95.916392 -283.850804)
		(end 95.868744 -284.033722)
		(width 0.0889)
		(layer "In11.Cu")
		(net "UPI_CPU1_CPU0_P2P2_DP<11>")
	)
	(arc
		(start 344.849704 -288.422334)
		(mid 344.980618 -288.285974)
		(end 345.028266 -288.103056)
		(width 0.0889)
		(layer "In11.Cu")
		(net "UPI_CPU1_CPU0_P2P2_DP<11>")
	)
	(arc
		(start 95.107506 -285.342076)
		(mid 94.928909 -285.661354)
		(end 95.107506 -285.980632)
		(width 0.0889)
		(layer "In11.Cu")
		(net "UPI_CPU1_CPU0_P2P2_DP<11>")
	)
	(arc
		(start 94.173548 -289.277806)
		(mid 94.333326 -289.400568)
		(end 94.443296 -289.569398)
		(width 0.0889)
		(layer "In11.Cu")
		(net "UPI_CPU1_CPU0_P2P2_DP<11>")
	)
	(arc
		(start 99.33686 -281.272742)
		(mid 99.205946 -281.409102)
		(end 99.158298 -281.59202)
		(width 0.0889)
		(layer "In11.Cu")
		(net "UPI_CPU1_CPU0_P2P2_DP<11>")
	)
	(arc
		(start 344.843862 -289.446462)
		(mid 344.66973 -289.307615)
		(end 344.558366 -289.114738)
		(width 0.0889)
		(layer "In11.Cu")
		(net "UPI_CPU1_CPU0_P2P2_DP<11>")
	)
	(arc
		(start 345.028266 -288.087562)
		(mid 345.107636 -287.813828)
		(end 345.31046 -287.613598)
		(width 0.0889)
		(layer "In11.Cu")
		(net "UPI_CPU1_CPU0_P2P2_DP<11>")
	)
	(arc
		(start 95.399098 -284.847538)
		(mid 95.325107 -285.127104)
		(end 95.122492 -285.33344)
		(width 0.0889)
		(layer "In11.Cu")
		(net "UPI_CPU1_CPU0_P2P2_DP<11>")
	)
	(arc
		(start 102.098348 -279.687274)
		(mid 102.011947 -279.795057)
		(end 101.97846 -279.929082)
		(width 0.0889)
		(layer "In11.Cu")
		(net "UPI_CPU1_CPU0_P2P2_DP<11>")
	)
	(arc
		(start 349.06966 -277.198074)
		(mid 348.866837 -276.997843)
		(end 348.787466 -276.72411)
		(width 0.0889)
		(layer "In11.Cu")
		(net "UPI_CPU1_CPU0_P2P2_DP<11>")
	)
	(arc
		(start 346.907612 -283.205682)
		(mid 346.986753 -282.931059)
		(end 347.19006 -282.730194)
		(width 0.0889)
		(layer "In11.Cu")
		(net "UPI_CPU1_CPU0_P2P2_DP<11>")
	)
	(arc
		(start 95.399098 -286.475424)
		(mid 95.326863 -286.751948)
		(end 95.128588 -286.95777)
		(width 0.0889)
		(layer "In11.Cu")
		(net "UPI_CPU1_CPU0_P2P2_DP<11>")
	)
	(arc
		(start 348.787212 -278.31796)
		(mid 348.867374 -278.045771)
		(end 349.06966 -277.84679)
		(width 0.0889)
		(layer "In11.Cu")
		(net "UPI_CPU1_CPU0_P2P2_DP<11>")
	)
	(arc
		(start 99.806506 -280.458926)
		(mid 99.675592 -280.595286)
		(end 99.627944 -280.778204)
		(width 0.0889)
		(layer "In11.Cu")
		(net "UPI_CPU1_CPU0_P2P2_DP<11>")
	)
	(arc
		(start 101.680264 -280.462482)
		(mid 101.403823 -280.529648)
		(end 101.129592 -280.453846)
		(width 0.0889)
		(layer "In11.Cu")
		(net "UPI_CPU1_CPU0_P2P2_DP<11>")
	)
	(arc
		(start 93.989398 -289.078416)
		(mid 94.064403 -289.193875)
		(end 94.173548 -289.277806)
		(width 0.0889)
		(layer "In11.Cu")
		(net "UPI_CPU1_CPU0_P2P2_DP<11>")
	)
	(arc
		(start 100.189792 -280.453846)
		(mid 100.002594 -280.403703)
		(end 99.815396 -280.453846)
		(width 0.0889)
		(layer "In11.Cu")
		(net "UPI_CPU1_CPU0_P2P2_DP<11>")
	)
	(arc
		(start 350.94926 -274.591272)
		(mid 351.223459 -274.515437)
		(end 351.499932 -274.582636)
		(width 0.0889)
		(layer "In11.Cu")
		(net "UPI_CPU1_CPU0_P2P2_DP<11>")
	)
	(arc
		(start 348.13875 -279.469596)
		(mid 348.269664 -279.333236)
		(end 348.317312 -279.150318)
		(width 0.0889)
		(layer "In11.Cu")
		(net "UPI_CPU1_CPU0_P2P2_DP<11>")
	)
	(arc
		(start 345.967812 -286.466788)
		(mid 345.915542 -286.284423)
		(end 345.780614 -286.151066)
		(width 0.0889)
		(layer "In11.Cu")
		(net "UPI_CPU1_CPU0_P2P2_DP<11>")
	)
	(arc
		(start 349.257112 -275.880576)
		(mid 349.336331 -275.605891)
		(end 349.539814 -275.405088)
		(width 0.0889)
		(layer "In11.Cu")
		(net "UPI_CPU1_CPU0_P2P2_DP<11>")
	)
	(arc
		(start 96.430592 -283.709364)
		(mid 96.243394 -283.659221)
		(end 96.056196 -283.709364)
		(width 0.0889)
		(layer "In11.Cu")
		(net "UPI_CPU1_CPU0_P2P2_DP<11>")
	)
	(arc
		(start 347.847666 -279.94864)
		(mid 347.927036 -279.674906)
		(end 348.12986 -279.474676)
		(width 0.0889)
		(layer "In11.Cu")
		(net "UPI_CPU1_CPU0_P2P2_DP<11>")
	)
	(arc
		(start 346.907866 -281.576526)
		(mid 346.987236 -281.302792)
		(end 347.19006 -281.102562)
		(width 0.0889)
		(layer "In11.Cu")
		(net "UPI_CPU1_CPU0_P2P2_DP<11>")
	)
	(arc
		(start 345.789504 -285.166816)
		(mid 345.920418 -285.030456)
		(end 345.968066 -284.847538)
		(width 0.0889)
		(layer "In11.Cu")
		(net "UPI_CPU1_CPU0_P2P2_DP<11>")
	)
	(segment
		(start 103.762048 -278.614378)
		(end 103.762048 -279.150064)
		(width 0.13208)
		(layer "F.Cu")
		(net "UPI_CPU1_CPU0_P2P2_DP<10>")
	)
	(segment
		(start 351.231962 -275.080476)
		(end 351.232216 -275.08073)
		(width 0.13208)
		(layer "F.Cu")
		(net "UPI_CPU1_CPU0_P2P2_DP<10>")
	)
	(segment
		(start 103.762048 -279.150064)
		(end 103.761794 -279.150318)
		(width 0.13208)
		(layer "F.Cu")
		(net "UPI_CPU1_CPU0_P2P2_DP<10>")
	)
	(segment
		(start 351.231962 -274.54479)
		(end 351.231962 -275.080476)
		(width 0.13208)
		(layer "F.Cu")
		(net "UPI_CPU1_CPU0_P2P2_DP<10>")
	)
	(segment
		(start 347.568012 -284.049216)
		(end 347.568012 -284.033722)
		(width 0.0889)
		(layer "In11.Cu")
		(net "UPI_CPU1_CPU0_P2P2_DP<10>")
	)
	(segment
		(start 66.459354 -324.160388)
		(end 65.105534 -329.053698)
		(width 0.14732)
		(layer "In11.Cu")
		(net "UPI_CPU1_CPU0_P2P2_DP<10>")
	)
	(segment
		(start 350.387412 -275.904706)
		(end 350.387412 -275.8948)
		(width 0.0889)
		(layer "In11.Cu")
		(net "UPI_CPU1_CPU0_P2P2_DP<10>")
	)
	(segment
		(start 348.695264 -281.102562)
		(end 348.686374 -281.097482)
		(width 0.0889)
		(layer "In11.Cu")
		(net "UPI_CPU1_CPU0_P2P2_DP<10>")
	)
	(segment
		(start 344.220292 -298.152312)
		(end 345.021408 -294.12438)
		(width 0.14732)
		(layer "In11.Cu")
		(net "UPI_CPU1_CPU0_P2P2_DP<10>")
	)
	(segment
		(start 93.798644 -285.661354)
		(end 93.798644 -285.675578)
		(width 0.0889)
		(layer "In11.Cu")
		(net "UPI_CPU1_CPU0_P2P2_DP<10>")
	)
	(segment
		(start 285.811214 -334.58023)
		(end 308.347618 -334.58023)
		(width 0.14732)
		(layer "In11.Cu")
		(net "UPI_CPU1_CPU0_P2P2_DP<10>")
	)
	(segment
		(start 102.554278 -278.652224)
		(end 102.539546 -278.66086)
		(width 0.0889)
		(layer "In11.Cu")
		(net "UPI_CPU1_CPU0_P2P2_DP<10>")
	)
	(segment
		(start 346.337128 -287.783778)
		(end 346.346018 -287.778698)
		(width 0.0889)
		(layer "In11.Cu")
		(net "UPI_CPU1_CPU0_P2P2_DP<10>")
	)
	(segment
		(start 94.080584 -286.80029)
		(end 94.07525 -286.803338)
		(width 0.0889)
		(layer "In11.Cu")
		(net "UPI_CPU1_CPU0_P2P2_DP<10>")
	)
	(segment
		(start 94.738444 -284.023816)
		(end 94.738444 -284.033722)
		(width 0.0889)
		(layer "In11.Cu")
		(net "UPI_CPU1_CPU0_P2P2_DP<10>")
	)
	(segment
		(start 350.85401 -275.146262)
		(end 350.919542 -275.08073)
		(width 0.0889)
		(layer "In11.Cu")
		(net "UPI_CPU1_CPU0_P2P2_DP<10>")
	)
	(segment
		(start 103.761794 -279.150318)
		(end 103.44912 -279.150318)
		(width 0.0889)
		(layer "In11.Cu")
		(net "UPI_CPU1_CPU0_P2P2_DP<10>")
	)
	(segment
		(start 94.268544 -286.466788)
		(end 94.268544 -286.48406)
		(width 0.0889)
		(layer "In11.Cu")
		(net "UPI_CPU1_CPU0_P2P2_DP<10>")
	)
	(segment
		(start 349.447866 -279.160224)
		(end 349.447866 -279.141682)
		(width 0.0889)
		(layer "In11.Cu")
		(net "UPI_CPU1_CPU0_P2P2_DP<10>")
	)
	(segment
		(start 347.75394 -283.71038)
		(end 347.76156 -283.705808)
		(width 0.0889)
		(layer "In11.Cu")
		(net "UPI_CPU1_CPU0_P2P2_DP<10>")
	)
	(segment
		(start 94.081346 -286.799782)
		(end 94.080584 -286.80029)
		(width 0.0889)
		(layer "In11.Cu")
		(net "UPI_CPU1_CPU0_P2P2_DP<10>")
	)
	(segment
		(start 93.150436 -288.422334)
		(end 93.141546 -288.427414)
		(width 0.0889)
		(layer "In11.Cu")
		(net "UPI_CPU1_CPU0_P2P2_DP<10>")
	)
	(segment
		(start 94.090236 -285.166562)
		(end 94.086172 -285.168848)
		(width 0.0889)
		(layer "In11.Cu")
		(net "UPI_CPU1_CPU0_P2P2_DP<10>")
	)
	(segment
		(start 92.165932 -299.3136)
		(end 91.02344 -300.25086)
		(width 0.14732)
		(layer "In11.Cu")
		(net "UPI_CPU1_CPU0_P2P2_DP<10>")
	)
	(segment
		(start 341.365332 -302.016922)
		(end 343.453974 -299.92828)
		(width 0.14732)
		(layer "In11.Cu")
		(net "UPI_CPU1_CPU0_P2P2_DP<10>")
	)
	(segment
		(start 65.105534 -329.053698)
		(end 64.766698 -332.494636)
		(width 0.14732)
		(layer "In11.Cu")
		(net "UPI_CPU1_CPU0_P2P2_DP<10>")
	)
	(segment
		(start 349.156528 -279.644856)
		(end 349.165418 -279.639776)
		(width 0.0889)
		(layer "In11.Cu")
		(net "UPI_CPU1_CPU0_P2P2_DP<10>")
	)
	(segment
		(start 93.287088 -294.080946)
		(end 93.287088 -296.987468)
		(width 0.14732)
		(layer "In11.Cu")
		(net "UPI_CPU1_CPU0_P2P2_DP<10>")
	)
	(segment
		(start 96.915478 -281.907742)
		(end 96.900746 -281.916378)
		(width 0.0889)
		(layer "In11.Cu")
		(net "UPI_CPU1_CPU0_P2P2_DP<10>")
	)
	(segment
		(start 345.026488 -291.496496)
		(end 345.026488 -291.474398)
		(width 0.0889)
		(layer "In11.Cu")
		(net "UPI_CPU1_CPU0_P2P2_DP<10>")
	)
	(segment
		(start 316.50686 -324.869048)
		(end 337.940142 -303.435766)
		(width 0.14732)
		(layer "In11.Cu")
		(net "UPI_CPU1_CPU0_P2P2_DP<10>")
	)
	(segment
		(start 69.578728 -366.159542)
		(end 74.302874 -370.883688)
		(width 0.14732)
		(layer "In11.Cu")
		(net "UPI_CPU1_CPU0_P2P2_DP<10>")
	)
	(segment
		(start 97.849436 -281.911298)
		(end 97.84207 -281.915616)
		(width 0.0889)
		(layer "In11.Cu")
		(net "UPI_CPU1_CPU0_P2P2_DP<10>")
	)
	(segment
		(start 344.042492 -298.507404)
		(end 344.220292 -298.152312)
		(width 0.14732)
		(layer "In11.Cu")
		(net "UPI_CPU1_CPU0_P2P2_DP<10>")
	)
	(segment
		(start 101.225096 -278.66086)
		(end 101.214682 -278.654764)
		(width 0.0889)
		(layer "In11.Cu")
		(net "UPI_CPU1_CPU0_P2P2_DP<10>")
	)
	(segment
		(start 96.37776 -380.026926)
		(end 125.668024 -384.37185)
		(width 0.14732)
		(layer "In11.Cu")
		(net "UPI_CPU1_CPU0_P2P2_DP<10>")
	)
	(segment
		(start 339.602318 -302.747172)
		(end 339.602572 -302.747172)
		(width 0.14732)
		(layer "In11.Cu")
		(net "UPI_CPU1_CPU0_P2P2_DP<10>")
	)
	(segment
		(start 281.073352 -336.542888)
		(end 285.811214 -334.58023)
		(width 0.14732)
		(layer "In11.Cu")
		(net "UPI_CPU1_CPU0_P2P2_DP<10>")
	)
	(segment
		(start 92.859098 -288.898584)
		(end 92.859098 -289.114738)
		(width 0.0889)
		(layer "In11.Cu")
		(net "UPI_CPU1_CPU0_P2P2_DP<10>")
	)
	(segment
		(start 101.609906 -278.654764)
		(end 101.599492 -278.66086)
		(width 0.0889)
		(layer "In11.Cu")
		(net "UPI_CPU1_CPU0_P2P2_DP<10>")
	)
	(segment
		(start 350.919542 -275.08073)
		(end 351.232216 -275.08073)
		(width 0.0889)
		(layer "In11.Cu")
		(net "UPI_CPU1_CPU0_P2P2_DP<10>")
	)
	(segment
		(start 349.917766 -276.717252)
		(end 349.917766 -276.69998)
		(width 0.0889)
		(layer "In11.Cu")
		(net "UPI_CPU1_CPU0_P2P2_DP<10>")
	)
	(segment
		(start 91.02344 -300.25086)
		(end 90.380058 -300.446186)
		(width 0.14732)
		(layer "In11.Cu")
		(net "UPI_CPU1_CPU0_P2P2_DP<10>")
	)
	(segment
		(start 346.158566 -288.121598)
		(end 346.158566 -288.103056)
		(width 0.0889)
		(layer "In11.Cu")
		(net "UPI_CPU1_CPU0_P2P2_DP<10>")
	)
	(segment
		(start 344.984324 -291.232844)
		(end 346.158312 -290.058856)
		(width 0.0889)
		(layer "In11.Cu")
		(net "UPI_CPU1_CPU0_P2P2_DP<10>")
	)
	(segment
		(start 125.668024 -384.37185)
		(end 161.168842 -384.37185)
		(width 0.14732)
		(layer "In11.Cu")
		(net "UPI_CPU1_CPU0_P2P2_DP<10>")
	)
	(segment
		(start 98.319082 -281.097482)
		(end 98.310192 -281.102562)
		(width 0.0889)
		(layer "In11.Cu")
		(net "UPI_CPU1_CPU0_P2P2_DP<10>")
	)
	(segment
		(start 93.328998 -294.016938)
		(end 93.287088 -294.058848)
		(width 0.0889)
		(layer "In11.Cu")
		(net "UPI_CPU1_CPU0_P2P2_DP<10>")
	)
	(segment
		(start 346.158312 -290.058856)
		(end 346.158312 -289.60953)
		(width 0.0889)
		(layer "In11.Cu")
		(net "UPI_CPU1_CPU0_P2P2_DP<10>")
	)
	(segment
		(start 99.815396 -279.474676)
		(end 99.800664 -279.46604)
		(width 0.0889)
		(layer "In11.Cu")
		(net "UPI_CPU1_CPU0_P2P2_DP<10>")
	)
	(segment
		(start 339.602572 -302.747172)
		(end 341.365332 -302.016922)
		(width 0.14732)
		(layer "In11.Cu")
		(net "UPI_CPU1_CPU0_P2P2_DP<10>")
	)
	(segment
		(start 93.287088 -294.058848)
		(end 93.287088 -294.080946)
		(width 0.0889)
		(layer "In11.Cu")
		(net "UPI_CPU1_CPU0_P2P2_DP<10>")
	)
	(segment
		(start 350.11106 -277.03653)
		(end 350.104964 -277.032974)
		(width 0.0889)
		(layer "In11.Cu")
		(net "UPI_CPU1_CPU0_P2P2_DP<10>")
	)
	(segment
		(start 348.686374 -282.086558)
		(end 348.695264 -282.081478)
		(width 0.0889)
		(layer "In11.Cu")
		(net "UPI_CPU1_CPU0_P2P2_DP<10>")
	)
	(segment
		(start 74.302874 -370.883688)
		(end 96.37776 -380.026926)
		(width 0.14732)
		(layer "In11.Cu")
		(net "UPI_CPU1_CPU0_P2P2_DP<10>")
	)
	(segment
		(start 162.763962 -384.363722)
		(end 261.76732 -375.962672)
		(width 0.14732)
		(layer "In11.Cu")
		(net "UPI_CPU1_CPU0_P2P2_DP<10>")
	)
	(segment
		(start 93.328744 -289.64509)
		(end 93.328998 -289.645598)
		(width 0.0889)
		(layer "In11.Cu")
		(net "UPI_CPU1_CPU0_P2P2_DP<10>")
	)
	(segment
		(start 348.977966 -279.978358)
		(end 348.977966 -279.964134)
		(width 0.0889)
		(layer "In11.Cu")
		(net "UPI_CPU1_CPU0_P2P2_DP<10>")
	)
	(segment
		(start 100.659946 -278.66086)
		(end 100.647754 -278.667972)
		(width 0.0889)
		(layer "In11.Cu")
		(net "UPI_CPU1_CPU0_P2P2_DP<10>")
	)
	(segment
		(start 347.098366 -286.475424)
		(end 347.098366 -286.467804)
		(width 0.0889)
		(layer "In11.Cu")
		(net "UPI_CPU1_CPU0_P2P2_DP<10>")
	)
	(segment
		(start 345.688666 -289.078416)
		(end 345.688666 -288.917126)
		(width 0.0889)
		(layer "In11.Cu")
		(net "UPI_CPU1_CPU0_P2P2_DP<10>")
	)
	(segment
		(start 68.129404 -320.628264)
		(end 66.459354 -324.160388)
		(width 0.14732)
		(layer "In11.Cu")
		(net "UPI_CPU1_CPU0_P2P2_DP<10>")
	)
	(segment
		(start 95.029782 -283.539184)
		(end 95.020892 -283.544264)
		(width 0.0889)
		(layer "In11.Cu")
		(net "UPI_CPU1_CPU0_P2P2_DP<10>")
	)
	(segment
		(start 94.559882 -284.353)
		(end 94.550992 -284.35808)
		(width 0.0889)
		(layer "In11.Cu")
		(net "UPI_CPU1_CPU0_P2P2_DP<10>")
	)
	(segment
		(start 347.276928 -284.52826)
		(end 347.285818 -284.52318)
		(width 0.0889)
		(layer "In11.Cu")
		(net "UPI_CPU1_CPU0_P2P2_DP<10>")
	)
	(segment
		(start 93.620082 -287.608518)
		(end 93.611192 -287.613598)
		(width 0.0889)
		(layer "In11.Cu")
		(net "UPI_CPU1_CPU0_P2P2_DP<10>")
	)
	(segment
		(start 98.967798 -279.94864)
		(end 98.967798 -279.964134)
		(width 0.0889)
		(layer "In11.Cu")
		(net "UPI_CPU1_CPU0_P2P2_DP<10>")
	)
	(segment
		(start 94.08287 -285.17088)
		(end 94.07525 -285.175452)
		(width 0.0889)
		(layer "In11.Cu")
		(net "UPI_CPU1_CPU0_P2P2_DP<10>")
	)
	(segment
		(start 261.76732 -375.962672)
		(end 271.13992 -366.590072)
		(width 0.14732)
		(layer "In11.Cu")
		(net "UPI_CPU1_CPU0_P2P2_DP<10>")
	)
	(segment
		(start 94.084648 -285.169864)
		(end 94.08287 -285.17088)
		(width 0.0889)
		(layer "In11.Cu")
		(net "UPI_CPU1_CPU0_P2P2_DP<10>")
	)
	(segment
		(start 345.026488 -294.1193)
		(end 345.026488 -291.496496)
		(width 0.14732)
		(layer "In11.Cu")
		(net "UPI_CPU1_CPU0_P2P2_DP<10>")
	)
	(segment
		(start 349.635064 -278.82596)
		(end 349.647256 -278.818848)
		(width 0.0889)
		(layer "In11.Cu")
		(net "UPI_CPU1_CPU0_P2P2_DP<10>")
	)
	(segment
		(start 95.499682 -282.725114)
		(end 95.490792 -282.730194)
		(width 0.0889)
		(layer "In11.Cu")
		(net "UPI_CPU1_CPU0_P2P2_DP<10>")
	)
	(segment
		(start 95.208344 -283.201364)
		(end 95.208344 -283.219906)
		(width 0.0889)
		(layer "In11.Cu")
		(net "UPI_CPU1_CPU0_P2P2_DP<10>")
	)
	(segment
		(start 78.848458 -309.90921)
		(end 68.129404 -320.628264)
		(width 0.14732)
		(layer "In11.Cu")
		(net "UPI_CPU1_CPU0_P2P2_DP<10>")
	)
	(segment
		(start 90.380058 -300.446186)
		(end 78.848458 -309.90921)
		(width 0.14732)
		(layer "In11.Cu")
		(net "UPI_CPU1_CPU0_P2P2_DP<10>")
	)
	(segment
		(start 345.021408 -294.12438)
		(end 345.026488 -294.1193)
		(width 0.14732)
		(layer "In11.Cu")
		(net "UPI_CPU1_CPU0_P2P2_DP<10>")
	)
	(segment
		(start 98.789236 -280.283412)
		(end 98.780346 -280.288492)
		(width 0.0889)
		(layer "In11.Cu")
		(net "UPI_CPU1_CPU0_P2P2_DP<10>")
	)
	(segment
		(start 308.347618 -334.58023)
		(end 315.409326 -327.518522)
		(width 0.14732)
		(layer "In11.Cu")
		(net "UPI_CPU1_CPU0_P2P2_DP<10>")
	)
	(segment
		(start 93.328998 -289.645598)
		(end 93.328998 -294.016938)
		(width 0.0889)
		(layer "In11.Cu")
		(net "UPI_CPU1_CPU0_P2P2_DP<10>")
	)
	(segment
		(start 271.13992 -366.590072)
		(end 271.13992 -346.47632)
		(width 0.14732)
		(layer "In11.Cu")
		(net "UPI_CPU1_CPU0_P2P2_DP<10>")
	)
	(segment
		(start 103.44912 -279.150318)
		(end 103.383588 -279.084786)
		(width 0.0889)
		(layer "In11.Cu")
		(net "UPI_CPU1_CPU0_P2P2_DP<10>")
	)
	(segment
		(start 348.70136 -281.106118)
		(end 348.695264 -281.102562)
		(width 0.0889)
		(layer "In11.Cu")
		(net "UPI_CPU1_CPU0_P2P2_DP<10>")
	)
	(segment
		(start 348.038166 -283.219906)
		(end 348.038166 -283.21127)
		(width 0.0889)
		(layer "In11.Cu")
		(net "UPI_CPU1_CPU0_P2P2_DP<10>")
	)
	(segment
		(start 348.507812 -282.424378)
		(end 348.507812 -282.405836)
		(width 0.0889)
		(layer "In11.Cu")
		(net "UPI_CPU1_CPU0_P2P2_DP<10>")
	)
	(segment
		(start 344.984324 -291.432234)
		(end 344.984324 -291.232844)
		(width 0.0889)
		(layer "In11.Cu")
		(net "UPI_CPU1_CPU0_P2P2_DP<10>")
	)
	(segment
		(start 346.628212 -287.304734)
		(end 346.628212 -287.28924)
		(width 0.0889)
		(layer "In11.Cu")
		(net "UPI_CPU1_CPU0_P2P2_DP<10>")
	)
	(segment
		(start 347.752162 -283.711396)
		(end 347.75394 -283.71038)
		(width 0.0889)
		(layer "In11.Cu")
		(net "UPI_CPU1_CPU0_P2P2_DP<10>")
	)
	(segment
		(start 97.84207 -281.915616)
		(end 97.840546 -281.916378)
		(width 0.0889)
		(layer "In11.Cu")
		(net "UPI_CPU1_CPU0_P2P2_DP<10>")
	)
	(segment
		(start 348.686374 -280.458926)
		(end 348.695264 -280.453846)
		(width 0.0889)
		(layer "In11.Cu")
		(net "UPI_CPU1_CPU0_P2P2_DP<10>")
	)
	(segment
		(start 346.815664 -286.964882)
		(end 346.827856 -286.95777)
		(width 0.0889)
		(layer "In11.Cu")
		(net "UPI_CPU1_CPU0_P2P2_DP<10>")
	)
	(segment
		(start 161.168842 -384.37185)
		(end 162.763962 -384.363722)
		(width 0.14732)
		(layer "In11.Cu")
		(net "UPI_CPU1_CPU0_P2P2_DP<10>")
	)
	(segment
		(start 93.287088 -296.987468)
		(end 92.523564 -298.831254)
		(width 0.14732)
		(layer "In11.Cu")
		(net "UPI_CPU1_CPU0_P2P2_DP<10>")
	)
	(segment
		(start 346.806774 -286.969962)
		(end 346.815664 -286.964882)
		(width 0.0889)
		(layer "In11.Cu")
		(net "UPI_CPU1_CPU0_P2P2_DP<10>")
	)
	(segment
		(start 271.13992 -346.47632)
		(end 281.073352 -336.542888)
		(width 0.14732)
		(layer "In11.Cu")
		(net "UPI_CPU1_CPU0_P2P2_DP<10>")
	)
	(segment
		(start 64.766698 -332.494636)
		(end 64.766698 -354.54082)
		(width 0.14732)
		(layer "In11.Cu")
		(net "UPI_CPU1_CPU0_P2P2_DP<10>")
	)
	(segment
		(start 350.387666 -277.540974)
		(end 350.387666 -277.522432)
		(width 0.0889)
		(layer "In11.Cu")
		(net "UPI_CPU1_CPU0_P2P2_DP<10>")
	)
	(segment
		(start 95.976186 -281.907742)
		(end 95.95485 -281.919934)
		(width 0.0889)
		(layer "In11.Cu")
		(net "UPI_CPU1_CPU0_P2P2_DP<10>")
	)
	(segment
		(start 346.815664 -285.336996)
		(end 346.82176 -285.33344)
		(width 0.0889)
		(layer "In11.Cu")
		(net "UPI_CPU1_CPU0_P2P2_DP<10>")
	)
	(segment
		(start 98.497644 -280.76398)
		(end 98.497644 -280.778204)
		(width 0.0889)
		(layer "In11.Cu")
		(net "UPI_CPU1_CPU0_P2P2_DP<10>")
	)
	(segment
		(start 345.026488 -291.474398)
		(end 344.984324 -291.432234)
		(width 0.0889)
		(layer "In11.Cu")
		(net "UPI_CPU1_CPU0_P2P2_DP<10>")
	)
	(segment
		(start 337.940142 -303.435766)
		(end 339.602318 -302.747172)
		(width 0.14732)
		(layer "In11.Cu")
		(net "UPI_CPU1_CPU0_P2P2_DP<10>")
	)
	(segment
		(start 94.086172 -285.168848)
		(end 94.084648 -285.169864)
		(width 0.0889)
		(layer "In11.Cu")
		(net "UPI_CPU1_CPU0_P2P2_DP<10>")
	)
	(segment
		(start 347.746574 -283.714444)
		(end 347.746574 -283.714698)
		(width 0.0889)
		(layer "In11.Cu")
		(net "UPI_CPU1_CPU0_P2P2_DP<10>")
	)
	(segment
		(start 92.523564 -298.831254)
		(end 92.165932 -299.3136)
		(width 0.14732)
		(layer "In11.Cu")
		(net "UPI_CPU1_CPU0_P2P2_DP<10>")
	)
	(segment
		(start 345.867228 -288.597848)
		(end 345.876118 -288.592768)
		(width 0.0889)
		(layer "In11.Cu")
		(net "UPI_CPU1_CPU0_P2P2_DP<10>")
	)
	(segment
		(start 315.409326 -327.518522)
		(end 316.50686 -324.869048)
		(width 0.14732)
		(layer "In11.Cu")
		(net "UPI_CPU1_CPU0_P2P2_DP<10>")
	)
	(segment
		(start 64.766698 -354.54082)
		(end 69.578728 -366.159542)
		(width 0.14732)
		(layer "In11.Cu")
		(net "UPI_CPU1_CPU0_P2P2_DP<10>")
	)
	(segment
		(start 93.328998 -288.087562)
		(end 93.328998 -288.103056)
		(width 0.0889)
		(layer "In11.Cu")
		(net "UPI_CPU1_CPU0_P2P2_DP<10>")
	)
	(segment
		(start 94.090236 -285.166816)
		(end 94.090236 -285.166562)
		(width 0.0889)
		(layer "In11.Cu")
		(net "UPI_CPU1_CPU0_P2P2_DP<10>")
	)
	(segment
		(start 98.027998 -281.576526)
		(end 98.027998 -281.59202)
		(width 0.0889)
		(layer "In11.Cu")
		(net "UPI_CPU1_CPU0_P2P2_DP<10>")
	)
	(segment
		(start 347.746574 -283.714698)
		(end 347.750638 -283.712412)
		(width 0.0889)
		(layer "In11.Cu")
		(net "UPI_CPU1_CPU0_P2P2_DP<10>")
	)
	(segment
		(start 350.565974 -275.575522)
		(end 350.574864 -275.570442)
		(width 0.0889)
		(layer "In11.Cu")
		(net "UPI_CPU1_CPU0_P2P2_DP<10>")
	)
	(segment
		(start 347.750638 -283.712412)
		(end 347.752162 -283.711396)
		(width 0.0889)
		(layer "In11.Cu")
		(net "UPI_CPU1_CPU0_P2P2_DP<10>")
	)
	(segment
		(start 346.815664 -285.985712)
		(end 346.806774 -285.980632)
		(width 0.0889)
		(layer "In11.Cu")
		(net "UPI_CPU1_CPU0_P2P2_DP<10>")
	)
	(segment
		(start 350.096328 -278.017224)
		(end 350.105218 -278.012144)
		(width 0.0889)
		(layer "In11.Cu")
		(net "UPI_CPU1_CPU0_P2P2_DP<10>")
	)
	(segment
		(start 95.975678 -281.907742)
		(end 95.976186 -281.907742)
		(width 0.0889)
		(layer "In11.Cu")
		(net "UPI_CPU1_CPU0_P2P2_DP<10>")
	)
	(segment
		(start 348.695264 -282.081478)
		(end 348.70136 -282.077922)
		(width 0.0889)
		(layer "In11.Cu")
		(net "UPI_CPU1_CPU0_P2P2_DP<10>")
	)
	(segment
		(start 346.806774 -285.342076)
		(end 346.815664 -285.336996)
		(width 0.0889)
		(layer "In11.Cu")
		(net "UPI_CPU1_CPU0_P2P2_DP<10>")
	)
	(segment
		(start 94.268798 -284.832044)
		(end 94.268798 -284.847538)
		(width 0.0889)
		(layer "In11.Cu")
		(net "UPI_CPU1_CPU0_P2P2_DP<10>")
	)
	(segment
		(start 93.144594 -289.446462)
		(end 93.144594 -289.446208)
		(width 0.0889)
		(layer "In11.Cu")
		(net "UPI_CPU1_CPU0_P2P2_DP<10>")
	)
	(segment
		(start 100.198682 -279.469596)
		(end 100.189792 -279.474676)
		(width 0.0889)
		(layer "In11.Cu")
		(net "UPI_CPU1_CPU0_P2P2_DP<10>")
	)
	(segment
		(start 343.453974 -299.92828)
		(end 344.042492 -298.507404)
		(width 0.14732)
		(layer "In11.Cu")
		(net "UPI_CPU1_CPU0_P2P2_DP<10>")
	)
	(arc
		(start 350.851216 -275.167344)
		(mid 350.852712 -275.156816)
		(end 350.85401 -275.146262)
		(width 0.0889)
		(layer "In11.Cu")
		(net "UPI_CPU1_CPU0_P2P2_DP<10>")
	)
	(arc
		(start 350.104964 -277.032974)
		(mid 349.970031 -276.89962)
		(end 349.917766 -276.717252)
		(width 0.0889)
		(layer "In11.Cu")
		(net "UPI_CPU1_CPU0_P2P2_DP<10>")
	)
	(arc
		(start 349.165418 -279.639776)
		(mid 349.369753 -279.437171)
		(end 349.447866 -279.160224)
		(width 0.0889)
		(layer "In11.Cu")
		(net "UPI_CPU1_CPU0_P2P2_DP<10>")
	)
	(arc
		(start 347.098366 -286.467804)
		(mid 347.020737 -286.189391)
		(end 346.815664 -285.985712)
		(width 0.0889)
		(layer "In11.Cu")
		(net "UPI_CPU1_CPU0_P2P2_DP<10>")
	)
	(arc
		(start 99.249992 -279.474676)
		(mid 99.047169 -279.674907)
		(end 98.967798 -279.94864)
		(width 0.0889)
		(layer "In11.Cu")
		(net "UPI_CPU1_CPU0_P2P2_DP<10>")
	)
	(arc
		(start 349.917766 -276.69998)
		(mid 349.970036 -276.517615)
		(end 350.104964 -276.384258)
		(width 0.0889)
		(layer "In11.Cu")
		(net "UPI_CPU1_CPU0_P2P2_DP<10>")
	)
	(arc
		(start 95.208344 -283.219906)
		(mid 95.160665 -283.402806)
		(end 95.029782 -283.539184)
		(width 0.0889)
		(layer "In11.Cu")
		(net "UPI_CPU1_CPU0_P2P2_DP<10>")
	)
	(arc
		(start 349.917766 -278.336502)
		(mid 349.965445 -278.153602)
		(end 350.096328 -278.017224)
		(width 0.0889)
		(layer "In11.Cu")
		(net "UPI_CPU1_CPU0_P2P2_DP<10>")
	)
	(arc
		(start 93.144594 -289.446208)
		(mid 93.253629 -289.529937)
		(end 93.328744 -289.64509)
		(width 0.0889)
		(layer "In11.Cu")
		(net "UPI_CPU1_CPU0_P2P2_DP<10>")
	)
	(arc
		(start 347.098366 -284.847538)
		(mid 347.146045 -284.664638)
		(end 347.276928 -284.52826)
		(width 0.0889)
		(layer "In11.Cu")
		(net "UPI_CPU1_CPU0_P2P2_DP<10>")
	)
	(arc
		(start 93.798644 -285.675578)
		(mid 93.877863 -285.950263)
		(end 94.081346 -286.151066)
		(width 0.0889)
		(layer "In11.Cu")
		(net "UPI_CPU1_CPU0_P2P2_DP<10>")
	)
	(arc
		(start 100.189792 -279.474676)
		(mid 100.002594 -279.524819)
		(end 99.815396 -279.474676)
		(width 0.0889)
		(layer "In11.Cu")
		(net "UPI_CPU1_CPU0_P2P2_DP<10>")
	)
	(arc
		(start 346.346018 -287.778698)
		(mid 346.548841 -287.578467)
		(end 346.628212 -287.304734)
		(width 0.0889)
		(layer "In11.Cu")
		(net "UPI_CPU1_CPU0_P2P2_DP<10>")
	)
	(arc
		(start 348.70136 -282.077922)
		(mid 348.977934 -281.59202)
		(end 348.70136 -281.106118)
		(width 0.0889)
		(layer "In11.Cu")
		(net "UPI_CPU1_CPU0_P2P2_DP<10>")
	)
	(arc
		(start 102.539546 -278.66086)
		(mid 102.352348 -278.711003)
		(end 102.16515 -278.66086)
		(width 0.0889)
		(layer "In11.Cu")
		(net "UPI_CPU1_CPU0_P2P2_DP<10>")
	)
	(arc
		(start 346.628212 -287.28924)
		(mid 346.675891 -287.10634)
		(end 346.806774 -286.969962)
		(width 0.0889)
		(layer "In11.Cu")
		(net "UPI_CPU1_CPU0_P2P2_DP<10>")
	)
	(arc
		(start 95.95485 -281.919934)
		(mid 95.752263 -282.126285)
		(end 95.678244 -282.405836)
		(width 0.0889)
		(layer "In11.Cu")
		(net "UPI_CPU1_CPU0_P2P2_DP<10>")
	)
	(arc
		(start 98.310192 -281.102562)
		(mid 98.107369 -281.302793)
		(end 98.027998 -281.576526)
		(width 0.0889)
		(layer "In11.Cu")
		(net "UPI_CPU1_CPU0_P2P2_DP<10>")
	)
	(arc
		(start 97.46615 -281.916378)
		(mid 97.191951 -281.840543)
		(end 96.915478 -281.907742)
		(width 0.0889)
		(layer "In11.Cu")
		(net "UPI_CPU1_CPU0_P2P2_DP<10>")
	)
	(arc
		(start 348.225364 -282.895548)
		(mid 348.42765 -282.696567)
		(end 348.507812 -282.424378)
		(width 0.0889)
		(layer "In11.Cu")
		(net "UPI_CPU1_CPU0_P2P2_DP<10>")
	)
	(arc
		(start 95.020892 -283.544264)
		(mid 94.816557 -283.746869)
		(end 94.738444 -284.023816)
		(width 0.0889)
		(layer "In11.Cu")
		(net "UPI_CPU1_CPU0_P2P2_DP<10>")
	)
	(arc
		(start 346.827856 -286.95777)
		(mid 347.026084 -286.751922)
		(end 347.098366 -286.475424)
		(width 0.0889)
		(layer "In11.Cu")
		(net "UPI_CPU1_CPU0_P2P2_DP<10>")
	)
	(arc
		(start 96.900746 -281.916378)
		(mid 96.713548 -281.966521)
		(end 96.52635 -281.916378)
		(width 0.0889)
		(layer "In11.Cu")
		(net "UPI_CPU1_CPU0_P2P2_DP<10>")
	)
	(arc
		(start 349.447866 -279.141682)
		(mid 349.500136 -278.959317)
		(end 349.635064 -278.82596)
		(width 0.0889)
		(layer "In11.Cu")
		(net "UPI_CPU1_CPU0_P2P2_DP<10>")
	)
	(arc
		(start 93.611192 -287.613598)
		(mid 93.408369 -287.813829)
		(end 93.328998 -288.087562)
		(width 0.0889)
		(layer "In11.Cu")
		(net "UPI_CPU1_CPU0_P2P2_DP<10>")
	)
	(arc
		(start 103.383588 -279.084786)
		(mid 103.38229 -279.074232)
		(end 103.380794 -279.063704)
		(width 0.0889)
		(layer "In11.Cu")
		(net "UPI_CPU1_CPU0_P2P2_DP<10>")
	)
	(arc
		(start 350.105218 -278.012144)
		(mid 350.307504 -277.813163)
		(end 350.387666 -277.540974)
		(width 0.0889)
		(layer "In11.Cu")
		(net "UPI_CPU1_CPU0_P2P2_DP<10>")
	)
	(arc
		(start 102.16515 -278.66086)
		(mid 101.888337 -278.58499)
		(end 101.609906 -278.654764)
		(width 0.0889)
		(layer "In11.Cu")
		(net "UPI_CPU1_CPU0_P2P2_DP<10>")
	)
	(arc
		(start 98.497644 -280.778204)
		(mid 98.449965 -280.961104)
		(end 98.319082 -281.097482)
		(width 0.0889)
		(layer "In11.Cu")
		(net "UPI_CPU1_CPU0_P2P2_DP<10>")
	)
	(arc
		(start 97.840546 -281.916378)
		(mid 97.653348 -281.966521)
		(end 97.46615 -281.916378)
		(width 0.0889)
		(layer "In11.Cu")
		(net "UPI_CPU1_CPU0_P2P2_DP<10>")
	)
	(arc
		(start 348.686374 -281.097482)
		(mid 348.507777 -280.778204)
		(end 348.686374 -280.458926)
		(width 0.0889)
		(layer "In11.Cu")
		(net "UPI_CPU1_CPU0_P2P2_DP<10>")
	)
	(arc
		(start 345.872816 -289.277806)
		(mid 345.763669 -289.193878)
		(end 345.688666 -289.078416)
		(width 0.0889)
		(layer "In11.Cu")
		(net "UPI_CPU1_CPU0_P2P2_DP<10>")
	)
	(arc
		(start 95.678244 -282.405836)
		(mid 95.630565 -282.588736)
		(end 95.499682 -282.725114)
		(width 0.0889)
		(layer "In11.Cu")
		(net "UPI_CPU1_CPU0_P2P2_DP<10>")
	)
	(arc
		(start 95.490792 -282.730194)
		(mid 95.288506 -282.929175)
		(end 95.208344 -283.201364)
		(width 0.0889)
		(layer "In11.Cu")
		(net "UPI_CPU1_CPU0_P2P2_DP<10>")
	)
	(arc
		(start 346.806774 -285.980632)
		(mid 346.628298 -285.661354)
		(end 346.806774 -285.342076)
		(width 0.0889)
		(layer "In11.Cu")
		(net "UPI_CPU1_CPU0_P2P2_DP<10>")
	)
	(arc
		(start 94.550992 -284.35808)
		(mid 94.348169 -284.558311)
		(end 94.268798 -284.832044)
		(width 0.0889)
		(layer "In11.Cu")
		(net "UPI_CPU1_CPU0_P2P2_DP<10>")
	)
	(arc
		(start 346.158566 -288.103056)
		(mid 346.206245 -287.920156)
		(end 346.337128 -287.783778)
		(width 0.0889)
		(layer "In11.Cu")
		(net "UPI_CPU1_CPU0_P2P2_DP<10>")
	)
	(arc
		(start 93.798644 -287.28924)
		(mid 93.750965 -287.47214)
		(end 93.620082 -287.608518)
		(width 0.0889)
		(layer "In11.Cu")
		(net "UPI_CPU1_CPU0_P2P2_DP<10>")
	)
	(arc
		(start 350.104964 -276.384258)
		(mid 350.309299 -276.181653)
		(end 350.387412 -275.904706)
		(width 0.0889)
		(layer "In11.Cu")
		(net "UPI_CPU1_CPU0_P2P2_DP<10>")
	)
	(arc
		(start 94.07525 -285.175452)
		(mid 93.872663 -285.381803)
		(end 93.798644 -285.661354)
		(width 0.0889)
		(layer "In11.Cu")
		(net "UPI_CPU1_CPU0_P2P2_DP<10>")
	)
	(arc
		(start 101.599492 -278.66086)
		(mid 101.412294 -278.711003)
		(end 101.225096 -278.66086)
		(width 0.0889)
		(layer "In11.Cu")
		(net "UPI_CPU1_CPU0_P2P2_DP<10>")
	)
	(arc
		(start 349.647256 -278.818848)
		(mid 349.845484 -278.613)
		(end 349.917766 -278.336502)
		(width 0.0889)
		(layer "In11.Cu")
		(net "UPI_CPU1_CPU0_P2P2_DP<10>")
	)
	(arc
		(start 94.268544 -286.48406)
		(mid 94.216274 -286.666425)
		(end 94.081346 -286.799782)
		(width 0.0889)
		(layer "In11.Cu")
		(net "UPI_CPU1_CPU0_P2P2_DP<10>")
	)
	(arc
		(start 350.387666 -277.522432)
		(mid 350.313675 -277.242866)
		(end 350.11106 -277.03653)
		(width 0.0889)
		(layer "In11.Cu")
		(net "UPI_CPU1_CPU0_P2P2_DP<10>")
	)
	(arc
		(start 103.380794 -279.063704)
		(mid 103.288633 -278.830932)
		(end 103.10495 -278.66086)
		(width 0.0889)
		(layer "In11.Cu")
		(net "UPI_CPU1_CPU0_P2P2_DP<10>")
	)
	(arc
		(start 98.027998 -281.59202)
		(mid 97.980319 -281.77492)
		(end 97.849436 -281.911298)
		(width 0.0889)
		(layer "In11.Cu")
		(net "UPI_CPU1_CPU0_P2P2_DP<10>")
	)
	(arc
		(start 94.268798 -284.847538)
		(mid 94.221119 -285.030438)
		(end 94.090236 -285.166816)
		(width 0.0889)
		(layer "In11.Cu")
		(net "UPI_CPU1_CPU0_P2P2_DP<10>")
	)
	(arc
		(start 348.507812 -282.405836)
		(mid 348.555491 -282.222936)
		(end 348.686374 -282.086558)
		(width 0.0889)
		(layer "In11.Cu")
		(net "UPI_CPU1_CPU0_P2P2_DP<10>")
	)
	(arc
		(start 94.07525 -286.803338)
		(mid 93.872663 -287.009689)
		(end 93.798644 -287.28924)
		(width 0.0889)
		(layer "In11.Cu")
		(net "UPI_CPU1_CPU0_P2P2_DP<10>")
	)
	(arc
		(start 347.76156 -283.705808)
		(mid 347.964147 -283.499457)
		(end 348.038166 -283.219906)
		(width 0.0889)
		(layer "In11.Cu")
		(net "UPI_CPU1_CPU0_P2P2_DP<10>")
	)
	(arc
		(start 98.780346 -280.288492)
		(mid 98.576865 -280.489296)
		(end 98.497644 -280.76398)
		(width 0.0889)
		(layer "In11.Cu")
		(net "UPI_CPU1_CPU0_P2P2_DP<10>")
	)
	(arc
		(start 350.574864 -275.570442)
		(mid 350.758851 -275.400303)
		(end 350.851216 -275.167344)
		(width 0.0889)
		(layer "In11.Cu")
		(net "UPI_CPU1_CPU0_P2P2_DP<10>")
	)
	(arc
		(start 347.568012 -284.033722)
		(mid 347.615691 -283.850822)
		(end 347.746574 -283.714444)
		(width 0.0889)
		(layer "In11.Cu")
		(net "UPI_CPU1_CPU0_P2P2_DP<10>")
	)
	(arc
		(start 94.081346 -286.151066)
		(mid 94.216279 -286.28442)
		(end 94.268544 -286.466788)
		(width 0.0889)
		(layer "In11.Cu")
		(net "UPI_CPU1_CPU0_P2P2_DP<10>")
	)
	(arc
		(start 346.158312 -289.60953)
		(mid 346.046974 -289.41663)
		(end 345.872816 -289.277806)
		(width 0.0889)
		(layer "In11.Cu")
		(net "UPI_CPU1_CPU0_P2P2_DP<10>")
	)
	(arc
		(start 101.214682 -278.654764)
		(mid 100.936504 -278.585041)
		(end 100.659946 -278.66086)
		(width 0.0889)
		(layer "In11.Cu")
		(net "UPI_CPU1_CPU0_P2P2_DP<10>")
	)
	(arc
		(start 100.377244 -279.150318)
		(mid 100.329565 -279.333218)
		(end 100.198682 -279.469596)
		(width 0.0889)
		(layer "In11.Cu")
		(net "UPI_CPU1_CPU0_P2P2_DP<10>")
	)
	(arc
		(start 348.038166 -283.21127)
		(mid 348.090436 -283.028905)
		(end 348.225364 -282.895548)
		(width 0.0889)
		(layer "In11.Cu")
		(net "UPI_CPU1_CPU0_P2P2_DP<10>")
	)
	(arc
		(start 93.328998 -288.103056)
		(mid 93.281319 -288.285956)
		(end 93.150436 -288.422334)
		(width 0.0889)
		(layer "In11.Cu")
		(net "UPI_CPU1_CPU0_P2P2_DP<10>")
	)
	(arc
		(start 99.800664 -279.46604)
		(mid 99.524189 -279.39872)
		(end 99.249992 -279.474676)
		(width 0.0889)
		(layer "In11.Cu")
		(net "UPI_CPU1_CPU0_P2P2_DP<10>")
	)
	(arc
		(start 345.688666 -288.917126)
		(mid 345.736345 -288.734226)
		(end 345.867228 -288.597848)
		(width 0.0889)
		(layer "In11.Cu")
		(net "UPI_CPU1_CPU0_P2P2_DP<10>")
	)
	(arc
		(start 348.977966 -279.964134)
		(mid 349.025645 -279.781234)
		(end 349.156528 -279.644856)
		(width 0.0889)
		(layer "In11.Cu")
		(net "UPI_CPU1_CPU0_P2P2_DP<10>")
	)
	(arc
		(start 350.387412 -275.8948)
		(mid 350.435091 -275.7119)
		(end 350.565974 -275.575522)
		(width 0.0889)
		(layer "In11.Cu")
		(net "UPI_CPU1_CPU0_P2P2_DP<10>")
	)
	(arc
		(start 348.695264 -280.453846)
		(mid 348.898745 -280.253042)
		(end 348.977966 -279.978358)
		(width 0.0889)
		(layer "In11.Cu")
		(net "UPI_CPU1_CPU0_P2P2_DP<10>")
	)
	(arc
		(start 92.859098 -289.114738)
		(mid 92.970436 -289.307638)
		(end 93.144594 -289.446462)
		(width 0.0889)
		(layer "In11.Cu")
		(net "UPI_CPU1_CPU0_P2P2_DP<10>")
	)
	(arc
		(start 103.10495 -278.66086)
		(mid 102.830751 -278.585025)
		(end 102.554278 -278.652224)
		(width 0.0889)
		(layer "In11.Cu")
		(net "UPI_CPU1_CPU0_P2P2_DP<10>")
	)
	(arc
		(start 346.82176 -285.33344)
		(mid 347.024347 -285.127089)
		(end 347.098366 -284.847538)
		(width 0.0889)
		(layer "In11.Cu")
		(net "UPI_CPU1_CPU0_P2P2_DP<10>")
	)
	(arc
		(start 98.967798 -279.964134)
		(mid 98.920119 -280.147034)
		(end 98.789236 -280.283412)
		(width 0.0889)
		(layer "In11.Cu")
		(net "UPI_CPU1_CPU0_P2P2_DP<10>")
	)
	(arc
		(start 100.647754 -278.667972)
		(mid 100.449526 -278.87382)
		(end 100.377244 -279.150318)
		(width 0.0889)
		(layer "In11.Cu")
		(net "UPI_CPU1_CPU0_P2P2_DP<10>")
	)
	(arc
		(start 345.876118 -288.592768)
		(mid 346.078404 -288.393787)
		(end 346.158566 -288.121598)
		(width 0.0889)
		(layer "In11.Cu")
		(net "UPI_CPU1_CPU0_P2P2_DP<10>")
	)
	(arc
		(start 96.52635 -281.916378)
		(mid 96.252151 -281.840543)
		(end 95.975678 -281.907742)
		(width 0.0889)
		(layer "In11.Cu")
		(net "UPI_CPU1_CPU0_P2P2_DP<10>")
	)
	(arc
		(start 94.738444 -284.033722)
		(mid 94.690765 -284.216622)
		(end 94.559882 -284.353)
		(width 0.0889)
		(layer "In11.Cu")
		(net "UPI_CPU1_CPU0_P2P2_DP<10>")
	)
	(arc
		(start 347.285818 -284.52318)
		(mid 347.488641 -284.322949)
		(end 347.568012 -284.049216)
		(width 0.0889)
		(layer "In11.Cu")
		(net "UPI_CPU1_CPU0_P2P2_DP<10>")
	)
	(arc
		(start 93.141546 -288.427414)
		(mid 92.93926 -288.626395)
		(end 92.859098 -288.898584)
		(width 0.0889)
		(layer "In11.Cu")
		(net "UPI_CPU1_CPU0_P2P2_DP<10>")
	)
	(segment
		(start 353.111562 -274.54479)
		(end 353.111562 -275.080476)
		(width 0.13208)
		(layer "F.Cu")
		(net "UPI_CPU1_CPU0_P2P2_DP<0>")
	)
	(segment
		(start 353.111562 -275.080476)
		(end 353.111816 -275.08073)
		(width 0.13208)
		(layer "F.Cu")
		(net "UPI_CPU1_CPU0_P2P2_DP<0>")
	)
	(segment
		(start 86.375494 -284.311598)
		(end 86.375494 -284.847538)
		(width 0.13208)
		(layer "F.Cu")
		(net "UPI_CPU1_CPU0_P2P2_DP<0>")
	)
	(segment
		(start 66.05651 -307.904642)
		(end 65.683638 -308.059074)
		(width 0.14732)
		(layer "In11.Cu")
		(net "UPI_CPU1_CPU0_P2P2_DP<0>")
	)
	(segment
		(start 355.187504 -275.400008)
		(end 355.178614 -275.405088)
		(width 0.0889)
		(layer "In11.Cu")
		(net "UPI_CPU1_CPU0_P2P2_DP<0>")
	)
	(segment
		(start 81.48955 -291.953188)
		(end 80.198976 -295.068752)
		(width 0.14732)
		(layer "In11.Cu")
		(net "UPI_CPU1_CPU0_P2P2_DP<0>")
	)
	(segment
		(start 341.531194 -311.594754)
		(end 343.63787 -310.72201)
		(width 0.14732)
		(layer "In11.Cu")
		(net "UPI_CPU1_CPU0_P2P2_DP<0>")
	)
	(segment
		(start 50.813208 -318.658494)
		(end 50.638202 -318.781176)
		(width 0.14732)
		(layer "In11.Cu")
		(net "UPI_CPU1_CPU0_P2P2_DP<0>")
	)
	(segment
		(start 356.834186 -298.819062)
		(end 357.122222 -298.123356)
		(width 0.14732)
		(layer "In11.Cu")
		(net "UPI_CPU1_CPU0_P2P2_DP<0>")
	)
	(segment
		(start 162.062922 -392.998452)
		(end 266.212828 -384.20294)
		(width 0.14732)
		(layer "In11.Cu")
		(net "UPI_CPU1_CPU0_P2P2_DP<0>")
	)
	(segment
		(start 358.093264 -285.336996)
		(end 358.105456 -285.329884)
		(width 0.0889)
		(layer "In11.Cu")
		(net "UPI_CPU1_CPU0_P2P2_DP<0>")
	)
	(segment
		(start 50.240692 -319.348866)
		(end 50.090832 -320.19113)
		(width 0.14732)
		(layer "In11.Cu")
		(net "UPI_CPU1_CPU0_P2P2_DP<0>")
	)
	(segment
		(start 359.973118 -276.219158)
		(end 359.964228 -276.214078)
		(width 0.0889)
		(layer "In11.Cu")
		(net "UPI_CPU1_CPU0_P2P2_DP<0>")
	)
	(segment
		(start 343.63787 -310.72201)
		(end 343.638124 -310.72201)
		(width 0.14732)
		(layer "In11.Cu")
		(net "UPI_CPU1_CPU0_P2P2_DP<0>")
	)
	(segment
		(start 84.27466 -289.227006)
		(end 83.752436 -289.74923)
		(width 0.0889)
		(layer "In11.Cu")
		(net "UPI_CPU1_CPU0_P2P2_DP<0>")
	)
	(segment
		(start 322.800472 -331.918056)
		(end 323.926454 -329.199494)
		(width 0.14732)
		(layer "In11.Cu")
		(net "UPI_CPU1_CPU0_P2P2_DP<0>")
	)
	(segment
		(start 356.718362 -291.484558)
		(end 356.496112 -291.262308)
		(width 0.0889)
		(layer "In11.Cu")
		(net "UPI_CPU1_CPU0_P2P2_DP<0>")
	)
	(segment
		(start 279.67432 -350.129348)
		(end 286.378396 -343.425272)
		(width 0.14732)
		(layer "In11.Cu")
		(net "UPI_CPU1_CPU0_P2P2_DP<0>")
	)
	(segment
		(start 359.503726 -279.639268)
		(end 359.50906 -279.63622)
		(width 0.0889)
		(layer "In11.Cu")
		(net "UPI_CPU1_CPU0_P2P2_DP<0>")
	)
	(segment
		(start 359.503726 -281.916886)
		(end 359.502964 -281.916378)
		(width 0.0889)
		(layer "In11.Cu")
		(net "UPI_CPU1_CPU0_P2P2_DP<0>")
	)
	(segment
		(start 356.7938 -291.500052)
		(end 356.778306 -291.484558)
		(width 0.0889)
		(layer "In11.Cu")
		(net "UPI_CPU1_CPU0_P2P2_DP<0>")
	)
	(segment
		(start 357.614474 -286.156146)
		(end 357.623364 -286.151066)
		(width 0.0889)
		(layer "In11.Cu")
		(net "UPI_CPU1_CPU0_P2P2_DP<0>")
	)
	(segment
		(start 55.243984 -334.762856)
		(end 56.440578 -337.635596)
		(width 0.14732)
		(layer "In11.Cu")
		(net "UPI_CPU1_CPU0_P2P2_DP<0>")
	)
	(segment
		(start 52.797964 -316.53353)
		(end 52.797964 -317.18377)
		(width 0.14732)
		(layer "In11.Cu")
		(net "UPI_CPU1_CPU0_P2P2_DP<0>")
	)
	(segment
		(start 359.315766 -279.97277)
		(end 359.315766 -279.955498)
		(width 0.0889)
		(layer "In11.Cu")
		(net "UPI_CPU1_CPU0_P2P2_DP<0>")
	)
	(segment
		(start 359.315766 -281.600656)
		(end 359.315766 -281.583384)
		(width 0.0889)
		(layer "In11.Cu")
		(net "UPI_CPU1_CPU0_P2P2_DP<0>")
	)
	(segment
		(start 83.693508 -289.74923)
		(end 83.678014 -289.764724)
		(width 0.0889)
		(layer "In11.Cu")
		(net "UPI_CPU1_CPU0_P2P2_DP<0>")
	)
	(segment
		(start 356.966266 -287.28924)
		(end 356.966266 -287.280604)
		(width 0.0889)
		(layer "In11.Cu")
		(net "UPI_CPU1_CPU0_P2P2_DP<0>")
	)
	(segment
		(start 83.678014 -289.764724)
		(end 81.48955 -291.953188)
		(width 0.14732)
		(layer "In11.Cu")
		(net "UPI_CPU1_CPU0_P2P2_DP<0>")
	)
	(segment
		(start 286.378396 -343.425272)
		(end 287.410144 -342.99779)
		(width 0.14732)
		(layer "In11.Cu")
		(net "UPI_CPU1_CPU0_P2P2_DP<0>")
	)
	(segment
		(start 54.119272 -333.478378)
		(end 55.243984 -334.762856)
		(width 0.14732)
		(layer "In11.Cu")
		(net "UPI_CPU1_CPU0_P2P2_DP<0>")
	)
	(segment
		(start 58.82386 -311.996328)
		(end 58.247026 -312.235088)
		(width 0.14732)
		(layer "In11.Cu")
		(net "UPI_CPU1_CPU0_P2P2_DP<0>")
	)
	(segment
		(start 358.558846 -284.52572)
		(end 358.563418 -284.52318)
		(width 0.0889)
		(layer "In11.Cu")
		(net "UPI_CPU1_CPU0_P2P2_DP<0>")
	)
	(segment
		(start 359.964228 -278.83104)
		(end 359.973118 -278.82596)
		(width 0.0889)
		(layer "In11.Cu")
		(net "UPI_CPU1_CPU0_P2P2_DP<0>")
	)
	(segment
		(start 356.598728 -274.585176)
		(end 356.588314 -274.591272)
		(width 0.0889)
		(layer "In11.Cu")
		(net "UPI_CPU1_CPU0_P2P2_DP<0>")
	)
	(segment
		(start 354.248974 -275.398992)
		(end 354.23856 -275.405088)
		(width 0.0889)
		(layer "In11.Cu")
		(net "UPI_CPU1_CPU0_P2P2_DP<0>")
	)
	(segment
		(start 356.778306 -291.484558)
		(end 356.718362 -291.484558)
		(width 0.0889)
		(layer "In11.Cu")
		(net "UPI_CPU1_CPU0_P2P2_DP<0>")
	)
	(segment
		(start 65.683638 -308.059074)
		(end 62.412372 -310.24576)
		(width 0.14732)
		(layer "In11.Cu")
		(net "UPI_CPU1_CPU0_P2P2_DP<0>")
	)
	(segment
		(start 69.99478 -305.27244)
		(end 66.05651 -307.904642)
		(width 0.14732)
		(layer "In11.Cu")
		(net "UPI_CPU1_CPU0_P2P2_DP<0>")
	)
	(segment
		(start 50.638202 -318.781176)
		(end 50.240692 -319.348866)
		(width 0.14732)
		(layer "In11.Cu")
		(net "UPI_CPU1_CPU0_P2P2_DP<0>")
	)
	(segment
		(start 360.725466 -277.536656)
		(end 360.725466 -277.522432)
		(width 0.0889)
		(layer "In11.Cu")
		(net "UPI_CPU1_CPU0_P2P2_DP<0>")
	)
	(segment
		(start 356.213918 -274.591272)
		(end 356.203504 -274.585176)
		(width 0.0889)
		(layer "In11.Cu")
		(net "UPI_CPU1_CPU0_P2P2_DP<0>")
	)
	(segment
		(start 360.255312 -276.708616)
		(end 360.255312 -276.693122)
		(width 0.0889)
		(layer "In11.Cu")
		(net "UPI_CPU1_CPU0_P2P2_DP<0>")
	)
	(segment
		(start 358.084374 -285.342076)
		(end 358.093264 -285.336996)
		(width 0.0889)
		(layer "In11.Cu")
		(net "UPI_CPU1_CPU0_P2P2_DP<0>")
	)
	(segment
		(start 86.06282 -284.847538)
		(end 85.997288 -284.782006)
		(width 0.0889)
		(layer "In11.Cu")
		(net "UPI_CPU1_CPU0_P2P2_DP<0>")
	)
	(segment
		(start 279.67432 -370.833142)
		(end 279.67432 -350.129348)
		(width 0.14732)
		(layer "In11.Cu")
		(net "UPI_CPU1_CPU0_P2P2_DP<0>")
	)
	(segment
		(start 359.315766 -275.089366)
		(end 359.315766 -275.070824)
		(width 0.0889)
		(layer "In11.Cu")
		(net "UPI_CPU1_CPU0_P2P2_DP<0>")
	)
	(segment
		(start 355.366066 -275.065236)
		(end 355.366066 -275.08073)
		(width 0.0889)
		(layer "In11.Cu")
		(net "UPI_CPU1_CPU0_P2P2_DP<0>")
	)
	(segment
		(start 50.090832 -325.464678)
		(end 50.453544 -329.149456)
		(width 0.14732)
		(layer "In11.Cu")
		(net "UPI_CPU1_CPU0_P2P2_DP<0>")
	)
	(segment
		(start 51.647852 -318.3128)
		(end 50.813208 -318.658494)
		(width 0.14732)
		(layer "In11.Cu")
		(net "UPI_CPU1_CPU0_P2P2_DP<0>")
	)
	(segment
		(start 358.563418 -284.52318)
		(end 358.569514 -284.519624)
		(width 0.0889)
		(layer "In11.Cu")
		(net "UPI_CPU1_CPU0_P2P2_DP<0>")
	)
	(segment
		(start 50.739294 -330.0984)
		(end 54.119272 -333.478378)
		(width 0.14732)
		(layer "In11.Cu")
		(net "UPI_CPU1_CPU0_P2P2_DP<0>")
	)
	(segment
		(start 50.090832 -320.19113)
		(end 50.090832 -325.464678)
		(width 0.14732)
		(layer "In11.Cu")
		(net "UPI_CPU1_CPU0_P2P2_DP<0>")
	)
	(segment
		(start 50.453544 -329.149456)
		(end 50.552858 -329.648566)
		(width 0.14732)
		(layer "In11.Cu")
		(net "UPI_CPU1_CPU0_P2P2_DP<0>")
	)
	(segment
		(start 356.683564 -287.778698)
		(end 356.68966 -287.775142)
		(width 0.0889)
		(layer "In11.Cu")
		(net "UPI_CPU1_CPU0_P2P2_DP<0>")
	)
	(segment
		(start 266.212828 -384.20294)
		(end 266.304776 -384.20294)
		(width 0.14732)
		(layer "In11.Cu")
		(net "UPI_CPU1_CPU0_P2P2_DP<0>")
	)
	(segment
		(start 84.82711 -284.827726)
		(end 84.27466 -286.159448)
		(width 0.0889)
		(layer "In11.Cu")
		(net "UPI_CPU1_CPU0_P2P2_DP<0>")
	)
	(segment
		(start 345.845638 -309.80761)
		(end 356.834186 -298.819062)
		(width 0.14732)
		(layer "In11.Cu")
		(net "UPI_CPU1_CPU0_P2P2_DP<0>")
	)
	(segment
		(start 357.435912 -286.48533)
		(end 357.435912 -286.475424)
		(width 0.0889)
		(layer "In11.Cu")
		(net "UPI_CPU1_CPU0_P2P2_DP<0>")
	)
	(segment
		(start 353.864164 -275.405088)
		(end 353.85375 -275.398992)
		(width 0.0889)
		(layer "In11.Cu")
		(net "UPI_CPU1_CPU0_P2P2_DP<0>")
	)
	(segment
		(start 360.433874 -278.017224)
		(end 360.442764 -278.012144)
		(width 0.0889)
		(layer "In11.Cu")
		(net "UPI_CPU1_CPU0_P2P2_DP<0>")
	)
	(segment
		(start 61.445648 -310.646318)
		(end 59.68111 -311.825386)
		(width 0.14732)
		(layer "In11.Cu")
		(net "UPI_CPU1_CPU0_P2P2_DP<0>")
	)
	(segment
		(start 52.46624 -317.739268)
		(end 51.647852 -318.3128)
		(width 0.14732)
		(layer "In11.Cu")
		(net "UPI_CPU1_CPU0_P2P2_DP<0>")
	)
	(segment
		(start 359.785666 -275.8948)
		(end 359.785666 -275.880576)
		(width 0.0889)
		(layer "In11.Cu")
		(net "UPI_CPU1_CPU0_P2P2_DP<0>")
	)
	(segment
		(start 352.976434 -275.429726)
		(end 352.955352 -275.351748)
		(width 0.0889)
		(layer "In11.Cu")
		(net "UPI_CPU1_CPU0_P2P2_DP<0>")
	)
	(segment
		(start 360.442764 -277.032974)
		(end 360.44124 -277.032212)
		(width 0.0889)
		(layer "In11.Cu")
		(net "UPI_CPU1_CPU0_P2P2_DP<0>")
	)
	(segment
		(start 62.262766 -370.686584)
		(end 70.399656 -378.823474)
		(width 0.14732)
		(layer "In11.Cu")
		(net "UPI_CPU1_CPU0_P2P2_DP<0>")
	)
	(segment
		(start 360.44886 -277.03653)
		(end 360.442764 -277.032974)
		(width 0.0889)
		(layer "In11.Cu")
		(net "UPI_CPU1_CPU0_P2P2_DP<0>")
	)
	(segment
		(start 356.496366 -288.195258)
		(end 356.496366 -288.09442)
		(width 0.0889)
		(layer "In11.Cu")
		(net "UPI_CPU1_CPU0_P2P2_DP<0>")
	)
	(segment
		(start 52.676298 -317.477394)
		(end 52.46624 -317.739268)
		(width 0.14732)
		(layer "In11.Cu")
		(net "UPI_CPU1_CPU0_P2P2_DP<0>")
	)
	(segment
		(start 311.720738 -342.99779)
		(end 322.800472 -331.918056)
		(width 0.14732)
		(layer "In11.Cu")
		(net "UPI_CPU1_CPU0_P2P2_DP<0>")
	)
	(segment
		(start 359.785666 -282.42006)
		(end 359.785666 -282.405836)
		(width 0.0889)
		(layer "In11.Cu")
		(net "UPI_CPU1_CPU0_P2P2_DP<0>")
	)
	(segment
		(start 359.503726 -281.267154)
		(end 359.50906 -281.264106)
		(width 0.0889)
		(layer "In11.Cu")
		(net "UPI_CPU1_CPU0_P2P2_DP<0>")
	)
	(segment
		(start 59.68111 -311.825386)
		(end 58.82386 -311.996328)
		(width 0.14732)
		(layer "In11.Cu")
		(net "UPI_CPU1_CPU0_P2P2_DP<0>")
	)
	(segment
		(start 84.82711 -284.657292)
		(end 84.82711 -284.827726)
		(width 0.0889)
		(layer "In11.Cu")
		(net "UPI_CPU1_CPU0_P2P2_DP<0>")
	)
	(segment
		(start 357.122222 -291.828474)
		(end 356.7938 -291.500052)
		(width 0.14732)
		(layer "In11.Cu")
		(net "UPI_CPU1_CPU0_P2P2_DP<0>")
	)
	(segment
		(start 359.033318 -274.591272)
		(end 359.032556 -274.590764)
		(width 0.0889)
		(layer "In11.Cu")
		(net "UPI_CPU1_CPU0_P2P2_DP<0>")
	)
	(segment
		(start 84.27466 -286.159448)
		(end 84.27466 -289.227006)
		(width 0.0889)
		(layer "In11.Cu")
		(net "UPI_CPU1_CPU0_P2P2_DP<0>")
	)
	(segment
		(start 83.752436 -289.74923)
		(end 83.693508 -289.74923)
		(width 0.0889)
		(layer "In11.Cu")
		(net "UPI_CPU1_CPU0_P2P2_DP<0>")
	)
	(segment
		(start 56.440578 -337.635596)
		(end 56.440578 -356.629716)
		(width 0.14732)
		(layer "In11.Cu")
		(net "UPI_CPU1_CPU0_P2P2_DP<0>")
	)
	(segment
		(start 92.07119 -387.799072)
		(end 127.121412 -392.998452)
		(width 0.14732)
		(layer "In11.Cu")
		(net "UPI_CPU1_CPU0_P2P2_DP<0>")
	)
	(segment
		(start 53.986176 -314.842652)
		(end 53.153056 -315.676026)
		(width 0.14732)
		(layer "In11.Cu")
		(net "UPI_CPU1_CPU0_P2P2_DP<0>")
	)
	(segment
		(start 359.785666 -280.778204)
		(end 359.785666 -280.76398)
		(width 0.0889)
		(layer "In11.Cu")
		(net "UPI_CPU1_CPU0_P2P2_DP<0>")
	)
	(segment
		(start 359.502964 -281.267662)
		(end 359.503726 -281.267154)
		(width 0.0889)
		(layer "In11.Cu")
		(net "UPI_CPU1_CPU0_P2P2_DP<0>")
	)
	(segment
		(start 85.036152 -284.447742)
		(end 84.82711 -284.657292)
		(width 0.0889)
		(layer "In11.Cu")
		(net "UPI_CPU1_CPU0_P2P2_DP<0>")
	)
	(segment
		(start 358.554528 -284.52826)
		(end 358.558846 -284.52572)
		(width 0.0889)
		(layer "In11.Cu")
		(net "UPI_CPU1_CPU0_P2P2_DP<0>")
	)
	(segment
		(start 357.122222 -298.123356)
		(end 357.122222 -291.828474)
		(width 0.14732)
		(layer "In11.Cu")
		(net "UPI_CPU1_CPU0_P2P2_DP<0>")
	)
	(segment
		(start 287.410144 -342.99779)
		(end 311.720738 -342.99779)
		(width 0.14732)
		(layer "In11.Cu")
		(net "UPI_CPU1_CPU0_P2P2_DP<0>")
	)
	(segment
		(start 359.50906 -281.919934)
		(end 359.503726 -281.916886)
		(width 0.0889)
		(layer "In11.Cu")
		(net "UPI_CPU1_CPU0_P2P2_DP<0>")
	)
	(segment
		(start 80.198976 -295.068752)
		(end 69.99478 -305.27244)
		(width 0.14732)
		(layer "In11.Cu")
		(net "UPI_CPU1_CPU0_P2P2_DP<0>")
	)
	(segment
		(start 86.375494 -284.847538)
		(end 86.06282 -284.847538)
		(width 0.0889)
		(layer "In11.Cu")
		(net "UPI_CPU1_CPU0_P2P2_DP<0>")
	)
	(segment
		(start 360.44124 -277.032212)
		(end 360.433874 -277.027894)
		(width 0.0889)
		(layer "In11.Cu")
		(net "UPI_CPU1_CPU0_P2P2_DP<0>")
	)
	(segment
		(start 53.153056 -315.676026)
		(end 52.797964 -316.53353)
		(width 0.14732)
		(layer "In11.Cu")
		(net "UPI_CPU1_CPU0_P2P2_DP<0>")
	)
	(segment
		(start 359.032556 -274.590764)
		(end 359.022904 -274.585176)
		(width 0.0889)
		(layer "In11.Cu")
		(net "UPI_CPU1_CPU0_P2P2_DP<0>")
	)
	(segment
		(start 56.440578 -356.629716)
		(end 62.262766 -370.686584)
		(width 0.14732)
		(layer "In11.Cu")
		(net "UPI_CPU1_CPU0_P2P2_DP<0>")
	)
	(segment
		(start 266.304776 -384.20294)
		(end 279.67432 -370.833142)
		(width 0.14732)
		(layer "In11.Cu")
		(net "UPI_CPU1_CPU0_P2P2_DP<0>")
	)
	(segment
		(start 343.638124 -310.72201)
		(end 345.845638 -309.80761)
		(width 0.14732)
		(layer "In11.Cu")
		(net "UPI_CPU1_CPU0_P2P2_DP<0>")
	)
	(segment
		(start 127.121412 -392.998452)
		(end 162.062922 -392.998452)
		(width 0.14732)
		(layer "In11.Cu")
		(net "UPI_CPU1_CPU0_P2P2_DP<0>")
	)
	(segment
		(start 58.247026 -312.235088)
		(end 55.778908 -313.88431)
		(width 0.14732)
		(layer "In11.Cu")
		(net "UPI_CPU1_CPU0_P2P2_DP<0>")
	)
	(segment
		(start 52.797964 -317.18377)
		(end 52.676298 -317.477394)
		(width 0.14732)
		(layer "In11.Cu")
		(net "UPI_CPU1_CPU0_P2P2_DP<0>")
	)
	(segment
		(start 55.778908 -313.88431)
		(end 53.986176 -314.842652)
		(width 0.14732)
		(layer "In11.Cu")
		(net "UPI_CPU1_CPU0_P2P2_DP<0>")
	)
	(segment
		(start 62.412372 -310.24576)
		(end 61.445648 -310.646318)
		(width 0.14732)
		(layer "In11.Cu")
		(net "UPI_CPU1_CPU0_P2P2_DP<0>")
	)
	(segment
		(start 359.024428 -283.714444)
		(end 359.033318 -283.709364)
		(width 0.0889)
		(layer "In11.Cu")
		(net "UPI_CPU1_CPU0_P2P2_DP<0>")
	)
	(segment
		(start 70.399656 -378.823474)
		(end 92.07119 -387.799072)
		(width 0.14732)
		(layer "In11.Cu")
		(net "UPI_CPU1_CPU0_P2P2_DP<0>")
	)
	(segment
		(start 356.957376 -289.131248)
		(end 356.966012 -288.97326)
		(width 0.0889)
		(layer "In11.Cu")
		(net "UPI_CPU1_CPU0_P2P2_DP<0>")
	)
	(segment
		(start 356.496112 -291.262308)
		(end 356.496112 -289.677602)
		(width 0.0889)
		(layer "In11.Cu")
		(net "UPI_CPU1_CPU0_P2P2_DP<0>")
	)
	(segment
		(start 356.966012 -288.97326)
		(end 356.972108 -288.863278)
		(width 0.0889)
		(layer "In11.Cu")
		(net "UPI_CPU1_CPU0_P2P2_DP<0>")
	)
	(segment
		(start 357.905812 -285.679896)
		(end 357.905812 -285.661354)
		(width 0.0889)
		(layer "In11.Cu")
		(net "UPI_CPU1_CPU0_P2P2_DP<0>")
	)
	(segment
		(start 359.502964 -279.639776)
		(end 359.503726 -279.639268)
		(width 0.0889)
		(layer "In11.Cu")
		(net "UPI_CPU1_CPU0_P2P2_DP<0>")
	)
	(segment
		(start 323.926454 -329.199494)
		(end 341.531194 -311.594754)
		(width 0.14732)
		(layer "In11.Cu")
		(net "UPI_CPU1_CPU0_P2P2_DP<0>")
	)
	(segment
		(start 360.255312 -278.351996)
		(end 360.255312 -278.336502)
		(width 0.0889)
		(layer "In11.Cu")
		(net "UPI_CPU1_CPU0_P2P2_DP<0>")
	)
	(segment
		(start 50.552858 -329.648566)
		(end 50.739294 -330.0984)
		(width 0.14732)
		(layer "In11.Cu")
		(net "UPI_CPU1_CPU0_P2P2_DP<0>")
	)
	(segment
		(start 352.955352 -275.351748)
		(end 353.111816 -275.08073)
		(width 0.0889)
		(layer "In11.Cu")
		(net "UPI_CPU1_CPU0_P2P2_DP<0>")
	)
	(segment
		(start 359.315766 -283.229812)
		(end 359.315766 -283.21127)
		(width 0.0889)
		(layer "In11.Cu")
		(net "UPI_CPU1_CPU0_P2P2_DP<0>")
	)
	(arc
		(start 356.966266 -287.280604)
		(mid 357.018536 -287.098239)
		(end 357.153464 -286.964882)
		(width 0.0889)
		(layer "In11.Cu")
		(net "UPI_CPU1_CPU0_P2P2_DP<0>")
	)
	(arc
		(start 355.366066 -275.08073)
		(mid 355.318387 -275.26363)
		(end 355.187504 -275.400008)
		(width 0.0889)
		(layer "In11.Cu")
		(net "UPI_CPU1_CPU0_P2P2_DP<0>")
	)
	(arc
		(start 353.85375 -275.398992)
		(mid 353.575572 -275.3293)
		(end 353.299014 -275.405088)
		(width 0.0889)
		(layer "In11.Cu")
		(net "UPI_CPU1_CPU0_P2P2_DP<0>")
	)
	(arc
		(start 360.433874 -277.027894)
		(mid 360.30296 -276.891534)
		(end 360.255312 -276.708616)
		(width 0.0889)
		(layer "In11.Cu")
		(net "UPI_CPU1_CPU0_P2P2_DP<0>")
	)
	(arc
		(start 358.093264 -274.591272)
		(mid 357.810562 -274.515496)
		(end 357.52786 -274.591272)
		(width 0.0889)
		(layer "In11.Cu")
		(net "UPI_CPU1_CPU0_P2P2_DP<0>")
	)
	(arc
		(start 359.502964 -281.916378)
		(mid 359.368031 -281.783024)
		(end 359.315766 -281.600656)
		(width 0.0889)
		(layer "In11.Cu")
		(net "UPI_CPU1_CPU0_P2P2_DP<0>")
	)
	(arc
		(start 359.785666 -282.405836)
		(mid 359.711675 -282.12627)
		(end 359.50906 -281.919934)
		(width 0.0889)
		(layer "In11.Cu")
		(net "UPI_CPU1_CPU0_P2P2_DP<0>")
	)
	(arc
		(start 355.64826 -274.591272)
		(mid 355.445437 -274.791503)
		(end 355.366066 -275.065236)
		(width 0.0889)
		(layer "In11.Cu")
		(net "UPI_CPU1_CPU0_P2P2_DP<0>")
	)
	(arc
		(start 359.502964 -282.895548)
		(mid 359.706445 -282.694744)
		(end 359.785666 -282.42006)
		(width 0.0889)
		(layer "In11.Cu")
		(net "UPI_CPU1_CPU0_P2P2_DP<0>")
	)
	(arc
		(start 85.052408 -284.431994)
		(mid 85.044201 -284.439786)
		(end 85.036152 -284.447742)
		(width 0.0889)
		(layer "In11.Cu")
		(net "UPI_CPU1_CPU0_P2P2_DP<0>")
	)
	(arc
		(start 359.50906 -279.63622)
		(mid 359.711647 -279.429869)
		(end 359.785666 -279.150318)
		(width 0.0889)
		(layer "In11.Cu")
		(net "UPI_CPU1_CPU0_P2P2_DP<0>")
	)
	(arc
		(start 357.153464 -274.591272)
		(mid 356.876905 -274.515529)
		(end 356.598728 -274.585176)
		(width 0.0889)
		(layer "In11.Cu")
		(net "UPI_CPU1_CPU0_P2P2_DP<0>")
	)
	(arc
		(start 359.315766 -275.070824)
		(mid 359.237655 -274.793875)
		(end 359.033318 -274.591272)
		(width 0.0889)
		(layer "In11.Cu")
		(net "UPI_CPU1_CPU0_P2P2_DP<0>")
	)
	(arc
		(start 357.153464 -286.964882)
		(mid 357.357799 -286.762277)
		(end 357.435912 -286.48533)
		(width 0.0889)
		(layer "In11.Cu")
		(net "UPI_CPU1_CPU0_P2P2_DP<0>")
	)
	(arc
		(start 359.315766 -279.955498)
		(mid 359.368036 -279.773133)
		(end 359.502964 -279.639776)
		(width 0.0889)
		(layer "In11.Cu")
		(net "UPI_CPU1_CPU0_P2P2_DP<0>")
	)
	(arc
		(start 359.964228 -276.214078)
		(mid 359.833314 -276.077718)
		(end 359.785666 -275.8948)
		(width 0.0889)
		(layer "In11.Cu")
		(net "UPI_CPU1_CPU0_P2P2_DP<0>")
	)
	(arc
		(start 359.502964 -280.288492)
		(mid 359.368031 -280.155138)
		(end 359.315766 -279.97277)
		(width 0.0889)
		(layer "In11.Cu")
		(net "UPI_CPU1_CPU0_P2P2_DP<0>")
	)
	(arc
		(start 356.681532 -289.458654)
		(mid 356.850337 -289.320972)
		(end 356.957376 -289.131248)
		(width 0.0889)
		(layer "In11.Cu")
		(net "UPI_CPU1_CPU0_P2P2_DP<0>")
	)
	(arc
		(start 359.033318 -283.709364)
		(mid 359.237653 -283.506759)
		(end 359.315766 -283.229812)
		(width 0.0889)
		(layer "In11.Cu")
		(net "UPI_CPU1_CPU0_P2P2_DP<0>")
	)
	(arc
		(start 356.496366 -288.09442)
		(mid 356.548636 -287.912055)
		(end 356.683564 -287.778698)
		(width 0.0889)
		(layer "In11.Cu")
		(net "UPI_CPU1_CPU0_P2P2_DP<0>")
	)
	(arc
		(start 356.588314 -274.591272)
		(mid 356.401116 -274.641415)
		(end 356.213918 -274.591272)
		(width 0.0889)
		(layer "In11.Cu")
		(net "UPI_CPU1_CPU0_P2P2_DP<0>")
	)
	(arc
		(start 360.255312 -276.693122)
		(mid 360.175942 -276.419388)
		(end 359.973118 -276.219158)
		(width 0.0889)
		(layer "In11.Cu")
		(net "UPI_CPU1_CPU0_P2P2_DP<0>")
	)
	(arc
		(start 359.502964 -275.405088)
		(mid 359.368031 -275.271734)
		(end 359.315766 -275.089366)
		(width 0.0889)
		(layer "In11.Cu")
		(net "UPI_CPU1_CPU0_P2P2_DP<0>")
	)
	(arc
		(start 357.905812 -285.661354)
		(mid 357.953491 -285.478454)
		(end 358.084374 -285.342076)
		(width 0.0889)
		(layer "In11.Cu")
		(net "UPI_CPU1_CPU0_P2P2_DP<0>")
	)
	(arc
		(start 359.973118 -278.82596)
		(mid 360.175941 -278.625729)
		(end 360.255312 -278.351996)
		(width 0.0889)
		(layer "In11.Cu")
		(net "UPI_CPU1_CPU0_P2P2_DP<0>")
	)
	(arc
		(start 359.785666 -275.880576)
		(mid 359.706447 -275.605891)
		(end 359.502964 -275.405088)
		(width 0.0889)
		(layer "In11.Cu")
		(net "UPI_CPU1_CPU0_P2P2_DP<0>")
	)
	(arc
		(start 85.997288 -284.782006)
		(mid 85.995989 -284.771452)
		(end 85.994494 -284.760924)
		(width 0.0889)
		(layer "In11.Cu")
		(net "UPI_CPU1_CPU0_P2P2_DP<0>")
	)
	(arc
		(start 85.994494 -284.760924)
		(mid 85.679964 -284.337703)
		(end 85.152992 -284.35808)
		(width 0.0889)
		(layer "In11.Cu")
		(net "UPI_CPU1_CPU0_P2P2_DP<0>")
	)
	(arc
		(start 356.972108 -288.863278)
		(mid 356.877056 -288.61746)
		(end 356.682548 -288.439606)
		(width 0.0889)
		(layer "In11.Cu")
		(net "UPI_CPU1_CPU0_P2P2_DP<0>")
	)
	(arc
		(start 359.315766 -283.21127)
		(mid 359.368036 -283.028905)
		(end 359.502964 -282.895548)
		(width 0.0889)
		(layer "In11.Cu")
		(net "UPI_CPU1_CPU0_P2P2_DP<0>")
	)
	(arc
		(start 358.46766 -274.591272)
		(mid 358.280462 -274.641415)
		(end 358.093264 -274.591272)
		(width 0.0889)
		(layer "In11.Cu")
		(net "UPI_CPU1_CPU0_P2P2_DP<0>")
	)
	(arc
		(start 358.375966 -284.847538)
		(mid 358.423645 -284.664638)
		(end 358.554528 -284.52826)
		(width 0.0889)
		(layer "In11.Cu")
		(net "UPI_CPU1_CPU0_P2P2_DP<0>")
	)
	(arc
		(start 356.68966 -287.775142)
		(mid 356.892247 -287.568791)
		(end 356.966266 -287.28924)
		(width 0.0889)
		(layer "In11.Cu")
		(net "UPI_CPU1_CPU0_P2P2_DP<0>")
	)
	(arc
		(start 353.299014 -275.405088)
		(mid 353.140526 -275.454021)
		(end 352.976434 -275.429726)
		(width 0.0889)
		(layer "In11.Cu")
		(net "UPI_CPU1_CPU0_P2P2_DP<0>")
	)
	(arc
		(start 355.178614 -275.405088)
		(mid 354.991416 -275.455231)
		(end 354.804218 -275.405088)
		(width 0.0889)
		(layer "In11.Cu")
		(net "UPI_CPU1_CPU0_P2P2_DP<0>")
	)
	(arc
		(start 354.804218 -275.405088)
		(mid 354.527405 -275.329252)
		(end 354.248974 -275.398992)
		(width 0.0889)
		(layer "In11.Cu")
		(net "UPI_CPU1_CPU0_P2P2_DP<0>")
	)
	(arc
		(start 357.52786 -274.591272)
		(mid 357.340662 -274.641415)
		(end 357.153464 -274.591272)
		(width 0.0889)
		(layer "In11.Cu")
		(net "UPI_CPU1_CPU0_P2P2_DP<0>")
	)
	(arc
		(start 358.845866 -284.033722)
		(mid 358.893545 -283.850822)
		(end 359.024428 -283.714444)
		(width 0.0889)
		(layer "In11.Cu")
		(net "UPI_CPU1_CPU0_P2P2_DP<0>")
	)
	(arc
		(start 359.50906 -281.264106)
		(mid 359.711647 -281.057755)
		(end 359.785666 -280.778204)
		(width 0.0889)
		(layer "In11.Cu")
		(net "UPI_CPU1_CPU0_P2P2_DP<0>")
	)
	(arc
		(start 85.152992 -284.35808)
		(mid 85.100656 -284.392255)
		(end 85.052408 -284.431994)
		(width 0.0889)
		(layer "In11.Cu")
		(net "UPI_CPU1_CPU0_P2P2_DP<0>")
	)
	(arc
		(start 356.682548 -288.439606)
		(mid 356.564063 -288.336778)
		(end 356.496366 -288.195258)
		(width 0.0889)
		(layer "In11.Cu")
		(net "UPI_CPU1_CPU0_P2P2_DP<0>")
	)
	(arc
		(start 359.022904 -274.585176)
		(mid 358.744472 -274.51533)
		(end 358.46766 -274.591272)
		(width 0.0889)
		(layer "In11.Cu")
		(net "UPI_CPU1_CPU0_P2P2_DP<0>")
	)
	(arc
		(start 360.442764 -278.012144)
		(mid 360.646245 -277.81134)
		(end 360.725466 -277.536656)
		(width 0.0889)
		(layer "In11.Cu")
		(net "UPI_CPU1_CPU0_P2P2_DP<0>")
	)
	(arc
		(start 359.315766 -281.583384)
		(mid 359.368036 -281.401019)
		(end 359.502964 -281.267662)
		(width 0.0889)
		(layer "In11.Cu")
		(net "UPI_CPU1_CPU0_P2P2_DP<0>")
	)
	(arc
		(start 360.255312 -278.336502)
		(mid 360.302991 -278.153602)
		(end 360.433874 -278.017224)
		(width 0.0889)
		(layer "In11.Cu")
		(net "UPI_CPU1_CPU0_P2P2_DP<0>")
	)
	(arc
		(start 357.435912 -286.475424)
		(mid 357.483591 -286.292524)
		(end 357.614474 -286.156146)
		(width 0.0889)
		(layer "In11.Cu")
		(net "UPI_CPU1_CPU0_P2P2_DP<0>")
	)
	(arc
		(start 356.203504 -274.585176)
		(mid 355.925072 -274.51533)
		(end 355.64826 -274.591272)
		(width 0.0889)
		(layer "In11.Cu")
		(net "UPI_CPU1_CPU0_P2P2_DP<0>")
	)
	(arc
		(start 358.105456 -285.329884)
		(mid 358.303684 -285.124036)
		(end 358.375966 -284.847538)
		(width 0.0889)
		(layer "In11.Cu")
		(net "UPI_CPU1_CPU0_P2P2_DP<0>")
	)
	(arc
		(start 359.785666 -280.76398)
		(mid 359.706447 -280.489295)
		(end 359.502964 -280.288492)
		(width 0.0889)
		(layer "In11.Cu")
		(net "UPI_CPU1_CPU0_P2P2_DP<0>")
	)
	(arc
		(start 354.23856 -275.405088)
		(mid 354.051362 -275.455231)
		(end 353.864164 -275.405088)
		(width 0.0889)
		(layer "In11.Cu")
		(net "UPI_CPU1_CPU0_P2P2_DP<0>")
	)
	(arc
		(start 357.623364 -286.151066)
		(mid 357.82565 -285.952085)
		(end 357.905812 -285.679896)
		(width 0.0889)
		(layer "In11.Cu")
		(net "UPI_CPU1_CPU0_P2P2_DP<0>")
	)
	(arc
		(start 356.496112 -289.677602)
		(mid 356.568285 -289.550721)
		(end 356.681532 -289.458654)
		(width 0.0889)
		(layer "In11.Cu")
		(net "UPI_CPU1_CPU0_P2P2_DP<0>")
	)
	(arc
		(start 358.569514 -284.519624)
		(mid 358.771927 -284.313211)
		(end 358.845866 -284.033722)
		(width 0.0889)
		(layer "In11.Cu")
		(net "UPI_CPU1_CPU0_P2P2_DP<0>")
	)
	(arc
		(start 359.785666 -279.150318)
		(mid 359.833345 -278.967418)
		(end 359.964228 -278.83104)
		(width 0.0889)
		(layer "In11.Cu")
		(net "UPI_CPU1_CPU0_P2P2_DP<0>")
	)
	(arc
		(start 360.725466 -277.522432)
		(mid 360.651475 -277.242866)
		(end 360.44886 -277.03653)
		(width 0.0889)
		(layer "In11.Cu")
		(net "UPI_CPU1_CPU0_P2P2_DP<0>")
	)
	(segment
		(start 93.893894 -281.05608)
		(end 93.893894 -281.59202)
		(width 0.13208)
		(layer "F.Cu")
		(net "UPI_CPU1_CPU0_P2P2_DN<9>")
	)
	(segment
		(start 351.231962 -276.708362)
		(end 351.232216 -276.708616)
		(width 0.13208)
		(layer "F.Cu")
		(net "UPI_CPU1_CPU0_P2P2_DN<9>")
	)
	(segment
		(start 351.231962 -276.172676)
		(end 351.231962 -276.708362)
		(width 0.13208)
		(layer "F.Cu")
		(net "UPI_CPU1_CPU0_P2P2_DN<9>")
	)
	(segment
		(start 346.720414 -288.427414)
		(end 346.729304 -288.422334)
		(width 0.0889)
		(layer "In11.Cu")
		(net "UPI_CPU1_CPU0_P2P2_DN<9>")
	)
	(segment
		(start 347.847412 -286.48406)
		(end 347.847412 -286.466788)
		(width 0.0889)
		(layer "In11.Cu")
		(net "UPI_CPU1_CPU0_P2P2_DN<9>")
	)
	(segment
		(start 339.01126 -303.661572)
		(end 339.20049 -303.740058)
		(width 0.14732)
		(layer "In11.Cu")
		(net "UPI_CPU1_CPU0_P2P2_DN<9>")
	)
	(segment
		(start 347.656658 -286.801814)
		(end 347.659452 -286.80029)
		(width 0.0889)
		(layer "In11.Cu")
		(net "UPI_CPU1_CPU0_P2P2_DN<9>")
	)
	(segment
		(start 337.872832 -304.289968)
		(end 338.592414 -303.992026)
		(width 0.14732)
		(layer "In11.Cu")
		(net "UPI_CPU1_CPU0_P2P2_DN<9>")
	)
	(segment
		(start 93.989144 -284.033722)
		(end 93.989144 -284.049216)
		(width 0.0889)
		(layer "In11.Cu")
		(net "UPI_CPU1_CPU0_P2P2_DN<9>")
	)
	(segment
		(start 262.001 -376.512074)
		(end 271.69364 -366.819434)
		(width 0.14732)
		(layer "In11.Cu")
		(net "UPI_CPU1_CPU0_P2P2_DN<9>")
	)
	(segment
		(start 93.227906 -285.980632)
		(end 93.236796 -285.985712)
		(width 0.0889)
		(layer "In11.Cu")
		(net "UPI_CPU1_CPU0_P2P2_DN<9>")
	)
	(segment
		(start 93.049598 -287.280604)
		(end 93.049598 -287.299146)
		(width 0.0889)
		(layer "In11.Cu")
		(net "UPI_CPU1_CPU0_P2P2_DN<9>")
	)
	(segment
		(start 93.70695 -284.52318)
		(end 93.69806 -284.52826)
		(width 0.0889)
		(layer "In11.Cu")
		(net "UPI_CPU1_CPU0_P2P2_DN<9>")
	)
	(segment
		(start 350.479614 -279.639776)
		(end 350.478852 -279.639268)
		(width 0.0889)
		(layer "In11.Cu")
		(net "UPI_CPU1_CPU0_P2P2_DN<9>")
	)
	(segment
		(start 93.236796 -285.336996)
		(end 93.227906 -285.342076)
		(width 0.0889)
		(layer "In11.Cu")
		(net "UPI_CPU1_CPU0_P2P2_DN<9>")
	)
	(segment
		(start 86.579202 -300.851316)
		(end 86.389718 -300.929802)
		(width 0.14732)
		(layer "In11.Cu")
		(net "UPI_CPU1_CPU0_P2P2_DN<9>")
	)
	(segment
		(start 64.49187 -329.176634)
		(end 64.205358 -332.06436)
		(width 0.14732)
		(layer "In11.Cu")
		(net "UPI_CPU1_CPU0_P2P2_DN<9>")
	)
	(segment
		(start 345.668346 -291.554408)
		(end 345.710256 -291.512498)
		(width 0.0889)
		(layer "In11.Cu")
		(net "UPI_CPU1_CPU0_P2P2_DN<9>")
	)
	(segment
		(start 92.579444 -289.60953)
		(end 92.579444 -291.432488)
		(width 0.0889)
		(layer "In11.Cu")
		(net "UPI_CPU1_CPU0_P2P2_DN<9>")
	)
	(segment
		(start 338.592414 -303.992026)
		(end 338.670646 -303.802542)
		(width 0.14732)
		(layer "In11.Cu")
		(net "UPI_CPU1_CPU0_P2P2_DN<9>")
	)
	(segment
		(start 69.10832 -366.476026)
		(end 74.01941 -371.387116)
		(width 0.14732)
		(layer "In11.Cu")
		(net "UPI_CPU1_CPU0_P2P2_DN<9>")
	)
	(segment
		(start 347.847666 -284.847538)
		(end 347.847666 -284.832044)
		(width 0.0889)
		(layer "In11.Cu")
		(net "UPI_CPU1_CPU0_P2P2_DN<9>")
	)
	(segment
		(start 92.579698 -288.103056)
		(end 92.579698 -288.121598)
		(width 0.0889)
		(layer "In11.Cu")
		(net "UPI_CPU1_CPU0_P2P2_DN<9>")
	)
	(segment
		(start 348.12986 -284.35808)
		(end 348.13875 -284.353)
		(width 0.0889)
		(layer "In11.Cu")
		(net "UPI_CPU1_CPU0_P2P2_DN<9>")
	)
	(segment
		(start 347.377512 -285.675578)
		(end 347.377512 -285.661354)
		(width 0.0889)
		(layer "In11.Cu")
		(net "UPI_CPU1_CPU0_P2P2_DN<9>")
	)
	(segment
		(start 88.41867 -296.03065)
		(end 87.427054 -298.425362)
		(width 0.14732)
		(layer "In11.Cu")
		(net "UPI_CPU1_CPU0_P2P2_DN<9>")
	)
	(segment
		(start 349.727266 -281.59202)
		(end 349.727266 -281.576526)
		(width 0.0889)
		(layer "In11.Cu")
		(net "UPI_CPU1_CPU0_P2P2_DN<9>")
	)
	(segment
		(start 350.666812 -279.97277)
		(end 350.666812 -279.955498)
		(width 0.0889)
		(layer "In11.Cu")
		(net "UPI_CPU1_CPU0_P2P2_DN<9>")
	)
	(segment
		(start 142.98422 -384.93319)
		(end 143.4211 -384.93319)
		(width 0.14732)
		(layer "In11.Cu")
		(net "UPI_CPU1_CPU0_P2P2_DN<9>")
	)
	(segment
		(start 94.176596 -283.709364)
		(end 94.167706 -283.714444)
		(width 0.0889)
		(layer "In11.Cu")
		(net "UPI_CPU1_CPU0_P2P2_DN<9>")
	)
	(segment
		(start 317.012828 -325.149972)
		(end 337.872832 -304.289968)
		(width 0.14732)
		(layer "In11.Cu")
		(net "UPI_CPU1_CPU0_P2P2_DN<9>")
	)
	(segment
		(start 85.9282 -302.0441)
		(end 67.67068 -320.301874)
		(width 0.14732)
		(layer "In11.Cu")
		(net "UPI_CPU1_CPU0_P2P2_DN<9>")
	)
	(segment
		(start 93.893894 -281.59202)
		(end 93.73743 -281.863038)
		(width 0.0889)
		(layer "In11.Cu")
		(net "UPI_CPU1_CPU0_P2P2_DN<9>")
	)
	(segment
		(start 349.539814 -281.916378)
		(end 349.548704 -281.911298)
		(width 0.0889)
		(layer "In11.Cu")
		(net "UPI_CPU1_CPU0_P2P2_DN<9>")
	)
	(segment
		(start 351.36455 -277.068788)
		(end 351.38868 -276.979634)
		(width 0.0889)
		(layer "In11.Cu")
		(net "UPI_CPU1_CPU0_P2P2_DN<9>")
	)
	(segment
		(start 92.29725 -288.592768)
		(end 92.28836 -288.597848)
		(width 0.0889)
		(layer "In11.Cu")
		(net "UPI_CPU1_CPU0_P2P2_DN<9>")
	)
	(segment
		(start 74.01941 -371.387116)
		(end 96.14789 -380.553214)
		(width 0.14732)
		(layer "In11.Cu")
		(net "UPI_CPU1_CPU0_P2P2_DN<9>")
	)
	(segment
		(start 345.710256 -291.297614)
		(end 346.907866 -290.100004)
		(width 0.0889)
		(layer "In11.Cu")
		(net "UPI_CPU1_CPU0_P2P2_DN<9>")
	)
	(segment
		(start 349.533718 -281.919934)
		(end 349.539814 -281.916378)
		(width 0.0889)
		(layer "In11.Cu")
		(net "UPI_CPU1_CPU0_P2P2_DN<9>")
	)
	(segment
		(start 87.427054 -298.425362)
		(end 87.50554 -298.614592)
		(width 0.14732)
		(layer "In11.Cu")
		(net "UPI_CPU1_CPU0_P2P2_DN<9>")
	)
	(segment
		(start 348.59976 -283.544264)
		(end 348.600522 -283.543756)
		(width 0.0889)
		(layer "In11.Cu")
		(net "UPI_CPU1_CPU0_P2P2_DN<9>")
	)
	(segment
		(start 93.242892 -286.961326)
		(end 93.237558 -286.964374)
		(width 0.0889)
		(layer "In11.Cu")
		(net "UPI_CPU1_CPU0_P2P2_DN<9>")
	)
	(segment
		(start 348.603062 -283.542232)
		(end 348.60865 -283.539184)
		(width 0.0889)
		(layer "In11.Cu")
		(net "UPI_CPU1_CPU0_P2P2_DN<9>")
	)
	(segment
		(start 350.010476 -281.102054)
		(end 350.01835 -281.097482)
		(width 0.0889)
		(layer "In11.Cu")
		(net "UPI_CPU1_CPU0_P2P2_DN<9>")
	)
	(segment
		(start 347.654118 -285.175452)
		(end 347.660214 -285.171896)
		(width 0.0889)
		(layer "In11.Cu")
		(net "UPI_CPU1_CPU0_P2P2_DN<9>")
	)
	(segment
		(start 347.654118 -286.803338)
		(end 347.656658 -286.801814)
		(width 0.0889)
		(layer "In11.Cu")
		(net "UPI_CPU1_CPU0_P2P2_DN<9>")
	)
	(segment
		(start 348.600522 -283.543756)
		(end 348.603062 -283.542232)
		(width 0.0889)
		(layer "In11.Cu")
		(net "UPI_CPU1_CPU0_P2P2_DN<9>")
	)
	(segment
		(start 285.98114 -335.13395)
		(end 308.582822 -335.13395)
		(width 0.14732)
		(layer "In11.Cu")
		(net "UPI_CPU1_CPU0_P2P2_DN<9>")
	)
	(segment
		(start 346.437966 -289.114738)
		(end 346.437966 -288.898584)
		(width 0.0889)
		(layer "In11.Cu")
		(net "UPI_CPU1_CPU0_P2P2_DN<9>")
	)
	(segment
		(start 350.94926 -277.84679)
		(end 350.95815 -277.84171)
		(width 0.0889)
		(layer "In11.Cu")
		(net "UPI_CPU1_CPU0_P2P2_DN<9>")
	)
	(segment
		(start 340.13013 -303.198276)
		(end 340.31936 -303.276508)
		(width 0.14732)
		(layer "In11.Cu")
		(net "UPI_CPU1_CPU0_P2P2_DN<9>")
	)
	(segment
		(start 346.907866 -290.100004)
		(end 346.907866 -289.64636)
		(width 0.0889)
		(layer "In11.Cu")
		(net "UPI_CPU1_CPU0_P2P2_DN<9>")
	)
	(segment
		(start 161.327846 -385.05511)
		(end 262.001 -376.512074)
		(width 0.14732)
		(layer "In11.Cu")
		(net "UPI_CPU1_CPU0_P2P2_DN<9>")
	)
	(segment
		(start 92.109798 -288.917126)
		(end 92.109798 -289.078416)
		(width 0.0889)
		(layer "In11.Cu")
		(net "UPI_CPU1_CPU0_P2P2_DN<9>")
	)
	(segment
		(start 64.205358 -332.06436)
		(end 64.205358 -354.63861)
		(width 0.14732)
		(layer "In11.Cu")
		(net "UPI_CPU1_CPU0_P2P2_DN<9>")
	)
	(segment
		(start 350.478852 -279.639268)
		(end 350.473518 -279.63622)
		(width 0.0889)
		(layer "In11.Cu")
		(net "UPI_CPU1_CPU0_P2P2_DN<9>")
	)
	(segment
		(start 94.459044 -283.197808)
		(end 94.459044 -283.229812)
		(width 0.0889)
		(layer "In11.Cu")
		(net "UPI_CPU1_CPU0_P2P2_DN<9>")
	)
	(segment
		(start 350.667066 -278.336502)
		(end 350.667066 -278.314404)
		(width 0.0889)
		(layer "In11.Cu")
		(net "UPI_CPU1_CPU0_P2P2_DN<9>")
	)
	(segment
		(start 271.69364 -366.819434)
		(end 271.69364 -346.705682)
		(width 0.14732)
		(layer "In11.Cu")
		(net "UPI_CPU1_CPU0_P2P2_DN<9>")
	)
	(segment
		(start 350.196912 -280.778204)
		(end 350.196912 -280.770584)
		(width 0.0889)
		(layer "In11.Cu")
		(net "UPI_CPU1_CPU0_P2P2_DN<9>")
	)
	(segment
		(start 64.205358 -354.63861)
		(end 69.10832 -366.476026)
		(width 0.14732)
		(layer "In11.Cu")
		(net "UPI_CPU1_CPU0_P2P2_DN<9>")
	)
	(segment
		(start 141.7447 -385.05511)
		(end 141.86662 -384.93319)
		(width 0.14732)
		(layer "In11.Cu")
		(net "UPI_CPU1_CPU0_P2P2_DN<9>")
	)
	(segment
		(start 86.389718 -300.929802)
		(end 85.9282 -302.0441)
		(width 0.14732)
		(layer "In11.Cu")
		(net "UPI_CPU1_CPU0_P2P2_DN<9>")
	)
	(segment
		(start 93.73743 -281.863038)
		(end 93.76156 -281.952192)
		(width 0.0889)
		(layer "In11.Cu")
		(net "UPI_CPU1_CPU0_P2P2_DN<9>")
	)
	(segment
		(start 94.16796 -282.725114)
		(end 94.17685 -282.730194)
		(width 0.0889)
		(layer "In11.Cu")
		(net "UPI_CPU1_CPU0_P2P2_DN<9>")
	)
	(segment
		(start 93.519498 -286.4612)
		(end 93.519498 -286.475424)
		(width 0.0889)
		(layer "In11.Cu")
		(net "UPI_CPU1_CPU0_P2P2_DN<9>")
	)
	(segment
		(start 315.914024 -327.802748)
		(end 317.012828 -325.149972)
		(width 0.14732)
		(layer "In11.Cu")
		(net "UPI_CPU1_CPU0_P2P2_DN<9>")
	)
	(segment
		(start 338.670646 -303.802542)
		(end 339.01126 -303.661572)
		(width 0.14732)
		(layer "In11.Cu")
		(net "UPI_CPU1_CPU0_P2P2_DN<9>")
	)
	(segment
		(start 308.582822 -335.13395)
		(end 315.914024 -327.802748)
		(width 0.14732)
		(layer "In11.Cu")
		(net "UPI_CPU1_CPU0_P2P2_DN<9>")
	)
	(segment
		(start 348.317312 -284.033722)
		(end 348.317312 -284.023816)
		(width 0.0889)
		(layer "In11.Cu")
		(net "UPI_CPU1_CPU0_P2P2_DN<9>")
	)
	(segment
		(start 340.31936 -303.276508)
		(end 341.302848 -302.869346)
		(width 0.14732)
		(layer "In11.Cu")
		(net "UPI_CPU1_CPU0_P2P2_DN<9>")
	)
	(segment
		(start 93.237558 -286.964374)
		(end 93.236796 -286.964882)
		(width 0.0889)
		(layer "In11.Cu")
		(net "UPI_CPU1_CPU0_P2P2_DN<9>")
	)
	(segment
		(start 86.971886 -299.903134)
		(end 86.782402 -299.98162)
		(width 0.14732)
		(layer "In11.Cu")
		(net "UPI_CPU1_CPU0_P2P2_DN<9>")
	)
	(segment
		(start 142.8623 -385.05511)
		(end 142.98422 -384.93319)
		(width 0.14732)
		(layer "In11.Cu")
		(net "UPI_CPU1_CPU0_P2P2_DN<9>")
	)
	(segment
		(start 126.498096 -385.05511)
		(end 141.7447 -385.05511)
		(width 0.14732)
		(layer "In11.Cu")
		(net "UPI_CPU1_CPU0_P2P2_DN<9>")
	)
	(segment
		(start 86.719918 -300.510702)
		(end 86.579202 -300.851316)
		(width 0.14732)
		(layer "In11.Cu")
		(net "UPI_CPU1_CPU0_P2P2_DN<9>")
	)
	(segment
		(start 345.668346 -294.038528)
		(end 345.668346 -291.576506)
		(width 0.14732)
		(layer "In11.Cu")
		(net "UPI_CPU1_CPU0_P2P2_DN<9>")
	)
	(segment
		(start 350.00946 -281.102562)
		(end 350.010476 -281.102054)
		(width 0.0889)
		(layer "In11.Cu")
		(net "UPI_CPU1_CPU0_P2P2_DN<9>")
	)
	(segment
		(start 344.850212 -298.150788)
		(end 345.668346 -294.038528)
		(width 0.14732)
		(layer "In11.Cu")
		(net "UPI_CPU1_CPU0_P2P2_DN<9>")
	)
	(segment
		(start 92.621608 -291.478208)
		(end 92.621608 -291.827712)
		(width 0.14732)
		(layer "In11.Cu")
		(net "UPI_CPU1_CPU0_P2P2_DN<9>")
	)
	(segment
		(start 347.659452 -286.80029)
		(end 347.660214 -286.799782)
		(width 0.0889)
		(layer "In11.Cu")
		(net "UPI_CPU1_CPU0_P2P2_DN<9>")
	)
	(segment
		(start 345.668346 -291.576506)
		(end 345.668346 -291.554408)
		(width 0.0889)
		(layer "In11.Cu")
		(net "UPI_CPU1_CPU0_P2P2_DN<9>")
	)
	(segment
		(start 347.660214 -285.171896)
		(end 347.669104 -285.166816)
		(width 0.0889)
		(layer "In11.Cu")
		(net "UPI_CPU1_CPU0_P2P2_DN<9>")
	)
	(segment
		(start 281.345132 -337.05419)
		(end 285.98114 -335.13395)
		(width 0.14732)
		(layer "In11.Cu")
		(net "UPI_CPU1_CPU0_P2P2_DN<9>")
	)
	(segment
		(start 345.710256 -291.512498)
		(end 345.710256 -291.297614)
		(width 0.0889)
		(layer "In11.Cu")
		(net "UPI_CPU1_CPU0_P2P2_DN<9>")
	)
	(segment
		(start 141.86662 -384.93319)
		(end 142.3035 -384.93319)
		(width 0.14732)
		(layer "In11.Cu")
		(net "UPI_CPU1_CPU0_P2P2_DN<9>")
	)
	(segment
		(start 347.19006 -287.613598)
		(end 347.19895 -287.608518)
		(width 0.0889)
		(layer "In11.Cu")
		(net "UPI_CPU1_CPU0_P2P2_DN<9>")
	)
	(segment
		(start 87.36457 -298.954952)
		(end 87.175086 -299.033438)
		(width 0.14732)
		(layer "In11.Cu")
		(net "UPI_CPU1_CPU0_P2P2_DN<9>")
	)
	(segment
		(start 93.242892 -285.33344)
		(end 93.236796 -285.336996)
		(width 0.0889)
		(layer "In11.Cu")
		(net "UPI_CPU1_CPU0_P2P2_DN<9>")
	)
	(segment
		(start 339.78977 -303.339246)
		(end 340.13013 -303.198276)
		(width 0.14732)
		(layer "In11.Cu")
		(net "UPI_CPU1_CPU0_P2P2_DN<9>")
	)
	(segment
		(start 349.06966 -282.730194)
		(end 349.07855 -282.725114)
		(width 0.0889)
		(layer "In11.Cu")
		(net "UPI_CPU1_CPU0_P2P2_DN<9>")
	)
	(segment
		(start 87.175086 -299.033438)
		(end 87.03437 -299.373544)
		(width 0.14732)
		(layer "In11.Cu")
		(net "UPI_CPU1_CPU0_P2P2_DN<9>")
	)
	(segment
		(start 87.03437 -299.373544)
		(end 87.112856 -299.562774)
		(width 0.14732)
		(layer "In11.Cu")
		(net "UPI_CPU1_CPU0_P2P2_DN<9>")
	)
	(segment
		(start 67.67068 -320.301874)
		(end 65.939162 -323.960744)
		(width 0.14732)
		(layer "In11.Cu")
		(net "UPI_CPU1_CPU0_P2P2_DN<9>")
	)
	(segment
		(start 142.3035 -384.93319)
		(end 142.42542 -385.05511)
		(width 0.14732)
		(layer "In11.Cu")
		(net "UPI_CPU1_CPU0_P2P2_DN<9>")
	)
	(segment
		(start 143.4211 -384.93319)
		(end 143.54302 -385.05511)
		(width 0.14732)
		(layer "In11.Cu")
		(net "UPI_CPU1_CPU0_P2P2_DN<9>")
	)
	(segment
		(start 348.787212 -283.219906)
		(end 348.787212 -283.205682)
		(width 0.0889)
		(layer "In11.Cu")
		(net "UPI_CPU1_CPU0_P2P2_DN<9>")
	)
	(segment
		(start 350.479614 -278.66086)
		(end 350.488504 -278.65578)
		(width 0.0889)
		(layer "In11.Cu")
		(net "UPI_CPU1_CPU0_P2P2_DN<9>")
	)
	(segment
		(start 92.621608 -291.827712)
		(end 88.41867 -296.03065)
		(width 0.14732)
		(layer "In11.Cu")
		(net "UPI_CPU1_CPU0_P2P2_DN<9>")
	)
	(segment
		(start 65.939162 -323.960744)
		(end 64.49187 -329.176634)
		(width 0.14732)
		(layer "In11.Cu")
		(net "UPI_CPU1_CPU0_P2P2_DN<9>")
	)
	(segment
		(start 339.20049 -303.740058)
		(end 339.711284 -303.528476)
		(width 0.14732)
		(layer "In11.Cu")
		(net "UPI_CPU1_CPU0_P2P2_DN<9>")
	)
	(segment
		(start 341.302848 -302.869346)
		(end 344.02268 -300.149514)
		(width 0.14732)
		(layer "In11.Cu")
		(net "UPI_CPU1_CPU0_P2P2_DN<9>")
	)
	(segment
		(start 142.42542 -385.05511)
		(end 142.8623 -385.05511)
		(width 0.14732)
		(layer "In11.Cu")
		(net "UPI_CPU1_CPU0_P2P2_DN<9>")
	)
	(segment
		(start 350.473518 -278.664416)
		(end 350.479614 -278.66086)
		(width 0.0889)
		(layer "In11.Cu")
		(net "UPI_CPU1_CPU0_P2P2_DN<9>")
	)
	(segment
		(start 87.50554 -298.614592)
		(end 87.36457 -298.954952)
		(width 0.14732)
		(layer "In11.Cu")
		(net "UPI_CPU1_CPU0_P2P2_DN<9>")
	)
	(segment
		(start 351.38868 -276.979634)
		(end 351.232216 -276.708616)
		(width 0.0889)
		(layer "In11.Cu")
		(net "UPI_CPU1_CPU0_P2P2_DN<9>")
	)
	(segment
		(start 87.112856 -299.562774)
		(end 86.971886 -299.903134)
		(width 0.14732)
		(layer "In11.Cu")
		(net "UPI_CPU1_CPU0_P2P2_DN<9>")
	)
	(segment
		(start 143.54302 -385.05511)
		(end 161.327846 -385.05511)
		(width 0.14732)
		(layer "In11.Cu")
		(net "UPI_CPU1_CPU0_P2P2_DN<9>")
	)
	(segment
		(start 339.711284 -303.528476)
		(end 339.78977 -303.339246)
		(width 0.14732)
		(layer "In11.Cu")
		(net "UPI_CPU1_CPU0_P2P2_DN<9>")
	)
	(segment
		(start 92.621608 -291.474652)
		(end 92.621608 -291.478208)
		(width 0.0889)
		(layer "In11.Cu")
		(net "UPI_CPU1_CPU0_P2P2_DN<9>")
	)
	(segment
		(start 346.907866 -289.64636)
		(end 346.907612 -289.645852)
		(width 0.0889)
		(layer "In11.Cu")
		(net "UPI_CPU1_CPU0_P2P2_DN<9>")
	)
	(segment
		(start 344.02268 -300.149514)
		(end 344.850212 -298.150788)
		(width 0.14732)
		(layer "In11.Cu")
		(net "UPI_CPU1_CPU0_P2P2_DN<9>")
	)
	(segment
		(start 92.76715 -287.778698)
		(end 92.75826 -287.783778)
		(width 0.0889)
		(layer "In11.Cu")
		(net "UPI_CPU1_CPU0_P2P2_DN<9>")
	)
	(segment
		(start 96.14789 -380.553214)
		(end 126.498096 -385.05511)
		(width 0.14732)
		(layer "In11.Cu")
		(net "UPI_CPU1_CPU0_P2P2_DN<9>")
	)
	(segment
		(start 271.69364 -346.705682)
		(end 281.345132 -337.05419)
		(width 0.14732)
		(layer "In11.Cu")
		(net "UPI_CPU1_CPU0_P2P2_DN<9>")
	)
	(segment
		(start 86.641686 -300.321726)
		(end 86.719918 -300.510702)
		(width 0.14732)
		(layer "In11.Cu")
		(net "UPI_CPU1_CPU0_P2P2_DN<9>")
	)
	(segment
		(start 92.579444 -291.432488)
		(end 92.621608 -291.474652)
		(width 0.0889)
		(layer "In11.Cu")
		(net "UPI_CPU1_CPU0_P2P2_DN<9>")
	)
	(segment
		(start 346.907866 -288.103056)
		(end 346.907866 -288.087562)
		(width 0.0889)
		(layer "In11.Cu")
		(net "UPI_CPU1_CPU0_P2P2_DN<9>")
	)
	(segment
		(start 86.782402 -299.98162)
		(end 86.641686 -300.321726)
		(width 0.14732)
		(layer "In11.Cu")
		(net "UPI_CPU1_CPU0_P2P2_DN<9>")
	)
	(arc
		(start 94.17685 -282.730194)
		(mid 94.378132 -282.927681)
		(end 94.459044 -283.197808)
		(width 0.0889)
		(layer "In11.Cu")
		(net "UPI_CPU1_CPU0_P2P2_DN<9>")
	)
	(arc
		(start 93.236796 -285.985712)
		(mid 93.440277 -286.186516)
		(end 93.519498 -286.4612)
		(width 0.0889)
		(layer "In11.Cu")
		(net "UPI_CPU1_CPU0_P2P2_DN<9>")
	)
	(arc
		(start 93.989652 -282.420568)
		(mid 94.040706 -282.595148)
		(end 94.16796 -282.725114)
		(width 0.0889)
		(layer "In11.Cu")
		(net "UPI_CPU1_CPU0_P2P2_DN<9>")
	)
	(arc
		(start 347.847412 -286.466788)
		(mid 347.795142 -286.284423)
		(end 347.660214 -286.151066)
		(width 0.0889)
		(layer "In11.Cu")
		(net "UPI_CPU1_CPU0_P2P2_DN<9>")
	)
	(arc
		(start 348.60865 -283.539184)
		(mid 348.739564 -283.402824)
		(end 348.787212 -283.219906)
		(width 0.0889)
		(layer "In11.Cu")
		(net "UPI_CPU1_CPU0_P2P2_DN<9>")
	)
	(arc
		(start 92.28836 -288.597848)
		(mid 92.157446 -288.734208)
		(end 92.109798 -288.917126)
		(width 0.0889)
		(layer "In11.Cu")
		(net "UPI_CPU1_CPU0_P2P2_DN<9>")
	)
	(arc
		(start 93.69806 -284.52826)
		(mid 93.567146 -284.66462)
		(end 93.519498 -284.847538)
		(width 0.0889)
		(layer "In11.Cu")
		(net "UPI_CPU1_CPU0_P2P2_DN<9>")
	)
	(arc
		(start 350.488504 -278.65578)
		(mid 350.619418 -278.51942)
		(end 350.667066 -278.336502)
		(width 0.0889)
		(layer "In11.Cu")
		(net "UPI_CPU1_CPU0_P2P2_DN<9>")
	)
	(arc
		(start 350.01835 -281.097482)
		(mid 350.149264 -280.961122)
		(end 350.196912 -280.778204)
		(width 0.0889)
		(layer "In11.Cu")
		(net "UPI_CPU1_CPU0_P2P2_DN<9>")
	)
	(arc
		(start 93.76156 -281.952192)
		(mid 93.770132 -281.958714)
		(end 93.778578 -281.9654)
		(width 0.0889)
		(layer "In11.Cu")
		(net "UPI_CPU1_CPU0_P2P2_DN<9>")
	)
	(arc
		(start 346.729304 -288.422334)
		(mid 346.860218 -288.285974)
		(end 346.907866 -288.103056)
		(width 0.0889)
		(layer "In11.Cu")
		(net "UPI_CPU1_CPU0_P2P2_DN<9>")
	)
	(arc
		(start 92.75826 -287.783778)
		(mid 92.627346 -287.920138)
		(end 92.579698 -288.103056)
		(width 0.0889)
		(layer "In11.Cu")
		(net "UPI_CPU1_CPU0_P2P2_DN<9>")
	)
	(arc
		(start 346.437966 -288.898584)
		(mid 346.518128 -288.626395)
		(end 346.720414 -288.427414)
		(width 0.0889)
		(layer "In11.Cu")
		(net "UPI_CPU1_CPU0_P2P2_DN<9>")
	)
	(arc
		(start 350.667066 -278.314404)
		(mid 350.747977 -278.044276)
		(end 350.94926 -277.84679)
		(width 0.0889)
		(layer "In11.Cu")
		(net "UPI_CPU1_CPU0_P2P2_DN<9>")
	)
	(arc
		(start 350.473518 -279.63622)
		(mid 350.196944 -279.150318)
		(end 350.473518 -278.664416)
		(width 0.0889)
		(layer "In11.Cu")
		(net "UPI_CPU1_CPU0_P2P2_DN<9>")
	)
	(arc
		(start 350.95815 -277.84171)
		(mid 351.085404 -277.711744)
		(end 351.136458 -277.537164)
		(width 0.0889)
		(layer "In11.Cu")
		(net "UPI_CPU1_CPU0_P2P2_DN<9>")
	)
	(arc
		(start 349.548704 -281.911298)
		(mid 349.679618 -281.774938)
		(end 349.727266 -281.59202)
		(width 0.0889)
		(layer "In11.Cu")
		(net "UPI_CPU1_CPU0_P2P2_DN<9>")
	)
	(arc
		(start 349.727266 -281.576526)
		(mid 349.806636 -281.302792)
		(end 350.00946 -281.102562)
		(width 0.0889)
		(layer "In11.Cu")
		(net "UPI_CPU1_CPU0_P2P2_DN<9>")
	)
	(arc
		(start 94.167706 -283.714444)
		(mid 94.036792 -283.850804)
		(end 93.989144 -284.033722)
		(width 0.0889)
		(layer "In11.Cu")
		(net "UPI_CPU1_CPU0_P2P2_DN<9>")
	)
	(arc
		(start 350.196912 -280.770584)
		(mid 350.274541 -280.492171)
		(end 350.479614 -280.288492)
		(width 0.0889)
		(layer "In11.Cu")
		(net "UPI_CPU1_CPU0_P2P2_DN<9>")
	)
	(arc
		(start 92.579698 -288.121598)
		(mid 92.499536 -288.393787)
		(end 92.29725 -288.592768)
		(width 0.0889)
		(layer "In11.Cu")
		(net "UPI_CPU1_CPU0_P2P2_DN<9>")
	)
	(arc
		(start 348.787212 -283.205682)
		(mid 348.866353 -282.931059)
		(end 349.06966 -282.730194)
		(width 0.0889)
		(layer "In11.Cu")
		(net "UPI_CPU1_CPU0_P2P2_DN<9>")
	)
	(arc
		(start 347.660214 -286.151066)
		(mid 347.456733 -285.950262)
		(end 347.377512 -285.675578)
		(width 0.0889)
		(layer "In11.Cu")
		(net "UPI_CPU1_CPU0_P2P2_DN<9>")
	)
	(arc
		(start 347.660214 -286.799782)
		(mid 347.795147 -286.666428)
		(end 347.847412 -286.48406)
		(width 0.0889)
		(layer "In11.Cu")
		(net "UPI_CPU1_CPU0_P2P2_DN<9>")
	)
	(arc
		(start 349.257112 -282.405836)
		(mid 349.331103 -282.12627)
		(end 349.533718 -281.919934)
		(width 0.0889)
		(layer "In11.Cu")
		(net "UPI_CPU1_CPU0_P2P2_DN<9>")
	)
	(arc
		(start 93.227906 -285.342076)
		(mid 93.049309 -285.661354)
		(end 93.227906 -285.980632)
		(width 0.0889)
		(layer "In11.Cu")
		(net "UPI_CPU1_CPU0_P2P2_DN<9>")
	)
	(arc
		(start 94.459044 -283.229812)
		(mid 94.380933 -283.506761)
		(end 94.176596 -283.709364)
		(width 0.0889)
		(layer "In11.Cu")
		(net "UPI_CPU1_CPU0_P2P2_DN<9>")
	)
	(arc
		(start 349.256858 -282.420568)
		(mid 349.257055 -282.413203)
		(end 349.257112 -282.405836)
		(width 0.0889)
		(layer "In11.Cu")
		(net "UPI_CPU1_CPU0_P2P2_DN<9>")
	)
	(arc
		(start 347.847666 -284.832044)
		(mid 347.927036 -284.55831)
		(end 348.12986 -284.35808)
		(width 0.0889)
		(layer "In11.Cu")
		(net "UPI_CPU1_CPU0_P2P2_DN<9>")
	)
	(arc
		(start 346.723462 -289.446462)
		(mid 346.54933 -289.307615)
		(end 346.437966 -289.114738)
		(width 0.0889)
		(layer "In11.Cu")
		(net "UPI_CPU1_CPU0_P2P2_DN<9>")
	)
	(arc
		(start 347.669104 -285.166816)
		(mid 347.800018 -285.030456)
		(end 347.847666 -284.847538)
		(width 0.0889)
		(layer "In11.Cu")
		(net "UPI_CPU1_CPU0_P2P2_DN<9>")
	)
	(arc
		(start 351.347532 -277.081996)
		(mid 351.355978 -277.075311)
		(end 351.36455 -277.068788)
		(width 0.0889)
		(layer "In11.Cu")
		(net "UPI_CPU1_CPU0_P2P2_DN<9>")
	)
	(arc
		(start 93.778578 -281.9654)
		(mid 93.933976 -282.161681)
		(end 93.989398 -282.405836)
		(width 0.0889)
		(layer "In11.Cu")
		(net "UPI_CPU1_CPU0_P2P2_DN<9>")
	)
	(arc
		(start 346.907866 -288.087562)
		(mid 346.987236 -287.813828)
		(end 347.19006 -287.613598)
		(width 0.0889)
		(layer "In11.Cu")
		(net "UPI_CPU1_CPU0_P2P2_DN<9>")
	)
	(arc
		(start 93.236796 -286.964882)
		(mid 93.101863 -287.098236)
		(end 93.049598 -287.280604)
		(width 0.0889)
		(layer "In11.Cu")
		(net "UPI_CPU1_CPU0_P2P2_DN<9>")
	)
	(arc
		(start 348.317312 -284.023816)
		(mid 348.395423 -283.746867)
		(end 348.59976 -283.544264)
		(width 0.0889)
		(layer "In11.Cu")
		(net "UPI_CPU1_CPU0_P2P2_DN<9>")
	)
	(arc
		(start 92.293948 -289.277806)
		(mid 92.46808 -289.416653)
		(end 92.579444 -289.60953)
		(width 0.0889)
		(layer "In11.Cu")
		(net "UPI_CPU1_CPU0_P2P2_DN<9>")
	)
	(arc
		(start 93.049598 -287.299146)
		(mid 92.971487 -287.576095)
		(end 92.76715 -287.778698)
		(width 0.0889)
		(layer "In11.Cu")
		(net "UPI_CPU1_CPU0_P2P2_DN<9>")
	)
	(arc
		(start 346.907612 -289.645852)
		(mid 346.832607 -289.530393)
		(end 346.723462 -289.446462)
		(width 0.0889)
		(layer "In11.Cu")
		(net "UPI_CPU1_CPU0_P2P2_DN<9>")
	)
	(arc
		(start 351.136712 -277.522432)
		(mid 351.192067 -277.278245)
		(end 351.347532 -277.081996)
		(width 0.0889)
		(layer "In11.Cu")
		(net "UPI_CPU1_CPU0_P2P2_DN<9>")
	)
	(arc
		(start 93.519498 -286.475424)
		(mid 93.445507 -286.75499)
		(end 93.242892 -286.961326)
		(width 0.0889)
		(layer "In11.Cu")
		(net "UPI_CPU1_CPU0_P2P2_DN<9>")
	)
	(arc
		(start 349.07855 -282.725114)
		(mid 349.205804 -282.595148)
		(end 349.256858 -282.420568)
		(width 0.0889)
		(layer "In11.Cu")
		(net "UPI_CPU1_CPU0_P2P2_DN<9>")
	)
	(arc
		(start 347.377512 -285.661354)
		(mid 347.451503 -285.381788)
		(end 347.654118 -285.175452)
		(width 0.0889)
		(layer "In11.Cu")
		(net "UPI_CPU1_CPU0_P2P2_DN<9>")
	)
	(arc
		(start 350.479614 -280.288492)
		(mid 350.614547 -280.155138)
		(end 350.666812 -279.97277)
		(width 0.0889)
		(layer "In11.Cu")
		(net "UPI_CPU1_CPU0_P2P2_DN<9>")
	)
	(arc
		(start 92.109798 -289.078416)
		(mid 92.184803 -289.193875)
		(end 92.293948 -289.277806)
		(width 0.0889)
		(layer "In11.Cu")
		(net "UPI_CPU1_CPU0_P2P2_DN<9>")
	)
	(arc
		(start 93.989144 -284.049216)
		(mid 93.909774 -284.32295)
		(end 93.70695 -284.52318)
		(width 0.0889)
		(layer "In11.Cu")
		(net "UPI_CPU1_CPU0_P2P2_DN<9>")
	)
	(arc
		(start 350.666812 -279.955498)
		(mid 350.614542 -279.773133)
		(end 350.479614 -279.639776)
		(width 0.0889)
		(layer "In11.Cu")
		(net "UPI_CPU1_CPU0_P2P2_DN<9>")
	)
	(arc
		(start 351.136458 -277.537164)
		(mid 351.136655 -277.529799)
		(end 351.136712 -277.522432)
		(width 0.0889)
		(layer "In11.Cu")
		(net "UPI_CPU1_CPU0_P2P2_DN<9>")
	)
	(arc
		(start 93.519498 -284.847538)
		(mid 93.445507 -285.127104)
		(end 93.242892 -285.33344)
		(width 0.0889)
		(layer "In11.Cu")
		(net "UPI_CPU1_CPU0_P2P2_DN<9>")
	)
	(arc
		(start 347.377512 -287.28924)
		(mid 347.451503 -287.009674)
		(end 347.654118 -286.803338)
		(width 0.0889)
		(layer "In11.Cu")
		(net "UPI_CPU1_CPU0_P2P2_DN<9>")
	)
	(arc
		(start 348.13875 -284.353)
		(mid 348.269664 -284.21664)
		(end 348.317312 -284.033722)
		(width 0.0889)
		(layer "In11.Cu")
		(net "UPI_CPU1_CPU0_P2P2_DN<9>")
	)
	(arc
		(start 93.989398 -282.405836)
		(mid 93.98945 -282.413203)
		(end 93.989652 -282.420568)
		(width 0.0889)
		(layer "In11.Cu")
		(net "UPI_CPU1_CPU0_P2P2_DN<9>")
	)
	(arc
		(start 347.19895 -287.608518)
		(mid 347.329864 -287.472158)
		(end 347.377512 -287.28924)
		(width 0.0889)
		(layer "In11.Cu")
		(net "UPI_CPU1_CPU0_P2P2_DN<9>")
	)
	(segment
		(start 92.954094 -282.683966)
		(end 92.954094 -283.219906)
		(width 0.13208)
		(layer "F.Cu")
		(net "UPI_CPU1_CPU0_P2P2_DN<8>")
	)
	(segment
		(start 353.111562 -276.172676)
		(end 353.111562 -276.708362)
		(width 0.13208)
		(layer "F.Cu")
		(net "UPI_CPU1_CPU0_P2P2_DN<8>")
	)
	(segment
		(start 353.111562 -276.708362)
		(end 353.111816 -276.708616)
		(width 0.13208)
		(layer "F.Cu")
		(net "UPI_CPU1_CPU0_P2P2_DN<8>")
	)
	(segment
		(start 65.94729 -321.263772)
		(end 66.18605 -320.510662)
		(width 0.14732)
		(layer "In11.Cu")
		(net "UPI_CPU1_CPU0_P2P2_DN<8>")
	)
	(segment
		(start 90.979498 -289.077908)
		(end 90.979498 -288.895028)
		(width 0.0889)
		(layer "In11.Cu")
		(net "UPI_CPU1_CPU0_P2P2_DN<8>")
	)
	(segment
		(start 91.919044 -285.675578)
		(end 91.919044 -285.651448)
		(width 0.0889)
		(layer "In11.Cu")
		(net "UPI_CPU1_CPU0_P2P2_DN<8>")
	)
	(segment
		(start 349.635064 -283.709364)
		(end 349.63354 -283.710126)
		(width 0.0889)
		(layer "In11.Cu")
		(net "UPI_CPU1_CPU0_P2P2_DN<8>")
	)
	(segment
		(start 309.09133 -336.23631)
		(end 286.231076 -336.23631)
		(width 0.14732)
		(layer "In11.Cu")
		(net "UPI_CPU1_CPU0_P2P2_DN<8>")
	)
	(segment
		(start 351.327466 -280.769568)
		(end 351.327466 -280.778204)
		(width 0.0889)
		(layer "In11.Cu")
		(net "UPI_CPU1_CPU0_P2P2_DN<8>")
	)
	(segment
		(start 61.929264 -330.382626)
		(end 60.88888 -328.436986)
		(width 0.14732)
		(layer "In11.Cu")
		(net "UPI_CPU1_CPU0_P2P2_DN<8>")
	)
	(segment
		(start 63.419228 -324.566788)
		(end 63.961772 -323.257164)
		(width 0.14732)
		(layer "In11.Cu")
		(net "UPI_CPU1_CPU0_P2P2_DN<8>")
	)
	(segment
		(start 350.566228 -282.725114)
		(end 350.575118 -282.730194)
		(width 0.0889)
		(layer "In11.Cu")
		(net "UPI_CPU1_CPU0_P2P2_DN<8>")
	)
	(segment
		(start 272.796 -347.162628)
		(end 272.796 -367.27638)
		(width 0.14732)
		(layer "In11.Cu")
		(net "UPI_CPU1_CPU0_P2P2_DN<8>")
	)
	(segment
		(start 345.918536 -298.49318)
		(end 344.784172 -301.232062)
		(width 0.14732)
		(layer "In11.Cu")
		(net "UPI_CPU1_CPU0_P2P2_DN<8>")
	)
	(segment
		(start 281.948382 -338.010246)
		(end 272.796 -347.162628)
		(width 0.14732)
		(layer "In11.Cu")
		(net "UPI_CPU1_CPU0_P2P2_DN<8>")
	)
	(segment
		(start 91.919298 -287.28924)
		(end 91.919298 -287.279334)
		(width 0.0889)
		(layer "In11.Cu")
		(net "UPI_CPU1_CPU0_P2P2_DN<8>")
	)
	(segment
		(start 93.266768 -283.219906)
		(end 92.954094 -283.219906)
		(width 0.0889)
		(layer "In11.Cu")
		(net "UPI_CPU1_CPU0_P2P2_DN<8>")
	)
	(segment
		(start 341.829136 -304.187098)
		(end 340.572852 -304.70729)
		(width 0.14732)
		(layer "In11.Cu")
		(net "UPI_CPU1_CPU0_P2P2_DN<8>")
	)
	(segment
		(start 352.799142 -276.708616)
		(end 352.733356 -276.774402)
		(width 0.0889)
		(layer "In11.Cu")
		(net "UPI_CPU1_CPU0_P2P2_DN<8>")
	)
	(segment
		(start 63.102998 -335.064862)
		(end 61.929264 -330.382626)
		(width 0.14732)
		(layer "In11.Cu")
		(net "UPI_CPU1_CPU0_P2P2_DN<8>")
	)
	(segment
		(start 91.261692 -288.427414)
		(end 91.262708 -288.426906)
		(width 0.0889)
		(layer "In11.Cu")
		(net "UPI_CPU1_CPU0_P2P2_DN<8>")
	)
	(segment
		(start 90.44305 -292.443408)
		(end 90.44305 -290.344606)
		(width 0.14732)
		(layer "In11.Cu")
		(net "UPI_CPU1_CPU0_P2P2_DN<8>")
	)
	(segment
		(start 93.324172 -283.27731)
		(end 93.266768 -283.219906)
		(width 0.0889)
		(layer "In11.Cu")
		(net "UPI_CPU1_CPU0_P2P2_DN<8>")
	)
	(segment
		(start 350.58096 -283.705808)
		(end 350.574864 -283.709364)
		(width 0.0889)
		(layer "In11.Cu")
		(net "UPI_CPU1_CPU0_P2P2_DN<8>")
	)
	(segment
		(start 68.864226 -317.30061)
		(end 85.125052 -301.044356)
		(width 0.14732)
		(layer "In11.Cu")
		(net "UPI_CPU1_CPU0_P2P2_DN<8>")
	)
	(segment
		(start 348.686374 -285.980632)
		(end 348.695264 -285.985712)
		(width 0.0889)
		(layer "In11.Cu")
		(net "UPI_CPU1_CPU0_P2P2_DN<8>")
	)
	(segment
		(start 349.165418 -284.52318)
		(end 349.156528 -284.52826)
		(width 0.0889)
		(layer "In11.Cu")
		(net "UPI_CPU1_CPU0_P2P2_DN<8>")
	)
	(segment
		(start 90.48496 -289.703764)
		(end 90.484706 -289.705034)
		(width 0.0889)
		(layer "In11.Cu")
		(net "UPI_CPU1_CPU0_P2P2_DN<8>")
	)
	(segment
		(start 90.48496 -290.280598)
		(end 90.48496 -289.703764)
		(width 0.0889)
		(layer "In11.Cu")
		(net "UPI_CPU1_CPU0_P2P2_DN<8>")
	)
	(segment
		(start 95.820484 -381.626364)
		(end 73.414636 -372.345458)
		(width 0.14732)
		(layer "In11.Cu")
		(net "UPI_CPU1_CPU0_P2P2_DN<8>")
	)
	(segment
		(start 64.356488 -322.864226)
		(end 64.981074 -322.607432)
		(width 0.14732)
		(layer "In11.Cu")
		(net "UPI_CPU1_CPU0_P2P2_DN<8>")
	)
	(segment
		(start 351.975928 -278.65578)
		(end 351.984818 -278.66086)
		(width 0.0889)
		(layer "In11.Cu")
		(net "UPI_CPU1_CPU0_P2P2_DN<8>")
	)
	(segment
		(start 63.102998 -354.879402)
		(end 63.102998 -335.064862)
		(width 0.14732)
		(layer "In11.Cu")
		(net "UPI_CPU1_CPU0_P2P2_DN<8>")
	)
	(segment
		(start 352.46056 -277.194518)
		(end 352.454464 -277.198074)
		(width 0.0889)
		(layer "In11.Cu")
		(net "UPI_CPU1_CPU0_P2P2_DN<8>")
	)
	(segment
		(start 352.267012 -279.134824)
		(end 352.267012 -279.165812)
		(width 0.0889)
		(layer "In11.Cu")
		(net "UPI_CPU1_CPU0_P2P2_DN<8>")
	)
	(segment
		(start 91.719654 -287.62071)
		(end 91.731846 -287.613598)
		(width 0.0889)
		(layer "In11.Cu")
		(net "UPI_CPU1_CPU0_P2P2_DN<8>")
	)
	(segment
		(start 90.44305 -290.344606)
		(end 90.44305 -290.322508)
		(width 0.0889)
		(layer "In11.Cu")
		(net "UPI_CPU1_CPU0_P2P2_DN<8>")
	)
	(segment
		(start 68.161916 -367.092738)
		(end 63.102998 -354.879402)
		(width 0.14732)
		(layer "In11.Cu")
		(net "UPI_CPU1_CPU0_P2P2_DN<8>")
	)
	(segment
		(start 351.797366 -279.964134)
		(end 351.797366 -279.971754)
		(width 0.0889)
		(layer "In11.Cu")
		(net "UPI_CPU1_CPU0_P2P2_DN<8>")
	)
	(segment
		(start 92.202508 -286.799274)
		(end 92.210636 -286.794702)
		(width 0.0889)
		(layer "In11.Cu")
		(net "UPI_CPU1_CPU0_P2P2_DN<8>")
	)
	(segment
		(start 352.454464 -277.198074)
		(end 352.445574 -277.203154)
		(width 0.0889)
		(layer "In11.Cu")
		(net "UPI_CPU1_CPU0_P2P2_DN<8>")
	)
	(segment
		(start 349.63354 -283.710126)
		(end 349.626174 -283.714444)
		(width 0.0889)
		(layer "In11.Cu")
		(net "UPI_CPU1_CPU0_P2P2_DN<8>")
	)
	(segment
		(start 61.16447 -325.958454)
		(end 62.637924 -325.348092)
		(width 0.14732)
		(layer "In11.Cu")
		(net "UPI_CPU1_CPU0_P2P2_DN<8>")
	)
	(segment
		(start 87.44585 -295.440608)
		(end 90.44305 -292.443408)
		(width 0.14732)
		(layer "In11.Cu")
		(net "UPI_CPU1_CPU0_P2P2_DN<8>")
	)
	(segment
		(start 92.201492 -285.171896)
		(end 92.210382 -285.166816)
		(width 0.0889)
		(layer "In11.Cu")
		(net "UPI_CPU1_CPU0_P2P2_DN<8>")
	)
	(segment
		(start 92.210636 -286.156146)
		(end 92.201746 -286.151066)
		(width 0.0889)
		(layer "In11.Cu")
		(net "UPI_CPU1_CPU0_P2P2_DN<8>")
	)
	(segment
		(start 60.88888 -326.395588)
		(end 61.002926 -326.119998)
		(width 0.14732)
		(layer "In11.Cu")
		(net "UPI_CPU1_CPU0_P2P2_DN<8>")
	)
	(segment
		(start 62.637924 -325.348092)
		(end 63.419228 -324.566788)
		(width 0.14732)
		(layer "In11.Cu")
		(net "UPI_CPU1_CPU0_P2P2_DN<8>")
	)
	(segment
		(start 348.037912 -290.155884)
		(end 348.080076 -290.198048)
		(width 0.0889)
		(layer "In11.Cu")
		(net "UPI_CPU1_CPU0_P2P2_DN<8>")
	)
	(segment
		(start 73.414636 -372.345458)
		(end 68.161916 -367.092738)
		(width 0.14732)
		(layer "In11.Cu")
		(net "UPI_CPU1_CPU0_P2P2_DN<8>")
	)
	(segment
		(start 351.984818 -278.012144)
		(end 351.975928 -278.017224)
		(width 0.0889)
		(layer "In11.Cu")
		(net "UPI_CPU1_CPU0_P2P2_DN<8>")
	)
	(segment
		(start 350.857566 -283.201364)
		(end 350.857566 -283.219906)
		(width 0.0889)
		(layer "In11.Cu")
		(net "UPI_CPU1_CPU0_P2P2_DN<8>")
	)
	(segment
		(start 317.979806 -325.74611)
		(end 316.847474 -328.480166)
		(width 0.14732)
		(layer "In11.Cu")
		(net "UPI_CPU1_CPU0_P2P2_DN<8>")
	)
	(segment
		(start 91.731846 -287.613598)
		(end 91.740736 -287.608518)
		(width 0.0889)
		(layer "In11.Cu")
		(net "UPI_CPU1_CPU0_P2P2_DN<8>")
	)
	(segment
		(start 68.864226 -317.544196)
		(end 68.864226 -317.30061)
		(width 0.14732)
		(layer "In11.Cu")
		(net "UPI_CPU1_CPU0_P2P2_DN<8>")
	)
	(segment
		(start 339.549232 -305.131724)
		(end 337.919314 -305.806602)
		(width 0.14732)
		(layer "In11.Cu")
		(net "UPI_CPU1_CPU0_P2P2_DN<8>")
	)
	(segment
		(start 348.037912 -289.60953)
		(end 348.037912 -290.155884)
		(width 0.0889)
		(layer "In11.Cu")
		(net "UPI_CPU1_CPU0_P2P2_DN<8>")
	)
	(segment
		(start 351.05086 -281.264106)
		(end 351.044764 -281.267662)
		(width 0.0889)
		(layer "In11.Cu")
		(net "UPI_CPU1_CPU0_P2P2_DN<8>")
	)
	(segment
		(start 348.038166 -288.103056)
		(end 348.038166 -288.121598)
		(width 0.0889)
		(layer "In11.Cu")
		(net "UPI_CPU1_CPU0_P2P2_DN<8>")
	)
	(segment
		(start 262.476996 -377.595384)
		(end 161.491422 -386.16509)
		(width 0.14732)
		(layer "In11.Cu")
		(net "UPI_CPU1_CPU0_P2P2_DN<8>")
	)
	(segment
		(start 65.435734 -322.192904)
		(end 65.94729 -321.263772)
		(width 0.14732)
		(layer "In11.Cu")
		(net "UPI_CPU1_CPU0_P2P2_DN<8>")
	)
	(segment
		(start 63.961772 -323.257164)
		(end 64.356488 -322.864226)
		(width 0.14732)
		(layer "In11.Cu")
		(net "UPI_CPU1_CPU0_P2P2_DN<8>")
	)
	(segment
		(start 91.262708 -288.426906)
		(end 91.270582 -288.422334)
		(width 0.0889)
		(layer "In11.Cu")
		(net "UPI_CPU1_CPU0_P2P2_DN<8>")
	)
	(segment
		(start 348.080076 -290.198048)
		(end 348.080076 -290.220146)
		(width 0.0889)
		(layer "In11.Cu")
		(net "UPI_CPU1_CPU0_P2P2_DN<8>")
	)
	(segment
		(start 351.983802 -279.640284)
		(end 351.975928 -279.644856)
		(width 0.0889)
		(layer "In11.Cu")
		(net "UPI_CPU1_CPU0_P2P2_DN<8>")
	)
	(segment
		(start 348.977966 -286.467804)
		(end 348.977966 -286.475424)
		(width 0.0889)
		(layer "In11.Cu")
		(net "UPI_CPU1_CPU0_P2P2_DN<8>")
	)
	(segment
		(start 344.784172 -301.232062)
		(end 341.829136 -304.187098)
		(width 0.14732)
		(layer "In11.Cu")
		(net "UPI_CPU1_CPU0_P2P2_DN<8>")
	)
	(segment
		(start 85.125052 -301.044356)
		(end 87.44585 -295.440608)
		(width 0.14732)
		(layer "In11.Cu")
		(net "UPI_CPU1_CPU0_P2P2_DN<8>")
	)
	(segment
		(start 316.847474 -328.480166)
		(end 309.09133 -336.23631)
		(width 0.14732)
		(layer "In11.Cu")
		(net "UPI_CPU1_CPU0_P2P2_DN<8>")
	)
	(segment
		(start 348.70136 -285.33344)
		(end 348.695264 -285.336996)
		(width 0.0889)
		(layer "In11.Cu")
		(net "UPI_CPU1_CPU0_P2P2_DN<8>")
	)
	(segment
		(start 348.695264 -285.336996)
		(end 348.686374 -285.342076)
		(width 0.0889)
		(layer "In11.Cu")
		(net "UPI_CPU1_CPU0_P2P2_DN<8>")
	)
	(segment
		(start 64.981074 -322.607432)
		(end 64.98082 -322.607432)
		(width 0.14732)
		(layer "In11.Cu")
		(net "UPI_CPU1_CPU0_P2P2_DN<8>")
	)
	(segment
		(start 286.231076 -336.23631)
		(end 281.948382 -338.010246)
		(width 0.14732)
		(layer "In11.Cu")
		(net "UPI_CPU1_CPU0_P2P2_DN<8>")
	)
	(segment
		(start 126.416054 -386.16509)
		(end 95.820484 -381.626364)
		(width 0.14732)
		(layer "In11.Cu")
		(net "UPI_CPU1_CPU0_P2P2_DN<8>")
	)
	(segment
		(start 348.707456 -286.95777)
		(end 348.695264 -286.964882)
		(width 0.0889)
		(layer "In11.Cu")
		(net "UPI_CPU1_CPU0_P2P2_DN<8>")
	)
	(segment
		(start 347.568266 -288.917126)
		(end 347.568266 -289.078416)
		(width 0.0889)
		(layer "In11.Cu")
		(net "UPI_CPU1_CPU0_P2P2_DN<8>")
	)
	(segment
		(start 353.111816 -276.708616)
		(end 352.799142 -276.708616)
		(width 0.0889)
		(layer "In11.Cu")
		(net "UPI_CPU1_CPU0_P2P2_DN<8>")
	)
	(segment
		(start 161.491422 -386.16509)
		(end 126.416054 -386.16509)
		(width 0.14732)
		(layer "In11.Cu")
		(net "UPI_CPU1_CPU0_P2P2_DN<8>")
	)
	(segment
		(start 348.695264 -286.964882)
		(end 348.686374 -286.969962)
		(width 0.0889)
		(layer "In11.Cu")
		(net "UPI_CPU1_CPU0_P2P2_DN<8>")
	)
	(segment
		(start 348.225618 -287.778698)
		(end 348.216728 -287.783778)
		(width 0.0889)
		(layer "In11.Cu")
		(net "UPI_CPU1_CPU0_P2P2_DN<8>")
	)
	(segment
		(start 339.549486 -305.131216)
		(end 339.549232 -305.131724)
		(width 0.14732)
		(layer "In11.Cu")
		(net "UPI_CPU1_CPU0_P2P2_DN<8>")
	)
	(segment
		(start 348.080076 -290.220146)
		(end 348.080076 -290.50996)
		(width 0.14732)
		(layer "In11.Cu")
		(net "UPI_CPU1_CPU0_P2P2_DN<8>")
	)
	(segment
		(start 340.572852 -304.70729)
		(end 339.549486 -305.131216)
		(width 0.14732)
		(layer "In11.Cu")
		(net "UPI_CPU1_CPU0_P2P2_DN<8>")
	)
	(segment
		(start 350.575118 -282.081478)
		(end 350.566228 -282.086558)
		(width 0.0889)
		(layer "In11.Cu")
		(net "UPI_CPU1_CPU0_P2P2_DN<8>")
	)
	(segment
		(start 350.574864 -283.709364)
		(end 350.560132 -283.718)
		(width 0.0889)
		(layer "In11.Cu")
		(net "UPI_CPU1_CPU0_P2P2_DN<8>")
	)
	(segment
		(start 349.447612 -284.033722)
		(end 349.447612 -284.049216)
		(width 0.0889)
		(layer "In11.Cu")
		(net "UPI_CPU1_CPU0_P2P2_DN<8>")
	)
	(segment
		(start 346.777056 -294.176196)
		(end 345.918536 -298.49318)
		(width 0.14732)
		(layer "In11.Cu")
		(net "UPI_CPU1_CPU0_P2P2_DN<8>")
	)
	(segment
		(start 93.141292 -283.544264)
		(end 93.150182 -283.539184)
		(width 0.0889)
		(layer "In11.Cu")
		(net "UPI_CPU1_CPU0_P2P2_DN<8>")
	)
	(segment
		(start 60.88888 -328.436986)
		(end 60.88888 -326.395588)
		(width 0.14732)
		(layer "In11.Cu")
		(net "UPI_CPU1_CPU0_P2P2_DN<8>")
	)
	(segment
		(start 348.507812 -287.28924)
		(end 348.507812 -287.304734)
		(width 0.0889)
		(layer "In11.Cu")
		(net "UPI_CPU1_CPU0_P2P2_DN<8>")
	)
	(segment
		(start 272.796 -367.27638)
		(end 262.476996 -377.595384)
		(width 0.14732)
		(layer "In11.Cu")
		(net "UPI_CPU1_CPU0_P2P2_DN<8>")
	)
	(segment
		(start 64.98082 -322.607432)
		(end 65.047114 -322.580508)
		(width 0.14732)
		(layer "In11.Cu")
		(net "UPI_CPU1_CPU0_P2P2_DN<8>")
	)
	(segment
		(start 348.080076 -290.50996)
		(end 346.777056 -291.81298)
		(width 0.14732)
		(layer "In11.Cu")
		(net "UPI_CPU1_CPU0_P2P2_DN<8>")
	)
	(segment
		(start 66.18605 -320.510662)
		(end 66.540634 -319.867026)
		(width 0.14732)
		(layer "In11.Cu")
		(net "UPI_CPU1_CPU0_P2P2_DN<8>")
	)
	(segment
		(start 92.665296 -284.361636)
		(end 92.671392 -284.35808)
		(width 0.0889)
		(layer "In11.Cu")
		(net "UPI_CPU1_CPU0_P2P2_DN<8>")
	)
	(segment
		(start 346.777056 -291.81298)
		(end 346.777056 -294.176196)
		(width 0.14732)
		(layer "In11.Cu")
		(net "UPI_CPU1_CPU0_P2P2_DN<8>")
	)
	(segment
		(start 351.984818 -279.639776)
		(end 351.983802 -279.640284)
		(width 0.0889)
		(layer "In11.Cu")
		(net "UPI_CPU1_CPU0_P2P2_DN<8>")
	)
	(segment
		(start 352.267012 -277.522432)
		(end 352.267012 -277.54453)
		(width 0.0889)
		(layer "In11.Cu")
		(net "UPI_CPU1_CPU0_P2P2_DN<8>")
	)
	(segment
		(start 92.671392 -284.35808)
		(end 92.680282 -284.353)
		(width 0.0889)
		(layer "In11.Cu")
		(net "UPI_CPU1_CPU0_P2P2_DN<8>")
	)
	(segment
		(start 350.857566 -281.583384)
		(end 350.857566 -281.601926)
		(width 0.0889)
		(layer "In11.Cu")
		(net "UPI_CPU1_CPU0_P2P2_DN<8>")
	)
	(segment
		(start 92.201746 -286.799782)
		(end 92.202508 -286.799274)
		(width 0.0889)
		(layer "In11.Cu")
		(net "UPI_CPU1_CPU0_P2P2_DN<8>")
	)
	(segment
		(start 65.047114 -322.580508)
		(end 65.435734 -322.192904)
		(width 0.14732)
		(layer "In11.Cu")
		(net "UPI_CPU1_CPU0_P2P2_DN<8>")
	)
	(segment
		(start 66.540634 -319.867026)
		(end 68.864226 -317.544196)
		(width 0.14732)
		(layer "In11.Cu")
		(net "UPI_CPU1_CPU0_P2P2_DN<8>")
	)
	(segment
		(start 347.755718 -288.592768)
		(end 347.746828 -288.597848)
		(width 0.0889)
		(layer "In11.Cu")
		(net "UPI_CPU1_CPU0_P2P2_DN<8>")
	)
	(segment
		(start 337.919314 -305.806602)
		(end 317.979806 -325.74611)
		(width 0.14732)
		(layer "In11.Cu")
		(net "UPI_CPU1_CPU0_P2P2_DN<8>")
	)
	(segment
		(start 92.858844 -284.033722)
		(end 92.858844 -284.023816)
		(width 0.0889)
		(layer "In11.Cu")
		(net "UPI_CPU1_CPU0_P2P2_DN<8>")
	)
	(segment
		(start 61.002926 -326.119998)
		(end 61.16447 -325.958454)
		(width 0.14732)
		(layer "In11.Cu")
		(net "UPI_CPU1_CPU0_P2P2_DN<8>")
	)
	(segment
		(start 90.44305 -290.322508)
		(end 90.48496 -290.280598)
		(width 0.0889)
		(layer "In11.Cu")
		(net "UPI_CPU1_CPU0_P2P2_DN<8>")
	)
	(arc
		(start 92.858844 -284.023816)
		(mid 92.936955 -283.746867)
		(end 93.141292 -283.544264)
		(width 0.0889)
		(layer "In11.Cu")
		(net "UPI_CPU1_CPU0_P2P2_DN<8>")
	)
	(arc
		(start 350.00946 -283.709364)
		(mid 349.822262 -283.659221)
		(end 349.635064 -283.709364)
		(width 0.0889)
		(layer "In11.Cu")
		(net "UPI_CPU1_CPU0_P2P2_DN<8>")
	)
	(arc
		(start 348.695264 -285.985712)
		(mid 348.900336 -286.189391)
		(end 348.977966 -286.467804)
		(width 0.0889)
		(layer "In11.Cu")
		(net "UPI_CPU1_CPU0_P2P2_DN<8>")
	)
	(arc
		(start 351.975928 -279.644856)
		(mid 351.845014 -279.781216)
		(end 351.797366 -279.964134)
		(width 0.0889)
		(layer "In11.Cu")
		(net "UPI_CPU1_CPU0_P2P2_DN<8>")
	)
	(arc
		(start 92.210382 -285.166816)
		(mid 92.341296 -285.030456)
		(end 92.388944 -284.847538)
		(width 0.0889)
		(layer "In11.Cu")
		(net "UPI_CPU1_CPU0_P2P2_DN<8>")
	)
	(arc
		(start 349.447612 -284.049216)
		(mid 349.368242 -284.32295)
		(end 349.165418 -284.52318)
		(width 0.0889)
		(layer "In11.Cu")
		(net "UPI_CPU1_CPU0_P2P2_DN<8>")
	)
	(arc
		(start 91.919044 -285.651448)
		(mid 91.997155 -285.374499)
		(end 92.201492 -285.171896)
		(width 0.0889)
		(layer "In11.Cu")
		(net "UPI_CPU1_CPU0_P2P2_DN<8>")
	)
	(arc
		(start 348.038166 -288.121598)
		(mid 347.958004 -288.393787)
		(end 347.755718 -288.592768)
		(width 0.0889)
		(layer "In11.Cu")
		(net "UPI_CPU1_CPU0_P2P2_DN<8>")
	)
	(arc
		(start 90.795094 -289.277806)
		(mid 90.90449 -289.193709)
		(end 90.979498 -289.077908)
		(width 0.0889)
		(layer "In11.Cu")
		(net "UPI_CPU1_CPU0_P2P2_DN<8>")
	)
	(arc
		(start 351.797366 -278.336502)
		(mid 351.845045 -278.519402)
		(end 351.975928 -278.65578)
		(width 0.0889)
		(layer "In11.Cu")
		(net "UPI_CPU1_CPU0_P2P2_DN<8>")
	)
	(arc
		(start 352.267012 -279.165812)
		(mid 352.187642 -279.439546)
		(end 351.984818 -279.639776)
		(width 0.0889)
		(layer "In11.Cu")
		(net "UPI_CPU1_CPU0_P2P2_DN<8>")
	)
	(arc
		(start 349.626174 -283.714444)
		(mid 349.49526 -283.850804)
		(end 349.447612 -284.033722)
		(width 0.0889)
		(layer "In11.Cu")
		(net "UPI_CPU1_CPU0_P2P2_DN<8>")
	)
	(arc
		(start 351.514664 -280.453846)
		(mid 351.379731 -280.5872)
		(end 351.327466 -280.769568)
		(width 0.0889)
		(layer "In11.Cu")
		(net "UPI_CPU1_CPU0_P2P2_DN<8>")
	)
	(arc
		(start 348.686374 -286.969962)
		(mid 348.55546 -287.106322)
		(end 348.507812 -287.28924)
		(width 0.0889)
		(layer "In11.Cu")
		(net "UPI_CPU1_CPU0_P2P2_DN<8>")
	)
	(arc
		(start 91.740736 -287.608518)
		(mid 91.87165 -287.472158)
		(end 91.919298 -287.28924)
		(width 0.0889)
		(layer "In11.Cu")
		(net "UPI_CPU1_CPU0_P2P2_DN<8>")
	)
	(arc
		(start 347.568266 -289.078416)
		(mid 347.643271 -289.193875)
		(end 347.752416 -289.277806)
		(width 0.0889)
		(layer "In11.Cu")
		(net "UPI_CPU1_CPU0_P2P2_DN<8>")
	)
	(arc
		(start 92.389198 -286.482028)
		(mid 92.389281 -286.474027)
		(end 92.389198 -286.466026)
		(width 0.0889)
		(layer "In11.Cu")
		(net "UPI_CPU1_CPU0_P2P2_DN<8>")
	)
	(arc
		(start 351.327466 -280.778204)
		(mid 351.253475 -281.05777)
		(end 351.05086 -281.264106)
		(width 0.0889)
		(layer "In11.Cu")
		(net "UPI_CPU1_CPU0_P2P2_DN<8>")
	)
	(arc
		(start 91.270582 -288.422334)
		(mid 91.401496 -288.285974)
		(end 91.449144 -288.103056)
		(width 0.0889)
		(layer "In11.Cu")
		(net "UPI_CPU1_CPU0_P2P2_DN<8>")
	)
	(arc
		(start 91.919298 -287.279334)
		(mid 91.997409 -287.002385)
		(end 92.201746 -286.799782)
		(width 0.0889)
		(layer "In11.Cu")
		(net "UPI_CPU1_CPU0_P2P2_DN<8>")
	)
	(arc
		(start 348.507812 -287.304734)
		(mid 348.428442 -287.578468)
		(end 348.225618 -287.778698)
		(width 0.0889)
		(layer "In11.Cu")
		(net "UPI_CPU1_CPU0_P2P2_DN<8>")
	)
	(arc
		(start 352.267012 -277.54453)
		(mid 352.186101 -277.814658)
		(end 351.984818 -278.012144)
		(width 0.0889)
		(layer "In11.Cu")
		(net "UPI_CPU1_CPU0_P2P2_DN<8>")
	)
	(arc
		(start 348.977966 -286.475424)
		(mid 348.905731 -286.751948)
		(end 348.707456 -286.95777)
		(width 0.0889)
		(layer "In11.Cu")
		(net "UPI_CPU1_CPU0_P2P2_DN<8>")
	)
	(arc
		(start 348.216728 -287.783778)
		(mid 348.085814 -287.920138)
		(end 348.038166 -288.103056)
		(width 0.0889)
		(layer "In11.Cu")
		(net "UPI_CPU1_CPU0_P2P2_DN<8>")
	)
	(arc
		(start 352.733356 -276.774402)
		(mid 352.732055 -276.784829)
		(end 352.730562 -276.79523)
		(width 0.0889)
		(layer "In11.Cu")
		(net "UPI_CPU1_CPU0_P2P2_DN<8>")
	)
	(arc
		(start 93.150182 -283.539184)
		(mid 93.265921 -283.42736)
		(end 93.324172 -283.27731)
		(width 0.0889)
		(layer "In11.Cu")
		(net "UPI_CPU1_CPU0_P2P2_DN<8>")
	)
	(arc
		(start 347.752416 -289.277806)
		(mid 347.926548 -289.416653)
		(end 348.037912 -289.60953)
		(width 0.0889)
		(layer "In11.Cu")
		(net "UPI_CPU1_CPU0_P2P2_DN<8>")
	)
	(arc
		(start 348.977966 -284.847538)
		(mid 348.903975 -285.127104)
		(end 348.70136 -285.33344)
		(width 0.0889)
		(layer "In11.Cu")
		(net "UPI_CPU1_CPU0_P2P2_DN<8>")
	)
	(arc
		(start 350.566228 -282.086558)
		(mid 350.387631 -282.405836)
		(end 350.566228 -282.725114)
		(width 0.0889)
		(layer "In11.Cu")
		(net "UPI_CPU1_CPU0_P2P2_DN<8>")
	)
	(arc
		(start 91.449144 -288.103056)
		(mid 91.521379 -287.826532)
		(end 91.719654 -287.62071)
		(width 0.0889)
		(layer "In11.Cu")
		(net "UPI_CPU1_CPU0_P2P2_DN<8>")
	)
	(arc
		(start 350.857566 -281.601926)
		(mid 350.779455 -281.878875)
		(end 350.575118 -282.081478)
		(width 0.0889)
		(layer "In11.Cu")
		(net "UPI_CPU1_CPU0_P2P2_DN<8>")
	)
	(arc
		(start 92.680282 -284.353)
		(mid 92.811196 -284.21664)
		(end 92.858844 -284.033722)
		(width 0.0889)
		(layer "In11.Cu")
		(net "UPI_CPU1_CPU0_P2P2_DN<8>")
	)
	(arc
		(start 350.560132 -283.718)
		(mid 350.283657 -283.78532)
		(end 350.00946 -283.709364)
		(width 0.0889)
		(layer "In11.Cu")
		(net "UPI_CPU1_CPU0_P2P2_DN<8>")
	)
	(arc
		(start 352.445574 -277.203154)
		(mid 352.31466 -277.339514)
		(end 352.267012 -277.522432)
		(width 0.0889)
		(layer "In11.Cu")
		(net "UPI_CPU1_CPU0_P2P2_DN<8>")
	)
	(arc
		(start 350.575118 -282.730194)
		(mid 350.777404 -282.929175)
		(end 350.857566 -283.201364)
		(width 0.0889)
		(layer "In11.Cu")
		(net "UPI_CPU1_CPU0_P2P2_DN<8>")
	)
	(arc
		(start 92.210636 -286.794702)
		(mid 92.339925 -286.661216)
		(end 92.389198 -286.482028)
		(width 0.0889)
		(layer "In11.Cu")
		(net "UPI_CPU1_CPU0_P2P2_DN<8>")
	)
	(arc
		(start 92.389198 -286.466026)
		(mid 92.339302 -286.288379)
		(end 92.210636 -286.156146)
		(width 0.0889)
		(layer "In11.Cu")
		(net "UPI_CPU1_CPU0_P2P2_DN<8>")
	)
	(arc
		(start 349.156528 -284.52826)
		(mid 349.025614 -284.66462)
		(end 348.977966 -284.847538)
		(width 0.0889)
		(layer "In11.Cu")
		(net "UPI_CPU1_CPU0_P2P2_DN<8>")
	)
	(arc
		(start 350.857566 -283.219906)
		(mid 350.783575 -283.499472)
		(end 350.58096 -283.705808)
		(width 0.0889)
		(layer "In11.Cu")
		(net "UPI_CPU1_CPU0_P2P2_DN<8>")
	)
	(arc
		(start 347.746828 -288.597848)
		(mid 347.615914 -288.734208)
		(end 347.568266 -288.917126)
		(width 0.0889)
		(layer "In11.Cu")
		(net "UPI_CPU1_CPU0_P2P2_DN<8>")
	)
	(arc
		(start 92.201746 -286.151066)
		(mid 91.998265 -285.950262)
		(end 91.919044 -285.675578)
		(width 0.0889)
		(layer "In11.Cu")
		(net "UPI_CPU1_CPU0_P2P2_DN<8>")
	)
	(arc
		(start 351.984818 -278.66086)
		(mid 352.187641 -278.861091)
		(end 352.267012 -279.134824)
		(width 0.0889)
		(layer "In11.Cu")
		(net "UPI_CPU1_CPU0_P2P2_DN<8>")
	)
	(arc
		(start 351.79762 -278.32177)
		(mid 351.797423 -278.329135)
		(end 351.797366 -278.336502)
		(width 0.0889)
		(layer "In11.Cu")
		(net "UPI_CPU1_CPU0_P2P2_DN<8>")
	)
	(arc
		(start 351.975928 -278.017224)
		(mid 351.848674 -278.14719)
		(end 351.79762 -278.32177)
		(width 0.0889)
		(layer "In11.Cu")
		(net "UPI_CPU1_CPU0_P2P2_DN<8>")
	)
	(arc
		(start 352.730562 -276.79523)
		(mid 352.640298 -277.02514)
		(end 352.46056 -277.194518)
		(width 0.0889)
		(layer "In11.Cu")
		(net "UPI_CPU1_CPU0_P2P2_DN<8>")
	)
	(arc
		(start 92.388944 -284.847538)
		(mid 92.46286 -284.568036)
		(end 92.665296 -284.361636)
		(width 0.0889)
		(layer "In11.Cu")
		(net "UPI_CPU1_CPU0_P2P2_DN<8>")
	)
	(arc
		(start 90.48877 -289.684206)
		(mid 90.596607 -289.446851)
		(end 90.795094 -289.277806)
		(width 0.0889)
		(layer "In11.Cu")
		(net "UPI_CPU1_CPU0_P2P2_DN<8>")
	)
	(arc
		(start 351.044764 -281.267662)
		(mid 350.909831 -281.401016)
		(end 350.857566 -281.583384)
		(width 0.0889)
		(layer "In11.Cu")
		(net "UPI_CPU1_CPU0_P2P2_DN<8>")
	)
	(arc
		(start 90.979498 -288.895028)
		(mid 91.060409 -288.6249)
		(end 91.261692 -288.427414)
		(width 0.0889)
		(layer "In11.Cu")
		(net "UPI_CPU1_CPU0_P2P2_DN<8>")
	)
	(arc
		(start 90.484706 -289.705034)
		(mid 90.486645 -289.694602)
		(end 90.48877 -289.684206)
		(width 0.0889)
		(layer "In11.Cu")
		(net "UPI_CPU1_CPU0_P2P2_DN<8>")
	)
	(arc
		(start 351.797366 -279.971754)
		(mid 351.719737 -280.250167)
		(end 351.514664 -280.453846)
		(width 0.0889)
		(layer "In11.Cu")
		(net "UPI_CPU1_CPU0_P2P2_DN<8>")
	)
	(arc
		(start 348.686374 -285.342076)
		(mid 348.507898 -285.661354)
		(end 348.686374 -285.980632)
		(width 0.0889)
		(layer "In11.Cu")
		(net "UPI_CPU1_CPU0_P2P2_DN<8>")
	)
	(segment
		(start 92.484702 -280.77795)
		(end 92.484448 -280.778204)
		(width 0.13208)
		(layer "F.Cu")
		(net "UPI_CPU1_CPU0_P2P2_DN<7>")
	)
	(segment
		(start 350.292162 -276.708616)
		(end 350.292162 -276.172676)
		(width 0.13208)
		(layer "F.Cu")
		(net "UPI_CPU1_CPU0_P2P2_DN<7>")
	)
	(segment
		(start 92.484448 -280.242264)
		(end 92.484702 -280.242518)
		(width 0.13208)
		(layer "F.Cu")
		(net "UPI_CPU1_CPU0_P2P2_DN<7>")
	)
	(segment
		(start 92.484702 -280.242518)
		(end 92.484702 -280.77795)
		(width 0.13208)
		(layer "F.Cu")
		(net "UPI_CPU1_CPU0_P2P2_DN<7>")
	)
	(segment
		(start 317.323724 -328.78776)
		(end 318.433196 -326.10933)
		(width 0.14732)
		(layer "In11.Cu")
		(net "UPI_CPU1_CPU0_P2P2_DN<7>")
	)
	(segment
		(start 86.947248 -295.15562)
		(end 84.769452 -300.414182)
		(width 0.14732)
		(layer "In11.Cu")
		(net "UPI_CPU1_CPU0_P2P2_DN<7>")
	)
	(segment
		(start 73.099676 -372.81739)
		(end 95.668592 -382.165606)
		(width 0.14732)
		(layer "In11.Cu")
		(net "UPI_CPU1_CPU0_P2P2_DN<7>")
	)
	(segment
		(start 82.95005 -302.233584)
		(end 82.95005 -302.40605)
		(width 0.14732)
		(layer "In11.Cu")
		(net "UPI_CPU1_CPU0_P2P2_DN<7>")
	)
	(segment
		(start 345.901264 -300.389798)
		(end 346.073476 -299.988478)
		(width 0.14732)
		(layer "In11.Cu")
		(net "UPI_CPU1_CPU0_P2P2_DN<7>")
	)
	(segment
		(start 61.454538 -330.962)
		(end 62.549278 -335.3308)
		(width 0.14732)
		(layer "In11.Cu")
		(net "UPI_CPU1_CPU0_P2P2_DN<7>")
	)
	(segment
		(start 63.432944 -322.977256)
		(end 62.938914 -324.170294)
		(width 0.14732)
		(layer "In11.Cu")
		(net "UPI_CPU1_CPU0_P2P2_DN<7>")
	)
	(segment
		(start 345.741244 -300.453806)
		(end 345.901772 -300.389798)
		(width 0.14732)
		(layer "In11.Cu")
		(net "UPI_CPU1_CPU0_P2P2_DN<7>")
	)
	(segment
		(start 90.41765 -288.592768)
		(end 90.402664 -288.601404)
		(width 0.0889)
		(layer "In11.Cu")
		(net "UPI_CPU1_CPU0_P2P2_DN<7>")
	)
	(segment
		(start 262.682736 -378.172726)
		(end 273.34972 -367.505742)
		(width 0.14732)
		(layer "In11.Cu")
		(net "UPI_CPU1_CPU0_P2P2_DN<7>")
	)
	(segment
		(start 60.520072 -325.796656)
		(end 60.325 -326.267572)
		(width 0.14732)
		(layer "In11.Cu")
		(net "UPI_CPU1_CPU0_P2P2_DN<7>")
	)
	(segment
		(start 60.325 -326.267572)
		(end 60.325 -328.848466)
		(width 0.14732)
		(layer "In11.Cu")
		(net "UPI_CPU1_CPU0_P2P2_DN<7>")
	)
	(segment
		(start 352.347276 -281.92349)
		(end 352.358452 -281.91714)
		(width 0.0889)
		(layer "In11.Cu")
		(net "UPI_CPU1_CPU0_P2P2_DN<7>")
	)
	(segment
		(start 81.85023 -303.50587)
		(end 81.677764 -303.50587)
		(width 0.14732)
		(layer "In11.Cu")
		(net "UPI_CPU1_CPU0_P2P2_DN<7>")
	)
	(segment
		(start 352.358706 -276.38375)
		(end 352.346768 -276.376638)
		(width 0.0889)
		(layer "In11.Cu")
		(net "UPI_CPU1_CPU0_P2P2_DN<7>")
	)
	(segment
		(start 91.639644 -284.847538)
		(end 91.639644 -284.863032)
		(width 0.0889)
		(layer "In11.Cu")
		(net "UPI_CPU1_CPU0_P2P2_DN<7>")
	)
	(segment
		(start 345.901772 -300.389798)
		(end 345.901264 -300.389798)
		(width 0.14732)
		(layer "In11.Cu")
		(net "UPI_CPU1_CPU0_P2P2_DN<7>")
	)
	(segment
		(start 126.44247 -386.730748)
		(end 161.83737 -386.730748)
		(width 0.14732)
		(layer "In11.Cu")
		(net "UPI_CPU1_CPU0_P2P2_DN<7>")
	)
	(segment
		(start 318.454024 -326.058784)
		(end 338.23656 -306.276248)
		(width 0.14732)
		(layer "In11.Cu")
		(net "UPI_CPU1_CPU0_P2P2_DN<7>")
	)
	(segment
		(start 352.8314 -279.473406)
		(end 352.833178 -279.47239)
		(width 0.0889)
		(layer "In11.Cu")
		(net "UPI_CPU1_CPU0_P2P2_DN<7>")
	)
	(segment
		(start 91.34856 -285.980632)
		(end 91.356434 -285.985204)
		(width 0.0889)
		(layer "In11.Cu")
		(net "UPI_CPU1_CPU0_P2P2_DN<7>")
	)
	(segment
		(start 346.5957 -297.956732)
		(end 346.739972 -297.861736)
		(width 0.14732)
		(layer "In11.Cu")
		(net "UPI_CPU1_CPU0_P2P2_DN<7>")
	)
	(segment
		(start 349.528384 -286.80664)
		(end 349.537528 -286.801306)
		(width 0.0889)
		(layer "In11.Cu")
		(net "UPI_CPU1_CPU0_P2P2_DN<7>")
	)
	(segment
		(start 346.964762 -296.766742)
		(end 346.964508 -296.766742)
		(width 0.14732)
		(layer "In11.Cu")
		(net "UPI_CPU1_CPU0_P2P2_DN<7>")
	)
	(segment
		(start 65.918334 -319.694306)
		(end 65.159636 -321.525646)
		(width 0.14732)
		(layer "In11.Cu")
		(net "UPI_CPU1_CPU0_P2P2_DN<7>")
	)
	(segment
		(start 92.109544 -284.033722)
		(end 92.109544 -284.043628)
		(width 0.0889)
		(layer "In11.Cu")
		(net "UPI_CPU1_CPU0_P2P2_DN<7>")
	)
	(segment
		(start 347.411802 -292.325298)
		(end 347.411802 -291.9222)
		(width 0.0889)
		(layer "In11.Cu")
		(net "UPI_CPU1_CPU0_P2P2_DN<7>")
	)
	(segment
		(start 350.477328 -285.17342)
		(end 350.478852 -285.172658)
		(width 0.0889)
		(layer "In11.Cu")
		(net "UPI_CPU1_CPU0_P2P2_DN<7>")
	)
	(segment
		(start 64.004698 -322.405502)
		(end 63.432944 -322.977256)
		(width 0.14732)
		(layer "In11.Cu")
		(net "UPI_CPU1_CPU0_P2P2_DN<7>")
	)
	(segment
		(start 346.18168 -299.426376)
		(end 346.342208 -299.362368)
		(width 0.14732)
		(layer "In11.Cu")
		(net "UPI_CPU1_CPU0_P2P2_DN<7>")
	)
	(segment
		(start 353.29876 -276.38375)
		(end 353.290378 -276.37867)
		(width 0.0889)
		(layer "In11.Cu")
		(net "UPI_CPU1_CPU0_P2P2_DN<7>")
	)
	(segment
		(start 349.72752 -286.475424)
		(end 349.72752 -286.464756)
		(width 0.0889)
		(layer "In11.Cu")
		(net "UPI_CPU1_CPU0_P2P2_DN<7>")
	)
	(segment
		(start 90.699844 -288.103056)
		(end 90.699844 -288.125154)
		(width 0.0889)
		(layer "In11.Cu")
		(net "UPI_CPU1_CPU0_P2P2_DN<7>")
	)
	(segment
		(start 346.342208 -299.362368)
		(end 346.514166 -298.961048)
		(width 0.14732)
		(layer "In11.Cu")
		(net "UPI_CPU1_CPU0_P2P2_DN<7>")
	)
	(segment
		(start 345.569032 -300.855634)
		(end 345.741244 -300.453806)
		(width 0.14732)
		(layer "In11.Cu")
		(net "UPI_CPU1_CPU0_P2P2_DN<7>")
	)
	(segment
		(start 90.229944 -288.917126)
		(end 90.229944 -289.165538)
		(width 0.0889)
		(layer "In11.Cu")
		(net "UPI_CPU1_CPU0_P2P2_DN<7>")
	)
	(segment
		(start 346.739718 -297.861736)
		(end 346.739972 -297.861482)
		(width 0.14732)
		(layer "In11.Cu")
		(net "UPI_CPU1_CPU0_P2P2_DN<7>")
	)
	(segment
		(start 82.159602 -303.024032)
		(end 82.159602 -303.196498)
		(width 0.14732)
		(layer "In11.Cu")
		(net "UPI_CPU1_CPU0_P2P2_DN<7>")
	)
	(segment
		(start 82.159602 -303.196498)
		(end 81.85023 -303.50587)
		(width 0.14732)
		(layer "In11.Cu")
		(net "UPI_CPU1_CPU0_P2P2_DN<7>")
	)
	(segment
		(start 84.769452 -300.414182)
		(end 83.763612 -301.420022)
		(width 0.14732)
		(layer "In11.Cu")
		(net "UPI_CPU1_CPU0_P2P2_DN<7>")
	)
	(segment
		(start 346.95892 -296.18686)
		(end 347.046804 -295.758616)
		(width 0.14732)
		(layer "In11.Cu")
		(net "UPI_CPU1_CPU0_P2P2_DN<7>")
	)
	(segment
		(start 346.739972 -297.861736)
		(end 346.739718 -297.861736)
		(width 0.14732)
		(layer "In11.Cu")
		(net "UPI_CPU1_CPU0_P2P2_DN<7>")
	)
	(segment
		(start 346.514166 -298.961048)
		(end 346.602812 -298.528994)
		(width 0.14732)
		(layer "In11.Cu")
		(net "UPI_CPU1_CPU0_P2P2_DN<7>")
	)
	(segment
		(start 347.369892 -294.793162)
		(end 347.369892 -292.389306)
		(width 0.14732)
		(layer "In11.Cu")
		(net "UPI_CPU1_CPU0_P2P2_DN<7>")
	)
	(segment
		(start 93.519244 -281.582114)
		(end 93.519244 -281.607514)
		(width 0.0889)
		(layer "In11.Cu")
		(net "UPI_CPU1_CPU0_P2P2_DN<7>")
	)
	(segment
		(start 346.739972 -297.861482)
		(end 346.827602 -297.434)
		(width 0.14732)
		(layer "In11.Cu")
		(net "UPI_CPU1_CPU0_P2P2_DN<7>")
	)
	(segment
		(start 352.358452 -281.91714)
		(end 352.360992 -281.915616)
		(width 0.0889)
		(layer "In11.Cu")
		(net "UPI_CPU1_CPU0_P2P2_DN<7>")
	)
	(segment
		(start 351.136966 -284.041596)
		(end 351.136966 -284.033722)
		(width 0.0889)
		(layer "In11.Cu")
		(net "UPI_CPU1_CPU0_P2P2_DN<7>")
	)
	(segment
		(start 349.059754 -287.619948)
		(end 349.070422 -287.613598)
		(width 0.0889)
		(layer "In11.Cu")
		(net "UPI_CPU1_CPU0_P2P2_DN<7>")
	)
	(segment
		(start 346.07373 -299.988478)
		(end 346.009722 -299.828204)
		(width 0.14732)
		(layer "In11.Cu")
		(net "UPI_CPU1_CPU0_P2P2_DN<7>")
	)
	(segment
		(start 61.048392 -330.201778)
		(end 61.454538 -330.962)
		(width 0.14732)
		(layer "In11.Cu")
		(net "UPI_CPU1_CPU0_P2P2_DN<7>")
	)
	(segment
		(start 352.358198 -281.2669)
		(end 352.355404 -281.265122)
		(width 0.0889)
		(layer "In11.Cu")
		(net "UPI_CPU1_CPU0_P2P2_DN<7>")
	)
	(segment
		(start 348.589854 -288.434018)
		(end 348.600522 -288.427668)
		(width 0.0889)
		(layer "In11.Cu")
		(net "UPI_CPU1_CPU0_P2P2_DN<7>")
	)
	(segment
		(start 348.31782 -289.113976)
		(end 348.31782 -288.917126)
		(width 0.0889)
		(layer "In11.Cu")
		(net "UPI_CPU1_CPU0_P2P2_DN<7>")
	)
	(segment
		(start 92.484448 -280.778204)
		(end 92.640912 -281.049222)
		(width 0.0889)
		(layer "In11.Cu")
		(net "UPI_CPU1_CPU0_P2P2_DN<7>")
	)
	(segment
		(start 82.640932 -302.715168)
		(end 82.468466 -302.715168)
		(width 0.14732)
		(layer "In11.Cu")
		(net "UPI_CPU1_CPU0_P2P2_DN<7>")
	)
	(segment
		(start 352.815906 -279.482804)
		(end 352.816668 -279.482296)
		(width 0.0889)
		(layer "In11.Cu")
		(net "UPI_CPU1_CPU0_P2P2_DN<7>")
	)
	(segment
		(start 352.82886 -279.47493)
		(end 352.8314 -279.473406)
		(width 0.0889)
		(layer "In11.Cu")
		(net "UPI_CPU1_CPU0_P2P2_DN<7>")
	)
	(segment
		(start 90.89263 -287.77565)
		(end 90.891614 -287.776158)
		(width 0.0889)
		(layer "In11.Cu")
		(net "UPI_CPU1_CPU0_P2P2_DN<7>")
	)
	(segment
		(start 353.016566 -277.537418)
		(end 353.016566 -277.522432)
		(width 0.0889)
		(layer "In11.Cu")
		(net "UPI_CPU1_CPU0_P2P2_DN<7>")
	)
	(segment
		(start 318.432942 -326.10933)
		(end 318.454024 -326.058784)
		(width 0.14732)
		(layer "In11.Cu")
		(net "UPI_CPU1_CPU0_P2P2_DN<7>")
	)
	(segment
		(start 350.557846 -276.421596)
		(end 350.557592 -276.422104)
		(width 0.0889)
		(layer "In11.Cu")
		(net "UPI_CPU1_CPU0_P2P2_DN<7>")
	)
	(segment
		(start 348.787466 -290.54806)
		(end 348.787466 -289.64509)
		(width 0.0889)
		(layer "In11.Cu")
		(net "UPI_CPU1_CPU0_P2P2_DN<7>")
	)
	(segment
		(start 350.197166 -285.67634)
		(end 350.197166 -285.661354)
		(width 0.0889)
		(layer "In11.Cu")
		(net "UPI_CPU1_CPU0_P2P2_DN<7>")
	)
	(segment
		(start 346.602812 -298.528994)
		(end 346.507816 -298.384976)
		(width 0.14732)
		(layer "In11.Cu")
		(net "UPI_CPU1_CPU0_P2P2_DN<7>")
	)
	(segment
		(start 62.549278 -354.99421)
		(end 67.691 -367.408714)
		(width 0.14732)
		(layer "In11.Cu")
		(net "UPI_CPU1_CPU0_P2P2_DN<7>")
	)
	(segment
		(start 68.009516 -317.174118)
		(end 68.009516 -317.603124)
		(width 0.14732)
		(layer "In11.Cu")
		(net "UPI_CPU1_CPU0_P2P2_DN<7>")
	)
	(segment
		(start 348.78772 -288.118042)
		(end 348.78772 -288.103056)
		(width 0.0889)
		(layer "In11.Cu")
		(net "UPI_CPU1_CPU0_P2P2_DN<7>")
	)
	(segment
		(start 93.049598 -282.405836)
		(end 93.049598 -282.42006)
		(width 0.0889)
		(layer "In11.Cu")
		(net "UPI_CPU1_CPU0_P2P2_DN<7>")
	)
	(segment
		(start 350.448626 -276.437598)
		(end 350.292162 -276.708616)
		(width 0.0889)
		(layer "In11.Cu")
		(net "UPI_CPU1_CPU0_P2P2_DN<7>")
	)
	(segment
		(start 353.296728 -277.034498)
		(end 353.298252 -277.033736)
		(width 0.0889)
		(layer "In11.Cu")
		(net "UPI_CPU1_CPU0_P2P2_DN<7>")
	)
	(segment
		(start 91.356434 -285.985204)
		(end 91.35745 -285.985712)
		(width 0.0889)
		(layer "In11.Cu")
		(net "UPI_CPU1_CPU0_P2P2_DN<7>")
	)
	(segment
		(start 352.840798 -278.832564)
		(end 352.839528 -278.831802)
		(width 0.0889)
		(layer "In11.Cu")
		(net "UPI_CPU1_CPU0_P2P2_DN<7>")
	)
	(segment
		(start 318.433196 -326.10933)
		(end 318.432942 -326.10933)
		(width 0.14732)
		(layer "In11.Cu")
		(net "UPI_CPU1_CPU0_P2P2_DN<7>")
	)
	(segment
		(start 352.833178 -279.47239)
		(end 352.834194 -279.471882)
		(width 0.0889)
		(layer "In11.Cu")
		(net "UPI_CPU1_CPU0_P2P2_DN<7>")
	)
	(segment
		(start 353.299268 -276.384004)
		(end 353.29876 -276.38375)
		(width 0.0889)
		(layer "In11.Cu")
		(net "UPI_CPU1_CPU0_P2P2_DN<7>")
	)
	(segment
		(start 89.886536 -292.216332)
		(end 86.947248 -295.15562)
		(width 0.14732)
		(layer "In11.Cu")
		(net "UPI_CPU1_CPU0_P2P2_DN<7>")
	)
	(segment
		(start 282.196032 -338.545678)
		(end 286.434784 -336.79003)
		(width 0.14732)
		(layer "In11.Cu")
		(net "UPI_CPU1_CPU0_P2P2_DN<7>")
	)
	(segment
		(start 60.835032 -325.481696)
		(end 60.520072 -325.796656)
		(width 0.14732)
		(layer "In11.Cu")
		(net "UPI_CPU1_CPU0_P2P2_DN<7>")
	)
	(segment
		(start 60.892436 -329.651106)
		(end 61.09843 -330.036678)
		(width 0.14732)
		(layer "In11.Cu")
		(net "UPI_CPU1_CPU0_P2P2_DN<7>")
	)
	(segment
		(start 82.468466 -302.715168)
		(end 82.159602 -303.024032)
		(width 0.14732)
		(layer "In11.Cu")
		(net "UPI_CPU1_CPU0_P2P2_DN<7>")
	)
	(segment
		(start 350.478852 -285.172658)
		(end 350.484948 -285.169102)
		(width 0.0889)
		(layer "In11.Cu")
		(net "UPI_CPU1_CPU0_P2P2_DN<7>")
	)
	(segment
		(start 89.844626 -291.879528)
		(end 89.886536 -291.921438)
		(width 0.0889)
		(layer "In11.Cu")
		(net "UPI_CPU1_CPU0_P2P2_DN<7>")
	)
	(segment
		(start 64.474852 -322.210684)
		(end 64.004698 -322.405502)
		(width 0.14732)
		(layer "In11.Cu")
		(net "UPI_CPU1_CPU0_P2P2_DN<7>")
	)
	(segment
		(start 273.34972 -367.505742)
		(end 273.34972 -347.39199)
		(width 0.14732)
		(layer "In11.Cu")
		(net "UPI_CPU1_CPU0_P2P2_DN<7>")
	)
	(segment
		(start 349.539052 -286.800544)
		(end 349.545148 -286.796988)
		(width 0.0889)
		(layer "In11.Cu")
		(net "UPI_CPU1_CPU0_P2P2_DN<7>")
	)
	(segment
		(start 91.363546 -286.961326)
		(end 91.35745 -286.964882)
		(width 0.0889)
		(layer "In11.Cu")
		(net "UPI_CPU1_CPU0_P2P2_DN<7>")
	)
	(segment
		(start 346.820744 -296.861738)
		(end 346.964762 -296.766742)
		(width 0.14732)
		(layer "In11.Cu")
		(net "UPI_CPU1_CPU0_P2P2_DN<7>")
	)
	(segment
		(start 338.23656 -306.276248)
		(end 342.156288 -304.652426)
		(width 0.14732)
		(layer "In11.Cu")
		(net "UPI_CPU1_CPU0_P2P2_DN<7>")
	)
	(segment
		(start 352.359214 -281.267408)
		(end 352.358198 -281.2669)
		(width 0.0889)
		(layer "In11.Cu")
		(net "UPI_CPU1_CPU0_P2P2_DN<7>")
	)
	(segment
		(start 82.95005 -302.40605)
		(end 82.640932 -302.715168)
		(width 0.14732)
		(layer "In11.Cu")
		(net "UPI_CPU1_CPU0_P2P2_DN<7>")
	)
	(segment
		(start 92.579444 -283.219906)
		(end 92.579444 -283.229812)
		(width 0.0889)
		(layer "In11.Cu")
		(net "UPI_CPU1_CPU0_P2P2_DN<7>")
	)
	(segment
		(start 352.839528 -278.831802)
		(end 352.827844 -278.825198)
		(width 0.0889)
		(layer "In11.Cu")
		(net "UPI_CPU1_CPU0_P2P2_DN<7>")
	)
	(segment
		(start 60.727082 -329.601068)
		(end 60.892436 -329.651106)
		(width 0.14732)
		(layer "In11.Cu")
		(net "UPI_CPU1_CPU0_P2P2_DN<7>")
	)
	(segment
		(start 352.355404 -281.265122)
		(end 352.3488 -281.261312)
		(width 0.0889)
		(layer "In11.Cu")
		(net "UPI_CPU1_CPU0_P2P2_DN<7>")
	)
	(segment
		(start 346.73286 -297.289982)
		(end 346.820744 -296.861738)
		(width 0.14732)
		(layer "In11.Cu")
		(net "UPI_CPU1_CPU0_P2P2_DN<7>")
	)
	(segment
		(start 350.66732 -284.847538)
		(end 350.66732 -284.83687)
		(width 0.0889)
		(layer "In11.Cu")
		(net "UPI_CPU1_CPU0_P2P2_DN<7>")
	)
	(segment
		(start 83.763612 -301.420022)
		(end 83.763612 -301.592488)
		(width 0.14732)
		(layer "In11.Cu")
		(net "UPI_CPU1_CPU0_P2P2_DN<7>")
	)
	(segment
		(start 90.229944 -289.165538)
		(end 89.844626 -289.550856)
		(width 0.0889)
		(layer "In11.Cu")
		(net "UPI_CPU1_CPU0_P2P2_DN<7>")
	)
	(segment
		(start 351.606866 -283.22778)
		(end 351.606866 -283.20492)
		(width 0.0889)
		(layer "In11.Cu")
		(net "UPI_CPU1_CPU0_P2P2_DN<7>")
	)
	(segment
		(start 351.418906 -276.38375)
		(end 351.406968 -276.376638)
		(width 0.0889)
		(layer "In11.Cu")
		(net "UPI_CPU1_CPU0_P2P2_DN<7>")
	)
	(segment
		(start 61.09843 -330.036678)
		(end 61.048392 -330.201778)
		(width 0.14732)
		(layer "In11.Cu")
		(net "UPI_CPU1_CPU0_P2P2_DN<7>")
	)
	(segment
		(start 65.159636 -321.525646)
		(end 64.474852 -322.210684)
		(width 0.14732)
		(layer "In11.Cu")
		(net "UPI_CPU1_CPU0_P2P2_DN<7>")
	)
	(segment
		(start 352.54692 -279.975564)
		(end 352.54692 -279.964134)
		(width 0.0889)
		(layer "In11.Cu")
		(net "UPI_CPU1_CPU0_P2P2_DN<7>")
	)
	(segment
		(start 347.053916 -296.330878)
		(end 346.95892 -296.18686)
		(width 0.14732)
		(layer "In11.Cu")
		(net "UPI_CPU1_CPU0_P2P2_DN<7>")
	)
	(segment
		(start 95.668592 -382.165606)
		(end 126.44247 -386.730748)
		(width 0.14732)
		(layer "In11.Cu")
		(net "UPI_CPU1_CPU0_P2P2_DN<7>")
	)
	(segment
		(start 351.13722 -282.416504)
		(end 351.13722 -282.395168)
		(width 0.0889)
		(layer "In11.Cu")
		(net "UPI_CPU1_CPU0_P2P2_DN<7>")
	)
	(segment
		(start 352.363786 -281.270202)
		(end 352.359214 -281.267408)
		(width 0.0889)
		(layer "In11.Cu")
		(net "UPI_CPU1_CPU0_P2P2_DN<7>")
	)
	(segment
		(start 352.360992 -281.915616)
		(end 352.364548 -281.913584)
		(width 0.0889)
		(layer "In11.Cu")
		(net "UPI_CPU1_CPU0_P2P2_DN<7>")
	)
	(segment
		(start 346.964508 -296.766742)
		(end 347.053916 -296.330878)
		(width 0.14732)
		(layer "In11.Cu")
		(net "UPI_CPU1_CPU0_P2P2_DN<7>")
	)
	(segment
		(start 89.886536 -291.943536)
		(end 89.886536 -292.216332)
		(width 0.14732)
		(layer "In11.Cu")
		(net "UPI_CPU1_CPU0_P2P2_DN<7>")
	)
	(segment
		(start 161.83737 -386.730748)
		(end 262.682736 -378.172726)
		(width 0.14732)
		(layer "In11.Cu")
		(net "UPI_CPU1_CPU0_P2P2_DN<7>")
	)
	(segment
		(start 352.54692 -278.34717)
		(end 352.54692 -278.325834)
		(width 0.0889)
		(layer "In11.Cu")
		(net "UPI_CPU1_CPU0_P2P2_DN<7>")
	)
	(segment
		(start 347.369638 -294.793416)
		(end 347.369892 -294.793162)
		(width 0.14732)
		(layer "In11.Cu")
		(net "UPI_CPU1_CPU0_P2P2_DN<7>")
	)
	(segment
		(start 92.296996 -283.709364)
		(end 92.288106 -283.714444)
		(width 0.0889)
		(layer "In11.Cu")
		(net "UPI_CPU1_CPU0_P2P2_DN<7>")
	)
	(segment
		(start 349.537528 -286.801306)
		(end 349.539052 -286.800544)
		(width 0.0889)
		(layer "In11.Cu")
		(net "UPI_CPU1_CPU0_P2P2_DN<7>")
	)
	(segment
		(start 353.287584 -277.039832)
		(end 353.296728 -277.034498)
		(width 0.0889)
		(layer "In11.Cu")
		(net "UPI_CPU1_CPU0_P2P2_DN<7>")
	)
	(segment
		(start 347.369892 -292.389306)
		(end 347.369892 -292.367208)
		(width 0.0889)
		(layer "In11.Cu")
		(net "UPI_CPU1_CPU0_P2P2_DN<7>")
	)
	(segment
		(start 67.691 -367.408714)
		(end 73.099676 -372.81739)
		(width 0.14732)
		(layer "In11.Cu")
		(net "UPI_CPU1_CPU0_P2P2_DN<7>")
	)
	(segment
		(start 346.507816 -298.384976)
		(end 346.5957 -297.956732)
		(width 0.14732)
		(layer "In11.Cu")
		(net "UPI_CPU1_CPU0_P2P2_DN<7>")
	)
	(segment
		(start 91.827096 -284.52318)
		(end 91.818206 -284.52826)
		(width 0.0889)
		(layer "In11.Cu")
		(net "UPI_CPU1_CPU0_P2P2_DN<7>")
	)
	(segment
		(start 90.887296 -287.778698)
		(end 90.880438 -287.782508)
		(width 0.0889)
		(layer "In11.Cu")
		(net "UPI_CPU1_CPU0_P2P2_DN<7>")
	)
	(segment
		(start 347.411802 -291.9222)
		(end 348.787466 -290.54806)
		(width 0.0889)
		(layer "In11.Cu")
		(net "UPI_CPU1_CPU0_P2P2_DN<7>")
	)
	(segment
		(start 62.938914 -324.170294)
		(end 62.187836 -324.921372)
		(width 0.14732)
		(layer "In11.Cu")
		(net "UPI_CPU1_CPU0_P2P2_DN<7>")
	)
	(segment
		(start 90.890852 -287.776666)
		(end 90.888058 -287.77819)
		(width 0.0889)
		(layer "In11.Cu")
		(net "UPI_CPU1_CPU0_P2P2_DN<7>")
	)
	(segment
		(start 93.23705 -282.081478)
		(end 93.22816 -282.086558)
		(width 0.0889)
		(layer "In11.Cu")
		(net "UPI_CPU1_CPU0_P2P2_DN<7>")
	)
	(segment
		(start 89.886536 -291.921438)
		(end 89.886536 -291.943536)
		(width 0.0889)
		(layer "In11.Cu")
		(net "UPI_CPU1_CPU0_P2P2_DN<7>")
	)
	(segment
		(start 346.827602 -297.434)
		(end 346.73286 -297.289982)
		(width 0.14732)
		(layer "In11.Cu")
		(net "UPI_CPU1_CPU0_P2P2_DN<7>")
	)
	(segment
		(start 346.073476 -299.988478)
		(end 346.07373 -299.988478)
		(width 0.14732)
		(layer "In11.Cu")
		(net "UPI_CPU1_CPU0_P2P2_DN<7>")
	)
	(segment
		(start 353.298252 -277.033736)
		(end 353.304348 -277.03018)
		(width 0.0889)
		(layer "In11.Cu")
		(net "UPI_CPU1_CPU0_P2P2_DN<7>")
	)
	(segment
		(start 90.888058 -287.77819)
		(end 90.887296 -287.778698)
		(width 0.0889)
		(layer "In11.Cu")
		(net "UPI_CPU1_CPU0_P2P2_DN<7>")
	)
	(segment
		(start 347.191076 -295.663874)
		(end 347.369638 -294.793416)
		(width 0.14732)
		(layer "In11.Cu")
		(net "UPI_CPU1_CPU0_P2P2_DN<7>")
	)
	(segment
		(start 89.844626 -289.550856)
		(end 89.844626 -291.879528)
		(width 0.0889)
		(layer "In11.Cu")
		(net "UPI_CPU1_CPU0_P2P2_DN<7>")
	)
	(segment
		(start 91.639898 -286.4612)
		(end 91.639898 -286.475424)
		(width 0.0889)
		(layer "In11.Cu")
		(net "UPI_CPU1_CPU0_P2P2_DN<7>")
	)
	(segment
		(start 350.468184 -285.178754)
		(end 350.477328 -285.17342)
		(width 0.0889)
		(layer "In11.Cu")
		(net "UPI_CPU1_CPU0_P2P2_DN<7>")
	)
	(segment
		(start 345.63304 -301.015654)
		(end 345.569032 -300.855634)
		(width 0.14732)
		(layer "In11.Cu")
		(net "UPI_CPU1_CPU0_P2P2_DN<7>")
	)
	(segment
		(start 62.187836 -324.921372)
		(end 60.835032 -325.481696)
		(width 0.14732)
		(layer "In11.Cu")
		(net "UPI_CPU1_CPU0_P2P2_DN<7>")
	)
	(segment
		(start 81.677764 -303.50587)
		(end 68.009516 -317.174118)
		(width 0.14732)
		(layer "In11.Cu")
		(net "UPI_CPU1_CPU0_P2P2_DN<7>")
	)
	(segment
		(start 347.369892 -292.367208)
		(end 347.411802 -292.325298)
		(width 0.0889)
		(layer "In11.Cu")
		(net "UPI_CPU1_CPU0_P2P2_DN<7>")
	)
	(segment
		(start 90.880438 -287.782508)
		(end 90.878406 -287.783778)
		(width 0.0889)
		(layer "In11.Cu")
		(net "UPI_CPU1_CPU0_P2P2_DN<7>")
	)
	(segment
		(start 351.409 -283.550614)
		(end 351.419668 -283.544264)
		(width 0.0889)
		(layer "In11.Cu")
		(net "UPI_CPU1_CPU0_P2P2_DN<7>")
	)
	(segment
		(start 91.35745 -285.336996)
		(end 91.34856 -285.342076)
		(width 0.0889)
		(layer "In11.Cu")
		(net "UPI_CPU1_CPU0_P2P2_DN<7>")
	)
	(segment
		(start 352.3488 -280.295096)
		(end 352.359468 -280.288746)
		(width 0.0889)
		(layer "In11.Cu")
		(net "UPI_CPU1_CPU0_P2P2_DN<7>")
	)
	(segment
		(start 353.48672 -276.708616)
		(end 353.48672 -276.700742)
		(width 0.0889)
		(layer "In11.Cu")
		(net "UPI_CPU1_CPU0_P2P2_DN<7>")
	)
	(segment
		(start 309.321454 -336.79003)
		(end 317.323724 -328.78776)
		(width 0.14732)
		(layer "In11.Cu")
		(net "UPI_CPU1_CPU0_P2P2_DN<7>")
	)
	(segment
		(start 273.34972 -347.39199)
		(end 282.196032 -338.545678)
		(width 0.14732)
		(layer "In11.Cu")
		(net "UPI_CPU1_CPU0_P2P2_DN<7>")
	)
	(segment
		(start 342.156288 -304.652426)
		(end 345.513152 -301.295562)
		(width 0.14732)
		(layer "In11.Cu")
		(net "UPI_CPU1_CPU0_P2P2_DN<7>")
	)
	(segment
		(start 68.009516 -317.603124)
		(end 65.918334 -319.694306)
		(width 0.14732)
		(layer "In11.Cu")
		(net "UPI_CPU1_CPU0_P2P2_DN<7>")
	)
	(segment
		(start 83.763612 -301.592488)
		(end 83.45424 -301.90186)
		(width 0.14732)
		(layer "In11.Cu")
		(net "UPI_CPU1_CPU0_P2P2_DN<7>")
	)
	(segment
		(start 352.816668 -279.482296)
		(end 352.82886 -279.47493)
		(width 0.0889)
		(layer "In11.Cu")
		(net "UPI_CPU1_CPU0_P2P2_DN<7>")
	)
	(segment
		(start 90.893392 -287.775142)
		(end 90.89263 -287.77565)
		(width 0.0889)
		(layer "In11.Cu")
		(net "UPI_CPU1_CPU0_P2P2_DN<7>")
	)
	(segment
		(start 347.046804 -295.758616)
		(end 347.191076 -295.663874)
		(width 0.14732)
		(layer "In11.Cu")
		(net "UPI_CPU1_CPU0_P2P2_DN<7>")
	)
	(segment
		(start 90.891614 -287.776158)
		(end 90.890852 -287.776666)
		(width 0.0889)
		(layer "In11.Cu")
		(net "UPI_CPU1_CPU0_P2P2_DN<7>")
	)
	(segment
		(start 286.434784 -336.79003)
		(end 309.321454 -336.79003)
		(width 0.14732)
		(layer "In11.Cu")
		(net "UPI_CPU1_CPU0_P2P2_DN<7>")
	)
	(segment
		(start 349.257366 -287.301686)
		(end 349.257366 -287.28924)
		(width 0.0889)
		(layer "In11.Cu")
		(net "UPI_CPU1_CPU0_P2P2_DN<7>")
	)
	(segment
		(start 92.640912 -281.049222)
		(end 92.729812 -281.073098)
		(width 0.0889)
		(layer "In11.Cu")
		(net "UPI_CPU1_CPU0_P2P2_DN<7>")
	)
	(segment
		(start 60.325 -328.848466)
		(end 60.727082 -329.601068)
		(width 0.14732)
		(layer "In11.Cu")
		(net "UPI_CPU1_CPU0_P2P2_DN<7>")
	)
	(segment
		(start 83.45424 -301.90186)
		(end 83.281774 -301.90186)
		(width 0.14732)
		(layer "In11.Cu")
		(net "UPI_CPU1_CPU0_P2P2_DN<7>")
	)
	(segment
		(start 92.766896 -282.895548)
		(end 92.758006 -282.900628)
		(width 0.0889)
		(layer "In11.Cu")
		(net "UPI_CPU1_CPU0_P2P2_DN<7>")
	)
	(segment
		(start 62.549278 -335.3308)
		(end 62.549278 -354.99421)
		(width 0.14732)
		(layer "In11.Cu")
		(net "UPI_CPU1_CPU0_P2P2_DN<7>")
	)
	(segment
		(start 350.537526 -276.413976)
		(end 350.448626 -276.437598)
		(width 0.0889)
		(layer "In11.Cu")
		(net "UPI_CPU1_CPU0_P2P2_DN<7>")
	)
	(segment
		(start 83.281774 -301.90186)
		(end 82.95005 -302.233584)
		(width 0.14732)
		(layer "In11.Cu")
		(net "UPI_CPU1_CPU0_P2P2_DN<7>")
	)
	(segment
		(start 346.009722 -299.828204)
		(end 346.18168 -299.426376)
		(width 0.14732)
		(layer "In11.Cu")
		(net "UPI_CPU1_CPU0_P2P2_DN<7>")
	)
	(segment
		(start 91.35745 -286.964882)
		(end 91.34856 -286.969962)
		(width 0.0889)
		(layer "In11.Cu")
		(net "UPI_CPU1_CPU0_P2P2_DN<7>")
	)
	(segment
		(start 345.513152 -301.295562)
		(end 345.63304 -301.015654)
		(width 0.14732)
		(layer "In11.Cu")
		(net "UPI_CPU1_CPU0_P2P2_DN<7>")
	)
	(arc
		(start 350.009714 -285.98622)
		(mid 350.143335 -285.855402)
		(end 350.197166 -285.67634)
		(width 0.0889)
		(layer "In11.Cu")
		(net "UPI_CPU1_CPU0_P2P2_DN<7>")
	)
	(arc
		(start 353.48672 -276.700742)
		(mid 353.434493 -276.517824)
		(end 353.299268 -276.384004)
		(width 0.0889)
		(layer "In11.Cu")
		(net "UPI_CPU1_CPU0_P2P2_DN<7>")
	)
	(arc
		(start 348.31782 -288.917126)
		(mid 348.390512 -288.639921)
		(end 348.589854 -288.434018)
		(width 0.0889)
		(layer "In11.Cu")
		(net "UPI_CPU1_CPU0_P2P2_DN<7>")
	)
	(arc
		(start 350.197166 -285.661354)
		(mid 350.26956 -285.384613)
		(end 350.468184 -285.178754)
		(width 0.0889)
		(layer "In11.Cu")
		(net "UPI_CPU1_CPU0_P2P2_DN<7>")
	)
	(arc
		(start 349.545148 -286.796988)
		(mid 349.678764 -286.660268)
		(end 349.72752 -286.475424)
		(width 0.0889)
		(layer "In11.Cu")
		(net "UPI_CPU1_CPU0_P2P2_DN<7>")
	)
	(arc
		(start 91.170252 -285.651194)
		(mid 91.170172 -285.663642)
		(end 91.170506 -285.676086)
		(width 0.0889)
		(layer "In11.Cu")
		(net "UPI_CPU1_CPU0_P2P2_DN<7>")
	)
	(arc
		(start 91.35745 -285.985712)
		(mid 91.560755 -286.186578)
		(end 91.639898 -286.4612)
		(width 0.0889)
		(layer "In11.Cu")
		(net "UPI_CPU1_CPU0_P2P2_DN<7>")
	)
	(arc
		(start 352.346768 -276.376638)
		(mid 352.164598 -276.333649)
		(end 351.98431 -276.384004)
		(width 0.0889)
		(layer "In11.Cu")
		(net "UPI_CPU1_CPU0_P2P2_DN<7>")
	)
	(arc
		(start 90.878406 -287.783778)
		(mid 90.747492 -287.920138)
		(end 90.699844 -288.103056)
		(width 0.0889)
		(layer "In11.Cu")
		(net "UPI_CPU1_CPU0_P2P2_DN<7>")
	)
	(arc
		(start 91.639898 -286.475424)
		(mid 91.565982 -286.754926)
		(end 91.363546 -286.961326)
		(width 0.0889)
		(layer "In11.Cu")
		(net "UPI_CPU1_CPU0_P2P2_DN<7>")
	)
	(arc
		(start 93.22816 -282.086558)
		(mid 93.097246 -282.222918)
		(end 93.049598 -282.405836)
		(width 0.0889)
		(layer "In11.Cu")
		(net "UPI_CPU1_CPU0_P2P2_DN<7>")
	)
	(arc
		(start 353.304348 -277.03018)
		(mid 353.437964 -276.89346)
		(end 353.48672 -276.708616)
		(width 0.0889)
		(layer "In11.Cu")
		(net "UPI_CPU1_CPU0_P2P2_DN<7>")
	)
	(arc
		(start 351.98431 -276.384004)
		(mid 351.701579 -276.459687)
		(end 351.418906 -276.38375)
		(width 0.0889)
		(layer "In11.Cu")
		(net "UPI_CPU1_CPU0_P2P2_DN<7>")
	)
	(arc
		(start 93.519244 -281.607514)
		(mid 93.439874 -281.881248)
		(end 93.23705 -282.081478)
		(width 0.0889)
		(layer "In11.Cu")
		(net "UPI_CPU1_CPU0_P2P2_DN<7>")
	)
	(arc
		(start 353.01682 -279.150318)
		(mid 352.969882 -278.968682)
		(end 352.840798 -278.832564)
		(width 0.0889)
		(layer "In11.Cu")
		(net "UPI_CPU1_CPU0_P2P2_DN<7>")
	)
	(arc
		(start 91.34856 -285.342076)
		(mid 91.220241 -285.474048)
		(end 91.170252 -285.651194)
		(width 0.0889)
		(layer "In11.Cu")
		(net "UPI_CPU1_CPU0_P2P2_DN<7>")
	)
	(arc
		(start 352.829114 -277.847298)
		(mid 352.962735 -277.71648)
		(end 353.016566 -277.537418)
		(width 0.0889)
		(layer "In11.Cu")
		(net "UPI_CPU1_CPU0_P2P2_DN<7>")
	)
	(arc
		(start 91.34856 -286.969962)
		(mid 91.217646 -287.106322)
		(end 91.169998 -287.28924)
		(width 0.0889)
		(layer "In11.Cu")
		(net "UPI_CPU1_CPU0_P2P2_DN<7>")
	)
	(arc
		(start 92.758006 -282.900628)
		(mid 92.627092 -283.036988)
		(end 92.579444 -283.219906)
		(width 0.0889)
		(layer "In11.Cu")
		(net "UPI_CPU1_CPU0_P2P2_DN<7>")
	)
	(arc
		(start 351.98431 -281.916632)
		(mid 352.164911 -281.966928)
		(end 352.347276 -281.92349)
		(width 0.0889)
		(layer "In11.Cu")
		(net "UPI_CPU1_CPU0_P2P2_DN<7>")
	)
	(arc
		(start 352.54692 -278.325834)
		(mid 352.625075 -278.049438)
		(end 352.829114 -277.847298)
		(width 0.0889)
		(layer "In11.Cu")
		(net "UPI_CPU1_CPU0_P2P2_DN<7>")
	)
	(arc
		(start 350.484948 -285.169102)
		(mid 350.618564 -285.032382)
		(end 350.66732 -284.847538)
		(width 0.0889)
		(layer "In11.Cu")
		(net "UPI_CPU1_CPU0_P2P2_DN<7>")
	)
	(arc
		(start 91.170506 -285.676086)
		(mid 91.221416 -285.850655)
		(end 91.34856 -285.980632)
		(width 0.0889)
		(layer "In11.Cu")
		(net "UPI_CPU1_CPU0_P2P2_DN<7>")
	)
	(arc
		(start 350.66732 -284.83687)
		(mid 350.745475 -284.560474)
		(end 350.949514 -284.358334)
		(width 0.0889)
		(layer "In11.Cu")
		(net "UPI_CPU1_CPU0_P2P2_DN<7>")
	)
	(arc
		(start 351.406968 -276.376638)
		(mid 351.224798 -276.333649)
		(end 351.04451 -276.384004)
		(width 0.0889)
		(layer "In11.Cu")
		(net "UPI_CPU1_CPU0_P2P2_DN<7>")
	)
	(arc
		(start 90.699844 -288.125154)
		(mid 90.618933 -288.395282)
		(end 90.41765 -288.592768)
		(width 0.0889)
		(layer "In11.Cu")
		(net "UPI_CPU1_CPU0_P2P2_DN<7>")
	)
	(arc
		(start 350.557592 -276.422104)
		(mid 350.54752 -276.418137)
		(end 350.537526 -276.413976)
		(width 0.0889)
		(layer "In11.Cu")
		(net "UPI_CPU1_CPU0_P2P2_DN<7>")
	)
	(arc
		(start 92.579444 -283.229812)
		(mid 92.501333 -283.506761)
		(end 92.296996 -283.709364)
		(width 0.0889)
		(layer "In11.Cu")
		(net "UPI_CPU1_CPU0_P2P2_DN<7>")
	)
	(arc
		(start 348.787466 -289.64509)
		(mid 348.712359 -289.529944)
		(end 348.603316 -289.446208)
		(width 0.0889)
		(layer "In11.Cu")
		(net "UPI_CPU1_CPU0_P2P2_DN<7>")
	)
	(arc
		(start 351.04451 -276.384004)
		(mid 350.805455 -276.458018)
		(end 350.557846 -276.421596)
		(width 0.0889)
		(layer "In11.Cu")
		(net "UPI_CPU1_CPU0_P2P2_DN<7>")
	)
	(arc
		(start 351.606866 -283.20492)
		(mid 351.552971 -283.025897)
		(end 351.419414 -282.89504)
		(width 0.0889)
		(layer "In11.Cu")
		(net "UPI_CPU1_CPU0_P2P2_DN<7>")
	)
	(arc
		(start 348.78772 -288.103056)
		(mid 348.860412 -287.825851)
		(end 349.059754 -287.619948)
		(width 0.0889)
		(layer "In11.Cu")
		(net "UPI_CPU1_CPU0_P2P2_DN<7>")
	)
	(arc
		(start 93.049598 -282.42006)
		(mid 92.970379 -282.694745)
		(end 92.766896 -282.895548)
		(width 0.0889)
		(layer "In11.Cu")
		(net "UPI_CPU1_CPU0_P2P2_DN<7>")
	)
	(arc
		(start 352.359468 -280.288746)
		(mid 352.49385 -280.156492)
		(end 352.54692 -279.975564)
		(width 0.0889)
		(layer "In11.Cu")
		(net "UPI_CPU1_CPU0_P2P2_DN<7>")
	)
	(arc
		(start 350.949514 -284.358334)
		(mid 351.084805 -284.224552)
		(end 351.136966 -284.041596)
		(width 0.0889)
		(layer "In11.Cu")
		(net "UPI_CPU1_CPU0_P2P2_DN<7>")
	)
	(arc
		(start 93.236796 -281.102562)
		(mid 93.441131 -281.305167)
		(end 93.519244 -281.582114)
		(width 0.0889)
		(layer "In11.Cu")
		(net "UPI_CPU1_CPU0_P2P2_DN<7>")
	)
	(arc
		(start 349.070422 -287.613598)
		(mid 349.20421 -287.481808)
		(end 349.257366 -287.301686)
		(width 0.0889)
		(layer "In11.Cu")
		(net "UPI_CPU1_CPU0_P2P2_DN<7>")
	)
	(arc
		(start 352.92411 -276.384004)
		(mid 352.641379 -276.459687)
		(end 352.358706 -276.38375)
		(width 0.0889)
		(layer "In11.Cu")
		(net "UPI_CPU1_CPU0_P2P2_DN<7>")
	)
	(arc
		(start 349.72752 -286.464756)
		(mid 349.805675 -286.18836)
		(end 350.009714 -285.98622)
		(width 0.0889)
		(layer "In11.Cu")
		(net "UPI_CPU1_CPU0_P2P2_DN<7>")
	)
	(arc
		(start 92.729812 -281.073098)
		(mid 92.98681 -281.02761)
		(end 93.236796 -281.102562)
		(width 0.0889)
		(layer "In11.Cu")
		(net "UPI_CPU1_CPU0_P2P2_DN<7>")
	)
	(arc
		(start 351.419414 -281.916632)
		(mid 351.701862 -281.840949)
		(end 351.98431 -281.916632)
		(width 0.0889)
		(layer "In11.Cu")
		(net "UPI_CPU1_CPU0_P2P2_DN<7>")
	)
	(arc
		(start 352.54692 -279.964134)
		(mid 352.618728 -279.688438)
		(end 352.815906 -279.482804)
		(width 0.0889)
		(layer "In11.Cu")
		(net "UPI_CPU1_CPU0_P2P2_DN<7>")
	)
	(arc
		(start 352.3488 -281.261312)
		(mid 352.076718 -280.778204)
		(end 352.3488 -280.295096)
		(width 0.0889)
		(layer "In11.Cu")
		(net "UPI_CPU1_CPU0_P2P2_DN<7>")
	)
	(arc
		(start 90.402664 -288.601404)
		(mid 90.275941 -288.737185)
		(end 90.229944 -288.917126)
		(width 0.0889)
		(layer "In11.Cu")
		(net "UPI_CPU1_CPU0_P2P2_DN<7>")
	)
	(arc
		(start 348.600522 -288.427668)
		(mid 348.733899 -288.296908)
		(end 348.78772 -288.118042)
		(width 0.0889)
		(layer "In11.Cu")
		(net "UPI_CPU1_CPU0_P2P2_DN<7>")
	)
	(arc
		(start 353.016566 -277.522432)
		(mid 353.08896 -277.245691)
		(end 353.287584 -277.039832)
		(width 0.0889)
		(layer "In11.Cu")
		(net "UPI_CPU1_CPU0_P2P2_DN<7>")
	)
	(arc
		(start 351.419668 -283.544264)
		(mid 351.554713 -283.41054)
		(end 351.606866 -283.22778)
		(width 0.0889)
		(layer "In11.Cu")
		(net "UPI_CPU1_CPU0_P2P2_DN<7>")
	)
	(arc
		(start 352.834194 -279.471882)
		(mid 352.967905 -279.335182)
		(end 353.01682 -279.150318)
		(width 0.0889)
		(layer "In11.Cu")
		(net "UPI_CPU1_CPU0_P2P2_DN<7>")
	)
	(arc
		(start 92.109544 -284.043628)
		(mid 92.031433 -284.320577)
		(end 91.827096 -284.52318)
		(width 0.0889)
		(layer "In11.Cu")
		(net "UPI_CPU1_CPU0_P2P2_DN<7>")
	)
	(arc
		(start 352.364548 -281.913584)
		(mid 352.546812 -281.591628)
		(end 352.363786 -281.270202)
		(width 0.0889)
		(layer "In11.Cu")
		(net "UPI_CPU1_CPU0_P2P2_DN<7>")
	)
	(arc
		(start 353.290378 -276.37867)
		(mid 353.106557 -276.333612)
		(end 352.92411 -276.384004)
		(width 0.0889)
		(layer "In11.Cu")
		(net "UPI_CPU1_CPU0_P2P2_DN<7>")
	)
	(arc
		(start 91.169998 -287.28924)
		(mid 91.096007 -287.568806)
		(end 90.893392 -287.775142)
		(width 0.0889)
		(layer "In11.Cu")
		(net "UPI_CPU1_CPU0_P2P2_DN<7>")
	)
	(arc
		(start 352.827844 -278.825198)
		(mid 352.624623 -278.623046)
		(end 352.54692 -278.34717)
		(width 0.0889)
		(layer "In11.Cu")
		(net "UPI_CPU1_CPU0_P2P2_DN<7>")
	)
	(arc
		(start 351.13722 -282.395168)
		(mid 351.215375 -282.118772)
		(end 351.419414 -281.916632)
		(width 0.0889)
		(layer "In11.Cu")
		(net "UPI_CPU1_CPU0_P2P2_DN<7>")
	)
	(arc
		(start 351.136966 -284.033722)
		(mid 351.209658 -283.756517)
		(end 351.409 -283.550614)
		(width 0.0889)
		(layer "In11.Cu")
		(net "UPI_CPU1_CPU0_P2P2_DN<7>")
	)
	(arc
		(start 92.288106 -283.714444)
		(mid 92.157192 -283.850804)
		(end 92.109544 -284.033722)
		(width 0.0889)
		(layer "In11.Cu")
		(net "UPI_CPU1_CPU0_P2P2_DN<7>")
	)
	(arc
		(start 351.419414 -282.89504)
		(mid 351.215436 -282.692864)
		(end 351.13722 -282.416504)
		(width 0.0889)
		(layer "In11.Cu")
		(net "UPI_CPU1_CPU0_P2P2_DN<7>")
	)
	(arc
		(start 349.257366 -287.28924)
		(mid 349.32976 -287.012499)
		(end 349.528384 -286.80664)
		(width 0.0889)
		(layer "In11.Cu")
		(net "UPI_CPU1_CPU0_P2P2_DN<7>")
	)
	(arc
		(start 91.818206 -284.52826)
		(mid 91.687292 -284.66462)
		(end 91.639644 -284.847538)
		(width 0.0889)
		(layer "In11.Cu")
		(net "UPI_CPU1_CPU0_P2P2_DN<7>")
	)
	(arc
		(start 91.639644 -284.863032)
		(mid 91.560274 -285.136766)
		(end 91.35745 -285.336996)
		(width 0.0889)
		(layer "In11.Cu")
		(net "UPI_CPU1_CPU0_P2P2_DN<7>")
	)
	(arc
		(start 348.603316 -289.446208)
		(mid 348.429071 -289.307162)
		(end 348.31782 -289.113976)
		(width 0.0889)
		(layer "In11.Cu")
		(net "UPI_CPU1_CPU0_P2P2_DN<7>")
	)
	(segment
		(start 91.544648 -281.869896)
		(end 91.544902 -281.87015)
		(width 0.13208)
		(layer "F.Cu")
		(net "UPI_CPU1_CPU0_P2P2_DN<6>")
	)
	(segment
		(start 354.991162 -276.708362)
		(end 354.991416 -276.708616)
		(width 0.13208)
		(layer "F.Cu")
		(net "UPI_CPU1_CPU0_P2P2_DN<6>")
	)
	(segment
		(start 354.991162 -276.172676)
		(end 354.991162 -276.708362)
		(width 0.13208)
		(layer "F.Cu")
		(net "UPI_CPU1_CPU0_P2P2_DN<6>")
	)
	(segment
		(start 91.544902 -282.405582)
		(end 91.544648 -282.405836)
		(width 0.13208)
		(layer "F.Cu")
		(net "UPI_CPU1_CPU0_P2P2_DN<6>")
	)
	(segment
		(start 91.544902 -281.87015)
		(end 91.544902 -282.405582)
		(width 0.13208)
		(layer "F.Cu")
		(net "UPI_CPU1_CPU0_P2P2_DN<6>")
	)
	(segment
		(start 90.416126 -285.33725)
		(end 90.412316 -285.339536)
		(width 0.0889)
		(layer "In11.Cu")
		(net "UPI_CPU1_CPU0_P2P2_DN<6>")
	)
	(segment
		(start 89.95791 -287.772602)
		(end 89.946988 -287.778444)
		(width 0.0889)
		(layer "In11.Cu")
		(net "UPI_CPU1_CPU0_P2P2_DN<6>")
	)
	(segment
		(start 351.41916 -285.171896)
		(end 351.419922 -285.171388)
		(width 0.0889)
		(layer "In11.Cu")
		(net "UPI_CPU1_CPU0_P2P2_DN<6>")
	)
	(segment
		(start 64.777366 -319.964054)
		(end 64.25438 -320.48704)
		(width 0.14732)
		(layer "In11.Cu")
		(net "UPI_CPU1_CPU0_P2P2_DN<6>")
	)
	(segment
		(start 90.897456 -284.51683)
		(end 90.886788 -284.52318)
		(width 0.0889)
		(layer "In11.Cu")
		(net "UPI_CPU1_CPU0_P2P2_DN<6>")
	)
	(segment
		(start 61.718698 -355.165406)
		(end 66.983356 -367.876074)
		(width 0.14732)
		(layer "In11.Cu")
		(net "UPI_CPU1_CPU0_P2P2_DN<6>")
	)
	(segment
		(start 62.74943 -321.281552)
		(end 62.493144 -322.570348)
		(width 0.14732)
		(layer "In11.Cu")
		(net "UPI_CPU1_CPU0_P2P2_DN<6>")
	)
	(segment
		(start 354.745798 -277.00351)
		(end 354.834952 -276.979634)
		(width 0.0889)
		(layer "In11.Cu")
		(net "UPI_CPU1_CPU0_P2P2_DN<6>")
	)
	(segment
		(start 353.299014 -281.916378)
		(end 353.307904 -281.911298)
		(width 0.0889)
		(layer "In11.Cu")
		(net "UPI_CPU1_CPU0_P2P2_DN<6>")
	)
	(segment
		(start 90.429842 -286.957262)
		(end 90.425016 -286.960056)
		(width 0.0889)
		(layer "In11.Cu")
		(net "UPI_CPU1_CPU0_P2P2_DN<6>")
	)
	(segment
		(start 349.064834 -291.30244)
		(end 349.080328 -291.286946)
		(width 0.0889)
		(layer "In11.Cu")
		(net "UPI_CPU1_CPU0_P2P2_DN<6>")
	)
	(segment
		(start 90.43035 -285.329122)
		(end 90.416126 -285.33725)
		(width 0.0889)
		(layer "In11.Cu")
		(net "UPI_CPU1_CPU0_P2P2_DN<6>")
	)
	(segment
		(start 351.415858 -286.801814)
		(end 351.418652 -286.80029)
		(width 0.0889)
		(layer "In11.Cu")
		(net "UPI_CPU1_CPU0_P2P2_DN<6>")
	)
	(segment
		(start 353.486466 -279.964134)
		(end 353.486466 -279.954228)
		(width 0.0889)
		(layer "In11.Cu")
		(net "UPI_CPU1_CPU0_P2P2_DN<6>")
	)
	(segment
		(start 86.225888 -294.703754)
		(end 84.172298 -299.662342)
		(width 0.14732)
		(layer "In11.Cu")
		(net "UPI_CPU1_CPU0_P2P2_DN<6>")
	)
	(segment
		(start 64.25438 -320.48704)
		(end 63.597536 -320.759074)
		(width 0.14732)
		(layer "In11.Cu")
		(net "UPI_CPU1_CPU0_P2P2_DN<6>")
	)
	(segment
		(start 64.998092 -319.431162)
		(end 64.777366 -319.964054)
		(width 0.14732)
		(layer "In11.Cu")
		(net "UPI_CPU1_CPU0_P2P2_DN<6>")
	)
	(segment
		(start 82.430874 -301.404274)
		(end 82.430874 -301.57674)
		(width 0.14732)
		(layer "In11.Cu")
		(net "UPI_CPU1_CPU0_P2P2_DN<6>")
	)
	(segment
		(start 274.416774 -367.107978)
		(end 274.271994 -366.963198)
		(width 0.14732)
		(layer "In11.Cu")
		(net "UPI_CPU1_CPU0_P2P2_DN<6>")
	)
	(segment
		(start 90.430604 -285.328868)
		(end 90.43035 -285.329122)
		(width 0.0889)
		(layer "In11.Cu")
		(net "UPI_CPU1_CPU0_P2P2_DN<6>")
	)
	(segment
		(start 351.88906 -284.35808)
		(end 351.89795 -284.353)
		(width 0.0889)
		(layer "In11.Cu")
		(net "UPI_CPU1_CPU0_P2P2_DN<6>")
	)
	(segment
		(start 351.422462 -285.169864)
		(end 351.42805 -285.166816)
		(width 0.0889)
		(layer "In11.Cu")
		(net "UPI_CPU1_CPU0_P2P2_DN<6>")
	)
	(segment
		(start 352.546412 -283.219906)
		(end 352.546412 -283.205682)
		(width 0.0889)
		(layer "In11.Cu")
		(net "UPI_CPU1_CPU0_P2P2_DN<6>")
	)
	(segment
		(start 89.28989 -288.900362)
		(end 89.28989 -289.32886)
		(width 0.0889)
		(layer "In11.Cu")
		(net "UPI_CPU1_CPU0_P2P2_DN<6>")
	)
	(segment
		(start 89.28989 -289.32886)
		(end 88.9762 -289.64255)
		(width 0.0889)
		(layer "In11.Cu")
		(net "UPI_CPU1_CPU0_P2P2_DN<6>")
	)
	(segment
		(start 347.232732 -299.906182)
		(end 347.173296 -299.710348)
		(width 0.14732)
		(layer "In11.Cu")
		(net "UPI_CPU1_CPU0_P2P2_DN<6>")
	)
	(segment
		(start 353.956112 -277.522432)
		(end 353.956112 -277.512526)
		(width 0.0889)
		(layer "In11.Cu")
		(net "UPI_CPU1_CPU0_P2P2_DN<6>")
	)
	(segment
		(start 67.024504 -317.404242)
		(end 64.998092 -319.431162)
		(width 0.14732)
		(layer "In11.Cu")
		(net "UPI_CPU1_CPU0_P2P2_DN<6>")
	)
	(segment
		(start 89.018364 -291.208206)
		(end 89.018364 -291.911278)
		(width 0.14732)
		(layer "In11.Cu")
		(net "UPI_CPU1_CPU0_P2P2_DN<6>")
	)
	(segment
		(start 348.209616 -292.157658)
		(end 349.064834 -291.30244)
		(width 0.14732)
		(layer "In11.Cu")
		(net "UPI_CPU1_CPU0_P2P2_DN<6>")
	)
	(segment
		(start 81.949544 -301.885858)
		(end 67.024504 -316.813438)
		(width 0.14732)
		(layer "In11.Cu")
		(net "UPI_CPU1_CPU0_P2P2_DN<6>")
	)
	(segment
		(start 352.35896 -283.544264)
		(end 352.359722 -283.543756)
		(width 0.0889)
		(layer "In11.Cu")
		(net "UPI_CPU1_CPU0_P2P2_DN<6>")
	)
	(segment
		(start 352.076512 -284.033722)
		(end 352.076512 -284.023816)
		(width 0.0889)
		(layer "In11.Cu")
		(net "UPI_CPU1_CPU0_P2P2_DN<6>")
	)
	(segment
		(start 89.018364 -291.186108)
		(end 89.018364 -291.208206)
		(width 0.0889)
		(layer "In11.Cu")
		(net "UPI_CPU1_CPU0_P2P2_DN<6>")
	)
	(segment
		(start 347.173296 -299.710348)
		(end 347.346778 -299.385228)
		(width 0.14732)
		(layer "In11.Cu")
		(net "UPI_CPU1_CPU0_P2P2_DN<6>")
	)
	(segment
		(start 353.777804 -278.83104)
		(end 353.768914 -278.82596)
		(width 0.0889)
		(layer "In11.Cu")
		(net "UPI_CPU1_CPU0_P2P2_DN<6>")
	)
	(segment
		(start 353.768914 -278.82596)
		(end 353.765104 -278.823674)
		(width 0.0889)
		(layer "In11.Cu")
		(net "UPI_CPU1_CPU0_P2P2_DN<6>")
	)
	(segment
		(start 62.493144 -322.570348)
		(end 62.466474 -322.63461)
		(width 0.14732)
		(layer "In11.Cu")
		(net "UPI_CPU1_CPU0_P2P2_DN<6>")
	)
	(segment
		(start 84.172298 -299.662342)
		(end 83.221068 -300.613572)
		(width 0.14732)
		(layer "In11.Cu")
		(net "UPI_CPU1_CPU0_P2P2_DN<6>")
	)
	(segment
		(start 90.425016 -285.990792)
		(end 90.430604 -285.994094)
		(width 0.0889)
		(layer "In11.Cu")
		(net "UPI_CPU1_CPU0_P2P2_DN<6>")
	)
	(segment
		(start 60.376562 -324.746366)
		(end 59.655202 -325.467726)
		(width 0.14732)
		(layer "In11.Cu")
		(net "UPI_CPU1_CPU0_P2P2_DN<6>")
	)
	(segment
		(start 351.882964 -284.361636)
		(end 351.88906 -284.35808)
		(width 0.0889)
		(layer "In11.Cu")
		(net "UPI_CPU1_CPU0_P2P2_DN<6>")
	)
	(segment
		(start 350.667066 -288.103056)
		(end 350.667066 -288.087562)
		(width 0.0889)
		(layer "In11.Cu")
		(net "UPI_CPU1_CPU0_P2P2_DN<6>")
	)
	(segment
		(start 63.041784 -320.989198)
		(end 62.74943 -321.281552)
		(width 0.14732)
		(layer "In11.Cu")
		(net "UPI_CPU1_CPU0_P2P2_DN<6>")
	)
	(segment
		(start 67.024504 -316.813438)
		(end 67.024504 -317.404242)
		(width 0.14732)
		(layer "In11.Cu")
		(net "UPI_CPU1_CPU0_P2P2_DN<6>")
	)
	(segment
		(start 82.739738 -301.09541)
		(end 82.430874 -301.404274)
		(width 0.14732)
		(layer "In11.Cu")
		(net "UPI_CPU1_CPU0_P2P2_DN<6>")
	)
	(segment
		(start 353.299014 -280.288492)
		(end 353.307904 -280.283412)
		(width 0.0889)
		(layer "In11.Cu")
		(net "UPI_CPU1_CPU0_P2P2_DN<6>")
	)
	(segment
		(start 346.266516 -301.7139)
		(end 347.232732 -299.906182)
		(width 0.14732)
		(layer "In11.Cu")
		(net "UPI_CPU1_CPU0_P2P2_DN<6>")
	)
	(segment
		(start 88.9762 -289.64255)
		(end 88.9762 -291.143944)
		(width 0.0889)
		(layer "In11.Cu")
		(net "UPI_CPU1_CPU0_P2P2_DN<6>")
	)
	(segment
		(start 82.430874 -301.57674)
		(end 82.121756 -301.885858)
		(width 0.14732)
		(layer "In11.Cu")
		(net "UPI_CPU1_CPU0_P2P2_DN<6>")
	)
	(segment
		(start 353.016312 -280.778204)
		(end 353.016312 -280.76398)
		(width 0.0889)
		(layer "In11.Cu")
		(net "UPI_CPU1_CPU0_P2P2_DN<6>")
	)
	(segment
		(start 349.080328 -291.286946)
		(end 349.140272 -291.286946)
		(width 0.0889)
		(layer "In11.Cu")
		(net "UPI_CPU1_CPU0_P2P2_DN<6>")
	)
	(segment
		(start 349.727012 -290.700206)
		(end 349.727012 -289.609784)
		(width 0.0889)
		(layer "In11.Cu")
		(net "UPI_CPU1_CPU0_P2P2_DN<6>")
	)
	(segment
		(start 82.91195 -301.09541)
		(end 82.739738 -301.09541)
		(width 0.14732)
		(layer "In11.Cu")
		(net "UPI_CPU1_CPU0_P2P2_DN<6>")
	)
	(segment
		(start 59.4868 -329.065128)
		(end 60.66155 -331.26299)
		(width 0.14732)
		(layer "In11.Cu")
		(net "UPI_CPU1_CPU0_P2P2_DN<6>")
	)
	(segment
		(start 353.486212 -278.336502)
		(end 353.486212 -278.322278)
		(width 0.0889)
		(layer "In11.Cu")
		(net "UPI_CPU1_CPU0_P2P2_DN<6>")
	)
	(segment
		(start 351.136712 -285.675578)
		(end 351.136712 -285.651448)
		(width 0.0889)
		(layer "In11.Cu")
		(net "UPI_CPU1_CPU0_P2P2_DN<6>")
	)
	(segment
		(start 263.16051 -379.030484)
		(end 274.416774 -367.77422)
		(width 0.14732)
		(layer "In11.Cu")
		(net "UPI_CPU1_CPU0_P2P2_DN<6>")
	)
	(segment
		(start 83.221068 -300.786038)
		(end 82.91195 -301.09541)
		(width 0.14732)
		(layer "In11.Cu")
		(net "UPI_CPU1_CPU0_P2P2_DN<6>")
	)
	(segment
		(start 61.718698 -335.482946)
		(end 61.718698 -355.165406)
		(width 0.14732)
		(layer "In11.Cu")
		(net "UPI_CPU1_CPU0_P2P2_DN<6>")
	)
	(segment
		(start 350.479614 -288.427414)
		(end 350.488504 -288.422334)
		(width 0.0889)
		(layer "In11.Cu")
		(net "UPI_CPU1_CPU0_P2P2_DN<6>")
	)
	(segment
		(start 90.69959 -284.839664)
		(end 90.69959 -284.847538)
		(width 0.0889)
		(layer "In11.Cu")
		(net "UPI_CPU1_CPU0_P2P2_DN<6>")
	)
	(segment
		(start 351.418652 -286.80029)
		(end 351.419414 -286.799782)
		(width 0.0889)
		(layer "In11.Cu")
		(net "UPI_CPU1_CPU0_P2P2_DN<6>")
	)
	(segment
		(start 352.359722 -283.543756)
		(end 352.3615 -283.54274)
		(width 0.0889)
		(layer "In11.Cu")
		(net "UPI_CPU1_CPU0_P2P2_DN<6>")
	)
	(segment
		(start 309.663338 -337.62061)
		(end 318.093852 -329.190096)
		(width 0.14732)
		(layer "In11.Cu")
		(net "UPI_CPU1_CPU0_P2P2_DN<6>")
	)
	(segment
		(start 89.75979 -288.095182)
		(end 89.75979 -288.103056)
		(width 0.0889)
		(layer "In11.Cu")
		(net "UPI_CPU1_CPU0_P2P2_DN<6>")
	)
	(segment
		(start 342.622886 -305.35753)
		(end 346.266516 -301.7139)
		(width 0.14732)
		(layer "In11.Cu")
		(net "UPI_CPU1_CPU0_P2P2_DN<6>")
	)
	(segment
		(start 59.655202 -325.467726)
		(end 59.4868 -325.874126)
		(width 0.14732)
		(layer "In11.Cu")
		(net "UPI_CPU1_CPU0_P2P2_DN<6>")
	)
	(segment
		(start 351.4217 -285.170372)
		(end 351.422462 -285.169864)
		(width 0.0889)
		(layer "In11.Cu")
		(net "UPI_CPU1_CPU0_P2P2_DN<6>")
	)
	(segment
		(start 274.271994 -366.963198)
		(end 274.271994 -366.594898)
		(width 0.14732)
		(layer "In11.Cu")
		(net "UPI_CPU1_CPU0_P2P2_DN<6>")
	)
	(segment
		(start 353.292918 -281.919934)
		(end 353.299014 -281.916378)
		(width 0.0889)
		(layer "In11.Cu")
		(net "UPI_CPU1_CPU0_P2P2_DN<6>")
	)
	(segment
		(start 66.983356 -367.876074)
		(end 72.654922 -373.54764)
		(width 0.14732)
		(layer "In11.Cu")
		(net "UPI_CPU1_CPU0_P2P2_DN<6>")
	)
	(segment
		(start 353.765104 -278.823674)
		(end 353.756722 -278.818848)
		(width 0.0889)
		(layer "In11.Cu")
		(net "UPI_CPU1_CPU0_P2P2_DN<6>")
	)
	(segment
		(start 354.834952 -276.979634)
		(end 354.991416 -276.708616)
		(width 0.0889)
		(layer "In11.Cu")
		(net "UPI_CPU1_CPU0_P2P2_DN<6>")
	)
	(segment
		(start 353.76866 -277.84679)
		(end 353.77755 -277.84171)
		(width 0.0889)
		(layer "In11.Cu")
		(net "UPI_CPU1_CPU0_P2P2_DN<6>")
	)
	(segment
		(start 318.093852 -329.190096)
		(end 319.222374 -326.465438)
		(width 0.14732)
		(layer "In11.Cu")
		(net "UPI_CPU1_CPU0_P2P2_DN<6>")
	)
	(segment
		(start 354.23856 -277.032974)
		(end 354.248974 -277.026878)
		(width 0.0889)
		(layer "In11.Cu")
		(net "UPI_CPU1_CPU0_P2P2_DN<6>")
	)
	(segment
		(start 274.416774 -347.49994)
		(end 282.670504 -339.24621)
		(width 0.14732)
		(layer "In11.Cu")
		(net "UPI_CPU1_CPU0_P2P2_DN<6>")
	)
	(segment
		(start 62.466474 -322.63461)
		(end 61.966094 -323.842634)
		(width 0.14732)
		(layer "In11.Cu")
		(net "UPI_CPU1_CPU0_P2P2_DN<6>")
	)
	(segment
		(start 351.413318 -286.803338)
		(end 351.415858 -286.801814)
		(width 0.0889)
		(layer "In11.Cu")
		(net "UPI_CPU1_CPU0_P2P2_DN<6>")
	)
	(segment
		(start 286.595312 -337.62061)
		(end 309.663338 -337.62061)
		(width 0.14732)
		(layer "In11.Cu")
		(net "UPI_CPU1_CPU0_P2P2_DN<6>")
	)
	(segment
		(start 274.271994 -366.594898)
		(end 274.416774 -366.450118)
		(width 0.14732)
		(layer "In11.Cu")
		(net "UPI_CPU1_CPU0_P2P2_DN<6>")
	)
	(segment
		(start 90.425016 -286.960056)
		(end 90.416126 -286.965136)
		(width 0.0889)
		(layer "In11.Cu")
		(net "UPI_CPU1_CPU0_P2P2_DN<6>")
	)
	(segment
		(start 89.018364 -291.911278)
		(end 86.225888 -294.703754)
		(width 0.14732)
		(layer "In11.Cu")
		(net "UPI_CPU1_CPU0_P2P2_DN<6>")
	)
	(segment
		(start 61.547502 -324.261226)
		(end 60.376562 -324.746366)
		(width 0.14732)
		(layer "In11.Cu")
		(net "UPI_CPU1_CPU0_P2P2_DN<6>")
	)
	(segment
		(start 351.419922 -285.171388)
		(end 351.4217 -285.170372)
		(width 0.0889)
		(layer "In11.Cu")
		(net "UPI_CPU1_CPU0_P2P2_DN<6>")
	)
	(segment
		(start 319.222374 -326.465438)
		(end 338.709 -306.978812)
		(width 0.14732)
		(layer "In11.Cu")
		(net "UPI_CPU1_CPU0_P2P2_DN<6>")
	)
	(segment
		(start 347.346778 -299.385228)
		(end 347.542866 -299.325792)
		(width 0.14732)
		(layer "In11.Cu")
		(net "UPI_CPU1_CPU0_P2P2_DN<6>")
	)
	(segment
		(start 162.158426 -387.558788)
		(end 263.16051 -379.030484)
		(width 0.14732)
		(layer "In11.Cu")
		(net "UPI_CPU1_CPU0_P2P2_DN<6>")
	)
	(segment
		(start 63.597536 -320.759074)
		(end 63.041784 -320.989198)
		(width 0.14732)
		(layer "In11.Cu")
		(net "UPI_CPU1_CPU0_P2P2_DN<6>")
	)
	(segment
		(start 89.487756 -288.586164)
		(end 89.477088 -288.592514)
		(width 0.0889)
		(layer "In11.Cu")
		(net "UPI_CPU1_CPU0_P2P2_DN<6>")
	)
	(segment
		(start 82.121756 -301.885858)
		(end 81.949544 -301.885858)
		(width 0.14732)
		(layer "In11.Cu")
		(net "UPI_CPU1_CPU0_P2P2_DN<6>")
	)
	(segment
		(start 338.709 -306.978812)
		(end 342.622886 -305.35753)
		(width 0.14732)
		(layer "In11.Cu")
		(net "UPI_CPU1_CPU0_P2P2_DN<6>")
	)
	(segment
		(start 83.221068 -300.613572)
		(end 83.221068 -300.786038)
		(width 0.14732)
		(layer "In11.Cu")
		(net "UPI_CPU1_CPU0_P2P2_DN<6>")
	)
	(segment
		(start 349.140272 -291.286946)
		(end 349.727012 -290.700206)
		(width 0.0889)
		(layer "In11.Cu")
		(net "UPI_CPU1_CPU0_P2P2_DN<6>")
	)
	(segment
		(start 352.362262 -283.542232)
		(end 352.36785 -283.539184)
		(width 0.0889)
		(layer "In11.Cu")
		(net "UPI_CPU1_CPU0_P2P2_DN<6>")
	)
	(segment
		(start 353.307904 -281.272742)
		(end 353.299014 -281.267662)
		(width 0.0889)
		(layer "In11.Cu")
		(net "UPI_CPU1_CPU0_P2P2_DN<6>")
	)
	(segment
		(start 126.355348 -387.558788)
		(end 162.158426 -387.558788)
		(width 0.14732)
		(layer "In11.Cu")
		(net "UPI_CPU1_CPU0_P2P2_DN<6>")
	)
	(segment
		(start 95.39224 -382.965706)
		(end 126.355348 -387.558788)
		(width 0.14732)
		(layer "In11.Cu")
		(net "UPI_CPU1_CPU0_P2P2_DN<6>")
	)
	(segment
		(start 61.966094 -323.842634)
		(end 61.547502 -324.261226)
		(width 0.14732)
		(layer "In11.Cu")
		(net "UPI_CPU1_CPU0_P2P2_DN<6>")
	)
	(segment
		(start 91.367356 -283.703014)
		(end 91.356688 -283.709364)
		(width 0.0889)
		(layer "In11.Cu")
		(net "UPI_CPU1_CPU0_P2P2_DN<6>")
	)
	(segment
		(start 90.430096 -286.957008)
		(end 90.429842 -286.957262)
		(width 0.0889)
		(layer "In11.Cu")
		(net "UPI_CPU1_CPU0_P2P2_DN<6>")
	)
	(segment
		(start 353.768914 -279.474676)
		(end 353.777804 -279.469596)
		(width 0.0889)
		(layer "In11.Cu")
		(net "UPI_CPU1_CPU0_P2P2_DN<6>")
	)
	(segment
		(start 274.416774 -366.450118)
		(end 274.416774 -347.49994)
		(width 0.14732)
		(layer "In11.Cu")
		(net "UPI_CPU1_CPU0_P2P2_DN<6>")
	)
	(segment
		(start 282.670504 -339.24621)
		(end 286.595312 -337.62061)
		(width 0.14732)
		(layer "In11.Cu")
		(net "UPI_CPU1_CPU0_P2P2_DN<6>")
	)
	(segment
		(start 72.654922 -373.54764)
		(end 95.39224 -382.965706)
		(width 0.14732)
		(layer "In11.Cu")
		(net "UPI_CPU1_CPU0_P2P2_DN<6>")
	)
	(segment
		(start 91.544648 -282.405836)
		(end 91.388184 -282.676854)
		(width 0.0889)
		(layer "In11.Cu")
		(net "UPI_CPU1_CPU0_P2P2_DN<6>")
	)
	(segment
		(start 347.542866 -299.325792)
		(end 348.209616 -298.078398)
		(width 0.14732)
		(layer "In11.Cu")
		(net "UPI_CPU1_CPU0_P2P2_DN<6>")
	)
	(segment
		(start 348.209616 -298.078398)
		(end 348.209616 -292.157658)
		(width 0.14732)
		(layer "In11.Cu")
		(net "UPI_CPU1_CPU0_P2P2_DN<6>")
	)
	(segment
		(start 90.416126 -286.965136)
		(end 90.412316 -286.967422)
		(width 0.0889)
		(layer "In11.Cu")
		(net "UPI_CPU1_CPU0_P2P2_DN<6>")
	)
	(segment
		(start 60.66155 -331.26299)
		(end 61.718698 -335.482946)
		(width 0.14732)
		(layer "In11.Cu")
		(net "UPI_CPU1_CPU0_P2P2_DN<6>")
	)
	(segment
		(start 353.299014 -281.267662)
		(end 353.292918 -281.264106)
		(width 0.0889)
		(layer "In11.Cu")
		(net "UPI_CPU1_CPU0_P2P2_DN<6>")
	)
	(segment
		(start 274.416774 -367.77422)
		(end 274.416774 -367.107978)
		(width 0.14732)
		(layer "In11.Cu")
		(net "UPI_CPU1_CPU0_P2P2_DN<6>")
	)
	(segment
		(start 59.4868 -325.874126)
		(end 59.4868 -329.065128)
		(width 0.14732)
		(layer "In11.Cu")
		(net "UPI_CPU1_CPU0_P2P2_DN<6>")
	)
	(segment
		(start 350.94926 -287.613598)
		(end 350.95815 -287.608518)
		(width 0.0889)
		(layer "In11.Cu")
		(net "UPI_CPU1_CPU0_P2P2_DN<6>")
	)
	(segment
		(start 90.416126 -285.985712)
		(end 90.425016 -285.990792)
		(width 0.0889)
		(layer "In11.Cu")
		(net "UPI_CPU1_CPU0_P2P2_DN<6>")
	)
	(segment
		(start 350.197166 -289.077908)
		(end 350.197166 -288.898584)
		(width 0.0889)
		(layer "In11.Cu")
		(net "UPI_CPU1_CPU0_P2P2_DN<6>")
	)
	(segment
		(start 90.22969 -285.661354)
		(end 90.22969 -285.672784)
		(width 0.0889)
		(layer "In11.Cu")
		(net "UPI_CPU1_CPU0_P2P2_DN<6>")
	)
	(segment
		(start 91.388184 -282.676854)
		(end 91.412314 -282.766008)
		(width 0.0889)
		(layer "In11.Cu")
		(net "UPI_CPU1_CPU0_P2P2_DN<6>")
	)
	(segment
		(start 352.82886 -282.730194)
		(end 352.83775 -282.725114)
		(width 0.0889)
		(layer "In11.Cu")
		(net "UPI_CPU1_CPU0_P2P2_DN<6>")
	)
	(segment
		(start 351.606612 -286.48406)
		(end 351.606612 -286.466788)
		(width 0.0889)
		(layer "In11.Cu")
		(net "UPI_CPU1_CPU0_P2P2_DN<6>")
	)
	(segment
		(start 352.3615 -283.54274)
		(end 352.362262 -283.542232)
		(width 0.0889)
		(layer "In11.Cu")
		(net "UPI_CPU1_CPU0_P2P2_DN<6>")
	)
	(segment
		(start 91.16949 -284.025848)
		(end 91.16949 -284.033722)
		(width 0.0889)
		(layer "In11.Cu")
		(net "UPI_CPU1_CPU0_P2P2_DN<6>")
	)
	(segment
		(start 91.412314 -282.766008)
		(end 91.411806 -282.766516)
		(width 0.0889)
		(layer "In11.Cu")
		(net "UPI_CPU1_CPU0_P2P2_DN<6>")
	)
	(segment
		(start 88.9762 -291.143944)
		(end 89.018364 -291.186108)
		(width 0.0889)
		(layer "In11.Cu")
		(net "UPI_CPU1_CPU0_P2P2_DN<6>")
	)
	(arc
		(start 350.667066 -288.087562)
		(mid 350.746436 -287.813828)
		(end 350.94926 -287.613598)
		(width 0.0889)
		(layer "In11.Cu")
		(net "UPI_CPU1_CPU0_P2P2_DN<6>")
	)
	(arc
		(start 350.488504 -288.422334)
		(mid 350.619418 -288.285974)
		(end 350.667066 -288.103056)
		(width 0.0889)
		(layer "In11.Cu")
		(net "UPI_CPU1_CPU0_P2P2_DN<6>")
	)
	(arc
		(start 353.292918 -281.264106)
		(mid 353.090331 -281.057755)
		(end 353.016312 -280.778204)
		(width 0.0889)
		(layer "In11.Cu")
		(net "UPI_CPU1_CPU0_P2P2_DN<6>")
	)
	(arc
		(start 354.725732 -276.995382)
		(mid 354.735803 -276.999351)
		(end 354.745798 -277.00351)
		(width 0.0889)
		(layer "In11.Cu")
		(net "UPI_CPU1_CPU0_P2P2_DN<6>")
	)
	(arc
		(start 91.356688 -283.709364)
		(mid 91.221643 -283.843088)
		(end 91.16949 -284.025848)
		(width 0.0889)
		(layer "In11.Cu")
		(net "UPI_CPU1_CPU0_P2P2_DN<6>")
	)
	(arc
		(start 351.136712 -287.28924)
		(mid 351.210703 -287.009674)
		(end 351.413318 -286.803338)
		(width 0.0889)
		(layer "In11.Cu")
		(net "UPI_CPU1_CPU0_P2P2_DN<6>")
	)
	(arc
		(start 90.22969 -287.28924)
		(mid 90.157134 -287.566523)
		(end 89.95791 -287.772602)
		(width 0.0889)
		(layer "In11.Cu")
		(net "UPI_CPU1_CPU0_P2P2_DN<6>")
	)
	(arc
		(start 353.486466 -279.954228)
		(mid 353.564577 -279.677279)
		(end 353.768914 -279.474676)
		(width 0.0889)
		(layer "In11.Cu")
		(net "UPI_CPU1_CPU0_P2P2_DN<6>")
	)
	(arc
		(start 90.412316 -285.339536)
		(mid 90.278542 -285.476346)
		(end 90.22969 -285.661354)
		(width 0.0889)
		(layer "In11.Cu")
		(net "UPI_CPU1_CPU0_P2P2_DN<6>")
	)
	(arc
		(start 352.36785 -283.539184)
		(mid 352.498764 -283.402824)
		(end 352.546412 -283.219906)
		(width 0.0889)
		(layer "In11.Cu")
		(net "UPI_CPU1_CPU0_P2P2_DN<6>")
	)
	(arc
		(start 90.412316 -286.967422)
		(mid 90.278542 -287.104232)
		(end 90.22969 -287.28924)
		(width 0.0889)
		(layer "In11.Cu")
		(net "UPI_CPU1_CPU0_P2P2_DN<6>")
	)
	(arc
		(start 351.606612 -286.466788)
		(mid 351.554342 -286.284423)
		(end 351.419414 -286.151066)
		(width 0.0889)
		(layer "In11.Cu")
		(net "UPI_CPU1_CPU0_P2P2_DN<6>")
	)
	(arc
		(start 353.307904 -281.911298)
		(mid 353.486501 -281.59202)
		(end 353.307904 -281.272742)
		(width 0.0889)
		(layer "In11.Cu")
		(net "UPI_CPU1_CPU0_P2P2_DN<6>")
	)
	(arc
		(start 350.197166 -288.898584)
		(mid 350.277328 -288.626395)
		(end 350.479614 -288.427414)
		(width 0.0889)
		(layer "In11.Cu")
		(net "UPI_CPU1_CPU0_P2P2_DN<6>")
	)
	(arc
		(start 351.606612 -284.847538)
		(mid 351.680528 -284.568036)
		(end 351.882964 -284.361636)
		(width 0.0889)
		(layer "In11.Cu")
		(net "UPI_CPU1_CPU0_P2P2_DN<6>")
	)
	(arc
		(start 353.016312 -282.405836)
		(mid 353.090303 -282.12627)
		(end 353.292918 -281.919934)
		(width 0.0889)
		(layer "In11.Cu")
		(net "UPI_CPU1_CPU0_P2P2_DN<6>")
	)
	(arc
		(start 353.486212 -278.322278)
		(mid 353.565353 -278.047655)
		(end 353.76866 -277.84679)
		(width 0.0889)
		(layer "In11.Cu")
		(net "UPI_CPU1_CPU0_P2P2_DN<6>")
	)
	(arc
		(start 90.22969 -285.672784)
		(mid 90.282374 -285.853407)
		(end 90.416126 -285.985712)
		(width 0.0889)
		(layer "In11.Cu")
		(net "UPI_CPU1_CPU0_P2P2_DN<6>")
	)
	(arc
		(start 352.83775 -282.725114)
		(mid 352.965004 -282.595148)
		(end 353.016058 -282.420568)
		(width 0.0889)
		(layer "In11.Cu")
		(net "UPI_CPU1_CPU0_P2P2_DN<6>")
	)
	(arc
		(start 350.95815 -287.608518)
		(mid 351.089064 -287.472158)
		(end 351.136712 -287.28924)
		(width 0.0889)
		(layer "In11.Cu")
		(net "UPI_CPU1_CPU0_P2P2_DN<6>")
	)
	(arc
		(start 353.956112 -277.512526)
		(mid 354.034223 -277.235577)
		(end 354.23856 -277.032974)
		(width 0.0889)
		(layer "In11.Cu")
		(net "UPI_CPU1_CPU0_P2P2_DN<6>")
	)
	(arc
		(start 90.69959 -286.49041)
		(mid 90.624002 -286.757866)
		(end 90.430096 -286.957008)
		(width 0.0889)
		(layer "In11.Cu")
		(net "UPI_CPU1_CPU0_P2P2_DN<6>")
	)
	(arc
		(start 353.016058 -282.420568)
		(mid 353.016255 -282.413203)
		(end 353.016312 -282.405836)
		(width 0.0889)
		(layer "In11.Cu")
		(net "UPI_CPU1_CPU0_P2P2_DN<6>")
	)
	(arc
		(start 353.77755 -277.84171)
		(mid 353.904804 -277.711744)
		(end 353.955858 -277.537164)
		(width 0.0889)
		(layer "In11.Cu")
		(net "UPI_CPU1_CPU0_P2P2_DN<6>")
	)
	(arc
		(start 352.076512 -284.023816)
		(mid 352.154623 -283.746867)
		(end 352.35896 -283.544264)
		(width 0.0889)
		(layer "In11.Cu")
		(net "UPI_CPU1_CPU0_P2P2_DN<6>")
	)
	(arc
		(start 90.886788 -284.52318)
		(mid 90.751743 -284.656904)
		(end 90.69959 -284.839664)
		(width 0.0889)
		(layer "In11.Cu")
		(net "UPI_CPU1_CPU0_P2P2_DN<6>")
	)
	(arc
		(start 351.419414 -286.799782)
		(mid 351.554347 -286.666428)
		(end 351.606612 -286.48406)
		(width 0.0889)
		(layer "In11.Cu")
		(net "UPI_CPU1_CPU0_P2P2_DN<6>")
	)
	(arc
		(start 351.419414 -286.151066)
		(mid 351.215933 -285.950262)
		(end 351.136712 -285.675578)
		(width 0.0889)
		(layer "In11.Cu")
		(net "UPI_CPU1_CPU0_P2P2_DN<6>")
	)
	(arc
		(start 90.430604 -285.994094)
		(mid 90.62225 -286.189888)
		(end 90.699336 -286.452818)
		(width 0.0889)
		(layer "In11.Cu")
		(net "UPI_CPU1_CPU0_P2P2_DN<6>")
	)
	(arc
		(start 353.777804 -279.469596)
		(mid 353.956401 -279.150318)
		(end 353.777804 -278.83104)
		(width 0.0889)
		(layer "In11.Cu")
		(net "UPI_CPU1_CPU0_P2P2_DN<6>")
	)
	(arc
		(start 91.639136 -283.198062)
		(mid 91.639371 -283.20911)
		(end 91.63939 -283.22016)
		(width 0.0889)
		(layer "In11.Cu")
		(net "UPI_CPU1_CPU0_P2P2_DN<6>")
	)
	(arc
		(start 352.546412 -283.205682)
		(mid 352.625553 -282.931059)
		(end 352.82886 -282.730194)
		(width 0.0889)
		(layer "In11.Cu")
		(net "UPI_CPU1_CPU0_P2P2_DN<6>")
	)
	(arc
		(start 350.012762 -289.277806)
		(mid 350.122158 -289.193709)
		(end 350.197166 -289.077908)
		(width 0.0889)
		(layer "In11.Cu")
		(net "UPI_CPU1_CPU0_P2P2_DN<6>")
	)
	(arc
		(start 89.477088 -288.592514)
		(mid 89.344086 -288.722482)
		(end 89.28989 -288.900362)
		(width 0.0889)
		(layer "In11.Cu")
		(net "UPI_CPU1_CPU0_P2P2_DN<6>")
	)
	(arc
		(start 353.955858 -277.537164)
		(mid 353.956055 -277.529799)
		(end 353.956112 -277.522432)
		(width 0.0889)
		(layer "In11.Cu")
		(net "UPI_CPU1_CPU0_P2P2_DN<6>")
	)
	(arc
		(start 90.69959 -284.847538)
		(mid 90.627782 -285.123234)
		(end 90.430604 -285.328868)
		(width 0.0889)
		(layer "In11.Cu")
		(net "UPI_CPU1_CPU0_P2P2_DN<6>")
	)
	(arc
		(start 89.946988 -287.778444)
		(mid 89.811878 -287.912278)
		(end 89.75979 -288.095182)
		(width 0.0889)
		(layer "In11.Cu")
		(net "UPI_CPU1_CPU0_P2P2_DN<6>")
	)
	(arc
		(start 351.89795 -284.353)
		(mid 352.028864 -284.21664)
		(end 352.076512 -284.033722)
		(width 0.0889)
		(layer "In11.Cu")
		(net "UPI_CPU1_CPU0_P2P2_DN<6>")
	)
	(arc
		(start 91.16949 -284.033722)
		(mid 91.096798 -284.310927)
		(end 90.897456 -284.51683)
		(width 0.0889)
		(layer "In11.Cu")
		(net "UPI_CPU1_CPU0_P2P2_DN<6>")
	)
	(arc
		(start 353.016312 -280.76398)
		(mid 353.095531 -280.489295)
		(end 353.299014 -280.288492)
		(width 0.0889)
		(layer "In11.Cu")
		(net "UPI_CPU1_CPU0_P2P2_DN<6>")
	)
	(arc
		(start 351.42805 -285.166816)
		(mid 351.558964 -285.030456)
		(end 351.606612 -284.847538)
		(width 0.0889)
		(layer "In11.Cu")
		(net "UPI_CPU1_CPU0_P2P2_DN<6>")
	)
	(arc
		(start 349.727012 -289.609784)
		(mid 349.734168 -289.590223)
		(end 349.741998 -289.570922)
		(width 0.0889)
		(layer "In11.Cu")
		(net "UPI_CPU1_CPU0_P2P2_DN<6>")
	)
	(arc
		(start 91.411806 -282.766516)
		(mid 91.574488 -282.956462)
		(end 91.639136 -283.198062)
		(width 0.0889)
		(layer "In11.Cu")
		(net "UPI_CPU1_CPU0_P2P2_DN<6>")
	)
	(arc
		(start 351.136712 -285.651448)
		(mid 351.214823 -285.374499)
		(end 351.41916 -285.171896)
		(width 0.0889)
		(layer "In11.Cu")
		(net "UPI_CPU1_CPU0_P2P2_DN<6>")
	)
	(arc
		(start 353.307904 -280.283412)
		(mid 353.438818 -280.147052)
		(end 353.486466 -279.964134)
		(width 0.0889)
		(layer "In11.Cu")
		(net "UPI_CPU1_CPU0_P2P2_DN<6>")
	)
	(arc
		(start 354.248974 -277.026878)
		(mid 354.483854 -276.958343)
		(end 354.725732 -276.995382)
		(width 0.0889)
		(layer "In11.Cu")
		(net "UPI_CPU1_CPU0_P2P2_DN<6>")
	)
	(arc
		(start 353.756722 -278.818848)
		(mid 353.558494 -278.613)
		(end 353.486212 -278.336502)
		(width 0.0889)
		(layer "In11.Cu")
		(net "UPI_CPU1_CPU0_P2P2_DN<6>")
	)
	(arc
		(start 91.63939 -283.22016)
		(mid 91.566636 -283.497221)
		(end 91.367356 -283.703014)
		(width 0.0889)
		(layer "In11.Cu")
		(net "UPI_CPU1_CPU0_P2P2_DN<6>")
	)
	(arc
		(start 349.741998 -289.570922)
		(mid 349.852255 -289.401162)
		(end 350.012762 -289.277806)
		(width 0.0889)
		(layer "In11.Cu")
		(net "UPI_CPU1_CPU0_P2P2_DN<6>")
	)
	(arc
		(start 90.699336 -286.452818)
		(mid 90.699775 -286.471612)
		(end 90.69959 -286.49041)
		(width 0.0889)
		(layer "In11.Cu")
		(net "UPI_CPU1_CPU0_P2P2_DN<6>")
	)
	(arc
		(start 89.75979 -288.103056)
		(mid 89.687098 -288.380261)
		(end 89.487756 -288.586164)
		(width 0.0889)
		(layer "In11.Cu")
		(net "UPI_CPU1_CPU0_P2P2_DN<6>")
	)
	(segment
		(start 355.461316 -276.986492)
		(end 355.461316 -277.522178)
		(width 0.13208)
		(layer "F.Cu")
		(net "UPI_CPU1_CPU0_P2P2_DN<5>")
	)
	(segment
		(start 355.461316 -277.522178)
		(end 355.461062 -277.522432)
		(width 0.13208)
		(layer "F.Cu")
		(net "UPI_CPU1_CPU0_P2P2_DN<5>")
	)
	(segment
		(start 91.074494 -281.05608)
		(end 91.074748 -281.056334)
		(width 0.13208)
		(layer "F.Cu")
		(net "UPI_CPU1_CPU0_P2P2_DN<5>")
	)
	(segment
		(start 91.074748 -281.591766)
		(end 91.074494 -281.59202)
		(width 0.13208)
		(layer "F.Cu")
		(net "UPI_CPU1_CPU0_P2P2_DN<5>")
	)
	(segment
		(start 91.074748 -281.056334)
		(end 91.074748 -281.591766)
		(width 0.13208)
		(layer "F.Cu")
		(net "UPI_CPU1_CPU0_P2P2_DN<5>")
	)
	(segment
		(start 88.142064 -290.729924)
		(end 88.241124 -290.828984)
		(width 0.0889)
		(layer "In11.Cu")
		(net "UPI_CPU1_CPU0_P2P2_DN<5>")
	)
	(segment
		(start 89.947496 -284.52318)
		(end 89.938606 -284.52826)
		(width 0.0889)
		(layer "In11.Cu")
		(net "UPI_CPU1_CPU0_P2P2_DN<5>")
	)
	(segment
		(start 82.234024 -300.249336)
		(end 81.921858 -300.561502)
		(width 0.14732)
		(layer "In11.Cu")
		(net "UPI_CPU1_CPU0_P2P2_DN<5>")
	)
	(segment
		(start 89.477596 -285.336996)
		(end 89.468706 -285.342076)
		(width 0.0889)
		(layer "In11.Cu")
		(net "UPI_CPU1_CPU0_P2P2_DN<5>")
	)
	(segment
		(start 274.778724 -368.799364)
		(end 275.25472 -368.323368)
		(width 0.14732)
		(layer "In11.Cu")
		(net "UPI_CPU1_CPU0_P2P2_DN<5>")
	)
	(segment
		(start 87.889588 -291.767514)
		(end 87.889588 -291.907976)
		(width 0.0889)
		(layer "In11.Cu")
		(net "UPI_CPU1_CPU0_P2P2_DN<5>")
	)
	(segment
		(start 353.29876 -285.171896)
		(end 353.30765 -285.166816)
		(width 0.0889)
		(layer "In11.Cu")
		(net "UPI_CPU1_CPU0_P2P2_DN<5>")
	)
	(segment
		(start 88.241124 -289.899344)
		(end 88.142064 -289.998404)
		(width 0.0889)
		(layer "In11.Cu")
		(net "UPI_CPU1_CPU0_P2P2_DN<5>")
	)
	(segment
		(start 88.350598 -288.917126)
		(end 88.350598 -289.167824)
		(width 0.0889)
		(layer "In11.Cu")
		(net "UPI_CPU1_CPU0_P2P2_DN<5>")
	)
	(segment
		(start 355.180138 -278.660098)
		(end 355.187504 -278.65578)
		(width 0.0889)
		(layer "In11.Cu")
		(net "UPI_CPU1_CPU0_P2P2_DN<5>")
	)
	(segment
		(start 88.53805 -288.592768)
		(end 88.537034 -288.593276)
		(width 0.0889)
		(layer "In11.Cu")
		(net "UPI_CPU1_CPU0_P2P2_DN<5>")
	)
	(segment
		(start 66.251836 -368.335052)
		(end 72.185276 -374.268492)
		(width 0.14732)
		(layer "In11.Cu")
		(net "UPI_CPU1_CPU0_P2P2_DN<5>")
	)
	(segment
		(start 354.23856 -283.544264)
		(end 354.24745 -283.539184)
		(width 0.0889)
		(layer "In11.Cu")
		(net "UPI_CPU1_CPU0_P2P2_DN<5>")
	)
	(segment
		(start 62.051184 -319.091818)
		(end 61.6077 -320.161666)
		(width 0.14732)
		(layer "In11.Cu")
		(net "UPI_CPU1_CPU0_P2P2_DN<5>")
	)
	(segment
		(start 60.87872 -355.36251)
		(end 66.251836 -368.335052)
		(width 0.14732)
		(layer "In11.Cu")
		(net "UPI_CPU1_CPU0_P2P2_DN<5>")
	)
	(segment
		(start 89.476072 -286.965644)
		(end 89.468706 -286.969962)
		(width 0.0889)
		(layer "In11.Cu")
		(net "UPI_CPU1_CPU0_P2P2_DN<5>")
	)
	(segment
		(start 355.172264 -278.66467)
		(end 355.178614 -278.66086)
		(width 0.0889)
		(layer "In11.Cu")
		(net "UPI_CPU1_CPU0_P2P2_DN<5>")
	)
	(segment
		(start 61.6077 -321.417696)
		(end 61.193172 -322.418456)
		(width 0.14732)
		(layer "In11.Cu")
		(net "UPI_CPU1_CPU0_P2P2_DN<5>")
	)
	(segment
		(start 59.157616 -324.454012)
		(end 58.6232 -325.744332)
		(width 0.14732)
		(layer "In11.Cu")
		(net "UPI_CPU1_CPU0_P2P2_DN<5>")
	)
	(segment
		(start 58.6232 -329.28687)
		(end 59.909202 -331.692758)
		(width 0.14732)
		(layer "In11.Cu")
		(net "UPI_CPU1_CPU0_P2P2_DN<5>")
	)
	(segment
		(start 91.169998 -282.405836)
		(end 91.169998 -282.42006)
		(width 0.0889)
		(layer "In11.Cu")
		(net "UPI_CPU1_CPU0_P2P2_DN<5>")
	)
	(segment
		(start 81.921858 -300.561502)
		(end 81.921858 -300.733968)
		(width 0.14732)
		(layer "In11.Cu")
		(net "UPI_CPU1_CPU0_P2P2_DN<5>")
	)
	(segment
		(start 348.118684 -300.195234)
		(end 348.323408 -299.888656)
		(width 0.14732)
		(layer "In11.Cu")
		(net "UPI_CPU1_CPU0_P2P2_DN<5>")
	)
	(segment
		(start 274.313396 -369.059968)
		(end 274.574 -368.799364)
		(width 0.14732)
		(layer "In11.Cu")
		(net "UPI_CPU1_CPU0_P2P2_DN<5>")
	)
	(segment
		(start 65.423796 -315.874654)
		(end 64.06134 -317.23711)
		(width 0.14732)
		(layer "In11.Cu")
		(net "UPI_CPU1_CPU0_P2P2_DN<5>")
	)
	(segment
		(start 351.890076 -287.61309)
		(end 351.89795 -287.608518)
		(width 0.0889)
		(layer "In11.Cu")
		(net "UPI_CPU1_CPU0_P2P2_DN<5>")
	)
	(segment
		(start 350.672654 -290.853368)
		(end 350.90735 -290.618672)
		(width 0.14732)
		(layer "In11.Cu")
		(net "UPI_CPU1_CPU0_P2P2_DN<5>")
	)
	(segment
		(start 339.123274 -307.739542)
		(end 341.128858 -306.908708)
		(width 0.14732)
		(layer "In11.Cu")
		(net "UPI_CPU1_CPU0_P2P2_DN<5>")
	)
	(segment
		(start 275.25472 -348.07144)
		(end 283.532834 -339.793326)
		(width 0.14732)
		(layer "In11.Cu")
		(net "UPI_CPU1_CPU0_P2P2_DN<5>")
	)
	(segment
		(start 80.649826 -301.833534)
		(end 80.340962 -302.142398)
		(width 0.14732)
		(layer "In11.Cu")
		(net "UPI_CPU1_CPU0_P2P2_DN<5>")
	)
	(segment
		(start 88.241124 -291.006784)
		(end 88.142064 -291.105844)
		(width 0.0889)
		(layer "In11.Cu")
		(net "UPI_CPU1_CPU0_P2P2_DN<5>")
	)
	(segment
		(start 88.241124 -289.721544)
		(end 88.241124 -289.899344)
		(width 0.0889)
		(layer "In11.Cu")
		(net "UPI_CPU1_CPU0_P2P2_DN<5>")
	)
	(segment
		(start 67.446652 -315.036708)
		(end 65.423796 -315.874654)
		(width 0.14732)
		(layer "In11.Cu")
		(net "UPI_CPU1_CPU0_P2P2_DN<5>")
	)
	(segment
		(start 343.03335 -306.119784)
		(end 346.953586 -302.199548)
		(width 0.14732)
		(layer "In11.Cu")
		(net "UPI_CPU1_CPU0_P2P2_DN<5>")
	)
	(segment
		(start 88.142064 -291.105844)
		(end 88.142064 -291.515038)
		(width 0.0889)
		(layer "In11.Cu")
		(net "UPI_CPU1_CPU0_P2P2_DN<5>")
	)
	(segment
		(start 80.340962 -302.142398)
		(end 80.340962 -302.314864)
		(width 0.14732)
		(layer "In11.Cu")
		(net "UPI_CPU1_CPU0_P2P2_DN<5>")
	)
	(segment
		(start 349.93453 -297.738546)
		(end 349.93453 -296.394378)
		(width 0.14732)
		(layer "In11.Cu")
		(net "UPI_CPU1_CPU0_P2P2_DN<5>")
	)
	(segment
		(start 89.760044 -284.847538)
		(end 89.760044 -284.857444)
		(width 0.0889)
		(layer "In11.Cu")
		(net "UPI_CPU1_CPU0_P2P2_DN<5>")
	)
	(segment
		(start 88.146128 -289.372294)
		(end 88.146128 -289.626548)
		(width 0.0889)
		(layer "In11.Cu")
		(net "UPI_CPU1_CPU0_P2P2_DN<5>")
	)
	(segment
		(start 354.426266 -281.607514)
		(end 354.426266 -281.576526)
		(width 0.0889)
		(layer "In11.Cu")
		(net "UPI_CPU1_CPU0_P2P2_DN<5>")
	)
	(segment
		(start 349.192342 -298.58843)
		(end 349.397066 -298.282106)
		(width 0.14732)
		(layer "In11.Cu")
		(net "UPI_CPU1_CPU0_P2P2_DN<5>")
	)
	(segment
		(start 354.70846 -282.730194)
		(end 354.71735 -282.725114)
		(width 0.0889)
		(layer "In11.Cu")
		(net "UPI_CPU1_CPU0_P2P2_DN<5>")
	)
	(segment
		(start 354.71735 -282.086558)
		(end 354.70846 -282.081478)
		(width 0.0889)
		(layer "In11.Cu")
		(net "UPI_CPU1_CPU0_P2P2_DN<5>")
	)
	(segment
		(start 275.25472 -368.323368)
		(end 275.25472 -348.07144)
		(width 0.14732)
		(layer "In11.Cu")
		(net "UPI_CPU1_CPU0_P2P2_DN<5>")
	)
	(segment
		(start 355.178614 -278.66086)
		(end 355.180138 -278.660098)
		(width 0.0889)
		(layer "In11.Cu")
		(net "UPI_CPU1_CPU0_P2P2_DN<5>")
	)
	(segment
		(start 346.953586 -302.199548)
		(end 348.158562 -300.396148)
		(width 0.14732)
		(layer "In11.Cu")
		(net "UPI_CPU1_CPU0_P2P2_DN<5>")
	)
	(segment
		(start 354.71735 -280.458926)
		(end 354.70846 -280.453846)
		(width 0.0889)
		(layer "In11.Cu")
		(net "UPI_CPU1_CPU0_P2P2_DN<5>")
	)
	(segment
		(start 162.186366 -388.39521)
		(end 263.759442 -379.818646)
		(width 0.14732)
		(layer "In11.Cu")
		(net "UPI_CPU1_CPU0_P2P2_DN<5>")
	)
	(segment
		(start 90.887296 -281.267662)
		(end 90.878406 -281.272742)
		(width 0.0889)
		(layer "In11.Cu")
		(net "UPI_CPU1_CPU0_P2P2_DN<5>")
	)
	(segment
		(start 286.644334 -338.50453)
		(end 309.953914 -338.50453)
		(width 0.14732)
		(layer "In11.Cu")
		(net "UPI_CPU1_CPU0_P2P2_DN<5>")
	)
	(segment
		(start 349.59798 -298.242228)
		(end 349.93453 -297.738546)
		(width 0.14732)
		(layer "In11.Cu")
		(net "UPI_CPU1_CPU0_P2P2_DN<5>")
	)
	(segment
		(start 283.532834 -339.793326)
		(end 286.644334 -338.50453)
		(width 0.14732)
		(layer "In11.Cu")
		(net "UPI_CPU1_CPU0_P2P2_DN<5>")
	)
	(segment
		(start 349.93453 -295.736518)
		(end 349.93453 -291.590476)
		(width 0.14732)
		(layer "In11.Cu")
		(net "UPI_CPU1_CPU0_P2P2_DN<5>")
	)
	(segment
		(start 81.921858 -300.733968)
		(end 81.61274 -301.043086)
		(width 0.14732)
		(layer "In11.Cu")
		(net "UPI_CPU1_CPU0_P2P2_DN<5>")
	)
	(segment
		(start 355.366066 -278.336502)
		(end 355.366066 -278.314404)
		(width 0.0889)
		(layer "In11.Cu")
		(net "UPI_CPU1_CPU0_P2P2_DN<5>")
	)
	(segment
		(start 348.158562 -300.396148)
		(end 348.118684 -300.195234)
		(width 0.14732)
		(layer "In11.Cu")
		(net "UPI_CPU1_CPU0_P2P2_DN<5>")
	)
	(segment
		(start 274.574 -368.799364)
		(end 274.778724 -368.799364)
		(width 0.14732)
		(layer "In11.Cu")
		(net "UPI_CPU1_CPU0_P2P2_DN<5>")
	)
	(segment
		(start 351.606866 -288.103056)
		(end 351.606866 -288.087562)
		(width 0.0889)
		(layer "In11.Cu")
		(net "UPI_CPU1_CPU0_P2P2_DN<5>")
	)
	(segment
		(start 350.671638 -290.853368)
		(end 350.672654 -290.853368)
		(width 0.14732)
		(layer "In11.Cu")
		(net "UPI_CPU1_CPU0_P2P2_DN<5>")
	)
	(segment
		(start 355.172518 -278.664416)
		(end 355.172264 -278.66467)
		(width 0.0889)
		(layer "In11.Cu")
		(net "UPI_CPU1_CPU0_P2P2_DN<5>")
	)
	(segment
		(start 341.128858 -306.908708)
		(end 343.03335 -306.119784)
		(width 0.14732)
		(layer "In11.Cu")
		(net "UPI_CPU1_CPU0_P2P2_DN<5>")
	)
	(segment
		(start 351.136966 -289.114738)
		(end 351.136966 -288.898584)
		(width 0.0889)
		(layer "In11.Cu")
		(net "UPI_CPU1_CPU0_P2P2_DN<5>")
	)
	(segment
		(start 80.822292 -301.833534)
		(end 80.649826 -301.833534)
		(width 0.14732)
		(layer "In11.Cu")
		(net "UPI_CPU1_CPU0_P2P2_DN<5>")
	)
	(segment
		(start 89.477596 -286.964882)
		(end 89.476072 -286.965644)
		(width 0.0889)
		(layer "In11.Cu")
		(net "UPI_CPU1_CPU0_P2P2_DN<5>")
	)
	(segment
		(start 350.981772 -290.603178)
		(end 351.606612 -289.978338)
		(width 0.0889)
		(layer "In11.Cu")
		(net "UPI_CPU1_CPU0_P2P2_DN<5>")
	)
	(segment
		(start 351.88906 -287.613598)
		(end 351.890076 -287.61309)
		(width 0.0889)
		(layer "In11.Cu")
		(net "UPI_CPU1_CPU0_P2P2_DN<5>")
	)
	(segment
		(start 88.241124 -290.275264)
		(end 88.241124 -290.453064)
		(width 0.0889)
		(layer "In11.Cu")
		(net "UPI_CPU1_CPU0_P2P2_DN<5>")
	)
	(segment
		(start 88.142064 -290.176204)
		(end 88.241124 -290.275264)
		(width 0.0889)
		(layer "In11.Cu")
		(net "UPI_CPU1_CPU0_P2P2_DN<5>")
	)
	(segment
		(start 90.699844 -283.219906)
		(end 90.699844 -283.229812)
		(width 0.0889)
		(layer "In11.Cu")
		(net "UPI_CPU1_CPU0_P2P2_DN<5>")
	)
	(segment
		(start 349.23222 -298.789344)
		(end 349.192342 -298.58843)
		(width 0.14732)
		(layer "In11.Cu")
		(net "UPI_CPU1_CPU0_P2P2_DN<5>")
	)
	(segment
		(start 81.13141 -301.35195)
		(end 81.13141 -301.524416)
		(width 0.14732)
		(layer "In11.Cu")
		(net "UPI_CPU1_CPU0_P2P2_DN<5>")
	)
	(segment
		(start 349.78975 -295.881298)
		(end 349.93453 -295.736518)
		(width 0.14732)
		(layer "In11.Cu")
		(net "UPI_CPU1_CPU0_P2P2_DN<5>")
	)
	(segment
		(start 88.537034 -288.593276)
		(end 88.52916 -288.597848)
		(width 0.0889)
		(layer "In11.Cu")
		(net "UPI_CPU1_CPU0_P2P2_DN<5>")
	)
	(segment
		(start 88.142064 -291.515038)
		(end 87.889588 -291.767514)
		(width 0.0889)
		(layer "In11.Cu")
		(net "UPI_CPU1_CPU0_P2P2_DN<5>")
	)
	(segment
		(start 72.185276 -374.268492)
		(end 95.117158 -383.766822)
		(width 0.14732)
		(layer "In11.Cu")
		(net "UPI_CPU1_CPU0_P2P2_DN<5>")
	)
	(segment
		(start 354.426266 -279.986232)
		(end 354.426266 -279.954228)
		(width 0.0889)
		(layer "In11.Cu")
		(net "UPI_CPU1_CPU0_P2P2_DN<5>")
	)
	(segment
		(start 87.763858 -292.033706)
		(end 87.623396 -292.033706)
		(width 0.0889)
		(layer "In11.Cu")
		(net "UPI_CPU1_CPU0_P2P2_DN<5>")
	)
	(segment
		(start 348.323408 -299.888656)
		(end 348.524322 -299.848778)
		(width 0.14732)
		(layer "In11.Cu")
		(net "UPI_CPU1_CPU0_P2P2_DN<5>")
	)
	(segment
		(start 263.759442 -379.818646)
		(end 273.522948 -370.05514)
		(width 0.14732)
		(layer "In11.Cu")
		(net "UPI_CPU1_CPU0_P2P2_DN<5>")
	)
	(segment
		(start 89.468706 -285.980632)
		(end 89.477596 -285.985712)
		(width 0.0889)
		(layer "In11.Cu")
		(net "UPI_CPU1_CPU0_P2P2_DN<5>")
	)
	(segment
		(start 81.13141 -301.524416)
		(end 80.822292 -301.833534)
		(width 0.14732)
		(layer "In11.Cu")
		(net "UPI_CPU1_CPU0_P2P2_DN<5>")
	)
	(segment
		(start 88.142064 -290.552124)
		(end 88.142064 -290.729924)
		(width 0.0889)
		(layer "In11.Cu")
		(net "UPI_CPU1_CPU0_P2P2_DN<5>")
	)
	(segment
		(start 90.229944 -284.033722)
		(end 90.229944 -284.043628)
		(width 0.0889)
		(layer "In11.Cu")
		(net "UPI_CPU1_CPU0_P2P2_DN<5>")
	)
	(segment
		(start 88.820244 -288.103056)
		(end 88.820244 -288.125154)
		(width 0.0889)
		(layer "In11.Cu")
		(net "UPI_CPU1_CPU0_P2P2_DN<5>")
	)
	(segment
		(start 91.270582 -281.272742)
		(end 91.261692 -281.267662)
		(width 0.0889)
		(layer "In11.Cu")
		(net "UPI_CPU1_CPU0_P2P2_DN<5>")
	)
	(segment
		(start 348.524322 -299.848778)
		(end 349.23222 -298.789344)
		(width 0.14732)
		(layer "In11.Cu")
		(net "UPI_CPU1_CPU0_P2P2_DN<5>")
	)
	(segment
		(start 87.187532 -292.46957)
		(end 87.187532 -292.529514)
		(width 0.0889)
		(layer "In11.Cu")
		(net "UPI_CPU1_CPU0_P2P2_DN<5>")
	)
	(segment
		(start 309.953914 -338.50453)
		(end 318.835278 -329.623166)
		(width 0.14732)
		(layer "In11.Cu")
		(net "UPI_CPU1_CPU0_P2P2_DN<5>")
	)
	(segment
		(start 273.832066 -369.573556)
		(end 274.004532 -369.573556)
		(width 0.14732)
		(layer "In11.Cu")
		(net "UPI_CPU1_CPU0_P2P2_DN<5>")
	)
	(segment
		(start 352.352864 -286.803338)
		(end 352.35896 -286.799782)
		(width 0.0889)
		(layer "In11.Cu")
		(net "UPI_CPU1_CPU0_P2P2_DN<5>")
	)
	(segment
		(start 89.290144 -287.28924)
		(end 89.290144 -287.299146)
		(width 0.0889)
		(layer "In11.Cu")
		(net "UPI_CPU1_CPU0_P2P2_DN<5>")
	)
	(segment
		(start 353.771962 -284.356048)
		(end 353.77755 -284.353)
		(width 0.0889)
		(layer "In11.Cu")
		(net "UPI_CPU1_CPU0_P2P2_DN<5>")
	)
	(segment
		(start 87.187532 -292.529514)
		(end 87.172038 -292.545008)
		(width 0.0889)
		(layer "In11.Cu")
		(net "UPI_CPU1_CPU0_P2P2_DN<5>")
	)
	(segment
		(start 354.426012 -283.219906)
		(end 354.426012 -283.205682)
		(width 0.0889)
		(layer "In11.Cu")
		(net "UPI_CPU1_CPU0_P2P2_DN<5>")
	)
	(segment
		(start 355.593396 -277.882604)
		(end 355.617526 -277.79345)
		(width 0.0889)
		(layer "In11.Cu")
		(net "UPI_CPU1_CPU0_P2P2_DN<5>")
	)
	(segment
		(start 352.546412 -286.475424)
		(end 352.546412 -286.4612)
		(width 0.0889)
		(layer "In11.Cu")
		(net "UPI_CPU1_CPU0_P2P2_DN<5>")
	)
	(segment
		(start 352.35896 -286.799782)
		(end 352.36785 -286.794702)
		(width 0.0889)
		(layer "In11.Cu")
		(net "UPI_CPU1_CPU0_P2P2_DN<5>")
	)
	(segment
		(start 88.241124 -290.453064)
		(end 88.142064 -290.552124)
		(width 0.0889)
		(layer "In11.Cu")
		(net "UPI_CPU1_CPU0_P2P2_DN<5>")
	)
	(segment
		(start 61.193172 -322.418456)
		(end 59.157616 -324.454012)
		(width 0.14732)
		(layer "In11.Cu")
		(net "UPI_CPU1_CPU0_P2P2_DN<5>")
	)
	(segment
		(start 82.715608 -299.940218)
		(end 82.40649 -300.249336)
		(width 0.14732)
		(layer "In11.Cu")
		(net "UPI_CPU1_CPU0_P2P2_DN<5>")
	)
	(segment
		(start 58.6232 -325.744332)
		(end 58.6232 -329.28687)
		(width 0.14732)
		(layer "In11.Cu")
		(net "UPI_CPU1_CPU0_P2P2_DN<5>")
	)
	(segment
		(start 87.889588 -291.907976)
		(end 87.763858 -292.033706)
		(width 0.0889)
		(layer "In11.Cu")
		(net "UPI_CPU1_CPU0_P2P2_DN<5>")
	)
	(segment
		(start 87.172038 -292.545008)
		(end 85.5472 -294.169846)
		(width 0.14732)
		(layer "In11.Cu")
		(net "UPI_CPU1_CPU0_P2P2_DN<5>")
	)
	(segment
		(start 352.82886 -285.985712)
		(end 352.83775 -285.980632)
		(width 0.0889)
		(layer "In11.Cu")
		(net "UPI_CPU1_CPU0_P2P2_DN<5>")
	)
	(segment
		(start 274.313396 -369.264692)
		(end 274.313396 -369.059968)
		(width 0.14732)
		(layer "In11.Cu")
		(net "UPI_CPU1_CPU0_P2P2_DN<5>")
	)
	(segment
		(start 351.419414 -288.427414)
		(end 351.428304 -288.422334)
		(width 0.0889)
		(layer "In11.Cu")
		(net "UPI_CPU1_CPU0_P2P2_DN<5>")
	)
	(segment
		(start 91.387168 -281.59202)
		(end 91.444572 -281.534616)
		(width 0.0889)
		(layer "In11.Cu")
		(net "UPI_CPU1_CPU0_P2P2_DN<5>")
	)
	(segment
		(start 353.292664 -285.175452)
		(end 353.29876 -285.171896)
		(width 0.0889)
		(layer "In11.Cu")
		(net "UPI_CPU1_CPU0_P2P2_DN<5>")
	)
	(segment
		(start 88.241124 -290.828984)
		(end 88.241124 -291.006784)
		(width 0.0889)
		(layer "In11.Cu")
		(net "UPI_CPU1_CPU0_P2P2_DN<5>")
	)
	(segment
		(start 81.61274 -301.043086)
		(end 81.440274 -301.043086)
		(width 0.14732)
		(layer "In11.Cu")
		(net "UPI_CPU1_CPU0_P2P2_DN<5>")
	)
	(segment
		(start 355.617526 -277.79345)
		(end 355.461062 -277.522432)
		(width 0.0889)
		(layer "In11.Cu")
		(net "UPI_CPU1_CPU0_P2P2_DN<5>")
	)
	(segment
		(start 60.87872 -335.562448)
		(end 60.87872 -355.36251)
		(width 0.14732)
		(layer "In11.Cu")
		(net "UPI_CPU1_CPU0_P2P2_DN<5>")
	)
	(segment
		(start 59.909202 -331.692758)
		(end 60.87872 -335.562448)
		(width 0.14732)
		(layer "In11.Cu")
		(net "UPI_CPU1_CPU0_P2P2_DN<5>")
	)
	(segment
		(start 91.074494 -281.59202)
		(end 91.387168 -281.59202)
		(width 0.0889)
		(layer "In11.Cu")
		(net "UPI_CPU1_CPU0_P2P2_DN<5>")
	)
	(segment
		(start 89.483946 -286.961072)
		(end 89.477596 -286.964882)
		(width 0.0889)
		(layer "In11.Cu")
		(net "UPI_CPU1_CPU0_P2P2_DN<5>")
	)
	(segment
		(start 354.232464 -283.54782)
		(end 354.23856 -283.544264)
		(width 0.0889)
		(layer "In11.Cu")
		(net "UPI_CPU1_CPU0_P2P2_DN<5>")
	)
	(segment
		(start 349.93453 -296.394378)
		(end 349.78975 -296.249598)
		(width 0.14732)
		(layer "In11.Cu")
		(net "UPI_CPU1_CPU0_P2P2_DN<5>")
	)
	(segment
		(start 90.878406 -281.911298)
		(end 90.887296 -281.916378)
		(width 0.0889)
		(layer "In11.Cu")
		(net "UPI_CPU1_CPU0_P2P2_DN<5>")
	)
	(segment
		(start 89.007696 -287.778698)
		(end 88.998806 -287.783778)
		(width 0.0889)
		(layer "In11.Cu")
		(net "UPI_CPU1_CPU0_P2P2_DN<5>")
	)
	(segment
		(start 351.606612 -289.978338)
		(end 351.606612 -289.645852)
		(width 0.0889)
		(layer "In11.Cu")
		(net "UPI_CPU1_CPU0_P2P2_DN<5>")
	)
	(segment
		(start 273.522948 -370.05514)
		(end 273.522948 -369.882674)
		(width 0.14732)
		(layer "In11.Cu")
		(net "UPI_CPU1_CPU0_P2P2_DN<5>")
	)
	(segment
		(start 354.895912 -279.158954)
		(end 354.895912 -279.150318)
		(width 0.0889)
		(layer "In11.Cu")
		(net "UPI_CPU1_CPU0_P2P2_DN<5>")
	)
	(segment
		(start 82.715608 -299.767752)
		(end 82.715608 -299.940218)
		(width 0.14732)
		(layer "In11.Cu")
		(net "UPI_CPU1_CPU0_P2P2_DN<5>")
	)
	(segment
		(start 274.004532 -369.573556)
		(end 274.313396 -369.264692)
		(width 0.14732)
		(layer "In11.Cu")
		(net "UPI_CPU1_CPU0_P2P2_DN<5>")
	)
	(segment
		(start 349.93453 -291.590476)
		(end 350.671638 -290.853368)
		(width 0.14732)
		(layer "In11.Cu")
		(net "UPI_CPU1_CPU0_P2P2_DN<5>")
	)
	(segment
		(start 318.835278 -329.623166)
		(end 319.9638 -326.899016)
		(width 0.14732)
		(layer "In11.Cu")
		(net "UPI_CPU1_CPU0_P2P2_DN<5>")
	)
	(segment
		(start 353.76866 -284.35808)
		(end 353.769422 -284.357572)
		(width 0.0889)
		(layer "In11.Cu")
		(net "UPI_CPU1_CPU0_P2P2_DN<5>")
	)
	(segment
		(start 90.417396 -283.709364)
		(end 90.408506 -283.714444)
		(width 0.0889)
		(layer "In11.Cu")
		(net "UPI_CPU1_CPU0_P2P2_DN<5>")
	)
	(segment
		(start 319.9638 -326.899016)
		(end 339.123274 -307.739542)
		(width 0.14732)
		(layer "In11.Cu")
		(net "UPI_CPU1_CPU0_P2P2_DN<5>")
	)
	(segment
		(start 81.440274 -301.043086)
		(end 81.13141 -301.35195)
		(width 0.14732)
		(layer "In11.Cu")
		(net "UPI_CPU1_CPU0_P2P2_DN<5>")
	)
	(segment
		(start 349.397066 -298.282106)
		(end 349.59798 -298.242228)
		(width 0.14732)
		(layer "In11.Cu")
		(net "UPI_CPU1_CPU0_P2P2_DN<5>")
	)
	(segment
		(start 90.887296 -281.916378)
		(end 90.893392 -281.919934)
		(width 0.0889)
		(layer "In11.Cu")
		(net "UPI_CPU1_CPU0_P2P2_DN<5>")
	)
	(segment
		(start 80.340962 -302.314864)
		(end 80.031844 -302.623982)
		(width 0.14732)
		(layer "In11.Cu")
		(net "UPI_CPU1_CPU0_P2P2_DN<5>")
	)
	(segment
		(start 95.117158 -383.766822)
		(end 126.317502 -388.39521)
		(width 0.14732)
		(layer "In11.Cu")
		(net "UPI_CPU1_CPU0_P2P2_DN<5>")
	)
	(segment
		(start 80.031844 -302.623982)
		(end 79.859378 -302.623982)
		(width 0.14732)
		(layer "In11.Cu")
		(net "UPI_CPU1_CPU0_P2P2_DN<5>")
	)
	(segment
		(start 90.887296 -282.895548)
		(end 90.878406 -282.900628)
		(width 0.0889)
		(layer "In11.Cu")
		(net "UPI_CPU1_CPU0_P2P2_DN<5>")
	)
	(segment
		(start 89.760298 -286.4612)
		(end 89.760298 -286.475424)
		(width 0.0889)
		(layer "In11.Cu")
		(net "UPI_CPU1_CPU0_P2P2_DN<5>")
	)
	(segment
		(start 353.769422 -284.357572)
		(end 353.771962 -284.356048)
		(width 0.0889)
		(layer "In11.Cu")
		(net "UPI_CPU1_CPU0_P2P2_DN<5>")
	)
	(segment
		(start 82.40649 -300.249336)
		(end 82.234024 -300.249336)
		(width 0.14732)
		(layer "In11.Cu")
		(net "UPI_CPU1_CPU0_P2P2_DN<5>")
	)
	(segment
		(start 354.70846 -281.102562)
		(end 354.71735 -281.097482)
		(width 0.0889)
		(layer "In11.Cu")
		(net "UPI_CPU1_CPU0_P2P2_DN<5>")
	)
	(segment
		(start 88.142064 -289.998404)
		(end 88.142064 -290.176204)
		(width 0.0889)
		(layer "In11.Cu")
		(net "UPI_CPU1_CPU0_P2P2_DN<5>")
	)
	(segment
		(start 88.146128 -289.626548)
		(end 88.241124 -289.721544)
		(width 0.0889)
		(layer "In11.Cu")
		(net "UPI_CPU1_CPU0_P2P2_DN<5>")
	)
	(segment
		(start 89.483692 -286.961326)
		(end 89.483946 -286.961072)
		(width 0.0889)
		(layer "In11.Cu")
		(net "UPI_CPU1_CPU0_P2P2_DN<5>")
	)
	(segment
		(start 349.78975 -296.249598)
		(end 349.78975 -295.881298)
		(width 0.14732)
		(layer "In11.Cu")
		(net "UPI_CPU1_CPU0_P2P2_DN<5>")
	)
	(segment
		(start 87.623396 -292.033706)
		(end 87.187532 -292.46957)
		(width 0.0889)
		(layer "In11.Cu")
		(net "UPI_CPU1_CPU0_P2P2_DN<5>")
	)
	(segment
		(start 83.591654 -298.891706)
		(end 82.715608 -299.767752)
		(width 0.14732)
		(layer "In11.Cu")
		(net "UPI_CPU1_CPU0_P2P2_DN<5>")
	)
	(segment
		(start 126.317502 -388.39521)
		(end 162.186366 -388.39521)
		(width 0.14732)
		(layer "In11.Cu")
		(net "UPI_CPU1_CPU0_P2P2_DN<5>")
	)
	(segment
		(start 353.486212 -284.847538)
		(end 353.486212 -284.837632)
		(width 0.0889)
		(layer "In11.Cu")
		(net "UPI_CPU1_CPU0_P2P2_DN<5>")
	)
	(segment
		(start 350.90735 -290.618672)
		(end 350.922844 -290.603178)
		(width 0.0889)
		(layer "In11.Cu")
		(net "UPI_CPU1_CPU0_P2P2_DN<5>")
	)
	(segment
		(start 61.6077 -320.161666)
		(end 61.6077 -321.417696)
		(width 0.14732)
		(layer "In11.Cu")
		(net "UPI_CPU1_CPU0_P2P2_DN<5>")
	)
	(segment
		(start 63.79591 -317.347092)
		(end 62.051184 -319.091818)
		(width 0.14732)
		(layer "In11.Cu")
		(net "UPI_CPU1_CPU0_P2P2_DN<5>")
	)
	(segment
		(start 88.350598 -289.167824)
		(end 88.146128 -289.372294)
		(width 0.0889)
		(layer "In11.Cu")
		(net "UPI_CPU1_CPU0_P2P2_DN<5>")
	)
	(segment
		(start 350.922844 -290.603178)
		(end 350.981772 -290.603178)
		(width 0.0889)
		(layer "In11.Cu")
		(net "UPI_CPU1_CPU0_P2P2_DN<5>")
	)
	(segment
		(start 273.522948 -369.882674)
		(end 273.832066 -369.573556)
		(width 0.14732)
		(layer "In11.Cu")
		(net "UPI_CPU1_CPU0_P2P2_DN<5>")
	)
	(segment
		(start 85.5472 -294.169846)
		(end 83.591654 -298.891706)
		(width 0.14732)
		(layer "In11.Cu")
		(net "UPI_CPU1_CPU0_P2P2_DN<5>")
	)
	(segment
		(start 64.06134 -317.23711)
		(end 63.79591 -317.347092)
		(width 0.14732)
		(layer "In11.Cu")
		(net "UPI_CPU1_CPU0_P2P2_DN<5>")
	)
	(segment
		(start 79.859378 -302.623982)
		(end 67.446652 -315.036708)
		(width 0.14732)
		(layer "In11.Cu")
		(net "UPI_CPU1_CPU0_P2P2_DN<5>")
	)
	(arc
		(start 354.426266 -279.954228)
		(mid 354.504377 -279.677279)
		(end 354.708714 -279.474676)
		(width 0.0889)
		(layer "In11.Cu")
		(net "UPI_CPU1_CPU0_P2P2_DN<5>")
	)
	(arc
		(start 354.895912 -279.150318)
		(mid 354.969903 -278.870752)
		(end 355.172518 -278.664416)
		(width 0.0889)
		(layer "In11.Cu")
		(net "UPI_CPU1_CPU0_P2P2_DN<5>")
	)
	(arc
		(start 90.878406 -281.272742)
		(mid 90.699809 -281.59202)
		(end 90.878406 -281.911298)
		(width 0.0889)
		(layer "In11.Cu")
		(net "UPI_CPU1_CPU0_P2P2_DN<5>")
	)
	(arc
		(start 354.895658 -282.420568)
		(mid 354.895855 -282.413203)
		(end 354.895912 -282.405836)
		(width 0.0889)
		(layer "In11.Cu")
		(net "UPI_CPU1_CPU0_P2P2_DN<5>")
	)
	(arc
		(start 351.606612 -289.645852)
		(mid 351.531607 -289.530393)
		(end 351.422462 -289.446462)
		(width 0.0889)
		(layer "In11.Cu")
		(net "UPI_CPU1_CPU0_P2P2_DN<5>")
	)
	(arc
		(start 89.938606 -284.52826)
		(mid 89.807692 -284.66462)
		(end 89.760044 -284.847538)
		(width 0.0889)
		(layer "In11.Cu")
		(net "UPI_CPU1_CPU0_P2P2_DN<5>")
	)
	(arc
		(start 89.290144 -285.65475)
		(mid 89.290056 -285.662751)
		(end 89.290144 -285.670752)
		(width 0.0889)
		(layer "In11.Cu")
		(net "UPI_CPU1_CPU0_P2P2_DN<5>")
	)
	(arc
		(start 90.408506 -283.714444)
		(mid 90.277592 -283.850804)
		(end 90.229944 -284.033722)
		(width 0.0889)
		(layer "In11.Cu")
		(net "UPI_CPU1_CPU0_P2P2_DN<5>")
	)
	(arc
		(start 354.426012 -283.205682)
		(mid 354.505153 -282.931059)
		(end 354.70846 -282.730194)
		(width 0.0889)
		(layer "In11.Cu")
		(net "UPI_CPU1_CPU0_P2P2_DN<5>")
	)
	(arc
		(start 351.606866 -288.087562)
		(mid 351.686236 -287.813828)
		(end 351.88906 -287.613598)
		(width 0.0889)
		(layer "In11.Cu")
		(net "UPI_CPU1_CPU0_P2P2_DN<5>")
	)
	(arc
		(start 88.820244 -288.125154)
		(mid 88.739333 -288.395282)
		(end 88.53805 -288.592768)
		(width 0.0889)
		(layer "In11.Cu")
		(net "UPI_CPU1_CPU0_P2P2_DN<5>")
	)
	(arc
		(start 89.290144 -287.299146)
		(mid 89.212033 -287.576095)
		(end 89.007696 -287.778698)
		(width 0.0889)
		(layer "In11.Cu")
		(net "UPI_CPU1_CPU0_P2P2_DN<5>")
	)
	(arc
		(start 354.426266 -281.576526)
		(mid 354.505636 -281.302792)
		(end 354.70846 -281.102562)
		(width 0.0889)
		(layer "In11.Cu")
		(net "UPI_CPU1_CPU0_P2P2_DN<5>")
	)
	(arc
		(start 352.546412 -286.4612)
		(mid 352.625553 -286.186577)
		(end 352.82886 -285.985712)
		(width 0.0889)
		(layer "In11.Cu")
		(net "UPI_CPU1_CPU0_P2P2_DN<5>")
	)
	(arc
		(start 354.71735 -282.725114)
		(mid 354.844604 -282.595148)
		(end 354.895658 -282.420568)
		(width 0.0889)
		(layer "In11.Cu")
		(net "UPI_CPU1_CPU0_P2P2_DN<5>")
	)
	(arc
		(start 353.486212 -284.837632)
		(mid 353.564323 -284.560683)
		(end 353.76866 -284.35808)
		(width 0.0889)
		(layer "In11.Cu")
		(net "UPI_CPU1_CPU0_P2P2_DN<5>")
	)
	(arc
		(start 354.70846 -282.081478)
		(mid 354.505637 -281.881247)
		(end 354.426266 -281.607514)
		(width 0.0889)
		(layer "In11.Cu")
		(net "UPI_CPU1_CPU0_P2P2_DN<5>")
	)
	(arc
		(start 353.77755 -284.353)
		(mid 353.908464 -284.21664)
		(end 353.956112 -284.033722)
		(width 0.0889)
		(layer "In11.Cu")
		(net "UPI_CPU1_CPU0_P2P2_DN<5>")
	)
	(arc
		(start 354.24745 -283.539184)
		(mid 354.378364 -283.402824)
		(end 354.426012 -283.219906)
		(width 0.0889)
		(layer "In11.Cu")
		(net "UPI_CPU1_CPU0_P2P2_DN<5>")
	)
	(arc
		(start 88.52916 -288.597848)
		(mid 88.398246 -288.734208)
		(end 88.350598 -288.917126)
		(width 0.0889)
		(layer "In11.Cu")
		(net "UPI_CPU1_CPU0_P2P2_DN<5>")
	)
	(arc
		(start 90.229944 -284.043628)
		(mid 90.151833 -284.320577)
		(end 89.947496 -284.52318)
		(width 0.0889)
		(layer "In11.Cu")
		(net "UPI_CPU1_CPU0_P2P2_DN<5>")
	)
	(arc
		(start 90.699844 -283.229812)
		(mid 90.621733 -283.506761)
		(end 90.417396 -283.709364)
		(width 0.0889)
		(layer "In11.Cu")
		(net "UPI_CPU1_CPU0_P2P2_DN<5>")
	)
	(arc
		(start 352.83775 -285.980632)
		(mid 352.968664 -285.844272)
		(end 353.016312 -285.661354)
		(width 0.0889)
		(layer "In11.Cu")
		(net "UPI_CPU1_CPU0_P2P2_DN<5>")
	)
	(arc
		(start 91.444572 -281.534616)
		(mid 91.386416 -281.384503)
		(end 91.270582 -281.272742)
		(width 0.0889)
		(layer "In11.Cu")
		(net "UPI_CPU1_CPU0_P2P2_DN<5>")
	)
	(arc
		(start 352.076512 -287.28924)
		(mid 352.150428 -287.009738)
		(end 352.352864 -286.803338)
		(width 0.0889)
		(layer "In11.Cu")
		(net "UPI_CPU1_CPU0_P2P2_DN<5>")
	)
	(arc
		(start 89.477596 -285.985712)
		(mid 89.681077 -286.186516)
		(end 89.760298 -286.4612)
		(width 0.0889)
		(layer "In11.Cu")
		(net "UPI_CPU1_CPU0_P2P2_DN<5>")
	)
	(arc
		(start 354.895658 -280.763472)
		(mid 354.844604 -280.588892)
		(end 354.71735 -280.458926)
		(width 0.0889)
		(layer "In11.Cu")
		(net "UPI_CPU1_CPU0_P2P2_DN<5>")
	)
	(arc
		(start 351.136966 -288.898584)
		(mid 351.217128 -288.626395)
		(end 351.419414 -288.427414)
		(width 0.0889)
		(layer "In11.Cu")
		(net "UPI_CPU1_CPU0_P2P2_DN<5>")
	)
	(arc
		(start 354.70846 -280.453846)
		(mid 354.507178 -280.256359)
		(end 354.426266 -279.986232)
		(width 0.0889)
		(layer "In11.Cu")
		(net "UPI_CPU1_CPU0_P2P2_DN<5>")
	)
	(arc
		(start 351.422462 -289.446462)
		(mid 351.24833 -289.307615)
		(end 351.136966 -289.114738)
		(width 0.0889)
		(layer "In11.Cu")
		(net "UPI_CPU1_CPU0_P2P2_DN<5>")
	)
	(arc
		(start 89.760298 -286.475424)
		(mid 89.686307 -286.75499)
		(end 89.483692 -286.961326)
		(width 0.0889)
		(layer "In11.Cu")
		(net "UPI_CPU1_CPU0_P2P2_DN<5>")
	)
	(arc
		(start 90.893392 -281.919934)
		(mid 91.095979 -282.126285)
		(end 91.169998 -282.405836)
		(width 0.0889)
		(layer "In11.Cu")
		(net "UPI_CPU1_CPU0_P2P2_DN<5>")
	)
	(arc
		(start 355.576632 -277.895558)
		(mid 355.584954 -277.889003)
		(end 355.593396 -277.882604)
		(width 0.0889)
		(layer "In11.Cu")
		(net "UPI_CPU1_CPU0_P2P2_DN<5>")
	)
	(arc
		(start 351.89795 -287.608518)
		(mid 352.028864 -287.472158)
		(end 352.076512 -287.28924)
		(width 0.0889)
		(layer "In11.Cu")
		(net "UPI_CPU1_CPU0_P2P2_DN<5>")
	)
	(arc
		(start 91.169998 -282.42006)
		(mid 91.090779 -282.694745)
		(end 90.887296 -282.895548)
		(width 0.0889)
		(layer "In11.Cu")
		(net "UPI_CPU1_CPU0_P2P2_DN<5>")
	)
	(arc
		(start 91.261692 -281.267662)
		(mid 91.074494 -281.217519)
		(end 90.887296 -281.267662)
		(width 0.0889)
		(layer "In11.Cu")
		(net "UPI_CPU1_CPU0_P2P2_DN<5>")
	)
	(arc
		(start 354.708714 -279.474676)
		(mid 354.843647 -279.341322)
		(end 354.895912 -279.158954)
		(width 0.0889)
		(layer "In11.Cu")
		(net "UPI_CPU1_CPU0_P2P2_DN<5>")
	)
	(arc
		(start 89.290144 -285.670752)
		(mid 89.34004 -285.848399)
		(end 89.468706 -285.980632)
		(width 0.0889)
		(layer "In11.Cu")
		(net "UPI_CPU1_CPU0_P2P2_DN<5>")
	)
	(arc
		(start 353.016312 -285.661354)
		(mid 353.090228 -285.381852)
		(end 353.292664 -285.175452)
		(width 0.0889)
		(layer "In11.Cu")
		(net "UPI_CPU1_CPU0_P2P2_DN<5>")
	)
	(arc
		(start 89.760044 -284.857444)
		(mid 89.681933 -285.134393)
		(end 89.477596 -285.336996)
		(width 0.0889)
		(layer "In11.Cu")
		(net "UPI_CPU1_CPU0_P2P2_DN<5>")
	)
	(arc
		(start 352.36785 -286.794702)
		(mid 352.498764 -286.658342)
		(end 352.546412 -286.475424)
		(width 0.0889)
		(layer "In11.Cu")
		(net "UPI_CPU1_CPU0_P2P2_DN<5>")
	)
	(arc
		(start 89.468706 -285.342076)
		(mid 89.339417 -285.475562)
		(end 89.290144 -285.65475)
		(width 0.0889)
		(layer "In11.Cu")
		(net "UPI_CPU1_CPU0_P2P2_DN<5>")
	)
	(arc
		(start 354.895912 -282.405836)
		(mid 354.848233 -282.222936)
		(end 354.71735 -282.086558)
		(width 0.0889)
		(layer "In11.Cu")
		(net "UPI_CPU1_CPU0_P2P2_DN<5>")
	)
	(arc
		(start 354.895912 -280.778204)
		(mid 354.89586 -280.770837)
		(end 354.895658 -280.763472)
		(width 0.0889)
		(layer "In11.Cu")
		(net "UPI_CPU1_CPU0_P2P2_DN<5>")
	)
	(arc
		(start 353.956112 -284.033722)
		(mid 354.030028 -283.75422)
		(end 354.232464 -283.54782)
		(width 0.0889)
		(layer "In11.Cu")
		(net "UPI_CPU1_CPU0_P2P2_DN<5>")
	)
	(arc
		(start 88.998806 -287.783778)
		(mid 88.867892 -287.920138)
		(end 88.820244 -288.103056)
		(width 0.0889)
		(layer "In11.Cu")
		(net "UPI_CPU1_CPU0_P2P2_DN<5>")
	)
	(arc
		(start 351.428304 -288.422334)
		(mid 351.559218 -288.285974)
		(end 351.606866 -288.103056)
		(width 0.0889)
		(layer "In11.Cu")
		(net "UPI_CPU1_CPU0_P2P2_DN<5>")
	)
	(arc
		(start 89.468706 -286.969962)
		(mid 89.337792 -287.106322)
		(end 89.290144 -287.28924)
		(width 0.0889)
		(layer "In11.Cu")
		(net "UPI_CPU1_CPU0_P2P2_DN<5>")
	)
	(arc
		(start 90.878406 -282.900628)
		(mid 90.747492 -283.036988)
		(end 90.699844 -283.219906)
		(width 0.0889)
		(layer "In11.Cu")
		(net "UPI_CPU1_CPU0_P2P2_DN<5>")
	)
	(arc
		(start 353.30765 -285.166816)
		(mid 353.438564 -285.030456)
		(end 353.486212 -284.847538)
		(width 0.0889)
		(layer "In11.Cu")
		(net "UPI_CPU1_CPU0_P2P2_DN<5>")
	)
	(arc
		(start 355.366066 -278.314404)
		(mid 355.425935 -278.082157)
		(end 355.576632 -277.895558)
		(width 0.0889)
		(layer "In11.Cu")
		(net "UPI_CPU1_CPU0_P2P2_DN<5>")
	)
	(arc
		(start 354.71735 -281.097482)
		(mid 354.848264 -280.961122)
		(end 354.895912 -280.778204)
		(width 0.0889)
		(layer "In11.Cu")
		(net "UPI_CPU1_CPU0_P2P2_DN<5>")
	)
	(arc
		(start 355.187504 -278.65578)
		(mid 355.318418 -278.51942)
		(end 355.366066 -278.336502)
		(width 0.0889)
		(layer "In11.Cu")
		(net "UPI_CPU1_CPU0_P2P2_DN<5>")
	)
	(segment
		(start 88.255094 -284.311598)
		(end 88.255094 -284.847538)
		(width 0.13208)
		(layer "F.Cu")
		(net "UPI_CPU1_CPU0_P2P2_DN<4>")
	)
	(segment
		(start 357.340662 -276.986492)
		(end 357.340662 -277.522432)
		(width 0.13208)
		(layer "F.Cu")
		(net "UPI_CPU1_CPU0_P2P2_DN<4>")
	)
	(segment
		(start 87.511382 -288.422334)
		(end 87.490554 -288.434272)
		(width 0.0889)
		(layer "In11.Cu")
		(net "UPI_CPU1_CPU0_P2P2_DN<4>")
	)
	(segment
		(start 355.735128 -281.272742)
		(end 355.744018 -281.267662)
		(width 0.0889)
		(layer "In11.Cu")
		(net "UPI_CPU1_CPU0_P2P2_DN<4>")
	)
	(segment
		(start 353.207066 -287.299146)
		(end 353.207066 -287.28924)
		(width 0.0889)
		(layer "In11.Cu")
		(net "UPI_CPU1_CPU0_P2P2_DN<4>")
	)
	(segment
		(start 59.56681 -318.447166)
		(end 58.563764 -319.450212)
		(width 0.14732)
		(layer "In11.Cu")
		(net "UPI_CPU1_CPU0_P2P2_DN<4>")
	)
	(segment
		(start 86.864952 -291.2872)
		(end 86.849458 -291.302694)
		(width 0.0889)
		(layer "In11.Cu")
		(net "UPI_CPU1_CPU0_P2P2_DN<4>")
	)
	(segment
		(start 352.737166 -288.121598)
		(end 352.737166 -288.103056)
		(width 0.0889)
		(layer "In11.Cu")
		(net "UPI_CPU1_CPU0_P2P2_DN<4>")
	)
	(segment
		(start 65.3161 -313.998102)
		(end 64.097408 -315.21654)
		(width 0.14732)
		(layer "In11.Cu")
		(net "UPI_CPU1_CPU0_P2P2_DN<4>")
	)
	(segment
		(start 276.35708 -369.20297)
		(end 276.35708 -348.528386)
		(width 0.14732)
		(layer "In11.Cu")
		(net "UPI_CPU1_CPU0_P2P2_DN<4>")
	)
	(segment
		(start 87.220044 -290.991036)
		(end 86.92388 -291.2872)
		(width 0.0889)
		(layer "In11.Cu")
		(net "UPI_CPU1_CPU0_P2P2_DN<4>")
	)
	(segment
		(start 67.74688 -312.9915)
		(end 65.3161 -313.998102)
		(width 0.14732)
		(layer "In11.Cu")
		(net "UPI_CPU1_CPU0_P2P2_DN<4>")
	)
	(segment
		(start 57.43956 -324.526656)
		(end 57.43956 -330.237592)
		(width 0.14732)
		(layer "In11.Cu")
		(net "UPI_CPU1_CPU0_P2P2_DN<4>")
	)
	(segment
		(start 87.689944 -288.09315)
		(end 87.689944 -288.103056)
		(width 0.0889)
		(layer "In11.Cu")
		(net "UPI_CPU1_CPU0_P2P2_DN<4>")
	)
	(segment
		(start 94.75724 -384.834638)
		(end 127.080518 -389.62965)
		(width 0.14732)
		(layer "In11.Cu")
		(net "UPI_CPU1_CPU0_P2P2_DN<4>")
	)
	(segment
		(start 355.086666 -284.033722)
		(end 355.086666 -284.025086)
		(width 0.0889)
		(layer "In11.Cu")
		(net "UPI_CPU1_CPU0_P2P2_DN<4>")
	)
	(segment
		(start 354.80244 -284.524196)
		(end 354.81006 -284.519624)
		(width 0.0889)
		(layer "In11.Cu")
		(net "UPI_CPU1_CPU0_P2P2_DN<4>")
	)
	(segment
		(start 58.276744 -323.520308)
		(end 58.15711 -323.809106)
		(width 0.14732)
		(layer "In11.Cu")
		(net "UPI_CPU1_CPU0_P2P2_DN<4>")
	)
	(segment
		(start 264.669016 -380.891288)
		(end 276.35708 -369.20297)
		(width 0.14732)
		(layer "In11.Cu")
		(net "UPI_CPU1_CPU0_P2P2_DN<4>")
	)
	(segment
		(start 88.159844 -287.279334)
		(end 88.159844 -287.28924)
		(width 0.0889)
		(layer "In11.Cu")
		(net "UPI_CPU1_CPU0_P2P2_DN<4>")
	)
	(segment
		(start 59.760358 -335.844134)
		(end 59.760358 -355.583744)
		(width 0.14732)
		(layer "In11.Cu")
		(net "UPI_CPU1_CPU0_P2P2_DN<4>")
	)
	(segment
		(start 59.760358 -355.583744)
		(end 65.293748 -368.942366)
		(width 0.14732)
		(layer "In11.Cu")
		(net "UPI_CPU1_CPU0_P2P2_DN<4>")
	)
	(segment
		(start 58.563764 -319.450212)
		(end 58.276744 -320.143632)
		(width 0.14732)
		(layer "In11.Cu")
		(net "UPI_CPU1_CPU0_P2P2_DN<4>")
	)
	(segment
		(start 353.676966 -286.48533)
		(end 353.676966 -286.466788)
		(width 0.0889)
		(layer "In11.Cu")
		(net "UPI_CPU1_CPU0_P2P2_DN<4>")
	)
	(segment
		(start 353.385628 -286.969962)
		(end 353.394518 -286.964882)
		(width 0.0889)
		(layer "In11.Cu")
		(net "UPI_CPU1_CPU0_P2P2_DN<4>")
	)
	(segment
		(start 356.026212 -279.160224)
		(end 356.026212 -279.150318)
		(width 0.0889)
		(layer "In11.Cu")
		(net "UPI_CPU1_CPU0_P2P2_DN<4>")
	)
	(segment
		(start 355.744018 -281.916378)
		(end 355.735128 -281.911298)
		(width 0.0889)
		(layer "In11.Cu")
		(net "UPI_CPU1_CPU0_P2P2_DN<4>")
	)
	(segment
		(start 339.752686 -308.673246)
		(end 343.659714 -307.054758)
		(width 0.14732)
		(layer "In11.Cu")
		(net "UPI_CPU1_CPU0_P2P2_DN<4>")
	)
	(segment
		(start 319.862962 -330.156566)
		(end 320.989452 -327.43648)
		(width 0.14732)
		(layer "In11.Cu")
		(net "UPI_CPU1_CPU0_P2P2_DN<4>")
	)
	(segment
		(start 355.735128 -282.900628)
		(end 355.744018 -282.895548)
		(width 0.0889)
		(layer "In11.Cu")
		(net "UPI_CPU1_CPU0_P2P2_DN<4>")
	)
	(segment
		(start 88.442292 -286.151066)
		(end 88.451182 -286.156146)
		(width 0.0889)
		(layer "In11.Cu")
		(net "UPI_CPU1_CPU0_P2P2_DN<4>")
	)
	(segment
		(start 354.616512 -284.863032)
		(end 354.616512 -284.847538)
		(width 0.0889)
		(layer "In11.Cu")
		(net "UPI_CPU1_CPU0_P2P2_DN<4>")
	)
	(segment
		(start 355.750114 -281.919934)
		(end 355.744018 -281.916378)
		(width 0.0889)
		(layer "In11.Cu")
		(net "UPI_CPU1_CPU0_P2P2_DN<4>")
	)
	(segment
		(start 87.220044 -285.651448)
		(end 87.220044 -285.679896)
		(width 0.0889)
		(layer "In11.Cu")
		(net "UPI_CPU1_CPU0_P2P2_DN<4>")
	)
	(segment
		(start 356.208838 -278.829008)
		(end 356.210362 -278.827992)
		(width 0.0889)
		(layer "In11.Cu")
		(net "UPI_CPU1_CPU0_P2P2_DN<4>")
	)
	(segment
		(start 354.795074 -284.528514)
		(end 354.799138 -284.526228)
		(width 0.0889)
		(layer "In11.Cu")
		(net "UPI_CPU1_CPU0_P2P2_DN<4>")
	)
	(segment
		(start 286.864552 -339.60689)
		(end 310.412638 -339.60689)
		(width 0.14732)
		(layer "In11.Cu")
		(net "UPI_CPU1_CPU0_P2P2_DN<4>")
	)
	(segment
		(start 352.778822 -290.208208)
		(end 352.736912 -290.166298)
		(width 0.0889)
		(layer "In11.Cu")
		(net "UPI_CPU1_CPU0_P2P2_DN<4>")
	)
	(segment
		(start 320.989452 -327.43648)
		(end 339.752686 -308.673246)
		(width 0.14732)
		(layer "In11.Cu")
		(net "UPI_CPU1_CPU0_P2P2_DN<4>")
	)
	(segment
		(start 87.220044 -288.917126)
		(end 87.220044 -290.991036)
		(width 0.0889)
		(layer "In11.Cu")
		(net "UPI_CPU1_CPU0_P2P2_DN<4>")
	)
	(segment
		(start 352.915728 -287.783778)
		(end 352.924618 -287.778698)
		(width 0.0889)
		(layer "In11.Cu")
		(net "UPI_CPU1_CPU0_P2P2_DN<4>")
	)
	(segment
		(start 352.778822 -290.230306)
		(end 352.778822 -290.208208)
		(width 0.0889)
		(layer "In11.Cu")
		(net "UPI_CPU1_CPU0_P2P2_DN<4>")
	)
	(segment
		(start 352.267266 -289.078416)
		(end 352.267266 -288.917126)
		(width 0.0889)
		(layer "In11.Cu")
		(net "UPI_CPU1_CPU0_P2P2_DN<4>")
	)
	(segment
		(start 86.92388 -291.2872)
		(end 86.864952 -291.2872)
		(width 0.0889)
		(layer "In11.Cu")
		(net "UPI_CPU1_CPU0_P2P2_DN<4>")
	)
	(segment
		(start 61.303916 -316.709806)
		(end 59.56681 -318.446912)
		(width 0.14732)
		(layer "In11.Cu")
		(net "UPI_CPU1_CPU0_P2P2_DN<4>")
	)
	(segment
		(start 88.255094 -284.847538)
		(end 88.09863 -285.118556)
		(width 0.0889)
		(layer "In11.Cu")
		(net "UPI_CPU1_CPU0_P2P2_DN<4>")
	)
	(segment
		(start 88.09863 -285.118556)
		(end 88.009476 -285.142432)
		(width 0.0889)
		(layer "In11.Cu")
		(net "UPI_CPU1_CPU0_P2P2_DN<4>")
	)
	(segment
		(start 355.273864 -283.709364)
		(end 355.274626 -283.708856)
		(width 0.0889)
		(layer "In11.Cu")
		(net "UPI_CPU1_CPU0_P2P2_DN<4>")
	)
	(segment
		(start 71.5899 -375.238518)
		(end 94.75724 -384.834638)
		(width 0.14732)
		(layer "In11.Cu")
		(net "UPI_CPU1_CPU0_P2P2_DN<4>")
	)
	(segment
		(start 356.496366 -278.336502)
		(end 356.496366 -278.327866)
		(width 0.0889)
		(layer "In11.Cu")
		(net "UPI_CPU1_CPU0_P2P2_DN<4>")
	)
	(segment
		(start 355.274626 -283.708856)
		(end 355.27996 -283.705808)
		(width 0.0889)
		(layer "In11.Cu")
		(net "UPI_CPU1_CPU0_P2P2_DN<4>")
	)
	(segment
		(start 87.48014 -288.440622)
		(end 87.480394 -288.44113)
		(width 0.0889)
		(layer "In11.Cu")
		(net "UPI_CPU1_CPU0_P2P2_DN<4>")
	)
	(segment
		(start 354.800662 -284.525212)
		(end 354.80244 -284.524196)
		(width 0.0889)
		(layer "In11.Cu")
		(net "UPI_CPU1_CPU0_P2P2_DN<4>")
	)
	(segment
		(start 352.445828 -288.597848)
		(end 352.454718 -288.592768)
		(width 0.0889)
		(layer "In11.Cu")
		(net "UPI_CPU1_CPU0_P2P2_DN<4>")
	)
	(segment
		(start 87.490554 -288.434272)
		(end 87.489284 -288.435034)
		(width 0.0889)
		(layer "In11.Cu")
		(net "UPI_CPU1_CPU0_P2P2_DN<4>")
	)
	(segment
		(start 357.027988 -277.522432)
		(end 357.340662 -277.522432)
		(width 0.0889)
		(layer "In11.Cu")
		(net "UPI_CPU1_CPU0_P2P2_DN<4>")
	)
	(segment
		(start 356.204774 -278.831294)
		(end 356.208838 -278.829008)
		(width 0.0889)
		(layer "In11.Cu")
		(net "UPI_CPU1_CPU0_P2P2_DN<4>")
	)
	(segment
		(start 354.325428 -285.342076)
		(end 354.334318 -285.336996)
		(width 0.0889)
		(layer "In11.Cu")
		(net "UPI_CPU1_CPU0_P2P2_DN<4>")
	)
	(segment
		(start 351.090484 -292.199314)
		(end 352.778822 -290.510976)
		(width 0.14732)
		(layer "In11.Cu")
		(net "UPI_CPU1_CPU0_P2P2_DN<4>")
	)
	(segment
		(start 352.778822 -290.510976)
		(end 352.778822 -290.230306)
		(width 0.14732)
		(layer "In11.Cu")
		(net "UPI_CPU1_CPU0_P2P2_DN<4>")
	)
	(segment
		(start 354.799138 -284.526228)
		(end 354.800662 -284.525212)
		(width 0.0889)
		(layer "In11.Cu")
		(net "UPI_CPU1_CPU0_P2P2_DN<4>")
	)
	(segment
		(start 310.412638 -339.60689)
		(end 319.862962 -330.156566)
		(width 0.14732)
		(layer "In11.Cu")
		(net "UPI_CPU1_CPU0_P2P2_DN<4>")
	)
	(segment
		(start 86.849458 -291.302694)
		(end 84.595462 -293.55669)
		(width 0.14732)
		(layer "In11.Cu")
		(net "UPI_CPU1_CPU0_P2P2_DN<4>")
	)
	(segment
		(start 58.276744 -320.143632)
		(end 58.276744 -323.520308)
		(width 0.14732)
		(layer "In11.Cu")
		(net "UPI_CPU1_CPU0_P2P2_DN<4>")
	)
	(segment
		(start 356.96271 -277.58771)
		(end 357.027988 -277.522432)
		(width 0.0889)
		(layer "In11.Cu")
		(net "UPI_CPU1_CPU0_P2P2_DN<4>")
	)
	(segment
		(start 58.15711 -323.809106)
		(end 57.43956 -324.526656)
		(width 0.14732)
		(layer "In11.Cu")
		(net "UPI_CPU1_CPU0_P2P2_DN<4>")
	)
	(segment
		(start 354.146866 -285.675578)
		(end 354.146866 -285.661354)
		(width 0.0889)
		(layer "In11.Cu")
		(net "UPI_CPU1_CPU0_P2P2_DN<4>")
	)
	(segment
		(start 64.097408 -315.21654)
		(end 61.303916 -316.709806)
		(width 0.14732)
		(layer "In11.Cu")
		(net "UPI_CPU1_CPU0_P2P2_DN<4>")
	)
	(segment
		(start 343.659714 -307.054758)
		(end 348.276926 -302.437546)
		(width 0.14732)
		(layer "In11.Cu")
		(net "UPI_CPU1_CPU0_P2P2_DN<4>")
	)
	(segment
		(start 356.204774 -278.83104)
		(end 356.204774 -278.831294)
		(width 0.0889)
		(layer "In11.Cu")
		(net "UPI_CPU1_CPU0_P2P2_DN<4>")
	)
	(segment
		(start 88.443054 -286.799274)
		(end 88.442292 -286.799782)
		(width 0.0889)
		(layer "In11.Cu")
		(net "UPI_CPU1_CPU0_P2P2_DN<4>")
	)
	(segment
		(start 356.026466 -280.778204)
		(end 356.026466 -280.770584)
		(width 0.0889)
		(layer "In11.Cu")
		(net "UPI_CPU1_CPU0_P2P2_DN<4>")
	)
	(segment
		(start 355.744018 -281.267662)
		(end 355.750114 -281.264106)
		(width 0.0889)
		(layer "In11.Cu")
		(net "UPI_CPU1_CPU0_P2P2_DN<4>")
	)
	(segment
		(start 354.795074 -284.52826)
		(end 354.795074 -284.528514)
		(width 0.0889)
		(layer "In11.Cu")
		(net "UPI_CPU1_CPU0_P2P2_DN<4>")
	)
	(segment
		(start 284.156912 -340.728554)
		(end 286.864552 -339.60689)
		(width 0.14732)
		(layer "In11.Cu")
		(net "UPI_CPU1_CPU0_P2P2_DN<4>")
	)
	(segment
		(start 348.276926 -302.437546)
		(end 351.090484 -298.226734)
		(width 0.14732)
		(layer "In11.Cu")
		(net "UPI_CPU1_CPU0_P2P2_DN<4>")
	)
	(segment
		(start 59.56681 -318.446912)
		(end 59.56681 -318.447166)
		(width 0.14732)
		(layer "In11.Cu")
		(net "UPI_CPU1_CPU0_P2P2_DN<4>")
	)
	(segment
		(start 161.179002 -389.62965)
		(end 264.669016 -380.891288)
		(width 0.14732)
		(layer "In11.Cu")
		(net "UPI_CPU1_CPU0_P2P2_DN<4>")
	)
	(segment
		(start 276.35708 -348.528386)
		(end 284.156912 -340.728554)
		(width 0.14732)
		(layer "In11.Cu")
		(net "UPI_CPU1_CPU0_P2P2_DN<4>")
	)
	(segment
		(start 65.293748 -368.942366)
		(end 71.5899 -375.238518)
		(width 0.14732)
		(layer "In11.Cu")
		(net "UPI_CPU1_CPU0_P2P2_DN<4>")
	)
	(segment
		(start 84.595462 -293.55669)
		(end 82.76717 -297.97121)
		(width 0.14732)
		(layer "In11.Cu")
		(net "UPI_CPU1_CPU0_P2P2_DN<4>")
	)
	(segment
		(start 127.080518 -389.62965)
		(end 161.179002 -389.62965)
		(width 0.14732)
		(layer "In11.Cu")
		(net "UPI_CPU1_CPU0_P2P2_DN<4>")
	)
	(segment
		(start 356.026466 -282.42006)
		(end 356.026466 -282.405836)
		(width 0.0889)
		(layer "In11.Cu")
		(net "UPI_CPU1_CPU0_P2P2_DN<4>")
	)
	(segment
		(start 352.736912 -290.166298)
		(end 352.736912 -289.60953)
		(width 0.0889)
		(layer "In11.Cu")
		(net "UPI_CPU1_CPU0_P2P2_DN<4>")
	)
	(segment
		(start 356.210362 -278.827992)
		(end 356.21214 -278.826976)
		(width 0.0889)
		(layer "In11.Cu")
		(net "UPI_CPU1_CPU0_P2P2_DN<4>")
	)
	(segment
		(start 88.451182 -286.794702)
		(end 88.443054 -286.799274)
		(width 0.0889)
		(layer "In11.Cu")
		(net "UPI_CPU1_CPU0_P2P2_DN<4>")
	)
	(segment
		(start 355.556566 -279.97277)
		(end 355.556566 -279.955498)
		(width 0.0889)
		(layer "In11.Cu")
		(net "UPI_CPU1_CPU0_P2P2_DN<4>")
	)
	(segment
		(start 87.981282 -287.608518)
		(end 87.972392 -287.613598)
		(width 0.0889)
		(layer "In11.Cu")
		(net "UPI_CPU1_CPU0_P2P2_DN<4>")
	)
	(segment
		(start 356.21214 -278.826976)
		(end 356.21976 -278.822404)
		(width 0.0889)
		(layer "In11.Cu")
		(net "UPI_CPU1_CPU0_P2P2_DN<4>")
	)
	(segment
		(start 82.76717 -297.97121)
		(end 67.74688 -312.9915)
		(width 0.14732)
		(layer "In11.Cu")
		(net "UPI_CPU1_CPU0_P2P2_DN<4>")
	)
	(segment
		(start 351.090484 -298.226734)
		(end 351.090484 -292.199314)
		(width 0.14732)
		(layer "In11.Cu")
		(net "UPI_CPU1_CPU0_P2P2_DN<4>")
	)
	(segment
		(start 57.43956 -330.237592)
		(end 59.760358 -335.844134)
		(width 0.14732)
		(layer "In11.Cu")
		(net "UPI_CPU1_CPU0_P2P2_DN<4>")
	)
	(arc
		(start 353.676966 -286.466788)
		(mid 353.729236 -286.284423)
		(end 353.864164 -286.151066)
		(width 0.0889)
		(layer "In11.Cu")
		(net "UPI_CPU1_CPU0_P2P2_DN<4>")
	)
	(arc
		(start 87.502492 -286.151066)
		(mid 87.785194 -286.226808)
		(end 88.067896 -286.151066)
		(width 0.0889)
		(layer "In11.Cu")
		(net "UPI_CPU1_CPU0_P2P2_DN<4>")
	)
	(arc
		(start 354.146866 -285.661354)
		(mid 354.194545 -285.478454)
		(end 354.325428 -285.342076)
		(width 0.0889)
		(layer "In11.Cu")
		(net "UPI_CPU1_CPU0_P2P2_DN<4>")
	)
	(arc
		(start 356.496366 -278.327866)
		(mid 356.548636 -278.145501)
		(end 356.683564 -278.012144)
		(width 0.0889)
		(layer "In11.Cu")
		(net "UPI_CPU1_CPU0_P2P2_DN<4>")
	)
	(arc
		(start 354.334318 -285.336996)
		(mid 354.537141 -285.136765)
		(end 354.616512 -284.863032)
		(width 0.0889)
		(layer "In11.Cu")
		(net "UPI_CPU1_CPU0_P2P2_DN<4>")
	)
	(arc
		(start 355.743764 -280.288492)
		(mid 355.608831 -280.155138)
		(end 355.556566 -279.97277)
		(width 0.0889)
		(layer "In11.Cu")
		(net "UPI_CPU1_CPU0_P2P2_DN<4>")
	)
	(arc
		(start 352.454718 -288.592768)
		(mid 352.657004 -288.393787)
		(end 352.737166 -288.121598)
		(width 0.0889)
		(layer "In11.Cu")
		(net "UPI_CPU1_CPU0_P2P2_DN<4>")
	)
	(arc
		(start 355.743764 -279.639776)
		(mid 355.948099 -279.437171)
		(end 356.026212 -279.160224)
		(width 0.0889)
		(layer "In11.Cu")
		(net "UPI_CPU1_CPU0_P2P2_DN<4>")
	)
	(arc
		(start 356.026212 -279.150318)
		(mid 356.073891 -278.967418)
		(end 356.204774 -278.83104)
		(width 0.0889)
		(layer "In11.Cu")
		(net "UPI_CPU1_CPU0_P2P2_DN<4>")
	)
	(arc
		(start 352.737166 -288.103056)
		(mid 352.784845 -287.920156)
		(end 352.915728 -287.783778)
		(width 0.0889)
		(layer "In11.Cu")
		(net "UPI_CPU1_CPU0_P2P2_DN<4>")
	)
	(arc
		(start 87.972392 -287.613598)
		(mid 87.768057 -287.816203)
		(end 87.689944 -288.09315)
		(width 0.0889)
		(layer "In11.Cu")
		(net "UPI_CPU1_CPU0_P2P2_DN<4>")
	)
	(arc
		(start 87.502492 -285.171896)
		(mid 87.298157 -285.374501)
		(end 87.220044 -285.651448)
		(width 0.0889)
		(layer "In11.Cu")
		(net "UPI_CPU1_CPU0_P2P2_DN<4>")
	)
	(arc
		(start 87.220044 -285.679896)
		(mid 87.300206 -285.952085)
		(end 87.502492 -286.151066)
		(width 0.0889)
		(layer "In11.Cu")
		(net "UPI_CPU1_CPU0_P2P2_DN<4>")
	)
	(arc
		(start 352.267266 -288.917126)
		(mid 352.314945 -288.734226)
		(end 352.445828 -288.597848)
		(width 0.0889)
		(layer "In11.Cu")
		(net "UPI_CPU1_CPU0_P2P2_DN<4>")
	)
	(arc
		(start 353.207066 -287.28924)
		(mid 353.254745 -287.10634)
		(end 353.385628 -286.969962)
		(width 0.0889)
		(layer "In11.Cu")
		(net "UPI_CPU1_CPU0_P2P2_DN<4>")
	)
	(arc
		(start 87.689944 -288.103056)
		(mid 87.642265 -288.285956)
		(end 87.511382 -288.422334)
		(width 0.0889)
		(layer "In11.Cu")
		(net "UPI_CPU1_CPU0_P2P2_DN<4>")
	)
	(arc
		(start 87.489284 -288.435034)
		(mid 87.484699 -288.437806)
		(end 87.48014 -288.440622)
		(width 0.0889)
		(layer "In11.Cu")
		(net "UPI_CPU1_CPU0_P2P2_DN<4>")
	)
	(arc
		(start 356.026466 -282.405836)
		(mid 355.95255 -282.126334)
		(end 355.750114 -281.919934)
		(width 0.0889)
		(layer "In11.Cu")
		(net "UPI_CPU1_CPU0_P2P2_DN<4>")
	)
	(arc
		(start 355.556566 -283.219906)
		(mid 355.556618 -283.212539)
		(end 355.55682 -283.205174)
		(width 0.0889)
		(layer "In11.Cu")
		(net "UPI_CPU1_CPU0_P2P2_DN<4>")
	)
	(arc
		(start 88.442292 -286.799782)
		(mid 88.237957 -287.002387)
		(end 88.159844 -287.279334)
		(width 0.0889)
		(layer "In11.Cu")
		(net "UPI_CPU1_CPU0_P2P2_DN<4>")
	)
	(arc
		(start 356.959916 -277.6093)
		(mid 356.961416 -277.598518)
		(end 356.96271 -277.58771)
		(width 0.0889)
		(layer "In11.Cu")
		(net "UPI_CPU1_CPU0_P2P2_DN<4>")
	)
	(arc
		(start 353.394518 -286.964882)
		(mid 353.598853 -286.762277)
		(end 353.676966 -286.48533)
		(width 0.0889)
		(layer "In11.Cu")
		(net "UPI_CPU1_CPU0_P2P2_DN<4>")
	)
	(arc
		(start 352.736912 -289.60953)
		(mid 352.625574 -289.41663)
		(end 352.451416 -289.277806)
		(width 0.0889)
		(layer "In11.Cu")
		(net "UPI_CPU1_CPU0_P2P2_DN<4>")
	)
	(arc
		(start 355.27996 -283.705808)
		(mid 355.482547 -283.499457)
		(end 355.556566 -283.219906)
		(width 0.0889)
		(layer "In11.Cu")
		(net "UPI_CPU1_CPU0_P2P2_DN<4>")
	)
	(arc
		(start 353.864164 -286.151066)
		(mid 354.067645 -285.950262)
		(end 354.146866 -285.675578)
		(width 0.0889)
		(layer "In11.Cu")
		(net "UPI_CPU1_CPU0_P2P2_DN<4>")
	)
	(arc
		(start 88.159844 -287.28924)
		(mid 88.112165 -287.47214)
		(end 87.981282 -287.608518)
		(width 0.0889)
		(layer "In11.Cu")
		(net "UPI_CPU1_CPU0_P2P2_DN<4>")
	)
	(arc
		(start 352.924618 -287.778698)
		(mid 353.128953 -287.576093)
		(end 353.207066 -287.299146)
		(width 0.0889)
		(layer "In11.Cu")
		(net "UPI_CPU1_CPU0_P2P2_DN<4>")
	)
	(arc
		(start 355.744018 -282.895548)
		(mid 355.947323 -282.694682)
		(end 356.026466 -282.42006)
		(width 0.0889)
		(layer "In11.Cu")
		(net "UPI_CPU1_CPU0_P2P2_DN<4>")
	)
	(arc
		(start 352.451416 -289.277806)
		(mid 352.342269 -289.193878)
		(end 352.267266 -289.078416)
		(width 0.0889)
		(layer "In11.Cu")
		(net "UPI_CPU1_CPU0_P2P2_DN<4>")
	)
	(arc
		(start 356.683564 -278.012144)
		(mid 356.867478 -277.842099)
		(end 356.959916 -277.6093)
		(width 0.0889)
		(layer "In11.Cu")
		(net "UPI_CPU1_CPU0_P2P2_DN<4>")
	)
	(arc
		(start 355.735128 -281.911298)
		(mid 355.556652 -281.59202)
		(end 355.735128 -281.272742)
		(width 0.0889)
		(layer "In11.Cu")
		(net "UPI_CPU1_CPU0_P2P2_DN<4>")
	)
	(arc
		(start 356.026466 -280.770584)
		(mid 355.948837 -280.492171)
		(end 355.743764 -280.288492)
		(width 0.0889)
		(layer "In11.Cu")
		(net "UPI_CPU1_CPU0_P2P2_DN<4>")
	)
	(arc
		(start 87.480394 -288.44113)
		(mid 87.289416 -288.645865)
		(end 87.220044 -288.917126)
		(width 0.0889)
		(layer "In11.Cu")
		(net "UPI_CPU1_CPU0_P2P2_DN<4>")
	)
	(arc
		(start 355.556566 -279.955498)
		(mid 355.608836 -279.773133)
		(end 355.743764 -279.639776)
		(width 0.0889)
		(layer "In11.Cu")
		(net "UPI_CPU1_CPU0_P2P2_DN<4>")
	)
	(arc
		(start 354.81006 -284.519624)
		(mid 355.012647 -284.313273)
		(end 355.086666 -284.033722)
		(width 0.0889)
		(layer "In11.Cu")
		(net "UPI_CPU1_CPU0_P2P2_DN<4>")
	)
	(arc
		(start 88.451182 -286.156146)
		(mid 88.629779 -286.475424)
		(end 88.451182 -286.794702)
		(width 0.0889)
		(layer "In11.Cu")
		(net "UPI_CPU1_CPU0_P2P2_DN<4>")
	)
	(arc
		(start 355.55682 -283.205174)
		(mid 355.607874 -283.030594)
		(end 355.735128 -282.900628)
		(width 0.0889)
		(layer "In11.Cu")
		(net "UPI_CPU1_CPU0_P2P2_DN<4>")
	)
	(arc
		(start 354.616512 -284.847538)
		(mid 354.664191 -284.664638)
		(end 354.795074 -284.52826)
		(width 0.0889)
		(layer "In11.Cu")
		(net "UPI_CPU1_CPU0_P2P2_DN<4>")
	)
	(arc
		(start 356.21976 -278.822404)
		(mid 356.422347 -278.616053)
		(end 356.496366 -278.336502)
		(width 0.0889)
		(layer "In11.Cu")
		(net "UPI_CPU1_CPU0_P2P2_DN<4>")
	)
	(arc
		(start 88.067896 -286.151066)
		(mid 88.255094 -286.100923)
		(end 88.442292 -286.151066)
		(width 0.0889)
		(layer "In11.Cu")
		(net "UPI_CPU1_CPU0_P2P2_DN<4>")
	)
	(arc
		(start 355.086666 -284.025086)
		(mid 355.138936 -283.842721)
		(end 355.273864 -283.709364)
		(width 0.0889)
		(layer "In11.Cu")
		(net "UPI_CPU1_CPU0_P2P2_DN<4>")
	)
	(arc
		(start 355.750114 -281.264106)
		(mid 355.952527 -281.057693)
		(end 356.026466 -280.778204)
		(width 0.0889)
		(layer "In11.Cu")
		(net "UPI_CPU1_CPU0_P2P2_DN<4>")
	)
	(arc
		(start 88.009476 -285.142432)
		(mid 87.752478 -285.096944)
		(end 87.502492 -285.171896)
		(width 0.0889)
		(layer "In11.Cu")
		(net "UPI_CPU1_CPU0_P2P2_DN<4>")
	)
	(segment
		(start 87.315294 -285.939484)
		(end 87.315294 -286.475424)
		(width 0.13208)
		(layer "F.Cu")
		(net "UPI_CPU1_CPU0_P2P2_DN<3>")
	)
	(segment
		(start 355.461316 -275.894546)
		(end 355.461062 -275.8948)
		(width 0.13208)
		(layer "F.Cu")
		(net "UPI_CPU1_CPU0_P2P2_DN<3>")
	)
	(segment
		(start 355.461316 -275.35886)
		(end 355.461316 -275.894546)
		(width 0.13208)
		(layer "F.Cu")
		(net "UPI_CPU1_CPU0_P2P2_DN<3>")
	)
	(segment
		(start 59.480958 -316.27953)
		(end 59.12866 -316.631828)
		(width 0.14732)
		(layer "In11.Cu")
		(net "UPI_CPU1_CPU0_P2P2_DN<3>")
	)
	(segment
		(start 81.84769 -297.68546)
		(end 68.152518 -311.380632)
		(width 0.14732)
		(layer "In11.Cu")
		(net "UPI_CPU1_CPU0_P2P2_DN<3>")
	)
	(segment
		(start 56.098694 -322.880228)
		(end 54.605936 -323.877686)
		(width 0.14732)
		(layer "In11.Cu")
		(net "UPI_CPU1_CPU0_P2P2_DN<3>")
	)
	(segment
		(start 356.674674 -279.644856)
		(end 356.683564 -279.639776)
		(width 0.0889)
		(layer "In11.Cu")
		(net "UPI_CPU1_CPU0_P2P2_DN<3>")
	)
	(segment
		(start 353.385628 -288.597848)
		(end 353.394518 -288.592768)
		(width 0.0889)
		(layer "In11.Cu")
		(net "UPI_CPU1_CPU0_P2P2_DN<3>")
	)
	(segment
		(start 59.50331 -316.264544)
		(end 59.480958 -316.27953)
		(width 0.14732)
		(layer "In11.Cu")
		(net "UPI_CPU1_CPU0_P2P2_DN<3>")
	)
	(segment
		(start 356.966012 -279.160224)
		(end 356.966012 -279.150318)
		(width 0.0889)
		(layer "In11.Cu")
		(net "UPI_CPU1_CPU0_P2P2_DN<3>")
	)
	(segment
		(start 356.205028 -283.714444)
		(end 356.213918 -283.709364)
		(width 0.0889)
		(layer "In11.Cu")
		(net "UPI_CPU1_CPU0_P2P2_DN<3>")
	)
	(segment
		(start 53.32476 -328.17054)
		(end 58.02376 -334.014064)
		(width 0.14732)
		(layer "In11.Cu")
		(net "UPI_CPU1_CPU0_P2P2_DN<3>")
	)
	(segment
		(start 356.966266 -280.778204)
		(end 356.966266 -280.76398)
		(width 0.0889)
		(layer "In11.Cu")
		(net "UPI_CPU1_CPU0_P2P2_DN<3>")
	)
	(segment
		(start 161.086546 -390.47293)
		(end 265.036808 -381.695198)
		(width 0.14732)
		(layer "In11.Cu")
		(net "UPI_CPU1_CPU0_P2P2_DN<3>")
	)
	(segment
		(start 356.496366 -281.600656)
		(end 356.496366 -281.583384)
		(width 0.0889)
		(layer "In11.Cu")
		(net "UPI_CPU1_CPU0_P2P2_DN<3>")
	)
	(segment
		(start 58.088784 -317.721742)
		(end 57.354978 -318.455548)
		(width 0.14732)
		(layer "In11.Cu")
		(net "UPI_CPU1_CPU0_P2P2_DN<3>")
	)
	(segment
		(start 86.750398 -288.103056)
		(end 86.750398 -288.322004)
		(width 0.0889)
		(layer "In11.Cu")
		(net "UPI_CPU1_CPU0_P2P2_DN<3>")
	)
	(segment
		(start 86.459314 -288.613088)
		(end 86.459314 -289.178238)
		(width 0.0889)
		(layer "In11.Cu")
		(net "UPI_CPU1_CPU0_P2P2_DN<3>")
	)
	(segment
		(start 58.768234 -317.721742)
		(end 58.088784 -317.721742)
		(width 0.14732)
		(layer "In11.Cu")
		(net "UPI_CPU1_CPU0_P2P2_DN<3>")
	)
	(segment
		(start 54.605936 -323.877686)
		(end 53.91785 -324.565518)
		(width 0.14732)
		(layer "In11.Cu")
		(net "UPI_CPU1_CPU0_P2P2_DN<3>")
	)
	(segment
		(start 355.086666 -285.675578)
		(end 355.086666 -285.652718)
		(width 0.0889)
		(layer "In11.Cu")
		(net "UPI_CPU1_CPU0_P2P2_DN<3>")
	)
	(segment
		(start 355.273864 -276.219158)
		(end 355.264974 -276.214078)
		(width 0.0889)
		(layer "In11.Cu")
		(net "UPI_CPU1_CPU0_P2P2_DN<3>")
	)
	(segment
		(start 321.774312 -327.826624)
		(end 340.116414 -309.484522)
		(width 0.14732)
		(layer "In11.Cu")
		(net "UPI_CPU1_CPU0_P2P2_DN<3>")
	)
	(segment
		(start 83.559396 -293.553388)
		(end 81.84769 -297.68546)
		(width 0.14732)
		(layer "In11.Cu")
		(net "UPI_CPU1_CPU0_P2P2_DN<3>")
	)
	(segment
		(start 355.744018 -277.032974)
		(end 355.735128 -277.027894)
		(width 0.0889)
		(layer "In11.Cu")
		(net "UPI_CPU1_CPU0_P2P2_DN<3>")
	)
	(segment
		(start 353.718876 -290.322508)
		(end 353.676712 -290.280344)
		(width 0.0889)
		(layer "In11.Cu")
		(net "UPI_CPU1_CPU0_P2P2_DN<3>")
	)
	(segment
		(start 357.435912 -278.346408)
		(end 357.435912 -278.336502)
		(width 0.0889)
		(layer "In11.Cu")
		(net "UPI_CPU1_CPU0_P2P2_DN<3>")
	)
	(segment
		(start 354.795074 -286.156146)
		(end 354.803964 -286.151066)
		(width 0.0889)
		(layer "In11.Cu")
		(net "UPI_CPU1_CPU0_P2P2_DN<3>")
	)
	(segment
		(start 355.090984 -275.952204)
		(end 355.148388 -275.8948)
		(width 0.0889)
		(layer "In11.Cu")
		(net "UPI_CPU1_CPU0_P2P2_DN<3>")
	)
	(segment
		(start 287.03016 -340.43493)
		(end 310.756554 -340.43493)
		(width 0.14732)
		(layer "In11.Cu")
		(net "UPI_CPU1_CPU0_P2P2_DN<3>")
	)
	(segment
		(start 87.627968 -286.475424)
		(end 87.685372 -286.532828)
		(width 0.0889)
		(layer "In11.Cu")
		(net "UPI_CPU1_CPU0_P2P2_DN<3>")
	)
	(segment
		(start 351.797874 -300.099984)
		(end 352.983546 -297.23715)
		(width 0.14732)
		(layer "In11.Cu")
		(net "UPI_CPU1_CPU0_P2P2_DN<3>")
	)
	(segment
		(start 71.15683 -375.980452)
		(end 94.448376 -385.628388)
		(width 0.14732)
		(layer "In11.Cu")
		(net "UPI_CPU1_CPU0_P2P2_DN<3>")
	)
	(segment
		(start 357.905812 -277.540974)
		(end 357.905812 -277.512526)
		(width 0.0889)
		(layer "In11.Cu")
		(net "UPI_CPU1_CPU0_P2P2_DN<3>")
	)
	(segment
		(start 56.344312 -322.63461)
		(end 56.098694 -322.880228)
		(width 0.14732)
		(layer "In11.Cu")
		(net "UPI_CPU1_CPU0_P2P2_DN<3>")
	)
	(segment
		(start 58.929778 -336.201512)
		(end 58.929778 -355.776276)
		(width 0.14732)
		(layer "In11.Cu")
		(net "UPI_CPU1_CPU0_P2P2_DN<3>")
	)
	(segment
		(start 87.041482 -287.608518)
		(end 87.032592 -287.613598)
		(width 0.0889)
		(layer "In11.Cu")
		(net "UPI_CPU1_CPU0_P2P2_DN<3>")
	)
	(segment
		(start 83.653884 -293.324788)
		(end 83.559396 -293.553388)
		(width 0.14732)
		(layer "In11.Cu")
		(net "UPI_CPU1_CPU0_P2P2_DN<3>")
	)
	(segment
		(start 355.148388 -275.8948)
		(end 355.461062 -275.8948)
		(width 0.0889)
		(layer "In11.Cu")
		(net "UPI_CPU1_CPU0_P2P2_DN<3>")
	)
	(segment
		(start 356.68966 -281.919934)
		(end 356.683564 -281.916378)
		(width 0.0889)
		(layer "In11.Cu")
		(net "UPI_CPU1_CPU0_P2P2_DN<3>")
	)
	(segment
		(start 355.744018 -284.52318)
		(end 355.750114 -284.519624)
		(width 0.0889)
		(layer "In11.Cu")
		(net "UPI_CPU1_CPU0_P2P2_DN<3>")
	)
	(segment
		(start 59.503564 -316.264544)
		(end 59.50331 -316.264544)
		(width 0.14732)
		(layer "In11.Cu")
		(net "UPI_CPU1_CPU0_P2P2_DN<3>")
	)
	(segment
		(start 344.037666 -307.860192)
		(end 351.797874 -300.099984)
		(width 0.14732)
		(layer "In11.Cu")
		(net "UPI_CPU1_CPU0_P2P2_DN<3>")
	)
	(segment
		(start 53.32476 -325.159116)
		(end 53.32476 -328.17054)
		(width 0.14732)
		(layer "In11.Cu")
		(net "UPI_CPU1_CPU0_P2P2_DN<3>")
	)
	(segment
		(start 353.718876 -291.317172)
		(end 353.718876 -290.344606)
		(width 0.14732)
		(layer "In11.Cu")
		(net "UPI_CPU1_CPU0_P2P2_DN<3>")
	)
	(segment
		(start 355.735128 -284.52826)
		(end 355.744018 -284.52318)
		(width 0.0889)
		(layer "In11.Cu")
		(net "UPI_CPU1_CPU0_P2P2_DN<3>")
	)
	(segment
		(start 353.676966 -288.121598)
		(end 353.676966 -288.09442)
		(width 0.0889)
		(layer "In11.Cu")
		(net "UPI_CPU1_CPU0_P2P2_DN<3>")
	)
	(segment
		(start 68.152518 -311.380632)
		(end 64.383666 -312.941716)
		(width 0.14732)
		(layer "In11.Cu")
		(net "UPI_CPU1_CPU0_P2P2_DN<3>")
	)
	(segment
		(start 53.91785 -324.566026)
		(end 53.32476 -325.159116)
		(width 0.14732)
		(layer "In11.Cu")
		(net "UPI_CPU1_CPU0_P2P2_DN<3>")
	)
	(segment
		(start 356.966266 -282.42006)
		(end 356.966266 -282.405836)
		(width 0.0889)
		(layer "In11.Cu")
		(net "UPI_CPU1_CPU0_P2P2_DN<3>")
	)
	(segment
		(start 357.614474 -278.017224)
		(end 357.623364 -278.012144)
		(width 0.0889)
		(layer "In11.Cu")
		(net "UPI_CPU1_CPU0_P2P2_DN<3>")
	)
	(segment
		(start 353.864926 -287.77819)
		(end 353.87026 -287.775142)
		(width 0.0889)
		(layer "In11.Cu")
		(net "UPI_CPU1_CPU0_P2P2_DN<3>")
	)
	(segment
		(start 87.315294 -286.475424)
		(end 87.627968 -286.475424)
		(width 0.0889)
		(layer "In11.Cu")
		(net "UPI_CPU1_CPU0_P2P2_DN<3>")
	)
	(segment
		(start 356.683564 -280.288492)
		(end 356.674674 -280.283412)
		(width 0.0889)
		(layer "In11.Cu")
		(net "UPI_CPU1_CPU0_P2P2_DN<3>")
	)
	(segment
		(start 57.354978 -321.624198)
		(end 56.874918 -322.104258)
		(width 0.14732)
		(layer "In11.Cu")
		(net "UPI_CPU1_CPU0_P2P2_DN<3>")
	)
	(segment
		(start 127.107696 -390.47293)
		(end 161.086546 -390.47293)
		(width 0.14732)
		(layer "In11.Cu")
		(net "UPI_CPU1_CPU0_P2P2_DN<3>")
	)
	(segment
		(start 310.756554 -340.43493)
		(end 320.649346 -330.542138)
		(width 0.14732)
		(layer "In11.Cu")
		(net "UPI_CPU1_CPU0_P2P2_DN<3>")
	)
	(segment
		(start 62.255654 -314.42533)
		(end 59.503564 -316.264544)
		(width 0.14732)
		(layer "In11.Cu")
		(net "UPI_CPU1_CPU0_P2P2_DN<3>")
	)
	(segment
		(start 53.91785 -324.565518)
		(end 53.91785 -324.566026)
		(width 0.14732)
		(layer "In11.Cu")
		(net "UPI_CPU1_CPU0_P2P2_DN<3>")
	)
	(segment
		(start 59.12866 -316.631828)
		(end 59.12866 -317.361316)
		(width 0.14732)
		(layer "In11.Cu")
		(net "UPI_CPU1_CPU0_P2P2_DN<3>")
	)
	(segment
		(start 352.983546 -297.23715)
		(end 352.983546 -292.052502)
		(width 0.14732)
		(layer "In11.Cu")
		(net "UPI_CPU1_CPU0_P2P2_DN<3>")
	)
	(segment
		(start 340.116414 -309.484522)
		(end 344.037666 -307.860192)
		(width 0.14732)
		(layer "In11.Cu")
		(net "UPI_CPU1_CPU0_P2P2_DN<3>")
	)
	(segment
		(start 355.27996 -276.222714)
		(end 355.273864 -276.219158)
		(width 0.0889)
		(layer "In11.Cu")
		(net "UPI_CPU1_CPU0_P2P2_DN<3>")
	)
	(segment
		(start 353.718876 -290.344606)
		(end 353.718876 -290.322508)
		(width 0.0889)
		(layer "In11.Cu")
		(net "UPI_CPU1_CPU0_P2P2_DN<3>")
	)
	(segment
		(start 320.649346 -330.542138)
		(end 321.774312 -327.826624)
		(width 0.14732)
		(layer "In11.Cu")
		(net "UPI_CPU1_CPU0_P2P2_DN<3>")
	)
	(segment
		(start 57.354978 -318.455548)
		(end 57.354978 -321.624198)
		(width 0.14732)
		(layer "In11.Cu")
		(net "UPI_CPU1_CPU0_P2P2_DN<3>")
	)
	(segment
		(start 353.676712 -290.280344)
		(end 353.676712 -289.60953)
		(width 0.0889)
		(layer "In11.Cu")
		(net "UPI_CPU1_CPU0_P2P2_DN<3>")
	)
	(segment
		(start 64.383666 -312.941716)
		(end 63.356744 -313.968638)
		(width 0.14732)
		(layer "In11.Cu")
		(net "UPI_CPU1_CPU0_P2P2_DN<3>")
	)
	(segment
		(start 56.874918 -322.104258)
		(end 56.344312 -322.63461)
		(width 0.14732)
		(layer "In11.Cu")
		(net "UPI_CPU1_CPU0_P2P2_DN<3>")
	)
	(segment
		(start 64.57061 -369.394232)
		(end 71.15683 -375.980452)
		(width 0.14732)
		(layer "In11.Cu")
		(net "UPI_CPU1_CPU0_P2P2_DN<3>")
	)
	(segment
		(start 277.1902 -369.541552)
		(end 277.1902 -348.86646)
		(width 0.14732)
		(layer "In11.Cu")
		(net "UPI_CPU1_CPU0_P2P2_DN<3>")
	)
	(segment
		(start 353.207066 -289.078416)
		(end 353.207066 -288.917126)
		(width 0.0889)
		(layer "In11.Cu")
		(net "UPI_CPU1_CPU0_P2P2_DN<3>")
	)
	(segment
		(start 265.036808 -381.695198)
		(end 277.1902 -369.541552)
		(width 0.14732)
		(layer "In11.Cu")
		(net "UPI_CPU1_CPU0_P2P2_DN<3>")
	)
	(segment
		(start 86.417404 -289.220148)
		(end 86.417404 -289.242246)
		(width 0.0889)
		(layer "In11.Cu")
		(net "UPI_CPU1_CPU0_P2P2_DN<3>")
	)
	(segment
		(start 63.356744 -313.968638)
		(end 62.255654 -314.42533)
		(width 0.14732)
		(layer "In11.Cu")
		(net "UPI_CPU1_CPU0_P2P2_DN<3>")
	)
	(segment
		(start 86.417404 -289.242246)
		(end 86.417404 -290.561268)
		(width 0.14732)
		(layer "In11.Cu")
		(net "UPI_CPU1_CPU0_P2P2_DN<3>")
	)
	(segment
		(start 353.864164 -287.778698)
		(end 353.864926 -287.77819)
		(width 0.0889)
		(layer "In11.Cu")
		(net "UPI_CPU1_CPU0_P2P2_DN<3>")
	)
	(segment
		(start 357.144574 -278.83104)
		(end 357.153464 -278.82596)
		(width 0.0889)
		(layer "In11.Cu")
		(net "UPI_CPU1_CPU0_P2P2_DN<3>")
	)
	(segment
		(start 87.511382 -286.794702)
		(end 87.502492 -286.799782)
		(width 0.0889)
		(layer "In11.Cu")
		(net "UPI_CPU1_CPU0_P2P2_DN<3>")
	)
	(segment
		(start 355.273864 -285.336996)
		(end 355.286056 -285.329884)
		(width 0.0889)
		(layer "In11.Cu")
		(net "UPI_CPU1_CPU0_P2P2_DN<3>")
	)
	(segment
		(start 86.459314 -289.178238)
		(end 86.417404 -289.220148)
		(width 0.0889)
		(layer "In11.Cu")
		(net "UPI_CPU1_CPU0_P2P2_DN<3>")
	)
	(segment
		(start 86.750398 -288.322004)
		(end 86.459314 -288.613088)
		(width 0.0889)
		(layer "In11.Cu")
		(net "UPI_CPU1_CPU0_P2P2_DN<3>")
	)
	(segment
		(start 58.929778 -355.776276)
		(end 64.57061 -369.394232)
		(width 0.14732)
		(layer "In11.Cu")
		(net "UPI_CPU1_CPU0_P2P2_DN<3>")
	)
	(segment
		(start 354.616512 -286.490918)
		(end 354.616512 -286.475424)
		(width 0.0889)
		(layer "In11.Cu")
		(net "UPI_CPU1_CPU0_P2P2_DN<3>")
	)
	(segment
		(start 356.683564 -281.267662)
		(end 356.68966 -281.264106)
		(width 0.0889)
		(layer "In11.Cu")
		(net "UPI_CPU1_CPU0_P2P2_DN<3>")
	)
	(segment
		(start 352.983546 -292.052502)
		(end 353.718876 -291.317172)
		(width 0.14732)
		(layer "In11.Cu")
		(net "UPI_CPU1_CPU0_P2P2_DN<3>")
	)
	(segment
		(start 277.1902 -348.86646)
		(end 284.625542 -341.431118)
		(width 0.14732)
		(layer "In11.Cu")
		(net "UPI_CPU1_CPU0_P2P2_DN<3>")
	)
	(segment
		(start 59.12866 -317.361316)
		(end 58.768234 -317.721742)
		(width 0.14732)
		(layer "In11.Cu")
		(net "UPI_CPU1_CPU0_P2P2_DN<3>")
	)
	(segment
		(start 356.128828 -277.026878)
		(end 356.118414 -277.032974)
		(width 0.0889)
		(layer "In11.Cu")
		(net "UPI_CPU1_CPU0_P2P2_DN<3>")
	)
	(segment
		(start 58.02376 -334.014064)
		(end 58.929778 -336.201512)
		(width 0.14732)
		(layer "In11.Cu")
		(net "UPI_CPU1_CPU0_P2P2_DN<3>")
	)
	(segment
		(start 354.325428 -286.969962)
		(end 354.334318 -286.964882)
		(width 0.0889)
		(layer "In11.Cu")
		(net "UPI_CPU1_CPU0_P2P2_DN<3>")
	)
	(segment
		(start 94.448376 -385.628388)
		(end 127.107696 -390.47293)
		(width 0.14732)
		(layer "In11.Cu")
		(net "UPI_CPU1_CPU0_P2P2_DN<3>")
	)
	(segment
		(start 87.220044 -287.279334)
		(end 87.220044 -287.28924)
		(width 0.0889)
		(layer "In11.Cu")
		(net "UPI_CPU1_CPU0_P2P2_DN<3>")
	)
	(segment
		(start 284.625542 -341.431118)
		(end 287.03016 -340.43493)
		(width 0.14732)
		(layer "In11.Cu")
		(net "UPI_CPU1_CPU0_P2P2_DN<3>")
	)
	(segment
		(start 356.496366 -283.229812)
		(end 356.496366 -283.21127)
		(width 0.0889)
		(layer "In11.Cu")
		(net "UPI_CPU1_CPU0_P2P2_DN<3>")
	)
	(segment
		(start 86.417404 -290.561268)
		(end 83.653884 -293.324788)
		(width 0.14732)
		(layer "In11.Cu")
		(net "UPI_CPU1_CPU0_P2P2_DN<3>")
	)
	(arc
		(start 357.905812 -277.512526)
		(mid 357.827701 -277.235577)
		(end 357.623364 -277.032974)
		(width 0.0889)
		(layer "In11.Cu")
		(net "UPI_CPU1_CPU0_P2P2_DN<3>")
	)
	(arc
		(start 354.616512 -286.475424)
		(mid 354.664191 -286.292524)
		(end 354.795074 -286.156146)
		(width 0.0889)
		(layer "In11.Cu")
		(net "UPI_CPU1_CPU0_P2P2_DN<3>")
	)
	(arc
		(start 87.220044 -287.28924)
		(mid 87.172365 -287.47214)
		(end 87.041482 -287.608518)
		(width 0.0889)
		(layer "In11.Cu")
		(net "UPI_CPU1_CPU0_P2P2_DN<3>")
	)
	(arc
		(start 355.264974 -276.214078)
		(mid 355.149235 -276.102254)
		(end 355.090984 -275.952204)
		(width 0.0889)
		(layer "In11.Cu")
		(net "UPI_CPU1_CPU0_P2P2_DN<3>")
	)
	(arc
		(start 353.676966 -288.09442)
		(mid 353.729236 -287.912055)
		(end 353.864164 -287.778698)
		(width 0.0889)
		(layer "In11.Cu")
		(net "UPI_CPU1_CPU0_P2P2_DN<3>")
	)
	(arc
		(start 353.391216 -289.277806)
		(mid 353.282069 -289.193878)
		(end 353.207066 -289.078416)
		(width 0.0889)
		(layer "In11.Cu")
		(net "UPI_CPU1_CPU0_P2P2_DN<3>")
	)
	(arc
		(start 357.153464 -278.82596)
		(mid 357.357799 -278.623355)
		(end 357.435912 -278.346408)
		(width 0.0889)
		(layer "In11.Cu")
		(net "UPI_CPU1_CPU0_P2P2_DN<3>")
	)
	(arc
		(start 87.019384 -287.621726)
		(mid 86.822208 -287.827361)
		(end 86.750398 -288.103056)
		(width 0.0889)
		(layer "In11.Cu")
		(net "UPI_CPU1_CPU0_P2P2_DN<3>")
	)
	(arc
		(start 355.735128 -277.027894)
		(mid 355.604214 -276.891534)
		(end 355.556566 -276.708616)
		(width 0.0889)
		(layer "In11.Cu")
		(net "UPI_CPU1_CPU0_P2P2_DN<3>")
	)
	(arc
		(start 356.966012 -279.150318)
		(mid 357.013691 -278.967418)
		(end 357.144574 -278.83104)
		(width 0.0889)
		(layer "In11.Cu")
		(net "UPI_CPU1_CPU0_P2P2_DN<3>")
	)
	(arc
		(start 357.435912 -278.336502)
		(mid 357.483591 -278.153602)
		(end 357.614474 -278.017224)
		(width 0.0889)
		(layer "In11.Cu")
		(net "UPI_CPU1_CPU0_P2P2_DN<3>")
	)
	(arc
		(start 353.207066 -288.917126)
		(mid 353.254745 -288.734226)
		(end 353.385628 -288.597848)
		(width 0.0889)
		(layer "In11.Cu")
		(net "UPI_CPU1_CPU0_P2P2_DN<3>")
	)
	(arc
		(start 356.966266 -282.405836)
		(mid 356.892275 -282.12627)
		(end 356.68966 -281.919934)
		(width 0.0889)
		(layer "In11.Cu")
		(net "UPI_CPU1_CPU0_P2P2_DN<3>")
	)
	(arc
		(start 355.086666 -285.652718)
		(mid 355.138936 -285.470353)
		(end 355.273864 -285.336996)
		(width 0.0889)
		(layer "In11.Cu")
		(net "UPI_CPU1_CPU0_P2P2_DN<3>")
	)
	(arc
		(start 355.556566 -284.847538)
		(mid 355.604245 -284.664638)
		(end 355.735128 -284.52826)
		(width 0.0889)
		(layer "In11.Cu")
		(net "UPI_CPU1_CPU0_P2P2_DN<3>")
	)
	(arc
		(start 355.750114 -284.519624)
		(mid 355.952527 -284.313211)
		(end 356.026466 -284.033722)
		(width 0.0889)
		(layer "In11.Cu")
		(net "UPI_CPU1_CPU0_P2P2_DN<3>")
	)
	(arc
		(start 87.685372 -286.532828)
		(mid 87.627216 -286.682941)
		(end 87.511382 -286.794702)
		(width 0.0889)
		(layer "In11.Cu")
		(net "UPI_CPU1_CPU0_P2P2_DN<3>")
	)
	(arc
		(start 356.683564 -277.032974)
		(mid 356.407005 -276.957231)
		(end 356.128828 -277.026878)
		(width 0.0889)
		(layer "In11.Cu")
		(net "UPI_CPU1_CPU0_P2P2_DN<3>")
	)
	(arc
		(start 355.556566 -276.708616)
		(mid 355.482575 -276.42905)
		(end 355.27996 -276.222714)
		(width 0.0889)
		(layer "In11.Cu")
		(net "UPI_CPU1_CPU0_P2P2_DN<3>")
	)
	(arc
		(start 356.68966 -281.264106)
		(mid 356.892247 -281.057755)
		(end 356.966266 -280.778204)
		(width 0.0889)
		(layer "In11.Cu")
		(net "UPI_CPU1_CPU0_P2P2_DN<3>")
	)
	(arc
		(start 356.213918 -283.709364)
		(mid 356.418253 -283.506759)
		(end 356.496366 -283.229812)
		(width 0.0889)
		(layer "In11.Cu")
		(net "UPI_CPU1_CPU0_P2P2_DN<3>")
	)
	(arc
		(start 356.966266 -280.76398)
		(mid 356.887047 -280.489295)
		(end 356.683564 -280.288492)
		(width 0.0889)
		(layer "In11.Cu")
		(net "UPI_CPU1_CPU0_P2P2_DN<3>")
	)
	(arc
		(start 356.496112 -279.95753)
		(mid 356.545365 -279.77833)
		(end 356.674674 -279.644856)
		(width 0.0889)
		(layer "In11.Cu")
		(net "UPI_CPU1_CPU0_P2P2_DN<3>")
	)
	(arc
		(start 354.803964 -286.151066)
		(mid 355.007445 -285.950262)
		(end 355.086666 -285.675578)
		(width 0.0889)
		(layer "In11.Cu")
		(net "UPI_CPU1_CPU0_P2P2_DN<3>")
	)
	(arc
		(start 353.394518 -288.592768)
		(mid 353.596804 -288.393787)
		(end 353.676966 -288.121598)
		(width 0.0889)
		(layer "In11.Cu")
		(net "UPI_CPU1_CPU0_P2P2_DN<3>")
	)
	(arc
		(start 356.118414 -277.032974)
		(mid 355.931216 -277.083117)
		(end 355.744018 -277.032974)
		(width 0.0889)
		(layer "In11.Cu")
		(net "UPI_CPU1_CPU0_P2P2_DN<3>")
	)
	(arc
		(start 357.05796 -277.032974)
		(mid 356.870762 -277.083117)
		(end 356.683564 -277.032974)
		(width 0.0889)
		(layer "In11.Cu")
		(net "UPI_CPU1_CPU0_P2P2_DN<3>")
	)
	(arc
		(start 356.683564 -279.639776)
		(mid 356.887899 -279.437171)
		(end 356.966012 -279.160224)
		(width 0.0889)
		(layer "In11.Cu")
		(net "UPI_CPU1_CPU0_P2P2_DN<3>")
	)
	(arc
		(start 87.032592 -287.613598)
		(mid 87.025961 -287.617618)
		(end 87.019384 -287.621726)
		(width 0.0889)
		(layer "In11.Cu")
		(net "UPI_CPU1_CPU0_P2P2_DN<3>")
	)
	(arc
		(start 354.334318 -286.964882)
		(mid 354.537141 -286.764651)
		(end 354.616512 -286.490918)
		(width 0.0889)
		(layer "In11.Cu")
		(net "UPI_CPU1_CPU0_P2P2_DN<3>")
	)
	(arc
		(start 87.502492 -286.799782)
		(mid 87.298157 -287.002387)
		(end 87.220044 -287.279334)
		(width 0.0889)
		(layer "In11.Cu")
		(net "UPI_CPU1_CPU0_P2P2_DN<3>")
	)
	(arc
		(start 356.496366 -281.583384)
		(mid 356.548636 -281.401019)
		(end 356.683564 -281.267662)
		(width 0.0889)
		(layer "In11.Cu")
		(net "UPI_CPU1_CPU0_P2P2_DN<3>")
	)
	(arc
		(start 356.496112 -279.973532)
		(mid 356.496029 -279.965531)
		(end 356.496112 -279.95753)
		(width 0.0889)
		(layer "In11.Cu")
		(net "UPI_CPU1_CPU0_P2P2_DN<3>")
	)
	(arc
		(start 354.146866 -287.28924)
		(mid 354.194545 -287.10634)
		(end 354.325428 -286.969962)
		(width 0.0889)
		(layer "In11.Cu")
		(net "UPI_CPU1_CPU0_P2P2_DN<3>")
	)
	(arc
		(start 357.623364 -277.032974)
		(mid 357.340662 -276.957198)
		(end 357.05796 -277.032974)
		(width 0.0889)
		(layer "In11.Cu")
		(net "UPI_CPU1_CPU0_P2P2_DN<3>")
	)
	(arc
		(start 357.623364 -278.012144)
		(mid 357.82565 -277.813163)
		(end 357.905812 -277.540974)
		(width 0.0889)
		(layer "In11.Cu")
		(net "UPI_CPU1_CPU0_P2P2_DN<3>")
	)
	(arc
		(start 356.683564 -281.916378)
		(mid 356.548631 -281.783024)
		(end 356.496366 -281.600656)
		(width 0.0889)
		(layer "In11.Cu")
		(net "UPI_CPU1_CPU0_P2P2_DN<3>")
	)
	(arc
		(start 355.286056 -285.329884)
		(mid 355.484284 -285.124036)
		(end 355.556566 -284.847538)
		(width 0.0889)
		(layer "In11.Cu")
		(net "UPI_CPU1_CPU0_P2P2_DN<3>")
	)
	(arc
		(start 356.674674 -280.283412)
		(mid 356.54608 -280.151138)
		(end 356.496112 -279.973532)
		(width 0.0889)
		(layer "In11.Cu")
		(net "UPI_CPU1_CPU0_P2P2_DN<3>")
	)
	(arc
		(start 353.676712 -289.60953)
		(mid 353.565374 -289.41663)
		(end 353.391216 -289.277806)
		(width 0.0889)
		(layer "In11.Cu")
		(net "UPI_CPU1_CPU0_P2P2_DN<3>")
	)
	(arc
		(start 353.87026 -287.775142)
		(mid 354.072847 -287.568791)
		(end 354.146866 -287.28924)
		(width 0.0889)
		(layer "In11.Cu")
		(net "UPI_CPU1_CPU0_P2P2_DN<3>")
	)
	(arc
		(start 356.026466 -284.033722)
		(mid 356.074145 -283.850822)
		(end 356.205028 -283.714444)
		(width 0.0889)
		(layer "In11.Cu")
		(net "UPI_CPU1_CPU0_P2P2_DN<3>")
	)
	(arc
		(start 356.683564 -282.895548)
		(mid 356.887045 -282.694744)
		(end 356.966266 -282.42006)
		(width 0.0889)
		(layer "In11.Cu")
		(net "UPI_CPU1_CPU0_P2P2_DN<3>")
	)
	(arc
		(start 356.496366 -283.21127)
		(mid 356.548636 -283.028905)
		(end 356.683564 -282.895548)
		(width 0.0889)
		(layer "In11.Cu")
		(net "UPI_CPU1_CPU0_P2P2_DN<3>")
	)
	(segment
		(start 356.870762 -276.172676)
		(end 356.870762 -276.708616)
		(width 0.13208)
		(layer "F.Cu")
		(net "UPI_CPU1_CPU0_P2P2_DN<2>")
	)
	(segment
		(start 86.375494 -285.939484)
		(end 86.375494 -286.475424)
		(width 0.13208)
		(layer "F.Cu")
		(net "UPI_CPU1_CPU0_P2P2_DN<2>")
	)
	(segment
		(start 353.080828 -298.855892)
		(end 352.940112 -299.195998)
		(width 0.14732)
		(layer "In11.Cu")
		(net "UPI_CPU1_CPU0_P2P2_DN<2>")
	)
	(segment
		(start 72.425052 -377.106942)
		(end 72.084692 -376.965972)
		(width 0.14732)
		(layer "In11.Cu")
		(net "UPI_CPU1_CPU0_P2P2_DN<2>")
	)
	(segment
		(start 355.65715 -285.980632)
		(end 355.64826 -285.985712)
		(width 0.0889)
		(layer "In11.Cu")
		(net "UPI_CPU1_CPU0_P2P2_DN<2>")
	)
	(segment
		(start 354.426266 -289.64636)
		(end 354.426266 -290.05149)
		(width 0.0889)
		(layer "In11.Cu")
		(net "UPI_CPU1_CPU0_P2P2_DN<2>")
	)
	(segment
		(start 354.384356 -291.461698)
		(end 354.384356 -291.483796)
		(width 0.0889)
		(layer "In11.Cu")
		(net "UPI_CPU1_CPU0_P2P2_DN<2>")
	)
	(segment
		(start 354.895912 -287.279334)
		(end 354.895912 -287.297876)
		(width 0.0889)
		(layer "In11.Cu")
		(net "UPI_CPU1_CPU0_P2P2_DN<2>")
	)
	(segment
		(start 85.82787 -288.31413)
		(end 85.9536 -288.1884)
		(width 0.0889)
		(layer "In11.Cu")
		(net "UPI_CPU1_CPU0_P2P2_DN<2>")
	)
	(segment
		(start 358.001062 -276.38629)
		(end 358.00665 -276.389338)
		(width 0.0889)
		(layer "In11.Cu")
		(net "UPI_CPU1_CPU0_P2P2_DN<2>")
	)
	(segment
		(start 60.223654 -314.784486)
		(end 60.263532 -314.583572)
		(width 0.14732)
		(layer "In11.Cu")
		(net "UPI_CPU1_CPU0_P2P2_DN<2>")
	)
	(segment
		(start 55.520844 -331.933804)
		(end 52.71008 -329.12304)
		(width 0.14732)
		(layer "In11.Cu")
		(net "UPI_CPU1_CPU0_P2P2_DN<2>")
	)
	(segment
		(start 357.5304 -279.473152)
		(end 357.528622 -279.474168)
		(width 0.0889)
		(layer "In11.Cu")
		(net "UPI_CPU1_CPU0_P2P2_DN<2>")
	)
	(segment
		(start 77.090524 -301.40529)
		(end 77.295248 -301.40529)
		(width 0.14732)
		(layer "In11.Cu")
		(net "UPI_CPU1_CPU0_P2P2_DN<2>")
	)
	(segment
		(start 277.74392 -349.207328)
		(end 277.74392 -369.771422)
		(width 0.14732)
		(layer "In11.Cu")
		(net "UPI_CPU1_CPU0_P2P2_DN<2>")
	)
	(segment
		(start 76.364592 -302.131222)
		(end 76.569316 -302.131222)
		(width 0.14732)
		(layer "In11.Cu")
		(net "UPI_CPU1_CPU0_P2P2_DN<2>")
	)
	(segment
		(start 57.504838 -316.42685)
		(end 59.716162 -314.949332)
		(width 0.14732)
		(layer "In11.Cu")
		(net "UPI_CPU1_CPU0_P2P2_DN<2>")
	)
	(segment
		(start 352.940112 -299.195998)
		(end 352.750882 -299.27423)
		(width 0.14732)
		(layer "In11.Cu")
		(net "UPI_CPU1_CPU0_P2P2_DN<2>")
	)
	(segment
		(start 354.426266 -290.42741)
		(end 354.426266 -290.60521)
		(width 0.0889)
		(layer "In11.Cu")
		(net "UPI_CPU1_CPU0_P2P2_DN<2>")
	)
	(segment
		(start 84.946744 -291.329364)
		(end 85.072474 -291.203634)
		(width 0.0889)
		(layer "In11.Cu")
		(net "UPI_CPU1_CPU0_P2P2_DN<2>")
	)
	(segment
		(start 71.895462 -377.044204)
		(end 71.090028 -376.710702)
		(width 0.14732)
		(layer "In11.Cu")
		(net "UPI_CPU1_CPU0_P2P2_DN<2>")
	)
	(segment
		(start 85.594952 -289.295078)
		(end 85.594952 -289.117278)
		(width 0.0889)
		(layer "In11.Cu")
		(net "UPI_CPU1_CPU0_P2P2_DN<2>")
	)
	(segment
		(start 85.694012 -289.394138)
		(end 85.594952 -289.295078)
		(width 0.0889)
		(layer "In11.Cu")
		(net "UPI_CPU1_CPU0_P2P2_DN<2>")
	)
	(segment
		(start 340.430866 -309.956962)
		(end 322.277486 -328.110342)
		(width 0.14732)
		(layer "In11.Cu")
		(net "UPI_CPU1_CPU0_P2P2_DN<2>")
	)
	(segment
		(start 93.731588 -386.089398)
		(end 72.503538 -377.296172)
		(width 0.14732)
		(layer "In11.Cu")
		(net "UPI_CPU1_CPU0_P2P2_DN<2>")
	)
	(segment
		(start 85.594952 -290.224718)
		(end 85.694012 -290.125658)
		(width 0.0889)
		(layer "In11.Cu")
		(net "UPI_CPU1_CPU0_P2P2_DN<2>")
	)
	(segment
		(start 78.020926 -300.679612)
		(end 78.28153 -300.419008)
		(width 0.14732)
		(layer "In11.Cu")
		(net "UPI_CPU1_CPU0_P2P2_DN<2>")
	)
	(segment
		(start 358.468422 -277.846282)
		(end 358.46766 -277.84679)
		(width 0.0889)
		(layer "In11.Cu")
		(net "UPI_CPU1_CPU0_P2P2_DN<2>")
	)
	(segment
		(start 85.594952 -290.540694)
		(end 85.594952 -290.224718)
		(width 0.0889)
		(layer "In11.Cu")
		(net "UPI_CPU1_CPU0_P2P2_DN<2>")
	)
	(segment
		(start 357.531162 -279.472644)
		(end 357.5304 -279.473152)
		(width 0.0889)
		(layer "In11.Cu")
		(net "UPI_CPU1_CPU0_P2P2_DN<2>")
	)
	(segment
		(start 354.426012 -288.111438)
		(end 354.425758 -288.117788)
		(width 0.0889)
		(layer "In11.Cu")
		(net "UPI_CPU1_CPU0_P2P2_DN<2>")
	)
	(segment
		(start 352.750882 -299.27423)
		(end 352.609912 -299.614844)
		(width 0.14732)
		(layer "In11.Cu")
		(net "UPI_CPU1_CPU0_P2P2_DN<2>")
	)
	(segment
		(start 52.71008 -329.12304)
		(end 52.71008 -324.930008)
		(width 0.14732)
		(layer "In11.Cu")
		(net "UPI_CPU1_CPU0_P2P2_DN<2>")
	)
	(segment
		(start 357.245412 -283.201364)
		(end 357.245412 -283.219906)
		(width 0.0889)
		(layer "In11.Cu")
		(net "UPI_CPU1_CPU0_P2P2_DN<2>")
	)
	(segment
		(start 83.170522 -293.024052)
		(end 84.694522 -291.500052)
		(width 0.14732)
		(layer "In11.Cu")
		(net "UPI_CPU1_CPU0_P2P2_DN<2>")
	)
	(segment
		(start 62.978284 -312.725816)
		(end 67.743832 -310.751982)
		(width 0.14732)
		(layer "In11.Cu")
		(net "UPI_CPU1_CPU0_P2P2_DN<2>")
	)
	(segment
		(start 357.52786 -280.453846)
		(end 357.53675 -280.458926)
		(width 0.0889)
		(layer "In11.Cu")
		(net "UPI_CPU1_CPU0_P2P2_DN<2>")
	)
	(segment
		(start 58.376058 -356.241096)
		(end 58.376058 -336.391504)
		(width 0.14732)
		(layer "In11.Cu")
		(net "UPI_CPU1_CPU0_P2P2_DN<2>")
	)
	(segment
		(start 86.345268 -287.65627)
		(end 86.470744 -287.530794)
		(width 0.0889)
		(layer "In11.Cu")
		(net "UPI_CPU1_CPU0_P2P2_DN<2>")
	)
	(segment
		(start 86.562692 -286.151066)
		(end 86.571582 -286.156146)
		(width 0.0889)
		(layer "In11.Cu")
		(net "UPI_CPU1_CPU0_P2P2_DN<2>")
	)
	(segment
		(start 55.54599 -331.963776)
		(end 55.543958 -331.961236)
		(width 0.14732)
		(layer "In11.Cu")
		(net "UPI_CPU1_CPU0_P2P2_DN<2>")
	)
	(segment
		(start 354.384356 -291.483796)
		(end 354.384356 -291.74821)
		(width 0.14732)
		(layer "In11.Cu")
		(net "UPI_CPU1_CPU0_P2P2_DN<2>")
	)
	(segment
		(start 355.18725 -286.794702)
		(end 355.17836 -286.799782)
		(width 0.0889)
		(layer "In11.Cu")
		(net "UPI_CPU1_CPU0_P2P2_DN<2>")
	)
	(segment
		(start 265.2395 -382.275842)
		(end 161.46399 -391.03935)
		(width 0.14732)
		(layer "In11.Cu")
		(net "UPI_CPU1_CPU0_P2P2_DN<2>")
	)
	(segment
		(start 77.555852 -301.144686)
		(end 77.555852 -300.939962)
		(width 0.14732)
		(layer "In11.Cu")
		(net "UPI_CPU1_CPU0_P2P2_DN<2>")
	)
	(segment
		(start 63.860426 -369.4811)
		(end 58.376058 -356.241096)
		(width 0.14732)
		(layer "In11.Cu")
		(net "UPI_CPU1_CPU0_P2P2_DN<2>")
	)
	(segment
		(start 356.305612 -284.847538)
		(end 356.305612 -284.856174)
		(width 0.0889)
		(layer "In11.Cu")
		(net "UPI_CPU1_CPU0_P2P2_DN<2>")
	)
	(segment
		(start 59.716162 -314.949332)
		(end 59.917076 -314.98921)
		(width 0.14732)
		(layer "In11.Cu")
		(net "UPI_CPU1_CPU0_P2P2_DN<2>")
	)
	(segment
		(start 353.581716 -292.55085)
		(end 353.581716 -297.646852)
		(width 0.14732)
		(layer "In11.Cu")
		(net "UPI_CPU1_CPU0_P2P2_DN<2>")
	)
	(segment
		(start 55.536338 -318.532002)
		(end 55.979568 -317.7032)
		(width 0.14732)
		(layer "In11.Cu")
		(net "UPI_CPU1_CPU0_P2P2_DN<2>")
	)
	(segment
		(start 358.185212 -278.31796)
		(end 358.185212 -278.336502)
		(width 0.0889)
		(layer "In11.Cu")
		(net "UPI_CPU1_CPU0_P2P2_DN<2>")
	)
	(segment
		(start 54.66588 -322.90893)
		(end 55.536338 -318.532002)
		(width 0.14732)
		(layer "In11.Cu")
		(net "UPI_CPU1_CPU0_P2P2_DN<2>")
	)
	(segment
		(start 55.979568 -317.7032)
		(end 56.115712 -317.567056)
		(width 0.14732)
		(layer "In11.Cu")
		(net "UPI_CPU1_CPU0_P2P2_DN<2>")
	)
	(segment
		(start 71.090028 -376.710702)
		(end 63.860426 -369.4811)
		(width 0.14732)
		(layer "In11.Cu")
		(net "UPI_CPU1_CPU0_P2P2_DN<2>")
	)
	(segment
		(start 358.463596 -277.195788)
		(end 358.47655 -277.203154)
		(width 0.0889)
		(layer "In11.Cu")
		(net "UPI_CPU1_CPU0_P2P2_DN<2>")
	)
	(segment
		(start 84.806282 -291.329364)
		(end 84.946744 -291.329364)
		(width 0.0889)
		(layer "In11.Cu")
		(net "UPI_CPU1_CPU0_P2P2_DN<2>")
	)
	(segment
		(start 77.816202 -300.679612)
		(end 78.020926 -300.679612)
		(width 0.14732)
		(layer "In11.Cu")
		(net "UPI_CPU1_CPU0_P2P2_DN<2>")
	)
	(segment
		(start 353.143566 -298.326048)
		(end 353.002596 -298.666662)
		(width 0.14732)
		(layer "In11.Cu")
		(net "UPI_CPU1_CPU0_P2P2_DN<2>")
	)
	(segment
		(start 356.870762 -276.708616)
		(end 357.027226 -276.437598)
		(width 0.0889)
		(layer "In11.Cu")
		(net "UPI_CPU1_CPU0_P2P2_DN<2>")
	)
	(segment
		(start 285.129478 -341.82177)
		(end 277.74392 -349.207328)
		(width 0.14732)
		(layer "In11.Cu")
		(net "UPI_CPU1_CPU0_P2P2_DN<2>")
	)
	(segment
		(start 354.426012 -289.645852)
		(end 354.426266 -289.64636)
		(width 0.0889)
		(layer "In11.Cu")
		(net "UPI_CPU1_CPU0_P2P2_DN<2>")
	)
	(segment
		(start 161.46399 -391.03935)
		(end 127.098552 -391.03935)
		(width 0.14732)
		(layer "In11.Cu")
		(net "UPI_CPU1_CPU0_P2P2_DN<2>")
	)
	(segment
		(start 321.153536 -330.823824)
		(end 310.90997 -341.06739)
		(width 0.14732)
		(layer "In11.Cu")
		(net "UPI_CPU1_CPU0_P2P2_DN<2>")
	)
	(segment
		(start 86.470744 -287.530794)
		(end 86.470744 -287.279334)
		(width 0.0889)
		(layer "In11.Cu")
		(net "UPI_CPU1_CPU0_P2P2_DN<2>")
	)
	(segment
		(start 356.588314 -284.35808)
		(end 356.582218 -284.361636)
		(width 0.0889)
		(layer "In11.Cu")
		(net "UPI_CPU1_CPU0_P2P2_DN<2>")
	)
	(segment
		(start 85.694012 -289.571938)
		(end 85.694012 -289.394138)
		(width 0.0889)
		(layer "In11.Cu")
		(net "UPI_CPU1_CPU0_P2P2_DN<2>")
	)
	(segment
		(start 85.072474 -291.063172)
		(end 85.19795 -290.937696)
		(width 0.0889)
		(layer "In11.Cu")
		(net "UPI_CPU1_CPU0_P2P2_DN<2>")
	)
	(segment
		(start 353.956366 -288.895028)
		(end 353.956366 -289.114738)
		(width 0.0889)
		(layer "In11.Cu")
		(net "UPI_CPU1_CPU0_P2P2_DN<2>")
	)
	(segment
		(start 85.694012 -289.947858)
		(end 85.594952 -289.848798)
		(width 0.0889)
		(layer "In11.Cu")
		(net "UPI_CPU1_CPU0_P2P2_DN<2>")
	)
	(segment
		(start 60.64631 -314.327794)
		(end 61.731398 -313.242452)
		(width 0.14732)
		(layer "In11.Cu")
		(net "UPI_CPU1_CPU0_P2P2_DN<2>")
	)
	(segment
		(start 79.472282 -299.228256)
		(end 79.732886 -298.967652)
		(width 0.14732)
		(layer "In11.Cu")
		(net "UPI_CPU1_CPU0_P2P2_DN<2>")
	)
	(segment
		(start 357.027226 -276.437598)
		(end 357.116126 -276.413976)
		(width 0.0889)
		(layer "In11.Cu")
		(net "UPI_CPU1_CPU0_P2P2_DN<2>")
	)
	(segment
		(start 357.528622 -279.474168)
		(end 357.52786 -279.474676)
		(width 0.0889)
		(layer "In11.Cu")
		(net "UPI_CPU1_CPU0_P2P2_DN<2>")
	)
	(segment
		(start 81.54289 -296.952924)
		(end 83.170522 -293.024052)
		(width 0.14732)
		(layer "In11.Cu")
		(net "UPI_CPU1_CPU0_P2P2_DN<2>")
	)
	(segment
		(start 127.098552 -391.03935)
		(end 93.731588 -386.089398)
		(width 0.14732)
		(layer "In11.Cu")
		(net "UPI_CPU1_CPU0_P2P2_DN<2>")
	)
	(segment
		(start 78.746604 -299.953934)
		(end 79.007208 -299.69333)
		(width 0.14732)
		(layer "In11.Cu")
		(net "UPI_CPU1_CPU0_P2P2_DN<2>")
	)
	(segment
		(start 358.47655 -277.84171)
		(end 358.468422 -277.846282)
		(width 0.0889)
		(layer "In11.Cu")
		(net "UPI_CPU1_CPU0_P2P2_DN<2>")
	)
	(segment
		(start 86.187534 -286.799274)
		(end 86.179406 -286.794702)
		(width 0.0889)
		(layer "In11.Cu")
		(net "UPI_CPU1_CPU0_P2P2_DN<2>")
	)
	(segment
		(start 354.708714 -287.613598)
		(end 354.707952 -287.614106)
		(width 0.0889)
		(layer "In11.Cu")
		(net "UPI_CPU1_CPU0_P2P2_DN<2>")
	)
	(segment
		(start 86.179406 -286.156146)
		(end 86.188296 -286.151066)
		(width 0.0889)
		(layer "In11.Cu")
		(net "UPI_CPU1_CPU0_P2P2_DN<2>")
	)
	(segment
		(start 357.52786 -282.081478)
		(end 357.53675 -282.086558)
		(width 0.0889)
		(layer "In11.Cu")
		(net "UPI_CPU1_CPU0_P2P2_DN<2>")
	)
	(segment
		(start 353.332796 -298.247816)
		(end 353.143566 -298.326048)
		(width 0.14732)
		(layer "In11.Cu")
		(net "UPI_CPU1_CPU0_P2P2_DN<2>")
	)
	(segment
		(start 86.61019 -286.76727)
		(end 86.531958 -286.746442)
		(width 0.0889)
		(layer "In11.Cu")
		(net "UPI_CPU1_CPU0_P2P2_DN<2>")
	)
	(segment
		(start 85.9536 -288.047938)
		(end 86.079076 -287.922462)
		(width 0.0889)
		(layer "In11.Cu")
		(net "UPI_CPU1_CPU0_P2P2_DN<2>")
	)
	(segment
		(start 357.998522 -276.384766)
		(end 358.001062 -276.38629)
		(width 0.0889)
		(layer "In11.Cu")
		(net "UPI_CPU1_CPU0_P2P2_DN<2>")
	)
	(segment
		(start 77.555852 -300.939962)
		(end 77.816202 -300.679612)
		(width 0.14732)
		(layer "In11.Cu")
		(net "UPI_CPU1_CPU0_P2P2_DN<2>")
	)
	(segment
		(start 352.547428 -300.14418)
		(end 344.363548 -308.32806)
		(width 0.14732)
		(layer "In11.Cu")
		(net "UPI_CPU1_CPU0_P2P2_DN<2>")
	)
	(segment
		(start 79.732886 -298.762928)
		(end 81.54289 -296.952924)
		(width 0.14732)
		(layer "In11.Cu")
		(net "UPI_CPU1_CPU0_P2P2_DN<2>")
	)
	(segment
		(start 85.594952 -289.117278)
		(end 85.694012 -289.018218)
		(width 0.0889)
		(layer "In11.Cu")
		(net "UPI_CPU1_CPU0_P2P2_DN<2>")
	)
	(segment
		(start 84.710016 -291.484558)
		(end 84.710016 -291.42563)
		(width 0.0889)
		(layer "In11.Cu")
		(net "UPI_CPU1_CPU0_P2P2_DN<2>")
	)
	(segment
		(start 85.694012 -289.018218)
		(end 85.694012 -288.840418)
		(width 0.0889)
		(layer "In11.Cu")
		(net "UPI_CPU1_CPU0_P2P2_DN<2>")
	)
	(segment
		(start 86.079076 -287.922462)
		(end 86.219538 -287.922462)
		(width 0.0889)
		(layer "In11.Cu")
		(net "UPI_CPU1_CPU0_P2P2_DN<2>")
	)
	(segment
		(start 357.53675 -282.725114)
		(end 357.52786 -282.730194)
		(width 0.0889)
		(layer "In11.Cu")
		(net "UPI_CPU1_CPU0_P2P2_DN<2>")
	)
	(segment
		(start 76.569316 -302.131222)
		(end 76.830174 -301.870364)
		(width 0.14732)
		(layer "In11.Cu")
		(net "UPI_CPU1_CPU0_P2P2_DN<2>")
	)
	(segment
		(start 357.53675 -279.469596)
		(end 357.531162 -279.472644)
		(width 0.0889)
		(layer "In11.Cu")
		(net "UPI_CPU1_CPU0_P2P2_DN<2>")
	)
	(segment
		(start 79.007208 -299.488606)
		(end 79.267558 -299.228256)
		(width 0.14732)
		(layer "In11.Cu")
		(net "UPI_CPU1_CPU0_P2P2_DN<2>")
	)
	(segment
		(start 352.688144 -299.804074)
		(end 352.547428 -300.14418)
		(width 0.14732)
		(layer "In11.Cu")
		(net "UPI_CPU1_CPU0_P2P2_DN<2>")
	)
	(segment
		(start 358.461564 -277.194518)
		(end 358.463596 -277.195788)
		(width 0.0889)
		(layer "In11.Cu")
		(net "UPI_CPU1_CPU0_P2P2_DN<2>")
	)
	(segment
		(start 84.694522 -291.500052)
		(end 84.710016 -291.484558)
		(width 0.0889)
		(layer "In11.Cu")
		(net "UPI_CPU1_CPU0_P2P2_DN<2>")
	)
	(segment
		(start 353.002596 -298.666662)
		(end 353.080828 -298.855892)
		(width 0.14732)
		(layer "In11.Cu")
		(net "UPI_CPU1_CPU0_P2P2_DN<2>")
	)
	(segment
		(start 357.06685 -283.539184)
		(end 357.05796 -283.544264)
		(width 0.0889)
		(layer "In11.Cu")
		(net "UPI_CPU1_CPU0_P2P2_DN<2>")
	)
	(segment
		(start 356.775512 -284.023816)
		(end 356.775512 -284.042358)
		(width 0.0889)
		(layer "In11.Cu")
		(net "UPI_CPU1_CPU0_P2P2_DN<2>")
	)
	(segment
		(start 62.900052 -312.9153)
		(end 62.978284 -312.725816)
		(width 0.14732)
		(layer "In11.Cu")
		(net "UPI_CPU1_CPU0_P2P2_DN<2>")
	)
	(segment
		(start 352.609912 -299.614844)
		(end 352.688144 -299.804074)
		(width 0.14732)
		(layer "In11.Cu")
		(net "UPI_CPU1_CPU0_P2P2_DN<2>")
	)
	(segment
		(start 85.687408 -288.31413)
		(end 85.82787 -288.31413)
		(width 0.0889)
		(layer "In11.Cu")
		(net "UPI_CPU1_CPU0_P2P2_DN<2>")
	)
	(segment
		(start 77.295248 -301.40529)
		(end 77.555852 -301.144686)
		(width 0.14732)
		(layer "In11.Cu")
		(net "UPI_CPU1_CPU0_P2P2_DN<2>")
	)
	(segment
		(start 286.950658 -341.06739)
		(end 285.129478 -341.82177)
		(width 0.14732)
		(layer "In11.Cu")
		(net "UPI_CPU1_CPU0_P2P2_DN<2>")
	)
	(segment
		(start 354.327206 -290.88207)
		(end 354.426266 -290.98113)
		(width 0.0889)
		(layer "In11.Cu")
		(net "UPI_CPU1_CPU0_P2P2_DN<2>")
	)
	(segment
		(start 358.00665 -278.65578)
		(end 357.99776 -278.66086)
		(width 0.0889)
		(layer "In11.Cu")
		(net "UPI_CPU1_CPU0_P2P2_DN<2>")
	)
	(segment
		(start 85.594952 -289.848798)
		(end 85.594952 -289.670998)
		(width 0.0889)
		(layer "In11.Cu")
		(net "UPI_CPU1_CPU0_P2P2_DN<2>")
	)
	(segment
		(start 85.9536 -288.1884)
		(end 85.9536 -288.047938)
		(width 0.0889)
		(layer "In11.Cu")
		(net "UPI_CPU1_CPU0_P2P2_DN<2>")
	)
	(segment
		(start 277.74392 -369.771422)
		(end 265.2395 -382.275842)
		(width 0.14732)
		(layer "In11.Cu")
		(net "UPI_CPU1_CPU0_P2P2_DN<2>")
	)
	(segment
		(start 59.917076 -314.98921)
		(end 60.223654 -314.784486)
		(width 0.14732)
		(layer "In11.Cu")
		(net "UPI_CPU1_CPU0_P2P2_DN<2>")
	)
	(segment
		(start 54.665626 -322.974462)
		(end 54.665626 -322.909184)
		(width 0.14732)
		(layer "In11.Cu")
		(net "UPI_CPU1_CPU0_P2P2_DN<2>")
	)
	(segment
		(start 354.707952 -287.614106)
		(end 354.702618 -287.617154)
		(width 0.0889)
		(layer "In11.Cu")
		(net "UPI_CPU1_CPU0_P2P2_DN<2>")
	)
	(segment
		(start 85.338412 -290.937696)
		(end 85.464142 -290.811966)
		(width 0.0889)
		(layer "In11.Cu")
		(net "UPI_CPU1_CPU0_P2P2_DN<2>")
	)
	(segment
		(start 58.376058 -336.391504)
		(end 57.517284 -334.318102)
		(width 0.14732)
		(layer "In11.Cu")
		(net "UPI_CPU1_CPU0_P2P2_DN<2>")
	)
	(segment
		(start 344.363548 -308.32806)
		(end 340.430866 -309.956962)
		(width 0.14732)
		(layer "In11.Cu")
		(net "UPI_CPU1_CPU0_P2P2_DN<2>")
	)
	(segment
		(start 354.327206 -290.70427)
		(end 354.327206 -290.88207)
		(width 0.0889)
		(layer "In11.Cu")
		(net "UPI_CPU1_CPU0_P2P2_DN<2>")
	)
	(segment
		(start 354.384356 -291.74821)
		(end 353.581716 -292.55085)
		(width 0.14732)
		(layer "In11.Cu")
		(net "UPI_CPU1_CPU0_P2P2_DN<2>")
	)
	(segment
		(start 85.594952 -288.741358)
		(end 85.594952 -288.406586)
		(width 0.0889)
		(layer "In11.Cu")
		(net "UPI_CPU1_CPU0_P2P2_DN<2>")
	)
	(segment
		(start 85.694012 -290.125658)
		(end 85.694012 -289.947858)
		(width 0.0889)
		(layer "In11.Cu")
		(net "UPI_CPU1_CPU0_P2P2_DN<2>")
	)
	(segment
		(start 310.90997 -341.06739)
		(end 286.950658 -341.06739)
		(width 0.14732)
		(layer "In11.Cu")
		(net "UPI_CPU1_CPU0_P2P2_DN<2>")
	)
	(segment
		(start 357.53675 -281.097482)
		(end 357.52786 -281.102562)
		(width 0.0889)
		(layer "In11.Cu")
		(net "UPI_CPU1_CPU0_P2P2_DN<2>")
	)
	(segment
		(start 86.345268 -287.796732)
		(end 86.345268 -287.65627)
		(width 0.0889)
		(layer "In11.Cu")
		(net "UPI_CPU1_CPU0_P2P2_DN<2>")
	)
	(segment
		(start 76.830174 -301.66564)
		(end 77.090524 -301.40529)
		(width 0.14732)
		(layer "In11.Cu")
		(net "UPI_CPU1_CPU0_P2P2_DN<2>")
	)
	(segment
		(start 85.594952 -289.670998)
		(end 85.694012 -289.571938)
		(width 0.0889)
		(layer "In11.Cu")
		(net "UPI_CPU1_CPU0_P2P2_DN<2>")
	)
	(segment
		(start 354.426266 -290.98113)
		(end 354.426266 -291.419788)
		(width 0.0889)
		(layer "In11.Cu")
		(net "UPI_CPU1_CPU0_P2P2_DN<2>")
	)
	(segment
		(start 354.426266 -290.05149)
		(end 354.327206 -290.15055)
		(width 0.0889)
		(layer "In11.Cu")
		(net "UPI_CPU1_CPU0_P2P2_DN<2>")
	)
	(segment
		(start 76.830174 -301.870364)
		(end 76.830174 -301.66564)
		(width 0.14732)
		(layer "In11.Cu")
		(net "UPI_CPU1_CPU0_P2P2_DN<2>")
	)
	(segment
		(start 357.245412 -281.582114)
		(end 357.245412 -281.601926)
		(width 0.0889)
		(layer "In11.Cu")
		(net "UPI_CPU1_CPU0_P2P2_DN<2>")
	)
	(segment
		(start 85.464142 -290.671504)
		(end 85.594952 -290.540694)
		(width 0.0889)
		(layer "In11.Cu")
		(net "UPI_CPU1_CPU0_P2P2_DN<2>")
	)
	(segment
		(start 354.426266 -290.60521)
		(end 354.327206 -290.70427)
		(width 0.0889)
		(layer "In11.Cu")
		(net "UPI_CPU1_CPU0_P2P2_DN<2>")
	)
	(segment
		(start 79.007208 -299.69333)
		(end 79.007208 -299.488606)
		(width 0.14732)
		(layer "In11.Cu")
		(net "UPI_CPU1_CPU0_P2P2_DN<2>")
	)
	(segment
		(start 354.327206 -290.32835)
		(end 354.426266 -290.42741)
		(width 0.0889)
		(layer "In11.Cu")
		(net "UPI_CPU1_CPU0_P2P2_DN<2>")
	)
	(segment
		(start 60.263532 -314.583572)
		(end 60.64631 -314.327794)
		(width 0.14732)
		(layer "In11.Cu")
		(net "UPI_CPU1_CPU0_P2P2_DN<2>")
	)
	(segment
		(start 357.245412 -279.954228)
		(end 357.245412 -279.982676)
		(width 0.0889)
		(layer "In11.Cu")
		(net "UPI_CPU1_CPU0_P2P2_DN<2>")
	)
	(segment
		(start 357.99776 -276.384258)
		(end 357.998522 -276.384766)
		(width 0.0889)
		(layer "In11.Cu")
		(net "UPI_CPU1_CPU0_P2P2_DN<2>")
	)
	(segment
		(start 354.327206 -290.15055)
		(end 354.327206 -290.32835)
		(width 0.0889)
		(layer "In11.Cu")
		(net "UPI_CPU1_CPU0_P2P2_DN<2>")
	)
	(segment
		(start 86.188296 -286.799782)
		(end 86.187534 -286.799274)
		(width 0.0889)
		(layer "In11.Cu")
		(net "UPI_CPU1_CPU0_P2P2_DN<2>")
	)
	(segment
		(start 322.277486 -328.110342)
		(end 321.153536 -330.823824)
		(width 0.14732)
		(layer "In11.Cu")
		(net "UPI_CPU1_CPU0_P2P2_DN<2>")
	)
	(segment
		(start 78.28153 -300.419008)
		(end 78.28153 -300.214284)
		(width 0.14732)
		(layer "In11.Cu")
		(net "UPI_CPU1_CPU0_P2P2_DN<2>")
	)
	(segment
		(start 72.084692 -376.965972)
		(end 71.895462 -377.044204)
		(width 0.14732)
		(layer "In11.Cu")
		(net "UPI_CPU1_CPU0_P2P2_DN<2>")
	)
	(segment
		(start 79.267558 -299.228256)
		(end 79.472282 -299.228256)
		(width 0.14732)
		(layer "In11.Cu")
		(net "UPI_CPU1_CPU0_P2P2_DN<2>")
	)
	(segment
		(start 356.118414 -285.171896)
		(end 356.106222 -285.179008)
		(width 0.0889)
		(layer "In11.Cu")
		(net "UPI_CPU1_CPU0_P2P2_DN<2>")
	)
	(segment
		(start 62.559438 -313.05627)
		(end 62.900052 -312.9153)
		(width 0.14732)
		(layer "In11.Cu")
		(net "UPI_CPU1_CPU0_P2P2_DN<2>")
	)
	(segment
		(start 354.24745 -288.422334)
		(end 354.23856 -288.427414)
		(width 0.0889)
		(layer "In11.Cu")
		(net "UPI_CPU1_CPU0_P2P2_DN<2>")
	)
	(segment
		(start 85.594952 -288.406586)
		(end 85.687408 -288.31413)
		(width 0.0889)
		(layer "In11.Cu")
		(net "UPI_CPU1_CPU0_P2P2_DN<2>")
	)
	(segment
		(start 52.71008 -324.930008)
		(end 54.665626 -322.974462)
		(width 0.14732)
		(layer "In11.Cu")
		(net "UPI_CPU1_CPU0_P2P2_DN<2>")
	)
	(segment
		(start 354.426266 -291.419788)
		(end 354.384356 -291.461698)
		(width 0.0889)
		(layer "In11.Cu")
		(net "UPI_CPU1_CPU0_P2P2_DN<2>")
	)
	(segment
		(start 78.54188 -299.953934)
		(end 78.746604 -299.953934)
		(width 0.14732)
		(layer "In11.Cu")
		(net "UPI_CPU1_CPU0_P2P2_DN<2>")
	)
	(segment
		(start 85.694012 -288.840418)
		(end 85.594952 -288.741358)
		(width 0.0889)
		(layer "In11.Cu")
		(net "UPI_CPU1_CPU0_P2P2_DN<2>")
	)
	(segment
		(start 85.19795 -290.937696)
		(end 85.338412 -290.937696)
		(width 0.0889)
		(layer "In11.Cu")
		(net "UPI_CPU1_CPU0_P2P2_DN<2>")
	)
	(segment
		(start 84.710016 -291.42563)
		(end 84.806282 -291.329364)
		(width 0.0889)
		(layer "In11.Cu")
		(net "UPI_CPU1_CPU0_P2P2_DN<2>")
	)
	(segment
		(start 57.517284 -334.318102)
		(end 55.54599 -331.963776)
		(width 0.14732)
		(layer "In11.Cu")
		(net "UPI_CPU1_CPU0_P2P2_DN<2>")
	)
	(segment
		(start 86.219538 -287.922462)
		(end 86.345268 -287.796732)
		(width 0.0889)
		(layer "In11.Cu")
		(net "UPI_CPU1_CPU0_P2P2_DN<2>")
	)
	(segment
		(start 78.28153 -300.214284)
		(end 78.54188 -299.953934)
		(width 0.14732)
		(layer "In11.Cu")
		(net "UPI_CPU1_CPU0_P2P2_DN<2>")
	)
	(segment
		(start 56.115712 -317.567056)
		(end 57.504838 -316.42685)
		(width 0.14732)
		(layer "In11.Cu")
		(net "UPI_CPU1_CPU0_P2P2_DN<2>")
	)
	(segment
		(start 355.365812 -286.4612)
		(end 355.365812 -286.475424)
		(width 0.0889)
		(layer "In11.Cu")
		(net "UPI_CPU1_CPU0_P2P2_DN<2>")
	)
	(segment
		(start 85.464142 -290.811966)
		(end 85.464142 -290.671504)
		(width 0.0889)
		(layer "In11.Cu")
		(net "UPI_CPU1_CPU0_P2P2_DN<2>")
	)
	(segment
		(start 85.072474 -291.203634)
		(end 85.072474 -291.063172)
		(width 0.0889)
		(layer "In11.Cu")
		(net "UPI_CPU1_CPU0_P2P2_DN<2>")
	)
	(segment
		(start 61.731398 -313.242452)
		(end 62.370462 -312.977784)
		(width 0.14732)
		(layer "In11.Cu")
		(net "UPI_CPU1_CPU0_P2P2_DN<2>")
	)
	(segment
		(start 72.503538 -377.296172)
		(end 72.425052 -377.106942)
		(width 0.14732)
		(layer "In11.Cu")
		(net "UPI_CPU1_CPU0_P2P2_DN<2>")
	)
	(segment
		(start 354.426012 -288.103056)
		(end 354.426012 -288.111438)
		(width 0.0889)
		(layer "In11.Cu")
		(net "UPI_CPU1_CPU0_P2P2_DN<2>")
	)
	(segment
		(start 79.732886 -298.967652)
		(end 79.732886 -298.762928)
		(width 0.14732)
		(layer "In11.Cu")
		(net "UPI_CPU1_CPU0_P2P2_DN<2>")
	)
	(segment
		(start 62.370462 -312.977784)
		(end 62.559438 -313.05627)
		(width 0.14732)
		(layer "In11.Cu")
		(net "UPI_CPU1_CPU0_P2P2_DN<2>")
	)
	(segment
		(start 357.99776 -278.66086)
		(end 357.991664 -278.664416)
		(width 0.0889)
		(layer "In11.Cu")
		(net "UPI_CPU1_CPU0_P2P2_DN<2>")
	)
	(segment
		(start 67.743832 -310.751982)
		(end 76.364592 -302.131222)
		(width 0.14732)
		(layer "In11.Cu")
		(net "UPI_CPU1_CPU0_P2P2_DN<2>")
	)
	(segment
		(start 54.665626 -322.909184)
		(end 54.66588 -322.90893)
		(width 0.14732)
		(layer "In11.Cu")
		(net "UPI_CPU1_CPU0_P2P2_DN<2>")
	)
	(segment
		(start 86.531958 -286.746442)
		(end 86.375494 -286.475424)
		(width 0.0889)
		(layer "In11.Cu")
		(net "UPI_CPU1_CPU0_P2P2_DN<2>")
	)
	(segment
		(start 55.543958 -331.961236)
		(end 55.520844 -331.933804)
		(width 0.14732)
		(layer "In11.Cu")
		(net "UPI_CPU1_CPU0_P2P2_DN<2>")
	)
	(segment
		(start 353.581716 -297.646852)
		(end 353.332796 -298.247816)
		(width 0.14732)
		(layer "In11.Cu")
		(net "UPI_CPU1_CPU0_P2P2_DN<2>")
	)
	(arc
		(start 357.715312 -282.399232)
		(mid 357.715302 -282.408632)
		(end 357.715058 -282.418028)
		(width 0.0889)
		(layer "In11.Cu")
		(net "UPI_CPU1_CPU0_P2P2_DN<2>")
	)
	(arc
		(start 356.305612 -284.856174)
		(mid 356.253342 -285.038539)
		(end 356.118414 -285.171896)
		(width 0.0889)
		(layer "In11.Cu")
		(net "UPI_CPU1_CPU0_P2P2_DN<2>")
	)
	(arc
		(start 358.185212 -276.708616)
		(mid 358.259128 -276.988118)
		(end 358.461564 -277.194518)
		(width 0.0889)
		(layer "In11.Cu")
		(net "UPI_CPU1_CPU0_P2P2_DN<2>")
	)
	(arc
		(start 357.245412 -281.601926)
		(mid 357.323523 -281.878875)
		(end 357.52786 -282.081478)
		(width 0.0889)
		(layer "In11.Cu")
		(net "UPI_CPU1_CPU0_P2P2_DN<2>")
	)
	(arc
		(start 357.991664 -278.664416)
		(mid 357.789251 -278.870829)
		(end 357.715312 -279.150318)
		(width 0.0889)
		(layer "In11.Cu")
		(net "UPI_CPU1_CPU0_P2P2_DN<2>")
	)
	(arc
		(start 86.000844 -286.482028)
		(mid 86.000854 -286.472628)
		(end 86.001098 -286.463232)
		(width 0.0889)
		(layer "In11.Cu")
		(net "UPI_CPU1_CPU0_P2P2_DN<2>")
	)
	(arc
		(start 357.53675 -280.458926)
		(mid 357.664643 -280.589988)
		(end 357.715058 -280.766012)
		(width 0.0889)
		(layer "In11.Cu")
		(net "UPI_CPU1_CPU0_P2P2_DN<2>")
	)
	(arc
		(start 357.05796 -283.544264)
		(mid 356.853625 -283.746869)
		(end 356.775512 -284.023816)
		(width 0.0889)
		(layer "In11.Cu")
		(net "UPI_CPU1_CPU0_P2P2_DN<2>")
	)
	(arc
		(start 355.835712 -285.661354)
		(mid 355.788033 -285.844254)
		(end 355.65715 -285.980632)
		(width 0.0889)
		(layer "In11.Cu")
		(net "UPI_CPU1_CPU0_P2P2_DN<2>")
	)
	(arc
		(start 357.52786 -281.102562)
		(mid 357.323525 -281.305167)
		(end 357.245412 -281.582114)
		(width 0.0889)
		(layer "In11.Cu")
		(net "UPI_CPU1_CPU0_P2P2_DN<2>")
	)
	(arc
		(start 356.582218 -284.361636)
		(mid 356.379631 -284.567987)
		(end 356.305612 -284.847538)
		(width 0.0889)
		(layer "In11.Cu")
		(net "UPI_CPU1_CPU0_P2P2_DN<2>")
	)
	(arc
		(start 86.188296 -286.151066)
		(mid 86.375494 -286.100923)
		(end 86.562692 -286.151066)
		(width 0.0889)
		(layer "In11.Cu")
		(net "UPI_CPU1_CPU0_P2P2_DN<2>")
	)
	(arc
		(start 354.241862 -289.446462)
		(mid 354.351009 -289.53039)
		(end 354.426012 -289.645852)
		(width 0.0889)
		(layer "In11.Cu")
		(net "UPI_CPU1_CPU0_P2P2_DN<2>")
	)
	(arc
		(start 357.715312 -279.150318)
		(mid 357.667633 -279.333218)
		(end 357.53675 -279.469596)
		(width 0.0889)
		(layer "In11.Cu")
		(net "UPI_CPU1_CPU0_P2P2_DN<2>")
	)
	(arc
		(start 358.00665 -276.389338)
		(mid 358.137564 -276.525698)
		(end 358.185212 -276.708616)
		(width 0.0889)
		(layer "In11.Cu")
		(net "UPI_CPU1_CPU0_P2P2_DN<2>")
	)
	(arc
		(start 357.53675 -282.086558)
		(mid 357.666039 -282.220044)
		(end 357.715312 -282.399232)
		(width 0.0889)
		(layer "In11.Cu")
		(net "UPI_CPU1_CPU0_P2P2_DN<2>")
	)
	(arc
		(start 86.179406 -286.794702)
		(mid 86.050117 -286.661216)
		(end 86.000844 -286.482028)
		(width 0.0889)
		(layer "In11.Cu")
		(net "UPI_CPU1_CPU0_P2P2_DN<2>")
	)
	(arc
		(start 357.135938 -276.422104)
		(mid 357.383949 -276.458569)
		(end 357.623364 -276.384258)
		(width 0.0889)
		(layer "In11.Cu")
		(net "UPI_CPU1_CPU0_P2P2_DN<2>")
	)
	(arc
		(start 355.64826 -285.985712)
		(mid 355.444955 -286.186578)
		(end 355.365812 -286.4612)
		(width 0.0889)
		(layer "In11.Cu")
		(net "UPI_CPU1_CPU0_P2P2_DN<2>")
	)
	(arc
		(start 354.425758 -288.117788)
		(mid 354.374704 -288.292368)
		(end 354.24745 -288.422334)
		(width 0.0889)
		(layer "In11.Cu")
		(net "UPI_CPU1_CPU0_P2P2_DN<2>")
	)
	(arc
		(start 357.116126 -276.413976)
		(mid 357.125993 -276.418135)
		(end 357.135938 -276.422104)
		(width 0.0889)
		(layer "In11.Cu")
		(net "UPI_CPU1_CPU0_P2P2_DN<2>")
	)
	(arc
		(start 353.956366 -289.114738)
		(mid 354.067704 -289.307638)
		(end 354.241862 -289.446462)
		(width 0.0889)
		(layer "In11.Cu")
		(net "UPI_CPU1_CPU0_P2P2_DN<2>")
	)
	(arc
		(start 357.715058 -282.418028)
		(mid 357.664565 -282.594006)
		(end 357.53675 -282.725114)
		(width 0.0889)
		(layer "In11.Cu")
		(net "UPI_CPU1_CPU0_P2P2_DN<2>")
	)
	(arc
		(start 358.185212 -278.336502)
		(mid 358.137533 -278.519402)
		(end 358.00665 -278.65578)
		(width 0.0889)
		(layer "In11.Cu")
		(net "UPI_CPU1_CPU0_P2P2_DN<2>")
	)
	(arc
		(start 86.470744 -287.279334)
		(mid 86.392633 -287.002385)
		(end 86.188296 -286.799782)
		(width 0.0889)
		(layer "In11.Cu")
		(net "UPI_CPU1_CPU0_P2P2_DN<2>")
	)
	(arc
		(start 355.17836 -286.799782)
		(mid 354.974025 -287.002387)
		(end 354.895912 -287.279334)
		(width 0.0889)
		(layer "In11.Cu")
		(net "UPI_CPU1_CPU0_P2P2_DN<2>")
	)
	(arc
		(start 354.895912 -287.297876)
		(mid 354.843642 -287.480241)
		(end 354.708714 -287.613598)
		(width 0.0889)
		(layer "In11.Cu")
		(net "UPI_CPU1_CPU0_P2P2_DN<2>")
	)
	(arc
		(start 354.23856 -288.427414)
		(mid 354.037278 -288.624901)
		(end 353.956366 -288.895028)
		(width 0.0889)
		(layer "In11.Cu")
		(net "UPI_CPU1_CPU0_P2P2_DN<2>")
	)
	(arc
		(start 86.001098 -286.463232)
		(mid 86.051591 -286.287254)
		(end 86.179406 -286.156146)
		(width 0.0889)
		(layer "In11.Cu")
		(net "UPI_CPU1_CPU0_P2P2_DN<2>")
	)
	(arc
		(start 86.571582 -286.156146)
		(mid 86.702496 -286.292506)
		(end 86.750144 -286.475424)
		(width 0.0889)
		(layer "In11.Cu")
		(net "UPI_CPU1_CPU0_P2P2_DN<2>")
	)
	(arc
		(start 356.775512 -284.042358)
		(mid 356.723242 -284.224723)
		(end 356.588314 -284.35808)
		(width 0.0889)
		(layer "In11.Cu")
		(net "UPI_CPU1_CPU0_P2P2_DN<2>")
	)
	(arc
		(start 358.46766 -277.84679)
		(mid 358.265374 -278.045771)
		(end 358.185212 -278.31796)
		(width 0.0889)
		(layer "In11.Cu")
		(net "UPI_CPU1_CPU0_P2P2_DN<2>")
	)
	(arc
		(start 358.47655 -277.203154)
		(mid 358.655147 -277.522432)
		(end 358.47655 -277.84171)
		(width 0.0889)
		(layer "In11.Cu")
		(net "UPI_CPU1_CPU0_P2P2_DN<2>")
	)
	(arc
		(start 354.702618 -287.617154)
		(mid 354.500031 -287.823505)
		(end 354.426012 -288.103056)
		(width 0.0889)
		(layer "In11.Cu")
		(net "UPI_CPU1_CPU0_P2P2_DN<2>")
	)
	(arc
		(start 86.750144 -286.475424)
		(mid 86.713284 -286.637221)
		(end 86.61019 -286.76727)
		(width 0.0889)
		(layer "In11.Cu")
		(net "UPI_CPU1_CPU0_P2P2_DN<2>")
	)
	(arc
		(start 357.245412 -283.219906)
		(mid 357.197733 -283.402806)
		(end 357.06685 -283.539184)
		(width 0.0889)
		(layer "In11.Cu")
		(net "UPI_CPU1_CPU0_P2P2_DN<2>")
	)
	(arc
		(start 357.52786 -282.730194)
		(mid 357.325574 -282.929175)
		(end 357.245412 -283.201364)
		(width 0.0889)
		(layer "In11.Cu")
		(net "UPI_CPU1_CPU0_P2P2_DN<2>")
	)
	(arc
		(start 357.623364 -276.384258)
		(mid 357.810562 -276.334115)
		(end 357.99776 -276.384258)
		(width 0.0889)
		(layer "In11.Cu")
		(net "UPI_CPU1_CPU0_P2P2_DN<2>")
	)
	(arc
		(start 357.715058 -280.766012)
		(mid 357.715303 -280.775408)
		(end 357.715312 -280.784808)
		(width 0.0889)
		(layer "In11.Cu")
		(net "UPI_CPU1_CPU0_P2P2_DN<2>")
	)
	(arc
		(start 357.52786 -279.474676)
		(mid 357.323525 -279.677281)
		(end 357.245412 -279.954228)
		(width 0.0889)
		(layer "In11.Cu")
		(net "UPI_CPU1_CPU0_P2P2_DN<2>")
	)
	(arc
		(start 355.365812 -286.475424)
		(mid 355.318133 -286.658324)
		(end 355.18725 -286.794702)
		(width 0.0889)
		(layer "In11.Cu")
		(net "UPI_CPU1_CPU0_P2P2_DN<2>")
	)
	(arc
		(start 357.245412 -279.982676)
		(mid 357.325574 -280.254865)
		(end 357.52786 -280.453846)
		(width 0.0889)
		(layer "In11.Cu")
		(net "UPI_CPU1_CPU0_P2P2_DN<2>")
	)
	(arc
		(start 356.106222 -285.179008)
		(mid 355.907994 -285.384856)
		(end 355.835712 -285.661354)
		(width 0.0889)
		(layer "In11.Cu")
		(net "UPI_CPU1_CPU0_P2P2_DN<2>")
	)
	(arc
		(start 357.715312 -280.784808)
		(mid 357.666059 -280.964008)
		(end 357.53675 -281.097482)
		(width 0.0889)
		(layer "In11.Cu")
		(net "UPI_CPU1_CPU0_P2P2_DN<2>")
	)
	(segment
		(start 334.785716 -280.77795)
		(end 334.785462 -280.778204)
		(width 0.13208)
		(layer "F.Cu")
		(net "UPI_CPU1_CPU0_P2P2_DN<23>")
	)
	(segment
		(start 108.930694 -272.917158)
		(end 108.930694 -273.453098)
		(width 0.13208)
		(layer "F.Cu")
		(net "UPI_CPU1_CPU0_P2P2_DN<23>")
	)
	(segment
		(start 334.785716 -280.242264)
		(end 334.785716 -280.77795)
		(width 0.13208)
		(layer "F.Cu")
		(net "UPI_CPU1_CPU0_P2P2_DN<23>")
	)
	(segment
		(start 250.171966 -349.01632)
		(end 249.864118 -349.324168)
		(width 0.14732)
		(layer "In11.Cu")
		(net "UPI_CPU1_CPU0_P2P2_DN<23>")
	)
	(segment
		(start 109.674406 -278.017224)
		(end 109.683296 -278.012144)
		(width 0.0889)
		(layer "In11.Cu")
		(net "UPI_CPU1_CPU0_P2P2_DN<23>")
	)
	(segment
		(start 245.764812 -353.126548)
		(end 245.72849 -353.331526)
		(width 0.14732)
		(layer "In11.Cu")
		(net "UPI_CPU1_CPU0_P2P2_DN<23>")
	)
	(segment
		(start 333.56042 -286.80156)
		(end 333.558896 -286.802576)
		(width 0.0889)
		(layer "In11.Cu")
		(net "UPI_CPU1_CPU0_P2P2_DN<23>")
	)
	(segment
		(start 109.309916 -291.383974)
		(end 109.309916 -290.420806)
		(width 0.0889)
		(layer "In11.Cu")
		(net "UPI_CPU1_CPU0_P2P2_DN<23>")
	)
	(segment
		(start 328.800714 -293.144956)
		(end 328.89698 -293.32555)
		(width 0.14732)
		(layer "In11.Cu")
		(net "UPI_CPU1_CPU0_P2P2_DN<23>")
	)
	(segment
		(start 75.879198 -335.273904)
		(end 76.436982 -329.604878)
		(width 0.14732)
		(layer "In11.Cu")
		(net "UPI_CPU1_CPU0_P2P2_DN<23>")
	)
	(segment
		(start 251.044456 -346.69984)
		(end 250.171966 -346.69984)
		(width 0.14732)
		(layer "In11.Cu")
		(net "UPI_CPU1_CPU0_P2P2_DN<23>")
	)
	(segment
		(start 333.557626 -286.803338)
		(end 333.55661 -286.803846)
		(width 0.0889)
		(layer "In11.Cu")
		(net "UPI_CPU1_CPU0_P2P2_DN<23>")
	)
	(segment
		(start 108.27385 -281.102562)
		(end 108.26496 -281.097482)
		(width 0.0889)
		(layer "In11.Cu")
		(net "UPI_CPU1_CPU0_P2P2_DN<23>")
	)
	(segment
		(start 329.089004 -292.695884)
		(end 328.907902 -292.792404)
		(width 0.14732)
		(layer "In11.Cu")
		(net "UPI_CPU1_CPU0_P2P2_DN<23>")
	)
	(segment
		(start 108.556044 -279.986232)
		(end 108.556044 -279.964134)
		(width 0.0889)
		(layer "In11.Cu")
		(net "UPI_CPU1_CPU0_P2P2_DN<23>")
	)
	(segment
		(start 75.879198 -352.312986)
		(end 75.879198 -335.273904)
		(width 0.14732)
		(layer "In11.Cu")
		(net "UPI_CPU1_CPU0_P2P2_DN<23>")
	)
	(segment
		(start 334.785462 -280.778204)
		(end 335.098136 -280.778204)
		(width 0.0889)
		(layer "In11.Cu")
		(net "UPI_CPU1_CPU0_P2P2_DN<23>")
	)
	(segment
		(start 334.492346 -284.516576)
		(end 334.500728 -284.521402)
		(width 0.0889)
		(layer "In11.Cu")
		(net "UPI_CPU1_CPU0_P2P2_DN<23>")
	)
	(segment
		(start 246.877586 -350.139254)
		(end 246.802148 -350.567752)
		(width 0.14732)
		(layer "In11.Cu")
		(net "UPI_CPU1_CPU0_P2P2_DN<23>")
	)
	(segment
		(start 260.134354 -327.740264)
		(end 249.864118 -338.0105)
		(width 0.14732)
		(layer "In11.Cu")
		(net "UPI_CPU1_CPU0_P2P2_DN<23>")
	)
	(segment
		(start 286.384238 -316.318646)
		(end 285.794704 -316.90818)
		(width 0.14732)
		(layer "In11.Cu")
		(net "UPI_CPU1_CPU0_P2P2_DN<23>")
	)
	(segment
		(start 199.94626 -366.31118)
		(end 160.741106 -373.224044)
		(width 0.14732)
		(layer "In11.Cu")
		(net "UPI_CPU1_CPU0_P2P2_DN<23>")
	)
	(segment
		(start 334.503268 -281.916632)
		(end 334.502252 -281.91714)
		(width 0.0889)
		(layer "In11.Cu")
		(net "UPI_CPU1_CPU0_P2P2_DN<23>")
	)
	(segment
		(start 80.45323 -361.241848)
		(end 78.9559 -359.744518)
		(width 0.14732)
		(layer "In11.Cu")
		(net "UPI_CPU1_CPU0_P2P2_DN<23>")
	)
	(segment
		(start 245.245636 -353.670108)
		(end 245.040658 -353.633786)
		(width 0.14732)
		(layer "In11.Cu")
		(net "UPI_CPU1_CPU0_P2P2_DN<23>")
	)
	(segment
		(start 109.204506 -278.83104)
		(end 109.213396 -278.82596)
		(width 0.0889)
		(layer "In11.Cu")
		(net "UPI_CPU1_CPU0_P2P2_DN<23>")
	)
	(segment
		(start 334.22082 -282.405836)
		(end 334.22082 -282.411932)
		(width 0.0889)
		(layer "In11.Cu")
		(net "UPI_CPU1_CPU0_P2P2_DN<23>")
	)
	(segment
		(start 109.176312 -273.747992)
		(end 109.087158 -273.724116)
		(width 0.0889)
		(layer "In11.Cu")
		(net "UPI_CPU1_CPU0_P2P2_DN<23>")
	)
	(segment
		(start 84.691728 -319.761362)
		(end 101.306376 -306.126642)
		(width 0.14732)
		(layer "In11.Cu")
		(net "UPI_CPU1_CPU0_P2P2_DN<23>")
	)
	(segment
		(start 111.467646 -289.780218)
		(end 111.845344 -289.40252)
		(width 0.0889)
		(layer "In11.Cu")
		(net "UPI_CPU1_CPU0_P2P2_DN<23>")
	)
	(segment
		(start 334.502252 -281.91714)
		(end 334.499458 -281.918918)
		(width 0.0889)
		(layer "In11.Cu")
		(net "UPI_CPU1_CPU0_P2P2_DN<23>")
	)
	(segment
		(start 251.044456 -349.01632)
		(end 250.171966 -349.01632)
		(width 0.14732)
		(layer "In11.Cu")
		(net "UPI_CPU1_CPU0_P2P2_DN<23>")
	)
	(segment
		(start 291.241226 -317.680848)
		(end 290.911788 -317.35141)
		(width 0.14732)
		(layer "In11.Cu")
		(net "UPI_CPU1_CPU0_P2P2_DN<23>")
	)
	(segment
		(start 112.03305 -287.613598)
		(end 112.02416 -287.608518)
		(width 0.0889)
		(layer "In11.Cu")
		(net "UPI_CPU1_CPU0_P2P2_DN<23>")
	)
	(segment
		(start 333.750666 -286.475424)
		(end 333.750666 -286.483298)
		(width 0.0889)
		(layer "In11.Cu")
		(net "UPI_CPU1_CPU0_P2P2_DN<23>")
	)
	(segment
		(start 249.864118 -347.824552)
		(end 250.171966 -348.1324)
		(width 0.14732)
		(layer "In11.Cu")
		(net "UPI_CPU1_CPU0_P2P2_DN<23>")
	)
	(segment
		(start 328.89698 -293.32555)
		(end 328.750422 -293.807642)
		(width 0.14732)
		(layer "In11.Cu")
		(net "UPI_CPU1_CPU0_P2P2_DN<23>")
	)
	(segment
		(start 274.676108 -322.278502)
		(end 263.07415 -322.278502)
		(width 0.14732)
		(layer "In11.Cu")
		(net "UPI_CPU1_CPU0_P2P2_DN<23>")
	)
	(segment
		(start 109.965744 -277.540974)
		(end 109.965744 -277.522432)
		(width 0.0889)
		(layer "In11.Cu")
		(net "UPI_CPU1_CPU0_P2P2_DN<23>")
	)
	(segment
		(start 261.868412 -324.97014)
		(end 261.343394 -324.445122)
		(width 0.14732)
		(layer "In11.Cu")
		(net "UPI_CPU1_CPU0_P2P2_DN<23>")
	)
	(segment
		(start 333.237586 -287.672526)
		(end 333.237586 -287.767014)
		(width 0.14732)
		(layer "In11.Cu")
		(net "UPI_CPU1_CPU0_P2P2_DN<23>")
	)
	(segment
		(start 247.97639 -349.745554)
		(end 247.547892 -349.670116)
		(width 0.14732)
		(layer "In11.Cu")
		(net "UPI_CPU1_CPU0_P2P2_DN<23>")
	)
	(segment
		(start 246.077994 -351.07499)
		(end 245.649496 -350.999552)
		(width 0.14732)
		(layer "In11.Cu")
		(net "UPI_CPU1_CPU0_P2P2_DN<23>")
	)
	(segment
		(start 110.144306 -277.203154)
		(end 110.153196 -277.198074)
		(width 0.0889)
		(layer "In11.Cu")
		(net "UPI_CPU1_CPU0_P2P2_DN<23>")
	)
	(segment
		(start 249.864118 -350.285812)
		(end 249.36323 -350.7867)
		(width 0.14732)
		(layer "In11.Cu")
		(net "UPI_CPU1_CPU0_P2P2_DN<23>")
	)
	(segment
		(start 109.155484 -297.186096)
		(end 109.155484 -292.829742)
		(width 0.14732)
		(layer "In11.Cu")
		(net "UPI_CPU1_CPU0_P2P2_DN<23>")
	)
	(segment
		(start 251.044456 -342.06688)
		(end 250.171966 -342.06688)
		(width 0.14732)
		(layer "In11.Cu")
		(net "UPI_CPU1_CPU0_P2P2_DN<23>")
	)
	(segment
		(start 299.268134 -317.810388)
		(end 298.081954 -317.810388)
		(width 0.14732)
		(layer "In11.Cu")
		(net "UPI_CPU1_CPU0_P2P2_DN<23>")
	)
	(segment
		(start 331.14361 -289.656266)
		(end 331.14361 -289.86099)
		(width 0.14732)
		(layer "In11.Cu")
		(net "UPI_CPU1_CPU0_P2P2_DN<23>")
	)
	(segment
		(start 110.165388 -276.22627)
		(end 110.153196 -276.219158)
		(width 0.0889)
		(layer "In11.Cu")
		(net "UPI_CPU1_CPU0_P2P2_DN<23>")
	)
	(segment
		(start 333.279496 -287.608518)
		(end 333.237586 -287.650428)
		(width 0.0889)
		(layer "In11.Cu")
		(net "UPI_CPU1_CPU0_P2P2_DN<23>")
	)
	(segment
		(start 313.875674 -307.68798)
		(end 311.720738 -307.68798)
		(width 0.14732)
		(layer "In11.Cu")
		(net "UPI_CPU1_CPU0_P2P2_DN<23>")
	)
	(segment
		(start 249.864118 -340.875112)
		(end 250.171966 -341.18296)
		(width 0.14732)
		(layer "In11.Cu")
		(net "UPI_CPU1_CPU0_P2P2_DN<23>")
	)
	(segment
		(start 275.128736 -320.12001)
		(end 275.128736 -321.825874)
		(width 0.14732)
		(layer "In11.Cu")
		(net "UPI_CPU1_CPU0_P2P2_DN<23>")
	)
	(segment
		(start 330.678536 -290.12134)
		(end 330.417932 -290.381944)
		(width 0.14732)
		(layer "In11.Cu")
		(net "UPI_CPU1_CPU0_P2P2_DN<23>")
	)
	(segment
		(start 110.153196 -277.198074)
		(end 110.165388 -277.190962)
		(width 0.0889)
		(layer "In11.Cu")
		(net "UPI_CPU1_CPU0_P2P2_DN<23>")
	)
	(segment
		(start 334.500728 -284.521402)
		(end 334.502252 -284.522418)
		(width 0.0889)
		(layer "In11.Cu")
		(net "UPI_CPU1_CPU0_P2P2_DN<23>")
	)
	(segment
		(start 262.494014 -324.344538)
		(end 262.494014 -324.504558)
		(width 0.14732)
		(layer "In11.Cu")
		(net "UPI_CPU1_CPU0_P2P2_DN<23>")
	)
	(segment
		(start 330.417932 -290.381944)
		(end 330.417932 -290.586668)
		(width 0.14732)
		(layer "In11.Cu")
		(net "UPI_CPU1_CPU0_P2P2_DN<23>")
	)
	(segment
		(start 251.191776 -341.91956)
		(end 251.044456 -342.06688)
		(width 0.14732)
		(layer "In11.Cu")
		(net "UPI_CPU1_CPU0_P2P2_DN<23>")
	)
	(segment
		(start 262.028432 -324.97014)
		(end 261.868412 -324.97014)
		(width 0.14732)
		(layer "In11.Cu")
		(net "UPI_CPU1_CPU0_P2P2_DN<23>")
	)
	(segment
		(start 243.830094 -354.660962)
		(end 228.073712 -365.694468)
		(width 0.14732)
		(layer "In11.Cu")
		(net "UPI_CPU1_CPU0_P2P2_DN<23>")
	)
	(segment
		(start 251.191776 -348.27972)
		(end 251.191776 -348.869)
		(width 0.14732)
		(layer "In11.Cu")
		(net "UPI_CPU1_CPU0_P2P2_DN<23>")
	)
	(segment
		(start 250.171966 -342.06688)
		(end 249.864118 -342.374728)
		(width 0.14732)
		(layer "In11.Cu")
		(net "UPI_CPU1_CPU0_P2P2_DN<23>")
	)
	(segment
		(start 330.88326 -290.12134)
		(end 330.678536 -290.12134)
		(width 0.14732)
		(layer "In11.Cu")
		(net "UPI_CPU1_CPU0_P2P2_DN<23>")
	)
	(segment
		(start 328.907902 -292.792404)
		(end 328.800714 -293.144956)
		(width 0.14732)
		(layer "In11.Cu")
		(net "UPI_CPU1_CPU0_P2P2_DN<23>")
	)
	(segment
		(start 276.98192 -318.266826)
		(end 275.128736 -320.12001)
		(width 0.14732)
		(layer "In11.Cu")
		(net "UPI_CPU1_CPU0_P2P2_DN<23>")
	)
	(segment
		(start 333.564484 -286.799274)
		(end 333.56042 -286.80156)
		(width 0.0889)
		(layer "In11.Cu")
		(net "UPI_CPU1_CPU0_P2P2_DN<23>")
	)
	(segment
		(start 251.191776 -343.64676)
		(end 251.191776 -344.23604)
		(width 0.14732)
		(layer "In11.Cu")
		(net "UPI_CPU1_CPU0_P2P2_DN<23>")
	)
	(segment
		(start 109.025944 -279.160224)
		(end 109.025944 -279.150318)
		(width 0.0889)
		(layer "In11.Cu")
		(net "UPI_CPU1_CPU0_P2P2_DN<23>")
	)
	(segment
		(start 249.36323 -350.7867)
		(end 249.042428 -351.011236)
		(width 0.14732)
		(layer "In11.Cu")
		(net "UPI_CPU1_CPU0_P2P2_DN<23>")
	)
	(segment
		(start 109.965744 -274.27682)
		(end 109.965744 -274.257008)
		(width 0.0889)
		(layer "In11.Cu")
		(net "UPI_CPU1_CPU0_P2P2_DN<23>")
	)
	(segment
		(start 111.568992 -286.803338)
		(end 111.563658 -286.80029)
		(width 0.0889)
		(layer "In11.Cu")
		(net "UPI_CPU1_CPU0_P2P2_DN<23>")
	)
	(segment
		(start 107.605576 -299.509942)
		(end 108.042964 -299.05071)
		(width 0.14732)
		(layer "In11.Cu")
		(net "UPI_CPU1_CPU0_P2P2_DN<23>")
	)
	(segment
		(start 108.734606 -279.644856)
		(end 108.743496 -279.639776)
		(width 0.0889)
		(layer "In11.Cu")
		(net "UPI_CPU1_CPU0_P2P2_DN<23>")
	)
	(segment
		(start 311.720738 -307.68798)
		(end 310.20258 -308.317138)
		(width 0.14732)
		(layer "In11.Cu")
		(net "UPI_CPU1_CPU0_P2P2_DN<23>")
	)
	(segment
		(start 244.903752 -351.897188)
		(end 245.764812 -353.126548)
		(width 0.14732)
		(layer "In11.Cu")
		(net "UPI_CPU1_CPU0_P2P2_DN<23>")
	)
	(segment
		(start 334.974692 -281.102054)
		(end 334.961992 -281.109166)
		(width 0.0889)
		(layer "In11.Cu")
		(net "UPI_CPU1_CPU0_P2P2_DN<23>")
	)
	(segment
		(start 109.026198 -282.414472)
		(end 109.026198 -282.405836)
		(width 0.0889)
		(layer "In11.Cu")
		(net "UPI_CPU1_CPU0_P2P2_DN<23>")
	)
	(segment
		(start 109.35208 -291.448236)
		(end 109.35208 -291.426138)
		(width 0.0889)
		(layer "In11.Cu")
		(net "UPI_CPU1_CPU0_P2P2_DN<23>")
	)
	(segment
		(start 244.97919 -351.46869)
		(end 244.903752 -351.897188)
		(width 0.14732)
		(layer "In11.Cu")
		(net "UPI_CPU1_CPU0_P2P2_DN<23>")
	)
	(segment
		(start 250.171966 -346.69984)
		(end 249.864118 -347.007688)
		(width 0.14732)
		(layer "In11.Cu")
		(net "UPI_CPU1_CPU0_P2P2_DN<23>")
	)
	(segment
		(start 108.042964 -299.05071)
		(end 108.813854 -298.011596)
		(width 0.14732)
		(layer "In11.Cu")
		(net "UPI_CPU1_CPU0_P2P2_DN<23>")
	)
	(segment
		(start 77.299566 -327.154286)
		(end 84.691728 -319.761362)
		(width 0.14732)
		(layer "In11.Cu")
		(net "UPI_CPU1_CPU0_P2P2_DN<23>")
	)
	(segment
		(start 251.044456 -345.81592)
		(end 251.191776 -345.96324)
		(width 0.14732)
		(layer "In11.Cu")
		(net "UPI_CPU1_CPU0_P2P2_DN<23>")
	)
	(segment
		(start 109.35208 -291.426138)
		(end 109.309916 -291.383974)
		(width 0.0889)
		(layer "In11.Cu")
		(net "UPI_CPU1_CPU0_P2P2_DN<23>")
	)
	(segment
		(start 275.128736 -321.825874)
		(end 274.676108 -322.278502)
		(width 0.14732)
		(layer "In11.Cu")
		(net "UPI_CPU1_CPU0_P2P2_DN<23>")
	)
	(segment
		(start 106.89082 -300.470824)
		(end 106.88574 -300.2661)
		(width 0.14732)
		(layer "In11.Cu")
		(net "UPI_CPU1_CPU0_P2P2_DN<23>")
	)
	(segment
		(start 109.965744 -275.8948)
		(end 109.965744 -275.880576)
		(width 0.0889)
		(layer "In11.Cu")
		(net "UPI_CPU1_CPU0_P2P2_DN<23>")
	)
	(segment
		(start 288.490406 -315.34989)
		(end 287.52165 -316.318646)
		(width 0.14732)
		(layer "In11.Cu")
		(net "UPI_CPU1_CPU0_P2P2_DN<23>")
	)
	(segment
		(start 109.155484 -292.829742)
		(end 109.35208 -292.35527)
		(width 0.14732)
		(layer "In11.Cu")
		(net "UPI_CPU1_CPU0_P2P2_DN<23>")
	)
	(segment
		(start 78.9559 -359.744518)
		(end 75.879198 -352.312986)
		(width 0.14732)
		(layer "In11.Cu")
		(net "UPI_CPU1_CPU0_P2P2_DN<23>")
	)
	(segment
		(start 249.864118 -349.324168)
		(end 249.864118 -350.285812)
		(width 0.14732)
		(layer "In11.Cu")
		(net "UPI_CPU1_CPU0_P2P2_DN<23>")
	)
	(segment
		(start 306.833778 -310.825388)
		(end 301.91583 -312.862722)
		(width 0.14732)
		(layer "In11.Cu")
		(net "UPI_CPU1_CPU0_P2P2_DN<23>")
	)
	(segment
		(start 314.059824 -307.610256)
		(end 313.875674 -307.68798)
		(width 0.14732)
		(layer "In11.Cu")
		(net "UPI_CPU1_CPU0_P2P2_DN<23>")
	)
	(segment
		(start 334.502252 -284.522418)
		(end 334.506824 -284.524958)
		(width 0.0889)
		(layer "In11.Cu")
		(net "UPI_CPU1_CPU0_P2P2_DN<23>")
	)
	(segment
		(start 308.798214 -309.25516)
		(end 308.023514 -310.02986)
		(width 0.14732)
		(layer "In11.Cu")
		(net "UPI_CPU1_CPU0_P2P2_DN<23>")
	)
	(segment
		(start 247.144032 -352.340672)
		(end 246.939054 -352.30435)
		(width 0.14732)
		(layer "In11.Cu")
		(net "UPI_CPU1_CPU0_P2P2_DN<23>")
	)
	(segment
		(start 111.845344 -288.832544)
		(end 111.845598 -288.832036)
		(width 0.0889)
		(layer "In11.Cu")
		(net "UPI_CPU1_CPU0_P2P2_DN<23>")
	)
	(segment
		(start 107.356402 -299.98162)
		(end 107.610656 -299.714666)
		(width 0.14732)
		(layer "In11.Cu")
		(net "UPI_CPU1_CPU0_P2P2_DN<23>")
	)
	(segment
		(start 334.690466 -284.835092)
		(end 334.690466 -284.855412)
		(width 0.0889)
		(layer "In11.Cu")
		(net "UPI_CPU1_CPU0_P2P2_DN<23>")
	)
	(segment
		(start 109.683296 -275.405088)
		(end 109.68228 -275.40458)
		(width 0.0889)
		(layer "In11.Cu")
		(net "UPI_CPU1_CPU0_P2P2_DN<23>")
	)
	(segment
		(start 289.900868 -315.34989)
		(end 288.490406 -315.34989)
		(width 0.14732)
		(layer "In11.Cu")
		(net "UPI_CPU1_CPU0_P2P2_DN<23>")
	)
	(segment
		(start 296.321988 -317.146432)
		(end 295.787572 -317.680848)
		(width 0.14732)
		(layer "In11.Cu")
		(net "UPI_CPU1_CPU0_P2P2_DN<23>")
	)
	(segment
		(start 251.044456 -343.49944)
		(end 251.191776 -343.64676)
		(width 0.14732)
		(layer "In11.Cu")
		(net "UPI_CPU1_CPU0_P2P2_DN<23>")
	)
	(segment
		(start 99.861116 -369.28044)
		(end 80.45323 -361.241848)
		(width 0.14732)
		(layer "In11.Cu")
		(net "UPI_CPU1_CPU0_P2P2_DN<23>")
	)
	(segment
		(start 247.547892 -349.670116)
		(end 246.877586 -350.139254)
		(width 0.14732)
		(layer "In11.Cu")
		(net "UPI_CPU1_CPU0_P2P2_DN<23>")
	)
	(segment
		(start 251.191776 -348.869)
		(end 251.044456 -349.01632)
		(width 0.14732)
		(layer "In11.Cu")
		(net "UPI_CPU1_CPU0_P2P2_DN<23>")
	)
	(segment
		(start 334.506824 -284.524958)
		(end 334.50784 -284.525466)
		(width 0.0889)
		(layer "In11.Cu")
		(net "UPI_CPU1_CPU0_P2P2_DN<23>")
	)
	(segment
		(start 249.042428 -351.011236)
		(end 248.83745 -350.974914)
		(width 0.14732)
		(layer "In11.Cu")
		(net "UPI_CPU1_CPU0_P2P2_DN<23>")
	)
	(segment
		(start 109.309916 -290.420806)
		(end 109.950504 -289.780218)
		(width 0.0889)
		(layer "In11.Cu")
		(net "UPI_CPU1_CPU0_P2P2_DN<23>")
	)
	(segment
		(start 334.982058 -281.097482)
		(end 334.974692 -281.102054)
		(width 0.0889)
		(layer "In11.Cu")
		(net "UPI_CPU1_CPU0_P2P2_DN<23>")
	)
	(segment
		(start 263.07415 -322.278502)
		(end 261.968996 -323.383656)
		(width 0.14732)
		(layer "In11.Cu")
		(net "UPI_CPU1_CPU0_P2P2_DN<23>")
	)
	(segment
		(start 111.09325 -285.985712)
		(end 111.08436 -285.980632)
		(width 0.0889)
		(layer "In11.Cu")
		(net "UPI_CPU1_CPU0_P2P2_DN<23>")
	)
	(segment
		(start 109.950504 -289.780218)
		(end 111.467646 -289.780218)
		(width 0.0889)
		(layer "In11.Cu")
		(net "UPI_CPU1_CPU0_P2P2_DN<23>")
	)
	(segment
		(start 331.14361 -289.86099)
		(end 330.88326 -290.12134)
		(width 0.14732)
		(layer "In11.Cu")
		(net "UPI_CPU1_CPU0_P2P2_DN<23>")
	)
	(segment
		(start 111.563658 -286.80029)
		(end 111.562896 -286.799782)
		(width 0.0889)
		(layer "In11.Cu")
		(net "UPI_CPU1_CPU0_P2P2_DN<23>")
	)
	(segment
		(start 109.965744 -284.033722)
		(end 109.965744 -284.023816)
		(width 0.0889)
		(layer "In11.Cu")
		(net "UPI_CPU1_CPU0_P2P2_DN<23>")
	)
	(segment
		(start 282.852114 -317.724282)
		(end 282.30957 -318.266826)
		(width 0.14732)
		(layer "In11.Cu")
		(net "UPI_CPU1_CPU0_P2P2_DN<23>")
	)
	(segment
		(start 251.044456 -341.18296)
		(end 251.191776 -341.33028)
		(width 0.14732)
		(layer "In11.Cu")
		(net "UPI_CPU1_CPU0_P2P2_DN<23>")
	)
	(segment
		(start 245.649496 -350.999552)
		(end 244.97919 -351.46869)
		(width 0.14732)
		(layer "In11.Cu")
		(net "UPI_CPU1_CPU0_P2P2_DN<23>")
	)
	(segment
		(start 106.636566 -300.738032)
		(end 106.89082 -300.470824)
		(width 0.14732)
		(layer "In11.Cu")
		(net "UPI_CPU1_CPU0_P2P2_DN<23>")
	)
	(segment
		(start 249.864118 -347.007688)
		(end 249.864118 -347.824552)
		(width 0.14732)
		(layer "In11.Cu")
		(net "UPI_CPU1_CPU0_P2P2_DN<23>")
	)
	(segment
		(start 250.171966 -348.1324)
		(end 251.044456 -348.1324)
		(width 0.14732)
		(layer "In11.Cu")
		(net "UPI_CPU1_CPU0_P2P2_DN<23>")
	)
	(segment
		(start 109.495844 -283.219906)
		(end 109.495844 -283.201364)
		(width 0.0889)
		(layer "In11.Cu")
		(net "UPI_CPU1_CPU0_P2P2_DN<23>")
	)
	(segment
		(start 245.72849 -353.331526)
		(end 245.245636 -353.670108)
		(width 0.14732)
		(layer "In11.Cu")
		(net "UPI_CPU1_CPU0_P2P2_DN<23>")
	)
	(segment
		(start 251.191776 -345.96324)
		(end 251.191776 -346.55252)
		(width 0.14732)
		(layer "In11.Cu")
		(net "UPI_CPU1_CPU0_P2P2_DN<23>")
	)
	(segment
		(start 334.038448 -283.712158)
		(end 334.043274 -283.714952)
		(width 0.0889)
		(layer "In11.Cu")
		(net "UPI_CPU1_CPU0_P2P2_DN<23>")
	)
	(segment
		(start 331.404214 -289.395662)
		(end 331.14361 -289.656266)
		(width 0.14732)
		(layer "In11.Cu")
		(net "UPI_CPU1_CPU0_P2P2_DN<23>")
	)
	(segment
		(start 262.494014 -324.504558)
		(end 262.028432 -324.97014)
		(width 0.14732)
		(layer "In11.Cu")
		(net "UPI_CPU1_CPU0_P2P2_DN<23>")
	)
	(segment
		(start 251.044456 -344.38336)
		(end 250.171966 -344.38336)
		(width 0.14732)
		(layer "In11.Cu")
		(net "UPI_CPU1_CPU0_P2P2_DN<23>")
	)
	(segment
		(start 329.823064 -291.181536)
		(end 329.322938 -291.926772)
		(width 0.14732)
		(layer "In11.Cu")
		(net "UPI_CPU1_CPU0_P2P2_DN<23>")
	)
	(segment
		(start 251.191776 -346.55252)
		(end 251.044456 -346.69984)
		(width 0.14732)
		(layer "In11.Cu")
		(net "UPI_CPU1_CPU0_P2P2_DN<23>")
	)
	(segment
		(start 334.50784 -281.913838)
		(end 334.503268 -281.916632)
		(width 0.0889)
		(layer "In11.Cu")
		(net "UPI_CPU1_CPU0_P2P2_DN<23>")
	)
	(segment
		(start 109.35208 -292.35527)
		(end 109.35208 -291.448236)
		(width 0.14732)
		(layer "In11.Cu")
		(net "UPI_CPU1_CPU0_P2P2_DN<23>")
	)
	(segment
		(start 301.91583 -312.862722)
		(end 299.617384 -314.945776)
		(width 0.14732)
		(layer "In11.Cu")
		(net "UPI_CPU1_CPU0_P2P2_DN<23>")
	)
	(segment
		(start 334.02524 -283.704538)
		(end 334.032098 -283.708602)
		(width 0.0889)
		(layer "In11.Cu")
		(net "UPI_CPU1_CPU0_P2P2_DN<23>")
	)
	(segment
		(start 333.558896 -286.802576)
		(end 333.557626 -286.803338)
		(width 0.0889)
		(layer "In11.Cu")
		(net "UPI_CPU1_CPU0_P2P2_DN<23>")
	)
	(segment
		(start 299.53458 -317.487554)
		(end 299.268134 -317.810388)
		(width 0.14732)
		(layer "In11.Cu")
		(net "UPI_CPU1_CPU0_P2P2_DN<23>")
	)
	(segment
		(start 328.462386 -294.256714)
		(end 328.558652 -294.437308)
		(width 0.14732)
		(layer "In11.Cu")
		(net "UPI_CPU1_CPU0_P2P2_DN<23>")
	)
	(segment
		(start 246.802148 -350.567752)
		(end 247.663208 -351.797112)
		(width 0.14732)
		(layer "In11.Cu")
		(net "UPI_CPU1_CPU0_P2P2_DN<23>")
	)
	(segment
		(start 244.179598 -352.404426)
		(end 243.7511 -352.328988)
		(width 0.14732)
		(layer "In11.Cu")
		(net "UPI_CPU1_CPU0_P2P2_DN<23>")
	)
	(segment
		(start 110.629446 -285.175452)
		(end 110.62335 -285.171896)
		(width 0.0889)
		(layer "In11.Cu")
		(net "UPI_CPU1_CPU0_P2P2_DN<23>")
	)
	(segment
		(start 108.749592 -281.919934)
		(end 108.743496 -281.916378)
		(width 0.0889)
		(layer "In11.Cu")
		(net "UPI_CPU1_CPU0_P2P2_DN<23>")
	)
	(segment
		(start 328.569574 -293.904162)
		(end 328.462386 -294.256714)
		(width 0.14732)
		(layer "In11.Cu")
		(net "UPI_CPU1_CPU0_P2P2_DN<23>")
	)
	(segment
		(start 109.683296 -283.544264)
		(end 109.674406 -283.539184)
		(width 0.0889)
		(layer "In11.Cu")
		(net "UPI_CPU1_CPU0_P2P2_DN<23>")
	)
	(segment
		(start 108.813854 -298.011596)
		(end 109.155484 -297.186096)
		(width 0.14732)
		(layer "In11.Cu")
		(net "UPI_CPU1_CPU0_P2P2_DN<23>")
	)
	(segment
		(start 106.431842 -300.742858)
		(end 106.636566 -300.738032)
		(width 0.14732)
		(layer "In11.Cu")
		(net "UPI_CPU1_CPU0_P2P2_DN<23>")
	)
	(segment
		(start 109.68228 -275.40458)
		(end 109.674406 -275.400008)
		(width 0.0889)
		(layer "In11.Cu")
		(net "UPI_CPU1_CPU0_P2P2_DN<23>")
	)
	(segment
		(start 249.864118 -342.374728)
		(end 249.864118 -343.191592)
		(width 0.14732)
		(layer "In11.Cu")
		(net "UPI_CPU1_CPU0_P2P2_DN<23>")
	)
	(segment
		(start 295.787572 -317.680848)
		(end 291.241226 -317.680848)
		(width 0.14732)
		(layer "In11.Cu")
		(net "UPI_CPU1_CPU0_P2P2_DN<23>")
	)
	(segment
		(start 250.171966 -344.38336)
		(end 249.864118 -344.691208)
		(width 0.14732)
		(layer "In11.Cu")
		(net "UPI_CPU1_CPU0_P2P2_DN<23>")
	)
	(segment
		(start 333.237586 -287.650428)
		(end 333.237586 -287.672526)
		(width 0.0889)
		(layer "In11.Cu")
		(net "UPI_CPU1_CPU0_P2P2_DN<23>")
	)
	(segment
		(start 76.436982 -329.604878)
		(end 76.857352 -328.088498)
		(width 0.14732)
		(layer "In11.Cu")
		(net "UPI_CPU1_CPU0_P2P2_DN<23>")
	)
	(segment
		(start 251.191776 -344.23604)
		(end 251.044456 -344.38336)
		(width 0.14732)
		(layer "In11.Cu")
		(net "UPI_CPU1_CPU0_P2P2_DN<23>")
	)
	(segment
		(start 261.343394 -324.445122)
		(end 260.90753 -324.445122)
		(width 0.14732)
		(layer "In11.Cu")
		(net "UPI_CPU1_CPU0_P2P2_DN<23>")
	)
	(segment
		(start 328.750422 -293.807642)
		(end 328.569574 -293.904162)
		(width 0.14732)
		(layer "In11.Cu")
		(net "UPI_CPU1_CPU0_P2P2_DN<23>")
	)
	(segment
		(start 318.102996 -307.610256)
		(end 314.059824 -307.610256)
		(width 0.14732)
		(layer "In11.Cu")
		(net "UPI_CPU1_CPU0_P2P2_DN<23>")
	)
	(segment
		(start 160.741106 -373.224044)
		(end 126.446026 -373.224044)
		(width 0.14732)
		(layer "In11.Cu")
		(net "UPI_CPU1_CPU0_P2P2_DN<23>")
	)
	(segment
		(start 297.417998 -317.146432)
		(end 296.321988 -317.146432)
		(width 0.14732)
		(layer "In11.Cu")
		(net "UPI_CPU1_CPU0_P2P2_DN<23>")
	)
	(segment
		(start 250.171966 -343.49944)
		(end 251.044456 -343.49944)
		(width 0.14732)
		(layer "In11.Cu")
		(net "UPI_CPU1_CPU0_P2P2_DN<23>")
	)
	(segment
		(start 109.495844 -278.346408)
		(end 109.495844 -278.336502)
		(width 0.0889)
		(layer "In11.Cu")
		(net "UPI_CPU1_CPU0_P2P2_DN<23>")
	)
	(segment
		(start 228.073712 -365.694468)
		(end 212.261704 -368.482626)
		(width 0.14732)
		(layer "In11.Cu")
		(net "UPI_CPU1_CPU0_P2P2_DN<23>")
	)
	(segment
		(start 329.322938 -291.926772)
		(end 329.089004 -292.695884)
		(width 0.14732)
		(layer "In11.Cu")
		(net "UPI_CPU1_CPU0_P2P2_DN<23>")
	)
	(segment
		(start 327.369678 -298.343574)
		(end 318.102996 -307.610256)
		(width 0.14732)
		(layer "In11.Cu")
		(net "UPI_CPU1_CPU0_P2P2_DN<23>")
	)
	(segment
		(start 290.911788 -317.35141)
		(end 290.911788 -316.36081)
		(width 0.14732)
		(layer "In11.Cu")
		(net "UPI_CPU1_CPU0_P2P2_DN<23>")
	)
	(segment
		(start 285.794704 -317.389256)
		(end 285.459678 -317.724282)
		(width 0.14732)
		(layer "In11.Cu")
		(net "UPI_CPU1_CPU0_P2P2_DN<23>")
	)
	(segment
		(start 107.151678 -299.9867)
		(end 107.356402 -299.98162)
		(width 0.14732)
		(layer "In11.Cu")
		(net "UPI_CPU1_CPU0_P2P2_DN<23>")
	)
	(segment
		(start 111.845344 -289.40252)
		(end 111.845344 -288.832544)
		(width 0.0889)
		(layer "In11.Cu")
		(net "UPI_CPU1_CPU0_P2P2_DN<23>")
	)
	(segment
		(start 248.83745 -350.974914)
		(end 247.97639 -349.745554)
		(width 0.14732)
		(layer "In11.Cu")
		(net "UPI_CPU1_CPU0_P2P2_DN<23>")
	)
	(segment
		(start 107.610656 -299.714666)
		(end 107.605576 -299.509942)
		(width 0.14732)
		(layer "In11.Cu")
		(net "UPI_CPU1_CPU0_P2P2_DN<23>")
	)
	(segment
		(start 290.911788 -316.36081)
		(end 289.900868 -315.34989)
		(width 0.14732)
		(layer "In11.Cu")
		(net "UPI_CPU1_CPU0_P2P2_DN<23>")
	)
	(segment
		(start 285.459678 -317.724282)
		(end 282.852114 -317.724282)
		(width 0.14732)
		(layer "In11.Cu")
		(net "UPI_CPU1_CPU0_P2P2_DN<23>")
	)
	(segment
		(start 260.90753 -324.445122)
		(end 260.134354 -325.218298)
		(width 0.14732)
		(layer "In11.Cu")
		(net "UPI_CPU1_CPU0_P2P2_DN<23>")
	)
	(segment
		(start 108.556298 -281.600656)
		(end 108.556298 -281.582114)
		(width 0.0889)
		(layer "In11.Cu")
		(net "UPI_CPU1_CPU0_P2P2_DN<23>")
	)
	(segment
		(start 250.171966 -341.18296)
		(end 251.044456 -341.18296)
		(width 0.14732)
		(layer "In11.Cu")
		(net "UPI_CPU1_CPU0_P2P2_DN<23>")
	)
	(segment
		(start 334.033368 -282.730448)
		(end 334.0227 -282.736798)
		(width 0.0889)
		(layer "In11.Cu")
		(net "UPI_CPU1_CPU0_P2P2_DN<23>")
	)
	(segment
		(start 110.62335 -285.171896)
		(end 110.61446 -285.166816)
		(width 0.0889)
		(layer "In11.Cu")
		(net "UPI_CPU1_CPU0_P2P2_DN<23>")
	)
	(segment
		(start 247.663208 -351.797112)
		(end 247.626886 -352.00209)
		(width 0.14732)
		(layer "In11.Cu")
		(net "UPI_CPU1_CPU0_P2P2_DN<23>")
	)
	(segment
		(start 335.155794 -280.835862)
		(end 335.156048 -280.835862)
		(width 0.0889)
		(layer "In11.Cu")
		(net "UPI_CPU1_CPU0_P2P2_DN<23>")
	)
	(segment
		(start 334.02016 -283.70149)
		(end 334.02524 -283.704538)
		(width 0.0889)
		(layer "In11.Cu")
		(net "UPI_CPU1_CPU0_P2P2_DN<23>")
	)
	(segment
		(start 261.968996 -323.81952)
		(end 262.494014 -324.344538)
		(width 0.14732)
		(layer "In11.Cu")
		(net "UPI_CPU1_CPU0_P2P2_DN<23>")
	)
	(segment
		(start 245.040658 -353.633786)
		(end 244.179598 -352.404426)
		(width 0.14732)
		(layer "In11.Cu")
		(net "UPI_CPU1_CPU0_P2P2_DN<23>")
	)
	(segment
		(start 109.087158 -273.724116)
		(end 108.930694 -273.453098)
		(width 0.0889)
		(layer "In11.Cu")
		(net "UPI_CPU1_CPU0_P2P2_DN<23>")
	)
	(segment
		(start 299.617384 -314.945776)
		(end 299.53458 -315.372242)
		(width 0.14732)
		(layer "In11.Cu")
		(net "UPI_CPU1_CPU0_P2P2_DN<23>")
	)
	(segment
		(start 334.033368 -285.985966)
		(end 334.0227 -285.992316)
		(width 0.0889)
		(layer "In11.Cu")
		(net "UPI_CPU1_CPU0_P2P2_DN<23>")
	)
	(segment
		(start 247.626886 -352.00209)
		(end 247.144032 -352.340672)
		(width 0.14732)
		(layer "In11.Cu")
		(net "UPI_CPU1_CPU0_P2P2_DN<23>")
	)
	(segment
		(start 249.864118 -343.191592)
		(end 250.171966 -343.49944)
		(width 0.14732)
		(layer "In11.Cu")
		(net "UPI_CPU1_CPU0_P2P2_DN<23>")
	)
	(segment
		(start 285.794704 -316.90818)
		(end 285.794704 -317.389256)
		(width 0.14732)
		(layer "In11.Cu")
		(net "UPI_CPU1_CPU0_P2P2_DN<23>")
	)
	(segment
		(start 243.080794 -352.798126)
		(end 243.005356 -353.226624)
		(width 0.14732)
		(layer "In11.Cu")
		(net "UPI_CPU1_CPU0_P2P2_DN<23>")
	)
	(segment
		(start 282.30957 -318.266826)
		(end 276.98192 -318.266826)
		(width 0.14732)
		(layer "In11.Cu")
		(net "UPI_CPU1_CPU0_P2P2_DN<23>")
	)
	(segment
		(start 110.165388 -284.365192)
		(end 110.153196 -284.35808)
		(width 0.0889)
		(layer "In11.Cu")
		(net "UPI_CPU1_CPU0_P2P2_DN<23>")
	)
	(segment
		(start 298.081954 -317.810388)
		(end 297.417998 -317.146432)
		(width 0.14732)
		(layer "In11.Cu")
		(net "UPI_CPU1_CPU0_P2P2_DN<23>")
	)
	(segment
		(start 112.315244 -288.30143)
		(end 112.315244 -288.087562)
		(width 0.0889)
		(layer "In11.Cu")
		(net "UPI_CPU1_CPU0_P2P2_DN<23>")
	)
	(segment
		(start 299.53458 -315.372242)
		(end 299.53458 -317.487554)
		(width 0.14732)
		(layer "In11.Cu")
		(net "UPI_CPU1_CPU0_P2P2_DN<23>")
	)
	(segment
		(start 334.032098 -283.708602)
		(end 334.035654 -283.710634)
		(width 0.0889)
		(layer "In11.Cu")
		(net "UPI_CPU1_CPU0_P2P2_DN<23>")
	)
	(segment
		(start 334.220566 -285.661354)
		(end 334.220566 -285.67634)
		(width 0.0889)
		(layer "In11.Cu")
		(net "UPI_CPU1_CPU0_P2P2_DN<23>")
	)
	(segment
		(start 109.674406 -274.761452)
		(end 109.683296 -274.756372)
		(width 0.0889)
		(layer "In11.Cu")
		(net "UPI_CPU1_CPU0_P2P2_DN<23>")
	)
	(segment
		(start 310.20258 -308.317138)
		(end 308.798214 -309.25516)
		(width 0.14732)
		(layer "In11.Cu")
		(net "UPI_CPU1_CPU0_P2P2_DN<23>")
	)
	(segment
		(start 108.26496 -280.458926)
		(end 108.27385 -280.453846)
		(width 0.0889)
		(layer "In11.Cu")
		(net "UPI_CPU1_CPU0_P2P2_DN<23>")
	)
	(segment
		(start 331.608938 -289.395662)
		(end 331.404214 -289.395662)
		(width 0.14732)
		(layer "In11.Cu")
		(net "UPI_CPU1_CPU0_P2P2_DN<23>")
	)
	(segment
		(start 334.499458 -281.918918)
		(end 334.492854 -281.922728)
		(width 0.0889)
		(layer "In11.Cu")
		(net "UPI_CPU1_CPU0_P2P2_DN<23>")
	)
	(segment
		(start 246.939054 -352.30435)
		(end 246.077994 -351.07499)
		(width 0.14732)
		(layer "In11.Cu")
		(net "UPI_CPU1_CPU0_P2P2_DN<23>")
	)
	(segment
		(start 334.503268 -285.171896)
		(end 334.4926 -285.178246)
		(width 0.0889)
		(layer "In11.Cu")
		(net "UPI_CPU1_CPU0_P2P2_DN<23>")
	)
	(segment
		(start 243.005356 -353.226624)
		(end 243.866416 -354.455984)
		(width 0.14732)
		(layer "In11.Cu")
		(net "UPI_CPU1_CPU0_P2P2_DN<23>")
	)
	(segment
		(start 287.52165 -316.318646)
		(end 286.384238 -316.318646)
		(width 0.14732)
		(layer "In11.Cu")
		(net "UPI_CPU1_CPU0_P2P2_DN<23>")
	)
	(segment
		(start 333.237586 -287.767014)
		(end 331.608938 -289.395662)
		(width 0.14732)
		(layer "In11.Cu")
		(net "UPI_CPU1_CPU0_P2P2_DN<23>")
	)
	(segment
		(start 250.171966 -345.81592)
		(end 251.044456 -345.81592)
		(width 0.14732)
		(layer "In11.Cu")
		(net "UPI_CPU1_CPU0_P2P2_DN<23>")
	)
	(segment
		(start 334.035654 -283.710634)
		(end 334.038448 -283.712158)
		(width 0.0889)
		(layer "In11.Cu")
		(net "UPI_CPU1_CPU0_P2P2_DN<23>")
	)
	(segment
		(start 110.153196 -284.35808)
		(end 110.144306 -284.353)
		(width 0.0889)
		(layer "In11.Cu")
		(net "UPI_CPU1_CPU0_P2P2_DN<23>")
	)
	(segment
		(start 101.306376 -306.126642)
		(end 106.431842 -300.742858)
		(width 0.14732)
		(layer "In11.Cu")
		(net "UPI_CPU1_CPU0_P2P2_DN<23>")
	)
	(segment
		(start 308.023514 -310.02986)
		(end 306.833778 -310.825388)
		(width 0.14732)
		(layer "In11.Cu")
		(net "UPI_CPU1_CPU0_P2P2_DN<23>")
	)
	(segment
		(start 261.968996 -323.383656)
		(end 261.968996 -323.81952)
		(width 0.14732)
		(layer "In11.Cu")
		(net "UPI_CPU1_CPU0_P2P2_DN<23>")
	)
	(segment
		(start 243.7511 -352.328988)
		(end 243.080794 -352.798126)
		(width 0.14732)
		(layer "In11.Cu")
		(net "UPI_CPU1_CPU0_P2P2_DN<23>")
	)
	(segment
		(start 335.098136 -280.778204)
		(end 335.155794 -280.835862)
		(width 0.0889)
		(layer "In11.Cu")
		(net "UPI_CPU1_CPU0_P2P2_DN<23>")
	)
	(segment
		(start 328.558652 -294.437308)
		(end 327.369678 -298.343574)
		(width 0.14732)
		(layer "In11.Cu")
		(net "UPI_CPU1_CPU0_P2P2_DN<23>")
	)
	(segment
		(start 249.864118 -345.508072)
		(end 250.171966 -345.81592)
		(width 0.14732)
		(layer "In11.Cu")
		(net "UPI_CPU1_CPU0_P2P2_DN<23>")
	)
	(segment
		(start 106.88574 -300.2661)
		(end 107.151678 -299.9867)
		(width 0.14732)
		(layer "In11.Cu")
		(net "UPI_CPU1_CPU0_P2P2_DN<23>")
	)
	(segment
		(start 212.261704 -368.482626)
		(end 199.94626 -366.31118)
		(width 0.14732)
		(layer "In11.Cu")
		(net "UPI_CPU1_CPU0_P2P2_DN<23>")
	)
	(segment
		(start 76.857352 -328.088498)
		(end 77.299566 -327.154286)
		(width 0.14732)
		(layer "In11.Cu")
		(net "UPI_CPU1_CPU0_P2P2_DN<23>")
	)
	(segment
		(start 126.446026 -373.224044)
		(end 99.861116 -369.28044)
		(width 0.14732)
		(layer "In11.Cu")
		(net "UPI_CPU1_CPU0_P2P2_DN<23>")
	)
	(segment
		(start 260.134354 -325.218298)
		(end 260.134354 -327.740264)
		(width 0.14732)
		(layer "In11.Cu")
		(net "UPI_CPU1_CPU0_P2P2_DN<23>")
	)
	(segment
		(start 333.279496 -287.168844)
		(end 333.279496 -287.608518)
		(width 0.0889)
		(layer "In11.Cu")
		(net "UPI_CPU1_CPU0_P2P2_DN<23>")
	)
	(segment
		(start 251.191776 -341.33028)
		(end 251.191776 -341.91956)
		(width 0.14732)
		(layer "In11.Cu")
		(net "UPI_CPU1_CPU0_P2P2_DN<23>")
	)
	(segment
		(start 243.866416 -354.455984)
		(end 243.830094 -354.660962)
		(width 0.14732)
		(layer "In11.Cu")
		(net "UPI_CPU1_CPU0_P2P2_DN<23>")
	)
	(segment
		(start 251.044456 -348.1324)
		(end 251.191776 -348.27972)
		(width 0.14732)
		(layer "In11.Cu")
		(net "UPI_CPU1_CPU0_P2P2_DN<23>")
	)
	(segment
		(start 110.153196 -276.219158)
		(end 110.144306 -276.214078)
		(width 0.0889)
		(layer "In11.Cu")
		(net "UPI_CPU1_CPU0_P2P2_DN<23>")
	)
	(segment
		(start 249.864118 -344.691208)
		(end 249.864118 -345.508072)
		(width 0.14732)
		(layer "In11.Cu")
		(net "UPI_CPU1_CPU0_P2P2_DN<23>")
	)
	(segment
		(start 249.864118 -338.0105)
		(end 249.864118 -340.875112)
		(width 0.14732)
		(layer "In11.Cu")
		(net "UPI_CPU1_CPU0_P2P2_DN<23>")
	)
	(segment
		(start 330.417932 -290.586668)
		(end 329.823064 -291.181536)
		(width 0.14732)
		(layer "In11.Cu")
		(net "UPI_CPU1_CPU0_P2P2_DN<23>")
	)
	(segment
		(start 111.375698 -286.48406)
		(end 111.375698 -286.456882)
		(width 0.0889)
		(layer "In11.Cu")
		(net "UPI_CPU1_CPU0_P2P2_DN<23>")
	)
	(arc
		(start 333.750666 -286.483298)
		(mid 333.698816 -286.665578)
		(end 333.564484 -286.799274)
		(width 0.0889)
		(layer "In11.Cu")
		(net "UPI_CPU1_CPU0_P2P2_DN<23>")
	)
	(arc
		(start 335.156048 -280.835862)
		(mid 335.097807 -280.985807)
		(end 334.982058 -281.097482)
		(width 0.0889)
		(layer "In11.Cu")
		(net "UPI_CPU1_CPU0_P2P2_DN<23>")
	)
	(arc
		(start 112.029748 -288.632646)
		(mid 112.203777 -288.494009)
		(end 112.315244 -288.30143)
		(width 0.0889)
		(layer "In11.Cu")
		(net "UPI_CPU1_CPU0_P2P2_DN<23>")
	)
	(arc
		(start 108.743496 -279.639776)
		(mid 108.947831 -279.437171)
		(end 109.025944 -279.160224)
		(width 0.0889)
		(layer "In11.Cu")
		(net "UPI_CPU1_CPU0_P2P2_DN<23>")
	)
	(arc
		(start 109.965744 -275.880576)
		(mid 109.886603 -275.605953)
		(end 109.683296 -275.405088)
		(width 0.0889)
		(layer "In11.Cu")
		(net "UPI_CPU1_CPU0_P2P2_DN<23>")
	)
	(arc
		(start 109.213396 -278.82596)
		(mid 109.417731 -278.623355)
		(end 109.495844 -278.346408)
		(width 0.0889)
		(layer "In11.Cu")
		(net "UPI_CPU1_CPU0_P2P2_DN<23>")
	)
	(arc
		(start 109.495844 -275.074126)
		(mid 109.545097 -274.894926)
		(end 109.674406 -274.761452)
		(width 0.0889)
		(layer "In11.Cu")
		(net "UPI_CPU1_CPU0_P2P2_DN<23>")
	)
	(arc
		(start 334.961992 -281.109166)
		(mid 334.763203 -281.315096)
		(end 334.69072 -281.59202)
		(width 0.0889)
		(layer "In11.Cu")
		(net "UPI_CPU1_CPU0_P2P2_DN<23>")
	)
	(arc
		(start 109.965744 -274.257008)
		(mid 109.887633 -273.980059)
		(end 109.683296 -273.777456)
		(width 0.0889)
		(layer "In11.Cu")
		(net "UPI_CPU1_CPU0_P2P2_DN<23>")
	)
	(arc
		(start 109.674406 -283.539184)
		(mid 109.543492 -283.402824)
		(end 109.495844 -283.219906)
		(width 0.0889)
		(layer "In11.Cu")
		(net "UPI_CPU1_CPU0_P2P2_DN<23>")
	)
	(arc
		(start 108.26496 -281.097482)
		(mid 108.086242 -280.778204)
		(end 108.26496 -280.458926)
		(width 0.0889)
		(layer "In11.Cu")
		(net "UPI_CPU1_CPU0_P2P2_DN<23>")
	)
	(arc
		(start 109.674406 -275.400008)
		(mid 109.547152 -275.270042)
		(end 109.496098 -275.095462)
		(width 0.0889)
		(layer "In11.Cu")
		(net "UPI_CPU1_CPU0_P2P2_DN<23>")
	)
	(arc
		(start 111.375698 -286.456882)
		(mid 111.295536 -286.184693)
		(end 111.09325 -285.985712)
		(width 0.0889)
		(layer "In11.Cu")
		(net "UPI_CPU1_CPU0_P2P2_DN<23>")
	)
	(arc
		(start 333.75092 -283.200856)
		(mid 333.750613 -283.215078)
		(end 333.750666 -283.229304)
		(width 0.0889)
		(layer "In11.Cu")
		(net "UPI_CPU1_CPU0_P2P2_DN<23>")
	)
	(arc
		(start 109.683296 -278.012144)
		(mid 109.885582 -277.813163)
		(end 109.965744 -277.540974)
		(width 0.0889)
		(layer "In11.Cu")
		(net "UPI_CPU1_CPU0_P2P2_DN<23>")
	)
	(arc
		(start 111.845598 -287.28924)
		(mid 111.771607 -287.009674)
		(end 111.568992 -286.803338)
		(width 0.0889)
		(layer "In11.Cu")
		(net "UPI_CPU1_CPU0_P2P2_DN<23>")
	)
	(arc
		(start 109.496098 -275.095462)
		(mid 109.495816 -275.084796)
		(end 109.495844 -275.074126)
		(width 0.0889)
		(layer "In11.Cu")
		(net "UPI_CPU1_CPU0_P2P2_DN<23>")
	)
	(arc
		(start 109.495844 -278.336502)
		(mid 109.543523 -278.153602)
		(end 109.674406 -278.017224)
		(width 0.0889)
		(layer "In11.Cu")
		(net "UPI_CPU1_CPU0_P2P2_DN<23>")
	)
	(arc
		(start 334.4926 -285.178246)
		(mid 334.293216 -285.384126)
		(end 334.220566 -285.661354)
		(width 0.0889)
		(layer "In11.Cu")
		(net "UPI_CPU1_CPU0_P2P2_DN<23>")
	)
	(arc
		(start 110.144306 -284.353)
		(mid 110.013392 -284.21664)
		(end 109.965744 -284.033722)
		(width 0.0889)
		(layer "In11.Cu")
		(net "UPI_CPU1_CPU0_P2P2_DN<23>")
	)
	(arc
		(start 109.683296 -274.756372)
		(mid 109.887631 -274.553767)
		(end 109.965744 -274.27682)
		(width 0.0889)
		(layer "In11.Cu")
		(net "UPI_CPU1_CPU0_P2P2_DN<23>")
	)
	(arc
		(start 108.27385 -280.453846)
		(mid 108.475132 -280.256359)
		(end 108.556044 -279.986232)
		(width 0.0889)
		(layer "In11.Cu")
		(net "UPI_CPU1_CPU0_P2P2_DN<23>")
	)
	(arc
		(start 334.69072 -281.59202)
		(mid 334.641737 -281.777046)
		(end 334.50784 -281.913838)
		(width 0.0889)
		(layer "In11.Cu")
		(net "UPI_CPU1_CPU0_P2P2_DN<23>")
	)
	(arc
		(start 109.495844 -283.201364)
		(mid 109.415682 -282.929175)
		(end 109.213396 -282.730194)
		(width 0.0889)
		(layer "In11.Cu")
		(net "UPI_CPU1_CPU0_P2P2_DN<23>")
	)
	(arc
		(start 334.22082 -284.033722)
		(mid 334.293352 -284.31071)
		(end 334.492346 -284.516576)
		(width 0.0889)
		(layer "In11.Cu")
		(net "UPI_CPU1_CPU0_P2P2_DN<23>")
	)
	(arc
		(start 110.144306 -276.214078)
		(mid 110.013392 -276.077718)
		(end 109.965744 -275.8948)
		(width 0.0889)
		(layer "In11.Cu")
		(net "UPI_CPU1_CPU0_P2P2_DN<23>")
	)
	(arc
		(start 111.845598 -288.832036)
		(mid 111.920603 -288.716577)
		(end 112.029748 -288.632646)
		(width 0.0889)
		(layer "In11.Cu")
		(net "UPI_CPU1_CPU0_P2P2_DN<23>")
	)
	(arc
		(start 110.165388 -277.190962)
		(mid 110.435844 -276.708616)
		(end 110.165388 -276.22627)
		(width 0.0889)
		(layer "In11.Cu")
		(net "UPI_CPU1_CPU0_P2P2_DN<23>")
	)
	(arc
		(start 109.965744 -284.023816)
		(mid 109.887633 -283.746867)
		(end 109.683296 -283.544264)
		(width 0.0889)
		(layer "In11.Cu")
		(net "UPI_CPU1_CPU0_P2P2_DN<23>")
	)
	(arc
		(start 334.220566 -285.67634)
		(mid 334.166761 -285.855215)
		(end 334.033368 -285.985966)
		(width 0.0889)
		(layer "In11.Cu")
		(net "UPI_CPU1_CPU0_P2P2_DN<23>")
	)
	(arc
		(start 109.213396 -282.730194)
		(mid 109.078463 -282.59684)
		(end 109.026198 -282.414472)
		(width 0.0889)
		(layer "In11.Cu")
		(net "UPI_CPU1_CPU0_P2P2_DN<23>")
	)
	(arc
		(start 108.556298 -281.582114)
		(mid 108.478187 -281.305165)
		(end 108.27385 -281.102562)
		(width 0.0889)
		(layer "In11.Cu")
		(net "UPI_CPU1_CPU0_P2P2_DN<23>")
	)
	(arc
		(start 110.905798 -285.661354)
		(mid 110.831882 -285.381852)
		(end 110.629446 -285.175452)
		(width 0.0889)
		(layer "In11.Cu")
		(net "UPI_CPU1_CPU0_P2P2_DN<23>")
	)
	(arc
		(start 111.08436 -285.980632)
		(mid 110.953446 -285.844272)
		(end 110.905798 -285.661354)
		(width 0.0889)
		(layer "In11.Cu")
		(net "UPI_CPU1_CPU0_P2P2_DN<23>")
	)
	(arc
		(start 334.0227 -282.736798)
		(mid 333.828061 -282.934417)
		(end 333.75092 -283.200856)
		(width 0.0889)
		(layer "In11.Cu")
		(net "UPI_CPU1_CPU0_P2P2_DN<23>")
	)
	(arc
		(start 334.690466 -284.855412)
		(mid 334.638328 -285.03818)
		(end 334.503268 -285.171896)
		(width 0.0889)
		(layer "In11.Cu")
		(net "UPI_CPU1_CPU0_P2P2_DN<23>")
	)
	(arc
		(start 109.683296 -273.777456)
		(mid 109.433307 -273.70256)
		(end 109.176312 -273.747992)
		(width 0.0889)
		(layer "In11.Cu")
		(net "UPI_CPU1_CPU0_P2P2_DN<23>")
	)
	(arc
		(start 112.02416 -287.608518)
		(mid 111.893246 -287.472158)
		(end 111.845598 -287.28924)
		(width 0.0889)
		(layer "In11.Cu")
		(net "UPI_CPU1_CPU0_P2P2_DN<23>")
	)
	(arc
		(start 334.043274 -283.714952)
		(mid 334.173451 -283.851279)
		(end 334.22082 -284.033722)
		(width 0.0889)
		(layer "In11.Cu")
		(net "UPI_CPU1_CPU0_P2P2_DN<23>")
	)
	(arc
		(start 334.0227 -285.992316)
		(mid 333.823316 -286.198196)
		(end 333.750666 -286.475424)
		(width 0.0889)
		(layer "In11.Cu")
		(net "UPI_CPU1_CPU0_P2P2_DN<23>")
	)
	(arc
		(start 109.965744 -277.522432)
		(mid 110.013423 -277.339532)
		(end 110.144306 -277.203154)
		(width 0.0889)
		(layer "In11.Cu")
		(net "UPI_CPU1_CPU0_P2P2_DN<23>")
	)
	(arc
		(start 111.562896 -286.799782)
		(mid 111.427963 -286.666428)
		(end 111.375698 -286.48406)
		(width 0.0889)
		(layer "In11.Cu")
		(net "UPI_CPU1_CPU0_P2P2_DN<23>")
	)
	(arc
		(start 110.61446 -285.166816)
		(mid 110.483546 -285.030456)
		(end 110.435898 -284.847538)
		(width 0.0889)
		(layer "In11.Cu")
		(net "UPI_CPU1_CPU0_P2P2_DN<23>")
	)
	(arc
		(start 109.025944 -279.150318)
		(mid 109.073623 -278.967418)
		(end 109.204506 -278.83104)
		(width 0.0889)
		(layer "In11.Cu")
		(net "UPI_CPU1_CPU0_P2P2_DN<23>")
	)
	(arc
		(start 333.750666 -283.229304)
		(mid 333.824877 -283.499949)
		(end 334.02016 -283.70149)
		(width 0.0889)
		(layer "In11.Cu")
		(net "UPI_CPU1_CPU0_P2P2_DN<23>")
	)
	(arc
		(start 108.743496 -281.916378)
		(mid 108.608563 -281.783024)
		(end 108.556298 -281.600656)
		(width 0.0889)
		(layer "In11.Cu")
		(net "UPI_CPU1_CPU0_P2P2_DN<23>")
	)
	(arc
		(start 334.50784 -284.525466)
		(mid 334.638654 -284.656979)
		(end 334.690466 -284.835092)
		(width 0.0889)
		(layer "In11.Cu")
		(net "UPI_CPU1_CPU0_P2P2_DN<23>")
	)
	(arc
		(start 109.026198 -282.405836)
		(mid 108.952207 -282.12627)
		(end 108.749592 -281.919934)
		(width 0.0889)
		(layer "In11.Cu")
		(net "UPI_CPU1_CPU0_P2P2_DN<23>")
	)
	(arc
		(start 110.435898 -284.847538)
		(mid 110.363663 -284.571014)
		(end 110.165388 -284.365192)
		(width 0.0889)
		(layer "In11.Cu")
		(net "UPI_CPU1_CPU0_P2P2_DN<23>")
	)
	(arc
		(start 333.55661 -286.803846)
		(mid 333.380015 -286.957464)
		(end 333.279496 -287.168844)
		(width 0.0889)
		(layer "In11.Cu")
		(net "UPI_CPU1_CPU0_P2P2_DN<23>")
	)
	(arc
		(start 334.22082 -282.411932)
		(mid 334.169037 -282.595877)
		(end 334.033368 -282.730448)
		(width 0.0889)
		(layer "In11.Cu")
		(net "UPI_CPU1_CPU0_P2P2_DN<23>")
	)
	(arc
		(start 108.556044 -279.964134)
		(mid 108.603723 -279.781234)
		(end 108.734606 -279.644856)
		(width 0.0889)
		(layer "In11.Cu")
		(net "UPI_CPU1_CPU0_P2P2_DN<23>")
	)
	(arc
		(start 334.492854 -281.922728)
		(mid 334.29347 -282.128608)
		(end 334.22082 -282.405836)
		(width 0.0889)
		(layer "In11.Cu")
		(net "UPI_CPU1_CPU0_P2P2_DN<23>")
	)
	(arc
		(start 112.315244 -288.087562)
		(mid 112.235874 -287.813828)
		(end 112.03305 -287.613598)
		(width 0.0889)
		(layer "In11.Cu")
		(net "UPI_CPU1_CPU0_P2P2_DN<23>")
	)
	(segment
		(start 334.785716 -281.869896)
		(end 334.785716 -282.405836)
		(width 0.13208)
		(layer "F.Cu")
		(net "UPI_CPU1_CPU0_P2P2_DN<22>")
	)
	(segment
		(start 106.581448 -280.77795)
		(end 106.581194 -280.778204)
		(width 0.13208)
		(layer "F.Cu")
		(net "UPI_CPU1_CPU0_P2P2_DN<22>")
	)
	(segment
		(start 106.581448 -280.242264)
		(end 106.581448 -280.77795)
		(width 0.13208)
		(layer "F.Cu")
		(net "UPI_CPU1_CPU0_P2P2_DN<22>")
	)
	(segment
		(start 264.715752 -323.931026)
		(end 261.23011 -327.416668)
		(width 0.14732)
		(layer "In11.Cu")
		(net "UPI_CPU1_CPU0_P2P2_DN<22>")
	)
	(segment
		(start 254.266954 -345.4654)
		(end 254.414274 -345.61272)
		(width 0.14732)
		(layer "In11.Cu")
		(net "UPI_CPU1_CPU0_P2P2_DN<22>")
	)
	(segment
		(start 108.597954 -290.375086)
		(end 108.597954 -290.352988)
		(width 0.0889)
		(layer "In11.Cu")
		(net "UPI_CPU1_CPU0_P2P2_DN<22>")
	)
	(segment
		(start 107.80395 -281.916378)
		(end 107.79506 -281.911298)
		(width 0.0889)
		(layer "In11.Cu")
		(net "UPI_CPU1_CPU0_P2P2_DN<22>")
	)
	(segment
		(start 252.046486 -346.657168)
		(end 252.046486 -349.640906)
		(width 0.14732)
		(layer "In11.Cu")
		(net "UPI_CPU1_CPU0_P2P2_DN<22>")
	)
	(segment
		(start 309.8292 -310.363616)
		(end 308.860698 -311.263792)
		(width 0.14732)
		(layer "In11.Cu")
		(net "UPI_CPU1_CPU0_P2P2_DN<22>")
	)
	(segment
		(start 257.09372 -337.53933)
		(end 257.09372 -337.747102)
		(width 0.14732)
		(layer "In11.Cu")
		(net "UPI_CPU1_CPU0_P2P2_DN<22>")
	)
	(segment
		(start 108.597954 -291.060886)
		(end 108.597954 -290.375086)
		(width 0.14732)
		(layer "In11.Cu")
		(net "UPI_CPU1_CPU0_P2P2_DN<22>")
	)
	(segment
		(start 330.563982 -291.624512)
		(end 330.073254 -292.358572)
		(width 0.14732)
		(layer "In11.Cu")
		(net "UPI_CPU1_CPU0_P2P2_DN<22>")
	)
	(segment
		(start 334.575658 -287.664144)
		(end 334.428592 -287.81121)
		(width 0.0889)
		(layer "In11.Cu")
		(net "UPI_CPU1_CPU0_P2P2_DN<22>")
	)
	(segment
		(start 334.428592 -287.81121)
		(end 334.28813 -287.81121)
		(width 0.0889)
		(layer "In11.Cu")
		(net "UPI_CPU1_CPU0_P2P2_DN<22>")
	)
	(segment
		(start 75.619102 -329.445112)
		(end 76.068936 -327.818242)
		(width 0.14732)
		(layer "In11.Cu")
		(net "UPI_CPU1_CPU0_P2P2_DN<22>")
	)
	(segment
		(start 107.79506 -284.52826)
		(end 107.810046 -284.519624)
		(width 0.0889)
		(layer "In11.Cu")
		(net "UPI_CPU1_CPU0_P2P2_DN<22>")
	)
	(segment
		(start 333.645256 -288.594546)
		(end 333.504794 -288.594546)
		(width 0.0889)
		(layer "In11.Cu")
		(net "UPI_CPU1_CPU0_P2P2_DN<22>")
	)
	(segment
		(start 334.1624 -288.077402)
		(end 334.036924 -288.202878)
		(width 0.0889)
		(layer "In11.Cu")
		(net "UPI_CPU1_CPU0_P2P2_DN<22>")
	)
	(segment
		(start 335.160112 -285.651448)
		(end 335.160112 -285.661354)
		(width 0.0889)
		(layer "In11.Cu")
		(net "UPI_CPU1_CPU0_P2P2_DN<22>")
	)
	(segment
		(start 160.756854 -374.062244)
		(end 126.427992 -374.062244)
		(width 0.14732)
		(layer "In11.Cu")
		(net "UPI_CPU1_CPU0_P2P2_DN<22>")
	)
	(segment
		(start 108.164884 -297.332146)
		(end 108.164884 -296.094658)
		(width 0.14732)
		(layer "In11.Cu")
		(net "UPI_CPU1_CPU0_P2P2_DN<22>")
	)
	(segment
		(start 254.70739 -335.153)
		(end 257.09372 -337.53933)
		(width 0.14732)
		(layer "In11.Cu")
		(net "UPI_CPU1_CPU0_P2P2_DN<22>")
	)
	(segment
		(start 317.19901 -309.225696)
		(end 317.05423 -309.080916)
		(width 0.14732)
		(layer "In11.Cu")
		(net "UPI_CPU1_CPU0_P2P2_DN<22>")
	)
	(segment
		(start 108.164884 -294.974518)
		(end 108.309664 -294.829738)
		(width 0.14732)
		(layer "In11.Cu")
		(net "UPI_CPU1_CPU0_P2P2_DN<22>")
	)
	(segment
		(start 316.02807 -309.080916)
		(end 315.65977 -309.080916)
		(width 0.14732)
		(layer "In11.Cu")
		(net "UPI_CPU1_CPU0_P2P2_DN<22>")
	)
	(segment
		(start 335.160112 -284.025086)
		(end 335.160112 -284.043628)
		(width 0.0889)
		(layer "In11.Cu")
		(net "UPI_CPU1_CPU0_P2P2_DN<22>")
	)
	(segment
		(start 126.427992 -374.062244)
		(end 99.618038 -370.085112)
		(width 0.14732)
		(layer "In11.Cu")
		(net "UPI_CPU1_CPU0_P2P2_DN<22>")
	)
	(segment
		(start 252.354334 -345.4654)
		(end 254.266954 -345.4654)
		(width 0.14732)
		(layer "In11.Cu")
		(net "UPI_CPU1_CPU0_P2P2_DN<22>")
	)
	(segment
		(start 108.164884 -296.094658)
		(end 108.309664 -295.949878)
		(width 0.14732)
		(layer "In11.Cu")
		(net "UPI_CPU1_CPU0_P2P2_DN<22>")
	)
	(segment
		(start 78.238604 -360.202226)
		(end 75.048618 -352.498914)
		(width 0.14732)
		(layer "In11.Cu")
		(net "UPI_CPU1_CPU0_P2P2_DN<22>")
	)
	(segment
		(start 252.046486 -345.157552)
		(end 252.354334 -345.4654)
		(width 0.14732)
		(layer "In11.Cu")
		(net "UPI_CPU1_CPU0_P2P2_DN<22>")
	)
	(segment
		(start 255.47574 -337.608418)
		(end 254.079248 -339.00491)
		(width 0.14732)
		(layer "In11.Cu")
		(net "UPI_CPU1_CPU0_P2P2_DN<22>")
	)
	(segment
		(start 253.4539 -338.58708)
		(end 253.4539 -338.379054)
		(width 0.14732)
		(layer "In11.Cu")
		(net "UPI_CPU1_CPU0_P2P2_DN<22>")
	)
	(segment
		(start 334.785462 -287.664144)
		(end 334.575658 -287.664144)
		(width 0.0889)
		(layer "In11.Cu")
		(net "UPI_CPU1_CPU0_P2P2_DN<22>")
	)
	(segment
		(start 333.070454 -289.169348)
		(end 333.011526 -289.169348)
		(width 0.0889)
		(layer "In11.Cu")
		(net "UPI_CPU1_CPU0_P2P2_DN<22>")
	)
	(segment
		(start 107.339892 -281.106118)
		(end 107.334558 -281.10307)
		(width 0.0889)
		(layer "In11.Cu")
		(net "UPI_CPU1_CPU0_P2P2_DN<22>")
	)
	(segment
		(start 335.44256 -284.52318)
		(end 335.45145 -284.52826)
		(width 0.0889)
		(layer "In11.Cu")
		(net "UPI_CPU1_CPU0_P2P2_DN<22>")
	)
	(segment
		(start 335.45145 -285.166816)
		(end 335.44256 -285.171896)
		(width 0.0889)
		(layer "In11.Cu")
		(net "UPI_CPU1_CPU0_P2P2_DN<22>")
	)
	(segment
		(start 300.93539 -316.589156)
		(end 300.928278 -316.629796)
		(width 0.14732)
		(layer "In11.Cu")
		(net "UPI_CPU1_CPU0_P2P2_DN<22>")
	)
	(segment
		(start 100.649024 -305.59121)
		(end 107.424982 -298.47413)
		(width 0.14732)
		(layer "In11.Cu")
		(net "UPI_CPU1_CPU0_P2P2_DN<22>")
	)
	(segment
		(start 293.632128 -318.508888)
		(end 290.616386 -318.508888)
		(width 0.14732)
		(layer "In11.Cu")
		(net "UPI_CPU1_CPU0_P2P2_DN<22>")
	)
	(segment
		(start 108.02874 -297.660314)
		(end 108.164884 -297.332146)
		(width 0.14732)
		(layer "In11.Cu")
		(net "UPI_CPU1_CPU0_P2P2_DN<22>")
	)
	(segment
		(start 76.625958 -326.641206)
		(end 84.06765 -319.199006)
		(width 0.14732)
		(layer "In11.Cu")
		(net "UPI_CPU1_CPU0_P2P2_DN<22>")
	)
	(segment
		(start 334.1624 -287.93694)
		(end 334.1624 -288.077402)
		(width 0.0889)
		(layer "In11.Cu")
		(net "UPI_CPU1_CPU0_P2P2_DN<22>")
	)
	(segment
		(start 300.928278 -316.629796)
		(end 300.928532 -316.629796)
		(width 0.14732)
		(layer "In11.Cu")
		(net "UPI_CPU1_CPU0_P2P2_DN<22>")
	)
	(segment
		(start 260.816344 -331.64399)
		(end 259.516372 -330.344018)
		(width 0.14732)
		(layer "In11.Cu")
		(net "UPI_CPU1_CPU0_P2P2_DN<22>")
	)
	(segment
		(start 254.414274 -346.202)
		(end 254.266954 -346.34932)
		(width 0.14732)
		(layer "In11.Cu")
		(net "UPI_CPU1_CPU0_P2P2_DN<22>")
	)
	(segment
		(start 333.770732 -288.46907)
		(end 333.645256 -288.594546)
		(width 0.0889)
		(layer "In11.Cu")
		(net "UPI_CPU1_CPU0_P2P2_DN<22>")
	)
	(segment
		(start 254.850138 -336.982816)
		(end 254.850138 -336.546952)
		(width 0.14732)
		(layer "In11.Cu")
		(net "UPI_CPU1_CPU0_P2P2_DN<22>")
	)
	(segment
		(start 108.086398 -282.405836)
		(end 108.086398 -282.39593)
		(width 0.0889)
		(layer "In11.Cu")
		(net "UPI_CPU1_CPU0_P2P2_DN<22>")
	)
	(segment
		(start 108.556298 -288.195258)
		(end 108.556298 -288.09442)
		(width 0.0889)
		(layer "In11.Cu")
		(net "UPI_CPU1_CPU0_P2P2_DN<22>")
	)
	(segment
		(start 333.770732 -288.328608)
		(end 333.770732 -288.46907)
		(width 0.0889)
		(layer "In11.Cu")
		(net "UPI_CPU1_CPU0_P2P2_DN<22>")
	)
	(segment
		(start 252.354334 -344.03284)
		(end 252.046486 -344.340688)
		(width 0.14732)
		(layer "In11.Cu")
		(net "UPI_CPU1_CPU0_P2P2_DN<22>")
	)
	(segment
		(start 333.504794 -288.594546)
		(end 333.379064 -288.720276)
		(width 0.0889)
		(layer "In11.Cu")
		(net "UPI_CPU1_CPU0_P2P2_DN<22>")
	)
	(segment
		(start 312.868818 -309.21833)
		(end 312.739024 -309.376826)
		(width 0.14732)
		(layer "In11.Cu")
		(net "UPI_CPU1_CPU0_P2P2_DN<22>")
	)
	(segment
		(start 313.39409 -309.311802)
		(end 313.235594 -309.182008)
		(width 0.14732)
		(layer "In11.Cu")
		(net "UPI_CPU1_CPU0_P2P2_DN<22>")
	)
	(segment
		(start 254.414274 -343.88552)
		(end 254.266954 -344.03284)
		(width 0.14732)
		(layer "In11.Cu")
		(net "UPI_CPU1_CPU0_P2P2_DN<22>")
	)
	(segment
		(start 75.048618 -335.24063)
		(end 75.619102 -329.445112)
		(width 0.14732)
		(layer "In11.Cu")
		(net "UPI_CPU1_CPU0_P2P2_DN<22>")
	)
	(segment
		(start 312.739024 -309.376826)
		(end 311.625234 -309.487062)
		(width 0.14732)
		(layer "In11.Cu")
		(net "UPI_CPU1_CPU0_P2P2_DN<22>")
	)
	(segment
		(start 310.959246 -309.650892)
		(end 310.62803 -309.812436)
		(width 0.14732)
		(layer "In11.Cu")
		(net "UPI_CPU1_CPU0_P2P2_DN<22>")
	)
	(segment
		(start 108.309664 -294.829738)
		(end 108.309664 -294.461438)
		(width 0.14732)
		(layer "In11.Cu")
		(net "UPI_CPU1_CPU0_P2P2_DN<22>")
	)
	(segment
		(start 251.075698 -350.61144)
		(end 228.401626 -366.487964)
		(width 0.14732)
		(layer "In11.Cu")
		(net "UPI_CPU1_CPU0_P2P2_DN<22>")
	)
	(segment
		(start 106.393996 -281.102562)
		(end 106.392472 -281.1018)
		(width 0.0889)
		(layer "In11.Cu")
		(net "UPI_CPU1_CPU0_P2P2_DN<22>")
	)
	(segment
		(start 334.966818 -283.705808)
		(end 334.972152 -283.708856)
		(width 0.0889)
		(layer "In11.Cu")
		(net "UPI_CPU1_CPU0_P2P2_DN<22>")
	)
	(segment
		(start 254.266954 -341.71636)
		(end 252.354334 -341.71636)
		(width 0.14732)
		(layer "In11.Cu")
		(net "UPI_CPU1_CPU0_P2P2_DN<22>")
	)
	(segment
		(start 254.414274 -343.29624)
		(end 254.414274 -343.88552)
		(width 0.14732)
		(layer "In11.Cu")
		(net "UPI_CPU1_CPU0_P2P2_DN<22>")
	)
	(segment
		(start 334.97266 -286.964882)
		(end 334.98155 -286.969962)
		(width 0.0889)
		(layer "In11.Cu")
		(net "UPI_CPU1_CPU0_P2P2_DN<22>")
	)
	(segment
		(start 253.645924 -335.778602)
		(end 252.046486 -337.37804)
		(width 0.14732)
		(layer "In11.Cu")
		(net "UPI_CPU1_CPU0_P2P2_DN<22>")
	)
	(segment
		(start 283.077666 -321.385438)
		(end 281.895296 -322.567808)
		(width 0.14732)
		(layer "In11.Cu")
		(net "UPI_CPU1_CPU0_P2P2_DN<22>")
	)
	(segment
		(start 333.896462 -288.202878)
		(end 333.770732 -288.328608)
		(width 0.0889)
		(layer "In11.Cu")
		(net "UPI_CPU1_CPU0_P2P2_DN<22>")
	)
	(segment
		(start 109.017308 -289.131248)
		(end 109.03204 -288.863278)
		(width 0.0889)
		(layer "In11.Cu")
		(net "UPI_CPU1_CPU0_P2P2_DN<22>")
	)
	(segment
		(start 108.27385 -282.730194)
		(end 108.26496 -282.725114)
		(width 0.0889)
		(layer "In11.Cu")
		(net "UPI_CPU1_CPU0_P2P2_DN<22>")
	)
	(segment
		(start 277.220172 -322.567808)
		(end 275.856954 -323.931026)
		(width 0.14732)
		(layer "In11.Cu")
		(net "UPI_CPU1_CPU0_P2P2_DN<22>")
	)
	(segment
		(start 254.850138 -336.546952)
		(end 254.081788 -335.778602)
		(width 0.14732)
		(layer "In11.Cu")
		(net "UPI_CPU1_CPU0_P2P2_DN<22>")
	)
	(segment
		(start 108.556044 -290.311078)
		(end 108.556044 -289.677348)
		(width 0.0889)
		(layer "In11.Cu")
		(net "UPI_CPU1_CPU0_P2P2_DN<22>")
	)
	(segment
		(start 108.309664 -293.803578)
		(end 108.309664 -293.435278)
		(width 0.14732)
		(layer "In11.Cu")
		(net "UPI_CPU1_CPU0_P2P2_DN<22>")
	)
	(segment
		(start 228.401626 -366.487964)
		(end 212.290914 -369.328954)
		(width 0.14732)
		(layer "In11.Cu")
		(net "UPI_CPU1_CPU0_P2P2_DN<22>")
	)
	(segment
		(start 254.414274 -345.61272)
		(end 254.414274 -346.202)
		(width 0.14732)
		(layer "In11.Cu")
		(net "UPI_CPU1_CPU0_P2P2_DN<22>")
	)
	(segment
		(start 310.561482 -310.006238)
		(end 309.8292 -310.363616)
		(width 0.14732)
		(layer "In11.Cu")
		(net "UPI_CPU1_CPU0_P2P2_DN<22>")
	)
	(segment
		(start 308.860698 -311.263792)
		(end 307.61559 -311.851294)
		(width 0.14732)
		(layer "In11.Cu")
		(net "UPI_CPU1_CPU0_P2P2_DN<22>")
	)
	(segment
		(start 333.379064 -288.720276)
		(end 333.379064 -288.860738)
		(width 0.0889)
		(layer "In11.Cu")
		(net "UPI_CPU1_CPU0_P2P2_DN<22>")
	)
	(segment
		(start 286.891476 -318.614044)
		(end 283.8069 -318.614044)
		(width 0.14732)
		(layer "In11.Cu")
		(net "UPI_CPU1_CPU0_P2P2_DN<22>")
	)
	(segment
		(start 254.414274 -341.56904)
		(end 254.266954 -341.71636)
		(width 0.14732)
		(layer "In11.Cu")
		(net "UPI_CPU1_CPU0_P2P2_DN<22>")
	)
	(segment
		(start 315.51499 -309.225696)
		(end 314.251848 -309.225696)
		(width 0.14732)
		(layer "In11.Cu")
		(net "UPI_CPU1_CPU0_P2P2_DN<22>")
	)
	(segment
		(start 334.28813 -287.81121)
		(end 334.1624 -287.93694)
		(width 0.0889)
		(layer "In11.Cu")
		(net "UPI_CPU1_CPU0_P2P2_DN<22>")
	)
	(segment
		(start 107.424982 -298.47413)
		(end 108.02874 -297.660314)
		(width 0.14732)
		(layer "In11.Cu")
		(net "UPI_CPU1_CPU0_P2P2_DN<22>")
	)
	(segment
		(start 316.54115 -309.225696)
		(end 316.17285 -309.225696)
		(width 0.14732)
		(layer "In11.Cu")
		(net "UPI_CPU1_CPU0_P2P2_DN<22>")
	)
	(segment
		(start 252.046486 -337.37804)
		(end 252.046486 -340.524592)
		(width 0.14732)
		(layer "In11.Cu")
		(net "UPI_CPU1_CPU0_P2P2_DN<22>")
	)
	(segment
		(start 79.992474 -361.956096)
		(end 78.238604 -360.202226)
		(width 0.14732)
		(layer "In11.Cu")
		(net "UPI_CPU1_CPU0_P2P2_DN<22>")
	)
	(segment
		(start 108.164884 -291.493956)
		(end 108.597954 -291.060886)
		(width 0.14732)
		(layer "In11.Cu")
		(net "UPI_CPU1_CPU0_P2P2_DN<22>")
	)
	(segment
		(start 307.61559 -311.851294)
		(end 306.889658 -311.947814)
		(width 0.14732)
		(layer "In11.Cu")
		(net "UPI_CPU1_CPU0_P2P2_DN<22>")
	)
	(segment
		(start 316.17285 -309.225696)
		(end 316.02807 -309.080916)
		(width 0.14732)
		(layer "In11.Cu")
		(net "UPI_CPU1_CPU0_P2P2_DN<22>")
	)
	(segment
		(start 254.081788 -335.778602)
		(end 253.645924 -335.778602)
		(width 0.14732)
		(layer "In11.Cu")
		(net "UPI_CPU1_CPU0_P2P2_DN<22>")
	)
	(segment
		(start 315.65977 -309.080916)
		(end 315.51499 -309.225696)
		(width 0.14732)
		(layer "In11.Cu")
		(net "UPI_CPU1_CPU0_P2P2_DN<22>")
	)
	(segment
		(start 252.046486 -340.524592)
		(end 252.354334 -340.83244)
		(width 0.14732)
		(layer "In11.Cu")
		(net "UPI_CPU1_CPU0_P2P2_DN<22>")
	)
	(segment
		(start 108.164884 -294.316658)
		(end 108.164884 -293.948358)
		(width 0.14732)
		(layer "In11.Cu")
		(net "UPI_CPU1_CPU0_P2P2_DN<22>")
	)
	(segment
		(start 257.09372 -337.747102)
		(end 256.67589 -338.164932)
		(width 0.14732)
		(layer "In11.Cu")
		(net "UPI_CPU1_CPU0_P2P2_DN<22>")
	)
	(segment
		(start 256.67589 -338.164932)
		(end 256.468118 -338.164932)
		(width 0.14732)
		(layer "In11.Cu")
		(net "UPI_CPU1_CPU0_P2P2_DN<22>")
	)
	(segment
		(start 311.625234 -309.487062)
		(end 311.152794 -309.71744)
		(width 0.14732)
		(layer "In11.Cu")
		(net "UPI_CPU1_CPU0_P2P2_DN<22>")
	)
	(segment
		(start 296.398442 -322.260468)
		(end 294.268398 -320.130424)
		(width 0.14732)
		(layer "In11.Cu")
		(net "UPI_CPU1_CPU0_P2P2_DN<22>")
	)
	(segment
		(start 260.141974 -329.718416)
		(end 261.441946 -331.018388)
		(width 0.14732)
		(layer "In11.Cu")
		(net "UPI_CPU1_CPU0_P2P2_DN<22>")
	)
	(segment
		(start 254.266954 -343.14892)
		(end 254.414274 -343.29624)
		(width 0.14732)
		(layer "In11.Cu")
		(net "UPI_CPU1_CPU0_P2P2_DN<22>")
	)
	(segment
		(start 254.266954 -344.03284)
		(end 252.354334 -344.03284)
		(width 0.14732)
		(layer "In11.Cu")
		(net "UPI_CPU1_CPU0_P2P2_DN<22>")
	)
	(segment
		(start 108.26496 -283.714444)
		(end 108.27385 -283.709364)
		(width 0.0889)
		(layer "In11.Cu")
		(net "UPI_CPU1_CPU0_P2P2_DN<22>")
	)
	(segment
		(start 108.164884 -293.290498)
		(end 108.164884 -291.493956)
		(width 0.14732)
		(layer "In11.Cu")
		(net "UPI_CPU1_CPU0_P2P2_DN<22>")
	)
	(segment
		(start 306.448206 -312.167524)
		(end 302.13935 -314.698634)
		(width 0.14732)
		(layer "In11.Cu")
		(net "UPI_CPU1_CPU0_P2P2_DN<22>")
	)
	(segment
		(start 108.749592 -286.803338)
		(end 108.743496 -286.799782)
		(width 0.0889)
		(layer "In11.Cu")
		(net "UPI_CPU1_CPU0_P2P2_DN<22>")
	)
	(segment
		(start 254.079248 -339.00491)
		(end 253.87173 -339.00491)
		(width 0.14732)
		(layer "In11.Cu")
		(net "UPI_CPU1_CPU0_P2P2_DN<22>")
	)
	(segment
		(start 317.66256 -309.225696)
		(end 317.19901 -309.225696)
		(width 0.14732)
		(layer "In11.Cu")
		(net "UPI_CPU1_CPU0_P2P2_DN<22>")
	)
	(segment
		(start 107.810046 -285.175452)
		(end 107.79506 -285.166816)
		(width 0.0889)
		(layer "In11.Cu")
		(net "UPI_CPU1_CPU0_P2P2_DN<22>")
	)
	(segment
		(start 275.856954 -323.931026)
		(end 264.715752 -323.931026)
		(width 0.14732)
		(layer "In11.Cu")
		(net "UPI_CPU1_CPU0_P2P2_DN<22>")
	)
	(segment
		(start 290.616386 -318.508888)
		(end 290.05911 -317.951612)
		(width 0.14732)
		(layer "In11.Cu")
		(net "UPI_CPU1_CPU0_P2P2_DN<22>")
	)
	(segment
		(start 252.046486 -342.024208)
		(end 252.046486 -342.841072)
		(width 0.14732)
		(layer "In11.Cu")
		(net "UPI_CPU1_CPU0_P2P2_DN<22>")
	)
	(segment
		(start 310.62803 -309.812436)
		(end 310.561482 -310.006238)
		(width 0.14732)
		(layer "In11.Cu")
		(net "UPI_CPU1_CPU0_P2P2_DN<22>")
	)
	(segment
		(start 253.87173 -339.00491)
		(end 253.4539 -338.58708)
		(width 0.14732)
		(layer "In11.Cu")
		(net "UPI_CPU1_CPU0_P2P2_DN<22>")
	)
	(segment
		(start 106.211116 -280.835608)
		(end 106.26852 -280.778204)
		(width 0.0889)
		(layer "In11.Cu")
		(net "UPI_CPU1_CPU0_P2P2_DN<22>")
	)
	(segment
		(start 289.508692 -316.992)
		(end 288.51352 -316.992)
		(width 0.14732)
		(layer "In11.Cu")
		(net "UPI_CPU1_CPU0_P2P2_DN<22>")
	)
	(segment
		(start 108.309664 -295.581578)
		(end 108.164884 -295.436798)
		(width 0.14732)
		(layer "In11.Cu")
		(net "UPI_CPU1_CPU0_P2P2_DN<22>")
	)
	(segment
		(start 255.911604 -337.608418)
		(end 255.47574 -337.608418)
		(width 0.14732)
		(layer "In11.Cu")
		(net "UPI_CPU1_CPU0_P2P2_DN<22>")
	)
	(segment
		(start 314.250578 -309.226966)
		(end 313.39409 -309.311802)
		(width 0.14732)
		(layer "In11.Cu")
		(net "UPI_CPU1_CPU0_P2P2_DN<22>")
	)
	(segment
		(start 75.048618 -352.498914)
		(end 75.048618 -335.24063)
		(width 0.14732)
		(layer "In11.Cu")
		(net "UPI_CPU1_CPU0_P2P2_DN<22>")
	)
	(segment
		(start 252.354334 -346.34932)
		(end 252.046486 -346.657168)
		(width 0.14732)
		(layer "In11.Cu")
		(net "UPI_CPU1_CPU0_P2P2_DN<22>")
	)
	(segment
		(start 260.141974 -329.282552)
		(end 260.141974 -329.718416)
		(width 0.14732)
		(layer "In11.Cu")
		(net "UPI_CPU1_CPU0_P2P2_DN<22>")
	)
	(segment
		(start 108.164884 -295.436798)
		(end 108.164884 -294.974518)
		(width 0.14732)
		(layer "In11.Cu")
		(net "UPI_CPU1_CPU0_P2P2_DN<22>")
	)
	(segment
		(start 332.996032 -289.184842)
		(end 330.563982 -291.616892)
		(width 0.14732)
		(layer "In11.Cu")
		(net "UPI_CPU1_CPU0_P2P2_DN<22>")
	)
	(segment
		(start 317.05423 -309.080916)
		(end 316.68593 -309.080916)
		(width 0.14732)
		(layer "In11.Cu")
		(net "UPI_CPU1_CPU0_P2P2_DN<22>")
	)
	(segment
		(start 254.70739 -334.717136)
		(end 254.70739 -335.153)
		(width 0.14732)
		(layer "In11.Cu")
		(net "UPI_CPU1_CPU0_P2P2_DN<22>")
	)
	(segment
		(start 300.928532 -316.629796)
		(end 300.802294 -317.36665)
		(width 0.14732)
		(layer "In11.Cu")
		(net "UPI_CPU1_CPU0_P2P2_DN<22>")
	)
	(segment
		(start 261.23011 -328.194416)
		(end 260.141974 -329.282552)
		(width 0.14732)
		(layer "In11.Cu")
		(net "UPI_CPU1_CPU0_P2P2_DN<22>")
	)
	(segment
		(start 254.266954 -346.34932)
		(end 252.354334 -346.34932)
		(width 0.14732)
		(layer "In11.Cu")
		(net "UPI_CPU1_CPU0_P2P2_DN<22>")
	)
	(segment
		(start 290.05911 -317.951612)
		(end 290.05911 -317.542418)
		(width 0.14732)
		(layer "In11.Cu")
		(net "UPI_CPU1_CPU0_P2P2_DN<22>")
	)
	(segment
		(start 294.268398 -320.130424)
		(end 294.268398 -319.145158)
		(width 0.14732)
		(layer "In11.Cu")
		(net "UPI_CPU1_CPU0_P2P2_DN<22>")
	)
	(segment
		(start 84.06765 -319.199006)
		(end 100.649024 -305.59121)
		(width 0.14732)
		(layer "In11.Cu")
		(net "UPI_CPU1_CPU0_P2P2_DN<22>")
	)
	(segment
		(start 311.152794 -309.71744)
		(end 310.959246 -309.650892)
		(width 0.14732)
		(layer "In11.Cu")
		(net "UPI_CPU1_CPU0_P2P2_DN<22>")
	)
	(segment
		(start 330.073254 -292.358572)
		(end 328.131932 -298.756324)
		(width 0.14732)
		(layer "In11.Cu")
		(net "UPI_CPU1_CPU0_P2P2_DN<22>")
	)
	(segment
		(start 76.068936 -327.818242)
		(end 76.625958 -326.641206)
		(width 0.14732)
		(layer "In11.Cu")
		(net "UPI_CPU1_CPU0_P2P2_DN<22>")
	)
	(segment
		(start 333.379064 -288.860738)
		(end 333.070454 -289.169348)
		(width 0.0889)
		(layer "In11.Cu")
		(net "UPI_CPU1_CPU0_P2P2_DN<22>")
	)
	(segment
		(start 108.309664 -295.949878)
		(end 108.309664 -295.581578)
		(width 0.14732)
		(layer "In11.Cu")
		(net "UPI_CPU1_CPU0_P2P2_DN<22>")
	)
	(segment
		(start 107.334558 -281.10307)
		(end 107.319064 -281.093926)
		(width 0.0889)
		(layer "In11.Cu")
		(net "UPI_CPU1_CPU0_P2P2_DN<22>")
	)
	(segment
		(start 261.441946 -331.22616)
		(end 261.024116 -331.64399)
		(width 0.14732)
		(layer "In11.Cu")
		(net "UPI_CPU1_CPU0_P2P2_DN<22>")
	)
	(segment
		(start 261.024116 -331.64399)
		(end 260.816344 -331.64399)
		(width 0.14732)
		(layer "In11.Cu")
		(net "UPI_CPU1_CPU0_P2P2_DN<22>")
	)
	(segment
		(start 99.618038 -370.085112)
		(end 79.992474 -361.956096)
		(width 0.14732)
		(layer "In11.Cu")
		(net "UPI_CPU1_CPU0_P2P2_DN<22>")
	)
	(segment
		(start 108.556298 -286.48406)
		(end 108.556298 -286.456882)
		(width 0.0889)
		(layer "In11.Cu")
		(net "UPI_CPU1_CPU0_P2P2_DN<22>")
	)
	(segment
		(start 328.131932 -298.756324)
		(end 317.66256 -309.225696)
		(width 0.14732)
		(layer "In11.Cu")
		(net "UPI_CPU1_CPU0_P2P2_DN<22>")
	)
	(segment
		(start 334.98155 -285.980632)
		(end 334.97266 -285.985712)
		(width 0.0889)
		(layer "In11.Cu")
		(net "UPI_CPU1_CPU0_P2P2_DN<22>")
	)
	(segment
		(start 288.51352 -316.992)
		(end 286.891476 -318.614044)
		(width 0.14732)
		(layer "In11.Cu")
		(net "UPI_CPU1_CPU0_P2P2_DN<22>")
	)
	(segment
		(start 299.019468 -320.877946)
		(end 297.636946 -322.260468)
		(width 0.14732)
		(layer "In11.Cu")
		(net "UPI_CPU1_CPU0_P2P2_DN<22>")
	)
	(segment
		(start 252.354334 -341.71636)
		(end 252.046486 -342.024208)
		(width 0.14732)
		(layer "In11.Cu")
		(net "UPI_CPU1_CPU0_P2P2_DN<22>")
	)
	(segment
		(start 334.94218 -282.134818)
		(end 335.020158 -282.11399)
		(width 0.0889)
		(layer "In11.Cu")
		(net "UPI_CPU1_CPU0_P2P2_DN<22>")
	)
	(segment
		(start 252.046486 -349.640906)
		(end 251.075698 -350.61144)
		(width 0.14732)
		(layer "In11.Cu")
		(net "UPI_CPU1_CPU0_P2P2_DN<22>")
	)
	(segment
		(start 301.608236 -315.254132)
		(end 300.93539 -316.589156)
		(width 0.14732)
		(layer "In11.Cu")
		(net "UPI_CPU1_CPU0_P2P2_DN<22>")
	)
	(segment
		(start 108.597954 -290.352988)
		(end 108.556044 -290.311078)
		(width 0.0889)
		(layer "In11.Cu")
		(net "UPI_CPU1_CPU0_P2P2_DN<22>")
	)
	(segment
		(start 297.636946 -322.260468)
		(end 296.398442 -322.260468)
		(width 0.14732)
		(layer "In11.Cu")
		(net "UPI_CPU1_CPU0_P2P2_DN<22>")
	)
	(segment
		(start 252.046486 -344.340688)
		(end 252.046486 -345.157552)
		(width 0.14732)
		(layer "In11.Cu")
		(net "UPI_CPU1_CPU0_P2P2_DN<22>")
	)
	(segment
		(start 253.4539 -338.379054)
		(end 254.850138 -336.982816)
		(width 0.14732)
		(layer "In11.Cu")
		(net "UPI_CPU1_CPU0_P2P2_DN<22>")
	)
	(segment
		(start 314.251848 -309.225696)
		(end 314.250578 -309.226966)
		(width 0.14732)
		(layer "In11.Cu")
		(net "UPI_CPU1_CPU0_P2P2_DN<22>")
	)
	(segment
		(start 254.266954 -340.83244)
		(end 254.414274 -340.97976)
		(width 0.14732)
		(layer "In11.Cu")
		(net "UPI_CPU1_CPU0_P2P2_DN<22>")
	)
	(segment
		(start 212.290914 -369.328954)
		(end 199.94626 -367.152174)
		(width 0.14732)
		(layer "In11.Cu")
		(net "UPI_CPU1_CPU0_P2P2_DN<22>")
	)
	(segment
		(start 330.563982 -291.616892)
		(end 330.563982 -291.624512)
		(width 0.14732)
		(layer "In11.Cu")
		(net "UPI_CPU1_CPU0_P2P2_DN<22>")
	)
	(segment
		(start 334.785716 -282.405836)
		(end 334.94218 -282.134818)
		(width 0.0889)
		(layer "In11.Cu")
		(net "UPI_CPU1_CPU0_P2P2_DN<22>")
	)
	(segment
		(start 256.468118 -338.164932)
		(end 255.911604 -337.608418)
		(width 0.14732)
		(layer "In11.Cu")
		(net "UPI_CPU1_CPU0_P2P2_DN<22>")
	)
	(segment
		(start 108.164884 -293.948358)
		(end 108.309664 -293.803578)
		(width 0.14732)
		(layer "In11.Cu")
		(net "UPI_CPU1_CPU0_P2P2_DN<22>")
	)
	(segment
		(start 334.036924 -288.202878)
		(end 333.896462 -288.202878)
		(width 0.0889)
		(layer "In11.Cu")
		(net "UPI_CPU1_CPU0_P2P2_DN<22>")
	)
	(segment
		(start 313.235594 -309.182008)
		(end 312.868818 -309.21833)
		(width 0.14732)
		(layer "In11.Cu")
		(net "UPI_CPU1_CPU0_P2P2_DN<22>")
	)
	(segment
		(start 261.23011 -327.416668)
		(end 261.23011 -328.194416)
		(width 0.14732)
		(layer "In11.Cu")
		(net "UPI_CPU1_CPU0_P2P2_DN<22>")
	)
	(segment
		(start 106.26852 -280.778204)
		(end 106.581194 -280.778204)
		(width 0.0889)
		(layer "In11.Cu")
		(net "UPI_CPU1_CPU0_P2P2_DN<22>")
	)
	(segment
		(start 302.13935 -314.698634)
		(end 301.608236 -315.254132)
		(width 0.14732)
		(layer "In11.Cu")
		(net "UPI_CPU1_CPU0_P2P2_DN<22>")
	)
	(segment
		(start 252.354334 -340.83244)
		(end 254.266954 -340.83244)
		(width 0.14732)
		(layer "In11.Cu")
		(net "UPI_CPU1_CPU0_P2P2_DN<22>")
	)
	(segment
		(start 261.441946 -331.018388)
		(end 261.441946 -331.22616)
		(width 0.14732)
		(layer "In11.Cu")
		(net "UPI_CPU1_CPU0_P2P2_DN<22>")
	)
	(segment
		(start 290.05911 -317.542418)
		(end 289.508692 -316.992)
		(width 0.14732)
		(layer "In11.Cu")
		(net "UPI_CPU1_CPU0_P2P2_DN<22>")
	)
	(segment
		(start 300.430692 -318.263524)
		(end 299.019468 -319.674748)
		(width 0.14732)
		(layer "In11.Cu")
		(net "UPI_CPU1_CPU0_P2P2_DN<22>")
	)
	(segment
		(start 294.268398 -319.145158)
		(end 293.632128 -318.508888)
		(width 0.14732)
		(layer "In11.Cu")
		(net "UPI_CPU1_CPU0_P2P2_DN<22>")
	)
	(segment
		(start 300.802294 -317.36665)
		(end 300.430692 -318.263524)
		(width 0.14732)
		(layer "In11.Cu")
		(net "UPI_CPU1_CPU0_P2P2_DN<22>")
	)
	(segment
		(start 252.046486 -342.841072)
		(end 252.354334 -343.14892)
		(width 0.14732)
		(layer "In11.Cu")
		(net "UPI_CPU1_CPU0_P2P2_DN<22>")
	)
	(segment
		(start 281.895296 -322.567808)
		(end 277.220172 -322.567808)
		(width 0.14732)
		(layer "In11.Cu")
		(net "UPI_CPU1_CPU0_P2P2_DN<22>")
	)
	(segment
		(start 333.011526 -289.169348)
		(end 332.996032 -289.184842)
		(width 0.0889)
		(layer "In11.Cu")
		(net "UPI_CPU1_CPU0_P2P2_DN<22>")
	)
	(segment
		(start 199.94626 -367.152174)
		(end 160.756854 -374.062244)
		(width 0.14732)
		(layer "In11.Cu")
		(net "UPI_CPU1_CPU0_P2P2_DN<22>")
	)
	(segment
		(start 252.354334 -343.14892)
		(end 254.266954 -343.14892)
		(width 0.14732)
		(layer "In11.Cu")
		(net "UPI_CPU1_CPU0_P2P2_DN<22>")
	)
	(segment
		(start 254.414274 -340.97976)
		(end 254.414274 -341.56904)
		(width 0.14732)
		(layer "In11.Cu")
		(net "UPI_CPU1_CPU0_P2P2_DN<22>")
	)
	(segment
		(start 108.309664 -294.461438)
		(end 108.164884 -294.316658)
		(width 0.14732)
		(layer "In11.Cu")
		(net "UPI_CPU1_CPU0_P2P2_DN<22>")
	)
	(segment
		(start 259.080508 -330.344018)
		(end 254.70739 -334.717136)
		(width 0.14732)
		(layer "In11.Cu")
		(net "UPI_CPU1_CPU0_P2P2_DN<22>")
	)
	(segment
		(start 306.889658 -311.947814)
		(end 306.448206 -312.167524)
		(width 0.14732)
		(layer "In11.Cu")
		(net "UPI_CPU1_CPU0_P2P2_DN<22>")
	)
	(segment
		(start 108.27385 -285.985712)
		(end 108.26496 -285.980632)
		(width 0.0889)
		(layer "In11.Cu")
		(net "UPI_CPU1_CPU0_P2P2_DN<22>")
	)
	(segment
		(start 334.972152 -283.708856)
		(end 334.972914 -283.709364)
		(width 0.0889)
		(layer "In11.Cu")
		(net "UPI_CPU1_CPU0_P2P2_DN<22>")
	)
	(segment
		(start 283.8069 -318.614044)
		(end 283.077666 -319.343278)
		(width 0.14732)
		(layer "In11.Cu")
		(net "UPI_CPU1_CPU0_P2P2_DN<22>")
	)
	(segment
		(start 259.516372 -330.344018)
		(end 259.080508 -330.344018)
		(width 0.14732)
		(layer "In11.Cu")
		(net "UPI_CPU1_CPU0_P2P2_DN<22>")
	)
	(segment
		(start 108.743496 -287.778698)
		(end 108.749592 -287.775142)
		(width 0.0889)
		(layer "In11.Cu")
		(net "UPI_CPU1_CPU0_P2P2_DN<22>")
	)
	(segment
		(start 316.68593 -309.080916)
		(end 316.54115 -309.225696)
		(width 0.14732)
		(layer "In11.Cu")
		(net "UPI_CPU1_CPU0_P2P2_DN<22>")
	)
	(segment
		(start 283.077666 -319.343278)
		(end 283.077666 -321.385438)
		(width 0.14732)
		(layer "In11.Cu")
		(net "UPI_CPU1_CPU0_P2P2_DN<22>")
	)
	(segment
		(start 108.309664 -293.435278)
		(end 108.164884 -293.290498)
		(width 0.14732)
		(layer "In11.Cu")
		(net "UPI_CPU1_CPU0_P2P2_DN<22>")
	)
	(segment
		(start 299.019468 -319.674748)
		(end 299.019468 -320.877946)
		(width 0.14732)
		(layer "In11.Cu")
		(net "UPI_CPU1_CPU0_P2P2_DN<22>")
	)
	(arc
		(start 109.03204 -288.863278)
		(mid 108.936988 -288.61746)
		(end 108.74248 -288.439606)
		(width 0.0889)
		(layer "In11.Cu")
		(net "UPI_CPU1_CPU0_P2P2_DN<22>")
	)
	(arc
		(start 334.972914 -283.709364)
		(mid 335.107847 -283.842718)
		(end 335.160112 -284.025086)
		(width 0.0889)
		(layer "In11.Cu")
		(net "UPI_CPU1_CPU0_P2P2_DN<22>")
	)
	(arc
		(start 107.79506 -285.166816)
		(mid 107.616463 -284.847538)
		(end 107.79506 -284.52826)
		(width 0.0889)
		(layer "In11.Cu")
		(net "UPI_CPU1_CPU0_P2P2_DN<22>")
	)
	(arc
		(start 335.160112 -284.043628)
		(mid 335.238223 -284.320577)
		(end 335.44256 -284.52318)
		(width 0.0889)
		(layer "In11.Cu")
		(net "UPI_CPU1_CPU0_P2P2_DN<22>")
	)
	(arc
		(start 108.74248 -288.439606)
		(mid 108.623995 -288.336778)
		(end 108.556298 -288.195258)
		(width 0.0889)
		(layer "In11.Cu")
		(net "UPI_CPU1_CPU0_P2P2_DN<22>")
	)
	(arc
		(start 108.741464 -289.458654)
		(mid 108.910269 -289.320972)
		(end 109.017308 -289.131248)
		(width 0.0889)
		(layer "In11.Cu")
		(net "UPI_CPU1_CPU0_P2P2_DN<22>")
	)
	(arc
		(start 335.160112 -285.661354)
		(mid 335.112433 -285.844254)
		(end 334.98155 -285.980632)
		(width 0.0889)
		(layer "In11.Cu")
		(net "UPI_CPU1_CPU0_P2P2_DN<22>")
	)
	(arc
		(start 334.97266 -285.985712)
		(mid 334.770488 -286.184853)
		(end 334.690466 -286.457136)
		(width 0.0889)
		(layer "In11.Cu")
		(net "UPI_CPU1_CPU0_P2P2_DN<22>")
	)
	(arc
		(start 107.79506 -281.911298)
		(mid 107.664146 -281.774938)
		(end 107.616498 -281.59202)
		(width 0.0889)
		(layer "In11.Cu")
		(net "UPI_CPU1_CPU0_P2P2_DN<22>")
	)
	(arc
		(start 335.020158 -282.11399)
		(mid 335.121928 -282.241023)
		(end 335.160112 -282.399232)
		(width 0.0889)
		(layer "In11.Cu")
		(net "UPI_CPU1_CPU0_P2P2_DN<22>")
	)
	(arc
		(start 334.972914 -282.730194)
		(mid 334.690046 -283.216313)
		(end 334.966818 -283.705808)
		(width 0.0889)
		(layer "In11.Cu")
		(net "UPI_CPU1_CPU0_P2P2_DN<22>")
	)
	(arc
		(start 108.26496 -282.725114)
		(mid 108.134046 -282.588754)
		(end 108.086398 -282.405836)
		(width 0.0889)
		(layer "In11.Cu")
		(net "UPI_CPU1_CPU0_P2P2_DN<22>")
	)
	(arc
		(start 335.160112 -282.415234)
		(mid 335.107664 -282.597174)
		(end 334.972914 -282.730194)
		(width 0.0889)
		(layer "In11.Cu")
		(net "UPI_CPU1_CPU0_P2P2_DN<22>")
	)
	(arc
		(start 335.160112 -282.399232)
		(mid 335.1602 -282.407233)
		(end 335.160112 -282.415234)
		(width 0.0889)
		(layer "In11.Cu")
		(net "UPI_CPU1_CPU0_P2P2_DN<22>")
	)
	(arc
		(start 334.690212 -286.48533)
		(mid 334.768301 -286.762311)
		(end 334.97266 -286.964882)
		(width 0.0889)
		(layer "In11.Cu")
		(net "UPI_CPU1_CPU0_P2P2_DN<22>")
	)
	(arc
		(start 107.319064 -281.093926)
		(mid 107.042589 -281.026606)
		(end 106.768392 -281.102562)
		(width 0.0889)
		(layer "In11.Cu")
		(net "UPI_CPU1_CPU0_P2P2_DN<22>")
	)
	(arc
		(start 108.26496 -285.980632)
		(mid 108.134046 -285.844272)
		(end 108.086398 -285.661354)
		(width 0.0889)
		(layer "In11.Cu")
		(net "UPI_CPU1_CPU0_P2P2_DN<22>")
	)
	(arc
		(start 108.086398 -285.661354)
		(mid 108.012482 -285.381852)
		(end 107.810046 -285.175452)
		(width 0.0889)
		(layer "In11.Cu")
		(net "UPI_CPU1_CPU0_P2P2_DN<22>")
	)
	(arc
		(start 108.556298 -288.09442)
		(mid 108.608568 -287.912055)
		(end 108.743496 -287.778698)
		(width 0.0889)
		(layer "In11.Cu")
		(net "UPI_CPU1_CPU0_P2P2_DN<22>")
	)
	(arc
		(start 108.556298 -286.456882)
		(mid 108.476136 -286.184693)
		(end 108.27385 -285.985712)
		(width 0.0889)
		(layer "In11.Cu")
		(net "UPI_CPU1_CPU0_P2P2_DN<22>")
	)
	(arc
		(start 108.086398 -282.39593)
		(mid 108.008287 -282.118981)
		(end 107.80395 -281.916378)
		(width 0.0889)
		(layer "In11.Cu")
		(net "UPI_CPU1_CPU0_P2P2_DN<22>")
	)
	(arc
		(start 108.743496 -286.799782)
		(mid 108.608563 -286.666428)
		(end 108.556298 -286.48406)
		(width 0.0889)
		(layer "In11.Cu")
		(net "UPI_CPU1_CPU0_P2P2_DN<22>")
	)
	(arc
		(start 108.27385 -283.709364)
		(mid 108.556382 -283.219843)
		(end 108.27385 -282.730194)
		(width 0.0889)
		(layer "In11.Cu")
		(net "UPI_CPU1_CPU0_P2P2_DN<22>")
	)
	(arc
		(start 106.768392 -281.102562)
		(mid 106.581194 -281.152705)
		(end 106.393996 -281.102562)
		(width 0.0889)
		(layer "In11.Cu")
		(net "UPI_CPU1_CPU0_P2P2_DN<22>")
	)
	(arc
		(start 107.810046 -284.519624)
		(mid 108.012459 -284.313211)
		(end 108.086398 -284.033722)
		(width 0.0889)
		(layer "In11.Cu")
		(net "UPI_CPU1_CPU0_P2P2_DN<22>")
	)
	(arc
		(start 335.44256 -285.171896)
		(mid 335.238225 -285.374501)
		(end 335.160112 -285.651448)
		(width 0.0889)
		(layer "In11.Cu")
		(net "UPI_CPU1_CPU0_P2P2_DN<22>")
	)
	(arc
		(start 335.45145 -284.52826)
		(mid 335.630047 -284.847538)
		(end 335.45145 -285.166816)
		(width 0.0889)
		(layer "In11.Cu")
		(net "UPI_CPU1_CPU0_P2P2_DN<22>")
	)
	(arc
		(start 106.392472 -281.1018)
		(mid 106.271745 -280.989179)
		(end 106.211116 -280.835608)
		(width 0.0889)
		(layer "In11.Cu")
		(net "UPI_CPU1_CPU0_P2P2_DN<22>")
	)
	(arc
		(start 108.086398 -284.033722)
		(mid 108.134077 -283.850822)
		(end 108.26496 -283.714444)
		(width 0.0889)
		(layer "In11.Cu")
		(net "UPI_CPU1_CPU0_P2P2_DN<22>")
	)
	(arc
		(start 108.556044 -289.677348)
		(mid 108.628313 -289.550676)
		(end 108.741464 -289.458654)
		(width 0.0889)
		(layer "In11.Cu")
		(net "UPI_CPU1_CPU0_P2P2_DN<22>")
	)
	(arc
		(start 108.749592 -287.775142)
		(mid 109.026042 -287.28924)
		(end 108.749592 -286.803338)
		(width 0.0889)
		(layer "In11.Cu")
		(net "UPI_CPU1_CPU0_P2P2_DN<22>")
	)
	(arc
		(start 107.616498 -281.59202)
		(mid 107.542507 -281.312454)
		(end 107.339892 -281.106118)
		(width 0.0889)
		(layer "In11.Cu")
		(net "UPI_CPU1_CPU0_P2P2_DN<22>")
	)
	(arc
		(start 334.98155 -286.969962)
		(mid 335.146029 -287.391123)
		(end 334.785462 -287.664144)
		(width 0.0889)
		(layer "In11.Cu")
		(net "UPI_CPU1_CPU0_P2P2_DN<22>")
	)
	(arc
		(start 334.690466 -286.457136)
		(mid 334.69016 -286.471231)
		(end 334.690212 -286.48533)
		(width 0.0889)
		(layer "In11.Cu")
		(net "UPI_CPU1_CPU0_P2P2_DN<22>")
	)
	(segment
		(start 335.725262 -281.869896)
		(end 335.725262 -282.405836)
		(width 0.13208)
		(layer "F.Cu")
		(net "UPI_CPU1_CPU0_P2P2_DN<21>")
	)
	(segment
		(start 106.111294 -281.05608)
		(end 106.111294 -281.591766)
		(width 0.13208)
		(layer "F.Cu")
		(net "UPI_CPU1_CPU0_P2P2_DN<21>")
	)
	(segment
		(start 106.111294 -281.591766)
		(end 106.111548 -281.59202)
		(width 0.13208)
		(layer "F.Cu")
		(net "UPI_CPU1_CPU0_P2P2_DN<21>")
	)
	(segment
		(start 74.795126 -329.311508)
		(end 74.212958 -335.22158)
		(width 0.14732)
		(layer "In11.Cu")
		(net "UPI_CPU1_CPU0_P2P2_DN<21>")
	)
	(segment
		(start 269.763494 -324.952868)
		(end 270.580358 -324.952868)
		(width 0.14732)
		(layer "In11.Cu")
		(net "UPI_CPU1_CPU0_P2P2_DN<21>")
	)
	(segment
		(start 255.942084 -341.360252)
		(end 255.942084 -340.070948)
		(width 0.14732)
		(layer "In11.Cu")
		(net "UPI_CPU1_CPU0_P2P2_DN<21>")
	)
	(segment
		(start 259.176012 -341.12454)
		(end 259.593842 -340.70671)
		(width 0.14732)
		(layer "In11.Cu")
		(net "UPI_CPU1_CPU0_P2P2_DN<21>")
	)
	(segment
		(start 336.099912 -287.28924)
		(end 336.099912 -287.279334)
		(width 0.0889)
		(layer "In11.Cu")
		(net "UPI_CPU1_CPU0_P2P2_DN<21>")
	)
	(segment
		(start 257.066034 -341.6681)
		(end 256.249932 -341.6681)
		(width 0.14732)
		(layer "In11.Cu")
		(net "UPI_CPU1_CPU0_P2P2_DN<21>")
	)
	(segment
		(start 331.341222 -292.01364)
		(end 334.301846 -289.053016)
		(width 0.14732)
		(layer "In11.Cu")
		(net "UPI_CPU1_CPU0_P2P2_DN<21>")
	)
	(segment
		(start 74.212958 -352.65868)
		(end 77.537818 -360.676444)
		(width 0.14732)
		(layer "In11.Cu")
		(net "UPI_CPU1_CPU0_P2P2_DN<21>")
	)
	(segment
		(start 288.190432 -323.105018)
		(end 298.882816 -323.105018)
		(width 0.14732)
		(layer "In11.Cu")
		(net "UPI_CPU1_CPU0_P2P2_DN<21>")
	)
	(segment
		(start 300.27245 -322.5292)
		(end 301.0789 -321.72275)
		(width 0.14732)
		(layer "In11.Cu")
		(net "UPI_CPU1_CPU0_P2P2_DN<21>")
	)
	(segment
		(start 311.982866 -311.384442)
		(end 312.3438 -311.31002)
		(width 0.14732)
		(layer "In11.Cu")
		(net "UPI_CPU1_CPU0_P2P2_DN<21>")
	)
	(segment
		(start 107.324906 -282.725114)
		(end 107.333796 -282.730194)
		(width 0.0889)
		(layer "In11.Cu")
		(net "UPI_CPU1_CPU0_P2P2_DN<21>")
	)
	(segment
		(start 336.099912 -285.679896)
		(end 336.099912 -285.651448)
		(width 0.0889)
		(layer "In11.Cu")
		(net "UPI_CPU1_CPU0_P2P2_DN<21>")
	)
	(segment
		(start 257.213354 -341.81542)
		(end 257.066034 -341.6681)
		(width 0.14732)
		(layer "In11.Cu")
		(net "UPI_CPU1_CPU0_P2P2_DN<21>")
	)
	(segment
		(start 315.65977 -311.009538)
		(end 315.80455 -310.864758)
		(width 0.14732)
		(layer "In11.Cu")
		(net "UPI_CPU1_CPU0_P2P2_DN<21>")
	)
	(segment
		(start 126.347728 -374.897904)
		(end 160.78708 -374.897904)
		(width 0.14732)
		(layer "In11.Cu")
		(net "UPI_CPU1_CPU0_P2P2_DN<21>")
	)
	(segment
		(start 301.879254 -316.656466)
		(end 302.341788 -316.329314)
		(width 0.14732)
		(layer "In11.Cu")
		(net "UPI_CPU1_CPU0_P2P2_DN<21>")
	)
	(segment
		(start 107.61599 -289.628834)
		(end 107.61599 -290.151058)
		(width 0.0889)
		(layer "In11.Cu")
		(net "UPI_CPU1_CPU0_P2P2_DN<21>")
	)
	(segment
		(start 335.91246 -287.613598)
		(end 335.92135 -287.608518)
		(width 0.0889)
		(layer "In11.Cu")
		(net "UPI_CPU1_CPU0_P2P2_DN<21>")
	)
	(segment
		(start 83.476084 -318.609472)
		(end 75.947524 -326.138032)
		(width 0.14732)
		(layer "In11.Cu")
		(net "UPI_CPU1_CPU0_P2P2_DN<21>")
	)
	(segment
		(start 107.79506 -288.422334)
		(end 107.803188 -288.426906)
		(width 0.0889)
		(layer "In11.Cu")
		(net "UPI_CPU1_CPU0_P2P2_DN<21>")
	)
	(segment
		(start 199.946514 -367.993422)
		(end 212.312504 -370.174012)
		(width 0.14732)
		(layer "In11.Cu")
		(net "UPI_CPU1_CPU0_P2P2_DN<21>")
	)
	(segment
		(start 317.8683 -310.19496)
		(end 328.881994 -299.181012)
		(width 0.14732)
		(layer "In11.Cu")
		(net "UPI_CPU1_CPU0_P2P2_DN<21>")
	)
	(segment
		(start 103.897176 -300.247812)
		(end 99.53117 -305.435762)
		(width 0.14732)
		(layer "In11.Cu")
		(net "UPI_CPU1_CPU0_P2P2_DN<21>")
	)
	(segment
		(start 261.634986 -334.378046)
		(end 262.251952 -333.76108)
		(width 0.14732)
		(layer "In11.Cu")
		(net "UPI_CPU1_CPU0_P2P2_DN<21>")
	)
	(segment
		(start 212.312504 -370.174012)
		(end 228.72954 -367.279428)
		(width 0.14732)
		(layer "In11.Cu")
		(net "UPI_CPU1_CPU0_P2P2_DN<21>")
	)
	(segment
		(start 257.146298 -339.302598)
		(end 258.96824 -341.12454)
		(width 0.14732)
		(layer "In11.Cu")
		(net "UPI_CPU1_CPU0_P2P2_DN<21>")
	)
	(segment
		(start 268.571726 -325.260716)
		(end 268.571726 -325.426324)
		(width 0.14732)
		(layer "In11.Cu")
		(net "UPI_CPU1_CPU0_P2P2_DN<21>")
	)
	(segment
		(start 276.371304 -324.952868)
		(end 277.424388 -323.899784)
		(width 0.14732)
		(layer "In11.Cu")
		(net "UPI_CPU1_CPU0_P2P2_DN<21>")
	)
	(segment
		(start 257.7719 -338.676996)
		(end 257.7719 -338.241132)
		(width 0.14732)
		(layer "In11.Cu")
		(net "UPI_CPU1_CPU0_P2P2_DN<21>")
	)
	(segment
		(start 283.699712 -323.057774)
		(end 284.247336 -322.51015)
		(width 0.14732)
		(layer "In11.Cu")
		(net "UPI_CPU1_CPU0_P2P2_DN<21>")
	)
	(segment
		(start 271.772126 -325.260716)
		(end 272.079974 -324.952868)
		(width 0.14732)
		(layer "In11.Cu")
		(net "UPI_CPU1_CPU0_P2P2_DN<21>")
	)
	(segment
		(start 262.608568 -331.379576)
		(end 266.82446 -331.379576)
		(width 0.14732)
		(layer "In11.Cu")
		(net "UPI_CPU1_CPU0_P2P2_DN<21>")
	)
	(segment
		(start 269.455646 -325.260716)
		(end 269.763494 -324.952868)
		(width 0.14732)
		(layer "In11.Cu")
		(net "UPI_CPU1_CPU0_P2P2_DN<21>")
	)
	(segment
		(start 308.42839 -312.882534)
		(end 308.57317 -312.737754)
		(width 0.14732)
		(layer "In11.Cu")
		(net "UPI_CPU1_CPU0_P2P2_DN<21>")
	)
	(segment
		(start 302.341788 -316.329314)
		(end 304.474372 -315.253878)
		(width 0.14732)
		(layer "In11.Cu")
		(net "UPI_CPU1_CPU0_P2P2_DN<21>")
	)
	(segment
		(start 106.869992 -284.519624)
		(end 106.862372 -284.523942)
		(width 0.0889)
		(layer "In11.Cu")
		(net "UPI_CPU1_CPU0_P2P2_DN<21>")
	)
	(segment
		(start 336.38236 -285.171896)
		(end 336.39125 -285.166816)
		(width 0.0889)
		(layer "In11.Cu")
		(net "UPI_CPU1_CPU0_P2P2_DN<21>")
	)
	(segment
		(start 228.72954 -367.279428)
		(end 252.608588 -350.556322)
		(width 0.14732)
		(layer "In11.Cu")
		(net "UPI_CPU1_CPU0_P2P2_DN<21>")
	)
	(segment
		(start 99.396296 -370.899944)
		(end 126.347728 -374.897904)
		(width 0.14732)
		(layer "In11.Cu")
		(net "UPI_CPU1_CPU0_P2P2_DN<21>")
	)
	(segment
		(start 75.287378 -327.533254)
		(end 74.795126 -329.311508)
		(width 0.14732)
		(layer "In11.Cu")
		(net "UPI_CPU1_CPU0_P2P2_DN<21>")
	)
	(segment
		(start 105.83418 -292.442646)
		(end 105.83418 -297.503596)
		(width 0.14732)
		(layer "In11.Cu")
		(net "UPI_CPU1_CPU0_P2P2_DN<21>")
	)
	(segment
		(start 317.053722 -311.009538)
		(end 317.402972 -310.660288)
		(width 0.14732)
		(layer "In11.Cu")
		(net "UPI_CPU1_CPU0_P2P2_DN<21>")
	)
	(segment
		(start 266.82446 -330.495656)
		(end 262.608568 -330.495656)
		(width 0.14732)
		(layer "In11.Cu")
		(net "UPI_CPU1_CPU0_P2P2_DN<21>")
	)
	(segment
		(start 106.855006 -285.166816)
		(end 106.869992 -285.175452)
		(width 0.0889)
		(layer "In11.Cu")
		(net "UPI_CPU1_CPU0_P2P2_DN<21>")
	)
	(segment
		(start 262.251952 -333.76108)
		(end 262.251952 -331.736192)
		(width 0.14732)
		(layer "In11.Cu")
		(net "UPI_CPU1_CPU0_P2P2_DN<21>")
	)
	(segment
		(start 262.251952 -331.736192)
		(end 262.608568 -331.379576)
		(width 0.14732)
		(layer "In11.Cu")
		(net "UPI_CPU1_CPU0_P2P2_DN<21>")
	)
	(segment
		(start 336.38236 -286.799782)
		(end 336.383122 -286.799274)
		(width 0.0889)
		(layer "In11.Cu")
		(net "UPI_CPU1_CPU0_P2P2_DN<21>")
	)
	(segment
		(start 334.301846 -289.053016)
		(end 334.31734 -289.037522)
		(width 0.0889)
		(layer "In11.Cu")
		(net "UPI_CPU1_CPU0_P2P2_DN<21>")
	)
	(segment
		(start 301.704502 -317.01613)
		(end 301.879254 -316.656466)
		(width 0.14732)
		(layer "In11.Cu")
		(net "UPI_CPU1_CPU0_P2P2_DN<21>")
	)
	(segment
		(start 308.57317 -312.737754)
		(end 308.94147 -312.737754)
		(width 0.14732)
		(layer "In11.Cu")
		(net "UPI_CPU1_CPU0_P2P2_DN<21>")
	)
	(segment
		(start 313.560206 -311.059576)
		(end 313.92114 -310.985408)
		(width 0.14732)
		(layer "In11.Cu")
		(net "UPI_CPU1_CPU0_P2P2_DN<21>")
	)
	(segment
		(start 107.339892 -283.705808)
		(end 107.337606 -283.707078)
		(width 0.0889)
		(layer "In11.Cu")
		(net "UPI_CPU1_CPU0_P2P2_DN<21>")
	)
	(segment
		(start 335.630012 -283.229812)
		(end 335.630012 -283.201364)
		(width 0.0889)
		(layer "In11.Cu")
		(net "UPI_CPU1_CPU0_P2P2_DN<21>")
	)
	(segment
		(start 77.537818 -360.676444)
		(end 79.533242 -362.671614)
		(width 0.14732)
		(layer "In11.Cu")
		(net "UPI_CPU1_CPU0_P2P2_DN<21>")
	)
	(segment
		(start 107.345988 -286.95777)
		(end 107.333796 -286.964882)
		(width 0.0889)
		(layer "In11.Cu")
		(net "UPI_CPU1_CPU0_P2P2_DN<21>")
	)
	(segment
		(start 262.251952 -327.84034)
		(end 265.139424 -324.952868)
		(width 0.14732)
		(layer "In11.Cu")
		(net "UPI_CPU1_CPU0_P2P2_DN<21>")
	)
	(segment
		(start 74.212958 -335.22158)
		(end 74.212958 -352.65868)
		(width 0.14732)
		(layer "In11.Cu")
		(net "UPI_CPU1_CPU0_P2P2_DN<21>")
	)
	(segment
		(start 270.888206 -325.260716)
		(end 270.888206 -325.426324)
		(width 0.14732)
		(layer "In11.Cu")
		(net "UPI_CPU1_CPU0_P2P2_DN<21>")
	)
	(segment
		(start 284.247336 -322.51015)
		(end 287.595564 -322.51015)
		(width 0.14732)
		(layer "In11.Cu")
		(net "UPI_CPU1_CPU0_P2P2_DN<21>")
	)
	(segment
		(start 336.39125 -284.52826)
		(end 336.38236 -284.52318)
		(width 0.0889)
		(layer "In11.Cu")
		(net "UPI_CPU1_CPU0_P2P2_DN<21>")
	)
	(segment
		(start 258.026662 -333.00543)
		(end 258.026916 -332.570074)
		(width 0.14732)
		(layer "In11.Cu")
		(net "UPI_CPU1_CPU0_P2P2_DN<21>")
	)
	(segment
		(start 335.857596 -282.766008)
		(end 335.881726 -282.676854)
		(width 0.0889)
		(layer "In11.Cu")
		(net "UPI_CPU1_CPU0_P2P2_DN<21>")
	)
	(segment
		(start 309.916068 -312.882534)
		(end 311.080404 -311.718198)
		(width 0.14732)
		(layer "In11.Cu")
		(net "UPI_CPU1_CPU0_P2P2_DN<21>")
	)
	(segment
		(start 259.601716 -336.411316)
		(end 260.412992 -335.60004)
		(width 0.14732)
		(layer "In11.Cu")
		(net "UPI_CPU1_CPU0_P2P2_DN<21>")
	)
	(segment
		(start 257.213354 -342.4047)
		(end 257.213354 -341.81542)
		(width 0.14732)
		(layer "In11.Cu")
		(net "UPI_CPU1_CPU0_P2P2_DN<21>")
	)
	(segment
		(start 308.94147 -312.737754)
		(end 309.08625 -312.882534)
		(width 0.14732)
		(layer "In11.Cu")
		(net "UPI_CPU1_CPU0_P2P2_DN<21>")
	)
	(segment
		(start 261.426706 -334.378046)
		(end 261.634986 -334.378046)
		(width 0.14732)
		(layer "In11.Cu")
		(net "UPI_CPU1_CPU0_P2P2_DN<21>")
	)
	(segment
		(start 304.474372 -315.253878)
		(end 306.166774 -313.875928)
		(width 0.14732)
		(layer "In11.Cu")
		(net "UPI_CPU1_CPU0_P2P2_DN<21>")
	)
	(segment
		(start 314.52185 -311.009538)
		(end 315.65977 -311.009538)
		(width 0.14732)
		(layer "In11.Cu")
		(net "UPI_CPU1_CPU0_P2P2_DN<21>")
	)
	(segment
		(start 269.308326 -325.573644)
		(end 269.455646 -325.426324)
		(width 0.14732)
		(layer "In11.Cu")
		(net "UPI_CPU1_CPU0_P2P2_DN<21>")
	)
	(segment
		(start 335.630012 -288.103056)
		(end 335.630012 -288.09315)
		(width 0.0889)
		(layer "In11.Cu")
		(net "UPI_CPU1_CPU0_P2P2_DN<21>")
	)
	(segment
		(start 255.942084 -342.859868)
		(end 256.249932 -342.55202)
		(width 0.14732)
		(layer "In11.Cu")
		(net "UPI_CPU1_CPU0_P2P2_DN<21>")
	)
	(segment
		(start 317.402972 -310.660288)
		(end 317.402972 -310.455564)
		(width 0.14732)
		(layer "In11.Cu")
		(net "UPI_CPU1_CPU0_P2P2_DN<21>")
	)
	(segment
		(start 255.942084 -340.070948)
		(end 256.710434 -339.302598)
		(width 0.14732)
		(layer "In11.Cu")
		(net "UPI_CPU1_CPU0_P2P2_DN<21>")
	)
	(segment
		(start 257.7719 -338.241132)
		(end 258.379722 -337.63331)
		(width 0.14732)
		(layer "In11.Cu")
		(net "UPI_CPU1_CPU0_P2P2_DN<21>")
	)
	(segment
		(start 301.0789 -321.72275)
		(end 301.0789 -320.637408)
		(width 0.14732)
		(layer "In11.Cu")
		(net "UPI_CPU1_CPU0_P2P2_DN<21>")
	)
	(segment
		(start 262.251952 -330.13904)
		(end 262.251952 -327.84034)
		(width 0.14732)
		(layer "In11.Cu")
		(net "UPI_CPU1_CPU0_P2P2_DN<21>")
	)
	(segment
		(start 311.080404 -311.718198)
		(end 311.870344 -311.555638)
		(width 0.14732)
		(layer "In11.Cu")
		(net "UPI_CPU1_CPU0_P2P2_DN<21>")
	)
	(segment
		(start 271.624806 -325.573644)
		(end 271.772126 -325.426324)
		(width 0.14732)
		(layer "In11.Cu")
		(net "UPI_CPU1_CPU0_P2P2_DN<21>")
	)
	(segment
		(start 317.402972 -310.455564)
		(end 317.663576 -310.19496)
		(width 0.14732)
		(layer "In11.Cu")
		(net "UPI_CPU1_CPU0_P2P2_DN<21>")
	)
	(segment
		(start 313.447684 -311.230772)
		(end 313.560206 -311.059576)
		(width 0.14732)
		(layer "In11.Cu")
		(net "UPI_CPU1_CPU0_P2P2_DN<21>")
	)
	(segment
		(start 287.595564 -322.51015)
		(end 288.190432 -323.105018)
		(width 0.14732)
		(layer "In11.Cu")
		(net "UPI_CPU1_CPU0_P2P2_DN<21>")
	)
	(segment
		(start 106.268012 -281.863038)
		(end 106.356912 -281.88666)
		(width 0.0889)
		(layer "In11.Cu")
		(net "UPI_CPU1_CPU0_P2P2_DN<21>")
	)
	(segment
		(start 107.146344 -282.390342)
		(end 107.146344 -282.405836)
		(width 0.0889)
		(layer "In11.Cu")
		(net "UPI_CPU1_CPU0_P2P2_DN<21>")
	)
	(segment
		(start 306.166774 -313.875928)
		(end 306.448714 -313.875928)
		(width 0.14732)
		(layer "In11.Cu")
		(net "UPI_CPU1_CPU0_P2P2_DN<21>")
	)
	(segment
		(start 317.663576 -310.19496)
		(end 317.8683 -310.19496)
		(width 0.14732)
		(layer "In11.Cu")
		(net "UPI_CPU1_CPU0_P2P2_DN<21>")
	)
	(segment
		(start 255.993392 -335.0387)
		(end 255.993392 -334.603344)
		(width 0.14732)
		(layer "In11.Cu")
		(net "UPI_CPU1_CPU0_P2P2_DN<21>")
	)
	(segment
		(start 255.942084 -347.222826)
		(end 255.942084 -342.859868)
		(width 0.14732)
		(layer "In11.Cu")
		(net "UPI_CPU1_CPU0_P2P2_DN<21>")
	)
	(segment
		(start 330.819506 -292.794944)
		(end 331.341222 -292.01364)
		(width 0.14732)
		(layer "In11.Cu")
		(net "UPI_CPU1_CPU0_P2P2_DN<21>")
	)
	(segment
		(start 314.092336 -311.09793)
		(end 314.52185 -311.009538)
		(width 0.14732)
		(layer "In11.Cu")
		(net "UPI_CPU1_CPU0_P2P2_DN<21>")
	)
	(segment
		(start 334.31734 -289.037522)
		(end 334.376268 -289.037522)
		(width 0.0889)
		(layer "In11.Cu")
		(net "UPI_CPU1_CPU0_P2P2_DN<21>")
	)
	(segment
		(start 260.412992 -335.39176)
		(end 258.026662 -333.00543)
		(width 0.14732)
		(layer "In11.Cu")
		(net "UPI_CPU1_CPU0_P2P2_DN<21>")
	)
	(segment
		(start 328.881994 -299.181012)
		(end 330.819506 -292.794944)
		(width 0.14732)
		(layer "In11.Cu")
		(net "UPI_CPU1_CPU0_P2P2_DN<21>")
	)
	(segment
		(start 107.337606 -283.707078)
		(end 107.333796 -283.709364)
		(width 0.0889)
		(layer "In11.Cu")
		(net "UPI_CPU1_CPU0_P2P2_DN<21>")
	)
	(segment
		(start 336.383122 -286.151574)
		(end 336.38236 -286.151066)
		(width 0.0889)
		(layer "In11.Cu")
		(net "UPI_CPU1_CPU0_P2P2_DN<21>")
	)
	(segment
		(start 105.709974 -297.804332)
		(end 103.897176 -300.247812)
		(width 0.14732)
		(layer "In11.Cu")
		(net "UPI_CPU1_CPU0_P2P2_DN<21>")
	)
	(segment
		(start 270.580358 -324.952868)
		(end 270.888206 -325.260716)
		(width 0.14732)
		(layer "In11.Cu")
		(net "UPI_CPU1_CPU0_P2P2_DN<21>")
	)
	(segment
		(start 301.0789 -320.637408)
		(end 301.415958 -318.85763)
		(width 0.14732)
		(layer "In11.Cu")
		(net "UPI_CPU1_CPU0_P2P2_DN<21>")
	)
	(segment
		(start 270.888206 -325.426324)
		(end 271.035526 -325.573644)
		(width 0.14732)
		(layer "In11.Cu")
		(net "UPI_CPU1_CPU0_P2P2_DN<21>")
	)
	(segment
		(start 268.263878 -324.952868)
		(end 268.571726 -325.260716)
		(width 0.14732)
		(layer "In11.Cu")
		(net "UPI_CPU1_CPU0_P2P2_DN<21>")
	)
	(segment
		(start 269.455646 -325.426324)
		(end 269.455646 -325.260716)
		(width 0.14732)
		(layer "In11.Cu")
		(net "UPI_CPU1_CPU0_P2P2_DN<21>")
	)
	(segment
		(start 259.040376 -331.991716)
		(end 261.426706 -334.378046)
		(width 0.14732)
		(layer "In11.Cu")
		(net "UPI_CPU1_CPU0_P2P2_DN<21>")
	)
	(segment
		(start 99.53117 -305.435762)
		(end 83.476084 -318.609472)
		(width 0.14732)
		(layer "In11.Cu")
		(net "UPI_CPU1_CPU0_P2P2_DN<21>")
	)
	(segment
		(start 107.803188 -288.426906)
		(end 107.80395 -288.427414)
		(width 0.0889)
		(layer "In11.Cu")
		(net "UPI_CPU1_CPU0_P2P2_DN<21>")
	)
	(segment
		(start 256.57175 -334.024986)
		(end 257.007106 -334.024986)
		(width 0.14732)
		(layer "In11.Cu")
		(net "UPI_CPU1_CPU0_P2P2_DN<21>")
	)
	(segment
		(start 277.424388 -323.899784)
		(end 283.552392 -323.899784)
		(width 0.14732)
		(layer "In11.Cu")
		(net "UPI_CPU1_CPU0_P2P2_DN<21>")
	)
	(segment
		(start 258.96824 -341.12454)
		(end 259.176012 -341.12454)
		(width 0.14732)
		(layer "In11.Cu")
		(net "UPI_CPU1_CPU0_P2P2_DN<21>")
	)
	(segment
		(start 312.514996 -311.422796)
		(end 313.447684 -311.230772)
		(width 0.14732)
		(layer "In11.Cu")
		(net "UPI_CPU1_CPU0_P2P2_DN<21>")
	)
	(segment
		(start 268.571726 -325.426324)
		(end 268.719046 -325.573644)
		(width 0.14732)
		(layer "In11.Cu")
		(net "UPI_CPU1_CPU0_P2P2_DN<21>")
	)
	(segment
		(start 75.947524 -326.138032)
		(end 75.287378 -327.533254)
		(width 0.14732)
		(layer "In11.Cu")
		(net "UPI_CPU1_CPU0_P2P2_DN<21>")
	)
	(segment
		(start 334.376268 -289.037522)
		(end 334.935576 -288.478214)
		(width 0.0889)
		(layer "In11.Cu")
		(net "UPI_CPU1_CPU0_P2P2_DN<21>")
	)
	(segment
		(start 259.593842 -340.498938)
		(end 257.7719 -338.676996)
		(width 0.14732)
		(layer "In11.Cu")
		(net "UPI_CPU1_CPU0_P2P2_DN<21>")
	)
	(segment
		(start 107.61599 -290.151058)
		(end 105.792016 -291.975032)
		(width 0.0889)
		(layer "In11.Cu")
		(net "UPI_CPU1_CPU0_P2P2_DN<21>")
	)
	(segment
		(start 316.31763 -311.009538)
		(end 317.053722 -311.009538)
		(width 0.14732)
		(layer "In11.Cu")
		(net "UPI_CPU1_CPU0_P2P2_DN<21>")
	)
	(segment
		(start 336.385662 -286.79775)
		(end 336.39125 -286.794702)
		(width 0.0889)
		(layer "In11.Cu")
		(net "UPI_CPU1_CPU0_P2P2_DN<21>")
	)
	(segment
		(start 256.710434 -339.302598)
		(end 257.146298 -339.302598)
		(width 0.14732)
		(layer "In11.Cu")
		(net "UPI_CPU1_CPU0_P2P2_DN<21>")
	)
	(segment
		(start 107.822238 -288.43859)
		(end 107.822238 -288.438844)
		(width 0.0889)
		(layer "In11.Cu")
		(net "UPI_CPU1_CPU0_P2P2_DN<21>")
	)
	(segment
		(start 252.608588 -350.556322)
		(end 255.942084 -347.222826)
		(width 0.14732)
		(layer "In11.Cu")
		(net "UPI_CPU1_CPU0_P2P2_DN<21>")
	)
	(segment
		(start 257.007106 -334.024986)
		(end 259.393436 -336.411316)
		(width 0.14732)
		(layer "In11.Cu")
		(net "UPI_CPU1_CPU0_P2P2_DN<21>")
	)
	(segment
		(start 268.719046 -325.573644)
		(end 269.308326 -325.573644)
		(width 0.14732)
		(layer "In11.Cu")
		(net "UPI_CPU1_CPU0_P2P2_DN<21>")
	)
	(segment
		(start 311.870344 -311.555638)
		(end 311.982866 -311.384442)
		(width 0.14732)
		(layer "In11.Cu")
		(net "UPI_CPU1_CPU0_P2P2_DN<21>")
	)
	(segment
		(start 106.111548 -281.59202)
		(end 106.268012 -281.863038)
		(width 0.0889)
		(layer "In11.Cu")
		(net "UPI_CPU1_CPU0_P2P2_DN<21>")
	)
	(segment
		(start 105.792016 -291.975032)
		(end 105.792016 -292.378384)
		(width 0.0889)
		(layer "In11.Cu")
		(net "UPI_CPU1_CPU0_P2P2_DN<21>")
	)
	(segment
		(start 265.139424 -324.952868)
		(end 268.263878 -324.952868)
		(width 0.14732)
		(layer "In11.Cu")
		(net "UPI_CPU1_CPU0_P2P2_DN<21>")
	)
	(segment
		(start 312.3438 -311.31002)
		(end 312.514996 -311.422796)
		(width 0.14732)
		(layer "In11.Cu")
		(net "UPI_CPU1_CPU0_P2P2_DN<21>")
	)
	(segment
		(start 79.533242 -362.671614)
		(end 99.396296 -370.899944)
		(width 0.14732)
		(layer "In11.Cu")
		(net "UPI_CPU1_CPU0_P2P2_DN<21>")
	)
	(segment
		(start 258.605528 -331.991462)
		(end 259.040376 -331.991716)
		(width 0.14732)
		(layer "In11.Cu")
		(net "UPI_CPU1_CPU0_P2P2_DN<21>")
	)
	(segment
		(start 258.379722 -337.42503)
		(end 255.993392 -335.0387)
		(width 0.14732)
		(layer "In11.Cu")
		(net "UPI_CPU1_CPU0_P2P2_DN<21>")
	)
	(segment
		(start 301.415958 -318.85763)
		(end 301.704502 -317.01613)
		(width 0.14732)
		(layer "In11.Cu")
		(net "UPI_CPU1_CPU0_P2P2_DN<21>")
	)
	(segment
		(start 255.993392 -334.603344)
		(end 256.57175 -334.024986)
		(width 0.14732)
		(layer "In11.Cu")
		(net "UPI_CPU1_CPU0_P2P2_DN<21>")
	)
	(segment
		(start 105.83418 -297.503596)
		(end 105.709974 -297.804332)
		(width 0.14732)
		(layer "In11.Cu")
		(net "UPI_CPU1_CPU0_P2P2_DN<21>")
	)
	(segment
		(start 262.608568 -330.495656)
		(end 262.251952 -330.13904)
		(width 0.14732)
		(layer "In11.Cu")
		(net "UPI_CPU1_CPU0_P2P2_DN<21>")
	)
	(segment
		(start 335.913222 -283.709872)
		(end 335.91246 -283.709364)
		(width 0.0889)
		(layer "In11.Cu")
		(net "UPI_CPU1_CPU0_P2P2_DN<21>")
	)
	(segment
		(start 298.882816 -323.105018)
		(end 300.27245 -322.5292)
		(width 0.14732)
		(layer "In11.Cu")
		(net "UPI_CPU1_CPU0_P2P2_DN<21>")
	)
	(segment
		(start 258.026916 -332.570074)
		(end 258.605528 -331.991462)
		(width 0.14732)
		(layer "In11.Cu")
		(net "UPI_CPU1_CPU0_P2P2_DN<21>")
	)
	(segment
		(start 106.862372 -284.523942)
		(end 106.855006 -284.52826)
		(width 0.0889)
		(layer "In11.Cu")
		(net "UPI_CPU1_CPU0_P2P2_DN<21>")
	)
	(segment
		(start 160.78708 -374.897904)
		(end 199.946514 -367.993422)
		(width 0.14732)
		(layer "In11.Cu")
		(net "UPI_CPU1_CPU0_P2P2_DN<21>")
	)
	(segment
		(start 105.83418 -292.420548)
		(end 105.83418 -292.442646)
		(width 0.0889)
		(layer "In11.Cu")
		(net "UPI_CPU1_CPU0_P2P2_DN<21>")
	)
	(segment
		(start 335.44256 -288.427414)
		(end 335.45145 -288.422334)
		(width 0.0889)
		(layer "In11.Cu")
		(net "UPI_CPU1_CPU0_P2P2_DN<21>")
	)
	(segment
		(start 271.035526 -325.573644)
		(end 271.624806 -325.573644)
		(width 0.14732)
		(layer "In11.Cu")
		(net "UPI_CPU1_CPU0_P2P2_DN<21>")
	)
	(segment
		(start 307.442108 -312.882534)
		(end 308.42839 -312.882534)
		(width 0.14732)
		(layer "In11.Cu")
		(net "UPI_CPU1_CPU0_P2P2_DN<21>")
	)
	(segment
		(start 316.17285 -310.864758)
		(end 316.31763 -311.009538)
		(width 0.14732)
		(layer "In11.Cu")
		(net "UPI_CPU1_CPU0_P2P2_DN<21>")
	)
	(segment
		(start 258.379722 -337.63331)
		(end 258.379722 -337.42503)
		(width 0.14732)
		(layer "In11.Cu")
		(net "UPI_CPU1_CPU0_P2P2_DN<21>")
	)
	(segment
		(start 336.38236 -284.52318)
		(end 336.376264 -284.519624)
		(width 0.0889)
		(layer "In11.Cu")
		(net "UPI_CPU1_CPU0_P2P2_DN<21>")
	)
	(segment
		(start 335.881726 -282.676854)
		(end 335.725262 -282.405836)
		(width 0.0889)
		(layer "In11.Cu")
		(net "UPI_CPU1_CPU0_P2P2_DN<21>")
	)
	(segment
		(start 272.079974 -324.952868)
		(end 276.371304 -324.952868)
		(width 0.14732)
		(layer "In11.Cu")
		(net "UPI_CPU1_CPU0_P2P2_DN<21>")
	)
	(segment
		(start 335.92135 -283.714444)
		(end 335.915762 -283.711396)
		(width 0.0889)
		(layer "In11.Cu")
		(net "UPI_CPU1_CPU0_P2P2_DN<21>")
	)
	(segment
		(start 271.772126 -325.426324)
		(end 271.772126 -325.260716)
		(width 0.14732)
		(layer "In11.Cu")
		(net "UPI_CPU1_CPU0_P2P2_DN<21>")
	)
	(segment
		(start 107.146598 -285.661354)
		(end 107.146598 -285.66999)
		(width 0.0889)
		(layer "In11.Cu")
		(net "UPI_CPU1_CPU0_P2P2_DN<21>")
	)
	(segment
		(start 313.92114 -310.985408)
		(end 314.092336 -311.09793)
		(width 0.14732)
		(layer "In11.Cu")
		(net "UPI_CPU1_CPU0_P2P2_DN<21>")
	)
	(segment
		(start 256.249932 -341.6681)
		(end 255.942084 -341.360252)
		(width 0.14732)
		(layer "In11.Cu")
		(net "UPI_CPU1_CPU0_P2P2_DN<21>")
	)
	(segment
		(start 257.066034 -342.55202)
		(end 257.213354 -342.4047)
		(width 0.14732)
		(layer "In11.Cu")
		(net "UPI_CPU1_CPU0_P2P2_DN<21>")
	)
	(segment
		(start 259.393436 -336.411316)
		(end 259.601716 -336.411316)
		(width 0.14732)
		(layer "In11.Cu")
		(net "UPI_CPU1_CPU0_P2P2_DN<21>")
	)
	(segment
		(start 107.333796 -287.613598)
		(end 107.345988 -287.62071)
		(width 0.0889)
		(layer "In11.Cu")
		(net "UPI_CPU1_CPU0_P2P2_DN<21>")
	)
	(segment
		(start 256.249932 -342.55202)
		(end 257.066034 -342.55202)
		(width 0.14732)
		(layer "In11.Cu")
		(net "UPI_CPU1_CPU0_P2P2_DN<21>")
	)
	(segment
		(start 260.412992 -335.60004)
		(end 260.412992 -335.39176)
		(width 0.14732)
		(layer "In11.Cu")
		(net "UPI_CPU1_CPU0_P2P2_DN<21>")
	)
	(segment
		(start 336.383122 -286.799274)
		(end 336.385662 -286.79775)
		(width 0.0889)
		(layer "In11.Cu")
		(net "UPI_CPU1_CPU0_P2P2_DN<21>")
	)
	(segment
		(start 283.552392 -323.899784)
		(end 283.699712 -323.752464)
		(width 0.14732)
		(layer "In11.Cu")
		(net "UPI_CPU1_CPU0_P2P2_DN<21>")
	)
	(segment
		(start 107.146598 -284.025086)
		(end 107.146598 -284.033722)
		(width 0.0889)
		(layer "In11.Cu")
		(net "UPI_CPU1_CPU0_P2P2_DN<21>")
	)
	(segment
		(start 309.08625 -312.882534)
		(end 309.916068 -312.882534)
		(width 0.14732)
		(layer "In11.Cu")
		(net "UPI_CPU1_CPU0_P2P2_DN<21>")
	)
	(segment
		(start 336.39125 -286.156146)
		(end 336.383122 -286.151574)
		(width 0.0889)
		(layer "In11.Cu")
		(net "UPI_CPU1_CPU0_P2P2_DN<21>")
	)
	(segment
		(start 266.97178 -330.642976)
		(end 266.82446 -330.495656)
		(width 0.14732)
		(layer "In11.Cu")
		(net "UPI_CPU1_CPU0_P2P2_DN<21>")
	)
	(segment
		(start 306.448714 -313.875928)
		(end 307.442108 -312.882534)
		(width 0.14732)
		(layer "In11.Cu")
		(net "UPI_CPU1_CPU0_P2P2_DN<21>")
	)
	(segment
		(start 107.951016 -289.293808)
		(end 107.61599 -289.628834)
		(width 0.0889)
		(layer "In11.Cu")
		(net "UPI_CPU1_CPU0_P2P2_DN<21>")
	)
	(segment
		(start 335.915762 -283.711396)
		(end 335.913222 -283.709872)
		(width 0.0889)
		(layer "In11.Cu")
		(net "UPI_CPU1_CPU0_P2P2_DN<21>")
	)
	(segment
		(start 315.80455 -310.864758)
		(end 316.17285 -310.864758)
		(width 0.14732)
		(layer "In11.Cu")
		(net "UPI_CPU1_CPU0_P2P2_DN<21>")
	)
	(segment
		(start 105.792016 -292.378384)
		(end 105.83418 -292.420548)
		(width 0.0889)
		(layer "In11.Cu")
		(net "UPI_CPU1_CPU0_P2P2_DN<21>")
	)
	(segment
		(start 266.82446 -331.379576)
		(end 266.97178 -331.232256)
		(width 0.14732)
		(layer "In11.Cu")
		(net "UPI_CPU1_CPU0_P2P2_DN<21>")
	)
	(segment
		(start 259.593842 -340.70671)
		(end 259.593842 -340.498938)
		(width 0.14732)
		(layer "In11.Cu")
		(net "UPI_CPU1_CPU0_P2P2_DN<21>")
	)
	(segment
		(start 266.97178 -331.232256)
		(end 266.97178 -330.642976)
		(width 0.14732)
		(layer "In11.Cu")
		(net "UPI_CPU1_CPU0_P2P2_DN<21>")
	)
	(segment
		(start 283.699712 -323.752464)
		(end 283.699712 -323.057774)
		(width 0.14732)
		(layer "In11.Cu")
		(net "UPI_CPU1_CPU0_P2P2_DN<21>")
	)
	(segment
		(start 334.935576 -288.478214)
		(end 335.255108 -288.478214)
		(width 0.0889)
		(layer "In11.Cu")
		(net "UPI_CPU1_CPU0_P2P2_DN<21>")
	)
	(arc
		(start 335.840578 -282.779216)
		(mid 335.849024 -282.772531)
		(end 335.857596 -282.766008)
		(width 0.0889)
		(layer "In11.Cu")
		(net "UPI_CPU1_CPU0_P2P2_DN<21>")
	)
	(arc
		(start 335.92135 -287.608518)
		(mid 336.052264 -287.472158)
		(end 336.099912 -287.28924)
		(width 0.0889)
		(layer "In11.Cu")
		(net "UPI_CPU1_CPU0_P2P2_DN<21>")
	)
	(arc
		(start 335.630012 -288.09315)
		(mid 335.708123 -287.816201)
		(end 335.91246 -287.613598)
		(width 0.0889)
		(layer "In11.Cu")
		(net "UPI_CPU1_CPU0_P2P2_DN<21>")
	)
	(arc
		(start 106.376724 -281.878532)
		(mid 106.624735 -281.84205)
		(end 106.86415 -281.916378)
		(width 0.0889)
		(layer "In11.Cu")
		(net "UPI_CPU1_CPU0_P2P2_DN<21>")
	)
	(arc
		(start 335.91246 -283.709364)
		(mid 335.708125 -283.506759)
		(end 335.630012 -283.229812)
		(width 0.0889)
		(layer "In11.Cu")
		(net "UPI_CPU1_CPU0_P2P2_DN<21>")
	)
	(arc
		(start 107.333796 -283.709364)
		(mid 107.198863 -283.842718)
		(end 107.146598 -284.025086)
		(width 0.0889)
		(layer "In11.Cu")
		(net "UPI_CPU1_CPU0_P2P2_DN<21>")
	)
	(arc
		(start 107.146344 -282.405836)
		(mid 107.194023 -282.588736)
		(end 107.324906 -282.725114)
		(width 0.0889)
		(layer "In11.Cu")
		(net "UPI_CPU1_CPU0_P2P2_DN<21>")
	)
	(arc
		(start 107.822238 -288.438844)
		(mid 108.026194 -288.66291)
		(end 108.085382 -288.960052)
		(width 0.0889)
		(layer "In11.Cu")
		(net "UPI_CPU1_CPU0_P2P2_DN<21>")
	)
	(arc
		(start 336.099912 -284.033722)
		(mid 336.052233 -283.850822)
		(end 335.92135 -283.714444)
		(width 0.0889)
		(layer "In11.Cu")
		(net "UPI_CPU1_CPU0_P2P2_DN<21>")
	)
	(arc
		(start 106.356912 -281.88666)
		(mid 106.366779 -281.882501)
		(end 106.376724 -281.878532)
		(width 0.0889)
		(layer "In11.Cu")
		(net "UPI_CPU1_CPU0_P2P2_DN<21>")
	)
	(arc
		(start 107.80395 -288.427414)
		(mid 107.813146 -288.432917)
		(end 107.822238 -288.43859)
		(width 0.0889)
		(layer "In11.Cu")
		(net "UPI_CPU1_CPU0_P2P2_DN<21>")
	)
	(arc
		(start 107.146598 -284.033722)
		(mid 107.072607 -284.313288)
		(end 106.869992 -284.519624)
		(width 0.0889)
		(layer "In11.Cu")
		(net "UPI_CPU1_CPU0_P2P2_DN<21>")
	)
	(arc
		(start 107.333796 -285.985712)
		(mid 107.616503 -286.468301)
		(end 107.345988 -286.95777)
		(width 0.0889)
		(layer "In11.Cu")
		(net "UPI_CPU1_CPU0_P2P2_DN<21>")
	)
	(arc
		(start 336.099912 -285.651448)
		(mid 336.178023 -285.374499)
		(end 336.38236 -285.171896)
		(width 0.0889)
		(layer "In11.Cu")
		(net "UPI_CPU1_CPU0_P2P2_DN<21>")
	)
	(arc
		(start 106.869992 -285.175452)
		(mid 107.072579 -285.381803)
		(end 107.146598 -285.661354)
		(width 0.0889)
		(layer "In11.Cu")
		(net "UPI_CPU1_CPU0_P2P2_DN<21>")
	)
	(arc
		(start 106.86415 -281.916378)
		(mid 107.066973 -282.116609)
		(end 107.146344 -282.390342)
		(width 0.0889)
		(layer "In11.Cu")
		(net "UPI_CPU1_CPU0_P2P2_DN<21>")
	)
	(arc
		(start 336.569812 -284.837378)
		(mid 336.519743 -284.660153)
		(end 336.39125 -284.52826)
		(width 0.0889)
		(layer "In11.Cu")
		(net "UPI_CPU1_CPU0_P2P2_DN<21>")
	)
	(arc
		(start 336.38236 -286.151066)
		(mid 336.180074 -285.952085)
		(end 336.099912 -285.679896)
		(width 0.0889)
		(layer "In11.Cu")
		(net "UPI_CPU1_CPU0_P2P2_DN<21>")
	)
	(arc
		(start 335.255108 -288.478214)
		(mid 335.352178 -288.465157)
		(end 335.44256 -288.427414)
		(width 0.0889)
		(layer "In11.Cu")
		(net "UPI_CPU1_CPU0_P2P2_DN<21>")
	)
	(arc
		(start 335.45145 -288.422334)
		(mid 335.582364 -288.285974)
		(end 335.630012 -288.103056)
		(width 0.0889)
		(layer "In11.Cu")
		(net "UPI_CPU1_CPU0_P2P2_DN<21>")
	)
	(arc
		(start 336.569812 -284.854142)
		(mid 336.569906 -284.84576)
		(end 336.569812 -284.837378)
		(width 0.0889)
		(layer "In11.Cu")
		(net "UPI_CPU1_CPU0_P2P2_DN<21>")
	)
	(arc
		(start 107.345988 -287.62071)
		(mid 107.544216 -287.826558)
		(end 107.616498 -288.103056)
		(width 0.0889)
		(layer "In11.Cu")
		(net "UPI_CPU1_CPU0_P2P2_DN<21>")
	)
	(arc
		(start 107.333796 -282.730194)
		(mid 107.616664 -283.216313)
		(end 107.339892 -283.705808)
		(width 0.0889)
		(layer "In11.Cu")
		(net "UPI_CPU1_CPU0_P2P2_DN<21>")
	)
	(arc
		(start 108.085382 -288.960052)
		(mid 108.052315 -289.140668)
		(end 107.951016 -289.293808)
		(width 0.0889)
		(layer "In11.Cu")
		(net "UPI_CPU1_CPU0_P2P2_DN<21>")
	)
	(arc
		(start 106.855006 -284.52826)
		(mid 106.676409 -284.847538)
		(end 106.855006 -285.166816)
		(width 0.0889)
		(layer "In11.Cu")
		(net "UPI_CPU1_CPU0_P2P2_DN<21>")
	)
	(arc
		(start 107.616498 -288.103056)
		(mid 107.664177 -288.285956)
		(end 107.79506 -288.422334)
		(width 0.0889)
		(layer "In11.Cu")
		(net "UPI_CPU1_CPU0_P2P2_DN<21>")
	)
	(arc
		(start 107.333796 -286.964882)
		(mid 107.146493 -287.28924)
		(end 107.333796 -287.613598)
		(width 0.0889)
		(layer "In11.Cu")
		(net "UPI_CPU1_CPU0_P2P2_DN<21>")
	)
	(arc
		(start 336.39125 -285.166816)
		(mid 336.520539 -285.03333)
		(end 336.569812 -284.854142)
		(width 0.0889)
		(layer "In11.Cu")
		(net "UPI_CPU1_CPU0_P2P2_DN<21>")
	)
	(arc
		(start 335.630012 -283.201364)
		(mid 335.689162 -282.967277)
		(end 335.840578 -282.779216)
		(width 0.0889)
		(layer "In11.Cu")
		(net "UPI_CPU1_CPU0_P2P2_DN<21>")
	)
	(arc
		(start 336.376264 -284.519624)
		(mid 336.173851 -284.313211)
		(end 336.099912 -284.033722)
		(width 0.0889)
		(layer "In11.Cu")
		(net "UPI_CPU1_CPU0_P2P2_DN<21>")
	)
	(arc
		(start 336.39125 -286.794702)
		(mid 336.569847 -286.475424)
		(end 336.39125 -286.156146)
		(width 0.0889)
		(layer "In11.Cu")
		(net "UPI_CPU1_CPU0_P2P2_DN<21>")
	)
	(arc
		(start 336.099912 -287.279334)
		(mid 336.178023 -287.002385)
		(end 336.38236 -286.799782)
		(width 0.0889)
		(layer "In11.Cu")
		(net "UPI_CPU1_CPU0_P2P2_DN<21>")
	)
	(arc
		(start 107.146598 -285.66999)
		(mid 107.198868 -285.852355)
		(end 107.333796 -285.985712)
		(width 0.0889)
		(layer "In11.Cu")
		(net "UPI_CPU1_CPU0_P2P2_DN<21>")
	)
	(segment
		(start 105.171748 -279.428448)
		(end 105.171748 -279.964134)
		(width 0.13208)
		(layer "F.Cu")
		(net "UPI_CPU1_CPU0_P2P2_DN<20>")
	)
	(segment
		(start 105.171494 -279.428194)
		(end 105.171748 -279.428448)
		(width 0.13208)
		(layer "F.Cu")
		(net "UPI_CPU1_CPU0_P2P2_DN<20>")
	)
	(segment
		(start 337.134962 -279.428194)
		(end 337.134962 -279.964134)
		(width 0.13208)
		(layer "F.Cu")
		(net "UPI_CPU1_CPU0_P2P2_DN<20>")
	)
	(segment
		(start 336.099912 -282.42006)
		(end 336.099912 -282.405836)
		(width 0.0889)
		(layer "In11.Cu")
		(net "UPI_CPU1_CPU0_P2P2_DN<20>")
	)
	(segment
		(start 264.002266 -332.207616)
		(end 264.437622 -332.207616)
		(width 0.14732)
		(layer "In11.Cu")
		(net "UPI_CPU1_CPU0_P2P2_DN<20>")
	)
	(segment
		(start 104.51465 -288.592768)
		(end 104.50576 -288.597848)
		(width 0.0889)
		(layer "In11.Cu")
		(net "UPI_CPU1_CPU0_P2P2_DN<20>")
	)
	(segment
		(start 337.321652 -286.80029)
		(end 337.322414 -286.799782)
		(width 0.0889)
		(layer "In11.Cu")
		(net "UPI_CPU1_CPU0_P2P2_DN<20>")
	)
	(segment
		(start 105.266998 -287.28924)
		(end 105.266998 -287.299146)
		(width 0.0889)
		(layer "In11.Cu")
		(net "UPI_CPU1_CPU0_P2P2_DN<20>")
	)
	(segment
		(start 259.583682 -342.324944)
		(end 260.634226 -343.375488)
		(width 0.14732)
		(layer "In11.Cu")
		(net "UPI_CPU1_CPU0_P2P2_DN<20>")
	)
	(segment
		(start 278.367998 -324.763384)
		(end 283.889196 -324.763384)
		(width 0.14732)
		(layer "In11.Cu")
		(net "UPI_CPU1_CPU0_P2P2_DN<20>")
	)
	(segment
		(start 266.747244 -334.517238)
		(end 266.955524 -334.517238)
		(width 0.14732)
		(layer "In11.Cu")
		(net "UPI_CPU1_CPU0_P2P2_DN<20>")
	)
	(segment
		(start 337.039712 -284.043628)
		(end 337.039712 -284.025086)
		(width 0.0889)
		(layer "In11.Cu")
		(net "UPI_CPU1_CPU0_P2P2_DN<20>")
	)
	(segment
		(start 106.206544 -282.390342)
		(end 106.206544 -282.405836)
		(width 0.0889)
		(layer "In11.Cu")
		(net "UPI_CPU1_CPU0_P2P2_DN<20>")
	)
	(segment
		(start 329.621134 -299.61713)
		(end 331.57033 -293.192708)
		(width 0.14732)
		(layer "In11.Cu")
		(net "UPI_CPU1_CPU0_P2P2_DN<20>")
	)
	(segment
		(start 336.569812 -288.103056)
		(end 336.569812 -288.09315)
		(width 0.0889)
		(layer "In11.Cu")
		(net "UPI_CPU1_CPU0_P2P2_DN<20>")
	)
	(segment
		(start 104.796844 -289.623754)
		(end 104.796844 -291.432234)
		(width 0.0889)
		(layer "In11.Cu")
		(net "UPI_CPU1_CPU0_P2P2_DN<20>")
	)
	(segment
		(start 106.385106 -282.725114)
		(end 106.393996 -282.730194)
		(width 0.0889)
		(layer "In11.Cu")
		(net "UPI_CPU1_CPU0_P2P2_DN<20>")
	)
	(segment
		(start 268.943836 -330.124562)
		(end 270.041878 -331.222604)
		(width 0.14732)
		(layer "In11.Cu")
		(net "UPI_CPU1_CPU0_P2P2_DN<20>")
	)
	(segment
		(start 106.676698 -283.212286)
		(end 106.676698 -283.219906)
		(width 0.0889)
		(layer "In11.Cu")
		(net "UPI_CPU1_CPU0_P2P2_DN<20>")
	)
	(segment
		(start 265.108436 -336.156046)
		(end 265.316716 -336.156046)
		(width 0.14732)
		(layer "In11.Cu")
		(net "UPI_CPU1_CPU0_P2P2_DN<20>")
	)
	(segment
		(start 312.18505 -313.524646)
		(end 313.170316 -312.53938)
		(width 0.14732)
		(layer "In11.Cu")
		(net "UPI_CPU1_CPU0_P2P2_DN<20>")
	)
	(segment
		(start 260.841998 -343.375488)
		(end 261.259828 -342.957658)
		(width 0.14732)
		(layer "In11.Cu")
		(net "UPI_CPU1_CPU0_P2P2_DN<20>")
	)
	(segment
		(start 335.683352 -289.640518)
		(end 335.683352 -289.500056)
		(width 0.0889)
		(layer "In11.Cu")
		(net "UPI_CPU1_CPU0_P2P2_DN<20>")
	)
	(segment
		(start 105.454196 -281.102562)
		(end 105.45572 -281.103578)
		(width 0.0889)
		(layer "In11.Cu")
		(net "UPI_CPU1_CPU0_P2P2_DN<20>")
	)
	(segment
		(start 98.851466 -304.917094)
		(end 82.907378 -318.002412)
		(width 0.14732)
		(layer "In11.Cu")
		(net "UPI_CPU1_CPU0_P2P2_DN<20>")
	)
	(segment
		(start 336.371946 -288.434018)
		(end 336.383376 -288.42716)
		(width 0.0889)
		(layer "In11.Cu")
		(net "UPI_CPU1_CPU0_P2P2_DN<20>")
	)
	(segment
		(start 263.423908 -333.22133)
		(end 263.423908 -332.785974)
		(width 0.14732)
		(layer "In11.Cu")
		(net "UPI_CPU1_CPU0_P2P2_DN<20>")
	)
	(segment
		(start 336.383376 -288.42716)
		(end 336.383122 -288.426906)
		(width 0.0889)
		(layer "In11.Cu")
		(net "UPI_CPU1_CPU0_P2P2_DN<20>")
	)
	(segment
		(start 305.598068 -315.976508)
		(end 306.024026 -315.672216)
		(width 0.14732)
		(layer "In11.Cu")
		(net "UPI_CPU1_CPU0_P2P2_DN<20>")
	)
	(segment
		(start 126.272036 -375.73839)
		(end 160.828228 -375.73839)
		(width 0.14732)
		(layer "In11.Cu")
		(net "UPI_CPU1_CPU0_P2P2_DN<20>")
	)
	(segment
		(start 260.633464 -336.550762)
		(end 261.211822 -335.972404)
		(width 0.14732)
		(layer "In11.Cu")
		(net "UPI_CPU1_CPU0_P2P2_DN<20>")
	)
	(segment
		(start 267.93063 -330.70292)
		(end 268.509242 -330.124308)
		(width 0.14732)
		(layer "In11.Cu")
		(net "UPI_CPU1_CPU0_P2P2_DN<20>")
	)
	(segment
		(start 336.099912 -289.223958)
		(end 336.099912 -288.917126)
		(width 0.0889)
		(layer "In11.Cu")
		(net "UPI_CPU1_CPU0_P2P2_DN<20>")
	)
	(segment
		(start 262.898636 -341.111078)
		(end 261.848092 -340.060534)
		(width 0.14732)
		(layer "In11.Cu")
		(net "UPI_CPU1_CPU0_P2P2_DN<20>")
	)
	(segment
		(start 262.272272 -334.911954)
		(end 262.85063 -334.333596)
		(width 0.14732)
		(layer "In11.Cu")
		(net "UPI_CPU1_CPU0_P2P2_DN<20>")
	)
	(segment
		(start 73.377298 -352.822256)
		(end 76.825856 -361.139486)
		(width 0.14732)
		(layer "In11.Cu")
		(net "UPI_CPU1_CPU0_P2P2_DN<20>")
	)
	(segment
		(start 336.39125 -282.900628)
		(end 336.38236 -282.895548)
		(width 0.0889)
		(layer "In11.Cu")
		(net "UPI_CPU1_CPU0_P2P2_DN<20>")
	)
	(segment
		(start 306.024026 -315.672216)
		(end 306.887626 -315.19749)
		(width 0.14732)
		(layer "In11.Cu")
		(net "UPI_CPU1_CPU0_P2P2_DN<20>")
	)
	(segment
		(start 277.687278 -325.444104)
		(end 278.367998 -324.763384)
		(width 0.14732)
		(layer "In11.Cu")
		(net "UPI_CPU1_CPU0_P2P2_DN<20>")
	)
	(segment
		(start 305.062636 -316.359286)
		(end 305.096418 -316.157102)
		(width 0.14732)
		(layer "In11.Cu")
		(net "UPI_CPU1_CPU0_P2P2_DN<20>")
	)
	(segment
		(start 105.266744 -280.756106)
		(end 105.266744 -280.778204)
		(width 0.0889)
		(layer "In11.Cu")
		(net "UPI_CPU1_CPU0_P2P2_DN<20>")
	)
	(segment
		(start 304.39741 -316.834774)
		(end 305.062636 -316.359286)
		(width 0.14732)
		(layer "In11.Cu")
		(net "UPI_CPU1_CPU0_P2P2_DN<20>")
	)
	(segment
		(start 337.447636 -279.964134)
		(end 337.134962 -279.964134)
		(width 0.0889)
		(layer "In11.Cu")
		(net "UPI_CPU1_CPU0_P2P2_DN<20>")
	)
	(segment
		(start 335.683352 -289.500056)
		(end 335.809082 -289.374326)
		(width 0.0889)
		(layer "In11.Cu")
		(net "UPI_CPU1_CPU0_P2P2_DN<20>")
	)
	(segment
		(start 311.598564 -313.76747)
		(end 312.18505 -313.524646)
		(width 0.14732)
		(layer "In11.Cu")
		(net "UPI_CPU1_CPU0_P2P2_DN<20>")
	)
	(segment
		(start 256.892044 -344.580718)
		(end 259.147818 -342.324944)
		(width 0.14732)
		(layer "In11.Cu")
		(net "UPI_CPU1_CPU0_P2P2_DN<20>")
	)
	(segment
		(start 104.796844 -291.432234)
		(end 104.839008 -291.474398)
		(width 0.0889)
		(layer "In11.Cu")
		(net "UPI_CPU1_CPU0_P2P2_DN<20>")
	)
	(segment
		(start 104.839008 -291.496496)
		(end 104.839008 -292.480492)
		(width 0.14732)
		(layer "In11.Cu")
		(net "UPI_CPU1_CPU0_P2P2_DN<20>")
	)
	(segment
		(start 105.452672 -281.1018)
		(end 105.454196 -281.102562)
		(width 0.0889)
		(layer "In11.Cu")
		(net "UPI_CPU1_CPU0_P2P2_DN<20>")
	)
	(segment
		(start 104.839008 -292.480492)
		(end 105.00614 -292.647624)
		(width 0.14732)
		(layer "In11.Cu")
		(net "UPI_CPU1_CPU0_P2P2_DN<20>")
	)
	(segment
		(start 316.40399 -312.179208)
		(end 317.05931 -312.179208)
		(width 0.14732)
		(layer "In11.Cu")
		(net "UPI_CPU1_CPU0_P2P2_DN<20>")
	)
	(segment
		(start 313.170316 -312.53938)
		(end 314.040012 -312.179208)
		(width 0.14732)
		(layer "In11.Cu")
		(net "UPI_CPU1_CPU0_P2P2_DN<20>")
	)
	(segment
		(start 104.839008 -291.474398)
		(end 104.839008 -291.496496)
		(width 0.0889)
		(layer "In11.Cu")
		(net "UPI_CPU1_CPU0_P2P2_DN<20>")
	)
	(segment
		(start 212.312504 -371.027706)
		(end 229.059232 -368.07521)
		(width 0.14732)
		(layer "In11.Cu")
		(net "UPI_CPU1_CPU0_P2P2_DN<20>")
	)
	(segment
		(start 259.147818 -342.324944)
		(end 259.583682 -342.324944)
		(width 0.14732)
		(layer "In11.Cu")
		(net "UPI_CPU1_CPU0_P2P2_DN<20>")
	)
	(segment
		(start 277.687278 -327.490328)
		(end 277.687278 -325.444104)
		(width 0.14732)
		(layer "In11.Cu")
		(net "UPI_CPU1_CPU0_P2P2_DN<20>")
	)
	(segment
		(start 261.259828 -342.957658)
		(end 261.259828 -342.749886)
		(width 0.14732)
		(layer "In11.Cu")
		(net "UPI_CPU1_CPU0_P2P2_DN<20>")
	)
	(segment
		(start 199.930258 -368.844322)
		(end 212.312504 -371.027706)
		(width 0.14732)
		(layer "In11.Cu")
		(net "UPI_CPU1_CPU0_P2P2_DN<20>")
	)
	(segment
		(start 299.096684 -323.934074)
		(end 300.795944 -323.229478)
		(width 0.14732)
		(layer "In11.Cu")
		(net "UPI_CPU1_CPU0_P2P2_DN<20>")
	)
	(segment
		(start 308.48935 -314.401708)
		(end 308.63413 -314.256928)
		(width 0.14732)
		(layer "In11.Cu")
		(net "UPI_CPU1_CPU0_P2P2_DN<20>")
	)
	(segment
		(start 264.437622 -332.207616)
		(end 266.747244 -334.517238)
		(width 0.14732)
		(layer "In11.Cu")
		(net "UPI_CPU1_CPU0_P2P2_DN<20>")
	)
	(segment
		(start 262.455914 -338.808568)
		(end 260.633464 -336.986118)
		(width 0.14732)
		(layer "In11.Cu")
		(net "UPI_CPU1_CPU0_P2P2_DN<20>")
	)
	(segment
		(start 74.512932 -327.223628)
		(end 73.971658 -329.181714)
		(width 0.14732)
		(layer "In11.Cu")
		(net "UPI_CPU1_CPU0_P2P2_DN<20>")
	)
	(segment
		(start 336.38236 -281.916378)
		(end 336.39125 -281.911298)
		(width 0.0889)
		(layer "In11.Cu")
		(net "UPI_CPU1_CPU0_P2P2_DN<20>")
	)
	(segment
		(start 310.990488 -314.019692)
		(end 311.068974 -313.830208)
		(width 0.14732)
		(layer "In11.Cu")
		(net "UPI_CPU1_CPU0_P2P2_DN<20>")
	)
	(segment
		(start 265.316716 -336.156046)
		(end 265.73353 -335.739232)
		(width 0.14732)
		(layer "In11.Cu")
		(net "UPI_CPU1_CPU0_P2P2_DN<20>")
	)
	(segment
		(start 337.50504 -280.021538)
		(end 337.447636 -279.964134)
		(width 0.0889)
		(layer "In11.Cu")
		(net "UPI_CPU1_CPU0_P2P2_DN<20>")
	)
	(segment
		(start 331.57033 -293.192708)
		(end 332.035404 -292.495986)
		(width 0.14732)
		(layer "In11.Cu")
		(net "UPI_CPU1_CPU0_P2P2_DN<20>")
	)
	(segment
		(start 265.73353 -335.530952)
		(end 263.423908 -333.22133)
		(width 0.14732)
		(layer "In11.Cu")
		(net "UPI_CPU1_CPU0_P2P2_DN<20>")
	)
	(segment
		(start 105.44556 -285.980632)
		(end 105.45445 -285.985712)
		(width 0.0889)
		(layer "In11.Cu")
		(net "UPI_CPU1_CPU0_P2P2_DN<20>")
	)
	(segment
		(start 105.45445 -286.964882)
		(end 105.44556 -286.969962)
		(width 0.0889)
		(layer "In11.Cu")
		(net "UPI_CPU1_CPU0_P2P2_DN<20>")
	)
	(segment
		(start 261.848092 -340.060534)
		(end 261.848092 -339.62467)
		(width 0.14732)
		(layer "In11.Cu")
		(net "UPI_CPU1_CPU0_P2P2_DN<20>")
	)
	(segment
		(start 264.094722 -337.37804)
		(end 264.094722 -337.16976)
		(width 0.14732)
		(layer "In11.Cu")
		(net "UPI_CPU1_CPU0_P2P2_DN<20>")
	)
	(segment
		(start 335.949544 -289.374326)
		(end 336.099912 -289.223958)
		(width 0.0889)
		(layer "In11.Cu")
		(net "UPI_CPU1_CPU0_P2P2_DN<20>")
	)
	(segment
		(start 105.015284 -280.235152)
		(end 105.039414 -280.324306)
		(width 0.0889)
		(layer "In11.Cu")
		(net "UPI_CPU1_CPU0_P2P2_DN<20>")
	)
	(segment
		(start 315.37783 -312.179208)
		(end 315.74613 -312.179208)
		(width 0.14732)
		(layer "In11.Cu")
		(net "UPI_CPU1_CPU0_P2P2_DN<20>")
	)
	(segment
		(start 332.035404 -292.495986)
		(end 333.676244 -290.855146)
		(width 0.14732)
		(layer "In11.Cu")
		(net "UPI_CPU1_CPU0_P2P2_DN<20>")
	)
	(segment
		(start 264.094722 -337.16976)
		(end 262.272272 -335.34731)
		(width 0.14732)
		(layer "In11.Cu")
		(net "UPI_CPU1_CPU0_P2P2_DN<20>")
	)
	(segment
		(start 256.770124 -346.456508)
		(end 256.770124 -346.019628)
		(width 0.14732)
		(layer "In11.Cu")
		(net "UPI_CPU1_CPU0_P2P2_DN<20>")
	)
	(segment
		(start 337.32216 -285.171896)
		(end 337.33105 -285.166816)
		(width 0.0889)
		(layer "In11.Cu")
		(net "UPI_CPU1_CPU0_P2P2_DN<20>")
	)
	(segment
		(start 268.845284 -335.16443)
		(end 269.053056 -335.16443)
		(width 0.14732)
		(layer "In11.Cu")
		(net "UPI_CPU1_CPU0_P2P2_DN<20>")
	)
	(segment
		(start 261.211822 -335.972404)
		(end 261.647178 -335.972404)
		(width 0.14732)
		(layer "In11.Cu")
		(net "UPI_CPU1_CPU0_P2P2_DN<20>")
	)
	(segment
		(start 99.19208 -371.719856)
		(end 126.272036 -375.73839)
		(width 0.14732)
		(layer "In11.Cu")
		(net "UPI_CPU1_CPU0_P2P2_DN<20>")
	)
	(segment
		(start 315.74613 -312.179208)
		(end 315.89091 -312.034428)
		(width 0.14732)
		(layer "In11.Cu")
		(net "UPI_CPU1_CPU0_P2P2_DN<20>")
	)
	(segment
		(start 309.00243 -314.256928)
		(end 309.14721 -314.401708)
		(width 0.14732)
		(layer "In11.Cu")
		(net "UPI_CPU1_CPU0_P2P2_DN<20>")
	)
	(segment
		(start 261.22249 -340.686136)
		(end 262.273034 -341.73668)
		(width 0.14732)
		(layer "In11.Cu")
		(net "UPI_CPU1_CPU0_P2P2_DN<20>")
	)
	(segment
		(start 263.677908 -337.794854)
		(end 264.094722 -337.37804)
		(width 0.14732)
		(layer "In11.Cu")
		(net "UPI_CPU1_CPU0_P2P2_DN<20>")
	)
	(segment
		(start 314.86475 -312.034428)
		(end 315.23305 -312.034428)
		(width 0.14732)
		(layer "In11.Cu")
		(net "UPI_CPU1_CPU0_P2P2_DN<20>")
	)
	(segment
		(start 256.770124 -346.019628)
		(end 256.892044 -345.897708)
		(width 0.14732)
		(layer "In11.Cu")
		(net "UPI_CPU1_CPU0_P2P2_DN<20>")
	)
	(segment
		(start 335.29524 -289.969702)
		(end 335.354168 -289.969702)
		(width 0.0889)
		(layer "In11.Cu")
		(net "UPI_CPU1_CPU0_P2P2_DN<20>")
	)
	(segment
		(start 262.272272 -335.34731)
		(end 262.272272 -334.911954)
		(width 0.14732)
		(layer "In11.Cu")
		(net "UPI_CPU1_CPU0_P2P2_DN<20>")
	)
	(segment
		(start 253.316486 -351.087182)
		(end 256.892044 -347.511624)
		(width 0.14732)
		(layer "In11.Cu")
		(net "UPI_CPU1_CPU0_P2P2_DN<20>")
	)
	(segment
		(start 260.634226 -343.375488)
		(end 260.841998 -343.375488)
		(width 0.14732)
		(layer "In11.Cu")
		(net "UPI_CPU1_CPU0_P2P2_DN<20>")
	)
	(segment
		(start 268.509242 -330.124308)
		(end 268.943836 -330.124562)
		(width 0.14732)
		(layer "In11.Cu")
		(net "UPI_CPU1_CPU0_P2P2_DN<20>")
	)
	(segment
		(start 275.254974 -329.922632)
		(end 277.687278 -327.490328)
		(width 0.14732)
		(layer "In11.Cu")
		(net "UPI_CPU1_CPU0_P2P2_DN<20>")
	)
	(segment
		(start 105.453434 -285.337504)
		(end 105.44556 -285.342076)
		(width 0.0889)
		(layer "In11.Cu")
		(net "UPI_CPU1_CPU0_P2P2_DN<20>")
	)
	(segment
		(start 315.89091 -312.034428)
		(end 316.25921 -312.034428)
		(width 0.14732)
		(layer "In11.Cu")
		(net "UPI_CPU1_CPU0_P2P2_DN<20>")
	)
	(segment
		(start 261.259828 -342.749886)
		(end 260.209284 -341.699342)
		(width 0.14732)
		(layer "In11.Cu")
		(net "UPI_CPU1_CPU0_P2P2_DN<20>")
	)
	(segment
		(start 260.209284 -341.263478)
		(end 260.786626 -340.686136)
		(width 0.14732)
		(layer "In11.Cu")
		(net "UPI_CPU1_CPU0_P2P2_DN<20>")
	)
	(segment
		(start 263.469628 -337.794854)
		(end 263.677908 -337.794854)
		(width 0.14732)
		(layer "In11.Cu")
		(net "UPI_CPU1_CPU0_P2P2_DN<20>")
	)
	(segment
		(start 262.898636 -341.31885)
		(end 262.898636 -341.111078)
		(width 0.14732)
		(layer "In11.Cu")
		(net "UPI_CPU1_CPU0_P2P2_DN<20>")
	)
	(segment
		(start 337.318858 -286.801814)
		(end 337.321652 -286.80029)
		(width 0.0889)
		(layer "In11.Cu")
		(net "UPI_CPU1_CPU0_P2P2_DN<20>")
	)
	(segment
		(start 306.887626 -315.19749)
		(end 307.683408 -314.401708)
		(width 0.14732)
		(layer "In11.Cu")
		(net "UPI_CPU1_CPU0_P2P2_DN<20>")
	)
	(segment
		(start 303.743106 -317.43015)
		(end 304.39741 -316.834774)
		(width 0.14732)
		(layer "In11.Cu")
		(net "UPI_CPU1_CPU0_P2P2_DN<20>")
	)
	(segment
		(start 303.426622 -318.961516)
		(end 303.565814 -317.775336)
		(width 0.14732)
		(layer "In11.Cu")
		(net "UPI_CPU1_CPU0_P2P2_DN<20>")
	)
	(segment
		(start 314.040012 -312.179208)
		(end 314.71997 -312.179208)
		(width 0.14732)
		(layer "In11.Cu")
		(net "UPI_CPU1_CPU0_P2P2_DN<20>")
	)
	(segment
		(start 75.255882 -325.654162)
		(end 74.512932 -327.223628)
		(width 0.14732)
		(layer "In11.Cu")
		(net "UPI_CPU1_CPU0_P2P2_DN<20>")
	)
	(segment
		(start 256.892044 -346.578428)
		(end 256.770124 -346.456508)
		(width 0.14732)
		(layer "In11.Cu")
		(net "UPI_CPU1_CPU0_P2P2_DN<20>")
	)
	(segment
		(start 105.736898 -286.456882)
		(end 105.736898 -286.48533)
		(width 0.0889)
		(layer "In11.Cu")
		(net "UPI_CPU1_CPU0_P2P2_DN<20>")
	)
	(segment
		(start 305.396138 -315.94298)
		(end 305.598068 -315.976508)
		(width 0.14732)
		(layer "In11.Cu")
		(net "UPI_CPU1_CPU0_P2P2_DN<20>")
	)
	(segment
		(start 160.828228 -375.73839)
		(end 199.930258 -368.844322)
		(width 0.14732)
		(layer "In11.Cu")
		(net "UPI_CPU1_CPU0_P2P2_DN<20>")
	)
	(segment
		(start 266.955524 -334.517238)
		(end 267.358876 -334.113886)
		(width 0.14732)
		(layer "In11.Cu")
		(net "UPI_CPU1_CPU0_P2P2_DN<20>")
	)
	(segment
		(start 229.059232 -368.07521)
		(end 253.316486 -351.087182)
		(width 0.14732)
		(layer "In11.Cu")
		(net "UPI_CPU1_CPU0_P2P2_DN<20>")
	)
	(segment
		(start 311.068974 -313.830208)
		(end 311.409334 -313.689238)
		(width 0.14732)
		(layer "In11.Cu")
		(net "UPI_CPU1_CPU0_P2P2_DN<20>")
	)
	(segment
		(start 268.420342 -333.488284)
		(end 268.420342 -333.05242)
		(width 0.14732)
		(layer "In11.Cu")
		(net "UPI_CPU1_CPU0_P2P2_DN<20>")
	)
	(segment
		(start 262.480806 -341.73668)
		(end 262.898636 -341.31885)
		(width 0.14732)
		(layer "In11.Cu")
		(net "UPI_CPU1_CPU0_P2P2_DN<20>")
	)
	(segment
		(start 303.565814 -317.775336)
		(end 303.743106 -317.43015)
		(width 0.14732)
		(layer "In11.Cu")
		(net "UPI_CPU1_CPU0_P2P2_DN<20>")
	)
	(segment
		(start 337.32216 -280.288492)
		(end 337.33105 -280.283412)
		(width 0.0889)
		(layer "In11.Cu")
		(net "UPI_CPU1_CPU0_P2P2_DN<20>")
	)
	(segment
		(start 104.98455 -287.778698)
		(end 104.97566 -287.783778)
		(width 0.0889)
		(layer "In11.Cu")
		(net "UPI_CPU1_CPU0_P2P2_DN<20>")
	)
	(segment
		(start 333.676244 -290.855146)
		(end 334.929226 -290.335716)
		(width 0.14732)
		(layer "In11.Cu")
		(net "UPI_CPU1_CPU0_P2P2_DN<20>")
	)
	(segment
		(start 302.401732 -321.623944)
		(end 303.426622 -318.961516)
		(width 0.14732)
		(layer "In11.Cu")
		(net "UPI_CPU1_CPU0_P2P2_DN<20>")
	)
	(segment
		(start 300.795944 -323.229478)
		(end 302.401732 -321.623944)
		(width 0.14732)
		(layer "In11.Cu")
		(net "UPI_CPU1_CPU0_P2P2_DN<20>")
	)
	(segment
		(start 262.273034 -341.73668)
		(end 262.480806 -341.73668)
		(width 0.14732)
		(layer "In11.Cu")
		(net "UPI_CPU1_CPU0_P2P2_DN<20>")
	)
	(segment
		(start 105.171748 -279.964134)
		(end 105.015284 -280.235152)
		(width 0.0889)
		(layer "In11.Cu")
		(net "UPI_CPU1_CPU0_P2P2_DN<20>")
	)
	(segment
		(start 261.647178 -335.972404)
		(end 263.469628 -337.794854)
		(width 0.14732)
		(layer "In11.Cu")
		(net "UPI_CPU1_CPU0_P2P2_DN<20>")
	)
	(segment
		(start 270.041878 -331.222604)
		(end 270.250158 -331.222604)
		(width 0.14732)
		(layer "In11.Cu")
		(net "UPI_CPU1_CPU0_P2P2_DN<20>")
	)
	(segment
		(start 336.846164 -281.106118)
		(end 336.85226 -281.102562)
		(width 0.0889)
		(layer "In11.Cu")
		(net "UPI_CPU1_CPU0_P2P2_DN<20>")
	)
	(segment
		(start 337.509612 -286.48406)
		(end 337.509612 -286.466788)
		(width 0.0889)
		(layer "In11.Cu")
		(net "UPI_CPU1_CPU0_P2P2_DN<20>")
	)
	(segment
		(start 336.85226 -287.613598)
		(end 336.86115 -287.608518)
		(width 0.0889)
		(layer "In11.Cu")
		(net "UPI_CPU1_CPU0_P2P2_DN<20>")
	)
	(segment
		(start 256.892044 -345.897708)
		(end 256.892044 -344.580718)
		(width 0.14732)
		(layer "In11.Cu")
		(net "UPI_CPU1_CPU0_P2P2_DN<20>")
	)
	(segment
		(start 104.327198 -288.917126)
		(end 104.327198 -289.078416)
		(width 0.0889)
		(layer "In11.Cu")
		(net "UPI_CPU1_CPU0_P2P2_DN<20>")
	)
	(segment
		(start 336.851752 -283.708856)
		(end 336.846418 -283.705808)
		(width 0.0889)
		(layer "In11.Cu")
		(net "UPI_CPU1_CPU0_P2P2_DN<20>")
	)
	(segment
		(start 283.889196 -324.763384)
		(end 284.718506 -323.934074)
		(width 0.14732)
		(layer "In11.Cu")
		(net "UPI_CPU1_CPU0_P2P2_DN<20>")
	)
	(segment
		(start 269.470886 -334.538828)
		(end 268.420342 -333.488284)
		(width 0.14732)
		(layer "In11.Cu")
		(net "UPI_CPU1_CPU0_P2P2_DN<20>")
	)
	(segment
		(start 104.797098 -288.103056)
		(end 104.797098 -288.121598)
		(width 0.0889)
		(layer "In11.Cu")
		(net "UPI_CPU1_CPU0_P2P2_DN<20>")
	)
	(segment
		(start 308.63413 -314.256928)
		(end 309.00243 -314.256928)
		(width 0.14732)
		(layer "In11.Cu")
		(net "UPI_CPU1_CPU0_P2P2_DN<20>")
	)
	(segment
		(start 269.028164 -332.236318)
		(end 267.930376 -331.13853)
		(width 0.14732)
		(layer "In11.Cu")
		(net "UPI_CPU1_CPU0_P2P2_DN<20>")
	)
	(segment
		(start 267.930376 -331.13853)
		(end 267.93063 -330.70292)
		(width 0.14732)
		(layer "In11.Cu")
		(net "UPI_CPU1_CPU0_P2P2_DN<20>")
	)
	(segment
		(start 317.05931 -312.179208)
		(end 329.621134 -299.61713)
		(width 0.14732)
		(layer "In11.Cu")
		(net "UPI_CPU1_CPU0_P2P2_DN<20>")
	)
	(segment
		(start 105.736644 -284.847538)
		(end 105.736644 -284.863032)
		(width 0.0889)
		(layer "In11.Cu")
		(net "UPI_CPU1_CPU0_P2P2_DN<20>")
	)
	(segment
		(start 82.907378 -318.002412)
		(end 75.255882 -325.654162)
		(width 0.14732)
		(layer "In11.Cu")
		(net "UPI_CPU1_CPU0_P2P2_DN<20>")
	)
	(segment
		(start 337.316318 -286.803338)
		(end 337.318858 -286.801814)
		(width 0.0889)
		(layer "In11.Cu")
		(net "UPI_CPU1_CPU0_P2P2_DN<20>")
	)
	(segment
		(start 103.28021 -299.65396)
		(end 98.851466 -304.917094)
		(width 0.14732)
		(layer "In11.Cu")
		(net "UPI_CPU1_CPU0_P2P2_DN<20>")
	)
	(segment
		(start 105.936288 -284.516068)
		(end 105.924096 -284.52318)
		(width 0.0889)
		(layer "In11.Cu")
		(net "UPI_CPU1_CPU0_P2P2_DN<20>")
	)
	(segment
		(start 105.924096 -284.52318)
		(end 105.915206 -284.52826)
		(width 0.0889)
		(layer "In11.Cu")
		(net "UPI_CPU1_CPU0_P2P2_DN<20>")
	)
	(segment
		(start 105.00614 -292.647624)
		(end 105.00614 -297.326812)
		(width 0.14732)
		(layer "In11.Cu")
		(net "UPI_CPU1_CPU0_P2P2_DN<20>")
	)
	(segment
		(start 79.073248 -363.38637)
		(end 99.19208 -371.719856)
		(width 0.14732)
		(layer "In11.Cu")
		(net "UPI_CPU1_CPU0_P2P2_DN<20>")
	)
	(segment
		(start 262.455914 -339.016848)
		(end 262.455914 -338.808568)
		(width 0.14732)
		(layer "In11.Cu")
		(net "UPI_CPU1_CPU0_P2P2_DN<20>")
	)
	(segment
		(start 260.786626 -340.686136)
		(end 261.22249 -340.686136)
		(width 0.14732)
		(layer "In11.Cu")
		(net "UPI_CPU1_CPU0_P2P2_DN<20>")
	)
	(segment
		(start 269.470886 -334.7466)
		(end 269.470886 -334.538828)
		(width 0.14732)
		(layer "In11.Cu")
		(net "UPI_CPU1_CPU0_P2P2_DN<20>")
	)
	(segment
		(start 335.354168 -289.969702)
		(end 335.683352 -289.640518)
		(width 0.0889)
		(layer "In11.Cu")
		(net "UPI_CPU1_CPU0_P2P2_DN<20>")
	)
	(segment
		(start 104.775762 -289.602418)
		(end 104.796844 -289.623754)
		(width 0.0889)
		(layer "In11.Cu")
		(net "UPI_CPU1_CPU0_P2P2_DN<20>")
	)
	(segment
		(start 269.053056 -335.16443)
		(end 269.470886 -334.7466)
		(width 0.14732)
		(layer "In11.Cu")
		(net "UPI_CPU1_CPU0_P2P2_DN<20>")
	)
	(segment
		(start 106.39425 -283.709364)
		(end 106.38536 -283.714444)
		(width 0.0889)
		(layer "In11.Cu")
		(net "UPI_CPU1_CPU0_P2P2_DN<20>")
	)
	(segment
		(start 310.068468 -314.401708)
		(end 310.990488 -314.019692)
		(width 0.14732)
		(layer "In11.Cu")
		(net "UPI_CPU1_CPU0_P2P2_DN<20>")
	)
	(segment
		(start 267.79474 -334.113886)
		(end 268.845284 -335.16443)
		(width 0.14732)
		(layer "In11.Cu")
		(net "UPI_CPU1_CPU0_P2P2_DN<20>")
	)
	(segment
		(start 105.91546 -281.911298)
		(end 105.92435 -281.916378)
		(width 0.0889)
		(layer "In11.Cu")
		(net "UPI_CPU1_CPU0_P2P2_DN<20>")
	)
	(segment
		(start 315.23305 -312.034428)
		(end 315.37783 -312.179208)
		(width 0.14732)
		(layer "In11.Cu")
		(net "UPI_CPU1_CPU0_P2P2_DN<20>")
	)
	(segment
		(start 336.376264 -281.919934)
		(end 336.38236 -281.916378)
		(width 0.0889)
		(layer "In11.Cu")
		(net "UPI_CPU1_CPU0_P2P2_DN<20>")
	)
	(segment
		(start 337.039712 -280.778204)
		(end 337.039712 -280.759662)
		(width 0.0889)
		(layer "In11.Cu")
		(net "UPI_CPU1_CPU0_P2P2_DN<20>")
	)
	(segment
		(start 105.45699 -281.10434)
		(end 105.460292 -281.106118)
		(width 0.0889)
		(layer "In11.Cu")
		(net "UPI_CPU1_CPU0_P2P2_DN<20>")
	)
	(segment
		(start 335.809082 -289.374326)
		(end 335.949544 -289.374326)
		(width 0.0889)
		(layer "In11.Cu")
		(net "UPI_CPU1_CPU0_P2P2_DN<20>")
	)
	(segment
		(start 336.852514 -283.709364)
		(end 336.851752 -283.708856)
		(width 0.0889)
		(layer "In11.Cu")
		(net "UPI_CPU1_CPU0_P2P2_DN<20>")
	)
	(segment
		(start 309.14721 -314.401708)
		(end 310.068468 -314.401708)
		(width 0.14732)
		(layer "In11.Cu")
		(net "UPI_CPU1_CPU0_P2P2_DN<20>")
	)
	(segment
		(start 336.85226 -281.102562)
		(end 336.86115 -281.097482)
		(width 0.0889)
		(layer "In11.Cu")
		(net "UPI_CPU1_CPU0_P2P2_DN<20>")
	)
	(segment
		(start 268.420342 -333.05242)
		(end 269.028164 -332.444598)
		(width 0.14732)
		(layer "In11.Cu")
		(net "UPI_CPU1_CPU0_P2P2_DN<20>")
	)
	(segment
		(start 256.892044 -347.511624)
		(end 256.892044 -346.578428)
		(width 0.14732)
		(layer "In11.Cu")
		(net "UPI_CPU1_CPU0_P2P2_DN<20>")
	)
	(segment
		(start 311.409334 -313.689238)
		(end 311.598564 -313.76747)
		(width 0.14732)
		(layer "In11.Cu")
		(net "UPI_CPU1_CPU0_P2P2_DN<20>")
	)
	(segment
		(start 261.848092 -339.62467)
		(end 262.455914 -339.016848)
		(width 0.14732)
		(layer "In11.Cu")
		(net "UPI_CPU1_CPU0_P2P2_DN<20>")
	)
	(segment
		(start 337.039712 -285.675578)
		(end 337.039712 -285.651448)
		(width 0.0889)
		(layer "In11.Cu")
		(net "UPI_CPU1_CPU0_P2P2_DN<20>")
	)
	(segment
		(start 307.683408 -314.401708)
		(end 308.48935 -314.401708)
		(width 0.14732)
		(layer "In11.Cu")
		(net "UPI_CPU1_CPU0_P2P2_DN<20>")
	)
	(segment
		(start 336.383122 -288.426906)
		(end 336.39125 -288.422334)
		(width 0.0889)
		(layer "In11.Cu")
		(net "UPI_CPU1_CPU0_P2P2_DN<20>")
	)
	(segment
		(start 271.55013 -329.922632)
		(end 275.254974 -329.922632)
		(width 0.14732)
		(layer "In11.Cu")
		(net "UPI_CPU1_CPU0_P2P2_DN<20>")
	)
	(segment
		(start 316.25921 -312.034428)
		(end 316.40399 -312.179208)
		(width 0.14732)
		(layer "In11.Cu")
		(net "UPI_CPU1_CPU0_P2P2_DN<20>")
	)
	(segment
		(start 106.400346 -283.705808)
		(end 106.39425 -283.709364)
		(width 0.0889)
		(layer "In11.Cu")
		(net "UPI_CPU1_CPU0_P2P2_DN<20>")
	)
	(segment
		(start 270.250158 -331.222604)
		(end 271.55013 -329.922632)
		(width 0.14732)
		(layer "In11.Cu")
		(net "UPI_CPU1_CPU0_P2P2_DN<20>")
	)
	(segment
		(start 314.71997 -312.179208)
		(end 314.86475 -312.034428)
		(width 0.14732)
		(layer "In11.Cu")
		(net "UPI_CPU1_CPU0_P2P2_DN<20>")
	)
	(segment
		(start 76.825856 -361.139486)
		(end 79.073248 -363.38637)
		(width 0.14732)
		(layer "In11.Cu")
		(net "UPI_CPU1_CPU0_P2P2_DN<20>")
	)
	(segment
		(start 260.209284 -341.699342)
		(end 260.209284 -341.263478)
		(width 0.14732)
		(layer "In11.Cu")
		(net "UPI_CPU1_CPU0_P2P2_DN<20>")
	)
	(segment
		(start 105.445306 -281.097482)
		(end 105.452672 -281.1018)
		(width 0.0889)
		(layer "In11.Cu")
		(net "UPI_CPU1_CPU0_P2P2_DN<20>")
	)
	(segment
		(start 335.279746 -289.985196)
		(end 335.29524 -289.969702)
		(width 0.0889)
		(layer "In11.Cu")
		(net "UPI_CPU1_CPU0_P2P2_DN<20>")
	)
	(segment
		(start 73.377298 -335.214468)
		(end 73.377298 -352.822256)
		(width 0.14732)
		(layer "In11.Cu")
		(net "UPI_CPU1_CPU0_P2P2_DN<20>")
	)
	(segment
		(start 263.285986 -334.333596)
		(end 265.108436 -336.156046)
		(width 0.14732)
		(layer "In11.Cu")
		(net "UPI_CPU1_CPU0_P2P2_DN<20>")
	)
	(segment
		(start 267.358876 -334.113886)
		(end 267.79474 -334.113886)
		(width 0.14732)
		(layer "In11.Cu")
		(net "UPI_CPU1_CPU0_P2P2_DN<20>")
	)
	(segment
		(start 260.633464 -336.986118)
		(end 260.633464 -336.550762)
		(width 0.14732)
		(layer "In11.Cu")
		(net "UPI_CPU1_CPU0_P2P2_DN<20>")
	)
	(segment
		(start 105.45572 -281.103578)
		(end 105.45699 -281.10434)
		(width 0.0889)
		(layer "In11.Cu")
		(net "UPI_CPU1_CPU0_P2P2_DN<20>")
	)
	(segment
		(start 265.73353 -335.739232)
		(end 265.73353 -335.530952)
		(width 0.14732)
		(layer "In11.Cu")
		(net "UPI_CPU1_CPU0_P2P2_DN<20>")
	)
	(segment
		(start 105.45445 -285.336996)
		(end 105.453434 -285.337504)
		(width 0.0889)
		(layer "In11.Cu")
		(net "UPI_CPU1_CPU0_P2P2_DN<20>")
	)
	(segment
		(start 262.85063 -334.333596)
		(end 263.285986 -334.333596)
		(width 0.14732)
		(layer "In11.Cu")
		(net "UPI_CPU1_CPU0_P2P2_DN<20>")
	)
	(segment
		(start 305.096418 -316.157102)
		(end 305.396138 -315.94298)
		(width 0.14732)
		(layer "In11.Cu")
		(net "UPI_CPU1_CPU0_P2P2_DN<20>")
	)
	(segment
		(start 269.028164 -332.444598)
		(end 269.028164 -332.236318)
		(width 0.14732)
		(layer "In11.Cu")
		(net "UPI_CPU1_CPU0_P2P2_DN<20>")
	)
	(segment
		(start 73.971658 -329.181714)
		(end 73.377298 -335.214468)
		(width 0.14732)
		(layer "In11.Cu")
		(net "UPI_CPU1_CPU0_P2P2_DN<20>")
	)
	(segment
		(start 334.929226 -290.335716)
		(end 335.279746 -289.985196)
		(width 0.14732)
		(layer "In11.Cu")
		(net "UPI_CPU1_CPU0_P2P2_DN<20>")
	)
	(segment
		(start 284.718506 -323.934074)
		(end 299.096684 -323.934074)
		(width 0.14732)
		(layer "In11.Cu")
		(net "UPI_CPU1_CPU0_P2P2_DN<20>")
	)
	(segment
		(start 337.33105 -284.52826)
		(end 337.32216 -284.52318)
		(width 0.0889)
		(layer "In11.Cu")
		(net "UPI_CPU1_CPU0_P2P2_DN<20>")
	)
	(segment
		(start 263.423908 -332.785974)
		(end 264.002266 -332.207616)
		(width 0.14732)
		(layer "In11.Cu")
		(net "UPI_CPU1_CPU0_P2P2_DN<20>")
	)
	(segment
		(start 105.00614 -297.326812)
		(end 103.28021 -299.65396)
		(width 0.14732)
		(layer "In11.Cu")
		(net "UPI_CPU1_CPU0_P2P2_DN<20>")
	)
	(arc
		(start 336.569812 -283.219906)
		(mid 336.56976 -283.212539)
		(end 336.569558 -283.205174)
		(width 0.0889)
		(layer "In11.Cu")
		(net "UPI_CPU1_CPU0_P2P2_DN<20>")
	)
	(arc
		(start 337.509612 -286.466788)
		(mid 337.457342 -286.284423)
		(end 337.322414 -286.151066)
		(width 0.0889)
		(layer "In11.Cu")
		(net "UPI_CPU1_CPU0_P2P2_DN<20>")
	)
	(arc
		(start 105.460292 -281.106118)
		(mid 105.662879 -281.312469)
		(end 105.736898 -281.59202)
		(width 0.0889)
		(layer "In11.Cu")
		(net "UPI_CPU1_CPU0_P2P2_DN<20>")
	)
	(arc
		(start 337.33105 -285.166816)
		(mid 337.509647 -284.847538)
		(end 337.33105 -284.52826)
		(width 0.0889)
		(layer "In11.Cu")
		(net "UPI_CPU1_CPU0_P2P2_DN<20>")
	)
	(arc
		(start 337.039712 -285.651448)
		(mid 337.117823 -285.374499)
		(end 337.32216 -285.171896)
		(width 0.0889)
		(layer "In11.Cu")
		(net "UPI_CPU1_CPU0_P2P2_DN<20>")
	)
	(arc
		(start 336.86115 -281.097482)
		(mid 336.992064 -280.961122)
		(end 337.039712 -280.778204)
		(width 0.0889)
		(layer "In11.Cu")
		(net "UPI_CPU1_CPU0_P2P2_DN<20>")
	)
	(arc
		(start 105.44556 -286.969962)
		(mid 105.314646 -287.106322)
		(end 105.266998 -287.28924)
		(width 0.0889)
		(layer "In11.Cu")
		(net "UPI_CPU1_CPU0_P2P2_DN<20>")
	)
	(arc
		(start 105.92435 -281.916378)
		(mid 106.127173 -282.116609)
		(end 106.206544 -282.390342)
		(width 0.0889)
		(layer "In11.Cu")
		(net "UPI_CPU1_CPU0_P2P2_DN<20>")
	)
	(arc
		(start 336.569558 -283.205174)
		(mid 336.518504 -283.030594)
		(end 336.39125 -282.900628)
		(width 0.0889)
		(layer "In11.Cu")
		(net "UPI_CPU1_CPU0_P2P2_DN<20>")
	)
	(arc
		(start 336.099912 -282.405836)
		(mid 336.173828 -282.126334)
		(end 336.376264 -281.919934)
		(width 0.0889)
		(layer "In11.Cu")
		(net "UPI_CPU1_CPU0_P2P2_DN<20>")
	)
	(arc
		(start 105.45445 -285.985712)
		(mid 105.656736 -286.184693)
		(end 105.736898 -286.456882)
		(width 0.0889)
		(layer "In11.Cu")
		(net "UPI_CPU1_CPU0_P2P2_DN<20>")
	)
	(arc
		(start 337.039712 -284.025086)
		(mid 336.987442 -283.842721)
		(end 336.852514 -283.709364)
		(width 0.0889)
		(layer "In11.Cu")
		(net "UPI_CPU1_CPU0_P2P2_DN<20>")
	)
	(arc
		(start 336.86115 -287.608518)
		(mid 336.992064 -287.472158)
		(end 337.039712 -287.28924)
		(width 0.0889)
		(layer "In11.Cu")
		(net "UPI_CPU1_CPU0_P2P2_DN<20>")
	)
	(arc
		(start 336.099912 -288.917126)
		(mid 336.172604 -288.639921)
		(end 336.371946 -288.434018)
		(width 0.0889)
		(layer "In11.Cu")
		(net "UPI_CPU1_CPU0_P2P2_DN<20>")
	)
	(arc
		(start 337.33105 -280.283412)
		(mid 337.446789 -280.171588)
		(end 337.50504 -280.021538)
		(width 0.0889)
		(layer "In11.Cu")
		(net "UPI_CPU1_CPU0_P2P2_DN<20>")
	)
	(arc
		(start 105.266998 -287.299146)
		(mid 105.188887 -287.576095)
		(end 104.98455 -287.778698)
		(width 0.0889)
		(layer "In11.Cu")
		(net "UPI_CPU1_CPU0_P2P2_DN<20>")
	)
	(arc
		(start 104.327198 -289.078416)
		(mid 104.402203 -289.193875)
		(end 104.511348 -289.277806)
		(width 0.0889)
		(layer "In11.Cu")
		(net "UPI_CPU1_CPU0_P2P2_DN<20>")
	)
	(arc
		(start 104.50576 -288.597848)
		(mid 104.374846 -288.734208)
		(end 104.327198 -288.917126)
		(width 0.0889)
		(layer "In11.Cu")
		(net "UPI_CPU1_CPU0_P2P2_DN<20>")
	)
	(arc
		(start 104.797098 -288.121598)
		(mid 104.716936 -288.393787)
		(end 104.51465 -288.592768)
		(width 0.0889)
		(layer "In11.Cu")
		(net "UPI_CPU1_CPU0_P2P2_DN<20>")
	)
	(arc
		(start 104.97566 -287.783778)
		(mid 104.844746 -287.920138)
		(end 104.797098 -288.103056)
		(width 0.0889)
		(layer "In11.Cu")
		(net "UPI_CPU1_CPU0_P2P2_DN<20>")
	)
	(arc
		(start 336.569812 -288.09315)
		(mid 336.647923 -287.816201)
		(end 336.85226 -287.613598)
		(width 0.0889)
		(layer "In11.Cu")
		(net "UPI_CPU1_CPU0_P2P2_DN<20>")
	)
	(arc
		(start 106.393996 -282.730194)
		(mid 106.599068 -282.933873)
		(end 106.676698 -283.212286)
		(width 0.0889)
		(layer "In11.Cu")
		(net "UPI_CPU1_CPU0_P2P2_DN<20>")
	)
	(arc
		(start 105.736644 -284.863032)
		(mid 105.657274 -285.136766)
		(end 105.45445 -285.336996)
		(width 0.0889)
		(layer "In11.Cu")
		(net "UPI_CPU1_CPU0_P2P2_DN<20>")
	)
	(arc
		(start 336.569812 -281.59202)
		(mid 336.643728 -281.312518)
		(end 336.846164 -281.106118)
		(width 0.0889)
		(layer "In11.Cu")
		(net "UPI_CPU1_CPU0_P2P2_DN<20>")
	)
	(arc
		(start 337.039712 -280.759662)
		(mid 337.119874 -280.487473)
		(end 337.32216 -280.288492)
		(width 0.0889)
		(layer "In11.Cu")
		(net "UPI_CPU1_CPU0_P2P2_DN<20>")
	)
	(arc
		(start 106.206798 -284.033722)
		(mid 106.134563 -284.310246)
		(end 105.936288 -284.516068)
		(width 0.0889)
		(layer "In11.Cu")
		(net "UPI_CPU1_CPU0_P2P2_DN<20>")
	)
	(arc
		(start 337.32216 -284.52318)
		(mid 337.117825 -284.320575)
		(end 337.039712 -284.043628)
		(width 0.0889)
		(layer "In11.Cu")
		(net "UPI_CPU1_CPU0_P2P2_DN<20>")
	)
	(arc
		(start 337.322414 -286.799782)
		(mid 337.457347 -286.666428)
		(end 337.509612 -286.48406)
		(width 0.0889)
		(layer "In11.Cu")
		(net "UPI_CPU1_CPU0_P2P2_DN<20>")
	)
	(arc
		(start 104.511348 -289.277806)
		(mid 104.676556 -289.413225)
		(end 104.775762 -289.602418)
		(width 0.0889)
		(layer "In11.Cu")
		(net "UPI_CPU1_CPU0_P2P2_DN<20>")
	)
	(arc
		(start 336.39125 -288.422334)
		(mid 336.522164 -288.285974)
		(end 336.569812 -288.103056)
		(width 0.0889)
		(layer "In11.Cu")
		(net "UPI_CPU1_CPU0_P2P2_DN<20>")
	)
	(arc
		(start 105.44556 -285.342076)
		(mid 105.266963 -285.661354)
		(end 105.44556 -285.980632)
		(width 0.0889)
		(layer "In11.Cu")
		(net "UPI_CPU1_CPU0_P2P2_DN<20>")
	)
	(arc
		(start 106.38536 -283.714444)
		(mid 106.254446 -283.850804)
		(end 106.206798 -284.033722)
		(width 0.0889)
		(layer "In11.Cu")
		(net "UPI_CPU1_CPU0_P2P2_DN<20>")
	)
	(arc
		(start 106.206544 -282.405836)
		(mid 106.254223 -282.588736)
		(end 106.385106 -282.725114)
		(width 0.0889)
		(layer "In11.Cu")
		(net "UPI_CPU1_CPU0_P2P2_DN<20>")
	)
	(arc
		(start 336.38236 -282.895548)
		(mid 336.179055 -282.694682)
		(end 336.099912 -282.42006)
		(width 0.0889)
		(layer "In11.Cu")
		(net "UPI_CPU1_CPU0_P2P2_DN<20>")
	)
	(arc
		(start 105.266744 -280.778204)
		(mid 105.314423 -280.961104)
		(end 105.445306 -281.097482)
		(width 0.0889)
		(layer "In11.Cu")
		(net "UPI_CPU1_CPU0_P2P2_DN<20>")
	)
	(arc
		(start 105.736898 -281.59202)
		(mid 105.784577 -281.77492)
		(end 105.91546 -281.911298)
		(width 0.0889)
		(layer "In11.Cu")
		(net "UPI_CPU1_CPU0_P2P2_DN<20>")
	)
	(arc
		(start 106.676698 -283.219906)
		(mid 106.602782 -283.499408)
		(end 106.400346 -283.705808)
		(width 0.0889)
		(layer "In11.Cu")
		(net "UPI_CPU1_CPU0_P2P2_DN<20>")
	)
	(arc
		(start 336.39125 -281.911298)
		(mid 336.522164 -281.774938)
		(end 336.569812 -281.59202)
		(width 0.0889)
		(layer "In11.Cu")
		(net "UPI_CPU1_CPU0_P2P2_DN<20>")
	)
	(arc
		(start 337.039712 -287.28924)
		(mid 337.113703 -287.009674)
		(end 337.316318 -286.803338)
		(width 0.0889)
		(layer "In11.Cu")
		(net "UPI_CPU1_CPU0_P2P2_DN<20>")
	)
	(arc
		(start 105.736898 -286.48533)
		(mid 105.658787 -286.762279)
		(end 105.45445 -286.964882)
		(width 0.0889)
		(layer "In11.Cu")
		(net "UPI_CPU1_CPU0_P2P2_DN<20>")
	)
	(arc
		(start 105.056178 -280.33726)
		(mid 105.206927 -280.523833)
		(end 105.266744 -280.756106)
		(width 0.0889)
		(layer "In11.Cu")
		(net "UPI_CPU1_CPU0_P2P2_DN<20>")
	)
	(arc
		(start 105.915206 -284.52826)
		(mid 105.784292 -284.66462)
		(end 105.736644 -284.847538)
		(width 0.0889)
		(layer "In11.Cu")
		(net "UPI_CPU1_CPU0_P2P2_DN<20>")
	)
	(arc
		(start 105.039414 -280.324306)
		(mid 105.047857 -280.330704)
		(end 105.056178 -280.33726)
		(width 0.0889)
		(layer "In11.Cu")
		(net "UPI_CPU1_CPU0_P2P2_DN<20>")
	)
	(arc
		(start 336.846418 -283.705808)
		(mid 336.643831 -283.499457)
		(end 336.569812 -283.219906)
		(width 0.0889)
		(layer "In11.Cu")
		(net "UPI_CPU1_CPU0_P2P2_DN<20>")
	)
	(arc
		(start 337.322414 -286.151066)
		(mid 337.118933 -285.950262)
		(end 337.039712 -285.675578)
		(width 0.0889)
		(layer "In11.Cu")
		(net "UPI_CPU1_CPU0_P2P2_DN<20>")
	)
	(segment
		(start 86.845648 -283.497782)
		(end 86.845648 -284.033722)
		(width 0.13208)
		(layer "F.Cu")
		(net "UPI_CPU1_CPU0_P2P2_DN<1>")
	)
	(segment
		(start 355.930962 -274.54479)
		(end 355.931216 -275.08073)
		(width 0.13208)
		(layer "F.Cu")
		(net "UPI_CPU1_CPU0_P2P2_DN<1>")
	)
	(segment
		(start 57.268618 -336.62239)
		(end 57.268618 -356.460806)
		(width 0.14732)
		(layer "In11.Cu")
		(net "UPI_CPU1_CPU0_P2P2_DN<1>")
	)
	(segment
		(start 56.592216 -334.991456)
		(end 57.268618 -336.62239)
		(width 0.14732)
		(layer "In11.Cu")
		(net "UPI_CPU1_CPU0_P2P2_DN<1>")
	)
	(segment
		(start 359.033318 -276.219158)
		(end 359.024428 -276.214078)
		(width 0.0889)
		(layer "In11.Cu")
		(net "UPI_CPU1_CPU0_P2P2_DN<1>")
	)
	(segment
		(start 345.08821 -309.223918)
		(end 355.970586 -298.26204)
		(width 0.14732)
		(layer "In11.Cu")
		(net "UPI_CPU1_CPU0_P2P2_DN<1>")
	)
	(segment
		(start 59.54522 -312.84037)
		(end 58.564018 -313.821318)
		(width 0.14732)
		(layer "In11.Cu")
		(net "UPI_CPU1_CPU0_P2P2_DN<1>")
	)
	(segment
		(start 87.002112 -284.30474)
		(end 86.977982 -284.393894)
		(width 0.0889)
		(layer "In11.Cu")
		(net "UPI_CPU1_CPU0_P2P2_DN<1>")
	)
	(segment
		(start 359.50906 -277.03653)
		(end 359.503726 -277.033482)
		(width 0.0889)
		(layer "In11.Cu")
		(net "UPI_CPU1_CPU0_P2P2_DN<1>")
	)
	(segment
		(start 85.340444 -285.651448)
		(end 85.340444 -285.661608)
		(width 0.0889)
		(layer "In11.Cu")
		(net "UPI_CPU1_CPU0_P2P2_DN<1>")
	)
	(segment
		(start 84.432394 -290.25342)
		(end 84.372958 -290.250118)
		(width 0.0889)
		(layer "In11.Cu")
		(net "UPI_CPU1_CPU0_P2P2_DN<1>")
	)
	(segment
		(start 51.36388 -329.42784)
		(end 54.673246 -332.737206)
		(width 0.14732)
		(layer "In11.Cu")
		(net "UPI_CPU1_CPU0_P2P2_DN<1>")
	)
	(segment
		(start 355.886258 -291.962586)
		(end 355.727 -291.803328)
		(width 0.14732)
		(layer "In11.Cu")
		(net "UPI_CPU1_CPU0_P2P2_DN<1>")
	)
	(segment
		(start 358.084374 -283.714444)
		(end 358.105456 -283.702252)
		(width 0.0889)
		(layer "In11.Cu")
		(net "UPI_CPU1_CPU0_P2P2_DN<1>")
	)
	(segment
		(start 58.564018 -313.821318)
		(end 55.825898 -315.651388)
		(width 0.14732)
		(layer "In11.Cu")
		(net "UPI_CPU1_CPU0_P2P2_DN<1>")
	)
	(segment
		(start 265.707368 -383.368042)
		(end 278.84628 -370.228876)
		(width 0.14732)
		(layer "In11.Cu")
		(net "UPI_CPU1_CPU0_P2P2_DN<1>")
	)
	(segment
		(start 86.845648 -284.033722)
		(end 87.002112 -284.30474)
		(width 0.0889)
		(layer "In11.Cu")
		(net "UPI_CPU1_CPU0_P2P2_DN<1>")
	)
	(segment
		(start 356.496366 -286.48533)
		(end 356.496366 -286.466788)
		(width 0.0889)
		(layer "In11.Cu")
		(net "UPI_CPU1_CPU0_P2P2_DN<1>")
	)
	(segment
		(start 57.268618 -356.460806)
		(end 62.9285 -370.125498)
		(width 0.14732)
		(layer "In11.Cu")
		(net "UPI_CPU1_CPU0_P2P2_DN<1>")
	)
	(segment
		(start 355.711506 -291.787834)
		(end 355.652578 -291.787834)
		(width 0.0889)
		(layer "In11.Cu")
		(net "UPI_CPU1_CPU0_P2P2_DN<1>")
	)
	(segment
		(start 64.429386 -310.36768)
		(end 64.379094 -310.388508)
		(width 0.14732)
		(layer "In11.Cu")
		(net "UPI_CPU1_CPU0_P2P2_DN<1>")
	)
	(segment
		(start 161.811208 -392.14171)
		(end 265.707368 -383.368042)
		(width 0.14732)
		(layer "In11.Cu")
		(net "UPI_CPU1_CPU0_P2P2_DN<1>")
	)
	(segment
		(start 52.099972 -323.629274)
		(end 52.070508 -323.629274)
		(width 0.14732)
		(layer "In11.Cu")
		(net "UPI_CPU1_CPU0_P2P2_DN<1>")
	)
	(segment
		(start 84.372958 -290.250118)
		(end 84.356448 -290.26485)
		(width 0.0889)
		(layer "In11.Cu")
		(net "UPI_CPU1_CPU0_P2P2_DN<1>")
	)
	(segment
		(start 278.84628 -370.228876)
		(end 278.84628 -349.664274)
		(width 0.14732)
		(layer "In11.Cu")
		(net "UPI_CPU1_CPU0_P2P2_DN<1>")
	)
	(segment
		(start 358.845866 -275.8948)
		(end 358.845866 -275.880576)
		(width 0.0889)
		(layer "In11.Cu")
		(net "UPI_CPU1_CPU0_P2P2_DN<1>")
	)
	(segment
		(start 84.52993 -290.165536)
		(end 84.432394 -290.25342)
		(width 0.0889)
		(layer "In11.Cu")
		(net "UPI_CPU1_CPU0_P2P2_DN<1>")
	)
	(segment
		(start 278.84628 -349.664274)
		(end 285.753556 -342.756998)
		(width 0.14732)
		(layer "In11.Cu")
		(net "UPI_CPU1_CPU0_P2P2_DN<1>")
	)
	(segment
		(start 52.070508 -323.629274)
		(end 51.36388 -324.335902)
		(width 0.14732)
		(layer "In11.Cu")
		(net "UPI_CPU1_CPU0_P2P2_DN<1>")
	)
	(segment
		(start 311.36971 -342.16975)
		(end 322.09994 -331.43952)
		(width 0.14732)
		(layer "In11.Cu")
		(net "UPI_CPU1_CPU0_P2P2_DN<1>")
	)
	(segment
		(start 359.494074 -278.017224)
		(end 359.502964 -278.012144)
		(width 0.0889)
		(layer "In11.Cu")
		(net "UPI_CPU1_CPU0_P2P2_DN<1>")
	)
	(segment
		(start 355.652578 -291.787834)
		(end 355.556312 -291.691568)
		(width 0.0889)
		(layer "In11.Cu")
		(net "UPI_CPU1_CPU0_P2P2_DN<1>")
	)
	(segment
		(start 55.825898 -315.651388)
		(end 54.057296 -316.383924)
		(width 0.14732)
		(layer "In11.Cu")
		(net "UPI_CPU1_CPU0_P2P2_DN<1>")
	)
	(segment
		(start 356.294182 -292.947598)
		(end 355.886258 -291.962586)
		(width 0.14732)
		(layer "In11.Cu")
		(net "UPI_CPU1_CPU0_P2P2_DN<1>")
	)
	(segment
		(start 64.42964 -310.36768)
		(end 64.429386 -310.36768)
		(width 0.14732)
		(layer "In11.Cu")
		(net "UPI_CPU1_CPU0_P2P2_DN<1>")
	)
	(segment
		(start 356.294182 -297.479212)
		(end 356.294182 -292.947598)
		(width 0.14732)
		(layer "In11.Cu")
		(net "UPI_CPU1_CPU0_P2P2_DN<1>")
	)
	(segment
		(start 53.643276 -321.61226)
		(end 53.460904 -322.528946)
		(width 0.14732)
		(layer "In11.Cu")
		(net "UPI_CPU1_CPU0_P2P2_DN<1>")
	)
	(segment
		(start 64.379094 -310.388508)
		(end 63.61176 -311.155842)
		(width 0.14732)
		(layer "In11.Cu")
		(net "UPI_CPU1_CPU0_P2P2_DN<1>")
	)
	(segment
		(start 355.556566 -288.11728)
		(end 355.556566 -288.103056)
		(width 0.0889)
		(layer "In11.Cu")
		(net "UPI_CPU1_CPU0_P2P2_DN<1>")
	)
	(segment
		(start 322.09994 -331.43952)
		(end 323.223382 -328.727562)
		(width 0.14732)
		(layer "In11.Cu")
		(net "UPI_CPU1_CPU0_P2P2_DN<1>")
	)
	(segment
		(start 127.002794 -392.14171)
		(end 161.811208 -392.14171)
		(width 0.14732)
		(layer "In11.Cu")
		(net "UPI_CPU1_CPU0_P2P2_DN<1>")
	)
	(segment
		(start 323.223382 -328.727562)
		(end 341.05723 -310.893714)
		(width 0.14732)
		(layer "In11.Cu")
		(net "UPI_CPU1_CPU0_P2P2_DN<1>")
	)
	(segment
		(start 358.562656 -279.640284)
		(end 358.563418 -279.639776)
		(width 0.0889)
		(layer "In11.Cu")
		(net "UPI_CPU1_CPU0_P2P2_DN<1>")
	)
	(segment
		(start 357.614474 -284.52826)
		(end 357.623364 -284.52318)
		(width 0.0889)
		(layer "In11.Cu")
		(net "UPI_CPU1_CPU0_P2P2_DN<1>")
	)
	(segment
		(start 62.9285 -370.125498)
		(end 70.689724 -377.886722)
		(width 0.14732)
		(layer "In11.Cu")
		(net "UPI_CPU1_CPU0_P2P2_DN<1>")
	)
	(segment
		(start 356.08768 -275.351748)
		(end 355.931216 -275.08073)
		(width 0.0889)
		(layer "In11.Cu")
		(net "UPI_CPU1_CPU0_P2P2_DN<1>")
	)
	(segment
		(start 53.804566 -316.636654)
		(end 53.643276 -317.02629)
		(width 0.14732)
		(layer "In11.Cu")
		(net "UPI_CPU1_CPU0_P2P2_DN<1>")
	)
	(segment
		(start 357.435912 -284.857444)
		(end 357.435912 -284.847538)
		(width 0.0889)
		(layer "In11.Cu")
		(net "UPI_CPU1_CPU0_P2P2_DN<1>")
	)
	(segment
		(start 359.315512 -278.351996)
		(end 359.315512 -278.336502)
		(width 0.0889)
		(layer "In11.Cu")
		(net "UPI_CPU1_CPU0_P2P2_DN<1>")
	)
	(segment
		(start 51.36388 -324.335902)
		(end 51.36388 -329.42784)
		(width 0.14732)
		(layer "In11.Cu")
		(net "UPI_CPU1_CPU0_P2P2_DN<1>")
	)
	(segment
		(start 359.503726 -277.033482)
		(end 359.502964 -277.032974)
		(width 0.0889)
		(layer "In11.Cu")
		(net "UPI_CPU1_CPU0_P2P2_DN<1>")
	)
	(segment
		(start 84.873592 -286.238188)
		(end 84.746084 -289.949636)
		(width 0.0889)
		(layer "In11.Cu")
		(net "UPI_CPU1_CPU0_P2P2_DN<1>")
	)
	(segment
		(start 85.036152 -286.075628)
		(end 84.873592 -286.238188)
		(width 0.0889)
		(layer "In11.Cu")
		(net "UPI_CPU1_CPU0_P2P2_DN<1>")
	)
	(segment
		(start 359.024428 -278.83104)
		(end 359.033318 -278.82596)
		(width 0.0889)
		(layer "In11.Cu")
		(net "UPI_CPU1_CPU0_P2P2_DN<1>")
	)
	(segment
		(start 358.845866 -279.160224)
		(end 358.845866 -279.150318)
		(width 0.0889)
		(layer "In11.Cu")
		(net "UPI_CPU1_CPU0_P2P2_DN<1>")
	)
	(segment
		(start 358.569514 -281.919934)
		(end 358.554528 -281.911298)
		(width 0.0889)
		(layer "In11.Cu")
		(net "UPI_CPU1_CPU0_P2P2_DN<1>")
	)
	(segment
		(start 358.554528 -279.644856)
		(end 358.560116 -279.641808)
		(width 0.0889)
		(layer "In11.Cu")
		(net "UPI_CPU1_CPU0_P2P2_DN<1>")
	)
	(segment
		(start 358.008174 -275.398992)
		(end 357.99776 -275.405088)
		(width 0.0889)
		(layer "In11.Cu")
		(net "UPI_CPU1_CPU0_P2P2_DN<1>")
	)
	(segment
		(start 54.057296 -316.383924)
		(end 53.804566 -316.636654)
		(width 0.14732)
		(layer "In11.Cu")
		(net "UPI_CPU1_CPU0_P2P2_DN<1>")
	)
	(segment
		(start 355.970586 -298.26204)
		(end 356.294182 -297.479212)
		(width 0.14732)
		(layer "In11.Cu")
		(net "UPI_CPU1_CPU0_P2P2_DN<1>")
	)
	(segment
		(start 357.072692 -275.396452)
		(end 357.05796 -275.405088)
		(width 0.0889)
		(layer "In11.Cu")
		(net "UPI_CPU1_CPU0_P2P2_DN<1>")
	)
	(segment
		(start 63.61176 -311.155842)
		(end 59.54522 -312.84037)
		(width 0.14732)
		(layer "In11.Cu")
		(net "UPI_CPU1_CPU0_P2P2_DN<1>")
	)
	(segment
		(start 356.205028 -286.969962)
		(end 356.213918 -286.964882)
		(width 0.0889)
		(layer "In11.Cu")
		(net "UPI_CPU1_CPU0_P2P2_DN<1>")
	)
	(segment
		(start 67.756278 -308.98973)
		(end 64.42964 -310.36768)
		(width 0.14732)
		(layer "In11.Cu")
		(net "UPI_CPU1_CPU0_P2P2_DN<1>")
	)
	(segment
		(start 355.556312 -289.551872)
		(end 355.086666 -289.082226)
		(width 0.0889)
		(layer "In11.Cu")
		(net "UPI_CPU1_CPU0_P2P2_DN<1>")
	)
	(segment
		(start 84.356448 -290.26485)
		(end 82.2198 -292.401498)
		(width 0.14732)
		(layer "In11.Cu")
		(net "UPI_CPU1_CPU0_P2P2_DN<1>")
	)
	(segment
		(start 355.727 -291.803328)
		(end 355.711506 -291.787834)
		(width 0.0889)
		(layer "In11.Cu")
		(net "UPI_CPU1_CPU0_P2P2_DN<1>")
	)
	(segment
		(start 80.71739 -296.028618)
		(end 67.756278 -308.98973)
		(width 0.14732)
		(layer "In11.Cu")
		(net "UPI_CPU1_CPU0_P2P2_DN<1>")
	)
	(segment
		(start 355.735128 -287.783778)
		(end 355.750114 -287.775142)
		(width 0.0889)
		(layer "In11.Cu")
		(net "UPI_CPU1_CPU0_P2P2_DN<1>")
	)
	(segment
		(start 359.315766 -276.717252)
		(end 359.315766 -276.69871)
		(width 0.0889)
		(layer "In11.Cu")
		(net "UPI_CPU1_CPU0_P2P2_DN<1>")
	)
	(segment
		(start 355.273864 -288.593022)
		(end 355.274118 -288.592768)
		(width 0.0889)
		(layer "In11.Cu")
		(net "UPI_CPU1_CPU0_P2P2_DN<1>")
	)
	(segment
		(start 54.673246 -332.737206)
		(end 56.592216 -334.991456)
		(width 0.14732)
		(layer "In11.Cu")
		(net "UPI_CPU1_CPU0_P2P2_DN<1>")
	)
	(segment
		(start 358.554528 -282.900628)
		(end 358.563418 -282.895548)
		(width 0.0889)
		(layer "In11.Cu")
		(net "UPI_CPU1_CPU0_P2P2_DN<1>")
	)
	(segment
		(start 341.05723 -310.893714)
		(end 345.08821 -309.223918)
		(width 0.14732)
		(layer "In11.Cu")
		(net "UPI_CPU1_CPU0_P2P2_DN<1>")
	)
	(segment
		(start 356.176834 -275.375624)
		(end 356.08768 -275.351748)
		(width 0.0889)
		(layer "In11.Cu")
		(net "UPI_CPU1_CPU0_P2P2_DN<1>")
	)
	(segment
		(start 285.753556 -342.756998)
		(end 287.17113 -342.16975)
		(width 0.14732)
		(layer "In11.Cu")
		(net "UPI_CPU1_CPU0_P2P2_DN<1>")
	)
	(segment
		(start 287.17113 -342.16975)
		(end 311.36971 -342.16975)
		(width 0.14732)
		(layer "In11.Cu")
		(net "UPI_CPU1_CPU0_P2P2_DN<1>")
	)
	(segment
		(start 70.689724 -377.886722)
		(end 92.89161 -387.081522)
		(width 0.14732)
		(layer "In11.Cu")
		(net "UPI_CPU1_CPU0_P2P2_DN<1>")
	)
	(segment
		(start 53.643276 -317.02629)
		(end 53.643276 -321.61226)
		(width 0.14732)
		(layer "In11.Cu")
		(net "UPI_CPU1_CPU0_P2P2_DN<1>")
	)
	(segment
		(start 358.554528 -281.272742)
		(end 358.569514 -281.264106)
		(width 0.0889)
		(layer "In11.Cu")
		(net "UPI_CPU1_CPU0_P2P2_DN<1>")
	)
	(segment
		(start 92.89161 -387.081522)
		(end 127.002794 -392.14171)
		(width 0.14732)
		(layer "In11.Cu")
		(net "UPI_CPU1_CPU0_P2P2_DN<1>")
	)
	(segment
		(start 85.161882 -285.980886)
		(end 85.152992 -285.985966)
		(width 0.0889)
		(layer "In11.Cu")
		(net "UPI_CPU1_CPU0_P2P2_DN<1>")
	)
	(segment
		(start 84.746084 -289.949636)
		(end 84.52993 -290.165536)
		(width 0.0889)
		(layer "In11.Cu")
		(net "UPI_CPU1_CPU0_P2P2_DN<1>")
	)
	(segment
		(start 52.544726 -323.445124)
		(end 52.099972 -323.629274)
		(width 0.14732)
		(layer "In11.Cu")
		(net "UPI_CPU1_CPU0_P2P2_DN<1>")
	)
	(segment
		(start 356.966266 -285.675578)
		(end 356.966266 -285.652718)
		(width 0.0889)
		(layer "In11.Cu")
		(net "UPI_CPU1_CPU0_P2P2_DN<1>")
	)
	(segment
		(start 358.563418 -280.288492)
		(end 358.554528 -280.283412)
		(width 0.0889)
		(layer "In11.Cu")
		(net "UPI_CPU1_CPU0_P2P2_DN<1>")
	)
	(segment
		(start 358.560116 -279.641808)
		(end 358.562656 -279.640284)
		(width 0.0889)
		(layer "In11.Cu")
		(net "UPI_CPU1_CPU0_P2P2_DN<1>")
	)
	(segment
		(start 355.086666 -289.082226)
		(end 355.086666 -288.917126)
		(width 0.0889)
		(layer "In11.Cu")
		(net "UPI_CPU1_CPU0_P2P2_DN<1>")
	)
	(segment
		(start 53.460904 -322.528946)
		(end 52.544726 -323.445124)
		(width 0.14732)
		(layer "In11.Cu")
		(net "UPI_CPU1_CPU0_P2P2_DN<1>")
	)
	(segment
		(start 357.905812 -284.043628)
		(end 357.905812 -284.033722)
		(width 0.0889)
		(layer "In11.Cu")
		(net "UPI_CPU1_CPU0_P2P2_DN<1>")
	)
	(segment
		(start 82.2198 -292.401498)
		(end 80.71739 -296.028618)
		(width 0.14732)
		(layer "In11.Cu")
		(net "UPI_CPU1_CPU0_P2P2_DN<1>")
	)
	(segment
		(start 355.556312 -291.691568)
		(end 355.556312 -289.551872)
		(width 0.0889)
		(layer "In11.Cu")
		(net "UPI_CPU1_CPU0_P2P2_DN<1>")
	)
	(segment
		(start 356.683564 -275.405088)
		(end 356.67315 -275.398992)
		(width 0.0889)
		(layer "In11.Cu")
		(net "UPI_CPU1_CPU0_P2P2_DN<1>")
	)
	(arc
		(start 357.623364 -284.52318)
		(mid 357.827699 -284.320575)
		(end 357.905812 -284.043628)
		(width 0.0889)
		(layer "In11.Cu")
		(net "UPI_CPU1_CPU0_P2P2_DN<1>")
	)
	(arc
		(start 357.99776 -275.405088)
		(mid 357.810562 -275.455231)
		(end 357.623364 -275.405088)
		(width 0.0889)
		(layer "In11.Cu")
		(net "UPI_CPU1_CPU0_P2P2_DN<1>")
	)
	(arc
		(start 356.496366 -286.466788)
		(mid 356.548636 -286.284423)
		(end 356.683564 -286.151066)
		(width 0.0889)
		(layer "In11.Cu")
		(net "UPI_CPU1_CPU0_P2P2_DN<1>")
	)
	(arc
		(start 86.977982 -284.393894)
		(mid 86.96941 -284.400416)
		(end 86.960964 -284.407102)
		(width 0.0889)
		(layer "In11.Cu")
		(net "UPI_CPU1_CPU0_P2P2_DN<1>")
	)
	(arc
		(start 357.905812 -284.033722)
		(mid 357.953491 -283.850822)
		(end 358.084374 -283.714444)
		(width 0.0889)
		(layer "In11.Cu")
		(net "UPI_CPU1_CPU0_P2P2_DN<1>")
	)
	(arc
		(start 356.196392 -275.367496)
		(mid 356.186574 -275.371466)
		(end 356.176834 -275.375624)
		(width 0.0889)
		(layer "In11.Cu")
		(net "UPI_CPU1_CPU0_P2P2_DN<1>")
	)
	(arc
		(start 358.845866 -280.778204)
		(mid 358.770259 -280.495496)
		(end 358.563418 -280.288492)
		(width 0.0889)
		(layer "In11.Cu")
		(net "UPI_CPU1_CPU0_P2P2_DN<1>")
	)
	(arc
		(start 356.966266 -285.652718)
		(mid 357.018536 -285.470353)
		(end 357.153464 -285.336996)
		(width 0.0889)
		(layer "In11.Cu")
		(net "UPI_CPU1_CPU0_P2P2_DN<1>")
	)
	(arc
		(start 85.340444 -285.661608)
		(mid 85.292765 -285.844508)
		(end 85.161882 -285.980886)
		(width 0.0889)
		(layer "In11.Cu")
		(net "UPI_CPU1_CPU0_P2P2_DN<1>")
	)
	(arc
		(start 358.563418 -279.639776)
		(mid 358.767753 -279.437171)
		(end 358.845866 -279.160224)
		(width 0.0889)
		(layer "In11.Cu")
		(net "UPI_CPU1_CPU0_P2P2_DN<1>")
	)
	(arc
		(start 355.274118 -288.592768)
		(mid 355.477423 -288.391902)
		(end 355.556566 -288.11728)
		(width 0.0889)
		(layer "In11.Cu")
		(net "UPI_CPU1_CPU0_P2P2_DN<1>")
	)
	(arc
		(start 355.556566 -288.103056)
		(mid 355.604245 -287.920156)
		(end 355.735128 -287.783778)
		(width 0.0889)
		(layer "In11.Cu")
		(net "UPI_CPU1_CPU0_P2P2_DN<1>")
	)
	(arc
		(start 358.563418 -282.895548)
		(mid 358.846159 -282.40943)
		(end 358.569514 -281.919934)
		(width 0.0889)
		(layer "In11.Cu")
		(net "UPI_CPU1_CPU0_P2P2_DN<1>")
	)
	(arc
		(start 356.026466 -287.28924)
		(mid 356.074145 -287.10634)
		(end 356.205028 -286.969962)
		(width 0.0889)
		(layer "In11.Cu")
		(net "UPI_CPU1_CPU0_P2P2_DN<1>")
	)
	(arc
		(start 359.502964 -277.032974)
		(mid 359.368031 -276.89962)
		(end 359.315766 -276.717252)
		(width 0.0889)
		(layer "In11.Cu")
		(net "UPI_CPU1_CPU0_P2P2_DN<1>")
	)
	(arc
		(start 86.750144 -284.847538)
		(mid 86.562845 -285.171979)
		(end 86.188296 -285.171896)
		(width 0.0889)
		(layer "In11.Cu")
		(net "UPI_CPU1_CPU0_P2P2_DN<1>")
	)
	(arc
		(start 85.052408 -286.05988)
		(mid 85.044201 -286.067672)
		(end 85.036152 -286.075628)
		(width 0.0889)
		(layer "In11.Cu")
		(net "UPI_CPU1_CPU0_P2P2_DN<1>")
	)
	(arc
		(start 355.750114 -287.775142)
		(mid 355.952527 -287.568729)
		(end 356.026466 -287.28924)
		(width 0.0889)
		(layer "In11.Cu")
		(net "UPI_CPU1_CPU0_P2P2_DN<1>")
	)
	(arc
		(start 356.67315 -275.398992)
		(mid 356.43827 -275.330427)
		(end 356.196392 -275.367496)
		(width 0.0889)
		(layer "In11.Cu")
		(net "UPI_CPU1_CPU0_P2P2_DN<1>")
	)
	(arc
		(start 358.845866 -279.150318)
		(mid 358.893545 -278.967418)
		(end 359.024428 -278.83104)
		(width 0.0889)
		(layer "In11.Cu")
		(net "UPI_CPU1_CPU0_P2P2_DN<1>")
	)
	(arc
		(start 356.683564 -286.151066)
		(mid 356.887045 -285.950262)
		(end 356.966266 -285.675578)
		(width 0.0889)
		(layer "In11.Cu")
		(net "UPI_CPU1_CPU0_P2P2_DN<1>")
	)
	(arc
		(start 358.554528 -281.911298)
		(mid 358.375931 -281.59202)
		(end 358.554528 -281.272742)
		(width 0.0889)
		(layer "In11.Cu")
		(net "UPI_CPU1_CPU0_P2P2_DN<1>")
	)
	(arc
		(start 357.435912 -284.847538)
		(mid 357.483591 -284.664638)
		(end 357.614474 -284.52826)
		(width 0.0889)
		(layer "In11.Cu")
		(net "UPI_CPU1_CPU0_P2P2_DN<1>")
	)
	(arc
		(start 359.033318 -278.82596)
		(mid 359.236141 -278.625729)
		(end 359.315512 -278.351996)
		(width 0.0889)
		(layer "In11.Cu")
		(net "UPI_CPU1_CPU0_P2P2_DN<1>")
	)
	(arc
		(start 358.105456 -283.702252)
		(mid 358.303684 -283.496404)
		(end 358.375966 -283.219906)
		(width 0.0889)
		(layer "In11.Cu")
		(net "UPI_CPU1_CPU0_P2P2_DN<1>")
	)
	(arc
		(start 357.153464 -285.336996)
		(mid 357.357799 -285.134391)
		(end 357.435912 -284.857444)
		(width 0.0889)
		(layer "In11.Cu")
		(net "UPI_CPU1_CPU0_P2P2_DN<1>")
	)
	(arc
		(start 357.05796 -275.405088)
		(mid 356.870762 -275.455231)
		(end 356.683564 -275.405088)
		(width 0.0889)
		(layer "In11.Cu")
		(net "UPI_CPU1_CPU0_P2P2_DN<1>")
	)
	(arc
		(start 86.188296 -285.171896)
		(mid 85.62732 -285.169365)
		(end 85.340444 -285.651448)
		(width 0.0889)
		(layer "In11.Cu")
		(net "UPI_CPU1_CPU0_P2P2_DN<1>")
	)
	(arc
		(start 358.375966 -283.219906)
		(mid 358.423645 -283.037006)
		(end 358.554528 -282.900628)
		(width 0.0889)
		(layer "In11.Cu")
		(net "UPI_CPU1_CPU0_P2P2_DN<1>")
	)
	(arc
		(start 356.213918 -286.964882)
		(mid 356.418253 -286.762277)
		(end 356.496366 -286.48533)
		(width 0.0889)
		(layer "In11.Cu")
		(net "UPI_CPU1_CPU0_P2P2_DN<1>")
	)
	(arc
		(start 358.554528 -280.283412)
		(mid 358.37581 -279.964134)
		(end 358.554528 -279.644856)
		(width 0.0889)
		(layer "In11.Cu")
		(net "UPI_CPU1_CPU0_P2P2_DN<1>")
	)
	(arc
		(start 358.845866 -275.880576)
		(mid 358.56233 -275.404459)
		(end 358.008174 -275.398992)
		(width 0.0889)
		(layer "In11.Cu")
		(net "UPI_CPU1_CPU0_P2P2_DN<1>")
	)
	(arc
		(start 359.315766 -276.69871)
		(mid 359.237655 -276.421761)
		(end 359.033318 -276.219158)
		(width 0.0889)
		(layer "In11.Cu")
		(net "UPI_CPU1_CPU0_P2P2_DN<1>")
	)
	(arc
		(start 86.960964 -284.407102)
		(mid 86.805566 -284.603383)
		(end 86.750144 -284.847538)
		(width 0.0889)
		(layer "In11.Cu")
		(net "UPI_CPU1_CPU0_P2P2_DN<1>")
	)
	(arc
		(start 357.623364 -275.405088)
		(mid 357.349135 -275.329163)
		(end 357.072692 -275.396452)
		(width 0.0889)
		(layer "In11.Cu")
		(net "UPI_CPU1_CPU0_P2P2_DN<1>")
	)
	(arc
		(start 359.502964 -278.012144)
		(mid 359.785959 -277.526025)
		(end 359.50906 -277.03653)
		(width 0.0889)
		(layer "In11.Cu")
		(net "UPI_CPU1_CPU0_P2P2_DN<1>")
	)
	(arc
		(start 355.086666 -288.917126)
		(mid 355.13683 -288.729988)
		(end 355.273864 -288.593022)
		(width 0.0889)
		(layer "In11.Cu")
		(net "UPI_CPU1_CPU0_P2P2_DN<1>")
	)
	(arc
		(start 359.024428 -276.214078)
		(mid 358.893514 -276.077718)
		(end 358.845866 -275.8948)
		(width 0.0889)
		(layer "In11.Cu")
		(net "UPI_CPU1_CPU0_P2P2_DN<1>")
	)
	(arc
		(start 359.315512 -278.336502)
		(mid 359.363191 -278.153602)
		(end 359.494074 -278.017224)
		(width 0.0889)
		(layer "In11.Cu")
		(net "UPI_CPU1_CPU0_P2P2_DN<1>")
	)
	(arc
		(start 358.569514 -281.264106)
		(mid 358.771927 -281.057693)
		(end 358.845866 -280.778204)
		(width 0.0889)
		(layer "In11.Cu")
		(net "UPI_CPU1_CPU0_P2P2_DN<1>")
	)
	(arc
		(start 85.152992 -285.985966)
		(mid 85.100656 -286.020141)
		(end 85.052408 -286.05988)
		(width 0.0889)
		(layer "In11.Cu")
		(net "UPI_CPU1_CPU0_P2P2_DN<1>")
	)
	(segment
		(start 105.641648 -281.869896)
		(end 105.641648 -282.405582)
		(width 0.13208)
		(layer "F.Cu")
		(net "UPI_CPU1_CPU0_P2P2_DN<19>")
	)
	(segment
		(start 336.665316 -282.405836)
		(end 336.665316 -281.869896)
		(width 0.13208)
		(layer "F.Cu")
		(net "UPI_CPU1_CPU0_P2P2_DN<19>")
	)
	(segment
		(start 105.641648 -282.405582)
		(end 105.641394 -282.405836)
		(width 0.13208)
		(layer "F.Cu")
		(net "UPI_CPU1_CPU0_P2P2_DN<19>")
	)
	(segment
		(start 104.512872 -285.337758)
		(end 104.514396 -285.336996)
		(width 0.0889)
		(layer "In11.Cu")
		(net "UPI_CPU1_CPU0_P2P2_DN<19>")
	)
	(segment
		(start 251.764546 -354.414582)
		(end 251.280676 -354.753672)
		(width 0.14732)
		(layer "In11.Cu")
		(net "UPI_CPU1_CPU0_P2P2_DN<19>")
	)
	(segment
		(start 305.576478 -320.546984)
		(end 305.28006 -321.261994)
		(width 0.14732)
		(layer "In11.Cu")
		(net "UPI_CPU1_CPU0_P2P2_DN<19>")
	)
	(segment
		(start 338.25942 -286.801814)
		(end 338.251546 -286.806132)
		(width 0.0889)
		(layer "In11.Cu")
		(net "UPI_CPU1_CPU0_P2P2_DN<19>")
	)
	(segment
		(start 257.303524 -349.139256)
		(end 256.885694 -349.557086)
		(width 0.14732)
		(layer "In11.Cu")
		(net "UPI_CPU1_CPU0_P2P2_DN<19>")
	)
	(segment
		(start 243.896896 -359.08615)
		(end 244.20703 -359.528872)
		(width 0.14732)
		(layer "In11.Cu")
		(net "UPI_CPU1_CPU0_P2P2_DN<19>")
	)
	(segment
		(start 103.857044 -291.432234)
		(end 103.857044 -289.752786)
		(width 0.0889)
		(layer "In11.Cu")
		(net "UPI_CPU1_CPU0_P2P2_DN<19>")
	)
	(segment
		(start 103.387144 -289.079178)
		(end 103.387144 -288.91738)
		(width 0.0889)
		(layer "In11.Cu")
		(net "UPI_CPU1_CPU0_P2P2_DN<19>")
	)
	(segment
		(start 303.364138 -322.844414)
		(end 302.457104 -323.502782)
		(width 0.14732)
		(layer "In11.Cu")
		(net "UPI_CPU1_CPU0_P2P2_DN<19>")
	)
	(segment
		(start 103.857298 -288.121598)
		(end 103.857298 -288.103056)
		(width 0.0889)
		(layer "In11.Cu")
		(net "UPI_CPU1_CPU0_P2P2_DN<19>")
	)
	(segment
		(start 235.888784 -365.355124)
		(end 235.578904 -364.912656)
		(width 0.14732)
		(layer "In11.Cu")
		(net "UPI_CPU1_CPU0_P2P2_DN<19>")
	)
	(segment
		(start 338.449666 -286.457644)
		(end 338.449666 -286.48787)
		(width 0.0889)
		(layer "In11.Cu")
		(net "UPI_CPU1_CPU0_P2P2_DN<19>")
	)
	(segment
		(start 305.576478 -318.89573)
		(end 305.576478 -319.411858)
		(width 0.14732)
		(layer "In11.Cu")
		(net "UPI_CPU1_CPU0_P2P2_DN<19>")
	)
	(segment
		(start 232.091992 -368.014504)
		(end 231.782112 -367.572036)
		(width 0.14732)
		(layer "In11.Cu")
		(net "UPI_CPU1_CPU0_P2P2_DN<19>")
	)
	(segment
		(start 312.755788 -314.695078)
		(end 312.23839 -315.212476)
		(width 0.14732)
		(layer "In11.Cu")
		(net "UPI_CPU1_CPU0_P2P2_DN<19>")
	)
	(segment
		(start 232.582466 -366.635538)
		(end 232.50652 -367.06429)
		(width 0.14732)
		(layer "In11.Cu")
		(net "UPI_CPU1_CPU0_P2P2_DN<19>")
	)
	(segment
		(start 262.8519 -343.763346)
		(end 262.644128 -343.763346)
		(width 0.14732)
		(layer "In11.Cu")
		(net "UPI_CPU1_CPU0_P2P2_DN<19>")
	)
	(segment
		(start 278.708612 -327.690226)
		(end 274.58289 -331.815948)
		(width 0.14732)
		(layer "In11.Cu")
		(net "UPI_CPU1_CPU0_P2P2_DN<19>")
	)
	(segment
		(start 73.156826 -328.99985)
		(end 73.721976 -326.958706)
		(width 0.14732)
		(layer "In11.Cu")
		(net "UPI_CPU1_CPU0_P2P2_DN<19>")
	)
	(segment
		(start 251.800614 -354.210112)
		(end 251.764546 -354.414582)
		(width 0.14732)
		(layer "In11.Cu")
		(net "UPI_CPU1_CPU0_P2P2_DN<19>")
	)
	(segment
		(start 238.946944 -362.17733)
		(end 238.277654 -362.646468)
		(width 0.14732)
		(layer "In11.Cu")
		(net "UPI_CPU1_CPU0_P2P2_DN<19>")
	)
	(segment
		(start 263.914636 -338.729574)
		(end 263.336278 -339.307932)
		(width 0.14732)
		(layer "In11.Cu")
		(net "UPI_CPU1_CPU0_P2P2_DN<19>")
	)
	(segment
		(start 337.509866 -288.103056)
		(end 337.509866 -288.114486)
		(width 0.0889)
		(layer "In11.Cu")
		(net "UPI_CPU1_CPU0_P2P2_DN<19>")
	)
	(segment
		(start 305.83632 -318.386968)
		(end 305.576478 -318.89573)
		(width 0.14732)
		(layer "In11.Cu")
		(net "UPI_CPU1_CPU0_P2P2_DN<19>")
	)
	(segment
		(start 316.842394 -313.57062)
		(end 315.79947 -313.57062)
		(width 0.14732)
		(layer "In11.Cu")
		(net "UPI_CPU1_CPU0_P2P2_DN<19>")
	)
	(segment
		(start 263.26973 -343.137744)
		(end 263.26973 -343.345516)
		(width 0.14732)
		(layer "In11.Cu")
		(net "UPI_CPU1_CPU0_P2P2_DN<19>")
	)
	(segment
		(start 251.075952 -354.717604)
		(end 250.766072 -354.275136)
		(width 0.14732)
		(layer "In11.Cu")
		(net "UPI_CPU1_CPU0_P2P2_DN<19>")
	)
	(segment
		(start 332.75651 -292.946836)
		(end 332.322424 -293.597076)
		(width 0.14732)
		(layer "In11.Cu")
		(net "UPI_CPU1_CPU0_P2P2_DN<19>")
	)
	(segment
		(start 272.348706 -333.841852)
		(end 270.887444 -332.38059)
		(width 0.14732)
		(layer "In11.Cu")
		(net "UPI_CPU1_CPU0_P2P2_DN<19>")
	)
	(segment
		(start 200.018396 -369.713764)
		(end 161.07918 -376.57913)
		(width 0.14732)
		(layer "In11.Cu")
		(net "UPI_CPU1_CPU0_P2P2_DN<19>")
	)
	(segment
		(start 105.45064 -283.711396)
		(end 105.452672 -283.710126)
		(width 0.0889)
		(layer "In11.Cu")
		(net "UPI_CPU1_CPU0_P2P2_DN<19>")
	)
	(segment
		(start 232.780586 -367.711482)
		(end 232.296716 -368.050572)
		(width 0.14732)
		(layer "In11.Cu")
		(net "UPI_CPU1_CPU0_P2P2_DN<19>")
	)
	(segment
		(start 237.991904 -364.061502)
		(end 237.78718 -364.025434)
		(width 0.14732)
		(layer "In11.Cu")
		(net "UPI_CPU1_CPU0_P2P2_DN<19>")
	)
	(segment
		(start 254.931164 -351.087944)
		(end 254.4953 -351.087944)
		(width 0.14732)
		(layer "In11.Cu")
		(net "UPI_CPU1_CPU0_P2P2_DN<19>")
	)
	(segment
		(start 264.349992 -338.729574)
		(end 263.914636 -338.729574)
		(width 0.14732)
		(layer "In11.Cu")
		(net "UPI_CPU1_CPU0_P2P2_DN<19>")
	)
	(segment
		(start 336.997548 -289.303968)
		(end 336.997548 -289.326066)
		(width 0.0889)
		(layer "In11.Cu")
		(net "UPI_CPU1_CPU0_P2P2_DN<19>")
	)
	(segment
		(start 267.627608 -335.451958)
		(end 267.192252 -335.451958)
		(width 0.14732)
		(layer "In11.Cu")
		(net "UPI_CPU1_CPU0_P2P2_DN<19>")
	)
	(segment
		(start 302.011588 -323.68744)
		(end 301.822612 -323.608954)
		(width 0.14732)
		(layer "In11.Cu")
		(net "UPI_CPU1_CPU0_P2P2_DN<19>")
	)
	(segment
		(start 103.899208 -291.474398)
		(end 103.857044 -291.432234)
		(width 0.0889)
		(layer "In11.Cu")
		(net "UPI_CPU1_CPU0_P2P2_DN<19>")
	)
	(segment
		(start 262.978392 -342.410542)
		(end 262.978392 -342.846406)
		(width 0.14732)
		(layer "In11.Cu")
		(net "UPI_CPU1_CPU0_P2P2_DN<19>")
	)
	(segment
		(start 265.553444 -337.090766)
		(end 264.975086 -337.669124)
		(width 0.14732)
		(layer "In11.Cu")
		(net "UPI_CPU1_CPU0_P2P2_DN<19>")
	)
	(segment
		(start 247.483884 -357.413052)
		(end 247.27916 -357.376984)
		(width 0.14732)
		(layer "In11.Cu")
		(net "UPI_CPU1_CPU0_P2P2_DN<19>")
	)
	(segment
		(start 244.20703 -359.528872)
		(end 244.170962 -359.733342)
		(width 0.14732)
		(layer "In11.Cu")
		(net "UPI_CPU1_CPU0_P2P2_DN<19>")
	)
	(segment
		(start 241.274092 -360.923586)
		(end 240.84534 -360.84764)
		(width 0.14732)
		(layer "In11.Cu")
		(net "UPI_CPU1_CPU0_P2P2_DN<19>")
	)
	(segment
		(start 259.700776 -345.688158)
		(end 259.700776 -346.124022)
		(width 0.14732)
		(layer "In11.Cu")
		(net "UPI_CPU1_CPU0_P2P2_DN<19>")
	)
	(segment
		(start 301.481998 -323.750178)
		(end 301.403766 -323.939408)
		(width 0.14732)
		(layer "In11.Cu")
		(net "UPI_CPU1_CPU0_P2P2_DN<19>")
	)
	(segment
		(start 257.870706 -347.71203)
		(end 257.195574 -348.38767)
		(width 0.14732)
		(layer "In11.Cu")
		(net "UPI_CPU1_CPU0_P2P2_DN<19>")
	)
	(segment
		(start 103.133144 -295.713658)
		(end 103.133144 -292.797484)
		(width 0.14732)
		(layer "In11.Cu")
		(net "UPI_CPU1_CPU0_P2P2_DN<19>")
	)
	(segment
		(start 257.195574 -348.823534)
		(end 257.303524 -348.931484)
		(width 0.14732)
		(layer "In11.Cu")
		(net "UPI_CPU1_CPU0_P2P2_DN<19>")
	)
	(segment
		(start 262.644128 -343.763346)
		(end 262.35279 -343.472008)
		(width 0.14732)
		(layer "In11.Cu")
		(net "UPI_CPU1_CPU0_P2P2_DN<19>")
	)
	(segment
		(start 104.04475 -287.778698)
		(end 104.050846 -287.775142)
		(width 0.0889)
		(layer "In11.Cu")
		(net "UPI_CPU1_CPU0_P2P2_DN<19>")
	)
	(segment
		(start 266.613894 -336.465672)
		(end 267.664438 -337.516216)
		(width 0.14732)
		(layer "In11.Cu")
		(net "UPI_CPU1_CPU0_P2P2_DN<19>")
	)
	(segment
		(start 337.7819 -283.703014)
		(end 337.792568 -283.709364)
		(width 0.0889)
		(layer "In11.Cu")
		(net "UPI_CPU1_CPU0_P2P2_DN<19>")
	)
	(segment
		(start 104.514396 -285.336996)
		(end 104.51719 -285.335472)
		(width 0.0889)
		(layer "In11.Cu")
		(net "UPI_CPU1_CPU0_P2P2_DN<19>")
	)
	(segment
		(start 105.454196 -283.709364)
		(end 105.460292 -283.705808)
		(width 0.0889)
		(layer "In11.Cu")
		(net "UPI_CPU1_CPU0_P2P2_DN<19>")
	)
	(segment
		(start 249.86615 -355.744272)
		(end 249.38228 -356.083362)
		(width 0.14732)
		(layer "In11.Cu")
		(net "UPI_CPU1_CPU0_P2P2_DN<19>")
	)
	(segment
		(start 259.700776 -346.124022)
		(end 259.992114 -346.41536)
		(width 0.14732)
		(layer "In11.Cu")
		(net "UPI_CPU1_CPU0_P2P2_DN<19>")
	)
	(segment
		(start 336.997548 -289.326066)
		(end 336.997548 -289.510724)
		(width 0.14732)
		(layer "In11.Cu")
		(net "UPI_CPU1_CPU0_P2P2_DN<19>")
	)
	(segment
		(start 251.280676 -354.753672)
		(end 251.075952 -354.717604)
		(width 0.14732)
		(layer "In11.Cu")
		(net "UPI_CPU1_CPU0_P2P2_DN<19>")
	)
	(segment
		(start 249.38228 -356.083362)
		(end 249.177556 -356.047294)
		(width 0.14732)
		(layer "In11.Cu")
		(net "UPI_CPU1_CPU0_P2P2_DN<19>")
	)
	(segment
		(start 239.685576 -362.695744)
		(end 239.375696 -362.253276)
		(width 0.14732)
		(layer "In11.Cu")
		(net "UPI_CPU1_CPU0_P2P2_DN<19>")
	)
	(segment
		(start 263.336278 -339.743288)
		(end 264.386822 -340.793832)
		(width 0.14732)
		(layer "In11.Cu")
		(net "UPI_CPU1_CPU0_P2P2_DN<19>")
	)
	(segment
		(start 253.824232 -351.759012)
		(end 253.823978 -351.759012)
		(width 0.14732)
		(layer "In11.Cu")
		(net "UPI_CPU1_CPU0_P2P2_DN<19>")
	)
	(segment
		(start 337.043268 -282.471114)
		(end 337.043776 -282.471114)
		(width 0.0889)
		(layer "In11.Cu")
		(net "UPI_CPU1_CPU0_P2P2_DN<19>")
	)
	(segment
		(start 273.360896 -333.037942)
		(end 272.556986 -333.841852)
		(width 0.14732)
		(layer "In11.Cu")
		(net "UPI_CPU1_CPU0_P2P2_DN<19>")
	)
	(segment
		(start 337.509866 -283.205428)
		(end 337.509866 -283.219906)
		(width 0.0889)
		(layer "In11.Cu")
		(net "UPI_CPU1_CPU0_P2P2_DN<19>")
	)
	(segment
		(start 311.45734 -315.212476)
		(end 310.561482 -316.108334)
		(width 0.14732)
		(layer "In11.Cu")
		(net "UPI_CPU1_CPU0_P2P2_DN<19>")
	)
	(segment
		(start 242.308634 -360.858562)
		(end 242.272566 -361.063032)
		(width 0.14732)
		(layer "In11.Cu")
		(net "UPI_CPU1_CPU0_P2P2_DN<19>")
	)
	(segment
		(start 104.50576 -286.969962)
		(end 104.520746 -286.961326)
		(width 0.0889)
		(layer "In11.Cu")
		(net "UPI_CPU1_CPU0_P2P2_DN<19>")
	)
	(segment
		(start 231.782112 -367.572036)
		(end 231.353106 -367.49609)
		(width 0.14732)
		(layer "In11.Cu")
		(net "UPI_CPU1_CPU0_P2P2_DN<19>")
	)
	(segment
		(start 255.556766 -350.026478)
		(end 255.556766 -350.462342)
		(width 0.14732)
		(layer "In11.Cu")
		(net "UPI_CPU1_CPU0_P2P2_DN<19>")
	)
	(segment
		(start 335.82229 -290.685982)
		(end 334.448404 -291.255196)
		(width 0.14732)
		(layer "In11.Cu")
		(net "UPI_CPU1_CPU0_P2P2_DN<19>")
	)
	(segment
		(start 103.387144 -288.91738)
		(end 103.387398 -288.917126)
		(width 0.0889)
		(layer "In11.Cu")
		(net "UPI_CPU1_CPU0_P2P2_DN<19>")
	)
	(segment
		(start 229.389432 -368.871246)
		(end 212.31225 -371.881654)
		(width 0.14732)
		(layer "In11.Cu")
		(net "UPI_CPU1_CPU0_P2P2_DN<19>")
	)
	(segment
		(start 251.49048 -353.76739)
		(end 251.800614 -354.210112)
		(width 0.14732)
		(layer "In11.Cu")
		(net "UPI_CPU1_CPU0_P2P2_DN<19>")
	)
	(segment
		(start 273.360896 -332.829662)
		(end 273.360896 -333.037942)
		(width 0.14732)
		(layer "In11.Cu")
		(net "UPI_CPU1_CPU0_P2P2_DN<19>")
	)
	(segment
		(start 103.899208 -292.03142)
		(end 103.899208 -291.496496)
		(width 0.14732)
		(layer "In11.Cu")
		(net "UPI_CPU1_CPU0_P2P2_DN<19>")
	)
	(segment
		(start 236.303312 -364.40491)
		(end 236.613446 -364.847632)
		(width 0.14732)
		(layer "In11.Cu")
		(net "UPI_CPU1_CPU0_P2P2_DN<19>")
	)
	(segment
		(start 234.404916 -365.7346)
		(end 234.71505 -366.177322)
		(width 0.14732)
		(layer "In11.Cu")
		(net "UPI_CPU1_CPU0_P2P2_DN<19>")
	)
	(segment
		(start 237.78718 -364.025434)
		(end 237.4773 -363.582966)
		(width 0.14732)
		(layer "In11.Cu")
		(net "UPI_CPU1_CPU0_P2P2_DN<19>")
	)
	(segment
		(start 268.678152 -336.502502)
		(end 267.627608 -335.451958)
		(width 0.14732)
		(layer "In11.Cu")
		(net "UPI_CPU1_CPU0_P2P2_DN<19>")
	)
	(segment
		(start 259.574284 -347.040962)
		(end 259.366512 -347.040962)
		(width 0.14732)
		(layer "In11.Cu")
		(net "UPI_CPU1_CPU0_P2P2_DN<19>")
	)
	(segment
		(start 257.195574 -348.38767)
		(end 257.195574 -348.823534)
		(width 0.14732)
		(layer "In11.Cu")
		(net "UPI_CPU1_CPU0_P2P2_DN<19>")
	)
	(segment
		(start 278.708612 -326.566022)
		(end 278.708612 -327.690226)
		(width 0.14732)
		(layer "In11.Cu")
		(net "UPI_CPU1_CPU0_P2P2_DN<19>")
	)
	(segment
		(start 105.736898 -283.219906)
		(end 105.736898 -283.205682)
		(width 0.0889)
		(layer "In11.Cu")
		(net "UPI_CPU1_CPU0_P2P2_DN<19>")
	)
	(segment
		(start 249.177556 -356.047294)
		(end 248.867676 -355.604826)
		(width 0.14732)
		(layer "In11.Cu")
		(net "UPI_CPU1_CPU0_P2P2_DN<19>")
	)
	(segment
		(start 309.647336 -316.108334)
		(end 308.920642 -316.835028)
		(width 0.14732)
		(layer "In11.Cu")
		(net "UPI_CPU1_CPU0_P2P2_DN<19>")
	)
	(segment
		(start 259.992114 -346.623132)
		(end 259.574284 -347.040962)
		(width 0.14732)
		(layer "In11.Cu")
		(net "UPI_CPU1_CPU0_P2P2_DN<19>")
	)
	(segment
		(start 103.899208 -291.496496)
		(end 103.899208 -291.474398)
		(width 0.0889)
		(layer "In11.Cu")
		(net "UPI_CPU1_CPU0_P2P2_DN<19>")
	)
	(segment
		(start 248.867676 -355.604826)
		(end 248.438924 -355.52888)
		(width 0.14732)
		(layer "In11.Cu")
		(net "UPI_CPU1_CPU0_P2P2_DN<19>")
	)
	(segment
		(start 233.251756 -366.1664)
		(end 232.582466 -366.635538)
		(width 0.14732)
		(layer "In11.Cu")
		(net "UPI_CPU1_CPU0_P2P2_DN<19>")
	)
	(segment
		(start 82.342228 -317.394082)
		(end 98.22307 -304.361342)
		(width 0.14732)
		(layer "In11.Cu")
		(net "UPI_CPU1_CPU0_P2P2_DN<19>")
	)
	(segment
		(start 284.121098 -325.784718)
		(end 279.489916 -325.784718)
		(width 0.14732)
		(layer "In11.Cu")
		(net "UPI_CPU1_CPU0_P2P2_DN<19>")
	)
	(segment
		(start 258.63931 -346.749624)
		(end 257.870706 -347.518228)
		(width 0.14732)
		(layer "In11.Cu")
		(net "UPI_CPU1_CPU0_P2P2_DN<19>")
	)
	(segment
		(start 243.972842 -358.657398)
		(end 243.896896 -359.08615)
		(width 0.14732)
		(layer "In11.Cu")
		(net "UPI_CPU1_CPU0_P2P2_DN<19>")
	)
	(segment
		(start 247.693688 -356.42677)
		(end 248.003822 -356.869492)
		(width 0.14732)
		(layer "In11.Cu")
		(net "UPI_CPU1_CPU0_P2P2_DN<19>")
	)
	(segment
		(start 332.322424 -293.597076)
		(end 330.365354 -300.04766)
		(width 0.14732)
		(layer "In11.Cu")
		(net "UPI_CPU1_CPU0_P2P2_DN<19>")
	)
	(segment
		(start 105.266744 -284.043628)
		(end 105.266744 -284.033722)
		(width 0.0889)
		(layer "In11.Cu")
		(net "UPI_CPU1_CPU0_P2P2_DN<19>")
	)
	(segment
		(start 305.576478 -320.069718)
		(end 305.576478 -320.546984)
		(width 0.14732)
		(layer "In11.Cu")
		(net "UPI_CPU1_CPU0_P2P2_DN<19>")
	)
	(segment
		(start 273.644868 -331.086206)
		(end 273.209512 -331.08646)
		(width 0.14732)
		(layer "In11.Cu")
		(net "UPI_CPU1_CPU0_P2P2_DN<19>")
	)
	(segment
		(start 234.195112 -366.720882)
		(end 233.990388 -366.684814)
		(width 0.14732)
		(layer "In11.Cu")
		(net "UPI_CPU1_CPU0_P2P2_DN<19>")
	)
	(segment
		(start 255.556766 -350.462342)
		(end 255.664716 -350.570292)
		(width 0.14732)
		(layer "In11.Cu")
		(net "UPI_CPU1_CPU0_P2P2_DN<19>")
	)
	(segment
		(start 103.56596 -288.597848)
		(end 103.570278 -288.595308)
		(width 0.0889)
		(layer "In11.Cu")
		(net "UPI_CPU1_CPU0_P2P2_DN<19>")
	)
	(segment
		(start 235.578904 -364.912656)
		(end 235.150152 -364.83671)
		(width 0.14732)
		(layer "In11.Cu")
		(net "UPI_CPU1_CPU0_P2P2_DN<19>")
	)
	(segment
		(start 247.27916 -357.376984)
		(end 246.96928 -356.934516)
		(width 0.14732)
		(layer "In11.Cu")
		(net "UPI_CPU1_CPU0_P2P2_DN<19>")
	)
	(segment
		(start 161.07918 -376.57913)
		(end 126.235206 -376.57913)
		(width 0.14732)
		(layer "In11.Cu")
		(net "UPI_CPU1_CPU0_P2P2_DN<19>")
	)
	(segment
		(start 238.277654 -362.646468)
		(end 238.201708 -363.07522)
		(width 0.14732)
		(layer "In11.Cu")
		(net "UPI_CPU1_CPU0_P2P2_DN<19>")
	)
	(segment
		(start 285.129478 -324.776338)
		(end 284.121098 -325.784718)
		(width 0.14732)
		(layer "In11.Cu")
		(net "UPI_CPU1_CPU0_P2P2_DN<19>")
	)
	(segment
		(start 248.003822 -356.869492)
		(end 247.967754 -357.073962)
		(width 0.14732)
		(layer "In11.Cu")
		(net "UPI_CPU1_CPU0_P2P2_DN<19>")
	)
	(segment
		(start 271.334992 -334.855566)
		(end 271.334992 -335.063846)
		(width 0.14732)
		(layer "In11.Cu")
		(net "UPI_CPU1_CPU0_P2P2_DN<19>")
	)
	(segment
		(start 254.4953 -351.087944)
		(end 253.824232 -351.759012)
		(width 0.14732)
		(layer "In11.Cu")
		(net "UPI_CPU1_CPU0_P2P2_DN<19>")
	)
	(segment
		(start 261.00532 -345.402154)
		(end 260.713982 -345.110816)
		(width 0.14732)
		(layer "In11.Cu")
		(net "UPI_CPU1_CPU0_P2P2_DN<19>")
	)
	(segment
		(start 303.896776 -322.457826)
		(end 303.694592 -322.425822)
		(width 0.14732)
		(layer "In11.Cu")
		(net "UPI_CPU1_CPU0_P2P2_DN<19>")
	)
	(segment
		(start 270.887444 -332.38059)
		(end 270.452088 -332.38059)
		(width 0.14732)
		(layer "In11.Cu")
		(net "UPI_CPU1_CPU0_P2P2_DN<19>")
	)
	(segment
		(start 103.277924 -296.226738)
		(end 103.277924 -295.858438)
		(width 0.14732)
		(layer "In11.Cu")
		(net "UPI_CPU1_CPU0_P2P2_DN<19>")
	)
	(segment
		(start 235.150152 -364.83671)
		(end 234.480862 -365.305848)
		(width 0.14732)
		(layer "In11.Cu")
		(net "UPI_CPU1_CPU0_P2P2_DN<19>")
	)
	(segment
		(start 246.105426 -358.199182)
		(end 246.069358 -358.403652)
		(width 0.14732)
		(layer "In11.Cu")
		(net "UPI_CPU1_CPU0_P2P2_DN<19>")
	)
	(segment
		(start 105.48493 -282.676854)
		(end 105.641394 -282.405836)
		(width 0.0889)
		(layer "In11.Cu")
		(net "UPI_CPU1_CPU0_P2P2_DN<19>")
	)
	(segment
		(start 259.075174 -346.749624)
		(end 258.63931 -346.749624)
		(width 0.14732)
		(layer "In11.Cu")
		(net "UPI_CPU1_CPU0_P2P2_DN<19>")
	)
	(segment
		(start 315.79947 -313.57062)
		(end 315.65469 -313.42584)
		(width 0.14732)
		(layer "In11.Cu")
		(net "UPI_CPU1_CPU0_P2P2_DN<19>")
	)
	(segment
		(start 237.048548 -363.50702)
		(end 236.379258 -363.976158)
		(width 0.14732)
		(layer "In11.Cu")
		(net "UPI_CPU1_CPU0_P2P2_DN<19>")
	)
	(segment
		(start 301.403766 -323.939408)
		(end 299.38472 -324.776338)
		(width 0.14732)
		(layer "In11.Cu")
		(net "UPI_CPU1_CPU0_P2P2_DN<19>")
	)
	(segment
		(start 338.265008 -286.798512)
		(end 338.25942 -286.801814)
		(width 0.0889)
		(layer "In11.Cu")
		(net "UPI_CPU1_CPU0_P2P2_DN<19>")
	)
	(segment
		(start 245.585488 -358.742742)
		(end 245.380764 -358.706674)
		(width 0.14732)
		(layer "In11.Cu")
		(net "UPI_CPU1_CPU0_P2P2_DN<19>")
	)
	(segment
		(start 233.990388 -366.684814)
		(end 233.680508 -366.242346)
		(width 0.14732)
		(layer "In11.Cu")
		(net "UPI_CPU1_CPU0_P2P2_DN<19>")
	)
	(segment
		(start 305.576478 -319.411858)
		(end 305.431698 -319.556638)
		(width 0.14732)
		(layer "In11.Cu")
		(net "UPI_CPU1_CPU0_P2P2_DN<19>")
	)
	(segment
		(start 241.9985 -360.41584)
		(end 242.308634 -360.858562)
		(width 0.14732)
		(layer "In11.Cu")
		(net "UPI_CPU1_CPU0_P2P2_DN<19>")
	)
	(segment
		(start 102.938834 -298.003468)
		(end 103.133144 -297.533568)
		(width 0.14732)
		(layer "In11.Cu")
		(net "UPI_CPU1_CPU0_P2P2_DN<19>")
	)
	(segment
		(start 305.431698 -319.556638)
		(end 305.431698 -319.924938)
		(width 0.14732)
		(layer "In11.Cu")
		(net "UPI_CPU1_CPU0_P2P2_DN<19>")
	)
	(segment
		(start 303.396396 -322.641976)
		(end 303.364138 -322.844414)
		(width 0.14732)
		(layer "In11.Cu")
		(net "UPI_CPU1_CPU0_P2P2_DN<19>")
	)
	(segment
		(start 263.26973 -343.345516)
		(end 262.8519 -343.763346)
		(width 0.14732)
		(layer "In11.Cu")
		(net "UPI_CPU1_CPU0_P2P2_DN<19>")
	)
	(segment
		(start 240.410238 -362.188252)
		(end 240.37417 -362.392722)
		(width 0.14732)
		(layer "In11.Cu")
		(net "UPI_CPU1_CPU0_P2P2_DN<19>")
	)
	(segment
		(start 242.272566 -361.063032)
		(end 241.788696 -361.402122)
		(width 0.14732)
		(layer "In11.Cu")
		(net "UPI_CPU1_CPU0_P2P2_DN<19>")
	)
	(segment
		(start 268.886432 -336.502502)
		(end 268.678152 -336.502502)
		(width 0.14732)
		(layer "In11.Cu")
		(net "UPI_CPU1_CPU0_P2P2_DN<19>")
	)
	(segment
		(start 337.979766 -284.025848)
		(end 337.979766 -284.033722)
		(width 0.0889)
		(layer "In11.Cu")
		(net "UPI_CPU1_CPU0_P2P2_DN<19>")
	)
	(segment
		(start 272.631154 -332.09992)
		(end 273.360896 -332.829662)
		(width 0.14732)
		(layer "In11.Cu")
		(net "UPI_CPU1_CPU0_P2P2_DN<19>")
	)
	(segment
		(start 260.713982 -345.110816)
		(end 260.278118 -345.110816)
		(width 0.14732)
		(layer "In11.Cu")
		(net "UPI_CPU1_CPU0_P2P2_DN<19>")
	)
	(segment
		(start 269.87373 -333.394304)
		(end 271.334992 -334.855566)
		(width 0.14732)
		(layer "In11.Cu")
		(net "UPI_CPU1_CPU0_P2P2_DN<19>")
	)
	(segment
		(start 312.23839 -315.212476)
		(end 311.45734 -315.212476)
		(width 0.14732)
		(layer "In11.Cu")
		(net "UPI_CPU1_CPU0_P2P2_DN<19>")
	)
	(segment
		(start 78.600808 -364.089442)
		(end 76.119736 -361.60837)
		(width 0.14732)
		(layer "In11.Cu")
		(net "UPI_CPU1_CPU0_P2P2_DN<19>")
	)
	(segment
		(start 266.02563 -339.155024)
		(end 266.02563 -339.363304)
		(width 0.14732)
		(layer "In11.Cu")
		(net "UPI_CPU1_CPU0_P2P2_DN<19>")
	)
	(segment
		(start 334.448404 -291.255196)
		(end 332.75651 -292.946836)
		(width 0.14732)
		(layer "In11.Cu")
		(net "UPI_CPU1_CPU0_P2P2_DN<19>")
	)
	(segment
		(start 250.766072 -354.275136)
		(end 250.33732 -354.19919)
		(width 0.14732)
		(layer "In11.Cu")
		(net "UPI_CPU1_CPU0_P2P2_DN<19>")
	)
	(segment
		(start 232.816654 -367.507012)
		(end 232.780586 -367.711482)
		(width 0.14732)
		(layer "In11.Cu")
		(net "UPI_CPU1_CPU0_P2P2_DN<19>")
	)
	(segment
		(start 279.489916 -325.784718)
		(end 278.708612 -326.566022)
		(width 0.14732)
		(layer "In11.Cu")
		(net "UPI_CPU1_CPU0_P2P2_DN<19>")
	)
	(segment
		(start 247.967754 -357.073962)
		(end 247.483884 -357.413052)
		(width 0.14732)
		(layer "In11.Cu")
		(net "UPI_CPU1_CPU0_P2P2_DN<19>")
	)
	(segment
		(start 302.457104 -323.502782)
		(end 302.011588 -323.68744)
		(width 0.14732)
		(layer "In11.Cu")
		(net "UPI_CPU1_CPU0_P2P2_DN<19>")
	)
	(segment
		(start 242.074446 -359.987088)
		(end 241.9985 -360.41584)
		(width 0.14732)
		(layer "In11.Cu")
		(net "UPI_CPU1_CPU0_P2P2_DN<19>")
	)
	(segment
		(start 103.133144 -296.371518)
		(end 103.277924 -296.226738)
		(width 0.14732)
		(layer "In11.Cu")
		(net "UPI_CPU1_CPU0_P2P2_DN<19>")
	)
	(segment
		(start 105.50906 -282.766008)
		(end 105.48493 -282.676854)
		(width 0.0889)
		(layer "In11.Cu")
		(net "UPI_CPU1_CPU0_P2P2_DN<19>")
	)
	(segment
		(start 104.03586 -287.783778)
		(end 104.04475 -287.778698)
		(width 0.0889)
		(layer "In11.Cu")
		(net "UPI_CPU1_CPU0_P2P2_DN<19>")
	)
	(segment
		(start 105.452672 -283.710126)
		(end 105.454196 -283.709364)
		(width 0.0889)
		(layer "In11.Cu")
		(net "UPI_CPU1_CPU0_P2P2_DN<19>")
	)
	(segment
		(start 246.96928 -356.934516)
		(end 246.540528 -356.85857)
		(width 0.14732)
		(layer "In11.Cu")
		(net "UPI_CPU1_CPU0_P2P2_DN<19>")
	)
	(segment
		(start 267.039344 -338.14131)
		(end 265.9888 -337.090766)
		(width 0.14732)
		(layer "In11.Cu")
		(net "UPI_CPU1_CPU0_P2P2_DN<19>")
	)
	(segment
		(start 239.8903 -362.731812)
		(end 239.685576 -362.695744)
		(width 0.14732)
		(layer "In11.Cu")
		(net "UPI_CPU1_CPU0_P2P2_DN<19>")
	)
	(segment
		(start 264.386822 -341.002112)
		(end 262.978392 -342.410542)
		(width 0.14732)
		(layer "In11.Cu")
		(net "UPI_CPU1_CPU0_P2P2_DN<19>")
	)
	(segment
		(start 259.366512 -347.040962)
		(end 259.075174 -346.749624)
		(width 0.14732)
		(layer "In11.Cu")
		(net "UPI_CPU1_CPU0_P2P2_DN<19>")
	)
	(segment
		(start 313.22137 -314.229496)
		(end 313.016646 -314.229496)
		(width 0.14732)
		(layer "In11.Cu")
		(net "UPI_CPU1_CPU0_P2P2_DN<19>")
	)
	(segment
		(start 337.79968 -287.60928)
		(end 337.793838 -287.612836)
		(width 0.0889)
		(layer "In11.Cu")
		(net "UPI_CPU1_CPU0_P2P2_DN<19>")
	)
	(segment
		(start 240.100104 -361.74553)
		(end 240.410238 -362.188252)
		(width 0.14732)
		(layer "In11.Cu")
		(net "UPI_CPU1_CPU0_P2P2_DN<19>")
	)
	(segment
		(start 253.82347 -351.75952)
		(end 251.566426 -353.338384)
		(width 0.14732)
		(layer "In11.Cu")
		(net "UPI_CPU1_CPU0_P2P2_DN<19>")
	)
	(segment
		(start 103.133144 -292.797484)
		(end 103.899208 -292.03142)
		(width 0.14732)
		(layer "In11.Cu")
		(net "UPI_CPU1_CPU0_P2P2_DN<19>")
	)
	(segment
		(start 306.336954 -317.886588)
		(end 305.83632 -318.386968)
		(width 0.14732)
		(layer "In11.Cu")
		(net "UPI_CPU1_CPU0_P2P2_DN<19>")
	)
	(segment
		(start 338.2518 -284.51683)
		(end 338.262468 -284.52318)
		(width 0.0889)
		(layer "In11.Cu")
		(net "UPI_CPU1_CPU0_P2P2_DN<19>")
	)
	(segment
		(start 269.87373 -332.958948)
		(end 269.87373 -333.394304)
		(width 0.14732)
		(layer "In11.Cu")
		(net "UPI_CPU1_CPU0_P2P2_DN<19>")
	)
	(segment
		(start 244.642132 -358.18826)
		(end 243.972842 -358.657398)
		(width 0.14732)
		(layer "In11.Cu")
		(net "UPI_CPU1_CPU0_P2P2_DN<19>")
	)
	(segment
		(start 253.823978 -351.759012)
		(end 253.82347 -351.75952)
		(width 0.14732)
		(layer "In11.Cu")
		(net "UPI_CPU1_CPU0_P2P2_DN<19>")
	)
	(segment
		(start 270.452088 -332.38059)
		(end 269.87373 -332.958948)
		(width 0.14732)
		(layer "In11.Cu")
		(net "UPI_CPU1_CPU0_P2P2_DN<19>")
	)
	(segment
		(start 305.431698 -319.924938)
		(end 305.576478 -320.069718)
		(width 0.14732)
		(layer "In11.Cu")
		(net "UPI_CPU1_CPU0_P2P2_DN<19>")
	)
	(segment
		(start 266.613894 -336.030316)
		(end 266.613894 -336.465672)
		(width 0.14732)
		(layer "In11.Cu")
		(net "UPI_CPU1_CPU0_P2P2_DN<19>")
	)
	(segment
		(start 249.66803 -354.668328)
		(end 249.592084 -355.09708)
		(width 0.14732)
		(layer "In11.Cu")
		(net "UPI_CPU1_CPU0_P2P2_DN<19>")
	)
	(segment
		(start 241.788696 -361.402122)
		(end 241.583972 -361.366054)
		(width 0.14732)
		(layer "In11.Cu")
		(net "UPI_CPU1_CPU0_P2P2_DN<19>")
	)
	(segment
		(start 243.687092 -360.072432)
		(end 243.482368 -360.036364)
		(width 0.14732)
		(layer "In11.Cu")
		(net "UPI_CPU1_CPU0_P2P2_DN<19>")
	)
	(segment
		(start 257.870706 -347.518228)
		(end 257.870706 -347.71203)
		(width 0.14732)
		(layer "In11.Cu")
		(net "UPI_CPU1_CPU0_P2P2_DN<19>")
	)
	(segment
		(start 243.482368 -360.036364)
		(end 243.172488 -359.593896)
		(width 0.14732)
		(layer "In11.Cu")
		(net "UPI_CPU1_CPU0_P2P2_DN<19>")
	)
	(segment
		(start 271.334992 -335.063846)
		(end 270.72717 -335.671668)
		(width 0.14732)
		(layer "In11.Cu")
		(net "UPI_CPU1_CPU0_P2P2_DN<19>")
	)
	(segment
		(start 330.365354 -300.04766)
		(end 316.842394 -313.57062)
		(width 0.14732)
		(layer "In11.Cu")
		(net "UPI_CPU1_CPU0_P2P2_DN<19>")
	)
	(segment
		(start 232.296716 -368.050572)
		(end 232.091992 -368.014504)
		(width 0.14732)
		(layer "In11.Cu")
		(net "UPI_CPU1_CPU0_P2P2_DN<19>")
	)
	(segment
		(start 270.72717 -335.671668)
		(end 269.717266 -335.671668)
		(width 0.14732)
		(layer "In11.Cu")
		(net "UPI_CPU1_CPU0_P2P2_DN<19>")
	)
	(segment
		(start 212.31225 -371.881654)
		(end 200.018396 -369.713764)
		(width 0.14732)
		(layer "In11.Cu")
		(net "UPI_CPU1_CPU0_P2P2_DN<19>")
	)
	(segment
		(start 240.17605 -361.316778)
		(end 240.100104 -361.74553)
		(width 0.14732)
		(layer "In11.Cu")
		(net "UPI_CPU1_CPU0_P2P2_DN<19>")
	)
	(segment
		(start 245.795292 -357.75646)
		(end 246.105426 -358.199182)
		(width 0.14732)
		(layer "In11.Cu")
		(net "UPI_CPU1_CPU0_P2P2_DN<19>")
	)
	(segment
		(start 237.4773 -363.582966)
		(end 237.048548 -363.50702)
		(width 0.14732)
		(layer "In11.Cu")
		(net "UPI_CPU1_CPU0_P2P2_DN<19>")
	)
	(segment
		(start 265.608816 -339.780118)
		(end 265.400536 -339.780118)
		(width 0.14732)
		(layer "In11.Cu")
		(net "UPI_CPU1_CPU0_P2P2_DN<19>")
	)
	(segment
		(start 261.339584 -344.04935)
		(end 261.339584 -344.485214)
		(width 0.14732)
		(layer "In11.Cu")
		(net "UPI_CPU1_CPU0_P2P2_DN<19>")
	)
	(segment
		(start 234.480862 -365.305848)
		(end 234.404916 -365.7346)
		(width 0.14732)
		(layer "In11.Cu")
		(net "UPI_CPU1_CPU0_P2P2_DN<19>")
	)
	(segment
		(start 315.14161 -313.57062)
		(end 313.880246 -313.57062)
		(width 0.14732)
		(layer "In11.Cu")
		(net "UPI_CPU1_CPU0_P2P2_DN<19>")
	)
	(segment
		(start 250.33732 -354.19919)
		(end 249.66803 -354.668328)
		(width 0.14732)
		(layer "In11.Cu")
		(net "UPI_CPU1_CPU0_P2P2_DN<19>")
	)
	(segment
		(start 308.920642 -316.835028)
		(end 308.715918 -316.835028)
		(width 0.14732)
		(layer "In11.Cu")
		(net "UPI_CPU1_CPU0_P2P2_DN<19>")
	)
	(segment
		(start 338.267802 -285.169102)
		(end 338.265008 -285.170626)
		(width 0.0889)
		(layer "In11.Cu")
		(net "UPI_CPU1_CPU0_P2P2_DN<19>")
	)
	(segment
		(start 126.235206 -376.57913)
		(end 98.996754 -372.538752)
		(width 0.14732)
		(layer "In11.Cu")
		(net "UPI_CPU1_CPU0_P2P2_DN<19>")
	)
	(segment
		(start 267.247624 -338.14131)
		(end 267.039344 -338.14131)
		(width 0.14732)
		(layer "In11.Cu")
		(net "UPI_CPU1_CPU0_P2P2_DN<19>")
	)
	(segment
		(start 234.678982 -366.381792)
		(end 234.195112 -366.720882)
		(width 0.14732)
		(layer "In11.Cu")
		(net "UPI_CPU1_CPU0_P2P2_DN<19>")
	)
	(segment
		(start 272.6309 -331.665072)
		(end 272.631154 -332.09992)
		(width 0.14732)
		(layer "In11.Cu")
		(net "UPI_CPU1_CPU0_P2P2_DN<19>")
	)
	(segment
		(start 256.134108 -349.449136)
		(end 255.556766 -350.026478)
		(width 0.14732)
		(layer "In11.Cu")
		(net "UPI_CPU1_CPU0_P2P2_DN<19>")
	)
	(segment
		(start 261.213092 -345.402154)
		(end 261.00532 -345.402154)
		(width 0.14732)
		(layer "In11.Cu")
		(net "UPI_CPU1_CPU0_P2P2_DN<19>")
	)
	(segment
		(start 98.22307 -304.361342)
		(end 102.938834 -298.003468)
		(width 0.14732)
		(layer "In11.Cu")
		(net "UPI_CPU1_CPU0_P2P2_DN<19>")
	)
	(segment
		(start 231.353106 -367.49609)
		(end 229.389432 -368.871246)
		(width 0.14732)
		(layer "In11.Cu")
		(net "UPI_CPU1_CPU0_P2P2_DN<19>")
	)
	(segment
		(start 315.28639 -313.42584)
		(end 315.14161 -313.57062)
		(width 0.14732)
		(layer "In11.Cu")
		(net "UPI_CPU1_CPU0_P2P2_DN<19>")
	)
	(segment
		(start 246.069358 -358.403652)
		(end 245.585488 -358.742742)
		(width 0.14732)
		(layer "In11.Cu")
		(net "UPI_CPU1_CPU0_P2P2_DN<19>")
	)
	(segment
		(start 255.664716 -350.778064)
		(end 255.246886 -351.195894)
		(width 0.14732)
		(layer "In11.Cu")
		(net "UPI_CPU1_CPU0_P2P2_DN<19>")
	)
	(segment
		(start 265.9888 -337.090766)
		(end 265.553444 -337.090766)
		(width 0.14732)
		(layer "In11.Cu")
		(net "UPI_CPU1_CPU0_P2P2_DN<19>")
	)
	(segment
		(start 274.37461 -331.815948)
		(end 273.644868 -331.086206)
		(width 0.14732)
		(layer "In11.Cu")
		(net "UPI_CPU1_CPU0_P2P2_DN<19>")
	)
	(segment
		(start 238.475774 -363.722412)
		(end 237.991904 -364.061502)
		(width 0.14732)
		(layer "In11.Cu")
		(net "UPI_CPU1_CPU0_P2P2_DN<19>")
	)
	(segment
		(start 310.561482 -316.108334)
		(end 309.647336 -316.108334)
		(width 0.14732)
		(layer "In11.Cu")
		(net "UPI_CPU1_CPU0_P2P2_DN<19>")
	)
	(segment
		(start 338.252054 -286.144462)
		(end 338.262722 -286.150812)
		(width 0.0889)
		(layer "In11.Cu")
		(net "UPI_CPU1_CPU0_P2P2_DN<19>")
	)
	(segment
		(start 307.869082 -317.886588)
		(end 306.336954 -317.886588)
		(width 0.14732)
		(layer "In11.Cu")
		(net "UPI_CPU1_CPU0_P2P2_DN<19>")
	)
	(segment
		(start 240.37417 -362.392722)
		(end 239.8903 -362.731812)
		(width 0.14732)
		(layer "In11.Cu")
		(net "UPI_CPU1_CPU0_P2P2_DN<19>")
	)
	(segment
		(start 249.902218 -355.539802)
		(end 249.86615 -355.744272)
		(width 0.14732)
		(layer "In11.Cu")
		(net "UPI_CPU1_CPU0_P2P2_DN<19>")
	)
	(segment
		(start 247.769634 -355.998018)
		(end 247.693688 -356.42677)
		(width 0.14732)
		(layer "In11.Cu")
		(net "UPI_CPU1_CPU0_P2P2_DN<19>")
	)
	(segment
		(start 103.277924 -295.858438)
		(end 103.133144 -295.713658)
		(width 0.14732)
		(layer "In11.Cu")
		(net "UPI_CPU1_CPU0_P2P2_DN<19>")
	)
	(segment
		(start 263.336278 -339.307932)
		(end 263.336278 -339.743288)
		(width 0.14732)
		(layer "In11.Cu")
		(net "UPI_CPU1_CPU0_P2P2_DN<19>")
	)
	(segment
		(start 255.039114 -351.195894)
		(end 254.931164 -351.087944)
		(width 0.14732)
		(layer "In11.Cu")
		(net "UPI_CPU1_CPU0_P2P2_DN<19>")
	)
	(segment
		(start 264.975086 -338.10448)
		(end 266.02563 -339.155024)
		(width 0.14732)
		(layer "In11.Cu")
		(net "UPI_CPU1_CPU0_P2P2_DN<19>")
	)
	(segment
		(start 255.246886 -351.195894)
		(end 255.039114 -351.195894)
		(width 0.14732)
		(layer "In11.Cu")
		(net "UPI_CPU1_CPU0_P2P2_DN<19>")
	)
	(segment
		(start 261.339584 -344.485214)
		(end 261.630922 -344.776552)
		(width 0.14732)
		(layer "In11.Cu")
		(net "UPI_CPU1_CPU0_P2P2_DN<19>")
	)
	(segment
		(start 315.65469 -313.42584)
		(end 315.28639 -313.42584)
		(width 0.14732)
		(layer "In11.Cu")
		(net "UPI_CPU1_CPU0_P2P2_DN<19>")
	)
	(segment
		(start 338.267802 -286.796988)
		(end 338.265008 -286.798512)
		(width 0.0889)
		(layer "In11.Cu")
		(net "UPI_CPU1_CPU0_P2P2_DN<19>")
	)
	(segment
		(start 76.119736 -361.60837)
		(end 72.549258 -352.997008)
		(width 0.14732)
		(layer "In11.Cu")
		(net "UPI_CPU1_CPU0_P2P2_DN<19>")
	)
	(segment
		(start 337.793838 -287.612836)
		(end 337.782154 -287.619694)
		(width 0.0889)
		(layer "In11.Cu")
		(net "UPI_CPU1_CPU0_P2P2_DN<19>")
	)
	(segment
		(start 240.84534 -360.84764)
		(end 240.17605 -361.316778)
		(width 0.14732)
		(layer "In11.Cu")
		(net "UPI_CPU1_CPU0_P2P2_DN<19>")
	)
	(segment
		(start 337.322414 -288.427668)
		(end 337.311746 -288.434018)
		(width 0.0889)
		(layer "In11.Cu")
		(net "UPI_CPU1_CPU0_P2P2_DN<19>")
	)
	(segment
		(start 236.613446 -364.847632)
		(end 236.577378 -365.052102)
		(width 0.14732)
		(layer "In11.Cu")
		(net "UPI_CPU1_CPU0_P2P2_DN<19>")
	)
	(segment
		(start 261.916926 -343.472008)
		(end 261.339584 -344.04935)
		(width 0.14732)
		(layer "In11.Cu")
		(net "UPI_CPU1_CPU0_P2P2_DN<19>")
	)
	(segment
		(start 269.717266 -335.671668)
		(end 268.886432 -336.502502)
		(width 0.14732)
		(layer "In11.Cu")
		(net "UPI_CPU1_CPU0_P2P2_DN<19>")
	)
	(segment
		(start 305.28006 -321.261994)
		(end 304.578512 -321.963288)
		(width 0.14732)
		(layer "In11.Cu")
		(net "UPI_CPU1_CPU0_P2P2_DN<19>")
	)
	(segment
		(start 264.386822 -340.793832)
		(end 264.386822 -341.002112)
		(width 0.14732)
		(layer "In11.Cu")
		(net "UPI_CPU1_CPU0_P2P2_DN<19>")
	)
	(segment
		(start 338.265008 -285.170626)
		(end 338.25942 -285.173928)
		(width 0.0889)
		(layer "In11.Cu")
		(net "UPI_CPU1_CPU0_P2P2_DN<19>")
	)
	(segment
		(start 313.880246 -313.57062)
		(end 313.22137 -314.229496)
		(width 0.14732)
		(layer "In11.Cu")
		(net "UPI_CPU1_CPU0_P2P2_DN<19>")
	)
	(segment
		(start 103.133144 -297.533568)
		(end 103.133144 -296.371518)
		(width 0.14732)
		(layer "In11.Cu")
		(net "UPI_CPU1_CPU0_P2P2_DN<19>")
	)
	(segment
		(start 104.797098 -284.847538)
		(end 104.797098 -284.838902)
		(width 0.0889)
		(layer "In11.Cu")
		(net "UPI_CPU1_CPU0_P2P2_DN<19>")
	)
	(segment
		(start 245.070884 -358.264206)
		(end 244.642132 -358.18826)
		(width 0.14732)
		(layer "In11.Cu")
		(net "UPI_CPU1_CPU0_P2P2_DN<19>")
	)
	(segment
		(start 336.665316 -282.405836)
		(end 336.97799 -282.405836)
		(width 0.0889)
		(layer "In11.Cu")
		(net "UPI_CPU1_CPU0_P2P2_DN<19>")
	)
	(segment
		(start 74.569066 -325.167244)
		(end 82.342228 -317.394082)
		(width 0.14732)
		(layer "In11.Cu")
		(net "UPI_CPU1_CPU0_P2P2_DN<19>")
	)
	(segment
		(start 242.743736 -359.51795)
		(end 242.074446 -359.987088)
		(width 0.14732)
		(layer "In11.Cu")
		(net "UPI_CPU1_CPU0_P2P2_DN<19>")
	)
	(segment
		(start 104.51719 -285.335472)
		(end 104.520492 -285.33344)
		(width 0.0889)
		(layer "In11.Cu")
		(net "UPI_CPU1_CPU0_P2P2_DN<19>")
	)
	(segment
		(start 103.570278 -288.595308)
		(end 103.57485 -288.592768)
		(width 0.0889)
		(layer "In11.Cu")
		(net "UPI_CPU1_CPU0_P2P2_DN<19>")
	)
	(segment
		(start 238.201708 -363.07522)
		(end 238.511842 -363.517942)
		(width 0.14732)
		(layer "In11.Cu")
		(net "UPI_CPU1_CPU0_P2P2_DN<19>")
	)
	(segment
		(start 233.680508 -366.242346)
		(end 233.251756 -366.1664)
		(width 0.14732)
		(layer "In11.Cu")
		(net "UPI_CPU1_CPU0_P2P2_DN<19>")
	)
	(segment
		(start 267.192252 -335.451958)
		(end 266.613894 -336.030316)
		(width 0.14732)
		(layer "In11.Cu")
		(net "UPI_CPU1_CPU0_P2P2_DN<19>")
	)
	(segment
		(start 304.578512 -321.963288)
		(end 303.896776 -322.457826)
		(width 0.14732)
		(layer "In11.Cu")
		(net "UPI_CPU1_CPU0_P2P2_DN<19>")
	)
	(segment
		(start 299.38472 -324.776338)
		(end 285.129478 -324.776338)
		(width 0.14732)
		(layer "In11.Cu")
		(net "UPI_CPU1_CPU0_P2P2_DN<19>")
	)
	(segment
		(start 308.45506 -317.095886)
		(end 308.45506 -317.30061)
		(width 0.14732)
		(layer "In11.Cu")
		(net "UPI_CPU1_CPU0_P2P2_DN<19>")
	)
	(segment
		(start 274.58289 -331.815948)
		(end 274.37461 -331.815948)
		(width 0.14732)
		(layer "In11.Cu")
		(net "UPI_CPU1_CPU0_P2P2_DN<19>")
	)
	(segment
		(start 256.885694 -349.557086)
		(end 256.677922 -349.557086)
		(width 0.14732)
		(layer "In11.Cu")
		(net "UPI_CPU1_CPU0_P2P2_DN<19>")
	)
	(segment
		(start 265.400536 -339.780118)
		(end 264.349992 -338.729574)
		(width 0.14732)
		(layer "In11.Cu")
		(net "UPI_CPU1_CPU0_P2P2_DN<19>")
	)
	(segment
		(start 337.782154 -287.619694)
		(end 337.778852 -287.621726)
		(width 0.0889)
		(layer "In11.Cu")
		(net "UPI_CPU1_CPU0_P2P2_DN<19>")
	)
	(segment
		(start 262.978392 -342.846406)
		(end 263.26973 -343.137744)
		(width 0.14732)
		(layer "In11.Cu")
		(net "UPI_CPU1_CPU0_P2P2_DN<19>")
	)
	(segment
		(start 72.549258 -335.17078)
		(end 73.156826 -328.99985)
		(width 0.14732)
		(layer "In11.Cu")
		(net "UPI_CPU1_CPU0_P2P2_DN<19>")
	)
	(segment
		(start 267.664438 -337.724496)
		(end 267.247624 -338.14131)
		(width 0.14732)
		(layer "In11.Cu")
		(net "UPI_CPU1_CPU0_P2P2_DN<19>")
	)
	(segment
		(start 105.447338 -283.713174)
		(end 105.45064 -283.711396)
		(width 0.0889)
		(layer "In11.Cu")
		(net "UPI_CPU1_CPU0_P2P2_DN<19>")
	)
	(segment
		(start 261.630922 -344.776552)
		(end 261.630922 -344.984324)
		(width 0.14732)
		(layer "In11.Cu")
		(net "UPI_CPU1_CPU0_P2P2_DN<19>")
	)
	(segment
		(start 264.975086 -337.669124)
		(end 264.975086 -338.10448)
		(width 0.14732)
		(layer "In11.Cu")
		(net "UPI_CPU1_CPU0_P2P2_DN<19>")
	)
	(segment
		(start 308.45506 -317.30061)
		(end 307.869082 -317.886588)
		(width 0.14732)
		(layer "In11.Cu")
		(net "UPI_CPU1_CPU0_P2P2_DN<19>")
	)
	(segment
		(start 337.802728 -287.607502)
		(end 337.79968 -287.60928)
		(width 0.0889)
		(layer "In11.Cu")
		(net "UPI_CPU1_CPU0_P2P2_DN<19>")
	)
	(segment
		(start 337.039712 -289.261804)
		(end 336.997548 -289.303968)
		(width 0.0889)
		(layer "In11.Cu")
		(net "UPI_CPU1_CPU0_P2P2_DN<19>")
	)
	(segment
		(start 257.303524 -348.931484)
		(end 257.303524 -349.139256)
		(width 0.14732)
		(layer "In11.Cu")
		(net "UPI_CPU1_CPU0_P2P2_DN<19>")
	)
	(segment
		(start 234.71505 -366.177322)
		(end 234.678982 -366.381792)
		(width 0.14732)
		(layer "In11.Cu")
		(net "UPI_CPU1_CPU0_P2P2_DN<19>")
	)
	(segment
		(start 267.664438 -337.516216)
		(end 267.664438 -337.724496)
		(width 0.14732)
		(layer "In11.Cu")
		(net "UPI_CPU1_CPU0_P2P2_DN<19>")
	)
	(segment
		(start 338.25942 -285.173928)
		(end 338.251546 -285.178246)
		(width 0.0889)
		(layer "In11.Cu")
		(net "UPI_CPU1_CPU0_P2P2_DN<19>")
	)
	(segment
		(start 308.715918 -316.835028)
		(end 308.45506 -317.095886)
		(width 0.14732)
		(layer "In11.Cu")
		(net "UPI_CPU1_CPU0_P2P2_DN<19>")
	)
	(segment
		(start 236.577378 -365.052102)
		(end 236.093508 -365.391192)
		(width 0.14732)
		(layer "In11.Cu")
		(net "UPI_CPU1_CPU0_P2P2_DN<19>")
	)
	(segment
		(start 337.312254 -282.888944)
		(end 337.322922 -282.895294)
		(width 0.0889)
		(layer "In11.Cu")
		(net "UPI_CPU1_CPU0_P2P2_DN<19>")
	)
	(segment
		(start 245.380764 -358.706674)
		(end 245.070884 -358.264206)
		(width 0.14732)
		(layer "In11.Cu")
		(net "UPI_CPU1_CPU0_P2P2_DN<19>")
	)
	(segment
		(start 236.093508 -365.391192)
		(end 235.888784 -365.355124)
		(width 0.14732)
		(layer "In11.Cu")
		(net "UPI_CPU1_CPU0_P2P2_DN<19>")
	)
	(segment
		(start 262.35279 -343.472008)
		(end 261.916926 -343.472008)
		(width 0.14732)
		(layer "In11.Cu")
		(net "UPI_CPU1_CPU0_P2P2_DN<19>")
	)
	(segment
		(start 73.721976 -326.958706)
		(end 74.569066 -325.167244)
		(width 0.14732)
		(layer "In11.Cu")
		(net "UPI_CPU1_CPU0_P2P2_DN<19>")
	)
	(segment
		(start 246.540528 -356.85857)
		(end 245.871238 -357.327708)
		(width 0.14732)
		(layer "In11.Cu")
		(net "UPI_CPU1_CPU0_P2P2_DN<19>")
	)
	(segment
		(start 251.566426 -353.338384)
		(end 251.49048 -353.76739)
		(width 0.14732)
		(layer "In11.Cu")
		(net "UPI_CPU1_CPU0_P2P2_DN<19>")
	)
	(segment
		(start 243.172488 -359.593896)
		(end 242.743736 -359.51795)
		(width 0.14732)
		(layer "In11.Cu")
		(net "UPI_CPU1_CPU0_P2P2_DN<19>")
	)
	(segment
		(start 105.445306 -283.714444)
		(end 105.447338 -283.713174)
		(width 0.0889)
		(layer "In11.Cu")
		(net "UPI_CPU1_CPU0_P2P2_DN<19>")
	)
	(segment
		(start 303.694592 -322.425822)
		(end 303.396396 -322.641976)
		(width 0.14732)
		(layer "In11.Cu")
		(net "UPI_CPU1_CPU0_P2P2_DN<19>")
	)
	(segment
		(start 104.505506 -285.342076)
		(end 104.512872 -285.337758)
		(width 0.0889)
		(layer "In11.Cu")
		(net "UPI_CPU1_CPU0_P2P2_DN<19>")
	)
	(segment
		(start 256.569972 -349.449136)
		(end 256.134108 -349.449136)
		(width 0.14732)
		(layer "In11.Cu")
		(net "UPI_CPU1_CPU0_P2P2_DN<19>")
	)
	(segment
		(start 104.514396 -285.985712)
		(end 104.513634 -285.985204)
		(width 0.0889)
		(layer "In11.Cu")
		(net "UPI_CPU1_CPU0_P2P2_DN<19>")
	)
	(segment
		(start 239.375696 -362.253276)
		(end 238.946944 -362.17733)
		(width 0.14732)
		(layer "In11.Cu")
		(net "UPI_CPU1_CPU0_P2P2_DN<19>")
	)
	(segment
		(start 236.379258 -363.976158)
		(end 236.303312 -364.40491)
		(width 0.14732)
		(layer "In11.Cu")
		(net "UPI_CPU1_CPU0_P2P2_DN<19>")
	)
	(segment
		(start 249.592084 -355.09708)
		(end 249.902218 -355.539802)
		(width 0.14732)
		(layer "In11.Cu")
		(net "UPI_CPU1_CPU0_P2P2_DN<19>")
	)
	(segment
		(start 98.996754 -372.538752)
		(end 78.600808 -364.089442)
		(width 0.14732)
		(layer "In11.Cu")
		(net "UPI_CPU1_CPU0_P2P2_DN<19>")
	)
	(segment
		(start 72.549258 -352.997008)
		(end 72.549258 -335.17078)
		(width 0.14732)
		(layer "In11.Cu")
		(net "UPI_CPU1_CPU0_P2P2_DN<19>")
	)
	(segment
		(start 261.630922 -344.984324)
		(end 261.213092 -345.402154)
		(width 0.14732)
		(layer "In11.Cu")
		(net "UPI_CPU1_CPU0_P2P2_DN<19>")
	)
	(segment
		(start 104.513634 -285.985204)
		(end 104.505506 -285.980632)
		(width 0.0889)
		(layer "In11.Cu")
		(net "UPI_CPU1_CPU0_P2P2_DN<19>")
	)
	(segment
		(start 272.556986 -333.841852)
		(end 272.348706 -333.841852)
		(width 0.14732)
		(layer "In11.Cu")
		(net "UPI_CPU1_CPU0_P2P2_DN<19>")
	)
	(segment
		(start 241.583972 -361.366054)
		(end 241.274092 -360.923586)
		(width 0.14732)
		(layer "In11.Cu")
		(net "UPI_CPU1_CPU0_P2P2_DN<19>")
	)
	(segment
		(start 244.170962 -359.733342)
		(end 243.687092 -360.072432)
		(width 0.14732)
		(layer "In11.Cu")
		(net "UPI_CPU1_CPU0_P2P2_DN<19>")
	)
	(segment
		(start 232.50652 -367.06429)
		(end 232.816654 -367.507012)
		(width 0.14732)
		(layer "In11.Cu")
		(net "UPI_CPU1_CPU0_P2P2_DN<19>")
	)
	(segment
		(start 313.016646 -314.229496)
		(end 312.755788 -314.490354)
		(width 0.14732)
		(layer "In11.Cu")
		(net "UPI_CPU1_CPU0_P2P2_DN<19>")
	)
	(segment
		(start 255.664716 -350.570292)
		(end 255.664716 -350.778064)
		(width 0.14732)
		(layer "In11.Cu")
		(net "UPI_CPU1_CPU0_P2P2_DN<19>")
	)
	(segment
		(start 336.997548 -289.510724)
		(end 335.82229 -290.685982)
		(width 0.14732)
		(layer "In11.Cu")
		(net "UPI_CPU1_CPU0_P2P2_DN<19>")
	)
	(segment
		(start 312.755788 -314.490354)
		(end 312.755788 -314.695078)
		(width 0.14732)
		(layer "In11.Cu")
		(net "UPI_CPU1_CPU0_P2P2_DN<19>")
	)
	(segment
		(start 245.871238 -357.327708)
		(end 245.795292 -357.75646)
		(width 0.14732)
		(layer "In11.Cu")
		(net "UPI_CPU1_CPU0_P2P2_DN<19>")
	)
	(segment
		(start 248.438924 -355.52888)
		(end 247.769634 -355.998018)
		(width 0.14732)
		(layer "In11.Cu")
		(net "UPI_CPU1_CPU0_P2P2_DN<19>")
	)
	(segment
		(start 260.278118 -345.110816)
		(end 259.700776 -345.688158)
		(width 0.14732)
		(layer "In11.Cu")
		(net "UPI_CPU1_CPU0_P2P2_DN<19>")
	)
	(segment
		(start 238.511842 -363.517942)
		(end 238.475774 -363.722412)
		(width 0.14732)
		(layer "In11.Cu")
		(net "UPI_CPU1_CPU0_P2P2_DN<19>")
	)
	(segment
		(start 256.677922 -349.557086)
		(end 256.569972 -349.449136)
		(width 0.14732)
		(layer "In11.Cu")
		(net "UPI_CPU1_CPU0_P2P2_DN<19>")
	)
	(segment
		(start 273.209512 -331.08646)
		(end 272.6309 -331.665072)
		(width 0.14732)
		(layer "In11.Cu")
		(net "UPI_CPU1_CPU0_P2P2_DN<19>")
	)
	(segment
		(start 337.039712 -288.917126)
		(end 337.039712 -289.261804)
		(width 0.0889)
		(layer "In11.Cu")
		(net "UPI_CPU1_CPU0_P2P2_DN<19>")
	)
	(segment
		(start 301.822612 -323.608954)
		(end 301.481998 -323.750178)
		(width 0.14732)
		(layer "In11.Cu")
		(net "UPI_CPU1_CPU0_P2P2_DN<19>")
	)
	(segment
		(start 266.02563 -339.363304)
		(end 265.608816 -339.780118)
		(width 0.14732)
		(layer "In11.Cu")
		(net "UPI_CPU1_CPU0_P2P2_DN<19>")
	)
	(segment
		(start 259.992114 -346.41536)
		(end 259.992114 -346.623132)
		(width 0.14732)
		(layer "In11.Cu")
		(net "UPI_CPU1_CPU0_P2P2_DN<19>")
	)
	(segment
		(start 336.97799 -282.405836)
		(end 337.043268 -282.471114)
		(width 0.0889)
		(layer "In11.Cu")
		(net "UPI_CPU1_CPU0_P2P2_DN<19>")
	)
	(arc
		(start 103.387398 -288.917126)
		(mid 103.435077 -288.734226)
		(end 103.56596 -288.597848)
		(width 0.0889)
		(layer "In11.Cu")
		(net "UPI_CPU1_CPU0_P2P2_DN<19>")
	)
	(arc
		(start 338.251546 -285.178246)
		(mid 337.979926 -285.661449)
		(end 338.252054 -286.144462)
		(width 0.0889)
		(layer "In11.Cu")
		(net "UPI_CPU1_CPU0_P2P2_DN<19>")
	)
	(arc
		(start 104.984296 -284.52318)
		(mid 105.188631 -284.320575)
		(end 105.266744 -284.043628)
		(width 0.0889)
		(layer "In11.Cu")
		(net "UPI_CPU1_CPU0_P2P2_DN<19>")
	)
	(arc
		(start 103.571548 -289.27806)
		(mid 103.462377 -289.194361)
		(end 103.387144 -289.079178)
		(width 0.0889)
		(layer "In11.Cu")
		(net "UPI_CPU1_CPU0_P2P2_DN<19>")
	)
	(arc
		(start 104.797098 -284.838902)
		(mid 104.849368 -284.656537)
		(end 104.984296 -284.52318)
		(width 0.0889)
		(layer "In11.Cu")
		(net "UPI_CPU1_CPU0_P2P2_DN<19>")
	)
	(arc
		(start 337.778852 -287.621726)
		(mid 337.581676 -287.827361)
		(end 337.509866 -288.103056)
		(width 0.0889)
		(layer "In11.Cu")
		(net "UPI_CPU1_CPU0_P2P2_DN<19>")
	)
	(arc
		(start 103.857044 -289.752786)
		(mid 103.780377 -289.475658)
		(end 103.571548 -289.27806)
		(width 0.0889)
		(layer "In11.Cu")
		(net "UPI_CPU1_CPU0_P2P2_DN<19>")
	)
	(arc
		(start 104.520492 -285.33344)
		(mid 104.723079 -285.127089)
		(end 104.797098 -284.847538)
		(width 0.0889)
		(layer "In11.Cu")
		(net "UPI_CPU1_CPU0_P2P2_DN<19>")
	)
	(arc
		(start 337.322922 -282.895294)
		(mid 337.456252 -283.026323)
		(end 337.509866 -283.205428)
		(width 0.0889)
		(layer "In11.Cu")
		(net "UPI_CPU1_CPU0_P2P2_DN<19>")
	)
	(arc
		(start 105.460292 -283.705808)
		(mid 105.662879 -283.499457)
		(end 105.736898 -283.219906)
		(width 0.0889)
		(layer "In11.Cu")
		(net "UPI_CPU1_CPU0_P2P2_DN<19>")
	)
	(arc
		(start 338.449666 -286.48787)
		(mid 338.398094 -286.665594)
		(end 338.267802 -286.796988)
		(width 0.0889)
		(layer "In11.Cu")
		(net "UPI_CPU1_CPU0_P2P2_DN<19>")
	)
	(arc
		(start 105.266744 -284.033722)
		(mid 105.314423 -283.850822)
		(end 105.445306 -283.714444)
		(width 0.0889)
		(layer "In11.Cu")
		(net "UPI_CPU1_CPU0_P2P2_DN<19>")
	)
	(arc
		(start 337.98002 -287.28924)
		(mid 337.932661 -287.47138)
		(end 337.802728 -287.607502)
		(width 0.0889)
		(layer "In11.Cu")
		(net "UPI_CPU1_CPU0_P2P2_DN<19>")
	)
	(arc
		(start 337.979766 -284.033722)
		(mid 338.052458 -284.310927)
		(end 338.2518 -284.51683)
		(width 0.0889)
		(layer "In11.Cu")
		(net "UPI_CPU1_CPU0_P2P2_DN<19>")
	)
	(arc
		(start 105.736898 -283.205682)
		(mid 105.678604 -282.969039)
		(end 105.526078 -282.778962)
		(width 0.0889)
		(layer "In11.Cu")
		(net "UPI_CPU1_CPU0_P2P2_DN<19>")
	)
	(arc
		(start 104.505506 -285.980632)
		(mid 104.326909 -285.661354)
		(end 104.505506 -285.342076)
		(width 0.0889)
		(layer "In11.Cu")
		(net "UPI_CPU1_CPU0_P2P2_DN<19>")
	)
	(arc
		(start 338.262722 -286.150812)
		(mid 338.395287 -286.280407)
		(end 338.449666 -286.457644)
		(width 0.0889)
		(layer "In11.Cu")
		(net "UPI_CPU1_CPU0_P2P2_DN<19>")
	)
	(arc
		(start 338.262468 -284.52318)
		(mid 338.449724 -284.844655)
		(end 338.267802 -285.169102)
		(width 0.0889)
		(layer "In11.Cu")
		(net "UPI_CPU1_CPU0_P2P2_DN<19>")
	)
	(arc
		(start 104.050846 -287.775142)
		(mid 104.253259 -287.568729)
		(end 104.327198 -287.28924)
		(width 0.0889)
		(layer "In11.Cu")
		(net "UPI_CPU1_CPU0_P2P2_DN<19>")
	)
	(arc
		(start 337.509866 -288.114486)
		(mid 337.456811 -288.295423)
		(end 337.322414 -288.427668)
		(width 0.0889)
		(layer "In11.Cu")
		(net "UPI_CPU1_CPU0_P2P2_DN<19>")
	)
	(arc
		(start 337.311746 -288.434018)
		(mid 337.112362 -288.639898)
		(end 337.039712 -288.917126)
		(width 0.0889)
		(layer "In11.Cu")
		(net "UPI_CPU1_CPU0_P2P2_DN<19>")
	)
	(arc
		(start 337.04657 -282.49245)
		(mid 337.135499 -282.72012)
		(end 337.312254 -282.888944)
		(width 0.0889)
		(layer "In11.Cu")
		(net "UPI_CPU1_CPU0_P2P2_DN<19>")
	)
	(arc
		(start 104.327198 -287.28924)
		(mid 104.374877 -287.10634)
		(end 104.50576 -286.969962)
		(width 0.0889)
		(layer "In11.Cu")
		(net "UPI_CPU1_CPU0_P2P2_DN<19>")
	)
	(arc
		(start 337.792568 -283.709364)
		(mid 337.927613 -283.843088)
		(end 337.979766 -284.025848)
		(width 0.0889)
		(layer "In11.Cu")
		(net "UPI_CPU1_CPU0_P2P2_DN<19>")
	)
	(arc
		(start 103.857298 -288.103056)
		(mid 103.904977 -287.920156)
		(end 104.03586 -287.783778)
		(width 0.0889)
		(layer "In11.Cu")
		(net "UPI_CPU1_CPU0_P2P2_DN<19>")
	)
	(arc
		(start 337.509866 -283.219906)
		(mid 337.582558 -283.497111)
		(end 337.7819 -283.703014)
		(width 0.0889)
		(layer "In11.Cu")
		(net "UPI_CPU1_CPU0_P2P2_DN<19>")
	)
	(arc
		(start 338.251546 -286.806132)
		(mid 338.052514 -287.012122)
		(end 337.98002 -287.28924)
		(width 0.0889)
		(layer "In11.Cu")
		(net "UPI_CPU1_CPU0_P2P2_DN<19>")
	)
	(arc
		(start 104.520746 -286.961326)
		(mid 104.797059 -286.471722)
		(end 104.514396 -285.985712)
		(width 0.0889)
		(layer "In11.Cu")
		(net "UPI_CPU1_CPU0_P2P2_DN<19>")
	)
	(arc
		(start 337.043776 -282.471114)
		(mid 337.045072 -282.481795)
		(end 337.04657 -282.49245)
		(width 0.0889)
		(layer "In11.Cu")
		(net "UPI_CPU1_CPU0_P2P2_DN<19>")
	)
	(arc
		(start 105.526078 -282.778962)
		(mid 105.51763 -282.772405)
		(end 105.50906 -282.766008)
		(width 0.0889)
		(layer "In11.Cu")
		(net "UPI_CPU1_CPU0_P2P2_DN<19>")
	)
	(arc
		(start 103.57485 -288.592768)
		(mid 103.777136 -288.393787)
		(end 103.857298 -288.121598)
		(width 0.0889)
		(layer "In11.Cu")
		(net "UPI_CPU1_CPU0_P2P2_DN<19>")
	)
	(segment
		(start 337.604862 -280.242264)
		(end 337.604862 -280.778204)
		(width 0.13208)
		(layer "F.Cu")
		(net "UPI_CPU1_CPU0_P2P2_DN<18>")
	)
	(segment
		(start 104.701848 -281.869896)
		(end 104.701848 -282.405582)
		(width 0.13208)
		(layer "F.Cu")
		(net "UPI_CPU1_CPU0_P2P2_DN<18>")
	)
	(segment
		(start 104.701848 -282.405582)
		(end 104.701594 -282.405836)
		(width 0.13208)
		(layer "F.Cu")
		(net "UPI_CPU1_CPU0_P2P2_DN<18>")
	)
	(segment
		(start 267.578332 -339.57768)
		(end 267.578332 -339.369908)
		(width 0.14732)
		(layer "In11.Cu")
		(net "UPI_CPU1_CPU0_P2P2_DN<18>")
	)
	(segment
		(start 102.627938 -291.369496)
		(end 102.726998 -291.468556)
		(width 0.0889)
		(layer "In11.Cu")
		(net "UPI_CPU1_CPU0_P2P2_DN<18>")
	)
	(segment
		(start 102.726998 -289.985196)
		(end 102.627938 -290.084256)
		(width 0.0889)
		(layer "In11.Cu")
		(net "UPI_CPU1_CPU0_P2P2_DN<18>")
	)
	(segment
		(start 338.827364 -287.778698)
		(end 338.83346 -287.775142)
		(width 0.0889)
		(layer "In11.Cu")
		(net "UPI_CPU1_CPU0_P2P2_DN<18>")
	)
	(segment
		(start 283.769816 -327.104502)
		(end 283.96184 -327.184004)
		(width 0.14732)
		(layer "In11.Cu")
		(net "UPI_CPU1_CPU0_P2P2_DN<18>")
	)
	(segment
		(start 283.144468 -327.522586)
		(end 283.22397 -327.330562)
		(width 0.14732)
		(layer "In11.Cu")
		(net "UPI_CPU1_CPU0_P2P2_DN<18>")
	)
	(segment
		(start 267.578332 -339.369908)
		(end 267.996162 -338.952078)
		(width 0.14732)
		(layer "In11.Cu")
		(net "UPI_CPU1_CPU0_P2P2_DN<18>")
	)
	(segment
		(start 248.015252 -358.616504)
		(end 248.051828 -358.41178)
		(width 0.14732)
		(layer "In11.Cu")
		(net "UPI_CPU1_CPU0_P2P2_DN<18>")
	)
	(segment
		(start 338.818474 -287.783778)
		(end 338.827364 -287.778698)
		(width 0.0889)
		(layer "In11.Cu")
		(net "UPI_CPU1_CPU0_P2P2_DN<18>")
	)
	(segment
		(start 233.23169 -368.924332)
		(end 233.402124 -369.168172)
		(width 0.14732)
		(layer "In11.Cu")
		(net "UPI_CPU1_CPU0_P2P2_DN<18>")
	)
	(segment
		(start 102.726998 -290.538916)
		(end 102.627938 -290.637976)
		(width 0.0889)
		(layer "In11.Cu")
		(net "UPI_CPU1_CPU0_P2P2_DN<18>")
	)
	(segment
		(start 283.302456 -327.90384)
		(end 283.144468 -327.522586)
		(width 0.14732)
		(layer "In11.Cu")
		(net "UPI_CPU1_CPU0_P2P2_DN<18>")
	)
	(segment
		(start 233.402124 -369.168172)
		(end 233.830368 -369.244626)
		(width 0.14732)
		(layer "In11.Cu")
		(net "UPI_CPU1_CPU0_P2P2_DN<18>")
	)
	(segment
		(start 338.342732 -288.601404)
		(end 338.357718 -288.592768)
		(width 0.0889)
		(layer "In11.Cu")
		(net "UPI_CPU1_CPU0_P2P2_DN<18>")
	)
	(segment
		(start 102.235508 -291.948616)
		(end 102.235508 -292.088824)
		(width 0.0889)
		(layer "In11.Cu")
		(net "UPI_CPU1_CPU0_P2P2_DN<18>")
	)
	(segment
		(start 242.995958 -364.113064)
		(end 243.072412 -363.684566)
		(width 0.14732)
		(layer "In11.Cu")
		(net "UPI_CPU1_CPU0_P2P2_DN<18>")
	)
	(segment
		(start 161.449766 -377.70435)
		(end 200.154286 -370.88064)
		(width 0.14732)
		(layer "In11.Cu")
		(net "UPI_CPU1_CPU0_P2P2_DN<18>")
	)
	(segment
		(start 237.128558 -366.02797)
		(end 237.333282 -366.064546)
		(width 0.14732)
		(layer "In11.Cu")
		(net "UPI_CPU1_CPU0_P2P2_DN<18>")
	)
	(segment
		(start 77.882242 -365.018066)
		(end 98.592386 -373.595646)
		(width 0.14732)
		(layer "In11.Cu")
		(net "UPI_CPU1_CPU0_P2P2_DN<18>")
	)
	(segment
		(start 313.026806 -316.54496)
		(end 313.703208 -315.868304)
		(width 0.14732)
		(layer "In11.Cu")
		(net "UPI_CPU1_CPU0_P2P2_DN<18>")
	)
	(segment
		(start 335.07045 -292.192964)
		(end 336.45602 -291.618924)
		(width 0.14732)
		(layer "In11.Cu")
		(net "UPI_CPU1_CPU0_P2P2_DN<18>")
	)
	(segment
		(start 103.479346 -286.799782)
		(end 103.478584 -286.80029)
		(width 0.0889)
		(layer "In11.Cu")
		(net "UPI_CPU1_CPU0_P2P2_DN<18>")
	)
	(segment
		(start 331.34935 -300.627288)
		(end 333.221584 -294.45585)
		(width 0.14732)
		(layer "In11.Cu")
		(net "UPI_CPU1_CPU0_P2P2_DN<18>")
	)
	(segment
		(start 102.627938 -290.084256)
		(end 102.627938 -290.262056)
		(width 0.0889)
		(layer "In11.Cu")
		(net "UPI_CPU1_CPU0_P2P2_DN<18>")
	)
	(segment
		(start 104.606344 -283.205682)
		(end 104.606344 -283.219906)
		(width 0.0889)
		(layer "In11.Cu")
		(net "UPI_CPU1_CPU0_P2P2_DN<18>")
	)
	(segment
		(start 102.726998 -288.087562)
		(end 102.726998 -288.103056)
		(width 0.0889)
		(layer "In11.Cu")
		(net "UPI_CPU1_CPU0_P2P2_DN<18>")
	)
	(segment
		(start 242.32489 -364.580932)
		(end 242.995958 -364.113064)
		(width 0.14732)
		(layer "In11.Cu")
		(net "UPI_CPU1_CPU0_P2P2_DN<18>")
	)
	(segment
		(start 339.579966 -286.475424)
		(end 339.579966 -286.4612)
		(width 0.0889)
		(layer "In11.Cu")
		(net "UPI_CPU1_CPU0_P2P2_DN<18>")
	)
	(segment
		(start 306.749958 -320.806318)
		(end 307.328316 -320.267584)
		(width 0.14732)
		(layer "In11.Cu")
		(net "UPI_CPU1_CPU0_P2P2_DN<18>")
	)
	(segment
		(start 102.020116 -297.304714)
		(end 101.943408 -297.489372)
		(width 0.14732)
		(layer "In11.Cu")
		(net "UPI_CPU1_CPU0_P2P2_DN<18>")
	)
	(segment
		(start 339.288628 -286.969962)
		(end 339.297518 -286.964882)
		(width 0.0889)
		(layer "In11.Cu")
		(net "UPI_CPU1_CPU0_P2P2_DN<18>")
	)
	(segment
		(start 338.357718 -282.730194)
		(end 338.348828 -282.725114)
		(width 0.0889)
		(layer "In11.Cu")
		(net "UPI_CPU1_CPU0_P2P2_DN<18>")
	)
	(segment
		(start 239.193578 -366.764316)
		(end 239.270032 -366.335818)
		(width 0.14732)
		(layer "In11.Cu")
		(net "UPI_CPU1_CPU0_P2P2_DN<18>")
	)
	(segment
		(start 267.869924 -340.305136)
		(end 267.869924 -339.869272)
		(width 0.14732)
		(layer "In11.Cu")
		(net "UPI_CPU1_CPU0_P2P2_DN<18>")
	)
	(segment
		(start 75.228196 -362.363512)
		(end 77.882242 -365.018066)
		(width 0.14732)
		(layer "In11.Cu")
		(net "UPI_CPU1_CPU0_P2P2_DN<18>")
	)
	(segment
		(start 104.38892 -282.405836)
		(end 104.331516 -282.348432)
		(width 0.0889)
		(layer "In11.Cu")
		(net "UPI_CPU1_CPU0_P2P2_DN<18>")
	)
	(segment
		(start 279.136602 -329.212702)
		(end 279.21585 -329.020932)
		(width 0.14732)
		(layer "In11.Cu")
		(net "UPI_CPU1_CPU0_P2P2_DN<18>")
	)
	(segment
		(start 104.897682 -282.725114)
		(end 104.888792 -282.730194)
		(width 0.0889)
		(layer "In11.Cu")
		(net "UPI_CPU1_CPU0_P2P2_DN<18>")
	)
	(segment
		(start 249.284744 -357.732076)
		(end 249.801634 -358.474264)
		(width 0.14732)
		(layer "In11.Cu")
		(net "UPI_CPU1_CPU0_P2P2_DN<18>")
	)
	(segment
		(start 268.495526 -339.24367)
		(end 268.93139 -339.24367)
		(width 0.14732)
		(layer "In11.Cu")
		(net "UPI_CPU1_CPU0_P2P2_DN<18>")
	)
	(segment
		(start 291.107876 -327.618852)
		(end 291.415724 -327.9267)
		(width 0.14732)
		(layer "In11.Cu")
		(net "UPI_CPU1_CPU0_P2P2_DN<18>")
	)
	(segment
		(start 245.066058 -362.491528)
		(end 244.212872 -361.267756)
		(width 0.14732)
		(layer "In11.Cu")
		(net "UPI_CPU1_CPU0_P2P2_DN<18>")
	)
	(segment
		(start 103.196644 -285.651448)
		(end 103.196644 -285.675578)
		(width 0.0889)
		(layer "In11.Cu")
		(net "UPI_CPU1_CPU0_P2P2_DN<18>")
	)
	(segment
		(start 102.627938 -291.191696)
		(end 102.627938 -291.369496)
		(width 0.0889)
		(layer "In11.Cu")
		(net "UPI_CPU1_CPU0_P2P2_DN<18>")
	)
	(segment
		(start 284.52191 -327.731882)
		(end 285.471362 -327.338436)
		(width 0.14732)
		(layer "In11.Cu")
		(net "UPI_CPU1_CPU0_P2P2_DN<18>")
	)
	(segment
		(start 104.419654 -283.543756)
		(end 104.418892 -283.544264)
		(width 0.0889)
		(layer "In11.Cu")
		(net "UPI_CPU1_CPU0_P2P2_DN<18>")
	)
	(segment
		(start 291.107876 -326.027542)
		(end 291.107876 -327.618852)
		(width 0.14732)
		(layer "In11.Cu")
		(net "UPI_CPU1_CPU0_P2P2_DN<18>")
	)
	(segment
		(start 269.21714 -337.938872)
		(end 269.21714 -337.7311)
		(width 0.14732)
		(layer "In11.Cu")
		(net "UPI_CPU1_CPU0_P2P2_DN<18>")
	)
	(segment
		(start 242.311682 -362.593382)
		(end 242.348258 -362.388658)
		(width 0.14732)
		(layer "In11.Cu")
		(net "UPI_CPU1_CPU0_P2P2_DN<18>")
	)
	(segment
		(start 103.957882 -284.353)
		(end 103.948992 -284.35808)
		(width 0.0889)
		(layer "In11.Cu")
		(net "UPI_CPU1_CPU0_P2P2_DN<18>")
	)
	(segment
		(start 244.318536 -363.387894)
		(end 244.989604 -362.920026)
		(width 0.14732)
		(layer "In11.Cu")
		(net "UPI_CPU1_CPU0_P2P2_DN<18>")
	)
	(segment
		(start 306.165504 -321.974718)
		(end 306.749958 -320.806318)
		(width 0.14732)
		(layer "In11.Cu")
		(net "UPI_CPU1_CPU0_P2P2_DN<18>")
	)
	(segment
		(start 269.508732 -338.666328)
		(end 269.508732 -338.230464)
		(width 0.14732)
		(layer "In11.Cu")
		(net "UPI_CPU1_CPU0_P2P2_DN<18>")
	)
	(segment
		(start 268.203934 -338.952078)
		(end 268.495526 -339.24367)
		(width 0.14732)
		(layer "In11.Cu")
		(net "UPI_CPU1_CPU0_P2P2_DN<18>")
	)
	(segment
		(start 250.460764 -356.912418)
		(end 250.49734 -356.707694)
		(width 0.14732)
		(layer "In11.Cu")
		(net "UPI_CPU1_CPU0_P2P2_DN<18>")
	)
	(segment
		(start 101.943408 -297.489372)
		(end 97.412302 -303.59858)
		(width 0.14732)
		(layer "In11.Cu")
		(net "UPI_CPU1_CPU0_P2P2_DN<18>")
	)
	(segment
		(start 299.60824 -325.890382)
		(end 303.983136 -324.078092)
		(width 0.14732)
		(layer "In11.Cu")
		(net "UPI_CPU1_CPU0_P2P2_DN<18>")
	)
	(segment
		(start 81.592674 -316.580774)
		(end 73.655936 -324.51802)
		(width 0.14732)
		(layer "In11.Cu")
		(net "UPI_CPU1_CPU0_P2P2_DN<18>")
	)
	(segment
		(start 245.698772 -361.853226)
		(end 246.12727 -361.92968)
		(width 0.14732)
		(layer "In11.Cu")
		(net "UPI_CPU1_CPU0_P2P2_DN<18>")
	)
	(segment
		(start 102.361238 -291.822886)
		(end 102.235508 -291.948616)
		(width 0.0889)
		(layer "In11.Cu")
		(net "UPI_CPU1_CPU0_P2P2_DN<18>")
	)
	(segment
		(start 98.592386 -373.595646)
		(end 126.287276 -377.70435)
		(width 0.14732)
		(layer "In11.Cu")
		(net "UPI_CPU1_CPU0_P2P2_DN<18>")
	)
	(segment
		(start 239.995202 -365.830104)
		(end 240.4237 -365.906558)
		(width 0.14732)
		(layer "In11.Cu")
		(net "UPI_CPU1_CPU0_P2P2_DN<18>")
	)
	(segment
		(start 102.501446 -291.822886)
		(end 102.361238 -291.822886)
		(width 0.0889)
		(layer "In11.Cu")
		(net "UPI_CPU1_CPU0_P2P2_DN<18>")
	)
	(segment
		(start 102.548436 -288.422334)
		(end 102.539546 -288.427414)
		(width 0.0889)
		(layer "In11.Cu")
		(net "UPI_CPU1_CPU0_P2P2_DN<18>")
	)
	(segment
		(start 247.599962 -360.5276)
		(end 248.02846 -360.604054)
		(width 0.14732)
		(layer "In11.Cu")
		(net "UPI_CPU1_CPU0_P2P2_DN<18>")
	)
	(segment
		(start 72.669146 -326.605646)
		(end 72.06488 -328.788776)
		(width 0.14732)
		(layer "In11.Cu")
		(net "UPI_CPU1_CPU0_P2P2_DN<18>")
	)
	(segment
		(start 102.235508 -292.088824)
		(end 102.062026 -292.262306)
		(width 0.0889)
		(layer "In11.Cu")
		(net "UPI_CPU1_CPU0_P2P2_DN<18>")
	)
	(segment
		(start 279.761696 -328.794872)
		(end 279.95372 -328.874374)
		(width 0.14732)
		(layer "In11.Cu")
		(net "UPI_CPU1_CPU0_P2P2_DN<18>")
	)
	(segment
		(start 283.135832 -328.305922)
		(end 283.302456 -327.90384)
		(width 0.14732)
		(layer "In11.Cu")
		(net "UPI_CPU1_CPU0_P2P2_DN<18>")
	)
	(segment
		(start 292.540436 -326.027542)
		(end 292.677596 -325.890382)
		(width 0.14732)
		(layer "In11.Cu")
		(net "UPI_CPU1_CPU0_P2P2_DN<18>")
	)
	(segment
		(start 338.639912 -283.219906)
		(end 338.639912 -283.197808)
		(width 0.0889)
		(layer "In11.Cu")
		(net "UPI_CPU1_CPU0_P2P2_DN<18>")
	)
	(segment
		(start 237.333282 -366.064546)
		(end 238.094012 -367.15573)
		(width 0.14732)
		(layer "In11.Cu")
		(net "UPI_CPU1_CPU0_P2P2_DN<18>")
	)
	(segment
		(start 241.896392 -364.504478)
		(end 242.32489 -364.580932)
		(width 0.14732)
		(layer "In11.Cu")
		(net "UPI_CPU1_CPU0_P2P2_DN<18>")
	)
	(segment
		(start 339.288628 -285.342076)
		(end 339.297518 -285.336996)
		(width 0.0889)
		(layer "In11.Cu")
		(net "UPI_CPU1_CPU0_P2P2_DN<18>")
	)
	(segment
		(start 339.109812 -284.033722)
		(end 339.109812 -284.023816)
		(width 0.0889)
		(layer "In11.Cu")
		(net "UPI_CPU1_CPU0_P2P2_DN<18>")
	)
	(segment
		(start 236.608112 -366.57026)
		(end 236.644688 -366.365536)
		(width 0.14732)
		(layer "In11.Cu")
		(net "UPI_CPU1_CPU0_P2P2_DN<18>")
	)
	(segment
		(start 283.22397 -327.330562)
		(end 283.769816 -327.104502)
		(width 0.14732)
		(layer "In11.Cu")
		(net "UPI_CPU1_CPU0_P2P2_DN<18>")
	)
	(segment
		(start 250.9012 -358.083104)
		(end 250.977908 -357.65486)
		(width 0.14732)
		(layer "In11.Cu")
		(net "UPI_CPU1_CPU0_P2P2_DN<18>")
	)
	(segment
		(start 104.427782 -283.539184)
		(end 104.419654 -283.543756)
		(width 0.0889)
		(layer "In11.Cu")
		(net "UPI_CPU1_CPU0_P2P2_DN<18>")
	)
	(segment
		(start 333.221584 -294.45585)
		(end 334.05445 -293.208964)
		(width 0.14732)
		(layer "In11.Cu")
		(net "UPI_CPU1_CPU0_P2P2_DN<18>")
	)
	(segment
		(start 248.699528 -360.136186)
		(end 248.775982 -359.707688)
		(width 0.14732)
		(layer "In11.Cu")
		(net "UPI_CPU1_CPU0_P2P2_DN<18>")
	)
	(segment
		(start 292.232588 -327.9267)
		(end 292.540436 -327.618852)
		(width 0.14732)
		(layer "In11.Cu")
		(net "UPI_CPU1_CPU0_P2P2_DN<18>")
	)
	(segment
		(start 104.136444 -284.023816)
		(end 104.136444 -284.033722)
		(width 0.0889)
		(layer "In11.Cu")
		(net "UPI_CPU1_CPU0_P2P2_DN<18>")
	)
	(segment
		(start 334.05445 -293.208964)
		(end 335.07045 -292.192964)
		(width 0.14732)
		(layer "In11.Cu")
		(net "UPI_CPU1_CPU0_P2P2_DN<18>")
	)
	(segment
		(start 239.029748 -364.702344)
		(end 239.234472 -364.73892)
		(width 0.14732)
		(layer "In11.Cu")
		(net "UPI_CPU1_CPU0_P2P2_DN<18>")
	)
	(segment
		(start 248.775982 -359.707688)
		(end 248.015252 -358.616504)
		(width 0.14732)
		(layer "In11.Cu")
		(net "UPI_CPU1_CPU0_P2P2_DN<18>")
	)
	(segment
		(start 244.212872 -361.267756)
		(end 244.249448 -361.063032)
		(width 0.14732)
		(layer "In11.Cu")
		(net "UPI_CPU1_CPU0_P2P2_DN<18>")
	)
	(segment
		(start 291.415724 -327.9267)
		(end 292.232588 -327.9267)
		(width 0.14732)
		(layer "In11.Cu")
		(net "UPI_CPU1_CPU0_P2P2_DN<18>")
	)
	(segment
		(start 234.501436 -368.776758)
		(end 234.57789 -368.348768)
		(width 0.14732)
		(layer "In11.Cu")
		(net "UPI_CPU1_CPU0_P2P2_DN<18>")
	)
	(segment
		(start 267.996162 -338.952078)
		(end 268.203934 -338.952078)
		(width 0.14732)
		(layer "In11.Cu")
		(net "UPI_CPU1_CPU0_P2P2_DN<18>")
	)
	(segment
		(start 309.97525 -318.063372)
		(end 309.97525 -318.063118)
		(width 0.14732)
		(layer "In11.Cu")
		(net "UPI_CPU1_CPU0_P2P2_DN<18>")
	)
	(segment
		(start 270.570198 -337.604862)
		(end 277.559008 -330.616052)
		(width 0.14732)
		(layer "In11.Cu")
		(net "UPI_CPU1_CPU0_P2P2_DN<18>")
	)
	(segment
		(start 240.4237 -365.906558)
		(end 241.094768 -365.43869)
		(width 0.14732)
		(layer "In11.Cu")
		(net "UPI_CPU1_CPU0_P2P2_DN<18>")
	)
	(segment
		(start 103.478584 -286.80029)
		(end 103.47325 -286.803338)
		(width 0.0889)
		(layer "In11.Cu")
		(net "UPI_CPU1_CPU0_P2P2_DN<18>")
	)
	(segment
		(start 269.508732 -338.230464)
		(end 269.21714 -337.938872)
		(width 0.14732)
		(layer "In11.Cu")
		(net "UPI_CPU1_CPU0_P2P2_DN<18>")
	)
	(segment
		(start 73.655936 -324.51802)
		(end 72.669146 -326.605646)
		(width 0.14732)
		(layer "In11.Cu")
		(net "UPI_CPU1_CPU0_P2P2_DN<18>")
	)
	(segment
		(start 102.062026 -293.798498)
		(end 102.020116 -293.840408)
		(width 0.0889)
		(layer "In11.Cu")
		(net "UPI_CPU1_CPU0_P2P2_DN<18>")
	)
	(segment
		(start 102.020116 -293.840408)
		(end 102.020116 -293.862506)
		(width 0.0889)
		(layer "In11.Cu")
		(net "UPI_CPU1_CPU0_P2P2_DN<18>")
	)
	(segment
		(start 239.234472 -364.73892)
		(end 239.995202 -365.830104)
		(width 0.14732)
		(layer "In11.Cu")
		(net "UPI_CPU1_CPU0_P2P2_DN<18>")
	)
	(segment
		(start 269.63497 -337.31327)
		(end 269.842742 -337.31327)
		(width 0.14732)
		(layer "In11.Cu")
		(net "UPI_CPU1_CPU0_P2P2_DN<18>")
	)
	(segment
		(start 280.503376 -329.396598)
		(end 283.135832 -328.305922)
		(width 0.14732)
		(layer "In11.Cu")
		(net "UPI_CPU1_CPU0_P2P2_DN<18>")
	)
	(segment
		(start 102.726998 -289.64509)
		(end 102.726998 -289.985196)
		(width 0.0889)
		(layer "In11.Cu")
		(net "UPI_CPU1_CPU0_P2P2_DN<18>")
	)
	(segment
		(start 316.267592 -315.708792)
		(end 331.34935 -300.627288)
		(width 0.14732)
		(layer "In11.Cu")
		(net "UPI_CPU1_CPU0_P2P2_DN<18>")
	)
	(segment
		(start 339.297518 -286.964882)
		(end 339.303614 -286.961326)
		(width 0.0889)
		(layer "In11.Cu")
		(net "UPI_CPU1_CPU0_P2P2_DN<18>")
	)
	(segment
		(start 101.962966 -292.756336)
		(end 102.062026 -292.855396)
		(width 0.0889)
		(layer "In11.Cu")
		(net "UPI_CPU1_CPU0_P2P2_DN<18>")
	)
	(segment
		(start 277.559008 -330.616052)
		(end 279.117298 -329.970384)
		(width 0.14732)
		(layer "In11.Cu")
		(net "UPI_CPU1_CPU0_P2P2_DN<18>")
	)
	(segment
		(start 240.410492 -363.919008)
		(end 240.447068 -363.714284)
		(width 0.14732)
		(layer "In11.Cu")
		(net "UPI_CPU1_CPU0_P2P2_DN<18>")
	)
	(segment
		(start 339.579712 -284.863032)
		(end 339.579712 -284.837632)
		(width 0.0889)
		(layer "In11.Cu")
		(net "UPI_CPU1_CPU0_P2P2_DN<18>")
	)
	(segment
		(start 238.545878 -365.03991)
		(end 239.029748 -364.702344)
		(width 0.14732)
		(layer "In11.Cu")
		(net "UPI_CPU1_CPU0_P2P2_DN<18>")
	)
	(segment
		(start 250.49734 -356.707694)
		(end 253.696724 -354.47859)
		(width 0.14732)
		(layer "In11.Cu")
		(net "UPI_CPU1_CPU0_P2P2_DN<18>")
	)
	(segment
		(start 267.869924 -339.869272)
		(end 267.578332 -339.57768)
		(width 0.14732)
		(layer "In11.Cu")
		(net "UPI_CPU1_CPU0_P2P2_DN<18>")
	)
	(segment
		(start 233.830368 -369.244626)
		(end 234.501436 -368.776758)
		(width 0.14732)
		(layer "In11.Cu")
		(net "UPI_CPU1_CPU0_P2P2_DN<18>")
	)
	(segment
		(start 339.297264 -284.35808)
		(end 339.288374 -284.353)
		(width 0.0889)
		(layer "In11.Cu")
		(net "UPI_CPU1_CPU0_P2P2_DN<18>")
	)
	(segment
		(start 248.051828 -358.41178)
		(end 249.08002 -357.6955)
		(width 0.14732)
		(layer "In11.Cu")
		(net "UPI_CPU1_CPU0_P2P2_DN<18>")
	)
	(segment
		(start 101.962966 -293.310056)
		(end 102.062026 -293.409116)
		(width 0.0889)
		(layer "In11.Cu")
		(net "UPI_CPU1_CPU0_P2P2_DN<18>")
	)
	(segment
		(start 336.578194 -291.49675)
		(end 336.593688 -291.481256)
		(width 0.0889)
		(layer "In11.Cu")
		(net "UPI_CPU1_CPU0_P2P2_DN<18>")
	)
	(segment
		(start 240.447068 -363.714284)
		(end 240.930938 -363.376718)
		(width 0.14732)
		(layer "In11.Cu")
		(net "UPI_CPU1_CPU0_P2P2_DN<18>")
	)
	(segment
		(start 233.026966 -368.887756)
		(end 233.23169 -368.924332)
		(width 0.14732)
		(layer "In11.Cu")
		(net "UPI_CPU1_CPU0_P2P2_DN<18>")
	)
	(segment
		(start 101.962966 -292.578536)
		(end 101.962966 -292.756336)
		(width 0.0889)
		(layer "In11.Cu")
		(net "UPI_CPU1_CPU0_P2P2_DN<18>")
	)
	(segment
		(start 238.52251 -367.232184)
		(end 239.193578 -366.764316)
		(width 0.14732)
		(layer "In11.Cu")
		(net "UPI_CPU1_CPU0_P2P2_DN<18>")
	)
	(segment
		(start 250.977908 -357.65486)
		(end 250.460764 -356.912418)
		(width 0.14732)
		(layer "In11.Cu")
		(net "UPI_CPU1_CPU0_P2P2_DN<18>")
	)
	(segment
		(start 313.703208 -315.868304)
		(end 314.088018 -315.708792)
		(width 0.14732)
		(layer "In11.Cu")
		(net "UPI_CPU1_CPU0_P2P2_DN<18>")
	)
	(segment
		(start 280.10104 -329.22972)
		(end 280.503376 -329.396598)
		(width 0.14732)
		(layer "In11.Cu")
		(net "UPI_CPU1_CPU0_P2P2_DN<18>")
	)
	(segment
		(start 102.062026 -292.479476)
		(end 101.962966 -292.578536)
		(width 0.0889)
		(layer "In11.Cu")
		(net "UPI_CPU1_CPU0_P2P2_DN<18>")
	)
	(segment
		(start 246.150638 -359.737406)
		(end 246.634508 -359.39984)
		(width 0.14732)
		(layer "In11.Cu")
		(net "UPI_CPU1_CPU0_P2P2_DN<18>")
	)
	(segment
		(start 337.888326 -281.916886)
		(end 337.887564 -281.916378)
		(width 0.0889)
		(layer "In11.Cu")
		(net "UPI_CPU1_CPU0_P2P2_DN<18>")
	)
	(segment
		(start 244.249448 -361.063032)
		(end 244.733318 -360.725466)
		(width 0.14732)
		(layer "In11.Cu")
		(net "UPI_CPU1_CPU0_P2P2_DN<18>")
	)
	(segment
		(start 236.644688 -366.365536)
		(end 237.128558 -366.02797)
		(width 0.14732)
		(layer "In11.Cu")
		(net "UPI_CPU1_CPU0_P2P2_DN<18>")
	)
	(segment
		(start 102.627938 -290.262056)
		(end 102.726998 -290.361116)
		(width 0.0889)
		(layer "In11.Cu")
		(net "UPI_CPU1_CPU0_P2P2_DN<18>")
	)
	(segment
		(start 101.962966 -293.132256)
		(end 101.962966 -293.310056)
		(width 0.0889)
		(layer "In11.Cu")
		(net "UPI_CPU1_CPU0_P2P2_DN<18>")
	)
	(segment
		(start 104.888792 -282.081478)
		(end 104.897682 -282.086558)
		(width 0.0889)
		(layer "In11.Cu")
		(net "UPI_CPU1_CPU0_P2P2_DN<18>")
	)
	(segment
		(start 337.892898 -281.919426)
		(end 337.891882 -281.918918)
		(width 0.0889)
		(layer "In11.Cu")
		(net "UPI_CPU1_CPU0_P2P2_DN<18>")
	)
	(segment
		(start 232.095294 -369.537234)
		(end 233.026966 -368.887756)
		(width 0.14732)
		(layer "In11.Cu")
		(net "UPI_CPU1_CPU0_P2P2_DN<18>")
	)
	(segment
		(start 269.21714 -337.7311)
		(end 269.63497 -337.31327)
		(width 0.14732)
		(layer "In11.Cu")
		(net "UPI_CPU1_CPU0_P2P2_DN<18>")
	)
	(segment
		(start 283.96184 -327.184004)
		(end 284.119828 -327.565258)
		(width 0.14732)
		(layer "In11.Cu")
		(net "UPI_CPU1_CPU0_P2P2_DN<18>")
	)
	(segment
		(start 103.487982 -285.166816)
		(end 103.479854 -285.171388)
		(width 0.0889)
		(layer "In11.Cu")
		(net "UPI_CPU1_CPU0_P2P2_DN<18>")
	)
	(segment
		(start 237.368842 -367.661444)
		(end 236.608112 -366.57026)
		(width 0.14732)
		(layer "In11.Cu")
		(net "UPI_CPU1_CPU0_P2P2_DN<18>")
	)
	(segment
		(start 104.701594 -282.405836)
		(end 104.38892 -282.405836)
		(width 0.0889)
		(layer "In11.Cu")
		(net "UPI_CPU1_CPU0_P2P2_DN<18>")
	)
	(segment
		(start 200.154286 -370.88064)
		(end 212.31225 -373.024654)
		(width 0.14732)
		(layer "In11.Cu")
		(net "UPI_CPU1_CPU0_P2P2_DN<18>")
	)
	(segment
		(start 102.062026 -293.409116)
		(end 102.062026 -293.798498)
		(width 0.0889)
		(layer "In11.Cu")
		(net "UPI_CPU1_CPU0_P2P2_DN<18>")
	)
	(segment
		(start 104.512872 -282.08224)
		(end 104.514396 -282.081478)
		(width 0.0889)
		(layer "In11.Cu")
		(net "UPI_CPU1_CPU0_P2P2_DN<18>")
	)
	(segment
		(start 103.948992 -284.35808)
		(end 103.942896 -284.361636)
		(width 0.0889)
		(layer "In11.Cu")
		(net "UPI_CPU1_CPU0_P2P2_DN<18>")
	)
	(segment
		(start 237.292388 -368.089942)
		(end 237.368842 -367.661444)
		(width 0.14732)
		(layer "In11.Cu")
		(net "UPI_CPU1_CPU0_P2P2_DN<18>")
	)
	(segment
		(start 309.97525 -318.063118)
		(end 312.613548 -316.970918)
		(width 0.14732)
		(layer "In11.Cu")
		(net "UPI_CPU1_CPU0_P2P2_DN<18>")
	)
	(segment
		(start 104.505506 -282.086558)
		(end 104.512872 -282.08224)
		(width 0.0889)
		(layer "In11.Cu")
		(net "UPI_CPU1_CPU0_P2P2_DN<18>")
	)
	(segment
		(start 312.613548 -316.970918)
		(end 313.026806 -316.55766)
		(width 0.14732)
		(layer "In11.Cu")
		(net "UPI_CPU1_CPU0_P2P2_DN<18>")
	)
	(segment
		(start 102.627938 -290.637976)
		(end 102.627938 -290.815776)
		(width 0.0889)
		(layer "In11.Cu")
		(net "UPI_CPU1_CPU0_P2P2_DN<18>")
	)
	(segment
		(start 241.094768 -365.43869)
		(end 241.171222 -365.010192)
		(width 0.14732)
		(layer "In11.Cu")
		(net "UPI_CPU1_CPU0_P2P2_DN<18>")
	)
	(segment
		(start 337.891882 -281.918918)
		(end 337.89112 -281.91841)
		(width 0.0889)
		(layer "In11.Cu")
		(net "UPI_CPU1_CPU0_P2P2_DN<18>")
	)
	(segment
		(start 244.938042 -360.762042)
		(end 245.698772 -361.853226)
		(width 0.14732)
		(layer "In11.Cu")
		(net "UPI_CPU1_CPU0_P2P2_DN<18>")
	)
	(segment
		(start 241.135662 -363.413294)
		(end 241.896392 -364.504478)
		(width 0.14732)
		(layer "In11.Cu")
		(net "UPI_CPU1_CPU0_P2P2_DN<18>")
	)
	(segment
		(start 242.832128 -362.051092)
		(end 243.036852 -362.087668)
		(width 0.14732)
		(layer "In11.Cu")
		(net "UPI_CPU1_CPU0_P2P2_DN<18>")
	)
	(segment
		(start 236.62132 -368.55781)
		(end 237.292388 -368.089942)
		(width 0.14732)
		(layer "In11.Cu")
		(net "UPI_CPU1_CPU0_P2P2_DN<18>")
	)
	(segment
		(start 102.062026 -292.262306)
		(end 102.062026 -292.479476)
		(width 0.0889)
		(layer "In11.Cu")
		(net "UPI_CPU1_CPU0_P2P2_DN<18>")
	)
	(segment
		(start 243.072412 -363.684566)
		(end 242.311682 -362.593382)
		(width 0.14732)
		(layer "In11.Cu")
		(net "UPI_CPU1_CPU0_P2P2_DN<18>")
	)
	(segment
		(start 102.627938 -290.815776)
		(end 102.726998 -290.914836)
		(width 0.0889)
		(layer "In11.Cu")
		(net "UPI_CPU1_CPU0_P2P2_DN<18>")
	)
	(segment
		(start 305.264058 -322.875656)
		(end 306.165504 -321.974718)
		(width 0.14732)
		(layer "In11.Cu")
		(net "UPI_CPU1_CPU0_P2P2_DN<18>")
	)
	(segment
		(start 279.117298 -329.970384)
		(end 279.283922 -329.568302)
		(width 0.14732)
		(layer "In11.Cu")
		(net "UPI_CPU1_CPU0_P2P2_DN<18>")
	)
	(segment
		(start 305.09464 -322.96608)
		(end 305.264058 -322.875656)
		(width 0.14732)
		(layer "In11.Cu")
		(net "UPI_CPU1_CPU0_P2P2_DN<18>")
	)
	(segment
		(start 243.036852 -362.087668)
		(end 243.890038 -363.31144)
		(width 0.14732)
		(layer "In11.Cu")
		(net "UPI_CPU1_CPU0_P2P2_DN<18>")
	)
	(segment
		(start 71.439278 -335.14284)
		(end 71.439278 -353.229164)
		(width 0.14732)
		(layer "In11.Cu")
		(net "UPI_CPU1_CPU0_P2P2_DN<18>")
	)
	(segment
		(start 270.134334 -337.604862)
		(end 270.570198 -337.604862)
		(width 0.14732)
		(layer "In11.Cu")
		(net "UPI_CPU1_CPU0_P2P2_DN<18>")
	)
	(segment
		(start 285.471362 -327.338436)
		(end 286.919416 -325.890382)
		(width 0.14732)
		(layer "In11.Cu")
		(net "UPI_CPU1_CPU0_P2P2_DN<18>")
	)
	(segment
		(start 313.026806 -316.55766)
		(end 313.026806 -316.54496)
		(width 0.14732)
		(layer "In11.Cu")
		(net "UPI_CPU1_CPU0_P2P2_DN<18>")
	)
	(segment
		(start 336.593688 -291.481256)
		(end 336.593688 -291.421312)
		(width 0.0889)
		(layer "In11.Cu")
		(net "UPI_CPU1_CPU0_P2P2_DN<18>")
	)
	(segment
		(start 102.257098 -288.898584)
		(end 102.257352 -288.898076)
		(width 0.0889)
		(layer "In11.Cu")
		(net "UPI_CPU1_CPU0_P2P2_DN<18>")
	)
	(segment
		(start 234.444286 -367.899696)
		(end 235.227368 -367.353596)
		(width 0.14732)
		(layer "In11.Cu")
		(net "UPI_CPU1_CPU0_P2P2_DN<18>")
	)
	(segment
		(start 246.114062 -359.94213)
		(end 246.150638 -359.737406)
		(width 0.14732)
		(layer "In11.Cu")
		(net "UPI_CPU1_CPU0_P2P2_DN<18>")
	)
	(segment
		(start 242.348258 -362.388658)
		(end 242.832128 -362.051092)
		(width 0.14732)
		(layer "In11.Cu")
		(net "UPI_CPU1_CPU0_P2P2_DN<18>")
	)
	(segment
		(start 235.432092 -367.390172)
		(end 236.192822 -368.481356)
		(width 0.14732)
		(layer "In11.Cu")
		(net "UPI_CPU1_CPU0_P2P2_DN<18>")
	)
	(segment
		(start 279.95372 -328.874374)
		(end 280.10104 -329.22972)
		(width 0.14732)
		(layer "In11.Cu")
		(net "UPI_CPU1_CPU0_P2P2_DN<18>")
	)
	(segment
		(start 292.677596 -325.890382)
		(end 299.60824 -325.890382)
		(width 0.14732)
		(layer "In11.Cu")
		(net "UPI_CPU1_CPU0_P2P2_DN<18>")
	)
	(segment
		(start 314.088018 -315.708792)
		(end 316.267592 -315.708792)
		(width 0.14732)
		(layer "In11.Cu")
		(net "UPI_CPU1_CPU0_P2P2_DN<18>")
	)
	(segment
		(start 338.170012 -289.844988)
		(end 338.170012 -288.917126)
		(width 0.0889)
		(layer "In11.Cu")
		(net "UPI_CPU1_CPU0_P2P2_DN<18>")
	)
	(segment
		(start 336.593688 -291.421312)
		(end 338.170012 -289.844988)
		(width 0.0889)
		(layer "In11.Cu")
		(net "UPI_CPU1_CPU0_P2P2_DN<18>")
	)
	(segment
		(start 235.227368 -367.353596)
		(end 235.432092 -367.390172)
		(width 0.14732)
		(layer "In11.Cu")
		(net "UPI_CPU1_CPU0_P2P2_DN<18>")
	)
	(segment
		(start 338.827364 -283.544264)
		(end 338.818474 -283.539184)
		(width 0.0889)
		(layer "In11.Cu")
		(net "UPI_CPU1_CPU0_P2P2_DN<18>")
	)
	(segment
		(start 238.094012 -367.15573)
		(end 238.52251 -367.232184)
		(width 0.14732)
		(layer "In11.Cu")
		(net "UPI_CPU1_CPU0_P2P2_DN<18>")
	)
	(segment
		(start 234.57789 -368.348768)
		(end 234.40771 -368.10442)
		(width 0.14732)
		(layer "In11.Cu")
		(net "UPI_CPU1_CPU0_P2P2_DN<18>")
	)
	(segment
		(start 97.412302 -303.59858)
		(end 81.592674 -316.580774)
		(width 0.14732)
		(layer "In11.Cu")
		(net "UPI_CPU1_CPU0_P2P2_DN<18>")
	)
	(segment
		(start 244.989604 -362.920026)
		(end 245.066058 -362.491528)
		(width 0.14732)
		(layer "In11.Cu")
		(net "UPI_CPU1_CPU0_P2P2_DN<18>")
	)
	(segment
		(start 284.119828 -327.565258)
		(end 284.52191 -327.731882)
		(width 0.14732)
		(layer "In11.Cu")
		(net "UPI_CPU1_CPU0_P2P2_DN<18>")
	)
	(segment
		(start 238.509302 -365.244634)
		(end 238.545878 -365.03991)
		(width 0.14732)
		(layer "In11.Cu")
		(net "UPI_CPU1_CPU0_P2P2_DN<18>")
	)
	(segment
		(start 126.287276 -377.70435)
		(end 161.449766 -377.70435)
		(width 0.14732)
		(layer "In11.Cu")
		(net "UPI_CPU1_CPU0_P2P2_DN<18>")
	)
	(segment
		(start 268.93139 -339.24367)
		(end 269.508732 -338.666328)
		(width 0.14732)
		(layer "In11.Cu")
		(net "UPI_CPU1_CPU0_P2P2_DN<18>")
	)
	(segment
		(start 337.89366 -281.919934)
		(end 337.892898 -281.919426)
		(width 0.0889)
		(layer "In11.Cu")
		(net "UPI_CPU1_CPU0_P2P2_DN<18>")
	)
	(segment
		(start 303.983136 -324.078092)
		(end 305.09464 -322.96608)
		(width 0.14732)
		(layer "In11.Cu")
		(net "UPI_CPU1_CPU0_P2P2_DN<18>")
	)
	(segment
		(start 241.171222 -365.010192)
		(end 240.410492 -363.919008)
		(width 0.14732)
		(layer "In11.Cu")
		(net "UPI_CPU1_CPU0_P2P2_DN<18>")
	)
	(segment
		(start 249.801634 -358.474264)
		(end 250.230132 -358.550972)
		(width 0.14732)
		(layer "In11.Cu")
		(net "UPI_CPU1_CPU0_P2P2_DN<18>")
	)
	(segment
		(start 336.45602 -291.618924)
		(end 336.578194 -291.49675)
		(width 0.14732)
		(layer "In11.Cu")
		(net "UPI_CPU1_CPU0_P2P2_DN<18>")
	)
	(segment
		(start 250.230132 -358.550972)
		(end 250.9012 -358.083104)
		(width 0.14732)
		(layer "In11.Cu")
		(net "UPI_CPU1_CPU0_P2P2_DN<18>")
	)
	(segment
		(start 102.020116 -293.862506)
		(end 102.020116 -297.304714)
		(width 0.14732)
		(layer "In11.Cu")
		(net "UPI_CPU1_CPU0_P2P2_DN<18>")
	)
	(segment
		(start 244.733318 -360.725466)
		(end 244.938042 -360.762042)
		(width 0.14732)
		(layer "In11.Cu")
		(net "UPI_CPU1_CPU0_P2P2_DN<18>")
	)
	(segment
		(start 279.283922 -329.568302)
		(end 279.136602 -329.212702)
		(width 0.14732)
		(layer "In11.Cu")
		(net "UPI_CPU1_CPU0_P2P2_DN<18>")
	)
	(segment
		(start 246.634508 -359.39984)
		(end 246.839232 -359.436416)
		(width 0.14732)
		(layer "In11.Cu")
		(net "UPI_CPU1_CPU0_P2P2_DN<18>")
	)
	(segment
		(start 72.06488 -328.788776)
		(end 71.439278 -335.14284)
		(width 0.14732)
		(layer "In11.Cu")
		(net "UPI_CPU1_CPU0_P2P2_DN<18>")
	)
	(segment
		(start 307.328316 -320.267584)
		(end 307.815234 -320.076068)
		(width 0.14732)
		(layer "In11.Cu")
		(net "UPI_CPU1_CPU0_P2P2_DN<18>")
	)
	(segment
		(start 240.930938 -363.376718)
		(end 241.135662 -363.413294)
		(width 0.14732)
		(layer "In11.Cu")
		(net "UPI_CPU1_CPU0_P2P2_DN<18>")
	)
	(segment
		(start 253.696724 -354.47859)
		(end 267.869924 -340.305136)
		(width 0.14732)
		(layer "In11.Cu")
		(net "UPI_CPU1_CPU0_P2P2_DN<18>")
	)
	(segment
		(start 103.479854 -285.171388)
		(end 103.479092 -285.171896)
		(width 0.0889)
		(layer "In11.Cu")
		(net "UPI_CPU1_CPU0_P2P2_DN<18>")
	)
	(segment
		(start 269.842742 -337.31327)
		(end 270.134334 -337.604862)
		(width 0.14732)
		(layer "In11.Cu")
		(net "UPI_CPU1_CPU0_P2P2_DN<18>")
	)
	(segment
		(start 246.839232 -359.436416)
		(end 247.599962 -360.5276)
		(width 0.14732)
		(layer "In11.Cu")
		(net "UPI_CPU1_CPU0_P2P2_DN<18>")
	)
	(segment
		(start 102.726998 -291.597334)
		(end 102.501446 -291.822886)
		(width 0.0889)
		(layer "In11.Cu")
		(net "UPI_CPU1_CPU0_P2P2_DN<18>")
	)
	(segment
		(start 102.726998 -291.468556)
		(end 102.726998 -291.597334)
		(width 0.0889)
		(layer "In11.Cu")
		(net "UPI_CPU1_CPU0_P2P2_DN<18>")
	)
	(segment
		(start 246.874792 -361.033314)
		(end 246.114062 -359.94213)
		(width 0.14732)
		(layer "In11.Cu")
		(net "UPI_CPU1_CPU0_P2P2_DN<18>")
	)
	(segment
		(start 102.062026 -292.855396)
		(end 102.062026 -293.033196)
		(width 0.0889)
		(layer "In11.Cu")
		(net "UPI_CPU1_CPU0_P2P2_DN<18>")
	)
	(segment
		(start 71.439278 -353.229164)
		(end 75.228196 -362.363512)
		(width 0.14732)
		(layer "In11.Cu")
		(net "UPI_CPU1_CPU0_P2P2_DN<18>")
	)
	(segment
		(start 102.726998 -290.361116)
		(end 102.726998 -290.538916)
		(width 0.0889)
		(layer "In11.Cu")
		(net "UPI_CPU1_CPU0_P2P2_DN<18>")
	)
	(segment
		(start 337.448398 -281.049222)
		(end 337.604862 -280.778204)
		(width 0.0889)
		(layer "In11.Cu")
		(net "UPI_CPU1_CPU0_P2P2_DN<18>")
	)
	(segment
		(start 243.890038 -363.31144)
		(end 244.318536 -363.387894)
		(width 0.14732)
		(layer "In11.Cu")
		(net "UPI_CPU1_CPU0_P2P2_DN<18>")
	)
	(segment
		(start 337.700366 -281.600656)
		(end 337.700366 -281.59202)
		(width 0.0889)
		(layer "In11.Cu")
		(net "UPI_CPU1_CPU0_P2P2_DN<18>")
	)
	(segment
		(start 102.257352 -288.898076)
		(end 102.257352 -289.113976)
		(width 0.0889)
		(layer "In11.Cu")
		(net "UPI_CPU1_CPU0_P2P2_DN<18>")
	)
	(segment
		(start 337.472528 -281.138376)
		(end 337.448398 -281.049222)
		(width 0.0889)
		(layer "In11.Cu")
		(net "UPI_CPU1_CPU0_P2P2_DN<18>")
	)
	(segment
		(start 279.21585 -329.020932)
		(end 279.761696 -328.794872)
		(width 0.14732)
		(layer "In11.Cu")
		(net "UPI_CPU1_CPU0_P2P2_DN<18>")
	)
	(segment
		(start 246.12727 -361.92968)
		(end 246.798338 -361.461812)
		(width 0.14732)
		(layer "In11.Cu")
		(net "UPI_CPU1_CPU0_P2P2_DN<18>")
	)
	(segment
		(start 338.639912 -288.125154)
		(end 338.639912 -288.103056)
		(width 0.0889)
		(layer "In11.Cu")
		(net "UPI_CPU1_CPU0_P2P2_DN<18>")
	)
	(segment
		(start 290.970716 -325.890382)
		(end 291.107876 -326.027542)
		(width 0.14732)
		(layer "In11.Cu")
		(net "UPI_CPU1_CPU0_P2P2_DN<18>")
	)
	(segment
		(start 292.540436 -327.618852)
		(end 292.540436 -326.027542)
		(width 0.14732)
		(layer "In11.Cu")
		(net "UPI_CPU1_CPU0_P2P2_DN<18>")
	)
	(segment
		(start 337.89112 -281.91841)
		(end 337.888326 -281.916886)
		(width 0.0889)
		(layer "In11.Cu")
		(net "UPI_CPU1_CPU0_P2P2_DN<18>")
	)
	(segment
		(start 103.666544 -286.466788)
		(end 103.666544 -286.48406)
		(width 0.0889)
		(layer "In11.Cu")
		(net "UPI_CPU1_CPU0_P2P2_DN<18>")
	)
	(segment
		(start 102.062026 -293.033196)
		(end 101.962966 -293.132256)
		(width 0.0889)
		(layer "In11.Cu")
		(net "UPI_CPU1_CPU0_P2P2_DN<18>")
	)
	(segment
		(start 103.018082 -287.608518)
		(end 103.009192 -287.613598)
		(width 0.0889)
		(layer "In11.Cu")
		(net "UPI_CPU1_CPU0_P2P2_DN<18>")
	)
	(segment
		(start 102.726998 -290.914836)
		(end 102.726998 -291.092636)
		(width 0.0889)
		(layer "In11.Cu")
		(net "UPI_CPU1_CPU0_P2P2_DN<18>")
	)
	(segment
		(start 339.297518 -285.985712)
		(end 339.288628 -285.980632)
		(width 0.0889)
		(layer "In11.Cu")
		(net "UPI_CPU1_CPU0_P2P2_DN<18>")
	)
	(segment
		(start 102.726998 -291.092636)
		(end 102.627938 -291.191696)
		(width 0.0889)
		(layer "In11.Cu")
		(net "UPI_CPU1_CPU0_P2P2_DN<18>")
	)
	(segment
		(start 234.40771 -368.10442)
		(end 234.444286 -367.899696)
		(width 0.14732)
		(layer "In11.Cu")
		(net "UPI_CPU1_CPU0_P2P2_DN<18>")
	)
	(segment
		(start 249.08002 -357.6955)
		(end 249.284744 -357.732076)
		(width 0.14732)
		(layer "In11.Cu")
		(net "UPI_CPU1_CPU0_P2P2_DN<18>")
	)
	(segment
		(start 236.192822 -368.481356)
		(end 236.62132 -368.55781)
		(width 0.14732)
		(layer "In11.Cu")
		(net "UPI_CPU1_CPU0_P2P2_DN<18>")
	)
	(segment
		(start 212.31225 -373.024654)
		(end 232.095294 -369.537234)
		(width 0.14732)
		(layer "In11.Cu")
		(net "UPI_CPU1_CPU0_P2P2_DN<18>")
	)
	(segment
		(start 239.270032 -366.335818)
		(end 238.509302 -365.244634)
		(width 0.14732)
		(layer "In11.Cu")
		(net "UPI_CPU1_CPU0_P2P2_DN<18>")
	)
	(segment
		(start 307.815234 -320.076068)
		(end 309.97525 -318.063372)
		(width 0.14732)
		(layer "In11.Cu")
		(net "UPI_CPU1_CPU0_P2P2_DN<18>")
	)
	(segment
		(start 248.02846 -360.604054)
		(end 248.699528 -360.136186)
		(width 0.14732)
		(layer "In11.Cu")
		(net "UPI_CPU1_CPU0_P2P2_DN<18>")
	)
	(segment
		(start 286.919416 -325.890382)
		(end 290.970716 -325.890382)
		(width 0.14732)
		(layer "In11.Cu")
		(net "UPI_CPU1_CPU0_P2P2_DN<18>")
	)
	(segment
		(start 246.798338 -361.461812)
		(end 246.874792 -361.033314)
		(width 0.14732)
		(layer "In11.Cu")
		(net "UPI_CPU1_CPU0_P2P2_DN<18>")
	)
	(arc
		(start 103.666544 -286.48406)
		(mid 103.614274 -286.666425)
		(end 103.479346 -286.799782)
		(width 0.0889)
		(layer "In11.Cu")
		(net "UPI_CPU1_CPU0_P2P2_DN<18>")
	)
	(arc
		(start 103.666544 -284.847538)
		(mid 103.618865 -285.030438)
		(end 103.487982 -285.166816)
		(width 0.0889)
		(layer "In11.Cu")
		(net "UPI_CPU1_CPU0_P2P2_DN<18>")
	)
	(arc
		(start 102.257352 -289.113976)
		(mid 102.368582 -289.30718)
		(end 102.542848 -289.446208)
		(width 0.0889)
		(layer "In11.Cu")
		(net "UPI_CPU1_CPU0_P2P2_DN<18>")
	)
	(arc
		(start 337.887564 -281.916378)
		(mid 337.752631 -281.783024)
		(end 337.700366 -281.600656)
		(width 0.0889)
		(layer "In11.Cu")
		(net "UPI_CPU1_CPU0_P2P2_DN<18>")
	)
	(arc
		(start 104.331516 -282.348432)
		(mid 104.389672 -282.198319)
		(end 104.505506 -282.086558)
		(width 0.0889)
		(layer "In11.Cu")
		(net "UPI_CPU1_CPU0_P2P2_DN<18>")
	)
	(arc
		(start 337.700366 -281.59202)
		(mid 337.640323 -281.338133)
		(end 337.472528 -281.138376)
		(width 0.0889)
		(layer "In11.Cu")
		(net "UPI_CPU1_CPU0_P2P2_DN<18>")
	)
	(arc
		(start 104.418892 -283.544264)
		(mid 104.214557 -283.746869)
		(end 104.136444 -284.023816)
		(width 0.0889)
		(layer "In11.Cu")
		(net "UPI_CPU1_CPU0_P2P2_DN<18>")
	)
	(arc
		(start 339.288628 -285.980632)
		(mid 339.161374 -285.850666)
		(end 339.11032 -285.676086)
		(width 0.0889)
		(layer "In11.Cu")
		(net "UPI_CPU1_CPU0_P2P2_DN<18>")
	)
	(arc
		(start 339.109812 -284.023816)
		(mid 339.031701 -283.746867)
		(end 338.827364 -283.544264)
		(width 0.0889)
		(layer "In11.Cu")
		(net "UPI_CPU1_CPU0_P2P2_DN<18>")
	)
	(arc
		(start 338.639912 -283.197808)
		(mid 338.559001 -282.92768)
		(end 338.357718 -282.730194)
		(width 0.0889)
		(layer "In11.Cu")
		(net "UPI_CPU1_CPU0_P2P2_DN<18>")
	)
	(arc
		(start 339.110066 -285.661354)
		(mid 339.157745 -285.478454)
		(end 339.288628 -285.342076)
		(width 0.0889)
		(layer "In11.Cu")
		(net "UPI_CPU1_CPU0_P2P2_DN<18>")
	)
	(arc
		(start 338.348828 -282.725114)
		(mid 338.221574 -282.595148)
		(end 338.17052 -282.420568)
		(width 0.0889)
		(layer "In11.Cu")
		(net "UPI_CPU1_CPU0_P2P2_DN<18>")
	)
	(arc
		(start 102.726998 -288.103056)
		(mid 102.679319 -288.285956)
		(end 102.548436 -288.422334)
		(width 0.0889)
		(layer "In11.Cu")
		(net "UPI_CPU1_CPU0_P2P2_DN<18>")
	)
	(arc
		(start 103.196644 -285.675578)
		(mid 103.275863 -285.950263)
		(end 103.479346 -286.151066)
		(width 0.0889)
		(layer "In11.Cu")
		(net "UPI_CPU1_CPU0_P2P2_DN<18>")
	)
	(arc
		(start 103.479092 -285.171896)
		(mid 103.274757 -285.374501)
		(end 103.196644 -285.651448)
		(width 0.0889)
		(layer "In11.Cu")
		(net "UPI_CPU1_CPU0_P2P2_DN<18>")
	)
	(arc
		(start 339.579712 -284.837632)
		(mid 339.501601 -284.560683)
		(end 339.297264 -284.35808)
		(width 0.0889)
		(layer "In11.Cu")
		(net "UPI_CPU1_CPU0_P2P2_DN<18>")
	)
	(arc
		(start 338.818474 -283.539184)
		(mid 338.68756 -283.402824)
		(end 338.639912 -283.219906)
		(width 0.0889)
		(layer "In11.Cu")
		(net "UPI_CPU1_CPU0_P2P2_DN<18>")
	)
	(arc
		(start 102.539546 -288.427414)
		(mid 102.33726 -288.626395)
		(end 102.257098 -288.898584)
		(width 0.0889)
		(layer "In11.Cu")
		(net "UPI_CPU1_CPU0_P2P2_DN<18>")
	)
	(arc
		(start 103.479346 -286.151066)
		(mid 103.614279 -286.28442)
		(end 103.666544 -286.466788)
		(width 0.0889)
		(layer "In11.Cu")
		(net "UPI_CPU1_CPU0_P2P2_DN<18>")
	)
	(arc
		(start 104.897682 -282.086558)
		(mid 105.028596 -282.222918)
		(end 105.076244 -282.405836)
		(width 0.0889)
		(layer "In11.Cu")
		(net "UPI_CPU1_CPU0_P2P2_DN<18>")
	)
	(arc
		(start 105.076244 -282.405836)
		(mid 105.076192 -282.413203)
		(end 105.07599 -282.420568)
		(width 0.0889)
		(layer "In11.Cu")
		(net "UPI_CPU1_CPU0_P2P2_DN<18>")
	)
	(arc
		(start 338.357718 -288.592768)
		(mid 338.559 -288.395281)
		(end 338.639912 -288.125154)
		(width 0.0889)
		(layer "In11.Cu")
		(net "UPI_CPU1_CPU0_P2P2_DN<18>")
	)
	(arc
		(start 103.009192 -287.613598)
		(mid 102.806369 -287.813829)
		(end 102.726998 -288.087562)
		(width 0.0889)
		(layer "In11.Cu")
		(net "UPI_CPU1_CPU0_P2P2_DN<18>")
	)
	(arc
		(start 339.303614 -286.961326)
		(mid 339.506027 -286.754913)
		(end 339.579966 -286.475424)
		(width 0.0889)
		(layer "In11.Cu")
		(net "UPI_CPU1_CPU0_P2P2_DN<18>")
	)
	(arc
		(start 102.542848 -289.446208)
		(mid 102.651928 -289.529909)
		(end 102.726998 -289.64509)
		(width 0.0889)
		(layer "In11.Cu")
		(net "UPI_CPU1_CPU0_P2P2_DN<18>")
	)
	(arc
		(start 339.579966 -286.4612)
		(mid 339.500825 -286.186577)
		(end 339.297518 -285.985712)
		(width 0.0889)
		(layer "In11.Cu")
		(net "UPI_CPU1_CPU0_P2P2_DN<18>")
	)
	(arc
		(start 338.170266 -282.405836)
		(mid 338.096275 -282.12627)
		(end 337.89366 -281.919934)
		(width 0.0889)
		(layer "In11.Cu")
		(net "UPI_CPU1_CPU0_P2P2_DN<18>")
	)
	(arc
		(start 338.83346 -287.775142)
		(mid 339.036047 -287.568791)
		(end 339.110066 -287.28924)
		(width 0.0889)
		(layer "In11.Cu")
		(net "UPI_CPU1_CPU0_P2P2_DN<18>")
	)
	(arc
		(start 338.170012 -288.917126)
		(mid 338.216016 -288.737189)
		(end 338.342732 -288.601404)
		(width 0.0889)
		(layer "In11.Cu")
		(net "UPI_CPU1_CPU0_P2P2_DN<18>")
	)
	(arc
		(start 338.639912 -288.103056)
		(mid 338.687591 -287.920156)
		(end 338.818474 -287.783778)
		(width 0.0889)
		(layer "In11.Cu")
		(net "UPI_CPU1_CPU0_P2P2_DN<18>")
	)
	(arc
		(start 103.196644 -287.28924)
		(mid 103.148965 -287.47214)
		(end 103.018082 -287.608518)
		(width 0.0889)
		(layer "In11.Cu")
		(net "UPI_CPU1_CPU0_P2P2_DN<18>")
	)
	(arc
		(start 104.888792 -282.730194)
		(mid 104.685487 -282.93106)
		(end 104.606344 -283.205682)
		(width 0.0889)
		(layer "In11.Cu")
		(net "UPI_CPU1_CPU0_P2P2_DN<18>")
	)
	(arc
		(start 339.288374 -284.353)
		(mid 339.15746 -284.21664)
		(end 339.109812 -284.033722)
		(width 0.0889)
		(layer "In11.Cu")
		(net "UPI_CPU1_CPU0_P2P2_DN<18>")
	)
	(arc
		(start 103.942896 -284.361636)
		(mid 103.740483 -284.568049)
		(end 103.666544 -284.847538)
		(width 0.0889)
		(layer "In11.Cu")
		(net "UPI_CPU1_CPU0_P2P2_DN<18>")
	)
	(arc
		(start 338.17052 -282.420568)
		(mid 338.170323 -282.413203)
		(end 338.170266 -282.405836)
		(width 0.0889)
		(layer "In11.Cu")
		(net "UPI_CPU1_CPU0_P2P2_DN<18>")
	)
	(arc
		(start 339.110066 -287.28924)
		(mid 339.157745 -287.10634)
		(end 339.288628 -286.969962)
		(width 0.0889)
		(layer "In11.Cu")
		(net "UPI_CPU1_CPU0_P2P2_DN<18>")
	)
	(arc
		(start 339.297518 -285.336996)
		(mid 339.500341 -285.136765)
		(end 339.579712 -284.863032)
		(width 0.0889)
		(layer "In11.Cu")
		(net "UPI_CPU1_CPU0_P2P2_DN<18>")
	)
	(arc
		(start 105.07599 -282.420568)
		(mid 105.024936 -282.595148)
		(end 104.897682 -282.725114)
		(width 0.0889)
		(layer "In11.Cu")
		(net "UPI_CPU1_CPU0_P2P2_DN<18>")
	)
	(arc
		(start 339.11032 -285.676086)
		(mid 339.110123 -285.668721)
		(end 339.110066 -285.661354)
		(width 0.0889)
		(layer "In11.Cu")
		(net "UPI_CPU1_CPU0_P2P2_DN<18>")
	)
	(arc
		(start 104.136444 -284.033722)
		(mid 104.088765 -284.216622)
		(end 103.957882 -284.353)
		(width 0.0889)
		(layer "In11.Cu")
		(net "UPI_CPU1_CPU0_P2P2_DN<18>")
	)
	(arc
		(start 104.514396 -282.081478)
		(mid 104.701594 -282.031335)
		(end 104.888792 -282.081478)
		(width 0.0889)
		(layer "In11.Cu")
		(net "UPI_CPU1_CPU0_P2P2_DN<18>")
	)
	(arc
		(start 104.606344 -283.219906)
		(mid 104.558665 -283.402806)
		(end 104.427782 -283.539184)
		(width 0.0889)
		(layer "In11.Cu")
		(net "UPI_CPU1_CPU0_P2P2_DN<18>")
	)
	(arc
		(start 103.47325 -286.803338)
		(mid 103.270663 -287.009689)
		(end 103.196644 -287.28924)
		(width 0.0889)
		(layer "In11.Cu")
		(net "UPI_CPU1_CPU0_P2P2_DN<18>")
	)
	(segment
		(start 343.243916 -280.77795)
		(end 343.243662 -280.778204)
		(width 0.13208)
		(layer "F.Cu")
		(net "UPI_CPU1_CPU0_P2P2_DN<17>")
	)
	(segment
		(start 343.243916 -280.242264)
		(end 343.243916 -280.77795)
		(width 0.13208)
		(layer "F.Cu")
		(net "UPI_CPU1_CPU0_P2P2_DN<17>")
	)
	(segment
		(start 103.762048 -280.77795)
		(end 103.761794 -280.778204)
		(width 0.13208)
		(layer "F.Cu")
		(net "UPI_CPU1_CPU0_P2P2_DN<17>")
	)
	(segment
		(start 103.762048 -280.242264)
		(end 103.762048 -280.77795)
		(width 0.13208)
		(layer "F.Cu")
		(net "UPI_CPU1_CPU0_P2P2_DN<17>")
	)
	(segment
		(start 161.53384 -378.27077)
		(end 126.281688 -378.27077)
		(width 0.14732)
		(layer "In11.Cu")
		(net "UPI_CPU1_CPU0_P2P2_DN<17>")
	)
	(segment
		(start 103.387398 -282.414472)
		(end 103.387398 -282.405836)
		(width 0.0889)
		(layer "In11.Cu")
		(net "UPI_CPU1_CPU0_P2P2_DN<17>")
	)
	(segment
		(start 252.378972 -366.453674)
		(end 248.782078 -361.317032)
		(width 0.14732)
		(layer "In11.Cu")
		(net "UPI_CPU1_CPU0_P2P2_DN<17>")
	)
	(segment
		(start 338.465668 -289.569398)
		(end 338.449666 -289.768788)
		(width 0.0889)
		(layer "In11.Cu")
		(net "UPI_CPU1_CPU0_P2P2_DN<17>")
	)
	(segment
		(start 101.460046 -290.598352)
		(end 101.585522 -290.472876)
		(width 0.0889)
		(layer "In11.Cu")
		(net "UPI_CPU1_CPU0_P2P2_DN<17>")
	)
	(segment
		(start 335.93659 -292.82898)
		(end 335.74736 -292.750748)
		(width 0.14732)
		(layer "In11.Cu")
		(net "UPI_CPU1_CPU0_P2P2_DN<17>")
	)
	(segment
		(start 339.680804 -287.608518)
		(end 339.659722 -287.62071)
		(width 0.0889)
		(layer "In11.Cu")
		(net "UPI_CPU1_CPU0_P2P2_DN<17>")
	)
	(segment
		(start 101.193854 -290.864544)
		(end 101.334316 -290.864544)
		(width 0.0889)
		(layer "In11.Cu")
		(net "UPI_CPU1_CPU0_P2P2_DN<17>")
	)
	(segment
		(start 71.519288 -328.67854)
		(end 72.145906 -326.415146)
		(width 0.14732)
		(layer "In11.Cu")
		(net "UPI_CPU1_CPU0_P2P2_DN<17>")
	)
	(segment
		(start 98.207322 -301.445168)
		(end 98.920046 -299.724064)
		(width 0.14732)
		(layer "In11.Cu")
		(net "UPI_CPU1_CPU0_P2P2_DN<17>")
	)
	(segment
		(start 253.81331 -355.149404)
		(end 253.456694 -355.398832)
		(width 0.14732)
		(layer "In11.Cu")
		(net "UPI_CPU1_CPU0_P2P2_DN<17>")
	)
	(segment
		(start 338.008722 -291.071046)
		(end 337.803998 -291.071046)
		(width 0.14732)
		(layer "In11.Cu")
		(net "UPI_CPU1_CPU0_P2P2_DN<17>")
	)
	(segment
		(start 246.454676 -362.570522)
		(end 236.889544 -369.26774)
		(width 0.14732)
		(layer "In11.Cu")
		(net "UPI_CPU1_CPU0_P2P2_DN<17>")
	)
	(segment
		(start 253.429008 -355.438456)
		(end 250.340114 -359.849928)
		(width 0.14732)
		(layer "In11.Cu")
		(net "UPI_CPU1_CPU0_P2P2_DN<17>")
	)
	(segment
		(start 102.641146 -285.333186)
		(end 102.640892 -285.33344)
		(width 0.0889)
		(layer "In11.Cu")
		(net "UPI_CPU1_CPU0_P2P2_DN<17>")
	)
	(segment
		(start 96.720914 -303.44872)
		(end 98.207322 -301.445168)
		(width 0.14732)
		(layer "In11.Cu")
		(net "UPI_CPU1_CPU0_P2P2_DN<17>")
	)
	(segment
		(start 103.99649 -281.07005)
		(end 103.918258 -281.049222)
		(width 0.0889)
		(layer "In11.Cu")
		(net "UPI_CPU1_CPU0_P2P2_DN<17>")
	)
	(segment
		(start 315.654436 -317.10884)
		(end 315.201046 -317.296292)
		(width 0.14732)
		(layer "In11.Cu")
		(net "UPI_CPU1_CPU0_P2P2_DN<17>")
	)
	(segment
		(start 101.851714 -290.347146)
		(end 101.851714 -290.206684)
		(width 0.0889)
		(layer "In11.Cu")
		(net "UPI_CPU1_CPU0_P2P2_DN<17>")
	)
	(segment
		(start 103.918258 -281.049222)
		(end 103.761794 -280.778204)
		(width 0.0889)
		(layer "In11.Cu")
		(net "UPI_CPU1_CPU0_P2P2_DN<17>")
	)
	(segment
		(start 310.044338 -319.11163)
		(end 309.098696 -319.984882)
		(width 0.14732)
		(layer "In11.Cu")
		(net "UPI_CPU1_CPU0_P2P2_DN<17>")
	)
	(segment
		(start 336.472784 -292.606984)
		(end 335.93659 -292.82898)
		(width 0.14732)
		(layer "In11.Cu")
		(net "UPI_CPU1_CPU0_P2P2_DN<17>")
	)
	(segment
		(start 253.456694 -355.398832)
		(end 253.429008 -355.438456)
		(width 0.14732)
		(layer "In11.Cu")
		(net "UPI_CPU1_CPU0_P2P2_DN<17>")
	)
	(segment
		(start 200.171558 -371.458998)
		(end 161.53384 -378.27077)
		(width 0.14732)
		(layer "In11.Cu")
		(net "UPI_CPU1_CPU0_P2P2_DN<17>")
	)
	(segment
		(start 100.486972 -293.907972)
		(end 100.486972 -293.718234)
		(width 0.0889)
		(layer "In11.Cu")
		(net "UPI_CPU1_CPU0_P2P2_DN<17>")
	)
	(segment
		(start 100.486972 -292.057074)
		(end 100.586032 -291.958014)
		(width 0.0889)
		(layer "In11.Cu")
		(net "UPI_CPU1_CPU0_P2P2_DN<17>")
	)
	(segment
		(start 338.449666 -289.768788)
		(end 338.449666 -290.275518)
		(width 0.0889)
		(layer "In11.Cu")
		(net "UPI_CPU1_CPU0_P2P2_DN<17>")
	)
	(segment
		(start 100.586032 -293.619174)
		(end 100.586032 -293.441374)
		(width 0.0889)
		(layer "In11.Cu")
		(net "UPI_CPU1_CPU0_P2P2_DN<17>")
	)
	(segment
		(start 100.586032 -294.184832)
		(end 100.586032 -294.007032)
		(width 0.0889)
		(layer "In11.Cu")
		(net "UPI_CPU1_CPU0_P2P2_DN<17>")
	)
	(segment
		(start 335.74736 -292.750748)
		(end 335.406746 -292.891718)
		(width 0.14732)
		(layer "In11.Cu")
		(net "UPI_CPU1_CPU0_P2P2_DN<17>")
	)
	(segment
		(start 70.877938 -335.190084)
		(end 71.519288 -328.67854)
		(width 0.14732)
		(layer "In11.Cu")
		(net "UPI_CPU1_CPU0_P2P2_DN<17>")
	)
	(segment
		(start 100.486972 -291.681154)
		(end 100.486972 -291.571426)
		(width 0.0889)
		(layer "In11.Cu")
		(net "UPI_CPU1_CPU0_P2P2_DN<17>")
	)
	(segment
		(start 103.110792 -281.919934)
		(end 103.104696 -281.916378)
		(width 0.0889)
		(layer "In11.Cu")
		(net "UPI_CPU1_CPU0_P2P2_DN<17>")
	)
	(segment
		(start 338.407756 -290.317428)
		(end 338.407756 -290.339526)
		(width 0.0889)
		(layer "In11.Cu")
		(net "UPI_CPU1_CPU0_P2P2_DN<17>")
	)
	(segment
		(start 99.312984 -298.775882)
		(end 99.502468 -298.697396)
		(width 0.14732)
		(layer "In11.Cu")
		(net "UPI_CPU1_CPU0_P2P2_DN<17>")
	)
	(segment
		(start 98.920046 -299.724064)
		(end 99.10953 -299.645578)
		(width 0.14732)
		(layer "In11.Cu")
		(net "UPI_CPU1_CPU0_P2P2_DN<17>")
	)
	(segment
		(start 337.543394 -291.33165)
		(end 337.543394 -291.536374)
		(width 0.14732)
		(layer "In11.Cu")
		(net "UPI_CPU1_CPU0_P2P2_DN<17>")
	)
	(segment
		(start 100.486972 -293.718234)
		(end 100.586032 -293.619174)
		(width 0.0889)
		(layer "In11.Cu")
		(net "UPI_CPU1_CPU0_P2P2_DN<17>")
	)
	(segment
		(start 103.857044 -283.229812)
		(end 103.857044 -283.201364)
		(width 0.0889)
		(layer "In11.Cu")
		(net "UPI_CPU1_CPU0_P2P2_DN<17>")
	)
	(segment
		(start 74.747628 -362.67009)
		(end 70.877938 -353.327462)
		(width 0.14732)
		(layer "In11.Cu")
		(net "UPI_CPU1_CPU0_P2P2_DN<17>")
	)
	(segment
		(start 100.586032 -292.511734)
		(end 100.586032 -292.333934)
		(width 0.0889)
		(layer "In11.Cu")
		(net "UPI_CPU1_CPU0_P2P2_DN<17>")
	)
	(segment
		(start 102.447344 -287.304734)
		(end 102.447344 -287.28924)
		(width 0.0889)
		(layer "In11.Cu")
		(net "UPI_CPU1_CPU0_P2P2_DN<17>")
	)
	(segment
		(start 338.465414 -289.569144)
		(end 338.465668 -289.569398)
		(width 0.0889)
		(layer "In11.Cu")
		(net "UPI_CPU1_CPU0_P2P2_DN<17>")
	)
	(segment
		(start 315.201046 -317.296292)
		(end 315.01207 -317.217806)
		(width 0.14732)
		(layer "In11.Cu")
		(net "UPI_CPU1_CPU0_P2P2_DN<17>")
	)
	(segment
		(start 340.144862 -284.525212)
		(end 340.15045 -284.52826)
		(width 0.0889)
		(layer "In11.Cu")
		(net "UPI_CPU1_CPU0_P2P2_DN<17>")
	)
	(segment
		(start 100.486972 -294.461692)
		(end 100.486972 -294.283892)
		(width 0.0889)
		(layer "In11.Cu")
		(net "UPI_CPU1_CPU0_P2P2_DN<17>")
	)
	(segment
		(start 337.07832 -291.796724)
		(end 336.817716 -292.057328)
		(width 0.14732)
		(layer "In11.Cu")
		(net "UPI_CPU1_CPU0_P2P2_DN<17>")
	)
	(segment
		(start 334.663288 -293.39032)
		(end 333.676752 -294.867076)
		(width 0.14732)
		(layer "In11.Cu")
		(net "UPI_CPU1_CPU0_P2P2_DN<17>")
	)
	(segment
		(start 101.507798 -289.078416)
		(end 101.507798 -288.917126)
		(width 0.0889)
		(layer "In11.Cu")
		(net "UPI_CPU1_CPU0_P2P2_DN<17>")
	)
	(segment
		(start 102.917498 -281.600656)
		(end 102.917498 -281.583384)
		(width 0.0889)
		(layer "In11.Cu")
		(net "UPI_CPU1_CPU0_P2P2_DN<17>")
	)
	(segment
		(start 100.486972 -293.164514)
		(end 100.586032 -293.065454)
		(width 0.0889)
		(layer "In11.Cu")
		(net "UPI_CPU1_CPU0_P2P2_DN<17>")
	)
	(segment
		(start 102.917498 -284.847538)
		(end 102.917498 -284.838902)
		(width 0.0889)
		(layer "In11.Cu")
		(net "UPI_CPU1_CPU0_P2P2_DN<17>")
	)
	(segment
		(start 309.098696 -319.984882)
		(end 308.915562 -320.539364)
		(width 0.14732)
		(layer "In11.Cu")
		(net "UPI_CPU1_CPU0_P2P2_DN<17>")
	)
	(segment
		(start 308.616858 -320.981324)
		(end 308.708806 -321.164204)
		(width 0.14732)
		(layer "In11.Cu")
		(net "UPI_CPU1_CPU0_P2P2_DN<17>")
	)
	(segment
		(start 100.508308 -295.890188)
		(end 100.529136 -295.86936)
		(width 0.14732)
		(layer "In11.Cu")
		(net "UPI_CPU1_CPU0_P2P2_DN<17>")
	)
	(segment
		(start 337.283044 -291.796724)
		(end 337.07832 -291.796724)
		(width 0.14732)
		(layer "In11.Cu")
		(net "UPI_CPU1_CPU0_P2P2_DN<17>")
	)
	(segment
		(start 246.883682 -362.646468)
		(end 246.454676 -362.570522)
		(width 0.14732)
		(layer "In11.Cu")
		(net "UPI_CPU1_CPU0_P2P2_DN<17>")
	)
	(segment
		(start 101.851714 -290.206684)
		(end 101.97719 -290.081208)
		(width 0.0889)
		(layer "In11.Cu")
		(net "UPI_CPU1_CPU0_P2P2_DN<17>")
	)
	(segment
		(start 308.708806 -321.164204)
		(end 308.57825 -321.559682)
		(width 0.14732)
		(layer "In11.Cu")
		(net "UPI_CPU1_CPU0_P2P2_DN<17>")
	)
	(segment
		(start 100.486972 -291.571426)
		(end 100.802186 -291.256212)
		(width 0.0889)
		(layer "In11.Cu")
		(net "UPI_CPU1_CPU0_P2P2_DN<17>")
	)
	(segment
		(start 336.817716 -292.057328)
		(end 336.817716 -292.262052)
		(width 0.14732)
		(layer "In11.Cu")
		(net "UPI_CPU1_CPU0_P2P2_DN<17>")
	)
	(segment
		(start 100.529136 -295.290748)
		(end 100.486972 -295.248584)
		(width 0.0889)
		(layer "In11.Cu")
		(net "UPI_CPU1_CPU0_P2P2_DN<17>")
	)
	(segment
		(start 253.10338 -365.946436)
		(end 253.067312 -366.150906)
		(width 0.14732)
		(layer "In11.Cu")
		(net "UPI_CPU1_CPU0_P2P2_DN<17>")
	)
	(segment
		(start 103.10749 -281.265884)
		(end 103.108506 -281.265376)
		(width 0.0889)
		(layer "In11.Cu")
		(net "UPI_CPU1_CPU0_P2P2_DN<17>")
	)
	(segment
		(start 314.59297 -317.548006)
		(end 312.388758 -318.459612)
		(width 0.14732)
		(layer "In11.Cu")
		(net "UPI_CPU1_CPU0_P2P2_DN<17>")
	)
	(segment
		(start 212.31225 -373.599964)
		(end 200.171558 -371.458998)
		(width 0.14732)
		(layer "In11.Cu")
		(net "UPI_CPU1_CPU0_P2P2_DN<17>")
	)
	(segment
		(start 100.486972 -294.283892)
		(end 100.586032 -294.184832)
		(width 0.0889)
		(layer "In11.Cu")
		(net "UPI_CPU1_CPU0_P2P2_DN<17>")
	)
	(segment
		(start 102.634796 -285.985712)
		(end 102.634034 -285.985204)
		(width 0.0889)
		(layer "In11.Cu")
		(net "UPI_CPU1_CPU0_P2P2_DN<17>")
	)
	(segment
		(start 101.977698 -288.121598)
		(end 101.977698 -288.103056)
		(width 0.0889)
		(layer "In11.Cu")
		(net "UPI_CPU1_CPU0_P2P2_DN<17>")
	)
	(segment
		(start 340.142322 -284.523688)
		(end 340.144862 -284.525212)
		(width 0.0889)
		(layer "In11.Cu")
		(net "UPI_CPU1_CPU0_P2P2_DN<17>")
	)
	(segment
		(start 277.768304 -331.199744)
		(end 253.81331 -355.149404)
		(width 0.14732)
		(layer "In11.Cu")
		(net "UPI_CPU1_CPU0_P2P2_DN<17>")
	)
	(segment
		(start 338.449666 -290.275518)
		(end 338.407756 -290.317428)
		(width 0.0889)
		(layer "In11.Cu")
		(net "UPI_CPU1_CPU0_P2P2_DN<17>")
	)
	(segment
		(start 99.172268 -299.115988)
		(end 99.312984 -298.775882)
		(width 0.14732)
		(layer "In11.Cu")
		(net "UPI_CPU1_CPU0_P2P2_DN<17>")
	)
	(segment
		(start 100.586032 -294.560752)
		(end 100.486972 -294.461692)
		(width 0.0889)
		(layer "In11.Cu")
		(net "UPI_CPU1_CPU0_P2P2_DN<17>")
	)
	(segment
		(start 100.529136 -295.86936)
		(end 100.529136 -295.312846)
		(width 0.14732)
		(layer "In11.Cu")
		(net "UPI_CPU1_CPU0_P2P2_DN<17>")
	)
	(segment
		(start 102.634034 -285.985204)
		(end 102.625906 -285.980632)
		(width 0.0889)
		(layer "In11.Cu")
		(net "UPI_CPU1_CPU0_P2P2_DN<17>")
	)
	(segment
		(start 101.691694 -289.27806)
		(end 101.691948 -289.277806)
		(width 0.0889)
		(layer "In11.Cu")
		(net "UPI_CPU1_CPU0_P2P2_DN<17>")
	)
	(segment
		(start 100.586032 -294.738552)
		(end 100.586032 -294.560752)
		(width 0.0889)
		(layer "In11.Cu")
		(net "UPI_CPU1_CPU0_P2P2_DN<17>")
	)
	(segment
		(start 102.625906 -285.342076)
		(end 102.641146 -285.333186)
		(width 0.0889)
		(layer "In11.Cu")
		(net "UPI_CPU1_CPU0_P2P2_DN<17>")
	)
	(segment
		(start 77.587602 -365.510064)
		(end 74.747628 -362.67009)
		(width 0.14732)
		(layer "In11.Cu")
		(net "UPI_CPU1_CPU0_P2P2_DN<17>")
	)
	(segment
		(start 100.586032 -293.065454)
		(end 100.586032 -292.887654)
		(width 0.0889)
		(layer "In11.Cu")
		(net "UPI_CPU1_CPU0_P2P2_DN<17>")
	)
	(segment
		(start 342.501728 -281.096466)
		(end 342.490552 -281.10307)
		(width 0.0889)
		(layer "In11.Cu")
		(net "UPI_CPU1_CPU0_P2P2_DN<17>")
	)
	(segment
		(start 340.14156 -284.52318)
		(end 340.142322 -284.523688)
		(width 0.0889)
		(layer "In11.Cu")
		(net "UPI_CPU1_CPU0_P2P2_DN<17>")
	)
	(segment
		(start 308.915562 -320.539364)
		(end 308.732428 -320.631566)
		(width 0.14732)
		(layer "In11.Cu")
		(net "UPI_CPU1_CPU0_P2P2_DN<17>")
	)
	(segment
		(start 101.460046 -290.738814)
		(end 101.460046 -290.598352)
		(width 0.0889)
		(layer "In11.Cu")
		(net "UPI_CPU1_CPU0_P2P2_DN<17>")
	)
	(segment
		(start 236.889544 -369.26774)
		(end 212.31225 -373.599964)
		(width 0.14732)
		(layer "In11.Cu")
		(net "UPI_CPU1_CPU0_P2P2_DN<17>")
	)
	(segment
		(start 341.738966 -282.390342)
		(end 341.738966 -282.405836)
		(width 0.0889)
		(layer "In11.Cu")
		(net "UPI_CPU1_CPU0_P2P2_DN<17>")
	)
	(segment
		(start 339.21065 -288.422334)
		(end 339.20176 -288.427414)
		(width 0.0889)
		(layer "In11.Cu")
		(net "UPI_CPU1_CPU0_P2P2_DN<17>")
	)
	(segment
		(start 340.15045 -285.166816)
		(end 340.14156 -285.171896)
		(width 0.0889)
		(layer "In11.Cu")
		(net "UPI_CPU1_CPU0_P2P2_DN<17>")
	)
	(segment
		(start 100.486972 -294.837612)
		(end 100.586032 -294.738552)
		(width 0.0889)
		(layer "In11.Cu")
		(net "UPI_CPU1_CPU0_P2P2_DN<17>")
	)
	(segment
		(start 99.564952 -298.167806)
		(end 99.705668 -297.8277)
		(width 0.14732)
		(layer "In11.Cu")
		(net "UPI_CPU1_CPU0_P2P2_DN<17>")
	)
	(segment
		(start 248.353072 -361.241086)
		(end 247.684036 -361.710224)
		(width 0.14732)
		(layer "In11.Cu")
		(net "UPI_CPU1_CPU0_P2P2_DN<17>")
	)
	(segment
		(start 340.141814 -286.151066)
		(end 340.150704 -286.156146)
		(width 0.0889)
		(layer "In11.Cu")
		(net "UPI_CPU1_CPU0_P2P2_DN<17>")
	)
	(segment
		(start 100.586032 -291.958014)
		(end 100.586032 -291.780214)
		(width 0.0889)
		(layer "In11.Cu")
		(net "UPI_CPU1_CPU0_P2P2_DN<17>")
	)
	(segment
		(start 337.803998 -291.071046)
		(end 337.543394 -291.33165)
		(width 0.14732)
		(layer "In11.Cu")
		(net "UPI_CPU1_CPU0_P2P2_DN<17>")
	)
	(segment
		(start 314.671456 -317.358522)
		(end 314.59297 -317.548006)
		(width 0.14732)
		(layer "In11.Cu")
		(net "UPI_CPU1_CPU0_P2P2_DN<17>")
	)
	(segment
		(start 338.407756 -290.339526)
		(end 338.407756 -290.672012)
		(width 0.14732)
		(layer "In11.Cu")
		(net "UPI_CPU1_CPU0_P2P2_DN<17>")
	)
	(segment
		(start 339.859366 -287.279334)
		(end 339.859366 -287.28924)
		(width 0.0889)
		(layer "In11.Cu")
		(net "UPI_CPU1_CPU0_P2P2_DN<17>")
	)
	(segment
		(start 101.585522 -290.472876)
		(end 101.725984 -290.472876)
		(width 0.0889)
		(layer "In11.Cu")
		(net "UPI_CPU1_CPU0_P2P2_DN<17>")
	)
	(segment
		(start 337.543394 -291.536374)
		(end 337.283044 -291.796724)
		(width 0.14732)
		(layer "In11.Cu")
		(net "UPI_CPU1_CPU0_P2P2_DN<17>")
	)
	(segment
		(start 70.877938 -353.327462)
		(end 70.877938 -335.190084)
		(width 0.14732)
		(layer "In11.Cu")
		(net "UPI_CPU1_CPU0_P2P2_DN<17>")
	)
	(segment
		(start 103.108506 -281.265376)
		(end 103.110792 -281.264106)
		(width 0.0889)
		(layer "In11.Cu")
		(net "UPI_CPU1_CPU0_P2P2_DN<17>")
	)
	(segment
		(start 331.838046 -300.92523)
		(end 315.654436 -317.10884)
		(width 0.14732)
		(layer "In11.Cu")
		(net "UPI_CPU1_CPU0_P2P2_DN<17>")
	)
	(segment
		(start 100.586032 -294.007032)
		(end 100.486972 -293.907972)
		(width 0.0889)
		(layer "In11.Cu")
		(net "UPI_CPU1_CPU0_P2P2_DN<17>")
	)
	(segment
		(start 100.486972 -292.234874)
		(end 100.486972 -292.057074)
		(width 0.0889)
		(layer "In11.Cu")
		(net "UPI_CPU1_CPU0_P2P2_DN<17>")
	)
	(segment
		(start 102.917498 -286.475424)
		(end 102.917498 -286.467804)
		(width 0.0889)
		(layer "In11.Cu")
		(net "UPI_CPU1_CPU0_P2P2_DN<17>")
	)
	(segment
		(start 338.919566 -288.895028)
		(end 338.919566 -289.077908)
		(width 0.0889)
		(layer "In11.Cu")
		(net "UPI_CPU1_CPU0_P2P2_DN<17>")
	)
	(segment
		(start 101.68636 -288.597848)
		(end 101.69525 -288.592768)
		(width 0.0889)
		(layer "In11.Cu")
		(net "UPI_CPU1_CPU0_P2P2_DN<17>")
	)
	(segment
		(start 73.204832 -324.17639)
		(end 81.170018 -316.21095)
		(width 0.14732)
		(layer "In11.Cu")
		(net "UPI_CPU1_CPU0_P2P2_DN<17>")
	)
	(segment
		(start 308.57825 -321.559682)
		(end 307.813964 -322.590922)
		(width 0.14732)
		(layer "In11.Cu")
		(net "UPI_CPU1_CPU0_P2P2_DN<17>")
	)
	(segment
		(start 248.782078 -361.317032)
		(end 248.353072 -361.241086)
		(width 0.14732)
		(layer "In11.Cu")
		(net "UPI_CPU1_CPU0_P2P2_DN<17>")
	)
	(segment
		(start 101.068378 -291.130482)
		(end 101.068378 -290.99002)
		(width 0.0889)
		(layer "In11.Cu")
		(net "UPI_CPU1_CPU0_P2P2_DN<17>")
	)
	(segment
		(start 249.506486 -360.80954)
		(end 253.10338 -365.946436)
		(width 0.14732)
		(layer "In11.Cu")
		(net "UPI_CPU1_CPU0_P2P2_DN<17>")
	)
	(segment
		(start 100.802186 -291.256212)
		(end 100.942648 -291.256212)
		(width 0.0889)
		(layer "In11.Cu")
		(net "UPI_CPU1_CPU0_P2P2_DN<17>")
	)
	(segment
		(start 99.705668 -297.8277)
		(end 99.895152 -297.749214)
		(width 0.14732)
		(layer "In11.Cu")
		(net "UPI_CPU1_CPU0_P2P2_DN<17>")
	)
	(segment
		(start 98.412808 -374.136666)
		(end 77.587602 -365.510064)
		(width 0.14732)
		(layer "In11.Cu")
		(net "UPI_CPU1_CPU0_P2P2_DN<17>")
	)
	(segment
		(start 338.407756 -290.672012)
		(end 338.008722 -291.071046)
		(width 0.14732)
		(layer "In11.Cu")
		(net "UPI_CPU1_CPU0_P2P2_DN<17>")
	)
	(segment
		(start 101.97719 -290.081208)
		(end 101.97719 -289.610292)
		(width 0.0889)
		(layer "In11.Cu")
		(net "UPI_CPU1_CPU0_P2P2_DN<17>")
	)
	(segment
		(start 99.957636 -297.219624)
		(end 100.508308 -295.890188)
		(width 0.14732)
		(layer "In11.Cu")
		(net "UPI_CPU1_CPU0_P2P2_DN<17>")
	)
	(segment
		(start 250.685046 -367.819178)
		(end 250.480576 -367.78311)
		(width 0.14732)
		(layer "In11.Cu")
		(net "UPI_CPU1_CPU0_P2P2_DN<17>")
	)
	(segment
		(start 249.582432 -360.380534)
		(end 249.506486 -360.80954)
		(width 0.14732)
		(layer "In11.Cu")
		(net "UPI_CPU1_CPU0_P2P2_DN<17>")
	)
	(segment
		(start 103.387398 -280.778204)
		(end 103.387398 -280.769568)
		(width 0.0889)
		(layer "In11.Cu")
		(net "UPI_CPU1_CPU0_P2P2_DN<17>")
	)
	(segment
		(start 247.60809 -362.138976)
		(end 251.204984 -367.275872)
		(width 0.14732)
		(layer "In11.Cu")
		(net "UPI_CPU1_CPU0_P2P2_DN<17>")
	)
	(segment
		(start 334.720946 -293.332662)
		(end 334.663288 -293.39032)
		(width 0.14732)
		(layer "In11.Cu")
		(net "UPI_CPU1_CPU0_P2P2_DN<17>")
	)
	(segment
		(start 298.656756 -328.49058)
		(end 284.309058 -328.49058)
		(width 0.14732)
		(layer "In11.Cu")
		(net "UPI_CPU1_CPU0_P2P2_DN<17>")
	)
	(segment
		(start 284.309058 -328.49058)
		(end 277.768304 -331.199744)
		(width 0.14732)
		(layer "In11.Cu")
		(net "UPI_CPU1_CPU0_P2P2_DN<17>")
	)
	(segment
		(start 102.634796 -286.964882)
		(end 102.646988 -286.95777)
		(width 0.0889)
		(layer "In11.Cu")
		(net "UPI_CPU1_CPU0_P2P2_DN<17>")
	)
	(segment
		(start 99.895152 -297.749214)
		(end 100.036122 -297.408854)
		(width 0.14732)
		(layer "In11.Cu")
		(net "UPI_CPU1_CPU0_P2P2_DN<17>")
	)
	(segment
		(start 81.170018 -316.21095)
		(end 96.720914 -303.44872)
		(width 0.14732)
		(layer "In11.Cu")
		(net "UPI_CPU1_CPU0_P2P2_DN<17>")
	)
	(segment
		(start 250.340114 -359.849928)
		(end 249.582432 -360.380534)
		(width 0.14732)
		(layer "In11.Cu")
		(net "UPI_CPU1_CPU0_P2P2_DN<17>")
	)
	(segment
		(start 301.08525 -326.061832)
		(end 298.656756 -328.49058)
		(width 0.14732)
		(layer "In11.Cu")
		(net "UPI_CPU1_CPU0_P2P2_DN<17>")
	)
	(segment
		(start 72.145906 -326.415146)
		(end 73.204832 -324.17639)
		(width 0.14732)
		(layer "In11.Cu")
		(net "UPI_CPU1_CPU0_P2P2_DN<17>")
	)
	(segment
		(start 306.64658 -323.75856)
		(end 301.08525 -326.061832)
		(width 0.14732)
		(layer "In11.Cu")
		(net "UPI_CPU1_CPU0_P2P2_DN<17>")
	)
	(segment
		(start 99.2505 -299.305218)
		(end 99.172268 -299.115988)
		(width 0.14732)
		(layer "In11.Cu")
		(net "UPI_CPU1_CPU0_P2P2_DN<17>")
	)
	(segment
		(start 247.684036 -361.710224)
		(end 247.60809 -362.138976)
		(width 0.14732)
		(layer "In11.Cu")
		(net "UPI_CPU1_CPU0_P2P2_DN<17>")
	)
	(segment
		(start 101.725984 -290.472876)
		(end 101.851714 -290.347146)
		(width 0.0889)
		(layer "In11.Cu")
		(net "UPI_CPU1_CPU0_P2P2_DN<17>")
	)
	(segment
		(start 103.387144 -284.043628)
		(end 103.387144 -284.033722)
		(width 0.0889)
		(layer "In11.Cu")
		(net "UPI_CPU1_CPU0_P2P2_DN<17>")
	)
	(segment
		(start 100.036122 -297.408854)
		(end 99.957636 -297.219624)
		(width 0.14732)
		(layer "In11.Cu")
		(net "UPI_CPU1_CPU0_P2P2_DN<17>")
	)
	(segment
		(start 340.15045 -283.539184)
		(end 340.14156 -283.544264)
		(width 0.0889)
		(layer "In11.Cu")
		(net "UPI_CPU1_CPU0_P2P2_DN<17>")
	)
	(segment
		(start 100.486972 -292.610794)
		(end 100.586032 -292.511734)
		(width 0.0889)
		(layer "In11.Cu")
		(net "UPI_CPU1_CPU0_P2P2_DN<17>")
	)
	(segment
		(start 252.583442 -366.489742)
		(end 252.378972 -366.453674)
		(width 0.14732)
		(layer "In11.Cu")
		(net "UPI_CPU1_CPU0_P2P2_DN<17>")
	)
	(segment
		(start 340.626446 -282.721558)
		(end 340.611714 -282.730194)
		(width 0.0889)
		(layer "In11.Cu")
		(net "UPI_CPU1_CPU0_P2P2_DN<17>")
	)
	(segment
		(start 336.817716 -292.262052)
		(end 336.472784 -292.606984)
		(width 0.14732)
		(layer "In11.Cu")
		(net "UPI_CPU1_CPU0_P2P2_DN<17>")
	)
	(segment
		(start 100.586032 -293.441374)
		(end 100.486972 -293.342314)
		(width 0.0889)
		(layer "In11.Cu")
		(net "UPI_CPU1_CPU0_P2P2_DN<17>")
	)
	(segment
		(start 126.281688 -378.27077)
		(end 98.412808 -374.136666)
		(width 0.14732)
		(layer "In11.Cu")
		(net "UPI_CPU1_CPU0_P2P2_DN<17>")
	)
	(segment
		(start 315.01207 -317.217806)
		(end 314.671456 -317.358522)
		(width 0.14732)
		(layer "In11.Cu")
		(net "UPI_CPU1_CPU0_P2P2_DN<17>")
	)
	(segment
		(start 100.486972 -295.248584)
		(end 100.486972 -294.837612)
		(width 0.0889)
		(layer "In11.Cu")
		(net "UPI_CPU1_CPU0_P2P2_DN<17>")
	)
	(segment
		(start 103.948992 -280.453846)
		(end 103.957882 -280.458926)
		(width 0.0889)
		(layer "In11.Cu")
		(net "UPI_CPU1_CPU0_P2P2_DN<17>")
	)
	(segment
		(start 101.334316 -290.864544)
		(end 101.460046 -290.738814)
		(width 0.0889)
		(layer "In11.Cu")
		(net "UPI_CPU1_CPU0_P2P2_DN<17>")
	)
	(segment
		(start 335.328514 -293.080948)
		(end 334.720946 -293.332662)
		(width 0.14732)
		(layer "In11.Cu")
		(net "UPI_CPU1_CPU0_P2P2_DN<17>")
	)
	(segment
		(start 251.204984 -367.275872)
		(end 251.168916 -367.480342)
		(width 0.14732)
		(layer "In11.Cu")
		(net "UPI_CPU1_CPU0_P2P2_DN<17>")
	)
	(segment
		(start 103.104696 -281.267662)
		(end 103.10749 -281.265884)
		(width 0.0889)
		(layer "In11.Cu")
		(net "UPI_CPU1_CPU0_P2P2_DN<17>")
	)
	(segment
		(start 333.676752 -294.867076)
		(end 331.838046 -300.92523)
		(width 0.14732)
		(layer "In11.Cu")
		(net "UPI_CPU1_CPU0_P2P2_DN<17>")
	)
	(segment
		(start 308.732428 -320.631566)
		(end 308.616858 -320.981324)
		(width 0.14732)
		(layer "In11.Cu")
		(net "UPI_CPU1_CPU0_P2P2_DN<17>")
	)
	(segment
		(start 99.10953 -299.645578)
		(end 99.2505 -299.305218)
		(width 0.14732)
		(layer "In11.Cu")
		(net "UPI_CPU1_CPU0_P2P2_DN<17>")
	)
	(segment
		(start 99.502468 -298.697396)
		(end 99.643438 -298.357036)
		(width 0.14732)
		(layer "In11.Cu")
		(net "UPI_CPU1_CPU0_P2P2_DN<17>")
	)
	(segment
		(start 307.813964 -322.590922)
		(end 306.64658 -323.75856)
		(width 0.14732)
		(layer "In11.Cu")
		(net "UPI_CPU1_CPU0_P2P2_DN<17>")
	)
	(segment
		(start 340.329012 -283.205682)
		(end 340.329012 -283.219906)
		(width 0.0889)
		(layer "In11.Cu")
		(net "UPI_CPU1_CPU0_P2P2_DN<17>")
	)
	(segment
		(start 251.168916 -367.480342)
		(end 250.685046 -367.819178)
		(width 0.14732)
		(layer "In11.Cu")
		(net "UPI_CPU1_CPU0_P2P2_DN<17>")
	)
	(segment
		(start 100.586032 -292.887654)
		(end 100.486972 -292.788594)
		(width 0.0889)
		(layer "In11.Cu")
		(net "UPI_CPU1_CPU0_P2P2_DN<17>")
	)
	(segment
		(start 100.529136 -295.312846)
		(end 100.529136 -295.290748)
		(width 0.0889)
		(layer "In11.Cu")
		(net "UPI_CPU1_CPU0_P2P2_DN<17>")
	)
	(segment
		(start 340.150704 -286.794702)
		(end 340.141814 -286.799782)
		(width 0.0889)
		(layer "In11.Cu")
		(net "UPI_CPU1_CPU0_P2P2_DN<17>")
	)
	(segment
		(start 100.586032 -292.333934)
		(end 100.486972 -292.234874)
		(width 0.0889)
		(layer "In11.Cu")
		(net "UPI_CPU1_CPU0_P2P2_DN<17>")
	)
	(segment
		(start 312.388758 -318.459612)
		(end 310.044338 -319.11163)
		(width 0.14732)
		(layer "In11.Cu")
		(net "UPI_CPU1_CPU0_P2P2_DN<17>")
	)
	(segment
		(start 100.486972 -292.788594)
		(end 100.486972 -292.610794)
		(width 0.0889)
		(layer "In11.Cu")
		(net "UPI_CPU1_CPU0_P2P2_DN<17>")
	)
	(segment
		(start 100.586032 -291.780214)
		(end 100.486972 -291.681154)
		(width 0.0889)
		(layer "In11.Cu")
		(net "UPI_CPU1_CPU0_P2P2_DN<17>")
	)
	(segment
		(start 250.480576 -367.78311)
		(end 246.883682 -362.646468)
		(width 0.14732)
		(layer "In11.Cu")
		(net "UPI_CPU1_CPU0_P2P2_DN<17>")
	)
	(segment
		(start 100.942648 -291.256212)
		(end 101.068378 -291.130482)
		(width 0.0889)
		(layer "In11.Cu")
		(net "UPI_CPU1_CPU0_P2P2_DN<17>")
	)
	(segment
		(start 99.643438 -298.357036)
		(end 99.564952 -298.167806)
		(width 0.14732)
		(layer "In11.Cu")
		(net "UPI_CPU1_CPU0_P2P2_DN<17>")
	)
	(segment
		(start 335.406746 -292.891718)
		(end 335.328514 -293.080948)
		(width 0.14732)
		(layer "In11.Cu")
		(net "UPI_CPU1_CPU0_P2P2_DN<17>")
	)
	(segment
		(start 342.490552 -281.10307)
		(end 342.485218 -281.106118)
		(width 0.0889)
		(layer "In11.Cu")
		(net "UPI_CPU1_CPU0_P2P2_DN<17>")
	)
	(segment
		(start 100.486972 -293.342314)
		(end 100.486972 -293.164514)
		(width 0.0889)
		(layer "In11.Cu")
		(net "UPI_CPU1_CPU0_P2P2_DN<17>")
	)
	(segment
		(start 103.565706 -283.714444)
		(end 103.574596 -283.709364)
		(width 0.0889)
		(layer "In11.Cu")
		(net "UPI_CPU1_CPU0_P2P2_DN<17>")
	)
	(segment
		(start 343.556336 -280.778204)
		(end 343.61374 -280.835608)
		(width 0.0889)
		(layer "In11.Cu")
		(net "UPI_CPU1_CPU0_P2P2_DN<17>")
	)
	(segment
		(start 102.15626 -287.783778)
		(end 102.16515 -287.778698)
		(width 0.0889)
		(layer "In11.Cu")
		(net "UPI_CPU1_CPU0_P2P2_DN<17>")
	)
	(segment
		(start 102.625906 -286.969962)
		(end 102.634796 -286.964882)
		(width 0.0889)
		(layer "In11.Cu")
		(net "UPI_CPU1_CPU0_P2P2_DN<17>")
	)
	(segment
		(start 253.067312 -366.150906)
		(end 252.583442 -366.489742)
		(width 0.14732)
		(layer "In11.Cu")
		(net "UPI_CPU1_CPU0_P2P2_DN<17>")
	)
	(segment
		(start 101.068378 -290.99002)
		(end 101.193854 -290.864544)
		(width 0.0889)
		(layer "In11.Cu")
		(net "UPI_CPU1_CPU0_P2P2_DN<17>")
	)
	(segment
		(start 343.243662 -280.778204)
		(end 343.556336 -280.778204)
		(width 0.0889)
		(layer "In11.Cu")
		(net "UPI_CPU1_CPU0_P2P2_DN<17>")
	)
	(segment
		(start 342.03005 -281.911298)
		(end 342.02116 -281.916378)
		(width 0.0889)
		(layer "In11.Cu")
		(net "UPI_CPU1_CPU0_P2P2_DN<17>")
	)
	(arc
		(start 339.20176 -288.427414)
		(mid 339.000478 -288.624901)
		(end 338.919566 -288.895028)
		(width 0.0889)
		(layer "In11.Cu")
		(net "UPI_CPU1_CPU0_P2P2_DN<17>")
	)
	(arc
		(start 340.329266 -286.482028)
		(mid 340.280013 -286.661228)
		(end 340.150704 -286.794702)
		(width 0.0889)
		(layer "In11.Cu")
		(net "UPI_CPU1_CPU0_P2P2_DN<17>")
	)
	(arc
		(start 341.177118 -282.730194)
		(mid 340.902889 -282.654269)
		(end 340.626446 -282.721558)
		(width 0.0889)
		(layer "In11.Cu")
		(net "UPI_CPU1_CPU0_P2P2_DN<17>")
	)
	(arc
		(start 343.61374 -280.835608)
		(mid 343.405418 -281.115762)
		(end 343.056464 -281.102562)
		(width 0.0889)
		(layer "In11.Cu")
		(net "UPI_CPU1_CPU0_P2P2_DN<17>")
	)
	(arc
		(start 338.483448 -289.531298)
		(mid 338.474095 -289.550061)
		(end 338.465414 -289.569144)
		(width 0.0889)
		(layer "In11.Cu")
		(net "UPI_CPU1_CPU0_P2P2_DN<17>")
	)
	(arc
		(start 101.69525 -288.592768)
		(mid 101.897536 -288.393787)
		(end 101.977698 -288.121598)
		(width 0.0889)
		(layer "In11.Cu")
		(net "UPI_CPU1_CPU0_P2P2_DN<17>")
	)
	(arc
		(start 102.640892 -285.33344)
		(mid 102.843479 -285.127089)
		(end 102.917498 -284.847538)
		(width 0.0889)
		(layer "In11.Cu")
		(net "UPI_CPU1_CPU0_P2P2_DN<17>")
	)
	(arc
		(start 340.329266 -286.466026)
		(mid 340.329354 -286.474027)
		(end 340.329266 -286.482028)
		(width 0.0889)
		(layer "In11.Cu")
		(net "UPI_CPU1_CPU0_P2P2_DN<17>")
	)
	(arc
		(start 102.16515 -287.778698)
		(mid 102.367973 -287.578467)
		(end 102.447344 -287.304734)
		(width 0.0889)
		(layer "In11.Cu")
		(net "UPI_CPU1_CPU0_P2P2_DN<17>")
	)
	(arc
		(start 103.857044 -283.201364)
		(mid 103.776882 -282.929175)
		(end 103.574596 -282.730194)
		(width 0.0889)
		(layer "In11.Cu")
		(net "UPI_CPU1_CPU0_P2P2_DN<17>")
	)
	(arc
		(start 103.574596 -282.730194)
		(mid 103.439663 -282.59684)
		(end 103.387398 -282.414472)
		(width 0.0889)
		(layer "In11.Cu")
		(net "UPI_CPU1_CPU0_P2P2_DN<17>")
	)
	(arc
		(start 340.329012 -283.219906)
		(mid 340.281333 -283.402806)
		(end 340.15045 -283.539184)
		(width 0.0889)
		(layer "In11.Cu")
		(net "UPI_CPU1_CPU0_P2P2_DN<17>")
	)
	(arc
		(start 340.150704 -286.156146)
		(mid 340.279298 -286.28842)
		(end 340.329266 -286.466026)
		(width 0.0889)
		(layer "In11.Cu")
		(net "UPI_CPU1_CPU0_P2P2_DN<17>")
	)
	(arc
		(start 340.15045 -284.52826)
		(mid 340.329047 -284.847538)
		(end 340.15045 -285.166816)
		(width 0.0889)
		(layer "In11.Cu")
		(net "UPI_CPU1_CPU0_P2P2_DN<17>")
	)
	(arc
		(start 103.110792 -281.264106)
		(mid 103.313379 -281.057755)
		(end 103.387398 -280.778204)
		(width 0.0889)
		(layer "In11.Cu")
		(net "UPI_CPU1_CPU0_P2P2_DN<17>")
	)
	(arc
		(start 103.387398 -282.405836)
		(mid 103.313407 -282.12627)
		(end 103.110792 -281.919934)
		(width 0.0889)
		(layer "In11.Cu")
		(net "UPI_CPU1_CPU0_P2P2_DN<17>")
	)
	(arc
		(start 338.735162 -289.277806)
		(mid 338.589921 -289.385312)
		(end 338.483448 -289.531298)
		(width 0.0889)
		(layer "In11.Cu")
		(net "UPI_CPU1_CPU0_P2P2_DN<17>")
	)
	(arc
		(start 340.14156 -283.544264)
		(mid 339.859028 -284.033722)
		(end 340.14156 -284.52318)
		(width 0.0889)
		(layer "In11.Cu")
		(net "UPI_CPU1_CPU0_P2P2_DN<17>")
	)
	(arc
		(start 102.447344 -287.28924)
		(mid 102.495023 -287.10634)
		(end 102.625906 -286.969962)
		(width 0.0889)
		(layer "In11.Cu")
		(net "UPI_CPU1_CPU0_P2P2_DN<17>")
	)
	(arc
		(start 102.917498 -286.467804)
		(mid 102.839869 -286.189391)
		(end 102.634796 -285.985712)
		(width 0.0889)
		(layer "In11.Cu")
		(net "UPI_CPU1_CPU0_P2P2_DN<17>")
	)
	(arc
		(start 103.104696 -281.916378)
		(mid 102.969763 -281.783024)
		(end 102.917498 -281.600656)
		(width 0.0889)
		(layer "In11.Cu")
		(net "UPI_CPU1_CPU0_P2P2_DN<17>")
	)
	(arc
		(start 104.136444 -280.778204)
		(mid 104.099584 -280.940001)
		(end 103.99649 -281.07005)
		(width 0.0889)
		(layer "In11.Cu")
		(net "UPI_CPU1_CPU0_P2P2_DN<17>")
	)
	(arc
		(start 339.659722 -287.62071)
		(mid 339.461494 -287.826558)
		(end 339.389212 -288.103056)
		(width 0.0889)
		(layer "In11.Cu")
		(net "UPI_CPU1_CPU0_P2P2_DN<17>")
	)
	(arc
		(start 103.574596 -283.709364)
		(mid 103.778931 -283.506759)
		(end 103.857044 -283.229812)
		(width 0.0889)
		(layer "In11.Cu")
		(net "UPI_CPU1_CPU0_P2P2_DN<17>")
	)
	(arc
		(start 103.387144 -284.033722)
		(mid 103.434823 -283.850822)
		(end 103.565706 -283.714444)
		(width 0.0889)
		(layer "In11.Cu")
		(net "UPI_CPU1_CPU0_P2P2_DN<17>")
	)
	(arc
		(start 339.389212 -288.103056)
		(mid 339.341533 -288.285956)
		(end 339.21065 -288.422334)
		(width 0.0889)
		(layer "In11.Cu")
		(net "UPI_CPU1_CPU0_P2P2_DN<17>")
	)
	(arc
		(start 102.917498 -281.583384)
		(mid 102.969768 -281.401019)
		(end 103.104696 -281.267662)
		(width 0.0889)
		(layer "In11.Cu")
		(net "UPI_CPU1_CPU0_P2P2_DN<17>")
	)
	(arc
		(start 342.208612 -281.59202)
		(mid 342.160933 -281.77492)
		(end 342.03005 -281.911298)
		(width 0.0889)
		(layer "In11.Cu")
		(net "UPI_CPU1_CPU0_P2P2_DN<17>")
	)
	(arc
		(start 340.141814 -286.799782)
		(mid 339.937479 -287.002387)
		(end 339.859366 -287.279334)
		(width 0.0889)
		(layer "In11.Cu")
		(net "UPI_CPU1_CPU0_P2P2_DN<17>")
	)
	(arc
		(start 101.691948 -289.277806)
		(mid 101.582801 -289.193878)
		(end 101.507798 -289.078416)
		(width 0.0889)
		(layer "In11.Cu")
		(net "UPI_CPU1_CPU0_P2P2_DN<17>")
	)
	(arc
		(start 103.574596 -280.453846)
		(mid 103.761794 -280.403703)
		(end 103.948992 -280.453846)
		(width 0.0889)
		(layer "In11.Cu")
		(net "UPI_CPU1_CPU0_P2P2_DN<17>")
	)
	(arc
		(start 339.859366 -287.28924)
		(mid 339.811687 -287.47214)
		(end 339.680804 -287.608518)
		(width 0.0889)
		(layer "In11.Cu")
		(net "UPI_CPU1_CPU0_P2P2_DN<17>")
	)
	(arc
		(start 102.625906 -285.980632)
		(mid 102.447309 -285.661354)
		(end 102.625906 -285.342076)
		(width 0.0889)
		(layer "In11.Cu")
		(net "UPI_CPU1_CPU0_P2P2_DN<17>")
	)
	(arc
		(start 103.387398 -280.769568)
		(mid 103.439668 -280.587203)
		(end 103.574596 -280.453846)
		(width 0.0889)
		(layer "In11.Cu")
		(net "UPI_CPU1_CPU0_P2P2_DN<17>")
	)
	(arc
		(start 340.611714 -282.730194)
		(mid 340.408233 -282.930998)
		(end 340.329012 -283.205682)
		(width 0.0889)
		(layer "In11.Cu")
		(net "UPI_CPU1_CPU0_P2P2_DN<17>")
	)
	(arc
		(start 101.97719 -289.610292)
		(mid 101.86596 -289.417088)
		(end 101.691694 -289.27806)
		(width 0.0889)
		(layer "In11.Cu")
		(net "UPI_CPU1_CPU0_P2P2_DN<17>")
	)
	(arc
		(start 103.957882 -280.458926)
		(mid 104.085136 -280.588892)
		(end 104.13619 -280.763472)
		(width 0.0889)
		(layer "In11.Cu")
		(net "UPI_CPU1_CPU0_P2P2_DN<17>")
	)
	(arc
		(start 102.917498 -284.838902)
		(mid 102.969768 -284.656537)
		(end 103.104696 -284.52318)
		(width 0.0889)
		(layer "In11.Cu")
		(net "UPI_CPU1_CPU0_P2P2_DN<17>")
	)
	(arc
		(start 103.104696 -284.52318)
		(mid 103.309031 -284.320575)
		(end 103.387144 -284.043628)
		(width 0.0889)
		(layer "In11.Cu")
		(net "UPI_CPU1_CPU0_P2P2_DN<17>")
	)
	(arc
		(start 101.977698 -288.103056)
		(mid 102.025377 -287.920156)
		(end 102.15626 -287.783778)
		(width 0.0889)
		(layer "In11.Cu")
		(net "UPI_CPU1_CPU0_P2P2_DN<17>")
	)
	(arc
		(start 343.056464 -281.102562)
		(mid 342.779905 -281.026819)
		(end 342.501728 -281.096466)
		(width 0.0889)
		(layer "In11.Cu")
		(net "UPI_CPU1_CPU0_P2P2_DN<17>")
	)
	(arc
		(start 102.646988 -286.95777)
		(mid 102.845216 -286.751922)
		(end 102.917498 -286.475424)
		(width 0.0889)
		(layer "In11.Cu")
		(net "UPI_CPU1_CPU0_P2P2_DN<17>")
	)
	(arc
		(start 341.738966 -282.405836)
		(mid 341.551667 -282.730277)
		(end 341.177118 -282.730194)
		(width 0.0889)
		(layer "In11.Cu")
		(net "UPI_CPU1_CPU0_P2P2_DN<17>")
	)
	(arc
		(start 338.919566 -289.077908)
		(mid 338.844495 -289.19365)
		(end 338.735162 -289.277806)
		(width 0.0889)
		(layer "In11.Cu")
		(net "UPI_CPU1_CPU0_P2P2_DN<17>")
	)
	(arc
		(start 101.507798 -288.917126)
		(mid 101.555477 -288.734226)
		(end 101.68636 -288.597848)
		(width 0.0889)
		(layer "In11.Cu")
		(net "UPI_CPU1_CPU0_P2P2_DN<17>")
	)
	(arc
		(start 342.485218 -281.106118)
		(mid 342.282631 -281.312469)
		(end 342.208612 -281.59202)
		(width 0.0889)
		(layer "In11.Cu")
		(net "UPI_CPU1_CPU0_P2P2_DN<17>")
	)
	(arc
		(start 342.02116 -281.916378)
		(mid 341.818337 -282.116609)
		(end 341.738966 -282.390342)
		(width 0.0889)
		(layer "In11.Cu")
		(net "UPI_CPU1_CPU0_P2P2_DN<17>")
	)
	(arc
		(start 340.14156 -285.171896)
		(mid 339.859028 -285.661527)
		(end 340.141814 -286.151066)
		(width 0.0889)
		(layer "In11.Cu")
		(net "UPI_CPU1_CPU0_P2P2_DN<17>")
	)
	(arc
		(start 104.13619 -280.763472)
		(mid 104.136387 -280.770837)
		(end 104.136444 -280.778204)
		(width 0.0889)
		(layer "In11.Cu")
		(net "UPI_CPU1_CPU0_P2P2_DN<17>")
	)
	(segment
		(start 102.352094 -281.591766)
		(end 102.352348 -281.59202)
		(width 0.13208)
		(layer "F.Cu")
		(net "UPI_CPU1_CPU0_P2P2_DN<16>")
	)
	(segment
		(start 102.352094 -281.05608)
		(end 102.352094 -281.591766)
		(width 0.13208)
		(layer "F.Cu")
		(net "UPI_CPU1_CPU0_P2P2_DN<16>")
	)
	(segment
		(start 343.243916 -281.869896)
		(end 343.243916 -282.405582)
		(width 0.13208)
		(layer "F.Cu")
		(net "UPI_CPU1_CPU0_P2P2_DN<16>")
	)
	(segment
		(start 343.243916 -282.405582)
		(end 343.243662 -282.405836)
		(width 0.13208)
		(layer "F.Cu")
		(net "UPI_CPU1_CPU0_P2P2_DN<16>")
	)
	(segment
		(start 340.394036 -290.199826)
		(end 340.394036 -290.340288)
		(width 0.0889)
		(layer "In11.Cu")
		(net "UPI_CPU1_CPU0_P2P2_DN<16>")
	)
	(segment
		(start 340.394036 -290.340288)
		(end 340.268306 -290.466018)
		(width 0.0889)
		(layer "In11.Cu")
		(net "UPI_CPU1_CPU0_P2P2_DN<16>")
	)
	(segment
		(start 339.15604 -291.49675)
		(end 339.15604 -291.497512)
		(width 0.14732)
		(layer "In11.Cu")
		(net "UPI_CPU1_CPU0_P2P2_DN<16>")
	)
	(segment
		(start 200.152254 -372.58244)
		(end 161.592768 -379.379988)
		(width 0.14732)
		(layer "In11.Cu")
		(net "UPI_CPU1_CPU0_P2P2_DN<16>")
	)
	(segment
		(start 342.116664 -283.709364)
		(end 342.107774 -283.714444)
		(width 0.0889)
		(layer "In11.Cu")
		(net "UPI_CPU1_CPU0_P2P2_DN<16>")
	)
	(segment
		(start 101.599746 -285.171896)
		(end 101.604318 -285.169102)
		(width 0.0889)
		(layer "In11.Cu")
		(net "UPI_CPU1_CPU0_P2P2_DN<16>")
	)
	(segment
		(start 309.796688 -321.799458)
		(end 309.052722 -322.979542)
		(width 0.14732)
		(layer "In11.Cu")
		(net "UPI_CPU1_CPU0_P2P2_DN<16>")
	)
	(segment
		(start 341.647018 -284.52318)
		(end 341.638128 -284.52826)
		(width 0.0889)
		(layer "In11.Cu")
		(net "UPI_CPU1_CPU0_P2P2_DN<16>")
	)
	(segment
		(start 245.272306 -370.846858)
		(end 244.449346 -370.701062)
		(width 0.14732)
		(layer "In11.Cu")
		(net "UPI_CPU1_CPU0_P2P2_DN<16>")
	)
	(segment
		(start 101.594158 -285.174944)
		(end 101.59492 -285.174436)
		(width 0.0889)
		(layer "In11.Cu")
		(net "UPI_CPU1_CPU0_P2P2_DN<16>")
	)
	(segment
		(start 101.317044 -282.42006)
		(end 101.317044 -282.405836)
		(width 0.0889)
		(layer "In11.Cu")
		(net "UPI_CPU1_CPU0_P2P2_DN<16>")
	)
	(segment
		(start 241.46002 -367.54689)
		(end 241.064288 -369.791488)
		(width 0.14732)
		(layer "In11.Cu")
		(net "UPI_CPU1_CPU0_P2P2_DN<16>")
	)
	(segment
		(start 69.773038 -335.000092)
		(end 70.407276 -328.556874)
		(width 0.14732)
		(layer "In11.Cu")
		(net "UPI_CPU1_CPU0_P2P2_DN<16>")
	)
	(segment
		(start 246.500142 -370.750592)
		(end 246.896128 -368.50574)
		(width 0.14732)
		(layer "In11.Cu")
		(net "UPI_CPU1_CPU0_P2P2_DN<16>")
	)
	(segment
		(start 241.935254 -369.945412)
		(end 242.33124 -367.70056)
		(width 0.14732)
		(layer "In11.Cu")
		(net "UPI_CPU1_CPU0_P2P2_DN<16>")
	)
	(segment
		(start 305.056286 -328.212196)
		(end 303.65573 -329.61199)
		(width 0.14732)
		(layer "In11.Cu")
		(net "UPI_CPU1_CPU0_P2P2_DN<16>")
	)
	(segment
		(start 341.177626 -286.964374)
		(end 341.176864 -286.964882)
		(width 0.0889)
		(layer "In11.Cu")
		(net "UPI_CPU1_CPU0_P2P2_DN<16>")
	)
	(segment
		(start 242.989862 -370.444268)
		(end 242.185444 -370.301774)
		(width 0.14732)
		(layer "In11.Cu")
		(net "UPI_CPU1_CPU0_P2P2_DN<16>")
	)
	(segment
		(start 305.49596 -327.664064)
		(end 305.056286 -328.212196)
		(width 0.14732)
		(layer "In11.Cu")
		(net "UPI_CPU1_CPU0_P2P2_DN<16>")
	)
	(segment
		(start 315.263276 -319.033398)
		(end 310.967374 -320.812922)
		(width 0.14732)
		(layer "In11.Cu")
		(net "UPI_CPU1_CPU0_P2P2_DN<16>")
	)
	(segment
		(start 101.59365 -281.919934)
		(end 101.614986 -281.907742)
		(width 0.0889)
		(layer "In11.Cu")
		(net "UPI_CPU1_CPU0_P2P2_DN<16>")
	)
	(segment
		(start 242.212114 -367.53038)
		(end 241.6302 -367.427764)
		(width 0.14732)
		(layer "In11.Cu")
		(net "UPI_CPU1_CPU0_P2P2_DN<16>")
	)
	(segment
		(start 97.183956 -300.966124)
		(end 99.379786 -295.665398)
		(width 0.14732)
		(layer "In11.Cu")
		(net "UPI_CPU1_CPU0_P2P2_DN<16>")
	)
	(segment
		(start 306.40528 -325.345298)
		(end 305.736752 -326.300338)
		(width 0.14732)
		(layer "In11.Cu")
		(net "UPI_CPU1_CPU0_P2P2_DN<16>")
	)
	(segment
		(start 339.48497 -291.249354)
		(end 339.344508 -291.249354)
		(width 0.0889)
		(layer "In11.Cu")
		(net "UPI_CPU1_CPU0_P2P2_DN<16>")
	)
	(segment
		(start 342.399112 -283.219906)
		(end 342.399112 -283.229812)
		(width 0.0889)
		(layer "In11.Cu")
		(net "UPI_CPU1_CPU0_P2P2_DN<16>")
	)
	(segment
		(start 309.052722 -322.979542)
		(end 307.58892 -324.516496)
		(width 0.14732)
		(layer "In11.Cu")
		(net "UPI_CPU1_CPU0_P2P2_DN<16>")
	)
	(segment
		(start 265.189462 -363.730286)
		(end 264.376662 -364.54334)
		(width 0.14732)
		(layer "In11.Cu")
		(net "UPI_CPU1_CPU0_P2P2_DN<16>")
	)
	(segment
		(start 99.907598 -288.103056)
		(end 99.907598 -288.087562)
		(width 0.0889)
		(layer "In11.Cu")
		(net "UPI_CPU1_CPU0_P2P2_DN<16>")
	)
	(segment
		(start 102.195884 -281.863038)
		(end 102.352348 -281.59202)
		(width 0.0889)
		(layer "In11.Cu")
		(net "UPI_CPU1_CPU0_P2P2_DN<16>")
	)
	(segment
		(start 99.907598 -289.977068)
		(end 99.907598 -289.64509)
		(width 0.0889)
		(layer "In11.Cu")
		(net "UPI_CPU1_CPU0_P2P2_DN<16>")
	)
	(segment
		(start 101.597714 -285.172912)
		(end 101.599746 -285.171896)
		(width 0.0889)
		(layer "In11.Cu")
		(net "UPI_CPU1_CPU0_P2P2_DN<16>")
	)
	(segment
		(start 101.786944 -286.463486)
		(end 101.787198 -286.463994)
		(width 0.0889)
		(layer "In11.Cu")
		(net "UPI_CPU1_CPU0_P2P2_DN<16>")
	)
	(segment
		(start 244.449346 -370.701062)
		(end 244.214396 -370.366544)
		(width 0.14732)
		(layer "In11.Cu")
		(net "UPI_CPU1_CPU0_P2P2_DN<16>")
	)
	(segment
		(start 102.10673 -281.886914)
		(end 102.195884 -281.863038)
		(width 0.0889)
		(layer "In11.Cu")
		(net "UPI_CPU1_CPU0_P2P2_DN<16>")
	)
	(segment
		(start 241.064288 -369.791488)
		(end 240.707672 -370.041678)
		(width 0.14732)
		(layer "In11.Cu")
		(net "UPI_CPU1_CPU0_P2P2_DN<16>")
	)
	(segment
		(start 102.528878 -283.550106)
		(end 102.539546 -283.544264)
		(width 0.0889)
		(layer "In11.Cu")
		(net "UPI_CPU1_CPU0_P2P2_DN<16>")
	)
	(segment
		(start 101.589078 -285.177992)
		(end 101.594158 -285.174944)
		(width 0.0889)
		(layer "In11.Cu")
		(net "UPI_CPU1_CPU0_P2P2_DN<16>")
	)
	(segment
		(start 341.929212 -284.033722)
		(end 341.929212 -284.049216)
		(width 0.0889)
		(layer "In11.Cu")
		(net "UPI_CPU1_CPU0_P2P2_DN<16>")
	)
	(segment
		(start 71.116698 -325.99376)
		(end 72.275192 -323.54393)
		(width 0.14732)
		(layer "In11.Cu")
		(net "UPI_CPU1_CPU0_P2P2_DN<16>")
	)
	(segment
		(start 100.189792 -287.613598)
		(end 100.198682 -287.608518)
		(width 0.0889)
		(layer "In11.Cu")
		(net "UPI_CPU1_CPU0_P2P2_DN<16>")
	)
	(segment
		(start 248.303796 -371.380766)
		(end 246.750332 -371.107208)
		(width 0.14732)
		(layer "In11.Cu")
		(net "UPI_CPU1_CPU0_P2P2_DN<16>")
	)
	(segment
		(start 338.636864 -292.016688)
		(end 337.040982 -293.612062)
		(width 0.14732)
		(layer "In11.Cu")
		(net "UPI_CPU1_CPU0_P2P2_DN<16>")
	)
	(segment
		(start 102.059232 -284.363922)
		(end 102.070154 -284.357826)
		(width 0.0889)
		(layer "In11.Cu")
		(net "UPI_CPU1_CPU0_P2P2_DN<16>")
	)
	(segment
		(start 99.720146 -288.427414)
		(end 99.729036 -288.422334)
		(width 0.0889)
		(layer "In11.Cu")
		(net "UPI_CPU1_CPU0_P2P2_DN<16>")
	)
	(segment
		(start 80.44053 -315.378592)
		(end 95.911924 -302.681386)
		(width 0.14732)
		(layer "In11.Cu")
		(net "UPI_CPU1_CPU0_P2P2_DN<16>")
	)
	(segment
		(start 100.377244 -287.28924)
		(end 100.377244 -287.279334)
		(width 0.0889)
		(layer "In11.Cu")
		(net "UPI_CPU1_CPU0_P2P2_DN<16>")
	)
	(segment
		(start 339.171534 -291.422328)
		(end 339.171534 -291.481256)
		(width 0.0889)
		(layer "In11.Cu")
		(net "UPI_CPU1_CPU0_P2P2_DN<16>")
	)
	(segment
		(start 339.876638 -290.857686)
		(end 339.736176 -290.857686)
		(width 0.0889)
		(layer "In11.Cu")
		(net "UPI_CPU1_CPU0_P2P2_DN<16>")
	)
	(segment
		(start 335.555082 -294.227758)
		(end 334.598518 -295.659302)
		(width 0.14732)
		(layer "In11.Cu")
		(net "UPI_CPU1_CPU0_P2P2_DN<16>")
	)
	(segment
		(start 99.421696 -290.46297)
		(end 99.907598 -289.977068)
		(width 0.0889)
		(layer "In11.Cu")
		(net "UPI_CPU1_CPU0_P2P2_DN<16>")
	)
	(segment
		(start 101.59492 -285.174436)
		(end 101.597714 -285.172912)
		(width 0.0889)
		(layer "In11.Cu")
		(net "UPI_CPU1_CPU0_P2P2_DN<16>")
	)
	(segment
		(start 339.6107 -291.123624)
		(end 339.48497 -291.249354)
		(width 0.0889)
		(layer "In11.Cu")
		(net "UPI_CPU1_CPU0_P2P2_DN<16>")
	)
	(segment
		(start 73.80351 -363.286802)
		(end 69.773038 -353.557332)
		(width 0.14732)
		(layer "In11.Cu")
		(net "UPI_CPU1_CPU0_P2P2_DN<16>")
	)
	(segment
		(start 305.736752 -326.300338)
		(end 305.49596 -327.664064)
		(width 0.14732)
		(layer "In11.Cu")
		(net "UPI_CPU1_CPU0_P2P2_DN<16>")
	)
	(segment
		(start 303.65573 -329.61199)
		(end 284.500574 -329.61199)
		(width 0.14732)
		(layer "In11.Cu")
		(net "UPI_CPU1_CPU0_P2P2_DN<16>")
	)
	(segment
		(start 99.379786 -295.665398)
		(end 99.379786 -293.202106)
		(width 0.14732)
		(layer "In11.Cu")
		(net "UPI_CPU1_CPU0_P2P2_DN<16>")
	)
	(segment
		(start 243.742464 -367.94948)
		(end 243.346732 -370.194078)
		(width 0.14732)
		(layer "In11.Cu")
		(net "UPI_CPU1_CPU0_P2P2_DN<16>")
	)
	(segment
		(start 341.167974 -285.980632)
		(end 341.176864 -285.985712)
		(width 0.0889)
		(layer "In11.Cu")
		(net "UPI_CPU1_CPU0_P2P2_DN<16>")
	)
	(segment
		(start 340.002368 -290.731956)
		(end 339.876638 -290.857686)
		(width 0.0889)
		(layer "In11.Cu")
		(net "UPI_CPU1_CPU0_P2P2_DN<16>")
	)
	(segment
		(start 340.989666 -287.280604)
		(end 340.989666 -287.299146)
		(width 0.0889)
		(layer "In11.Cu")
		(net "UPI_CPU1_CPU0_P2P2_DN<16>")
	)
	(segment
		(start 240.707672 -370.041678)
		(end 239.796574 -369.880642)
		(width 0.14732)
		(layer "In11.Cu")
		(net "UPI_CPU1_CPU0_P2P2_DN<16>")
	)
	(segment
		(start 337.040982 -293.612062)
		(end 335.555082 -294.227758)
		(width 0.14732)
		(layer "In11.Cu")
		(net "UPI_CPU1_CPU0_P2P2_DN<16>")
	)
	(segment
		(start 243.346732 -370.194078)
		(end 242.989862 -370.444268)
		(width 0.14732)
		(layer "In11.Cu")
		(net "UPI_CPU1_CPU0_P2P2_DN<16>")
	)
	(segment
		(start 248.305066 -371.38102)
		(end 248.30405 -371.38102)
		(width 0.14732)
		(layer "In11.Cu")
		(net "UPI_CPU1_CPU0_P2P2_DN<16>")
	)
	(segment
		(start 243.912644 -367.830354)
		(end 243.742464 -367.94948)
		(width 0.14732)
		(layer "In11.Cu")
		(net "UPI_CPU1_CPU0_P2P2_DN<16>")
	)
	(segment
		(start 241.6302 -367.427764)
		(end 241.46002 -367.54689)
		(width 0.14732)
		(layer "In11.Cu")
		(net "UPI_CPU1_CPU0_P2P2_DN<16>")
	)
	(segment
		(start 340.002368 -290.591494)
		(end 340.002368 -290.731956)
		(width 0.0889)
		(layer "In11.Cu")
		(net "UPI_CPU1_CPU0_P2P2_DN<16>")
	)
	(segment
		(start 244.494558 -367.93297)
		(end 243.912644 -367.830354)
		(width 0.14732)
		(layer "In11.Cu")
		(net "UPI_CPU1_CPU0_P2P2_DN<16>")
	)
	(segment
		(start 265.189462 -345.36507)
		(end 265.189462 -363.730286)
		(width 0.14732)
		(layer "In11.Cu")
		(net "UPI_CPU1_CPU0_P2P2_DN<16>")
	)
	(segment
		(start 315.292994 -319.033398)
		(end 315.263276 -319.033398)
		(width 0.14732)
		(layer "In11.Cu")
		(net "UPI_CPU1_CPU0_P2P2_DN<16>")
	)
	(segment
		(start 342.586564 -282.895548)
		(end 342.577674 -282.900628)
		(width 0.0889)
		(layer "In11.Cu")
		(net "UPI_CPU1_CPU0_P2P2_DN<16>")
	)
	(segment
		(start 239.796574 -369.880642)
		(end 212.31225 -374.726708)
		(width 0.14732)
		(layer "In11.Cu")
		(net "UPI_CPU1_CPU0_P2P2_DN<16>")
	)
	(segment
		(start 246.777002 -368.33556)
		(end 246.195088 -368.232944)
		(width 0.14732)
		(layer "In11.Cu")
		(net "UPI_CPU1_CPU0_P2P2_DN<16>")
	)
	(segment
		(start 248.352818 -371.389402)
		(end 248.305066 -371.38102)
		(width 0.14732)
		(layer "In11.Cu")
		(net "UPI_CPU1_CPU0_P2P2_DN<16>")
	)
	(segment
		(start 99.437952 -289.113976)
		(end 99.437952 -288.898076)
		(width 0.0889)
		(layer "In11.Cu")
		(net "UPI_CPU1_CPU0_P2P2_DN<16>")
	)
	(segment
		(start 341.18296 -286.961326)
		(end 341.177626 -286.964374)
		(width 0.0889)
		(layer "In11.Cu")
		(net "UPI_CPU1_CPU0_P2P2_DN<16>")
	)
	(segment
		(start 246.750332 -371.107208)
		(end 246.500142 -370.750592)
		(width 0.14732)
		(layer "In11.Cu")
		(net "UPI_CPU1_CPU0_P2P2_DN<16>")
	)
	(segment
		(start 246.195088 -368.232944)
		(end 246.024908 -368.35207)
		(width 0.14732)
		(layer "In11.Cu")
		(net "UPI_CPU1_CPU0_P2P2_DN<16>")
	)
	(segment
		(start 342.869266 -282.3972)
		(end 342.869266 -282.42006)
		(width 0.0889)
		(layer "In11.Cu")
		(net "UPI_CPU1_CPU0_P2P2_DN<16>")
	)
	(segment
		(start 307.58892 -324.516496)
		(end 306.40528 -325.345298)
		(width 0.14732)
		(layer "In11.Cu")
		(net "UPI_CPU1_CPU0_P2P2_DN<16>")
	)
	(segment
		(start 72.275192 -323.54393)
		(end 80.44053 -315.378592)
		(width 0.14732)
		(layer "In11.Cu")
		(net "UPI_CPU1_CPU0_P2P2_DN<16>")
	)
	(segment
		(start 70.407276 -328.556874)
		(end 71.116698 -325.99376)
		(width 0.14732)
		(layer "In11.Cu")
		(net "UPI_CPU1_CPU0_P2P2_DN<16>")
	)
	(segment
		(start 315.313822 -319.01257)
		(end 315.292994 -319.033398)
		(width 0.14732)
		(layer "In11.Cu")
		(net "UPI_CPU1_CPU0_P2P2_DN<16>")
	)
	(segment
		(start 256.701798 -369.917472)
		(end 248.354088 -371.389148)
		(width 0.14732)
		(layer "In11.Cu")
		(net "UPI_CPU1_CPU0_P2P2_DN<16>")
	)
	(segment
		(start 99.379786 -293.180008)
		(end 99.421696 -293.138098)
		(width 0.0889)
		(layer "In11.Cu")
		(net "UPI_CPU1_CPU0_P2P2_DN<16>")
	)
	(segment
		(start 334.598518 -295.659302)
		(end 332.826106 -301.50054)
		(width 0.14732)
		(layer "In11.Cu")
		(net "UPI_CPU1_CPU0_P2P2_DN<16>")
	)
	(segment
		(start 278.426672 -332.12786)
		(end 265.189462 -345.36507)
		(width 0.14732)
		(layer "In11.Cu")
		(net "UPI_CPU1_CPU0_P2P2_DN<16>")
	)
	(segment
		(start 339.6107 -290.983162)
		(end 339.6107 -291.123624)
		(width 0.0889)
		(layer "In11.Cu")
		(net "UPI_CPU1_CPU0_P2P2_DN<16>")
	)
	(segment
		(start 340.519512 -289.60953)
		(end 340.519512 -290.07435)
		(width 0.0889)
		(layer "In11.Cu")
		(net "UPI_CPU1_CPU0_P2P2_DN<16>")
	)
	(segment
		(start 341.18296 -285.33344)
		(end 341.167974 -285.342076)
		(width 0.0889)
		(layer "In11.Cu")
		(net "UPI_CPU1_CPU0_P2P2_DN<16>")
	)
	(segment
		(start 246.024908 -368.35207)
		(end 245.629176 -370.596668)
		(width 0.14732)
		(layer "In11.Cu")
		(net "UPI_CPU1_CPU0_P2P2_DN<16>")
	)
	(segment
		(start 248.30405 -371.38102)
		(end 248.303796 -371.380766)
		(width 0.14732)
		(layer "In11.Cu")
		(net "UPI_CPU1_CPU0_P2P2_DN<16>")
	)
	(segment
		(start 245.629176 -370.596668)
		(end 245.272306 -370.846858)
		(width 0.14732)
		(layer "In11.Cu")
		(net "UPI_CPU1_CPU0_P2P2_DN<16>")
	)
	(segment
		(start 284.500574 -329.61199)
		(end 278.426672 -332.12786)
		(width 0.14732)
		(layer "In11.Cu")
		(net "UPI_CPU1_CPU0_P2P2_DN<16>")
	)
	(segment
		(start 340.049866 -288.917126)
		(end 340.049866 -289.078416)
		(width 0.0889)
		(layer "In11.Cu")
		(net "UPI_CPU1_CPU0_P2P2_DN<16>")
	)
	(segment
		(start 244.214396 -370.366544)
		(end 244.613684 -368.10315)
		(width 0.14732)
		(layer "In11.Cu")
		(net "UPI_CPU1_CPU0_P2P2_DN<16>")
	)
	(segment
		(start 212.31225 -374.726708)
		(end 200.152254 -372.58244)
		(width 0.14732)
		(layer "In11.Cu")
		(net "UPI_CPU1_CPU0_P2P2_DN<16>")
	)
	(segment
		(start 339.171534 -291.481256)
		(end 339.15604 -291.49675)
		(width 0.0889)
		(layer "In11.Cu")
		(net "UPI_CPU1_CPU0_P2P2_DN<16>")
	)
	(segment
		(start 264.376662 -364.54334)
		(end 256.701798 -369.917472)
		(width 0.14732)
		(layer "In11.Cu")
		(net "UPI_CPU1_CPU0_P2P2_DN<16>")
	)
	(segment
		(start 340.237318 -288.592768)
		(end 340.228428 -288.597848)
		(width 0.0889)
		(layer "In11.Cu")
		(net "UPI_CPU1_CPU0_P2P2_DN<16>")
	)
	(segment
		(start 332.826106 -301.50054)
		(end 315.313822 -319.01257)
		(width 0.14732)
		(layer "In11.Cu")
		(net "UPI_CPU1_CPU0_P2P2_DN<16>")
	)
	(segment
		(start 340.519766 -288.103056)
		(end 340.519766 -288.121598)
		(width 0.0889)
		(layer "In11.Cu")
		(net "UPI_CPU1_CPU0_P2P2_DN<16>")
	)
	(segment
		(start 340.268306 -290.466018)
		(end 340.127844 -290.466018)
		(width 0.0889)
		(layer "In11.Cu")
		(net "UPI_CPU1_CPU0_P2P2_DN<16>")
	)
	(segment
		(start 244.613684 -368.10315)
		(end 244.494558 -367.93297)
		(width 0.14732)
		(layer "In11.Cu")
		(net "UPI_CPU1_CPU0_P2P2_DN<16>")
	)
	(segment
		(start 242.185444 -370.301774)
		(end 241.935254 -369.945412)
		(width 0.14732)
		(layer "In11.Cu")
		(net "UPI_CPU1_CPU0_P2P2_DN<16>")
	)
	(segment
		(start 101.614986 -281.907742)
		(end 101.614478 -281.907742)
		(width 0.0889)
		(layer "In11.Cu")
		(net "UPI_CPU1_CPU0_P2P2_DN<16>")
	)
	(segment
		(start 339.15604 -291.497512)
		(end 338.636864 -292.016688)
		(width 0.14732)
		(layer "In11.Cu")
		(net "UPI_CPU1_CPU0_P2P2_DN<16>")
	)
	(segment
		(start 126.064518 -379.379988)
		(end 98.139504 -375.234454)
		(width 0.14732)
		(layer "In11.Cu")
		(net "UPI_CPU1_CPU0_P2P2_DN<16>")
	)
	(segment
		(start 102.256844 -284.046168)
		(end 102.256844 -284.033722)
		(width 0.0889)
		(layer "In11.Cu")
		(net "UPI_CPU1_CPU0_P2P2_DN<16>")
	)
	(segment
		(start 343.400126 -282.134818)
		(end 343.379044 -282.05684)
		(width 0.0889)
		(layer "In11.Cu")
		(net "UPI_CPU1_CPU0_P2P2_DN<16>")
	)
	(segment
		(start 161.592768 -379.379988)
		(end 126.064518 -379.379988)
		(width 0.14732)
		(layer "In11.Cu")
		(net "UPI_CPU1_CPU0_P2P2_DN<16>")
	)
	(segment
		(start 99.421696 -293.138098)
		(end 99.421696 -290.46297)
		(width 0.0889)
		(layer "In11.Cu")
		(net "UPI_CPU1_CPU0_P2P2_DN<16>")
	)
	(segment
		(start 340.707218 -287.778698)
		(end 340.698328 -287.783778)
		(width 0.0889)
		(layer "In11.Cu")
		(net "UPI_CPU1_CPU0_P2P2_DN<16>")
	)
	(segment
		(start 98.139504 -375.234454)
		(end 76.99121 -366.474502)
		(width 0.14732)
		(layer "In11.Cu")
		(net "UPI_CPU1_CPU0_P2P2_DN<16>")
	)
	(segment
		(start 340.519512 -290.07435)
		(end 340.394036 -290.199826)
		(width 0.0889)
		(layer "In11.Cu")
		(net "UPI_CPU1_CPU0_P2P2_DN<16>")
	)
	(segment
		(start 99.379786 -293.202106)
		(end 99.379786 -293.180008)
		(width 0.0889)
		(layer "In11.Cu")
		(net "UPI_CPU1_CPU0_P2P2_DN<16>")
	)
	(segment
		(start 102.726744 -283.228542)
		(end 102.726744 -283.21127)
		(width 0.0889)
		(layer "In11.Cu")
		(net "UPI_CPU1_CPU0_P2P2_DN<16>")
	)
	(segment
		(start 101.6 -286.151066)
		(end 101.589078 -286.14497)
		(width 0.0889)
		(layer "In11.Cu")
		(net "UPI_CPU1_CPU0_P2P2_DN<16>")
	)
	(segment
		(start 101.786944 -286.48406)
		(end 101.786944 -286.463486)
		(width 0.0889)
		(layer "In11.Cu")
		(net "UPI_CPU1_CPU0_P2P2_DN<16>")
	)
	(segment
		(start 242.33124 -367.70056)
		(end 242.212114 -367.53038)
		(width 0.14732)
		(layer "In11.Cu")
		(net "UPI_CPU1_CPU0_P2P2_DN<16>")
	)
	(segment
		(start 339.344508 -291.249354)
		(end 339.171534 -291.422328)
		(width 0.0889)
		(layer "In11.Cu")
		(net "UPI_CPU1_CPU0_P2P2_DN<16>")
	)
	(segment
		(start 76.99121 -366.474502)
		(end 73.80351 -363.286802)
		(width 0.14732)
		(layer "In11.Cu")
		(net "UPI_CPU1_CPU0_P2P2_DN<16>")
	)
	(segment
		(start 248.354088 -371.389148)
		(end 248.352818 -371.389402)
		(width 0.14732)
		(layer "In11.Cu")
		(net "UPI_CPU1_CPU0_P2P2_DN<16>")
	)
	(segment
		(start 340.127844 -290.466018)
		(end 340.002368 -290.591494)
		(width 0.0889)
		(layer "In11.Cu")
		(net "UPI_CPU1_CPU0_P2P2_DN<16>")
	)
	(segment
		(start 339.736176 -290.857686)
		(end 339.6107 -290.983162)
		(width 0.0889)
		(layer "In11.Cu")
		(net "UPI_CPU1_CPU0_P2P2_DN<16>")
	)
	(segment
		(start 246.896128 -368.50574)
		(end 246.777002 -368.33556)
		(width 0.14732)
		(layer "In11.Cu")
		(net "UPI_CPU1_CPU0_P2P2_DN<16>")
	)
	(segment
		(start 95.911924 -302.681386)
		(end 97.183956 -300.966124)
		(width 0.14732)
		(layer "In11.Cu")
		(net "UPI_CPU1_CPU0_P2P2_DN<16>")
	)
	(segment
		(start 101.614478 -282.904184)
		(end 101.599746 -282.895548)
		(width 0.0889)
		(layer "In11.Cu")
		(net "UPI_CPU1_CPU0_P2P2_DN<16>")
	)
	(segment
		(start 310.967374 -320.812922)
		(end 309.796688 -321.799458)
		(width 0.14732)
		(layer "In11.Cu")
		(net "UPI_CPU1_CPU0_P2P2_DN<16>")
	)
	(segment
		(start 99.437952 -288.898076)
		(end 99.437698 -288.898584)
		(width 0.0889)
		(layer "In11.Cu")
		(net "UPI_CPU1_CPU0_P2P2_DN<16>")
	)
	(segment
		(start 343.243662 -282.405836)
		(end 343.400126 -282.134818)
		(width 0.0889)
		(layer "In11.Cu")
		(net "UPI_CPU1_CPU0_P2P2_DN<16>")
	)
	(segment
		(start 69.773038 -353.557332)
		(end 69.773038 -335.000092)
		(width 0.14732)
		(layer "In11.Cu")
		(net "UPI_CPU1_CPU0_P2P2_DN<16>")
	)
	(arc
		(start 102.539546 -283.544264)
		(mid 102.674479 -283.41091)
		(end 102.726744 -283.228542)
		(width 0.0889)
		(layer "In11.Cu")
		(net "UPI_CPU1_CPU0_P2P2_DN<16>")
	)
	(arc
		(start 101.604318 -285.169102)
		(mid 101.73829 -285.032494)
		(end 101.787198 -284.847538)
		(width 0.0889)
		(layer "In11.Cu")
		(net "UPI_CPU1_CPU0_P2P2_DN<16>")
	)
	(arc
		(start 102.086664 -281.878786)
		(mid 102.096736 -281.882753)
		(end 102.10673 -281.886914)
		(width 0.0889)
		(layer "In11.Cu")
		(net "UPI_CPU1_CPU0_P2P2_DN<16>")
	)
	(arc
		(start 342.107774 -283.714444)
		(mid 341.97686 -283.850804)
		(end 341.929212 -284.033722)
		(width 0.0889)
		(layer "In11.Cu")
		(net "UPI_CPU1_CPU0_P2P2_DN<16>")
	)
	(arc
		(start 99.907598 -289.64509)
		(mid 99.832491 -289.529944)
		(end 99.723448 -289.446208)
		(width 0.0889)
		(layer "In11.Cu")
		(net "UPI_CPU1_CPU0_P2P2_DN<16>")
	)
	(arc
		(start 101.599746 -282.895548)
		(mid 101.396265 -282.694744)
		(end 101.317044 -282.42006)
		(width 0.0889)
		(layer "In11.Cu")
		(net "UPI_CPU1_CPU0_P2P2_DN<16>")
	)
	(arc
		(start 99.729036 -288.422334)
		(mid 99.85995 -288.285974)
		(end 99.907598 -288.103056)
		(width 0.0889)
		(layer "In11.Cu")
		(net "UPI_CPU1_CPU0_P2P2_DN<16>")
	)
	(arc
		(start 102.070154 -284.357826)
		(mid 102.203784 -284.226126)
		(end 102.256844 -284.046168)
		(width 0.0889)
		(layer "In11.Cu")
		(net "UPI_CPU1_CPU0_P2P2_DN<16>")
	)
	(arc
		(start 341.176864 -286.964882)
		(mid 341.041931 -287.098236)
		(end 340.989666 -287.280604)
		(width 0.0889)
		(layer "In11.Cu")
		(net "UPI_CPU1_CPU0_P2P2_DN<16>")
	)
	(arc
		(start 341.459566 -284.847538)
		(mid 341.385575 -285.127104)
		(end 341.18296 -285.33344)
		(width 0.0889)
		(layer "In11.Cu")
		(net "UPI_CPU1_CPU0_P2P2_DN<16>")
	)
	(arc
		(start 340.989666 -287.299146)
		(mid 340.911555 -287.576095)
		(end 340.707218 -287.778698)
		(width 0.0889)
		(layer "In11.Cu")
		(net "UPI_CPU1_CPU0_P2P2_DN<16>")
	)
	(arc
		(start 101.787198 -284.847538)
		(mid 101.859819 -284.570073)
		(end 102.059232 -284.363922)
		(width 0.0889)
		(layer "In11.Cu")
		(net "UPI_CPU1_CPU0_P2P2_DN<16>")
	)
	(arc
		(start 342.869266 -282.42006)
		(mid 342.790047 -282.694745)
		(end 342.586564 -282.895548)
		(width 0.0889)
		(layer "In11.Cu")
		(net "UPI_CPU1_CPU0_P2P2_DN<16>")
	)
	(arc
		(start 341.167974 -285.342076)
		(mid 340.989256 -285.661354)
		(end 341.167974 -285.980632)
		(width 0.0889)
		(layer "In11.Cu")
		(net "UPI_CPU1_CPU0_P2P2_DN<16>")
	)
	(arc
		(start 342.399112 -283.229812)
		(mid 342.321001 -283.506761)
		(end 342.116664 -283.709364)
		(width 0.0889)
		(layer "In11.Cu")
		(net "UPI_CPU1_CPU0_P2P2_DN<16>")
	)
	(arc
		(start 99.907598 -288.087562)
		(mid 99.986968 -287.813828)
		(end 100.189792 -287.613598)
		(width 0.0889)
		(layer "In11.Cu")
		(net "UPI_CPU1_CPU0_P2P2_DN<16>")
	)
	(arc
		(start 102.539546 -282.895548)
		(mid 102.352348 -282.845405)
		(end 102.16515 -282.895548)
		(width 0.0889)
		(layer "In11.Cu")
		(net "UPI_CPU1_CPU0_P2P2_DN<16>")
	)
	(arc
		(start 340.519766 -288.121598)
		(mid 340.439604 -288.393787)
		(end 340.237318 -288.592768)
		(width 0.0889)
		(layer "In11.Cu")
		(net "UPI_CPU1_CPU0_P2P2_DN<16>")
	)
	(arc
		(start 340.049866 -289.078416)
		(mid 340.124871 -289.193875)
		(end 340.234016 -289.277806)
		(width 0.0889)
		(layer "In11.Cu")
		(net "UPI_CPU1_CPU0_P2P2_DN<16>")
	)
	(arc
		(start 99.437698 -288.898584)
		(mid 99.51786 -288.626395)
		(end 99.720146 -288.427414)
		(width 0.0889)
		(layer "In11.Cu")
		(net "UPI_CPU1_CPU0_P2P2_DN<16>")
	)
	(arc
		(start 102.256844 -284.033722)
		(mid 102.329465 -283.756257)
		(end 102.528878 -283.550106)
		(width 0.0889)
		(layer "In11.Cu")
		(net "UPI_CPU1_CPU0_P2P2_DN<16>")
	)
	(arc
		(start 343.379044 -282.05684)
		(mid 343.035757 -282.094545)
		(end 342.869266 -282.3972)
		(width 0.0889)
		(layer "In11.Cu")
		(net "UPI_CPU1_CPU0_P2P2_DN<16>")
	)
	(arc
		(start 101.787198 -286.463994)
		(mid 101.73421 -286.283239)
		(end 101.6 -286.151066)
		(width 0.0889)
		(layer "In11.Cu")
		(net "UPI_CPU1_CPU0_P2P2_DN<16>")
	)
	(arc
		(start 341.638128 -284.52826)
		(mid 341.507214 -284.66462)
		(end 341.459566 -284.847538)
		(width 0.0889)
		(layer "In11.Cu")
		(net "UPI_CPU1_CPU0_P2P2_DN<16>")
	)
	(arc
		(start 341.176864 -285.985712)
		(mid 341.383846 -286.192674)
		(end 341.459566 -286.475424)
		(width 0.0889)
		(layer "In11.Cu")
		(net "UPI_CPU1_CPU0_P2P2_DN<16>")
	)
	(arc
		(start 102.16515 -282.895548)
		(mid 101.890921 -282.971473)
		(end 101.614478 -282.904184)
		(width 0.0889)
		(layer "In11.Cu")
		(net "UPI_CPU1_CPU0_P2P2_DN<16>")
	)
	(arc
		(start 342.577674 -282.900628)
		(mid 342.44676 -283.036988)
		(end 342.399112 -283.219906)
		(width 0.0889)
		(layer "In11.Cu")
		(net "UPI_CPU1_CPU0_P2P2_DN<16>")
	)
	(arc
		(start 100.377244 -287.279334)
		(mid 100.664214 -286.797194)
		(end 101.22535 -286.799782)
		(width 0.0889)
		(layer "In11.Cu")
		(net "UPI_CPU1_CPU0_P2P2_DN<16>")
	)
	(arc
		(start 341.459566 -286.475424)
		(mid 341.385575 -286.75499)
		(end 341.18296 -286.961326)
		(width 0.0889)
		(layer "In11.Cu")
		(net "UPI_CPU1_CPU0_P2P2_DN<16>")
	)
	(arc
		(start 102.726744 -283.21127)
		(mid 102.674474 -283.028905)
		(end 102.539546 -282.895548)
		(width 0.0889)
		(layer "In11.Cu")
		(net "UPI_CPU1_CPU0_P2P2_DN<16>")
	)
	(arc
		(start 100.198682 -287.608518)
		(mid 100.329596 -287.472158)
		(end 100.377244 -287.28924)
		(width 0.0889)
		(layer "In11.Cu")
		(net "UPI_CPU1_CPU0_P2P2_DN<16>")
	)
	(arc
		(start 101.589078 -286.14497)
		(mid 101.316901 -285.661542)
		(end 101.589078 -285.177992)
		(width 0.0889)
		(layer "In11.Cu")
		(net "UPI_CPU1_CPU0_P2P2_DN<16>")
	)
	(arc
		(start 101.614478 -281.907742)
		(mid 101.847393 -281.841531)
		(end 102.086664 -281.878786)
		(width 0.0889)
		(layer "In11.Cu")
		(net "UPI_CPU1_CPU0_P2P2_DN<16>")
	)
	(arc
		(start 340.698328 -287.783778)
		(mid 340.567414 -287.920138)
		(end 340.519766 -288.103056)
		(width 0.0889)
		(layer "In11.Cu")
		(net "UPI_CPU1_CPU0_P2P2_DN<16>")
	)
	(arc
		(start 341.929212 -284.049216)
		(mid 341.849842 -284.32295)
		(end 341.647018 -284.52318)
		(width 0.0889)
		(layer "In11.Cu")
		(net "UPI_CPU1_CPU0_P2P2_DN<16>")
	)
	(arc
		(start 340.234016 -289.277806)
		(mid 340.408148 -289.416653)
		(end 340.519512 -289.60953)
		(width 0.0889)
		(layer "In11.Cu")
		(net "UPI_CPU1_CPU0_P2P2_DN<16>")
	)
	(arc
		(start 340.228428 -288.597848)
		(mid 340.097514 -288.734208)
		(end 340.049866 -288.917126)
		(width 0.0889)
		(layer "In11.Cu")
		(net "UPI_CPU1_CPU0_P2P2_DN<16>")
	)
	(arc
		(start 101.317044 -282.405836)
		(mid 101.391035 -282.12627)
		(end 101.59365 -281.919934)
		(width 0.0889)
		(layer "In11.Cu")
		(net "UPI_CPU1_CPU0_P2P2_DN<16>")
	)
	(arc
		(start 101.22535 -286.799782)
		(mid 101.59602 -286.801906)
		(end 101.786944 -286.48406)
		(width 0.0889)
		(layer "In11.Cu")
		(net "UPI_CPU1_CPU0_P2P2_DN<16>")
	)
	(arc
		(start 99.723448 -289.446208)
		(mid 99.549203 -289.307162)
		(end 99.437952 -289.113976)
		(width 0.0889)
		(layer "In11.Cu")
		(net "UPI_CPU1_CPU0_P2P2_DN<16>")
	)
	(segment
		(start 101.412294 -283.219652)
		(end 101.412548 -283.219906)
		(width 0.13208)
		(layer "F.Cu")
		(net "UPI_CPU1_CPU0_P2P2_DN<15>")
	)
	(segment
		(start 101.412294 -282.683966)
		(end 101.412294 -283.219652)
		(width 0.13208)
		(layer "F.Cu")
		(net "UPI_CPU1_CPU0_P2P2_DN<15>")
	)
	(segment
		(start 345.123516 -280.77795)
		(end 345.123262 -280.778204)
		(width 0.13208)
		(layer "F.Cu")
		(net "UPI_CPU1_CPU0_P2P2_DN<15>")
	)
	(segment
		(start 345.123516 -280.242264)
		(end 345.123516 -280.77795)
		(width 0.13208)
		(layer "F.Cu")
		(net "UPI_CPU1_CPU0_P2P2_DN<15>")
	)
	(segment
		(start 98.497898 -289.077908)
		(end 98.497898 -288.898584)
		(width 0.0889)
		(layer "In11.Cu")
		(net "UPI_CPU1_CPU0_P2P2_DN<15>")
	)
	(segment
		(start 342.12276 -285.33344)
		(end 342.107774 -285.342076)
		(width 0.0889)
		(layer "In11.Cu")
		(net "UPI_CPU1_CPU0_P2P2_DN<15>")
	)
	(segment
		(start 98.027744 -290.341558)
		(end 98.027744 -289.611054)
		(width 0.0889)
		(layer "In11.Cu")
		(net "UPI_CPU1_CPU0_P2P2_DN<15>")
	)
	(segment
		(start 101.129592 -284.35808)
		(end 101.138482 -284.353)
		(width 0.0889)
		(layer "In11.Cu")
		(net "UPI_CPU1_CPU0_P2P2_DN<15>")
	)
	(segment
		(start 100.847398 -284.847538)
		(end 100.847398 -284.832044)
		(width 0.0889)
		(layer "In11.Cu")
		(net "UPI_CPU1_CPU0_P2P2_DN<15>")
	)
	(segment
		(start 161.662364 -380.20879)
		(end 125.966728 -380.20879)
		(width 0.14732)
		(layer "In11.Cu")
		(net "UPI_CPU1_CPU0_P2P2_DN<15>")
	)
	(segment
		(start 227.985828 -374.205246)
		(end 227.65258 -373.925084)
		(width 0.14732)
		(layer "In11.Cu")
		(net "UPI_CPU1_CPU0_P2P2_DN<15>")
	)
	(segment
		(start 101.725222 -283.219906)
		(end 101.412548 -283.219906)
		(width 0.0889)
		(layer "In11.Cu")
		(net "UPI_CPU1_CPU0_P2P2_DN<15>")
	)
	(segment
		(start 262.254238 -368.631216)
		(end 262.1788 -369.059714)
		(width 0.14732)
		(layer "In11.Cu")
		(net "UPI_CPU1_CPU0_P2P2_DN<15>")
	)
	(segment
		(start 125.966728 -380.20879)
		(end 97.86366 -376.039634)
		(width 0.14732)
		(layer "In11.Cu")
		(net "UPI_CPU1_CPU0_P2P2_DN<15>")
	)
	(segment
		(start 314.424314 -321.076828)
		(end 311.460896 -323.151754)
		(width 0.14732)
		(layer "In11.Cu")
		(net "UPI_CPU1_CPU0_P2P2_DN<15>")
	)
	(segment
		(start 340.884256 -290.811458)
		(end 340.868762 -290.826952)
		(width 0.0889)
		(layer "In11.Cu")
		(net "UPI_CPU1_CPU0_P2P2_DN<15>")
	)
	(segment
		(start 234.911646 -373.596408)
		(end 234.578398 -373.316246)
		(width 0.14732)
		(layer "In11.Cu")
		(net "UPI_CPU1_CPU0_P2P2_DN<15>")
	)
	(segment
		(start 224.562416 -373.66194)
		(end 224.429066 -373.821198)
		(width 0.14732)
		(layer "In11.Cu")
		(net "UPI_CPU1_CPU0_P2P2_DN<15>")
	)
	(segment
		(start 342.107774 -285.980632)
		(end 342.116664 -285.985712)
		(width 0.0889)
		(layer "In11.Cu")
		(net "UPI_CPU1_CPU0_P2P2_DN<15>")
	)
	(segment
		(start 258.52628 -370.103146)
		(end 257.460242 -370.849652)
		(width 0.14732)
		(layer "In11.Cu")
		(net "UPI_CPU1_CPU0_P2P2_DN<15>")
	)
	(segment
		(start 239.19561 -372.910354)
		(end 239.161574 -372.526306)
		(width 0.14732)
		(layer "In11.Cu")
		(net "UPI_CPU1_CPU0_P2P2_DN<15>")
	)
	(segment
		(start 336.109056 -294.89908)
		(end 335.354676 -296.027856)
		(width 0.14732)
		(layer "In11.Cu")
		(net "UPI_CPU1_CPU0_P2P2_DN<15>")
	)
	(segment
		(start 69.586348 -328.408538)
		(end 70.334378 -325.705216)
		(width 0.14732)
		(layer "In11.Cu")
		(net "UPI_CPU1_CPU0_P2P2_DN<15>")
	)
	(segment
		(start 243.031264 -372.038372)
		(end 242.897914 -372.19763)
		(width 0.14732)
		(layer "In11.Cu")
		(net "UPI_CPU1_CPU0_P2P2_DN<15>")
	)
	(segment
		(start 239.161574 -372.526306)
		(end 239.002316 -372.392702)
		(width 0.14732)
		(layer "In11.Cu")
		(net "UPI_CPU1_CPU0_P2P2_DN<15>")
	)
	(segment
		(start 262.1788 -369.059714)
		(end 261.508494 -369.528852)
		(width 0.14732)
		(layer "In11.Cu")
		(net "UPI_CPU1_CPU0_P2P2_DN<15>")
	)
	(segment
		(start 234.544362 -372.932198)
		(end 234.385104 -372.798594)
		(width 0.14732)
		(layer "In11.Cu")
		(net "UPI_CPU1_CPU0_P2P2_DN<15>")
	)
	(segment
		(start 340.134194 -291.99586)
		(end 338.02447 -294.105584)
		(width 0.14732)
		(layer "In11.Cu")
		(net "UPI_CPU1_CPU0_P2P2_DN<15>")
	)
	(segment
		(start 229.046278 -373.415306)
		(end 229.08006 -373.799862)
		(width 0.14732)
		(layer "In11.Cu")
		(net "UPI_CPU1_CPU0_P2P2_DN<15>")
	)
	(segment
		(start 200.15073 -373.423942)
		(end 161.662364 -380.20879)
		(width 0.14732)
		(layer "In11.Cu")
		(net "UPI_CPU1_CPU0_P2P2_DN<15>")
	)
	(segment
		(start 261.803896 -367.987834)
		(end 262.254238 -368.631216)
		(width 0.14732)
		(layer "In11.Cu")
		(net "UPI_CPU1_CPU0_P2P2_DN<15>")
	)
	(segment
		(start 228.799898 -374.13311)
		(end 227.985828 -374.205246)
		(width 0.14732)
		(layer "In11.Cu")
		(net "UPI_CPU1_CPU0_P2P2_DN<15>")
	)
	(segment
		(start 227.65258 -373.925084)
		(end 227.618544 -373.541036)
		(width 0.14732)
		(layer "In11.Cu")
		(net "UPI_CPU1_CPU0_P2P2_DN<15>")
	)
	(segment
		(start 235.725716 -373.524272)
		(end 234.911646 -373.596408)
		(width 0.14732)
		(layer "In11.Cu")
		(net "UPI_CPU1_CPU0_P2P2_DN<15>")
	)
	(segment
		(start 96.438466 -300.563026)
		(end 97.985834 -296.827702)
		(width 0.14732)
		(layer "In11.Cu")
		(net "UPI_CPU1_CPU0_P2P2_DN<15>")
	)
	(segment
		(start 224.429066 -373.821198)
		(end 224.462848 -374.205754)
		(width 0.14732)
		(layer "In11.Cu")
		(net "UPI_CPU1_CPU0_P2P2_DN<15>")
	)
	(segment
		(start 311.460896 -323.151754)
		(end 311.411112 -323.186806)
		(width 0.14732)
		(layer "In11.Cu")
		(net "UPI_CPU1_CPU0_P2P2_DN<15>")
	)
	(segment
		(start 343.338912 -283.219906)
		(end 343.338912 -283.229812)
		(width 0.0889)
		(layer "In11.Cu")
		(net "UPI_CPU1_CPU0_P2P2_DN<15>")
	)
	(segment
		(start 344.748866 -280.769568)
		(end 344.748866 -280.78811)
		(width 0.0889)
		(layer "In11.Cu")
		(net "UPI_CPU1_CPU0_P2P2_DN<15>")
	)
	(segment
		(start 343.526364 -282.895548)
		(end 343.517474 -282.900628)
		(width 0.0889)
		(layer "In11.Cu")
		(net "UPI_CPU1_CPU0_P2P2_DN<15>")
	)
	(segment
		(start 260.42493 -368.77371)
		(end 259.941822 -369.112292)
		(width 0.14732)
		(layer "In11.Cu")
		(net "UPI_CPU1_CPU0_P2P2_DN<15>")
	)
	(segment
		(start 71.584312 -323.062092)
		(end 79.886556 -314.759594)
		(width 0.14732)
		(layer "In11.Cu")
		(net "UPI_CPU1_CPU0_P2P2_DN<15>")
	)
	(segment
		(start 240.589308 -372.400576)
		(end 240.62309 -372.785132)
		(width 0.14732)
		(layer "In11.Cu")
		(net "UPI_CPU1_CPU0_P2P2_DN<15>")
	)
	(segment
		(start 258.731258 -370.139468)
		(end 258.52628 -370.103146)
		(width 0.14732)
		(layer "In11.Cu")
		(net "UPI_CPU1_CPU0_P2P2_DN<15>")
	)
	(segment
		(start 101.608636 -283.53893)
		(end 101.608636 -283.539184)
		(width 0.0889)
		(layer "In11.Cu")
		(net "UPI_CPU1_CPU0_P2P2_DN<15>")
	)
	(segment
		(start 99.249992 -287.613598)
		(end 99.258882 -287.608518)
		(width 0.0889)
		(layer "In11.Cu")
		(net "UPI_CPU1_CPU0_P2P2_DN<15>")
	)
	(segment
		(start 333.560674 -301.940976)
		(end 333.511906 -301.989744)
		(width 0.14732)
		(layer "In11.Cu")
		(net "UPI_CPU1_CPU0_P2P2_DN<15>")
	)
	(segment
		(start 344.966798 -280.507186)
		(end 344.88882 -280.486358)
		(width 0.0889)
		(layer "In11.Cu")
		(net "UPI_CPU1_CPU0_P2P2_DN<15>")
	)
	(segment
		(start 259.1816 -370.78285)
		(end 258.731258 -370.139468)
		(width 0.14732)
		(layer "In11.Cu")
		(net "UPI_CPU1_CPU0_P2P2_DN<15>")
	)
	(segment
		(start 224.462848 -374.205754)
		(end 224.190814 -374.52935)
		(width 0.14732)
		(layer "In11.Cu")
		(net "UPI_CPU1_CPU0_P2P2_DN<15>")
	)
	(segment
		(start 261.079996 -369.453414)
		(end 260.629654 -368.810032)
		(width 0.14732)
		(layer "In11.Cu")
		(net "UPI_CPU1_CPU0_P2P2_DN<15>")
	)
	(segment
		(start 341.459566 -288.103056)
		(end 341.459566 -288.121598)
		(width 0.0889)
		(layer "In11.Cu")
		(net "UPI_CPU1_CPU0_P2P2_DN<15>")
	)
	(segment
		(start 212.361526 -375.5771)
		(end 200.15073 -373.423942)
		(width 0.14732)
		(layer "In11.Cu")
		(net "UPI_CPU1_CPU0_P2P2_DN<15>")
	)
	(segment
		(start 242.931696 -372.582186)
		(end 242.651534 -372.915434)
		(width 0.14732)
		(layer "In11.Cu")
		(net "UPI_CPU1_CPU0_P2P2_DN<15>")
	)
	(segment
		(start 231.488234 -373.053102)
		(end 231.354884 -373.21236)
		(width 0.14732)
		(layer "In11.Cu")
		(net "UPI_CPU1_CPU0_P2P2_DN<15>")
	)
	(segment
		(start 241.310922 -372.189756)
		(end 240.722658 -372.241318)
		(width 0.14732)
		(layer "In11.Cu")
		(net "UPI_CPU1_CPU0_P2P2_DN<15>")
	)
	(segment
		(start 341.459312 -290.176458)
		(end 340.884256 -290.751514)
		(width 0.0889)
		(layer "In11.Cu")
		(net "UPI_CPU1_CPU0_P2P2_DN<15>")
	)
	(segment
		(start 223.001332 -373.946928)
		(end 222.842074 -373.813324)
		(width 0.14732)
		(layer "In11.Cu")
		(net "UPI_CPU1_CPU0_P2P2_DN<15>")
	)
	(segment
		(start 333.511906 -301.98949)
		(end 314.424314 -321.076828)
		(width 0.14732)
		(layer "In11.Cu")
		(net "UPI_CPU1_CPU0_P2P2_DN<15>")
	)
	(segment
		(start 284.802834 -330.44003)
		(end 278.798782 -332.926944)
		(width 0.14732)
		(layer "In11.Cu")
		(net "UPI_CPU1_CPU0_P2P2_DN<15>")
	)
	(segment
		(start 99.71405 -286.803338)
		(end 99.719384 -286.80029)
		(width 0.0889)
		(layer "In11.Cu")
		(net "UPI_CPU1_CPU0_P2P2_DN<15>")
	)
	(segment
		(start 227.459286 -373.407432)
		(end 226.871022 -373.458994)
		(width 0.14732)
		(layer "In11.Cu")
		(net "UPI_CPU1_CPU0_P2P2_DN<15>")
	)
	(segment
		(start 310.160162 -323.407278)
		(end 309.810912 -323.756782)
		(width 0.14732)
		(layer "In11.Cu")
		(net "UPI_CPU1_CPU0_P2P2_DN<15>")
	)
	(segment
		(start 309.810912 -323.756782)
		(end 307.503322 -325.698358)
		(width 0.14732)
		(layer "In11.Cu")
		(net "UPI_CPU1_CPU0_P2P2_DN<15>")
	)
	(segment
		(start 235.972096 -372.806468)
		(end 236.005878 -373.191024)
		(width 0.14732)
		(layer "In11.Cu")
		(net "UPI_CPU1_CPU0_P2P2_DN<15>")
	)
	(segment
		(start 238.280702 -372.603522)
		(end 238.314484 -372.988078)
		(width 0.14732)
		(layer "In11.Cu")
		(net "UPI_CPU1_CPU0_P2P2_DN<15>")
	)
	(segment
		(start 343.056464 -283.709364)
		(end 343.047574 -283.714444)
		(width 0.0889)
		(layer "In11.Cu")
		(net "UPI_CPU1_CPU0_P2P2_DN<15>")
	)
	(segment
		(start 232.269792 -373.519192)
		(end 232.235756 -373.135144)
		(width 0.14732)
		(layer "In11.Cu")
		(net "UPI_CPU1_CPU0_P2P2_DN<15>")
	)
	(segment
		(start 76.55179 -367.212626)
		(end 73.0885 -363.749082)
		(width 0.14732)
		(layer "In11.Cu")
		(net "UPI_CPU1_CPU0_P2P2_DN<15>")
	)
	(segment
		(start 244.14607 -372.784624)
		(end 243.812822 -372.504208)
		(width 0.14732)
		(layer "In11.Cu")
		(net "UPI_CPU1_CPU0_P2P2_DN<15>")
	)
	(segment
		(start 307.19268 -325.915782)
		(end 306.792122 -326.488044)
		(width 0.14732)
		(layer "In11.Cu")
		(net "UPI_CPU1_CPU0_P2P2_DN<15>")
	)
	(segment
		(start 101.782626 -283.27731)
		(end 101.725222 -283.219906)
		(width 0.0889)
		(layer "In11.Cu")
		(net "UPI_CPU1_CPU0_P2P2_DN<15>")
	)
	(segment
		(start 236.105446 -372.64721)
		(end 235.972096 -372.806468)
		(width 0.14732)
		(layer "In11.Cu")
		(net "UPI_CPU1_CPU0_P2P2_DN<15>")
	)
	(segment
		(start 229.08006 -373.799862)
		(end 228.799898 -374.13311)
		(width 0.14732)
		(layer "In11.Cu")
		(net "UPI_CPU1_CPU0_P2P2_DN<15>")
	)
	(segment
		(start 222.154242 -374.4087)
		(end 222.08109 -374.495822)
		(width 0.14732)
		(layer "In11.Cu")
		(net "UPI_CPU1_CPU0_P2P2_DN<15>")
	)
	(segment
		(start 338.02447 -294.105584)
		(end 336.109056 -294.89908)
		(width 0.14732)
		(layer "In11.Cu")
		(net "UPI_CPU1_CPU0_P2P2_DN<15>")
	)
	(segment
		(start 97.985834 -290.383468)
		(end 98.027744 -290.341558)
		(width 0.0889)
		(layer "In11.Cu")
		(net "UPI_CPU1_CPU0_P2P2_DN<15>")
	)
	(segment
		(start 70.334378 -325.705216)
		(end 71.584312 -323.062092)
		(width 0.14732)
		(layer "In11.Cu")
		(net "UPI_CPU1_CPU0_P2P2_DN<15>")
	)
	(segment
		(start 231.108504 -373.930164)
		(end 230.294434 -374.0023)
		(width 0.14732)
		(layer "In11.Cu")
		(net "UPI_CPU1_CPU0_P2P2_DN<15>")
	)
	(segment
		(start 226.771454 -374.002808)
		(end 226.491292 -374.336056)
		(width 0.14732)
		(layer "In11.Cu")
		(net "UPI_CPU1_CPU0_P2P2_DN<15>")
	)
	(segment
		(start 342.12276 -286.961326)
		(end 342.11514 -286.965644)
		(width 0.0889)
		(layer "In11.Cu")
		(net "UPI_CPU1_CPU0_P2P2_DN<15>")
	)
	(segment
		(start 259.941822 -369.112292)
		(end 259.9055 -369.31727)
		(width 0.14732)
		(layer "In11.Cu")
		(net "UPI_CPU1_CPU0_P2P2_DN<15>")
	)
	(segment
		(start 340.134194 -291.56152)
		(end 340.134194 -291.99586)
		(width 0.14732)
		(layer "In11.Cu")
		(net "UPI_CPU1_CPU0_P2P2_DN<15>")
	)
	(segment
		(start 340.868762 -290.826952)
		(end 340.134194 -291.56152)
		(width 0.14732)
		(layer "In11.Cu")
		(net "UPI_CPU1_CPU0_P2P2_DN<15>")
	)
	(segment
		(start 248.765568 -372.382542)
		(end 244.14607 -372.784624)
		(width 0.14732)
		(layer "In11.Cu")
		(net "UPI_CPU1_CPU0_P2P2_DN<15>")
	)
	(segment
		(start 311.411112 -323.186806)
		(end 310.160162 -323.407278)
		(width 0.14732)
		(layer "In11.Cu")
		(net "UPI_CPU1_CPU0_P2P2_DN<15>")
	)
	(segment
		(start 240.62309 -372.785132)
		(end 240.342928 -373.11838)
		(width 0.14732)
		(layer "In11.Cu")
		(net "UPI_CPU1_CPU0_P2P2_DN<15>")
	)
	(segment
		(start 266.284456 -364.256574)
		(end 264.902696 -365.638334)
		(width 0.14732)
		(layer "In11.Cu")
		(net "UPI_CPU1_CPU0_P2P2_DN<15>")
	)
	(segment
		(start 341.929212 -287.28924)
		(end 341.929212 -287.304734)
		(width 0.0889)
		(layer "In11.Cu")
		(net "UPI_CPU1_CPU0_P2P2_DN<15>")
	)
	(segment
		(start 225.343974 -374.12803)
		(end 225.309938 -373.743982)
		(width 0.14732)
		(layer "In11.Cu")
		(net "UPI_CPU1_CPU0_P2P2_DN<15>")
	)
	(segment
		(start 264.902696 -365.638334)
		(end 264.032238 -366.24768)
		(width 0.14732)
		(layer "In11.Cu")
		(net "UPI_CPU1_CPU0_P2P2_DN<15>")
	)
	(segment
		(start 233.66349 -373.009414)
		(end 233.697272 -373.39397)
		(width 0.14732)
		(layer "In11.Cu")
		(net "UPI_CPU1_CPU0_P2P2_DN<15>")
	)
	(segment
		(start 226.491292 -374.336056)
		(end 225.677222 -374.408192)
		(width 0.14732)
		(layer "In11.Cu")
		(net "UPI_CPU1_CPU0_P2P2_DN<15>")
	)
	(segment
		(start 264.032238 -366.24768)
		(end 261.840218 -367.782856)
		(width 0.14732)
		(layer "In11.Cu")
		(net "UPI_CPU1_CPU0_P2P2_DN<15>")
	)
	(segment
		(start 236.69371 -372.595648)
		(end 236.105446 -372.64721)
		(width 0.14732)
		(layer "In11.Cu")
		(net "UPI_CPU1_CPU0_P2P2_DN<15>")
	)
	(segment
		(start 98.313494 -289.27806)
		(end 98.313494 -289.277806)
		(width 0.0889)
		(layer "In11.Cu")
		(net "UPI_CPU1_CPU0_P2P2_DN<15>")
	)
	(segment
		(start 68.944998 -353.7458)
		(end 68.944998 -334.922622)
		(width 0.14732)
		(layer "In11.Cu")
		(net "UPI_CPU1_CPU0_P2P2_DN<15>")
	)
	(segment
		(start 233.79684 -372.850156)
		(end 233.66349 -373.009414)
		(width 0.14732)
		(layer "In11.Cu")
		(net "UPI_CPU1_CPU0_P2P2_DN<15>")
	)
	(segment
		(start 231.388666 -373.596916)
		(end 231.108504 -373.930164)
		(width 0.14732)
		(layer "In11.Cu")
		(net "UPI_CPU1_CPU0_P2P2_DN<15>")
	)
	(segment
		(start 230.294434 -374.0023)
		(end 229.961186 -373.722138)
		(width 0.14732)
		(layer "In11.Cu")
		(net "UPI_CPU1_CPU0_P2P2_DN<15>")
	)
	(segment
		(start 97.86366 -376.039634)
		(end 76.55179 -367.212626)
		(width 0.14732)
		(layer "In11.Cu")
		(net "UPI_CPU1_CPU0_P2P2_DN<15>")
	)
	(segment
		(start 222.080836 -374.495822)
		(end 221.87408 -374.742202)
		(width 0.14732)
		(layer "In11.Cu")
		(net "UPI_CPU1_CPU0_P2P2_DN<15>")
	)
	(segment
		(start 342.586818 -284.52318)
		(end 342.577928 -284.52826)
		(width 0.0889)
		(layer "In11.Cu")
		(net "UPI_CPU1_CPU0_P2P2_DN<15>")
	)
	(segment
		(start 99.907344 -286.48406)
		(end 99.907344 -286.456882)
		(width 0.0889)
		(layer "In11.Cu")
		(net "UPI_CPU1_CPU0_P2P2_DN<15>")
	)
	(segment
		(start 225.677222 -374.408192)
		(end 225.343974 -374.12803)
		(width 0.14732)
		(layer "In11.Cu")
		(net "UPI_CPU1_CPU0_P2P2_DN<15>")
	)
	(segment
		(start 100.65385 -285.175452)
		(end 100.668836 -285.166562)
		(width 0.0889)
		(layer "In11.Cu")
		(net "UPI_CPU1_CPU0_P2P2_DN<15>")
	)
	(segment
		(start 79.886556 -314.759594)
		(end 95.276416 -302.129952)
		(width 0.14732)
		(layer "In11.Cu")
		(net "UPI_CPU1_CPU0_P2P2_DN<15>")
	)
	(segment
		(start 342.399366 -286.4612)
		(end 342.399366 -286.475424)
		(width 0.0889)
		(layer "In11.Cu")
		(net "UPI_CPU1_CPU0_P2P2_DN<15>")
	)
	(segment
		(start 98.780346 -288.427414)
		(end 98.789236 -288.422334)
		(width 0.0889)
		(layer "In11.Cu")
		(net "UPI_CPU1_CPU0_P2P2_DN<15>")
	)
	(segment
		(start 68.944998 -334.922622)
		(end 69.586348 -328.408538)
		(width 0.14732)
		(layer "In11.Cu")
		(net "UPI_CPU1_CPU0_P2P2_DN<15>")
	)
	(segment
		(start 231.354884 -373.21236)
		(end 231.388666 -373.596916)
		(width 0.14732)
		(layer "In11.Cu")
		(net "UPI_CPU1_CPU0_P2P2_DN<15>")
	)
	(segment
		(start 259.9055 -369.31727)
		(end 260.355842 -369.960652)
		(width 0.14732)
		(layer "In11.Cu")
		(net "UPI_CPU1_CPU0_P2P2_DN<15>")
	)
	(segment
		(start 344.00236 -282.077922)
		(end 343.987374 -282.086558)
		(width 0.0889)
		(layer "In11.Cu")
		(net "UPI_CPU1_CPU0_P2P2_DN<15>")
	)
	(segment
		(start 229.179628 -373.256048)
		(end 229.046278 -373.415306)
		(width 0.14732)
		(layer "In11.Cu")
		(net "UPI_CPU1_CPU0_P2P2_DN<15>")
	)
	(segment
		(start 100.668836 -285.166562)
		(end 100.668836 -285.166816)
		(width 0.0889)
		(layer "In11.Cu")
		(net "UPI_CPU1_CPU0_P2P2_DN<15>")
	)
	(segment
		(start 261.508494 -369.528852)
		(end 261.079996 -369.453414)
		(width 0.14732)
		(layer "In11.Cu")
		(net "UPI_CPU1_CPU0_P2P2_DN<15>")
	)
	(segment
		(start 333.511906 -301.989744)
		(end 333.511906 -301.98949)
		(width 0.14732)
		(layer "In11.Cu")
		(net "UPI_CPU1_CPU0_P2P2_DN<15>")
	)
	(segment
		(start 342.869012 -284.033722)
		(end 342.869012 -284.049216)
		(width 0.0889)
		(layer "In11.Cu")
		(net "UPI_CPU1_CPU0_P2P2_DN<15>")
	)
	(segment
		(start 237.220252 -373.393462)
		(end 236.887004 -373.1133)
		(width 0.14732)
		(layer "In11.Cu")
		(net "UPI_CPU1_CPU0_P2P2_DN<15>")
	)
	(segment
		(start 344.466418 -281.267662)
		(end 344.457528 -281.272742)
		(width 0.0889)
		(layer "In11.Cu")
		(net "UPI_CPU1_CPU0_P2P2_DN<15>")
	)
	(segment
		(start 239.002316 -372.392702)
		(end 238.414052 -372.444264)
		(width 0.14732)
		(layer "In11.Cu")
		(net "UPI_CPU1_CPU0_P2P2_DN<15>")
	)
	(segment
		(start 100.189792 -285.985712)
		(end 100.198682 -285.980632)
		(width 0.0889)
		(layer "In11.Cu")
		(net "UPI_CPU1_CPU0_P2P2_DN<15>")
	)
	(segment
		(start 225.309938 -373.743982)
		(end 225.15068 -373.610378)
		(width 0.14732)
		(layer "In11.Cu")
		(net "UPI_CPU1_CPU0_P2P2_DN<15>")
	)
	(segment
		(start 260.629654 -368.810032)
		(end 260.42493 -368.77371)
		(width 0.14732)
		(layer "In11.Cu")
		(net "UPI_CPU1_CPU0_P2P2_DN<15>")
	)
	(segment
		(start 259.610098 -370.858288)
		(end 259.1816 -370.78285)
		(width 0.14732)
		(layer "In11.Cu")
		(net "UPI_CPU1_CPU0_P2P2_DN<15>")
	)
	(segment
		(start 341.459312 -289.60953)
		(end 341.459312 -290.176458)
		(width 0.0889)
		(layer "In11.Cu")
		(net "UPI_CPU1_CPU0_P2P2_DN<15>")
	)
	(segment
		(start 340.989666 -288.917126)
		(end 340.989666 -289.078416)
		(width 0.0889)
		(layer "In11.Cu")
		(net "UPI_CPU1_CPU0_P2P2_DN<15>")
	)
	(segment
		(start 232.235756 -373.135144)
		(end 232.076498 -373.00154)
		(width 0.14732)
		(layer "In11.Cu")
		(net "UPI_CPU1_CPU0_P2P2_DN<15>")
	)
	(segment
		(start 266.284456 -345.44127)
		(end 266.284456 -364.256574)
		(width 0.14732)
		(layer "In11.Cu")
		(net "UPI_CPU1_CPU0_P2P2_DN<15>")
	)
	(segment
		(start 243.778786 -372.120414)
		(end 243.619528 -371.98681)
		(width 0.14732)
		(layer "In11.Cu")
		(net "UPI_CPU1_CPU0_P2P2_DN<15>")
	)
	(segment
		(start 233.41711 -373.727218)
		(end 232.60304 -373.799354)
		(width 0.14732)
		(layer "In11.Cu")
		(net "UPI_CPU1_CPU0_P2P2_DN<15>")
	)
	(segment
		(start 340.884256 -290.751514)
		(end 340.884256 -290.811458)
		(width 0.0889)
		(layer "In11.Cu")
		(net "UPI_CPU1_CPU0_P2P2_DN<15>")
	)
	(segment
		(start 239.528858 -373.190516)
		(end 239.19561 -372.910354)
		(width 0.14732)
		(layer "In11.Cu")
		(net "UPI_CPU1_CPU0_P2P2_DN<15>")
	)
	(segment
		(start 242.897914 -372.19763)
		(end 242.931696 -372.582186)
		(width 0.14732)
		(layer "In11.Cu")
		(net "UPI_CPU1_CPU0_P2P2_DN<15>")
	)
	(segment
		(start 99.719384 -286.80029)
		(end 99.720146 -286.799782)
		(width 0.0889)
		(layer "In11.Cu")
		(net "UPI_CPU1_CPU0_P2P2_DN<15>")
	)
	(segment
		(start 243.812822 -372.504208)
		(end 243.778786 -372.120414)
		(width 0.14732)
		(layer "In11.Cu")
		(net "UPI_CPU1_CPU0_P2P2_DN<15>")
	)
	(segment
		(start 343.808812 -282.405836)
		(end 343.808812 -282.424378)
		(width 0.0889)
		(layer "In11.Cu")
		(net "UPI_CPU1_CPU0_P2P2_DN<15>")
	)
	(segment
		(start 224.190814 -374.52935)
		(end 223.358964 -374.60301)
		(width 0.14732)
		(layer "In11.Cu")
		(net "UPI_CPU1_CPU0_P2P2_DN<15>")
	)
	(segment
		(start 226.737672 -373.618252)
		(end 226.771454 -374.002808)
		(width 0.14732)
		(layer "In11.Cu")
		(net "UPI_CPU1_CPU0_P2P2_DN<15>")
	)
	(segment
		(start 101.59365 -283.54782)
		(end 101.608636 -283.53893)
		(width 0.0889)
		(layer "In11.Cu")
		(net "UPI_CPU1_CPU0_P2P2_DN<15>")
	)
	(segment
		(start 342.11514 -286.965644)
		(end 342.107774 -286.969962)
		(width 0.0889)
		(layer "In11.Cu")
		(net "UPI_CPU1_CPU0_P2P2_DN<15>")
	)
	(segment
		(start 257.460242 -370.849652)
		(end 248.765568 -372.382542)
		(width 0.14732)
		(layer "In11.Cu")
		(net "UPI_CPU1_CPU0_P2P2_DN<15>")
	)
	(segment
		(start 345.123262 -280.778204)
		(end 344.966798 -280.507186)
		(width 0.0889)
		(layer "In11.Cu")
		(net "UPI_CPU1_CPU0_P2P2_DN<15>")
	)
	(segment
		(start 260.280404 -370.38915)
		(end 259.610098 -370.858288)
		(width 0.14732)
		(layer "In11.Cu")
		(net "UPI_CPU1_CPU0_P2P2_DN<15>")
	)
	(segment
		(start 98.967798 -288.103056)
		(end 98.967798 -288.087562)
		(width 0.0889)
		(layer "In11.Cu")
		(net "UPI_CPU1_CPU0_P2P2_DN<15>")
	)
	(segment
		(start 95.276416 -302.129952)
		(end 96.438466 -300.563026)
		(width 0.14732)
		(layer "In11.Cu")
		(net "UPI_CPU1_CPU0_P2P2_DN<15>")
	)
	(segment
		(start 240.722658 -372.241318)
		(end 240.589308 -372.400576)
		(width 0.14732)
		(layer "In11.Cu")
		(net "UPI_CPU1_CPU0_P2P2_DN<15>")
	)
	(segment
		(start 229.767892 -373.204486)
		(end 229.179628 -373.256048)
		(width 0.14732)
		(layer "In11.Cu")
		(net "UPI_CPU1_CPU0_P2P2_DN<15>")
	)
	(segment
		(start 227.618544 -373.541036)
		(end 227.459286 -373.407432)
		(width 0.14732)
		(layer "In11.Cu")
		(net "UPI_CPU1_CPU0_P2P2_DN<15>")
	)
	(segment
		(start 305.960272 -328.87666)
		(end 304.39614 -330.44003)
		(width 0.14732)
		(layer "In11.Cu")
		(net "UPI_CPU1_CPU0_P2P2_DN<15>")
	)
	(segment
		(start 229.961186 -373.722138)
		(end 229.92715 -373.33809)
		(width 0.14732)
		(layer "In11.Cu")
		(net "UPI_CPU1_CPU0_P2P2_DN<15>")
	)
	(segment
		(start 222.842074 -373.813324)
		(end 222.25381 -373.864886)
		(width 0.14732)
		(layer "In11.Cu")
		(net "UPI_CPU1_CPU0_P2P2_DN<15>")
	)
	(segment
		(start 307.503322 -325.698358)
		(end 307.19268 -325.915782)
		(width 0.14732)
		(layer "In11.Cu")
		(net "UPI_CPU1_CPU0_P2P2_DN<15>")
	)
	(segment
		(start 242.651534 -372.915434)
		(end 241.837464 -372.98757)
		(width 0.14732)
		(layer "In11.Cu")
		(net "UPI_CPU1_CPU0_P2P2_DN<15>")
	)
	(segment
		(start 236.005878 -373.191024)
		(end 235.725716 -373.524272)
		(width 0.14732)
		(layer "In11.Cu")
		(net "UPI_CPU1_CPU0_P2P2_DN<15>")
	)
	(segment
		(start 233.697272 -373.39397)
		(end 233.41711 -373.727218)
		(width 0.14732)
		(layer "In11.Cu")
		(net "UPI_CPU1_CPU0_P2P2_DN<15>")
	)
	(segment
		(start 223.035368 -374.330976)
		(end 223.001332 -373.946928)
		(width 0.14732)
		(layer "In11.Cu")
		(net "UPI_CPU1_CPU0_P2P2_DN<15>")
	)
	(segment
		(start 234.385104 -372.798594)
		(end 233.79684 -372.850156)
		(width 0.14732)
		(layer "In11.Cu")
		(net "UPI_CPU1_CPU0_P2P2_DN<15>")
	)
	(segment
		(start 306.792122 -326.488044)
		(end 306.509166 -328.09307)
		(width 0.14732)
		(layer "In11.Cu")
		(net "UPI_CPU1_CPU0_P2P2_DN<15>")
	)
	(segment
		(start 278.798782 -332.926944)
		(end 266.284456 -345.44127)
		(width 0.14732)
		(layer "In11.Cu")
		(net "UPI_CPU1_CPU0_P2P2_DN<15>")
	)
	(segment
		(start 341.177118 -288.592768)
		(end 341.168228 -288.597848)
		(width 0.0889)
		(layer "In11.Cu")
		(net "UPI_CPU1_CPU0_P2P2_DN<15>")
	)
	(segment
		(start 232.60304 -373.799354)
		(end 232.269792 -373.519192)
		(width 0.14732)
		(layer "In11.Cu")
		(net "UPI_CPU1_CPU0_P2P2_DN<15>")
	)
	(segment
		(start 97.985834 -296.827702)
		(end 97.985834 -290.405566)
		(width 0.14732)
		(layer "In11.Cu")
		(net "UPI_CPU1_CPU0_P2P2_DN<15>")
	)
	(segment
		(start 306.509166 -328.09307)
		(end 305.960272 -328.87666)
		(width 0.14732)
		(layer "In11.Cu")
		(net "UPI_CPU1_CPU0_P2P2_DN<15>")
	)
	(segment
		(start 232.076498 -373.00154)
		(end 231.488234 -373.053102)
		(width 0.14732)
		(layer "In11.Cu")
		(net "UPI_CPU1_CPU0_P2P2_DN<15>")
	)
	(segment
		(start 236.887004 -373.1133)
		(end 236.852968 -372.729252)
		(width 0.14732)
		(layer "In11.Cu")
		(net "UPI_CPU1_CPU0_P2P2_DN<15>")
	)
	(segment
		(start 335.354676 -296.027856)
		(end 333.560674 -301.940976)
		(width 0.14732)
		(layer "In11.Cu")
		(net "UPI_CPU1_CPU0_P2P2_DN<15>")
	)
	(segment
		(start 241.47018 -372.32336)
		(end 241.310922 -372.189756)
		(width 0.14732)
		(layer "In11.Cu")
		(net "UPI_CPU1_CPU0_P2P2_DN<15>")
	)
	(segment
		(start 222.12046 -374.024144)
		(end 222.154242 -374.4087)
		(width 0.14732)
		(layer "In11.Cu")
		(net "UPI_CPU1_CPU0_P2P2_DN<15>")
	)
	(segment
		(start 238.034322 -373.321326)
		(end 237.220252 -373.393462)
		(width 0.14732)
		(layer "In11.Cu")
		(net "UPI_CPU1_CPU0_P2P2_DN<15>")
	)
	(segment
		(start 223.358964 -374.60301)
		(end 223.035368 -374.330976)
		(width 0.14732)
		(layer "In11.Cu")
		(net "UPI_CPU1_CPU0_P2P2_DN<15>")
	)
	(segment
		(start 240.342928 -373.11838)
		(end 239.528858 -373.190516)
		(width 0.14732)
		(layer "In11.Cu")
		(net "UPI_CPU1_CPU0_P2P2_DN<15>")
	)
	(segment
		(start 261.840218 -367.782856)
		(end 261.803896 -367.987834)
		(width 0.14732)
		(layer "In11.Cu")
		(net "UPI_CPU1_CPU0_P2P2_DN<15>")
	)
	(segment
		(start 226.871022 -373.458994)
		(end 226.737672 -373.618252)
		(width 0.14732)
		(layer "In11.Cu")
		(net "UPI_CPU1_CPU0_P2P2_DN<15>")
	)
	(segment
		(start 234.578398 -373.316246)
		(end 234.544362 -372.932198)
		(width 0.14732)
		(layer "In11.Cu")
		(net "UPI_CPU1_CPU0_P2P2_DN<15>")
	)
	(segment
		(start 97.985834 -290.405566)
		(end 97.985834 -290.383468)
		(width 0.0889)
		(layer "In11.Cu")
		(net "UPI_CPU1_CPU0_P2P2_DN<15>")
	)
	(segment
		(start 238.414052 -372.444264)
		(end 238.280702 -372.603522)
		(width 0.14732)
		(layer "In11.Cu")
		(net "UPI_CPU1_CPU0_P2P2_DN<15>")
	)
	(segment
		(start 222.25381 -373.864886)
		(end 222.12046 -374.024144)
		(width 0.14732)
		(layer "In11.Cu")
		(net "UPI_CPU1_CPU0_P2P2_DN<15>")
	)
	(segment
		(start 73.0885 -363.749082)
		(end 68.944998 -353.7458)
		(width 0.14732)
		(layer "In11.Cu")
		(net "UPI_CPU1_CPU0_P2P2_DN<15>")
	)
	(segment
		(start 260.355842 -369.960652)
		(end 260.280404 -370.38915)
		(width 0.14732)
		(layer "In11.Cu")
		(net "UPI_CPU1_CPU0_P2P2_DN<15>")
	)
	(segment
		(start 304.39614 -330.44003)
		(end 284.802834 -330.44003)
		(width 0.14732)
		(layer "In11.Cu")
		(net "UPI_CPU1_CPU0_P2P2_DN<15>")
	)
	(segment
		(start 236.852968 -372.729252)
		(end 236.69371 -372.595648)
		(width 0.14732)
		(layer "In11.Cu")
		(net "UPI_CPU1_CPU0_P2P2_DN<15>")
	)
	(segment
		(start 222.08109 -374.495822)
		(end 222.080836 -374.495822)
		(width 0.14732)
		(layer "In11.Cu")
		(net "UPI_CPU1_CPU0_P2P2_DN<15>")
	)
	(segment
		(start 341.647018 -287.778698)
		(end 341.638128 -287.783778)
		(width 0.0889)
		(layer "In11.Cu")
		(net "UPI_CPU1_CPU0_P2P2_DN<15>")
	)
	(segment
		(start 225.15068 -373.610378)
		(end 224.562416 -373.66194)
		(width 0.14732)
		(layer "In11.Cu")
		(net "UPI_CPU1_CPU0_P2P2_DN<15>")
	)
	(segment
		(start 229.92715 -373.33809)
		(end 229.767892 -373.204486)
		(width 0.14732)
		(layer "In11.Cu")
		(net "UPI_CPU1_CPU0_P2P2_DN<15>")
	)
	(segment
		(start 241.504216 -372.707408)
		(end 241.47018 -372.32336)
		(width 0.14732)
		(layer "In11.Cu")
		(net "UPI_CPU1_CPU0_P2P2_DN<15>")
	)
	(segment
		(start 243.619528 -371.98681)
		(end 243.031264 -372.038372)
		(width 0.14732)
		(layer "In11.Cu")
		(net "UPI_CPU1_CPU0_P2P2_DN<15>")
	)
	(segment
		(start 241.837464 -372.98757)
		(end 241.504216 -372.707408)
		(width 0.14732)
		(layer "In11.Cu")
		(net "UPI_CPU1_CPU0_P2P2_DN<15>")
	)
	(segment
		(start 238.314484 -372.988078)
		(end 238.034322 -373.321326)
		(width 0.14732)
		(layer "In11.Cu")
		(net "UPI_CPU1_CPU0_P2P2_DN<15>")
	)
	(segment
		(start 221.87408 -374.742202)
		(end 212.361526 -375.5771)
		(width 0.14732)
		(layer "In11.Cu")
		(net "UPI_CPU1_CPU0_P2P2_DN<15>")
	)
	(arc
		(start 100.377244 -285.661354)
		(mid 100.451235 -285.381788)
		(end 100.65385 -285.175452)
		(width 0.0889)
		(layer "In11.Cu")
		(net "UPI_CPU1_CPU0_P2P2_DN<15>")
	)
	(arc
		(start 343.987374 -282.086558)
		(mid 343.85646 -282.222918)
		(end 343.808812 -282.405836)
		(width 0.0889)
		(layer "In11.Cu")
		(net "UPI_CPU1_CPU0_P2P2_DN<15>")
	)
	(arc
		(start 342.399366 -284.847538)
		(mid 342.325375 -285.127104)
		(end 342.12276 -285.33344)
		(width 0.0889)
		(layer "In11.Cu")
		(net "UPI_CPU1_CPU0_P2P2_DN<15>")
	)
	(arc
		(start 98.967798 -288.087562)
		(mid 99.047168 -287.813828)
		(end 99.249992 -287.613598)
		(width 0.0889)
		(layer "In11.Cu")
		(net "UPI_CPU1_CPU0_P2P2_DN<15>")
	)
	(arc
		(start 341.168228 -288.597848)
		(mid 341.037314 -288.734208)
		(end 340.989666 -288.917126)
		(width 0.0889)
		(layer "In11.Cu")
		(net "UPI_CPU1_CPU0_P2P2_DN<15>")
	)
	(arc
		(start 100.198682 -285.980632)
		(mid 100.329596 -285.844272)
		(end 100.377244 -285.661354)
		(width 0.0889)
		(layer "In11.Cu")
		(net "UPI_CPU1_CPU0_P2P2_DN<15>")
	)
	(arc
		(start 343.808812 -282.424378)
		(mid 343.72865 -282.696567)
		(end 343.526364 -282.895548)
		(width 0.0889)
		(layer "In11.Cu")
		(net "UPI_CPU1_CPU0_P2P2_DN<15>")
	)
	(arc
		(start 100.668836 -285.166816)
		(mid 100.79975 -285.030456)
		(end 100.847398 -284.847538)
		(width 0.0889)
		(layer "In11.Cu")
		(net "UPI_CPU1_CPU0_P2P2_DN<15>")
	)
	(arc
		(start 98.027744 -289.611054)
		(mid 98.139027 -289.417463)
		(end 98.313494 -289.27806)
		(width 0.0889)
		(layer "In11.Cu")
		(net "UPI_CPU1_CPU0_P2P2_DN<15>")
	)
	(arc
		(start 341.173816 -289.277806)
		(mid 341.347948 -289.416653)
		(end 341.459312 -289.60953)
		(width 0.0889)
		(layer "In11.Cu")
		(net "UPI_CPU1_CPU0_P2P2_DN<15>")
	)
	(arc
		(start 100.847398 -284.832044)
		(mid 100.926768 -284.55831)
		(end 101.129592 -284.35808)
		(width 0.0889)
		(layer "In11.Cu")
		(net "UPI_CPU1_CPU0_P2P2_DN<15>")
	)
	(arc
		(start 343.517474 -282.900628)
		(mid 343.38656 -283.036988)
		(end 343.338912 -283.219906)
		(width 0.0889)
		(layer "In11.Cu")
		(net "UPI_CPU1_CPU0_P2P2_DN<15>")
	)
	(arc
		(start 342.107774 -286.969962)
		(mid 341.97686 -287.106322)
		(end 341.929212 -287.28924)
		(width 0.0889)
		(layer "In11.Cu")
		(net "UPI_CPU1_CPU0_P2P2_DN<15>")
	)
	(arc
		(start 99.907344 -286.456882)
		(mid 99.987506 -286.184693)
		(end 100.189792 -285.985712)
		(width 0.0889)
		(layer "In11.Cu")
		(net "UPI_CPU1_CPU0_P2P2_DN<15>")
	)
	(arc
		(start 98.313494 -289.277806)
		(mid 98.42289 -289.193709)
		(end 98.497898 -289.077908)
		(width 0.0889)
		(layer "In11.Cu")
		(net "UPI_CPU1_CPU0_P2P2_DN<15>")
	)
	(arc
		(start 344.278966 -281.59202)
		(mid 344.204975 -281.871586)
		(end 344.00236 -282.077922)
		(width 0.0889)
		(layer "In11.Cu")
		(net "UPI_CPU1_CPU0_P2P2_DN<15>")
	)
	(arc
		(start 340.989666 -289.078416)
		(mid 341.064671 -289.193875)
		(end 341.173816 -289.277806)
		(width 0.0889)
		(layer "In11.Cu")
		(net "UPI_CPU1_CPU0_P2P2_DN<15>")
	)
	(arc
		(start 101.608636 -283.539184)
		(mid 101.724375 -283.42736)
		(end 101.782626 -283.27731)
		(width 0.0889)
		(layer "In11.Cu")
		(net "UPI_CPU1_CPU0_P2P2_DN<15>")
	)
	(arc
		(start 341.459566 -288.121598)
		(mid 341.379404 -288.393787)
		(end 341.177118 -288.592768)
		(width 0.0889)
		(layer "In11.Cu")
		(net "UPI_CPU1_CPU0_P2P2_DN<15>")
	)
	(arc
		(start 341.929212 -287.304734)
		(mid 341.849842 -287.578468)
		(end 341.647018 -287.778698)
		(width 0.0889)
		(layer "In11.Cu")
		(net "UPI_CPU1_CPU0_P2P2_DN<15>")
	)
	(arc
		(start 99.258882 -287.608518)
		(mid 99.389796 -287.472158)
		(end 99.437444 -287.28924)
		(width 0.0889)
		(layer "In11.Cu")
		(net "UPI_CPU1_CPU0_P2P2_DN<15>")
	)
	(arc
		(start 343.338912 -283.229812)
		(mid 343.260801 -283.506761)
		(end 343.056464 -283.709364)
		(width 0.0889)
		(layer "In11.Cu")
		(net "UPI_CPU1_CPU0_P2P2_DN<15>")
	)
	(arc
		(start 342.577928 -284.52826)
		(mid 342.447014 -284.66462)
		(end 342.399366 -284.847538)
		(width 0.0889)
		(layer "In11.Cu")
		(net "UPI_CPU1_CPU0_P2P2_DN<15>")
	)
	(arc
		(start 99.437444 -287.28924)
		(mid 99.511435 -287.009674)
		(end 99.71405 -286.803338)
		(width 0.0889)
		(layer "In11.Cu")
		(net "UPI_CPU1_CPU0_P2P2_DN<15>")
	)
	(arc
		(start 344.88882 -280.486358)
		(mid 344.787499 -280.612479)
		(end 344.748866 -280.769568)
		(width 0.0889)
		(layer "In11.Cu")
		(net "UPI_CPU1_CPU0_P2P2_DN<15>")
	)
	(arc
		(start 98.789236 -288.422334)
		(mid 98.92015 -288.285974)
		(end 98.967798 -288.103056)
		(width 0.0889)
		(layer "In11.Cu")
		(net "UPI_CPU1_CPU0_P2P2_DN<15>")
	)
	(arc
		(start 344.457528 -281.272742)
		(mid 344.326614 -281.409102)
		(end 344.278966 -281.59202)
		(width 0.0889)
		(layer "In11.Cu")
		(net "UPI_CPU1_CPU0_P2P2_DN<15>")
	)
	(arc
		(start 342.869012 -284.049216)
		(mid 342.789642 -284.32295)
		(end 342.586818 -284.52318)
		(width 0.0889)
		(layer "In11.Cu")
		(net "UPI_CPU1_CPU0_P2P2_DN<15>")
	)
	(arc
		(start 101.138482 -284.353)
		(mid 101.269396 -284.21664)
		(end 101.317044 -284.033722)
		(width 0.0889)
		(layer "In11.Cu")
		(net "UPI_CPU1_CPU0_P2P2_DN<15>")
	)
	(arc
		(start 341.638128 -287.783778)
		(mid 341.507214 -287.920138)
		(end 341.459566 -288.103056)
		(width 0.0889)
		(layer "In11.Cu")
		(net "UPI_CPU1_CPU0_P2P2_DN<15>")
	)
	(arc
		(start 101.317044 -284.033722)
		(mid 101.391035 -283.754156)
		(end 101.59365 -283.54782)
		(width 0.0889)
		(layer "In11.Cu")
		(net "UPI_CPU1_CPU0_P2P2_DN<15>")
	)
	(arc
		(start 342.107774 -285.342076)
		(mid 341.929056 -285.661354)
		(end 342.107774 -285.980632)
		(width 0.0889)
		(layer "In11.Cu")
		(net "UPI_CPU1_CPU0_P2P2_DN<15>")
	)
	(arc
		(start 344.748866 -280.78811)
		(mid 344.670755 -281.065059)
		(end 344.466418 -281.267662)
		(width 0.0889)
		(layer "In11.Cu")
		(net "UPI_CPU1_CPU0_P2P2_DN<15>")
	)
	(arc
		(start 342.116664 -285.985712)
		(mid 342.320145 -286.186516)
		(end 342.399366 -286.4612)
		(width 0.0889)
		(layer "In11.Cu")
		(net "UPI_CPU1_CPU0_P2P2_DN<15>")
	)
	(arc
		(start 343.047574 -283.714444)
		(mid 342.91666 -283.850804)
		(end 342.869012 -284.033722)
		(width 0.0889)
		(layer "In11.Cu")
		(net "UPI_CPU1_CPU0_P2P2_DN<15>")
	)
	(arc
		(start 99.720146 -286.799782)
		(mid 99.855079 -286.666428)
		(end 99.907344 -286.48406)
		(width 0.0889)
		(layer "In11.Cu")
		(net "UPI_CPU1_CPU0_P2P2_DN<15>")
	)
	(arc
		(start 98.497898 -288.898584)
		(mid 98.57806 -288.626395)
		(end 98.780346 -288.427414)
		(width 0.0889)
		(layer "In11.Cu")
		(net "UPI_CPU1_CPU0_P2P2_DN<15>")
	)
	(arc
		(start 342.399366 -286.475424)
		(mid 342.325375 -286.75499)
		(end 342.12276 -286.961326)
		(width 0.0889)
		(layer "In11.Cu")
		(net "UPI_CPU1_CPU0_P2P2_DN<15>")
	)
	(segment
		(start 344.653362 -283.219652)
		(end 344.653616 -283.219906)
		(width 0.13208)
		(layer "F.Cu")
		(net "UPI_CPU1_CPU0_P2P2_DN<14>")
	)
	(segment
		(start 100.942648 -280.77795)
		(end 100.942394 -280.778204)
		(width 0.13208)
		(layer "F.Cu")
		(net "UPI_CPU1_CPU0_P2P2_DN<14>")
	)
	(segment
		(start 100.942648 -280.242264)
		(end 100.942648 -280.77795)
		(width 0.13208)
		(layer "F.Cu")
		(net "UPI_CPU1_CPU0_P2P2_DN<14>")
	)
	(segment
		(start 344.653362 -282.683966)
		(end 344.653362 -283.219652)
		(width 0.13208)
		(layer "F.Cu")
		(net "UPI_CPU1_CPU0_P2P2_DN<14>")
	)
	(segment
		(start 184.216802 -377.664218)
		(end 184.572402 -377.914662)
		(width 0.14732)
		(layer "In11.Cu")
		(net "UPI_CPU1_CPU0_P2P2_DN<14>")
	)
	(segment
		(start 343.056464 -286.964882)
		(end 343.060274 -286.962596)
		(width 0.0889)
		(layer "In11.Cu")
		(net "UPI_CPU1_CPU0_P2P2_DN<14>")
	)
	(segment
		(start 190.249302 -376.074178)
		(end 190.8302 -375.972832)
		(width 0.14732)
		(layer "In11.Cu")
		(net "UPI_CPU1_CPU0_P2P2_DN<14>")
	)
	(segment
		(start 193.113406 -375.575322)
		(end 193.283586 -375.69521)
		(width 0.14732)
		(layer "In11.Cu")
		(net "UPI_CPU1_CPU0_P2P2_DN<14>")
	)
	(segment
		(start 68.742306 -328.349102)
		(end 68.101718 -334.855312)
		(width 0.14732)
		(layer "In11.Cu")
		(net "UPI_CPU1_CPU0_P2P2_DN<14>")
	)
	(segment
		(start 179.65039 -378.459238)
		(end 180.00599 -378.709682)
		(width 0.14732)
		(layer "In11.Cu")
		(net "UPI_CPU1_CPU0_P2P2_DN<14>")
	)
	(segment
		(start 343.060274 -286.962596)
		(end 343.068656 -286.95777)
		(width 0.0889)
		(layer "In11.Cu")
		(net "UPI_CPU1_CPU0_P2P2_DN<14>")
	)
	(segment
		(start 341.02929 -292.59403)
		(end 341.15756 -292.284404)
		(width 0.14732)
		(layer "In11.Cu")
		(net "UPI_CPU1_CPU0_P2P2_DN<14>")
	)
	(segment
		(start 181.697376 -377.562872)
		(end 181.867556 -377.68276)
		(width 0.14732)
		(layer "In11.Cu")
		(net "UPI_CPU1_CPU0_P2P2_DN<14>")
	)
	(segment
		(start 311.456832 -324.367652)
		(end 311.456832 -324.367398)
		(width 0.14732)
		(layer "In11.Cu")
		(net "UPI_CPU1_CPU0_P2P2_DN<14>")
	)
	(segment
		(start 174.146972 -379.026928)
		(end 174.26686 -378.856748)
		(width 0.14732)
		(layer "In11.Cu")
		(net "UPI_CPU1_CPU0_P2P2_DN<14>")
	)
	(segment
		(start 179.58435 -378.08027)
		(end 179.65039 -378.459238)
		(width 0.14732)
		(layer "In11.Cu")
		(net "UPI_CPU1_CPU0_P2P2_DN<14>")
	)
	(segment
		(start 176.550066 -378.459238)
		(end 177.130964 -378.357892)
		(width 0.14732)
		(layer "In11.Cu")
		(net "UPI_CPU1_CPU0_P2P2_DN<14>")
	)
	(segment
		(start 313.154822 -323.172836)
		(end 314.205366 -322.471034)
		(width 0.14732)
		(layer "In11.Cu")
		(net "UPI_CPU1_CPU0_P2P2_DN<14>")
	)
	(segment
		(start 305.116738 -331.26807)
		(end 306.222146 -330.162662)
		(width 0.14732)
		(layer "In11.Cu")
		(net "UPI_CPU1_CPU0_P2P2_DN<14>")
	)
	(segment
		(start 194.761866 -375.828052)
		(end 194.695826 -375.449338)
		(width 0.14732)
		(layer "In11.Cu")
		(net "UPI_CPU1_CPU0_P2P2_DN<14>")
	)
	(segment
		(start 181.933596 -378.061728)
		(end 182.289196 -378.312172)
		(width 0.14732)
		(layer "In11.Cu")
		(net "UPI_CPU1_CPU0_P2P2_DN<14>")
	)
	(segment
		(start 192.41262 -375.846848)
		(end 192.532508 -375.676668)
		(width 0.14732)
		(layer "In11.Cu")
		(net "UPI_CPU1_CPU0_P2P2_DN<14>")
	)
	(segment
		(start 194.511168 -376.18416)
		(end 194.761866 -375.828052)
		(width 0.14732)
		(layer "In11.Cu")
		(net "UPI_CPU1_CPU0_P2P2_DN<14>")
	)
	(segment
		(start 342.399366 -288.121598)
		(end 342.399366 -288.103056)
		(width 0.0889)
		(layer "In11.Cu")
		(net "UPI_CPU1_CPU0_P2P2_DN<14>")
	)
	(segment
		(start 260.253226 -372.26875)
		(end 267.26134 -365.260382)
		(width 0.14732)
		(layer "In11.Cu")
		(net "UPI_CPU1_CPU0_P2P2_DN<14>")
	)
	(segment
		(start 185.563002 -377.039378)
		(end 185.68289 -376.869198)
		(width 0.14732)
		(layer "In11.Cu")
		(net "UPI_CPU1_CPU0_P2P2_DN<14>")
	)
	(segment
		(start 183.399684 -377.266708)
		(end 183.980582 -377.165362)
		(width 0.14732)
		(layer "In11.Cu")
		(net "UPI_CPU1_CPU0_P2P2_DN<14>")
	)
	(segment
		(start 197.045072 -375.430542)
		(end 196.979032 -375.051574)
		(width 0.14732)
		(layer "In11.Cu")
		(net "UPI_CPU1_CPU0_P2P2_DN<14>")
	)
	(segment
		(start 190.195454 -376.623072)
		(end 190.129414 -376.244358)
		(width 0.14732)
		(layer "In11.Cu")
		(net "UPI_CPU1_CPU0_P2P2_DN<14>")
	)
	(segment
		(start 341.15756 -292.284404)
		(end 341.15756 -291.605462)
		(width 0.14732)
		(layer "In11.Cu")
		(net "UPI_CPU1_CPU0_P2P2_DN<14>")
	)
	(segment
		(start 97.046288 -291.474398)
		(end 97.046288 -291.496496)
		(width 0.0889)
		(layer "In11.Cu")
		(net "UPI_CPU1_CPU0_P2P2_DN<14>")
	)
	(segment
		(start 94.659196 -301.561754)
		(end 79.33055 -314.141612)
		(width 0.14732)
		(layer "In11.Cu")
		(net "UPI_CPU1_CPU0_P2P2_DN<14>")
	)
	(segment
		(start 342.399112 -290.091622)
		(end 342.399112 -289.60953)
		(width 0.0889)
		(layer "In11.Cu")
		(net "UPI_CPU1_CPU0_P2P2_DN<14>")
	)
	(segment
		(start 125.875796 -381.03683)
		(end 161.735516 -381.03683)
		(width 0.14732)
		(layer "In11.Cu")
		(net "UPI_CPU1_CPU0_P2P2_DN<14>")
	)
	(segment
		(start 101.098858 -281.049222)
		(end 101.074728 -281.138376)
		(width 0.0889)
		(layer "In11.Cu")
		(net "UPI_CPU1_CPU0_P2P2_DN<14>")
	)
	(segment
		(start 343.517728 -284.52826)
		(end 343.526618 -284.52318)
		(width 0.0889)
		(layer "In11.Cu")
		(net "UPI_CPU1_CPU0_P2P2_DN<14>")
	)
	(segment
		(start 307.739542 -326.973438)
		(end 308.374034 -326.066912)
		(width 0.14732)
		(layer "In11.Cu")
		(net "UPI_CPU1_CPU0_P2P2_DN<14>")
	)
	(segment
		(start 100.377244 -284.023816)
		(end 100.377244 -284.033722)
		(width 0.0889)
		(layer "In11.Cu")
		(net "UPI_CPU1_CPU0_P2P2_DN<14>")
	)
	(segment
		(start 183.980582 -377.165362)
		(end 184.150762 -377.28525)
		(width 0.14732)
		(layer "In11.Cu")
		(net "UPI_CPU1_CPU0_P2P2_DN<14>")
	)
	(segment
		(start 161.735516 -381.03683)
		(end 172.564552 -379.152912)
		(width 0.14732)
		(layer "In11.Cu")
		(net "UPI_CPU1_CPU0_P2P2_DN<14>")
	)
	(segment
		(start 195.396612 -375.177812)
		(end 195.566792 -375.2977)
		(width 0.14732)
		(layer "In11.Cu")
		(net "UPI_CPU1_CPU0_P2P2_DN<14>")
	)
	(segment
		(start 181.116478 -377.664218)
		(end 181.697376 -377.562872)
		(width 0.14732)
		(layer "In11.Cu")
		(net "UPI_CPU1_CPU0_P2P2_DN<14>")
	)
	(segment
		(start 96.909636 -288.422334)
		(end 96.900746 -288.427414)
		(width 0.0889)
		(layer "In11.Cu")
		(net "UPI_CPU1_CPU0_P2P2_DN<14>")
	)
	(segment
		(start 184.150762 -377.28525)
		(end 184.216802 -377.664218)
		(width 0.14732)
		(layer "In11.Cu")
		(net "UPI_CPU1_CPU0_P2P2_DN<14>")
	)
	(segment
		(start 97.087944 -289.64509)
		(end 97.088198 -289.645598)
		(width 0.0889)
		(layer "In11.Cu")
		(net "UPI_CPU1_CPU0_P2P2_DN<14>")
	)
	(segment
		(start 190.129414 -376.244358)
		(end 190.249302 -376.074178)
		(width 0.14732)
		(layer "In11.Cu")
		(net "UPI_CPU1_CPU0_P2P2_DN<14>")
	)
	(segment
		(start 69.555106 -325.412354)
		(end 68.742306 -328.349102)
		(width 0.14732)
		(layer "In11.Cu")
		(net "UPI_CPU1_CPU0_P2P2_DN<14>")
	)
	(segment
		(start 187.66155 -377.37669)
		(end 187.912248 -377.020582)
		(width 0.14732)
		(layer "In11.Cu")
		(net "UPI_CPU1_CPU0_P2P2_DN<14>")
	)
	(segment
		(start 189.138814 -377.119642)
		(end 189.944756 -376.97918)
		(width 0.14732)
		(layer "In11.Cu")
		(net "UPI_CPU1_CPU0_P2P2_DN<14>")
	)
	(segment
		(start 186.433968 -376.88774)
		(end 186.500008 -377.266708)
		(width 0.14732)
		(layer "In11.Cu")
		(net "UPI_CPU1_CPU0_P2P2_DN<14>")
	)
	(segment
		(start 99.907598 -284.832044)
		(end 99.907598 -284.847538)
		(width 0.0889)
		(layer "In11.Cu")
		(net "UPI_CPU1_CPU0_P2P2_DN<14>")
	)
	(segment
		(start 180.811932 -378.56922)
		(end 181.06263 -378.213112)
		(width 0.14732)
		(layer "In11.Cu")
		(net "UPI_CPU1_CPU0_P2P2_DN<14>")
	)
	(segment
		(start 177.722784 -379.107192)
		(end 178.528726 -378.96673)
		(width 0.14732)
		(layer "In11.Cu")
		(net "UPI_CPU1_CPU0_P2P2_DN<14>")
	)
	(segment
		(start 343.056464 -285.985712)
		(end 343.055702 -285.985204)
		(width 0.0889)
		(layer "In11.Cu")
		(net "UPI_CPU1_CPU0_P2P2_DN<14>")
	)
	(segment
		(start 175.017938 -378.87529)
		(end 175.083978 -379.254258)
		(width 0.14732)
		(layer "In11.Cu")
		(net "UPI_CPU1_CPU0_P2P2_DN<14>")
	)
	(segment
		(start 307.499766 -328.332592)
		(end 307.739542 -326.973438)
		(width 0.14732)
		(layer "In11.Cu")
		(net "UPI_CPU1_CPU0_P2P2_DN<14>")
	)
	(segment
		(start 194.815714 -375.279158)
		(end 195.396612 -375.177812)
		(width 0.14732)
		(layer "In11.Cu")
		(net "UPI_CPU1_CPU0_P2P2_DN<14>")
	)
	(segment
		(start 186.500008 -377.266708)
		(end 186.855608 -377.517152)
		(width 0.14732)
		(layer "In11.Cu")
		(net "UPI_CPU1_CPU0_P2P2_DN<14>")
	)
	(segment
		(start 177.367184 -378.856748)
		(end 177.722784 -379.107192)
		(width 0.14732)
		(layer "In11.Cu")
		(net "UPI_CPU1_CPU0_P2P2_DN<14>")
	)
	(segment
		(start 98.027744 -286.456882)
		(end 98.027744 -286.48406)
		(width 0.0889)
		(layer "In11.Cu")
		(net "UPI_CPU1_CPU0_P2P2_DN<14>")
	)
	(segment
		(start 341.281766 -291.481256)
		(end 341.281766 -291.421312)
		(width 0.0889)
		(layer "In11.Cu")
		(net "UPI_CPU1_CPU0_P2P2_DN<14>")
	)
	(segment
		(start 194.695826 -375.449338)
		(end 194.815714 -375.279158)
		(width 0.14732)
		(layer "In11.Cu")
		(net "UPI_CPU1_CPU0_P2P2_DN<14>")
	)
	(segment
		(start 172.564552 -379.152912)
		(end 172.734732 -379.2728)
		(width 0.14732)
		(layer "In11.Cu")
		(net "UPI_CPU1_CPU0_P2P2_DN<14>")
	)
	(segment
		(start 79.33055 -314.141612)
		(end 70.896226 -322.575936)
		(width 0.14732)
		(layer "In11.Cu")
		(net "UPI_CPU1_CPU0_P2P2_DN<14>")
	)
	(segment
		(start 177.301144 -378.47778)
		(end 177.367184 -378.856748)
		(width 0.14732)
		(layer "In11.Cu")
		(net "UPI_CPU1_CPU0_P2P2_DN<14>")
	)
	(segment
		(start 100.942394 -280.778204)
		(end 101.098858 -281.049222)
		(width 0.0889)
		(layer "In11.Cu")
		(net "UPI_CPU1_CPU0_P2P2_DN<14>")
	)
	(segment
		(start 184.572402 -377.914662)
		(end 185.378344 -377.7742)
		(width 0.14732)
		(layer "In11.Cu")
		(net "UPI_CPU1_CPU0_P2P2_DN<14>")
	)
	(segment
		(start 343.339166 -286.475424)
		(end 343.339166 -286.467804)
		(width 0.0889)
		(layer "In11.Cu")
		(net "UPI_CPU1_CPU0_P2P2_DN<14>")
	)
	(segment
		(start 70.896226 -322.575936)
		(end 69.555106 -325.412354)
		(width 0.14732)
		(layer "In11.Cu")
		(net "UPI_CPU1_CPU0_P2P2_DN<14>")
	)
	(segment
		(start 176.496218 -379.008132)
		(end 176.430178 -378.629418)
		(width 0.14732)
		(layer "In11.Cu")
		(net "UPI_CPU1_CPU0_P2P2_DN<14>")
	)
	(segment
		(start 190.8302 -375.972832)
		(end 191.00038 -376.09272)
		(width 0.14732)
		(layer "In11.Cu")
		(net "UPI_CPU1_CPU0_P2P2_DN<14>")
	)
	(segment
		(start 97.088198 -289.645598)
		(end 97.088198 -291.432488)
		(width 0.0889)
		(layer "In11.Cu")
		(net "UPI_CPU1_CPU0_P2P2_DN<14>")
	)
	(segment
		(start 193.283586 -375.69521)
		(end 193.349626 -376.074178)
		(width 0.14732)
		(layer "In11.Cu")
		(net "UPI_CPU1_CPU0_P2P2_DN<14>")
	)
	(segment
		(start 314.205366 -322.471034)
		(end 334.296766 -302.379888)
		(width 0.14732)
		(layer "In11.Cu")
		(net "UPI_CPU1_CPU0_P2P2_DN<14>")
	)
	(segment
		(start 344.497152 -282.948888)
		(end 344.653616 -283.219906)
		(width 0.0889)
		(layer "In11.Cu")
		(net "UPI_CPU1_CPU0_P2P2_DN<14>")
	)
	(segment
		(start 174.26686 -378.856748)
		(end 174.847758 -378.755402)
		(width 0.14732)
		(layer "In11.Cu")
		(net "UPI_CPU1_CPU0_P2P2_DN<14>")
	)
	(segment
		(start 68.101718 -353.894644)
		(end 72.398636 -364.257082)
		(width 0.14732)
		(layer "In11.Cu")
		(net "UPI_CPU1_CPU0_P2P2_DN<14>")
	)
	(segment
		(start 341.929466 -289.078416)
		(end 341.929466 -288.917126)
		(width 0.0889)
		(layer "In11.Cu")
		(net "UPI_CPU1_CPU0_P2P2_DN<14>")
	)
	(segment
		(start 97.088198 -288.087562)
		(end 97.088198 -288.103056)
		(width 0.0889)
		(layer "In11.Cu")
		(net "UPI_CPU1_CPU0_P2P2_DN<14>")
	)
	(segment
		(start 100.660454 -283.543756)
		(end 100.659692 -283.544264)
		(width 0.0889)
		(layer "In11.Cu")
		(net "UPI_CPU1_CPU0_P2P2_DN<14>")
	)
	(segment
		(start 183.095138 -378.17171)
		(end 183.345836 -377.815602)
		(width 0.14732)
		(layer "In11.Cu")
		(net "UPI_CPU1_CPU0_P2P2_DN<14>")
	)
	(segment
		(start 199.505824 -374.463818)
		(end 205.54696 -375.397522)
		(width 0.14732)
		(layer "In11.Cu")
		(net "UPI_CPU1_CPU0_P2P2_DN<14>")
	)
	(segment
		(start 176.24552 -379.36424)
		(end 176.496218 -379.008132)
		(width 0.14732)
		(layer "In11.Cu")
		(net "UPI_CPU1_CPU0_P2P2_DN<14>")
	)
	(segment
		(start 188.717174 -376.49023)
		(end 188.783214 -376.869198)
		(width 0.14732)
		(layer "In11.Cu")
		(net "UPI_CPU1_CPU0_P2P2_DN<14>")
	)
	(segment
		(start 97.046288 -296.926254)
		(end 95.717106 -300.135544)
		(width 0.14732)
		(layer "In11.Cu")
		(net "UPI_CPU1_CPU0_P2P2_DN<14>")
	)
	(segment
		(start 310.471566 -324.59803)
		(end 311.341516 -324.445122)
		(width 0.14732)
		(layer "In11.Cu")
		(net "UPI_CPU1_CPU0_P2P2_DN<14>")
	)
	(segment
		(start 279.220676 -333.676244)
		(end 285.034482 -331.26807)
		(width 0.14732)
		(layer "In11.Cu")
		(net "UPI_CPU1_CPU0_P2P2_DN<14>")
	)
	(segment
		(start 96.903794 -289.446462)
		(end 96.903794 -289.446208)
		(width 0.0889)
		(layer "In11.Cu")
		(net "UPI_CPU1_CPU0_P2P2_DN<14>")
	)
	(segment
		(start 212.594952 -376.486674)
		(end 260.253226 -372.26875)
		(width 0.14732)
		(layer "In11.Cu")
		(net "UPI_CPU1_CPU0_P2P2_DN<14>")
	)
	(segment
		(start 76.108814 -367.96726)
		(end 97.500694 -376.827796)
		(width 0.14732)
		(layer "In11.Cu")
		(net "UPI_CPU1_CPU0_P2P2_DN<14>")
	)
	(segment
		(start 98.319082 -285.980632)
		(end 98.310192 -285.985712)
		(width 0.0889)
		(layer "In11.Cu")
		(net "UPI_CPU1_CPU0_P2P2_DN<14>")
	)
	(segment
		(start 178.713384 -378.231908)
		(end 178.833272 -378.061728)
		(width 0.14732)
		(layer "In11.Cu")
		(net "UPI_CPU1_CPU0_P2P2_DN<14>")
	)
	(segment
		(start 175.083978 -379.254258)
		(end 175.439578 -379.504702)
		(width 0.14732)
		(layer "In11.Cu")
		(net "UPI_CPU1_CPU0_P2P2_DN<14>")
	)
	(segment
		(start 186.855608 -377.517152)
		(end 187.66155 -377.37669)
		(width 0.14732)
		(layer "In11.Cu")
		(net "UPI_CPU1_CPU0_P2P2_DN<14>")
	)
	(segment
		(start 98.795078 -285.16326)
		(end 98.795586 -285.16326)
		(width 0.0889)
		(layer "In11.Cu")
		(net "UPI_CPU1_CPU0_P2P2_DN<14>")
	)
	(segment
		(start 188.546994 -376.370342)
		(end 188.717174 -376.49023)
		(width 0.14732)
		(layer "In11.Cu")
		(net "UPI_CPU1_CPU0_P2P2_DN<14>")
	)
	(segment
		(start 186.263788 -376.767852)
		(end 186.433968 -376.88774)
		(width 0.14732)
		(layer "In11.Cu")
		(net "UPI_CPU1_CPU0_P2P2_DN<14>")
	)
	(segment
		(start 306.222146 -330.15682)
		(end 307.499766 -328.332592)
		(width 0.14732)
		(layer "In11.Cu")
		(net "UPI_CPU1_CPU0_P2P2_DN<14>")
	)
	(segment
		(start 344.41892 -282.92806)
		(end 344.497152 -282.948888)
		(width 0.0889)
		(layer "In11.Cu")
		(net "UPI_CPU1_CPU0_P2P2_DN<14>")
	)
	(segment
		(start 193.349626 -376.074178)
		(end 193.705226 -376.324622)
		(width 0.14732)
		(layer "In11.Cu")
		(net "UPI_CPU1_CPU0_P2P2_DN<14>")
	)
	(segment
		(start 341.4903 -291.212778)
		(end 341.4903 -291.000434)
		(width 0.0889)
		(layer "In11.Cu")
		(net "UPI_CPU1_CPU0_P2P2_DN<14>")
	)
	(segment
		(start 176.430178 -378.629418)
		(end 176.550066 -378.459238)
		(width 0.14732)
		(layer "In11.Cu")
		(net "UPI_CPU1_CPU0_P2P2_DN<14>")
	)
	(segment
		(start 185.629042 -377.418092)
		(end 185.563002 -377.039378)
		(width 0.14732)
		(layer "In11.Cu")
		(net "UPI_CPU1_CPU0_P2P2_DN<14>")
	)
	(segment
		(start 100.198682 -284.353)
		(end 100.189792 -284.35808)
		(width 0.0889)
		(layer "In11.Cu")
		(net "UPI_CPU1_CPU0_P2P2_DN<14>")
	)
	(segment
		(start 195.566792 -375.2977)
		(end 195.632832 -375.676668)
		(width 0.14732)
		(layer "In11.Cu")
		(net "UPI_CPU1_CPU0_P2P2_DN<14>")
	)
	(segment
		(start 100.668582 -283.539184)
		(end 100.660454 -283.543756)
		(width 0.0889)
		(layer "In11.Cu")
		(net "UPI_CPU1_CPU0_P2P2_DN<14>")
	)
	(segment
		(start 97.046288 -291.496496)
		(end 97.046288 -296.926254)
		(width 0.14732)
		(layer "In11.Cu")
		(net "UPI_CPU1_CPU0_P2P2_DN<14>")
	)
	(segment
		(start 187.966096 -376.471688)
		(end 188.546994 -376.370342)
		(width 0.14732)
		(layer "In11.Cu")
		(net "UPI_CPU1_CPU0_P2P2_DN<14>")
	)
	(segment
		(start 68.101718 -334.855312)
		(end 68.101718 -353.894644)
		(width 0.14732)
		(layer "In11.Cu")
		(net "UPI_CPU1_CPU0_P2P2_DN<14>")
	)
	(segment
		(start 178.528726 -378.96673)
		(end 178.779424 -378.610622)
		(width 0.14732)
		(layer "In11.Cu")
		(net "UPI_CPU1_CPU0_P2P2_DN<14>")
	)
	(segment
		(start 193.705226 -376.324622)
		(end 194.511168 -376.18416)
		(width 0.14732)
		(layer "In11.Cu")
		(net "UPI_CPU1_CPU0_P2P2_DN<14>")
	)
	(segment
		(start 343.055702 -285.985204)
		(end 343.047574 -285.980632)
		(width 0.0889)
		(layer "In11.Cu")
		(net "UPI_CPU1_CPU0_P2P2_DN<14>")
	)
	(segment
		(start 100.377244 -282.405836)
		(end 100.377244 -282.424378)
		(width 0.0889)
		(layer "In11.Cu")
		(net "UPI_CPU1_CPU0_P2P2_DN<14>")
	)
	(segment
		(start 205.547468 -375.397776)
		(end 212.594952 -376.486674)
		(width 0.14732)
		(layer "In11.Cu")
		(net "UPI_CPU1_CPU0_P2P2_DN<14>")
	)
	(segment
		(start 185.68289 -376.869198)
		(end 186.263788 -376.767852)
		(width 0.14732)
		(layer "In11.Cu")
		(net "UPI_CPU1_CPU0_P2P2_DN<14>")
	)
	(segment
		(start 97.500694 -376.827796)
		(end 125.875796 -381.03683)
		(width 0.14732)
		(layer "In11.Cu")
		(net "UPI_CPU1_CPU0_P2P2_DN<14>")
	)
	(segment
		(start 180.99659 -377.834398)
		(end 181.116478 -377.664218)
		(width 0.14732)
		(layer "In11.Cu")
		(net "UPI_CPU1_CPU0_P2P2_DN<14>")
	)
	(segment
		(start 267.26134 -365.260382)
		(end 267.26134 -345.63558)
		(width 0.14732)
		(layer "In11.Cu")
		(net "UPI_CPU1_CPU0_P2P2_DN<14>")
	)
	(segment
		(start 100.847398 -281.576526)
		(end 100.847398 -281.59202)
		(width 0.0889)
		(layer "In11.Cu")
		(net "UPI_CPU1_CPU0_P2P2_DN<14>")
	)
	(segment
		(start 338.985606 -294.637714)
		(end 341.02929 -292.59403)
		(width 0.14732)
		(layer "In11.Cu")
		(net "UPI_CPU1_CPU0_P2P2_DN<14>")
	)
	(segment
		(start 192.227962 -376.58167)
		(end 192.47866 -376.225562)
		(width 0.14732)
		(layer "In11.Cu")
		(net "UPI_CPU1_CPU0_P2P2_DN<14>")
	)
	(segment
		(start 179.41417 -377.960382)
		(end 179.58435 -378.08027)
		(width 0.14732)
		(layer "In11.Cu")
		(net "UPI_CPU1_CPU0_P2P2_DN<14>")
	)
	(segment
		(start 196.794374 -375.78665)
		(end 197.045072 -375.430542)
		(width 0.14732)
		(layer "In11.Cu")
		(net "UPI_CPU1_CPU0_P2P2_DN<14>")
	)
	(segment
		(start 99.729036 -285.166816)
		(end 99.72167 -285.171134)
		(width 0.0889)
		(layer "In11.Cu")
		(net "UPI_CPU1_CPU0_P2P2_DN<14>")
	)
	(segment
		(start 343.808812 -284.049216)
		(end 343.808812 -284.033722)
		(width 0.0889)
		(layer "In11.Cu")
		(net "UPI_CPU1_CPU0_P2P2_DN<14>")
	)
	(segment
		(start 97.379282 -287.608518)
		(end 97.370392 -287.613598)
		(width 0.0889)
		(layer "In11.Cu")
		(net "UPI_CPU1_CPU0_P2P2_DN<14>")
	)
	(segment
		(start 311.456832 -324.367398)
		(end 313.154822 -323.172836)
		(width 0.14732)
		(layer "In11.Cu")
		(net "UPI_CPU1_CPU0_P2P2_DN<14>")
	)
	(segment
		(start 97.839784 -286.80029)
		(end 97.83445 -286.803338)
		(width 0.0889)
		(layer "In11.Cu")
		(net "UPI_CPU1_CPU0_P2P2_DN<14>")
	)
	(segment
		(start 343.047574 -286.969962)
		(end 343.056464 -286.964882)
		(width 0.0889)
		(layer "In11.Cu")
		(net "UPI_CPU1_CPU0_P2P2_DN<14>")
	)
	(segment
		(start 187.912248 -377.020582)
		(end 187.846208 -376.641868)
		(width 0.14732)
		(layer "In11.Cu")
		(net "UPI_CPU1_CPU0_P2P2_DN<14>")
	)
	(segment
		(start 172.800772 -379.651768)
		(end 173.156372 -379.902212)
		(width 0.14732)
		(layer "In11.Cu")
		(net "UPI_CPU1_CPU0_P2P2_DN<14>")
	)
	(segment
		(start 191.06642 -376.471688)
		(end 191.42202 -376.722132)
		(width 0.14732)
		(layer "In11.Cu")
		(net "UPI_CPU1_CPU0_P2P2_DN<14>")
	)
	(segment
		(start 173.962314 -379.76175)
		(end 174.213012 -379.405642)
		(width 0.14732)
		(layer "In11.Cu")
		(net "UPI_CPU1_CPU0_P2P2_DN<14>")
	)
	(segment
		(start 98.795586 -285.16326)
		(end 98.77425 -285.175452)
		(width 0.0889)
		(layer "In11.Cu")
		(net "UPI_CPU1_CPU0_P2P2_DN<14>")
	)
	(segment
		(start 191.00038 -376.09272)
		(end 191.06642 -376.471688)
		(width 0.14732)
		(layer "In11.Cu")
		(net "UPI_CPU1_CPU0_P2P2_DN<14>")
	)
	(segment
		(start 172.734732 -379.2728)
		(end 172.800772 -379.651768)
		(width 0.14732)
		(layer "In11.Cu")
		(net "UPI_CPU1_CPU0_P2P2_DN<14>")
	)
	(segment
		(start 188.783214 -376.869198)
		(end 189.138814 -377.119642)
		(width 0.14732)
		(layer "In11.Cu")
		(net "UPI_CPU1_CPU0_P2P2_DN<14>")
	)
	(segment
		(start 189.944756 -376.97918)
		(end 190.195454 -376.623072)
		(width 0.14732)
		(layer "In11.Cu")
		(net "UPI_CPU1_CPU0_P2P2_DN<14>")
	)
	(segment
		(start 342.577928 -287.783778)
		(end 342.586818 -287.778698)
		(width 0.0889)
		(layer "In11.Cu")
		(net "UPI_CPU1_CPU0_P2P2_DN<14>")
	)
	(segment
		(start 336.649822 -295.6052)
		(end 338.985606 -294.637714)
		(width 0.14732)
		(layer "In11.Cu")
		(net "UPI_CPU1_CPU0_P2P2_DN<14>")
	)
	(segment
		(start 181.06263 -378.213112)
		(end 180.99659 -377.834398)
		(width 0.14732)
		(layer "In11.Cu")
		(net "UPI_CPU1_CPU0_P2P2_DN<14>")
	)
	(segment
		(start 341.4903 -291.000434)
		(end 342.399112 -290.091622)
		(width 0.0889)
		(layer "In11.Cu")
		(net "UPI_CPU1_CPU0_P2P2_DN<14>")
	)
	(segment
		(start 195.988432 -375.927112)
		(end 196.794374 -375.78665)
		(width 0.14732)
		(layer "In11.Cu")
		(net "UPI_CPU1_CPU0_P2P2_DN<14>")
	)
	(segment
		(start 343.996264 -283.709364)
		(end 344.000074 -283.707078)
		(width 0.0889)
		(layer "In11.Cu")
		(net "UPI_CPU1_CPU0_P2P2_DN<14>")
	)
	(segment
		(start 181.867556 -377.68276)
		(end 181.933596 -378.061728)
		(width 0.14732)
		(layer "In11.Cu")
		(net "UPI_CPU1_CPU0_P2P2_DN<14>")
	)
	(segment
		(start 308.374034 -326.066912)
		(end 310.471566 -324.59803)
		(width 0.14732)
		(layer "In11.Cu")
		(net "UPI_CPU1_CPU0_P2P2_DN<14>")
	)
	(segment
		(start 182.289196 -378.312172)
		(end 183.095138 -378.17171)
		(width 0.14732)
		(layer "In11.Cu")
		(net "UPI_CPU1_CPU0_P2P2_DN<14>")
	)
	(segment
		(start 178.779424 -378.610622)
		(end 178.713384 -378.231908)
		(width 0.14732)
		(layer "In11.Cu")
		(net "UPI_CPU1_CPU0_P2P2_DN<14>")
	)
	(segment
		(start 341.266272 -291.49675)
		(end 341.281766 -291.481256)
		(width 0.0889)
		(layer "In11.Cu")
		(net "UPI_CPU1_CPU0_P2P2_DN<14>")
	)
	(segment
		(start 175.439578 -379.504702)
		(end 176.24552 -379.36424)
		(width 0.14732)
		(layer "In11.Cu")
		(net "UPI_CPU1_CPU0_P2P2_DN<14>")
	)
	(segment
		(start 342.108028 -288.597848)
		(end 342.116918 -288.592768)
		(width 0.0889)
		(layer "In11.Cu")
		(net "UPI_CPU1_CPU0_P2P2_DN<14>")
	)
	(segment
		(start 187.846208 -376.641868)
		(end 187.966096 -376.471688)
		(width 0.14732)
		(layer "In11.Cu")
		(net "UPI_CPU1_CPU0_P2P2_DN<14>")
	)
	(segment
		(start 100.668836 -281.911044)
		(end 100.65385 -281.919934)
		(width 0.0889)
		(layer "In11.Cu")
		(net "UPI_CPU1_CPU0_P2P2_DN<14>")
	)
	(segment
		(start 285.034482 -331.26807)
		(end 305.116738 -331.26807)
		(width 0.14732)
		(layer "In11.Cu")
		(net "UPI_CPU1_CPU0_P2P2_DN<14>")
	)
	(segment
		(start 197.100952 -374.878854)
		(end 199.505824 -374.463818)
		(width 0.14732)
		(layer "In11.Cu")
		(net "UPI_CPU1_CPU0_P2P2_DN<14>")
	)
	(segment
		(start 341.281766 -291.421312)
		(end 341.4903 -291.212778)
		(width 0.0889)
		(layer "In11.Cu")
		(net "UPI_CPU1_CPU0_P2P2_DN<14>")
	)
	(segment
		(start 97.088198 -291.432488)
		(end 97.046288 -291.474398)
		(width 0.0889)
		(layer "In11.Cu")
		(net "UPI_CPU1_CPU0_P2P2_DN<14>")
	)
	(segment
		(start 174.847758 -378.755402)
		(end 175.017938 -378.87529)
		(width 0.14732)
		(layer "In11.Cu")
		(net "UPI_CPU1_CPU0_P2P2_DN<14>")
	)
	(segment
		(start 96.618298 -288.898584)
		(end 96.618298 -289.114738)
		(width 0.0889)
		(layer "In11.Cu")
		(net "UPI_CPU1_CPU0_P2P2_DN<14>")
	)
	(segment
		(start 192.532508 -375.676668)
		(end 193.113406 -375.575322)
		(width 0.14732)
		(layer "In11.Cu")
		(net "UPI_CPU1_CPU0_P2P2_DN<14>")
	)
	(segment
		(start 196.979032 -375.051574)
		(end 197.100952 -374.878854)
		(width 0.14732)
		(layer "In11.Cu")
		(net "UPI_CPU1_CPU0_P2P2_DN<14>")
	)
	(segment
		(start 100.659692 -282.895548)
		(end 100.668582 -282.900628)
		(width 0.0889)
		(layer "In11.Cu")
		(net "UPI_CPU1_CPU0_P2P2_DN<14>")
	)
	(segment
		(start 344.000074 -283.707078)
		(end 344.008456 -283.702252)
		(width 0.0889)
		(layer "In11.Cu")
		(net "UPI_CPU1_CPU0_P2P2_DN<14>")
	)
	(segment
		(start 97.840546 -286.799782)
		(end 97.839784 -286.80029)
		(width 0.0889)
		(layer "In11.Cu")
		(net "UPI_CPU1_CPU0_P2P2_DN<14>")
	)
	(segment
		(start 185.378344 -377.7742)
		(end 185.629042 -377.418092)
		(width 0.14732)
		(layer "In11.Cu")
		(net "UPI_CPU1_CPU0_P2P2_DN<14>")
	)
	(segment
		(start 343.987374 -283.714444)
		(end 343.996264 -283.709364)
		(width 0.0889)
		(layer "In11.Cu")
		(net "UPI_CPU1_CPU0_P2P2_DN<14>")
	)
	(segment
		(start 336.105754 -296.419524)
		(end 336.649822 -295.6052)
		(width 0.14732)
		(layer "In11.Cu")
		(net "UPI_CPU1_CPU0_P2P2_DN<14>")
	)
	(segment
		(start 100.668836 -281.911298)
		(end 100.668836 -281.911044)
		(width 0.0889)
		(layer "In11.Cu")
		(net "UPI_CPU1_CPU0_P2P2_DN<14>")
	)
	(segment
		(start 192.47866 -376.225562)
		(end 192.41262 -375.846848)
		(width 0.14732)
		(layer "In11.Cu")
		(net "UPI_CPU1_CPU0_P2P2_DN<14>")
	)
	(segment
		(start 174.213012 -379.405642)
		(end 174.146972 -379.026928)
		(width 0.14732)
		(layer "In11.Cu")
		(net "UPI_CPU1_CPU0_P2P2_DN<14>")
	)
	(segment
		(start 334.296766 -302.379888)
		(end 336.105754 -296.419524)
		(width 0.14732)
		(layer "In11.Cu")
		(net "UPI_CPU1_CPU0_P2P2_DN<14>")
	)
	(segment
		(start 341.15756 -291.605462)
		(end 341.266272 -291.49675)
		(width 0.14732)
		(layer "In11.Cu")
		(net "UPI_CPU1_CPU0_P2P2_DN<14>")
	)
	(segment
		(start 99.72167 -285.171134)
		(end 99.720146 -285.171896)
		(width 0.0889)
		(layer "In11.Cu")
		(net "UPI_CPU1_CPU0_P2P2_DN<14>")
	)
	(segment
		(start 178.833272 -378.061728)
		(end 179.41417 -377.960382)
		(width 0.14732)
		(layer "In11.Cu")
		(net "UPI_CPU1_CPU0_P2P2_DN<14>")
	)
	(segment
		(start 267.26134 -345.63558)
		(end 279.220676 -333.676244)
		(width 0.14732)
		(layer "In11.Cu")
		(net "UPI_CPU1_CPU0_P2P2_DN<14>")
	)
	(segment
		(start 95.717106 -300.135544)
		(end 94.659196 -301.561754)
		(width 0.14732)
		(layer "In11.Cu")
		(net "UPI_CPU1_CPU0_P2P2_DN<14>")
	)
	(segment
		(start 180.00599 -378.709682)
		(end 180.811932 -378.56922)
		(width 0.14732)
		(layer "In11.Cu")
		(net "UPI_CPU1_CPU0_P2P2_DN<14>")
	)
	(segment
		(start 191.42202 -376.722132)
		(end 192.227962 -376.58167)
		(width 0.14732)
		(layer "In11.Cu")
		(net "UPI_CPU1_CPU0_P2P2_DN<14>")
	)
	(segment
		(start 342.869012 -287.304734)
		(end 342.869012 -287.28924)
		(width 0.0889)
		(layer "In11.Cu")
		(net "UPI_CPU1_CPU0_P2P2_DN<14>")
	)
	(segment
		(start 311.341516 -324.445122)
		(end 311.456832 -324.367652)
		(width 0.14732)
		(layer "In11.Cu")
		(net "UPI_CPU1_CPU0_P2P2_DN<14>")
	)
	(segment
		(start 205.54696 -375.397522)
		(end 205.547468 -375.397776)
		(width 0.14732)
		(layer "In11.Cu")
		(net "UPI_CPU1_CPU0_P2P2_DN<14>")
	)
	(segment
		(start 183.279796 -377.436888)
		(end 183.399684 -377.266708)
		(width 0.14732)
		(layer "In11.Cu")
		(net "UPI_CPU1_CPU0_P2P2_DN<14>")
	)
	(segment
		(start 177.130964 -378.357892)
		(end 177.301144 -378.47778)
		(width 0.14732)
		(layer "In11.Cu")
		(net "UPI_CPU1_CPU0_P2P2_DN<14>")
	)
	(segment
		(start 195.632832 -375.676668)
		(end 195.988432 -375.927112)
		(width 0.14732)
		(layer "In11.Cu")
		(net "UPI_CPU1_CPU0_P2P2_DN<14>")
	)
	(segment
		(start 173.156372 -379.902212)
		(end 173.962314 -379.76175)
		(width 0.14732)
		(layer "In11.Cu")
		(net "UPI_CPU1_CPU0_P2P2_DN<14>")
	)
	(segment
		(start 343.047574 -285.342076)
		(end 343.06256 -285.33344)
		(width 0.0889)
		(layer "In11.Cu")
		(net "UPI_CPU1_CPU0_P2P2_DN<14>")
	)
	(segment
		(start 306.222146 -330.162662)
		(end 306.222146 -330.15682)
		(width 0.14732)
		(layer "In11.Cu")
		(net "UPI_CPU1_CPU0_P2P2_DN<14>")
	)
	(segment
		(start 72.398636 -364.257082)
		(end 76.108814 -367.96726)
		(width 0.14732)
		(layer "In11.Cu")
		(net "UPI_CPU1_CPU0_P2P2_DN<14>")
	)
	(segment
		(start 183.345836 -377.815602)
		(end 183.279796 -377.436888)
		(width 0.14732)
		(layer "In11.Cu")
		(net "UPI_CPU1_CPU0_P2P2_DN<14>")
	)
	(arc
		(start 342.399112 -289.60953)
		(mid 342.287774 -289.41663)
		(end 342.113616 -289.277806)
		(width 0.0889)
		(layer "In11.Cu")
		(net "UPI_CPU1_CPU0_P2P2_DN<14>")
	)
	(arc
		(start 343.339166 -286.467804)
		(mid 343.261537 -286.189391)
		(end 343.056464 -285.985712)
		(width 0.0889)
		(layer "In11.Cu")
		(net "UPI_CPU1_CPU0_P2P2_DN<14>")
	)
	(arc
		(start 99.907598 -284.847538)
		(mid 99.859919 -285.030438)
		(end 99.729036 -285.166816)
		(width 0.0889)
		(layer "In11.Cu")
		(net "UPI_CPU1_CPU0_P2P2_DN<14>")
	)
	(arc
		(start 343.06256 -285.33344)
		(mid 343.265147 -285.127089)
		(end 343.339166 -284.847538)
		(width 0.0889)
		(layer "In11.Cu")
		(net "UPI_CPU1_CPU0_P2P2_DN<14>")
	)
	(arc
		(start 100.668582 -282.900628)
		(mid 100.847179 -283.219906)
		(end 100.668582 -283.539184)
		(width 0.0889)
		(layer "In11.Cu")
		(net "UPI_CPU1_CPU0_P2P2_DN<14>")
	)
	(arc
		(start 97.088198 -288.103056)
		(mid 97.040519 -288.285956)
		(end 96.909636 -288.422334)
		(width 0.0889)
		(layer "In11.Cu")
		(net "UPI_CPU1_CPU0_P2P2_DN<14>")
	)
	(arc
		(start 101.074728 -281.138376)
		(mid 101.066287 -281.144776)
		(end 101.057964 -281.15133)
		(width 0.0889)
		(layer "In11.Cu")
		(net "UPI_CPU1_CPU0_P2P2_DN<14>")
	)
	(arc
		(start 341.929466 -288.917126)
		(mid 341.977145 -288.734226)
		(end 342.108028 -288.597848)
		(width 0.0889)
		(layer "In11.Cu")
		(net "UPI_CPU1_CPU0_P2P2_DN<14>")
	)
	(arc
		(start 342.586818 -287.778698)
		(mid 342.789641 -287.578467)
		(end 342.869012 -287.304734)
		(width 0.0889)
		(layer "In11.Cu")
		(net "UPI_CPU1_CPU0_P2P2_DN<14>")
	)
	(arc
		(start 343.526618 -284.52318)
		(mid 343.729441 -284.322949)
		(end 343.808812 -284.049216)
		(width 0.0889)
		(layer "In11.Cu")
		(net "UPI_CPU1_CPU0_P2P2_DN<14>")
	)
	(arc
		(start 343.808812 -284.033722)
		(mid 343.856491 -283.850822)
		(end 343.987374 -283.714444)
		(width 0.0889)
		(layer "In11.Cu")
		(net "UPI_CPU1_CPU0_P2P2_DN<14>")
	)
	(arc
		(start 343.047574 -285.980632)
		(mid 342.869098 -285.661354)
		(end 343.047574 -285.342076)
		(width 0.0889)
		(layer "In11.Cu")
		(net "UPI_CPU1_CPU0_P2P2_DN<14>")
	)
	(arc
		(start 100.377244 -282.424378)
		(mid 100.457406 -282.696567)
		(end 100.659692 -282.895548)
		(width 0.0889)
		(layer "In11.Cu")
		(net "UPI_CPU1_CPU0_P2P2_DN<14>")
	)
	(arc
		(start 99.720146 -285.171896)
		(mid 99.532948 -285.222039)
		(end 99.34575 -285.171896)
		(width 0.0889)
		(layer "In11.Cu")
		(net "UPI_CPU1_CPU0_P2P2_DN<14>")
	)
	(arc
		(start 342.116918 -288.592768)
		(mid 342.319204 -288.393787)
		(end 342.399366 -288.121598)
		(width 0.0889)
		(layer "In11.Cu")
		(net "UPI_CPU1_CPU0_P2P2_DN<14>")
	)
	(arc
		(start 98.77425 -285.175452)
		(mid 98.571663 -285.381803)
		(end 98.497644 -285.661354)
		(width 0.0889)
		(layer "In11.Cu")
		(net "UPI_CPU1_CPU0_P2P2_DN<14>")
	)
	(arc
		(start 344.278966 -283.219906)
		(mid 344.315826 -283.058109)
		(end 344.41892 -282.92806)
		(width 0.0889)
		(layer "In11.Cu")
		(net "UPI_CPU1_CPU0_P2P2_DN<14>")
	)
	(arc
		(start 98.497644 -285.661354)
		(mid 98.449965 -285.844254)
		(end 98.319082 -285.980632)
		(width 0.0889)
		(layer "In11.Cu")
		(net "UPI_CPU1_CPU0_P2P2_DN<14>")
	)
	(arc
		(start 97.557844 -287.28924)
		(mid 97.510165 -287.47214)
		(end 97.379282 -287.608518)
		(width 0.0889)
		(layer "In11.Cu")
		(net "UPI_CPU1_CPU0_P2P2_DN<14>")
	)
	(arc
		(start 96.900746 -288.427414)
		(mid 96.69846 -288.626395)
		(end 96.618298 -288.898584)
		(width 0.0889)
		(layer "In11.Cu")
		(net "UPI_CPU1_CPU0_P2P2_DN<14>")
	)
	(arc
		(start 97.370392 -287.613598)
		(mid 97.167569 -287.813829)
		(end 97.088198 -288.087562)
		(width 0.0889)
		(layer "In11.Cu")
		(net "UPI_CPU1_CPU0_P2P2_DN<14>")
	)
	(arc
		(start 342.399366 -288.103056)
		(mid 342.447045 -287.920156)
		(end 342.577928 -287.783778)
		(width 0.0889)
		(layer "In11.Cu")
		(net "UPI_CPU1_CPU0_P2P2_DN<14>")
	)
	(arc
		(start 343.339166 -284.847538)
		(mid 343.386845 -284.664638)
		(end 343.517728 -284.52826)
		(width 0.0889)
		(layer "In11.Cu")
		(net "UPI_CPU1_CPU0_P2P2_DN<14>")
	)
	(arc
		(start 344.008456 -283.702252)
		(mid 344.206684 -283.496404)
		(end 344.278966 -283.219906)
		(width 0.0889)
		(layer "In11.Cu")
		(net "UPI_CPU1_CPU0_P2P2_DN<14>")
	)
	(arc
		(start 100.189792 -284.35808)
		(mid 99.986969 -284.558311)
		(end 99.907598 -284.832044)
		(width 0.0889)
		(layer "In11.Cu")
		(net "UPI_CPU1_CPU0_P2P2_DN<14>")
	)
	(arc
		(start 343.068656 -286.95777)
		(mid 343.266884 -286.751922)
		(end 343.339166 -286.475424)
		(width 0.0889)
		(layer "In11.Cu")
		(net "UPI_CPU1_CPU0_P2P2_DN<14>")
	)
	(arc
		(start 100.847398 -281.59202)
		(mid 100.799719 -281.77492)
		(end 100.668836 -281.911298)
		(width 0.0889)
		(layer "In11.Cu")
		(net "UPI_CPU1_CPU0_P2P2_DN<14>")
	)
	(arc
		(start 101.057964 -281.15133)
		(mid 100.905882 -281.340762)
		(end 100.847398 -281.576526)
		(width 0.0889)
		(layer "In11.Cu")
		(net "UPI_CPU1_CPU0_P2P2_DN<14>")
	)
	(arc
		(start 99.34575 -285.171896)
		(mid 99.071551 -285.096061)
		(end 98.795078 -285.16326)
		(width 0.0889)
		(layer "In11.Cu")
		(net "UPI_CPU1_CPU0_P2P2_DN<14>")
	)
	(arc
		(start 342.869012 -287.28924)
		(mid 342.916691 -287.10634)
		(end 343.047574 -286.969962)
		(width 0.0889)
		(layer "In11.Cu")
		(net "UPI_CPU1_CPU0_P2P2_DN<14>")
	)
	(arc
		(start 100.659692 -283.544264)
		(mid 100.455357 -283.746869)
		(end 100.377244 -284.023816)
		(width 0.0889)
		(layer "In11.Cu")
		(net "UPI_CPU1_CPU0_P2P2_DN<14>")
	)
	(arc
		(start 100.65385 -281.919934)
		(mid 100.451263 -282.126285)
		(end 100.377244 -282.405836)
		(width 0.0889)
		(layer "In11.Cu")
		(net "UPI_CPU1_CPU0_P2P2_DN<14>")
	)
	(arc
		(start 98.310192 -285.985712)
		(mid 98.107906 -286.184693)
		(end 98.027744 -286.456882)
		(width 0.0889)
		(layer "In11.Cu")
		(net "UPI_CPU1_CPU0_P2P2_DN<14>")
	)
	(arc
		(start 98.027744 -286.48406)
		(mid 97.975474 -286.666425)
		(end 97.840546 -286.799782)
		(width 0.0889)
		(layer "In11.Cu")
		(net "UPI_CPU1_CPU0_P2P2_DN<14>")
	)
	(arc
		(start 96.903794 -289.446208)
		(mid 97.012829 -289.529937)
		(end 97.087944 -289.64509)
		(width 0.0889)
		(layer "In11.Cu")
		(net "UPI_CPU1_CPU0_P2P2_DN<14>")
	)
	(arc
		(start 100.377244 -284.033722)
		(mid 100.329565 -284.216622)
		(end 100.198682 -284.353)
		(width 0.0889)
		(layer "In11.Cu")
		(net "UPI_CPU1_CPU0_P2P2_DN<14>")
	)
	(arc
		(start 97.83445 -286.803338)
		(mid 97.631863 -287.009689)
		(end 97.557844 -287.28924)
		(width 0.0889)
		(layer "In11.Cu")
		(net "UPI_CPU1_CPU0_P2P2_DN<14>")
	)
	(arc
		(start 342.113616 -289.277806)
		(mid 342.004469 -289.193878)
		(end 341.929466 -289.078416)
		(width 0.0889)
		(layer "In11.Cu")
		(net "UPI_CPU1_CPU0_P2P2_DN<14>")
	)
	(arc
		(start 96.618298 -289.114738)
		(mid 96.729636 -289.307638)
		(end 96.903794 -289.446462)
		(width 0.0889)
		(layer "In11.Cu")
		(net "UPI_CPU1_CPU0_P2P2_DN<14>")
	)
	(segment
		(start 346.063316 -280.77795)
		(end 346.063062 -280.778204)
		(width 0.13208)
		(layer "F.Cu")
		(net "UPI_CPU1_CPU0_P2P2_DN<13>")
	)
	(segment
		(start 100.002848 -281.869896)
		(end 100.002848 -282.405582)
		(width 0.13208)
		(layer "F.Cu")
		(net "UPI_CPU1_CPU0_P2P2_DN<13>")
	)
	(segment
		(start 100.002848 -282.405582)
		(end 100.002594 -282.405836)
		(width 0.13208)
		(layer "F.Cu")
		(net "UPI_CPU1_CPU0_P2P2_DN<13>")
	)
	(segment
		(start 346.063316 -280.242264)
		(end 346.063316 -280.77795)
		(width 0.13208)
		(layer "F.Cu")
		(net "UPI_CPU1_CPU0_P2P2_DN<13>")
	)
	(segment
		(start 199.96658 -377.537218)
		(end 199.798686 -377.41479)
		(width 0.14732)
		(layer "In11.Cu")
		(net "UPI_CPU1_CPU0_P2P2_DN<13>")
	)
	(segment
		(start 96.995996 -286.964882)
		(end 96.997266 -286.96412)
		(width 0.0889)
		(layer "In11.Cu")
		(net "UPI_CPU1_CPU0_P2P2_DN<13>")
	)
	(segment
		(start 98.780346 -284.52318)
		(end 98.795078 -284.531816)
		(width 0.0889)
		(layer "In11.Cu")
		(net "UPI_CPU1_CPU0_P2P2_DN<13>")
	)
	(segment
		(start 99.84613 -282.676854)
		(end 100.002594 -282.405836)
		(width 0.0889)
		(layer "In11.Cu")
		(net "UPI_CPU1_CPU0_P2P2_DN<13>")
	)
	(segment
		(start 206.153766 -377.556776)
		(end 205.566264 -377.493276)
		(width 0.14732)
		(layer "In11.Cu")
		(net "UPI_CPU1_CPU0_P2P2_DN<13>")
	)
	(segment
		(start 265.250168 -368.398298)
		(end 260.719824 -372.928642)
		(width 0.14732)
		(layer "In11.Cu")
		(net "UPI_CPU1_CPU0_P2P2_DN<13>")
	)
	(segment
		(start 96.995996 -285.985712)
		(end 96.995234 -285.985204)
		(width 0.0889)
		(layer "In11.Cu")
		(net "UPI_CPU1_CPU0_P2P2_DN<13>")
	)
	(segment
		(start 266.828778 -366.614964)
		(end 266.828778 -366.819688)
		(width 0.14732)
		(layer "In11.Cu")
		(net "UPI_CPU1_CPU0_P2P2_DN<13>")
	)
	(segment
		(start 71.909686 -364.555024)
		(end 67.542918 -354.012754)
		(width 0.14732)
		(layer "In11.Cu")
		(net "UPI_CPU1_CPU0_P2P2_DN<13>")
	)
	(segment
		(start 96.380554 -291.474398)
		(end 96.338644 -291.432488)
		(width 0.0889)
		(layer "In11.Cu")
		(net "UPI_CPU1_CPU0_P2P2_DN<13>")
	)
	(segment
		(start 346.063062 -280.778204)
		(end 345.906598 -281.049222)
		(width 0.0889)
		(layer "In11.Cu")
		(net "UPI_CPU1_CPU0_P2P2_DN<13>")
	)
	(segment
		(start 308.189884 -329.859894)
		(end 306.227988 -331.82179)
		(width 0.14732)
		(layer "In11.Cu")
		(net "UPI_CPU1_CPU0_P2P2_DN<13>")
	)
	(segment
		(start 340.91118 -298.104052)
		(end 340.586568 -298.887388)
		(width 0.14732)
		(layer "In11.Cu")
		(net "UPI_CPU1_CPU0_P2P2_DN<13>")
	)
	(segment
		(start 344.088466 -284.832044)
		(end 344.088466 -284.847538)
		(width 0.0889)
		(layer "In11.Cu")
		(net "UPI_CPU1_CPU0_P2P2_DN<13>")
	)
	(segment
		(start 67.542918 -354.012754)
		(end 67.542918 -334.815688)
		(width 0.14732)
		(layer "In11.Cu")
		(net "UPI_CPU1_CPU0_P2P2_DN<13>")
	)
	(segment
		(start 99.87026 -282.766008)
		(end 99.84613 -282.676854)
		(width 0.0889)
		(layer "In11.Cu")
		(net "UPI_CPU1_CPU0_P2P2_DN<13>")
	)
	(segment
		(start 96.997266 -286.96412)
		(end 97.008188 -286.95777)
		(width 0.0889)
		(layer "In11.Cu")
		(net "UPI_CPU1_CPU0_P2P2_DN<13>")
	)
	(segment
		(start 314.143136 -323.320156)
		(end 313.216544 -324.64375)
		(width 0.14732)
		(layer "In11.Cu")
		(net "UPI_CPU1_CPU0_P2P2_DN<13>")
	)
	(segment
		(start 97.940114 -285.334456)
		(end 97.941892 -285.33344)
		(width 0.0889)
		(layer "In11.Cu")
		(net "UPI_CPU1_CPU0_P2P2_DN<13>")
	)
	(segment
		(start 125.82144 -381.59563)
		(end 97.304352 -377.36526)
		(width 0.14732)
		(layer "In11.Cu")
		(net "UPI_CPU1_CPU0_P2P2_DN<13>")
	)
	(segment
		(start 203.849478 -377.308364)
		(end 203.261976 -377.244864)
		(width 0.14732)
		(layer "In11.Cu")
		(net "UPI_CPU1_CPU0_P2P2_DN<13>")
	)
	(segment
		(start 96.808544 -287.304734)
		(end 96.808544 -287.28924)
		(width 0.0889)
		(layer "In11.Cu")
		(net "UPI_CPU1_CPU0_P2P2_DN<13>")
	)
	(segment
		(start 343.901014 -285.171896)
		(end 343.894918 -285.175452)
		(width 0.0889)
		(layer "In11.Cu")
		(net "UPI_CPU1_CPU0_P2P2_DN<13>")
	)
	(segment
		(start 96.04756 -288.597848)
		(end 96.05645 -288.592768)
		(width 0.0889)
		(layer "In11.Cu")
		(net "UPI_CPU1_CPU0_P2P2_DN<13>")
	)
	(segment
		(start 204.010768 -377.178062)
		(end 203.849478 -377.308364)
		(width 0.14732)
		(layer "In11.Cu")
		(net "UPI_CPU1_CPU0_P2P2_DN<13>")
	)
	(segment
		(start 95.868998 -289.078416)
		(end 95.868998 -288.917126)
		(width 0.0889)
		(layer "In11.Cu")
		(net "UPI_CPU1_CPU0_P2P2_DN<13>")
	)
	(segment
		(start 342.133174 -291.137848)
		(end 342.074246 -291.137848)
		(width 0.0889)
		(layer "In11.Cu")
		(net "UPI_CPU1_CPU0_P2P2_DN<13>")
	)
	(segment
		(start 341.305134 -296.122852)
		(end 340.911688 -298.102782)
		(width 0.14732)
		(layer "In11.Cu")
		(net "UPI_CPU1_CPU0_P2P2_DN<13>")
	)
	(segment
		(start 266.568428 -367.080038)
		(end 266.363704 -367.080038)
		(width 0.14732)
		(layer "In11.Cu")
		(net "UPI_CPU1_CPU0_P2P2_DN<13>")
	)
	(segment
		(start 205.238858 -376.28449)
		(end 204.426312 -376.197114)
		(width 0.14732)
		(layer "In11.Cu")
		(net "UPI_CPU1_CPU0_P2P2_DN<13>")
	)
	(segment
		(start 97.921064 -285.345632)
		(end 97.935796 -285.336996)
		(width 0.0889)
		(layer "In11.Cu")
		(net "UPI_CPU1_CPU0_P2P2_DN<13>")
	)
	(segment
		(start 96.987106 -286.969962)
		(end 96.995996 -286.964882)
		(width 0.0889)
		(layer "In11.Cu")
		(net "UPI_CPU1_CPU0_P2P2_DN<13>")
	)
	(segment
		(start 344.840814 -283.544264)
		(end 344.840052 -283.544772)
		(width 0.0889)
		(layer "In11.Cu")
		(net "UPI_CPU1_CPU0_P2P2_DN<13>")
	)
	(segment
		(start 100.098098 -283.219906)
		(end 100.098098 -283.205682)
		(width 0.0889)
		(layer "In11.Cu")
		(net "UPI_CPU1_CPU0_P2P2_DN<13>")
	)
	(segment
		(start 97.304352 -377.36526)
		(end 75.82154 -368.466878)
		(width 0.14732)
		(layer "In11.Cu")
		(net "UPI_CPU1_CPU0_P2P2_DN<13>")
	)
	(segment
		(start 99.627944 -284.049216)
		(end 99.627944 -284.033722)
		(width 0.0889)
		(layer "In11.Cu")
		(net "UPI_CPU1_CPU0_P2P2_DN<13>")
	)
	(segment
		(start 96.995234 -285.985204)
		(end 96.987106 -285.980632)
		(width 0.0889)
		(layer "In11.Cu")
		(net "UPI_CPU1_CPU0_P2P2_DN<13>")
	)
	(segment
		(start 306.227988 -331.82179)
		(end 285.156402 -331.82179)
		(width 0.14732)
		(layer "In11.Cu")
		(net "UPI_CPU1_CPU0_P2P2_DN<13>")
	)
	(segment
		(start 344.840052 -283.544772)
		(end 344.834718 -283.54782)
		(width 0.0889)
		(layer "In11.Cu")
		(net "UPI_CPU1_CPU0_P2P2_DN<13>")
	)
	(segment
		(start 343.148666 -289.64636)
		(end 343.148666 -290.122356)
		(width 0.0889)
		(layer "In11.Cu")
		(net "UPI_CPU1_CPU0_P2P2_DN<13>")
	)
	(segment
		(start 336.369914 -301.093378)
		(end 315.03874 -322.424552)
		(width 0.14732)
		(layer "In11.Cu")
		(net "UPI_CPU1_CPU0_P2P2_DN<13>")
	)
	(segment
		(start 266.363704 -367.080038)
		(end 266.1031 -367.340642)
		(width 0.14732)
		(layer "In11.Cu")
		(net "UPI_CPU1_CPU0_P2P2_DN<13>")
	)
	(segment
		(start 202.93457 -376.036332)
		(end 201.912728 -375.925842)
		(width 0.14732)
		(layer "In11.Cu")
		(net "UPI_CPU1_CPU0_P2P2_DN<13>")
	)
	(segment
		(start 341.263224 -295.590976)
		(end 341.191596 -295.952418)
		(width 0.14732)
		(layer "In11.Cu")
		(net "UPI_CPU1_CPU0_P2P2_DN<13>")
	)
	(segment
		(start 344.558112 -282.405836)
		(end 344.558112 -282.42006)
		(width 0.0889)
		(layer "In11.Cu")
		(net "UPI_CPU1_CPU0_P2P2_DN<13>")
	)
	(segment
		(start 212.927692 -377.111768)
		(end 206.7306 -376.445526)
		(width 0.14732)
		(layer "In11.Cu")
		(net "UPI_CPU1_CPU0_P2P2_DN<13>")
	)
	(segment
		(start 343.900252 -286.80029)
		(end 343.894918 -286.803338)
		(width 0.0889)
		(layer "In11.Cu")
		(net "UPI_CPU1_CPU0_P2P2_DN<13>")
	)
	(segment
		(start 267.089636 -366.354106)
		(end 266.828778 -366.614964)
		(width 0.14732)
		(layer "In11.Cu")
		(net "UPI_CPU1_CPU0_P2P2_DN<13>")
	)
	(segment
		(start 341.499952 -294.400986)
		(end 341.428324 -294.762428)
		(width 0.14732)
		(layer "In11.Cu")
		(net "UPI_CPU1_CPU0_P2P2_DN<13>")
	)
	(segment
		(start 344.849704 -281.911298)
		(end 344.840814 -281.916378)
		(width 0.0889)
		(layer "In11.Cu")
		(net "UPI_CPU1_CPU0_P2P2_DN<13>")
	)
	(segment
		(start 99.813872 -283.710126)
		(end 99.815396 -283.709364)
		(width 0.0889)
		(layer "In11.Cu")
		(net "UPI_CPU1_CPU0_P2P2_DN<13>")
	)
	(segment
		(start 96.380808 -291.547042)
		(end 96.380554 -291.546788)
		(width 0.14732)
		(layer "In11.Cu")
		(net "UPI_CPU1_CPU0_P2P2_DN<13>")
	)
	(segment
		(start 95.233236 -299.851826)
		(end 96.380808 -297.080686)
		(width 0.14732)
		(layer "In11.Cu")
		(net "UPI_CPU1_CPU0_P2P2_DN<13>")
	)
	(segment
		(start 343.148666 -290.122356)
		(end 342.133174 -291.137848)
		(width 0.0889)
		(layer "In11.Cu")
		(net "UPI_CPU1_CPU0_P2P2_DN<13>")
	)
	(segment
		(start 99.815396 -283.709364)
		(end 99.81819 -283.70784)
		(width 0.0889)
		(layer "In11.Cu")
		(net "UPI_CPU1_CPU0_P2P2_DN<13>")
	)
	(segment
		(start 313.216544 -324.64375)
		(end 312.174636 -325.372984)
		(width 0.14732)
		(layer "In11.Cu")
		(net "UPI_CPU1_CPU0_P2P2_DN<13>")
	)
	(segment
		(start 339.8012 -299.672756)
		(end 336.369914 -301.093378)
		(width 0.14732)
		(layer "In11.Cu")
		(net "UPI_CPU1_CPU0_P2P2_DN<13>")
	)
	(segment
		(start 67.542918 -334.815688)
		(end 68.187062 -328.278998)
		(width 0.14732)
		(layer "In11.Cu")
		(net "UPI_CPU1_CPU0_P2P2_DN<13>")
	)
	(segment
		(start 96.380554 -291.546788)
		(end 96.380554 -291.496496)
		(width 0.14732)
		(layer "In11.Cu")
		(net "UPI_CPU1_CPU0_P2P2_DN<13>")
	)
	(segment
		(start 343.148666 -288.087562)
		(end 343.148666 -288.103056)
		(width 0.0889)
		(layer "In11.Cu")
		(net "UPI_CPU1_CPU0_P2P2_DN<13>")
	)
	(segment
		(start 265.511026 -367.932716)
		(end 265.250168 -368.193574)
		(width 0.14732)
		(layer "In11.Cu")
		(net "UPI_CPU1_CPU0_P2P2_DN<13>")
	)
	(segment
		(start 260.719824 -372.928642)
		(end 212.927692 -377.111768)
		(width 0.14732)
		(layer "In11.Cu")
		(net "UPI_CPU1_CPU0_P2P2_DN<13>")
	)
	(segment
		(start 96.994472 -285.337758)
		(end 96.995996 -285.336996)
		(width 0.0889)
		(layer "In11.Cu")
		(net "UPI_CPU1_CPU0_P2P2_DN<13>")
	)
	(segment
		(start 343.901014 -286.799782)
		(end 343.900252 -286.80029)
		(width 0.0889)
		(layer "In11.Cu")
		(net "UPI_CPU1_CPU0_P2P2_DN<13>")
	)
	(segment
		(start 342.074246 -291.137848)
		(end 342.058752 -291.153342)
		(width 0.0889)
		(layer "In11.Cu")
		(net "UPI_CPU1_CPU0_P2P2_DN<13>")
	)
	(segment
		(start 97.935796 -285.336996)
		(end 97.938082 -285.335726)
		(width 0.0889)
		(layer "In11.Cu")
		(net "UPI_CPU1_CPU0_P2P2_DN<13>")
	)
	(segment
		(start 341.428324 -294.762428)
		(end 341.542116 -294.932608)
		(width 0.14732)
		(layer "In11.Cu")
		(net "UPI_CPU1_CPU0_P2P2_DN<13>")
	)
	(segment
		(start 267.29436 -366.354106)
		(end 267.089636 -366.354106)
		(width 0.14732)
		(layer "In11.Cu")
		(net "UPI_CPU1_CPU0_P2P2_DN<13>")
	)
	(segment
		(start 203.20762 -376.375422)
		(end 202.93457 -376.036332)
		(width 0.14732)
		(layer "In11.Cu")
		(net "UPI_CPU1_CPU0_P2P2_DN<13>")
	)
	(segment
		(start 341.670386 -294.287194)
		(end 341.499952 -294.400986)
		(width 0.14732)
		(layer "In11.Cu")
		(net "UPI_CPU1_CPU0_P2P2_DN<13>")
	)
	(segment
		(start 265.71575 -367.932716)
		(end 265.511026 -367.932716)
		(width 0.14732)
		(layer "In11.Cu")
		(net "UPI_CPU1_CPU0_P2P2_DN<13>")
	)
	(segment
		(start 345.028266 -281.576526)
		(end 345.028266 -281.59202)
		(width 0.0889)
		(layer "In11.Cu")
		(net "UPI_CPU1_CPU0_P2P2_DN<13>")
	)
	(segment
		(start 266.1031 -367.340642)
		(end 266.1031 -367.545366)
		(width 0.14732)
		(layer "In11.Cu")
		(net "UPI_CPU1_CPU0_P2P2_DN<13>")
	)
	(segment
		(start 200.549764 -377.444762)
		(end 199.96658 -377.537218)
		(width 0.14732)
		(layer "In11.Cu")
		(net "UPI_CPU1_CPU0_P2P2_DN<13>")
	)
	(segment
		(start 97.938082 -285.335726)
		(end 97.940114 -285.334456)
		(width 0.0889)
		(layer "In11.Cu")
		(net "UPI_CPU1_CPU0_P2P2_DN<13>")
	)
	(segment
		(start 97.278698 -286.475424)
		(end 97.278698 -286.467804)
		(width 0.0889)
		(layer "In11.Cu")
		(net "UPI_CPU1_CPU0_P2P2_DN<13>")
	)
	(segment
		(start 341.433912 -295.477184)
		(end 341.263224 -295.590976)
		(width 0.14732)
		(layer "In11.Cu")
		(net "UPI_CPU1_CPU0_P2P2_DN<13>")
	)
	(segment
		(start 342.058752 -291.153342)
		(end 341.828374 -291.38372)
		(width 0.14732)
		(layer "In11.Cu")
		(net "UPI_CPU1_CPU0_P2P2_DN<13>")
	)
	(segment
		(start 312.174636 -325.372984)
		(end 310.847994 -325.372984)
		(width 0.14732)
		(layer "In11.Cu")
		(net "UPI_CPU1_CPU0_P2P2_DN<13>")
	)
	(segment
		(start 96.380808 -297.080686)
		(end 96.380808 -291.547042)
		(width 0.14732)
		(layer "In11.Cu")
		(net "UPI_CPU1_CPU0_P2P2_DN<13>")
	)
	(segment
		(start 342.678766 -288.898584)
		(end 342.678766 -289.114738)
		(width 0.0889)
		(layer "In11.Cu")
		(net "UPI_CPU1_CPU0_P2P2_DN<13>")
	)
	(segment
		(start 308.43728 -327.294748)
		(end 308.189884 -328.697844)
		(width 0.14732)
		(layer "In11.Cu")
		(net "UPI_CPU1_CPU0_P2P2_DN<13>")
	)
	(segment
		(start 342.970104 -288.422334)
		(end 342.961214 -288.427414)
		(width 0.0889)
		(layer "In11.Cu")
		(net "UPI_CPU1_CPU0_P2P2_DN<13>")
	)
	(segment
		(start 78.22438 -314.44311)
		(end 78.850998 -313.816492)
		(width 0.14732)
		(layer "In11.Cu")
		(net "UPI_CPU1_CPU0_P2P2_DN<13>")
	)
	(segment
		(start 343.148412 -289.645852)
		(end 343.148666 -289.64636)
		(width 0.0889)
		(layer "In11.Cu")
		(net "UPI_CPU1_CPU0_P2P2_DN<13>")
	)
	(segment
		(start 206.7306 -376.445526)
		(end 206.391256 -376.718576)
		(width 0.14732)
		(layer "In11.Cu")
		(net "UPI_CPU1_CPU0_P2P2_DN<13>")
	)
	(segment
		(start 266.828778 -366.819688)
		(end 266.568428 -367.080038)
		(width 0.14732)
		(layer "In11.Cu")
		(net "UPI_CPU1_CPU0_P2P2_DN<13>")
	)
	(segment
		(start 340.910926 -298.104052)
		(end 340.91118 -298.104052)
		(width 0.14732)
		(layer "In11.Cu")
		(net "UPI_CPU1_CPU0_P2P2_DN<13>")
	)
	(segment
		(start 343.909904 -285.166816)
		(end 343.901014 -285.171896)
		(width 0.0889)
		(layer "In11.Cu")
		(net "UPI_CPU1_CPU0_P2P2_DN<13>")
	)
	(segment
		(start 205.511908 -376.623834)
		(end 205.238858 -376.28449)
		(width 0.14732)
		(layer "In11.Cu")
		(net "UPI_CPU1_CPU0_P2P2_DN<13>")
	)
	(segment
		(start 96.338898 -288.121598)
		(end 96.338898 -288.103056)
		(width 0.0889)
		(layer "In11.Cu")
		(net "UPI_CPU1_CPU0_P2P2_DN<13>")
	)
	(segment
		(start 171.366434 -380.753112)
		(end 161.701734 -381.59563)
		(width 0.14732)
		(layer "In11.Cu")
		(net "UPI_CPU1_CPU0_P2P2_DN<13>")
	)
	(segment
		(start 345.906598 -281.049222)
		(end 345.817698 -281.072844)
		(width 0.0889)
		(layer "In11.Cu")
		(net "UPI_CPU1_CPU0_P2P2_DN<13>")
	)
	(segment
		(start 199.668638 -376.592338)
		(end 199.316594 -376.336306)
		(width 0.14732)
		(layer "In11.Cu")
		(net "UPI_CPU1_CPU0_P2P2_DN<13>")
	)
	(segment
		(start 344.088212 -286.466788)
		(end 344.088212 -286.48406)
		(width 0.0889)
		(layer "In11.Cu")
		(net "UPI_CPU1_CPU0_P2P2_DN<13>")
	)
	(segment
		(start 206.315056 -377.426474)
		(end 206.153766 -377.556776)
		(width 0.14732)
		(layer "In11.Cu")
		(net "UPI_CPU1_CPU0_P2P2_DN<13>")
	)
	(segment
		(start 70.4469 -322.220844)
		(end 78.224634 -314.44311)
		(width 0.14732)
		(layer "In11.Cu")
		(net "UPI_CPU1_CPU0_P2P2_DN<13>")
	)
	(segment
		(start 265.250168 -368.193574)
		(end 265.250168 -368.398298)
		(width 0.14732)
		(layer "In11.Cu")
		(net "UPI_CPU1_CPU0_P2P2_DN<13>")
	)
	(segment
		(start 266.1031 -367.545366)
		(end 265.71575 -367.932716)
		(width 0.14732)
		(layer "In11.Cu")
		(net "UPI_CPU1_CPU0_P2P2_DN<13>")
	)
	(segment
		(start 99.806506 -283.714444)
		(end 99.813872 -283.710126)
		(width 0.0889)
		(layer "In11.Cu")
		(net "UPI_CPU1_CPU0_P2P2_DN<13>")
	)
	(segment
		(start 285.156402 -331.82179)
		(end 279.526238 -334.153764)
		(width 0.14732)
		(layer "In11.Cu")
		(net "UPI_CPU1_CPU0_P2P2_DN<13>")
	)
	(segment
		(start 200.542144 -376.454162)
		(end 200.672192 -377.276868)
		(width 0.14732)
		(layer "In11.Cu")
		(net "UPI_CPU1_CPU0_P2P2_DN<13>")
	)
	(segment
		(start 279.526238 -334.153764)
		(end 267.93952 -345.740482)
		(width 0.14732)
		(layer "In11.Cu")
		(net "UPI_CPU1_CPU0_P2P2_DN<13>")
	)
	(segment
		(start 98.39706 -284.52826)
		(end 98.40595 -284.52318)
		(width 0.0889)
		(layer "In11.Cu")
		(net "UPI_CPU1_CPU0_P2P2_DN<13>")
	)
	(segment
		(start 96.338644 -291.432488)
		(end 96.338644 -289.60953)
		(width 0.0889)
		(layer "In11.Cu")
		(net "UPI_CPU1_CPU0_P2P2_DN<13>")
	)
	(segment
		(start 341.542116 -294.932608)
		(end 341.433912 -295.477184)
		(width 0.14732)
		(layer "In11.Cu")
		(net "UPI_CPU1_CPU0_P2P2_DN<13>")
	)
	(segment
		(start 200.672192 -377.276868)
		(end 200.549764 -377.444762)
		(width 0.14732)
		(layer "In11.Cu")
		(net "UPI_CPU1_CPU0_P2P2_DN<13>")
	)
	(segment
		(start 344.37955 -284.353)
		(end 344.37066 -284.35808)
		(width 0.0889)
		(layer "In11.Cu")
		(net "UPI_CPU1_CPU0_P2P2_DN<13>")
	)
	(segment
		(start 267.93952 -345.740482)
		(end 267.93952 -365.708946)
		(width 0.14732)
		(layer "In11.Cu")
		(net "UPI_CPU1_CPU0_P2P2_DN<13>")
	)
	(segment
		(start 75.82154 -368.466878)
		(end 71.909686 -364.555024)
		(width 0.14732)
		(layer "In11.Cu")
		(net "UPI_CPU1_CPU0_P2P2_DN<13>")
	)
	(segment
		(start 340.911688 -298.102782)
		(end 340.910926 -298.104052)
		(width 0.14732)
		(layer "In11.Cu")
		(net "UPI_CPU1_CPU0_P2P2_DN<13>")
	)
	(segment
		(start 340.586568 -298.887388)
		(end 339.8012 -299.672756)
		(width 0.14732)
		(layer "In11.Cu")
		(net "UPI_CPU1_CPU0_P2P2_DN<13>")
	)
	(segment
		(start 204.426312 -376.197114)
		(end 204.086968 -376.470164)
		(width 0.14732)
		(layer "In11.Cu")
		(net "UPI_CPU1_CPU0_P2P2_DN<13>")
	)
	(segment
		(start 200.798176 -376.102118)
		(end 200.542144 -376.454162)
		(width 0.14732)
		(layer "In11.Cu")
		(net "UPI_CPU1_CPU0_P2P2_DN<13>")
	)
	(segment
		(start 341.191596 -295.952418)
		(end 341.305134 -296.122852)
		(width 0.14732)
		(layer "In11.Cu")
		(net "UPI_CPU1_CPU0_P2P2_DN<13>")
	)
	(segment
		(start 315.03874 -322.424552)
		(end 315.037978 -322.42506)
		(width 0.14732)
		(layer "In11.Cu")
		(net "UPI_CPU1_CPU0_P2P2_DN<13>")
	)
	(segment
		(start 341.828374 -293.492174)
		(end 341.670386 -294.287194)
		(width 0.14732)
		(layer "In11.Cu")
		(net "UPI_CPU1_CPU0_P2P2_DN<13>")
	)
	(segment
		(start 199.798686 -377.41479)
		(end 199.668638 -376.592338)
		(width 0.14732)
		(layer "In11.Cu")
		(net "UPI_CPU1_CPU0_P2P2_DN<13>")
	)
	(segment
		(start 96.51746 -287.783778)
		(end 96.52635 -287.778698)
		(width 0.0889)
		(layer "In11.Cu")
		(net "UPI_CPU1_CPU0_P2P2_DN<13>")
	)
	(segment
		(start 206.391256 -376.718576)
		(end 206.315056 -377.426474)
		(width 0.14732)
		(layer "In11.Cu")
		(net "UPI_CPU1_CPU0_P2P2_DN<13>")
	)
	(segment
		(start 199.316594 -376.336306)
		(end 171.366434 -380.753112)
		(width 0.14732)
		(layer "In11.Cu")
		(net "UPI_CPU1_CPU0_P2P2_DN<13>")
	)
	(segment
		(start 78.850998 -313.816492)
		(end 94.245176 -301.183802)
		(width 0.14732)
		(layer "In11.Cu")
		(net "UPI_CPU1_CPU0_P2P2_DN<13>")
	)
	(segment
		(start 205.566264 -377.493276)
		(end 205.435708 -377.331224)
		(width 0.14732)
		(layer "In11.Cu")
		(net "UPI_CPU1_CPU0_P2P2_DN<13>")
	)
	(segment
		(start 94.245176 -301.183802)
		(end 95.233236 -299.851826)
		(width 0.14732)
		(layer "In11.Cu")
		(net "UPI_CPU1_CPU0_P2P2_DN<13>")
	)
	(segment
		(start 203.261976 -377.244864)
		(end 203.13142 -377.082812)
		(width 0.14732)
		(layer "In11.Cu")
		(net "UPI_CPU1_CPU0_P2P2_DN<13>")
	)
	(segment
		(start 343.43975 -287.608518)
		(end 343.43086 -287.613598)
		(width 0.0889)
		(layer "In11.Cu")
		(net "UPI_CPU1_CPU0_P2P2_DN<13>")
	)
	(segment
		(start 315.037978 -322.42506)
		(end 314.143136 -323.320156)
		(width 0.14732)
		(layer "In11.Cu")
		(net "UPI_CPU1_CPU0_P2P2_DN<13>")
	)
	(segment
		(start 267.93952 -365.708946)
		(end 267.29436 -366.354106)
		(width 0.14732)
		(layer "In11.Cu")
		(net "UPI_CPU1_CPU0_P2P2_DN<13>")
	)
	(segment
		(start 344.840814 -281.916378)
		(end 344.834718 -281.919934)
		(width 0.0889)
		(layer "In11.Cu")
		(net "UPI_CPU1_CPU0_P2P2_DN<13>")
	)
	(segment
		(start 161.701734 -381.59563)
		(end 125.82144 -381.59563)
		(width 0.14732)
		(layer "In11.Cu")
		(net "UPI_CPU1_CPU0_P2P2_DN<13>")
	)
	(segment
		(start 309.426864 -326.076564)
		(end 308.97068 -326.532748)
		(width 0.14732)
		(layer "In11.Cu")
		(net "UPI_CPU1_CPU0_P2P2_DN<13>")
	)
	(segment
		(start 203.13142 -377.082812)
		(end 203.20762 -376.375422)
		(width 0.14732)
		(layer "In11.Cu")
		(net "UPI_CPU1_CPU0_P2P2_DN<13>")
	)
	(segment
		(start 78.224634 -314.44311)
		(end 78.22438 -314.44311)
		(width 0.14732)
		(layer "In11.Cu")
		(net "UPI_CPU1_CPU0_P2P2_DN<13>")
	)
	(segment
		(start 343.618312 -285.661354)
		(end 343.618312 -285.675578)
		(width 0.0889)
		(layer "In11.Cu")
		(net "UPI_CPU1_CPU0_P2P2_DN<13>")
	)
	(segment
		(start 341.828374 -291.38372)
		(end 341.828374 -293.492174)
		(width 0.14732)
		(layer "In11.Cu")
		(net "UPI_CPU1_CPU0_P2P2_DN<13>")
	)
	(segment
		(start 96.380554 -291.496496)
		(end 96.380554 -291.474398)
		(width 0.0889)
		(layer "In11.Cu")
		(net "UPI_CPU1_CPU0_P2P2_DN<13>")
	)
	(segment
		(start 205.435708 -377.331224)
		(end 205.511908 -376.623834)
		(width 0.14732)
		(layer "In11.Cu")
		(net "UPI_CPU1_CPU0_P2P2_DN<13>")
	)
	(segment
		(start 96.987106 -285.342076)
		(end 96.994472 -285.337758)
		(width 0.0889)
		(layer "In11.Cu")
		(net "UPI_CPU1_CPU0_P2P2_DN<13>")
	)
	(segment
		(start 345.028012 -283.21127)
		(end 345.028012 -283.228542)
		(width 0.0889)
		(layer "In11.Cu")
		(net "UPI_CPU1_CPU0_P2P2_DN<13>")
	)
	(segment
		(start 69.040756 -325.19366)
		(end 70.4469 -322.220844)
		(width 0.14732)
		(layer "In11.Cu")
		(net "UPI_CPU1_CPU0_P2P2_DN<13>")
	)
	(segment
		(start 308.97068 -326.532748)
		(end 308.43728 -327.294748)
		(width 0.14732)
		(layer "In11.Cu")
		(net "UPI_CPU1_CPU0_P2P2_DN<13>")
	)
	(segment
		(start 204.086968 -376.470164)
		(end 204.010768 -377.178062)
		(width 0.14732)
		(layer "In11.Cu")
		(net "UPI_CPU1_CPU0_P2P2_DN<13>")
	)
	(segment
		(start 68.187062 -328.278998)
		(end 69.040756 -325.19366)
		(width 0.14732)
		(layer "In11.Cu")
		(net "UPI_CPU1_CPU0_P2P2_DN<13>")
	)
	(segment
		(start 308.189884 -328.697844)
		(end 308.189884 -329.859894)
		(width 0.14732)
		(layer "In11.Cu")
		(net "UPI_CPU1_CPU0_P2P2_DN<13>")
	)
	(segment
		(start 99.81819 -283.70784)
		(end 99.821492 -283.705808)
		(width 0.0889)
		(layer "In11.Cu")
		(net "UPI_CPU1_CPU0_P2P2_DN<13>")
	)
	(segment
		(start 309.879746 -325.77405)
		(end 309.426864 -326.076564)
		(width 0.14732)
		(layer "In11.Cu")
		(net "UPI_CPU1_CPU0_P2P2_DN<13>")
	)
	(segment
		(start 201.912728 -375.925842)
		(end 200.798176 -376.102118)
		(width 0.14732)
		(layer "In11.Cu")
		(net "UPI_CPU1_CPU0_P2P2_DN<13>")
	)
	(segment
		(start 310.847994 -325.372984)
		(end 309.879746 -325.77405)
		(width 0.14732)
		(layer "In11.Cu")
		(net "UPI_CPU1_CPU0_P2P2_DN<13>")
	)
	(arc
		(start 99.34575 -284.52318)
		(mid 99.548573 -284.322949)
		(end 99.627944 -284.049216)
		(width 0.0889)
		(layer "In11.Cu")
		(net "UPI_CPU1_CPU0_P2P2_DN<13>")
	)
	(arc
		(start 344.840814 -282.895548)
		(mid 344.975747 -283.028902)
		(end 345.028012 -283.21127)
		(width 0.0889)
		(layer "In11.Cu")
		(net "UPI_CPU1_CPU0_P2P2_DN<13>")
	)
	(arc
		(start 344.834718 -281.919934)
		(mid 344.632131 -282.126285)
		(end 344.558112 -282.405836)
		(width 0.0889)
		(layer "In11.Cu")
		(net "UPI_CPU1_CPU0_P2P2_DN<13>")
	)
	(arc
		(start 96.053148 -289.277806)
		(mid 95.944001 -289.193878)
		(end 95.868998 -289.078416)
		(width 0.0889)
		(layer "In11.Cu")
		(net "UPI_CPU1_CPU0_P2P2_DN<13>")
	)
	(arc
		(start 97.278698 -286.467804)
		(mid 97.201069 -286.189391)
		(end 96.995996 -285.985712)
		(width 0.0889)
		(layer "In11.Cu")
		(net "UPI_CPU1_CPU0_P2P2_DN<13>")
	)
	(arc
		(start 97.370392 -285.336996)
		(mid 97.644591 -285.412831)
		(end 97.921064 -285.345632)
		(width 0.0889)
		(layer "In11.Cu")
		(net "UPI_CPU1_CPU0_P2P2_DN<13>")
	)
	(arc
		(start 344.088212 -286.48406)
		(mid 344.035942 -286.666425)
		(end 343.901014 -286.799782)
		(width 0.0889)
		(layer "In11.Cu")
		(net "UPI_CPU1_CPU0_P2P2_DN<13>")
	)
	(arc
		(start 98.40595 -284.52318)
		(mid 98.593148 -284.473037)
		(end 98.780346 -284.52318)
		(width 0.0889)
		(layer "In11.Cu")
		(net "UPI_CPU1_CPU0_P2P2_DN<13>")
	)
	(arc
		(start 342.964262 -289.446462)
		(mid 343.073409 -289.53039)
		(end 343.148412 -289.645852)
		(width 0.0889)
		(layer "In11.Cu")
		(net "UPI_CPU1_CPU0_P2P2_DN<13>")
	)
	(arc
		(start 345.817698 -281.072844)
		(mid 345.807957 -281.068689)
		(end 345.79814 -281.064716)
		(width 0.0889)
		(layer "In11.Cu")
		(net "UPI_CPU1_CPU0_P2P2_DN<13>")
	)
	(arc
		(start 343.148666 -288.103056)
		(mid 343.100987 -288.285956)
		(end 342.970104 -288.422334)
		(width 0.0889)
		(layer "In11.Cu")
		(net "UPI_CPU1_CPU0_P2P2_DN<13>")
	)
	(arc
		(start 343.618312 -287.28924)
		(mid 343.570633 -287.47214)
		(end 343.43975 -287.608518)
		(width 0.0889)
		(layer "In11.Cu")
		(net "UPI_CPU1_CPU0_P2P2_DN<13>")
	)
	(arc
		(start 344.088466 -284.847538)
		(mid 344.040787 -285.030438)
		(end 343.909904 -285.166816)
		(width 0.0889)
		(layer "In11.Cu")
		(net "UPI_CPU1_CPU0_P2P2_DN<13>")
	)
	(arc
		(start 343.618312 -285.675578)
		(mid 343.697531 -285.950263)
		(end 343.901014 -286.151066)
		(width 0.0889)
		(layer "In11.Cu")
		(net "UPI_CPU1_CPU0_P2P2_DN<13>")
	)
	(arc
		(start 96.995996 -285.336996)
		(mid 97.183194 -285.286853)
		(end 97.370392 -285.336996)
		(width 0.0889)
		(layer "In11.Cu")
		(net "UPI_CPU1_CPU0_P2P2_DN<13>")
	)
	(arc
		(start 96.338644 -289.60953)
		(mid 96.227306 -289.41663)
		(end 96.053148 -289.277806)
		(width 0.0889)
		(layer "In11.Cu")
		(net "UPI_CPU1_CPU0_P2P2_DN<13>")
	)
	(arc
		(start 96.987106 -285.980632)
		(mid 96.808509 -285.661354)
		(end 96.987106 -285.342076)
		(width 0.0889)
		(layer "In11.Cu")
		(net "UPI_CPU1_CPU0_P2P2_DN<13>")
	)
	(arc
		(start 96.808544 -287.28924)
		(mid 96.856223 -287.10634)
		(end 96.987106 -286.969962)
		(width 0.0889)
		(layer "In11.Cu")
		(net "UPI_CPU1_CPU0_P2P2_DN<13>")
	)
	(arc
		(start 342.961214 -288.427414)
		(mid 342.758928 -288.626395)
		(end 342.678766 -288.898584)
		(width 0.0889)
		(layer "In11.Cu")
		(net "UPI_CPU1_CPU0_P2P2_DN<13>")
	)
	(arc
		(start 344.558112 -284.033722)
		(mid 344.510433 -284.216622)
		(end 344.37955 -284.353)
		(width 0.0889)
		(layer "In11.Cu")
		(net "UPI_CPU1_CPU0_P2P2_DN<13>")
	)
	(arc
		(start 344.834718 -283.54782)
		(mid 344.632131 -283.754171)
		(end 344.558112 -284.033722)
		(width 0.0889)
		(layer "In11.Cu")
		(net "UPI_CPU1_CPU0_P2P2_DN<13>")
	)
	(arc
		(start 345.028266 -281.59202)
		(mid 344.980587 -281.77492)
		(end 344.849704 -281.911298)
		(width 0.0889)
		(layer "In11.Cu")
		(net "UPI_CPU1_CPU0_P2P2_DN<13>")
	)
	(arc
		(start 343.43086 -287.613598)
		(mid 343.228037 -287.813829)
		(end 343.148666 -288.087562)
		(width 0.0889)
		(layer "In11.Cu")
		(net "UPI_CPU1_CPU0_P2P2_DN<13>")
	)
	(arc
		(start 343.894918 -285.175452)
		(mid 343.692331 -285.381803)
		(end 343.618312 -285.661354)
		(width 0.0889)
		(layer "In11.Cu")
		(net "UPI_CPU1_CPU0_P2P2_DN<13>")
	)
	(arc
		(start 97.941892 -285.33344)
		(mid 98.144479 -285.127089)
		(end 98.218498 -284.847538)
		(width 0.0889)
		(layer "In11.Cu")
		(net "UPI_CPU1_CPU0_P2P2_DN<13>")
	)
	(arc
		(start 99.627944 -284.033722)
		(mid 99.675623 -283.850822)
		(end 99.806506 -283.714444)
		(width 0.0889)
		(layer "In11.Cu")
		(net "UPI_CPU1_CPU0_P2P2_DN<13>")
	)
	(arc
		(start 99.821492 -283.705808)
		(mid 100.024079 -283.499457)
		(end 100.098098 -283.219906)
		(width 0.0889)
		(layer "In11.Cu")
		(net "UPI_CPU1_CPU0_P2P2_DN<13>")
	)
	(arc
		(start 98.218498 -284.847538)
		(mid 98.266177 -284.664638)
		(end 98.39706 -284.52826)
		(width 0.0889)
		(layer "In11.Cu")
		(net "UPI_CPU1_CPU0_P2P2_DN<13>")
	)
	(arc
		(start 342.678766 -289.114738)
		(mid 342.790104 -289.307638)
		(end 342.964262 -289.446462)
		(width 0.0889)
		(layer "In11.Cu")
		(net "UPI_CPU1_CPU0_P2P2_DN<13>")
	)
	(arc
		(start 96.52635 -287.778698)
		(mid 96.729173 -287.578467)
		(end 96.808544 -287.304734)
		(width 0.0889)
		(layer "In11.Cu")
		(net "UPI_CPU1_CPU0_P2P2_DN<13>")
	)
	(arc
		(start 97.008188 -286.95777)
		(mid 97.206416 -286.751922)
		(end 97.278698 -286.475424)
		(width 0.0889)
		(layer "In11.Cu")
		(net "UPI_CPU1_CPU0_P2P2_DN<13>")
	)
	(arc
		(start 343.901014 -286.151066)
		(mid 344.035947 -286.28442)
		(end 344.088212 -286.466788)
		(width 0.0889)
		(layer "In11.Cu")
		(net "UPI_CPU1_CPU0_P2P2_DN<13>")
	)
	(arc
		(start 96.338898 -288.103056)
		(mid 96.386577 -287.920156)
		(end 96.51746 -287.783778)
		(width 0.0889)
		(layer "In11.Cu")
		(net "UPI_CPU1_CPU0_P2P2_DN<13>")
	)
	(arc
		(start 344.558112 -282.42006)
		(mid 344.637331 -282.694745)
		(end 344.840814 -282.895548)
		(width 0.0889)
		(layer "In11.Cu")
		(net "UPI_CPU1_CPU0_P2P2_DN<13>")
	)
	(arc
		(start 345.31046 -281.102562)
		(mid 345.107637 -281.302793)
		(end 345.028266 -281.576526)
		(width 0.0889)
		(layer "In11.Cu")
		(net "UPI_CPU1_CPU0_P2P2_DN<13>")
	)
	(arc
		(start 344.37066 -284.35808)
		(mid 344.167837 -284.558311)
		(end 344.088466 -284.832044)
		(width 0.0889)
		(layer "In11.Cu")
		(net "UPI_CPU1_CPU0_P2P2_DN<13>")
	)
	(arc
		(start 96.05645 -288.592768)
		(mid 96.258736 -288.393787)
		(end 96.338898 -288.121598)
		(width 0.0889)
		(layer "In11.Cu")
		(net "UPI_CPU1_CPU0_P2P2_DN<13>")
	)
	(arc
		(start 345.028012 -283.228542)
		(mid 344.975742 -283.410907)
		(end 344.840814 -283.544264)
		(width 0.0889)
		(layer "In11.Cu")
		(net "UPI_CPU1_CPU0_P2P2_DN<13>")
	)
	(arc
		(start 99.887278 -282.778962)
		(mid 99.87883 -282.772405)
		(end 99.87026 -282.766008)
		(width 0.0889)
		(layer "In11.Cu")
		(net "UPI_CPU1_CPU0_P2P2_DN<13>")
	)
	(arc
		(start 100.098098 -283.205682)
		(mid 100.039804 -282.969039)
		(end 99.887278 -282.778962)
		(width 0.0889)
		(layer "In11.Cu")
		(net "UPI_CPU1_CPU0_P2P2_DN<13>")
	)
	(arc
		(start 345.79814 -281.064716)
		(mid 345.549987 -281.028117)
		(end 345.31046 -281.102562)
		(width 0.0889)
		(layer "In11.Cu")
		(net "UPI_CPU1_CPU0_P2P2_DN<13>")
	)
	(arc
		(start 98.795078 -284.531816)
		(mid 99.071553 -284.599136)
		(end 99.34575 -284.52318)
		(width 0.0889)
		(layer "In11.Cu")
		(net "UPI_CPU1_CPU0_P2P2_DN<13>")
	)
	(arc
		(start 95.868998 -288.917126)
		(mid 95.916677 -288.734226)
		(end 96.04756 -288.597848)
		(width 0.0889)
		(layer "In11.Cu")
		(net "UPI_CPU1_CPU0_P2P2_DN<13>")
	)
	(arc
		(start 343.894918 -286.803338)
		(mid 343.692331 -287.009689)
		(end 343.618312 -287.28924)
		(width 0.0889)
		(layer "In11.Cu")
		(net "UPI_CPU1_CPU0_P2P2_DN<13>")
	)
	(segment
		(start 99.532694 -281.05608)
		(end 99.532694 -281.591766)
		(width 0.13208)
		(layer "F.Cu")
		(net "UPI_CPU1_CPU0_P2P2_DN<12>")
	)
	(segment
		(start 99.532694 -281.591766)
		(end 99.532948 -281.59202)
		(width 0.13208)
		(layer "F.Cu")
		(net "UPI_CPU1_CPU0_P2P2_DN<12>")
	)
	(segment
		(start 346.063316 -282.405582)
		(end 346.063062 -282.405836)
		(width 0.13208)
		(layer "F.Cu")
		(net "UPI_CPU1_CPU0_P2P2_DN<12>")
	)
	(segment
		(start 346.063316 -281.869896)
		(end 346.063316 -282.405582)
		(width 0.13208)
		(layer "F.Cu")
		(net "UPI_CPU1_CPU0_P2P2_DN<12>")
	)
	(segment
		(start 315.039756 -323.986652)
		(end 336.992214 -302.034194)
		(width 0.14732)
		(layer "In11.Cu")
		(net "UPI_CPU1_CPU0_P2P2_DN<12>")
	)
	(segment
		(start 70.970902 -365.179356)
		(end 75.242166 -369.45062)
		(width 0.14732)
		(layer "In11.Cu")
		(net "UPI_CPU1_CPU0_P2P2_DN<12>")
	)
	(segment
		(start 180.102764 -380.496572)
		(end 180.691028 -380.44628)
		(width 0.14732)
		(layer "In11.Cu")
		(net "UPI_CPU1_CPU0_P2P2_DN<12>")
	)
	(segment
		(start 343.809066 -289.078416)
		(end 343.809066 -288.917126)
		(width 0.0889)
		(layer "In11.Cu")
		(net "UPI_CPU1_CPU0_P2P2_DN<12>")
	)
	(segment
		(start 193.823336 -379.474222)
		(end 193.957448 -379.315472)
		(width 0.14732)
		(layer "In11.Cu")
		(net "UPI_CPU1_CPU0_P2P2_DN<12>")
	)
	(segment
		(start 181.200552 -381.068072)
		(end 182.014876 -380.998476)
		(width 0.14732)
		(layer "In11.Cu")
		(net "UPI_CPU1_CPU0_P2P2_DN<12>")
	)
	(segment
		(start 198.575676 -378.921772)
		(end 199.16394 -378.87148)
		(width 0.14732)
		(layer "In11.Cu")
		(net "UPI_CPU1_CPU0_P2P2_DN<12>")
	)
	(segment
		(start 198.459344 -379.287532)
		(end 198.441564 -379.080522)
		(width 0.14732)
		(layer "In11.Cu")
		(net "UPI_CPU1_CPU0_P2P2_DN<12>")
	)
	(segment
		(start 94.738698 -288.898584)
		(end 94.738698 -289.114738)
		(width 0.0889)
		(layer "In11.Cu")
		(net "UPI_CPU1_CPU0_P2P2_DN<12>")
	)
	(segment
		(start 343.20099 -291.859716)
		(end 343.20099 -291.506656)
		(width 0.14732)
		(layer "In11.Cu")
		(net "UPI_CPU1_CPU0_P2P2_DN<12>")
	)
	(segment
		(start 344.936064 -285.985712)
		(end 344.927174 -285.980632)
		(width 0.0889)
		(layer "In11.Cu")
		(net "UPI_CPU1_CPU0_P2P2_DN<12>")
	)
	(segment
		(start 343.200736 -293.230808)
		(end 343.200736 -291.85997)
		(width 0.14732)
		(layer "In11.Cu")
		(net "UPI_CPU1_CPU0_P2P2_DN<12>")
	)
	(segment
		(start 179.705762 -381.195326)
		(end 179.986432 -380.862332)
		(width 0.14732)
		(layer "In11.Cu")
		(net "UPI_CPU1_CPU0_P2P2_DN<12>")
	)
	(segment
		(start 345.866974 -283.714444)
		(end 345.875864 -283.709364)
		(width 0.0889)
		(layer "In11.Cu")
		(net "UPI_CPU1_CPU0_P2P2_DN<12>")
	)
	(segment
		(start 67.556126 -326.417686)
		(end 67.095116 -328.083418)
		(width 0.14732)
		(layer "In11.Cu")
		(net "UPI_CPU1_CPU0_P2P2_DN<12>")
	)
	(segment
		(start 99.258882 -282.725114)
		(end 99.249992 -282.730194)
		(width 0.0889)
		(layer "In11.Cu")
		(net "UPI_CPU1_CPU0_P2P2_DN<12>")
	)
	(segment
		(start 344.278966 -288.121598)
		(end 344.278966 -288.103056)
		(width 0.0889)
		(layer "In11.Cu")
		(net "UPI_CPU1_CPU0_P2P2_DN<12>")
	)
	(segment
		(start 196.266562 -379.118622)
		(end 196.854826 -379.06833)
		(width 0.14732)
		(layer "In11.Cu")
		(net "UPI_CPU1_CPU0_P2P2_DN<12>")
	)
	(segment
		(start 345.692984 -282.46324)
		(end 345.750388 -282.405836)
		(width 0.0889)
		(layer "In11.Cu")
		(net "UPI_CPU1_CPU0_P2P2_DN<12>")
	)
	(segment
		(start 183.509666 -380.871222)
		(end 184.32399 -380.801626)
		(width 0.14732)
		(layer "In11.Cu")
		(net "UPI_CPU1_CPU0_P2P2_DN<12>")
	)
	(segment
		(start 191.514222 -379.671072)
		(end 191.648334 -379.512322)
		(width 0.14732)
		(layer "In11.Cu")
		(net "UPI_CPU1_CPU0_P2P2_DN<12>")
	)
	(segment
		(start 99.723448 -281.914346)
		(end 99.72167 -281.915362)
		(width 0.0889)
		(layer "In11.Cu")
		(net "UPI_CPU1_CPU0_P2P2_DN<12>")
	)
	(segment
		(start 199.67321 -379.493272)
		(end 261.028942 -374.267222)
		(width 0.14732)
		(layer "In11.Cu")
		(net "UPI_CPU1_CPU0_P2P2_DN<12>")
	)
	(segment
		(start 343.20099 -291.484558)
		(end 343.158826 -291.442394)
		(width 0.0889)
		(layer "In11.Cu")
		(net "UPI_CPU1_CPU0_P2P2_DN<12>")
	)
	(segment
		(start 307.656738 -332.92415)
		(end 313.940444 -326.640444)
		(width 0.14732)
		(layer "In11.Cu")
		(net "UPI_CPU1_CPU0_P2P2_DN<12>")
	)
	(segment
		(start 194.545712 -379.26518)
		(end 194.704462 -379.399292)
		(width 0.14732)
		(layer "In11.Cu")
		(net "UPI_CPU1_CPU0_P2P2_DN<12>")
	)
	(segment
		(start 343.158826 -291.306758)
		(end 344.278712 -290.186872)
		(width 0.0889)
		(layer "In11.Cu")
		(net "UPI_CPU1_CPU0_P2P2_DN<12>")
	)
	(segment
		(start 99.532948 -281.59202)
		(end 99.845622 -281.59202)
		(width 0.0889)
		(layer "In11.Cu")
		(net "UPI_CPU1_CPU0_P2P2_DN<12>")
	)
	(segment
		(start 344.457528 -287.783778)
		(end 344.466418 -287.778698)
		(width 0.0889)
		(layer "In11.Cu")
		(net "UPI_CPU1_CPU0_P2P2_DN<12>")
	)
	(segment
		(start 93.952822 -299.72635)
		(end 93.440758 -300.416722)
		(width 0.14732)
		(layer "In11.Cu")
		(net "UPI_CPU1_CPU0_P2P2_DN<12>")
	)
	(segment
		(start 193.560446 -380.014226)
		(end 193.841116 -379.681232)
		(width 0.14732)
		(layer "In11.Cu")
		(net "UPI_CPU1_CPU0_P2P2_DN<12>")
	)
	(segment
		(start 342.202262 -298.225718)
		(end 342.202008 -298.225718)
		(width 0.14732)
		(layer "In11.Cu")
		(net "UPI_CPU1_CPU0_P2P2_DN<12>")
	)
	(segment
		(start 95.96247 -285.17088)
		(end 95.95485 -285.175452)
		(width 0.0889)
		(layer "In11.Cu")
		(net "UPI_CPU1_CPU0_P2P2_DN<12>")
	)
	(segment
		(start 180.867812 -380.787402)
		(end 181.200552 -381.068072)
		(width 0.14732)
		(layer "In11.Cu")
		(net "UPI_CPU1_CPU0_P2P2_DN<12>")
	)
	(segment
		(start 95.166434 -296.795952)
		(end 93.952822 -299.72635)
		(width 0.14732)
		(layer "In11.Cu")
		(net "UPI_CPU1_CPU0_P2P2_DN<12>")
	)
	(segment
		(start 180.849778 -380.580392)
		(end 180.867812 -380.787402)
		(width 0.14732)
		(layer "In11.Cu")
		(net "UPI_CPU1_CPU0_P2P2_DN<12>")
	)
	(segment
		(start 190.104268 -380.000002)
		(end 190.437008 -380.280672)
		(width 0.14732)
		(layer "In11.Cu")
		(net "UPI_CPU1_CPU0_P2P2_DN<12>")
	)
	(segment
		(start 198.441564 -379.080522)
		(end 198.575676 -378.921772)
		(width 0.14732)
		(layer "In11.Cu")
		(net "UPI_CPU1_CPU0_P2P2_DN<12>")
	)
	(segment
		(start 66.435478 -334.78343)
		(end 66.435478 -354.229162)
		(width 0.14732)
		(layer "In11.Cu")
		(net "UPI_CPU1_CPU0_P2P2_DN<12>")
	)
	(segment
		(start 198.178674 -379.620526)
		(end 198.459344 -379.287532)
		(width 0.14732)
		(layer "In11.Cu")
		(net "UPI_CPU1_CPU0_P2P2_DN<12>")
	)
	(segment
		(start 95.960946 -286.799782)
		(end 95.960184 -286.80029)
		(width 0.0889)
		(layer "In11.Cu")
		(net "UPI_CPU1_CPU0_P2P2_DN<12>")
	)
	(segment
		(start 343.987628 -288.597848)
		(end 343.996518 -288.592768)
		(width 0.0889)
		(layer "In11.Cu")
		(net "UPI_CPU1_CPU0_P2P2_DN<12>")
	)
	(segment
		(start 344.927174 -286.969962)
		(end 344.936064 -286.964882)
		(width 0.0889)
		(layer "In11.Cu")
		(net "UPI_CPU1_CPU0_P2P2_DN<12>")
	)
	(segment
		(start 344.278712 -290.186872)
		(end 344.278712 -289.60953)
		(width 0.0889)
		(layer "In11.Cu")
		(net "UPI_CPU1_CPU0_P2P2_DN<12>")
	)
	(segment
		(start 99.729036 -281.911044)
		(end 99.724972 -281.91333)
		(width 0.0889)
		(layer "In11.Cu")
		(net "UPI_CPU1_CPU0_P2P2_DN<12>")
	)
	(segment
		(start 69.50964 -321.595496)
		(end 68.01739 -324.751954)
		(width 0.14732)
		(layer "In11.Cu")
		(net "UPI_CPU1_CPU0_P2P2_DN<12>")
	)
	(segment
		(start 187.61837 -379.85573)
		(end 187.77712 -379.989842)
		(width 0.14732)
		(layer "In11.Cu")
		(net "UPI_CPU1_CPU0_P2P2_DN<12>")
	)
	(segment
		(start 344.936064 -286.964882)
		(end 344.948256 -286.95777)
		(width 0.0889)
		(layer "In11.Cu")
		(net "UPI_CPU1_CPU0_P2P2_DN<12>")
	)
	(segment
		(start 193.841116 -379.681232)
		(end 193.823336 -379.474222)
		(width 0.14732)
		(layer "In11.Cu")
		(net "UPI_CPU1_CPU0_P2P2_DN<12>")
	)
	(segment
		(start 190.437008 -380.280672)
		(end 191.251332 -380.211076)
		(width 0.14732)
		(layer "In11.Cu")
		(net "UPI_CPU1_CPU0_P2P2_DN<12>")
	)
	(segment
		(start 261.028942 -374.267222)
		(end 261.120382 -374.267222)
		(width 0.14732)
		(layer "In11.Cu")
		(net "UPI_CPU1_CPU0_P2P2_DN<12>")
	)
	(segment
		(start 95.965772 -285.168848)
		(end 95.964248 -285.169864)
		(width 0.0889)
		(layer "In11.Cu")
		(net "UPI_CPU1_CPU0_P2P2_DN<12>")
	)
	(segment
		(start 95.208598 -288.087562)
		(end 95.208598 -288.103056)
		(width 0.0889)
		(layer "In11.Cu")
		(net "UPI_CPU1_CPU0_P2P2_DN<12>")
	)
	(segment
		(start 68.01739 -324.751954)
		(end 67.556126 -326.417686)
		(width 0.14732)
		(layer "In11.Cu")
		(net "UPI_CPU1_CPU0_P2P2_DN<12>")
	)
	(segment
		(start 344.936064 -285.336996)
		(end 344.94216 -285.33344)
		(width 0.0889)
		(layer "In11.Cu")
		(net "UPI_CPU1_CPU0_P2P2_DN<12>")
	)
	(segment
		(start 187.030106 -379.906022)
		(end 187.61837 -379.85573)
		(width 0.14732)
		(layer "In11.Cu")
		(net "UPI_CPU1_CPU0_P2P2_DN<12>")
	)
	(segment
		(start 182.277766 -380.458472)
		(end 182.411878 -380.299722)
		(width 0.14732)
		(layer "In11.Cu")
		(net "UPI_CPU1_CPU0_P2P2_DN<12>")
	)
	(segment
		(start 192.746122 -380.083822)
		(end 193.560446 -380.014226)
		(width 0.14732)
		(layer "In11.Cu")
		(net "UPI_CPU1_CPU0_P2P2_DN<12>")
	)
	(segment
		(start 95.166434 -290.774628)
		(end 95.166434 -290.796726)
		(width 0.0889)
		(layer "In11.Cu")
		(net "UPI_CPU1_CPU0_P2P2_DN<12>")
	)
	(segment
		(start 182.295546 -380.665482)
		(end 182.277766 -380.458472)
		(width 0.14732)
		(layer "In11.Cu")
		(net "UPI_CPU1_CPU0_P2P2_DN<12>")
	)
	(segment
		(start 269.3797 -345.894152)
		(end 280.159968 -335.113884)
		(width 0.14732)
		(layer "In11.Cu")
		(net "UPI_CPU1_CPU0_P2P2_DN<12>")
	)
	(segment
		(start 280.159968 -335.113884)
		(end 285.44647 -332.92415)
		(width 0.14732)
		(layer "In11.Cu")
		(net "UPI_CPU1_CPU0_P2P2_DN<12>")
	)
	(segment
		(start 95.969836 -285.166816)
		(end 95.969836 -285.166562)
		(width 0.0889)
		(layer "In11.Cu")
		(net "UPI_CPU1_CPU0_P2P2_DN<12>")
	)
	(segment
		(start 185.309256 -380.05258)
		(end 185.468006 -380.186692)
		(width 0.14732)
		(layer "In11.Cu")
		(net "UPI_CPU1_CPU0_P2P2_DN<12>")
	)
	(segment
		(start 97.379282 -284.353)
		(end 97.370392 -284.35808)
		(width 0.0889)
		(layer "In11.Cu")
		(net "UPI_CPU1_CPU0_P2P2_DN<12>")
	)
	(segment
		(start 340.417658 -300.616112)
		(end 341.774018 -299.259752)
		(width 0.14732)
		(layer "In11.Cu")
		(net "UPI_CPU1_CPU0_P2P2_DN<12>")
	)
	(segment
		(start 186.895994 -380.064772)
		(end 187.030106 -379.906022)
		(width 0.14732)
		(layer "In11.Cu")
		(net "UPI_CPU1_CPU0_P2P2_DN<12>")
	)
	(segment
		(start 199.340724 -379.212602)
		(end 199.67321 -379.493272)
		(width 0.14732)
		(layer "In11.Cu")
		(net "UPI_CPU1_CPU0_P2P2_DN<12>")
	)
	(segment
		(start 343.158826 -291.442394)
		(end 343.158826 -291.306758)
		(width 0.0889)
		(layer "In11.Cu")
		(net "UPI_CPU1_CPU0_P2P2_DN<12>")
	)
	(segment
		(start 199.16394 -378.87148)
		(end 199.32269 -379.005592)
		(width 0.14732)
		(layer "In11.Cu")
		(net "UPI_CPU1_CPU0_P2P2_DN<12>")
	)
	(segment
		(start 261.120382 -374.267222)
		(end 269.3797 -366.007904)
		(width 0.14732)
		(layer "In11.Cu")
		(net "UPI_CPU1_CPU0_P2P2_DN<12>")
	)
	(segment
		(start 197.013576 -379.202442)
		(end 197.03161 -379.409452)
		(width 0.14732)
		(layer "In11.Cu")
		(net "UPI_CPU1_CPU0_P2P2_DN<12>")
	)
	(segment
		(start 343.200736 -291.85997)
		(end 343.20099 -291.859716)
		(width 0.14732)
		(layer "In11.Cu")
		(net "UPI_CPU1_CPU0_P2P2_DN<12>")
	)
	(segment
		(start 95.024194 -289.446462)
		(end 95.024194 -289.446208)
		(width 0.0889)
		(layer "In11.Cu")
		(net "UPI_CPU1_CPU0_P2P2_DN<12>")
	)
	(segment
		(start 186.633104 -380.604776)
		(end 186.913774 -380.271782)
		(width 0.14732)
		(layer "In11.Cu")
		(net "UPI_CPU1_CPU0_P2P2_DN<12>")
	)
	(segment
		(start 179.986432 -380.862332)
		(end 179.968652 -380.655322)
		(width 0.14732)
		(layer "In11.Cu")
		(net "UPI_CPU1_CPU0_P2P2_DN<12>")
	)
	(segment
		(start 186.913774 -380.271782)
		(end 186.895994 -380.064772)
		(width 0.14732)
		(layer "In11.Cu")
		(net "UPI_CPU1_CPU0_P2P2_DN<12>")
	)
	(segment
		(start 345.875864 -282.730194)
		(end 345.866974 -282.725114)
		(width 0.0889)
		(layer "In11.Cu")
		(net "UPI_CPU1_CPU0_P2P2_DN<12>")
	)
	(segment
		(start 285.44647 -332.92415)
		(end 307.656738 -332.92415)
		(width 0.14732)
		(layer "In11.Cu")
		(net "UPI_CPU1_CPU0_P2P2_DN<12>")
	)
	(segment
		(start 188.127894 -380.477522)
		(end 188.942218 -380.407926)
		(width 0.14732)
		(layer "In11.Cu")
		(net "UPI_CPU1_CPU0_P2P2_DN<12>")
	)
	(segment
		(start 344.748612 -287.304734)
		(end 344.748612 -287.28924)
		(width 0.0889)
		(layer "In11.Cu")
		(net "UPI_CPU1_CPU0_P2P2_DN<12>")
	)
	(segment
		(start 191.532002 -379.878082)
		(end 191.514222 -379.671072)
		(width 0.14732)
		(layer "In11.Cu")
		(net "UPI_CPU1_CPU0_P2P2_DN<12>")
	)
	(segment
		(start 189.33922 -379.709172)
		(end 189.927484 -379.65888)
		(width 0.14732)
		(layer "In11.Cu")
		(net "UPI_CPU1_CPU0_P2P2_DN<12>")
	)
	(segment
		(start 345.397328 -284.52826)
		(end 345.406218 -284.52318)
		(width 0.0889)
		(layer "In11.Cu")
		(net "UPI_CPU1_CPU0_P2P2_DN<12>")
	)
	(segment
		(start 162.019742 -382.699768)
		(end 179.705762 -381.195326)
		(width 0.14732)
		(layer "In11.Cu")
		(net "UPI_CPU1_CPU0_P2P2_DN<12>")
	)
	(segment
		(start 336.992214 -302.034194)
		(end 340.417658 -300.616112)
		(width 0.14732)
		(layer "In11.Cu")
		(net "UPI_CPU1_CPU0_P2P2_DN<12>")
	)
	(segment
		(start 96.902016 -378.4219)
		(end 125.7427 -382.699768)
		(width 0.14732)
		(layer "In11.Cu")
		(net "UPI_CPU1_CPU0_P2P2_DN<12>")
	)
	(segment
		(start 185.468006 -380.186692)
		(end 185.48604 -380.393702)
		(width 0.14732)
		(layer "In11.Cu")
		(net "UPI_CPU1_CPU0_P2P2_DN<12>")
	)
	(segment
		(start 189.927484 -379.65888)
		(end 190.086234 -379.792992)
		(width 0.14732)
		(layer "In11.Cu")
		(net "UPI_CPU1_CPU0_P2P2_DN<12>")
	)
	(segment
		(start 189.222888 -380.074932)
		(end 189.205108 -379.867922)
		(width 0.14732)
		(layer "In11.Cu")
		(net "UPI_CPU1_CPU0_P2P2_DN<12>")
	)
	(segment
		(start 345.688412 -284.049216)
		(end 345.688412 -284.033722)
		(width 0.0889)
		(layer "In11.Cu")
		(net "UPI_CPU1_CPU0_P2P2_DN<12>")
	)
	(segment
		(start 195.055236 -379.886972)
		(end 195.86956 -379.817376)
		(width 0.14732)
		(layer "In11.Cu")
		(net "UPI_CPU1_CPU0_P2P2_DN<12>")
	)
	(segment
		(start 95.678244 -285.661354)
		(end 95.678244 -285.675578)
		(width 0.0889)
		(layer "In11.Cu")
		(net "UPI_CPU1_CPU0_P2P2_DN<12>")
	)
	(segment
		(start 75.242166 -369.45062)
		(end 96.902016 -378.4219)
		(width 0.14732)
		(layer "In11.Cu")
		(net "UPI_CPU1_CPU0_P2P2_DN<12>")
	)
	(segment
		(start 78.095856 -313.009026)
		(end 69.50964 -321.595496)
		(width 0.14732)
		(layer "In11.Cu")
		(net "UPI_CPU1_CPU0_P2P2_DN<12>")
	)
	(segment
		(start 194.722496 -379.606302)
		(end 195.055236 -379.886972)
		(width 0.14732)
		(layer "In11.Cu")
		(net "UPI_CPU1_CPU0_P2P2_DN<12>")
	)
	(segment
		(start 185.81878 -380.674372)
		(end 186.633104 -380.604776)
		(width 0.14732)
		(layer "In11.Cu")
		(net "UPI_CPU1_CPU0_P2P2_DN<12>")
	)
	(segment
		(start 95.964248 -285.169864)
		(end 95.96247 -285.17088)
		(width 0.0889)
		(layer "In11.Cu")
		(net "UPI_CPU1_CPU0_P2P2_DN<12>")
	)
	(segment
		(start 96.995996 -284.35808)
		(end 96.981264 -284.349444)
		(width 0.0889)
		(layer "In11.Cu")
		(net "UPI_CPU1_CPU0_P2P2_DN<12>")
	)
	(segment
		(start 185.48604 -380.393702)
		(end 185.81878 -380.674372)
		(width 0.14732)
		(layer "In11.Cu")
		(net "UPI_CPU1_CPU0_P2P2_DN<12>")
	)
	(segment
		(start 345.218766 -286.475424)
		(end 345.218766 -286.467804)
		(width 0.0889)
		(layer "In11.Cu")
		(net "UPI_CPU1_CPU0_P2P2_DN<12>")
	)
	(segment
		(start 93.440758 -300.416722)
		(end 78.095856 -313.009026)
		(width 0.14732)
		(layer "In11.Cu")
		(net "UPI_CPU1_CPU0_P2P2_DN<12>")
	)
	(segment
		(start 96.148398 -284.832044)
		(end 96.148398 -284.847538)
		(width 0.0889)
		(layer "In11.Cu")
		(net "UPI_CPU1_CPU0_P2P2_DN<12>")
	)
	(segment
		(start 125.7427 -382.699768)
		(end 162.019742 -382.699768)
		(width 0.14732)
		(layer "In11.Cu")
		(net "UPI_CPU1_CPU0_P2P2_DN<12>")
	)
	(segment
		(start 187.795154 -380.196852)
		(end 188.127894 -380.477522)
		(width 0.14732)
		(layer "In11.Cu")
		(net "UPI_CPU1_CPU0_P2P2_DN<12>")
	)
	(segment
		(start 196.15023 -379.484382)
		(end 196.13245 -379.277372)
		(width 0.14732)
		(layer "In11.Cu")
		(net "UPI_CPU1_CPU0_P2P2_DN<12>")
	)
	(segment
		(start 194.704462 -379.399292)
		(end 194.722496 -379.606302)
		(width 0.14732)
		(layer "In11.Cu")
		(net "UPI_CPU1_CPU0_P2P2_DN<12>")
	)
	(segment
		(start 313.940444 -326.640444)
		(end 315.039756 -323.986652)
		(width 0.14732)
		(layer "In11.Cu")
		(net "UPI_CPU1_CPU0_P2P2_DN<12>")
	)
	(segment
		(start 184.60466 -380.468632)
		(end 184.58688 -380.261622)
		(width 0.14732)
		(layer "In11.Cu")
		(net "UPI_CPU1_CPU0_P2P2_DN<12>")
	)
	(segment
		(start 99.845622 -281.59202)
		(end 99.903026 -281.649424)
		(width 0.0889)
		(layer "In11.Cu")
		(net "UPI_CPU1_CPU0_P2P2_DN<12>")
	)
	(segment
		(start 66.435478 -354.229162)
		(end 70.970902 -365.179356)
		(width 0.14732)
		(layer "In11.Cu")
		(net "UPI_CPU1_CPU0_P2P2_DN<12>")
	)
	(segment
		(start 95.166434 -290.796726)
		(end 95.166434 -296.795952)
		(width 0.14732)
		(layer "In11.Cu")
		(net "UPI_CPU1_CPU0_P2P2_DN<12>")
	)
	(segment
		(start 192.395348 -379.596142)
		(end 192.413382 -379.803152)
		(width 0.14732)
		(layer "In11.Cu")
		(net "UPI_CPU1_CPU0_P2P2_DN<12>")
	)
	(segment
		(start 191.648334 -379.512322)
		(end 192.236598 -379.46203)
		(width 0.14732)
		(layer "In11.Cu")
		(net "UPI_CPU1_CPU0_P2P2_DN<12>")
	)
	(segment
		(start 183.176926 -380.590552)
		(end 183.509666 -380.871222)
		(width 0.14732)
		(layer "In11.Cu")
		(net "UPI_CPU1_CPU0_P2P2_DN<12>")
	)
	(segment
		(start 96.148144 -286.466788)
		(end 96.148144 -286.48406)
		(width 0.0889)
		(layer "In11.Cu")
		(net "UPI_CPU1_CPU0_P2P2_DN<12>")
	)
	(segment
		(start 98.967544 -283.205682)
		(end 98.967544 -283.219906)
		(width 0.0889)
		(layer "In11.Cu")
		(net "UPI_CPU1_CPU0_P2P2_DN<12>")
	)
	(segment
		(start 343.20099 -291.506656)
		(end 343.20099 -291.484558)
		(width 0.0889)
		(layer "In11.Cu")
		(net "UPI_CPU1_CPU0_P2P2_DN<12>")
	)
	(segment
		(start 188.942218 -380.407926)
		(end 189.222888 -380.074932)
		(width 0.14732)
		(layer "In11.Cu")
		(net "UPI_CPU1_CPU0_P2P2_DN<12>")
	)
	(segment
		(start 344.927174 -285.342076)
		(end 344.936064 -285.336996)
		(width 0.0889)
		(layer "In11.Cu")
		(net "UPI_CPU1_CPU0_P2P2_DN<12>")
	)
	(segment
		(start 99.72167 -281.915362)
		(end 99.71405 -281.919934)
		(width 0.0889)
		(layer "In11.Cu")
		(net "UPI_CPU1_CPU0_P2P2_DN<12>")
	)
	(segment
		(start 182.411878 -380.299722)
		(end 183.000142 -380.24943)
		(width 0.14732)
		(layer "In11.Cu")
		(net "UPI_CPU1_CPU0_P2P2_DN<12>")
	)
	(segment
		(start 99.729036 -281.911298)
		(end 99.729036 -281.911044)
		(width 0.0889)
		(layer "In11.Cu")
		(net "UPI_CPU1_CPU0_P2P2_DN<12>")
	)
	(segment
		(start 184.32399 -380.801626)
		(end 184.60466 -380.468632)
		(width 0.14732)
		(layer "In11.Cu")
		(net "UPI_CPU1_CPU0_P2P2_DN<12>")
	)
	(segment
		(start 184.720992 -380.102872)
		(end 185.309256 -380.05258)
		(width 0.14732)
		(layer "In11.Cu")
		(net "UPI_CPU1_CPU0_P2P2_DN<12>")
	)
	(segment
		(start 199.32269 -379.005592)
		(end 199.340724 -379.212602)
		(width 0.14732)
		(layer "In11.Cu")
		(net "UPI_CPU1_CPU0_P2P2_DN<12>")
	)
	(segment
		(start 346.158312 -283.229812)
		(end 346.158312 -283.201364)
		(width 0.0889)
		(layer "In11.Cu")
		(net "UPI_CPU1_CPU0_P2P2_DN<12>")
	)
	(segment
		(start 183.158892 -380.383542)
		(end 183.176926 -380.590552)
		(width 0.14732)
		(layer "In11.Cu")
		(net "UPI_CPU1_CPU0_P2P2_DN<12>")
	)
	(segment
		(start 67.095116 -328.083418)
		(end 66.435478 -334.78343)
		(width 0.14732)
		(layer "In11.Cu")
		(net "UPI_CPU1_CPU0_P2P2_DN<12>")
	)
	(segment
		(start 189.205108 -379.867922)
		(end 189.33922 -379.709172)
		(width 0.14732)
		(layer "In11.Cu")
		(net "UPI_CPU1_CPU0_P2P2_DN<12>")
	)
	(segment
		(start 192.236598 -379.46203)
		(end 192.395348 -379.596142)
		(width 0.14732)
		(layer "In11.Cu")
		(net "UPI_CPU1_CPU0_P2P2_DN<12>")
	)
	(segment
		(start 193.957448 -379.315472)
		(end 194.545712 -379.26518)
		(width 0.14732)
		(layer "In11.Cu")
		(net "UPI_CPU1_CPU0_P2P2_DN<12>")
	)
	(segment
		(start 345.750388 -282.405836)
		(end 346.063062 -282.405836)
		(width 0.0889)
		(layer "In11.Cu")
		(net "UPI_CPU1_CPU0_P2P2_DN<12>")
	)
	(segment
		(start 179.968652 -380.655322)
		(end 180.102764 -380.496572)
		(width 0.14732)
		(layer "In11.Cu")
		(net "UPI_CPU1_CPU0_P2P2_DN<12>")
	)
	(segment
		(start 180.691028 -380.44628)
		(end 180.849778 -380.580392)
		(width 0.14732)
		(layer "In11.Cu")
		(net "UPI_CPU1_CPU0_P2P2_DN<12>")
	)
	(segment
		(start 342.202008 -298.225718)
		(end 343.195656 -293.235888)
		(width 0.14732)
		(layer "In11.Cu")
		(net "UPI_CPU1_CPU0_P2P2_DN<12>")
	)
	(segment
		(start 187.77712 -379.989842)
		(end 187.795154 -380.196852)
		(width 0.14732)
		(layer "In11.Cu")
		(net "UPI_CPU1_CPU0_P2P2_DN<12>")
	)
	(segment
		(start 195.86956 -379.817376)
		(end 196.15023 -379.484382)
		(width 0.14732)
		(layer "In11.Cu")
		(net "UPI_CPU1_CPU0_P2P2_DN<12>")
	)
	(segment
		(start 190.086234 -379.792992)
		(end 190.104268 -380.000002)
		(width 0.14732)
		(layer "In11.Cu")
		(net "UPI_CPU1_CPU0_P2P2_DN<12>")
	)
	(segment
		(start 197.36435 -379.690122)
		(end 198.178674 -379.620526)
		(width 0.14732)
		(layer "In11.Cu")
		(net "UPI_CPU1_CPU0_P2P2_DN<12>")
	)
	(segment
		(start 99.724972 -281.91333)
		(end 99.723448 -281.914346)
		(width 0.0889)
		(layer "In11.Cu")
		(net "UPI_CPU1_CPU0_P2P2_DN<12>")
	)
	(segment
		(start 183.000142 -380.24943)
		(end 183.158892 -380.383542)
		(width 0.14732)
		(layer "In11.Cu")
		(net "UPI_CPU1_CPU0_P2P2_DN<12>")
	)
	(segment
		(start 182.014876 -380.998476)
		(end 182.295546 -380.665482)
		(width 0.14732)
		(layer "In11.Cu")
		(net "UPI_CPU1_CPU0_P2P2_DN<12>")
	)
	(segment
		(start 192.413382 -379.803152)
		(end 192.746122 -380.083822)
		(width 0.14732)
		(layer "In11.Cu")
		(net "UPI_CPU1_CPU0_P2P2_DN<12>")
	)
	(segment
		(start 98.788982 -283.539184)
		(end 98.780092 -283.544264)
		(width 0.0889)
		(layer "In11.Cu")
		(net "UPI_CPU1_CPU0_P2P2_DN<12>")
	)
	(segment
		(start 196.854826 -379.06833)
		(end 197.013576 -379.202442)
		(width 0.14732)
		(layer "In11.Cu")
		(net "UPI_CPU1_CPU0_P2P2_DN<12>")
	)
	(segment
		(start 95.030036 -288.422334)
		(end 95.021146 -288.427414)
		(width 0.0889)
		(layer "In11.Cu")
		(net "UPI_CPU1_CPU0_P2P2_DN<12>")
	)
	(segment
		(start 343.195656 -293.235888)
		(end 343.200736 -293.230808)
		(width 0.14732)
		(layer "In11.Cu")
		(net "UPI_CPU1_CPU0_P2P2_DN<12>")
	)
	(segment
		(start 269.3797 -366.007904)
		(end 269.3797 -345.894152)
		(width 0.14732)
		(layer "In11.Cu")
		(net "UPI_CPU1_CPU0_P2P2_DN<12>")
	)
	(segment
		(start 197.03161 -379.409452)
		(end 197.36435 -379.690122)
		(width 0.14732)
		(layer "In11.Cu")
		(net "UPI_CPU1_CPU0_P2P2_DN<12>")
	)
	(segment
		(start 95.499682 -287.608518)
		(end 95.490792 -287.613598)
		(width 0.0889)
		(layer "In11.Cu")
		(net "UPI_CPU1_CPU0_P2P2_DN<12>")
	)
	(segment
		(start 191.251332 -380.211076)
		(end 191.532002 -379.878082)
		(width 0.14732)
		(layer "In11.Cu")
		(net "UPI_CPU1_CPU0_P2P2_DN<12>")
	)
	(segment
		(start 95.969836 -285.166562)
		(end 95.965772 -285.168848)
		(width 0.0889)
		(layer "In11.Cu")
		(net "UPI_CPU1_CPU0_P2P2_DN<12>")
	)
	(segment
		(start 341.774018 -299.259752)
		(end 342.202262 -298.225718)
		(width 0.14732)
		(layer "In11.Cu")
		(net "UPI_CPU1_CPU0_P2P2_DN<12>")
	)
	(segment
		(start 95.208344 -289.64509)
		(end 95.208344 -290.732718)
		(width 0.0889)
		(layer "In11.Cu")
		(net "UPI_CPU1_CPU0_P2P2_DN<12>")
	)
	(segment
		(start 95.960184 -286.80029)
		(end 95.95485 -286.803338)
		(width 0.0889)
		(layer "In11.Cu")
		(net "UPI_CPU1_CPU0_P2P2_DN<12>")
	)
	(segment
		(start 196.13245 -379.277372)
		(end 196.266562 -379.118622)
		(width 0.14732)
		(layer "In11.Cu")
		(net "UPI_CPU1_CPU0_P2P2_DN<12>")
	)
	(segment
		(start 97.557844 -284.023816)
		(end 97.557844 -284.033722)
		(width 0.0889)
		(layer "In11.Cu")
		(net "UPI_CPU1_CPU0_P2P2_DN<12>")
	)
	(segment
		(start 95.208344 -290.732718)
		(end 95.166434 -290.774628)
		(width 0.0889)
		(layer "In11.Cu")
		(net "UPI_CPU1_CPU0_P2P2_DN<12>")
	)
	(segment
		(start 184.58688 -380.261622)
		(end 184.720992 -380.102872)
		(width 0.14732)
		(layer "In11.Cu")
		(net "UPI_CPU1_CPU0_P2P2_DN<12>")
	)
	(arc
		(start 99.71405 -281.919934)
		(mid 99.511463 -282.126285)
		(end 99.437444 -282.405836)
		(width 0.0889)
		(layer "In11.Cu")
		(net "UPI_CPU1_CPU0_P2P2_DN<12>")
	)
	(arc
		(start 344.278966 -288.103056)
		(mid 344.326645 -287.920156)
		(end 344.457528 -287.783778)
		(width 0.0889)
		(layer "In11.Cu")
		(net "UPI_CPU1_CPU0_P2P2_DN<12>")
	)
	(arc
		(start 345.866974 -282.725114)
		(mid 345.751235 -282.61329)
		(end 345.692984 -282.46324)
		(width 0.0889)
		(layer "In11.Cu")
		(net "UPI_CPU1_CPU0_P2P2_DN<12>")
	)
	(arc
		(start 343.809066 -288.917126)
		(mid 343.856745 -288.734226)
		(end 343.987628 -288.597848)
		(width 0.0889)
		(layer "In11.Cu")
		(net "UPI_CPU1_CPU0_P2P2_DN<12>")
	)
	(arc
		(start 345.218766 -286.467804)
		(mid 345.141137 -286.189391)
		(end 344.936064 -285.985712)
		(width 0.0889)
		(layer "In11.Cu")
		(net "UPI_CPU1_CPU0_P2P2_DN<12>")
	)
	(arc
		(start 344.748612 -287.28924)
		(mid 344.796291 -287.10634)
		(end 344.927174 -286.969962)
		(width 0.0889)
		(layer "In11.Cu")
		(net "UPI_CPU1_CPU0_P2P2_DN<12>")
	)
	(arc
		(start 99.43719 -282.420568)
		(mid 99.386136 -282.595148)
		(end 99.258882 -282.725114)
		(width 0.0889)
		(layer "In11.Cu")
		(net "UPI_CPU1_CPU0_P2P2_DN<12>")
	)
	(arc
		(start 97.370392 -284.35808)
		(mid 97.183194 -284.408223)
		(end 96.995996 -284.35808)
		(width 0.0889)
		(layer "In11.Cu")
		(net "UPI_CPU1_CPU0_P2P2_DN<12>")
	)
	(arc
		(start 95.678244 -287.28924)
		(mid 95.630565 -287.47214)
		(end 95.499682 -287.608518)
		(width 0.0889)
		(layer "In11.Cu")
		(net "UPI_CPU1_CPU0_P2P2_DN<12>")
	)
	(arc
		(start 98.967544 -283.219906)
		(mid 98.919865 -283.402806)
		(end 98.788982 -283.539184)
		(width 0.0889)
		(layer "In11.Cu")
		(net "UPI_CPU1_CPU0_P2P2_DN<12>")
	)
	(arc
		(start 98.780092 -283.544264)
		(mid 98.592894 -283.594407)
		(end 98.405696 -283.544264)
		(width 0.0889)
		(layer "In11.Cu")
		(net "UPI_CPU1_CPU0_P2P2_DN<12>")
	)
	(arc
		(start 343.993216 -289.277806)
		(mid 343.884069 -289.193878)
		(end 343.809066 -289.078416)
		(width 0.0889)
		(layer "In11.Cu")
		(net "UPI_CPU1_CPU0_P2P2_DN<12>")
	)
	(arc
		(start 344.466418 -287.778698)
		(mid 344.669241 -287.578467)
		(end 344.748612 -287.304734)
		(width 0.0889)
		(layer "In11.Cu")
		(net "UPI_CPU1_CPU0_P2P2_DN<12>")
	)
	(arc
		(start 96.430592 -284.35808)
		(mid 96.227769 -284.558311)
		(end 96.148398 -284.832044)
		(width 0.0889)
		(layer "In11.Cu")
		(net "UPI_CPU1_CPU0_P2P2_DN<12>")
	)
	(arc
		(start 343.996518 -288.592768)
		(mid 344.198804 -288.393787)
		(end 344.278966 -288.121598)
		(width 0.0889)
		(layer "In11.Cu")
		(net "UPI_CPU1_CPU0_P2P2_DN<12>")
	)
	(arc
		(start 344.278712 -289.60953)
		(mid 344.167374 -289.41663)
		(end 343.993216 -289.277806)
		(width 0.0889)
		(layer "In11.Cu")
		(net "UPI_CPU1_CPU0_P2P2_DN<12>")
	)
	(arc
		(start 99.437444 -282.405836)
		(mid 99.437392 -282.413203)
		(end 99.43719 -282.420568)
		(width 0.0889)
		(layer "In11.Cu")
		(net "UPI_CPU1_CPU0_P2P2_DN<12>")
	)
	(arc
		(start 95.024194 -289.446208)
		(mid 95.133229 -289.529937)
		(end 95.208344 -289.64509)
		(width 0.0889)
		(layer "In11.Cu")
		(net "UPI_CPU1_CPU0_P2P2_DN<12>")
	)
	(arc
		(start 99.903026 -281.649424)
		(mid 99.84487 -281.799537)
		(end 99.729036 -281.911298)
		(width 0.0889)
		(layer "In11.Cu")
		(net "UPI_CPU1_CPU0_P2P2_DN<12>")
	)
	(arc
		(start 95.208598 -288.103056)
		(mid 95.160919 -288.285956)
		(end 95.030036 -288.422334)
		(width 0.0889)
		(layer "In11.Cu")
		(net "UPI_CPU1_CPU0_P2P2_DN<12>")
	)
	(arc
		(start 97.557844 -284.033722)
		(mid 97.510165 -284.216622)
		(end 97.379282 -284.353)
		(width 0.0889)
		(layer "In11.Cu")
		(net "UPI_CPU1_CPU0_P2P2_DN<12>")
	)
	(arc
		(start 95.95485 -286.803338)
		(mid 95.752263 -287.009689)
		(end 95.678244 -287.28924)
		(width 0.0889)
		(layer "In11.Cu")
		(net "UPI_CPU1_CPU0_P2P2_DN<12>")
	)
	(arc
		(start 95.021146 -288.427414)
		(mid 94.81886 -288.626395)
		(end 94.738698 -288.898584)
		(width 0.0889)
		(layer "In11.Cu")
		(net "UPI_CPU1_CPU0_P2P2_DN<12>")
	)
	(arc
		(start 95.490792 -287.613598)
		(mid 95.287969 -287.813829)
		(end 95.208598 -288.087562)
		(width 0.0889)
		(layer "In11.Cu")
		(net "UPI_CPU1_CPU0_P2P2_DN<12>")
	)
	(arc
		(start 345.688412 -284.033722)
		(mid 345.736091 -283.850822)
		(end 345.866974 -283.714444)
		(width 0.0889)
		(layer "In11.Cu")
		(net "UPI_CPU1_CPU0_P2P2_DN<12>")
	)
	(arc
		(start 95.678244 -285.675578)
		(mid 95.757463 -285.950263)
		(end 95.960946 -286.151066)
		(width 0.0889)
		(layer "In11.Cu")
		(net "UPI_CPU1_CPU0_P2P2_DN<12>")
	)
	(arc
		(start 99.249992 -282.730194)
		(mid 99.046687 -282.93106)
		(end 98.967544 -283.205682)
		(width 0.0889)
		(layer "In11.Cu")
		(net "UPI_CPU1_CPU0_P2P2_DN<12>")
	)
	(arc
		(start 98.405696 -283.544264)
		(mid 98.122994 -283.468488)
		(end 97.840292 -283.544264)
		(width 0.0889)
		(layer "In11.Cu")
		(net "UPI_CPU1_CPU0_P2P2_DN<12>")
	)
	(arc
		(start 96.148398 -284.847538)
		(mid 96.100719 -285.030438)
		(end 95.969836 -285.166816)
		(width 0.0889)
		(layer "In11.Cu")
		(net "UPI_CPU1_CPU0_P2P2_DN<12>")
	)
	(arc
		(start 97.840292 -283.544264)
		(mid 97.635957 -283.746869)
		(end 97.557844 -284.023816)
		(width 0.0889)
		(layer "In11.Cu")
		(net "UPI_CPU1_CPU0_P2P2_DN<12>")
	)
	(arc
		(start 94.738698 -289.114738)
		(mid 94.850036 -289.307638)
		(end 95.024194 -289.446462)
		(width 0.0889)
		(layer "In11.Cu")
		(net "UPI_CPU1_CPU0_P2P2_DN<12>")
	)
	(arc
		(start 95.95485 -285.175452)
		(mid 95.752263 -285.381803)
		(end 95.678244 -285.661354)
		(width 0.0889)
		(layer "In11.Cu")
		(net "UPI_CPU1_CPU0_P2P2_DN<12>")
	)
	(arc
		(start 96.981264 -284.349444)
		(mid 96.704789 -284.282124)
		(end 96.430592 -284.35808)
		(width 0.0889)
		(layer "In11.Cu")
		(net "UPI_CPU1_CPU0_P2P2_DN<12>")
	)
	(arc
		(start 95.960946 -286.151066)
		(mid 96.095879 -286.28442)
		(end 96.148144 -286.466788)
		(width 0.0889)
		(layer "In11.Cu")
		(net "UPI_CPU1_CPU0_P2P2_DN<12>")
	)
	(arc
		(start 345.218766 -284.847538)
		(mid 345.266445 -284.664638)
		(end 345.397328 -284.52826)
		(width 0.0889)
		(layer "In11.Cu")
		(net "UPI_CPU1_CPU0_P2P2_DN<12>")
	)
	(arc
		(start 346.158312 -283.201364)
		(mid 346.07815 -282.929175)
		(end 345.875864 -282.730194)
		(width 0.0889)
		(layer "In11.Cu")
		(net "UPI_CPU1_CPU0_P2P2_DN<12>")
	)
	(arc
		(start 345.406218 -284.52318)
		(mid 345.609041 -284.322949)
		(end 345.688412 -284.049216)
		(width 0.0889)
		(layer "In11.Cu")
		(net "UPI_CPU1_CPU0_P2P2_DN<12>")
	)
	(arc
		(start 96.148144 -286.48406)
		(mid 96.095874 -286.666425)
		(end 95.960946 -286.799782)
		(width 0.0889)
		(layer "In11.Cu")
		(net "UPI_CPU1_CPU0_P2P2_DN<12>")
	)
	(arc
		(start 344.927174 -285.980632)
		(mid 344.748698 -285.661354)
		(end 344.927174 -285.342076)
		(width 0.0889)
		(layer "In11.Cu")
		(net "UPI_CPU1_CPU0_P2P2_DN<12>")
	)
	(arc
		(start 344.94216 -285.33344)
		(mid 345.144747 -285.127089)
		(end 345.218766 -284.847538)
		(width 0.0889)
		(layer "In11.Cu")
		(net "UPI_CPU1_CPU0_P2P2_DN<12>")
	)
	(arc
		(start 344.948256 -286.95777)
		(mid 345.146484 -286.751922)
		(end 345.218766 -286.475424)
		(width 0.0889)
		(layer "In11.Cu")
		(net "UPI_CPU1_CPU0_P2P2_DN<12>")
	)
	(arc
		(start 345.875864 -283.709364)
		(mid 346.080199 -283.506759)
		(end 346.158312 -283.229812)
		(width 0.0889)
		(layer "In11.Cu")
		(net "UPI_CPU1_CPU0_P2P2_DN<12>")
	)
	(segment
		(start 352.171762 -275.080476)
		(end 352.172016 -275.08073)
		(width 0.13208)
		(layer "F.Cu")
		(net "UPI_CPU1_CPU0_P2P2_DN<11>")
	)
	(segment
		(start 101.882448 -278.614378)
		(end 101.882448 -279.150064)
		(width 0.13208)
		(layer "F.Cu")
		(net "UPI_CPU1_CPU0_P2P2_DN<11>")
	)
	(segment
		(start 352.171762 -274.54479)
		(end 352.171762 -275.080476)
		(width 0.13208)
		(layer "F.Cu")
		(net "UPI_CPU1_CPU0_P2P2_DN<11>")
	)
	(segment
		(start 101.882448 -279.150064)
		(end 101.882194 -279.150318)
		(width 0.13208)
		(layer "F.Cu")
		(net "UPI_CPU1_CPU0_P2P2_DN<11>")
	)
	(segment
		(start 95.208598 -284.832044)
		(end 95.208598 -284.847538)
		(width 0.0889)
		(layer "In11.Cu")
		(net "UPI_CPU1_CPU0_P2P2_DN<11>")
	)
	(segment
		(start 78.51521 -311.416446)
		(end 68.818252 -321.113404)
		(width 0.14732)
		(layer "In11.Cu")
		(net "UPI_CPU1_CPU0_P2P2_DN<11>")
	)
	(segment
		(start 345.397328 -287.783778)
		(end 345.406218 -287.778698)
		(width 0.0889)
		(layer "In11.Cu")
		(net "UPI_CPU1_CPU0_P2P2_DN<11>")
	)
	(segment
		(start 344.12301 -291.432234)
		(end 344.12301 -291.151564)
		(width 0.0889)
		(layer "In11.Cu")
		(net "UPI_CPU1_CPU0_P2P2_DN<11>")
	)
	(segment
		(start 350.479614 -274.756372)
		(end 350.494346 -274.765008)
		(width 0.0889)
		(layer "In11.Cu")
		(net "UPI_CPU1_CPU0_P2P2_DN<11>")
	)
	(segment
		(start 67.23888 -324.453758)
		(end 66.266314 -327.966324)
		(width 0.14732)
		(layer "In11.Cu")
		(net "UPI_CPU1_CPU0_P2P2_DN<11>")
	)
	(segment
		(start 350.096328 -274.761452)
		(end 350.105218 -274.756372)
		(width 0.0889)
		(layer "In11.Cu")
		(net "UPI_CPU1_CPU0_P2P2_DN<11>")
	)
	(segment
		(start 94.226634 -296.88917)
		(end 93.236034 -299.280834)
		(width 0.14732)
		(layer "In11.Cu")
		(net "UPI_CPU1_CPU0_P2P2_DN<11>")
	)
	(segment
		(start 94.738444 -287.279334)
		(end 94.738444 -287.28924)
		(width 0.0889)
		(layer "In11.Cu")
		(net "UPI_CPU1_CPU0_P2P2_DN<11>")
	)
	(segment
		(start 66.266314 -327.966324)
		(end 65.602358 -334.711294)
		(width 0.14732)
		(layer "In11.Cu")
		(net "UPI_CPU1_CPU0_P2P2_DN<11>")
	)
	(segment
		(start 342.728804 -299.480224)
		(end 343.208864 -298.316396)
		(width 0.14732)
		(layer "In11.Cu")
		(net "UPI_CPU1_CPU0_P2P2_DN<11>")
	)
	(segment
		(start 93.236034 -299.280834)
		(end 92.7989 -299.870622)
		(width 0.14732)
		(layer "In11.Cu")
		(net "UPI_CPU1_CPU0_P2P2_DN<11>")
	)
	(segment
		(start 349.447866 -275.904706)
		(end 349.447866 -275.886164)
		(width 0.0889)
		(layer "In11.Cu")
		(net "UPI_CPU1_CPU0_P2P2_DN<11>")
	)
	(segment
		(start 345.218512 -290.056062)
		(end 345.218512 -289.60953)
		(width 0.0889)
		(layer "In11.Cu")
		(net "UPI_CPU1_CPU0_P2P2_DN<11>")
	)
	(segment
		(start 344.889074 -290.525962)
		(end 345.014804 -290.400232)
		(width 0.0889)
		(layer "In11.Cu")
		(net "UPI_CPU1_CPU0_P2P2_DN<11>")
	)
	(segment
		(start 344.927428 -288.597848)
		(end 344.936318 -288.592768)
		(width 0.0889)
		(layer "In11.Cu")
		(net "UPI_CPU1_CPU0_P2P2_DN<11>")
	)
	(segment
		(start 315.789056 -324.411848)
		(end 337.465162 -302.735742)
		(width 0.14732)
		(layer "In11.Cu")
		(net "UPI_CPU1_CPU0_P2P2_DN<11>")
	)
	(segment
		(start 346.628212 -284.049216)
		(end 346.628212 -284.033722)
		(width 0.0889)
		(layer "In11.Cu")
		(net "UPI_CPU1_CPU0_P2P2_DN<11>")
	)
	(segment
		(start 95.025972 -285.168848)
		(end 95.024448 -285.169864)
		(width 0.0889)
		(layer "In11.Cu")
		(net "UPI_CPU1_CPU0_P2P2_DN<11>")
	)
	(segment
		(start 74.788522 -370.171472)
		(end 96.63303 -379.219714)
		(width 0.14732)
		(layer "In11.Cu")
		(net "UPI_CPU1_CPU0_P2P2_DN<11>")
	)
	(segment
		(start 97.087944 -283.201364)
		(end 97.087944 -283.228542)
		(width 0.0889)
		(layer "In11.Cu")
		(net "UPI_CPU1_CPU0_P2P2_DN<11>")
	)
	(segment
		(start 70.2691 -365.65205)
		(end 74.788522 -370.171472)
		(width 0.14732)
		(layer "In11.Cu")
		(net "UPI_CPU1_CPU0_P2P2_DN<11>")
	)
	(segment
		(start 349.171514 -277.03653)
		(end 349.165418 -277.032974)
		(width 0.0889)
		(layer "In11.Cu")
		(net "UPI_CPU1_CPU0_P2P2_DN<11>")
	)
	(segment
		(start 95.030036 -285.166816)
		(end 95.030036 -285.166562)
		(width 0.0889)
		(layer "In11.Cu")
		(net "UPI_CPU1_CPU0_P2P2_DN<11>")
	)
	(segment
		(start 348.225618 -279.639776)
		(end 348.231714 -279.63622)
		(width 0.0889)
		(layer "In11.Cu")
		(net "UPI_CPU1_CPU0_P2P2_DN<11>")
	)
	(segment
		(start 98.783648 -281.914346)
		(end 98.78187 -281.915362)
		(width 0.0889)
		(layer "In11.Cu")
		(net "UPI_CPU1_CPU0_P2P2_DN<11>")
	)
	(segment
		(start 349.917766 -275.094954)
		(end 349.917766 -275.08073)
		(width 0.0889)
		(layer "In11.Cu")
		(net "UPI_CPU1_CPU0_P2P2_DN<11>")
	)
	(segment
		(start 343.220548 -298.292012)
		(end 344.165174 -293.54145)
		(width 0.14732)
		(layer "In11.Cu")
		(net "UPI_CPU1_CPU0_P2P2_DN<11>")
	)
	(segment
		(start 99.734878 -280.279856)
		(end 99.720146 -280.288492)
		(width 0.0889)
		(layer "In11.Cu")
		(net "UPI_CPU1_CPU0_P2P2_DN<11>")
	)
	(segment
		(start 351.045018 -274.756372)
		(end 351.044764 -274.755864)
		(width 0.0889)
		(layer "In11.Cu")
		(net "UPI_CPU1_CPU0_P2P2_DN<11>")
	)
	(segment
		(start 94.268544 -291.432488)
		(end 94.226634 -291.474398)
		(width 0.0889)
		(layer "In11.Cu")
		(net "UPI_CPU1_CPU0_P2P2_DN<11>")
	)
	(segment
		(start 351.407222 -274.749006)
		(end 351.4471 -274.77212)
		(width 0.0889)
		(layer "In11.Cu")
		(net "UPI_CPU1_CPU0_P2P2_DN<11>")
	)
	(segment
		(start 95.030036 -285.166562)
		(end 95.025972 -285.168848)
		(width 0.0889)
		(layer "In11.Cu")
		(net "UPI_CPU1_CPU0_P2P2_DN<11>")
	)
	(segment
		(start 162.742626 -383.527808)
		(end 163.202874 -383.4511)
		(width 0.14732)
		(layer "In11.Cu")
		(net "UPI_CPU1_CPU0_P2P2_DN<11>")
	)
	(segment
		(start 101.997764 -279.523444)
		(end 101.978968 -279.53843)
		(width 0.0889)
		(layer "In11.Cu")
		(net "UPI_CPU1_CPU0_P2P2_DN<11>")
	)
	(segment
		(start 349.165418 -277.032974)
		(end 349.156528 -277.027894)
		(width 0.0889)
		(layer "In11.Cu")
		(net "UPI_CPU1_CPU0_P2P2_DN<11>")
	)
	(segment
		(start 347.276928 -282.900628)
		(end 347.285818 -282.895548)
		(width 0.0889)
		(layer "In11.Cu")
		(net "UPI_CPU1_CPU0_P2P2_DN<11>")
	)
	(segment
		(start 347.568012 -282.427934)
		(end 347.568012 -282.390342)
		(width 0.0889)
		(layer "In11.Cu")
		(net "UPI_CPU1_CPU0_P2P2_DN<11>")
	)
	(segment
		(start 347.285818 -281.916378)
		(end 347.276928 -281.911298)
		(width 0.0889)
		(layer "In11.Cu")
		(net "UPI_CPU1_CPU0_P2P2_DN<11>")
	)
	(segment
		(start 102.038658 -279.421336)
		(end 102.014528 -279.51049)
		(width 0.0889)
		(layer "In11.Cu")
		(net "UPI_CPU1_CPU0_P2P2_DN<11>")
	)
	(segment
		(start 346.158566 -286.475424)
		(end 346.158566 -286.4612)
		(width 0.0889)
		(layer "In11.Cu")
		(net "UPI_CPU1_CPU0_P2P2_DN<11>")
	)
	(segment
		(start 95.971106 -283.538168)
		(end 95.960692 -283.544264)
		(width 0.0889)
		(layer "In11.Cu")
		(net "UPI_CPU1_CPU0_P2P2_DN<11>")
	)
	(segment
		(start 347.276928 -281.272742)
		(end 347.285818 -281.267662)
		(width 0.0889)
		(layer "In11.Cu")
		(net "UPI_CPU1_CPU0_P2P2_DN<11>")
	)
	(segment
		(start 344.165174 -293.54145)
		(end 344.165174 -291.496496)
		(width 0.14732)
		(layer "In11.Cu")
		(net "UPI_CPU1_CPU0_P2P2_DN<11>")
	)
	(segment
		(start 340.892892 -301.315882)
		(end 342.728804 -299.480224)
		(width 0.14732)
		(layer "In11.Cu")
		(net "UPI_CPU1_CPU0_P2P2_DN<11>")
	)
	(segment
		(start 94.559882 -287.608518)
		(end 94.550992 -287.613598)
		(width 0.0889)
		(layer "In11.Cu")
		(net "UPI_CPU1_CPU0_P2P2_DN<11>")
	)
	(segment
		(start 314.691014 -327.063354)
		(end 315.789056 -324.411848)
		(width 0.14732)
		(layer "In11.Cu")
		(net "UPI_CPU1_CPU0_P2P2_DN<11>")
	)
	(segment
		(start 125.68936 -383.52984)
		(end 161.281364 -383.52984)
		(width 0.14732)
		(layer "In11.Cu")
		(net "UPI_CPU1_CPU0_P2P2_DN<11>")
	)
	(segment
		(start 351.875852 -274.80514)
		(end 351.92589 -274.785836)
		(width 0.0889)
		(layer "In11.Cu")
		(net "UPI_CPU1_CPU0_P2P2_DN<11>")
	)
	(segment
		(start 95.020892 -286.151066)
		(end 95.029782 -286.156146)
		(width 0.0889)
		(layer "In11.Cu")
		(net "UPI_CPU1_CPU0_P2P2_DN<11>")
	)
	(segment
		(start 347.568012 -280.793698)
		(end 347.568012 -280.778204)
		(width 0.0889)
		(layer "In11.Cu")
		(net "UPI_CPU1_CPU0_P2P2_DN<11>")
	)
	(segment
		(start 95.678244 -284.023816)
		(end 95.678244 -284.033722)
		(width 0.0889)
		(layer "In11.Cu")
		(net "UPI_CPU1_CPU0_P2P2_DN<11>")
	)
	(segment
		(start 65.602358 -354.384356)
		(end 70.2691 -365.65205)
		(width 0.14732)
		(layer "In11.Cu")
		(net "UPI_CPU1_CPU0_P2P2_DN<11>")
	)
	(segment
		(start 91.251024 -301.140876)
		(end 90.910156 -301.244254)
		(width 0.14732)
		(layer "In11.Cu")
		(net "UPI_CPU1_CPU0_P2P2_DN<11>")
	)
	(segment
		(start 161.281364 -383.52984)
		(end 161.28238 -383.528824)
		(width 0.14732)
		(layer "In11.Cu")
		(net "UPI_CPU1_CPU0_P2P2_DN<11>")
	)
	(segment
		(start 94.738444 -285.661354)
		(end 94.738444 -285.679896)
		(width 0.0889)
		(layer "In11.Cu")
		(net "UPI_CPU1_CPU0_P2P2_DN<11>")
	)
	(segment
		(start 93.798898 -288.898584)
		(end 93.798898 -289.114738)
		(width 0.0889)
		(layer "In11.Cu")
		(net "UPI_CPU1_CPU0_P2P2_DN<11>")
	)
	(segment
		(start 346.337128 -284.52826)
		(end 346.346018 -284.52318)
		(width 0.0889)
		(layer "In11.Cu")
		(net "UPI_CPU1_CPU0_P2P2_DN<11>")
	)
	(segment
		(start 344.165174 -291.496496)
		(end 344.165174 -291.474398)
		(width 0.0889)
		(layer "In11.Cu")
		(net "UPI_CPU1_CPU0_P2P2_DN<11>")
	)
	(segment
		(start 344.748866 -289.078416)
		(end 344.748866 -288.917126)
		(width 0.0889)
		(layer "In11.Cu")
		(net "UPI_CPU1_CPU0_P2P2_DN<11>")
	)
	(segment
		(start 68.818252 -321.113404)
		(end 67.23888 -324.453758)
		(width 0.14732)
		(layer "In11.Cu")
		(net "UPI_CPU1_CPU0_P2P2_DN<11>")
	)
	(segment
		(start 99.437444 -280.76398)
		(end 99.437444 -280.778204)
		(width 0.0889)
		(layer "In11.Cu")
		(net "UPI_CPU1_CPU0_P2P2_DN<11>")
	)
	(segment
		(start 344.623136 -290.651438)
		(end 344.748612 -290.525962)
		(width 0.0889)
		(layer "In11.Cu")
		(net "UPI_CPU1_CPU0_P2P2_DN<11>")
	)
	(segment
		(start 351.926398 -274.785836)
		(end 352.015552 -274.809712)
		(width 0.0889)
		(layer "In11.Cu")
		(net "UPI_CPU1_CPU0_P2P2_DN<11>")
	)
	(segment
		(start 351.92589 -274.785836)
		(end 351.926398 -274.785836)
		(width 0.0889)
		(layer "In11.Cu")
		(net "UPI_CPU1_CPU0_P2P2_DN<11>")
	)
	(segment
		(start 95.021654 -286.799274)
		(end 95.020892 -286.799782)
		(width 0.0889)
		(layer "In11.Cu")
		(net "UPI_CPU1_CPU0_P2P2_DN<11>")
	)
	(segment
		(start 95.029782 -286.794702)
		(end 95.021654 -286.799274)
		(width 0.0889)
		(layer "In11.Cu")
		(net "UPI_CPU1_CPU0_P2P2_DN<11>")
	)
	(segment
		(start 98.789236 -281.911298)
		(end 98.789236 -281.911044)
		(width 0.0889)
		(layer "In11.Cu")
		(net "UPI_CPU1_CPU0_P2P2_DN<11>")
	)
	(segment
		(start 344.748612 -290.525962)
		(end 344.889074 -290.525962)
		(width 0.0889)
		(layer "In11.Cu")
		(net "UPI_CPU1_CPU0_P2P2_DN<11>")
	)
	(segment
		(start 161.28238 -383.528824)
		(end 162.734244 -383.528824)
		(width 0.14732)
		(layer "In11.Cu")
		(net "UPI_CPU1_CPU0_P2P2_DN<11>")
	)
	(segment
		(start 345.875864 -285.336996)
		(end 345.88196 -285.33344)
		(width 0.0889)
		(layer "In11.Cu")
		(net "UPI_CPU1_CPU0_P2P2_DN<11>")
	)
	(segment
		(start 343.208864 -298.316396)
		(end 343.220548 -298.292012)
		(width 0.14732)
		(layer "In11.Cu")
		(net "UPI_CPU1_CPU0_P2P2_DN<11>")
	)
	(segment
		(start 349.156528 -276.389338)
		(end 349.165418 -276.384258)
		(width 0.0889)
		(layer "In11.Cu")
		(net "UPI_CPU1_CPU0_P2P2_DN<11>")
	)
	(segment
		(start 345.866974 -285.342076)
		(end 345.875864 -285.336996)
		(width 0.0889)
		(layer "In11.Cu")
		(net "UPI_CPU1_CPU0_P2P2_DN<11>")
	)
	(segment
		(start 348.686628 -278.83104)
		(end 348.695518 -278.82596)
		(width 0.0889)
		(layer "In11.Cu")
		(net "UPI_CPU1_CPU0_P2P2_DN<11>")
	)
	(segment
		(start 101.882194 -279.150318)
		(end 102.038658 -279.421336)
		(width 0.0889)
		(layer "In11.Cu")
		(net "UPI_CPU1_CPU0_P2P2_DN<11>")
	)
	(segment
		(start 94.226634 -291.496496)
		(end 94.226634 -296.88917)
		(width 0.14732)
		(layer "In11.Cu")
		(net "UPI_CPU1_CPU0_P2P2_DN<11>")
	)
	(segment
		(start 345.014804 -290.400232)
		(end 345.014804 -290.25977)
		(width 0.0889)
		(layer "In11.Cu")
		(net "UPI_CPU1_CPU0_P2P2_DN<11>")
	)
	(segment
		(start 308.002178 -333.75219)
		(end 314.691014 -327.063354)
		(width 0.14732)
		(layer "In11.Cu")
		(net "UPI_CPU1_CPU0_P2P2_DN<11>")
	)
	(segment
		(start 345.688412 -287.304734)
		(end 345.688412 -287.28924)
		(width 0.0889)
		(layer "In11.Cu")
		(net "UPI_CPU1_CPU0_P2P2_DN<11>")
	)
	(segment
		(start 94.268544 -289.64509)
		(end 94.268544 -291.432488)
		(width 0.0889)
		(layer "In11.Cu")
		(net "UPI_CPU1_CPU0_P2P2_DN<11>")
	)
	(segment
		(start 261.427214 -375.131584)
		(end 270.31188 -366.246918)
		(width 0.14732)
		(layer "In11.Cu")
		(net "UPI_CPU1_CPU0_P2P2_DN<11>")
	)
	(segment
		(start 344.623136 -290.7919)
		(end 344.623136 -290.651438)
		(width 0.0889)
		(layer "In11.Cu")
		(net "UPI_CPU1_CPU0_P2P2_DN<11>")
	)
	(segment
		(start 98.319082 -282.725114)
		(end 98.310192 -282.730194)
		(width 0.0889)
		(layer "In11.Cu")
		(net "UPI_CPU1_CPU0_P2P2_DN<11>")
	)
	(segment
		(start 94.090236 -288.422334)
		(end 94.081346 -288.427414)
		(width 0.0889)
		(layer "In11.Cu")
		(net "UPI_CPU1_CPU0_P2P2_DN<11>")
	)
	(segment
		(start 100.674678 -280.279856)
		(end 100.659946 -280.288492)
		(width 0.0889)
		(layer "In11.Cu")
		(net "UPI_CPU1_CPU0_P2P2_DN<11>")
	)
	(segment
		(start 162.734244 -383.528824)
		(end 162.742626 -383.527808)
		(width 0.14732)
		(layer "In11.Cu")
		(net "UPI_CPU1_CPU0_P2P2_DN<11>")
	)
	(segment
		(start 344.165174 -291.474398)
		(end 344.12301 -291.432234)
		(width 0.0889)
		(layer "In11.Cu")
		(net "UPI_CPU1_CPU0_P2P2_DN<11>")
	)
	(segment
		(start 90.910156 -301.244254)
		(end 78.51521 -311.416446)
		(width 0.14732)
		(layer "In11.Cu")
		(net "UPI_CPU1_CPU0_P2P2_DN<11>")
	)
	(segment
		(start 344.12301 -291.151564)
		(end 344.356944 -290.91763)
		(width 0.0889)
		(layer "In11.Cu")
		(net "UPI_CPU1_CPU0_P2P2_DN<11>")
	)
	(segment
		(start 98.785172 -281.91333)
		(end 98.783648 -281.914346)
		(width 0.0889)
		(layer "In11.Cu")
		(net "UPI_CPU1_CPU0_P2P2_DN<11>")
	)
	(segment
		(start 95.499682 -284.353)
		(end 95.490792 -284.35808)
		(width 0.0889)
		(layer "In11.Cu")
		(net "UPI_CPU1_CPU0_P2P2_DN<11>")
	)
	(segment
		(start 349.447866 -277.530052)
		(end 349.447866 -277.522432)
		(width 0.0889)
		(layer "In11.Cu")
		(net "UPI_CPU1_CPU0_P2P2_DN<11>")
	)
	(segment
		(start 101.78796 -279.924764)
		(end 101.787198 -279.964134)
		(width 0.0889)
		(layer "In11.Cu")
		(net "UPI_CPU1_CPU0_P2P2_DN<11>")
	)
	(segment
		(start 270.31188 -366.246918)
		(end 270.31188 -346.133166)
		(width 0.14732)
		(layer "In11.Cu")
		(net "UPI_CPU1_CPU0_P2P2_DN<11>")
	)
	(segment
		(start 99.258882 -281.097482)
		(end 99.249992 -281.102562)
		(width 0.0889)
		(layer "In11.Cu")
		(net "UPI_CPU1_CPU0_P2P2_DN<11>")
	)
	(segment
		(start 280.628852 -335.816194)
		(end 285.611824 -333.75219)
		(width 0.14732)
		(layer "In11.Cu")
		(net "UPI_CPU1_CPU0_P2P2_DN<11>")
	)
	(segment
		(start 94.268798 -288.087562)
		(end 94.268798 -288.103056)
		(width 0.0889)
		(layer "In11.Cu")
		(net "UPI_CPU1_CPU0_P2P2_DN<11>")
	)
	(segment
		(start 98.78187 -281.915362)
		(end 98.77425 -281.919934)
		(width 0.0889)
		(layer "In11.Cu")
		(net "UPI_CPU1_CPU0_P2P2_DN<11>")
	)
	(segment
		(start 337.465162 -302.735742)
		(end 340.892892 -301.315882)
		(width 0.14732)
		(layer "In11.Cu")
		(net "UPI_CPU1_CPU0_P2P2_DN<11>")
	)
	(segment
		(start 95.024448 -285.169864)
		(end 95.02267 -285.17088)
		(width 0.0889)
		(layer "In11.Cu")
		(net "UPI_CPU1_CPU0_P2P2_DN<11>")
	)
	(segment
		(start 345.875864 -285.985712)
		(end 345.866974 -285.980632)
		(width 0.0889)
		(layer "In11.Cu")
		(net "UPI_CPU1_CPU0_P2P2_DN<11>")
	)
	(segment
		(start 65.602358 -334.711294)
		(end 65.602358 -354.384356)
		(width 0.14732)
		(layer "In11.Cu")
		(net "UPI_CPU1_CPU0_P2P2_DN<11>")
	)
	(segment
		(start 270.31188 -346.133166)
		(end 280.628852 -335.816194)
		(width 0.14732)
		(layer "In11.Cu")
		(net "UPI_CPU1_CPU0_P2P2_DN<11>")
	)
	(segment
		(start 346.806774 -283.714444)
		(end 346.815664 -283.709364)
		(width 0.0889)
		(layer "In11.Cu")
		(net "UPI_CPU1_CPU0_P2P2_DN<11>")
	)
	(segment
		(start 348.038166 -279.978358)
		(end 348.038166 -279.964134)
		(width 0.0889)
		(layer "In11.Cu")
		(net "UPI_CPU1_CPU0_P2P2_DN<11>")
	)
	(segment
		(start 348.977966 -278.346408)
		(end 348.977966 -278.327866)
		(width 0.0889)
		(layer "In11.Cu")
		(net "UPI_CPU1_CPU0_P2P2_DN<11>")
	)
	(segment
		(start 345.87434 -286.965898)
		(end 345.88196 -286.961326)
		(width 0.0889)
		(layer "In11.Cu")
		(net "UPI_CPU1_CPU0_P2P2_DN<11>")
	)
	(segment
		(start 345.866974 -286.970216)
		(end 345.871038 -286.96793)
		(width 0.0889)
		(layer "In11.Cu")
		(net "UPI_CPU1_CPU0_P2P2_DN<11>")
	)
	(segment
		(start 346.815664 -283.709364)
		(end 346.827856 -283.702252)
		(width 0.0889)
		(layer "In11.Cu")
		(net "UPI_CPU1_CPU0_P2P2_DN<11>")
	)
	(segment
		(start 345.866974 -286.969962)
		(end 345.866974 -286.970216)
		(width 0.0889)
		(layer "In11.Cu")
		(net "UPI_CPU1_CPU0_P2P2_DN<11>")
	)
	(segment
		(start 345.871038 -286.96793)
		(end 345.872562 -286.966914)
		(width 0.0889)
		(layer "In11.Cu")
		(net "UPI_CPU1_CPU0_P2P2_DN<11>")
	)
	(segment
		(start 95.02267 -285.17088)
		(end 95.01505 -285.175452)
		(width 0.0889)
		(layer "In11.Cu")
		(net "UPI_CPU1_CPU0_P2P2_DN<11>")
	)
	(segment
		(start 96.63303 -379.219714)
		(end 125.68936 -383.52984)
		(width 0.14732)
		(layer "In11.Cu")
		(net "UPI_CPU1_CPU0_P2P2_DN<11>")
	)
	(segment
		(start 285.611824 -333.75219)
		(end 308.002178 -333.75219)
		(width 0.14732)
		(layer "In11.Cu")
		(net "UPI_CPU1_CPU0_P2P2_DN<11>")
	)
	(segment
		(start 345.218766 -288.121598)
		(end 345.218766 -288.103056)
		(width 0.0889)
		(layer "In11.Cu")
		(net "UPI_CPU1_CPU0_P2P2_DN<11>")
	)
	(segment
		(start 94.226634 -291.474398)
		(end 94.226634 -291.496496)
		(width 0.0889)
		(layer "In11.Cu")
		(net "UPI_CPU1_CPU0_P2P2_DN<11>")
	)
	(segment
		(start 352.015552 -274.809712)
		(end 352.172016 -275.08073)
		(width 0.0889)
		(layer "In11.Cu")
		(net "UPI_CPU1_CPU0_P2P2_DN<11>")
	)
	(segment
		(start 92.7989 -299.870622)
		(end 91.251024 -301.140876)
		(width 0.14732)
		(layer "In11.Cu")
		(net "UPI_CPU1_CPU0_P2P2_DN<11>")
	)
	(segment
		(start 163.202874 -383.4511)
		(end 261.427214 -375.131584)
		(width 0.14732)
		(layer "In11.Cu")
		(net "UPI_CPU1_CPU0_P2P2_DN<11>")
	)
	(segment
		(start 344.356944 -290.91763)
		(end 344.497406 -290.91763)
		(width 0.0889)
		(layer "In11.Cu")
		(net "UPI_CPU1_CPU0_P2P2_DN<11>")
	)
	(segment
		(start 345.014804 -290.25977)
		(end 345.218512 -290.056062)
		(width 0.0889)
		(layer "In11.Cu")
		(net "UPI_CPU1_CPU0_P2P2_DN<11>")
	)
	(segment
		(start 344.497406 -290.91763)
		(end 344.623136 -290.7919)
		(width 0.0889)
		(layer "In11.Cu")
		(net "UPI_CPU1_CPU0_P2P2_DN<11>")
	)
	(segment
		(start 98.967798 -281.576526)
		(end 98.967798 -281.59202)
		(width 0.0889)
		(layer "In11.Cu")
		(net "UPI_CPU1_CPU0_P2P2_DN<11>")
	)
	(segment
		(start 348.216728 -279.644856)
		(end 348.225618 -279.639776)
		(width 0.0889)
		(layer "In11.Cu")
		(net "UPI_CPU1_CPU0_P2P2_DN<11>")
	)
	(segment
		(start 94.084394 -289.446462)
		(end 94.084394 -289.446208)
		(width 0.0889)
		(layer "In11.Cu")
		(net "UPI_CPU1_CPU0_P2P2_DN<11>")
	)
	(segment
		(start 345.872562 -286.966914)
		(end 345.87434 -286.965898)
		(width 0.0889)
		(layer "In11.Cu")
		(net "UPI_CPU1_CPU0_P2P2_DN<11>")
	)
	(segment
		(start 347.746574 -280.458926)
		(end 347.755464 -280.453846)
		(width 0.0889)
		(layer "In11.Cu")
		(net "UPI_CPU1_CPU0_P2P2_DN<11>")
	)
	(segment
		(start 98.789236 -281.911044)
		(end 98.785172 -281.91333)
		(width 0.0889)
		(layer "In11.Cu")
		(net "UPI_CPU1_CPU0_P2P2_DN<11>")
	)
	(arc
		(start 99.437444 -280.778204)
		(mid 99.389765 -280.961104)
		(end 99.258882 -281.097482)
		(width 0.0889)
		(layer "In11.Cu")
		(net "UPI_CPU1_CPU0_P2P2_DN<11>")
	)
	(arc
		(start 94.081346 -288.427414)
		(mid 93.87906 -288.626395)
		(end 93.798898 -288.898584)
		(width 0.0889)
		(layer "In11.Cu")
		(net "UPI_CPU1_CPU0_P2P2_DN<11>")
	)
	(arc
		(start 349.165418 -276.384258)
		(mid 349.369753 -276.181653)
		(end 349.447866 -275.904706)
		(width 0.0889)
		(layer "In11.Cu")
		(net "UPI_CPU1_CPU0_P2P2_DN<11>")
	)
	(arc
		(start 348.97822 -276.702012)
		(mid 349.027327 -276.522823)
		(end 349.156528 -276.389338)
		(width 0.0889)
		(layer "In11.Cu")
		(net "UPI_CPU1_CPU0_P2P2_DN<11>")
	)
	(arc
		(start 95.029782 -286.156146)
		(mid 95.208379 -286.475424)
		(end 95.029782 -286.794702)
		(width 0.0889)
		(layer "In11.Cu")
		(net "UPI_CPU1_CPU0_P2P2_DN<11>")
	)
	(arc
		(start 349.156528 -277.027894)
		(mid 349.028209 -276.895922)
		(end 348.97822 -276.718776)
		(width 0.0889)
		(layer "In11.Cu")
		(net "UPI_CPU1_CPU0_P2P2_DN<11>")
	)
	(arc
		(start 350.494346 -274.765008)
		(mid 350.770821 -274.832328)
		(end 351.045018 -274.756372)
		(width 0.0889)
		(layer "In11.Cu")
		(net "UPI_CPU1_CPU0_P2P2_DN<11>")
	)
	(arc
		(start 101.787198 -279.964134)
		(mid 101.599931 -280.28841)
		(end 101.22535 -280.288492)
		(width 0.0889)
		(layer "In11.Cu")
		(net "UPI_CPU1_CPU0_P2P2_DN<11>")
	)
	(arc
		(start 94.738444 -287.28924)
		(mid 94.690765 -287.47214)
		(end 94.559882 -287.608518)
		(width 0.0889)
		(layer "In11.Cu")
		(net "UPI_CPU1_CPU0_P2P2_DN<11>")
	)
	(arc
		(start 348.508066 -279.150318)
		(mid 348.555745 -278.967418)
		(end 348.686628 -278.83104)
		(width 0.0889)
		(layer "In11.Cu")
		(net "UPI_CPU1_CPU0_P2P2_DN<11>")
	)
	(arc
		(start 99.720146 -280.288492)
		(mid 99.516665 -280.489296)
		(end 99.437444 -280.76398)
		(width 0.0889)
		(layer "In11.Cu")
		(net "UPI_CPU1_CPU0_P2P2_DN<11>")
	)
	(arc
		(start 348.97822 -276.718776)
		(mid 348.978126 -276.710394)
		(end 348.97822 -276.702012)
		(width 0.0889)
		(layer "In11.Cu")
		(net "UPI_CPU1_CPU0_P2P2_DN<11>")
	)
	(arc
		(start 350.105218 -274.756372)
		(mid 350.292416 -274.706229)
		(end 350.479614 -274.756372)
		(width 0.0889)
		(layer "In11.Cu")
		(net "UPI_CPU1_CPU0_P2P2_DN<11>")
	)
	(arc
		(start 344.748866 -288.917126)
		(mid 344.796545 -288.734226)
		(end 344.927428 -288.597848)
		(width 0.0889)
		(layer "In11.Cu")
		(net "UPI_CPU1_CPU0_P2P2_DN<11>")
	)
	(arc
		(start 94.084394 -289.446208)
		(mid 94.193429 -289.529937)
		(end 94.268544 -289.64509)
		(width 0.0889)
		(layer "In11.Cu")
		(net "UPI_CPU1_CPU0_P2P2_DN<11>")
	)
	(arc
		(start 349.165164 -278.012144)
		(mid 349.370236 -277.808465)
		(end 349.447866 -277.530052)
		(width 0.0889)
		(layer "In11.Cu")
		(net "UPI_CPU1_CPU0_P2P2_DN<11>")
	)
	(arc
		(start 97.370392 -282.730194)
		(mid 97.168106 -282.929175)
		(end 97.087944 -283.201364)
		(width 0.0889)
		(layer "In11.Cu")
		(net "UPI_CPU1_CPU0_P2P2_DN<11>")
	)
	(arc
		(start 348.977966 -278.327866)
		(mid 349.030236 -278.145501)
		(end 349.165164 -278.012144)
		(width 0.0889)
		(layer "In11.Cu")
		(net "UPI_CPU1_CPU0_P2P2_DN<11>")
	)
	(arc
		(start 348.231714 -279.63622)
		(mid 348.434127 -279.429807)
		(end 348.508066 -279.150318)
		(width 0.0889)
		(layer "In11.Cu")
		(net "UPI_CPU1_CPU0_P2P2_DN<11>")
	)
	(arc
		(start 98.967798 -281.59202)
		(mid 98.920119 -281.77492)
		(end 98.789236 -281.911298)
		(width 0.0889)
		(layer "In11.Cu")
		(net "UPI_CPU1_CPU0_P2P2_DN<11>")
	)
	(arc
		(start 349.917766 -275.08073)
		(mid 349.965445 -274.89783)
		(end 350.096328 -274.761452)
		(width 0.0889)
		(layer "In11.Cu")
		(net "UPI_CPU1_CPU0_P2P2_DN<11>")
	)
	(arc
		(start 347.755464 -280.453846)
		(mid 347.958945 -280.253042)
		(end 348.038166 -279.978358)
		(width 0.0889)
		(layer "In11.Cu")
		(net "UPI_CPU1_CPU0_P2P2_DN<11>")
	)
	(arc
		(start 102.014528 -279.51049)
		(mid 102.006087 -279.51689)
		(end 101.997764 -279.523444)
		(width 0.0889)
		(layer "In11.Cu")
		(net "UPI_CPU1_CPU0_P2P2_DN<11>")
	)
	(arc
		(start 95.960692 -283.544264)
		(mid 95.756357 -283.746869)
		(end 95.678244 -284.023816)
		(width 0.0889)
		(layer "In11.Cu")
		(net "UPI_CPU1_CPU0_P2P2_DN<11>")
	)
	(arc
		(start 345.88196 -286.961326)
		(mid 346.084547 -286.754975)
		(end 346.158566 -286.475424)
		(width 0.0889)
		(layer "In11.Cu")
		(net "UPI_CPU1_CPU0_P2P2_DN<11>")
	)
	(arc
		(start 345.218766 -288.103056)
		(mid 345.266445 -287.920156)
		(end 345.397328 -287.783778)
		(width 0.0889)
		(layer "In11.Cu")
		(net "UPI_CPU1_CPU0_P2P2_DN<11>")
	)
	(arc
		(start 96.52635 -283.544264)
		(mid 96.249537 -283.468394)
		(end 95.971106 -283.538168)
		(width 0.0889)
		(layer "In11.Cu")
		(net "UPI_CPU1_CPU0_P2P2_DN<11>")
	)
	(arc
		(start 347.285818 -282.895548)
		(mid 347.4871 -282.698061)
		(end 347.568012 -282.427934)
		(width 0.0889)
		(layer "In11.Cu")
		(net "UPI_CPU1_CPU0_P2P2_DN<11>")
	)
	(arc
		(start 100.659946 -280.288492)
		(mid 100.472748 -280.338635)
		(end 100.28555 -280.288492)
		(width 0.0889)
		(layer "In11.Cu")
		(net "UPI_CPU1_CPU0_P2P2_DN<11>")
	)
	(arc
		(start 347.285818 -281.267662)
		(mid 347.488641 -281.067431)
		(end 347.568012 -280.793698)
		(width 0.0889)
		(layer "In11.Cu")
		(net "UPI_CPU1_CPU0_P2P2_DN<11>")
	)
	(arc
		(start 345.88196 -285.33344)
		(mid 346.084547 -285.127089)
		(end 346.158566 -284.847538)
		(width 0.0889)
		(layer "In11.Cu")
		(net "UPI_CPU1_CPU0_P2P2_DN<11>")
	)
	(arc
		(start 345.688412 -287.28924)
		(mid 345.736091 -287.10634)
		(end 345.866974 -286.969962)
		(width 0.0889)
		(layer "In11.Cu")
		(net "UPI_CPU1_CPU0_P2P2_DN<11>")
	)
	(arc
		(start 99.249992 -281.102562)
		(mid 99.047169 -281.302793)
		(end 98.967798 -281.576526)
		(width 0.0889)
		(layer "In11.Cu")
		(net "UPI_CPU1_CPU0_P2P2_DN<11>")
	)
	(arc
		(start 345.866974 -285.980632)
		(mid 345.688256 -285.661354)
		(end 345.866974 -285.342076)
		(width 0.0889)
		(layer "In11.Cu")
		(net "UPI_CPU1_CPU0_P2P2_DN<11>")
	)
	(arc
		(start 347.568012 -280.778204)
		(mid 347.615691 -280.595304)
		(end 347.746574 -280.458926)
		(width 0.0889)
		(layer "In11.Cu")
		(net "UPI_CPU1_CPU0_P2P2_DN<11>")
	)
	(arc
		(start 345.406218 -287.778698)
		(mid 345.609041 -287.578467)
		(end 345.688412 -287.304734)
		(width 0.0889)
		(layer "In11.Cu")
		(net "UPI_CPU1_CPU0_P2P2_DN<11>")
	)
	(arc
		(start 100.28555 -280.288492)
		(mid 100.011321 -280.212567)
		(end 99.734878 -280.279856)
		(width 0.0889)
		(layer "In11.Cu")
		(net "UPI_CPU1_CPU0_P2P2_DN<11>")
	)
	(arc
		(start 347.568012 -282.390342)
		(mid 347.488642 -282.116608)
		(end 347.285818 -281.916378)
		(width 0.0889)
		(layer "In11.Cu")
		(net "UPI_CPU1_CPU0_P2P2_DN<11>")
	)
	(arc
		(start 98.497644 -282.405836)
		(mid 98.449965 -282.588736)
		(end 98.319082 -282.725114)
		(width 0.0889)
		(layer "In11.Cu")
		(net "UPI_CPU1_CPU0_P2P2_DN<11>")
	)
	(arc
		(start 347.276928 -281.911298)
		(mid 347.098452 -281.59202)
		(end 347.276928 -281.272742)
		(width 0.0889)
		(layer "In11.Cu")
		(net "UPI_CPU1_CPU0_P2P2_DN<11>")
	)
	(arc
		(start 98.77425 -281.919934)
		(mid 98.571663 -282.126285)
		(end 98.497644 -282.405836)
		(width 0.0889)
		(layer "In11.Cu")
		(net "UPI_CPU1_CPU0_P2P2_DN<11>")
	)
	(arc
		(start 349.635064 -275.570442)
		(mid 349.838545 -275.369638)
		(end 349.917766 -275.094954)
		(width 0.0889)
		(layer "In11.Cu")
		(net "UPI_CPU1_CPU0_P2P2_DN<11>")
	)
	(arc
		(start 344.933016 -289.277806)
		(mid 344.823869 -289.193878)
		(end 344.748866 -289.078416)
		(width 0.0889)
		(layer "In11.Cu")
		(net "UPI_CPU1_CPU0_P2P2_DN<11>")
	)
	(arc
		(start 97.087944 -283.228542)
		(mid 97.035674 -283.410907)
		(end 96.900746 -283.544264)
		(width 0.0889)
		(layer "In11.Cu")
		(net "UPI_CPU1_CPU0_P2P2_DN<11>")
	)
	(arc
		(start 344.936318 -288.592768)
		(mid 345.138604 -288.393787)
		(end 345.218766 -288.121598)
		(width 0.0889)
		(layer "In11.Cu")
		(net "UPI_CPU1_CPU0_P2P2_DN<11>")
	)
	(arc
		(start 97.935796 -282.730194)
		(mid 97.653094 -282.654452)
		(end 97.370392 -282.730194)
		(width 0.0889)
		(layer "In11.Cu")
		(net "UPI_CPU1_CPU0_P2P2_DN<11>")
	)
	(arc
		(start 347.098366 -283.219906)
		(mid 347.146045 -283.037006)
		(end 347.276928 -282.900628)
		(width 0.0889)
		(layer "In11.Cu")
		(net "UPI_CPU1_CPU0_P2P2_DN<11>")
	)
	(arc
		(start 349.447866 -277.522432)
		(mid 349.37395 -277.24293)
		(end 349.171514 -277.03653)
		(width 0.0889)
		(layer "In11.Cu")
		(net "UPI_CPU1_CPU0_P2P2_DN<11>")
	)
	(arc
		(start 349.447866 -275.886164)
		(mid 349.500136 -275.703799)
		(end 349.635064 -275.570442)
		(width 0.0889)
		(layer "In11.Cu")
		(net "UPI_CPU1_CPU0_P2P2_DN<11>")
	)
	(arc
		(start 346.158566 -284.847538)
		(mid 346.206245 -284.664638)
		(end 346.337128 -284.52826)
		(width 0.0889)
		(layer "In11.Cu")
		(net "UPI_CPU1_CPU0_P2P2_DN<11>")
	)
	(arc
		(start 95.020892 -286.799782)
		(mid 94.816557 -287.002387)
		(end 94.738444 -287.279334)
		(width 0.0889)
		(layer "In11.Cu")
		(net "UPI_CPU1_CPU0_P2P2_DN<11>")
	)
	(arc
		(start 95.208598 -284.847538)
		(mid 95.160919 -285.030438)
		(end 95.030036 -285.166816)
		(width 0.0889)
		(layer "In11.Cu")
		(net "UPI_CPU1_CPU0_P2P2_DN<11>")
	)
	(arc
		(start 95.678244 -284.033722)
		(mid 95.630565 -284.216622)
		(end 95.499682 -284.353)
		(width 0.0889)
		(layer "In11.Cu")
		(net "UPI_CPU1_CPU0_P2P2_DN<11>")
	)
	(arc
		(start 101.22535 -280.288492)
		(mid 100.951121 -280.212567)
		(end 100.674678 -280.279856)
		(width 0.0889)
		(layer "In11.Cu")
		(net "UPI_CPU1_CPU0_P2P2_DN<11>")
	)
	(arc
		(start 351.4471 -274.77212)
		(mid 351.65773 -274.837424)
		(end 351.875852 -274.80514)
		(width 0.0889)
		(layer "In11.Cu")
		(net "UPI_CPU1_CPU0_P2P2_DN<11>")
	)
	(arc
		(start 94.738444 -285.679896)
		(mid 94.818606 -285.952085)
		(end 95.020892 -286.151066)
		(width 0.0889)
		(layer "In11.Cu")
		(net "UPI_CPU1_CPU0_P2P2_DN<11>")
	)
	(arc
		(start 94.550992 -287.613598)
		(mid 94.348169 -287.813829)
		(end 94.268798 -288.087562)
		(width 0.0889)
		(layer "In11.Cu")
		(net "UPI_CPU1_CPU0_P2P2_DN<11>")
	)
	(arc
		(start 348.038166 -279.964134)
		(mid 348.085845 -279.781234)
		(end 348.216728 -279.644856)
		(width 0.0889)
		(layer "In11.Cu")
		(net "UPI_CPU1_CPU0_P2P2_DN<11>")
	)
	(arc
		(start 348.695518 -278.82596)
		(mid 348.899853 -278.623355)
		(end 348.977966 -278.346408)
		(width 0.0889)
		(layer "In11.Cu")
		(net "UPI_CPU1_CPU0_P2P2_DN<11>")
	)
	(arc
		(start 346.346018 -284.52318)
		(mid 346.548841 -284.322949)
		(end 346.628212 -284.049216)
		(width 0.0889)
		(layer "In11.Cu")
		(net "UPI_CPU1_CPU0_P2P2_DN<11>")
	)
	(arc
		(start 95.01505 -285.175452)
		(mid 94.812463 -285.381803)
		(end 94.738444 -285.661354)
		(width 0.0889)
		(layer "In11.Cu")
		(net "UPI_CPU1_CPU0_P2P2_DN<11>")
	)
	(arc
		(start 346.827856 -283.702252)
		(mid 347.026084 -283.496404)
		(end 347.098366 -283.219906)
		(width 0.0889)
		(layer "In11.Cu")
		(net "UPI_CPU1_CPU0_P2P2_DN<11>")
	)
	(arc
		(start 346.158566 -286.4612)
		(mid 346.079347 -286.186515)
		(end 345.875864 -285.985712)
		(width 0.0889)
		(layer "In11.Cu")
		(net "UPI_CPU1_CPU0_P2P2_DN<11>")
	)
	(arc
		(start 345.218512 -289.60953)
		(mid 345.107174 -289.41663)
		(end 344.933016 -289.277806)
		(width 0.0889)
		(layer "In11.Cu")
		(net "UPI_CPU1_CPU0_P2P2_DN<11>")
	)
	(arc
		(start 94.268798 -288.103056)
		(mid 94.221119 -288.285956)
		(end 94.090236 -288.422334)
		(width 0.0889)
		(layer "In11.Cu")
		(net "UPI_CPU1_CPU0_P2P2_DN<11>")
	)
	(arc
		(start 95.490792 -284.35808)
		(mid 95.287969 -284.558311)
		(end 95.208598 -284.832044)
		(width 0.0889)
		(layer "In11.Cu")
		(net "UPI_CPU1_CPU0_P2P2_DN<11>")
	)
	(arc
		(start 101.978968 -279.53843)
		(mid 101.840957 -279.710585)
		(end 101.78796 -279.924764)
		(width 0.0889)
		(layer "In11.Cu")
		(net "UPI_CPU1_CPU0_P2P2_DN<11>")
	)
	(arc
		(start 346.628212 -284.033722)
		(mid 346.675891 -283.850822)
		(end 346.806774 -283.714444)
		(width 0.0889)
		(layer "In11.Cu")
		(net "UPI_CPU1_CPU0_P2P2_DN<11>")
	)
	(arc
		(start 96.900746 -283.544264)
		(mid 96.713548 -283.594407)
		(end 96.52635 -283.544264)
		(width 0.0889)
		(layer "In11.Cu")
		(net "UPI_CPU1_CPU0_P2P2_DN<11>")
	)
	(arc
		(start 93.798898 -289.114738)
		(mid 93.910236 -289.307638)
		(end 94.084394 -289.446462)
		(width 0.0889)
		(layer "In11.Cu")
		(net "UPI_CPU1_CPU0_P2P2_DN<11>")
	)
	(arc
		(start 351.044764 -274.755864)
		(mid 351.225111 -274.705729)
		(end 351.407222 -274.749006)
		(width 0.0889)
		(layer "In11.Cu")
		(net "UPI_CPU1_CPU0_P2P2_DN<11>")
	)
	(arc
		(start 98.310192 -282.730194)
		(mid 98.122994 -282.780337)
		(end 97.935796 -282.730194)
		(width 0.0889)
		(layer "In11.Cu")
		(net "UPI_CPU1_CPU0_P2P2_DN<11>")
	)
	(segment
		(start 350.292162 -275.080476)
		(end 350.292416 -275.08073)
		(width 0.13208)
		(layer "F.Cu")
		(net "UPI_CPU1_CPU0_P2P2_DN<10>")
	)
	(segment
		(start 350.292162 -274.54479)
		(end 350.292162 -275.080476)
		(width 0.13208)
		(layer "F.Cu")
		(net "UPI_CPU1_CPU0_P2P2_DN<10>")
	)
	(segment
		(start 102.822248 -278.614378)
		(end 102.822248 -279.150064)
		(width 0.13208)
		(layer "F.Cu")
		(net "UPI_CPU1_CPU0_P2P2_DN<10>")
	)
	(segment
		(start 102.822248 -279.150064)
		(end 102.821994 -279.150318)
		(width 0.13208)
		(layer "F.Cu")
		(net "UPI_CPU1_CPU0_P2P2_DN<10>")
	)
	(segment
		(start 347.655896 -283.546804)
		(end 347.656658 -283.546296)
		(width 0.0889)
		(layer "In11.Cu")
		(net "UPI_CPU1_CPU0_P2P2_DN<10>")
	)
	(segment
		(start 96.054672 -282.08224)
		(end 96.047306 -282.086558)
		(width 0.0889)
		(layer "In11.Cu")
		(net "UPI_CPU1_CPU0_P2P2_DN<10>")
	)
	(segment
		(start 65.041018 -332.508352)
		(end 65.041018 -354.48621)
		(width 0.14732)
		(layer "In11.Cu")
		(net "UPI_CPU1_CPU0_P2P2_DN<10>")
	)
	(segment
		(start 348.317312 -280.778204)
		(end 348.317312 -280.76398)
		(width 0.0889)
		(layer "In11.Cu")
		(net "UPI_CPU1_CPU0_P2P2_DN<10>")
	)
	(segment
		(start 86.08441 -304.484278)
		(end 85.746336 -304.761646)
		(width 0.14732)
		(layer "In11.Cu")
		(net "UPI_CPU1_CPU0_P2P2_DN<10>")
	)
	(segment
		(start 346.72016 -286.799782)
		(end 346.720922 -286.799274)
		(width 0.0889)
		(layer "In11.Cu")
		(net "UPI_CPU1_CPU0_P2P2_DN<10>")
	)
	(segment
		(start 93.618304 -290.309554)
		(end 93.519244 -290.408614)
		(width 0.0889)
		(layer "In11.Cu")
		(net "UPI_CPU1_CPU0_P2P2_DN<10>")
	)
	(segment
		(start 85.574886 -304.744882)
		(end 79.033116 -310.112918)
		(width 0.14732)
		(layer "In11.Cu")
		(net "UPI_CPU1_CPU0_P2P2_DN<10>")
	)
	(segment
		(start 93.561408 -294.058848)
		(end 93.561408 -294.080946)
		(width 0.0889)
		(layer "In11.Cu")
		(net "UPI_CPU1_CPU0_P2P2_DN<10>")
	)
	(segment
		(start 94.18193 -285.333948)
		(end 94.180914 -285.334456)
		(width 0.0889)
		(layer "In11.Cu")
		(net "UPI_CPU1_CPU0_P2P2_DN<10>")
	)
	(segment
		(start 88.042496 -302.877474)
		(end 87.704422 -303.154842)
		(width 0.14732)
		(layer "In11.Cu")
		(net "UPI_CPU1_CPU0_P2P2_DN<10>")
	)
	(segment
		(start 343.792556 -298.393104)
		(end 343.958418 -298.062396)
		(width 0.14732)
		(layer "In11.Cu")
		(net "UPI_CPU1_CPU0_P2P2_DN<10>")
	)
	(segment
		(start 93.519244 -291.693854)
		(end 93.618304 -291.792914)
		(width 0.0889)
		(layer "In11.Cu")
		(net "UPI_CPU1_CPU0_P2P2_DN<10>")
	)
	(segment
		(start 345.968066 -289.979862)
		(end 345.968066 -289.64509)
		(width 0.0889)
		(layer "In11.Cu")
		(net "UPI_CPU1_CPU0_P2P2_DN<10>")
	)
	(segment
		(start 93.989144 -287.28924)
		(end 93.989144 -287.304734)
		(width 0.0889)
		(layer "In11.Cu")
		(net "UPI_CPU1_CPU0_P2P2_DN<10>")
	)
	(segment
		(start 65.31991 -331.154024)
		(end 65.161414 -331.284072)
		(width 0.14732)
		(layer "In11.Cu")
		(net "UPI_CPU1_CPU0_P2P2_DN<10>")
	)
	(segment
		(start 344.794078 -291.432488)
		(end 344.794078 -291.15385)
		(width 0.0889)
		(layer "In11.Cu")
		(net "UPI_CPU1_CPU0_P2P2_DN<10>")
	)
	(segment
		(start 347.656658 -283.546296)
		(end 347.659452 -283.544772)
		(width 0.0889)
		(layer "In11.Cu")
		(net "UPI_CPU1_CPU0_P2P2_DN<10>")
	)
	(segment
		(start 347.659452 -283.544772)
		(end 347.660214 -283.544264)
		(width 0.0889)
		(layer "In11.Cu")
		(net "UPI_CPU1_CPU0_P2P2_DN<10>")
	)
	(segment
		(start 94.180152 -285.334964)
		(end 94.177358 -285.336488)
		(width 0.0889)
		(layer "In11.Cu")
		(net "UPI_CPU1_CPU0_P2P2_DN<10>")
	)
	(segment
		(start 93.519244 -291.140134)
		(end 93.618304 -291.239194)
		(width 0.0889)
		(layer "In11.Cu")
		(net "UPI_CPU1_CPU0_P2P2_DN<10>")
	)
	(segment
		(start 93.519244 -290.408614)
		(end 93.519244 -290.586414)
		(width 0.0889)
		(layer "In11.Cu")
		(net "UPI_CPU1_CPU0_P2P2_DN<10>")
	)
	(segment
		(start 99.34575 -279.639776)
		(end 99.33686 -279.644856)
		(width 0.0889)
		(layer "In11.Cu")
		(net "UPI_CPU1_CPU0_P2P2_DN<10>")
	)
	(segment
		(start 93.618304 -291.792914)
		(end 93.618304 -291.970714)
		(width 0.0889)
		(layer "In11.Cu")
		(net "UPI_CPU1_CPU0_P2P2_DN<10>")
	)
	(segment
		(start 270.8656 -346.362528)
		(end 280.917904 -336.310224)
		(width 0.14732)
		(layer "In11.Cu")
		(net "UPI_CPU1_CPU0_P2P2_DN<10>")
	)
	(segment
		(start 344.752168 -291.474398)
		(end 344.794078 -291.432488)
		(width 0.0889)
		(layer "In11.Cu")
		(net "UPI_CPU1_CPU0_P2P2_DN<10>")
	)
	(segment
		(start 94.176596 -285.336996)
		(end 94.169738 -285.340806)
		(width 0.0889)
		(layer "In11.Cu")
		(net "UPI_CPU1_CPU0_P2P2_DN<10>")
	)
	(segment
		(start 90.512138 -300.693074)
		(end 89.79027 -301.285402)
		(width 0.14732)
		(layer "In11.Cu")
		(net "UPI_CPU1_CPU0_P2P2_DN<10>")
	)
	(segment
		(start 161.16808 -384.09753)
		(end 162.75177 -384.089402)
		(width 0.14732)
		(layer "In11.Cu")
		(net "UPI_CPU1_CPU0_P2P2_DN<10>")
	)
	(segment
		(start 125.688344 -384.09753)
		(end 161.16808 -384.09753)
		(width 0.14732)
		(layer "In11.Cu")
		(net "UPI_CPU1_CPU0_P2P2_DN<10>")
	)
	(segment
		(start 65.226184 -330.629006)
		(end 65.356232 -330.787248)
		(width 0.14732)
		(layer "In11.Cu")
		(net "UPI_CPU1_CPU0_P2P2_DN<10>")
	)
	(segment
		(start 346.25026 -287.613598)
		(end 346.25915 -287.608518)
		(width 0.0889)
		(layer "In11.Cu")
		(net "UPI_CPU1_CPU0_P2P2_DN<10>")
	)
	(segment
		(start 74.458322 -370.651024)
		(end 96.45142 -379.76048)
		(width 0.14732)
		(layer "In11.Cu")
		(net "UPI_CPU1_CPU0_P2P2_DN<10>")
	)
	(segment
		(start 93.519244 -292.623494)
		(end 93.519244 -292.801294)
		(width 0.0889)
		(layer "In11.Cu")
		(net "UPI_CPU1_CPU0_P2P2_DN<10>")
	)
	(segment
		(start 95.868744 -282.405836)
		(end 95.868744 -282.424378)
		(width 0.0889)
		(layer "In11.Cu")
		(net "UPI_CPU1_CPU0_P2P2_DN<10>")
	)
	(segment
		(start 103.018082 -278.83104)
		(end 103.009192 -278.82596)
		(width 0.0889)
		(layer "In11.Cu")
		(net "UPI_CPU1_CPU0_P2P2_DN<10>")
	)
	(segment
		(start 96.995996 -282.081478)
		(end 96.981264 -282.090114)
		(width 0.0889)
		(layer "In11.Cu")
		(net "UPI_CPU1_CPU0_P2P2_DN<10>")
	)
	(segment
		(start 93.70695 -287.778698)
		(end 93.69806 -287.783778)
		(width 0.0889)
		(layer "In11.Cu")
		(net "UPI_CPU1_CPU0_P2P2_DN<10>")
	)
	(segment
		(start 93.618304 -290.863274)
		(end 93.519244 -290.962334)
		(width 0.0889)
		(layer "In11.Cu")
		(net "UPI_CPU1_CPU0_P2P2_DN<10>")
	)
	(segment
		(start 337.784694 -303.203102)
		(end 341.209884 -301.784258)
		(width 0.14732)
		(layer "In11.Cu")
		(net "UPI_CPU1_CPU0_P2P2_DN<10>")
	)
	(segment
		(start 103.134668 -279.150318)
		(end 103.192072 -279.092914)
		(width 0.0889)
		(layer "In11.Cu")
		(net "UPI_CPU1_CPU0_P2P2_DN<10>")
	)
	(segment
		(start 346.723462 -286.79775)
		(end 346.72905 -286.794702)
		(width 0.0889)
		(layer "In11.Cu")
		(net "UPI_CPU1_CPU0_P2P2_DN<10>")
	)
	(segment
		(start 89.773506 -301.456852)
		(end 89.435432 -301.734474)
		(width 0.14732)
		(layer "In11.Cu")
		(net "UPI_CPU1_CPU0_P2P2_DN<10>")
	)
	(segment
		(start 87.704422 -303.154842)
		(end 87.532972 -303.137824)
		(width 0.14732)
		(layer "In11.Cu")
		(net "UPI_CPU1_CPU0_P2P2_DN<10>")
	)
	(segment
		(start 96.056196 -282.081478)
		(end 96.054672 -282.08224)
		(width 0.0889)
		(layer "In11.Cu")
		(net "UPI_CPU1_CPU0_P2P2_DN<10>")
	)
	(segment
		(start 79.033116 -310.112918)
		(end 68.357242 -320.788792)
		(width 0.14732)
		(layer "In11.Cu")
		(net "UPI_CPU1_CPU0_P2P2_DN<10>")
	)
	(segment
		(start 88.059514 -302.70577)
		(end 88.042496 -302.877474)
		(width 0.14732)
		(layer "In11.Cu")
		(net "UPI_CPU1_CPU0_P2P2_DN<10>")
	)
	(segment
		(start 350.60509 -275.08073)
		(end 350.292416 -275.08073)
		(width 0.0889)
		(layer "In11.Cu")
		(net "UPI_CPU1_CPU0_P2P2_DN<10>")
	)
	(segment
		(start 344.498676 -295.344088)
		(end 344.402918 -295.200578)
		(width 0.14732)
		(layer "In11.Cu")
		(net "UPI_CPU1_CPU0_P2P2_DN<10>")
	)
	(segment
		(start 344.26144 -296.537888)
		(end 344.165682 -296.394378)
		(width 0.14732)
		(layer "In11.Cu")
		(net "UPI_CPU1_CPU0_P2P2_DN<10>")
	)
	(segment
		(start 344.165682 -296.394378)
		(end 344.250772 -295.965626)
		(width 0.14732)
		(layer "In11.Cu")
		(net "UPI_CPU1_CPU0_P2P2_DN<10>")
	)
	(segment
		(start 343.958418 -298.062396)
		(end 343.958164 -298.062396)
		(width 0.14732)
		(layer "In11.Cu")
		(net "UPI_CPU1_CPU0_P2P2_DN<10>")
	)
	(segment
		(start 94.459298 -286.4612)
		(end 94.459298 -286.475424)
		(width 0.0889)
		(layer "In11.Cu")
		(net "UPI_CPU1_CPU0_P2P2_DN<10>")
	)
	(segment
		(start 343.958164 -298.062396)
		(end 344.043254 -297.634152)
		(width 0.14732)
		(layer "In11.Cu")
		(net "UPI_CPU1_CPU0_P2P2_DN<10>")
	)
	(segment
		(start 65.161414 -331.284072)
		(end 65.041018 -332.508352)
		(width 0.14732)
		(layer "In11.Cu")
		(net "UPI_CPU1_CPU0_P2P2_DN<10>")
	)
	(segment
		(start 315.176662 -327.363074)
		(end 316.274196 -324.7136)
		(width 0.14732)
		(layer "In11.Cu")
		(net "UPI_CPU1_CPU0_P2P2_DN<10>")
	)
	(segment
		(start 344.394282 -295.869868)
		(end 344.498676 -295.344088)
		(width 0.14732)
		(layer "In11.Cu")
		(net "UPI_CPU1_CPU0_P2P2_DN<10>")
	)
	(segment
		(start 93.519244 -290.032694)
		(end 93.618304 -290.131754)
		(width 0.0889)
		(layer "In11.Cu")
		(net "UPI_CPU1_CPU0_P2P2_DN<10>")
	)
	(segment
		(start 102.821994 -279.150318)
		(end 103.134668 -279.150318)
		(width 0.0889)
		(layer "In11.Cu")
		(net "UPI_CPU1_CPU0_P2P2_DN<10>")
	)
	(segment
		(start 270.8656 -366.47628)
		(end 270.8656 -346.362528)
		(width 0.14732)
		(layer "In11.Cu")
		(net "UPI_CPU1_CPU0_P2P2_DN<10>")
	)
	(segment
		(start 350.00946 -276.219158)
		(end 350.01835 -276.214078)
		(width 0.0889)
		(layer "In11.Cu")
		(net "UPI_CPU1_CPU0_P2P2_DN<10>")
	)
	(segment
		(start 93.519244 -290.962334)
		(end 93.519244 -291.140134)
		(width 0.0889)
		(layer "In11.Cu")
		(net "UPI_CPU1_CPU0_P2P2_DN<10>")
	)
	(segment
		(start 344.043254 -297.634152)
		(end 343.947496 -297.490642)
		(width 0.14732)
		(layer "In11.Cu")
		(net "UPI_CPU1_CPU0_P2P2_DN<10>")
	)
	(segment
		(start 92.366338 -299.504354)
		(end 91.15552 -300.497748)
		(width 0.14732)
		(layer "In11.Cu")
		(net "UPI_CPU1_CPU0_P2P2_DN<10>")
	)
	(segment
		(start 93.561408 -297.042078)
		(end 92.764356 -298.967652)
		(width 0.14732)
		(layer "In11.Cu")
		(net "UPI_CPU1_CPU0_P2P2_DN<10>")
	)
	(segment
		(start 94.176596 -286.964882)
		(end 94.175072 -286.965644)
		(width 0.0889)
		(layer "In11.Cu")
		(net "UPI_CPU1_CPU0_P2P2_DN<10>")
	)
	(segment
		(start 92.764356 -298.967652)
		(end 92.366338 -299.504354)
		(width 0.14732)
		(layer "In11.Cu")
		(net "UPI_CPU1_CPU0_P2P2_DN<10>")
	)
	(segment
		(start 348.600014 -281.916378)
		(end 348.608904 -281.911298)
		(width 0.0889)
		(layer "In11.Cu")
		(net "UPI_CPU1_CPU0_P2P2_DN<10>")
	)
	(segment
		(start 349.53956 -278.66086)
		(end 349.54845 -278.65578)
		(width 0.0889)
		(layer "In11.Cu")
		(net "UPI_CPU1_CPU0_P2P2_DN<10>")
	)
	(segment
		(start 348.593918 -281.919934)
		(end 348.600014 -281.916378)
		(width 0.0889)
		(layer "In11.Cu")
		(net "UPI_CPU1_CPU0_P2P2_DN<10>")
	)
	(segment
		(start 347.65488 -283.547312)
		(end 347.655896 -283.546804)
		(width 0.0889)
		(layer "In11.Cu")
		(net "UPI_CPU1_CPU0_P2P2_DN<10>")
	)
	(segment
		(start 343.947496 -297.490642)
		(end 344.032586 -297.06189)
		(width 0.14732)
		(layer "In11.Cu")
		(net "UPI_CPU1_CPU0_P2P2_DN<10>")
	)
	(segment
		(start 344.17635 -296.966132)
		(end 344.26144 -296.537888)
		(width 0.14732)
		(layer "In11.Cu")
		(net "UPI_CPU1_CPU0_P2P2_DN<10>")
	)
	(segment
		(start 341.209884 -301.784258)
		(end 343.22131 -299.772832)
		(width 0.14732)
		(layer "In11.Cu")
		(net "UPI_CPU1_CPU0_P2P2_DN<10>")
	)
	(segment
		(start 349.727012 -278.336502)
		(end 349.727012 -278.328882)
		(width 0.0889)
		(layer "In11.Cu")
		(net "UPI_CPU1_CPU0_P2P2_DN<10>")
	)
	(segment
		(start 261.64413 -375.69775)
		(end 270.8656 -366.47628)
		(width 0.14732)
		(layer "In11.Cu")
		(net "UPI_CPU1_CPU0_P2P2_DN<10>")
	)
	(segment
		(start 93.618304 -292.346634)
		(end 93.618304 -292.524434)
		(width 0.0889)
		(layer "In11.Cu")
		(net "UPI_CPU1_CPU0_P2P2_DN<10>")
	)
	(segment
		(start 344.751914 -294.07104)
		(end 344.752168 -294.070786)
		(width 0.14732)
		(layer "In11.Cu")
		(net "UPI_CPU1_CPU0_P2P2_DN<10>")
	)
	(segment
		(start 349.727012 -276.708616)
		(end 349.727012 -276.69871)
		(width 0.0889)
		(layer "In11.Cu")
		(net "UPI_CPU1_CPU0_P2P2_DN<10>")
	)
	(segment
		(start 89.263728 -301.717456)
		(end 88.926162 -301.99457)
		(width 0.14732)
		(layer "In11.Cu")
		(net "UPI_CPU1_CPU0_P2P2_DN<10>")
	)
	(segment
		(start 93.618304 -292.900354)
		(end 93.618304 -293.078154)
		(width 0.0889)
		(layer "In11.Cu")
		(net "UPI_CPU1_CPU0_P2P2_DN<10>")
	)
	(segment
		(start 345.498166 -289.113722)
		(end 345.498166 -288.898584)
		(width 0.0889)
		(layer "In11.Cu")
		(net "UPI_CPU1_CPU0_P2P2_DN<10>")
	)
	(segment
		(start 93.519244 -294.016684)
		(end 93.561408 -294.058848)
		(width 0.0889)
		(layer "In11.Cu")
		(net "UPI_CPU1_CPU0_P2P2_DN<10>")
	)
	(segment
		(start 98.875596 -280.453846)
		(end 98.866706 -280.458926)
		(width 0.0889)
		(layer "In11.Cu")
		(net "UPI_CPU1_CPU0_P2P2_DN<10>")
	)
	(segment
		(start 97.941892 -282.077922)
		(end 97.921064 -282.090114)
		(width 0.0889)
		(layer "In11.Cu")
		(net "UPI_CPU1_CPU0_P2P2_DN<10>")
	)
	(segment
		(start 348.600014 -280.288492)
		(end 348.608904 -280.283412)
		(width 0.0889)
		(layer "In11.Cu")
		(net "UPI_CPU1_CPU0_P2P2_DN<10>")
	)
	(segment
		(start 346.7227 -286.798258)
		(end 346.723462 -286.79775)
		(width 0.0889)
		(layer "In11.Cu")
		(net "UPI_CPU1_CPU0_P2P2_DN<10>")
	)
	(segment
		(start 93.618304 -291.970714)
		(end 93.519244 -292.069774)
		(width 0.0889)
		(layer "In11.Cu")
		(net "UPI_CPU1_CPU0_P2P2_DN<10>")
	)
	(segment
		(start 350.196912 -277.531068)
		(end 350.196912 -277.513796)
		(width 0.0889)
		(layer "In11.Cu")
		(net "UPI_CPU1_CPU0_P2P2_DN<10>")
	)
	(segment
		(start 346.720922 -286.799274)
		(end 346.7227 -286.798258)
		(width 0.0889)
		(layer "In11.Cu")
		(net "UPI_CPU1_CPU0_P2P2_DN<10>")
	)
	(segment
		(start 308.233826 -334.30591)
		(end 315.176662 -327.363074)
		(width 0.14732)
		(layer "In11.Cu")
		(net "UPI_CPU1_CPU0_P2P2_DN<10>")
	)
	(segment
		(start 101.14026 -278.832056)
		(end 101.129846 -278.82596)
		(width 0.0889)
		(layer "In11.Cu")
		(net "UPI_CPU1_CPU0_P2P2_DN<10>")
	)
	(segment
		(start 344.752168 -294.070786)
		(end 344.752168 -291.496496)
		(width 0.14732)
		(layer "In11.Cu")
		(net "UPI_CPU1_CPU0_P2P2_DN<10>")
	)
	(segment
		(start 344.488008 -294.77208)
		(end 344.631772 -294.676068)
		(width 0.14732)
		(layer "In11.Cu")
		(net "UPI_CPU1_CPU0_P2P2_DN<10>")
	)
	(segment
		(start 344.631772 -294.676068)
		(end 344.751914 -294.07104)
		(width 0.14732)
		(layer "In11.Cu")
		(net "UPI_CPU1_CPU0_P2P2_DN<10>")
	)
	(segment
		(start 345.780614 -288.427414)
		(end 345.789504 -288.422334)
		(width 0.0889)
		(layer "In11.Cu")
		(net "UPI_CPU1_CPU0_P2P2_DN<10>")
	)
	(segment
		(start 88.926162 -301.99457)
		(end 88.909144 -302.16602)
		(width 0.14732)
		(layer "In11.Cu")
		(net "UPI_CPU1_CPU0_P2P2_DN<10>")
	)
	(segment
		(start 93.519498 -288.103056)
		(end 93.519498 -288.121598)
		(width 0.0889)
		(layer "In11.Cu")
		(net "UPI_CPU1_CPU0_P2P2_DN<10>")
	)
	(segment
		(start 93.618304 -293.454074)
		(end 93.618304 -293.631874)
		(width 0.0889)
		(layer "In11.Cu")
		(net "UPI_CPU1_CPU0_P2P2_DN<10>")
	)
	(segment
		(start 66.717418 -324.2564)
		(end 65.376298 -329.10399)
		(width 0.14732)
		(layer "In11.Cu")
		(net "UPI_CPU1_CPU0_P2P2_DN<10>")
	)
	(segment
		(start 94.64675 -284.52318)
		(end 94.63786 -284.52826)
		(width 0.0889)
		(layer "In11.Cu")
		(net "UPI_CPU1_CPU0_P2P2_DN<10>")
	)
	(segment
		(start 94.175072 -286.965644)
		(end 94.167706 -286.969962)
		(width 0.0889)
		(layer "In11.Cu")
		(net "UPI_CPU1_CPU0_P2P2_DN<10>")
	)
	(segment
		(start 94.182946 -286.961072)
		(end 94.176596 -286.964882)
		(width 0.0889)
		(layer "In11.Cu")
		(net "UPI_CPU1_CPU0_P2P2_DN<10>")
	)
	(segment
		(start 88.571324 -302.443388)
		(end 88.39962 -302.426624)
		(width 0.14732)
		(layer "In11.Cu")
		(net "UPI_CPU1_CPU0_P2P2_DN<10>")
	)
	(segment
		(start 348.12986 -282.730194)
		(end 348.13875 -282.725114)
		(width 0.0889)
		(layer "In11.Cu")
		(net "UPI_CPU1_CPU0_P2P2_DN<10>")
	)
	(segment
		(start 344.794078 -291.15385)
		(end 345.968066 -289.979862)
		(width 0.0889)
		(layer "In11.Cu")
		(net "UPI_CPU1_CPU0_P2P2_DN<10>")
	)
	(segment
		(start 343.22131 -299.772832)
		(end 343.792556 -298.393104)
		(width 0.14732)
		(layer "In11.Cu")
		(net "UPI_CPU1_CPU0_P2P2_DN<10>")
	)
	(segment
		(start 99.734878 -279.648412)
		(end 99.720146 -279.639776)
		(width 0.0889)
		(layer "In11.Cu")
		(net "UPI_CPU1_CPU0_P2P2_DN<10>")
	)
	(segment
		(start 99.158298 -279.964134)
		(end 99.158298 -279.978358)
		(width 0.0889)
		(layer "In11.Cu")
		(net "UPI_CPU1_CPU0_P2P2_DN<10>")
	)
	(segment
		(start 100.75545 -278.82596)
		(end 100.74656 -278.83104)
		(width 0.0889)
		(layer "In11.Cu")
		(net "UPI_CPU1_CPU0_P2P2_DN<10>")
	)
	(segment
		(start 91.15552 -300.497748)
		(end 90.512138 -300.693074)
		(width 0.14732)
		(layer "In11.Cu")
		(net "UPI_CPU1_CPU0_P2P2_DN<10>")
	)
	(segment
		(start 346.72905 -286.156146)
		(end 346.720922 -286.151574)
		(width 0.0889)
		(layer "In11.Cu")
		(net "UPI_CPU1_CPU0_P2P2_DN<10>")
	)
	(segment
		(start 100.291646 -279.63622)
		(end 100.28555 -279.639776)
		(width 0.0889)
		(layer "In11.Cu")
		(net "UPI_CPU1_CPU0_P2P2_DN<10>")
	)
	(segment
		(start 345.968066 -288.103056)
		(end 345.968066 -288.087562)
		(width 0.0889)
		(layer "In11.Cu")
		(net "UPI_CPU1_CPU0_P2P2_DN<10>")
	)
	(segment
		(start 350.009714 -277.198074)
		(end 350.003618 -277.194518)
		(width 0.0889)
		(layer "In11.Cu")
		(net "UPI_CPU1_CPU0_P2P2_DN<10>")
	)
	(segment
		(start 344.250772 -295.965626)
		(end 344.394282 -295.869868)
		(width 0.14732)
		(layer "In11.Cu")
		(net "UPI_CPU1_CPU0_P2P2_DN<10>")
	)
	(segment
		(start 94.182692 -285.33344)
		(end 94.18193 -285.333948)
		(width 0.0889)
		(layer "In11.Cu")
		(net "UPI_CPU1_CPU0_P2P2_DN<10>")
	)
	(segment
		(start 93.618304 -290.685474)
		(end 93.618304 -290.863274)
		(width 0.0889)
		(layer "In11.Cu")
		(net "UPI_CPU1_CPU0_P2P2_DN<10>")
	)
	(segment
		(start 162.75177 -384.089402)
		(end 261.64413 -375.69775)
		(width 0.14732)
		(layer "In11.Cu")
		(net "UPI_CPU1_CPU0_P2P2_DN<10>")
	)
	(segment
		(start 94.182692 -286.961326)
		(end 94.182946 -286.961072)
		(width 0.0889)
		(layer "In11.Cu")
		(net "UPI_CPU1_CPU0_P2P2_DN<10>")
	)
	(segment
		(start 89.79027 -301.285402)
		(end 89.773506 -301.456852)
		(width 0.14732)
		(layer "In11.Cu")
		(net "UPI_CPU1_CPU0_P2P2_DN<10>")
	)
	(segment
		(start 93.618304 -290.131754)
		(end 93.618304 -290.309554)
		(width 0.0889)
		(layer "In11.Cu")
		(net "UPI_CPU1_CPU0_P2P2_DN<10>")
	)
	(segment
		(start 346.720922 -286.151574)
		(end 346.72016 -286.151066)
		(width 0.0889)
		(layer "In11.Cu")
		(net "UPI_CPU1_CPU0_P2P2_DN<10>")
	)
	(segment
		(start 344.032586 -297.06189)
		(end 344.17635 -296.966132)
		(width 0.14732)
		(layer "In11.Cu")
		(net "UPI_CPU1_CPU0_P2P2_DN<10>")
	)
	(segment
		(start 102.634796 -278.82596)
		(end 102.620064 -278.834596)
		(width 0.0889)
		(layer "In11.Cu")
		(net "UPI_CPU1_CPU0_P2P2_DN<10>")
	)
	(segment
		(start 93.519244 -292.801294)
		(end 93.618304 -292.900354)
		(width 0.0889)
		(layer "In11.Cu")
		(net "UPI_CPU1_CPU0_P2P2_DN<10>")
	)
	(segment
		(start 93.049598 -288.917126)
		(end 93.049598 -289.078416)
		(width 0.0889)
		(layer "In11.Cu")
		(net "UPI_CPU1_CPU0_P2P2_DN<10>")
	)
	(segment
		(start 349.257112 -279.158954)
		(end 349.257112 -279.140412)
		(width 0.0889)
		(layer "In11.Cu")
		(net "UPI_CPU1_CPU0_P2P2_DN<10>")
	)
	(segment
		(start 69.811392 -366.004094)
		(end 74.458322 -370.651024)
		(width 0.14732)
		(layer "In11.Cu")
		(net "UPI_CPU1_CPU0_P2P2_DN<10>")
	)
	(segment
		(start 280.917904 -336.310224)
		(end 285.756604 -334.30591)
		(width 0.14732)
		(layer "In11.Cu")
		(net "UPI_CPU1_CPU0_P2P2_DN<10>")
	)
	(segment
		(start 93.618304 -293.631874)
		(end 93.519244 -293.730934)
		(width 0.0889)
		(layer "In11.Cu")
		(net "UPI_CPU1_CPU0_P2P2_DN<10>")
	)
	(segment
		(start 94.167706 -285.980632)
		(end 94.176596 -285.985712)
		(width 0.0889)
		(layer "In11.Cu")
		(net "UPI_CPU1_CPU0_P2P2_DN<10>")
	)
	(segment
		(start 285.756604 -334.30591)
		(end 308.233826 -334.30591)
		(width 0.14732)
		(layer "In11.Cu")
		(net "UPI_CPU1_CPU0_P2P2_DN<10>")
	)
	(segment
		(start 346.437712 -285.679896)
		(end 346.437712 -285.661354)
		(width 0.0889)
		(layer "In11.Cu")
		(net "UPI_CPU1_CPU0_P2P2_DN<10>")
	)
	(segment
		(start 346.714318 -285.175452)
		(end 346.720414 -285.171896)
		(width 0.0889)
		(layer "In11.Cu")
		(net "UPI_CPU1_CPU0_P2P2_DN<10>")
	)
	(segment
		(start 94.169738 -285.340806)
		(end 94.167706 -285.342076)
		(width 0.0889)
		(layer "In11.Cu")
		(net "UPI_CPU1_CPU0_P2P2_DN<10>")
	)
	(segment
		(start 348.608904 -281.272742)
		(end 348.600014 -281.267662)
		(width 0.0889)
		(layer "In11.Cu")
		(net "UPI_CPU1_CPU0_P2P2_DN<10>")
	)
	(segment
		(start 94.180914 -285.334456)
		(end 94.180152 -285.334964)
		(width 0.0889)
		(layer "In11.Cu")
		(net "UPI_CPU1_CPU0_P2P2_DN<10>")
	)
	(segment
		(start 94.177358 -285.336488)
		(end 94.176596 -285.336996)
		(width 0.0889)
		(layer "In11.Cu")
		(net "UPI_CPU1_CPU0_P2P2_DN<10>")
	)
	(segment
		(start 65.356232 -330.787248)
		(end 65.31991 -331.154024)
		(width 0.14732)
		(layer "In11.Cu")
		(net "UPI_CPU1_CPU0_P2P2_DN<10>")
	)
	(segment
		(start 350.196912 -275.8948)
		(end 350.196912 -275.880576)
		(width 0.0889)
		(layer "In11.Cu")
		(net "UPI_CPU1_CPU0_P2P2_DN<10>")
	)
	(segment
		(start 316.274196 -324.7136)
		(end 337.784694 -303.203102)
		(width 0.14732)
		(layer "In11.Cu")
		(net "UPI_CPU1_CPU0_P2P2_DN<10>")
	)
	(segment
		(start 88.909144 -302.16602)
		(end 88.571324 -302.443388)
		(width 0.14732)
		(layer "In11.Cu")
		(net "UPI_CPU1_CPU0_P2P2_DN<10>")
	)
	(segment
		(start 93.618304 -293.078154)
		(end 93.519244 -293.177214)
		(width 0.0889)
		(layer "In11.Cu")
		(net "UPI_CPU1_CPU0_P2P2_DN<10>")
	)
	(segment
		(start 93.618304 -292.524434)
		(end 93.519244 -292.623494)
		(width 0.0889)
		(layer "In11.Cu")
		(net "UPI_CPU1_CPU0_P2P2_DN<10>")
	)
	(segment
		(start 93.519244 -290.586414)
		(end 93.618304 -290.685474)
		(width 0.0889)
		(layer "In11.Cu")
		(net "UPI_CPU1_CPU0_P2P2_DN<10>")
	)
	(segment
		(start 350.479614 -275.405088)
		(end 350.488504 -275.400008)
		(width 0.0889)
		(layer "In11.Cu")
		(net "UPI_CPU1_CPU0_P2P2_DN<10>")
	)
	(segment
		(start 95.398844 -283.219906)
		(end 95.398844 -283.229812)
		(width 0.0889)
		(layer "In11.Cu")
		(net "UPI_CPU1_CPU0_P2P2_DN<10>")
	)
	(segment
		(start 98.688144 -280.778204)
		(end 98.688144 -280.793698)
		(width 0.0889)
		(layer "In11.Cu")
		(net "UPI_CPU1_CPU0_P2P2_DN<10>")
	)
	(segment
		(start 344.402918 -295.200578)
		(end 344.488008 -294.77208)
		(width 0.14732)
		(layer "In11.Cu")
		(net "UPI_CPU1_CPU0_P2P2_DN<10>")
	)
	(segment
		(start 65.376298 -329.10399)
		(end 65.226184 -330.629006)
		(width 0.14732)
		(layer "In11.Cu")
		(net "UPI_CPU1_CPU0_P2P2_DN<10>")
	)
	(segment
		(start 93.519244 -292.069774)
		(end 93.519244 -292.247574)
		(width 0.0889)
		(layer "In11.Cu")
		(net "UPI_CPU1_CPU0_P2P2_DN<10>")
	)
	(segment
		(start 346.720414 -285.171896)
		(end 346.729304 -285.166816)
		(width 0.0889)
		(layer "In11.Cu")
		(net "UPI_CPU1_CPU0_P2P2_DN<10>")
	)
	(segment
		(start 348.600014 -281.267662)
		(end 348.593918 -281.264106)
		(width 0.0889)
		(layer "In11.Cu")
		(net "UPI_CPU1_CPU0_P2P2_DN<10>")
	)
	(segment
		(start 93.561408 -294.080946)
		(end 93.561408 -297.042078)
		(width 0.14732)
		(layer "In11.Cu")
		(net "UPI_CPU1_CPU0_P2P2_DN<10>")
	)
	(segment
		(start 93.23705 -288.592768)
		(end 93.22816 -288.597848)
		(width 0.0889)
		(layer "In11.Cu")
		(net "UPI_CPU1_CPU0_P2P2_DN<10>")
	)
	(segment
		(start 88.39962 -302.426624)
		(end 88.059514 -302.70577)
		(width 0.14732)
		(layer "In11.Cu")
		(net "UPI_CPU1_CPU0_P2P2_DN<10>")
	)
	(segment
		(start 347.847412 -283.228542)
		(end 347.847412 -283.201364)
		(width 0.0889)
		(layer "In11.Cu")
		(net "UPI_CPU1_CPU0_P2P2_DN<10>")
	)
	(segment
		(start 65.041018 -354.48621)
		(end 69.811392 -366.004094)
		(width 0.14732)
		(layer "In11.Cu")
		(net "UPI_CPU1_CPU0_P2P2_DN<10>")
	)
	(segment
		(start 96.45142 -379.76048)
		(end 125.688344 -384.09753)
		(width 0.14732)
		(layer "In11.Cu")
		(net "UPI_CPU1_CPU0_P2P2_DN<10>")
	)
	(segment
		(start 347.19006 -284.35808)
		(end 347.19895 -284.353)
		(width 0.0889)
		(layer "In11.Cu")
		(net "UPI_CPU1_CPU0_P2P2_DN<10>")
	)
	(segment
		(start 344.752168 -291.496496)
		(end 344.752168 -291.474398)
		(width 0.0889)
		(layer "In11.Cu")
		(net "UPI_CPU1_CPU0_P2P2_DN<10>")
	)
	(segment
		(start 93.618304 -291.239194)
		(end 93.618304 -291.416994)
		(width 0.0889)
		(layer "In11.Cu")
		(net "UPI_CPU1_CPU0_P2P2_DN<10>")
	)
	(segment
		(start 95.586296 -282.895548)
		(end 95.577406 -282.900628)
		(width 0.0889)
		(layer "In11.Cu")
		(net "UPI_CPU1_CPU0_P2P2_DN<10>")
	)
	(segment
		(start 85.746336 -304.761646)
		(end 85.574886 -304.744882)
		(width 0.14732)
		(layer "In11.Cu")
		(net "UPI_CPU1_CPU0_P2P2_DN<10>")
	)
	(segment
		(start 93.519244 -293.177214)
		(end 93.519244 -293.355014)
		(width 0.0889)
		(layer "In11.Cu")
		(net "UPI_CPU1_CPU0_P2P2_DN<10>")
	)
	(segment
		(start 94.928944 -284.033722)
		(end 94.928944 -284.049216)
		(width 0.0889)
		(layer "In11.Cu")
		(net "UPI_CPU1_CPU0_P2P2_DN<10>")
	)
	(segment
		(start 347.654118 -283.54782)
		(end 347.65488 -283.547312)
		(width 0.0889)
		(layer "In11.Cu")
		(net "UPI_CPU1_CPU0_P2P2_DN<10>")
	)
	(segment
		(start 89.435432 -301.734474)
		(end 89.263728 -301.717456)
		(width 0.14732)
		(layer "In11.Cu")
		(net "UPI_CPU1_CPU0_P2P2_DN<10>")
	)
	(segment
		(start 346.907866 -284.847538)
		(end 346.907866 -284.832044)
		(width 0.0889)
		(layer "In11.Cu")
		(net "UPI_CPU1_CPU0_P2P2_DN<10>")
	)
	(segment
		(start 93.519244 -292.247574)
		(end 93.618304 -292.346634)
		(width 0.0889)
		(layer "In11.Cu")
		(net "UPI_CPU1_CPU0_P2P2_DN<10>")
	)
	(segment
		(start 68.357242 -320.788792)
		(end 66.717418 -324.2564)
		(width 0.14732)
		(layer "In11.Cu")
		(net "UPI_CPU1_CPU0_P2P2_DN<10>")
	)
	(segment
		(start 93.618304 -291.416994)
		(end 93.519244 -291.516054)
		(width 0.0889)
		(layer "In11.Cu")
		(net "UPI_CPU1_CPU0_P2P2_DN<10>")
	)
	(segment
		(start 93.519244 -293.730934)
		(end 93.519244 -294.016684)
		(width 0.0889)
		(layer "In11.Cu")
		(net "UPI_CPU1_CPU0_P2P2_DN<10>")
	)
	(segment
		(start 345.49842 -289.113976)
		(end 345.498166 -289.113722)
		(width 0.0889)
		(layer "In11.Cu")
		(net "UPI_CPU1_CPU0_P2P2_DN<10>")
	)
	(segment
		(start 348.787466 -279.964134)
		(end 348.787466 -279.954228)
		(width 0.0889)
		(layer "In11.Cu")
		(net "UPI_CPU1_CPU0_P2P2_DN<10>")
	)
	(segment
		(start 93.519244 -293.355014)
		(end 93.618304 -293.454074)
		(width 0.0889)
		(layer "In11.Cu")
		(net "UPI_CPU1_CPU0_P2P2_DN<10>")
	)
	(segment
		(start 93.519244 -291.516054)
		(end 93.519244 -291.693854)
		(width 0.0889)
		(layer "In11.Cu")
		(net "UPI_CPU1_CPU0_P2P2_DN<10>")
	)
	(segment
		(start 350.662494 -275.138134)
		(end 350.60509 -275.08073)
		(width 0.0889)
		(layer "In11.Cu")
		(net "UPI_CPU1_CPU0_P2P2_DN<10>")
	)
	(segment
		(start 86.101174 -304.312828)
		(end 86.08441 -304.484278)
		(width 0.14732)
		(layer "In11.Cu")
		(net "UPI_CPU1_CPU0_P2P2_DN<10>")
	)
	(segment
		(start 98.40595 -281.267662)
		(end 98.39706 -281.272742)
		(width 0.0889)
		(layer "In11.Cu")
		(net "UPI_CPU1_CPU0_P2P2_DN<10>")
	)
	(segment
		(start 93.519244 -289.609276)
		(end 93.519244 -290.032694)
		(width 0.0889)
		(layer "In11.Cu")
		(net "UPI_CPU1_CPU0_P2P2_DN<10>")
	)
	(segment
		(start 87.532972 -303.137824)
		(end 86.101174 -304.312828)
		(width 0.14732)
		(layer "In11.Cu")
		(net "UPI_CPU1_CPU0_P2P2_DN<10>")
	)
	(segment
		(start 346.437712 -287.28924)
		(end 346.437712 -287.279334)
		(width 0.0889)
		(layer "In11.Cu")
		(net "UPI_CPU1_CPU0_P2P2_DN<10>")
	)
	(segment
		(start 95.116396 -283.709364)
		(end 95.107506 -283.714444)
		(width 0.0889)
		(layer "In11.Cu")
		(net "UPI_CPU1_CPU0_P2P2_DN<10>")
	)
	(arc
		(start 102.620064 -278.834596)
		(mid 102.343589 -278.901916)
		(end 102.069392 -278.82596)
		(width 0.0889)
		(layer "In11.Cu")
		(net "UPI_CPU1_CPU0_P2P2_DN<10>")
	)
	(arc
		(start 95.398844 -283.229812)
		(mid 95.320733 -283.506761)
		(end 95.116396 -283.709364)
		(width 0.0889)
		(layer "In11.Cu")
		(net "UPI_CPU1_CPU0_P2P2_DN<10>")
	)
	(arc
		(start 350.009714 -277.84679)
		(mid 350.144647 -277.713436)
		(end 350.196912 -277.531068)
		(width 0.0889)
		(layer "In11.Cu")
		(net "UPI_CPU1_CPU0_P2P2_DN<10>")
	)
	(arc
		(start 100.567998 -279.150318)
		(mid 100.494082 -279.42982)
		(end 100.291646 -279.63622)
		(width 0.0889)
		(layer "In11.Cu")
		(net "UPI_CPU1_CPU0_P2P2_DN<10>")
	)
	(arc
		(start 346.72016 -286.151066)
		(mid 346.517874 -285.952085)
		(end 346.437712 -285.679896)
		(width 0.0889)
		(layer "In11.Cu")
		(net "UPI_CPU1_CPU0_P2P2_DN<10>")
	)
	(arc
		(start 350.196912 -275.880576)
		(mid 350.276131 -275.605891)
		(end 350.479614 -275.405088)
		(width 0.0889)
		(layer "In11.Cu")
		(net "UPI_CPU1_CPU0_P2P2_DN<10>")
	)
	(arc
		(start 96.981264 -282.090114)
		(mid 96.704789 -282.157434)
		(end 96.430592 -282.081478)
		(width 0.0889)
		(layer "In11.Cu")
		(net "UPI_CPU1_CPU0_P2P2_DN<10>")
	)
	(arc
		(start 350.003618 -277.194518)
		(mid 349.801031 -276.988167)
		(end 349.727012 -276.708616)
		(width 0.0889)
		(layer "In11.Cu")
		(net "UPI_CPU1_CPU0_P2P2_DN<10>")
	)
	(arc
		(start 98.39706 -281.272742)
		(mid 98.266146 -281.409102)
		(end 98.218498 -281.59202)
		(width 0.0889)
		(layer "In11.Cu")
		(net "UPI_CPU1_CPU0_P2P2_DN<10>")
	)
	(arc
		(start 347.377512 -284.033722)
		(mid 347.451503 -283.754156)
		(end 347.654118 -283.54782)
		(width 0.0889)
		(layer "In11.Cu")
		(net "UPI_CPU1_CPU0_P2P2_DN<10>")
	)
	(arc
		(start 99.720146 -279.639776)
		(mid 99.532948 -279.589633)
		(end 99.34575 -279.639776)
		(width 0.0889)
		(layer "In11.Cu")
		(net "UPI_CPU1_CPU0_P2P2_DN<10>")
	)
	(arc
		(start 95.868744 -282.424378)
		(mid 95.788582 -282.696567)
		(end 95.586296 -282.895548)
		(width 0.0889)
		(layer "In11.Cu")
		(net "UPI_CPU1_CPU0_P2P2_DN<10>")
	)
	(arc
		(start 103.009192 -278.82596)
		(mid 102.821994 -278.775817)
		(end 102.634796 -278.82596)
		(width 0.0889)
		(layer "In11.Cu")
		(net "UPI_CPU1_CPU0_P2P2_DN<10>")
	)
	(arc
		(start 349.727012 -278.328882)
		(mid 349.804641 -278.050469)
		(end 350.009714 -277.84679)
		(width 0.0889)
		(layer "In11.Cu")
		(net "UPI_CPU1_CPU0_P2P2_DN<10>")
	)
	(arc
		(start 96.430592 -282.081478)
		(mid 96.243394 -282.031335)
		(end 96.056196 -282.081478)
		(width 0.0889)
		(layer "In11.Cu")
		(net "UPI_CPU1_CPU0_P2P2_DN<10>")
	)
	(arc
		(start 346.729304 -285.166816)
		(mid 346.860218 -285.030456)
		(end 346.907866 -284.847538)
		(width 0.0889)
		(layer "In11.Cu")
		(net "UPI_CPU1_CPU0_P2P2_DN<10>")
	)
	(arc
		(start 348.608904 -281.911298)
		(mid 348.787501 -281.59202)
		(end 348.608904 -281.272742)
		(width 0.0889)
		(layer "In11.Cu")
		(net "UPI_CPU1_CPU0_P2P2_DN<10>")
	)
	(arc
		(start 345.513914 -289.1536)
		(mid 345.505814 -289.133926)
		(end 345.49842 -289.113976)
		(width 0.0889)
		(layer "In11.Cu")
		(net "UPI_CPU1_CPU0_P2P2_DN<10>")
	)
	(arc
		(start 93.69806 -287.783778)
		(mid 93.567146 -287.920138)
		(end 93.519498 -288.103056)
		(width 0.0889)
		(layer "In11.Cu")
		(net "UPI_CPU1_CPU0_P2P2_DN<10>")
	)
	(arc
		(start 350.196912 -277.513796)
		(mid 350.144642 -277.331431)
		(end 350.009714 -277.198074)
		(width 0.0889)
		(layer "In11.Cu")
		(net "UPI_CPU1_CPU0_P2P2_DN<10>")
	)
	(arc
		(start 100.74656 -278.83104)
		(mid 100.615646 -278.9674)
		(end 100.567998 -279.150318)
		(width 0.0889)
		(layer "In11.Cu")
		(net "UPI_CPU1_CPU0_P2P2_DN<10>")
	)
	(arc
		(start 96.047306 -282.086558)
		(mid 95.916392 -282.222918)
		(end 95.868744 -282.405836)
		(width 0.0889)
		(layer "In11.Cu")
		(net "UPI_CPU1_CPU0_P2P2_DN<10>")
	)
	(arc
		(start 349.54845 -278.65578)
		(mid 349.679364 -278.51942)
		(end 349.727012 -278.336502)
		(width 0.0889)
		(layer "In11.Cu")
		(net "UPI_CPU1_CPU0_P2P2_DN<10>")
	)
	(arc
		(start 345.968066 -289.64509)
		(mid 345.892959 -289.529944)
		(end 345.783916 -289.446208)
		(width 0.0889)
		(layer "In11.Cu")
		(net "UPI_CPU1_CPU0_P2P2_DN<10>")
	)
	(arc
		(start 93.049598 -289.078416)
		(mid 93.124603 -289.193875)
		(end 93.233748 -289.277806)
		(width 0.0889)
		(layer "In11.Cu")
		(net "UPI_CPU1_CPU0_P2P2_DN<10>")
	)
	(arc
		(start 93.50375 -289.569398)
		(mid 93.511857 -289.589197)
		(end 93.519244 -289.609276)
		(width 0.0889)
		(layer "In11.Cu")
		(net "UPI_CPU1_CPU0_P2P2_DN<10>")
	)
	(arc
		(start 348.593918 -281.264106)
		(mid 348.391331 -281.057755)
		(end 348.317312 -280.778204)
		(width 0.0889)
		(layer "In11.Cu")
		(net "UPI_CPU1_CPU0_P2P2_DN<10>")
	)
	(arc
		(start 347.19895 -284.353)
		(mid 347.329864 -284.21664)
		(end 347.377512 -284.033722)
		(width 0.0889)
		(layer "In11.Cu")
		(net "UPI_CPU1_CPU0_P2P2_DN<10>")
	)
	(arc
		(start 103.192072 -279.092914)
		(mid 103.133916 -278.942801)
		(end 103.018082 -278.83104)
		(width 0.0889)
		(layer "In11.Cu")
		(net "UPI_CPU1_CPU0_P2P2_DN<10>")
	)
	(arc
		(start 97.921064 -282.090114)
		(mid 97.644589 -282.157434)
		(end 97.370392 -282.081478)
		(width 0.0889)
		(layer "In11.Cu")
		(net "UPI_CPU1_CPU0_P2P2_DN<10>")
	)
	(arc
		(start 346.437712 -285.661354)
		(mid 346.511703 -285.381788)
		(end 346.714318 -285.175452)
		(width 0.0889)
		(layer "In11.Cu")
		(net "UPI_CPU1_CPU0_P2P2_DN<10>")
	)
	(arc
		(start 346.437712 -287.279334)
		(mid 346.515823 -287.002385)
		(end 346.72016 -286.799782)
		(width 0.0889)
		(layer "In11.Cu")
		(net "UPI_CPU1_CPU0_P2P2_DN<10>")
	)
	(arc
		(start 345.498166 -288.898584)
		(mid 345.578328 -288.626395)
		(end 345.780614 -288.427414)
		(width 0.0889)
		(layer "In11.Cu")
		(net "UPI_CPU1_CPU0_P2P2_DN<10>")
	)
	(arc
		(start 348.787466 -279.954228)
		(mid 348.865577 -279.677279)
		(end 349.069914 -279.474676)
		(width 0.0889)
		(layer "In11.Cu")
		(net "UPI_CPU1_CPU0_P2P2_DN<10>")
	)
	(arc
		(start 93.233748 -289.277806)
		(mid 93.393662 -289.400538)
		(end 93.50375 -289.569398)
		(width 0.0889)
		(layer "In11.Cu")
		(net "UPI_CPU1_CPU0_P2P2_DN<10>")
	)
	(arc
		(start 349.257112 -279.140412)
		(mid 349.335223 -278.863463)
		(end 349.53956 -278.66086)
		(width 0.0889)
		(layer "In11.Cu")
		(net "UPI_CPU1_CPU0_P2P2_DN<10>")
	)
	(arc
		(start 94.176596 -285.985712)
		(mid 94.380077 -286.186516)
		(end 94.459298 -286.4612)
		(width 0.0889)
		(layer "In11.Cu")
		(net "UPI_CPU1_CPU0_P2P2_DN<10>")
	)
	(arc
		(start 348.608904 -280.283412)
		(mid 348.739818 -280.147052)
		(end 348.787466 -279.964134)
		(width 0.0889)
		(layer "In11.Cu")
		(net "UPI_CPU1_CPU0_P2P2_DN<10>")
	)
	(arc
		(start 348.317312 -280.76398)
		(mid 348.396531 -280.489295)
		(end 348.600014 -280.288492)
		(width 0.0889)
		(layer "In11.Cu")
		(net "UPI_CPU1_CPU0_P2P2_DN<10>")
	)
	(arc
		(start 348.13875 -282.725114)
		(mid 348.269664 -282.588754)
		(end 348.317312 -282.405836)
		(width 0.0889)
		(layer "In11.Cu")
		(net "UPI_CPU1_CPU0_P2P2_DN<10>")
	)
	(arc
		(start 349.727012 -276.69871)
		(mid 349.805123 -276.421761)
		(end 350.00946 -276.219158)
		(width 0.0889)
		(layer "In11.Cu")
		(net "UPI_CPU1_CPU0_P2P2_DN<10>")
	)
	(arc
		(start 100.28555 -279.639776)
		(mid 100.011351 -279.715611)
		(end 99.734878 -279.648412)
		(width 0.0889)
		(layer "In11.Cu")
		(net "UPI_CPU1_CPU0_P2P2_DN<10>")
	)
	(arc
		(start 345.789504 -288.422334)
		(mid 345.920418 -288.285974)
		(end 345.968066 -288.103056)
		(width 0.0889)
		(layer "In11.Cu")
		(net "UPI_CPU1_CPU0_P2P2_DN<10>")
	)
	(arc
		(start 94.167706 -285.342076)
		(mid 93.989109 -285.661354)
		(end 94.167706 -285.980632)
		(width 0.0889)
		(layer "In11.Cu")
		(net "UPI_CPU1_CPU0_P2P2_DN<10>")
	)
	(arc
		(start 98.866706 -280.458926)
		(mid 98.735792 -280.595286)
		(end 98.688144 -280.778204)
		(width 0.0889)
		(layer "In11.Cu")
		(net "UPI_CPU1_CPU0_P2P2_DN<10>")
	)
	(arc
		(start 345.783916 -289.446208)
		(mid 345.623879 -289.323012)
		(end 345.513914 -289.1536)
		(width 0.0889)
		(layer "In11.Cu")
		(net "UPI_CPU1_CPU0_P2P2_DN<10>")
	)
	(arc
		(start 347.660214 -283.544264)
		(mid 347.795147 -283.41091)
		(end 347.847412 -283.228542)
		(width 0.0889)
		(layer "In11.Cu")
		(net "UPI_CPU1_CPU0_P2P2_DN<10>")
	)
	(arc
		(start 94.928944 -284.049216)
		(mid 94.849574 -284.32295)
		(end 94.64675 -284.52318)
		(width 0.0889)
		(layer "In11.Cu")
		(net "UPI_CPU1_CPU0_P2P2_DN<10>")
	)
	(arc
		(start 346.25915 -287.608518)
		(mid 346.390064 -287.472158)
		(end 346.437712 -287.28924)
		(width 0.0889)
		(layer "In11.Cu")
		(net "UPI_CPU1_CPU0_P2P2_DN<10>")
	)
	(arc
		(start 93.22816 -288.597848)
		(mid 93.097246 -288.734208)
		(end 93.049598 -288.917126)
		(width 0.0889)
		(layer "In11.Cu")
		(net "UPI_CPU1_CPU0_P2P2_DN<10>")
	)
	(arc
		(start 94.167706 -286.969962)
		(mid 94.036792 -287.106322)
		(end 93.989144 -287.28924)
		(width 0.0889)
		(layer "In11.Cu")
		(net "UPI_CPU1_CPU0_P2P2_DN<10>")
	)
	(arc
		(start 348.317312 -282.405836)
		(mid 348.391303 -282.12627)
		(end 348.593918 -281.919934)
		(width 0.0889)
		(layer "In11.Cu")
		(net "UPI_CPU1_CPU0_P2P2_DN<10>")
	)
	(arc
		(start 346.72905 -286.794702)
		(mid 346.907647 -286.475424)
		(end 346.72905 -286.156146)
		(width 0.0889)
		(layer "In11.Cu")
		(net "UPI_CPU1_CPU0_P2P2_DN<10>")
	)
	(arc
		(start 99.158298 -279.978358)
		(mid 99.079079 -280.253043)
		(end 98.875596 -280.453846)
		(width 0.0889)
		(layer "In11.Cu")
		(net "UPI_CPU1_CPU0_P2P2_DN<10>")
	)
	(arc
		(start 94.459298 -284.847538)
		(mid 94.385307 -285.127104)
		(end 94.182692 -285.33344)
		(width 0.0889)
		(layer "In11.Cu")
		(net "UPI_CPU1_CPU0_P2P2_DN<10>")
	)
	(arc
		(start 95.107506 -283.714444)
		(mid 94.976592 -283.850804)
		(end 94.928944 -284.033722)
		(width 0.0889)
		(layer "In11.Cu")
		(net "UPI_CPU1_CPU0_P2P2_DN<10>")
	)
	(arc
		(start 94.459298 -286.475424)
		(mid 94.385307 -286.75499)
		(end 94.182692 -286.961326)
		(width 0.0889)
		(layer "In11.Cu")
		(net "UPI_CPU1_CPU0_P2P2_DN<10>")
	)
	(arc
		(start 101.694996 -278.82596)
		(mid 101.418437 -278.901703)
		(end 101.14026 -278.832056)
		(width 0.0889)
		(layer "In11.Cu")
		(net "UPI_CPU1_CPU0_P2P2_DN<10>")
	)
	(arc
		(start 349.069914 -279.474676)
		(mid 349.204847 -279.341322)
		(end 349.257112 -279.158954)
		(width 0.0889)
		(layer "In11.Cu")
		(net "UPI_CPU1_CPU0_P2P2_DN<10>")
	)
	(arc
		(start 95.577406 -282.900628)
		(mid 95.446492 -283.036988)
		(end 95.398844 -283.219906)
		(width 0.0889)
		(layer "In11.Cu")
		(net "UPI_CPU1_CPU0_P2P2_DN<10>")
	)
	(arc
		(start 99.33686 -279.644856)
		(mid 99.205946 -279.781216)
		(end 99.158298 -279.964134)
		(width 0.0889)
		(layer "In11.Cu")
		(net "UPI_CPU1_CPU0_P2P2_DN<10>")
	)
	(arc
		(start 98.688144 -280.793698)
		(mid 98.608774 -281.067432)
		(end 98.40595 -281.267662)
		(width 0.0889)
		(layer "In11.Cu")
		(net "UPI_CPU1_CPU0_P2P2_DN<10>")
	)
	(arc
		(start 346.907866 -284.832044)
		(mid 346.987236 -284.55831)
		(end 347.19006 -284.35808)
		(width 0.0889)
		(layer "In11.Cu")
		(net "UPI_CPU1_CPU0_P2P2_DN<10>")
	)
	(arc
		(start 350.01835 -276.214078)
		(mid 350.149264 -276.077718)
		(end 350.196912 -275.8948)
		(width 0.0889)
		(layer "In11.Cu")
		(net "UPI_CPU1_CPU0_P2P2_DN<10>")
	)
	(arc
		(start 345.968066 -288.087562)
		(mid 346.047436 -287.813828)
		(end 346.25026 -287.613598)
		(width 0.0889)
		(layer "In11.Cu")
		(net "UPI_CPU1_CPU0_P2P2_DN<10>")
	)
	(arc
		(start 101.129846 -278.82596)
		(mid 100.942648 -278.775817)
		(end 100.75545 -278.82596)
		(width 0.0889)
		(layer "In11.Cu")
		(net "UPI_CPU1_CPU0_P2P2_DN<10>")
	)
	(arc
		(start 98.218498 -281.59202)
		(mid 98.144507 -281.871586)
		(end 97.941892 -282.077922)
		(width 0.0889)
		(layer "In11.Cu")
		(net "UPI_CPU1_CPU0_P2P2_DN<10>")
	)
	(arc
		(start 93.519498 -288.121598)
		(mid 93.439336 -288.393787)
		(end 93.23705 -288.592768)
		(width 0.0889)
		(layer "In11.Cu")
		(net "UPI_CPU1_CPU0_P2P2_DN<10>")
	)
	(arc
		(start 350.488504 -275.400008)
		(mid 350.604243 -275.288184)
		(end 350.662494 -275.138134)
		(width 0.0889)
		(layer "In11.Cu")
		(net "UPI_CPU1_CPU0_P2P2_DN<10>")
	)
	(arc
		(start 97.370392 -282.081478)
		(mid 97.183194 -282.031335)
		(end 96.995996 -282.081478)
		(width 0.0889)
		(layer "In11.Cu")
		(net "UPI_CPU1_CPU0_P2P2_DN<10>")
	)
	(arc
		(start 102.069392 -278.82596)
		(mid 101.882194 -278.775817)
		(end 101.694996 -278.82596)
		(width 0.0889)
		(layer "In11.Cu")
		(net "UPI_CPU1_CPU0_P2P2_DN<10>")
	)
	(arc
		(start 347.847412 -283.201364)
		(mid 347.927574 -282.929175)
		(end 348.12986 -282.730194)
		(width 0.0889)
		(layer "In11.Cu")
		(net "UPI_CPU1_CPU0_P2P2_DN<10>")
	)
	(arc
		(start 93.989144 -287.304734)
		(mid 93.909774 -287.578468)
		(end 93.70695 -287.778698)
		(width 0.0889)
		(layer "In11.Cu")
		(net "UPI_CPU1_CPU0_P2P2_DN<10>")
	)
	(arc
		(start 94.63786 -284.52826)
		(mid 94.506946 -284.66462)
		(end 94.459298 -284.847538)
		(width 0.0889)
		(layer "In11.Cu")
		(net "UPI_CPU1_CPU0_P2P2_DN<10>")
	)
	(segment
		(start 352.641916 -275.894546)
		(end 352.641662 -275.8948)
		(width 0.13208)
		(layer "F.Cu")
		(net "UPI_CPU1_CPU0_P2P2_DN<0>")
	)
	(segment
		(start 352.641916 -275.35886)
		(end 352.641916 -275.894546)
		(width 0.13208)
		(layer "F.Cu")
		(net "UPI_CPU1_CPU0_P2P2_DN<0>")
	)
	(segment
		(start 85.435694 -284.311598)
		(end 85.435694 -284.847538)
		(width 0.13208)
		(layer "F.Cu")
		(net "UPI_CPU1_CPU0_P2P2_DN<0>")
	)
	(segment
		(start 356.847902 -298.068746)
		(end 356.847902 -291.942266)
		(width 0.14732)
		(layer "In11.Cu")
		(net "UPI_CPU1_CPU0_P2P2_DN<0>")
	)
	(segment
		(start 354.964238 -300.096174)
		(end 355.224842 -299.83557)
		(width 0.14732)
		(layer "In11.Cu")
		(net "UPI_CPU1_CPU0_P2P2_DN<0>")
	)
	(segment
		(start 84.464906 -286.83839)
		(end 84.464906 -287.01619)
		(width 0.0889)
		(layer "In11.Cu")
		(net "UPI_CPU1_CPU0_P2P2_DN<0>")
	)
	(segment
		(start 83.887564 -289.883342)
		(end 83.887564 -289.943286)
		(width 0.0889)
		(layer "In11.Cu")
		(net "UPI_CPU1_CPU0_P2P2_DN<0>")
	)
	(segment
		(start 56.714898 -356.575106)
		(end 62.49543 -370.531136)
		(width 0.14732)
		(layer "In11.Cu")
		(net "UPI_CPU1_CPU0_P2P2_DN<0>")
	)
	(segment
		(start 359.12552 -281.602688)
		(end 359.12552 -281.581352)
		(width 0.0889)
		(layer "In11.Cu")
		(net "UPI_CPU1_CPU0_P2P2_DN<0>")
	)
	(segment
		(start 346.781882 -308.310788)
		(end 347.091 -308.00167)
		(width 0.14732)
		(layer "In11.Cu")
		(net "UPI_CPU1_CPU0_P2P2_DN<0>")
	)
	(segment
		(start 359.59542 -282.417266)
		(end 359.59542 -282.405836)
		(width 0.0889)
		(layer "In11.Cu")
		(net "UPI_CPU1_CPU0_P2P2_DN<0>")
	)
	(segment
		(start 62.54242 -310.488838)
		(end 62.033912 -310.699912)
		(width 0.14732)
		(layer "In11.Cu")
		(net "UPI_CPU1_CPU0_P2P2_DN<0>")
	)
	(segment
		(start 358.938068 -274.756118)
		(end 358.93756 -274.755864)
		(width 0.0889)
		(layer "In11.Cu")
		(net "UPI_CPU1_CPU0_P2P2_DN<0>")
	)
	(segment
		(start 322.567808 -331.762608)
		(end 323.69379 -329.044046)
		(width 0.14732)
		(layer "In11.Cu")
		(net "UPI_CPU1_CPU0_P2P2_DN<0>")
	)
	(segment
		(start 359.409492 -282.08224)
		(end 359.398316 -282.075636)
		(width 0.0889)
		(layer "In11.Cu")
		(net "UPI_CPU1_CPU0_P2P2_DN<0>")
	)
	(segment
		(start 84.563966 -287.66897)
		(end 84.563966 -287.84677)
		(width 0.0889)
		(layer "In11.Cu")
		(net "UPI_CPU1_CPU0_P2P2_DN<0>")
	)
	(segment
		(start 356.768908 -289.092132)
		(end 356.77602 -288.962846)
		(width 0.0889)
		(layer "In11.Cu")
		(net "UPI_CPU1_CPU0_P2P2_DN<0>")
	)
	(segment
		(start 277.85441 -372.060216)
		(end 278.115268 -371.799358)
		(width 0.14732)
		(layer "In11.Cu")
		(net "UPI_CPU1_CPU0_P2P2_DN<0>")
	)
	(segment
		(start 347.94063 -307.15204)
		(end 348.113096 -307.15204)
		(width 0.14732)
		(layer "In11.Cu")
		(net "UPI_CPU1_CPU0_P2P2_DN<0>")
	)
	(segment
		(start 358.467152 -284.358842)
		(end 358.468168 -284.358334)
		(width 0.0889)
		(layer "In11.Cu")
		(net "UPI_CPU1_CPU0_P2P2_DN<0>")
	)
	(segment
		(start 84.563966 -287.84677)
		(end 84.464906 -287.94583)
		(width 0.0889)
		(layer "In11.Cu")
		(net "UPI_CPU1_CPU0_P2P2_DN<0>")
	)
	(segment
		(start 85.748368 -284.847538)
		(end 85.805772 -284.790134)
		(width 0.0889)
		(layer "In11.Cu")
		(net "UPI_CPU1_CPU0_P2P2_DN<0>")
	)
	(segment
		(start 83.87207 -289.95878)
		(end 81.722214 -292.108636)
		(width 0.14732)
		(layer "In11.Cu")
		(net "UPI_CPU1_CPU0_P2P2_DN<0>")
	)
	(segment
		(start 359.398316 -282.075636)
		(end 359.398062 -282.075382)
		(width 0.0889)
		(layer "In11.Cu")
		(net "UPI_CPU1_CPU0_P2P2_DN<0>")
	)
	(segment
		(start 358.468168 -284.358334)
		(end 358.47274 -284.35554)
		(width 0.0889)
		(layer "In11.Cu")
		(net "UPI_CPU1_CPU0_P2P2_DN<0>")
	)
	(segment
		(start 52.655978 -317.941706)
		(end 51.780694 -318.554862)
		(width 0.14732)
		(layer "In11.Cu")
		(net "UPI_CPU1_CPU0_P2P2_DN<0>")
	)
	(segment
		(start 266.189968 -383.929382)
		(end 276.338284 -373.781066)
		(width 0.14732)
		(layer "In11.Cu")
		(net "UPI_CPU1_CPU0_P2P2_DN<0>")
	)
	(segment
		(start 360.065066 -276.708616)
		(end 360.065066 -276.69617)
		(width 0.0889)
		(layer "In11.Cu")
		(net "UPI_CPU1_CPU0_P2P2_DN<0>")
	)
	(segment
		(start 277.128732 -372.990618)
		(end 277.128732 -372.785894)
		(width 0.14732)
		(layer "In11.Cu")
		(net "UPI_CPU1_CPU0_P2P2_DN<0>")
	)
	(segment
		(start 357.715566 -285.67634)
		(end 357.715566 -285.661354)
		(width 0.0889)
		(layer "In11.Cu")
		(net "UPI_CPU1_CPU0_P2P2_DN<0>")
	)
	(segment
		(start 278.934926 -370.9797)
		(end 279.13965 -370.9797)
		(width 0.14732)
		(layer "In11.Cu")
		(net "UPI_CPU1_CPU0_P2P2_DN<0>")
	)
	(segment
		(start 62.033912 -310.699658)
		(end 61.575696 -310.889396)
		(width 0.14732)
		(layer "In11.Cu")
		(net "UPI_CPU1_CPU0_P2P2_DN<0>")
	)
	(segment
		(start 58.90387 -312.260234)
		(end 58.377074 -312.47842)
		(width 0.14732)
		(layer "In11.Cu")
		(net "UPI_CPU1_CPU0_P2P2_DN<0>")
	)
	(segment
		(start 352.88728 -275.599906)
		(end 352.798126 -275.623782)
		(width 0.0889)
		(layer "In11.Cu")
		(net "UPI_CPU1_CPU0_P2P2_DN<0>")
	)
	(segment
		(start 355.284278 -275.563838)
		(end 355.273356 -275.570188)
		(width 0.0889)
		(layer "In11.Cu")
		(net "UPI_CPU1_CPU0_P2P2_DN<0>")
	)
	(segment
		(start 58.377074 -312.47842)
		(end 55.920132 -314.120022)
		(width 0.14732)
		(layer "In11.Cu")
		(net "UPI_CPU1_CPU0_P2P2_DN<0>")
	)
	(segment
		(start 359.867454 -278.66721)
		(end 359.878122 -278.66086)
		(width 0.0889)
		(layer "In11.Cu")
		(net "UPI_CPU1_CPU0_P2P2_DN<0>")
	)
	(segment
		(start 50.816764 -329.568556)
		(end 50.972466 -329.94346)
		(width 0.14732)
		(layer "In11.Cu")
		(net "UPI_CPU1_CPU0_P2P2_DN<0>")
	)
	(segment
		(start 53.072284 -316.58814)
		(end 53.072284 -317.23838)
		(width 0.14732)
		(layer "In11.Cu")
		(net "UPI_CPU1_CPU0_P2P2_DN<0>")
	)
	(segment
		(start 66.186558 -308.14772)
		(end 65.813686 -308.302152)
		(width 0.14732)
		(layer "In11.Cu")
		(net "UPI_CPU1_CPU0_P2P2_DN<0>")
	)
	(segment
		(start 52.915058 -317.618618)
		(end 52.655978 -317.941706)
		(width 0.14732)
		(layer "In11.Cu")
		(net "UPI_CPU1_CPU0_P2P2_DN<0>")
	)
	(segment
		(start 352.907092 -275.607018)
		(end 352.907346 -275.608034)
		(width 0.0889)
		(layer "In11.Cu")
		(net "UPI_CPU1_CPU0_P2P2_DN<0>")
	)
	(segment
		(start 85.17128 -284.582362)
		(end 85.171026 -284.582362)
		(width 0.0889)
		(layer "In11.Cu")
		(net "UPI_CPU1_CPU0_P2P2_DN<0>")
	)
	(segment
		(start 356.305866 -291.341556)
		(end 356.305866 -289.648392)
		(width 0.0889)
		(layer "In11.Cu")
		(net "UPI_CPU1_CPU0_P2P2_DN<0>")
	)
	(segment
		(start 83.522566 -383.961386)
		(end 83.711796 -383.883154)
		(width 0.14732)
		(layer "In11.Cu")
		(net "UPI_CPU1_CPU0_P2P2_DN<0>")
	)
	(segment
		(start 84.130642 -384.213354)
		(end 92.14485 -387.532626)
		(width 0.14732)
		(layer "In11.Cu")
		(net "UPI_CPU1_CPU0_P2P2_DN<0>")
	)
	(segment
		(start 355.95052 -299.109892)
		(end 356.155244 -299.109892)
		(width 0.14732)
		(layer "In11.Cu")
		(net "UPI_CPU1_CPU0_P2P2_DN<0>")
	)
	(segment
		(start 53.38572 -315.831474)
		(end 53.072284 -316.58814)
		(width 0.14732)
		(layer "In11.Cu")
		(net "UPI_CPU1_CPU0_P2P2_DN<0>")
	)
	(segment
		(start 311.606946 -342.72347)
		(end 322.567808 -331.762608)
		(width 0.14732)
		(layer "In11.Cu")
		(net "UPI_CPU1_CPU0_P2P2_DN<0>")
	)
	(segment
		(start 359.59542 -275.8948)
		(end 359.59542 -275.88337)
		(width 0.0889)
		(layer "In11.Cu")
		(net "UPI_CPU1_CPU0_P2P2_DN<0>")
	)
	(segment
		(start 56.714898 -337.580732)
		(end 56.714898 -356.575106)
		(width 0.14732)
		(layer "In11.Cu")
		(net "UPI_CPU1_CPU0_P2P2_DN<0>")
	)
	(segment
		(start 347.263466 -308.00167)
		(end 347.631512 -307.633624)
		(width 0.14732)
		(layer "In11.Cu")
		(net "UPI_CPU1_CPU0_P2P2_DN<0>")
	)
	(segment
		(start 92.14485 -387.532626)
		(end 127.141732 -392.724132)
		(width 0.14732)
		(layer "In11.Cu")
		(net "UPI_CPU1_CPU0_P2P2_DN<0>")
	)
	(segment
		(start 356.77602 -287.28924)
		(end 356.77602 -287.278572)
		(width 0.0889)
		(layer "In11.Cu")
		(net "UPI_CPU1_CPU0_P2P2_DN<0>")
	)
	(segment
		(start 82.574384 -383.568702)
		(end 82.763614 -383.49047)
		(width 0.14732)
		(layer "In11.Cu")
		(net "UPI_CPU1_CPU0_P2P2_DN<0>")
	)
	(segment
		(start 358.457754 -284.36443)
		(end 358.464358 -284.36062)
		(width 0.0889)
		(layer "In11.Cu")
		(net "UPI_CPU1_CPU0_P2P2_DN<0>")
	)
	(segment
		(start 358.927654 -283.550614)
		(end 358.938322 -283.544264)
		(width 0.0889)
		(layer "In11.Cu")
		(net "UPI_CPU1_CPU0_P2P2_DN<0>")
	)
	(segment
		(start 360.3371 -277.853394)
		(end 360.347768 -277.847044)
		(width 0.0889)
		(layer "In11.Cu")
		(net "UPI_CPU1_CPU0_P2P2_DN<0>")
	)
	(segment
		(start 359.12552 -275.091398)
		(end 359.12552 -275.072856)
		(width 0.0889)
		(layer "In11.Cu")
		(net "UPI_CPU1_CPU0_P2P2_DN<0>")
	)
	(segment
		(start 84.464906 -289.05327)
		(end 84.464906 -289.306)
		(width 0.0889)
		(layer "In11.Cu")
		(net "UPI_CPU1_CPU0_P2P2_DN<0>")
	)
	(segment
		(start 354.23856 -300.821852)
		(end 354.499164 -300.561248)
		(width 0.14732)
		(layer "In11.Cu")
		(net "UPI_CPU1_CPU0_P2P2_DN<0>")
	)
	(segment
		(start 277.85441 -372.26494)
		(end 277.85441 -372.060216)
		(width 0.14732)
		(layer "In11.Cu")
		(net "UPI_CPU1_CPU0_P2P2_DN<0>")
	)
	(segment
		(start 347.631512 -307.633624)
		(end 347.631512 -307.461158)
		(width 0.14732)
		(layer "In11.Cu")
		(net "UPI_CPU1_CPU0_P2P2_DN<0>")
	)
	(segment
		(start 278.674322 -371.445028)
		(end 278.674322 -371.240304)
		(width 0.14732)
		(layer "In11.Cu")
		(net "UPI_CPU1_CPU0_P2P2_DN<0>")
	)
	(segment
		(start 84.464906 -288.49955)
		(end 84.464906 -288.67735)
		(width 0.0889)
		(layer "In11.Cu")
		(net "UPI_CPU1_CPU0_P2P2_DN<0>")
	)
	(segment
		(start 356.11816 -274.755864)
		(end 356.109778 -274.750784)
		(width 0.0889)
		(layer "In11.Cu")
		(net "UPI_CPU1_CPU0_P2P2_DN<0>")
	)
	(segment
		(start 360.352848 -277.200868)
		(end 360.346752 -277.197312)
		(width 0.0889)
		(layer "In11.Cu")
		(net "UPI_CPU1_CPU0_P2P2_DN<0>")
	)
	(segment
		(start 62.033912 -310.699912)
		(end 62.033912 -310.699658)
		(width 0.14732)
		(layer "In11.Cu")
		(net "UPI_CPU1_CPU0_P2P2_DN<0>")
	)
	(segment
		(start 81.722214 -292.108636)
		(end 80.43164 -295.2242)
		(width 0.14732)
		(layer "In11.Cu")
		(net "UPI_CPU1_CPU0_P2P2_DN<0>")
	)
	(segment
		(start 355.689916 -299.370496)
		(end 355.95052 -299.109892)
		(width 0.14732)
		(layer "In11.Cu")
		(net "UPI_CPU1_CPU0_P2P2_DN<0>")
	)
	(segment
		(start 71.753476 -379.087126)
		(end 82.57413 -383.568702)
		(width 0.14732)
		(layer "In11.Cu")
		(net "UPI_CPU1_CPU0_P2P2_DN<0>")
	)
	(segment
		(start 355.556312 -275.068284)
		(end 355.556312 -275.08073)
		(width 0.0889)
		(layer "In11.Cu")
		(net "UPI_CPU1_CPU0_P2P2_DN<0>")
	)
	(segment
		(start 84.563966 -288.77641)
		(end 84.563966 -288.95421)
		(width 0.0889)
		(layer "In11.Cu")
		(net "UPI_CPU1_CPU0_P2P2_DN<0>")
	)
	(segment
		(start 50.94605 -318.900556)
		(end 50.835306 -318.978026)
		(width 0.14732)
		(layer "In11.Cu")
		(net "UPI_CPU1_CPU0_P2P2_DN<0>")
	)
	(segment
		(start 84.464906 -286.197548)
		(end 84.464906 -286.46247)
		(width 0.0889)
		(layer "In11.Cu")
		(net "UPI_CPU1_CPU0_P2P2_DN<0>")
	)
	(segment
		(start 84.563966 -288.22269)
		(end 84.563966 -288.40049)
		(width 0.0889)
		(layer "In11.Cu")
		(net "UPI_CPU1_CPU0_P2P2_DN<0>")
	)
	(segment
		(start 71.67499 -378.897896)
		(end 71.753476 -379.087126)
		(width 0.14732)
		(layer "In11.Cu")
		(net "UPI_CPU1_CPU0_P2P2_DN<0>")
	)
	(segment
		(start 61.575696 -310.889396)
		(end 59.788298 -312.083958)
		(width 0.14732)
		(layer "In11.Cu")
		(net "UPI_CPU1_CPU0_P2P2_DN<0>")
	)
	(segment
		(start 53.072284 -317.23838)
		(end 52.915058 -317.618618)
		(width 0.14732)
		(layer "In11.Cu")
		(net "UPI_CPU1_CPU0_P2P2_DN<0>")
	)
	(segment
		(start 54.15153 -315.065664)
		(end 53.38572 -315.831474)
		(width 0.14732)
		(layer "In11.Cu")
		(net "UPI_CPU1_CPU0_P2P2_DN<0>")
	)
	(segment
		(start 355.429566 -299.83557)
		(end 355.689916 -299.57522)
		(width 0.14732)
		(layer "In11.Cu")
		(net "UPI_CPU1_CPU0_P2P2_DN<0>")
	)
	(segment
		(start 276.338284 -373.781066)
		(end 276.338284 -373.6086)
		(width 0.14732)
		(layer "In11.Cu")
		(net "UPI_CPU1_CPU0_P2P2_DN<0>")
	)
	(segment
		(start 354.3427 -275.564854)
		(end 354.334318 -275.56968)
		(width 0.0889)
		(layer "In11.Cu")
		(net "UPI_CPU1_CPU0_P2P2_DN<0>")
	)
	(segment
		(start 354.964238 -300.300898)
		(end 354.964238 -300.096174)
		(width 0.14732)
		(layer "In11.Cu")
		(net "UPI_CPU1_CPU0_P2P2_DN<0>")
	)
	(segment
		(start 276.647402 -373.299482)
		(end 276.819868 -373.299482)
		(width 0.14732)
		(layer "In11.Cu")
		(net "UPI_CPU1_CPU0_P2P2_DN<0>")
	)
	(segment
		(start 59.788298 -312.083958)
		(end 58.90387 -312.260234)
		(width 0.14732)
		(layer "In11.Cu")
		(net "UPI_CPU1_CPU0_P2P2_DN<0>")
	)
	(segment
		(start 278.674322 -371.240304)
		(end 278.934926 -370.9797)
		(width 0.14732)
		(layer "In11.Cu")
		(net "UPI_CPU1_CPU0_P2P2_DN<0>")
	)
	(segment
		(start 55.480204 -334.61579)
		(end 56.714898 -337.580732)
		(width 0.14732)
		(layer "In11.Cu")
		(net "UPI_CPU1_CPU0_P2P2_DN<0>")
	)
	(segment
		(start 279.4 -370.71935)
		(end 279.4 -350.015556)
		(width 0.14732)
		(layer "In11.Cu")
		(net "UPI_CPU1_CPU0_P2P2_DN<0>")
	)
	(segment
		(start 356.58425 -291.678614)
		(end 356.58425 -291.619686)
		(width 0.0889)
		(layer "In11.Cu")
		(net "UPI_CPU1_CPU0_P2P2_DN<0>")
	)
	(segment
		(start 357.984552 -285.180024)
		(end 357.99014 -285.176722)
		(width 0.0889)
		(layer "In11.Cu")
		(net "UPI_CPU1_CPU0_P2P2_DN<0>")
	)
	(segment
		(start 359.12552 -279.974802)
		(end 359.12552 -279.953466)
		(width 0.0889)
		(layer "In11.Cu")
		(net "UPI_CPU1_CPU0_P2P2_DN<0>")
	)
	(segment
		(start 359.398824 -281.107896)
		(end 359.409238 -281.102054)
		(width 0.0889)
		(layer "In11.Cu")
		(net "UPI_CPU1_CPU0_P2P2_DN<0>")
	)
	(segment
		(start 359.12552 -283.22778)
		(end 359.12552 -283.209238)
		(width 0.0889)
		(layer "In11.Cu")
		(net "UPI_CPU1_CPU0_P2P2_DN<0>")
	)
	(segment
		(start 65.813686 -308.302152)
		(end 62.54242 -310.488838)
		(width 0.14732)
		(layer "In11.Cu")
		(net "UPI_CPU1_CPU0_P2P2_DN<0>")
	)
	(segment
		(start 323.69379 -329.044046)
		(end 341.375746 -311.36209)
		(width 0.14732)
		(layer "In11.Cu")
		(net "UPI_CPU1_CPU0_P2P2_DN<0>")
	)
	(segment
		(start 277.128732 -372.785894)
		(end 277.389336 -372.52529)
		(width 0.14732)
		(layer "In11.Cu")
		(net "UPI_CPU1_CPU0_P2P2_DN<0>")
	)
	(segment
		(start 356.77602 -288.962846)
		(end 356.780846 -288.873184)
		(width 0.0889)
		(layer "In11.Cu")
		(net "UPI_CPU1_CPU0_P2P2_DN<0>")
	)
	(segment
		(start 346.781882 -308.483254)
		(end 346.781882 -308.310788)
		(width 0.14732)
		(layer "In11.Cu")
		(net "UPI_CPU1_CPU0_P2P2_DN<0>")
	)
	(segment
		(start 162.051238 -392.724132)
		(end 266.189968 -383.929382)
		(width 0.14732)
		(layer "In11.Cu")
		(net "UPI_CPU1_CPU0_P2P2_DN<0>")
	)
	(segment
		(start 84.464906 -288.12363)
		(end 84.563966 -288.22269)
		(width 0.0889)
		(layer "In11.Cu")
		(net "UPI_CPU1_CPU0_P2P2_DN<0>")
	)
	(segment
		(start 80.43164 -295.2242)
		(end 70.169786 -305.485546)
		(width 0.14732)
		(layer "In11.Cu")
		(net "UPI_CPU1_CPU0_P2P2_DN<0>")
	)
	(segment
		(start 50.365152 -320.215514)
		(end 50.365152 -325.450962)
		(width 0.14732)
		(layer "In11.Cu")
		(net "UPI_CPU1_CPU0_P2P2_DN<0>")
	)
	(segment
		(start 84.05241 -384.024124)
		(end 84.130642 -384.213354)
		(width 0.14732)
		(layer "In11.Cu")
		(net "UPI_CPU1_CPU0_P2P2_DN<0>")
	)
	(segment
		(start 279.4 -350.015556)
		(end 286.222948 -343.192608)
		(width 0.14732)
		(layer "In11.Cu")
		(net "UPI_CPU1_CPU0_P2P2_DN<0>")
	)
	(segment
		(start 50.50028 -319.456562)
		(end 50.365152 -320.215514)
		(width 0.14732)
		(layer "In11.Cu")
		(net "UPI_CPU1_CPU0_P2P2_DN<0>")
	)
	(segment
		(start 359.409238 -279.474168)
		(end 359.413048 -279.471882)
		(width 0.0889)
		(layer "In11.Cu")
		(net "UPI_CPU1_CPU0_P2P2_DN<0>")
	)
	(segment
		(start 62.49543 -370.531136)
		(end 70.555104 -378.59081)
		(width 0.14732)
		(layer "In11.Cu")
		(net "UPI_CPU1_CPU0_P2P2_DN<0>")
	)
	(segment
		(start 82.57413 -383.568702)
		(end 82.574384 -383.568702)
		(width 0.14732)
		(layer "In11.Cu")
		(net "UPI_CPU1_CPU0_P2P2_DN<0>")
	)
	(segment
		(start 54.319932 -333.290672)
		(end 55.480204 -334.61579)
		(width 0.14732)
		(layer "In11.Cu")
		(net "UPI_CPU1_CPU0_P2P2_DN<0>")
	)
	(segment
		(start 357.99903 -285.171642)
		(end 358.00919 -285.165546)
		(width 0.0889)
		(layer "In11.Cu")
		(net "UPI_CPU1_CPU0_P2P2_DN<0>")
	)
	(segment
		(start 84.464906 -287.94583)
		(end 84.464906 -288.12363)
		(width 0.0889)
		(layer "In11.Cu")
		(net "UPI_CPU1_CPU0_P2P2_DN<0>")
	)
	(segment
		(start 358.93756 -274.755864)
		(end 358.929178 -274.750784)
		(width 0.0889)
		(layer "In11.Cu")
		(net "UPI_CPU1_CPU0_P2P2_DN<0>")
	)
	(segment
		(start 352.798126 -275.623782)
		(end 352.641662 -275.8948)
		(width 0.0889)
		(layer "In11.Cu")
		(net "UPI_CPU1_CPU0_P2P2_DN<0>")
	)
	(segment
		(start 84.464906 -287.01619)
		(end 84.563966 -287.11525)
		(width 0.0889)
		(layer "In11.Cu")
		(net "UPI_CPU1_CPU0_P2P2_DN<0>")
	)
	(segment
		(start 356.692454 -274.751038)
		(end 356.684072 -274.755864)
		(width 0.0889)
		(layer "In11.Cu")
		(net "UPI_CPU1_CPU0_P2P2_DN<0>")
	)
	(segment
		(start 83.711796 -383.883154)
		(end 84.05241 -384.024124)
		(width 0.14732)
		(layer "In11.Cu")
		(net "UPI_CPU1_CPU0_P2P2_DN<0>")
	)
	(segment
		(start 277.59406 -372.52529)
		(end 277.85441 -372.26494)
		(width 0.14732)
		(layer "In11.Cu")
		(net "UPI_CPU1_CPU0_P2P2_DN<0>")
	)
	(segment
		(start 84.464906 -288.67735)
		(end 84.563966 -288.77641)
		(width 0.0889)
		(layer "In11.Cu")
		(net "UPI_CPU1_CPU0_P2P2_DN<0>")
	)
	(segment
		(start 84.464906 -287.56991)
		(end 84.563966 -287.66897)
		(width 0.0889)
		(layer "In11.Cu")
		(net "UPI_CPU1_CPU0_P2P2_DN<0>")
	)
	(segment
		(start 356.847902 -291.942266)
		(end 356.599744 -291.694108)
		(width 0.14732)
		(layer "In11.Cu")
		(net "UPI_CPU1_CPU0_P2P2_DN<0>")
	)
	(segment
		(start 355.689916 -299.57522)
		(end 355.689916 -299.370496)
		(width 0.14732)
		(layer "In11.Cu")
		(net "UPI_CPU1_CPU0_P2P2_DN<0>")
	)
	(segment
		(start 84.464906 -286.46247)
		(end 84.563966 -286.56153)
		(width 0.0889)
		(layer "In11.Cu")
		(net "UPI_CPU1_CPU0_P2P2_DN<0>")
	)
	(segment
		(start 278.319992 -371.799358)
		(end 278.674322 -371.445028)
		(width 0.14732)
		(layer "In11.Cu")
		(net "UPI_CPU1_CPU0_P2P2_DN<0>")
	)
	(segment
		(start 71.1454 -378.835158)
		(end 71.33463 -378.756926)
		(width 0.14732)
		(layer "In11.Cu")
		(net "UPI_CPU1_CPU0_P2P2_DN<0>")
	)
	(segment
		(start 347.631512 -307.461158)
		(end 347.94063 -307.15204)
		(width 0.14732)
		(layer "In11.Cu")
		(net "UPI_CPU1_CPU0_P2P2_DN<0>")
	)
	(segment
		(start 357.5177 -285.992316)
		(end 357.528368 -285.985966)
		(width 0.0889)
		(layer "In11.Cu")
		(net "UPI_CPU1_CPU0_P2P2_DN<0>")
	)
	(segment
		(start 356.599744 -291.694108)
		(end 356.58425 -291.678614)
		(width 0.0889)
		(layer "In11.Cu")
		(net "UPI_CPU1_CPU0_P2P2_DN<0>")
	)
	(segment
		(start 84.563966 -288.40049)
		(end 84.464906 -288.49955)
		(width 0.0889)
		(layer "In11.Cu")
		(net "UPI_CPU1_CPU0_P2P2_DN<0>")
	)
	(segment
		(start 357.99014 -285.176722)
		(end 357.99903 -285.171642)
		(width 0.0889)
		(layer "In11.Cu")
		(net "UPI_CPU1_CPU0_P2P2_DN<0>")
	)
	(segment
		(start 84.563966 -287.11525)
		(end 84.563966 -287.29305)
		(width 0.0889)
		(layer "In11.Cu")
		(net "UPI_CPU1_CPU0_P2P2_DN<0>")
	)
	(segment
		(start 353.768406 -275.56968)
		(end 353.760024 -275.564854)
		(width 0.0889)
		(layer "In11.Cu")
		(net "UPI_CPU1_CPU0_P2P2_DN<0>")
	)
	(segment
		(start 360.346752 -277.197312)
		(end 360.345228 -277.19655)
		(width 0.0889)
		(layer "In11.Cu")
		(net "UPI_CPU1_CPU0_P2P2_DN<0>")
	)
	(segment
		(start 356.58806 -287.614106)
		(end 356.592886 -287.611058)
		(width 0.0889)
		(layer "In11.Cu")
		(net "UPI_CPU1_CPU0_P2P2_DN<0>")
	)
	(segment
		(start 82.763614 -383.49047)
		(end 83.103974 -383.631186)
		(width 0.14732)
		(layer "In11.Cu")
		(net "UPI_CPU1_CPU0_P2P2_DN<0>")
	)
	(segment
		(start 348.113096 -307.15204)
		(end 354.23856 -301.026576)
		(width 0.14732)
		(layer "In11.Cu")
		(net "UPI_CPU1_CPU0_P2P2_DN<0>")
	)
	(segment
		(start 278.115268 -371.799358)
		(end 278.319992 -371.799358)
		(width 0.14732)
		(layer "In11.Cu")
		(net "UPI_CPU1_CPU0_P2P2_DN<0>")
	)
	(segment
		(start 279.13965 -370.9797)
		(end 279.4 -370.71935)
		(width 0.14732)
		(layer "In11.Cu")
		(net "UPI_CPU1_CPU0_P2P2_DN<0>")
	)
	(segment
		(start 68.177918 -306.81676)
		(end 68.177918 -306.817014)
		(width 0.14732)
		(layer "In11.Cu")
		(net "UPI_CPU1_CPU0_P2P2_DN<0>")
	)
	(segment
		(start 84.464906 -289.306)
		(end 83.887564 -289.883342)
		(width 0.0889)
		(layer "In11.Cu")
		(net "UPI_CPU1_CPU0_P2P2_DN<0>")
	)
	(segment
		(start 71.33463 -378.756926)
		(end 71.67499 -378.897896)
		(width 0.14732)
		(layer "In11.Cu")
		(net "UPI_CPU1_CPU0_P2P2_DN<0>")
	)
	(segment
		(start 85.017356 -284.865826)
		(end 84.464906 -286.197548)
		(width 0.0889)
		(layer "In11.Cu")
		(net "UPI_CPU1_CPU0_P2P2_DN<0>")
	)
	(segment
		(start 50.835306 -318.978026)
		(end 50.50028 -319.456562)
		(width 0.14732)
		(layer "In11.Cu")
		(net "UPI_CPU1_CPU0_P2P2_DN<0>")
	)
	(segment
		(start 359.59542 -280.778204)
		(end 359.59542 -280.766774)
		(width 0.0889)
		(layer "In11.Cu")
		(net "UPI_CPU1_CPU0_P2P2_DN<0>")
	)
	(segment
		(start 360.53522 -277.533862)
		(end 360.53522 -277.522432)
		(width 0.0889)
		(layer "In11.Cu")
		(net "UPI_CPU1_CPU0_P2P2_DN<0>")
	)
	(segment
		(start 356.30612 -288.216086)
		(end 356.30612 -288.092388)
		(width 0.0889)
		(layer "In11.Cu")
		(net "UPI_CPU1_CPU0_P2P2_DN<0>")
	)
	(segment
		(start 85.171026 -284.582362)
		(end 85.017356 -284.736032)
		(width 0.0889)
		(layer "In11.Cu")
		(net "UPI_CPU1_CPU0_P2P2_DN<0>")
	)
	(segment
		(start 127.141732 -392.724132)
		(end 162.051238 -392.724132)
		(width 0.14732)
		(layer "In11.Cu")
		(net "UPI_CPU1_CPU0_P2P2_DN<0>")
	)
	(segment
		(start 356.58425 -291.619686)
		(end 356.305866 -291.341556)
		(width 0.0889)
		(layer "In11.Cu")
		(net "UPI_CPU1_CPU0_P2P2_DN<0>")
	)
	(segment
		(start 55.920132 -314.120022)
		(end 54.15153 -315.065664)
		(width 0.14732)
		(layer "In11.Cu")
		(net "UPI_CPU1_CPU0_P2P2_DN<0>")
	)
	(segment
		(start 286.222948 -343.192608)
		(end 287.355534 -342.72347)
		(width 0.14732)
		(layer "In11.Cu")
		(net "UPI_CPU1_CPU0_P2P2_DN<0>")
	)
	(segment
		(start 359.398824 -279.48001)
		(end 359.409238 -279.474168)
		(width 0.0889)
		(layer "In11.Cu")
		(net "UPI_CPU1_CPU0_P2P2_DN<0>")
	)
	(segment
		(start 85.017356 -284.736032)
		(end 85.017356 -284.865826)
		(width 0.0889)
		(layer "In11.Cu")
		(net "UPI_CPU1_CPU0_P2P2_DN<0>")
	)
	(segment
		(start 85.631782 -284.52826)
		(end 85.622892 -284.52318)
		(width 0.0889)
		(layer "In11.Cu")
		(net "UPI_CPU1_CPU0_P2P2_DN<0>")
	)
	(segment
		(start 85.171534 -284.581854)
		(end 85.17128 -284.582362)
		(width 0.0889)
		(layer "In11.Cu")
		(net "UPI_CPU1_CPU0_P2P2_DN<0>")
	)
	(segment
		(start 356.601522 -298.663614)
		(end 356.847902 -298.068746)
		(width 0.14732)
		(layer "In11.Cu")
		(net "UPI_CPU1_CPU0_P2P2_DN<0>")
	)
	(segment
		(start 83.18246 -383.82067)
		(end 83.522566 -383.961386)
		(width 0.14732)
		(layer "In11.Cu")
		(net "UPI_CPU1_CPU0_P2P2_DN<0>")
	)
	(segment
		(start 359.413048 -282.084272)
		(end 359.409492 -282.08224)
		(width 0.0889)
		(layer "In11.Cu")
		(net "UPI_CPU1_CPU0_P2P2_DN<0>")
	)
	(segment
		(start 341.375746 -311.36209)
		(end 345.69019 -309.574946)
		(width 0.14732)
		(layer "In11.Cu")
		(net "UPI_CPU1_CPU0_P2P2_DN<0>")
	)
	(segment
		(start 84.563966 -288.95421)
		(end 84.464906 -289.05327)
		(width 0.0889)
		(layer "In11.Cu")
		(net "UPI_CPU1_CPU0_P2P2_DN<0>")
	)
	(segment
		(start 354.23856 -301.026576)
		(end 354.23856 -300.821852)
		(width 0.14732)
		(layer "In11.Cu")
		(net "UPI_CPU1_CPU0_P2P2_DN<0>")
	)
	(segment
		(start 70.169786 -305.485546)
		(end 68.177918 -306.81676)
		(width 0.14732)
		(layer "In11.Cu")
		(net "UPI_CPU1_CPU0_P2P2_DN<0>")
	)
	(segment
		(start 70.555104 -378.59081)
		(end 71.1454 -378.835158)
		(width 0.14732)
		(layer "In11.Cu")
		(net "UPI_CPU1_CPU0_P2P2_DN<0>")
	)
	(segment
		(start 360.065066 -278.348948)
		(end 360.065066 -278.336502)
		(width 0.0889)
		(layer "In11.Cu")
		(net "UPI_CPU1_CPU0_P2P2_DN<0>")
	)
	(segment
		(start 357.245666 -286.483298)
		(end 357.245666 -286.475424)
		(width 0.0889)
		(layer "In11.Cu")
		(net "UPI_CPU1_CPU0_P2P2_DN<0>")
	)
	(segment
		(start 345.69019 -309.574946)
		(end 346.781882 -308.483254)
		(width 0.14732)
		(layer "In11.Cu")
		(net "UPI_CPU1_CPU0_P2P2_DN<0>")
	)
	(segment
		(start 359.398062 -281.108658)
		(end 359.398824 -281.107896)
		(width 0.0889)
		(layer "In11.Cu")
		(net "UPI_CPU1_CPU0_P2P2_DN<0>")
	)
	(segment
		(start 51.780694 -318.554862)
		(end 50.94605 -318.900556)
		(width 0.14732)
		(layer "In11.Cu")
		(net "UPI_CPU1_CPU0_P2P2_DN<0>")
	)
	(segment
		(start 50.365152 -325.450962)
		(end 50.725324 -329.10907)
		(width 0.14732)
		(layer "In11.Cu")
		(net "UPI_CPU1_CPU0_P2P2_DN<0>")
	)
	(segment
		(start 50.725324 -329.10907)
		(end 50.816764 -329.568556)
		(width 0.14732)
		(layer "In11.Cu")
		(net "UPI_CPU1_CPU0_P2P2_DN<0>")
	)
	(segment
		(start 360.345228 -277.19655)
		(end 360.336084 -277.191216)
		(width 0.0889)
		(layer "In11.Cu")
		(net "UPI_CPU1_CPU0_P2P2_DN<0>")
	)
	(segment
		(start 276.338284 -373.6086)
		(end 276.647402 -373.299482)
		(width 0.14732)
		(layer "In11.Cu")
		(net "UPI_CPU1_CPU0_P2P2_DN<0>")
	)
	(segment
		(start 84.563966 -287.29305)
		(end 84.464906 -287.39211)
		(width 0.0889)
		(layer "In11.Cu")
		(net "UPI_CPU1_CPU0_P2P2_DN<0>")
	)
	(segment
		(start 354.499164 -300.561248)
		(end 354.703888 -300.561248)
		(width 0.14732)
		(layer "In11.Cu")
		(net "UPI_CPU1_CPU0_P2P2_DN<0>")
	)
	(segment
		(start 356.155244 -299.109892)
		(end 356.601522 -298.663614)
		(width 0.14732)
		(layer "In11.Cu")
		(net "UPI_CPU1_CPU0_P2P2_DN<0>")
	)
	(segment
		(start 83.887564 -289.943286)
		(end 83.87207 -289.95878)
		(width 0.0889)
		(layer "In11.Cu")
		(net "UPI_CPU1_CPU0_P2P2_DN<0>")
	)
	(segment
		(start 84.464906 -287.39211)
		(end 84.464906 -287.56991)
		(width 0.0889)
		(layer "In11.Cu")
		(net "UPI_CPU1_CPU0_P2P2_DN<0>")
	)
	(segment
		(start 84.563966 -286.56153)
		(end 84.563966 -286.73933)
		(width 0.0889)
		(layer "In11.Cu")
		(net "UPI_CPU1_CPU0_P2P2_DN<0>")
	)
	(segment
		(start 83.103974 -383.631186)
		(end 83.18246 -383.82067)
		(width 0.14732)
		(layer "In11.Cu")
		(net "UPI_CPU1_CPU0_P2P2_DN<0>")
	)
	(segment
		(start 85.435694 -284.847538)
		(end 85.748368 -284.847538)
		(width 0.0889)
		(layer "In11.Cu")
		(net "UPI_CPU1_CPU0_P2P2_DN<0>")
	)
	(segment
		(start 68.177918 -306.817014)
		(end 66.186558 -308.14772)
		(width 0.14732)
		(layer "In11.Cu")
		(net "UPI_CPU1_CPU0_P2P2_DN<0>")
	)
	(segment
		(start 347.091 -308.00167)
		(end 347.263466 -308.00167)
		(width 0.14732)
		(layer "In11.Cu")
		(net "UPI_CPU1_CPU0_P2P2_DN<0>")
	)
	(segment
		(start 354.703888 -300.561248)
		(end 354.964238 -300.300898)
		(width 0.14732)
		(layer "In11.Cu")
		(net "UPI_CPU1_CPU0_P2P2_DN<0>")
	)
	(segment
		(start 358.464358 -284.36062)
		(end 358.467152 -284.358842)
		(width 0.0889)
		(layer "In11.Cu")
		(net "UPI_CPU1_CPU0_P2P2_DN<0>")
	)
	(segment
		(start 277.389336 -372.52529)
		(end 277.59406 -372.52529)
		(width 0.14732)
		(layer "In11.Cu")
		(net "UPI_CPU1_CPU0_P2P2_DN<0>")
	)
	(segment
		(start 359.398062 -279.480772)
		(end 359.398824 -279.48001)
		(width 0.0889)
		(layer "In11.Cu")
		(net "UPI_CPU1_CPU0_P2P2_DN<0>")
	)
	(segment
		(start 355.224842 -299.83557)
		(end 355.429566 -299.83557)
		(width 0.14732)
		(layer "In11.Cu")
		(net "UPI_CPU1_CPU0_P2P2_DN<0>")
	)
	(segment
		(start 50.972466 -329.94346)
		(end 54.319932 -333.290672)
		(width 0.14732)
		(layer "In11.Cu")
		(net "UPI_CPU1_CPU0_P2P2_DN<0>")
	)
	(segment
		(start 359.409238 -281.102054)
		(end 359.413048 -281.099768)
		(width 0.0889)
		(layer "In11.Cu")
		(net "UPI_CPU1_CPU0_P2P2_DN<0>")
	)
	(segment
		(start 84.563966 -286.73933)
		(end 84.464906 -286.83839)
		(width 0.0889)
		(layer "In11.Cu")
		(net "UPI_CPU1_CPU0_P2P2_DN<0>")
	)
	(segment
		(start 287.355534 -342.72347)
		(end 311.606946 -342.72347)
		(width 0.14732)
		(layer "In11.Cu")
		(net "UPI_CPU1_CPU0_P2P2_DN<0>")
	)
	(segment
		(start 276.819868 -373.299482)
		(end 277.128732 -372.990618)
		(width 0.14732)
		(layer "In11.Cu")
		(net "UPI_CPU1_CPU0_P2P2_DN<0>")
	)
	(segment
		(start 359.878122 -276.384258)
		(end 359.867454 -276.377908)
		(width 0.0889)
		(layer "In11.Cu")
		(net "UPI_CPU1_CPU0_P2P2_DN<0>")
	)
	(arc
		(start 359.398062 -282.075382)
		(mid 359.200906 -281.874136)
		(end 359.12552 -281.602688)
		(width 0.0889)
		(layer "In11.Cu")
		(net "UPI_CPU1_CPU0_P2P2_DN<0>")
	)
	(arc
		(start 85.622892 -284.52318)
		(mid 85.435694 -284.473037)
		(end 85.248496 -284.52318)
		(width 0.0889)
		(layer "In11.Cu")
		(net "UPI_CPU1_CPU0_P2P2_DN<0>")
	)
	(arc
		(start 352.907346 -275.608034)
		(mid 352.897274 -275.604067)
		(end 352.88728 -275.599906)
		(width 0.0889)
		(layer "In11.Cu")
		(net "UPI_CPU1_CPU0_P2P2_DN<0>")
	)
	(arc
		(start 357.528368 -285.985966)
		(mid 357.661745 -285.855206)
		(end 357.715566 -285.67634)
		(width 0.0889)
		(layer "In11.Cu")
		(net "UPI_CPU1_CPU0_P2P2_DN<0>")
	)
	(arc
		(start 358.56291 -274.756118)
		(mid 358.280462 -274.831801)
		(end 357.998014 -274.756118)
		(width 0.0889)
		(layer "In11.Cu")
		(net "UPI_CPU1_CPU0_P2P2_DN<0>")
	)
	(arc
		(start 359.12552 -279.953466)
		(mid 359.200926 -279.68203)
		(end 359.398062 -279.480772)
		(width 0.0889)
		(layer "In11.Cu")
		(net "UPI_CPU1_CPU0_P2P2_DN<0>")
	)
	(arc
		(start 359.59542 -280.766774)
		(mid 359.542276 -280.585688)
		(end 359.407714 -280.453338)
		(width 0.0889)
		(layer "In11.Cu")
		(net "UPI_CPU1_CPU0_P2P2_DN<0>")
	)
	(arc
		(start 356.109778 -274.750784)
		(mid 355.925957 -274.705726)
		(end 355.74351 -274.756118)
		(width 0.0889)
		(layer "In11.Cu")
		(net "UPI_CPU1_CPU0_P2P2_DN<0>")
	)
	(arc
		(start 358.47274 -284.35554)
		(mid 358.606696 -284.218781)
		(end 358.65562 -284.033722)
		(width 0.0889)
		(layer "In11.Cu")
		(net "UPI_CPU1_CPU0_P2P2_DN<0>")
	)
	(arc
		(start 355.74351 -274.756118)
		(mid 355.609478 -274.887966)
		(end 355.556312 -275.068284)
		(width 0.0889)
		(layer "In11.Cu")
		(net "UPI_CPU1_CPU0_P2P2_DN<0>")
	)
	(arc
		(start 354.708968 -275.569934)
		(mid 354.526492 -275.519641)
		(end 354.3427 -275.564854)
		(width 0.0889)
		(layer "In11.Cu")
		(net "UPI_CPU1_CPU0_P2P2_DN<0>")
	)
	(arc
		(start 85.248496 -284.52318)
		(mid 85.213602 -284.545823)
		(end 85.18144 -284.572202)
		(width 0.0889)
		(layer "In11.Cu")
		(net "UPI_CPU1_CPU0_P2P2_DN<0>")
	)
	(arc
		(start 360.065066 -278.336502)
		(mid 360.137758 -278.059297)
		(end 360.3371 -277.853394)
		(width 0.0889)
		(layer "In11.Cu")
		(net "UPI_CPU1_CPU0_P2P2_DN<0>")
	)
	(arc
		(start 356.30612 -288.092388)
		(mid 356.38428 -287.816229)
		(end 356.58806 -287.614106)
		(width 0.0889)
		(layer "In11.Cu")
		(net "UPI_CPU1_CPU0_P2P2_DN<0>")
	)
	(arc
		(start 359.407714 -282.730702)
		(mid 359.542341 -282.59839)
		(end 359.59542 -282.417266)
		(width 0.0889)
		(layer "In11.Cu")
		(net "UPI_CPU1_CPU0_P2P2_DN<0>")
	)
	(arc
		(start 356.589584 -288.605722)
		(mid 356.405158 -288.441972)
		(end 356.30612 -288.216086)
		(width 0.0889)
		(layer "In11.Cu")
		(net "UPI_CPU1_CPU0_P2P2_DN<0>")
	)
	(arc
		(start 357.245666 -286.475424)
		(mid 357.318358 -286.198219)
		(end 357.5177 -285.992316)
		(width 0.0889)
		(layer "In11.Cu")
		(net "UPI_CPU1_CPU0_P2P2_DN<0>")
	)
	(arc
		(start 356.592886 -287.611058)
		(mid 356.727016 -287.47436)
		(end 356.77602 -287.28924)
		(width 0.0889)
		(layer "In11.Cu")
		(net "UPI_CPU1_CPU0_P2P2_DN<0>")
	)
	(arc
		(start 359.12552 -275.072856)
		(mid 359.073293 -274.889938)
		(end 358.938068 -274.756118)
		(width 0.0889)
		(layer "In11.Cu")
		(net "UPI_CPU1_CPU0_P2P2_DN<0>")
	)
	(arc
		(start 356.77602 -287.278572)
		(mid 356.854175 -287.002176)
		(end 357.058214 -286.800036)
		(width 0.0889)
		(layer "In11.Cu")
		(net "UPI_CPU1_CPU0_P2P2_DN<0>")
	)
	(arc
		(start 357.715566 -285.661354)
		(mid 357.787374 -285.385658)
		(end 357.984552 -285.180024)
		(width 0.0889)
		(layer "In11.Cu")
		(net "UPI_CPU1_CPU0_P2P2_DN<0>")
	)
	(arc
		(start 359.407714 -275.569934)
		(mid 359.203736 -275.367758)
		(end 359.12552 -275.091398)
		(width 0.0889)
		(layer "In11.Cu")
		(net "UPI_CPU1_CPU0_P2P2_DN<0>")
	)
	(arc
		(start 359.59542 -282.405836)
		(mid 359.546651 -282.221)
		(end 359.413048 -282.084272)
		(width 0.0889)
		(layer "In11.Cu")
		(net "UPI_CPU1_CPU0_P2P2_DN<0>")
	)
	(arc
		(start 359.867454 -276.377908)
		(mid 359.66807 -276.172028)
		(end 359.59542 -275.8948)
		(width 0.0889)
		(layer "In11.Cu")
		(net "UPI_CPU1_CPU0_P2P2_DN<0>")
	)
	(arc
		(start 356.305866 -289.648392)
		(mid 356.412116 -289.441146)
		(end 356.5906 -289.291522)
		(width 0.0889)
		(layer "In11.Cu")
		(net "UPI_CPU1_CPU0_P2P2_DN<0>")
	)
	(arc
		(start 354.334318 -275.56968)
		(mid 354.051362 -275.645651)
		(end 353.768406 -275.56968)
		(width 0.0889)
		(layer "In11.Cu")
		(net "UPI_CPU1_CPU0_P2P2_DN<0>")
	)
	(arc
		(start 353.760024 -275.564854)
		(mid 353.576342 -275.51967)
		(end 353.39401 -275.569934)
		(width 0.0889)
		(layer "In11.Cu")
		(net "UPI_CPU1_CPU0_P2P2_DN<0>")
	)
	(arc
		(start 360.347768 -277.847044)
		(mid 360.48215 -277.71479)
		(end 360.53522 -277.533862)
		(width 0.0889)
		(layer "In11.Cu")
		(net "UPI_CPU1_CPU0_P2P2_DN<0>")
	)
	(arc
		(start 355.273356 -275.570188)
		(mid 354.991133 -275.645583)
		(end 354.708968 -275.569934)
		(width 0.0889)
		(layer "In11.Cu")
		(net "UPI_CPU1_CPU0_P2P2_DN<0>")
	)
	(arc
		(start 359.413048 -279.471882)
		(mid 359.546664 -279.335162)
		(end 359.59542 -279.150318)
		(width 0.0889)
		(layer "In11.Cu")
		(net "UPI_CPU1_CPU0_P2P2_DN<0>")
	)
	(arc
		(start 358.00919 -285.165546)
		(mid 358.138645 -285.029404)
		(end 358.18572 -284.847538)
		(width 0.0889)
		(layer "In11.Cu")
		(net "UPI_CPU1_CPU0_P2P2_DN<0>")
	)
	(arc
		(start 358.18572 -284.847538)
		(mid 358.258412 -284.570333)
		(end 358.457754 -284.36443)
		(width 0.0889)
		(layer "In11.Cu")
		(net "UPI_CPU1_CPU0_P2P2_DN<0>")
	)
	(arc
		(start 357.62311 -274.756118)
		(mid 357.340662 -274.831801)
		(end 357.058214 -274.756118)
		(width 0.0889)
		(layer "In11.Cu")
		(net "UPI_CPU1_CPU0_P2P2_DN<0>")
	)
	(arc
		(start 353.39401 -275.569934)
		(mid 353.154762 -275.643855)
		(end 352.907092 -275.607018)
		(width 0.0889)
		(layer "In11.Cu")
		(net "UPI_CPU1_CPU0_P2P2_DN<0>")
	)
	(arc
		(start 357.058214 -274.756118)
		(mid 356.875992 -274.705918)
		(end 356.692454 -274.751038)
		(width 0.0889)
		(layer "In11.Cu")
		(net "UPI_CPU1_CPU0_P2P2_DN<0>")
	)
	(arc
		(start 360.53522 -277.522432)
		(mid 360.486451 -277.337596)
		(end 360.352848 -277.200868)
		(width 0.0889)
		(layer "In11.Cu")
		(net "UPI_CPU1_CPU0_P2P2_DN<0>")
	)
	(arc
		(start 359.413048 -281.099768)
		(mid 359.546664 -280.963048)
		(end 359.59542 -280.778204)
		(width 0.0889)
		(layer "In11.Cu")
		(net "UPI_CPU1_CPU0_P2P2_DN<0>")
	)
	(arc
		(start 359.12552 -283.209238)
		(mid 359.203675 -282.932842)
		(end 359.407714 -282.730702)
		(width 0.0889)
		(layer "In11.Cu")
		(net "UPI_CPU1_CPU0_P2P2_DN<0>")
	)
	(arc
		(start 359.59542 -275.88337)
		(mid 359.542276 -275.702284)
		(end 359.407714 -275.569934)
		(width 0.0889)
		(layer "In11.Cu")
		(net "UPI_CPU1_CPU0_P2P2_DN<0>")
	)
	(arc
		(start 356.684072 -274.755864)
		(mid 356.401116 -274.831835)
		(end 356.11816 -274.755864)
		(width 0.0889)
		(layer "In11.Cu")
		(net "UPI_CPU1_CPU0_P2P2_DN<0>")
	)
	(arc
		(start 359.59542 -279.150318)
		(mid 359.668112 -278.873113)
		(end 359.867454 -278.66721)
		(width 0.0889)
		(layer "In11.Cu")
		(net "UPI_CPU1_CPU0_P2P2_DN<0>")
	)
	(arc
		(start 358.65562 -284.033722)
		(mid 358.728312 -283.756517)
		(end 358.927654 -283.550614)
		(width 0.0889)
		(layer "In11.Cu")
		(net "UPI_CPU1_CPU0_P2P2_DN<0>")
	)
	(arc
		(start 85.18144 -284.572202)
		(mid 85.176442 -284.576981)
		(end 85.171534 -284.581854)
		(width 0.0889)
		(layer "In11.Cu")
		(net "UPI_CPU1_CPU0_P2P2_DN<0>")
	)
	(arc
		(start 356.5906 -289.291522)
		(mid 356.697075 -289.20731)
		(end 356.768908 -289.092132)
		(width 0.0889)
		(layer "In11.Cu")
		(net "UPI_CPU1_CPU0_P2P2_DN<0>")
	)
	(arc
		(start 85.805772 -284.790134)
		(mid 85.747616 -284.640021)
		(end 85.631782 -284.52826)
		(width 0.0889)
		(layer "In11.Cu")
		(net "UPI_CPU1_CPU0_P2P2_DN<0>")
	)
	(arc
		(start 360.336084 -277.191216)
		(mid 360.137443 -276.985367)
		(end 360.065066 -276.708616)
		(width 0.0889)
		(layer "In11.Cu")
		(net "UPI_CPU1_CPU0_P2P2_DN<0>")
	)
	(arc
		(start 359.12552 -281.581352)
		(mid 359.200926 -281.309916)
		(end 359.398062 -281.108658)
		(width 0.0889)
		(layer "In11.Cu")
		(net "UPI_CPU1_CPU0_P2P2_DN<0>")
	)
	(arc
		(start 356.780846 -288.873184)
		(mid 356.715141 -288.718045)
		(end 356.589584 -288.605722)
		(width 0.0889)
		(layer "In11.Cu")
		(net "UPI_CPU1_CPU0_P2P2_DN<0>")
	)
	(arc
		(start 358.929178 -274.750784)
		(mid 358.745357 -274.705726)
		(end 358.56291 -274.756118)
		(width 0.0889)
		(layer "In11.Cu")
		(net "UPI_CPU1_CPU0_P2P2_DN<0>")
	)
	(arc
		(start 358.938322 -283.544264)
		(mid 359.073367 -283.41054)
		(end 359.12552 -283.22778)
		(width 0.0889)
		(layer "In11.Cu")
		(net "UPI_CPU1_CPU0_P2P2_DN<0>")
	)
	(arc
		(start 359.407714 -280.453338)
		(mid 359.203736 -280.251162)
		(end 359.12552 -279.974802)
		(width 0.0889)
		(layer "In11.Cu")
		(net "UPI_CPU1_CPU0_P2P2_DN<0>")
	)
	(arc
		(start 357.998014 -274.756118)
		(mid 357.810562 -274.705882)
		(end 357.62311 -274.756118)
		(width 0.0889)
		(layer "In11.Cu")
		(net "UPI_CPU1_CPU0_P2P2_DN<0>")
	)
	(arc
		(start 355.556312 -275.08073)
		(mid 355.48362 -275.357935)
		(end 355.284278 -275.563838)
		(width 0.0889)
		(layer "In11.Cu")
		(net "UPI_CPU1_CPU0_P2P2_DN<0>")
	)
	(arc
		(start 360.065066 -276.69617)
		(mid 360.011924 -276.51604)
		(end 359.878122 -276.384258)
		(width 0.0889)
		(layer "In11.Cu")
		(net "UPI_CPU1_CPU0_P2P2_DN<0>")
	)
	(arc
		(start 359.878122 -278.66086)
		(mid 360.01191 -278.52907)
		(end 360.065066 -278.348948)
		(width 0.0889)
		(layer "In11.Cu")
		(net "UPI_CPU1_CPU0_P2P2_DN<0>")
	)
	(arc
		(start 357.058214 -286.800036)
		(mid 357.193505 -286.666254)
		(end 357.245666 -286.483298)
		(width 0.0889)
		(layer "In11.Cu")
		(net "UPI_CPU1_CPU0_P2P2_DN<0>")
	)
	(segment
		(start 345.953334 -217.600276)
		(end 345.953334 -217.06459)
		(width 0.13208)
		(layer "F.Cu")
		(net "UPI_CPU1_CPU0_P1P0_DP<9>")
	)
	(segment
		(start 345.953334 -217.06459)
		(end 345.95308 -217.064336)
		(width 0.13208)
		(layer "F.Cu")
		(net "UPI_CPU1_CPU0_P1P0_DP<9>")
	)
	(segment
		(start 125.267466 -218.692476)
		(end 125.267212 -218.692222)
		(width 0.13208)
		(layer "F.Cu")
		(net "UPI_CPU1_CPU0_P1P0_DP<9>")
	)
	(segment
		(start 125.267466 -219.228162)
		(end 125.267466 -218.692476)
		(width 0.13208)
		(layer "F.Cu")
		(net "UPI_CPU1_CPU0_P1P0_DP<9>")
	)
	(segment
		(start 346.48648 -204.569314)
		(end 346.48648 -209.949288)
		(width 0.14732)
		(layer "In4.Cu")
		(net "UPI_CPU1_CPU0_P1P0_DP<9>")
	)
	(segment
		(start 345.796616 -217.335354)
		(end 345.95308 -217.064336)
		(width 0.0889)
		(layer "In4.Cu")
		(net "UPI_CPU1_CPU0_P1P0_DP<9>")
	)
	(segment
		(start 345.620594 -210.815174)
		(end 345.620594 -211.762848)
		(width 0.14732)
		(layer "In4.Cu")
		(net "UPI_CPU1_CPU0_P1P0_DP<9>")
	)
	(segment
		(start 158.88843 -181.667912)
		(end 200.608184 -180.975508)
		(width 0.14732)
		(layer "In4.Cu")
		(net "UPI_CPU1_CPU0_P1P0_DP<9>")
	)
	(segment
		(start 125.641862 -215.436704)
		(end 125.641862 -215.414606)
		(width 0.0889)
		(layer "In4.Cu")
		(net "UPI_CPU1_CPU0_P1P0_DP<9>")
	)
	(segment
		(start 125.600206 -211.782406)
		(end 128.261364 -204.180948)
		(width 0.14732)
		(layer "In4.Cu")
		(net "UPI_CPU1_CPU0_P1P0_DP<9>")
	)
	(segment
		(start 346.048076 -214.424768)
		(end 346.048076 -214.644732)
		(width 0.0889)
		(layer "In4.Cu")
		(net "UPI_CPU1_CPU0_P1P0_DP<9>")
	)
	(segment
		(start 324.74281 -184.850786)
		(end 327.53427 -186.889898)
		(width 0.14732)
		(layer "In4.Cu")
		(net "UPI_CPU1_CPU0_P1P0_DP<9>")
	)
	(segment
		(start 125.267212 -218.692222)
		(end 125.423676 -218.421204)
		(width 0.0889)
		(layer "In4.Cu")
		(net "UPI_CPU1_CPU0_P1P0_DP<9>")
	)
	(segment
		(start 345.578684 -212.917278)
		(end 345.578684 -213.092538)
		(width 0.0889)
		(layer "In4.Cu")
		(net "UPI_CPU1_CPU0_P1P0_DP<9>")
	)
	(segment
		(start 125.172216 -216.260426)
		(end 125.172216 -216.235026)
		(width 0.0889)
		(layer "In4.Cu")
		(net "UPI_CPU1_CPU0_P1P0_DP<9>")
	)
	(segment
		(start 125.600206 -212.02523)
		(end 125.600206 -211.782406)
		(width 0.14732)
		(layer "In4.Cu")
		(net "UPI_CPU1_CPU0_P1P0_DP<9>")
	)
	(segment
		(start 345.677744 -212.818218)
		(end 345.578684 -212.917278)
		(width 0.0889)
		(layer "In4.Cu")
		(net "UPI_CPU1_CPU0_P1P0_DP<9>")
	)
	(segment
		(start 144.394174 -187.3758)
		(end 152.198578 -183.38038)
		(width 0.14732)
		(layer "In4.Cu")
		(net "UPI_CPU1_CPU0_P1P0_DP<9>")
	)
	(segment
		(start 273.198844 -181.329838)
		(end 302.423068 -180.621178)
		(width 0.14732)
		(layer "In4.Cu")
		(net "UPI_CPU1_CPU0_P1P0_DP<9>")
	)
	(segment
		(start 345.768676 -215.762586)
		(end 345.771978 -215.764618)
		(width 0.0889)
		(layer "In4.Cu")
		(net "UPI_CPU1_CPU0_P1P0_DP<9>")
	)
	(segment
		(start 344.83675 -200.586086)
		(end 346.48648 -204.569314)
		(width 0.14732)
		(layer "In4.Cu")
		(net "UPI_CPU1_CPU0_P1P0_DP<9>")
	)
	(segment
		(start 345.578684 -212.038692)
		(end 345.578684 -212.543898)
		(width 0.0889)
		(layer "In4.Cu")
		(net "UPI_CPU1_CPU0_P1P0_DP<9>")
	)
	(segment
		(start 327.53427 -186.889898)
		(end 329.265534 -188.107828)
		(width 0.14732)
		(layer "In4.Cu")
		(net "UPI_CPU1_CPU0_P1P0_DP<9>")
	)
	(segment
		(start 345.766644 -216.73947)
		(end 345.765882 -216.739978)
		(width 0.0889)
		(layer "In4.Cu")
		(net "UPI_CPU1_CPU0_P1P0_DP<9>")
	)
	(segment
		(start 312.469784 -180.805836)
		(end 315.192664 -181.578758)
		(width 0.14732)
		(layer "In4.Cu")
		(net "UPI_CPU1_CPU0_P1P0_DP<9>")
	)
	(segment
		(start 125.924056 -214.946992)
		(end 125.932946 -214.941912)
		(width 0.0889)
		(layer "In4.Cu")
		(net "UPI_CPU1_CPU0_P1P0_DP<9>")
	)
	(segment
		(start 128.261364 -204.180948)
		(end 133.813296 -197.350888)
		(width 0.14732)
		(layer "In4.Cu")
		(net "UPI_CPU1_CPU0_P1P0_DP<9>")
	)
	(segment
		(start 212.424264 -181.494684)
		(end 238.626904 -181.494684)
		(width 0.14732)
		(layer "In4.Cu")
		(net "UPI_CPU1_CPU0_P1P0_DP<9>")
	)
	(segment
		(start 302.423068 -180.621178)
		(end 312.469784 -180.805836)
		(width 0.14732)
		(layer "In4.Cu")
		(net "UPI_CPU1_CPU0_P1P0_DP<9>")
	)
	(segment
		(start 345.756992 -215.755982)
		(end 345.764358 -215.7603)
		(width 0.0889)
		(layer "In4.Cu")
		(net "UPI_CPU1_CPU0_P1P0_DP<9>")
	)
	(segment
		(start 133.813296 -197.350888)
		(end 133.813042 -197.350634)
		(width 0.14732)
		(layer "In4.Cu")
		(net "UPI_CPU1_CPU0_P1P0_DP<9>")
	)
	(segment
		(start 152.198578 -183.38038)
		(end 158.88843 -181.667912)
		(width 0.14732)
		(layer "In4.Cu")
		(net "UPI_CPU1_CPU0_P1P0_DP<9>")
	)
	(segment
		(start 125.932946 -214.303356)
		(end 125.889512 -214.27821)
		(width 0.0889)
		(layer "In4.Cu")
		(net "UPI_CPU1_CPU0_P1P0_DP<9>")
	)
	(segment
		(start 125.642116 -213.762844)
		(end 125.642116 -212.089238)
		(width 0.0889)
		(layer "In4.Cu")
		(net "UPI_CPU1_CPU0_P1P0_DP<9>")
	)
	(segment
		(start 125.45441 -215.761062)
		(end 125.4633 -215.755982)
		(width 0.0889)
		(layer "In4.Cu")
		(net "UPI_CPU1_CPU0_P1P0_DP<9>")
	)
	(segment
		(start 125.423676 -218.421204)
		(end 125.399546 -218.33205)
		(width 0.0889)
		(layer "In4.Cu")
		(net "UPI_CPU1_CPU0_P1P0_DP<9>")
	)
	(segment
		(start 346.48648 -209.949288)
		(end 345.620594 -210.815174)
		(width 0.14732)
		(layer "In4.Cu")
		(net "UPI_CPU1_CPU0_P1P0_DP<9>")
	)
	(segment
		(start 345.765882 -215.761062)
		(end 345.768676 -215.762586)
		(width 0.0889)
		(layer "In4.Cu")
		(net "UPI_CPU1_CPU0_P1P0_DP<9>")
	)
	(segment
		(start 329.265534 -188.107828)
		(end 332.766924 -189.589156)
		(width 0.14732)
		(layer "In4.Cu")
		(net "UPI_CPU1_CPU0_P1P0_DP<9>")
	)
	(segment
		(start 345.620848 -211.996528)
		(end 345.578684 -212.038692)
		(width 0.0889)
		(layer "In4.Cu")
		(net "UPI_CPU1_CPU0_P1P0_DP<9>")
	)
	(segment
		(start 125.642116 -212.089238)
		(end 125.600206 -212.047328)
		(width 0.0889)
		(layer "In4.Cu")
		(net "UPI_CPU1_CPU0_P1P0_DP<9>")
	)
	(segment
		(start 345.620594 -211.762848)
		(end 345.620848 -211.763102)
		(width 0.14732)
		(layer "In4.Cu")
		(net "UPI_CPU1_CPU0_P1P0_DP<9>")
	)
	(segment
		(start 345.771978 -216.736422)
		(end 345.766644 -216.73947)
		(width 0.0889)
		(layer "In4.Cu")
		(net "UPI_CPU1_CPU0_P1P0_DP<9>")
	)
	(segment
		(start 345.764358 -215.7603)
		(end 345.765882 -215.761062)
		(width 0.0889)
		(layer "In4.Cu")
		(net "UPI_CPU1_CPU0_P1P0_DP<9>")
	)
	(segment
		(start 345.578684 -217.0557)
		(end 345.578684 -217.072972)
		(width 0.0889)
		(layer "In4.Cu")
		(net "UPI_CPU1_CPU0_P1P0_DP<9>")
	)
	(segment
		(start 345.578684 -212.543898)
		(end 345.677744 -212.642958)
		(width 0.0889)
		(layer "In4.Cu")
		(net "UPI_CPU1_CPU0_P1P0_DP<9>")
	)
	(segment
		(start 345.677744 -213.366858)
		(end 345.578684 -213.465918)
		(width 0.0889)
		(layer "In4.Cu")
		(net "UPI_CPU1_CPU0_P1P0_DP<9>")
	)
	(segment
		(start 315.192664 -181.578758)
		(end 324.74281 -184.850786)
		(width 0.14732)
		(layer "In4.Cu")
		(net "UPI_CPU1_CPU0_P1P0_DP<9>")
	)
	(segment
		(start 345.620848 -211.763102)
		(end 345.620848 -211.97443)
		(width 0.14732)
		(layer "In4.Cu")
		(net "UPI_CPU1_CPU0_P1P0_DP<9>")
	)
	(segment
		(start 200.608184 -180.975508)
		(end 212.424264 -181.494684)
		(width 0.14732)
		(layer "In4.Cu")
		(net "UPI_CPU1_CPU0_P1P0_DP<9>")
	)
	(segment
		(start 345.578684 -213.092538)
		(end 345.677744 -213.191598)
		(width 0.0889)
		(layer "In4.Cu")
		(net "UPI_CPU1_CPU0_P1P0_DP<9>")
	)
	(segment
		(start 345.620848 -211.97443)
		(end 345.620848 -211.996528)
		(width 0.0889)
		(layer "In4.Cu")
		(net "UPI_CPU1_CPU0_P1P0_DP<9>")
	)
	(segment
		(start 125.641862 -217.072972)
		(end 125.641862 -217.0557)
		(width 0.0889)
		(layer "In4.Cu")
		(net "UPI_CPU1_CPU0_P1P0_DP<9>")
	)
	(segment
		(start 140.052552 -193.203322)
		(end 144.394174 -187.3758)
		(width 0.14732)
		(layer "In4.Cu")
		(net "UPI_CPU1_CPU0_P1P0_DP<9>")
	)
	(segment
		(start 332.766924 -189.589156)
		(end 333.140812 -189.883288)
		(width 0.14732)
		(layer "In4.Cu")
		(net "UPI_CPU1_CPU0_P1P0_DP<9>")
	)
	(segment
		(start 345.765882 -215.112346)
		(end 345.764866 -215.112854)
		(width 0.0889)
		(layer "In4.Cu")
		(net "UPI_CPU1_CPU0_P1P0_DP<9>")
	)
	(segment
		(start 345.718638 -217.356182)
		(end 345.796616 -217.335354)
		(width 0.0889)
		(layer "In4.Cu")
		(net "UPI_CPU1_CPU0_P1P0_DP<9>")
	)
	(segment
		(start 345.677744 -213.191598)
		(end 345.677744 -213.366858)
		(width 0.0889)
		(layer "In4.Cu")
		(net "UPI_CPU1_CPU0_P1P0_DP<9>")
	)
	(segment
		(start 333.140812 -189.883288)
		(end 337.7946 -193.543682)
		(width 0.14732)
		(layer "In4.Cu")
		(net "UPI_CPU1_CPU0_P1P0_DP<9>")
	)
	(segment
		(start 345.764866 -215.112854)
		(end 345.756992 -215.117426)
		(width 0.0889)
		(layer "In4.Cu")
		(net "UPI_CPU1_CPU0_P1P0_DP<9>")
	)
	(segment
		(start 345.578684 -213.465918)
		(end 345.578684 -213.893908)
		(width 0.0889)
		(layer "In4.Cu")
		(net "UPI_CPU1_CPU0_P1P0_DP<9>")
	)
	(segment
		(start 125.172216 -217.8939)
		(end 125.172216 -217.859864)
		(width 0.0889)
		(layer "In4.Cu")
		(net "UPI_CPU1_CPU0_P1P0_DP<9>")
	)
	(segment
		(start 337.7946 -193.543682)
		(end 344.83675 -200.586086)
		(width 0.14732)
		(layer "In4.Cu")
		(net "UPI_CPU1_CPU0_P1P0_DP<9>")
	)
	(segment
		(start 345.677744 -212.642958)
		(end 345.677744 -212.818218)
		(width 0.0889)
		(layer "In4.Cu")
		(net "UPI_CPU1_CPU0_P1P0_DP<9>")
	)
	(segment
		(start 125.600206 -212.047328)
		(end 125.600206 -212.02523)
		(width 0.0889)
		(layer "In4.Cu")
		(net "UPI_CPU1_CPU0_P1P0_DP<9>")
	)
	(segment
		(start 238.626904 -181.494684)
		(end 273.198844 -181.329838)
		(width 0.14732)
		(layer "In4.Cu")
		(net "UPI_CPU1_CPU0_P1P0_DP<9>")
	)
	(segment
		(start 133.813042 -197.350634)
		(end 140.052552 -193.203322)
		(width 0.14732)
		(layer "In4.Cu")
		(net "UPI_CPU1_CPU0_P1P0_DP<9>")
	)
	(arc
		(start 125.382782 -218.319096)
		(mid 125.2307 -218.129664)
		(end 125.172216 -217.8939)
		(width 0.0889)
		(layer "In4.Cu")
		(net "UPI_CPU1_CPU0_P1P0_DP<9>")
	)
	(arc
		(start 125.172216 -216.235026)
		(mid 125.251586 -215.961292)
		(end 125.45441 -215.761062)
		(width 0.0889)
		(layer "In4.Cu")
		(net "UPI_CPU1_CPU0_P1P0_DP<9>")
	)
	(arc
		(start 125.454664 -217.388694)
		(mid 125.589597 -217.25534)
		(end 125.641862 -217.072972)
		(width 0.0889)
		(layer "In4.Cu")
		(net "UPI_CPU1_CPU0_P1P0_DP<9>")
	)
	(arc
		(start 345.771978 -215.764618)
		(mid 346.048552 -216.25052)
		(end 345.771978 -216.736422)
		(width 0.0889)
		(layer "In4.Cu")
		(net "UPI_CPU1_CPU0_P1P0_DP<9>")
	)
	(arc
		(start 125.889512 -214.27821)
		(mid 125.69611 -214.053999)
		(end 125.642116 -213.762844)
		(width 0.0889)
		(layer "In4.Cu")
		(net "UPI_CPU1_CPU0_P1P0_DP<9>")
	)
	(arc
		(start 125.399546 -218.33205)
		(mid 125.391105 -218.32565)
		(end 125.382782 -218.319096)
		(width 0.0889)
		(layer "In4.Cu")
		(net "UPI_CPU1_CPU0_P1P0_DP<9>")
	)
	(arc
		(start 345.756992 -215.117426)
		(mid 345.629738 -215.247392)
		(end 345.578684 -215.421972)
		(width 0.0889)
		(layer "In4.Cu")
		(net "UPI_CPU1_CPU0_P1P0_DP<9>")
	)
	(arc
		(start 346.048076 -214.644732)
		(mid 345.967165 -214.91486)
		(end 345.765882 -215.112346)
		(width 0.0889)
		(layer "In4.Cu")
		(net "UPI_CPU1_CPU0_P1P0_DP<9>")
	)
	(arc
		(start 125.172216 -217.859864)
		(mid 125.252378 -217.587675)
		(end 125.454664 -217.388694)
		(width 0.0889)
		(layer "In4.Cu")
		(net "UPI_CPU1_CPU0_P1P0_DP<9>")
	)
	(arc
		(start 125.932946 -214.941912)
		(mid 126.0602 -214.811946)
		(end 126.111254 -214.637366)
		(width 0.0889)
		(layer "In4.Cu")
		(net "UPI_CPU1_CPU0_P1P0_DP<9>")
	)
	(arc
		(start 125.454664 -216.739978)
		(mid 125.250329 -216.537373)
		(end 125.172216 -216.260426)
		(width 0.0889)
		(layer "In4.Cu")
		(net "UPI_CPU1_CPU0_P1P0_DP<9>")
	)
	(arc
		(start 345.765882 -216.739978)
		(mid 345.630949 -216.873332)
		(end 345.578684 -217.0557)
		(width 0.0889)
		(layer "In4.Cu")
		(net "UPI_CPU1_CPU0_P1P0_DP<9>")
	)
	(arc
		(start 345.57843 -215.436704)
		(mid 345.626109 -215.619604)
		(end 345.756992 -215.755982)
		(width 0.0889)
		(layer "In4.Cu")
		(net "UPI_CPU1_CPU0_P1P0_DP<9>")
	)
	(arc
		(start 126.111254 -214.637366)
		(mid 126.111587 -214.624922)
		(end 126.111508 -214.612474)
		(width 0.0889)
		(layer "In4.Cu")
		(net "UPI_CPU1_CPU0_P1P0_DP<9>")
	)
	(arc
		(start 125.641862 -217.0557)
		(mid 125.589592 -216.873335)
		(end 125.454664 -216.739978)
		(width 0.0889)
		(layer "In4.Cu")
		(net "UPI_CPU1_CPU0_P1P0_DP<9>")
	)
	(arc
		(start 125.641862 -215.414606)
		(mid 125.722773 -215.144478)
		(end 125.924056 -214.946992)
		(width 0.0889)
		(layer "In4.Cu")
		(net "UPI_CPU1_CPU0_P1P0_DP<9>")
	)
	(arc
		(start 345.578684 -217.072972)
		(mid 345.617358 -217.23004)
		(end 345.718638 -217.356182)
		(width 0.0889)
		(layer "In4.Cu")
		(net "UPI_CPU1_CPU0_P1P0_DP<9>")
	)
	(arc
		(start 345.578684 -213.893908)
		(mid 345.653689 -214.009367)
		(end 345.762834 -214.093298)
		(width 0.0889)
		(layer "In4.Cu")
		(net "UPI_CPU1_CPU0_P1P0_DP<9>")
	)
	(arc
		(start 126.111508 -214.612474)
		(mid 126.061439 -214.435249)
		(end 125.932946 -214.303356)
		(width 0.0889)
		(layer "In4.Cu")
		(net "UPI_CPU1_CPU0_P1P0_DP<9>")
	)
	(arc
		(start 345.578684 -215.421972)
		(mid 345.578487 -215.429337)
		(end 345.57843 -215.436704)
		(width 0.0889)
		(layer "In4.Cu")
		(net "UPI_CPU1_CPU0_P1P0_DP<9>")
	)
	(arc
		(start 125.4633 -215.755982)
		(mid 125.594214 -215.619622)
		(end 125.641862 -215.436704)
		(width 0.0889)
		(layer "In4.Cu")
		(net "UPI_CPU1_CPU0_P1P0_DP<9>")
	)
	(arc
		(start 345.762834 -214.093298)
		(mid 345.936797 -214.232062)
		(end 346.048076 -214.424768)
		(width 0.0889)
		(layer "In4.Cu")
		(net "UPI_CPU1_CPU0_P1P0_DP<9>")
	)
	(segment
		(start 126.207266 -217.06459)
		(end 126.207012 -217.064336)
		(width 0.13208)
		(layer "F.Cu")
		(net "UPI_CPU1_CPU0_P1P0_DP<8>")
	)
	(segment
		(start 345.013534 -219.228162)
		(end 345.013534 -218.692476)
		(width 0.13208)
		(layer "F.Cu")
		(net "UPI_CPU1_CPU0_P1P0_DP<8>")
	)
	(segment
		(start 126.207266 -217.600276)
		(end 126.207266 -217.06459)
		(width 0.13208)
		(layer "F.Cu")
		(net "UPI_CPU1_CPU0_P1P0_DP<8>")
	)
	(segment
		(start 345.013534 -218.692476)
		(end 345.01328 -218.692222)
		(width 0.13208)
		(layer "F.Cu")
		(net "UPI_CPU1_CPU0_P1P0_DP<8>")
	)
	(segment
		(start 126.58217 -212.784944)
		(end 126.482856 -212.68563)
		(width 0.0889)
		(layer "In4.Cu")
		(net "UPI_CPU1_CPU0_P1P0_DP<8>")
	)
	(segment
		(start 344.68054 -210.582002)
		(end 344.68054 -211.762848)
		(width 0.14732)
		(layer "In4.Cu")
		(net "UPI_CPU1_CPU0_P1P0_DP<8>")
	)
	(segment
		(start 126.58217 -213.051644)
		(end 126.58217 -212.784944)
		(width 0.0889)
		(layer "In4.Cu")
		(net "UPI_CPU1_CPU0_P1P0_DP<8>")
	)
	(segment
		(start 126.58217 -213.516972)
		(end 126.482856 -213.417658)
		(width 0.0889)
		(layer "In4.Cu")
		(net "UPI_CPU1_CPU0_P1P0_DP<8>")
	)
	(segment
		(start 126.482856 -213.150958)
		(end 126.58217 -213.051644)
		(width 0.0889)
		(layer "In4.Cu")
		(net "UPI_CPU1_CPU0_P1P0_DP<8>")
	)
	(segment
		(start 126.363476 -217.335354)
		(end 126.441708 -217.356182)
		(width 0.0889)
		(layer "In4.Cu")
		(net "UPI_CPU1_CPU0_P1P0_DP<8>")
	)
	(segment
		(start 273.21129 -182.164482)
		(end 302.503332 -181.454552)
		(width 0.14732)
		(layer "In4.Cu")
		(net "UPI_CPU1_CPU0_P1P0_DP<8>")
	)
	(segment
		(start 126.39421 -215.761062)
		(end 126.4031 -215.755982)
		(width 0.0889)
		(layer "In4.Cu")
		(net "UPI_CPU1_CPU0_P1P0_DP<8>")
	)
	(segment
		(start 345.108276 -214.424768)
		(end 345.108276 -214.644732)
		(width 0.0889)
		(layer "In4.Cu")
		(net "UPI_CPU1_CPU0_P1P0_DP<8>")
	)
	(segment
		(start 344.826336 -216.739978)
		(end 344.825574 -216.740486)
		(width 0.0889)
		(layer "In4.Cu")
		(net "UPI_CPU1_CPU0_P1P0_DP<8>")
	)
	(segment
		(start 302.503332 -181.454552)
		(end 312.32221 -181.636162)
		(width 0.14732)
		(layer "In4.Cu")
		(net "UPI_CPU1_CPU0_P1P0_DP<8>")
	)
	(segment
		(start 344.68054 -211.762848)
		(end 344.680794 -211.763102)
		(width 0.14732)
		(layer "In4.Cu")
		(net "UPI_CPU1_CPU0_P1P0_DP<8>")
	)
	(segment
		(start 344.856816 -218.421204)
		(end 345.01328 -218.692222)
		(width 0.0889)
		(layer "In4.Cu")
		(net "UPI_CPU1_CPU0_P1P0_DP<8>")
	)
	(segment
		(start 345.108784 -216.25052)
		(end 345.108784 -216.260426)
		(width 0.0889)
		(layer "In4.Cu")
		(net "UPI_CPU1_CPU0_P1P0_DP<8>")
	)
	(segment
		(start 328.90968 -188.868558)
		(end 329.595988 -189.183264)
		(width 0.14732)
		(layer "In4.Cu")
		(net "UPI_CPU1_CPU0_P1P0_DP<8>")
	)
	(segment
		(start 344.825574 -216.740486)
		(end 344.820494 -216.74328)
		(width 0.0889)
		(layer "In4.Cu")
		(net "UPI_CPU1_CPU0_P1P0_DP<8>")
	)
	(segment
		(start 126.863856 -214.946992)
		(end 126.872746 -214.941912)
		(width 0.0889)
		(layer "In4.Cu")
		(net "UPI_CPU1_CPU0_P1P0_DP<8>")
	)
	(segment
		(start 344.824558 -215.7603)
		(end 344.826082 -215.761062)
		(width 0.0889)
		(layer "In4.Cu")
		(net "UPI_CPU1_CPU0_P1P0_DP<8>")
	)
	(segment
		(start 126.207012 -217.064336)
		(end 126.363476 -217.335354)
		(width 0.0889)
		(layer "In4.Cu")
		(net "UPI_CPU1_CPU0_P1P0_DP<8>")
	)
	(segment
		(start 345.6559 -209.606642)
		(end 344.68054 -210.582002)
		(width 0.14732)
		(layer "In4.Cu")
		(net "UPI_CPU1_CPU0_P1P0_DP<8>")
	)
	(segment
		(start 126.482856 -212.41893)
		(end 126.58217 -212.319616)
		(width 0.0889)
		(layer "In4.Cu")
		(net "UPI_CPU1_CPU0_P1P0_DP<8>")
	)
	(segment
		(start 126.581662 -215.436704)
		(end 126.581662 -215.414606)
		(width 0.0889)
		(layer "In4.Cu")
		(net "UPI_CPU1_CPU0_P1P0_DP<8>")
	)
	(segment
		(start 344.820494 -216.74328)
		(end 344.817446 -216.745058)
		(width 0.0889)
		(layer "In4.Cu")
		(net "UPI_CPU1_CPU0_P1P0_DP<8>")
	)
	(segment
		(start 337.34756 -194.280028)
		(end 344.092022 -201.024744)
		(width 0.14732)
		(layer "In4.Cu")
		(net "UPI_CPU1_CPU0_P1P0_DP<8>")
	)
	(segment
		(start 312.32221 -181.636162)
		(end 314.78347 -182.414164)
		(width 0.14732)
		(layer "In4.Cu")
		(net "UPI_CPU1_CPU0_P1P0_DP<8>")
	)
	(segment
		(start 128.931924 -204.891894)
		(end 134.727696 -197.763384)
		(width 0.14732)
		(layer "In4.Cu")
		(net "UPI_CPU1_CPU0_P1P0_DP<8>")
	)
	(segment
		(start 159.104838 -182.503318)
		(end 200.58761 -181.81447)
		(width 0.14732)
		(layer "In4.Cu")
		(net "UPI_CPU1_CPU0_P1P0_DP<8>")
	)
	(segment
		(start 344.880946 -218.33205)
		(end 344.856816 -218.421204)
		(width 0.0889)
		(layer "In4.Cu")
		(net "UPI_CPU1_CPU0_P1P0_DP<8>")
	)
	(segment
		(start 126.482856 -212.68563)
		(end 126.482856 -212.41893)
		(width 0.0889)
		(layer "In4.Cu")
		(net "UPI_CPU1_CPU0_P1P0_DP<8>")
	)
	(segment
		(start 134.727696 -197.763384)
		(end 140.632434 -193.838322)
		(width 0.14732)
		(layer "In4.Cu")
		(net "UPI_CPU1_CPU0_P1P0_DP<8>")
	)
	(segment
		(start 344.826082 -215.761062)
		(end 344.828876 -215.762586)
		(width 0.0889)
		(layer "In4.Cu")
		(net "UPI_CPU1_CPU0_P1P0_DP<8>")
	)
	(segment
		(start 344.680794 -211.996528)
		(end 344.63863 -212.038692)
		(width 0.0889)
		(layer "In4.Cu")
		(net "UPI_CPU1_CPU0_P1P0_DP<8>")
	)
	(segment
		(start 345.108784 -217.859864)
		(end 345.108784 -217.878406)
		(width 0.0889)
		(layer "In4.Cu")
		(net "UPI_CPU1_CPU0_P1P0_DP<8>")
	)
	(segment
		(start 334.25765 -191.849248)
		(end 337.34756 -194.280028)
		(width 0.14732)
		(layer "In4.Cu")
		(net "UPI_CPU1_CPU0_P1P0_DP<8>")
	)
	(segment
		(start 323.748654 -186.333638)
		(end 328.90968 -188.868558)
		(width 0.14732)
		(layer "In4.Cu")
		(net "UPI_CPU1_CPU0_P1P0_DP<8>")
	)
	(segment
		(start 126.482856 -213.417658)
		(end 126.482856 -213.150958)
		(width 0.0889)
		(layer "In4.Cu")
		(net "UPI_CPU1_CPU0_P1P0_DP<8>")
	)
	(segment
		(start 152.376378 -184.225692)
		(end 159.104838 -182.503318)
		(width 0.14732)
		(layer "In4.Cu")
		(net "UPI_CPU1_CPU0_P1P0_DP<8>")
	)
	(segment
		(start 126.54026 -211.83219)
		(end 126.54026 -211.723986)
		(width 0.14732)
		(layer "In4.Cu")
		(net "UPI_CPU1_CPU0_P1P0_DP<8>")
	)
	(segment
		(start 345.6559 -204.800708)
		(end 345.6559 -209.606642)
		(width 0.14732)
		(layer "In4.Cu")
		(net "UPI_CPU1_CPU0_P1P0_DP<8>")
	)
	(segment
		(start 344.817192 -215.755982)
		(end 344.824558 -215.7603)
		(width 0.0889)
		(layer "In4.Cu")
		(net "UPI_CPU1_CPU0_P1P0_DP<8>")
	)
	(segment
		(start 329.595988 -189.183264)
		(end 334.25765 -191.849248)
		(width 0.14732)
		(layer "In4.Cu")
		(net "UPI_CPU1_CPU0_P1P0_DP<8>")
	)
	(segment
		(start 344.63863 -213.8934)
		(end 344.638884 -213.893908)
		(width 0.0889)
		(layer "In4.Cu")
		(net "UPI_CPU1_CPU0_P1P0_DP<8>")
	)
	(segment
		(start 238.629444 -182.329328)
		(end 273.21129 -182.164482)
		(width 0.14732)
		(layer "In4.Cu")
		(net "UPI_CPU1_CPU0_P1P0_DP<8>")
	)
	(segment
		(start 344.63863 -212.038692)
		(end 344.63863 -213.8934)
		(width 0.0889)
		(layer "In4.Cu")
		(net "UPI_CPU1_CPU0_P1P0_DP<8>")
	)
	(segment
		(start 140.632434 -193.838322)
		(end 144.96796 -188.018674)
		(width 0.14732)
		(layer "In4.Cu")
		(net "UPI_CPU1_CPU0_P1P0_DP<8>")
	)
	(segment
		(start 144.96796 -188.018674)
		(end 152.376378 -184.225692)
		(width 0.14732)
		(layer "In4.Cu")
		(net "UPI_CPU1_CPU0_P1P0_DP<8>")
	)
	(segment
		(start 344.828876 -215.762586)
		(end 344.832178 -215.764618)
		(width 0.0889)
		(layer "In4.Cu")
		(net "UPI_CPU1_CPU0_P1P0_DP<8>")
	)
	(segment
		(start 212.298534 -182.329328)
		(end 238.629444 -182.329328)
		(width 0.14732)
		(layer "In4.Cu")
		(net "UPI_CPU1_CPU0_P1P0_DP<8>")
	)
	(segment
		(start 126.58217 -212.319616)
		(end 126.58217 -211.896198)
		(width 0.0889)
		(layer "In4.Cu")
		(net "UPI_CPU1_CPU0_P1P0_DP<8>")
	)
	(segment
		(start 314.78347 -182.414164)
		(end 322.70192 -185.762138)
		(width 0.14732)
		(layer "In4.Cu")
		(net "UPI_CPU1_CPU0_P1P0_DP<8>")
	)
	(segment
		(start 344.680794 -211.763102)
		(end 344.680794 -211.97443)
		(width 0.14732)
		(layer "In4.Cu")
		(net "UPI_CPU1_CPU0_P1P0_DP<8>")
	)
	(segment
		(start 126.58217 -213.974934)
		(end 126.58217 -213.516972)
		(width 0.0889)
		(layer "In4.Cu")
		(net "UPI_CPU1_CPU0_P1P0_DP<8>")
	)
	(segment
		(start 200.58761 -181.81447)
		(end 212.298534 -182.329328)
		(width 0.14732)
		(layer "In4.Cu")
		(net "UPI_CPU1_CPU0_P1P0_DP<8>")
	)
	(segment
		(start 344.680794 -211.97443)
		(end 344.680794 -211.996528)
		(width 0.0889)
		(layer "In4.Cu")
		(net "UPI_CPU1_CPU0_P1P0_DP<8>")
	)
	(segment
		(start 126.395226 -216.740486)
		(end 126.39421 -216.739978)
		(width 0.0889)
		(layer "In4.Cu")
		(net "UPI_CPU1_CPU0_P1P0_DP<8>")
	)
	(segment
		(start 344.817446 -217.383614)
		(end 344.826336 -217.388694)
		(width 0.0889)
		(layer "In4.Cu")
		(net "UPI_CPU1_CPU0_P1P0_DP<8>")
	)
	(segment
		(start 126.54026 -211.854288)
		(end 126.54026 -211.83219)
		(width 0.0889)
		(layer "In4.Cu")
		(net "UPI_CPU1_CPU0_P1P0_DP<8>")
	)
	(segment
		(start 322.70192 -185.762138)
		(end 323.748654 -186.333638)
		(width 0.14732)
		(layer "In4.Cu")
		(net "UPI_CPU1_CPU0_P1P0_DP<8>")
	)
	(segment
		(start 126.54026 -211.723986)
		(end 128.931924 -204.891894)
		(width 0.14732)
		(layer "In4.Cu")
		(net "UPI_CPU1_CPU0_P1P0_DP<8>")
	)
	(segment
		(start 344.092022 -201.024744)
		(end 345.6559 -204.800708)
		(width 0.14732)
		(layer "In4.Cu")
		(net "UPI_CPU1_CPU0_P1P0_DP<8>")
	)
	(segment
		(start 344.826082 -215.112346)
		(end 344.825066 -215.112854)
		(width 0.0889)
		(layer "In4.Cu")
		(net "UPI_CPU1_CPU0_P1P0_DP<8>")
	)
	(segment
		(start 126.79045 -214.183468)
		(end 126.58217 -213.974934)
		(width 0.0889)
		(layer "In4.Cu")
		(net "UPI_CPU1_CPU0_P1P0_DP<8>")
	)
	(segment
		(start 127.051308 -214.622634)
		(end 127.045466 -214.447882)
		(width 0.0889)
		(layer "In4.Cu")
		(net "UPI_CPU1_CPU0_P1P0_DP<8>")
	)
	(segment
		(start 344.825066 -215.112854)
		(end 344.817192 -215.117426)
		(width 0.0889)
		(layer "In4.Cu")
		(net "UPI_CPU1_CPU0_P1P0_DP<8>")
	)
	(segment
		(start 126.4031 -216.745058)
		(end 126.395226 -216.740486)
		(width 0.0889)
		(layer "In4.Cu")
		(net "UPI_CPU1_CPU0_P1P0_DP<8>")
	)
	(segment
		(start 126.112016 -216.266014)
		(end 126.112016 -216.235026)
		(width 0.0889)
		(layer "In4.Cu")
		(net "UPI_CPU1_CPU0_P1P0_DP<8>")
	)
	(segment
		(start 126.58217 -211.896198)
		(end 126.54026 -211.854288)
		(width 0.0889)
		(layer "In4.Cu")
		(net "UPI_CPU1_CPU0_P1P0_DP<8>")
	)
	(arc
		(start 126.581662 -215.414606)
		(mid 126.662573 -215.144478)
		(end 126.863856 -214.946992)
		(width 0.0889)
		(layer "In4.Cu")
		(net "UPI_CPU1_CPU0_P1P0_DP<8>")
	)
	(arc
		(start 127.045466 -214.447882)
		(mid 126.987316 -214.35248)
		(end 126.90475 -214.277194)
		(width 0.0889)
		(layer "In4.Cu")
		(net "UPI_CPU1_CPU0_P1P0_DP<8>")
	)
	(arc
		(start 345.108784 -216.260426)
		(mid 345.030673 -216.537375)
		(end 344.826336 -216.739978)
		(width 0.0889)
		(layer "In4.Cu")
		(net "UPI_CPU1_CPU0_P1P0_DP<8>")
	)
	(arc
		(start 126.872746 -214.941912)
		(mid 127 -214.811946)
		(end 127.051054 -214.637366)
		(width 0.0889)
		(layer "In4.Cu")
		(net "UPI_CPU1_CPU0_P1P0_DP<8>")
	)
	(arc
		(start 127.051054 -214.637366)
		(mid 127.051251 -214.630001)
		(end 127.051308 -214.622634)
		(width 0.0889)
		(layer "In4.Cu")
		(net "UPI_CPU1_CPU0_P1P0_DP<8>")
	)
	(arc
		(start 344.832178 -215.764618)
		(mid 345.034765 -215.970969)
		(end 345.108784 -216.25052)
		(width 0.0889)
		(layer "In4.Cu")
		(net "UPI_CPU1_CPU0_P1P0_DP<8>")
	)
	(arc
		(start 344.817192 -215.117426)
		(mid 344.689938 -215.247392)
		(end 344.638884 -215.421972)
		(width 0.0889)
		(layer "In4.Cu")
		(net "UPI_CPU1_CPU0_P1P0_DP<8>")
	)
	(arc
		(start 344.897964 -218.318842)
		(mid 344.889518 -218.325527)
		(end 344.880946 -218.33205)
		(width 0.0889)
		(layer "In4.Cu")
		(net "UPI_CPU1_CPU0_P1P0_DP<8>")
	)
	(arc
		(start 126.112016 -216.235026)
		(mid 126.191386 -215.961292)
		(end 126.39421 -215.761062)
		(width 0.0889)
		(layer "In4.Cu")
		(net "UPI_CPU1_CPU0_P1P0_DP<8>")
	)
	(arc
		(start 344.63863 -215.436704)
		(mid 344.686309 -215.619604)
		(end 344.817192 -215.755982)
		(width 0.0889)
		(layer "In4.Cu")
		(net "UPI_CPU1_CPU0_P1P0_DP<8>")
	)
	(arc
		(start 344.823034 -214.093298)
		(mid 344.996997 -214.232062)
		(end 345.108276 -214.424768)
		(width 0.0889)
		(layer "In4.Cu")
		(net "UPI_CPU1_CPU0_P1P0_DP<8>")
	)
	(arc
		(start 344.826336 -217.388694)
		(mid 345.028622 -217.587675)
		(end 345.108784 -217.859864)
		(width 0.0889)
		(layer "In4.Cu")
		(net "UPI_CPU1_CPU0_P1P0_DP<8>")
	)
	(arc
		(start 344.638884 -215.421972)
		(mid 344.638687 -215.429337)
		(end 344.63863 -215.436704)
		(width 0.0889)
		(layer "In4.Cu")
		(net "UPI_CPU1_CPU0_P1P0_DP<8>")
	)
	(arc
		(start 344.638884 -213.893908)
		(mid 344.713889 -214.009367)
		(end 344.823034 -214.093298)
		(width 0.0889)
		(layer "In4.Cu")
		(net "UPI_CPU1_CPU0_P1P0_DP<8>")
	)
	(arc
		(start 126.581662 -217.064336)
		(mid 126.533983 -216.881436)
		(end 126.4031 -216.745058)
		(width 0.0889)
		(layer "In4.Cu")
		(net "UPI_CPU1_CPU0_P1P0_DP<8>")
	)
	(arc
		(start 345.108276 -214.644732)
		(mid 345.027365 -214.91486)
		(end 344.826082 -215.112346)
		(width 0.0889)
		(layer "In4.Cu")
		(net "UPI_CPU1_CPU0_P1P0_DP<8>")
	)
	(arc
		(start 345.108784 -217.878406)
		(mid 345.053429 -218.122593)
		(end 344.897964 -218.318842)
		(width 0.0889)
		(layer "In4.Cu")
		(net "UPI_CPU1_CPU0_P1P0_DP<8>")
	)
	(arc
		(start 126.441708 -217.356182)
		(mid 126.544853 -217.226157)
		(end 126.581662 -217.064336)
		(width 0.0889)
		(layer "In4.Cu")
		(net "UPI_CPU1_CPU0_P1P0_DP<8>")
	)
	(arc
		(start 126.4031 -215.755982)
		(mid 126.534014 -215.619622)
		(end 126.581662 -215.436704)
		(width 0.0889)
		(layer "In4.Cu")
		(net "UPI_CPU1_CPU0_P1P0_DP<8>")
	)
	(arc
		(start 126.90475 -214.277194)
		(mid 126.845357 -214.233067)
		(end 126.79045 -214.183468)
		(width 0.0889)
		(layer "In4.Cu")
		(net "UPI_CPU1_CPU0_P1P0_DP<8>")
	)
	(arc
		(start 126.39421 -216.739978)
		(mid 126.191387 -216.539747)
		(end 126.112016 -216.266014)
		(width 0.0889)
		(layer "In4.Cu")
		(net "UPI_CPU1_CPU0_P1P0_DP<8>")
	)
	(arc
		(start 344.817446 -216.745058)
		(mid 344.638849 -217.064336)
		(end 344.817446 -217.383614)
		(width 0.0889)
		(layer "In4.Cu")
		(net "UPI_CPU1_CPU0_P1P0_DP<8>")
	)
	(segment
		(start 343.60358 -218.414346)
		(end 343.60358 -217.87866)
		(width 0.13208)
		(layer "F.Cu")
		(net "UPI_CPU1_CPU0_P1P0_DP<7>")
	)
	(segment
		(start 127.616712 -217.87866)
		(end 127.616966 -217.878406)
		(width 0.13208)
		(layer "F.Cu")
		(net "UPI_CPU1_CPU0_P1P0_DP<7>")
	)
	(segment
		(start 127.616712 -218.414346)
		(end 127.616712 -217.87866)
		(width 0.13208)
		(layer "F.Cu")
		(net "UPI_CPU1_CPU0_P1P0_DP<7>")
	)
	(segment
		(start 343.60358 -217.87866)
		(end 343.603834 -217.878406)
		(width 0.13208)
		(layer "F.Cu")
		(net "UPI_CPU1_CPU0_P1P0_DP<7>")
	)
	(segment
		(start 127.711962 -213.2584)
		(end 127.711962 -213.786974)
		(width 0.0889)
		(layer "In4.Cu")
		(net "UPI_CPU1_CPU0_P1P0_DP<7>")
	)
	(segment
		(start 251.666756 -183.405272)
		(end 251.665232 -183.405272)
		(width 0.14732)
		(layer "In4.Cu")
		(net "UPI_CPU1_CPU0_P1P0_DP<7>")
	)
	(segment
		(start 343.508838 -213.929468)
		(end 343.508838 -212.038438)
		(width 0.0889)
		(layer "In4.Cu")
		(net "UPI_CPU1_CPU0_P1P0_DP<7>")
	)
	(segment
		(start 134.12216 -200.464674)
		(end 134.12216 -200.465182)
		(width 0.14732)
		(layer "In4.Cu")
		(net "UPI_CPU1_CPU0_P1P0_DP<7>")
	)
	(segment
		(start 140.029692 -195.761102)
		(end 139.828778 -195.720716)
		(width 0.14732)
		(layer "In4.Cu")
		(net "UPI_CPU1_CPU0_P1P0_DP<7>")
	)
	(segment
		(start 323.324474 -187.375292)
		(end 322.12534 -186.726068)
		(width 0.14732)
		(layer "In4.Cu")
		(net "UPI_CPU1_CPU0_P1P0_DP<7>")
	)
	(segment
		(start 136.663176 -197.999604)
		(end 136.35609 -198.203566)
		(width 0.14732)
		(layer "In4.Cu")
		(net "UPI_CPU1_CPU0_P1P0_DP<7>")
	)
	(segment
		(start 238.632492 -183.467502)
		(end 212.45576 -183.467502)
		(width 0.14732)
		(layer "In4.Cu")
		(net "UPI_CPU1_CPU0_P1P0_DP<7>")
	)
	(segment
		(start 343.760298 -217.607388)
		(end 343.736168 -217.518234)
		(width 0.0889)
		(layer "In4.Cu")
		(net "UPI_CPU1_CPU0_P1P0_DP<7>")
	)
	(segment
		(start 343.466674 -210.23326)
		(end 344.55354 -209.146394)
		(width 0.14732)
		(layer "In4.Cu")
		(net "UPI_CPU1_CPU0_P1P0_DP<7>")
	)
	(segment
		(start 134.53745 -199.954134)
		(end 134.558532 -200.157842)
		(width 0.14732)
		(layer "In4.Cu")
		(net "UPI_CPU1_CPU0_P1P0_DP<7>")
	)
	(segment
		(start 147.313396 -188.059314)
		(end 146.985736 -188.226954)
		(width 0.14732)
		(layer "In4.Cu")
		(net "UPI_CPU1_CPU0_P1P0_DP<7>")
	)
	(segment
		(start 127.420878 -216.569798)
		(end 127.429768 -216.574878)
		(width 0.0889)
		(layer "In4.Cu")
		(net "UPI_CPU1_CPU0_P1P0_DP<7>")
	)
	(segment
		(start 343.133426 -201.638154)
		(end 336.934048 -195.438776)
		(width 0.14732)
		(layer "In4.Cu")
		(net "UPI_CPU1_CPU0_P1P0_DP<7>")
	)
	(segment
		(start 133.030976 -202.036426)
		(end 132.827268 -202.057508)
		(width 0.14732)
		(layer "In4.Cu")
		(net "UPI_CPU1_CPU0_P1P0_DP<7>")
	)
	(segment
		(start 336.934048 -195.438776)
		(end 333.444088 -192.693036)
		(width 0.14732)
		(layer "In4.Cu")
		(net "UPI_CPU1_CPU0_P1P0_DP<7>")
	)
	(segment
		(start 133.474714 -201.260964)
		(end 133.474714 -201.261472)
		(width 0.14732)
		(layer "In4.Cu")
		(net "UPI_CPU1_CPU0_P1P0_DP<7>")
	)
	(segment
		(start 141.425168 -194.659504)
		(end 140.377164 -195.35648)
		(width 0.14732)
		(layer "In4.Cu")
		(net "UPI_CPU1_CPU0_P1P0_DP<7>")
	)
	(segment
		(start 127.711962 -212.88502)
		(end 127.811022 -212.98408)
		(width 0.0889)
		(layer "In4.Cu")
		(net "UPI_CPU1_CPU0_P1P0_DP<7>")
	)
	(segment
		(start 327.346818 -190.52667)
		(end 326.89419 -190.248032)
		(width 0.14732)
		(layer "In4.Cu")
		(net "UPI_CPU1_CPU0_P1P0_DP<7>")
	)
	(segment
		(start 146.59483 -188.58992)
		(end 146.400012 -188.526928)
		(width 0.14732)
		(layer "In4.Cu")
		(net "UPI_CPU1_CPU0_P1P0_DP<7>")
	)
	(segment
		(start 343.791032 -216.574878)
		(end 343.792556 -216.574116)
		(width 0.0889)
		(layer "In4.Cu")
		(net "UPI_CPU1_CPU0_P1P0_DP<7>")
	)
	(segment
		(start 344.55354 -205.066646)
		(end 343.133426 -201.638154)
		(width 0.14732)
		(layer "In4.Cu")
		(net "UPI_CPU1_CPU0_P1P0_DP<7>")
	)
	(segment
		(start 127.899414 -215.112346)
		(end 127.898398 -215.112854)
		(width 0.0889)
		(layer "In4.Cu")
		(net "UPI_CPU1_CPU0_P1P0_DP<7>")
	)
	(segment
		(start 127.460502 -218.149424)
		(end 127.616966 -217.878406)
		(width 0.0889)
		(layer "In4.Cu")
		(net "UPI_CPU1_CPU0_P1P0_DP<7>")
	)
	(segment
		(start 343.466928 -211.805774)
		(end 343.466674 -211.80552)
		(width 0.14732)
		(layer "In4.Cu")
		(net "UPI_CPU1_CPU0_P1P0_DP<7>")
	)
	(segment
		(start 343.50833 -215.436704)
		(end 343.50833 -215.414606)
		(width 0.0889)
		(layer "In4.Cu")
		(net "UPI_CPU1_CPU0_P1P0_DP<7>")
	)
	(segment
		(start 127.711962 -212.33638)
		(end 127.811022 -212.43544)
		(width 0.0889)
		(layer "In4.Cu")
		(net "UPI_CPU1_CPU0_P1P0_DP<7>")
	)
	(segment
		(start 133.474714 -201.261472)
		(end 133.243066 -201.546968)
		(width 0.14732)
		(layer "In4.Cu")
		(net "UPI_CPU1_CPU0_P1P0_DP<7>")
	)
	(segment
		(start 251.665232 -183.405272)
		(end 238.632492 -183.467502)
		(width 0.14732)
		(layer "In4.Cu")
		(net "UPI_CPU1_CPU0_P1P0_DP<7>")
	)
	(segment
		(start 127.38227 -218.170252)
		(end 127.460502 -218.149424)
		(width 0.0889)
		(layer "In4.Cu")
		(net "UPI_CPU1_CPU0_P1P0_DP<7>")
	)
	(segment
		(start 302.524414 -182.59298)
		(end 273.228054 -183.302656)
		(width 0.14732)
		(layer "In4.Cu")
		(net "UPI_CPU1_CPU0_P1P0_DP<7>")
	)
	(segment
		(start 127.712216 -217.05443)
		(end 127.712216 -217.082878)
		(width 0.0889)
		(layer "In4.Cu")
		(net "UPI_CPU1_CPU0_P1P0_DP<7>")
	)
	(segment
		(start 134.325868 -200.443846)
		(end 134.12216 -200.464674)
		(width 0.14732)
		(layer "In4.Cu")
		(net "UPI_CPU1_CPU0_P1P0_DP<7>")
	)
	(segment
		(start 136.15543 -198.16318)
		(end 135.80364 -198.39686)
		(width 0.14732)
		(layer "In4.Cu")
		(net "UPI_CPU1_CPU0_P1P0_DP<7>")
	)
	(segment
		(start 132.827268 -202.057508)
		(end 129.795524 -205.786482)
		(width 0.14732)
		(layer "In4.Cu")
		(net "UPI_CPU1_CPU0_P1P0_DP<7>")
	)
	(segment
		(start 133.890512 -200.750678)
		(end 133.890004 -200.750424)
		(width 0.14732)
		(layer "In4.Cu")
		(net "UPI_CPU1_CPU0_P1P0_DP<7>")
	)
	(segment
		(start 127.898398 -215.112854)
		(end 127.890524 -215.117426)
		(width 0.0889)
		(layer "In4.Cu")
		(net "UPI_CPU1_CPU0_P1P0_DP<7>")
	)
	(segment
		(start 133.26364 -201.750422)
		(end 133.030976 -202.036426)
		(width 0.14732)
		(layer "In4.Cu")
		(net "UPI_CPU1_CPU0_P1P0_DP<7>")
	)
	(segment
		(start 159.397192 -183.607964)
		(end 152.61971 -185.343546)
		(width 0.14732)
		(layer "In4.Cu")
		(net "UPI_CPU1_CPU0_P1P0_DP<7>")
	)
	(segment
		(start 133.678422 -201.240136)
		(end 133.474714 -201.260964)
		(width 0.14732)
		(layer "In4.Cu")
		(net "UPI_CPU1_CPU0_P1P0_DP<7>")
	)
	(segment
		(start 343.792556 -215.926924)
		(end 343.791032 -215.926162)
		(width 0.0889)
		(layer "In4.Cu")
		(net "UPI_CPU1_CPU0_P1P0_DP<7>")
	)
	(segment
		(start 128.181354 -214.501222)
		(end 128.181608 -214.644732)
		(width 0.0889)
		(layer "In4.Cu")
		(net "UPI_CPU1_CPU0_P1P0_DP<7>")
	)
	(segment
		(start 127.429768 -215.926162)
		(end 127.420878 -215.931242)
		(width 0.0889)
		(layer "In4.Cu")
		(net "UPI_CPU1_CPU0_P1P0_DP<7>")
	)
	(segment
		(start 343.977976 -214.622634)
		(end 343.977976 -214.461344)
		(width 0.0889)
		(layer "In4.Cu")
		(net "UPI_CPU1_CPU0_P1P0_DP<7>")
	)
	(segment
		(start 127.754126 -211.82711)
		(end 127.754126 -211.849208)
		(width 0.0889)
		(layer "In4.Cu")
		(net "UPI_CPU1_CPU0_P1P0_DP<7>")
	)
	(segment
		(start 146.400012 -188.526928)
		(end 145.743676 -188.862716)
		(width 0.14732)
		(layer "In4.Cu")
		(net "UPI_CPU1_CPU0_P1P0_DP<7>")
	)
	(segment
		(start 127.711962 -212.70976)
		(end 127.711962 -212.88502)
		(width 0.0889)
		(layer "In4.Cu")
		(net "UPI_CPU1_CPU0_P1P0_DP<7>")
	)
	(segment
		(start 343.508584 -213.929722)
		(end 343.508838 -213.929468)
		(width 0.0889)
		(layer "In4.Cu")
		(net "UPI_CPU1_CPU0_P1P0_DP<7>")
	)
	(segment
		(start 127.811022 -212.98408)
		(end 127.811022 -213.15934)
		(width 0.0889)
		(layer "In4.Cu")
		(net "UPI_CPU1_CPU0_P1P0_DP<7>")
	)
	(segment
		(start 140.377164 -195.35648)
		(end 140.37691 -195.356226)
		(width 0.14732)
		(layer "In4.Cu")
		(net "UPI_CPU1_CPU0_P1P0_DP<7>")
	)
	(segment
		(start 135.80364 -198.39686)
		(end 134.53745 -199.954134)
		(width 0.14732)
		(layer "In4.Cu")
		(net "UPI_CPU1_CPU0_P1P0_DP<7>")
	)
	(segment
		(start 343.508584 -213.930484)
		(end 343.508584 -213.929722)
		(width 0.0889)
		(layer "In4.Cu")
		(net "UPI_CPU1_CPU0_P1P0_DP<7>")
	)
	(segment
		(start 147.508214 -188.122306)
		(end 147.313396 -188.059314)
		(width 0.14732)
		(layer "In4.Cu")
		(net "UPI_CPU1_CPU0_P1P0_DP<7>")
	)
	(segment
		(start 343.466928 -211.97443)
		(end 343.466928 -211.805774)
		(width 0.14732)
		(layer "In4.Cu")
		(net "UPI_CPU1_CPU0_P1P0_DP<7>")
	)
	(segment
		(start 140.336524 -195.557394)
		(end 140.029692 -195.761102)
		(width 0.14732)
		(layer "In4.Cu")
		(net "UPI_CPU1_CPU0_P1P0_DP<7>")
	)
	(segment
		(start 129.795524 -205.786482)
		(end 127.754126 -211.616798)
		(width 0.14732)
		(layer "In4.Cu")
		(net "UPI_CPU1_CPU0_P1P0_DP<7>")
	)
	(segment
		(start 139.828778 -195.720716)
		(end 138.262106 -196.76237)
		(width 0.14732)
		(layer "In4.Cu")
		(net "UPI_CPU1_CPU0_P1P0_DP<7>")
	)
	(segment
		(start 147.899374 -187.75934)
		(end 147.836382 -187.954412)
		(width 0.14732)
		(layer "In4.Cu")
		(net "UPI_CPU1_CPU0_P1P0_DP<7>")
	)
	(segment
		(start 343.466674 -211.80552)
		(end 343.466674 -210.23326)
		(width 0.14732)
		(layer "In4.Cu")
		(net "UPI_CPU1_CPU0_P1P0_DP<7>")
	)
	(segment
		(start 312.15457 -182.770272)
		(end 302.524414 -182.59298)
		(width 0.14732)
		(layer "In4.Cu")
		(net "UPI_CPU1_CPU0_P1P0_DP<7>")
	)
	(segment
		(start 146.922998 -188.422026)
		(end 146.59483 -188.58992)
		(width 0.14732)
		(layer "In4.Cu")
		(net "UPI_CPU1_CPU0_P1P0_DP<7>")
	)
	(segment
		(start 133.242558 -201.546714)
		(end 133.26364 -201.750422)
		(width 0.14732)
		(layer "In4.Cu")
		(net "UPI_CPU1_CPU0_P1P0_DP<7>")
	)
	(segment
		(start 152.61971 -185.343546)
		(end 147.899374 -187.75934)
		(width 0.14732)
		(layer "In4.Cu")
		(net "UPI_CPU1_CPU0_P1P0_DP<7>")
	)
	(segment
		(start 273.228054 -183.302656)
		(end 251.666756 -183.405272)
		(width 0.14732)
		(layer "In4.Cu")
		(net "UPI_CPU1_CPU0_P1P0_DP<7>")
	)
	(segment
		(start 343.79027 -215.925654)
		(end 343.784936 -215.922606)
		(width 0.0889)
		(layer "In4.Cu")
		(net "UPI_CPU1_CPU0_P1P0_DP<7>")
	)
	(segment
		(start 127.711962 -215.436704)
		(end 127.711962 -215.452198)
		(width 0.0889)
		(layer "In4.Cu")
		(net "UPI_CPU1_CPU0_P1P0_DP<7>")
	)
	(segment
		(start 343.788238 -216.576402)
		(end 343.791032 -216.574878)
		(width 0.0889)
		(layer "In4.Cu")
		(net "UPI_CPU1_CPU0_P1P0_DP<7>")
	)
	(segment
		(start 127.754126 -211.849208)
		(end 127.711962 -211.891372)
		(width 0.0889)
		(layer "In4.Cu")
		(net "UPI_CPU1_CPU0_P1P0_DP<7>")
	)
	(segment
		(start 146.985736 -188.226954)
		(end 146.922998 -188.422026)
		(width 0.14732)
		(layer "In4.Cu")
		(net "UPI_CPU1_CPU0_P1P0_DP<7>")
	)
	(segment
		(start 136.35609 -198.203566)
		(end 136.15543 -198.16318)
		(width 0.14732)
		(layer "In4.Cu")
		(net "UPI_CPU1_CPU0_P1P0_DP<7>")
	)
	(segment
		(start 127.754126 -211.616798)
		(end 127.754126 -211.82711)
		(width 0.14732)
		(layer "In4.Cu")
		(net "UPI_CPU1_CPU0_P1P0_DP<7>")
	)
	(segment
		(start 343.792556 -216.574116)
		(end 343.799922 -216.569798)
		(width 0.0889)
		(layer "In4.Cu")
		(net "UPI_CPU1_CPU0_P1P0_DP<7>")
	)
	(segment
		(start 343.50833 -217.07856)
		(end 343.50833 -217.064336)
		(width 0.0889)
		(layer "In4.Cu")
		(net "UPI_CPU1_CPU0_P1P0_DP<7>")
	)
	(segment
		(start 343.799922 -215.931242)
		(end 343.792556 -215.926924)
		(width 0.0889)
		(layer "In4.Cu")
		(net "UPI_CPU1_CPU0_P1P0_DP<7>")
	)
	(segment
		(start 145.743676 -188.862716)
		(end 141.425168 -194.659504)
		(width 0.14732)
		(layer "In4.Cu")
		(net "UPI_CPU1_CPU0_P1P0_DP<7>")
	)
	(segment
		(start 127.429768 -217.554048)
		(end 127.420878 -217.559128)
		(width 0.0889)
		(layer "In4.Cu")
		(net "UPI_CPU1_CPU0_P1P0_DP<7>")
	)
	(segment
		(start 343.791032 -215.926162)
		(end 343.79027 -215.925654)
		(width 0.0889)
		(layer "In4.Cu")
		(net "UPI_CPU1_CPU0_P1P0_DP<7>")
	)
	(segment
		(start 147.836382 -187.954412)
		(end 147.508214 -188.122306)
		(width 0.14732)
		(layer "In4.Cu")
		(net "UPI_CPU1_CPU0_P1P0_DP<7>")
	)
	(segment
		(start 134.12216 -200.465182)
		(end 133.890512 -200.750678)
		(width 0.14732)
		(layer "In4.Cu")
		(net "UPI_CPU1_CPU0_P1P0_DP<7>")
	)
	(segment
		(start 127.711962 -211.891372)
		(end 127.711962 -212.33638)
		(width 0.0889)
		(layer "In4.Cu")
		(net "UPI_CPU1_CPU0_P1P0_DP<7>")
	)
	(segment
		(start 343.466928 -211.996528)
		(end 343.466928 -211.97443)
		(width 0.0889)
		(layer "In4.Cu")
		(net "UPI_CPU1_CPU0_P1P0_DP<7>")
	)
	(segment
		(start 343.790524 -214.946992)
		(end 343.799414 -214.941912)
		(width 0.0889)
		(layer "In4.Cu")
		(net "UPI_CPU1_CPU0_P1P0_DP<7>")
	)
	(segment
		(start 127.811022 -213.15934)
		(end 127.711962 -213.2584)
		(width 0.0889)
		(layer "In4.Cu")
		(net "UPI_CPU1_CPU0_P1P0_DP<7>")
	)
	(segment
		(start 140.37691 -195.356226)
		(end 140.336524 -195.557394)
		(width 0.14732)
		(layer "In4.Cu")
		(net "UPI_CPU1_CPU0_P1P0_DP<7>")
	)
	(segment
		(start 137.914888 -197.167246)
		(end 137.714228 -197.12686)
		(width 0.14732)
		(layer "In4.Cu")
		(net "UPI_CPU1_CPU0_P1P0_DP<7>")
	)
	(segment
		(start 200.230486 -182.930292)
		(end 159.397192 -183.607964)
		(width 0.14732)
		(layer "In4.Cu")
		(net "UPI_CPU1_CPU0_P1P0_DP<7>")
	)
	(segment
		(start 127.811022 -212.43544)
		(end 127.811022 -212.6107)
		(width 0.0889)
		(layer "In4.Cu")
		(net "UPI_CPU1_CPU0_P1P0_DP<7>")
	)
	(segment
		(start 133.243066 -201.546968)
		(end 133.242558 -201.546714)
		(width 0.14732)
		(layer "In4.Cu")
		(net "UPI_CPU1_CPU0_P1P0_DP<7>")
	)
	(segment
		(start 137.714228 -197.12686)
		(end 136.703562 -197.79869)
		(width 0.14732)
		(layer "In4.Cu")
		(net "UPI_CPU1_CPU0_P1P0_DP<7>")
	)
	(segment
		(start 343.508838 -212.038438)
		(end 343.466928 -211.996528)
		(width 0.0889)
		(layer "In4.Cu")
		(net "UPI_CPU1_CPU0_P1P0_DP<7>")
	)
	(segment
		(start 138.262106 -196.76237)
		(end 138.22172 -196.963284)
		(width 0.14732)
		(layer "In4.Cu")
		(net "UPI_CPU1_CPU0_P1P0_DP<7>")
	)
	(segment
		(start 333.444088 -192.693036)
		(end 327.346818 -190.52667)
		(width 0.14732)
		(layer "In4.Cu")
		(net "UPI_CPU1_CPU0_P1P0_DP<7>")
	)
	(segment
		(start 322.12534 -186.726068)
		(end 314.310014 -183.446674)
		(width 0.14732)
		(layer "In4.Cu")
		(net "UPI_CPU1_CPU0_P1P0_DP<7>")
	)
	(segment
		(start 127.811022 -212.6107)
		(end 127.711962 -212.70976)
		(width 0.0889)
		(layer "In4.Cu")
		(net "UPI_CPU1_CPU0_P1P0_DP<7>")
	)
	(segment
		(start 314.310014 -183.446674)
		(end 312.15457 -182.770272)
		(width 0.14732)
		(layer "In4.Cu")
		(net "UPI_CPU1_CPU0_P1P0_DP<7>")
	)
	(segment
		(start 136.703562 -197.79869)
		(end 136.663176 -197.999604)
		(width 0.14732)
		(layer "In4.Cu")
		(net "UPI_CPU1_CPU0_P1P0_DP<7>")
	)
	(segment
		(start 138.22172 -196.963284)
		(end 137.914888 -197.167246)
		(width 0.14732)
		(layer "In4.Cu")
		(net "UPI_CPU1_CPU0_P1P0_DP<7>")
	)
	(segment
		(start 133.911086 -200.954132)
		(end 133.678422 -201.240136)
		(width 0.14732)
		(layer "In4.Cu")
		(net "UPI_CPU1_CPU0_P1P0_DP<7>")
	)
	(segment
		(start 344.55354 -209.146394)
		(end 344.55354 -205.066646)
		(width 0.14732)
		(layer "In4.Cu")
		(net "UPI_CPU1_CPU0_P1P0_DP<7>")
	)
	(segment
		(start 212.45576 -183.467502)
		(end 200.230486 -182.930292)
		(width 0.14732)
		(layer "In4.Cu")
		(net "UPI_CPU1_CPU0_P1P0_DP<7>")
	)
	(segment
		(start 343.784936 -216.578434)
		(end 343.788238 -216.576402)
		(width 0.0889)
		(layer "In4.Cu")
		(net "UPI_CPU1_CPU0_P1P0_DP<7>")
	)
	(segment
		(start 343.603834 -217.878406)
		(end 343.760298 -217.607388)
		(width 0.0889)
		(layer "In4.Cu")
		(net "UPI_CPU1_CPU0_P1P0_DP<7>")
	)
	(segment
		(start 326.89419 -190.248032)
		(end 323.324474 -187.375292)
		(width 0.14732)
		(layer "In4.Cu")
		(net "UPI_CPU1_CPU0_P1P0_DP<7>")
	)
	(segment
		(start 133.890004 -200.750424)
		(end 133.911086 -200.954132)
		(width 0.14732)
		(layer "In4.Cu")
		(net "UPI_CPU1_CPU0_P1P0_DP<7>")
	)
	(segment
		(start 134.558532 -200.157842)
		(end 134.325868 -200.443846)
		(width 0.14732)
		(layer "In4.Cu")
		(net "UPI_CPU1_CPU0_P1P0_DP<7>")
	)
	(arc
		(start 343.50833 -217.064336)
		(mid 343.582321 -216.78477)
		(end 343.784936 -216.578434)
		(width 0.0889)
		(layer "In4.Cu")
		(net "UPI_CPU1_CPU0_P1P0_DP<7>")
	)
	(arc
		(start 343.736168 -217.518234)
		(mid 343.727597 -217.511838)
		(end 343.71915 -217.50528)
		(width 0.0889)
		(layer "In4.Cu")
		(net "UPI_CPU1_CPU0_P1P0_DP<7>")
	)
	(arc
		(start 127.712216 -215.421972)
		(mid 127.712019 -215.429337)
		(end 127.711962 -215.436704)
		(width 0.0889)
		(layer "In4.Cu")
		(net "UPI_CPU1_CPU0_P1P0_DP<7>")
	)
	(arc
		(start 127.429768 -216.574878)
		(mid 127.634103 -216.777483)
		(end 127.712216 -217.05443)
		(width 0.0889)
		(layer "In4.Cu")
		(net "UPI_CPU1_CPU0_P1P0_DP<7>")
	)
	(arc
		(start 343.977976 -214.461344)
		(mid 343.902971 -214.345885)
		(end 343.793826 -214.261954)
		(width 0.0889)
		(layer "In4.Cu")
		(net "UPI_CPU1_CPU0_P1P0_DP<7>")
	)
	(arc
		(start 127.242316 -216.257124)
		(mid 127.291569 -216.436324)
		(end 127.420878 -216.569798)
		(width 0.0889)
		(layer "In4.Cu")
		(net "UPI_CPU1_CPU0_P1P0_DP<7>")
	)
	(arc
		(start 343.793826 -214.261954)
		(mid 343.633754 -214.138774)
		(end 343.523824 -213.969346)
		(width 0.0889)
		(layer "In4.Cu")
		(net "UPI_CPU1_CPU0_P1P0_DP<7>")
	)
	(arc
		(start 128.181608 -214.644732)
		(mid 128.100697 -214.91486)
		(end 127.899414 -215.112346)
		(width 0.0889)
		(layer "In4.Cu")
		(net "UPI_CPU1_CPU0_P1P0_DP<7>")
	)
	(arc
		(start 343.523824 -213.969346)
		(mid 343.515861 -213.950049)
		(end 343.508584 -213.930484)
		(width 0.0889)
		(layer "In4.Cu")
		(net "UPI_CPU1_CPU0_P1P0_DP<7>")
	)
	(arc
		(start 343.71915 -217.50528)
		(mid 343.566663 -217.315184)
		(end 343.50833 -217.07856)
		(width 0.0889)
		(layer "In4.Cu")
		(net "UPI_CPU1_CPU0_P1P0_DP<7>")
	)
	(arc
		(start 127.711962 -215.452198)
		(mid 127.632592 -215.725932)
		(end 127.429768 -215.926162)
		(width 0.0889)
		(layer "In4.Cu")
		(net "UPI_CPU1_CPU0_P1P0_DP<7>")
	)
	(arc
		(start 128.132332 -214.319104)
		(mid 128.169013 -214.40689)
		(end 128.181354 -214.501222)
		(width 0.0889)
		(layer "In4.Cu")
		(net "UPI_CPU1_CPU0_P1P0_DP<7>")
	)
	(arc
		(start 127.420878 -217.559128)
		(mid 127.289964 -217.695488)
		(end 127.242316 -217.878406)
		(width 0.0889)
		(layer "In4.Cu")
		(net "UPI_CPU1_CPU0_P1P0_DP<7>")
	)
	(arc
		(start 127.711962 -213.786974)
		(mid 127.76156 -213.965783)
		(end 127.896366 -214.093298)
		(width 0.0889)
		(layer "In4.Cu")
		(net "UPI_CPU1_CPU0_P1P0_DP<7>")
	)
	(arc
		(start 343.799922 -216.569798)
		(mid 343.978519 -216.25052)
		(end 343.799922 -215.931242)
		(width 0.0889)
		(layer "In4.Cu")
		(net "UPI_CPU1_CPU0_P1P0_DP<7>")
	)
	(arc
		(start 127.420878 -215.931242)
		(mid 127.292474 -216.063187)
		(end 127.242316 -216.24036)
		(width 0.0889)
		(layer "In4.Cu")
		(net "UPI_CPU1_CPU0_P1P0_DP<7>")
	)
	(arc
		(start 343.784936 -215.922606)
		(mid 343.582349 -215.716255)
		(end 343.50833 -215.436704)
		(width 0.0889)
		(layer "In4.Cu")
		(net "UPI_CPU1_CPU0_P1P0_DP<7>")
	)
	(arc
		(start 343.50833 -215.414606)
		(mid 343.589241 -215.144478)
		(end 343.790524 -214.946992)
		(width 0.0889)
		(layer "In4.Cu")
		(net "UPI_CPU1_CPU0_P1P0_DP<7>")
	)
	(arc
		(start 127.712216 -217.082878)
		(mid 127.632054 -217.355067)
		(end 127.429768 -217.554048)
		(width 0.0889)
		(layer "In4.Cu")
		(net "UPI_CPU1_CPU0_P1P0_DP<7>")
	)
	(arc
		(start 127.896366 -214.093298)
		(mid 128.030063 -214.189784)
		(end 128.132332 -214.319104)
		(width 0.0889)
		(layer "In4.Cu")
		(net "UPI_CPU1_CPU0_P1P0_DP<7>")
	)
	(arc
		(start 127.242316 -216.24036)
		(mid 127.242222 -216.248742)
		(end 127.242316 -216.257124)
		(width 0.0889)
		(layer "In4.Cu")
		(net "UPI_CPU1_CPU0_P1P0_DP<7>")
	)
	(arc
		(start 127.890524 -215.117426)
		(mid 127.76327 -215.247392)
		(end 127.712216 -215.421972)
		(width 0.0889)
		(layer "In4.Cu")
		(net "UPI_CPU1_CPU0_P1P0_DP<7>")
	)
	(arc
		(start 127.242316 -217.878406)
		(mid 127.279176 -218.040203)
		(end 127.38227 -218.170252)
		(width 0.0889)
		(layer "In4.Cu")
		(net "UPI_CPU1_CPU0_P1P0_DP<7>")
	)
	(arc
		(start 343.799414 -214.941912)
		(mid 343.930328 -214.805552)
		(end 343.977976 -214.622634)
		(width 0.0889)
		(layer "In4.Cu")
		(net "UPI_CPU1_CPU0_P1P0_DP<7>")
	)
	(segment
		(start 128.086866 -217.06459)
		(end 128.086612 -217.064336)
		(width 0.13208)
		(layer "F.Cu")
		(net "UPI_CPU1_CPU0_P1P0_DP<6>")
	)
	(segment
		(start 343.133934 -218.692476)
		(end 343.13368 -218.692222)
		(width 0.13208)
		(layer "F.Cu")
		(net "UPI_CPU1_CPU0_P1P0_DP<6>")
	)
	(segment
		(start 343.133934 -219.228162)
		(end 343.133934 -218.692476)
		(width 0.13208)
		(layer "F.Cu")
		(net "UPI_CPU1_CPU0_P1P0_DP<6>")
	)
	(segment
		(start 128.086866 -217.600276)
		(end 128.086866 -217.06459)
		(width 0.13208)
		(layer "F.Cu")
		(net "UPI_CPU1_CPU0_P1P0_DP<6>")
	)
	(segment
		(start 342.945466 -215.112854)
		(end 342.946482 -215.112346)
		(width 0.0889)
		(layer "In4.Cu")
		(net "UPI_CPU1_CPU0_P1P0_DP<6>")
	)
	(segment
		(start 342.75903 -212.038692)
		(end 342.801194 -211.996528)
		(width 0.0889)
		(layer "In4.Cu")
		(net "UPI_CPU1_CPU0_P1P0_DP<6>")
	)
	(segment
		(start 342.75903 -213.8934)
		(end 342.75903 -212.038692)
		(width 0.0889)
		(layer "In4.Cu")
		(net "UPI_CPU1_CPU0_P1P0_DP<6>")
	)
	(segment
		(start 128.41986 -211.82711)
		(end 128.41986 -211.849208)
		(width 0.0889)
		(layer "In4.Cu")
		(net "UPI_CPU1_CPU0_P1P0_DP<6>")
	)
	(segment
		(start 342.801194 -211.97443)
		(end 342.801194 -211.628482)
		(width 0.14732)
		(layer "In4.Cu")
		(net "UPI_CPU1_CPU0_P1P0_DP<6>")
	)
	(segment
		(start 128.930908 -214.500968)
		(end 128.930908 -214.622634)
		(width 0.0889)
		(layer "In4.Cu")
		(net "UPI_CPU1_CPU0_P1P0_DP<6>")
	)
	(segment
		(start 128.46177 -212.784944)
		(end 128.46177 -213.051644)
		(width 0.0889)
		(layer "In4.Cu")
		(net "UPI_CPU1_CPU0_P1P0_DP<6>")
	)
	(segment
		(start 343.9922 -208.915)
		(end 343.9922 -205.19898)
		(width 0.14732)
		(layer "In4.Cu")
		(net "UPI_CPU1_CPU0_P1P0_DP<6>")
	)
	(segment
		(start 152.850342 -185.857896)
		(end 148.995384 -187.831476)
		(width 0.14732)
		(layer "In4.Cu")
		(net "UPI_CPU1_CPU0_P1P0_DP<6>")
	)
	(segment
		(start 128.243076 -217.335354)
		(end 128.086612 -217.064336)
		(width 0.0889)
		(layer "In4.Cu")
		(net "UPI_CPU1_CPU0_P1P0_DP<6>")
	)
	(segment
		(start 342.759284 -213.893908)
		(end 342.75903 -213.8934)
		(width 0.0889)
		(layer "In4.Cu")
		(net "UPI_CPU1_CPU0_P1P0_DP<6>")
	)
	(segment
		(start 250.505468 -184.039256)
		(end 238.634016 -184.095898)
		(width 0.14732)
		(layer "In4.Cu")
		(net "UPI_CPU1_CPU0_P1P0_DP<6>")
	)
	(segment
		(start 342.949276 -215.762586)
		(end 342.946482 -215.761062)
		(width 0.0889)
		(layer "In4.Cu")
		(net "UPI_CPU1_CPU0_P1P0_DP<6>")
	)
	(segment
		(start 128.752346 -214.941912)
		(end 128.743456 -214.946992)
		(width 0.0889)
		(layer "In4.Cu")
		(net "UPI_CPU1_CPU0_P1P0_DP<6>")
	)
	(segment
		(start 128.274826 -216.740486)
		(end 128.2827 -216.745058)
		(width 0.0889)
		(layer "In4.Cu")
		(net "UPI_CPU1_CPU0_P1P0_DP<6>")
	)
	(segment
		(start 342.946736 -217.388694)
		(end 342.937846 -217.383614)
		(width 0.0889)
		(layer "In4.Cu")
		(net "UPI_CPU1_CPU0_P1P0_DP<6>")
	)
	(segment
		(start 342.946482 -215.761062)
		(end 342.944958 -215.7603)
		(width 0.0889)
		(layer "In4.Cu")
		(net "UPI_CPU1_CPU0_P1P0_DP<6>")
	)
	(segment
		(start 159.463994 -184.164986)
		(end 152.850342 -185.857896)
		(width 0.14732)
		(layer "In4.Cu")
		(net "UPI_CPU1_CPU0_P1P0_DP<6>")
	)
	(segment
		(start 312.36793 -183.438546)
		(end 301.69231 -183.24195)
		(width 0.14732)
		(layer "In4.Cu")
		(net "UPI_CPU1_CPU0_P1P0_DP<6>")
	)
	(segment
		(start 343.229184 -217.878406)
		(end 343.229184 -217.859864)
		(width 0.0889)
		(layer "In4.Cu")
		(net "UPI_CPU1_CPU0_P1P0_DP<6>")
	)
	(segment
		(start 128.419606 -211.602828)
		(end 128.41986 -211.603082)
		(width 0.14732)
		(layer "In4.Cu")
		(net "UPI_CPU1_CPU0_P1P0_DP<6>")
	)
	(segment
		(start 127.991616 -216.235026)
		(end 127.991616 -216.266014)
		(width 0.0889)
		(layer "In4.Cu")
		(net "UPI_CPU1_CPU0_P1P0_DP<6>")
	)
	(segment
		(start 343.9922 -205.19898)
		(end 342.646 -201.948796)
		(width 0.14732)
		(layer "In4.Cu")
		(net "UPI_CPU1_CPU0_P1P0_DP<6>")
	)
	(segment
		(start 128.362456 -212.68563)
		(end 128.46177 -212.784944)
		(width 0.0889)
		(layer "In4.Cu")
		(net "UPI_CPU1_CPU0_P1P0_DP<6>")
	)
	(segment
		(start 343.13368 -218.692222)
		(end 342.977216 -218.421204)
		(width 0.0889)
		(layer "In4.Cu")
		(net "UPI_CPU1_CPU0_P1P0_DP<6>")
	)
	(segment
		(start 342.952578 -215.764618)
		(end 342.949276 -215.762586)
		(width 0.0889)
		(layer "In4.Cu")
		(net "UPI_CPU1_CPU0_P1P0_DP<6>")
	)
	(segment
		(start 322.938648 -187.828428)
		(end 321.81038 -187.227718)
		(width 0.14732)
		(layer "In4.Cu")
		(net "UPI_CPU1_CPU0_P1P0_DP<6>")
	)
	(segment
		(start 128.41986 -211.603082)
		(end 128.41986 -211.82711)
		(width 0.14732)
		(layer "In4.Cu")
		(net "UPI_CPU1_CPU0_P1P0_DP<6>")
	)
	(segment
		(start 132.91947 -202.850242)
		(end 130.271774 -206.106268)
		(width 0.14732)
		(layer "In4.Cu")
		(net "UPI_CPU1_CPU0_P1P0_DP<6>")
	)
	(segment
		(start 327.10374 -191.030098)
		(end 326.445626 -190.624714)
		(width 0.14732)
		(layer "In4.Cu")
		(net "UPI_CPU1_CPU0_P1P0_DP<6>")
	)
	(segment
		(start 342.937846 -216.745058)
		(end 342.940894 -216.74328)
		(width 0.0889)
		(layer "In4.Cu")
		(net "UPI_CPU1_CPU0_P1P0_DP<6>")
	)
	(segment
		(start 128.41986 -211.849208)
		(end 128.46177 -211.891118)
		(width 0.0889)
		(layer "In4.Cu")
		(net "UPI_CPU1_CPU0_P1P0_DP<6>")
	)
	(segment
		(start 333.1591 -193.192908)
		(end 327.10374 -191.030098)
		(width 0.14732)
		(layer "In4.Cu")
		(net "UPI_CPU1_CPU0_P1P0_DP<6>")
	)
	(segment
		(start 342.80094 -210.10626)
		(end 343.9922 -208.915)
		(width 0.14732)
		(layer "In4.Cu")
		(net "UPI_CPU1_CPU0_P1P0_DP<6>")
	)
	(segment
		(start 128.419606 -211.39531)
		(end 128.419606 -211.602828)
		(width 0.14732)
		(layer "In4.Cu")
		(net "UPI_CPU1_CPU0_P1P0_DP<6>")
	)
	(segment
		(start 142.05077 -196.6722)
		(end 141.71422 -196.991478)
		(width 0.14732)
		(layer "In4.Cu")
		(net "UPI_CPU1_CPU0_P1P0_DP<6>")
	)
	(segment
		(start 128.362456 -213.417658)
		(end 128.46177 -213.516972)
		(width 0.0889)
		(layer "In4.Cu")
		(net "UPI_CPU1_CPU0_P1P0_DP<6>")
	)
	(segment
		(start 273.237452 -183.931052)
		(end 250.520708 -184.039256)
		(width 0.14732)
		(layer "In4.Cu")
		(net "UPI_CPU1_CPU0_P1P0_DP<6>")
	)
	(segment
		(start 342.801194 -211.628482)
		(end 342.80094 -211.628228)
		(width 0.14732)
		(layer "In4.Cu")
		(net "UPI_CPU1_CPU0_P1P0_DP<6>")
	)
	(segment
		(start 128.27381 -216.739978)
		(end 128.274826 -216.740486)
		(width 0.0889)
		(layer "In4.Cu")
		(net "UPI_CPU1_CPU0_P1P0_DP<6>")
	)
	(segment
		(start 128.46177 -212.319616)
		(end 128.362456 -212.41893)
		(width 0.0889)
		(layer "In4.Cu")
		(net "UPI_CPU1_CPU0_P1P0_DP<6>")
	)
	(segment
		(start 314.143644 -183.995568)
		(end 314.14339 -183.995568)
		(width 0.14732)
		(layer "In4.Cu")
		(net "UPI_CPU1_CPU0_P1P0_DP<6>")
	)
	(segment
		(start 321.81038 -187.227718)
		(end 319.827148 -186.391804)
		(width 0.14732)
		(layer "In4.Cu")
		(net "UPI_CPU1_CPU0_P1P0_DP<6>")
	)
	(segment
		(start 148.995384 -187.831476)
		(end 147.776438 -188.987176)
		(width 0.14732)
		(layer "In4.Cu")
		(net "UPI_CPU1_CPU0_P1P0_DP<6>")
	)
	(segment
		(start 141.71422 -196.991478)
		(end 132.91947 -202.850242)
		(width 0.14732)
		(layer "In4.Cu")
		(net "UPI_CPU1_CPU0_P1P0_DP<6>")
	)
	(segment
		(start 336.584798 -195.88734)
		(end 333.1591 -193.192908)
		(width 0.14732)
		(layer "In4.Cu")
		(net "UPI_CPU1_CPU0_P1P0_DP<6>")
	)
	(segment
		(start 342.945974 -216.740486)
		(end 342.946736 -216.739978)
		(width 0.0889)
		(layer "In4.Cu")
		(net "UPI_CPU1_CPU0_P1P0_DP<6>")
	)
	(segment
		(start 342.646 -201.948796)
		(end 336.584798 -195.88734)
		(width 0.14732)
		(layer "In4.Cu")
		(net "UPI_CPU1_CPU0_P1P0_DP<6>")
	)
	(segment
		(start 326.445626 -190.624714)
		(end 322.938648 -187.828428)
		(width 0.14732)
		(layer "In4.Cu")
		(net "UPI_CPU1_CPU0_P1P0_DP<6>")
	)
	(segment
		(start 238.634016 -184.095898)
		(end 213.961218 -184.095898)
		(width 0.14732)
		(layer "In4.Cu")
		(net "UPI_CPU1_CPU0_P1P0_DP<6>")
	)
	(segment
		(start 128.2827 -215.755982)
		(end 128.27381 -215.761062)
		(width 0.0889)
		(layer "In4.Cu")
		(net "UPI_CPU1_CPU0_P1P0_DP<6>")
	)
	(segment
		(start 128.46177 -213.516972)
		(end 128.46177 -213.787228)
		(width 0.0889)
		(layer "In4.Cu")
		(net "UPI_CPU1_CPU0_P1P0_DP<6>")
	)
	(segment
		(start 128.321308 -217.356182)
		(end 128.243076 -217.335354)
		(width 0.0889)
		(layer "In4.Cu")
		(net "UPI_CPU1_CPU0_P1P0_DP<6>")
	)
	(segment
		(start 342.940894 -216.74328)
		(end 342.945974 -216.740486)
		(width 0.0889)
		(layer "In4.Cu")
		(net "UPI_CPU1_CPU0_P1P0_DP<6>")
	)
	(segment
		(start 342.944958 -215.7603)
		(end 342.937592 -215.755982)
		(width 0.0889)
		(layer "In4.Cu")
		(net "UPI_CPU1_CPU0_P1P0_DP<6>")
	)
	(segment
		(start 342.80094 -211.628228)
		(end 342.80094 -210.10626)
		(width 0.14732)
		(layer "In4.Cu")
		(net "UPI_CPU1_CPU0_P1P0_DP<6>")
	)
	(segment
		(start 342.977216 -218.421204)
		(end 343.001346 -218.33205)
		(width 0.0889)
		(layer "In4.Cu")
		(net "UPI_CPU1_CPU0_P1P0_DP<6>")
	)
	(segment
		(start 319.827148 -186.391804)
		(end 314.143644 -183.995568)
		(width 0.14732)
		(layer "In4.Cu")
		(net "UPI_CPU1_CPU0_P1P0_DP<6>")
	)
	(segment
		(start 314.14339 -183.995568)
		(end 312.36793 -183.438546)
		(width 0.14732)
		(layer "In4.Cu")
		(net "UPI_CPU1_CPU0_P1P0_DP<6>")
	)
	(segment
		(start 128.46177 -211.891118)
		(end 128.46177 -212.319616)
		(width 0.0889)
		(layer "In4.Cu")
		(net "UPI_CPU1_CPU0_P1P0_DP<6>")
	)
	(segment
		(start 343.228676 -214.644732)
		(end 343.228676 -214.424768)
		(width 0.0889)
		(layer "In4.Cu")
		(net "UPI_CPU1_CPU0_P1P0_DP<6>")
	)
	(segment
		(start 128.362456 -212.41893)
		(end 128.362456 -212.68563)
		(width 0.0889)
		(layer "In4.Cu")
		(net "UPI_CPU1_CPU0_P1P0_DP<6>")
	)
	(segment
		(start 200.156318 -183.489092)
		(end 159.463994 -184.164986)
		(width 0.14732)
		(layer "In4.Cu")
		(net "UPI_CPU1_CPU0_P1P0_DP<6>")
	)
	(segment
		(start 342.937592 -215.117426)
		(end 342.945466 -215.112854)
		(width 0.0889)
		(layer "In4.Cu")
		(net "UPI_CPU1_CPU0_P1P0_DP<6>")
	)
	(segment
		(start 301.69231 -183.24195)
		(end 273.237452 -183.931052)
		(width 0.14732)
		(layer "In4.Cu")
		(net "UPI_CPU1_CPU0_P1P0_DP<6>")
	)
	(segment
		(start 147.776438 -188.987176)
		(end 142.05077 -196.6722)
		(width 0.14732)
		(layer "In4.Cu")
		(net "UPI_CPU1_CPU0_P1P0_DP<6>")
	)
	(segment
		(start 343.229184 -216.260426)
		(end 343.229184 -216.25052)
		(width 0.0889)
		(layer "In4.Cu")
		(net "UPI_CPU1_CPU0_P1P0_DP<6>")
	)
	(segment
		(start 128.46177 -213.051644)
		(end 128.362456 -213.150958)
		(width 0.0889)
		(layer "In4.Cu")
		(net "UPI_CPU1_CPU0_P1P0_DP<6>")
	)
	(segment
		(start 130.271774 -206.106268)
		(end 128.419606 -211.39531)
		(width 0.14732)
		(layer "In4.Cu")
		(net "UPI_CPU1_CPU0_P1P0_DP<6>")
	)
	(segment
		(start 250.520708 -184.039256)
		(end 250.505468 -184.039256)
		(width 0.14732)
		(layer "In4.Cu")
		(net "UPI_CPU1_CPU0_P1P0_DP<6>")
	)
	(segment
		(start 342.801194 -211.996528)
		(end 342.801194 -211.97443)
		(width 0.0889)
		(layer "In4.Cu")
		(net "UPI_CPU1_CPU0_P1P0_DP<6>")
	)
	(segment
		(start 128.461262 -215.414606)
		(end 128.461262 -215.436704)
		(width 0.0889)
		(layer "In4.Cu")
		(net "UPI_CPU1_CPU0_P1P0_DP<6>")
	)
	(segment
		(start 128.362456 -213.150958)
		(end 128.362456 -213.417658)
		(width 0.0889)
		(layer "In4.Cu")
		(net "UPI_CPU1_CPU0_P1P0_DP<6>")
	)
	(segment
		(start 213.961218 -184.095898)
		(end 200.156318 -183.489092)
		(width 0.14732)
		(layer "In4.Cu")
		(net "UPI_CPU1_CPU0_P1P0_DP<6>")
	)
	(arc
		(start 127.991616 -216.266014)
		(mid 128.070986 -216.539748)
		(end 128.27381 -216.739978)
		(width 0.0889)
		(layer "In4.Cu")
		(net "UPI_CPU1_CPU0_P1P0_DP<6>")
	)
	(arc
		(start 343.018364 -218.318842)
		(mid 343.173762 -218.122561)
		(end 343.229184 -217.878406)
		(width 0.0889)
		(layer "In4.Cu")
		(net "UPI_CPU1_CPU0_P1P0_DP<6>")
	)
	(arc
		(start 343.001346 -218.33205)
		(mid 343.009918 -218.325528)
		(end 343.018364 -218.318842)
		(width 0.0889)
		(layer "In4.Cu")
		(net "UPI_CPU1_CPU0_P1P0_DP<6>")
	)
	(arc
		(start 342.937592 -215.755982)
		(mid 342.806678 -215.619622)
		(end 342.75903 -215.436704)
		(width 0.0889)
		(layer "In4.Cu")
		(net "UPI_CPU1_CPU0_P1P0_DP<6>")
	)
	(arc
		(start 342.759284 -215.421972)
		(mid 342.810338 -215.247392)
		(end 342.937592 -215.117426)
		(width 0.0889)
		(layer "In4.Cu")
		(net "UPI_CPU1_CPU0_P1P0_DP<6>")
	)
	(arc
		(start 342.937846 -217.383614)
		(mid 342.759249 -217.064336)
		(end 342.937846 -216.745058)
		(width 0.0889)
		(layer "In4.Cu")
		(net "UPI_CPU1_CPU0_P1P0_DP<6>")
	)
	(arc
		(start 342.946482 -215.112346)
		(mid 343.147764 -214.914859)
		(end 343.228676 -214.644732)
		(width 0.0889)
		(layer "In4.Cu")
		(net "UPI_CPU1_CPU0_P1P0_DP<6>")
	)
	(arc
		(start 128.743456 -214.946992)
		(mid 128.542174 -215.144479)
		(end 128.461262 -215.414606)
		(width 0.0889)
		(layer "In4.Cu")
		(net "UPI_CPU1_CPU0_P1P0_DP<6>")
	)
	(arc
		(start 128.747012 -214.261446)
		(mid 128.838055 -214.327132)
		(end 128.907794 -214.415116)
		(width 0.0889)
		(layer "In4.Cu")
		(net "UPI_CPU1_CPU0_P1P0_DP<6>")
	)
	(arc
		(start 128.27381 -215.761062)
		(mid 128.070987 -215.961293)
		(end 127.991616 -216.235026)
		(width 0.0889)
		(layer "In4.Cu")
		(net "UPI_CPU1_CPU0_P1P0_DP<6>")
	)
	(arc
		(start 128.2827 -216.745058)
		(mid 128.413614 -216.881418)
		(end 128.461262 -217.064336)
		(width 0.0889)
		(layer "In4.Cu")
		(net "UPI_CPU1_CPU0_P1P0_DP<6>")
	)
	(arc
		(start 342.75903 -215.436704)
		(mid 342.759082 -215.429337)
		(end 342.759284 -215.421972)
		(width 0.0889)
		(layer "In4.Cu")
		(net "UPI_CPU1_CPU0_P1P0_DP<6>")
	)
	(arc
		(start 128.46177 -213.787228)
		(mid 128.538457 -214.063994)
		(end 128.747012 -214.261446)
		(width 0.0889)
		(layer "In4.Cu")
		(net "UPI_CPU1_CPU0_P1P0_DP<6>")
	)
	(arc
		(start 128.461262 -215.436704)
		(mid 128.413583 -215.619604)
		(end 128.2827 -215.755982)
		(width 0.0889)
		(layer "In4.Cu")
		(net "UPI_CPU1_CPU0_P1P0_DP<6>")
	)
	(arc
		(start 343.229184 -216.25052)
		(mid 343.155193 -215.970954)
		(end 342.952578 -215.764618)
		(width 0.0889)
		(layer "In4.Cu")
		(net "UPI_CPU1_CPU0_P1P0_DP<6>")
	)
	(arc
		(start 343.229184 -217.859864)
		(mid 343.149022 -217.587675)
		(end 342.946736 -217.388694)
		(width 0.0889)
		(layer "In4.Cu")
		(net "UPI_CPU1_CPU0_P1P0_DP<6>")
	)
	(arc
		(start 128.930908 -214.622634)
		(mid 128.930856 -214.630001)
		(end 128.930654 -214.637366)
		(width 0.0889)
		(layer "In4.Cu")
		(net "UPI_CPU1_CPU0_P1P0_DP<6>")
	)
	(arc
		(start 128.461262 -217.064336)
		(mid 128.424402 -217.226133)
		(end 128.321308 -217.356182)
		(width 0.0889)
		(layer "In4.Cu")
		(net "UPI_CPU1_CPU0_P1P0_DP<6>")
	)
	(arc
		(start 342.943434 -214.093298)
		(mid 342.834287 -214.00937)
		(end 342.759284 -213.893908)
		(width 0.0889)
		(layer "In4.Cu")
		(net "UPI_CPU1_CPU0_P1P0_DP<6>")
	)
	(arc
		(start 128.907794 -214.415116)
		(mid 128.925063 -214.456501)
		(end 128.930908 -214.500968)
		(width 0.0889)
		(layer "In4.Cu")
		(net "UPI_CPU1_CPU0_P1P0_DP<6>")
	)
	(arc
		(start 128.930654 -214.637366)
		(mid 128.8796 -214.811946)
		(end 128.752346 -214.941912)
		(width 0.0889)
		(layer "In4.Cu")
		(net "UPI_CPU1_CPU0_P1P0_DP<6>")
	)
	(arc
		(start 342.946736 -216.739978)
		(mid 343.151071 -216.537373)
		(end 343.229184 -216.260426)
		(width 0.0889)
		(layer "In4.Cu")
		(net "UPI_CPU1_CPU0_P1P0_DP<6>")
	)
	(arc
		(start 343.228676 -214.424768)
		(mid 343.117397 -214.232062)
		(end 342.943434 -214.093298)
		(width 0.0889)
		(layer "In4.Cu")
		(net "UPI_CPU1_CPU0_P1P0_DP<6>")
	)
	(segment
		(start 129.026666 -218.692476)
		(end 129.026412 -218.692222)
		(width 0.13208)
		(layer "F.Cu")
		(net "UPI_CPU1_CPU0_P1P0_DP<5>")
	)
	(segment
		(start 342.194134 -217.600276)
		(end 342.194134 -217.06459)
		(width 0.13208)
		(layer "F.Cu")
		(net "UPI_CPU1_CPU0_P1P0_DP<5>")
	)
	(segment
		(start 129.026666 -219.228162)
		(end 129.026666 -218.692476)
		(width 0.13208)
		(layer "F.Cu")
		(net "UPI_CPU1_CPU0_P1P0_DP<5>")
	)
	(segment
		(start 342.194134 -217.06459)
		(end 342.19388 -217.064336)
		(width 0.13208)
		(layer "F.Cu")
		(net "UPI_CPU1_CPU0_P1P0_DP<5>")
	)
	(segment
		(start 312.313066 -184.298336)
		(end 301.086266 -184.091834)
		(width 0.14732)
		(layer "In4.Cu")
		(net "UPI_CPU1_CPU0_P1P0_DP<5>")
	)
	(segment
		(start 129.182876 -218.421204)
		(end 129.026412 -218.692222)
		(width 0.0889)
		(layer "In4.Cu")
		(net "UPI_CPU1_CPU0_P1P0_DP<5>")
	)
	(segment
		(start 341.997792 -215.117426)
		(end 342.005666 -215.112854)
		(width 0.0889)
		(layer "In4.Cu")
		(net "UPI_CPU1_CPU0_P1P0_DP<5>")
	)
	(segment
		(start 273.249898 -184.765696)
		(end 250.22429 -184.875424)
		(width 0.14732)
		(layer "In4.Cu")
		(net "UPI_CPU1_CPU0_P1P0_DP<5>")
	)
	(segment
		(start 341.819484 -212.444838)
		(end 341.819484 -212.102192)
		(width 0.0889)
		(layer "In4.Cu")
		(net "UPI_CPU1_CPU0_P1P0_DP<5>")
	)
	(segment
		(start 341.861394 -211.676488)
		(end 341.861394 -209.841846)
		(width 0.14732)
		(layer "In4.Cu")
		(net "UPI_CPU1_CPU0_P1P0_DP<5>")
	)
	(segment
		(start 129.35966 -211.78647)
		(end 129.35966 -211.808568)
		(width 0.0889)
		(layer "In4.Cu")
		(net "UPI_CPU1_CPU0_P1P0_DP<5>")
	)
	(segment
		(start 148.41855 -189.52972)
		(end 142.676118 -197.238366)
		(width 0.14732)
		(layer "In4.Cu")
		(net "UPI_CPU1_CPU0_P1P0_DP<5>")
	)
	(segment
		(start 341.929466 -202.433682)
		(end 335.957164 -196.461126)
		(width 0.14732)
		(layer "In4.Cu")
		(net "UPI_CPU1_CPU0_P1P0_DP<5>")
	)
	(segment
		(start 129.158746 -218.33205)
		(end 129.182876 -218.421204)
		(width 0.0889)
		(layer "In4.Cu")
		(net "UPI_CPU1_CPU0_P1P0_DP<5>")
	)
	(segment
		(start 200.116694 -184.32145)
		(end 159.584898 -184.994296)
		(width 0.14732)
		(layer "In4.Cu")
		(net "UPI_CPU1_CPU0_P1P0_DP<5>")
	)
	(segment
		(start 142.676118 -197.238366)
		(end 142.676118 -197.23862)
		(width 0.14732)
		(layer "In4.Cu")
		(net "UPI_CPU1_CPU0_P1P0_DP<5>")
	)
	(segment
		(start 342.012778 -215.764618)
		(end 342.009476 -215.762586)
		(width 0.0889)
		(layer "In4.Cu")
		(net "UPI_CPU1_CPU0_P1P0_DP<5>")
	)
	(segment
		(start 129.2225 -215.755982)
		(end 129.21361 -215.761062)
		(width 0.0889)
		(layer "In4.Cu")
		(net "UPI_CPU1_CPU0_P1P0_DP<5>")
	)
	(segment
		(start 128.931416 -216.235026)
		(end 128.931416 -216.260426)
		(width 0.0889)
		(layer "In4.Cu")
		(net "UPI_CPU1_CPU0_P1P0_DP<5>")
	)
	(segment
		(start 129.870708 -214.500968)
		(end 129.870708 -214.622634)
		(width 0.0889)
		(layer "In4.Cu")
		(net "UPI_CPU1_CPU0_P1P0_DP<5>")
	)
	(segment
		(start 250.195334 -184.875424)
		(end 238.636302 -184.930542)
		(width 0.14732)
		(layer "In4.Cu")
		(net "UPI_CPU1_CPU0_P1P0_DP<5>")
	)
	(segment
		(start 341.918544 -212.543898)
		(end 341.819484 -212.444838)
		(width 0.0889)
		(layer "In4.Cu")
		(net "UPI_CPU1_CPU0_P1P0_DP<5>")
	)
	(segment
		(start 153.148284 -186.642502)
		(end 149.489922 -188.51499)
		(width 0.14732)
		(layer "In4.Cu")
		(net "UPI_CPU1_CPU0_P1P0_DP<5>")
	)
	(segment
		(start 142.484856 -197.495414)
		(end 141.33068 -198.262748)
		(width 0.14732)
		(layer "In4.Cu")
		(net "UPI_CPU1_CPU0_P1P0_DP<5>")
	)
	(segment
		(start 342.19388 -217.064336)
		(end 342.037416 -217.335354)
		(width 0.0889)
		(layer "In4.Cu")
		(net "UPI_CPU1_CPU0_P1P0_DP<5>")
	)
	(segment
		(start 341.819484 -213.893908)
		(end 341.819484 -213.366858)
		(width 0.0889)
		(layer "In4.Cu")
		(net "UPI_CPU1_CPU0_P1P0_DP<5>")
	)
	(segment
		(start 129.359406 -211.602828)
		(end 129.35966 -211.603082)
		(width 0.14732)
		(layer "In4.Cu")
		(net "UPI_CPU1_CPU0_P1P0_DP<5>")
	)
	(segment
		(start 129.401062 -215.414606)
		(end 129.401062 -215.436704)
		(width 0.0889)
		(layer "In4.Cu")
		(net "UPI_CPU1_CPU0_P1P0_DP<5>")
	)
	(segment
		(start 341.819484 -212.818218)
		(end 341.918544 -212.719158)
		(width 0.0889)
		(layer "In4.Cu")
		(net "UPI_CPU1_CPU0_P1P0_DP<5>")
	)
	(segment
		(start 142.59687 -197.345046)
		(end 142.484856 -197.495414)
		(width 0.14732)
		(layer "In4.Cu")
		(net "UPI_CPU1_CPU0_P1P0_DP<5>")
	)
	(segment
		(start 159.584898 -184.994296)
		(end 153.148284 -186.642502)
		(width 0.14732)
		(layer "In4.Cu")
		(net "UPI_CPU1_CPU0_P1P0_DP<5>")
	)
	(segment
		(start 141.330426 -198.262748)
		(end 133.480302 -203.481178)
		(width 0.14732)
		(layer "In4.Cu")
		(net "UPI_CPU1_CPU0_P1P0_DP<5>")
	)
	(segment
		(start 213.97468 -184.930542)
		(end 200.116694 -184.32145)
		(width 0.14732)
		(layer "In4.Cu")
		(net "UPI_CPU1_CPU0_P1P0_DP<5>")
	)
	(segment
		(start 341.861394 -209.841846)
		(end 343.12352 -208.57972)
		(width 0.14732)
		(layer "In4.Cu")
		(net "UPI_CPU1_CPU0_P1P0_DP<5>")
	)
	(segment
		(start 342.007444 -216.73947)
		(end 342.012778 -216.736422)
		(width 0.0889)
		(layer "In4.Cu")
		(net "UPI_CPU1_CPU0_P1P0_DP<5>")
	)
	(segment
		(start 343.12352 -205.316836)
		(end 341.929466 -202.433682)
		(width 0.14732)
		(layer "In4.Cu")
		(net "UPI_CPU1_CPU0_P1P0_DP<5>")
	)
	(segment
		(start 142.676118 -197.23862)
		(end 142.59687 -197.345046)
		(width 0.14732)
		(layer "In4.Cu")
		(net "UPI_CPU1_CPU0_P1P0_DP<5>")
	)
	(segment
		(start 250.22429 -184.875424)
		(end 250.195334 -184.875424)
		(width 0.14732)
		(layer "In4.Cu")
		(net "UPI_CPU1_CPU0_P1P0_DP<5>")
	)
	(segment
		(start 342.006682 -216.739978)
		(end 342.007444 -216.73947)
		(width 0.0889)
		(layer "In4.Cu")
		(net "UPI_CPU1_CPU0_P1P0_DP<5>")
	)
	(segment
		(start 341.918544 -212.719158)
		(end 341.918544 -212.543898)
		(width 0.0889)
		(layer "In4.Cu")
		(net "UPI_CPU1_CPU0_P1P0_DP<5>")
	)
	(segment
		(start 341.819484 -213.366858)
		(end 341.918544 -213.267798)
		(width 0.0889)
		(layer "In4.Cu")
		(net "UPI_CPU1_CPU0_P1P0_DP<5>")
	)
	(segment
		(start 301.086266 -184.091834)
		(end 273.249898 -184.765696)
		(width 0.14732)
		(layer "In4.Cu")
		(net "UPI_CPU1_CPU0_P1P0_DP<5>")
	)
	(segment
		(start 129.401062 -217.0557)
		(end 129.401062 -217.072972)
		(width 0.0889)
		(layer "In4.Cu")
		(net "UPI_CPU1_CPU0_P1P0_DP<5>")
	)
	(segment
		(start 326.197214 -191.624204)
		(end 322.552822 -189.680342)
		(width 0.14732)
		(layer "In4.Cu")
		(net "UPI_CPU1_CPU0_P1P0_DP<5>")
	)
	(segment
		(start 129.35966 -211.808568)
		(end 129.40157 -211.850478)
		(width 0.0889)
		(layer "In4.Cu")
		(net "UPI_CPU1_CPU0_P1P0_DP<5>")
	)
	(segment
		(start 133.480302 -203.481178)
		(end 131.00431 -206.526384)
		(width 0.14732)
		(layer "In4.Cu")
		(net "UPI_CPU1_CPU0_P1P0_DP<5>")
	)
	(segment
		(start 341.918544 -213.092538)
		(end 341.819484 -212.993478)
		(width 0.0889)
		(layer "In4.Cu")
		(net "UPI_CPU1_CPU0_P1P0_DP<5>")
	)
	(segment
		(start 342.009476 -215.762586)
		(end 342.006682 -215.761062)
		(width 0.0889)
		(layer "In4.Cu")
		(net "UPI_CPU1_CPU0_P1P0_DP<5>")
	)
	(segment
		(start 341.819484 -212.993478)
		(end 341.819484 -212.818218)
		(width 0.0889)
		(layer "In4.Cu")
		(net "UPI_CPU1_CPU0_P1P0_DP<5>")
	)
	(segment
		(start 342.037416 -217.335354)
		(end 341.959438 -217.356182)
		(width 0.0889)
		(layer "In4.Cu")
		(net "UPI_CPU1_CPU0_P1P0_DP<5>")
	)
	(segment
		(start 341.861648 -212.03793)
		(end 341.861648 -211.676742)
		(width 0.14732)
		(layer "In4.Cu")
		(net "UPI_CPU1_CPU0_P1P0_DP<5>")
	)
	(segment
		(start 141.33068 -198.262748)
		(end 141.330426 -198.262748)
		(width 0.14732)
		(layer "In4.Cu")
		(net "UPI_CPU1_CPU0_P1P0_DP<5>")
	)
	(segment
		(start 238.636302 -184.930542)
		(end 213.97468 -184.930542)
		(width 0.14732)
		(layer "In4.Cu")
		(net "UPI_CPU1_CPU0_P1P0_DP<5>")
	)
	(segment
		(start 322.552822 -189.680342)
		(end 313.826906 -184.772046)
		(width 0.14732)
		(layer "In4.Cu")
		(net "UPI_CPU1_CPU0_P1P0_DP<5>")
	)
	(segment
		(start 342.005158 -215.7603)
		(end 341.997792 -215.755982)
		(width 0.0889)
		(layer "In4.Cu")
		(net "UPI_CPU1_CPU0_P1P0_DP<5>")
	)
	(segment
		(start 341.861648 -212.060028)
		(end 341.861648 -212.03793)
		(width 0.0889)
		(layer "In4.Cu")
		(net "UPI_CPU1_CPU0_P1P0_DP<5>")
	)
	(segment
		(start 129.40157 -211.850478)
		(end 129.40157 -213.787228)
		(width 0.0889)
		(layer "In4.Cu")
		(net "UPI_CPU1_CPU0_P1P0_DP<5>")
	)
	(segment
		(start 341.918544 -213.267798)
		(end 341.918544 -213.092538)
		(width 0.0889)
		(layer "In4.Cu")
		(net "UPI_CPU1_CPU0_P1P0_DP<5>")
	)
	(segment
		(start 131.00431 -206.526384)
		(end 130.988308 -206.57185)
		(width 0.14732)
		(layer "In4.Cu")
		(net "UPI_CPU1_CPU0_P1P0_DP<5>")
	)
	(segment
		(start 128.931416 -217.859864)
		(end 128.931416 -217.8939)
		(width 0.0889)
		(layer "In4.Cu")
		(net "UPI_CPU1_CPU0_P1P0_DP<5>")
	)
	(segment
		(start 341.819484 -217.072972)
		(end 341.819484 -217.0557)
		(width 0.0889)
		(layer "In4.Cu")
		(net "UPI_CPU1_CPU0_P1P0_DP<5>")
	)
	(segment
		(start 342.006682 -215.761062)
		(end 342.005158 -215.7603)
		(width 0.0889)
		(layer "In4.Cu")
		(net "UPI_CPU1_CPU0_P1P0_DP<5>")
	)
	(segment
		(start 341.819484 -212.102192)
		(end 341.861648 -212.060028)
		(width 0.0889)
		(layer "In4.Cu")
		(net "UPI_CPU1_CPU0_P1P0_DP<5>")
	)
	(segment
		(start 332.894432 -194.051936)
		(end 326.197214 -191.624204)
		(width 0.14732)
		(layer "In4.Cu")
		(net "UPI_CPU1_CPU0_P1P0_DP<5>")
	)
	(segment
		(start 335.957164 -196.461126)
		(end 332.894432 -194.051936)
		(width 0.14732)
		(layer "In4.Cu")
		(net "UPI_CPU1_CPU0_P1P0_DP<5>")
	)
	(segment
		(start 343.12352 -208.57972)
		(end 343.12352 -205.316836)
		(width 0.14732)
		(layer "In4.Cu")
		(net "UPI_CPU1_CPU0_P1P0_DP<5>")
	)
	(segment
		(start 341.861648 -211.676742)
		(end 341.861394 -211.676488)
		(width 0.14732)
		(layer "In4.Cu")
		(net "UPI_CPU1_CPU0_P1P0_DP<5>")
	)
	(segment
		(start 129.359406 -211.223352)
		(end 129.359406 -211.602828)
		(width 0.14732)
		(layer "In4.Cu")
		(net "UPI_CPU1_CPU0_P1P0_DP<5>")
	)
	(segment
		(start 129.35966 -211.603082)
		(end 129.35966 -211.78647)
		(width 0.14732)
		(layer "In4.Cu")
		(net "UPI_CPU1_CPU0_P1P0_DP<5>")
	)
	(segment
		(start 129.692146 -214.941912)
		(end 129.683256 -214.946992)
		(width 0.0889)
		(layer "In4.Cu")
		(net "UPI_CPU1_CPU0_P1P0_DP<5>")
	)
	(segment
		(start 149.489922 -188.51499)
		(end 148.41855 -189.52972)
		(width 0.14732)
		(layer "In4.Cu")
		(net "UPI_CPU1_CPU0_P1P0_DP<5>")
	)
	(segment
		(start 342.288876 -214.644732)
		(end 342.288876 -214.424768)
		(width 0.0889)
		(layer "In4.Cu")
		(net "UPI_CPU1_CPU0_P1P0_DP<5>")
	)
	(segment
		(start 342.005666 -215.112854)
		(end 342.006682 -215.112346)
		(width 0.0889)
		(layer "In4.Cu")
		(net "UPI_CPU1_CPU0_P1P0_DP<5>")
	)
	(segment
		(start 130.988308 -206.57185)
		(end 129.359406 -211.223352)
		(width 0.14732)
		(layer "In4.Cu")
		(net "UPI_CPU1_CPU0_P1P0_DP<5>")
	)
	(segment
		(start 313.826906 -184.772046)
		(end 312.313066 -184.298336)
		(width 0.14732)
		(layer "In4.Cu")
		(net "UPI_CPU1_CPU0_P1P0_DP<5>")
	)
	(arc
		(start 129.213864 -217.388694)
		(mid 129.011578 -217.587675)
		(end 128.931416 -217.859864)
		(width 0.0889)
		(layer "In4.Cu")
		(net "UPI_CPU1_CPU0_P1P0_DP<5>")
	)
	(arc
		(start 129.141982 -218.319096)
		(mid 129.150302 -218.325653)
		(end 129.158746 -218.33205)
		(width 0.0889)
		(layer "In4.Cu")
		(net "UPI_CPU1_CPU0_P1P0_DP<5>")
	)
	(arc
		(start 341.819484 -217.0557)
		(mid 341.871754 -216.873335)
		(end 342.006682 -216.739978)
		(width 0.0889)
		(layer "In4.Cu")
		(net "UPI_CPU1_CPU0_P1P0_DP<5>")
	)
	(arc
		(start 129.21361 -215.761062)
		(mid 129.010787 -215.961293)
		(end 128.931416 -216.235026)
		(width 0.0889)
		(layer "In4.Cu")
		(net "UPI_CPU1_CPU0_P1P0_DP<5>")
	)
	(arc
		(start 341.959438 -217.356182)
		(mid 341.858117 -217.230061)
		(end 341.819484 -217.072972)
		(width 0.0889)
		(layer "In4.Cu")
		(net "UPI_CPU1_CPU0_P1P0_DP<5>")
	)
	(arc
		(start 341.819484 -215.421972)
		(mid 341.870538 -215.247392)
		(end 341.997792 -215.117426)
		(width 0.0889)
		(layer "In4.Cu")
		(net "UPI_CPU1_CPU0_P1P0_DP<5>")
	)
	(arc
		(start 129.686812 -214.261446)
		(mid 129.777855 -214.327132)
		(end 129.847594 -214.415116)
		(width 0.0889)
		(layer "In4.Cu")
		(net "UPI_CPU1_CPU0_P1P0_DP<5>")
	)
	(arc
		(start 129.401062 -215.436704)
		(mid 129.353383 -215.619604)
		(end 129.2225 -215.755982)
		(width 0.0889)
		(layer "In4.Cu")
		(net "UPI_CPU1_CPU0_P1P0_DP<5>")
	)
	(arc
		(start 341.81923 -215.436704)
		(mid 341.819282 -215.429337)
		(end 341.819484 -215.421972)
		(width 0.0889)
		(layer "In4.Cu")
		(net "UPI_CPU1_CPU0_P1P0_DP<5>")
	)
	(arc
		(start 342.288876 -214.424768)
		(mid 342.177597 -214.232062)
		(end 342.003634 -214.093298)
		(width 0.0889)
		(layer "In4.Cu")
		(net "UPI_CPU1_CPU0_P1P0_DP<5>")
	)
	(arc
		(start 129.213864 -216.739978)
		(mid 129.348797 -216.873332)
		(end 129.401062 -217.0557)
		(width 0.0889)
		(layer "In4.Cu")
		(net "UPI_CPU1_CPU0_P1P0_DP<5>")
	)
	(arc
		(start 128.931416 -217.8939)
		(mid 128.989969 -218.12963)
		(end 129.141982 -218.319096)
		(width 0.0889)
		(layer "In4.Cu")
		(net "UPI_CPU1_CPU0_P1P0_DP<5>")
	)
	(arc
		(start 129.870708 -214.622634)
		(mid 129.823029 -214.805534)
		(end 129.692146 -214.941912)
		(width 0.0889)
		(layer "In4.Cu")
		(net "UPI_CPU1_CPU0_P1P0_DP<5>")
	)
	(arc
		(start 129.401062 -217.072972)
		(mid 129.348792 -217.255337)
		(end 129.213864 -217.388694)
		(width 0.0889)
		(layer "In4.Cu")
		(net "UPI_CPU1_CPU0_P1P0_DP<5>")
	)
	(arc
		(start 129.40157 -213.787228)
		(mid 129.478257 -214.063994)
		(end 129.686812 -214.261446)
		(width 0.0889)
		(layer "In4.Cu")
		(net "UPI_CPU1_CPU0_P1P0_DP<5>")
	)
	(arc
		(start 342.012778 -216.736422)
		(mid 342.289352 -216.25052)
		(end 342.012778 -215.764618)
		(width 0.0889)
		(layer "In4.Cu")
		(net "UPI_CPU1_CPU0_P1P0_DP<5>")
	)
	(arc
		(start 342.006682 -215.112346)
		(mid 342.207964 -214.914859)
		(end 342.288876 -214.644732)
		(width 0.0889)
		(layer "In4.Cu")
		(net "UPI_CPU1_CPU0_P1P0_DP<5>")
	)
	(arc
		(start 128.931416 -216.260426)
		(mid 129.009527 -216.537375)
		(end 129.213864 -216.739978)
		(width 0.0889)
		(layer "In4.Cu")
		(net "UPI_CPU1_CPU0_P1P0_DP<5>")
	)
	(arc
		(start 342.003634 -214.093298)
		(mid 341.894487 -214.00937)
		(end 341.819484 -213.893908)
		(width 0.0889)
		(layer "In4.Cu")
		(net "UPI_CPU1_CPU0_P1P0_DP<5>")
	)
	(arc
		(start 341.997792 -215.755982)
		(mid 341.866878 -215.619622)
		(end 341.81923 -215.436704)
		(width 0.0889)
		(layer "In4.Cu")
		(net "UPI_CPU1_CPU0_P1P0_DP<5>")
	)
	(arc
		(start 129.847594 -214.415116)
		(mid 129.864863 -214.456501)
		(end 129.870708 -214.500968)
		(width 0.0889)
		(layer "In4.Cu")
		(net "UPI_CPU1_CPU0_P1P0_DP<5>")
	)
	(arc
		(start 129.683256 -214.946992)
		(mid 129.481974 -215.144479)
		(end 129.401062 -215.414606)
		(width 0.0889)
		(layer "In4.Cu")
		(net "UPI_CPU1_CPU0_P1P0_DP<5>")
	)
	(segment
		(start 341.254334 -218.692476)
		(end 341.25408 -218.692222)
		(width 0.13208)
		(layer "F.Cu")
		(net "UPI_CPU1_CPU0_P1P0_DP<4>")
	)
	(segment
		(start 341.254334 -219.228162)
		(end 341.254334 -218.692476)
		(width 0.13208)
		(layer "F.Cu")
		(net "UPI_CPU1_CPU0_P1P0_DP<4>")
	)
	(segment
		(start 129.966466 -217.06459)
		(end 129.966212 -217.064336)
		(width 0.13208)
		(layer "F.Cu")
		(net "UPI_CPU1_CPU0_P1P0_DP<4>")
	)
	(segment
		(start 129.966466 -217.600276)
		(end 129.966466 -217.06459)
		(width 0.13208)
		(layer "F.Cu")
		(net "UPI_CPU1_CPU0_P1P0_DP<4>")
	)
	(segment
		(start 342.27008 -208.224374)
		(end 342.27008 -205.444344)
		(width 0.14732)
		(layer "In4.Cu")
		(net "UPI_CPU1_CPU0_P1P0_DP<4>")
	)
	(segment
		(start 153.841958 -188.510418)
		(end 153.541222 -189.443614)
		(width 0.14732)
		(layer "In4.Cu")
		(net "UPI_CPU1_CPU0_P1P0_DP<4>")
	)
	(segment
		(start 146.71548 -193.628772)
		(end 146.105626 -194.174364)
		(width 0.14732)
		(layer "In4.Cu")
		(net "UPI_CPU1_CPU0_P1P0_DP<4>")
	)
	(segment
		(start 150.170896 -190.539116)
		(end 149.561042 -191.084708)
		(width 0.14732)
		(layer "In4.Cu")
		(net "UPI_CPU1_CPU0_P1P0_DP<4>")
	)
	(segment
		(start 341.057992 -215.117426)
		(end 341.065866 -215.112854)
		(width 0.0889)
		(layer "In4.Cu")
		(net "UPI_CPU1_CPU0_P1P0_DP<4>")
	)
	(segment
		(start 302.478186 -184.96788)
		(end 302.24984 -184.96788)
		(width 0.14732)
		(layer "In4.Cu")
		(net "UPI_CPU1_CPU0_P1P0_DP<4>")
	)
	(segment
		(start 148.443188 -192.083944)
		(end 147.833334 -192.629536)
		(width 0.14732)
		(layer "In4.Cu")
		(net "UPI_CPU1_CPU0_P1P0_DP<4>")
	)
	(segment
		(start 149.527514 -192.835022)
		(end 148.877528 -192.108328)
		(width 0.14732)
		(layer "In4.Cu")
		(net "UPI_CPU1_CPU0_P1P0_DP<4>")
	)
	(segment
		(start 130.340862 -215.414606)
		(end 130.340862 -215.436704)
		(width 0.0889)
		(layer "In4.Cu")
		(net "UPI_CPU1_CPU0_P1P0_DP<4>")
	)
	(segment
		(start 273.21129 -185.768742)
		(end 215.533732 -185.898536)
		(width 0.14732)
		(layer "In4.Cu")
		(net "UPI_CPU1_CPU0_P1P0_DP<4>")
	)
	(segment
		(start 326.986392 -192.977262)
		(end 322.104258 -190.433198)
		(width 0.14732)
		(layer "In4.Cu")
		(net "UPI_CPU1_CPU0_P1P0_DP<4>")
	)
	(segment
		(start 341.058246 -216.745058)
		(end 341.061294 -216.74328)
		(width 0.0889)
		(layer "In4.Cu")
		(net "UPI_CPU1_CPU0_P1P0_DP<4>")
	)
	(segment
		(start 341.067136 -217.388694)
		(end 341.058246 -217.383614)
		(width 0.0889)
		(layer "In4.Cu")
		(net "UPI_CPU1_CPU0_P1P0_DP<4>")
	)
	(segment
		(start 340.879684 -213.893908)
		(end 340.87943 -213.8934)
		(width 0.0889)
		(layer "In4.Cu")
		(net "UPI_CPU1_CPU0_P1P0_DP<4>")
	)
	(segment
		(start 146.081242 -194.608704)
		(end 146.731228 -195.335398)
		(width 0.14732)
		(layer "In4.Cu")
		(net "UPI_CPU1_CPU0_P1P0_DP<4>")
	)
	(segment
		(start 341.065358 -215.7603)
		(end 341.057992 -215.755982)
		(width 0.0889)
		(layer "In4.Cu")
		(net "UPI_CPU1_CPU0_P1P0_DP<4>")
	)
	(segment
		(start 136.79932 -207.642968)
		(end 133.028944 -211.413344)
		(width 0.14732)
		(layer "In4.Cu")
		(net "UPI_CPU1_CPU0_P1P0_DP<4>")
	)
	(segment
		(start 129.871216 -216.235026)
		(end 129.871216 -216.266014)
		(width 0.0889)
		(layer "In4.Cu")
		(net "UPI_CPU1_CPU0_P1P0_DP<4>")
	)
	(segment
		(start 341.066374 -216.740486)
		(end 341.067136 -216.739978)
		(width 0.0889)
		(layer "In4.Cu")
		(net "UPI_CPU1_CPU0_P1P0_DP<4>")
	)
	(segment
		(start 150.17496 -192.453514)
		(end 149.735286 -192.846706)
		(width 0.14732)
		(layer "In4.Cu")
		(net "UPI_CPU1_CPU0_P1P0_DP<4>")
	)
	(segment
		(start 341.069676 -215.762586)
		(end 341.066882 -215.761062)
		(width 0.0889)
		(layer "In4.Cu")
		(net "UPI_CPU1_CPU0_P1P0_DP<4>")
	)
	(segment
		(start 130.1623 -215.755982)
		(end 130.15341 -215.761062)
		(width 0.0889)
		(layer "In4.Cu")
		(net "UPI_CPU1_CPU0_P1P0_DP<4>")
	)
	(segment
		(start 341.349584 -217.878406)
		(end 341.349584 -217.859864)
		(width 0.0889)
		(layer "In4.Cu")
		(net "UPI_CPU1_CPU0_P1P0_DP<4>")
	)
	(segment
		(start 341.25408 -218.692222)
		(end 341.097616 -218.421204)
		(width 0.0889)
		(layer "In4.Cu")
		(net "UPI_CPU1_CPU0_P1P0_DP<4>")
	)
	(segment
		(start 147.799806 -194.37985)
		(end 147.14982 -193.653156)
		(width 0.14732)
		(layer "In4.Cu")
		(net "UPI_CPU1_CPU0_P1P0_DP<4>")
	)
	(segment
		(start 148.877528 -192.108328)
		(end 148.443188 -192.083944)
		(width 0.14732)
		(layer "In4.Cu")
		(net "UPI_CPU1_CPU0_P1P0_DP<4>")
	)
	(segment
		(start 146.719544 -195.54317)
		(end 142.92199 -198.938642)
		(width 0.14732)
		(layer "In4.Cu")
		(net "UPI_CPU1_CPU0_P1P0_DP<4>")
	)
	(segment
		(start 133.028944 -211.413344)
		(end 133.01345 -211.428838)
		(width 0.0889)
		(layer "In4.Cu")
		(net "UPI_CPU1_CPU0_P1P0_DP<4>")
	)
	(segment
		(start 130.122676 -217.335354)
		(end 129.966212 -217.064336)
		(width 0.0889)
		(layer "In4.Cu")
		(net "UPI_CPU1_CPU0_P1P0_DP<4>")
	)
	(segment
		(start 340.921594 -212.03793)
		(end 340.921594 -211.801202)
		(width 0.14732)
		(layer "In4.Cu")
		(net "UPI_CPU1_CPU0_P1P0_DP<4>")
	)
	(segment
		(start 151.255222 -191.290194)
		(end 150.605236 -190.5635)
		(width 0.14732)
		(layer "In4.Cu")
		(net "UPI_CPU1_CPU0_P1P0_DP<4>")
	)
	(segment
		(start 340.92134 -209.573114)
		(end 342.27008 -208.224374)
		(width 0.14732)
		(layer "In4.Cu")
		(net "UPI_CPU1_CPU0_P1P0_DP<4>")
	)
	(segment
		(start 130.154426 -216.740486)
		(end 130.1623 -216.745058)
		(width 0.0889)
		(layer "In4.Cu")
		(net "UPI_CPU1_CPU0_P1P0_DP<4>")
	)
	(segment
		(start 148.458936 -193.79057)
		(end 148.447252 -193.998342)
		(width 0.14732)
		(layer "In4.Cu")
		(net "UPI_CPU1_CPU0_P1P0_DP<4>")
	)
	(segment
		(start 341.072978 -215.764618)
		(end 341.069676 -215.762586)
		(width 0.0889)
		(layer "In4.Cu")
		(net "UPI_CPU1_CPU0_P1P0_DP<4>")
	)
	(segment
		(start 155.167076 -187.30976)
		(end 153.841958 -188.510418)
		(width 0.14732)
		(layer "In4.Cu")
		(net "UPI_CPU1_CPU0_P1P0_DP<4>")
	)
	(segment
		(start 302.24984 -184.96788)
		(end 273.21129 -185.768742)
		(width 0.14732)
		(layer "In4.Cu")
		(net "UPI_CPU1_CPU0_P1P0_DP<4>")
	)
	(segment
		(start 149.561042 -191.084708)
		(end 149.536658 -191.519048)
		(width 0.14732)
		(layer "In4.Cu")
		(net "UPI_CPU1_CPU0_P1P0_DP<4>")
	)
	(segment
		(start 133.01345 -211.428838)
		(end 133.01345 -211.488782)
		(width 0.0889)
		(layer "In4.Cu")
		(net "UPI_CPU1_CPU0_P1P0_DP<4>")
	)
	(segment
		(start 340.92134 -211.800948)
		(end 340.92134 -209.573114)
		(width 0.14732)
		(layer "In4.Cu")
		(net "UPI_CPU1_CPU0_P1P0_DP<4>")
	)
	(segment
		(start 150.186644 -192.245742)
		(end 150.17496 -192.453514)
		(width 0.14732)
		(layer "In4.Cu")
		(net "UPI_CPU1_CPU0_P1P0_DP<4>")
	)
	(segment
		(start 332.961234 -195.163186)
		(end 326.986392 -192.977262)
		(width 0.14732)
		(layer "In4.Cu")
		(net "UPI_CPU1_CPU0_P1P0_DP<4>")
	)
	(segment
		(start 146.731228 -195.335398)
		(end 146.719544 -195.54317)
		(width 0.14732)
		(layer "In4.Cu")
		(net "UPI_CPU1_CPU0_P1P0_DP<4>")
	)
	(segment
		(start 341.349584 -216.260426)
		(end 341.349584 -216.25052)
		(width 0.0889)
		(layer "In4.Cu")
		(net "UPI_CPU1_CPU0_P1P0_DP<4>")
	)
	(segment
		(start 133.01345 -211.488782)
		(end 131.280916 -213.221316)
		(width 0.0889)
		(layer "In4.Cu")
		(net "UPI_CPU1_CPU0_P1P0_DP<4>")
	)
	(segment
		(start 312.147966 -185.154062)
		(end 302.478186 -184.96788)
		(width 0.14732)
		(layer "In4.Cu")
		(net "UPI_CPU1_CPU0_P1P0_DP<4>")
	)
	(segment
		(start 142.92199 -198.938642)
		(end 136.79932 -207.642968)
		(width 0.14732)
		(layer "In4.Cu")
		(net "UPI_CPU1_CPU0_P1P0_DP<4>")
	)
	(segment
		(start 340.921594 -212.060028)
		(end 340.921594 -212.03793)
		(width 0.0889)
		(layer "In4.Cu")
		(net "UPI_CPU1_CPU0_P1P0_DP<4>")
	)
	(segment
		(start 130.200908 -217.356182)
		(end 130.122676 -217.335354)
		(width 0.0889)
		(layer "In4.Cu")
		(net "UPI_CPU1_CPU0_P1P0_DP<4>")
	)
	(segment
		(start 148.447252 -193.998342)
		(end 148.007578 -194.391534)
		(width 0.14732)
		(layer "In4.Cu")
		(net "UPI_CPU1_CPU0_P1P0_DP<4>")
	)
	(segment
		(start 149.735286 -192.846706)
		(end 149.527514 -192.835022)
		(width 0.14732)
		(layer "In4.Cu")
		(net "UPI_CPU1_CPU0_P1P0_DP<4>")
	)
	(segment
		(start 147.833334 -192.629536)
		(end 147.80895 -193.063876)
		(width 0.14732)
		(layer "In4.Cu")
		(net "UPI_CPU1_CPU0_P1P0_DP<4>")
	)
	(segment
		(start 153.541222 -189.443614)
		(end 151.462994 -191.301878)
		(width 0.14732)
		(layer "In4.Cu")
		(net "UPI_CPU1_CPU0_P1P0_DP<4>")
	)
	(segment
		(start 147.14982 -193.653156)
		(end 146.71548 -193.628772)
		(width 0.14732)
		(layer "In4.Cu")
		(net "UPI_CPU1_CPU0_P1P0_DP<4>")
	)
	(segment
		(start 340.87943 -213.8934)
		(end 340.87943 -212.102192)
		(width 0.0889)
		(layer "In4.Cu")
		(net "UPI_CPU1_CPU0_P1P0_DP<4>")
	)
	(segment
		(start 341.349076 -214.644732)
		(end 341.349076 -214.424768)
		(width 0.0889)
		(layer "In4.Cu")
		(net "UPI_CPU1_CPU0_P1P0_DP<4>")
	)
	(segment
		(start 130.15341 -216.739978)
		(end 130.154426 -216.740486)
		(width 0.0889)
		(layer "In4.Cu")
		(net "UPI_CPU1_CPU0_P1P0_DP<4>")
	)
	(segment
		(start 159.592772 -185.862468)
		(end 157.199838 -186.645042)
		(width 0.14732)
		(layer "In4.Cu")
		(net "UPI_CPU1_CPU0_P1P0_DP<4>")
	)
	(segment
		(start 341.066882 -215.761062)
		(end 341.065358 -215.7603)
		(width 0.0889)
		(layer "In4.Cu")
		(net "UPI_CPU1_CPU0_P1P0_DP<4>")
	)
	(segment
		(start 148.007578 -194.391534)
		(end 147.799806 -194.37985)
		(width 0.14732)
		(layer "In4.Cu")
		(net "UPI_CPU1_CPU0_P1P0_DP<4>")
	)
	(segment
		(start 340.921594 -211.801202)
		(end 340.92134 -211.800948)
		(width 0.14732)
		(layer "In4.Cu")
		(net "UPI_CPU1_CPU0_P1P0_DP<4>")
	)
	(segment
		(start 322.104258 -190.433198)
		(end 313.409076 -185.54192)
		(width 0.14732)
		(layer "In4.Cu")
		(net "UPI_CPU1_CPU0_P1P0_DP<4>")
	)
	(segment
		(start 130.810508 -214.425784)
		(end 130.810508 -214.622634)
		(width 0.0889)
		(layer "In4.Cu")
		(net "UPI_CPU1_CPU0_P1P0_DP<4>")
	)
	(segment
		(start 341.065866 -215.112854)
		(end 341.066882 -215.112346)
		(width 0.0889)
		(layer "In4.Cu")
		(net "UPI_CPU1_CPU0_P1P0_DP<4>")
	)
	(segment
		(start 150.605236 -190.5635)
		(end 150.170896 -190.539116)
		(width 0.14732)
		(layer "In4.Cu")
		(net "UPI_CPU1_CPU0_P1P0_DP<4>")
	)
	(segment
		(start 215.533732 -185.898536)
		(end 200.608184 -185.174382)
		(width 0.14732)
		(layer "In4.Cu")
		(net "UPI_CPU1_CPU0_P1P0_DP<4>")
	)
	(segment
		(start 313.409076 -185.54192)
		(end 312.147966 -185.154062)
		(width 0.14732)
		(layer "In4.Cu")
		(net "UPI_CPU1_CPU0_P1P0_DP<4>")
	)
	(segment
		(start 341.061294 -216.74328)
		(end 341.066374 -216.740486)
		(width 0.0889)
		(layer "In4.Cu")
		(net "UPI_CPU1_CPU0_P1P0_DP<4>")
	)
	(segment
		(start 149.536658 -191.519048)
		(end 150.186644 -192.245742)
		(width 0.14732)
		(layer "In4.Cu")
		(net "UPI_CPU1_CPU0_P1P0_DP<4>")
	)
	(segment
		(start 341.231728 -202.93711)
		(end 335.289906 -196.995034)
		(width 0.14732)
		(layer "In4.Cu")
		(net "UPI_CPU1_CPU0_P1P0_DP<4>")
	)
	(segment
		(start 146.105626 -194.174364)
		(end 146.081242 -194.608704)
		(width 0.14732)
		(layer "In4.Cu")
		(net "UPI_CPU1_CPU0_P1P0_DP<4>")
	)
	(segment
		(start 200.608184 -185.174382)
		(end 159.592772 -185.862468)
		(width 0.14732)
		(layer "In4.Cu")
		(net "UPI_CPU1_CPU0_P1P0_DP<4>")
	)
	(segment
		(start 157.199838 -186.645042)
		(end 155.167076 -187.30976)
		(width 0.14732)
		(layer "In4.Cu")
		(net "UPI_CPU1_CPU0_P1P0_DP<4>")
	)
	(segment
		(start 131.280916 -213.221316)
		(end 131.280916 -213.8934)
		(width 0.0889)
		(layer "In4.Cu")
		(net "UPI_CPU1_CPU0_P1P0_DP<4>")
	)
	(segment
		(start 151.462994 -191.301878)
		(end 151.255222 -191.290194)
		(width 0.14732)
		(layer "In4.Cu")
		(net "UPI_CPU1_CPU0_P1P0_DP<4>")
	)
	(segment
		(start 342.27008 -205.444344)
		(end 341.231728 -202.93711)
		(width 0.14732)
		(layer "In4.Cu")
		(net "UPI_CPU1_CPU0_P1P0_DP<4>")
	)
	(segment
		(start 341.097616 -218.421204)
		(end 341.121746 -218.33205)
		(width 0.0889)
		(layer "In4.Cu")
		(net "UPI_CPU1_CPU0_P1P0_DP<4>")
	)
	(segment
		(start 340.87943 -212.102192)
		(end 340.921594 -212.060028)
		(width 0.0889)
		(layer "In4.Cu")
		(net "UPI_CPU1_CPU0_P1P0_DP<4>")
	)
	(segment
		(start 335.289906 -196.995034)
		(end 332.961234 -195.163186)
		(width 0.14732)
		(layer "In4.Cu")
		(net "UPI_CPU1_CPU0_P1P0_DP<4>")
	)
	(segment
		(start 130.631946 -214.941912)
		(end 130.623056 -214.946992)
		(width 0.0889)
		(layer "In4.Cu")
		(net "UPI_CPU1_CPU0_P1P0_DP<4>")
	)
	(segment
		(start 147.80895 -193.063876)
		(end 148.458936 -193.79057)
		(width 0.14732)
		(layer "In4.Cu")
		(net "UPI_CPU1_CPU0_P1P0_DP<4>")
	)
	(arc
		(start 341.349076 -214.424768)
		(mid 341.237797 -214.232062)
		(end 341.063834 -214.093298)
		(width 0.0889)
		(layer "In4.Cu")
		(net "UPI_CPU1_CPU0_P1P0_DP<4>")
	)
	(arc
		(start 129.871216 -216.266014)
		(mid 129.950586 -216.539748)
		(end 130.15341 -216.739978)
		(width 0.0889)
		(layer "In4.Cu")
		(net "UPI_CPU1_CPU0_P1P0_DP<4>")
	)
	(arc
		(start 341.057992 -215.755982)
		(mid 340.927078 -215.619622)
		(end 340.87943 -215.436704)
		(width 0.0889)
		(layer "In4.Cu")
		(net "UPI_CPU1_CPU0_P1P0_DP<4>")
	)
	(arc
		(start 341.138764 -218.318842)
		(mid 341.294162 -218.122561)
		(end 341.349584 -217.878406)
		(width 0.0889)
		(layer "In4.Cu")
		(net "UPI_CPU1_CPU0_P1P0_DP<4>")
	)
	(arc
		(start 340.87943 -215.436704)
		(mid 340.879482 -215.429337)
		(end 340.879684 -215.421972)
		(width 0.0889)
		(layer "In4.Cu")
		(net "UPI_CPU1_CPU0_P1P0_DP<4>")
	)
	(arc
		(start 130.15341 -215.761062)
		(mid 129.950587 -215.961293)
		(end 129.871216 -216.235026)
		(width 0.0889)
		(layer "In4.Cu")
		(net "UPI_CPU1_CPU0_P1P0_DP<4>")
	)
	(arc
		(start 130.623056 -214.946992)
		(mid 130.421774 -215.144479)
		(end 130.340862 -215.414606)
		(width 0.0889)
		(layer "In4.Cu")
		(net "UPI_CPU1_CPU0_P1P0_DP<4>")
	)
	(arc
		(start 341.349584 -217.859864)
		(mid 341.269422 -217.587675)
		(end 341.067136 -217.388694)
		(width 0.0889)
		(layer "In4.Cu")
		(net "UPI_CPU1_CPU0_P1P0_DP<4>")
	)
	(arc
		(start 130.810508 -214.622634)
		(mid 130.762829 -214.805534)
		(end 130.631946 -214.941912)
		(width 0.0889)
		(layer "In4.Cu")
		(net "UPI_CPU1_CPU0_P1P0_DP<4>")
	)
	(arc
		(start 341.058246 -217.383614)
		(mid 340.879649 -217.064336)
		(end 341.058246 -216.745058)
		(width 0.0889)
		(layer "In4.Cu")
		(net "UPI_CPU1_CPU0_P1P0_DP<4>")
	)
	(arc
		(start 130.340862 -215.436704)
		(mid 130.293183 -215.619604)
		(end 130.1623 -215.755982)
		(width 0.0889)
		(layer "In4.Cu")
		(net "UPI_CPU1_CPU0_P1P0_DP<4>")
	)
	(arc
		(start 341.349584 -216.25052)
		(mid 341.275593 -215.970954)
		(end 341.072978 -215.764618)
		(width 0.0889)
		(layer "In4.Cu")
		(net "UPI_CPU1_CPU0_P1P0_DP<4>")
	)
	(arc
		(start 341.121746 -218.33205)
		(mid 341.130318 -218.325528)
		(end 341.138764 -218.318842)
		(width 0.0889)
		(layer "In4.Cu")
		(net "UPI_CPU1_CPU0_P1P0_DP<4>")
	)
	(arc
		(start 341.066882 -215.112346)
		(mid 341.268164 -214.914859)
		(end 341.349076 -214.644732)
		(width 0.0889)
		(layer "In4.Cu")
		(net "UPI_CPU1_CPU0_P1P0_DP<4>")
	)
	(arc
		(start 341.067136 -216.739978)
		(mid 341.271471 -216.537373)
		(end 341.349584 -216.260426)
		(width 0.0889)
		(layer "In4.Cu")
		(net "UPI_CPU1_CPU0_P1P0_DP<4>")
	)
	(arc
		(start 131.280916 -213.8934)
		(mid 131.205845 -214.009142)
		(end 131.096512 -214.093298)
		(width 0.0889)
		(layer "In4.Cu")
		(net "UPI_CPU1_CPU0_P1P0_DP<4>")
	)
	(arc
		(start 131.096512 -214.093298)
		(mid 130.921964 -214.232402)
		(end 130.810508 -214.425784)
		(width 0.0889)
		(layer "In4.Cu")
		(net "UPI_CPU1_CPU0_P1P0_DP<4>")
	)
	(arc
		(start 341.063834 -214.093298)
		(mid 340.954687 -214.00937)
		(end 340.879684 -213.893908)
		(width 0.0889)
		(layer "In4.Cu")
		(net "UPI_CPU1_CPU0_P1P0_DP<4>")
	)
	(arc
		(start 340.879684 -215.421972)
		(mid 340.930738 -215.247392)
		(end 341.057992 -215.117426)
		(width 0.0889)
		(layer "In4.Cu")
		(net "UPI_CPU1_CPU0_P1P0_DP<4>")
	)
	(arc
		(start 130.340862 -217.064336)
		(mid 130.304002 -217.226133)
		(end 130.200908 -217.356182)
		(width 0.0889)
		(layer "In4.Cu")
		(net "UPI_CPU1_CPU0_P1P0_DP<4>")
	)
	(arc
		(start 130.1623 -216.745058)
		(mid 130.293214 -216.881418)
		(end 130.340862 -217.064336)
		(width 0.0889)
		(layer "In4.Cu")
		(net "UPI_CPU1_CPU0_P1P0_DP<4>")
	)
	(segment
		(start 130.906266 -219.228162)
		(end 130.906266 -218.692476)
		(width 0.13208)
		(layer "F.Cu")
		(net "UPI_CPU1_CPU0_P1P0_DP<3>")
	)
	(segment
		(start 130.906266 -218.692476)
		(end 130.906012 -218.692222)
		(width 0.13208)
		(layer "F.Cu")
		(net "UPI_CPU1_CPU0_P1P0_DP<3>")
	)
	(segment
		(start 340.314534 -217.06459)
		(end 340.31428 -217.064336)
		(width 0.13208)
		(layer "F.Cu")
		(net "UPI_CPU1_CPU0_P1P0_DP<3>")
	)
	(segment
		(start 340.314534 -217.600276)
		(end 340.314534 -217.06459)
		(width 0.13208)
		(layer "F.Cu")
		(net "UPI_CPU1_CPU0_P1P0_DP<3>")
	)
	(segment
		(start 319.472564 -191.39027)
		(end 332.535276 -195.897246)
		(width 0.14732)
		(layer "In4.Cu")
		(net "UPI_CPU1_CPU0_P1P0_DP<3>")
	)
	(segment
		(start 260.82371 -189.748668)
		(end 261.761478 -189.229492)
		(width 0.14732)
		(layer "In4.Cu")
		(net "UPI_CPU1_CPU0_P1P0_DP<3>")
	)
	(segment
		(start 339.982048 -212.03793)
		(end 339.982048 -212.060028)
		(width 0.0889)
		(layer "In4.Cu")
		(net "UPI_CPU1_CPU0_P1P0_DP<3>")
	)
	(segment
		(start 249.3899 -192.722754)
		(end 260.82371 -189.748668)
		(width 0.14732)
		(layer "In4.Cu")
		(net "UPI_CPU1_CPU0_P1P0_DP<3>")
	)
	(segment
		(start 131.062476 -218.421204)
		(end 131.038346 -218.33205)
		(width 0.0889)
		(layer "In4.Cu")
		(net "UPI_CPU1_CPU0_P1P0_DP<3>")
	)
	(segment
		(start 340.409276 -214.424768)
		(end 340.409276 -214.644732)
		(width 0.0889)
		(layer "In4.Cu")
		(net "UPI_CPU1_CPU0_P1P0_DP<3>")
	)
	(segment
		(start 302.46701 -185.81878)
		(end 312.034174 -185.99658)
		(width 0.14732)
		(layer "In4.Cu")
		(net "UPI_CPU1_CPU0_P1P0_DP<3>")
	)
	(segment
		(start 261.475982 -188.410088)
		(end 261.596378 -187.990988)
		(width 0.14732)
		(layer "In4.Cu")
		(net "UPI_CPU1_CPU0_P1P0_DP<3>")
	)
	(segment
		(start 132.220716 -213.483444)
		(end 132.591048 -213.113112)
		(width 0.0889)
		(layer "In4.Cu")
		(net "UPI_CPU1_CPU0_P1P0_DP<3>")
	)
	(segment
		(start 332.535276 -195.897246)
		(end 334.775048 -197.658736)
		(width 0.14732)
		(layer "In4.Cu")
		(net "UPI_CPU1_CPU0_P1P0_DP<3>")
	)
	(segment
		(start 238.429038 -197.737984)
		(end 249.3899 -192.722754)
		(width 0.14732)
		(layer "In4.Cu")
		(net "UPI_CPU1_CPU0_P1P0_DP<3>")
	)
	(segment
		(start 132.690108 -214.622634)
		(end 132.690108 -214.461344)
		(width 0.0889)
		(layer "In4.Cu")
		(net "UPI_CPU1_CPU0_P1P0_DP<3>")
	)
	(segment
		(start 130.811016 -217.8939)
		(end 130.811016 -217.859864)
		(width 0.0889)
		(layer "In4.Cu")
		(net "UPI_CPU1_CPU0_P1P0_DP<3>")
	)
	(segment
		(start 334.775048 -197.658736)
		(end 340.53018 -203.414122)
		(width 0.14732)
		(layer "In4.Cu")
		(net "UPI_CPU1_CPU0_P1P0_DP<3>")
	)
	(segment
		(start 340.118192 -215.755982)
		(end 340.125558 -215.7603)
		(width 0.0889)
		(layer "In4.Cu")
		(net "UPI_CPU1_CPU0_P1P0_DP<3>")
	)
	(segment
		(start 159.725106 -186.698382)
		(end 200.424542 -186.02833)
		(width 0.14732)
		(layer "In4.Cu")
		(net "UPI_CPU1_CPU0_P1P0_DP<3>")
	)
	(segment
		(start 157.849824 -187.791852)
		(end 159.725106 -186.698382)
		(width 0.14732)
		(layer "In4.Cu")
		(net "UPI_CPU1_CPU0_P1P0_DP<3>")
	)
	(segment
		(start 340.038944 -213.310978)
		(end 339.939884 -213.410038)
		(width 0.0889)
		(layer "In4.Cu")
		(net "UPI_CPU1_CPU0_P1P0_DP<3>")
	)
	(segment
		(start 261.596378 -187.990988)
		(end 262.311642 -187.595256)
		(width 0.14732)
		(layer "In4.Cu")
		(net "UPI_CPU1_CPU0_P1P0_DP<3>")
	)
	(segment
		(start 339.939884 -213.036658)
		(end 340.038944 -213.135718)
		(width 0.0889)
		(layer "In4.Cu")
		(net "UPI_CPU1_CPU0_P1P0_DP<3>")
	)
	(segment
		(start 131.280662 -215.436704)
		(end 131.280662 -215.414606)
		(width 0.0889)
		(layer "In4.Cu")
		(net "UPI_CPU1_CPU0_P1P0_DP<3>")
	)
	(segment
		(start 130.906012 -218.692222)
		(end 131.062476 -218.421204)
		(width 0.0889)
		(layer "In4.Cu")
		(net "UPI_CPU1_CPU0_P1P0_DP<3>")
	)
	(segment
		(start 133.71449 -212.08619)
		(end 133.71449 -212.026246)
		(width 0.0889)
		(layer "In4.Cu")
		(net "UPI_CPU1_CPU0_P1P0_DP<3>")
	)
	(segment
		(start 340.53018 -203.414122)
		(end 341.41156 -205.542388)
		(width 0.14732)
		(layer "In4.Cu")
		(net "UPI_CPU1_CPU0_P1P0_DP<3>")
	)
	(segment
		(start 262.729726 -187.715652)
		(end 263.07288 -188.335158)
		(width 0.14732)
		(layer "In4.Cu")
		(net "UPI_CPU1_CPU0_P1P0_DP<3>")
	)
	(segment
		(start 132.687568 -213.113112)
		(end 133.71449 -212.08619)
		(width 0.0889)
		(layer "In4.Cu")
		(net "UPI_CPU1_CPU0_P1P0_DP<3>")
	)
	(segment
		(start 340.127844 -216.73947)
		(end 340.127082 -216.739978)
		(width 0.0889)
		(layer "In4.Cu")
		(net "UPI_CPU1_CPU0_P1P0_DP<3>")
	)
	(segment
		(start 339.981794 -211.800948)
		(end 339.982048 -211.801202)
		(width 0.14732)
		(layer "In4.Cu")
		(net "UPI_CPU1_CPU0_P1P0_DP<3>")
	)
	(segment
		(start 340.133178 -216.736422)
		(end 340.127844 -216.73947)
		(width 0.0889)
		(layer "In4.Cu")
		(net "UPI_CPU1_CPU0_P1P0_DP<3>")
	)
	(segment
		(start 200.424542 -186.02833)
		(end 215.27262 -186.722258)
		(width 0.14732)
		(layer "In4.Cu")
		(net "UPI_CPU1_CPU0_P1P0_DP<3>")
	)
	(segment
		(start 262.311642 -187.595256)
		(end 262.729726 -187.715652)
		(width 0.14732)
		(layer "In4.Cu")
		(net "UPI_CPU1_CPU0_P1P0_DP<3>")
	)
	(segment
		(start 339.939884 -212.861398)
		(end 339.939884 -213.036658)
		(width 0.0889)
		(layer "In4.Cu")
		(net "UPI_CPU1_CPU0_P1P0_DP<3>")
	)
	(segment
		(start 261.819136 -189.029594)
		(end 261.475982 -188.410088)
		(width 0.14732)
		(layer "In4.Cu")
		(net "UPI_CPU1_CPU0_P1P0_DP<3>")
	)
	(segment
		(start 132.220716 -213.930484)
		(end 132.220716 -213.483444)
		(width 0.0889)
		(layer "In4.Cu")
		(net "UPI_CPU1_CPU0_P1P0_DP<3>")
	)
	(segment
		(start 339.939884 -213.410038)
		(end 339.939884 -213.893908)
		(width 0.0889)
		(layer "In4.Cu")
		(net "UPI_CPU1_CPU0_P1P0_DP<3>")
	)
	(segment
		(start 148.108924 -195.428108)
		(end 151.931624 -192.431416)
		(width 0.14732)
		(layer "In4.Cu")
		(net "UPI_CPU1_CPU0_P1P0_DP<3>")
	)
	(segment
		(start 143.513556 -199.552814)
		(end 148.108924 -195.428108)
		(width 0.14732)
		(layer "In4.Cu")
		(net "UPI_CPU1_CPU0_P1P0_DP<3>")
	)
	(segment
		(start 131.280662 -217.072972)
		(end 131.280662 -217.0557)
		(width 0.0889)
		(layer "In4.Cu")
		(net "UPI_CPU1_CPU0_P1P0_DP<3>")
	)
	(segment
		(start 235.95965 -197.887844)
		(end 237.232444 -197.887844)
		(width 0.14732)
		(layer "In4.Cu")
		(net "UPI_CPU1_CPU0_P1P0_DP<3>")
	)
	(segment
		(start 341.41156 -207.875886)
		(end 339.981794 -209.305652)
		(width 0.14732)
		(layer "In4.Cu")
		(net "UPI_CPU1_CPU0_P1P0_DP<3>")
	)
	(segment
		(start 132.113528 -214.938356)
		(end 132.12826 -214.946992)
		(width 0.0889)
		(layer "In4.Cu")
		(net "UPI_CPU1_CPU0_P1P0_DP<3>")
	)
	(segment
		(start 339.981794 -209.305652)
		(end 339.981794 -211.800948)
		(width 0.14732)
		(layer "In4.Cu")
		(net "UPI_CPU1_CPU0_P1P0_DP<3>")
	)
	(segment
		(start 135.175498 -210.564984)
		(end 137.212324 -208.527904)
		(width 0.14732)
		(layer "In4.Cu")
		(net "UPI_CPU1_CPU0_P1P0_DP<3>")
	)
	(segment
		(start 339.982048 -211.801202)
		(end 339.982048 -212.03793)
		(width 0.14732)
		(layer "In4.Cu")
		(net "UPI_CPU1_CPU0_P1P0_DP<3>")
	)
	(segment
		(start 264.540492 -187.691014)
		(end 264.586974 -187.66536)
		(width 0.14732)
		(layer "In4.Cu")
		(net "UPI_CPU1_CPU0_P1P0_DP<3>")
	)
	(segment
		(start 339.939884 -212.102192)
		(end 339.939884 -212.488018)
		(width 0.0889)
		(layer "In4.Cu")
		(net "UPI_CPU1_CPU0_P1P0_DP<3>")
	)
	(segment
		(start 137.212324 -208.527904)
		(end 143.513556 -199.552814)
		(width 0.14732)
		(layer "In4.Cu")
		(net "UPI_CPU1_CPU0_P1P0_DP<3>")
	)
	(segment
		(start 264.586974 -187.66536)
		(end 273.011138 -186.631834)
		(width 0.14732)
		(layer "In4.Cu")
		(net "UPI_CPU1_CPU0_P1P0_DP<3>")
	)
	(segment
		(start 313.116214 -186.32805)
		(end 319.472564 -191.39027)
		(width 0.14732)
		(layer "In4.Cu")
		(net "UPI_CPU1_CPU0_P1P0_DP<3>")
	)
	(segment
		(start 273.011138 -186.631834)
		(end 302.46701 -185.81878)
		(width 0.14732)
		(layer "In4.Cu")
		(net "UPI_CPU1_CPU0_P1P0_DP<3>")
	)
	(segment
		(start 264.540492 -187.691268)
		(end 264.540492 -187.691014)
		(width 0.14732)
		(layer "In4.Cu")
		(net "UPI_CPU1_CPU0_P1P0_DP<3>")
	)
	(segment
		(start 233.656378 -197.207124)
		(end 235.95965 -197.887844)
		(width 0.14732)
		(layer "In4.Cu")
		(net "UPI_CPU1_CPU0_P1P0_DP<3>")
	)
	(segment
		(start 340.129876 -215.762586)
		(end 340.133178 -215.764618)
		(width 0.0889)
		(layer "In4.Cu")
		(net "UPI_CPU1_CPU0_P1P0_DP<3>")
	)
	(segment
		(start 132.591048 -213.113112)
		(end 132.687568 -213.113112)
		(width 0.0889)
		(layer "In4.Cu")
		(net "UPI_CPU1_CPU0_P1P0_DP<3>")
	)
	(segment
		(start 340.038944 -212.762338)
		(end 339.939884 -212.861398)
		(width 0.0889)
		(layer "In4.Cu")
		(net "UPI_CPU1_CPU0_P1P0_DP<3>")
	)
	(segment
		(start 339.982048 -212.060028)
		(end 339.939884 -212.102192)
		(width 0.0889)
		(layer "In4.Cu")
		(net "UPI_CPU1_CPU0_P1P0_DP<3>")
	)
	(segment
		(start 312.034174 -185.99658)
		(end 313.116214 -186.32805)
		(width 0.14732)
		(layer "In4.Cu")
		(net "UPI_CPU1_CPU0_P1P0_DP<3>")
	)
	(segment
		(start 341.41156 -205.542388)
		(end 341.41156 -207.875886)
		(width 0.14732)
		(layer "In4.Cu")
		(net "UPI_CPU1_CPU0_P1P0_DP<3>")
	)
	(segment
		(start 340.038944 -213.135718)
		(end 340.038944 -213.310978)
		(width 0.0889)
		(layer "In4.Cu")
		(net "UPI_CPU1_CPU0_P1P0_DP<3>")
	)
	(segment
		(start 340.125558 -215.7603)
		(end 340.127082 -215.761062)
		(width 0.0889)
		(layer "In4.Cu")
		(net "UPI_CPU1_CPU0_P1P0_DP<3>")
	)
	(segment
		(start 263.273032 -188.392816)
		(end 264.540492 -187.691268)
		(width 0.14732)
		(layer "In4.Cu")
		(net "UPI_CPU1_CPU0_P1P0_DP<3>")
	)
	(segment
		(start 340.038944 -212.587078)
		(end 340.038944 -212.762338)
		(width 0.0889)
		(layer "In4.Cu")
		(net "UPI_CPU1_CPU0_P1P0_DP<3>")
	)
	(segment
		(start 339.939884 -217.0557)
		(end 339.939884 -217.072972)
		(width 0.0889)
		(layer "In4.Cu")
		(net "UPI_CPU1_CPU0_P1P0_DP<3>")
	)
	(segment
		(start 135.175752 -210.564984)
		(end 135.175498 -210.564984)
		(width 0.14732)
		(layer "In4.Cu")
		(net "UPI_CPU1_CPU0_P1P0_DP<3>")
	)
	(segment
		(start 340.127082 -215.112346)
		(end 340.126066 -215.112854)
		(width 0.0889)
		(layer "In4.Cu")
		(net "UPI_CPU1_CPU0_P1P0_DP<3>")
	)
	(segment
		(start 215.27262 -186.722258)
		(end 223.391222 -190.55842)
		(width 0.14732)
		(layer "In4.Cu")
		(net "UPI_CPU1_CPU0_P1P0_DP<3>")
	)
	(segment
		(start 340.126066 -215.112854)
		(end 340.118192 -215.117426)
		(width 0.0889)
		(layer "In4.Cu")
		(net "UPI_CPU1_CPU0_P1P0_DP<3>")
	)
	(segment
		(start 340.127082 -215.761062)
		(end 340.129876 -215.762586)
		(width 0.0889)
		(layer "In4.Cu")
		(net "UPI_CPU1_CPU0_P1P0_DP<3>")
	)
	(segment
		(start 340.157816 -217.335354)
		(end 340.31428 -217.064336)
		(width 0.0889)
		(layer "In4.Cu")
		(net "UPI_CPU1_CPU0_P1P0_DP<3>")
	)
	(segment
		(start 340.079838 -217.356182)
		(end 340.157816 -217.335354)
		(width 0.0889)
		(layer "In4.Cu")
		(net "UPI_CPU1_CPU0_P1P0_DP<3>")
	)
	(segment
		(start 133.71449 -212.026246)
		(end 133.729984 -212.010752)
		(width 0.0889)
		(layer "In4.Cu")
		(net "UPI_CPU1_CPU0_P1P0_DP<3>")
	)
	(segment
		(start 261.761478 -189.229492)
		(end 261.819136 -189.029594)
		(width 0.14732)
		(layer "In4.Cu")
		(net "UPI_CPU1_CPU0_P1P0_DP<3>")
	)
	(segment
		(start 237.232444 -197.887844)
		(end 238.429038 -197.737984)
		(width 0.14732)
		(layer "In4.Cu")
		(net "UPI_CPU1_CPU0_P1P0_DP<3>")
	)
	(segment
		(start 151.931624 -192.431416)
		(end 157.849824 -187.791852)
		(width 0.14732)
		(layer "In4.Cu")
		(net "UPI_CPU1_CPU0_P1P0_DP<3>")
	)
	(segment
		(start 133.729984 -212.010752)
		(end 135.175752 -210.564984)
		(width 0.14732)
		(layer "In4.Cu")
		(net "UPI_CPU1_CPU0_P1P0_DP<3>")
	)
	(segment
		(start 263.07288 -188.335158)
		(end 263.273032 -188.392816)
		(width 0.14732)
		(layer "In4.Cu")
		(net "UPI_CPU1_CPU0_P1P0_DP<3>")
	)
	(segment
		(start 223.391222 -190.55842)
		(end 233.656378 -197.207124)
		(width 0.14732)
		(layer "In4.Cu")
		(net "UPI_CPU1_CPU0_P1P0_DP<3>")
	)
	(segment
		(start 132.502656 -214.946992)
		(end 132.511546 -214.941912)
		(width 0.0889)
		(layer "In4.Cu")
		(net "UPI_CPU1_CPU0_P1P0_DP<3>")
	)
	(segment
		(start 339.939884 -212.488018)
		(end 340.038944 -212.587078)
		(width 0.0889)
		(layer "In4.Cu")
		(net "UPI_CPU1_CPU0_P1P0_DP<3>")
	)
	(segment
		(start 131.09321 -215.761062)
		(end 131.1021 -215.755982)
		(width 0.0889)
		(layer "In4.Cu")
		(net "UPI_CPU1_CPU0_P1P0_DP<3>")
	)
	(arc
		(start 132.12826 -214.946992)
		(mid 132.315458 -214.997135)
		(end 132.502656 -214.946992)
		(width 0.0889)
		(layer "In4.Cu")
		(net "UPI_CPU1_CPU0_P1P0_DP<3>")
	)
	(arc
		(start 131.021582 -218.319096)
		(mid 130.8695 -218.129664)
		(end 130.811016 -217.8939)
		(width 0.0889)
		(layer "In4.Cu")
		(net "UPI_CPU1_CPU0_P1P0_DP<3>")
	)
	(arc
		(start 131.093464 -217.388694)
		(mid 131.228397 -217.25534)
		(end 131.280662 -217.072972)
		(width 0.0889)
		(layer "In4.Cu")
		(net "UPI_CPU1_CPU0_P1P0_DP<3>")
	)
	(arc
		(start 340.409276 -214.644732)
		(mid 340.328365 -214.91486)
		(end 340.127082 -215.112346)
		(width 0.0889)
		(layer "In4.Cu")
		(net "UPI_CPU1_CPU0_P1P0_DP<3>")
	)
	(arc
		(start 132.689854 -214.637366)
		(mid 132.690051 -214.630001)
		(end 132.690108 -214.622634)
		(width 0.0889)
		(layer "In4.Cu")
		(net "UPI_CPU1_CPU0_P1P0_DP<3>")
	)
	(arc
		(start 131.280662 -215.414606)
		(mid 131.361573 -215.144478)
		(end 131.562856 -214.946992)
		(width 0.0889)
		(layer "In4.Cu")
		(net "UPI_CPU1_CPU0_P1P0_DP<3>")
	)
	(arc
		(start 339.939884 -217.072972)
		(mid 339.978558 -217.23004)
		(end 340.079838 -217.356182)
		(width 0.0889)
		(layer "In4.Cu")
		(net "UPI_CPU1_CPU0_P1P0_DP<3>")
	)
	(arc
		(start 339.939884 -213.893908)
		(mid 340.014889 -214.009367)
		(end 340.124034 -214.093298)
		(width 0.0889)
		(layer "In4.Cu")
		(net "UPI_CPU1_CPU0_P1P0_DP<3>")
	)
	(arc
		(start 339.93963 -215.436704)
		(mid 339.987309 -215.619604)
		(end 340.118192 -215.755982)
		(width 0.0889)
		(layer "In4.Cu")
		(net "UPI_CPU1_CPU0_P1P0_DP<3>")
	)
	(arc
		(start 130.811016 -217.859864)
		(mid 130.891178 -217.587675)
		(end 131.093464 -217.388694)
		(width 0.0889)
		(layer "In4.Cu")
		(net "UPI_CPU1_CPU0_P1P0_DP<3>")
	)
	(arc
		(start 132.511546 -214.941912)
		(mid 132.6388 -214.811946)
		(end 132.689854 -214.637366)
		(width 0.0889)
		(layer "In4.Cu")
		(net "UPI_CPU1_CPU0_P1P0_DP<3>")
	)
	(arc
		(start 131.280662 -217.0557)
		(mid 131.228392 -216.873335)
		(end 131.093464 -216.739978)
		(width 0.0889)
		(layer "In4.Cu")
		(net "UPI_CPU1_CPU0_P1P0_DP<3>")
	)
	(arc
		(start 131.093464 -216.739978)
		(mid 130.810932 -216.25063)
		(end 131.09321 -215.761062)
		(width 0.0889)
		(layer "In4.Cu")
		(net "UPI_CPU1_CPU0_P1P0_DP<3>")
	)
	(arc
		(start 132.690108 -214.461344)
		(mid 132.615103 -214.345885)
		(end 132.505958 -214.261954)
		(width 0.0889)
		(layer "In4.Cu")
		(net "UPI_CPU1_CPU0_P1P0_DP<3>")
	)
	(arc
		(start 131.562856 -214.946992)
		(mid 131.837085 -214.871067)
		(end 132.113528 -214.938356)
		(width 0.0889)
		(layer "In4.Cu")
		(net "UPI_CPU1_CPU0_P1P0_DP<3>")
	)
	(arc
		(start 131.1021 -215.755982)
		(mid 131.233014 -215.619622)
		(end 131.280662 -215.436704)
		(width 0.0889)
		(layer "In4.Cu")
		(net "UPI_CPU1_CPU0_P1P0_DP<3>")
	)
	(arc
		(start 340.133178 -215.764618)
		(mid 340.409752 -216.25052)
		(end 340.133178 -216.736422)
		(width 0.0889)
		(layer "In4.Cu")
		(net "UPI_CPU1_CPU0_P1P0_DP<3>")
	)
	(arc
		(start 132.235956 -213.969346)
		(mid 132.227993 -213.950049)
		(end 132.220716 -213.930484)
		(width 0.0889)
		(layer "In4.Cu")
		(net "UPI_CPU1_CPU0_P1P0_DP<3>")
	)
	(arc
		(start 340.127082 -216.739978)
		(mid 339.992149 -216.873332)
		(end 339.939884 -217.0557)
		(width 0.0889)
		(layer "In4.Cu")
		(net "UPI_CPU1_CPU0_P1P0_DP<3>")
	)
	(arc
		(start 340.118192 -215.117426)
		(mid 339.990938 -215.247392)
		(end 339.939884 -215.421972)
		(width 0.0889)
		(layer "In4.Cu")
		(net "UPI_CPU1_CPU0_P1P0_DP<3>")
	)
	(arc
		(start 131.038346 -218.33205)
		(mid 131.029905 -218.32565)
		(end 131.021582 -218.319096)
		(width 0.0889)
		(layer "In4.Cu")
		(net "UPI_CPU1_CPU0_P1P0_DP<3>")
	)
	(arc
		(start 340.124034 -214.093298)
		(mid 340.297997 -214.232062)
		(end 340.409276 -214.424768)
		(width 0.0889)
		(layer "In4.Cu")
		(net "UPI_CPU1_CPU0_P1P0_DP<3>")
	)
	(arc
		(start 132.505958 -214.261954)
		(mid 132.345886 -214.138774)
		(end 132.235956 -213.969346)
		(width 0.0889)
		(layer "In4.Cu")
		(net "UPI_CPU1_CPU0_P1P0_DP<3>")
	)
	(arc
		(start 339.939884 -215.421972)
		(mid 339.939687 -215.429337)
		(end 339.93963 -215.436704)
		(width 0.0889)
		(layer "In4.Cu")
		(net "UPI_CPU1_CPU0_P1P0_DP<3>")
	)
	(segment
		(start 131.846066 -217.600276)
		(end 131.846066 -217.06459)
		(width 0.13208)
		(layer "F.Cu")
		(net "UPI_CPU1_CPU0_P1P0_DP<2>")
	)
	(segment
		(start 339.374734 -219.228162)
		(end 339.374734 -218.692476)
		(width 0.13208)
		(layer "F.Cu")
		(net "UPI_CPU1_CPU0_P1P0_DP<2>")
	)
	(segment
		(start 131.846066 -217.06459)
		(end 131.845812 -217.064336)
		(width 0.13208)
		(layer "F.Cu")
		(net "UPI_CPU1_CPU0_P1P0_DP<2>")
	)
	(segment
		(start 339.374734 -218.692476)
		(end 339.37448 -218.692222)
		(width 0.13208)
		(layer "F.Cu")
		(net "UPI_CPU1_CPU0_P1P0_DP<2>")
	)
	(segment
		(start 339.04174 -209.0166)
		(end 340.55812 -207.50022)
		(width 0.14732)
		(layer "In4.Cu")
		(net "UPI_CPU1_CPU0_P1P0_DP<2>")
	)
	(segment
		(start 200.17867 -186.881008)
		(end 159.91078 -187.572396)
		(width 0.14732)
		(layer "In4.Cu")
		(net "UPI_CPU1_CPU0_P1P0_DP<2>")
	)
	(segment
		(start 132.080508 -217.356182)
		(end 132.002276 -217.335354)
		(width 0.0889)
		(layer "In4.Cu")
		(net "UPI_CPU1_CPU0_P1P0_DP<2>")
	)
	(segment
		(start 299.03547 -187.075064)
		(end 299.06087 -187.99048)
		(width 0.14732)
		(layer "In4.Cu")
		(net "UPI_CPU1_CPU0_P1P0_DP<2>")
	)
	(segment
		(start 223.372172 -191.594994)
		(end 215.0745 -187.673742)
		(width 0.14732)
		(layer "In4.Cu")
		(net "UPI_CPU1_CPU0_P1P0_DP<2>")
	)
	(segment
		(start 339.184234 -216.74201)
		(end 339.186774 -216.740486)
		(width 0.0889)
		(layer "In4.Cu")
		(net "UPI_CPU1_CPU0_P1P0_DP<2>")
	)
	(segment
		(start 133.160262 -215.414606)
		(end 133.160262 -215.436704)
		(width 0.0889)
		(layer "In4.Cu")
		(net "UPI_CPU1_CPU0_P1P0_DP<2>")
	)
	(segment
		(start 132.034026 -216.740486)
		(end 132.0419 -216.745058)
		(width 0.0889)
		(layer "In4.Cu")
		(net "UPI_CPU1_CPU0_P1P0_DP<2>")
	)
	(segment
		(start 339.187282 -215.761062)
		(end 339.185758 -215.7603)
		(width 0.0889)
		(layer "In4.Cu")
		(net "UPI_CPU1_CPU0_P1P0_DP<2>")
	)
	(segment
		(start 131.750816 -216.235026)
		(end 131.750816 -216.266014)
		(width 0.0889)
		(layer "In4.Cu")
		(net "UPI_CPU1_CPU0_P1P0_DP<2>")
	)
	(segment
		(start 294.291512 -187.854336)
		(end 293.701216 -187.870846)
		(width 0.14732)
		(layer "In4.Cu")
		(net "UPI_CPU1_CPU0_P1P0_DP<2>")
	)
	(segment
		(start 271.73682 -187.815982)
		(end 268.900656 -190.029846)
		(width 0.14732)
		(layer "In4.Cu")
		(net "UPI_CPU1_CPU0_P1P0_DP<2>")
	)
	(segment
		(start 298.327826 -188.15812)
		(end 298.17695 -188.015372)
		(width 0.14732)
		(layer "In4.Cu")
		(net "UPI_CPU1_CPU0_P1P0_DP<2>")
	)
	(segment
		(start 339.041994 -211.801202)
		(end 339.04174 -211.800948)
		(width 0.14732)
		(layer "In4.Cu")
		(net "UPI_CPU1_CPU0_P1P0_DP<2>")
	)
	(segment
		(start 260.992112 -190.592202)
		(end 249.803412 -193.564256)
		(width 0.14732)
		(layer "In4.Cu")
		(net "UPI_CPU1_CPU0_P1P0_DP<2>")
	)
	(segment
		(start 293.53637 -187.227464)
		(end 293.22014 -186.928252)
		(width 0.14732)
		(layer "In4.Cu")
		(net "UPI_CPU1_CPU0_P1P0_DP<2>")
	)
	(segment
		(start 339.04174 -211.800948)
		(end 339.04174 -209.0166)
		(width 0.14732)
		(layer "In4.Cu")
		(net "UPI_CPU1_CPU0_P1P0_DP<2>")
	)
	(segment
		(start 237.291626 -198.832724)
		(end 236.11459 -198.832724)
		(width 0.14732)
		(layer "In4.Cu")
		(net "UPI_CPU1_CPU0_P1P0_DP<2>")
	)
	(segment
		(start 238.665766 -198.660766)
		(end 237.291626 -198.832724)
		(width 0.14732)
		(layer "In4.Cu")
		(net "UPI_CPU1_CPU0_P1P0_DP<2>")
	)
	(segment
		(start 318.977518 -192.101724)
		(end 312.725308 -187.076588)
		(width 0.14732)
		(layer "In4.Cu")
		(net "UPI_CPU1_CPU0_P1P0_DP<2>")
	)
	(segment
		(start 249.803412 -193.564256)
		(end 238.665766 -198.660766)
		(width 0.14732)
		(layer "In4.Cu")
		(net "UPI_CPU1_CPU0_P1P0_DP<2>")
	)
	(segment
		(start 158.706312 -188.29147)
		(end 152.56764 -194.429888)
		(width 0.14732)
		(layer "In4.Cu")
		(net "UPI_CPU1_CPU0_P1P0_DP<2>")
	)
	(segment
		(start 299.334936 -186.758834)
		(end 299.03547 -187.075064)
		(width 0.14732)
		(layer "In4.Cu")
		(net "UPI_CPU1_CPU0_P1P0_DP<2>")
	)
	(segment
		(start 339.469984 -217.878406)
		(end 339.469984 -217.859864)
		(width 0.0889)
		(layer "In4.Cu")
		(net "UPI_CPU1_CPU0_P1P0_DP<2>")
	)
	(segment
		(start 299.06087 -187.99048)
		(end 298.918122 -188.14161)
		(width 0.14732)
		(layer "In4.Cu")
		(net "UPI_CPU1_CPU0_P1P0_DP<2>")
	)
	(segment
		(start 133.90626 -213.151212)
		(end 133.630416 -213.427056)
		(width 0.0889)
		(layer "In4.Cu")
		(net "UPI_CPU1_CPU0_P1P0_DP<2>")
	)
	(segment
		(start 291.21989 -187.29198)
		(end 290.90366 -186.992768)
		(width 0.14732)
		(layer "In4.Cu")
		(net "UPI_CPU1_CPU0_P1P0_DP<2>")
	)
	(segment
		(start 338.99983 -212.102192)
		(end 339.041994 -212.060028)
		(width 0.0889)
		(layer "In4.Cu")
		(net "UPI_CPU1_CPU0_P1P0_DP<2>")
	)
	(segment
		(start 338.99983 -213.8934)
		(end 338.99983 -212.102192)
		(width 0.0889)
		(layer "In4.Cu")
		(net "UPI_CPU1_CPU0_P1P0_DP<2>")
	)
	(segment
		(start 339.37448 -218.692222)
		(end 339.218016 -218.421204)
		(width 0.0889)
		(layer "In4.Cu")
		(net "UPI_CPU1_CPU0_P1P0_DP<2>")
	)
	(segment
		(start 332.164436 -196.66712)
		(end 318.977518 -192.101724)
		(width 0.14732)
		(layer "In4.Cu")
		(net "UPI_CPU1_CPU0_P1P0_DP<2>")
	)
	(segment
		(start 215.0745 -187.673742)
		(end 211.219288 -187.437268)
		(width 0.14732)
		(layer "In4.Cu")
		(net "UPI_CPU1_CPU0_P1P0_DP<2>")
	)
	(segment
		(start 294.43426 -187.703206)
		(end 294.291512 -187.854336)
		(width 0.14732)
		(layer "In4.Cu")
		(net "UPI_CPU1_CPU0_P1P0_DP<2>")
	)
	(segment
		(start 148.61667 -196.089016)
		(end 143.980408 -200.380092)
		(width 0.14732)
		(layer "In4.Cu")
		(net "UPI_CPU1_CPU0_P1P0_DP<2>")
	)
	(segment
		(start 132.9817 -215.755982)
		(end 132.97281 -215.761062)
		(width 0.0889)
		(layer "In4.Cu")
		(net "UPI_CPU1_CPU0_P1P0_DP<2>")
	)
	(segment
		(start 339.469476 -214.644732)
		(end 339.469476 -214.424768)
		(width 0.0889)
		(layer "In4.Cu")
		(net "UPI_CPU1_CPU0_P1P0_DP<2>")
	)
	(segment
		(start 339.000084 -213.893908)
		(end 338.99983 -213.8934)
		(width 0.0889)
		(layer "In4.Cu")
		(net "UPI_CPU1_CPU0_P1P0_DP<2>")
	)
	(segment
		(start 268.5542 -190.156846)
		(end 267.4493 -190.322454)
		(width 0.14732)
		(layer "In4.Cu")
		(net "UPI_CPU1_CPU0_P1P0_DP<2>")
	)
	(segment
		(start 339.218016 -218.421204)
		(end 339.242146 -218.33205)
		(width 0.0889)
		(layer "In4.Cu")
		(net "UPI_CPU1_CPU0_P1P0_DP<2>")
	)
	(segment
		(start 311.955688 -186.846718)
		(end 302.452024 -186.672728)
		(width 0.14732)
		(layer "In4.Cu")
		(net "UPI_CPU1_CPU0_P1P0_DP<2>")
	)
	(segment
		(start 291.23386 -187.792614)
		(end 291.21989 -187.29198)
		(width 0.14732)
		(layer "In4.Cu")
		(net "UPI_CPU1_CPU0_P1P0_DP<2>")
	)
	(segment
		(start 291.384736 -187.935362)
		(end 291.23386 -187.792614)
		(width 0.14732)
		(layer "In4.Cu")
		(net "UPI_CPU1_CPU0_P1P0_DP<2>")
	)
	(segment
		(start 267.4493 -190.322454)
		(end 260.992112 -190.592202)
		(width 0.14732)
		(layer "In4.Cu")
		(net "UPI_CPU1_CPU0_P1P0_DP<2>")
	)
	(segment
		(start 339.193378 -215.764618)
		(end 339.190076 -215.762586)
		(width 0.0889)
		(layer "In4.Cu")
		(net "UPI_CPU1_CPU0_P1P0_DP<2>")
	)
	(segment
		(start 133.474714 -214.92845)
		(end 133.442456 -214.946992)
		(width 0.0889)
		(layer "In4.Cu")
		(net "UPI_CPU1_CPU0_P1P0_DP<2>")
	)
	(segment
		(start 339.178392 -215.117426)
		(end 339.186266 -215.112854)
		(width 0.0889)
		(layer "In4.Cu")
		(net "UPI_CPU1_CPU0_P1P0_DP<2>")
	)
	(segment
		(start 298.15155 -187.099956)
		(end 297.83532 -186.80049)
		(width 0.14732)
		(layer "In4.Cu")
		(net "UPI_CPU1_CPU0_P1P0_DP<2>")
	)
	(segment
		(start 302.452024 -186.672728)
		(end 299.334936 -186.758834)
		(width 0.14732)
		(layer "In4.Cu")
		(net "UPI_CPU1_CPU0_P1P0_DP<2>")
	)
	(segment
		(start 133.921754 -213.075774)
		(end 133.90626 -213.091268)
		(width 0.0889)
		(layer "In4.Cu")
		(net "UPI_CPU1_CPU0_P1P0_DP<2>")
	)
	(segment
		(start 137.705084 -209.292444)
		(end 135.14705 -211.850732)
		(width 0.14732)
		(layer "In4.Cu")
		(net "UPI_CPU1_CPU0_P1P0_DP<2>")
	)
	(segment
		(start 293.55034 -187.728098)
		(end 293.53637 -187.227464)
		(width 0.14732)
		(layer "In4.Cu")
		(net "UPI_CPU1_CPU0_P1P0_DP<2>")
	)
	(segment
		(start 135.14705 -211.850732)
		(end 135.146796 -211.850732)
		(width 0.14732)
		(layer "In4.Cu")
		(net "UPI_CPU1_CPU0_P1P0_DP<2>")
	)
	(segment
		(start 298.17695 -188.015372)
		(end 298.15155 -187.099956)
		(width 0.14732)
		(layer "In4.Cu")
		(net "UPI_CPU1_CPU0_P1P0_DP<2>")
	)
	(segment
		(start 312.725308 -187.076588)
		(end 311.955688 -186.846718)
		(width 0.14732)
		(layer "In4.Cu")
		(net "UPI_CPU1_CPU0_P1P0_DP<2>")
	)
	(segment
		(start 292.10381 -187.267342)
		(end 292.11778 -187.767722)
		(width 0.14732)
		(layer "In4.Cu")
		(net "UPI_CPU1_CPU0_P1P0_DP<2>")
	)
	(segment
		(start 293.22014 -186.928252)
		(end 292.403022 -186.951112)
		(width 0.14732)
		(layer "In4.Cu")
		(net "UPI_CPU1_CPU0_P1P0_DP<2>")
	)
	(segment
		(start 292.11778 -187.767722)
		(end 291.975032 -187.918852)
		(width 0.14732)
		(layer "In4.Cu")
		(net "UPI_CPU1_CPU0_P1P0_DP<2>")
	)
	(segment
		(start 132.03301 -216.739978)
		(end 132.034026 -216.740486)
		(width 0.0889)
		(layer "In4.Cu")
		(net "UPI_CPU1_CPU0_P1P0_DP<2>")
	)
	(segment
		(start 236.11459 -198.832724)
		(end 233.23042 -197.980046)
		(width 0.14732)
		(layer "In4.Cu")
		(net "UPI_CPU1_CPU0_P1P0_DP<2>")
	)
	(segment
		(start 152.56764 -194.429888)
		(end 148.61667 -196.089016)
		(width 0.14732)
		(layer "In4.Cu")
		(net "UPI_CPU1_CPU0_P1P0_DP<2>")
	)
	(segment
		(start 339.187536 -217.388694)
		(end 339.178646 -217.383614)
		(width 0.0889)
		(layer "In4.Cu")
		(net "UPI_CPU1_CPU0_P1P0_DP<2>")
	)
	(segment
		(start 135.146796 -211.850732)
		(end 133.921754 -213.075774)
		(width 0.14732)
		(layer "In4.Cu")
		(net "UPI_CPU1_CPU0_P1P0_DP<2>")
	)
	(segment
		(start 268.900656 -190.029846)
		(end 268.5542 -190.156846)
		(width 0.14732)
		(layer "In4.Cu")
		(net "UPI_CPU1_CPU0_P1P0_DP<2>")
	)
	(segment
		(start 233.23042 -197.980046)
		(end 223.372172 -191.594994)
		(width 0.14732)
		(layer "In4.Cu")
		(net "UPI_CPU1_CPU0_P1P0_DP<2>")
	)
	(segment
		(start 294.719756 -186.886596)
		(end 294.42029 -187.202826)
		(width 0.14732)
		(layer "In4.Cu")
		(net "UPI_CPU1_CPU0_P1P0_DP<2>")
	)
	(segment
		(start 340.55812 -205.646528)
		(end 339.849206 -203.934822)
		(width 0.14732)
		(layer "In4.Cu")
		(net "UPI_CPU1_CPU0_P1P0_DP<2>")
	)
	(segment
		(start 339.041994 -212.060028)
		(end 339.041994 -212.03793)
		(width 0.0889)
		(layer "In4.Cu")
		(net "UPI_CPU1_CPU0_P1P0_DP<2>")
	)
	(segment
		(start 339.185758 -215.7603)
		(end 339.178392 -215.755982)
		(width 0.0889)
		(layer "In4.Cu")
		(net "UPI_CPU1_CPU0_P1P0_DP<2>")
	)
	(segment
		(start 339.849206 -203.934822)
		(end 334.119982 -198.205344)
		(width 0.14732)
		(layer "In4.Cu")
		(net "UPI_CPU1_CPU0_P1P0_DP<2>")
	)
	(segment
		(start 339.186266 -215.112854)
		(end 339.187282 -215.112346)
		(width 0.0889)
		(layer "In4.Cu")
		(net "UPI_CPU1_CPU0_P1P0_DP<2>")
	)
	(segment
		(start 292.403022 -186.951112)
		(end 292.10381 -187.267342)
		(width 0.14732)
		(layer "In4.Cu")
		(net "UPI_CPU1_CPU0_P1P0_DP<2>")
	)
	(segment
		(start 340.55812 -207.50022)
		(end 340.55812 -205.646528)
		(width 0.14732)
		(layer "In4.Cu")
		(net "UPI_CPU1_CPU0_P1P0_DP<2>")
	)
	(segment
		(start 298.918122 -188.14161)
		(end 298.327826 -188.15812)
		(width 0.14732)
		(layer "In4.Cu")
		(net "UPI_CPU1_CPU0_P1P0_DP<2>")
	)
	(segment
		(start 273.00555 -187.489846)
		(end 271.73682 -187.815982)
		(width 0.14732)
		(layer "In4.Cu")
		(net "UPI_CPU1_CPU0_P1P0_DP<2>")
	)
	(segment
		(start 291.975032 -187.918852)
		(end 291.384736 -187.935362)
		(width 0.14732)
		(layer "In4.Cu")
		(net "UPI_CPU1_CPU0_P1P0_DP<2>")
	)
	(segment
		(start 297.83532 -186.80049)
		(end 294.719756 -186.886596)
		(width 0.14732)
		(layer "In4.Cu")
		(net "UPI_CPU1_CPU0_P1P0_DP<2>")
	)
	(segment
		(start 159.91078 -187.572396)
		(end 158.706312 -188.29147)
		(width 0.14732)
		(layer "In4.Cu")
		(net "UPI_CPU1_CPU0_P1P0_DP<2>")
	)
	(segment
		(start 339.469984 -216.260426)
		(end 339.469984 -216.25052)
		(width 0.0889)
		(layer "In4.Cu")
		(net "UPI_CPU1_CPU0_P1P0_DP<2>")
	)
	(segment
		(start 339.178646 -216.745058)
		(end 339.184234 -216.74201)
		(width 0.0889)
		(layer "In4.Cu")
		(net "UPI_CPU1_CPU0_P1P0_DP<2>")
	)
	(segment
		(start 132.598414 -215.761062)
		(end 132.583682 -215.752426)
		(width 0.0889)
		(layer "In4.Cu")
		(net "UPI_CPU1_CPU0_P1P0_DP<2>")
	)
	(segment
		(start 133.630416 -213.427056)
		(end 133.630416 -214.592408)
		(width 0.0889)
		(layer "In4.Cu")
		(net "UPI_CPU1_CPU0_P1P0_DP<2>")
	)
	(segment
		(start 334.119982 -198.205344)
		(end 332.164436 -196.66712)
		(width 0.14732)
		(layer "In4.Cu")
		(net "UPI_CPU1_CPU0_P1P0_DP<2>")
	)
	(segment
		(start 132.002276 -217.335354)
		(end 131.845812 -217.064336)
		(width 0.0889)
		(layer "In4.Cu")
		(net "UPI_CPU1_CPU0_P1P0_DP<2>")
	)
	(segment
		(start 339.041994 -212.03793)
		(end 339.041994 -211.801202)
		(width 0.14732)
		(layer "In4.Cu")
		(net "UPI_CPU1_CPU0_P1P0_DP<2>")
	)
	(segment
		(start 339.186774 -216.740486)
		(end 339.187536 -216.739978)
		(width 0.0889)
		(layer "In4.Cu")
		(net "UPI_CPU1_CPU0_P1P0_DP<2>")
	)
	(segment
		(start 211.219288 -187.437268)
		(end 207.791304 -187.67171)
		(width 0.14732)
		(layer "In4.Cu")
		(net "UPI_CPU1_CPU0_P1P0_DP<2>")
	)
	(segment
		(start 133.90626 -213.091268)
		(end 133.90626 -213.151212)
		(width 0.0889)
		(layer "In4.Cu")
		(net "UPI_CPU1_CPU0_P1P0_DP<2>")
	)
	(segment
		(start 207.791304 -187.67171)
		(end 200.17867 -186.881008)
		(width 0.14732)
		(layer "In4.Cu")
		(net "UPI_CPU1_CPU0_P1P0_DP<2>")
	)
	(segment
		(start 143.980408 -200.380092)
		(end 137.705084 -209.292444)
		(width 0.14732)
		(layer "In4.Cu")
		(net "UPI_CPU1_CPU0_P1P0_DP<2>")
	)
	(segment
		(start 290.90366 -186.992768)
		(end 273.00555 -187.489846)
		(width 0.14732)
		(layer "In4.Cu")
		(net "UPI_CPU1_CPU0_P1P0_DP<2>")
	)
	(segment
		(start 339.190076 -215.762586)
		(end 339.187282 -215.761062)
		(width 0.0889)
		(layer "In4.Cu")
		(net "UPI_CPU1_CPU0_P1P0_DP<2>")
	)
	(segment
		(start 294.42029 -187.202826)
		(end 294.43426 -187.703206)
		(width 0.14732)
		(layer "In4.Cu")
		(net "UPI_CPU1_CPU0_P1P0_DP<2>")
	)
	(segment
		(start 293.701216 -187.870846)
		(end 293.55034 -187.728098)
		(width 0.14732)
		(layer "In4.Cu")
		(net "UPI_CPU1_CPU0_P1P0_DP<2>")
	)
	(arc
		(start 339.178392 -215.755982)
		(mid 339.047478 -215.619622)
		(end 338.99983 -215.436704)
		(width 0.0889)
		(layer "In4.Cu")
		(net "UPI_CPU1_CPU0_P1P0_DP<2>")
	)
	(arc
		(start 339.187282 -215.112346)
		(mid 339.388564 -214.914859)
		(end 339.469476 -214.644732)
		(width 0.0889)
		(layer "In4.Cu")
		(net "UPI_CPU1_CPU0_P1P0_DP<2>")
	)
	(arc
		(start 133.630416 -214.592408)
		(mid 133.596742 -214.780893)
		(end 133.474714 -214.92845)
		(width 0.0889)
		(layer "In4.Cu")
		(net "UPI_CPU1_CPU0_P1P0_DP<2>")
	)
	(arc
		(start 132.03301 -215.761062)
		(mid 131.830187 -215.961293)
		(end 131.750816 -216.235026)
		(width 0.0889)
		(layer "In4.Cu")
		(net "UPI_CPU1_CPU0_P1P0_DP<2>")
	)
	(arc
		(start 132.220462 -217.064336)
		(mid 132.183602 -217.226133)
		(end 132.080508 -217.356182)
		(width 0.0889)
		(layer "In4.Cu")
		(net "UPI_CPU1_CPU0_P1P0_DP<2>")
	)
	(arc
		(start 339.242146 -218.33205)
		(mid 339.250718 -218.325528)
		(end 339.259164 -218.318842)
		(width 0.0889)
		(layer "In4.Cu")
		(net "UPI_CPU1_CPU0_P1P0_DP<2>")
	)
	(arc
		(start 132.97281 -215.761062)
		(mid 132.785612 -215.811205)
		(end 132.598414 -215.761062)
		(width 0.0889)
		(layer "In4.Cu")
		(net "UPI_CPU1_CPU0_P1P0_DP<2>")
	)
	(arc
		(start 339.187536 -216.739978)
		(mid 339.391871 -216.537373)
		(end 339.469984 -216.260426)
		(width 0.0889)
		(layer "In4.Cu")
		(net "UPI_CPU1_CPU0_P1P0_DP<2>")
	)
	(arc
		(start 339.469984 -217.859864)
		(mid 339.389822 -217.587675)
		(end 339.187536 -217.388694)
		(width 0.0889)
		(layer "In4.Cu")
		(net "UPI_CPU1_CPU0_P1P0_DP<2>")
	)
	(arc
		(start 133.160262 -215.436704)
		(mid 133.112583 -215.619604)
		(end 132.9817 -215.755982)
		(width 0.0889)
		(layer "In4.Cu")
		(net "UPI_CPU1_CPU0_P1P0_DP<2>")
	)
	(arc
		(start 131.750816 -216.266014)
		(mid 131.830186 -216.539748)
		(end 132.03301 -216.739978)
		(width 0.0889)
		(layer "In4.Cu")
		(net "UPI_CPU1_CPU0_P1P0_DP<2>")
	)
	(arc
		(start 339.178646 -217.383614)
		(mid 339.000049 -217.064336)
		(end 339.178646 -216.745058)
		(width 0.0889)
		(layer "In4.Cu")
		(net "UPI_CPU1_CPU0_P1P0_DP<2>")
	)
	(arc
		(start 339.469984 -216.25052)
		(mid 339.395993 -215.970954)
		(end 339.193378 -215.764618)
		(width 0.0889)
		(layer "In4.Cu")
		(net "UPI_CPU1_CPU0_P1P0_DP<2>")
	)
	(arc
		(start 338.99983 -215.436704)
		(mid 338.999882 -215.429337)
		(end 339.000084 -215.421972)
		(width 0.0889)
		(layer "In4.Cu")
		(net "UPI_CPU1_CPU0_P1P0_DP<2>")
	)
	(arc
		(start 132.0419 -216.745058)
		(mid 132.172814 -216.881418)
		(end 132.220462 -217.064336)
		(width 0.0889)
		(layer "In4.Cu")
		(net "UPI_CPU1_CPU0_P1P0_DP<2>")
	)
	(arc
		(start 132.583682 -215.752426)
		(mid 132.307207 -215.685106)
		(end 132.03301 -215.761062)
		(width 0.0889)
		(layer "In4.Cu")
		(net "UPI_CPU1_CPU0_P1P0_DP<2>")
	)
	(arc
		(start 339.184234 -214.093298)
		(mid 339.075087 -214.00937)
		(end 339.000084 -213.893908)
		(width 0.0889)
		(layer "In4.Cu")
		(net "UPI_CPU1_CPU0_P1P0_DP<2>")
	)
	(arc
		(start 339.259164 -218.318842)
		(mid 339.414562 -218.122561)
		(end 339.469984 -217.878406)
		(width 0.0889)
		(layer "In4.Cu")
		(net "UPI_CPU1_CPU0_P1P0_DP<2>")
	)
	(arc
		(start 339.000084 -215.421972)
		(mid 339.051138 -215.247392)
		(end 339.178392 -215.117426)
		(width 0.0889)
		(layer "In4.Cu")
		(net "UPI_CPU1_CPU0_P1P0_DP<2>")
	)
	(arc
		(start 339.469476 -214.424768)
		(mid 339.358197 -214.232062)
		(end 339.184234 -214.093298)
		(width 0.0889)
		(layer "In4.Cu")
		(net "UPI_CPU1_CPU0_P1P0_DP<2>")
	)
	(arc
		(start 133.442456 -214.946992)
		(mid 133.241174 -215.144479)
		(end 133.160262 -215.414606)
		(width 0.0889)
		(layer "In4.Cu")
		(net "UPI_CPU1_CPU0_P1P0_DP<2>")
	)
	(segment
		(start 112.110266 -219.228162)
		(end 112.110266 -218.692476)
		(width 0.13208)
		(layer "F.Cu")
		(net "UPI_CPU1_CPU0_P1P0_DP<23>")
	)
	(segment
		(start 112.110266 -218.692476)
		(end 112.110012 -218.692222)
		(width 0.13208)
		(layer "F.Cu")
		(net "UPI_CPU1_CPU0_P1P0_DP<23>")
	)
	(segment
		(start 359.110534 -217.600276)
		(end 359.110534 -217.064336)
		(width 0.13208)
		(layer "F.Cu")
		(net "UPI_CPU1_CPU0_P1P0_DP<23>")
	)
	(segment
		(start 136.542018 -178.099974)
		(end 149.601428 -171.413678)
		(width 0.14732)
		(layer "In4.Cu")
		(net "UPI_CPU1_CPU0_P1P0_DP<23>")
	)
	(segment
		(start 359.304082 -213.293198)
		(end 359.304082 -213.468458)
		(width 0.0889)
		(layer "In4.Cu")
		(net "UPI_CPU1_CPU0_P1P0_DP<23>")
	)
	(segment
		(start 359.246932 -212.557868)
		(end 359.247186 -212.558122)
		(width 0.14732)
		(layer "In4.Cu")
		(net "UPI_CPU1_CPU0_P1P0_DP<23>")
	)
	(segment
		(start 273.025362 -169.42943)
		(end 302.461676 -168.712134)
		(width 0.14732)
		(layer "In4.Cu")
		(net "UPI_CPU1_CPU0_P1P0_DP<23>")
	)
	(segment
		(start 332.130146 -174.893224)
		(end 339.47354 -178.070002)
		(width 0.14732)
		(layer "In4.Cu")
		(net "UPI_CPU1_CPU0_P1P0_DP<23>")
	)
	(segment
		(start 302.47336 -168.712134)
		(end 314.080144 -168.928288)
		(width 0.14732)
		(layer "In4.Cu")
		(net "UPI_CPU1_CPU0_P1P0_DP<23>")
	)
	(segment
		(start 345.9353 -183.817768)
		(end 348.410022 -187.331858)
		(width 0.14732)
		(layer "In4.Cu")
		(net "UPI_CPU1_CPU0_P1P0_DP<23>")
	)
	(segment
		(start 314.080144 -168.928288)
		(end 319.45707 -170.430698)
		(width 0.14732)
		(layer "In4.Cu")
		(net "UPI_CPU1_CPU0_P1P0_DP<23>")
	)
	(segment
		(start 112.315752 -212.05063)
		(end 112.315752 -211.733638)
		(width 0.14732)
		(layer "In4.Cu")
		(net "UPI_CPU1_CPU0_P1P0_DP<23>")
	)
	(segment
		(start 111.545116 -217.086434)
		(end 111.545116 -217.05443)
		(width 0.0889)
		(layer "In4.Cu")
		(net "UPI_CPU1_CPU0_P1P0_DP<23>")
	)
	(segment
		(start 200.412096 -169.138854)
		(end 210.78698 -169.594276)
		(width 0.14732)
		(layer "In4.Cu")
		(net "UPI_CPU1_CPU0_P1P0_DP<23>")
	)
	(segment
		(start 124.144786 -189.181994)
		(end 132.346192 -183.731154)
		(width 0.14732)
		(layer "In4.Cu")
		(net "UPI_CPU1_CPU0_P1P0_DP<23>")
	)
	(segment
		(start 359.383838 -214.941912)
		(end 359.384346 -214.942674)
		(width 0.0889)
		(layer "In4.Cu")
		(net "UPI_CPU1_CPU0_P1P0_DP<23>")
	)
	(segment
		(start 359.304082 -214.017098)
		(end 359.205022 -214.116158)
		(width 0.0889)
		(layer "In4.Cu")
		(net "UPI_CPU1_CPU0_P1P0_DP<23>")
	)
	(segment
		(start 358.95407 -217.335354)
		(end 359.110534 -217.064336)
		(width 0.0889)
		(layer "In4.Cu")
		(net "UPI_CPU1_CPU0_P1P0_DP<23>")
	)
	(segment
		(start 359.304082 -213.468458)
		(end 359.205022 -213.567518)
		(width 0.0889)
		(layer "In4.Cu")
		(net "UPI_CPU1_CPU0_P1P0_DP<23>")
	)
	(segment
		(start 112.315752 -212.072728)
		(end 112.315752 -212.05063)
		(width 0.0889)
		(layer "In4.Cu")
		(net "UPI_CPU1_CPU0_P1P0_DP<23>")
	)
	(segment
		(start 210.78698 -169.594276)
		(end 238.595154 -169.594276)
		(width 0.14732)
		(layer "In4.Cu")
		(net "UPI_CPU1_CPU0_P1P0_DP<23>")
	)
	(segment
		(start 341.701882 -179.58435)
		(end 345.9353 -183.817768)
		(width 0.14732)
		(layer "In4.Cu")
		(net "UPI_CPU1_CPU0_P1P0_DP<23>")
	)
	(segment
		(start 358.875838 -217.356182)
		(end 358.95407 -217.335354)
		(width 0.0889)
		(layer "In4.Cu")
		(net "UPI_CPU1_CPU0_P1P0_DP<23>")
	)
	(segment
		(start 112.29721 -215.761062)
		(end 112.3061 -215.755982)
		(width 0.0889)
		(layer "In4.Cu")
		(net "UPI_CPU1_CPU0_P1P0_DP<23>")
	)
	(segment
		(start 112.266476 -218.421204)
		(end 112.242346 -218.33205)
		(width 0.0889)
		(layer "In4.Cu")
		(net "UPI_CPU1_CPU0_P1P0_DP<23>")
	)
	(segment
		(start 359.205022 -213.742778)
		(end 359.304082 -213.841838)
		(width 0.0889)
		(layer "In4.Cu")
		(net "UPI_CPU1_CPU0_P1P0_DP<23>")
	)
	(segment
		(start 149.601428 -171.413678)
		(end 155.57754 -169.884344)
		(width 0.14732)
		(layer "In4.Cu")
		(net "UPI_CPU1_CPU0_P1P0_DP<23>")
	)
	(segment
		(start 358.923336 -216.739978)
		(end 358.914446 -216.745058)
		(width 0.0889)
		(layer "In4.Cu")
		(net "UPI_CPU1_CPU0_P1P0_DP<23>")
	)
	(segment
		(start 302.467518 -168.71188)
		(end 302.473106 -168.71188)
		(width 0.14732)
		(layer "In4.Cu")
		(net "UPI_CPU1_CPU0_P1P0_DP<23>")
	)
	(segment
		(start 112.484662 -215.436704)
		(end 112.484662 -215.275922)
		(width 0.0889)
		(layer "In4.Cu")
		(net "UPI_CPU1_CPU0_P1P0_DP<23>")
	)
	(segment
		(start 354.893372 -193.976244)
		(end 359.246932 -204.487018)
		(width 0.14732)
		(layer "In4.Cu")
		(net "UPI_CPU1_CPU0_P1P0_DP<23>")
	)
	(segment
		(start 359.675176 -215.436704)
		(end 359.67543 -215.436704)
		(width 0.0889)
		(layer "In4.Cu")
		(net "UPI_CPU1_CPU0_P1P0_DP<23>")
	)
	(segment
		(start 155.57754 -169.884344)
		(end 200.412096 -169.138854)
		(width 0.14732)
		(layer "In4.Cu")
		(net "UPI_CPU1_CPU0_P1P0_DP<23>")
	)
	(segment
		(start 359.246932 -204.487018)
		(end 359.246932 -212.557868)
		(width 0.14732)
		(layer "In4.Cu")
		(net "UPI_CPU1_CPU0_P1P0_DP<23>")
	)
	(segment
		(start 112.014762 -214.745062)
		(end 112.014762 -214.44331)
		(width 0.0889)
		(layer "In4.Cu")
		(net "UPI_CPU1_CPU0_P1P0_DP<23>")
	)
	(segment
		(start 359.205022 -213.031324)
		(end 359.205022 -213.194138)
		(width 0.0889)
		(layer "In4.Cu")
		(net "UPI_CPU1_CPU0_P1P0_DP<23>")
	)
	(segment
		(start 339.47354 -178.070002)
		(end 341.701882 -179.58435)
		(width 0.14732)
		(layer "In4.Cu")
		(net "UPI_CPU1_CPU0_P1P0_DP<23>")
	)
	(segment
		(start 112.117378 -214.195152)
		(end 112.307116 -214.005414)
		(width 0.0889)
		(layer "In4.Cu")
		(net "UPI_CPU1_CPU0_P1P0_DP<23>")
	)
	(segment
		(start 359.205022 -214.62238)
		(end 359.205276 -214.622634)
		(width 0.0889)
		(layer "In4.Cu")
		(net "UPI_CPU1_CPU0_P1P0_DP<23>")
	)
	(segment
		(start 359.205022 -214.116158)
		(end 359.205022 -214.62238)
		(width 0.0889)
		(layer "In4.Cu")
		(net "UPI_CPU1_CPU0_P1P0_DP<23>")
	)
	(segment
		(start 117.233446 -197.685152)
		(end 124.144786 -189.181994)
		(width 0.14732)
		(layer "In4.Cu")
		(net "UPI_CPU1_CPU0_P1P0_DP<23>")
	)
	(segment
		(start 302.473106 -168.71188)
		(end 302.47336 -168.712134)
		(width 0.14732)
		(layer "In4.Cu")
		(net "UPI_CPU1_CPU0_P1P0_DP<23>")
	)
	(segment
		(start 359.393236 -215.926162)
		(end 359.384346 -215.931242)
		(width 0.0889)
		(layer "In4.Cu")
		(net "UPI_CPU1_CPU0_P1P0_DP<23>")
	)
	(segment
		(start 359.247186 -212.558122)
		(end 359.247186 -212.967062)
		(width 0.14732)
		(layer "In4.Cu")
		(net "UPI_CPU1_CPU0_P1P0_DP<23>")
	)
	(segment
		(start 359.247186 -212.98916)
		(end 359.205022 -213.031324)
		(width 0.0889)
		(layer "In4.Cu")
		(net "UPI_CPU1_CPU0_P1P0_DP<23>")
	)
	(segment
		(start 359.205784 -216.25052)
		(end 359.205784 -216.260426)
		(width 0.0889)
		(layer "In4.Cu")
		(net "UPI_CPU1_CPU0_P1P0_DP<23>")
	)
	(segment
		(start 238.595154 -169.594276)
		(end 273.025362 -169.42943)
		(width 0.14732)
		(layer "In4.Cu")
		(net "UPI_CPU1_CPU0_P1P0_DP<23>")
	)
	(segment
		(start 111.8362 -217.559128)
		(end 111.828326 -217.554556)
		(width 0.0889)
		(layer "In4.Cu")
		(net "UPI_CPU1_CPU0_P1P0_DP<23>")
	)
	(segment
		(start 319.45707 -170.430698)
		(end 332.130146 -174.893224)
		(width 0.14732)
		(layer "In4.Cu")
		(net "UPI_CPU1_CPU0_P1P0_DP<23>")
	)
	(segment
		(start 112.357662 -212.114638)
		(end 112.315752 -212.072728)
		(width 0.0889)
		(layer "In4.Cu")
		(net "UPI_CPU1_CPU0_P1P0_DP<23>")
	)
	(segment
		(start 359.247186 -212.967062)
		(end 359.247186 -212.98916)
		(width 0.0889)
		(layer "In4.Cu")
		(net "UPI_CPU1_CPU0_P1P0_DP<23>")
	)
	(segment
		(start 359.205022 -213.194138)
		(end 359.304082 -213.293198)
		(width 0.0889)
		(layer "In4.Cu")
		(net "UPI_CPU1_CPU0_P1P0_DP<23>")
	)
	(segment
		(start 359.67543 -215.436704)
		(end 359.67543 -215.452198)
		(width 0.0889)
		(layer "In4.Cu")
		(net "UPI_CPU1_CPU0_P1P0_DP<23>")
	)
	(segment
		(start 112.014762 -216.259156)
		(end 112.014762 -216.240614)
		(width 0.0889)
		(layer "In4.Cu")
		(net "UPI_CPU1_CPU0_P1P0_DP<23>")
	)
	(segment
		(start 112.315752 -211.733638)
		(end 117.233446 -197.685152)
		(width 0.14732)
		(layer "In4.Cu")
		(net "UPI_CPU1_CPU0_P1P0_DP<23>")
	)
	(segment
		(start 302.461676 -168.712134)
		(end 302.467518 -168.71188)
		(width 0.14732)
		(layer "In4.Cu")
		(net "UPI_CPU1_CPU0_P1P0_DP<23>")
	)
	(segment
		(start 359.384346 -214.942674)
		(end 359.40619 -214.955374)
		(width 0.0889)
		(layer "In4.Cu")
		(net "UPI_CPU1_CPU0_P1P0_DP<23>")
	)
	(segment
		(start 359.304082 -213.841838)
		(end 359.304082 -214.017098)
		(width 0.0889)
		(layer "In4.Cu")
		(net "UPI_CPU1_CPU0_P1P0_DP<23>")
	)
	(segment
		(start 111.828326 -217.554556)
		(end 111.82731 -217.554048)
		(width 0.0889)
		(layer "In4.Cu")
		(net "UPI_CPU1_CPU0_P1P0_DP<23>")
	)
	(segment
		(start 112.110012 -218.692222)
		(end 112.266476 -218.421204)
		(width 0.0889)
		(layer "In4.Cu")
		(net "UPI_CPU1_CPU0_P1P0_DP<23>")
	)
	(segment
		(start 132.346192 -183.731154)
		(end 136.542018 -178.099974)
		(width 0.14732)
		(layer "In4.Cu")
		(net "UPI_CPU1_CPU0_P1P0_DP<23>")
	)
	(segment
		(start 112.357662 -213.88324)
		(end 112.357662 -212.114638)
		(width 0.0889)
		(layer "In4.Cu")
		(net "UPI_CPU1_CPU0_P1P0_DP<23>")
	)
	(segment
		(start 348.410022 -187.331858)
		(end 354.893372 -193.976244)
		(width 0.14732)
		(layer "In4.Cu")
		(net "UPI_CPU1_CPU0_P1P0_DP<23>")
	)
	(segment
		(start 359.205022 -213.567518)
		(end 359.205022 -213.742778)
		(width 0.0889)
		(layer "In4.Cu")
		(net "UPI_CPU1_CPU0_P1P0_DP<23>")
	)
	(arc
		(start 112.029748 -214.78367)
		(mid 112.021918 -214.764497)
		(end 112.014762 -214.745062)
		(width 0.0889)
		(layer "In4.Cu")
		(net "UPI_CPU1_CPU0_P1P0_DP<23>")
	)
	(arc
		(start 359.40619 -214.955374)
		(mid 359.603366 -215.161009)
		(end 359.675176 -215.436704)
		(width 0.0889)
		(layer "In4.Cu")
		(net "UPI_CPU1_CPU0_P1P0_DP<23>")
	)
	(arc
		(start 358.914446 -216.745058)
		(mid 358.783532 -216.881418)
		(end 358.735884 -217.064336)
		(width 0.0889)
		(layer "In4.Cu")
		(net "UPI_CPU1_CPU0_P1P0_DP<23>")
	)
	(arc
		(start 359.384346 -215.931242)
		(mid 359.253432 -216.067602)
		(end 359.205784 -216.25052)
		(width 0.0889)
		(layer "In4.Cu")
		(net "UPI_CPU1_CPU0_P1P0_DP<23>")
	)
	(arc
		(start 112.225582 -218.319096)
		(mid 112.070108 -218.122697)
		(end 112.014762 -217.878406)
		(width 0.0889)
		(layer "In4.Cu")
		(net "UPI_CPU1_CPU0_P1P0_DP<23>")
	)
	(arc
		(start 112.014762 -214.44331)
		(mid 112.041365 -214.309007)
		(end 112.117378 -214.195152)
		(width 0.0889)
		(layer "In4.Cu")
		(net "UPI_CPU1_CPU0_P1P0_DP<23>")
	)
	(arc
		(start 112.484662 -215.275922)
		(mid 112.409591 -215.16018)
		(end 112.300258 -215.076024)
		(width 0.0889)
		(layer "In4.Cu")
		(net "UPI_CPU1_CPU0_P1P0_DP<23>")
	)
	(arc
		(start 112.3061 -215.755982)
		(mid 112.437014 -215.619622)
		(end 112.484662 -215.436704)
		(width 0.0889)
		(layer "In4.Cu")
		(net "UPI_CPU1_CPU0_P1P0_DP<23>")
	)
	(arc
		(start 358.735884 -217.064336)
		(mid 358.772744 -217.226133)
		(end 358.875838 -217.356182)
		(width 0.0889)
		(layer "In4.Cu")
		(net "UPI_CPU1_CPU0_P1P0_DP<23>")
	)
	(arc
		(start 112.014762 -216.240614)
		(mid 112.092873 -215.963665)
		(end 112.29721 -215.761062)
		(width 0.0889)
		(layer "In4.Cu")
		(net "UPI_CPU1_CPU0_P1P0_DP<23>")
	)
	(arc
		(start 112.307116 -214.005414)
		(mid 112.344516 -213.949346)
		(end 112.357662 -213.88324)
		(width 0.0889)
		(layer "In4.Cu")
		(net "UPI_CPU1_CPU0_P1P0_DP<23>")
	)
	(arc
		(start 111.82731 -217.554048)
		(mid 111.626028 -217.356561)
		(end 111.545116 -217.086434)
		(width 0.0889)
		(layer "In4.Cu")
		(net "UPI_CPU1_CPU0_P1P0_DP<23>")
	)
	(arc
		(start 111.545116 -217.05443)
		(mid 111.623227 -216.777481)
		(end 111.827564 -216.574878)
		(width 0.0889)
		(layer "In4.Cu")
		(net "UPI_CPU1_CPU0_P1P0_DP<23>")
	)
	(arc
		(start 359.205784 -216.260426)
		(mid 359.127673 -216.537375)
		(end 358.923336 -216.739978)
		(width 0.0889)
		(layer "In4.Cu")
		(net "UPI_CPU1_CPU0_P1P0_DP<23>")
	)
	(arc
		(start 112.300258 -215.076024)
		(mid 112.139982 -214.953)
		(end 112.029748 -214.78367)
		(width 0.0889)
		(layer "In4.Cu")
		(net "UPI_CPU1_CPU0_P1P0_DP<23>")
	)
	(arc
		(start 359.205276 -214.622634)
		(mid 359.252955 -214.805534)
		(end 359.383838 -214.941912)
		(width 0.0889)
		(layer "In4.Cu")
		(net "UPI_CPU1_CPU0_P1P0_DP<23>")
	)
	(arc
		(start 112.242346 -218.33205)
		(mid 112.233903 -218.325652)
		(end 112.225582 -218.319096)
		(width 0.0889)
		(layer "In4.Cu")
		(net "UPI_CPU1_CPU0_P1P0_DP<23>")
	)
	(arc
		(start 112.014762 -217.878406)
		(mid 111.967083 -217.695506)
		(end 111.8362 -217.559128)
		(width 0.0889)
		(layer "In4.Cu")
		(net "UPI_CPU1_CPU0_P1P0_DP<23>")
	)
	(arc
		(start 111.827564 -216.574878)
		(mid 111.962497 -216.441524)
		(end 112.014762 -216.259156)
		(width 0.0889)
		(layer "In4.Cu")
		(net "UPI_CPU1_CPU0_P1P0_DP<23>")
	)
	(arc
		(start 359.67543 -215.452198)
		(mid 359.59606 -215.725932)
		(end 359.393236 -215.926162)
		(width 0.0889)
		(layer "In4.Cu")
		(net "UPI_CPU1_CPU0_P1P0_DP<23>")
	)
	(segment
		(start 357.70058 -217.87866)
		(end 357.700834 -217.878406)
		(width 0.13208)
		(layer "F.Cu")
		(net "UPI_CPU1_CPU0_P1P0_DP<22>")
	)
	(segment
		(start 357.70058 -218.414346)
		(end 357.70058 -217.87866)
		(width 0.13208)
		(layer "F.Cu")
		(net "UPI_CPU1_CPU0_P1P0_DP<22>")
	)
	(segment
		(start 113.519712 -218.414346)
		(end 113.519712 -217.87866)
		(width 0.13208)
		(layer "F.Cu")
		(net "UPI_CPU1_CPU0_P1P0_DP<22>")
	)
	(segment
		(start 113.519712 -217.87866)
		(end 113.519966 -217.878406)
		(width 0.13208)
		(layer "F.Cu")
		(net "UPI_CPU1_CPU0_P1P0_DP<22>")
	)
	(segment
		(start 358.03332 -204.481684)
		(end 358.03332 -212.7631)
		(width 0.14732)
		(layer "In4.Cu")
		(net "UPI_CPU1_CPU0_P1P0_DP<22>")
	)
	(segment
		(start 353.93884 -194.596766)
		(end 358.03332 -204.481684)
		(width 0.14732)
		(layer "In4.Cu")
		(net "UPI_CPU1_CPU0_P1P0_DP<22>")
	)
	(segment
		(start 347.491304 -187.988956)
		(end 353.93884 -194.596766)
		(width 0.14732)
		(layer "In4.Cu")
		(net "UPI_CPU1_CPU0_P1P0_DP<22>")
	)
	(segment
		(start 119.025416 -197.644766)
		(end 119.00789 -197.473316)
		(width 0.14732)
		(layer "In4.Cu")
		(net "UPI_CPU1_CPU0_P1P0_DP<22>")
	)
	(segment
		(start 123.106688 -192.622678)
		(end 123.382532 -192.283334)
		(width 0.14732)
		(layer "In4.Cu")
		(net "UPI_CPU1_CPU0_P1P0_DP<22>")
	)
	(segment
		(start 155.666948 -171.028868)
		(end 155.666948 -171.028614)
		(width 0.14732)
		(layer "In4.Cu")
		(net "UPI_CPU1_CPU0_P1P0_DP<22>")
	)
	(segment
		(start 119.282972 -197.134226)
		(end 119.454422 -197.116446)
		(width 0.14732)
		(layer "In4.Cu")
		(net "UPI_CPU1_CPU0_P1P0_DP<22>")
	)
	(segment
		(start 120.86463 -195.381626)
		(end 121.14022 -195.042282)
		(width 0.14732)
		(layer "In4.Cu")
		(net "UPI_CPU1_CPU0_P1P0_DP<22>")
	)
	(segment
		(start 357.976424 -214.10168)
		(end 358.075484 -214.20074)
		(width 0.0889)
		(layer "In4.Cu")
		(net "UPI_CPU1_CPU0_P1P0_DP<22>")
	)
	(segment
		(start 113.323624 -215.931242)
		(end 113.331752 -215.92667)
		(width 0.0889)
		(layer "In4.Cu")
		(net "UPI_CPU1_CPU0_P1P0_DP<22>")
	)
	(segment
		(start 358.075484 -213.82736)
		(end 357.976424 -213.92642)
		(width 0.0889)
		(layer "In4.Cu")
		(net "UPI_CPU1_CPU0_P1P0_DP<22>")
	)
	(segment
		(start 149.927564 -172.497242)
		(end 155.666948 -171.028868)
		(width 0.14732)
		(layer "In4.Cu")
		(net "UPI_CPU1_CPU0_P1P0_DP<22>")
	)
	(segment
		(start 123.382532 -192.283334)
		(end 123.364752 -192.111884)
		(width 0.14732)
		(layer "In4.Cu")
		(net "UPI_CPU1_CPU0_P1P0_DP<22>")
	)
	(segment
		(start 113.644426 -211.585302)
		(end 113.644172 -211.585048)
		(width 0.14732)
		(layer "In4.Cu")
		(net "UPI_CPU1_CPU0_P1P0_DP<22>")
	)
	(segment
		(start 340.971124 -180.436266)
		(end 345.033092 -184.49798)
		(width 0.14732)
		(layer "In4.Cu")
		(net "UPI_CPU1_CPU0_P1P0_DP<22>")
	)
	(segment
		(start 119.283226 -197.13448)
		(end 119.282972 -197.134226)
		(width 0.14732)
		(layer "In4.Cu")
		(net "UPI_CPU1_CPU0_P1P0_DP<22>")
	)
	(segment
		(start 122.935238 -192.640458)
		(end 123.106688 -192.622678)
		(width 0.14732)
		(layer "In4.Cu")
		(net "UPI_CPU1_CPU0_P1P0_DP<22>")
	)
	(segment
		(start 331.712316 -175.920908)
		(end 338.896198 -179.02682)
		(width 0.14732)
		(layer "In4.Cu")
		(net "UPI_CPU1_CPU0_P1P0_DP<22>")
	)
	(segment
		(start 357.60533 -217.064336)
		(end 357.60533 -217.071956)
		(width 0.0889)
		(layer "In4.Cu")
		(net "UPI_CPU1_CPU0_P1P0_DP<22>")
	)
	(segment
		(start 118.578122 -198.00189)
		(end 118.749572 -197.98411)
		(width 0.14732)
		(layer "In4.Cu")
		(net "UPI_CPU1_CPU0_P1P0_DP<22>")
	)
	(segment
		(start 113.644172 -211.295742)
		(end 118.086632 -198.60641)
		(width 0.14732)
		(layer "In4.Cu")
		(net "UPI_CPU1_CPU0_P1P0_DP<22>")
	)
	(segment
		(start 319.136014 -171.491402)
		(end 331.712316 -175.920908)
		(width 0.14732)
		(layer "In4.Cu")
		(net "UPI_CPU1_CPU0_P1P0_DP<22>")
	)
	(segment
		(start 124.089414 -191.413638)
		(end 124.071634 -191.242188)
		(width 0.14732)
		(layer "In4.Cu")
		(net "UPI_CPU1_CPU0_P1P0_DP<22>")
	)
	(segment
		(start 122.401838 -193.490088)
		(end 122.677682 -193.150744)
		(width 0.14732)
		(layer "In4.Cu")
		(net "UPI_CPU1_CPU0_P1P0_DP<22>")
	)
	(segment
		(start 120.435116 -195.909692)
		(end 120.41759 -195.738242)
		(width 0.14732)
		(layer "In4.Cu")
		(net "UPI_CPU1_CPU0_P1P0_DP<22>")
	)
	(segment
		(start 119.00789 -197.473316)
		(end 119.283226 -197.13448)
		(width 0.14732)
		(layer "In4.Cu")
		(net "UPI_CPU1_CPU0_P1P0_DP<22>")
	)
	(segment
		(start 122.659902 -192.979294)
		(end 122.935238 -192.640458)
		(width 0.14732)
		(layer "In4.Cu")
		(net "UPI_CPU1_CPU0_P1P0_DP<22>")
	)
	(segment
		(start 113.614962 -215.44661)
		(end 113.614962 -215.436704)
		(width 0.0889)
		(layer "In4.Cu")
		(net "UPI_CPU1_CPU0_P1P0_DP<22>")
	)
	(segment
		(start 358.075484 -214.20074)
		(end 358.075484 -214.636604)
		(width 0.0889)
		(layer "In4.Cu")
		(net "UPI_CPU1_CPU0_P1P0_DP<22>")
	)
	(segment
		(start 338.896198 -179.02682)
		(end 340.971124 -180.436266)
		(width 0.14732)
		(layer "In4.Cu")
		(net "UPI_CPU1_CPU0_P1P0_DP<22>")
	)
	(segment
		(start 119.98833 -196.26707)
		(end 119.987822 -196.266816)
		(width 0.14732)
		(layer "In4.Cu")
		(net "UPI_CPU1_CPU0_P1P0_DP<22>")
	)
	(segment
		(start 357.976424 -213.55304)
		(end 358.075484 -213.6521)
		(width 0.0889)
		(layer "In4.Cu")
		(net "UPI_CPU1_CPU0_P1P0_DP<22>")
	)
	(segment
		(start 123.64212 -191.770508)
		(end 123.81357 -191.752982)
		(width 0.14732)
		(layer "In4.Cu")
		(net "UPI_CPU1_CPU0_P1P0_DP<22>")
	)
	(segment
		(start 357.976424 -213.92642)
		(end 357.976424 -214.10168)
		(width 0.0889)
		(layer "In4.Cu")
		(net "UPI_CPU1_CPU0_P1P0_DP<22>")
	)
	(segment
		(start 120.692926 -195.399406)
		(end 120.86463 -195.381626)
		(width 0.14732)
		(layer "In4.Cu")
		(net "UPI_CPU1_CPU0_P1P0_DP<22>")
	)
	(segment
		(start 114.084862 -214.636858)
		(end 114.084862 -214.308182)
		(width 0.0889)
		(layer "In4.Cu")
		(net "UPI_CPU1_CPU0_P1P0_DP<22>")
	)
	(segment
		(start 155.666948 -171.028614)
		(end 201.033126 -170.276012)
		(width 0.14732)
		(layer "In4.Cu")
		(net "UPI_CPU1_CPU0_P1P0_DP<22>")
	)
	(segment
		(start 113.644426 -212.05063)
		(end 113.644426 -211.585302)
		(width 0.14732)
		(layer "In4.Cu")
		(net "UPI_CPU1_CPU0_P1P0_DP<22>")
	)
	(segment
		(start 113.793524 -215.117426)
		(end 113.801398 -215.112854)
		(width 0.0889)
		(layer "In4.Cu")
		(net "UPI_CPU1_CPU0_P1P0_DP<22>")
	)
	(segment
		(start 113.331752 -215.92667)
		(end 113.332514 -215.926162)
		(width 0.0889)
		(layer "In4.Cu")
		(net "UPI_CPU1_CPU0_P1P0_DP<22>")
	)
	(segment
		(start 358.075484 -213.27872)
		(end 357.976424 -213.37778)
		(width 0.0889)
		(layer "In4.Cu")
		(net "UPI_CPU1_CPU0_P1P0_DP<22>")
	)
	(segment
		(start 121.845324 -194.174872)
		(end 121.827544 -194.003422)
		(width 0.14732)
		(layer "In4.Cu")
		(net "UPI_CPU1_CPU0_P1P0_DP<22>")
	)
	(segment
		(start 358.033574 -212.98916)
		(end 358.075484 -213.03107)
		(width 0.0889)
		(layer "In4.Cu")
		(net "UPI_CPU1_CPU0_P1P0_DP<22>")
	)
	(segment
		(start 114.084862 -214.308182)
		(end 113.663476 -213.886796)
		(width 0.0889)
		(layer "In4.Cu")
		(net "UPI_CPU1_CPU0_P1P0_DP<22>")
	)
	(segment
		(start 113.801398 -215.112854)
		(end 113.802414 -215.112346)
		(width 0.0889)
		(layer "In4.Cu")
		(net "UPI_CPU1_CPU0_P1P0_DP<22>")
	)
	(segment
		(start 137.258044 -178.985164)
		(end 149.927564 -172.497242)
		(width 0.14732)
		(layer "In4.Cu")
		(net "UPI_CPU1_CPU0_P1P0_DP<22>")
	)
	(segment
		(start 121.14022 -195.042282)
		(end 121.122694 -194.870832)
		(width 0.14732)
		(layer "In4.Cu")
		(net "UPI_CPU1_CPU0_P1P0_DP<22>")
	)
	(segment
		(start 113.332514 -216.574878)
		(end 113.323624 -216.569798)
		(width 0.0889)
		(layer "In4.Cu")
		(net "UPI_CPU1_CPU0_P1P0_DP<22>")
	)
	(segment
		(start 358.033574 -212.763354)
		(end 358.033574 -212.967062)
		(width 0.14732)
		(layer "In4.Cu")
		(net "UPI_CPU1_CPU0_P1P0_DP<22>")
	)
	(segment
		(start 119.712486 -196.605652)
		(end 119.71274 -196.605906)
		(width 0.14732)
		(layer "In4.Cu")
		(net "UPI_CPU1_CPU0_P1P0_DP<22>")
	)
	(segment
		(start 314.005976 -170.058334)
		(end 319.136014 -171.491402)
		(width 0.14732)
		(layer "In4.Cu")
		(net "UPI_CPU1_CPU0_P1P0_DP<22>")
	)
	(segment
		(start 121.122694 -194.870832)
		(end 121.39803 -194.531996)
		(width 0.14732)
		(layer "In4.Cu")
		(net "UPI_CPU1_CPU0_P1P0_DP<22>")
	)
	(segment
		(start 357.888032 -216.574878)
		(end 357.87584 -216.58199)
		(width 0.0889)
		(layer "In4.Cu")
		(net "UPI_CPU1_CPU0_P1P0_DP<22>")
	)
	(segment
		(start 358.033574 -212.967062)
		(end 358.033574 -212.98916)
		(width 0.0889)
		(layer "In4.Cu")
		(net "UPI_CPU1_CPU0_P1P0_DP<22>")
	)
	(segment
		(start 125.264672 -189.774068)
		(end 133.100064 -184.566306)
		(width 0.14732)
		(layer "In4.Cu")
		(net "UPI_CPU1_CPU0_P1P0_DP<22>")
	)
	(segment
		(start 357.896922 -216.569798)
		(end 357.888032 -216.574878)
		(width 0.0889)
		(layer "In4.Cu")
		(net "UPI_CPU1_CPU0_P1P0_DP<22>")
	)
	(segment
		(start 113.363502 -217.607388)
		(end 113.387632 -217.518234)
		(width 0.0889)
		(layer "In4.Cu")
		(net "UPI_CPU1_CPU0_P1P0_DP<22>")
	)
	(segment
		(start 113.602262 -212.114892)
		(end 113.644426 -212.072728)
		(width 0.0889)
		(layer "In4.Cu")
		(net "UPI_CPU1_CPU0_P1P0_DP<22>")
	)
	(segment
		(start 120.41759 -195.738242)
		(end 120.692926 -195.399406)
		(width 0.14732)
		(layer "In4.Cu")
		(net "UPI_CPU1_CPU0_P1P0_DP<22>")
	)
	(segment
		(start 358.357678 -215.112346)
		(end 358.358694 -215.112854)
		(width 0.0889)
		(layer "In4.Cu")
		(net "UPI_CPU1_CPU0_P1P0_DP<22>")
	)
	(segment
		(start 113.644426 -212.072728)
		(end 113.644426 -212.05063)
		(width 0.0889)
		(layer "In4.Cu")
		(net "UPI_CPU1_CPU0_P1P0_DP<22>")
	)
	(segment
		(start 123.364752 -192.111884)
		(end 123.64212 -191.770508)
		(width 0.14732)
		(layer "In4.Cu")
		(net "UPI_CPU1_CPU0_P1P0_DP<22>")
	)
	(segment
		(start 113.602262 -213.738968)
		(end 113.602262 -212.114892)
		(width 0.0889)
		(layer "In4.Cu")
		(net "UPI_CPU1_CPU0_P1P0_DP<22>")
	)
	(segment
		(start 358.358694 -215.112854)
		(end 358.366568 -215.117426)
		(width 0.0889)
		(layer "In4.Cu")
		(net "UPI_CPU1_CPU0_P1P0_DP<22>")
	)
	(segment
		(start 201.033126 -170.276012)
		(end 211.269072 -170.725084)
		(width 0.14732)
		(layer "In4.Cu")
		(net "UPI_CPU1_CPU0_P1P0_DP<22>")
	)
	(segment
		(start 358.075484 -213.03107)
		(end 358.075484 -213.27872)
		(width 0.0889)
		(layer "In4.Cu")
		(net "UPI_CPU1_CPU0_P1P0_DP<22>")
	)
	(segment
		(start 118.749572 -197.98411)
		(end 119.025416 -197.644766)
		(width 0.14732)
		(layer "In4.Cu")
		(net "UPI_CPU1_CPU0_P1P0_DP<22>")
	)
	(segment
		(start 119.71274 -196.605906)
		(end 119.98833 -196.26707)
		(width 0.14732)
		(layer "In4.Cu")
		(net "UPI_CPU1_CPU0_P1P0_DP<22>")
	)
	(segment
		(start 113.615216 -217.07856)
		(end 113.615216 -217.064336)
		(width 0.0889)
		(layer "In4.Cu")
		(net "UPI_CPU1_CPU0_P1P0_DP<22>")
	)
	(segment
		(start 124.071634 -191.242188)
		(end 125.264672 -189.774068)
		(width 0.14732)
		(layer "In4.Cu")
		(net "UPI_CPU1_CPU0_P1P0_DP<22>")
	)
	(segment
		(start 273.041872 -170.560238)
		(end 302.470566 -169.84345)
		(width 0.14732)
		(layer "In4.Cu")
		(net "UPI_CPU1_CPU0_P1P0_DP<22>")
	)
	(segment
		(start 358.075484 -213.6521)
		(end 358.075484 -213.82736)
		(width 0.0889)
		(layer "In4.Cu")
		(net "UPI_CPU1_CPU0_P1P0_DP<22>")
	)
	(segment
		(start 358.075484 -216.235026)
		(end 358.075484 -216.25052)
		(width 0.0889)
		(layer "In4.Cu")
		(net "UPI_CPU1_CPU0_P1P0_DP<22>")
	)
	(segment
		(start 133.100064 -184.566306)
		(end 137.258044 -178.985164)
		(width 0.14732)
		(layer "In4.Cu")
		(net "UPI_CPU1_CPU0_P1P0_DP<22>")
	)
	(segment
		(start 238.598202 -170.725084)
		(end 273.041872 -170.560238)
		(width 0.14732)
		(layer "In4.Cu")
		(net "UPI_CPU1_CPU0_P1P0_DP<22>")
	)
	(segment
		(start 122.230388 -193.507868)
		(end 122.401838 -193.490088)
		(width 0.14732)
		(layer "In4.Cu")
		(net "UPI_CPU1_CPU0_P1P0_DP<22>")
	)
	(segment
		(start 123.81357 -191.752982)
		(end 124.089414 -191.413638)
		(width 0.14732)
		(layer "In4.Cu")
		(net "UPI_CPU1_CPU0_P1P0_DP<22>")
	)
	(segment
		(start 358.366568 -215.755982)
		(end 358.357678 -215.761062)
		(width 0.0889)
		(layer "In4.Cu")
		(net "UPI_CPU1_CPU0_P1P0_DP<22>")
	)
	(segment
		(start 345.033092 -184.49798)
		(end 347.491304 -187.988956)
		(width 0.14732)
		(layer "In4.Cu")
		(net "UPI_CPU1_CPU0_P1P0_DP<22>")
	)
	(segment
		(start 119.987822 -196.266816)
		(end 120.159526 -196.249036)
		(width 0.14732)
		(layer "In4.Cu")
		(net "UPI_CPU1_CPU0_P1P0_DP<22>")
	)
	(segment
		(start 121.827544 -194.003422)
		(end 122.230388 -193.507868)
		(width 0.14732)
		(layer "In4.Cu")
		(net "UPI_CPU1_CPU0_P1P0_DP<22>")
	)
	(segment
		(start 118.086632 -198.60641)
		(end 118.578122 -198.00189)
		(width 0.14732)
		(layer "In4.Cu")
		(net "UPI_CPU1_CPU0_P1P0_DP<22>")
	)
	(segment
		(start 113.519966 -217.878406)
		(end 113.363502 -217.607388)
		(width 0.0889)
		(layer "In4.Cu")
		(net "UPI_CPU1_CPU0_P1P0_DP<22>")
	)
	(segment
		(start 357.93553 -218.170252)
		(end 357.857298 -218.149424)
		(width 0.0889)
		(layer "In4.Cu")
		(net "UPI_CPU1_CPU0_P1P0_DP<22>")
	)
	(segment
		(start 119.730266 -196.777356)
		(end 119.712486 -196.605652)
		(width 0.14732)
		(layer "In4.Cu")
		(net "UPI_CPU1_CPU0_P1P0_DP<22>")
	)
	(segment
		(start 122.677682 -193.150744)
		(end 122.659902 -192.979294)
		(width 0.14732)
		(layer "In4.Cu")
		(net "UPI_CPU1_CPU0_P1P0_DP<22>")
	)
	(segment
		(start 120.159526 -196.249036)
		(end 120.435116 -195.909692)
		(width 0.14732)
		(layer "In4.Cu")
		(net "UPI_CPU1_CPU0_P1P0_DP<22>")
	)
	(segment
		(start 357.976424 -213.37778)
		(end 357.976424 -213.55304)
		(width 0.0889)
		(layer "In4.Cu")
		(net "UPI_CPU1_CPU0_P1P0_DP<22>")
	)
	(segment
		(start 358.03332 -212.7631)
		(end 358.033574 -212.763354)
		(width 0.14732)
		(layer "In4.Cu")
		(net "UPI_CPU1_CPU0_P1P0_DP<22>")
	)
	(segment
		(start 113.644172 -211.585048)
		(end 113.644172 -211.295742)
		(width 0.14732)
		(layer "In4.Cu")
		(net "UPI_CPU1_CPU0_P1P0_DP<22>")
	)
	(segment
		(start 357.888032 -217.554048)
		(end 357.896922 -217.559128)
		(width 0.0889)
		(layer "In4.Cu")
		(net "UPI_CPU1_CPU0_P1P0_DP<22>")
	)
	(segment
		(start 113.344706 -216.58199)
		(end 113.332514 -216.574878)
		(width 0.0889)
		(layer "In4.Cu")
		(net "UPI_CPU1_CPU0_P1P0_DP<22>")
	)
	(segment
		(start 357.857298 -218.149424)
		(end 357.700834 -217.878406)
		(width 0.0889)
		(layer "In4.Cu")
		(net "UPI_CPU1_CPU0_P1P0_DP<22>")
	)
	(segment
		(start 211.269072 -170.725084)
		(end 238.598202 -170.725084)
		(width 0.14732)
		(layer "In4.Cu")
		(net "UPI_CPU1_CPU0_P1P0_DP<22>")
	)
	(segment
		(start 119.454422 -197.116446)
		(end 119.730266 -196.777356)
		(width 0.14732)
		(layer "In4.Cu")
		(net "UPI_CPU1_CPU0_P1P0_DP<22>")
	)
	(segment
		(start 121.56948 -194.514216)
		(end 121.845324 -194.174872)
		(width 0.14732)
		(layer "In4.Cu")
		(net "UPI_CPU1_CPU0_P1P0_DP<22>")
	)
	(segment
		(start 121.39803 -194.531996)
		(end 121.56948 -194.514216)
		(width 0.14732)
		(layer "In4.Cu")
		(net "UPI_CPU1_CPU0_P1P0_DP<22>")
	)
	(segment
		(start 358.075484 -214.636604)
		(end 358.07523 -214.636858)
		(width 0.0889)
		(layer "In4.Cu")
		(net "UPI_CPU1_CPU0_P1P0_DP<22>")
	)
	(segment
		(start 302.470566 -169.84345)
		(end 314.005976 -170.058334)
		(width 0.14732)
		(layer "In4.Cu")
		(net "UPI_CPU1_CPU0_P1P0_DP<22>")
	)
	(arc
		(start 113.614962 -215.436704)
		(mid 113.615014 -215.429337)
		(end 113.615216 -215.421972)
		(width 0.0889)
		(layer "In4.Cu")
		(net "UPI_CPU1_CPU0_P1P0_DP<22>")
	)
	(arc
		(start 113.332514 -215.926162)
		(mid 113.536849 -215.723557)
		(end 113.614962 -215.44661)
		(width 0.0889)
		(layer "In4.Cu")
		(net "UPI_CPU1_CPU0_P1P0_DP<22>")
	)
	(arc
		(start 357.87584 -216.58199)
		(mid 357.677612 -216.787838)
		(end 357.60533 -217.064336)
		(width 0.0889)
		(layer "In4.Cu")
		(net "UPI_CPU1_CPU0_P1P0_DP<22>")
	)
	(arc
		(start 358.075484 -217.878406)
		(mid 358.038624 -218.040203)
		(end 357.93553 -218.170252)
		(width 0.0889)
		(layer "In4.Cu")
		(net "UPI_CPU1_CPU0_P1P0_DP<22>")
	)
	(arc
		(start 113.615216 -217.064336)
		(mid 113.542981 -216.787812)
		(end 113.344706 -216.58199)
		(width 0.0889)
		(layer "In4.Cu")
		(net "UPI_CPU1_CPU0_P1P0_DP<22>")
	)
	(arc
		(start 358.075484 -216.25052)
		(mid 358.027805 -216.43342)
		(end 357.896922 -216.569798)
		(width 0.0889)
		(layer "In4.Cu")
		(net "UPI_CPU1_CPU0_P1P0_DP<22>")
	)
	(arc
		(start 358.366568 -215.117426)
		(mid 358.493822 -215.247392)
		(end 358.544876 -215.421972)
		(width 0.0889)
		(layer "In4.Cu")
		(net "UPI_CPU1_CPU0_P1P0_DP<22>")
	)
	(arc
		(start 357.896922 -217.559128)
		(mid 358.027836 -217.695488)
		(end 358.075484 -217.878406)
		(width 0.0889)
		(layer "In4.Cu")
		(net "UPI_CPU1_CPU0_P1P0_DP<22>")
	)
	(arc
		(start 113.387632 -217.518234)
		(mid 113.396075 -217.511836)
		(end 113.404396 -217.50528)
		(width 0.0889)
		(layer "In4.Cu")
		(net "UPI_CPU1_CPU0_P1P0_DP<22>")
	)
	(arc
		(start 358.54513 -215.436704)
		(mid 358.497451 -215.619604)
		(end 358.366568 -215.755982)
		(width 0.0889)
		(layer "In4.Cu")
		(net "UPI_CPU1_CPU0_P1P0_DP<22>")
	)
	(arc
		(start 113.323624 -216.569798)
		(mid 113.145027 -216.25052)
		(end 113.323624 -215.931242)
		(width 0.0889)
		(layer "In4.Cu")
		(net "UPI_CPU1_CPU0_P1P0_DP<22>")
	)
	(arc
		(start 113.802414 -215.112346)
		(mid 114.005719 -214.91148)
		(end 114.084862 -214.636858)
		(width 0.0889)
		(layer "In4.Cu")
		(net "UPI_CPU1_CPU0_P1P0_DP<22>")
	)
	(arc
		(start 113.663476 -213.886796)
		(mid 113.618157 -213.818972)
		(end 113.602262 -213.738968)
		(width 0.0889)
		(layer "In4.Cu")
		(net "UPI_CPU1_CPU0_P1P0_DP<22>")
	)
	(arc
		(start 358.357678 -215.761062)
		(mid 358.154855 -215.961293)
		(end 358.075484 -216.235026)
		(width 0.0889)
		(layer "In4.Cu")
		(net "UPI_CPU1_CPU0_P1P0_DP<22>")
	)
	(arc
		(start 113.615216 -215.421972)
		(mid 113.66627 -215.247392)
		(end 113.793524 -215.117426)
		(width 0.0889)
		(layer "In4.Cu")
		(net "UPI_CPU1_CPU0_P1P0_DP<22>")
	)
	(arc
		(start 358.544876 -215.421972)
		(mid 358.545073 -215.429337)
		(end 358.54513 -215.436704)
		(width 0.0889)
		(layer "In4.Cu")
		(net "UPI_CPU1_CPU0_P1P0_DP<22>")
	)
	(arc
		(start 357.60533 -217.071956)
		(mid 357.682959 -217.350369)
		(end 357.888032 -217.554048)
		(width 0.0889)
		(layer "In4.Cu")
		(net "UPI_CPU1_CPU0_P1P0_DP<22>")
	)
	(arc
		(start 358.07523 -214.636858)
		(mid 358.154371 -214.911481)
		(end 358.357678 -215.112346)
		(width 0.0889)
		(layer "In4.Cu")
		(net "UPI_CPU1_CPU0_P1P0_DP<22>")
	)
	(arc
		(start 113.404396 -217.50528)
		(mid 113.556903 -217.315182)
		(end 113.615216 -217.07856)
		(width 0.0889)
		(layer "In4.Cu")
		(net "UPI_CPU1_CPU0_P1P0_DP<22>")
	)
	(segment
		(start 357.230934 -217.600276)
		(end 357.230934 -217.06459)
		(width 0.13208)
		(layer "F.Cu")
		(net "UPI_CPU1_CPU0_P1P0_DP<21>")
	)
	(segment
		(start 357.230934 -217.06459)
		(end 357.23068 -217.064336)
		(width 0.13208)
		(layer "F.Cu")
		(net "UPI_CPU1_CPU0_P1P0_DP<21>")
	)
	(segment
		(start 113.989866 -219.228162)
		(end 113.989866 -218.692222)
		(width 0.13208)
		(layer "F.Cu")
		(net "UPI_CPU1_CPU0_P1P0_DP<21>")
	)
	(segment
		(start 113.989866 -218.692222)
		(end 114.14633 -218.421204)
		(width 0.0889)
		(layer "In4.Cu")
		(net "UPI_CPU1_CPU0_P1P0_DP<21>")
	)
	(segment
		(start 114.322606 -212.05063)
		(end 114.322606 -211.585302)
		(width 0.14732)
		(layer "In4.Cu")
		(net "UPI_CPU1_CPU0_P1P0_DP<21>")
	)
	(segment
		(start 114.322606 -211.585302)
		(end 114.322352 -211.585048)
		(width 0.14732)
		(layer "In4.Cu")
		(net "UPI_CPU1_CPU0_P1P0_DP<21>")
	)
	(segment
		(start 114.833908 -214.63127)
		(end 114.833908 -214.613998)
		(width 0.0889)
		(layer "In4.Cu")
		(net "UPI_CPU1_CPU0_P1P0_DP<21>")
	)
	(segment
		(start 353.461574 -194.90309)
		(end 357.367332 -204.33284)
		(width 0.14732)
		(layer "In4.Cu")
		(net "UPI_CPU1_CPU0_P1P0_DP<21>")
	)
	(segment
		(start 357.36784 -212.753956)
		(end 357.36784 -213.11489)
		(width 0.14732)
		(layer "In4.Cu")
		(net "UPI_CPU1_CPU0_P1P0_DP<21>")
	)
	(segment
		(start 114.322352 -211.08797)
		(end 118.474998 -199.225662)
		(width 0.14732)
		(layer "In4.Cu")
		(net "UPI_CPU1_CPU0_P1P0_DP<21>")
	)
	(segment
		(start 357.043482 -215.761062)
		(end 357.046276 -215.762586)
		(width 0.0889)
		(layer "In4.Cu")
		(net "UPI_CPU1_CPU0_P1P0_DP<21>")
	)
	(segment
		(start 118.474998 -199.225662)
		(end 126.016258 -189.94755)
		(width 0.14732)
		(layer "In4.Cu")
		(net "UPI_CPU1_CPU0_P1P0_DP<21>")
	)
	(segment
		(start 114.529616 -214.208614)
		(end 114.364516 -214.043514)
		(width 0.0889)
		(layer "In4.Cu")
		(net "UPI_CPU1_CPU0_P1P0_DP<21>")
	)
	(segment
		(start 357.36784 -213.136988)
		(end 357.325676 -213.179152)
		(width 0.0889)
		(layer "In4.Cu")
		(net "UPI_CPU1_CPU0_P1P0_DP<21>")
	)
	(segment
		(start 302.477932 -170.432984)
		(end 302.478186 -170.433238)
		(width 0.14732)
		(layer "In4.Cu")
		(net "UPI_CPU1_CPU0_P1P0_DP<21>")
	)
	(segment
		(start 114.170714 -215.764618)
		(end 114.17681 -215.761062)
		(width 0.0889)
		(layer "In4.Cu")
		(net "UPI_CPU1_CPU0_P1P0_DP<21>")
	)
	(segment
		(start 357.074216 -217.335354)
		(end 357.23068 -217.064336)
		(width 0.0889)
		(layer "In4.Cu")
		(net "UPI_CPU1_CPU0_P1P0_DP<21>")
	)
	(segment
		(start 273.050508 -171.149518)
		(end 302.466502 -170.433238)
		(width 0.14732)
		(layer "In4.Cu")
		(net "UPI_CPU1_CPU0_P1P0_DP<21>")
	)
	(segment
		(start 114.364516 -214.043514)
		(end 114.364516 -212.114638)
		(width 0.0889)
		(layer "In4.Cu")
		(net "UPI_CPU1_CPU0_P1P0_DP<21>")
	)
	(segment
		(start 200.736454 -170.842178)
		(end 211.49564 -171.314364)
		(width 0.14732)
		(layer "In4.Cu")
		(net "UPI_CPU1_CPU0_P1P0_DP<21>")
	)
	(segment
		(start 114.177064 -216.739978)
		(end 114.164872 -216.732866)
		(width 0.0889)
		(layer "In4.Cu")
		(net "UPI_CPU1_CPU0_P1P0_DP<21>")
	)
	(segment
		(start 331.46873 -176.437798)
		(end 338.58073 -179.50053)
		(width 0.14732)
		(layer "In4.Cu")
		(net "UPI_CPU1_CPU0_P1P0_DP<21>")
	)
	(segment
		(start 338.58073 -179.50053)
		(end 340.623144 -180.885846)
		(width 0.14732)
		(layer "In4.Cu")
		(net "UPI_CPU1_CPU0_P1P0_DP<21>")
	)
	(segment
		(start 357.36784 -213.11489)
		(end 357.36784 -213.136988)
		(width 0.0889)
		(layer "In4.Cu")
		(net "UPI_CPU1_CPU0_P1P0_DP<21>")
	)
	(segment
		(start 133.475984 -184.98947)
		(end 137.61339 -179.43576)
		(width 0.14732)
		(layer "In4.Cu")
		(net "UPI_CPU1_CPU0_P1P0_DP<21>")
	)
	(segment
		(start 302.466502 -170.433238)
		(end 302.472344 -170.432984)
		(width 0.14732)
		(layer "In4.Cu")
		(net "UPI_CPU1_CPU0_P1P0_DP<21>")
	)
	(segment
		(start 356.996238 -217.356182)
		(end 357.074216 -217.335354)
		(width 0.0889)
		(layer "In4.Cu")
		(net "UPI_CPU1_CPU0_P1P0_DP<21>")
	)
	(segment
		(start 302.478186 -170.433238)
		(end 313.812682 -170.644058)
		(width 0.14732)
		(layer "In4.Cu")
		(net "UPI_CPU1_CPU0_P1P0_DP<21>")
	)
	(segment
		(start 357.367332 -204.33284)
		(end 357.367332 -212.753448)
		(width 0.14732)
		(layer "In4.Cu")
		(net "UPI_CPU1_CPU0_P1P0_DP<21>")
	)
	(segment
		(start 113.894616 -217.888312)
		(end 113.894616 -217.859864)
		(width 0.0889)
		(layer "In4.Cu")
		(net "UPI_CPU1_CPU0_P1P0_DP<21>")
	)
	(segment
		(start 313.812682 -170.644058)
		(end 318.93637 -172.075348)
		(width 0.14732)
		(layer "In4.Cu")
		(net "UPI_CPU1_CPU0_P1P0_DP<21>")
	)
	(segment
		(start 114.14633 -218.421204)
		(end 114.1222 -218.33205)
		(width 0.0889)
		(layer "In4.Cu")
		(net "UPI_CPU1_CPU0_P1P0_DP<21>")
	)
	(segment
		(start 344.592656 -184.855358)
		(end 347.019118 -188.301122)
		(width 0.14732)
		(layer "In4.Cu")
		(net "UPI_CPU1_CPU0_P1P0_DP<21>")
	)
	(segment
		(start 340.623144 -180.885846)
		(end 344.592656 -184.855358)
		(width 0.14732)
		(layer "In4.Cu")
		(net "UPI_CPU1_CPU0_P1P0_DP<21>")
	)
	(segment
		(start 357.367332 -212.753448)
		(end 357.36784 -212.753956)
		(width 0.14732)
		(layer "In4.Cu")
		(net "UPI_CPU1_CPU0_P1P0_DP<21>")
	)
	(segment
		(start 114.364516 -212.114638)
		(end 114.322606 -212.072728)
		(width 0.0889)
		(layer "In4.Cu")
		(net "UPI_CPU1_CPU0_P1P0_DP<21>")
	)
	(segment
		(start 357.044244 -216.73947)
		(end 357.043482 -216.739978)
		(width 0.0889)
		(layer "In4.Cu")
		(net "UPI_CPU1_CPU0_P1P0_DP<21>")
	)
	(segment
		(start 357.046276 -215.762586)
		(end 357.049578 -215.764618)
		(width 0.0889)
		(layer "In4.Cu")
		(net "UPI_CPU1_CPU0_P1P0_DP<21>")
	)
	(segment
		(start 126.016258 -189.94755)
		(end 133.475984 -184.98947)
		(width 0.14732)
		(layer "In4.Cu")
		(net "UPI_CPU1_CPU0_P1P0_DP<21>")
	)
	(segment
		(start 114.364262 -215.436704)
		(end 114.364262 -215.418162)
		(width 0.0889)
		(layer "In4.Cu")
		(net "UPI_CPU1_CPU0_P1P0_DP<21>")
	)
	(segment
		(start 137.61339 -179.43576)
		(end 149.912832 -173.137576)
		(width 0.14732)
		(layer "In4.Cu")
		(net "UPI_CPU1_CPU0_P1P0_DP<21>")
	)
	(segment
		(start 357.325676 -213.179152)
		(end 357.325676 -214.644732)
		(width 0.0889)
		(layer "In4.Cu")
		(net "UPI_CPU1_CPU0_P1P0_DP<21>")
	)
	(segment
		(start 357.034592 -215.755982)
		(end 357.041958 -215.7603)
		(width 0.0889)
		(layer "In4.Cu")
		(net "UPI_CPU1_CPU0_P1P0_DP<21>")
	)
	(segment
		(start 357.043482 -215.112346)
		(end 357.042466 -215.112854)
		(width 0.0889)
		(layer "In4.Cu")
		(net "UPI_CPU1_CPU0_P1P0_DP<21>")
	)
	(segment
		(start 114.322352 -211.585048)
		(end 114.322352 -211.08797)
		(width 0.14732)
		(layer "In4.Cu")
		(net "UPI_CPU1_CPU0_P1P0_DP<21>")
	)
	(segment
		(start 114.364262 -217.072972)
		(end 114.364262 -217.0557)
		(width 0.0889)
		(layer "In4.Cu")
		(net "UPI_CPU1_CPU0_P1P0_DP<21>")
	)
	(segment
		(start 211.49564 -171.314364)
		(end 238.599218 -171.314364)
		(width 0.14732)
		(layer "In4.Cu")
		(net "UPI_CPU1_CPU0_P1P0_DP<21>")
	)
	(segment
		(start 149.912832 -173.137576)
		(end 155.980384 -171.585128)
		(width 0.14732)
		(layer "In4.Cu")
		(net "UPI_CPU1_CPU0_P1P0_DP<21>")
	)
	(segment
		(start 114.17681 -215.761062)
		(end 114.1857 -215.755982)
		(width 0.0889)
		(layer "In4.Cu")
		(net "UPI_CPU1_CPU0_P1P0_DP<21>")
	)
	(segment
		(start 155.980384 -171.585128)
		(end 200.736454 -170.842178)
		(width 0.14732)
		(layer "In4.Cu")
		(net "UPI_CPU1_CPU0_P1P0_DP<21>")
	)
	(segment
		(start 357.041958 -215.7603)
		(end 357.043482 -215.761062)
		(width 0.0889)
		(layer "In4.Cu")
		(net "UPI_CPU1_CPU0_P1P0_DP<21>")
	)
	(segment
		(start 347.019118 -188.301122)
		(end 353.461574 -194.90309)
		(width 0.14732)
		(layer "In4.Cu")
		(net "UPI_CPU1_CPU0_P1P0_DP<21>")
	)
	(segment
		(start 318.93637 -172.075348)
		(end 331.46873 -176.437798)
		(width 0.14732)
		(layer "In4.Cu")
		(net "UPI_CPU1_CPU0_P1P0_DP<21>")
	)
	(segment
		(start 302.472344 -170.432984)
		(end 302.477932 -170.432984)
		(width 0.14732)
		(layer "In4.Cu")
		(net "UPI_CPU1_CPU0_P1P0_DP<21>")
	)
	(segment
		(start 357.049578 -216.736422)
		(end 357.044244 -216.73947)
		(width 0.0889)
		(layer "In4.Cu")
		(net "UPI_CPU1_CPU0_P1P0_DP<21>")
	)
	(segment
		(start 238.599218 -171.314364)
		(end 273.050508 -171.149518)
		(width 0.14732)
		(layer "In4.Cu")
		(net "UPI_CPU1_CPU0_P1P0_DP<21>")
	)
	(segment
		(start 114.322606 -212.072728)
		(end 114.322606 -212.05063)
		(width 0.0889)
		(layer "In4.Cu")
		(net "UPI_CPU1_CPU0_P1P0_DP<21>")
	)
	(segment
		(start 357.042466 -215.112854)
		(end 357.034592 -215.117426)
		(width 0.0889)
		(layer "In4.Cu")
		(net "UPI_CPU1_CPU0_P1P0_DP<21>")
	)
	(arc
		(start 114.1857 -215.755982)
		(mid 114.316614 -215.619622)
		(end 114.364262 -215.436704)
		(width 0.0889)
		(layer "In4.Cu")
		(net "UPI_CPU1_CPU0_P1P0_DP<21>")
	)
	(arc
		(start 357.034592 -215.117426)
		(mid 356.855995 -215.436704)
		(end 357.034592 -215.755982)
		(width 0.0889)
		(layer "In4.Cu")
		(net "UPI_CPU1_CPU0_P1P0_DP<21>")
	)
	(arc
		(start 114.105436 -218.319096)
		(mid 113.952052 -218.127177)
		(end 113.894616 -217.888312)
		(width 0.0889)
		(layer "In4.Cu")
		(net "UPI_CPU1_CPU0_P1P0_DP<21>")
	)
	(arc
		(start 357.049578 -215.764618)
		(mid 357.326152 -216.25052)
		(end 357.049578 -216.736422)
		(width 0.0889)
		(layer "In4.Cu")
		(net "UPI_CPU1_CPU0_P1P0_DP<21>")
	)
	(arc
		(start 113.894362 -216.25052)
		(mid 113.968278 -215.971018)
		(end 114.170714 -215.764618)
		(width 0.0889)
		(layer "In4.Cu")
		(net "UPI_CPU1_CPU0_P1P0_DP<21>")
	)
	(arc
		(start 357.325676 -214.644732)
		(mid 357.244765 -214.91486)
		(end 357.043482 -215.112346)
		(width 0.0889)
		(layer "In4.Cu")
		(net "UPI_CPU1_CPU0_P1P0_DP<21>")
	)
	(arc
		(start 114.364262 -217.0557)
		(mid 114.311992 -216.873335)
		(end 114.177064 -216.739978)
		(width 0.0889)
		(layer "In4.Cu")
		(net "UPI_CPU1_CPU0_P1P0_DP<21>")
	)
	(arc
		(start 114.64671 -214.298276)
		(mid 114.585232 -214.257274)
		(end 114.529616 -214.208614)
		(width 0.0889)
		(layer "In4.Cu")
		(net "UPI_CPU1_CPU0_P1P0_DP<21>")
	)
	(arc
		(start 114.164872 -216.732866)
		(mid 113.966644 -216.527018)
		(end 113.894362 -216.25052)
		(width 0.0889)
		(layer "In4.Cu")
		(net "UPI_CPU1_CPU0_P1P0_DP<21>")
	)
	(arc
		(start 114.364262 -215.418162)
		(mid 114.444424 -215.145973)
		(end 114.64671 -214.946992)
		(width 0.0889)
		(layer "In4.Cu")
		(net "UPI_CPU1_CPU0_P1P0_DP<21>")
	)
	(arc
		(start 114.1222 -218.33205)
		(mid 114.113756 -218.325653)
		(end 114.105436 -218.319096)
		(width 0.0889)
		(layer "In4.Cu")
		(net "UPI_CPU1_CPU0_P1P0_DP<21>")
	)
	(arc
		(start 114.177064 -217.388694)
		(mid 114.311997 -217.25534)
		(end 114.364262 -217.072972)
		(width 0.0889)
		(layer "In4.Cu")
		(net "UPI_CPU1_CPU0_P1P0_DP<21>")
	)
	(arc
		(start 114.64671 -214.946992)
		(mid 114.781643 -214.813638)
		(end 114.833908 -214.63127)
		(width 0.0889)
		(layer "In4.Cu")
		(net "UPI_CPU1_CPU0_P1P0_DP<21>")
	)
	(arc
		(start 113.894616 -217.859864)
		(mid 113.974778 -217.587675)
		(end 114.177064 -217.388694)
		(width 0.0889)
		(layer "In4.Cu")
		(net "UPI_CPU1_CPU0_P1P0_DP<21>")
	)
	(arc
		(start 357.043482 -216.739978)
		(mid 356.857279 -217.035655)
		(end 356.996238 -217.356182)
		(width 0.0889)
		(layer "In4.Cu")
		(net "UPI_CPU1_CPU0_P1P0_DP<21>")
	)
	(arc
		(start 114.833908 -214.613998)
		(mid 114.781638 -214.431633)
		(end 114.64671 -214.298276)
		(width 0.0889)
		(layer "In4.Cu")
		(net "UPI_CPU1_CPU0_P1P0_DP<21>")
	)
	(segment
		(start 115.399312 -218.414346)
		(end 115.399312 -217.87866)
		(width 0.13208)
		(layer "F.Cu")
		(net "UPI_CPU1_CPU0_P1P0_DP<20>")
	)
	(segment
		(start 355.82098 -218.414346)
		(end 355.82098 -217.87866)
		(width 0.13208)
		(layer "F.Cu")
		(net "UPI_CPU1_CPU0_P1P0_DP<20>")
	)
	(segment
		(start 355.82098 -217.87866)
		(end 355.821234 -217.878406)
		(width 0.13208)
		(layer "F.Cu")
		(net "UPI_CPU1_CPU0_P1P0_DP<20>")
	)
	(segment
		(start 115.399312 -217.87866)
		(end 115.399566 -217.878406)
		(width 0.13208)
		(layer "F.Cu")
		(net "UPI_CPU1_CPU0_P1P0_DP<20>")
	)
	(segment
		(start 115.536472 -211.585048)
		(end 115.536472 -210.96732)
		(width 0.14732)
		(layer "In4.Cu")
		(net "UPI_CPU1_CPU0_P1P0_DP<20>")
	)
	(segment
		(start 355.68382 -211.8106)
		(end 355.684074 -211.810854)
		(width 0.14732)
		(layer "In4.Cu")
		(net "UPI_CPU1_CPU0_P1P0_DP<20>")
	)
	(segment
		(start 356.000812 -216.579196)
		(end 355.99624 -216.58199)
		(width 0.0889)
		(layer "In4.Cu")
		(net "UPI_CPU1_CPU0_P1P0_DP<20>")
	)
	(segment
		(start 356.24262 -208.700878)
		(end 356.09784 -208.845658)
		(width 0.14732)
		(layer "In4.Cu")
		(net "UPI_CPU1_CPU0_P1P0_DP<20>")
	)
	(segment
		(start 356.24262 -209.358738)
		(end 356.24262 -209.823304)
		(width 0.14732)
		(layer "In4.Cu")
		(net "UPI_CPU1_CPU0_P1P0_DP<20>")
	)
	(segment
		(start 356.009956 -215.926924)
		(end 356.017322 -215.931242)
		(width 0.0889)
		(layer "In4.Cu")
		(net "UPI_CPU1_CPU0_P1P0_DP<20>")
	)
	(segment
		(start 125.529848 -192.494916)
		(end 125.805184 -192.15608)
		(width 0.14732)
		(layer "In4.Cu")
		(net "UPI_CPU1_CPU0_P1P0_DP<20>")
	)
	(segment
		(start 125.805184 -192.15608)
		(end 125.976634 -192.1383)
		(width 0.14732)
		(layer "In4.Cu")
		(net "UPI_CPU1_CPU0_P1P0_DP<20>")
	)
	(segment
		(start 123.144788 -195.622672)
		(end 123.420378 -195.283328)
		(width 0.14732)
		(layer "In4.Cu")
		(net "UPI_CPU1_CPU0_P1P0_DP<20>")
	)
	(segment
		(start 122.439684 -196.490082)
		(end 122.715274 -196.150992)
		(width 0.14732)
		(layer "In4.Cu")
		(net "UPI_CPU1_CPU0_P1P0_DP<20>")
	)
	(segment
		(start 125.271784 -193.00571)
		(end 125.547374 -192.666366)
		(width 0.14732)
		(layer "In4.Cu")
		(net "UPI_CPU1_CPU0_P1P0_DP<20>")
	)
	(segment
		(start 122.973084 -195.640452)
		(end 123.144788 -195.622672)
		(width 0.14732)
		(layer "In4.Cu")
		(net "UPI_CPU1_CPU0_P1P0_DP<20>")
	)
	(segment
		(start 149.978618 -174.361856)
		(end 156.489908 -172.69587)
		(width 0.14732)
		(layer "In4.Cu")
		(net "UPI_CPU1_CPU0_P1P0_DP<20>")
	)
	(segment
		(start 121.73331 -197.35927)
		(end 122.0089 -197.019926)
		(width 0.14732)
		(layer "In4.Cu")
		(net "UPI_CPU1_CPU0_P1P0_DP<20>")
	)
	(segment
		(start 338.063078 -180.496464)
		(end 339.881718 -181.7243)
		(width 0.14732)
		(layer "In4.Cu")
		(net "UPI_CPU1_CPU0_P1P0_DP<20>")
	)
	(segment
		(start 120.856756 -198.24446)
		(end 121.02846 -198.22668)
		(width 0.14732)
		(layer "In4.Cu")
		(net "UPI_CPU1_CPU0_P1P0_DP<20>")
	)
	(segment
		(start 124.383292 -193.905632)
		(end 124.554742 -193.887852)
		(width 0.14732)
		(layer "In4.Cu")
		(net "UPI_CPU1_CPU0_P1P0_DP<20>")
	)
	(segment
		(start 313.644026 -171.758356)
		(end 318.550544 -173.12894)
		(width 0.14732)
		(layer "In4.Cu")
		(net "UPI_CPU1_CPU0_P1P0_DP<20>")
	)
	(segment
		(start 356.09784 -208.845658)
		(end 356.09784 -209.213958)
		(width 0.14732)
		(layer "In4.Cu")
		(net "UPI_CPU1_CPU0_P1P0_DP<20>")
	)
	(segment
		(start 115.399566 -217.878406)
		(end 115.243102 -217.607388)
		(width 0.0889)
		(layer "In4.Cu")
		(net "UPI_CPU1_CPU0_P1P0_DP<20>")
	)
	(segment
		(start 125.547374 -192.666366)
		(end 125.529848 -192.494916)
		(width 0.14732)
		(layer "In4.Cu")
		(net "UPI_CPU1_CPU0_P1P0_DP<20>")
	)
	(segment
		(start 115.243102 -217.607388)
		(end 115.267232 -217.518234)
		(width 0.0889)
		(layer "In4.Cu")
		(net "UPI_CPU1_CPU0_P1P0_DP<20>")
	)
	(segment
		(start 126.234698 -191.627506)
		(end 127.077978 -190.589916)
		(width 0.14732)
		(layer "In4.Cu")
		(net "UPI_CPU1_CPU0_P1P0_DP<20>")
	)
	(segment
		(start 125.976634 -192.1383)
		(end 126.252478 -191.798956)
		(width 0.14732)
		(layer "In4.Cu")
		(net "UPI_CPU1_CPU0_P1P0_DP<20>")
	)
	(segment
		(start 126.252478 -191.798956)
		(end 126.234698 -191.627506)
		(width 0.14732)
		(layer "In4.Cu")
		(net "UPI_CPU1_CPU0_P1P0_DP<20>")
	)
	(segment
		(start 115.494562 -213.808818)
		(end 115.494562 -212.114892)
		(width 0.0889)
		(layer "In4.Cu")
		(net "UPI_CPU1_CPU0_P1P0_DP<20>")
	)
	(segment
		(start 355.977698 -218.149424)
		(end 355.821234 -217.878406)
		(width 0.0889)
		(layer "In4.Cu")
		(net "UPI_CPU1_CPU0_P1P0_DP<20>")
	)
	(segment
		(start 355.684074 -212.072728)
		(end 355.725984 -212.114638)
		(width 0.0889)
		(layer "In4.Cu")
		(net "UPI_CPU1_CPU0_P1P0_DP<20>")
	)
	(segment
		(start 156.489908 -172.69587)
		(end 200.877678 -171.959016)
		(width 0.14732)
		(layer "In4.Cu")
		(net "UPI_CPU1_CPU0_P1P0_DP<20>")
	)
	(segment
		(start 356.00767 -215.925654)
		(end 356.008432 -215.926162)
		(width 0.0889)
		(layer "In4.Cu")
		(net "UPI_CPU1_CPU0_P1P0_DP<20>")
	)
	(segment
		(start 115.536726 -212.072728)
		(end 115.536726 -212.05063)
		(width 0.0889)
		(layer "In4.Cu")
		(net "UPI_CPU1_CPU0_P1P0_DP<20>")
	)
	(segment
		(start 134.223252 -185.840878)
		(end 138.330686 -180.327046)
		(width 0.14732)
		(layer "In4.Cu")
		(net "UPI_CPU1_CPU0_P1P0_DP<20>")
	)
	(segment
		(start 121.561606 -197.37705)
		(end 121.73331 -197.35927)
		(width 0.14732)
		(layer "In4.Cu")
		(net "UPI_CPU1_CPU0_P1P0_DP<20>")
	)
	(segment
		(start 138.330686 -180.327046)
		(end 149.978618 -174.361856)
		(width 0.14732)
		(layer "In4.Cu")
		(net "UPI_CPU1_CPU0_P1P0_DP<20>")
	)
	(segment
		(start 121.30405 -197.887336)
		(end 121.286524 -197.715886)
		(width 0.14732)
		(layer "In4.Cu")
		(net "UPI_CPU1_CPU0_P1P0_DP<20>")
	)
	(segment
		(start 121.991374 -196.848476)
		(end 121.991628 -196.848476)
		(width 0.14732)
		(layer "In4.Cu")
		(net "UPI_CPU1_CPU0_P1P0_DP<20>")
	)
	(segment
		(start 355.725984 -212.114638)
		(end 355.725984 -213.930484)
		(width 0.0889)
		(layer "In4.Cu")
		(net "UPI_CPU1_CPU0_P1P0_DP<20>")
	)
	(segment
		(start 356.195376 -214.461344)
		(end 356.195376 -214.622634)
		(width 0.0889)
		(layer "In4.Cu")
		(net "UPI_CPU1_CPU0_P1P0_DP<20>")
	)
	(segment
		(start 122.0089 -197.019926)
		(end 121.991374 -196.848476)
		(width 0.14732)
		(layer "In4.Cu")
		(net "UPI_CPU1_CPU0_P1P0_DP<20>")
	)
	(segment
		(start 356.09784 -209.213958)
		(end 356.24262 -209.358738)
		(width 0.14732)
		(layer "In4.Cu")
		(net "UPI_CPU1_CPU0_P1P0_DP<20>")
	)
	(segment
		(start 115.682014 -214.133176)
		(end 115.673124 -214.128096)
		(width 0.0889)
		(layer "In4.Cu")
		(net "UPI_CPU1_CPU0_P1P0_DP<20>")
	)
	(segment
		(start 356.016814 -214.941912)
		(end 356.007924 -214.946992)
		(width 0.0889)
		(layer "In4.Cu")
		(net "UPI_CPU1_CPU0_P1P0_DP<20>")
	)
	(segment
		(start 123.678188 -194.773042)
		(end 123.849892 -194.755262)
		(width 0.14732)
		(layer "In4.Cu")
		(net "UPI_CPU1_CPU0_P1P0_DP<20>")
	)
	(segment
		(start 115.536726 -212.05063)
		(end 115.536726 -211.585302)
		(width 0.14732)
		(layer "In4.Cu")
		(net "UPI_CPU1_CPU0_P1P0_DP<20>")
	)
	(segment
		(start 123.402852 -195.111878)
		(end 123.678188 -194.773042)
		(width 0.14732)
		(layer "In4.Cu")
		(net "UPI_CPU1_CPU0_P1P0_DP<20>")
	)
	(segment
		(start 346.22359 -189.102238)
		(end 352.52279 -195.556886)
		(width 0.14732)
		(layer "In4.Cu")
		(net "UPI_CPU1_CPU0_P1P0_DP<20>")
	)
	(segment
		(start 355.72573 -215.414606)
		(end 355.72573 -215.436704)
		(width 0.0889)
		(layer "In4.Cu")
		(net "UPI_CPU1_CPU0_P1P0_DP<20>")
	)
	(segment
		(start 122.715274 -196.150992)
		(end 122.697748 -195.979542)
		(width 0.14732)
		(layer "In4.Cu")
		(net "UPI_CPU1_CPU0_P1P0_DP<20>")
	)
	(segment
		(start 127.077978 -190.589916)
		(end 134.223252 -185.840878)
		(width 0.14732)
		(layer "In4.Cu")
		(net "UPI_CPU1_CPU0_P1P0_DP<20>")
	)
	(segment
		(start 115.494816 -217.07856)
		(end 115.494816 -217.064336)
		(width 0.0889)
		(layer "In4.Cu")
		(net "UPI_CPU1_CPU0_P1P0_DP<20>")
	)
	(segment
		(start 355.684074 -212.05063)
		(end 355.684074 -212.072728)
		(width 0.0889)
		(layer "In4.Cu")
		(net "UPI_CPU1_CPU0_P1P0_DP<20>")
	)
	(segment
		(start 115.536472 -210.96732)
		(end 119.335042 -200.116948)
		(width 0.14732)
		(layer "In4.Cu")
		(net "UPI_CPU1_CPU0_P1P0_DP<20>")
	)
	(segment
		(start 356.008432 -217.554048)
		(end 356.009194 -217.554556)
		(width 0.0889)
		(layer "In4.Cu")
		(net "UPI_CPU1_CPU0_P1P0_DP<20>")
	)
	(segment
		(start 355.684074 -211.810854)
		(end 355.684074 -212.05063)
		(width 0.14732)
		(layer "In4.Cu")
		(net "UPI_CPU1_CPU0_P1P0_DP<20>")
	)
	(segment
		(start 120.856756 -198.244714)
		(end 120.856756 -198.24446)
		(width 0.14732)
		(layer "In4.Cu")
		(net "UPI_CPU1_CPU0_P1P0_DP<20>")
	)
	(segment
		(start 273.067018 -172.266356)
		(end 302.475392 -171.550584)
		(width 0.14732)
		(layer "In4.Cu")
		(net "UPI_CPU1_CPU0_P1P0_DP<20>")
	)
	(segment
		(start 355.68382 -211.172552)
		(end 355.68382 -211.8106)
		(width 0.14732)
		(layer "In4.Cu")
		(net "UPI_CPU1_CPU0_P1P0_DP<20>")
	)
	(segment
		(start 124.830586 -193.548508)
		(end 124.812806 -193.377058)
		(width 0.14732)
		(layer "In4.Cu")
		(net "UPI_CPU1_CPU0_P1P0_DP<20>")
	)
	(segment
		(start 356.017322 -216.569798)
		(end 356.008432 -216.574878)
		(width 0.0889)
		(layer "In4.Cu")
		(net "UPI_CPU1_CPU0_P1P0_DP<20>")
	)
	(segment
		(start 115.964208 -214.644732)
		(end 115.964208 -214.60714)
		(width 0.0889)
		(layer "In4.Cu")
		(net "UPI_CPU1_CPU0_P1P0_DP<20>")
	)
	(segment
		(start 115.494562 -215.44661)
		(end 115.494562 -215.436704)
		(width 0.0889)
		(layer "In4.Cu")
		(net "UPI_CPU1_CPU0_P1P0_DP<20>")
	)
	(segment
		(start 211.63788 -172.431202)
		(end 238.602774 -172.431202)
		(width 0.14732)
		(layer "In4.Cu")
		(net "UPI_CPU1_CPU0_P1P0_DP<20>")
	)
	(segment
		(start 356.009194 -217.554556)
		(end 356.017322 -217.559128)
		(width 0.0889)
		(layer "In4.Cu")
		(net "UPI_CPU1_CPU0_P1P0_DP<20>")
	)
	(segment
		(start 124.125482 -194.415918)
		(end 124.107956 -194.244468)
		(width 0.14732)
		(layer "In4.Cu")
		(net "UPI_CPU1_CPU0_P1P0_DP<20>")
	)
	(segment
		(start 238.602774 -172.431202)
		(end 273.067018 -172.266356)
		(width 0.14732)
		(layer "In4.Cu")
		(net "UPI_CPU1_CPU0_P1P0_DP<20>")
	)
	(segment
		(start 123.420378 -195.283328)
		(end 123.402852 -195.111878)
		(width 0.14732)
		(layer "In4.Cu")
		(net "UPI_CPU1_CPU0_P1P0_DP<20>")
	)
	(segment
		(start 356.002336 -215.922606)
		(end 356.00767 -215.925654)
		(width 0.0889)
		(layer "In4.Cu")
		(net "UPI_CPU1_CPU0_P1P0_DP<20>")
	)
	(segment
		(start 121.991628 -196.848476)
		(end 122.268488 -196.508116)
		(width 0.14732)
		(layer "In4.Cu")
		(net "UPI_CPU1_CPU0_P1P0_DP<20>")
	)
	(segment
		(start 318.550544 -173.12894)
		(end 330.839318 -177.422048)
		(width 0.14732)
		(layer "In4.Cu")
		(net "UPI_CPU1_CPU0_P1P0_DP<20>")
	)
	(segment
		(start 124.812806 -193.377058)
		(end 125.10008 -193.02349)
		(width 0.14732)
		(layer "In4.Cu")
		(net "UPI_CPU1_CPU0_P1P0_DP<20>")
	)
	(segment
		(start 122.973338 -195.640452)
		(end 122.973084 -195.640452)
		(width 0.14732)
		(layer "In4.Cu")
		(net "UPI_CPU1_CPU0_P1P0_DP<20>")
	)
	(segment
		(start 356.004622 -216.577164)
		(end 356.000812 -216.579196)
		(width 0.0889)
		(layer "In4.Cu")
		(net "UPI_CPU1_CPU0_P1P0_DP<20>")
	)
	(segment
		(start 115.024916 -216.259156)
		(end 115.024916 -216.241884)
		(width 0.0889)
		(layer "In4.Cu")
		(net "UPI_CPU1_CPU0_P1P0_DP<20>")
	)
	(segment
		(start 122.26798 -196.507862)
		(end 122.439684 -196.490082)
		(width 0.14732)
		(layer "In4.Cu")
		(net "UPI_CPU1_CPU0_P1P0_DP<20>")
	)
	(segment
		(start 200.877678 -171.959016)
		(end 211.63788 -172.431202)
		(width 0.14732)
		(layer "In4.Cu")
		(net "UPI_CPU1_CPU0_P1P0_DP<20>")
	)
	(segment
		(start 356.05593 -218.170252)
		(end 355.977698 -218.149424)
		(width 0.0889)
		(layer "In4.Cu")
		(net "UPI_CPU1_CPU0_P1P0_DP<20>")
	)
	(segment
		(start 302.475392 -171.550584)
		(end 313.644026 -171.758356)
		(width 0.14732)
		(layer "In4.Cu")
		(net "UPI_CPU1_CPU0_P1P0_DP<20>")
	)
	(segment
		(start 115.224306 -216.58199)
		(end 115.212114 -216.574878)
		(width 0.0889)
		(layer "In4.Cu")
		(net "UPI_CPU1_CPU0_P1P0_DP<20>")
	)
	(segment
		(start 125.10008 -193.02349)
		(end 125.271784 -193.00571)
		(width 0.14732)
		(layer "In4.Cu")
		(net "UPI_CPU1_CPU0_P1P0_DP<20>")
	)
	(segment
		(start 115.673124 -215.117426)
		(end 115.682014 -215.112346)
		(width 0.0889)
		(layer "In4.Cu")
		(net "UPI_CPU1_CPU0_P1P0_DP<20>")
	)
	(segment
		(start 124.107956 -194.244468)
		(end 124.383292 -193.905632)
		(width 0.14732)
		(layer "In4.Cu")
		(net "UPI_CPU1_CPU0_P1P0_DP<20>")
	)
	(segment
		(start 352.52279 -195.556886)
		(end 356.24262 -204.536802)
		(width 0.14732)
		(layer "In4.Cu")
		(net "UPI_CPU1_CPU0_P1P0_DP<20>")
	)
	(segment
		(start 121.02846 -198.22668)
		(end 121.30405 -197.887336)
		(width 0.14732)
		(layer "In4.Cu")
		(net "UPI_CPU1_CPU0_P1P0_DP<20>")
	)
	(segment
		(start 123.849892 -194.755262)
		(end 124.125482 -194.415918)
		(width 0.14732)
		(layer "In4.Cu")
		(net "UPI_CPU1_CPU0_P1P0_DP<20>")
	)
	(segment
		(start 122.268488 -196.508116)
		(end 122.26798 -196.507862)
		(width 0.14732)
		(layer "In4.Cu")
		(net "UPI_CPU1_CPU0_P1P0_DP<20>")
	)
	(segment
		(start 122.697748 -195.979542)
		(end 122.973338 -195.640452)
		(width 0.14732)
		(layer "In4.Cu")
		(net "UPI_CPU1_CPU0_P1P0_DP<20>")
	)
	(segment
		(start 356.008432 -215.926162)
		(end 356.009956 -215.926924)
		(width 0.0889)
		(layer "In4.Cu")
		(net "UPI_CPU1_CPU0_P1P0_DP<20>")
	)
	(segment
		(start 121.56186 -197.37705)
		(end 121.561606 -197.37705)
		(width 0.14732)
		(layer "In4.Cu")
		(net "UPI_CPU1_CPU0_P1P0_DP<20>")
	)
	(segment
		(start 330.839318 -177.422048)
		(end 338.063078 -180.496464)
		(width 0.14732)
		(layer "In4.Cu")
		(net "UPI_CPU1_CPU0_P1P0_DP<20>")
	)
	(segment
		(start 339.881718 -181.7243)
		(end 343.75852 -185.600848)
		(width 0.14732)
		(layer "In4.Cu")
		(net "UPI_CPU1_CPU0_P1P0_DP<20>")
	)
	(segment
		(start 356.24262 -209.823304)
		(end 355.68382 -211.172552)
		(width 0.14732)
		(layer "In4.Cu")
		(net "UPI_CPU1_CPU0_P1P0_DP<20>")
	)
	(segment
		(start 355.72573 -217.064336)
		(end 355.72573 -217.071956)
		(width 0.0889)
		(layer "In4.Cu")
		(net "UPI_CPU1_CPU0_P1P0_DP<20>")
	)
	(segment
		(start 343.75852 -185.600848)
		(end 346.22359 -189.102238)
		(width 0.14732)
		(layer "In4.Cu")
		(net "UPI_CPU1_CPU0_P1P0_DP<20>")
	)
	(segment
		(start 115.536726 -211.585302)
		(end 115.536472 -211.585048)
		(width 0.14732)
		(layer "In4.Cu")
		(net "UPI_CPU1_CPU0_P1P0_DP<20>")
	)
	(segment
		(start 356.24262 -204.536802)
		(end 356.24262 -208.700878)
		(width 0.14732)
		(layer "In4.Cu")
		(net "UPI_CPU1_CPU0_P1P0_DP<20>")
	)
	(segment
		(start 124.554742 -193.887852)
		(end 124.830586 -193.548508)
		(width 0.14732)
		(layer "In4.Cu")
		(net "UPI_CPU1_CPU0_P1P0_DP<20>")
	)
	(segment
		(start 121.286524 -197.715886)
		(end 121.56186 -197.37705)
		(width 0.14732)
		(layer "In4.Cu")
		(net "UPI_CPU1_CPU0_P1P0_DP<20>")
	)
	(segment
		(start 119.335042 -200.116948)
		(end 120.856756 -198.244714)
		(width 0.14732)
		(layer "In4.Cu")
		(net "UPI_CPU1_CPU0_P1P0_DP<20>")
	)
	(segment
		(start 356.008432 -216.574878)
		(end 356.004622 -216.577164)
		(width 0.0889)
		(layer "In4.Cu")
		(net "UPI_CPU1_CPU0_P1P0_DP<20>")
	)
	(segment
		(start 115.494562 -212.114892)
		(end 115.536726 -212.072728)
		(width 0.0889)
		(layer "In4.Cu")
		(net "UPI_CPU1_CPU0_P1P0_DP<20>")
	)
	(arc
		(start 115.283996 -217.50528)
		(mid 115.436503 -217.315182)
		(end 115.494816 -217.07856)
		(width 0.0889)
		(layer "In4.Cu")
		(net "UPI_CPU1_CPU0_P1P0_DP<20>")
	)
	(arc
		(start 115.212114 -215.926162)
		(mid 115.416449 -215.723557)
		(end 115.494562 -215.44661)
		(width 0.0889)
		(layer "In4.Cu")
		(net "UPI_CPU1_CPU0_P1P0_DP<20>")
	)
	(arc
		(start 115.673124 -214.128096)
		(mid 115.54221 -213.991736)
		(end 115.494562 -213.808818)
		(width 0.0889)
		(layer "In4.Cu")
		(net "UPI_CPU1_CPU0_P1P0_DP<20>")
	)
	(arc
		(start 355.725984 -213.930484)
		(mid 355.733269 -213.950046)
		(end 355.741224 -213.969346)
		(width 0.0889)
		(layer "In4.Cu")
		(net "UPI_CPU1_CPU0_P1P0_DP<20>")
	)
	(arc
		(start 355.99624 -216.58199)
		(mid 355.798012 -216.787838)
		(end 355.72573 -217.064336)
		(width 0.0889)
		(layer "In4.Cu")
		(net "UPI_CPU1_CPU0_P1P0_DP<20>")
	)
	(arc
		(start 115.212114 -216.574878)
		(mid 115.077181 -216.441524)
		(end 115.024916 -216.259156)
		(width 0.0889)
		(layer "In4.Cu")
		(net "UPI_CPU1_CPU0_P1P0_DP<20>")
	)
	(arc
		(start 115.682014 -215.112346)
		(mid 115.883296 -214.914859)
		(end 115.964208 -214.644732)
		(width 0.0889)
		(layer "In4.Cu")
		(net "UPI_CPU1_CPU0_P1P0_DP<20>")
	)
	(arc
		(start 355.72573 -217.071956)
		(mid 355.803359 -217.350369)
		(end 356.008432 -217.554048)
		(width 0.0889)
		(layer "In4.Cu")
		(net "UPI_CPU1_CPU0_P1P0_DP<20>")
	)
	(arc
		(start 356.017322 -217.559128)
		(mid 356.148236 -217.695488)
		(end 356.195884 -217.878406)
		(width 0.0889)
		(layer "In4.Cu")
		(net "UPI_CPU1_CPU0_P1P0_DP<20>")
	)
	(arc
		(start 356.195376 -214.622634)
		(mid 356.147697 -214.805534)
		(end 356.016814 -214.941912)
		(width 0.0889)
		(layer "In4.Cu")
		(net "UPI_CPU1_CPU0_P1P0_DP<20>")
	)
	(arc
		(start 356.007924 -214.946992)
		(mid 355.806642 -215.144479)
		(end 355.72573 -215.414606)
		(width 0.0889)
		(layer "In4.Cu")
		(net "UPI_CPU1_CPU0_P1P0_DP<20>")
	)
	(arc
		(start 115.494816 -215.421972)
		(mid 115.54587 -215.247392)
		(end 115.673124 -215.117426)
		(width 0.0889)
		(layer "In4.Cu")
		(net "UPI_CPU1_CPU0_P1P0_DP<20>")
	)
	(arc
		(start 115.494816 -217.064336)
		(mid 115.422581 -216.787812)
		(end 115.224306 -216.58199)
		(width 0.0889)
		(layer "In4.Cu")
		(net "UPI_CPU1_CPU0_P1P0_DP<20>")
	)
	(arc
		(start 115.964208 -214.60714)
		(mid 115.884838 -214.333406)
		(end 115.682014 -214.133176)
		(width 0.0889)
		(layer "In4.Cu")
		(net "UPI_CPU1_CPU0_P1P0_DP<20>")
	)
	(arc
		(start 115.024916 -216.241884)
		(mid 115.077186 -216.059519)
		(end 115.212114 -215.926162)
		(width 0.0889)
		(layer "In4.Cu")
		(net "UPI_CPU1_CPU0_P1P0_DP<20>")
	)
	(arc
		(start 355.741224 -213.969346)
		(mid 355.851218 -214.138715)
		(end 356.011226 -214.261954)
		(width 0.0889)
		(layer "In4.Cu")
		(net "UPI_CPU1_CPU0_P1P0_DP<20>")
	)
	(arc
		(start 115.494562 -215.436704)
		(mid 115.494614 -215.429337)
		(end 115.494816 -215.421972)
		(width 0.0889)
		(layer "In4.Cu")
		(net "UPI_CPU1_CPU0_P1P0_DP<20>")
	)
	(arc
		(start 355.72573 -215.436704)
		(mid 355.799721 -215.71627)
		(end 356.002336 -215.922606)
		(width 0.0889)
		(layer "In4.Cu")
		(net "UPI_CPU1_CPU0_P1P0_DP<20>")
	)
	(arc
		(start 356.011226 -214.261954)
		(mid 356.120373 -214.345882)
		(end 356.195376 -214.461344)
		(width 0.0889)
		(layer "In4.Cu")
		(net "UPI_CPU1_CPU0_P1P0_DP<20>")
	)
	(arc
		(start 115.267232 -217.518234)
		(mid 115.275675 -217.511836)
		(end 115.283996 -217.50528)
		(width 0.0889)
		(layer "In4.Cu")
		(net "UPI_CPU1_CPU0_P1P0_DP<20>")
	)
	(arc
		(start 356.017322 -215.931242)
		(mid 356.195919 -216.25052)
		(end 356.017322 -216.569798)
		(width 0.0889)
		(layer "In4.Cu")
		(net "UPI_CPU1_CPU0_P1P0_DP<20>")
	)
	(arc
		(start 356.195884 -217.878406)
		(mid 356.159024 -218.040203)
		(end 356.05593 -218.170252)
		(width 0.0889)
		(layer "In4.Cu")
		(net "UPI_CPU1_CPU0_P1P0_DP<20>")
	)
	(segment
		(start 337.96478 -218.414346)
		(end 337.96478 -217.87866)
		(width 0.13208)
		(layer "F.Cu")
		(net "UPI_CPU1_CPU0_P1P0_DP<1>")
	)
	(segment
		(start 337.96478 -217.87866)
		(end 337.965034 -217.878406)
		(width 0.13208)
		(layer "F.Cu")
		(net "UPI_CPU1_CPU0_P1P0_DP<1>")
	)
	(segment
		(start 133.255512 -217.87866)
		(end 133.255766 -217.878406)
		(width 0.13208)
		(layer "F.Cu")
		(net "UPI_CPU1_CPU0_P1P0_DP<1>")
	)
	(segment
		(start 133.255512 -218.414346)
		(end 133.255512 -217.87866)
		(width 0.13208)
		(layer "F.Cu")
		(net "UPI_CPU1_CPU0_P1P0_DP<1>")
	)
	(segment
		(start 144.605756 -201.736706)
		(end 144.813274 -201.735944)
		(width 0.14732)
		(layer "In4.Cu")
		(net "UPI_CPU1_CPU0_P1P0_DP<1>")
	)
	(segment
		(start 337.827874 -208.571338)
		(end 337.827874 -209.053938)
		(width 0.14732)
		(layer "In4.Cu")
		(net "UPI_CPU1_CPU0_P1P0_DP<1>")
	)
	(segment
		(start 163.841938 -190.602362)
		(end 163.86175 -189.125098)
		(width 0.14732)
		(layer "In4.Cu")
		(net "UPI_CPU1_CPU0_P1P0_DP<1>")
	)
	(segment
		(start 146.237198 -200.090024)
		(end 146.444716 -200.089008)
		(width 0.14732)
		(layer "In4.Cu")
		(net "UPI_CPU1_CPU0_P1P0_DP<1>")
	)
	(segment
		(start 338.097368 -217.518234)
		(end 338.121498 -217.607388)
		(width 0.0889)
		(layer "In4.Cu")
		(net "UPI_CPU1_CPU0_P1P0_DP<1>")
	)
	(segment
		(start 301.009558 -188.520832)
		(end 302.473106 -187.788804)
		(width 0.14732)
		(layer "In4.Cu")
		(net "UPI_CPU1_CPU0_P1P0_DP<1>")
	)
	(segment
		(start 134.760208 -213.928452)
		(end 135.018272 -213.670388)
		(width 0.0889)
		(layer "In4.Cu")
		(net "UPI_CPU1_CPU0_P1P0_DP<1>")
	)
	(segment
		(start 318.426592 -193.129662)
		(end 331.620876 -197.648576)
		(width 0.14732)
		(layer "In4.Cu")
		(net "UPI_CPU1_CPU0_P1P0_DP<1>")
	)
	(segment
		(start 338.152232 -215.926162)
		(end 338.153756 -215.926924)
		(width 0.0889)
		(layer "In4.Cu")
		(net "UPI_CPU1_CPU0_P1P0_DP<1>")
	)
	(segment
		(start 139.743942 -208.510632)
		(end 139.944856 -208.4705)
		(width 0.14732)
		(layer "In4.Cu")
		(net "UPI_CPU1_CPU0_P1P0_DP<1>")
	)
	(segment
		(start 164.010594 -188.980318)
		(end 164.601144 -188.988192)
		(width 0.14732)
		(layer "In4.Cu")
		(net "UPI_CPU1_CPU0_P1P0_DP<1>")
	)
	(segment
		(start 133.538976 -216.73947)
		(end 133.54431 -216.736422)
		(width 0.0889)
		(layer "In4.Cu")
		(net "UPI_CPU1_CPU0_P1P0_DP<1>")
	)
	(segment
		(start 135.230362 -215.452198)
		(end 135.230362 -215.23833)
		(width 0.0889)
		(layer "In4.Cu")
		(net "UPI_CPU1_CPU0_P1P0_DP<1>")
	)
	(segment
		(start 142.408656 -205.232)
		(end 142.792958 -204.844142)
		(width 0.14732)
		(layer "In4.Cu")
		(net "UPI_CPU1_CPU0_P1P0_DP<1>")
	)
	(segment
		(start 133.059678 -217.559128)
		(end 133.068568 -217.554048)
		(width 0.0889)
		(layer "In4.Cu")
		(net "UPI_CPU1_CPU0_P1P0_DP<1>")
	)
	(segment
		(start 138.762994 -209.984594)
		(end 139.175236 -209.365088)
		(width 0.14732)
		(layer "In4.Cu")
		(net "UPI_CPU1_CPU0_P1P0_DP<1>")
	)
	(segment
		(start 148.07565 -198.442326)
		(end 148.391626 -198.755254)
		(width 0.14732)
		(layer "In4.Cu")
		(net "UPI_CPU1_CPU0_P1P0_DP<1>")
	)
	(segment
		(start 141.68628 -205.96098)
		(end 141.94536 -205.699614)
		(width 0.14732)
		(layer "In4.Cu")
		(net "UPI_CPU1_CPU0_P1P0_DP<1>")
	)
	(segment
		(start 331.620876 -197.648576)
		(end 333.344774 -199.004682)
		(width 0.14732)
		(layer "In4.Cu")
		(net "UPI_CPU1_CPU0_P1P0_DP<1>")
	)
	(segment
		(start 140.938504 -206.71536)
		(end 141.222984 -206.42834)
		(width 0.14732)
		(layer "In4.Cu")
		(net "UPI_CPU1_CPU0_P1P0_DP<1>")
	)
	(segment
		(start 141.94536 -205.699614)
		(end 142.150084 -205.698598)
		(width 0.14732)
		(layer "In4.Cu")
		(net "UPI_CPU1_CPU0_P1P0_DP<1>")
	)
	(segment
		(start 338.919312 -204.57922)
		(end 339.422994 -205.795118)
		(width 0.14732)
		(layer "In4.Cu")
		(net "UPI_CPU1_CPU0_P1P0_DP<1>")
	)
	(segment
		(start 139.944856 -208.4705)
		(end 140.148818 -208.163414)
		(width 0.14732)
		(layer "In4.Cu")
		(net "UPI_CPU1_CPU0_P1P0_DP<1>")
	)
	(segment
		(start 135.0772 -213.670388)
		(end 135.092694 -213.654894)
		(width 0.0889)
		(layer "In4.Cu")
		(net "UPI_CPU1_CPU0_P1P0_DP<1>")
	)
	(segment
		(start 140.513308 -207.616044)
		(end 140.71727 -207.308958)
		(width 0.14732)
		(layer "In4.Cu")
		(net "UPI_CPU1_CPU0_P1P0_DP<1>")
	)
	(segment
		(start 156.17952 -192.386966)
		(end 157.525974 -191.702944)
		(width 0.14732)
		(layer "In4.Cu")
		(net "UPI_CPU1_CPU0_P1P0_DP<1>")
	)
	(segment
		(start 133.351016 -217.082878)
		(end 133.351016 -217.0557)
		(width 0.0889)
		(layer "In4.Cu")
		(net "UPI_CPU1_CPU0_P1P0_DP<1>")
	)
	(segment
		(start 311.982104 -188.005974)
		(end 318.426592 -193.129662)
		(width 0.14732)
		(layer "In4.Cu")
		(net "UPI_CPU1_CPU0_P1P0_DP<1>")
	)
	(segment
		(start 145.821146 -200.509886)
		(end 146.237198 -200.090024)
		(width 0.14732)
		(layer "In4.Cu")
		(net "UPI_CPU1_CPU0_P1P0_DP<1>")
	)
	(segment
		(start 145.129504 -202.048872)
		(end 145.565114 -202.046586)
		(width 0.14732)
		(layer "In4.Cu")
		(net "UPI_CPU1_CPU0_P1P0_DP<1>")
	)
	(segment
		(start 147.196302 -200.400158)
		(end 147.771358 -199.819768)
		(width 0.14732)
		(layer "In4.Cu")
		(net "UPI_CPU1_CPU0_P1P0_DP<1>")
	)
	(segment
		(start 139.37615 -209.324702)
		(end 139.580112 -209.01787)
		(width 0.14732)
		(layer "In4.Cu")
		(net "UPI_CPU1_CPU0_P1P0_DP<1>")
	)
	(segment
		(start 337.870038 -212.101938)
		(end 337.870038 -213.929468)
		(width 0.0889)
		(layer "In4.Cu")
		(net "UPI_CPU1_CPU0_P1P0_DP<1>")
	)
	(segment
		(start 337.827874 -211.800948)
		(end 337.828128 -211.801202)
		(width 0.14732)
		(layer "In4.Cu")
		(net "UPI_CPU1_CPU0_P1P0_DP<1>")
	)
	(segment
		(start 337.869784 -213.929722)
		(end 337.869784 -213.930484)
		(width 0.0889)
		(layer "In4.Cu")
		(net "UPI_CPU1_CPU0_P1P0_DP<1>")
	)
	(segment
		(start 141.427708 -206.427578)
		(end 141.687042 -206.165704)
		(width 0.14732)
		(layer "In4.Cu")
		(net "UPI_CPU1_CPU0_P1P0_DP<1>")
	)
	(segment
		(start 140.108432 -207.962754)
		(end 140.312394 -207.656176)
		(width 0.14732)
		(layer "In4.Cu")
		(net "UPI_CPU1_CPU0_P1P0_DP<1>")
	)
	(segment
		(start 140.677138 -207.108298)
		(end 140.938504 -206.71536)
		(width 0.14732)
		(layer "In4.Cu")
		(net "UPI_CPU1_CPU0_P1P0_DP<1>")
	)
	(segment
		(start 151.445214 -196.114416)
		(end 153.226008 -195.366894)
		(width 0.14732)
		(layer "In4.Cu")
		(net "UPI_CPU1_CPU0_P1P0_DP<1>")
	)
	(segment
		(start 147.868386 -198.443342)
		(end 148.07565 -198.442326)
		(width 0.14732)
		(layer "In4.Cu")
		(net "UPI_CPU1_CPU0_P1P0_DP<1>")
	)
	(segment
		(start 239.036352 -199.73417)
		(end 250.227338 -194.613022)
		(width 0.14732)
		(layer "In4.Cu")
		(net "UPI_CPU1_CPU0_P1P0_DP<1>")
	)
	(segment
		(start 337.86953 -217.064336)
		(end 337.86953 -217.07856)
		(width 0.0889)
		(layer "In4.Cu")
		(net "UPI_CPU1_CPU0_P1P0_DP<1>")
	)
	(segment
		(start 141.687042 -206.165704)
		(end 141.68628 -205.96098)
		(width 0.14732)
		(layer "In4.Cu")
		(net "UPI_CPU1_CPU0_P1P0_DP<1>")
	)
	(segment
		(start 142.150084 -205.698598)
		(end 142.409672 -205.436724)
		(width 0.14732)
		(layer "In4.Cu")
		(net "UPI_CPU1_CPU0_P1P0_DP<1>")
	)
	(segment
		(start 311.86882 -187.972446)
		(end 311.982104 -188.005974)
		(width 0.14732)
		(layer "In4.Cu")
		(net "UPI_CPU1_CPU0_P1P0_DP<1>")
	)
	(segment
		(start 157.525974 -191.702944)
		(end 159.862012 -190.857124)
		(width 0.14732)
		(layer "In4.Cu")
		(net "UPI_CPU1_CPU0_P1P0_DP<1>")
	)
	(segment
		(start 235.964476 -199.943466)
		(end 237.361222 -199.943466)
		(width 0.14732)
		(layer "In4.Cu")
		(net "UPI_CPU1_CPU0_P1P0_DP<1>")
	)
	(segment
		(start 163.530534 -190.9064)
		(end 163.841938 -190.602362)
		(width 0.14732)
		(layer "In4.Cu")
		(net "UPI_CPU1_CPU0_P1P0_DP<1>")
	)
	(segment
		(start 146.444716 -200.089008)
		(end 146.760946 -200.40219)
		(width 0.14732)
		(layer "In4.Cu")
		(net "UPI_CPU1_CPU0_P1P0_DP<1>")
	)
	(segment
		(start 146.137884 -201.030586)
		(end 145.822162 -200.717658)
		(width 0.14732)
		(layer "In4.Cu")
		(net "UPI_CPU1_CPU0_P1P0_DP<1>")
	)
	(segment
		(start 335.612486 -202.242674)
		(end 335.612486 -202.67803)
		(width 0.14732)
		(layer "In4.Cu")
		(net "UPI_CPU1_CPU0_P1P0_DP<1>")
	)
	(segment
		(start 337.828128 -212.060028)
		(end 337.870038 -212.101938)
		(width 0.0889)
		(layer "In4.Cu")
		(net "UPI_CPU1_CPU0_P1P0_DP<1>")
	)
	(segment
		(start 154.062684 -194.728592)
		(end 154.061668 -194.523868)
		(width 0.14732)
		(layer "In4.Cu")
		(net "UPI_CPU1_CPU0_P1P0_DP<1>")
	)
	(segment
		(start 143.256254 -204.376782)
		(end 144.508728 -203.112878)
		(width 0.14732)
		(layer "In4.Cu")
		(net "UPI_CPU1_CPU0_P1P0_DP<1>")
	)
	(segment
		(start 337.683094 -209.567018)
		(end 337.827874 -209.711798)
		(width 0.14732)
		(layer "In4.Cu")
		(net "UPI_CPU1_CPU0_P1P0_DP<1>")
	)
	(segment
		(start 165.031166 -190.925958)
		(end 191.097154 -191.274954)
		(width 0.14732)
		(layer "In4.Cu")
		(net "UPI_CPU1_CPU0_P1P0_DP<1>")
	)
	(segment
		(start 148.827236 -198.75373)
		(end 151.445214 -196.114416)
		(width 0.14732)
		(layer "In4.Cu")
		(net "UPI_CPU1_CPU0_P1P0_DP<1>")
	)
	(segment
		(start 237.361222 -199.943466)
		(end 239.036352 -199.73417)
		(width 0.14732)
		(layer "In4.Cu")
		(net "UPI_CPU1_CPU0_P1P0_DP<1>")
	)
	(segment
		(start 338.161122 -216.569798)
		(end 338.153756 -216.574116)
		(width 0.0889)
		(layer "In4.Cu")
		(net "UPI_CPU1_CPU0_P1P0_DP<1>")
	)
	(segment
		(start 333.344774 -199.004682)
		(end 334.947006 -200.606914)
		(width 0.14732)
		(layer "In4.Cu")
		(net "UPI_CPU1_CPU0_P1P0_DP<1>")
	)
	(segment
		(start 338.149438 -216.576402)
		(end 338.146136 -216.578434)
		(width 0.0889)
		(layer "In4.Cu")
		(net "UPI_CPU1_CPU0_P1P0_DP<1>")
	)
	(segment
		(start 208.440782 -190.573914)
		(end 220.23832 -192.476882)
		(width 0.14732)
		(layer "In4.Cu")
		(net "UPI_CPU1_CPU0_P1P0_DP<1>")
	)
	(segment
		(start 250.227338 -194.613022)
		(end 261.11835 -191.708024)
		(width 0.14732)
		(layer "In4.Cu")
		(net "UPI_CPU1_CPU0_P1P0_DP<1>")
	)
	(segment
		(start 297.719496 -190.744856)
		(end 298.43476 -190.580518)
		(width 0.14732)
		(layer "In4.Cu")
		(net "UPI_CPU1_CPU0_P1P0_DP<1>")
	)
	(segment
		(start 133.255766 -217.878406)
		(end 133.099302 -218.149424)
		(width 0.0889)
		(layer "In4.Cu")
		(net "UPI_CPU1_CPU0_P1P0_DP<1>")
	)
	(segment
		(start 164.746432 -189.13729)
		(end 164.72662 -190.615062)
		(width 0.14732)
		(layer "In4.Cu")
		(net "UPI_CPU1_CPU0_P1P0_DP<1>")
	)
	(segment
		(start 135.092694 -213.654894)
		(end 138.762994 -209.984594)
		(width 0.14732)
		(layer "In4.Cu")
		(net "UPI_CPU1_CPU0_P1P0_DP<1>")
	)
	(segment
		(start 135.018272 -213.670388)
		(end 135.0772 -213.670388)
		(width 0.0889)
		(layer "In4.Cu")
		(net "UPI_CPU1_CPU0_P1P0_DP<1>")
	)
	(segment
		(start 335.436464 -201.096372)
		(end 335.993486 -201.653394)
		(width 0.14732)
		(layer "In4.Cu")
		(net "UPI_CPU1_CPU0_P1P0_DP<1>")
	)
	(segment
		(start 159.862012 -190.857124)
		(end 163.530534 -190.9064)
		(width 0.14732)
		(layer "In4.Cu")
		(net "UPI_CPU1_CPU0_P1P0_DP<1>")
	)
	(segment
		(start 134.760716 -214.707978)
		(end 134.760208 -214.70747)
		(width 0.0889)
		(layer "In4.Cu")
		(net "UPI_CPU1_CPU0_P1P0_DP<1>")
	)
	(segment
		(start 338.121498 -217.607388)
		(end 337.965034 -217.878406)
		(width 0.0889)
		(layer "In4.Cu")
		(net "UPI_CPU1_CPU0_P1P0_DP<1>")
	)
	(segment
		(start 144.813274 -201.735944)
		(end 145.129504 -202.048872)
		(width 0.14732)
		(layer "In4.Cu")
		(net "UPI_CPU1_CPU0_P1P0_DP<1>")
	)
	(segment
		(start 140.148818 -208.163414)
		(end 140.108432 -207.962754)
		(width 0.14732)
		(layer "In4.Cu")
		(net "UPI_CPU1_CPU0_P1P0_DP<1>")
	)
	(segment
		(start 339.422994 -205.795118)
		(end 339.422994 -206.976218)
		(width 0.14732)
		(layer "In4.Cu")
		(net "UPI_CPU1_CPU0_P1P0_DP<1>")
	)
	(segment
		(start 337.828128 -211.801202)
		(end 337.828128 -212.03793)
		(width 0.14732)
		(layer "In4.Cu")
		(net "UPI_CPU1_CPU0_P1P0_DP<1>")
	)
	(segment
		(start 140.71727 -207.308958)
		(end 140.677138 -207.108298)
		(width 0.14732)
		(layer "In4.Cu")
		(net "UPI_CPU1_CPU0_P1P0_DP<1>")
	)
	(segment
		(start 232.848404 -199.168004)
		(end 235.964476 -199.943466)
		(width 0.14732)
		(layer "In4.Cu")
		(net "UPI_CPU1_CPU0_P1P0_DP<1>")
	)
	(segment
		(start 143.25727 -204.581252)
		(end 143.256254 -204.376782)
		(width 0.14732)
		(layer "In4.Cu")
		(net "UPI_CPU1_CPU0_P1P0_DP<1>")
	)
	(segment
		(start 337.870038 -213.929468)
		(end 337.869784 -213.929722)
		(width 0.0889)
		(layer "In4.Cu")
		(net "UPI_CPU1_CPU0_P1P0_DP<1>")
	)
	(segment
		(start 153.598372 -194.991228)
		(end 153.803096 -194.990466)
		(width 0.14732)
		(layer "In4.Cu")
		(net "UPI_CPU1_CPU0_P1P0_DP<1>")
	)
	(segment
		(start 144.507204 -202.677522)
		(end 144.190974 -202.364086)
		(width 0.14732)
		(layer "In4.Cu")
		(net "UPI_CPU1_CPU0_P1P0_DP<1>")
	)
	(segment
		(start 154.061668 -194.523868)
		(end 156.17952 -192.386966)
		(width 0.14732)
		(layer "In4.Cu")
		(net "UPI_CPU1_CPU0_P1P0_DP<1>")
	)
	(segment
		(start 144.189958 -202.156314)
		(end 144.605756 -201.736706)
		(width 0.14732)
		(layer "In4.Cu")
		(net "UPI_CPU1_CPU0_P1P0_DP<1>")
	)
	(segment
		(start 140.312394 -207.656176)
		(end 140.513308 -207.616044)
		(width 0.14732)
		(layer "In4.Cu")
		(net "UPI_CPU1_CPU0_P1P0_DP<1>")
	)
	(segment
		(start 139.580112 -209.01787)
		(end 139.53998 -208.81721)
		(width 0.14732)
		(layer "In4.Cu")
		(net "UPI_CPU1_CPU0_P1P0_DP<1>")
	)
	(segment
		(start 338.146136 -215.922606)
		(end 338.15147 -215.925654)
		(width 0.0889)
		(layer "In4.Cu")
		(net "UPI_CPU1_CPU0_P1P0_DP<1>")
	)
	(segment
		(start 286.488886 -190.696088)
		(end 297.719496 -190.744856)
		(width 0.14732)
		(layer "In4.Cu")
		(net "UPI_CPU1_CPU0_P1P0_DP<1>")
	)
	(segment
		(start 338.153756 -215.926924)
		(end 338.161122 -215.931242)
		(width 0.0889)
		(layer "In4.Cu")
		(net "UPI_CPU1_CPU0_P1P0_DP<1>")
	)
	(segment
		(start 134.760208 -214.70747)
		(end 134.760208 -213.928452)
		(width 0.0889)
		(layer "In4.Cu")
		(net "UPI_CPU1_CPU0_P1P0_DP<1>")
	)
	(segment
		(start 153.803096 -194.990466)
		(end 154.062684 -194.728592)
		(width 0.14732)
		(layer "In4.Cu")
		(net "UPI_CPU1_CPU0_P1P0_DP<1>")
	)
	(segment
		(start 134.382764 -215.926162)
		(end 134.397496 -215.934798)
		(width 0.0889)
		(layer "In4.Cu")
		(net "UPI_CPU1_CPU0_P1P0_DP<1>")
	)
	(segment
		(start 337.828128 -212.03793)
		(end 337.828128 -212.060028)
		(width 0.0889)
		(layer "In4.Cu")
		(net "UPI_CPU1_CPU0_P1P0_DP<1>")
	)
	(segment
		(start 147.769072 -199.383904)
		(end 147.45335 -199.070976)
		(width 0.14732)
		(layer "In4.Cu")
		(net "UPI_CPU1_CPU0_P1P0_DP<1>")
	)
	(segment
		(start 142.409672 -205.436724)
		(end 142.408656 -205.232)
		(width 0.14732)
		(layer "In4.Cu")
		(net "UPI_CPU1_CPU0_P1P0_DP<1>")
	)
	(segment
		(start 147.452334 -198.863204)
		(end 147.868386 -198.443342)
		(width 0.14732)
		(layer "In4.Cu")
		(net "UPI_CPU1_CPU0_P1P0_DP<1>")
	)
	(segment
		(start 147.45335 -199.070976)
		(end 147.452334 -198.863204)
		(width 0.14732)
		(layer "In4.Cu")
		(net "UPI_CPU1_CPU0_P1P0_DP<1>")
	)
	(segment
		(start 144.190974 -202.364086)
		(end 144.189958 -202.156314)
		(width 0.14732)
		(layer "In4.Cu")
		(net "UPI_CPU1_CPU0_P1P0_DP<1>")
	)
	(segment
		(start 302.473106 -187.788804)
		(end 311.86882 -187.972446)
		(width 0.14732)
		(layer "In4.Cu")
		(net "UPI_CPU1_CPU0_P1P0_DP<1>")
	)
	(segment
		(start 142.792958 -204.844142)
		(end 142.997682 -204.843126)
		(width 0.14732)
		(layer "In4.Cu")
		(net "UPI_CPU1_CPU0_P1P0_DP<1>")
	)
	(segment
		(start 335.612486 -202.67803)
		(end 336.190844 -203.256388)
		(width 0.14732)
		(layer "In4.Cu")
		(net "UPI_CPU1_CPU0_P1P0_DP<1>")
	)
	(segment
		(start 146.760946 -200.40219)
		(end 147.196302 -200.400158)
		(width 0.14732)
		(layer "In4.Cu")
		(net "UPI_CPU1_CPU0_P1P0_DP<1>")
	)
	(segment
		(start 298.43476 -190.580518)
		(end 301.009558 -188.520832)
		(width 0.14732)
		(layer "In4.Cu")
		(net "UPI_CPU1_CPU0_P1P0_DP<1>")
	)
	(segment
		(start 142.997682 -204.843126)
		(end 143.25727 -204.581252)
		(width 0.14732)
		(layer "In4.Cu")
		(net "UPI_CPU1_CPU0_P1P0_DP<1>")
	)
	(segment
		(start 337.683094 -209.198718)
		(end 337.683094 -209.567018)
		(width 0.14732)
		(layer "In4.Cu")
		(net "UPI_CPU1_CPU0_P1P0_DP<1>")
	)
	(segment
		(start 335.993486 -201.653394)
		(end 335.993486 -201.861674)
		(width 0.14732)
		(layer "In4.Cu")
		(net "UPI_CPU1_CPU0_P1P0_DP<1>")
	)
	(segment
		(start 148.391626 -198.755254)
		(end 148.827236 -198.75373)
		(width 0.14732)
		(layer "In4.Cu")
		(net "UPI_CPU1_CPU0_P1P0_DP<1>")
	)
	(segment
		(start 334.947006 -200.606914)
		(end 334.947006 -200.811638)
		(width 0.14732)
		(layer "In4.Cu")
		(net "UPI_CPU1_CPU0_P1P0_DP<1>")
	)
	(segment
		(start 335.993486 -201.861674)
		(end 335.612486 -202.242674)
		(width 0.14732)
		(layer "In4.Cu")
		(net "UPI_CPU1_CPU0_P1P0_DP<1>")
	)
	(segment
		(start 220.23832 -192.476882)
		(end 232.848404 -199.168004)
		(width 0.14732)
		(layer "In4.Cu")
		(net "UPI_CPU1_CPU0_P1P0_DP<1>")
	)
	(segment
		(start 336.6262 -203.256388)
		(end 337.0072 -202.875388)
		(width 0.14732)
		(layer "In4.Cu")
		(net "UPI_CPU1_CPU0_P1P0_DP<1>")
	)
	(segment
		(start 335.23174 -201.096372)
		(end 335.436464 -201.096372)
		(width 0.14732)
		(layer "In4.Cu")
		(net "UPI_CPU1_CPU0_P1P0_DP<1>")
	)
	(segment
		(start 337.86953 -215.414606)
		(end 337.86953 -215.436704)
		(width 0.0889)
		(layer "In4.Cu")
		(net "UPI_CPU1_CPU0_P1P0_DP<1>")
	)
	(segment
		(start 147.771358 -199.819768)
		(end 147.769072 -199.383904)
		(width 0.14732)
		(layer "In4.Cu")
		(net "UPI_CPU1_CPU0_P1P0_DP<1>")
	)
	(segment
		(start 139.53998 -208.81721)
		(end 139.743942 -208.510632)
		(width 0.14732)
		(layer "In4.Cu")
		(net "UPI_CPU1_CPU0_P1P0_DP<1>")
	)
	(segment
		(start 339.422994 -206.976218)
		(end 337.827874 -208.571338)
		(width 0.14732)
		(layer "In4.Cu")
		(net "UPI_CPU1_CPU0_P1P0_DP<1>")
	)
	(segment
		(start 145.822162 -200.717658)
		(end 145.821146 -200.509886)
		(width 0.14732)
		(layer "In4.Cu")
		(net "UPI_CPU1_CPU0_P1P0_DP<1>")
	)
	(segment
		(start 337.827874 -209.053938)
		(end 337.683094 -209.198718)
		(width 0.14732)
		(layer "In4.Cu")
		(net "UPI_CPU1_CPU0_P1P0_DP<1>")
	)
	(segment
		(start 145.565114 -202.046586)
		(end 146.14017 -201.465942)
		(width 0.14732)
		(layer "In4.Cu")
		(net "UPI_CPU1_CPU0_P1P0_DP<1>")
	)
	(segment
		(start 337.827874 -209.711798)
		(end 337.827874 -211.800948)
		(width 0.14732)
		(layer "In4.Cu")
		(net "UPI_CPU1_CPU0_P1P0_DP<1>")
	)
	(segment
		(start 261.11835 -191.708024)
		(end 286.488886 -190.696088)
		(width 0.14732)
		(layer "In4.Cu")
		(net "UPI_CPU1_CPU0_P1P0_DP<1>")
	)
	(segment
		(start 338.339176 -214.461344)
		(end 338.339176 -214.622634)
		(width 0.0889)
		(layer "In4.Cu")
		(net "UPI_CPU1_CPU0_P1P0_DP<1>")
	)
	(segment
		(start 141.222984 -206.42834)
		(end 141.427708 -206.427578)
		(width 0.14732)
		(layer "In4.Cu")
		(net "UPI_CPU1_CPU0_P1P0_DP<1>")
	)
	(segment
		(start 164.72662 -190.615062)
		(end 165.031166 -190.925958)
		(width 0.14732)
		(layer "In4.Cu")
		(net "UPI_CPU1_CPU0_P1P0_DP<1>")
	)
	(segment
		(start 144.508728 -203.112878)
		(end 144.507204 -202.677522)
		(width 0.14732)
		(layer "In4.Cu")
		(net "UPI_CPU1_CPU0_P1P0_DP<1>")
	)
	(segment
		(start 338.160614 -214.941912)
		(end 338.151724 -214.946992)
		(width 0.0889)
		(layer "In4.Cu")
		(net "UPI_CPU1_CPU0_P1P0_DP<1>")
	)
	(segment
		(start 337.0072 -202.875388)
		(end 337.21548 -202.875388)
		(width 0.14732)
		(layer "In4.Cu")
		(net "UPI_CPU1_CPU0_P1P0_DP<1>")
	)
	(segment
		(start 164.601144 -188.988192)
		(end 164.746432 -189.13729)
		(width 0.14732)
		(layer "In4.Cu")
		(net "UPI_CPU1_CPU0_P1P0_DP<1>")
	)
	(segment
		(start 133.099302 -218.149424)
		(end 133.02107 -218.170252)
		(width 0.0889)
		(layer "In4.Cu")
		(net "UPI_CPU1_CPU0_P1P0_DP<1>")
	)
	(segment
		(start 133.538214 -216.739978)
		(end 133.538976 -216.73947)
		(width 0.0889)
		(layer "In4.Cu")
		(net "UPI_CPU1_CPU0_P1P0_DP<1>")
	)
	(segment
		(start 153.226008 -195.366894)
		(end 153.598372 -194.991228)
		(width 0.14732)
		(layer "In4.Cu")
		(net "UPI_CPU1_CPU0_P1P0_DP<1>")
	)
	(segment
		(start 133.999478 -215.931242)
		(end 134.008368 -215.926162)
		(width 0.0889)
		(layer "In4.Cu")
		(net "UPI_CPU1_CPU0_P1P0_DP<1>")
	)
	(segment
		(start 336.190844 -203.256388)
		(end 336.6262 -203.256388)
		(width 0.14732)
		(layer "In4.Cu")
		(net "UPI_CPU1_CPU0_P1P0_DP<1>")
	)
	(segment
		(start 191.097154 -191.274954)
		(end 208.440782 -190.573914)
		(width 0.14732)
		(layer "In4.Cu")
		(net "UPI_CPU1_CPU0_P1P0_DP<1>")
	)
	(segment
		(start 146.14017 -201.465942)
		(end 146.137884 -201.030586)
		(width 0.14732)
		(layer "In4.Cu")
		(net "UPI_CPU1_CPU0_P1P0_DP<1>")
	)
	(segment
		(start 139.175236 -209.365088)
		(end 139.37615 -209.324702)
		(width 0.14732)
		(layer "In4.Cu")
		(net "UPI_CPU1_CPU0_P1P0_DP<1>")
	)
	(segment
		(start 163.86175 -189.125098)
		(end 164.010594 -188.980318)
		(width 0.14732)
		(layer "In4.Cu")
		(net "UPI_CPU1_CPU0_P1P0_DP<1>")
	)
	(segment
		(start 338.153756 -216.574116)
		(end 338.152232 -216.574878)
		(width 0.0889)
		(layer "In4.Cu")
		(net "UPI_CPU1_CPU0_P1P0_DP<1>")
	)
	(segment
		(start 334.947006 -200.811638)
		(end 335.23174 -201.096372)
		(width 0.14732)
		(layer "In4.Cu")
		(net "UPI_CPU1_CPU0_P1P0_DP<1>")
	)
	(segment
		(start 337.21548 -202.875388)
		(end 338.919312 -204.57922)
		(width 0.14732)
		(layer "In4.Cu")
		(net "UPI_CPU1_CPU0_P1P0_DP<1>")
	)
	(segment
		(start 338.152232 -216.574878)
		(end 338.149438 -216.576402)
		(width 0.0889)
		(layer "In4.Cu")
		(net "UPI_CPU1_CPU0_P1P0_DP<1>")
	)
	(segment
		(start 338.15147 -215.925654)
		(end 338.152232 -215.926162)
		(width 0.0889)
		(layer "In4.Cu")
		(net "UPI_CPU1_CPU0_P1P0_DP<1>")
	)
	(arc
		(start 134.944866 -214.907114)
		(mid 134.835741 -214.823311)
		(end 134.760716 -214.707978)
		(width 0.0889)
		(layer "In4.Cu")
		(net "UPI_CPU1_CPU0_P1P0_DP<1>")
	)
	(arc
		(start 337.869784 -213.930484)
		(mid 337.877069 -213.950046)
		(end 337.885024 -213.969346)
		(width 0.0889)
		(layer "In4.Cu")
		(net "UPI_CPU1_CPU0_P1P0_DP<1>")
	)
	(arc
		(start 337.86953 -217.07856)
		(mid 337.927824 -217.315203)
		(end 338.08035 -217.50528)
		(width 0.0889)
		(layer "In4.Cu")
		(net "UPI_CPU1_CPU0_P1P0_DP<1>")
	)
	(arc
		(start 133.820916 -216.25052)
		(mid 133.868595 -216.06762)
		(end 133.999478 -215.931242)
		(width 0.0889)
		(layer "In4.Cu")
		(net "UPI_CPU1_CPU0_P1P0_DP<1>")
	)
	(arc
		(start 337.86953 -215.436704)
		(mid 337.943521 -215.71627)
		(end 338.146136 -215.922606)
		(width 0.0889)
		(layer "In4.Cu")
		(net "UPI_CPU1_CPU0_P1P0_DP<1>")
	)
	(arc
		(start 134.948168 -215.926162)
		(mid 135.150991 -215.725931)
		(end 135.230362 -215.452198)
		(width 0.0889)
		(layer "In4.Cu")
		(net "UPI_CPU1_CPU0_P1P0_DP<1>")
	)
	(arc
		(start 338.339176 -214.622634)
		(mid 338.291497 -214.805534)
		(end 338.160614 -214.941912)
		(width 0.0889)
		(layer "In4.Cu")
		(net "UPI_CPU1_CPU0_P1P0_DP<1>")
	)
	(arc
		(start 132.881116 -217.878406)
		(mid 132.928795 -217.695506)
		(end 133.059678 -217.559128)
		(width 0.0889)
		(layer "In4.Cu")
		(net "UPI_CPU1_CPU0_P1P0_DP<1>")
	)
	(arc
		(start 134.008368 -215.926162)
		(mid 134.195566 -215.876019)
		(end 134.382764 -215.926162)
		(width 0.0889)
		(layer "In4.Cu")
		(net "UPI_CPU1_CPU0_P1P0_DP<1>")
	)
	(arc
		(start 133.068568 -217.554048)
		(mid 133.270854 -217.355067)
		(end 133.351016 -217.082878)
		(width 0.0889)
		(layer "In4.Cu")
		(net "UPI_CPU1_CPU0_P1P0_DP<1>")
	)
	(arc
		(start 133.54431 -216.736422)
		(mid 133.746897 -216.530071)
		(end 133.820916 -216.25052)
		(width 0.0889)
		(layer "In4.Cu")
		(net "UPI_CPU1_CPU0_P1P0_DP<1>")
	)
	(arc
		(start 337.885024 -213.969346)
		(mid 337.995018 -214.138715)
		(end 338.155026 -214.261954)
		(width 0.0889)
		(layer "In4.Cu")
		(net "UPI_CPU1_CPU0_P1P0_DP<1>")
	)
	(arc
		(start 338.08035 -217.50528)
		(mid 338.088798 -217.511837)
		(end 338.097368 -217.518234)
		(width 0.0889)
		(layer "In4.Cu")
		(net "UPI_CPU1_CPU0_P1P0_DP<1>")
	)
	(arc
		(start 338.161122 -215.931242)
		(mid 338.339719 -216.25052)
		(end 338.161122 -216.569798)
		(width 0.0889)
		(layer "In4.Cu")
		(net "UPI_CPU1_CPU0_P1P0_DP<1>")
	)
	(arc
		(start 133.02107 -218.170252)
		(mid 132.917925 -218.040227)
		(end 132.881116 -217.878406)
		(width 0.0889)
		(layer "In4.Cu")
		(net "UPI_CPU1_CPU0_P1P0_DP<1>")
	)
	(arc
		(start 338.146136 -216.578434)
		(mid 337.943549 -216.784785)
		(end 337.86953 -217.064336)
		(width 0.0889)
		(layer "In4.Cu")
		(net "UPI_CPU1_CPU0_P1P0_DP<1>")
	)
	(arc
		(start 133.351016 -217.0557)
		(mid 133.403286 -216.873335)
		(end 133.538214 -216.739978)
		(width 0.0889)
		(layer "In4.Cu")
		(net "UPI_CPU1_CPU0_P1P0_DP<1>")
	)
	(arc
		(start 338.151724 -214.946992)
		(mid 337.950442 -215.144479)
		(end 337.86953 -215.414606)
		(width 0.0889)
		(layer "In4.Cu")
		(net "UPI_CPU1_CPU0_P1P0_DP<1>")
	)
	(arc
		(start 338.155026 -214.261954)
		(mid 338.264173 -214.345882)
		(end 338.339176 -214.461344)
		(width 0.0889)
		(layer "In4.Cu")
		(net "UPI_CPU1_CPU0_P1P0_DP<1>")
	)
	(arc
		(start 135.230362 -215.23833)
		(mid 135.118942 -215.045711)
		(end 134.944866 -214.907114)
		(width 0.0889)
		(layer "In4.Cu")
		(net "UPI_CPU1_CPU0_P1P0_DP<1>")
	)
	(arc
		(start 134.397496 -215.934798)
		(mid 134.673971 -216.002118)
		(end 134.948168 -215.926162)
		(width 0.0889)
		(layer "In4.Cu")
		(net "UPI_CPU1_CPU0_P1P0_DP<1>")
	)
	(segment
		(start 355.351334 -217.06459)
		(end 355.35108 -217.064336)
		(width 0.13208)
		(layer "F.Cu")
		(net "UPI_CPU1_CPU0_P1P0_DP<19>")
	)
	(segment
		(start 115.869466 -218.692476)
		(end 115.869212 -218.692222)
		(width 0.13208)
		(layer "F.Cu")
		(net "UPI_CPU1_CPU0_P1P0_DP<19>")
	)
	(segment
		(start 115.869466 -219.228162)
		(end 115.869466 -218.692476)
		(width 0.13208)
		(layer "F.Cu")
		(net "UPI_CPU1_CPU0_P1P0_DP<19>")
	)
	(segment
		(start 355.351334 -217.600276)
		(end 355.351334 -217.06459)
		(width 0.13208)
		(layer "F.Cu")
		(net "UPI_CPU1_CPU0_P1P0_DP<19>")
	)
	(segment
		(start 116.201952 -210.842352)
		(end 119.732806 -200.757282)
		(width 0.14732)
		(layer "In4.Cu")
		(net "UPI_CPU1_CPU0_P1P0_DP<19>")
	)
	(segment
		(start 156.69895 -173.25721)
		(end 200.7997 -172.525182)
		(width 0.14732)
		(layer "In4.Cu")
		(net "UPI_CPU1_CPU0_P1P0_DP<19>")
	)
	(segment
		(start 318.327786 -173.656244)
		(end 330.849986 -178.032664)
		(width 0.14732)
		(layer "In4.Cu")
		(net "UPI_CPU1_CPU0_P1P0_DP<19>")
	)
	(segment
		(start 355.162866 -215.112854)
		(end 355.154992 -215.117426)
		(width 0.0889)
		(layer "In4.Cu")
		(net "UPI_CPU1_CPU0_P1P0_DP<19>")
	)
	(segment
		(start 355.163882 -215.761062)
		(end 355.166676 -215.762586)
		(width 0.0889)
		(layer "In4.Cu")
		(net "UPI_CPU1_CPU0_P1P0_DP<19>")
	)
	(segment
		(start 355.164644 -216.73947)
		(end 355.163882 -216.739978)
		(width 0.0889)
		(layer "In4.Cu")
		(net "UPI_CPU1_CPU0_P1P0_DP<19>")
	)
	(segment
		(start 116.526056 -214.946992)
		(end 116.534946 -214.941912)
		(width 0.0889)
		(layer "In4.Cu")
		(net "UPI_CPU1_CPU0_P1P0_DP<19>")
	)
	(segment
		(start 355.018848 -211.856574)
		(end 355.018848 -211.878672)
		(width 0.0889)
		(layer "In4.Cu")
		(net "UPI_CPU1_CPU0_P1P0_DP<19>")
	)
	(segment
		(start 116.202206 -212.072728)
		(end 116.202206 -212.05063)
		(width 0.0889)
		(layer "In4.Cu")
		(net "UPI_CPU1_CPU0_P1P0_DP<19>")
	)
	(segment
		(start 354.976684 -217.0557)
		(end 354.976684 -217.072972)
		(width 0.0889)
		(layer "In4.Cu")
		(net "UPI_CPU1_CPU0_P1P0_DP<19>")
	)
	(segment
		(start 355.169978 -216.736422)
		(end 355.164644 -216.73947)
		(width 0.0889)
		(layer "In4.Cu")
		(net "UPI_CPU1_CPU0_P1P0_DP<19>")
	)
	(segment
		(start 116.243862 -217.072972)
		(end 116.243862 -217.0557)
		(width 0.0889)
		(layer "In4.Cu")
		(net "UPI_CPU1_CPU0_P1P0_DP<19>")
	)
	(segment
		(start 302.482758 -172.112178)
		(end 313.530742 -172.31741)
		(width 0.14732)
		(layer "In4.Cu")
		(net "UPI_CPU1_CPU0_P1P0_DP<19>")
	)
	(segment
		(start 115.869212 -218.692222)
		(end 116.025676 -218.421204)
		(width 0.0889)
		(layer "In4.Cu")
		(net "UPI_CPU1_CPU0_P1P0_DP<19>")
	)
	(segment
		(start 119.732806 -200.757282)
		(end 127.897636 -190.711328)
		(width 0.14732)
		(layer "In4.Cu")
		(net "UPI_CPU1_CPU0_P1P0_DP<19>")
	)
	(segment
		(start 116.05641 -215.761062)
		(end 116.0653 -215.755982)
		(width 0.0889)
		(layer "In4.Cu")
		(net "UPI_CPU1_CPU0_P1P0_DP<19>")
	)
	(segment
		(start 115.774216 -217.8939)
		(end 115.774216 -217.859864)
		(width 0.0889)
		(layer "In4.Cu")
		(net "UPI_CPU1_CPU0_P1P0_DP<19>")
	)
	(segment
		(start 238.383318 -172.992288)
		(end 273.075146 -172.827442)
		(width 0.14732)
		(layer "In4.Cu")
		(net "UPI_CPU1_CPU0_P1P0_DP<19>")
	)
	(segment
		(start 355.018848 -211.374482)
		(end 355.018848 -211.856574)
		(width 0.14732)
		(layer "In4.Cu")
		(net "UPI_CPU1_CPU0_P1P0_DP<19>")
	)
	(segment
		(start 150.043388 -174.96028)
		(end 156.69895 -173.25721)
		(width 0.14732)
		(layer "In4.Cu")
		(net "UPI_CPU1_CPU0_P1P0_DP<19>")
	)
	(segment
		(start 116.202206 -211.585302)
		(end 116.201952 -211.585048)
		(width 0.14732)
		(layer "In4.Cu")
		(net "UPI_CPU1_CPU0_P1P0_DP<19>")
	)
	(segment
		(start 115.774216 -216.260426)
		(end 115.774216 -216.235026)
		(width 0.0889)
		(layer "In4.Cu")
		(net "UPI_CPU1_CPU0_P1P0_DP<19>")
	)
	(segment
		(start 355.116638 -217.356182)
		(end 355.194616 -217.335354)
		(width 0.0889)
		(layer "In4.Cu")
		(net "UPI_CPU1_CPU0_P1P0_DP<19>")
	)
	(segment
		(start 337.76158 -180.971444)
		(end 339.537802 -182.170324)
		(width 0.14732)
		(layer "In4.Cu")
		(net "UPI_CPU1_CPU0_P1P0_DP<19>")
	)
	(segment
		(start 355.154992 -215.755982)
		(end 355.162358 -215.7603)
		(width 0.0889)
		(layer "In4.Cu")
		(net "UPI_CPU1_CPU0_P1P0_DP<19>")
	)
	(segment
		(start 116.243862 -215.436704)
		(end 116.243862 -215.414606)
		(width 0.0889)
		(layer "In4.Cu")
		(net "UPI_CPU1_CPU0_P1P0_DP<19>")
	)
	(segment
		(start 302.482504 -172.111924)
		(end 302.482758 -172.112178)
		(width 0.14732)
		(layer "In4.Cu")
		(net "UPI_CPU1_CPU0_P1P0_DP<19>")
	)
	(segment
		(start 302.471074 -172.112178)
		(end 302.476916 -172.111924)
		(width 0.14732)
		(layer "In4.Cu")
		(net "UPI_CPU1_CPU0_P1P0_DP<19>")
	)
	(segment
		(start 273.075146 -172.827442)
		(end 302.471074 -172.112178)
		(width 0.14732)
		(layer "In4.Cu")
		(net "UPI_CPU1_CPU0_P1P0_DP<19>")
	)
	(segment
		(start 343.321132 -185.953654)
		(end 345.82608 -189.51067)
		(width 0.14732)
		(layer "In4.Cu")
		(net "UPI_CPU1_CPU0_P1P0_DP<19>")
	)
	(segment
		(start 116.244116 -213.78672)
		(end 116.244116 -212.114638)
		(width 0.0889)
		(layer "In4.Cu")
		(net "UPI_CPU1_CPU0_P1P0_DP<19>")
	)
	(segment
		(start 127.897636 -190.711328)
		(end 134.640066 -186.23026)
		(width 0.14732)
		(layer "In4.Cu")
		(net "UPI_CPU1_CPU0_P1P0_DP<19>")
	)
	(segment
		(start 211.441538 -172.992288)
		(end 238.383318 -172.992288)
		(width 0.14732)
		(layer "In4.Cu")
		(net "UPI_CPU1_CPU0_P1P0_DP<19>")
	)
	(segment
		(start 134.640066 -186.23026)
		(end 138.713718 -180.761386)
		(width 0.14732)
		(layer "In4.Cu")
		(net "UPI_CPU1_CPU0_P1P0_DP<19>")
	)
	(segment
		(start 355.51618 -209.889852)
		(end 355.018594 -211.091272)
		(width 0.14732)
		(layer "In4.Cu")
		(net "UPI_CPU1_CPU0_P1P0_DP<19>")
	)
	(segment
		(start 355.163882 -215.112346)
		(end 355.162866 -215.112854)
		(width 0.0889)
		(layer "In4.Cu")
		(net "UPI_CPU1_CPU0_P1P0_DP<19>")
	)
	(segment
		(start 355.194616 -217.335354)
		(end 355.35108 -217.064336)
		(width 0.0889)
		(layer "In4.Cu")
		(net "UPI_CPU1_CPU0_P1P0_DP<19>")
	)
	(segment
		(start 355.018848 -211.878672)
		(end 354.976684 -211.920836)
		(width 0.0889)
		(layer "In4.Cu")
		(net "UPI_CPU1_CPU0_P1P0_DP<19>")
	)
	(segment
		(start 330.849986 -178.032664)
		(end 337.76158 -180.971444)
		(width 0.14732)
		(layer "In4.Cu")
		(net "UPI_CPU1_CPU0_P1P0_DP<19>")
	)
	(segment
		(start 116.201952 -211.585048)
		(end 116.201952 -210.842352)
		(width 0.14732)
		(layer "In4.Cu")
		(net "UPI_CPU1_CPU0_P1P0_DP<19>")
	)
	(segment
		(start 116.202206 -212.05063)
		(end 116.202206 -211.585302)
		(width 0.14732)
		(layer "In4.Cu")
		(net "UPI_CPU1_CPU0_P1P0_DP<19>")
	)
	(segment
		(start 354.976684 -211.920836)
		(end 354.976684 -213.893908)
		(width 0.0889)
		(layer "In4.Cu")
		(net "UPI_CPU1_CPU0_P1P0_DP<19>")
	)
	(segment
		(start 355.018594 -211.374228)
		(end 355.018848 -211.374482)
		(width 0.14732)
		(layer "In4.Cu")
		(net "UPI_CPU1_CPU0_P1P0_DP<19>")
	)
	(segment
		(start 313.530742 -172.31741)
		(end 318.327786 -173.656244)
		(width 0.14732)
		(layer "In4.Cu")
		(net "UPI_CPU1_CPU0_P1P0_DP<19>")
	)
	(segment
		(start 345.82608 -189.51067)
		(end 352.043492 -195.882514)
		(width 0.14732)
		(layer "In4.Cu")
		(net "UPI_CPU1_CPU0_P1P0_DP<19>")
	)
	(segment
		(start 355.166676 -215.762586)
		(end 355.169978 -215.764618)
		(width 0.0889)
		(layer "In4.Cu")
		(net "UPI_CPU1_CPU0_P1P0_DP<19>")
	)
	(segment
		(start 355.162358 -215.7603)
		(end 355.163882 -215.761062)
		(width 0.0889)
		(layer "In4.Cu")
		(net "UPI_CPU1_CPU0_P1P0_DP<19>")
	)
	(segment
		(start 302.476916 -172.111924)
		(end 302.482504 -172.111924)
		(width 0.14732)
		(layer "In4.Cu")
		(net "UPI_CPU1_CPU0_P1P0_DP<19>")
	)
	(segment
		(start 339.537802 -182.170324)
		(end 343.321132 -185.953654)
		(width 0.14732)
		(layer "In4.Cu")
		(net "UPI_CPU1_CPU0_P1P0_DP<19>")
	)
	(segment
		(start 355.51618 -204.267562)
		(end 355.51618 -209.889852)
		(width 0.14732)
		(layer "In4.Cu")
		(net "UPI_CPU1_CPU0_P1P0_DP<19>")
	)
	(segment
		(start 200.7997 -172.525182)
		(end 211.441538 -172.992288)
		(width 0.14732)
		(layer "In4.Cu")
		(net "UPI_CPU1_CPU0_P1P0_DP<19>")
	)
	(segment
		(start 116.244116 -212.114638)
		(end 116.202206 -212.072728)
		(width 0.0889)
		(layer "In4.Cu")
		(net "UPI_CPU1_CPU0_P1P0_DP<19>")
	)
	(segment
		(start 352.043492 -195.882514)
		(end 355.51618 -204.267562)
		(width 0.14732)
		(layer "In4.Cu")
		(net "UPI_CPU1_CPU0_P1P0_DP<19>")
	)
	(segment
		(start 116.713508 -214.622634)
		(end 116.713508 -214.500968)
		(width 0.0889)
		(layer "In4.Cu")
		(net "UPI_CPU1_CPU0_P1P0_DP<19>")
	)
	(segment
		(start 355.018594 -211.091272)
		(end 355.018594 -211.374228)
		(width 0.14732)
		(layer "In4.Cu")
		(net "UPI_CPU1_CPU0_P1P0_DP<19>")
	)
	(segment
		(start 355.446076 -214.424768)
		(end 355.446076 -214.644732)
		(width 0.0889)
		(layer "In4.Cu")
		(net "UPI_CPU1_CPU0_P1P0_DP<19>")
	)
	(segment
		(start 138.713718 -180.761386)
		(end 150.043388 -174.96028)
		(width 0.14732)
		(layer "In4.Cu")
		(net "UPI_CPU1_CPU0_P1P0_DP<19>")
	)
	(segment
		(start 116.025676 -218.421204)
		(end 116.001546 -218.33205)
		(width 0.0889)
		(layer "In4.Cu")
		(net "UPI_CPU1_CPU0_P1P0_DP<19>")
	)
	(arc
		(start 116.243862 -215.414606)
		(mid 116.324773 -215.144478)
		(end 116.526056 -214.946992)
		(width 0.0889)
		(layer "In4.Cu")
		(net "UPI_CPU1_CPU0_P1P0_DP<19>")
	)
	(arc
		(start 116.534946 -214.941912)
		(mid 116.66586 -214.805552)
		(end 116.713508 -214.622634)
		(width 0.0889)
		(layer "In4.Cu")
		(net "UPI_CPU1_CPU0_P1P0_DP<19>")
	)
	(arc
		(start 116.001546 -218.33205)
		(mid 115.993105 -218.32565)
		(end 115.984782 -218.319096)
		(width 0.0889)
		(layer "In4.Cu")
		(net "UPI_CPU1_CPU0_P1P0_DP<19>")
	)
	(arc
		(start 116.690394 -214.415116)
		(mid 116.620685 -214.327101)
		(end 116.529612 -214.261446)
		(width 0.0889)
		(layer "In4.Cu")
		(net "UPI_CPU1_CPU0_P1P0_DP<19>")
	)
	(arc
		(start 116.056664 -216.739978)
		(mid 115.852329 -216.537373)
		(end 115.774216 -216.260426)
		(width 0.0889)
		(layer "In4.Cu")
		(net "UPI_CPU1_CPU0_P1P0_DP<19>")
	)
	(arc
		(start 116.0653 -215.755982)
		(mid 116.196214 -215.619622)
		(end 116.243862 -215.436704)
		(width 0.0889)
		(layer "In4.Cu")
		(net "UPI_CPU1_CPU0_P1P0_DP<19>")
	)
	(arc
		(start 355.160834 -214.093298)
		(mid 355.334797 -214.232062)
		(end 355.446076 -214.424768)
		(width 0.0889)
		(layer "In4.Cu")
		(net "UPI_CPU1_CPU0_P1P0_DP<19>")
	)
	(arc
		(start 115.774216 -217.859864)
		(mid 115.854378 -217.587675)
		(end 116.056664 -217.388694)
		(width 0.0889)
		(layer "In4.Cu")
		(net "UPI_CPU1_CPU0_P1P0_DP<19>")
	)
	(arc
		(start 116.056664 -217.388694)
		(mid 116.191597 -217.25534)
		(end 116.243862 -217.072972)
		(width 0.0889)
		(layer "In4.Cu")
		(net "UPI_CPU1_CPU0_P1P0_DP<19>")
	)
	(arc
		(start 115.984782 -218.319096)
		(mid 115.8327 -218.129664)
		(end 115.774216 -217.8939)
		(width 0.0889)
		(layer "In4.Cu")
		(net "UPI_CPU1_CPU0_P1P0_DP<19>")
	)
	(arc
		(start 354.976684 -217.072972)
		(mid 355.015358 -217.23004)
		(end 355.116638 -217.356182)
		(width 0.0889)
		(layer "In4.Cu")
		(net "UPI_CPU1_CPU0_P1P0_DP<19>")
	)
	(arc
		(start 354.97643 -215.436704)
		(mid 355.024109 -215.619604)
		(end 355.154992 -215.755982)
		(width 0.0889)
		(layer "In4.Cu")
		(net "UPI_CPU1_CPU0_P1P0_DP<19>")
	)
	(arc
		(start 116.529612 -214.261446)
		(mid 116.320813 -214.063793)
		(end 116.244116 -213.78672)
		(width 0.0889)
		(layer "In4.Cu")
		(net "UPI_CPU1_CPU0_P1P0_DP<19>")
	)
	(arc
		(start 355.169978 -215.764618)
		(mid 355.446552 -216.25052)
		(end 355.169978 -216.736422)
		(width 0.0889)
		(layer "In4.Cu")
		(net "UPI_CPU1_CPU0_P1P0_DP<19>")
	)
	(arc
		(start 354.976684 -213.893908)
		(mid 355.051689 -214.009367)
		(end 355.160834 -214.093298)
		(width 0.0889)
		(layer "In4.Cu")
		(net "UPI_CPU1_CPU0_P1P0_DP<19>")
	)
	(arc
		(start 355.154992 -215.117426)
		(mid 355.027738 -215.247392)
		(end 354.976684 -215.421972)
		(width 0.0889)
		(layer "In4.Cu")
		(net "UPI_CPU1_CPU0_P1P0_DP<19>")
	)
	(arc
		(start 354.976684 -215.421972)
		(mid 354.976487 -215.429337)
		(end 354.97643 -215.436704)
		(width 0.0889)
		(layer "In4.Cu")
		(net "UPI_CPU1_CPU0_P1P0_DP<19>")
	)
	(arc
		(start 116.713508 -214.500968)
		(mid 116.707704 -214.45649)
		(end 116.690394 -214.415116)
		(width 0.0889)
		(layer "In4.Cu")
		(net "UPI_CPU1_CPU0_P1P0_DP<19>")
	)
	(arc
		(start 115.774216 -216.235026)
		(mid 115.853586 -215.961292)
		(end 116.05641 -215.761062)
		(width 0.0889)
		(layer "In4.Cu")
		(net "UPI_CPU1_CPU0_P1P0_DP<19>")
	)
	(arc
		(start 355.163882 -216.739978)
		(mid 355.028949 -216.873332)
		(end 354.976684 -217.0557)
		(width 0.0889)
		(layer "In4.Cu")
		(net "UPI_CPU1_CPU0_P1P0_DP<19>")
	)
	(arc
		(start 355.446076 -214.644732)
		(mid 355.365165 -214.91486)
		(end 355.163882 -215.112346)
		(width 0.0889)
		(layer "In4.Cu")
		(net "UPI_CPU1_CPU0_P1P0_DP<19>")
	)
	(arc
		(start 116.243862 -217.0557)
		(mid 116.191592 -216.873335)
		(end 116.056664 -216.739978)
		(width 0.0889)
		(layer "In4.Cu")
		(net "UPI_CPU1_CPU0_P1P0_DP<19>")
	)
	(segment
		(start 117.278912 -218.414346)
		(end 117.278912 -217.87866)
		(width 0.13208)
		(layer "F.Cu")
		(net "UPI_CPU1_CPU0_P1P0_DP<18>")
	)
	(segment
		(start 353.94138 -218.414346)
		(end 353.94138 -217.87866)
		(width 0.13208)
		(layer "F.Cu")
		(net "UPI_CPU1_CPU0_P1P0_DP<18>")
	)
	(segment
		(start 353.94138 -217.87866)
		(end 353.941634 -217.878406)
		(width 0.13208)
		(layer "F.Cu")
		(net "UPI_CPU1_CPU0_P1P0_DP<18>")
	)
	(segment
		(start 117.278912 -217.87866)
		(end 117.279166 -217.878406)
		(width 0.13208)
		(layer "F.Cu")
		(net "UPI_CPU1_CPU0_P1P0_DP<18>")
	)
	(segment
		(start 354.129594 -217.554556)
		(end 354.137722 -217.559128)
		(width 0.0889)
		(layer "In4.Cu")
		(net "UPI_CPU1_CPU0_P1P0_DP<18>")
	)
	(segment
		(start 273.091402 -173.936914)
		(end 302.479964 -173.222158)
		(width 0.14732)
		(layer "In4.Cu")
		(net "UPI_CPU1_CPU0_P1P0_DP<18>")
	)
	(segment
		(start 353.846384 -213.006686)
		(end 353.846384 -213.930484)
		(width 0.0889)
		(layer "In4.Cu")
		(net "UPI_CPU1_CPU0_P1P0_DP<18>")
	)
	(segment
		(start 126.006352 -195.000372)
		(end 126.177802 -194.982592)
		(width 0.14732)
		(layer "In4.Cu")
		(net "UPI_CPU1_CPU0_P1P0_DP<18>")
	)
	(segment
		(start 337.2739 -181.974998)
		(end 338.813394 -183.012842)
		(width 0.14732)
		(layer "In4.Cu")
		(net "UPI_CPU1_CPU0_P1P0_DP<18>")
	)
	(segment
		(start 122.416824 -199.416162)
		(end 122.588274 -199.398636)
		(width 0.14732)
		(layer "In4.Cu")
		(net "UPI_CPU1_CPU0_P1P0_DP<18>")
	)
	(segment
		(start 122.416824 -199.416416)
		(end 122.416824 -199.416162)
		(width 0.14732)
		(layer "In4.Cu")
		(net "UPI_CPU1_CPU0_P1P0_DP<18>")
	)
	(segment
		(start 117.552724 -215.117426)
		(end 117.561614 -215.112346)
		(width 0.0889)
		(layer "In4.Cu")
		(net "UPI_CPU1_CPU0_P1P0_DP<18>")
	)
	(segment
		(start 117.416326 -212.05063)
		(end 117.416326 -211.585302)
		(width 0.14732)
		(layer "In4.Cu")
		(net "UPI_CPU1_CPU0_P1P0_DP<18>")
	)
	(segment
		(start 117.416326 -212.072728)
		(end 117.416326 -212.05063)
		(width 0.0889)
		(layer "In4.Cu")
		(net "UPI_CPU1_CPU0_P1P0_DP<18>")
	)
	(segment
		(start 117.374162 -213.786466)
		(end 117.374162 -212.114892)
		(width 0.0889)
		(layer "In4.Cu")
		(net "UPI_CPU1_CPU0_P1P0_DP<18>")
	)
	(segment
		(start 117.412008 -213.92896)
		(end 117.390418 -213.873334)
		(width 0.0889)
		(layer "In4.Cu")
		(net "UPI_CPU1_CPU0_P1P0_DP<18>")
	)
	(segment
		(start 117.416072 -210.873848)
		(end 120.678448 -201.555096)
		(width 0.14732)
		(layer "In4.Cu")
		(net "UPI_CPU1_CPU0_P1P0_DP<18>")
	)
	(segment
		(start 354.34524 -209.253074)
		(end 354.34524 -209.621374)
		(width 0.14732)
		(layer "In4.Cu")
		(net "UPI_CPU1_CPU0_P1P0_DP<18>")
	)
	(segment
		(start 354.128832 -217.554048)
		(end 354.129594 -217.554556)
		(width 0.0889)
		(layer "In4.Cu")
		(net "UPI_CPU1_CPU0_P1P0_DP<18>")
	)
	(segment
		(start 124.732796 -196.760592)
		(end 125.00864 -196.421248)
		(width 0.14732)
		(layer "In4.Cu")
		(net "UPI_CPU1_CPU0_P1P0_DP<18>")
	)
	(segment
		(start 126.453646 -194.643502)
		(end 126.435866 -194.471798)
		(width 0.14732)
		(layer "In4.Cu")
		(net "UPI_CPU1_CPU0_P1P0_DP<18>")
	)
	(segment
		(start 125.695964 -195.382388)
		(end 126.006352 -195.000372)
		(width 0.14732)
		(layer "In4.Cu")
		(net "UPI_CPU1_CPU0_P1P0_DP<18>")
	)
	(segment
		(start 211.194396 -174.10176)
		(end 238.277146 -174.10176)
		(width 0.14732)
		(layer "In4.Cu")
		(net "UPI_CPU1_CPU0_P1P0_DP<18>")
	)
	(segment
		(start 354.20046 -208.739994)
		(end 354.20046 -209.108294)
		(width 0.14732)
		(layer "In4.Cu")
		(net "UPI_CPU1_CPU0_P1P0_DP<18>")
	)
	(segment
		(start 338.813394 -183.012842)
		(end 342.459056 -186.65825)
		(width 0.14732)
		(layer "In4.Cu")
		(net "UPI_CPU1_CPU0_P1P0_DP<18>")
	)
	(segment
		(start 354.20046 -208.082134)
		(end 354.34524 -208.226914)
		(width 0.14732)
		(layer "In4.Cu")
		(net "UPI_CPU1_CPU0_P1P0_DP<18>")
	)
	(segment
		(start 124.99086 -196.249798)
		(end 125.266196 -195.910962)
		(width 0.14732)
		(layer "In4.Cu")
		(net "UPI_CPU1_CPU0_P1P0_DP<18>")
	)
	(segment
		(start 353.840034 -212.350604)
		(end 353.881944 -212.392514)
		(width 0.0889)
		(layer "In4.Cu")
		(net "UPI_CPU1_CPU0_P1P0_DP<18>")
	)
	(segment
		(start 353.83978 -210.841844)
		(end 353.83978 -212.1408)
		(width 0.14732)
		(layer "In4.Cu")
		(net "UPI_CPU1_CPU0_P1P0_DP<18>")
	)
	(segment
		(start 125.266196 -195.910962)
		(end 125.4379 -195.893182)
		(width 0.14732)
		(layer "In4.Cu")
		(net "UPI_CPU1_CPU0_P1P0_DP<18>")
	)
	(segment
		(start 342.459056 -186.65825)
		(end 345.00439 -190.27267)
		(width 0.14732)
		(layer "In4.Cu")
		(net "UPI_CPU1_CPU0_P1P0_DP<18>")
	)
	(segment
		(start 354.137214 -214.941912)
		(end 354.128324 -214.946992)
		(width 0.0889)
		(layer "In4.Cu")
		(net "UPI_CPU1_CPU0_P1P0_DP<18>")
	)
	(segment
		(start 124.561346 -196.778372)
		(end 124.732796 -196.760592)
		(width 0.14732)
		(layer "In4.Cu")
		(net "UPI_CPU1_CPU0_P1P0_DP<18>")
	)
	(segment
		(start 117.098064 -216.578434)
		(end 117.091968 -216.574878)
		(width 0.0889)
		(layer "In4.Cu")
		(net "UPI_CPU1_CPU0_P1P0_DP<18>")
	)
	(segment
		(start 117.083078 -215.931242)
		(end 117.091968 -215.926162)
		(width 0.0889)
		(layer "In4.Cu")
		(net "UPI_CPU1_CPU0_P1P0_DP<18>")
	)
	(segment
		(start 135.390382 -187.070238)
		(end 139.409424 -181.67604)
		(width 0.14732)
		(layer "In4.Cu")
		(net "UPI_CPU1_CPU0_P1P0_DP<18>")
	)
	(segment
		(start 150.516082 -175.989234)
		(end 156.826966 -174.374556)
		(width 0.14732)
		(layer "In4.Cu")
		(net "UPI_CPU1_CPU0_P1P0_DP<18>")
	)
	(segment
		(start 123.827032 -197.681596)
		(end 123.998736 -197.663816)
		(width 0.14732)
		(layer "In4.Cu")
		(net "UPI_CPU1_CPU0_P1P0_DP<18>")
	)
	(segment
		(start 139.409424 -181.67604)
		(end 150.516082 -175.989234)
		(width 0.14732)
		(layer "In4.Cu")
		(net "UPI_CPU1_CPU0_P1P0_DP<18>")
	)
	(segment
		(start 123.551696 -198.020432)
		(end 123.827032 -197.681596)
		(width 0.14732)
		(layer "In4.Cu")
		(net "UPI_CPU1_CPU0_P1P0_DP<18>")
	)
	(segment
		(start 122.864118 -199.059292)
		(end 122.846592 -198.887842)
		(width 0.14732)
		(layer "In4.Cu")
		(net "UPI_CPU1_CPU0_P1P0_DP<18>")
	)
	(segment
		(start 117.843808 -214.644732)
		(end 117.843554 -214.501222)
		(width 0.0889)
		(layer "In4.Cu")
		(net "UPI_CPU1_CPU0_P1P0_DP<18>")
	)
	(segment
		(start 354.130356 -215.926924)
		(end 354.137722 -215.931242)
		(width 0.0889)
		(layer "In4.Cu")
		(net "UPI_CPU1_CPU0_P1P0_DP<18>")
	)
	(segment
		(start 354.34524 -207.569054)
		(end 354.20046 -207.713834)
		(width 0.14732)
		(layer "In4.Cu")
		(net "UPI_CPU1_CPU0_P1P0_DP<18>")
	)
	(segment
		(start 354.137722 -216.569798)
		(end 354.128832 -216.574878)
		(width 0.0889)
		(layer "In4.Cu")
		(net "UPI_CPU1_CPU0_P1P0_DP<18>")
	)
	(segment
		(start 351.04705 -196.464936)
		(end 354.34524 -204.427328)
		(width 0.14732)
		(layer "In4.Cu")
		(net "UPI_CPU1_CPU0_P1P0_DP<18>")
	)
	(segment
		(start 117.374162 -215.452198)
		(end 117.374162 -215.436704)
		(width 0.0889)
		(layer "In4.Cu")
		(net "UPI_CPU1_CPU0_P1P0_DP<18>")
	)
	(segment
		(start 124.2568 -197.153022)
		(end 124.561346 -196.778372)
		(width 0.14732)
		(layer "In4.Cu")
		(net "UPI_CPU1_CPU0_P1P0_DP<18>")
	)
	(segment
		(start 354.128832 -216.574878)
		(end 354.125022 -216.577164)
		(width 0.0889)
		(layer "In4.Cu")
		(net "UPI_CPU1_CPU0_P1P0_DP<18>")
	)
	(segment
		(start 354.098098 -218.149424)
		(end 353.941634 -217.878406)
		(width 0.0889)
		(layer "In4.Cu")
		(net "UPI_CPU1_CPU0_P1P0_DP<18>")
	)
	(segment
		(start 125.71349 -195.553838)
		(end 125.695964 -195.382388)
		(width 0.14732)
		(layer "In4.Cu")
		(net "UPI_CPU1_CPU0_P1P0_DP<18>")
	)
	(segment
		(start 117.416072 -211.585048)
		(end 117.416072 -210.873848)
		(width 0.14732)
		(layer "In4.Cu")
		(net "UPI_CPU1_CPU0_P1P0_DP<18>")
	)
	(segment
		(start 313.374786 -173.42485)
		(end 318.00419 -174.717964)
		(width 0.14732)
		(layer "In4.Cu")
		(net "UPI_CPU1_CPU0_P1P0_DP<18>")
	)
	(segment
		(start 354.12807 -215.925654)
		(end 354.128832 -215.926162)
		(width 0.0889)
		(layer "In4.Cu")
		(net "UPI_CPU1_CPU0_P1P0_DP<18>")
	)
	(segment
		(start 125.00864 -196.421248)
		(end 124.99086 -196.249798)
		(width 0.14732)
		(layer "In4.Cu")
		(net "UPI_CPU1_CPU0_P1P0_DP<18>")
	)
	(segment
		(start 354.122736 -215.922606)
		(end 354.12807 -215.925654)
		(width 0.0889)
		(layer "In4.Cu")
		(net "UPI_CPU1_CPU0_P1P0_DP<18>")
	)
	(segment
		(start 330.284328 -179.014374)
		(end 337.2739 -181.974998)
		(width 0.14732)
		(layer "In4.Cu")
		(net "UPI_CPU1_CPU0_P1P0_DP<18>")
	)
	(segment
		(start 353.83978 -212.1408)
		(end 353.840034 -212.141054)
		(width 0.14732)
		(layer "In4.Cu")
		(net "UPI_CPU1_CPU0_P1P0_DP<18>")
	)
	(segment
		(start 354.17633 -218.170252)
		(end 354.098098 -218.149424)
		(width 0.0889)
		(layer "In4.Cu")
		(net "UPI_CPU1_CPU0_P1P0_DP<18>")
	)
	(segment
		(start 126.177802 -194.982592)
		(end 126.453646 -194.643502)
		(width 0.14732)
		(layer "In4.Cu")
		(net "UPI_CPU1_CPU0_P1P0_DP<18>")
	)
	(segment
		(start 123.569222 -198.191882)
		(end 123.551696 -198.020432)
		(width 0.14732)
		(layer "In4.Cu")
		(net "UPI_CPU1_CPU0_P1P0_DP<18>")
	)
	(segment
		(start 124.274326 -197.324472)
		(end 124.2568 -197.153022)
		(width 0.14732)
		(layer "In4.Cu")
		(net "UPI_CPU1_CPU0_P1P0_DP<18>")
	)
	(segment
		(start 156.826966 -174.374302)
		(end 200.782682 -173.644814)
		(width 0.14732)
		(layer "In4.Cu")
		(net "UPI_CPU1_CPU0_P1P0_DP<18>")
	)
	(segment
		(start 353.840034 -212.328506)
		(end 353.840034 -212.350604)
		(width 0.0889)
		(layer "In4.Cu")
		(net "UPI_CPU1_CPU0_P1P0_DP<18>")
	)
	(segment
		(start 354.128832 -215.926162)
		(end 354.130356 -215.926924)
		(width 0.0889)
		(layer "In4.Cu")
		(net "UPI_CPU1_CPU0_P1P0_DP<18>")
	)
	(segment
		(start 354.20046 -209.108294)
		(end 354.34524 -209.253074)
		(width 0.14732)
		(layer "In4.Cu")
		(net "UPI_CPU1_CPU0_P1P0_DP<18>")
	)
	(segment
		(start 122.588274 -199.398636)
		(end 122.864118 -199.059292)
		(width 0.14732)
		(layer "In4.Cu")
		(net "UPI_CPU1_CPU0_P1P0_DP<18>")
	)
	(segment
		(start 353.881944 -212.392514)
		(end 353.881944 -212.920834)
		(width 0.0889)
		(layer "In4.Cu")
		(net "UPI_CPU1_CPU0_P1P0_DP<18>")
	)
	(segment
		(start 345.00439 -190.27267)
		(end 351.04705 -196.464936)
		(width 0.14732)
		(layer "In4.Cu")
		(net "UPI_CPU1_CPU0_P1P0_DP<18>")
	)
	(segment
		(start 117.374416 -217.07856)
		(end 117.374416 -217.064336)
		(width 0.0889)
		(layer "In4.Cu")
		(net "UPI_CPU1_CPU0_P1P0_DP<18>")
	)
	(segment
		(start 123.998736 -197.663816)
		(end 124.274326 -197.324472)
		(width 0.14732)
		(layer "In4.Cu")
		(net "UPI_CPU1_CPU0_P1P0_DP<18>")
	)
	(segment
		(start 238.277146 -174.10176)
		(end 273.091402 -173.936914)
		(width 0.14732)
		(layer "In4.Cu")
		(net "UPI_CPU1_CPU0_P1P0_DP<18>")
	)
	(segment
		(start 354.121212 -216.579196)
		(end 354.11664 -216.58199)
		(width 0.0889)
		(layer "In4.Cu")
		(net "UPI_CPU1_CPU0_P1P0_DP<18>")
	)
	(segment
		(start 354.125022 -216.577164)
		(end 354.121212 -216.579196)
		(width 0.0889)
		(layer "In4.Cu")
		(net "UPI_CPU1_CPU0_P1P0_DP<18>")
	)
	(segment
		(start 354.34524 -208.226914)
		(end 354.34524 -208.595214)
		(width 0.14732)
		(layer "In4.Cu")
		(net "UPI_CPU1_CPU0_P1P0_DP<18>")
	)
	(segment
		(start 126.435866 -194.471798)
		(end 128.998472 -191.318896)
		(width 0.14732)
		(layer "In4.Cu")
		(net "UPI_CPU1_CPU0_P1P0_DP<18>")
	)
	(segment
		(start 117.091968 -216.574878)
		(end 117.083078 -216.569798)
		(width 0.0889)
		(layer "In4.Cu")
		(net "UPI_CPU1_CPU0_P1P0_DP<18>")
	)
	(segment
		(start 156.826966 -174.374556)
		(end 156.826966 -174.374302)
		(width 0.14732)
		(layer "In4.Cu")
		(net "UPI_CPU1_CPU0_P1P0_DP<18>")
	)
	(segment
		(start 353.881944 -212.920834)
		(end 353.846384 -213.006686)
		(width 0.0889)
		(layer "In4.Cu")
		(net "UPI_CPU1_CPU0_P1P0_DP<18>")
	)
	(segment
		(start 123.293632 -198.531226)
		(end 123.569222 -198.191882)
		(width 0.14732)
		(layer "In4.Cu")
		(net "UPI_CPU1_CPU0_P1P0_DP<18>")
	)
	(segment
		(start 353.84613 -215.414606)
		(end 353.84613 -215.436704)
		(width 0.0889)
		(layer "In4.Cu")
		(net "UPI_CPU1_CPU0_P1P0_DP<18>")
	)
	(segment
		(start 353.84613 -217.064336)
		(end 353.84613 -217.071956)
		(width 0.0889)
		(layer "In4.Cu")
		(net "UPI_CPU1_CPU0_P1P0_DP<18>")
	)
	(segment
		(start 354.34524 -209.621374)
		(end 353.83978 -210.841844)
		(width 0.14732)
		(layer "In4.Cu")
		(net "UPI_CPU1_CPU0_P1P0_DP<18>")
	)
	(segment
		(start 117.122702 -217.607388)
		(end 117.146832 -217.518234)
		(width 0.0889)
		(layer "In4.Cu")
		(net "UPI_CPU1_CPU0_P1P0_DP<18>")
	)
	(segment
		(start 302.479964 -173.222158)
		(end 313.374786 -173.42485)
		(width 0.14732)
		(layer "In4.Cu")
		(net "UPI_CPU1_CPU0_P1P0_DP<18>")
	)
	(segment
		(start 353.840034 -212.141054)
		(end 353.840034 -212.328506)
		(width 0.14732)
		(layer "In4.Cu")
		(net "UPI_CPU1_CPU0_P1P0_DP<18>")
	)
	(segment
		(start 117.279166 -217.878406)
		(end 117.122702 -217.607388)
		(width 0.0889)
		(layer "In4.Cu")
		(net "UPI_CPU1_CPU0_P1P0_DP<18>")
	)
	(segment
		(start 354.34524 -204.427328)
		(end 354.34524 -207.569054)
		(width 0.14732)
		(layer "In4.Cu")
		(net "UPI_CPU1_CPU0_P1P0_DP<18>")
	)
	(segment
		(start 120.678448 -201.555096)
		(end 122.416824 -199.416416)
		(width 0.14732)
		(layer "In4.Cu")
		(net "UPI_CPU1_CPU0_P1P0_DP<18>")
	)
	(segment
		(start 123.121928 -198.549006)
		(end 123.293632 -198.531226)
		(width 0.14732)
		(layer "In4.Cu")
		(net "UPI_CPU1_CPU0_P1P0_DP<18>")
	)
	(segment
		(start 125.4379 -195.893182)
		(end 125.71349 -195.553838)
		(width 0.14732)
		(layer "In4.Cu")
		(net "UPI_CPU1_CPU0_P1P0_DP<18>")
	)
	(segment
		(start 318.00419 -174.717964)
		(end 330.284328 -179.014374)
		(width 0.14732)
		(layer "In4.Cu")
		(net "UPI_CPU1_CPU0_P1P0_DP<18>")
	)
	(segment
		(start 354.34524 -208.595214)
		(end 354.20046 -208.739994)
		(width 0.14732)
		(layer "In4.Cu")
		(net "UPI_CPU1_CPU0_P1P0_DP<18>")
	)
	(segment
		(start 117.374162 -212.114892)
		(end 117.416326 -212.072728)
		(width 0.0889)
		(layer "In4.Cu")
		(net "UPI_CPU1_CPU0_P1P0_DP<18>")
	)
	(segment
		(start 200.782682 -173.644814)
		(end 211.194396 -174.10176)
		(width 0.14732)
		(layer "In4.Cu")
		(net "UPI_CPU1_CPU0_P1P0_DP<18>")
	)
	(segment
		(start 128.998472 -191.318896)
		(end 135.390382 -187.070238)
		(width 0.14732)
		(layer "In4.Cu")
		(net "UPI_CPU1_CPU0_P1P0_DP<18>")
	)
	(segment
		(start 117.416326 -211.585302)
		(end 117.416072 -211.585048)
		(width 0.14732)
		(layer "In4.Cu")
		(net "UPI_CPU1_CPU0_P1P0_DP<18>")
	)
	(segment
		(start 122.846592 -198.887842)
		(end 123.121928 -198.549006)
		(width 0.14732)
		(layer "In4.Cu")
		(net "UPI_CPU1_CPU0_P1P0_DP<18>")
	)
	(segment
		(start 354.315776 -214.461344)
		(end 354.315776 -214.622634)
		(width 0.0889)
		(layer "In4.Cu")
		(net "UPI_CPU1_CPU0_P1P0_DP<18>")
	)
	(segment
		(start 354.20046 -207.713834)
		(end 354.20046 -208.082134)
		(width 0.14732)
		(layer "In4.Cu")
		(net "UPI_CPU1_CPU0_P1P0_DP<18>")
	)
	(arc
		(start 353.84613 -217.071956)
		(mid 353.923759 -217.350369)
		(end 354.128832 -217.554048)
		(width 0.0889)
		(layer "In4.Cu")
		(net "UPI_CPU1_CPU0_P1P0_DP<18>")
	)
	(arc
		(start 354.316284 -217.878406)
		(mid 354.279424 -218.040203)
		(end 354.17633 -218.170252)
		(width 0.0889)
		(layer "In4.Cu")
		(net "UPI_CPU1_CPU0_P1P0_DP<18>")
	)
	(arc
		(start 117.794532 -214.319104)
		(mid 117.692232 -214.189817)
		(end 117.558566 -214.093298)
		(width 0.0889)
		(layer "In4.Cu")
		(net "UPI_CPU1_CPU0_P1P0_DP<18>")
	)
	(arc
		(start 117.374416 -215.421972)
		(mid 117.42547 -215.247392)
		(end 117.552724 -215.117426)
		(width 0.0889)
		(layer "In4.Cu")
		(net "UPI_CPU1_CPU0_P1P0_DP<18>")
	)
	(arc
		(start 117.390418 -213.873334)
		(mid 117.378232 -213.830659)
		(end 117.374162 -213.786466)
		(width 0.0889)
		(layer "In4.Cu")
		(net "UPI_CPU1_CPU0_P1P0_DP<18>")
	)
	(arc
		(start 117.146832 -217.518234)
		(mid 117.155275 -217.511836)
		(end 117.163596 -217.50528)
		(width 0.0889)
		(layer "In4.Cu")
		(net "UPI_CPU1_CPU0_P1P0_DP<18>")
	)
	(arc
		(start 354.11664 -216.58199)
		(mid 353.918412 -216.787838)
		(end 353.84613 -217.064336)
		(width 0.0889)
		(layer "In4.Cu")
		(net "UPI_CPU1_CPU0_P1P0_DP<18>")
	)
	(arc
		(start 354.137722 -217.559128)
		(mid 354.268636 -217.695488)
		(end 354.316284 -217.878406)
		(width 0.0889)
		(layer "In4.Cu")
		(net "UPI_CPU1_CPU0_P1P0_DP<18>")
	)
	(arc
		(start 354.315776 -214.622634)
		(mid 354.268097 -214.805534)
		(end 354.137214 -214.941912)
		(width 0.0889)
		(layer "In4.Cu")
		(net "UPI_CPU1_CPU0_P1P0_DP<18>")
	)
	(arc
		(start 117.163596 -217.50528)
		(mid 117.316103 -217.315182)
		(end 117.374416 -217.07856)
		(width 0.0889)
		(layer "In4.Cu")
		(net "UPI_CPU1_CPU0_P1P0_DP<18>")
	)
	(arc
		(start 117.374416 -217.064336)
		(mid 117.3005 -216.784834)
		(end 117.098064 -216.578434)
		(width 0.0889)
		(layer "In4.Cu")
		(net "UPI_CPU1_CPU0_P1P0_DP<18>")
	)
	(arc
		(start 117.091968 -215.926162)
		(mid 117.294791 -215.725931)
		(end 117.374162 -215.452198)
		(width 0.0889)
		(layer "In4.Cu")
		(net "UPI_CPU1_CPU0_P1P0_DP<18>")
	)
	(arc
		(start 117.374162 -215.436704)
		(mid 117.374214 -215.429337)
		(end 117.374416 -215.421972)
		(width 0.0889)
		(layer "In4.Cu")
		(net "UPI_CPU1_CPU0_P1P0_DP<18>")
	)
	(arc
		(start 117.843554 -214.501222)
		(mid 117.831173 -214.406901)
		(end 117.794532 -214.319104)
		(width 0.0889)
		(layer "In4.Cu")
		(net "UPI_CPU1_CPU0_P1P0_DP<18>")
	)
	(arc
		(start 354.128324 -214.946992)
		(mid 353.927042 -215.144479)
		(end 353.84613 -215.414606)
		(width 0.0889)
		(layer "In4.Cu")
		(net "UPI_CPU1_CPU0_P1P0_DP<18>")
	)
	(arc
		(start 117.558566 -214.093298)
		(mid 117.470482 -214.024332)
		(end 117.412008 -213.92896)
		(width 0.0889)
		(layer "In4.Cu")
		(net "UPI_CPU1_CPU0_P1P0_DP<18>")
	)
	(arc
		(start 353.846384 -213.930484)
		(mid 353.853669 -213.950046)
		(end 353.861624 -213.969346)
		(width 0.0889)
		(layer "In4.Cu")
		(net "UPI_CPU1_CPU0_P1P0_DP<18>")
	)
	(arc
		(start 353.84613 -215.436704)
		(mid 353.920121 -215.71627)
		(end 354.122736 -215.922606)
		(width 0.0889)
		(layer "In4.Cu")
		(net "UPI_CPU1_CPU0_P1P0_DP<18>")
	)
	(arc
		(start 117.561614 -215.112346)
		(mid 117.762896 -214.914859)
		(end 117.843808 -214.644732)
		(width 0.0889)
		(layer "In4.Cu")
		(net "UPI_CPU1_CPU0_P1P0_DP<18>")
	)
	(arc
		(start 354.137722 -215.931242)
		(mid 354.316319 -216.25052)
		(end 354.137722 -216.569798)
		(width 0.0889)
		(layer "In4.Cu")
		(net "UPI_CPU1_CPU0_P1P0_DP<18>")
	)
	(arc
		(start 354.131626 -214.261954)
		(mid 354.240773 -214.345882)
		(end 354.315776 -214.461344)
		(width 0.0889)
		(layer "In4.Cu")
		(net "UPI_CPU1_CPU0_P1P0_DP<18>")
	)
	(arc
		(start 353.861624 -213.969346)
		(mid 353.971618 -214.138715)
		(end 354.131626 -214.261954)
		(width 0.0889)
		(layer "In4.Cu")
		(net "UPI_CPU1_CPU0_P1P0_DP<18>")
	)
	(arc
		(start 117.083078 -216.569798)
		(mid 116.904602 -216.25052)
		(end 117.083078 -215.931242)
		(width 0.0889)
		(layer "In4.Cu")
		(net "UPI_CPU1_CPU0_P1P0_DP<18>")
	)
	(segment
		(start 353.471734 -217.06459)
		(end 353.47148 -217.064336)
		(width 0.13208)
		(layer "F.Cu")
		(net "UPI_CPU1_CPU0_P1P0_DP<17>")
	)
	(segment
		(start 117.749066 -218.692476)
		(end 117.748812 -218.692222)
		(width 0.13208)
		(layer "F.Cu")
		(net "UPI_CPU1_CPU0_P1P0_DP<17>")
	)
	(segment
		(start 117.749066 -219.228162)
		(end 117.749066 -218.692476)
		(width 0.13208)
		(layer "F.Cu")
		(net "UPI_CPU1_CPU0_P1P0_DP<17>")
	)
	(segment
		(start 353.471734 -217.600276)
		(end 353.471734 -217.06459)
		(width 0.13208)
		(layer "F.Cu")
		(net "UPI_CPU1_CPU0_P1P0_DP<17>")
	)
	(segment
		(start 117.653816 -217.8939)
		(end 117.653816 -217.859864)
		(width 0.0889)
		(layer "In4.Cu")
		(net "UPI_CPU1_CPU0_P1P0_DP<17>")
	)
	(segment
		(start 118.081552 -211.585048)
		(end 118.081552 -210.741006)
		(width 0.14732)
		(layer "In4.Cu")
		(net "UPI_CPU1_CPU0_P1P0_DP<17>")
	)
	(segment
		(start 338.428076 -183.423052)
		(end 342.010492 -187.005468)
		(width 0.14732)
		(layer "In4.Cu")
		(net "UPI_CPU1_CPU0_P1P0_DP<17>")
	)
	(segment
		(start 353.237038 -217.356182)
		(end 353.315016 -217.335354)
		(width 0.0889)
		(layer "In4.Cu")
		(net "UPI_CPU1_CPU0_P1P0_DP<17>")
	)
	(segment
		(start 118.081806 -212.05063)
		(end 118.081806 -211.585302)
		(width 0.14732)
		(layer "In4.Cu")
		(net "UPI_CPU1_CPU0_P1P0_DP<17>")
	)
	(segment
		(start 139.78382 -182.124858)
		(end 150.347426 -176.715928)
		(width 0.14732)
		(layer "In4.Cu")
		(net "UPI_CPU1_CPU0_P1P0_DP<17>")
	)
	(segment
		(start 117.653816 -216.260426)
		(end 117.653816 -216.235026)
		(width 0.0889)
		(layer "In4.Cu")
		(net "UPI_CPU1_CPU0_P1P0_DP<17>")
	)
	(segment
		(start 353.282758 -215.7603)
		(end 353.284282 -215.761062)
		(width 0.0889)
		(layer "In4.Cu")
		(net "UPI_CPU1_CPU0_P1P0_DP<17>")
	)
	(segment
		(start 353.60356 -204.127862)
		(end 353.60356 -209.8802)
		(width 0.14732)
		(layer "In4.Cu")
		(net "UPI_CPU1_CPU0_P1P0_DP<17>")
	)
	(segment
		(start 121.063766 -202.174348)
		(end 129.74574 -191.492124)
		(width 0.14732)
		(layer "In4.Cu")
		(net "UPI_CPU1_CPU0_P1P0_DP<17>")
	)
	(segment
		(start 302.48733 -173.790864)
		(end 313.311794 -173.992032)
		(width 0.14732)
		(layer "In4.Cu")
		(net "UPI_CPU1_CPU0_P1P0_DP<17>")
	)
	(segment
		(start 129.74574 -191.492124)
		(end 135.805418 -187.465716)
		(width 0.14732)
		(layer "In4.Cu")
		(net "UPI_CPU1_CPU0_P1P0_DP<17>")
	)
	(segment
		(start 317.857124 -175.261778)
		(end 330.016104 -179.514246)
		(width 0.14732)
		(layer "In4.Cu")
		(net "UPI_CPU1_CPU0_P1P0_DP<17>")
	)
	(segment
		(start 353.566476 -214.424768)
		(end 353.566476 -214.644732)
		(width 0.0889)
		(layer "In4.Cu")
		(net "UPI_CPU1_CPU0_P1P0_DP<17>")
	)
	(segment
		(start 353.27336 -211.813648)
		(end 353.273614 -211.813902)
		(width 0.14732)
		(layer "In4.Cu")
		(net "UPI_CPU1_CPU0_P1P0_DP<17>")
	)
	(segment
		(start 302.487076 -173.79061)
		(end 302.48733 -173.790864)
		(width 0.14732)
		(layer "In4.Cu")
		(net "UPI_CPU1_CPU0_P1P0_DP<17>")
	)
	(segment
		(start 313.311794 -173.992032)
		(end 317.857124 -175.261778)
		(width 0.14732)
		(layer "In4.Cu")
		(net "UPI_CPU1_CPU0_P1P0_DP<17>")
	)
	(segment
		(start 353.23145 -212.130132)
		(end 353.23145 -212.549232)
		(width 0.0889)
		(layer "In4.Cu")
		(net "UPI_CPU1_CPU0_P1P0_DP<17>")
	)
	(segment
		(start 302.481488 -173.79061)
		(end 302.487076 -173.79061)
		(width 0.14732)
		(layer "In4.Cu")
		(net "UPI_CPU1_CPU0_P1P0_DP<17>")
	)
	(segment
		(start 330.016104 -179.514246)
		(end 337.065874 -182.504334)
		(width 0.14732)
		(layer "In4.Cu")
		(net "UPI_CPU1_CPU0_P1P0_DP<17>")
	)
	(segment
		(start 353.287076 -215.762586)
		(end 353.290378 -215.764618)
		(width 0.0889)
		(layer "In4.Cu")
		(net "UPI_CPU1_CPU0_P1P0_DP<17>")
	)
	(segment
		(start 353.27336 -210.677506)
		(end 353.27336 -211.813648)
		(width 0.14732)
		(layer "In4.Cu")
		(net "UPI_CPU1_CPU0_P1P0_DP<17>")
	)
	(segment
		(start 353.290378 -216.736422)
		(end 353.285044 -216.73947)
		(width 0.0889)
		(layer "In4.Cu")
		(net "UPI_CPU1_CPU0_P1P0_DP<17>")
	)
	(segment
		(start 150.347426 -176.715928)
		(end 157.31236 -174.93361)
		(width 0.14732)
		(layer "In4.Cu")
		(net "UPI_CPU1_CPU0_P1P0_DP<17>")
	)
	(segment
		(start 344.626692 -190.720472)
		(end 350.575372 -196.817234)
		(width 0.14732)
		(layer "In4.Cu")
		(net "UPI_CPU1_CPU0_P1P0_DP<17>")
	)
	(segment
		(start 353.283266 -215.112854)
		(end 353.275392 -215.117426)
		(width 0.0889)
		(layer "In4.Cu")
		(net "UPI_CPU1_CPU0_P1P0_DP<17>")
	)
	(segment
		(start 118.207282 -214.088472)
		(end 118.207028 -214.088218)
		(width 0.0889)
		(layer "In4.Cu")
		(net "UPI_CPU1_CPU0_P1P0_DP<17>")
	)
	(segment
		(start 353.097084 -217.0557)
		(end 353.097084 -217.072972)
		(width 0.0889)
		(layer "In4.Cu")
		(net "UPI_CPU1_CPU0_P1P0_DP<17>")
	)
	(segment
		(start 353.097084 -212.683598)
		(end 353.097084 -213.893908)
		(width 0.0889)
		(layer "In4.Cu")
		(net "UPI_CPU1_CPU0_P1P0_DP<17>")
	)
	(segment
		(start 118.593108 -214.622634)
		(end 118.593108 -214.461344)
		(width 0.0889)
		(layer "In4.Cu")
		(net "UPI_CPU1_CPU0_P1P0_DP<17>")
	)
	(segment
		(start 337.065874 -182.504334)
		(end 338.428076 -183.423052)
		(width 0.14732)
		(layer "In4.Cu")
		(net "UPI_CPU1_CPU0_P1P0_DP<17>")
	)
	(segment
		(start 118.081806 -211.585302)
		(end 118.081552 -211.585048)
		(width 0.14732)
		(layer "In4.Cu")
		(net "UPI_CPU1_CPU0_P1P0_DP<17>")
	)
	(segment
		(start 118.081552 -210.741006)
		(end 121.063766 -202.174348)
		(width 0.14732)
		(layer "In4.Cu")
		(net "UPI_CPU1_CPU0_P1P0_DP<17>")
	)
	(segment
		(start 117.93601 -215.761062)
		(end 117.9449 -215.755982)
		(width 0.0889)
		(layer "In4.Cu")
		(net "UPI_CPU1_CPU0_P1P0_DP<17>")
	)
	(segment
		(start 118.123462 -217.072972)
		(end 118.123462 -217.0557)
		(width 0.0889)
		(layer "In4.Cu")
		(net "UPI_CPU1_CPU0_P1P0_DP<17>")
	)
	(segment
		(start 118.123716 -212.114638)
		(end 118.081806 -212.072728)
		(width 0.0889)
		(layer "In4.Cu")
		(net "UPI_CPU1_CPU0_P1P0_DP<17>")
	)
	(segment
		(start 118.123716 -213.834472)
		(end 118.123716 -212.114638)
		(width 0.0889)
		(layer "In4.Cu")
		(net "UPI_CPU1_CPU0_P1P0_DP<17>")
	)
	(segment
		(start 353.273614 -212.087968)
		(end 353.23145 -212.130132)
		(width 0.0889)
		(layer "In4.Cu")
		(net "UPI_CPU1_CPU0_P1P0_DP<17>")
	)
	(segment
		(start 273.099784 -174.505112)
		(end 302.475646 -173.790864)
		(width 0.14732)
		(layer "In4.Cu")
		(net "UPI_CPU1_CPU0_P1P0_DP<17>")
	)
	(segment
		(start 350.575372 -196.817234)
		(end 353.60356 -204.127862)
		(width 0.14732)
		(layer "In4.Cu")
		(net "UPI_CPU1_CPU0_P1P0_DP<17>")
	)
	(segment
		(start 117.905276 -218.421204)
		(end 117.881146 -218.33205)
		(width 0.0889)
		(layer "In4.Cu")
		(net "UPI_CPU1_CPU0_P1P0_DP<17>")
	)
	(segment
		(start 118.405656 -214.946992)
		(end 118.414546 -214.941912)
		(width 0.0889)
		(layer "In4.Cu")
		(net "UPI_CPU1_CPU0_P1P0_DP<17>")
	)
	(segment
		(start 238.60887 -174.669958)
		(end 273.099784 -174.505112)
		(width 0.14732)
		(layer "In4.Cu")
		(net "UPI_CPU1_CPU0_P1P0_DP<17>")
	)
	(segment
		(start 137.607802 -185.046112)
		(end 137.607548 -185.046112)
		(width 0.14732)
		(layer "In4.Cu")
		(net "UPI_CPU1_CPU0_P1P0_DP<17>")
	)
	(segment
		(start 353.284282 -215.761062)
		(end 353.287076 -215.762586)
		(width 0.0889)
		(layer "In4.Cu")
		(net "UPI_CPU1_CPU0_P1P0_DP<17>")
	)
	(segment
		(start 137.607548 -185.046112)
		(end 139.78382 -182.124858)
		(width 0.14732)
		(layer "In4.Cu")
		(net "UPI_CPU1_CPU0_P1P0_DP<17>")
	)
	(segment
		(start 117.748812 -218.692222)
		(end 117.905276 -218.421204)
		(width 0.0889)
		(layer "In4.Cu")
		(net "UPI_CPU1_CPU0_P1P0_DP<17>")
	)
	(segment
		(start 353.315016 -217.335354)
		(end 353.47148 -217.064336)
		(width 0.0889)
		(layer "In4.Cu")
		(net "UPI_CPU1_CPU0_P1P0_DP<17>")
	)
	(segment
		(start 135.805418 -187.465716)
		(end 137.607802 -185.046112)
		(width 0.14732)
		(layer "In4.Cu")
		(net "UPI_CPU1_CPU0_P1P0_DP<17>")
	)
	(segment
		(start 157.31236 -174.93361)
		(end 200.609962 -174.21479)
		(width 0.14732)
		(layer "In4.Cu")
		(net "UPI_CPU1_CPU0_P1P0_DP<17>")
	)
	(segment
		(start 302.475646 -173.790864)
		(end 302.481488 -173.79061)
		(width 0.14732)
		(layer "In4.Cu")
		(net "UPI_CPU1_CPU0_P1P0_DP<17>")
	)
	(segment
		(start 353.284282 -215.112346)
		(end 353.283266 -215.112854)
		(width 0.0889)
		(layer "In4.Cu")
		(net "UPI_CPU1_CPU0_P1P0_DP<17>")
	)
	(segment
		(start 342.010492 -187.005468)
		(end 344.626692 -190.720472)
		(width 0.14732)
		(layer "In4.Cu")
		(net "UPI_CPU1_CPU0_P1P0_DP<17>")
	)
	(segment
		(start 353.285044 -216.73947)
		(end 353.284282 -216.739978)
		(width 0.0889)
		(layer "In4.Cu")
		(net "UPI_CPU1_CPU0_P1P0_DP<17>")
	)
	(segment
		(start 353.273614 -211.813902)
		(end 353.273614 -212.06587)
		(width 0.14732)
		(layer "In4.Cu")
		(net "UPI_CPU1_CPU0_P1P0_DP<17>")
	)
	(segment
		(start 118.123462 -215.436704)
		(end 118.123462 -215.414606)
		(width 0.0889)
		(layer "In4.Cu")
		(net "UPI_CPU1_CPU0_P1P0_DP<17>")
	)
	(segment
		(start 353.23145 -212.549232)
		(end 353.097084 -212.683598)
		(width 0.0889)
		(layer "In4.Cu")
		(net "UPI_CPU1_CPU0_P1P0_DP<17>")
	)
	(segment
		(start 353.60356 -209.8802)
		(end 353.27336 -210.677506)
		(width 0.14732)
		(layer "In4.Cu")
		(net "UPI_CPU1_CPU0_P1P0_DP<17>")
	)
	(segment
		(start 353.273614 -212.06587)
		(end 353.273614 -212.087968)
		(width 0.0889)
		(layer "In4.Cu")
		(net "UPI_CPU1_CPU0_P1P0_DP<17>")
	)
	(segment
		(start 118.081806 -212.072728)
		(end 118.081806 -212.05063)
		(width 0.0889)
		(layer "In4.Cu")
		(net "UPI_CPU1_CPU0_P1P0_DP<17>")
	)
	(segment
		(start 200.609962 -174.21479)
		(end 210.97621 -174.669958)
		(width 0.14732)
		(layer "In4.Cu")
		(net "UPI_CPU1_CPU0_P1P0_DP<17>")
	)
	(segment
		(start 353.275392 -215.755982)
		(end 353.282758 -215.7603)
		(width 0.0889)
		(layer "In4.Cu")
		(net "UPI_CPU1_CPU0_P1P0_DP<17>")
	)
	(segment
		(start 210.97621 -174.669958)
		(end 238.60887 -174.669958)
		(width 0.14732)
		(layer "In4.Cu")
		(net "UPI_CPU1_CPU0_P1P0_DP<17>")
	)
	(arc
		(start 117.864382 -218.319096)
		(mid 117.7123 -218.129664)
		(end 117.653816 -217.8939)
		(width 0.0889)
		(layer "In4.Cu")
		(net "UPI_CPU1_CPU0_P1P0_DP<17>")
	)
	(arc
		(start 353.097084 -213.893908)
		(mid 353.172089 -214.009367)
		(end 353.281234 -214.093298)
		(width 0.0889)
		(layer "In4.Cu")
		(net "UPI_CPU1_CPU0_P1P0_DP<17>")
	)
	(arc
		(start 353.566476 -214.644732)
		(mid 353.485565 -214.91486)
		(end 353.284282 -215.112346)
		(width 0.0889)
		(layer "In4.Cu")
		(net "UPI_CPU1_CPU0_P1P0_DP<17>")
	)
	(arc
		(start 118.414546 -214.941912)
		(mid 118.54546 -214.805552)
		(end 118.593108 -214.622634)
		(width 0.0889)
		(layer "In4.Cu")
		(net "UPI_CPU1_CPU0_P1P0_DP<17>")
	)
	(arc
		(start 118.123462 -215.414606)
		(mid 118.204373 -215.144478)
		(end 118.405656 -214.946992)
		(width 0.0889)
		(layer "In4.Cu")
		(net "UPI_CPU1_CPU0_P1P0_DP<17>")
	)
	(arc
		(start 117.653816 -217.859864)
		(mid 117.733978 -217.587675)
		(end 117.936264 -217.388694)
		(width 0.0889)
		(layer "In4.Cu")
		(net "UPI_CPU1_CPU0_P1P0_DP<17>")
	)
	(arc
		(start 353.09683 -215.436704)
		(mid 353.144509 -215.619604)
		(end 353.275392 -215.755982)
		(width 0.0889)
		(layer "In4.Cu")
		(net "UPI_CPU1_CPU0_P1P0_DP<17>")
	)
	(arc
		(start 353.281234 -214.093298)
		(mid 353.455197 -214.232062)
		(end 353.566476 -214.424768)
		(width 0.0889)
		(layer "In4.Cu")
		(net "UPI_CPU1_CPU0_P1P0_DP<17>")
	)
	(arc
		(start 118.123462 -217.0557)
		(mid 118.071192 -216.873335)
		(end 117.936264 -216.739978)
		(width 0.0889)
		(layer "In4.Cu")
		(net "UPI_CPU1_CPU0_P1P0_DP<17>")
	)
	(arc
		(start 117.881146 -218.33205)
		(mid 117.872705 -218.32565)
		(end 117.864382 -218.319096)
		(width 0.0889)
		(layer "In4.Cu")
		(net "UPI_CPU1_CPU0_P1P0_DP<17>")
	)
	(arc
		(start 117.936264 -217.388694)
		(mid 118.071197 -217.25534)
		(end 118.123462 -217.072972)
		(width 0.0889)
		(layer "In4.Cu")
		(net "UPI_CPU1_CPU0_P1P0_DP<17>")
	)
	(arc
		(start 353.275392 -215.117426)
		(mid 353.148138 -215.247392)
		(end 353.097084 -215.421972)
		(width 0.0889)
		(layer "In4.Cu")
		(net "UPI_CPU1_CPU0_P1P0_DP<17>")
	)
	(arc
		(start 117.9449 -215.755982)
		(mid 118.075814 -215.619622)
		(end 118.123462 -215.436704)
		(width 0.0889)
		(layer "In4.Cu")
		(net "UPI_CPU1_CPU0_P1P0_DP<17>")
	)
	(arc
		(start 117.653816 -216.235026)
		(mid 117.733186 -215.961292)
		(end 117.93601 -215.761062)
		(width 0.0889)
		(layer "In4.Cu")
		(net "UPI_CPU1_CPU0_P1P0_DP<17>")
	)
	(arc
		(start 118.593108 -214.461344)
		(mid 118.518103 -214.345885)
		(end 118.408958 -214.261954)
		(width 0.0889)
		(layer "In4.Cu")
		(net "UPI_CPU1_CPU0_P1P0_DP<17>")
	)
	(arc
		(start 353.284282 -216.739978)
		(mid 353.149349 -216.873332)
		(end 353.097084 -217.0557)
		(width 0.0889)
		(layer "In4.Cu")
		(net "UPI_CPU1_CPU0_P1P0_DP<17>")
	)
	(arc
		(start 118.207028 -214.088218)
		(mid 118.145027 -213.968028)
		(end 118.123716 -213.834472)
		(width 0.0889)
		(layer "In4.Cu")
		(net "UPI_CPU1_CPU0_P1P0_DP<17>")
	)
	(arc
		(start 118.408958 -214.261954)
		(mid 118.298367 -214.186552)
		(end 118.207282 -214.088472)
		(width 0.0889)
		(layer "In4.Cu")
		(net "UPI_CPU1_CPU0_P1P0_DP<17>")
	)
	(arc
		(start 353.290378 -215.764618)
		(mid 353.566952 -216.25052)
		(end 353.290378 -216.736422)
		(width 0.0889)
		(layer "In4.Cu")
		(net "UPI_CPU1_CPU0_P1P0_DP<17>")
	)
	(arc
		(start 117.936264 -216.739978)
		(mid 117.731929 -216.537373)
		(end 117.653816 -216.260426)
		(width 0.0889)
		(layer "In4.Cu")
		(net "UPI_CPU1_CPU0_P1P0_DP<17>")
	)
	(arc
		(start 353.097084 -217.072972)
		(mid 353.135758 -217.23004)
		(end 353.237038 -217.356182)
		(width 0.0889)
		(layer "In4.Cu")
		(net "UPI_CPU1_CPU0_P1P0_DP<17>")
	)
	(arc
		(start 353.097084 -215.421972)
		(mid 353.096887 -215.429337)
		(end 353.09683 -215.436704)
		(width 0.0889)
		(layer "In4.Cu")
		(net "UPI_CPU1_CPU0_P1P0_DP<17>")
	)
	(segment
		(start 352.06178 -217.87866)
		(end 352.062034 -217.878406)
		(width 0.13208)
		(layer "F.Cu")
		(net "UPI_CPU1_CPU0_P1P0_DP<16>")
	)
	(segment
		(start 119.158512 -218.414346)
		(end 119.158512 -217.87866)
		(width 0.13208)
		(layer "F.Cu")
		(net "UPI_CPU1_CPU0_P1P0_DP<16>")
	)
	(segment
		(start 352.06178 -218.414346)
		(end 352.06178 -217.87866)
		(width 0.13208)
		(layer "F.Cu")
		(net "UPI_CPU1_CPU0_P1P0_DP<16>")
	)
	(segment
		(start 119.158512 -217.87866)
		(end 119.158766 -217.878406)
		(width 0.13208)
		(layer "F.Cu")
		(net "UPI_CPU1_CPU0_P1P0_DP<16>")
	)
	(segment
		(start 352.158554 -212.11159)
		(end 352.158554 -212.133688)
		(width 0.0889)
		(layer "In4.Cu")
		(net "UPI_CPU1_CPU0_P1P0_DP<16>")
	)
	(segment
		(start 352.243136 -215.922606)
		(end 352.24847 -215.925654)
		(width 0.0889)
		(layer "In4.Cu")
		(net "UPI_CPU1_CPU0_P1P0_DP<16>")
	)
	(segment
		(start 119.432324 -215.117426)
		(end 119.441214 -215.112346)
		(width 0.0889)
		(layer "In4.Cu")
		(net "UPI_CPU1_CPU0_P1P0_DP<16>")
	)
	(segment
		(start 131.055364 -192.155064)
		(end 131.36245 -191.951102)
		(width 0.14732)
		(layer "In4.Cu")
		(net "UPI_CPU1_CPU0_P1P0_DP<16>")
	)
	(segment
		(start 119.723408 -214.644732)
		(end 119.723154 -214.501222)
		(width 0.0889)
		(layer "In4.Cu")
		(net "UPI_CPU1_CPU0_P1P0_DP<16>")
	)
	(segment
		(start 119.29618 -212.024468)
		(end 119.29618 -212.00237)
		(width 0.0889)
		(layer "In4.Cu")
		(net "UPI_CPU1_CPU0_P1P0_DP<16>")
	)
	(segment
		(start 120.86082 -206.534766)
		(end 121.005092 -206.122524)
		(width 0.14732)
		(layer "In4.Cu")
		(net "UPI_CPU1_CPU0_P1P0_DP<16>")
	)
	(segment
		(start 119.752872 -209.699606)
		(end 119.897144 -209.287364)
		(width 0.14732)
		(layer "In4.Cu")
		(net "UPI_CPU1_CPU0_P1P0_DP<16>")
	)
	(segment
		(start 352.249232 -217.554048)
		(end 352.249994 -217.554556)
		(width 0.0889)
		(layer "In4.Cu")
		(net "UPI_CPU1_CPU0_P1P0_DP<16>")
	)
	(segment
		(start 352.16846 -207.448912)
		(end 352.31324 -207.593692)
		(width 0.14732)
		(layer "In4.Cu")
		(net "UPI_CPU1_CPU0_P1P0_DP<16>")
	)
	(segment
		(start 352.241612 -216.579196)
		(end 352.23704 -216.58199)
		(width 0.0889)
		(layer "In4.Cu")
		(net "UPI_CPU1_CPU0_P1P0_DP<16>")
	)
	(segment
		(start 352.1583 -211.955888)
		(end 352.158554 -211.956142)
		(width 0.14732)
		(layer "In4.Cu")
		(net "UPI_CPU1_CPU0_P1P0_DP<16>")
	)
	(segment
		(start 341.081106 -187.6425)
		(end 343.707466 -191.370966)
		(width 0.14732)
		(layer "In4.Cu")
		(net "UPI_CPU1_CPU0_P1P0_DP<16>")
	)
	(segment
		(start 120.26646 -208.232502)
		(end 120.421908 -208.157826)
		(width 0.14732)
		(layer "In4.Cu")
		(net "UPI_CPU1_CPU0_P1P0_DP<16>")
	)
	(segment
		(start 136.559544 -188.322712)
		(end 140.535406 -182.985918)
		(width 0.14732)
		(layer "In4.Cu")
		(net "UPI_CPU1_CPU0_P1P0_DP<16>")
	)
	(segment
		(start 352.31324 -206.935832)
		(end 352.16846 -207.080612)
		(width 0.14732)
		(layer "In4.Cu")
		(net "UPI_CPU1_CPU0_P1P0_DP<16>")
	)
	(segment
		(start 119.29618 -212.00237)
		(end 119.29618 -211.699602)
		(width 0.14732)
		(layer "In4.Cu")
		(net "UPI_CPU1_CPU0_P1P0_DP<16>")
	)
	(segment
		(start 119.253762 -215.452198)
		(end 119.253762 -215.436704)
		(width 0.0889)
		(layer "In4.Cu")
		(net "UPI_CPU1_CPU0_P1P0_DP<16>")
	)
	(segment
		(start 121.005092 -206.122524)
		(end 121.16054 -206.047848)
		(width 0.14732)
		(layer "In4.Cu")
		(net "UPI_CPU1_CPU0_P1P0_DP<16>")
	)
	(segment
		(start 351.96653 -217.064336)
		(end 351.96653 -217.071956)
		(width 0.0889)
		(layer "In4.Cu")
		(net "UPI_CPU1_CPU0_P1P0_DP<16>")
	)
	(segment
		(start 352.200464 -212.175598)
		(end 352.200464 -212.553804)
		(width 0.0889)
		(layer "In4.Cu")
		(net "UPI_CPU1_CPU0_P1P0_DP<16>")
	)
	(segment
		(start 121.304812 -205.635098)
		(end 121.230136 -205.47965)
		(width 0.14732)
		(layer "In4.Cu")
		(net "UPI_CPU1_CPU0_P1P0_DP<16>")
	)
	(segment
		(start 352.16846 -208.106772)
		(end 352.16846 -208.475072)
		(width 0.14732)
		(layer "In4.Cu")
		(net "UPI_CPU1_CPU0_P1P0_DP<16>")
	)
	(segment
		(start 130.45313 -192.381378)
		(end 130.854704 -192.114424)
		(width 0.14732)
		(layer "In4.Cu")
		(net "UPI_CPU1_CPU0_P1P0_DP<16>")
	)
	(segment
		(start 120.421908 -208.157826)
		(end 120.566434 -207.745076)
		(width 0.14732)
		(layer "In4.Cu")
		(net "UPI_CPU1_CPU0_P1P0_DP<16>")
	)
	(segment
		(start 119.254016 -213.787482)
		(end 119.254016 -212.066632)
		(width 0.0889)
		(layer "In4.Cu")
		(net "UPI_CPU1_CPU0_P1P0_DP<16>")
	)
	(segment
		(start 140.535406 -182.985918)
		(end 150.644098 -177.810414)
		(width 0.14732)
		(layer "In4.Cu")
		(net "UPI_CPU1_CPU0_P1P0_DP<16>")
	)
	(segment
		(start 118.962678 -215.931242)
		(end 118.971568 -215.926162)
		(width 0.0889)
		(layer "In4.Cu")
		(net "UPI_CPU1_CPU0_P1P0_DP<16>")
	)
	(segment
		(start 119.158766 -217.878406)
		(end 119.002302 -217.607388)
		(width 0.0889)
		(layer "In4.Cu")
		(net "UPI_CPU1_CPU0_P1P0_DP<16>")
	)
	(segment
		(start 119.295926 -211.004912)
		(end 119.527828 -210.342226)
		(width 0.14732)
		(layer "In4.Cu")
		(net "UPI_CPU1_CPU0_P1P0_DP<16>")
	)
	(segment
		(start 336.516218 -183.477916)
		(end 337.740752 -184.302146)
		(width 0.14732)
		(layer "In4.Cu")
		(net "UPI_CPU1_CPU0_P1P0_DP<16>")
	)
	(segment
		(start 329.628754 -180.568092)
		(end 336.516218 -183.477916)
		(width 0.14732)
		(layer "In4.Cu")
		(net "UPI_CPU1_CPU0_P1P0_DP<16>")
	)
	(segment
		(start 120.635776 -207.17764)
		(end 120.791224 -207.102964)
		(width 0.14732)
		(layer "In4.Cu")
		(net "UPI_CPU1_CPU0_P1P0_DP<16>")
	)
	(segment
		(start 302.48479 -174.921926)
		(end 313.24804 -175.122078)
		(width 0.14732)
		(layer "In4.Cu")
		(net "UPI_CPU1_CPU0_P1P0_DP<16>")
	)
	(segment
		(start 352.249994 -217.554556)
		(end 352.258122 -217.559128)
		(width 0.0889)
		(layer "In4.Cu")
		(net "UPI_CPU1_CPU0_P1P0_DP<16>")
	)
	(segment
		(start 352.250756 -215.926924)
		(end 352.258122 -215.931242)
		(width 0.0889)
		(layer "In4.Cu")
		(net "UPI_CPU1_CPU0_P1P0_DP<16>")
	)
	(segment
		(start 352.16846 -207.080612)
		(end 352.16846 -207.448912)
		(width 0.14732)
		(layer "In4.Cu")
		(net "UPI_CPU1_CPU0_P1P0_DP<16>")
	)
	(segment
		(start 352.436176 -214.461344)
		(end 352.436176 -214.622634)
		(width 0.0889)
		(layer "In4.Cu")
		(net "UPI_CPU1_CPU0_P1P0_DP<16>")
	)
	(segment
		(start 154.101038 -176.925732)
		(end 157.558486 -176.040796)
		(width 0.14732)
		(layer "In4.Cu")
		(net "UPI_CPU1_CPU0_P1P0_DP<16>")
	)
	(segment
		(start 119.295926 -211.699348)
		(end 119.295926 -211.004912)
		(width 0.14732)
		(layer "In4.Cu")
		(net "UPI_CPU1_CPU0_P1P0_DP<16>")
	)
	(segment
		(start 119.827802 -209.855054)
		(end 119.752872 -209.699606)
		(width 0.14732)
		(layer "In4.Cu")
		(net "UPI_CPU1_CPU0_P1P0_DP<16>")
	)
	(segment
		(start 120.052592 -209.212688)
		(end 120.197118 -208.799938)
		(width 0.14732)
		(layer "In4.Cu")
		(net "UPI_CPU1_CPU0_P1P0_DP<16>")
	)
	(segment
		(start 119.254016 -212.066632)
		(end 119.29618 -212.024468)
		(width 0.0889)
		(layer "In4.Cu")
		(net "UPI_CPU1_CPU0_P1P0_DP<16>")
	)
	(segment
		(start 273.116294 -175.635666)
		(end 302.48479 -174.921926)
		(width 0.14732)
		(layer "In4.Cu")
		(net "UPI_CPU1_CPU0_P1P0_DP<16>")
	)
	(segment
		(start 122.306334 -202.404218)
		(end 122.306842 -202.40371)
		(width 0.14732)
		(layer "In4.Cu")
		(net "UPI_CPU1_CPU0_P1P0_DP<16>")
	)
	(segment
		(start 317.498984 -176.309274)
		(end 329.628754 -180.568092)
		(width 0.14732)
		(layer "In4.Cu")
		(net "UPI_CPU1_CPU0_P1P0_DP<16>")
	)
	(segment
		(start 122.306842 -202.40371)
		(end 130.45313 -192.381378)
		(width 0.14732)
		(layer "In4.Cu")
		(net "UPI_CPU1_CPU0_P1P0_DP<16>")
	)
	(segment
		(start 118.971568 -216.574878)
		(end 118.962678 -216.569798)
		(width 0.0889)
		(layer "In4.Cu")
		(net "UPI_CPU1_CPU0_P1P0_DP<16>")
	)
	(segment
		(start 352.245422 -216.577164)
		(end 352.241612 -216.579196)
		(width 0.0889)
		(layer "In4.Cu")
		(net "UPI_CPU1_CPU0_P1P0_DP<16>")
	)
	(segment
		(start 120.791224 -207.102964)
		(end 120.935496 -206.690214)
		(width 0.14732)
		(layer "In4.Cu")
		(net "UPI_CPU1_CPU0_P1P0_DP<16>")
	)
	(segment
		(start 130.854704 -192.114424)
		(end 131.055364 -192.155064)
		(width 0.14732)
		(layer "In4.Cu")
		(net "UPI_CPU1_CPU0_P1P0_DP<16>")
	)
	(segment
		(start 119.527828 -210.342226)
		(end 119.683276 -210.26755)
		(width 0.14732)
		(layer "In4.Cu")
		(net "UPI_CPU1_CPU0_P1P0_DP<16>")
	)
	(segment
		(start 150.644098 -177.810414)
		(end 154.100784 -176.925986)
		(width 0.14732)
		(layer "In4.Cu")
		(net "UPI_CPU1_CPU0_P1P0_DP<16>")
	)
	(segment
		(start 337.740752 -184.302146)
		(end 341.081106 -187.6425)
		(width 0.14732)
		(layer "In4.Cu")
		(net "UPI_CPU1_CPU0_P1P0_DP<16>")
	)
	(segment
		(start 119.29618 -211.699602)
		(end 119.295926 -211.699348)
		(width 0.14732)
		(layer "In4.Cu")
		(net "UPI_CPU1_CPU0_P1P0_DP<16>")
	)
	(segment
		(start 343.707466 -191.370966)
		(end 349.60433 -197.41515)
		(width 0.14732)
		(layer "In4.Cu")
		(net "UPI_CPU1_CPU0_P1P0_DP<16>")
	)
	(segment
		(start 352.31324 -208.619852)
		(end 352.31324 -208.988152)
		(width 0.14732)
		(layer "In4.Cu")
		(net "UPI_CPU1_CPU0_P1P0_DP<16>")
	)
	(segment
		(start 352.31324 -207.593692)
		(end 352.31324 -207.961992)
		(width 0.14732)
		(layer "In4.Cu")
		(net "UPI_CPU1_CPU0_P1P0_DP<16>")
	)
	(segment
		(start 119.254016 -217.07856)
		(end 119.254016 -217.064336)
		(width 0.0889)
		(layer "In4.Cu")
		(net "UPI_CPU1_CPU0_P1P0_DP<16>")
	)
	(segment
		(start 352.257614 -214.941912)
		(end 352.248724 -214.946992)
		(width 0.0889)
		(layer "In4.Cu")
		(net "UPI_CPU1_CPU0_P1P0_DP<16>")
	)
	(segment
		(start 352.29673 -218.170252)
		(end 352.218498 -218.149424)
		(width 0.0889)
		(layer "In4.Cu")
		(net "UPI_CPU1_CPU0_P1P0_DP<16>")
	)
	(segment
		(start 352.31324 -203.955142)
		(end 352.31324 -206.935832)
		(width 0.14732)
		(layer "In4.Cu")
		(net "UPI_CPU1_CPU0_P1P0_DP<16>")
	)
	(segment
		(start 157.558486 -176.040796)
		(end 200.182226 -175.33366)
		(width 0.14732)
		(layer "In4.Cu")
		(net "UPI_CPU1_CPU0_P1P0_DP<16>")
	)
	(segment
		(start 352.16846 -209.501232)
		(end 352.31324 -209.646012)
		(width 0.14732)
		(layer "In4.Cu")
		(net "UPI_CPU1_CPU0_P1P0_DP<16>")
	)
	(segment
		(start 131.402836 -191.750188)
		(end 136.559544 -188.322712)
		(width 0.14732)
		(layer "In4.Cu")
		(net "UPI_CPU1_CPU0_P1P0_DP<16>")
	)
	(segment
		(start 121.16054 -206.047848)
		(end 121.304812 -205.635098)
		(width 0.14732)
		(layer "In4.Cu")
		(net "UPI_CPU1_CPU0_P1P0_DP<16>")
	)
	(segment
		(start 210.814666 -175.800512)
		(end 238.611918 -175.800512)
		(width 0.14732)
		(layer "In4.Cu")
		(net "UPI_CPU1_CPU0_P1P0_DP<16>")
	)
	(segment
		(start 238.611918 -175.800512)
		(end 273.116294 -175.635666)
		(width 0.14732)
		(layer "In4.Cu")
		(net "UPI_CPU1_CPU0_P1P0_DP<16>")
	)
	(segment
		(start 352.158554 -211.956142)
		(end 352.158554 -212.11159)
		(width 0.14732)
		(layer "In4.Cu")
		(net "UPI_CPU1_CPU0_P1P0_DP<16>")
	)
	(segment
		(start 349.60433 -197.41515)
		(end 352.31324 -203.955142)
		(width 0.14732)
		(layer "In4.Cu")
		(net "UPI_CPU1_CPU0_P1P0_DP<16>")
	)
	(segment
		(start 351.966784 -212.787484)
		(end 351.966784 -213.930484)
		(width 0.0889)
		(layer "In4.Cu")
		(net "UPI_CPU1_CPU0_P1P0_DP<16>")
	)
	(segment
		(start 118.977664 -216.578434)
		(end 118.971568 -216.574878)
		(width 0.0889)
		(layer "In4.Cu")
		(net "UPI_CPU1_CPU0_P1P0_DP<16>")
	)
	(segment
		(start 120.566434 -207.745076)
		(end 120.491504 -207.589882)
		(width 0.14732)
		(layer "In4.Cu")
		(net "UPI_CPU1_CPU0_P1P0_DP<16>")
	)
	(segment
		(start 120.491504 -207.589882)
		(end 120.635776 -207.17764)
		(width 0.14732)
		(layer "In4.Cu")
		(net "UPI_CPU1_CPU0_P1P0_DP<16>")
	)
	(segment
		(start 131.36245 -191.951102)
		(end 131.402836 -191.750188)
		(width 0.14732)
		(layer "In4.Cu")
		(net "UPI_CPU1_CPU0_P1P0_DP<16>")
	)
	(segment
		(start 352.258122 -216.569798)
		(end 352.249232 -216.574878)
		(width 0.0889)
		(layer "In4.Cu")
		(net "UPI_CPU1_CPU0_P1P0_DP<16>")
	)
	(segment
		(start 352.158554 -212.133688)
		(end 352.200464 -212.175598)
		(width 0.0889)
		(layer "In4.Cu")
		(net "UPI_CPU1_CPU0_P1P0_DP<16>")
	)
	(segment
		(start 119.002302 -217.607388)
		(end 119.026432 -217.518234)
		(width 0.0889)
		(layer "In4.Cu")
		(net "UPI_CPU1_CPU0_P1P0_DP<16>")
	)
	(segment
		(start 120.935496 -206.690214)
		(end 120.86082 -206.534766)
		(width 0.14732)
		(layer "In4.Cu")
		(net "UPI_CPU1_CPU0_P1P0_DP<16>")
	)
	(segment
		(start 313.24804 -175.122078)
		(end 317.498984 -176.309274)
		(width 0.14732)
		(layer "In4.Cu")
		(net "UPI_CPU1_CPU0_P1P0_DP<16>")
	)
	(segment
		(start 200.182226 -175.33366)
		(end 210.814666 -175.800512)
		(width 0.14732)
		(layer "In4.Cu")
		(net "UPI_CPU1_CPU0_P1P0_DP<16>")
	)
	(segment
		(start 352.249232 -215.926162)
		(end 352.250756 -215.926924)
		(width 0.0889)
		(layer "In4.Cu")
		(net "UPI_CPU1_CPU0_P1P0_DP<16>")
	)
	(segment
		(start 154.100784 -176.925986)
		(end 154.101038 -176.925732)
		(width 0.14732)
		(layer "In4.Cu")
		(net "UPI_CPU1_CPU0_P1P0_DP<16>")
	)
	(segment
		(start 352.31324 -208.988152)
		(end 352.16846 -209.132932)
		(width 0.14732)
		(layer "In4.Cu")
		(net "UPI_CPU1_CPU0_P1P0_DP<16>")
	)
	(segment
		(start 352.218498 -218.149424)
		(end 352.062034 -217.878406)
		(width 0.0889)
		(layer "In4.Cu")
		(net "UPI_CPU1_CPU0_P1P0_DP<16>")
	)
	(segment
		(start 352.249232 -216.574878)
		(end 352.245422 -216.577164)
		(width 0.0889)
		(layer "In4.Cu")
		(net "UPI_CPU1_CPU0_P1P0_DP<16>")
	)
	(segment
		(start 121.230136 -205.47965)
		(end 122.306334 -202.404218)
		(width 0.14732)
		(layer "In4.Cu")
		(net "UPI_CPU1_CPU0_P1P0_DP<16>")
	)
	(segment
		(start 119.683276 -210.26755)
		(end 119.827802 -209.855054)
		(width 0.14732)
		(layer "In4.Cu")
		(net "UPI_CPU1_CPU0_P1P0_DP<16>")
	)
	(segment
		(start 352.31324 -207.961992)
		(end 352.16846 -208.106772)
		(width 0.14732)
		(layer "In4.Cu")
		(net "UPI_CPU1_CPU0_P1P0_DP<16>")
	)
	(segment
		(start 352.1583 -210.388454)
		(end 352.1583 -211.955888)
		(width 0.14732)
		(layer "In4.Cu")
		(net "UPI_CPU1_CPU0_P1P0_DP<16>")
	)
	(segment
		(start 352.200464 -212.553804)
		(end 351.966784 -212.787484)
		(width 0.0889)
		(layer "In4.Cu")
		(net "UPI_CPU1_CPU0_P1P0_DP<16>")
	)
	(segment
		(start 352.16846 -208.475072)
		(end 352.31324 -208.619852)
		(width 0.14732)
		(layer "In4.Cu")
		(net "UPI_CPU1_CPU0_P1P0_DP<16>")
	)
	(segment
		(start 351.96653 -215.414606)
		(end 351.96653 -215.436704)
		(width 0.0889)
		(layer "In4.Cu")
		(net "UPI_CPU1_CPU0_P1P0_DP<16>")
	)
	(segment
		(start 119.897144 -209.287364)
		(end 120.052592 -209.212688)
		(width 0.14732)
		(layer "In4.Cu")
		(net "UPI_CPU1_CPU0_P1P0_DP<16>")
	)
	(segment
		(start 120.122188 -208.644744)
		(end 120.26646 -208.232502)
		(width 0.14732)
		(layer "In4.Cu")
		(net "UPI_CPU1_CPU0_P1P0_DP<16>")
	)
	(segment
		(start 352.16846 -209.132932)
		(end 352.16846 -209.501232)
		(width 0.14732)
		(layer "In4.Cu")
		(net "UPI_CPU1_CPU0_P1P0_DP<16>")
	)
	(segment
		(start 120.197118 -208.799938)
		(end 120.122188 -208.644744)
		(width 0.14732)
		(layer "In4.Cu")
		(net "UPI_CPU1_CPU0_P1P0_DP<16>")
	)
	(segment
		(start 352.31324 -209.646012)
		(end 352.31324 -210.014312)
		(width 0.14732)
		(layer "In4.Cu")
		(net "UPI_CPU1_CPU0_P1P0_DP<16>")
	)
	(segment
		(start 352.31324 -210.014312)
		(end 352.1583 -210.388454)
		(width 0.14732)
		(layer "In4.Cu")
		(net "UPI_CPU1_CPU0_P1P0_DP<16>")
	)
	(segment
		(start 352.24847 -215.925654)
		(end 352.249232 -215.926162)
		(width 0.0889)
		(layer "In4.Cu")
		(net "UPI_CPU1_CPU0_P1P0_DP<16>")
	)
	(arc
		(start 352.258122 -215.931242)
		(mid 352.436719 -216.25052)
		(end 352.258122 -216.569798)
		(width 0.0889)
		(layer "In4.Cu")
		(net "UPI_CPU1_CPU0_P1P0_DP<16>")
	)
	(arc
		(start 352.436176 -214.622634)
		(mid 352.388497 -214.805534)
		(end 352.257614 -214.941912)
		(width 0.0889)
		(layer "In4.Cu")
		(net "UPI_CPU1_CPU0_P1P0_DP<16>")
	)
	(arc
		(start 352.258122 -217.559128)
		(mid 352.389036 -217.695488)
		(end 352.436684 -217.878406)
		(width 0.0889)
		(layer "In4.Cu")
		(net "UPI_CPU1_CPU0_P1P0_DP<16>")
	)
	(arc
		(start 119.254016 -217.064336)
		(mid 119.1801 -216.784834)
		(end 118.977664 -216.578434)
		(width 0.0889)
		(layer "In4.Cu")
		(net "UPI_CPU1_CPU0_P1P0_DP<16>")
	)
	(arc
		(start 118.971568 -215.926162)
		(mid 119.174391 -215.725931)
		(end 119.253762 -215.452198)
		(width 0.0889)
		(layer "In4.Cu")
		(net "UPI_CPU1_CPU0_P1P0_DP<16>")
	)
	(arc
		(start 119.674132 -214.319104)
		(mid 119.571832 -214.189817)
		(end 119.438166 -214.093298)
		(width 0.0889)
		(layer "In4.Cu")
		(net "UPI_CPU1_CPU0_P1P0_DP<16>")
	)
	(arc
		(start 119.441214 -215.112346)
		(mid 119.642496 -214.914859)
		(end 119.723408 -214.644732)
		(width 0.0889)
		(layer "In4.Cu")
		(net "UPI_CPU1_CPU0_P1P0_DP<16>")
	)
	(arc
		(start 119.438166 -214.093298)
		(mid 119.303587 -213.965994)
		(end 119.254016 -213.787482)
		(width 0.0889)
		(layer "In4.Cu")
		(net "UPI_CPU1_CPU0_P1P0_DP<16>")
	)
	(arc
		(start 119.026432 -217.518234)
		(mid 119.034875 -217.511836)
		(end 119.043196 -217.50528)
		(width 0.0889)
		(layer "In4.Cu")
		(net "UPI_CPU1_CPU0_P1P0_DP<16>")
	)
	(arc
		(start 352.248724 -214.946992)
		(mid 352.047442 -215.144479)
		(end 351.96653 -215.414606)
		(width 0.0889)
		(layer "In4.Cu")
		(net "UPI_CPU1_CPU0_P1P0_DP<16>")
	)
	(arc
		(start 351.96653 -215.436704)
		(mid 352.040521 -215.71627)
		(end 352.243136 -215.922606)
		(width 0.0889)
		(layer "In4.Cu")
		(net "UPI_CPU1_CPU0_P1P0_DP<16>")
	)
	(arc
		(start 352.252026 -214.261954)
		(mid 352.361173 -214.345882)
		(end 352.436176 -214.461344)
		(width 0.0889)
		(layer "In4.Cu")
		(net "UPI_CPU1_CPU0_P1P0_DP<16>")
	)
	(arc
		(start 118.962678 -216.569798)
		(mid 118.784202 -216.25052)
		(end 118.962678 -215.931242)
		(width 0.0889)
		(layer "In4.Cu")
		(net "UPI_CPU1_CPU0_P1P0_DP<16>")
	)
	(arc
		(start 119.043196 -217.50528)
		(mid 119.195703 -217.315182)
		(end 119.254016 -217.07856)
		(width 0.0889)
		(layer "In4.Cu")
		(net "UPI_CPU1_CPU0_P1P0_DP<16>")
	)
	(arc
		(start 119.253762 -215.436704)
		(mid 119.253814 -215.429337)
		(end 119.254016 -215.421972)
		(width 0.0889)
		(layer "In4.Cu")
		(net "UPI_CPU1_CPU0_P1P0_DP<16>")
	)
	(arc
		(start 119.254016 -215.421972)
		(mid 119.30507 -215.247392)
		(end 119.432324 -215.117426)
		(width 0.0889)
		(layer "In4.Cu")
		(net "UPI_CPU1_CPU0_P1P0_DP<16>")
	)
	(arc
		(start 351.966784 -213.930484)
		(mid 351.974069 -213.950046)
		(end 351.982024 -213.969346)
		(width 0.0889)
		(layer "In4.Cu")
		(net "UPI_CPU1_CPU0_P1P0_DP<16>")
	)
	(arc
		(start 351.982024 -213.969346)
		(mid 352.092018 -214.138715)
		(end 352.252026 -214.261954)
		(width 0.0889)
		(layer "In4.Cu")
		(net "UPI_CPU1_CPU0_P1P0_DP<16>")
	)
	(arc
		(start 352.436684 -217.878406)
		(mid 352.399824 -218.040203)
		(end 352.29673 -218.170252)
		(width 0.0889)
		(layer "In4.Cu")
		(net "UPI_CPU1_CPU0_P1P0_DP<16>")
	)
	(arc
		(start 351.96653 -217.071956)
		(mid 352.044159 -217.350369)
		(end 352.249232 -217.554048)
		(width 0.0889)
		(layer "In4.Cu")
		(net "UPI_CPU1_CPU0_P1P0_DP<16>")
	)
	(arc
		(start 119.723154 -214.501222)
		(mid 119.710773 -214.406901)
		(end 119.674132 -214.319104)
		(width 0.0889)
		(layer "In4.Cu")
		(net "UPI_CPU1_CPU0_P1P0_DP<16>")
	)
	(arc
		(start 352.23704 -216.58199)
		(mid 352.038812 -216.787838)
		(end 351.96653 -217.064336)
		(width 0.0889)
		(layer "In4.Cu")
		(net "UPI_CPU1_CPU0_P1P0_DP<16>")
	)
	(segment
		(start 351.592134 -217.600276)
		(end 351.592134 -217.06459)
		(width 0.13208)
		(layer "F.Cu")
		(net "UPI_CPU1_CPU0_P1P0_DP<15>")
	)
	(segment
		(start 119.628666 -219.228162)
		(end 119.628666 -218.692476)
		(width 0.13208)
		(layer "F.Cu")
		(net "UPI_CPU1_CPU0_P1P0_DP<15>")
	)
	(segment
		(start 351.592134 -217.06459)
		(end 351.59188 -217.064336)
		(width 0.13208)
		(layer "F.Cu")
		(net "UPI_CPU1_CPU0_P1P0_DP<15>")
	)
	(segment
		(start 119.628666 -218.692476)
		(end 119.628412 -218.692222)
		(width 0.13208)
		(layer "F.Cu")
		(net "UPI_CPU1_CPU0_P1P0_DP<15>")
	)
	(segment
		(start 351.592134 -212.03285)
		(end 351.592134 -212.054948)
		(width 0.0889)
		(layer "In4.Cu")
		(net "UPI_CPU1_CPU0_P1P0_DP<15>")
	)
	(segment
		(start 351.405444 -216.73947)
		(end 351.404682 -216.739978)
		(width 0.0889)
		(layer "In4.Cu")
		(net "UPI_CPU1_CPU0_P1P0_DP<15>")
	)
	(segment
		(start 351.59188 -211.745068)
		(end 351.592134 -211.745322)
		(width 0.14732)
		(layer "In4.Cu")
		(net "UPI_CPU1_CPU0_P1P0_DP<15>")
	)
	(segment
		(start 336.251804 -183.969152)
		(end 337.384136 -184.731152)
		(width 0.14732)
		(layer "In4.Cu")
		(net "UPI_CPU1_CPU0_P1P0_DP<15>")
	)
	(segment
		(start 351.592134 -211.745322)
		(end 351.592134 -212.03285)
		(width 0.14732)
		(layer "In4.Cu")
		(net "UPI_CPU1_CPU0_P1P0_DP<15>")
	)
	(segment
		(start 349.113602 -197.720458)
		(end 351.571052 -203.653644)
		(width 0.14732)
		(layer "In4.Cu")
		(net "UPI_CPU1_CPU0_P1P0_DP<15>")
	)
	(segment
		(start 351.404682 -215.761062)
		(end 351.407476 -215.762586)
		(width 0.0889)
		(layer "In4.Cu")
		(net "UPI_CPU1_CPU0_P1P0_DP<15>")
	)
	(segment
		(start 302.492156 -175.504602)
		(end 302.49241 -175.504856)
		(width 0.14732)
		(layer "In4.Cu")
		(net "UPI_CPU1_CPU0_P1P0_DP<15>")
	)
	(segment
		(start 119.81561 -215.761062)
		(end 119.8245 -215.755982)
		(width 0.0889)
		(layer "In4.Cu")
		(net "UPI_CPU1_CPU0_P1P0_DP<15>")
	)
	(segment
		(start 351.395792 -215.755982)
		(end 351.403158 -215.7603)
		(width 0.0889)
		(layer "In4.Cu")
		(net "UPI_CPU1_CPU0_P1P0_DP<15>")
	)
	(segment
		(start 120.003316 -212.066378)
		(end 119.961406 -212.024468)
		(width 0.0889)
		(layer "In4.Cu")
		(net "UPI_CPU1_CPU0_P1P0_DP<15>")
	)
	(segment
		(start 313.216036 -175.703992)
		(end 317.27013 -176.836324)
		(width 0.14732)
		(layer "In4.Cu")
		(net "UPI_CPU1_CPU0_P1P0_DP<15>")
	)
	(segment
		(start 351.404682 -215.112346)
		(end 351.403666 -215.112854)
		(width 0.0889)
		(layer "In4.Cu")
		(net "UPI_CPU1_CPU0_P1P0_DP<15>")
	)
	(segment
		(start 119.961406 -212.00237)
		(end 119.961406 -211.699602)
		(width 0.14732)
		(layer "In4.Cu")
		(net "UPI_CPU1_CPU0_P1P0_DP<15>")
	)
	(segment
		(start 329.4761 -181.111398)
		(end 336.251804 -183.969152)
		(width 0.14732)
		(layer "In4.Cu")
		(net "UPI_CPU1_CPU0_P1P0_DP<15>")
	)
	(segment
		(start 150.792688 -178.388264)
		(end 157.691074 -176.62271)
		(width 0.14732)
		(layer "In4.Cu")
		(net "UPI_CPU1_CPU0_P1P0_DP<15>")
	)
	(segment
		(start 120.003062 -217.072972)
		(end 120.003062 -217.0557)
		(width 0.0889)
		(layer "In4.Cu")
		(net "UPI_CPU1_CPU0_P1P0_DP<15>")
	)
	(segment
		(start 351.407476 -215.762586)
		(end 351.410778 -215.764618)
		(width 0.0889)
		(layer "In4.Cu")
		(net "UPI_CPU1_CPU0_P1P0_DP<15>")
	)
	(segment
		(start 119.961152 -211.699348)
		(end 119.961152 -211.171028)
		(width 0.14732)
		(layer "In4.Cu")
		(net "UPI_CPU1_CPU0_P1P0_DP<15>")
	)
	(segment
		(start 351.217484 -212.733636)
		(end 351.217484 -213.893908)
		(width 0.0889)
		(layer "In4.Cu")
		(net "UPI_CPU1_CPU0_P1P0_DP<15>")
	)
	(segment
		(start 351.403666 -215.112854)
		(end 351.395792 -215.117426)
		(width 0.0889)
		(layer "In4.Cu")
		(net "UPI_CPU1_CPU0_P1P0_DP<15>")
	)
	(segment
		(start 119.961406 -211.699602)
		(end 119.961152 -211.699348)
		(width 0.14732)
		(layer "In4.Cu")
		(net "UPI_CPU1_CPU0_P1P0_DP<15>")
	)
	(segment
		(start 210.943952 -176.382934)
		(end 238.613442 -176.382934)
		(width 0.14732)
		(layer "In4.Cu")
		(net "UPI_CPU1_CPU0_P1P0_DP<15>")
	)
	(segment
		(start 157.691074 -176.62271)
		(end 200.302876 -175.915574)
		(width 0.14732)
		(layer "In4.Cu")
		(net "UPI_CPU1_CPU0_P1P0_DP<15>")
	)
	(segment
		(start 351.357438 -217.356182)
		(end 351.435416 -217.335354)
		(width 0.0889)
		(layer "In4.Cu")
		(net "UPI_CPU1_CPU0_P1P0_DP<15>")
	)
	(segment
		(start 351.686876 -214.424768)
		(end 351.686876 -214.644732)
		(width 0.0889)
		(layer "In4.Cu")
		(net "UPI_CPU1_CPU0_P1P0_DP<15>")
	)
	(segment
		(start 351.59188 -203.674472)
		(end 351.59188 -211.745068)
		(width 0.14732)
		(layer "In4.Cu")
		(net "UPI_CPU1_CPU0_P1P0_DP<15>")
	)
	(segment
		(start 351.54997 -212.485478)
		(end 351.217484 -212.733636)
		(width 0.0889)
		(layer "In4.Cu")
		(net "UPI_CPU1_CPU0_P1P0_DP<15>")
	)
	(segment
		(start 351.435416 -217.335354)
		(end 351.59188 -217.064336)
		(width 0.0889)
		(layer "In4.Cu")
		(net "UPI_CPU1_CPU0_P1P0_DP<15>")
	)
	(segment
		(start 119.961152 -211.171028)
		(end 123.034298 -202.394312)
		(width 0.14732)
		(layer "In4.Cu")
		(net "UPI_CPU1_CPU0_P1P0_DP<15>")
	)
	(segment
		(start 302.480726 -175.504856)
		(end 302.486568 -175.504602)
		(width 0.14732)
		(layer "In4.Cu")
		(net "UPI_CPU1_CPU0_P1P0_DP<15>")
	)
	(segment
		(start 302.486568 -175.504602)
		(end 302.492156 -175.504602)
		(width 0.14732)
		(layer "In4.Cu")
		(net "UPI_CPU1_CPU0_P1P0_DP<15>")
	)
	(segment
		(start 351.592134 -212.054948)
		(end 351.54997 -212.097112)
		(width 0.0889)
		(layer "In4.Cu")
		(net "UPI_CPU1_CPU0_P1P0_DP<15>")
	)
	(segment
		(start 136.520428 -189.325504)
		(end 140.893038 -183.456326)
		(width 0.14732)
		(layer "In4.Cu")
		(net "UPI_CPU1_CPU0_P1P0_DP<15>")
	)
	(segment
		(start 340.650576 -187.997592)
		(end 343.306908 -191.77)
		(width 0.14732)
		(layer "In4.Cu")
		(net "UPI_CPU1_CPU0_P1P0_DP<15>")
	)
	(segment
		(start 238.613442 -176.382934)
		(end 273.124676 -176.218088)
		(width 0.14732)
		(layer "In4.Cu")
		(net "UPI_CPU1_CPU0_P1P0_DP<15>")
	)
	(segment
		(start 119.628412 -218.692222)
		(end 119.784876 -218.421204)
		(width 0.0889)
		(layer "In4.Cu")
		(net "UPI_CPU1_CPU0_P1P0_DP<15>")
	)
	(segment
		(start 343.306908 -191.77)
		(end 349.113602 -197.720458)
		(width 0.14732)
		(layer "In4.Cu")
		(net "UPI_CPU1_CPU0_P1P0_DP<15>")
	)
	(segment
		(start 351.403158 -215.7603)
		(end 351.404682 -215.761062)
		(width 0.0889)
		(layer "In4.Cu")
		(net "UPI_CPU1_CPU0_P1P0_DP<15>")
	)
	(segment
		(start 351.571052 -203.653644)
		(end 351.59188 -203.674472)
		(width 0.14732)
		(layer "In4.Cu")
		(net "UPI_CPU1_CPU0_P1P0_DP<15>")
	)
	(segment
		(start 119.533416 -217.8939)
		(end 119.533416 -217.859864)
		(width 0.0889)
		(layer "In4.Cu")
		(net "UPI_CPU1_CPU0_P1P0_DP<15>")
	)
	(segment
		(start 123.034298 -202.394312)
		(end 130.289554 -193.467736)
		(width 0.14732)
		(layer "In4.Cu")
		(net "UPI_CPU1_CPU0_P1P0_DP<15>")
	)
	(segment
		(start 351.54997 -212.097112)
		(end 351.54997 -212.485478)
		(width 0.0889)
		(layer "In4.Cu")
		(net "UPI_CPU1_CPU0_P1P0_DP<15>")
	)
	(segment
		(start 120.003316 -213.815168)
		(end 120.003316 -212.066378)
		(width 0.0889)
		(layer "In4.Cu")
		(net "UPI_CPU1_CPU0_P1P0_DP<15>")
	)
	(segment
		(start 120.003062 -215.436704)
		(end 120.003062 -215.414606)
		(width 0.0889)
		(layer "In4.Cu")
		(net "UPI_CPU1_CPU0_P1P0_DP<15>")
	)
	(segment
		(start 119.784876 -218.421204)
		(end 119.760746 -218.33205)
		(width 0.0889)
		(layer "In4.Cu")
		(net "UPI_CPU1_CPU0_P1P0_DP<15>")
	)
	(segment
		(start 273.124676 -176.218088)
		(end 302.480726 -175.504856)
		(width 0.14732)
		(layer "In4.Cu")
		(net "UPI_CPU1_CPU0_P1P0_DP<15>")
	)
	(segment
		(start 120.472708 -214.622634)
		(end 120.472708 -214.461344)
		(width 0.0889)
		(layer "In4.Cu")
		(net "UPI_CPU1_CPU0_P1P0_DP<15>")
	)
	(segment
		(start 140.893038 -183.456326)
		(end 150.792688 -178.388264)
		(width 0.14732)
		(layer "In4.Cu")
		(net "UPI_CPU1_CPU0_P1P0_DP<15>")
	)
	(segment
		(start 317.27013 -176.836324)
		(end 329.4761 -181.111398)
		(width 0.14732)
		(layer "In4.Cu")
		(net "UPI_CPU1_CPU0_P1P0_DP<15>")
	)
	(segment
		(start 119.533416 -216.260426)
		(end 119.533416 -216.235026)
		(width 0.0889)
		(layer "In4.Cu")
		(net "UPI_CPU1_CPU0_P1P0_DP<15>")
	)
	(segment
		(start 200.302876 -175.915574)
		(end 210.943952 -176.382934)
		(width 0.14732)
		(layer "In4.Cu")
		(net "UPI_CPU1_CPU0_P1P0_DP<15>")
	)
	(segment
		(start 130.289554 -193.467736)
		(end 136.520428 -189.325504)
		(width 0.14732)
		(layer "In4.Cu")
		(net "UPI_CPU1_CPU0_P1P0_DP<15>")
	)
	(segment
		(start 119.961406 -212.024468)
		(end 119.961406 -212.00237)
		(width 0.0889)
		(layer "In4.Cu")
		(net "UPI_CPU1_CPU0_P1P0_DP<15>")
	)
	(segment
		(start 351.410778 -216.736422)
		(end 351.405444 -216.73947)
		(width 0.0889)
		(layer "In4.Cu")
		(net "UPI_CPU1_CPU0_P1P0_DP<15>")
	)
	(segment
		(start 337.384136 -184.731152)
		(end 340.650576 -187.997592)
		(width 0.14732)
		(layer "In4.Cu")
		(net "UPI_CPU1_CPU0_P1P0_DP<15>")
	)
	(segment
		(start 302.49241 -175.504856)
		(end 313.216036 -175.703992)
		(width 0.14732)
		(layer "In4.Cu")
		(net "UPI_CPU1_CPU0_P1P0_DP<15>")
	)
	(segment
		(start 120.285256 -214.946992)
		(end 120.294146 -214.941912)
		(width 0.0889)
		(layer "In4.Cu")
		(net "UPI_CPU1_CPU0_P1P0_DP<15>")
	)
	(segment
		(start 351.217484 -217.0557)
		(end 351.217484 -217.072972)
		(width 0.0889)
		(layer "In4.Cu")
		(net "UPI_CPU1_CPU0_P1P0_DP<15>")
	)
	(arc
		(start 119.815864 -217.388694)
		(mid 119.950797 -217.25534)
		(end 120.003062 -217.072972)
		(width 0.0889)
		(layer "In4.Cu")
		(net "UPI_CPU1_CPU0_P1P0_DP<15>")
	)
	(arc
		(start 119.533416 -217.859864)
		(mid 119.613578 -217.587675)
		(end 119.815864 -217.388694)
		(width 0.0889)
		(layer "In4.Cu")
		(net "UPI_CPU1_CPU0_P1P0_DP<15>")
	)
	(arc
		(start 120.294146 -214.941912)
		(mid 120.42506 -214.805552)
		(end 120.472708 -214.622634)
		(width 0.0889)
		(layer "In4.Cu")
		(net "UPI_CPU1_CPU0_P1P0_DP<15>")
	)
	(arc
		(start 119.743982 -218.319096)
		(mid 119.5919 -218.129664)
		(end 119.533416 -217.8939)
		(width 0.0889)
		(layer "In4.Cu")
		(net "UPI_CPU1_CPU0_P1P0_DP<15>")
	)
	(arc
		(start 120.288558 -214.261954)
		(mid 120.208019 -214.210764)
		(end 120.136666 -214.1474)
		(width 0.0889)
		(layer "In4.Cu")
		(net "UPI_CPU1_CPU0_P1P0_DP<15>")
	)
	(arc
		(start 351.217484 -217.072972)
		(mid 351.256158 -217.23004)
		(end 351.357438 -217.356182)
		(width 0.0889)
		(layer "In4.Cu")
		(net "UPI_CPU1_CPU0_P1P0_DP<15>")
	)
	(arc
		(start 120.136666 -214.1474)
		(mid 120.037862 -213.994188)
		(end 120.003316 -213.815168)
		(width 0.0889)
		(layer "In4.Cu")
		(net "UPI_CPU1_CPU0_P1P0_DP<15>")
	)
	(arc
		(start 120.003062 -215.414606)
		(mid 120.083973 -215.144478)
		(end 120.285256 -214.946992)
		(width 0.0889)
		(layer "In4.Cu")
		(net "UPI_CPU1_CPU0_P1P0_DP<15>")
	)
	(arc
		(start 351.395792 -215.117426)
		(mid 351.268538 -215.247392)
		(end 351.217484 -215.421972)
		(width 0.0889)
		(layer "In4.Cu")
		(net "UPI_CPU1_CPU0_P1P0_DP<15>")
	)
	(arc
		(start 120.003062 -217.0557)
		(mid 119.950792 -216.873335)
		(end 119.815864 -216.739978)
		(width 0.0889)
		(layer "In4.Cu")
		(net "UPI_CPU1_CPU0_P1P0_DP<15>")
	)
	(arc
		(start 351.410778 -215.764618)
		(mid 351.687352 -216.25052)
		(end 351.410778 -216.736422)
		(width 0.0889)
		(layer "In4.Cu")
		(net "UPI_CPU1_CPU0_P1P0_DP<15>")
	)
	(arc
		(start 119.760746 -218.33205)
		(mid 119.752305 -218.32565)
		(end 119.743982 -218.319096)
		(width 0.0889)
		(layer "In4.Cu")
		(net "UPI_CPU1_CPU0_P1P0_DP<15>")
	)
	(arc
		(start 351.217484 -215.421972)
		(mid 351.217287 -215.429337)
		(end 351.21723 -215.436704)
		(width 0.0889)
		(layer "In4.Cu")
		(net "UPI_CPU1_CPU0_P1P0_DP<15>")
	)
	(arc
		(start 120.472708 -214.461344)
		(mid 120.397703 -214.345885)
		(end 120.288558 -214.261954)
		(width 0.0889)
		(layer "In4.Cu")
		(net "UPI_CPU1_CPU0_P1P0_DP<15>")
	)
	(arc
		(start 351.686876 -214.644732)
		(mid 351.605965 -214.91486)
		(end 351.404682 -215.112346)
		(width 0.0889)
		(layer "In4.Cu")
		(net "UPI_CPU1_CPU0_P1P0_DP<15>")
	)
	(arc
		(start 351.21723 -215.436704)
		(mid 351.264909 -215.619604)
		(end 351.395792 -215.755982)
		(width 0.0889)
		(layer "In4.Cu")
		(net "UPI_CPU1_CPU0_P1P0_DP<15>")
	)
	(arc
		(start 351.401634 -214.093298)
		(mid 351.575597 -214.232062)
		(end 351.686876 -214.424768)
		(width 0.0889)
		(layer "In4.Cu")
		(net "UPI_CPU1_CPU0_P1P0_DP<15>")
	)
	(arc
		(start 119.815864 -216.739978)
		(mid 119.611529 -216.537373)
		(end 119.533416 -216.260426)
		(width 0.0889)
		(layer "In4.Cu")
		(net "UPI_CPU1_CPU0_P1P0_DP<15>")
	)
	(arc
		(start 119.533416 -216.235026)
		(mid 119.612786 -215.961292)
		(end 119.81561 -215.761062)
		(width 0.0889)
		(layer "In4.Cu")
		(net "UPI_CPU1_CPU0_P1P0_DP<15>")
	)
	(arc
		(start 351.217484 -213.893908)
		(mid 351.292489 -214.009367)
		(end 351.401634 -214.093298)
		(width 0.0889)
		(layer "In4.Cu")
		(net "UPI_CPU1_CPU0_P1P0_DP<15>")
	)
	(arc
		(start 119.8245 -215.755982)
		(mid 119.955414 -215.619622)
		(end 120.003062 -215.436704)
		(width 0.0889)
		(layer "In4.Cu")
		(net "UPI_CPU1_CPU0_P1P0_DP<15>")
	)
	(arc
		(start 351.404682 -216.739978)
		(mid 351.269749 -216.873332)
		(end 351.217484 -217.0557)
		(width 0.0889)
		(layer "In4.Cu")
		(net "UPI_CPU1_CPU0_P1P0_DP<15>")
	)
	(segment
		(start 350.18218 -218.414346)
		(end 350.18218 -217.87866)
		(width 0.13208)
		(layer "F.Cu")
		(net "UPI_CPU1_CPU0_P1P0_DP<14>")
	)
	(segment
		(start 350.18218 -217.87866)
		(end 350.182434 -217.878406)
		(width 0.13208)
		(layer "F.Cu")
		(net "UPI_CPU1_CPU0_P1P0_DP<14>")
	)
	(segment
		(start 121.038112 -218.414346)
		(end 121.038112 -217.87866)
		(width 0.13208)
		(layer "F.Cu")
		(net "UPI_CPU1_CPU0_P1P0_DP<14>")
	)
	(segment
		(start 121.038112 -217.87866)
		(end 121.038366 -217.878406)
		(width 0.13208)
		(layer "F.Cu")
		(net "UPI_CPU1_CPU0_P1P0_DP<14>")
	)
	(segment
		(start 316.831472 -177.86985)
		(end 329.178412 -182.191152)
		(width 0.14732)
		(layer "In4.Cu")
		(net "UPI_CPU1_CPU0_P1P0_DP<14>")
	)
	(segment
		(start 350.369632 -217.554048)
		(end 350.370394 -217.554556)
		(width 0.0889)
		(layer "In4.Cu")
		(net "UPI_CPU1_CPU0_P1P0_DP<14>")
	)
	(segment
		(start 123.178316 -205.707996)
		(end 123.333764 -205.63332)
		(width 0.14732)
		(layer "In4.Cu")
		(net "UPI_CPU1_CPU0_P1P0_DP<14>")
	)
	(segment
		(start 154.552396 -178.599338)
		(end 157.912562 -177.739294)
		(width 0.14732)
		(layer "In4.Cu")
		(net "UPI_CPU1_CPU0_P1P0_DP<14>")
	)
	(segment
		(start 122.964448 -206.688182)
		(end 123.108974 -206.275432)
		(width 0.14732)
		(layer "In4.Cu")
		(net "UPI_CPU1_CPU0_P1P0_DP<14>")
	)
	(segment
		(start 350.556576 -214.461344)
		(end 350.556576 -214.622634)
		(width 0.0889)
		(layer "In4.Cu")
		(net "UPI_CPU1_CPU0_P1P0_DP<14>")
	)
	(segment
		(start 154.552142 -178.599338)
		(end 154.552396 -178.599338)
		(width 0.14732)
		(layer "In4.Cu")
		(net "UPI_CPU1_CPU0_P1P0_DP<14>")
	)
	(segment
		(start 121.133616 -212.066632)
		(end 121.17578 -212.024468)
		(width 0.0889)
		(layer "In4.Cu")
		(net "UPI_CPU1_CPU0_P1P0_DP<14>")
	)
	(segment
		(start 151.192484 -179.459128)
		(end 154.552142 -178.599338)
		(width 0.14732)
		(layer "In4.Cu")
		(net "UPI_CPU1_CPU0_P1P0_DP<14>")
	)
	(segment
		(start 238.61649 -177.50663)
		(end 273.141186 -177.341784)
		(width 0.14732)
		(layer "In4.Cu")
		(net "UPI_CPU1_CPU0_P1P0_DP<14>")
	)
	(segment
		(start 123.916948 -203.597764)
		(end 123.916694 -203.597764)
		(width 0.14732)
		(layer "In4.Cu")
		(net "UPI_CPU1_CPU0_P1P0_DP<14>")
	)
	(segment
		(start 350.087184 -212.40115)
		(end 350.087184 -212.554058)
		(width 0.0889)
		(layer "In4.Cu")
		(net "UPI_CPU1_CPU0_P1P0_DP<14>")
	)
	(segment
		(start 146.408902 -181.908196)
		(end 146.408648 -181.908196)
		(width 0.14732)
		(layer "In4.Cu")
		(net "UPI_CPU1_CPU0_P1P0_DP<14>")
	)
	(segment
		(start 350.087184 -212.927438)
		(end 350.087184 -213.102698)
		(width 0.0889)
		(layer "In4.Cu")
		(net "UPI_CPU1_CPU0_P1P0_DP<14>")
	)
	(segment
		(start 121.17578 -212.00237)
		(end 121.17578 -211.699602)
		(width 0.14732)
		(layer "In4.Cu")
		(net "UPI_CPU1_CPU0_P1P0_DP<14>")
	)
	(segment
		(start 350.087184 -213.476078)
		(end 350.087184 -213.930484)
		(width 0.0889)
		(layer "In4.Cu")
		(net "UPI_CPU1_CPU0_P1P0_DP<14>")
	)
	(segment
		(start 120.842278 -215.931242)
		(end 120.851168 -215.926162)
		(width 0.0889)
		(layer "In4.Cu")
		(net "UPI_CPU1_CPU0_P1P0_DP<14>")
	)
	(segment
		(start 121.8565 -209.852768)
		(end 122.000772 -209.440018)
		(width 0.14732)
		(layer "In4.Cu")
		(net "UPI_CPU1_CPU0_P1P0_DP<14>")
	)
	(segment
		(start 336.694018 -185.60542)
		(end 339.812122 -188.723524)
		(width 0.14732)
		(layer "In4.Cu")
		(net "UPI_CPU1_CPU0_P1P0_DP<14>")
	)
	(segment
		(start 141.624558 -184.357264)
		(end 146.408902 -181.908196)
		(width 0.14732)
		(layer "In4.Cu")
		(net "UPI_CPU1_CPU0_P1P0_DP<14>")
	)
	(segment
		(start 335.7753 -184.98566)
		(end 336.694018 -185.60542)
		(width 0.14732)
		(layer "In4.Cu")
		(net "UPI_CPU1_CPU0_P1P0_DP<14>")
	)
	(segment
		(start 121.311924 -215.117426)
		(end 121.320814 -215.112346)
		(width 0.0889)
		(layer "In4.Cu")
		(net "UPI_CPU1_CPU0_P1P0_DP<14>")
	)
	(segment
		(start 121.175526 -211.427822)
		(end 121.331482 -210.982306)
		(width 0.14732)
		(layer "In4.Cu")
		(net "UPI_CPU1_CPU0_P1P0_DP<14>")
	)
	(segment
		(start 121.48693 -210.90763)
		(end 121.631202 -210.49488)
		(width 0.14732)
		(layer "In4.Cu")
		(net "UPI_CPU1_CPU0_P1P0_DP<14>")
	)
	(segment
		(start 124.216668 -203.110338)
		(end 124.141738 -202.955144)
		(width 0.14732)
		(layer "In4.Cu")
		(net "UPI_CPU1_CPU0_P1P0_DP<14>")
	)
	(segment
		(start 122.595132 -207.743044)
		(end 122.739658 -207.330294)
		(width 0.14732)
		(layer "In4.Cu")
		(net "UPI_CPU1_CPU0_P1P0_DP<14>")
	)
	(segment
		(start 121.133362 -215.452198)
		(end 121.133362 -215.436704)
		(width 0.0889)
		(layer "In4.Cu")
		(net "UPI_CPU1_CPU0_P1P0_DP<14>")
	)
	(segment
		(start 350.36887 -215.925654)
		(end 350.369632 -215.926162)
		(width 0.0889)
		(layer "In4.Cu")
		(net "UPI_CPU1_CPU0_P1P0_DP<14>")
	)
	(segment
		(start 350.371156 -215.926924)
		(end 350.378522 -215.931242)
		(width 0.0889)
		(layer "In4.Cu")
		(net "UPI_CPU1_CPU0_P1P0_DP<14>")
	)
	(segment
		(start 121.331228 -210.982306)
		(end 121.48693 -210.90763)
		(width 0.14732)
		(layer "In4.Cu")
		(net "UPI_CPU1_CPU0_P1P0_DP<14>")
	)
	(segment
		(start 349.988124 -213.201758)
		(end 349.988124 -213.377018)
		(width 0.0889)
		(layer "In4.Cu")
		(net "UPI_CPU1_CPU0_P1P0_DP<14>")
	)
	(segment
		(start 123.333764 -205.63332)
		(end 123.47829 -205.22057)
		(width 0.14732)
		(layer "In4.Cu")
		(net "UPI_CPU1_CPU0_P1P0_DP<14>")
	)
	(segment
		(start 339.812122 -188.723524)
		(end 342.492838 -192.530476)
		(width 0.14732)
		(layer "In4.Cu")
		(net "UPI_CPU1_CPU0_P1P0_DP<14>")
	)
	(segment
		(start 122.370342 -208.385156)
		(end 122.295412 -208.229962)
		(width 0.14732)
		(layer "In4.Cu")
		(net "UPI_CPU1_CPU0_P1P0_DP<14>")
	)
	(segment
		(start 122.000772 -209.440018)
		(end 121.926096 -209.284824)
		(width 0.14732)
		(layer "In4.Cu")
		(net "UPI_CPU1_CPU0_P1P0_DP<14>")
	)
	(segment
		(start 350.365822 -216.577164)
		(end 350.362012 -216.579196)
		(width 0.0889)
		(layer "In4.Cu")
		(net "UPI_CPU1_CPU0_P1P0_DP<14>")
	)
	(segment
		(start 137.29843 -190.164974)
		(end 141.624558 -184.357264)
		(width 0.14732)
		(layer "In4.Cu")
		(net "UPI_CPU1_CPU0_P1P0_DP<14>")
	)
	(segment
		(start 121.17578 -211.699602)
		(end 121.175526 -211.699348)
		(width 0.14732)
		(layer "In4.Cu")
		(net "UPI_CPU1_CPU0_P1P0_DP<14>")
	)
	(segment
		(start 350.41713 -218.170252)
		(end 350.338898 -218.149424)
		(width 0.0889)
		(layer "In4.Cu")
		(net "UPI_CPU1_CPU0_P1P0_DP<14>")
	)
	(segment
		(start 121.603008 -214.644732)
		(end 121.603008 -214.424768)
		(width 0.0889)
		(layer "In4.Cu")
		(net "UPI_CPU1_CPU0_P1P0_DP<14>")
	)
	(segment
		(start 157.912562 -177.739294)
		(end 200.52792 -177.031904)
		(width 0.14732)
		(layer "In4.Cu")
		(net "UPI_CPU1_CPU0_P1P0_DP<14>")
	)
	(segment
		(start 350.363536 -215.922606)
		(end 350.36887 -215.925654)
		(width 0.0889)
		(layer "In4.Cu")
		(net "UPI_CPU1_CPU0_P1P0_DP<14>")
	)
	(segment
		(start 350.47682 -211.635848)
		(end 350.51873 -211.677758)
		(width 0.0889)
		(layer "In4.Cu")
		(net "UPI_CPU1_CPU0_P1P0_DP<14>")
	)
	(segment
		(start 350.362012 -216.579196)
		(end 350.35744 -216.58199)
		(width 0.0889)
		(layer "In4.Cu")
		(net "UPI_CPU1_CPU0_P1P0_DP<14>")
	)
	(segment
		(start 349.988124 -213.377018)
		(end 350.087184 -213.476078)
		(width 0.0889)
		(layer "In4.Cu")
		(net "UPI_CPU1_CPU0_P1P0_DP<14>")
	)
	(segment
		(start 123.70308 -204.578458)
		(end 123.847606 -204.165708)
		(width 0.14732)
		(layer "In4.Cu")
		(net "UPI_CPU1_CPU0_P1P0_DP<14>")
	)
	(segment
		(start 350.378014 -214.941912)
		(end 350.369124 -214.946992)
		(width 0.0889)
		(layer "In4.Cu")
		(net "UPI_CPU1_CPU0_P1P0_DP<14>")
	)
	(segment
		(start 146.408648 -181.908196)
		(end 151.192484 -179.459128)
		(width 0.14732)
		(layer "In4.Cu")
		(net "UPI_CPU1_CPU0_P1P0_DP<14>")
	)
	(segment
		(start 121.17578 -212.024468)
		(end 121.17578 -212.00237)
		(width 0.0889)
		(layer "In4.Cu")
		(net "UPI_CPU1_CPU0_P1P0_DP<14>")
	)
	(segment
		(start 124.072142 -203.523088)
		(end 124.216668 -203.110338)
		(width 0.14732)
		(layer "In4.Cu")
		(net "UPI_CPU1_CPU0_P1P0_DP<14>")
	)
	(segment
		(start 123.916694 -203.597764)
		(end 124.072142 -203.523088)
		(width 0.14732)
		(layer "In4.Cu")
		(net "UPI_CPU1_CPU0_P1P0_DP<14>")
	)
	(segment
		(start 121.175526 -211.699348)
		(end 121.175526 -211.427822)
		(width 0.14732)
		(layer "In4.Cu")
		(net "UPI_CPU1_CPU0_P1P0_DP<14>")
	)
	(segment
		(start 124.141992 -202.955144)
		(end 124.243084 -202.665838)
		(width 0.14732)
		(layer "In4.Cu")
		(net "UPI_CPU1_CPU0_P1P0_DP<14>")
	)
	(segment
		(start 123.772676 -204.010006)
		(end 123.916948 -203.597764)
		(width 0.14732)
		(layer "In4.Cu")
		(net "UPI_CPU1_CPU0_P1P0_DP<14>")
	)
	(segment
		(start 350.47682 -203.922884)
		(end 350.47682 -211.61375)
		(width 0.14732)
		(layer "In4.Cu")
		(net "UPI_CPU1_CPU0_P1P0_DP<14>")
	)
	(segment
		(start 329.178412 -182.191152)
		(end 335.7753 -184.98566)
		(width 0.14732)
		(layer "In4.Cu")
		(net "UPI_CPU1_CPU0_P1P0_DP<14>")
	)
	(segment
		(start 350.087184 -212.554058)
		(end 349.988124 -212.653118)
		(width 0.0889)
		(layer "In4.Cu")
		(net "UPI_CPU1_CPU0_P1P0_DP<14>")
	)
	(segment
		(start 350.378522 -216.569798)
		(end 350.369632 -216.574878)
		(width 0.0889)
		(layer "In4.Cu")
		(net "UPI_CPU1_CPU0_P1P0_DP<14>")
	)
	(segment
		(start 123.034044 -206.120238)
		(end 123.178316 -205.707996)
		(width 0.14732)
		(layer "In4.Cu")
		(net "UPI_CPU1_CPU0_P1P0_DP<14>")
	)
	(segment
		(start 342.492838 -192.530476)
		(end 348.164912 -198.34225)
		(width 0.14732)
		(layer "In4.Cu")
		(net "UPI_CPU1_CPU0_P1P0_DP<14>")
	)
	(segment
		(start 120.851168 -216.574878)
		(end 120.842278 -216.569798)
		(width 0.0889)
		(layer "In4.Cu")
		(net "UPI_CPU1_CPU0_P1P0_DP<14>")
	)
	(segment
		(start 350.087184 -213.102698)
		(end 349.988124 -213.201758)
		(width 0.0889)
		(layer "In4.Cu")
		(net "UPI_CPU1_CPU0_P1P0_DP<14>")
	)
	(segment
		(start 121.556526 -210.339686)
		(end 121.700798 -209.927444)
		(width 0.14732)
		(layer "In4.Cu")
		(net "UPI_CPU1_CPU0_P1P0_DP<14>")
	)
	(segment
		(start 313.0931 -176.82591)
		(end 316.831472 -177.86985)
		(width 0.14732)
		(layer "In4.Cu")
		(net "UPI_CPU1_CPU0_P1P0_DP<14>")
	)
	(segment
		(start 120.857264 -216.578434)
		(end 120.851168 -216.574878)
		(width 0.0889)
		(layer "In4.Cu")
		(net "UPI_CPU1_CPU0_P1P0_DP<14>")
	)
	(segment
		(start 123.547632 -204.653134)
		(end 123.70308 -204.578458)
		(width 0.14732)
		(layer "In4.Cu")
		(net "UPI_CPU1_CPU0_P1P0_DP<14>")
	)
	(segment
		(start 122.739658 -207.330294)
		(end 122.664728 -207.1751)
		(width 0.14732)
		(layer "In4.Cu")
		(net "UPI_CPU1_CPU0_P1P0_DP<14>")
	)
	(segment
		(start 121.700798 -209.927444)
		(end 121.8565 -209.852768)
		(width 0.14732)
		(layer "In4.Cu")
		(net "UPI_CPU1_CPU0_P1P0_DP<14>")
	)
	(segment
		(start 124.243084 -202.665838)
		(end 131.002024 -194.34937)
		(width 0.14732)
		(layer "In4.Cu")
		(net "UPI_CPU1_CPU0_P1P0_DP<14>")
	)
	(segment
		(start 123.847606 -204.165708)
		(end 123.772422 -204.010006)
		(width 0.14732)
		(layer "In4.Cu")
		(net "UPI_CPU1_CPU0_P1P0_DP<14>")
	)
	(segment
		(start 121.331482 -210.982306)
		(end 121.331228 -210.982306)
		(width 0.14732)
		(layer "In4.Cu")
		(net "UPI_CPU1_CPU0_P1P0_DP<14>")
	)
	(segment
		(start 350.51873 -211.677758)
		(end 350.51873 -212.020912)
		(width 0.0889)
		(layer "In4.Cu")
		(net "UPI_CPU1_CPU0_P1P0_DP<14>")
	)
	(segment
		(start 122.809 -206.762858)
		(end 122.964448 -206.688182)
		(width 0.14732)
		(layer "In4.Cu")
		(net "UPI_CPU1_CPU0_P1P0_DP<14>")
	)
	(segment
		(start 123.47829 -205.22057)
		(end 123.40336 -205.065376)
		(width 0.14732)
		(layer "In4.Cu")
		(net "UPI_CPU1_CPU0_P1P0_DP<14>")
	)
	(segment
		(start 350.47682 -211.61375)
		(end 350.47682 -211.635848)
		(width 0.0889)
		(layer "In4.Cu")
		(net "UPI_CPU1_CPU0_P1P0_DP<14>")
	)
	(segment
		(start 350.51873 -212.020912)
		(end 350.087184 -212.40115)
		(width 0.0889)
		(layer "In4.Cu")
		(net "UPI_CPU1_CPU0_P1P0_DP<14>")
	)
	(segment
		(start 122.664728 -207.1751)
		(end 122.809 -206.762858)
		(width 0.14732)
		(layer "In4.Cu")
		(net "UPI_CPU1_CPU0_P1P0_DP<14>")
	)
	(segment
		(start 122.295412 -208.229962)
		(end 122.439684 -207.81772)
		(width 0.14732)
		(layer "In4.Cu")
		(net "UPI_CPU1_CPU0_P1P0_DP<14>")
	)
	(segment
		(start 349.988124 -212.828378)
		(end 350.087184 -212.927438)
		(width 0.0889)
		(layer "In4.Cu")
		(net "UPI_CPU1_CPU0_P1P0_DP<14>")
	)
	(segment
		(start 211.33943 -177.50663)
		(end 238.61649 -177.50663)
		(width 0.14732)
		(layer "In4.Cu")
		(net "UPI_CPU1_CPU0_P1P0_DP<14>")
	)
	(segment
		(start 124.141738 -202.955144)
		(end 124.141992 -202.955144)
		(width 0.14732)
		(layer "In4.Cu")
		(net "UPI_CPU1_CPU0_P1P0_DP<14>")
	)
	(segment
		(start 121.038366 -217.878406)
		(end 120.881902 -217.607388)
		(width 0.0889)
		(layer "In4.Cu")
		(net "UPI_CPU1_CPU0_P1P0_DP<14>")
	)
	(segment
		(start 273.141186 -177.341784)
		(end 302.489616 -176.62906)
		(width 0.14732)
		(layer "In4.Cu")
		(net "UPI_CPU1_CPU0_P1P0_DP<14>")
	)
	(segment
		(start 121.133616 -217.07856)
		(end 121.133616 -217.064336)
		(width 0.0889)
		(layer "In4.Cu")
		(net "UPI_CPU1_CPU0_P1P0_DP<14>")
	)
	(segment
		(start 350.369632 -216.574878)
		(end 350.365822 -216.577164)
		(width 0.0889)
		(layer "In4.Cu")
		(net "UPI_CPU1_CPU0_P1P0_DP<14>")
	)
	(segment
		(start 350.08693 -217.064336)
		(end 350.08693 -217.071956)
		(width 0.0889)
		(layer "In4.Cu")
		(net "UPI_CPU1_CPU0_P1P0_DP<14>")
	)
	(segment
		(start 122.070368 -208.872582)
		(end 122.225816 -208.797906)
		(width 0.14732)
		(layer "In4.Cu")
		(net "UPI_CPU1_CPU0_P1P0_DP<14>")
	)
	(segment
		(start 302.489616 -176.62906)
		(end 313.0931 -176.82591)
		(width 0.14732)
		(layer "In4.Cu")
		(net "UPI_CPU1_CPU0_P1P0_DP<14>")
	)
	(segment
		(start 121.926096 -209.284824)
		(end 122.070368 -208.872582)
		(width 0.14732)
		(layer "In4.Cu")
		(net "UPI_CPU1_CPU0_P1P0_DP<14>")
	)
	(segment
		(start 350.370394 -217.554556)
		(end 350.378522 -217.559128)
		(width 0.0889)
		(layer "In4.Cu")
		(net "UPI_CPU1_CPU0_P1P0_DP<14>")
	)
	(segment
		(start 121.133616 -213.893908)
		(end 121.133616 -212.066632)
		(width 0.0889)
		(layer "In4.Cu")
		(net "UPI_CPU1_CPU0_P1P0_DP<14>")
	)
	(segment
		(start 122.439684 -207.81772)
		(end 122.595132 -207.743044)
		(width 0.14732)
		(layer "In4.Cu")
		(net "UPI_CPU1_CPU0_P1P0_DP<14>")
	)
	(segment
		(start 349.988124 -212.653118)
		(end 349.988124 -212.828378)
		(width 0.0889)
		(layer "In4.Cu")
		(net "UPI_CPU1_CPU0_P1P0_DP<14>")
	)
	(segment
		(start 131.002024 -194.34937)
		(end 137.29843 -190.164974)
		(width 0.14732)
		(layer "In4.Cu")
		(net "UPI_CPU1_CPU0_P1P0_DP<14>")
	)
	(segment
		(start 350.08693 -215.414606)
		(end 350.08693 -215.436704)
		(width 0.0889)
		(layer "In4.Cu")
		(net "UPI_CPU1_CPU0_P1P0_DP<14>")
	)
	(segment
		(start 121.631202 -210.49488)
		(end 121.556526 -210.339686)
		(width 0.14732)
		(layer "In4.Cu")
		(net "UPI_CPU1_CPU0_P1P0_DP<14>")
	)
	(segment
		(start 123.108974 -206.275432)
		(end 123.034044 -206.120238)
		(width 0.14732)
		(layer "In4.Cu")
		(net "UPI_CPU1_CPU0_P1P0_DP<14>")
	)
	(segment
		(start 350.338898 -218.149424)
		(end 350.182434 -217.878406)
		(width 0.0889)
		(layer "In4.Cu")
		(net "UPI_CPU1_CPU0_P1P0_DP<14>")
	)
	(segment
		(start 123.40336 -205.065376)
		(end 123.547632 -204.653134)
		(width 0.14732)
		(layer "In4.Cu")
		(net "UPI_CPU1_CPU0_P1P0_DP<14>")
	)
	(segment
		(start 348.164912 -198.34225)
		(end 350.47682 -203.922884)
		(width 0.14732)
		(layer "In4.Cu")
		(net "UPI_CPU1_CPU0_P1P0_DP<14>")
	)
	(segment
		(start 200.52792 -177.031904)
		(end 211.33943 -177.50663)
		(width 0.14732)
		(layer "In4.Cu")
		(net "UPI_CPU1_CPU0_P1P0_DP<14>")
	)
	(segment
		(start 120.881902 -217.607388)
		(end 120.906032 -217.518234)
		(width 0.0889)
		(layer "In4.Cu")
		(net "UPI_CPU1_CPU0_P1P0_DP<14>")
	)
	(segment
		(start 123.772422 -204.010006)
		(end 123.772676 -204.010006)
		(width 0.14732)
		(layer "In4.Cu")
		(net "UPI_CPU1_CPU0_P1P0_DP<14>")
	)
	(segment
		(start 122.225816 -208.797906)
		(end 122.370342 -208.385156)
		(width 0.14732)
		(layer "In4.Cu")
		(net "UPI_CPU1_CPU0_P1P0_DP<14>")
	)
	(segment
		(start 350.369632 -215.926162)
		(end 350.371156 -215.926924)
		(width 0.0889)
		(layer "In4.Cu")
		(net "UPI_CPU1_CPU0_P1P0_DP<14>")
	)
	(arc
		(start 350.08693 -217.071956)
		(mid 350.164559 -217.350369)
		(end 350.369632 -217.554048)
		(width 0.0889)
		(layer "In4.Cu")
		(net "UPI_CPU1_CPU0_P1P0_DP<14>")
	)
	(arc
		(start 121.133616 -217.064336)
		(mid 121.0597 -216.784834)
		(end 120.857264 -216.578434)
		(width 0.0889)
		(layer "In4.Cu")
		(net "UPI_CPU1_CPU0_P1P0_DP<14>")
	)
	(arc
		(start 121.603008 -214.424768)
		(mid 121.491729 -214.232062)
		(end 121.317766 -214.093298)
		(width 0.0889)
		(layer "In4.Cu")
		(net "UPI_CPU1_CPU0_P1P0_DP<14>")
	)
	(arc
		(start 121.133362 -215.436704)
		(mid 121.133414 -215.429337)
		(end 121.133616 -215.421972)
		(width 0.0889)
		(layer "In4.Cu")
		(net "UPI_CPU1_CPU0_P1P0_DP<14>")
	)
	(arc
		(start 120.842278 -216.569798)
		(mid 120.663802 -216.25052)
		(end 120.842278 -215.931242)
		(width 0.0889)
		(layer "In4.Cu")
		(net "UPI_CPU1_CPU0_P1P0_DP<14>")
	)
	(arc
		(start 350.378522 -217.559128)
		(mid 350.509436 -217.695488)
		(end 350.557084 -217.878406)
		(width 0.0889)
		(layer "In4.Cu")
		(net "UPI_CPU1_CPU0_P1P0_DP<14>")
	)
	(arc
		(start 121.320814 -215.112346)
		(mid 121.522096 -214.914859)
		(end 121.603008 -214.644732)
		(width 0.0889)
		(layer "In4.Cu")
		(net "UPI_CPU1_CPU0_P1P0_DP<14>")
	)
	(arc
		(start 350.557084 -217.878406)
		(mid 350.520224 -218.040203)
		(end 350.41713 -218.170252)
		(width 0.0889)
		(layer "In4.Cu")
		(net "UPI_CPU1_CPU0_P1P0_DP<14>")
	)
	(arc
		(start 120.851168 -215.926162)
		(mid 121.053991 -215.725931)
		(end 121.133362 -215.452198)
		(width 0.0889)
		(layer "In4.Cu")
		(net "UPI_CPU1_CPU0_P1P0_DP<14>")
	)
	(arc
		(start 350.369124 -214.946992)
		(mid 350.167842 -215.144479)
		(end 350.08693 -215.414606)
		(width 0.0889)
		(layer "In4.Cu")
		(net "UPI_CPU1_CPU0_P1P0_DP<14>")
	)
	(arc
		(start 350.35744 -216.58199)
		(mid 350.159212 -216.787838)
		(end 350.08693 -217.064336)
		(width 0.0889)
		(layer "In4.Cu")
		(net "UPI_CPU1_CPU0_P1P0_DP<14>")
	)
	(arc
		(start 121.133616 -215.421972)
		(mid 121.18467 -215.247392)
		(end 121.311924 -215.117426)
		(width 0.0889)
		(layer "In4.Cu")
		(net "UPI_CPU1_CPU0_P1P0_DP<14>")
	)
	(arc
		(start 120.906032 -217.518234)
		(mid 120.914475 -217.511836)
		(end 120.922796 -217.50528)
		(width 0.0889)
		(layer "In4.Cu")
		(net "UPI_CPU1_CPU0_P1P0_DP<14>")
	)
	(arc
		(start 120.922796 -217.50528)
		(mid 121.075303 -217.315182)
		(end 121.133616 -217.07856)
		(width 0.0889)
		(layer "In4.Cu")
		(net "UPI_CPU1_CPU0_P1P0_DP<14>")
	)
	(arc
		(start 350.102424 -213.969346)
		(mid 350.212418 -214.138715)
		(end 350.372426 -214.261954)
		(width 0.0889)
		(layer "In4.Cu")
		(net "UPI_CPU1_CPU0_P1P0_DP<14>")
	)
	(arc
		(start 350.378522 -215.931242)
		(mid 350.557119 -216.25052)
		(end 350.378522 -216.569798)
		(width 0.0889)
		(layer "In4.Cu")
		(net "UPI_CPU1_CPU0_P1P0_DP<14>")
	)
	(arc
		(start 121.317766 -214.093298)
		(mid 121.208619 -214.00937)
		(end 121.133616 -213.893908)
		(width 0.0889)
		(layer "In4.Cu")
		(net "UPI_CPU1_CPU0_P1P0_DP<14>")
	)
	(arc
		(start 350.372426 -214.261954)
		(mid 350.481573 -214.345882)
		(end 350.556576 -214.461344)
		(width 0.0889)
		(layer "In4.Cu")
		(net "UPI_CPU1_CPU0_P1P0_DP<14>")
	)
	(arc
		(start 350.08693 -215.436704)
		(mid 350.160921 -215.71627)
		(end 350.363536 -215.922606)
		(width 0.0889)
		(layer "In4.Cu")
		(net "UPI_CPU1_CPU0_P1P0_DP<14>")
	)
	(arc
		(start 350.556576 -214.622634)
		(mid 350.508897 -214.805534)
		(end 350.378014 -214.941912)
		(width 0.0889)
		(layer "In4.Cu")
		(net "UPI_CPU1_CPU0_P1P0_DP<14>")
	)
	(arc
		(start 350.087184 -213.930484)
		(mid 350.094469 -213.950046)
		(end 350.102424 -213.969346)
		(width 0.0889)
		(layer "In4.Cu")
		(net "UPI_CPU1_CPU0_P1P0_DP<14>")
	)
	(segment
		(start 349.712534 -217.06459)
		(end 349.71228 -217.064336)
		(width 0.13208)
		(layer "F.Cu")
		(net "UPI_CPU1_CPU0_P1P0_DP<13>")
	)
	(segment
		(start 121.508266 -219.228162)
		(end 121.508266 -218.692476)
		(width 0.13208)
		(layer "F.Cu")
		(net "UPI_CPU1_CPU0_P1P0_DP<13>")
	)
	(segment
		(start 121.508266 -218.692476)
		(end 121.508012 -218.692222)
		(width 0.13208)
		(layer "F.Cu")
		(net "UPI_CPU1_CPU0_P1P0_DP<13>")
	)
	(segment
		(start 349.712534 -217.600276)
		(end 349.712534 -217.06459)
		(width 0.13208)
		(layer "F.Cu")
		(net "UPI_CPU1_CPU0_P1P0_DP<13>")
	)
	(segment
		(start 349.337884 -212.947758)
		(end 349.337884 -213.123018)
		(width 0.0889)
		(layer "In4.Cu")
		(net "UPI_CPU1_CPU0_P1P0_DP<13>")
	)
	(segment
		(start 121.508012 -218.692222)
		(end 121.664476 -218.421204)
		(width 0.0889)
		(layer "In4.Cu")
		(net "UPI_CPU1_CPU0_P1P0_DP<13>")
	)
	(segment
		(start 349.380048 -212.03793)
		(end 349.380048 -212.060028)
		(width 0.0889)
		(layer "In4.Cu")
		(net "UPI_CPU1_CPU0_P1P0_DP<13>")
	)
	(segment
		(start 349.380048 -212.060028)
		(end 349.337884 -212.102192)
		(width 0.0889)
		(layer "In4.Cu")
		(net "UPI_CPU1_CPU0_P1P0_DP<13>")
	)
	(segment
		(start 121.882662 -215.436704)
		(end 121.882662 -215.414606)
		(width 0.0889)
		(layer "In4.Cu")
		(net "UPI_CPU1_CPU0_P1P0_DP<13>")
	)
	(segment
		(start 211.885276 -178.089052)
		(end 238.618014 -178.089052)
		(width 0.14732)
		(layer "In4.Cu")
		(net "UPI_CPU1_CPU0_P1P0_DP<13>")
	)
	(segment
		(start 124.963682 -202.663806)
		(end 131.371086 -194.780916)
		(width 0.14732)
		(layer "In4.Cu")
		(net "UPI_CPU1_CPU0_P1P0_DP<13>")
	)
	(segment
		(start 349.9104 -211.331556)
		(end 349.380048 -211.861908)
		(width 0.14732)
		(layer "In4.Cu")
		(net "UPI_CPU1_CPU0_P1P0_DP<13>")
	)
	(segment
		(start 349.477838 -217.356182)
		(end 349.555816 -217.335354)
		(width 0.0889)
		(layer "In4.Cu")
		(net "UPI_CPU1_CPU0_P1P0_DP<13>")
	)
	(segment
		(start 122.168158 -214.261954)
		(end 121.882916 -213.976712)
		(width 0.0889)
		(layer "In4.Cu")
		(net "UPI_CPU1_CPU0_P1P0_DP<13>")
	)
	(segment
		(start 313.095386 -177.408586)
		(end 316.606936 -178.392074)
		(width 0.14732)
		(layer "In4.Cu")
		(net "UPI_CPU1_CPU0_P1P0_DP<13>")
	)
	(segment
		(start 349.525082 -215.112346)
		(end 349.524066 -215.112854)
		(width 0.0889)
		(layer "In4.Cu")
		(net "UPI_CPU1_CPU0_P1P0_DP<13>")
	)
	(segment
		(start 121.882916 -213.976712)
		(end 121.882916 -212.066378)
		(width 0.0889)
		(layer "In4.Cu")
		(net "UPI_CPU1_CPU0_P1P0_DP<13>")
	)
	(segment
		(start 121.690384 -215.763856)
		(end 121.691146 -215.763348)
		(width 0.0889)
		(layer "In4.Cu")
		(net "UPI_CPU1_CPU0_P1P0_DP<13>")
	)
	(segment
		(start 349.531178 -216.736422)
		(end 349.525844 -216.73947)
		(width 0.0889)
		(layer "In4.Cu")
		(net "UPI_CPU1_CPU0_P1P0_DP<13>")
	)
	(segment
		(start 121.687844 -215.76538)
		(end 121.689368 -215.764364)
		(width 0.0889)
		(layer "In4.Cu")
		(net "UPI_CPU1_CPU0_P1P0_DP<13>")
	)
	(segment
		(start 121.840752 -211.699348)
		(end 121.840752 -211.58454)
		(width 0.14732)
		(layer "In4.Cu")
		(net "UPI_CPU1_CPU0_P1P0_DP<13>")
	)
	(segment
		(start 349.524066 -215.112854)
		(end 349.516192 -215.117426)
		(width 0.0889)
		(layer "In4.Cu")
		(net "UPI_CPU1_CPU0_P1P0_DP<13>")
	)
	(segment
		(start 200.864978 -177.604928)
		(end 211.885276 -178.089052)
		(width 0.14732)
		(layer "In4.Cu")
		(net "UPI_CPU1_CPU0_P1P0_DP<13>")
	)
	(segment
		(start 339.377782 -189.074044)
		(end 342.077294 -192.907158)
		(width 0.14732)
		(layer "In4.Cu")
		(net "UPI_CPU1_CPU0_P1P0_DP<13>")
	)
	(segment
		(start 121.841006 -212.024468)
		(end 121.841006 -212.00237)
		(width 0.0889)
		(layer "In4.Cu")
		(net "UPI_CPU1_CPU0_P1P0_DP<13>")
	)
	(segment
		(start 342.077294 -192.907158)
		(end 347.665802 -198.634604)
		(width 0.14732)
		(layer "In4.Cu")
		(net "UPI_CPU1_CPU0_P1P0_DP<13>")
	)
	(segment
		(start 349.436944 -212.673438)
		(end 349.436944 -212.848698)
		(width 0.0889)
		(layer "In4.Cu")
		(net "UPI_CPU1_CPU0_P1P0_DP<13>")
	)
	(segment
		(start 316.606936 -178.392074)
		(end 328.90206 -182.690008)
		(width 0.14732)
		(layer "In4.Cu")
		(net "UPI_CPU1_CPU0_P1P0_DP<13>")
	)
	(segment
		(start 121.691146 -215.763348)
		(end 121.69521 -215.761062)
		(width 0.0889)
		(layer "In4.Cu")
		(net "UPI_CPU1_CPU0_P1P0_DP<13>")
	)
	(segment
		(start 131.371086 -194.780916)
		(end 137.765536 -190.531242)
		(width 0.14732)
		(layer "In4.Cu")
		(net "UPI_CPU1_CPU0_P1P0_DP<13>")
	)
	(segment
		(start 349.516192 -215.755982)
		(end 349.523558 -215.7603)
		(width 0.0889)
		(layer "In4.Cu")
		(net "UPI_CPU1_CPU0_P1P0_DP<13>")
	)
	(segment
		(start 121.650252 -215.789764)
		(end 121.671588 -215.774524)
		(width 0.0889)
		(layer "In4.Cu")
		(net "UPI_CPU1_CPU0_P1P0_DP<13>")
	)
	(segment
		(start 121.882916 -212.066378)
		(end 121.841006 -212.024468)
		(width 0.0889)
		(layer "In4.Cu")
		(net "UPI_CPU1_CPU0_P1P0_DP<13>")
	)
	(segment
		(start 349.337884 -213.123018)
		(end 349.436944 -213.222078)
		(width 0.0889)
		(layer "In4.Cu")
		(net "UPI_CPU1_CPU0_P1P0_DP<13>")
	)
	(segment
		(start 349.436944 -212.848698)
		(end 349.337884 -212.947758)
		(width 0.0889)
		(layer "In4.Cu")
		(net "UPI_CPU1_CPU0_P1P0_DP<13>")
	)
	(segment
		(start 349.523558 -215.7603)
		(end 349.525082 -215.761062)
		(width 0.0889)
		(layer "In4.Cu")
		(net "UPI_CPU1_CPU0_P1P0_DP<13>")
	)
	(segment
		(start 144.419066 -183.561228)
		(end 151.363426 -180.00599)
		(width 0.14732)
		(layer "In4.Cu")
		(net "UPI_CPU1_CPU0_P1P0_DP<13>")
	)
	(segment
		(start 121.689368 -215.764364)
		(end 121.690384 -215.763856)
		(width 0.0889)
		(layer "In4.Cu")
		(net "UPI_CPU1_CPU0_P1P0_DP<13>")
	)
	(segment
		(start 121.882662 -217.072972)
		(end 121.882662 -217.0557)
		(width 0.0889)
		(layer "In4.Cu")
		(net "UPI_CPU1_CPU0_P1P0_DP<13>")
	)
	(segment
		(start 302.491394 -177.211736)
		(end 313.095386 -177.408586)
		(width 0.14732)
		(layer "In4.Cu")
		(net "UPI_CPU1_CPU0_P1P0_DP<13>")
	)
	(segment
		(start 349.525844 -216.73947)
		(end 349.525082 -216.739978)
		(width 0.0889)
		(layer "In4.Cu")
		(net "UPI_CPU1_CPU0_P1P0_DP<13>")
	)
	(segment
		(start 121.841006 -212.00237)
		(end 121.841006 -211.699602)
		(width 0.14732)
		(layer "In4.Cu")
		(net "UPI_CPU1_CPU0_P1P0_DP<13>")
	)
	(segment
		(start 349.527876 -215.762586)
		(end 349.531178 -215.764618)
		(width 0.0889)
		(layer "In4.Cu")
		(net "UPI_CPU1_CPU0_P1P0_DP<13>")
	)
	(segment
		(start 349.380048 -211.861908)
		(end 349.380048 -212.03793)
		(width 0.14732)
		(layer "In4.Cu")
		(net "UPI_CPU1_CPU0_P1P0_DP<13>")
	)
	(segment
		(start 121.664476 -218.421204)
		(end 121.640346 -218.33205)
		(width 0.0889)
		(layer "In4.Cu")
		(net "UPI_CPU1_CPU0_P1P0_DP<13>")
	)
	(segment
		(start 137.765536 -190.531242)
		(end 142.056358 -184.770776)
		(width 0.14732)
		(layer "In4.Cu")
		(net "UPI_CPU1_CPU0_P1P0_DP<13>")
	)
	(segment
		(start 349.555816 -217.335354)
		(end 349.71228 -217.064336)
		(width 0.0889)
		(layer "In4.Cu")
		(net "UPI_CPU1_CPU0_P1P0_DP<13>")
	)
	(segment
		(start 349.337884 -217.0557)
		(end 349.337884 -217.072972)
		(width 0.0889)
		(layer "In4.Cu")
		(net "UPI_CPU1_CPU0_P1P0_DP<13>")
	)
	(segment
		(start 349.436944 -213.222078)
		(end 349.436944 -213.397338)
		(width 0.0889)
		(layer "In4.Cu")
		(net "UPI_CPU1_CPU0_P1P0_DP<13>")
	)
	(segment
		(start 121.413016 -216.260426)
		(end 121.413016 -216.235026)
		(width 0.0889)
		(layer "In4.Cu")
		(net "UPI_CPU1_CPU0_P1P0_DP<13>")
	)
	(segment
		(start 151.363426 -180.00599)
		(end 157.963616 -178.31689)
		(width 0.14732)
		(layer "In4.Cu")
		(net "UPI_CPU1_CPU0_P1P0_DP<13>")
	)
	(segment
		(start 349.337884 -213.496398)
		(end 349.337884 -213.893908)
		(width 0.0889)
		(layer "In4.Cu")
		(net "UPI_CPU1_CPU0_P1P0_DP<13>")
	)
	(segment
		(start 157.963616 -178.31689)
		(end 200.864978 -177.604928)
		(width 0.14732)
		(layer "In4.Cu")
		(net "UPI_CPU1_CPU0_P1P0_DP<13>")
	)
	(segment
		(start 121.671588 -215.774524)
		(end 121.687844 -215.76538)
		(width 0.0889)
		(layer "In4.Cu")
		(net "UPI_CPU1_CPU0_P1P0_DP<13>")
	)
	(segment
		(start 349.337884 -212.102192)
		(end 349.337884 -212.574378)
		(width 0.0889)
		(layer "In4.Cu")
		(net "UPI_CPU1_CPU0_P1P0_DP<13>")
	)
	(segment
		(start 142.056358 -184.770776)
		(end 144.419066 -183.561228)
		(width 0.14732)
		(layer "In4.Cu")
		(net "UPI_CPU1_CPU0_P1P0_DP<13>")
	)
	(segment
		(start 349.807276 -214.424768)
		(end 349.807276 -214.644732)
		(width 0.0889)
		(layer "In4.Cu")
		(net "UPI_CPU1_CPU0_P1P0_DP<13>")
	)
	(segment
		(start 349.525082 -215.761062)
		(end 349.527876 -215.762586)
		(width 0.0889)
		(layer "In4.Cu")
		(net "UPI_CPU1_CPU0_P1P0_DP<13>")
	)
	(segment
		(start 336.34934 -186.045602)
		(end 339.377782 -189.074044)
		(width 0.14732)
		(layer "In4.Cu")
		(net "UPI_CPU1_CPU0_P1P0_DP<13>")
	)
	(segment
		(start 347.665802 -198.634604)
		(end 349.9104 -204.053948)
		(width 0.14732)
		(layer "In4.Cu")
		(net "UPI_CPU1_CPU0_P1P0_DP<13>")
	)
	(segment
		(start 122.164856 -214.946992)
		(end 122.173746 -214.941912)
		(width 0.0889)
		(layer "In4.Cu")
		(net "UPI_CPU1_CPU0_P1P0_DP<13>")
	)
	(segment
		(start 273.149568 -177.924206)
		(end 302.491394 -177.211736)
		(width 0.14732)
		(layer "In4.Cu")
		(net "UPI_CPU1_CPU0_P1P0_DP<13>")
	)
	(segment
		(start 121.840752 -211.58454)
		(end 124.963682 -202.663806)
		(width 0.14732)
		(layer "In4.Cu")
		(net "UPI_CPU1_CPU0_P1P0_DP<13>")
	)
	(segment
		(start 349.9104 -204.053948)
		(end 349.9104 -211.331556)
		(width 0.14732)
		(layer "In4.Cu")
		(net "UPI_CPU1_CPU0_P1P0_DP<13>")
	)
	(segment
		(start 349.436944 -213.397338)
		(end 349.337884 -213.496398)
		(width 0.0889)
		(layer "In4.Cu")
		(net "UPI_CPU1_CPU0_P1P0_DP<13>")
	)
	(segment
		(start 349.337884 -212.574378)
		(end 349.436944 -212.673438)
		(width 0.0889)
		(layer "In4.Cu")
		(net "UPI_CPU1_CPU0_P1P0_DP<13>")
	)
	(segment
		(start 121.69521 -215.761062)
		(end 121.7041 -215.755982)
		(width 0.0889)
		(layer "In4.Cu")
		(net "UPI_CPU1_CPU0_P1P0_DP<13>")
	)
	(segment
		(start 122.352308 -214.622634)
		(end 122.352308 -214.461344)
		(width 0.0889)
		(layer "In4.Cu")
		(net "UPI_CPU1_CPU0_P1P0_DP<13>")
	)
	(segment
		(start 121.413016 -217.8939)
		(end 121.413016 -217.859864)
		(width 0.0889)
		(layer "In4.Cu")
		(net "UPI_CPU1_CPU0_P1P0_DP<13>")
	)
	(segment
		(start 335.50479 -185.47715)
		(end 336.34934 -186.045602)
		(width 0.14732)
		(layer "In4.Cu")
		(net "UPI_CPU1_CPU0_P1P0_DP<13>")
	)
	(segment
		(start 328.90206 -182.690008)
		(end 335.50479 -185.47715)
		(width 0.14732)
		(layer "In4.Cu")
		(net "UPI_CPU1_CPU0_P1P0_DP<13>")
	)
	(segment
		(start 121.841006 -211.699602)
		(end 121.840752 -211.699348)
		(width 0.14732)
		(layer "In4.Cu")
		(net "UPI_CPU1_CPU0_P1P0_DP<13>")
	)
	(segment
		(start 238.618014 -178.089052)
		(end 273.149568 -177.924206)
		(width 0.14732)
		(layer "In4.Cu")
		(net "UPI_CPU1_CPU0_P1P0_DP<13>")
	)
	(arc
		(start 121.623582 -218.319096)
		(mid 121.4715 -218.129664)
		(end 121.413016 -217.8939)
		(width 0.0889)
		(layer "In4.Cu")
		(net "UPI_CPU1_CPU0_P1P0_DP<13>")
	)
	(arc
		(start 349.531178 -215.764618)
		(mid 349.807752 -216.25052)
		(end 349.531178 -216.736422)
		(width 0.0889)
		(layer "In4.Cu")
		(net "UPI_CPU1_CPU0_P1P0_DP<13>")
	)
	(arc
		(start 349.337884 -217.072972)
		(mid 349.376558 -217.23004)
		(end 349.477838 -217.356182)
		(width 0.0889)
		(layer "In4.Cu")
		(net "UPI_CPU1_CPU0_P1P0_DP<13>")
	)
	(arc
		(start 121.695464 -217.388694)
		(mid 121.830397 -217.25534)
		(end 121.882662 -217.072972)
		(width 0.0889)
		(layer "In4.Cu")
		(net "UPI_CPU1_CPU0_P1P0_DP<13>")
	)
	(arc
		(start 349.337884 -213.893908)
		(mid 349.412889 -214.009367)
		(end 349.522034 -214.093298)
		(width 0.0889)
		(layer "In4.Cu")
		(net "UPI_CPU1_CPU0_P1P0_DP<13>")
	)
	(arc
		(start 122.352054 -214.637366)
		(mid 122.352251 -214.630001)
		(end 122.352308 -214.622634)
		(width 0.0889)
		(layer "In4.Cu")
		(net "UPI_CPU1_CPU0_P1P0_DP<13>")
	)
	(arc
		(start 349.807276 -214.644732)
		(mid 349.726365 -214.91486)
		(end 349.525082 -215.112346)
		(width 0.0889)
		(layer "In4.Cu")
		(net "UPI_CPU1_CPU0_P1P0_DP<13>")
	)
	(arc
		(start 121.695464 -216.739978)
		(mid 121.491129 -216.537373)
		(end 121.413016 -216.260426)
		(width 0.0889)
		(layer "In4.Cu")
		(net "UPI_CPU1_CPU0_P1P0_DP<13>")
	)
	(arc
		(start 121.640346 -218.33205)
		(mid 121.631905 -218.32565)
		(end 121.623582 -218.319096)
		(width 0.0889)
		(layer "In4.Cu")
		(net "UPI_CPU1_CPU0_P1P0_DP<13>")
	)
	(arc
		(start 121.882662 -217.0557)
		(mid 121.830392 -216.873335)
		(end 121.695464 -216.739978)
		(width 0.0889)
		(layer "In4.Cu")
		(net "UPI_CPU1_CPU0_P1P0_DP<13>")
	)
	(arc
		(start 122.173746 -214.941912)
		(mid 122.301 -214.811946)
		(end 122.352054 -214.637366)
		(width 0.0889)
		(layer "In4.Cu")
		(net "UPI_CPU1_CPU0_P1P0_DP<13>")
	)
	(arc
		(start 349.525082 -216.739978)
		(mid 349.390149 -216.873332)
		(end 349.337884 -217.0557)
		(width 0.0889)
		(layer "In4.Cu")
		(net "UPI_CPU1_CPU0_P1P0_DP<13>")
	)
	(arc
		(start 121.882662 -215.414606)
		(mid 121.963573 -215.144478)
		(end 122.164856 -214.946992)
		(width 0.0889)
		(layer "In4.Cu")
		(net "UPI_CPU1_CPU0_P1P0_DP<13>")
	)
	(arc
		(start 122.352308 -214.461344)
		(mid 122.277303 -214.345885)
		(end 122.168158 -214.261954)
		(width 0.0889)
		(layer "In4.Cu")
		(net "UPI_CPU1_CPU0_P1P0_DP<13>")
	)
	(arc
		(start 349.33763 -215.436704)
		(mid 349.385309 -215.619604)
		(end 349.516192 -215.755982)
		(width 0.0889)
		(layer "In4.Cu")
		(net "UPI_CPU1_CPU0_P1P0_DP<13>")
	)
	(arc
		(start 349.522034 -214.093298)
		(mid 349.695997 -214.232062)
		(end 349.807276 -214.424768)
		(width 0.0889)
		(layer "In4.Cu")
		(net "UPI_CPU1_CPU0_P1P0_DP<13>")
	)
	(arc
		(start 349.516192 -215.117426)
		(mid 349.388938 -215.247392)
		(end 349.337884 -215.421972)
		(width 0.0889)
		(layer "In4.Cu")
		(net "UPI_CPU1_CPU0_P1P0_DP<13>")
	)
	(arc
		(start 121.7041 -215.755982)
		(mid 121.835014 -215.619622)
		(end 121.882662 -215.436704)
		(width 0.0889)
		(layer "In4.Cu")
		(net "UPI_CPU1_CPU0_P1P0_DP<13>")
	)
	(arc
		(start 121.413016 -216.235026)
		(mid 121.479197 -215.984452)
		(end 121.650252 -215.789764)
		(width 0.0889)
		(layer "In4.Cu")
		(net "UPI_CPU1_CPU0_P1P0_DP<13>")
	)
	(arc
		(start 121.413016 -217.859864)
		(mid 121.493178 -217.587675)
		(end 121.695464 -217.388694)
		(width 0.0889)
		(layer "In4.Cu")
		(net "UPI_CPU1_CPU0_P1P0_DP<13>")
	)
	(arc
		(start 349.337884 -215.421972)
		(mid 349.337687 -215.429337)
		(end 349.33763 -215.436704)
		(width 0.0889)
		(layer "In4.Cu")
		(net "UPI_CPU1_CPU0_P1P0_DP<13>")
	)
	(segment
		(start 122.917712 -218.414346)
		(end 122.917712 -217.87866)
		(width 0.13208)
		(layer "F.Cu")
		(net "UPI_CPU1_CPU0_P1P0_DP<12>")
	)
	(segment
		(start 348.30258 -218.414346)
		(end 348.30258 -217.87866)
		(width 0.13208)
		(layer "F.Cu")
		(net "UPI_CPU1_CPU0_P1P0_DP<12>")
	)
	(segment
		(start 348.30258 -217.87866)
		(end 348.302834 -217.878406)
		(width 0.13208)
		(layer "F.Cu")
		(net "UPI_CPU1_CPU0_P1P0_DP<12>")
	)
	(segment
		(start 122.917712 -217.87866)
		(end 122.917966 -217.878406)
		(width 0.13208)
		(layer "F.Cu")
		(net "UPI_CPU1_CPU0_P1P0_DP<12>")
	)
	(segment
		(start 135.249412 -193.572638)
		(end 135.418576 -193.606674)
		(width 0.14732)
		(layer "In4.Cu")
		(net "UPI_CPU1_CPU0_P1P0_DP<12>")
	)
	(segment
		(start 151.814784 -181.041548)
		(end 158.142686 -179.421536)
		(width 0.14732)
		(layer "In4.Cu")
		(net "UPI_CPU1_CPU0_P1P0_DP<12>")
	)
	(segment
		(start 135.782558 -193.364612)
		(end 135.816594 -193.195448)
		(width 0.14732)
		(layer "In4.Cu")
		(net "UPI_CPU1_CPU0_P1P0_DP<12>")
	)
	(segment
		(start 123.013216 -213.893908)
		(end 123.013216 -212.066632)
		(width 0.0889)
		(layer "In4.Cu")
		(net "UPI_CPU1_CPU0_P1P0_DP<12>")
	)
	(segment
		(start 348.7674 -210.89493)
		(end 348.16542 -211.49691)
		(width 0.14732)
		(layer "In4.Cu")
		(net "UPI_CPU1_CPU0_P1P0_DP<12>")
	)
	(segment
		(start 302.494696 -178.343306)
		(end 313.022234 -178.538886)
		(width 0.14732)
		(layer "In4.Cu")
		(net "UPI_CPU1_CPU0_P1P0_DP<12>")
	)
	(segment
		(start 313.022234 -178.538886)
		(end 316.215522 -179.430426)
		(width 0.14732)
		(layer "In4.Cu")
		(net "UPI_CPU1_CPU0_P1P0_DP<12>")
	)
	(segment
		(start 122.761502 -217.607388)
		(end 122.785632 -217.518234)
		(width 0.0889)
		(layer "In4.Cu")
		(net "UPI_CPU1_CPU0_P1P0_DP<12>")
	)
	(segment
		(start 133.36397 -194.825874)
		(end 133.533134 -194.85991)
		(width 0.14732)
		(layer "In4.Cu")
		(net "UPI_CPU1_CPU0_P1P0_DP<12>")
	)
	(segment
		(start 348.48927 -215.925654)
		(end 348.490032 -215.926162)
		(width 0.0889)
		(layer "In4.Cu")
		(net "UPI_CPU1_CPU0_P1P0_DP<12>")
	)
	(segment
		(start 136.789414 -192.695322)
		(end 136.82345 -192.526158)
		(width 0.14732)
		(layer "In4.Cu")
		(net "UPI_CPU1_CPU0_P1P0_DP<12>")
	)
	(segment
		(start 134.851648 -193.983356)
		(end 134.885684 -193.814446)
		(width 0.14732)
		(layer "In4.Cu")
		(net "UPI_CPU1_CPU0_P1P0_DP<12>")
	)
	(segment
		(start 123.05538 -211.857336)
		(end 126.188216 -202.91171)
		(width 0.14732)
		(layer "In4.Cu")
		(net "UPI_CPU1_CPU0_P1P0_DP<12>")
	)
	(segment
		(start 132.43306 -195.444618)
		(end 132.602224 -195.478654)
		(width 0.14732)
		(layer "In4.Cu")
		(net "UPI_CPU1_CPU0_P1P0_DP<12>")
	)
	(segment
		(start 348.207584 -213.117938)
		(end 348.108524 -213.216998)
		(width 0.0889)
		(layer "In4.Cu")
		(net "UPI_CPU1_CPU0_P1P0_DP<12>")
	)
	(segment
		(start 122.917966 -217.878406)
		(end 122.761502 -217.607388)
		(width 0.0889)
		(layer "In4.Cu")
		(net "UPI_CPU1_CPU0_P1P0_DP<12>")
	)
	(segment
		(start 338.860638 -190.259462)
		(end 338.825586 -190.461138)
		(width 0.14732)
		(layer "In4.Cu")
		(net "UPI_CPU1_CPU0_P1P0_DP<12>")
	)
	(segment
		(start 130.586734 -197.501256)
		(end 130.58648 -197.501256)
		(width 0.14732)
		(layer "In4.Cu")
		(net "UPI_CPU1_CPU0_P1P0_DP<12>")
	)
	(segment
		(start 341.245698 -193.646298)
		(end 346.729558 -199.266302)
		(width 0.14732)
		(layer "In4.Cu")
		(net "UPI_CPU1_CPU0_P1P0_DP<12>")
	)
	(segment
		(start 348.490032 -217.554048)
		(end 348.490794 -217.554556)
		(width 0.0889)
		(layer "In4.Cu")
		(net "UPI_CPU1_CPU0_P1P0_DP<12>")
	)
	(segment
		(start 348.7674 -204.185266)
		(end 348.7674 -210.89493)
		(width 0.14732)
		(layer "In4.Cu")
		(net "UPI_CPU1_CPU0_P1P0_DP<12>")
	)
	(segment
		(start 348.108524 -212.843618)
		(end 348.207584 -212.942678)
		(width 0.0889)
		(layer "In4.Cu")
		(net "UPI_CPU1_CPU0_P1P0_DP<12>")
	)
	(segment
		(start 136.425178 -192.937384)
		(end 136.789414 -192.695322)
		(width 0.14732)
		(layer "In4.Cu")
		(net "UPI_CPU1_CPU0_P1P0_DP<12>")
	)
	(segment
		(start 123.013216 -212.066632)
		(end 123.05538 -212.024468)
		(width 0.0889)
		(layer "In4.Cu")
		(net "UPI_CPU1_CPU0_P1P0_DP<12>")
	)
	(segment
		(start 348.108524 -213.392258)
		(end 348.207584 -213.491318)
		(width 0.0889)
		(layer "In4.Cu")
		(net "UPI_CPU1_CPU0_P1P0_DP<12>")
	)
	(segment
		(start 348.16542 -211.790788)
		(end 348.165674 -211.791042)
		(width 0.14732)
		(layer "In4.Cu")
		(net "UPI_CPU1_CPU0_P1P0_DP<12>")
	)
	(segment
		(start 128.387602 -200.206356)
		(end 130.586734 -197.501256)
		(width 0.14732)
		(layer "In4.Cu")
		(net "UPI_CPU1_CPU0_P1P0_DP<12>")
	)
	(segment
		(start 123.199398 -215.112854)
		(end 123.200414 -215.112346)
		(width 0.0889)
		(layer "In4.Cu")
		(net "UPI_CPU1_CPU0_P1P0_DP<12>")
	)
	(segment
		(start 348.108524 -213.216998)
		(end 348.108524 -213.392258)
		(width 0.0889)
		(layer "In4.Cu")
		(net "UPI_CPU1_CPU0_P1P0_DP<12>")
	)
	(segment
		(start 123.191524 -215.117426)
		(end 123.199398 -215.112854)
		(width 0.0889)
		(layer "In4.Cu")
		(net "UPI_CPU1_CPU0_P1P0_DP<12>")
	)
	(segment
		(start 338.525612 -189.783466)
		(end 338.860638 -190.259462)
		(width 0.14732)
		(layer "In4.Cu")
		(net "UPI_CPU1_CPU0_P1P0_DP<12>")
	)
	(segment
		(start 348.165674 -211.791042)
		(end 348.165674 -212.02523)
		(width 0.14732)
		(layer "In4.Cu")
		(net "UPI_CPU1_CPU0_P1P0_DP<12>")
	)
	(segment
		(start 338.825586 -190.461138)
		(end 339.037676 -190.762636)
		(width 0.14732)
		(layer "In4.Cu")
		(net "UPI_CPU1_CPU0_P1P0_DP<12>")
	)
	(segment
		(start 348.108524 -212.668358)
		(end 348.108524 -212.843618)
		(width 0.0889)
		(layer "In4.Cu")
		(net "UPI_CPU1_CPU0_P1P0_DP<12>")
	)
	(segment
		(start 134.885684 -193.814446)
		(end 135.249412 -193.572638)
		(width 0.14732)
		(layer "In4.Cu")
		(net "UPI_CPU1_CPU0_P1P0_DP<12>")
	)
	(segment
		(start 348.207584 -213.491318)
		(end 348.207584 -213.930484)
		(width 0.0889)
		(layer "In4.Cu")
		(net "UPI_CPU1_CPU0_P1P0_DP<12>")
	)
	(segment
		(start 348.498922 -216.569798)
		(end 348.490032 -216.574878)
		(width 0.0889)
		(layer "In4.Cu")
		(net "UPI_CPU1_CPU0_P1P0_DP<12>")
	)
	(segment
		(start 348.490032 -216.574878)
		(end 348.486222 -216.577164)
		(width 0.0889)
		(layer "In4.Cu")
		(net "UPI_CPU1_CPU0_P1P0_DP<12>")
	)
	(segment
		(start 348.490794 -217.554556)
		(end 348.498922 -217.559128)
		(width 0.0889)
		(layer "In4.Cu")
		(net "UPI_CPU1_CPU0_P1P0_DP<12>")
	)
	(segment
		(start 137.788396 -191.884554)
		(end 138.59637 -191.347344)
		(width 0.14732)
		(layer "In4.Cu")
		(net "UPI_CPU1_CPU0_P1P0_DP<12>")
	)
	(segment
		(start 122.721878 -215.931242)
		(end 122.730768 -215.926162)
		(width 0.0889)
		(layer "In4.Cu")
		(net "UPI_CPU1_CPU0_P1P0_DP<12>")
	)
	(segment
		(start 142.858998 -185.625486)
		(end 151.814784 -181.041548)
		(width 0.14732)
		(layer "In4.Cu")
		(net "UPI_CPU1_CPU0_P1P0_DP<12>")
	)
	(segment
		(start 123.482608 -214.644732)
		(end 123.482608 -214.424768)
		(width 0.0889)
		(layer "In4.Cu")
		(net "UPI_CPU1_CPU0_P1P0_DP<12>")
	)
	(segment
		(start 348.486222 -216.577164)
		(end 348.482412 -216.579196)
		(width 0.0889)
		(layer "In4.Cu")
		(net "UPI_CPU1_CPU0_P1P0_DP<12>")
	)
	(segment
		(start 348.498414 -214.941912)
		(end 348.489524 -214.946992)
		(width 0.0889)
		(layer "In4.Cu")
		(net "UPI_CPU1_CPU0_P1P0_DP<12>")
	)
	(segment
		(start 158.142686 -179.421536)
		(end 200.807574 -178.713638)
		(width 0.14732)
		(layer "In4.Cu")
		(net "UPI_CPU1_CPU0_P1P0_DP<12>")
	)
	(segment
		(start 133.897116 -194.617848)
		(end 133.931152 -194.448938)
		(width 0.14732)
		(layer "In4.Cu")
		(net "UPI_CPU1_CPU0_P1P0_DP<12>")
	)
	(segment
		(start 348.165674 -212.02523)
		(end 348.165674 -212.047328)
		(width 0.0889)
		(layer "In4.Cu")
		(net "UPI_CPU1_CPU0_P1P0_DP<12>")
	)
	(segment
		(start 136.82345 -192.526158)
		(end 137.221214 -192.261744)
		(width 0.14732)
		(layer "In4.Cu")
		(net "UPI_CPU1_CPU0_P1P0_DP<12>")
	)
	(segment
		(start 200.807574 -178.713638)
		(end 212.332316 -179.21986)
		(width 0.14732)
		(layer "In4.Cu")
		(net "UPI_CPU1_CPU0_P1P0_DP<12>")
	)
	(segment
		(start 348.207584 -212.942678)
		(end 348.207584 -213.117938)
		(width 0.0889)
		(layer "In4.Cu")
		(net "UPI_CPU1_CPU0_P1P0_DP<12>")
	)
	(segment
		(start 137.75436 -192.053464)
		(end 137.788396 -191.884554)
		(width 0.14732)
		(layer "In4.Cu")
		(net "UPI_CPU1_CPU0_P1P0_DP<12>")
	)
	(segment
		(start 348.490032 -215.926162)
		(end 348.491556 -215.926924)
		(width 0.0889)
		(layer "In4.Cu")
		(net "UPI_CPU1_CPU0_P1P0_DP<12>")
	)
	(segment
		(start 346.729558 -199.266302)
		(end 348.7674 -204.185266)
		(width 0.14732)
		(layer "In4.Cu")
		(net "UPI_CPU1_CPU0_P1P0_DP<12>")
	)
	(segment
		(start 335.656682 -186.914536)
		(end 336.370676 -187.62853)
		(width 0.14732)
		(layer "In4.Cu")
		(net "UPI_CPU1_CPU0_P1P0_DP<12>")
	)
	(segment
		(start 122.736864 -216.578434)
		(end 122.730768 -216.574878)
		(width 0.0889)
		(layer "In4.Cu")
		(net "UPI_CPU1_CPU0_P1P0_DP<12>")
	)
	(segment
		(start 348.491556 -215.926924)
		(end 348.498922 -215.931242)
		(width 0.0889)
		(layer "In4.Cu")
		(net "UPI_CPU1_CPU0_P1P0_DP<12>")
	)
	(segment
		(start 336.836258 -188.094112)
		(end 338.525612 -189.783466)
		(width 0.14732)
		(layer "In4.Cu")
		(net "UPI_CPU1_CPU0_P1P0_DP<12>")
	)
	(segment
		(start 132.602224 -195.478654)
		(end 132.966206 -195.236592)
		(width 0.14732)
		(layer "In4.Cu")
		(net "UPI_CPU1_CPU0_P1P0_DP<12>")
	)
	(segment
		(start 133.533134 -194.85991)
		(end 133.897116 -194.617848)
		(width 0.14732)
		(layer "In4.Cu")
		(net "UPI_CPU1_CPU0_P1P0_DP<12>")
	)
	(segment
		(start 136.256268 -192.903348)
		(end 136.425178 -192.937384)
		(width 0.14732)
		(layer "In4.Cu")
		(net "UPI_CPU1_CPU0_P1P0_DP<12>")
	)
	(segment
		(start 339.037676 -190.762636)
		(end 339.23986 -190.797434)
		(width 0.14732)
		(layer "In4.Cu")
		(net "UPI_CPU1_CPU0_P1P0_DP<12>")
	)
	(segment
		(start 123.012962 -215.452198)
		(end 123.012962 -215.436704)
		(width 0.0889)
		(layer "In4.Cu")
		(net "UPI_CPU1_CPU0_P1P0_DP<12>")
	)
	(segment
		(start 122.730768 -216.574878)
		(end 122.721878 -216.569798)
		(width 0.0889)
		(layer "In4.Cu")
		(net "UPI_CPU1_CPU0_P1P0_DP<12>")
	)
	(segment
		(start 316.215522 -179.430426)
		(end 328.487024 -183.72328)
		(width 0.14732)
		(layer "In4.Cu")
		(net "UPI_CPU1_CPU0_P1P0_DP<12>")
	)
	(segment
		(start 348.16542 -211.49691)
		(end 348.16542 -211.790788)
		(width 0.14732)
		(layer "In4.Cu")
		(net "UPI_CPU1_CPU0_P1P0_DP<12>")
	)
	(segment
		(start 137.221214 -192.261744)
		(end 137.390124 -192.29578)
		(width 0.14732)
		(layer "In4.Cu")
		(net "UPI_CPU1_CPU0_P1P0_DP<12>")
	)
	(segment
		(start 339.23986 -190.797434)
		(end 341.245698 -193.646298)
		(width 0.14732)
		(layer "In4.Cu")
		(net "UPI_CPU1_CPU0_P1P0_DP<12>")
	)
	(segment
		(start 135.418576 -193.606674)
		(end 135.782558 -193.364612)
		(width 0.14732)
		(layer "In4.Cu")
		(net "UPI_CPU1_CPU0_P1P0_DP<12>")
	)
	(segment
		(start 135.816594 -193.195448)
		(end 136.256268 -192.903348)
		(width 0.14732)
		(layer "In4.Cu")
		(net "UPI_CPU1_CPU0_P1P0_DP<12>")
	)
	(segment
		(start 138.59637 -191.347344)
		(end 142.858998 -185.625486)
		(width 0.14732)
		(layer "In4.Cu")
		(net "UPI_CPU1_CPU0_P1P0_DP<12>")
	)
	(segment
		(start 126.188216 -202.91171)
		(end 128.387856 -200.206356)
		(width 0.14732)
		(layer "In4.Cu")
		(net "UPI_CPU1_CPU0_P1P0_DP<12>")
	)
	(segment
		(start 123.05538 -212.00237)
		(end 123.05538 -211.857336)
		(width 0.14732)
		(layer "In4.Cu")
		(net "UPI_CPU1_CPU0_P1P0_DP<12>")
	)
	(segment
		(start 348.483936 -215.922606)
		(end 348.48927 -215.925654)
		(width 0.0889)
		(layer "In4.Cu")
		(net "UPI_CPU1_CPU0_P1P0_DP<12>")
	)
	(segment
		(start 137.390124 -192.29578)
		(end 137.75436 -192.053464)
		(width 0.14732)
		(layer "In4.Cu")
		(net "UPI_CPU1_CPU0_P1P0_DP<12>")
	)
	(segment
		(start 348.165674 -212.047328)
		(end 348.207584 -212.089238)
		(width 0.0889)
		(layer "In4.Cu")
		(net "UPI_CPU1_CPU0_P1P0_DP<12>")
	)
	(segment
		(start 348.676976 -214.461344)
		(end 348.676976 -214.622634)
		(width 0.0889)
		(layer "In4.Cu")
		(net "UPI_CPU1_CPU0_P1P0_DP<12>")
	)
	(segment
		(start 133.931152 -194.448938)
		(end 134.318502 -194.191382)
		(width 0.14732)
		(layer "In4.Cu")
		(net "UPI_CPU1_CPU0_P1P0_DP<12>")
	)
	(segment
		(start 348.482412 -216.579196)
		(end 348.47784 -216.58199)
		(width 0.0889)
		(layer "In4.Cu")
		(net "UPI_CPU1_CPU0_P1P0_DP<12>")
	)
	(segment
		(start 134.487666 -194.225418)
		(end 134.851648 -193.983356)
		(width 0.14732)
		(layer "In4.Cu")
		(net "UPI_CPU1_CPU0_P1P0_DP<12>")
	)
	(segment
		(start 348.207584 -212.089238)
		(end 348.207584 -212.569298)
		(width 0.0889)
		(layer "In4.Cu")
		(net "UPI_CPU1_CPU0_P1P0_DP<12>")
	)
	(segment
		(start 348.53753 -218.170252)
		(end 348.459298 -218.149424)
		(width 0.0889)
		(layer "In4.Cu")
		(net "UPI_CPU1_CPU0_P1P0_DP<12>")
	)
	(segment
		(start 273.166078 -179.055014)
		(end 302.494696 -178.343306)
		(width 0.14732)
		(layer "In4.Cu")
		(net "UPI_CPU1_CPU0_P1P0_DP<12>")
	)
	(segment
		(start 133.000242 -195.067682)
		(end 133.36397 -194.825874)
		(width 0.14732)
		(layer "In4.Cu")
		(net "UPI_CPU1_CPU0_P1P0_DP<12>")
	)
	(segment
		(start 348.459298 -218.149424)
		(end 348.302834 -217.878406)
		(width 0.0889)
		(layer "In4.Cu")
		(net "UPI_CPU1_CPU0_P1P0_DP<12>")
	)
	(segment
		(start 335.017872 -186.48426)
		(end 335.656682 -186.914536)
		(width 0.14732)
		(layer "In4.Cu")
		(net "UPI_CPU1_CPU0_P1P0_DP<12>")
	)
	(segment
		(start 336.370676 -187.62853)
		(end 336.370676 -187.833254)
		(width 0.14732)
		(layer "In4.Cu")
		(net "UPI_CPU1_CPU0_P1P0_DP<12>")
	)
	(segment
		(start 128.387856 -200.206356)
		(end 128.387602 -200.206356)
		(width 0.14732)
		(layer "In4.Cu")
		(net "UPI_CPU1_CPU0_P1P0_DP<12>")
	)
	(segment
		(start 348.20733 -215.414606)
		(end 348.20733 -215.436704)
		(width 0.0889)
		(layer "In4.Cu")
		(net "UPI_CPU1_CPU0_P1P0_DP<12>")
	)
	(segment
		(start 348.20733 -217.064336)
		(end 348.20733 -217.071956)
		(width 0.0889)
		(layer "In4.Cu")
		(net "UPI_CPU1_CPU0_P1P0_DP<12>")
	)
	(segment
		(start 238.621062 -179.21986)
		(end 273.166078 -179.055014)
		(width 0.14732)
		(layer "In4.Cu")
		(net "UPI_CPU1_CPU0_P1P0_DP<12>")
	)
	(segment
		(start 130.58648 -197.501256)
		(end 132.052314 -195.697856)
		(width 0.14732)
		(layer "In4.Cu")
		(net "UPI_CPU1_CPU0_P1P0_DP<12>")
	)
	(segment
		(start 336.370676 -187.833254)
		(end 336.631534 -188.094112)
		(width 0.14732)
		(layer "In4.Cu")
		(net "UPI_CPU1_CPU0_P1P0_DP<12>")
	)
	(segment
		(start 328.487024 -183.72328)
		(end 335.017872 -186.48426)
		(width 0.14732)
		(layer "In4.Cu")
		(net "UPI_CPU1_CPU0_P1P0_DP<12>")
	)
	(segment
		(start 132.966206 -195.236592)
		(end 133.000242 -195.067682)
		(width 0.14732)
		(layer "In4.Cu")
		(net "UPI_CPU1_CPU0_P1P0_DP<12>")
	)
	(segment
		(start 132.052314 -195.697856)
		(end 132.43306 -195.444618)
		(width 0.14732)
		(layer "In4.Cu")
		(net "UPI_CPU1_CPU0_P1P0_DP<12>")
	)
	(segment
		(start 123.05538 -212.024468)
		(end 123.05538 -212.00237)
		(width 0.0889)
		(layer "In4.Cu")
		(net "UPI_CPU1_CPU0_P1P0_DP<12>")
	)
	(segment
		(start 134.318502 -194.191382)
		(end 134.487666 -194.225418)
		(width 0.14732)
		(layer "In4.Cu")
		(net "UPI_CPU1_CPU0_P1P0_DP<12>")
	)
	(segment
		(start 123.013216 -217.07856)
		(end 123.013216 -217.064336)
		(width 0.0889)
		(layer "In4.Cu")
		(net "UPI_CPU1_CPU0_P1P0_DP<12>")
	)
	(segment
		(start 348.207584 -212.569298)
		(end 348.108524 -212.668358)
		(width 0.0889)
		(layer "In4.Cu")
		(net "UPI_CPU1_CPU0_P1P0_DP<12>")
	)
	(segment
		(start 212.332316 -179.21986)
		(end 238.621062 -179.21986)
		(width 0.14732)
		(layer "In4.Cu")
		(net "UPI_CPU1_CPU0_P1P0_DP<12>")
	)
	(segment
		(start 336.631534 -188.094112)
		(end 336.836258 -188.094112)
		(width 0.14732)
		(layer "In4.Cu")
		(net "UPI_CPU1_CPU0_P1P0_DP<12>")
	)
	(arc
		(start 348.676976 -214.622634)
		(mid 348.629297 -214.805534)
		(end 348.498414 -214.941912)
		(width 0.0889)
		(layer "In4.Cu")
		(net "UPI_CPU1_CPU0_P1P0_DP<12>")
	)
	(arc
		(start 122.730768 -215.926162)
		(mid 122.933591 -215.725931)
		(end 123.012962 -215.452198)
		(width 0.0889)
		(layer "In4.Cu")
		(net "UPI_CPU1_CPU0_P1P0_DP<12>")
	)
	(arc
		(start 123.197366 -214.093298)
		(mid 123.088219 -214.00937)
		(end 123.013216 -213.893908)
		(width 0.0889)
		(layer "In4.Cu")
		(net "UPI_CPU1_CPU0_P1P0_DP<12>")
	)
	(arc
		(start 123.013216 -215.421972)
		(mid 123.06427 -215.247392)
		(end 123.191524 -215.117426)
		(width 0.0889)
		(layer "In4.Cu")
		(net "UPI_CPU1_CPU0_P1P0_DP<12>")
	)
	(arc
		(start 348.492826 -214.261954)
		(mid 348.601973 -214.345882)
		(end 348.676976 -214.461344)
		(width 0.0889)
		(layer "In4.Cu")
		(net "UPI_CPU1_CPU0_P1P0_DP<12>")
	)
	(arc
		(start 123.012962 -215.436704)
		(mid 123.013014 -215.429337)
		(end 123.013216 -215.421972)
		(width 0.0889)
		(layer "In4.Cu")
		(net "UPI_CPU1_CPU0_P1P0_DP<12>")
	)
	(arc
		(start 348.498922 -217.559128)
		(mid 348.629836 -217.695488)
		(end 348.677484 -217.878406)
		(width 0.0889)
		(layer "In4.Cu")
		(net "UPI_CPU1_CPU0_P1P0_DP<12>")
	)
	(arc
		(start 123.013216 -217.064336)
		(mid 122.9393 -216.784834)
		(end 122.736864 -216.578434)
		(width 0.0889)
		(layer "In4.Cu")
		(net "UPI_CPU1_CPU0_P1P0_DP<12>")
	)
	(arc
		(start 348.47784 -216.58199)
		(mid 348.279612 -216.787838)
		(end 348.20733 -217.064336)
		(width 0.0889)
		(layer "In4.Cu")
		(net "UPI_CPU1_CPU0_P1P0_DP<12>")
	)
	(arc
		(start 348.207584 -213.930484)
		(mid 348.214869 -213.950046)
		(end 348.222824 -213.969346)
		(width 0.0889)
		(layer "In4.Cu")
		(net "UPI_CPU1_CPU0_P1P0_DP<12>")
	)
	(arc
		(start 123.200414 -215.112346)
		(mid 123.401696 -214.914859)
		(end 123.482608 -214.644732)
		(width 0.0889)
		(layer "In4.Cu")
		(net "UPI_CPU1_CPU0_P1P0_DP<12>")
	)
	(arc
		(start 348.677484 -217.878406)
		(mid 348.640624 -218.040203)
		(end 348.53753 -218.170252)
		(width 0.0889)
		(layer "In4.Cu")
		(net "UPI_CPU1_CPU0_P1P0_DP<12>")
	)
	(arc
		(start 348.489524 -214.946992)
		(mid 348.288242 -215.144479)
		(end 348.20733 -215.414606)
		(width 0.0889)
		(layer "In4.Cu")
		(net "UPI_CPU1_CPU0_P1P0_DP<12>")
	)
	(arc
		(start 348.222824 -213.969346)
		(mid 348.332818 -214.138715)
		(end 348.492826 -214.261954)
		(width 0.0889)
		(layer "In4.Cu")
		(net "UPI_CPU1_CPU0_P1P0_DP<12>")
	)
	(arc
		(start 122.721878 -216.569798)
		(mid 122.543402 -216.25052)
		(end 122.721878 -215.931242)
		(width 0.0889)
		(layer "In4.Cu")
		(net "UPI_CPU1_CPU0_P1P0_DP<12>")
	)
	(arc
		(start 348.20733 -217.071956)
		(mid 348.284959 -217.350369)
		(end 348.490032 -217.554048)
		(width 0.0889)
		(layer "In4.Cu")
		(net "UPI_CPU1_CPU0_P1P0_DP<12>")
	)
	(arc
		(start 348.20733 -215.436704)
		(mid 348.281321 -215.71627)
		(end 348.483936 -215.922606)
		(width 0.0889)
		(layer "In4.Cu")
		(net "UPI_CPU1_CPU0_P1P0_DP<12>")
	)
	(arc
		(start 348.498922 -215.931242)
		(mid 348.677519 -216.25052)
		(end 348.498922 -216.569798)
		(width 0.0889)
		(layer "In4.Cu")
		(net "UPI_CPU1_CPU0_P1P0_DP<12>")
	)
	(arc
		(start 122.785632 -217.518234)
		(mid 122.794075 -217.511836)
		(end 122.802396 -217.50528)
		(width 0.0889)
		(layer "In4.Cu")
		(net "UPI_CPU1_CPU0_P1P0_DP<12>")
	)
	(arc
		(start 122.802396 -217.50528)
		(mid 122.954903 -217.315182)
		(end 123.013216 -217.07856)
		(width 0.0889)
		(layer "In4.Cu")
		(net "UPI_CPU1_CPU0_P1P0_DP<12>")
	)
	(arc
		(start 123.482608 -214.424768)
		(mid 123.371329 -214.232062)
		(end 123.197366 -214.093298)
		(width 0.0889)
		(layer "In4.Cu")
		(net "UPI_CPU1_CPU0_P1P0_DP<12>")
	)
	(segment
		(start 347.832934 -217.06459)
		(end 347.83268 -217.064336)
		(width 0.13208)
		(layer "F.Cu")
		(net "UPI_CPU1_CPU0_P1P0_DP<11>")
	)
	(segment
		(start 123.387866 -218.692476)
		(end 123.387612 -218.692222)
		(width 0.13208)
		(layer "F.Cu")
		(net "UPI_CPU1_CPU0_P1P0_DP<11>")
	)
	(segment
		(start 347.832934 -217.600276)
		(end 347.832934 -217.06459)
		(width 0.13208)
		(layer "F.Cu")
		(net "UPI_CPU1_CPU0_P1P0_DP<11>")
	)
	(segment
		(start 123.387866 -219.228162)
		(end 123.387866 -218.692476)
		(width 0.13208)
		(layer "F.Cu")
		(net "UPI_CPU1_CPU0_P1P0_DP<11>")
	)
	(segment
		(start 273.174206 -179.623212)
		(end 302.49622 -178.911758)
		(width 0.14732)
		(layer "In4.Cu")
		(net "UPI_CPU1_CPU0_P1P0_DP<11>")
	)
	(segment
		(start 347.646244 -216.73947)
		(end 347.645482 -216.739978)
		(width 0.0889)
		(layer "In4.Cu")
		(net "UPI_CPU1_CPU0_P1P0_DP<11>")
	)
	(segment
		(start 335.963514 -189.441328)
		(end 336.631026 -190.41364)
		(width 0.14732)
		(layer "In4.Cu")
		(net "UPI_CPU1_CPU0_P1P0_DP<11>")
	)
	(segment
		(start 347.500448 -211.791042)
		(end 347.500448 -212.02015)
		(width 0.14732)
		(layer "In4.Cu")
		(net "UPI_CPU1_CPU0_P1P0_DP<11>")
	)
	(segment
		(start 123.720352 -211.892388)
		(end 123.720352 -211.685124)
		(width 0.14732)
		(layer "In4.Cu")
		(net "UPI_CPU1_CPU0_P1P0_DP<11>")
	)
	(segment
		(start 124.053346 -214.303356)
		(end 124.009912 -214.27821)
		(width 0.0889)
		(layer "In4.Cu")
		(net "UPI_CPU1_CPU0_P1P0_DP<11>")
	)
	(segment
		(start 347.458284 -212.904578)
		(end 347.458284 -213.079838)
		(width 0.0889)
		(layer "In4.Cu")
		(net "UPI_CPU1_CPU0_P1P0_DP<11>")
	)
	(segment
		(start 347.636592 -215.755982)
		(end 347.643958 -215.7603)
		(width 0.0889)
		(layer "In4.Cu")
		(net "UPI_CPU1_CPU0_P1P0_DP<11>")
	)
	(segment
		(start 348.20098 -210.596734)
		(end 347.500194 -211.29752)
		(width 0.14732)
		(layer "In4.Cu")
		(net "UPI_CPU1_CPU0_P1P0_DP<11>")
	)
	(segment
		(start 138.838686 -192.004696)
		(end 143.257778 -186.072272)
		(width 0.14732)
		(layer "In4.Cu")
		(net "UPI_CPU1_CPU0_P1P0_DP<11>")
	)
	(segment
		(start 347.458284 -213.079838)
		(end 347.557344 -213.178898)
		(width 0.0889)
		(layer "In4.Cu")
		(net "UPI_CPU1_CPU0_P1P0_DP<11>")
	)
	(segment
		(start 212.027516 -179.788058)
		(end 238.622586 -179.788058)
		(width 0.14732)
		(layer "In4.Cu")
		(net "UPI_CPU1_CPU0_P1P0_DP<11>")
	)
	(segment
		(start 123.57481 -215.761062)
		(end 123.5837 -215.755982)
		(width 0.0889)
		(layer "In4.Cu")
		(net "UPI_CPU1_CPU0_P1P0_DP<11>")
	)
	(segment
		(start 346.270072 -199.647048)
		(end 348.20098 -204.308964)
		(width 0.14732)
		(layer "In4.Cu")
		(net "UPI_CPU1_CPU0_P1P0_DP<11>")
	)
	(segment
		(start 126.708154 -203.152248)
		(end 132.164074 -196.441314)
		(width 0.14732)
		(layer "In4.Cu")
		(net "UPI_CPU1_CPU0_P1P0_DP<11>")
	)
	(segment
		(start 347.557344 -213.178898)
		(end 347.557344 -213.354158)
		(width 0.0889)
		(layer "In4.Cu")
		(net "UPI_CPU1_CPU0_P1P0_DP<11>")
	)
	(segment
		(start 347.648276 -215.762586)
		(end 347.651578 -215.764618)
		(width 0.0889)
		(layer "In4.Cu")
		(net "UPI_CPU1_CPU0_P1P0_DP<11>")
	)
	(segment
		(start 347.458284 -213.453218)
		(end 347.458284 -213.893908)
		(width 0.0889)
		(layer "In4.Cu")
		(net "UPI_CPU1_CPU0_P1P0_DP<11>")
	)
	(segment
		(start 238.622586 -179.788058)
		(end 273.174206 -179.623212)
		(width 0.14732)
		(layer "In4.Cu")
		(net "UPI_CPU1_CPU0_P1P0_DP<11>")
	)
	(segment
		(start 347.644466 -215.112854)
		(end 347.636592 -215.117426)
		(width 0.0889)
		(layer "In4.Cu")
		(net "UPI_CPU1_CPU0_P1P0_DP<11>")
	)
	(segment
		(start 348.20098 -204.308964)
		(end 348.20098 -210.596734)
		(width 0.14732)
		(layer "In4.Cu")
		(net "UPI_CPU1_CPU0_P1P0_DP<11>")
	)
	(segment
		(start 123.762516 -213.762844)
		(end 123.762516 -212.119718)
		(width 0.0889)
		(layer "In4.Cu")
		(net "UPI_CPU1_CPU0_P1P0_DP<11>")
	)
	(segment
		(start 123.762262 -217.072972)
		(end 123.762262 -217.0557)
		(width 0.0889)
		(layer "In4.Cu")
		(net "UPI_CPU1_CPU0_P1P0_DP<11>")
	)
	(segment
		(start 347.557344 -213.354158)
		(end 347.458284 -213.453218)
		(width 0.0889)
		(layer "In4.Cu")
		(net "UPI_CPU1_CPU0_P1P0_DP<11>")
	)
	(segment
		(start 347.500194 -211.29752)
		(end 347.500194 -211.790788)
		(width 0.14732)
		(layer "In4.Cu")
		(net "UPI_CPU1_CPU0_P1P0_DP<11>")
	)
	(segment
		(start 347.651578 -216.736422)
		(end 347.646244 -216.73947)
		(width 0.0889)
		(layer "In4.Cu")
		(net "UPI_CPU1_CPU0_P1P0_DP<11>")
	)
	(segment
		(start 338.523834 -191.900556)
		(end 346.270072 -199.647048)
		(width 0.14732)
		(layer "In4.Cu")
		(net "UPI_CPU1_CPU0_P1P0_DP<11>")
	)
	(segment
		(start 347.458284 -217.0557)
		(end 347.458284 -217.072972)
		(width 0.0889)
		(layer "In4.Cu")
		(net "UPI_CPU1_CPU0_P1P0_DP<11>")
	)
	(segment
		(start 335.382616 -188.23813)
		(end 335.963514 -189.441328)
		(width 0.14732)
		(layer "In4.Cu")
		(net "UPI_CPU1_CPU0_P1P0_DP<11>")
	)
	(segment
		(start 328.256138 -184.237122)
		(end 334.684116 -186.948572)
		(width 0.14732)
		(layer "In4.Cu")
		(net "UPI_CPU1_CPU0_P1P0_DP<11>")
	)
	(segment
		(start 123.762262 -215.436704)
		(end 123.762262 -215.414606)
		(width 0.0889)
		(layer "In4.Cu")
		(net "UPI_CPU1_CPU0_P1P0_DP<11>")
	)
	(segment
		(start 347.500448 -212.02015)
		(end 347.500448 -212.042248)
		(width 0.0889)
		(layer "In4.Cu")
		(net "UPI_CPU1_CPU0_P1P0_DP<11>")
	)
	(segment
		(start 347.458284 -212.531198)
		(end 347.557344 -212.630258)
		(width 0.0889)
		(layer "In4.Cu")
		(net "UPI_CPU1_CPU0_P1P0_DP<11>")
	)
	(segment
		(start 143.257778 -186.072272)
		(end 152.00376 -181.595014)
		(width 0.14732)
		(layer "In4.Cu")
		(net "UPI_CPU1_CPU0_P1P0_DP<11>")
	)
	(segment
		(start 312.759598 -179.102004)
		(end 316.029086 -180.015896)
		(width 0.14732)
		(layer "In4.Cu")
		(net "UPI_CPU1_CPU0_P1P0_DP<11>")
	)
	(segment
		(start 123.292616 -216.260426)
		(end 123.292616 -216.235026)
		(width 0.0889)
		(layer "In4.Cu")
		(net "UPI_CPU1_CPU0_P1P0_DP<11>")
	)
	(segment
		(start 152.00376 -181.595014)
		(end 158.259018 -179.993798)
		(width 0.14732)
		(layer "In4.Cu")
		(net "UPI_CPU1_CPU0_P1P0_DP<11>")
	)
	(segment
		(start 124.044456 -214.946992)
		(end 124.053346 -214.941912)
		(width 0.0889)
		(layer "In4.Cu")
		(net "UPI_CPU1_CPU0_P1P0_DP<11>")
	)
	(segment
		(start 347.676216 -217.335354)
		(end 347.83268 -217.064336)
		(width 0.0889)
		(layer "In4.Cu")
		(net "UPI_CPU1_CPU0_P1P0_DP<11>")
	)
	(segment
		(start 336.631026 -190.41364)
		(end 338.523834 -191.900556)
		(width 0.14732)
		(layer "In4.Cu")
		(net "UPI_CPU1_CPU0_P1P0_DP<11>")
	)
	(segment
		(start 347.500448 -212.042248)
		(end 347.458284 -212.084412)
		(width 0.0889)
		(layer "In4.Cu")
		(net "UPI_CPU1_CPU0_P1P0_DP<11>")
	)
	(segment
		(start 347.500194 -211.790788)
		(end 347.500448 -211.791042)
		(width 0.14732)
		(layer "In4.Cu")
		(net "UPI_CPU1_CPU0_P1P0_DP<11>")
	)
	(segment
		(start 347.645482 -215.761062)
		(end 347.648276 -215.762586)
		(width 0.0889)
		(layer "In4.Cu")
		(net "UPI_CPU1_CPU0_P1P0_DP<11>")
	)
	(segment
		(start 123.720352 -211.685124)
		(end 126.708154 -203.152248)
		(width 0.14732)
		(layer "In4.Cu")
		(net "UPI_CPU1_CPU0_P1P0_DP<11>")
	)
	(segment
		(start 123.387612 -218.692222)
		(end 123.544076 -218.421204)
		(width 0.0889)
		(layer "In4.Cu")
		(net "UPI_CPU1_CPU0_P1P0_DP<11>")
	)
	(segment
		(start 316.029086 -180.015896)
		(end 328.256138 -184.237122)
		(width 0.14732)
		(layer "In4.Cu")
		(net "UPI_CPU1_CPU0_P1P0_DP<11>")
	)
	(segment
		(start 123.720606 -212.077808)
		(end 123.720606 -212.05571)
		(width 0.0889)
		(layer "In4.Cu")
		(net "UPI_CPU1_CPU0_P1P0_DP<11>")
	)
	(segment
		(start 123.292616 -217.8939)
		(end 123.292616 -217.859864)
		(width 0.0889)
		(layer "In4.Cu")
		(net "UPI_CPU1_CPU0_P1P0_DP<11>")
	)
	(segment
		(start 347.557344 -212.805518)
		(end 347.458284 -212.904578)
		(width 0.0889)
		(layer "In4.Cu")
		(net "UPI_CPU1_CPU0_P1P0_DP<11>")
	)
	(segment
		(start 347.557344 -212.630258)
		(end 347.557344 -212.805518)
		(width 0.0889)
		(layer "In4.Cu")
		(net "UPI_CPU1_CPU0_P1P0_DP<11>")
	)
	(segment
		(start 123.544076 -218.421204)
		(end 123.519946 -218.33205)
		(width 0.0889)
		(layer "In4.Cu")
		(net "UPI_CPU1_CPU0_P1P0_DP<11>")
	)
	(segment
		(start 347.645482 -215.112346)
		(end 347.644466 -215.112854)
		(width 0.0889)
		(layer "In4.Cu")
		(net "UPI_CPU1_CPU0_P1P0_DP<11>")
	)
	(segment
		(start 158.259018 -179.993798)
		(end 200.688448 -179.289964)
		(width 0.14732)
		(layer "In4.Cu")
		(net "UPI_CPU1_CPU0_P1P0_DP<11>")
	)
	(segment
		(start 200.688448 -179.289964)
		(end 212.027516 -179.788058)
		(width 0.14732)
		(layer "In4.Cu")
		(net "UPI_CPU1_CPU0_P1P0_DP<11>")
	)
	(segment
		(start 132.164074 -196.441314)
		(end 138.838686 -192.004696)
		(width 0.14732)
		(layer "In4.Cu")
		(net "UPI_CPU1_CPU0_P1P0_DP<11>")
	)
	(segment
		(start 334.684116 -186.948572)
		(end 335.163922 -187.526422)
		(width 0.14732)
		(layer "In4.Cu")
		(net "UPI_CPU1_CPU0_P1P0_DP<11>")
	)
	(segment
		(start 347.927676 -214.424768)
		(end 347.927676 -214.644732)
		(width 0.0889)
		(layer "In4.Cu")
		(net "UPI_CPU1_CPU0_P1P0_DP<11>")
	)
	(segment
		(start 347.643958 -215.7603)
		(end 347.645482 -215.761062)
		(width 0.0889)
		(layer "In4.Cu")
		(net "UPI_CPU1_CPU0_P1P0_DP<11>")
	)
	(segment
		(start 123.762516 -212.119718)
		(end 123.720606 -212.077808)
		(width 0.0889)
		(layer "In4.Cu")
		(net "UPI_CPU1_CPU0_P1P0_DP<11>")
	)
	(segment
		(start 302.49622 -178.911758)
		(end 312.759598 -179.102004)
		(width 0.14732)
		(layer "In4.Cu")
		(net "UPI_CPU1_CPU0_P1P0_DP<11>")
	)
	(segment
		(start 123.720606 -211.892642)
		(end 123.720352 -211.892388)
		(width 0.14732)
		(layer "In4.Cu")
		(net "UPI_CPU1_CPU0_P1P0_DP<11>")
	)
	(segment
		(start 347.458284 -212.084412)
		(end 347.458284 -212.531198)
		(width 0.0889)
		(layer "In4.Cu")
		(net "UPI_CPU1_CPU0_P1P0_DP<11>")
	)
	(segment
		(start 347.598238 -217.356182)
		(end 347.676216 -217.335354)
		(width 0.0889)
		(layer "In4.Cu")
		(net "UPI_CPU1_CPU0_P1P0_DP<11>")
	)
	(segment
		(start 123.720606 -212.05571)
		(end 123.720606 -211.892642)
		(width 0.14732)
		(layer "In4.Cu")
		(net "UPI_CPU1_CPU0_P1P0_DP<11>")
	)
	(segment
		(start 335.163922 -187.526422)
		(end 335.382616 -188.23813)
		(width 0.14732)
		(layer "In4.Cu")
		(net "UPI_CPU1_CPU0_P1P0_DP<11>")
	)
	(arc
		(start 347.45803 -215.436704)
		(mid 347.505709 -215.619604)
		(end 347.636592 -215.755982)
		(width 0.0889)
		(layer "In4.Cu")
		(net "UPI_CPU1_CPU0_P1P0_DP<11>")
	)
	(arc
		(start 123.292616 -217.859864)
		(mid 123.372778 -217.587675)
		(end 123.575064 -217.388694)
		(width 0.0889)
		(layer "In4.Cu")
		(net "UPI_CPU1_CPU0_P1P0_DP<11>")
	)
	(arc
		(start 123.762262 -215.414606)
		(mid 123.843173 -215.144478)
		(end 124.044456 -214.946992)
		(width 0.0889)
		(layer "In4.Cu")
		(net "UPI_CPU1_CPU0_P1P0_DP<11>")
	)
	(arc
		(start 347.458284 -215.421972)
		(mid 347.458087 -215.429337)
		(end 347.45803 -215.436704)
		(width 0.0889)
		(layer "In4.Cu")
		(net "UPI_CPU1_CPU0_P1P0_DP<11>")
	)
	(arc
		(start 347.636592 -215.117426)
		(mid 347.509338 -215.247392)
		(end 347.458284 -215.421972)
		(width 0.0889)
		(layer "In4.Cu")
		(net "UPI_CPU1_CPU0_P1P0_DP<11>")
	)
	(arc
		(start 123.575064 -216.739978)
		(mid 123.370729 -216.537373)
		(end 123.292616 -216.260426)
		(width 0.0889)
		(layer "In4.Cu")
		(net "UPI_CPU1_CPU0_P1P0_DP<11>")
	)
	(arc
		(start 124.231908 -214.612474)
		(mid 124.181839 -214.435249)
		(end 124.053346 -214.303356)
		(width 0.0889)
		(layer "In4.Cu")
		(net "UPI_CPU1_CPU0_P1P0_DP<11>")
	)
	(arc
		(start 123.503182 -218.319096)
		(mid 123.3511 -218.129664)
		(end 123.292616 -217.8939)
		(width 0.0889)
		(layer "In4.Cu")
		(net "UPI_CPU1_CPU0_P1P0_DP<11>")
	)
	(arc
		(start 123.519946 -218.33205)
		(mid 123.511505 -218.32565)
		(end 123.503182 -218.319096)
		(width 0.0889)
		(layer "In4.Cu")
		(net "UPI_CPU1_CPU0_P1P0_DP<11>")
	)
	(arc
		(start 124.009912 -214.27821)
		(mid 123.81651 -214.053999)
		(end 123.762516 -213.762844)
		(width 0.0889)
		(layer "In4.Cu")
		(net "UPI_CPU1_CPU0_P1P0_DP<11>")
	)
	(arc
		(start 124.053346 -214.941912)
		(mid 124.1806 -214.811946)
		(end 124.231654 -214.637366)
		(width 0.0889)
		(layer "In4.Cu")
		(net "UPI_CPU1_CPU0_P1P0_DP<11>")
	)
	(arc
		(start 123.575064 -217.388694)
		(mid 123.709997 -217.25534)
		(end 123.762262 -217.072972)
		(width 0.0889)
		(layer "In4.Cu")
		(net "UPI_CPU1_CPU0_P1P0_DP<11>")
	)
	(arc
		(start 347.642434 -214.093298)
		(mid 347.816397 -214.232062)
		(end 347.927676 -214.424768)
		(width 0.0889)
		(layer "In4.Cu")
		(net "UPI_CPU1_CPU0_P1P0_DP<11>")
	)
	(arc
		(start 347.927676 -214.644732)
		(mid 347.846765 -214.91486)
		(end 347.645482 -215.112346)
		(width 0.0889)
		(layer "In4.Cu")
		(net "UPI_CPU1_CPU0_P1P0_DP<11>")
	)
	(arc
		(start 123.5837 -215.755982)
		(mid 123.714614 -215.619622)
		(end 123.762262 -215.436704)
		(width 0.0889)
		(layer "In4.Cu")
		(net "UPI_CPU1_CPU0_P1P0_DP<11>")
	)
	(arc
		(start 123.292616 -216.235026)
		(mid 123.371986 -215.961292)
		(end 123.57481 -215.761062)
		(width 0.0889)
		(layer "In4.Cu")
		(net "UPI_CPU1_CPU0_P1P0_DP<11>")
	)
	(arc
		(start 347.645482 -216.739978)
		(mid 347.510549 -216.873332)
		(end 347.458284 -217.0557)
		(width 0.0889)
		(layer "In4.Cu")
		(net "UPI_CPU1_CPU0_P1P0_DP<11>")
	)
	(arc
		(start 347.458284 -217.072972)
		(mid 347.496958 -217.23004)
		(end 347.598238 -217.356182)
		(width 0.0889)
		(layer "In4.Cu")
		(net "UPI_CPU1_CPU0_P1P0_DP<11>")
	)
	(arc
		(start 347.458284 -213.893908)
		(mid 347.533289 -214.009367)
		(end 347.642434 -214.093298)
		(width 0.0889)
		(layer "In4.Cu")
		(net "UPI_CPU1_CPU0_P1P0_DP<11>")
	)
	(arc
		(start 123.762262 -217.0557)
		(mid 123.709992 -216.873335)
		(end 123.575064 -216.739978)
		(width 0.0889)
		(layer "In4.Cu")
		(net "UPI_CPU1_CPU0_P1P0_DP<11>")
	)
	(arc
		(start 347.651578 -215.764618)
		(mid 347.928152 -216.25052)
		(end 347.651578 -216.736422)
		(width 0.0889)
		(layer "In4.Cu")
		(net "UPI_CPU1_CPU0_P1P0_DP<11>")
	)
	(arc
		(start 124.231654 -214.637366)
		(mid 124.231987 -214.624922)
		(end 124.231908 -214.612474)
		(width 0.0889)
		(layer "In4.Cu")
		(net "UPI_CPU1_CPU0_P1P0_DP<11>")
	)
	(segment
		(start 124.797312 -217.87866)
		(end 124.797566 -217.878406)
		(width 0.13208)
		(layer "F.Cu")
		(net "UPI_CPU1_CPU0_P1P0_DP<10>")
	)
	(segment
		(start 124.797312 -218.414346)
		(end 124.797312 -217.87866)
		(width 0.13208)
		(layer "F.Cu")
		(net "UPI_CPU1_CPU0_P1P0_DP<10>")
	)
	(segment
		(start 346.42298 -218.414346)
		(end 346.42298 -217.87866)
		(width 0.13208)
		(layer "F.Cu")
		(net "UPI_CPU1_CPU0_P1P0_DP<10>")
	)
	(segment
		(start 346.42298 -217.87866)
		(end 346.423234 -217.878406)
		(width 0.13208)
		(layer "F.Cu")
		(net "UPI_CPU1_CPU0_P1P0_DP<10>")
	)
	(segment
		(start 124.641102 -217.607388)
		(end 124.665232 -217.518234)
		(width 0.0889)
		(layer "In4.Cu")
		(net "UPI_CPU1_CPU0_P1P0_DP<10>")
	)
	(segment
		(start 330.7207 -187.295536)
		(end 330.757784 -187.497212)
		(width 0.14732)
		(layer "In4.Cu")
		(net "UPI_CPU1_CPU0_P1P0_DP<10>")
	)
	(segment
		(start 129.02819 -202.351132)
		(end 129.304034 -202.011788)
		(width 0.14732)
		(layer "In4.Cu")
		(net "UPI_CPU1_CPU0_P1P0_DP<10>")
	)
	(segment
		(start 315.634878 -181.122066)
		(end 327.760838 -185.25236)
		(width 0.14732)
		(layer "In4.Cu")
		(net "UPI_CPU1_CPU0_P1P0_DP<10>")
	)
	(segment
		(start 346.286074 -212.02015)
		(end 346.286074 -212.042248)
		(width 0.0889)
		(layer "In4.Cu")
		(net "UPI_CPU1_CPU0_P1P0_DP<10>")
	)
	(segment
		(start 238.625634 -180.904896)
		(end 273.190462 -180.74005)
		(width 0.14732)
		(layer "In4.Cu")
		(net "UPI_CPU1_CPU0_P1P0_DP<10>")
	)
	(segment
		(start 124.610368 -216.574878)
		(end 124.601478 -216.569798)
		(width 0.0889)
		(layer "In4.Cu")
		(net "UPI_CPU1_CPU0_P1P0_DP<10>")
	)
	(segment
		(start 312.530744 -180.240178)
		(end 315.634878 -181.122066)
		(width 0.14732)
		(layer "In4.Cu")
		(net "UPI_CPU1_CPU0_P1P0_DP<10>")
	)
	(segment
		(start 124.934472 -211.917788)
		(end 124.934472 -211.89569)
		(width 0.0889)
		(layer "In4.Cu")
		(net "UPI_CPU1_CPU0_P1P0_DP<10>")
	)
	(segment
		(start 158.728664 -181.111144)
		(end 179.731416 -180.762656)
		(width 0.14732)
		(layer "In4.Cu")
		(net "UPI_CPU1_CPU0_P1P0_DP<10>")
	)
	(segment
		(start 131.677156 -198.900034)
		(end 131.848606 -198.882508)
		(width 0.14732)
		(layer "In4.Cu")
		(net "UPI_CPU1_CPU0_P1P0_DP<10>")
	)
	(segment
		(start 346.618814 -214.941912)
		(end 346.609924 -214.946992)
		(width 0.0889)
		(layer "In4.Cu")
		(net "UPI_CPU1_CPU0_P1P0_DP<10>")
	)
	(segment
		(start 131.848606 -198.882508)
		(end 132.12445 -198.543164)
		(width 0.14732)
		(layer "In4.Cu")
		(net "UPI_CPU1_CPU0_P1P0_DP<10>")
	)
	(segment
		(start 129.733294 -201.483976)
		(end 130.009138 -201.144632)
		(width 0.14732)
		(layer "In4.Cu")
		(net "UPI_CPU1_CPU0_P1P0_DP<10>")
	)
	(segment
		(start 346.604336 -215.922606)
		(end 346.60967 -215.925654)
		(width 0.0889)
		(layer "In4.Cu")
		(net "UPI_CPU1_CPU0_P1P0_DP<10>")
	)
	(segment
		(start 346.228924 -212.762338)
		(end 346.327984 -212.861398)
		(width 0.0889)
		(layer "In4.Cu")
		(net "UPI_CPU1_CPU0_P1P0_DP<10>")
	)
	(segment
		(start 346.327984 -212.084158)
		(end 346.327984 -212.488018)
		(width 0.0889)
		(layer "In4.Cu")
		(net "UPI_CPU1_CPU0_P1P0_DP<10>")
	)
	(segment
		(start 124.797566 -217.878406)
		(end 124.641102 -217.607388)
		(width 0.0889)
		(layer "In4.Cu")
		(net "UPI_CPU1_CPU0_P1P0_DP<10>")
	)
	(segment
		(start 200.734676 -180.413914)
		(end 211.913216 -180.904896)
		(width 0.14732)
		(layer "In4.Cu")
		(net "UPI_CPU1_CPU0_P1P0_DP<10>")
	)
	(segment
		(start 346.228924 -213.310978)
		(end 346.327984 -213.410038)
		(width 0.0889)
		(layer "In4.Cu")
		(net "UPI_CPU1_CPU0_P1P0_DP<10>")
	)
	(segment
		(start 346.32773 -217.064336)
		(end 346.32773 -217.071956)
		(width 0.0889)
		(layer "In4.Cu")
		(net "UPI_CPU1_CPU0_P1P0_DP<10>")
	)
	(segment
		(start 132.38226 -198.032878)
		(end 132.55371 -198.015352)
		(width 0.14732)
		(layer "In4.Cu")
		(net "UPI_CPU1_CPU0_P1P0_DP<10>")
	)
	(segment
		(start 132.55371 -198.015352)
		(end 132.829554 -197.676008)
		(width 0.14732)
		(layer "In4.Cu")
		(net "UPI_CPU1_CPU0_P1P0_DP<10>")
	)
	(segment
		(start 346.327984 -213.036658)
		(end 346.228924 -213.135718)
		(width 0.0889)
		(layer "In4.Cu")
		(net "UPI_CPU1_CPU0_P1P0_DP<10>")
	)
	(segment
		(start 124.892816 -217.07856)
		(end 124.892816 -217.064336)
		(width 0.0889)
		(layer "In4.Cu")
		(net "UPI_CPU1_CPU0_P1P0_DP<10>")
	)
	(segment
		(start 124.616464 -216.578434)
		(end 124.610368 -216.574878)
		(width 0.0889)
		(layer "In4.Cu")
		(net "UPI_CPU1_CPU0_P1P0_DP<10>")
	)
	(segment
		(start 346.611194 -217.554556)
		(end 346.619322 -217.559128)
		(width 0.0889)
		(layer "In4.Cu")
		(net "UPI_CPU1_CPU0_P1P0_DP<10>")
	)
	(segment
		(start 132.811774 -197.504558)
		(end 133.087364 -197.165722)
		(width 0.14732)
		(layer "In4.Cu")
		(net "UPI_CPU1_CPU0_P1P0_DP<10>")
	)
	(segment
		(start 327.760838 -185.25236)
		(end 329.02652 -186.125866)
		(width 0.14732)
		(layer "In4.Cu")
		(net "UPI_CPU1_CPU0_P1P0_DP<10>")
	)
	(segment
		(start 133.087364 -197.165722)
		(end 139.629388 -192.816226)
		(width 0.14732)
		(layer "In4.Cu")
		(net "UPI_CPU1_CPU0_P1P0_DP<10>")
	)
	(segment
		(start 347.07068 -210.152488)
		(end 346.28582 -210.937348)
		(width 0.14732)
		(layer "In4.Cu")
		(net "UPI_CPU1_CPU0_P1P0_DP<10>")
	)
	(segment
		(start 124.934472 -211.89569)
		(end 124.934472 -211.846668)
		(width 0.14732)
		(layer "In4.Cu")
		(net "UPI_CPU1_CPU0_P1P0_DP<10>")
	)
	(segment
		(start 130.009138 -201.144632)
		(end 129.991358 -200.973182)
		(width 0.14732)
		(layer "In4.Cu")
		(net "UPI_CPU1_CPU0_P1P0_DP<10>")
	)
	(segment
		(start 346.611956 -215.926924)
		(end 346.619322 -215.931242)
		(width 0.0889)
		(layer "In4.Cu")
		(net "UPI_CPU1_CPU0_P1P0_DP<10>")
	)
	(segment
		(start 329.063604 -186.327542)
		(end 329.36688 -186.536838)
		(width 0.14732)
		(layer "In4.Cu")
		(net "UPI_CPU1_CPU0_P1P0_DP<10>")
	)
	(segment
		(start 346.610432 -215.926162)
		(end 346.611956 -215.926924)
		(width 0.0889)
		(layer "In4.Cu")
		(net "UPI_CPU1_CPU0_P1P0_DP<10>")
	)
	(segment
		(start 273.190462 -180.74005)
		(end 301.879508 -180.044344)
		(width 0.14732)
		(layer "In4.Cu")
		(net "UPI_CPU1_CPU0_P1P0_DP<10>")
	)
	(segment
		(start 125.198378 -211.209636)
		(end 127.868426 -203.584048)
		(width 0.14732)
		(layer "In4.Cu")
		(net "UPI_CPU1_CPU0_P1P0_DP<10>")
	)
	(segment
		(start 179.731416 -180.762656)
		(end 179.73167 -180.762656)
		(width 0.14732)
		(layer "In4.Cu")
		(net "UPI_CPU1_CPU0_P1P0_DP<10>")
	)
	(segment
		(start 346.286074 -211.754974)
		(end 346.286074 -212.02015)
		(width 0.14732)
		(layer "In4.Cu")
		(net "UPI_CPU1_CPU0_P1P0_DP<10>")
	)
	(segment
		(start 346.28582 -210.937348)
		(end 346.28582 -211.75472)
		(width 0.14732)
		(layer "In4.Cu")
		(net "UPI_CPU1_CPU0_P1P0_DP<10>")
	)
	(segment
		(start 347.07068 -204.52715)
		(end 347.07068 -210.152488)
		(width 0.14732)
		(layer "In4.Cu")
		(net "UPI_CPU1_CPU0_P1P0_DP<10>")
	)
	(segment
		(start 346.228924 -212.587078)
		(end 346.228924 -212.762338)
		(width 0.0889)
		(layer "In4.Cu")
		(net "UPI_CPU1_CPU0_P1P0_DP<10>")
	)
	(segment
		(start 211.913216 -180.904896)
		(end 238.625634 -180.904896)
		(width 0.14732)
		(layer "In4.Cu")
		(net "UPI_CPU1_CPU0_P1P0_DP<10>")
	)
	(segment
		(start 329.02652 -186.125866)
		(end 329.063604 -186.327542)
		(width 0.14732)
		(layer "In4.Cu")
		(net "UPI_CPU1_CPU0_P1P0_DP<10>")
	)
	(segment
		(start 346.65793 -218.170252)
		(end 346.579698 -218.149424)
		(width 0.0889)
		(layer "In4.Cu")
		(net "UPI_CPU1_CPU0_P1P0_DP<10>")
	)
	(segment
		(start 124.892308 -213.796118)
		(end 124.892308 -211.959952)
		(width 0.0889)
		(layer "In4.Cu")
		(net "UPI_CPU1_CPU0_P1P0_DP<10>")
	)
	(segment
		(start 131.143502 -199.749664)
		(end 131.419346 -199.41032)
		(width 0.14732)
		(layer "In4.Cu")
		(net "UPI_CPU1_CPU0_P1P0_DP<10>")
	)
	(segment
		(start 131.419346 -199.41032)
		(end 131.401566 -199.23887)
		(width 0.14732)
		(layer "In4.Cu")
		(net "UPI_CPU1_CPU0_P1P0_DP<10>")
	)
	(segment
		(start 132.10667 -198.371714)
		(end 132.38226 -198.032878)
		(width 0.14732)
		(layer "In4.Cu")
		(net "UPI_CPU1_CPU0_P1P0_DP<10>")
	)
	(segment
		(start 125.362208 -214.644732)
		(end 125.362208 -214.424768)
		(width 0.0889)
		(layer "In4.Cu")
		(net "UPI_CPU1_CPU0_P1P0_DP<10>")
	)
	(segment
		(start 331.89926 -188.108844)
		(end 337.808062 -192.756536)
		(width 0.14732)
		(layer "In4.Cu")
		(net "UPI_CPU1_CPU0_P1P0_DP<10>")
	)
	(segment
		(start 152.09393 -182.809642)
		(end 158.728664 -181.111144)
		(width 0.14732)
		(layer "In4.Cu")
		(net "UPI_CPU1_CPU0_P1P0_DP<10>")
	)
	(segment
		(start 346.286074 -212.042248)
		(end 346.327984 -212.084158)
		(width 0.0889)
		(layer "In4.Cu")
		(net "UPI_CPU1_CPU0_P1P0_DP<10>")
	)
	(segment
		(start 124.892308 -211.959952)
		(end 124.934472 -211.917788)
		(width 0.0889)
		(layer "In4.Cu")
		(net "UPI_CPU1_CPU0_P1P0_DP<10>")
	)
	(segment
		(start 346.327984 -213.410038)
		(end 346.327984 -213.930484)
		(width 0.0889)
		(layer "In4.Cu")
		(net "UPI_CPU1_CPU0_P1P0_DP<10>")
	)
	(segment
		(start 130.266948 -200.634346)
		(end 130.438398 -200.61682)
		(width 0.14732)
		(layer "In4.Cu")
		(net "UPI_CPU1_CPU0_P1P0_DP<10>")
	)
	(segment
		(start 129.991358 -200.973182)
		(end 130.266948 -200.634346)
		(width 0.14732)
		(layer "In4.Cu")
		(net "UPI_CPU1_CPU0_P1P0_DP<10>")
	)
	(segment
		(start 346.797376 -214.461344)
		(end 346.797376 -214.622634)
		(width 0.0889)
		(layer "In4.Cu")
		(net "UPI_CPU1_CPU0_P1P0_DP<10>")
	)
	(segment
		(start 346.610432 -217.554048)
		(end 346.611194 -217.554556)
		(width 0.0889)
		(layer "In4.Cu")
		(net "UPI_CPU1_CPU0_P1P0_DP<10>")
	)
	(segment
		(start 131.401566 -199.23887)
		(end 131.677156 -198.900034)
		(width 0.14732)
		(layer "In4.Cu")
		(net "UPI_CPU1_CPU0_P1P0_DP<10>")
	)
	(segment
		(start 345.297252 -200.245726)
		(end 347.07068 -204.52715)
		(width 0.14732)
		(layer "In4.Cu")
		(net "UPI_CPU1_CPU0_P1P0_DP<10>")
	)
	(segment
		(start 346.327984 -212.488018)
		(end 346.228924 -212.587078)
		(width 0.0889)
		(layer "In4.Cu")
		(net "UPI_CPU1_CPU0_P1P0_DP<10>")
	)
	(segment
		(start 139.629388 -192.816226)
		(end 143.995902 -186.955176)
		(width 0.14732)
		(layer "In4.Cu")
		(net "UPI_CPU1_CPU0_P1P0_DP<10>")
	)
	(segment
		(start 346.228924 -213.135718)
		(end 346.228924 -213.310978)
		(width 0.0889)
		(layer "In4.Cu")
		(net "UPI_CPU1_CPU0_P1P0_DP<10>")
	)
	(segment
		(start 346.610432 -216.574878)
		(end 346.606622 -216.577164)
		(width 0.0889)
		(layer "In4.Cu")
		(net "UPI_CPU1_CPU0_P1P0_DP<10>")
	)
	(segment
		(start 124.892562 -215.452198)
		(end 124.892562 -215.436704)
		(width 0.0889)
		(layer "In4.Cu")
		(net "UPI_CPU1_CPU0_P1P0_DP<10>")
	)
	(segment
		(start 346.32773 -215.414606)
		(end 346.32773 -215.436704)
		(width 0.0889)
		(layer "In4.Cu")
		(net "UPI_CPU1_CPU0_P1P0_DP<10>")
	)
	(segment
		(start 330.757784 -187.497212)
		(end 331.06106 -187.706254)
		(width 0.14732)
		(layer "In4.Cu")
		(net "UPI_CPU1_CPU0_P1P0_DP<10>")
	)
	(segment
		(start 329.568302 -186.500008)
		(end 330.7207 -187.295536)
		(width 0.14732)
		(layer "In4.Cu")
		(net "UPI_CPU1_CPU0_P1P0_DP<10>")
	)
	(segment
		(start 346.579698 -218.149424)
		(end 346.423234 -217.878406)
		(width 0.0889)
		(layer "In4.Cu")
		(net "UPI_CPU1_CPU0_P1P0_DP<10>")
	)
	(segment
		(start 346.619322 -216.569798)
		(end 346.610432 -216.574878)
		(width 0.0889)
		(layer "In4.Cu")
		(net "UPI_CPU1_CPU0_P1P0_DP<10>")
	)
	(segment
		(start 129.561844 -201.501502)
		(end 129.733294 -201.483976)
		(width 0.14732)
		(layer "In4.Cu")
		(net "UPI_CPU1_CPU0_P1P0_DP<10>")
	)
	(segment
		(start 346.327984 -212.861398)
		(end 346.327984 -213.036658)
		(width 0.0889)
		(layer "In4.Cu")
		(net "UPI_CPU1_CPU0_P1P0_DP<10>")
	)
	(segment
		(start 130.972052 -199.76719)
		(end 131.143502 -199.749664)
		(width 0.14732)
		(layer "In4.Cu")
		(net "UPI_CPU1_CPU0_P1P0_DP<10>")
	)
	(segment
		(start 337.808062 -192.756536)
		(end 345.297252 -200.245726)
		(width 0.14732)
		(layer "In4.Cu")
		(net "UPI_CPU1_CPU0_P1P0_DP<10>")
	)
	(segment
		(start 130.714242 -200.277476)
		(end 130.696462 -200.106026)
		(width 0.14732)
		(layer "In4.Cu")
		(net "UPI_CPU1_CPU0_P1P0_DP<10>")
	)
	(segment
		(start 329.36688 -186.536838)
		(end 329.568302 -186.500008)
		(width 0.14732)
		(layer "In4.Cu")
		(net "UPI_CPU1_CPU0_P1P0_DP<10>")
	)
	(segment
		(start 124.601478 -215.931242)
		(end 124.610368 -215.926162)
		(width 0.0889)
		(layer "In4.Cu")
		(net "UPI_CPU1_CPU0_P1P0_DP<10>")
	)
	(segment
		(start 130.438398 -200.61682)
		(end 130.714242 -200.277476)
		(width 0.14732)
		(layer "In4.Cu")
		(net "UPI_CPU1_CPU0_P1P0_DP<10>")
	)
	(segment
		(start 132.829554 -197.676008)
		(end 132.811774 -197.504558)
		(width 0.14732)
		(layer "In4.Cu")
		(net "UPI_CPU1_CPU0_P1P0_DP<10>")
	)
	(segment
		(start 124.934472 -211.846668)
		(end 125.198378 -211.209636)
		(width 0.14732)
		(layer "In4.Cu")
		(net "UPI_CPU1_CPU0_P1P0_DP<10>")
	)
	(segment
		(start 125.071124 -215.117426)
		(end 125.078998 -215.112854)
		(width 0.0889)
		(layer "In4.Cu")
		(net "UPI_CPU1_CPU0_P1P0_DP<10>")
	)
	(segment
		(start 129.286254 -201.840338)
		(end 129.561844 -201.501502)
		(width 0.14732)
		(layer "In4.Cu")
		(net "UPI_CPU1_CPU0_P1P0_DP<10>")
	)
	(segment
		(start 331.06106 -187.706254)
		(end 331.262482 -187.669424)
		(width 0.14732)
		(layer "In4.Cu")
		(net "UPI_CPU1_CPU0_P1P0_DP<10>")
	)
	(segment
		(start 179.73167 -180.762656)
		(end 200.734676 -180.413914)
		(width 0.14732)
		(layer "In4.Cu")
		(net "UPI_CPU1_CPU0_P1P0_DP<10>")
	)
	(segment
		(start 127.868426 -203.584048)
		(end 128.85674 -202.368658)
		(width 0.14732)
		(layer "In4.Cu")
		(net "UPI_CPU1_CPU0_P1P0_DP<10>")
	)
	(segment
		(start 346.606622 -216.577164)
		(end 346.602812 -216.579196)
		(width 0.0889)
		(layer "In4.Cu")
		(net "UPI_CPU1_CPU0_P1P0_DP<10>")
	)
	(segment
		(start 346.60967 -215.925654)
		(end 346.610432 -215.926162)
		(width 0.0889)
		(layer "In4.Cu")
		(net "UPI_CPU1_CPU0_P1P0_DP<10>")
	)
	(segment
		(start 125.078998 -215.112854)
		(end 125.080014 -215.112346)
		(width 0.0889)
		(layer "In4.Cu")
		(net "UPI_CPU1_CPU0_P1P0_DP<10>")
	)
	(segment
		(start 346.28582 -211.75472)
		(end 346.286074 -211.754974)
		(width 0.14732)
		(layer "In4.Cu")
		(net "UPI_CPU1_CPU0_P1P0_DP<10>")
	)
	(segment
		(start 346.602812 -216.579196)
		(end 346.59824 -216.58199)
		(width 0.0889)
		(layer "In4.Cu")
		(net "UPI_CPU1_CPU0_P1P0_DP<10>")
	)
	(segment
		(start 301.879508 -180.044344)
		(end 312.530744 -180.240178)
		(width 0.14732)
		(layer "In4.Cu")
		(net "UPI_CPU1_CPU0_P1P0_DP<10>")
	)
	(segment
		(start 129.304034 -202.011788)
		(end 129.286254 -201.840338)
		(width 0.14732)
		(layer "In4.Cu")
		(net "UPI_CPU1_CPU0_P1P0_DP<10>")
	)
	(segment
		(start 331.262482 -187.669424)
		(end 331.89926 -188.108844)
		(width 0.14732)
		(layer "In4.Cu")
		(net "UPI_CPU1_CPU0_P1P0_DP<10>")
	)
	(segment
		(start 128.85674 -202.368658)
		(end 129.02819 -202.351132)
		(width 0.14732)
		(layer "In4.Cu")
		(net "UPI_CPU1_CPU0_P1P0_DP<10>")
	)
	(segment
		(start 130.696462 -200.106026)
		(end 130.972052 -199.76719)
		(width 0.14732)
		(layer "In4.Cu")
		(net "UPI_CPU1_CPU0_P1P0_DP<10>")
	)
	(segment
		(start 132.12445 -198.543164)
		(end 132.10667 -198.371714)
		(width 0.14732)
		(layer "In4.Cu")
		(net "UPI_CPU1_CPU0_P1P0_DP<10>")
	)
	(segment
		(start 143.995902 -186.955176)
		(end 152.09393 -182.809642)
		(width 0.14732)
		(layer "In4.Cu")
		(net "UPI_CPU1_CPU0_P1P0_DP<10>")
	)
	(arc
		(start 125.070362 -214.080852)
		(mid 125.041052 -214.052504)
		(end 125.012704 -214.023194)
		(width 0.0889)
		(layer "In4.Cu")
		(net "UPI_CPU1_CPU0_P1P0_DP<10>")
	)
	(arc
		(start 124.91339 -213.882732)
		(mid 124.897669 -213.84069)
		(end 124.892308 -213.796118)
		(width 0.0889)
		(layer "In4.Cu")
		(net "UPI_CPU1_CPU0_P1P0_DP<10>")
	)
	(arc
		(start 346.609924 -214.946992)
		(mid 346.408642 -215.144479)
		(end 346.32773 -215.414606)
		(width 0.0889)
		(layer "In4.Cu")
		(net "UPI_CPU1_CPU0_P1P0_DP<10>")
	)
	(arc
		(start 346.797376 -214.622634)
		(mid 346.749697 -214.805534)
		(end 346.618814 -214.941912)
		(width 0.0889)
		(layer "In4.Cu")
		(net "UPI_CPU1_CPU0_P1P0_DP<10>")
	)
	(arc
		(start 346.797884 -217.878406)
		(mid 346.761024 -218.040203)
		(end 346.65793 -218.170252)
		(width 0.0889)
		(layer "In4.Cu")
		(net "UPI_CPU1_CPU0_P1P0_DP<10>")
	)
	(arc
		(start 124.681996 -217.50528)
		(mid 124.834503 -217.315182)
		(end 124.892816 -217.07856)
		(width 0.0889)
		(layer "In4.Cu")
		(net "UPI_CPU1_CPU0_P1P0_DP<10>")
	)
	(arc
		(start 125.012704 -214.023194)
		(mid 125.01245 -214.02294)
		(end 125.012196 -214.022686)
		(width 0.0889)
		(layer "In4.Cu")
		(net "UPI_CPU1_CPU0_P1P0_DP<10>")
	)
	(arc
		(start 125.116336 -214.115396)
		(mid 125.092514 -214.099235)
		(end 125.070362 -214.080852)
		(width 0.0889)
		(layer "In4.Cu")
		(net "UPI_CPU1_CPU0_P1P0_DP<10>")
	)
	(arc
		(start 346.327984 -213.930484)
		(mid 346.335269 -213.950046)
		(end 346.343224 -213.969346)
		(width 0.0889)
		(layer "In4.Cu")
		(net "UPI_CPU1_CPU0_P1P0_DP<10>")
	)
	(arc
		(start 125.012196 -214.022686)
		(mid 124.957972 -213.956112)
		(end 124.91339 -213.882732)
		(width 0.0889)
		(layer "In4.Cu")
		(net "UPI_CPU1_CPU0_P1P0_DP<10>")
	)
	(arc
		(start 124.665232 -217.518234)
		(mid 124.673675 -217.511836)
		(end 124.681996 -217.50528)
		(width 0.0889)
		(layer "In4.Cu")
		(net "UPI_CPU1_CPU0_P1P0_DP<10>")
	)
	(arc
		(start 346.32773 -215.436704)
		(mid 346.401721 -215.71627)
		(end 346.604336 -215.922606)
		(width 0.0889)
		(layer "In4.Cu")
		(net "UPI_CPU1_CPU0_P1P0_DP<10>")
	)
	(arc
		(start 125.080014 -215.112346)
		(mid 125.281296 -214.914859)
		(end 125.362208 -214.644732)
		(width 0.0889)
		(layer "In4.Cu")
		(net "UPI_CPU1_CPU0_P1P0_DP<10>")
	)
	(arc
		(start 124.892562 -215.436704)
		(mid 124.892614 -215.429337)
		(end 124.892816 -215.421972)
		(width 0.0889)
		(layer "In4.Cu")
		(net "UPI_CPU1_CPU0_P1P0_DP<10>")
	)
	(arc
		(start 124.601478 -216.569798)
		(mid 124.423002 -216.25052)
		(end 124.601478 -215.931242)
		(width 0.0889)
		(layer "In4.Cu")
		(net "UPI_CPU1_CPU0_P1P0_DP<10>")
	)
	(arc
		(start 346.619322 -217.559128)
		(mid 346.750236 -217.695488)
		(end 346.797884 -217.878406)
		(width 0.0889)
		(layer "In4.Cu")
		(net "UPI_CPU1_CPU0_P1P0_DP<10>")
	)
	(arc
		(start 124.892816 -217.064336)
		(mid 124.8189 -216.784834)
		(end 124.616464 -216.578434)
		(width 0.0889)
		(layer "In4.Cu")
		(net "UPI_CPU1_CPU0_P1P0_DP<10>")
	)
	(arc
		(start 346.343224 -213.969346)
		(mid 346.453218 -214.138715)
		(end 346.613226 -214.261954)
		(width 0.0889)
		(layer "In4.Cu")
		(net "UPI_CPU1_CPU0_P1P0_DP<10>")
	)
	(arc
		(start 124.892816 -215.421972)
		(mid 124.94387 -215.247392)
		(end 125.071124 -215.117426)
		(width 0.0889)
		(layer "In4.Cu")
		(net "UPI_CPU1_CPU0_P1P0_DP<10>")
	)
	(arc
		(start 346.619322 -215.931242)
		(mid 346.797919 -216.25052)
		(end 346.619322 -216.569798)
		(width 0.0889)
		(layer "In4.Cu")
		(net "UPI_CPU1_CPU0_P1P0_DP<10>")
	)
	(arc
		(start 346.59824 -216.58199)
		(mid 346.400012 -216.787838)
		(end 346.32773 -217.064336)
		(width 0.0889)
		(layer "In4.Cu")
		(net "UPI_CPU1_CPU0_P1P0_DP<10>")
	)
	(arc
		(start 346.613226 -214.261954)
		(mid 346.722373 -214.345882)
		(end 346.797376 -214.461344)
		(width 0.0889)
		(layer "In4.Cu")
		(net "UPI_CPU1_CPU0_P1P0_DP<10>")
	)
	(arc
		(start 124.610368 -215.926162)
		(mid 124.813191 -215.725931)
		(end 124.892562 -215.452198)
		(width 0.0889)
		(layer "In4.Cu")
		(net "UPI_CPU1_CPU0_P1P0_DP<10>")
	)
	(arc
		(start 346.32773 -217.071956)
		(mid 346.405359 -217.350369)
		(end 346.610432 -217.554048)
		(width 0.0889)
		(layer "In4.Cu")
		(net "UPI_CPU1_CPU0_P1P0_DP<10>")
	)
	(arc
		(start 125.362208 -214.424768)
		(mid 125.26553 -214.24921)
		(end 125.116336 -214.115396)
		(width 0.0889)
		(layer "In4.Cu")
		(net "UPI_CPU1_CPU0_P1P0_DP<10>")
	)
	(segment
		(start 337.495134 -218.692476)
		(end 337.49488 -218.692222)
		(width 0.13208)
		(layer "F.Cu")
		(net "UPI_CPU1_CPU0_P1P0_DP<0>")
	)
	(segment
		(start 337.495134 -219.228162)
		(end 337.495134 -218.692476)
		(width 0.13208)
		(layer "F.Cu")
		(net "UPI_CPU1_CPU0_P1P0_DP<0>")
	)
	(segment
		(start 133.725666 -217.600276)
		(end 133.725666 -217.06459)
		(width 0.13208)
		(layer "F.Cu")
		(net "UPI_CPU1_CPU0_P1P0_DP<0>")
	)
	(segment
		(start 133.725666 -217.06459)
		(end 133.725412 -217.064336)
		(width 0.13208)
		(layer "F.Cu")
		(net "UPI_CPU1_CPU0_P1P0_DP<0>")
	)
	(segment
		(start 149.164802 -200.735692)
		(end 149.372828 -200.734676)
		(width 0.14732)
		(layer "In4.Cu")
		(net "UPI_CPU1_CPU0_P1P0_DP<0>")
	)
	(segment
		(start 148.808694 -200.382378)
		(end 149.164802 -200.735692)
		(width 0.14732)
		(layer "In4.Cu")
		(net "UPI_CPU1_CPU0_P1P0_DP<0>")
	)
	(segment
		(start 135.802624 -213.829392)
		(end 135.818118 -213.813898)
		(width 0.0889)
		(layer "In4.Cu")
		(net "UPI_CPU1_CPU0_P1P0_DP<0>")
	)
	(segment
		(start 311.41162 -190.381128)
		(end 311.643014 -190.749682)
		(width 0.14732)
		(layer "In4.Cu")
		(net "UPI_CPU1_CPU0_P1P0_DP<0>")
	)
	(segment
		(start 150.440644 -198.736966)
		(end 150.796752 -199.090026)
		(width 0.14732)
		(layer "In4.Cu")
		(net "UPI_CPU1_CPU0_P1P0_DP<0>")
	)
	(segment
		(start 143.260064 -206.83601)
		(end 143.259556 -206.690468)
		(width 0.14732)
		(layer "In4.Cu")
		(net "UPI_CPU1_CPU0_P1P0_DP<0>")
	)
	(segment
		(start 337.162394 -211.463382)
		(end 337.162394 -211.69249)
		(width 0.14732)
		(layer "In4.Cu")
		(net "UPI_CPU1_CPU0_P1P0_DP<0>")
	)
	(segment
		(start 313.134502 -191.849756)
		(end 313.268868 -191.608202)
		(width 0.14732)
		(layer "In4.Cu")
		(net "UPI_CPU1_CPU0_P1P0_DP<0>")
	)
	(segment
		(start 337.162394 -211.714588)
		(end 337.12023 -211.756752)
		(width 0.0889)
		(layer "In4.Cu")
		(net "UPI_CPU1_CPU0_P1P0_DP<0>")
	)
	(segment
		(start 299.983906 -190.483998)
		(end 300.260512 -190.147956)
		(width 0.14732)
		(layer "In4.Cu")
		(net "UPI_CPU1_CPU0_P1P0_DP<0>")
	)
	(segment
		(start 142.903448 -206.337662)
		(end 142.90167 -205.939136)
		(width 0.14732)
		(layer "In4.Cu")
		(net "UPI_CPU1_CPU0_P1P0_DP<0>")
	)
	(segment
		(start 145.544794 -203.673964)
		(end 145.900902 -204.027024)
		(width 0.14732)
		(layer "In4.Cu")
		(net "UPI_CPU1_CPU0_P1P0_DP<0>")
	)
	(segment
		(start 147.176744 -202.028298)
		(end 147.532852 -202.381358)
		(width 0.14732)
		(layer "In4.Cu")
		(net "UPI_CPU1_CPU0_P1P0_DP<0>")
	)
	(segment
		(start 312.470038 -191.64808)
		(end 312.93435 -191.906652)
		(width 0.14732)
		(layer "In4.Cu")
		(net "UPI_CPU1_CPU0_P1P0_DP<0>")
	)
	(segment
		(start 150.005542 -198.738744)
		(end 150.440644 -198.736966)
		(width 0.14732)
		(layer "In4.Cu")
		(net "UPI_CPU1_CPU0_P1P0_DP<0>")
	)
	(segment
		(start 330.957428 -198.238364)
		(end 331.940916 -198.60514)
		(width 0.14732)
		(layer "In4.Cu")
		(net "UPI_CPU1_CPU0_P1P0_DP<0>")
	)
	(segment
		(start 134.370572 -216.58199)
		(end 134.372604 -216.58072)
		(width 0.0889)
		(layer "In4.Cu")
		(net "UPI_CPU1_CPU0_P1P0_DP<0>")
	)
	(segment
		(start 135.79221 -215.761062)
		(end 135.807196 -215.752426)
		(width 0.0889)
		(layer "In4.Cu")
		(net "UPI_CPU1_CPU0_P1P0_DP<0>")
	)
	(segment
		(start 149.431248 -199.754744)
		(end 149.42947 -199.319642)
		(width 0.14732)
		(layer "In4.Cu")
		(net "UPI_CPU1_CPU0_P1P0_DP<0>")
	)
	(segment
		(start 143.260572 -206.981806)
		(end 143.260064 -206.83601)
		(width 0.14732)
		(layer "In4.Cu")
		(net "UPI_CPU1_CPU0_P1P0_DP<0>")
	)
	(segment
		(start 298.001944 -191.333882)
		(end 299.900594 -191.149478)
		(width 0.14732)
		(layer "In4.Cu")
		(net "UPI_CPU1_CPU0_P1P0_DP<0>")
	)
	(segment
		(start 310.614314 -190.198502)
		(end 311.41162 -190.381128)
		(width 0.14732)
		(layer "In4.Cu")
		(net "UPI_CPU1_CPU0_P1P0_DP<0>")
	)
	(segment
		(start 337.307682 -215.112346)
		(end 337.306666 -215.112854)
		(width 0.0889)
		(layer "In4.Cu")
		(net "UPI_CPU1_CPU0_P1P0_DP<0>")
	)
	(segment
		(start 142.267686 -207.982566)
		(end 143.260572 -206.981806)
		(width 0.14732)
		(layer "In4.Cu")
		(net "UPI_CPU1_CPU0_P1P0_DP<0>")
	)
	(segment
		(start 314.386976 -192.546986)
		(end 314.443872 -192.746884)
		(width 0.14732)
		(layer "In4.Cu")
		(net "UPI_CPU1_CPU0_P1P0_DP<0>")
	)
	(segment
		(start 135.322564 -216.574878)
		(end 135.331454 -216.569798)
		(width 0.0889)
		(layer "In4.Cu")
		(net "UPI_CPU1_CPU0_P1P0_DP<0>")
	)
	(segment
		(start 305.175158 -190.63843)
		(end 308.043326 -190.7286)
		(width 0.14732)
		(layer "In4.Cu")
		(net "UPI_CPU1_CPU0_P1P0_DP<0>")
	)
	(segment
		(start 151.637492 -197.093078)
		(end 152.072594 -197.0913)
		(width 0.14732)
		(layer "In4.Cu")
		(net "UPI_CPU1_CPU0_P1P0_DP<0>")
	)
	(segment
		(start 147.799298 -201.40041)
		(end 147.79752 -200.965308)
		(width 0.14732)
		(layer "In4.Cu")
		(net "UPI_CPU1_CPU0_P1P0_DP<0>")
	)
	(segment
		(start 146.167348 -203.046076)
		(end 146.16557 -202.610974)
		(width 0.14732)
		(layer "In4.Cu")
		(net "UPI_CPU1_CPU0_P1P0_DP<0>")
	)
	(segment
		(start 314.402216 -191.887094)
		(end 314.521342 -192.305432)
		(width 0.14732)
		(layer "In4.Cu")
		(net "UPI_CPU1_CPU0_P1P0_DP<0>")
	)
	(segment
		(start 301.620428 -190.983108)
		(end 305.175158 -190.63843)
		(width 0.14732)
		(layer "In4.Cu")
		(net "UPI_CPU1_CPU0_P1P0_DP<0>")
	)
	(segment
		(start 133.881876 -217.335354)
		(end 133.960108 -217.356182)
		(width 0.0889)
		(layer "In4.Cu")
		(net "UPI_CPU1_CPU0_P1P0_DP<0>")
	)
	(segment
		(start 337.590384 -217.859864)
		(end 337.590384 -217.878406)
		(width 0.0889)
		(layer "In4.Cu")
		(net "UPI_CPU1_CPU0_P1P0_DP<0>")
	)
	(segment
		(start 135.818118 -213.813898)
		(end 140.750036 -208.84261)
		(width 0.14732)
		(layer "In4.Cu")
		(net "UPI_CPU1_CPU0_P1P0_DP<0>")
	)
	(segment
		(start 337.307936 -216.739978)
		(end 337.307174 -216.740486)
		(width 0.0889)
		(layer "In4.Cu")
		(net "UPI_CPU1_CPU0_P1P0_DP<0>")
	)
	(segment
		(start 337.12023 -211.756752)
		(end 337.12023 -213.8934)
		(width 0.0889)
		(layer "In4.Cu")
		(net "UPI_CPU1_CPU0_P1P0_DP<0>")
	)
	(segment
		(start 142.90167 -205.939136)
		(end 143.514572 -205.321154)
		(width 0.14732)
		(layer "In4.Cu")
		(net "UPI_CPU1_CPU0_P1P0_DP<0>")
	)
	(segment
		(start 335.911698 -209.10423)
		(end 336.347562 -209.10423)
		(width 0.14732)
		(layer "In4.Cu")
		(net "UPI_CPU1_CPU0_P1P0_DP<0>")
	)
	(segment
		(start 135.979916 -215.436704)
		(end 135.979916 -215.276176)
		(width 0.0889)
		(layer "In4.Cu")
		(net "UPI_CPU1_CPU0_P1P0_DP<0>")
	)
	(segment
		(start 133.725412 -217.064336)
		(end 133.881876 -217.335354)
		(width 0.0889)
		(layer "In4.Cu")
		(net "UPI_CPU1_CPU0_P1P0_DP<0>")
	)
	(segment
		(start 143.913098 -205.31963)
		(end 144.268952 -205.67269)
		(width 0.14732)
		(layer "In4.Cu")
		(net "UPI_CPU1_CPU0_P1P0_DP<0>")
	)
	(segment
		(start 286.4993 -191.284352)
		(end 286.505396 -191.284352)
		(width 0.14732)
		(layer "In4.Cu")
		(net "UPI_CPU1_CPU0_P1P0_DP<0>")
	)
	(segment
		(start 337.306666 -215.112854)
		(end 337.298792 -215.117426)
		(width 0.0889)
		(layer "In4.Cu")
		(net "UPI_CPU1_CPU0_P1P0_DP<0>")
	)
	(segment
		(start 189.991492 -191.885824)
		(end 208.370932 -191.14262)
		(width 0.14732)
		(layer "In4.Cu")
		(net "UPI_CPU1_CPU0_P1P0_DP<0>")
	)
	(segment
		(start 235.95711 -200.531476)
		(end 237.398052 -200.531476)
		(width 0.14732)
		(layer "In4.Cu")
		(net "UPI_CPU1_CPU0_P1P0_DP<0>")
	)
	(segment
		(start 135.509762 -214.182198)
		(end 135.802624 -213.889336)
		(width 0.0889)
		(layer "In4.Cu")
		(net "UPI_CPU1_CPU0_P1P0_DP<0>")
	)
	(segment
		(start 135.509762 -214.744046)
		(end 135.509762 -214.182198)
		(width 0.0889)
		(layer "In4.Cu")
		(net "UPI_CPU1_CPU0_P1P0_DP<0>")
	)
	(segment
		(start 308.044088 -190.729362)
		(end 308.04485 -190.729362)
		(width 0.14732)
		(layer "In4.Cu")
		(net "UPI_CPU1_CPU0_P1P0_DP<0>")
	)
	(segment
		(start 313.268868 -191.608202)
		(end 313.687206 -191.489076)
		(width 0.14732)
		(layer "In4.Cu")
		(net "UPI_CPU1_CPU0_P1P0_DP<0>")
	)
	(segment
		(start 148.373592 -200.38441)
		(end 148.808694 -200.382378)
		(width 0.14732)
		(layer "In4.Cu")
		(net "UPI_CPU1_CPU0_P1P0_DP<0>")
	)
	(segment
		(start 143.514572 -205.321154)
		(end 143.913098 -205.31963)
		(width 0.14732)
		(layer "In4.Cu")
		(net "UPI_CPU1_CPU0_P1P0_DP<0>")
	)
	(segment
		(start 208.370932 -191.14262)
		(end 220.074744 -193.032126)
		(width 0.14732)
		(layer "In4.Cu")
		(net "UPI_CPU1_CPU0_P1P0_DP<0>")
	)
	(segment
		(start 337.338416 -218.421204)
		(end 337.49488 -218.692222)
		(width 0.0889)
		(layer "In4.Cu")
		(net "UPI_CPU1_CPU0_P1P0_DP<0>")
	)
	(segment
		(start 239.312958 -200.292462)
		(end 250.623832 -195.116196)
		(width 0.14732)
		(layer "In4.Cu")
		(net "UPI_CPU1_CPU0_P1P0_DP<0>")
	)
	(segment
		(start 337.306158 -215.7603)
		(end 337.307682 -215.761062)
		(width 0.0889)
		(layer "In4.Cu")
		(net "UPI_CPU1_CPU0_P1P0_DP<0>")
	)
	(segment
		(start 150.796752 -199.090026)
		(end 151.004778 -199.089264)
		(width 0.14732)
		(layer "In4.Cu")
		(net "UPI_CPU1_CPU0_P1P0_DP<0>")
	)
	(segment
		(start 156.553154 -192.898776)
		(end 157.775148 -192.278)
		(width 0.14732)
		(layer "In4.Cu")
		(net "UPI_CPU1_CPU0_P1P0_DP<0>")
	)
	(segment
		(start 314.521342 -192.305432)
		(end 314.386976 -192.546986)
		(width 0.14732)
		(layer "In4.Cu")
		(net "UPI_CPU1_CPU0_P1P0_DP<0>")
	)
	(segment
		(start 310.124348 -190.960248)
		(end 310.24576 -190.429896)
		(width 0.14732)
		(layer "In4.Cu")
		(net "UPI_CPU1_CPU0_P1P0_DP<0>")
	)
	(segment
		(start 237.398052 -200.531476)
		(end 239.312958 -200.292462)
		(width 0.14732)
		(layer "In4.Cu")
		(net "UPI_CPU1_CPU0_P1P0_DP<0>")
	)
	(segment
		(start 151.420068 -198.670164)
		(end 151.419306 -198.462138)
		(width 0.14732)
		(layer "In4.Cu")
		(net "UPI_CPU1_CPU0_P1P0_DP<0>")
	)
	(segment
		(start 140.750798 -208.84261)
		(end 141.130274 -208.459832)
		(width 0.14732)
		(layer "In4.Cu")
		(net "UPI_CPU1_CPU0_P1P0_DP<0>")
	)
	(segment
		(start 145.900902 -204.027024)
		(end 146.108928 -204.026262)
		(width 0.14732)
		(layer "In4.Cu")
		(net "UPI_CPU1_CPU0_P1P0_DP<0>")
	)
	(segment
		(start 337.307174 -216.740486)
		(end 337.302094 -216.74328)
		(width 0.0889)
		(layer "In4.Cu")
		(net "UPI_CPU1_CPU0_P1P0_DP<0>")
	)
	(segment
		(start 144.268952 -205.67269)
		(end 144.477232 -205.671674)
		(width 0.14732)
		(layer "In4.Cu")
		(net "UPI_CPU1_CPU0_P1P0_DP<0>")
	)
	(segment
		(start 311.643014 -190.749682)
		(end 311.521602 -191.280034)
		(width 0.14732)
		(layer "In4.Cu")
		(net "UPI_CPU1_CPU0_P1P0_DP<0>")
	)
	(segment
		(start 312.93435 -191.906652)
		(end 313.134502 -191.849756)
		(width 0.14732)
		(layer "In4.Cu")
		(net "UPI_CPU1_CPU0_P1P0_DP<0>")
	)
	(segment
		(start 232.663238 -199.71131)
		(end 235.95711 -200.531476)
		(width 0.14732)
		(layer "In4.Cu")
		(net "UPI_CPU1_CPU0_P1P0_DP<0>")
	)
	(segment
		(start 308.043326 -190.7286)
		(end 308.044088 -190.729362)
		(width 0.14732)
		(layer "In4.Cu")
		(net "UPI_CPU1_CPU0_P1P0_DP<0>")
	)
	(segment
		(start 149.788118 -200.315576)
		(end 149.787356 -200.107804)
		(width 0.14732)
		(layer "In4.Cu")
		(net "UPI_CPU1_CPU0_P1P0_DP<0>")
	)
	(segment
		(start 148.155406 -201.75347)
		(end 147.799298 -201.40041)
		(width 0.14732)
		(layer "In4.Cu")
		(net "UPI_CPU1_CPU0_P1P0_DP<0>")
	)
	(segment
		(start 309.948072 -191.070992)
		(end 310.124348 -190.960248)
		(width 0.14732)
		(layer "In4.Cu")
		(net "UPI_CPU1_CPU0_P1P0_DP<0>")
	)
	(segment
		(start 313.687206 -191.489076)
		(end 314.402216 -191.887094)
		(width 0.14732)
		(layer "In4.Cu")
		(net "UPI_CPU1_CPU0_P1P0_DP<0>")
	)
	(segment
		(start 301.459646 -190.85052)
		(end 301.620428 -190.983108)
		(width 0.14732)
		(layer "In4.Cu")
		(net "UPI_CPU1_CPU0_P1P0_DP<0>")
	)
	(segment
		(start 331.940916 -198.60514)
		(end 332.834742 -199.308212)
		(width 0.14732)
		(layer "In4.Cu")
		(net "UPI_CPU1_CPU0_P1P0_DP<0>")
	)
	(segment
		(start 147.740878 -202.380342)
		(end 148.156168 -201.961242)
		(width 0.14732)
		(layer "In4.Cu")
		(net "UPI_CPU1_CPU0_P1P0_DP<0>")
	)
	(segment
		(start 337.302094 -216.74328)
		(end 337.299046 -216.745058)
		(width 0.0889)
		(layer "In4.Cu")
		(net "UPI_CPU1_CPU0_P1P0_DP<0>")
	)
	(segment
		(start 336.347562 -209.10423)
		(end 337.16214 -209.918808)
		(width 0.14732)
		(layer "In4.Cu")
		(net "UPI_CPU1_CPU0_P1P0_DP<0>")
	)
	(segment
		(start 141.130274 -208.459832)
		(end 142.267686 -207.982566)
		(width 0.14732)
		(layer "In4.Cu")
		(net "UPI_CPU1_CPU0_P1P0_DP<0>")
	)
	(segment
		(start 299.900594 -191.149478)
		(end 300.032928 -190.98895)
		(width 0.14732)
		(layer "In4.Cu")
		(net "UPI_CPU1_CPU0_P1P0_DP<0>")
	)
	(segment
		(start 337.590384 -216.25052)
		(end 337.590384 -216.260426)
		(width 0.0889)
		(layer "In4.Cu")
		(net "UPI_CPU1_CPU0_P1P0_DP<0>")
	)
	(segment
		(start 146.524218 -203.607162)
		(end 146.523456 -203.399136)
		(width 0.14732)
		(layer "In4.Cu")
		(net "UPI_CPU1_CPU0_P1P0_DP<0>")
	)
	(segment
		(start 144.535398 -204.691742)
		(end 144.53362 -204.25664)
		(width 0.14732)
		(layer "In4.Cu")
		(net "UPI_CPU1_CPU0_P1P0_DP<0>")
	)
	(segment
		(start 144.477232 -205.671674)
		(end 144.892268 -205.253082)
		(width 0.14732)
		(layer "In4.Cu")
		(net "UPI_CPU1_CPU0_P1P0_DP<0>")
	)
	(segment
		(start 149.42947 -199.319642)
		(end 150.005542 -198.738744)
		(width 0.14732)
		(layer "In4.Cu")
		(net "UPI_CPU1_CPU0_P1P0_DP<0>")
	)
	(segment
		(start 334.726026 -210.08213)
		(end 334.933798 -210.08213)
		(width 0.14732)
		(layer "In4.Cu")
		(net "UPI_CPU1_CPU0_P1P0_DP<0>")
	)
	(segment
		(start 157.775148 -192.278)
		(end 159.967422 -191.483996)
		(width 0.14732)
		(layer "In4.Cu")
		(net "UPI_CPU1_CPU0_P1P0_DP<0>")
	)
	(segment
		(start 146.523456 -203.399136)
		(end 146.167348 -203.046076)
		(width 0.14732)
		(layer "In4.Cu")
		(net "UPI_CPU1_CPU0_P1P0_DP<0>")
	)
	(segment
		(start 159.967422 -191.483996)
		(end 189.991492 -191.885824)
		(width 0.14732)
		(layer "In4.Cu")
		(net "UPI_CPU1_CPU0_P1P0_DP<0>")
	)
	(segment
		(start 152.428702 -197.44436)
		(end 152.636728 -197.443598)
		(width 0.14732)
		(layer "In4.Cu")
		(net "UPI_CPU1_CPU0_P1P0_DP<0>")
	)
	(segment
		(start 337.362546 -218.33205)
		(end 337.338416 -218.421204)
		(width 0.0889)
		(layer "In4.Cu")
		(net "UPI_CPU1_CPU0_P1P0_DP<0>")
	)
	(segment
		(start 143.259556 -206.690468)
		(end 142.903448 -206.337662)
		(width 0.14732)
		(layer "In4.Cu")
		(net "UPI_CPU1_CPU0_P1P0_DP<0>")
	)
	(segment
		(start 334.933798 -210.08213)
		(end 335.911698 -209.10423)
		(width 0.14732)
		(layer "In4.Cu")
		(net "UPI_CPU1_CPU0_P1P0_DP<0>")
	)
	(segment
		(start 334.308196 -209.456528)
		(end 334.308196 -209.6643)
		(width 0.14732)
		(layer "In4.Cu")
		(net "UPI_CPU1_CPU0_P1P0_DP<0>")
	)
	(segment
		(start 144.892268 -205.253082)
		(end 144.891506 -205.044802)
		(width 0.14732)
		(layer "In4.Cu")
		(net "UPI_CPU1_CPU0_P1P0_DP<0>")
	)
	(segment
		(start 149.787356 -200.107804)
		(end 149.431248 -199.754744)
		(width 0.14732)
		(layer "In4.Cu")
		(net "UPI_CPU1_CPU0_P1P0_DP<0>")
	)
	(segment
		(start 152.072594 -197.0913)
		(end 152.428702 -197.44436)
		(width 0.14732)
		(layer "In4.Cu")
		(net "UPI_CPU1_CPU0_P1P0_DP<0>")
	)
	(segment
		(start 337.307682 -215.761062)
		(end 337.310476 -215.762586)
		(width 0.0889)
		(layer "In4.Cu")
		(net "UPI_CPU1_CPU0_P1P0_DP<0>")
	)
	(segment
		(start 300.260512 -190.147956)
		(end 301.074582 -190.068962)
		(width 0.14732)
		(layer "In4.Cu")
		(net "UPI_CPU1_CPU0_P1P0_DP<0>")
	)
	(segment
		(start 314.443872 -192.746884)
		(end 315.151262 -193.140584)
		(width 0.14732)
		(layer "In4.Cu")
		(net "UPI_CPU1_CPU0_P1P0_DP<0>")
	)
	(segment
		(start 220.074744 -193.032126)
		(end 232.663238 -199.71131)
		(width 0.14732)
		(layer "In4.Cu")
		(net "UPI_CPU1_CPU0_P1P0_DP<0>")
	)
	(segment
		(start 154.829764 -194.637406)
		(end 156.553154 -192.898776)
		(width 0.14732)
		(layer "In4.Cu")
		(net "UPI_CPU1_CPU0_P1P0_DP<0>")
	)
	(segment
		(start 135.802624 -213.889336)
		(end 135.802624 -213.829392)
		(width 0.0889)
		(layer "In4.Cu")
		(net "UPI_CPU1_CPU0_P1P0_DP<0>")
	)
	(segment
		(start 250.623832 -195.116196)
		(end 261.206996 -192.292986)
		(width 0.14732)
		(layer "In4.Cu")
		(net "UPI_CPU1_CPU0_P1P0_DP<0>")
	)
	(segment
		(start 144.891506 -205.044802)
		(end 144.535398 -204.691742)
		(width 0.14732)
		(layer "In4.Cu")
		(net "UPI_CPU1_CPU0_P1P0_DP<0>")
	)
	(segment
		(start 335.286096 -208.478628)
		(end 334.308196 -209.456528)
		(width 0.14732)
		(layer "In4.Cu")
		(net "UPI_CPU1_CPU0_P1P0_DP<0>")
	)
	(segment
		(start 134.372604 -216.58072)
		(end 134.382764 -216.574878)
		(width 0.0889)
		(layer "In4.Cu")
		(net "UPI_CPU1_CPU0_P1P0_DP<0>")
	)
	(segment
		(start 301.410624 -190.345568)
		(end 301.459646 -190.85052)
		(width 0.14732)
		(layer "In4.Cu")
		(net "UPI_CPU1_CPU0_P1P0_DP<0>")
	)
	(segment
		(start 135.510016 -216.25052)
		(end 135.510016 -216.235026)
		(width 0.0889)
		(layer "In4.Cu")
		(net "UPI_CPU1_CPU0_P1P0_DP<0>")
	)
	(segment
		(start 337.310476 -215.762586)
		(end 337.313778 -215.764618)
		(width 0.0889)
		(layer "In4.Cu")
		(net "UPI_CPU1_CPU0_P1P0_DP<0>")
	)
	(segment
		(start 335.286096 -208.042764)
		(end 335.286096 -208.478628)
		(width 0.14732)
		(layer "In4.Cu")
		(net "UPI_CPU1_CPU0_P1P0_DP<0>")
	)
	(segment
		(start 145.109692 -203.675742)
		(end 145.544794 -203.673964)
		(width 0.14732)
		(layer "In4.Cu")
		(net "UPI_CPU1_CPU0_P1P0_DP<0>")
	)
	(segment
		(start 310.24576 -190.429896)
		(end 310.614314 -190.198502)
		(width 0.14732)
		(layer "In4.Cu")
		(net "UPI_CPU1_CPU0_P1P0_DP<0>")
	)
	(segment
		(start 334.308196 -209.6643)
		(end 334.726026 -210.08213)
		(width 0.14732)
		(layer "In4.Cu")
		(net "UPI_CPU1_CPU0_P1P0_DP<0>")
	)
	(segment
		(start 315.151262 -193.140584)
		(end 330.957428 -198.238364)
		(width 0.14732)
		(layer "In4.Cu")
		(net "UPI_CPU1_CPU0_P1P0_DP<0>")
	)
	(segment
		(start 337.16214 -211.463128)
		(end 337.162394 -211.463382)
		(width 0.14732)
		(layer "In4.Cu")
		(net "UPI_CPU1_CPU0_P1P0_DP<0>")
	)
	(segment
		(start 147.79752 -200.965308)
		(end 148.373592 -200.38441)
		(width 0.14732)
		(layer "In4.Cu")
		(net "UPI_CPU1_CPU0_P1P0_DP<0>")
	)
	(segment
		(start 147.532852 -202.381358)
		(end 147.740878 -202.380342)
		(width 0.14732)
		(layer "In4.Cu")
		(net "UPI_CPU1_CPU0_P1P0_DP<0>")
	)
	(segment
		(start 148.156168 -201.961242)
		(end 148.155406 -201.75347)
		(width 0.14732)
		(layer "In4.Cu")
		(net "UPI_CPU1_CPU0_P1P0_DP<0>")
	)
	(segment
		(start 337.589876 -214.424768)
		(end 337.589876 -214.644732)
		(width 0.0889)
		(layer "In4.Cu")
		(net "UPI_CPU1_CPU0_P1P0_DP<0>")
	)
	(segment
		(start 151.004778 -199.089264)
		(end 151.420068 -198.670164)
		(width 0.14732)
		(layer "In4.Cu")
		(net "UPI_CPU1_CPU0_P1P0_DP<0>")
	)
	(segment
		(start 149.372828 -200.734676)
		(end 149.788118 -200.315576)
		(width 0.14732)
		(layer "In4.Cu")
		(net "UPI_CPU1_CPU0_P1P0_DP<0>")
	)
	(segment
		(start 309.00497 -190.855346)
		(end 309.948072 -191.070992)
		(width 0.14732)
		(layer "In4.Cu")
		(net "UPI_CPU1_CPU0_P1P0_DP<0>")
	)
	(segment
		(start 144.53362 -204.25664)
		(end 145.109692 -203.675742)
		(width 0.14732)
		(layer "In4.Cu")
		(net "UPI_CPU1_CPU0_P1P0_DP<0>")
	)
	(segment
		(start 152.636728 -197.443598)
		(end 154.416252 -195.648072)
		(width 0.14732)
		(layer "In4.Cu")
		(net "UPI_CPU1_CPU0_P1P0_DP<0>")
	)
	(segment
		(start 308.04485 -190.729362)
		(end 309.00497 -190.855346)
		(width 0.14732)
		(layer "In4.Cu")
		(net "UPI_CPU1_CPU0_P1P0_DP<0>")
	)
	(segment
		(start 146.741642 -202.030076)
		(end 147.176744 -202.028298)
		(width 0.14732)
		(layer "In4.Cu")
		(net "UPI_CPU1_CPU0_P1P0_DP<0>")
	)
	(segment
		(start 286.505396 -191.284352)
		(end 298.001944 -191.333882)
		(width 0.14732)
		(layer "In4.Cu")
		(net "UPI_CPU1_CPU0_P1P0_DP<0>")
	)
	(segment
		(start 151.419306 -198.462138)
		(end 151.063198 -198.109078)
		(width 0.14732)
		(layer "In4.Cu")
		(net "UPI_CPU1_CPU0_P1P0_DP<0>")
	)
	(segment
		(start 337.16214 -209.918808)
		(end 337.16214 -211.463128)
		(width 0.14732)
		(layer "In4.Cu")
		(net "UPI_CPU1_CPU0_P1P0_DP<0>")
	)
	(segment
		(start 337.298792 -215.755982)
		(end 337.306158 -215.7603)
		(width 0.0889)
		(layer "In4.Cu")
		(net "UPI_CPU1_CPU0_P1P0_DP<0>")
	)
	(segment
		(start 151.06142 -197.673976)
		(end 151.637492 -197.093078)
		(width 0.14732)
		(layer "In4.Cu")
		(net "UPI_CPU1_CPU0_P1P0_DP<0>")
	)
	(segment
		(start 311.632346 -191.45631)
		(end 312.470038 -191.64808)
		(width 0.14732)
		(layer "In4.Cu")
		(net "UPI_CPU1_CPU0_P1P0_DP<0>")
	)
	(segment
		(start 146.108928 -204.026262)
		(end 146.524218 -203.607162)
		(width 0.14732)
		(layer "In4.Cu")
		(net "UPI_CPU1_CPU0_P1P0_DP<0>")
	)
	(segment
		(start 332.834742 -199.308212)
		(end 334.36814 -200.841864)
		(width 0.14732)
		(layer "In4.Cu")
		(net "UPI_CPU1_CPU0_P1P0_DP<0>")
	)
	(segment
		(start 140.750036 -208.84261)
		(end 140.750798 -208.84261)
		(width 0.14732)
		(layer "In4.Cu")
		(net "UPI_CPU1_CPU0_P1P0_DP<0>")
	)
	(segment
		(start 301.074582 -190.068962)
		(end 301.410624 -190.345568)
		(width 0.14732)
		(layer "In4.Cu")
		(net "UPI_CPU1_CPU0_P1P0_DP<0>")
	)
	(segment
		(start 146.16557 -202.610974)
		(end 146.741642 -202.030076)
		(width 0.14732)
		(layer "In4.Cu")
		(net "UPI_CPU1_CPU0_P1P0_DP<0>")
	)
	(segment
		(start 261.206996 -192.292986)
		(end 286.4993 -191.284352)
		(width 0.14732)
		(layer "In4.Cu")
		(net "UPI_CPU1_CPU0_P1P0_DP<0>")
	)
	(segment
		(start 154.416252 -195.648072)
		(end 154.829764 -194.637406)
		(width 0.14732)
		(layer "In4.Cu")
		(net "UPI_CPU1_CPU0_P1P0_DP<0>")
	)
	(segment
		(start 337.299046 -217.383614)
		(end 337.307936 -217.388694)
		(width 0.0889)
		(layer "In4.Cu")
		(net "UPI_CPU1_CPU0_P1P0_DP<0>")
	)
	(segment
		(start 337.162394 -211.69249)
		(end 337.162394 -211.714588)
		(width 0.0889)
		(layer "In4.Cu")
		(net "UPI_CPU1_CPU0_P1P0_DP<0>")
	)
	(segment
		(start 311.521602 -191.280034)
		(end 311.632346 -191.45631)
		(width 0.14732)
		(layer "In4.Cu")
		(net "UPI_CPU1_CPU0_P1P0_DP<0>")
	)
	(segment
		(start 300.032928 -190.98895)
		(end 299.983906 -190.483998)
		(width 0.14732)
		(layer "In4.Cu")
		(net "UPI_CPU1_CPU0_P1P0_DP<0>")
	)
	(segment
		(start 151.063198 -198.109078)
		(end 151.06142 -197.673976)
		(width 0.14732)
		(layer "In4.Cu")
		(net "UPI_CPU1_CPU0_P1P0_DP<0>")
	)
	(segment
		(start 337.12023 -213.8934)
		(end 337.120484 -213.893908)
		(width 0.0889)
		(layer "In4.Cu")
		(net "UPI_CPU1_CPU0_P1P0_DP<0>")
	)
	(segment
		(start 334.36814 -200.841864)
		(end 334.36814 -207.124808)
		(width 0.14732)
		(layer "In4.Cu")
		(net "UPI_CPU1_CPU0_P1P0_DP<0>")
	)
	(segment
		(start 334.36814 -207.124808)
		(end 335.286096 -208.042764)
		(width 0.14732)
		(layer "In4.Cu")
		(net "UPI_CPU1_CPU0_P1P0_DP<0>")
	)
	(arc
		(start 337.298792 -215.117426)
		(mid 337.171538 -215.247392)
		(end 337.120484 -215.421972)
		(width 0.0889)
		(layer "In4.Cu")
		(net "UPI_CPU1_CPU0_P1P0_DP<0>")
	)
	(arc
		(start 337.589876 -214.644732)
		(mid 337.508965 -214.91486)
		(end 337.307682 -215.112346)
		(width 0.0889)
		(layer "In4.Cu")
		(net "UPI_CPU1_CPU0_P1P0_DP<0>")
	)
	(arc
		(start 337.590384 -217.878406)
		(mid 337.535029 -218.122593)
		(end 337.379564 -218.318842)
		(width 0.0889)
		(layer "In4.Cu")
		(net "UPI_CPU1_CPU0_P1P0_DP<0>")
	)
	(arc
		(start 337.120484 -215.421972)
		(mid 337.120287 -215.429337)
		(end 337.12023 -215.436704)
		(width 0.0889)
		(layer "In4.Cu")
		(net "UPI_CPU1_CPU0_P1P0_DP<0>")
	)
	(arc
		(start 134.382764 -216.574878)
		(mid 134.665466 -216.499102)
		(end 134.948168 -216.574878)
		(width 0.0889)
		(layer "In4.Cu")
		(net "UPI_CPU1_CPU0_P1P0_DP<0>")
	)
	(arc
		(start 135.807196 -215.752426)
		(mid 135.933919 -215.616645)
		(end 135.979916 -215.436704)
		(width 0.0889)
		(layer "In4.Cu")
		(net "UPI_CPU1_CPU0_P1P0_DP<0>")
	)
	(arc
		(start 135.525002 -214.783416)
		(mid 135.517038 -214.763864)
		(end 135.509762 -214.744046)
		(width 0.0889)
		(layer "In4.Cu")
		(net "UPI_CPU1_CPU0_P1P0_DP<0>")
	)
	(arc
		(start 135.510016 -216.235026)
		(mid 135.589386 -215.961292)
		(end 135.79221 -215.761062)
		(width 0.0889)
		(layer "In4.Cu")
		(net "UPI_CPU1_CPU0_P1P0_DP<0>")
	)
	(arc
		(start 133.960108 -217.356182)
		(mid 134.063253 -217.226157)
		(end 134.100062 -217.064336)
		(width 0.0889)
		(layer "In4.Cu")
		(net "UPI_CPU1_CPU0_P1P0_DP<0>")
	)
	(arc
		(start 134.948168 -216.574878)
		(mid 135.135366 -216.625021)
		(end 135.322564 -216.574878)
		(width 0.0889)
		(layer "In4.Cu")
		(net "UPI_CPU1_CPU0_P1P0_DP<0>")
	)
	(arc
		(start 337.304634 -214.093298)
		(mid 337.478597 -214.232062)
		(end 337.589876 -214.424768)
		(width 0.0889)
		(layer "In4.Cu")
		(net "UPI_CPU1_CPU0_P1P0_DP<0>")
	)
	(arc
		(start 337.379564 -218.318842)
		(mid 337.371118 -218.325527)
		(end 337.362546 -218.33205)
		(width 0.0889)
		(layer "In4.Cu")
		(net "UPI_CPU1_CPU0_P1P0_DP<0>")
	)
	(arc
		(start 135.979916 -215.276176)
		(mid 135.904879 -215.160294)
		(end 135.795512 -215.076024)
		(width 0.0889)
		(layer "In4.Cu")
		(net "UPI_CPU1_CPU0_P1P0_DP<0>")
	)
	(arc
		(start 337.313778 -215.764618)
		(mid 337.516365 -215.970969)
		(end 337.590384 -216.25052)
		(width 0.0889)
		(layer "In4.Cu")
		(net "UPI_CPU1_CPU0_P1P0_DP<0>")
	)
	(arc
		(start 337.12023 -215.436704)
		(mid 337.167909 -215.619604)
		(end 337.298792 -215.755982)
		(width 0.0889)
		(layer "In4.Cu")
		(net "UPI_CPU1_CPU0_P1P0_DP<0>")
	)
	(arc
		(start 134.100062 -217.064336)
		(mid 134.172297 -216.787812)
		(end 134.370572 -216.58199)
		(width 0.0889)
		(layer "In4.Cu")
		(net "UPI_CPU1_CPU0_P1P0_DP<0>")
	)
	(arc
		(start 337.299046 -216.745058)
		(mid 337.120449 -217.064336)
		(end 337.299046 -217.383614)
		(width 0.0889)
		(layer "In4.Cu")
		(net "UPI_CPU1_CPU0_P1P0_DP<0>")
	)
	(arc
		(start 337.590384 -216.260426)
		(mid 337.512273 -216.537375)
		(end 337.307936 -216.739978)
		(width 0.0889)
		(layer "In4.Cu")
		(net "UPI_CPU1_CPU0_P1P0_DP<0>")
	)
	(arc
		(start 337.307936 -217.388694)
		(mid 337.510222 -217.587675)
		(end 337.590384 -217.859864)
		(width 0.0889)
		(layer "In4.Cu")
		(net "UPI_CPU1_CPU0_P1P0_DP<0>")
	)
	(arc
		(start 135.331454 -216.569798)
		(mid 135.462368 -216.433438)
		(end 135.510016 -216.25052)
		(width 0.0889)
		(layer "In4.Cu")
		(net "UPI_CPU1_CPU0_P1P0_DP<0>")
	)
	(arc
		(start 337.120484 -213.893908)
		(mid 337.195489 -214.009367)
		(end 337.304634 -214.093298)
		(width 0.0889)
		(layer "In4.Cu")
		(net "UPI_CPU1_CPU0_P1P0_DP<0>")
	)
	(arc
		(start 135.795512 -215.076024)
		(mid 135.635168 -214.952903)
		(end 135.525002 -214.783416)
		(width 0.0889)
		(layer "In4.Cu")
		(net "UPI_CPU1_CPU0_P1P0_DP<0>")
	)
	(segment
		(start 345.48318 -218.414346)
		(end 345.48318 -217.87866)
		(width 0.13208)
		(layer "F.Cu")
		(net "UPI_CPU1_CPU0_P1P0_DN<9>")
	)
	(segment
		(start 345.48318 -217.87866)
		(end 345.483434 -217.878406)
		(width 0.13208)
		(layer "F.Cu")
		(net "UPI_CPU1_CPU0_P1P0_DN<9>")
	)
	(segment
		(start 125.737112 -218.414346)
		(end 125.737112 -217.87866)
		(width 0.13208)
		(layer "F.Cu")
		(net "UPI_CPU1_CPU0_P1P0_DN<9>")
	)
	(segment
		(start 125.737112 -217.87866)
		(end 125.737366 -217.878406)
		(width 0.13208)
		(layer "F.Cu")
		(net "UPI_CPU1_CPU0_P1P0_DN<9>")
	)
	(segment
		(start 155.610306 -182.790338)
		(end 155.610814 -182.790338)
		(width 0.14732)
		(layer "In4.Cu")
		(net "UPI_CPU1_CPU0_P1P0_DN<9>")
	)
	(segment
		(start 132.717032 -199.134476)
		(end 132.888736 -199.116696)
		(width 0.14732)
		(layer "In4.Cu")
		(net "UPI_CPU1_CPU0_P1P0_DN<9>")
	)
	(segment
		(start 332.994762 -190.11773)
		(end 333.019146 -190.32093)
		(width 0.14732)
		(layer "In4.Cu")
		(net "UPI_CPU1_CPU0_P1P0_DN<9>")
	)
	(segment
		(start 126.302008 -214.644732)
		(end 126.302008 -214.60714)
		(width 0.0889)
		(layer "In4.Cu")
		(net "UPI_CPU1_CPU0_P1P0_DN<9>")
	)
	(segment
		(start 345.679522 -216.569798)
		(end 345.672156 -216.574116)
		(width 0.0889)
		(layer "In4.Cu")
		(net "UPI_CPU1_CPU0_P1P0_DN<9>")
	)
	(segment
		(start 130.291586 -202.311762)
		(end 130.273806 -202.140312)
		(width 0.14732)
		(layer "In4.Cu")
		(net "UPI_CPU1_CPU0_P1P0_DN<9>")
	)
	(segment
		(start 302.425354 -180.895752)
		(end 312.429144 -181.079648)
		(width 0.14732)
		(layer "In4.Cu")
		(net "UPI_CPU1_CPU0_P1P0_DN<9>")
	)
	(segment
		(start 273.202908 -181.604158)
		(end 302.425354 -180.895752)
		(width 0.14732)
		(layer "In4.Cu")
		(net "UPI_CPU1_CPU0_P1P0_DN<9>")
	)
	(segment
		(start 125.832616 -217.082878)
		(end 125.832616 -217.05443)
		(width 0.0889)
		(layer "In4.Cu")
		(net "UPI_CPU1_CPU0_P1P0_DN<9>")
	)
	(segment
		(start 130.273806 -202.140312)
		(end 130.557778 -201.790808)
		(width 0.14732)
		(layer "In4.Cu")
		(net "UPI_CPU1_CPU0_P1P0_DN<9>")
	)
	(segment
		(start 152.296368 -183.638698)
		(end 155.610306 -182.790338)
		(width 0.14732)
		(layer "In4.Cu")
		(net "UPI_CPU1_CPU0_P1P0_DN<9>")
	)
	(segment
		(start 329.131676 -188.349128)
		(end 331.657706 -189.41796)
		(width 0.14732)
		(layer "In4.Cu")
		(net "UPI_CPU1_CPU0_P1P0_DN<9>")
	)
	(segment
		(start 345.388438 -212.038438)
		(end 345.388438 -213.929468)
		(width 0.0889)
		(layer "In4.Cu")
		(net "UPI_CPU1_CPU0_P1P0_DN<9>")
	)
	(segment
		(start 333.308706 -190.549022)
		(end 333.51216 -190.524638)
		(width 0.14732)
		(layer "In4.Cu")
		(net "UPI_CPU1_CPU0_P1P0_DN<9>")
	)
	(segment
		(start 315.110622 -181.840632)
		(end 324.61454 -185.096912)
		(width 0.14732)
		(layer "In4.Cu")
		(net "UPI_CPU1_CPU0_P1P0_DN<9>")
	)
	(segment
		(start 345.672156 -216.574116)
		(end 345.670632 -216.574878)
		(width 0.0889)
		(layer "In4.Cu")
		(net "UPI_CPU1_CPU0_P1P0_DN<9>")
	)
	(segment
		(start 131.27228 -200.912222)
		(end 131.44373 -200.894442)
		(width 0.14732)
		(layer "In4.Cu")
		(net "UPI_CPU1_CPU0_P1P0_DN<9>")
	)
	(segment
		(start 345.346528 -211.763102)
		(end 345.346528 -211.97443)
		(width 0.14732)
		(layer "In4.Cu")
		(net "UPI_CPU1_CPU0_P1P0_DN<9>")
	)
	(segment
		(start 125.832362 -213.778592)
		(end 125.831854 -213.778338)
		(width 0.0889)
		(layer "In4.Cu")
		(net "UPI_CPU1_CPU0_P1P0_DN<9>")
	)
	(segment
		(start 345.38793 -215.414606)
		(end 345.38793 -215.436704)
		(width 0.0889)
		(layer "In4.Cu")
		(net "UPI_CPU1_CPU0_P1P0_DN<9>")
	)
	(segment
		(start 125.832362 -213.770718)
		(end 125.832362 -213.2965)
		(width 0.0889)
		(layer "In4.Cu")
		(net "UPI_CPU1_CPU0_P1P0_DN<9>")
	)
	(segment
		(start 345.615768 -217.518234)
		(end 345.639898 -217.607388)
		(width 0.0889)
		(layer "In4.Cu")
		(net "UPI_CPU1_CPU0_P1P0_DN<9>")
	)
	(segment
		(start 125.874526 -211.829142)
		(end 128.504442 -204.316838)
		(width 0.14732)
		(layer "In4.Cu")
		(net "UPI_CPU1_CPU0_P1P0_DN<9>")
	)
	(segment
		(start 238.627666 -181.769004)
		(end 273.202908 -181.604158)
		(width 0.14732)
		(layer "In4.Cu")
		(net "UPI_CPU1_CPU0_P1P0_DN<9>")
	)
	(segment
		(start 345.388438 -213.929468)
		(end 345.388184 -213.929722)
		(width 0.0889)
		(layer "In4.Cu")
		(net "UPI_CPU1_CPU0_P1P0_DN<9>")
	)
	(segment
		(start 333.51216 -190.524638)
		(end 337.611974 -193.749422)
		(width 0.14732)
		(layer "In4.Cu")
		(net "UPI_CPU1_CPU0_P1P0_DN<9>")
	)
	(segment
		(start 126.010924 -215.117426)
		(end 126.019814 -215.112346)
		(width 0.0889)
		(layer "In4.Cu")
		(net "UPI_CPU1_CPU0_P1P0_DN<9>")
	)
	(segment
		(start 327.374504 -187.11291)
		(end 329.131676 -188.349128)
		(width 0.14732)
		(layer "In4.Cu")
		(net "UPI_CPU1_CPU0_P1P0_DN<9>")
	)
	(segment
		(start 130.987546 -201.262488)
		(end 131.27228 -200.912222)
		(width 0.14732)
		(layer "In4.Cu")
		(net "UPI_CPU1_CPU0_P1P0_DN<9>")
	)
	(segment
		(start 346.21216 -204.623924)
		(end 346.21216 -209.835496)
		(width 0.14732)
		(layer "In4.Cu")
		(net "UPI_CPU1_CPU0_P1P0_DN<9>")
	)
	(segment
		(start 131.005072 -201.433938)
		(end 130.987546 -201.262488)
		(width 0.14732)
		(layer "In4.Cu")
		(net "UPI_CPU1_CPU0_P1P0_DN<9>")
	)
	(segment
		(start 133.999986 -197.556628)
		(end 133.999732 -197.55612)
		(width 0.14732)
		(layer "In4.Cu")
		(net "UPI_CPU1_CPU0_P1P0_DN<9>")
	)
	(segment
		(start 331.734668 -189.607952)
		(end 332.074012 -189.751462)
		(width 0.14732)
		(layer "In4.Cu")
		(net "UPI_CPU1_CPU0_P1P0_DN<9>")
	)
	(segment
		(start 125.931422 -213.02218)
		(end 125.832362 -212.92312)
		(width 0.0889)
		(layer "In4.Cu")
		(net "UPI_CPU1_CPU0_P1P0_DN<9>")
	)
	(segment
		(start 345.670632 -216.574878)
		(end 345.667838 -216.576402)
		(width 0.0889)
		(layer "In4.Cu")
		(net "UPI_CPU1_CPU0_P1P0_DN<9>")
	)
	(segment
		(start 332.625954 -189.827662)
		(end 332.994762 -190.11773)
		(width 0.14732)
		(layer "In4.Cu")
		(net "UPI_CPU1_CPU0_P1P0_DN<9>")
	)
	(segment
		(start 125.832362 -212.37448)
		(end 125.832362 -212.089492)
		(width 0.0889)
		(layer "In4.Cu")
		(net "UPI_CPU1_CPU0_P1P0_DN<9>")
	)
	(segment
		(start 125.832362 -215.452198)
		(end 125.832362 -215.436704)
		(width 0.0889)
		(layer "In4.Cu")
		(net "UPI_CPU1_CPU0_P1P0_DN<9>")
	)
	(segment
		(start 125.832362 -212.089492)
		(end 125.874526 -212.047328)
		(width 0.0889)
		(layer "In4.Cu")
		(net "UPI_CPU1_CPU0_P1P0_DN<9>")
	)
	(segment
		(start 331.657706 -189.41796)
		(end 331.734668 -189.607952)
		(width 0.14732)
		(layer "In4.Cu")
		(net "UPI_CPU1_CPU0_P1P0_DN<9>")
	)
	(segment
		(start 125.832362 -212.92312)
		(end 125.832362 -212.74786)
		(width 0.0889)
		(layer "In4.Cu")
		(net "UPI_CPU1_CPU0_P1P0_DN<9>")
	)
	(segment
		(start 345.664536 -215.922606)
		(end 345.66987 -215.925654)
		(width 0.0889)
		(layer "In4.Cu")
		(net "UPI_CPU1_CPU0_P1P0_DN<9>")
	)
	(segment
		(start 125.874526 -212.02523)
		(end 125.874526 -211.829142)
		(width 0.14732)
		(layer "In4.Cu")
		(net "UPI_CPU1_CPU0_P1P0_DN<9>")
	)
	(segment
		(start 131.701794 -200.383648)
		(end 132.012182 -200.001886)
		(width 0.14732)
		(layer "In4.Cu")
		(net "UPI_CPU1_CPU0_P1P0_DN<9>")
	)
	(segment
		(start 125.931422 -212.47354)
		(end 125.832362 -212.37448)
		(width 0.0889)
		(layer "In4.Cu")
		(net "UPI_CPU1_CPU0_P1P0_DN<9>")
	)
	(segment
		(start 125.541278 -215.931242)
		(end 125.550168 -215.926162)
		(width 0.0889)
		(layer "In4.Cu")
		(net "UPI_CPU1_CPU0_P1P0_DN<9>")
	)
	(segment
		(start 125.832362 -212.74786)
		(end 125.931422 -212.6488)
		(width 0.0889)
		(layer "In4.Cu")
		(net "UPI_CPU1_CPU0_P1P0_DN<9>")
	)
	(segment
		(start 125.832362 -213.2965)
		(end 125.931422 -213.19744)
		(width 0.0889)
		(layer "In4.Cu")
		(net "UPI_CPU1_CPU0_P1P0_DN<9>")
	)
	(segment
		(start 345.388184 -213.929722)
		(end 345.388184 -213.930484)
		(width 0.0889)
		(layer "In4.Cu")
		(net "UPI_CPU1_CPU0_P1P0_DN<9>")
	)
	(segment
		(start 125.737366 -217.878406)
		(end 125.580902 -218.149424)
		(width 0.0889)
		(layer "In4.Cu")
		(net "UPI_CPU1_CPU0_P1P0_DN<9>")
	)
	(segment
		(start 155.610814 -182.790338)
		(end 158.92526 -181.941724)
		(width 0.14732)
		(layer "In4.Cu")
		(net "UPI_CPU1_CPU0_P1P0_DN<9>")
	)
	(segment
		(start 133.999732 -197.55612)
		(end 140.244068 -193.405506)
		(width 0.14732)
		(layer "In4.Cu")
		(net "UPI_CPU1_CPU0_P1P0_DN<9>")
	)
	(segment
		(start 130.729228 -201.773282)
		(end 131.005072 -201.433938)
		(width 0.14732)
		(layer "In4.Cu")
		(net "UPI_CPU1_CPU0_P1P0_DN<9>")
	)
	(segment
		(start 133.1468 -198.605902)
		(end 133.999732 -197.556628)
		(width 0.14732)
		(layer "In4.Cu")
		(net "UPI_CPU1_CPU0_P1P0_DN<9>")
	)
	(segment
		(start 125.874526 -212.047328)
		(end 125.874526 -212.02523)
		(width 0.0889)
		(layer "In4.Cu")
		(net "UPI_CPU1_CPU0_P1P0_DN<9>")
	)
	(segment
		(start 345.679014 -214.941912)
		(end 345.670124 -214.946992)
		(width 0.0889)
		(layer "In4.Cu")
		(net "UPI_CPU1_CPU0_P1P0_DN<9>")
	)
	(segment
		(start 345.346528 -211.97443)
		(end 345.346528 -211.996528)
		(width 0.0889)
		(layer "In4.Cu")
		(net "UPI_CPU1_CPU0_P1P0_DN<9>")
	)
	(segment
		(start 345.66987 -215.925654)
		(end 345.670632 -215.926162)
		(width 0.0889)
		(layer "In4.Cu")
		(net "UPI_CPU1_CPU0_P1P0_DN<9>")
	)
	(segment
		(start 158.92526 -181.941724)
		(end 200.604374 -181.250082)
		(width 0.14732)
		(layer "In4.Cu")
		(net "UPI_CPU1_CPU0_P1P0_DN<9>")
	)
	(segment
		(start 345.346528 -211.996528)
		(end 345.388438 -212.038438)
		(width 0.0889)
		(layer "In4.Cu")
		(net "UPI_CPU1_CPU0_P1P0_DN<9>")
	)
	(segment
		(start 345.667838 -216.576402)
		(end 345.664536 -216.578434)
		(width 0.0889)
		(layer "In4.Cu")
		(net "UPI_CPU1_CPU0_P1P0_DN<9>")
	)
	(segment
		(start 130.015742 -202.650852)
		(end 130.291586 -202.311762)
		(width 0.14732)
		(layer "In4.Cu")
		(net "UPI_CPU1_CPU0_P1P0_DN<9>")
	)
	(segment
		(start 133.16458 -198.777352)
		(end 133.1468 -198.605902)
		(width 0.14732)
		(layer "In4.Cu")
		(net "UPI_CPU1_CPU0_P1P0_DN<9>")
	)
	(segment
		(start 140.244068 -193.405506)
		(end 144.576038 -187.590938)
		(width 0.14732)
		(layer "In4.Cu")
		(net "UPI_CPU1_CPU0_P1P0_DN<9>")
	)
	(segment
		(start 332.074012 -189.751462)
		(end 332.26375 -189.6745)
		(width 0.14732)
		(layer "In4.Cu")
		(net "UPI_CPU1_CPU0_P1P0_DN<9>")
	)
	(segment
		(start 125.931422 -212.6488)
		(end 125.931422 -212.47354)
		(width 0.0889)
		(layer "In4.Cu")
		(net "UPI_CPU1_CPU0_P1P0_DN<9>")
	)
	(segment
		(start 132.459476 -199.644762)
		(end 132.441696 -199.473312)
		(width 0.14732)
		(layer "In4.Cu")
		(net "UPI_CPU1_CPU0_P1P0_DN<9>")
	)
	(segment
		(start 345.346274 -211.762848)
		(end 345.346528 -211.763102)
		(width 0.14732)
		(layer "In4.Cu")
		(net "UPI_CPU1_CPU0_P1P0_DN<9>")
	)
	(segment
		(start 345.670632 -215.926162)
		(end 345.672156 -215.926924)
		(width 0.0889)
		(layer "In4.Cu")
		(net "UPI_CPU1_CPU0_P1P0_DN<9>")
	)
	(segment
		(start 312.429144 -181.079648)
		(end 315.110622 -181.840632)
		(width 0.14732)
		(layer "In4.Cu")
		(net "UPI_CPU1_CPU0_P1P0_DN<9>")
	)
	(segment
		(start 132.441696 -199.473312)
		(end 132.717032 -199.134476)
		(width 0.14732)
		(layer "In4.Cu")
		(net "UPI_CPU1_CPU0_P1P0_DN<9>")
	)
	(segment
		(start 132.888736 -199.116696)
		(end 133.16458 -198.777352)
		(width 0.14732)
		(layer "In4.Cu")
		(net "UPI_CPU1_CPU0_P1P0_DN<9>")
	)
	(segment
		(start 132.012182 -200.001886)
		(end 132.183632 -199.984106)
		(width 0.14732)
		(layer "In4.Cu")
		(net "UPI_CPU1_CPU0_P1P0_DN<9>")
	)
	(segment
		(start 212.418168 -181.769004)
		(end 238.627666 -181.769004)
		(width 0.14732)
		(layer "In4.Cu")
		(net "UPI_CPU1_CPU0_P1P0_DN<9>")
	)
	(segment
		(start 345.38793 -217.064336)
		(end 345.38793 -217.07856)
		(width 0.0889)
		(layer "In4.Cu")
		(net "UPI_CPU1_CPU0_P1P0_DN<9>")
	)
	(segment
		(start 129.844292 -202.668632)
		(end 130.015742 -202.650852)
		(width 0.14732)
		(layer "In4.Cu")
		(net "UPI_CPU1_CPU0_P1P0_DN<9>")
	)
	(segment
		(start 346.21216 -209.835496)
		(end 345.346274 -210.701382)
		(width 0.14732)
		(layer "In4.Cu")
		(net "UPI_CPU1_CPU0_P1P0_DN<9>")
	)
	(segment
		(start 200.604374 -181.250082)
		(end 212.418168 -181.769004)
		(width 0.14732)
		(layer "In4.Cu")
		(net "UPI_CPU1_CPU0_P1P0_DN<9>")
	)
	(segment
		(start 126.019814 -214.133176)
		(end 125.992128 -214.117174)
		(width 0.0889)
		(layer "In4.Cu")
		(net "UPI_CPU1_CPU0_P1P0_DN<9>")
	)
	(segment
		(start 345.346274 -210.701382)
		(end 345.346274 -211.762848)
		(width 0.14732)
		(layer "In4.Cu")
		(net "UPI_CPU1_CPU0_P1P0_DN<9>")
	)
	(segment
		(start 132.183632 -199.984106)
		(end 132.459476 -199.644762)
		(width 0.14732)
		(layer "In4.Cu")
		(net "UPI_CPU1_CPU0_P1P0_DN<9>")
	)
	(segment
		(start 332.26375 -189.6745)
		(end 332.625954 -189.827662)
		(width 0.14732)
		(layer "In4.Cu")
		(net "UPI_CPU1_CPU0_P1P0_DN<9>")
	)
	(segment
		(start 345.639898 -217.607388)
		(end 345.483434 -217.878406)
		(width 0.0889)
		(layer "In4.Cu")
		(net "UPI_CPU1_CPU0_P1P0_DN<9>")
	)
	(segment
		(start 130.557778 -201.790808)
		(end 130.729228 -201.773282)
		(width 0.14732)
		(layer "In4.Cu")
		(net "UPI_CPU1_CPU0_P1P0_DN<9>")
	)
	(segment
		(start 125.541278 -217.559128)
		(end 125.550168 -217.554048)
		(width 0.0889)
		(layer "In4.Cu")
		(net "UPI_CPU1_CPU0_P1P0_DN<9>")
	)
	(segment
		(start 337.611974 -193.749422)
		(end 344.604086 -200.741534)
		(width 0.14732)
		(layer "In4.Cu")
		(net "UPI_CPU1_CPU0_P1P0_DN<9>")
	)
	(segment
		(start 131.44373 -200.894442)
		(end 131.719574 -200.555098)
		(width 0.14732)
		(layer "In4.Cu")
		(net "UPI_CPU1_CPU0_P1P0_DN<9>")
	)
	(segment
		(start 125.831854 -213.778338)
		(end 125.832362 -213.770718)
		(width 0.0889)
		(layer "In4.Cu")
		(net "UPI_CPU1_CPU0_P1P0_DN<9>")
	)
	(segment
		(start 333.019146 -190.32093)
		(end 333.308706 -190.549022)
		(width 0.14732)
		(layer "In4.Cu")
		(net "UPI_CPU1_CPU0_P1P0_DN<9>")
	)
	(segment
		(start 344.604086 -200.741534)
		(end 346.21216 -204.623924)
		(width 0.14732)
		(layer "In4.Cu")
		(net "UPI_CPU1_CPU0_P1P0_DN<9>")
	)
	(segment
		(start 133.999732 -197.556628)
		(end 133.999986 -197.556628)
		(width 0.14732)
		(layer "In4.Cu")
		(net "UPI_CPU1_CPU0_P1P0_DN<9>")
	)
	(segment
		(start 125.550168 -216.574878)
		(end 125.541278 -216.569798)
		(width 0.0889)
		(layer "In4.Cu")
		(net "UPI_CPU1_CPU0_P1P0_DN<9>")
	)
	(segment
		(start 324.61454 -185.096912)
		(end 327.374504 -187.11291)
		(width 0.14732)
		(layer "In4.Cu")
		(net "UPI_CPU1_CPU0_P1P0_DN<9>")
	)
	(segment
		(start 144.576038 -187.590938)
		(end 152.296368 -183.638698)
		(width 0.14732)
		(layer "In4.Cu")
		(net "UPI_CPU1_CPU0_P1P0_DN<9>")
	)
	(segment
		(start 125.931422 -213.19744)
		(end 125.931422 -213.02218)
		(width 0.0889)
		(layer "In4.Cu")
		(net "UPI_CPU1_CPU0_P1P0_DN<9>")
	)
	(segment
		(start 125.580902 -218.149424)
		(end 125.50267 -218.170252)
		(width 0.0889)
		(layer "In4.Cu")
		(net "UPI_CPU1_CPU0_P1P0_DN<9>")
	)
	(segment
		(start 128.504442 -204.316838)
		(end 129.844292 -202.668632)
		(width 0.14732)
		(layer "In4.Cu")
		(net "UPI_CPU1_CPU0_P1P0_DN<9>")
	)
	(segment
		(start 131.719574 -200.555098)
		(end 131.701794 -200.383648)
		(width 0.14732)
		(layer "In4.Cu")
		(net "UPI_CPU1_CPU0_P1P0_DN<9>")
	)
	(segment
		(start 345.857576 -214.461344)
		(end 345.857576 -214.622634)
		(width 0.0889)
		(layer "In4.Cu")
		(net "UPI_CPU1_CPU0_P1P0_DN<9>")
	)
	(segment
		(start 345.672156 -215.926924)
		(end 345.679522 -215.931242)
		(width 0.0889)
		(layer "In4.Cu")
		(net "UPI_CPU1_CPU0_P1P0_DN<9>")
	)
	(arc
		(start 345.857576 -214.622634)
		(mid 345.809897 -214.805534)
		(end 345.679014 -214.941912)
		(width 0.0889)
		(layer "In4.Cu")
		(net "UPI_CPU1_CPU0_P1P0_DN<9>")
	)
	(arc
		(start 345.38793 -217.07856)
		(mid 345.446224 -217.315203)
		(end 345.59875 -217.50528)
		(width 0.0889)
		(layer "In4.Cu")
		(net "UPI_CPU1_CPU0_P1P0_DN<9>")
	)
	(arc
		(start 345.673426 -214.261954)
		(mid 345.782573 -214.345882)
		(end 345.857576 -214.461344)
		(width 0.0889)
		(layer "In4.Cu")
		(net "UPI_CPU1_CPU0_P1P0_DN<9>")
	)
	(arc
		(start 345.664536 -216.578434)
		(mid 345.461949 -216.784785)
		(end 345.38793 -217.064336)
		(width 0.0889)
		(layer "In4.Cu")
		(net "UPI_CPU1_CPU0_P1P0_DN<9>")
	)
	(arc
		(start 125.50267 -218.170252)
		(mid 125.399525 -218.040227)
		(end 125.362716 -217.878406)
		(width 0.0889)
		(layer "In4.Cu")
		(net "UPI_CPU1_CPU0_P1P0_DN<9>")
	)
	(arc
		(start 125.362716 -217.878406)
		(mid 125.410395 -217.695506)
		(end 125.541278 -217.559128)
		(width 0.0889)
		(layer "In4.Cu")
		(net "UPI_CPU1_CPU0_P1P0_DN<9>")
	)
	(arc
		(start 126.019814 -215.112346)
		(mid 126.221096 -214.914859)
		(end 126.302008 -214.644732)
		(width 0.0889)
		(layer "In4.Cu")
		(net "UPI_CPU1_CPU0_P1P0_DN<9>")
	)
	(arc
		(start 125.550168 -217.554048)
		(mid 125.752454 -217.355067)
		(end 125.832616 -217.082878)
		(width 0.0889)
		(layer "In4.Cu")
		(net "UPI_CPU1_CPU0_P1P0_DN<9>")
	)
	(arc
		(start 126.302008 -214.60714)
		(mid 126.222638 -214.333406)
		(end 126.019814 -214.133176)
		(width 0.0889)
		(layer "In4.Cu")
		(net "UPI_CPU1_CPU0_P1P0_DN<9>")
	)
	(arc
		(start 345.403424 -213.969346)
		(mid 345.513418 -214.138715)
		(end 345.673426 -214.261954)
		(width 0.0889)
		(layer "In4.Cu")
		(net "UPI_CPU1_CPU0_P1P0_DN<9>")
	)
	(arc
		(start 125.832616 -217.05443)
		(mid 125.754505 -216.777481)
		(end 125.550168 -216.574878)
		(width 0.0889)
		(layer "In4.Cu")
		(net "UPI_CPU1_CPU0_P1P0_DN<9>")
	)
	(arc
		(start 345.679522 -215.931242)
		(mid 345.858119 -216.25052)
		(end 345.679522 -216.569798)
		(width 0.0889)
		(layer "In4.Cu")
		(net "UPI_CPU1_CPU0_P1P0_DN<9>")
	)
	(arc
		(start 125.832362 -215.436704)
		(mid 125.832414 -215.429337)
		(end 125.832616 -215.421972)
		(width 0.0889)
		(layer "In4.Cu")
		(net "UPI_CPU1_CPU0_P1P0_DN<9>")
	)
	(arc
		(start 125.362716 -216.257124)
		(mid 125.362622 -216.248742)
		(end 125.362716 -216.24036)
		(width 0.0889)
		(layer "In4.Cu")
		(net "UPI_CPU1_CPU0_P1P0_DN<9>")
	)
	(arc
		(start 345.388184 -213.930484)
		(mid 345.395469 -213.950046)
		(end 345.403424 -213.969346)
		(width 0.0889)
		(layer "In4.Cu")
		(net "UPI_CPU1_CPU0_P1P0_DN<9>")
	)
	(arc
		(start 125.550168 -215.926162)
		(mid 125.752991 -215.725931)
		(end 125.832362 -215.452198)
		(width 0.0889)
		(layer "In4.Cu")
		(net "UPI_CPU1_CPU0_P1P0_DN<9>")
	)
	(arc
		(start 125.541278 -216.569798)
		(mid 125.411989 -216.436312)
		(end 125.362716 -216.257124)
		(width 0.0889)
		(layer "In4.Cu")
		(net "UPI_CPU1_CPU0_P1P0_DN<9>")
	)
	(arc
		(start 345.59875 -217.50528)
		(mid 345.607198 -217.511837)
		(end 345.615768 -217.518234)
		(width 0.0889)
		(layer "In4.Cu")
		(net "UPI_CPU1_CPU0_P1P0_DN<9>")
	)
	(arc
		(start 345.38793 -215.436704)
		(mid 345.461921 -215.71627)
		(end 345.664536 -215.922606)
		(width 0.0889)
		(layer "In4.Cu")
		(net "UPI_CPU1_CPU0_P1P0_DN<9>")
	)
	(arc
		(start 125.362716 -216.24036)
		(mid 125.412785 -216.063135)
		(end 125.541278 -215.931242)
		(width 0.0889)
		(layer "In4.Cu")
		(net "UPI_CPU1_CPU0_P1P0_DN<9>")
	)
	(arc
		(start 345.670124 -214.946992)
		(mid 345.468842 -215.144479)
		(end 345.38793 -215.414606)
		(width 0.0889)
		(layer "In4.Cu")
		(net "UPI_CPU1_CPU0_P1P0_DN<9>")
	)
	(arc
		(start 125.832616 -215.421972)
		(mid 125.88367 -215.247392)
		(end 126.010924 -215.117426)
		(width 0.0889)
		(layer "In4.Cu")
		(net "UPI_CPU1_CPU0_P1P0_DN<9>")
	)
	(arc
		(start 125.992128 -214.117174)
		(mid 125.867101 -213.969189)
		(end 125.832362 -213.778592)
		(width 0.0889)
		(layer "In4.Cu")
		(net "UPI_CPU1_CPU0_P1P0_DN<9>")
	)
	(segment
		(start 126.676912 -218.414346)
		(end 126.676912 -217.87866)
		(width 0.13208)
		(layer "F.Cu")
		(net "UPI_CPU1_CPU0_P1P0_DN<8>")
	)
	(segment
		(start 344.54338 -217.87866)
		(end 344.543634 -217.878406)
		(width 0.13208)
		(layer "F.Cu")
		(net "UPI_CPU1_CPU0_P1P0_DN<8>")
	)
	(segment
		(start 126.676912 -217.87866)
		(end 126.677166 -217.878406)
		(width 0.13208)
		(layer "F.Cu")
		(net "UPI_CPU1_CPU0_P1P0_DN<8>")
	)
	(segment
		(start 344.54338 -218.414346)
		(end 344.54338 -217.87866)
		(width 0.13208)
		(layer "F.Cu")
		(net "UPI_CPU1_CPU0_P1P0_DN<8>")
	)
	(segment
		(start 132.362448 -201.107548)
		(end 132.533898 -201.089768)
		(width 0.14732)
		(layer "In4.Cu")
		(net "UPI_CPU1_CPU0_P1P0_DN<8>")
	)
	(segment
		(start 133.525006 -199.677528)
		(end 133.800596 -199.338692)
		(width 0.14732)
		(layer "In4.Cu")
		(net "UPI_CPU1_CPU0_P1P0_DN<8>")
	)
	(segment
		(start 126.81458 -211.854288)
		(end 126.81458 -211.83219)
		(width 0.0889)
		(layer "In4.Cu")
		(net "UPI_CPU1_CPU0_P1P0_DN<8>")
	)
	(segment
		(start 134.24789 -198.981822)
		(end 134.23011 -198.810372)
		(width 0.14732)
		(layer "In4.Cu")
		(net "UPI_CPU1_CPU0_P1P0_DN<8>")
	)
	(segment
		(start 302.504094 -181.729126)
		(end 312.277252 -181.909974)
		(width 0.14732)
		(layer "In4.Cu")
		(net "UPI_CPU1_CPU0_P1P0_DN<8>")
	)
	(segment
		(start 314.688474 -182.671974)
		(end 322.58254 -186.009534)
		(width 0.14732)
		(layer "In4.Cu")
		(net "UPI_CPU1_CPU0_P1P0_DN<8>")
	)
	(segment
		(start 129.967482 -204.053186)
		(end 130.243072 -203.71435)
		(width 0.14732)
		(layer "In4.Cu")
		(net "UPI_CPU1_CPU0_P1P0_DN<8>")
	)
	(segment
		(start 159.141668 -182.77713)
		(end 200.5838 -182.089044)
		(width 0.14732)
		(layer "In4.Cu")
		(net "UPI_CPU1_CPU0_P1P0_DN<8>")
	)
	(segment
		(start 344.731594 -217.554556)
		(end 344.739722 -217.559128)
		(width 0.0889)
		(layer "In4.Cu")
		(net "UPI_CPU1_CPU0_P1P0_DN<8>")
	)
	(segment
		(start 344.40622 -211.762848)
		(end 344.406474 -211.763102)
		(width 0.14732)
		(layer "In4.Cu")
		(net "UPI_CPU1_CPU0_P1P0_DN<8>")
	)
	(segment
		(start 130.690366 -203.35748)
		(end 130.672586 -203.18603)
		(width 0.14732)
		(layer "In4.Cu")
		(net "UPI_CPU1_CPU0_P1P0_DN<8>")
	)
	(segment
		(start 344.349324 -213.173818)
		(end 344.349324 -213.349078)
		(width 0.0889)
		(layer "In4.Cu")
		(net "UPI_CPU1_CPU0_P1P0_DN<8>")
	)
	(segment
		(start 152.474168 -184.48401)
		(end 159.141668 -182.77713)
		(width 0.14732)
		(layer "In4.Cu")
		(net "UPI_CPU1_CPU0_P1P0_DN<8>")
	)
	(segment
		(start 126.772162 -215.452198)
		(end 126.772162 -215.436704)
		(width 0.0889)
		(layer "In4.Cu")
		(net "UPI_CPU1_CPU0_P1P0_DN<8>")
	)
	(segment
		(start 344.724736 -215.922606)
		(end 344.73007 -215.925654)
		(width 0.0889)
		(layer "In4.Cu")
		(net "UPI_CPU1_CPU0_P1P0_DN<8>")
	)
	(segment
		(start 344.700098 -218.149424)
		(end 344.543634 -217.878406)
		(width 0.0889)
		(layer "In4.Cu")
		(net "UPI_CPU1_CPU0_P1P0_DN<8>")
	)
	(segment
		(start 344.349324 -212.800438)
		(end 344.448384 -212.899498)
		(width 0.0889)
		(layer "In4.Cu")
		(net "UPI_CPU1_CPU0_P1P0_DN<8>")
	)
	(segment
		(start 323.622162 -186.577478)
		(end 328.792078 -189.116462)
		(width 0.14732)
		(layer "In4.Cu")
		(net "UPI_CPU1_CPU0_P1P0_DN<8>")
	)
	(segment
		(start 331.6986 -190.70193)
		(end 331.752448 -190.899796)
		(width 0.14732)
		(layer "In4.Cu")
		(net "UPI_CPU1_CPU0_P1P0_DN<8>")
	)
	(segment
		(start 134.23011 -198.810372)
		(end 134.914386 -197.96887)
		(width 0.14732)
		(layer "In4.Cu")
		(net "UPI_CPU1_CPU0_P1P0_DN<8>")
	)
	(segment
		(start 331.752448 -190.899796)
		(end 332.072488 -191.082676)
		(width 0.14732)
		(layer "In4.Cu")
		(net "UPI_CPU1_CPU0_P1P0_DN<8>")
	)
	(segment
		(start 344.730832 -217.554048)
		(end 344.731594 -217.554556)
		(width 0.0889)
		(layer "In4.Cu")
		(net "UPI_CPU1_CPU0_P1P0_DN<8>")
	)
	(segment
		(start 273.217894 -182.438802)
		(end 302.504094 -181.729126)
		(width 0.14732)
		(layer "In4.Cu")
		(net "UPI_CPU1_CPU0_P1P0_DN<8>")
	)
	(segment
		(start 133.800596 -199.338692)
		(end 133.972046 -199.320912)
		(width 0.14732)
		(layer "In4.Cu")
		(net "UPI_CPU1_CPU0_P1P0_DN<8>")
	)
	(segment
		(start 126.481078 -215.931242)
		(end 126.489968 -215.926162)
		(width 0.0889)
		(layer "In4.Cu")
		(net "UPI_CPU1_CPU0_P1P0_DN<8>")
	)
	(segment
		(start 344.406474 -211.97443)
		(end 344.406474 -211.996528)
		(width 0.0889)
		(layer "In4.Cu")
		(net "UPI_CPU1_CPU0_P1P0_DN<8>")
	)
	(segment
		(start 344.349324 -213.349078)
		(end 344.448384 -213.448138)
		(width 0.0889)
		(layer "In4.Cu")
		(net "UPI_CPU1_CPU0_P1P0_DN<8>")
	)
	(segment
		(start 126.950724 -215.117426)
		(end 126.958598 -215.112854)
		(width 0.0889)
		(layer "In4.Cu")
		(net "UPI_CPU1_CPU0_P1P0_DN<8>")
	)
	(segment
		(start 312.277252 -181.909974)
		(end 314.688474 -182.671974)
		(width 0.14732)
		(layer "In4.Cu")
		(net "UPI_CPU1_CPU0_P1P0_DN<8>")
	)
	(segment
		(start 130.243072 -203.71435)
		(end 130.414522 -203.69657)
		(width 0.14732)
		(layer "In4.Cu")
		(net "UPI_CPU1_CPU0_P1P0_DN<8>")
	)
	(segment
		(start 344.739214 -214.941912)
		(end 344.730324 -214.946992)
		(width 0.0889)
		(layer "In4.Cu")
		(net "UPI_CPU1_CPU0_P1P0_DN<8>")
	)
	(segment
		(start 126.92507 -214.048594)
		(end 126.772416 -213.89594)
		(width 0.0889)
		(layer "In4.Cu")
		(net "UPI_CPU1_CPU0_P1P0_DN<8>")
	)
	(segment
		(start 238.630206 -182.603648)
		(end 273.21256 -182.439056)
		(width 0.14732)
		(layer "In4.Cu")
		(net "UPI_CPU1_CPU0_P1P0_DN<8>")
	)
	(segment
		(start 322.58254 -186.009534)
		(end 323.622162 -186.577478)
		(width 0.14732)
		(layer "In4.Cu")
		(net "UPI_CPU1_CPU0_P1P0_DN<8>")
	)
	(segment
		(start 212.292438 -182.603648)
		(end 238.630206 -182.603648)
		(width 0.14732)
		(layer "In4.Cu")
		(net "UPI_CPU1_CPU0_P1P0_DN<8>")
	)
	(segment
		(start 129.175002 -205.027784)
		(end 129.537714 -204.58176)
		(width 0.14732)
		(layer "In4.Cu")
		(net "UPI_CPU1_CPU0_P1P0_DN<8>")
	)
	(segment
		(start 133.095492 -200.206102)
		(end 133.266942 -200.188322)
		(width 0.14732)
		(layer "In4.Cu")
		(net "UPI_CPU1_CPU0_P1P0_DN<8>")
	)
	(segment
		(start 133.542786 -199.848978)
		(end 133.525006 -199.677528)
		(width 0.14732)
		(layer "In4.Cu")
		(net "UPI_CPU1_CPU0_P1P0_DN<8>")
	)
	(segment
		(start 329.470512 -189.427612)
		(end 331.6986 -190.70193)
		(width 0.14732)
		(layer "In4.Cu")
		(net "UPI_CPU1_CPU0_P1P0_DN<8>")
	)
	(segment
		(start 344.406474 -211.996528)
		(end 344.448384 -212.038438)
		(width 0.0889)
		(layer "In4.Cu")
		(net "UPI_CPU1_CPU0_P1P0_DN<8>")
	)
	(segment
		(start 344.448384 -213.448138)
		(end 344.448384 -213.930484)
		(width 0.0889)
		(layer "In4.Cu")
		(net "UPI_CPU1_CPU0_P1P0_DN<8>")
	)
	(segment
		(start 344.349324 -212.625178)
		(end 344.349324 -212.800438)
		(width 0.0889)
		(layer "In4.Cu")
		(net "UPI_CPU1_CPU0_P1P0_DN<8>")
	)
	(segment
		(start 344.739722 -216.569798)
		(end 344.730832 -216.574878)
		(width 0.0889)
		(layer "In4.Cu")
		(net "UPI_CPU1_CPU0_P1P0_DN<8>")
	)
	(segment
		(start 332.072488 -191.082676)
		(end 332.269846 -191.028828)
		(width 0.14732)
		(layer "In4.Cu")
		(net "UPI_CPU1_CPU0_P1P0_DN<8>")
	)
	(segment
		(start 345.38158 -204.855318)
		(end 345.38158 -209.49285)
		(width 0.14732)
		(layer "In4.Cu")
		(net "UPI_CPU1_CPU0_P1P0_DN<8>")
	)
	(segment
		(start 132.533898 -201.089768)
		(end 132.809742 -200.750678)
		(width 0.14732)
		(layer "In4.Cu")
		(net "UPI_CPU1_CPU0_P1P0_DN<8>")
	)
	(segment
		(start 130.414522 -203.69657)
		(end 130.690366 -203.35748)
		(width 0.14732)
		(layer "In4.Cu")
		(net "UPI_CPU1_CPU0_P1P0_DN<8>")
	)
	(segment
		(start 273.21256 -182.439056)
		(end 273.21256 -182.438802)
		(width 0.14732)
		(layer "In4.Cu")
		(net "UPI_CPU1_CPU0_P1P0_DN<8>")
	)
	(segment
		(start 131.39547 -202.490324)
		(end 131.37769 -202.318874)
		(width 0.14732)
		(layer "In4.Cu")
		(net "UPI_CPU1_CPU0_P1P0_DN<8>")
	)
	(segment
		(start 126.81458 -211.83219)
		(end 126.81458 -211.770722)
		(width 0.14732)
		(layer "In4.Cu")
		(net "UPI_CPU1_CPU0_P1P0_DN<8>")
	)
	(segment
		(start 344.77833 -218.170252)
		(end 344.700098 -218.149424)
		(width 0.0889)
		(layer "In4.Cu")
		(net "UPI_CPU1_CPU0_P1P0_DN<8>")
	)
	(segment
		(start 127.241554 -214.618824)
		(end 127.234696 -214.409274)
		(width 0.0889)
		(layer "In4.Cu")
		(net "UPI_CPU1_CPU0_P1P0_DN<8>")
	)
	(segment
		(start 127.241808 -214.644732)
		(end 127.241808 -214.625936)
		(width 0.0889)
		(layer "In4.Cu")
		(net "UPI_CPU1_CPU0_P1P0_DN<8>")
	)
	(segment
		(start 131.82473 -201.962258)
		(end 132.100574 -201.623168)
		(width 0.14732)
		(layer "In4.Cu")
		(net "UPI_CPU1_CPU0_P1P0_DN<8>")
	)
	(segment
		(start 131.119626 -202.829414)
		(end 131.39547 -202.490324)
		(width 0.14732)
		(layer "In4.Cu")
		(net "UPI_CPU1_CPU0_P1P0_DN<8>")
	)
	(segment
		(start 132.100574 -201.623168)
		(end 132.082794 -201.451464)
		(width 0.14732)
		(layer "In4.Cu")
		(net "UPI_CPU1_CPU0_P1P0_DN<8>")
	)
	(segment
		(start 126.677166 -217.878406)
		(end 126.520702 -217.607388)
		(width 0.0889)
		(layer "In4.Cu")
		(net "UPI_CPU1_CPU0_P1P0_DN<8>")
	)
	(segment
		(start 126.772416 -211.896452)
		(end 126.81458 -211.854288)
		(width 0.0889)
		(layer "In4.Cu")
		(net "UPI_CPU1_CPU0_P1P0_DN<8>")
	)
	(segment
		(start 126.489968 -216.574878)
		(end 126.481078 -216.569798)
		(width 0.0889)
		(layer "In4.Cu")
		(net "UPI_CPU1_CPU0_P1P0_DN<8>")
	)
	(segment
		(start 344.448384 -212.038438)
		(end 344.448384 -212.526118)
		(width 0.0889)
		(layer "In4.Cu")
		(net "UPI_CPU1_CPU0_P1P0_DN<8>")
	)
	(segment
		(start 131.65328 -201.980038)
		(end 131.82473 -201.962258)
		(width 0.14732)
		(layer "In4.Cu")
		(net "UPI_CPU1_CPU0_P1P0_DN<8>")
	)
	(segment
		(start 145.149824 -188.233812)
		(end 152.474168 -184.48401)
		(width 0.14732)
		(layer "In4.Cu")
		(net "UPI_CPU1_CPU0_P1P0_DN<8>")
	)
	(segment
		(start 126.772416 -217.07856)
		(end 126.772416 -217.064336)
		(width 0.0889)
		(layer "In4.Cu")
		(net "UPI_CPU1_CPU0_P1P0_DN<8>")
	)
	(segment
		(start 332.269846 -191.028828)
		(end 334.103726 -192.077594)
		(width 0.14732)
		(layer "In4.Cu")
		(net "UPI_CPU1_CPU0_P1P0_DN<8>")
	)
	(segment
		(start 344.40622 -210.46821)
		(end 344.40622 -211.762848)
		(width 0.14732)
		(layer "In4.Cu")
		(net "UPI_CPU1_CPU0_P1P0_DN<8>")
	)
	(segment
		(start 130.948176 -202.847194)
		(end 131.119626 -202.829414)
		(width 0.14732)
		(layer "In4.Cu")
		(net "UPI_CPU1_CPU0_P1P0_DN<8>")
	)
	(segment
		(start 129.709164 -204.56398)
		(end 129.985008 -204.224636)
		(width 0.14732)
		(layer "In4.Cu")
		(net "UPI_CPU1_CPU0_P1P0_DN<8>")
	)
	(segment
		(start 133.266942 -200.188322)
		(end 133.542786 -199.848978)
		(width 0.14732)
		(layer "In4.Cu")
		(net "UPI_CPU1_CPU0_P1P0_DN<8>")
	)
	(segment
		(start 344.406474 -211.763102)
		(end 344.406474 -211.97443)
		(width 0.14732)
		(layer "In4.Cu")
		(net "UPI_CPU1_CPU0_P1P0_DN<8>")
	)
	(segment
		(start 334.103726 -192.077594)
		(end 337.164934 -194.485768)
		(width 0.14732)
		(layer "In4.Cu")
		(net "UPI_CPU1_CPU0_P1P0_DN<8>")
	)
	(segment
		(start 345.38158 -209.49285)
		(end 344.40622 -210.46821)
		(width 0.14732)
		(layer "In4.Cu")
		(net "UPI_CPU1_CPU0_P1P0_DN<8>")
	)
	(segment
		(start 344.44813 -215.414606)
		(end 344.44813 -215.436704)
		(width 0.0889)
		(layer "In4.Cu")
		(net "UPI_CPU1_CPU0_P1P0_DN<8>")
	)
	(segment
		(start 131.37769 -202.318874)
		(end 131.65328 -201.980038)
		(width 0.14732)
		(layer "In4.Cu")
		(net "UPI_CPU1_CPU0_P1P0_DN<8>")
	)
	(segment
		(start 126.81458 -211.770722)
		(end 129.175002 -205.027784)
		(width 0.14732)
		(layer "In4.Cu")
		(net "UPI_CPU1_CPU0_P1P0_DN<8>")
	)
	(segment
		(start 344.723212 -216.579196)
		(end 344.71864 -216.58199)
		(width 0.0889)
		(layer "In4.Cu")
		(net "UPI_CPU1_CPU0_P1P0_DN<8>")
	)
	(segment
		(start 344.44813 -217.064336)
		(end 344.44813 -217.071956)
		(width 0.0889)
		(layer "In4.Cu")
		(net "UPI_CPU1_CPU0_P1P0_DN<8>")
	)
	(segment
		(start 343.859358 -201.180192)
		(end 345.38158 -204.855318)
		(width 0.14732)
		(layer "In4.Cu")
		(net "UPI_CPU1_CPU0_P1P0_DN<8>")
	)
	(segment
		(start 344.448384 -212.899498)
		(end 344.448384 -213.074758)
		(width 0.0889)
		(layer "In4.Cu")
		(net "UPI_CPU1_CPU0_P1P0_DN<8>")
	)
	(segment
		(start 328.792078 -189.116462)
		(end 329.470512 -189.427612)
		(width 0.14732)
		(layer "In4.Cu")
		(net "UPI_CPU1_CPU0_P1P0_DN<8>")
	)
	(segment
		(start 129.985008 -204.224636)
		(end 129.967482 -204.053186)
		(width 0.14732)
		(layer "In4.Cu")
		(net "UPI_CPU1_CPU0_P1P0_DN<8>")
	)
	(segment
		(start 132.809742 -200.750678)
		(end 132.792216 -200.578974)
		(width 0.14732)
		(layer "In4.Cu")
		(net "UPI_CPU1_CPU0_P1P0_DN<8>")
	)
	(segment
		(start 344.448384 -212.526118)
		(end 344.349324 -212.625178)
		(width 0.0889)
		(layer "In4.Cu")
		(net "UPI_CPU1_CPU0_P1P0_DN<8>")
	)
	(segment
		(start 344.448384 -213.074758)
		(end 344.349324 -213.173818)
		(width 0.0889)
		(layer "In4.Cu")
		(net "UPI_CPU1_CPU0_P1P0_DN<8>")
	)
	(segment
		(start 130.672586 -203.18603)
		(end 130.948176 -202.847194)
		(width 0.14732)
		(layer "In4.Cu")
		(net "UPI_CPU1_CPU0_P1P0_DN<8>")
	)
	(segment
		(start 344.732356 -215.926924)
		(end 344.739722 -215.931242)
		(width 0.0889)
		(layer "In4.Cu")
		(net "UPI_CPU1_CPU0_P1P0_DN<8>")
	)
	(segment
		(start 132.792216 -200.578974)
		(end 133.095492 -200.206102)
		(width 0.14732)
		(layer "In4.Cu")
		(net "UPI_CPU1_CPU0_P1P0_DN<8>")
	)
	(segment
		(start 129.537714 -204.58176)
		(end 129.709164 -204.56398)
		(width 0.14732)
		(layer "In4.Cu")
		(net "UPI_CPU1_CPU0_P1P0_DN<8>")
	)
	(segment
		(start 344.73007 -215.925654)
		(end 344.730832 -215.926162)
		(width 0.0889)
		(layer "In4.Cu")
		(net "UPI_CPU1_CPU0_P1P0_DN<8>")
	)
	(segment
		(start 273.21256 -182.438802)
		(end 273.217894 -182.438802)
		(width 0.14732)
		(layer "In4.Cu")
		(net "UPI_CPU1_CPU0_P1P0_DN<8>")
	)
	(segment
		(start 344.730832 -216.574878)
		(end 344.727022 -216.577164)
		(width 0.0889)
		(layer "In4.Cu")
		(net "UPI_CPU1_CPU0_P1P0_DN<8>")
	)
	(segment
		(start 134.914386 -197.96887)
		(end 140.82395 -194.040506)
		(width 0.14732)
		(layer "In4.Cu")
		(net "UPI_CPU1_CPU0_P1P0_DN<8>")
	)
	(segment
		(start 344.727022 -216.577164)
		(end 344.723212 -216.579196)
		(width 0.0889)
		(layer "In4.Cu")
		(net "UPI_CPU1_CPU0_P1P0_DN<8>")
	)
	(segment
		(start 344.730832 -215.926162)
		(end 344.732356 -215.926924)
		(width 0.0889)
		(layer "In4.Cu")
		(net "UPI_CPU1_CPU0_P1P0_DN<8>")
	)
	(segment
		(start 344.917776 -214.461344)
		(end 344.917776 -214.622634)
		(width 0.0889)
		(layer "In4.Cu")
		(net "UPI_CPU1_CPU0_P1P0_DN<8>")
	)
	(segment
		(start 126.496064 -216.578434)
		(end 126.489968 -216.574878)
		(width 0.0889)
		(layer "In4.Cu")
		(net "UPI_CPU1_CPU0_P1P0_DN<8>")
	)
	(segment
		(start 133.972046 -199.320912)
		(end 134.24789 -198.981822)
		(width 0.14732)
		(layer "In4.Cu")
		(net "UPI_CPU1_CPU0_P1P0_DN<8>")
	)
	(segment
		(start 200.5838 -182.089044)
		(end 212.292438 -182.603648)
		(width 0.14732)
		(layer "In4.Cu")
		(net "UPI_CPU1_CPU0_P1P0_DN<8>")
	)
	(segment
		(start 126.772416 -213.89594)
		(end 126.772416 -211.896452)
		(width 0.0889)
		(layer "In4.Cu")
		(net "UPI_CPU1_CPU0_P1P0_DN<8>")
	)
	(segment
		(start 337.164934 -194.485768)
		(end 343.859358 -201.180192)
		(width 0.14732)
		(layer "In4.Cu")
		(net "UPI_CPU1_CPU0_P1P0_DN<8>")
	)
	(segment
		(start 126.520702 -217.607388)
		(end 126.544832 -217.518234)
		(width 0.0889)
		(layer "In4.Cu")
		(net "UPI_CPU1_CPU0_P1P0_DN<8>")
	)
	(segment
		(start 140.82395 -194.040506)
		(end 145.149824 -188.233812)
		(width 0.14732)
		(layer "In4.Cu")
		(net "UPI_CPU1_CPU0_P1P0_DN<8>")
	)
	(segment
		(start 126.958598 -215.112854)
		(end 126.959614 -215.112346)
		(width 0.0889)
		(layer "In4.Cu")
		(net "UPI_CPU1_CPU0_P1P0_DN<8>")
	)
	(segment
		(start 132.082794 -201.451464)
		(end 132.362448 -201.107548)
		(width 0.14732)
		(layer "In4.Cu")
		(net "UPI_CPU1_CPU0_P1P0_DN<8>")
	)
	(arc
		(start 344.733626 -214.261954)
		(mid 344.842773 -214.345882)
		(end 344.917776 -214.461344)
		(width 0.0889)
		(layer "In4.Cu")
		(net "UPI_CPU1_CPU0_P1P0_DN<8>")
	)
	(arc
		(start 344.917776 -214.622634)
		(mid 344.870097 -214.805534)
		(end 344.739214 -214.941912)
		(width 0.0889)
		(layer "In4.Cu")
		(net "UPI_CPU1_CPU0_P1P0_DN<8>")
	)
	(arc
		(start 126.561596 -217.50528)
		(mid 126.714103 -217.315182)
		(end 126.772416 -217.07856)
		(width 0.0889)
		(layer "In4.Cu")
		(net "UPI_CPU1_CPU0_P1P0_DN<8>")
	)
	(arc
		(start 126.489968 -215.926162)
		(mid 126.692791 -215.725931)
		(end 126.772162 -215.452198)
		(width 0.0889)
		(layer "In4.Cu")
		(net "UPI_CPU1_CPU0_P1P0_DN<8>")
	)
	(arc
		(start 344.44813 -217.071956)
		(mid 344.525759 -217.350369)
		(end 344.730832 -217.554048)
		(width 0.0889)
		(layer "In4.Cu")
		(net "UPI_CPU1_CPU0_P1P0_DN<8>")
	)
	(arc
		(start 126.481078 -216.569798)
		(mid 126.302602 -216.25052)
		(end 126.481078 -215.931242)
		(width 0.0889)
		(layer "In4.Cu")
		(net "UPI_CPU1_CPU0_P1P0_DN<8>")
	)
	(arc
		(start 127.234696 -214.409274)
		(mid 127.146225 -214.246405)
		(end 127.011176 -214.11946)
		(width 0.0889)
		(layer "In4.Cu")
		(net "UPI_CPU1_CPU0_P1P0_DN<8>")
	)
	(arc
		(start 126.544832 -217.518234)
		(mid 126.553275 -217.511836)
		(end 126.561596 -217.50528)
		(width 0.0889)
		(layer "In4.Cu")
		(net "UPI_CPU1_CPU0_P1P0_DN<8>")
	)
	(arc
		(start 126.772416 -215.421972)
		(mid 126.82347 -215.247392)
		(end 126.950724 -215.117426)
		(width 0.0889)
		(layer "In4.Cu")
		(net "UPI_CPU1_CPU0_P1P0_DN<8>")
	)
	(arc
		(start 344.739722 -217.559128)
		(mid 344.870636 -217.695488)
		(end 344.918284 -217.878406)
		(width 0.0889)
		(layer "In4.Cu")
		(net "UPI_CPU1_CPU0_P1P0_DN<8>")
	)
	(arc
		(start 344.448384 -213.930484)
		(mid 344.455669 -213.950046)
		(end 344.463624 -213.969346)
		(width 0.0889)
		(layer "In4.Cu")
		(net "UPI_CPU1_CPU0_P1P0_DN<8>")
	)
	(arc
		(start 344.918284 -217.878406)
		(mid 344.881424 -218.040203)
		(end 344.77833 -218.170252)
		(width 0.0889)
		(layer "In4.Cu")
		(net "UPI_CPU1_CPU0_P1P0_DN<8>")
	)
	(arc
		(start 126.772162 -215.436704)
		(mid 126.772214 -215.429337)
		(end 126.772416 -215.421972)
		(width 0.0889)
		(layer "In4.Cu")
		(net "UPI_CPU1_CPU0_P1P0_DN<8>")
	)
	(arc
		(start 126.959614 -215.112346)
		(mid 127.160896 -214.914859)
		(end 127.241808 -214.644732)
		(width 0.0889)
		(layer "In4.Cu")
		(net "UPI_CPU1_CPU0_P1P0_DN<8>")
	)
	(arc
		(start 126.772416 -217.064336)
		(mid 126.6985 -216.784834)
		(end 126.496064 -216.578434)
		(width 0.0889)
		(layer "In4.Cu")
		(net "UPI_CPU1_CPU0_P1P0_DN<8>")
	)
	(arc
		(start 344.739722 -215.931242)
		(mid 344.918319 -216.25052)
		(end 344.739722 -216.569798)
		(width 0.0889)
		(layer "In4.Cu")
		(net "UPI_CPU1_CPU0_P1P0_DN<8>")
	)
	(arc
		(start 344.730324 -214.946992)
		(mid 344.529042 -215.144479)
		(end 344.44813 -215.414606)
		(width 0.0889)
		(layer "In4.Cu")
		(net "UPI_CPU1_CPU0_P1P0_DN<8>")
	)
	(arc
		(start 127.011176 -214.11946)
		(mid 126.966436 -214.086078)
		(end 126.92507 -214.048594)
		(width 0.0889)
		(layer "In4.Cu")
		(net "UPI_CPU1_CPU0_P1P0_DN<8>")
	)
	(arc
		(start 344.44813 -215.436704)
		(mid 344.522121 -215.71627)
		(end 344.724736 -215.922606)
		(width 0.0889)
		(layer "In4.Cu")
		(net "UPI_CPU1_CPU0_P1P0_DN<8>")
	)
	(arc
		(start 127.241808 -214.625936)
		(mid 127.241693 -214.62238)
		(end 127.241554 -214.618824)
		(width 0.0889)
		(layer "In4.Cu")
		(net "UPI_CPU1_CPU0_P1P0_DN<8>")
	)
	(arc
		(start 344.71864 -216.58199)
		(mid 344.520412 -216.787838)
		(end 344.44813 -217.064336)
		(width 0.0889)
		(layer "In4.Cu")
		(net "UPI_CPU1_CPU0_P1P0_DN<8>")
	)
	(arc
		(start 344.463624 -213.969346)
		(mid 344.573618 -214.138715)
		(end 344.733626 -214.261954)
		(width 0.0889)
		(layer "In4.Cu")
		(net "UPI_CPU1_CPU0_P1P0_DN<8>")
	)
	(segment
		(start 344.073734 -217.600276)
		(end 344.073734 -217.06459)
		(width 0.13208)
		(layer "F.Cu")
		(net "UPI_CPU1_CPU0_P1P0_DN<7>")
	)
	(segment
		(start 127.147066 -219.228162)
		(end 127.147066 -218.692476)
		(width 0.13208)
		(layer "F.Cu")
		(net "UPI_CPU1_CPU0_P1P0_DN<7>")
	)
	(segment
		(start 344.073734 -217.06459)
		(end 344.07348 -217.064336)
		(width 0.13208)
		(layer "F.Cu")
		(net "UPI_CPU1_CPU0_P1P0_DN<7>")
	)
	(segment
		(start 127.147066 -218.692476)
		(end 127.146812 -218.692222)
		(width 0.13208)
		(layer "F.Cu")
		(net "UPI_CPU1_CPU0_P1P0_DN<7>")
	)
	(segment
		(start 343.884758 -215.7603)
		(end 343.877392 -215.755982)
		(width 0.0889)
		(layer "In4.Cu")
		(net "UPI_CPU1_CPU0_P1P0_DN<7>")
	)
	(segment
		(start 343.741248 -211.97443)
		(end 343.741248 -211.691982)
		(width 0.14732)
		(layer "In4.Cu")
		(net "UPI_CPU1_CPU0_P1P0_DN<7>")
	)
	(segment
		(start 251.665994 -183.130952)
		(end 251.66447 -183.130952)
		(width 0.14732)
		(layer "In4.Cu")
		(net "UPI_CPU1_CPU0_P1P0_DN<7>")
	)
	(segment
		(start 314.404502 -183.18861)
		(end 312.19902 -182.496714)
		(width 0.14732)
		(layer "In4.Cu")
		(net "UPI_CPU1_CPU0_P1P0_DN<7>")
	)
	(segment
		(start 127.521716 -211.891118)
		(end 127.521716 -213.78672)
		(width 0.0889)
		(layer "In4.Cu")
		(net "UPI_CPU1_CPU0_P1P0_DN<7>")
	)
	(segment
		(start 312.19902 -182.496714)
		(end 302.523652 -182.318406)
		(width 0.14732)
		(layer "In4.Cu")
		(net "UPI_CPU1_CPU0_P1P0_DN<7>")
	)
	(segment
		(start 343.886282 -216.739978)
		(end 343.887044 -216.73947)
		(width 0.0889)
		(layer "In4.Cu")
		(net "UPI_CPU1_CPU0_P1P0_DN<7>")
	)
	(segment
		(start 238.63173 -183.193182)
		(end 212.461856 -183.193182)
		(width 0.14732)
		(layer "In4.Cu")
		(net "UPI_CPU1_CPU0_P1P0_DN<7>")
	)
	(segment
		(start 127.991108 -214.500968)
		(end 127.991108 -214.622634)
		(width 0.0889)
		(layer "In4.Cu")
		(net "UPI_CPU1_CPU0_P1P0_DN<7>")
	)
	(segment
		(start 127.479806 -211.570062)
		(end 127.479806 -211.82711)
		(width 0.14732)
		(layer "In4.Cu")
		(net "UPI_CPU1_CPU0_P1P0_DN<7>")
	)
	(segment
		(start 344.82786 -209.260186)
		(end 344.82786 -205.012036)
		(width 0.14732)
		(layer "In4.Cu")
		(net "UPI_CPU1_CPU0_P1P0_DN<7>")
	)
	(segment
		(start 127.279146 -218.33205)
		(end 127.303276 -218.421204)
		(width 0.0889)
		(layer "In4.Cu")
		(net "UPI_CPU1_CPU0_P1P0_DN<7>")
	)
	(segment
		(start 344.168476 -214.644732)
		(end 344.168476 -214.424768)
		(width 0.0889)
		(layer "In4.Cu")
		(net "UPI_CPU1_CPU0_P1P0_DN<7>")
	)
	(segment
		(start 322.244212 -186.478164)
		(end 314.404502 -183.18861)
		(width 0.14732)
		(layer "In4.Cu")
		(net "UPI_CPU1_CPU0_P1P0_DN<7>")
	)
	(segment
		(start 327.465944 -190.27775)
		(end 327.05294 -190.023242)
		(width 0.14732)
		(layer "In4.Cu")
		(net "UPI_CPU1_CPU0_P1P0_DN<7>")
	)
	(segment
		(start 159.360362 -183.334152)
		(end 152.52192 -185.085228)
		(width 0.14732)
		(layer "In4.Cu")
		(net "UPI_CPU1_CPU0_P1P0_DN<7>")
	)
	(segment
		(start 344.07348 -217.064336)
		(end 343.917016 -217.335354)
		(width 0.0889)
		(layer "In4.Cu")
		(net "UPI_CPU1_CPU0_P1P0_DN<7>")
	)
	(segment
		(start 200.234296 -182.655718)
		(end 159.360362 -183.334152)
		(width 0.14732)
		(layer "In4.Cu")
		(net "UPI_CPU1_CPU0_P1P0_DN<7>")
	)
	(segment
		(start 343.740994 -210.347052)
		(end 344.82786 -209.260186)
		(width 0.14732)
		(layer "In4.Cu")
		(net "UPI_CPU1_CPU0_P1P0_DN<7>")
	)
	(segment
		(start 141.233652 -194.45732)
		(end 135.61695 -198.191374)
		(width 0.14732)
		(layer "In4.Cu")
		(net "UPI_CPU1_CPU0_P1P0_DN<7>")
	)
	(segment
		(start 323.477128 -187.14593)
		(end 322.244212 -186.478164)
		(width 0.14732)
		(layer "In4.Cu")
		(net "UPI_CPU1_CPU0_P1P0_DN<7>")
	)
	(segment
		(start 343.886282 -215.761062)
		(end 343.884758 -215.7603)
		(width 0.0889)
		(layer "In4.Cu")
		(net "UPI_CPU1_CPU0_P1P0_DN<7>")
	)
	(segment
		(start 127.303276 -218.421204)
		(end 127.146812 -218.692222)
		(width 0.0889)
		(layer "In4.Cu")
		(net "UPI_CPU1_CPU0_P1P0_DN<7>")
	)
	(segment
		(start 327.05294 -190.023242)
		(end 323.477128 -187.14593)
		(width 0.14732)
		(layer "In4.Cu")
		(net "UPI_CPU1_CPU0_P1P0_DN<7>")
	)
	(segment
		(start 343.798144 -213.382098)
		(end 343.798144 -213.206838)
		(width 0.0889)
		(layer "In4.Cu")
		(net "UPI_CPU1_CPU0_P1P0_DN<7>")
	)
	(segment
		(start 337.116674 -195.233036)
		(end 333.578454 -192.44945)
		(width 0.14732)
		(layer "In4.Cu")
		(net "UPI_CPU1_CPU0_P1P0_DN<7>")
	)
	(segment
		(start 343.798144 -213.206838)
		(end 343.699084 -213.107778)
		(width 0.0889)
		(layer "In4.Cu")
		(net "UPI_CPU1_CPU0_P1P0_DN<7>")
	)
	(segment
		(start 343.36609 -201.482706)
		(end 337.116674 -195.233036)
		(width 0.14732)
		(layer "In4.Cu")
		(net "UPI_CPU1_CPU0_P1P0_DN<7>")
	)
	(segment
		(start 302.523652 -182.318406)
		(end 273.22399 -183.028336)
		(width 0.14732)
		(layer "In4.Cu")
		(net "UPI_CPU1_CPU0_P1P0_DN<7>")
	)
	(segment
		(start 145.561812 -188.647578)
		(end 141.233652 -194.45732)
		(width 0.14732)
		(layer "In4.Cu")
		(net "UPI_CPU1_CPU0_P1P0_DN<7>")
	)
	(segment
		(start 333.578454 -192.44945)
		(end 327.465944 -190.27775)
		(width 0.14732)
		(layer "In4.Cu")
		(net "UPI_CPU1_CPU0_P1P0_DN<7>")
	)
	(segment
		(start 343.877392 -215.117426)
		(end 343.885266 -215.112854)
		(width 0.0889)
		(layer "In4.Cu")
		(net "UPI_CPU1_CPU0_P1P0_DN<7>")
	)
	(segment
		(start 152.52192 -185.085228)
		(end 145.561812 -188.647578)
		(width 0.14732)
		(layer "In4.Cu")
		(net "UPI_CPU1_CPU0_P1P0_DN<7>")
	)
	(segment
		(start 127.051816 -217.859864)
		(end 127.051816 -217.8939)
		(width 0.0889)
		(layer "In4.Cu")
		(net "UPI_CPU1_CPU0_P1P0_DN<7>")
	)
	(segment
		(start 273.22399 -183.028336)
		(end 251.665994 -183.130952)
		(width 0.14732)
		(layer "In4.Cu")
		(net "UPI_CPU1_CPU0_P1P0_DN<7>")
	)
	(segment
		(start 343.741248 -211.691982)
		(end 343.740994 -211.691728)
		(width 0.14732)
		(layer "In4.Cu")
		(net "UPI_CPU1_CPU0_P1P0_DN<7>")
	)
	(segment
		(start 343.798144 -212.833458)
		(end 343.798144 -212.658198)
		(width 0.0889)
		(layer "In4.Cu")
		(net "UPI_CPU1_CPU0_P1P0_DN<7>")
	)
	(segment
		(start 343.741248 -211.996528)
		(end 343.741248 -211.97443)
		(width 0.0889)
		(layer "In4.Cu")
		(net "UPI_CPU1_CPU0_P1P0_DN<7>")
	)
	(segment
		(start 343.798144 -212.658198)
		(end 343.699084 -212.559138)
		(width 0.0889)
		(layer "In4.Cu")
		(net "UPI_CPU1_CPU0_P1P0_DN<7>")
	)
	(segment
		(start 344.82786 -205.012036)
		(end 343.36609 -201.482706)
		(width 0.14732)
		(layer "In4.Cu")
		(net "UPI_CPU1_CPU0_P1P0_DN<7>")
	)
	(segment
		(start 343.917016 -217.335354)
		(end 343.839038 -217.356182)
		(width 0.0889)
		(layer "In4.Cu")
		(net "UPI_CPU1_CPU0_P1P0_DN<7>")
	)
	(segment
		(start 343.699084 -213.107778)
		(end 343.699084 -212.932518)
		(width 0.0889)
		(layer "In4.Cu")
		(net "UPI_CPU1_CPU0_P1P0_DN<7>")
	)
	(segment
		(start 127.051816 -216.235026)
		(end 127.051816 -216.260426)
		(width 0.0889)
		(layer "In4.Cu")
		(net "UPI_CPU1_CPU0_P1P0_DN<7>")
	)
	(segment
		(start 127.812546 -214.941912)
		(end 127.803656 -214.946992)
		(width 0.0889)
		(layer "In4.Cu")
		(net "UPI_CPU1_CPU0_P1P0_DN<7>")
	)
	(segment
		(start 127.521462 -217.0557)
		(end 127.521462 -217.072972)
		(width 0.0889)
		(layer "In4.Cu")
		(net "UPI_CPU1_CPU0_P1P0_DN<7>")
	)
	(segment
		(start 343.699084 -213.481158)
		(end 343.798144 -213.382098)
		(width 0.0889)
		(layer "In4.Cu")
		(net "UPI_CPU1_CPU0_P1P0_DN<7>")
	)
	(segment
		(start 343.699084 -213.893908)
		(end 343.699084 -213.481158)
		(width 0.0889)
		(layer "In4.Cu")
		(net "UPI_CPU1_CPU0_P1P0_DN<7>")
	)
	(segment
		(start 212.461856 -183.193182)
		(end 200.234296 -182.655718)
		(width 0.14732)
		(layer "In4.Cu")
		(net "UPI_CPU1_CPU0_P1P0_DN<7>")
	)
	(segment
		(start 129.552446 -205.650592)
		(end 127.479806 -211.570062)
		(width 0.14732)
		(layer "In4.Cu")
		(net "UPI_CPU1_CPU0_P1P0_DN<7>")
	)
	(segment
		(start 127.479806 -211.82711)
		(end 127.479806 -211.849208)
		(width 0.0889)
		(layer "In4.Cu")
		(net "UPI_CPU1_CPU0_P1P0_DN<7>")
	)
	(segment
		(start 251.66447 -183.130952)
		(end 238.63173 -183.193182)
		(width 0.14732)
		(layer "In4.Cu")
		(net "UPI_CPU1_CPU0_P1P0_DN<7>")
	)
	(segment
		(start 343.699084 -212.932518)
		(end 343.798144 -212.833458)
		(width 0.0889)
		(layer "In4.Cu")
		(net "UPI_CPU1_CPU0_P1P0_DN<7>")
	)
	(segment
		(start 343.699084 -217.072972)
		(end 343.699084 -217.0557)
		(width 0.0889)
		(layer "In4.Cu")
		(net "UPI_CPU1_CPU0_P1P0_DN<7>")
	)
	(segment
		(start 127.3429 -215.755982)
		(end 127.33401 -215.761062)
		(width 0.0889)
		(layer "In4.Cu")
		(net "UPI_CPU1_CPU0_P1P0_DN<7>")
	)
	(segment
		(start 343.699084 -212.559138)
		(end 343.699084 -212.038692)
		(width 0.0889)
		(layer "In4.Cu")
		(net "UPI_CPU1_CPU0_P1P0_DN<7>")
	)
	(segment
		(start 343.740994 -211.691728)
		(end 343.740994 -210.347052)
		(width 0.14732)
		(layer "In4.Cu")
		(net "UPI_CPU1_CPU0_P1P0_DN<7>")
	)
	(segment
		(start 343.887044 -216.73947)
		(end 343.892378 -216.736422)
		(width 0.0889)
		(layer "In4.Cu")
		(net "UPI_CPU1_CPU0_P1P0_DN<7>")
	)
	(segment
		(start 127.521462 -215.414606)
		(end 127.521462 -215.436704)
		(width 0.0889)
		(layer "In4.Cu")
		(net "UPI_CPU1_CPU0_P1P0_DN<7>")
	)
	(segment
		(start 127.479806 -211.849208)
		(end 127.521716 -211.891118)
		(width 0.0889)
		(layer "In4.Cu")
		(net "UPI_CPU1_CPU0_P1P0_DN<7>")
	)
	(segment
		(start 343.699084 -212.038692)
		(end 343.741248 -211.996528)
		(width 0.0889)
		(layer "In4.Cu")
		(net "UPI_CPU1_CPU0_P1P0_DN<7>")
	)
	(segment
		(start 343.889076 -215.762586)
		(end 343.886282 -215.761062)
		(width 0.0889)
		(layer "In4.Cu")
		(net "UPI_CPU1_CPU0_P1P0_DN<7>")
	)
	(segment
		(start 135.61695 -198.191374)
		(end 129.552446 -205.650592)
		(width 0.14732)
		(layer "In4.Cu")
		(net "UPI_CPU1_CPU0_P1P0_DN<7>")
	)
	(segment
		(start 343.885266 -215.112854)
		(end 343.886282 -215.112346)
		(width 0.0889)
		(layer "In4.Cu")
		(net "UPI_CPU1_CPU0_P1P0_DN<7>")
	)
	(segment
		(start 343.892378 -215.764618)
		(end 343.889076 -215.762586)
		(width 0.0889)
		(layer "In4.Cu")
		(net "UPI_CPU1_CPU0_P1P0_DN<7>")
	)
	(arc
		(start 127.334264 -217.388694)
		(mid 127.131978 -217.587675)
		(end 127.051816 -217.859864)
		(width 0.0889)
		(layer "In4.Cu")
		(net "UPI_CPU1_CPU0_P1P0_DN<7>")
	)
	(arc
		(start 343.883234 -214.093298)
		(mid 343.774087 -214.00937)
		(end 343.699084 -213.893908)
		(width 0.0889)
		(layer "In4.Cu")
		(net "UPI_CPU1_CPU0_P1P0_DN<7>")
	)
	(arc
		(start 127.807212 -214.261446)
		(mid 127.898255 -214.327132)
		(end 127.967994 -214.415116)
		(width 0.0889)
		(layer "In4.Cu")
		(net "UPI_CPU1_CPU0_P1P0_DN<7>")
	)
	(arc
		(start 344.168476 -214.424768)
		(mid 344.057197 -214.232062)
		(end 343.883234 -214.093298)
		(width 0.0889)
		(layer "In4.Cu")
		(net "UPI_CPU1_CPU0_P1P0_DN<7>")
	)
	(arc
		(start 127.521462 -217.072972)
		(mid 127.469192 -217.255337)
		(end 127.334264 -217.388694)
		(width 0.0889)
		(layer "In4.Cu")
		(net "UPI_CPU1_CPU0_P1P0_DN<7>")
	)
	(arc
		(start 127.990854 -214.637366)
		(mid 127.9398 -214.811946)
		(end 127.812546 -214.941912)
		(width 0.0889)
		(layer "In4.Cu")
		(net "UPI_CPU1_CPU0_P1P0_DN<7>")
	)
	(arc
		(start 343.886282 -215.112346)
		(mid 344.087564 -214.914859)
		(end 344.168476 -214.644732)
		(width 0.0889)
		(layer "In4.Cu")
		(net "UPI_CPU1_CPU0_P1P0_DN<7>")
	)
	(arc
		(start 127.262382 -218.319096)
		(mid 127.270702 -218.325653)
		(end 127.279146 -218.33205)
		(width 0.0889)
		(layer "In4.Cu")
		(net "UPI_CPU1_CPU0_P1P0_DN<7>")
	)
	(arc
		(start 343.699084 -217.0557)
		(mid 343.751354 -216.873335)
		(end 343.886282 -216.739978)
		(width 0.0889)
		(layer "In4.Cu")
		(net "UPI_CPU1_CPU0_P1P0_DN<7>")
	)
	(arc
		(start 127.521716 -213.78672)
		(mid 127.598479 -214.063753)
		(end 127.807212 -214.261446)
		(width 0.0889)
		(layer "In4.Cu")
		(net "UPI_CPU1_CPU0_P1P0_DN<7>")
	)
	(arc
		(start 343.699084 -215.421972)
		(mid 343.750138 -215.247392)
		(end 343.877392 -215.117426)
		(width 0.0889)
		(layer "In4.Cu")
		(net "UPI_CPU1_CPU0_P1P0_DN<7>")
	)
	(arc
		(start 127.33401 -215.761062)
		(mid 127.131187 -215.961293)
		(end 127.051816 -216.235026)
		(width 0.0889)
		(layer "In4.Cu")
		(net "UPI_CPU1_CPU0_P1P0_DN<7>")
	)
	(arc
		(start 343.839038 -217.356182)
		(mid 343.737717 -217.230061)
		(end 343.699084 -217.072972)
		(width 0.0889)
		(layer "In4.Cu")
		(net "UPI_CPU1_CPU0_P1P0_DN<7>")
	)
	(arc
		(start 127.521462 -215.436704)
		(mid 127.473783 -215.619604)
		(end 127.3429 -215.755982)
		(width 0.0889)
		(layer "In4.Cu")
		(net "UPI_CPU1_CPU0_P1P0_DN<7>")
	)
	(arc
		(start 343.877392 -215.755982)
		(mid 343.746478 -215.619622)
		(end 343.69883 -215.436704)
		(width 0.0889)
		(layer "In4.Cu")
		(net "UPI_CPU1_CPU0_P1P0_DN<7>")
	)
	(arc
		(start 343.69883 -215.436704)
		(mid 343.698882 -215.429337)
		(end 343.699084 -215.421972)
		(width 0.0889)
		(layer "In4.Cu")
		(net "UPI_CPU1_CPU0_P1P0_DN<7>")
	)
	(arc
		(start 127.051816 -216.260426)
		(mid 127.129927 -216.537375)
		(end 127.334264 -216.739978)
		(width 0.0889)
		(layer "In4.Cu")
		(net "UPI_CPU1_CPU0_P1P0_DN<7>")
	)
	(arc
		(start 127.051816 -217.8939)
		(mid 127.110369 -218.12963)
		(end 127.262382 -218.319096)
		(width 0.0889)
		(layer "In4.Cu")
		(net "UPI_CPU1_CPU0_P1P0_DN<7>")
	)
	(arc
		(start 127.991108 -214.622634)
		(mid 127.991056 -214.630001)
		(end 127.990854 -214.637366)
		(width 0.0889)
		(layer "In4.Cu")
		(net "UPI_CPU1_CPU0_P1P0_DN<7>")
	)
	(arc
		(start 127.967994 -214.415116)
		(mid 127.985263 -214.456501)
		(end 127.991108 -214.500968)
		(width 0.0889)
		(layer "In4.Cu")
		(net "UPI_CPU1_CPU0_P1P0_DN<7>")
	)
	(arc
		(start 343.892378 -216.736422)
		(mid 344.168952 -216.25052)
		(end 343.892378 -215.764618)
		(width 0.0889)
		(layer "In4.Cu")
		(net "UPI_CPU1_CPU0_P1P0_DN<7>")
	)
	(arc
		(start 127.334264 -216.739978)
		(mid 127.469197 -216.873332)
		(end 127.521462 -217.0557)
		(width 0.0889)
		(layer "In4.Cu")
		(net "UPI_CPU1_CPU0_P1P0_DN<7>")
	)
	(arc
		(start 127.803656 -214.946992)
		(mid 127.602374 -215.144479)
		(end 127.521462 -215.414606)
		(width 0.0889)
		(layer "In4.Cu")
		(net "UPI_CPU1_CPU0_P1P0_DN<7>")
	)
	(segment
		(start 342.66378 -217.87866)
		(end 342.664034 -217.878406)
		(width 0.13208)
		(layer "F.Cu")
		(net "UPI_CPU1_CPU0_P1P0_DN<6>")
	)
	(segment
		(start 128.556512 -217.87866)
		(end 128.556766 -217.878406)
		(width 0.13208)
		(layer "F.Cu")
		(net "UPI_CPU1_CPU0_P1P0_DN<6>")
	)
	(segment
		(start 128.556512 -218.414346)
		(end 128.556512 -217.87866)
		(width 0.13208)
		(layer "F.Cu")
		(net "UPI_CPU1_CPU0_P1P0_DN<6>")
	)
	(segment
		(start 342.66378 -218.414346)
		(end 342.66378 -217.87866)
		(width 0.13208)
		(layer "F.Cu")
		(net "UPI_CPU1_CPU0_P1P0_DN<6>")
	)
	(segment
		(start 273.241516 -184.205372)
		(end 250.52147 -184.313576)
		(width 0.14732)
		(layer "In4.Cu")
		(net "UPI_CPU1_CPU0_P1P0_DN<6>")
	)
	(segment
		(start 342.851232 -216.574878)
		(end 342.860122 -216.569798)
		(width 0.0889)
		(layer "In4.Cu")
		(net "UPI_CPU1_CPU0_P1P0_DN<6>")
	)
	(segment
		(start 131.810252 -204.649578)
		(end 130.514852 -206.242158)
		(width 0.14732)
		(layer "In4.Cu")
		(net "UPI_CPU1_CPU0_P1P0_DN<6>")
	)
	(segment
		(start 342.469724 -212.533738)
		(end 342.568784 -212.434678)
		(width 0.0889)
		(layer "In4.Cu")
		(net "UPI_CPU1_CPU0_P1P0_DN<6>")
	)
	(segment
		(start 128.369568 -215.926162)
		(end 128.360678 -215.931242)
		(width 0.0889)
		(layer "In4.Cu")
		(net "UPI_CPU1_CPU0_P1P0_DN<6>")
	)
	(segment
		(start 325.0057 -189.827662)
		(end 324.802246 -189.850776)
		(width 0.14732)
		(layer "In4.Cu")
		(net "UPI_CPU1_CPU0_P1P0_DN<6>")
	)
	(segment
		(start 342.843612 -216.579196)
		(end 342.847422 -216.577164)
		(width 0.0889)
		(layer "In4.Cu")
		(net "UPI_CPU1_CPU0_P1P0_DN<6>")
	)
	(segment
		(start 128.693926 -211.602828)
		(end 128.69418 -211.603082)
		(width 0.14732)
		(layer "In4.Cu")
		(net "UPI_CPU1_CPU0_P1P0_DN<6>")
	)
	(segment
		(start 342.568784 -212.808058)
		(end 342.469724 -212.708998)
		(width 0.0889)
		(layer "In4.Cu")
		(net "UPI_CPU1_CPU0_P1P0_DN<6>")
	)
	(segment
		(start 319.030604 -186.353958)
		(end 318.69126 -186.210956)
		(width 0.14732)
		(layer "In4.Cu")
		(net "UPI_CPU1_CPU0_P1P0_DN<6>")
	)
	(segment
		(start 342.83904 -216.58199)
		(end 342.843612 -216.579196)
		(width 0.0889)
		(layer "In4.Cu")
		(net "UPI_CPU1_CPU0_P1P0_DN<6>")
	)
	(segment
		(start 316.270894 -185.34761)
		(end 316.193678 -185.157618)
		(width 0.14732)
		(layer "In4.Cu")
		(net "UPI_CPU1_CPU0_P1P0_DN<6>")
	)
	(segment
		(start 342.860122 -215.931242)
		(end 342.852756 -215.926924)
		(width 0.0889)
		(layer "In4.Cu")
		(net "UPI_CPU1_CPU0_P1P0_DN<6>")
	)
	(segment
		(start 342.847422 -216.577164)
		(end 342.851232 -216.574878)
		(width 0.0889)
		(layer "In4.Cu")
		(net "UPI_CPU1_CPU0_P1P0_DN<6>")
	)
	(segment
		(start 319.976246 -186.752738)
		(end 319.636902 -186.609736)
		(width 0.14732)
		(layer "In4.Cu")
		(net "UPI_CPU1_CPU0_P1P0_DN<6>")
	)
	(segment
		(start 342.851994 -217.554556)
		(end 342.851232 -217.554048)
		(width 0.0889)
		(layer "In4.Cu")
		(net "UPI_CPU1_CPU0_P1P0_DN<6>")
	)
	(segment
		(start 325.316342 -190.260732)
		(end 325.293482 -190.057278)
		(width 0.14732)
		(layer "In4.Cu")
		(net "UPI_CPU1_CPU0_P1P0_DN<6>")
	)
	(segment
		(start 128.69418 -211.849208)
		(end 128.652016 -211.891372)
		(width 0.0889)
		(layer "In4.Cu")
		(net "UPI_CPU1_CPU0_P1P0_DN<6>")
	)
	(segment
		(start 316.193678 -185.157618)
		(end 314.048902 -184.253632)
		(width 0.14732)
		(layer "In4.Cu")
		(net "UPI_CPU1_CPU0_P1P0_DN<6>")
	)
	(segment
		(start 317.216282 -185.746136)
		(end 317.13932 -185.556398)
		(width 0.14732)
		(layer "In4.Cu")
		(net "UPI_CPU1_CPU0_P1P0_DN<6>")
	)
	(segment
		(start 323.68871 -188.777372)
		(end 322.787518 -188.058806)
		(width 0.14732)
		(layer "In4.Cu")
		(net "UPI_CPU1_CPU0_P1P0_DN<6>")
	)
	(segment
		(start 326.98436 -191.278764)
		(end 326.287384 -190.849758)
		(width 0.14732)
		(layer "In4.Cu")
		(net "UPI_CPU1_CPU0_P1P0_DN<6>")
	)
	(segment
		(start 159.500824 -184.438798)
		(end 152.948132 -186.116214)
		(width 0.14732)
		(layer "In4.Cu")
		(net "UPI_CPU1_CPU0_P1P0_DN<6>")
	)
	(segment
		(start 342.469724 -213.257638)
		(end 342.469724 -213.082378)
		(width 0.0889)
		(layer "In4.Cu")
		(net "UPI_CPU1_CPU0_P1P0_DN<6>")
	)
	(segment
		(start 318.084962 -185.955178)
		(end 317.745618 -185.812176)
		(width 0.14732)
		(layer "In4.Cu")
		(net "UPI_CPU1_CPU0_P1P0_DN<6>")
	)
	(segment
		(start 324.491096 -189.417452)
		(end 324.203314 -189.187836)
		(width 0.14732)
		(layer "In4.Cu")
		(net "UPI_CPU1_CPU0_P1P0_DN<6>")
	)
	(segment
		(start 128.69418 -211.603082)
		(end 128.69418 -211.82711)
		(width 0.14732)
		(layer "In4.Cu")
		(net "UPI_CPU1_CPU0_P1P0_DN<6>")
	)
	(segment
		(start 342.85047 -215.925654)
		(end 342.845136 -215.922606)
		(width 0.0889)
		(layer "In4.Cu")
		(net "UPI_CPU1_CPU0_P1P0_DN<6>")
	)
	(segment
		(start 129.121154 -214.501222)
		(end 129.121408 -214.644732)
		(width 0.0889)
		(layer "In4.Cu")
		(net "UPI_CPU1_CPU0_P1P0_DN<6>")
	)
	(segment
		(start 325.808086 -190.467488)
		(end 325.604632 -190.490602)
		(width 0.14732)
		(layer "In4.Cu")
		(net "UPI_CPU1_CPU0_P1P0_DN<6>")
	)
	(segment
		(start 128.839214 -215.112346)
		(end 128.838198 -215.112854)
		(width 0.0889)
		(layer "In4.Cu")
		(net "UPI_CPU1_CPU0_P1P0_DN<6>")
	)
	(segment
		(start 342.568784 -212.983318)
		(end 342.568784 -212.808058)
		(width 0.0889)
		(layer "In4.Cu")
		(net "UPI_CPU1_CPU0_P1P0_DN<6>")
	)
	(segment
		(start 320.053462 -186.942476)
		(end 319.976246 -186.752738)
		(width 0.14732)
		(layer "In4.Cu")
		(net "UPI_CPU1_CPU0_P1P0_DN<6>")
	)
	(segment
		(start 316.799976 -185.413396)
		(end 316.610492 -185.490612)
		(width 0.14732)
		(layer "In4.Cu")
		(net "UPI_CPU1_CPU0_P1P0_DN<6>")
	)
	(segment
		(start 149.155404 -188.05779)
		(end 147.982432 -189.170056)
		(width 0.14732)
		(layer "In4.Cu")
		(net "UPI_CPU1_CPU0_P1P0_DN<6>")
	)
	(segment
		(start 325.293482 -190.057278)
		(end 325.0057 -189.827662)
		(width 0.14732)
		(layer "In4.Cu")
		(net "UPI_CPU1_CPU0_P1P0_DN<6>")
	)
	(segment
		(start 326.287384 -190.849758)
		(end 325.808086 -190.467488)
		(width 0.14732)
		(layer "In4.Cu")
		(net "UPI_CPU1_CPU0_P1P0_DN<6>")
	)
	(segment
		(start 342.469724 -212.708998)
		(end 342.469724 -212.533738)
		(width 0.0889)
		(layer "In4.Cu")
		(net "UPI_CPU1_CPU0_P1P0_DN<6>")
	)
	(segment
		(start 317.745618 -185.812176)
		(end 317.556134 -185.889392)
		(width 0.14732)
		(layer "In4.Cu")
		(net "UPI_CPU1_CPU0_P1P0_DN<6>")
	)
	(segment
		(start 324.802246 -189.850776)
		(end 324.513956 -189.620906)
		(width 0.14732)
		(layer "In4.Cu")
		(net "UPI_CPU1_CPU0_P1P0_DN<6>")
	)
	(segment
		(start 152.948132 -186.116214)
		(end 149.155404 -188.05779)
		(width 0.14732)
		(layer "In4.Cu")
		(net "UPI_CPU1_CPU0_P1P0_DN<6>")
	)
	(segment
		(start 324.203314 -189.187836)
		(end 323.99986 -189.210696)
		(width 0.14732)
		(layer "In4.Cu")
		(net "UPI_CPU1_CPU0_P1P0_DN<6>")
	)
	(segment
		(start 131.810252 -204.649324)
		(end 131.810252 -204.649578)
		(width 0.14732)
		(layer "In4.Cu")
		(net "UPI_CPU1_CPU0_P1P0_DN<6>")
	)
	(segment
		(start 321.69227 -187.475876)
		(end 320.582544 -187.008262)
		(width 0.14732)
		(layer "In4.Cu")
		(net "UPI_CPU1_CPU0_P1P0_DN<6>")
	)
	(segment
		(start 342.526874 -211.996528)
		(end 342.526874 -211.97443)
		(width 0.0889)
		(layer "In4.Cu")
		(net "UPI_CPU1_CPU0_P1P0_DN<6>")
	)
	(segment
		(start 342.852756 -215.926924)
		(end 342.851232 -215.926162)
		(width 0.0889)
		(layer "In4.Cu")
		(net "UPI_CPU1_CPU0_P1P0_DN<6>")
	)
	(segment
		(start 342.526874 -211.97443)
		(end 342.526874 -211.742274)
		(width 0.14732)
		(layer "In4.Cu")
		(net "UPI_CPU1_CPU0_P1P0_DN<6>")
	)
	(segment
		(start 343.71788 -208.801208)
		(end 343.71788 -205.25359)
		(width 0.14732)
		(layer "In4.Cu")
		(net "UPI_CPU1_CPU0_P1P0_DN<6>")
	)
	(segment
		(start 343.038176 -214.622634)
		(end 343.038176 -214.461344)
		(width 0.0889)
		(layer "In4.Cu")
		(net "UPI_CPU1_CPU0_P1P0_DN<6>")
	)
	(segment
		(start 200.152508 -183.763666)
		(end 159.500824 -184.438798)
		(width 0.14732)
		(layer "In4.Cu")
		(net "UPI_CPU1_CPU0_P1P0_DN<6>")
	)
	(segment
		(start 133.10616 -203.055728)
		(end 131.810252 -204.649324)
		(width 0.14732)
		(layer "In4.Cu")
		(net "UPI_CPU1_CPU0_P1P0_DN<6>")
	)
	(segment
		(start 128.838198 -215.112854)
		(end 128.830324 -215.117426)
		(width 0.0889)
		(layer "In4.Cu")
		(net "UPI_CPU1_CPU0_P1P0_DN<6>")
	)
	(segment
		(start 128.360678 -216.569798)
		(end 128.369568 -216.574878)
		(width 0.0889)
		(layer "In4.Cu")
		(net "UPI_CPU1_CPU0_P1P0_DN<6>")
	)
	(segment
		(start 250.50623 -184.313576)
		(end 238.634778 -184.370218)
		(width 0.14732)
		(layer "In4.Cu")
		(net "UPI_CPU1_CPU0_P1P0_DN<6>")
	)
	(segment
		(start 342.851232 -215.926162)
		(end 342.85047 -215.925654)
		(width 0.0889)
		(layer "In4.Cu")
		(net "UPI_CPU1_CPU0_P1P0_DN<6>")
	)
	(segment
		(start 342.850724 -214.946992)
		(end 342.859614 -214.941912)
		(width 0.0889)
		(layer "In4.Cu")
		(net "UPI_CPU1_CPU0_P1P0_DN<6>")
	)
	(segment
		(start 325.604632 -190.490602)
		(end 325.316342 -190.260732)
		(width 0.14732)
		(layer "In4.Cu")
		(net "UPI_CPU1_CPU0_P1P0_DN<6>")
	)
	(segment
		(start 142.256764 -196.85508)
		(end 141.886178 -197.20687)
		(width 0.14732)
		(layer "In4.Cu")
		(net "UPI_CPU1_CPU0_P1P0_DN<6>")
	)
	(segment
		(start 318.501776 -186.288172)
		(end 318.161924 -186.144916)
		(width 0.14732)
		(layer "In4.Cu")
		(net "UPI_CPU1_CPU0_P1P0_DN<6>")
	)
	(segment
		(start 318.69126 -186.210956)
		(end 318.501776 -186.288172)
		(width 0.14732)
		(layer "In4.Cu")
		(net "UPI_CPU1_CPU0_P1P0_DN<6>")
	)
	(segment
		(start 342.56853 -217.071956)
		(end 342.56853 -217.064336)
		(width 0.0889)
		(layer "In4.Cu")
		(net "UPI_CPU1_CPU0_P1P0_DN<6>")
	)
	(segment
		(start 213.955122 -184.370218)
		(end 200.152508 -183.763666)
		(width 0.14732)
		(layer "In4.Cu")
		(net "UPI_CPU1_CPU0_P1P0_DN<6>")
	)
	(segment
		(start 342.413336 -202.104244)
		(end 336.402172 -196.09308)
		(width 0.14732)
		(layer "In4.Cu")
		(net "UPI_CPU1_CPU0_P1P0_DN<6>")
	)
	(segment
		(start 141.886178 -197.20687)
		(end 133.10616 -203.055728)
		(width 0.14732)
		(layer "In4.Cu")
		(net "UPI_CPU1_CPU0_P1P0_DN<6>")
	)
	(segment
		(start 130.514852 -206.242158)
		(end 128.693926 -211.442046)
		(width 0.14732)
		(layer "In4.Cu")
		(net "UPI_CPU1_CPU0_P1P0_DN<6>")
	)
	(segment
		(start 128.69418 -211.82711)
		(end 128.69418 -211.849208)
		(width 0.0889)
		(layer "In4.Cu")
		(net "UPI_CPU1_CPU0_P1P0_DN<6>")
	)
	(segment
		(start 319.636902 -186.609736)
		(end 319.447418 -186.686952)
		(width 0.14732)
		(layer "In4.Cu")
		(net "UPI_CPU1_CPU0_P1P0_DN<6>")
	)
	(segment
		(start 238.634778 -184.370218)
		(end 213.955122 -184.370218)
		(width 0.14732)
		(layer "In4.Cu")
		(net "UPI_CPU1_CPU0_P1P0_DN<6>")
	)
	(segment
		(start 342.52662 -211.74202)
		(end 342.52662 -209.992468)
		(width 0.14732)
		(layer "In4.Cu")
		(net "UPI_CPU1_CPU0_P1P0_DN<6>")
	)
	(segment
		(start 333.024734 -193.43624)
		(end 333.02448 -193.43624)
		(width 0.14732)
		(layer "In4.Cu")
		(net "UPI_CPU1_CPU0_P1P0_DN<6>")
	)
	(segment
		(start 320.39306 -187.085478)
		(end 320.053462 -186.942476)
		(width 0.14732)
		(layer "In4.Cu")
		(net "UPI_CPU1_CPU0_P1P0_DN<6>")
	)
	(segment
		(start 342.469724 -213.082378)
		(end 342.568784 -212.983318)
		(width 0.0889)
		(layer "In4.Cu")
		(net "UPI_CPU1_CPU0_P1P0_DN<6>")
	)
	(segment
		(start 314.048902 -184.253632)
		(end 312.32348 -183.712358)
		(width 0.14732)
		(layer "In4.Cu")
		(net "UPI_CPU1_CPU0_P1P0_DN<6>")
	)
	(segment
		(start 317.13932 -185.556398)
		(end 316.799976 -185.413396)
		(width 0.14732)
		(layer "In4.Cu")
		(net "UPI_CPU1_CPU0_P1P0_DN<6>")
	)
	(segment
		(start 333.02448 -193.43624)
		(end 326.98436 -191.278764)
		(width 0.14732)
		(layer "In4.Cu")
		(net "UPI_CPU1_CPU0_P1P0_DN<6>")
	)
	(segment
		(start 322.787518 -188.058806)
		(end 321.69227 -187.475876)
		(width 0.14732)
		(layer "In4.Cu")
		(net "UPI_CPU1_CPU0_P1P0_DN<6>")
	)
	(segment
		(start 147.982432 -189.170056)
		(end 142.256764 -196.85508)
		(width 0.14732)
		(layer "In4.Cu")
		(net "UPI_CPU1_CPU0_P1P0_DN<6>")
	)
	(segment
		(start 319.447418 -186.686952)
		(end 319.10782 -186.543696)
		(width 0.14732)
		(layer "In4.Cu")
		(net "UPI_CPU1_CPU0_P1P0_DN<6>")
	)
	(segment
		(start 128.369568 -216.574878)
		(end 128.375664 -216.578434)
		(width 0.0889)
		(layer "In4.Cu")
		(net "UPI_CPU1_CPU0_P1P0_DN<6>")
	)
	(segment
		(start 128.424432 -217.518234)
		(end 128.400302 -217.607388)
		(width 0.0889)
		(layer "In4.Cu")
		(net "UPI_CPU1_CPU0_P1P0_DN<6>")
	)
	(segment
		(start 317.556134 -185.889392)
		(end 317.216282 -185.746136)
		(width 0.14732)
		(layer "In4.Cu")
		(net "UPI_CPU1_CPU0_P1P0_DN<6>")
	)
	(segment
		(start 324.513956 -189.620906)
		(end 324.491096 -189.417452)
		(width 0.14732)
		(layer "In4.Cu")
		(net "UPI_CPU1_CPU0_P1P0_DN<6>")
	)
	(segment
		(start 250.52147 -184.313576)
		(end 250.50623 -184.313576)
		(width 0.14732)
		(layer "In4.Cu")
		(net "UPI_CPU1_CPU0_P1P0_DN<6>")
	)
	(segment
		(start 342.664034 -217.878406)
		(end 342.820498 -218.149424)
		(width 0.0889)
		(layer "In4.Cu")
		(net "UPI_CPU1_CPU0_P1P0_DN<6>")
	)
	(segment
		(start 336.402172 -196.09308)
		(end 333.024734 -193.43624)
		(width 0.14732)
		(layer "In4.Cu")
		(net "UPI_CPU1_CPU0_P1P0_DN<6>")
	)
	(segment
		(start 128.652016 -211.891372)
		(end 128.652016 -213.787482)
		(width 0.0889)
		(layer "In4.Cu")
		(net "UPI_CPU1_CPU0_P1P0_DN<6>")
	)
	(segment
		(start 342.526874 -211.742274)
		(end 342.52662 -211.74202)
		(width 0.14732)
		(layer "In4.Cu")
		(net "UPI_CPU1_CPU0_P1P0_DN<6>")
	)
	(segment
		(start 342.52662 -209.992468)
		(end 343.71788 -208.801208)
		(width 0.14732)
		(layer "In4.Cu")
		(net "UPI_CPU1_CPU0_P1P0_DN<6>")
	)
	(segment
		(start 312.32348 -183.712358)
		(end 301.693072 -183.516524)
		(width 0.14732)
		(layer "In4.Cu")
		(net "UPI_CPU1_CPU0_P1P0_DN<6>")
	)
	(segment
		(start 323.71157 -188.980826)
		(end 323.68871 -188.777372)
		(width 0.14732)
		(layer "In4.Cu")
		(net "UPI_CPU1_CPU0_P1P0_DN<6>")
	)
	(segment
		(start 342.56853 -215.436704)
		(end 342.56853 -215.414606)
		(width 0.0889)
		(layer "In4.Cu")
		(net "UPI_CPU1_CPU0_P1P0_DN<6>")
	)
	(segment
		(start 320.582544 -187.008262)
		(end 320.39306 -187.085478)
		(width 0.14732)
		(layer "In4.Cu")
		(net "UPI_CPU1_CPU0_P1P0_DN<6>")
	)
	(segment
		(start 128.651762 -215.436704)
		(end 128.651762 -215.452198)
		(width 0.0889)
		(layer "In4.Cu")
		(net "UPI_CPU1_CPU0_P1P0_DN<6>")
	)
	(segment
		(start 342.568784 -213.930484)
		(end 342.568784 -213.356698)
		(width 0.0889)
		(layer "In4.Cu")
		(net "UPI_CPU1_CPU0_P1P0_DN<6>")
	)
	(segment
		(start 342.860122 -217.559128)
		(end 342.851994 -217.554556)
		(width 0.0889)
		(layer "In4.Cu")
		(net "UPI_CPU1_CPU0_P1P0_DN<6>")
	)
	(segment
		(start 316.610492 -185.490612)
		(end 316.270894 -185.34761)
		(width 0.14732)
		(layer "In4.Cu")
		(net "UPI_CPU1_CPU0_P1P0_DN<6>")
	)
	(segment
		(start 342.820498 -218.149424)
		(end 342.89873 -218.170252)
		(width 0.0889)
		(layer "In4.Cu")
		(net "UPI_CPU1_CPU0_P1P0_DN<6>")
	)
	(segment
		(start 128.693926 -211.442046)
		(end 128.693926 -211.602828)
		(width 0.14732)
		(layer "In4.Cu")
		(net "UPI_CPU1_CPU0_P1P0_DN<6>")
	)
	(segment
		(start 318.161924 -186.144916)
		(end 318.084962 -185.955178)
		(width 0.14732)
		(layer "In4.Cu")
		(net "UPI_CPU1_CPU0_P1P0_DN<6>")
	)
	(segment
		(start 342.568784 -212.038438)
		(end 342.526874 -211.996528)
		(width 0.0889)
		(layer "In4.Cu")
		(net "UPI_CPU1_CPU0_P1P0_DN<6>")
	)
	(segment
		(start 343.71788 -205.25359)
		(end 342.413336 -202.104244)
		(width 0.14732)
		(layer "In4.Cu")
		(net "UPI_CPU1_CPU0_P1P0_DN<6>")
	)
	(segment
		(start 342.568784 -213.356698)
		(end 342.469724 -213.257638)
		(width 0.0889)
		(layer "In4.Cu")
		(net "UPI_CPU1_CPU0_P1P0_DN<6>")
	)
	(segment
		(start 128.400302 -217.607388)
		(end 128.556766 -217.878406)
		(width 0.0889)
		(layer "In4.Cu")
		(net "UPI_CPU1_CPU0_P1P0_DN<6>")
	)
	(segment
		(start 323.99986 -189.210696)
		(end 323.71157 -188.980826)
		(width 0.14732)
		(layer "In4.Cu")
		(net "UPI_CPU1_CPU0_P1P0_DN<6>")
	)
	(segment
		(start 301.693072 -183.516524)
		(end 273.241516 -184.205372)
		(width 0.14732)
		(layer "In4.Cu")
		(net "UPI_CPU1_CPU0_P1P0_DN<6>")
	)
	(segment
		(start 319.10782 -186.543696)
		(end 319.030604 -186.353958)
		(width 0.14732)
		(layer "In4.Cu")
		(net "UPI_CPU1_CPU0_P1P0_DN<6>")
	)
	(segment
		(start 128.652016 -217.064336)
		(end 128.652016 -217.07856)
		(width 0.0889)
		(layer "In4.Cu")
		(net "UPI_CPU1_CPU0_P1P0_DN<6>")
	)
	(segment
		(start 342.568784 -212.434678)
		(end 342.568784 -212.038438)
		(width 0.0889)
		(layer "In4.Cu")
		(net "UPI_CPU1_CPU0_P1P0_DN<6>")
	)
	(arc
		(start 128.375664 -216.578434)
		(mid 128.578077 -216.784847)
		(end 128.652016 -217.064336)
		(width 0.0889)
		(layer "In4.Cu")
		(net "UPI_CPU1_CPU0_P1P0_DN<6>")
	)
	(arc
		(start 343.038176 -214.461344)
		(mid 342.963171 -214.345885)
		(end 342.854026 -214.261954)
		(width 0.0889)
		(layer "In4.Cu")
		(net "UPI_CPU1_CPU0_P1P0_DN<6>")
	)
	(arc
		(start 342.859614 -214.941912)
		(mid 342.990528 -214.805552)
		(end 343.038176 -214.622634)
		(width 0.0889)
		(layer "In4.Cu")
		(net "UPI_CPU1_CPU0_P1P0_DN<6>")
	)
	(arc
		(start 128.360678 -215.931242)
		(mid 128.182202 -216.25052)
		(end 128.360678 -216.569798)
		(width 0.0889)
		(layer "In4.Cu")
		(net "UPI_CPU1_CPU0_P1P0_DN<6>")
	)
	(arc
		(start 129.121408 -214.644732)
		(mid 129.040497 -214.91486)
		(end 128.839214 -215.112346)
		(width 0.0889)
		(layer "In4.Cu")
		(net "UPI_CPU1_CPU0_P1P0_DN<6>")
	)
	(arc
		(start 128.652016 -217.07856)
		(mid 128.593655 -217.315158)
		(end 128.441196 -217.50528)
		(width 0.0889)
		(layer "In4.Cu")
		(net "UPI_CPU1_CPU0_P1P0_DN<6>")
	)
	(arc
		(start 342.56853 -215.414606)
		(mid 342.649441 -215.144478)
		(end 342.850724 -214.946992)
		(width 0.0889)
		(layer "In4.Cu")
		(net "UPI_CPU1_CPU0_P1P0_DN<6>")
	)
	(arc
		(start 342.89873 -218.170252)
		(mid 343.001875 -218.040227)
		(end 343.038684 -217.878406)
		(width 0.0889)
		(layer "In4.Cu")
		(net "UPI_CPU1_CPU0_P1P0_DN<6>")
	)
	(arc
		(start 342.845136 -215.922606)
		(mid 342.642549 -215.716255)
		(end 342.56853 -215.436704)
		(width 0.0889)
		(layer "In4.Cu")
		(net "UPI_CPU1_CPU0_P1P0_DN<6>")
	)
	(arc
		(start 342.860122 -216.569798)
		(mid 343.038719 -216.25052)
		(end 342.860122 -215.931242)
		(width 0.0889)
		(layer "In4.Cu")
		(net "UPI_CPU1_CPU0_P1P0_DN<6>")
	)
	(arc
		(start 128.652016 -213.787482)
		(mid 128.701538 -213.966023)
		(end 128.836166 -214.093298)
		(width 0.0889)
		(layer "In4.Cu")
		(net "UPI_CPU1_CPU0_P1P0_DN<6>")
	)
	(arc
		(start 342.851232 -217.554048)
		(mid 342.64616 -217.350369)
		(end 342.56853 -217.071956)
		(width 0.0889)
		(layer "In4.Cu")
		(net "UPI_CPU1_CPU0_P1P0_DN<6>")
	)
	(arc
		(start 128.836166 -214.093298)
		(mid 128.969863 -214.189784)
		(end 129.072132 -214.319104)
		(width 0.0889)
		(layer "In4.Cu")
		(net "UPI_CPU1_CPU0_P1P0_DN<6>")
	)
	(arc
		(start 129.072132 -214.319104)
		(mid 129.108813 -214.40689)
		(end 129.121154 -214.501222)
		(width 0.0889)
		(layer "In4.Cu")
		(net "UPI_CPU1_CPU0_P1P0_DN<6>")
	)
	(arc
		(start 128.441196 -217.50528)
		(mid 128.432874 -217.511835)
		(end 128.424432 -217.518234)
		(width 0.0889)
		(layer "In4.Cu")
		(net "UPI_CPU1_CPU0_P1P0_DN<6>")
	)
	(arc
		(start 342.584024 -213.969346)
		(mid 342.576061 -213.950049)
		(end 342.568784 -213.930484)
		(width 0.0889)
		(layer "In4.Cu")
		(net "UPI_CPU1_CPU0_P1P0_DN<6>")
	)
	(arc
		(start 343.038684 -217.878406)
		(mid 342.991005 -217.695506)
		(end 342.860122 -217.559128)
		(width 0.0889)
		(layer "In4.Cu")
		(net "UPI_CPU1_CPU0_P1P0_DN<6>")
	)
	(arc
		(start 128.651762 -215.452198)
		(mid 128.572392 -215.725932)
		(end 128.369568 -215.926162)
		(width 0.0889)
		(layer "In4.Cu")
		(net "UPI_CPU1_CPU0_P1P0_DN<6>")
	)
	(arc
		(start 128.652016 -215.421972)
		(mid 128.651819 -215.429337)
		(end 128.651762 -215.436704)
		(width 0.0889)
		(layer "In4.Cu")
		(net "UPI_CPU1_CPU0_P1P0_DN<6>")
	)
	(arc
		(start 342.56853 -217.064336)
		(mid 342.640765 -216.787812)
		(end 342.83904 -216.58199)
		(width 0.0889)
		(layer "In4.Cu")
		(net "UPI_CPU1_CPU0_P1P0_DN<6>")
	)
	(arc
		(start 128.830324 -215.117426)
		(mid 128.70307 -215.247392)
		(end 128.652016 -215.421972)
		(width 0.0889)
		(layer "In4.Cu")
		(net "UPI_CPU1_CPU0_P1P0_DN<6>")
	)
	(arc
		(start 342.854026 -214.261954)
		(mid 342.693954 -214.138774)
		(end 342.584024 -213.969346)
		(width 0.0889)
		(layer "In4.Cu")
		(net "UPI_CPU1_CPU0_P1P0_DN<6>")
	)
	(segment
		(start 129.496312 -218.414346)
		(end 129.496312 -217.87866)
		(width 0.13208)
		(layer "F.Cu")
		(net "UPI_CPU1_CPU0_P1P0_DN<5>")
	)
	(segment
		(start 341.72398 -218.414346)
		(end 341.72398 -217.87866)
		(width 0.13208)
		(layer "F.Cu")
		(net "UPI_CPU1_CPU0_P1P0_DN<5>")
	)
	(segment
		(start 129.496312 -217.87866)
		(end 129.496566 -217.878406)
		(width 0.13208)
		(layer "F.Cu")
		(net "UPI_CPU1_CPU0_P1P0_DN<5>")
	)
	(segment
		(start 341.72398 -217.87866)
		(end 341.724234 -217.878406)
		(width 0.13208)
		(layer "F.Cu")
		(net "UPI_CPU1_CPU0_P1P0_DN<5>")
	)
	(segment
		(start 341.696802 -202.58913)
		(end 335.774538 -196.666866)
		(width 0.14732)
		(layer "In4.Cu")
		(net "UPI_CPU1_CPU0_P1P0_DN<5>")
	)
	(segment
		(start 341.91067 -215.925654)
		(end 341.905336 -215.922606)
		(width 0.0889)
		(layer "In4.Cu")
		(net "UPI_CPU1_CPU0_P1P0_DN<5>")
	)
	(segment
		(start 130.383026 -209.568034)
		(end 130.26136 -209.916014)
		(width 0.14732)
		(layer "In4.Cu")
		(net "UPI_CPU1_CPU0_P1P0_DN<5>")
	)
	(segment
		(start 129.690876 -213.26094)
		(end 129.591816 -213.36)
		(width 0.0889)
		(layer "In4.Cu")
		(net "UPI_CPU1_CPU0_P1P0_DN<5>")
	)
	(segment
		(start 141.441932 -198.692262)
		(end 141.134846 -198.896224)
		(width 0.14732)
		(layer "In4.Cu")
		(net "UPI_CPU1_CPU0_P1P0_DN<5>")
	)
	(segment
		(start 131.479544 -206.376524)
		(end 131.479798 -206.376778)
		(width 0.14732)
		(layer "In4.Cu")
		(net "UPI_CPU1_CPU0_P1P0_DN<5>")
	)
	(segment
		(start 250.225052 -185.149744)
		(end 250.196096 -185.149744)
		(width 0.14732)
		(layer "In4.Cu")
		(net "UPI_CPU1_CPU0_P1P0_DN<5>")
	)
	(segment
		(start 341.628984 -213.929722)
		(end 341.629238 -213.929468)
		(width 0.0889)
		(layer "In4.Cu")
		(net "UPI_CPU1_CPU0_P1P0_DN<5>")
	)
	(segment
		(start 341.587074 -211.79028)
		(end 341.587074 -209.728054)
		(width 0.14732)
		(layer "In4.Cu")
		(net "UPI_CPU1_CPU0_P1P0_DN<5>")
	)
	(segment
		(start 143.319246 -197.077076)
		(end 143.099028 -197.372732)
		(width 0.14732)
		(layer "In4.Cu")
		(net "UPI_CPU1_CPU0_P1P0_DN<5>")
	)
	(segment
		(start 342.8492 -208.465928)
		(end 342.8492 -205.371446)
		(width 0.14732)
		(layer "In4.Cu")
		(net "UPI_CPU1_CPU0_P1P0_DN<5>")
	)
	(segment
		(start 301.087028 -184.366408)
		(end 273.253962 -185.040016)
		(width 0.14732)
		(layer "In4.Cu")
		(net "UPI_CPU1_CPU0_P1P0_DN<5>")
	)
	(segment
		(start 129.591562 -215.436704)
		(end 129.591562 -215.452198)
		(width 0.0889)
		(layer "In4.Cu")
		(net "UPI_CPU1_CPU0_P1P0_DN<5>")
	)
	(segment
		(start 129.591816 -213.36)
		(end 129.591816 -213.787482)
		(width 0.0889)
		(layer "In4.Cu")
		(net "UPI_CPU1_CPU0_P1P0_DN<5>")
	)
	(segment
		(start 131.055618 -207.209898)
		(end 131.144518 -207.394302)
		(width 0.14732)
		(layer "In4.Cu")
		(net "UPI_CPU1_CPU0_P1P0_DN<5>")
	)
	(segment
		(start 131.894834 -205.865984)
		(end 131.915916 -206.069692)
		(width 0.14732)
		(layer "In4.Cu")
		(net "UPI_CPU1_CPU0_P1P0_DN<5>")
	)
	(segment
		(start 129.779014 -215.112346)
		(end 129.770124 -215.117426)
		(width 0.0889)
		(layer "In4.Cu")
		(net "UPI_CPU1_CPU0_P1P0_DN<5>")
	)
	(segment
		(start 341.908638 -216.576402)
		(end 341.911432 -216.574878)
		(width 0.0889)
		(layer "In4.Cu")
		(net "UPI_CPU1_CPU0_P1P0_DN<5>")
	)
	(segment
		(start 129.26187 -218.170252)
		(end 129.340102 -218.149424)
		(width 0.0889)
		(layer "In4.Cu")
		(net "UPI_CPU1_CPU0_P1P0_DN<5>")
	)
	(segment
		(start 341.629238 -213.929468)
		(end 341.629238 -212.101938)
		(width 0.0889)
		(layer "In4.Cu")
		(net "UPI_CPU1_CPU0_P1P0_DN<5>")
	)
	(segment
		(start 335.774538 -196.666866)
		(end 332.759304 -194.295014)
		(width 0.14732)
		(layer "In4.Cu")
		(net "UPI_CPU1_CPU0_P1P0_DN<5>")
	)
	(segment
		(start 341.587328 -212.03793)
		(end 341.587328 -211.790534)
		(width 0.14732)
		(layer "In4.Cu")
		(net "UPI_CPU1_CPU0_P1P0_DN<5>")
	)
	(segment
		(start 129.309368 -217.554048)
		(end 129.300478 -217.559128)
		(width 0.0889)
		(layer "In4.Cu")
		(net "UPI_CPU1_CPU0_P1P0_DN<5>")
	)
	(segment
		(start 139.990322 -199.483218)
		(end 133.666992 -203.686664)
		(width 0.14732)
		(layer "In4.Cu")
		(net "UPI_CPU1_CPU0_P1P0_DN<5>")
	)
	(segment
		(start 133.666992 -203.686664)
		(end 131.894834 -205.865984)
		(width 0.14732)
		(layer "In4.Cu")
		(net "UPI_CPU1_CPU0_P1P0_DN<5>")
	)
	(segment
		(start 140.934186 -198.855584)
		(end 140.93444 -198.855838)
		(width 0.14732)
		(layer "In4.Cu")
		(net "UPI_CPU1_CPU0_P1P0_DN<5>")
	)
	(segment
		(start 159.621728 -185.268108)
		(end 153.246074 -186.90082)
		(width 0.14732)
		(layer "In4.Cu")
		(net "UPI_CPU1_CPU0_P1P0_DN<5>")
	)
	(segment
		(start 129.690876 -213.08568)
		(end 129.690876 -213.26094)
		(width 0.0889)
		(layer "In4.Cu")
		(net "UPI_CPU1_CPU0_P1P0_DN<5>")
	)
	(segment
		(start 140.538454 -199.118982)
		(end 140.498068 -199.319642)
		(width 0.14732)
		(layer "In4.Cu")
		(net "UPI_CPU1_CPU0_P1P0_DN<5>")
	)
	(segment
		(start 322.420996 -189.921134)
		(end 313.717432 -185.025284)
		(width 0.14732)
		(layer "In4.Cu")
		(net "UPI_CPU1_CPU0_P1P0_DN<5>")
	)
	(segment
		(start 129.633726 -211.602828)
		(end 129.63398 -211.603082)
		(width 0.14732)
		(layer "In4.Cu")
		(net "UPI_CPU1_CPU0_P1P0_DN<5>")
	)
	(segment
		(start 312.268616 -184.571894)
		(end 301.087028 -184.366408)
		(width 0.14732)
		(layer "In4.Cu")
		(net "UPI_CPU1_CPU0_P1P0_DN<5>")
	)
	(segment
		(start 313.717432 -185.025284)
		(end 312.268616 -184.571894)
		(width 0.14732)
		(layer "In4.Cu")
		(net "UPI_CPU1_CPU0_P1P0_DN<5>")
	)
	(segment
		(start 341.628984 -213.930484)
		(end 341.628984 -213.929722)
		(width 0.0889)
		(layer "In4.Cu")
		(net "UPI_CPU1_CPU0_P1P0_DN<5>")
	)
	(segment
		(start 140.498068 -199.319642)
		(end 140.190982 -199.523604)
		(width 0.14732)
		(layer "In4.Cu")
		(net "UPI_CPU1_CPU0_P1P0_DN<5>")
	)
	(segment
		(start 130.498596 -208.799684)
		(end 130.498596 -208.800446)
		(width 0.14732)
		(layer "In4.Cu")
		(net "UPI_CPU1_CPU0_P1P0_DN<5>")
	)
	(segment
		(start 141.134846 -198.896224)
		(end 140.934186 -198.855584)
		(width 0.14732)
		(layer "In4.Cu")
		(net "UPI_CPU1_CPU0_P1P0_DN<5>")
	)
	(segment
		(start 131.915916 -206.069692)
		(end 131.683252 -206.355696)
		(width 0.14732)
		(layer "In4.Cu")
		(net "UPI_CPU1_CPU0_P1P0_DN<5>")
	)
	(segment
		(start 129.63398 -211.808568)
		(end 129.591816 -211.850732)
		(width 0.0889)
		(layer "In4.Cu")
		(net "UPI_CPU1_CPU0_P1P0_DN<5>")
	)
	(segment
		(start 130.060954 -214.501222)
		(end 130.061208 -214.644732)
		(width 0.0889)
		(layer "In4.Cu")
		(net "UPI_CPU1_CPU0_P1P0_DN<5>")
	)
	(segment
		(start 148.624544 -189.712854)
		(end 144.109186 -195.77431)
		(width 0.14732)
		(layer "In4.Cu")
		(net "UPI_CPU1_CPU0_P1P0_DN<5>")
	)
	(segment
		(start 341.587328 -211.790534)
		(end 341.587074 -211.79028)
		(width 0.14732)
		(layer "In4.Cu")
		(net "UPI_CPU1_CPU0_P1P0_DN<5>")
	)
	(segment
		(start 129.591816 -212.98662)
		(end 129.690876 -213.08568)
		(width 0.0889)
		(layer "In4.Cu")
		(net "UPI_CPU1_CPU0_P1P0_DN<5>")
	)
	(segment
		(start 129.633726 -211.270088)
		(end 129.633726 -211.602828)
		(width 0.14732)
		(layer "In4.Cu")
		(net "UPI_CPU1_CPU0_P1P0_DN<5>")
	)
	(segment
		(start 341.724234 -217.878406)
		(end 341.880698 -217.607388)
		(width 0.0889)
		(layer "In4.Cu")
		(net "UPI_CPU1_CPU0_P1P0_DN<5>")
	)
	(segment
		(start 131.144518 -207.394302)
		(end 131.022852 -207.742282)
		(width 0.14732)
		(layer "In4.Cu")
		(net "UPI_CPU1_CPU0_P1P0_DN<5>")
	)
	(segment
		(start 129.63398 -211.78647)
		(end 129.63398 -211.808568)
		(width 0.0889)
		(layer "In4.Cu")
		(net "UPI_CPU1_CPU0_P1P0_DN<5>")
	)
	(segment
		(start 141.482318 -198.491348)
		(end 141.441932 -198.692262)
		(width 0.14732)
		(layer "In4.Cu")
		(net "UPI_CPU1_CPU0_P1P0_DN<5>")
	)
	(segment
		(start 341.910924 -214.946992)
		(end 341.919814 -214.941912)
		(width 0.0889)
		(layer "In4.Cu")
		(net "UPI_CPU1_CPU0_P1P0_DN<5>")
	)
	(segment
		(start 341.629238 -212.101938)
		(end 341.587328 -212.060028)
		(width 0.0889)
		(layer "In4.Cu")
		(net "UPI_CPU1_CPU0_P1P0_DN<5>")
	)
	(segment
		(start 130.29438 -209.38363)
		(end 130.383026 -209.568034)
		(width 0.14732)
		(layer "In4.Cu")
		(net "UPI_CPU1_CPU0_P1P0_DN<5>")
	)
	(segment
		(start 143.289528 -196.874638)
		(end 143.319246 -197.077076)
		(width 0.14732)
		(layer "In4.Cu")
		(net "UPI_CPU1_CPU0_P1P0_DN<5>")
	)
	(segment
		(start 129.591816 -212.38464)
		(end 129.690876 -212.4837)
		(width 0.0889)
		(layer "In4.Cu")
		(net "UPI_CPU1_CPU0_P1P0_DN<5>")
	)
	(segment
		(start 144.109186 -195.77431)
		(end 144.138904 -195.976748)
		(width 0.14732)
		(layer "In4.Cu")
		(net "UPI_CPU1_CPU0_P1P0_DN<5>")
	)
	(segment
		(start 131.683252 -206.355696)
		(end 131.479544 -206.376524)
		(width 0.14732)
		(layer "In4.Cu")
		(net "UPI_CPU1_CPU0_P1P0_DN<5>")
	)
	(segment
		(start 341.912956 -215.926924)
		(end 341.911432 -215.926162)
		(width 0.0889)
		(layer "In4.Cu")
		(net "UPI_CPU1_CPU0_P1P0_DN<5>")
	)
	(segment
		(start 341.911432 -216.574878)
		(end 341.912956 -216.574116)
		(width 0.0889)
		(layer "In4.Cu")
		(net "UPI_CPU1_CPU0_P1P0_DN<5>")
	)
	(segment
		(start 250.196096 -185.149744)
		(end 238.637064 -185.204862)
		(width 0.14732)
		(layer "In4.Cu")
		(net "UPI_CPU1_CPU0_P1P0_DN<5>")
	)
	(segment
		(start 131.247642 -206.662274)
		(end 131.247388 -206.662274)
		(width 0.14732)
		(layer "In4.Cu")
		(net "UPI_CPU1_CPU0_P1P0_DN<5>")
	)
	(segment
		(start 130.26136 -209.916014)
		(end 130.076702 -210.00466)
		(width 0.14732)
		(layer "In4.Cu")
		(net "UPI_CPU1_CPU0_P1P0_DN<5>")
	)
	(segment
		(start 130.076702 -210.005422)
		(end 129.633726 -211.270088)
		(width 0.14732)
		(layer "In4.Cu")
		(net "UPI_CPU1_CPU0_P1P0_DN<5>")
	)
	(segment
		(start 341.912956 -216.574116)
		(end 341.920322 -216.569798)
		(width 0.0889)
		(layer "In4.Cu")
		(net "UPI_CPU1_CPU0_P1P0_DN<5>")
	)
	(segment
		(start 143.91894 -196.272404)
		(end 143.715994 -196.302122)
		(width 0.14732)
		(layer "In4.Cu")
		(net "UPI_CPU1_CPU0_P1P0_DN<5>")
	)
	(segment
		(start 129.300478 -216.569798)
		(end 129.309368 -216.574878)
		(width 0.0889)
		(layer "In4.Cu")
		(net "UPI_CPU1_CPU0_P1P0_DN<5>")
	)
	(segment
		(start 144.138904 -195.976748)
		(end 143.91894 -196.272404)
		(width 0.14732)
		(layer "In4.Cu")
		(net "UPI_CPU1_CPU0_P1P0_DN<5>")
	)
	(segment
		(start 129.591816 -212.75802)
		(end 129.591816 -212.98662)
		(width 0.0889)
		(layer "In4.Cu")
		(net "UPI_CPU1_CPU0_P1P0_DN<5>")
	)
	(segment
		(start 341.62873 -215.436704)
		(end 341.62873 -215.414606)
		(width 0.0889)
		(layer "In4.Cu")
		(net "UPI_CPU1_CPU0_P1P0_DN<5>")
	)
	(segment
		(start 129.309368 -215.926162)
		(end 129.300478 -215.931242)
		(width 0.0889)
		(layer "In4.Cu")
		(net "UPI_CPU1_CPU0_P1P0_DN<5>")
	)
	(segment
		(start 342.8492 -205.371446)
		(end 341.696802 -202.58913)
		(width 0.14732)
		(layer "In4.Cu")
		(net "UPI_CPU1_CPU0_P1P0_DN<5>")
	)
	(segment
		(start 332.759304 -194.295014)
		(end 326.0852 -191.875664)
		(width 0.14732)
		(layer "In4.Cu")
		(net "UPI_CPU1_CPU0_P1P0_DN<5>")
	)
	(segment
		(start 142.676372 -197.697598)
		(end 141.482318 -198.491348)
		(width 0.14732)
		(layer "In4.Cu")
		(net "UPI_CPU1_CPU0_P1P0_DN<5>")
	)
	(segment
		(start 140.190982 -199.523604)
		(end 139.990322 -199.483218)
		(width 0.14732)
		(layer "In4.Cu")
		(net "UPI_CPU1_CPU0_P1P0_DN<5>")
	)
	(segment
		(start 341.587074 -209.728054)
		(end 342.8492 -208.465928)
		(width 0.14732)
		(layer "In4.Cu")
		(net "UPI_CPU1_CPU0_P1P0_DN<5>")
	)
	(segment
		(start 129.63398 -211.603082)
		(end 129.63398 -211.78647)
		(width 0.14732)
		(layer "In4.Cu")
		(net "UPI_CPU1_CPU0_P1P0_DN<5>")
	)
	(segment
		(start 238.637064 -185.204862)
		(end 213.968584 -185.204862)
		(width 0.14732)
		(layer "In4.Cu")
		(net "UPI_CPU1_CPU0_P1P0_DN<5>")
	)
	(segment
		(start 130.716528 -208.178654)
		(end 130.805174 -208.362804)
		(width 0.14732)
		(layer "In4.Cu")
		(net "UPI_CPU1_CPU0_P1P0_DN<5>")
	)
	(segment
		(start 129.340102 -218.149424)
		(end 129.496566 -217.878406)
		(width 0.0889)
		(layer "In4.Cu")
		(net "UPI_CPU1_CPU0_P1P0_DN<5>")
	)
	(segment
		(start 326.0852 -191.875664)
		(end 322.420996 -189.921134)
		(width 0.14732)
		(layer "In4.Cu")
		(net "UPI_CPU1_CPU0_P1P0_DN<5>")
	)
	(segment
		(start 129.591816 -211.850732)
		(end 129.591816 -212.38464)
		(width 0.0889)
		(layer "In4.Cu")
		(net "UPI_CPU1_CPU0_P1P0_DN<5>")
	)
	(segment
		(start 149.649942 -188.741304)
		(end 148.624544 -189.712854)
		(width 0.14732)
		(layer "In4.Cu")
		(net "UPI_CPU1_CPU0_P1P0_DN<5>")
	)
	(segment
		(start 130.076702 -210.00466)
		(end 130.076702 -210.005422)
		(width 0.14732)
		(layer "In4.Cu")
		(net "UPI_CPU1_CPU0_P1P0_DN<5>")
	)
	(segment
		(start 341.911432 -215.926162)
		(end 341.91067 -215.925654)
		(width 0.0889)
		(layer "In4.Cu")
		(net "UPI_CPU1_CPU0_P1P0_DN<5>")
	)
	(segment
		(start 341.920322 -215.931242)
		(end 341.912956 -215.926924)
		(width 0.0889)
		(layer "In4.Cu")
		(net "UPI_CPU1_CPU0_P1P0_DN<5>")
	)
	(segment
		(start 130.838194 -207.830674)
		(end 130.716528 -208.178654)
		(width 0.14732)
		(layer "In4.Cu")
		(net "UPI_CPU1_CPU0_P1P0_DN<5>")
	)
	(segment
		(start 200.112884 -184.596024)
		(end 159.621728 -185.268108)
		(width 0.14732)
		(layer "In4.Cu")
		(net "UPI_CPU1_CPU0_P1P0_DN<5>")
	)
	(segment
		(start 142.896336 -197.40245)
		(end 142.676372 -197.697598)
		(width 0.14732)
		(layer "In4.Cu")
		(net "UPI_CPU1_CPU0_P1P0_DN<5>")
	)
	(segment
		(start 341.587328 -212.060028)
		(end 341.587328 -212.03793)
		(width 0.0889)
		(layer "In4.Cu")
		(net "UPI_CPU1_CPU0_P1P0_DN<5>")
	)
	(segment
		(start 129.690876 -212.4837)
		(end 129.690876 -212.65896)
		(width 0.0889)
		(layer "In4.Cu")
		(net "UPI_CPU1_CPU0_P1P0_DN<5>")
	)
	(segment
		(start 342.098376 -214.622634)
		(end 342.098376 -214.461344)
		(width 0.0889)
		(layer "In4.Cu")
		(net "UPI_CPU1_CPU0_P1P0_DN<5>")
	)
	(segment
		(start 131.247388 -206.662274)
		(end 131.055618 -207.209898)
		(width 0.14732)
		(layer "In4.Cu")
		(net "UPI_CPU1_CPU0_P1P0_DN<5>")
	)
	(segment
		(start 143.099028 -197.372732)
		(end 142.896336 -197.40245)
		(width 0.14732)
		(layer "In4.Cu")
		(net "UPI_CPU1_CPU0_P1P0_DN<5>")
	)
	(segment
		(start 129.591816 -217.05443)
		(end 129.591816 -217.082878)
		(width 0.0889)
		(layer "In4.Cu")
		(net "UPI_CPU1_CPU0_P1P0_DN<5>")
	)
	(segment
		(start 273.253962 -185.040016)
		(end 250.225052 -185.149744)
		(width 0.14732)
		(layer "In4.Cu")
		(net "UPI_CPU1_CPU0_P1P0_DN<5>")
	)
	(segment
		(start 341.905336 -216.578434)
		(end 341.908638 -216.576402)
		(width 0.0889)
		(layer "In4.Cu")
		(net "UPI_CPU1_CPU0_P1P0_DN<5>")
	)
	(segment
		(start 143.715994 -196.302122)
		(end 143.289528 -196.874638)
		(width 0.14732)
		(layer "In4.Cu")
		(net "UPI_CPU1_CPU0_P1P0_DN<5>")
	)
	(segment
		(start 153.246074 -186.90082)
		(end 149.649942 -188.741304)
		(width 0.14732)
		(layer "In4.Cu")
		(net "UPI_CPU1_CPU0_P1P0_DN<5>")
	)
	(segment
		(start 130.498596 -208.800446)
		(end 130.29438 -209.38363)
		(width 0.14732)
		(layer "In4.Cu")
		(net "UPI_CPU1_CPU0_P1P0_DN<5>")
	)
	(segment
		(start 140.93444 -198.855838)
		(end 140.538454 -199.118982)
		(width 0.14732)
		(layer "In4.Cu")
		(net "UPI_CPU1_CPU0_P1P0_DN<5>")
	)
	(segment
		(start 213.968584 -185.204862)
		(end 200.112884 -184.596024)
		(width 0.14732)
		(layer "In4.Cu")
		(net "UPI_CPU1_CPU0_P1P0_DN<5>")
	)
	(segment
		(start 131.479798 -206.376778)
		(end 131.247642 -206.662274)
		(width 0.14732)
		(layer "In4.Cu")
		(net "UPI_CPU1_CPU0_P1P0_DN<5>")
	)
	(segment
		(start 341.880698 -217.607388)
		(end 341.856568 -217.518234)
		(width 0.0889)
		(layer "In4.Cu")
		(net "UPI_CPU1_CPU0_P1P0_DN<5>")
	)
	(segment
		(start 130.805174 -208.362804)
		(end 130.683508 -208.710784)
		(width 0.14732)
		(layer "In4.Cu")
		(net "UPI_CPU1_CPU0_P1P0_DN<5>")
	)
	(segment
		(start 131.022852 -207.742282)
		(end 130.838194 -207.830674)
		(width 0.14732)
		(layer "In4.Cu")
		(net "UPI_CPU1_CPU0_P1P0_DN<5>")
	)
	(segment
		(start 130.683508 -208.710784)
		(end 130.498596 -208.799684)
		(width 0.14732)
		(layer "In4.Cu")
		(net "UPI_CPU1_CPU0_P1P0_DN<5>")
	)
	(segment
		(start 341.62873 -217.07856)
		(end 341.62873 -217.064336)
		(width 0.0889)
		(layer "In4.Cu")
		(net "UPI_CPU1_CPU0_P1P0_DN<5>")
	)
	(segment
		(start 129.690876 -212.65896)
		(end 129.591816 -212.75802)
		(width 0.0889)
		(layer "In4.Cu")
		(net "UPI_CPU1_CPU0_P1P0_DN<5>")
	)
	(arc
		(start 129.775966 -214.093298)
		(mid 129.909663 -214.189784)
		(end 130.011932 -214.319104)
		(width 0.0889)
		(layer "In4.Cu")
		(net "UPI_CPU1_CPU0_P1P0_DN<5>")
	)
	(arc
		(start 129.591562 -215.452198)
		(mid 129.512192 -215.725932)
		(end 129.309368 -215.926162)
		(width 0.0889)
		(layer "In4.Cu")
		(net "UPI_CPU1_CPU0_P1P0_DN<5>")
	)
	(arc
		(start 341.919814 -214.941912)
		(mid 342.050728 -214.805552)
		(end 342.098376 -214.622634)
		(width 0.0889)
		(layer "In4.Cu")
		(net "UPI_CPU1_CPU0_P1P0_DN<5>")
	)
	(arc
		(start 129.300478 -217.559128)
		(mid 129.169564 -217.695488)
		(end 129.121916 -217.878406)
		(width 0.0889)
		(layer "In4.Cu")
		(net "UPI_CPU1_CPU0_P1P0_DN<5>")
	)
	(arc
		(start 342.098376 -214.461344)
		(mid 342.023371 -214.345885)
		(end 341.914226 -214.261954)
		(width 0.0889)
		(layer "In4.Cu")
		(net "UPI_CPU1_CPU0_P1P0_DN<5>")
	)
	(arc
		(start 341.83955 -217.50528)
		(mid 341.687063 -217.315184)
		(end 341.62873 -217.07856)
		(width 0.0889)
		(layer "In4.Cu")
		(net "UPI_CPU1_CPU0_P1P0_DN<5>")
	)
	(arc
		(start 129.121916 -217.878406)
		(mid 129.158776 -218.040203)
		(end 129.26187 -218.170252)
		(width 0.0889)
		(layer "In4.Cu")
		(net "UPI_CPU1_CPU0_P1P0_DN<5>")
	)
	(arc
		(start 341.62873 -215.414606)
		(mid 341.709641 -215.144478)
		(end 341.910924 -214.946992)
		(width 0.0889)
		(layer "In4.Cu")
		(net "UPI_CPU1_CPU0_P1P0_DN<5>")
	)
	(arc
		(start 129.309368 -216.574878)
		(mid 129.513703 -216.777483)
		(end 129.591816 -217.05443)
		(width 0.0889)
		(layer "In4.Cu")
		(net "UPI_CPU1_CPU0_P1P0_DN<5>")
	)
	(arc
		(start 341.905336 -215.922606)
		(mid 341.702749 -215.716255)
		(end 341.62873 -215.436704)
		(width 0.0889)
		(layer "In4.Cu")
		(net "UPI_CPU1_CPU0_P1P0_DN<5>")
	)
	(arc
		(start 129.591816 -215.421972)
		(mid 129.591619 -215.429337)
		(end 129.591562 -215.436704)
		(width 0.0889)
		(layer "In4.Cu")
		(net "UPI_CPU1_CPU0_P1P0_DN<5>")
	)
	(arc
		(start 129.121916 -216.24036)
		(mid 129.121822 -216.248742)
		(end 129.121916 -216.257124)
		(width 0.0889)
		(layer "In4.Cu")
		(net "UPI_CPU1_CPU0_P1P0_DN<5>")
	)
	(arc
		(start 129.770124 -215.117426)
		(mid 129.64287 -215.247392)
		(end 129.591816 -215.421972)
		(width 0.0889)
		(layer "In4.Cu")
		(net "UPI_CPU1_CPU0_P1P0_DN<5>")
	)
	(arc
		(start 130.011932 -214.319104)
		(mid 130.048613 -214.40689)
		(end 130.060954 -214.501222)
		(width 0.0889)
		(layer "In4.Cu")
		(net "UPI_CPU1_CPU0_P1P0_DN<5>")
	)
	(arc
		(start 341.856568 -217.518234)
		(mid 341.847997 -217.511838)
		(end 341.83955 -217.50528)
		(width 0.0889)
		(layer "In4.Cu")
		(net "UPI_CPU1_CPU0_P1P0_DN<5>")
	)
	(arc
		(start 129.591816 -213.787482)
		(mid 129.641338 -213.966023)
		(end 129.775966 -214.093298)
		(width 0.0889)
		(layer "In4.Cu")
		(net "UPI_CPU1_CPU0_P1P0_DN<5>")
	)
	(arc
		(start 341.62873 -217.064336)
		(mid 341.702721 -216.78477)
		(end 341.905336 -216.578434)
		(width 0.0889)
		(layer "In4.Cu")
		(net "UPI_CPU1_CPU0_P1P0_DN<5>")
	)
	(arc
		(start 341.644224 -213.969346)
		(mid 341.636261 -213.950049)
		(end 341.628984 -213.930484)
		(width 0.0889)
		(layer "In4.Cu")
		(net "UPI_CPU1_CPU0_P1P0_DN<5>")
	)
	(arc
		(start 341.920322 -216.569798)
		(mid 342.098919 -216.25052)
		(end 341.920322 -215.931242)
		(width 0.0889)
		(layer "In4.Cu")
		(net "UPI_CPU1_CPU0_P1P0_DN<5>")
	)
	(arc
		(start 341.914226 -214.261954)
		(mid 341.754154 -214.138774)
		(end 341.644224 -213.969346)
		(width 0.0889)
		(layer "In4.Cu")
		(net "UPI_CPU1_CPU0_P1P0_DN<5>")
	)
	(arc
		(start 129.591816 -217.082878)
		(mid 129.511654 -217.355067)
		(end 129.309368 -217.554048)
		(width 0.0889)
		(layer "In4.Cu")
		(net "UPI_CPU1_CPU0_P1P0_DN<5>")
	)
	(arc
		(start 129.121916 -216.257124)
		(mid 129.171169 -216.436324)
		(end 129.300478 -216.569798)
		(width 0.0889)
		(layer "In4.Cu")
		(net "UPI_CPU1_CPU0_P1P0_DN<5>")
	)
	(arc
		(start 130.061208 -214.644732)
		(mid 129.980297 -214.91486)
		(end 129.779014 -215.112346)
		(width 0.0889)
		(layer "In4.Cu")
		(net "UPI_CPU1_CPU0_P1P0_DN<5>")
	)
	(arc
		(start 129.300478 -215.931242)
		(mid 129.172074 -216.063187)
		(end 129.121916 -216.24036)
		(width 0.0889)
		(layer "In4.Cu")
		(net "UPI_CPU1_CPU0_P1P0_DN<5>")
	)
	(segment
		(start 130.436112 -217.87866)
		(end 130.436366 -217.878406)
		(width 0.13208)
		(layer "F.Cu")
		(net "UPI_CPU1_CPU0_P1P0_DN<4>")
	)
	(segment
		(start 340.78418 -218.414346)
		(end 340.78418 -217.87866)
		(width 0.13208)
		(layer "F.Cu")
		(net "UPI_CPU1_CPU0_P1P0_DN<4>")
	)
	(segment
		(start 130.436112 -218.414346)
		(end 130.436112 -217.87866)
		(width 0.13208)
		(layer "F.Cu")
		(net "UPI_CPU1_CPU0_P1P0_DN<4>")
	)
	(segment
		(start 340.78418 -217.87866)
		(end 340.784434 -217.878406)
		(width 0.13208)
		(layer "F.Cu")
		(net "UPI_CPU1_CPU0_P1P0_DN<4>")
	)
	(segment
		(start 148.541486 -192.36436)
		(end 148.10105 -192.758314)
		(width 0.14732)
		(layer "In4.Cu")
		(net "UPI_CPU1_CPU0_P1P0_DN<4>")
	)
	(segment
		(start 200.603866 -185.448956)
		(end 159.638746 -186.13628)
		(width 0.14732)
		(layer "In4.Cu")
		(net "UPI_CPU1_CPU0_P1P0_DN<4>")
	)
	(segment
		(start 340.689184 -213.415118)
		(end 340.590124 -213.316058)
		(width 0.0889)
		(layer "In4.Cu")
		(net "UPI_CPU1_CPU0_P1P0_DN<4>")
	)
	(segment
		(start 322.77177 -191.09055)
		(end 321.973448 -190.674752)
		(width 0.14732)
		(layer "In4.Cu")
		(net "UPI_CPU1_CPU0_P1P0_DN<4>")
	)
	(segment
		(start 340.647274 -212.03793)
		(end 340.647274 -211.801202)
		(width 0.14732)
		(layer "In4.Cu")
		(net "UPI_CPU1_CPU0_P1P0_DN<4>")
	)
	(segment
		(start 150.269194 -190.819532)
		(end 149.828758 -191.213486)
		(width 0.14732)
		(layer "In4.Cu")
		(net "UPI_CPU1_CPU0_P1P0_DN<4>")
	)
	(segment
		(start 312.104024 -185.427874)
		(end 302.475392 -185.2422)
		(width 0.14732)
		(layer "In4.Cu")
		(net "UPI_CPU1_CPU0_P1P0_DN<4>")
	)
	(segment
		(start 150.476458 -190.831216)
		(end 150.269194 -190.819532)
		(width 0.14732)
		(layer "In4.Cu")
		(net "UPI_CPU1_CPU0_P1P0_DN<4>")
	)
	(segment
		(start 159.638746 -186.13628)
		(end 158.742126 -186.429396)
		(width 0.14732)
		(layer "In4.Cu")
		(net "UPI_CPU1_CPU0_P1P0_DN<4>")
	)
	(segment
		(start 157.67431 -186.9313)
		(end 157.32379 -187.045854)
		(width 0.14732)
		(layer "In4.Cu")
		(net "UPI_CPU1_CPU0_P1P0_DN<4>")
	)
	(segment
		(start 133.223 -211.6074)
		(end 133.207506 -211.622894)
		(width 0.0889)
		(layer "In4.Cu")
		(net "UPI_CPU1_CPU0_P1P0_DN<4>")
	)
	(segment
		(start 130.249168 -216.574878)
		(end 130.255264 -216.578434)
		(width 0.0889)
		(layer "In4.Cu")
		(net "UPI_CPU1_CPU0_P1P0_DN<4>")
	)
	(segment
		(start 158.116778 -186.63412)
		(end 157.766766 -186.74842)
		(width 0.14732)
		(layer "In4.Cu")
		(net "UPI_CPU1_CPU0_P1P0_DN<4>")
	)
	(segment
		(start 340.971632 -215.926162)
		(end 340.97087 -215.925654)
		(width 0.0889)
		(layer "In4.Cu")
		(net "UPI_CPU1_CPU0_P1P0_DN<4>")
	)
	(segment
		(start 147.671028 -194.647566)
		(end 147.021042 -193.920872)
		(width 0.14732)
		(layer "In4.Cu")
		(net "UPI_CPU1_CPU0_P1P0_DN<4>")
	)
	(segment
		(start 151.561292 -191.582294)
		(end 151.126444 -191.55791)
		(width 0.14732)
		(layer "In4.Cu")
		(net "UPI_CPU1_CPU0_P1P0_DN<4>")
	)
	(segment
		(start 137.01014 -207.82026)
		(end 133.223 -211.6074)
		(width 0.14732)
		(layer "In4.Cu")
		(net "UPI_CPU1_CPU0_P1P0_DN<4>")
	)
	(segment
		(start 157.141164 -186.953144)
		(end 155.308046 -187.552584)
		(width 0.14732)
		(layer "In4.Cu")
		(net "UPI_CPU1_CPU0_P1P0_DN<4>")
	)
	(segment
		(start 154.964892 -188.058806)
		(end 154.691588 -188.306456)
		(width 0.14732)
		(layer "In4.Cu")
		(net "UPI_CPU1_CPU0_P1P0_DN<4>")
	)
	(segment
		(start 340.590124 -212.592158)
		(end 340.689184 -212.493098)
		(width 0.0889)
		(layer "In4.Cu")
		(net "UPI_CPU1_CPU0_P1P0_DN<4>")
	)
	(segment
		(start 130.531362 -215.436704)
		(end 130.531362 -215.452198)
		(width 0.0889)
		(layer "In4.Cu")
		(net "UPI_CPU1_CPU0_P1P0_DN<4>")
	)
	(segment
		(start 324.069964 -191.930528)
		(end 323.74332 -191.760348)
		(width 0.14732)
		(layer "In4.Cu")
		(net "UPI_CPU1_CPU0_P1P0_DN<4>")
	)
	(segment
		(start 148.105876 -194.67195)
		(end 147.671028 -194.647566)
		(width 0.14732)
		(layer "In4.Cu")
		(net "UPI_CPU1_CPU0_P1P0_DN<4>")
	)
	(segment
		(start 147.021042 -193.920872)
		(end 146.813778 -193.909188)
		(width 0.14732)
		(layer "In4.Cu")
		(net "UPI_CPU1_CPU0_P1P0_DN<4>")
	)
	(segment
		(start 340.980522 -215.931242)
		(end 340.973156 -215.926924)
		(width 0.0889)
		(layer "In4.Cu")
		(net "UPI_CPU1_CPU0_P1P0_DN<4>")
	)
	(segment
		(start 155.308046 -187.552584)
		(end 154.974798 -187.854336)
		(width 0.14732)
		(layer "In4.Cu")
		(net "UPI_CPU1_CPU0_P1P0_DN<4>")
	)
	(segment
		(start 130.304032 -217.518234)
		(end 130.279902 -217.607388)
		(width 0.0889)
		(layer "In4.Cu")
		(net "UPI_CPU1_CPU0_P1P0_DN<4>")
	)
	(segment
		(start 148.089366 -192.965578)
		(end 148.739352 -193.692272)
		(width 0.14732)
		(layer "In4.Cu")
		(net "UPI_CPU1_CPU0_P1P0_DN<4>")
	)
	(segment
		(start 130.531616 -217.064336)
		(end 130.531616 -217.07856)
		(width 0.0889)
		(layer "In4.Cu")
		(net "UPI_CPU1_CPU0_P1P0_DN<4>")
	)
	(segment
		(start 341.99576 -208.110582)
		(end 341.99576 -205.498954)
		(width 0.14732)
		(layer "In4.Cu")
		(net "UPI_CPU1_CPU0_P1P0_DN<4>")
	)
	(segment
		(start 154.080718 -188.664596)
		(end 153.779728 -189.598554)
		(width 0.14732)
		(layer "In4.Cu")
		(net "UPI_CPU1_CPU0_P1P0_DN<4>")
	)
	(segment
		(start 148.10105 -192.758314)
		(end 148.089366 -192.965578)
		(width 0.14732)
		(layer "In4.Cu")
		(net "UPI_CPU1_CPU0_P1P0_DN<4>")
	)
	(segment
		(start 332.825852 -195.40601)
		(end 326.875394 -193.228976)
		(width 0.14732)
		(layer "In4.Cu")
		(net "UPI_CPU1_CPU0_P1P0_DN<4>")
	)
	(segment
		(start 340.973156 -215.926924)
		(end 340.971632 -215.926162)
		(width 0.0889)
		(layer "In4.Cu")
		(net "UPI_CPU1_CPU0_P1P0_DN<4>")
	)
	(segment
		(start 302.475392 -185.2422)
		(end 302.25365 -185.2422)
		(width 0.14732)
		(layer "In4.Cu")
		(net "UPI_CPU1_CPU0_P1P0_DN<4>")
	)
	(segment
		(start 340.64702 -209.459322)
		(end 341.99576 -208.110582)
		(width 0.14732)
		(layer "In4.Cu")
		(net "UPI_CPU1_CPU0_P1P0_DN<4>")
	)
	(segment
		(start 340.590124 -212.767418)
		(end 340.590124 -212.592158)
		(width 0.0889)
		(layer "In4.Cu")
		(net "UPI_CPU1_CPU0_P1P0_DN<4>")
	)
	(segment
		(start 158.742126 -186.429396)
		(end 158.64967 -186.612276)
		(width 0.14732)
		(layer "In4.Cu")
		(net "UPI_CPU1_CPU0_P1P0_DN<4>")
	)
	(segment
		(start 340.590124 -213.316058)
		(end 340.590124 -213.140798)
		(width 0.0889)
		(layer "In4.Cu")
		(net "UPI_CPU1_CPU0_P1P0_DN<4>")
	)
	(segment
		(start 340.68893 -215.436704)
		(end 340.68893 -215.414606)
		(width 0.0889)
		(layer "In4.Cu")
		(net "UPI_CPU1_CPU0_P1P0_DN<4>")
	)
	(segment
		(start 130.240278 -216.569798)
		(end 130.249168 -216.574878)
		(width 0.0889)
		(layer "In4.Cu")
		(net "UPI_CPU1_CPU0_P1P0_DN<4>")
	)
	(segment
		(start 154.487118 -188.296296)
		(end 154.080718 -188.664596)
		(width 0.14732)
		(layer "In4.Cu")
		(net "UPI_CPU1_CPU0_P1P0_DN<4>")
	)
	(segment
		(start 130.717798 -215.112854)
		(end 130.709924 -215.117426)
		(width 0.0889)
		(layer "In4.Cu")
		(net "UPI_CPU1_CPU0_P1P0_DN<4>")
	)
	(segment
		(start 147.011644 -195.2371)
		(end 146.98726 -195.672202)
		(width 0.14732)
		(layer "In4.Cu")
		(net "UPI_CPU1_CPU0_P1P0_DN<4>")
	)
	(segment
		(start 340.68893 -217.071956)
		(end 340.68893 -217.064336)
		(width 0.0889)
		(layer "In4.Cu")
		(net "UPI_CPU1_CPU0_P1P0_DN<4>")
	)
	(segment
		(start 323.160136 -191.45631)
		(end 322.833238 -191.28613)
		(width 0.14732)
		(layer "In4.Cu")
		(net "UPI_CPU1_CPU0_P1P0_DN<4>")
	)
	(segment
		(start 154.691588 -188.306456)
		(end 154.487118 -188.296296)
		(width 0.14732)
		(layer "In4.Cu")
		(net "UPI_CPU1_CPU0_P1P0_DN<4>")
	)
	(segment
		(start 151.126444 -191.55791)
		(end 150.476458 -190.831216)
		(width 0.14732)
		(layer "In4.Cu")
		(net "UPI_CPU1_CPU0_P1P0_DN<4>")
	)
	(segment
		(start 146.373342 -194.303142)
		(end 146.361658 -194.510406)
		(width 0.14732)
		(layer "In4.Cu")
		(net "UPI_CPU1_CPU0_P1P0_DN<4>")
	)
	(segment
		(start 146.98726 -195.672202)
		(end 143.128238 -199.122284)
		(width 0.14732)
		(layer "In4.Cu")
		(net "UPI_CPU1_CPU0_P1P0_DN<4>")
	)
	(segment
		(start 340.689184 -212.101938)
		(end 340.647274 -212.060028)
		(width 0.0889)
		(layer "In4.Cu")
		(net "UPI_CPU1_CPU0_P1P0_DN<4>")
	)
	(segment
		(start 341.99576 -205.498954)
		(end 340.999064 -203.092558)
		(width 0.14732)
		(layer "In4.Cu")
		(net "UPI_CPU1_CPU0_P1P0_DN<4>")
	)
	(segment
		(start 340.689184 -212.493098)
		(end 340.689184 -212.101938)
		(width 0.0889)
		(layer "In4.Cu")
		(net "UPI_CPU1_CPU0_P1P0_DN<4>")
	)
	(segment
		(start 324.59168 -192.038986)
		(end 324.26529 -191.86906)
		(width 0.14732)
		(layer "In4.Cu")
		(net "UPI_CPU1_CPU0_P1P0_DN<4>")
	)
	(segment
		(start 131.001008 -214.461852)
		(end 131.001008 -214.644732)
		(width 0.0889)
		(layer "In4.Cu")
		(net "UPI_CPU1_CPU0_P1P0_DN<4>")
	)
	(segment
		(start 133.148578 -211.622894)
		(end 131.471162 -213.30031)
		(width 0.0889)
		(layer "In4.Cu")
		(net "UPI_CPU1_CPU0_P1P0_DN<4>")
	)
	(segment
		(start 131.471162 -213.30031)
		(end 131.471162 -213.93023)
		(width 0.0889)
		(layer "In4.Cu")
		(net "UPI_CPU1_CPU0_P1P0_DN<4>")
	)
	(segment
		(start 340.590124 -213.140798)
		(end 340.689184 -213.041738)
		(width 0.0889)
		(layer "In4.Cu")
		(net "UPI_CPU1_CPU0_P1P0_DN<4>")
	)
	(segment
		(start 130.718814 -215.112346)
		(end 130.717798 -215.112854)
		(width 0.0889)
		(layer "In4.Cu")
		(net "UPI_CPU1_CPU0_P1P0_DN<4>")
	)
	(segment
		(start 149.398736 -193.102738)
		(end 148.74875 -192.376044)
		(width 0.14732)
		(layer "In4.Cu")
		(net "UPI_CPU1_CPU0_P1P0_DN<4>")
	)
	(segment
		(start 150.46706 -192.147444)
		(end 150.442676 -192.582292)
		(width 0.14732)
		(layer "In4.Cu")
		(net "UPI_CPU1_CPU0_P1P0_DN<4>")
	)
	(segment
		(start 323.681598 -191.565022)
		(end 323.355208 -191.394842)
		(width 0.14732)
		(layer "In4.Cu")
		(net "UPI_CPU1_CPU0_P1P0_DN<4>")
	)
	(segment
		(start 340.999064 -203.092558)
		(end 335.10728 -197.200774)
		(width 0.14732)
		(layer "In4.Cu")
		(net "UPI_CPU1_CPU0_P1P0_DN<4>")
	)
	(segment
		(start 340.647274 -211.801202)
		(end 340.64702 -211.800948)
		(width 0.14732)
		(layer "In4.Cu")
		(net "UPI_CPU1_CPU0_P1P0_DN<4>")
	)
	(segment
		(start 158.64967 -186.612276)
		(end 158.299404 -186.726576)
		(width 0.14732)
		(layer "In4.Cu")
		(net "UPI_CPU1_CPU0_P1P0_DN<4>")
	)
	(segment
		(start 326.875394 -193.228976)
		(end 325.175372 -192.343278)
		(width 0.14732)
		(layer "In4.Cu")
		(net "UPI_CPU1_CPU0_P1P0_DN<4>")
	)
	(segment
		(start 324.653402 -192.234566)
		(end 324.59168 -192.038986)
		(width 0.14732)
		(layer "In4.Cu")
		(net "UPI_CPU1_CPU0_P1P0_DN<4>")
	)
	(segment
		(start 157.32379 -187.045854)
		(end 157.141164 -186.953144)
		(width 0.14732)
		(layer "In4.Cu")
		(net "UPI_CPU1_CPU0_P1P0_DN<4>")
	)
	(segment
		(start 340.784434 -217.878406)
		(end 340.940898 -218.149424)
		(width 0.0889)
		(layer "In4.Cu")
		(net "UPI_CPU1_CPU0_P1P0_DN<4>")
	)
	(segment
		(start 153.779728 -189.598554)
		(end 151.561292 -191.582294)
		(width 0.14732)
		(layer "In4.Cu")
		(net "UPI_CPU1_CPU0_P1P0_DN<4>")
	)
	(segment
		(start 146.813778 -193.909188)
		(end 146.373342 -194.303142)
		(width 0.14732)
		(layer "In4.Cu")
		(net "UPI_CPU1_CPU0_P1P0_DN<4>")
	)
	(segment
		(start 148.74875 -192.376044)
		(end 148.541486 -192.36436)
		(width 0.14732)
		(layer "In4.Cu")
		(net "UPI_CPU1_CPU0_P1P0_DN<4>")
	)
	(segment
		(start 340.689184 -213.930484)
		(end 340.689184 -213.415118)
		(width 0.0889)
		(layer "In4.Cu")
		(net "UPI_CPU1_CPU0_P1P0_DN<4>")
	)
	(segment
		(start 340.972394 -217.554556)
		(end 340.971632 -217.554048)
		(width 0.0889)
		(layer "In4.Cu")
		(net "UPI_CPU1_CPU0_P1P0_DN<4>")
	)
	(segment
		(start 148.714968 -194.12712)
		(end 148.105876 -194.67195)
		(width 0.14732)
		(layer "In4.Cu")
		(net "UPI_CPU1_CPU0_P1P0_DN<4>")
	)
	(segment
		(start 335.10728 -197.200774)
		(end 332.825852 -195.40601)
		(width 0.14732)
		(layer "In4.Cu")
		(net "UPI_CPU1_CPU0_P1P0_DN<4>")
	)
	(segment
		(start 149.817074 -191.42075)
		(end 150.46706 -192.147444)
		(width 0.14732)
		(layer "In4.Cu")
		(net "UPI_CPU1_CPU0_P1P0_DN<4>")
	)
	(segment
		(start 130.279902 -217.607388)
		(end 130.436366 -217.878406)
		(width 0.0889)
		(layer "In4.Cu")
		(net "UPI_CPU1_CPU0_P1P0_DN<4>")
	)
	(segment
		(start 154.974798 -187.854336)
		(end 154.964892 -188.058806)
		(width 0.14732)
		(layer "In4.Cu")
		(net "UPI_CPU1_CPU0_P1P0_DN<4>")
	)
	(segment
		(start 133.207506 -211.622894)
		(end 133.148578 -211.622894)
		(width 0.0889)
		(layer "In4.Cu")
		(net "UPI_CPU1_CPU0_P1P0_DN<4>")
	)
	(segment
		(start 148.739352 -193.692272)
		(end 148.714968 -194.12712)
		(width 0.14732)
		(layer "In4.Cu")
		(net "UPI_CPU1_CPU0_P1P0_DN<4>")
	)
	(segment
		(start 325.175372 -192.343278)
		(end 324.980046 -192.404746)
		(width 0.14732)
		(layer "In4.Cu")
		(net "UPI_CPU1_CPU0_P1P0_DN<4>")
	)
	(segment
		(start 340.95944 -216.58199)
		(end 340.964012 -216.579196)
		(width 0.0889)
		(layer "In4.Cu")
		(net "UPI_CPU1_CPU0_P1P0_DN<4>")
	)
	(segment
		(start 340.971124 -214.946992)
		(end 340.980014 -214.941912)
		(width 0.0889)
		(layer "In4.Cu")
		(net "UPI_CPU1_CPU0_P1P0_DN<4>")
	)
	(segment
		(start 340.980522 -217.559128)
		(end 340.972394 -217.554556)
		(width 0.0889)
		(layer "In4.Cu")
		(net "UPI_CPU1_CPU0_P1P0_DN<4>")
	)
	(segment
		(start 322.833238 -191.28613)
		(end 322.77177 -191.09055)
		(width 0.14732)
		(layer "In4.Cu")
		(net "UPI_CPU1_CPU0_P1P0_DN<4>")
	)
	(segment
		(start 150.442676 -192.582292)
		(end 149.833584 -193.127122)
		(width 0.14732)
		(layer "In4.Cu")
		(net "UPI_CPU1_CPU0_P1P0_DN<4>")
	)
	(segment
		(start 143.128238 -199.122284)
		(end 137.01014 -207.82026)
		(width 0.14732)
		(layer "In4.Cu")
		(net "UPI_CPU1_CPU0_P1P0_DN<4>")
	)
	(segment
		(start 157.766766 -186.74842)
		(end 157.67431 -186.9313)
		(width 0.14732)
		(layer "In4.Cu")
		(net "UPI_CPU1_CPU0_P1P0_DN<4>")
	)
	(segment
		(start 340.64702 -211.800948)
		(end 340.64702 -209.459322)
		(width 0.14732)
		(layer "In4.Cu")
		(net "UPI_CPU1_CPU0_P1P0_DN<4>")
	)
	(segment
		(start 158.299404 -186.726576)
		(end 158.116778 -186.63412)
		(width 0.14732)
		(layer "In4.Cu")
		(net "UPI_CPU1_CPU0_P1P0_DN<4>")
	)
	(segment
		(start 323.355208 -191.394842)
		(end 323.160136 -191.45631)
		(width 0.14732)
		(layer "In4.Cu")
		(net "UPI_CPU1_CPU0_P1P0_DN<4>")
	)
	(segment
		(start 149.828758 -191.213486)
		(end 149.817074 -191.42075)
		(width 0.14732)
		(layer "In4.Cu")
		(net "UPI_CPU1_CPU0_P1P0_DN<4>")
	)
	(segment
		(start 273.215354 -186.043062)
		(end 215.527382 -186.17311)
		(width 0.14732)
		(layer "In4.Cu")
		(net "UPI_CPU1_CPU0_P1P0_DN<4>")
	)
	(segment
		(start 324.26529 -191.86906)
		(end 324.069964 -191.930528)
		(width 0.14732)
		(layer "In4.Cu")
		(net "UPI_CPU1_CPU0_P1P0_DN<4>")
	)
	(segment
		(start 340.964012 -216.579196)
		(end 340.967822 -216.577164)
		(width 0.0889)
		(layer "In4.Cu")
		(net "UPI_CPU1_CPU0_P1P0_DN<4>")
	)
	(segment
		(start 323.74332 -191.760348)
		(end 323.681598 -191.565022)
		(width 0.14732)
		(layer "In4.Cu")
		(net "UPI_CPU1_CPU0_P1P0_DN<4>")
	)
	(segment
		(start 321.973448 -190.674752)
		(end 313.30011 -185.795666)
		(width 0.14732)
		(layer "In4.Cu")
		(net "UPI_CPU1_CPU0_P1P0_DN<4>")
	)
	(segment
		(start 340.967822 -216.577164)
		(end 340.971632 -216.574878)
		(width 0.0889)
		(layer "In4.Cu")
		(net "UPI_CPU1_CPU0_P1P0_DN<4>")
	)
	(segment
		(start 324.980046 -192.404746)
		(end 324.653402 -192.234566)
		(width 0.14732)
		(layer "In4.Cu")
		(net "UPI_CPU1_CPU0_P1P0_DN<4>")
	)
	(segment
		(start 340.689184 -212.866478)
		(end 340.590124 -212.767418)
		(width 0.0889)
		(layer "In4.Cu")
		(net "UPI_CPU1_CPU0_P1P0_DN<4>")
	)
	(segment
		(start 149.833584 -193.127122)
		(end 149.398736 -193.102738)
		(width 0.14732)
		(layer "In4.Cu")
		(net "UPI_CPU1_CPU0_P1P0_DN<4>")
	)
	(segment
		(start 341.158576 -214.622634)
		(end 341.158576 -214.461344)
		(width 0.0889)
		(layer "In4.Cu")
		(net "UPI_CPU1_CPU0_P1P0_DN<4>")
	)
	(segment
		(start 131.471162 -213.93023)
		(end 131.471416 -213.929468)
		(width 0.0889)
		(layer "In4.Cu")
		(net "UPI_CPU1_CPU0_P1P0_DN<4>")
	)
	(segment
		(start 340.97087 -215.925654)
		(end 340.965536 -215.922606)
		(width 0.0889)
		(layer "In4.Cu")
		(net "UPI_CPU1_CPU0_P1P0_DN<4>")
	)
	(segment
		(start 130.249168 -215.926162)
		(end 130.240278 -215.931242)
		(width 0.0889)
		(layer "In4.Cu")
		(net "UPI_CPU1_CPU0_P1P0_DN<4>")
	)
	(segment
		(start 340.940898 -218.149424)
		(end 341.01913 -218.170252)
		(width 0.0889)
		(layer "In4.Cu")
		(net "UPI_CPU1_CPU0_P1P0_DN<4>")
	)
	(segment
		(start 313.30011 -185.795666)
		(end 312.104024 -185.427874)
		(width 0.14732)
		(layer "In4.Cu")
		(net "UPI_CPU1_CPU0_P1P0_DN<4>")
	)
	(segment
		(start 340.971632 -216.574878)
		(end 340.980522 -216.569798)
		(width 0.0889)
		(layer "In4.Cu")
		(net "UPI_CPU1_CPU0_P1P0_DN<4>")
	)
	(segment
		(start 340.647274 -212.060028)
		(end 340.647274 -212.03793)
		(width 0.0889)
		(layer "In4.Cu")
		(net "UPI_CPU1_CPU0_P1P0_DN<4>")
	)
	(segment
		(start 340.689184 -213.041738)
		(end 340.689184 -212.866478)
		(width 0.0889)
		(layer "In4.Cu")
		(net "UPI_CPU1_CPU0_P1P0_DN<4>")
	)
	(segment
		(start 215.527382 -186.17311)
		(end 200.603866 -185.448956)
		(width 0.14732)
		(layer "In4.Cu")
		(net "UPI_CPU1_CPU0_P1P0_DN<4>")
	)
	(segment
		(start 302.25365 -185.2422)
		(end 273.215354 -186.043062)
		(width 0.14732)
		(layer "In4.Cu")
		(net "UPI_CPU1_CPU0_P1P0_DN<4>")
	)
	(segment
		(start 146.361658 -194.510406)
		(end 147.011644 -195.2371)
		(width 0.14732)
		(layer "In4.Cu")
		(net "UPI_CPU1_CPU0_P1P0_DN<4>")
	)
	(arc
		(start 131.471416 -213.929468)
		(mid 131.464138 -213.949159)
		(end 131.456176 -213.968584)
		(width 0.0889)
		(layer "In4.Cu")
		(net "UPI_CPU1_CPU0_P1P0_DN<4>")
	)
	(arc
		(start 340.68893 -217.064336)
		(mid 340.761165 -216.787812)
		(end 340.95944 -216.58199)
		(width 0.0889)
		(layer "In4.Cu")
		(net "UPI_CPU1_CPU0_P1P0_DN<4>")
	)
	(arc
		(start 340.974426 -214.261954)
		(mid 340.814354 -214.138774)
		(end 340.704424 -213.969346)
		(width 0.0889)
		(layer "In4.Cu")
		(net "UPI_CPU1_CPU0_P1P0_DN<4>")
	)
	(arc
		(start 131.001008 -214.644732)
		(mid 130.920097 -214.91486)
		(end 130.718814 -215.112346)
		(width 0.0889)
		(layer "In4.Cu")
		(net "UPI_CPU1_CPU0_P1P0_DN<4>")
	)
	(arc
		(start 130.320796 -217.50528)
		(mid 130.312474 -217.511835)
		(end 130.304032 -217.518234)
		(width 0.0889)
		(layer "In4.Cu")
		(net "UPI_CPU1_CPU0_P1P0_DN<4>")
	)
	(arc
		(start 131.456176 -213.968584)
		(mid 131.34597 -214.138501)
		(end 131.185412 -214.261954)
		(width 0.0889)
		(layer "In4.Cu")
		(net "UPI_CPU1_CPU0_P1P0_DN<4>")
	)
	(arc
		(start 340.980522 -216.569798)
		(mid 341.159119 -216.25052)
		(end 340.980522 -215.931242)
		(width 0.0889)
		(layer "In4.Cu")
		(net "UPI_CPU1_CPU0_P1P0_DN<4>")
	)
	(arc
		(start 341.158576 -214.461344)
		(mid 341.083571 -214.345885)
		(end 340.974426 -214.261954)
		(width 0.0889)
		(layer "In4.Cu")
		(net "UPI_CPU1_CPU0_P1P0_DN<4>")
	)
	(arc
		(start 130.709924 -215.117426)
		(mid 130.58267 -215.247392)
		(end 130.531616 -215.421972)
		(width 0.0889)
		(layer "In4.Cu")
		(net "UPI_CPU1_CPU0_P1P0_DN<4>")
	)
	(arc
		(start 130.531362 -215.452198)
		(mid 130.451992 -215.725932)
		(end 130.249168 -215.926162)
		(width 0.0889)
		(layer "In4.Cu")
		(net "UPI_CPU1_CPU0_P1P0_DN<4>")
	)
	(arc
		(start 341.159084 -217.878406)
		(mid 341.111405 -217.695506)
		(end 340.980522 -217.559128)
		(width 0.0889)
		(layer "In4.Cu")
		(net "UPI_CPU1_CPU0_P1P0_DN<4>")
	)
	(arc
		(start 340.68893 -215.414606)
		(mid 340.769841 -215.144478)
		(end 340.971124 -214.946992)
		(width 0.0889)
		(layer "In4.Cu")
		(net "UPI_CPU1_CPU0_P1P0_DN<4>")
	)
	(arc
		(start 341.01913 -218.170252)
		(mid 341.122275 -218.040227)
		(end 341.159084 -217.878406)
		(width 0.0889)
		(layer "In4.Cu")
		(net "UPI_CPU1_CPU0_P1P0_DN<4>")
	)
	(arc
		(start 130.255264 -216.578434)
		(mid 130.457677 -216.784847)
		(end 130.531616 -217.064336)
		(width 0.0889)
		(layer "In4.Cu")
		(net "UPI_CPU1_CPU0_P1P0_DN<4>")
	)
	(arc
		(start 340.971632 -217.554048)
		(mid 340.76656 -217.350369)
		(end 340.68893 -217.071956)
		(width 0.0889)
		(layer "In4.Cu")
		(net "UPI_CPU1_CPU0_P1P0_DN<4>")
	)
	(arc
		(start 130.531616 -215.421972)
		(mid 130.531419 -215.429337)
		(end 130.531362 -215.436704)
		(width 0.0889)
		(layer "In4.Cu")
		(net "UPI_CPU1_CPU0_P1P0_DN<4>")
	)
	(arc
		(start 340.965536 -215.922606)
		(mid 340.762949 -215.716255)
		(end 340.68893 -215.436704)
		(width 0.0889)
		(layer "In4.Cu")
		(net "UPI_CPU1_CPU0_P1P0_DN<4>")
	)
	(arc
		(start 130.531616 -217.07856)
		(mid 130.473255 -217.315158)
		(end 130.320796 -217.50528)
		(width 0.0889)
		(layer "In4.Cu")
		(net "UPI_CPU1_CPU0_P1P0_DN<4>")
	)
	(arc
		(start 340.704424 -213.969346)
		(mid 340.696461 -213.950049)
		(end 340.689184 -213.930484)
		(width 0.0889)
		(layer "In4.Cu")
		(net "UPI_CPU1_CPU0_P1P0_DN<4>")
	)
	(arc
		(start 130.240278 -215.931242)
		(mid 130.061802 -216.25052)
		(end 130.240278 -216.569798)
		(width 0.0889)
		(layer "In4.Cu")
		(net "UPI_CPU1_CPU0_P1P0_DN<4>")
	)
	(arc
		(start 131.185412 -214.261954)
		(mid 131.076016 -214.346051)
		(end 131.001008 -214.461852)
		(width 0.0889)
		(layer "In4.Cu")
		(net "UPI_CPU1_CPU0_P1P0_DN<4>")
	)
	(arc
		(start 340.980014 -214.941912)
		(mid 341.110928 -214.805552)
		(end 341.158576 -214.622634)
		(width 0.0889)
		(layer "In4.Cu")
		(net "UPI_CPU1_CPU0_P1P0_DN<4>")
	)
	(segment
		(start 131.375912 -218.414346)
		(end 131.375912 -217.87866)
		(width 0.13208)
		(layer "F.Cu")
		(net "UPI_CPU1_CPU0_P1P0_DN<3>")
	)
	(segment
		(start 339.84438 -218.414346)
		(end 339.84438 -217.87866)
		(width 0.13208)
		(layer "F.Cu")
		(net "UPI_CPU1_CPU0_P1P0_DN<3>")
	)
	(segment
		(start 339.84438 -217.87866)
		(end 339.844634 -217.878406)
		(width 0.13208)
		(layer "F.Cu")
		(net "UPI_CPU1_CPU0_P1P0_DN<3>")
	)
	(segment
		(start 131.375912 -217.87866)
		(end 131.376166 -217.878406)
		(width 0.13208)
		(layer "F.Cu")
		(net "UPI_CPU1_CPU0_P1P0_DN<3>")
	)
	(segment
		(start 340.033356 -215.926924)
		(end 340.040722 -215.931242)
		(width 0.0889)
		(layer "In4.Cu")
		(net "UPI_CPU1_CPU0_P1P0_DN<3>")
	)
	(segment
		(start 233.540554 -197.459092)
		(end 234.730036 -197.810628)
		(width 0.14732)
		(layer "In4.Cu")
		(net "UPI_CPU1_CPU0_P1P0_DN<3>")
	)
	(segment
		(start 149.159976 -194.952874)
		(end 149.363176 -194.977512)
		(width 0.14732)
		(layer "In4.Cu")
		(net "UPI_CPU1_CPU0_P1P0_DN<3>")
	)
	(segment
		(start 132.766562 -213.303358)
		(end 133.849618 -212.220302)
		(width 0.0889)
		(layer "In4.Cu")
		(net "UPI_CPU1_CPU0_P1P0_DN<3>")
	)
	(segment
		(start 263.306306 -188.687964)
		(end 264.673334 -187.931298)
		(width 0.14732)
		(layer "In4.Cu")
		(net "UPI_CPU1_CPU0_P1P0_DN<3>")
	)
	(segment
		(start 156.457396 -189.232286)
		(end 156.660596 -189.256924)
		(width 0.14732)
		(layer "In4.Cu")
		(net "UPI_CPU1_CPU0_P1P0_DN<3>")
	)
	(segment
		(start 137.423398 -208.705196)
		(end 143.720312 -199.736202)
		(width 0.14732)
		(layer "In4.Cu")
		(net "UPI_CPU1_CPU0_P1P0_DN<3>")
	)
	(segment
		(start 153.429716 -191.789812)
		(end 153.719784 -191.562482)
		(width 0.14732)
		(layer "In4.Cu")
		(net "UPI_CPU1_CPU0_P1P0_DN<3>")
	)
	(segment
		(start 132.880608 -214.644732)
		(end 132.880608 -214.424768)
		(width 0.0889)
		(layer "In4.Cu")
		(net "UPI_CPU1_CPU0_P1P0_DN<3>")
	)
	(segment
		(start 312.986166 -186.575192)
		(end 319.338452 -191.634364)
		(width 0.14732)
		(layer "In4.Cu")
		(net "UPI_CPU1_CPU0_P1P0_DN<3>")
	)
	(segment
		(start 261.993634 -189.414658)
		(end 262.114284 -188.99632)
		(width 0.14732)
		(layer "In4.Cu")
		(net "UPI_CPU1_CPU0_P1P0_DN<3>")
	)
	(segment
		(start 155.359862 -190.092584)
		(end 155.649676 -189.865508)
		(width 0.14732)
		(layer "In4.Cu")
		(net "UPI_CPU1_CPU0_P1P0_DN<3>")
	)
	(segment
		(start 158.004256 -188.019436)
		(end 159.801306 -186.971686)
		(width 0.14732)
		(layer "In4.Cu")
		(net "UPI_CPU1_CPU0_P1P0_DN<3>")
	)
	(segment
		(start 340.031832 -215.926162)
		(end 340.033356 -215.926924)
		(width 0.0889)
		(layer "In4.Cu")
		(net "UPI_CPU1_CPU0_P1P0_DN<3>")
	)
	(segment
		(start 133.908546 -212.220302)
		(end 133.92404 -212.204808)
		(width 0.0889)
		(layer "In4.Cu")
		(net "UPI_CPU1_CPU0_P1P0_DN<3>")
	)
	(segment
		(start 339.707728 -212.060028)
		(end 339.749638 -212.101938)
		(width 0.0889)
		(layer "In4.Cu")
		(net "UPI_CPU1_CPU0_P1P0_DN<3>")
	)
	(segment
		(start 131.471416 -217.082878)
		(end 131.471416 -217.05443)
		(width 0.0889)
		(layer "In4.Cu")
		(net "UPI_CPU1_CPU0_P1P0_DN<3>")
	)
	(segment
		(start 340.040722 -216.569798)
		(end 340.033356 -216.574116)
		(width 0.0889)
		(layer "In4.Cu")
		(net "UPI_CPU1_CPU0_P1P0_DN<3>")
	)
	(segment
		(start 151.268684 -193.483992)
		(end 151.293322 -193.280538)
		(width 0.14732)
		(layer "In4.Cu")
		(net "UPI_CPU1_CPU0_P1P0_DN<3>")
	)
	(segment
		(start 155.649676 -189.865508)
		(end 155.852876 -189.890146)
		(width 0.14732)
		(layer "In4.Cu")
		(net "UPI_CPU1_CPU0_P1P0_DN<3>")
	)
	(segment
		(start 152.101042 -192.647316)
		(end 153.226516 -191.765174)
		(width 0.14732)
		(layer "In4.Cu")
		(net "UPI_CPU1_CPU0_P1P0_DN<3>")
	)
	(segment
		(start 234.730036 -197.810628)
		(end 235.919772 -198.162164)
		(width 0.14732)
		(layer "In4.Cu")
		(net "UPI_CPU1_CPU0_P1P0_DN<3>")
	)
	(segment
		(start 131.180078 -217.559128)
		(end 131.188968 -217.554048)
		(width 0.0889)
		(layer "In4.Cu")
		(net "UPI_CPU1_CPU0_P1P0_DN<3>")
	)
	(segment
		(start 341.13724 -207.762094)
		(end 339.707474 -209.19186)
		(width 0.14732)
		(layer "In4.Cu")
		(net "UPI_CPU1_CPU0_P1P0_DN<3>")
	)
	(segment
		(start 131.376166 -217.878406)
		(end 131.219702 -218.149424)
		(width 0.0889)
		(layer "In4.Cu")
		(net "UPI_CPU1_CPU0_P1P0_DN<3>")
	)
	(segment
		(start 154.237436 -191.15659)
		(end 154.527504 -190.92926)
		(width 0.14732)
		(layer "In4.Cu")
		(net "UPI_CPU1_CPU0_P1P0_DN<3>")
	)
	(segment
		(start 135.449818 -210.678776)
		(end 137.423398 -208.705196)
		(width 0.14732)
		(layer "In4.Cu")
		(net "UPI_CPU1_CPU0_P1P0_DN<3>")
	)
	(segment
		(start 151.786336 -193.0781)
		(end 152.076404 -192.85077)
		(width 0.14732)
		(layer "In4.Cu")
		(net "UPI_CPU1_CPU0_P1P0_DN<3>")
	)
	(segment
		(start 131.471162 -215.452198)
		(end 131.471162 -215.436704)
		(width 0.0889)
		(layer "In4.Cu")
		(net "UPI_CPU1_CPU0_P1P0_DN<3>")
	)
	(segment
		(start 148.285454 -195.63842)
		(end 149.159976 -194.952874)
		(width 0.14732)
		(layer "In4.Cu")
		(net "UPI_CPU1_CPU0_P1P0_DN<3>")
	)
	(segment
		(start 340.297516 -203.56957)
		(end 341.13724 -205.596998)
		(width 0.14732)
		(layer "In4.Cu")
		(net "UPI_CPU1_CPU0_P1P0_DN<3>")
	)
	(segment
		(start 132.670042 -213.303358)
		(end 132.766562 -213.303358)
		(width 0.0889)
		(layer "In4.Cu")
		(net "UPI_CPU1_CPU0_P1P0_DN<3>")
	)
	(segment
		(start 151.293322 -193.280538)
		(end 151.583136 -193.053462)
		(width 0.14732)
		(layer "In4.Cu")
		(net "UPI_CPU1_CPU0_P1P0_DN<3>")
	)
	(segment
		(start 340.031832 -216.574878)
		(end 340.029038 -216.576402)
		(width 0.0889)
		(layer "In4.Cu")
		(net "UPI_CPU1_CPU0_P1P0_DN<3>")
	)
	(segment
		(start 262.54456 -187.948062)
		(end 262.887714 -188.567568)
		(width 0.14732)
		(layer "In4.Cu")
		(net "UPI_CPU1_CPU0_P1P0_DN<3>")
	)
	(segment
		(start 340.029038 -216.576402)
		(end 340.025736 -216.578434)
		(width 0.0889)
		(layer "In4.Cu")
		(net "UPI_CPU1_CPU0_P1P0_DN<3>")
	)
	(segment
		(start 319.338452 -191.634364)
		(end 332.40218 -196.141594)
		(width 0.14732)
		(layer "In4.Cu")
		(net "UPI_CPU1_CPU0_P1P0_DN<3>")
	)
	(segment
		(start 132.411216 -213.893908)
		(end 132.410962 -213.8934)
		(width 0.0889)
		(layer "In4.Cu")
		(net "UPI_CPU1_CPU0_P1P0_DN<3>")
	)
	(segment
		(start 339.74913 -215.414606)
		(end 339.74913 -215.436704)
		(width 0.0889)
		(layer "In4.Cu")
		(net "UPI_CPU1_CPU0_P1P0_DN<3>")
	)
	(segment
		(start 261.77113 -188.37656)
		(end 261.828788 -188.176154)
		(width 0.14732)
		(layer "In4.Cu")
		(net "UPI_CPU1_CPU0_P1P0_DN<3>")
	)
	(segment
		(start 151.583136 -193.053462)
		(end 151.786336 -193.0781)
		(width 0.14732)
		(layer "In4.Cu")
		(net "UPI_CPU1_CPU0_P1P0_DN<3>")
	)
	(segment
		(start 302.46828 -186.093354)
		(end 311.990486 -186.270138)
		(width 0.14732)
		(layer "In4.Cu")
		(net "UPI_CPU1_CPU0_P1P0_DN<3>")
	)
	(segment
		(start 152.076404 -192.85077)
		(end 152.101042 -192.647316)
		(width 0.14732)
		(layer "In4.Cu")
		(net "UPI_CPU1_CPU0_P1P0_DN<3>")
	)
	(segment
		(start 340.040214 -214.941912)
		(end 340.031324 -214.946992)
		(width 0.0889)
		(layer "In4.Cu")
		(net "UPI_CPU1_CPU0_P1P0_DN<3>")
	)
	(segment
		(start 238.504984 -198.004938)
		(end 249.482356 -192.982342)
		(width 0.14732)
		(layer "In4.Cu")
		(net "UPI_CPU1_CPU0_P1P0_DN<3>")
	)
	(segment
		(start 339.976968 -217.518234)
		(end 340.001098 -217.607388)
		(width 0.0889)
		(layer "In4.Cu")
		(net "UPI_CPU1_CPU0_P1P0_DN<3>")
	)
	(segment
		(start 132.410962 -213.562438)
		(end 132.670042 -213.303358)
		(width 0.0889)
		(layer "In4.Cu")
		(net "UPI_CPU1_CPU0_P1P0_DN<3>")
	)
	(segment
		(start 200.420478 -186.302904)
		(end 200.422764 -186.302904)
		(width 0.14732)
		(layer "In4.Cu")
		(net "UPI_CPU1_CPU0_P1P0_DN<3>")
	)
	(segment
		(start 155.852876 -189.890146)
		(end 156.142944 -189.662816)
		(width 0.14732)
		(layer "In4.Cu")
		(net "UPI_CPU1_CPU0_P1P0_DN<3>")
	)
	(segment
		(start 132.410962 -213.8934)
		(end 132.410962 -213.562438)
		(width 0.0889)
		(layer "In4.Cu")
		(net "UPI_CPU1_CPU0_P1P0_DN<3>")
	)
	(segment
		(start 264.673334 -187.931298)
		(end 273.031712 -186.9059)
		(width 0.14732)
		(layer "In4.Cu")
		(net "UPI_CPU1_CPU0_P1P0_DN<3>")
	)
	(segment
		(start 273.031712 -186.9059)
		(end 302.46828 -186.093354)
		(width 0.14732)
		(layer "In4.Cu")
		(net "UPI_CPU1_CPU0_P1P0_DN<3>")
	)
	(segment
		(start 150.460964 -194.117214)
		(end 150.485602 -193.91376)
		(width 0.14732)
		(layer "In4.Cu")
		(net "UPI_CPU1_CPU0_P1P0_DN<3>")
	)
	(segment
		(start 149.363176 -194.977512)
		(end 149.653244 -194.750436)
		(width 0.14732)
		(layer "In4.Cu")
		(net "UPI_CPU1_CPU0_P1P0_DN<3>")
	)
	(segment
		(start 155.045156 -190.523368)
		(end 155.335224 -190.296038)
		(width 0.14732)
		(layer "In4.Cu")
		(net "UPI_CPU1_CPU0_P1P0_DN<3>")
	)
	(segment
		(start 340.218776 -214.461344)
		(end 340.218776 -214.622634)
		(width 0.0889)
		(layer "In4.Cu")
		(net "UPI_CPU1_CPU0_P1P0_DN<3>")
	)
	(segment
		(start 339.749638 -213.929468)
		(end 339.749384 -213.929722)
		(width 0.0889)
		(layer "In4.Cu")
		(net "UPI_CPU1_CPU0_P1P0_DN<3>")
	)
	(segment
		(start 311.990486 -186.270138)
		(end 312.986166 -186.575192)
		(width 0.14732)
		(layer "In4.Cu")
		(net "UPI_CPU1_CPU0_P1P0_DN<3>")
	)
	(segment
		(start 340.033356 -216.574116)
		(end 340.031832 -216.574878)
		(width 0.0889)
		(layer "In4.Cu")
		(net "UPI_CPU1_CPU0_P1P0_DN<3>")
	)
	(segment
		(start 132.03301 -215.112346)
		(end 132.047742 -215.120982)
		(width 0.0889)
		(layer "In4.Cu")
		(net "UPI_CPU1_CPU0_P1P0_DN<3>")
	)
	(segment
		(start 215.205056 -186.993784)
		(end 223.257364 -190.798704)
		(width 0.14732)
		(layer "In4.Cu")
		(net "UPI_CPU1_CPU0_P1P0_DN<3>")
	)
	(segment
		(start 340.001098 -217.607388)
		(end 339.844634 -217.878406)
		(width 0.0889)
		(layer "In4.Cu")
		(net "UPI_CPU1_CPU0_P1P0_DN<3>")
	)
	(segment
		(start 154.841956 -190.49873)
		(end 155.045156 -190.523368)
		(width 0.14732)
		(layer "In4.Cu")
		(net "UPI_CPU1_CPU0_P1P0_DN<3>")
	)
	(segment
		(start 150.485602 -193.91376)
		(end 150.775416 -193.686684)
		(width 0.14732)
		(layer "In4.Cu")
		(net "UPI_CPU1_CPU0_P1P0_DN<3>")
	)
	(segment
		(start 262.344916 -187.890404)
		(end 262.54456 -187.948062)
		(width 0.14732)
		(layer "In4.Cu")
		(net "UPI_CPU1_CPU0_P1P0_DN<3>")
	)
	(segment
		(start 339.749384 -213.929722)
		(end 339.749384 -213.930484)
		(width 0.0889)
		(layer "In4.Cu")
		(net "UPI_CPU1_CPU0_P1P0_DN<3>")
	)
	(segment
		(start 135.449818 -210.67903)
		(end 135.449818 -210.678776)
		(width 0.14732)
		(layer "In4.Cu")
		(net "UPI_CPU1_CPU0_P1P0_DN<3>")
	)
	(segment
		(start 154.034236 -191.131952)
		(end 154.237436 -191.15659)
		(width 0.14732)
		(layer "In4.Cu")
		(net "UPI_CPU1_CPU0_P1P0_DN<3>")
	)
	(segment
		(start 340.03107 -215.925654)
		(end 340.031832 -215.926162)
		(width 0.0889)
		(layer "In4.Cu")
		(net "UPI_CPU1_CPU0_P1P0_DN<3>")
	)
	(segment
		(start 262.887714 -188.567568)
		(end 263.306306 -188.687964)
		(width 0.14732)
		(layer "In4.Cu")
		(net "UPI_CPU1_CPU0_P1P0_DN<3>")
	)
	(segment
		(start 131.219702 -218.149424)
		(end 131.14147 -218.170252)
		(width 0.0889)
		(layer "In4.Cu")
		(net "UPI_CPU1_CPU0_P1P0_DN<3>")
	)
	(segment
		(start 150.978616 -193.711322)
		(end 151.268684 -193.483992)
		(width 0.14732)
		(layer "In4.Cu")
		(net "UPI_CPU1_CPU0_P1P0_DN<3>")
	)
	(segment
		(start 339.707728 -211.801202)
		(end 339.707728 -212.03793)
		(width 0.14732)
		(layer "In4.Cu")
		(net "UPI_CPU1_CPU0_P1P0_DN<3>")
	)
	(segment
		(start 332.40218 -196.141594)
		(end 334.592422 -197.864476)
		(width 0.14732)
		(layer "In4.Cu")
		(net "UPI_CPU1_CPU0_P1P0_DN<3>")
	)
	(segment
		(start 341.13724 -205.596998)
		(end 341.13724 -207.762094)
		(width 0.14732)
		(layer "In4.Cu")
		(net "UPI_CPU1_CPU0_P1P0_DN<3>")
	)
	(segment
		(start 200.422764 -186.302904)
		(end 215.205056 -186.993784)
		(width 0.14732)
		(layer "In4.Cu")
		(net "UPI_CPU1_CPU0_P1P0_DN<3>")
	)
	(segment
		(start 260.926326 -190.005462)
		(end 261.993634 -189.414658)
		(width 0.14732)
		(layer "In4.Cu")
		(net "UPI_CPU1_CPU0_P1P0_DN<3>")
	)
	(segment
		(start 155.335224 -190.296038)
		(end 155.359862 -190.092584)
		(width 0.14732)
		(layer "In4.Cu")
		(net "UPI_CPU1_CPU0_P1P0_DN<3>")
	)
	(segment
		(start 153.226516 -191.765174)
		(end 153.429716 -191.789812)
		(width 0.14732)
		(layer "In4.Cu")
		(net "UPI_CPU1_CPU0_P1P0_DN<3>")
	)
	(segment
		(start 143.720312 -199.736202)
		(end 148.285454 -195.63842)
		(width 0.14732)
		(layer "In4.Cu")
		(net "UPI_CPU1_CPU0_P1P0_DN<3>")
	)
	(segment
		(start 156.167582 -189.459362)
		(end 156.457396 -189.232286)
		(width 0.14732)
		(layer "In4.Cu")
		(net "UPI_CPU1_CPU0_P1P0_DN<3>")
	)
	(segment
		(start 153.719784 -191.562482)
		(end 153.744422 -191.359028)
		(width 0.14732)
		(layer "In4.Cu")
		(net "UPI_CPU1_CPU0_P1P0_DN<3>")
	)
	(segment
		(start 149.653244 -194.750436)
		(end 149.677882 -194.546982)
		(width 0.14732)
		(layer "In4.Cu")
		(net "UPI_CPU1_CPU0_P1P0_DN<3>")
	)
	(segment
		(start 156.660596 -189.256924)
		(end 156.950664 -189.029594)
		(width 0.14732)
		(layer "In4.Cu")
		(net "UPI_CPU1_CPU0_P1P0_DN<3>")
	)
	(segment
		(start 339.707474 -211.800948)
		(end 339.707728 -211.801202)
		(width 0.14732)
		(layer "In4.Cu")
		(net "UPI_CPU1_CPU0_P1P0_DN<3>")
	)
	(segment
		(start 339.707474 -209.19186)
		(end 339.707474 -211.800948)
		(width 0.14732)
		(layer "In4.Cu")
		(net "UPI_CPU1_CPU0_P1P0_DN<3>")
	)
	(segment
		(start 159.801306 -186.971686)
		(end 200.420478 -186.302904)
		(width 0.14732)
		(layer "In4.Cu")
		(net "UPI_CPU1_CPU0_P1P0_DN<3>")
	)
	(segment
		(start 249.482356 -192.982342)
		(end 260.926326 -190.005462)
		(width 0.14732)
		(layer "In4.Cu")
		(net "UPI_CPU1_CPU0_P1P0_DN<3>")
	)
	(segment
		(start 150.775416 -193.686684)
		(end 150.978616 -193.711322)
		(width 0.14732)
		(layer "In4.Cu")
		(net "UPI_CPU1_CPU0_P1P0_DN<3>")
	)
	(segment
		(start 154.527504 -190.92926)
		(end 154.552142 -190.725806)
		(width 0.14732)
		(layer "In4.Cu")
		(net "UPI_CPU1_CPU0_P1P0_DN<3>")
	)
	(segment
		(start 237.249716 -198.162164)
		(end 238.504984 -198.004938)
		(width 0.14732)
		(layer "In4.Cu")
		(net "UPI_CPU1_CPU0_P1P0_DN<3>")
	)
	(segment
		(start 261.828788 -188.176154)
		(end 262.344916 -187.890404)
		(width 0.14732)
		(layer "In4.Cu")
		(net "UPI_CPU1_CPU0_P1P0_DN<3>")
	)
	(segment
		(start 131.180078 -215.931242)
		(end 131.188968 -215.926162)
		(width 0.0889)
		(layer "In4.Cu")
		(net "UPI_CPU1_CPU0_P1P0_DN<3>")
	)
	(segment
		(start 133.849618 -212.220302)
		(end 133.908546 -212.220302)
		(width 0.0889)
		(layer "In4.Cu")
		(net "UPI_CPU1_CPU0_P1P0_DN<3>")
	)
	(segment
		(start 235.919772 -198.162164)
		(end 237.249716 -198.162164)
		(width 0.14732)
		(layer "In4.Cu")
		(net "UPI_CPU1_CPU0_P1P0_DN<3>")
	)
	(segment
		(start 131.649724 -215.117426)
		(end 131.658614 -215.112346)
		(width 0.0889)
		(layer "In4.Cu")
		(net "UPI_CPU1_CPU0_P1P0_DN<3>")
	)
	(segment
		(start 149.677882 -194.546982)
		(end 149.967696 -194.319906)
		(width 0.14732)
		(layer "In4.Cu")
		(net "UPI_CPU1_CPU0_P1P0_DN<3>")
	)
	(segment
		(start 133.92404 -212.204808)
		(end 135.449818 -210.67903)
		(width 0.14732)
		(layer "In4.Cu")
		(net "UPI_CPU1_CPU0_P1P0_DN<3>")
	)
	(segment
		(start 156.950664 -189.029594)
		(end 156.975302 -188.82614)
		(width 0.14732)
		(layer "In4.Cu")
		(net "UPI_CPU1_CPU0_P1P0_DN<3>")
	)
	(segment
		(start 339.707728 -212.03793)
		(end 339.707728 -212.060028)
		(width 0.0889)
		(layer "In4.Cu")
		(net "UPI_CPU1_CPU0_P1P0_DN<3>")
	)
	(segment
		(start 156.142944 -189.662816)
		(end 156.167582 -189.459362)
		(width 0.14732)
		(layer "In4.Cu")
		(net "UPI_CPU1_CPU0_P1P0_DN<3>")
	)
	(segment
		(start 156.975302 -188.82614)
		(end 158.004256 -188.019436)
		(width 0.14732)
		(layer "In4.Cu")
		(net "UPI_CPU1_CPU0_P1P0_DN<3>")
	)
	(segment
		(start 154.552142 -190.725806)
		(end 154.841956 -190.49873)
		(width 0.14732)
		(layer "In4.Cu")
		(net "UPI_CPU1_CPU0_P1P0_DN<3>")
	)
	(segment
		(start 149.967696 -194.319906)
		(end 150.170896 -194.344544)
		(width 0.14732)
		(layer "In4.Cu")
		(net "UPI_CPU1_CPU0_P1P0_DN<3>")
	)
	(segment
		(start 262.114284 -188.99632)
		(end 261.77113 -188.37656)
		(width 0.14732)
		(layer "In4.Cu")
		(net "UPI_CPU1_CPU0_P1P0_DN<3>")
	)
	(segment
		(start 223.257364 -190.798704)
		(end 233.540554 -197.459092)
		(width 0.14732)
		(layer "In4.Cu")
		(net "UPI_CPU1_CPU0_P1P0_DN<3>")
	)
	(segment
		(start 150.170896 -194.344544)
		(end 150.460964 -194.117214)
		(width 0.14732)
		(layer "In4.Cu")
		(net "UPI_CPU1_CPU0_P1P0_DN<3>")
	)
	(segment
		(start 334.592422 -197.864476)
		(end 340.297516 -203.56957)
		(width 0.14732)
		(layer "In4.Cu")
		(net "UPI_CPU1_CPU0_P1P0_DN<3>")
	)
	(segment
		(start 131.188968 -216.574878)
		(end 131.180078 -216.569798)
		(width 0.0889)
		(layer "In4.Cu")
		(net "UPI_CPU1_CPU0_P1P0_DN<3>")
	)
	(segment
		(start 153.744422 -191.359028)
		(end 154.034236 -191.131952)
		(width 0.14732)
		(layer "In4.Cu")
		(net "UPI_CPU1_CPU0_P1P0_DN<3>")
	)
	(segment
		(start 339.749638 -212.101938)
		(end 339.749638 -213.929468)
		(width 0.0889)
		(layer "In4.Cu")
		(net "UPI_CPU1_CPU0_P1P0_DN<3>")
	)
	(segment
		(start 339.74913 -217.064336)
		(end 339.74913 -217.07856)
		(width 0.0889)
		(layer "In4.Cu")
		(net "UPI_CPU1_CPU0_P1P0_DN<3>")
	)
	(segment
		(start 340.025736 -215.922606)
		(end 340.03107 -215.925654)
		(width 0.0889)
		(layer "In4.Cu")
		(net "UPI_CPU1_CPU0_P1P0_DN<3>")
	)
	(arc
		(start 132.598414 -215.112346)
		(mid 132.799696 -214.914859)
		(end 132.880608 -214.644732)
		(width 0.0889)
		(layer "In4.Cu")
		(net "UPI_CPU1_CPU0_P1P0_DN<3>")
	)
	(arc
		(start 339.74913 -215.436704)
		(mid 339.823121 -215.71627)
		(end 340.025736 -215.922606)
		(width 0.0889)
		(layer "In4.Cu")
		(net "UPI_CPU1_CPU0_P1P0_DN<3>")
	)
	(arc
		(start 340.040722 -215.931242)
		(mid 340.219319 -216.25052)
		(end 340.040722 -216.569798)
		(width 0.0889)
		(layer "In4.Cu")
		(net "UPI_CPU1_CPU0_P1P0_DN<3>")
	)
	(arc
		(start 339.74913 -217.07856)
		(mid 339.807424 -217.315203)
		(end 339.95995 -217.50528)
		(width 0.0889)
		(layer "In4.Cu")
		(net "UPI_CPU1_CPU0_P1P0_DN<3>")
	)
	(arc
		(start 131.001516 -217.878406)
		(mid 131.049195 -217.695506)
		(end 131.180078 -217.559128)
		(width 0.0889)
		(layer "In4.Cu")
		(net "UPI_CPU1_CPU0_P1P0_DN<3>")
	)
	(arc
		(start 131.14147 -218.170252)
		(mid 131.038325 -218.040227)
		(end 131.001516 -217.878406)
		(width 0.0889)
		(layer "In4.Cu")
		(net "UPI_CPU1_CPU0_P1P0_DN<3>")
	)
	(arc
		(start 340.218776 -214.622634)
		(mid 340.171097 -214.805534)
		(end 340.040214 -214.941912)
		(width 0.0889)
		(layer "In4.Cu")
		(net "UPI_CPU1_CPU0_P1P0_DN<3>")
	)
	(arc
		(start 131.180078 -216.569798)
		(mid 131.001481 -216.25052)
		(end 131.180078 -215.931242)
		(width 0.0889)
		(layer "In4.Cu")
		(net "UPI_CPU1_CPU0_P1P0_DN<3>")
	)
	(arc
		(start 132.880608 -214.424768)
		(mid 132.769329 -214.232062)
		(end 132.595366 -214.093298)
		(width 0.0889)
		(layer "In4.Cu")
		(net "UPI_CPU1_CPU0_P1P0_DN<3>")
	)
	(arc
		(start 339.749384 -213.930484)
		(mid 339.756669 -213.950046)
		(end 339.764624 -213.969346)
		(width 0.0889)
		(layer "In4.Cu")
		(net "UPI_CPU1_CPU0_P1P0_DN<3>")
	)
	(arc
		(start 132.595366 -214.093298)
		(mid 132.486219 -214.00937)
		(end 132.411216 -213.893908)
		(width 0.0889)
		(layer "In4.Cu")
		(net "UPI_CPU1_CPU0_P1P0_DN<3>")
	)
	(arc
		(start 340.034626 -214.261954)
		(mid 340.143773 -214.345882)
		(end 340.218776 -214.461344)
		(width 0.0889)
		(layer "In4.Cu")
		(net "UPI_CPU1_CPU0_P1P0_DN<3>")
	)
	(arc
		(start 131.658614 -215.112346)
		(mid 131.845812 -215.062203)
		(end 132.03301 -215.112346)
		(width 0.0889)
		(layer "In4.Cu")
		(net "UPI_CPU1_CPU0_P1P0_DN<3>")
	)
	(arc
		(start 131.471416 -215.421972)
		(mid 131.52247 -215.247392)
		(end 131.649724 -215.117426)
		(width 0.0889)
		(layer "In4.Cu")
		(net "UPI_CPU1_CPU0_P1P0_DN<3>")
	)
	(arc
		(start 131.471416 -217.05443)
		(mid 131.393305 -216.777481)
		(end 131.188968 -216.574878)
		(width 0.0889)
		(layer "In4.Cu")
		(net "UPI_CPU1_CPU0_P1P0_DN<3>")
	)
	(arc
		(start 132.047742 -215.120982)
		(mid 132.324183 -215.188148)
		(end 132.598414 -215.112346)
		(width 0.0889)
		(layer "In4.Cu")
		(net "UPI_CPU1_CPU0_P1P0_DN<3>")
	)
	(arc
		(start 131.188968 -217.554048)
		(mid 131.391254 -217.355067)
		(end 131.471416 -217.082878)
		(width 0.0889)
		(layer "In4.Cu")
		(net "UPI_CPU1_CPU0_P1P0_DN<3>")
	)
	(arc
		(start 340.031324 -214.946992)
		(mid 339.830042 -215.144479)
		(end 339.74913 -215.414606)
		(width 0.0889)
		(layer "In4.Cu")
		(net "UPI_CPU1_CPU0_P1P0_DN<3>")
	)
	(arc
		(start 339.95995 -217.50528)
		(mid 339.968398 -217.511837)
		(end 339.976968 -217.518234)
		(width 0.0889)
		(layer "In4.Cu")
		(net "UPI_CPU1_CPU0_P1P0_DN<3>")
	)
	(arc
		(start 340.025736 -216.578434)
		(mid 339.823149 -216.784785)
		(end 339.74913 -217.064336)
		(width 0.0889)
		(layer "In4.Cu")
		(net "UPI_CPU1_CPU0_P1P0_DN<3>")
	)
	(arc
		(start 339.764624 -213.969346)
		(mid 339.874618 -214.138715)
		(end 340.034626 -214.261954)
		(width 0.0889)
		(layer "In4.Cu")
		(net "UPI_CPU1_CPU0_P1P0_DN<3>")
	)
	(arc
		(start 131.471162 -215.436704)
		(mid 131.471214 -215.429337)
		(end 131.471416 -215.421972)
		(width 0.0889)
		(layer "In4.Cu")
		(net "UPI_CPU1_CPU0_P1P0_DN<3>")
	)
	(arc
		(start 131.188968 -215.926162)
		(mid 131.391791 -215.725931)
		(end 131.471162 -215.452198)
		(width 0.0889)
		(layer "In4.Cu")
		(net "UPI_CPU1_CPU0_P1P0_DN<3>")
	)
	(segment
		(start 132.315712 -218.414346)
		(end 132.315712 -217.87866)
		(width 0.13208)
		(layer "F.Cu")
		(net "UPI_CPU1_CPU0_P1P0_DN<2>")
	)
	(segment
		(start 132.315712 -217.87866)
		(end 132.315966 -217.878406)
		(width 0.13208)
		(layer "F.Cu")
		(net "UPI_CPU1_CPU0_P1P0_DN<2>")
	)
	(segment
		(start 338.90458 -218.414346)
		(end 338.90458 -217.87866)
		(width 0.13208)
		(layer "F.Cu")
		(net "UPI_CPU1_CPU0_P1P0_DN<2>")
	)
	(segment
		(start 338.90458 -217.87866)
		(end 338.904834 -217.878406)
		(width 0.13208)
		(layer "F.Cu")
		(net "UPI_CPU1_CPU0_P1P0_DN<2>")
	)
	(segment
		(start 141.990064 -203.935076)
		(end 141.778228 -204.23632)
		(width 0.14732)
		(layer "In4.Cu")
		(net "UPI_CPU1_CPU0_P1P0_DN<2>")
	)
	(segment
		(start 338.710524 -212.729318)
		(end 338.710524 -212.554058)
		(width 0.0889)
		(layer "In4.Cu")
		(net "UPI_CPU1_CPU0_P1P0_DN<2>")
	)
	(segment
		(start 152.723596 -194.662044)
		(end 150.237698 -195.705984)
		(width 0.14732)
		(layer "In4.Cu")
		(net "UPI_CPU1_CPU0_P1P0_DN<2>")
	)
	(segment
		(start 332.031086 -196.911468)
		(end 318.842644 -192.345564)
		(width 0.14732)
		(layer "In4.Cu")
		(net "UPI_CPU1_CPU0_P1P0_DN<2>")
	)
	(segment
		(start 339.100922 -215.931242)
		(end 339.093556 -215.926924)
		(width 0.0889)
		(layer "In4.Cu")
		(net "UPI_CPU1_CPU0_P1P0_DN<2>")
	)
	(segment
		(start 132.128768 -216.574878)
		(end 132.134864 -216.578434)
		(width 0.0889)
		(layer "In4.Cu")
		(net "UPI_CPU1_CPU0_P1P0_DN<2>")
	)
	(segment
		(start 156.921962 -190.463932)
		(end 156.484574 -190.90132)
		(width 0.14732)
		(layer "In4.Cu")
		(net "UPI_CPU1_CPU0_P1P0_DN<2>")
	)
	(segment
		(start 132.119878 -216.569798)
		(end 132.128768 -216.574878)
		(width 0.0889)
		(layer "In4.Cu")
		(net "UPI_CPU1_CPU0_P1P0_DN<2>")
	)
	(segment
		(start 134.041388 -213.285324)
		(end 133.820662 -213.50605)
		(width 0.0889)
		(layer "In4.Cu")
		(net "UPI_CPU1_CPU0_P1P0_DN<2>")
	)
	(segment
		(start 318.842644 -192.345564)
		(end 312.59526 -187.324238)
		(width 0.14732)
		(layer "In4.Cu")
		(net "UPI_CPU1_CPU0_P1P0_DN<2>")
	)
	(segment
		(start 142.402052 -203.350368)
		(end 142.199868 -203.38542)
		(width 0.14732)
		(layer "In4.Cu")
		(net "UPI_CPU1_CPU0_P1P0_DN<2>")
	)
	(segment
		(start 338.710524 -213.102698)
		(end 338.809584 -213.003638)
		(width 0.0889)
		(layer "In4.Cu")
		(net "UPI_CPU1_CPU0_P1P0_DN<2>")
	)
	(segment
		(start 339.092794 -217.554556)
		(end 339.092032 -217.554048)
		(width 0.0889)
		(layer "In4.Cu")
		(net "UPI_CPU1_CPU0_P1P0_DN<2>")
	)
	(segment
		(start 269.03553 -190.27267)
		(end 268.622526 -190.424054)
		(width 0.14732)
		(layer "In4.Cu")
		(net "UPI_CPU1_CPU0_P1P0_DN<2>")
	)
	(segment
		(start 338.76742 -211.800948)
		(end 338.76742 -208.902808)
		(width 0.14732)
		(layer "In4.Cu")
		(net "UPI_CPU1_CPU0_P1P0_DN<2>")
	)
	(segment
		(start 340.2838 -205.701138)
		(end 339.616542 -204.09027)
		(width 0.14732)
		(layer "In4.Cu")
		(net "UPI_CPU1_CPU0_P1P0_DN<2>")
	)
	(segment
		(start 338.809584 -212.454998)
		(end 338.809584 -212.101938)
		(width 0.0889)
		(layer "In4.Cu")
		(net "UPI_CPU1_CPU0_P1P0_DN<2>")
	)
	(segment
		(start 290.797488 -187.27039)
		(end 273.043904 -187.763404)
		(width 0.14732)
		(layer "In4.Cu")
		(net "UPI_CPU1_CPU0_P1P0_DN<2>")
	)
	(segment
		(start 339.100922 -217.559128)
		(end 339.092794 -217.554556)
		(width 0.0889)
		(layer "In4.Cu")
		(net "UPI_CPU1_CPU0_P1P0_DN<2>")
	)
	(segment
		(start 142.199868 -203.38542)
		(end 141.955012 -203.7334)
		(width 0.14732)
		(layer "In4.Cu")
		(net "UPI_CPU1_CPU0_P1P0_DN<2>")
	)
	(segment
		(start 299.456094 -187.030106)
		(end 299.313092 -187.181236)
		(width 0.14732)
		(layer "In4.Cu")
		(net "UPI_CPU1_CPU0_P1P0_DN<2>")
	)
	(segment
		(start 144.18818 -200.561956)
		(end 142.57909 -202.847448)
		(width 0.14732)
		(layer "In4.Cu")
		(net "UPI_CPU1_CPU0_P1P0_DN<2>")
	)
	(segment
		(start 338.76742 -208.902808)
		(end 340.2838 -207.386428)
		(width 0.14732)
		(layer "In4.Cu")
		(net "UPI_CPU1_CPU0_P1P0_DN<2>")
	)
	(segment
		(start 297.880278 -187.221114)
		(end 297.729148 -187.078112)
		(width 0.14732)
		(layer "In4.Cu")
		(net "UPI_CPU1_CPU0_P1P0_DN<2>")
	)
	(segment
		(start 132.517896 -215.934798)
		(end 132.503164 -215.926162)
		(width 0.0889)
		(layer "In4.Cu")
		(net "UPI_CPU1_CPU0_P1P0_DN<2>")
	)
	(segment
		(start 339.093556 -215.926924)
		(end 339.092032 -215.926162)
		(width 0.0889)
		(layer "In4.Cu")
		(net "UPI_CPU1_CPU0_P1P0_DN<2>")
	)
	(segment
		(start 294.711882 -187.809378)
		(end 294.41267 -188.125354)
		(width 0.14732)
		(layer "In4.Cu")
		(net "UPI_CPU1_CPU0_P1P0_DN<2>")
	)
	(segment
		(start 339.091524 -214.946992)
		(end 339.100414 -214.941912)
		(width 0.0889)
		(layer "In4.Cu")
		(net "UPI_CPU1_CPU0_P1P0_DN<2>")
	)
	(segment
		(start 150.160482 -195.895468)
		(end 149.82063 -196.038216)
		(width 0.14732)
		(layer "In4.Cu")
		(net "UPI_CPU1_CPU0_P1P0_DN<2>")
	)
	(segment
		(start 135.260842 -212.125052)
		(end 135.260588 -212.125052)
		(width 0.14732)
		(layer "In4.Cu")
		(net "UPI_CPU1_CPU0_P1P0_DN<2>")
	)
	(segment
		(start 299.338492 -188.096652)
		(end 299.03928 -188.412628)
		(width 0.14732)
		(layer "In4.Cu")
		(net "UPI_CPU1_CPU0_P1P0_DN<2>")
	)
	(segment
		(start 141.357096 -204.833982)
		(end 141.145006 -205.13548)
		(width 0.14732)
		(layer "In4.Cu")
		(net "UPI_CPU1_CPU0_P1P0_DN<2>")
	)
	(segment
		(start 338.809584 -212.101938)
		(end 338.767674 -212.060028)
		(width 0.0889)
		(layer "In4.Cu")
		(net "UPI_CPU1_CPU0_P1P0_DN<2>")
	)
	(segment
		(start 135.260588 -212.125052)
		(end 134.11581 -213.26983)
		(width 0.14732)
		(layer "In4.Cu")
		(net "UPI_CPU1_CPU0_P1P0_DN<2>")
	)
	(segment
		(start 294.697912 -187.308998)
		(end 294.711882 -187.809378)
		(width 0.14732)
		(layer "In4.Cu")
		(net "UPI_CPU1_CPU0_P1P0_DN<2>")
	)
	(segment
		(start 339.092032 -216.574878)
		(end 339.100922 -216.569798)
		(width 0.0889)
		(layer "In4.Cu")
		(net "UPI_CPU1_CPU0_P1P0_DN<2>")
	)
	(segment
		(start 298.221654 -188.435742)
		(end 297.905678 -188.13653)
		(width 0.14732)
		(layer "In4.Cu")
		(net "UPI_CPU1_CPU0_P1P0_DN<2>")
	)
	(segment
		(start 132.128768 -215.926162)
		(end 132.119878 -215.931242)
		(width 0.0889)
		(layer "In4.Cu")
		(net "UPI_CPU1_CPU0_P1P0_DN<2>")
	)
	(segment
		(start 338.767674 -211.801202)
		(end 338.76742 -211.800948)
		(width 0.14732)
		(layer "In4.Cu")
		(net "UPI_CPU1_CPU0_P1P0_DN<2>")
	)
	(segment
		(start 338.80933 -217.071956)
		(end 338.80933 -217.064336)
		(width 0.0889)
		(layer "In4.Cu")
		(net "UPI_CPU1_CPU0_P1P0_DN<2>")
	)
	(segment
		(start 293.113968 -187.205874)
		(end 292.524434 -187.222384)
		(width 0.14732)
		(layer "In4.Cu")
		(net "UPI_CPU1_CPU0_P1P0_DN<2>")
	)
	(segment
		(start 134.100316 -213.285324)
		(end 134.041388 -213.285324)
		(width 0.0889)
		(layer "In4.Cu")
		(net "UPI_CPU1_CPU0_P1P0_DN<2>")
	)
	(segment
		(start 148.767546 -196.323204)
		(end 144.18818 -200.561956)
		(width 0.14732)
		(layer "In4.Cu")
		(net "UPI_CPU1_CPU0_P1P0_DN<2>")
	)
	(segment
		(start 236.074712 -199.107044)
		(end 233.114596 -198.232014)
		(width 0.14732)
		(layer "In4.Cu")
		(net "UPI_CPU1_CPU0_P1P0_DN<2>")
	)
	(segment
		(start 339.088222 -216.577164)
		(end 339.092032 -216.574878)
		(width 0.0889)
		(layer "In4.Cu")
		(net "UPI_CPU1_CPU0_P1P0_DN<2>")
	)
	(segment
		(start 140.943076 -205.170532)
		(end 137.915904 -209.469736)
		(width 0.14732)
		(layer "In4.Cu")
		(net "UPI_CPU1_CPU0_P1P0_DN<2>")
	)
	(segment
		(start 207.786478 -187.947046)
		(end 200.166732 -187.155582)
		(width 0.14732)
		(layer "In4.Cu")
		(net "UPI_CPU1_CPU0_P1P0_DN<2>")
	)
	(segment
		(start 297.905678 -188.13653)
		(end 297.880278 -187.221114)
		(width 0.14732)
		(layer "In4.Cu")
		(net "UPI_CPU1_CPU0_P1P0_DN<2>")
	)
	(segment
		(start 137.915396 -209.470498)
		(end 135.260842 -212.125052)
		(width 0.14732)
		(layer "In4.Cu")
		(net "UPI_CPU1_CPU0_P1P0_DN<2>")
	)
	(segment
		(start 156.223716 -191.366648)
		(end 156.018992 -191.366648)
		(width 0.14732)
		(layer "In4.Cu")
		(net "UPI_CPU1_CPU0_P1P0_DN<2>")
	)
	(segment
		(start 299.03928 -188.412628)
		(end 298.221654 -188.435742)
		(width 0.14732)
		(layer "In4.Cu")
		(net "UPI_CPU1_CPU0_P1P0_DN<2>")
	)
	(segment
		(start 338.809584 -212.828378)
		(end 338.710524 -212.729318)
		(width 0.0889)
		(layer "In4.Cu")
		(net "UPI_CPU1_CPU0_P1P0_DN<2>")
	)
	(segment
		(start 299.313092 -187.181236)
		(end 299.338492 -188.096652)
		(width 0.14732)
		(layer "In4.Cu")
		(net "UPI_CPU1_CPU0_P1P0_DN<2>")
	)
	(segment
		(start 157.387544 -189.99835)
		(end 157.387544 -190.203074)
		(width 0.14732)
		(layer "In4.Cu")
		(net "UPI_CPU1_CPU0_P1P0_DN<2>")
	)
	(segment
		(start 333.937356 -198.411084)
		(end 332.031086 -196.911468)
		(width 0.14732)
		(layer "In4.Cu")
		(net "UPI_CPU1_CPU0_P1P0_DN<2>")
	)
	(segment
		(start 237.308898 -199.107044)
		(end 236.074712 -199.107044)
		(width 0.14732)
		(layer "In4.Cu")
		(net "UPI_CPU1_CPU0_P1P0_DN<2>")
	)
	(segment
		(start 156.484574 -190.90132)
		(end 156.48432 -191.106044)
		(width 0.14732)
		(layer "In4.Cu")
		(net "UPI_CPU1_CPU0_P1P0_DN<2>")
	)
	(segment
		(start 292.381432 -187.373514)
		(end 292.395402 -187.873894)
		(width 0.14732)
		(layer "In4.Cu")
		(net "UPI_CPU1_CPU0_P1P0_DN<2>")
	)
	(segment
		(start 339.09127 -215.925654)
		(end 339.085936 -215.922606)
		(width 0.0889)
		(layer "In4.Cu")
		(net "UPI_CPU1_CPU0_P1P0_DN<2>")
	)
	(segment
		(start 293.265098 -187.348876)
		(end 293.113968 -187.205874)
		(width 0.14732)
		(layer "In4.Cu")
		(net "UPI_CPU1_CPU0_P1P0_DN<2>")
	)
	(segment
		(start 338.767674 -212.060028)
		(end 338.767674 -212.03793)
		(width 0.0889)
		(layer "In4.Cu")
		(net "UPI_CPU1_CPU0_P1P0_DN<2>")
	)
	(segment
		(start 149.82063 -196.038216)
		(end 149.630892 -195.960746)
		(width 0.14732)
		(layer "In4.Cu")
		(net "UPI_CPU1_CPU0_P1P0_DN<2>")
	)
	(segment
		(start 141.576044 -204.271372)
		(end 141.322044 -204.632306)
		(width 0.14732)
		(layer "In4.Cu")
		(net "UPI_CPU1_CPU0_P1P0_DN<2>")
	)
	(segment
		(start 137.915904 -209.469736)
		(end 137.915396 -209.470498)
		(width 0.14732)
		(layer "In4.Cu")
		(net "UPI_CPU1_CPU0_P1P0_DN<2>")
	)
	(segment
		(start 338.80933 -215.436704)
		(end 338.80933 -215.414606)
		(width 0.0889)
		(layer "In4.Cu")
		(net "UPI_CPU1_CPU0_P1P0_DN<2>")
	)
	(segment
		(start 233.114596 -198.232014)
		(end 223.238314 -191.835278)
		(width 0.14732)
		(layer "In4.Cu")
		(net "UPI_CPU1_CPU0_P1P0_DN<2>")
	)
	(segment
		(start 297.729148 -187.078112)
		(end 294.840914 -187.157868)
		(width 0.14732)
		(layer "In4.Cu")
		(net "UPI_CPU1_CPU0_P1P0_DN<2>")
	)
	(segment
		(start 157.387544 -190.203074)
		(end 157.126686 -190.463932)
		(width 0.14732)
		(layer "In4.Cu")
		(net "UPI_CPU1_CPU0_P1P0_DN<2>")
	)
	(segment
		(start 215.004904 -187.944506)
		(end 211.220304 -187.71235)
		(width 0.14732)
		(layer "In4.Cu")
		(net "UPI_CPU1_CPU0_P1P0_DN<2>")
	)
	(segment
		(start 338.904834 -217.878406)
		(end 339.061298 -218.149424)
		(width 0.0889)
		(layer "In4.Cu")
		(net "UPI_CPU1_CPU0_P1P0_DN<2>")
	)
	(segment
		(start 134.11581 -213.26983)
		(end 134.100316 -213.285324)
		(width 0.0889)
		(layer "In4.Cu")
		(net "UPI_CPU1_CPU0_P1P0_DN<2>")
	)
	(segment
		(start 211.220304 -187.71235)
		(end 207.786478 -187.947046)
		(width 0.14732)
		(layer "In4.Cu")
		(net "UPI_CPU1_CPU0_P1P0_DN<2>")
	)
	(segment
		(start 156.018992 -191.366648)
		(end 152.723596 -194.662044)
		(width 0.14732)
		(layer "In4.Cu")
		(net "UPI_CPU1_CPU0_P1P0_DN<2>")
	)
	(segment
		(start 292.09619 -188.18987)
		(end 291.278564 -188.212984)
		(width 0.14732)
		(layer "In4.Cu")
		(net "UPI_CPU1_CPU0_P1P0_DN<2>")
	)
	(segment
		(start 338.809584 -213.003638)
		(end 338.809584 -212.828378)
		(width 0.0889)
		(layer "In4.Cu")
		(net "UPI_CPU1_CPU0_P1P0_DN<2>")
	)
	(segment
		(start 141.955012 -203.7334)
		(end 141.990064 -203.935076)
		(width 0.14732)
		(layer "In4.Cu")
		(net "UPI_CPU1_CPU0_P1P0_DN<2>")
	)
	(segment
		(start 132.159502 -217.607388)
		(end 132.315966 -217.878406)
		(width 0.0889)
		(layer "In4.Cu")
		(net "UPI_CPU1_CPU0_P1P0_DN<2>")
	)
	(segment
		(start 290.948618 -187.413392)
		(end 290.797488 -187.27039)
		(width 0.14732)
		(layer "In4.Cu")
		(net "UPI_CPU1_CPU0_P1P0_DN<2>")
	)
	(segment
		(start 338.710524 -213.277958)
		(end 338.710524 -213.102698)
		(width 0.0889)
		(layer "In4.Cu")
		(net "UPI_CPU1_CPU0_P1P0_DN<2>")
	)
	(segment
		(start 261.033514 -190.865252)
		(end 249.896376 -193.82359)
		(width 0.14732)
		(layer "In4.Cu")
		(net "UPI_CPU1_CPU0_P1P0_DN<2>")
	)
	(segment
		(start 339.278976 -214.622634)
		(end 339.278976 -214.461344)
		(width 0.0889)
		(layer "In4.Cu")
		(net "UPI_CPU1_CPU0_P1P0_DN<2>")
	)
	(segment
		(start 200.166732 -187.155582)
		(end 159.988758 -187.8457)
		(width 0.14732)
		(layer "In4.Cu")
		(net "UPI_CPU1_CPU0_P1P0_DN<2>")
	)
	(segment
		(start 291.278564 -188.212984)
		(end 290.962588 -187.913772)
		(width 0.14732)
		(layer "In4.Cu")
		(net "UPI_CPU1_CPU0_P1P0_DN<2>")
	)
	(segment
		(start 294.41267 -188.125354)
		(end 293.595044 -188.148468)
		(width 0.14732)
		(layer "In4.Cu")
		(net "UPI_CPU1_CPU0_P1P0_DN<2>")
	)
	(segment
		(start 339.092032 -215.926162)
		(end 339.09127 -215.925654)
		(width 0.0889)
		(layer "In4.Cu")
		(net "UPI_CPU1_CPU0_P1P0_DN<2>")
	)
	(segment
		(start 312.59526 -187.324238)
		(end 311.913016 -187.12053)
		(width 0.14732)
		(layer "In4.Cu")
		(net "UPI_CPU1_CPU0_P1P0_DN<2>")
	)
	(segment
		(start 159.988758 -187.8457)
		(end 158.876238 -188.509656)
		(width 0.14732)
		(layer "In4.Cu")
		(net "UPI_CPU1_CPU0_P1P0_DN<2>")
	)
	(segment
		(start 292.395402 -187.873894)
		(end 292.09619 -188.18987)
		(width 0.14732)
		(layer "In4.Cu")
		(net "UPI_CPU1_CPU0_P1P0_DN<2>")
	)
	(segment
		(start 339.616542 -204.09027)
		(end 333.937356 -198.411084)
		(width 0.14732)
		(layer "In4.Cu")
		(net "UPI_CPU1_CPU0_P1P0_DN<2>")
	)
	(segment
		(start 268.622526 -190.424054)
		(end 267.475462 -190.596012)
		(width 0.14732)
		(layer "In4.Cu")
		(net "UPI_CPU1_CPU0_P1P0_DN<2>")
	)
	(segment
		(start 158.876238 -188.509656)
		(end 157.387544 -189.99835)
		(width 0.14732)
		(layer "In4.Cu")
		(net "UPI_CPU1_CPU0_P1P0_DN<2>")
	)
	(segment
		(start 156.48432 -191.106044)
		(end 156.223716 -191.366648)
		(width 0.14732)
		(layer "In4.Cu")
		(net "UPI_CPU1_CPU0_P1P0_DN<2>")
	)
	(segment
		(start 141.145006 -205.13548)
		(end 140.943076 -205.170532)
		(width 0.14732)
		(layer "In4.Cu")
		(net "UPI_CPU1_CPU0_P1P0_DN<2>")
	)
	(segment
		(start 149.630892 -195.960746)
		(end 148.767546 -196.323204)
		(width 0.14732)
		(layer "In4.Cu")
		(net "UPI_CPU1_CPU0_P1P0_DN<2>")
	)
	(segment
		(start 132.183632 -217.518234)
		(end 132.159502 -217.607388)
		(width 0.0889)
		(layer "In4.Cu")
		(net "UPI_CPU1_CPU0_P1P0_DN<2>")
	)
	(segment
		(start 339.061298 -218.149424)
		(end 339.13953 -218.170252)
		(width 0.0889)
		(layer "In4.Cu")
		(net "UPI_CPU1_CPU0_P1P0_DN<2>")
	)
	(segment
		(start 292.524434 -187.222384)
		(end 292.381432 -187.373514)
		(width 0.14732)
		(layer "In4.Cu")
		(net "UPI_CPU1_CPU0_P1P0_DN<2>")
	)
	(segment
		(start 141.778228 -204.23632)
		(end 141.576044 -204.271372)
		(width 0.14732)
		(layer "In4.Cu")
		(net "UPI_CPU1_CPU0_P1P0_DN<2>")
	)
	(segment
		(start 133.820662 -213.50605)
		(end 133.820662 -214.579962)
		(width 0.0889)
		(layer "In4.Cu")
		(net "UPI_CPU1_CPU0_P1P0_DN<2>")
	)
	(segment
		(start 293.595044 -188.148468)
		(end 293.279068 -187.849256)
		(width 0.14732)
		(layer "In4.Cu")
		(net "UPI_CPU1_CPU0_P1P0_DN<2>")
	)
	(segment
		(start 290.962588 -187.913772)
		(end 290.948618 -187.413392)
		(width 0.14732)
		(layer "In4.Cu")
		(net "UPI_CPU1_CPU0_P1P0_DN<2>")
	)
	(segment
		(start 294.840914 -187.157868)
		(end 294.697912 -187.308998)
		(width 0.14732)
		(layer "In4.Cu")
		(net "UPI_CPU1_CPU0_P1P0_DN<2>")
	)
	(segment
		(start 132.411216 -217.064336)
		(end 132.411216 -217.07856)
		(width 0.0889)
		(layer "In4.Cu")
		(net "UPI_CPU1_CPU0_P1P0_DN<2>")
	)
	(segment
		(start 267.475462 -190.596012)
		(end 261.033514 -190.865252)
		(width 0.14732)
		(layer "In4.Cu")
		(net "UPI_CPU1_CPU0_P1P0_DN<2>")
	)
	(segment
		(start 339.07984 -216.58199)
		(end 339.088222 -216.577164)
		(width 0.0889)
		(layer "In4.Cu")
		(net "UPI_CPU1_CPU0_P1P0_DN<2>")
	)
	(segment
		(start 223.238314 -191.835278)
		(end 215.004904 -187.944506)
		(width 0.14732)
		(layer "In4.Cu")
		(net "UPI_CPU1_CPU0_P1P0_DN<2>")
	)
	(segment
		(start 141.322044 -204.632306)
		(end 141.357096 -204.833982)
		(width 0.14732)
		(layer "In4.Cu")
		(net "UPI_CPU1_CPU0_P1P0_DN<2>")
	)
	(segment
		(start 271.860518 -188.067442)
		(end 269.03553 -190.27267)
		(width 0.14732)
		(layer "In4.Cu")
		(net "UPI_CPU1_CPU0_P1P0_DN<2>")
	)
	(segment
		(start 338.809584 -213.377018)
		(end 338.710524 -213.277958)
		(width 0.0889)
		(layer "In4.Cu")
		(net "UPI_CPU1_CPU0_P1P0_DN<2>")
	)
	(segment
		(start 273.043904 -187.763404)
		(end 271.860518 -188.067442)
		(width 0.14732)
		(layer "In4.Cu")
		(net "UPI_CPU1_CPU0_P1P0_DN<2>")
	)
	(segment
		(start 338.710524 -212.554058)
		(end 338.809584 -212.454998)
		(width 0.0889)
		(layer "In4.Cu")
		(net "UPI_CPU1_CPU0_P1P0_DN<2>")
	)
	(segment
		(start 142.57909 -202.847448)
		(end 142.613888 -203.049124)
		(width 0.14732)
		(layer "In4.Cu")
		(net "UPI_CPU1_CPU0_P1P0_DN<2>")
	)
	(segment
		(start 338.767674 -212.03793)
		(end 338.767674 -211.801202)
		(width 0.14732)
		(layer "In4.Cu")
		(net "UPI_CPU1_CPU0_P1P0_DN<2>")
	)
	(segment
		(start 311.913016 -187.12053)
		(end 302.453294 -186.947302)
		(width 0.14732)
		(layer "In4.Cu")
		(net "UPI_CPU1_CPU0_P1P0_DN<2>")
	)
	(segment
		(start 150.237698 -195.705984)
		(end 150.160482 -195.895468)
		(width 0.14732)
		(layer "In4.Cu")
		(net "UPI_CPU1_CPU0_P1P0_DN<2>")
	)
	(segment
		(start 302.453294 -186.947302)
		(end 299.456094 -187.030106)
		(width 0.14732)
		(layer "In4.Cu")
		(net "UPI_CPU1_CPU0_P1P0_DN<2>")
	)
	(segment
		(start 340.2838 -207.386428)
		(end 340.2838 -205.701138)
		(width 0.14732)
		(layer "In4.Cu")
		(net "UPI_CPU1_CPU0_P1P0_DN<2>")
	)
	(segment
		(start 238.741712 -198.927974)
		(end 237.308898 -199.107044)
		(width 0.14732)
		(layer "In4.Cu")
		(net "UPI_CPU1_CPU0_P1P0_DN<2>")
	)
	(segment
		(start 249.896376 -193.82359)
		(end 238.741712 -198.927974)
		(width 0.14732)
		(layer "In4.Cu")
		(net "UPI_CPU1_CPU0_P1P0_DN<2>")
	)
	(segment
		(start 133.350762 -215.436704)
		(end 133.350762 -215.452198)
		(width 0.0889)
		(layer "In4.Cu")
		(net "UPI_CPU1_CPU0_P1P0_DN<2>")
	)
	(segment
		(start 338.809584 -213.930484)
		(end 338.809584 -213.377018)
		(width 0.0889)
		(layer "In4.Cu")
		(net "UPI_CPU1_CPU0_P1P0_DN<2>")
	)
	(segment
		(start 133.573266 -215.092026)
		(end 133.529324 -215.117426)
		(width 0.0889)
		(layer "In4.Cu")
		(net "UPI_CPU1_CPU0_P1P0_DN<2>")
	)
	(segment
		(start 142.613888 -203.049124)
		(end 142.402052 -203.350368)
		(width 0.14732)
		(layer "In4.Cu")
		(net "UPI_CPU1_CPU0_P1P0_DN<2>")
	)
	(segment
		(start 293.279068 -187.849256)
		(end 293.265098 -187.348876)
		(width 0.14732)
		(layer "In4.Cu")
		(net "UPI_CPU1_CPU0_P1P0_DN<2>")
	)
	(segment
		(start 157.126686 -190.463932)
		(end 156.921962 -190.463932)
		(width 0.14732)
		(layer "In4.Cu")
		(net "UPI_CPU1_CPU0_P1P0_DN<2>")
	)
	(arc
		(start 132.411216 -217.07856)
		(mid 132.352855 -217.315158)
		(end 132.200396 -217.50528)
		(width 0.0889)
		(layer "In4.Cu")
		(net "UPI_CPU1_CPU0_P1P0_DN<2>")
	)
	(arc
		(start 132.503164 -215.926162)
		(mid 132.315966 -215.876019)
		(end 132.128768 -215.926162)
		(width 0.0889)
		(layer "In4.Cu")
		(net "UPI_CPU1_CPU0_P1P0_DN<2>")
	)
	(arc
		(start 339.085936 -215.922606)
		(mid 338.883349 -215.716255)
		(end 338.80933 -215.436704)
		(width 0.0889)
		(layer "In4.Cu")
		(net "UPI_CPU1_CPU0_P1P0_DN<2>")
	)
	(arc
		(start 133.350762 -215.452198)
		(mid 133.271392 -215.725932)
		(end 133.068568 -215.926162)
		(width 0.0889)
		(layer "In4.Cu")
		(net "UPI_CPU1_CPU0_P1P0_DN<2>")
	)
	(arc
		(start 339.100414 -214.941912)
		(mid 339.231328 -214.805552)
		(end 339.278976 -214.622634)
		(width 0.0889)
		(layer "In4.Cu")
		(net "UPI_CPU1_CPU0_P1P0_DN<2>")
	)
	(arc
		(start 339.100922 -216.569798)
		(mid 339.279519 -216.25052)
		(end 339.100922 -215.931242)
		(width 0.0889)
		(layer "In4.Cu")
		(net "UPI_CPU1_CPU0_P1P0_DN<2>")
	)
	(arc
		(start 339.278976 -214.461344)
		(mid 339.203971 -214.345885)
		(end 339.094826 -214.261954)
		(width 0.0889)
		(layer "In4.Cu")
		(net "UPI_CPU1_CPU0_P1P0_DN<2>")
	)
	(arc
		(start 338.80933 -217.064336)
		(mid 338.881565 -216.787812)
		(end 339.07984 -216.58199)
		(width 0.0889)
		(layer "In4.Cu")
		(net "UPI_CPU1_CPU0_P1P0_DN<2>")
	)
	(arc
		(start 132.134864 -216.578434)
		(mid 132.337277 -216.784847)
		(end 132.411216 -217.064336)
		(width 0.0889)
		(layer "In4.Cu")
		(net "UPI_CPU1_CPU0_P1P0_DN<2>")
	)
	(arc
		(start 339.13953 -218.170252)
		(mid 339.242675 -218.040227)
		(end 339.279484 -217.878406)
		(width 0.0889)
		(layer "In4.Cu")
		(net "UPI_CPU1_CPU0_P1P0_DN<2>")
	)
	(arc
		(start 132.200396 -217.50528)
		(mid 132.192074 -217.511835)
		(end 132.183632 -217.518234)
		(width 0.0889)
		(layer "In4.Cu")
		(net "UPI_CPU1_CPU0_P1P0_DN<2>")
	)
	(arc
		(start 338.824824 -213.969346)
		(mid 338.816861 -213.950049)
		(end 338.809584 -213.930484)
		(width 0.0889)
		(layer "In4.Cu")
		(net "UPI_CPU1_CPU0_P1P0_DN<2>")
	)
	(arc
		(start 133.820662 -214.579962)
		(mid 133.765821 -214.869267)
		(end 133.573266 -215.092026)
		(width 0.0889)
		(layer "In4.Cu")
		(net "UPI_CPU1_CPU0_P1P0_DN<2>")
	)
	(arc
		(start 338.80933 -215.414606)
		(mid 338.890241 -215.144478)
		(end 339.091524 -214.946992)
		(width 0.0889)
		(layer "In4.Cu")
		(net "UPI_CPU1_CPU0_P1P0_DN<2>")
	)
	(arc
		(start 339.279484 -217.878406)
		(mid 339.231805 -217.695506)
		(end 339.100922 -217.559128)
		(width 0.0889)
		(layer "In4.Cu")
		(net "UPI_CPU1_CPU0_P1P0_DN<2>")
	)
	(arc
		(start 133.351016 -215.421972)
		(mid 133.350819 -215.429337)
		(end 133.350762 -215.436704)
		(width 0.0889)
		(layer "In4.Cu")
		(net "UPI_CPU1_CPU0_P1P0_DN<2>")
	)
	(arc
		(start 133.529324 -215.117426)
		(mid 133.40207 -215.247392)
		(end 133.351016 -215.421972)
		(width 0.0889)
		(layer "In4.Cu")
		(net "UPI_CPU1_CPU0_P1P0_DN<2>")
	)
	(arc
		(start 339.092032 -217.554048)
		(mid 338.88696 -217.350369)
		(end 338.80933 -217.071956)
		(width 0.0889)
		(layer "In4.Cu")
		(net "UPI_CPU1_CPU0_P1P0_DN<2>")
	)
	(arc
		(start 132.119878 -215.931242)
		(mid 131.941402 -216.25052)
		(end 132.119878 -216.569798)
		(width 0.0889)
		(layer "In4.Cu")
		(net "UPI_CPU1_CPU0_P1P0_DN<2>")
	)
	(arc
		(start 339.094826 -214.261954)
		(mid 338.934754 -214.138774)
		(end 338.824824 -213.969346)
		(width 0.0889)
		(layer "In4.Cu")
		(net "UPI_CPU1_CPU0_P1P0_DN<2>")
	)
	(arc
		(start 133.068568 -215.926162)
		(mid 132.794369 -216.001997)
		(end 132.517896 -215.934798)
		(width 0.0889)
		(layer "In4.Cu")
		(net "UPI_CPU1_CPU0_P1P0_DN<2>")
	)
	(segment
		(start 112.579912 -217.87866)
		(end 112.580166 -217.878406)
		(width 0.13208)
		(layer "F.Cu")
		(net "UPI_CPU1_CPU0_P1P0_DN<23>")
	)
	(segment
		(start 112.579912 -218.414346)
		(end 112.579912 -217.87866)
		(width 0.13208)
		(layer "F.Cu")
		(net "UPI_CPU1_CPU0_P1P0_DN<23>")
	)
	(segment
		(start 358.640634 -217.878406)
		(end 358.640634 -218.414346)
		(width 0.13208)
		(layer "F.Cu")
		(net "UPI_CPU1_CPU0_P1P0_DN<23>")
	)
	(segment
		(start 122.446034 -191.707262)
		(end 122.617738 -191.689482)
		(width 0.14732)
		(layer "In4.Cu")
		(net "UPI_CPU1_CPU0_P1P0_DN<23>")
	)
	(segment
		(start 359.29951 -215.113616)
		(end 359.30332 -215.115648)
		(width 0.0889)
		(layer "In4.Cu")
		(net "UPI_CPU1_CPU0_P1P0_DN<23>")
	)
	(segment
		(start 123.598432 -190.482728)
		(end 123.580652 -190.311278)
		(width 0.14732)
		(layer "In4.Cu")
		(net "UPI_CPU1_CPU0_P1P0_DN<23>")
	)
	(segment
		(start 121.20753 -193.424302)
		(end 121.48312 -193.084958)
		(width 0.14732)
		(layer "In4.Cu")
		(net "UPI_CPU1_CPU0_P1P0_DN<23>")
	)
	(segment
		(start 359.30332 -215.115648)
		(end 359.304082 -215.116156)
		(width 0.0889)
		(layer "In4.Cu")
		(net "UPI_CPU1_CPU0_P1P0_DN<23>")
	)
	(segment
		(start 345.72448 -183.995314)
		(end 348.198186 -187.50788)
		(width 0.14732)
		(layer "In4.Cu")
		(net "UPI_CPU1_CPU0_P1P0_DN<23>")
	)
	(segment
		(start 118.645178 -196.383148)
		(end 118.920514 -196.044312)
		(width 0.14732)
		(layer "In4.Cu")
		(net "UPI_CPU1_CPU0_P1P0_DN<23>")
	)
	(segment
		(start 122.188224 -192.217548)
		(end 122.170698 -192.046098)
		(width 0.14732)
		(layer "In4.Cu")
		(net "UPI_CPU1_CPU0_P1P0_DN<23>")
	)
	(segment
		(start 118.662958 -196.554598)
		(end 118.645178 -196.383148)
		(width 0.14732)
		(layer "In4.Cu")
		(net "UPI_CPU1_CPU0_P1P0_DN<23>")
	)
	(segment
		(start 111.923068 -217.388694)
		(end 111.914178 -217.383614)
		(width 0.0889)
		(layer "In4.Cu")
		(net "UPI_CPU1_CPU0_P1P0_DN<23>")
	)
	(segment
		(start 121.912634 -192.556892)
		(end 122.188224 -192.217548)
		(width 0.14732)
		(layer "In4.Cu")
		(net "UPI_CPU1_CPU0_P1P0_DN<23>")
	)
	(segment
		(start 123.151138 -190.839852)
		(end 123.322588 -190.822072)
		(width 0.14732)
		(layer "In4.Cu")
		(net "UPI_CPU1_CPU0_P1P0_DN<23>")
	)
	(segment
		(start 348.198186 -187.50788)
		(end 354.659946 -194.130168)
		(width 0.14732)
		(layer "In4.Cu")
		(net "UPI_CPU1_CPU0_P1P0_DN<23>")
	)
	(segment
		(start 358.772968 -217.518234)
		(end 358.772968 -217.518488)
		(width 0.0889)
		(layer "In4.Cu")
		(net "UPI_CPU1_CPU0_P1P0_DN<23>")
	)
	(segment
		(start 112.646968 -213.59622)
		(end 112.646968 -213.42096)
		(width 0.0889)
		(layer "In4.Cu")
		(net "UPI_CPU1_CPU0_P1P0_DN<23>")
	)
	(segment
		(start 112.580166 -217.878406)
		(end 112.423702 -218.149424)
		(width 0.0889)
		(layer "In4.Cu")
		(net "UPI_CPU1_CPU0_P1P0_DN<23>")
	)
	(segment
		(start 358.972866 -212.967062)
		(end 358.972866 -212.98916)
		(width 0.0889)
		(layer "In4.Cu")
		(net "UPI_CPU1_CPU0_P1P0_DN<23>")
	)
	(segment
		(start 319.37452 -170.692572)
		(end 332.029816 -175.149002)
		(width 0.14732)
		(layer "In4.Cu")
		(net "UPI_CPU1_CPU0_P1P0_DN<23>")
	)
	(segment
		(start 112.205008 -214.707724)
		(end 112.205008 -214.44331)
		(width 0.0889)
		(layer "In4.Cu")
		(net "UPI_CPU1_CPU0_P1P0_DN<23>")
	)
	(segment
		(start 119.797322 -195.159122)
		(end 120.072912 -194.819778)
		(width 0.14732)
		(layer "In4.Cu")
		(net "UPI_CPU1_CPU0_P1P0_DN<23>")
	)
	(segment
		(start 123.580652 -190.311278)
		(end 124.331476 -189.38748)
		(width 0.14732)
		(layer "In4.Cu")
		(net "UPI_CPU1_CPU0_P1P0_DN<23>")
	)
	(segment
		(start 112.423702 -218.149424)
		(end 112.34547 -218.170252)
		(width 0.0889)
		(layer "In4.Cu")
		(net "UPI_CPU1_CPU0_P1P0_DN<23>")
	)
	(segment
		(start 314.040012 -169.2021)
		(end 319.37452 -170.692572)
		(width 0.14732)
		(layer "In4.Cu")
		(net "UPI_CPU1_CPU0_P1P0_DN<23>")
	)
	(segment
		(start 112.646968 -213.42096)
		(end 112.547908 -213.3219)
		(width 0.0889)
		(layer "In4.Cu")
		(net "UPI_CPU1_CPU0_P1P0_DN<23>")
	)
	(segment
		(start 358.836722 -216.569798)
		(end 358.827832 -216.574878)
		(width 0.0889)
		(layer "In4.Cu")
		(net "UPI_CPU1_CPU0_P1P0_DN<23>")
	)
	(segment
		(start 143.211804 -174.993554)
		(end 143.21155 -174.993554)
		(width 0.14732)
		(layer "In4.Cu")
		(net "UPI_CPU1_CPU0_P1P0_DN<23>")
	)
	(segment
		(start 359.297478 -215.112346)
		(end 359.29951 -215.113616)
		(width 0.0889)
		(layer "In4.Cu")
		(net "UPI_CPU1_CPU0_P1P0_DN<23>")
	)
	(segment
		(start 358.797098 -217.607388)
		(end 358.640634 -217.878406)
		(width 0.0889)
		(layer "In4.Cu")
		(net "UPI_CPU1_CPU0_P1P0_DN<23>")
	)
	(segment
		(start 358.545384 -217.05443)
		(end 358.545384 -217.082878)
		(width 0.0889)
		(layer "In4.Cu")
		(net "UPI_CPU1_CPU0_P1P0_DN<23>")
	)
	(segment
		(start 341.526114 -179.796948)
		(end 345.72448 -183.995314)
		(width 0.14732)
		(layer "In4.Cu")
		(net "UPI_CPU1_CPU0_P1P0_DN<23>")
	)
	(segment
		(start 302.46828 -168.986454)
		(end 314.040012 -169.2021)
		(width 0.14732)
		(layer "In4.Cu")
		(net "UPI_CPU1_CPU0_P1P0_DN<23>")
	)
	(segment
		(start 121.465594 -192.913508)
		(end 121.74093 -192.574672)
		(width 0.14732)
		(layer "In4.Cu")
		(net "UPI_CPU1_CPU0_P1P0_DN<23>")
	)
	(segment
		(start 112.547908 -212.65134)
		(end 112.547908 -212.114892)
		(width 0.0889)
		(layer "In4.Cu")
		(net "UPI_CPU1_CPU0_P1P0_DN<23>")
	)
	(segment
		(start 119.368062 -195.687188)
		(end 119.350282 -195.515738)
		(width 0.14732)
		(layer "In4.Cu")
		(net "UPI_CPU1_CPU0_P1P0_DN<23>")
	)
	(segment
		(start 136.723882 -178.315112)
		(end 143.211804 -174.993554)
		(width 0.14732)
		(layer "In4.Cu")
		(net "UPI_CPU1_CPU0_P1P0_DN<23>")
	)
	(segment
		(start 122.893328 -191.350138)
		(end 122.875802 -191.178688)
		(width 0.14732)
		(layer "In4.Cu")
		(net "UPI_CPU1_CPU0_P1P0_DN<23>")
	)
	(segment
		(start 122.170698 -192.046098)
		(end 122.446034 -191.707262)
		(width 0.14732)
		(layer "In4.Cu")
		(net "UPI_CPU1_CPU0_P1P0_DN<23>")
	)
	(segment
		(start 354.659946 -194.130168)
		(end 358.972612 -204.541628)
		(width 0.14732)
		(layer "In4.Cu")
		(net "UPI_CPU1_CPU0_P1P0_DN<23>")
	)
	(segment
		(start 358.972866 -212.671914)
		(end 358.972866 -212.967062)
		(width 0.14732)
		(layer "In4.Cu")
		(net "UPI_CPU1_CPU0_P1P0_DN<23>")
	)
	(segment
		(start 359.304082 -215.116156)
		(end 359.308146 -215.118696)
		(width 0.0889)
		(layer "In4.Cu")
		(net "UPI_CPU1_CPU0_P1P0_DN<23>")
	)
	(segment
		(start 118.387114 -196.893942)
		(end 118.662958 -196.554598)
		(width 0.14732)
		(layer "In4.Cu")
		(net "UPI_CPU1_CPU0_P1P0_DN<23>")
	)
	(segment
		(start 117.476524 -197.821042)
		(end 118.215664 -196.911722)
		(width 0.14732)
		(layer "In4.Cu")
		(net "UPI_CPU1_CPU0_P1P0_DN<23>")
	)
	(segment
		(start 358.972612 -204.541628)
		(end 358.972612 -212.67166)
		(width 0.14732)
		(layer "In4.Cu")
		(net "UPI_CPU1_CPU0_P1P0_DN<23>")
	)
	(segment
		(start 358.972866 -212.98916)
		(end 359.014776 -213.03107)
		(width 0.0889)
		(layer "In4.Cu")
		(net "UPI_CPU1_CPU0_P1P0_DN<23>")
	)
	(segment
		(start 339.340698 -178.311556)
		(end 341.526114 -179.796948)
		(width 0.14732)
		(layer "In4.Cu")
		(net "UPI_CPU1_CPU0_P1P0_DN<23>")
	)
	(segment
		(start 124.331476 -189.38748)
		(end 132.537708 -183.933338)
		(width 0.14732)
		(layer "In4.Cu")
		(net "UPI_CPU1_CPU0_P1P0_DN<23>")
	)
	(segment
		(start 112.547908 -212.114892)
		(end 112.590072 -212.072728)
		(width 0.0889)
		(layer "In4.Cu")
		(net "UPI_CPU1_CPU0_P1P0_DN<23>")
	)
	(segment
		(start 112.675162 -215.44661)
		(end 112.675162 -215.238838)
		(width 0.0889)
		(layer "In4.Cu")
		(net "UPI_CPU1_CPU0_P1P0_DN<23>")
	)
	(segment
		(start 332.029816 -175.149002)
		(end 339.340698 -178.311556)
		(width 0.14732)
		(layer "In4.Cu")
		(net "UPI_CPU1_CPU0_P1P0_DN<23>")
	)
	(segment
		(start 112.251998 -214.329772)
		(end 112.44199 -214.140034)
		(width 0.0889)
		(layer "In4.Cu")
		(net "UPI_CPU1_CPU0_P1P0_DN<23>")
	)
	(segment
		(start 358.772968 -217.518488)
		(end 358.797098 -217.607388)
		(width 0.0889)
		(layer "In4.Cu")
		(net "UPI_CPU1_CPU0_P1P0_DN<23>")
	)
	(segment
		(start 120.072912 -194.819778)
		(end 120.055386 -194.648328)
		(width 0.14732)
		(layer "In4.Cu")
		(net "UPI_CPU1_CPU0_P1P0_DN<23>")
	)
	(segment
		(start 112.547908 -213.883494)
		(end 112.547908 -213.69528)
		(width 0.0889)
		(layer "In4.Cu")
		(net "UPI_CPU1_CPU0_P1P0_DN<23>")
	)
	(segment
		(start 119.625618 -195.176902)
		(end 119.797322 -195.159122)
		(width 0.14732)
		(layer "In4.Cu")
		(net "UPI_CPU1_CPU0_P1P0_DN<23>")
	)
	(segment
		(start 112.547908 -213.3219)
		(end 112.547908 -213.02472)
		(width 0.0889)
		(layer "In4.Cu")
		(net "UPI_CPU1_CPU0_P1P0_DN<23>")
	)
	(segment
		(start 123.322588 -190.822072)
		(end 123.598432 -190.482728)
		(width 0.14732)
		(layer "In4.Cu")
		(net "UPI_CPU1_CPU0_P1P0_DN<23>")
	)
	(segment
		(start 112.205262 -214.707978)
		(end 112.205008 -214.707724)
		(width 0.0889)
		(layer "In4.Cu")
		(net "UPI_CPU1_CPU0_P1P0_DN<23>")
	)
	(segment
		(start 112.205516 -217.878406)
		(end 112.205516 -217.864182)
		(width 0.0889)
		(layer "In4.Cu")
		(net "UPI_CPU1_CPU0_P1P0_DN<23>")
	)
	(segment
		(start 119.092218 -196.026532)
		(end 119.368062 -195.687188)
		(width 0.14732)
		(layer "In4.Cu")
		(net "UPI_CPU1_CPU0_P1P0_DN<23>")
	)
	(segment
		(start 112.590072 -212.072728)
		(end 112.590072 -212.05063)
		(width 0.0889)
		(layer "In4.Cu")
		(net "UPI_CPU1_CPU0_P1P0_DN<23>")
	)
	(segment
		(start 111.914178 -216.745058)
		(end 111.923068 -216.739978)
		(width 0.0889)
		(layer "In4.Cu")
		(net "UPI_CPU1_CPU0_P1P0_DN<23>")
	)
	(segment
		(start 273.029426 -169.70375)
		(end 302.46828 -168.986454)
		(width 0.14732)
		(layer "In4.Cu")
		(net "UPI_CPU1_CPU0_P1P0_DN<23>")
	)
	(segment
		(start 122.875802 -191.178688)
		(end 123.151138 -190.839852)
		(width 0.14732)
		(layer "In4.Cu")
		(net "UPI_CPU1_CPU0_P1P0_DN<23>")
	)
	(segment
		(start 143.21155 -174.993554)
		(end 149.699218 -171.671996)
		(width 0.14732)
		(layer "In4.Cu")
		(net "UPI_CPU1_CPU0_P1P0_DN<23>")
	)
	(segment
		(start 132.537708 -183.933338)
		(end 136.723882 -178.315112)
		(width 0.14732)
		(layer "In4.Cu")
		(net "UPI_CPU1_CPU0_P1P0_DN<23>")
	)
	(segment
		(start 121.48312 -193.084958)
		(end 121.465594 -192.913508)
		(width 0.14732)
		(layer "In4.Cu")
		(net "UPI_CPU1_CPU0_P1P0_DN<23>")
	)
	(segment
		(start 112.646968 -212.7504)
		(end 112.547908 -212.65134)
		(width 0.0889)
		(layer "In4.Cu")
		(net "UPI_CPU1_CPU0_P1P0_DN<23>")
	)
	(segment
		(start 118.215664 -196.911722)
		(end 118.387114 -196.893942)
		(width 0.14732)
		(layer "In4.Cu")
		(net "UPI_CPU1_CPU0_P1P0_DN<23>")
	)
	(segment
		(start 118.920514 -196.044312)
		(end 119.092218 -196.026532)
		(width 0.14732)
		(layer "In4.Cu")
		(net "UPI_CPU1_CPU0_P1P0_DN<23>")
	)
	(segment
		(start 359.015284 -216.235026)
		(end 359.015284 -216.25052)
		(width 0.0889)
		(layer "In4.Cu")
		(net "UPI_CPU1_CPU0_P1P0_DN<23>")
	)
	(segment
		(start 120.330722 -194.309492)
		(end 120.502426 -194.291712)
		(width 0.14732)
		(layer "In4.Cu")
		(net "UPI_CPU1_CPU0_P1P0_DN<23>")
	)
	(segment
		(start 121.74093 -192.574672)
		(end 121.912634 -192.556892)
		(width 0.14732)
		(layer "In4.Cu")
		(net "UPI_CPU1_CPU0_P1P0_DN<23>")
	)
	(segment
		(start 149.699218 -171.671996)
		(end 155.61437 -170.15841)
		(width 0.14732)
		(layer "In4.Cu")
		(net "UPI_CPU1_CPU0_P1P0_DN<23>")
	)
	(segment
		(start 155.61437 -170.15841)
		(end 155.61437 -170.158156)
		(width 0.14732)
		(layer "In4.Cu")
		(net "UPI_CPU1_CPU0_P1P0_DN<23>")
	)
	(segment
		(start 200.408286 -169.413428)
		(end 210.780884 -169.868596)
		(width 0.14732)
		(layer "In4.Cu")
		(net "UPI_CPU1_CPU0_P1P0_DN<23>")
	)
	(segment
		(start 122.617738 -191.689482)
		(end 122.893328 -191.350138)
		(width 0.14732)
		(layer "In4.Cu")
		(net "UPI_CPU1_CPU0_P1P0_DN<23>")
	)
	(segment
		(start 120.502426 -194.291712)
		(end 120.778016 -193.952368)
		(width 0.14732)
		(layer "In4.Cu")
		(net "UPI_CPU1_CPU0_P1P0_DN<23>")
	)
	(segment
		(start 358.972612 -212.67166)
		(end 358.972866 -212.671914)
		(width 0.14732)
		(layer "In4.Cu")
		(net "UPI_CPU1_CPU0_P1P0_DN<23>")
	)
	(segment
		(start 210.780884 -169.868596)
		(end 238.595916 -169.868596)
		(width 0.14732)
		(layer "In4.Cu")
		(net "UPI_CPU1_CPU0_P1P0_DN<23>")
	)
	(segment
		(start 112.590072 -212.05063)
		(end 112.590072 -211.780374)
		(width 0.14732)
		(layer "In4.Cu")
		(net "UPI_CPU1_CPU0_P1P0_DN<23>")
	)
	(segment
		(start 112.547908 -213.69528)
		(end 112.646968 -213.59622)
		(width 0.0889)
		(layer "In4.Cu")
		(net "UPI_CPU1_CPU0_P1P0_DN<23>")
	)
	(segment
		(start 120.76049 -193.780918)
		(end 121.035826 -193.442082)
		(width 0.14732)
		(layer "In4.Cu")
		(net "UPI_CPU1_CPU0_P1P0_DN<23>")
	)
	(segment
		(start 359.306368 -215.755982)
		(end 359.297478 -215.761062)
		(width 0.0889)
		(layer "In4.Cu")
		(net "UPI_CPU1_CPU0_P1P0_DN<23>")
	)
	(segment
		(start 121.035826 -193.442082)
		(end 121.20753 -193.424302)
		(width 0.14732)
		(layer "In4.Cu")
		(net "UPI_CPU1_CPU0_P1P0_DN<23>")
	)
	(segment
		(start 119.350282 -195.515738)
		(end 119.625618 -195.176902)
		(width 0.14732)
		(layer "In4.Cu")
		(net "UPI_CPU1_CPU0_P1P0_DN<23>")
	)
	(segment
		(start 112.590072 -211.780374)
		(end 117.476524 -197.821042)
		(width 0.14732)
		(layer "In4.Cu")
		(net "UPI_CPU1_CPU0_P1P0_DN<23>")
	)
	(segment
		(start 112.205516 -216.260426)
		(end 112.205516 -216.241884)
		(width 0.0889)
		(layer "In4.Cu")
		(net "UPI_CPU1_CPU0_P1P0_DN<23>")
	)
	(segment
		(start 238.595916 -169.868596)
		(end 273.029426 -169.70375)
		(width 0.14732)
		(layer "In4.Cu")
		(net "UPI_CPU1_CPU0_P1P0_DN<23>")
	)
	(segment
		(start 112.547908 -213.02472)
		(end 112.646968 -212.92566)
		(width 0.0889)
		(layer "In4.Cu")
		(net "UPI_CPU1_CPU0_P1P0_DN<23>")
	)
	(segment
		(start 112.646968 -212.92566)
		(end 112.646968 -212.7504)
		(width 0.0889)
		(layer "In4.Cu")
		(net "UPI_CPU1_CPU0_P1P0_DN<23>")
	)
	(segment
		(start 359.014776 -213.03107)
		(end 359.014776 -214.636858)
		(width 0.0889)
		(layer "In4.Cu")
		(net "UPI_CPU1_CPU0_P1P0_DN<23>")
	)
	(segment
		(start 120.055386 -194.648328)
		(end 120.330722 -194.309492)
		(width 0.14732)
		(layer "In4.Cu")
		(net "UPI_CPU1_CPU0_P1P0_DN<23>")
	)
	(segment
		(start 120.778016 -193.952368)
		(end 120.76049 -193.780918)
		(width 0.14732)
		(layer "In4.Cu")
		(net "UPI_CPU1_CPU0_P1P0_DN<23>")
	)
	(segment
		(start 155.61437 -170.158156)
		(end 200.408286 -169.413428)
		(width 0.14732)
		(layer "In4.Cu")
		(net "UPI_CPU1_CPU0_P1P0_DN<23>")
	)
	(arc
		(start 112.205008 -214.44331)
		(mid 112.217227 -214.381879)
		(end 112.251998 -214.329772)
		(width 0.0889)
		(layer "In4.Cu")
		(net "UPI_CPU1_CPU0_P1P0_DN<23>")
	)
	(arc
		(start 112.389412 -214.907114)
		(mid 112.280287 -214.823311)
		(end 112.205262 -214.707978)
		(width 0.0889)
		(layer "In4.Cu")
		(net "UPI_CPU1_CPU0_P1P0_DN<23>")
	)
	(arc
		(start 112.44199 -214.140034)
		(mid 112.520421 -214.022276)
		(end 112.547908 -213.883494)
		(width 0.0889)
		(layer "In4.Cu")
		(net "UPI_CPU1_CPU0_P1P0_DN<23>")
	)
	(arc
		(start 358.827832 -216.574878)
		(mid 358.623497 -216.777483)
		(end 358.545384 -217.05443)
		(width 0.0889)
		(layer "In4.Cu")
		(net "UPI_CPU1_CPU0_P1P0_DN<23>")
	)
	(arc
		(start 111.923068 -216.739978)
		(mid 112.127403 -216.537373)
		(end 112.205516 -216.260426)
		(width 0.0889)
		(layer "In4.Cu")
		(net "UPI_CPU1_CPU0_P1P0_DN<23>")
	)
	(arc
		(start 112.205516 -216.241884)
		(mid 112.257786 -216.059519)
		(end 112.392714 -215.926162)
		(width 0.0889)
		(layer "In4.Cu")
		(net "UPI_CPU1_CPU0_P1P0_DN<23>")
	)
	(arc
		(start 359.014776 -214.636858)
		(mid 359.093995 -214.911543)
		(end 359.297478 -215.112346)
		(width 0.0889)
		(layer "In4.Cu")
		(net "UPI_CPU1_CPU0_P1P0_DN<23>")
	)
	(arc
		(start 111.735616 -217.064336)
		(mid 111.783295 -216.881436)
		(end 111.914178 -216.745058)
		(width 0.0889)
		(layer "In4.Cu")
		(net "UPI_CPU1_CPU0_P1P0_DN<23>")
	)
	(arc
		(start 112.34547 -218.170252)
		(mid 112.242325 -218.040227)
		(end 112.205516 -217.878406)
		(width 0.0889)
		(layer "In4.Cu")
		(net "UPI_CPU1_CPU0_P1P0_DN<23>")
	)
	(arc
		(start 112.392714 -215.926162)
		(mid 112.597049 -215.723557)
		(end 112.675162 -215.44661)
		(width 0.0889)
		(layer "In4.Cu")
		(net "UPI_CPU1_CPU0_P1P0_DN<23>")
	)
	(arc
		(start 358.545384 -217.082878)
		(mid 358.604534 -217.316965)
		(end 358.75595 -217.505026)
		(width 0.0889)
		(layer "In4.Cu")
		(net "UPI_CPU1_CPU0_P1P0_DN<23>")
	)
	(arc
		(start 112.205516 -217.864182)
		(mid 112.126375 -217.589559)
		(end 111.923068 -217.388694)
		(width 0.0889)
		(layer "In4.Cu")
		(net "UPI_CPU1_CPU0_P1P0_DN<23>")
	)
	(arc
		(start 111.914178 -217.383614)
		(mid 111.786924 -217.253648)
		(end 111.73587 -217.079068)
		(width 0.0889)
		(layer "In4.Cu")
		(net "UPI_CPU1_CPU0_P1P0_DN<23>")
	)
	(arc
		(start 358.75595 -217.505026)
		(mid 358.764396 -217.511711)
		(end 358.772968 -217.518234)
		(width 0.0889)
		(layer "In4.Cu")
		(net "UPI_CPU1_CPU0_P1P0_DN<23>")
	)
	(arc
		(start 359.015284 -216.25052)
		(mid 358.967605 -216.43342)
		(end 358.836722 -216.569798)
		(width 0.0889)
		(layer "In4.Cu")
		(net "UPI_CPU1_CPU0_P1P0_DN<23>")
	)
	(arc
		(start 111.73587 -217.079068)
		(mid 111.735673 -217.071703)
		(end 111.735616 -217.064336)
		(width 0.0889)
		(layer "In4.Cu")
		(net "UPI_CPU1_CPU0_P1P0_DN<23>")
	)
	(arc
		(start 359.297478 -215.761062)
		(mid 359.094655 -215.961293)
		(end 359.015284 -216.235026)
		(width 0.0889)
		(layer "In4.Cu")
		(net "UPI_CPU1_CPU0_P1P0_DN<23>")
	)
	(arc
		(start 359.308146 -215.118696)
		(mid 359.484579 -215.437794)
		(end 359.306368 -215.755982)
		(width 0.0889)
		(layer "In4.Cu")
		(net "UPI_CPU1_CPU0_P1P0_DN<23>")
	)
	(arc
		(start 112.675162 -215.238838)
		(mid 112.563698 -215.045917)
		(end 112.389412 -214.907114)
		(width 0.0889)
		(layer "In4.Cu")
		(net "UPI_CPU1_CPU0_P1P0_DN<23>")
	)
	(segment
		(start 113.050066 -217.06459)
		(end 113.049812 -217.064336)
		(width 0.13208)
		(layer "F.Cu")
		(net "UPI_CPU1_CPU0_P1P0_DN<22>")
	)
	(segment
		(start 358.170734 -219.228162)
		(end 358.170734 -218.692222)
		(width 0.13208)
		(layer "F.Cu")
		(net "UPI_CPU1_CPU0_P1P0_DN<22>")
	)
	(segment
		(start 113.050066 -217.600276)
		(end 113.050066 -217.06459)
		(width 0.13208)
		(layer "F.Cu")
		(net "UPI_CPU1_CPU0_P1P0_DN<22>")
	)
	(segment
		(start 358.453436 -215.926162)
		(end 358.444546 -215.931242)
		(width 0.0889)
		(layer "In4.Cu")
		(net "UPI_CPU1_CPU0_P1P0_DN<22>")
	)
	(segment
		(start 357.974646 -217.383614)
		(end 357.982774 -217.388186)
		(width 0.0889)
		(layer "In4.Cu")
		(net "UPI_CPU1_CPU0_P1P0_DN<22>")
	)
	(segment
		(start 113.369852 -211.585048)
		(end 113.369852 -211.249006)
		(width 0.14732)
		(layer "In4.Cu")
		(net "UPI_CPU1_CPU0_P1P0_DN<22>")
	)
	(segment
		(start 358.265984 -213.03107)
		(end 358.265984 -214.622634)
		(width 0.0889)
		(layer "In4.Cu")
		(net "UPI_CPU1_CPU0_P1P0_DN<22>")
	)
	(segment
		(start 113.369852 -211.249006)
		(end 117.843554 -198.47052)
		(width 0.14732)
		(layer "In4.Cu")
		(net "UPI_CPU1_CPU0_P1P0_DN<22>")
	)
	(segment
		(start 117.843554 -198.47052)
		(end 125.077982 -189.568582)
		(width 0.14732)
		(layer "In4.Cu")
		(net "UPI_CPU1_CPU0_P1P0_DN<22>")
	)
	(segment
		(start 113.23701 -215.761062)
		(end 113.2459 -215.755982)
		(width 0.0889)
		(layer "In4.Cu")
		(net "UPI_CPU1_CPU0_P1P0_DN<22>")
	)
	(segment
		(start 358.444546 -214.941912)
		(end 358.453436 -214.946992)
		(width 0.0889)
		(layer "In4.Cu")
		(net "UPI_CPU1_CPU0_P1P0_DN<22>")
	)
	(segment
		(start 113.424462 -215.436704)
		(end 113.424462 -215.414606)
		(width 0.0889)
		(layer "In4.Cu")
		(net "UPI_CPU1_CPU0_P1P0_DN<22>")
	)
	(segment
		(start 358.307894 -212.649562)
		(end 358.307894 -212.967062)
		(width 0.14732)
		(layer "In4.Cu")
		(net "UPI_CPU1_CPU0_P1P0_DN<22>")
	)
	(segment
		(start 357.983536 -216.739978)
		(end 357.982774 -216.740486)
		(width 0.0889)
		(layer "In4.Cu")
		(net "UPI_CPU1_CPU0_P1P0_DN<22>")
	)
	(segment
		(start 113.312956 -212.77834)
		(end 113.312956 -212.60308)
		(width 0.0889)
		(layer "In4.Cu")
		(net "UPI_CPU1_CPU0_P1P0_DN<22>")
	)
	(segment
		(start 358.307894 -212.98916)
		(end 358.265984 -213.03107)
		(width 0.0889)
		(layer "In4.Cu")
		(net "UPI_CPU1_CPU0_P1P0_DN<22>")
	)
	(segment
		(start 345.243912 -184.320434)
		(end 347.70314 -187.812934)
		(width 0.14732)
		(layer "In4.Cu")
		(net "UPI_CPU1_CPU0_P1P0_DN<22>")
	)
	(segment
		(start 314.046108 -169.784522)
		(end 319.218564 -171.229528)
		(width 0.14732)
		(layer "In4.Cu")
		(net "UPI_CPU1_CPU0_P1P0_DN<22>")
	)
	(segment
		(start 128.993392 -186.966098)
		(end 128.993392 -186.966352)
		(width 0.14732)
		(layer "In4.Cu")
		(net "UPI_CPU1_CPU0_P1P0_DN<22>")
	)
	(segment
		(start 358.265984 -217.859864)
		(end 358.265984 -217.888312)
		(width 0.0889)
		(layer "In4.Cu")
		(net "UPI_CPU1_CPU0_P1P0_DN<22>")
	)
	(segment
		(start 358.265984 -216.25052)
		(end 358.265984 -216.260426)
		(width 0.0889)
		(layer "In4.Cu")
		(net "UPI_CPU1_CPU0_P1P0_DN<22>")
	)
	(segment
		(start 113.312956 -213.209886)
		(end 113.412016 -213.110826)
		(width 0.0889)
		(layer "In4.Cu")
		(net "UPI_CPU1_CPU0_P1P0_DN<22>")
	)
	(segment
		(start 302.463962 -169.56913)
		(end 302.469804 -169.568876)
		(width 0.14732)
		(layer "In4.Cu")
		(net "UPI_CPU1_CPU0_P1P0_DN<22>")
	)
	(segment
		(start 354.172266 -194.442842)
		(end 358.30764 -204.427074)
		(width 0.14732)
		(layer "In4.Cu")
		(net "UPI_CPU1_CPU0_P1P0_DN<22>")
	)
	(segment
		(start 113.049812 -217.064336)
		(end 113.206276 -217.335354)
		(width 0.0889)
		(layer "In4.Cu")
		(net "UPI_CPU1_CPU0_P1P0_DN<22>")
	)
	(segment
		(start 357.980996 -216.741502)
		(end 357.980234 -216.74201)
		(width 0.0889)
		(layer "In4.Cu")
		(net "UPI_CPU1_CPU0_P1P0_DN<22>")
	)
	(segment
		(start 358.307894 -212.967062)
		(end 358.307894 -212.98916)
		(width 0.0889)
		(layer "In4.Cu")
		(net "UPI_CPU1_CPU0_P1P0_DN<22>")
	)
	(segment
		(start 358.01427 -218.421204)
		(end 358.170734 -218.692222)
		(width 0.0889)
		(layer "In4.Cu")
		(net "UPI_CPU1_CPU0_P1P0_DN<22>")
	)
	(segment
		(start 113.2459 -216.745058)
		(end 113.237772 -216.740486)
		(width 0.0889)
		(layer "In4.Cu")
		(net "UPI_CPU1_CPU0_P1P0_DN<22>")
	)
	(segment
		(start 357.980234 -216.74201)
		(end 357.974646 -216.745058)
		(width 0.0889)
		(layer "In4.Cu")
		(net "UPI_CPU1_CPU0_P1P0_DN<22>")
	)
	(segment
		(start 347.70314 -187.812934)
		(end 354.172266 -194.442842)
		(width 0.14732)
		(layer "In4.Cu")
		(net "UPI_CPU1_CPU0_P1P0_DN<22>")
	)
	(segment
		(start 137.07618 -178.770026)
		(end 149.829774 -172.238924)
		(width 0.14732)
		(layer "In4.Cu")
		(net "UPI_CPU1_CPU0_P1P0_DN<22>")
	)
	(segment
		(start 149.829774 -172.238924)
		(end 155.630118 -170.754802)
		(width 0.14732)
		(layer "In4.Cu")
		(net "UPI_CPU1_CPU0_P1P0_DN<22>")
	)
	(segment
		(start 125.077982 -189.568582)
		(end 128.993392 -186.966098)
		(width 0.14732)
		(layer "In4.Cu")
		(net "UPI_CPU1_CPU0_P1P0_DN<22>")
	)
	(segment
		(start 113.706656 -214.946992)
		(end 113.715546 -214.941912)
		(width 0.0889)
		(layer "In4.Cu")
		(net "UPI_CPU1_CPU0_P1P0_DN<22>")
	)
	(segment
		(start 358.0384 -218.33205)
		(end 358.01427 -218.421204)
		(width 0.0889)
		(layer "In4.Cu")
		(net "UPI_CPU1_CPU0_P1P0_DN<22>")
	)
	(segment
		(start 132.908548 -184.364122)
		(end 137.07618 -178.770026)
		(width 0.14732)
		(layer "In4.Cu")
		(net "UPI_CPU1_CPU0_P1P0_DN<22>")
	)
	(segment
		(start 302.469804 -169.568876)
		(end 302.475392 -169.568876)
		(width 0.14732)
		(layer "In4.Cu")
		(net "UPI_CPU1_CPU0_P1P0_DN<22>")
	)
	(segment
		(start 113.312956 -213.385146)
		(end 113.312956 -213.209886)
		(width 0.0889)
		(layer "In4.Cu")
		(net "UPI_CPU1_CPU0_P1P0_DN<22>")
	)
	(segment
		(start 331.812646 -175.66513)
		(end 339.02904 -178.785012)
		(width 0.14732)
		(layer "In4.Cu")
		(net "UPI_CPU1_CPU0_P1P0_DN<22>")
	)
	(segment
		(start 113.206276 -217.335354)
		(end 113.284508 -217.356182)
		(width 0.0889)
		(layer "In4.Cu")
		(net "UPI_CPU1_CPU0_P1P0_DN<22>")
	)
	(segment
		(start 211.275168 -170.450764)
		(end 238.59744 -170.450764)
		(width 0.14732)
		(layer "In4.Cu")
		(net "UPI_CPU1_CPU0_P1P0_DN<22>")
	)
	(segment
		(start 201.036936 -170.001438)
		(end 211.275168 -170.450764)
		(width 0.14732)
		(layer "In4.Cu")
		(net "UPI_CPU1_CPU0_P1P0_DN<22>")
	)
	(segment
		(start 358.30764 -212.649308)
		(end 358.307894 -212.649562)
		(width 0.14732)
		(layer "In4.Cu")
		(net "UPI_CPU1_CPU0_P1P0_DN<22>")
	)
	(segment
		(start 113.894616 -214.622126)
		(end 113.894616 -214.387176)
		(width 0.0889)
		(layer "In4.Cu")
		(net "UPI_CPU1_CPU0_P1P0_DN<22>")
	)
	(segment
		(start 113.370106 -211.585302)
		(end 113.369852 -211.585048)
		(width 0.14732)
		(layer "In4.Cu")
		(net "UPI_CPU1_CPU0_P1P0_DN<22>")
	)
	(segment
		(start 319.218564 -171.229528)
		(end 331.812646 -175.66513)
		(width 0.14732)
		(layer "In4.Cu")
		(net "UPI_CPU1_CPU0_P1P0_DN<22>")
	)
	(segment
		(start 341.146892 -180.223668)
		(end 345.243912 -184.320434)
		(width 0.14732)
		(layer "In4.Cu")
		(net "UPI_CPU1_CPU0_P1P0_DN<22>")
	)
	(segment
		(start 113.894616 -214.387176)
		(end 113.528856 -214.021416)
		(width 0.0889)
		(layer "In4.Cu")
		(net "UPI_CPU1_CPU0_P1P0_DN<22>")
	)
	(segment
		(start 358.73563 -215.414606)
		(end 358.73563 -215.452198)
		(width 0.0889)
		(layer "In4.Cu")
		(net "UPI_CPU1_CPU0_P1P0_DN<22>")
	)
	(segment
		(start 113.370106 -212.05063)
		(end 113.370106 -211.585302)
		(width 0.14732)
		(layer "In4.Cu")
		(net "UPI_CPU1_CPU0_P1P0_DN<22>")
	)
	(segment
		(start 113.312956 -212.60308)
		(end 113.412016 -212.50402)
		(width 0.0889)
		(layer "In4.Cu")
		(net "UPI_CPU1_CPU0_P1P0_DN<22>")
	)
	(segment
		(start 113.412016 -212.114638)
		(end 113.370106 -212.072728)
		(width 0.0889)
		(layer "In4.Cu")
		(net "UPI_CPU1_CPU0_P1P0_DN<22>")
	)
	(segment
		(start 128.993392 -186.966352)
		(end 132.908548 -184.364122)
		(width 0.14732)
		(layer "In4.Cu")
		(net "UPI_CPU1_CPU0_P1P0_DN<22>")
	)
	(segment
		(start 113.370106 -212.072728)
		(end 113.370106 -212.05063)
		(width 0.0889)
		(layer "In4.Cu")
		(net "UPI_CPU1_CPU0_P1P0_DN<22>")
	)
	(segment
		(start 113.894108 -214.622634)
		(end 113.894616 -214.622126)
		(width 0.0889)
		(layer "In4.Cu")
		(net "UPI_CPU1_CPU0_P1P0_DN<22>")
	)
	(segment
		(start 339.02904 -178.785012)
		(end 341.146892 -180.223668)
		(width 0.14732)
		(layer "In4.Cu")
		(net "UPI_CPU1_CPU0_P1P0_DN<22>")
	)
	(segment
		(start 357.982774 -216.740486)
		(end 357.980996 -216.741502)
		(width 0.0889)
		(layer "In4.Cu")
		(net "UPI_CPU1_CPU0_P1P0_DN<22>")
	)
	(segment
		(start 113.237772 -216.740486)
		(end 113.23701 -216.739978)
		(width 0.0889)
		(layer "In4.Cu")
		(net "UPI_CPU1_CPU0_P1P0_DN<22>")
	)
	(segment
		(start 273.037808 -170.285918)
		(end 302.463962 -169.56913)
		(width 0.14732)
		(layer "In4.Cu")
		(net "UPI_CPU1_CPU0_P1P0_DN<22>")
	)
	(segment
		(start 302.475646 -169.56913)
		(end 314.046108 -169.784522)
		(width 0.14732)
		(layer "In4.Cu")
		(net "UPI_CPU1_CPU0_P1P0_DN<22>")
	)
	(segment
		(start 357.982774 -217.388186)
		(end 357.983536 -217.388694)
		(width 0.0889)
		(layer "In4.Cu")
		(net "UPI_CPU1_CPU0_P1P0_DN<22>")
	)
	(segment
		(start 113.412016 -213.484206)
		(end 113.312956 -213.385146)
		(width 0.0889)
		(layer "In4.Cu")
		(net "UPI_CPU1_CPU0_P1P0_DN<22>")
	)
	(segment
		(start 112.954562 -216.260426)
		(end 112.954562 -216.240614)
		(width 0.0889)
		(layer "In4.Cu")
		(net "UPI_CPU1_CPU0_P1P0_DN<22>")
	)
	(segment
		(start 113.412016 -212.50402)
		(end 113.412016 -212.114638)
		(width 0.0889)
		(layer "In4.Cu")
		(net "UPI_CPU1_CPU0_P1P0_DN<22>")
	)
	(segment
		(start 113.412016 -213.739222)
		(end 113.412016 -213.484206)
		(width 0.0889)
		(layer "In4.Cu")
		(net "UPI_CPU1_CPU0_P1P0_DN<22>")
	)
	(segment
		(start 238.59744 -170.450764)
		(end 273.037808 -170.285918)
		(width 0.14732)
		(layer "In4.Cu")
		(net "UPI_CPU1_CPU0_P1P0_DN<22>")
	)
	(segment
		(start 302.475392 -169.568876)
		(end 302.475646 -169.56913)
		(width 0.14732)
		(layer "In4.Cu")
		(net "UPI_CPU1_CPU0_P1P0_DN<22>")
	)
	(segment
		(start 113.412016 -212.8774)
		(end 113.312956 -212.77834)
		(width 0.0889)
		(layer "In4.Cu")
		(net "UPI_CPU1_CPU0_P1P0_DN<22>")
	)
	(segment
		(start 113.412016 -213.110826)
		(end 113.412016 -212.8774)
		(width 0.0889)
		(layer "In4.Cu")
		(net "UPI_CPU1_CPU0_P1P0_DN<22>")
	)
	(segment
		(start 155.630118 -170.754802)
		(end 201.036936 -170.001438)
		(width 0.14732)
		(layer "In4.Cu")
		(net "UPI_CPU1_CPU0_P1P0_DN<22>")
	)
	(segment
		(start 358.30764 -204.427074)
		(end 358.30764 -212.649308)
		(width 0.14732)
		(layer "In4.Cu")
		(net "UPI_CPU1_CPU0_P1P0_DN<22>")
	)
	(arc
		(start 113.715546 -214.941912)
		(mid 113.84646 -214.805552)
		(end 113.894108 -214.622634)
		(width 0.0889)
		(layer "In4.Cu")
		(net "UPI_CPU1_CPU0_P1P0_DN<22>")
	)
	(arc
		(start 358.265984 -214.622634)
		(mid 358.313663 -214.805534)
		(end 358.444546 -214.941912)
		(width 0.0889)
		(layer "In4.Cu")
		(net "UPI_CPU1_CPU0_P1P0_DN<22>")
	)
	(arc
		(start 358.73563 -215.452198)
		(mid 358.65626 -215.725932)
		(end 358.453436 -215.926162)
		(width 0.0889)
		(layer "In4.Cu")
		(net "UPI_CPU1_CPU0_P1P0_DN<22>")
	)
	(arc
		(start 113.424462 -215.414606)
		(mid 113.505373 -215.144478)
		(end 113.706656 -214.946992)
		(width 0.0889)
		(layer "In4.Cu")
		(net "UPI_CPU1_CPU0_P1P0_DN<22>")
	)
	(arc
		(start 113.23701 -216.739978)
		(mid 113.032675 -216.537373)
		(end 112.954562 -216.260426)
		(width 0.0889)
		(layer "In4.Cu")
		(net "UPI_CPU1_CPU0_P1P0_DN<22>")
	)
	(arc
		(start 358.055164 -218.319096)
		(mid 358.046842 -218.32565)
		(end 358.0384 -218.33205)
		(width 0.0889)
		(layer "In4.Cu")
		(net "UPI_CPU1_CPU0_P1P0_DN<22>")
	)
	(arc
		(start 358.265984 -217.888312)
		(mid 358.208511 -218.127159)
		(end 358.055164 -218.319096)
		(width 0.0889)
		(layer "In4.Cu")
		(net "UPI_CPU1_CPU0_P1P0_DN<22>")
	)
	(arc
		(start 112.954562 -216.240614)
		(mid 113.032673 -215.963665)
		(end 113.23701 -215.761062)
		(width 0.0889)
		(layer "In4.Cu")
		(net "UPI_CPU1_CPU0_P1P0_DN<22>")
	)
	(arc
		(start 358.453436 -214.946992)
		(mid 358.654718 -215.144479)
		(end 358.73563 -215.414606)
		(width 0.0889)
		(layer "In4.Cu")
		(net "UPI_CPU1_CPU0_P1P0_DN<22>")
	)
	(arc
		(start 358.265984 -216.260426)
		(mid 358.187873 -216.537375)
		(end 357.983536 -216.739978)
		(width 0.0889)
		(layer "In4.Cu")
		(net "UPI_CPU1_CPU0_P1P0_DN<22>")
	)
	(arc
		(start 113.284508 -217.356182)
		(mid 113.387653 -217.226157)
		(end 113.424462 -217.064336)
		(width 0.0889)
		(layer "In4.Cu")
		(net "UPI_CPU1_CPU0_P1P0_DN<22>")
	)
	(arc
		(start 358.444546 -215.931242)
		(mid 358.313632 -216.067602)
		(end 358.265984 -216.25052)
		(width 0.0889)
		(layer "In4.Cu")
		(net "UPI_CPU1_CPU0_P1P0_DN<22>")
	)
	(arc
		(start 357.974646 -216.745058)
		(mid 357.796049 -217.064336)
		(end 357.974646 -217.383614)
		(width 0.0889)
		(layer "In4.Cu")
		(net "UPI_CPU1_CPU0_P1P0_DN<22>")
	)
	(arc
		(start 113.528856 -214.021416)
		(mid 113.442346 -213.891944)
		(end 113.412016 -213.739222)
		(width 0.0889)
		(layer "In4.Cu")
		(net "UPI_CPU1_CPU0_P1P0_DN<22>")
	)
	(arc
		(start 113.2459 -215.755982)
		(mid 113.376814 -215.619622)
		(end 113.424462 -215.436704)
		(width 0.0889)
		(layer "In4.Cu")
		(net "UPI_CPU1_CPU0_P1P0_DN<22>")
	)
	(arc
		(start 113.424462 -217.064336)
		(mid 113.376783 -216.881436)
		(end 113.2459 -216.745058)
		(width 0.0889)
		(layer "In4.Cu")
		(net "UPI_CPU1_CPU0_P1P0_DN<22>")
	)
	(arc
		(start 357.983536 -217.388694)
		(mid 358.185822 -217.587675)
		(end 358.265984 -217.859864)
		(width 0.0889)
		(layer "In4.Cu")
		(net "UPI_CPU1_CPU0_P1P0_DN<22>")
	)
	(segment
		(start 356.76078 -217.87866)
		(end 356.761034 -217.878406)
		(width 0.13208)
		(layer "F.Cu")
		(net "UPI_CPU1_CPU0_P1P0_DN<21>")
	)
	(segment
		(start 356.76078 -218.414346)
		(end 356.76078 -217.87866)
		(width 0.13208)
		(layer "F.Cu")
		(net "UPI_CPU1_CPU0_P1P0_DN<21>")
	)
	(segment
		(start 114.459766 -217.878406)
		(end 114.459766 -218.414346)
		(width 0.13208)
		(layer "F.Cu")
		(net "UPI_CPU1_CPU0_P1P0_DN<21>")
	)
	(segment
		(start 120.404382 -197.287388)
		(end 120.679718 -196.948806)
		(width 0.14732)
		(layer "In4.Cu")
		(net "UPI_CPU1_CPU0_P1P0_DN<21>")
	)
	(segment
		(start 114.459766 -217.878406)
		(end 114.303302 -218.149424)
		(width 0.0889)
		(layer "In4.Cu")
		(net "UPI_CPU1_CPU0_P1P0_DN<21>")
	)
	(segment
		(start 114.733324 -215.117426)
		(end 114.742214 -215.112346)
		(width 0.0889)
		(layer "In4.Cu")
		(net "UPI_CPU1_CPU0_P1P0_DN<21>")
	)
	(segment
		(start 114.596672 -211.585048)
		(end 114.596672 -211.134706)
		(width 0.14732)
		(layer "In4.Cu")
		(net "UPI_CPU1_CPU0_P1P0_DN<21>")
	)
	(segment
		(start 120.421908 -197.458584)
		(end 120.404128 -197.287134)
		(width 0.14732)
		(layer "In4.Cu")
		(net "UPI_CPU1_CPU0_P1P0_DN<21>")
	)
	(segment
		(start 357.09352 -213.136988)
		(end 357.13543 -213.178898)
		(width 0.0889)
		(layer "In4.Cu")
		(net "UPI_CPU1_CPU0_P1P0_DN<21>")
	)
	(segment
		(start 356.945438 -216.576402)
		(end 356.942136 -216.578434)
		(width 0.0889)
		(layer "In4.Cu")
		(net "UPI_CPU1_CPU0_P1P0_DN<21>")
	)
	(segment
		(start 356.956614 -214.941912)
		(end 356.947724 -214.946992)
		(width 0.0889)
		(layer "In4.Cu")
		(net "UPI_CPU1_CPU0_P1P0_DN<21>")
	)
	(segment
		(start 114.263678 -215.931242)
		(end 114.271552 -215.92667)
		(width 0.0889)
		(layer "In4.Cu")
		(net "UPI_CPU1_CPU0_P1P0_DN<21>")
	)
	(segment
		(start 114.554762 -213.01964)
		(end 114.653822 -212.92058)
		(width 0.0889)
		(layer "In4.Cu")
		(net "UPI_CPU1_CPU0_P1P0_DN<21>")
	)
	(segment
		(start 121.814336 -195.552314)
		(end 122.109738 -195.18884)
		(width 0.14732)
		(layer "In4.Cu")
		(net "UPI_CPU1_CPU0_P1P0_DN<21>")
	)
	(segment
		(start 120.851168 -196.930518)
		(end 121.127012 -196.591174)
		(width 0.14732)
		(layer "In4.Cu")
		(net "UPI_CPU1_CPU0_P1P0_DN<21>")
	)
	(segment
		(start 120.679718 -196.948806)
		(end 120.679464 -196.948298)
		(width 0.14732)
		(layer "In4.Cu")
		(net "UPI_CPU1_CPU0_P1P0_DN<21>")
	)
	(segment
		(start 122.539252 -194.66052)
		(end 122.814588 -194.321684)
		(width 0.14732)
		(layer "In4.Cu")
		(net "UPI_CPU1_CPU0_P1P0_DN<21>")
	)
	(segment
		(start 122.109738 -195.18884)
		(end 122.281188 -195.171314)
		(width 0.14732)
		(layer "In4.Cu")
		(net "UPI_CPU1_CPU0_P1P0_DN<21>")
	)
	(segment
		(start 356.949756 -216.574116)
		(end 356.948232 -216.574878)
		(width 0.0889)
		(layer "In4.Cu")
		(net "UPI_CPU1_CPU0_P1P0_DN<21>")
	)
	(segment
		(start 137.795254 -179.650898)
		(end 150.010622 -173.395894)
		(width 0.14732)
		(layer "In4.Cu")
		(net "UPI_CPU1_CPU0_P1P0_DN<21>")
	)
	(segment
		(start 356.893368 -217.518234)
		(end 356.917498 -217.607388)
		(width 0.0889)
		(layer "In4.Cu")
		(net "UPI_CPU1_CPU0_P1P0_DN<21>")
	)
	(segment
		(start 123.519692 -193.454274)
		(end 123.691396 -193.436494)
		(width 0.14732)
		(layer "In4.Cu")
		(net "UPI_CPU1_CPU0_P1P0_DN<21>")
	)
	(segment
		(start 123.966986 -193.09715)
		(end 123.94946 -192.9257)
		(width 0.14732)
		(layer "In4.Cu")
		(net "UPI_CPU1_CPU0_P1P0_DN<21>")
	)
	(segment
		(start 114.303302 -218.149424)
		(end 114.22507 -218.170252)
		(width 0.0889)
		(layer "In4.Cu")
		(net "UPI_CPU1_CPU0_P1P0_DN<21>")
	)
	(segment
		(start 122.557032 -194.83197)
		(end 122.539252 -194.66052)
		(width 0.14732)
		(layer "In4.Cu")
		(net "UPI_CPU1_CPU0_P1P0_DN<21>")
	)
	(segment
		(start 114.554762 -213.56828)
		(end 114.653822 -213.46922)
		(width 0.0889)
		(layer "In4.Cu")
		(net "UPI_CPU1_CPU0_P1P0_DN<21>")
	)
	(segment
		(start 211.489544 -171.588684)
		(end 238.600488 -171.588684)
		(width 0.14732)
		(layer "In4.Cu")
		(net "UPI_CPU1_CPU0_P1P0_DN<21>")
	)
	(segment
		(start 122.814588 -194.321684)
		(end 122.986292 -194.303904)
		(width 0.14732)
		(layer "In4.Cu")
		(net "UPI_CPU1_CPU0_P1P0_DN<21>")
	)
	(segment
		(start 356.957122 -216.569798)
		(end 356.949756 -216.574116)
		(width 0.0889)
		(layer "In4.Cu")
		(net "UPI_CPU1_CPU0_P1P0_DN<21>")
	)
	(segment
		(start 357.13543 -213.178898)
		(end 357.13543 -214.640414)
		(width 0.0889)
		(layer "In4.Cu")
		(net "UPI_CPU1_CPU0_P1P0_DN<21>")
	)
	(segment
		(start 273.054572 -171.423838)
		(end 302.473106 -170.707558)
		(width 0.14732)
		(layer "In4.Cu")
		(net "UPI_CPU1_CPU0_P1P0_DN<21>")
	)
	(segment
		(start 114.271552 -215.92667)
		(end 114.272568 -215.926162)
		(width 0.0889)
		(layer "In4.Cu")
		(net "UPI_CPU1_CPU0_P1P0_DN<21>")
	)
	(segment
		(start 114.554762 -212.114892)
		(end 114.596926 -212.072728)
		(width 0.0889)
		(layer "In4.Cu")
		(net "UPI_CPU1_CPU0_P1P0_DN<21>")
	)
	(segment
		(start 156.017214 -171.85894)
		(end 200.732644 -171.116752)
		(width 0.14732)
		(layer "In4.Cu")
		(net "UPI_CPU1_CPU0_P1P0_DN<21>")
	)
	(segment
		(start 114.272568 -216.574878)
		(end 114.263678 -216.569798)
		(width 0.0889)
		(layer "In4.Cu")
		(net "UPI_CPU1_CPU0_P1P0_DN<21>")
	)
	(segment
		(start 114.554762 -215.452198)
		(end 114.554762 -215.436704)
		(width 0.0889)
		(layer "In4.Cu")
		(net "UPI_CPU1_CPU0_P1P0_DN<21>")
	)
	(segment
		(start 331.369162 -176.69383)
		(end 338.448142 -179.742338)
		(width 0.14732)
		(layer "In4.Cu")
		(net "UPI_CPU1_CPU0_P1P0_DN<21>")
	)
	(segment
		(start 114.596926 -211.585302)
		(end 114.596672 -211.585048)
		(width 0.14732)
		(layer "In4.Cu")
		(net "UPI_CPU1_CPU0_P1P0_DN<21>")
	)
	(segment
		(start 123.261882 -193.96456)
		(end 123.244356 -193.79311)
		(width 0.14732)
		(layer "In4.Cu")
		(net "UPI_CPU1_CPU0_P1P0_DN<21>")
	)
	(segment
		(start 340.447376 -181.098444)
		(end 344.381836 -185.032904)
		(width 0.14732)
		(layer "In4.Cu")
		(net "UPI_CPU1_CPU0_P1P0_DN<21>")
	)
	(segment
		(start 120.404128 -197.287134)
		(end 120.404382 -197.287388)
		(width 0.14732)
		(layer "In4.Cu")
		(net "UPI_CPU1_CPU0_P1P0_DN<21>")
	)
	(segment
		(start 133.6675 -185.191654)
		(end 137.795254 -179.650898)
		(width 0.14732)
		(layer "In4.Cu")
		(net "UPI_CPU1_CPU0_P1P0_DN<21>")
	)
	(segment
		(start 114.554762 -212.64626)
		(end 114.554762 -212.114892)
		(width 0.0889)
		(layer "In4.Cu")
		(net "UPI_CPU1_CPU0_P1P0_DN<21>")
	)
	(segment
		(start 119.974614 -197.815708)
		(end 120.146064 -197.797928)
		(width 0.14732)
		(layer "In4.Cu")
		(net "UPI_CPU1_CPU0_P1P0_DN<21>")
	)
	(segment
		(start 123.94946 -192.9257)
		(end 126.202948 -190.153036)
		(width 0.14732)
		(layer "In4.Cu")
		(net "UPI_CPU1_CPU0_P1P0_DN<21>")
	)
	(segment
		(start 123.244356 -193.79311)
		(end 123.519692 -193.454274)
		(width 0.14732)
		(layer "In4.Cu")
		(net "UPI_CPU1_CPU0_P1P0_DN<21>")
	)
	(segment
		(start 114.554762 -213.96452)
		(end 114.554762 -213.56828)
		(width 0.0889)
		(layer "In4.Cu")
		(net "UPI_CPU1_CPU0_P1P0_DN<21>")
	)
	(segment
		(start 356.94747 -215.925654)
		(end 356.957122 -215.931242)
		(width 0.0889)
		(layer "In4.Cu")
		(net "UPI_CPU1_CPU0_P1P0_DN<21>")
	)
	(segment
		(start 302.473106 -170.707558)
		(end 313.77255 -170.91787)
		(width 0.14732)
		(layer "In4.Cu")
		(net "UPI_CPU1_CPU0_P1P0_DN<21>")
	)
	(segment
		(start 200.732644 -171.116752)
		(end 211.489544 -171.588684)
		(width 0.14732)
		(layer "In4.Cu")
		(net "UPI_CPU1_CPU0_P1P0_DN<21>")
	)
	(segment
		(start 114.596926 -212.072728)
		(end 114.596926 -212.05063)
		(width 0.0889)
		(layer "In4.Cu")
		(net "UPI_CPU1_CPU0_P1P0_DN<21>")
	)
	(segment
		(start 238.600488 -171.588684)
		(end 273.054572 -171.423838)
		(width 0.14732)
		(layer "In4.Cu")
		(net "UPI_CPU1_CPU0_P1P0_DN<21>")
	)
	(segment
		(start 357.09352 -212.867748)
		(end 357.09352 -213.11489)
		(width 0.14732)
		(layer "In4.Cu")
		(net "UPI_CPU1_CPU0_P1P0_DN<21>")
	)
	(segment
		(start 357.09352 -213.11489)
		(end 357.09352 -213.136988)
		(width 0.0889)
		(layer "In4.Cu")
		(net "UPI_CPU1_CPU0_P1P0_DN<21>")
	)
	(segment
		(start 114.263678 -217.559128)
		(end 114.272568 -217.554048)
		(width 0.0889)
		(layer "In4.Cu")
		(net "UPI_CPU1_CPU0_P1P0_DN<21>")
	)
	(segment
		(start 123.691396 -193.436494)
		(end 123.966986 -193.09715)
		(width 0.14732)
		(layer "In4.Cu")
		(net "UPI_CPU1_CPU0_P1P0_DN<21>")
	)
	(segment
		(start 356.957122 -214.942166)
		(end 356.956614 -214.941912)
		(width 0.0889)
		(layer "In4.Cu")
		(net "UPI_CPU1_CPU0_P1P0_DN<21>")
	)
	(segment
		(start 357.093012 -212.86724)
		(end 357.09352 -212.867748)
		(width 0.14732)
		(layer "In4.Cu")
		(net "UPI_CPU1_CPU0_P1P0_DN<21>")
	)
	(segment
		(start 313.77255 -170.91787)
		(end 318.854328 -172.337476)
		(width 0.14732)
		(layer "In4.Cu")
		(net "UPI_CPU1_CPU0_P1P0_DN<21>")
	)
	(segment
		(start 114.596672 -211.134706)
		(end 118.718076 -199.361552)
		(width 0.14732)
		(layer "In4.Cu")
		(net "UPI_CPU1_CPU0_P1P0_DN<21>")
	)
	(segment
		(start 156.017214 -171.859194)
		(end 156.017214 -171.85894)
		(width 0.14732)
		(layer "In4.Cu")
		(net "UPI_CPU1_CPU0_P1P0_DN<21>")
	)
	(segment
		(start 357.093012 -204.38745)
		(end 357.093012 -212.86724)
		(width 0.14732)
		(layer "In4.Cu")
		(net "UPI_CPU1_CPU0_P1P0_DN<21>")
	)
	(segment
		(start 346.807282 -188.477144)
		(end 353.228148 -195.057014)
		(width 0.14732)
		(layer "In4.Cu")
		(net "UPI_CPU1_CPU0_P1P0_DN<21>")
	)
	(segment
		(start 120.146064 -197.797928)
		(end 120.421908 -197.458584)
		(width 0.14732)
		(layer "In4.Cu")
		(net "UPI_CPU1_CPU0_P1P0_DN<21>")
	)
	(segment
		(start 122.986292 -194.303904)
		(end 123.261882 -193.96456)
		(width 0.14732)
		(layer "In4.Cu")
		(net "UPI_CPU1_CPU0_P1P0_DN<21>")
	)
	(segment
		(start 121.556272 -196.063108)
		(end 121.831862 -195.723764)
		(width 0.14732)
		(layer "In4.Cu")
		(net "UPI_CPU1_CPU0_P1P0_DN<21>")
	)
	(segment
		(start 353.228148 -195.057014)
		(end 357.093012 -204.38745)
		(width 0.14732)
		(layer "In4.Cu")
		(net "UPI_CPU1_CPU0_P1P0_DN<21>")
	)
	(segment
		(start 114.653822 -213.29396)
		(end 114.554762 -213.1949)
		(width 0.0889)
		(layer "In4.Cu")
		(net "UPI_CPU1_CPU0_P1P0_DN<21>")
	)
	(segment
		(start 114.653822 -212.92058)
		(end 114.653822 -212.74532)
		(width 0.0889)
		(layer "In4.Cu")
		(net "UPI_CPU1_CPU0_P1P0_DN<21>")
	)
	(segment
		(start 115.024662 -214.610188)
		(end 115.024154 -214.60968)
		(width 0.0889)
		(layer "In4.Cu")
		(net "UPI_CPU1_CPU0_P1P0_DN<21>")
	)
	(segment
		(start 122.281188 -195.171314)
		(end 122.557032 -194.83197)
		(width 0.14732)
		(layer "In4.Cu")
		(net "UPI_CPU1_CPU0_P1P0_DN<21>")
	)
	(segment
		(start 356.917498 -217.607388)
		(end 356.761034 -217.878406)
		(width 0.0889)
		(layer "In4.Cu")
		(net "UPI_CPU1_CPU0_P1P0_DN<21>")
	)
	(segment
		(start 115.024662 -214.641176)
		(end 115.024662 -214.610188)
		(width 0.0889)
		(layer "In4.Cu")
		(net "UPI_CPU1_CPU0_P1P0_DN<21>")
	)
	(segment
		(start 318.854328 -172.337476)
		(end 331.369162 -176.69383)
		(width 0.14732)
		(layer "In4.Cu")
		(net "UPI_CPU1_CPU0_P1P0_DN<21>")
	)
	(segment
		(start 356.948232 -216.574878)
		(end 356.945438 -216.576402)
		(width 0.0889)
		(layer "In4.Cu")
		(net "UPI_CPU1_CPU0_P1P0_DN<21>")
	)
	(segment
		(start 114.653822 -212.74532)
		(end 114.554762 -212.64626)
		(width 0.0889)
		(layer "In4.Cu")
		(net "UPI_CPU1_CPU0_P1P0_DN<21>")
	)
	(segment
		(start 344.381836 -185.032904)
		(end 346.807282 -188.477144)
		(width 0.14732)
		(layer "In4.Cu")
		(net "UPI_CPU1_CPU0_P1P0_DN<21>")
	)
	(segment
		(start 121.127012 -196.591174)
		(end 121.109232 -196.419724)
		(width 0.14732)
		(layer "In4.Cu")
		(net "UPI_CPU1_CPU0_P1P0_DN<21>")
	)
	(segment
		(start 126.202948 -190.153036)
		(end 133.6675 -185.191654)
		(width 0.14732)
		(layer "In4.Cu")
		(net "UPI_CPU1_CPU0_P1P0_DN<21>")
	)
	(segment
		(start 356.66553 -217.064336)
		(end 356.66553 -217.07856)
		(width 0.0889)
		(layer "In4.Cu")
		(net "UPI_CPU1_CPU0_P1P0_DN<21>")
	)
	(segment
		(start 121.384568 -196.080888)
		(end 121.556272 -196.063108)
		(width 0.14732)
		(layer "In4.Cu")
		(net "UPI_CPU1_CPU0_P1P0_DN<21>")
	)
	(segment
		(start 114.555016 -217.082878)
		(end 114.555016 -217.05443)
		(width 0.0889)
		(layer "In4.Cu")
		(net "UPI_CPU1_CPU0_P1P0_DN<21>")
	)
	(segment
		(start 114.554762 -213.1949)
		(end 114.554762 -213.01964)
		(width 0.0889)
		(layer "In4.Cu")
		(net "UPI_CPU1_CPU0_P1P0_DN<21>")
	)
	(segment
		(start 114.664236 -214.07374)
		(end 114.554762 -213.96452)
		(width 0.0889)
		(layer "In4.Cu")
		(net "UPI_CPU1_CPU0_P1P0_DN<21>")
	)
	(segment
		(start 150.010622 -173.395894)
		(end 156.017214 -171.859194)
		(width 0.14732)
		(layer "In4.Cu")
		(net "UPI_CPU1_CPU0_P1P0_DN<21>")
	)
	(segment
		(start 121.831862 -195.723764)
		(end 121.814336 -195.552314)
		(width 0.14732)
		(layer "In4.Cu")
		(net "UPI_CPU1_CPU0_P1P0_DN<21>")
	)
	(segment
		(start 121.109232 -196.419724)
		(end 121.384568 -196.080888)
		(width 0.14732)
		(layer "In4.Cu")
		(net "UPI_CPU1_CPU0_P1P0_DN<21>")
	)
	(segment
		(start 114.596926 -212.05063)
		(end 114.596926 -211.585302)
		(width 0.14732)
		(layer "In4.Cu")
		(net "UPI_CPU1_CPU0_P1P0_DN<21>")
	)
	(segment
		(start 118.718076 -199.361552)
		(end 119.974614 -197.815708)
		(width 0.14732)
		(layer "In4.Cu")
		(net "UPI_CPU1_CPU0_P1P0_DN<21>")
	)
	(segment
		(start 356.942136 -215.922606)
		(end 356.94747 -215.925654)
		(width 0.0889)
		(layer "In4.Cu")
		(net "UPI_CPU1_CPU0_P1P0_DN<21>")
	)
	(segment
		(start 338.448142 -179.742338)
		(end 340.447376 -181.098444)
		(width 0.14732)
		(layer "In4.Cu")
		(net "UPI_CPU1_CPU0_P1P0_DN<21>")
	)
	(segment
		(start 120.679464 -196.948298)
		(end 120.851168 -196.930518)
		(width 0.14732)
		(layer "In4.Cu")
		(net "UPI_CPU1_CPU0_P1P0_DN<21>")
	)
	(segment
		(start 114.653822 -213.46922)
		(end 114.653822 -213.29396)
		(width 0.0889)
		(layer "In4.Cu")
		(net "UPI_CPU1_CPU0_P1P0_DN<21>")
	)
	(arc
		(start 114.263678 -216.569798)
		(mid 114.085081 -216.25052)
		(end 114.263678 -215.931242)
		(width 0.0889)
		(layer "In4.Cu")
		(net "UPI_CPU1_CPU0_P1P0_DN<21>")
	)
	(arc
		(start 356.66553 -217.07856)
		(mid 356.723824 -217.315203)
		(end 356.87635 -217.50528)
		(width 0.0889)
		(layer "In4.Cu")
		(net "UPI_CPU1_CPU0_P1P0_DN<21>")
	)
	(arc
		(start 114.742214 -215.112346)
		(mid 114.9445 -214.913365)
		(end 115.024662 -214.641176)
		(width 0.0889)
		(layer "In4.Cu")
		(net "UPI_CPU1_CPU0_P1P0_DN<21>")
	)
	(arc
		(start 114.272568 -217.554048)
		(mid 114.474854 -217.355067)
		(end 114.555016 -217.082878)
		(width 0.0889)
		(layer "In4.Cu")
		(net "UPI_CPU1_CPU0_P1P0_DN<21>")
	)
	(arc
		(start 114.555016 -217.05443)
		(mid 114.476905 -216.777481)
		(end 114.272568 -216.574878)
		(width 0.0889)
		(layer "In4.Cu")
		(net "UPI_CPU1_CPU0_P1P0_DN<21>")
	)
	(arc
		(start 357.13543 -214.640414)
		(mid 357.083642 -214.813363)
		(end 356.957122 -214.942166)
		(width 0.0889)
		(layer "In4.Cu")
		(net "UPI_CPU1_CPU0_P1P0_DN<21>")
	)
	(arc
		(start 115.024154 -214.60968)
		(mid 114.945309 -214.334555)
		(end 114.741706 -214.13343)
		(width 0.0889)
		(layer "In4.Cu")
		(net "UPI_CPU1_CPU0_P1P0_DN<21>")
	)
	(arc
		(start 114.22507 -218.170252)
		(mid 114.121925 -218.040227)
		(end 114.085116 -217.878406)
		(width 0.0889)
		(layer "In4.Cu")
		(net "UPI_CPU1_CPU0_P1P0_DN<21>")
	)
	(arc
		(start 114.554762 -215.436704)
		(mid 114.602441 -215.253804)
		(end 114.733324 -215.117426)
		(width 0.0889)
		(layer "In4.Cu")
		(net "UPI_CPU1_CPU0_P1P0_DN<21>")
	)
	(arc
		(start 356.942136 -216.578434)
		(mid 356.739549 -216.784785)
		(end 356.66553 -217.064336)
		(width 0.0889)
		(layer "In4.Cu")
		(net "UPI_CPU1_CPU0_P1P0_DN<21>")
	)
	(arc
		(start 114.085116 -217.878406)
		(mid 114.132795 -217.695506)
		(end 114.263678 -217.559128)
		(width 0.0889)
		(layer "In4.Cu")
		(net "UPI_CPU1_CPU0_P1P0_DN<21>")
	)
	(arc
		(start 356.87635 -217.50528)
		(mid 356.884798 -217.511837)
		(end 356.893368 -217.518234)
		(width 0.0889)
		(layer "In4.Cu")
		(net "UPI_CPU1_CPU0_P1P0_DN<21>")
	)
	(arc
		(start 356.957122 -215.931242)
		(mid 357.135719 -216.25052)
		(end 356.957122 -216.569798)
		(width 0.0889)
		(layer "In4.Cu")
		(net "UPI_CPU1_CPU0_P1P0_DN<21>")
	)
	(arc
		(start 114.272568 -215.926162)
		(mid 114.475391 -215.725931)
		(end 114.554762 -215.452198)
		(width 0.0889)
		(layer "In4.Cu")
		(net "UPI_CPU1_CPU0_P1P0_DN<21>")
	)
	(arc
		(start 356.947724 -214.946992)
		(mid 356.665201 -215.433205)
		(end 356.942136 -215.922606)
		(width 0.0889)
		(layer "In4.Cu")
		(net "UPI_CPU1_CPU0_P1P0_DN<21>")
	)
	(arc
		(start 114.741706 -214.13343)
		(mid 114.701019 -214.106119)
		(end 114.664236 -214.07374)
		(width 0.0889)
		(layer "In4.Cu")
		(net "UPI_CPU1_CPU0_P1P0_DN<21>")
	)
	(segment
		(start 114.929666 -217.600276)
		(end 114.929666 -217.06459)
		(width 0.13208)
		(layer "F.Cu")
		(net "UPI_CPU1_CPU0_P1P0_DN<20>")
	)
	(segment
		(start 356.291134 -218.692476)
		(end 356.29088 -218.692222)
		(width 0.13208)
		(layer "F.Cu")
		(net "UPI_CPU1_CPU0_P1P0_DN<20>")
	)
	(segment
		(start 114.929666 -217.06459)
		(end 114.929412 -217.064336)
		(width 0.13208)
		(layer "F.Cu")
		(net "UPI_CPU1_CPU0_P1P0_DN<20>")
	)
	(segment
		(start 356.291134 -219.228162)
		(end 356.291134 -218.692476)
		(width 0.13208)
		(layer "F.Cu")
		(net "UPI_CPU1_CPU0_P1P0_DN<20>")
	)
	(segment
		(start 356.103174 -216.740486)
		(end 356.098094 -216.74328)
		(width 0.0889)
		(layer "In4.Cu")
		(net "UPI_CPU1_CPU0_P1P0_DN<20>")
	)
	(segment
		(start 115.11661 -215.761062)
		(end 115.1255 -215.755982)
		(width 0.0889)
		(layer "In4.Cu")
		(net "UPI_CPU1_CPU0_P1P0_DN<20>")
	)
	(segment
		(start 356.386384 -216.25052)
		(end 356.386384 -216.260426)
		(width 0.0889)
		(layer "In4.Cu")
		(net "UPI_CPU1_CPU0_P1P0_DN<20>")
	)
	(segment
		(start 149.880828 -174.103538)
		(end 156.453078 -172.422058)
		(width 0.14732)
		(layer "In4.Cu")
		(net "UPI_CPU1_CPU0_P1P0_DN<20>")
	)
	(segment
		(start 355.91623 -213.8934)
		(end 355.916484 -213.893908)
		(width 0.0889)
		(layer "In4.Cu")
		(net "UPI_CPU1_CPU0_P1P0_DN<20>")
	)
	(segment
		(start 330.938378 -177.166016)
		(end 338.194904 -180.254148)
		(width 0.14732)
		(layer "In4.Cu")
		(net "UPI_CPU1_CPU0_P1P0_DN<20>")
	)
	(segment
		(start 318.63284 -172.867066)
		(end 330.938378 -177.166016)
		(width 0.14732)
		(layer "In4.Cu")
		(net "UPI_CPU1_CPU0_P1P0_DN<20>")
	)
	(segment
		(start 138.148822 -180.111908)
		(end 149.880828 -174.103538)
		(width 0.14732)
		(layer "In4.Cu")
		(net "UPI_CPU1_CPU0_P1P0_DN<20>")
	)
	(segment
		(start 115.262406 -211.585302)
		(end 115.262152 -211.585048)
		(width 0.14732)
		(layer "In4.Cu")
		(net "UPI_CPU1_CPU0_P1P0_DN<20>")
	)
	(segment
		(start 115.304316 -212.4837)
		(end 115.304316 -212.114638)
		(width 0.0889)
		(layer "In4.Cu")
		(net "UPI_CPU1_CPU0_P1P0_DN<20>")
	)
	(segment
		(start 338.194904 -180.254148)
		(end 340.057232 -181.511448)
		(width 0.14732)
		(layer "In4.Cu")
		(net "UPI_CPU1_CPU0_P1P0_DN<20>")
	)
	(segment
		(start 355.95814 -211.696808)
		(end 355.958394 -211.697062)
		(width 0.14732)
		(layer "In4.Cu")
		(net "UPI_CPU1_CPU0_P1P0_DN<20>")
	)
	(segment
		(start 355.91623 -212.114892)
		(end 355.91623 -213.8934)
		(width 0.0889)
		(layer "In4.Cu")
		(net "UPI_CPU1_CPU0_P1P0_DN<20>")
	)
	(segment
		(start 115.262152 -211.585048)
		(end 115.262152 -210.920584)
		(width 0.14732)
		(layer "In4.Cu")
		(net "UPI_CPU1_CPU0_P1P0_DN<20>")
	)
	(segment
		(start 156.453078 -172.422058)
		(end 200.881488 -171.684442)
		(width 0.14732)
		(layer "In4.Cu")
		(net "UPI_CPU1_CPU0_P1P0_DN<20>")
	)
	(segment
		(start 356.134416 -218.421204)
		(end 356.29088 -218.692222)
		(width 0.0889)
		(layer "In4.Cu")
		(net "UPI_CPU1_CPU0_P1P0_DN<20>")
	)
	(segment
		(start 340.057232 -181.511448)
		(end 343.96934 -185.423556)
		(width 0.14732)
		(layer "In4.Cu")
		(net "UPI_CPU1_CPU0_P1P0_DN<20>")
	)
	(segment
		(start 115.205256 -212.75802)
		(end 115.205256 -212.58276)
		(width 0.0889)
		(layer "In4.Cu")
		(net "UPI_CPU1_CPU0_P1P0_DN<20>")
	)
	(segment
		(start 356.385876 -214.424768)
		(end 356.385876 -214.644732)
		(width 0.0889)
		(layer "In4.Cu")
		(net "UPI_CPU1_CPU0_P1P0_DN<20>")
	)
	(segment
		(start 114.834162 -216.260426)
		(end 114.834162 -216.240614)
		(width 0.0889)
		(layer "In4.Cu")
		(net "UPI_CPU1_CPU0_P1P0_DN<20>")
	)
	(segment
		(start 355.95814 -211.227162)
		(end 355.95814 -211.696808)
		(width 0.14732)
		(layer "In4.Cu")
		(net "UPI_CPU1_CPU0_P1P0_DN<20>")
	)
	(segment
		(start 115.262406 -212.072728)
		(end 115.262406 -212.05063)
		(width 0.0889)
		(layer "In4.Cu")
		(net "UPI_CPU1_CPU0_P1P0_DN<20>")
	)
	(segment
		(start 211.643976 -172.156882)
		(end 238.601504 -172.156882)
		(width 0.14732)
		(layer "In4.Cu")
		(net "UPI_CPU1_CPU0_P1P0_DN<20>")
	)
	(segment
		(start 313.684158 -171.484544)
		(end 318.63284 -172.867066)
		(width 0.14732)
		(layer "In4.Cu")
		(net "UPI_CPU1_CPU0_P1P0_DN<20>")
	)
	(segment
		(start 302.468788 -171.276264)
		(end 302.47463 -171.27601)
		(width 0.14732)
		(layer "In4.Cu")
		(net "UPI_CPU1_CPU0_P1P0_DN<20>")
	)
	(segment
		(start 115.205256 -212.58276)
		(end 115.304316 -212.4837)
		(width 0.0889)
		(layer "In4.Cu")
		(net "UPI_CPU1_CPU0_P1P0_DN<20>")
	)
	(segment
		(start 273.062954 -171.992036)
		(end 302.468788 -171.276264)
		(width 0.14732)
		(layer "In4.Cu")
		(net "UPI_CPU1_CPU0_P1P0_DN<20>")
	)
	(segment
		(start 119.091964 -199.981058)
		(end 126.891288 -190.38443)
		(width 0.14732)
		(layer "In4.Cu")
		(net "UPI_CPU1_CPU0_P1P0_DN<20>")
	)
	(segment
		(start 302.47463 -171.27601)
		(end 302.480218 -171.27601)
		(width 0.14732)
		(layer "In4.Cu")
		(net "UPI_CPU1_CPU0_P1P0_DN<20>")
	)
	(segment
		(start 352.756216 -195.402962)
		(end 356.51694 -204.482192)
		(width 0.14732)
		(layer "In4.Cu")
		(net "UPI_CPU1_CPU0_P1P0_DN<20>")
	)
	(segment
		(start 115.304316 -213.52256)
		(end 115.205256 -213.4235)
		(width 0.0889)
		(layer "In4.Cu")
		(net "UPI_CPU1_CPU0_P1P0_DN<20>")
	)
	(segment
		(start 355.958394 -212.05063)
		(end 355.958394 -212.072728)
		(width 0.0889)
		(layer "In4.Cu")
		(net "UPI_CPU1_CPU0_P1P0_DN<20>")
	)
	(segment
		(start 114.929412 -217.064336)
		(end 115.085876 -217.335354)
		(width 0.0889)
		(layer "In4.Cu")
		(net "UPI_CPU1_CPU0_P1P0_DN<20>")
	)
	(segment
		(start 130.461258 -188.011562)
		(end 130.461512 -188.011562)
		(width 0.14732)
		(layer "In4.Cu")
		(net "UPI_CPU1_CPU0_P1P0_DN<20>")
	)
	(segment
		(start 343.96934 -185.423556)
		(end 346.435426 -188.926216)
		(width 0.14732)
		(layer "In4.Cu")
		(net "UPI_CPU1_CPU0_P1P0_DN<20>")
	)
	(segment
		(start 302.480472 -171.276264)
		(end 313.684158 -171.484544)
		(width 0.14732)
		(layer "In4.Cu")
		(net "UPI_CPU1_CPU0_P1P0_DN<20>")
	)
	(segment
		(start 356.106476 -215.762586)
		(end 356.109778 -215.764618)
		(width 0.0889)
		(layer "In4.Cu")
		(net "UPI_CPU1_CPU0_P1P0_DN<20>")
	)
	(segment
		(start 238.601504 -172.156882)
		(end 273.062954 -171.992036)
		(width 0.14732)
		(layer "In4.Cu")
		(net "UPI_CPU1_CPU0_P1P0_DN<20>")
	)
	(segment
		(start 115.1255 -216.745058)
		(end 115.11661 -216.739978)
		(width 0.0889)
		(layer "In4.Cu")
		(net "UPI_CPU1_CPU0_P1P0_DN<20>")
	)
	(segment
		(start 115.304062 -213.824312)
		(end 115.304062 -213.809072)
		(width 0.0889)
		(layer "In4.Cu")
		(net "UPI_CPU1_CPU0_P1P0_DN<20>")
	)
	(segment
		(start 356.094792 -215.755982)
		(end 356.102158 -215.7603)
		(width 0.0889)
		(layer "In4.Cu")
		(net "UPI_CPU1_CPU0_P1P0_DN<20>")
	)
	(segment
		(start 356.158546 -218.33205)
		(end 356.134416 -218.421204)
		(width 0.0889)
		(layer "In4.Cu")
		(net "UPI_CPU1_CPU0_P1P0_DN<20>")
	)
	(segment
		(start 356.386384 -217.859864)
		(end 356.386384 -217.878406)
		(width 0.0889)
		(layer "In4.Cu")
		(net "UPI_CPU1_CPU0_P1P0_DN<20>")
	)
	(segment
		(start 356.103682 -215.761062)
		(end 356.106476 -215.762586)
		(width 0.0889)
		(layer "In4.Cu")
		(net "UPI_CPU1_CPU0_P1P0_DN<20>")
	)
	(segment
		(start 355.958394 -211.697062)
		(end 355.958394 -212.05063)
		(width 0.14732)
		(layer "In4.Cu")
		(net "UPI_CPU1_CPU0_P1P0_DN<20>")
	)
	(segment
		(start 115.205256 -213.24824)
		(end 115.304316 -213.14918)
		(width 0.0889)
		(layer "In4.Cu")
		(net "UPI_CPU1_CPU0_P1P0_DN<20>")
	)
	(segment
		(start 126.891288 -190.38443)
		(end 130.461258 -188.011562)
		(width 0.14732)
		(layer "In4.Cu")
		(net "UPI_CPU1_CPU0_P1P0_DN<20>")
	)
	(segment
		(start 115.205256 -213.4235)
		(end 115.205256 -213.24824)
		(width 0.0889)
		(layer "In4.Cu")
		(net "UPI_CPU1_CPU0_P1P0_DN<20>")
	)
	(segment
		(start 134.031736 -185.638694)
		(end 138.148822 -180.111908)
		(width 0.14732)
		(layer "In4.Cu")
		(net "UPI_CPU1_CPU0_P1P0_DN<20>")
	)
	(segment
		(start 356.51694 -204.482192)
		(end 356.51694 -209.877914)
		(width 0.14732)
		(layer "In4.Cu")
		(net "UPI_CPU1_CPU0_P1P0_DN<20>")
	)
	(segment
		(start 356.103936 -216.739978)
		(end 356.103174 -216.740486)
		(width 0.0889)
		(layer "In4.Cu")
		(net "UPI_CPU1_CPU0_P1P0_DN<20>")
	)
	(segment
		(start 356.102158 -215.7603)
		(end 356.103682 -215.761062)
		(width 0.0889)
		(layer "In4.Cu")
		(net "UPI_CPU1_CPU0_P1P0_DN<20>")
	)
	(segment
		(start 115.304316 -213.808818)
		(end 115.304316 -213.52256)
		(width 0.0889)
		(layer "In4.Cu")
		(net "UPI_CPU1_CPU0_P1P0_DN<20>")
	)
	(segment
		(start 115.304062 -215.436704)
		(end 115.304062 -215.414606)
		(width 0.0889)
		(layer "In4.Cu")
		(net "UPI_CPU1_CPU0_P1P0_DN<20>")
	)
	(segment
		(start 356.098094 -216.74328)
		(end 356.095046 -216.745058)
		(width 0.0889)
		(layer "In4.Cu")
		(net "UPI_CPU1_CPU0_P1P0_DN<20>")
	)
	(segment
		(start 356.095046 -217.383614)
		(end 356.103936 -217.388694)
		(width 0.0889)
		(layer "In4.Cu")
		(net "UPI_CPU1_CPU0_P1P0_DN<20>")
	)
	(segment
		(start 355.958394 -212.072728)
		(end 355.91623 -212.114892)
		(width 0.0889)
		(layer "In4.Cu")
		(net "UPI_CPU1_CPU0_P1P0_DN<20>")
	)
	(segment
		(start 302.480218 -171.27601)
		(end 302.480472 -171.276264)
		(width 0.14732)
		(layer "In4.Cu")
		(net "UPI_CPU1_CPU0_P1P0_DN<20>")
	)
	(segment
		(start 115.595146 -214.303356)
		(end 115.587272 -214.298784)
		(width 0.0889)
		(layer "In4.Cu")
		(net "UPI_CPU1_CPU0_P1P0_DN<20>")
	)
	(segment
		(start 200.881488 -171.684442)
		(end 211.643976 -172.156882)
		(width 0.14732)
		(layer "In4.Cu")
		(net "UPI_CPU1_CPU0_P1P0_DN<20>")
	)
	(segment
		(start 356.51694 -209.877914)
		(end 355.95814 -211.227162)
		(width 0.14732)
		(layer "In4.Cu")
		(net "UPI_CPU1_CPU0_P1P0_DN<20>")
	)
	(segment
		(start 115.262152 -210.920584)
		(end 119.091964 -199.981058)
		(width 0.14732)
		(layer "In4.Cu")
		(net "UPI_CPU1_CPU0_P1P0_DN<20>")
	)
	(segment
		(start 346.435426 -188.926216)
		(end 352.756216 -195.402962)
		(width 0.14732)
		(layer "In4.Cu")
		(net "UPI_CPU1_CPU0_P1P0_DN<20>")
	)
	(segment
		(start 130.461512 -188.011562)
		(end 134.031736 -185.638694)
		(width 0.14732)
		(layer "In4.Cu")
		(net "UPI_CPU1_CPU0_P1P0_DN<20>")
	)
	(segment
		(start 115.304316 -213.14918)
		(end 115.304316 -212.85708)
		(width 0.0889)
		(layer "In4.Cu")
		(net "UPI_CPU1_CPU0_P1P0_DN<20>")
	)
	(segment
		(start 356.103682 -215.112346)
		(end 356.102666 -215.112854)
		(width 0.0889)
		(layer "In4.Cu")
		(net "UPI_CPU1_CPU0_P1P0_DN<20>")
	)
	(segment
		(start 115.304316 -212.85708)
		(end 115.205256 -212.75802)
		(width 0.0889)
		(layer "In4.Cu")
		(net "UPI_CPU1_CPU0_P1P0_DN<20>")
	)
	(segment
		(start 115.587272 -214.298784)
		(end 115.586256 -214.298276)
		(width 0.0889)
		(layer "In4.Cu")
		(net "UPI_CPU1_CPU0_P1P0_DN<20>")
	)
	(segment
		(start 115.304316 -212.114638)
		(end 115.262406 -212.072728)
		(width 0.0889)
		(layer "In4.Cu")
		(net "UPI_CPU1_CPU0_P1P0_DN<20>")
	)
	(segment
		(start 115.262406 -212.05063)
		(end 115.262406 -211.585302)
		(width 0.14732)
		(layer "In4.Cu")
		(net "UPI_CPU1_CPU0_P1P0_DN<20>")
	)
	(segment
		(start 115.304062 -213.809072)
		(end 115.304316 -213.808818)
		(width 0.0889)
		(layer "In4.Cu")
		(net "UPI_CPU1_CPU0_P1P0_DN<20>")
	)
	(segment
		(start 115.085876 -217.335354)
		(end 115.164108 -217.356182)
		(width 0.0889)
		(layer "In4.Cu")
		(net "UPI_CPU1_CPU0_P1P0_DN<20>")
	)
	(segment
		(start 356.102666 -215.112854)
		(end 356.094792 -215.117426)
		(width 0.0889)
		(layer "In4.Cu")
		(net "UPI_CPU1_CPU0_P1P0_DN<20>")
	)
	(segment
		(start 115.586256 -214.946992)
		(end 115.595146 -214.941912)
		(width 0.0889)
		(layer "In4.Cu")
		(net "UPI_CPU1_CPU0_P1P0_DN<20>")
	)
	(arc
		(start 115.773708 -214.622634)
		(mid 115.726029 -214.439734)
		(end 115.595146 -214.303356)
		(width 0.0889)
		(layer "In4.Cu")
		(net "UPI_CPU1_CPU0_P1P0_DN<20>")
	)
	(arc
		(start 355.916484 -215.421972)
		(mid 355.916287 -215.429337)
		(end 355.91623 -215.436704)
		(width 0.0889)
		(layer "In4.Cu")
		(net "UPI_CPU1_CPU0_P1P0_DN<20>")
	)
	(arc
		(start 115.586256 -214.298276)
		(mid 115.383433 -214.098045)
		(end 115.304062 -213.824312)
		(width 0.0889)
		(layer "In4.Cu")
		(net "UPI_CPU1_CPU0_P1P0_DN<20>")
	)
	(arc
		(start 115.595146 -214.941912)
		(mid 115.7224 -214.811946)
		(end 115.773454 -214.637366)
		(width 0.0889)
		(layer "In4.Cu")
		(net "UPI_CPU1_CPU0_P1P0_DN<20>")
	)
	(arc
		(start 114.834162 -216.240614)
		(mid 114.912273 -215.963665)
		(end 115.11661 -215.761062)
		(width 0.0889)
		(layer "In4.Cu")
		(net "UPI_CPU1_CPU0_P1P0_DN<20>")
	)
	(arc
		(start 356.094792 -215.117426)
		(mid 355.967538 -215.247392)
		(end 355.916484 -215.421972)
		(width 0.0889)
		(layer "In4.Cu")
		(net "UPI_CPU1_CPU0_P1P0_DN<20>")
	)
	(arc
		(start 356.109778 -215.764618)
		(mid 356.312365 -215.970969)
		(end 356.386384 -216.25052)
		(width 0.0889)
		(layer "In4.Cu")
		(net "UPI_CPU1_CPU0_P1P0_DN<20>")
	)
	(arc
		(start 115.773454 -214.637366)
		(mid 115.773651 -214.630001)
		(end 115.773708 -214.622634)
		(width 0.0889)
		(layer "In4.Cu")
		(net "UPI_CPU1_CPU0_P1P0_DN<20>")
	)
	(arc
		(start 356.103936 -217.388694)
		(mid 356.306222 -217.587675)
		(end 356.386384 -217.859864)
		(width 0.0889)
		(layer "In4.Cu")
		(net "UPI_CPU1_CPU0_P1P0_DN<20>")
	)
	(arc
		(start 115.304062 -217.064336)
		(mid 115.256383 -216.881436)
		(end 115.1255 -216.745058)
		(width 0.0889)
		(layer "In4.Cu")
		(net "UPI_CPU1_CPU0_P1P0_DN<20>")
	)
	(arc
		(start 356.100634 -214.093298)
		(mid 356.274597 -214.232062)
		(end 356.385876 -214.424768)
		(width 0.0889)
		(layer "In4.Cu")
		(net "UPI_CPU1_CPU0_P1P0_DN<20>")
	)
	(arc
		(start 355.91623 -215.436704)
		(mid 355.963909 -215.619604)
		(end 356.094792 -215.755982)
		(width 0.0889)
		(layer "In4.Cu")
		(net "UPI_CPU1_CPU0_P1P0_DN<20>")
	)
	(arc
		(start 115.11661 -216.739978)
		(mid 114.912275 -216.537373)
		(end 114.834162 -216.260426)
		(width 0.0889)
		(layer "In4.Cu")
		(net "UPI_CPU1_CPU0_P1P0_DN<20>")
	)
	(arc
		(start 115.1255 -215.755982)
		(mid 115.256414 -215.619622)
		(end 115.304062 -215.436704)
		(width 0.0889)
		(layer "In4.Cu")
		(net "UPI_CPU1_CPU0_P1P0_DN<20>")
	)
	(arc
		(start 356.175564 -218.318842)
		(mid 356.167118 -218.325527)
		(end 356.158546 -218.33205)
		(width 0.0889)
		(layer "In4.Cu")
		(net "UPI_CPU1_CPU0_P1P0_DN<20>")
	)
	(arc
		(start 115.304062 -215.414606)
		(mid 115.384973 -215.144478)
		(end 115.586256 -214.946992)
		(width 0.0889)
		(layer "In4.Cu")
		(net "UPI_CPU1_CPU0_P1P0_DN<20>")
	)
	(arc
		(start 355.916484 -213.893908)
		(mid 355.991489 -214.009367)
		(end 356.100634 -214.093298)
		(width 0.0889)
		(layer "In4.Cu")
		(net "UPI_CPU1_CPU0_P1P0_DN<20>")
	)
	(arc
		(start 356.385876 -214.644732)
		(mid 356.304965 -214.91486)
		(end 356.103682 -215.112346)
		(width 0.0889)
		(layer "In4.Cu")
		(net "UPI_CPU1_CPU0_P1P0_DN<20>")
	)
	(arc
		(start 356.386384 -216.260426)
		(mid 356.308273 -216.537375)
		(end 356.103936 -216.739978)
		(width 0.0889)
		(layer "In4.Cu")
		(net "UPI_CPU1_CPU0_P1P0_DN<20>")
	)
	(arc
		(start 115.164108 -217.356182)
		(mid 115.267253 -217.226157)
		(end 115.304062 -217.064336)
		(width 0.0889)
		(layer "In4.Cu")
		(net "UPI_CPU1_CPU0_P1P0_DN<20>")
	)
	(arc
		(start 356.095046 -216.745058)
		(mid 355.916449 -217.064336)
		(end 356.095046 -217.383614)
		(width 0.0889)
		(layer "In4.Cu")
		(net "UPI_CPU1_CPU0_P1P0_DN<20>")
	)
	(arc
		(start 356.386384 -217.878406)
		(mid 356.331029 -218.122593)
		(end 356.175564 -218.318842)
		(width 0.0889)
		(layer "In4.Cu")
		(net "UPI_CPU1_CPU0_P1P0_DN<20>")
	)
	(segment
		(start 338.434934 -217.06459)
		(end 338.43468 -217.064336)
		(width 0.13208)
		(layer "F.Cu")
		(net "UPI_CPU1_CPU0_P1P0_DN<1>")
	)
	(segment
		(start 132.785866 -219.228162)
		(end 132.785866 -218.692476)
		(width 0.13208)
		(layer "F.Cu")
		(net "UPI_CPU1_CPU0_P1P0_DN<1>")
	)
	(segment
		(start 338.434934 -217.600276)
		(end 338.434934 -217.06459)
		(width 0.13208)
		(layer "F.Cu")
		(net "UPI_CPU1_CPU0_P1P0_DN<1>")
	)
	(segment
		(start 132.785866 -218.692476)
		(end 132.785612 -218.692222)
		(width 0.13208)
		(layer "F.Cu")
		(net "UPI_CPU1_CPU0_P1P0_DN<1>")
	)
	(segment
		(start 165.148006 -190.653162)
		(end 191.093344 -191.00038)
		(width 0.14732)
		(layer "In4.Cu")
		(net "UPI_CPU1_CPU0_P1P0_DN<1>")
	)
	(segment
		(start 335.840832 -201.112628)
		(end 336.267806 -201.539602)
		(width 0.14732)
		(layer "In4.Cu")
		(net "UPI_CPU1_CPU0_P1P0_DN<1>")
	)
	(segment
		(start 134.883144 -213.536276)
		(end 134.883144 -213.476332)
		(width 0.0889)
		(layer "In4.Cu")
		(net "UPI_CPU1_CPU0_P1P0_DN<1>")
	)
	(segment
		(start 338.102448 -211.801202)
		(end 338.102448 -212.03793)
		(width 0.14732)
		(layer "In4.Cu")
		(net "UPI_CPU1_CPU0_P1P0_DN<1>")
	)
	(segment
		(start 235.998258 -199.669146)
		(end 237.34395 -199.669146)
		(width 0.14732)
		(layer "In4.Cu")
		(net "UPI_CPU1_CPU0_P1P0_DN<1>")
	)
	(segment
		(start 135.039862 -215.436704)
		(end 135.039862 -215.275922)
		(width 0.0889)
		(layer "In4.Cu")
		(net "UPI_CPU1_CPU0_P1P0_DN<1>")
	)
	(segment
		(start 165.022276 -189.027308)
		(end 165.002464 -190.504572)
		(width 0.14732)
		(layer "In4.Cu")
		(net "UPI_CPU1_CPU0_P1P0_DN<1>")
	)
	(segment
		(start 153.069544 -195.134992)
		(end 156.01569 -192.162176)
		(width 0.14732)
		(layer "In4.Cu")
		(net "UPI_CPU1_CPU0_P1P0_DN<1>")
	)
	(segment
		(start 147.08124 -200.126092)
		(end 147.496276 -199.707246)
		(width 0.14732)
		(layer "In4.Cu")
		(net "UPI_CPU1_CPU0_P1P0_DN<1>")
	)
	(segment
		(start 237.34395 -199.669146)
		(end 238.960406 -199.466962)
		(width 0.14732)
		(layer "In4.Cu")
		(net "UPI_CPU1_CPU0_P1P0_DN<1>")
	)
	(segment
		(start 133.436614 -216.578688)
		(end 133.442964 -216.574878)
		(width 0.0889)
		(layer "In4.Cu")
		(net "UPI_CPU1_CPU0_P1P0_DN<1>")
	)
	(segment
		(start 144.925796 -201.460862)
		(end 145.241772 -201.77379)
		(width 0.14732)
		(layer "In4.Cu")
		(net "UPI_CPU1_CPU0_P1P0_DN<1>")
	)
	(segment
		(start 145.548096 -200.83272)
		(end 145.546318 -200.397364)
		(width 0.14732)
		(layer "In4.Cu")
		(net "UPI_CPU1_CPU0_P1P0_DN<1>")
	)
	(segment
		(start 339.151976 -204.423772)
		(end 339.697314 -205.740508)
		(width 0.14732)
		(layer "In4.Cu")
		(net "UPI_CPU1_CPU0_P1P0_DN<1>")
	)
	(segment
		(start 159.815784 -190.582042)
		(end 163.420298 -190.630556)
		(width 0.14732)
		(layer "In4.Cu")
		(net "UPI_CPU1_CPU0_P1P0_DN<1>")
	)
	(segment
		(start 338.248244 -216.73947)
		(end 338.247482 -216.739978)
		(width 0.0889)
		(layer "In4.Cu")
		(net "UPI_CPU1_CPU0_P1P0_DN<1>")
	)
	(segment
		(start 163.420298 -190.630556)
		(end 163.569142 -190.485268)
		(width 0.14732)
		(layer "In4.Cu")
		(net "UPI_CPU1_CPU0_P1P0_DN<1>")
	)
	(segment
		(start 145.241772 -201.77379)
		(end 145.450052 -201.772774)
		(width 0.14732)
		(layer "In4.Cu")
		(net "UPI_CPU1_CPU0_P1P0_DN<1>")
	)
	(segment
		(start 147.177506 -198.750682)
		(end 147.753324 -198.16953)
		(width 0.14732)
		(layer "In4.Cu")
		(net "UPI_CPU1_CPU0_P1P0_DN<1>")
	)
	(segment
		(start 163.588954 -189.00775)
		(end 163.900612 -188.70422)
		(width 0.14732)
		(layer "In4.Cu")
		(net "UPI_CPU1_CPU0_P1P0_DN<1>")
	)
	(segment
		(start 331.753972 -197.403974)
		(end 333.5274 -198.798942)
		(width 0.14732)
		(layer "In4.Cu")
		(net "UPI_CPU1_CPU0_P1P0_DN<1>")
	)
	(segment
		(start 146.122136 -199.816212)
		(end 146.556984 -199.813926)
		(width 0.14732)
		(layer "In4.Cu")
		(net "UPI_CPU1_CPU0_P1P0_DN<1>")
	)
	(segment
		(start 339.697314 -207.09001)
		(end 338.102194 -208.68513)
		(width 0.14732)
		(layer "In4.Cu")
		(net "UPI_CPU1_CPU0_P1P0_DN<1>")
	)
	(segment
		(start 133.436868 -216.578434)
		(end 133.436614 -216.578688)
		(width 0.0889)
		(layer "In4.Cu")
		(net "UPI_CPU1_CPU0_P1P0_DN<1>")
	)
	(segment
		(start 147.496276 -199.707246)
		(end 147.49526 -199.498966)
		(width 0.14732)
		(layer "In4.Cu")
		(net "UPI_CPU1_CPU0_P1P0_DN<1>")
	)
	(segment
		(start 338.250276 -215.762586)
		(end 338.253578 -215.764618)
		(width 0.0889)
		(layer "In4.Cu")
		(net "UPI_CPU1_CPU0_P1P0_DN<1>")
	)
	(segment
		(start 338.060284 -212.102192)
		(end 338.060284 -212.467698)
		(width 0.0889)
		(layer "In4.Cu")
		(net "UPI_CPU1_CPU0_P1P0_DN<1>")
	)
	(segment
		(start 297.689016 -190.470282)
		(end 298.312078 -190.327026)
		(width 0.14732)
		(layer "In4.Cu")
		(net "UPI_CPU1_CPU0_P1P0_DN<1>")
	)
	(segment
		(start 335.886806 -202.356466)
		(end 335.886806 -202.564238)
		(width 0.14732)
		(layer "In4.Cu")
		(net "UPI_CPU1_CPU0_P1P0_DN<1>")
	)
	(segment
		(start 335.840832 -201.112374)
		(end 335.840832 -201.112628)
		(width 0.14732)
		(layer "In4.Cu")
		(net "UPI_CPU1_CPU0_P1P0_DN<1>")
	)
	(segment
		(start 338.159344 -213.290658)
		(end 338.060284 -213.389718)
		(width 0.0889)
		(layer "In4.Cu")
		(net "UPI_CPU1_CPU0_P1P0_DN<1>")
	)
	(segment
		(start 338.060284 -217.0557)
		(end 338.060284 -217.072972)
		(width 0.0889)
		(layer "In4.Cu")
		(net "UPI_CPU1_CPU0_P1P0_DN<1>")
	)
	(segment
		(start 132.785612 -218.692222)
		(end 132.942076 -218.421204)
		(width 0.0889)
		(layer "In4.Cu")
		(net "UPI_CPU1_CPU0_P1P0_DN<1>")
	)
	(segment
		(start 134.569962 -213.849458)
		(end 134.883144 -213.536276)
		(width 0.0889)
		(layer "In4.Cu")
		(net "UPI_CPU1_CPU0_P1P0_DN<1>")
	)
	(segment
		(start 220.326712 -192.21323)
		(end 232.947464 -198.909686)
		(width 0.14732)
		(layer "In4.Cu")
		(net "UPI_CPU1_CPU0_P1P0_DN<1>")
	)
	(segment
		(start 338.060284 -212.467698)
		(end 338.159344 -212.566758)
		(width 0.0889)
		(layer "In4.Cu")
		(net "UPI_CPU1_CPU0_P1P0_DN<1>")
	)
	(segment
		(start 338.278216 -217.335354)
		(end 338.43468 -217.064336)
		(width 0.0889)
		(layer "In4.Cu")
		(net "UPI_CPU1_CPU0_P1P0_DN<1>")
	)
	(segment
		(start 145.450052 -201.772774)
		(end 145.865088 -201.353674)
		(width 0.14732)
		(layer "In4.Cu")
		(net "UPI_CPU1_CPU0_P1P0_DN<1>")
	)
	(segment
		(start 191.093344 -191.00038)
		(end 208.457292 -190.298578)
		(width 0.14732)
		(layer "In4.Cu")
		(net "UPI_CPU1_CPU0_P1P0_DN<1>")
	)
	(segment
		(start 148.188172 -198.167244)
		(end 148.504148 -198.480426)
		(width 0.14732)
		(layer "In4.Cu")
		(net "UPI_CPU1_CPU0_P1P0_DN<1>")
	)
	(segment
		(start 336.512408 -202.982068)
		(end 336.893408 -202.601068)
		(width 0.14732)
		(layer "In4.Cu")
		(net "UPI_CPU1_CPU0_P1P0_DN<1>")
	)
	(segment
		(start 143.917162 -202.479148)
		(end 143.914876 -202.044046)
		(width 0.14732)
		(layer "In4.Cu")
		(net "UPI_CPU1_CPU0_P1P0_DN<1>")
	)
	(segment
		(start 338.060284 -213.389718)
		(end 338.060284 -213.893908)
		(width 0.0889)
		(layer "In4.Cu")
		(net "UPI_CPU1_CPU0_P1P0_DN<1>")
	)
	(segment
		(start 338.245958 -215.7603)
		(end 338.247482 -215.761062)
		(width 0.0889)
		(layer "In4.Cu")
		(net "UPI_CPU1_CPU0_P1P0_DN<1>")
	)
	(segment
		(start 250.13412 -194.353688)
		(end 261.076948 -191.434974)
		(width 0.14732)
		(layer "In4.Cu")
		(net "UPI_CPU1_CPU0_P1P0_DN<1>")
	)
	(segment
		(start 338.060284 -213.016338)
		(end 338.159344 -213.115398)
		(width 0.0889)
		(layer "In4.Cu")
		(net "UPI_CPU1_CPU0_P1P0_DN<1>")
	)
	(segment
		(start 238.960406 -199.466962)
		(end 250.13412 -194.353688)
		(width 0.14732)
		(layer "In4.Cu")
		(net "UPI_CPU1_CPU0_P1P0_DN<1>")
	)
	(segment
		(start 148.712428 -198.479664)
		(end 151.28875 -195.882514)
		(width 0.14732)
		(layer "In4.Cu")
		(net "UPI_CPU1_CPU0_P1P0_DN<1>")
	)
	(segment
		(start 164.718492 -188.715396)
		(end 165.022276 -189.027308)
		(width 0.14732)
		(layer "In4.Cu")
		(net "UPI_CPU1_CPU0_P1P0_DN<1>")
	)
	(segment
		(start 338.102194 -211.800948)
		(end 338.102448 -211.801202)
		(width 0.14732)
		(layer "In4.Cu")
		(net "UPI_CPU1_CPU0_P1P0_DN<1>")
	)
	(segment
		(start 165.002464 -190.504572)
		(end 165.148006 -190.653162)
		(width 0.14732)
		(layer "In4.Cu")
		(net "UPI_CPU1_CPU0_P1P0_DN<1>")
	)
	(segment
		(start 147.49526 -199.498966)
		(end 147.179284 -199.186038)
		(width 0.14732)
		(layer "In4.Cu")
		(net "UPI_CPU1_CPU0_P1P0_DN<1>")
	)
	(segment
		(start 133.442964 -216.574878)
		(end 133.444488 -216.574116)
		(width 0.0889)
		(layer "In4.Cu")
		(net "UPI_CPU1_CPU0_P1P0_DN<1>")
	)
	(segment
		(start 286.48406 -190.421514)
		(end 297.689016 -190.470282)
		(width 0.14732)
		(layer "In4.Cu")
		(net "UPI_CPU1_CPU0_P1P0_DN<1>")
	)
	(segment
		(start 298.312078 -190.327026)
		(end 300.860714 -188.288168)
		(width 0.14732)
		(layer "In4.Cu")
		(net "UPI_CPU1_CPU0_P1P0_DN<1>")
	)
	(segment
		(start 144.490694 -201.46264)
		(end 144.925796 -201.460862)
		(width 0.14732)
		(layer "In4.Cu")
		(net "UPI_CPU1_CPU0_P1P0_DN<1>")
	)
	(segment
		(start 144.233138 -202.79233)
		(end 143.917162 -202.479148)
		(width 0.14732)
		(layer "In4.Cu")
		(net "UPI_CPU1_CPU0_P1P0_DN<1>")
	)
	(segment
		(start 145.864072 -201.145902)
		(end 145.548096 -200.83272)
		(width 0.14732)
		(layer "In4.Cu")
		(net "UPI_CPU1_CPU0_P1P0_DN<1>")
	)
	(segment
		(start 337.329272 -202.601068)
		(end 339.151976 -204.423772)
		(width 0.14732)
		(layer "In4.Cu")
		(net "UPI_CPU1_CPU0_P1P0_DN<1>")
	)
	(segment
		(start 163.900612 -188.70422)
		(end 164.718492 -188.715396)
		(width 0.14732)
		(layer "In4.Cu")
		(net "UPI_CPU1_CPU0_P1P0_DN<1>")
	)
	(segment
		(start 338.102448 -212.060028)
		(end 338.060284 -212.102192)
		(width 0.0889)
		(layer "In4.Cu")
		(net "UPI_CPU1_CPU0_P1P0_DN<1>")
	)
	(segment
		(start 157.416754 -191.450722)
		(end 159.815784 -190.582042)
		(width 0.14732)
		(layer "In4.Cu")
		(net "UPI_CPU1_CPU0_P1P0_DN<1>")
	)
	(segment
		(start 151.28875 -195.882514)
		(end 153.069544 -195.134992)
		(width 0.14732)
		(layer "In4.Cu")
		(net "UPI_CPU1_CPU0_P1P0_DN<1>")
	)
	(segment
		(start 147.179284 -199.186038)
		(end 147.177506 -198.750682)
		(width 0.14732)
		(layer "In4.Cu")
		(net "UPI_CPU1_CPU0_P1P0_DN<1>")
	)
	(segment
		(start 134.569962 -214.744808)
		(end 134.569962 -213.849458)
		(width 0.0889)
		(layer "In4.Cu")
		(net "UPI_CPU1_CPU0_P1P0_DN<1>")
	)
	(segment
		(start 146.873214 -200.127108)
		(end 147.08124 -200.126092)
		(width 0.14732)
		(layer "In4.Cu")
		(net "UPI_CPU1_CPU0_P1P0_DN<1>")
	)
	(segment
		(start 134.463282 -215.752426)
		(end 134.478014 -215.761062)
		(width 0.0889)
		(layer "In4.Cu")
		(net "UPI_CPU1_CPU0_P1P0_DN<1>")
	)
	(segment
		(start 163.569142 -190.485268)
		(end 163.588954 -189.00775)
		(width 0.14732)
		(layer "In4.Cu")
		(net "UPI_CPU1_CPU0_P1P0_DN<1>")
	)
	(segment
		(start 335.886806 -202.564238)
		(end 336.304636 -202.982068)
		(width 0.14732)
		(layer "In4.Cu")
		(net "UPI_CPU1_CPU0_P1P0_DN<1>")
	)
	(segment
		(start 140.72489 -206.541116)
		(end 144.2339 -203.000356)
		(width 0.14732)
		(layer "In4.Cu")
		(net "UPI_CPU1_CPU0_P1P0_DN<1>")
	)
	(segment
		(start 312.111136 -187.75807)
		(end 318.56045 -192.885314)
		(width 0.14732)
		(layer "In4.Cu")
		(net "UPI_CPU1_CPU0_P1P0_DN<1>")
	)
	(segment
		(start 261.076948 -191.434974)
		(end 286.48406 -190.421514)
		(width 0.14732)
		(layer "In4.Cu")
		(net "UPI_CPU1_CPU0_P1P0_DN<1>")
	)
	(segment
		(start 338.060284 -212.841078)
		(end 338.060284 -213.016338)
		(width 0.0889)
		(layer "In4.Cu")
		(net "UPI_CPU1_CPU0_P1P0_DN<1>")
	)
	(segment
		(start 132.942076 -218.421204)
		(end 132.917946 -218.33205)
		(width 0.0889)
		(layer "In4.Cu")
		(net "UPI_CPU1_CPU0_P1P0_DN<1>")
	)
	(segment
		(start 338.247482 -215.112346)
		(end 338.246466 -215.112854)
		(width 0.0889)
		(layer "In4.Cu")
		(net "UPI_CPU1_CPU0_P1P0_DN<1>")
	)
	(segment
		(start 133.160262 -217.072972)
		(end 133.160262 -217.064336)
		(width 0.0889)
		(layer "In4.Cu")
		(net "UPI_CPU1_CPU0_P1P0_DN<1>")
	)
	(segment
		(start 336.267806 -201.975466)
		(end 335.886806 -202.356466)
		(width 0.14732)
		(layer "In4.Cu")
		(net "UPI_CPU1_CPU0_P1P0_DN<1>")
	)
	(segment
		(start 138.549634 -209.809842)
		(end 140.72489 -206.541116)
		(width 0.14732)
		(layer "In4.Cu")
		(net "UPI_CPU1_CPU0_P1P0_DN<1>")
	)
	(segment
		(start 338.246466 -215.112854)
		(end 338.238592 -215.117426)
		(width 0.0889)
		(layer "In4.Cu")
		(net "UPI_CPU1_CPU0_P1P0_DN<1>")
	)
	(segment
		(start 145.865088 -201.353674)
		(end 145.864072 -201.145902)
		(width 0.14732)
		(layer "In4.Cu")
		(net "UPI_CPU1_CPU0_P1P0_DN<1>")
	)
	(segment
		(start 338.159344 -212.566758)
		(end 338.159344 -212.742018)
		(width 0.0889)
		(layer "In4.Cu")
		(net "UPI_CPU1_CPU0_P1P0_DN<1>")
	)
	(segment
		(start 339.697314 -205.740508)
		(end 339.697314 -207.09001)
		(width 0.14732)
		(layer "In4.Cu")
		(net "UPI_CPU1_CPU0_P1P0_DN<1>")
	)
	(segment
		(start 144.2339 -203.000356)
		(end 144.233138 -202.79233)
		(width 0.14732)
		(layer "In4.Cu")
		(net "UPI_CPU1_CPU0_P1P0_DN<1>")
	)
	(segment
		(start 336.893408 -202.601068)
		(end 337.329272 -202.601068)
		(width 0.14732)
		(layer "In4.Cu")
		(net "UPI_CPU1_CPU0_P1P0_DN<1>")
	)
	(segment
		(start 148.504148 -198.480426)
		(end 148.712428 -198.479664)
		(width 0.14732)
		(layer "In4.Cu")
		(net "UPI_CPU1_CPU0_P1P0_DN<1>")
	)
	(segment
		(start 133.444488 -216.574116)
		(end 133.451854 -216.569798)
		(width 0.0889)
		(layer "In4.Cu")
		(net "UPI_CPU1_CPU0_P1P0_DN<1>")
	)
	(segment
		(start 302.410876 -187.51296)
		(end 311.911238 -187.698888)
		(width 0.14732)
		(layer "In4.Cu")
		(net "UPI_CPU1_CPU0_P1P0_DN<1>")
	)
	(segment
		(start 338.253578 -216.736422)
		(end 338.248244 -216.73947)
		(width 0.0889)
		(layer "In4.Cu")
		(net "UPI_CPU1_CPU0_P1P0_DN<1>")
	)
	(segment
		(start 338.238592 -215.755982)
		(end 338.245958 -215.7603)
		(width 0.0889)
		(layer "In4.Cu")
		(net "UPI_CPU1_CPU0_P1P0_DN<1>")
	)
	(segment
		(start 156.01569 -192.162176)
		(end 157.416754 -191.450722)
		(width 0.14732)
		(layer "In4.Cu")
		(net "UPI_CPU1_CPU0_P1P0_DN<1>")
	)
	(segment
		(start 338.529676 -214.424768)
		(end 338.529676 -214.644732)
		(width 0.0889)
		(layer "In4.Cu")
		(net "UPI_CPU1_CPU0_P1P0_DN<1>")
	)
	(segment
		(start 300.860714 -188.288168)
		(end 302.410876 -187.51296)
		(width 0.14732)
		(layer "In4.Cu")
		(net "UPI_CPU1_CPU0_P1P0_DN<1>")
	)
	(segment
		(start 133.630416 -216.25052)
		(end 133.630416 -216.235026)
		(width 0.0889)
		(layer "In4.Cu")
		(net "UPI_CPU1_CPU0_P1P0_DN<1>")
	)
	(segment
		(start 338.102448 -212.03793)
		(end 338.102448 -212.060028)
		(width 0.0889)
		(layer "In4.Cu")
		(net "UPI_CPU1_CPU0_P1P0_DN<1>")
	)
	(segment
		(start 134.85241 -215.761062)
		(end 134.8613 -215.755982)
		(width 0.0889)
		(layer "In4.Cu")
		(net "UPI_CPU1_CPU0_P1P0_DN<1>")
	)
	(segment
		(start 333.5274 -198.798942)
		(end 335.840832 -201.112374)
		(width 0.14732)
		(layer "In4.Cu")
		(net "UPI_CPU1_CPU0_P1P0_DN<1>")
	)
	(segment
		(start 338.247482 -215.761062)
		(end 338.250276 -215.762586)
		(width 0.0889)
		(layer "In4.Cu")
		(net "UPI_CPU1_CPU0_P1P0_DN<1>")
	)
	(segment
		(start 336.304636 -202.982068)
		(end 336.512408 -202.982068)
		(width 0.14732)
		(layer "In4.Cu")
		(net "UPI_CPU1_CPU0_P1P0_DN<1>")
	)
	(segment
		(start 338.102194 -208.68513)
		(end 338.102194 -211.800948)
		(width 0.14732)
		(layer "In4.Cu")
		(net "UPI_CPU1_CPU0_P1P0_DN<1>")
	)
	(segment
		(start 232.947464 -198.909686)
		(end 235.998258 -199.669146)
		(width 0.14732)
		(layer "In4.Cu")
		(net "UPI_CPU1_CPU0_P1P0_DN<1>")
	)
	(segment
		(start 338.159344 -213.115398)
		(end 338.159344 -213.290658)
		(width 0.0889)
		(layer "In4.Cu")
		(net "UPI_CPU1_CPU0_P1P0_DN<1>")
	)
	(segment
		(start 145.546318 -200.397364)
		(end 146.122136 -199.816212)
		(width 0.14732)
		(layer "In4.Cu")
		(net "UPI_CPU1_CPU0_P1P0_DN<1>")
	)
	(segment
		(start 132.690616 -217.8939)
		(end 132.690616 -217.859864)
		(width 0.0889)
		(layer "In4.Cu")
		(net "UPI_CPU1_CPU0_P1P0_DN<1>")
	)
	(segment
		(start 318.56045 -192.885314)
		(end 331.753972 -197.403974)
		(width 0.14732)
		(layer "In4.Cu")
		(net "UPI_CPU1_CPU0_P1P0_DN<1>")
	)
	(segment
		(start 143.914876 -202.044046)
		(end 144.490694 -201.46264)
		(width 0.14732)
		(layer "In4.Cu")
		(net "UPI_CPU1_CPU0_P1P0_DN<1>")
	)
	(segment
		(start 338.159344 -212.742018)
		(end 338.060284 -212.841078)
		(width 0.0889)
		(layer "In4.Cu")
		(net "UPI_CPU1_CPU0_P1P0_DN<1>")
	)
	(segment
		(start 208.457292 -190.298578)
		(end 220.326712 -192.21323)
		(width 0.14732)
		(layer "In4.Cu")
		(net "UPI_CPU1_CPU0_P1P0_DN<1>")
	)
	(segment
		(start 311.911238 -187.698888)
		(end 312.111136 -187.75807)
		(width 0.14732)
		(layer "In4.Cu")
		(net "UPI_CPU1_CPU0_P1P0_DN<1>")
	)
	(segment
		(start 147.753324 -198.16953)
		(end 148.188172 -198.167244)
		(width 0.14732)
		(layer "In4.Cu")
		(net "UPI_CPU1_CPU0_P1P0_DN<1>")
	)
	(segment
		(start 134.898638 -213.460838)
		(end 138.549634 -209.809842)
		(width 0.14732)
		(layer "In4.Cu")
		(net "UPI_CPU1_CPU0_P1P0_DN<1>")
	)
	(segment
		(start 338.200238 -217.356182)
		(end 338.278216 -217.335354)
		(width 0.0889)
		(layer "In4.Cu")
		(net "UPI_CPU1_CPU0_P1P0_DN<1>")
	)
	(segment
		(start 134.883144 -213.476332)
		(end 134.898638 -213.460838)
		(width 0.0889)
		(layer "In4.Cu")
		(net "UPI_CPU1_CPU0_P1P0_DN<1>")
	)
	(segment
		(start 146.556984 -199.813926)
		(end 146.873214 -200.127108)
		(width 0.14732)
		(layer "In4.Cu")
		(net "UPI_CPU1_CPU0_P1P0_DN<1>")
	)
	(segment
		(start 336.267806 -201.539602)
		(end 336.267806 -201.975466)
		(width 0.14732)
		(layer "In4.Cu")
		(net "UPI_CPU1_CPU0_P1P0_DN<1>")
	)
	(arc
		(start 338.06003 -215.436704)
		(mid 338.107709 -215.619604)
		(end 338.238592 -215.755982)
		(width 0.0889)
		(layer "In4.Cu")
		(net "UPI_CPU1_CPU0_P1P0_DN<1>")
	)
	(arc
		(start 338.238592 -215.117426)
		(mid 338.111338 -215.247392)
		(end 338.060284 -215.421972)
		(width 0.0889)
		(layer "In4.Cu")
		(net "UPI_CPU1_CPU0_P1P0_DN<1>")
	)
	(arc
		(start 133.451854 -216.569798)
		(mid 133.582768 -216.433438)
		(end 133.630416 -216.25052)
		(width 0.0889)
		(layer "In4.Cu")
		(net "UPI_CPU1_CPU0_P1P0_DN<1>")
	)
	(arc
		(start 338.060284 -217.072972)
		(mid 338.098958 -217.23004)
		(end 338.200238 -217.356182)
		(width 0.0889)
		(layer "In4.Cu")
		(net "UPI_CPU1_CPU0_P1P0_DN<1>")
	)
	(arc
		(start 134.855458 -215.076024)
		(mid 134.695329 -214.952959)
		(end 134.585202 -214.78367)
		(width 0.0889)
		(layer "In4.Cu")
		(net "UPI_CPU1_CPU0_P1P0_DN<1>")
	)
	(arc
		(start 135.039862 -215.275922)
		(mid 134.964791 -215.16018)
		(end 134.855458 -215.076024)
		(width 0.0889)
		(layer "In4.Cu")
		(net "UPI_CPU1_CPU0_P1P0_DN<1>")
	)
	(arc
		(start 338.244434 -214.093298)
		(mid 338.418397 -214.232062)
		(end 338.529676 -214.424768)
		(width 0.0889)
		(layer "In4.Cu")
		(net "UPI_CPU1_CPU0_P1P0_DN<1>")
	)
	(arc
		(start 338.529676 -214.644732)
		(mid 338.448765 -214.91486)
		(end 338.247482 -215.112346)
		(width 0.0889)
		(layer "In4.Cu")
		(net "UPI_CPU1_CPU0_P1P0_DN<1>")
	)
	(arc
		(start 132.901182 -218.319096)
		(mid 132.7491 -218.129664)
		(end 132.690616 -217.8939)
		(width 0.0889)
		(layer "In4.Cu")
		(net "UPI_CPU1_CPU0_P1P0_DN<1>")
	)
	(arc
		(start 133.160262 -217.064336)
		(mid 133.234253 -216.78477)
		(end 133.436868 -216.578434)
		(width 0.0889)
		(layer "In4.Cu")
		(net "UPI_CPU1_CPU0_P1P0_DN<1>")
	)
	(arc
		(start 338.247482 -216.739978)
		(mid 338.112549 -216.873332)
		(end 338.060284 -217.0557)
		(width 0.0889)
		(layer "In4.Cu")
		(net "UPI_CPU1_CPU0_P1P0_DN<1>")
	)
	(arc
		(start 134.585202 -214.78367)
		(mid 134.577243 -214.764372)
		(end 134.569962 -214.744808)
		(width 0.0889)
		(layer "In4.Cu")
		(net "UPI_CPU1_CPU0_P1P0_DN<1>")
	)
	(arc
		(start 133.91261 -215.761062)
		(mid 134.186809 -215.685227)
		(end 134.463282 -215.752426)
		(width 0.0889)
		(layer "In4.Cu")
		(net "UPI_CPU1_CPU0_P1P0_DN<1>")
	)
	(arc
		(start 132.690616 -217.859864)
		(mid 132.770778 -217.587675)
		(end 132.973064 -217.388694)
		(width 0.0889)
		(layer "In4.Cu")
		(net "UPI_CPU1_CPU0_P1P0_DN<1>")
	)
	(arc
		(start 133.630416 -216.235026)
		(mid 133.709786 -215.961292)
		(end 133.91261 -215.761062)
		(width 0.0889)
		(layer "In4.Cu")
		(net "UPI_CPU1_CPU0_P1P0_DN<1>")
	)
	(arc
		(start 338.060284 -213.893908)
		(mid 338.135289 -214.009367)
		(end 338.244434 -214.093298)
		(width 0.0889)
		(layer "In4.Cu")
		(net "UPI_CPU1_CPU0_P1P0_DN<1>")
	)
	(arc
		(start 132.917946 -218.33205)
		(mid 132.909505 -218.32565)
		(end 132.901182 -218.319096)
		(width 0.0889)
		(layer "In4.Cu")
		(net "UPI_CPU1_CPU0_P1P0_DN<1>")
	)
	(arc
		(start 134.478014 -215.761062)
		(mid 134.665212 -215.811205)
		(end 134.85241 -215.761062)
		(width 0.0889)
		(layer "In4.Cu")
		(net "UPI_CPU1_CPU0_P1P0_DN<1>")
	)
	(arc
		(start 132.973064 -217.388694)
		(mid 133.107997 -217.25534)
		(end 133.160262 -217.072972)
		(width 0.0889)
		(layer "In4.Cu")
		(net "UPI_CPU1_CPU0_P1P0_DN<1>")
	)
	(arc
		(start 338.253578 -215.764618)
		(mid 338.530152 -216.25052)
		(end 338.253578 -216.736422)
		(width 0.0889)
		(layer "In4.Cu")
		(net "UPI_CPU1_CPU0_P1P0_DN<1>")
	)
	(arc
		(start 134.8613 -215.755982)
		(mid 134.992214 -215.619622)
		(end 135.039862 -215.436704)
		(width 0.0889)
		(layer "In4.Cu")
		(net "UPI_CPU1_CPU0_P1P0_DN<1>")
	)
	(arc
		(start 338.060284 -215.421972)
		(mid 338.060087 -215.429337)
		(end 338.06003 -215.436704)
		(width 0.0889)
		(layer "In4.Cu")
		(net "UPI_CPU1_CPU0_P1P0_DN<1>")
	)
	(segment
		(start 116.339112 -218.414346)
		(end 116.339112 -217.87866)
		(width 0.13208)
		(layer "F.Cu")
		(net "UPI_CPU1_CPU0_P1P0_DN<19>")
	)
	(segment
		(start 354.88118 -218.414346)
		(end 354.88118 -217.87866)
		(width 0.13208)
		(layer "F.Cu")
		(net "UPI_CPU1_CPU0_P1P0_DN<19>")
	)
	(segment
		(start 354.88118 -217.87866)
		(end 354.881434 -217.878406)
		(width 0.13208)
		(layer "F.Cu")
		(net "UPI_CPU1_CPU0_P1P0_DN<19>")
	)
	(segment
		(start 116.339112 -217.87866)
		(end 116.339366 -217.878406)
		(width 0.13208)
		(layer "F.Cu")
		(net "UPI_CPU1_CPU0_P1P0_DN<19>")
	)
	(segment
		(start 122.503184 -197.976998)
		(end 122.778774 -197.637654)
		(width 0.14732)
		(layer "In4.Cu")
		(net "UPI_CPU1_CPU0_P1P0_DN<19>")
	)
	(segment
		(start 124.206508 -195.881244)
		(end 124.188982 -195.709794)
		(width 0.14732)
		(layer "In4.Cu")
		(net "UPI_CPU1_CPU0_P1P0_DN<19>")
	)
	(segment
		(start 116.476272 -211.585048)
		(end 116.476272 -210.889088)
		(width 0.14732)
		(layer "In4.Cu")
		(net "UPI_CPU1_CPU0_P1P0_DN<19>")
	)
	(segment
		(start 313.49061 -172.591222)
		(end 318.24549 -173.918118)
		(width 0.14732)
		(layer "In4.Cu")
		(net "UPI_CPU1_CPU0_P1P0_DN<19>")
	)
	(segment
		(start 116.476272 -210.889088)
		(end 119.975884 -200.893172)
		(width 0.14732)
		(layer "In4.Cu")
		(net "UPI_CPU1_CPU0_P1P0_DN<19>")
	)
	(segment
		(start 122.778774 -197.637654)
		(end 122.761248 -197.466204)
		(width 0.14732)
		(layer "In4.Cu")
		(net "UPI_CPU1_CPU0_P1P0_DN<19>")
	)
	(segment
		(start 121.79808 -198.844408)
		(end 122.073924 -198.505064)
		(width 0.14732)
		(layer "In4.Cu")
		(net "UPI_CPU1_CPU0_P1P0_DN<19>")
	)
	(segment
		(start 124.696728 -195.278502)
		(end 124.972572 -194.939158)
		(width 0.14732)
		(layer "In4.Cu")
		(net "UPI_CPU1_CPU0_P1P0_DN<19>")
	)
	(segment
		(start 125.659642 -193.900298)
		(end 128.084326 -190.916814)
		(width 0.14732)
		(layer "In4.Cu")
		(net "UPI_CPU1_CPU0_P1P0_DN<19>")
	)
	(segment
		(start 116.476526 -211.585302)
		(end 116.476272 -211.585048)
		(width 0.14732)
		(layer "In4.Cu")
		(net "UPI_CPU1_CPU0_P1P0_DN<19>")
	)
	(segment
		(start 122.33148 -197.994778)
		(end 122.503184 -197.976998)
		(width 0.14732)
		(layer "In4.Cu")
		(net "UPI_CPU1_CPU0_P1P0_DN<19>")
	)
	(segment
		(start 355.013768 -217.518234)
		(end 355.037898 -217.607388)
		(width 0.0889)
		(layer "In4.Cu")
		(net "UPI_CPU1_CPU0_P1P0_DN<19>")
	)
	(segment
		(start 238.38408 -173.266608)
		(end 273.07921 -173.101762)
		(width 0.14732)
		(layer "In4.Cu")
		(net "UPI_CPU1_CPU0_P1P0_DN<19>")
	)
	(segment
		(start 354.744528 -211.856574)
		(end 354.744528 -211.878672)
		(width 0.0889)
		(layer "In4.Cu")
		(net "UPI_CPU1_CPU0_P1P0_DN<19>")
	)
	(segment
		(start 116.434616 -217.082878)
		(end 116.434616 -217.05443)
		(width 0.0889)
		(layer "In4.Cu")
		(net "UPI_CPU1_CPU0_P1P0_DN<19>")
	)
	(segment
		(start 330.750926 -178.288696)
		(end 337.629754 -181.21376)
		(width 0.14732)
		(layer "In4.Cu")
		(net "UPI_CPU1_CPU0_P1P0_DN<19>")
	)
	(segment
		(start 116.339366 -217.878406)
		(end 116.182902 -218.149424)
		(width 0.0889)
		(layer "In4.Cu")
		(net "UPI_CPU1_CPU0_P1P0_DN<19>")
	)
	(segment
		(start 116.476526 -212.072728)
		(end 116.476526 -212.05063)
		(width 0.0889)
		(layer "In4.Cu")
		(net "UPI_CPU1_CPU0_P1P0_DN<19>")
	)
	(segment
		(start 122.056144 -198.333614)
		(end 122.056398 -198.333614)
		(width 0.14732)
		(layer "In4.Cu")
		(net "UPI_CPU1_CPU0_P1P0_DN<19>")
	)
	(segment
		(start 345.614244 -189.686692)
		(end 351.810066 -196.036438)
		(width 0.14732)
		(layer "In4.Cu")
		(net "UPI_CPU1_CPU0_P1P0_DN<19>")
	)
	(segment
		(start 355.24186 -204.322172)
		(end 355.24186 -209.835242)
		(width 0.14732)
		(layer "In4.Cu")
		(net "UPI_CPU1_CPU0_P1P0_DN<19>")
	)
	(segment
		(start 124.188982 -195.709794)
		(end 124.525278 -195.296028)
		(width 0.14732)
		(layer "In4.Cu")
		(net "UPI_CPU1_CPU0_P1P0_DN<19>")
	)
	(segment
		(start 122.073924 -198.505064)
		(end 122.056144 -198.333614)
		(width 0.14732)
		(layer "In4.Cu")
		(net "UPI_CPU1_CPU0_P1P0_DN<19>")
	)
	(segment
		(start 116.434362 -212.93836)
		(end 116.533422 -212.8393)
		(width 0.0889)
		(layer "In4.Cu")
		(net "UPI_CPU1_CPU0_P1P0_DN<19>")
	)
	(segment
		(start 302.477678 -172.386498)
		(end 313.49061 -172.591222)
		(width 0.14732)
		(layer "In4.Cu")
		(net "UPI_CPU1_CPU0_P1P0_DN<19>")
	)
	(segment
		(start 355.077014 -214.941912)
		(end 355.068124 -214.946992)
		(width 0.0889)
		(layer "In4.Cu")
		(net "UPI_CPU1_CPU0_P1P0_DN<19>")
	)
	(segment
		(start 153.438606 -174.37481)
		(end 156.73578 -173.531022)
		(width 0.14732)
		(layer "In4.Cu")
		(net "UPI_CPU1_CPU0_P1P0_DN<19>")
	)
	(segment
		(start 123.225814 -197.087998)
		(end 123.501658 -196.748654)
		(width 0.14732)
		(layer "In4.Cu")
		(net "UPI_CPU1_CPU0_P1P0_DN<19>")
	)
	(segment
		(start 354.744528 -211.488274)
		(end 354.744528 -211.856574)
		(width 0.14732)
		(layer "In4.Cu")
		(net "UPI_CPU1_CPU0_P1P0_DN<19>")
	)
	(segment
		(start 116.612924 -215.117426)
		(end 116.621814 -215.112346)
		(width 0.0889)
		(layer "In4.Cu")
		(net "UPI_CPU1_CPU0_P1P0_DN<19>")
	)
	(segment
		(start 116.434362 -212.56498)
		(end 116.434362 -212.114892)
		(width 0.0889)
		(layer "In4.Cu")
		(net "UPI_CPU1_CPU0_P1P0_DN<19>")
	)
	(segment
		(start 116.434362 -213.487)
		(end 116.533422 -213.38794)
		(width 0.0889)
		(layer "In4.Cu")
		(net "UPI_CPU1_CPU0_P1P0_DN<19>")
	)
	(segment
		(start 355.24186 -209.835242)
		(end 354.744274 -211.036662)
		(width 0.14732)
		(layer "In4.Cu")
		(net "UPI_CPU1_CPU0_P1P0_DN<19>")
	)
	(segment
		(start 153.43886 -174.37481)
		(end 153.438606 -174.37481)
		(width 0.14732)
		(layer "In4.Cu")
		(net "UPI_CPU1_CPU0_P1P0_DN<19>")
	)
	(segment
		(start 125.401578 -194.411092)
		(end 125.677422 -194.071748)
		(width 0.14732)
		(layer "In4.Cu")
		(net "UPI_CPU1_CPU0_P1P0_DN<19>")
	)
	(segment
		(start 128.084326 -190.916814)
		(end 134.831582 -186.432444)
		(width 0.14732)
		(layer "In4.Cu")
		(net "UPI_CPU1_CPU0_P1P0_DN<19>")
	)
	(segment
		(start 123.759214 -196.238368)
		(end 123.930918 -196.220588)
		(width 0.14732)
		(layer "In4.Cu")
		(net "UPI_CPU1_CPU0_P1P0_DN<19>")
	)
	(segment
		(start 116.143278 -215.931242)
		(end 116.152168 -215.926162)
		(width 0.0889)
		(layer "In4.Cu")
		(net "UPI_CPU1_CPU0_P1P0_DN<19>")
	)
	(segment
		(start 200.79589 -172.799756)
		(end 211.435442 -173.266608)
		(width 0.14732)
		(layer "In4.Cu")
		(net "UPI_CPU1_CPU0_P1P0_DN<19>")
	)
	(segment
		(start 116.434362 -212.114892)
		(end 116.476526 -212.072728)
		(width 0.0889)
		(layer "In4.Cu")
		(net "UPI_CPU1_CPU0_P1P0_DN<19>")
	)
	(segment
		(start 354.786438 -213.929468)
		(end 354.786184 -213.929722)
		(width 0.0889)
		(layer "In4.Cu")
		(net "UPI_CPU1_CPU0_P1P0_DN<19>")
	)
	(segment
		(start 134.831582 -186.432444)
		(end 138.895582 -180.976524)
		(width 0.14732)
		(layer "In4.Cu")
		(net "UPI_CPU1_CPU0_P1P0_DN<19>")
	)
	(segment
		(start 354.786438 -211.920582)
		(end 354.786438 -213.929468)
		(width 0.0889)
		(layer "In4.Cu")
		(net "UPI_CPU1_CPU0_P1P0_DN<19>")
	)
	(segment
		(start 150.141178 -175.218598)
		(end 153.43886 -174.37481)
		(width 0.14732)
		(layer "In4.Cu")
		(net "UPI_CPU1_CPU0_P1P0_DN<19>")
	)
	(segment
		(start 318.24549 -173.918118)
		(end 330.750926 -178.288696)
		(width 0.14732)
		(layer "In4.Cu")
		(net "UPI_CPU1_CPU0_P1P0_DN<19>")
	)
	(segment
		(start 354.744528 -211.878672)
		(end 354.786438 -211.920582)
		(width 0.0889)
		(layer "In4.Cu")
		(net "UPI_CPU1_CPU0_P1P0_DN<19>")
	)
	(segment
		(start 116.476526 -212.05063)
		(end 116.476526 -211.585302)
		(width 0.14732)
		(layer "In4.Cu")
		(net "UPI_CPU1_CPU0_P1P0_DN<19>")
	)
	(segment
		(start 343.110312 -186.1312)
		(end 345.614244 -189.686692)
		(width 0.14732)
		(layer "In4.Cu")
		(net "UPI_CPU1_CPU0_P1P0_DN<19>")
	)
	(segment
		(start 125.230128 -194.428872)
		(end 125.401578 -194.411092)
		(width 0.14732)
		(layer "In4.Cu")
		(net "UPI_CPU1_CPU0_P1P0_DN<19>")
	)
	(segment
		(start 116.533422 -213.21268)
		(end 116.434362 -213.11362)
		(width 0.0889)
		(layer "In4.Cu")
		(net "UPI_CPU1_CPU0_P1P0_DN<19>")
	)
	(segment
		(start 355.070156 -215.926924)
		(end 355.077522 -215.931242)
		(width 0.0889)
		(layer "In4.Cu")
		(net "UPI_CPU1_CPU0_P1P0_DN<19>")
	)
	(segment
		(start 355.070156 -216.574116)
		(end 355.068632 -216.574878)
		(width 0.0889)
		(layer "In4.Cu")
		(net "UPI_CPU1_CPU0_P1P0_DN<19>")
	)
	(segment
		(start 355.065838 -216.576402)
		(end 355.062536 -216.578434)
		(width 0.0889)
		(layer "In4.Cu")
		(net "UPI_CPU1_CPU0_P1P0_DN<19>")
	)
	(segment
		(start 351.810066 -196.036438)
		(end 355.24186 -204.322172)
		(width 0.14732)
		(layer "In4.Cu")
		(net "UPI_CPU1_CPU0_P1P0_DN<19>")
	)
	(segment
		(start 354.78593 -215.414606)
		(end 354.78593 -215.436704)
		(width 0.0889)
		(layer "In4.Cu")
		(net "UPI_CPU1_CPU0_P1P0_DN<19>")
	)
	(segment
		(start 122.331734 -197.995032)
		(end 122.33148 -197.994778)
		(width 0.14732)
		(layer "In4.Cu")
		(net "UPI_CPU1_CPU0_P1P0_DN<19>")
	)
	(segment
		(start 339.362288 -182.383176)
		(end 343.110312 -186.1312)
		(width 0.14732)
		(layer "In4.Cu")
		(net "UPI_CPU1_CPU0_P1P0_DN<19>")
	)
	(segment
		(start 123.483878 -196.577204)
		(end 123.759214 -196.238368)
		(width 0.14732)
		(layer "In4.Cu")
		(net "UPI_CPU1_CPU0_P1P0_DN<19>")
	)
	(segment
		(start 121.62663 -198.862188)
		(end 121.79808 -198.844408)
		(width 0.14732)
		(layer "In4.Cu")
		(net "UPI_CPU1_CPU0_P1P0_DN<19>")
	)
	(segment
		(start 116.143278 -217.559128)
		(end 116.152168 -217.554048)
		(width 0.0889)
		(layer "In4.Cu")
		(net "UPI_CPU1_CPU0_P1P0_DN<19>")
	)
	(segment
		(start 116.182902 -218.149424)
		(end 116.10467 -218.170252)
		(width 0.0889)
		(layer "In4.Cu")
		(net "UPI_CPU1_CPU0_P1P0_DN<19>")
	)
	(segment
		(start 123.930918 -196.220588)
		(end 124.206508 -195.881244)
		(width 0.14732)
		(layer "In4.Cu")
		(net "UPI_CPU1_CPU0_P1P0_DN<19>")
	)
	(segment
		(start 116.434362 -213.786974)
		(end 116.434362 -213.487)
		(width 0.0889)
		(layer "In4.Cu")
		(net "UPI_CPU1_CPU0_P1P0_DN<19>")
	)
	(segment
		(start 355.062536 -215.922606)
		(end 355.06787 -215.925654)
		(width 0.0889)
		(layer "In4.Cu")
		(net "UPI_CPU1_CPU0_P1P0_DN<19>")
	)
	(segment
		(start 355.255576 -214.461344)
		(end 355.255576 -214.622634)
		(width 0.0889)
		(layer "In4.Cu")
		(net "UPI_CPU1_CPU0_P1P0_DN<19>")
	)
	(segment
		(start 355.077522 -216.569798)
		(end 355.070156 -216.574116)
		(width 0.0889)
		(layer "In4.Cu")
		(net "UPI_CPU1_CPU0_P1P0_DN<19>")
	)
	(segment
		(start 124.525278 -195.296028)
		(end 124.696728 -195.278502)
		(width 0.14732)
		(layer "In4.Cu")
		(net "UPI_CPU1_CPU0_P1P0_DN<19>")
	)
	(segment
		(start 124.954792 -194.767708)
		(end 125.230128 -194.428872)
		(width 0.14732)
		(layer "In4.Cu")
		(net "UPI_CPU1_CPU0_P1P0_DN<19>")
	)
	(segment
		(start 116.152168 -216.574878)
		(end 116.143278 -216.569798)
		(width 0.0889)
		(layer "In4.Cu")
		(net "UPI_CPU1_CPU0_P1P0_DN<19>")
	)
	(segment
		(start 119.975884 -200.893172)
		(end 121.62663 -198.862188)
		(width 0.14732)
		(layer "In4.Cu")
		(net "UPI_CPU1_CPU0_P1P0_DN<19>")
	)
	(segment
		(start 273.07921 -173.101762)
		(end 302.477678 -172.386498)
		(width 0.14732)
		(layer "In4.Cu")
		(net "UPI_CPU1_CPU0_P1P0_DN<19>")
	)
	(segment
		(start 116.533422 -212.8393)
		(end 116.533422 -212.66404)
		(width 0.0889)
		(layer "In4.Cu")
		(net "UPI_CPU1_CPU0_P1P0_DN<19>")
	)
	(segment
		(start 354.786184 -213.929722)
		(end 354.786184 -213.930484)
		(width 0.0889)
		(layer "In4.Cu")
		(net "UPI_CPU1_CPU0_P1P0_DN<19>")
	)
	(segment
		(start 354.744274 -211.48802)
		(end 354.744528 -211.488274)
		(width 0.14732)
		(layer "In4.Cu")
		(net "UPI_CPU1_CPU0_P1P0_DN<19>")
	)
	(segment
		(start 123.054364 -197.105778)
		(end 123.225814 -197.087998)
		(width 0.14732)
		(layer "In4.Cu")
		(net "UPI_CPU1_CPU0_P1P0_DN<19>")
	)
	(segment
		(start 354.78593 -217.064336)
		(end 354.78593 -217.07856)
		(width 0.0889)
		(layer "In4.Cu")
		(net "UPI_CPU1_CPU0_P1P0_DN<19>")
	)
	(segment
		(start 116.434362 -213.11362)
		(end 116.434362 -212.93836)
		(width 0.0889)
		(layer "In4.Cu")
		(net "UPI_CPU1_CPU0_P1P0_DN<19>")
	)
	(segment
		(start 116.533422 -212.66404)
		(end 116.434362 -212.56498)
		(width 0.0889)
		(layer "In4.Cu")
		(net "UPI_CPU1_CPU0_P1P0_DN<19>")
	)
	(segment
		(start 337.629754 -181.21376)
		(end 339.362288 -182.383176)
		(width 0.14732)
		(layer "In4.Cu")
		(net "UPI_CPU1_CPU0_P1P0_DN<19>")
	)
	(segment
		(start 124.972572 -194.939158)
		(end 124.954792 -194.767708)
		(width 0.14732)
		(layer "In4.Cu")
		(net "UPI_CPU1_CPU0_P1P0_DN<19>")
	)
	(segment
		(start 354.744274 -211.036662)
		(end 354.744274 -211.48802)
		(width 0.14732)
		(layer "In4.Cu")
		(net "UPI_CPU1_CPU0_P1P0_DN<19>")
	)
	(segment
		(start 355.068632 -215.926162)
		(end 355.070156 -215.926924)
		(width 0.0889)
		(layer "In4.Cu")
		(net "UPI_CPU1_CPU0_P1P0_DN<19>")
	)
	(segment
		(start 355.037898 -217.607388)
		(end 354.881434 -217.878406)
		(width 0.0889)
		(layer "In4.Cu")
		(net "UPI_CPU1_CPU0_P1P0_DN<19>")
	)
	(segment
		(start 355.06787 -215.925654)
		(end 355.068632 -215.926162)
		(width 0.0889)
		(layer "In4.Cu")
		(net "UPI_CPU1_CPU0_P1P0_DN<19>")
	)
	(segment
		(start 156.73578 -173.531022)
		(end 200.79589 -172.799756)
		(width 0.14732)
		(layer "In4.Cu")
		(net "UPI_CPU1_CPU0_P1P0_DN<19>")
	)
	(segment
		(start 355.068632 -216.574878)
		(end 355.065838 -216.576402)
		(width 0.0889)
		(layer "In4.Cu")
		(net "UPI_CPU1_CPU0_P1P0_DN<19>")
	)
	(segment
		(start 122.761248 -197.466204)
		(end 123.054364 -197.105778)
		(width 0.14732)
		(layer "In4.Cu")
		(net "UPI_CPU1_CPU0_P1P0_DN<19>")
	)
	(segment
		(start 116.434362 -215.452198)
		(end 116.434362 -215.436704)
		(width 0.0889)
		(layer "In4.Cu")
		(net "UPI_CPU1_CPU0_P1P0_DN<19>")
	)
	(segment
		(start 116.904008 -214.644732)
		(end 116.903754 -214.501222)
		(width 0.0889)
		(layer "In4.Cu")
		(net "UPI_CPU1_CPU0_P1P0_DN<19>")
	)
	(segment
		(start 211.435442 -173.266608)
		(end 238.38408 -173.266608)
		(width 0.14732)
		(layer "In4.Cu")
		(net "UPI_CPU1_CPU0_P1P0_DN<19>")
	)
	(segment
		(start 122.056398 -198.333614)
		(end 122.331734 -197.995032)
		(width 0.14732)
		(layer "In4.Cu")
		(net "UPI_CPU1_CPU0_P1P0_DN<19>")
	)
	(segment
		(start 138.895582 -180.976524)
		(end 150.141178 -175.218598)
		(width 0.14732)
		(layer "In4.Cu")
		(net "UPI_CPU1_CPU0_P1P0_DN<19>")
	)
	(segment
		(start 116.533422 -213.38794)
		(end 116.533422 -213.21268)
		(width 0.0889)
		(layer "In4.Cu")
		(net "UPI_CPU1_CPU0_P1P0_DN<19>")
	)
	(segment
		(start 125.677422 -194.071748)
		(end 125.659642 -193.900298)
		(width 0.14732)
		(layer "In4.Cu")
		(net "UPI_CPU1_CPU0_P1P0_DN<19>")
	)
	(segment
		(start 123.501658 -196.748654)
		(end 123.483878 -196.577204)
		(width 0.14732)
		(layer "In4.Cu")
		(net "UPI_CPU1_CPU0_P1P0_DN<19>")
	)
	(arc
		(start 116.143278 -216.569798)
		(mid 116.013989 -216.436312)
		(end 115.964716 -216.257124)
		(width 0.0889)
		(layer "In4.Cu")
		(net "UPI_CPU1_CPU0_P1P0_DN<19>")
	)
	(arc
		(start 116.434362 -215.436704)
		(mid 116.434414 -215.429337)
		(end 116.434616 -215.421972)
		(width 0.0889)
		(layer "In4.Cu")
		(net "UPI_CPU1_CPU0_P1P0_DN<19>")
	)
	(arc
		(start 116.434616 -215.421972)
		(mid 116.48567 -215.247392)
		(end 116.612924 -215.117426)
		(width 0.0889)
		(layer "In4.Cu")
		(net "UPI_CPU1_CPU0_P1P0_DN<19>")
	)
	(arc
		(start 355.062536 -216.578434)
		(mid 354.859949 -216.784785)
		(end 354.78593 -217.064336)
		(width 0.0889)
		(layer "In4.Cu")
		(net "UPI_CPU1_CPU0_P1P0_DN<19>")
	)
	(arc
		(start 116.854732 -214.319104)
		(mid 116.752432 -214.189817)
		(end 116.618766 -214.093298)
		(width 0.0889)
		(layer "In4.Cu")
		(net "UPI_CPU1_CPU0_P1P0_DN<19>")
	)
	(arc
		(start 355.071426 -214.261954)
		(mid 355.180573 -214.345882)
		(end 355.255576 -214.461344)
		(width 0.0889)
		(layer "In4.Cu")
		(net "UPI_CPU1_CPU0_P1P0_DN<19>")
	)
	(arc
		(start 354.99675 -217.50528)
		(mid 355.005198 -217.511837)
		(end 355.013768 -217.518234)
		(width 0.0889)
		(layer "In4.Cu")
		(net "UPI_CPU1_CPU0_P1P0_DN<19>")
	)
	(arc
		(start 355.068124 -214.946992)
		(mid 354.866842 -215.144479)
		(end 354.78593 -215.414606)
		(width 0.0889)
		(layer "In4.Cu")
		(net "UPI_CPU1_CPU0_P1P0_DN<19>")
	)
	(arc
		(start 116.618766 -214.093298)
		(mid 116.483958 -213.965784)
		(end 116.434362 -213.786974)
		(width 0.0889)
		(layer "In4.Cu")
		(net "UPI_CPU1_CPU0_P1P0_DN<19>")
	)
	(arc
		(start 354.78593 -217.07856)
		(mid 354.844224 -217.315203)
		(end 354.99675 -217.50528)
		(width 0.0889)
		(layer "In4.Cu")
		(net "UPI_CPU1_CPU0_P1P0_DN<19>")
	)
	(arc
		(start 116.10467 -218.170252)
		(mid 116.001525 -218.040227)
		(end 115.964716 -217.878406)
		(width 0.0889)
		(layer "In4.Cu")
		(net "UPI_CPU1_CPU0_P1P0_DN<19>")
	)
	(arc
		(start 116.434616 -217.05443)
		(mid 116.356505 -216.777481)
		(end 116.152168 -216.574878)
		(width 0.0889)
		(layer "In4.Cu")
		(net "UPI_CPU1_CPU0_P1P0_DN<19>")
	)
	(arc
		(start 116.903754 -214.501222)
		(mid 116.891373 -214.406901)
		(end 116.854732 -214.319104)
		(width 0.0889)
		(layer "In4.Cu")
		(net "UPI_CPU1_CPU0_P1P0_DN<19>")
	)
	(arc
		(start 354.78593 -215.436704)
		(mid 354.859921 -215.71627)
		(end 355.062536 -215.922606)
		(width 0.0889)
		(layer "In4.Cu")
		(net "UPI_CPU1_CPU0_P1P0_DN<19>")
	)
	(arc
		(start 115.964716 -216.24036)
		(mid 116.014785 -216.063135)
		(end 116.143278 -215.931242)
		(width 0.0889)
		(layer "In4.Cu")
		(net "UPI_CPU1_CPU0_P1P0_DN<19>")
	)
	(arc
		(start 115.964716 -217.878406)
		(mid 116.012395 -217.695506)
		(end 116.143278 -217.559128)
		(width 0.0889)
		(layer "In4.Cu")
		(net "UPI_CPU1_CPU0_P1P0_DN<19>")
	)
	(arc
		(start 116.621814 -215.112346)
		(mid 116.823096 -214.914859)
		(end 116.904008 -214.644732)
		(width 0.0889)
		(layer "In4.Cu")
		(net "UPI_CPU1_CPU0_P1P0_DN<19>")
	)
	(arc
		(start 354.801424 -213.969346)
		(mid 354.911418 -214.138715)
		(end 355.071426 -214.261954)
		(width 0.0889)
		(layer "In4.Cu")
		(net "UPI_CPU1_CPU0_P1P0_DN<19>")
	)
	(arc
		(start 354.786184 -213.930484)
		(mid 354.793469 -213.950046)
		(end 354.801424 -213.969346)
		(width 0.0889)
		(layer "In4.Cu")
		(net "UPI_CPU1_CPU0_P1P0_DN<19>")
	)
	(arc
		(start 355.255576 -214.622634)
		(mid 355.207897 -214.805534)
		(end 355.077014 -214.941912)
		(width 0.0889)
		(layer "In4.Cu")
		(net "UPI_CPU1_CPU0_P1P0_DN<19>")
	)
	(arc
		(start 355.077522 -215.931242)
		(mid 355.256119 -216.25052)
		(end 355.077522 -216.569798)
		(width 0.0889)
		(layer "In4.Cu")
		(net "UPI_CPU1_CPU0_P1P0_DN<19>")
	)
	(arc
		(start 115.964716 -216.257124)
		(mid 115.964622 -216.248742)
		(end 115.964716 -216.24036)
		(width 0.0889)
		(layer "In4.Cu")
		(net "UPI_CPU1_CPU0_P1P0_DN<19>")
	)
	(arc
		(start 116.152168 -215.926162)
		(mid 116.354991 -215.725931)
		(end 116.434362 -215.452198)
		(width 0.0889)
		(layer "In4.Cu")
		(net "UPI_CPU1_CPU0_P1P0_DN<19>")
	)
	(arc
		(start 116.152168 -217.554048)
		(mid 116.354454 -217.355067)
		(end 116.434616 -217.082878)
		(width 0.0889)
		(layer "In4.Cu")
		(net "UPI_CPU1_CPU0_P1P0_DN<19>")
	)
	(segment
		(start 116.809266 -217.06459)
		(end 116.809012 -217.064336)
		(width 0.13208)
		(layer "F.Cu")
		(net "UPI_CPU1_CPU0_P1P0_DN<18>")
	)
	(segment
		(start 116.809266 -217.600276)
		(end 116.809266 -217.06459)
		(width 0.13208)
		(layer "F.Cu")
		(net "UPI_CPU1_CPU0_P1P0_DN<18>")
	)
	(segment
		(start 354.411534 -219.228162)
		(end 354.411534 -218.692476)
		(width 0.13208)
		(layer "F.Cu")
		(net "UPI_CPU1_CPU0_P1P0_DN<18>")
	)
	(segment
		(start 354.411534 -218.692476)
		(end 354.41128 -218.692222)
		(width 0.13208)
		(layer "F.Cu")
		(net "UPI_CPU1_CPU0_P1P0_DN<18>")
	)
	(segment
		(start 211.200492 -173.82744)
		(end 238.276384 -173.82744)
		(width 0.14732)
		(layer "In4.Cu")
		(net "UPI_CPU1_CPU0_P1P0_DN<18>")
	)
	(segment
		(start 354.114354 -212.027262)
		(end 354.114354 -212.328506)
		(width 0.14732)
		(layer "In4.Cu")
		(net "UPI_CPU1_CPU0_P1P0_DN<18>")
	)
	(segment
		(start 354.226876 -215.762586)
		(end 354.230178 -215.764618)
		(width 0.0889)
		(layer "In4.Cu")
		(net "UPI_CPU1_CPU0_P1P0_DN<18>")
	)
	(segment
		(start 354.224336 -216.739978)
		(end 354.223574 -216.740486)
		(width 0.0889)
		(layer "In4.Cu")
		(net "UPI_CPU1_CPU0_P1P0_DN<18>")
	)
	(segment
		(start 354.506784 -216.25052)
		(end 354.506784 -216.260426)
		(width 0.0889)
		(layer "In4.Cu")
		(net "UPI_CPU1_CPU0_P1P0_DN<18>")
	)
	(segment
		(start 132.005324 -188.990732)
		(end 135.198866 -186.868054)
		(width 0.14732)
		(layer "In4.Cu")
		(net "UPI_CPU1_CPU0_P1P0_DN<18>")
	)
	(segment
		(start 117.183916 -213.786212)
		(end 117.183916 -212.114638)
		(width 0.0889)
		(layer "In4.Cu")
		(net "UPI_CPU1_CPU0_P1P0_DN<18>")
	)
	(segment
		(start 128.811782 -191.11341)
		(end 132.00507 -188.990732)
		(width 0.14732)
		(layer "In4.Cu")
		(net "UPI_CPU1_CPU0_P1P0_DN<18>")
	)
	(segment
		(start 116.984018 -216.732358)
		(end 116.983256 -216.73185)
		(width 0.0889)
		(layer "In4.Cu")
		(net "UPI_CPU1_CPU0_P1P0_DN<18>")
	)
	(segment
		(start 354.03663 -213.8934)
		(end 354.036884 -213.893908)
		(width 0.0889)
		(layer "In4.Cu")
		(net "UPI_CPU1_CPU0_P1P0_DN<18>")
	)
	(segment
		(start 139.22756 -181.460902)
		(end 150.418292 -175.730916)
		(width 0.14732)
		(layer "In4.Cu")
		(net "UPI_CPU1_CPU0_P1P0_DN<18>")
	)
	(segment
		(start 342.669876 -186.480704)
		(end 345.216226 -190.096648)
		(width 0.14732)
		(layer "In4.Cu")
		(net "UPI_CPU1_CPU0_P1P0_DN<18>")
	)
	(segment
		(start 117.142006 -211.585302)
		(end 117.141752 -211.585048)
		(width 0.14732)
		(layer "In4.Cu")
		(net "UPI_CPU1_CPU0_P1P0_DN<18>")
	)
	(segment
		(start 117.141752 -211.585048)
		(end 117.141752 -210.827112)
		(width 0.14732)
		(layer "In4.Cu")
		(net "UPI_CPU1_CPU0_P1P0_DN<18>")
	)
	(segment
		(start 337.405218 -181.732682)
		(end 338.988908 -182.79999)
		(width 0.14732)
		(layer "In4.Cu")
		(net "UPI_CPU1_CPU0_P1P0_DN<18>")
	)
	(segment
		(start 354.278946 -218.33205)
		(end 354.254816 -218.421204)
		(width 0.0889)
		(layer "In4.Cu")
		(net "UPI_CPU1_CPU0_P1P0_DN<18>")
	)
	(segment
		(start 354.07219 -212.95868)
		(end 354.03663 -213.044532)
		(width 0.0889)
		(layer "In4.Cu")
		(net "UPI_CPU1_CPU0_P1P0_DN<18>")
	)
	(segment
		(start 117.183916 -215.446864)
		(end 117.183916 -215.436704)
		(width 0.0889)
		(layer "In4.Cu")
		(net "UPI_CPU1_CPU0_P1P0_DN<18>")
	)
	(segment
		(start 318.086486 -174.45609)
		(end 330.383388 -178.758088)
		(width 0.14732)
		(layer "In4.Cu")
		(net "UPI_CPU1_CPU0_P1P0_DN<18>")
	)
	(segment
		(start 354.114354 -212.328506)
		(end 354.114354 -212.350604)
		(width 0.0889)
		(layer "In4.Cu")
		(net "UPI_CPU1_CPU0_P1P0_DN<18>")
	)
	(segment
		(start 345.216226 -190.096648)
		(end 351.280476 -196.311012)
		(width 0.14732)
		(layer "In4.Cu")
		(net "UPI_CPU1_CPU0_P1P0_DN<18>")
	)
	(segment
		(start 354.506784 -217.859864)
		(end 354.506784 -217.878406)
		(width 0.0889)
		(layer "In4.Cu")
		(net "UPI_CPU1_CPU0_P1P0_DN<18>")
	)
	(segment
		(start 117.001544 -216.742772)
		(end 116.984018 -216.732358)
		(width 0.0889)
		(layer "In4.Cu")
		(net "UPI_CPU1_CPU0_P1P0_DN<18>")
	)
	(segment
		(start 117.234462 -213.998048)
		(end 117.212872 -213.942422)
		(width 0.0889)
		(layer "In4.Cu")
		(net "UPI_CPU1_CPU0_P1P0_DN<18>")
	)
	(segment
		(start 238.276384 -173.82744)
		(end 273.087338 -173.662594)
		(width 0.14732)
		(layer "In4.Cu")
		(net "UPI_CPU1_CPU0_P1P0_DN<18>")
	)
	(segment
		(start 117.45595 -214.953596)
		(end 117.466618 -214.947246)
		(width 0.0889)
		(layer "In4.Cu")
		(net "UPI_CPU1_CPU0_P1P0_DN<18>")
	)
	(segment
		(start 302.485044 -172.947838)
		(end 313.414918 -173.151038)
		(width 0.14732)
		(layer "In4.Cu")
		(net "UPI_CPU1_CPU0_P1P0_DN<18>")
	)
	(segment
		(start 354.215446 -217.383614)
		(end 354.224336 -217.388694)
		(width 0.0889)
		(layer "In4.Cu")
		(net "UPI_CPU1_CPU0_P1P0_DN<18>")
	)
	(segment
		(start 116.986304 -215.767412)
		(end 116.996972 -215.761062)
		(width 0.0889)
		(layer "In4.Cu")
		(net "UPI_CPU1_CPU0_P1P0_DN<18>")
	)
	(segment
		(start 354.215192 -215.755982)
		(end 354.222558 -215.7603)
		(width 0.0889)
		(layer "In4.Cu")
		(net "UPI_CPU1_CPU0_P1P0_DN<18>")
	)
	(segment
		(start 354.03663 -213.044532)
		(end 354.03663 -213.8934)
		(width 0.0889)
		(layer "In4.Cu")
		(net "UPI_CPU1_CPU0_P1P0_DN<18>")
	)
	(segment
		(start 117.142006 -212.05063)
		(end 117.142006 -211.585302)
		(width 0.14732)
		(layer "In4.Cu")
		(net "UPI_CPU1_CPU0_P1P0_DN<18>")
	)
	(segment
		(start 354.61956 -209.675984)
		(end 354.1141 -210.896454)
		(width 0.14732)
		(layer "In4.Cu")
		(net "UPI_CPU1_CPU0_P1P0_DN<18>")
	)
	(segment
		(start 302.47336 -172.947838)
		(end 302.479202 -172.947584)
		(width 0.14732)
		(layer "In4.Cu")
		(net "UPI_CPU1_CPU0_P1P0_DN<18>")
	)
	(segment
		(start 117.183916 -212.114638)
		(end 117.142006 -212.072728)
		(width 0.0889)
		(layer "In4.Cu")
		(net "UPI_CPU1_CPU0_P1P0_DN<18>")
	)
	(segment
		(start 117.141752 -210.827112)
		(end 120.43537 -201.419206)
		(width 0.14732)
		(layer "In4.Cu")
		(net "UPI_CPU1_CPU0_P1P0_DN<18>")
	)
	(segment
		(start 273.087338 -173.662594)
		(end 302.47336 -172.947838)
		(width 0.14732)
		(layer "In4.Cu")
		(net "UPI_CPU1_CPU0_P1P0_DN<18>")
	)
	(segment
		(start 117.653308 -214.640668)
		(end 117.653054 -214.501222)
		(width 0.0889)
		(layer "In4.Cu")
		(net "UPI_CPU1_CPU0_P1P0_DN<18>")
	)
	(segment
		(start 313.414918 -173.151038)
		(end 318.086486 -174.45609)
		(width 0.14732)
		(layer "In4.Cu")
		(net "UPI_CPU1_CPU0_P1P0_DN<18>")
	)
	(segment
		(start 354.222558 -215.7603)
		(end 354.224082 -215.761062)
		(width 0.0889)
		(layer "In4.Cu")
		(net "UPI_CPU1_CPU0_P1P0_DN<18>")
	)
	(segment
		(start 302.479202 -172.947584)
		(end 302.48479 -172.947584)
		(width 0.14732)
		(layer "In4.Cu")
		(net "UPI_CPU1_CPU0_P1P0_DN<18>")
	)
	(segment
		(start 117.18417 -215.415114)
		(end 117.18417 -215.414606)
		(width 0.0889)
		(layer "In4.Cu")
		(net "UPI_CPU1_CPU0_P1P0_DN<18>")
	)
	(segment
		(start 302.48479 -172.947584)
		(end 302.485044 -172.947838)
		(width 0.14732)
		(layer "In4.Cu")
		(net "UPI_CPU1_CPU0_P1P0_DN<18>")
	)
	(segment
		(start 354.254816 -218.421204)
		(end 354.41128 -218.692222)
		(width 0.0889)
		(layer "In4.Cu")
		(net "UPI_CPU1_CPU0_P1P0_DN<18>")
	)
	(segment
		(start 120.43537 -201.419206)
		(end 128.811782 -191.11341)
		(width 0.14732)
		(layer "In4.Cu")
		(net "UPI_CPU1_CPU0_P1P0_DN<18>")
	)
	(segment
		(start 354.224082 -215.112346)
		(end 354.223066 -215.112854)
		(width 0.0889)
		(layer "In4.Cu")
		(net "UPI_CPU1_CPU0_P1P0_DN<18>")
	)
	(segment
		(start 117.18417 -217.075766)
		(end 117.18417 -217.064336)
		(width 0.0889)
		(layer "In4.Cu")
		(net "UPI_CPU1_CPU0_P1P0_DN<18>")
	)
	(segment
		(start 354.218494 -216.74328)
		(end 354.215446 -216.745058)
		(width 0.0889)
		(layer "In4.Cu")
		(net "UPI_CPU1_CPU0_P1P0_DN<18>")
	)
	(segment
		(start 351.280476 -196.311012)
		(end 354.61956 -204.372718)
		(width 0.14732)
		(layer "In4.Cu")
		(net "UPI_CPU1_CPU0_P1P0_DN<18>")
	)
	(segment
		(start 200.786492 -173.37024)
		(end 211.200492 -173.82744)
		(width 0.14732)
		(layer "In4.Cu")
		(net "UPI_CPU1_CPU0_P1P0_DN<18>")
	)
	(segment
		(start 338.988908 -182.79999)
		(end 342.669876 -186.480704)
		(width 0.14732)
		(layer "In4.Cu")
		(net "UPI_CPU1_CPU0_P1P0_DN<18>")
	)
	(segment
		(start 330.383388 -178.758088)
		(end 337.405218 -181.732682)
		(width 0.14732)
		(layer "In4.Cu")
		(net "UPI_CPU1_CPU0_P1P0_DN<18>")
	)
	(segment
		(start 117.653054 -214.501222)
		(end 117.653054 -214.500714)
		(width 0.0889)
		(layer "In4.Cu")
		(net "UPI_CPU1_CPU0_P1P0_DN<18>")
	)
	(segment
		(start 116.965476 -217.335354)
		(end 117.043708 -217.356182)
		(width 0.0889)
		(layer "In4.Cu")
		(net "UPI_CPU1_CPU0_P1P0_DN<18>")
	)
	(segment
		(start 354.224082 -215.761062)
		(end 354.226876 -215.762586)
		(width 0.0889)
		(layer "In4.Cu")
		(net "UPI_CPU1_CPU0_P1P0_DN<18>")
	)
	(segment
		(start 117.043708 -217.356182)
		(end 117.044216 -217.356944)
		(width 0.0889)
		(layer "In4.Cu")
		(net "UPI_CPU1_CPU0_P1P0_DN<18>")
	)
	(segment
		(start 150.418292 -175.730916)
		(end 156.790136 -174.10049)
		(width 0.14732)
		(layer "In4.Cu")
		(net "UPI_CPU1_CPU0_P1P0_DN<18>")
	)
	(segment
		(start 354.61956 -204.372718)
		(end 354.61956 -209.675984)
		(width 0.14732)
		(layer "In4.Cu")
		(net "UPI_CPU1_CPU0_P1P0_DN<18>")
	)
	(segment
		(start 354.223574 -216.740486)
		(end 354.218494 -216.74328)
		(width 0.0889)
		(layer "In4.Cu")
		(net "UPI_CPU1_CPU0_P1P0_DN<18>")
	)
	(segment
		(start 156.790136 -174.10049)
		(end 200.786492 -173.37024)
		(width 0.14732)
		(layer "In4.Cu")
		(net "UPI_CPU1_CPU0_P1P0_DN<18>")
	)
	(segment
		(start 354.1141 -210.896454)
		(end 354.1141 -212.027008)
		(width 0.14732)
		(layer "In4.Cu")
		(net "UPI_CPU1_CPU0_P1P0_DN<18>")
	)
	(segment
		(start 135.198866 -186.868054)
		(end 139.22756 -181.460902)
		(width 0.14732)
		(layer "In4.Cu")
		(net "UPI_CPU1_CPU0_P1P0_DN<18>")
	)
	(segment
		(start 132.00507 -188.990732)
		(end 132.005324 -188.990732)
		(width 0.14732)
		(layer "In4.Cu")
		(net "UPI_CPU1_CPU0_P1P0_DN<18>")
	)
	(segment
		(start 354.1141 -212.027008)
		(end 354.114354 -212.027262)
		(width 0.14732)
		(layer "In4.Cu")
		(net "UPI_CPU1_CPU0_P1P0_DN<18>")
	)
	(segment
		(start 117.142006 -212.072728)
		(end 117.142006 -212.05063)
		(width 0.0889)
		(layer "In4.Cu")
		(net "UPI_CPU1_CPU0_P1P0_DN<18>")
	)
	(segment
		(start 354.223066 -215.112854)
		(end 354.215192 -215.117426)
		(width 0.0889)
		(layer "In4.Cu")
		(net "UPI_CPU1_CPU0_P1P0_DN<18>")
	)
	(segment
		(start 116.809012 -217.064336)
		(end 116.965476 -217.335354)
		(width 0.0889)
		(layer "In4.Cu")
		(net "UPI_CPU1_CPU0_P1P0_DN<18>")
	)
	(segment
		(start 354.114354 -212.350604)
		(end 354.07219 -212.392768)
		(width 0.0889)
		(layer "In4.Cu")
		(net "UPI_CPU1_CPU0_P1P0_DN<18>")
	)
	(segment
		(start 354.07219 -212.392768)
		(end 354.07219 -212.95868)
		(width 0.0889)
		(layer "In4.Cu")
		(net "UPI_CPU1_CPU0_P1P0_DN<18>")
	)
	(segment
		(start 354.506276 -214.424768)
		(end 354.506276 -214.644732)
		(width 0.0889)
		(layer "In4.Cu")
		(net "UPI_CPU1_CPU0_P1P0_DN<18>")
	)
	(arc
		(start 116.714524 -216.23528)
		(mid 116.790766 -215.966693)
		(end 116.986304 -215.767412)
		(width 0.0889)
		(layer "In4.Cu")
		(net "UPI_CPU1_CPU0_P1P0_DN<18>")
	)
	(arc
		(start 354.036884 -213.893908)
		(mid 354.111889 -214.009367)
		(end 354.221034 -214.093298)
		(width 0.0889)
		(layer "In4.Cu")
		(net "UPI_CPU1_CPU0_P1P0_DN<18>")
	)
	(arc
		(start 116.996972 -215.761062)
		(mid 117.131346 -215.628291)
		(end 117.183916 -215.446864)
		(width 0.0889)
		(layer "In4.Cu")
		(net "UPI_CPU1_CPU0_P1P0_DN<18>")
	)
	(arc
		(start 117.044216 -217.356944)
		(mid 117.144973 -217.231688)
		(end 117.18417 -217.075766)
		(width 0.0889)
		(layer "In4.Cu")
		(net "UPI_CPU1_CPU0_P1P0_DN<18>")
	)
	(arc
		(start 354.221034 -214.093298)
		(mid 354.394997 -214.232062)
		(end 354.506276 -214.424768)
		(width 0.0889)
		(layer "In4.Cu")
		(net "UPI_CPU1_CPU0_P1P0_DN<18>")
	)
	(arc
		(start 354.506784 -216.260426)
		(mid 354.428673 -216.537375)
		(end 354.224336 -216.739978)
		(width 0.0889)
		(layer "In4.Cu")
		(net "UPI_CPU1_CPU0_P1P0_DN<18>")
	)
	(arc
		(start 117.18417 -215.414606)
		(mid 117.262059 -215.149919)
		(end 117.45595 -214.953596)
		(width 0.0889)
		(layer "In4.Cu")
		(net "UPI_CPU1_CPU0_P1P0_DN<18>")
	)
	(arc
		(start 117.466618 -214.947246)
		(mid 117.599025 -214.817741)
		(end 117.653308 -214.640668)
		(width 0.0889)
		(layer "In4.Cu")
		(net "UPI_CPU1_CPU0_P1P0_DN<18>")
	)
	(arc
		(start 354.215192 -215.117426)
		(mid 354.087938 -215.247392)
		(end 354.036884 -215.421972)
		(width 0.0889)
		(layer "In4.Cu")
		(net "UPI_CPU1_CPU0_P1P0_DN<18>")
	)
	(arc
		(start 354.295964 -218.318842)
		(mid 354.287518 -218.325527)
		(end 354.278946 -218.33205)
		(width 0.0889)
		(layer "In4.Cu")
		(net "UPI_CPU1_CPU0_P1P0_DN<18>")
	)
	(arc
		(start 117.212872 -213.942422)
		(mid 117.191114 -213.865667)
		(end 117.183916 -213.786212)
		(width 0.0889)
		(layer "In4.Cu")
		(net "UPI_CPU1_CPU0_P1P0_DN<18>")
	)
	(arc
		(start 354.036884 -215.421972)
		(mid 354.036687 -215.429337)
		(end 354.03663 -215.436704)
		(width 0.0889)
		(layer "In4.Cu")
		(net "UPI_CPU1_CPU0_P1P0_DN<18>")
	)
	(arc
		(start 354.506784 -217.878406)
		(mid 354.451429 -218.122593)
		(end 354.295964 -218.318842)
		(width 0.0889)
		(layer "In4.Cu")
		(net "UPI_CPU1_CPU0_P1P0_DN<18>")
	)
	(arc
		(start 117.630194 -214.41537)
		(mid 117.560485 -214.327355)
		(end 117.469412 -214.2617)
		(width 0.0889)
		(layer "In4.Cu")
		(net "UPI_CPU1_CPU0_P1P0_DN<18>")
	)
	(arc
		(start 117.469412 -214.2617)
		(mid 117.328175 -214.151046)
		(end 117.234462 -213.998048)
		(width 0.0889)
		(layer "In4.Cu")
		(net "UPI_CPU1_CPU0_P1P0_DN<18>")
	)
	(arc
		(start 116.983256 -216.73185)
		(mid 116.789843 -216.532843)
		(end 116.714524 -216.26576)
		(width 0.0889)
		(layer "In4.Cu")
		(net "UPI_CPU1_CPU0_P1P0_DN<18>")
	)
	(arc
		(start 354.506276 -214.644732)
		(mid 354.425365 -214.91486)
		(end 354.224082 -215.112346)
		(width 0.0889)
		(layer "In4.Cu")
		(net "UPI_CPU1_CPU0_P1P0_DN<18>")
	)
	(arc
		(start 354.230178 -215.764618)
		(mid 354.432765 -215.970969)
		(end 354.506784 -216.25052)
		(width 0.0889)
		(layer "In4.Cu")
		(net "UPI_CPU1_CPU0_P1P0_DN<18>")
	)
	(arc
		(start 354.215446 -216.745058)
		(mid 354.036849 -217.064336)
		(end 354.215446 -217.383614)
		(width 0.0889)
		(layer "In4.Cu")
		(net "UPI_CPU1_CPU0_P1P0_DN<18>")
	)
	(arc
		(start 117.183916 -215.436704)
		(mid 117.183941 -215.425908)
		(end 117.18417 -215.415114)
		(width 0.0889)
		(layer "In4.Cu")
		(net "UPI_CPU1_CPU0_P1P0_DN<18>")
	)
	(arc
		(start 354.03663 -215.436704)
		(mid 354.084309 -215.619604)
		(end 354.215192 -215.755982)
		(width 0.0889)
		(layer "In4.Cu")
		(net "UPI_CPU1_CPU0_P1P0_DN<18>")
	)
	(arc
		(start 354.224336 -217.388694)
		(mid 354.426622 -217.587675)
		(end 354.506784 -217.859864)
		(width 0.0889)
		(layer "In4.Cu")
		(net "UPI_CPU1_CPU0_P1P0_DN<18>")
	)
	(arc
		(start 116.714524 -216.26576)
		(mid 116.714318 -216.25052)
		(end 116.714524 -216.23528)
		(width 0.0889)
		(layer "In4.Cu")
		(net "UPI_CPU1_CPU0_P1P0_DN<18>")
	)
	(arc
		(start 117.18417 -217.064336)
		(mid 117.135273 -216.879462)
		(end 117.001544 -216.742772)
		(width 0.0889)
		(layer "In4.Cu")
		(net "UPI_CPU1_CPU0_P1P0_DN<18>")
	)
	(arc
		(start 117.653054 -214.500714)
		(mid 117.647315 -214.456515)
		(end 117.630194 -214.41537)
		(width 0.0889)
		(layer "In4.Cu")
		(net "UPI_CPU1_CPU0_P1P0_DN<18>")
	)
	(segment
		(start 353.00158 -218.414346)
		(end 353.00158 -217.87866)
		(width 0.13208)
		(layer "F.Cu")
		(net "UPI_CPU1_CPU0_P1P0_DN<17>")
	)
	(segment
		(start 118.218712 -217.87866)
		(end 118.218966 -217.878406)
		(width 0.13208)
		(layer "F.Cu")
		(net "UPI_CPU1_CPU0_P1P0_DN<17>")
	)
	(segment
		(start 118.218712 -218.414346)
		(end 118.218712 -217.87866)
		(width 0.13208)
		(layer "F.Cu")
		(net "UPI_CPU1_CPU0_P1P0_DN<17>")
	)
	(segment
		(start 353.00158 -217.87866)
		(end 353.001834 -217.878406)
		(width 0.13208)
		(layer "F.Cu")
		(net "UPI_CPU1_CPU0_P1P0_DN<17>")
	)
	(segment
		(start 119.65432 -207.05826)
		(end 119.654066 -207.058006)
		(width 0.14732)
		(layer "In4.Cu")
		(net "UPI_CPU1_CPU0_P1P0_DN<17>")
	)
	(segment
		(start 118.355872 -211.585048)
		(end 118.355872 -210.787488)
		(width 0.14732)
		(layer "In4.Cu")
		(net "UPI_CPU1_CPU0_P1P0_DN<17>")
	)
	(segment
		(start 119.654066 -207.058006)
		(end 119.65432 -207.058006)
		(width 0.14732)
		(layer "In4.Cu")
		(net "UPI_CPU1_CPU0_P1P0_DN<17>")
	)
	(segment
		(start 121.173494 -203.064618)
		(end 121.098564 -202.909424)
		(width 0.14732)
		(layer "In4.Cu")
		(net "UPI_CPU1_CPU0_P1P0_DN<17>")
	)
	(segment
		(start 118.062502 -218.149424)
		(end 117.98427 -218.170252)
		(width 0.0889)
		(layer "In4.Cu")
		(net "UPI_CPU1_CPU0_P1P0_DN<17>")
	)
	(segment
		(start 352.906838 -212.604604)
		(end 352.906838 -213.929468)
		(width 0.0889)
		(layer "In4.Cu")
		(net "UPI_CPU1_CPU0_P1P0_DN<17>")
	)
	(segment
		(start 119.349266 -208.305146)
		(end 119.274082 -208.149952)
		(width 0.14732)
		(layer "In4.Cu")
		(net "UPI_CPU1_CPU0_P1P0_DN<17>")
	)
	(segment
		(start 120.874536 -203.552552)
		(end 121.029984 -203.477368)
		(width 0.14732)
		(layer "In4.Cu")
		(net "UPI_CPU1_CPU0_P1P0_DN<17>")
	)
	(segment
		(start 118.492524 -215.117426)
		(end 118.501414 -215.112346)
		(width 0.0889)
		(layer "In4.Cu")
		(net "UPI_CPU1_CPU0_P1P0_DN<17>")
	)
	(segment
		(start 352.999294 -212.087968)
		(end 353.041204 -212.129878)
		(width 0.0889)
		(layer "In4.Cu")
		(net "UPI_CPU1_CPU0_P1P0_DN<17>")
	)
	(segment
		(start 353.197922 -216.569798)
		(end 353.190556 -216.574116)
		(width 0.0889)
		(layer "In4.Cu")
		(net "UPI_CPU1_CPU0_P1P0_DN<17>")
	)
	(segment
		(start 118.031768 -216.574878)
		(end 118.022878 -216.569798)
		(width 0.0889)
		(layer "In4.Cu")
		(net "UPI_CPU1_CPU0_P1P0_DN<17>")
	)
	(segment
		(start 353.197414 -214.941912)
		(end 353.188524 -214.946992)
		(width 0.0889)
		(layer "In4.Cu")
		(net "UPI_CPU1_CPU0_P1P0_DN<17>")
	)
	(segment
		(start 341.799672 -187.183014)
		(end 344.414856 -190.896494)
		(width 0.14732)
		(layer "In4.Cu")
		(net "UPI_CPU1_CPU0_P1P0_DN<17>")
	)
	(segment
		(start 352.906838 -213.929468)
		(end 352.906584 -213.929722)
		(width 0.0889)
		(layer "In4.Cu")
		(net "UPI_CPU1_CPU0_P1P0_DN<17>")
	)
	(segment
		(start 120.731026 -203.965048)
		(end 120.874536 -203.552552)
		(width 0.14732)
		(layer "In4.Cu")
		(net "UPI_CPU1_CPU0_P1P0_DN<17>")
	)
	(segment
		(start 118.314216 -217.082878)
		(end 118.314216 -217.05443)
		(width 0.0889)
		(layer "In4.Cu")
		(net "UPI_CPU1_CPU0_P1P0_DN<17>")
	)
	(segment
		(start 118.413022 -212.72246)
		(end 118.413022 -212.5472)
		(width 0.0889)
		(layer "In4.Cu")
		(net "UPI_CPU1_CPU0_P1P0_DN<17>")
	)
	(segment
		(start 119.72925 -207.213454)
		(end 119.65432 -207.05826)
		(width 0.14732)
		(layer "In4.Cu")
		(net "UPI_CPU1_CPU0_P1P0_DN<17>")
	)
	(segment
		(start 353.186238 -216.576402)
		(end 353.182936 -216.578434)
		(width 0.0889)
		(layer "In4.Cu")
		(net "UPI_CPU1_CPU0_P1P0_DN<17>")
	)
	(segment
		(start 352.99904 -211.813648)
		(end 352.999294 -211.813902)
		(width 0.14732)
		(layer "In4.Cu")
		(net "UPI_CPU1_CPU0_P1P0_DN<17>")
	)
	(segment
		(start 121.029984 -203.477368)
		(end 121.173494 -203.064618)
		(width 0.14732)
		(layer "In4.Cu")
		(net "UPI_CPU1_CPU0_P1P0_DN<17>")
	)
	(segment
		(start 344.414856 -190.896494)
		(end 350.341946 -196.971158)
		(width 0.14732)
		(layer "In4.Cu")
		(net "UPI_CPU1_CPU0_P1P0_DN<17>")
	)
	(segment
		(start 350.341946 -196.971158)
		(end 353.32924 -204.182472)
		(width 0.14732)
		(layer "In4.Cu")
		(net "UPI_CPU1_CPU0_P1P0_DN<17>")
	)
	(segment
		(start 120.662446 -204.532992)
		(end 120.80621 -204.120242)
		(width 0.14732)
		(layer "In4.Cu")
		(net "UPI_CPU1_CPU0_P1P0_DN<17>")
	)
	(segment
		(start 138.154156 -184.771792)
		(end 139.965684 -182.34025)
		(width 0.14732)
		(layer "In4.Cu")
		(net "UPI_CPU1_CPU0_P1P0_DN<17>")
	)
	(segment
		(start 353.32924 -208.79943)
		(end 353.18446 -208.94421)
		(width 0.14732)
		(layer "In4.Cu")
		(net "UPI_CPU1_CPU0_P1P0_DN<17>")
	)
	(segment
		(start 120.80621 -204.120242)
		(end 120.731026 -203.965048)
		(width 0.14732)
		(layer "In4.Cu")
		(net "UPI_CPU1_CPU0_P1P0_DN<17>")
	)
	(segment
		(start 120.506998 -204.608176)
		(end 120.662446 -204.532992)
		(width 0.14732)
		(layer "In4.Cu")
		(net "UPI_CPU1_CPU0_P1P0_DN<17>")
	)
	(segment
		(start 353.158298 -217.607388)
		(end 353.001834 -217.878406)
		(width 0.0889)
		(layer "In4.Cu")
		(net "UPI_CPU1_CPU0_P1P0_DN<17>")
	)
	(segment
		(start 118.356126 -211.585302)
		(end 118.355872 -211.585048)
		(width 0.14732)
		(layer "In4.Cu")
		(net "UPI_CPU1_CPU0_P1P0_DN<17>")
	)
	(segment
		(start 338.252562 -183.635904)
		(end 341.799672 -187.183014)
		(width 0.14732)
		(layer "In4.Cu")
		(net "UPI_CPU1_CPU0_P1P0_DN<17>")
	)
	(segment
		(start 118.356126 -212.072728)
		(end 118.356126 -212.05063)
		(width 0.0889)
		(layer "In4.Cu")
		(net "UPI_CPU1_CPU0_P1P0_DN<17>")
	)
	(segment
		(start 150.445216 -176.974246)
		(end 153.896822 -176.091088)
		(width 0.14732)
		(layer "In4.Cu")
		(net "UPI_CPU1_CPU0_P1P0_DN<17>")
	)
	(segment
		(start 273.103848 -174.779432)
		(end 302.48225 -174.065184)
		(width 0.14732)
		(layer "In4.Cu")
		(net "UPI_CPU1_CPU0_P1P0_DN<17>")
	)
	(segment
		(start 135.996934 -187.6679)
		(end 138.15441 -184.771792)
		(width 0.14732)
		(layer "In4.Cu")
		(net "UPI_CPU1_CPU0_P1P0_DN<17>")
	)
	(segment
		(start 118.413022 -212.5472)
		(end 118.313962 -212.44814)
		(width 0.0889)
		(layer "In4.Cu")
		(net "UPI_CPU1_CPU0_P1P0_DN<17>")
	)
	(segment
		(start 153.896822 -176.091088)
		(end 153.897076 -176.090834)
		(width 0.14732)
		(layer "In4.Cu")
		(net "UPI_CPU1_CPU0_P1P0_DN<17>")
	)
	(segment
		(start 352.999294 -212.06587)
		(end 352.999294 -212.087968)
		(width 0.0889)
		(layer "In4.Cu")
		(net "UPI_CPU1_CPU0_P1P0_DN<17>")
	)
	(segment
		(start 353.18446 -209.31251)
		(end 353.32924 -209.45729)
		(width 0.14732)
		(layer "In4.Cu")
		(net "UPI_CPU1_CPU0_P1P0_DN<17>")
	)
	(segment
		(start 353.189032 -215.926162)
		(end 353.190556 -215.926924)
		(width 0.0889)
		(layer "In4.Cu")
		(net "UPI_CPU1_CPU0_P1P0_DN<17>")
	)
	(segment
		(start 313.271662 -174.265844)
		(end 317.774828 -175.523652)
		(width 0.14732)
		(layer "In4.Cu")
		(net "UPI_CPU1_CPU0_P1P0_DN<17>")
	)
	(segment
		(start 353.041204 -212.470238)
		(end 352.906838 -212.604604)
		(width 0.0889)
		(layer "In4.Cu")
		(net "UPI_CPU1_CPU0_P1P0_DN<17>")
	)
	(segment
		(start 118.355872 -210.787488)
		(end 119.0498 -208.794096)
		(width 0.14732)
		(layer "In4.Cu")
		(net "UPI_CPU1_CPU0_P1P0_DN<17>")
	)
	(segment
		(start 153.897076 -176.090834)
		(end 157.34919 -175.207422)
		(width 0.14732)
		(layer "In4.Cu")
		(net "UPI_CPU1_CPU0_P1P0_DN<17>")
	)
	(segment
		(start 118.313962 -212.114892)
		(end 118.356126 -212.072728)
		(width 0.0889)
		(layer "In4.Cu")
		(net "UPI_CPU1_CPU0_P1P0_DN<17>")
	)
	(segment
		(start 353.041204 -212.129878)
		(end 353.041204 -212.470238)
		(width 0.0889)
		(layer "In4.Cu")
		(net "UPI_CPU1_CPU0_P1P0_DN<17>")
	)
	(segment
		(start 118.313962 -213.834726)
		(end 118.313962 -213.40318)
		(width 0.0889)
		(layer "In4.Cu")
		(net "UPI_CPU1_CPU0_P1P0_DN<17>")
	)
	(segment
		(start 353.32924 -209.45729)
		(end 353.32924 -209.82559)
		(width 0.14732)
		(layer "In4.Cu")
		(net "UPI_CPU1_CPU0_P1P0_DN<17>")
	)
	(segment
		(start 118.313962 -212.82152)
		(end 118.413022 -212.72246)
		(width 0.0889)
		(layer "In4.Cu")
		(net "UPI_CPU1_CPU0_P1P0_DN<17>")
	)
	(segment
		(start 138.15441 -184.771792)
		(end 138.154156 -184.771792)
		(width 0.14732)
		(layer "In4.Cu")
		(net "UPI_CPU1_CPU0_P1P0_DN<17>")
	)
	(segment
		(start 352.99904 -210.622896)
		(end 352.99904 -211.813648)
		(width 0.14732)
		(layer "In4.Cu")
		(net "UPI_CPU1_CPU0_P1P0_DN<17>")
	)
	(segment
		(start 119.050054 -208.79308)
		(end 119.205502 -208.717896)
		(width 0.14732)
		(layer "In4.Cu")
		(net "UPI_CPU1_CPU0_P1P0_DN<17>")
	)
	(segment
		(start 353.182936 -215.922606)
		(end 353.18827 -215.925654)
		(width 0.0889)
		(layer "In4.Cu")
		(net "UPI_CPU1_CPU0_P1P0_DN<17>")
	)
	(segment
		(start 139.965684 -182.34025)
		(end 139.965684 -182.339996)
		(width 0.14732)
		(layer "In4.Cu")
		(net "UPI_CPU1_CPU0_P1P0_DN<17>")
	)
	(segment
		(start 352.906584 -213.929722)
		(end 352.906584 -213.930484)
		(width 0.0889)
		(layer "In4.Cu")
		(net "UPI_CPU1_CPU0_P1P0_DN<17>")
	)
	(segment
		(start 353.375976 -214.461344)
		(end 353.375976 -214.622634)
		(width 0.0889)
		(layer "In4.Cu")
		(net "UPI_CPU1_CPU0_P1P0_DN<17>")
	)
	(segment
		(start 121.098564 -202.909424)
		(end 121.307098 -202.309984)
		(width 0.14732)
		(layer "In4.Cu")
		(net "UPI_CPU1_CPU0_P1P0_DN<17>")
	)
	(segment
		(start 118.313962 -215.452198)
		(end 118.313962 -215.436704)
		(width 0.0889)
		(layer "In4.Cu")
		(net "UPI_CPU1_CPU0_P1P0_DN<17>")
	)
	(segment
		(start 353.32924 -207.77327)
		(end 353.18446 -207.91805)
		(width 0.14732)
		(layer "In4.Cu")
		(net "UPI_CPU1_CPU0_P1P0_DN<17>")
	)
	(segment
		(start 119.65432 -207.058006)
		(end 120.506998 -204.608176)
		(width 0.14732)
		(layer "In4.Cu")
		(net "UPI_CPU1_CPU0_P1P0_DN<17>")
	)
	(segment
		(start 353.32924 -204.182472)
		(end 353.32924 -207.77327)
		(width 0.14732)
		(layer "In4.Cu")
		(net "UPI_CPU1_CPU0_P1P0_DN<17>")
	)
	(segment
		(start 353.18446 -207.91805)
		(end 353.18446 -208.28635)
		(width 0.14732)
		(layer "In4.Cu")
		(net "UPI_CPU1_CPU0_P1P0_DN<17>")
	)
	(segment
		(start 353.18827 -215.925654)
		(end 353.189032 -215.926162)
		(width 0.0889)
		(layer "In4.Cu")
		(net "UPI_CPU1_CPU0_P1P0_DN<17>")
	)
	(segment
		(start 352.90633 -215.414606)
		(end 352.90633 -215.436704)
		(width 0.0889)
		(layer "In4.Cu")
		(net "UPI_CPU1_CPU0_P1P0_DN<17>")
	)
	(segment
		(start 119.430292 -207.701388)
		(end 119.58574 -207.626204)
		(width 0.14732)
		(layer "In4.Cu")
		(net "UPI_CPU1_CPU0_P1P0_DN<17>")
	)
	(segment
		(start 119.205502 -208.717896)
		(end 119.349266 -208.305146)
		(width 0.14732)
		(layer "In4.Cu")
		(net "UPI_CPU1_CPU0_P1P0_DN<17>")
	)
	(segment
		(start 336.934302 -182.74665)
		(end 338.252562 -183.635904)
		(width 0.14732)
		(layer "In4.Cu")
		(net "UPI_CPU1_CPU0_P1P0_DN<17>")
	)
	(segment
		(start 121.307098 -202.309984)
		(end 129.93243 -191.69761)
		(width 0.14732)
		(layer "In4.Cu")
		(net "UPI_CPU1_CPU0_P1P0_DN<17>")
	)
	(segment
		(start 238.609632 -174.944278)
		(end 273.103848 -174.779432)
		(width 0.14732)
		(layer "In4.Cu")
		(net "UPI_CPU1_CPU0_P1P0_DN<17>")
	)
	(segment
		(start 118.022878 -215.931242)
		(end 118.031768 -215.926162)
		(width 0.0889)
		(layer "In4.Cu")
		(net "UPI_CPU1_CPU0_P1P0_DN<17>")
	)
	(segment
		(start 119.0498 -208.794096)
		(end 119.050054 -208.79308)
		(width 0.14732)
		(layer "In4.Cu")
		(net "UPI_CPU1_CPU0_P1P0_DN<17>")
	)
	(segment
		(start 118.218966 -217.878406)
		(end 118.062502 -218.149424)
		(width 0.0889)
		(layer "In4.Cu")
		(net "UPI_CPU1_CPU0_P1P0_DN<17>")
	)
	(segment
		(start 119.58574 -207.626204)
		(end 119.72925 -207.213454)
		(width 0.14732)
		(layer "In4.Cu")
		(net "UPI_CPU1_CPU0_P1P0_DN<17>")
	)
	(segment
		(start 118.313962 -213.40318)
		(end 118.413022 -213.30412)
		(width 0.0889)
		(layer "In4.Cu")
		(net "UPI_CPU1_CPU0_P1P0_DN<17>")
	)
	(segment
		(start 118.413022 -213.30412)
		(end 118.413022 -213.12886)
		(width 0.0889)
		(layer "In4.Cu")
		(net "UPI_CPU1_CPU0_P1P0_DN<17>")
	)
	(segment
		(start 139.965684 -182.339996)
		(end 150.445216 -176.974246)
		(width 0.14732)
		(layer "In4.Cu")
		(net "UPI_CPU1_CPU0_P1P0_DN<17>")
	)
	(segment
		(start 118.022878 -217.559128)
		(end 118.031768 -217.554048)
		(width 0.0889)
		(layer "In4.Cu")
		(net "UPI_CPU1_CPU0_P1P0_DN<17>")
	)
	(segment
		(start 118.498366 -214.093298)
		(end 118.498112 -214.093806)
		(width 0.0889)
		(layer "In4.Cu")
		(net "UPI_CPU1_CPU0_P1P0_DN<17>")
	)
	(segment
		(start 119.274082 -208.149952)
		(end 119.430292 -207.701388)
		(width 0.14732)
		(layer "In4.Cu")
		(net "UPI_CPU1_CPU0_P1P0_DN<17>")
	)
	(segment
		(start 200.606152 -174.489364)
		(end 210.970114 -174.944278)
		(width 0.14732)
		(layer "In4.Cu")
		(net "UPI_CPU1_CPU0_P1P0_DN<17>")
	)
	(segment
		(start 317.774828 -175.523652)
		(end 329.917044 -179.770278)
		(width 0.14732)
		(layer "In4.Cu")
		(net "UPI_CPU1_CPU0_P1P0_DN<17>")
	)
	(segment
		(start 353.18446 -208.28635)
		(end 353.32924 -208.43113)
		(width 0.14732)
		(layer "In4.Cu")
		(net "UPI_CPU1_CPU0_P1P0_DN<17>")
	)
	(segment
		(start 353.134168 -217.518234)
		(end 353.158298 -217.607388)
		(width 0.0889)
		(layer "In4.Cu")
		(net "UPI_CPU1_CPU0_P1P0_DN<17>")
	)
	(segment
		(start 118.413022 -213.12886)
		(end 118.313962 -213.0298)
		(width 0.0889)
		(layer "In4.Cu")
		(net "UPI_CPU1_CPU0_P1P0_DN<17>")
	)
	(segment
		(start 353.32924 -208.43113)
		(end 353.32924 -208.79943)
		(width 0.14732)
		(layer "In4.Cu")
		(net "UPI_CPU1_CPU0_P1P0_DN<17>")
	)
	(segment
		(start 353.190556 -216.574116)
		(end 353.189032 -216.574878)
		(width 0.0889)
		(layer "In4.Cu")
		(net "UPI_CPU1_CPU0_P1P0_DN<17>")
	)
	(segment
		(start 157.34919 -175.207422)
		(end 200.606152 -174.489364)
		(width 0.14732)
		(layer "In4.Cu")
		(net "UPI_CPU1_CPU0_P1P0_DN<17>")
	)
	(segment
		(start 353.18446 -208.94421)
		(end 353.18446 -209.31251)
		(width 0.14732)
		(layer "In4.Cu")
		(net "UPI_CPU1_CPU0_P1P0_DN<17>")
	)
	(segment
		(start 353.189032 -216.574878)
		(end 353.186238 -216.576402)
		(width 0.0889)
		(layer "In4.Cu")
		(net "UPI_CPU1_CPU0_P1P0_DN<17>")
	)
	(segment
		(start 129.93243 -191.69761)
		(end 135.996934 -187.6679)
		(width 0.14732)
		(layer "In4.Cu")
		(net "UPI_CPU1_CPU0_P1P0_DN<17>")
	)
	(segment
		(start 118.313962 -212.44814)
		(end 118.313962 -212.114892)
		(width 0.0889)
		(layer "In4.Cu")
		(net "UPI_CPU1_CPU0_P1P0_DN<17>")
	)
	(segment
		(start 210.970114 -174.944278)
		(end 238.609632 -174.944278)
		(width 0.14732)
		(layer "In4.Cu")
		(net "UPI_CPU1_CPU0_P1P0_DN<17>")
	)
	(segment
		(start 302.48225 -174.065184)
		(end 313.271662 -174.265844)
		(width 0.14732)
		(layer "In4.Cu")
		(net "UPI_CPU1_CPU0_P1P0_DN<17>")
	)
	(segment
		(start 352.90633 -217.064336)
		(end 352.90633 -217.07856)
		(width 0.0889)
		(layer "In4.Cu")
		(net "UPI_CPU1_CPU0_P1P0_DN<17>")
	)
	(segment
		(start 118.356126 -212.05063)
		(end 118.356126 -211.585302)
		(width 0.14732)
		(layer "In4.Cu")
		(net "UPI_CPU1_CPU0_P1P0_DN<17>")
	)
	(segment
		(start 118.313962 -213.0298)
		(end 118.313962 -212.82152)
		(width 0.0889)
		(layer "In4.Cu")
		(net "UPI_CPU1_CPU0_P1P0_DN<17>")
	)
	(segment
		(start 118.783608 -214.644732)
		(end 118.783608 -214.424768)
		(width 0.0889)
		(layer "In4.Cu")
		(net "UPI_CPU1_CPU0_P1P0_DN<17>")
	)
	(segment
		(start 353.190556 -215.926924)
		(end 353.197922 -215.931242)
		(width 0.0889)
		(layer "In4.Cu")
		(net "UPI_CPU1_CPU0_P1P0_DN<17>")
	)
	(segment
		(start 329.917044 -179.770278)
		(end 336.934302 -182.74665)
		(width 0.14732)
		(layer "In4.Cu")
		(net "UPI_CPU1_CPU0_P1P0_DN<17>")
	)
	(segment
		(start 353.32924 -209.82559)
		(end 352.99904 -210.622896)
		(width 0.14732)
		(layer "In4.Cu")
		(net "UPI_CPU1_CPU0_P1P0_DN<17>")
	)
	(segment
		(start 352.999294 -211.813902)
		(end 352.999294 -212.06587)
		(width 0.14732)
		(layer "In4.Cu")
		(net "UPI_CPU1_CPU0_P1P0_DN<17>")
	)
	(arc
		(start 353.182936 -216.578434)
		(mid 352.980349 -216.784785)
		(end 352.90633 -217.064336)
		(width 0.0889)
		(layer "In4.Cu")
		(net "UPI_CPU1_CPU0_P1P0_DN<17>")
	)
	(arc
		(start 117.844316 -216.24036)
		(mid 117.894385 -216.063135)
		(end 118.022878 -215.931242)
		(width 0.0889)
		(layer "In4.Cu")
		(net "UPI_CPU1_CPU0_P1P0_DN<17>")
	)
	(arc
		(start 352.90633 -217.07856)
		(mid 352.964624 -217.315203)
		(end 353.11715 -217.50528)
		(width 0.0889)
		(layer "In4.Cu")
		(net "UPI_CPU1_CPU0_P1P0_DN<17>")
	)
	(arc
		(start 118.031768 -217.554048)
		(mid 118.234054 -217.355067)
		(end 118.314216 -217.082878)
		(width 0.0889)
		(layer "In4.Cu")
		(net "UPI_CPU1_CPU0_P1P0_DN<17>")
	)
	(arc
		(start 352.906584 -213.930484)
		(mid 352.913869 -213.950046)
		(end 352.921824 -213.969346)
		(width 0.0889)
		(layer "In4.Cu")
		(net "UPI_CPU1_CPU0_P1P0_DN<17>")
	)
	(arc
		(start 118.36019 -213.975188)
		(mid 118.325811 -213.908664)
		(end 118.313962 -213.834726)
		(width 0.0889)
		(layer "In4.Cu")
		(net "UPI_CPU1_CPU0_P1P0_DN<17>")
	)
	(arc
		(start 118.783608 -214.424768)
		(mid 118.672329 -214.232062)
		(end 118.498366 -214.093298)
		(width 0.0889)
		(layer "In4.Cu")
		(net "UPI_CPU1_CPU0_P1P0_DN<17>")
	)
	(arc
		(start 118.022878 -216.569798)
		(mid 117.893589 -216.436312)
		(end 117.844316 -216.257124)
		(width 0.0889)
		(layer "In4.Cu")
		(net "UPI_CPU1_CPU0_P1P0_DN<17>")
	)
	(arc
		(start 353.188524 -214.946992)
		(mid 352.987242 -215.144479)
		(end 352.90633 -215.414606)
		(width 0.0889)
		(layer "In4.Cu")
		(net "UPI_CPU1_CPU0_P1P0_DN<17>")
	)
	(arc
		(start 118.314216 -217.05443)
		(mid 118.236105 -216.777481)
		(end 118.031768 -216.574878)
		(width 0.0889)
		(layer "In4.Cu")
		(net "UPI_CPU1_CPU0_P1P0_DN<17>")
	)
	(arc
		(start 353.375976 -214.622634)
		(mid 353.328297 -214.805534)
		(end 353.197414 -214.941912)
		(width 0.0889)
		(layer "In4.Cu")
		(net "UPI_CPU1_CPU0_P1P0_DN<17>")
	)
	(arc
		(start 118.314216 -215.421972)
		(mid 118.36527 -215.247392)
		(end 118.492524 -215.117426)
		(width 0.0889)
		(layer "In4.Cu")
		(net "UPI_CPU1_CPU0_P1P0_DN<17>")
	)
	(arc
		(start 117.844316 -216.257124)
		(mid 117.844222 -216.248742)
		(end 117.844316 -216.24036)
		(width 0.0889)
		(layer "In4.Cu")
		(net "UPI_CPU1_CPU0_P1P0_DN<17>")
	)
	(arc
		(start 353.197922 -215.931242)
		(mid 353.376519 -216.25052)
		(end 353.197922 -216.569798)
		(width 0.0889)
		(layer "In4.Cu")
		(net "UPI_CPU1_CPU0_P1P0_DN<17>")
	)
	(arc
		(start 117.844316 -217.878406)
		(mid 117.891995 -217.695506)
		(end 118.022878 -217.559128)
		(width 0.0889)
		(layer "In4.Cu")
		(net "UPI_CPU1_CPU0_P1P0_DN<17>")
	)
	(arc
		(start 352.90633 -215.436704)
		(mid 352.980321 -215.71627)
		(end 353.182936 -215.922606)
		(width 0.0889)
		(layer "In4.Cu")
		(net "UPI_CPU1_CPU0_P1P0_DN<17>")
	)
	(arc
		(start 118.031768 -215.926162)
		(mid 118.234591 -215.725931)
		(end 118.313962 -215.452198)
		(width 0.0889)
		(layer "In4.Cu")
		(net "UPI_CPU1_CPU0_P1P0_DN<17>")
	)
	(arc
		(start 118.501414 -215.112346)
		(mid 118.702696 -214.914859)
		(end 118.783608 -214.644732)
		(width 0.0889)
		(layer "In4.Cu")
		(net "UPI_CPU1_CPU0_P1P0_DN<17>")
	)
	(arc
		(start 352.921824 -213.969346)
		(mid 353.031818 -214.138715)
		(end 353.191826 -214.261954)
		(width 0.0889)
		(layer "In4.Cu")
		(net "UPI_CPU1_CPU0_P1P0_DN<17>")
	)
	(arc
		(start 118.313962 -215.436704)
		(mid 118.314014 -215.429337)
		(end 118.314216 -215.421972)
		(width 0.0889)
		(layer "In4.Cu")
		(net "UPI_CPU1_CPU0_P1P0_DN<17>")
	)
	(arc
		(start 117.98427 -218.170252)
		(mid 117.881125 -218.040227)
		(end 117.844316 -217.878406)
		(width 0.0889)
		(layer "In4.Cu")
		(net "UPI_CPU1_CPU0_P1P0_DN<17>")
	)
	(arc
		(start 353.11715 -217.50528)
		(mid 353.125598 -217.511837)
		(end 353.134168 -217.518234)
		(width 0.0889)
		(layer "In4.Cu")
		(net "UPI_CPU1_CPU0_P1P0_DN<17>")
	)
	(arc
		(start 118.498112 -214.093806)
		(mid 118.422475 -214.042262)
		(end 118.36019 -213.975188)
		(width 0.0889)
		(layer "In4.Cu")
		(net "UPI_CPU1_CPU0_P1P0_DN<17>")
	)
	(arc
		(start 353.191826 -214.261954)
		(mid 353.300973 -214.345882)
		(end 353.375976 -214.461344)
		(width 0.0889)
		(layer "In4.Cu")
		(net "UPI_CPU1_CPU0_P1P0_DN<17>")
	)
	(segment
		(start 118.688866 -217.600276)
		(end 118.688866 -217.06459)
		(width 0.13208)
		(layer "F.Cu")
		(net "UPI_CPU1_CPU0_P1P0_DN<16>")
	)
	(segment
		(start 352.531934 -218.692476)
		(end 352.53168 -218.692222)
		(width 0.13208)
		(layer "F.Cu")
		(net "UPI_CPU1_CPU0_P1P0_DN<16>")
	)
	(segment
		(start 352.531934 -219.228162)
		(end 352.531934 -218.692476)
		(width 0.13208)
		(layer "F.Cu")
		(net "UPI_CPU1_CPU0_P1P0_DN<16>")
	)
	(segment
		(start 118.688866 -217.06459)
		(end 118.688612 -217.064336)
		(width 0.13208)
		(layer "F.Cu")
		(net "UPI_CPU1_CPU0_P1P0_DN<16>")
	)
	(segment
		(start 119.02186 -212.024468)
		(end 119.02186 -212.00237)
		(width 0.0889)
		(layer "In4.Cu")
		(net "UPI_CPU1_CPU0_P1P0_DN<16>")
	)
	(segment
		(start 352.344482 -215.761062)
		(end 352.347276 -215.762586)
		(width 0.0889)
		(layer "In4.Cu")
		(net "UPI_CPU1_CPU0_P1P0_DN<16>")
	)
	(segment
		(start 273.11223 -175.361346)
		(end 302.478186 -174.647606)
		(width 0.14732)
		(layer "In4.Cu")
		(net "UPI_CPU1_CPU0_P1P0_DN<16>")
	)
	(segment
		(start 302.478186 -174.647606)
		(end 302.484028 -174.647352)
		(width 0.14732)
		(layer "In4.Cu")
		(net "UPI_CPU1_CPU0_P1P0_DN<16>")
	)
	(segment
		(start 200.186036 -175.059086)
		(end 210.820762 -175.526192)
		(width 0.14732)
		(layer "In4.Cu")
		(net "UPI_CPU1_CPU0_P1P0_DN<16>")
	)
	(segment
		(start 118.688612 -217.064336)
		(end 118.845076 -217.335354)
		(width 0.0889)
		(layer "In4.Cu")
		(net "UPI_CPU1_CPU0_P1P0_DN<16>")
	)
	(segment
		(start 118.96471 -213.11108)
		(end 119.06377 -213.01202)
		(width 0.0889)
		(layer "In4.Cu")
		(net "UPI_CPU1_CPU0_P1P0_DN<16>")
	)
	(segment
		(start 118.845076 -217.335354)
		(end 118.923308 -217.356182)
		(width 0.0889)
		(layer "In4.Cu")
		(net "UPI_CPU1_CPU0_P1P0_DN<16>")
	)
	(segment
		(start 210.820762 -175.526192)
		(end 238.611156 -175.526192)
		(width 0.14732)
		(layer "In4.Cu")
		(net "UPI_CPU1_CPU0_P1P0_DN<16>")
	)
	(segment
		(start 122.06351 -202.26782)
		(end 130.26644 -192.175892)
		(width 0.14732)
		(layer "In4.Cu")
		(net "UPI_CPU1_CPU0_P1P0_DN<16>")
	)
	(segment
		(start 352.43262 -210.443064)
		(end 352.43262 -211.955888)
		(width 0.14732)
		(layer "In4.Cu")
		(net "UPI_CPU1_CPU0_P1P0_DN<16>")
	)
	(segment
		(start 352.344736 -216.739978)
		(end 352.343974 -216.740486)
		(width 0.0889)
		(layer "In4.Cu")
		(net "UPI_CPU1_CPU0_P1P0_DN<16>")
	)
	(segment
		(start 352.343974 -216.740486)
		(end 352.338894 -216.74328)
		(width 0.0889)
		(layer "In4.Cu")
		(net "UPI_CPU1_CPU0_P1P0_DN<16>")
	)
	(segment
		(start 352.43262 -211.955888)
		(end 352.432874 -211.956142)
		(width 0.14732)
		(layer "In4.Cu")
		(net "UPI_CPU1_CPU0_P1P0_DN<16>")
	)
	(segment
		(start 157.521656 -175.766984)
		(end 200.186036 -175.059086)
		(width 0.14732)
		(layer "In4.Cu")
		(net "UPI_CPU1_CPU0_P1P0_DN<16>")
	)
	(segment
		(start 118.96471 -212.71738)
		(end 118.96471 -212.54212)
		(width 0.0889)
		(layer "In4.Cu")
		(net "UPI_CPU1_CPU0_P1P0_DN<16>")
	)
	(segment
		(start 119.532908 -214.622634)
		(end 119.532908 -214.500968)
		(width 0.0889)
		(layer "In4.Cu")
		(net "UPI_CPU1_CPU0_P1P0_DN<16>")
	)
	(segment
		(start 118.87581 -215.761062)
		(end 118.8847 -215.755982)
		(width 0.0889)
		(layer "In4.Cu")
		(net "UPI_CPU1_CPU0_P1P0_DN<16>")
	)
	(segment
		(start 119.02186 -212.00237)
		(end 119.02186 -211.699602)
		(width 0.14732)
		(layer "In4.Cu")
		(net "UPI_CPU1_CPU0_P1P0_DN<16>")
	)
	(segment
		(start 119.063262 -215.436704)
		(end 119.063262 -215.414606)
		(width 0.0889)
		(layer "In4.Cu")
		(net "UPI_CPU1_CPU0_P1P0_DN<16>")
	)
	(segment
		(start 119.06377 -213.01202)
		(end 119.06377 -212.81644)
		(width 0.0889)
		(layer "In4.Cu")
		(net "UPI_CPU1_CPU0_P1P0_DN<16>")
	)
	(segment
		(start 302.484028 -174.647352)
		(end 302.489616 -174.647352)
		(width 0.14732)
		(layer "In4.Cu")
		(net "UPI_CPU1_CPU0_P1P0_DN<16>")
	)
	(segment
		(start 119.06377 -213.3854)
		(end 118.96471 -213.28634)
		(width 0.0889)
		(layer "In4.Cu")
		(net "UPI_CPU1_CPU0_P1P0_DN<16>")
	)
	(segment
		(start 352.347276 -215.762586)
		(end 352.350578 -215.764618)
		(width 0.0889)
		(layer "In4.Cu")
		(net "UPI_CPU1_CPU0_P1P0_DN<16>")
	)
	(segment
		(start 352.626676 -214.424768)
		(end 352.626676 -214.644732)
		(width 0.0889)
		(layer "In4.Cu")
		(net "UPI_CPU1_CPU0_P1P0_DN<16>")
	)
	(segment
		(start 119.06377 -212.44306)
		(end 119.06377 -212.066378)
		(width 0.0889)
		(layer "In4.Cu")
		(net "UPI_CPU1_CPU0_P1P0_DN<16>")
	)
	(segment
		(start 352.335592 -215.755982)
		(end 352.342958 -215.7603)
		(width 0.0889)
		(layer "In4.Cu")
		(net "UPI_CPU1_CPU0_P1P0_DN<16>")
	)
	(segment
		(start 352.344482 -215.112346)
		(end 352.343466 -215.112854)
		(width 0.0889)
		(layer "In4.Cu")
		(net "UPI_CPU1_CPU0_P1P0_DN<16>")
	)
	(segment
		(start 352.432874 -211.956142)
		(end 352.432874 -212.11159)
		(width 0.14732)
		(layer "In4.Cu")
		(net "UPI_CPU1_CPU0_P1P0_DN<16>")
	)
	(segment
		(start 352.342958 -215.7603)
		(end 352.344482 -215.761062)
		(width 0.0889)
		(layer "In4.Cu")
		(net "UPI_CPU1_CPU0_P1P0_DN<16>")
	)
	(segment
		(start 140.353542 -182.77078)
		(end 150.546308 -177.552096)
		(width 0.14732)
		(layer "In4.Cu")
		(net "UPI_CPU1_CPU0_P1P0_DN<16>")
	)
	(segment
		(start 349.837756 -197.261226)
		(end 352.58756 -203.900532)
		(width 0.14732)
		(layer "In4.Cu")
		(net "UPI_CPU1_CPU0_P1P0_DN<16>")
	)
	(segment
		(start 118.8847 -216.745058)
		(end 118.876826 -216.740486)
		(width 0.0889)
		(layer "In4.Cu")
		(net "UPI_CPU1_CPU0_P1P0_DN<16>")
	)
	(segment
		(start 352.432874 -212.11159)
		(end 352.432874 -212.133688)
		(width 0.0889)
		(layer "In4.Cu")
		(net "UPI_CPU1_CPU0_P1P0_DN<16>")
	)
	(segment
		(start 352.58756 -203.900532)
		(end 352.58756 -210.068922)
		(width 0.14732)
		(layer "In4.Cu")
		(net "UPI_CPU1_CPU0_P1P0_DN<16>")
	)
	(segment
		(start 352.338894 -216.74328)
		(end 352.335846 -216.745058)
		(width 0.0889)
		(layer "In4.Cu")
		(net "UPI_CPU1_CPU0_P1P0_DN<16>")
	)
	(segment
		(start 118.96471 -212.54212)
		(end 119.06377 -212.44306)
		(width 0.0889)
		(layer "In4.Cu")
		(net "UPI_CPU1_CPU0_P1P0_DN<16>")
	)
	(segment
		(start 352.432874 -212.133688)
		(end 352.39071 -212.175852)
		(width 0.0889)
		(layer "In4.Cu")
		(net "UPI_CPU1_CPU0_P1P0_DN<16>")
	)
	(segment
		(start 336.647536 -183.235346)
		(end 337.916012 -184.089294)
		(width 0.14732)
		(layer "In4.Cu")
		(net "UPI_CPU1_CPU0_P1P0_DN<16>")
	)
	(segment
		(start 119.02186 -211.699602)
		(end 119.021606 -211.699348)
		(width 0.14732)
		(layer "In4.Cu")
		(net "UPI_CPU1_CPU0_P1P0_DN<16>")
	)
	(segment
		(start 341.291926 -187.464954)
		(end 343.919302 -191.194944)
		(width 0.14732)
		(layer "In4.Cu")
		(net "UPI_CPU1_CPU0_P1P0_DN<16>")
	)
	(segment
		(start 343.919302 -191.194944)
		(end 349.837756 -197.261226)
		(width 0.14732)
		(layer "In4.Cu")
		(net "UPI_CPU1_CPU0_P1P0_DN<16>")
	)
	(segment
		(start 352.39071 -212.175852)
		(end 352.39071 -212.632798)
		(width 0.0889)
		(layer "In4.Cu")
		(net "UPI_CPU1_CPU0_P1P0_DN<16>")
	)
	(segment
		(start 118.96471 -213.28634)
		(end 118.96471 -213.11108)
		(width 0.0889)
		(layer "In4.Cu")
		(net "UPI_CPU1_CPU0_P1P0_DN<16>")
	)
	(segment
		(start 352.58756 -210.068922)
		(end 352.43262 -210.443064)
		(width 0.14732)
		(layer "In4.Cu")
		(net "UPI_CPU1_CPU0_P1P0_DN<16>")
	)
	(segment
		(start 130.26644 -192.175892)
		(end 136.368028 -188.120528)
		(width 0.14732)
		(layer "In4.Cu")
		(net "UPI_CPU1_CPU0_P1P0_DN<16>")
	)
	(segment
		(start 352.343466 -215.112854)
		(end 352.335592 -215.117426)
		(width 0.0889)
		(layer "In4.Cu")
		(net "UPI_CPU1_CPU0_P1P0_DN<16>")
	)
	(segment
		(start 352.627184 -216.25052)
		(end 352.627184 -216.260426)
		(width 0.0889)
		(layer "In4.Cu")
		(net "UPI_CPU1_CPU0_P1P0_DN<16>")
	)
	(segment
		(start 302.489616 -174.647352)
		(end 302.48987 -174.647606)
		(width 0.14732)
		(layer "In4.Cu")
		(net "UPI_CPU1_CPU0_P1P0_DN<16>")
	)
	(segment
		(start 119.021606 -210.958176)
		(end 122.06351 -202.26782)
		(width 0.14732)
		(layer "In4.Cu")
		(net "UPI_CPU1_CPU0_P1P0_DN<16>")
	)
	(segment
		(start 352.15703 -212.866478)
		(end 352.15703 -213.8934)
		(width 0.0889)
		(layer "In4.Cu")
		(net "UPI_CPU1_CPU0_P1P0_DN<16>")
	)
	(segment
		(start 238.611156 -175.526192)
		(end 273.11223 -175.361346)
		(width 0.14732)
		(layer "In4.Cu")
		(net "UPI_CPU1_CPU0_P1P0_DN<16>")
	)
	(segment
		(start 317.58128 -176.0474)
		(end 329.727814 -180.311806)
		(width 0.14732)
		(layer "In4.Cu")
		(net "UPI_CPU1_CPU0_P1P0_DN<16>")
	)
	(segment
		(start 352.15703 -213.8934)
		(end 352.157284 -213.893908)
		(width 0.0889)
		(layer "In4.Cu")
		(net "UPI_CPU1_CPU0_P1P0_DN<16>")
	)
	(segment
		(start 118.876826 -216.740486)
		(end 118.87581 -216.739978)
		(width 0.0889)
		(layer "In4.Cu")
		(net "UPI_CPU1_CPU0_P1P0_DN<16>")
	)
	(segment
		(start 119.021606 -211.699348)
		(end 119.021606 -210.958176)
		(width 0.14732)
		(layer "In4.Cu")
		(net "UPI_CPU1_CPU0_P1P0_DN<16>")
	)
	(segment
		(start 150.546308 -177.552096)
		(end 157.521656 -175.766984)
		(width 0.14732)
		(layer "In4.Cu")
		(net "UPI_CPU1_CPU0_P1P0_DN<16>")
	)
	(segment
		(start 119.06377 -213.787228)
		(end 119.06377 -213.3854)
		(width 0.0889)
		(layer "In4.Cu")
		(net "UPI_CPU1_CPU0_P1P0_DN<16>")
	)
	(segment
		(start 337.916012 -184.089294)
		(end 341.291926 -187.464954)
		(width 0.14732)
		(layer "In4.Cu")
		(net "UPI_CPU1_CPU0_P1P0_DN<16>")
	)
	(segment
		(start 352.399346 -218.33205)
		(end 352.375216 -218.421204)
		(width 0.0889)
		(layer "In4.Cu")
		(net "UPI_CPU1_CPU0_P1P0_DN<16>")
	)
	(segment
		(start 302.48987 -174.647606)
		(end 313.288172 -174.848266)
		(width 0.14732)
		(layer "In4.Cu")
		(net "UPI_CPU1_CPU0_P1P0_DN<16>")
	)
	(segment
		(start 313.288172 -174.848266)
		(end 317.58128 -176.0474)
		(width 0.14732)
		(layer "In4.Cu")
		(net "UPI_CPU1_CPU0_P1P0_DN<16>")
	)
	(segment
		(start 119.345456 -214.946992)
		(end 119.354346 -214.941912)
		(width 0.0889)
		(layer "In4.Cu")
		(net "UPI_CPU1_CPU0_P1P0_DN<16>")
	)
	(segment
		(start 352.39071 -212.632798)
		(end 352.15703 -212.866478)
		(width 0.0889)
		(layer "In4.Cu")
		(net "UPI_CPU1_CPU0_P1P0_DN<16>")
	)
	(segment
		(start 136.368028 -188.120528)
		(end 140.353542 -182.77078)
		(width 0.14732)
		(layer "In4.Cu")
		(net "UPI_CPU1_CPU0_P1P0_DN<16>")
	)
	(segment
		(start 352.627184 -217.859864)
		(end 352.627184 -217.878406)
		(width 0.0889)
		(layer "In4.Cu")
		(net "UPI_CPU1_CPU0_P1P0_DN<16>")
	)
	(segment
		(start 352.375216 -218.421204)
		(end 352.53168 -218.692222)
		(width 0.0889)
		(layer "In4.Cu")
		(net "UPI_CPU1_CPU0_P1P0_DN<16>")
	)
	(segment
		(start 352.335846 -217.383614)
		(end 352.344736 -217.388694)
		(width 0.0889)
		(layer "In4.Cu")
		(net "UPI_CPU1_CPU0_P1P0_DN<16>")
	)
	(segment
		(start 118.593616 -216.266014)
		(end 118.593616 -216.235026)
		(width 0.0889)
		(layer "In4.Cu")
		(net "UPI_CPU1_CPU0_P1P0_DN<16>")
	)
	(segment
		(start 119.06377 -212.81644)
		(end 118.96471 -212.71738)
		(width 0.0889)
		(layer "In4.Cu")
		(net "UPI_CPU1_CPU0_P1P0_DN<16>")
	)
	(segment
		(start 119.06377 -212.066378)
		(end 119.02186 -212.024468)
		(width 0.0889)
		(layer "In4.Cu")
		(net "UPI_CPU1_CPU0_P1P0_DN<16>")
	)
	(segment
		(start 329.727814 -180.311806)
		(end 336.647536 -183.235346)
		(width 0.14732)
		(layer "In4.Cu")
		(net "UPI_CPU1_CPU0_P1P0_DN<16>")
	)
	(arc
		(start 352.335846 -216.745058)
		(mid 352.157249 -217.064336)
		(end 352.335846 -217.383614)
		(width 0.0889)
		(layer "In4.Cu")
		(net "UPI_CPU1_CPU0_P1P0_DN<16>")
	)
	(arc
		(start 119.509794 -214.415116)
		(mid 119.440085 -214.327101)
		(end 119.349012 -214.261446)
		(width 0.0889)
		(layer "In4.Cu")
		(net "UPI_CPU1_CPU0_P1P0_DN<16>")
	)
	(arc
		(start 118.87581 -216.739978)
		(mid 118.672987 -216.539747)
		(end 118.593616 -216.266014)
		(width 0.0889)
		(layer "In4.Cu")
		(net "UPI_CPU1_CPU0_P1P0_DN<16>")
	)
	(arc
		(start 118.8847 -215.755982)
		(mid 119.015614 -215.619622)
		(end 119.063262 -215.436704)
		(width 0.0889)
		(layer "In4.Cu")
		(net "UPI_CPU1_CPU0_P1P0_DN<16>")
	)
	(arc
		(start 352.627184 -216.260426)
		(mid 352.549073 -216.537375)
		(end 352.344736 -216.739978)
		(width 0.0889)
		(layer "In4.Cu")
		(net "UPI_CPU1_CPU0_P1P0_DN<16>")
	)
	(arc
		(start 118.593616 -216.235026)
		(mid 118.672986 -215.961292)
		(end 118.87581 -215.761062)
		(width 0.0889)
		(layer "In4.Cu")
		(net "UPI_CPU1_CPU0_P1P0_DN<16>")
	)
	(arc
		(start 352.416364 -218.318842)
		(mid 352.407918 -218.325527)
		(end 352.399346 -218.33205)
		(width 0.0889)
		(layer "In4.Cu")
		(net "UPI_CPU1_CPU0_P1P0_DN<16>")
	)
	(arc
		(start 119.349012 -214.261446)
		(mid 119.140442 -214.064003)
		(end 119.06377 -213.787228)
		(width 0.0889)
		(layer "In4.Cu")
		(net "UPI_CPU1_CPU0_P1P0_DN<16>")
	)
	(arc
		(start 352.15703 -215.436704)
		(mid 352.204709 -215.619604)
		(end 352.335592 -215.755982)
		(width 0.0889)
		(layer "In4.Cu")
		(net "UPI_CPU1_CPU0_P1P0_DN<16>")
	)
	(arc
		(start 352.350578 -215.764618)
		(mid 352.553165 -215.970969)
		(end 352.627184 -216.25052)
		(width 0.0889)
		(layer "In4.Cu")
		(net "UPI_CPU1_CPU0_P1P0_DN<16>")
	)
	(arc
		(start 352.627184 -217.878406)
		(mid 352.571829 -218.122593)
		(end 352.416364 -218.318842)
		(width 0.0889)
		(layer "In4.Cu")
		(net "UPI_CPU1_CPU0_P1P0_DN<16>")
	)
	(arc
		(start 352.626676 -214.644732)
		(mid 352.545765 -214.91486)
		(end 352.344482 -215.112346)
		(width 0.0889)
		(layer "In4.Cu")
		(net "UPI_CPU1_CPU0_P1P0_DN<16>")
	)
	(arc
		(start 119.063262 -215.414606)
		(mid 119.144173 -215.144478)
		(end 119.345456 -214.946992)
		(width 0.0889)
		(layer "In4.Cu")
		(net "UPI_CPU1_CPU0_P1P0_DN<16>")
	)
	(arc
		(start 352.157284 -215.421972)
		(mid 352.157087 -215.429337)
		(end 352.15703 -215.436704)
		(width 0.0889)
		(layer "In4.Cu")
		(net "UPI_CPU1_CPU0_P1P0_DN<16>")
	)
	(arc
		(start 352.157284 -213.893908)
		(mid 352.232289 -214.009367)
		(end 352.341434 -214.093298)
		(width 0.0889)
		(layer "In4.Cu")
		(net "UPI_CPU1_CPU0_P1P0_DN<16>")
	)
	(arc
		(start 119.532908 -214.500968)
		(mid 119.527104 -214.45649)
		(end 119.509794 -214.415116)
		(width 0.0889)
		(layer "In4.Cu")
		(net "UPI_CPU1_CPU0_P1P0_DN<16>")
	)
	(arc
		(start 119.063262 -217.064336)
		(mid 119.015583 -216.881436)
		(end 118.8847 -216.745058)
		(width 0.0889)
		(layer "In4.Cu")
		(net "UPI_CPU1_CPU0_P1P0_DN<16>")
	)
	(arc
		(start 118.923308 -217.356182)
		(mid 119.026453 -217.226157)
		(end 119.063262 -217.064336)
		(width 0.0889)
		(layer "In4.Cu")
		(net "UPI_CPU1_CPU0_P1P0_DN<16>")
	)
	(arc
		(start 352.335592 -215.117426)
		(mid 352.208338 -215.247392)
		(end 352.157284 -215.421972)
		(width 0.0889)
		(layer "In4.Cu")
		(net "UPI_CPU1_CPU0_P1P0_DN<16>")
	)
	(arc
		(start 352.341434 -214.093298)
		(mid 352.515397 -214.232062)
		(end 352.626676 -214.424768)
		(width 0.0889)
		(layer "In4.Cu")
		(net "UPI_CPU1_CPU0_P1P0_DN<16>")
	)
	(arc
		(start 352.344736 -217.388694)
		(mid 352.547022 -217.587675)
		(end 352.627184 -217.859864)
		(width 0.0889)
		(layer "In4.Cu")
		(net "UPI_CPU1_CPU0_P1P0_DN<16>")
	)
	(arc
		(start 119.354346 -214.941912)
		(mid 119.48526 -214.805552)
		(end 119.532908 -214.622634)
		(width 0.0889)
		(layer "In4.Cu")
		(net "UPI_CPU1_CPU0_P1P0_DN<16>")
	)
	(segment
		(start 351.12198 -217.87866)
		(end 351.122234 -217.878406)
		(width 0.13208)
		(layer "F.Cu")
		(net "UPI_CPU1_CPU0_P1P0_DN<15>")
	)
	(segment
		(start 120.098312 -217.87866)
		(end 120.098566 -217.878406)
		(width 0.13208)
		(layer "F.Cu")
		(net "UPI_CPU1_CPU0_P1P0_DN<15>")
	)
	(segment
		(start 351.12198 -218.414346)
		(end 351.12198 -217.87866)
		(width 0.13208)
		(layer "F.Cu")
		(net "UPI_CPU1_CPU0_P1P0_DN<15>")
	)
	(segment
		(start 120.098312 -218.414346)
		(end 120.098312 -217.87866)
		(width 0.13208)
		(layer "F.Cu")
		(net "UPI_CPU1_CPU0_P1P0_DN<15>")
	)
	(segment
		(start 351.02673 -217.064336)
		(end 351.02673 -217.07856)
		(width 0.0889)
		(layer "In4.Cu")
		(net "UPI_CPU1_CPU0_P1P0_DN<15>")
	)
	(segment
		(start 313.175904 -175.977804)
		(end 317.187834 -177.098198)
		(width 0.14732)
		(layer "In4.Cu")
		(net "UPI_CPU1_CPU0_P1P0_DN<15>")
	)
	(segment
		(start 120.193562 -213.09584)
		(end 120.193562 -212.80374)
		(width 0.0889)
		(layer "In4.Cu")
		(net "UPI_CPU1_CPU0_P1P0_DN<15>")
	)
	(segment
		(start 351.306638 -216.576402)
		(end 351.303336 -216.578434)
		(width 0.0889)
		(layer "In4.Cu")
		(net "UPI_CPU1_CPU0_P1P0_DN<15>")
	)
	(segment
		(start 122.277886 -205.754478)
		(end 122.422412 -205.341728)
		(width 0.14732)
		(layer "In4.Cu")
		(net "UPI_CPU1_CPU0_P1P0_DN<15>")
	)
	(segment
		(start 120.663208 -214.644732)
		(end 120.663208 -214.424768)
		(width 0.0889)
		(layer "In4.Cu")
		(net "UPI_CPU1_CPU0_P1P0_DN<15>")
	)
	(segment
		(start 210.937856 -176.657254)
		(end 238.614204 -176.657254)
		(width 0.14732)
		(layer "In4.Cu")
		(net "UPI_CPU1_CPU0_P1P0_DN<15>")
	)
	(segment
		(start 351.317814 -214.941912)
		(end 351.308924 -214.946992)
		(width 0.0889)
		(layer "In4.Cu")
		(net "UPI_CPU1_CPU0_P1P0_DN<15>")
	)
	(segment
		(start 121.978166 -206.241396)
		(end 122.122438 -205.829154)
		(width 0.14732)
		(layer "In4.Cu")
		(net "UPI_CPU1_CPU0_P1P0_DN<15>")
	)
	(segment
		(start 351.359724 -212.096858)
		(end 351.359724 -212.389974)
		(width 0.0889)
		(layer "In4.Cu")
		(net "UPI_CPU1_CPU0_P1P0_DN<15>")
	)
	(segment
		(start 120.193562 -213.815422)
		(end 120.193562 -213.46922)
		(width 0.0889)
		(layer "In4.Cu")
		(net "UPI_CPU1_CPU0_P1P0_DN<15>")
	)
	(segment
		(start 120.235726 -212.024468)
		(end 120.235726 -212.00237)
		(width 0.0889)
		(layer "In4.Cu")
		(net "UPI_CPU1_CPU0_P1P0_DN<15>")
	)
	(segment
		(start 120.292622 -212.52942)
		(end 120.193562 -212.43036)
		(width 0.0889)
		(layer "In4.Cu")
		(net "UPI_CPU1_CPU0_P1P0_DN<15>")
	)
	(segment
		(start 121.68378 -207.451452)
		(end 121.60885 -207.296258)
		(width 0.14732)
		(layer "In4.Cu")
		(net "UPI_CPU1_CPU0_P1P0_DN<15>")
	)
	(segment
		(start 351.31248 -214.2617)
		(end 351.312226 -214.261954)
		(width 0.0889)
		(layer "In4.Cu")
		(net "UPI_CPU1_CPU0_P1P0_DN<15>")
	)
	(segment
		(start 351.317814 -212.03285)
		(end 351.317814 -212.054948)
		(width 0.0889)
		(layer "In4.Cu")
		(net "UPI_CPU1_CPU0_P1P0_DN<15>")
	)
	(segment
		(start 141.074902 -183.671464)
		(end 150.890478 -178.646582)
		(width 0.14732)
		(layer "In4.Cu")
		(net "UPI_CPU1_CPU0_P1P0_DN<15>")
	)
	(segment
		(start 122.053096 -206.39659)
		(end 121.978166 -206.241396)
		(width 0.14732)
		(layer "In4.Cu")
		(net "UPI_CPU1_CPU0_P1P0_DN<15>")
	)
	(segment
		(start 351.318322 -216.569798)
		(end 351.310956 -216.574116)
		(width 0.0889)
		(layer "In4.Cu")
		(net "UPI_CPU1_CPU0_P1P0_DN<15>")
	)
	(segment
		(start 122.422412 -205.341728)
		(end 122.347482 -205.186534)
		(width 0.14732)
		(layer "In4.Cu")
		(net "UPI_CPU1_CPU0_P1P0_DN<15>")
	)
	(segment
		(start 119.902478 -217.559128)
		(end 119.911368 -217.554048)
		(width 0.0889)
		(layer "In4.Cu")
		(net "UPI_CPU1_CPU0_P1P0_DN<15>")
	)
	(segment
		(start 351.496376 -214.461344)
		(end 351.496376 -214.622634)
		(width 0.0889)
		(layer "In4.Cu")
		(net "UPI_CPU1_CPU0_P1P0_DN<15>")
	)
	(segment
		(start 122.821954 -204.200252)
		(end 122.747278 -204.044804)
		(width 0.14732)
		(layer "In4.Cu")
		(net "UPI_CPU1_CPU0_P1P0_DN<15>")
	)
	(segment
		(start 130.476244 -193.673222)
		(end 136.711944 -189.527688)
		(width 0.14732)
		(layer "In4.Cu")
		(net "UPI_CPU1_CPU0_P1P0_DN<15>")
	)
	(segment
		(start 121.239534 -208.35112)
		(end 121.383806 -207.938878)
		(width 0.14732)
		(layer "In4.Cu")
		(net "UPI_CPU1_CPU0_P1P0_DN<15>")
	)
	(segment
		(start 348.880176 -197.874382)
		(end 351.31756 -203.758546)
		(width 0.14732)
		(layer "In4.Cu")
		(net "UPI_CPU1_CPU0_P1P0_DN<15>")
	)
	(segment
		(start 317.187834 -177.098198)
		(end 329.377294 -181.367684)
		(width 0.14732)
		(layer "In4.Cu")
		(net "UPI_CPU1_CPU0_P1P0_DN<15>")
	)
	(segment
		(start 351.309432 -216.574878)
		(end 351.306638 -216.576402)
		(width 0.0889)
		(layer "In4.Cu")
		(net "UPI_CPU1_CPU0_P1P0_DN<15>")
	)
	(segment
		(start 120.235472 -211.699348)
		(end 120.235472 -211.217764)
		(width 0.14732)
		(layer "In4.Cu")
		(net "UPI_CPU1_CPU0_P1P0_DN<15>")
	)
	(segment
		(start 120.644666 -210.048602)
		(end 120.800368 -209.973926)
		(width 0.14732)
		(layer "In4.Cu")
		(net "UPI_CPU1_CPU0_P1P0_DN<15>")
	)
	(segment
		(start 351.309432 -215.926162)
		(end 351.310956 -215.926924)
		(width 0.0889)
		(layer "In4.Cu")
		(net "UPI_CPU1_CPU0_P1P0_DN<15>")
	)
	(segment
		(start 238.614204 -176.657254)
		(end 273.12874 -176.492408)
		(width 0.14732)
		(layer "In4.Cu")
		(net "UPI_CPU1_CPU0_P1P0_DN<15>")
	)
	(segment
		(start 122.52198 -204.687424)
		(end 122.677682 -204.612748)
		(width 0.14732)
		(layer "In4.Cu")
		(net "UPI_CPU1_CPU0_P1P0_DN<15>")
	)
	(segment
		(start 120.193562 -213.46922)
		(end 120.292622 -213.37016)
		(width 0.0889)
		(layer "In4.Cu")
		(net "UPI_CPU1_CPU0_P1P0_DN<15>")
	)
	(segment
		(start 336.120486 -184.211722)
		(end 337.208876 -184.944004)
		(width 0.14732)
		(layer "In4.Cu")
		(net "UPI_CPU1_CPU0_P1P0_DN<15>")
	)
	(segment
		(start 351.317814 -212.054948)
		(end 351.359724 -212.096858)
		(width 0.0889)
		(layer "In4.Cu")
		(net "UPI_CPU1_CPU0_P1P0_DN<15>")
	)
	(segment
		(start 273.12874 -176.492408)
		(end 302.48733 -175.779176)
		(width 0.14732)
		(layer "In4.Cu")
		(net "UPI_CPU1_CPU0_P1P0_DN<15>")
	)
	(segment
		(start 154.309064 -177.771552)
		(end 157.727904 -176.896522)
		(width 0.14732)
		(layer "In4.Cu")
		(net "UPI_CPU1_CPU0_P1P0_DN<15>")
	)
	(segment
		(start 120.193562 -212.066632)
		(end 120.235726 -212.024468)
		(width 0.0889)
		(layer "In4.Cu")
		(net "UPI_CPU1_CPU0_P1P0_DN<15>")
	)
	(segment
		(start 120.292622 -213.37016)
		(end 120.292622 -213.1949)
		(width 0.0889)
		(layer "In4.Cu")
		(net "UPI_CPU1_CPU0_P1P0_DN<15>")
	)
	(segment
		(start 120.292622 -213.1949)
		(end 120.193562 -213.09584)
		(width 0.0889)
		(layer "In4.Cu")
		(net "UPI_CPU1_CPU0_P1P0_DN<15>")
	)
	(segment
		(start 120.94464 -209.561176)
		(end 120.869964 -209.405982)
		(width 0.14732)
		(layer "In4.Cu")
		(net "UPI_CPU1_CPU0_P1P0_DN<15>")
	)
	(segment
		(start 122.747278 -204.044804)
		(end 123.277376 -202.530202)
		(width 0.14732)
		(layer "In4.Cu")
		(net "UPI_CPU1_CPU0_P1P0_DN<15>")
	)
	(segment
		(start 150.890478 -178.646582)
		(end 154.30881 -177.771806)
		(width 0.14732)
		(layer "In4.Cu")
		(net "UPI_CPU1_CPU0_P1P0_DN<15>")
	)
	(segment
		(start 340.439756 -188.175138)
		(end 343.095072 -191.946022)
		(width 0.14732)
		(layer "In4.Cu")
		(net "UPI_CPU1_CPU0_P1P0_DN<15>")
	)
	(segment
		(start 120.800368 -209.973926)
		(end 120.94464 -209.561176)
		(width 0.14732)
		(layer "In4.Cu")
		(net "UPI_CPU1_CPU0_P1P0_DN<15>")
	)
	(segment
		(start 120.292622 -212.70468)
		(end 120.292622 -212.52942)
		(width 0.0889)
		(layer "In4.Cu")
		(net "UPI_CPU1_CPU0_P1P0_DN<15>")
	)
	(segment
		(start 329.377294 -181.367684)
		(end 336.120486 -184.211722)
		(width 0.14732)
		(layer "In4.Cu")
		(net "UPI_CPU1_CPU0_P1P0_DN<15>")
	)
	(segment
		(start 200.299066 -176.190148)
		(end 210.937856 -176.657254)
		(width 0.14732)
		(layer "In4.Cu")
		(net "UPI_CPU1_CPU0_P1P0_DN<15>")
	)
	(segment
		(start 351.31756 -211.85886)
		(end 351.317814 -211.859114)
		(width 0.14732)
		(layer "In4.Cu")
		(net "UPI_CPU1_CPU0_P1P0_DN<15>")
	)
	(segment
		(start 302.48733 -175.779176)
		(end 313.175904 -175.977804)
		(width 0.14732)
		(layer "In4.Cu")
		(net "UPI_CPU1_CPU0_P1P0_DN<15>")
	)
	(segment
		(start 123.277376 -202.530202)
		(end 130.476244 -193.673222)
		(width 0.14732)
		(layer "In4.Cu")
		(net "UPI_CPU1_CPU0_P1P0_DN<15>")
	)
	(segment
		(start 351.254568 -217.518234)
		(end 351.278698 -217.607388)
		(width 0.0889)
		(layer "In4.Cu")
		(net "UPI_CPU1_CPU0_P1P0_DN<15>")
	)
	(segment
		(start 351.278698 -217.607388)
		(end 351.122234 -217.878406)
		(width 0.0889)
		(layer "In4.Cu")
		(net "UPI_CPU1_CPU0_P1P0_DN<15>")
	)
	(segment
		(start 119.911368 -216.574878)
		(end 119.902478 -216.569798)
		(width 0.0889)
		(layer "In4.Cu")
		(net "UPI_CPU1_CPU0_P1P0_DN<15>")
	)
	(segment
		(start 119.902478 -215.931242)
		(end 119.911368 -215.926162)
		(width 0.0889)
		(layer "In4.Cu")
		(net "UPI_CPU1_CPU0_P1P0_DN<15>")
	)
	(segment
		(start 120.098566 -217.878406)
		(end 119.942102 -218.149424)
		(width 0.0889)
		(layer "In4.Cu")
		(net "UPI_CPU1_CPU0_P1P0_DN<15>")
	)
	(segment
		(start 343.095072 -191.946022)
		(end 348.880176 -197.874382)
		(width 0.14732)
		(layer "In4.Cu")
		(net "UPI_CPU1_CPU0_P1P0_DN<15>")
	)
	(segment
		(start 120.193562 -212.80374)
		(end 120.292622 -212.70468)
		(width 0.0889)
		(layer "In4.Cu")
		(net "UPI_CPU1_CPU0_P1P0_DN<15>")
	)
	(segment
		(start 122.347482 -205.186534)
		(end 122.52198 -204.687424)
		(width 0.14732)
		(layer "In4.Cu")
		(net "UPI_CPU1_CPU0_P1P0_DN<15>")
	)
	(segment
		(start 351.359724 -212.389974)
		(end 351.027238 -212.638132)
		(width 0.0889)
		(layer "In4.Cu")
		(net "UPI_CPU1_CPU0_P1P0_DN<15>")
	)
	(segment
		(start 121.90857 -206.80934)
		(end 122.053096 -206.39659)
		(width 0.14732)
		(layer "In4.Cu")
		(net "UPI_CPU1_CPU0_P1P0_DN<15>")
	)
	(segment
		(start 122.677682 -204.612748)
		(end 122.821954 -204.200252)
		(width 0.14732)
		(layer "In4.Cu")
		(net "UPI_CPU1_CPU0_P1P0_DN<15>")
	)
	(segment
		(start 337.208876 -184.944004)
		(end 340.439756 -188.175138)
		(width 0.14732)
		(layer "In4.Cu")
		(net "UPI_CPU1_CPU0_P1P0_DN<15>")
	)
	(segment
		(start 121.60885 -207.296258)
		(end 121.753122 -206.884016)
		(width 0.14732)
		(layer "In4.Cu")
		(net "UPI_CPU1_CPU0_P1P0_DN<15>")
	)
	(segment
		(start 121.383806 -207.938878)
		(end 121.539254 -207.864202)
		(width 0.14732)
		(layer "In4.Cu")
		(net "UPI_CPU1_CPU0_P1P0_DN<15>")
	)
	(segment
		(start 120.193816 -217.082878)
		(end 120.193816 -217.05443)
		(width 0.0889)
		(layer "In4.Cu")
		(net "UPI_CPU1_CPU0_P1P0_DN<15>")
	)
	(segment
		(start 120.869964 -209.405982)
		(end 121.014236 -208.99374)
		(width 0.14732)
		(layer "In4.Cu")
		(net "UPI_CPU1_CPU0_P1P0_DN<15>")
	)
	(segment
		(start 121.014236 -208.99374)
		(end 121.169938 -208.919064)
		(width 0.14732)
		(layer "In4.Cu")
		(net "UPI_CPU1_CPU0_P1P0_DN<15>")
	)
	(segment
		(start 351.31756 -203.758546)
		(end 351.31756 -211.85886)
		(width 0.14732)
		(layer "In4.Cu")
		(net "UPI_CPU1_CPU0_P1P0_DN<15>")
	)
	(segment
		(start 120.644666 -210.04911)
		(end 120.644666 -210.048602)
		(width 0.14732)
		(layer "In4.Cu")
		(net "UPI_CPU1_CPU0_P1P0_DN<15>")
	)
	(segment
		(start 120.193562 -212.43036)
		(end 120.193562 -212.066632)
		(width 0.0889)
		(layer "In4.Cu")
		(net "UPI_CPU1_CPU0_P1P0_DN<15>")
	)
	(segment
		(start 351.02673 -215.414606)
		(end 351.02673 -215.436704)
		(width 0.0889)
		(layer "In4.Cu")
		(net "UPI_CPU1_CPU0_P1P0_DN<15>")
	)
	(segment
		(start 121.539254 -207.864202)
		(end 121.68378 -207.451452)
		(width 0.14732)
		(layer "In4.Cu")
		(net "UPI_CPU1_CPU0_P1P0_DN<15>")
	)
	(segment
		(start 120.235726 -211.699602)
		(end 120.235472 -211.699348)
		(width 0.14732)
		(layer "In4.Cu")
		(net "UPI_CPU1_CPU0_P1P0_DN<15>")
	)
	(segment
		(start 351.310956 -215.926924)
		(end 351.318322 -215.931242)
		(width 0.0889)
		(layer "In4.Cu")
		(net "UPI_CPU1_CPU0_P1P0_DN<15>")
	)
	(segment
		(start 136.711944 -189.527688)
		(end 141.074902 -183.671464)
		(width 0.14732)
		(layer "In4.Cu")
		(net "UPI_CPU1_CPU0_P1P0_DN<15>")
	)
	(segment
		(start 351.303336 -215.922606)
		(end 351.30867 -215.925654)
		(width 0.0889)
		(layer "In4.Cu")
		(net "UPI_CPU1_CPU0_P1P0_DN<15>")
	)
	(segment
		(start 351.027238 -212.638132)
		(end 351.027238 -213.929468)
		(width 0.0889)
		(layer "In4.Cu")
		(net "UPI_CPU1_CPU0_P1P0_DN<15>")
	)
	(segment
		(start 120.377966 -214.093298)
		(end 120.377712 -214.093806)
		(width 0.0889)
		(layer "In4.Cu")
		(net "UPI_CPU1_CPU0_P1P0_DN<15>")
	)
	(segment
		(start 119.942102 -218.149424)
		(end 119.86387 -218.170252)
		(width 0.0889)
		(layer "In4.Cu")
		(net "UPI_CPU1_CPU0_P1P0_DN<15>")
	)
	(segment
		(start 120.372124 -215.117426)
		(end 120.381014 -215.112346)
		(width 0.0889)
		(layer "In4.Cu")
		(net "UPI_CPU1_CPU0_P1P0_DN<15>")
	)
	(segment
		(start 157.727904 -176.896522)
		(end 200.299066 -176.190148)
		(width 0.14732)
		(layer "In4.Cu")
		(net "UPI_CPU1_CPU0_P1P0_DN<15>")
	)
	(segment
		(start 120.235726 -212.00237)
		(end 120.235726 -211.699602)
		(width 0.14732)
		(layer "In4.Cu")
		(net "UPI_CPU1_CPU0_P1P0_DN<15>")
	)
	(segment
		(start 120.235472 -211.217764)
		(end 120.644666 -210.04911)
		(width 0.14732)
		(layer "In4.Cu")
		(net "UPI_CPU1_CPU0_P1P0_DN<15>")
	)
	(segment
		(start 121.169938 -208.919064)
		(end 121.31421 -208.506314)
		(width 0.14732)
		(layer "In4.Cu")
		(net "UPI_CPU1_CPU0_P1P0_DN<15>")
	)
	(segment
		(start 122.122438 -205.829154)
		(end 122.277886 -205.754478)
		(width 0.14732)
		(layer "In4.Cu")
		(net "UPI_CPU1_CPU0_P1P0_DN<15>")
	)
	(segment
		(start 121.753122 -206.884016)
		(end 121.90857 -206.80934)
		(width 0.14732)
		(layer "In4.Cu")
		(net "UPI_CPU1_CPU0_P1P0_DN<15>")
	)
	(segment
		(start 120.193562 -215.452198)
		(end 120.193562 -215.436704)
		(width 0.0889)
		(layer "In4.Cu")
		(net "UPI_CPU1_CPU0_P1P0_DN<15>")
	)
	(segment
		(start 121.31421 -208.506314)
		(end 121.239534 -208.35112)
		(width 0.14732)
		(layer "In4.Cu")
		(net "UPI_CPU1_CPU0_P1P0_DN<15>")
	)
	(segment
		(start 154.30881 -177.771806)
		(end 154.309064 -177.771552)
		(width 0.14732)
		(layer "In4.Cu")
		(net "UPI_CPU1_CPU0_P1P0_DN<15>")
	)
	(segment
		(start 351.310956 -216.574116)
		(end 351.309432 -216.574878)
		(width 0.0889)
		(layer "In4.Cu")
		(net "UPI_CPU1_CPU0_P1P0_DN<15>")
	)
	(segment
		(start 351.317814 -211.859114)
		(end 351.317814 -212.03285)
		(width 0.14732)
		(layer "In4.Cu")
		(net "UPI_CPU1_CPU0_P1P0_DN<15>")
	)
	(segment
		(start 351.30867 -215.925654)
		(end 351.309432 -215.926162)
		(width 0.0889)
		(layer "In4.Cu")
		(net "UPI_CPU1_CPU0_P1P0_DN<15>")
	)
	(arc
		(start 120.193562 -215.436704)
		(mid 120.193614 -215.429337)
		(end 120.193816 -215.421972)
		(width 0.0889)
		(layer "In4.Cu")
		(net "UPI_CPU1_CPU0_P1P0_DN<15>")
	)
	(arc
		(start 351.23755 -217.50528)
		(mid 351.245998 -217.511837)
		(end 351.254568 -217.518234)
		(width 0.0889)
		(layer "In4.Cu")
		(net "UPI_CPU1_CPU0_P1P0_DN<15>")
	)
	(arc
		(start 351.496376 -214.622634)
		(mid 351.448697 -214.805534)
		(end 351.317814 -214.941912)
		(width 0.0889)
		(layer "In4.Cu")
		(net "UPI_CPU1_CPU0_P1P0_DN<15>")
	)
	(arc
		(start 119.902478 -216.569798)
		(mid 119.773189 -216.436312)
		(end 119.723916 -216.257124)
		(width 0.0889)
		(layer "In4.Cu")
		(net "UPI_CPU1_CPU0_P1P0_DN<15>")
	)
	(arc
		(start 120.193816 -215.421972)
		(mid 120.24487 -215.247392)
		(end 120.372124 -215.117426)
		(width 0.0889)
		(layer "In4.Cu")
		(net "UPI_CPU1_CPU0_P1P0_DN<15>")
	)
	(arc
		(start 351.318322 -215.931242)
		(mid 351.496919 -216.25052)
		(end 351.318322 -216.569798)
		(width 0.0889)
		(layer "In4.Cu")
		(net "UPI_CPU1_CPU0_P1P0_DN<15>")
	)
	(arc
		(start 120.381014 -215.112346)
		(mid 120.582296 -214.914859)
		(end 120.663208 -214.644732)
		(width 0.0889)
		(layer "In4.Cu")
		(net "UPI_CPU1_CPU0_P1P0_DN<15>")
	)
	(arc
		(start 119.723916 -216.257124)
		(mid 119.723822 -216.248742)
		(end 119.723916 -216.24036)
		(width 0.0889)
		(layer "In4.Cu")
		(net "UPI_CPU1_CPU0_P1P0_DN<15>")
	)
	(arc
		(start 119.723916 -217.878406)
		(mid 119.771595 -217.695506)
		(end 119.902478 -217.559128)
		(width 0.0889)
		(layer "In4.Cu")
		(net "UPI_CPU1_CPU0_P1P0_DN<15>")
	)
	(arc
		(start 119.723916 -216.24036)
		(mid 119.773985 -216.063135)
		(end 119.902478 -215.931242)
		(width 0.0889)
		(layer "In4.Cu")
		(net "UPI_CPU1_CPU0_P1P0_DN<15>")
	)
	(arc
		(start 351.308924 -214.946992)
		(mid 351.107642 -215.144479)
		(end 351.02673 -215.414606)
		(width 0.0889)
		(layer "In4.Cu")
		(net "UPI_CPU1_CPU0_P1P0_DN<15>")
	)
	(arc
		(start 120.27408 -214.015828)
		(mid 120.214455 -213.923414)
		(end 120.193562 -213.815422)
		(width 0.0889)
		(layer "In4.Cu")
		(net "UPI_CPU1_CPU0_P1P0_DN<15>")
	)
	(arc
		(start 120.193816 -217.05443)
		(mid 120.115705 -216.777481)
		(end 119.911368 -216.574878)
		(width 0.0889)
		(layer "In4.Cu")
		(net "UPI_CPU1_CPU0_P1P0_DN<15>")
	)
	(arc
		(start 351.02673 -217.07856)
		(mid 351.085024 -217.315203)
		(end 351.23755 -217.50528)
		(width 0.0889)
		(layer "In4.Cu")
		(net "UPI_CPU1_CPU0_P1P0_DN<15>")
	)
	(arc
		(start 119.86387 -218.170252)
		(mid 119.760725 -218.040227)
		(end 119.723916 -217.878406)
		(width 0.0889)
		(layer "In4.Cu")
		(net "UPI_CPU1_CPU0_P1P0_DN<15>")
	)
	(arc
		(start 119.911368 -215.926162)
		(mid 120.114191 -215.725931)
		(end 120.193562 -215.452198)
		(width 0.0889)
		(layer "In4.Cu")
		(net "UPI_CPU1_CPU0_P1P0_DN<15>")
	)
	(arc
		(start 119.911368 -217.554048)
		(mid 120.113654 -217.355067)
		(end 120.193816 -217.082878)
		(width 0.0889)
		(layer "In4.Cu")
		(net "UPI_CPU1_CPU0_P1P0_DN<15>")
	)
	(arc
		(start 351.027238 -213.929468)
		(mid 351.138366 -214.122627)
		(end 351.31248 -214.2617)
		(width 0.0889)
		(layer "In4.Cu")
		(net "UPI_CPU1_CPU0_P1P0_DN<15>")
	)
	(arc
		(start 120.663208 -214.424768)
		(mid 120.551929 -214.232062)
		(end 120.377966 -214.093298)
		(width 0.0889)
		(layer "In4.Cu")
		(net "UPI_CPU1_CPU0_P1P0_DN<15>")
	)
	(arc
		(start 351.312226 -214.261954)
		(mid 351.421373 -214.345882)
		(end 351.496376 -214.461344)
		(width 0.0889)
		(layer "In4.Cu")
		(net "UPI_CPU1_CPU0_P1P0_DN<15>")
	)
	(arc
		(start 120.377712 -214.093806)
		(mid 120.322793 -214.058944)
		(end 120.27408 -214.015828)
		(width 0.0889)
		(layer "In4.Cu")
		(net "UPI_CPU1_CPU0_P1P0_DN<15>")
	)
	(arc
		(start 351.303336 -216.578434)
		(mid 351.100749 -216.784785)
		(end 351.02673 -217.064336)
		(width 0.0889)
		(layer "In4.Cu")
		(net "UPI_CPU1_CPU0_P1P0_DN<15>")
	)
	(arc
		(start 351.02673 -215.436704)
		(mid 351.100721 -215.71627)
		(end 351.303336 -215.922606)
		(width 0.0889)
		(layer "In4.Cu")
		(net "UPI_CPU1_CPU0_P1P0_DN<15>")
	)
	(segment
		(start 120.568466 -217.600276)
		(end 120.568466 -217.06459)
		(width 0.13208)
		(layer "F.Cu")
		(net "UPI_CPU1_CPU0_P1P0_DN<14>")
	)
	(segment
		(start 350.652334 -219.228162)
		(end 350.652334 -218.692476)
		(width 0.13208)
		(layer "F.Cu")
		(net "UPI_CPU1_CPU0_P1P0_DN<14>")
	)
	(segment
		(start 120.568466 -217.06459)
		(end 120.568212 -217.064336)
		(width 0.13208)
		(layer "F.Cu")
		(net "UPI_CPU1_CPU0_P1P0_DN<14>")
	)
	(segment
		(start 350.652334 -218.692476)
		(end 350.65208 -218.692222)
		(width 0.13208)
		(layer "F.Cu")
		(net "UPI_CPU1_CPU0_P1P0_DN<14>")
	)
	(segment
		(start 350.459294 -216.74328)
		(end 350.456246 -216.745058)
		(width 0.0889)
		(layer "In4.Cu")
		(net "UPI_CPU1_CPU0_P1P0_DN<14>")
	)
	(segment
		(start 350.495616 -218.421204)
		(end 350.65208 -218.692222)
		(width 0.0889)
		(layer "In4.Cu")
		(net "UPI_CPU1_CPU0_P1P0_DN<14>")
	)
	(segment
		(start 350.708976 -212.107018)
		(end 350.27743 -212.487256)
		(width 0.0889)
		(layer "In4.Cu")
		(net "UPI_CPU1_CPU0_P1P0_DN<14>")
	)
	(segment
		(start 120.75541 -215.761062)
		(end 120.7643 -215.755982)
		(width 0.0889)
		(layer "In4.Cu")
		(net "UPI_CPU1_CPU0_P1P0_DN<14>")
	)
	(segment
		(start 350.747076 -214.424768)
		(end 350.747076 -214.644732)
		(width 0.0889)
		(layer "In4.Cu")
		(net "UPI_CPU1_CPU0_P1P0_DN<14>")
	)
	(segment
		(start 350.467676 -215.762586)
		(end 350.470978 -215.764618)
		(width 0.0889)
		(layer "In4.Cu")
		(net "UPI_CPU1_CPU0_P1P0_DN<14>")
	)
	(segment
		(start 157.875732 -177.465482)
		(end 200.53173 -176.75733)
		(width 0.14732)
		(layer "In4.Cu")
		(net "UPI_CPU1_CPU0_P1P0_DN<14>")
	)
	(segment
		(start 120.94337 -213.05266)
		(end 120.94337 -212.86978)
		(width 0.0889)
		(layer "In4.Cu")
		(net "UPI_CPU1_CPU0_P1P0_DN<14>")
	)
	(segment
		(start 350.464374 -216.740486)
		(end 350.459294 -216.74328)
		(width 0.0889)
		(layer "In4.Cu")
		(net "UPI_CPU1_CPU0_P1P0_DN<14>")
	)
	(segment
		(start 130.815334 -194.143884)
		(end 137.106914 -189.96279)
		(width 0.14732)
		(layer "In4.Cu")
		(net "UPI_CPU1_CPU0_P1P0_DN<14>")
	)
	(segment
		(start 121.225056 -214.946992)
		(end 121.233946 -214.941912)
		(width 0.0889)
		(layer "In4.Cu")
		(net "UPI_CPU1_CPU0_P1P0_DN<14>")
	)
	(segment
		(start 350.708976 -211.678012)
		(end 350.708976 -212.107018)
		(width 0.0889)
		(layer "In4.Cu")
		(net "UPI_CPU1_CPU0_P1P0_DN<14>")
	)
	(segment
		(start 120.94337 -213.42604)
		(end 120.84431 -213.32698)
		(width 0.0889)
		(layer "In4.Cu")
		(net "UPI_CPU1_CPU0_P1P0_DN<14>")
	)
	(segment
		(start 329.277472 -181.934866)
		(end 335.906618 -184.743344)
		(width 0.14732)
		(layer "In4.Cu")
		(net "UPI_CPU1_CPU0_P1P0_DN<14>")
	)
	(segment
		(start 120.84431 -212.77072)
		(end 120.84431 -212.59546)
		(width 0.0889)
		(layer "In4.Cu")
		(net "UPI_CPU1_CPU0_P1P0_DN<14>")
	)
	(segment
		(start 335.906618 -184.743344)
		(end 336.869532 -185.392568)
		(width 0.14732)
		(layer "In4.Cu")
		(net "UPI_CPU1_CPU0_P1P0_DN<14>")
	)
	(segment
		(start 120.90146 -211.699602)
		(end 120.901206 -211.699348)
		(width 0.14732)
		(layer "In4.Cu")
		(net "UPI_CPU1_CPU0_P1P0_DN<14>")
	)
	(segment
		(start 273.137122 -177.067464)
		(end 302.483012 -176.35474)
		(width 0.14732)
		(layer "In4.Cu")
		(net "UPI_CPU1_CPU0_P1P0_DN<14>")
	)
	(segment
		(start 141.442694 -184.142126)
		(end 143.891762 -182.888382)
		(width 0.14732)
		(layer "In4.Cu")
		(net "UPI_CPU1_CPU0_P1P0_DN<14>")
	)
	(segment
		(start 238.615728 -177.23231)
		(end 273.137122 -177.067464)
		(width 0.14732)
		(layer "In4.Cu")
		(net "UPI_CPU1_CPU0_P1P0_DN<14>")
	)
	(segment
		(start 120.943116 -213.930484)
		(end 120.94337 -213.893908)
		(width 0.0889)
		(layer "In4.Cu")
		(net "UPI_CPU1_CPU0_P1P0_DN<14>")
	)
	(segment
		(start 336.869532 -185.392568)
		(end 340.022942 -188.545978)
		(width 0.14732)
		(layer "In4.Cu")
		(net "UPI_CPU1_CPU0_P1P0_DN<14>")
	)
	(segment
		(start 348.398338 -198.188326)
		(end 350.75114 -203.868274)
		(width 0.14732)
		(layer "In4.Cu")
		(net "UPI_CPU1_CPU0_P1P0_DN<14>")
	)
	(segment
		(start 350.27743 -213.8934)
		(end 350.277684 -213.893908)
		(width 0.0889)
		(layer "In4.Cu")
		(net "UPI_CPU1_CPU0_P1P0_DN<14>")
	)
	(segment
		(start 350.519746 -218.33205)
		(end 350.495616 -218.421204)
		(width 0.0889)
		(layer "In4.Cu")
		(net "UPI_CPU1_CPU0_P1P0_DN<14>")
	)
	(segment
		(start 120.568212 -217.064336)
		(end 120.724676 -217.335354)
		(width 0.0889)
		(layer "In4.Cu")
		(net "UPI_CPU1_CPU0_P1P0_DN<14>")
	)
	(segment
		(start 316.913768 -177.607976)
		(end 329.277472 -181.934866)
		(width 0.14732)
		(layer "In4.Cu")
		(net "UPI_CPU1_CPU0_P1P0_DN<14>")
	)
	(segment
		(start 350.27743 -212.487256)
		(end 350.27743 -213.8934)
		(width 0.0889)
		(layer "In4.Cu")
		(net "UPI_CPU1_CPU0_P1P0_DN<14>")
	)
	(segment
		(start 120.94337 -212.066378)
		(end 120.90146 -212.024468)
		(width 0.0889)
		(layer "In4.Cu")
		(net "UPI_CPU1_CPU0_P1P0_DN<14>")
	)
	(segment
		(start 137.106914 -189.96279)
		(end 141.442694 -184.142126)
		(width 0.14732)
		(layer "In4.Cu")
		(net "UPI_CPU1_CPU0_P1P0_DN<14>")
	)
	(segment
		(start 121.412508 -214.622634)
		(end 121.412508 -214.461344)
		(width 0.0889)
		(layer "In4.Cu")
		(net "UPI_CPU1_CPU0_P1P0_DN<14>")
	)
	(segment
		(start 302.494696 -176.35474)
		(end 313.133232 -176.552098)
		(width 0.14732)
		(layer "In4.Cu")
		(net "UPI_CPU1_CPU0_P1P0_DN<14>")
	)
	(segment
		(start 350.75114 -203.868274)
		(end 350.75114 -211.61375)
		(width 0.14732)
		(layer "In4.Cu")
		(net "UPI_CPU1_CPU0_P1P0_DN<14>")
	)
	(segment
		(start 340.022942 -188.545978)
		(end 342.704674 -192.354454)
		(width 0.14732)
		(layer "In4.Cu")
		(net "UPI_CPU1_CPU0_P1P0_DN<14>")
	)
	(segment
		(start 350.747584 -216.25052)
		(end 350.747584 -216.260426)
		(width 0.0889)
		(layer "In4.Cu")
		(net "UPI_CPU1_CPU0_P1P0_DN<14>")
	)
	(segment
		(start 120.942862 -215.436704)
		(end 120.942862 -215.414606)
		(width 0.0889)
		(layer "In4.Cu")
		(net "UPI_CPU1_CPU0_P1P0_DN<14>")
	)
	(segment
		(start 120.90146 -212.00237)
		(end 120.90146 -211.699602)
		(width 0.14732)
		(layer "In4.Cu")
		(net "UPI_CPU1_CPU0_P1P0_DN<14>")
	)
	(segment
		(start 350.464882 -215.112346)
		(end 350.463866 -215.112854)
		(width 0.0889)
		(layer "In4.Cu")
		(net "UPI_CPU1_CPU0_P1P0_DN<14>")
	)
	(segment
		(start 120.84431 -213.32698)
		(end 120.84431 -213.15172)
		(width 0.0889)
		(layer "In4.Cu")
		(net "UPI_CPU1_CPU0_P1P0_DN<14>")
	)
	(segment
		(start 302.488854 -176.354486)
		(end 302.494442 -176.354486)
		(width 0.14732)
		(layer "In4.Cu")
		(net "UPI_CPU1_CPU0_P1P0_DN<14>")
	)
	(segment
		(start 350.456246 -217.383614)
		(end 350.465136 -217.388694)
		(width 0.0889)
		(layer "In4.Cu")
		(net "UPI_CPU1_CPU0_P1P0_DN<14>")
	)
	(segment
		(start 350.464882 -215.761062)
		(end 350.467676 -215.762586)
		(width 0.0889)
		(layer "In4.Cu")
		(net "UPI_CPU1_CPU0_P1P0_DN<14>")
	)
	(segment
		(start 143.891762 -182.888382)
		(end 151.094694 -179.20081)
		(width 0.14732)
		(layer "In4.Cu")
		(net "UPI_CPU1_CPU0_P1P0_DN<14>")
	)
	(segment
		(start 120.901206 -211.699348)
		(end 120.901206 -211.380832)
		(width 0.14732)
		(layer "In4.Cu")
		(net "UPI_CPU1_CPU0_P1P0_DN<14>")
	)
	(segment
		(start 350.75114 -211.61375)
		(end 350.75114 -211.635848)
		(width 0.0889)
		(layer "In4.Cu")
		(net "UPI_CPU1_CPU0_P1P0_DN<14>")
	)
	(segment
		(start 124.000006 -202.529948)
		(end 130.815334 -194.143884)
		(width 0.14732)
		(layer "In4.Cu")
		(net "UPI_CPU1_CPU0_P1P0_DN<14>")
	)
	(segment
		(start 350.747584 -217.859864)
		(end 350.747584 -217.878406)
		(width 0.0889)
		(layer "In4.Cu")
		(net "UPI_CPU1_CPU0_P1P0_DN<14>")
	)
	(segment
		(start 151.094694 -179.20081)
		(end 157.875732 -177.465482)
		(width 0.14732)
		(layer "In4.Cu")
		(net "UPI_CPU1_CPU0_P1P0_DN<14>")
	)
	(segment
		(start 120.84431 -212.59546)
		(end 120.94337 -212.4964)
		(width 0.0889)
		(layer "In4.Cu")
		(net "UPI_CPU1_CPU0_P1P0_DN<14>")
	)
	(segment
		(start 211.345526 -177.23231)
		(end 238.615728 -177.23231)
		(width 0.14732)
		(layer "In4.Cu")
		(net "UPI_CPU1_CPU0_P1P0_DN<14>")
	)
	(segment
		(start 120.94337 -212.86978)
		(end 120.84431 -212.77072)
		(width 0.0889)
		(layer "In4.Cu")
		(net "UPI_CPU1_CPU0_P1P0_DN<14>")
	)
	(segment
		(start 120.84431 -213.15172)
		(end 120.94337 -213.05266)
		(width 0.0889)
		(layer "In4.Cu")
		(net "UPI_CPU1_CPU0_P1P0_DN<14>")
	)
	(segment
		(start 313.133232 -176.552098)
		(end 316.913768 -177.607976)
		(width 0.14732)
		(layer "In4.Cu")
		(net "UPI_CPU1_CPU0_P1P0_DN<14>")
	)
	(segment
		(start 120.473216 -216.266014)
		(end 120.473216 -216.235026)
		(width 0.0889)
		(layer "In4.Cu")
		(net "UPI_CPU1_CPU0_P1P0_DN<14>")
	)
	(segment
		(start 350.463866 -215.112854)
		(end 350.455992 -215.117426)
		(width 0.0889)
		(layer "In4.Cu")
		(net "UPI_CPU1_CPU0_P1P0_DN<14>")
	)
	(segment
		(start 120.90146 -212.024468)
		(end 120.90146 -212.00237)
		(width 0.0889)
		(layer "In4.Cu")
		(net "UPI_CPU1_CPU0_P1P0_DN<14>")
	)
	(segment
		(start 350.465136 -216.739978)
		(end 350.464374 -216.740486)
		(width 0.0889)
		(layer "In4.Cu")
		(net "UPI_CPU1_CPU0_P1P0_DN<14>")
	)
	(segment
		(start 120.94337 -213.893908)
		(end 120.94337 -213.42604)
		(width 0.0889)
		(layer "In4.Cu")
		(net "UPI_CPU1_CPU0_P1P0_DN<14>")
	)
	(segment
		(start 350.463358 -215.7603)
		(end 350.464882 -215.761062)
		(width 0.0889)
		(layer "In4.Cu")
		(net "UPI_CPU1_CPU0_P1P0_DN<14>")
	)
	(segment
		(start 200.53173 -176.75733)
		(end 211.345526 -177.23231)
		(width 0.14732)
		(layer "In4.Cu")
		(net "UPI_CPU1_CPU0_P1P0_DN<14>")
	)
	(segment
		(start 342.704674 -192.354454)
		(end 348.398338 -198.188326)
		(width 0.14732)
		(layer "In4.Cu")
		(net "UPI_CPU1_CPU0_P1P0_DN<14>")
	)
	(segment
		(start 120.7643 -216.745058)
		(end 120.756426 -216.740486)
		(width 0.0889)
		(layer "In4.Cu")
		(net "UPI_CPU1_CPU0_P1P0_DN<14>")
	)
	(segment
		(start 302.494442 -176.354486)
		(end 302.494696 -176.35474)
		(width 0.14732)
		(layer "In4.Cu")
		(net "UPI_CPU1_CPU0_P1P0_DN<14>")
	)
	(segment
		(start 120.724676 -217.335354)
		(end 120.802908 -217.356182)
		(width 0.0889)
		(layer "In4.Cu")
		(net "UPI_CPU1_CPU0_P1P0_DN<14>")
	)
	(segment
		(start 120.94337 -212.4964)
		(end 120.94337 -212.066378)
		(width 0.0889)
		(layer "In4.Cu")
		(net "UPI_CPU1_CPU0_P1P0_DN<14>")
	)
	(segment
		(start 302.483012 -176.35474)
		(end 302.488854 -176.354486)
		(width 0.14732)
		(layer "In4.Cu")
		(net "UPI_CPU1_CPU0_P1P0_DN<14>")
	)
	(segment
		(start 120.901206 -211.380832)
		(end 124.000006 -202.529948)
		(width 0.14732)
		(layer "In4.Cu")
		(net "UPI_CPU1_CPU0_P1P0_DN<14>")
	)
	(segment
		(start 120.756426 -216.740486)
		(end 120.75541 -216.739978)
		(width 0.0889)
		(layer "In4.Cu")
		(net "UPI_CPU1_CPU0_P1P0_DN<14>")
	)
	(segment
		(start 350.75114 -211.635848)
		(end 350.708976 -211.678012)
		(width 0.0889)
		(layer "In4.Cu")
		(net "UPI_CPU1_CPU0_P1P0_DN<14>")
	)
	(segment
		(start 350.455992 -215.755982)
		(end 350.463358 -215.7603)
		(width 0.0889)
		(layer "In4.Cu")
		(net "UPI_CPU1_CPU0_P1P0_DN<14>")
	)
	(arc
		(start 350.536764 -218.318842)
		(mid 350.528318 -218.325527)
		(end 350.519746 -218.33205)
		(width 0.0889)
		(layer "In4.Cu")
		(net "UPI_CPU1_CPU0_P1P0_DN<14>")
	)
	(arc
		(start 120.942862 -215.414606)
		(mid 121.023773 -215.144478)
		(end 121.225056 -214.946992)
		(width 0.0889)
		(layer "In4.Cu")
		(net "UPI_CPU1_CPU0_P1P0_DN<14>")
	)
	(arc
		(start 120.75541 -216.739978)
		(mid 120.552587 -216.539747)
		(end 120.473216 -216.266014)
		(width 0.0889)
		(layer "In4.Cu")
		(net "UPI_CPU1_CPU0_P1P0_DN<14>")
	)
	(arc
		(start 350.455992 -215.117426)
		(mid 350.328738 -215.247392)
		(end 350.277684 -215.421972)
		(width 0.0889)
		(layer "In4.Cu")
		(net "UPI_CPU1_CPU0_P1P0_DN<14>")
	)
	(arc
		(start 350.465136 -217.388694)
		(mid 350.667422 -217.587675)
		(end 350.747584 -217.859864)
		(width 0.0889)
		(layer "In4.Cu")
		(net "UPI_CPU1_CPU0_P1P0_DN<14>")
	)
	(arc
		(start 350.747584 -217.878406)
		(mid 350.692229 -218.122593)
		(end 350.536764 -218.318842)
		(width 0.0889)
		(layer "In4.Cu")
		(net "UPI_CPU1_CPU0_P1P0_DN<14>")
	)
	(arc
		(start 350.277684 -213.893908)
		(mid 350.352689 -214.009367)
		(end 350.461834 -214.093298)
		(width 0.0889)
		(layer "In4.Cu")
		(net "UPI_CPU1_CPU0_P1P0_DN<14>")
	)
	(arc
		(start 120.7643 -215.755982)
		(mid 120.895214 -215.619622)
		(end 120.942862 -215.436704)
		(width 0.0889)
		(layer "In4.Cu")
		(net "UPI_CPU1_CPU0_P1P0_DN<14>")
	)
	(arc
		(start 350.747584 -216.260426)
		(mid 350.669473 -216.537375)
		(end 350.465136 -216.739978)
		(width 0.0889)
		(layer "In4.Cu")
		(net "UPI_CPU1_CPU0_P1P0_DN<14>")
	)
	(arc
		(start 350.747076 -214.644732)
		(mid 350.666165 -214.91486)
		(end 350.464882 -215.112346)
		(width 0.0889)
		(layer "In4.Cu")
		(net "UPI_CPU1_CPU0_P1P0_DN<14>")
	)
	(arc
		(start 350.277684 -215.421972)
		(mid 350.277487 -215.429337)
		(end 350.27743 -215.436704)
		(width 0.0889)
		(layer "In4.Cu")
		(net "UPI_CPU1_CPU0_P1P0_DN<14>")
	)
	(arc
		(start 121.412508 -214.461344)
		(mid 121.337503 -214.345885)
		(end 121.228358 -214.261954)
		(width 0.0889)
		(layer "In4.Cu")
		(net "UPI_CPU1_CPU0_P1P0_DN<14>")
	)
	(arc
		(start 120.802908 -217.356182)
		(mid 120.906053 -217.226157)
		(end 120.942862 -217.064336)
		(width 0.0889)
		(layer "In4.Cu")
		(net "UPI_CPU1_CPU0_P1P0_DN<14>")
	)
	(arc
		(start 120.958356 -213.969346)
		(mid 120.950393 -213.950049)
		(end 120.943116 -213.930484)
		(width 0.0889)
		(layer "In4.Cu")
		(net "UPI_CPU1_CPU0_P1P0_DN<14>")
	)
	(arc
		(start 350.470978 -215.764618)
		(mid 350.673565 -215.970969)
		(end 350.747584 -216.25052)
		(width 0.0889)
		(layer "In4.Cu")
		(net "UPI_CPU1_CPU0_P1P0_DN<14>")
	)
	(arc
		(start 350.456246 -216.745058)
		(mid 350.277649 -217.064336)
		(end 350.456246 -217.383614)
		(width 0.0889)
		(layer "In4.Cu")
		(net "UPI_CPU1_CPU0_P1P0_DN<14>")
	)
	(arc
		(start 350.461834 -214.093298)
		(mid 350.635797 -214.232062)
		(end 350.747076 -214.424768)
		(width 0.0889)
		(layer "In4.Cu")
		(net "UPI_CPU1_CPU0_P1P0_DN<14>")
	)
	(arc
		(start 121.233946 -214.941912)
		(mid 121.36486 -214.805552)
		(end 121.412508 -214.622634)
		(width 0.0889)
		(layer "In4.Cu")
		(net "UPI_CPU1_CPU0_P1P0_DN<14>")
	)
	(arc
		(start 121.228358 -214.261954)
		(mid 121.068286 -214.138774)
		(end 120.958356 -213.969346)
		(width 0.0889)
		(layer "In4.Cu")
		(net "UPI_CPU1_CPU0_P1P0_DN<14>")
	)
	(arc
		(start 120.942862 -217.064336)
		(mid 120.895183 -216.881436)
		(end 120.7643 -216.745058)
		(width 0.0889)
		(layer "In4.Cu")
		(net "UPI_CPU1_CPU0_P1P0_DN<14>")
	)
	(arc
		(start 120.473216 -216.235026)
		(mid 120.552586 -215.961292)
		(end 120.75541 -215.761062)
		(width 0.0889)
		(layer "In4.Cu")
		(net "UPI_CPU1_CPU0_P1P0_DN<14>")
	)
	(arc
		(start 350.27743 -215.436704)
		(mid 350.325109 -215.619604)
		(end 350.455992 -215.755982)
		(width 0.0889)
		(layer "In4.Cu")
		(net "UPI_CPU1_CPU0_P1P0_DN<14>")
	)
	(segment
		(start 349.24238 -217.87866)
		(end 349.242634 -217.878406)
		(width 0.13208)
		(layer "F.Cu")
		(net "UPI_CPU1_CPU0_P1P0_DN<13>")
	)
	(segment
		(start 349.24238 -218.414346)
		(end 349.24238 -217.87866)
		(width 0.13208)
		(layer "F.Cu")
		(net "UPI_CPU1_CPU0_P1P0_DN<13>")
	)
	(segment
		(start 121.977912 -217.87866)
		(end 121.978166 -217.878406)
		(width 0.13208)
		(layer "F.Cu")
		(net "UPI_CPU1_CPU0_P1P0_DN<13>")
	)
	(segment
		(start 121.977912 -218.414346)
		(end 121.977912 -217.87866)
		(width 0.13208)
		(layer "F.Cu")
		(net "UPI_CPU1_CPU0_P1P0_DN<13>")
	)
	(segment
		(start 122.073416 -213.897972)
		(end 122.073162 -213.897718)
		(width 0.0889)
		(layer "In4.Cu")
		(net "UPI_CPU1_CPU0_P1P0_DN<13>")
	)
	(segment
		(start 123.558046 -207.87995)
		(end 123.702318 -207.4672)
		(width 0.14732)
		(layer "In4.Cu")
		(net "UPI_CPU1_CPU0_P1P0_DN<13>")
	)
	(segment
		(start 123.627388 -207.311752)
		(end 123.777248 -206.883508)
		(width 0.14732)
		(layer "In4.Cu")
		(net "UPI_CPU1_CPU0_P1P0_DN<13>")
	)
	(segment
		(start 124.077222 -206.396082)
		(end 124.002292 -206.240888)
		(width 0.14732)
		(layer "In4.Cu")
		(net "UPI_CPU1_CPU0_P1P0_DN<13>")
	)
	(segment
		(start 125.040644 -203.644246)
		(end 125.18517 -203.231496)
		(width 0.14732)
		(layer "In4.Cu")
		(net "UPI_CPU1_CPU0_P1P0_DN<13>")
	)
	(segment
		(start 349.63608 -211.217764)
		(end 349.105728 -211.748116)
		(width 0.14732)
		(layer "In4.Cu")
		(net "UPI_CPU1_CPU0_P1P0_DN<13>")
	)
	(segment
		(start 273.156172 -178.198526)
		(end 302.492156 -177.48631)
		(width 0.14732)
		(layer "In4.Cu")
		(net "UPI_CPU1_CPU0_P1P0_DN<13>")
	)
	(segment
		(start 121.78665 -215.928702)
		(end 121.789952 -215.92667)
		(width 0.0889)
		(layer "In4.Cu")
		(net "UPI_CPU1_CPU0_P1P0_DN<13>")
	)
	(segment
		(start 122.115326 -211.699602)
		(end 122.115072 -211.699348)
		(width 0.14732)
		(layer "In4.Cu")
		(net "UPI_CPU1_CPU0_P1P0_DN<13>")
	)
	(segment
		(start 125.207014 -202.799696)
		(end 131.557776 -194.986402)
		(width 0.14732)
		(layer "In4.Cu")
		(net "UPI_CPU1_CPU0_P1P0_DN<13>")
	)
	(segment
		(start 349.63608 -204.108558)
		(end 349.63608 -211.217764)
		(width 0.14732)
		(layer "In4.Cu")
		(net "UPI_CPU1_CPU0_P1P0_DN<13>")
	)
	(segment
		(start 349.438722 -216.569798)
		(end 349.431356 -216.574116)
		(width 0.0889)
		(layer "In4.Cu")
		(net "UPI_CPU1_CPU0_P1P0_DN<13>")
	)
	(segment
		(start 121.785126 -215.929464)
		(end 121.78665 -215.928702)
		(width 0.0889)
		(layer "In4.Cu")
		(net "UPI_CPU1_CPU0_P1P0_DN<13>")
	)
	(segment
		(start 302.492156 -177.48631)
		(end 313.055254 -177.682398)
		(width 0.14732)
		(layer "In4.Cu")
		(net "UPI_CPU1_CPU0_P1P0_DN<13>")
	)
	(segment
		(start 121.782078 -215.931242)
		(end 121.785126 -215.929464)
		(width 0.0889)
		(layer "In4.Cu")
		(net "UPI_CPU1_CPU0_P1P0_DN<13>")
	)
	(segment
		(start 349.423736 -215.922606)
		(end 349.42907 -215.925654)
		(width 0.0889)
		(layer "In4.Cu")
		(net "UPI_CPU1_CPU0_P1P0_DN<13>")
	)
	(segment
		(start 349.14713 -217.064336)
		(end 349.14713 -217.07856)
		(width 0.0889)
		(layer "In4.Cu")
		(net "UPI_CPU1_CPU0_P1P0_DN<13>")
	)
	(segment
		(start 349.429832 -216.574878)
		(end 349.427038 -216.576402)
		(width 0.0889)
		(layer "In4.Cu")
		(net "UPI_CPU1_CPU0_P1P0_DN<13>")
	)
	(segment
		(start 349.105728 -211.748116)
		(end 349.105728 -212.03793)
		(width 0.14732)
		(layer "In4.Cu")
		(net "UPI_CPU1_CPU0_P1P0_DN<13>")
	)
	(segment
		(start 122.073162 -213.08568)
		(end 122.073162 -212.78088)
		(width 0.0889)
		(layer "In4.Cu")
		(net "UPI_CPU1_CPU0_P1P0_DN<13>")
	)
	(segment
		(start 123.702318 -207.4672)
		(end 123.627388 -207.311752)
		(width 0.14732)
		(layer "In4.Cu")
		(net "UPI_CPU1_CPU0_P1P0_DN<13>")
	)
	(segment
		(start 124.302012 -205.75397)
		(end 124.446538 -205.34122)
		(width 0.14732)
		(layer "In4.Cu")
		(net "UPI_CPU1_CPU0_P1P0_DN<13>")
	)
	(segment
		(start 273.150838 -178.19878)
		(end 273.150838 -178.198526)
		(width 0.14732)
		(layer "In4.Cu")
		(net "UPI_CPU1_CPU0_P1P0_DN<13>")
	)
	(segment
		(start 154.730704 -179.427632)
		(end 158.000446 -178.590702)
		(width 0.14732)
		(layer "In4.Cu")
		(net "UPI_CPU1_CPU0_P1P0_DN<13>")
	)
	(segment
		(start 123.302268 -208.609438)
		(end 123.227592 -208.45399)
		(width 0.14732)
		(layer "In4.Cu")
		(net "UPI_CPU1_CPU0_P1P0_DN<13>")
	)
	(segment
		(start 151.461216 -180.264308)
		(end 154.73045 -179.427632)
		(width 0.14732)
		(layer "In4.Cu")
		(net "UPI_CPU1_CPU0_P1P0_DN<13>")
	)
	(segment
		(start 341.865458 -193.08318)
		(end 347.432376 -198.788528)
		(width 0.14732)
		(layer "In4.Cu")
		(net "UPI_CPU1_CPU0_P1P0_DN<13>")
	)
	(segment
		(start 122.559318 -210.731608)
		(end 122.484388 -210.576414)
		(width 0.14732)
		(layer "In4.Cu")
		(net "UPI_CPU1_CPU0_P1P0_DN<13>")
	)
	(segment
		(start 349.105728 -212.060028)
		(end 349.147638 -212.101938)
		(width 0.0889)
		(layer "In4.Cu")
		(net "UPI_CPU1_CPU0_P1P0_DN<13>")
	)
	(segment
		(start 347.432376 -198.788528)
		(end 349.63608 -204.108558)
		(width 0.14732)
		(layer "In4.Cu")
		(net "UPI_CPU1_CPU0_P1P0_DN<13>")
	)
	(segment
		(start 335.373472 -185.71972)
		(end 336.17408 -186.258454)
		(width 0.14732)
		(layer "In4.Cu")
		(net "UPI_CPU1_CPU0_P1P0_DN<13>")
	)
	(segment
		(start 122.172222 -213.18474)
		(end 122.073162 -213.08568)
		(width 0.0889)
		(layer "In4.Cu")
		(net "UPI_CPU1_CPU0_P1P0_DN<13>")
	)
	(segment
		(start 124.371608 -205.186026)
		(end 124.51588 -204.773784)
		(width 0.14732)
		(layer "In4.Cu")
		(net "UPI_CPU1_CPU0_P1P0_DN<13>")
	)
	(segment
		(start 349.429832 -215.926162)
		(end 349.431356 -215.926924)
		(width 0.0889)
		(layer "In4.Cu")
		(net "UPI_CPU1_CPU0_P1P0_DN<13>")
	)
	(segment
		(start 122.928634 -209.676746)
		(end 122.853704 -209.521552)
		(width 0.14732)
		(layer "In4.Cu")
		(net "UPI_CPU1_CPU0_P1P0_DN<13>")
	)
	(segment
		(start 349.399098 -217.607388)
		(end 349.242634 -217.878406)
		(width 0.0889)
		(layer "In4.Cu")
		(net "UPI_CPU1_CPU0_P1P0_DN<13>")
	)
	(segment
		(start 122.073416 -217.082878)
		(end 122.073416 -217.05443)
		(width 0.0889)
		(layer "In4.Cu")
		(net "UPI_CPU1_CPU0_P1P0_DN<13>")
	)
	(segment
		(start 123.002294 -209.096864)
		(end 123.157996 -209.021934)
		(width 0.14732)
		(layer "In4.Cu")
		(net "UPI_CPU1_CPU0_P1P0_DN<13>")
	)
	(segment
		(start 122.073162 -213.897718)
		(end 122.073162 -213.45906)
		(width 0.0889)
		(layer "In4.Cu")
		(net "UPI_CPU1_CPU0_P1P0_DN<13>")
	)
	(segment
		(start 124.002292 -206.240888)
		(end 124.146564 -205.828646)
		(width 0.14732)
		(layer "In4.Cu")
		(net "UPI_CPU1_CPU0_P1P0_DN<13>")
	)
	(segment
		(start 122.542808 -214.644732)
		(end 122.542808 -214.424768)
		(width 0.0889)
		(layer "In4.Cu")
		(net "UPI_CPU1_CPU0_P1P0_DN<13>")
	)
	(segment
		(start 122.172222 -213.36)
		(end 122.172222 -213.18474)
		(width 0.0889)
		(layer "In4.Cu")
		(net "UPI_CPU1_CPU0_P1P0_DN<13>")
	)
	(segment
		(start 122.172222 -212.50656)
		(end 122.073162 -212.4075)
		(width 0.0889)
		(layer "In4.Cu")
		(net "UPI_CPU1_CPU0_P1P0_DN<13>")
	)
	(segment
		(start 349.147638 -213.929468)
		(end 349.147384 -213.929722)
		(width 0.0889)
		(layer "In4.Cu")
		(net "UPI_CPU1_CPU0_P1P0_DN<13>")
	)
	(segment
		(start 137.957052 -190.733426)
		(end 142.238222 -184.985914)
		(width 0.14732)
		(layer "In4.Cu")
		(net "UPI_CPU1_CPU0_P1P0_DN<13>")
	)
	(segment
		(start 349.438214 -214.941912)
		(end 349.429324 -214.946992)
		(width 0.0889)
		(layer "In4.Cu")
		(net "UPI_CPU1_CPU0_P1P0_DN<13>")
	)
	(segment
		(start 121.782078 -217.559128)
		(end 121.790968 -217.554048)
		(width 0.0889)
		(layer "In4.Cu")
		(net "UPI_CPU1_CPU0_P1P0_DN<13>")
	)
	(segment
		(start 349.147638 -212.101938)
		(end 349.147638 -213.929468)
		(width 0.0889)
		(layer "In4.Cu")
		(net "UPI_CPU1_CPU0_P1P0_DN<13>")
	)
	(segment
		(start 211.87918 -178.363372)
		(end 238.618776 -178.363372)
		(width 0.14732)
		(layer "In4.Cu")
		(net "UPI_CPU1_CPU0_P1P0_DN<13>")
	)
	(segment
		(start 122.115072 -211.699348)
		(end 122.115072 -211.631276)
		(width 0.14732)
		(layer "In4.Cu")
		(net "UPI_CPU1_CPU0_P1P0_DN<13>")
	)
	(segment
		(start 124.885196 -203.718922)
		(end 125.040644 -203.644246)
		(width 0.14732)
		(layer "In4.Cu")
		(net "UPI_CPU1_CPU0_P1P0_DN<13>")
	)
	(segment
		(start 238.618776 -178.363372)
		(end 273.150838 -178.19878)
		(width 0.14732)
		(layer "In4.Cu")
		(net "UPI_CPU1_CPU0_P1P0_DN<13>")
	)
	(segment
		(start 122.251724 -215.117426)
		(end 122.260614 -215.112346)
		(width 0.0889)
		(layer "In4.Cu")
		(net "UPI_CPU1_CPU0_P1P0_DN<13>")
	)
	(segment
		(start 122.073162 -215.452198)
		(end 122.073162 -215.436704)
		(width 0.0889)
		(layer "In4.Cu")
		(net "UPI_CPU1_CPU0_P1P0_DN<13>")
	)
	(segment
		(start 125.11024 -203.076302)
		(end 125.207014 -202.799696)
		(width 0.14732)
		(layer "In4.Cu")
		(net "UPI_CPU1_CPU0_P1P0_DN<13>")
	)
	(segment
		(start 146.849846 -182.624984)
		(end 151.461216 -180.264308)
		(width 0.14732)
		(layer "In4.Cu")
		(net "UPI_CPU1_CPU0_P1P0_DN<13>")
	)
	(segment
		(start 122.259344 -211.219034)
		(end 122.414792 -211.144358)
		(width 0.14732)
		(layer "In4.Cu")
		(net "UPI_CPU1_CPU0_P1P0_DN<13>")
	)
	(segment
		(start 124.671328 -204.699108)
		(end 124.815854 -204.286358)
		(width 0.14732)
		(layer "In4.Cu")
		(net "UPI_CPU1_CPU0_P1P0_DN<13>")
	)
	(segment
		(start 339.166962 -189.25159)
		(end 341.865458 -193.08318)
		(width 0.14732)
		(layer "In4.Cu")
		(net "UPI_CPU1_CPU0_P1P0_DN<13>")
	)
	(segment
		(start 349.431356 -215.926924)
		(end 349.438722 -215.931242)
		(width 0.0889)
		(layer "In4.Cu")
		(net "UPI_CPU1_CPU0_P1P0_DN<13>")
	)
	(segment
		(start 200.861168 -177.879502)
		(end 211.87918 -178.363372)
		(width 0.14732)
		(layer "In4.Cu")
		(net "UPI_CPU1_CPU0_P1P0_DN<13>")
	)
	(segment
		(start 273.150838 -178.198526)
		(end 273.156172 -178.198526)
		(width 0.14732)
		(layer "In4.Cu")
		(net "UPI_CPU1_CPU0_P1P0_DN<13>")
	)
	(segment
		(start 124.815854 -204.286358)
		(end 124.740924 -204.131164)
		(width 0.14732)
		(layer "In4.Cu")
		(net "UPI_CPU1_CPU0_P1P0_DN<13>")
	)
	(segment
		(start 349.147384 -213.929722)
		(end 349.147384 -213.930484)
		(width 0.0889)
		(layer "In4.Cu")
		(net "UPI_CPU1_CPU0_P1P0_DN<13>")
	)
	(segment
		(start 123.227592 -208.45399)
		(end 123.402344 -207.954626)
		(width 0.14732)
		(layer "In4.Cu")
		(net "UPI_CPU1_CPU0_P1P0_DN<13>")
	)
	(segment
		(start 336.17408 -186.258454)
		(end 339.166962 -189.25159)
		(width 0.14732)
		(layer "In4.Cu")
		(net "UPI_CPU1_CPU0_P1P0_DN<13>")
	)
	(segment
		(start 154.73045 -179.427632)
		(end 154.730704 -179.427632)
		(width 0.14732)
		(layer "In4.Cu")
		(net "UPI_CPU1_CPU0_P1P0_DN<13>")
	)
	(segment
		(start 123.402344 -207.954626)
		(end 123.558046 -207.87995)
		(width 0.14732)
		(layer "In4.Cu")
		(net "UPI_CPU1_CPU0_P1P0_DN<13>")
	)
	(segment
		(start 124.146564 -205.828646)
		(end 124.302012 -205.75397)
		(width 0.14732)
		(layer "In4.Cu")
		(net "UPI_CPU1_CPU0_P1P0_DN<13>")
	)
	(segment
		(start 121.821702 -218.149424)
		(end 121.74347 -218.170252)
		(width 0.0889)
		(layer "In4.Cu")
		(net "UPI_CPU1_CPU0_P1P0_DN<13>")
	)
	(segment
		(start 122.853704 -209.521552)
		(end 123.002294 -209.096864)
		(width 0.14732)
		(layer "In4.Cu")
		(net "UPI_CPU1_CPU0_P1P0_DN<13>")
	)
	(segment
		(start 124.446538 -205.34122)
		(end 124.371608 -205.186026)
		(width 0.14732)
		(layer "In4.Cu")
		(net "UPI_CPU1_CPU0_P1P0_DN<13>")
	)
	(segment
		(start 122.115326 -212.024468)
		(end 122.115326 -212.00237)
		(width 0.0889)
		(layer "In4.Cu")
		(net "UPI_CPU1_CPU0_P1P0_DN<13>")
	)
	(segment
		(start 123.93295 -206.808832)
		(end 124.077222 -206.396082)
		(width 0.14732)
		(layer "In4.Cu")
		(net "UPI_CPU1_CPU0_P1P0_DN<13>")
	)
	(segment
		(start 122.484388 -210.576414)
		(end 122.62866 -210.164172)
		(width 0.14732)
		(layer "In4.Cu")
		(net "UPI_CPU1_CPU0_P1P0_DN<13>")
	)
	(segment
		(start 123.157996 -209.021934)
		(end 123.302268 -208.609438)
		(width 0.14732)
		(layer "In4.Cu")
		(net "UPI_CPU1_CPU0_P1P0_DN<13>")
	)
	(segment
		(start 121.789952 -215.92667)
		(end 121.790968 -215.926162)
		(width 0.0889)
		(layer "In4.Cu")
		(net "UPI_CPU1_CPU0_P1P0_DN<13>")
	)
	(segment
		(start 122.784108 -210.089496)
		(end 122.928634 -209.676746)
		(width 0.14732)
		(layer "In4.Cu")
		(net "UPI_CPU1_CPU0_P1P0_DN<13>")
	)
	(segment
		(start 122.283728 -214.10803)
		(end 122.073416 -213.897972)
		(width 0.0889)
		(layer "In4.Cu")
		(net "UPI_CPU1_CPU0_P1P0_DN<13>")
	)
	(segment
		(start 349.42907 -215.925654)
		(end 349.429832 -215.926162)
		(width 0.0889)
		(layer "In4.Cu")
		(net "UPI_CPU1_CPU0_P1P0_DN<13>")
	)
	(segment
		(start 122.073162 -212.78088)
		(end 122.172222 -212.68182)
		(width 0.0889)
		(layer "In4.Cu")
		(net "UPI_CPU1_CPU0_P1P0_DN<13>")
	)
	(segment
		(start 349.374968 -217.518234)
		(end 349.399098 -217.607388)
		(width 0.0889)
		(layer "In4.Cu")
		(net "UPI_CPU1_CPU0_P1P0_DN<13>")
	)
	(segment
		(start 122.115072 -211.631276)
		(end 122.259344 -211.219034)
		(width 0.14732)
		(layer "In4.Cu")
		(net "UPI_CPU1_CPU0_P1P0_DN<13>")
	)
	(segment
		(start 123.777248 -206.883508)
		(end 123.93295 -206.808832)
		(width 0.14732)
		(layer "In4.Cu")
		(net "UPI_CPU1_CPU0_P1P0_DN<13>")
	)
	(segment
		(start 328.803254 -182.946294)
		(end 335.373472 -185.71972)
		(width 0.14732)
		(layer "In4.Cu")
		(net "UPI_CPU1_CPU0_P1P0_DN<13>")
	)
	(segment
		(start 122.414792 -211.144358)
		(end 122.559318 -210.731608)
		(width 0.14732)
		(layer "In4.Cu")
		(net "UPI_CPU1_CPU0_P1P0_DN<13>")
	)
	(segment
		(start 158.000446 -178.590702)
		(end 200.861168 -177.879502)
		(width 0.14732)
		(layer "In4.Cu")
		(net "UPI_CPU1_CPU0_P1P0_DN<13>")
	)
	(segment
		(start 349.427038 -216.576402)
		(end 349.423736 -216.578434)
		(width 0.0889)
		(layer "In4.Cu")
		(net "UPI_CPU1_CPU0_P1P0_DN<13>")
	)
	(segment
		(start 349.616776 -214.461344)
		(end 349.616776 -214.622634)
		(width 0.0889)
		(layer "In4.Cu")
		(net "UPI_CPU1_CPU0_P1P0_DN<13>")
	)
	(segment
		(start 122.073162 -212.066632)
		(end 122.115326 -212.024468)
		(width 0.0889)
		(layer "In4.Cu")
		(net "UPI_CPU1_CPU0_P1P0_DN<13>")
	)
	(segment
		(start 131.557776 -194.986402)
		(end 137.957052 -190.733426)
		(width 0.14732)
		(layer "In4.Cu")
		(net "UPI_CPU1_CPU0_P1P0_DN<13>")
	)
	(segment
		(start 349.105728 -212.03793)
		(end 349.105728 -212.060028)
		(width 0.0889)
		(layer "In4.Cu")
		(net "UPI_CPU1_CPU0_P1P0_DN<13>")
	)
	(segment
		(start 146.849846 -182.625238)
		(end 146.849846 -182.624984)
		(width 0.14732)
		(layer "In4.Cu")
		(net "UPI_CPU1_CPU0_P1P0_DN<13>")
	)
	(segment
		(start 121.790968 -216.574878)
		(end 121.782078 -216.569798)
		(width 0.0889)
		(layer "In4.Cu")
		(net "UPI_CPU1_CPU0_P1P0_DN<13>")
	)
	(segment
		(start 121.978166 -217.878406)
		(end 121.821702 -218.149424)
		(width 0.0889)
		(layer "In4.Cu")
		(net "UPI_CPU1_CPU0_P1P0_DN<13>")
	)
	(segment
		(start 313.055254 -177.682398)
		(end 316.52464 -178.653948)
		(width 0.14732)
		(layer "In4.Cu")
		(net "UPI_CPU1_CPU0_P1P0_DN<13>")
	)
	(segment
		(start 124.740924 -204.131164)
		(end 124.885196 -203.718922)
		(width 0.14732)
		(layer "In4.Cu")
		(net "UPI_CPU1_CPU0_P1P0_DN<13>")
	)
	(segment
		(start 316.52464 -178.653948)
		(end 328.803254 -182.946294)
		(width 0.14732)
		(layer "In4.Cu")
		(net "UPI_CPU1_CPU0_P1P0_DN<13>")
	)
	(segment
		(start 124.51588 -204.773784)
		(end 124.671328 -204.699108)
		(width 0.14732)
		(layer "In4.Cu")
		(net "UPI_CPU1_CPU0_P1P0_DN<13>")
	)
	(segment
		(start 142.238222 -184.985914)
		(end 146.849846 -182.625238)
		(width 0.14732)
		(layer "In4.Cu")
		(net "UPI_CPU1_CPU0_P1P0_DN<13>")
	)
	(segment
		(start 349.14713 -215.414606)
		(end 349.14713 -215.436704)
		(width 0.0889)
		(layer "In4.Cu")
		(net "UPI_CPU1_CPU0_P1P0_DN<13>")
	)
	(segment
		(start 122.073162 -212.4075)
		(end 122.073162 -212.066632)
		(width 0.0889)
		(layer "In4.Cu")
		(net "UPI_CPU1_CPU0_P1P0_DN<13>")
	)
	(segment
		(start 349.431356 -216.574116)
		(end 349.429832 -216.574878)
		(width 0.0889)
		(layer "In4.Cu")
		(net "UPI_CPU1_CPU0_P1P0_DN<13>")
	)
	(segment
		(start 122.073162 -213.45906)
		(end 122.172222 -213.36)
		(width 0.0889)
		(layer "In4.Cu")
		(net "UPI_CPU1_CPU0_P1P0_DN<13>")
	)
	(segment
		(start 122.62866 -210.164172)
		(end 122.784108 -210.089496)
		(width 0.14732)
		(layer "In4.Cu")
		(net "UPI_CPU1_CPU0_P1P0_DN<13>")
	)
	(segment
		(start 122.172222 -212.68182)
		(end 122.172222 -212.50656)
		(width 0.0889)
		(layer "In4.Cu")
		(net "UPI_CPU1_CPU0_P1P0_DN<13>")
	)
	(segment
		(start 125.18517 -203.231496)
		(end 125.11024 -203.076302)
		(width 0.14732)
		(layer "In4.Cu")
		(net "UPI_CPU1_CPU0_P1P0_DN<13>")
	)
	(segment
		(start 122.115326 -212.00237)
		(end 122.115326 -211.699602)
		(width 0.14732)
		(layer "In4.Cu")
		(net "UPI_CPU1_CPU0_P1P0_DN<13>")
	)
	(arc
		(start 121.74347 -218.170252)
		(mid 121.640325 -218.040227)
		(end 121.603516 -217.878406)
		(width 0.0889)
		(layer "In4.Cu")
		(net "UPI_CPU1_CPU0_P1P0_DN<13>")
	)
	(arc
		(start 349.35795 -217.50528)
		(mid 349.366398 -217.511837)
		(end 349.374968 -217.518234)
		(width 0.0889)
		(layer "In4.Cu")
		(net "UPI_CPU1_CPU0_P1P0_DN<13>")
	)
	(arc
		(start 349.432626 -214.261954)
		(mid 349.541773 -214.345882)
		(end 349.616776 -214.461344)
		(width 0.0889)
		(layer "In4.Cu")
		(net "UPI_CPU1_CPU0_P1P0_DN<13>")
	)
	(arc
		(start 349.438722 -215.931242)
		(mid 349.617319 -216.25052)
		(end 349.438722 -216.569798)
		(width 0.0889)
		(layer "In4.Cu")
		(net "UPI_CPU1_CPU0_P1P0_DN<13>")
	)
	(arc
		(start 121.603516 -216.24036)
		(mid 121.653654 -216.063188)
		(end 121.782078 -215.931242)
		(width 0.0889)
		(layer "In4.Cu")
		(net "UPI_CPU1_CPU0_P1P0_DN<13>")
	)
	(arc
		(start 349.162624 -213.969346)
		(mid 349.272618 -214.138715)
		(end 349.432626 -214.261954)
		(width 0.0889)
		(layer "In4.Cu")
		(net "UPI_CPU1_CPU0_P1P0_DN<13>")
	)
	(arc
		(start 122.073416 -215.421972)
		(mid 122.12447 -215.247392)
		(end 122.251724 -215.117426)
		(width 0.0889)
		(layer "In4.Cu")
		(net "UPI_CPU1_CPU0_P1P0_DN<13>")
	)
	(arc
		(start 349.14713 -215.436704)
		(mid 349.221121 -215.71627)
		(end 349.423736 -215.922606)
		(width 0.0889)
		(layer "In4.Cu")
		(net "UPI_CPU1_CPU0_P1P0_DN<13>")
	)
	(arc
		(start 122.073162 -215.436704)
		(mid 122.073214 -215.429337)
		(end 122.073416 -215.421972)
		(width 0.0889)
		(layer "In4.Cu")
		(net "UPI_CPU1_CPU0_P1P0_DN<13>")
	)
	(arc
		(start 121.790968 -215.926162)
		(mid 121.993791 -215.725931)
		(end 122.073162 -215.452198)
		(width 0.0889)
		(layer "In4.Cu")
		(net "UPI_CPU1_CPU0_P1P0_DN<13>")
	)
	(arc
		(start 349.147384 -213.930484)
		(mid 349.154669 -213.950046)
		(end 349.162624 -213.969346)
		(width 0.0889)
		(layer "In4.Cu")
		(net "UPI_CPU1_CPU0_P1P0_DN<13>")
	)
	(arc
		(start 121.790968 -217.554048)
		(mid 121.993254 -217.355067)
		(end 122.073416 -217.082878)
		(width 0.0889)
		(layer "In4.Cu")
		(net "UPI_CPU1_CPU0_P1P0_DN<13>")
	)
	(arc
		(start 349.423736 -216.578434)
		(mid 349.221149 -216.784785)
		(end 349.14713 -217.064336)
		(width 0.0889)
		(layer "In4.Cu")
		(net "UPI_CPU1_CPU0_P1P0_DN<13>")
	)
	(arc
		(start 122.542808 -214.424768)
		(mid 122.441179 -214.243564)
		(end 122.283728 -214.10803)
		(width 0.0889)
		(layer "In4.Cu")
		(net "UPI_CPU1_CPU0_P1P0_DN<13>")
	)
	(arc
		(start 121.603516 -217.878406)
		(mid 121.651195 -217.695506)
		(end 121.782078 -217.559128)
		(width 0.0889)
		(layer "In4.Cu")
		(net "UPI_CPU1_CPU0_P1P0_DN<13>")
	)
	(arc
		(start 122.260614 -215.112346)
		(mid 122.461896 -214.914859)
		(end 122.542808 -214.644732)
		(width 0.0889)
		(layer "In4.Cu")
		(net "UPI_CPU1_CPU0_P1P0_DN<13>")
	)
	(arc
		(start 349.14713 -217.07856)
		(mid 349.205424 -217.315203)
		(end 349.35795 -217.50528)
		(width 0.0889)
		(layer "In4.Cu")
		(net "UPI_CPU1_CPU0_P1P0_DN<13>")
	)
	(arc
		(start 122.073416 -217.05443)
		(mid 121.995305 -216.777481)
		(end 121.790968 -216.574878)
		(width 0.0889)
		(layer "In4.Cu")
		(net "UPI_CPU1_CPU0_P1P0_DN<13>")
	)
	(arc
		(start 121.782078 -216.569798)
		(mid 121.652789 -216.436312)
		(end 121.603516 -216.257124)
		(width 0.0889)
		(layer "In4.Cu")
		(net "UPI_CPU1_CPU0_P1P0_DN<13>")
	)
	(arc
		(start 349.616776 -214.622634)
		(mid 349.569097 -214.805534)
		(end 349.438214 -214.941912)
		(width 0.0889)
		(layer "In4.Cu")
		(net "UPI_CPU1_CPU0_P1P0_DN<13>")
	)
	(arc
		(start 349.429324 -214.946992)
		(mid 349.228042 -215.144479)
		(end 349.14713 -215.414606)
		(width 0.0889)
		(layer "In4.Cu")
		(net "UPI_CPU1_CPU0_P1P0_DN<13>")
	)
	(arc
		(start 121.603516 -216.257124)
		(mid 121.603422 -216.248742)
		(end 121.603516 -216.24036)
		(width 0.0889)
		(layer "In4.Cu")
		(net "UPI_CPU1_CPU0_P1P0_DN<13>")
	)
	(segment
		(start 122.448066 -217.06459)
		(end 122.447812 -217.064336)
		(width 0.13208)
		(layer "F.Cu")
		(net "UPI_CPU1_CPU0_P1P0_DN<12>")
	)
	(segment
		(start 348.772734 -219.228162)
		(end 348.772734 -218.692476)
		(width 0.13208)
		(layer "F.Cu")
		(net "UPI_CPU1_CPU0_P1P0_DN<12>")
	)
	(segment
		(start 122.448066 -217.600276)
		(end 122.448066 -217.06459)
		(width 0.13208)
		(layer "F.Cu")
		(net "UPI_CPU1_CPU0_P1P0_DN<12>")
	)
	(segment
		(start 348.772734 -218.692476)
		(end 348.77248 -218.692222)
		(width 0.13208)
		(layer "F.Cu")
		(net "UPI_CPU1_CPU0_P1P0_DN<12>")
	)
	(segment
		(start 348.584774 -216.740486)
		(end 348.579694 -216.74328)
		(width 0.0889)
		(layer "In4.Cu")
		(net "UPI_CPU1_CPU0_P1P0_DN<12>")
	)
	(segment
		(start 341.457534 -193.470276)
		(end 346.962984 -199.112378)
		(width 0.14732)
		(layer "In4.Cu")
		(net "UPI_CPU1_CPU0_P1P0_DN<12>")
	)
	(segment
		(start 122.604276 -217.335354)
		(end 122.682508 -217.356182)
		(width 0.0889)
		(layer "In4.Cu")
		(net "UPI_CPU1_CPU0_P1P0_DN<12>")
	)
	(segment
		(start 349.04172 -204.130656)
		(end 349.04172 -211.008722)
		(width 0.14732)
		(layer "In4.Cu")
		(net "UPI_CPU1_CPU0_P1P0_DN<12>")
	)
	(segment
		(start 348.39783 -212.089492)
		(end 348.39783 -213.8934)
		(width 0.0889)
		(layer "In4.Cu")
		(net "UPI_CPU1_CPU0_P1P0_DN<12>")
	)
	(segment
		(start 348.584266 -215.112854)
		(end 348.576392 -215.117426)
		(width 0.0889)
		(layer "In4.Cu")
		(net "UPI_CPU1_CPU0_P1P0_DN<12>")
	)
	(segment
		(start 302.488092 -178.068986)
		(end 302.493934 -178.068732)
		(width 0.14732)
		(layer "In4.Cu")
		(net "UPI_CPU1_CPU0_P1P0_DN<12>")
	)
	(segment
		(start 122.72391 -212.73262)
		(end 122.72391 -212.55736)
		(width 0.0889)
		(layer "In4.Cu")
		(net "UPI_CPU1_CPU0_P1P0_DN<12>")
	)
	(segment
		(start 122.6439 -216.745058)
		(end 122.636026 -216.740486)
		(width 0.0889)
		(layer "In4.Cu")
		(net "UPI_CPU1_CPU0_P1P0_DN<12>")
	)
	(segment
		(start 348.867984 -217.859864)
		(end 348.867984 -217.878406)
		(width 0.0889)
		(layer "In4.Cu")
		(net "UPI_CPU1_CPU0_P1P0_DN<12>")
	)
	(segment
		(start 123.292108 -214.622634)
		(end 123.292108 -214.461344)
		(width 0.0889)
		(layer "In4.Cu")
		(net "UPI_CPU1_CPU0_P1P0_DN<12>")
	)
	(segment
		(start 348.39783 -213.8934)
		(end 348.398084 -213.893908)
		(width 0.0889)
		(layer "In4.Cu")
		(net "UPI_CPU1_CPU0_P1P0_DN<12>")
	)
	(segment
		(start 122.82297 -212.83168)
		(end 122.72391 -212.73262)
		(width 0.0889)
		(layer "In4.Cu")
		(net "UPI_CPU1_CPU0_P1P0_DN<12>")
	)
	(segment
		(start 122.82297 -212.066378)
		(end 122.78106 -212.024468)
		(width 0.0889)
		(layer "In4.Cu")
		(net "UPI_CPU1_CPU0_P1P0_DN<12>")
	)
	(segment
		(start 122.82297 -213.38286)
		(end 122.72391 -213.2838)
		(width 0.0889)
		(layer "In4.Cu")
		(net "UPI_CPU1_CPU0_P1P0_DN<12>")
	)
	(segment
		(start 131.865624 -195.49237)
		(end 138.404854 -191.14516)
		(width 0.14732)
		(layer "In4.Cu")
		(net "UPI_CPU1_CPU0_P1P0_DN<12>")
	)
	(segment
		(start 348.585282 -215.112346)
		(end 348.584266 -215.112854)
		(width 0.0889)
		(layer "In4.Cu")
		(net "UPI_CPU1_CPU0_P1P0_DN<12>")
	)
	(segment
		(start 348.576646 -217.383614)
		(end 348.585536 -217.388694)
		(width 0.0889)
		(layer "In4.Cu")
		(net "UPI_CPU1_CPU0_P1P0_DN<12>")
	)
	(segment
		(start 348.616016 -218.421204)
		(end 348.77248 -218.692222)
		(width 0.0889)
		(layer "In4.Cu")
		(net "UPI_CPU1_CPU0_P1P0_DN<12>")
	)
	(segment
		(start 122.447812 -217.064336)
		(end 122.604276 -217.335354)
		(width 0.0889)
		(layer "In4.Cu")
		(net "UPI_CPU1_CPU0_P1P0_DN<12>")
	)
	(segment
		(start 348.439994 -211.791042)
		(end 348.439994 -212.02523)
		(width 0.14732)
		(layer "In4.Cu")
		(net "UPI_CPU1_CPU0_P1P0_DN<12>")
	)
	(segment
		(start 200.811384 -178.439064)
		(end 212.338412 -178.94554)
		(width 0.14732)
		(layer "In4.Cu")
		(net "UPI_CPU1_CPU0_P1P0_DN<12>")
	)
	(segment
		(start 316.297818 -179.168552)
		(end 328.58583 -183.466994)
		(width 0.14732)
		(layer "In4.Cu")
		(net "UPI_CPU1_CPU0_P1P0_DN<12>")
	)
	(segment
		(start 122.78106 -211.8106)
		(end 125.945138 -202.77582)
		(width 0.14732)
		(layer "In4.Cu")
		(net "UPI_CPU1_CPU0_P1P0_DN<12>")
	)
	(segment
		(start 122.72391 -213.2838)
		(end 122.72391 -213.10854)
		(width 0.0889)
		(layer "In4.Cu")
		(net "UPI_CPU1_CPU0_P1P0_DN<12>")
	)
	(segment
		(start 348.583758 -215.7603)
		(end 348.585282 -215.761062)
		(width 0.0889)
		(layer "In4.Cu")
		(net "UPI_CPU1_CPU0_P1P0_DN<12>")
	)
	(segment
		(start 122.78106 -212.00237)
		(end 122.78106 -211.8106)
		(width 0.14732)
		(layer "In4.Cu")
		(net "UPI_CPU1_CPU0_P1P0_DN<12>")
	)
	(segment
		(start 328.58583 -183.466994)
		(end 335.14919 -186.241944)
		(width 0.14732)
		(layer "In4.Cu")
		(net "UPI_CPU1_CPU0_P1P0_DN<12>")
	)
	(segment
		(start 238.6203 -178.94554)
		(end 273.162014 -178.780694)
		(width 0.14732)
		(layer "In4.Cu")
		(net "UPI_CPU1_CPU0_P1P0_DN<12>")
	)
	(segment
		(start 122.72391 -212.55736)
		(end 122.82297 -212.4583)
		(width 0.0889)
		(layer "In4.Cu")
		(net "UPI_CPU1_CPU0_P1P0_DN<12>")
	)
	(segment
		(start 122.72391 -213.10854)
		(end 122.82297 -213.00948)
		(width 0.0889)
		(layer "In4.Cu")
		(net "UPI_CPU1_CPU0_P1P0_DN<12>")
	)
	(segment
		(start 348.640146 -218.33205)
		(end 348.616016 -218.421204)
		(width 0.0889)
		(layer "In4.Cu")
		(net "UPI_CPU1_CPU0_P1P0_DN<12>")
	)
	(segment
		(start 142.677134 -185.410348)
		(end 151.716994 -180.78323)
		(width 0.14732)
		(layer "In4.Cu")
		(net "UPI_CPU1_CPU0_P1P0_DN<12>")
	)
	(segment
		(start 302.493934 -178.068732)
		(end 302.499522 -178.068732)
		(width 0.14732)
		(layer "In4.Cu")
		(net "UPI_CPU1_CPU0_P1P0_DN<12>")
	)
	(segment
		(start 302.499522 -178.068732)
		(end 302.499776 -178.068986)
		(width 0.14732)
		(layer "In4.Cu")
		(net "UPI_CPU1_CPU0_P1P0_DN<12>")
	)
	(segment
		(start 348.867476 -214.424768)
		(end 348.867476 -214.644732)
		(width 0.0889)
		(layer "In4.Cu")
		(net "UPI_CPU1_CPU0_P1P0_DN<12>")
	)
	(segment
		(start 125.945138 -202.77582)
		(end 131.865624 -195.49237)
		(width 0.14732)
		(layer "In4.Cu")
		(net "UPI_CPU1_CPU0_P1P0_DN<12>")
	)
	(segment
		(start 348.43974 -211.610702)
		(end 348.43974 -211.790788)
		(width 0.14732)
		(layer "In4.Cu")
		(net "UPI_CPU1_CPU0_P1P0_DN<12>")
	)
	(segment
		(start 335.14919 -186.241944)
		(end 335.831942 -186.701684)
		(width 0.14732)
		(layer "In4.Cu")
		(net "UPI_CPU1_CPU0_P1P0_DN<12>")
	)
	(segment
		(start 151.716994 -180.78323)
		(end 158.105856 -179.147724)
		(width 0.14732)
		(layer "In4.Cu")
		(net "UPI_CPU1_CPU0_P1P0_DN<12>")
	)
	(segment
		(start 348.576392 -215.755982)
		(end 348.583758 -215.7603)
		(width 0.0889)
		(layer "In4.Cu")
		(net "UPI_CPU1_CPU0_P1P0_DN<12>")
	)
	(segment
		(start 348.867984 -216.25052)
		(end 348.867984 -216.260426)
		(width 0.0889)
		(layer "In4.Cu")
		(net "UPI_CPU1_CPU0_P1P0_DN<12>")
	)
	(segment
		(start 348.585282 -215.761062)
		(end 348.588076 -215.762586)
		(width 0.0889)
		(layer "In4.Cu")
		(net "UPI_CPU1_CPU0_P1P0_DN<12>")
	)
	(segment
		(start 123.104656 -214.946992)
		(end 123.113546 -214.941912)
		(width 0.0889)
		(layer "In4.Cu")
		(net "UPI_CPU1_CPU0_P1P0_DN<12>")
	)
	(segment
		(start 138.404854 -191.14516)
		(end 142.677134 -185.410348)
		(width 0.14732)
		(layer "In4.Cu")
		(net "UPI_CPU1_CPU0_P1P0_DN<12>")
	)
	(segment
		(start 348.585536 -216.739978)
		(end 348.584774 -216.740486)
		(width 0.0889)
		(layer "In4.Cu")
		(net "UPI_CPU1_CPU0_P1P0_DN<12>")
	)
	(segment
		(start 122.78106 -212.024468)
		(end 122.78106 -212.00237)
		(width 0.0889)
		(layer "In4.Cu")
		(net "UPI_CPU1_CPU0_P1P0_DN<12>")
	)
	(segment
		(start 348.588076 -215.762586)
		(end 348.591378 -215.764618)
		(width 0.0889)
		(layer "In4.Cu")
		(net "UPI_CPU1_CPU0_P1P0_DN<12>")
	)
	(segment
		(start 349.04172 -211.008722)
		(end 348.43974 -211.610702)
		(width 0.14732)
		(layer "In4.Cu")
		(net "UPI_CPU1_CPU0_P1P0_DN<12>")
	)
	(segment
		(start 123.107958 -214.261954)
		(end 123.108212 -214.261446)
		(width 0.0889)
		(layer "In4.Cu")
		(net "UPI_CPU1_CPU0_P1P0_DN<12>")
	)
	(segment
		(start 338.736432 -189.60592)
		(end 341.457534 -193.470276)
		(width 0.14732)
		(layer "In4.Cu")
		(net "UPI_CPU1_CPU0_P1P0_DN<12>")
	)
	(segment
		(start 273.162014 -178.780694)
		(end 302.488092 -178.068986)
		(width 0.14732)
		(layer "In4.Cu")
		(net "UPI_CPU1_CPU0_P1P0_DN<12>")
	)
	(segment
		(start 348.579694 -216.74328)
		(end 348.576646 -216.745058)
		(width 0.0889)
		(layer "In4.Cu")
		(net "UPI_CPU1_CPU0_P1P0_DN<12>")
	)
	(segment
		(start 348.439994 -212.047328)
		(end 348.39783 -212.089492)
		(width 0.0889)
		(layer "In4.Cu")
		(net "UPI_CPU1_CPU0_P1P0_DN<12>")
	)
	(segment
		(start 122.63501 -215.761062)
		(end 122.6439 -215.755982)
		(width 0.0889)
		(layer "In4.Cu")
		(net "UPI_CPU1_CPU0_P1P0_DN<12>")
	)
	(segment
		(start 212.338412 -178.94554)
		(end 238.6203 -178.94554)
		(width 0.14732)
		(layer "In4.Cu")
		(net "UPI_CPU1_CPU0_P1P0_DN<12>")
	)
	(segment
		(start 335.832196 -186.701684)
		(end 338.736432 -189.60592)
		(width 0.14732)
		(layer "In4.Cu")
		(net "UPI_CPU1_CPU0_P1P0_DN<12>")
	)
	(segment
		(start 122.82297 -213.929468)
		(end 122.82297 -213.38286)
		(width 0.0889)
		(layer "In4.Cu")
		(net "UPI_CPU1_CPU0_P1P0_DN<12>")
	)
	(segment
		(start 346.962984 -199.112378)
		(end 349.04172 -204.130656)
		(width 0.14732)
		(layer "In4.Cu")
		(net "UPI_CPU1_CPU0_P1P0_DN<12>")
	)
	(segment
		(start 122.636026 -216.740486)
		(end 122.63501 -216.739978)
		(width 0.0889)
		(layer "In4.Cu")
		(net "UPI_CPU1_CPU0_P1P0_DN<12>")
	)
	(segment
		(start 313.062366 -178.265074)
		(end 316.297818 -179.168552)
		(width 0.14732)
		(layer "In4.Cu")
		(net "UPI_CPU1_CPU0_P1P0_DN<12>")
	)
	(segment
		(start 158.105856 -179.147724)
		(end 200.811384 -178.439064)
		(width 0.14732)
		(layer "In4.Cu")
		(net "UPI_CPU1_CPU0_P1P0_DN<12>")
	)
	(segment
		(start 348.439994 -212.02523)
		(end 348.439994 -212.047328)
		(width 0.0889)
		(layer "In4.Cu")
		(net "UPI_CPU1_CPU0_P1P0_DN<12>")
	)
	(segment
		(start 122.822462 -215.436704)
		(end 122.822462 -215.414606)
		(width 0.0889)
		(layer "In4.Cu")
		(net "UPI_CPU1_CPU0_P1P0_DN<12>")
	)
	(segment
		(start 122.82297 -213.00948)
		(end 122.82297 -212.83168)
		(width 0.0889)
		(layer "In4.Cu")
		(net "UPI_CPU1_CPU0_P1P0_DN<12>")
	)
	(segment
		(start 122.82297 -212.4583)
		(end 122.82297 -212.066378)
		(width 0.0889)
		(layer "In4.Cu")
		(net "UPI_CPU1_CPU0_P1P0_DN<12>")
	)
	(segment
		(start 122.352816 -216.266014)
		(end 122.352816 -216.235026)
		(width 0.0889)
		(layer "In4.Cu")
		(net "UPI_CPU1_CPU0_P1P0_DN<12>")
	)
	(segment
		(start 302.499776 -178.068986)
		(end 313.062366 -178.265074)
		(width 0.14732)
		(layer "In4.Cu")
		(net "UPI_CPU1_CPU0_P1P0_DN<12>")
	)
	(segment
		(start 335.831942 -186.701684)
		(end 335.832196 -186.701684)
		(width 0.14732)
		(layer "In4.Cu")
		(net "UPI_CPU1_CPU0_P1P0_DN<12>")
	)
	(segment
		(start 348.43974 -211.790788)
		(end 348.439994 -211.791042)
		(width 0.14732)
		(layer "In4.Cu")
		(net "UPI_CPU1_CPU0_P1P0_DN<12>")
	)
	(arc
		(start 348.576392 -215.117426)
		(mid 348.449138 -215.247392)
		(end 348.398084 -215.421972)
		(width 0.0889)
		(layer "In4.Cu")
		(net "UPI_CPU1_CPU0_P1P0_DN<12>")
	)
	(arc
		(start 348.591378 -215.764618)
		(mid 348.793965 -215.970969)
		(end 348.867984 -216.25052)
		(width 0.0889)
		(layer "In4.Cu")
		(net "UPI_CPU1_CPU0_P1P0_DN<12>")
	)
	(arc
		(start 122.822462 -215.414606)
		(mid 122.903373 -215.144478)
		(end 123.104656 -214.946992)
		(width 0.0889)
		(layer "In4.Cu")
		(net "UPI_CPU1_CPU0_P1P0_DN<12>")
	)
	(arc
		(start 122.822462 -217.064336)
		(mid 122.774783 -216.881436)
		(end 122.6439 -216.745058)
		(width 0.0889)
		(layer "In4.Cu")
		(net "UPI_CPU1_CPU0_P1P0_DN<12>")
	)
	(arc
		(start 123.292108 -214.461344)
		(mid 123.217103 -214.345885)
		(end 123.107958 -214.261954)
		(width 0.0889)
		(layer "In4.Cu")
		(net "UPI_CPU1_CPU0_P1P0_DN<12>")
	)
	(arc
		(start 348.576646 -216.745058)
		(mid 348.398049 -217.064336)
		(end 348.576646 -217.383614)
		(width 0.0889)
		(layer "In4.Cu")
		(net "UPI_CPU1_CPU0_P1P0_DN<12>")
	)
	(arc
		(start 123.291854 -214.637366)
		(mid 123.292051 -214.630001)
		(end 123.292108 -214.622634)
		(width 0.0889)
		(layer "In4.Cu")
		(net "UPI_CPU1_CPU0_P1P0_DN<12>")
	)
	(arc
		(start 348.657164 -218.318842)
		(mid 348.648718 -218.325527)
		(end 348.640146 -218.33205)
		(width 0.0889)
		(layer "In4.Cu")
		(net "UPI_CPU1_CPU0_P1P0_DN<12>")
	)
	(arc
		(start 123.113546 -214.941912)
		(mid 123.2408 -214.811946)
		(end 123.291854 -214.637366)
		(width 0.0889)
		(layer "In4.Cu")
		(net "UPI_CPU1_CPU0_P1P0_DN<12>")
	)
	(arc
		(start 122.6439 -215.755982)
		(mid 122.774814 -215.619622)
		(end 122.822462 -215.436704)
		(width 0.0889)
		(layer "In4.Cu")
		(net "UPI_CPU1_CPU0_P1P0_DN<12>")
	)
	(arc
		(start 348.585536 -217.388694)
		(mid 348.787822 -217.587675)
		(end 348.867984 -217.859864)
		(width 0.0889)
		(layer "In4.Cu")
		(net "UPI_CPU1_CPU0_P1P0_DN<12>")
	)
	(arc
		(start 348.39783 -215.436704)
		(mid 348.445509 -215.619604)
		(end 348.576392 -215.755982)
		(width 0.0889)
		(layer "In4.Cu")
		(net "UPI_CPU1_CPU0_P1P0_DN<12>")
	)
	(arc
		(start 122.352816 -216.235026)
		(mid 122.432186 -215.961292)
		(end 122.63501 -215.761062)
		(width 0.0889)
		(layer "In4.Cu")
		(net "UPI_CPU1_CPU0_P1P0_DN<12>")
	)
	(arc
		(start 348.398084 -215.421972)
		(mid 348.397887 -215.429337)
		(end 348.39783 -215.436704)
		(width 0.0889)
		(layer "In4.Cu")
		(net "UPI_CPU1_CPU0_P1P0_DN<12>")
	)
	(arc
		(start 122.63501 -216.739978)
		(mid 122.432187 -216.539747)
		(end 122.352816 -216.266014)
		(width 0.0889)
		(layer "In4.Cu")
		(net "UPI_CPU1_CPU0_P1P0_DN<12>")
	)
	(arc
		(start 122.682508 -217.356182)
		(mid 122.785653 -217.226157)
		(end 122.822462 -217.064336)
		(width 0.0889)
		(layer "In4.Cu")
		(net "UPI_CPU1_CPU0_P1P0_DN<12>")
	)
	(arc
		(start 348.582234 -214.093298)
		(mid 348.756197 -214.232062)
		(end 348.867476 -214.424768)
		(width 0.0889)
		(layer "In4.Cu")
		(net "UPI_CPU1_CPU0_P1P0_DN<12>")
	)
	(arc
		(start 348.867984 -216.260426)
		(mid 348.789873 -216.537375)
		(end 348.585536 -216.739978)
		(width 0.0889)
		(layer "In4.Cu")
		(net "UPI_CPU1_CPU0_P1P0_DN<12>")
	)
	(arc
		(start 348.398084 -213.893908)
		(mid 348.473089 -214.009367)
		(end 348.582234 -214.093298)
		(width 0.0889)
		(layer "In4.Cu")
		(net "UPI_CPU1_CPU0_P1P0_DN<12>")
	)
	(arc
		(start 123.108212 -214.261446)
		(mid 122.934136 -214.122483)
		(end 122.82297 -213.929468)
		(width 0.0889)
		(layer "In4.Cu")
		(net "UPI_CPU1_CPU0_P1P0_DN<12>")
	)
	(arc
		(start 348.867476 -214.644732)
		(mid 348.786565 -214.91486)
		(end 348.585282 -215.112346)
		(width 0.0889)
		(layer "In4.Cu")
		(net "UPI_CPU1_CPU0_P1P0_DN<12>")
	)
	(arc
		(start 348.867984 -217.878406)
		(mid 348.812629 -218.122593)
		(end 348.657164 -218.318842)
		(width 0.0889)
		(layer "In4.Cu")
		(net "UPI_CPU1_CPU0_P1P0_DN<12>")
	)
	(segment
		(start 123.857512 -218.414346)
		(end 123.857512 -217.87866)
		(width 0.13208)
		(layer "F.Cu")
		(net "UPI_CPU1_CPU0_P1P0_DN<11>")
	)
	(segment
		(start 347.36278 -217.87866)
		(end 347.363034 -217.878406)
		(width 0.13208)
		(layer "F.Cu")
		(net "UPI_CPU1_CPU0_P1P0_DN<11>")
	)
	(segment
		(start 123.857512 -217.87866)
		(end 123.857766 -217.878406)
		(width 0.13208)
		(layer "F.Cu")
		(net "UPI_CPU1_CPU0_P1P0_DN<11>")
	)
	(segment
		(start 347.36278 -218.414346)
		(end 347.36278 -217.87866)
		(width 0.13208)
		(layer "F.Cu")
		(net "UPI_CPU1_CPU0_P1P0_DN<11>")
	)
	(segment
		(start 124.422408 -214.644732)
		(end 124.422408 -214.60714)
		(width 0.0889)
		(layer "In4.Cu")
		(net "UPI_CPU1_CPU0_P1P0_DN<11>")
	)
	(segment
		(start 123.661678 -217.559128)
		(end 123.670568 -217.554048)
		(width 0.0889)
		(layer "In4.Cu")
		(net "UPI_CPU1_CPU0_P1P0_DN<11>")
	)
	(segment
		(start 124.194824 -211.160106)
		(end 124.350526 -211.08543)
		(width 0.14732)
		(layer "In4.Cu")
		(net "UPI_CPU1_CPU0_P1P0_DN<11>")
	)
	(segment
		(start 126.951232 -203.288138)
		(end 132.350764 -196.6468)
		(width 0.14732)
		(layer "In4.Cu")
		(net "UPI_CPU1_CPU0_P1P0_DN<11>")
	)
	(segment
		(start 238.623348 -180.062378)
		(end 273.17827 -179.897532)
		(width 0.14732)
		(layer "In4.Cu")
		(net "UPI_CPU1_CPU0_P1P0_DN<11>")
	)
	(segment
		(start 336.428334 -190.603632)
		(end 338.341208 -192.106296)
		(width 0.14732)
		(layer "In4.Cu")
		(net "UPI_CPU1_CPU0_P1P0_DN<11>")
	)
	(segment
		(start 347.737176 -214.461344)
		(end 347.737176 -214.622634)
		(width 0.0889)
		(layer "In4.Cu")
		(net "UPI_CPU1_CPU0_P1P0_DN<11>")
	)
	(segment
		(start 124.869956 -209.601562)
		(end 124.79528 -209.446368)
		(width 0.14732)
		(layer "In4.Cu")
		(net "UPI_CPU1_CPU0_P1P0_DN<11>")
	)
	(segment
		(start 347.26753 -217.064336)
		(end 347.26753 -217.07856)
		(width 0.0889)
		(layer "In4.Cu")
		(net "UPI_CPU1_CPU0_P1P0_DN<11>")
	)
	(segment
		(start 124.051822 -213.32698)
		(end 124.051822 -213.15172)
		(width 0.0889)
		(layer "In4.Cu")
		(net "UPI_CPU1_CPU0_P1P0_DN<11>")
	)
	(segment
		(start 124.569982 -210.088988)
		(end 124.725684 -210.014312)
		(width 0.14732)
		(layer "In4.Cu")
		(net "UPI_CPU1_CPU0_P1P0_DN<11>")
	)
	(segment
		(start 123.952762 -212.42782)
		(end 123.952762 -212.119972)
		(width 0.0889)
		(layer "In4.Cu")
		(net "UPI_CPU1_CPU0_P1P0_DN<11>")
	)
	(segment
		(start 138.990324 -192.23355)
		(end 139.030202 -192.20688)
		(width 0.14732)
		(layer "In4.Cu")
		(net "UPI_CPU1_CPU0_P1P0_DN<11>")
	)
	(segment
		(start 347.550232 -215.926162)
		(end 347.551756 -215.926924)
		(width 0.0889)
		(layer "In4.Cu")
		(net "UPI_CPU1_CPU0_P1P0_DN<11>")
	)
	(segment
		(start 347.495368 -217.518234)
		(end 347.519498 -217.607388)
		(width 0.0889)
		(layer "In4.Cu")
		(net "UPI_CPU1_CPU0_P1P0_DN<11>")
	)
	(segment
		(start 123.953016 -217.082878)
		(end 123.953016 -217.05443)
		(width 0.0889)
		(layer "In4.Cu")
		(net "UPI_CPU1_CPU0_P1P0_DN<11>")
	)
	(segment
		(start 347.92666 -204.363574)
		(end 347.92666 -210.482942)
		(width 0.14732)
		(layer "In4.Cu")
		(net "UPI_CPU1_CPU0_P1P0_DN<11>")
	)
	(segment
		(start 347.547438 -216.576402)
		(end 347.544136 -216.578434)
		(width 0.0889)
		(layer "In4.Cu")
		(net "UPI_CPU1_CPU0_P1P0_DN<11>")
	)
	(segment
		(start 123.952762 -213.778592)
		(end 123.952254 -213.778338)
		(width 0.0889)
		(layer "In4.Cu")
		(net "UPI_CPU1_CPU0_P1P0_DN<11>")
	)
	(segment
		(start 347.551756 -215.926924)
		(end 347.559122 -215.931242)
		(width 0.0889)
		(layer "In4.Cu")
		(net "UPI_CPU1_CPU0_P1P0_DN<11>")
	)
	(segment
		(start 335.725516 -189.579504)
		(end 336.428334 -190.603632)
		(width 0.14732)
		(layer "In4.Cu")
		(net "UPI_CPU1_CPU0_P1P0_DN<11>")
	)
	(segment
		(start 123.857766 -217.878406)
		(end 123.701302 -218.149424)
		(width 0.0889)
		(layer "In4.Cu")
		(net "UPI_CPU1_CPU0_P1P0_DN<11>")
	)
	(segment
		(start 347.544136 -215.922606)
		(end 347.54947 -215.925654)
		(width 0.0889)
		(layer "In4.Cu")
		(net "UPI_CPU1_CPU0_P1P0_DN<11>")
	)
	(segment
		(start 125.496066 -207.814418)
		(end 125.640338 -207.401668)
		(width 0.14732)
		(layer "In4.Cu")
		(net "UPI_CPU1_CPU0_P1P0_DN<11>")
	)
	(segment
		(start 347.225874 -211.183728)
		(end 347.225874 -211.790788)
		(width 0.14732)
		(layer "In4.Cu")
		(net "UPI_CPU1_CPU0_P1P0_DN<11>")
	)
	(segment
		(start 124.051822 -212.52688)
		(end 123.952762 -212.42782)
		(width 0.0889)
		(layer "In4.Cu")
		(net "UPI_CPU1_CPU0_P1P0_DN<11>")
	)
	(segment
		(start 123.661678 -215.931242)
		(end 123.670568 -215.926162)
		(width 0.0889)
		(layer "In4.Cu")
		(net "UPI_CPU1_CPU0_P1P0_DN<11>")
	)
	(segment
		(start 312.719466 -179.375816)
		(end 315.947298 -180.278024)
		(width 0.14732)
		(layer "In4.Cu")
		(net "UPI_CPU1_CPU0_P1P0_DN<11>")
	)
	(segment
		(start 212.02142 -180.062378)
		(end 238.623348 -180.062378)
		(width 0.14732)
		(layer "In4.Cu")
		(net "UPI_CPU1_CPU0_P1P0_DN<11>")
	)
	(segment
		(start 124.131324 -215.117426)
		(end 124.140214 -215.112346)
		(width 0.0889)
		(layer "In4.Cu")
		(net "UPI_CPU1_CPU0_P1P0_DN<11>")
	)
	(segment
		(start 347.226128 -212.02015)
		(end 347.226128 -212.042248)
		(width 0.0889)
		(layer "In4.Cu")
		(net "UPI_CPU1_CPU0_P1P0_DN<11>")
	)
	(segment
		(start 126.110492 -205.69047)
		(end 126.26594 -205.615794)
		(width 0.14732)
		(layer "In4.Cu")
		(net "UPI_CPU1_CPU0_P1P0_DN<11>")
	)
	(segment
		(start 347.226128 -212.042248)
		(end 347.268038 -212.084158)
		(width 0.0889)
		(layer "In4.Cu")
		(net "UPI_CPU1_CPU0_P1P0_DN<11>")
	)
	(segment
		(start 347.92666 -210.482942)
		(end 347.225874 -211.183728)
		(width 0.14732)
		(layer "In4.Cu")
		(net "UPI_CPU1_CPU0_P1P0_DN<11>")
	)
	(segment
		(start 123.952762 -213.05266)
		(end 123.952762 -212.8012)
		(width 0.0889)
		(layer "In4.Cu")
		(net "UPI_CPU1_CPU0_P1P0_DN<11>")
	)
	(segment
		(start 158.295848 -180.26761)
		(end 200.684638 -179.564538)
		(width 0.14732)
		(layer "In4.Cu")
		(net "UPI_CPU1_CPU0_P1P0_DN<11>")
	)
	(segment
		(start 123.952762 -215.452198)
		(end 123.952762 -215.436704)
		(width 0.0889)
		(layer "In4.Cu")
		(net "UPI_CPU1_CPU0_P1P0_DN<11>")
	)
	(segment
		(start 347.26753 -215.414606)
		(end 347.26753 -215.436704)
		(width 0.0889)
		(layer "In4.Cu")
		(net "UPI_CPU1_CPU0_P1P0_DN<11>")
	)
	(segment
		(start 124.051822 -212.70214)
		(end 124.051822 -212.52688)
		(width 0.0889)
		(layer "In4.Cu")
		(net "UPI_CPU1_CPU0_P1P0_DN<11>")
	)
	(segment
		(start 126.040896 -206.257906)
		(end 125.96622 -206.102712)
		(width 0.14732)
		(layer "In4.Cu")
		(net "UPI_CPU1_CPU0_P1P0_DN<11>")
	)
	(segment
		(start 273.17827 -179.897532)
		(end 302.496982 -179.186332)
		(width 0.14732)
		(layer "In4.Cu")
		(net "UPI_CPU1_CPU0_P1P0_DN<11>")
	)
	(segment
		(start 125.896624 -206.670656)
		(end 126.040896 -206.257906)
		(width 0.14732)
		(layer "In4.Cu")
		(net "UPI_CPU1_CPU0_P1P0_DN<11>")
	)
	(segment
		(start 125.191012 -208.316068)
		(end 125.340364 -207.889094)
		(width 0.14732)
		(layer "In4.Cu")
		(net "UPI_CPU1_CPU0_P1P0_DN<11>")
	)
	(segment
		(start 347.54947 -215.925654)
		(end 347.550232 -215.926162)
		(width 0.0889)
		(layer "In4.Cu")
		(net "UPI_CPU1_CPU0_P1P0_DN<11>")
	)
	(segment
		(start 123.952762 -212.8012)
		(end 124.051822 -212.70214)
		(width 0.0889)
		(layer "In4.Cu")
		(net "UPI_CPU1_CPU0_P1P0_DN<11>")
	)
	(segment
		(start 124.965968 -208.958688)
		(end 125.121416 -208.884012)
		(width 0.14732)
		(layer "In4.Cu")
		(net "UPI_CPU1_CPU0_P1P0_DN<11>")
	)
	(segment
		(start 347.225874 -211.790788)
		(end 347.226128 -211.791042)
		(width 0.14732)
		(layer "In4.Cu")
		(net "UPI_CPU1_CPU0_P1P0_DN<11>")
	)
	(segment
		(start 138.990324 -192.233296)
		(end 138.990324 -192.23355)
		(width 0.14732)
		(layer "In4.Cu")
		(net "UPI_CPU1_CPU0_P1P0_DN<11>")
	)
	(segment
		(start 200.684638 -179.564538)
		(end 212.02142 -180.062378)
		(width 0.14732)
		(layer "In4.Cu")
		(net "UPI_CPU1_CPU0_P1P0_DN<11>")
	)
	(segment
		(start 333.186786 -186.614816)
		(end 333.263748 -186.804808)
		(width 0.14732)
		(layer "In4.Cu")
		(net "UPI_CPU1_CPU0_P1P0_DN<11>")
	)
	(segment
		(start 155.198064 -181.060598)
		(end 155.198572 -181.060598)
		(width 0.14732)
		(layer "In4.Cu")
		(net "UPI_CPU1_CPU0_P1P0_DN<11>")
	)
	(segment
		(start 126.779528 -204.147928)
		(end 126.704852 -203.99248)
		(width 0.14732)
		(layer "In4.Cu")
		(net "UPI_CPU1_CPU0_P1P0_DN<11>")
	)
	(segment
		(start 125.265942 -208.471262)
		(end 125.191012 -208.316068)
		(width 0.14732)
		(layer "In4.Cu")
		(net "UPI_CPU1_CPU0_P1P0_DN<11>")
	)
	(segment
		(start 139.030202 -192.20688)
		(end 143.439642 -186.28741)
		(width 0.14732)
		(layer "In4.Cu")
		(net "UPI_CPU1_CPU0_P1P0_DN<11>")
	)
	(segment
		(start 123.701302 -218.149424)
		(end 123.62307 -218.170252)
		(width 0.0889)
		(layer "In4.Cu")
		(net "UPI_CPU1_CPU0_P1P0_DN<11>")
	)
	(segment
		(start 124.725684 -210.014312)
		(end 124.869956 -209.601562)
		(width 0.14732)
		(layer "In4.Cu")
		(net "UPI_CPU1_CPU0_P1P0_DN<11>")
	)
	(segment
		(start 124.051822 -213.15172)
		(end 123.952762 -213.05266)
		(width 0.0889)
		(layer "In4.Cu")
		(net "UPI_CPU1_CPU0_P1P0_DN<11>")
	)
	(segment
		(start 124.350526 -211.08543)
		(end 124.494798 -210.67268)
		(width 0.14732)
		(layer "In4.Cu")
		(net "UPI_CPU1_CPU0_P1P0_DN<11>")
	)
	(segment
		(start 333.603346 -186.948064)
		(end 333.793084 -186.870848)
		(width 0.14732)
		(layer "In4.Cu")
		(net "UPI_CPU1_CPU0_P1P0_DN<11>")
	)
	(segment
		(start 347.519498 -217.607388)
		(end 347.363034 -217.878406)
		(width 0.0889)
		(layer "In4.Cu")
		(net "UPI_CPU1_CPU0_P1P0_DN<11>")
	)
	(segment
		(start 126.704852 -203.99248)
		(end 126.951232 -203.288138)
		(width 0.14732)
		(layer "In4.Cu")
		(net "UPI_CPU1_CPU0_P1P0_DN<11>")
	)
	(segment
		(start 125.640338 -207.401668)
		(end 125.565662 -207.246474)
		(width 0.14732)
		(layer "In4.Cu")
		(net "UPI_CPU1_CPU0_P1P0_DN<11>")
	)
	(segment
		(start 347.559122 -216.569798)
		(end 347.551756 -216.574116)
		(width 0.0889)
		(layer "In4.Cu")
		(net "UPI_CPU1_CPU0_P1P0_DN<11>")
	)
	(segment
		(start 333.793084 -186.870848)
		(end 334.515714 -187.175648)
		(width 0.14732)
		(layer "In4.Cu")
		(net "UPI_CPU1_CPU0_P1P0_DN<11>")
	)
	(segment
		(start 123.952762 -213.42604)
		(end 124.051822 -213.32698)
		(width 0.0889)
		(layer "In4.Cu")
		(net "UPI_CPU1_CPU0_P1P0_DN<11>")
	)
	(segment
		(start 347.268038 -213.929468)
		(end 347.267784 -213.929722)
		(width 0.0889)
		(layer "In4.Cu")
		(net "UPI_CPU1_CPU0_P1P0_DN<11>")
	)
	(segment
		(start 123.994672 -211.73186)
		(end 124.194824 -211.160106)
		(width 0.14732)
		(layer "In4.Cu")
		(net "UPI_CPU1_CPU0_P1P0_DN<11>")
	)
	(segment
		(start 126.26594 -205.615794)
		(end 126.410212 -205.203044)
		(width 0.14732)
		(layer "In4.Cu")
		(net "UPI_CPU1_CPU0_P1P0_DN<11>")
	)
	(segment
		(start 315.947298 -180.278024)
		(end 328.15784 -184.493408)
		(width 0.14732)
		(layer "In4.Cu")
		(net "UPI_CPU1_CPU0_P1P0_DN<11>")
	)
	(segment
		(start 124.79528 -209.446368)
		(end 124.965968 -208.958688)
		(width 0.14732)
		(layer "In4.Cu")
		(net "UPI_CPU1_CPU0_P1P0_DN<11>")
	)
	(segment
		(start 328.15784 -184.493408)
		(end 333.186786 -186.614816)
		(width 0.14732)
		(layer "In4.Cu")
		(net "UPI_CPU1_CPU0_P1P0_DN<11>")
	)
	(segment
		(start 125.96622 -206.102712)
		(end 126.110492 -205.69047)
		(width 0.14732)
		(layer "In4.Cu")
		(net "UPI_CPU1_CPU0_P1P0_DN<11>")
	)
	(segment
		(start 124.420122 -210.517486)
		(end 124.569982 -210.088988)
		(width 0.14732)
		(layer "In4.Cu")
		(net "UPI_CPU1_CPU0_P1P0_DN<11>")
	)
	(segment
		(start 123.952762 -213.770718)
		(end 123.952762 -213.42604)
		(width 0.0889)
		(layer "In4.Cu")
		(net "UPI_CPU1_CPU0_P1P0_DN<11>")
	)
	(segment
		(start 123.994926 -212.077808)
		(end 123.994926 -212.05571)
		(width 0.0889)
		(layer "In4.Cu")
		(net "UPI_CPU1_CPU0_P1P0_DN<11>")
	)
	(segment
		(start 347.558614 -214.941912)
		(end 347.549724 -214.946992)
		(width 0.0889)
		(layer "In4.Cu")
		(net "UPI_CPU1_CPU0_P1P0_DN<11>")
	)
	(segment
		(start 132.350764 -196.6468)
		(end 138.990324 -192.233296)
		(width 0.14732)
		(layer "In4.Cu")
		(net "UPI_CPU1_CPU0_P1P0_DN<11>")
	)
	(segment
		(start 126.479808 -204.635354)
		(end 126.635256 -204.560678)
		(width 0.14732)
		(layer "In4.Cu")
		(net "UPI_CPU1_CPU0_P1P0_DN<11>")
	)
	(segment
		(start 123.670568 -216.574878)
		(end 123.661678 -216.569798)
		(width 0.0889)
		(layer "In4.Cu")
		(net "UPI_CPU1_CPU0_P1P0_DN<11>")
	)
	(segment
		(start 125.565662 -207.246474)
		(end 125.740922 -206.745332)
		(width 0.14732)
		(layer "In4.Cu")
		(net "UPI_CPU1_CPU0_P1P0_DN<11>")
	)
	(segment
		(start 124.494798 -210.67268)
		(end 124.420122 -210.517486)
		(width 0.14732)
		(layer "In4.Cu")
		(net "UPI_CPU1_CPU0_P1P0_DN<11>")
	)
	(segment
		(start 347.551756 -216.574116)
		(end 347.550232 -216.574878)
		(width 0.0889)
		(layer "In4.Cu")
		(net "UPI_CPU1_CPU0_P1P0_DN<11>")
	)
	(segment
		(start 123.952762 -212.119972)
		(end 123.994926 -212.077808)
		(width 0.0889)
		(layer "In4.Cu")
		(net "UPI_CPU1_CPU0_P1P0_DN<11>")
	)
	(segment
		(start 302.496982 -179.186332)
		(end 312.719466 -179.375816)
		(width 0.14732)
		(layer "In4.Cu")
		(net "UPI_CPU1_CPU0_P1P0_DN<11>")
	)
	(segment
		(start 125.740922 -206.745332)
		(end 125.896624 -206.670656)
		(width 0.14732)
		(layer "In4.Cu")
		(net "UPI_CPU1_CPU0_P1P0_DN<11>")
	)
	(segment
		(start 126.410212 -205.203044)
		(end 126.335536 -205.047596)
		(width 0.14732)
		(layer "In4.Cu")
		(net "UPI_CPU1_CPU0_P1P0_DN<11>")
	)
	(segment
		(start 126.635256 -204.560678)
		(end 126.779528 -204.147928)
		(width 0.14732)
		(layer "In4.Cu")
		(net "UPI_CPU1_CPU0_P1P0_DN<11>")
	)
	(segment
		(start 125.121416 -208.884012)
		(end 125.265942 -208.471262)
		(width 0.14732)
		(layer "In4.Cu")
		(net "UPI_CPU1_CPU0_P1P0_DN<11>")
	)
	(segment
		(start 123.994926 -211.892642)
		(end 123.994672 -211.892388)
		(width 0.14732)
		(layer "In4.Cu")
		(net "UPI_CPU1_CPU0_P1P0_DN<11>")
	)
	(segment
		(start 123.994926 -212.05571)
		(end 123.994926 -211.892642)
		(width 0.14732)
		(layer "In4.Cu")
		(net "UPI_CPU1_CPU0_P1P0_DN<11>")
	)
	(segment
		(start 347.226128 -211.791042)
		(end 347.226128 -212.02015)
		(width 0.14732)
		(layer "In4.Cu")
		(net "UPI_CPU1_CPU0_P1P0_DN<11>")
	)
	(segment
		(start 125.340364 -207.889094)
		(end 125.496066 -207.814418)
		(width 0.14732)
		(layer "In4.Cu")
		(net "UPI_CPU1_CPU0_P1P0_DN<11>")
	)
	(segment
		(start 346.037408 -199.802496)
		(end 347.92666 -204.363574)
		(width 0.14732)
		(layer "In4.Cu")
		(net "UPI_CPU1_CPU0_P1P0_DN<11>")
	)
	(segment
		(start 347.550232 -216.574878)
		(end 347.547438 -216.576402)
		(width 0.0889)
		(layer "In4.Cu")
		(net "UPI_CPU1_CPU0_P1P0_DN<11>")
	)
	(segment
		(start 124.140214 -214.133176)
		(end 124.112528 -214.117174)
		(width 0.0889)
		(layer "In4.Cu")
		(net "UPI_CPU1_CPU0_P1P0_DN<11>")
	)
	(segment
		(start 334.515714 -187.175648)
		(end 334.917796 -187.659518)
		(width 0.14732)
		(layer "In4.Cu")
		(net "UPI_CPU1_CPU0_P1P0_DN<11>")
	)
	(segment
		(start 152.10155 -181.853332)
		(end 155.198064 -181.060598)
		(width 0.14732)
		(layer "In4.Cu")
		(net "UPI_CPU1_CPU0_P1P0_DN<11>")
	)
	(segment
		(start 347.267784 -213.929722)
		(end 347.267784 -213.930484)
		(width 0.0889)
		(layer "In4.Cu")
		(net "UPI_CPU1_CPU0_P1P0_DN<11>")
	)
	(segment
		(start 126.335536 -205.047596)
		(end 126.479808 -204.635354)
		(width 0.14732)
		(layer "In4.Cu")
		(net "UPI_CPU1_CPU0_P1P0_DN<11>")
	)
	(segment
		(start 335.12633 -188.338714)
		(end 335.725516 -189.579504)
		(width 0.14732)
		(layer "In4.Cu")
		(net "UPI_CPU1_CPU0_P1P0_DN<11>")
	)
	(segment
		(start 347.268038 -212.084158)
		(end 347.268038 -213.929468)
		(width 0.0889)
		(layer "In4.Cu")
		(net "UPI_CPU1_CPU0_P1P0_DN<11>")
	)
	(segment
		(start 143.439642 -186.28741)
		(end 152.10155 -181.853332)
		(width 0.14732)
		(layer "In4.Cu")
		(net "UPI_CPU1_CPU0_P1P0_DN<11>")
	)
	(segment
		(start 123.952254 -213.778338)
		(end 123.952762 -213.770718)
		(width 0.0889)
		(layer "In4.Cu")
		(net "UPI_CPU1_CPU0_P1P0_DN<11>")
	)
	(segment
		(start 334.917796 -187.659518)
		(end 335.12633 -188.338714)
		(width 0.14732)
		(layer "In4.Cu")
		(net "UPI_CPU1_CPU0_P1P0_DN<11>")
	)
	(segment
		(start 338.341208 -192.106296)
		(end 346.037408 -199.802496)
		(width 0.14732)
		(layer "In4.Cu")
		(net "UPI_CPU1_CPU0_P1P0_DN<11>")
	)
	(segment
		(start 123.994672 -211.892388)
		(end 123.994672 -211.73186)
		(width 0.14732)
		(layer "In4.Cu")
		(net "UPI_CPU1_CPU0_P1P0_DN<11>")
	)
	(segment
		(start 333.263748 -186.804808)
		(end 333.603346 -186.948064)
		(width 0.14732)
		(layer "In4.Cu")
		(net "UPI_CPU1_CPU0_P1P0_DN<11>")
	)
	(segment
		(start 155.198572 -181.060598)
		(end 158.295848 -180.26761)
		(width 0.14732)
		(layer "In4.Cu")
		(net "UPI_CPU1_CPU0_P1P0_DN<11>")
	)
	(arc
		(start 124.422408 -214.60714)
		(mid 124.343038 -214.333406)
		(end 124.140214 -214.133176)
		(width 0.0889)
		(layer "In4.Cu")
		(net "UPI_CPU1_CPU0_P1P0_DN<11>")
	)
	(arc
		(start 123.670568 -217.554048)
		(mid 123.872854 -217.355067)
		(end 123.953016 -217.082878)
		(width 0.0889)
		(layer "In4.Cu")
		(net "UPI_CPU1_CPU0_P1P0_DN<11>")
	)
	(arc
		(start 347.544136 -216.578434)
		(mid 347.341549 -216.784785)
		(end 347.26753 -217.064336)
		(width 0.0889)
		(layer "In4.Cu")
		(net "UPI_CPU1_CPU0_P1P0_DN<11>")
	)
	(arc
		(start 124.112528 -214.117174)
		(mid 123.987501 -213.969189)
		(end 123.952762 -213.778592)
		(width 0.0889)
		(layer "In4.Cu")
		(net "UPI_CPU1_CPU0_P1P0_DN<11>")
	)
	(arc
		(start 347.559122 -215.931242)
		(mid 347.737719 -216.25052)
		(end 347.559122 -216.569798)
		(width 0.0889)
		(layer "In4.Cu")
		(net "UPI_CPU1_CPU0_P1P0_DN<11>")
	)
	(arc
		(start 347.737176 -214.622634)
		(mid 347.689497 -214.805534)
		(end 347.558614 -214.941912)
		(width 0.0889)
		(layer "In4.Cu")
		(net "UPI_CPU1_CPU0_P1P0_DN<11>")
	)
	(arc
		(start 347.283024 -213.969346)
		(mid 347.393018 -214.138715)
		(end 347.553026 -214.261954)
		(width 0.0889)
		(layer "In4.Cu")
		(net "UPI_CPU1_CPU0_P1P0_DN<11>")
	)
	(arc
		(start 347.26753 -217.07856)
		(mid 347.325824 -217.315203)
		(end 347.47835 -217.50528)
		(width 0.0889)
		(layer "In4.Cu")
		(net "UPI_CPU1_CPU0_P1P0_DN<11>")
	)
	(arc
		(start 123.483116 -217.878406)
		(mid 123.530795 -217.695506)
		(end 123.661678 -217.559128)
		(width 0.0889)
		(layer "In4.Cu")
		(net "UPI_CPU1_CPU0_P1P0_DN<11>")
	)
	(arc
		(start 347.267784 -213.930484)
		(mid 347.275069 -213.950046)
		(end 347.283024 -213.969346)
		(width 0.0889)
		(layer "In4.Cu")
		(net "UPI_CPU1_CPU0_P1P0_DN<11>")
	)
	(arc
		(start 123.952762 -215.436704)
		(mid 123.952814 -215.429337)
		(end 123.953016 -215.421972)
		(width 0.0889)
		(layer "In4.Cu")
		(net "UPI_CPU1_CPU0_P1P0_DN<11>")
	)
	(arc
		(start 123.661678 -216.569798)
		(mid 123.532389 -216.436312)
		(end 123.483116 -216.257124)
		(width 0.0889)
		(layer "In4.Cu")
		(net "UPI_CPU1_CPU0_P1P0_DN<11>")
	)
	(arc
		(start 347.553026 -214.261954)
		(mid 347.662173 -214.345882)
		(end 347.737176 -214.461344)
		(width 0.0889)
		(layer "In4.Cu")
		(net "UPI_CPU1_CPU0_P1P0_DN<11>")
	)
	(arc
		(start 123.483116 -216.24036)
		(mid 123.533185 -216.063135)
		(end 123.661678 -215.931242)
		(width 0.0889)
		(layer "In4.Cu")
		(net "UPI_CPU1_CPU0_P1P0_DN<11>")
	)
	(arc
		(start 123.953016 -215.421972)
		(mid 124.00407 -215.247392)
		(end 124.131324 -215.117426)
		(width 0.0889)
		(layer "In4.Cu")
		(net "UPI_CPU1_CPU0_P1P0_DN<11>")
	)
	(arc
		(start 347.26753 -215.436704)
		(mid 347.341521 -215.71627)
		(end 347.544136 -215.922606)
		(width 0.0889)
		(layer "In4.Cu")
		(net "UPI_CPU1_CPU0_P1P0_DN<11>")
	)
	(arc
		(start 123.670568 -215.926162)
		(mid 123.873391 -215.725931)
		(end 123.952762 -215.452198)
		(width 0.0889)
		(layer "In4.Cu")
		(net "UPI_CPU1_CPU0_P1P0_DN<11>")
	)
	(arc
		(start 123.483116 -216.257124)
		(mid 123.483022 -216.248742)
		(end 123.483116 -216.24036)
		(width 0.0889)
		(layer "In4.Cu")
		(net "UPI_CPU1_CPU0_P1P0_DN<11>")
	)
	(arc
		(start 347.47835 -217.50528)
		(mid 347.486798 -217.511837)
		(end 347.495368 -217.518234)
		(width 0.0889)
		(layer "In4.Cu")
		(net "UPI_CPU1_CPU0_P1P0_DN<11>")
	)
	(arc
		(start 123.953016 -217.05443)
		(mid 123.874905 -216.777481)
		(end 123.670568 -216.574878)
		(width 0.0889)
		(layer "In4.Cu")
		(net "UPI_CPU1_CPU0_P1P0_DN<11>")
	)
	(arc
		(start 347.549724 -214.946992)
		(mid 347.348442 -215.144479)
		(end 347.26753 -215.414606)
		(width 0.0889)
		(layer "In4.Cu")
		(net "UPI_CPU1_CPU0_P1P0_DN<11>")
	)
	(arc
		(start 123.62307 -218.170252)
		(mid 123.519925 -218.040227)
		(end 123.483116 -217.878406)
		(width 0.0889)
		(layer "In4.Cu")
		(net "UPI_CPU1_CPU0_P1P0_DN<11>")
	)
	(arc
		(start 124.140214 -215.112346)
		(mid 124.341496 -214.914859)
		(end 124.422408 -214.644732)
		(width 0.0889)
		(layer "In4.Cu")
		(net "UPI_CPU1_CPU0_P1P0_DN<11>")
	)
	(segment
		(start 124.327666 -217.06459)
		(end 124.327412 -217.064336)
		(width 0.13208)
		(layer "F.Cu")
		(net "UPI_CPU1_CPU0_P1P0_DN<10>")
	)
	(segment
		(start 346.893134 -218.692476)
		(end 346.89288 -218.692222)
		(width 0.13208)
		(layer "F.Cu")
		(net "UPI_CPU1_CPU0_P1P0_DN<10>")
	)
	(segment
		(start 124.327666 -217.600276)
		(end 124.327666 -217.06459)
		(width 0.13208)
		(layer "F.Cu")
		(net "UPI_CPU1_CPU0_P1P0_DN<10>")
	)
	(segment
		(start 346.893134 -219.228162)
		(end 346.893134 -218.692476)
		(width 0.13208)
		(layer "F.Cu")
		(net "UPI_CPU1_CPU0_P1P0_DN<10>")
	)
	(segment
		(start 124.603002 -212.6107)
		(end 124.603002 -212.43544)
		(width 0.0889)
		(layer "In4.Cu")
		(net "UPI_CPU1_CPU0_P1P0_DN<10>")
	)
	(segment
		(start 125.171454 -214.637366)
		(end 125.171962 -214.624412)
		(width 0.0889)
		(layer "In4.Cu")
		(net "UPI_CPU1_CPU0_P1P0_DN<10>")
	)
	(segment
		(start 329.755754 -186.296046)
		(end 332.062074 -187.887864)
		(width 0.14732)
		(layer "In4.Cu")
		(net "UPI_CPU1_CPU0_P1P0_DN<10>")
	)
	(segment
		(start 211.919312 -180.630576)
		(end 238.624872 -180.630576)
		(width 0.14732)
		(layer "In4.Cu")
		(net "UPI_CPU1_CPU0_P1P0_DN<10>")
	)
	(segment
		(start 158.691834 -180.837332)
		(end 200.738486 -180.13934)
		(width 0.14732)
		(layer "In4.Cu")
		(net "UPI_CPU1_CPU0_P1P0_DN<10>")
	)
	(segment
		(start 124.483876 -217.335354)
		(end 124.562108 -217.356182)
		(width 0.0889)
		(layer "In4.Cu")
		(net "UPI_CPU1_CPU0_P1P0_DN<10>")
	)
	(segment
		(start 347.345 -204.47254)
		(end 347.345 -210.26628)
		(width 0.14732)
		(layer "In4.Cu")
		(net "UPI_CPU1_CPU0_P1P0_DN<10>")
	)
	(segment
		(start 332.062074 -187.887864)
		(end 337.990688 -192.550796)
		(width 0.14732)
		(layer "In4.Cu")
		(net "UPI_CPU1_CPU0_P1P0_DN<10>")
	)
	(segment
		(start 346.705682 -215.112346)
		(end 346.704666 -215.112854)
		(width 0.0889)
		(layer "In4.Cu")
		(net "UPI_CPU1_CPU0_P1P0_DN<10>")
	)
	(segment
		(start 346.51823 -213.8934)
		(end 346.518484 -213.893908)
		(width 0.0889)
		(layer "In4.Cu")
		(net "UPI_CPU1_CPU0_P1P0_DN<10>")
	)
	(segment
		(start 200.738486 -180.13934)
		(end 211.919312 -180.630576)
		(width 0.14732)
		(layer "In4.Cu")
		(net "UPI_CPU1_CPU0_P1P0_DN<10>")
	)
	(segment
		(start 124.660152 -211.792058)
		(end 124.941838 -211.111592)
		(width 0.14732)
		(layer "In4.Cu")
		(net "UPI_CPU1_CPU0_P1P0_DN<10>")
	)
	(segment
		(start 345.529916 -200.090278)
		(end 347.345 -204.47254)
		(width 0.14732)
		(layer "In4.Cu")
		(net "UPI_CPU1_CPU0_P1P0_DN<10>")
	)
	(segment
		(start 124.5235 -216.745058)
		(end 124.515626 -216.740486)
		(width 0.0889)
		(layer "In4.Cu")
		(net "UPI_CPU1_CPU0_P1P0_DN<10>")
	)
	(segment
		(start 346.705936 -216.739978)
		(end 346.705174 -216.740486)
		(width 0.0889)
		(layer "In4.Cu")
		(net "UPI_CPU1_CPU0_P1P0_DN<10>")
	)
	(segment
		(start 127.625348 -203.448158)
		(end 132.900674 -196.960236)
		(width 0.14732)
		(layer "In4.Cu")
		(net "UPI_CPU1_CPU0_P1P0_DN<10>")
	)
	(segment
		(start 346.560394 -212.042248)
		(end 346.51823 -212.084412)
		(width 0.0889)
		(layer "In4.Cu")
		(net "UPI_CPU1_CPU0_P1P0_DN<10>")
	)
	(segment
		(start 327.885552 -185.00471)
		(end 329.755754 -186.296046)
		(width 0.14732)
		(layer "In4.Cu")
		(net "UPI_CPU1_CPU0_P1P0_DN<10>")
	)
	(segment
		(start 346.705174 -216.740486)
		(end 346.700094 -216.74328)
		(width 0.0889)
		(layer "In4.Cu")
		(net "UPI_CPU1_CPU0_P1P0_DN<10>")
	)
	(segment
		(start 346.560394 -212.02015)
		(end 346.560394 -212.042248)
		(width 0.0889)
		(layer "In4.Cu")
		(net "UPI_CPU1_CPU0_P1P0_DN<10>")
	)
	(segment
		(start 346.736416 -218.421204)
		(end 346.89288 -218.692222)
		(width 0.0889)
		(layer "In4.Cu")
		(net "UPI_CPU1_CPU0_P1P0_DN<10>")
	)
	(segment
		(start 124.702062 -212.88502)
		(end 124.702062 -212.70976)
		(width 0.0889)
		(layer "In4.Cu")
		(net "UPI_CPU1_CPU0_P1P0_DN<10>")
	)
	(segment
		(start 346.51823 -212.084412)
		(end 346.51823 -213.8934)
		(width 0.0889)
		(layer "In4.Cu")
		(net "UPI_CPU1_CPU0_P1P0_DN<10>")
	)
	(segment
		(start 124.660152 -211.89569)
		(end 124.660152 -211.792058)
		(width 0.14732)
		(layer "In4.Cu")
		(net "UPI_CPU1_CPU0_P1P0_DN<10>")
	)
	(segment
		(start 124.702062 -213.2584)
		(end 124.603002 -213.15934)
		(width 0.0889)
		(layer "In4.Cu")
		(net "UPI_CPU1_CPU0_P1P0_DN<10>")
	)
	(segment
		(start 346.697046 -217.383614)
		(end 346.705936 -217.388694)
		(width 0.0889)
		(layer "In4.Cu")
		(net "UPI_CPU1_CPU0_P1P0_DN<10>")
	)
	(segment
		(start 273.186398 -180.46573)
		(end 301.878746 -179.76977)
		(width 0.14732)
		(layer "In4.Cu")
		(net "UPI_CPU1_CPU0_P1P0_DN<10>")
	)
	(segment
		(start 312.571384 -179.966366)
		(end 315.716666 -180.859938)
		(width 0.14732)
		(layer "In4.Cu")
		(net "UPI_CPU1_CPU0_P1P0_DN<10>")
	)
	(segment
		(start 346.56014 -211.05114)
		(end 346.56014 -211.640928)
		(width 0.14732)
		(layer "In4.Cu")
		(net "UPI_CPU1_CPU0_P1P0_DN<10>")
	)
	(segment
		(start 124.603002 -212.43544)
		(end 124.702062 -212.33638)
		(width 0.0889)
		(layer "In4.Cu")
		(net "UPI_CPU1_CPU0_P1P0_DN<10>")
	)
	(segment
		(start 124.660152 -211.917788)
		(end 124.660152 -211.89569)
		(width 0.0889)
		(layer "In4.Cu")
		(net "UPI_CPU1_CPU0_P1P0_DN<10>")
	)
	(segment
		(start 301.878746 -179.76977)
		(end 312.571384 -179.966366)
		(width 0.14732)
		(layer "In4.Cu")
		(net "UPI_CPU1_CPU0_P1P0_DN<10>")
	)
	(segment
		(start 124.702062 -212.33638)
		(end 124.702062 -211.959698)
		(width 0.0889)
		(layer "In4.Cu")
		(net "UPI_CPU1_CPU0_P1P0_DN<10>")
	)
	(segment
		(start 143.814038 -186.740038)
		(end 151.99614 -182.551324)
		(width 0.14732)
		(layer "In4.Cu")
		(net "UPI_CPU1_CPU0_P1P0_DN<10>")
	)
	(segment
		(start 124.327412 -217.064336)
		(end 124.483876 -217.335354)
		(width 0.0889)
		(layer "In4.Cu")
		(net "UPI_CPU1_CPU0_P1P0_DN<10>")
	)
	(segment
		(start 124.702062 -211.959698)
		(end 124.660152 -211.917788)
		(width 0.0889)
		(layer "In4.Cu")
		(net "UPI_CPU1_CPU0_P1P0_DN<10>")
	)
	(segment
		(start 124.515626 -216.740486)
		(end 124.51461 -216.739978)
		(width 0.0889)
		(layer "In4.Cu")
		(net "UPI_CPU1_CPU0_P1P0_DN<10>")
	)
	(segment
		(start 346.705682 -215.761062)
		(end 346.708476 -215.762586)
		(width 0.0889)
		(layer "In4.Cu")
		(net "UPI_CPU1_CPU0_P1P0_DN<10>")
	)
	(segment
		(start 124.702062 -213.802468)
		(end 124.702062 -213.2584)
		(width 0.0889)
		(layer "In4.Cu")
		(net "UPI_CPU1_CPU0_P1P0_DN<10>")
	)
	(segment
		(start 347.345 -210.26628)
		(end 346.56014 -211.05114)
		(width 0.14732)
		(layer "In4.Cu")
		(net "UPI_CPU1_CPU0_P1P0_DN<10>")
	)
	(segment
		(start 346.696792 -215.755982)
		(end 346.704158 -215.7603)
		(width 0.0889)
		(layer "In4.Cu")
		(net "UPI_CPU1_CPU0_P1P0_DN<10>")
	)
	(segment
		(start 346.560394 -211.641182)
		(end 346.560394 -212.02015)
		(width 0.14732)
		(layer "In4.Cu")
		(net "UPI_CPU1_CPU0_P1P0_DN<10>")
	)
	(segment
		(start 346.700094 -216.74328)
		(end 346.697046 -216.745058)
		(width 0.0889)
		(layer "In4.Cu")
		(net "UPI_CPU1_CPU0_P1P0_DN<10>")
	)
	(segment
		(start 124.51461 -215.761062)
		(end 124.5235 -215.755982)
		(width 0.0889)
		(layer "In4.Cu")
		(net "UPI_CPU1_CPU0_P1P0_DN<10>")
	)
	(segment
		(start 124.603002 -213.15934)
		(end 124.603002 -212.98408)
		(width 0.0889)
		(layer "In4.Cu")
		(net "UPI_CPU1_CPU0_P1P0_DN<10>")
	)
	(segment
		(start 346.988384 -217.859864)
		(end 346.988384 -217.878406)
		(width 0.0889)
		(layer "In4.Cu")
		(net "UPI_CPU1_CPU0_P1P0_DN<10>")
	)
	(segment
		(start 337.990688 -192.550796)
		(end 345.529916 -200.090278)
		(width 0.14732)
		(layer "In4.Cu")
		(net "UPI_CPU1_CPU0_P1P0_DN<10>")
	)
	(segment
		(start 346.704158 -215.7603)
		(end 346.705682 -215.761062)
		(width 0.0889)
		(layer "In4.Cu")
		(net "UPI_CPU1_CPU0_P1P0_DN<10>")
	)
	(segment
		(start 346.988384 -216.25052)
		(end 346.988384 -216.260426)
		(width 0.0889)
		(layer "In4.Cu")
		(net "UPI_CPU1_CPU0_P1P0_DN<10>")
	)
	(segment
		(start 346.760546 -218.33205)
		(end 346.736416 -218.421204)
		(width 0.0889)
		(layer "In4.Cu")
		(net "UPI_CPU1_CPU0_P1P0_DN<10>")
	)
	(segment
		(start 139.437872 -192.614042)
		(end 143.814038 -186.740038)
		(width 0.14732)
		(layer "In4.Cu")
		(net "UPI_CPU1_CPU0_P1P0_DN<10>")
	)
	(segment
		(start 346.56014 -211.640928)
		(end 346.560394 -211.641182)
		(width 0.14732)
		(layer "In4.Cu")
		(net "UPI_CPU1_CPU0_P1P0_DN<10>")
	)
	(segment
		(start 315.716666 -180.859938)
		(end 327.885552 -185.00471)
		(width 0.14732)
		(layer "In4.Cu")
		(net "UPI_CPU1_CPU0_P1P0_DN<10>")
	)
	(segment
		(start 132.900674 -196.960236)
		(end 139.437872 -192.614042)
		(width 0.14732)
		(layer "In4.Cu")
		(net "UPI_CPU1_CPU0_P1P0_DN<10>")
	)
	(segment
		(start 151.99614 -182.551324)
		(end 158.691834 -180.837332)
		(width 0.14732)
		(layer "In4.Cu")
		(net "UPI_CPU1_CPU0_P1P0_DN<10>")
	)
	(segment
		(start 346.987876 -214.424768)
		(end 346.987876 -214.644732)
		(width 0.0889)
		(layer "In4.Cu")
		(net "UPI_CPU1_CPU0_P1P0_DN<10>")
	)
	(segment
		(start 124.702062 -215.436704)
		(end 124.702062 -215.414606)
		(width 0.0889)
		(layer "In4.Cu")
		(net "UPI_CPU1_CPU0_P1P0_DN<10>")
	)
	(segment
		(start 346.704666 -215.112854)
		(end 346.696792 -215.117426)
		(width 0.0889)
		(layer "In4.Cu")
		(net "UPI_CPU1_CPU0_P1P0_DN<10>")
	)
	(segment
		(start 346.708476 -215.762586)
		(end 346.711778 -215.764618)
		(width 0.0889)
		(layer "In4.Cu")
		(net "UPI_CPU1_CPU0_P1P0_DN<10>")
	)
	(segment
		(start 124.941838 -211.111592)
		(end 127.625348 -203.448158)
		(width 0.14732)
		(layer "In4.Cu")
		(net "UPI_CPU1_CPU0_P1P0_DN<10>")
	)
	(segment
		(start 124.984256 -214.946992)
		(end 124.993146 -214.941912)
		(width 0.0889)
		(layer "In4.Cu")
		(net "UPI_CPU1_CPU0_P1P0_DN<10>")
	)
	(segment
		(start 124.702062 -212.70976)
		(end 124.603002 -212.6107)
		(width 0.0889)
		(layer "In4.Cu")
		(net "UPI_CPU1_CPU0_P1P0_DN<10>")
	)
	(segment
		(start 238.624872 -180.630576)
		(end 273.186398 -180.46573)
		(width 0.14732)
		(layer "In4.Cu")
		(net "UPI_CPU1_CPU0_P1P0_DN<10>")
	)
	(segment
		(start 124.232416 -216.266014)
		(end 124.232416 -216.235026)
		(width 0.0889)
		(layer "In4.Cu")
		(net "UPI_CPU1_CPU0_P1P0_DN<10>")
	)
	(segment
		(start 124.603002 -212.98408)
		(end 124.702062 -212.88502)
		(width 0.0889)
		(layer "In4.Cu")
		(net "UPI_CPU1_CPU0_P1P0_DN<10>")
	)
	(segment
		(start 125.171962 -214.624412)
		(end 125.171962 -214.460328)
		(width 0.0889)
		(layer "In4.Cu")
		(net "UPI_CPU1_CPU0_P1P0_DN<10>")
	)
	(arc
		(start 346.988384 -217.878406)
		(mid 346.933029 -218.122593)
		(end 346.777564 -218.318842)
		(width 0.0889)
		(layer "In4.Cu")
		(net "UPI_CPU1_CPU0_P1P0_DN<10>")
	)
	(arc
		(start 346.702634 -214.093298)
		(mid 346.876597 -214.232062)
		(end 346.987876 -214.424768)
		(width 0.0889)
		(layer "In4.Cu")
		(net "UPI_CPU1_CPU0_P1P0_DN<10>")
	)
	(arc
		(start 124.562108 -217.356182)
		(mid 124.665253 -217.226157)
		(end 124.702062 -217.064336)
		(width 0.0889)
		(layer "In4.Cu")
		(net "UPI_CPU1_CPU0_P1P0_DN<10>")
	)
	(arc
		(start 346.518484 -213.893908)
		(mid 346.593489 -214.009367)
		(end 346.702634 -214.093298)
		(width 0.0889)
		(layer "In4.Cu")
		(net "UPI_CPU1_CPU0_P1P0_DN<10>")
	)
	(arc
		(start 124.737876 -213.957408)
		(mid 124.710981 -213.882015)
		(end 124.702062 -213.802468)
		(width 0.0889)
		(layer "In4.Cu")
		(net "UPI_CPU1_CPU0_P1P0_DN<10>")
	)
	(arc
		(start 124.51461 -216.739978)
		(mid 124.311787 -216.539747)
		(end 124.232416 -216.266014)
		(width 0.0889)
		(layer "In4.Cu")
		(net "UPI_CPU1_CPU0_P1P0_DN<10>")
	)
	(arc
		(start 346.518484 -215.421972)
		(mid 346.518287 -215.429337)
		(end 346.51823 -215.436704)
		(width 0.0889)
		(layer "In4.Cu")
		(net "UPI_CPU1_CPU0_P1P0_DN<10>")
	)
	(arc
		(start 346.705936 -217.388694)
		(mid 346.908222 -217.587675)
		(end 346.988384 -217.859864)
		(width 0.0889)
		(layer "In4.Cu")
		(net "UPI_CPU1_CPU0_P1P0_DN<10>")
	)
	(arc
		(start 346.51823 -215.436704)
		(mid 346.565909 -215.619604)
		(end 346.696792 -215.755982)
		(width 0.0889)
		(layer "In4.Cu")
		(net "UPI_CPU1_CPU0_P1P0_DN<10>")
	)
	(arc
		(start 346.697046 -216.745058)
		(mid 346.518449 -217.064336)
		(end 346.697046 -217.383614)
		(width 0.0889)
		(layer "In4.Cu")
		(net "UPI_CPU1_CPU0_P1P0_DN<10>")
	)
	(arc
		(start 124.940568 -214.220044)
		(mid 124.906345 -214.186957)
		(end 124.873258 -214.152734)
		(width 0.0889)
		(layer "In4.Cu")
		(net "UPI_CPU1_CPU0_P1P0_DN<10>")
	)
	(arc
		(start 124.232416 -216.235026)
		(mid 124.311786 -215.961292)
		(end 124.51461 -215.761062)
		(width 0.0889)
		(layer "In4.Cu")
		(net "UPI_CPU1_CPU0_P1P0_DN<10>")
	)
	(arc
		(start 346.988384 -216.260426)
		(mid 346.910273 -216.537375)
		(end 346.705936 -216.739978)
		(width 0.0889)
		(layer "In4.Cu")
		(net "UPI_CPU1_CPU0_P1P0_DN<10>")
	)
	(arc
		(start 124.702062 -215.414606)
		(mid 124.782973 -215.144478)
		(end 124.984256 -214.946992)
		(width 0.0889)
		(layer "In4.Cu")
		(net "UPI_CPU1_CPU0_P1P0_DN<10>")
	)
	(arc
		(start 346.696792 -215.117426)
		(mid 346.569538 -215.247392)
		(end 346.518484 -215.421972)
		(width 0.0889)
		(layer "In4.Cu")
		(net "UPI_CPU1_CPU0_P1P0_DN<10>")
	)
	(arc
		(start 346.987876 -214.644732)
		(mid 346.906965 -214.91486)
		(end 346.705682 -215.112346)
		(width 0.0889)
		(layer "In4.Cu")
		(net "UPI_CPU1_CPU0_P1P0_DN<10>")
	)
	(arc
		(start 125.015244 -214.27694)
		(mid 124.976534 -214.250292)
		(end 124.940568 -214.220044)
		(width 0.0889)
		(layer "In4.Cu")
		(net "UPI_CPU1_CPU0_P1P0_DN<10>")
	)
	(arc
		(start 124.5235 -215.755982)
		(mid 124.654414 -215.619622)
		(end 124.702062 -215.436704)
		(width 0.0889)
		(layer "In4.Cu")
		(net "UPI_CPU1_CPU0_P1P0_DN<10>")
	)
	(arc
		(start 124.873258 -214.152734)
		(mid 124.79842 -214.060026)
		(end 124.737876 -213.957408)
		(width 0.0889)
		(layer "In4.Cu")
		(net "UPI_CPU1_CPU0_P1P0_DN<10>")
	)
	(arc
		(start 125.171962 -214.460328)
		(mid 125.107469 -214.356778)
		(end 125.015244 -214.27694)
		(width 0.0889)
		(layer "In4.Cu")
		(net "UPI_CPU1_CPU0_P1P0_DN<10>")
	)
	(arc
		(start 346.711778 -215.764618)
		(mid 346.914365 -215.970969)
		(end 346.988384 -216.25052)
		(width 0.0889)
		(layer "In4.Cu")
		(net "UPI_CPU1_CPU0_P1P0_DN<10>")
	)
	(arc
		(start 346.777564 -218.318842)
		(mid 346.769118 -218.325527)
		(end 346.760546 -218.33205)
		(width 0.0889)
		(layer "In4.Cu")
		(net "UPI_CPU1_CPU0_P1P0_DN<10>")
	)
	(arc
		(start 124.993146 -214.941912)
		(mid 125.1204 -214.811946)
		(end 125.171454 -214.637366)
		(width 0.0889)
		(layer "In4.Cu")
		(net "UPI_CPU1_CPU0_P1P0_DN<10>")
	)
	(arc
		(start 124.702062 -217.064336)
		(mid 124.654383 -216.881436)
		(end 124.5235 -216.745058)
		(width 0.0889)
		(layer "In4.Cu")
		(net "UPI_CPU1_CPU0_P1P0_DN<10>")
	)
	(segment
		(start 337.02498 -218.414346)
		(end 337.02498 -217.87866)
		(width 0.13208)
		(layer "F.Cu")
		(net "UPI_CPU1_CPU0_P1P0_DN<0>")
	)
	(segment
		(start 337.02498 -217.87866)
		(end 337.025234 -217.878406)
		(width 0.13208)
		(layer "F.Cu")
		(net "UPI_CPU1_CPU0_P1P0_DN<0>")
	)
	(segment
		(start 134.195566 -218.414346)
		(end 134.195566 -217.878406)
		(width 0.13208)
		(layer "F.Cu")
		(net "UPI_CPU1_CPU0_P1P0_DN<0>")
	)
	(segment
		(start 311.239662 -190.62319)
		(end 311.350152 -190.799212)
		(width 0.14732)
		(layer "In4.Cu")
		(net "UPI_CPU1_CPU0_P1P0_DN<0>")
	)
	(segment
		(start 143.62938 -205.59522)
		(end 143.800576 -205.594712)
		(width 0.14732)
		(layer "In4.Cu")
		(net "UPI_CPU1_CPU0_P1P0_DN<0>")
	)
	(segment
		(start 336.830924 -213.135718)
		(end 336.830924 -213.310978)
		(width 0.0889)
		(layer "In4.Cu")
		(net "UPI_CPU1_CPU0_P1P0_DN<0>")
	)
	(segment
		(start 334.09382 -207.2386)
		(end 335.011776 -208.156556)
		(width 0.14732)
		(layer "In4.Cu")
		(net "UPI_CPU1_CPU0_P1P0_DN<0>")
	)
	(segment
		(start 308.007766 -191.002158)
		(end 308.008528 -191.001396)
		(width 0.14732)
		(layer "In4.Cu")
		(net "UPI_CPU1_CPU0_P1P0_DN<0>")
	)
	(segment
		(start 336.888074 -211.463382)
		(end 336.888074 -211.69249)
		(width 0.14732)
		(layer "In4.Cu")
		(net "UPI_CPU1_CPU0_P1P0_DN<0>")
	)
	(segment
		(start 311.350152 -190.799212)
		(end 311.22874 -191.329564)
		(width 0.14732)
		(layer "In4.Cu")
		(net "UPI_CPU1_CPU0_P1P0_DN<0>")
	)
	(segment
		(start 311.460388 -191.698372)
		(end 312.370724 -191.906906)
		(width 0.14732)
		(layer "In4.Cu")
		(net "UPI_CPU1_CPU0_P1P0_DN<0>")
	)
	(segment
		(start 135.700008 -214.261192)
		(end 135.937752 -214.023448)
		(width 0.0889)
		(layer "In4.Cu")
		(net "UPI_CPU1_CPU0_P1P0_DN<0>")
	)
	(segment
		(start 336.888074 -211.69249)
		(end 336.888074 -211.714588)
		(width 0.0889)
		(layer "In4.Cu")
		(net "UPI_CPU1_CPU0_P1P0_DN<0>")
	)
	(segment
		(start 146.223736 -204.300328)
		(end 146.799046 -203.719684)
		(width 0.14732)
		(layer "In4.Cu")
		(net "UPI_CPU1_CPU0_P1P0_DN<0>")
	)
	(segment
		(start 138.314684 -211.690204)
		(end 138.519408 -211.689188)
		(width 0.14732)
		(layer "In4.Cu")
		(net "UPI_CPU1_CPU0_P1P0_DN<0>")
	)
	(segment
		(start 335.04759 -210.35645)
		(end 336.02549 -209.37855)
		(width 0.14732)
		(layer "In4.Cu")
		(net "UPI_CPU1_CPU0_P1P0_DN<0>")
	)
	(segment
		(start 144.592294 -205.94574)
		(end 145.167096 -205.365604)
		(width 0.14732)
		(layer "In4.Cu")
		(net "UPI_CPU1_CPU0_P1P0_DN<0>")
	)
	(segment
		(start 151.693372 -198.34733)
		(end 151.337264 -197.99427)
		(width 0.14732)
		(layer "In4.Cu")
		(net "UPI_CPU1_CPU0_P1P0_DN<0>")
	)
	(segment
		(start 312.370724 -191.906906)
		(end 312.90006 -192.2018)
		(width 0.14732)
		(layer "In4.Cu")
		(net "UPI_CPU1_CPU0_P1P0_DN<0>")
	)
	(segment
		(start 137.332974 -212.67674)
		(end 137.588244 -212.419184)
		(width 0.14732)
		(layer "In4.Cu")
		(net "UPI_CPU1_CPU0_P1P0_DN<0>")
	)
	(segment
		(start 154.649678 -195.802504)
		(end 154.649678 -195.802758)
		(width 0.14732)
		(layer "In4.Cu")
		(net "UPI_CPU1_CPU0_P1P0_DN<0>")
	)
	(segment
		(start 239.388904 -200.55967)
		(end 250.71705 -195.37553)
		(width 0.14732)
		(layer "In4.Cu")
		(net "UPI_CPU1_CPU0_P1P0_DN<0>")
	)
	(segment
		(start 138.778234 -211.219796)
		(end 139.034774 -210.961224)
		(width 0.14732)
		(layer "In4.Cu")
		(net "UPI_CPU1_CPU0_P1P0_DN<0>")
	)
	(segment
		(start 313.31916 -192.082674)
		(end 313.453526 -191.84112)
		(width 0.14732)
		(layer "In4.Cu")
		(net "UPI_CPU1_CPU0_P1P0_DN<0>")
	)
	(segment
		(start 144.15643 -205.947772)
		(end 144.592294 -205.94574)
		(width 0.14732)
		(layer "In4.Cu")
		(net "UPI_CPU1_CPU0_P1P0_DN<0>")
	)
	(segment
		(start 337.221322 -216.569798)
		(end 337.212432 -216.574878)
		(width 0.0889)
		(layer "In4.Cu")
		(net "UPI_CPU1_CPU0_P1P0_DN<0>")
	)
	(segment
		(start 336.23377 -209.37855)
		(end 336.88782 -210.0326)
		(width 0.14732)
		(layer "In4.Cu")
		(net "UPI_CPU1_CPU0_P1P0_DN<0>")
	)
	(segment
		(start 334.09382 -200.955656)
		(end 334.09382 -207.2386)
		(width 0.14732)
		(layer "In4.Cu")
		(net "UPI_CPU1_CPU0_P1P0_DN<0>")
	)
	(segment
		(start 135.700516 -214.707724)
		(end 135.700008 -214.706454)
		(width 0.0889)
		(layer "In4.Cu")
		(net "UPI_CPU1_CPU0_P1P0_DN<0>")
	)
	(segment
		(start 134.469378 -216.745058)
		(end 134.478268 -216.739978)
		(width 0.0889)
		(layer "In4.Cu")
		(net "UPI_CPU1_CPU0_P1P0_DN<0>")
	)
	(segment
		(start 145.2245 -203.949808)
		(end 145.432272 -203.948792)
		(width 0.14732)
		(layer "In4.Cu")
		(net "UPI_CPU1_CPU0_P1P0_DN<0>")
	)
	(segment
		(start 139.75969 -210.232244)
		(end 139.964414 -210.231228)
		(width 0.14732)
		(layer "In4.Cu")
		(net "UPI_CPU1_CPU0_P1P0_DN<0>")
	)
	(segment
		(start 138.056366 -212.156294)
		(end 138.055604 -211.95157)
		(width 0.14732)
		(layer "In4.Cu")
		(net "UPI_CPU1_CPU0_P1P0_DN<0>")
	)
	(segment
		(start 337.220814 -214.941912)
		(end 337.211924 -214.946992)
		(width 0.0889)
		(layer "In4.Cu")
		(net "UPI_CPU1_CPU0_P1P0_DN<0>")
	)
	(segment
		(start 301.197518 -190.989966)
		(end 301.53356 -191.267334)
		(width 0.14732)
		(layer "In4.Cu")
		(net "UPI_CPU1_CPU0_P1P0_DN<0>")
	)
	(segment
		(start 300.04004 -191.411606)
		(end 300.317154 -191.075818)
		(width 0.14732)
		(layer "In4.Cu")
		(net "UPI_CPU1_CPU0_P1P0_DN<0>")
	)
	(segment
		(start 309.997856 -191.363854)
		(end 310.36641 -191.132206)
		(width 0.14732)
		(layer "In4.Cu")
		(net "UPI_CPU1_CPU0_P1P0_DN<0>")
	)
	(segment
		(start 336.929984 -212.488018)
		(end 336.830924 -212.587078)
		(width 0.0889)
		(layer "In4.Cu")
		(net "UPI_CPU1_CPU0_P1P0_DN<0>")
	)
	(segment
		(start 151.119586 -199.36333)
		(end 151.694896 -198.782686)
		(width 0.14732)
		(layer "In4.Cu")
		(net "UPI_CPU1_CPU0_P1P0_DN<0>")
	)
	(segment
		(start 250.71705 -195.37553)
		(end 261.248398 -192.566036)
		(width 0.14732)
		(layer "In4.Cu")
		(net "UPI_CPU1_CPU0_P1P0_DN<0>")
	)
	(segment
		(start 300.317154 -191.075818)
		(end 300.268132 -190.570612)
		(width 0.14732)
		(layer "In4.Cu")
		(net "UPI_CPU1_CPU0_P1P0_DN<0>")
	)
	(segment
		(start 146.799046 -203.719684)
		(end 146.797522 -203.284328)
		(width 0.14732)
		(layer "In4.Cu")
		(net "UPI_CPU1_CPU0_P1P0_DN<0>")
	)
	(segment
		(start 140.946632 -209.240374)
		(end 140.945616 -209.035904)
		(width 0.14732)
		(layer "In4.Cu")
		(net "UPI_CPU1_CPU0_P1P0_DN<0>")
	)
	(segment
		(start 149.705314 -199.639936)
		(end 149.704298 -199.432164)
		(width 0.14732)
		(layer "In4.Cu")
		(net "UPI_CPU1_CPU0_P1P0_DN<0>")
	)
	(segment
		(start 147.064222 -202.303126)
		(end 147.42033 -202.65644)
		(width 0.14732)
		(layer "In4.Cu")
		(net "UPI_CPU1_CPU0_P1P0_DN<0>")
	)
	(segment
		(start 150.328122 -199.011794)
		(end 150.68423 -199.364854)
		(width 0.14732)
		(layer "In4.Cu")
		(net "UPI_CPU1_CPU0_P1P0_DN<0>")
	)
	(segment
		(start 150.68423 -199.364854)
		(end 151.119586 -199.36333)
		(width 0.14732)
		(layer "In4.Cu")
		(net "UPI_CPU1_CPU0_P1P0_DN<0>")
	)
	(segment
		(start 140.687044 -209.502248)
		(end 140.946632 -209.240374)
		(width 0.14732)
		(layer "In4.Cu")
		(net "UPI_CPU1_CPU0_P1P0_DN<0>")
	)
	(segment
		(start 134.039102 -217.607388)
		(end 134.063232 -217.518234)
		(width 0.0889)
		(layer "In4.Cu")
		(net "UPI_CPU1_CPU0_P1P0_DN<0>")
	)
	(segment
		(start 261.248398 -192.566036)
		(end 286.504126 -191.55918)
		(width 0.14732)
		(layer "In4.Cu")
		(net "UPI_CPU1_CPU0_P1P0_DN<0>")
	)
	(segment
		(start 140.22324 -209.76463)
		(end 140.48232 -209.503264)
		(width 0.14732)
		(layer "In4.Cu")
		(net "UPI_CPU1_CPU0_P1P0_DN<0>")
	)
	(segment
		(start 136.170416 -215.436704)
		(end 136.170416 -215.239092)
		(width 0.0889)
		(layer "In4.Cu")
		(net "UPI_CPU1_CPU0_P1P0_DN<0>")
	)
	(segment
		(start 143.177514 -206.2226)
		(end 143.176752 -206.051658)
		(width 0.14732)
		(layer "In4.Cu")
		(net "UPI_CPU1_CPU0_P1P0_DN<0>")
	)
	(segment
		(start 138.778996 -211.427314)
		(end 138.778234 -211.22259)
		(width 0.14732)
		(layer "In4.Cu")
		(net "UPI_CPU1_CPU0_P1P0_DN<0>")
	)
	(segment
		(start 337.213194 -217.554556)
		(end 337.221322 -217.559128)
		(width 0.0889)
		(layer "In4.Cu")
		(net "UPI_CPU1_CPU0_P1P0_DN<0>")
	)
	(segment
		(start 143.5354 -207.094328)
		(end 143.533622 -206.57566)
		(width 0.14732)
		(layer "In4.Cu")
		(net "UPI_CPU1_CPU0_P1P0_DN<0>")
	)
	(segment
		(start 135.700516 -216.260426)
		(end 135.700516 -216.25052)
		(width 0.0889)
		(layer "In4.Cu")
		(net "UPI_CPU1_CPU0_P1P0_DN<0>")
	)
	(segment
		(start 336.830924 -212.762338)
		(end 336.929984 -212.861398)
		(width 0.0889)
		(layer "In4.Cu")
		(net "UPI_CPU1_CPU0_P1P0_DN<0>")
	)
	(segment
		(start 336.929984 -213.036658)
		(end 336.830924 -213.135718)
		(width 0.0889)
		(layer "In4.Cu")
		(net "UPI_CPU1_CPU0_P1P0_DN<0>")
	)
	(segment
		(start 155.06319 -194.791838)
		(end 156.716984 -193.123566)
		(width 0.14732)
		(layer "In4.Cu")
		(net "UPI_CPU1_CPU0_P1P0_DN<0>")
	)
	(segment
		(start 337.208622 -216.577164)
		(end 337.204812 -216.579196)
		(width 0.0889)
		(layer "In4.Cu")
		(net "UPI_CPU1_CPU0_P1P0_DN<0>")
	)
	(segment
		(start 138.055604 -211.95157)
		(end 138.055604 -211.948014)
		(width 0.14732)
		(layer "In4.Cu")
		(net "UPI_CPU1_CPU0_P1P0_DN<0>")
	)
	(segment
		(start 137.796778 -212.418168)
		(end 138.056366 -212.156294)
		(width 0.14732)
		(layer "In4.Cu")
		(net "UPI_CPU1_CPU0_P1P0_DN<0>")
	)
	(segment
		(start 286.504126 -191.55918)
		(end 286.504126 -191.558926)
		(width 0.14732)
		(layer "In4.Cu")
		(net "UPI_CPU1_CPU0_P1P0_DN<0>")
	)
	(segment
		(start 146.85645 -202.304142)
		(end 147.064222 -202.303126)
		(width 0.14732)
		(layer "In4.Cu")
		(net "UPI_CPU1_CPU0_P1P0_DN<0>")
	)
	(segment
		(start 336.92973 -217.064336)
		(end 336.92973 -217.071956)
		(width 0.0889)
		(layer "In4.Cu")
		(net "UPI_CPU1_CPU0_P1P0_DN<0>")
	)
	(segment
		(start 138.055604 -211.948014)
		(end 138.311636 -211.690204)
		(width 0.14732)
		(layer "In4.Cu")
		(net "UPI_CPU1_CPU0_P1P0_DN<0>")
	)
	(segment
		(start 146.440398 -202.723496)
		(end 146.85645 -202.304142)
		(width 0.14732)
		(layer "In4.Cu")
		(net "UPI_CPU1_CPU0_P1P0_DN<0>")
	)
	(segment
		(start 312.90006 -192.2018)
		(end 313.31916 -192.082674)
		(width 0.14732)
		(layer "In4.Cu")
		(net "UPI_CPU1_CPU0_P1P0_DN<0>")
	)
	(segment
		(start 136.86536 -213.148164)
		(end 136.869678 -213.148164)
		(width 0.14732)
		(layer "In4.Cu")
		(net "UPI_CPU1_CPU0_P1P0_DN<0>")
	)
	(segment
		(start 315.04128 -193.393568)
		(end 330.867258 -198.497698)
		(width 0.14732)
		(layer "In4.Cu")
		(net "UPI_CPU1_CPU0_P1P0_DN<0>")
	)
	(segment
		(start 149.704298 -199.432164)
		(end 150.12035 -199.01281)
		(width 0.14732)
		(layer "In4.Cu")
		(net "UPI_CPU1_CPU0_P1P0_DN<0>")
	)
	(segment
		(start 135.887968 -215.926162)
		(end 135.894064 -215.922606)
		(width 0.0889)
		(layer "In4.Cu")
		(net "UPI_CPU1_CPU0_P1P0_DN<0>")
	)
	(segment
		(start 149.05228 -201.01052)
		(end 149.487382 -201.008996)
		(width 0.14732)
		(layer "In4.Cu")
		(net "UPI_CPU1_CPU0_P1P0_DN<0>")
	)
	(segment
		(start 336.929984 -212.861398)
		(end 336.929984 -213.036658)
		(width 0.0889)
		(layer "In4.Cu")
		(net "UPI_CPU1_CPU0_P1P0_DN<0>")
	)
	(segment
		(start 337.204812 -216.579196)
		(end 337.20024 -216.58199)
		(width 0.0889)
		(layer "In4.Cu")
		(net "UPI_CPU1_CPU0_P1P0_DN<0>")
	)
	(segment
		(start 334.612234 -210.35645)
		(end 335.04759 -210.35645)
		(width 0.14732)
		(layer "In4.Cu")
		(net "UPI_CPU1_CPU0_P1P0_DN<0>")
	)
	(segment
		(start 151.694896 -198.782686)
		(end 151.693372 -198.34733)
		(width 0.14732)
		(layer "In4.Cu")
		(net "UPI_CPU1_CPU0_P1P0_DN<0>")
	)
	(segment
		(start 300.268132 -190.570612)
		(end 300.400212 -190.410084)
		(width 0.14732)
		(layer "In4.Cu")
		(net "UPI_CPU1_CPU0_P1P0_DN<0>")
	)
	(segment
		(start 151.960072 -197.366128)
		(end 152.31618 -197.719188)
		(width 0.14732)
		(layer "In4.Cu")
		(net "UPI_CPU1_CPU0_P1P0_DN<0>")
	)
	(segment
		(start 305.184048 -190.913258)
		(end 308.007766 -191.002158)
		(width 0.14732)
		(layer "In4.Cu")
		(net "UPI_CPU1_CPU0_P1P0_DN<0>")
	)
	(segment
		(start 139.037314 -210.961224)
		(end 139.242038 -210.960208)
		(width 0.14732)
		(layer "In4.Cu")
		(net "UPI_CPU1_CPU0_P1P0_DN<0>")
	)
	(segment
		(start 135.879078 -215.931242)
		(end 135.887968 -215.926162)
		(width 0.0889)
		(layer "In4.Cu")
		(net "UPI_CPU1_CPU0_P1P0_DN<0>")
	)
	(segment
		(start 300.400212 -190.410084)
		(end 300.987968 -190.353188)
		(width 0.14732)
		(layer "In4.Cu")
		(net "UPI_CPU1_CPU0_P1P0_DN<0>")
	)
	(segment
		(start 336.92973 -215.414606)
		(end 336.92973 -215.436704)
		(width 0.0889)
		(layer "In4.Cu")
		(net "UPI_CPU1_CPU0_P1P0_DN<0>")
	)
	(segment
		(start 334.033876 -209.342736)
		(end 334.033876 -209.778092)
		(width 0.14732)
		(layer "In4.Cu")
		(net "UPI_CPU1_CPU0_P1P0_DN<0>")
	)
	(segment
		(start 336.929984 -211.756498)
		(end 336.929984 -212.488018)
		(width 0.0889)
		(layer "In4.Cu")
		(net "UPI_CPU1_CPU0_P1P0_DN<0>")
	)
	(segment
		(start 314.210954 -192.931542)
		(end 315.04128 -193.393568)
		(width 0.14732)
		(layer "In4.Cu")
		(net "UPI_CPU1_CPU0_P1P0_DN<0>")
	)
	(segment
		(start 313.652916 -191.784224)
		(end 314.169298 -192.071752)
		(width 0.14732)
		(layer "In4.Cu")
		(net "UPI_CPU1_CPU0_P1P0_DN<0>")
	)
	(segment
		(start 157.884368 -192.530222)
		(end 160.013904 -191.759078)
		(width 0.14732)
		(layer "In4.Cu")
		(net "UPI_CPU1_CPU0_P1P0_DN<0>")
	)
	(segment
		(start 330.867258 -198.497698)
		(end 331.804772 -198.847456)
		(width 0.14732)
		(layer "In4.Cu")
		(net "UPI_CPU1_CPU0_P1P0_DN<0>")
	)
	(segment
		(start 145.432272 -203.948792)
		(end 145.78838 -204.301852)
		(width 0.14732)
		(layer "In4.Cu")
		(net "UPI_CPU1_CPU0_P1P0_DN<0>")
	)
	(segment
		(start 145.167096 -205.365604)
		(end 145.165572 -204.929994)
		(width 0.14732)
		(layer "In4.Cu")
		(net "UPI_CPU1_CPU0_P1P0_DN<0>")
	)
	(segment
		(start 337.212432 -215.926162)
		(end 337.213956 -215.926924)
		(width 0.0889)
		(layer "In4.Cu")
		(net "UPI_CPU1_CPU0_P1P0_DN<0>")
	)
	(segment
		(start 337.25993 -218.170252)
		(end 337.181698 -218.149424)
		(width 0.0889)
		(layer "In4.Cu")
		(net "UPI_CPU1_CPU0_P1P0_DN<0>")
	)
	(segment
		(start 154.649678 -195.802758)
		(end 155.06319 -194.791838)
		(width 0.14732)
		(layer "In4.Cu")
		(net "UPI_CPU1_CPU0_P1P0_DN<0>")
	)
	(segment
		(start 140.224002 -209.969354)
		(end 140.22324 -209.76463)
		(width 0.14732)
		(layer "In4.Cu")
		(net "UPI_CPU1_CPU0_P1P0_DN<0>")
	)
	(segment
		(start 141.286738 -208.691734)
		(end 142.42415 -208.214468)
		(width 0.14732)
		(layer "In4.Cu")
		(net "UPI_CPU1_CPU0_P1P0_DN<0>")
	)
	(segment
		(start 139.50061 -210.491832)
		(end 139.757912 -210.232244)
		(width 0.14732)
		(layer "In4.Cu")
		(net "UPI_CPU1_CPU0_P1P0_DN<0>")
	)
	(segment
		(start 156.716984 -193.123566)
		(end 157.884368 -192.530222)
		(width 0.14732)
		(layer "In4.Cu")
		(net "UPI_CPU1_CPU0_P1P0_DN<0>")
	)
	(segment
		(start 300.987968 -190.353188)
		(end 301.148496 -190.485268)
		(width 0.14732)
		(layer "In4.Cu")
		(net "UPI_CPU1_CPU0_P1P0_DN<0>")
	)
	(segment
		(start 143.533622 -206.57566)
		(end 143.177514 -206.2226)
		(width 0.14732)
		(layer "In4.Cu")
		(net "UPI_CPU1_CPU0_P1P0_DN<0>")
	)
	(segment
		(start 148.429472 -201.638662)
		(end 148.073364 -201.285602)
		(width 0.14732)
		(layer "In4.Cu")
		(net "UPI_CPU1_CPU0_P1P0_DN<0>")
	)
	(segment
		(start 337.181698 -218.149424)
		(end 337.025234 -217.878406)
		(width 0.0889)
		(layer "In4.Cu")
		(net "UPI_CPU1_CPU0_P1P0_DN<0>")
	)
	(segment
		(start 232.596944 -199.977502)
		(end 235.923328 -200.805796)
		(width 0.14732)
		(layer "In4.Cu")
		(net "UPI_CPU1_CPU0_P1P0_DN<0>")
	)
	(segment
		(start 134.290816 -217.07856)
		(end 134.290816 -217.064336)
		(width 0.0889)
		(layer "In4.Cu")
		(net "UPI_CPU1_CPU0_P1P0_DN<0>")
	)
	(segment
		(start 151.7523 -197.367144)
		(end 151.960072 -197.366128)
		(width 0.14732)
		(layer "In4.Cu")
		(net "UPI_CPU1_CPU0_P1P0_DN<0>")
	)
	(segment
		(start 134.195566 -217.878406)
		(end 134.039102 -217.607388)
		(width 0.0889)
		(layer "In4.Cu")
		(net "UPI_CPU1_CPU0_P1P0_DN<0>")
	)
	(segment
		(start 219.986352 -193.295778)
		(end 232.564178 -199.969628)
		(width 0.14732)
		(layer "In4.Cu")
		(net "UPI_CPU1_CPU0_P1P0_DN<0>")
	)
	(segment
		(start 336.88782 -210.0326)
		(end 336.88782 -211.463128)
		(width 0.14732)
		(layer "In4.Cu")
		(net "UPI_CPU1_CPU0_P1P0_DN<0>")
	)
	(segment
		(start 232.564178 -199.969628)
		(end 232.59669 -199.977756)
		(width 0.14732)
		(layer "In4.Cu")
		(net "UPI_CPU1_CPU0_P1P0_DN<0>")
	)
	(segment
		(start 301.53356 -191.267334)
		(end 305.184048 -190.913258)
		(width 0.14732)
		(layer "In4.Cu")
		(net "UPI_CPU1_CPU0_P1P0_DN<0>")
	)
	(segment
		(start 144.808956 -204.467968)
		(end 144.808448 -204.369162)
		(width 0.14732)
		(layer "In4.Cu")
		(net "UPI_CPU1_CPU0_P1P0_DN<0>")
	)
	(segment
		(start 314.169298 -192.071752)
		(end 314.226194 -192.271396)
		(width 0.14732)
		(layer "In4.Cu")
		(net "UPI_CPU1_CPU0_P1P0_DN<0>")
	)
	(segment
		(start 148.430996 -202.073764)
		(end 148.429472 -201.638662)
		(width 0.14732)
		(layer "In4.Cu")
		(net "UPI_CPU1_CPU0_P1P0_DN<0>")
	)
	(segment
		(start 135.99668 -214.023448)
		(end 136.012174 -214.007954)
		(width 0.0889)
		(layer "In4.Cu")
		(net "UPI_CPU1_CPU0_P1P0_DN<0>")
	)
	(segment
		(start 147.42033 -202.65644)
		(end 147.855432 -202.654662)
		(width 0.14732)
		(layer "In4.Cu")
		(net "UPI_CPU1_CPU0_P1P0_DN<0>")
	)
	(segment
		(start 208.354422 -191.417956)
		(end 219.986352 -193.295778)
		(width 0.14732)
		(layer "In4.Cu")
		(net "UPI_CPU1_CPU0_P1P0_DN<0>")
	)
	(segment
		(start 149.487382 -201.008996)
		(end 150.062946 -200.428098)
		(width 0.14732)
		(layer "In4.Cu")
		(net "UPI_CPU1_CPU0_P1P0_DN<0>")
	)
	(segment
		(start 232.59669 -199.977756)
		(end 232.596944 -199.977502)
		(width 0.14732)
		(layer "In4.Cu")
		(net "UPI_CPU1_CPU0_P1P0_DN<0>")
	)
	(segment
		(start 137.332974 -212.68055)
		(end 137.332974 -212.67674)
		(width 0.14732)
		(layer "In4.Cu")
		(net "UPI_CPU1_CPU0_P1P0_DN<0>")
	)
	(segment
		(start 137.074402 -213.147148)
		(end 137.33399 -212.885274)
		(width 0.14732)
		(layer "In4.Cu")
		(net "UPI_CPU1_CPU0_P1P0_DN<0>")
	)
	(segment
		(start 301.148496 -190.485268)
		(end 301.197518 -190.989966)
		(width 0.14732)
		(layer "In4.Cu")
		(net "UPI_CPU1_CPU0_P1P0_DN<0>")
	)
	(segment
		(start 286.504126 -191.558926)
		(end 298.014644 -191.608456)
		(width 0.14732)
		(layer "In4.Cu")
		(net "UPI_CPU1_CPU0_P1P0_DN<0>")
	)
	(segment
		(start 337.399376 -214.461344)
		(end 337.399376 -214.622634)
		(width 0.0889)
		(layer "In4.Cu")
		(net "UPI_CPU1_CPU0_P1P0_DN<0>")
	)
	(segment
		(start 337.21167 -215.925654)
		(end 337.212432 -215.926162)
		(width 0.0889)
		(layer "In4.Cu")
		(net "UPI_CPU1_CPU0_P1P0_DN<0>")
	)
	(segment
		(start 298.014644 -191.608456)
		(end 300.04004 -191.411606)
		(width 0.14732)
		(layer "In4.Cu")
		(net "UPI_CPU1_CPU0_P1P0_DN<0>")
	)
	(segment
		(start 152.31618 -197.719188)
		(end 152.751536 -197.717664)
		(width 0.14732)
		(layer "In4.Cu")
		(net "UPI_CPU1_CPU0_P1P0_DN<0>")
	)
	(segment
		(start 146.797522 -203.284328)
		(end 146.441414 -202.931268)
		(width 0.14732)
		(layer "In4.Cu")
		(net "UPI_CPU1_CPU0_P1P0_DN<0>")
	)
	(segment
		(start 335.011776 -208.156556)
		(end 335.011776 -208.364836)
		(width 0.14732)
		(layer "In4.Cu")
		(net "UPI_CPU1_CPU0_P1P0_DN<0>")
	)
	(segment
		(start 147.855432 -202.654662)
		(end 148.430996 -202.073764)
		(width 0.14732)
		(layer "In4.Cu")
		(net "UPI_CPU1_CPU0_P1P0_DN<0>")
	)
	(segment
		(start 314.226194 -192.271396)
		(end 314.091828 -192.51295)
		(width 0.14732)
		(layer "In4.Cu")
		(net "UPI_CPU1_CPU0_P1P0_DN<0>")
	)
	(segment
		(start 237.415324 -200.805796)
		(end 239.388904 -200.55967)
		(width 0.14732)
		(layer "In4.Cu")
		(net "UPI_CPU1_CPU0_P1P0_DN<0>")
	)
	(segment
		(start 150.062946 -200.428098)
		(end 150.061422 -199.992996)
		(width 0.14732)
		(layer "In4.Cu")
		(net "UPI_CPU1_CPU0_P1P0_DN<0>")
	)
	(segment
		(start 337.206336 -215.922606)
		(end 337.21167 -215.925654)
		(width 0.0889)
		(layer "In4.Cu")
		(net "UPI_CPU1_CPU0_P1P0_DN<0>")
	)
	(segment
		(start 337.212432 -216.574878)
		(end 337.208622 -216.577164)
		(width 0.0889)
		(layer "In4.Cu")
		(net "UPI_CPU1_CPU0_P1P0_DN<0>")
	)
	(segment
		(start 336.02549 -209.37855)
		(end 336.23377 -209.37855)
		(width 0.14732)
		(layer "In4.Cu")
		(net "UPI_CPU1_CPU0_P1P0_DN<0>")
	)
	(segment
		(start 235.923328 -200.805796)
		(end 237.415324 -200.805796)
		(width 0.14732)
		(layer "In4.Cu")
		(net "UPI_CPU1_CPU0_P1P0_DN<0>")
	)
	(segment
		(start 150.061422 -199.992996)
		(end 149.705314 -199.639936)
		(width 0.14732)
		(layer "In4.Cu")
		(net "UPI_CPU1_CPU0_P1P0_DN<0>")
	)
	(segment
		(start 144.809464 -204.576934)
		(end 144.808956 -204.473302)
		(width 0.14732)
		(layer "In4.Cu")
		(net "UPI_CPU1_CPU0_P1P0_DN<0>")
	)
	(segment
		(start 144.808448 -204.369162)
		(end 145.2245 -203.949808)
		(width 0.14732)
		(layer "In4.Cu")
		(net "UPI_CPU1_CPU0_P1P0_DN<0>")
	)
	(segment
		(start 308.00929 -191.001396)
		(end 308.956456 -191.125856)
		(width 0.14732)
		(layer "In4.Cu")
		(net "UPI_CPU1_CPU0_P1P0_DN<0>")
	)
	(segment
		(start 313.453526 -191.84112)
		(end 313.652916 -191.784224)
		(width 0.14732)
		(layer "In4.Cu")
		(net "UPI_CPU1_CPU0_P1P0_DN<0>")
	)
	(segment
		(start 148.4884 -200.658476)
		(end 148.696172 -200.65746)
		(width 0.14732)
		(layer "In4.Cu")
		(net "UPI_CPU1_CPU0_P1P0_DN<0>")
	)
	(segment
		(start 139.757912 -210.232244)
		(end 139.75969 -210.232244)
		(width 0.14732)
		(layer "In4.Cu")
		(net "UPI_CPU1_CPU0_P1P0_DN<0>")
	)
	(segment
		(start 310.663844 -190.491364)
		(end 311.239662 -190.62319)
		(width 0.14732)
		(layer "In4.Cu")
		(net "UPI_CPU1_CPU0_P1P0_DN<0>")
	)
	(segment
		(start 148.072348 -201.07783)
		(end 148.4884 -200.658476)
		(width 0.14732)
		(layer "In4.Cu")
		(net "UPI_CPU1_CPU0_P1P0_DN<0>")
	)
	(segment
		(start 151.337264 -197.99427)
		(end 151.336248 -197.786498)
		(width 0.14732)
		(layer "In4.Cu")
		(net "UPI_CPU1_CPU0_P1P0_DN<0>")
	)
	(segment
		(start 336.830924 -212.587078)
		(end 336.830924 -212.762338)
		(width 0.0889)
		(layer "In4.Cu")
		(net "UPI_CPU1_CPU0_P1P0_DN<0>")
	)
	(segment
		(start 331.804772 -198.847456)
		(end 332.652116 -199.513952)
		(width 0.14732)
		(layer "In4.Cu")
		(net "UPI_CPU1_CPU0_P1P0_DN<0>")
	)
	(segment
		(start 139.964414 -210.231228)
		(end 140.224002 -209.969354)
		(width 0.14732)
		(layer "In4.Cu")
		(net "UPI_CPU1_CPU0_P1P0_DN<0>")
	)
	(segment
		(start 140.945616 -209.035904)
		(end 141.286738 -208.691734)
		(width 0.14732)
		(layer "In4.Cu")
		(net "UPI_CPU1_CPU0_P1P0_DN<0>")
	)
	(segment
		(start 308.956456 -191.125856)
		(end 309.997856 -191.363854)
		(width 0.14732)
		(layer "In4.Cu")
		(net "UPI_CPU1_CPU0_P1P0_DN<0>")
	)
	(segment
		(start 143.800576 -205.594712)
		(end 144.15643 -205.947772)
		(width 0.14732)
		(layer "In4.Cu")
		(net "UPI_CPU1_CPU0_P1P0_DN<0>")
	)
	(segment
		(start 145.78838 -204.301852)
		(end 146.223736 -204.300328)
		(width 0.14732)
		(layer "In4.Cu")
		(net "UPI_CPU1_CPU0_P1P0_DN<0>")
	)
	(segment
		(start 189.995302 -192.160398)
		(end 208.354422 -191.417956)
		(width 0.14732)
		(layer "In4.Cu")
		(net "UPI_CPU1_CPU0_P1P0_DN<0>")
	)
	(segment
		(start 144.808956 -204.473302)
		(end 144.808956 -204.467968)
		(width 0.14732)
		(layer "In4.Cu")
		(net "UPI_CPU1_CPU0_P1P0_DN<0>")
	)
	(segment
		(start 139.501626 -210.698334)
		(end 139.50061 -210.49361)
		(width 0.14732)
		(layer "In4.Cu")
		(net "UPI_CPU1_CPU0_P1P0_DN<0>")
	)
	(segment
		(start 138.311636 -211.690204)
		(end 138.314684 -211.690204)
		(width 0.14732)
		(layer "In4.Cu")
		(net "UPI_CPU1_CPU0_P1P0_DN<0>")
	)
	(segment
		(start 146.441414 -202.931268)
		(end 146.440398 -202.723496)
		(width 0.14732)
		(layer "In4.Cu")
		(net "UPI_CPU1_CPU0_P1P0_DN<0>")
	)
	(segment
		(start 137.592054 -212.419184)
		(end 137.796778 -212.418168)
		(width 0.14732)
		(layer "In4.Cu")
		(net "UPI_CPU1_CPU0_P1P0_DN<0>")
	)
	(segment
		(start 336.929984 -213.410038)
		(end 336.929984 -213.930484)
		(width 0.0889)
		(layer "In4.Cu")
		(net "UPI_CPU1_CPU0_P1P0_DN<0>")
	)
	(segment
		(start 337.212432 -217.554048)
		(end 337.213194 -217.554556)
		(width 0.0889)
		(layer "In4.Cu")
		(net "UPI_CPU1_CPU0_P1P0_DN<0>")
	)
	(segment
		(start 336.830924 -213.310978)
		(end 336.929984 -213.410038)
		(width 0.0889)
		(layer "In4.Cu")
		(net "UPI_CPU1_CPU0_P1P0_DN<0>")
	)
	(segment
		(start 148.073364 -201.285602)
		(end 148.072348 -201.07783)
		(width 0.14732)
		(layer "In4.Cu")
		(net "UPI_CPU1_CPU0_P1P0_DN<0>")
	)
	(segment
		(start 337.213956 -215.926924)
		(end 337.221322 -215.931242)
		(width 0.0889)
		(layer "In4.Cu")
		(net "UPI_CPU1_CPU0_P1P0_DN<0>")
	)
	(segment
		(start 140.48232 -209.503264)
		(end 140.687044 -209.502248)
		(width 0.14732)
		(layer "In4.Cu")
		(net "UPI_CPU1_CPU0_P1P0_DN<0>")
	)
	(segment
		(start 310.36641 -191.132206)
		(end 310.487822 -190.601854)
		(width 0.14732)
		(layer "In4.Cu")
		(net "UPI_CPU1_CPU0_P1P0_DN<0>")
	)
	(segment
		(start 152.751536 -197.717664)
		(end 154.649678 -195.802504)
		(width 0.14732)
		(layer "In4.Cu")
		(net "UPI_CPU1_CPU0_P1P0_DN<0>")
	)
	(segment
		(start 138.778234 -211.22259)
		(end 138.778234 -211.219796)
		(width 0.14732)
		(layer "In4.Cu")
		(net "UPI_CPU1_CPU0_P1P0_DN<0>")
	)
	(segment
		(start 336.88782 -211.463128)
		(end 336.888074 -211.463382)
		(width 0.14732)
		(layer "In4.Cu")
		(net "UPI_CPU1_CPU0_P1P0_DN<0>")
	)
	(segment
		(start 308.008528 -191.001396)
		(end 308.00929 -191.001396)
		(width 0.14732)
		(layer "In4.Cu")
		(net "UPI_CPU1_CPU0_P1P0_DN<0>")
	)
	(segment
		(start 335.011776 -208.364836)
		(end 334.033876 -209.342736)
		(width 0.14732)
		(layer "In4.Cu")
		(net "UPI_CPU1_CPU0_P1P0_DN<0>")
	)
	(segment
		(start 139.034774 -210.961224)
		(end 139.037314 -210.961224)
		(width 0.14732)
		(layer "In4.Cu")
		(net "UPI_CPU1_CPU0_P1P0_DN<0>")
	)
	(segment
		(start 135.700008 -214.706454)
		(end 135.700008 -214.261192)
		(width 0.0889)
		(layer "In4.Cu")
		(net "UPI_CPU1_CPU0_P1P0_DN<0>")
	)
	(segment
		(start 148.696172 -200.65746)
		(end 149.05228 -201.01052)
		(width 0.14732)
		(layer "In4.Cu")
		(net "UPI_CPU1_CPU0_P1P0_DN<0>")
	)
	(segment
		(start 136.869678 -213.148164)
		(end 137.074402 -213.147148)
		(width 0.14732)
		(layer "In4.Cu")
		(net "UPI_CPU1_CPU0_P1P0_DN<0>")
	)
	(segment
		(start 143.176752 -206.051658)
		(end 143.62938 -205.59522)
		(width 0.14732)
		(layer "In4.Cu")
		(net "UPI_CPU1_CPU0_P1P0_DN<0>")
	)
	(segment
		(start 310.487822 -190.601854)
		(end 310.663844 -190.491364)
		(width 0.14732)
		(layer "In4.Cu")
		(net "UPI_CPU1_CPU0_P1P0_DN<0>")
	)
	(segment
		(start 135.937752 -214.023448)
		(end 135.99668 -214.023448)
		(width 0.0889)
		(layer "In4.Cu")
		(net "UPI_CPU1_CPU0_P1P0_DN<0>")
	)
	(segment
		(start 332.652116 -199.513952)
		(end 334.09382 -200.955656)
		(width 0.14732)
		(layer "In4.Cu")
		(net "UPI_CPU1_CPU0_P1P0_DN<0>")
	)
	(segment
		(start 142.42415 -208.214468)
		(end 143.5354 -207.094328)
		(width 0.14732)
		(layer "In4.Cu")
		(net "UPI_CPU1_CPU0_P1P0_DN<0>")
	)
	(segment
		(start 137.33399 -212.885274)
		(end 137.332974 -212.68055)
		(width 0.14732)
		(layer "In4.Cu")
		(net "UPI_CPU1_CPU0_P1P0_DN<0>")
	)
	(segment
		(start 334.033876 -209.778092)
		(end 334.612234 -210.35645)
		(width 0.14732)
		(layer "In4.Cu")
		(net "UPI_CPU1_CPU0_P1P0_DN<0>")
	)
	(segment
		(start 139.242038 -210.960208)
		(end 139.501626 -210.698334)
		(width 0.14732)
		(layer "In4.Cu")
		(net "UPI_CPU1_CPU0_P1P0_DN<0>")
	)
	(segment
		(start 151.336248 -197.786498)
		(end 151.7523 -197.367144)
		(width 0.14732)
		(layer "In4.Cu")
		(net "UPI_CPU1_CPU0_P1P0_DN<0>")
	)
	(segment
		(start 145.165572 -204.929994)
		(end 144.809464 -204.576934)
		(width 0.14732)
		(layer "In4.Cu")
		(net "UPI_CPU1_CPU0_P1P0_DN<0>")
	)
	(segment
		(start 311.22874 -191.329564)
		(end 311.460388 -191.698372)
		(width 0.14732)
		(layer "In4.Cu")
		(net "UPI_CPU1_CPU0_P1P0_DN<0>")
	)
	(segment
		(start 160.013904 -191.759078)
		(end 189.995302 -192.160398)
		(width 0.14732)
		(layer "In4.Cu")
		(net "UPI_CPU1_CPU0_P1P0_DN<0>")
	)
	(segment
		(start 139.50061 -210.49361)
		(end 139.50061 -210.491832)
		(width 0.14732)
		(layer "In4.Cu")
		(net "UPI_CPU1_CPU0_P1P0_DN<0>")
	)
	(segment
		(start 150.12035 -199.01281)
		(end 150.328122 -199.011794)
		(width 0.14732)
		(layer "In4.Cu")
		(net "UPI_CPU1_CPU0_P1P0_DN<0>")
	)
	(segment
		(start 136.012174 -214.007954)
		(end 136.86536 -213.148164)
		(width 0.14732)
		(layer "In4.Cu")
		(net "UPI_CPU1_CPU0_P1P0_DN<0>")
	)
	(segment
		(start 314.091828 -192.51295)
		(end 314.210954 -192.931542)
		(width 0.14732)
		(layer "In4.Cu")
		(net "UPI_CPU1_CPU0_P1P0_DN<0>")
	)
	(segment
		(start 138.519408 -211.689188)
		(end 138.778996 -211.427314)
		(width 0.14732)
		(layer "In4.Cu")
		(net "UPI_CPU1_CPU0_P1P0_DN<0>")
	)
	(segment
		(start 336.888074 -211.714588)
		(end 336.929984 -211.756498)
		(width 0.0889)
		(layer "In4.Cu")
		(net "UPI_CPU1_CPU0_P1P0_DN<0>")
	)
	(segment
		(start 137.588244 -212.419184)
		(end 137.592054 -212.419184)
		(width 0.14732)
		(layer "In4.Cu")
		(net "UPI_CPU1_CPU0_P1P0_DN<0>")
	)
	(arc
		(start 337.215226 -214.261954)
		(mid 337.324373 -214.345882)
		(end 337.399376 -214.461344)
		(width 0.0889)
		(layer "In4.Cu")
		(net "UPI_CPU1_CPU0_P1P0_DN<0>")
	)
	(arc
		(start 134.478268 -216.739978)
		(mid 134.665466 -216.689835)
		(end 134.852664 -216.739978)
		(width 0.0889)
		(layer "In4.Cu")
		(net "UPI_CPU1_CPU0_P1P0_DN<0>")
	)
	(arc
		(start 134.079996 -217.50528)
		(mid 134.232503 -217.315182)
		(end 134.290816 -217.07856)
		(width 0.0889)
		(layer "In4.Cu")
		(net "UPI_CPU1_CPU0_P1P0_DN<0>")
	)
	(arc
		(start 135.418068 -216.739978)
		(mid 135.622403 -216.537373)
		(end 135.700516 -216.260426)
		(width 0.0889)
		(layer "In4.Cu")
		(net "UPI_CPU1_CPU0_P1P0_DN<0>")
	)
	(arc
		(start 337.221322 -215.931242)
		(mid 337.399919 -216.25052)
		(end 337.221322 -216.569798)
		(width 0.0889)
		(layer "In4.Cu")
		(net "UPI_CPU1_CPU0_P1P0_DN<0>")
	)
	(arc
		(start 336.945224 -213.969346)
		(mid 337.055218 -214.138715)
		(end 337.215226 -214.261954)
		(width 0.0889)
		(layer "In4.Cu")
		(net "UPI_CPU1_CPU0_P1P0_DN<0>")
	)
	(arc
		(start 134.290816 -217.064336)
		(mid 134.338495 -216.881436)
		(end 134.469378 -216.745058)
		(width 0.0889)
		(layer "In4.Cu")
		(net "UPI_CPU1_CPU0_P1P0_DN<0>")
	)
	(arc
		(start 134.063232 -217.518234)
		(mid 134.071675 -217.511836)
		(end 134.079996 -217.50528)
		(width 0.0889)
		(layer "In4.Cu")
		(net "UPI_CPU1_CPU0_P1P0_DN<0>")
	)
	(arc
		(start 337.20024 -216.58199)
		(mid 337.002012 -216.787838)
		(end 336.92973 -217.064336)
		(width 0.0889)
		(layer "In4.Cu")
		(net "UPI_CPU1_CPU0_P1P0_DN<0>")
	)
	(arc
		(start 337.221322 -217.559128)
		(mid 337.352236 -217.695488)
		(end 337.399884 -217.878406)
		(width 0.0889)
		(layer "In4.Cu")
		(net "UPI_CPU1_CPU0_P1P0_DN<0>")
	)
	(arc
		(start 135.894064 -215.922606)
		(mid 136.096477 -215.716193)
		(end 136.170416 -215.436704)
		(width 0.0889)
		(layer "In4.Cu")
		(net "UPI_CPU1_CPU0_P1P0_DN<0>")
	)
	(arc
		(start 337.399376 -214.622634)
		(mid 337.351697 -214.805534)
		(end 337.220814 -214.941912)
		(width 0.0889)
		(layer "In4.Cu")
		(net "UPI_CPU1_CPU0_P1P0_DN<0>")
	)
	(arc
		(start 134.852664 -216.739978)
		(mid 135.135366 -216.815754)
		(end 135.418068 -216.739978)
		(width 0.0889)
		(layer "In4.Cu")
		(net "UPI_CPU1_CPU0_P1P0_DN<0>")
	)
	(arc
		(start 336.92973 -217.071956)
		(mid 337.007359 -217.350369)
		(end 337.212432 -217.554048)
		(width 0.0889)
		(layer "In4.Cu")
		(net "UPI_CPU1_CPU0_P1P0_DN<0>")
	)
	(arc
		(start 136.170416 -215.239092)
		(mid 136.058995 -215.046023)
		(end 135.884666 -214.907114)
		(width 0.0889)
		(layer "In4.Cu")
		(net "UPI_CPU1_CPU0_P1P0_DN<0>")
	)
	(arc
		(start 337.211924 -214.946992)
		(mid 337.010642 -215.144479)
		(end 336.92973 -215.414606)
		(width 0.0889)
		(layer "In4.Cu")
		(net "UPI_CPU1_CPU0_P1P0_DN<0>")
	)
	(arc
		(start 135.884666 -214.907114)
		(mid 135.775519 -214.823186)
		(end 135.700516 -214.707724)
		(width 0.0889)
		(layer "In4.Cu")
		(net "UPI_CPU1_CPU0_P1P0_DN<0>")
	)
	(arc
		(start 336.92973 -215.436704)
		(mid 337.003721 -215.71627)
		(end 337.206336 -215.922606)
		(width 0.0889)
		(layer "In4.Cu")
		(net "UPI_CPU1_CPU0_P1P0_DN<0>")
	)
	(arc
		(start 135.700516 -216.25052)
		(mid 135.748195 -216.06762)
		(end 135.879078 -215.931242)
		(width 0.0889)
		(layer "In4.Cu")
		(net "UPI_CPU1_CPU0_P1P0_DN<0>")
	)
	(arc
		(start 337.399884 -217.878406)
		(mid 337.363024 -218.040203)
		(end 337.25993 -218.170252)
		(width 0.0889)
		(layer "In4.Cu")
		(net "UPI_CPU1_CPU0_P1P0_DN<0>")
	)
	(arc
		(start 336.929984 -213.930484)
		(mid 336.937269 -213.950046)
		(end 336.945224 -213.969346)
		(width 0.0889)
		(layer "In4.Cu")
		(net "UPI_CPU1_CPU0_P1P0_DN<0>")
	)
	(segment
		(start 370.819172 -193.53911)
		(end 376.291348 -188.066934)
		(width 0.13208)
		(layer "F.Cu")
		(net "UPI_CPU1_CPU0_P0P1_DP<9>")
	)
	(segment
		(start 375.88063 -183.66994)
		(end 375.558812 -183.348122)
		(width 0.13208)
		(layer "F.Cu")
		(net "UPI_CPU1_CPU0_P0P1_DP<9>")
	)
	(segment
		(start 376.056652 -183.66994)
		(end 375.88063 -183.66994)
		(width 0.13208)
		(layer "F.Cu")
		(net "UPI_CPU1_CPU0_P0P1_DP<9>")
	)
	(segment
		(start 374.712484 -213.536276)
		(end 374.772428 -213.476332)
		(width 0.0889)
		(layer "F.Cu")
		(net "UPI_CPU1_CPU0_P0P1_DP<9>")
	)
	(segment
		(start 376.337068 -184.126378)
		(end 376.337068 -183.950356)
		(width 0.13208)
		(layer "F.Cu")
		(net "UPI_CPU1_CPU0_P0P1_DP<9>")
	)
	(segment
		(start 374.772428 -212.13064)
		(end 369.543584 -206.901542)
		(width 0.0889)
		(layer "F.Cu")
		(net "UPI_CPU1_CPU0_P0P1_DP<9>")
	)
	(segment
		(start 97.073466 -215.972644)
		(end 97.073466 -215.436958)
		(width 0.13208)
		(layer "F.Cu")
		(net "UPI_CPU1_CPU0_P0P1_DP<9>")
	)
	(segment
		(start 376.337068 -183.950356)
		(end 376.056652 -183.66994)
		(width 0.13208)
		(layer "F.Cu")
		(net "UPI_CPU1_CPU0_P0P1_DP<9>")
	)
	(segment
		(start 368.534188 -205.39075)
		(end 368.534188 -205.261718)
		(width 0.0889)
		(layer "F.Cu")
		(net "UPI_CPU1_CPU0_P0P1_DP<9>")
	)
	(segment
		(start 374.61698 -215.158574)
		(end 374.461786 -214.889588)
		(width 0.0889)
		(layer "F.Cu")
		(net "UPI_CPU1_CPU0_P0P1_DP<9>")
	)
	(segment
		(start 368.568732 -201.02449)
		(end 368.638582 -200.67397)
		(width 0.13208)
		(layer "F.Cu")
		(net "UPI_CPU1_CPU0_P0P1_DP<9>")
	)
	(segment
		(start 376.937778 -186.506612)
		(end 376.937778 -185.075068)
		(width 0.13208)
		(layer "F.Cu")
		(net "UPI_CPU1_CPU0_P0P1_DP<9>")
	)
	(segment
		(start 97.073466 -215.436958)
		(end 97.073212 -215.436704)
		(width 0.13208)
		(layer "F.Cu")
		(net "UPI_CPU1_CPU0_P0P1_DP<9>")
	)
	(segment
		(start 374.772428 -213.476332)
		(end 374.772428 -212.13064)
		(width 0.0889)
		(layer "F.Cu")
		(net "UPI_CPU1_CPU0_P0P1_DP<9>")
	)
	(segment
		(start 374.214898 -182.502556)
		(end 374.278652 -182.39232)
		(width 0.13208)
		(layer "F.Cu")
		(net "UPI_CPU1_CPU0_P0P1_DP<9>")
	)
	(segment
		(start 376.291348 -188.066934)
		(end 376.937778 -186.506612)
		(width 0.13208)
		(layer "F.Cu")
		(net "UPI_CPU1_CPU0_P0P1_DP<9>")
	)
	(segment
		(start 369.543584 -206.901542)
		(end 368.534188 -205.39075)
		(width 0.0889)
		(layer "F.Cu")
		(net "UPI_CPU1_CPU0_P0P1_DP<9>")
	)
	(segment
		(start 374.278652 -182.39232)
		(end 374.831356 -182.242968)
		(width 0.13208)
		(layer "F.Cu")
		(net "UPI_CPU1_CPU0_P0P1_DP<9>")
	)
	(segment
		(start 368.568732 -205.227174)
		(end 368.568732 -205.205076)
		(width 0.0889)
		(layer "F.Cu")
		(net "UPI_CPU1_CPU0_P0P1_DP<9>")
	)
	(segment
		(start 374.388634 -182.863236)
		(end 374.214898 -182.6895)
		(width 0.13208)
		(layer "F.Cu")
		(net "UPI_CPU1_CPU0_P0P1_DP<9>")
	)
	(segment
		(start 368.568732 -205.205076)
		(end 368.568732 -201.02449)
		(width 0.13208)
		(layer "F.Cu")
		(net "UPI_CPU1_CPU0_P0P1_DP<9>")
	)
	(segment
		(start 374.461786 -214.889588)
		(end 374.486932 -214.796878)
		(width 0.0889)
		(layer "F.Cu")
		(net "UPI_CPU1_CPU0_P0P1_DP<9>")
	)
	(segment
		(start 376.937778 -185.075068)
		(end 376.691906 -184.481216)
		(width 0.13208)
		(layer "F.Cu")
		(net "UPI_CPU1_CPU0_P0P1_DP<9>")
	)
	(segment
		(start 369.3541 -197.076568)
		(end 370.819172 -193.53911)
		(width 0.13208)
		(layer "F.Cu")
		(net "UPI_CPU1_CPU0_P0P1_DP<9>")
	)
	(segment
		(start 368.534188 -205.261718)
		(end 368.568732 -205.227174)
		(width 0.0889)
		(layer "F.Cu")
		(net "UPI_CPU1_CPU0_P0P1_DP<9>")
	)
	(segment
		(start 374.712484 -214.344758)
		(end 374.712484 -213.536276)
		(width 0.0889)
		(layer "F.Cu")
		(net "UPI_CPU1_CPU0_P0P1_DP<9>")
	)
	(segment
		(start 375.558812 -183.348122)
		(end 374.388634 -182.863236)
		(width 0.13208)
		(layer "F.Cu")
		(net "UPI_CPU1_CPU0_P0P1_DP<9>")
	)
	(segment
		(start 374.214898 -182.6895)
		(end 374.214898 -182.502556)
		(width 0.13208)
		(layer "F.Cu")
		(net "UPI_CPU1_CPU0_P0P1_DP<9>")
	)
	(segment
		(start 376.691906 -184.481216)
		(end 376.337068 -184.126378)
		(width 0.13208)
		(layer "F.Cu")
		(net "UPI_CPU1_CPU0_P0P1_DP<9>")
	)
	(segment
		(start 368.638582 -200.67397)
		(end 369.3541 -197.076568)
		(width 0.13208)
		(layer "F.Cu")
		(net "UPI_CPU1_CPU0_P0P1_DP<9>")
	)
	(arc
		(start 374.486932 -214.796878)
		(mid 374.495632 -214.790229)
		(end 374.504204 -214.783416)
		(width 0.0889)
		(layer "F.Cu")
		(net "UPI_CPU1_CPU0_P0P1_DP<9>")
	)
	(arc
		(start 374.504204 -214.783416)
		(mid 374.657833 -214.587592)
		(end 374.712484 -214.344758)
		(width 0.0889)
		(layer "F.Cu")
		(net "UPI_CPU1_CPU0_P0P1_DP<9>")
	)
	(segment
		(start 97.40646 -211.793328)
		(end 97.40646 -211.77123)
		(width 0.0889)
		(layer "In6.Cu")
		(net "UPI_CPU1_CPU0_P0P1_DP<9>")
	)
	(segment
		(start 329.315318 -148.22043)
		(end 331.695298 -149.853396)
		(width 0.14732)
		(layer "In6.Cu")
		(net "UPI_CPU1_CPU0_P0P1_DP<9>")
	)
	(segment
		(start 371.579902 -180.185314)
		(end 371.579902 -180.18506)
		(width 0.14732)
		(layer "In6.Cu")
		(net "UPI_CPU1_CPU0_P0P1_DP<9>")
	)
	(segment
		(start 371.579902 -180.18506)
		(end 374.481598 -180.548534)
		(width 0.14732)
		(layer "In6.Cu")
		(net "UPI_CPU1_CPU0_P0P1_DP<9>")
	)
	(segment
		(start 97.448116 -213.8934)
		(end 97.44837 -213.892892)
		(width 0.0889)
		(layer "In6.Cu")
		(net "UPI_CPU1_CPU0_P0P1_DP<9>")
	)
	(segment
		(start 369.459256 -179.919884)
		(end 371.579902 -180.185314)
		(width 0.14732)
		(layer "In6.Cu")
		(net "UPI_CPU1_CPU0_P0P1_DP<9>")
	)
	(segment
		(start 374.686576 -181.701694)
		(end 374.686068 -181.702456)
		(width 0.14732)
		(layer "In6.Cu")
		(net "UPI_CPU1_CPU0_P0P1_DP<9>")
	)
	(segment
		(start 374.481598 -180.548534)
		(end 374.8405 -180.907436)
		(width 0.14732)
		(layer "In6.Cu")
		(net "UPI_CPU1_CPU0_P0P1_DP<9>")
	)
	(segment
		(start 374.8405 -181.435248)
		(end 374.686576 -181.701694)
		(width 0.14732)
		(layer "In6.Cu")
		(net "UPI_CPU1_CPU0_P0P1_DP<9>")
	)
	(segment
		(start 374.686068 -181.702456)
		(end 374.831356 -182.242968)
		(width 0.14732)
		(layer "In6.Cu")
		(net "UPI_CPU1_CPU0_P0P1_DP<9>")
	)
	(segment
		(start 169.708576 -143.60525)
		(end 238.595662 -144.719548)
		(width 0.14732)
		(layer "In6.Cu")
		(net "UPI_CPU1_CPU0_P0P1_DP<9>")
	)
	(segment
		(start 97.40646 -211.303616)
		(end 105.334308 -189.833758)
		(width 0.14732)
		(layer "In6.Cu")
		(net "UPI_CPU1_CPU0_P0P1_DP<9>")
	)
	(segment
		(start 97.073212 -215.436704)
		(end 97.229676 -215.165686)
		(width 0.0889)
		(layer "In6.Cu")
		(net "UPI_CPU1_CPU0_P0P1_DP<9>")
	)
	(segment
		(start 105.334308 -189.833758)
		(end 108.397802 -185.992262)
		(width 0.14732)
		(layer "In6.Cu")
		(net "UPI_CPU1_CPU0_P0P1_DP<9>")
	)
	(segment
		(start 356.87762 -167.131492)
		(end 369.190016 -179.774596)
		(width 0.14732)
		(layer "In6.Cu")
		(net "UPI_CPU1_CPU0_P0P1_DP<9>")
	)
	(segment
		(start 275.988272 -144.046448)
		(end 319.665096 -145.745962)
		(width 0.14732)
		(layer "In6.Cu")
		(net "UPI_CPU1_CPU0_P0P1_DP<9>")
	)
	(segment
		(start 96.977708 -214.636858)
		(end 96.977708 -214.425784)
		(width 0.0889)
		(layer "In6.Cu")
		(net "UPI_CPU1_CPU0_P0P1_DP<9>")
	)
	(segment
		(start 162.540442 -146.08175)
		(end 169.708576 -143.60525)
		(width 0.14732)
		(layer "In6.Cu")
		(net "UPI_CPU1_CPU0_P0P1_DP<9>")
	)
	(segment
		(start 374.8405 -180.907436)
		(end 374.8405 -181.435248)
		(width 0.14732)
		(layer "In6.Cu")
		(net "UPI_CPU1_CPU0_P0P1_DP<9>")
	)
	(segment
		(start 319.665096 -145.745962)
		(end 329.315318 -148.22043)
		(width 0.14732)
		(layer "In6.Cu")
		(net "UPI_CPU1_CPU0_P0P1_DP<9>")
	)
	(segment
		(start 128.63449 -166.943786)
		(end 162.540442 -146.08175)
		(width 0.14732)
		(layer "In6.Cu")
		(net "UPI_CPU1_CPU0_P0P1_DP<9>")
	)
	(segment
		(start 238.595662 -144.719548)
		(end 275.988272 -144.046448)
		(width 0.14732)
		(layer "In6.Cu")
		(net "UPI_CPU1_CPU0_P0P1_DP<9>")
	)
	(segment
		(start 369.190016 -179.774596)
		(end 369.459256 -179.919884)
		(width 0.14732)
		(layer "In6.Cu")
		(net "UPI_CPU1_CPU0_P0P1_DP<9>")
	)
	(segment
		(start 97.44837 -211.835238)
		(end 97.40646 -211.793328)
		(width 0.0889)
		(layer "In6.Cu")
		(net "UPI_CPU1_CPU0_P0P1_DP<9>")
	)
	(segment
		(start 108.397802 -185.992262)
		(end 128.63449 -166.943786)
		(width 0.14732)
		(layer "In6.Cu")
		(net "UPI_CPU1_CPU0_P0P1_DP<9>")
	)
	(segment
		(start 97.40646 -211.77123)
		(end 97.40646 -211.303616)
		(width 0.14732)
		(layer "In6.Cu")
		(net "UPI_CPU1_CPU0_P0P1_DP<9>")
	)
	(segment
		(start 331.695298 -149.853396)
		(end 356.87762 -167.131492)
		(width 0.14732)
		(layer "In6.Cu")
		(net "UPI_CPU1_CPU0_P0P1_DP<9>")
	)
	(segment
		(start 97.44837 -213.892892)
		(end 97.44837 -211.835238)
		(width 0.0889)
		(layer "In6.Cu")
		(net "UPI_CPU1_CPU0_P0P1_DP<9>")
	)
	(segment
		(start 97.229676 -215.165686)
		(end 97.205546 -215.076532)
		(width 0.0889)
		(layer "In6.Cu")
		(net "UPI_CPU1_CPU0_P0P1_DP<9>")
	)
	(arc
		(start 97.188528 -215.063324)
		(mid 97.036097 -214.873342)
		(end 96.977708 -214.636858)
		(width 0.0889)
		(layer "In6.Cu")
		(net "UPI_CPU1_CPU0_P0P1_DP<9>")
	)
	(arc
		(start 97.205546 -215.076532)
		(mid 97.196974 -215.070009)
		(end 97.188528 -215.063324)
		(width 0.0889)
		(layer "In6.Cu")
		(net "UPI_CPU1_CPU0_P0P1_DP<9>")
	)
	(arc
		(start 96.977708 -214.425784)
		(mid 97.089148 -214.232389)
		(end 97.263712 -214.093298)
		(width 0.0889)
		(layer "In6.Cu")
		(net "UPI_CPU1_CPU0_P0P1_DP<9>")
	)
	(arc
		(start 97.263712 -214.093298)
		(mid 97.373108 -214.009201)
		(end 97.448116 -213.8934)
		(width 0.0889)
		(layer "In6.Cu")
		(net "UPI_CPU1_CPU0_P0P1_DP<9>")
	)
	(segment
		(start 375.868946 -212.264498)
		(end 375.769632 -212.165184)
		(width 0.0889)
		(layer "F.Cu")
		(net "UPI_CPU1_CPU0_P0P1_DP<8>")
	)
	(segment
		(start 369.842034 -205.261718)
		(end 369.876578 -205.227174)
		(width 0.0889)
		(layer "F.Cu")
		(net "UPI_CPU1_CPU0_P0P1_DP<8>")
	)
	(segment
		(start 375.652284 -213.879176)
		(end 375.751344 -213.780116)
		(width 0.0889)
		(layer "F.Cu")
		(net "UPI_CPU1_CPU0_P0P1_DP<8>")
	)
	(segment
		(start 375.769886 -212.515958)
		(end 375.868946 -212.416898)
		(width 0.0889)
		(layer "F.Cu")
		(net "UPI_CPU1_CPU0_P0P1_DP<8>")
	)
	(segment
		(start 377.46686 -188.738002)
		(end 378.253498 -186.839352)
		(width 0.13208)
		(layer "F.Cu")
		(net "UPI_CPU1_CPU0_P0P1_DP<8>")
	)
	(segment
		(start 375.652284 -214.319104)
		(end 375.652284 -213.879176)
		(width 0.0889)
		(layer "F.Cu")
		(net "UPI_CPU1_CPU0_P0P1_DP<8>")
	)
	(segment
		(start 369.997482 -200.67397)
		(end 370.66093 -197.33895)
		(width 0.13208)
		(layer "F.Cu")
		(net "UPI_CPU1_CPU0_P0P1_DP<8>")
	)
	(segment
		(start 375.652284 -213.528656)
		(end 375.652284 -213.376256)
		(width 0.0889)
		(layer "F.Cu")
		(net "UPI_CPU1_CPU0_P0P1_DP<8>")
	)
	(segment
		(start 371.929914 -194.274948)
		(end 377.46686 -188.738002)
		(width 0.13208)
		(layer "F.Cu")
		(net "UPI_CPU1_CPU0_P0P1_DP<8>")
	)
	(segment
		(start 370.896134 -179.09794)
		(end 371.046756 -178.534568)
		(width 0.13208)
		(layer "F.Cu")
		(net "UPI_CPU1_CPU0_P0P1_DP<8>")
	)
	(segment
		(start 375.401586 -215.42756)
		(end 375.32056 -215.44915)
		(width 0.0889)
		(layer "F.Cu")
		(net "UPI_CPU1_CPU0_P0P1_DP<8>")
	)
	(segment
		(start 369.876578 -205.205076)
		(end 369.876578 -201.282046)
		(width 0.13208)
		(layer "F.Cu")
		(net "UPI_CPU1_CPU0_P0P1_DP<8>")
	)
	(segment
		(start 378.253498 -184.71007)
		(end 377.951492 -183.980836)
		(width 0.13208)
		(layer "F.Cu")
		(net "UPI_CPU1_CPU0_P0P1_DP<8>")
	)
	(segment
		(start 370.347748 -206.621126)
		(end 369.842034 -205.400656)
		(width 0.0889)
		(layer "F.Cu")
		(net "UPI_CPU1_CPU0_P0P1_DP<8>")
	)
	(segment
		(start 375.18213 -215.158574)
		(end 375.18213 -215.133174)
		(width 0.0889)
		(layer "F.Cu")
		(net "UPI_CPU1_CPU0_P0P1_DP<8>")
	)
	(segment
		(start 375.868946 -212.416898)
		(end 375.868946 -212.264498)
		(width 0.0889)
		(layer "F.Cu")
		(net "UPI_CPU1_CPU0_P0P1_DP<8>")
	)
	(segment
		(start 375.861834 -181.570376)
		(end 374.94591 -180.958744)
		(width 0.13208)
		(layer "F.Cu")
		(net "UPI_CPU1_CPU0_P0P1_DP<8>")
	)
	(segment
		(start 377.951492 -183.980836)
		(end 377.30684 -183.016144)
		(width 0.13208)
		(layer "F.Cu")
		(net "UPI_CPU1_CPU0_P0P1_DP<8>")
	)
	(segment
		(start 371.418866 -179.66182)
		(end 371.033802 -179.336954)
		(width 0.13208)
		(layer "F.Cu")
		(net "UPI_CPU1_CPU0_P0P1_DP<8>")
	)
	(segment
		(start 375.369582 -214.808816)
		(end 375.371868 -214.807546)
		(width 0.0889)
		(layer "F.Cu")
		(net "UPI_CPU1_CPU0_P0P1_DP<8>")
	)
	(segment
		(start 375.368058 -214.809578)
		(end 375.369582 -214.808816)
		(width 0.0889)
		(layer "F.Cu")
		(net "UPI_CPU1_CPU0_P0P1_DP<8>")
	)
	(segment
		(start 375.55678 -215.158574)
		(end 375.401586 -215.42756)
		(width 0.0889)
		(layer "F.Cu")
		(net "UPI_CPU1_CPU0_P0P1_DP<8>")
	)
	(segment
		(start 377.30684 -183.016144)
		(end 375.861834 -181.570376)
		(width 0.13208)
		(layer "F.Cu")
		(net "UPI_CPU1_CPU0_P0P1_DP<8>")
	)
	(segment
		(start 378.253498 -186.839352)
		(end 378.253498 -184.71007)
		(width 0.13208)
		(layer "F.Cu")
		(net "UPI_CPU1_CPU0_P0P1_DP<8>")
	)
	(segment
		(start 370.66093 -197.33895)
		(end 371.929914 -194.274948)
		(width 0.13208)
		(layer "F.Cu")
		(net "UPI_CPU1_CPU0_P0P1_DP<8>")
	)
	(segment
		(start 375.769632 -212.165184)
		(end 375.769632 -212.043264)
		(width 0.0889)
		(layer "F.Cu")
		(net "UPI_CPU1_CPU0_P0P1_DP<8>")
	)
	(segment
		(start 371.033802 -179.336954)
		(end 370.896134 -179.09794)
		(width 0.13208)
		(layer "F.Cu")
		(net "UPI_CPU1_CPU0_P0P1_DP<8>")
	)
	(segment
		(start 96.133666 -214.344758)
		(end 96.133666 -213.732618)
		(width 0.13208)
		(layer "F.Cu")
		(net "UPI_CPU1_CPU0_P0P1_DP<8>")
	)
	(segment
		(start 375.360692 -214.813896)
		(end 375.368058 -214.809578)
		(width 0.0889)
		(layer "F.Cu")
		(net "UPI_CPU1_CPU0_P0P1_DP<8>")
	)
	(segment
		(start 369.842034 -205.400656)
		(end 369.842034 -205.261718)
		(width 0.0889)
		(layer "F.Cu")
		(net "UPI_CPU1_CPU0_P0P1_DP<8>")
	)
	(segment
		(start 375.751344 -213.627716)
		(end 375.652284 -213.528656)
		(width 0.0889)
		(layer "F.Cu")
		(net "UPI_CPU1_CPU0_P0P1_DP<8>")
	)
	(segment
		(start 369.876578 -201.282046)
		(end 369.997482 -200.67397)
		(width 0.13208)
		(layer "F.Cu")
		(net "UPI_CPU1_CPU0_P0P1_DP<8>")
	)
	(segment
		(start 375.751344 -213.780116)
		(end 375.751344 -213.627716)
		(width 0.0889)
		(layer "F.Cu")
		(net "UPI_CPU1_CPU0_P0P1_DP<8>")
	)
	(segment
		(start 369.876578 -205.227174)
		(end 369.876578 -205.205076)
		(width 0.0889)
		(layer "F.Cu")
		(net "UPI_CPU1_CPU0_P0P1_DP<8>")
	)
	(segment
		(start 375.769886 -213.258654)
		(end 375.769886 -212.515958)
		(width 0.0889)
		(layer "F.Cu")
		(net "UPI_CPU1_CPU0_P0P1_DP<8>")
	)
	(segment
		(start 375.769632 -212.043264)
		(end 370.347748 -206.621126)
		(width 0.0889)
		(layer "F.Cu")
		(net "UPI_CPU1_CPU0_P0P1_DP<8>")
	)
	(segment
		(start 374.94591 -180.958744)
		(end 371.418866 -179.66182)
		(width 0.13208)
		(layer "F.Cu")
		(net "UPI_CPU1_CPU0_P0P1_DP<8>")
	)
	(segment
		(start 375.652284 -213.376256)
		(end 375.769886 -213.258654)
		(width 0.0889)
		(layer "F.Cu")
		(net "UPI_CPU1_CPU0_P0P1_DP<8>")
	)
	(arc
		(start 375.371868 -214.807546)
		(mid 375.577177 -214.600704)
		(end 375.652284 -214.319104)
		(width 0.0889)
		(layer "F.Cu")
		(net "UPI_CPU1_CPU0_P0P1_DP<8>")
	)
	(arc
		(start 375.32056 -215.44915)
		(mid 375.218539 -215.319488)
		(end 375.18213 -215.158574)
		(width 0.0889)
		(layer "F.Cu")
		(net "UPI_CPU1_CPU0_P0P1_DP<8>")
	)
	(arc
		(start 375.18213 -215.133174)
		(mid 375.229809 -214.950274)
		(end 375.360692 -214.813896)
		(width 0.0889)
		(layer "F.Cu")
		(net "UPI_CPU1_CPU0_P0P1_DP<8>")
	)
	(segment
		(start 96.508316 -213.033864)
		(end 96.409002 -213.133178)
		(width 0.0889)
		(layer "In6.Cu")
		(net "UPI_CPU1_CPU0_P0P1_DP<8>")
	)
	(segment
		(start 106.99877 -186.1566)
		(end 104.600248 -189.16396)
		(width 0.14732)
		(layer "In6.Cu")
		(net "UPI_CPU1_CPU0_P0P1_DP<8>")
	)
	(segment
		(start 169.519092 -142.766542)
		(end 162.26028 -145.273014)
		(width 0.14732)
		(layer "In6.Cu")
		(net "UPI_CPU1_CPU0_P0P1_DP<8>")
	)
	(segment
		(start 370.506244 -178.389788)
		(end 370.505736 -178.389026)
		(width 0.14732)
		(layer "In6.Cu")
		(net "UPI_CPU1_CPU0_P0P1_DP<8>")
	)
	(segment
		(start 96.409002 -213.399878)
		(end 96.508316 -213.499192)
		(width 0.0889)
		(layer "In6.Cu")
		(net "UPI_CPU1_CPU0_P0P1_DP<8>")
	)
	(segment
		(start 357.938832 -166.850568)
		(end 329.641454 -147.435062)
		(width 0.14732)
		(layer "In6.Cu")
		(net "UPI_CPU1_CPU0_P0P1_DP<8>")
	)
	(segment
		(start 371.046756 -178.534568)
		(end 370.506244 -178.389788)
		(width 0.14732)
		(layer "In6.Cu")
		(net "UPI_CPU1_CPU0_P0P1_DP<8>")
	)
	(segment
		(start 96.376998 -214.05977)
		(end 96.292416 -214.033608)
		(width 0.0889)
		(layer "In6.Cu")
		(net "UPI_CPU1_CPU0_P0P1_DP<8>")
	)
	(segment
		(start 329.641454 -147.435062)
		(end 319.795906 -144.90954)
		(width 0.14732)
		(layer "In6.Cu")
		(net "UPI_CPU1_CPU0_P0P1_DP<8>")
	)
	(segment
		(start 238.593122 -143.883634)
		(end 169.519092 -142.766542)
		(width 0.14732)
		(layer "In6.Cu")
		(net "UPI_CPU1_CPU0_P0P1_DP<8>")
	)
	(segment
		(start 96.409002 -212.40115)
		(end 96.409002 -212.66785)
		(width 0.0889)
		(layer "In6.Cu")
		(net "UPI_CPU1_CPU0_P0P1_DP<8>")
	)
	(segment
		(start 96.409002 -212.66785)
		(end 96.508316 -212.767164)
		(width 0.0889)
		(layer "In6.Cu")
		(net "UPI_CPU1_CPU0_P0P1_DP<8>")
	)
	(segment
		(start 96.466406 -211.191602)
		(end 96.466406 -211.77123)
		(width 0.14732)
		(layer "In6.Cu")
		(net "UPI_CPU1_CPU0_P0P1_DP<8>")
	)
	(segment
		(start 96.508316 -213.499192)
		(end 96.508316 -213.8934)
		(width 0.0889)
		(layer "In6.Cu")
		(net "UPI_CPU1_CPU0_P0P1_DP<8>")
	)
	(segment
		(start 96.508316 -211.835238)
		(end 96.508316 -212.301836)
		(width 0.0889)
		(layer "In6.Cu")
		(net "UPI_CPU1_CPU0_P0P1_DP<8>")
	)
	(segment
		(start 96.508316 -212.767164)
		(end 96.508316 -213.033864)
		(width 0.0889)
		(layer "In6.Cu")
		(net "UPI_CPU1_CPU0_P0P1_DP<8>")
	)
	(segment
		(start 96.508316 -212.301836)
		(end 96.409002 -212.40115)
		(width 0.0889)
		(layer "In6.Cu")
		(net "UPI_CPU1_CPU0_P0P1_DP<8>")
	)
	(segment
		(start 96.409002 -213.133178)
		(end 96.409002 -213.399878)
		(width 0.0889)
		(layer "In6.Cu")
		(net "UPI_CPU1_CPU0_P0P1_DP<8>")
	)
	(segment
		(start 96.292416 -214.033608)
		(end 96.133666 -213.732618)
		(width 0.0889)
		(layer "In6.Cu")
		(net "UPI_CPU1_CPU0_P0P1_DP<8>")
	)
	(segment
		(start 96.466406 -211.77123)
		(end 96.466406 -211.793328)
		(width 0.0889)
		(layer "In6.Cu")
		(net "UPI_CPU1_CPU0_P0P1_DP<8>")
	)
	(segment
		(start 370.505736 -178.389026)
		(end 370.35486 -178.127914)
		(width 0.14732)
		(layer "In6.Cu")
		(net "UPI_CPU1_CPU0_P0P1_DP<8>")
	)
	(segment
		(start 162.26028 -145.273014)
		(end 128.108456 -166.286942)
		(width 0.14732)
		(layer "In6.Cu")
		(net "UPI_CPU1_CPU0_P0P1_DP<8>")
	)
	(segment
		(start 368.658394 -177.420524)
		(end 357.938832 -166.850568)
		(width 0.14732)
		(layer "In6.Cu")
		(net "UPI_CPU1_CPU0_P0P1_DP<8>")
	)
	(segment
		(start 319.795906 -144.90954)
		(end 276.089364 -143.209264)
		(width 0.14732)
		(layer "In6.Cu")
		(net "UPI_CPU1_CPU0_P0P1_DP<8>")
	)
	(segment
		(start 370.35486 -178.127914)
		(end 368.658394 -177.420524)
		(width 0.14732)
		(layer "In6.Cu")
		(net "UPI_CPU1_CPU0_P0P1_DP<8>")
	)
	(segment
		(start 104.600248 -189.16396)
		(end 96.466406 -211.191602)
		(width 0.14732)
		(layer "In6.Cu")
		(net "UPI_CPU1_CPU0_P0P1_DP<8>")
	)
	(segment
		(start 276.089364 -143.209264)
		(end 238.593122 -143.883634)
		(width 0.14732)
		(layer "In6.Cu")
		(net "UPI_CPU1_CPU0_P0P1_DP<8>")
	)
	(segment
		(start 128.108456 -166.286942)
		(end 106.99877 -186.1566)
		(width 0.14732)
		(layer "In6.Cu")
		(net "UPI_CPU1_CPU0_P0P1_DP<8>")
	)
	(segment
		(start 96.466406 -211.793328)
		(end 96.508316 -211.835238)
		(width 0.0889)
		(layer "In6.Cu")
		(net "UPI_CPU1_CPU0_P0P1_DP<8>")
	)
	(arc
		(start 96.508316 -213.8934)
		(mid 96.453646 -213.985256)
		(end 96.376998 -214.05977)
		(width 0.0889)
		(layer "In6.Cu")
		(net "UPI_CPU1_CPU0_P0P1_DP<8>")
	)
	(segment
		(start 378.591572 -189.45987)
		(end 379.576838 -187.081414)
		(width 0.13208)
		(layer "F.Cu")
		(net "UPI_CPU1_CPU0_P0P1_DP<7>")
	)
	(segment
		(start 95.193866 -215.972644)
		(end 95.193866 -215.436958)
		(width 0.13208)
		(layer "F.Cu")
		(net "UPI_CPU1_CPU0_P0P1_DP<7>")
	)
	(segment
		(start 371.184678 -205.205076)
		(end 371.184678 -201.494898)
		(width 0.13208)
		(layer "F.Cu")
		(net "UPI_CPU1_CPU0_P0P1_DP<7>")
	)
	(segment
		(start 374.071388 -179.069238)
		(end 374.276366 -178.712876)
		(width 0.13208)
		(layer "F.Cu")
		(net "UPI_CPU1_CPU0_P0P1_DP<7>")
	)
	(segment
		(start 376.842274 -180.636418)
		(end 375.597674 -179.804822)
		(width 0.13208)
		(layer "F.Cu")
		(net "UPI_CPU1_CPU0_P0P1_DP<7>")
	)
	(segment
		(start 378.79401 -182.588408)
		(end 376.842274 -180.636418)
		(width 0.13208)
		(layer "F.Cu")
		(net "UPI_CPU1_CPU0_P0P1_DP<7>")
	)
	(segment
		(start 376.592084 -214.344758)
		(end 376.592084 -213.401148)
		(width 0.0889)
		(layer "F.Cu")
		(net "UPI_CPU1_CPU0_P0P1_DP<7>")
	)
	(segment
		(start 374.278652 -178.70932)
		(end 374.831356 -178.559968)
		(width 0.13208)
		(layer "F.Cu")
		(net "UPI_CPU1_CPU0_P0P1_DP<7>")
	)
	(segment
		(start 95.193866 -215.436958)
		(end 95.193612 -215.436704)
		(width 0.13208)
		(layer "F.Cu")
		(net "UPI_CPU1_CPU0_P0P1_DP<7>")
	)
	(segment
		(start 374.278144 -178.710082)
		(end 374.278652 -178.70932)
		(width 0.13208)
		(layer "F.Cu")
		(net "UPI_CPU1_CPU0_P0P1_DP<7>")
	)
	(segment
		(start 371.184678 -205.227174)
		(end 371.184678 -205.205076)
		(width 0.0889)
		(layer "F.Cu")
		(net "UPI_CPU1_CPU0_P0P1_DP<7>")
	)
	(segment
		(start 375.597674 -179.804822)
		(end 374.15978 -179.262786)
		(width 0.13208)
		(layer "F.Cu")
		(net "UPI_CPU1_CPU0_P0P1_DP<7>")
	)
	(segment
		(start 374.276366 -178.712876)
		(end 374.278144 -178.710082)
		(width 0.13208)
		(layer "F.Cu")
		(net "UPI_CPU1_CPU0_P0P1_DP<7>")
	)
	(segment
		(start 373.157496 -194.893946)
		(end 378.591572 -189.45987)
		(width 0.13208)
		(layer "F.Cu")
		(net "UPI_CPU1_CPU0_P0P1_DP<7>")
	)
	(segment
		(start 371.348 -200.67397)
		(end 371.888004 -197.958964)
		(width 0.13208)
		(layer "F.Cu")
		(net "UPI_CPU1_CPU0_P0P1_DP<7>")
	)
	(segment
		(start 378.794264 -182.588916)
		(end 378.79401 -182.588408)
		(width 0.13208)
		(layer "F.Cu")
		(net "UPI_CPU1_CPU0_P0P1_DP<7>")
	)
	(segment
		(start 379.576838 -184.478168)
		(end 378.794264 -182.588916)
		(width 0.13208)
		(layer "F.Cu")
		(net "UPI_CPU1_CPU0_P0P1_DP<7>")
	)
	(segment
		(start 371.888004 -197.958964)
		(end 373.157496 -194.893946)
		(width 0.13208)
		(layer "F.Cu")
		(net "UPI_CPU1_CPU0_P0P1_DP<7>")
	)
	(segment
		(start 371.714268 -206.891128)
		(end 371.150134 -205.52918)
		(width 0.0889)
		(layer "F.Cu")
		(net "UPI_CPU1_CPU0_P0P1_DP<7>")
	)
	(segment
		(start 371.184678 -201.494898)
		(end 371.348 -200.67397)
		(width 0.13208)
		(layer "F.Cu")
		(net "UPI_CPU1_CPU0_P0P1_DP<7>")
	)
	(segment
		(start 371.150134 -205.52918)
		(end 371.150134 -205.261718)
		(width 0.0889)
		(layer "F.Cu")
		(net "UPI_CPU1_CPU0_P0P1_DP<7>")
	)
	(segment
		(start 376.592084 -213.401148)
		(end 376.782584 -213.210648)
		(width 0.0889)
		(layer "F.Cu")
		(net "UPI_CPU1_CPU0_P0P1_DP<7>")
	)
	(segment
		(start 374.15978 -179.262786)
		(end 374.086374 -179.172108)
		(width 0.13208)
		(layer "F.Cu")
		(net "UPI_CPU1_CPU0_P0P1_DP<7>")
	)
	(segment
		(start 371.150134 -205.261718)
		(end 371.184678 -205.227174)
		(width 0.0889)
		(layer "F.Cu")
		(net "UPI_CPU1_CPU0_P0P1_DP<7>")
	)
	(segment
		(start 374.086374 -179.172108)
		(end 374.071388 -179.069238)
		(width 0.13208)
		(layer "F.Cu")
		(net "UPI_CPU1_CPU0_P0P1_DP<7>")
	)
	(segment
		(start 379.576838 -187.081414)
		(end 379.576838 -184.478168)
		(width 0.13208)
		(layer "F.Cu")
		(net "UPI_CPU1_CPU0_P0P1_DP<7>")
	)
	(segment
		(start 376.782584 -213.210648)
		(end 376.782584 -211.959444)
		(width 0.0889)
		(layer "F.Cu")
		(net "UPI_CPU1_CPU0_P0P1_DP<7>")
	)
	(segment
		(start 376.49658 -215.158574)
		(end 376.341386 -214.889588)
		(width 0.0889)
		(layer "F.Cu")
		(net "UPI_CPU1_CPU0_P0P1_DP<7>")
	)
	(segment
		(start 376.341386 -214.889588)
		(end 376.366532 -214.796878)
		(width 0.0889)
		(layer "F.Cu")
		(net "UPI_CPU1_CPU0_P0P1_DP<7>")
	)
	(segment
		(start 376.782584 -211.959444)
		(end 371.714268 -206.891128)
		(width 0.0889)
		(layer "F.Cu")
		(net "UPI_CPU1_CPU0_P0P1_DP<7>")
	)
	(arc
		(start 376.366532 -214.796878)
		(mid 376.375232 -214.790229)
		(end 376.383804 -214.783416)
		(width 0.0889)
		(layer "F.Cu")
		(net "UPI_CPU1_CPU0_P0P1_DP<7>")
	)
	(arc
		(start 376.383804 -214.783416)
		(mid 376.537433 -214.587592)
		(end 376.592084 -214.344758)
		(width 0.0889)
		(layer "F.Cu")
		(net "UPI_CPU1_CPU0_P0P1_DP<7>")
	)
	(segment
		(start 95.350076 -215.165686)
		(end 95.325946 -215.076532)
		(width 0.0889)
		(layer "In6.Cu")
		(net "UPI_CPU1_CPU0_P0P1_DP<7>")
	)
	(segment
		(start 106.516678 -185.2168)
		(end 126.854966 -166.073582)
		(width 0.14732)
		(layer "In6.Cu")
		(net "UPI_CPU1_CPU0_P0P1_DP<7>")
	)
	(segment
		(start 374.590056 -176.920652)
		(end 374.8659 -177.196496)
		(width 0.14732)
		(layer "In6.Cu")
		(net "UPI_CPU1_CPU0_P0P1_DP<7>")
	)
	(segment
		(start 126.854966 -166.073582)
		(end 162.005772 -144.445482)
		(width 0.14732)
		(layer "In6.Cu")
		(net "UPI_CPU1_CPU0_P0P1_DP<7>")
	)
	(segment
		(start 169.313352 -141.921484)
		(end 238.590836 -143.041624)
		(width 0.14732)
		(layer "In6.Cu")
		(net "UPI_CPU1_CPU0_P0P1_DP<7>")
	)
	(segment
		(start 103.944166 -188.442346)
		(end 106.516678 -185.2168)
		(width 0.14732)
		(layer "In6.Cu")
		(net "UPI_CPU1_CPU0_P0P1_DP<7>")
	)
	(segment
		(start 369.14201 -176.722532)
		(end 369.488466 -176.86782)
		(width 0.14732)
		(layer "In6.Cu")
		(net "UPI_CPU1_CPU0_P0P1_DP<7>")
	)
	(segment
		(start 95.52686 -211.77123)
		(end 95.52686 -211.240116)
		(width 0.14732)
		(layer "In6.Cu")
		(net "UPI_CPU1_CPU0_P0P1_DP<7>")
	)
	(segment
		(start 330.553314 -146.804888)
		(end 331.343 -147.346416)
		(width 0.14732)
		(layer "In6.Cu")
		(net "UPI_CPU1_CPU0_P0P1_DP<7>")
	)
	(segment
		(start 374.243346 -176.780952)
		(end 374.590056 -176.920652)
		(width 0.14732)
		(layer "In6.Cu")
		(net "UPI_CPU1_CPU0_P0P1_DP<7>")
	)
	(segment
		(start 95.568516 -213.8934)
		(end 95.56877 -213.892892)
		(width 0.0889)
		(layer "In6.Cu")
		(net "UPI_CPU1_CPU0_P0P1_DP<7>")
	)
	(segment
		(start 95.56877 -211.835238)
		(end 95.52686 -211.793328)
		(width 0.0889)
		(layer "In6.Cu")
		(net "UPI_CPU1_CPU0_P0P1_DP<7>")
	)
	(segment
		(start 369.488466 -176.86782)
		(end 374.243346 -176.780952)
		(width 0.14732)
		(layer "In6.Cu")
		(net "UPI_CPU1_CPU0_P0P1_DP<7>")
	)
	(segment
		(start 95.52686 -211.793328)
		(end 95.52686 -211.77123)
		(width 0.0889)
		(layer "In6.Cu")
		(net "UPI_CPU1_CPU0_P0P1_DP<7>")
	)
	(segment
		(start 374.686068 -178.019456)
		(end 374.831356 -178.559968)
		(width 0.14732)
		(layer "In6.Cu")
		(net "UPI_CPU1_CPU0_P0P1_DP<7>")
	)
	(segment
		(start 95.56877 -213.892892)
		(end 95.56877 -211.835238)
		(width 0.0889)
		(layer "In6.Cu")
		(net "UPI_CPU1_CPU0_P0P1_DP<7>")
	)
	(segment
		(start 331.343 -147.346416)
		(end 358.076754 -165.68928)
		(width 0.14732)
		(layer "In6.Cu")
		(net "UPI_CPU1_CPU0_P0P1_DP<7>")
	)
	(segment
		(start 95.098108 -214.636858)
		(end 95.098108 -214.425784)
		(width 0.0889)
		(layer "In6.Cu")
		(net "UPI_CPU1_CPU0_P0P1_DP<7>")
	)
	(segment
		(start 238.590836 -143.041624)
		(end 276.432772 -142.361158)
		(width 0.14732)
		(layer "In6.Cu")
		(net "UPI_CPU1_CPU0_P0P1_DP<7>")
	)
	(segment
		(start 95.193612 -215.436704)
		(end 95.350076 -215.165686)
		(width 0.0889)
		(layer "In6.Cu")
		(net "UPI_CPU1_CPU0_P0P1_DP<7>")
	)
	(segment
		(start 374.8659 -177.196496)
		(end 374.8659 -177.708306)
		(width 0.14732)
		(layer "In6.Cu")
		(net "UPI_CPU1_CPU0_P0P1_DP<7>")
	)
	(segment
		(start 162.005772 -144.445482)
		(end 169.313352 -141.921484)
		(width 0.14732)
		(layer "In6.Cu")
		(net "UPI_CPU1_CPU0_P0P1_DP<7>")
	)
	(segment
		(start 374.686576 -178.018694)
		(end 374.686068 -178.019456)
		(width 0.14732)
		(layer "In6.Cu")
		(net "UPI_CPU1_CPU0_P0P1_DP<7>")
	)
	(segment
		(start 358.076754 -165.68928)
		(end 369.14201 -176.722532)
		(width 0.14732)
		(layer "In6.Cu")
		(net "UPI_CPU1_CPU0_P0P1_DP<7>")
	)
	(segment
		(start 95.52686 -211.240116)
		(end 103.944166 -188.442346)
		(width 0.14732)
		(layer "In6.Cu")
		(net "UPI_CPU1_CPU0_P0P1_DP<7>")
	)
	(segment
		(start 276.432772 -142.361158)
		(end 319.806066 -144.048734)
		(width 0.14732)
		(layer "In6.Cu")
		(net "UPI_CPU1_CPU0_P0P1_DP<7>")
	)
	(segment
		(start 319.806066 -144.048734)
		(end 330.553314 -146.804888)
		(width 0.14732)
		(layer "In6.Cu")
		(net "UPI_CPU1_CPU0_P0P1_DP<7>")
	)
	(segment
		(start 374.8659 -177.708306)
		(end 374.686576 -178.018694)
		(width 0.14732)
		(layer "In6.Cu")
		(net "UPI_CPU1_CPU0_P0P1_DP<7>")
	)
	(arc
		(start 95.308928 -215.063324)
		(mid 95.156497 -214.873342)
		(end 95.098108 -214.636858)
		(width 0.0889)
		(layer "In6.Cu")
		(net "UPI_CPU1_CPU0_P0P1_DP<7>")
	)
	(arc
		(start 95.098108 -214.425784)
		(mid 95.209548 -214.232389)
		(end 95.384112 -214.093298)
		(width 0.0889)
		(layer "In6.Cu")
		(net "UPI_CPU1_CPU0_P0P1_DP<7>")
	)
	(arc
		(start 95.325946 -215.076532)
		(mid 95.317374 -215.070009)
		(end 95.308928 -215.063324)
		(width 0.0889)
		(layer "In6.Cu")
		(net "UPI_CPU1_CPU0_P0P1_DP<7>")
	)
	(arc
		(start 95.384112 -214.093298)
		(mid 95.493508 -214.009201)
		(end 95.568516 -213.8934)
		(width 0.0889)
		(layer "In6.Cu")
		(net "UPI_CPU1_CPU0_P0P1_DP<7>")
	)
	(segment
		(start 374.118886 -195.412868)
		(end 379.50267 -190.029084)
		(width 0.13208)
		(layer "F.Cu")
		(net "UPI_CPU1_CPU0_P0P1_DP<6>")
	)
	(segment
		(start 380.917958 -184.970166)
		(end 379.68174 -181.985666)
		(width 0.13208)
		(layer "F.Cu")
		(net "UPI_CPU1_CPU0_P0P1_DP<6>")
	)
	(segment
		(start 376.021092 -178.325018)
		(end 375.807224 -178.11115)
		(width 0.13208)
		(layer "F.Cu")
		(net "UPI_CPU1_CPU0_P0P1_DP<6>")
	)
	(segment
		(start 377.588526 -212.542628)
		(end 377.588526 -211.934298)
		(width 0.0889)
		(layer "F.Cu")
		(net "UPI_CPU1_CPU0_P0P1_DP<6>")
	)
	(segment
		(start 377.153424 -214.64397)
		(end 377.153678 -214.643716)
		(width 0.0889)
		(layer "F.Cu")
		(net "UPI_CPU1_CPU0_P0P1_DP<6>")
	)
	(segment
		(start 372.858538 -207.204564)
		(end 372.267988 -205.778862)
		(width 0.0889)
		(layer "F.Cu")
		(net "UPI_CPU1_CPU0_P0P1_DP<6>")
	)
	(segment
		(start 372.233698 -205.227174)
		(end 372.233698 -205.205076)
		(width 0.0889)
		(layer "F.Cu")
		(net "UPI_CPU1_CPU0_P0P1_DP<6>")
	)
	(segment
		(start 377.588272 -212.542882)
		(end 377.588526 -212.542628)
		(width 0.0889)
		(layer "F.Cu")
		(net "UPI_CPU1_CPU0_P0P1_DP<6>")
	)
	(segment
		(start 372.267988 -205.261464)
		(end 372.233698 -205.227174)
		(width 0.0889)
		(layer "F.Cu")
		(net "UPI_CPU1_CPU0_P0P1_DP<6>")
	)
	(segment
		(start 374.75287 -177.4063)
		(end 371.31752 -176.722278)
		(width 0.13208)
		(layer "F.Cu")
		(net "UPI_CPU1_CPU0_P0P1_DP<6>")
	)
	(segment
		(start 377.152916 -214.644224)
		(end 377.153424 -214.64397)
		(width 0.0889)
		(layer "F.Cu")
		(net "UPI_CPU1_CPU0_P0P1_DP<6>")
	)
	(segment
		(start 372.857776 -198.457566)
		(end 374.118886 -195.412868)
		(width 0.13208)
		(layer "F.Cu")
		(net "UPI_CPU1_CPU0_P0P1_DP<6>")
	)
	(segment
		(start 370.834666 -176.409858)
		(end 370.683536 -176.183036)
		(width 0.13208)
		(layer "F.Cu")
		(net "UPI_CPU1_CPU0_P0P1_DP<6>")
	)
	(segment
		(start 376.966734 -215.972644)
		(end 376.97156 -215.964262)
		(width 0.0889)
		(layer "F.Cu")
		(net "UPI_CPU1_CPU0_P0P1_DP<6>")
	)
	(segment
		(start 370.6749 -176.16932)
		(end 370.122704 -176.019968)
		(width 0.13208)
		(layer "F.Cu")
		(net "UPI_CPU1_CPU0_P0P1_DP<6>")
	)
	(segment
		(start 94.723712 -214.622888)
		(end 94.723458 -214.622634)
		(width 0.13208)
		(layer "F.Cu")
		(net "UPI_CPU1_CPU0_P0P1_DP<6>")
	)
	(segment
		(start 377.341638 -214.31885)
		(end 377.341384 -214.318596)
		(width 0.0889)
		(layer "F.Cu")
		(net "UPI_CPU1_CPU0_P0P1_DP<6>")
	)
	(segment
		(start 377.142248 -214.65032)
		(end 377.152916 -214.644224)
		(width 0.0889)
		(layer "F.Cu")
		(net "UPI_CPU1_CPU0_P0P1_DP<6>")
	)
	(segment
		(start 370.682774 -176.18329)
		(end 370.6749 -176.16932)
		(width 0.13208)
		(layer "F.Cu")
		(net "UPI_CPU1_CPU0_P0P1_DP<6>")
	)
	(segment
		(start 371.31752 -176.722278)
		(end 370.834666 -176.409858)
		(width 0.13208)
		(layer "F.Cu")
		(net "UPI_CPU1_CPU0_P0P1_DP<6>")
	)
	(segment
		(start 376.301508 -178.781456)
		(end 376.021092 -178.50104)
		(width 0.13208)
		(layer "F.Cu")
		(net "UPI_CPU1_CPU0_P0P1_DP<6>")
	)
	(segment
		(start 377.588272 -213.050374)
		(end 377.588272 -212.542882)
		(width 0.0889)
		(layer "F.Cu")
		(net "UPI_CPU1_CPU0_P0P1_DP<6>")
	)
	(segment
		(start 370.683536 -176.183036)
		(end 370.682774 -176.18329)
		(width 0.13208)
		(layer "F.Cu")
		(net "UPI_CPU1_CPU0_P0P1_DP<6>")
	)
	(segment
		(start 377.341384 -214.319104)
		(end 377.341638 -214.31885)
		(width 0.0889)
		(layer "F.Cu")
		(net "UPI_CPU1_CPU0_P0P1_DP<6>")
	)
	(segment
		(start 377.079764 -215.597232)
		(end 377.080018 -215.597232)
		(width 0.0889)
		(layer "F.Cu")
		(net "UPI_CPU1_CPU0_P0P1_DP<6>")
	)
	(segment
		(start 376.47753 -178.781456)
		(end 376.301508 -178.781456)
		(width 0.13208)
		(layer "F.Cu")
		(net "UPI_CPU1_CPU0_P0P1_DP<6>")
	)
	(segment
		(start 377.153678 -214.643716)
		(end 377.153932 -214.643716)
		(width 0.0889)
		(layer "F.Cu")
		(net "UPI_CPU1_CPU0_P0P1_DP<6>")
	)
	(segment
		(start 380.917958 -186.61253)
		(end 380.917958 -184.970166)
		(width 0.13208)
		(layer "F.Cu")
		(net "UPI_CPU1_CPU0_P0P1_DP<6>")
	)
	(segment
		(start 377.121928 -215.703658)
		(end 377.096782 -215.610694)
		(width 0.0889)
		(layer "F.Cu")
		(net "UPI_CPU1_CPU0_P0P1_DP<6>")
	)
	(segment
		(start 94.723712 -215.158574)
		(end 94.723712 -214.622888)
		(width 0.13208)
		(layer "F.Cu")
		(net "UPI_CPU1_CPU0_P0P1_DP<6>")
	)
	(segment
		(start 375.807224 -178.11115)
		(end 374.75287 -177.4063)
		(width 0.13208)
		(layer "F.Cu")
		(net "UPI_CPU1_CPU0_P0P1_DP<6>")
	)
	(segment
		(start 372.233698 -201.594466)
		(end 372.857776 -198.457566)
		(width 0.13208)
		(layer "F.Cu")
		(net "UPI_CPU1_CPU0_P0P1_DP<6>")
	)
	(segment
		(start 372.233698 -205.205076)
		(end 372.233698 -201.594466)
		(width 0.13208)
		(layer "F.Cu")
		(net "UPI_CPU1_CPU0_P0P1_DP<6>")
	)
	(segment
		(start 376.021092 -178.50104)
		(end 376.021092 -178.325018)
		(width 0.13208)
		(layer "F.Cu")
		(net "UPI_CPU1_CPU0_P0P1_DP<6>")
	)
	(segment
		(start 377.341384 -214.318596)
		(end 377.341384 -213.297262)
		(width 0.0889)
		(layer "F.Cu")
		(net "UPI_CPU1_CPU0_P0P1_DP<6>")
	)
	(segment
		(start 372.267988 -205.778862)
		(end 372.267988 -205.261464)
		(width 0.0889)
		(layer "F.Cu")
		(net "UPI_CPU1_CPU0_P0P1_DP<6>")
	)
	(segment
		(start 376.87123 -215.158828)
		(end 376.87123 -215.133428)
		(width 0.0889)
		(layer "F.Cu")
		(net "UPI_CPU1_CPU0_P0P1_DP<6>")
	)
	(segment
		(start 377.588526 -211.934298)
		(end 372.858538 -207.204564)
		(width 0.0889)
		(layer "F.Cu")
		(net "UPI_CPU1_CPU0_P0P1_DP<6>")
	)
	(segment
		(start 377.153932 -214.643716)
		(end 377.160282 -214.639906)
		(width 0.0889)
		(layer "F.Cu")
		(net "UPI_CPU1_CPU0_P0P1_DP<6>")
	)
	(segment
		(start 379.50267 -190.029084)
		(end 380.917958 -186.61253)
		(width 0.13208)
		(layer "F.Cu")
		(net "UPI_CPU1_CPU0_P0P1_DP<6>")
	)
	(segment
		(start 379.68174 -181.985666)
		(end 376.47753 -178.781456)
		(width 0.13208)
		(layer "F.Cu")
		(net "UPI_CPU1_CPU0_P0P1_DP<6>")
	)
	(segment
		(start 377.341384 -213.297262)
		(end 377.588272 -213.050374)
		(width 0.0889)
		(layer "F.Cu")
		(net "UPI_CPU1_CPU0_P0P1_DP<6>")
	)
	(segment
		(start 376.97156 -215.964262)
		(end 377.121928 -215.703658)
		(width 0.0889)
		(layer "F.Cu")
		(net "UPI_CPU1_CPU0_P0P1_DP<6>")
	)
	(arc
		(start 376.87123 -215.133428)
		(mid 376.943479 -214.85637)
		(end 377.142248 -214.65032)
		(width 0.0889)
		(layer "F.Cu")
		(net "UPI_CPU1_CPU0_P0P1_DP<6>")
	)
	(arc
		(start 377.160282 -214.639906)
		(mid 377.292994 -214.503303)
		(end 377.341384 -214.319104)
		(width 0.0889)
		(layer "F.Cu")
		(net "UPI_CPU1_CPU0_P0P1_DP<6>")
	)
	(arc
		(start 377.096782 -215.610694)
		(mid 377.088208 -215.604045)
		(end 377.079764 -215.597232)
		(width 0.0889)
		(layer "F.Cu")
		(net "UPI_CPU1_CPU0_P0P1_DP<6>")
	)
	(arc
		(start 377.080018 -215.597232)
		(mid 376.926131 -215.401598)
		(end 376.87123 -215.158828)
		(width 0.0889)
		(layer "F.Cu")
		(net "UPI_CPU1_CPU0_P0P1_DP<6>")
	)
	(segment
		(start 365.439452 -171.895262)
		(end 365.234728 -171.898564)
		(width 0.14732)
		(layer "In6.Cu")
		(net "UPI_CPU1_CPU0_P0P1_DP<6>")
	)
	(segment
		(start 238.590328 -142.376144)
		(end 169.377868 -141.25702)
		(width 0.14732)
		(layer "In6.Cu")
		(net "UPI_CPU1_CPU0_P0P1_DP<6>")
	)
	(segment
		(start 366.607852 -173.230032)
		(end 366.604804 -173.025308)
		(width 0.14732)
		(layer "In6.Cu")
		(net "UPI_CPU1_CPU0_P0P1_DP<6>")
	)
	(segment
		(start 94.861126 -211.38896)
		(end 94.861126 -212.101938)
		(width 0.14732)
		(layer "In6.Cu")
		(net "UPI_CPU1_CPU0_P0P1_DP<6>")
	)
	(segment
		(start 94.594934 -214.22487)
		(end 94.564708 -214.321644)
		(width 0.0889)
		(layer "In6.Cu")
		(net "UPI_CPU1_CPU0_P0P1_DP<6>")
	)
	(segment
		(start 370.163598 -175.297592)
		(end 369.89004 -175.128428)
		(width 0.14732)
		(layer "In6.Cu")
		(net "UPI_CPU1_CPU0_P0P1_DP<6>")
	)
	(segment
		(start 104.891078 -186.350656)
		(end 104.661208 -186.638946)
		(width 0.14732)
		(layer "In6.Cu")
		(net "UPI_CPU1_CPU0_P0P1_DP<6>")
	)
	(segment
		(start 169.377868 -141.25702)
		(end 161.906204 -143.836644)
		(width 0.14732)
		(layer "In6.Cu")
		(net "UPI_CPU1_CPU0_P0P1_DP<6>")
	)
	(segment
		(start 364.97006 -171.64177)
		(end 364.967012 -171.437046)
		(width 0.14732)
		(layer "In6.Cu")
		(net "UPI_CPU1_CPU0_P0P1_DP<6>")
	)
	(segment
		(start 366.87252 -173.486572)
		(end 366.607852 -173.230032)
		(width 0.14732)
		(layer "In6.Cu")
		(net "UPI_CPU1_CPU0_P0P1_DP<6>")
	)
	(segment
		(start 367.819432 -174.203106)
		(end 367.614708 -174.206408)
		(width 0.14732)
		(layer "In6.Cu")
		(net "UPI_CPU1_CPU0_P0P1_DP<6>")
	)
	(segment
		(start 104.228138 -186.949588)
		(end 104.251252 -187.153042)
		(width 0.14732)
		(layer "In6.Cu")
		(net "UPI_CPU1_CPU0_P0P1_DP<6>")
	)
	(segment
		(start 94.861126 -212.124036)
		(end 94.818962 -212.1662)
		(width 0.0889)
		(layer "In6.Cu")
		(net "UPI_CPU1_CPU0_P0P1_DP<6>")
	)
	(segment
		(start 94.818962 -213.93023)
		(end 94.819216 -213.929468)
		(width 0.0889)
		(layer "In6.Cu")
		(net "UPI_CPU1_CPU0_P0P1_DP<6>")
	)
	(segment
		(start 364.967012 -171.437046)
		(end 358.97058 -165.62197)
		(width 0.14732)
		(layer "In6.Cu")
		(net "UPI_CPU1_CPU0_P0P1_DP<6>")
	)
	(segment
		(start 367.35004 -173.949614)
		(end 367.346738 -173.74489)
		(width 0.14732)
		(layer "In6.Cu")
		(net "UPI_CPU1_CPU0_P0P1_DP<6>")
	)
	(segment
		(start 276.752304 -141.689836)
		(end 238.590328 -142.376144)
		(width 0.14732)
		(layer "In6.Cu")
		(net "UPI_CPU1_CPU0_P0P1_DP<6>")
	)
	(segment
		(start 365.234728 -171.898564)
		(end 364.97006 -171.64177)
		(width 0.14732)
		(layer "In6.Cu")
		(net "UPI_CPU1_CPU0_P0P1_DP<6>")
	)
	(segment
		(start 365.771938 -172.217588)
		(end 365.439452 -171.895262)
		(width 0.14732)
		(layer "In6.Cu")
		(net "UPI_CPU1_CPU0_P0P1_DP<6>")
	)
	(segment
		(start 94.818962 -212.1662)
		(end 94.818962 -213.93023)
		(width 0.0889)
		(layer "In6.Cu")
		(net "UPI_CPU1_CPU0_P0P1_DP<6>")
	)
	(segment
		(start 161.906204 -143.836644)
		(end 126.074678 -165.883844)
		(width 0.14732)
		(layer "In6.Cu")
		(net "UPI_CPU1_CPU0_P0P1_DP<6>")
	)
	(segment
		(start 365.774986 -172.422312)
		(end 365.771938 -172.217588)
		(width 0.14732)
		(layer "In6.Cu")
		(net "UPI_CPU1_CPU0_P0P1_DP<6>")
	)
	(segment
		(start 367.614708 -174.206408)
		(end 367.35004 -173.949614)
		(width 0.14732)
		(layer "In6.Cu")
		(net "UPI_CPU1_CPU0_P0P1_DP<6>")
	)
	(segment
		(start 366.244378 -172.675804)
		(end 366.039654 -172.679106)
		(width 0.14732)
		(layer "In6.Cu")
		(net "UPI_CPU1_CPU0_P0P1_DP<6>")
	)
	(segment
		(start 104.661208 -186.638946)
		(end 104.457754 -186.661806)
		(width 0.14732)
		(layer "In6.Cu")
		(net "UPI_CPU1_CPU0_P0P1_DP<6>")
	)
	(segment
		(start 103.588312 -187.751974)
		(end 94.861126 -211.38896)
		(width 0.14732)
		(layer "In6.Cu")
		(net "UPI_CPU1_CPU0_P0P1_DP<6>")
	)
	(segment
		(start 369.89004 -175.128428)
		(end 368.90325 -174.93742)
		(width 0.14732)
		(layer "In6.Cu")
		(net "UPI_CPU1_CPU0_P0P1_DP<6>")
	)
	(segment
		(start 103.817928 -187.464192)
		(end 103.588312 -187.751974)
		(width 0.14732)
		(layer "In6.Cu")
		(net "UPI_CPU1_CPU0_P0P1_DP<6>")
	)
	(segment
		(start 366.604804 -173.025308)
		(end 366.244378 -172.675804)
		(width 0.14732)
		(layer "In6.Cu")
		(net "UPI_CPU1_CPU0_P0P1_DP<6>")
	)
	(segment
		(start 367.077244 -173.483524)
		(end 366.87252 -173.486572)
		(width 0.14732)
		(layer "In6.Cu")
		(net "UPI_CPU1_CPU0_P0P1_DP<6>")
	)
	(segment
		(start 319.917064 -143.488156)
		(end 276.752304 -141.689836)
		(width 0.14732)
		(layer "In6.Cu")
		(net "UPI_CPU1_CPU0_P0P1_DP<6>")
	)
	(segment
		(start 126.074678 -165.883844)
		(end 105.83291 -184.936892)
		(width 0.14732)
		(layer "In6.Cu")
		(net "UPI_CPU1_CPU0_P0P1_DP<6>")
	)
	(segment
		(start 94.564708 -214.321644)
		(end 94.723458 -214.622634)
		(width 0.0889)
		(layer "In6.Cu")
		(net "UPI_CPU1_CPU0_P0P1_DP<6>")
	)
	(segment
		(start 368.90325 -174.93742)
		(end 368.095022 -174.470568)
		(width 0.14732)
		(layer "In6.Cu")
		(net "UPI_CPU1_CPU0_P0P1_DP<6>")
	)
	(segment
		(start 330.765912 -146.27098)
		(end 319.917064 -143.488156)
		(width 0.14732)
		(layer "In6.Cu")
		(net "UPI_CPU1_CPU0_P0P1_DP<6>")
	)
	(segment
		(start 366.039654 -172.679106)
		(end 365.774986 -172.422312)
		(width 0.14732)
		(layer "In6.Cu")
		(net "UPI_CPU1_CPU0_P0P1_DP<6>")
	)
	(segment
		(start 104.021382 -187.441332)
		(end 103.817928 -187.464192)
		(width 0.14732)
		(layer "In6.Cu")
		(net "UPI_CPU1_CPU0_P0P1_DP<6>")
	)
	(segment
		(start 94.861126 -212.101938)
		(end 94.861126 -212.124036)
		(width 0.0889)
		(layer "In6.Cu")
		(net "UPI_CPU1_CPU0_P0P1_DP<6>")
	)
	(segment
		(start 370.122704 -176.019968)
		(end 370.267992 -175.47844)
		(width 0.14732)
		(layer "In6.Cu")
		(net "UPI_CPU1_CPU0_P0P1_DP<6>")
	)
	(segment
		(start 104.251252 -187.153042)
		(end 104.021382 -187.441332)
		(width 0.14732)
		(layer "In6.Cu")
		(net "UPI_CPU1_CPU0_P0P1_DP<6>")
	)
	(segment
		(start 358.97058 -165.62197)
		(end 330.765912 -146.27098)
		(width 0.14732)
		(layer "In6.Cu")
		(net "UPI_CPU1_CPU0_P0P1_DP<6>")
	)
	(segment
		(start 105.83291 -184.936892)
		(end 104.867964 -186.147202)
		(width 0.14732)
		(layer "In6.Cu")
		(net "UPI_CPU1_CPU0_P0P1_DP<6>")
	)
	(segment
		(start 368.095022 -174.470568)
		(end 367.819432 -174.203106)
		(width 0.14732)
		(layer "In6.Cu")
		(net "UPI_CPU1_CPU0_P0P1_DP<6>")
	)
	(segment
		(start 370.267992 -175.47844)
		(end 370.163598 -175.297592)
		(width 0.14732)
		(layer "In6.Cu")
		(net "UPI_CPU1_CPU0_P0P1_DP<6>")
	)
	(segment
		(start 104.867964 -186.147202)
		(end 104.891078 -186.350656)
		(width 0.14732)
		(layer "In6.Cu")
		(net "UPI_CPU1_CPU0_P0P1_DP<6>")
	)
	(segment
		(start 104.457754 -186.661806)
		(end 104.228138 -186.949588)
		(width 0.14732)
		(layer "In6.Cu")
		(net "UPI_CPU1_CPU0_P0P1_DP<6>")
	)
	(segment
		(start 367.346738 -173.74489)
		(end 367.077244 -173.483524)
		(width 0.14732)
		(layer "In6.Cu")
		(net "UPI_CPU1_CPU0_P0P1_DP<6>")
	)
	(arc
		(start 94.80423 -213.96833)
		(mid 94.717679 -214.111364)
		(end 94.594934 -214.22487)
		(width 0.0889)
		(layer "In6.Cu")
		(net "UPI_CPU1_CPU0_P0P1_DP<6>")
	)
	(arc
		(start 94.819216 -213.929468)
		(mid 94.812058 -213.949028)
		(end 94.80423 -213.96833)
		(width 0.0889)
		(layer "In6.Cu")
		(net "UPI_CPU1_CPU0_P0P1_DP<6>")
	)
	(segment
		(start 375.576338 -196.168772)
		(end 380.829312 -190.915798)
		(width 0.13208)
		(layer "F.Cu")
		(net "UPI_CPU1_CPU0_P0P1_DP<5>")
	)
	(segment
		(start 93.314266 -215.972644)
		(end 93.314012 -215.97239)
		(width 0.13208)
		(layer "F.Cu")
		(net "UPI_CPU1_CPU0_P0P1_DP<5>")
	)
	(segment
		(start 378.6886 -213.131908)
		(end 378.6886 -211.870798)
		(width 0.0889)
		(layer "F.Cu")
		(net "UPI_CPU1_CPU0_P0P1_DP<5>")
	)
	(segment
		(start 374.338088 -199.157844)
		(end 375.576338 -196.168772)
		(width 0.13208)
		(layer "F.Cu")
		(net "UPI_CPU1_CPU0_P0P1_DP<5>")
	)
	(segment
		(start 375.325132 -175.906176)
		(end 374.27916 -175.70323)
		(width 0.13208)
		(layer "F.Cu")
		(net "UPI_CPU1_CPU0_P0P1_DP<5>")
	)
	(segment
		(start 373.800878 -205.227174)
		(end 373.800878 -205.205076)
		(width 0.0889)
		(layer "F.Cu")
		(net "UPI_CPU1_CPU0_P0P1_DP<5>")
	)
	(segment
		(start 378.6886 -211.870798)
		(end 378.447046 -211.286852)
		(width 0.0889)
		(layer "F.Cu")
		(net "UPI_CPU1_CPU0_P0P1_DP<5>")
	)
	(segment
		(start 378.447046 -211.286852)
		(end 374.623076 -207.462882)
		(width 0.0889)
		(layer "F.Cu")
		(net "UPI_CPU1_CPU0_P0P1_DP<5>")
	)
	(segment
		(start 374.27916 -175.70323)
		(end 374.11914 -175.556672)
		(width 0.13208)
		(layer "F.Cu")
		(net "UPI_CPU1_CPU0_P0P1_DP<5>")
	)
	(segment
		(start 376.29973 -176.407064)
		(end 375.969784 -176.186846)
		(width 0.13208)
		(layer "F.Cu")
		(net "UPI_CPU1_CPU0_P0P1_DP<5>")
	)
	(segment
		(start 373.766334 -205.395576)
		(end 373.766334 -205.261718)
		(width 0.0889)
		(layer "F.Cu")
		(net "UPI_CPU1_CPU0_P0P1_DP<5>")
	)
	(segment
		(start 375.969784 -176.186846)
		(end 375.797318 -176.221136)
		(width 0.13208)
		(layer "F.Cu")
		(net "UPI_CPU1_CPU0_P0P1_DP<5>")
	)
	(segment
		(start 374.278398 -175.02632)
		(end 374.831356 -174.876968)
		(width 0.13208)
		(layer "F.Cu")
		(net "UPI_CPU1_CPU0_P0P1_DP<5>")
	)
	(segment
		(start 375.797318 -176.221136)
		(end 375.325132 -175.906176)
		(width 0.13208)
		(layer "F.Cu")
		(net "UPI_CPU1_CPU0_P0P1_DP<5>")
	)
	(segment
		(start 374.11914 -175.556672)
		(end 374.11914 -175.3362)
		(width 0.13208)
		(layer "F.Cu")
		(net "UPI_CPU1_CPU0_P0P1_DP<5>")
	)
	(segment
		(start 378.471684 -213.348824)
		(end 378.6886 -213.131908)
		(width 0.0889)
		(layer "F.Cu")
		(net "UPI_CPU1_CPU0_P0P1_DP<5>")
	)
	(segment
		(start 376.830336 -176.910746)
		(end 376.33402 -176.57953)
		(width 0.13208)
		(layer "F.Cu")
		(net "UPI_CPU1_CPU0_P0P1_DP<5>")
	)
	(segment
		(start 373.800878 -205.205076)
		(end 373.800878 -201.857864)
		(width 0.13208)
		(layer "F.Cu")
		(net "UPI_CPU1_CPU0_P0P1_DP<5>")
	)
	(segment
		(start 374.11914 -175.3362)
		(end 374.177306 -175.202342)
		(width 0.13208)
		(layer "F.Cu")
		(net "UPI_CPU1_CPU0_P0P1_DP<5>")
	)
	(segment
		(start 373.766334 -205.261718)
		(end 373.800878 -205.227174)
		(width 0.0889)
		(layer "F.Cu")
		(net "UPI_CPU1_CPU0_P0P1_DP<5>")
	)
	(segment
		(start 378.220986 -214.889588)
		(end 378.246132 -214.796878)
		(width 0.0889)
		(layer "F.Cu")
		(net "UPI_CPU1_CPU0_P0P1_DP<5>")
	)
	(segment
		(start 378.37618 -215.158574)
		(end 378.220986 -214.889588)
		(width 0.0889)
		(layer "F.Cu")
		(net "UPI_CPU1_CPU0_P0P1_DP<5>")
	)
	(segment
		(start 374.177306 -175.202342)
		(end 374.278398 -175.02632)
		(width 0.13208)
		(layer "F.Cu")
		(net "UPI_CPU1_CPU0_P0P1_DP<5>")
	)
	(segment
		(start 374.623076 -207.462882)
		(end 373.766334 -205.395576)
		(width 0.0889)
		(layer "F.Cu")
		(net "UPI_CPU1_CPU0_P0P1_DP<5>")
	)
	(segment
		(start 376.33402 -176.57953)
		(end 376.29973 -176.407064)
		(width 0.13208)
		(layer "F.Cu")
		(net "UPI_CPU1_CPU0_P0P1_DP<5>")
	)
	(segment
		(start 380.829312 -190.915798)
		(end 382.490218 -186.906154)
		(width 0.13208)
		(layer "F.Cu")
		(net "UPI_CPU1_CPU0_P0P1_DP<5>")
	)
	(segment
		(start 373.800878 -201.857864)
		(end 374.338088 -199.157844)
		(width 0.13208)
		(layer "F.Cu")
		(net "UPI_CPU1_CPU0_P0P1_DP<5>")
	)
	(segment
		(start 382.490218 -186.906154)
		(end 382.490218 -184.668414)
		(width 0.13208)
		(layer "F.Cu")
		(net "UPI_CPU1_CPU0_P0P1_DP<5>")
	)
	(segment
		(start 381.007112 -181.087776)
		(end 376.830336 -176.910746)
		(width 0.13208)
		(layer "F.Cu")
		(net "UPI_CPU1_CPU0_P0P1_DP<5>")
	)
	(segment
		(start 378.471684 -214.344758)
		(end 378.471684 -213.348824)
		(width 0.0889)
		(layer "F.Cu")
		(net "UPI_CPU1_CPU0_P0P1_DP<5>")
	)
	(segment
		(start 93.314012 -215.97239)
		(end 93.314012 -215.436704)
		(width 0.13208)
		(layer "F.Cu")
		(net "UPI_CPU1_CPU0_P0P1_DP<5>")
	)
	(segment
		(start 382.490218 -184.668414)
		(end 381.007112 -181.087776)
		(width 0.13208)
		(layer "F.Cu")
		(net "UPI_CPU1_CPU0_P0P1_DP<5>")
	)
	(arc
		(start 378.246132 -214.796878)
		(mid 378.254832 -214.790229)
		(end 378.263404 -214.783416)
		(width 0.0889)
		(layer "F.Cu")
		(net "UPI_CPU1_CPU0_P0P1_DP<5>")
	)
	(arc
		(start 378.263404 -214.783416)
		(mid 378.417033 -214.587592)
		(end 378.471684 -214.344758)
		(width 0.0889)
		(layer "F.Cu")
		(net "UPI_CPU1_CPU0_P0P1_DP<5>")
	)
	(segment
		(start 102.243636 -187.60821)
		(end 94.16288 -209.496152)
		(width 0.14732)
		(layer "In6.Cu")
		(net "UPI_CPU1_CPU0_P0P1_DP<5>")
	)
	(segment
		(start 93.470476 -215.165686)
		(end 93.314012 -215.436704)
		(width 0.0889)
		(layer "In6.Cu")
		(net "UPI_CPU1_CPU0_P0P1_DP<5>")
	)
	(segment
		(start 93.64726 -211.73059)
		(end 93.64726 -211.752688)
		(width 0.0889)
		(layer "In6.Cu")
		(net "UPI_CPU1_CPU0_P0P1_DP<5>")
	)
	(segment
		(start 93.64726 -211.752688)
		(end 93.68917 -211.794598)
		(width 0.0889)
		(layer "In6.Cu")
		(net "UPI_CPU1_CPU0_P0P1_DP<5>")
	)
	(segment
		(start 369.544854 -173.870366)
		(end 369.27409 -173.864524)
		(width 0.14732)
		(layer "In6.Cu")
		(net "UPI_CPU1_CPU0_P0P1_DP<5>")
	)
	(segment
		(start 238.589312 -141.161008)
		(end 169.44848 -140.043154)
		(width 0.14732)
		(layer "In6.Cu")
		(net "UPI_CPU1_CPU0_P0P1_DP<5>")
	)
	(segment
		(start 93.446346 -215.076532)
		(end 93.470476 -215.165686)
		(width 0.0889)
		(layer "In6.Cu")
		(net "UPI_CPU1_CPU0_P0P1_DP<5>")
	)
	(segment
		(start 374.457722 -173.120558)
		(end 374.399556 -173.099476)
		(width 0.14732)
		(layer "In6.Cu")
		(net "UPI_CPU1_CPU0_P0P1_DP<5>")
	)
	(segment
		(start 359.135426 -164.13734)
		(end 332.301596 -145.72742)
		(width 0.14732)
		(layer "In6.Cu")
		(net "UPI_CPU1_CPU0_P0P1_DP<5>")
	)
	(segment
		(start 319.669922 -142.269718)
		(end 317.27267 -142.269718)
		(width 0.14732)
		(layer "In6.Cu")
		(net "UPI_CPU1_CPU0_P0P1_DP<5>")
	)
	(segment
		(start 93.218508 -214.425784)
		(end 93.218508 -214.636858)
		(width 0.0889)
		(layer "In6.Cu")
		(net "UPI_CPU1_CPU0_P0P1_DP<5>")
	)
	(segment
		(start 93.68917 -213.892892)
		(end 93.688916 -213.8934)
		(width 0.0889)
		(layer "In6.Cu")
		(net "UPI_CPU1_CPU0_P0P1_DP<5>")
	)
	(segment
		(start 371.948964 -173.37532)
		(end 369.544854 -173.870366)
		(width 0.14732)
		(layer "In6.Cu")
		(net "UPI_CPU1_CPU0_P0P1_DP<5>")
	)
	(segment
		(start 93.68917 -211.794598)
		(end 93.68917 -213.892892)
		(width 0.0889)
		(layer "In6.Cu")
		(net "UPI_CPU1_CPU0_P0P1_DP<5>")
	)
	(segment
		(start 125.336808 -165.028118)
		(end 104.943148 -184.223406)
		(width 0.14732)
		(layer "In6.Cu")
		(net "UPI_CPU1_CPU0_P0P1_DP<5>")
	)
	(segment
		(start 94.16288 -209.496152)
		(end 94.162626 -209.496914)
		(width 0.14732)
		(layer "In6.Cu")
		(net "UPI_CPU1_CPU0_P0P1_DP<5>")
	)
	(segment
		(start 93.64726 -210.892644)
		(end 93.64726 -211.73059)
		(width 0.14732)
		(layer "In6.Cu")
		(net "UPI_CPU1_CPU0_P0P1_DP<5>")
	)
	(segment
		(start 161.459164 -142.80134)
		(end 125.336808 -165.028118)
		(width 0.14732)
		(layer "In6.Cu")
		(net "UPI_CPU1_CPU0_P0P1_DP<5>")
	)
	(segment
		(start 374.831356 -174.876968)
		(end 374.686068 -174.336456)
		(width 0.14732)
		(layer "In6.Cu")
		(net "UPI_CPU1_CPU0_P0P1_DP<5>")
	)
	(segment
		(start 104.943148 -184.223406)
		(end 102.243636 -187.60821)
		(width 0.14732)
		(layer "In6.Cu")
		(net "UPI_CPU1_CPU0_P0P1_DP<5>")
	)
	(segment
		(start 94.162626 -209.496914)
		(end 93.807026 -210.460082)
		(width 0.14732)
		(layer "In6.Cu")
		(net "UPI_CPU1_CPU0_P0P1_DP<5>")
	)
	(segment
		(start 93.807026 -210.460082)
		(end 93.64726 -210.892644)
		(width 0.14732)
		(layer "In6.Cu")
		(net "UPI_CPU1_CPU0_P0P1_DP<5>")
	)
	(segment
		(start 332.301596 -145.72742)
		(end 331.794358 -145.379694)
		(width 0.14732)
		(layer "In6.Cu")
		(net "UPI_CPU1_CPU0_P0P1_DP<5>")
	)
	(segment
		(start 371.949218 -173.37532)
		(end 371.948964 -173.37532)
		(width 0.14732)
		(layer "In6.Cu")
		(net "UPI_CPU1_CPU0_P0P1_DP<5>")
	)
	(segment
		(start 374.83796 -174.073566)
		(end 374.83796 -173.500796)
		(width 0.14732)
		(layer "In6.Cu")
		(net "UPI_CPU1_CPU0_P0P1_DP<5>")
	)
	(segment
		(start 374.686576 -174.335694)
		(end 374.83796 -174.073566)
		(width 0.14732)
		(layer "In6.Cu")
		(net "UPI_CPU1_CPU0_P0P1_DP<5>")
	)
	(segment
		(start 374.399556 -173.09973)
		(end 373.994426 -172.954188)
		(width 0.14732)
		(layer "In6.Cu")
		(net "UPI_CPU1_CPU0_P0P1_DP<5>")
	)
	(segment
		(start 369.27409 -173.864524)
		(end 368.783616 -173.569376)
		(width 0.14732)
		(layer "In6.Cu")
		(net "UPI_CPU1_CPU0_P0P1_DP<5>")
	)
	(segment
		(start 373.994426 -172.954188)
		(end 371.949218 -173.37532)
		(width 0.14732)
		(layer "In6.Cu")
		(net "UPI_CPU1_CPU0_P0P1_DP<5>")
	)
	(segment
		(start 374.83796 -173.500796)
		(end 374.457722 -173.120558)
		(width 0.14732)
		(layer "In6.Cu")
		(net "UPI_CPU1_CPU0_P0P1_DP<5>")
	)
	(segment
		(start 274.96643 -140.507212)
		(end 238.589312 -141.161008)
		(width 0.14732)
		(layer "In6.Cu")
		(net "UPI_CPU1_CPU0_P0P1_DP<5>")
	)
	(segment
		(start 169.44848 -140.043154)
		(end 161.459164 -142.80134)
		(width 0.14732)
		(layer "In6.Cu")
		(net "UPI_CPU1_CPU0_P0P1_DP<5>")
	)
	(segment
		(start 374.399556 -173.099476)
		(end 374.399556 -173.09973)
		(width 0.14732)
		(layer "In6.Cu")
		(net "UPI_CPU1_CPU0_P0P1_DP<5>")
	)
	(segment
		(start 368.783616 -173.569376)
		(end 359.135426 -164.13734)
		(width 0.14732)
		(layer "In6.Cu")
		(net "UPI_CPU1_CPU0_P0P1_DP<5>")
	)
	(segment
		(start 331.794358 -145.379694)
		(end 319.669922 -142.269718)
		(width 0.14732)
		(layer "In6.Cu")
		(net "UPI_CPU1_CPU0_P0P1_DP<5>")
	)
	(segment
		(start 374.686068 -174.336456)
		(end 374.686576 -174.335694)
		(width 0.14732)
		(layer "In6.Cu")
		(net "UPI_CPU1_CPU0_P0P1_DP<5>")
	)
	(segment
		(start 317.27267 -142.269718)
		(end 274.96643 -140.507212)
		(width 0.14732)
		(layer "In6.Cu")
		(net "UPI_CPU1_CPU0_P0P1_DP<5>")
	)
	(arc
		(start 93.688916 -213.8934)
		(mid 93.613845 -214.009142)
		(end 93.504512 -214.093298)
		(width 0.0889)
		(layer "In6.Cu")
		(net "UPI_CPU1_CPU0_P0P1_DP<5>")
	)
	(arc
		(start 93.218508 -214.636858)
		(mid 93.276853 -214.873363)
		(end 93.429328 -215.063324)
		(width 0.0889)
		(layer "In6.Cu")
		(net "UPI_CPU1_CPU0_P0P1_DP<5>")
	)
	(arc
		(start 93.504512 -214.093298)
		(mid 93.329964 -214.232402)
		(end 93.218508 -214.425784)
		(width 0.0889)
		(layer "In6.Cu")
		(net "UPI_CPU1_CPU0_P0P1_DP<5>")
	)
	(arc
		(start 93.429328 -215.063324)
		(mid 93.437774 -215.070009)
		(end 93.446346 -215.076532)
		(width 0.0889)
		(layer "In6.Cu")
		(net "UPI_CPU1_CPU0_P0P1_DP<5>")
	)
	(segment
		(start 373.728234 -173.449488)
		(end 371.067584 -173.449488)
		(width 0.13208)
		(layer "F.Cu")
		(net "UPI_CPU1_CPU0_P0P1_DP<4>")
	)
	(segment
		(start 381.89662 -180.473096)
		(end 376.678952 -175.255174)
		(width 0.13208)
		(layer "F.Cu")
		(net "UPI_CPU1_CPU0_P0P1_DP<4>")
	)
	(segment
		(start 376.50293 -175.255174)
		(end 376.222514 -174.974758)
		(width 0.13208)
		(layer "F.Cu")
		(net "UPI_CPU1_CPU0_P0P1_DP<4>")
	)
	(segment
		(start 375.355358 -199.503538)
		(end 376.51055 -196.714872)
		(width 0.13208)
		(layer "F.Cu")
		(net "UPI_CPU1_CPU0_P0P1_DP<4>")
	)
	(segment
		(start 374.884188 -205.261464)
		(end 374.849898 -205.227174)
		(width 0.0889)
		(layer "F.Cu")
		(net "UPI_CPU1_CPU0_P0P1_DP<4>")
	)
	(segment
		(start 375.835926 -207.82788)
		(end 374.884188 -205.529434)
		(width 0.0889)
		(layer "F.Cu")
		(net "UPI_CPU1_CPU0_P0P1_DP<4>")
	)
	(segment
		(start 374.884188 -205.529434)
		(end 374.884188 -205.261464)
		(width 0.0889)
		(layer "F.Cu")
		(net "UPI_CPU1_CPU0_P0P1_DP<4>")
	)
	(segment
		(start 374.849898 -205.205076)
		(end 374.849898 -202.044808)
		(width 0.13208)
		(layer "F.Cu")
		(net "UPI_CPU1_CPU0_P0P1_DP<4>")
	)
	(segment
		(start 376.222514 -174.798736)
		(end 375.942352 -174.518574)
		(width 0.13208)
		(layer "F.Cu")
		(net "UPI_CPU1_CPU0_P0P1_DP<4>")
	)
	(segment
		(start 379.220984 -214.319104)
		(end 379.220984 -213.422484)
		(width 0.0889)
		(layer "F.Cu")
		(net "UPI_CPU1_CPU0_P0P1_DP<4>")
	)
	(segment
		(start 374.849898 -202.044808)
		(end 375.355358 -199.503538)
		(width 0.13208)
		(layer "F.Cu")
		(net "UPI_CPU1_CPU0_P0P1_DP<4>")
	)
	(segment
		(start 376.222514 -174.974758)
		(end 376.222514 -174.798736)
		(width 0.13208)
		(layer "F.Cu")
		(net "UPI_CPU1_CPU0_P0P1_DP<4>")
	)
	(segment
		(start 378.85116 -215.964262)
		(end 379.001528 -215.703658)
		(width 0.0889)
		(layer "F.Cu")
		(net "UPI_CPU1_CPU0_P0P1_DP<4>")
	)
	(segment
		(start 378.75083 -215.158828)
		(end 378.75083 -215.133428)
		(width 0.0889)
		(layer "F.Cu")
		(net "UPI_CPU1_CPU0_P0P1_DP<4>")
	)
	(segment
		(start 371.067584 -173.449488)
		(end 370.826792 -173.384972)
		(width 0.13208)
		(layer "F.Cu")
		(net "UPI_CPU1_CPU0_P0P1_DP<4>")
	)
	(segment
		(start 370.675154 -173.12132)
		(end 370.122704 -172.971968)
		(width 0.13208)
		(layer "F.Cu")
		(net "UPI_CPU1_CPU0_P0P1_DP<4>")
	)
	(segment
		(start 384.209798 -189.015624)
		(end 384.209798 -186.718702)
		(width 0.13208)
		(layer "F.Cu")
		(net "UPI_CPU1_CPU0_P0P1_DP<4>")
	)
	(segment
		(start 379.016514 -211.008468)
		(end 375.835926 -207.82788)
		(width 0.0889)
		(layer "F.Cu")
		(net "UPI_CPU1_CPU0_P0P1_DP<4>")
	)
	(segment
		(start 376.678952 -175.255174)
		(end 376.50293 -175.255174)
		(width 0.13208)
		(layer "F.Cu")
		(net "UPI_CPU1_CPU0_P0P1_DP<4>")
	)
	(segment
		(start 374.85193 -173.79061)
		(end 373.728234 -173.449488)
		(width 0.13208)
		(layer "F.Cu")
		(net "UPI_CPU1_CPU0_P0P1_DP<4>")
	)
	(segment
		(start 384.209798 -186.718702)
		(end 383.460498 -184.248298)
		(width 0.13208)
		(layer "F.Cu")
		(net "UPI_CPU1_CPU0_P0P1_DP<4>")
	)
	(segment
		(start 376.51055 -196.714872)
		(end 384.209798 -189.015624)
		(width 0.13208)
		(layer "F.Cu")
		(net "UPI_CPU1_CPU0_P0P1_DP<4>")
	)
	(segment
		(start 375.942352 -174.518574)
		(end 374.85193 -173.79061)
		(width 0.13208)
		(layer "F.Cu")
		(net "UPI_CPU1_CPU0_P0P1_DP<4>")
	)
	(segment
		(start 378.846334 -215.972644)
		(end 378.85116 -215.964262)
		(width 0.0889)
		(layer "F.Cu")
		(net "UPI_CPU1_CPU0_P0P1_DP<4>")
	)
	(segment
		(start 379.033278 -214.643716)
		(end 379.033532 -214.643716)
		(width 0.0889)
		(layer "F.Cu")
		(net "UPI_CPU1_CPU0_P0P1_DP<4>")
	)
	(segment
		(start 379.220984 -213.422484)
		(end 379.221238 -213.42223)
		(width 0.0889)
		(layer "F.Cu")
		(net "UPI_CPU1_CPU0_P0P1_DP<4>")
	)
	(segment
		(start 378.959364 -215.597232)
		(end 378.959618 -215.597232)
		(width 0.0889)
		(layer "F.Cu")
		(net "UPI_CPU1_CPU0_P0P1_DP<4>")
	)
	(segment
		(start 379.033532 -214.643716)
		(end 379.039882 -214.639906)
		(width 0.0889)
		(layer "F.Cu")
		(net "UPI_CPU1_CPU0_P0P1_DP<4>")
	)
	(segment
		(start 379.032516 -214.644224)
		(end 379.033024 -214.64397)
		(width 0.0889)
		(layer "F.Cu")
		(net "UPI_CPU1_CPU0_P0P1_DP<4>")
	)
	(segment
		(start 374.849898 -205.227174)
		(end 374.849898 -205.205076)
		(width 0.0889)
		(layer "F.Cu")
		(net "UPI_CPU1_CPU0_P0P1_DP<4>")
	)
	(segment
		(start 379.033024 -214.64397)
		(end 379.033278 -214.643716)
		(width 0.0889)
		(layer "F.Cu")
		(net "UPI_CPU1_CPU0_P0P1_DP<4>")
	)
	(segment
		(start 383.460498 -184.248298)
		(end 381.89662 -180.473096)
		(width 0.13208)
		(layer "F.Cu")
		(net "UPI_CPU1_CPU0_P0P1_DP<4>")
	)
	(segment
		(start 379.001528 -215.703658)
		(end 378.976382 -215.610694)
		(width 0.0889)
		(layer "F.Cu")
		(net "UPI_CPU1_CPU0_P0P1_DP<4>")
	)
	(segment
		(start 379.021848 -214.65032)
		(end 379.032516 -214.644224)
		(width 0.0889)
		(layer "F.Cu")
		(net "UPI_CPU1_CPU0_P0P1_DP<4>")
	)
	(segment
		(start 92.844112 -214.622888)
		(end 92.843858 -214.622634)
		(width 0.13208)
		(layer "F.Cu")
		(net "UPI_CPU1_CPU0_P0P1_DP<4>")
	)
	(segment
		(start 379.221238 -213.42223)
		(end 379.221238 -211.50199)
		(width 0.0889)
		(layer "F.Cu")
		(net "UPI_CPU1_CPU0_P0P1_DP<4>")
	)
	(segment
		(start 370.826792 -173.384972)
		(end 370.675154 -173.12132)
		(width 0.13208)
		(layer "F.Cu")
		(net "UPI_CPU1_CPU0_P0P1_DP<4>")
	)
	(segment
		(start 379.221238 -211.50199)
		(end 379.016514 -211.008468)
		(width 0.0889)
		(layer "F.Cu")
		(net "UPI_CPU1_CPU0_P0P1_DP<4>")
	)
	(segment
		(start 92.844112 -215.158574)
		(end 92.844112 -214.622888)
		(width 0.13208)
		(layer "F.Cu")
		(net "UPI_CPU1_CPU0_P0P1_DP<4>")
	)
	(arc
		(start 378.75083 -215.133428)
		(mid 378.823079 -214.85637)
		(end 379.021848 -214.65032)
		(width 0.0889)
		(layer "F.Cu")
		(net "UPI_CPU1_CPU0_P0P1_DP<4>")
	)
	(arc
		(start 379.039882 -214.639906)
		(mid 379.172594 -214.503303)
		(end 379.220984 -214.319104)
		(width 0.0889)
		(layer "F.Cu")
		(net "UPI_CPU1_CPU0_P0P1_DP<4>")
	)
	(arc
		(start 378.976382 -215.610694)
		(mid 378.967808 -215.604045)
		(end 378.959364 -215.597232)
		(width 0.0889)
		(layer "F.Cu")
		(net "UPI_CPU1_CPU0_P0P1_DP<4>")
	)
	(arc
		(start 378.959618 -215.597232)
		(mid 378.805731 -215.401598)
		(end 378.75083 -215.158828)
		(width 0.0889)
		(layer "F.Cu")
		(net "UPI_CPU1_CPU0_P0P1_DP<4>")
	)
	(segment
		(start 319.319402 -141.604492)
		(end 332.071472 -144.874742)
		(width 0.14732)
		(layer "In6.Cu")
		(net "UPI_CPU1_CPU0_P0P1_DP<4>")
	)
	(segment
		(start 366.37595 -169.779696)
		(end 366.751616 -170.11904)
		(width 0.14732)
		(layer "In6.Cu")
		(net "UPI_CPU1_CPU0_P0P1_DP<4>")
	)
	(segment
		(start 104.521254 -183.83123)
		(end 124.980446 -164.574474)
		(width 0.14732)
		(layer "In6.Cu")
		(net "UPI_CPU1_CPU0_P0P1_DP<4>")
	)
	(segment
		(start 92.939362 -213.93023)
		(end 92.939362 -211.644992)
		(width 0.0889)
		(layer "In6.Cu")
		(net "UPI_CPU1_CPU0_P0P1_DP<4>")
	)
	(segment
		(start 365.125762 -168.650666)
		(end 365.136176 -168.855136)
		(width 0.14732)
		(layer "In6.Cu")
		(net "UPI_CPU1_CPU0_P0P1_DP<4>")
	)
	(segment
		(start 92.981526 -210.711542)
		(end 93.132656 -210.30184)
		(width 0.14732)
		(layer "In6.Cu")
		(net "UPI_CPU1_CPU0_P0P1_DP<4>")
	)
	(segment
		(start 161.15157 -142.317978)
		(end 169.657268 -139.380976)
		(width 0.14732)
		(layer "In6.Cu")
		(net "UPI_CPU1_CPU0_P0P1_DP<4>")
	)
	(segment
		(start 92.981526 -211.58073)
		(end 92.981526 -210.711542)
		(width 0.14732)
		(layer "In6.Cu")
		(net "UPI_CPU1_CPU0_P0P1_DP<4>")
	)
	(segment
		(start 364.852458 -168.404032)
		(end 365.125762 -168.650666)
		(width 0.14732)
		(layer "In6.Cu")
		(net "UPI_CPU1_CPU0_P0P1_DP<4>")
	)
	(segment
		(start 364.37443 -168.167304)
		(end 364.647988 -168.414446)
		(width 0.14732)
		(layer "In6.Cu")
		(net "UPI_CPU1_CPU0_P0P1_DP<4>")
	)
	(segment
		(start 92.939362 -211.644992)
		(end 92.981526 -211.602828)
		(width 0.0889)
		(layer "In6.Cu")
		(net "UPI_CPU1_CPU0_P0P1_DP<4>")
	)
	(segment
		(start 93.755718 -208.614518)
		(end 101.512624 -187.603892)
		(width 0.14732)
		(layer "In6.Cu")
		(net "UPI_CPU1_CPU0_P0P1_DP<4>")
	)
	(segment
		(start 365.614204 -169.091864)
		(end 365.887508 -169.338498)
		(width 0.14732)
		(layer "In6.Cu")
		(net "UPI_CPU1_CPU0_P0P1_DP<4>")
	)
	(segment
		(start 93.676724 -209.181192)
		(end 93.827854 -208.770982)
		(width 0.14732)
		(layer "In6.Cu")
		(net "UPI_CPU1_CPU0_P0P1_DP<4>")
	)
	(segment
		(start 92.981526 -211.602828)
		(end 92.981526 -211.58073)
		(width 0.0889)
		(layer "In6.Cu")
		(net "UPI_CPU1_CPU0_P0P1_DP<4>")
	)
	(segment
		(start 364.364016 -167.962834)
		(end 364.37443 -168.167304)
		(width 0.14732)
		(layer "In6.Cu")
		(net "UPI_CPU1_CPU0_P0P1_DP<4>")
	)
	(segment
		(start 366.751616 -170.11904)
		(end 366.76203 -170.32351)
		(width 0.14732)
		(layer "In6.Cu")
		(net "UPI_CPU1_CPU0_P0P1_DP<4>")
	)
	(segment
		(start 366.17148 -169.79011)
		(end 366.37595 -169.779696)
		(width 0.14732)
		(layer "In6.Cu")
		(net "UPI_CPU1_CPU0_P0P1_DP<4>")
	)
	(segment
		(start 101.512624 -187.603892)
		(end 104.521254 -183.83123)
		(width 0.14732)
		(layer "In6.Cu")
		(net "UPI_CPU1_CPU0_P0P1_DP<4>")
	)
	(segment
		(start 366.76203 -170.32351)
		(end 367.035588 -170.570652)
		(width 0.14732)
		(layer "In6.Cu")
		(net "UPI_CPU1_CPU0_P0P1_DP<4>")
	)
	(segment
		(start 238.593376 -140.495528)
		(end 273.148552 -139.874498)
		(width 0.14732)
		(layer "In6.Cu")
		(net "UPI_CPU1_CPU0_P0P1_DP<4>")
	)
	(segment
		(start 365.136176 -168.855136)
		(end 365.409734 -169.102278)
		(width 0.14732)
		(layer "In6.Cu")
		(net "UPI_CPU1_CPU0_P0P1_DP<4>")
	)
	(segment
		(start 370.160804 -172.245528)
		(end 370.267484 -172.430694)
		(width 0.14732)
		(layer "In6.Cu")
		(net "UPI_CPU1_CPU0_P0P1_DP<4>")
	)
	(segment
		(start 367.035588 -170.570652)
		(end 367.240058 -170.560238)
		(width 0.14732)
		(layer "In6.Cu")
		(net "UPI_CPU1_CPU0_P0P1_DP<4>")
	)
	(segment
		(start 365.409734 -169.102278)
		(end 365.614204 -169.091864)
		(width 0.14732)
		(layer "In6.Cu")
		(net "UPI_CPU1_CPU0_P0P1_DP<4>")
	)
	(segment
		(start 93.519752 -209.253328)
		(end 93.676724 -209.181192)
		(width 0.14732)
		(layer "In6.Cu")
		(net "UPI_CPU1_CPU0_P0P1_DP<4>")
	)
	(segment
		(start 93.440758 -209.819494)
		(end 93.368622 -209.66303)
		(width 0.14732)
		(layer "In6.Cu")
		(net "UPI_CPU1_CPU0_P0P1_DP<4>")
	)
	(segment
		(start 92.843858 -214.622634)
		(end 92.685108 -214.321644)
		(width 0.0889)
		(layer "In6.Cu")
		(net "UPI_CPU1_CPU0_P0P1_DP<4>")
	)
	(segment
		(start 360.065828 -164.080698)
		(end 364.364016 -167.962834)
		(width 0.14732)
		(layer "In6.Cu")
		(net "UPI_CPU1_CPU0_P0P1_DP<4>")
	)
	(segment
		(start 368.99977 -171.823634)
		(end 369.932712 -172.070776)
		(width 0.14732)
		(layer "In6.Cu")
		(net "UPI_CPU1_CPU0_P0P1_DP<4>")
	)
	(segment
		(start 368.18443 -171.41317)
		(end 368.99977 -171.823634)
		(width 0.14732)
		(layer "In6.Cu")
		(net "UPI_CPU1_CPU0_P0P1_DP<4>")
	)
	(segment
		(start 92.685108 -214.321644)
		(end 92.715334 -214.22487)
		(width 0.0889)
		(layer "In6.Cu")
		(net "UPI_CPU1_CPU0_P0P1_DP<4>")
	)
	(segment
		(start 370.267992 -172.431456)
		(end 370.122704 -172.971968)
		(width 0.14732)
		(layer "In6.Cu")
		(net "UPI_CPU1_CPU0_P0P1_DP<4>")
	)
	(segment
		(start 369.932712 -172.070776)
		(end 370.160804 -172.245528)
		(width 0.14732)
		(layer "In6.Cu")
		(net "UPI_CPU1_CPU0_P0P1_DP<4>")
	)
	(segment
		(start 364.647988 -168.414446)
		(end 364.852458 -168.404032)
		(width 0.14732)
		(layer "In6.Cu")
		(net "UPI_CPU1_CPU0_P0P1_DP<4>")
	)
	(segment
		(start 93.827854 -208.770982)
		(end 93.755718 -208.614518)
		(width 0.14732)
		(layer "In6.Cu")
		(net "UPI_CPU1_CPU0_P0P1_DP<4>")
	)
	(segment
		(start 370.267484 -172.430694)
		(end 370.267992 -172.431456)
		(width 0.14732)
		(layer "In6.Cu")
		(net "UPI_CPU1_CPU0_P0P1_DP<4>")
	)
	(segment
		(start 273.148552 -139.874498)
		(end 314.673488 -141.604492)
		(width 0.14732)
		(layer "In6.Cu")
		(net "UPI_CPU1_CPU0_P0P1_DP<4>")
	)
	(segment
		(start 314.673488 -141.604492)
		(end 319.319402 -141.604492)
		(width 0.14732)
		(layer "In6.Cu")
		(net "UPI_CPU1_CPU0_P0P1_DP<4>")
	)
	(segment
		(start 93.132656 -210.30184)
		(end 93.289628 -210.229704)
		(width 0.14732)
		(layer "In6.Cu")
		(net "UPI_CPU1_CPU0_P0P1_DP<4>")
	)
	(segment
		(start 365.897922 -169.542968)
		(end 366.17148 -169.79011)
		(width 0.14732)
		(layer "In6.Cu")
		(net "UPI_CPU1_CPU0_P0P1_DP<4>")
	)
	(segment
		(start 124.980446 -164.574474)
		(end 161.15157 -142.317978)
		(width 0.14732)
		(layer "In6.Cu")
		(net "UPI_CPU1_CPU0_P0P1_DP<4>")
	)
	(segment
		(start 238.584232 -140.495528)
		(end 238.593376 -140.495528)
		(width 0.14732)
		(layer "In6.Cu")
		(net "UPI_CPU1_CPU0_P0P1_DP<4>")
	)
	(segment
		(start 93.368622 -209.66303)
		(end 93.519752 -209.253328)
		(width 0.14732)
		(layer "In6.Cu")
		(net "UPI_CPU1_CPU0_P0P1_DP<4>")
	)
	(segment
		(start 367.240058 -170.560238)
		(end 368.18443 -171.41317)
		(width 0.14732)
		(layer "In6.Cu")
		(net "UPI_CPU1_CPU0_P0P1_DP<4>")
	)
	(segment
		(start 169.657268 -139.380976)
		(end 238.584232 -140.495528)
		(width 0.14732)
		(layer "In6.Cu")
		(net "UPI_CPU1_CPU0_P0P1_DP<4>")
	)
	(segment
		(start 332.071472 -144.874742)
		(end 360.065828 -164.080698)
		(width 0.14732)
		(layer "In6.Cu")
		(net "UPI_CPU1_CPU0_P0P1_DP<4>")
	)
	(segment
		(start 365.887508 -169.338498)
		(end 365.897922 -169.542968)
		(width 0.14732)
		(layer "In6.Cu")
		(net "UPI_CPU1_CPU0_P0P1_DP<4>")
	)
	(segment
		(start 93.289628 -210.229704)
		(end 93.440758 -209.819494)
		(width 0.14732)
		(layer "In6.Cu")
		(net "UPI_CPU1_CPU0_P0P1_DP<4>")
	)
	(segment
		(start 92.939616 -213.929468)
		(end 92.939362 -213.93023)
		(width 0.0889)
		(layer "In6.Cu")
		(net "UPI_CPU1_CPU0_P0P1_DP<4>")
	)
	(arc
		(start 92.92463 -213.96833)
		(mid 92.932465 -213.949031)
		(end 92.939616 -213.929468)
		(width 0.0889)
		(layer "In6.Cu")
		(net "UPI_CPU1_CPU0_P0P1_DP<4>")
	)
	(arc
		(start 92.715334 -214.22487)
		(mid 92.83808 -214.111365)
		(end 92.92463 -213.96833)
		(width 0.0889)
		(layer "In6.Cu")
		(net "UPI_CPU1_CPU0_P0P1_DP<4>")
	)
	(segment
		(start 376.205242 -172.66158)
		(end 376.032522 -172.69587)
		(width 0.13208)
		(layer "F.Cu")
		(net "UPI_CPU1_CPU0_P0P1_DP<3>")
	)
	(segment
		(start 91.434412 -215.97239)
		(end 91.434412 -215.436704)
		(width 0.13208)
		(layer "F.Cu")
		(net "UPI_CPU1_CPU0_P0P1_DP<3>")
	)
	(segment
		(start 375.476262 -172.324268)
		(end 374.31853 -171.99229)
		(width 0.13208)
		(layer "F.Cu")
		(net "UPI_CPU1_CPU0_P0P1_DP<3>")
	)
	(segment
		(start 380.25578 -215.158574)
		(end 380.100586 -214.889588)
		(width 0.0889)
		(layer "F.Cu")
		(net "UPI_CPU1_CPU0_P0P1_DP<3>")
	)
	(segment
		(start 380.35103 -211.38007)
		(end 379.95098 -210.413092)
		(width 0.0889)
		(layer "F.Cu")
		(net "UPI_CPU1_CPU0_P0P1_DP<3>")
	)
	(segment
		(start 380.35103 -214.344758)
		(end 380.35103 -211.38007)
		(width 0.0889)
		(layer "F.Cu")
		(net "UPI_CPU1_CPU0_P0P1_DP<3>")
	)
	(segment
		(start 380.100586 -214.889588)
		(end 380.125732 -214.796878)
		(width 0.0889)
		(layer "F.Cu")
		(net "UPI_CPU1_CPU0_P0P1_DP<3>")
	)
	(segment
		(start 376.417078 -202.1967)
		(end 376.7201 -200.67397)
		(width 0.13208)
		(layer "F.Cu")
		(net "UPI_CPU1_CPU0_P0P1_DP<3>")
	)
	(segment
		(start 374.116092 -171.739052)
		(end 374.130316 -171.600876)
		(width 0.13208)
		(layer "F.Cu")
		(net "UPI_CPU1_CPU0_P0P1_DP<3>")
	)
	(segment
		(start 386.213858 -189.224666)
		(end 386.213858 -186.802522)
		(width 0.13208)
		(layer "F.Cu")
		(net "UPI_CPU1_CPU0_P0P1_DP<3>")
	)
	(segment
		(start 376.032522 -172.69587)
		(end 375.476262 -172.324268)
		(width 0.13208)
		(layer "F.Cu")
		(net "UPI_CPU1_CPU0_P0P1_DP<3>")
	)
	(segment
		(start 376.382534 -205.504796)
		(end 376.382534 -205.261718)
		(width 0.0889)
		(layer "F.Cu")
		(net "UPI_CPU1_CPU0_P0P1_DP<3>")
	)
	(segment
		(start 376.534934 -172.882052)
		(end 376.205242 -172.66158)
		(width 0.13208)
		(layer "F.Cu")
		(net "UPI_CPU1_CPU0_P0P1_DP<3>")
	)
	(segment
		(start 376.963432 -173.31817)
		(end 376.569224 -173.054772)
		(width 0.13208)
		(layer "F.Cu")
		(net "UPI_CPU1_CPU0_P0P1_DP<3>")
	)
	(segment
		(start 91.434666 -215.972644)
		(end 91.434412 -215.97239)
		(width 0.13208)
		(layer "F.Cu")
		(net "UPI_CPU1_CPU0_P0P1_DP<3>")
	)
	(segment
		(start 376.569224 -173.054772)
		(end 376.534934 -172.882052)
		(width 0.13208)
		(layer "F.Cu")
		(net "UPI_CPU1_CPU0_P0P1_DP<3>")
	)
	(segment
		(start 376.828558 -200.128378)
		(end 377.902216 -197.536308)
		(width 0.13208)
		(layer "F.Cu")
		(net "UPI_CPU1_CPU0_P0P1_DP<3>")
	)
	(segment
		(start 386.213858 -186.802522)
		(end 383.21996 -179.574698)
		(width 0.13208)
		(layer "F.Cu")
		(net "UPI_CPU1_CPU0_P0P1_DP<3>")
	)
	(segment
		(start 379.95098 -210.413092)
		(end 377.329954 -207.792066)
		(width 0.0889)
		(layer "F.Cu")
		(net "UPI_CPU1_CPU0_P0P1_DP<3>")
	)
	(segment
		(start 377.329954 -207.792066)
		(end 376.382534 -205.504796)
		(width 0.0889)
		(layer "F.Cu")
		(net "UPI_CPU1_CPU0_P0P1_DP<3>")
	)
	(segment
		(start 376.382534 -205.261718)
		(end 376.417078 -205.227174)
		(width 0.0889)
		(layer "F.Cu")
		(net "UPI_CPU1_CPU0_P0P1_DP<3>")
	)
	(segment
		(start 380.351284 -214.345012)
		(end 380.35103 -214.344758)
		(width 0.0889)
		(layer "F.Cu")
		(net "UPI_CPU1_CPU0_P0P1_DP<3>")
	)
	(segment
		(start 374.278398 -171.34332)
		(end 374.831356 -171.193968)
		(width 0.13208)
		(layer "F.Cu")
		(net "UPI_CPU1_CPU0_P0P1_DP<3>")
	)
	(segment
		(start 376.7201 -200.67397)
		(end 376.828558 -200.128378)
		(width 0.13208)
		(layer "F.Cu")
		(net "UPI_CPU1_CPU0_P0P1_DP<3>")
	)
	(segment
		(start 383.21996 -179.574698)
		(end 376.963432 -173.31817)
		(width 0.13208)
		(layer "F.Cu")
		(net "UPI_CPU1_CPU0_P0P1_DP<3>")
	)
	(segment
		(start 376.417078 -205.227174)
		(end 376.417078 -205.205076)
		(width 0.0889)
		(layer "F.Cu")
		(net "UPI_CPU1_CPU0_P0P1_DP<3>")
	)
	(segment
		(start 374.130316 -171.600876)
		(end 374.278398 -171.34332)
		(width 0.13208)
		(layer "F.Cu")
		(net "UPI_CPU1_CPU0_P0P1_DP<3>")
	)
	(segment
		(start 374.31853 -171.99229)
		(end 374.144032 -171.817538)
		(width 0.13208)
		(layer "F.Cu")
		(net "UPI_CPU1_CPU0_P0P1_DP<3>")
	)
	(segment
		(start 377.902216 -197.536308)
		(end 386.213858 -189.224666)
		(width 0.13208)
		(layer "F.Cu")
		(net "UPI_CPU1_CPU0_P0P1_DP<3>")
	)
	(segment
		(start 374.144032 -171.817538)
		(end 374.116092 -171.739052)
		(width 0.13208)
		(layer "F.Cu")
		(net "UPI_CPU1_CPU0_P0P1_DP<3>")
	)
	(segment
		(start 376.417078 -205.205076)
		(end 376.417078 -202.1967)
		(width 0.13208)
		(layer "F.Cu")
		(net "UPI_CPU1_CPU0_P0P1_DP<3>")
	)
	(arc
		(start 380.143004 -214.783416)
		(mid 380.296579 -214.587707)
		(end 380.351284 -214.345012)
		(width 0.0889)
		(layer "F.Cu")
		(net "UPI_CPU1_CPU0_P0P1_DP<3>")
	)
	(arc
		(start 380.125732 -214.796878)
		(mid 380.134432 -214.790229)
		(end 380.143004 -214.783416)
		(width 0.0889)
		(layer "F.Cu")
		(net "UPI_CPU1_CPU0_P0P1_DP<3>")
	)
	(segment
		(start 91.76766 -210.41995)
		(end 100.279454 -187.362084)
		(width 0.14732)
		(layer "In6.Cu")
		(net "UPI_CPU1_CPU0_P0P1_DP<3>")
	)
	(segment
		(start 91.80957 -213.892892)
		(end 91.80957 -211.835238)
		(width 0.0889)
		(layer "In6.Cu")
		(net "UPI_CPU1_CPU0_P0P1_DP<3>")
	)
	(segment
		(start 91.434412 -215.436704)
		(end 91.590876 -215.165686)
		(width 0.0889)
		(layer "In6.Cu")
		(net "UPI_CPU1_CPU0_P0P1_DP<3>")
	)
	(segment
		(start 360.257344 -162.624262)
		(end 368.873532 -170.519598)
		(width 0.14732)
		(layer "In6.Cu")
		(net "UPI_CPU1_CPU0_P0P1_DP<3>")
	)
	(segment
		(start 91.76766 -211.77123)
		(end 91.76766 -210.41995)
		(width 0.14732)
		(layer "In6.Cu")
		(net "UPI_CPU1_CPU0_P0P1_DP<3>")
	)
	(segment
		(start 238.585756 -139.280646)
		(end 238.590074 -139.280646)
		(width 0.14732)
		(layer "In6.Cu")
		(net "UPI_CPU1_CPU0_P0P1_DP<3>")
	)
	(segment
		(start 124.270008 -163.708842)
		(end 160.719262 -141.28115)
		(width 0.14732)
		(layer "In6.Cu")
		(net "UPI_CPU1_CPU0_P0P1_DP<3>")
	)
	(segment
		(start 91.80957 -211.835238)
		(end 91.76766 -211.793328)
		(width 0.0889)
		(layer "In6.Cu")
		(net "UPI_CPU1_CPU0_P0P1_DP<3>")
	)
	(segment
		(start 368.873532 -170.519598)
		(end 369.319048 -170.742102)
		(width 0.14732)
		(layer "In6.Cu")
		(net "UPI_CPU1_CPU0_P0P1_DP<3>")
	)
	(segment
		(start 271.367758 -138.691366)
		(end 271.368012 -138.691112)
		(width 0.14732)
		(layer "In6.Cu")
		(net "UPI_CPU1_CPU0_P0P1_DP<3>")
	)
	(segment
		(start 238.590074 -139.280646)
		(end 271.367758 -138.691366)
		(width 0.14732)
		(layer "In6.Cu")
		(net "UPI_CPU1_CPU0_P0P1_DP<3>")
	)
	(segment
		(start 374.686068 -170.653456)
		(end 374.831356 -171.193968)
		(width 0.14732)
		(layer "In6.Cu")
		(net "UPI_CPU1_CPU0_P0P1_DP<3>")
	)
	(segment
		(start 91.590876 -215.165686)
		(end 91.566746 -215.076532)
		(width 0.0889)
		(layer "In6.Cu")
		(net "UPI_CPU1_CPU0_P0P1_DP<3>")
	)
	(segment
		(start 333.001874 -143.926052)
		(end 360.257344 -162.624262)
		(width 0.14732)
		(layer "In6.Cu")
		(net "UPI_CPU1_CPU0_P0P1_DP<3>")
	)
	(segment
		(start 369.66398 -170.7134)
		(end 369.66398 -170.713654)
		(width 0.14732)
		(layer "In6.Cu")
		(net "UPI_CPU1_CPU0_P0P1_DP<3>")
	)
	(segment
		(start 374.686576 -170.652694)
		(end 374.686068 -170.653456)
		(width 0.14732)
		(layer "In6.Cu")
		(net "UPI_CPU1_CPU0_P0P1_DP<3>")
	)
	(segment
		(start 91.338908 -214.636858)
		(end 91.338908 -214.425784)
		(width 0.0889)
		(layer "In6.Cu")
		(net "UPI_CPU1_CPU0_P0P1_DP<3>")
	)
	(segment
		(start 100.279454 -187.362084)
		(end 103.710232 -183.060594)
		(width 0.14732)
		(layer "In6.Cu")
		(net "UPI_CPU1_CPU0_P0P1_DP<3>")
	)
	(segment
		(start 369.66398 -170.713654)
		(end 373.905526 -169.22877)
		(width 0.14732)
		(layer "In6.Cu")
		(net "UPI_CPU1_CPU0_P0P1_DP<3>")
	)
	(segment
		(start 271.368012 -138.691112)
		(end 271.375886 -138.691112)
		(width 0.14732)
		(layer "In6.Cu")
		(net "UPI_CPU1_CPU0_P0P1_DP<3>")
	)
	(segment
		(start 369.319048 -170.742102)
		(end 369.66398 -170.7134)
		(width 0.14732)
		(layer "In6.Cu")
		(net "UPI_CPU1_CPU0_P0P1_DP<3>")
	)
	(segment
		(start 91.76766 -211.793328)
		(end 91.76766 -211.77123)
		(width 0.0889)
		(layer "In6.Cu")
		(net "UPI_CPU1_CPU0_P0P1_DP<3>")
	)
	(segment
		(start 103.710232 -183.060594)
		(end 124.270008 -163.708842)
		(width 0.14732)
		(layer "In6.Cu")
		(net "UPI_CPU1_CPU0_P0P1_DP<3>")
	)
	(segment
		(start 374.8532 -169.812716)
		(end 374.8532 -170.36415)
		(width 0.14732)
		(layer "In6.Cu")
		(net "UPI_CPU1_CPU0_P0P1_DP<3>")
	)
	(segment
		(start 374.391682 -169.351198)
		(end 374.8532 -169.812716)
		(width 0.14732)
		(layer "In6.Cu")
		(net "UPI_CPU1_CPU0_P0P1_DP<3>")
	)
	(segment
		(start 312.141362 -140.390118)
		(end 319.21323 -140.390118)
		(width 0.14732)
		(layer "In6.Cu")
		(net "UPI_CPU1_CPU0_P0P1_DP<3>")
	)
	(segment
		(start 91.809316 -213.8934)
		(end 91.80957 -213.892892)
		(width 0.0889)
		(layer "In6.Cu")
		(net "UPI_CPU1_CPU0_P0P1_DP<3>")
	)
	(segment
		(start 373.905526 -169.22877)
		(end 374.391682 -169.351198)
		(width 0.14732)
		(layer "In6.Cu")
		(net "UPI_CPU1_CPU0_P0P1_DP<3>")
	)
	(segment
		(start 169.737786 -138.167618)
		(end 238.585756 -139.280646)
		(width 0.14732)
		(layer "In6.Cu")
		(net "UPI_CPU1_CPU0_P0P1_DP<3>")
	)
	(segment
		(start 160.719262 -141.28115)
		(end 169.737786 -138.167618)
		(width 0.14732)
		(layer "In6.Cu")
		(net "UPI_CPU1_CPU0_P0P1_DP<3>")
	)
	(segment
		(start 319.21323 -140.390118)
		(end 333.001874 -143.926052)
		(width 0.14732)
		(layer "In6.Cu")
		(net "UPI_CPU1_CPU0_P0P1_DP<3>")
	)
	(segment
		(start 374.8532 -170.36415)
		(end 374.686576 -170.652694)
		(width 0.14732)
		(layer "In6.Cu")
		(net "UPI_CPU1_CPU0_P0P1_DP<3>")
	)
	(segment
		(start 271.375886 -138.691112)
		(end 312.141362 -140.390118)
		(width 0.14732)
		(layer "In6.Cu")
		(net "UPI_CPU1_CPU0_P0P1_DP<3>")
	)
	(arc
		(start 91.549728 -215.063324)
		(mid 91.397297 -214.873342)
		(end 91.338908 -214.636858)
		(width 0.0889)
		(layer "In6.Cu")
		(net "UPI_CPU1_CPU0_P0P1_DP<3>")
	)
	(arc
		(start 91.566746 -215.076532)
		(mid 91.558174 -215.070009)
		(end 91.549728 -215.063324)
		(width 0.0889)
		(layer "In6.Cu")
		(net "UPI_CPU1_CPU0_P0P1_DP<3>")
	)
	(arc
		(start 91.624912 -214.093298)
		(mid 91.734308 -214.009201)
		(end 91.809316 -213.8934)
		(width 0.0889)
		(layer "In6.Cu")
		(net "UPI_CPU1_CPU0_P0P1_DP<3>")
	)
	(arc
		(start 91.338908 -214.425784)
		(mid 91.450348 -214.232389)
		(end 91.624912 -214.093298)
		(width 0.0889)
		(layer "In6.Cu")
		(net "UPI_CPU1_CPU0_P0P1_DP<3>")
	)
	(segment
		(start 376.34926 -171.267882)
		(end 376.174 -171.285154)
		(width 0.13208)
		(layer "F.Cu")
		(net "UPI_CPU1_CPU0_P0P1_DP<2>")
	)
	(segment
		(start 381.040386 -215.42756)
		(end 381.06223 -215.508332)
		(width 0.0889)
		(layer "F.Cu")
		(net "UPI_CPU1_CPU0_P0P1_DP<2>")
	)
	(segment
		(start 386.883402 -191.268858)
		(end 387.819138 -190.333122)
		(width 0.13208)
		(layer "F.Cu")
		(net "UPI_CPU1_CPU0_P0P1_DP<2>")
	)
	(segment
		(start 381.06223 -215.508332)
		(end 381.061976 -215.509094)
		(width 0.0889)
		(layer "F.Cu")
		(net "UPI_CPU1_CPU0_P0P1_DP<2>")
	)
	(segment
		(start 371.799104 -170.264328)
		(end 371.418104 -170.42765)
		(width 0.13208)
		(layer "F.Cu")
		(net "UPI_CPU1_CPU0_P0P1_DP<2>")
	)
	(segment
		(start 381.469138 -214.244936)
		(end 381.570738 -214.143336)
		(width 0.0889)
		(layer "F.Cu")
		(net "UPI_CPU1_CPU0_P0P1_DP<2>")
	)
	(segment
		(start 374.753886 -170.04538)
		(end 373.292878 -169.75455)
		(width 0.13208)
		(layer "F.Cu")
		(net "UPI_CPU1_CPU0_P0P1_DP<2>")
	)
	(segment
		(start 377.466098 -205.227174)
		(end 377.466098 -205.205076)
		(width 0.0889)
		(layer "F.Cu")
		(net "UPI_CPU1_CPU0_P0P1_DP<2>")
	)
	(segment
		(start 371.96268 -170.329606)
		(end 371.799104 -170.264328)
		(width 0.13208)
		(layer "F.Cu")
		(net "UPI_CPU1_CPU0_P0P1_DP<2>")
	)
	(segment
		(start 380.692406 -210.118706)
		(end 378.242322 -207.668876)
		(width 0.0889)
		(layer "F.Cu")
		(net "UPI_CPU1_CPU0_P0P1_DP<2>")
	)
	(segment
		(start 375.867422 -171.03344)
		(end 375.85015 -170.858434)
		(width 0.13208)
		(layer "F.Cu")
		(net "UPI_CPU1_CPU0_P0P1_DP<2>")
	)
	(segment
		(start 381.471678 -212.65642)
		(end 381.471678 -212.50402)
		(width 0.0889)
		(layer "F.Cu")
		(net "UPI_CPU1_CPU0_P0P1_DP<2>")
	)
	(segment
		(start 381.469138 -213.82228)
		(end 381.469138 -213.61908)
		(width 0.0889)
		(layer "F.Cu")
		(net "UPI_CPU1_CPU0_P0P1_DP<2>")
	)
	(segment
		(start 90.964512 -215.158574)
		(end 90.964512 -214.622888)
		(width 0.13208)
		(layer "F.Cu")
		(net "UPI_CPU1_CPU0_P0P1_DP<2>")
	)
	(segment
		(start 378.242322 -207.668876)
		(end 377.500388 -205.877414)
		(width 0.0889)
		(layer "F.Cu")
		(net "UPI_CPU1_CPU0_P0P1_DP<2>")
	)
	(segment
		(start 381.19558 -215.158574)
		(end 381.040386 -215.42756)
		(width 0.0889)
		(layer "F.Cu")
		(net "UPI_CPU1_CPU0_P0P1_DP<2>")
	)
	(segment
		(start 378.795534 -198.123302)
		(end 384.777742 -192.141094)
		(width 0.13208)
		(layer "F.Cu")
		(net "UPI_CPU1_CPU0_P0P1_DP<2>")
	)
	(segment
		(start 375.85015 -170.858434)
		(end 374.9675 -170.134026)
		(width 0.13208)
		(layer "F.Cu")
		(net "UPI_CPU1_CPU0_P0P1_DP<2>")
	)
	(segment
		(start 387.819138 -189.10427)
		(end 387.374638 -186.869578)
		(width 0.13208)
		(layer "F.Cu")
		(net "UPI_CPU1_CPU0_P0P1_DP<2>")
	)
	(segment
		(start 387.819138 -190.333122)
		(end 387.819138 -189.10427)
		(width 0.13208)
		(layer "F.Cu")
		(net "UPI_CPU1_CPU0_P0P1_DP<2>")
	)
	(segment
		(start 372.987316 -169.75455)
		(end 372.392194 -170.00982)
		(width 0.13208)
		(layer "F.Cu")
		(net "UPI_CPU1_CPU0_P0P1_DP<2>")
	)
	(segment
		(start 381.570738 -214.549736)
		(end 381.469138 -214.448136)
		(width 0.0889)
		(layer "F.Cu")
		(net "UPI_CPU1_CPU0_P0P1_DP<2>")
	)
	(segment
		(start 377.852432 -200.400158)
		(end 378.795534 -198.123302)
		(width 0.13208)
		(layer "F.Cu")
		(net "UPI_CPU1_CPU0_P0P1_DP<2>")
	)
	(segment
		(start 370.6749 -170.07332)
		(end 370.122704 -169.923968)
		(width 0.13208)
		(layer "F.Cu")
		(net "UPI_CPU1_CPU0_P0P1_DP<2>")
	)
	(segment
		(start 384.777742 -192.141094)
		(end 386.883402 -191.268858)
		(width 0.13208)
		(layer "F.Cu")
		(net "UPI_CPU1_CPU0_P0P1_DP<2>")
	)
	(segment
		(start 381.570738 -212.75548)
		(end 381.471678 -212.65642)
		(width 0.0889)
		(layer "F.Cu")
		(net "UPI_CPU1_CPU0_P0P1_DP<2>")
	)
	(segment
		(start 381.570738 -215.170004)
		(end 381.570738 -214.549736)
		(width 0.0889)
		(layer "F.Cu")
		(net "UPI_CPU1_CPU0_P0P1_DP<2>")
	)
	(segment
		(start 377.798076 -200.67397)
		(end 377.852432 -200.400158)
		(width 0.13208)
		(layer "F.Cu")
		(net "UPI_CPU1_CPU0_P0P1_DP<2>")
	)
	(segment
		(start 381.570738 -212.240622)
		(end 380.692406 -210.118706)
		(width 0.0889)
		(layer "F.Cu")
		(net "UPI_CPU1_CPU0_P0P1_DP<2>")
	)
	(segment
		(start 373.292878 -169.75455)
		(end 372.987316 -169.75455)
		(width 0.13208)
		(layer "F.Cu")
		(net "UPI_CPU1_CPU0_P0P1_DP<2>")
	)
	(segment
		(start 376.174 -171.285154)
		(end 375.867422 -171.03344)
		(width 0.13208)
		(layer "F.Cu")
		(net "UPI_CPU1_CPU0_P0P1_DP<2>")
	)
	(segment
		(start 384.099816 -178.963828)
		(end 376.65533 -171.519088)
		(width 0.13208)
		(layer "F.Cu")
		(net "UPI_CPU1_CPU0_P0P1_DP<2>")
	)
	(segment
		(start 371.418104 -170.42765)
		(end 371.054884 -170.42765)
		(width 0.13208)
		(layer "F.Cu")
		(net "UPI_CPU1_CPU0_P0P1_DP<2>")
	)
	(segment
		(start 377.500388 -205.877414)
		(end 377.500388 -205.261464)
		(width 0.0889)
		(layer "F.Cu")
		(net "UPI_CPU1_CPU0_P0P1_DP<2>")
	)
	(segment
		(start 381.471678 -212.50402)
		(end 381.570738 -212.40496)
		(width 0.0889)
		(layer "F.Cu")
		(net "UPI_CPU1_CPU0_P0P1_DP<2>")
	)
	(segment
		(start 381.570738 -213.31428)
		(end 381.469138 -213.21268)
		(width 0.0889)
		(layer "F.Cu")
		(net "UPI_CPU1_CPU0_P0P1_DP<2>")
	)
	(segment
		(start 381.570738 -212.40496)
		(end 381.570738 -212.240622)
		(width 0.0889)
		(layer "F.Cu")
		(net "UPI_CPU1_CPU0_P0P1_DP<2>")
	)
	(segment
		(start 372.392194 -170.00982)
		(end 372.326916 -170.173396)
		(width 0.13208)
		(layer "F.Cu")
		(net "UPI_CPU1_CPU0_P0P1_DP<2>")
	)
	(segment
		(start 381.469138 -213.21268)
		(end 381.469138 -213.00948)
		(width 0.0889)
		(layer "F.Cu")
		(net "UPI_CPU1_CPU0_P0P1_DP<2>")
	)
	(segment
		(start 370.791486 -170.274996)
		(end 370.6749 -170.07332)
		(width 0.13208)
		(layer "F.Cu")
		(net "UPI_CPU1_CPU0_P0P1_DP<2>")
	)
	(segment
		(start 387.374638 -186.869578)
		(end 384.099816 -178.963828)
		(width 0.13208)
		(layer "F.Cu")
		(net "UPI_CPU1_CPU0_P0P1_DP<2>")
	)
	(segment
		(start 381.570738 -214.143336)
		(end 381.570738 -213.92388)
		(width 0.0889)
		(layer "F.Cu")
		(net "UPI_CPU1_CPU0_P0P1_DP<2>")
	)
	(segment
		(start 374.9675 -170.134026)
		(end 374.753886 -170.04538)
		(width 0.13208)
		(layer "F.Cu")
		(net "UPI_CPU1_CPU0_P0P1_DP<2>")
	)
	(segment
		(start 381.469138 -214.448136)
		(end 381.469138 -214.244936)
		(width 0.0889)
		(layer "F.Cu")
		(net "UPI_CPU1_CPU0_P0P1_DP<2>")
	)
	(segment
		(start 377.466098 -205.205076)
		(end 377.466098 -202.343004)
		(width 0.13208)
		(layer "F.Cu")
		(net "UPI_CPU1_CPU0_P0P1_DP<2>")
	)
	(segment
		(start 90.964512 -214.622888)
		(end 90.964258 -214.622634)
		(width 0.13208)
		(layer "F.Cu")
		(net "UPI_CPU1_CPU0_P0P1_DP<2>")
	)
	(segment
		(start 381.469138 -213.61908)
		(end 381.570738 -213.51748)
		(width 0.0889)
		(layer "F.Cu")
		(net "UPI_CPU1_CPU0_P0P1_DP<2>")
	)
	(segment
		(start 381.570738 -212.90788)
		(end 381.570738 -212.75548)
		(width 0.0889)
		(layer "F.Cu")
		(net "UPI_CPU1_CPU0_P0P1_DP<2>")
	)
	(segment
		(start 381.570738 -213.51748)
		(end 381.570738 -213.31428)
		(width 0.0889)
		(layer "F.Cu")
		(net "UPI_CPU1_CPU0_P0P1_DP<2>")
	)
	(segment
		(start 381.469138 -213.00948)
		(end 381.570738 -212.90788)
		(width 0.0889)
		(layer "F.Cu")
		(net "UPI_CPU1_CPU0_P0P1_DP<2>")
	)
	(segment
		(start 377.466098 -202.343004)
		(end 377.798076 -200.67397)
		(width 0.13208)
		(layer "F.Cu")
		(net "UPI_CPU1_CPU0_P0P1_DP<2>")
	)
	(segment
		(start 377.500388 -205.261464)
		(end 377.466098 -205.227174)
		(width 0.0889)
		(layer "F.Cu")
		(net "UPI_CPU1_CPU0_P0P1_DP<2>")
	)
	(segment
		(start 372.326916 -170.173396)
		(end 371.96268 -170.329606)
		(width 0.13208)
		(layer "F.Cu")
		(net "UPI_CPU1_CPU0_P0P1_DP<2>")
	)
	(segment
		(start 381.570738 -213.92388)
		(end 381.469138 -213.82228)
		(width 0.0889)
		(layer "F.Cu")
		(net "UPI_CPU1_CPU0_P0P1_DP<2>")
	)
	(segment
		(start 371.054884 -170.42765)
		(end 370.791486 -170.274996)
		(width 0.13208)
		(layer "F.Cu")
		(net "UPI_CPU1_CPU0_P0P1_DP<2>")
	)
	(segment
		(start 376.65533 -171.519088)
		(end 376.34926 -171.267882)
		(width 0.13208)
		(layer "F.Cu")
		(net "UPI_CPU1_CPU0_P0P1_DP<2>")
	)
	(arc
		(start 381.061976 -215.509094)
		(mid 381.403686 -215.470674)
		(end 381.570738 -215.170004)
		(width 0.0889)
		(layer "F.Cu")
		(net "UPI_CPU1_CPU0_P0P1_DP<2>")
	)
	(segment
		(start 91.686634 -208.603088)
		(end 91.558618 -208.948528)
		(width 0.14732)
		(layer "In6.Cu")
		(net "UPI_CPU1_CPU0_P0P1_DP<2>")
	)
	(segment
		(start 365.3028 -166.238936)
		(end 365.018828 -166.003986)
		(width 0.14732)
		(layer "In6.Cu")
		(net "UPI_CPU1_CPU0_P0P1_DP<2>")
	)
	(segment
		(start 91.872816 -208.517998)
		(end 91.686634 -208.603088)
		(width 0.14732)
		(layer "In6.Cu")
		(net "UPI_CPU1_CPU0_P0P1_DP<2>")
	)
	(segment
		(start 366.297972 -166.873428)
		(end 366.09401 -166.892732)
		(width 0.14732)
		(layer "In6.Cu")
		(net "UPI_CPU1_CPU0_P0P1_DP<2>")
	)
	(segment
		(start 369.385088 -168.994582)
		(end 368.37493 -168.58996)
		(width 0.14732)
		(layer "In6.Cu")
		(net "UPI_CPU1_CPU0_P0P1_DP<2>")
	)
	(segment
		(start 312.23331 -139.818872)
		(end 271.480534 -138.110976)
		(width 0.14732)
		(layer "In6.Cu")
		(net "UPI_CPU1_CPU0_P0P1_DP<2>")
	)
	(segment
		(start 366.618774 -167.138604)
		(end 366.297972 -166.873428)
		(width 0.14732)
		(layer "In6.Cu")
		(net "UPI_CPU1_CPU0_P0P1_DP<2>")
	)
	(segment
		(start 367.49228 -167.860726)
		(end 367.126012 -167.558212)
		(width 0.14732)
		(layer "In6.Cu")
		(net "UPI_CPU1_CPU0_P0P1_DP<2>")
	)
	(segment
		(start 91.915996 -207.98409)
		(end 91.915488 -207.986122)
		(width 0.14732)
		(layer "In6.Cu")
		(net "UPI_CPU1_CPU0_P0P1_DP<2>")
	)
	(segment
		(start 366.922304 -167.577262)
		(end 366.638332 -167.342312)
		(width 0.14732)
		(layer "In6.Cu")
		(net "UPI_CPU1_CPU0_P0P1_DP<2>")
	)
	(segment
		(start 95.97644 -197.030594)
		(end 95.975678 -197.03288)
		(width 0.14732)
		(layer "In6.Cu")
		(net "UPI_CPU1_CPU0_P0P1_DP<2>")
	)
	(segment
		(start 91.059762 -211.835492)
		(end 91.059762 -213.93023)
		(width 0.0889)
		(layer "In6.Cu")
		(net "UPI_CPU1_CPU0_P0P1_DP<2>")
	)
	(segment
		(start 160.221676 -140.861796)
		(end 124.054108 -163.117276)
		(width 0.14732)
		(layer "In6.Cu")
		(net "UPI_CPU1_CPU0_P0P1_DP<2>")
	)
	(segment
		(start 169.709084 -137.57783)
		(end 160.221676 -140.861796)
		(width 0.14732)
		(layer "In6.Cu")
		(net "UPI_CPU1_CPU0_P0P1_DP<2>")
	)
	(segment
		(start 367.511838 -168.064434)
		(end 367.492534 -167.860472)
		(width 0.14732)
		(layer "In6.Cu")
		(net "UPI_CPU1_CPU0_P0P1_DP<2>")
	)
	(segment
		(start 271.480534 -138.110976)
		(end 238.619792 -138.698478)
		(width 0.14732)
		(layer "In6.Cu")
		(net "UPI_CPU1_CPU0_P0P1_DP<2>")
	)
	(segment
		(start 91.059762 -213.93023)
		(end 91.060016 -213.929468)
		(width 0.0889)
		(layer "In6.Cu")
		(net "UPI_CPU1_CPU0_P0P1_DP<2>")
	)
	(segment
		(start 365.018828 -166.003986)
		(end 364.99927 -165.800278)
		(width 0.14732)
		(layer "In6.Cu")
		(net "UPI_CPU1_CPU0_P0P1_DP<2>")
	)
	(segment
		(start 360.690922 -162.239706)
		(end 333.229204 -143.39951)
		(width 0.14732)
		(layer "In6.Cu")
		(net "UPI_CPU1_CPU0_P0P1_DP<2>")
	)
	(segment
		(start 91.644216 -209.13471)
		(end 91.5162 -209.48015)
		(width 0.14732)
		(layer "In6.Cu")
		(net "UPI_CPU1_CPU0_P0P1_DP<2>")
	)
	(segment
		(start 367.126012 -167.558212)
		(end 367.126266 -167.557958)
		(width 0.14732)
		(layer "In6.Cu")
		(net "UPI_CPU1_CPU0_P0P1_DP<2>")
	)
	(segment
		(start 103.414322 -182.534052)
		(end 99.574858 -187.32246)
		(width 0.14732)
		(layer "In6.Cu")
		(net "UPI_CPU1_CPU0_P0P1_DP<2>")
	)
	(segment
		(start 95.97644 -197.03034)
		(end 95.97644 -197.030594)
		(width 0.14732)
		(layer "In6.Cu")
		(net "UPI_CPU1_CPU0_P0P1_DP<2>")
	)
	(segment
		(start 95.975424 -197.033388)
		(end 91.915996 -207.98409)
		(width 0.14732)
		(layer "In6.Cu")
		(net "UPI_CPU1_CPU0_P0P1_DP<2>")
	)
	(segment
		(start 124.054108 -163.117276)
		(end 103.414322 -182.534052)
		(width 0.14732)
		(layer "In6.Cu")
		(net "UPI_CPU1_CPU0_P0P1_DP<2>")
	)
	(segment
		(start 91.101926 -211.77123)
		(end 91.101926 -211.793328)
		(width 0.0889)
		(layer "In6.Cu")
		(net "UPI_CPU1_CPU0_P0P1_DP<2>")
	)
	(segment
		(start 90.835734 -214.22487)
		(end 90.805508 -214.321644)
		(width 0.0889)
		(layer "In6.Cu")
		(net "UPI_CPU1_CPU0_P0P1_DP<2>")
	)
	(segment
		(start 370.267992 -169.38244)
		(end 370.163598 -169.201592)
		(width 0.14732)
		(layer "In6.Cu")
		(net "UPI_CPU1_CPU0_P0P1_DP<2>")
	)
	(segment
		(start 368.37493 -168.58996)
		(end 367.999518 -168.279826)
		(width 0.14732)
		(layer "In6.Cu")
		(net "UPI_CPU1_CPU0_P0P1_DP<2>")
	)
	(segment
		(start 370.163598 -169.201592)
		(end 369.909852 -169.082212)
		(width 0.14732)
		(layer "In6.Cu")
		(net "UPI_CPU1_CPU0_P0P1_DP<2>")
	)
	(segment
		(start 365.506762 -166.219632)
		(end 365.3028 -166.238936)
		(width 0.14732)
		(layer "In6.Cu")
		(net "UPI_CPU1_CPU0_P0P1_DP<2>")
	)
	(segment
		(start 365.79048 -166.454074)
		(end 365.506762 -166.219632)
		(width 0.14732)
		(layer "In6.Cu")
		(net "UPI_CPU1_CPU0_P0P1_DP<2>")
	)
	(segment
		(start 333.229204 -143.39951)
		(end 319.263522 -139.818872)
		(width 0.14732)
		(layer "In6.Cu")
		(net "UPI_CPU1_CPU0_P0P1_DP<2>")
	)
	(segment
		(start 365.809784 -166.658036)
		(end 365.79048 -166.454074)
		(width 0.14732)
		(layer "In6.Cu")
		(net "UPI_CPU1_CPU0_P0P1_DP<2>")
	)
	(segment
		(start 95.975678 -197.03288)
		(end 95.975424 -197.033388)
		(width 0.14732)
		(layer "In6.Cu")
		(net "UPI_CPU1_CPU0_P0P1_DP<2>")
	)
	(segment
		(start 238.619792 -138.698478)
		(end 238.6076 -138.698478)
		(width 0.14732)
		(layer "In6.Cu")
		(net "UPI_CPU1_CPU0_P0P1_DP<2>")
	)
	(segment
		(start 91.558618 -208.948528)
		(end 91.644216 -209.13471)
		(width 0.14732)
		(layer "In6.Cu")
		(net "UPI_CPU1_CPU0_P0P1_DP<2>")
	)
	(segment
		(start 364.99927 -165.800278)
		(end 360.690922 -162.239706)
		(width 0.14732)
		(layer "In6.Cu")
		(net "UPI_CPU1_CPU0_P0P1_DP<2>")
	)
	(segment
		(start 367.492534 -167.860472)
		(end 367.49228 -167.860726)
		(width 0.14732)
		(layer "In6.Cu")
		(net "UPI_CPU1_CPU0_P0P1_DP<2>")
	)
	(segment
		(start 91.330018 -209.56524)
		(end 91.101926 -210.180428)
		(width 0.14732)
		(layer "In6.Cu")
		(net "UPI_CPU1_CPU0_P0P1_DP<2>")
	)
	(segment
		(start 366.638332 -167.342312)
		(end 366.618774 -167.138604)
		(width 0.14732)
		(layer "In6.Cu")
		(net "UPI_CPU1_CPU0_P0P1_DP<2>")
	)
	(segment
		(start 370.122704 -169.923968)
		(end 370.267992 -169.38244)
		(width 0.14732)
		(layer "In6.Cu")
		(net "UPI_CPU1_CPU0_P0P1_DP<2>")
	)
	(segment
		(start 91.915488 -207.986122)
		(end 92.000832 -208.172304)
		(width 0.14732)
		(layer "In6.Cu")
		(net "UPI_CPU1_CPU0_P0P1_DP<2>")
	)
	(segment
		(start 99.574858 -187.32246)
		(end 95.97644 -197.03034)
		(width 0.14732)
		(layer "In6.Cu")
		(net "UPI_CPU1_CPU0_P0P1_DP<2>")
	)
	(segment
		(start 369.909852 -169.082212)
		(end 369.385088 -168.994582)
		(width 0.14732)
		(layer "In6.Cu")
		(net "UPI_CPU1_CPU0_P0P1_DP<2>")
	)
	(segment
		(start 238.6076 -138.698478)
		(end 169.709084 -137.57783)
		(width 0.14732)
		(layer "In6.Cu")
		(net "UPI_CPU1_CPU0_P0P1_DP<2>")
	)
	(segment
		(start 92.000832 -208.172304)
		(end 91.872816 -208.517998)
		(width 0.14732)
		(layer "In6.Cu")
		(net "UPI_CPU1_CPU0_P0P1_DP<2>")
	)
	(segment
		(start 367.79581 -168.299384)
		(end 367.511838 -168.064434)
		(width 0.14732)
		(layer "In6.Cu")
		(net "UPI_CPU1_CPU0_P0P1_DP<2>")
	)
	(segment
		(start 91.101926 -211.793328)
		(end 91.059762 -211.835492)
		(width 0.0889)
		(layer "In6.Cu")
		(net "UPI_CPU1_CPU0_P0P1_DP<2>")
	)
	(segment
		(start 367.126266 -167.557958)
		(end 366.922304 -167.577262)
		(width 0.14732)
		(layer "In6.Cu")
		(net "UPI_CPU1_CPU0_P0P1_DP<2>")
	)
	(segment
		(start 91.101926 -210.180428)
		(end 91.101926 -211.77123)
		(width 0.14732)
		(layer "In6.Cu")
		(net "UPI_CPU1_CPU0_P0P1_DP<2>")
	)
	(segment
		(start 90.805508 -214.321644)
		(end 90.964258 -214.622634)
		(width 0.0889)
		(layer "In6.Cu")
		(net "UPI_CPU1_CPU0_P0P1_DP<2>")
	)
	(segment
		(start 319.263522 -139.818872)
		(end 312.23331 -139.818872)
		(width 0.14732)
		(layer "In6.Cu")
		(net "UPI_CPU1_CPU0_P0P1_DP<2>")
	)
	(segment
		(start 367.999518 -168.279826)
		(end 367.79581 -168.299384)
		(width 0.14732)
		(layer "In6.Cu")
		(net "UPI_CPU1_CPU0_P0P1_DP<2>")
	)
	(segment
		(start 91.5162 -209.48015)
		(end 91.330018 -209.56524)
		(width 0.14732)
		(layer "In6.Cu")
		(net "UPI_CPU1_CPU0_P0P1_DP<2>")
	)
	(segment
		(start 366.09401 -166.892732)
		(end 365.809784 -166.658036)
		(width 0.14732)
		(layer "In6.Cu")
		(net "UPI_CPU1_CPU0_P0P1_DP<2>")
	)
	(arc
		(start 91.060016 -213.929468)
		(mid 91.052858 -213.949028)
		(end 91.04503 -213.96833)
		(width 0.0889)
		(layer "In6.Cu")
		(net "UPI_CPU1_CPU0_P0P1_DP<2>")
	)
	(arc
		(start 91.04503 -213.96833)
		(mid 90.958479 -214.111364)
		(end 90.835734 -214.22487)
		(width 0.0889)
		(layer "In6.Cu")
		(net "UPI_CPU1_CPU0_P0P1_DP<2>")
	)
	(segment
		(start 350.255078 -205.732888)
		(end 350.255078 -198.254874)
		(width 0.13208)
		(layer "F.Cu")
		(net "UPI_CPU1_CPU0_P0P1_DP<23>")
	)
	(segment
		(start 352.2472 -187.397644)
		(end 352.799904 -187.248292)
		(width 0.13208)
		(layer "F.Cu")
		(net "UPI_CPU1_CPU0_P0P1_DP<23>")
	)
	(segment
		(start 111.170466 -215.972644)
		(end 111.170466 -215.436958)
		(width 0.13208)
		(layer "F.Cu")
		(net "UPI_CPU1_CPU0_P0P1_DP<23>")
	)
	(segment
		(start 350.255078 -198.254874)
		(end 351.88398 -188.08446)
		(width 0.13208)
		(layer "F.Cu")
		(net "UPI_CPU1_CPU0_P0P1_DP<23>")
	)
	(segment
		(start 356.294436 -211.772246)
		(end 350.255078 -205.732888)
		(width 0.13208)
		(layer "F.Cu")
		(net "UPI_CPU1_CPU0_P0P1_DP<23>")
	)
	(segment
		(start 360.630724 -213.568534)
		(end 356.294436 -211.772246)
		(width 0.13208)
		(layer "F.Cu")
		(net "UPI_CPU1_CPU0_P0P1_DP<23>")
	)
	(segment
		(start 352.246692 -187.398406)
		(end 352.2472 -187.397644)
		(width 0.13208)
		(layer "F.Cu")
		(net "UPI_CPU1_CPU0_P0P1_DP<23>")
	)
	(segment
		(start 361.11942 -214.818214)
		(end 361.11942 -214.05723)
		(width 0.13208)
		(layer "F.Cu")
		(net "UPI_CPU1_CPU0_P0P1_DP<23>")
	)
	(segment
		(start 111.170466 -215.436958)
		(end 111.170212 -215.436704)
		(width 0.13208)
		(layer "F.Cu")
		(net "UPI_CPU1_CPU0_P0P1_DP<23>")
	)
	(segment
		(start 352.078036 -187.69203)
		(end 352.079052 -187.691014)
		(width 0.13208)
		(layer "F.Cu")
		(net "UPI_CPU1_CPU0_P0P1_DP<23>")
	)
	(segment
		(start 361.45978 -215.158574)
		(end 361.11942 -214.818214)
		(width 0.13208)
		(layer "F.Cu")
		(net "UPI_CPU1_CPU0_P0P1_DP<23>")
	)
	(segment
		(start 352.079052 -187.691014)
		(end 352.246692 -187.398406)
		(width 0.13208)
		(layer "F.Cu")
		(net "UPI_CPU1_CPU0_P0P1_DP<23>")
	)
	(segment
		(start 351.88398 -188.08446)
		(end 352.078036 -187.69203)
		(width 0.13208)
		(layer "F.Cu")
		(net "UPI_CPU1_CPU0_P0P1_DP<23>")
	)
	(segment
		(start 361.11942 -214.05723)
		(end 360.630724 -213.568534)
		(width 0.13208)
		(layer "F.Cu")
		(net "UPI_CPU1_CPU0_P0P1_DP<23>")
	)
	(segment
		(start 227.228908 -163.566602)
		(end 226.854258 -163.345368)
		(width 0.14732)
		(layer "In6.Cu")
		(net "UPI_CPU1_CPU0_P0P1_DP<23>")
	)
	(segment
		(start 127.1143 -185.985404)
		(end 126.519432 -186.546998)
		(width 0.14732)
		(layer "In6.Cu")
		(net "UPI_CPU1_CPU0_P0P1_DP<23>")
	)
	(segment
		(start 226.854258 -163.345368)
		(end 226.24669 -160.98901)
		(width 0.14732)
		(layer "In6.Cu")
		(net "UPI_CPU1_CPU0_P0P1_DP<23>")
	)
	(segment
		(start 212.78215 -164.460682)
		(end 212.60308 -164.354764)
		(width 0.14732)
		(layer "In6.Cu")
		(net "UPI_CPU1_CPU0_P0P1_DP<23>")
	)
	(segment
		(start 111.011462 -215.135714)
		(end 111.170212 -215.436704)
		(width 0.0889)
		(layer "In6.Cu")
		(net "UPI_CPU1_CPU0_P0P1_DP<23>")
	)
	(segment
		(start 130.48488 -182.8038)
		(end 129.890012 -183.365394)
		(width 0.14732)
		(layer "In6.Cu")
		(net "UPI_CPU1_CPU0_P0P1_DP<23>")
	)
	(segment
		(start 132.013198 -180.598064)
		(end 132.18287 -180.777896)
		(width 0.14732)
		(layer "In6.Cu")
		(net "UPI_CPU1_CPU0_P0P1_DP<23>")
	)
	(segment
		(start 111.96701 -210.017106)
		(end 111.811054 -210.091274)
		(width 0.14732)
		(layer "In6.Cu")
		(net "UPI_CPU1_CPU0_P0P1_DP<23>")
	)
	(segment
		(start 149.307042 -170.58005)
		(end 134.28726 -178.250088)
		(width 0.14732)
		(layer "In6.Cu")
		(net "UPI_CPU1_CPU0_P0P1_DP<23>")
	)
	(segment
		(start 125.706886 -186.348624)
		(end 123.825 -188.124846)
		(width 0.14732)
		(layer "In6.Cu")
		(net "UPI_CPU1_CPU0_P0P1_DP<23>")
	)
	(segment
		(start 130.970782 -181.58206)
		(end 130.762756 -181.576218)
		(width 0.14732)
		(layer "In6.Cu")
		(net "UPI_CPU1_CPU0_P0P1_DP<23>")
	)
	(segment
		(start 128.642618 -183.779668)
		(end 128.81229 -183.9595)
		(width 0.14732)
		(layer "In6.Cu")
		(net "UPI_CPU1_CPU0_P0P1_DP<23>")
	)
	(segment
		(start 351.415096 -188.668406)
		(end 350.75368 -189.329568)
		(width 0.14732)
		(layer "In6.Cu")
		(net "UPI_CPU1_CPU0_P0P1_DP<23>")
	)
	(segment
		(start 213.764368 -167.038274)
		(end 213.389718 -166.81704)
		(width 0.14732)
		(layer "In6.Cu")
		(net "UPI_CPU1_CPU0_P0P1_DP<23>")
	)
	(segment
		(start 217.09126 -163.19754)
		(end 216.520268 -163.345114)
		(width 0.14732)
		(layer "In6.Cu")
		(net "UPI_CPU1_CPU0_P0P1_DP<23>")
	)
	(segment
		(start 218.65844 -162.945572)
		(end 219.266008 -165.30193)
		(width 0.14732)
		(layer "In6.Cu")
		(net "UPI_CPU1_CPU0_P0P1_DP<23>")
	)
	(segment
		(start 228.021134 -163.362132)
		(end 227.228908 -163.566602)
		(width 0.14732)
		(layer "In6.Cu")
		(net "UPI_CPU1_CPU0_P0P1_DP<23>")
	)
	(segment
		(start 112.112552 -209.604864)
		(end 111.96701 -210.017106)
		(width 0.14732)
		(layer "In6.Cu")
		(net "UPI_CPU1_CPU0_P0P1_DP<23>")
	)
	(segment
		(start 129.455164 -183.352694)
		(end 129.285492 -183.172862)
		(width 0.14732)
		(layer "In6.Cu")
		(net "UPI_CPU1_CPU0_P0P1_DP<23>")
	)
	(segment
		(start 128.81229 -183.9595)
		(end 128.79959 -184.394602)
		(width 0.14732)
		(layer "In6.Cu")
		(net "UPI_CPU1_CPU0_P0P1_DP<23>")
	)
	(segment
		(start 223.252538 -161.609278)
		(end 223.14662 -161.788348)
		(width 0.14732)
		(layer "In6.Cu")
		(net "UPI_CPU1_CPU0_P0P1_DP<23>")
	)
	(segment
		(start 225.998278 -163.566094)
		(end 225.777044 -163.940744)
		(width 0.14732)
		(layer "In6.Cu")
		(net "UPI_CPU1_CPU0_P0P1_DP<23>")
	)
	(segment
		(start 214.777828 -166.459154)
		(end 214.556594 -166.833804)
		(width 0.14732)
		(layer "In6.Cu")
		(net "UPI_CPU1_CPU0_P0P1_DP<23>")
	)
	(segment
		(start 314.30976 -168.057068)
		(end 302.4886 -167.815768)
		(width 0.14732)
		(layer "In6.Cu")
		(net "UPI_CPU1_CPU0_P0P1_DP<23>")
	)
	(segment
		(start 280.284428 -168.19372)
		(end 274.470876 -168.19372)
		(width 0.14732)
		(layer "In6.Cu")
		(net "UPI_CPU1_CPU0_P0P1_DP<23>")
	)
	(segment
		(start 228.242368 -162.987482)
		(end 228.021134 -163.362132)
		(width 0.14732)
		(layer "In6.Cu")
		(net "UPI_CPU1_CPU0_P0P1_DP<23>")
	)
	(segment
		(start 199.654668 -167.693086)
		(end 195.166996 -168.270428)
		(width 0.14732)
		(layer "In6.Cu")
		(net "UPI_CPU1_CPU0_P0P1_DP<23>")
	)
	(segment
		(start 111.265462 -214.745062)
		(end 111.265716 -214.7443)
		(width 0.0889)
		(layer "In6.Cu")
		(net "UPI_CPU1_CPU0_P0P1_DP<23>")
	)
	(segment
		(start 125.914912 -186.354466)
		(end 125.706886 -186.348624)
		(width 0.14732)
		(layer "In6.Cu")
		(net "UPI_CPU1_CPU0_P0P1_DP<23>")
	)
	(segment
		(start 227.740718 -160.452054)
		(end 227.6348 -160.631124)
		(width 0.14732)
		(layer "In6.Cu")
		(net "UPI_CPU1_CPU0_P0P1_DP<23>")
	)
	(segment
		(start 116.259102 -197.514972)
		(end 112.038384 -209.449416)
		(width 0.14732)
		(layer "In6.Cu")
		(net "UPI_CPU1_CPU0_P0P1_DP<23>")
	)
	(segment
		(start 214.84717 -163.776152)
		(end 214.276178 -163.923726)
		(width 0.14732)
		(layer "In6.Cu")
		(net "UPI_CPU1_CPU0_P0P1_DP<23>")
	)
	(segment
		(start 129.890012 -183.365394)
		(end 129.455164 -183.352694)
		(width 0.14732)
		(layer "In6.Cu")
		(net "UPI_CPU1_CPU0_P0P1_DP<23>")
	)
	(segment
		(start 221.57944 -162.040316)
		(end 221.008448 -162.18789)
		(width 0.14732)
		(layer "In6.Cu")
		(net "UPI_CPU1_CPU0_P0P1_DP<23>")
	)
	(segment
		(start 212.60308 -164.354764)
		(end 199.654668 -167.693086)
		(width 0.14732)
		(layer "In6.Cu")
		(net "UPI_CPU1_CPU0_P0P1_DP<23>")
	)
	(segment
		(start 342.624156 -182.11927)
		(end 338.392516 -179.07889)
		(width 0.14732)
		(layer "In6.Cu")
		(net "UPI_CPU1_CPU0_P0P1_DP<23>")
	)
	(segment
		(start 127.600202 -184.763664)
		(end 127.392176 -184.757822)
		(width 0.14732)
		(layer "In6.Cu")
		(net "UPI_CPU1_CPU0_P0P1_DP<23>")
	)
	(segment
		(start 111.307626 -211.51469)
		(end 111.307626 -211.64423)
		(width 0.14732)
		(layer "In6.Cu")
		(net "UPI_CPU1_CPU0_P0P1_DP<23>")
	)
	(segment
		(start 220.121988 -165.081204)
		(end 219.51442 -162.724846)
		(width 0.14732)
		(layer "In6.Cu")
		(net "UPI_CPU1_CPU0_P0P1_DP<23>")
	)
	(segment
		(start 129.077466 -183.16702)
		(end 128.64846 -183.571642)
		(width 0.14732)
		(layer "In6.Cu")
		(net "UPI_CPU1_CPU0_P0P1_DP<23>")
	)
	(segment
		(start 111.307626 -211.655406)
		(end 111.265462 -211.69757)
		(width 0.0889)
		(layer "In6.Cu")
		(net "UPI_CPU1_CPU0_P0P1_DP<23>")
	)
	(segment
		(start 351.92843 -187.962286)
		(end 351.415096 -188.668406)
		(width 0.14732)
		(layer "In6.Cu")
		(net "UPI_CPU1_CPU0_P0P1_DP<23>")
	)
	(segment
		(start 218.764358 -162.766502)
		(end 218.65844 -162.945572)
		(width 0.14732)
		(layer "In6.Cu")
		(net "UPI_CPU1_CPU0_P0P1_DP<23>")
	)
	(segment
		(start 128.79959 -184.394602)
		(end 128.204722 -184.956196)
		(width 0.14732)
		(layer "In6.Cu")
		(net "UPI_CPU1_CPU0_P0P1_DP<23>")
	)
	(segment
		(start 111.265462 -211.69757)
		(end 111.265462 -214.745062)
		(width 0.0889)
		(layer "In6.Cu")
		(net "UPI_CPU1_CPU0_P0P1_DP<23>")
	)
	(segment
		(start 217.27033 -163.303458)
		(end 217.09126 -163.19754)
		(width 0.14732)
		(layer "In6.Cu")
		(net "UPI_CPU1_CPU0_P0P1_DP<23>")
	)
	(segment
		(start 223.532954 -164.519356)
		(end 222.740728 -164.723826)
		(width 0.14732)
		(layer "In6.Cu")
		(net "UPI_CPU1_CPU0_P0P1_DP<23>")
	)
	(segment
		(start 215.633808 -166.238428)
		(end 215.02624 -163.88207)
		(width 0.14732)
		(layer "In6.Cu")
		(net "UPI_CPU1_CPU0_P0P1_DP<23>")
	)
	(segment
		(start 111.430562 -211.167218)
		(end 111.307626 -211.51469)
		(width 0.14732)
		(layer "In6.Cu")
		(net "UPI_CPU1_CPU0_P0P1_DP<23>")
	)
	(segment
		(start 274.470876 -168.19372)
		(end 236.019848 -158.317692)
		(width 0.14732)
		(layer "In6.Cu")
		(net "UPI_CPU1_CPU0_P0P1_DP<23>")
	)
	(segment
		(start 213.389718 -166.81704)
		(end 212.78215 -164.460682)
		(width 0.14732)
		(layer "In6.Cu")
		(net "UPI_CPU1_CPU0_P0P1_DP<23>")
	)
	(segment
		(start 223.82353 -161.461704)
		(end 223.252538 -161.609278)
		(width 0.14732)
		(layer "In6.Cu")
		(net "UPI_CPU1_CPU0_P0P1_DP<23>")
	)
	(segment
		(start 221.75851 -162.146234)
		(end 221.57944 -162.040316)
		(width 0.14732)
		(layer "In6.Cu")
		(net "UPI_CPU1_CPU0_P0P1_DP<23>")
	)
	(segment
		(start 111.307626 -211.64423)
		(end 111.307626 -211.655406)
		(width 0.0889)
		(layer "In6.Cu")
		(net "UPI_CPU1_CPU0_P0P1_DP<23>")
	)
	(segment
		(start 350.75368 -189.329568)
		(end 350.140778 -189.329568)
		(width 0.14732)
		(layer "In6.Cu")
		(net "UPI_CPU1_CPU0_P0P1_DP<23>")
	)
	(segment
		(start 195.166996 -168.270428)
		(end 189.352682 -168.270428)
		(width 0.14732)
		(layer "In6.Cu")
		(net "UPI_CPU1_CPU0_P0P1_DP<23>")
	)
	(segment
		(start 130.49758 -182.368698)
		(end 130.48488 -182.8038)
		(width 0.14732)
		(layer "In6.Cu")
		(net "UPI_CPU1_CPU0_P0P1_DP<23>")
	)
	(segment
		(start 111.738156 -210.731862)
		(end 111.61522 -211.079334)
		(width 0.14732)
		(layer "In6.Cu")
		(net "UPI_CPU1_CPU0_P0P1_DP<23>")
	)
	(segment
		(start 189.352682 -168.270428)
		(end 155.458414 -169.02811)
		(width 0.14732)
		(layer "In6.Cu")
		(net "UPI_CPU1_CPU0_P0P1_DP<23>")
	)
	(segment
		(start 214.276178 -163.923726)
		(end 214.17026 -164.102796)
		(width 0.14732)
		(layer "In6.Cu")
		(net "UPI_CPU1_CPU0_P0P1_DP<23>")
	)
	(segment
		(start 126.957328 -185.37047)
		(end 127.127 -185.550302)
		(width 0.14732)
		(layer "In6.Cu")
		(net "UPI_CPU1_CPU0_P0P1_DP<23>")
	)
	(segment
		(start 352.799904 -187.248292)
		(end 352.259392 -187.393072)
		(width 0.14732)
		(layer "In6.Cu")
		(net "UPI_CPU1_CPU0_P0P1_DP<23>")
	)
	(segment
		(start 128.204722 -184.956196)
		(end 127.769874 -184.943496)
		(width 0.14732)
		(layer "In6.Cu")
		(net "UPI_CPU1_CPU0_P0P1_DP<23>")
	)
	(segment
		(start 134.28726 -178.250088)
		(end 132.01904 -180.390292)
		(width 0.14732)
		(layer "In6.Cu")
		(net "UPI_CPU1_CPU0_P0P1_DP<23>")
	)
	(segment
		(start 214.556594 -166.833804)
		(end 213.764368 -167.038274)
		(width 0.14732)
		(layer "In6.Cu")
		(net "UPI_CPU1_CPU0_P0P1_DP<23>")
	)
	(segment
		(start 126.084584 -186.534298)
		(end 125.914912 -186.354466)
		(width 0.14732)
		(layer "In6.Cu")
		(net "UPI_CPU1_CPU0_P0P1_DP<23>")
	)
	(segment
		(start 111.650018 -210.547204)
		(end 111.738156 -210.731862)
		(width 0.14732)
		(layer "In6.Cu")
		(net "UPI_CPU1_CPU0_P0P1_DP<23>")
	)
	(segment
		(start 225.39071 -161.209736)
		(end 225.998278 -163.566094)
		(width 0.14732)
		(layer "In6.Cu")
		(net "UPI_CPU1_CPU0_P0P1_DP<23>")
	)
	(segment
		(start 351.93097 -187.961778)
		(end 351.92843 -187.962286)
		(width 0.14732)
		(layer "In6.Cu")
		(net "UPI_CPU1_CPU0_P0P1_DP<23>")
	)
	(segment
		(start 225.777044 -163.940744)
		(end 224.984818 -164.145214)
		(width 0.14732)
		(layer "In6.Cu")
		(net "UPI_CPU1_CPU0_P0P1_DP<23>")
	)
	(segment
		(start 224.610168 -163.92398)
		(end 224.0026 -161.567622)
		(width 0.14732)
		(layer "In6.Cu")
		(net "UPI_CPU1_CPU0_P0P1_DP<23>")
	)
	(segment
		(start 302.4886 -167.815768)
		(end 280.284428 -168.19372)
		(width 0.14732)
		(layer "In6.Cu")
		(net "UPI_CPU1_CPU0_P0P1_DP<23>")
	)
	(segment
		(start 217.021918 -165.880542)
		(end 216.800684 -166.255192)
		(width 0.14732)
		(layer "In6.Cu")
		(net "UPI_CPU1_CPU0_P0P1_DP<23>")
	)
	(segment
		(start 216.41435 -163.524184)
		(end 217.021918 -165.880542)
		(width 0.14732)
		(layer "In6.Cu")
		(net "UPI_CPU1_CPU0_P0P1_DP<23>")
	)
	(segment
		(start 126.519432 -186.546998)
		(end 126.084584 -186.534298)
		(width 0.14732)
		(layer "In6.Cu")
		(net "UPI_CPU1_CPU0_P0P1_DP<23>")
	)
	(segment
		(start 236.019848 -158.317692)
		(end 227.740718 -160.452054)
		(width 0.14732)
		(layer "In6.Cu")
		(net "UPI_CPU1_CPU0_P0P1_DP<23>")
	)
	(segment
		(start 130.762756 -181.576218)
		(end 130.33375 -181.98084)
		(width 0.14732)
		(layer "In6.Cu")
		(net "UPI_CPU1_CPU0_P0P1_DP<23>")
	)
	(segment
		(start 220.90253 -162.36696)
		(end 221.510098 -164.723318)
		(width 0.14732)
		(layer "In6.Cu")
		(net "UPI_CPU1_CPU0_P0P1_DP<23>")
	)
	(segment
		(start 132.17017 -181.212998)
		(end 131.575302 -181.774592)
		(width 0.14732)
		(layer "In6.Cu")
		(net "UPI_CPU1_CPU0_P0P1_DP<23>")
	)
	(segment
		(start 217.877898 -165.659816)
		(end 217.27033 -163.303458)
		(width 0.14732)
		(layer "In6.Cu")
		(net "UPI_CPU1_CPU0_P0P1_DP<23>")
	)
	(segment
		(start 216.800684 -166.255192)
		(end 216.008458 -166.459662)
		(width 0.14732)
		(layer "In6.Cu")
		(net "UPI_CPU1_CPU0_P0P1_DP<23>")
	)
	(segment
		(start 221.510098 -164.723318)
		(end 221.288864 -165.097968)
		(width 0.14732)
		(layer "In6.Cu")
		(net "UPI_CPU1_CPU0_P0P1_DP<23>")
	)
	(segment
		(start 226.24669 -160.98901)
		(end 226.06762 -160.883092)
		(width 0.14732)
		(layer "In6.Cu")
		(net "UPI_CPU1_CPU0_P0P1_DP<23>")
	)
	(segment
		(start 219.266008 -165.30193)
		(end 219.044774 -165.67658)
		(width 0.14732)
		(layer "In6.Cu")
		(net "UPI_CPU1_CPU0_P0P1_DP<23>")
	)
	(segment
		(start 129.285492 -183.172862)
		(end 129.077466 -183.16702)
		(width 0.14732)
		(layer "In6.Cu")
		(net "UPI_CPU1_CPU0_P0P1_DP<23>")
	)
	(segment
		(start 222.366078 -164.502592)
		(end 221.75851 -162.146234)
		(width 0.14732)
		(layer "In6.Cu")
		(net "UPI_CPU1_CPU0_P0P1_DP<23>")
	)
	(segment
		(start 222.740728 -164.723826)
		(end 222.366078 -164.502592)
		(width 0.14732)
		(layer "In6.Cu")
		(net "UPI_CPU1_CPU0_P0P1_DP<23>")
	)
	(segment
		(start 226.06762 -160.883092)
		(end 225.496628 -161.030666)
		(width 0.14732)
		(layer "In6.Cu")
		(net "UPI_CPU1_CPU0_P0P1_DP<23>")
	)
	(segment
		(start 155.458414 -169.02811)
		(end 149.307042 -170.58005)
		(width 0.14732)
		(layer "In6.Cu")
		(net "UPI_CPU1_CPU0_P0P1_DP<23>")
	)
	(segment
		(start 131.140454 -181.761892)
		(end 130.970782 -181.58206)
		(width 0.14732)
		(layer "In6.Cu")
		(net "UPI_CPU1_CPU0_P0P1_DP<23>")
	)
	(segment
		(start 128.64846 -183.571642)
		(end 128.642618 -183.779668)
		(width 0.14732)
		(layer "In6.Cu")
		(net "UPI_CPU1_CPU0_P0P1_DP<23>")
	)
	(segment
		(start 219.51442 -162.724846)
		(end 219.33535 -162.618928)
		(width 0.14732)
		(layer "In6.Cu")
		(net "UPI_CPU1_CPU0_P0P1_DP<23>")
	)
	(segment
		(start 352.259392 -187.393072)
		(end 351.93097 -187.961778)
		(width 0.14732)
		(layer "In6.Cu")
		(net "UPI_CPU1_CPU0_P0P1_DP<23>")
	)
	(segment
		(start 127.769874 -184.943496)
		(end 127.600202 -184.763664)
		(width 0.14732)
		(layer "In6.Cu")
		(net "UPI_CPU1_CPU0_P0P1_DP<23>")
	)
	(segment
		(start 111.61522 -211.079334)
		(end 111.430562 -211.167218)
		(width 0.14732)
		(layer "In6.Cu")
		(net "UPI_CPU1_CPU0_P0P1_DP<23>")
	)
	(segment
		(start 338.392516 -179.07889)
		(end 320.966846 -169.935652)
		(width 0.14732)
		(layer "In6.Cu")
		(net "UPI_CPU1_CPU0_P0P1_DP<23>")
	)
	(segment
		(start 220.496638 -165.302438)
		(end 220.121988 -165.081204)
		(width 0.14732)
		(layer "In6.Cu")
		(net "UPI_CPU1_CPU0_P0P1_DP<23>")
	)
	(segment
		(start 225.496628 -161.030666)
		(end 225.39071 -161.209736)
		(width 0.14732)
		(layer "In6.Cu")
		(net "UPI_CPU1_CPU0_P0P1_DP<23>")
	)
	(segment
		(start 350.140778 -189.329568)
		(end 342.624156 -182.11927)
		(width 0.14732)
		(layer "In6.Cu")
		(net "UPI_CPU1_CPU0_P0P1_DP<23>")
	)
	(segment
		(start 221.288864 -165.097968)
		(end 220.496638 -165.302438)
		(width 0.14732)
		(layer "In6.Cu")
		(net "UPI_CPU1_CPU0_P0P1_DP<23>")
	)
	(segment
		(start 215.02624 -163.88207)
		(end 214.84717 -163.776152)
		(width 0.14732)
		(layer "In6.Cu")
		(net "UPI_CPU1_CPU0_P0P1_DP<23>")
	)
	(segment
		(start 111.811054 -210.091274)
		(end 111.650018 -210.547204)
		(width 0.14732)
		(layer "In6.Cu")
		(net "UPI_CPU1_CPU0_P0P1_DP<23>")
	)
	(segment
		(start 218.252548 -165.88105)
		(end 217.877898 -165.659816)
		(width 0.14732)
		(layer "In6.Cu")
		(net "UPI_CPU1_CPU0_P0P1_DP<23>")
	)
	(segment
		(start 112.038384 -209.449416)
		(end 112.112552 -209.604864)
		(width 0.14732)
		(layer "In6.Cu")
		(net "UPI_CPU1_CPU0_P0P1_DP<23>")
	)
	(segment
		(start 111.041688 -215.038686)
		(end 111.011462 -215.135714)
		(width 0.0889)
		(layer "In6.Cu")
		(net "UPI_CPU1_CPU0_P0P1_DP<23>")
	)
	(segment
		(start 131.575302 -181.774592)
		(end 131.140454 -181.761892)
		(width 0.14732)
		(layer "In6.Cu")
		(net "UPI_CPU1_CPU0_P0P1_DP<23>")
	)
	(segment
		(start 219.33535 -162.618928)
		(end 218.764358 -162.766502)
		(width 0.14732)
		(layer "In6.Cu")
		(net "UPI_CPU1_CPU0_P0P1_DP<23>")
	)
	(segment
		(start 221.008448 -162.18789)
		(end 220.90253 -162.36696)
		(width 0.14732)
		(layer "In6.Cu")
		(net "UPI_CPU1_CPU0_P0P1_DP<23>")
	)
	(segment
		(start 216.520268 -163.345114)
		(end 216.41435 -163.524184)
		(width 0.14732)
		(layer "In6.Cu")
		(net "UPI_CPU1_CPU0_P0P1_DP<23>")
	)
	(segment
		(start 219.044774 -165.67658)
		(end 218.252548 -165.88105)
		(width 0.14732)
		(layer "In6.Cu")
		(net "UPI_CPU1_CPU0_P0P1_DP<23>")
	)
	(segment
		(start 223.14662 -161.788348)
		(end 223.754188 -164.144706)
		(width 0.14732)
		(layer "In6.Cu")
		(net "UPI_CPU1_CPU0_P0P1_DP<23>")
	)
	(segment
		(start 130.327908 -182.188866)
		(end 130.49758 -182.368698)
		(width 0.14732)
		(layer "In6.Cu")
		(net "UPI_CPU1_CPU0_P0P1_DP<23>")
	)
	(segment
		(start 132.18287 -180.777896)
		(end 132.17017 -181.212998)
		(width 0.14732)
		(layer "In6.Cu")
		(net "UPI_CPU1_CPU0_P0P1_DP<23>")
	)
	(segment
		(start 126.96317 -185.162444)
		(end 126.957328 -185.37047)
		(width 0.14732)
		(layer "In6.Cu")
		(net "UPI_CPU1_CPU0_P0P1_DP<23>")
	)
	(segment
		(start 214.17026 -164.102796)
		(end 214.777828 -166.459154)
		(width 0.14732)
		(layer "In6.Cu")
		(net "UPI_CPU1_CPU0_P0P1_DP<23>")
	)
	(segment
		(start 132.01904 -180.390292)
		(end 132.013198 -180.598064)
		(width 0.14732)
		(layer "In6.Cu")
		(net "UPI_CPU1_CPU0_P0P1_DP<23>")
	)
	(segment
		(start 223.754188 -164.144706)
		(end 223.532954 -164.519356)
		(width 0.14732)
		(layer "In6.Cu")
		(net "UPI_CPU1_CPU0_P0P1_DP<23>")
	)
	(segment
		(start 130.33375 -181.98084)
		(end 130.327908 -182.188866)
		(width 0.14732)
		(layer "In6.Cu")
		(net "UPI_CPU1_CPU0_P0P1_DP<23>")
	)
	(segment
		(start 216.008458 -166.459662)
		(end 215.633808 -166.238428)
		(width 0.14732)
		(layer "In6.Cu")
		(net "UPI_CPU1_CPU0_P0P1_DP<23>")
	)
	(segment
		(start 224.0026 -161.567622)
		(end 223.82353 -161.461704)
		(width 0.14732)
		(layer "In6.Cu")
		(net "UPI_CPU1_CPU0_P0P1_DP<23>")
	)
	(segment
		(start 127.127 -185.550302)
		(end 127.1143 -185.985404)
		(width 0.14732)
		(layer "In6.Cu")
		(net "UPI_CPU1_CPU0_P0P1_DP<23>")
	)
	(segment
		(start 127.392176 -184.757822)
		(end 126.96317 -185.162444)
		(width 0.14732)
		(layer "In6.Cu")
		(net "UPI_CPU1_CPU0_P0P1_DP<23>")
	)
	(segment
		(start 123.825 -188.124846)
		(end 116.259102 -197.514972)
		(width 0.14732)
		(layer "In6.Cu")
		(net "UPI_CPU1_CPU0_P0P1_DP<23>")
	)
	(segment
		(start 227.6348 -160.631124)
		(end 228.242368 -162.987482)
		(width 0.14732)
		(layer "In6.Cu")
		(net "UPI_CPU1_CPU0_P0P1_DP<23>")
	)
	(segment
		(start 224.984818 -164.145214)
		(end 224.610168 -163.92398)
		(width 0.14732)
		(layer "In6.Cu")
		(net "UPI_CPU1_CPU0_P0P1_DP<23>")
	)
	(segment
		(start 320.966846 -169.935652)
		(end 314.30976 -168.057068)
		(width 0.14732)
		(layer "In6.Cu")
		(net "UPI_CPU1_CPU0_P0P1_DP<23>")
	)
	(arc
		(start 111.250984 -214.7824)
		(mid 111.164377 -214.925273)
		(end 111.041688 -215.038686)
		(width 0.0889)
		(layer "In6.Cu")
		(net "UPI_CPU1_CPU0_P0P1_DP<23>")
	)
	(arc
		(start 111.265716 -214.7443)
		(mid 111.258674 -214.763475)
		(end 111.250984 -214.7824)
		(width 0.0889)
		(layer "In6.Cu")
		(net "UPI_CPU1_CPU0_P0P1_DP<23>")
	)
	(segment
		(start 349.942404 -182.825644)
		(end 349.941896 -182.824882)
		(width 0.13208)
		(layer "F.Cu")
		(net "UPI_CPU1_CPU0_P0P1_DP<22>")
	)
	(segment
		(start 350.096328 -183.093106)
		(end 349.942404 -182.825898)
		(width 0.13208)
		(layer "F.Cu")
		(net "UPI_CPU1_CPU0_P0P1_DP<22>")
	)
	(segment
		(start 351.563178 -205.205076)
		(end 351.563178 -198.505318)
		(width 0.13208)
		(layer "F.Cu")
		(net "UPI_CPU1_CPU0_P0P1_DP<22>")
	)
	(segment
		(start 362.091986 -214.537036)
		(end 361.992926 -214.437976)
		(width 0.0889)
		(layer "F.Cu")
		(net "UPI_CPU1_CPU0_P0P1_DP<22>")
	)
	(segment
		(start 361.992926 -213.935056)
		(end 361.992926 -213.535006)
		(width 0.0889)
		(layer "F.Cu")
		(net "UPI_CPU1_CPU0_P0P1_DP<22>")
	)
	(segment
		(start 362.091986 -214.034116)
		(end 361.992926 -213.935056)
		(width 0.0889)
		(layer "F.Cu")
		(net "UPI_CPU1_CPU0_P0P1_DP<22>")
	)
	(segment
		(start 353.686872 -190.41491)
		(end 354.592382 -188.225684)
		(width 0.13208)
		(layer "F.Cu")
		(net "UPI_CPU1_CPU0_P0P1_DP<22>")
	)
	(segment
		(start 352.563176 -185.560208)
		(end 350.096328 -183.093106)
		(width 0.13208)
		(layer "F.Cu")
		(net "UPI_CPU1_CPU0_P0P1_DP<22>")
	)
	(segment
		(start 362.24464 -215.42756)
		(end 362.163614 -215.44915)
		(width 0.0889)
		(layer "F.Cu")
		(net "UPI_CPU1_CPU0_P0P1_DP<22>")
	)
	(segment
		(start 351.728024 -197.676516)
		(end 352.44913 -194.04711)
		(width 0.13208)
		(layer "F.Cu")
		(net "UPI_CPU1_CPU0_P0P1_DP<22>")
	)
	(segment
		(start 351.563178 -205.227174)
		(end 351.563178 -205.205076)
		(width 0.0889)
		(layer "F.Cu")
		(net "UPI_CPU1_CPU0_P0P1_DP<22>")
	)
	(segment
		(start 109.290866 -215.436958)
		(end 109.290612 -215.436704)
		(width 0.13208)
		(layer "F.Cu")
		(net "UPI_CPU1_CPU0_P0P1_DP<22>")
	)
	(segment
		(start 354.592382 -188.225684)
		(end 354.592382 -187.333382)
		(width 0.13208)
		(layer "F.Cu")
		(net "UPI_CPU1_CPU0_P0P1_DP<22>")
	)
	(segment
		(start 357.316786 -211.243164)
		(end 351.528634 -205.455266)
		(width 0.0889)
		(layer "F.Cu")
		(net "UPI_CPU1_CPU0_P0P1_DP<22>")
	)
	(segment
		(start 351.528634 -205.455266)
		(end 351.528634 -205.261718)
		(width 0.0889)
		(layer "F.Cu")
		(net "UPI_CPU1_CPU0_P0P1_DP<22>")
	)
	(segment
		(start 354.049838 -186.573668)
		(end 352.563176 -185.560208)
		(width 0.13208)
		(layer "F.Cu")
		(net "UPI_CPU1_CPU0_P0P1_DP<22>")
	)
	(segment
		(start 362.091986 -214.186516)
		(end 362.091986 -214.034116)
		(width 0.0889)
		(layer "F.Cu")
		(net "UPI_CPU1_CPU0_P0P1_DP<22>")
	)
	(segment
		(start 361.992926 -214.900764)
		(end 361.992926 -214.788496)
		(width 0.0889)
		(layer "F.Cu")
		(net "UPI_CPU1_CPU0_P0P1_DP<22>")
	)
	(segment
		(start 349.941896 -182.824882)
		(end 350.089724 -182.272432)
		(width 0.13208)
		(layer "F.Cu")
		(net "UPI_CPU1_CPU0_P0P1_DP<22>")
	)
	(segment
		(start 361.388914 -212.930994)
		(end 357.316786 -211.243164)
		(width 0.0889)
		(layer "F.Cu")
		(net "UPI_CPU1_CPU0_P0P1_DP<22>")
	)
	(segment
		(start 354.592382 -187.333382)
		(end 354.42906 -186.939174)
		(width 0.13208)
		(layer "F.Cu")
		(net "UPI_CPU1_CPU0_P0P1_DP<22>")
	)
	(segment
		(start 362.399834 -215.158574)
		(end 362.24464 -215.42756)
		(width 0.0889)
		(layer "F.Cu")
		(net "UPI_CPU1_CPU0_P0P1_DP<22>")
	)
	(segment
		(start 362.025184 -214.933022)
		(end 361.992926 -214.900764)
		(width 0.0889)
		(layer "F.Cu")
		(net "UPI_CPU1_CPU0_P0P1_DP<22>")
	)
	(segment
		(start 361.992926 -214.788496)
		(end 362.091986 -214.689436)
		(width 0.0889)
		(layer "F.Cu")
		(net "UPI_CPU1_CPU0_P0P1_DP<22>")
	)
	(segment
		(start 351.528634 -205.261718)
		(end 351.563178 -205.227174)
		(width 0.0889)
		(layer "F.Cu")
		(net "UPI_CPU1_CPU0_P0P1_DP<22>")
	)
	(segment
		(start 352.69424 -192.813432)
		(end 353.686618 -190.415164)
		(width 0.13208)
		(layer "F.Cu")
		(net "UPI_CPU1_CPU0_P0P1_DP<22>")
	)
	(segment
		(start 354.42906 -186.939174)
		(end 354.049838 -186.573668)
		(width 0.13208)
		(layer "F.Cu")
		(net "UPI_CPU1_CPU0_P0P1_DP<22>")
	)
	(segment
		(start 109.290866 -215.972644)
		(end 109.290866 -215.436958)
		(width 0.13208)
		(layer "F.Cu")
		(net "UPI_CPU1_CPU0_P0P1_DP<22>")
	)
	(segment
		(start 352.44913 -194.04711)
		(end 352.69424 -192.813432)
		(width 0.13208)
		(layer "F.Cu")
		(net "UPI_CPU1_CPU0_P0P1_DP<22>")
	)
	(segment
		(start 361.992926 -214.285576)
		(end 362.091986 -214.186516)
		(width 0.0889)
		(layer "F.Cu")
		(net "UPI_CPU1_CPU0_P0P1_DP<22>")
	)
	(segment
		(start 362.091986 -214.689436)
		(end 362.091986 -214.537036)
		(width 0.0889)
		(layer "F.Cu")
		(net "UPI_CPU1_CPU0_P0P1_DP<22>")
	)
	(segment
		(start 349.942404 -182.825898)
		(end 349.942404 -182.825644)
		(width 0.13208)
		(layer "F.Cu")
		(net "UPI_CPU1_CPU0_P0P1_DP<22>")
	)
	(segment
		(start 351.563178 -198.505318)
		(end 351.728024 -197.676516)
		(width 0.13208)
		(layer "F.Cu")
		(net "UPI_CPU1_CPU0_P0P1_DP<22>")
	)
	(segment
		(start 362.025184 -215.158828)
		(end 362.025184 -214.933022)
		(width 0.0889)
		(layer "F.Cu")
		(net "UPI_CPU1_CPU0_P0P1_DP<22>")
	)
	(segment
		(start 361.992926 -214.437976)
		(end 361.992926 -214.285576)
		(width 0.0889)
		(layer "F.Cu")
		(net "UPI_CPU1_CPU0_P0P1_DP<22>")
	)
	(segment
		(start 353.686618 -190.415164)
		(end 353.686872 -190.41491)
		(width 0.13208)
		(layer "F.Cu")
		(net "UPI_CPU1_CPU0_P0P1_DP<22>")
	)
	(segment
		(start 361.992926 -213.535006)
		(end 361.388914 -212.930994)
		(width 0.0889)
		(layer "F.Cu")
		(net "UPI_CPU1_CPU0_P0P1_DP<22>")
	)
	(arc
		(start 362.163614 -215.44915)
		(mid 362.061648 -215.319602)
		(end 362.025184 -215.158828)
		(width 0.0889)
		(layer "F.Cu")
		(net "UPI_CPU1_CPU0_P0P1_DP<22>")
	)
	(segment
		(start 172.235622 -166.004494)
		(end 173.053502 -165.984682)
		(width 0.14732)
		(layer "In6.Cu")
		(net "UPI_CPU1_CPU0_P0P1_DP<22>")
	)
	(segment
		(start 349.314008 -181.81447)
		(end 349.441516 -181.941978)
		(width 0.14732)
		(layer "In6.Cu")
		(net "UPI_CPU1_CPU0_P0P1_DP<22>")
	)
	(segment
		(start 182.809896 -167.189658)
		(end 189.316106 -167.035734)
		(width 0.14732)
		(layer "In6.Cu")
		(net "UPI_CPU1_CPU0_P0P1_DP<22>")
	)
	(segment
		(start 344.486992 -181.822852)
		(end 345.040966 -182.028084)
		(width 0.14732)
		(layer "In6.Cu")
		(net "UPI_CPU1_CPU0_P0P1_DP<22>")
	)
	(segment
		(start 174.55261 -165.949376)
		(end 175.37049 -165.929564)
		(width 0.14732)
		(layer "In6.Cu")
		(net "UPI_CPU1_CPU0_P0P1_DP<22>")
	)
	(segment
		(start 159.42183 -167.59809)
		(end 159.381444 -165.91661)
		(width 0.14732)
		(layer "In6.Cu")
		(net "UPI_CPU1_CPU0_P0P1_DP<22>")
	)
	(segment
		(start 178.886104 -166.153846)
		(end 179.186586 -165.83914)
		(width 0.14732)
		(layer "In6.Cu")
		(net "UPI_CPU1_CPU0_P0P1_DP<22>")
	)
	(segment
		(start 171.814744 -167.45077)
		(end 171.958508 -167.300402)
		(width 0.14732)
		(layer "In6.Cu")
		(net "UPI_CPU1_CPU0_P0P1_DP<22>")
	)
	(segment
		(start 148.953728 -169.516806)
		(end 150.00732 -169.250868)
		(width 0.14732)
		(layer "In6.Cu")
		(net "UPI_CPU1_CPU0_P0P1_DP<22>")
	)
	(segment
		(start 163.1315 -165.827456)
		(end 163.171886 -167.508936)
		(width 0.14732)
		(layer "In6.Cu")
		(net "UPI_CPU1_CPU0_P0P1_DP<22>")
	)
	(segment
		(start 196.111368 -167.035734)
		(end 196.662294 -166.966392)
		(width 0.14732)
		(layer "In6.Cu")
		(net "UPI_CPU1_CPU0_P0P1_DP<22>")
	)
	(segment
		(start 182.659528 -167.045894)
		(end 182.809896 -167.189658)
		(width 0.14732)
		(layer "In6.Cu")
		(net "UPI_CPU1_CPU0_P0P1_DP<22>")
	)
	(segment
		(start 178.002184 -166.174928)
		(end 178.025552 -167.15613)
		(width 0.14732)
		(layer "In6.Cu")
		(net "UPI_CPU1_CPU0_P0P1_DP<22>")
	)
	(segment
		(start 181.082442 -167.230298)
		(end 181.22646 -167.079676)
		(width 0.14732)
		(layer "In6.Cu")
		(net "UPI_CPU1_CPU0_P0P1_DP<22>")
	)
	(segment
		(start 276.00148 -167.045894)
		(end 280.180288 -167.045894)
		(width 0.14732)
		(layer "In6.Cu")
		(net "UPI_CPU1_CPU0_P0P1_DP<22>")
	)
	(segment
		(start 189.316106 -167.035734)
		(end 196.111368 -167.035734)
		(width 0.14732)
		(layer "In6.Cu")
		(net "UPI_CPU1_CPU0_P0P1_DP<22>")
	)
	(segment
		(start 151.504142 -168.721532)
		(end 151.682704 -168.828466)
		(width 0.14732)
		(layer "In6.Cu")
		(net "UPI_CPU1_CPU0_P0P1_DP<22>")
	)
	(segment
		(start 234.718098 -157.155134)
		(end 237.49381 -157.155134)
		(width 0.14732)
		(layer "In6.Cu")
		(net "UPI_CPU1_CPU0_P0P1_DP<22>")
	)
	(segment
		(start 347.000068 -181.28615)
		(end 346.573602 -182.438548)
		(width 0.14732)
		(layer "In6.Cu")
		(net "UPI_CPU1_CPU0_P0P1_DP<22>")
	)
	(segment
		(start 110.134908 -211.708238)
		(end 110.092998 -211.666328)
		(width 0.0889)
		(layer "In6.Cu")
		(net "UPI_CPU1_CPU0_P0P1_DP<22>")
	)
	(segment
		(start 174.131478 -167.395652)
		(end 174.275496 -167.24503)
		(width 0.14732)
		(layer "In6.Cu")
		(net "UPI_CPU1_CPU0_P0P1_DP<22>")
	)
	(segment
		(start 346.051632 -180.606954)
		(end 346.818204 -180.890672)
		(width 0.14732)
		(layer "In6.Cu")
		(net "UPI_CPU1_CPU0_P0P1_DP<22>")
	)
	(segment
		(start 181.503574 -165.784022)
		(end 182.321454 -165.76421)
		(width 0.14732)
		(layer "In6.Cu")
		(net "UPI_CPU1_CPU0_P0P1_DP<22>")
	)
	(segment
		(start 175.685196 -166.230046)
		(end 175.708564 -167.211248)
		(width 0.14732)
		(layer "In6.Cu")
		(net "UPI_CPU1_CPU0_P0P1_DP<22>")
	)
	(segment
		(start 196.662294 -166.966392)
		(end 234.718098 -157.155134)
		(width 0.14732)
		(layer "In6.Cu")
		(net "UPI_CPU1_CPU0_P0P1_DP<22>")
	)
	(segment
		(start 159.381444 -165.91661)
		(end 159.681926 -165.601904)
		(width 0.14732)
		(layer "In6.Cu")
		(net "UPI_CPU1_CPU0_P0P1_DP<22>")
	)
	(segment
		(start 173.368208 -166.285164)
		(end 173.391576 -167.266366)
		(width 0.14732)
		(layer "In6.Cu")
		(net "UPI_CPU1_CPU0_P0P1_DP<22>")
	)
	(segment
		(start 344.644726 -180.086254)
		(end 344.82659 -180.481732)
		(width 0.14732)
		(layer "In6.Cu")
		(net "UPI_CPU1_CPU0_P0P1_DP<22>")
	)
	(segment
		(start 151.929084 -166.792148)
		(end 152.15235 -166.418514)
		(width 0.14732)
		(layer "In6.Cu")
		(net "UPI_CPU1_CPU0_P0P1_DP<22>")
	)
	(segment
		(start 151.682704 -168.828466)
		(end 152.254458 -168.68394)
		(width 0.14732)
		(layer "In6.Cu")
		(net "UPI_CPU1_CPU0_P0P1_DP<22>")
	)
	(segment
		(start 153.75128 -168.15435)
		(end 153.929842 -168.261284)
		(width 0.14732)
		(layer "In6.Cu")
		(net "UPI_CPU1_CPU0_P0P1_DP<22>")
	)
	(segment
		(start 349.549212 -182.127652)
		(end 350.089724 -182.272432)
		(width 0.14732)
		(layer "In6.Cu")
		(net "UPI_CPU1_CPU0_P0P1_DP<22>")
	)
	(segment
		(start 149.905212 -166.985696)
		(end 150.698454 -166.78529)
		(width 0.14732)
		(layer "In6.Cu")
		(net "UPI_CPU1_CPU0_P0P1_DP<22>")
	)
	(segment
		(start 175.858932 -167.355012)
		(end 176.448466 -167.340534)
		(width 0.14732)
		(layer "In6.Cu")
		(net "UPI_CPU1_CPU0_P0P1_DP<22>")
	)
	(segment
		(start 280.180288 -167.045894)
		(end 302.490632 -166.661592)
		(width 0.14732)
		(layer "In6.Cu")
		(net "UPI_CPU1_CPU0_P0P1_DP<22>")
	)
	(segment
		(start 110.092998 -211.666328)
		(end 110.092998 -211.64423)
		(width 0.0889)
		(layer "In6.Cu")
		(net "UPI_CPU1_CPU0_P0P1_DP<22>")
	)
	(segment
		(start 151.071834 -167.008556)
		(end 151.504142 -168.721532)
		(width 0.14732)
		(layer "In6.Cu")
		(net "UPI_CPU1_CPU0_P0P1_DP<22>")
	)
	(segment
		(start 346.573602 -182.438548)
		(end 346.66047 -182.62727)
		(width 0.14732)
		(layer "In6.Cu")
		(net "UPI_CPU1_CPU0_P0P1_DP<22>")
	)
	(segment
		(start 347.214444 -182.832502)
		(end 347.403166 -182.745634)
		(width 0.14732)
		(layer "In6.Cu")
		(net "UPI_CPU1_CPU0_P0P1_DP<22>")
	)
	(segment
		(start 157.364938 -165.657022)
		(end 158.182818 -165.63721)
		(width 0.14732)
		(layer "In6.Cu")
		(net "UPI_CPU1_CPU0_P0P1_DP<22>")
	)
	(segment
		(start 178.025552 -167.15613)
		(end 178.17592 -167.299894)
		(width 0.14732)
		(layer "In6.Cu")
		(net "UPI_CPU1_CPU0_P0P1_DP<22>")
	)
	(segment
		(start 146.647916 -170.697906)
		(end 146.713448 -170.495722)
		(width 0.14732)
		(layer "In6.Cu")
		(net "UPI_CPU1_CPU0_P0P1_DP<22>")
	)
	(segment
		(start 345.040966 -182.028084)
		(end 345.229688 -181.941216)
		(width 0.14732)
		(layer "In6.Cu")
		(net "UPI_CPU1_CPU0_P0P1_DP<22>")
	)
	(segment
		(start 321.60718 -168.91762)
		(end 338.704174 -177.888392)
		(width 0.14732)
		(layer "In6.Cu")
		(net "UPI_CPU1_CPU0_P0P1_DP<22>")
	)
	(segment
		(start 156.961078 -167.803576)
		(end 157.104842 -167.653208)
		(width 0.14732)
		(layer "In6.Cu")
		(net "UPI_CPU1_CPU0_P0P1_DP<22>")
	)
	(segment
		(start 173.541944 -167.41013)
		(end 174.131478 -167.395652)
		(width 0.14732)
		(layer "In6.Cu")
		(net "UPI_CPU1_CPU0_P0P1_DP<22>")
	)
	(segment
		(start 182.321454 -165.76421)
		(end 182.63616 -166.064692)
		(width 0.14732)
		(layer "In6.Cu")
		(net "UPI_CPU1_CPU0_P0P1_DP<22>")
	)
	(segment
		(start 109.290612 -215.436704)
		(end 109.535722 -215.436704)
		(width 0.0889)
		(layer "In6.Cu")
		(net "UPI_CPU1_CPU0_P0P1_DP<22>")
	)
	(segment
		(start 150.00732 -169.250868)
		(end 150.114254 -169.072306)
		(width 0.14732)
		(layer "In6.Cu")
		(net "UPI_CPU1_CPU0_P0P1_DP<22>")
	)
	(segment
		(start 157.064456 -165.971728)
		(end 157.364938 -165.657022)
		(width 0.14732)
		(layer "In6.Cu")
		(net "UPI_CPU1_CPU0_P0P1_DP<22>")
	)
	(segment
		(start 347.403166 -182.745634)
		(end 347.829632 -181.593236)
		(width 0.14732)
		(layer "In6.Cu")
		(net "UPI_CPU1_CPU0_P0P1_DP<22>")
	)
	(segment
		(start 175.708564 -167.211248)
		(end 175.858932 -167.355012)
		(width 0.14732)
		(layer "In6.Cu")
		(net "UPI_CPU1_CPU0_P0P1_DP<22>")
	)
	(segment
		(start 346.818204 -180.890672)
		(end 347.000068 -181.28615)
		(width 0.14732)
		(layer "In6.Cu")
		(net "UPI_CPU1_CPU0_P0P1_DP<22>")
	)
	(segment
		(start 302.490632 -166.661592)
		(end 314.480702 -166.906194)
		(width 0.14732)
		(layer "In6.Cu")
		(net "UPI_CPU1_CPU0_P0P1_DP<22>")
	)
	(segment
		(start 180.34254 -167.101012)
		(end 180.492908 -167.244776)
		(width 0.14732)
		(layer "In6.Cu")
		(net "UPI_CPU1_CPU0_P0P1_DP<22>")
	)
	(segment
		(start 346.66047 -182.62727)
		(end 347.214444 -182.832502)
		(width 0.14732)
		(layer "In6.Cu")
		(net "UPI_CPU1_CPU0_P0P1_DP<22>")
	)
	(segment
		(start 178.909472 -167.134794)
		(end 178.886104 -166.153846)
		(width 0.14732)
		(layer "In6.Cu")
		(net "UPI_CPU1_CPU0_P0P1_DP<22>")
	)
	(segment
		(start 110.134908 -214.601552)
		(end 110.134908 -211.708238)
		(width 0.0889)
		(layer "In6.Cu")
		(net "UPI_CPU1_CPU0_P0P1_DP<22>")
	)
	(segment
		(start 161.698432 -165.861492)
		(end 161.998914 -165.546786)
		(width 0.14732)
		(layer "In6.Cu")
		(net "UPI_CPU1_CPU0_P0P1_DP<22>")
	)
	(segment
		(start 345.229688 -181.941216)
		(end 345.656154 -180.788818)
		(width 0.14732)
		(layer "In6.Cu")
		(net "UPI_CPU1_CPU0_P0P1_DP<22>")
	)
	(segment
		(start 152.15235 -166.418514)
		(end 152.945592 -166.218108)
		(width 0.14732)
		(layer "In6.Cu")
		(net "UPI_CPU1_CPU0_P0P1_DP<22>")
	)
	(segment
		(start 176.448466 -167.340534)
		(end 176.592484 -167.189912)
		(width 0.14732)
		(layer "In6.Cu")
		(net "UPI_CPU1_CPU0_P0P1_DP<22>")
	)
	(segment
		(start 109.695234 -215.16975)
		(end 109.694472 -215.169242)
		(width 0.0889)
		(layer "In6.Cu")
		(net "UPI_CPU1_CPU0_P0P1_DP<22>")
	)
	(segment
		(start 178.17592 -167.299894)
		(end 178.765454 -167.285416)
		(width 0.14732)
		(layer "In6.Cu")
		(net "UPI_CPU1_CPU0_P0P1_DP<22>")
	)
	(segment
		(start 178.765454 -167.285416)
		(end 178.909472 -167.134794)
		(width 0.14732)
		(layer "In6.Cu")
		(net "UPI_CPU1_CPU0_P0P1_DP<22>")
	)
	(segment
		(start 171.958508 -167.300402)
		(end 171.93514 -166.3192)
		(width 0.14732)
		(layer "In6.Cu")
		(net "UPI_CPU1_CPU0_P0P1_DP<22>")
	)
	(segment
		(start 181.22646 -167.079676)
		(end 181.203092 -166.098728)
		(width 0.14732)
		(layer "In6.Cu")
		(net "UPI_CPU1_CPU0_P0P1_DP<22>")
	)
	(segment
		(start 146.19732 -169.48531)
		(end 146.331432 -169.07129)
		(width 0.14732)
		(layer "In6.Cu")
		(net "UPI_CPU1_CPU0_P0P1_DP<22>")
	)
	(segment
		(start 180.004466 -165.819328)
		(end 180.319172 -166.11981)
		(width 0.14732)
		(layer "In6.Cu")
		(net "UPI_CPU1_CPU0_P0P1_DP<22>")
	)
	(segment
		(start 150.114254 -169.072306)
		(end 149.681946 -167.35933)
		(width 0.14732)
		(layer "In6.Cu")
		(net "UPI_CPU1_CPU0_P0P1_DP<22>")
	)
	(segment
		(start 152.361392 -168.505124)
		(end 151.929084 -166.792148)
		(width 0.14732)
		(layer "In6.Cu")
		(net "UPI_CPU1_CPU0_P0P1_DP<22>")
	)
	(segment
		(start 182.63616 -166.064692)
		(end 182.659528 -167.045894)
		(width 0.14732)
		(layer "In6.Cu")
		(net "UPI_CPU1_CPU0_P0P1_DP<22>")
	)
	(segment
		(start 161.998914 -165.546786)
		(end 162.816794 -165.526974)
		(width 0.14732)
		(layer "In6.Cu")
		(net "UPI_CPU1_CPU0_P0P1_DP<22>")
	)
	(segment
		(start 160.814512 -165.882574)
		(end 160.854898 -167.564054)
		(width 0.14732)
		(layer "In6.Cu")
		(net "UPI_CPU1_CPU0_P0P1_DP<22>")
	)
	(segment
		(start 344.400124 -181.63413)
		(end 344.486992 -181.822852)
		(width 0.14732)
		(layer "In6.Cu")
		(net "UPI_CPU1_CPU0_P0P1_DP<22>")
	)
	(segment
		(start 147.059904 -168.69918)
		(end 147.473924 -168.833292)
		(width 0.14732)
		(layer "In6.Cu")
		(net "UPI_CPU1_CPU0_P0P1_DP<22>")
	)
	(segment
		(start 153.318972 -166.441374)
		(end 153.75128 -168.15435)
		(width 0.14732)
		(layer "In6.Cu")
		(net "UPI_CPU1_CPU0_P0P1_DP<22>")
	)
	(segment
		(start 115.037616 -197.271132)
		(end 123.082812 -187.285884)
		(width 0.14732)
		(layer "In6.Cu")
		(net "UPI_CPU1_CPU0_P0P1_DP<22>")
	)
	(segment
		(start 347.829632 -181.593236)
		(end 348.22511 -181.411372)
		(width 0.14732)
		(layer "In6.Cu")
		(net "UPI_CPU1_CPU0_P0P1_DP<22>")
	)
	(segment
		(start 177.687478 -165.874446)
		(end 178.002184 -166.174928)
		(width 0.14732)
		(layer "In6.Cu")
		(net "UPI_CPU1_CPU0_P0P1_DP<22>")
	)
	(segment
		(start 148.187918 -169.907966)
		(end 148.953728 -169.516806)
		(width 0.14732)
		(layer "In6.Cu")
		(net "UPI_CPU1_CPU0_P0P1_DP<22>")
	)
	(segment
		(start 349.548704 -182.12689)
		(end 349.549212 -182.127652)
		(width 0.14732)
		(layer "In6.Cu")
		(net "UPI_CPU1_CPU0_P0P1_DP<22>")
	)
	(segment
		(start 147.473924 -168.833292)
		(end 147.990052 -169.843704)
		(width 0.14732)
		(layer "In6.Cu")
		(net "UPI_CPU1_CPU0_P0P1_DP<22>")
	)
	(segment
		(start 180.492908 -167.244776)
		(end 181.082442 -167.230298)
		(width 0.14732)
		(layer "In6.Cu")
		(net "UPI_CPU1_CPU0_P0P1_DP<22>")
	)
	(segment
		(start 314.480702 -166.906194)
		(end 321.60718 -168.91762)
		(width 0.14732)
		(layer "In6.Cu")
		(net "UPI_CPU1_CPU0_P0P1_DP<22>")
	)
	(segment
		(start 349.441516 -181.941978)
		(end 349.548704 -182.12689)
		(width 0.14732)
		(layer "In6.Cu")
		(net "UPI_CPU1_CPU0_P0P1_DP<22>")
	)
	(segment
		(start 176.592484 -167.189912)
		(end 176.569116 -166.208964)
		(width 0.14732)
		(layer "In6.Cu")
		(net "UPI_CPU1_CPU0_P0P1_DP<22>")
	)
	(segment
		(start 163.322254 -167.6527)
		(end 171.814744 -167.45077)
		(width 0.14732)
		(layer "In6.Cu")
		(net "UPI_CPU1_CPU0_P0P1_DP<22>")
	)
	(segment
		(start 159.681926 -165.601904)
		(end 160.499806 -165.582092)
		(width 0.14732)
		(layer "In6.Cu")
		(net "UPI_CPU1_CPU0_P0P1_DP<22>")
	)
	(segment
		(start 180.319172 -166.11981)
		(end 180.34254 -167.101012)
		(width 0.14732)
		(layer "In6.Cu")
		(net "UPI_CPU1_CPU0_P0P1_DP<22>")
	)
	(segment
		(start 163.171886 -167.508936)
		(end 163.322254 -167.6527)
		(width 0.14732)
		(layer "In6.Cu")
		(net "UPI_CPU1_CPU0_P0P1_DP<22>")
	)
	(segment
		(start 338.704174 -177.888392)
		(end 344.644726 -180.086254)
		(width 0.14732)
		(layer "In6.Cu")
		(net "UPI_CPU1_CPU0_P0P1_DP<22>")
	)
	(segment
		(start 147.990052 -169.843704)
		(end 148.187918 -169.907966)
		(width 0.14732)
		(layer "In6.Cu")
		(net "UPI_CPU1_CPU0_P0P1_DP<22>")
	)
	(segment
		(start 157.104842 -167.653208)
		(end 157.064456 -165.971728)
		(width 0.14732)
		(layer "In6.Cu")
		(net "UPI_CPU1_CPU0_P0P1_DP<22>")
	)
	(segment
		(start 161.738818 -167.542972)
		(end 161.698432 -165.861492)
		(width 0.14732)
		(layer "In6.Cu")
		(net "UPI_CPU1_CPU0_P0P1_DP<22>")
	)
	(segment
		(start 176.569116 -166.208964)
		(end 176.869598 -165.894258)
		(width 0.14732)
		(layer "In6.Cu")
		(net "UPI_CPU1_CPU0_P0P1_DP<22>")
	)
	(segment
		(start 161.595054 -167.69334)
		(end 161.738818 -167.542972)
		(width 0.14732)
		(layer "In6.Cu")
		(net "UPI_CPU1_CPU0_P0P1_DP<22>")
	)
	(segment
		(start 146.713448 -170.495722)
		(end 146.19732 -169.48531)
		(width 0.14732)
		(layer "In6.Cu")
		(net "UPI_CPU1_CPU0_P0P1_DP<22>")
	)
	(segment
		(start 152.254458 -168.68394)
		(end 152.361392 -168.505124)
		(width 0.14732)
		(layer "In6.Cu")
		(net "UPI_CPU1_CPU0_P0P1_DP<22>")
	)
	(segment
		(start 348.22511 -181.411372)
		(end 349.314008 -181.814216)
		(width 0.14732)
		(layer "In6.Cu")
		(net "UPI_CPU1_CPU0_P0P1_DP<22>")
	)
	(segment
		(start 179.186586 -165.83914)
		(end 180.004466 -165.819328)
		(width 0.14732)
		(layer "In6.Cu")
		(net "UPI_CPU1_CPU0_P0P1_DP<22>")
	)
	(segment
		(start 176.869598 -165.894258)
		(end 177.687478 -165.874446)
		(width 0.14732)
		(layer "In6.Cu")
		(net "UPI_CPU1_CPU0_P0P1_DP<22>")
	)
	(segment
		(start 110.092998 -211.251292)
		(end 115.037616 -197.271132)
		(width 0.14732)
		(layer "In6.Cu")
		(net "UPI_CPU1_CPU0_P0P1_DP<22>")
	)
	(segment
		(start 174.252128 -166.264082)
		(end 174.55261 -165.949376)
		(width 0.14732)
		(layer "In6.Cu")
		(net "UPI_CPU1_CPU0_P0P1_DP<22>")
	)
	(segment
		(start 344.82659 -180.481732)
		(end 344.400124 -181.63413)
		(width 0.14732)
		(layer "In6.Cu")
		(net "UPI_CPU1_CPU0_P0P1_DP<22>")
	)
	(segment
		(start 133.594856 -177.363628)
		(end 146.647916 -170.697906)
		(width 0.14732)
		(layer "In6.Cu")
		(net "UPI_CPU1_CPU0_P0P1_DP<22>")
	)
	(segment
		(start 162.816794 -165.526974)
		(end 163.1315 -165.827456)
		(width 0.14732)
		(layer "In6.Cu")
		(net "UPI_CPU1_CPU0_P0P1_DP<22>")
	)
	(segment
		(start 158.53791 -167.619172)
		(end 158.688278 -167.762936)
		(width 0.14732)
		(layer "In6.Cu")
		(net "UPI_CPU1_CPU0_P0P1_DP<22>")
	)
	(segment
		(start 161.005266 -167.707818)
		(end 161.595054 -167.69334)
		(width 0.14732)
		(layer "In6.Cu")
		(net "UPI_CPU1_CPU0_P0P1_DP<22>")
	)
	(segment
		(start 159.278066 -167.748458)
		(end 159.42183 -167.59809)
		(width 0.14732)
		(layer "In6.Cu")
		(net "UPI_CPU1_CPU0_P0P1_DP<22>")
	)
	(segment
		(start 173.053502 -165.984682)
		(end 173.368208 -166.285164)
		(width 0.14732)
		(layer "In6.Cu")
		(net "UPI_CPU1_CPU0_P0P1_DP<22>")
	)
	(segment
		(start 173.391576 -167.266366)
		(end 173.541944 -167.41013)
		(width 0.14732)
		(layer "In6.Cu")
		(net "UPI_CPU1_CPU0_P0P1_DP<22>")
	)
	(segment
		(start 110.092998 -211.64423)
		(end 110.092998 -211.251292)
		(width 0.14732)
		(layer "In6.Cu")
		(net "UPI_CPU1_CPU0_P0P1_DP<22>")
	)
	(segment
		(start 160.854898 -167.564054)
		(end 161.005266 -167.707818)
		(width 0.14732)
		(layer "In6.Cu")
		(net "UPI_CPU1_CPU0_P0P1_DP<22>")
	)
	(segment
		(start 150.698454 -166.78529)
		(end 151.071834 -167.008556)
		(width 0.14732)
		(layer "In6.Cu")
		(net "UPI_CPU1_CPU0_P0P1_DP<22>")
	)
	(segment
		(start 345.656154 -180.788818)
		(end 346.051632 -180.606954)
		(width 0.14732)
		(layer "In6.Cu")
		(net "UPI_CPU1_CPU0_P0P1_DP<22>")
	)
	(segment
		(start 149.681946 -167.35933)
		(end 149.905212 -166.985696)
		(width 0.14732)
		(layer "In6.Cu")
		(net "UPI_CPU1_CPU0_P0P1_DP<22>")
	)
	(segment
		(start 349.314008 -181.814216)
		(end 349.314008 -181.81447)
		(width 0.14732)
		(layer "In6.Cu")
		(net "UPI_CPU1_CPU0_P0P1_DP<22>")
	)
	(segment
		(start 146.331432 -169.07129)
		(end 147.059904 -168.69918)
		(width 0.14732)
		(layer "In6.Cu")
		(net "UPI_CPU1_CPU0_P0P1_DP<22>")
	)
	(segment
		(start 160.499806 -165.582092)
		(end 160.814512 -165.882574)
		(width 0.14732)
		(layer "In6.Cu")
		(net "UPI_CPU1_CPU0_P0P1_DP<22>")
	)
	(segment
		(start 158.688278 -167.762936)
		(end 159.278066 -167.748458)
		(width 0.14732)
		(layer "In6.Cu")
		(net "UPI_CPU1_CPU0_P0P1_DP<22>")
	)
	(segment
		(start 123.082812 -187.285884)
		(end 133.594856 -177.363628)
		(width 0.14732)
		(layer "In6.Cu")
		(net "UPI_CPU1_CPU0_P0P1_DP<22>")
	)
	(segment
		(start 158.182818 -165.63721)
		(end 158.497524 -165.937692)
		(width 0.14732)
		(layer "In6.Cu")
		(net "UPI_CPU1_CPU0_P0P1_DP<22>")
	)
	(segment
		(start 171.93514 -166.3192)
		(end 172.235622 -166.004494)
		(width 0.14732)
		(layer "In6.Cu")
		(net "UPI_CPU1_CPU0_P0P1_DP<22>")
	)
	(segment
		(start 152.945592 -166.218108)
		(end 153.318972 -166.441374)
		(width 0.14732)
		(layer "In6.Cu")
		(net "UPI_CPU1_CPU0_P0P1_DP<22>")
	)
	(segment
		(start 158.497524 -165.937692)
		(end 158.53791 -167.619172)
		(width 0.14732)
		(layer "In6.Cu")
		(net "UPI_CPU1_CPU0_P0P1_DP<22>")
	)
	(segment
		(start 181.203092 -166.098728)
		(end 181.503574 -165.784022)
		(width 0.14732)
		(layer "In6.Cu")
		(net "UPI_CPU1_CPU0_P0P1_DP<22>")
	)
	(segment
		(start 237.49381 -157.155134)
		(end 276.00148 -167.045894)
		(width 0.14732)
		(layer "In6.Cu")
		(net "UPI_CPU1_CPU0_P0P1_DP<22>")
	)
	(segment
		(start 155.617926 -167.83558)
		(end 156.961078 -167.803576)
		(width 0.14732)
		(layer "In6.Cu")
		(net "UPI_CPU1_CPU0_P0P1_DP<22>")
	)
	(segment
		(start 174.275496 -167.24503)
		(end 174.252128 -166.264082)
		(width 0.14732)
		(layer "In6.Cu")
		(net "UPI_CPU1_CPU0_P0P1_DP<22>")
	)
	(segment
		(start 175.37049 -165.929564)
		(end 175.685196 -166.230046)
		(width 0.14732)
		(layer "In6.Cu")
		(net "UPI_CPU1_CPU0_P0P1_DP<22>")
	)
	(segment
		(start 153.929842 -168.261284)
		(end 155.617926 -167.83558)
		(width 0.14732)
		(layer "In6.Cu")
		(net "UPI_CPU1_CPU0_P0P1_DP<22>")
	)
	(arc
		(start 109.694472 -215.169242)
		(mid 109.802042 -215.018055)
		(end 109.950758 -214.907114)
		(width 0.0889)
		(layer "In6.Cu")
		(net "UPI_CPU1_CPU0_P0P1_DP<22>")
	)
	(arc
		(start 109.535722 -215.436704)
		(mid 109.624986 -215.39973)
		(end 109.66196 -215.310466)
		(width 0.0889)
		(layer "In6.Cu")
		(net "UPI_CPU1_CPU0_P0P1_DP<22>")
	)
	(arc
		(start 109.66196 -215.310466)
		(mid 109.670445 -215.238179)
		(end 109.695234 -215.16975)
		(width 0.0889)
		(layer "In6.Cu")
		(net "UPI_CPU1_CPU0_P0P1_DP<22>")
	)
	(arc
		(start 109.950758 -214.907114)
		(mid 110.085366 -214.779953)
		(end 110.134908 -214.601552)
		(width 0.0889)
		(layer "In6.Cu")
		(net "UPI_CPU1_CPU0_P0P1_DP<22>")
	)
	(segment
		(start 362.230162 -212.72119)
		(end 358.037892 -210.984084)
		(width 0.0889)
		(layer "F.Cu")
		(net "UPI_CPU1_CPU0_P0P1_DP<21>")
	)
	(segment
		(start 353.737164 -193.053462)
		(end 355.70668 -188.300614)
		(width 0.13208)
		(layer "F.Cu")
		(net "UPI_CPU1_CPU0_P0P1_DP<21>")
	)
	(segment
		(start 352.976688 -183.792368)
		(end 353.096068 -183.58612)
		(width 0.13208)
		(layer "F.Cu")
		(net "UPI_CPU1_CPU0_P0P1_DP<21>")
	)
	(segment
		(start 362.869734 -214.344758)
		(end 363.024928 -214.613744)
		(width 0.0889)
		(layer "F.Cu")
		(net "UPI_CPU1_CPU0_P0P1_DP<21>")
	)
	(segment
		(start 362.507276 -213.138766)
		(end 362.507276 -212.998304)
		(width 0.0889)
		(layer "F.Cu")
		(net "UPI_CPU1_CPU0_P0P1_DP<21>")
	)
	(segment
		(start 352.612198 -205.205076)
		(end 352.612198 -198.715884)
		(width 0.13208)
		(layer "F.Cu")
		(net "UPI_CPU1_CPU0_P0P1_DP<21>")
	)
	(segment
		(start 352.646488 -205.261464)
		(end 352.612198 -205.227174)
		(width 0.0889)
		(layer "F.Cu")
		(net "UPI_CPU1_CPU0_P0P1_DP<21>")
	)
	(segment
		(start 353.021392 -184.132982)
		(end 352.976688 -183.792368)
		(width 0.13208)
		(layer "F.Cu")
		(net "UPI_CPU1_CPU0_P0P1_DP<21>")
	)
	(segment
		(start 362.615226 -213.246462)
		(end 362.507276 -213.138766)
		(width 0.0889)
		(layer "F.Cu")
		(net "UPI_CPU1_CPU0_P0P1_DP<21>")
	)
	(segment
		(start 362.86313 -213.494112)
		(end 362.86313 -213.354158)
		(width 0.0889)
		(layer "F.Cu")
		(net "UPI_CPU1_CPU0_P0P1_DP<21>")
	)
	(segment
		(start 362.97108 -213.602062)
		(end 362.86313 -213.494112)
		(width 0.0889)
		(layer "F.Cu")
		(net "UPI_CPU1_CPU0_P0P1_DP<21>")
	)
	(segment
		(start 363.024928 -214.613744)
		(end 363.105954 -214.635334)
		(width 0.0889)
		(layer "F.Cu")
		(net "UPI_CPU1_CPU0_P0P1_DP<21>")
	)
	(segment
		(start 352.646488 -205.59268)
		(end 352.646488 -205.261464)
		(width 0.0889)
		(layer "F.Cu")
		(net "UPI_CPU1_CPU0_P0P1_DP<21>")
	)
	(segment
		(start 355.490272 -186.509152)
		(end 354.258118 -185.276998)
		(width 0.13208)
		(layer "F.Cu")
		(net "UPI_CPU1_CPU0_P0P1_DP<21>")
	)
	(segment
		(start 353.508056 -184.876186)
		(end 353.122992 -184.33923)
		(width 0.13208)
		(layer "F.Cu")
		(net "UPI_CPU1_CPU0_P0P1_DP<21>")
	)
	(segment
		(start 363.244384 -214.345012)
		(end 363.244384 -213.735158)
		(width 0.0889)
		(layer "F.Cu")
		(net "UPI_CPU1_CPU0_P0P1_DP<21>")
	)
	(segment
		(start 355.70668 -187.031376)
		(end 355.490272 -186.509152)
		(width 0.13208)
		(layer "F.Cu")
		(net "UPI_CPU1_CPU0_P0P1_DP<21>")
	)
	(segment
		(start 354.258118 -185.276998)
		(end 353.508056 -184.876186)
		(width 0.13208)
		(layer "F.Cu")
		(net "UPI_CPU1_CPU0_P0P1_DP<21>")
	)
	(segment
		(start 362.86313 -213.354158)
		(end 362.755434 -213.246462)
		(width 0.0889)
		(layer "F.Cu")
		(net "UPI_CPU1_CPU0_P0P1_DP<21>")
	)
	(segment
		(start 108.351066 -215.972644)
		(end 108.351066 -215.436958)
		(width 0.13208)
		(layer "F.Cu")
		(net "UPI_CPU1_CPU0_P0P1_DP<21>")
	)
	(segment
		(start 358.037892 -210.984084)
		(end 352.646488 -205.59268)
		(width 0.0889)
		(layer "F.Cu")
		(net "UPI_CPU1_CPU0_P0P1_DP<21>")
	)
	(segment
		(start 353.122992 -184.33923)
		(end 353.021392 -184.132982)
		(width 0.13208)
		(layer "F.Cu")
		(net "UPI_CPU1_CPU0_P0P1_DP<21>")
	)
	(segment
		(start 352.612198 -198.715884)
		(end 353.737164 -193.053462)
		(width 0.13208)
		(layer "F.Cu")
		(net "UPI_CPU1_CPU0_P0P1_DP<21>")
	)
	(segment
		(start 362.755434 -213.246462)
		(end 362.615226 -213.246462)
		(width 0.0889)
		(layer "F.Cu")
		(net "UPI_CPU1_CPU0_P0P1_DP<21>")
	)
	(segment
		(start 352.612198 -205.227174)
		(end 352.612198 -205.205076)
		(width 0.0889)
		(layer "F.Cu")
		(net "UPI_CPU1_CPU0_P0P1_DP<21>")
	)
	(segment
		(start 108.351066 -215.436958)
		(end 108.350812 -215.436704)
		(width 0.13208)
		(layer "F.Cu")
		(net "UPI_CPU1_CPU0_P0P1_DP<21>")
	)
	(segment
		(start 363.244384 -213.735158)
		(end 363.111288 -213.602062)
		(width 0.0889)
		(layer "F.Cu")
		(net "UPI_CPU1_CPU0_P0P1_DP<21>")
	)
	(segment
		(start 355.70668 -188.300614)
		(end 355.70668 -187.031376)
		(width 0.13208)
		(layer "F.Cu")
		(net "UPI_CPU1_CPU0_P0P1_DP<21>")
	)
	(segment
		(start 353.096068 -183.58612)
		(end 352.948494 -183.034432)
		(width 0.13208)
		(layer "F.Cu")
		(net "UPI_CPU1_CPU0_P0P1_DP<21>")
	)
	(segment
		(start 363.111288 -213.602062)
		(end 362.97108 -213.602062)
		(width 0.0889)
		(layer "F.Cu")
		(net "UPI_CPU1_CPU0_P0P1_DP<21>")
	)
	(segment
		(start 362.507276 -212.998304)
		(end 362.230162 -212.72119)
		(width 0.0889)
		(layer "F.Cu")
		(net "UPI_CPU1_CPU0_P0P1_DP<21>")
	)
	(arc
		(start 363.105954 -214.635334)
		(mid 363.20792 -214.505786)
		(end 363.244384 -214.345012)
		(width 0.0889)
		(layer "F.Cu")
		(net "UPI_CPU1_CPU0_P0P1_DP<21>")
	)
	(segment
		(start 189.215776 -166.200582)
		(end 194.854576 -166.200582)
		(width 0.14732)
		(layer "In6.Cu")
		(net "UPI_CPU1_CPU0_P0P1_DP<21>")
	)
	(segment
		(start 177.63363 -164.719254)
		(end 177.784252 -164.862764)
		(width 0.14732)
		(layer "In6.Cu")
		(net "UPI_CPU1_CPU0_P0P1_DP<21>")
	)
	(segment
		(start 177.555652 -161.561526)
		(end 177.706274 -161.705036)
		(width 0.14732)
		(layer "In6.Cu")
		(net "UPI_CPU1_CPU0_P0P1_DP<21>")
	)
	(segment
		(start 345.724226 -179.502308)
		(end 345.915488 -179.420266)
		(width 0.14732)
		(layer "In6.Cu")
		(net "UPI_CPU1_CPU0_P0P1_DP<21>")
	)
	(segment
		(start 237.600744 -156.310838)
		(end 276.108414 -166.201598)
		(width 0.14732)
		(layer "In6.Cu")
		(net "UPI_CPU1_CPU0_P0P1_DP<21>")
	)
	(segment
		(start 234.61091 -156.310838)
		(end 237.600744 -156.310838)
		(width 0.14732)
		(layer "In6.Cu")
		(net "UPI_CPU1_CPU0_P0P1_DP<21>")
	)
	(segment
		(start 108.514134 -214.108538)
		(end 109.021118 -213.601808)
		(width 0.0889)
		(layer "In6.Cu")
		(net "UPI_CPU1_CPU0_P0P1_DP<21>")
	)
	(segment
		(start 155.941268 -164.357558)
		(end 156.24429 -164.044884)
		(width 0.14732)
		(layer "In6.Cu")
		(net "UPI_CPU1_CPU0_P0P1_DP<21>")
	)
	(segment
		(start 143.4338 -170.189398)
		(end 143.69669 -170.617642)
		(width 0.14732)
		(layer "In6.Cu")
		(net "UPI_CPU1_CPU0_P0P1_DP<21>")
	)
	(segment
		(start 280.172668 -166.201598)
		(end 302.492156 -165.816788)
		(width 0.14732)
		(layer "In6.Cu")
		(net "UPI_CPU1_CPU0_P0P1_DP<21>")
	)
	(segment
		(start 158.930086 -164.307774)
		(end 159.233108 -163.9951)
		(width 0.14732)
		(layer "In6.Cu")
		(net "UPI_CPU1_CPU0_P0P1_DP<21>")
	)
	(segment
		(start 181.458108 -164.77234)
		(end 181.508146 -164.77234)
		(width 0.14732)
		(layer "In6.Cu")
		(net "UPI_CPU1_CPU0_P0P1_DP<21>")
	)
	(segment
		(start 108.979208 -211.77123)
		(end 108.979208 -211.542122)
		(width 0.14732)
		(layer "In6.Cu")
		(net "UPI_CPU1_CPU0_P0P1_DP<21>")
	)
	(segment
		(start 176.057052 -164.905436)
		(end 176.200562 -164.754814)
		(width 0.14732)
		(layer "In6.Cu")
		(net "UPI_CPU1_CPU0_P0P1_DP<21>")
	)
	(segment
		(start 108.507276 -215.165686)
		(end 108.483146 -215.076532)
		(width 0.0889)
		(layer "In6.Cu")
		(net "UPI_CPU1_CPU0_P0P1_DP<21>")
	)
	(segment
		(start 343.573354 -178.63947)
		(end 343.764616 -178.557428)
		(width 0.14732)
		(layer "In6.Cu")
		(net "UPI_CPU1_CPU0_P0P1_DP<21>")
	)
	(segment
		(start 173.363382 -163.75126)
		(end 173.048168 -163.451286)
		(width 0.14732)
		(layer "In6.Cu")
		(net "UPI_CPU1_CPU0_P0P1_DP<21>")
	)
	(segment
		(start 350.825308 -181.098698)
		(end 351.215198 -181.341522)
		(width 0.14732)
		(layer "In6.Cu")
		(net "UPI_CPU1_CPU0_P0P1_DP<21>")
	)
	(segment
		(start 173.710092 -163.742624)
		(end 173.363382 -163.75126)
		(width 0.14732)
		(layer "In6.Cu")
		(net "UPI_CPU1_CPU0_P0P1_DP<21>")
	)
	(segment
		(start 141.45895 -171.402756)
		(end 141.755622 -171.885864)
		(width 0.14732)
		(layer "In6.Cu")
		(net "UPI_CPU1_CPU0_P0P1_DP<21>")
	)
	(segment
		(start 345.012264 -178.471576)
		(end 345.183206 -178.871626)
		(width 0.14732)
		(layer "In6.Cu")
		(net "UPI_CPU1_CPU0_P0P1_DP<21>")
	)
	(segment
		(start 137.085832 -173.727364)
		(end 137.50925 -173.828964)
		(width 0.14732)
		(layer "In6.Cu")
		(net "UPI_CPU1_CPU0_P0P1_DP<21>")
	)
	(segment
		(start 177.741834 -163.138104)
		(end 177.598324 -163.288726)
		(width 0.14732)
		(layer "In6.Cu")
		(net "UPI_CPU1_CPU0_P0P1_DP<21>")
	)
	(segment
		(start 122.506994 -186.677808)
		(end 134.629906 -175.234092)
		(width 0.14732)
		(layer "In6.Cu")
		(net "UPI_CPU1_CPU0_P0P1_DP<21>")
	)
	(segment
		(start 346.403676 -179.029868)
		(end 347.163136 -179.334414)
		(width 0.14732)
		(layer "In6.Cu")
		(net "UPI_CPU1_CPU0_P0P1_DP<21>")
	)
	(segment
		(start 345.17711 -179.282598)
		(end 345.724226 -179.502308)
		(width 0.14732)
		(layer "In6.Cu")
		(net "UPI_CPU1_CPU0_P0P1_DP<21>")
	)
	(segment
		(start 158.199836 -164.74694)
		(end 158.790386 -164.737034)
		(width 0.14732)
		(layer "In6.Cu")
		(net "UPI_CPU1_CPU0_P0P1_DP<21>")
	)
	(segment
		(start 341.50173 -177.376074)
		(end 342.310974 -177.700686)
		(width 0.14732)
		(layer "In6.Cu")
		(net "UPI_CPU1_CPU0_P0P1_DP<21>")
	)
	(segment
		(start 156.24429 -164.044884)
		(end 157.732984 -164.019738)
		(width 0.14732)
		(layer "In6.Cu")
		(net "UPI_CPU1_CPU0_P0P1_DP<21>")
	)
	(segment
		(start 347.163136 -179.334414)
		(end 347.334078 -179.734464)
		(width 0.14732)
		(layer "In6.Cu")
		(net "UPI_CPU1_CPU0_P0P1_DP<21>")
	)
	(segment
		(start 108.979208 -211.793328)
		(end 108.979208 -211.77123)
		(width 0.0889)
		(layer "In6.Cu")
		(net "UPI_CPU1_CPU0_P0P1_DP<21>")
	)
	(segment
		(start 194.854576 -166.200582)
		(end 197.581012 -165.857428)
		(width 0.14732)
		(layer "In6.Cu")
		(net "UPI_CPU1_CPU0_P0P1_DP<21>")
	)
	(segment
		(start 173.027848 -162.633406)
		(end 173.327822 -162.318446)
		(width 0.14732)
		(layer "In6.Cu")
		(net "UPI_CPU1_CPU0_P0P1_DP<21>")
	)
	(segment
		(start 347.334078 -179.734464)
		(end 347.24594 -179.95392)
		(width 0.14732)
		(layer "In6.Cu")
		(net "UPI_CPU1_CPU0_P0P1_DP<21>")
	)
	(segment
		(start 137.50925 -173.828964)
		(end 137.645648 -174.05096)
		(width 0.14732)
		(layer "In6.Cu")
		(net "UPI_CPU1_CPU0_P0P1_DP<21>")
	)
	(segment
		(start 344.252804 -178.16703)
		(end 345.012264 -178.471576)
		(width 0.14732)
		(layer "In6.Cu")
		(net "UPI_CPU1_CPU0_P0P1_DP<21>")
	)
	(segment
		(start 155.957524 -165.32225)
		(end 155.941268 -164.357558)
		(width 0.14732)
		(layer "In6.Cu")
		(net "UPI_CPU1_CPU0_P0P1_DP<21>")
	)
	(segment
		(start 351.45853 -181.654196)
		(end 351.73158 -183.304688)
		(width 0.14732)
		(layer "In6.Cu")
		(net "UPI_CPU1_CPU0_P0P1_DP<21>")
	)
	(segment
		(start 144.450054 -170.154346)
		(end 144.187418 -169.726102)
		(width 0.14732)
		(layer "In6.Cu")
		(net "UPI_CPU1_CPU0_P0P1_DP<21>")
	)
	(segment
		(start 155.073096 -165.337236)
		(end 155.222448 -165.481762)
		(width 0.14732)
		(layer "In6.Cu")
		(net "UPI_CPU1_CPU0_P0P1_DP<21>")
	)
	(segment
		(start 143.69669 -170.617642)
		(end 143.898366 -170.665902)
		(width 0.14732)
		(layer "In6.Cu")
		(net "UPI_CPU1_CPU0_P0P1_DP<21>")
	)
	(segment
		(start 158.934912 -164.587936)
		(end 158.930086 -164.307774)
		(width 0.14732)
		(layer "In6.Cu")
		(net "UPI_CPU1_CPU0_P0P1_DP<21>")
	)
	(segment
		(start 173.860714 -163.886134)
		(end 173.710092 -163.742624)
		(width 0.14732)
		(layer "In6.Cu")
		(net "UPI_CPU1_CPU0_P0P1_DP<21>")
	)
	(segment
		(start 159.233108 -163.9951)
		(end 161.797746 -163.952428)
		(width 0.14732)
		(layer "In6.Cu")
		(net "UPI_CPU1_CPU0_P0P1_DP<21>")
	)
	(segment
		(start 173.327822 -162.318446)
		(end 173.674532 -162.309556)
		(width 0.14732)
		(layer "In6.Cu")
		(net "UPI_CPU1_CPU0_P0P1_DP<21>")
	)
	(segment
		(start 184.942988 -165.381686)
		(end 185.94705 -165.204648)
		(width 0.14732)
		(layer "In6.Cu")
		(net "UPI_CPU1_CPU0_P0P1_DP<21>")
	)
	(segment
		(start 144.187418 -169.726102)
		(end 144.288764 -169.302684)
		(width 0.14732)
		(layer "In6.Cu")
		(net "UPI_CPU1_CPU0_P0P1_DP<21>")
	)
	(segment
		(start 137.847578 -174.09922)
		(end 138.351006 -173.789848)
		(width 0.14732)
		(layer "In6.Cu")
		(net "UPI_CPU1_CPU0_P0P1_DP<21>")
	)
	(segment
		(start 109.021118 -213.601808)
		(end 109.021118 -211.835238)
		(width 0.0889)
		(layer "In6.Cu")
		(net "UPI_CPU1_CPU0_P0P1_DP<21>")
	)
	(segment
		(start 168.49852 -165.900608)
		(end 169.754296 -165.57117)
		(width 0.14732)
		(layer "In6.Cu")
		(net "UPI_CPU1_CPU0_P0P1_DP<21>")
	)
	(segment
		(start 177.534062 -160.702244)
		(end 177.555652 -161.561526)
		(width 0.14732)
		(layer "In6.Cu")
		(net "UPI_CPU1_CPU0_P0P1_DP<21>")
	)
	(segment
		(start 141.957552 -171.934124)
		(end 142.46098 -171.624752)
		(width 0.14732)
		(layer "In6.Cu")
		(net "UPI_CPU1_CPU0_P0P1_DP<21>")
	)
	(segment
		(start 108.350812 -215.436704)
		(end 108.507276 -215.165686)
		(width 0.0889)
		(layer "In6.Cu")
		(net "UPI_CPU1_CPU0_P0P1_DP<21>")
	)
	(segment
		(start 353.093782 -183.57596)
		(end 352.948494 -183.034432)
		(width 0.14732)
		(layer "In6.Cu")
		(net "UPI_CPU1_CPU0_P0P1_DP<21>")
	)
	(segment
		(start 139.4841 -172.61586)
		(end 139.620498 -172.837856)
		(width 0.14732)
		(layer "In6.Cu")
		(net "UPI_CPU1_CPU0_P0P1_DP<21>")
	)
	(segment
		(start 347.327982 -180.145182)
		(end 348.511622 -180.620162)
		(width 0.14732)
		(layer "In6.Cu")
		(net "UPI_CPU1_CPU0_P0P1_DP<21>")
	)
	(segment
		(start 197.581012 -165.857428)
		(end 234.61091 -156.310838)
		(width 0.14732)
		(layer "In6.Cu")
		(net "UPI_CPU1_CPU0_P0P1_DP<21>")
	)
	(segment
		(start 155.222448 -165.481762)
		(end 155.812998 -165.471602)
		(width 0.14732)
		(layer "In6.Cu")
		(net "UPI_CPU1_CPU0_P0P1_DP<21>")
	)
	(segment
		(start 185.94705 -165.204648)
		(end 186.412378 -165.204648)
		(width 0.14732)
		(layer "In6.Cu")
		(net "UPI_CPU1_CPU0_P0P1_DP<21>")
	)
	(segment
		(start 352.874834 -183.871108)
		(end 352.989642 -183.7563)
		(width 0.14732)
		(layer "In6.Cu")
		(net "UPI_CPU1_CPU0_P0P1_DP<21>")
	)
	(segment
		(start 155.05684 -164.372798)
		(end 155.073096 -165.337236)
		(width 0.14732)
		(layer "In6.Cu")
		(net "UPI_CPU1_CPU0_P0P1_DP<21>")
	)
	(segment
		(start 109.021118 -211.835238)
		(end 108.979208 -211.793328)
		(width 0.0889)
		(layer "In6.Cu")
		(net "UPI_CPU1_CPU0_P0P1_DP<21>")
	)
	(segment
		(start 345.915488 -179.420266)
		(end 346.003626 -179.20081)
		(width 0.14732)
		(layer "In6.Cu")
		(net "UPI_CPU1_CPU0_P0P1_DP<21>")
	)
	(segment
		(start 140.339064 -171.728892)
		(end 141.035278 -171.301156)
		(width 0.14732)
		(layer "In6.Cu")
		(net "UPI_CPU1_CPU0_P0P1_DP<21>")
	)
	(segment
		(start 166.759382 -165.835584)
		(end 166.803324 -165.844474)
		(width 0.14732)
		(layer "In6.Cu")
		(net "UPI_CPU1_CPU0_P0P1_DP<21>")
	)
	(segment
		(start 174.084488 -160.479994)
		(end 174.902368 -160.459674)
		(width 0.14732)
		(layer "In6.Cu")
		(net "UPI_CPU1_CPU0_P0P1_DP<21>")
	)
	(segment
		(start 340.980014 -177.59934)
		(end 341.50173 -177.376074)
		(width 0.14732)
		(layer "In6.Cu")
		(net "UPI_CPU1_CPU0_P0P1_DP<21>")
	)
	(segment
		(start 157.732984 -164.019738)
		(end 158.045658 -164.32276)
		(width 0.14732)
		(layer "In6.Cu")
		(net "UPI_CPU1_CPU0_P0P1_DP<21>")
	)
	(segment
		(start 139.060428 -172.51426)
		(end 139.4841 -172.61586)
		(width 0.14732)
		(layer "In6.Cu")
		(net "UPI_CPU1_CPU0_P0P1_DP<21>")
	)
	(segment
		(start 181.512464 -164.776658)
		(end 184.942988 -165.381686)
		(width 0.14732)
		(layer "In6.Cu")
		(net "UPI_CPU1_CPU0_P0P1_DP<21>")
	)
	(segment
		(start 351.91446 -183.672988)
		(end 352.25482 -183.871108)
		(width 0.14732)
		(layer "In6.Cu")
		(net "UPI_CPU1_CPU0_P0P1_DP<21>")
	)
	(segment
		(start 176.100994 -160.737804)
		(end 176.401222 -160.42259)
		(width 0.14732)
		(layer "In6.Cu")
		(net "UPI_CPU1_CPU0_P0P1_DP<21>")
	)
	(segment
		(start 352.989642 -183.7563)
		(end 353.093782 -183.57596)
		(width 0.14732)
		(layer "In6.Cu")
		(net "UPI_CPU1_CPU0_P0P1_DP<21>")
	)
	(segment
		(start 173.740318 -164.96284)
		(end 173.883828 -164.812218)
		(width 0.14732)
		(layer "In6.Cu")
		(net "UPI_CPU1_CPU0_P0P1_DP<21>")
	)
	(segment
		(start 137.645648 -174.05096)
		(end 137.847578 -174.09922)
		(width 0.14732)
		(layer "In6.Cu")
		(net "UPI_CPU1_CPU0_P0P1_DP<21>")
	)
	(segment
		(start 179.029106 -161.67227)
		(end 179.34432 -161.972244)
		(width 0.14732)
		(layer "In6.Cu")
		(net "UPI_CPU1_CPU0_P0P1_DP<21>")
	)
	(segment
		(start 176.200562 -164.754814)
		(end 176.100994 -160.737804)
		(width 0.14732)
		(layer "In6.Cu")
		(net "UPI_CPU1_CPU0_P0P1_DP<21>")
	)
	(segment
		(start 144.401794 -170.356784)
		(end 144.450054 -170.154346)
		(width 0.14732)
		(layer "In6.Cu")
		(net "UPI_CPU1_CPU0_P0P1_DP<21>")
	)
	(segment
		(start 158.790386 -164.737034)
		(end 158.934912 -164.587936)
		(width 0.14732)
		(layer "In6.Cu")
		(net "UPI_CPU1_CPU0_P0P1_DP<21>")
	)
	(segment
		(start 161.797746 -163.952428)
		(end 166.759382 -165.835584)
		(width 0.14732)
		(layer "In6.Cu")
		(net "UPI_CPU1_CPU0_P0P1_DP<21>")
	)
	(segment
		(start 138.364214 -172.941996)
		(end 139.060428 -172.51426)
		(width 0.14732)
		(layer "In6.Cu")
		(net "UPI_CPU1_CPU0_P0P1_DP<21>")
	)
	(segment
		(start 179.36464 -162.790124)
		(end 179.064666 -163.105084)
		(width 0.14732)
		(layer "In6.Cu")
		(net "UPI_CPU1_CPU0_P0P1_DP<21>")
	)
	(segment
		(start 174.902368 -160.459674)
		(end 175.217328 -160.759648)
		(width 0.14732)
		(layer "In6.Cu")
		(net "UPI_CPU1_CPU0_P0P1_DP<21>")
	)
	(segment
		(start 336.697574 -175.881284)
		(end 340.980014 -177.59934)
		(width 0.14732)
		(layer "In6.Cu")
		(net "UPI_CPU1_CPU0_P0P1_DP<21>")
	)
	(segment
		(start 352.25482 -183.871108)
		(end 352.874834 -183.871108)
		(width 0.14732)
		(layer "In6.Cu")
		(net "UPI_CPU1_CPU0_P0P1_DP<21>")
	)
	(segment
		(start 158.050484 -164.602414)
		(end 158.199836 -164.74694)
		(width 0.14732)
		(layer "In6.Cu")
		(net "UPI_CPU1_CPU0_P0P1_DP<21>")
	)
	(segment
		(start 181.508146 -164.77234)
		(end 181.512464 -164.776658)
		(width 0.14732)
		(layer "In6.Cu")
		(net "UPI_CPU1_CPU0_P0P1_DP<21>")
	)
	(segment
		(start 158.045658 -164.32276)
		(end 158.050484 -164.602414)
		(width 0.14732)
		(layer "In6.Cu")
		(net "UPI_CPU1_CPU0_P0P1_DP<21>")
	)
	(segment
		(start 140.237718 -172.15231)
		(end 140.339064 -171.728892)
		(width 0.14732)
		(layer "In6.Cu")
		(net "UPI_CPU1_CPU0_P0P1_DP<21>")
	)
	(segment
		(start 139.822428 -172.886116)
		(end 140.325856 -172.576744)
		(width 0.14732)
		(layer "In6.Cu")
		(net "UPI_CPU1_CPU0_P0P1_DP<21>")
	)
	(segment
		(start 166.803324 -165.844474)
		(end 168.49852 -165.900608)
		(width 0.14732)
		(layer "In6.Cu")
		(net "UPI_CPU1_CPU0_P0P1_DP<21>")
	)
	(segment
		(start 179.064666 -163.105084)
		(end 177.741834 -163.138104)
		(width 0.14732)
		(layer "In6.Cu")
		(net "UPI_CPU1_CPU0_P0P1_DP<21>")
	)
	(segment
		(start 346.003626 -179.20081)
		(end 346.403676 -179.029868)
		(width 0.14732)
		(layer "In6.Cu")
		(net "UPI_CPU1_CPU0_P0P1_DP<21>")
	)
	(segment
		(start 175.467518 -164.920168)
		(end 176.057052 -164.905436)
		(width 0.14732)
		(layer "In6.Cu")
		(net "UPI_CPU1_CPU0_P0P1_DP<21>")
	)
	(segment
		(start 351.73158 -183.304688)
		(end 351.91446 -183.672988)
		(width 0.14732)
		(layer "In6.Cu")
		(net "UPI_CPU1_CPU0_P0P1_DP<21>")
	)
	(segment
		(start 140.325856 -172.576744)
		(end 140.374116 -172.374814)
		(width 0.14732)
		(layer "In6.Cu")
		(net "UPI_CPU1_CPU0_P0P1_DP<21>")
	)
	(segment
		(start 134.629906 -175.234092)
		(end 137.085832 -173.727364)
		(width 0.14732)
		(layer "In6.Cu")
		(net "UPI_CPU1_CPU0_P0P1_DP<21>")
	)
	(segment
		(start 347.24594 -179.95392)
		(end 347.327982 -180.145182)
		(width 0.14732)
		(layer "In6.Cu")
		(net "UPI_CPU1_CPU0_P0P1_DP<21>")
	)
	(segment
		(start 348.511622 -180.620162)
		(end 350.825308 -181.098698)
		(width 0.14732)
		(layer "In6.Cu")
		(net "UPI_CPU1_CPU0_P0P1_DP<21>")
	)
	(segment
		(start 142.50924 -171.422822)
		(end 142.212568 -170.939206)
		(width 0.14732)
		(layer "In6.Cu")
		(net "UPI_CPU1_CPU0_P0P1_DP<21>")
	)
	(segment
		(start 345.095068 -179.091082)
		(end 345.17711 -179.282598)
		(width 0.14732)
		(layer "In6.Cu")
		(net "UPI_CPU1_CPU0_P0P1_DP<21>")
	)
	(segment
		(start 138.351006 -173.789848)
		(end 138.399266 -173.587918)
		(width 0.14732)
		(layer "In6.Cu")
		(net "UPI_CPU1_CPU0_P0P1_DP<21>")
	)
	(segment
		(start 138.399266 -173.587918)
		(end 138.262868 -173.365414)
		(width 0.14732)
		(layer "In6.Cu")
		(net "UPI_CPU1_CPU0_P0P1_DP<21>")
	)
	(segment
		(start 177.219102 -160.40227)
		(end 177.534062 -160.702244)
		(width 0.14732)
		(layer "In6.Cu")
		(net "UPI_CPU1_CPU0_P0P1_DP<21>")
	)
	(segment
		(start 155.812998 -165.471602)
		(end 155.957524 -165.32225)
		(width 0.14732)
		(layer "In6.Cu")
		(net "UPI_CPU1_CPU0_P0P1_DP<21>")
	)
	(segment
		(start 108.255308 -214.636858)
		(end 108.255308 -214.425784)
		(width 0.0889)
		(layer "In6.Cu")
		(net "UPI_CPU1_CPU0_P0P1_DP<21>")
	)
	(segment
		(start 141.755622 -171.885864)
		(end 141.957552 -171.934124)
		(width 0.14732)
		(layer "In6.Cu")
		(net "UPI_CPU1_CPU0_P0P1_DP<21>")
	)
	(segment
		(start 143.898366 -170.665902)
		(end 144.401794 -170.356784)
		(width 0.14732)
		(layer "In6.Cu")
		(net "UPI_CPU1_CPU0_P0P1_DP<21>")
	)
	(segment
		(start 173.674532 -162.309556)
		(end 173.818042 -162.158934)
		(width 0.14732)
		(layer "In6.Cu")
		(net "UPI_CPU1_CPU0_P0P1_DP<21>")
	)
	(segment
		(start 114.068606 -197.15226)
		(end 122.506994 -186.677808)
		(width 0.14732)
		(layer "In6.Cu")
		(net "UPI_CPU1_CPU0_P0P1_DP<21>")
	)
	(segment
		(start 177.598324 -163.288726)
		(end 177.63363 -164.719254)
		(width 0.14732)
		(layer "In6.Cu")
		(net "UPI_CPU1_CPU0_P0P1_DP<21>")
	)
	(segment
		(start 177.706274 -161.705036)
		(end 179.029106 -161.67227)
		(width 0.14732)
		(layer "In6.Cu")
		(net "UPI_CPU1_CPU0_P0P1_DP<21>")
	)
	(segment
		(start 176.401222 -160.42259)
		(end 177.219102 -160.40227)
		(width 0.14732)
		(layer "In6.Cu")
		(net "UPI_CPU1_CPU0_P0P1_DP<21>")
	)
	(segment
		(start 302.492156 -165.816788)
		(end 314.605924 -166.06393)
		(width 0.14732)
		(layer "In6.Cu")
		(net "UPI_CPU1_CPU0_P0P1_DP<21>")
	)
	(segment
		(start 138.262868 -173.365414)
		(end 138.364214 -172.941996)
		(width 0.14732)
		(layer "In6.Cu")
		(net "UPI_CPU1_CPU0_P0P1_DP<21>")
	)
	(segment
		(start 169.754296 -165.57117)
		(end 171.162726 -165.026848)
		(width 0.14732)
		(layer "In6.Cu")
		(net "UPI_CPU1_CPU0_P0P1_DP<21>")
	)
	(segment
		(start 140.374116 -172.374814)
		(end 140.237718 -172.15231)
		(width 0.14732)
		(layer "In6.Cu")
		(net "UPI_CPU1_CPU0_P0P1_DP<21>")
	)
	(segment
		(start 153.516584 -164.090604)
		(end 154.744166 -164.069776)
		(width 0.14732)
		(layer "In6.Cu")
		(net "UPI_CPU1_CPU0_P0P1_DP<21>")
	)
	(segment
		(start 321.921378 -168.128696)
		(end 336.697574 -175.881284)
		(width 0.14732)
		(layer "In6.Cu")
		(net "UPI_CPU1_CPU0_P0P1_DP<21>")
	)
	(segment
		(start 152.107646 -164.500814)
		(end 153.516584 -164.090604)
		(width 0.14732)
		(layer "In6.Cu")
		(net "UPI_CPU1_CPU0_P0P1_DP<21>")
	)
	(segment
		(start 179.34432 -161.972244)
		(end 179.36464 -162.790124)
		(width 0.14732)
		(layer "In6.Cu")
		(net "UPI_CPU1_CPU0_P0P1_DP<21>")
	)
	(segment
		(start 142.313914 -170.515788)
		(end 143.010128 -170.088052)
		(width 0.14732)
		(layer "In6.Cu")
		(net "UPI_CPU1_CPU0_P0P1_DP<21>")
	)
	(segment
		(start 173.78426 -160.795208)
		(end 174.084488 -160.479994)
		(width 0.14732)
		(layer "In6.Cu")
		(net "UPI_CPU1_CPU0_P0P1_DP<21>")
	)
	(segment
		(start 343.764616 -178.557428)
		(end 343.852754 -178.337972)
		(width 0.14732)
		(layer "In6.Cu")
		(net "UPI_CPU1_CPU0_P0P1_DP<21>")
	)
	(segment
		(start 351.215198 -181.341522)
		(end 351.45853 -181.654196)
		(width 0.14732)
		(layer "In6.Cu")
		(net "UPI_CPU1_CPU0_P0P1_DP<21>")
	)
	(segment
		(start 143.010128 -170.088052)
		(end 143.4338 -170.189398)
		(width 0.14732)
		(layer "In6.Cu")
		(net "UPI_CPU1_CPU0_P0P1_DP<21>")
	)
	(segment
		(start 171.162726 -165.026848)
		(end 173.740318 -164.96284)
		(width 0.14732)
		(layer "In6.Cu")
		(net "UPI_CPU1_CPU0_P0P1_DP<21>")
	)
	(segment
		(start 141.035278 -171.301156)
		(end 141.45895 -171.402756)
		(width 0.14732)
		(layer "In6.Cu")
		(net "UPI_CPU1_CPU0_P0P1_DP<21>")
	)
	(segment
		(start 173.818042 -162.158934)
		(end 173.78426 -160.795208)
		(width 0.14732)
		(layer "In6.Cu")
		(net "UPI_CPU1_CPU0_P0P1_DP<21>")
	)
	(segment
		(start 144.288764 -169.302684)
		(end 152.107646 -164.500814)
		(width 0.14732)
		(layer "In6.Cu")
		(net "UPI_CPU1_CPU0_P0P1_DP<21>")
	)
	(segment
		(start 175.217328 -160.759648)
		(end 175.316896 -164.776658)
		(width 0.14732)
		(layer "In6.Cu")
		(net "UPI_CPU1_CPU0_P0P1_DP<21>")
	)
	(segment
		(start 142.46098 -171.624752)
		(end 142.50924 -171.422822)
		(width 0.14732)
		(layer "In6.Cu")
		(net "UPI_CPU1_CPU0_P0P1_DP<21>")
	)
	(segment
		(start 173.048168 -163.451286)
		(end 173.027848 -162.633406)
		(width 0.14732)
		(layer "In6.Cu")
		(net "UPI_CPU1_CPU0_P0P1_DP<21>")
	)
	(segment
		(start 276.108414 -166.201598)
		(end 280.172668 -166.201598)
		(width 0.14732)
		(layer "In6.Cu")
		(net "UPI_CPU1_CPU0_P0P1_DP<21>")
	)
	(segment
		(start 343.852754 -178.337972)
		(end 344.252804 -178.16703)
		(width 0.14732)
		(layer "In6.Cu")
		(net "UPI_CPU1_CPU0_P0P1_DP<21>")
	)
	(segment
		(start 186.412378 -165.204648)
		(end 189.215776 -166.200582)
		(width 0.14732)
		(layer "In6.Cu")
		(net "UPI_CPU1_CPU0_P0P1_DP<21>")
	)
	(segment
		(start 139.620498 -172.837856)
		(end 139.822428 -172.886116)
		(width 0.14732)
		(layer "In6.Cu")
		(net "UPI_CPU1_CPU0_P0P1_DP<21>")
	)
	(segment
		(start 142.212568 -170.939206)
		(end 142.313914 -170.515788)
		(width 0.14732)
		(layer "In6.Cu")
		(net "UPI_CPU1_CPU0_P0P1_DP<21>")
	)
	(segment
		(start 177.784252 -164.862764)
		(end 181.458108 -164.77234)
		(width 0.14732)
		(layer "In6.Cu")
		(net "UPI_CPU1_CPU0_P0P1_DP<21>")
	)
	(segment
		(start 175.316896 -164.776658)
		(end 175.467518 -164.920168)
		(width 0.14732)
		(layer "In6.Cu")
		(net "UPI_CPU1_CPU0_P0P1_DP<21>")
	)
	(segment
		(start 345.183206 -178.871626)
		(end 345.095068 -179.091082)
		(width 0.14732)
		(layer "In6.Cu")
		(net "UPI_CPU1_CPU0_P0P1_DP<21>")
	)
	(segment
		(start 173.883828 -164.812218)
		(end 173.860714 -163.886134)
		(width 0.14732)
		(layer "In6.Cu")
		(net "UPI_CPU1_CPU0_P0P1_DP<21>")
	)
	(segment
		(start 314.605924 -166.06393)
		(end 321.921378 -168.128696)
		(width 0.14732)
		(layer "In6.Cu")
		(net "UPI_CPU1_CPU0_P0P1_DP<21>")
	)
	(segment
		(start 154.744166 -164.069776)
		(end 155.05684 -164.372798)
		(width 0.14732)
		(layer "In6.Cu")
		(net "UPI_CPU1_CPU0_P0P1_DP<21>")
	)
	(segment
		(start 342.310974 -177.700686)
		(end 342.533986 -178.222402)
		(width 0.14732)
		(layer "In6.Cu")
		(net "UPI_CPU1_CPU0_P0P1_DP<21>")
	)
	(segment
		(start 342.533986 -178.222402)
		(end 343.573354 -178.63947)
		(width 0.14732)
		(layer "In6.Cu")
		(net "UPI_CPU1_CPU0_P0P1_DP<21>")
	)
	(segment
		(start 108.979208 -211.542122)
		(end 114.068606 -197.15226)
		(width 0.14732)
		(layer "In6.Cu")
		(net "UPI_CPU1_CPU0_P0P1_DP<21>")
	)
	(arc
		(start 108.466128 -215.063324)
		(mid 108.313697 -214.873342)
		(end 108.255308 -214.636858)
		(width 0.0889)
		(layer "In6.Cu")
		(net "UPI_CPU1_CPU0_P0P1_DP<21>")
	)
	(arc
		(start 108.255308 -214.425784)
		(mid 108.356742 -214.244333)
		(end 108.514134 -214.108538)
		(width 0.0889)
		(layer "In6.Cu")
		(net "UPI_CPU1_CPU0_P0P1_DP<21>")
	)
	(arc
		(start 108.483146 -215.076532)
		(mid 108.474574 -215.070009)
		(end 108.466128 -215.063324)
		(width 0.0889)
		(layer "In6.Cu")
		(net "UPI_CPU1_CPU0_P0P1_DP<21>")
	)
	(segment
		(start 356.867968 -184.876694)
		(end 354.530406 -182.539132)
		(width 0.13208)
		(layer "F.Cu")
		(net "UPI_CPU1_CPU0_P0P1_DP<20>")
	)
	(segment
		(start 354.179378 -205.205076)
		(end 354.179378 -198.914766)
		(width 0.13208)
		(layer "F.Cu")
		(net "UPI_CPU1_CPU0_P0P1_DP<20>")
	)
	(segment
		(start 352.833686 -181.701948)
		(end 350.110806 -180.069744)
		(width 0.13208)
		(layer "F.Cu")
		(net "UPI_CPU1_CPU0_P0P1_DP<20>")
	)
	(segment
		(start 364.27918 -215.158574)
		(end 364.123986 -215.42756)
		(width 0.0889)
		(layer "F.Cu")
		(net "UPI_CPU1_CPU0_P0P1_DP<20>")
	)
	(segment
		(start 364.374684 -213.994746)
		(end 364.473744 -213.895686)
		(width 0.0889)
		(layer "F.Cu")
		(net "UPI_CPU1_CPU0_P0P1_DP<20>")
	)
	(segment
		(start 354.154232 -182.287672)
		(end 352.833686 -181.701948)
		(width 0.13208)
		(layer "F.Cu")
		(net "UPI_CPU1_CPU0_P0P1_DP<20>")
	)
	(segment
		(start 364.374684 -213.644226)
		(end 364.374684 -213.491826)
		(width 0.0889)
		(layer "F.Cu")
		(net "UPI_CPU1_CPU0_P0P1_DP<20>")
	)
	(segment
		(start 349.942658 -179.777898)
		(end 349.941896 -179.776882)
		(width 0.13208)
		(layer "F.Cu")
		(net "UPI_CPU1_CPU0_P0P1_DP<20>")
	)
	(segment
		(start 354.179378 -198.914766)
		(end 355.25964 -193.485008)
		(width 0.13208)
		(layer "F.Cu")
		(net "UPI_CPU1_CPU0_P0P1_DP<20>")
	)
	(segment
		(start 364.266988 -213.38413)
		(end 364.266988 -213.243922)
		(width 0.0889)
		(layer "F.Cu")
		(net "UPI_CPU1_CPU0_P0P1_DP<20>")
	)
	(segment
		(start 364.266988 -213.243922)
		(end 364.218728 -213.195662)
		(width 0.0889)
		(layer "F.Cu")
		(net "UPI_CPU1_CPU0_P0P1_DP<20>")
	)
	(segment
		(start 355.25964 -193.485008)
		(end 357.478838 -188.126878)
		(width 0.13208)
		(layer "F.Cu")
		(net "UPI_CPU1_CPU0_P0P1_DP<20>")
	)
	(segment
		(start 349.941896 -179.776882)
		(end 350.089724 -179.224432)
		(width 0.13208)
		(layer "F.Cu")
		(net "UPI_CPU1_CPU0_P0P1_DP<20>")
	)
	(segment
		(start 357.478838 -188.126878)
		(end 357.478838 -186.351164)
		(width 0.13208)
		(layer "F.Cu")
		(net "UPI_CPU1_CPU0_P0P1_DP<20>")
	)
	(segment
		(start 364.374684 -214.345266)
		(end 364.374684 -213.994746)
		(width 0.0889)
		(layer "F.Cu")
		(net "UPI_CPU1_CPU0_P0P1_DP<20>")
	)
	(segment
		(start 364.159292 -213.135972)
		(end 364.019084 -213.135972)
		(width 0.0889)
		(layer "F.Cu")
		(net "UPI_CPU1_CPU0_P0P1_DP<20>")
	)
	(segment
		(start 364.473744 -213.895686)
		(end 364.473744 -213.743286)
		(width 0.0889)
		(layer "F.Cu")
		(net "UPI_CPU1_CPU0_P0P1_DP<20>")
	)
	(segment
		(start 364.218728 -213.195662)
		(end 364.159292 -213.135972)
		(width 0.0889)
		(layer "F.Cu")
		(net "UPI_CPU1_CPU0_P0P1_DP<20>")
	)
	(segment
		(start 354.144834 -205.261718)
		(end 354.179378 -205.227174)
		(width 0.0889)
		(layer "F.Cu")
		(net "UPI_CPU1_CPU0_P0P1_DP<20>")
	)
	(segment
		(start 357.478838 -186.351164)
		(end 356.867968 -184.876694)
		(width 0.13208)
		(layer "F.Cu")
		(net "UPI_CPU1_CPU0_P0P1_DP<20>")
	)
	(segment
		(start 362.735114 -211.852256)
		(end 358.751632 -210.20151)
		(width 0.0889)
		(layer "F.Cu")
		(net "UPI_CPU1_CPU0_P0P1_DP<20>")
	)
	(segment
		(start 350.110806 -180.069744)
		(end 349.942658 -179.777898)
		(width 0.13208)
		(layer "F.Cu")
		(net "UPI_CPU1_CPU0_P0P1_DP<20>")
	)
	(segment
		(start 358.751632 -210.20151)
		(end 354.144834 -205.594712)
		(width 0.0889)
		(layer "F.Cu")
		(net "UPI_CPU1_CPU0_P0P1_DP<20>")
	)
	(segment
		(start 354.179378 -205.227174)
		(end 354.179378 -205.205076)
		(width 0.0889)
		(layer "F.Cu")
		(net "UPI_CPU1_CPU0_P0P1_DP<20>")
	)
	(segment
		(start 364.019084 -213.135972)
		(end 362.735622 -211.85251)
		(width 0.0889)
		(layer "F.Cu")
		(net "UPI_CPU1_CPU0_P0P1_DP<20>")
	)
	(segment
		(start 107.411266 -214.344758)
		(end 107.411266 -213.732618)
		(width 0.13208)
		(layer "F.Cu")
		(net "UPI_CPU1_CPU0_P0P1_DP<20>")
	)
	(segment
		(start 364.473744 -213.743286)
		(end 364.374684 -213.644226)
		(width 0.0889)
		(layer "F.Cu")
		(net "UPI_CPU1_CPU0_P0P1_DP<20>")
	)
	(segment
		(start 364.123986 -215.42756)
		(end 364.04296 -215.44915)
		(width 0.0889)
		(layer "F.Cu")
		(net "UPI_CPU1_CPU0_P0P1_DP<20>")
	)
	(segment
		(start 354.144834 -205.594712)
		(end 354.144834 -205.261718)
		(width 0.0889)
		(layer "F.Cu")
		(net "UPI_CPU1_CPU0_P0P1_DP<20>")
	)
	(segment
		(start 354.530406 -182.539132)
		(end 354.154232 -182.287672)
		(width 0.13208)
		(layer "F.Cu")
		(net "UPI_CPU1_CPU0_P0P1_DP<20>")
	)
	(segment
		(start 364.374684 -213.491826)
		(end 364.266988 -213.38413)
		(width 0.0889)
		(layer "F.Cu")
		(net "UPI_CPU1_CPU0_P0P1_DP<20>")
	)
	(segment
		(start 362.735622 -211.85251)
		(end 362.735114 -211.852256)
		(width 0.0889)
		(layer "F.Cu")
		(net "UPI_CPU1_CPU0_P0P1_DP<20>")
	)
	(arc
		(start 364.103158 -214.827612)
		(mid 364.104304 -214.826982)
		(end 364.105444 -214.826342)
		(width 0.0889)
		(layer "F.Cu")
		(net "UPI_CPU1_CPU0_P0P1_DP<20>")
	)
	(arc
		(start 364.105444 -214.826342)
		(mid 364.302652 -214.620838)
		(end 364.374684 -214.345266)
		(width 0.0889)
		(layer "F.Cu")
		(net "UPI_CPU1_CPU0_P0P1_DP<20>")
	)
	(arc
		(start 364.04296 -215.44915)
		(mid 363.906155 -215.122216)
		(end 364.103158 -214.827612)
		(width 0.0889)
		(layer "F.Cu")
		(net "UPI_CPU1_CPU0_P0P1_DP<20>")
	)
	(segment
		(start 175.476916 -158.383224)
		(end 174.95393 -159.38246)
		(width 0.14732)
		(layer "In6.Cu")
		(net "UPI_CPU1_CPU0_P0P1_DP<20>")
	)
	(segment
		(start 158.773876 -159.472376)
		(end 158.699454 -159.785304)
		(width 0.14732)
		(layer "In6.Cu")
		(net "UPI_CPU1_CPU0_P0P1_DP<20>")
	)
	(segment
		(start 328.806556 -169.55135)
		(end 328.360532 -170.401488)
		(width 0.14732)
		(layer "In6.Cu")
		(net "UPI_CPU1_CPU0_P0P1_DP<20>")
	)
	(segment
		(start 332.266036 -172.616876)
		(end 331.743812 -172.34281)
		(width 0.14732)
		(layer "In6.Cu")
		(net "UPI_CPU1_CPU0_P0P1_DP<20>")
	)
	(segment
		(start 157.564328 -162.640772)
		(end 157.061154 -162.950906)
		(width 0.14732)
		(layer "In6.Cu")
		(net "UPI_CPU1_CPU0_P0P1_DP<20>")
	)
	(segment
		(start 133.924294 -174.691802)
		(end 121.751344 -186.139836)
		(width 0.14732)
		(layer "In6.Cu")
		(net "UPI_CPU1_CPU0_P0P1_DP<20>")
	)
	(segment
		(start 335.378298 -172.651928)
		(end 334.962754 -172.781468)
		(width 0.14732)
		(layer "In6.Cu")
		(net "UPI_CPU1_CPU0_P0P1_DP<20>")
	)
	(segment
		(start 334.179926 -172.37075)
		(end 334.050386 -171.955206)
		(width 0.14732)
		(layer "In6.Cu")
		(net "UPI_CPU1_CPU0_P0P1_DP<20>")
	)
	(segment
		(start 107.785916 -212.301836)
		(end 107.686602 -212.40115)
		(width 0.0889)
		(layer "In6.Cu")
		(net "UPI_CPU1_CPU0_P0P1_DP<20>")
	)
	(segment
		(start 332.910688 -171.704762)
		(end 332.464664 -172.5549)
		(width 0.14732)
		(layer "In6.Cu")
		(net "UPI_CPU1_CPU0_P0P1_DP<20>")
	)
	(segment
		(start 159.495744 -158.93288)
		(end 158.848552 -159.33166)
		(width 0.14732)
		(layer "In6.Cu")
		(net "UPI_CPU1_CPU0_P0P1_DP<20>")
	)
	(segment
		(start 174.232062 -159.17037)
		(end 174.170086 -158.97225)
		(width 0.14732)
		(layer "In6.Cu")
		(net "UPI_CPU1_CPU0_P0P1_DP<20>")
	)
	(segment
		(start 329.2221 -169.42181)
		(end 328.806556 -169.55135)
		(width 0.14732)
		(layer "In6.Cu")
		(net "UPI_CPU1_CPU0_P0P1_DP<20>")
	)
	(segment
		(start 157.612334 -162.438842)
		(end 157.564328 -162.640772)
		(width 0.14732)
		(layer "In6.Cu")
		(net "UPI_CPU1_CPU0_P0P1_DP<20>")
	)
	(segment
		(start 334.050386 -171.955206)
		(end 333.326232 -171.575222)
		(width 0.14732)
		(layer "In6.Cu")
		(net "UPI_CPU1_CPU0_P0P1_DP<20>")
	)
	(segment
		(start 314.729368 -165.234112)
		(end 302.49368 -164.98443)
		(width 0.14732)
		(layer "In6.Cu")
		(net "UPI_CPU1_CPU0_P0P1_DP<20>")
	)
	(segment
		(start 330.075794 -170.217338)
		(end 329.946254 -169.801794)
		(width 0.14732)
		(layer "In6.Cu")
		(net "UPI_CPU1_CPU0_P0P1_DP<20>")
	)
	(segment
		(start 330.412598 -171.478194)
		(end 330.21397 -171.54017)
		(width 0.14732)
		(layer "In6.Cu")
		(net "UPI_CPU1_CPU0_P0P1_DP<20>")
	)
	(segment
		(start 322.231004 -167.351456)
		(end 314.729368 -165.234112)
		(width 0.14732)
		(layer "In6.Cu")
		(net "UPI_CPU1_CPU0_P0P1_DP<20>")
	)
	(segment
		(start 167.050974 -154.796998)
		(end 165.105842 -155.476194)
		(width 0.14732)
		(layer "In6.Cu")
		(net "UPI_CPU1_CPU0_P0P1_DP<20>")
	)
	(segment
		(start 174.95393 -159.38246)
		(end 174.75581 -159.444436)
		(width 0.14732)
		(layer "In6.Cu")
		(net "UPI_CPU1_CPU0_P0P1_DP<20>")
	)
	(segment
		(start 160.746694 -158.256478)
		(end 160.746948 -158.256478)
		(width 0.14732)
		(layer "In6.Cu")
		(net "UPI_CPU1_CPU0_P0P1_DP<20>")
	)
	(segment
		(start 159.919416 -159.033464)
		(end 159.495744 -158.93288)
		(width 0.14732)
		(layer "In6.Cu")
		(net "UPI_CPU1_CPU0_P0P1_DP<20>")
	)
	(segment
		(start 335.785968 -174.297594)
		(end 336.231992 -173.447456)
		(width 0.14732)
		(layer "In6.Cu")
		(net "UPI_CPU1_CPU0_P0P1_DP<20>")
	)
	(segment
		(start 197.526402 -165.01237)
		(end 194.767962 -165.359588)
		(width 0.14732)
		(layer "In6.Cu")
		(net "UPI_CPU1_CPU0_P0P1_DP<20>")
	)
	(segment
		(start 331.274166 -170.498516)
		(end 330.858622 -170.628056)
		(width 0.14732)
		(layer "In6.Cu")
		(net "UPI_CPU1_CPU0_P0P1_DP<20>")
	)
	(segment
		(start 194.767962 -165.359588)
		(end 189.475364 -165.359588)
		(width 0.14732)
		(layer "In6.Cu")
		(net "UPI_CPU1_CPU0_P0P1_DP<20>")
	)
	(segment
		(start 155.973272 -161.46526)
		(end 155.5496 -161.364676)
		(width 0.14732)
		(layer "In6.Cu")
		(net "UPI_CPU1_CPU0_P0P1_DP<20>")
	)
	(segment
		(start 175.892206 -158.252922)
		(end 175.476916 -158.383224)
		(width 0.14732)
		(layer "In6.Cu")
		(net "UPI_CPU1_CPU0_P0P1_DP<20>")
	)
	(segment
		(start 155.5496 -161.364676)
		(end 133.924294 -174.691802)
		(width 0.14732)
		(layer "In6.Cu")
		(net "UPI_CPU1_CPU0_P0P1_DP<20>")
	)
	(segment
		(start 107.654598 -214.05977)
		(end 107.570016 -214.033608)
		(width 0.0889)
		(layer "In6.Cu")
		(net "UPI_CPU1_CPU0_P0P1_DP<20>")
	)
	(segment
		(start 157.522672 -160.148778)
		(end 156.826966 -160.57753)
		(width 0.14732)
		(layer "In6.Cu")
		(net "UPI_CPU1_CPU0_P0P1_DP<20>")
	)
	(segment
		(start 350.089724 -179.224432)
		(end 349.549212 -179.079652)
		(width 0.14732)
		(layer "In6.Cu")
		(net "UPI_CPU1_CPU0_P0P1_DP<20>")
	)
	(segment
		(start 169.257218 -154.855672)
		(end 167.050974 -154.796998)
		(width 0.14732)
		(layer "In6.Cu")
		(net "UPI_CPU1_CPU0_P0P1_DP<20>")
	)
	(segment
		(start 165.105842 -155.476194)
		(end 160.77311 -158.145734)
		(width 0.14732)
		(layer "In6.Cu")
		(net "UPI_CPU1_CPU0_P0P1_DP<20>")
	)
	(segment
		(start 174.56277 -157.557724)
		(end 171.88942 -156.158946)
		(width 0.14732)
		(layer "In6.Cu")
		(net "UPI_CPU1_CPU0_P0P1_DP<20>")
	)
	(segment
		(start 160.956752 -160.716722)
		(end 159.919416 -159.033464)
		(width 0.14732)
		(layer "In6.Cu")
		(net "UPI_CPU1_CPU0_P0P1_DP<20>")
	)
	(segment
		(start 333.733902 -173.220888)
		(end 334.179926 -172.37075)
		(width 0.14732)
		(layer "In6.Cu")
		(net "UPI_CPU1_CPU0_P0P1_DP<20>")
	)
	(segment
		(start 332.12786 -171.294044)
		(end 331.99832 -170.8785)
		(width 0.14732)
		(layer "In6.Cu")
		(net "UPI_CPU1_CPU0_P0P1_DP<20>")
	)
	(segment
		(start 331.99832 -170.8785)
		(end 331.274166 -170.498516)
		(width 0.14732)
		(layer "In6.Cu")
		(net "UPI_CPU1_CPU0_P0P1_DP<20>")
	)
	(segment
		(start 107.744006 -211.77123)
		(end 107.744006 -211.793328)
		(width 0.0889)
		(layer "In6.Cu")
		(net "UPI_CPU1_CPU0_P0P1_DP<20>")
	)
	(segment
		(start 174.75581 -159.444436)
		(end 174.232062 -159.17037)
		(width 0.14732)
		(layer "In6.Cu")
		(net "UPI_CPU1_CPU0_P0P1_DP<20>")
	)
	(segment
		(start 160.77311 -158.145734)
		(end 160.746694 -158.256478)
		(width 0.14732)
		(layer "In6.Cu")
		(net "UPI_CPU1_CPU0_P0P1_DP<20>")
	)
	(segment
		(start 161.709862 -160.252664)
		(end 161.661856 -160.454594)
		(width 0.14732)
		(layer "In6.Cu")
		(net "UPI_CPU1_CPU0_P0P1_DP<20>")
	)
	(segment
		(start 160.746948 -158.256478)
		(end 160.672526 -158.569406)
		(width 0.14732)
		(layer "In6.Cu")
		(net "UPI_CPU1_CPU0_P0P1_DP<20>")
	)
	(segment
		(start 189.475364 -165.359588)
		(end 175.892206 -158.252922)
		(width 0.14732)
		(layer "In6.Cu")
		(net "UPI_CPU1_CPU0_P0P1_DP<20>")
	)
	(segment
		(start 334.962754 -172.781468)
		(end 334.51673 -173.631606)
		(width 0.14732)
		(layer "In6.Cu")
		(net "UPI_CPU1_CPU0_P0P1_DP<20>")
	)
	(segment
		(start 332.464664 -172.5549)
		(end 332.266036 -172.616876)
		(width 0.14732)
		(layer "In6.Cu")
		(net "UPI_CPU1_CPU0_P0P1_DP<20>")
	)
	(segment
		(start 329.62977 -171.067476)
		(end 330.075794 -170.217338)
		(width 0.14732)
		(layer "In6.Cu")
		(net "UPI_CPU1_CPU0_P0P1_DP<20>")
	)
	(segment
		(start 348.920308 -178.602132)
		(end 336.722974 -174.955454)
		(width 0.14732)
		(layer "In6.Cu")
		(net "UPI_CPU1_CPU0_P0P1_DP<20>")
	)
	(segment
		(start 329.946254 -169.801794)
		(end 329.2221 -169.42181)
		(width 0.14732)
		(layer "In6.Cu")
		(net "UPI_CPU1_CPU0_P0P1_DP<20>")
	)
	(segment
		(start 107.785916 -211.835238)
		(end 107.785916 -212.301836)
		(width 0.0889)
		(layer "In6.Cu")
		(net "UPI_CPU1_CPU0_P0P1_DP<20>")
	)
	(segment
		(start 330.858622 -170.628056)
		(end 330.412598 -171.478194)
		(width 0.14732)
		(layer "In6.Cu")
		(net "UPI_CPU1_CPU0_P0P1_DP<20>")
	)
	(segment
		(start 107.686602 -212.66785)
		(end 107.785916 -212.767164)
		(width 0.0889)
		(layer "In6.Cu")
		(net "UPI_CPU1_CPU0_P0P1_DP<20>")
	)
	(segment
		(start 161.158682 -160.764728)
		(end 160.956752 -160.716722)
		(width 0.14732)
		(layer "In6.Cu")
		(net "UPI_CPU1_CPU0_P0P1_DP<20>")
	)
	(segment
		(start 158.800038 -159.361632)
		(end 158.773622 -159.472376)
		(width 0.14732)
		(layer "In6.Cu")
		(net "UPI_CPU1_CPU0_P0P1_DP<20>")
	)
	(segment
		(start 349.548704 -179.07889)
		(end 349.400368 -178.82235)
		(width 0.14732)
		(layer "In6.Cu")
		(net "UPI_CPU1_CPU0_P0P1_DP<20>")
	)
	(segment
		(start 333.326232 -171.575222)
		(end 332.910688 -171.704762)
		(width 0.14732)
		(layer "In6.Cu")
		(net "UPI_CPU1_CPU0_P0P1_DP<20>")
	)
	(segment
		(start 160.672526 -158.569406)
		(end 161.709862 -160.252664)
		(width 0.14732)
		(layer "In6.Cu")
		(net "UPI_CPU1_CPU0_P0P1_DP<20>")
	)
	(segment
		(start 107.744006 -211.793328)
		(end 107.785916 -211.835238)
		(width 0.0889)
		(layer "In6.Cu")
		(net "UPI_CPU1_CPU0_P0P1_DP<20>")
	)
	(segment
		(start 159.89681 -161.728404)
		(end 159.848804 -161.930334)
		(width 0.14732)
		(layer "In6.Cu")
		(net "UPI_CPU1_CPU0_P0P1_DP<20>")
	)
	(segment
		(start 276.213824 -165.369748)
		(end 237.706154 -155.478988)
		(width 0.14732)
		(layer "In6.Cu")
		(net "UPI_CPU1_CPU0_P0P1_DP<20>")
	)
	(segment
		(start 328.360532 -170.401488)
		(end 328.161904 -170.463464)
		(width 0.14732)
		(layer "In6.Cu")
		(net "UPI_CPU1_CPU0_P0P1_DP<20>")
	)
	(segment
		(start 107.785916 -213.499192)
		(end 107.785916 -213.8934)
		(width 0.0889)
		(layer "In6.Cu")
		(net "UPI_CPU1_CPU0_P0P1_DP<20>")
	)
	(segment
		(start 107.785916 -213.033864)
		(end 107.686602 -213.133178)
		(width 0.0889)
		(layer "In6.Cu")
		(net "UPI_CPU1_CPU0_P0P1_DP<20>")
	)
	(segment
		(start 157.061154 -162.950906)
		(end 156.859224 -162.9029)
		(width 0.14732)
		(layer "In6.Cu")
		(net "UPI_CPU1_CPU0_P0P1_DP<20>")
	)
	(segment
		(start 334.318102 -173.693582)
		(end 333.795878 -173.419516)
		(width 0.14732)
		(layer "In6.Cu")
		(net "UPI_CPU1_CPU0_P0P1_DP<20>")
	)
	(segment
		(start 333.795878 -173.419516)
		(end 333.733902 -173.220888)
		(width 0.14732)
		(layer "In6.Cu")
		(net "UPI_CPU1_CPU0_P0P1_DP<20>")
	)
	(segment
		(start 302.49368 -164.98443)
		(end 280.165302 -165.369748)
		(width 0.14732)
		(layer "In6.Cu")
		(net "UPI_CPU1_CPU0_P0P1_DP<20>")
	)
	(segment
		(start 329.691746 -171.266104)
		(end 329.62977 -171.067476)
		(width 0.14732)
		(layer "In6.Cu")
		(net "UPI_CPU1_CPU0_P0P1_DP<20>")
	)
	(segment
		(start 234.505246 -155.478988)
		(end 197.526402 -165.01237)
		(width 0.14732)
		(layer "In6.Cu")
		(net "UPI_CPU1_CPU0_P0P1_DP<20>")
	)
	(segment
		(start 107.686602 -213.399878)
		(end 107.785916 -213.499192)
		(width 0.0889)
		(layer "In6.Cu")
		(net "UPI_CPU1_CPU0_P0P1_DP<20>")
	)
	(segment
		(start 171.88942 -156.158946)
		(end 169.257218 -154.855672)
		(width 0.14732)
		(layer "In6.Cu")
		(net "UPI_CPU1_CPU0_P0P1_DP<20>")
	)
	(segment
		(start 174.693072 -157.973014)
		(end 174.56277 -157.557724)
		(width 0.14732)
		(layer "In6.Cu")
		(net "UPI_CPU1_CPU0_P0P1_DP<20>")
	)
	(segment
		(start 336.231992 -173.447456)
		(end 336.102452 -173.031912)
		(width 0.14732)
		(layer "In6.Cu")
		(net "UPI_CPU1_CPU0_P0P1_DP<20>")
	)
	(segment
		(start 107.570016 -214.033608)
		(end 107.411266 -213.732618)
		(width 0.0889)
		(layer "In6.Cu")
		(net "UPI_CPU1_CPU0_P0P1_DP<20>")
	)
	(segment
		(start 158.773622 -159.472376)
		(end 158.773876 -159.472376)
		(width 0.14732)
		(layer "In6.Cu")
		(net "UPI_CPU1_CPU0_P0P1_DP<20>")
	)
	(segment
		(start 336.722974 -174.955454)
		(end 335.847944 -174.496222)
		(width 0.14732)
		(layer "In6.Cu")
		(net "UPI_CPU1_CPU0_P0P1_DP<20>")
	)
	(segment
		(start 237.706154 -155.478988)
		(end 234.505246 -155.478988)
		(width 0.14732)
		(layer "In6.Cu")
		(net "UPI_CPU1_CPU0_P0P1_DP<20>")
	)
	(segment
		(start 159.848804 -161.930334)
		(end 159.34563 -162.240468)
		(width 0.14732)
		(layer "In6.Cu")
		(net "UPI_CPU1_CPU0_P0P1_DP<20>")
	)
	(segment
		(start 107.744006 -211.40547)
		(end 107.744006 -211.77123)
		(width 0.14732)
		(layer "In6.Cu")
		(net "UPI_CPU1_CPU0_P0P1_DP<20>")
	)
	(segment
		(start 107.785916 -212.767164)
		(end 107.785916 -213.033864)
		(width 0.0889)
		(layer "In6.Cu")
		(net "UPI_CPU1_CPU0_P0P1_DP<20>")
	)
	(segment
		(start 121.751344 -186.139836)
		(end 112.880648 -197.306438)
		(width 0.14732)
		(layer "In6.Cu")
		(net "UPI_CPU1_CPU0_P0P1_DP<20>")
	)
	(segment
		(start 159.1437 -162.192462)
		(end 157.946344 -160.249362)
		(width 0.14732)
		(layer "In6.Cu")
		(net "UPI_CPU1_CPU0_P0P1_DP<20>")
	)
	(segment
		(start 280.165302 -165.369748)
		(end 276.213824 -165.369748)
		(width 0.14732)
		(layer "In6.Cu")
		(net "UPI_CPU1_CPU0_P0P1_DP<20>")
	)
	(segment
		(start 158.699454 -159.785304)
		(end 159.89681 -161.728404)
		(width 0.14732)
		(layer "In6.Cu")
		(net "UPI_CPU1_CPU0_P0P1_DP<20>")
	)
	(segment
		(start 156.726382 -161.001202)
		(end 157.612334 -162.438842)
		(width 0.14732)
		(layer "In6.Cu")
		(net "UPI_CPU1_CPU0_P0P1_DP<20>")
	)
	(segment
		(start 161.661856 -160.454594)
		(end 161.158682 -160.764728)
		(width 0.14732)
		(layer "In6.Cu")
		(net "UPI_CPU1_CPU0_P0P1_DP<20>")
	)
	(segment
		(start 328.161904 -170.463464)
		(end 322.231004 -167.351456)
		(width 0.14732)
		(layer "In6.Cu")
		(net "UPI_CPU1_CPU0_P0P1_DP<20>")
	)
	(segment
		(start 174.170086 -158.97225)
		(end 174.693072 -157.973014)
		(width 0.14732)
		(layer "In6.Cu")
		(net "UPI_CPU1_CPU0_P0P1_DP<20>")
	)
	(segment
		(start 159.34563 -162.240468)
		(end 159.1437 -162.192462)
		(width 0.14732)
		(layer "In6.Cu")
		(net "UPI_CPU1_CPU0_P0P1_DP<20>")
	)
	(segment
		(start 112.880648 -197.306438)
		(end 107.744006 -211.40547)
		(width 0.14732)
		(layer "In6.Cu")
		(net "UPI_CPU1_CPU0_P0P1_DP<20>")
	)
	(segment
		(start 156.826966 -160.57753)
		(end 156.726382 -161.001202)
		(width 0.14732)
		(layer "In6.Cu")
		(net "UPI_CPU1_CPU0_P0P1_DP<20>")
	)
	(segment
		(start 156.859224 -162.9029)
		(end 155.973272 -161.46526)
		(width 0.14732)
		(layer "In6.Cu")
		(net "UPI_CPU1_CPU0_P0P1_DP<20>")
	)
	(segment
		(start 335.847944 -174.496222)
		(end 335.785968 -174.297594)
		(width 0.14732)
		(layer "In6.Cu")
		(net "UPI_CPU1_CPU0_P0P1_DP<20>")
	)
	(segment
		(start 349.549212 -179.079652)
		(end 349.548704 -179.07889)
		(width 0.14732)
		(layer "In6.Cu")
		(net "UPI_CPU1_CPU0_P0P1_DP<20>")
	)
	(segment
		(start 157.946344 -160.249362)
		(end 157.522672 -160.148778)
		(width 0.14732)
		(layer "In6.Cu")
		(net "UPI_CPU1_CPU0_P0P1_DP<20>")
	)
	(segment
		(start 331.681836 -172.144182)
		(end 332.12786 -171.294044)
		(width 0.14732)
		(layer "In6.Cu")
		(net "UPI_CPU1_CPU0_P0P1_DP<20>")
	)
	(segment
		(start 336.102452 -173.031912)
		(end 335.378298 -172.651928)
		(width 0.14732)
		(layer "In6.Cu")
		(net "UPI_CPU1_CPU0_P0P1_DP<20>")
	)
	(segment
		(start 349.400368 -178.82235)
		(end 348.920308 -178.602132)
		(width 0.14732)
		(layer "In6.Cu")
		(net "UPI_CPU1_CPU0_P0P1_DP<20>")
	)
	(segment
		(start 331.743812 -172.34281)
		(end 331.681836 -172.144182)
		(width 0.14732)
		(layer "In6.Cu")
		(net "UPI_CPU1_CPU0_P0P1_DP<20>")
	)
	(segment
		(start 107.686602 -212.40115)
		(end 107.686602 -212.66785)
		(width 0.0889)
		(layer "In6.Cu")
		(net "UPI_CPU1_CPU0_P0P1_DP<20>")
	)
	(segment
		(start 158.848552 -159.33166)
		(end 158.800038 -159.361632)
		(width 0.14732)
		(layer "In6.Cu")
		(net "UPI_CPU1_CPU0_P0P1_DP<20>")
	)
	(segment
		(start 330.21397 -171.54017)
		(end 329.691746 -171.266104)
		(width 0.14732)
		(layer "In6.Cu")
		(net "UPI_CPU1_CPU0_P0P1_DP<20>")
	)
	(segment
		(start 334.51673 -173.631606)
		(end 334.318102 -173.693582)
		(width 0.14732)
		(layer "In6.Cu")
		(net "UPI_CPU1_CPU0_P0P1_DP<20>")
	)
	(segment
		(start 107.686602 -213.133178)
		(end 107.686602 -213.399878)
		(width 0.0889)
		(layer "In6.Cu")
		(net "UPI_CPU1_CPU0_P0P1_DP<20>")
	)
	(arc
		(start 107.785916 -213.8934)
		(mid 107.731246 -213.985256)
		(end 107.654598 -214.05977)
		(width 0.0889)
		(layer "In6.Cu")
		(net "UPI_CPU1_CPU0_P0P1_DP<20>")
	)
	(segment
		(start 375.731532 -168.735502)
		(end 376.055128 -169.000678)
		(width 0.13208)
		(layer "F.Cu")
		(net "UPI_CPU1_CPU0_P0P1_DP<1>")
	)
	(segment
		(start 376.22988 -168.983152)
		(end 376.536712 -169.234612)
		(width 0.13208)
		(layer "F.Cu")
		(net "UPI_CPU1_CPU0_P0P1_DP<1>")
	)
	(segment
		(start 89.555066 -215.436958)
		(end 89.554812 -215.436704)
		(width 0.13208)
		(layer "F.Cu")
		(net "UPI_CPU1_CPU0_P0P1_DP<1>")
	)
	(segment
		(start 385.45262 -178.09337)
		(end 389.383778 -187.584588)
		(width 0.13208)
		(layer "F.Cu")
		(net "UPI_CPU1_CPU0_P0P1_DP<1>")
	)
	(segment
		(start 382.412494 -215.650826)
		(end 382.411732 -215.651334)
		(width 0.0889)
		(layer "F.Cu")
		(net "UPI_CPU1_CPU0_P0P1_DP<1>")
	)
	(segment
		(start 376.553984 -169.409872)
		(end 377.748292 -170.389042)
		(width 0.13208)
		(layer "F.Cu")
		(net "UPI_CPU1_CPU0_P0P1_DP<1>")
	)
	(segment
		(start 382.700784 -214.688166)
		(end 382.799844 -214.787226)
		(width 0.0889)
		(layer "F.Cu")
		(net "UPI_CPU1_CPU0_P0P1_DP<1>")
	)
	(segment
		(start 380.130558 -199.001888)
		(end 380.130558 -199.001634)
		(width 0.13208)
		(layer "F.Cu")
		(net "UPI_CPU1_CPU0_P0P1_DP<1>")
	)
	(segment
		(start 376.536712 -169.234612)
		(end 376.553984 -169.409872)
		(width 0.13208)
		(layer "F.Cu")
		(net "UPI_CPU1_CPU0_P0P1_DP<1>")
	)
	(segment
		(start 382.411732 -215.651334)
		(end 382.411732 -215.651588)
		(width 0.0889)
		(layer "F.Cu")
		(net "UPI_CPU1_CPU0_P0P1_DP<1>")
	)
	(segment
		(start 376.055128 -169.000678)
		(end 376.22988 -168.983152)
		(width 0.13208)
		(layer "F.Cu")
		(net "UPI_CPU1_CPU0_P0P1_DP<1>")
	)
	(segment
		(start 378.998734 -205.856078)
		(end 379.79223 -207.77073)
		(width 0.0889)
		(layer "F.Cu")
		(net "UPI_CPU1_CPU0_P0P1_DP<1>")
	)
	(segment
		(start 382.799844 -214.939626)
		(end 382.700784 -215.038686)
		(width 0.0889)
		(layer "F.Cu")
		(net "UPI_CPU1_CPU0_P0P1_DP<1>")
	)
	(segment
		(start 379.033278 -202.51293)
		(end 379.033278 -205.205076)
		(width 0.13208)
		(layer "F.Cu")
		(net "UPI_CPU1_CPU0_P0P1_DP<1>")
	)
	(segment
		(start 388.27837 -192.330578)
		(end 383.827274 -195.304918)
		(width 0.13208)
		(layer "F.Cu")
		(net "UPI_CPU1_CPU0_P0P1_DP<1>")
	)
	(segment
		(start 379.79223 -207.77073)
		(end 381.867918 -209.846418)
		(width 0.0889)
		(layer "F.Cu")
		(net "UPI_CPU1_CPU0_P0P1_DP<1>")
	)
	(segment
		(start 382.700784 -215.038686)
		(end 382.700784 -215.23325)
		(width 0.0889)
		(layer "F.Cu")
		(net "UPI_CPU1_CPU0_P0P1_DP<1>")
	)
	(segment
		(start 374.831356 -167.510968)
		(end 374.27535 -167.661336)
		(width 0.13208)
		(layer "F.Cu")
		(net "UPI_CPU1_CPU0_P0P1_DP<1>")
	)
	(segment
		(start 374.10644 -168.175686)
		(end 374.186196 -168.28135)
		(width 0.13208)
		(layer "F.Cu")
		(net "UPI_CPU1_CPU0_P0P1_DP<1>")
	)
	(segment
		(start 382.700784 -211.857336)
		(end 382.700784 -214.688166)
		(width 0.0889)
		(layer "F.Cu")
		(net "UPI_CPU1_CPU0_P0P1_DP<1>")
	)
	(segment
		(start 382.494536 -215.600788)
		(end 382.412494 -215.650826)
		(width 0.0889)
		(layer "F.Cu")
		(net "UPI_CPU1_CPU0_P0P1_DP<1>")
	)
	(segment
		(start 380.130558 -199.001634)
		(end 379.438154 -200.67397)
		(width 0.13208)
		(layer "F.Cu")
		(net "UPI_CPU1_CPU0_P0P1_DP<1>")
	)
	(segment
		(start 382.424432 -215.972644)
		(end 382.605534 -215.972644)
		(width 0.0889)
		(layer "F.Cu")
		(net "UPI_CPU1_CPU0_P0P1_DP<1>")
	)
	(segment
		(start 379.033278 -205.205076)
		(end 379.033278 -205.227174)
		(width 0.0889)
		(layer "F.Cu")
		(net "UPI_CPU1_CPU0_P0P1_DP<1>")
	)
	(segment
		(start 379.362716 -200.856088)
		(end 379.033278 -202.51293)
		(width 0.13208)
		(layer "F.Cu")
		(net "UPI_CPU1_CPU0_P0P1_DP<1>")
	)
	(segment
		(start 89.555066 -215.972644)
		(end 89.555066 -215.436958)
		(width 0.13208)
		(layer "F.Cu")
		(net "UPI_CPU1_CPU0_P0P1_DP<1>")
	)
	(segment
		(start 382.31572 -215.887046)
		(end 382.348486 -215.933274)
		(width 0.0889)
		(layer "F.Cu")
		(net "UPI_CPU1_CPU0_P0P1_DP<1>")
	)
	(segment
		(start 389.383778 -187.584588)
		(end 389.383778 -191.224916)
		(width 0.13208)
		(layer "F.Cu")
		(net "UPI_CPU1_CPU0_P0P1_DP<1>")
	)
	(segment
		(start 389.383778 -191.224916)
		(end 388.27837 -192.330578)
		(width 0.13208)
		(layer "F.Cu")
		(net "UPI_CPU1_CPU0_P0P1_DP<1>")
	)
	(segment
		(start 382.411732 -215.651588)
		(end 382.389126 -215.674194)
		(width 0.0889)
		(layer "F.Cu")
		(net "UPI_CPU1_CPU0_P0P1_DP<1>")
	)
	(segment
		(start 382.799844 -214.787226)
		(end 382.799844 -214.939626)
		(width 0.0889)
		(layer "F.Cu")
		(net "UPI_CPU1_CPU0_P0P1_DP<1>")
	)
	(segment
		(start 374.27535 -167.661336)
		(end 374.114314 -167.931592)
		(width 0.13208)
		(layer "F.Cu")
		(net "UPI_CPU1_CPU0_P0P1_DP<1>")
	)
	(segment
		(start 377.748292 -170.389042)
		(end 385.45262 -178.09337)
		(width 0.13208)
		(layer "F.Cu")
		(net "UPI_CPU1_CPU0_P0P1_DP<1>")
	)
	(segment
		(start 381.867918 -209.846418)
		(end 382.700784 -211.857336)
		(width 0.0889)
		(layer "F.Cu")
		(net "UPI_CPU1_CPU0_P0P1_DP<1>")
	)
	(segment
		(start 379.033278 -205.227174)
		(end 378.998734 -205.261718)
		(width 0.0889)
		(layer "F.Cu")
		(net "UPI_CPU1_CPU0_P0P1_DP<1>")
	)
	(segment
		(start 383.827274 -195.304918)
		(end 380.130558 -199.001888)
		(width 0.13208)
		(layer "F.Cu")
		(net "UPI_CPU1_CPU0_P0P1_DP<1>")
	)
	(segment
		(start 378.998734 -205.261718)
		(end 378.998734 -205.856078)
		(width 0.0889)
		(layer "F.Cu")
		(net "UPI_CPU1_CPU0_P0P1_DP<1>")
	)
	(segment
		(start 382.31572 -215.851486)
		(end 382.31572 -215.887046)
		(width 0.0889)
		(layer "F.Cu")
		(net "UPI_CPU1_CPU0_P0P1_DP<1>")
	)
	(segment
		(start 374.114314 -167.931592)
		(end 374.10644 -168.175686)
		(width 0.13208)
		(layer "F.Cu")
		(net "UPI_CPU1_CPU0_P0P1_DP<1>")
	)
	(segment
		(start 374.186196 -168.28135)
		(end 375.22023 -168.543732)
		(width 0.13208)
		(layer "F.Cu")
		(net "UPI_CPU1_CPU0_P0P1_DP<1>")
	)
	(segment
		(start 379.438154 -200.67397)
		(end 379.362716 -200.856088)
		(width 0.13208)
		(layer "F.Cu")
		(net "UPI_CPU1_CPU0_P0P1_DP<1>")
	)
	(segment
		(start 375.22023 -168.543732)
		(end 375.731532 -168.735502)
		(width 0.13208)
		(layer "F.Cu")
		(net "UPI_CPU1_CPU0_P0P1_DP<1>")
	)
	(arc
		(start 382.700784 -215.23325)
		(mid 382.645693 -215.443968)
		(end 382.494536 -215.600788)
		(width 0.0889)
		(layer "F.Cu")
		(net "UPI_CPU1_CPU0_P0P1_DP<1>")
	)
	(arc
		(start 382.389126 -215.674194)
		(mid 382.334775 -215.755536)
		(end 382.31572 -215.851486)
		(width 0.0889)
		(layer "F.Cu")
		(net "UPI_CPU1_CPU0_P0P1_DP<1>")
	)
	(arc
		(start 382.348486 -215.933274)
		(mid 382.381663 -215.962208)
		(end 382.424432 -215.972644)
		(width 0.0889)
		(layer "F.Cu")
		(net "UPI_CPU1_CPU0_P0P1_DP<1>")
	)
	(segment
		(start 374.772682 -166.820596)
		(end 374.686576 -166.969694)
		(width 0.14732)
		(layer "In6.Cu")
		(net "UPI_CPU1_CPU0_P0P1_DP<1>")
	)
	(segment
		(start 89.711276 -215.165686)
		(end 89.687146 -215.076532)
		(width 0.0889)
		(layer "In6.Cu")
		(net "UPI_CPU1_CPU0_P0P1_DP<1>")
	)
	(segment
		(start 89.820242 -213.765892)
		(end 89.820242 -211.804758)
		(width 0.0889)
		(layer "In6.Cu")
		(net "UPI_CPU1_CPU0_P0P1_DP<1>")
	)
	(segment
		(start 334.008476 -142.41526)
		(end 360.17708 -160.367726)
		(width 0.14732)
		(layer "In6.Cu")
		(net "UPI_CPU1_CPU0_P0P1_DP<1>")
	)
	(segment
		(start 369.5192 -167.843708)
		(end 369.985798 -167.806624)
		(width 0.14732)
		(layer "In6.Cu")
		(net "UPI_CPU1_CPU0_P0P1_DP<1>")
	)
	(segment
		(start 374.686068 -166.970456)
		(end 374.831356 -167.510968)
		(width 0.14732)
		(layer "In6.Cu")
		(net "UPI_CPU1_CPU0_P0P1_DP<1>")
	)
	(segment
		(start 319.533778 -138.703812)
		(end 334.008476 -142.41526)
		(width 0.14732)
		(layer "In6.Cu")
		(net "UPI_CPU1_CPU0_P0P1_DP<1>")
	)
	(segment
		(start 89.778332 -211.762848)
		(end 89.778332 -211.74075)
		(width 0.0889)
		(layer "In6.Cu")
		(net "UPI_CPU1_CPU0_P0P1_DP<1>")
	)
	(segment
		(start 86.275672 -204.705204)
		(end 96.303592 -192.788286)
		(width 0.14732)
		(layer "In6.Cu")
		(net "UPI_CPU1_CPU0_P0P1_DP<1>")
	)
	(segment
		(start 159.894016 -139.75461)
		(end 169.527982 -136.456674)
		(width 0.14732)
		(layer "In6.Cu")
		(net "UPI_CPU1_CPU0_P0P1_DP<1>")
	)
	(segment
		(start 123.391676 -162.20694)
		(end 159.894016 -139.75461)
		(width 0.14732)
		(layer "In6.Cu")
		(net "UPI_CPU1_CPU0_P0P1_DP<1>")
	)
	(segment
		(start 89.459562 -214.637366)
		(end 89.459562 -214.126572)
		(width 0.0889)
		(layer "In6.Cu")
		(net "UPI_CPU1_CPU0_P0P1_DP<1>")
	)
	(segment
		(start 86.405974 -207.579214)
		(end 86.075266 -206.86776)
		(width 0.14732)
		(layer "In6.Cu")
		(net "UPI_CPU1_CPU0_P0P1_DP<1>")
	)
	(segment
		(start 89.459562 -214.126572)
		(end 89.820242 -213.765892)
		(width 0.0889)
		(layer "In6.Cu")
		(net "UPI_CPU1_CPU0_P0P1_DP<1>")
	)
	(segment
		(start 89.459308 -214.636858)
		(end 89.459562 -214.637366)
		(width 0.0889)
		(layer "In6.Cu")
		(net "UPI_CPU1_CPU0_P0P1_DP<1>")
	)
	(segment
		(start 312.03646 -138.703812)
		(end 319.533778 -138.703812)
		(width 0.14732)
		(layer "In6.Cu")
		(net "UPI_CPU1_CPU0_P0P1_DP<1>")
	)
	(segment
		(start 89.778332 -211.74075)
		(end 89.778332 -210.951572)
		(width 0.14732)
		(layer "In6.Cu")
		(net "UPI_CPU1_CPU0_P0P1_DP<1>")
	)
	(segment
		(start 89.820242 -211.804758)
		(end 89.778332 -211.762848)
		(width 0.0889)
		(layer "In6.Cu")
		(net "UPI_CPU1_CPU0_P0P1_DP<1>")
	)
	(segment
		(start 89.778332 -210.951572)
		(end 86.405974 -207.579214)
		(width 0.14732)
		(layer "In6.Cu")
		(net "UPI_CPU1_CPU0_P0P1_DP<1>")
	)
	(segment
		(start 238.602266 -137.591038)
		(end 271.347438 -136.993376)
		(width 0.14732)
		(layer "In6.Cu")
		(net "UPI_CPU1_CPU0_P0P1_DP<1>")
	)
	(segment
		(start 369.985798 -167.806624)
		(end 373.357648 -165.715188)
		(width 0.14732)
		(layer "In6.Cu")
		(net "UPI_CPU1_CPU0_P0P1_DP<1>")
	)
	(segment
		(start 271.347438 -136.993376)
		(end 312.036206 -138.703558)
		(width 0.14732)
		(layer "In6.Cu")
		(net "UPI_CPU1_CPU0_P0P1_DP<1>")
	)
	(segment
		(start 169.527982 -136.456674)
		(end 238.602266 -137.591038)
		(width 0.14732)
		(layer "In6.Cu")
		(net "UPI_CPU1_CPU0_P0P1_DP<1>")
	)
	(segment
		(start 360.17708 -160.367726)
		(end 368.914934 -167.589454)
		(width 0.14732)
		(layer "In6.Cu")
		(net "UPI_CPU1_CPU0_P0P1_DP<1>")
	)
	(segment
		(start 368.914934 -167.589454)
		(end 369.5192 -167.843708)
		(width 0.14732)
		(layer "In6.Cu")
		(net "UPI_CPU1_CPU0_P0P1_DP<1>")
	)
	(segment
		(start 312.036206 -138.703558)
		(end 312.03646 -138.703812)
		(width 0.14732)
		(layer "In6.Cu")
		(net "UPI_CPU1_CPU0_P0P1_DP<1>")
	)
	(segment
		(start 374.8278 -166.185596)
		(end 374.8278 -166.765224)
		(width 0.14732)
		(layer "In6.Cu")
		(net "UPI_CPU1_CPU0_P0P1_DP<1>")
	)
	(segment
		(start 86.046564 -205.969108)
		(end 86.275672 -204.705204)
		(width 0.14732)
		(layer "In6.Cu")
		(net "UPI_CPU1_CPU0_P0P1_DP<1>")
	)
	(segment
		(start 98.616516 -186.637168)
		(end 102.343458 -181.999128)
		(width 0.14732)
		(layer "In6.Cu")
		(net "UPI_CPU1_CPU0_P0P1_DP<1>")
	)
	(segment
		(start 374.357392 -165.715188)
		(end 374.8278 -166.185596)
		(width 0.14732)
		(layer "In6.Cu")
		(net "UPI_CPU1_CPU0_P0P1_DP<1>")
	)
	(segment
		(start 89.554812 -215.436704)
		(end 89.711276 -215.165686)
		(width 0.0889)
		(layer "In6.Cu")
		(net "UPI_CPU1_CPU0_P0P1_DP<1>")
	)
	(segment
		(start 102.343458 -181.999128)
		(end 123.391676 -162.20694)
		(width 0.14732)
		(layer "In6.Cu")
		(net "UPI_CPU1_CPU0_P0P1_DP<1>")
	)
	(segment
		(start 86.075266 -206.86776)
		(end 86.046564 -205.969108)
		(width 0.14732)
		(layer "In6.Cu")
		(net "UPI_CPU1_CPU0_P0P1_DP<1>")
	)
	(segment
		(start 374.8278 -166.765224)
		(end 374.772682 -166.820596)
		(width 0.14732)
		(layer "In6.Cu")
		(net "UPI_CPU1_CPU0_P0P1_DP<1>")
	)
	(segment
		(start 373.357648 -165.715188)
		(end 374.357392 -165.715188)
		(width 0.14732)
		(layer "In6.Cu")
		(net "UPI_CPU1_CPU0_P0P1_DP<1>")
	)
	(segment
		(start 96.303592 -192.788286)
		(end 98.616516 -186.637168)
		(width 0.14732)
		(layer "In6.Cu")
		(net "UPI_CPU1_CPU0_P0P1_DP<1>")
	)
	(segment
		(start 374.686576 -166.969694)
		(end 374.686068 -166.970456)
		(width 0.14732)
		(layer "In6.Cu")
		(net "UPI_CPU1_CPU0_P0P1_DP<1>")
	)
	(arc
		(start 89.687146 -215.076532)
		(mid 89.678574 -215.070009)
		(end 89.670128 -215.063324)
		(width 0.0889)
		(layer "In6.Cu")
		(net "UPI_CPU1_CPU0_P0P1_DP<1>")
	)
	(arc
		(start 89.670128 -215.063324)
		(mid 89.517697 -214.873342)
		(end 89.459308 -214.636858)
		(width 0.0889)
		(layer "In6.Cu")
		(net "UPI_CPU1_CPU0_P0P1_DP<1>")
	)
	(segment
		(start 364.768384 -213.016592)
		(end 363.071156 -211.319364)
		(width 0.0889)
		(layer "F.Cu")
		(net "UPI_CPU1_CPU0_P0P1_DP<19>")
	)
	(segment
		(start 363.071156 -211.319364)
		(end 359.221532 -209.724752)
		(width 0.0889)
		(layer "F.Cu")
		(net "UPI_CPU1_CPU0_P0P1_DP<19>")
	)
	(segment
		(start 355.228398 -205.227174)
		(end 355.228398 -205.205076)
		(width 0.0889)
		(layer "F.Cu")
		(net "UPI_CPU1_CPU0_P0P1_DP<19>")
	)
	(segment
		(start 356.231952 -194.04711)
		(end 356.294436 -193.733166)
		(width 0.13208)
		(layer "F.Cu")
		(net "UPI_CPU1_CPU0_P0P1_DP<19>")
	)
	(segment
		(start 353.276916 -180.742844)
		(end 353.017074 -180.483256)
		(width 0.13208)
		(layer "F.Cu")
		(net "UPI_CPU1_CPU0_P0P1_DP<19>")
	)
	(segment
		(start 358.530398 -188.335412)
		(end 358.530398 -186.03087)
		(width 0.13208)
		(layer "F.Cu")
		(net "UPI_CPU1_CPU0_P0P1_DP<19>")
	)
	(segment
		(start 353.017074 -180.483256)
		(end 352.970592 -180.123338)
		(width 0.13208)
		(layer "F.Cu")
		(net "UPI_CPU1_CPU0_P0P1_DP<19>")
	)
	(segment
		(start 364.904528 -214.613744)
		(end 364.985554 -214.635334)
		(width 0.0889)
		(layer "F.Cu")
		(net "UPI_CPU1_CPU0_P0P1_DP<19>")
	)
	(segment
		(start 359.221532 -209.724752)
		(end 355.262688 -205.765654)
		(width 0.0889)
		(layer "F.Cu")
		(net "UPI_CPU1_CPU0_P0P1_DP<19>")
	)
	(segment
		(start 355.228398 -199.07504)
		(end 355.233224 -199.070214)
		(width 0.13208)
		(layer "F.Cu")
		(net "UPI_CPU1_CPU0_P0P1_DP<19>")
	)
	(segment
		(start 364.876334 -213.26475)
		(end 364.768384 -213.157054)
		(width 0.0889)
		(layer "F.Cu")
		(net "UPI_CPU1_CPU0_P0P1_DP<19>")
	)
	(segment
		(start 355.233224 -199.070214)
		(end 356.231952 -194.04711)
		(width 0.13208)
		(layer "F.Cu")
		(net "UPI_CPU1_CPU0_P0P1_DP<19>")
	)
	(segment
		(start 354.882196 -181.407054)
		(end 353.276916 -180.742844)
		(width 0.13208)
		(layer "F.Cu")
		(net "UPI_CPU1_CPU0_P0P1_DP<19>")
	)
	(segment
		(start 365.024924 -213.823042)
		(end 365.124238 -213.723728)
		(width 0.0889)
		(layer "F.Cu")
		(net "UPI_CPU1_CPU0_P0P1_DP<19>")
	)
	(segment
		(start 365.124238 -213.723728)
		(end 365.124238 -213.372446)
		(width 0.0889)
		(layer "F.Cu")
		(net "UPI_CPU1_CPU0_P0P1_DP<19>")
	)
	(segment
		(start 106.471466 -215.436958)
		(end 106.471212 -215.436704)
		(width 0.13208)
		(layer "F.Cu")
		(net "UPI_CPU1_CPU0_P0P1_DP<19>")
	)
	(segment
		(start 365.016542 -213.26475)
		(end 364.876334 -213.26475)
		(width 0.0889)
		(layer "F.Cu")
		(net "UPI_CPU1_CPU0_P0P1_DP<19>")
	)
	(segment
		(start 364.768384 -213.157054)
		(end 364.768384 -213.016592)
		(width 0.0889)
		(layer "F.Cu")
		(net "UPI_CPU1_CPU0_P0P1_DP<19>")
	)
	(segment
		(start 355.262688 -205.261464)
		(end 355.228398 -205.227174)
		(width 0.0889)
		(layer "F.Cu")
		(net "UPI_CPU1_CPU0_P0P1_DP<19>")
	)
	(segment
		(start 357.840534 -184.365392)
		(end 354.882196 -181.407054)
		(width 0.13208)
		(layer "F.Cu")
		(net "UPI_CPU1_CPU0_P0P1_DP<19>")
	)
	(segment
		(start 358.530398 -186.03087)
		(end 357.840534 -184.365392)
		(width 0.13208)
		(layer "F.Cu")
		(net "UPI_CPU1_CPU0_P0P1_DP<19>")
	)
	(segment
		(start 365.123984 -214.345012)
		(end 365.123984 -214.074502)
		(width 0.0889)
		(layer "F.Cu")
		(net "UPI_CPU1_CPU0_P0P1_DP<19>")
	)
	(segment
		(start 365.123984 -214.074502)
		(end 365.024924 -213.975442)
		(width 0.0889)
		(layer "F.Cu")
		(net "UPI_CPU1_CPU0_P0P1_DP<19>")
	)
	(segment
		(start 365.124238 -213.372446)
		(end 365.016542 -213.26475)
		(width 0.0889)
		(layer "F.Cu")
		(net "UPI_CPU1_CPU0_P0P1_DP<19>")
	)
	(segment
		(start 356.294436 -193.733166)
		(end 358.530398 -188.335412)
		(width 0.13208)
		(layer "F.Cu")
		(net "UPI_CPU1_CPU0_P0P1_DP<19>")
	)
	(segment
		(start 352.970592 -180.123338)
		(end 353.097846 -179.90312)
		(width 0.13208)
		(layer "F.Cu")
		(net "UPI_CPU1_CPU0_P0P1_DP<19>")
	)
	(segment
		(start 355.262688 -205.765654)
		(end 355.262688 -205.261464)
		(width 0.0889)
		(layer "F.Cu")
		(net "UPI_CPU1_CPU0_P0P1_DP<19>")
	)
	(segment
		(start 365.024924 -213.975442)
		(end 365.024924 -213.823042)
		(width 0.0889)
		(layer "F.Cu")
		(net "UPI_CPU1_CPU0_P0P1_DP<19>")
	)
	(segment
		(start 106.471466 -215.972644)
		(end 106.471466 -215.436958)
		(width 0.13208)
		(layer "F.Cu")
		(net "UPI_CPU1_CPU0_P0P1_DP<19>")
	)
	(segment
		(start 364.749334 -214.344758)
		(end 364.904528 -214.613744)
		(width 0.0889)
		(layer "F.Cu")
		(net "UPI_CPU1_CPU0_P0P1_DP<19>")
	)
	(segment
		(start 353.097846 -179.90312)
		(end 352.950272 -179.351432)
		(width 0.13208)
		(layer "F.Cu")
		(net "UPI_CPU1_CPU0_P0P1_DP<19>")
	)
	(segment
		(start 355.228398 -205.205076)
		(end 355.228398 -199.07504)
		(width 0.13208)
		(layer "F.Cu")
		(net "UPI_CPU1_CPU0_P0P1_DP<19>")
	)
	(arc
		(start 364.985554 -214.635334)
		(mid 365.08752 -214.505786)
		(end 365.123984 -214.345012)
		(width 0.0889)
		(layer "F.Cu")
		(net "UPI_CPU1_CPU0_P0P1_DP<19>")
	)
	(segment
		(start 352.46056 -180.190648)
		(end 352.07956 -179.906168)
		(width 0.14732)
		(layer "In6.Cu")
		(net "UPI_CPU1_CPU0_P0P1_DP<19>")
	)
	(segment
		(start 304.502312 -162.11169)
		(end 304.200814 -161.798)
		(width 0.14732)
		(layer "In6.Cu")
		(net "UPI_CPU1_CPU0_P0P1_DP<19>")
	)
	(segment
		(start 352.99142 -180.0733)
		(end 352.874072 -180.190648)
		(width 0.14732)
		(layer "In6.Cu")
		(net "UPI_CPU1_CPU0_P0P1_DP<19>")
	)
	(segment
		(start 305.699922 -161.828734)
		(end 305.386232 -162.129978)
		(width 0.14732)
		(layer "In6.Cu")
		(net "UPI_CPU1_CPU0_P0P1_DP<19>")
	)
	(segment
		(start 194.715638 -164.526468)
		(end 189.911228 -164.526468)
		(width 0.14732)
		(layer "In6.Cu")
		(net "UPI_CPU1_CPU0_P0P1_DP<19>")
	)
	(segment
		(start 121.068846 -185.639202)
		(end 111.865156 -197.223888)
		(width 0.14732)
		(layer "In6.Cu")
		(net "UPI_CPU1_CPU0_P0P1_DP<19>")
	)
	(segment
		(start 311.151778 -161.941256)
		(end 310.333898 -161.924238)
		(width 0.14732)
		(layer "In6.Cu")
		(net "UPI_CPU1_CPU0_P0P1_DP<19>")
	)
	(segment
		(start 106.84637 -211.835238)
		(end 106.84637 -213.892892)
		(width 0.0889)
		(layer "In6.Cu")
		(net "UPI_CPU1_CPU0_P0P1_DP<19>")
	)
	(segment
		(start 307.70322 -162.17773)
		(end 307.663596 -164.107876)
		(width 0.14732)
		(layer "In6.Cu")
		(net "UPI_CPU1_CPU0_P0P1_DP<19>")
	)
	(segment
		(start 311.558178 -164.335206)
		(end 311.413652 -164.184838)
		(width 0.14732)
		(layer "In6.Cu")
		(net "UPI_CPU1_CPU0_P0P1_DP<19>")
	)
	(segment
		(start 237.811818 -154.645868)
		(end 234.399328 -154.645868)
		(width 0.14732)
		(layer "In6.Cu")
		(net "UPI_CPU1_CPU0_P0P1_DP<19>")
	)
	(segment
		(start 311.413652 -164.184838)
		(end 311.453276 -162.254946)
		(width 0.14732)
		(layer "In6.Cu")
		(net "UPI_CPU1_CPU0_P0P1_DP<19>")
	)
	(segment
		(start 306.924202 -164.239702)
		(end 306.779676 -164.089334)
		(width 0.14732)
		(layer "In6.Cu")
		(net "UPI_CPU1_CPU0_P0P1_DP<19>")
	)
	(segment
		(start 306.8193 -162.159442)
		(end 306.517802 -161.845752)
		(width 0.14732)
		(layer "In6.Cu")
		(net "UPI_CPU1_CPU0_P0P1_DP<19>")
	)
	(segment
		(start 172.315886 -155.321)
		(end 169.48912 -153.921206)
		(width 0.14732)
		(layer "In6.Cu")
		(net "UPI_CPU1_CPU0_P0P1_DP<19>")
	)
	(segment
		(start 314.853066 -164.403024)
		(end 313.874912 -164.382704)
		(width 0.14732)
		(layer "In6.Cu")
		(net "UPI_CPU1_CPU0_P0P1_DP<19>")
	)
	(segment
		(start 309.136288 -162.207194)
		(end 308.83479 -161.893504)
		(width 0.14732)
		(layer "In6.Cu")
		(net "UPI_CPU1_CPU0_P0P1_DP<19>")
	)
	(segment
		(start 313.770264 -162.302698)
		(end 313.468766 -161.989008)
		(width 0.14732)
		(layer "In6.Cu")
		(net "UPI_CPU1_CPU0_P0P1_DP<19>")
	)
	(segment
		(start 166.903654 -153.852372)
		(end 165.112192 -154.477974)
		(width 0.14732)
		(layer "In6.Cu")
		(net "UPI_CPU1_CPU0_P0P1_DP<19>")
	)
	(segment
		(start 309.24119 -164.287454)
		(end 309.096664 -164.137086)
		(width 0.14732)
		(layer "In6.Cu")
		(net "UPI_CPU1_CPU0_P0P1_DP<19>")
	)
	(segment
		(start 312.650886 -161.97199)
		(end 312.337196 -162.273234)
		(width 0.14732)
		(layer "In6.Cu")
		(net "UPI_CPU1_CPU0_P0P1_DP<19>")
	)
	(segment
		(start 189.911228 -164.526468)
		(end 172.315886 -155.321)
		(width 0.14732)
		(layer "In6.Cu")
		(net "UPI_CPU1_CPU0_P0P1_DP<19>")
	)
	(segment
		(start 349.04426 -177.751232)
		(end 344.02776 -176.254918)
		(width 0.14732)
		(layer "In6.Cu")
		(net "UPI_CPU1_CPU0_P0P1_DP<19>")
	)
	(segment
		(start 329.111864 -168.427908)
		(end 314.853066 -164.403024)
		(width 0.14732)
		(layer "In6.Cu")
		(net "UPI_CPU1_CPU0_P0P1_DP<19>")
	)
	(segment
		(start 309.980584 -164.155628)
		(end 309.830724 -164.2999)
		(width 0.14732)
		(layer "In6.Cu")
		(net "UPI_CPU1_CPU0_P0P1_DP<19>")
	)
	(segment
		(start 312.297572 -164.20338)
		(end 312.147712 -164.347652)
		(width 0.14732)
		(layer "In6.Cu")
		(net "UPI_CPU1_CPU0_P0P1_DP<19>")
	)
	(segment
		(start 344.02776 -176.254918)
		(end 329.111864 -168.427908)
		(width 0.14732)
		(layer "In6.Cu")
		(net "UPI_CPU1_CPU0_P0P1_DP<19>")
	)
	(segment
		(start 106.80446 -211.77123)
		(end 106.80446 -211.793328)
		(width 0.0889)
		(layer "In6.Cu")
		(net "UPI_CPU1_CPU0_P0P1_DP<19>")
	)
	(segment
		(start 307.663596 -164.107876)
		(end 307.513736 -164.252148)
		(width 0.14732)
		(layer "In6.Cu")
		(net "UPI_CPU1_CPU0_P0P1_DP<19>")
	)
	(segment
		(start 310.020208 -162.225482)
		(end 309.980584 -164.155628)
		(width 0.14732)
		(layer "In6.Cu")
		(net "UPI_CPU1_CPU0_P0P1_DP<19>")
	)
	(segment
		(start 352.07956 -179.906168)
		(end 351.305368 -178.389026)
		(width 0.14732)
		(layer "In6.Cu")
		(net "UPI_CPU1_CPU0_P0P1_DP<19>")
	)
	(segment
		(start 133.467602 -173.979078)
		(end 121.068846 -185.639202)
		(width 0.14732)
		(layer "In6.Cu")
		(net "UPI_CPU1_CPU0_P0P1_DP<19>")
	)
	(segment
		(start 302.879252 -164.157406)
		(end 302.58766 -164.15258)
		(width 0.14732)
		(layer "In6.Cu")
		(net "UPI_CPU1_CPU0_P0P1_DP<19>")
	)
	(segment
		(start 312.147712 -164.347652)
		(end 311.558178 -164.335206)
		(width 0.14732)
		(layer "In6.Cu")
		(net "UPI_CPU1_CPU0_P0P1_DP<19>")
	)
	(segment
		(start 304.462688 -164.041582)
		(end 304.502312 -162.11169)
		(width 0.14732)
		(layer "In6.Cu")
		(net "UPI_CPU1_CPU0_P0P1_DP<19>")
	)
	(segment
		(start 106.80446 -211.116418)
		(end 106.80446 -211.77123)
		(width 0.14732)
		(layer "In6.Cu")
		(net "UPI_CPU1_CPU0_P0P1_DP<19>")
	)
	(segment
		(start 305.196748 -164.204396)
		(end 304.607214 -164.19195)
		(width 0.14732)
		(layer "In6.Cu")
		(net "UPI_CPU1_CPU0_P0P1_DP<19>")
	)
	(segment
		(start 106.84637 -213.892892)
		(end 106.846116 -213.8934)
		(width 0.0889)
		(layer "In6.Cu")
		(net "UPI_CPU1_CPU0_P0P1_DP<19>")
	)
	(segment
		(start 304.200814 -161.798)
		(end 303.382934 -161.780982)
		(width 0.14732)
		(layer "In6.Cu")
		(net "UPI_CPU1_CPU0_P0P1_DP<19>")
	)
	(segment
		(start 352.874072 -180.190648)
		(end 352.46056 -180.190648)
		(width 0.14732)
		(layer "In6.Cu")
		(net "UPI_CPU1_CPU0_P0P1_DP<19>")
	)
	(segment
		(start 234.399328 -154.645868)
		(end 197.369684 -164.192204)
		(width 0.14732)
		(layer "In6.Cu")
		(net "UPI_CPU1_CPU0_P0P1_DP<19>")
	)
	(segment
		(start 303.02962 -164.011864)
		(end 302.879252 -164.157406)
		(width 0.14732)
		(layer "In6.Cu")
		(net "UPI_CPU1_CPU0_P0P1_DP<19>")
	)
	(segment
		(start 308.83479 -161.893504)
		(end 308.01691 -161.876486)
		(width 0.14732)
		(layer "In6.Cu")
		(net "UPI_CPU1_CPU0_P0P1_DP<19>")
	)
	(segment
		(start 308.01691 -161.876486)
		(end 307.70322 -162.17773)
		(width 0.14732)
		(layer "In6.Cu")
		(net "UPI_CPU1_CPU0_P0P1_DP<19>")
	)
	(segment
		(start 197.369684 -164.192204)
		(end 194.715638 -164.526468)
		(width 0.14732)
		(layer "In6.Cu")
		(net "UPI_CPU1_CPU0_P0P1_DP<19>")
	)
	(segment
		(start 306.517802 -161.845752)
		(end 305.699922 -161.828734)
		(width 0.14732)
		(layer "In6.Cu")
		(net "UPI_CPU1_CPU0_P0P1_DP<19>")
	)
	(segment
		(start 303.069244 -162.082226)
		(end 303.02962 -164.011864)
		(width 0.14732)
		(layer "In6.Cu")
		(net "UPI_CPU1_CPU0_P0P1_DP<19>")
	)
	(segment
		(start 313.468766 -161.989008)
		(end 312.650886 -161.97199)
		(width 0.14732)
		(layer "In6.Cu")
		(net "UPI_CPU1_CPU0_P0P1_DP<19>")
	)
	(segment
		(start 305.346608 -164.060124)
		(end 305.196748 -164.204396)
		(width 0.14732)
		(layer "In6.Cu")
		(net "UPI_CPU1_CPU0_P0P1_DP<19>")
	)
	(segment
		(start 351.305368 -178.389026)
		(end 350.872044 -178.058064)
		(width 0.14732)
		(layer "In6.Cu")
		(net "UPI_CPU1_CPU0_P0P1_DP<19>")
	)
	(segment
		(start 106.80446 -211.793328)
		(end 106.84637 -211.835238)
		(width 0.0889)
		(layer "In6.Cu")
		(net "UPI_CPU1_CPU0_P0P1_DP<19>")
	)
	(segment
		(start 353.09556 -179.89296)
		(end 352.99142 -180.0733)
		(width 0.14732)
		(layer "In6.Cu")
		(net "UPI_CPU1_CPU0_P0P1_DP<19>")
	)
	(segment
		(start 305.386232 -162.129978)
		(end 305.346608 -164.060124)
		(width 0.14732)
		(layer "In6.Cu")
		(net "UPI_CPU1_CPU0_P0P1_DP<19>")
	)
	(segment
		(start 303.382934 -161.780982)
		(end 303.069244 -162.082226)
		(width 0.14732)
		(layer "In6.Cu")
		(net "UPI_CPU1_CPU0_P0P1_DP<19>")
	)
	(segment
		(start 313.874912 -164.382704)
		(end 313.73064 -164.232844)
		(width 0.14732)
		(layer "In6.Cu")
		(net "UPI_CPU1_CPU0_P0P1_DP<19>")
	)
	(segment
		(start 350.872044 -178.058064)
		(end 349.796862 -177.82413)
		(width 0.14732)
		(layer "In6.Cu")
		(net "UPI_CPU1_CPU0_P0P1_DP<19>")
	)
	(segment
		(start 352.950272 -179.351432)
		(end 353.09556 -179.89296)
		(width 0.14732)
		(layer "In6.Cu")
		(net "UPI_CPU1_CPU0_P0P1_DP<19>")
	)
	(segment
		(start 165.112192 -154.477974)
		(end 133.467602 -173.979078)
		(width 0.14732)
		(layer "In6.Cu")
		(net "UPI_CPU1_CPU0_P0P1_DP<19>")
	)
	(segment
		(start 302.58766 -164.15258)
		(end 302.5775 -164.15258)
		(width 0.14732)
		(layer "In6.Cu")
		(net "UPI_CPU1_CPU0_P0P1_DP<19>")
	)
	(segment
		(start 304.607214 -164.19195)
		(end 304.462688 -164.041582)
		(width 0.14732)
		(layer "In6.Cu")
		(net "UPI_CPU1_CPU0_P0P1_DP<19>")
	)
	(segment
		(start 307.513736 -164.252148)
		(end 306.924202 -164.239702)
		(width 0.14732)
		(layer "In6.Cu")
		(net "UPI_CPU1_CPU0_P0P1_DP<19>")
	)
	(segment
		(start 111.865156 -197.223888)
		(end 106.80446 -211.116418)
		(width 0.14732)
		(layer "In6.Cu")
		(net "UPI_CPU1_CPU0_P0P1_DP<19>")
	)
	(segment
		(start 309.096664 -164.137086)
		(end 309.136288 -162.207194)
		(width 0.14732)
		(layer "In6.Cu")
		(net "UPI_CPU1_CPU0_P0P1_DP<19>")
	)
	(segment
		(start 276.290024 -164.529008)
		(end 237.811818 -154.645868)
		(width 0.14732)
		(layer "In6.Cu")
		(net "UPI_CPU1_CPU0_P0P1_DP<19>")
	)
	(segment
		(start 349.796862 -177.82413)
		(end 349.04426 -177.751232)
		(width 0.14732)
		(layer "In6.Cu")
		(net "UPI_CPU1_CPU0_P0P1_DP<19>")
	)
	(segment
		(start 312.337196 -162.273234)
		(end 312.297572 -164.20338)
		(width 0.14732)
		(layer "In6.Cu")
		(net "UPI_CPU1_CPU0_P0P1_DP<19>")
	)
	(segment
		(start 106.603546 -215.076532)
		(end 106.627676 -215.165686)
		(width 0.0889)
		(layer "In6.Cu")
		(net "UPI_CPU1_CPU0_P0P1_DP<19>")
	)
	(segment
		(start 313.73064 -164.232844)
		(end 313.770264 -162.302698)
		(width 0.14732)
		(layer "In6.Cu")
		(net "UPI_CPU1_CPU0_P0P1_DP<19>")
	)
	(segment
		(start 309.830724 -164.2999)
		(end 309.24119 -164.287454)
		(width 0.14732)
		(layer "In6.Cu")
		(net "UPI_CPU1_CPU0_P0P1_DP<19>")
	)
	(segment
		(start 302.5775 -164.15258)
		(end 280.841704 -164.529008)
		(width 0.14732)
		(layer "In6.Cu")
		(net "UPI_CPU1_CPU0_P0P1_DP<19>")
	)
	(segment
		(start 169.48912 -153.921206)
		(end 166.903654 -153.852372)
		(width 0.14732)
		(layer "In6.Cu")
		(net "UPI_CPU1_CPU0_P0P1_DP<19>")
	)
	(segment
		(start 280.841704 -164.529008)
		(end 276.290024 -164.529008)
		(width 0.14732)
		(layer "In6.Cu")
		(net "UPI_CPU1_CPU0_P0P1_DP<19>")
	)
	(segment
		(start 311.453276 -162.254946)
		(end 311.151778 -161.941256)
		(width 0.14732)
		(layer "In6.Cu")
		(net "UPI_CPU1_CPU0_P0P1_DP<19>")
	)
	(segment
		(start 106.627676 -215.165686)
		(end 106.471212 -215.436704)
		(width 0.0889)
		(layer "In6.Cu")
		(net "UPI_CPU1_CPU0_P0P1_DP<19>")
	)
	(segment
		(start 310.333898 -161.924238)
		(end 310.020208 -162.225482)
		(width 0.14732)
		(layer "In6.Cu")
		(net "UPI_CPU1_CPU0_P0P1_DP<19>")
	)
	(segment
		(start 106.375708 -214.425784)
		(end 106.375708 -214.636858)
		(width 0.0889)
		(layer "In6.Cu")
		(net "UPI_CPU1_CPU0_P0P1_DP<19>")
	)
	(segment
		(start 306.779676 -164.089334)
		(end 306.8193 -162.159442)
		(width 0.14732)
		(layer "In6.Cu")
		(net "UPI_CPU1_CPU0_P0P1_DP<19>")
	)
	(arc
		(start 106.846116 -213.8934)
		(mid 106.771045 -214.009142)
		(end 106.661712 -214.093298)
		(width 0.0889)
		(layer "In6.Cu")
		(net "UPI_CPU1_CPU0_P0P1_DP<19>")
	)
	(arc
		(start 106.375708 -214.636858)
		(mid 106.434053 -214.873363)
		(end 106.586528 -215.063324)
		(width 0.0889)
		(layer "In6.Cu")
		(net "UPI_CPU1_CPU0_P0P1_DP<19>")
	)
	(arc
		(start 106.586528 -215.063324)
		(mid 106.594974 -215.070009)
		(end 106.603546 -215.076532)
		(width 0.0889)
		(layer "In6.Cu")
		(net "UPI_CPU1_CPU0_P0P1_DP<19>")
	)
	(arc
		(start 106.661712 -214.093298)
		(mid 106.487164 -214.232402)
		(end 106.375708 -214.425784)
		(width 0.0889)
		(layer "In6.Cu")
		(net "UPI_CPU1_CPU0_P0P1_DP<19>")
	)
	(segment
		(start 366.264444 -213.264496)
		(end 366.01654 -213.016592)
		(width 0.0889)
		(layer "F.Cu")
		(net "UPI_CPU1_CPU0_P0P1_DP<18>")
	)
	(segment
		(start 366.264444 -214.325962)
		(end 366.264444 -213.83371)
		(width 0.0889)
		(layer "F.Cu")
		(net "UPI_CPU1_CPU0_P0P1_DP<18>")
	)
	(segment
		(start 356.795578 -199.308212)
		(end 357.826056 -194.126358)
		(width 0.13208)
		(layer "F.Cu")
		(net "UPI_CPU1_CPU0_P0P1_DP<18>")
	)
	(segment
		(start 366.363504 -213.58225)
		(end 366.264444 -213.48319)
		(width 0.0889)
		(layer "F.Cu")
		(net "UPI_CPU1_CPU0_P0P1_DP<18>")
	)
	(segment
		(start 359.197402 -183.507634)
		(end 354.744782 -179.055014)
		(width 0.13208)
		(layer "F.Cu")
		(net "UPI_CPU1_CPU0_P0P1_DP<18>")
	)
	(segment
		(start 360.166158 -185.84672)
		(end 359.197402 -183.507634)
		(width 0.13208)
		(layer "F.Cu")
		(net "UPI_CPU1_CPU0_P0P1_DP<18>")
	)
	(segment
		(start 357.826056 -194.126358)
		(end 357.858822 -194.04711)
		(width 0.13208)
		(layer "F.Cu")
		(net "UPI_CPU1_CPU0_P0P1_DP<18>")
	)
	(segment
		(start 365.908844 -212.768688)
		(end 365.768636 -212.768688)
		(width 0.0889)
		(layer "F.Cu")
		(net "UPI_CPU1_CPU0_P0P1_DP<18>")
	)
	(segment
		(start 366.264444 -213.48319)
		(end 366.264444 -213.264496)
		(width 0.0889)
		(layer "F.Cu")
		(net "UPI_CPU1_CPU0_P0P1_DP<18>")
	)
	(segment
		(start 365.990124 -214.82304)
		(end 365.990378 -214.822532)
		(width 0.0889)
		(layer "F.Cu")
		(net "UPI_CPU1_CPU0_P0P1_DP<18>")
	)
	(segment
		(start 366.264444 -213.83371)
		(end 366.363504 -213.73465)
		(width 0.0889)
		(layer "F.Cu")
		(net "UPI_CPU1_CPU0_P0P1_DP<18>")
	)
	(segment
		(start 353.981512 -178.544982)
		(end 350.082866 -176.930812)
		(width 0.13208)
		(layer "F.Cu")
		(net "UPI_CPU1_CPU0_P0P1_DP<18>")
	)
	(segment
		(start 360.166158 -188.476128)
		(end 360.166158 -185.84672)
		(width 0.13208)
		(layer "F.Cu")
		(net "UPI_CPU1_CPU0_P0P1_DP<18>")
	)
	(segment
		(start 349.943928 -176.722278)
		(end 350.089724 -176.176432)
		(width 0.13208)
		(layer "F.Cu")
		(net "UPI_CPU1_CPU0_P0P1_DP<18>")
	)
	(segment
		(start 356.761034 -205.76286)
		(end 356.761034 -205.261718)
		(width 0.0889)
		(layer "F.Cu")
		(net "UPI_CPU1_CPU0_P0P1_DP<18>")
	)
	(segment
		(start 363.51464 -210.514438)
		(end 360.097832 -209.099658)
		(width 0.0889)
		(layer "F.Cu")
		(net "UPI_CPU1_CPU0_P0P1_DP<18>")
	)
	(segment
		(start 366.01654 -212.876384)
		(end 365.908844 -212.768688)
		(width 0.0889)
		(layer "F.Cu")
		(net "UPI_CPU1_CPU0_P0P1_DP<18>")
	)
	(segment
		(start 360.097832 -209.099658)
		(end 356.761034 -205.76286)
		(width 0.0889)
		(layer "F.Cu")
		(net "UPI_CPU1_CPU0_P0P1_DP<18>")
	)
	(segment
		(start 357.858822 -194.04711)
		(end 360.166158 -188.476128)
		(width 0.13208)
		(layer "F.Cu")
		(net "UPI_CPU1_CPU0_P0P1_DP<18>")
	)
	(segment
		(start 356.795578 -205.227174)
		(end 356.795578 -205.205076)
		(width 0.0889)
		(layer "F.Cu")
		(net "UPI_CPU1_CPU0_P0P1_DP<18>")
	)
	(segment
		(start 366.15878 -215.158574)
		(end 366.003586 -215.42756)
		(width 0.0889)
		(layer "F.Cu")
		(net "UPI_CPU1_CPU0_P0P1_DP<18>")
	)
	(segment
		(start 105.531666 -214.344758)
		(end 105.531666 -213.732618)
		(width 0.13208)
		(layer "F.Cu")
		(net "UPI_CPU1_CPU0_P0P1_DP<18>")
	)
	(segment
		(start 365.768636 -212.768688)
		(end 363.51464 -210.514438)
		(width 0.0889)
		(layer "F.Cu")
		(net "UPI_CPU1_CPU0_P0P1_DP<18>")
	)
	(segment
		(start 350.082866 -176.930812)
		(end 349.943928 -176.722278)
		(width 0.13208)
		(layer "F.Cu")
		(net "UPI_CPU1_CPU0_P0P1_DP<18>")
	)
	(segment
		(start 366.003586 -215.42756)
		(end 365.92256 -215.44915)
		(width 0.0889)
		(layer "F.Cu")
		(net "UPI_CPU1_CPU0_P0P1_DP<18>")
	)
	(segment
		(start 356.761034 -205.261718)
		(end 356.795578 -205.227174)
		(width 0.0889)
		(layer "F.Cu")
		(net "UPI_CPU1_CPU0_P0P1_DP<18>")
	)
	(segment
		(start 356.795578 -205.205076)
		(end 356.795578 -199.308212)
		(width 0.13208)
		(layer "F.Cu")
		(net "UPI_CPU1_CPU0_P0P1_DP<18>")
	)
	(segment
		(start 366.363504 -213.73465)
		(end 366.363504 -213.58225)
		(width 0.0889)
		(layer "F.Cu")
		(net "UPI_CPU1_CPU0_P0P1_DP<18>")
	)
	(segment
		(start 354.744782 -179.055014)
		(end 353.981512 -178.544982)
		(width 0.13208)
		(layer "F.Cu")
		(net "UPI_CPU1_CPU0_P0P1_DP<18>")
	)
	(segment
		(start 366.01654 -213.016592)
		(end 366.01654 -212.876384)
		(width 0.0889)
		(layer "F.Cu")
		(net "UPI_CPU1_CPU0_P0P1_DP<18>")
	)
	(arc
		(start 365.78413 -215.158574)
		(mid 365.837536 -214.965538)
		(end 365.982758 -214.827612)
		(width 0.0889)
		(layer "F.Cu")
		(net "UPI_CPU1_CPU0_P0P1_DP<18>")
	)
	(arc
		(start 365.990378 -214.822532)
		(mid 366.191356 -214.609532)
		(end 366.264444 -214.325962)
		(width 0.0889)
		(layer "F.Cu")
		(net "UPI_CPU1_CPU0_P0P1_DP<18>")
	)
	(arc
		(start 365.982758 -214.827612)
		(mid 365.983904 -214.826982)
		(end 365.985044 -214.826342)
		(width 0.0889)
		(layer "F.Cu")
		(net "UPI_CPU1_CPU0_P0P1_DP<18>")
	)
	(arc
		(start 365.985044 -214.826342)
		(mid 365.987588 -214.824697)
		(end 365.990124 -214.82304)
		(width 0.0889)
		(layer "F.Cu")
		(net "UPI_CPU1_CPU0_P0P1_DP<18>")
	)
	(arc
		(start 365.92256 -215.44915)
		(mid 365.820539 -215.319488)
		(end 365.78413 -215.158574)
		(width 0.0889)
		(layer "F.Cu")
		(net "UPI_CPU1_CPU0_P0P1_DP<18>")
	)
	(segment
		(start 105.906316 -211.835238)
		(end 105.864406 -211.793328)
		(width 0.0889)
		(layer "In6.Cu")
		(net "UPI_CPU1_CPU0_P0P1_DP<18>")
	)
	(segment
		(start 349.01505 -175.586136)
		(end 349.440754 -175.843946)
		(width 0.14732)
		(layer "In6.Cu")
		(net "UPI_CPU1_CPU0_P0P1_DP<18>")
	)
	(segment
		(start 132.969 -173.300898)
		(end 165.150292 -153.469594)
		(width 0.14732)
		(layer "In6.Cu")
		(net "UPI_CPU1_CPU0_P0P1_DP<18>")
	)
	(segment
		(start 332.874874 -164.337746)
		(end 333.5147 -163.736274)
		(width 0.14732)
		(layer "In6.Cu")
		(net "UPI_CPU1_CPU0_P0P1_DP<18>")
	)
	(segment
		(start 336.6897 -167.113458)
		(end 337.125056 -167.126666)
		(width 0.14732)
		(layer "In6.Cu")
		(net "UPI_CPU1_CPU0_P0P1_DP<18>")
	)
	(segment
		(start 105.906316 -213.499192)
		(end 105.807002 -213.399878)
		(width 0.0889)
		(layer "In6.Cu")
		(net "UPI_CPU1_CPU0_P0P1_DP<18>")
	)
	(segment
		(start 349.548704 -176.03089)
		(end 349.549212 -176.031652)
		(width 0.14732)
		(layer "In6.Cu")
		(net "UPI_CPU1_CPU0_P0P1_DP<18>")
	)
	(segment
		(start 190.340996 -163.690808)
		(end 194.66306 -163.690808)
		(width 0.14732)
		(layer "In6.Cu")
		(net "UPI_CPU1_CPU0_P0P1_DP<18>")
	)
	(segment
		(start 323.343016 -154.772868)
		(end 325.44766 -155.302712)
		(width 0.14732)
		(layer "In6.Cu")
		(net "UPI_CPU1_CPU0_P0P1_DP<18>")
	)
	(segment
		(start 105.864406 -211.77123)
		(end 105.864406 -211.236052)
		(width 0.14732)
		(layer "In6.Cu")
		(net "UPI_CPU1_CPU0_P0P1_DP<18>")
	)
	(segment
		(start 339.25891 -169.846244)
		(end 338.61883 -170.447716)
		(width 0.14732)
		(layer "In6.Cu")
		(net "UPI_CPU1_CPU0_P0P1_DP<18>")
	)
	(segment
		(start 119.850154 -185.637932)
		(end 132.969 -173.300898)
		(width 0.14732)
		(layer "In6.Cu")
		(net "UPI_CPU1_CPU0_P0P1_DP<18>")
	)
	(segment
		(start 105.807002 -212.66785)
		(end 105.807002 -212.40115)
		(width 0.0889)
		(layer "In6.Cu")
		(net "UPI_CPU1_CPU0_P0P1_DP<18>")
	)
	(segment
		(start 105.531666 -213.732618)
		(end 105.690416 -214.033608)
		(width 0.0889)
		(layer "In6.Cu")
		(net "UPI_CPU1_CPU0_P0P1_DP<18>")
	)
	(segment
		(start 332.667102 -164.331396)
		(end 332.874874 -164.337746)
		(width 0.14732)
		(layer "In6.Cu")
		(net "UPI_CPU1_CPU0_P0P1_DP<18>")
	)
	(segment
		(start 334.254602 -166.019988)
		(end 334.462374 -166.026338)
		(width 0.14732)
		(layer "In6.Cu")
		(net "UPI_CPU1_CPU0_P0P1_DP<18>")
	)
	(segment
		(start 337.125056 -167.126666)
		(end 337.684618 -167.722296)
		(width 0.14732)
		(layer "In6.Cu")
		(net "UPI_CPU1_CPU0_P0P1_DP<18>")
	)
	(segment
		(start 330.67498 -162.212274)
		(end 331.079602 -162.642804)
		(width 0.14732)
		(layer "In6.Cu")
		(net "UPI_CPU1_CPU0_P0P1_DP<18>")
	)
	(segment
		(start 344.600784 -174.723806)
		(end 349.01505 -175.586136)
		(width 0.14732)
		(layer "In6.Cu")
		(net "UPI_CPU1_CPU0_P0P1_DP<18>")
	)
	(segment
		(start 337.637374 -169.403522)
		(end 338.2772 -168.80205)
		(width 0.14732)
		(layer "In6.Cu")
		(net "UPI_CPU1_CPU0_P0P1_DP<18>")
	)
	(segment
		(start 105.807002 -213.133178)
		(end 105.906316 -213.033864)
		(width 0.0889)
		(layer "In6.Cu")
		(net "UPI_CPU1_CPU0_P0P1_DP<18>")
	)
	(segment
		(start 334.509618 -164.345112)
		(end 334.49641 -164.780468)
		(width 0.14732)
		(layer "In6.Cu")
		(net "UPI_CPU1_CPU0_P0P1_DP<18>")
	)
	(segment
		(start 105.906316 -213.8934)
		(end 105.906316 -213.499192)
		(width 0.0889)
		(layer "In6.Cu")
		(net "UPI_CPU1_CPU0_P0P1_DP<18>")
	)
	(segment
		(start 165.150292 -153.469594)
		(end 166.756588 -152.908508)
		(width 0.14732)
		(layer "In6.Cu")
		(net "UPI_CPU1_CPU0_P0P1_DP<18>")
	)
	(segment
		(start 337.67141 -168.157652)
		(end 337.03133 -168.759124)
		(width 0.14732)
		(layer "In6.Cu")
		(net "UPI_CPU1_CPU0_P0P1_DP<18>")
	)
	(segment
		(start 332.922118 -162.65652)
		(end 332.90891 -163.091876)
		(width 0.14732)
		(layer "In6.Cu")
		(net "UPI_CPU1_CPU0_P0P1_DP<18>")
	)
	(segment
		(start 331.287374 -162.649154)
		(end 331.9272 -162.047682)
		(width 0.14732)
		(layer "In6.Cu")
		(net "UPI_CPU1_CPU0_P0P1_DP<18>")
	)
	(segment
		(start 237.917736 -153.810208)
		(end 276.425406 -163.700968)
		(width 0.14732)
		(layer "In6.Cu")
		(net "UPI_CPU1_CPU0_P0P1_DP<18>")
	)
	(segment
		(start 105.864406 -211.793328)
		(end 105.864406 -211.77123)
		(width 0.0889)
		(layer "In6.Cu")
		(net "UPI_CPU1_CPU0_P0P1_DP<18>")
	)
	(segment
		(start 340.299802 -170.504104)
		(end 343.911682 -174.343314)
		(width 0.14732)
		(layer "In6.Cu")
		(net "UPI_CPU1_CPU0_P0P1_DP<18>")
	)
	(segment
		(start 197.212458 -163.369498)
		(end 234.293156 -153.810208)
		(width 0.14732)
		(layer "In6.Cu")
		(net "UPI_CPU1_CPU0_P0P1_DP<18>")
	)
	(segment
		(start 105.906316 -213.033864)
		(end 105.906316 -212.767164)
		(width 0.0889)
		(layer "In6.Cu")
		(net "UPI_CPU1_CPU0_P0P1_DP<18>")
	)
	(segment
		(start 339.8647 -170.490642)
		(end 340.299802 -170.504104)
		(width 0.14732)
		(layer "In6.Cu")
		(net "UPI_CPU1_CPU0_P0P1_DP<18>")
	)
	(segment
		(start 339.272118 -169.410888)
		(end 339.25891 -169.846244)
		(width 0.14732)
		(layer "In6.Cu")
		(net "UPI_CPU1_CPU0_P0P1_DP<18>")
	)
	(segment
		(start 331.32141 -161.403284)
		(end 330.68133 -162.004756)
		(width 0.14732)
		(layer "In6.Cu")
		(net "UPI_CPU1_CPU0_P0P1_DP<18>")
	)
	(segment
		(start 336.08391 -166.46906)
		(end 335.44383 -167.070532)
		(width 0.14732)
		(layer "In6.Cu")
		(net "UPI_CPU1_CPU0_P0P1_DP<18>")
	)
	(segment
		(start 335.842102 -167.70858)
		(end 336.049874 -167.71493)
		(width 0.14732)
		(layer "In6.Cu")
		(net "UPI_CPU1_CPU0_P0P1_DP<18>")
	)
	(segment
		(start 333.950056 -163.749482)
		(end 334.509618 -164.345112)
		(width 0.14732)
		(layer "In6.Cu")
		(net "UPI_CPU1_CPU0_P0P1_DP<18>")
	)
	(segment
		(start 335.1022 -165.424866)
		(end 335.537556 -165.438074)
		(width 0.14732)
		(layer "In6.Cu")
		(net "UPI_CPU1_CPU0_P0P1_DP<18>")
	)
	(segment
		(start 332.26883 -163.693348)
		(end 332.26248 -163.900866)
		(width 0.14732)
		(layer "In6.Cu")
		(net "UPI_CPU1_CPU0_P0P1_DP<18>")
	)
	(segment
		(start 331.079602 -162.642804)
		(end 331.287374 -162.649154)
		(width 0.14732)
		(layer "In6.Cu")
		(net "UPI_CPU1_CPU0_P0P1_DP<18>")
	)
	(segment
		(start 331.334618 -160.967928)
		(end 331.32141 -161.403284)
		(width 0.14732)
		(layer "In6.Cu")
		(net "UPI_CPU1_CPU0_P0P1_DP<18>")
	)
	(segment
		(start 349.440754 -175.843946)
		(end 349.546926 -176.028096)
		(width 0.14732)
		(layer "In6.Cu")
		(net "UPI_CPU1_CPU0_P0P1_DP<18>")
	)
	(segment
		(start 339.017102 -171.085764)
		(end 339.224874 -171.092114)
		(width 0.14732)
		(layer "In6.Cu")
		(net "UPI_CPU1_CPU0_P0P1_DP<18>")
	)
	(segment
		(start 333.84998 -165.589458)
		(end 334.254602 -166.019988)
		(width 0.14732)
		(layer "In6.Cu")
		(net "UPI_CPU1_CPU0_P0P1_DP<18>")
	)
	(segment
		(start 169.720768 -152.987248)
		(end 172.742352 -154.483308)
		(width 0.14732)
		(layer "In6.Cu")
		(net "UPI_CPU1_CPU0_P0P1_DP<18>")
	)
	(segment
		(start 349.546926 -176.028096)
		(end 349.548704 -176.03089)
		(width 0.14732)
		(layer "In6.Cu")
		(net "UPI_CPU1_CPU0_P0P1_DP<18>")
	)
	(segment
		(start 330.68133 -162.004756)
		(end 330.67498 -162.212274)
		(width 0.14732)
		(layer "In6.Cu")
		(net "UPI_CPU1_CPU0_P0P1_DP<18>")
	)
	(segment
		(start 105.807002 -213.399878)
		(end 105.807002 -213.133178)
		(width 0.0889)
		(layer "In6.Cu")
		(net "UPI_CPU1_CPU0_P0P1_DP<18>")
	)
	(segment
		(start 337.684618 -167.722296)
		(end 337.67141 -168.157652)
		(width 0.14732)
		(layer "In6.Cu")
		(net "UPI_CPU1_CPU0_P0P1_DP<18>")
	)
	(segment
		(start 325.44766 -155.302712)
		(end 327.435718 -156.821378)
		(width 0.14732)
		(layer "In6.Cu")
		(net "UPI_CPU1_CPU0_P0P1_DP<18>")
	)
	(segment
		(start 334.49641 -164.780468)
		(end 333.85633 -165.38194)
		(width 0.14732)
		(layer "In6.Cu")
		(net "UPI_CPU1_CPU0_P0P1_DP<18>")
	)
	(segment
		(start 332.90891 -163.091876)
		(end 332.26883 -163.693348)
		(width 0.14732)
		(layer "In6.Cu")
		(net "UPI_CPU1_CPU0_P0P1_DP<18>")
	)
	(segment
		(start 339.224874 -171.092114)
		(end 339.8647 -170.490642)
		(width 0.14732)
		(layer "In6.Cu")
		(net "UPI_CPU1_CPU0_P0P1_DP<18>")
	)
	(segment
		(start 234.293156 -153.810208)
		(end 237.917736 -153.810208)
		(width 0.14732)
		(layer "In6.Cu")
		(net "UPI_CPU1_CPU0_P0P1_DP<18>")
	)
	(segment
		(start 335.44383 -167.070532)
		(end 335.43748 -167.27805)
		(width 0.14732)
		(layer "In6.Cu")
		(net "UPI_CPU1_CPU0_P0P1_DP<18>")
	)
	(segment
		(start 333.5147 -163.736274)
		(end 333.950056 -163.749482)
		(width 0.14732)
		(layer "In6.Cu")
		(net "UPI_CPU1_CPU0_P0P1_DP<18>")
	)
	(segment
		(start 331.9272 -162.047682)
		(end 332.362556 -162.06089)
		(width 0.14732)
		(layer "In6.Cu")
		(net "UPI_CPU1_CPU0_P0P1_DP<18>")
	)
	(segment
		(start 279.705816 -163.700968)
		(end 322.321936 -154.772868)
		(width 0.14732)
		(layer "In6.Cu")
		(net "UPI_CPU1_CPU0_P0P1_DP<18>")
	)
	(segment
		(start 337.02498 -168.966642)
		(end 337.429602 -169.397172)
		(width 0.14732)
		(layer "In6.Cu")
		(net "UPI_CPU1_CPU0_P0P1_DP<18>")
	)
	(segment
		(start 335.537556 -165.438074)
		(end 336.097118 -166.033704)
		(width 0.14732)
		(layer "In6.Cu")
		(net "UPI_CPU1_CPU0_P0P1_DP<18>")
	)
	(segment
		(start 276.425406 -163.700968)
		(end 279.705816 -163.700968)
		(width 0.14732)
		(layer "In6.Cu")
		(net "UPI_CPU1_CPU0_P0P1_DP<18>")
	)
	(segment
		(start 105.690416 -214.033608)
		(end 105.774998 -214.05977)
		(width 0.0889)
		(layer "In6.Cu")
		(net "UPI_CPU1_CPU0_P0P1_DP<18>")
	)
	(segment
		(start 333.85633 -165.38194)
		(end 333.84998 -165.589458)
		(width 0.14732)
		(layer "In6.Cu")
		(net "UPI_CPU1_CPU0_P0P1_DP<18>")
	)
	(segment
		(start 194.66306 -163.690808)
		(end 197.212458 -163.369498)
		(width 0.14732)
		(layer "In6.Cu")
		(net "UPI_CPU1_CPU0_P0P1_DP<18>")
	)
	(segment
		(start 338.61883 -170.447716)
		(end 338.61248 -170.655234)
		(width 0.14732)
		(layer "In6.Cu")
		(net "UPI_CPU1_CPU0_P0P1_DP<18>")
	)
	(segment
		(start 349.549212 -176.031652)
		(end 350.089724 -176.176432)
		(width 0.14732)
		(layer "In6.Cu")
		(net "UPI_CPU1_CPU0_P0P1_DP<18>")
	)
	(segment
		(start 338.2772 -168.80205)
		(end 338.712556 -168.815258)
		(width 0.14732)
		(layer "In6.Cu")
		(net "UPI_CPU1_CPU0_P0P1_DP<18>")
	)
	(segment
		(start 335.43748 -167.27805)
		(end 335.842102 -167.70858)
		(width 0.14732)
		(layer "In6.Cu")
		(net "UPI_CPU1_CPU0_P0P1_DP<18>")
	)
	(segment
		(start 105.906316 -212.767164)
		(end 105.807002 -212.66785)
		(width 0.0889)
		(layer "In6.Cu")
		(net "UPI_CPU1_CPU0_P0P1_DP<18>")
	)
	(segment
		(start 172.742352 -154.483308)
		(end 190.340996 -163.690808)
		(width 0.14732)
		(layer "In6.Cu")
		(net "UPI_CPU1_CPU0_P0P1_DP<18>")
	)
	(segment
		(start 343.911682 -174.343314)
		(end 344.600784 -174.723806)
		(width 0.14732)
		(layer "In6.Cu")
		(net "UPI_CPU1_CPU0_P0P1_DP<18>")
	)
	(segment
		(start 332.26248 -163.900866)
		(end 332.667102 -164.331396)
		(width 0.14732)
		(layer "In6.Cu")
		(net "UPI_CPU1_CPU0_P0P1_DP<18>")
	)
	(segment
		(start 337.429602 -169.397172)
		(end 337.637374 -169.403522)
		(width 0.14732)
		(layer "In6.Cu")
		(net "UPI_CPU1_CPU0_P0P1_DP<18>")
	)
	(segment
		(start 336.049874 -167.71493)
		(end 336.6897 -167.113458)
		(width 0.14732)
		(layer "In6.Cu")
		(net "UPI_CPU1_CPU0_P0P1_DP<18>")
	)
	(segment
		(start 334.462374 -166.026338)
		(end 335.1022 -165.424866)
		(width 0.14732)
		(layer "In6.Cu")
		(net "UPI_CPU1_CPU0_P0P1_DP<18>")
	)
	(segment
		(start 322.321936 -154.772868)
		(end 323.343016 -154.772868)
		(width 0.14732)
		(layer "In6.Cu")
		(net "UPI_CPU1_CPU0_P0P1_DP<18>")
	)
	(segment
		(start 327.435718 -156.821378)
		(end 331.334618 -160.967928)
		(width 0.14732)
		(layer "In6.Cu")
		(net "UPI_CPU1_CPU0_P0P1_DP<18>")
	)
	(segment
		(start 332.362556 -162.06089)
		(end 332.922118 -162.65652)
		(width 0.14732)
		(layer "In6.Cu")
		(net "UPI_CPU1_CPU0_P0P1_DP<18>")
	)
	(segment
		(start 337.03133 -168.759124)
		(end 337.02498 -168.966642)
		(width 0.14732)
		(layer "In6.Cu")
		(net "UPI_CPU1_CPU0_P0P1_DP<18>")
	)
	(segment
		(start 338.712556 -168.815258)
		(end 339.272118 -169.410888)
		(width 0.14732)
		(layer "In6.Cu")
		(net "UPI_CPU1_CPU0_P0P1_DP<18>")
	)
	(segment
		(start 166.756588 -152.908508)
		(end 169.720768 -152.987248)
		(width 0.14732)
		(layer "In6.Cu")
		(net "UPI_CPU1_CPU0_P0P1_DP<18>")
	)
	(segment
		(start 105.807002 -212.40115)
		(end 105.906316 -212.301836)
		(width 0.0889)
		(layer "In6.Cu")
		(net "UPI_CPU1_CPU0_P0P1_DP<18>")
	)
	(segment
		(start 336.097118 -166.033704)
		(end 336.08391 -166.46906)
		(width 0.14732)
		(layer "In6.Cu")
		(net "UPI_CPU1_CPU0_P0P1_DP<18>")
	)
	(segment
		(start 105.864406 -211.236052)
		(end 111.24184 -196.47408)
		(width 0.14732)
		(layer "In6.Cu")
		(net "UPI_CPU1_CPU0_P0P1_DP<18>")
	)
	(segment
		(start 111.24184 -196.47408)
		(end 119.850154 -185.637932)
		(width 0.14732)
		(layer "In6.Cu")
		(net "UPI_CPU1_CPU0_P0P1_DP<18>")
	)
	(segment
		(start 105.906316 -212.301836)
		(end 105.906316 -211.835238)
		(width 0.0889)
		(layer "In6.Cu")
		(net "UPI_CPU1_CPU0_P0P1_DP<18>")
	)
	(segment
		(start 338.61248 -170.655234)
		(end 339.017102 -171.085764)
		(width 0.14732)
		(layer "In6.Cu")
		(net "UPI_CPU1_CPU0_P0P1_DP<18>")
	)
	(arc
		(start 105.774998 -214.05977)
		(mid 105.851671 -213.985276)
		(end 105.906316 -213.8934)
		(width 0.0889)
		(layer "In6.Cu")
		(net "UPI_CPU1_CPU0_P0P1_DP<18>")
	)
	(segment
		(start 360.930698 -208.901284)
		(end 357.878888 -205.849474)
		(width 0.0889)
		(layer "F.Cu")
		(net "UPI_CPU1_CPU0_P0P1_DP<17>")
	)
	(segment
		(start 361.245658 -185.603896)
		(end 360.112818 -182.869332)
		(width 0.13208)
		(layer "F.Cu")
		(net "UPI_CPU1_CPU0_P0P1_DP<17>")
	)
	(segment
		(start 357.844598 -199.411336)
		(end 357.849424 -199.40651)
		(width 0.13208)
		(layer "F.Cu")
		(net "UPI_CPU1_CPU0_P0P1_DP<17>")
	)
	(segment
		(start 366.904524 -213.935056)
		(end 366.904524 -213.810596)
		(width 0.0889)
		(layer "F.Cu")
		(net "UPI_CPU1_CPU0_P0P1_DP<17>")
	)
	(segment
		(start 367.003584 -214.034116)
		(end 366.904524 -213.935056)
		(width 0.0889)
		(layer "F.Cu")
		(net "UPI_CPU1_CPU0_P0P1_DP<17>")
	)
	(segment
		(start 357.844598 -205.205076)
		(end 357.844598 -199.411336)
		(width 0.13208)
		(layer "F.Cu")
		(net "UPI_CPU1_CPU0_P0P1_DP<17>")
	)
	(segment
		(start 358.991662 -194.04711)
		(end 361.245658 -188.60516)
		(width 0.13208)
		(layer "F.Cu")
		(net "UPI_CPU1_CPU0_P0P1_DP<17>")
	)
	(segment
		(start 355.682296 -178.439318)
		(end 354.686108 -177.700178)
		(width 0.13208)
		(layer "F.Cu")
		(net "UPI_CPU1_CPU0_P0P1_DP<17>")
	)
	(segment
		(start 366.647222 -212.794088)
		(end 364.043214 -210.190334)
		(width 0.0889)
		(layer "F.Cu")
		(net "UPI_CPU1_CPU0_P0P1_DP<17>")
	)
	(segment
		(start 360.112818 -182.869332)
		(end 355.682296 -178.439318)
		(width 0.13208)
		(layer "F.Cu")
		(net "UPI_CPU1_CPU0_P0P1_DP<17>")
	)
	(segment
		(start 354.686108 -177.700178)
		(end 353.25685 -177.108104)
		(width 0.13208)
		(layer "F.Cu")
		(net "UPI_CPU1_CPU0_P0P1_DP<17>")
	)
	(segment
		(start 366.647222 -212.93455)
		(end 366.647222 -212.794088)
		(width 0.0889)
		(layer "F.Cu")
		(net "UPI_CPU1_CPU0_P0P1_DP<17>")
	)
	(segment
		(start 367.003584 -214.344758)
		(end 367.003584 -214.034116)
		(width 0.0889)
		(layer "F.Cu")
		(net "UPI_CPU1_CPU0_P0P1_DP<17>")
	)
	(segment
		(start 357.844598 -205.227174)
		(end 357.844598 -205.205076)
		(width 0.0889)
		(layer "F.Cu")
		(net "UPI_CPU1_CPU0_P0P1_DP<17>")
	)
	(segment
		(start 104.591866 -215.972644)
		(end 104.591866 -215.436958)
		(width 0.13208)
		(layer "F.Cu")
		(net "UPI_CPU1_CPU0_P0P1_DP<17>")
	)
	(segment
		(start 366.904524 -213.810596)
		(end 367.003838 -213.711282)
		(width 0.0889)
		(layer "F.Cu")
		(net "UPI_CPU1_CPU0_P0P1_DP<17>")
	)
	(segment
		(start 361.245658 -188.60516)
		(end 361.245658 -185.603896)
		(width 0.13208)
		(layer "F.Cu")
		(net "UPI_CPU1_CPU0_P0P1_DP<17>")
	)
	(segment
		(start 364.043214 -210.190334)
		(end 360.930698 -208.901284)
		(width 0.0889)
		(layer "F.Cu")
		(net "UPI_CPU1_CPU0_P0P1_DP<17>")
	)
	(segment
		(start 366.755172 -213.042246)
		(end 366.647222 -212.93455)
		(width 0.0889)
		(layer "F.Cu")
		(net "UPI_CPU1_CPU0_P0P1_DP<17>")
	)
	(segment
		(start 104.591866 -215.436958)
		(end 104.591612 -215.436704)
		(width 0.13208)
		(layer "F.Cu")
		(net "UPI_CPU1_CPU0_P0P1_DP<17>")
	)
	(segment
		(start 367.003838 -213.663022)
		(end 367.003076 -213.149942)
		(width 0.0889)
		(layer "F.Cu")
		(net "UPI_CPU1_CPU0_P0P1_DP<17>")
	)
	(segment
		(start 367.003838 -213.711282)
		(end 367.003838 -213.663022)
		(width 0.0889)
		(layer "F.Cu")
		(net "UPI_CPU1_CPU0_P0P1_DP<17>")
	)
	(segment
		(start 352.994722 -176.808892)
		(end 352.96094 -176.456848)
		(width 0.13208)
		(layer "F.Cu")
		(net "UPI_CPU1_CPU0_P0P1_DP<17>")
	)
	(segment
		(start 357.878888 -205.261464)
		(end 357.844598 -205.227174)
		(width 0.0889)
		(layer "F.Cu")
		(net "UPI_CPU1_CPU0_P0P1_DP<17>")
	)
	(segment
		(start 358.844088 -194.403218)
		(end 358.991662 -194.04711)
		(width 0.13208)
		(layer "F.Cu")
		(net "UPI_CPU1_CPU0_P0P1_DP<17>")
	)
	(segment
		(start 367.003076 -213.149942)
		(end 366.89538 -213.042246)
		(width 0.0889)
		(layer "F.Cu")
		(net "UPI_CPU1_CPU0_P0P1_DP<17>")
	)
	(segment
		(start 353.097846 -176.22012)
		(end 352.950272 -175.668432)
		(width 0.13208)
		(layer "F.Cu")
		(net "UPI_CPU1_CPU0_P0P1_DP<17>")
	)
	(segment
		(start 366.89538 -213.042246)
		(end 366.755172 -213.042246)
		(width 0.0889)
		(layer "F.Cu")
		(net "UPI_CPU1_CPU0_P0P1_DP<17>")
	)
	(segment
		(start 366.628934 -214.344758)
		(end 366.784128 -214.613744)
		(width 0.0889)
		(layer "F.Cu")
		(net "UPI_CPU1_CPU0_P0P1_DP<17>")
	)
	(segment
		(start 357.878888 -205.849474)
		(end 357.878888 -205.261464)
		(width 0.0889)
		(layer "F.Cu")
		(net "UPI_CPU1_CPU0_P0P1_DP<17>")
	)
	(segment
		(start 357.849424 -199.40651)
		(end 358.844088 -194.403218)
		(width 0.13208)
		(layer "F.Cu")
		(net "UPI_CPU1_CPU0_P0P1_DP<17>")
	)
	(segment
		(start 366.784128 -214.613744)
		(end 366.865154 -214.635334)
		(width 0.0889)
		(layer "F.Cu")
		(net "UPI_CPU1_CPU0_P0P1_DP<17>")
	)
	(segment
		(start 353.25685 -177.108104)
		(end 352.994722 -176.808892)
		(width 0.13208)
		(layer "F.Cu")
		(net "UPI_CPU1_CPU0_P0P1_DP<17>")
	)
	(segment
		(start 352.96094 -176.456848)
		(end 353.097846 -176.22012)
		(width 0.13208)
		(layer "F.Cu")
		(net "UPI_CPU1_CPU0_P0P1_DP<17>")
	)
	(arc
		(start 366.865154 -214.635334)
		(mid 366.967175 -214.505672)
		(end 367.003584 -214.344758)
		(width 0.0889)
		(layer "F.Cu")
		(net "UPI_CPU1_CPU0_P0P1_DP<17>")
	)
	(segment
		(start 347.764608 -174.445676)
		(end 347.648022 -174.27321)
		(width 0.14732)
		(layer "In6.Cu")
		(net "UPI_CPU1_CPU0_P0P1_DP<17>")
	)
	(segment
		(start 339.856318 -167.105076)
		(end 339.421216 -167.092122)
		(width 0.14732)
		(layer "In6.Cu")
		(net "UPI_CPU1_CPU0_P0P1_DP<17>")
	)
	(segment
		(start 339.421216 -167.092122)
		(end 338.916772 -167.56761)
		(width 0.14732)
		(layer "In6.Cu")
		(net "UPI_CPU1_CPU0_P0P1_DP<17>")
	)
	(segment
		(start 104.496108 -214.425784)
		(end 104.496108 -214.636858)
		(width 0.0889)
		(layer "In6.Cu")
		(net "UPI_CPU1_CPU0_P0P1_DP<17>")
	)
	(segment
		(start 327.937368 -156.127704)
		(end 325.827644 -154.515312)
		(width 0.14732)
		(layer "In6.Cu")
		(net "UPI_CPU1_CPU0_P0P1_DP<17>")
	)
	(segment
		(start 322.233036 -153.916888)
		(end 279.616916 -162.844988)
		(width 0.14732)
		(layer "In6.Cu")
		(net "UPI_CPU1_CPU0_P0P1_DP<17>")
	)
	(segment
		(start 353.09556 -176.20996)
		(end 352.991166 -176.390808)
		(width 0.14732)
		(layer "In6.Cu")
		(net "UPI_CPU1_CPU0_P0P1_DP<17>")
	)
	(segment
		(start 351.215198 -175.211486)
		(end 351.004124 -175.075088)
		(width 0.14732)
		(layer "In6.Cu")
		(net "UPI_CPU1_CPU0_P0P1_DP<17>")
	)
	(segment
		(start 276.533864 -162.844988)
		(end 238.0361 -152.956768)
		(width 0.14732)
		(layer "In6.Cu")
		(net "UPI_CPU1_CPU0_P0P1_DP<17>")
	)
	(segment
		(start 346.628974 -173.61535)
		(end 346.268294 -173.858682)
		(width 0.14732)
		(layer "In6.Cu")
		(net "UPI_CPU1_CPU0_P0P1_DP<17>")
	)
	(segment
		(start 334.666082 -163.26993)
		(end 334.672432 -163.061904)
		(width 0.14732)
		(layer "In6.Cu")
		(net "UPI_CPU1_CPU0_P0P1_DP<17>")
	)
	(segment
		(start 104.92486 -211.793328)
		(end 104.96677 -211.835238)
		(width 0.0889)
		(layer "In6.Cu")
		(net "UPI_CPU1_CPU0_P0P1_DP<17>")
	)
	(segment
		(start 340.41715 -167.700452)
		(end 339.856318 -167.105076)
		(width 0.14732)
		(layer "In6.Cu")
		(net "UPI_CPU1_CPU0_P0P1_DP<17>")
	)
	(segment
		(start 335.53019 -164.187124)
		(end 334.666082 -163.26993)
		(width 0.14732)
		(layer "In6.Cu")
		(net "UPI_CPU1_CPU0_P0P1_DP<17>")
	)
	(segment
		(start 336.714846 -165.444932)
		(end 336.721196 -165.236906)
		(width 0.14732)
		(layer "In6.Cu")
		(net "UPI_CPU1_CPU0_P0P1_DP<17>")
	)
	(segment
		(start 333.481426 -162.012122)
		(end 327.937368 -156.127704)
		(width 0.14732)
		(layer "In6.Cu")
		(net "UPI_CPU1_CPU0_P0P1_DP<17>")
	)
	(segment
		(start 352.950272 -175.668432)
		(end 353.09556 -176.20996)
		(width 0.14732)
		(layer "In6.Cu")
		(net "UPI_CPU1_CPU0_P0P1_DP<17>")
	)
	(segment
		(start 352.815652 -176.566068)
		(end 352.500692 -176.566068)
		(width 0.14732)
		(layer "In6.Cu")
		(net "UPI_CPU1_CPU0_P0P1_DP<17>")
	)
	(segment
		(start 194.609212 -162.834828)
		(end 190.733172 -162.834828)
		(width 0.14732)
		(layer "In6.Cu")
		(net "UPI_CPU1_CPU0_P0P1_DP<17>")
	)
	(segment
		(start 323.449188 -153.916888)
		(end 322.233036 -153.916888)
		(width 0.14732)
		(layer "In6.Cu")
		(net "UPI_CPU1_CPU0_P0P1_DP<17>")
	)
	(segment
		(start 165.128448 -152.48128)
		(end 132.503926 -172.585888)
		(width 0.14732)
		(layer "In6.Cu")
		(net "UPI_CPU1_CPU0_P0P1_DP<17>")
	)
	(segment
		(start 333.689452 -162.018472)
		(end 333.481426 -162.012122)
		(width 0.14732)
		(layer "In6.Cu")
		(net "UPI_CPU1_CPU0_P0P1_DP<17>")
	)
	(segment
		(start 337.327494 -165.880542)
		(end 337.119468 -165.874192)
		(width 0.14732)
		(layer "In6.Cu")
		(net "UPI_CPU1_CPU0_P0P1_DP<17>")
	)
	(segment
		(start 339.899752 -168.611042)
		(end 340.404196 -168.135554)
		(width 0.14732)
		(layer "In6.Cu")
		(net "UPI_CPU1_CPU0_P0P1_DP<17>")
	)
	(segment
		(start 132.503926 -172.585888)
		(end 118.39067 -185.857134)
		(width 0.14732)
		(layer "In6.Cu")
		(net "UPI_CPU1_CPU0_P0P1_DP<17>")
	)
	(segment
		(start 337.238594 -164.326316)
		(end 336.677762 -163.73094)
		(width 0.14732)
		(layer "In6.Cu")
		(net "UPI_CPU1_CPU0_P0P1_DP<17>")
	)
	(segment
		(start 339.893402 -168.819068)
		(end 339.899752 -168.611042)
		(width 0.14732)
		(layer "In6.Cu")
		(net "UPI_CPU1_CPU0_P0P1_DP<17>")
	)
	(segment
		(start 104.748076 -215.165686)
		(end 104.591612 -215.436704)
		(width 0.0889)
		(layer "In6.Cu")
		(net "UPI_CPU1_CPU0_P0P1_DP<17>")
	)
	(segment
		(start 104.723946 -215.076532)
		(end 104.748076 -215.165686)
		(width 0.0889)
		(layer "In6.Cu")
		(net "UPI_CPU1_CPU0_P0P1_DP<17>")
	)
	(segment
		(start 346.068396 -174.116238)
		(end 344.845386 -173.87824)
		(width 0.14732)
		(layer "In6.Cu")
		(net "UPI_CPU1_CPU0_P0P1_DP<17>")
	)
	(segment
		(start 173.168818 -153.645362)
		(end 169.952924 -152.052782)
		(width 0.14732)
		(layer "In6.Cu")
		(net "UPI_CPU1_CPU0_P0P1_DP<17>")
	)
	(segment
		(start 325.827644 -154.515312)
		(end 323.449188 -153.916888)
		(width 0.14732)
		(layer "In6.Cu")
		(net "UPI_CPU1_CPU0_P0P1_DP<17>")
	)
	(segment
		(start 104.92486 -211.387436)
		(end 104.92486 -211.77123)
		(width 0.14732)
		(layer "In6.Cu")
		(net "UPI_CPU1_CPU0_P0P1_DP<17>")
	)
	(segment
		(start 352.991166 -176.390808)
		(end 352.815652 -176.566068)
		(width 0.14732)
		(layer "In6.Cu")
		(net "UPI_CPU1_CPU0_P0P1_DP<17>")
	)
	(segment
		(start 334.361028 -161.808668)
		(end 333.925926 -161.795714)
		(width 0.14732)
		(layer "In6.Cu")
		(net "UPI_CPU1_CPU0_P0P1_DP<17>")
	)
	(segment
		(start 104.96677 -213.892892)
		(end 104.966516 -213.8934)
		(width 0.0889)
		(layer "In6.Cu")
		(net "UPI_CPU1_CPU0_P0P1_DP<17>")
	)
	(segment
		(start 338.708746 -167.56126)
		(end 338.304124 -167.132)
		(width 0.14732)
		(layer "In6.Cu")
		(net "UPI_CPU1_CPU0_P0P1_DP<17>")
	)
	(segment
		(start 169.952924 -152.052782)
		(end 166.609268 -151.964136)
		(width 0.14732)
		(layer "In6.Cu")
		(net "UPI_CPU1_CPU0_P0P1_DP<17>")
	)
	(segment
		(start 338.916772 -167.56761)
		(end 338.708746 -167.56126)
		(width 0.14732)
		(layer "In6.Cu")
		(net "UPI_CPU1_CPU0_P0P1_DP<17>")
	)
	(segment
		(start 347.432122 -173.77156)
		(end 346.628974 -173.61535)
		(width 0.14732)
		(layer "In6.Cu")
		(net "UPI_CPU1_CPU0_P0P1_DP<17>")
	)
	(segment
		(start 197.051422 -162.52698)
		(end 194.609212 -162.834828)
		(width 0.14732)
		(layer "In6.Cu")
		(net "UPI_CPU1_CPU0_P0P1_DP<17>")
	)
	(segment
		(start 104.96677 -211.835238)
		(end 104.96677 -213.892892)
		(width 0.0889)
		(layer "In6.Cu")
		(net "UPI_CPU1_CPU0_P0P1_DP<17>")
	)
	(segment
		(start 334.672432 -163.061904)
		(end 334.908906 -162.839146)
		(width 0.14732)
		(layer "In6.Cu")
		(net "UPI_CPU1_CPU0_P0P1_DP<17>")
	)
	(segment
		(start 352.0567 -176.330864)
		(end 351.215198 -175.211486)
		(width 0.14732)
		(layer "In6.Cu")
		(net "UPI_CPU1_CPU0_P0P1_DP<17>")
	)
	(segment
		(start 234.174538 -152.956768)
		(end 197.051422 -162.52698)
		(width 0.14732)
		(layer "In6.Cu")
		(net "UPI_CPU1_CPU0_P0P1_DP<17>")
	)
	(segment
		(start 279.616916 -162.844988)
		(end 276.533864 -162.844988)
		(width 0.14732)
		(layer "In6.Cu")
		(net "UPI_CPU1_CPU0_P0P1_DP<17>")
	)
	(segment
		(start 333.925926 -161.795714)
		(end 333.689452 -162.018472)
		(width 0.14732)
		(layer "In6.Cu")
		(net "UPI_CPU1_CPU0_P0P1_DP<17>")
	)
	(segment
		(start 338.827872 -166.013384)
		(end 338.26704 -165.418008)
		(width 0.14732)
		(layer "In6.Cu")
		(net "UPI_CPU1_CPU0_P0P1_DP<17>")
	)
	(segment
		(start 344.458036 -173.664626)
		(end 339.893402 -168.819068)
		(width 0.14732)
		(layer "In6.Cu")
		(net "UPI_CPU1_CPU0_P0P1_DP<17>")
	)
	(segment
		(start 337.22564 -164.761418)
		(end 337.238594 -164.326316)
		(width 0.14732)
		(layer "In6.Cu")
		(net "UPI_CPU1_CPU0_P0P1_DP<17>")
	)
	(segment
		(start 166.609268 -151.964136)
		(end 165.128448 -152.48128)
		(width 0.14732)
		(layer "In6.Cu")
		(net "UPI_CPU1_CPU0_P0P1_DP<17>")
	)
	(segment
		(start 335.738216 -164.193474)
		(end 335.53019 -164.187124)
		(width 0.14732)
		(layer "In6.Cu")
		(net "UPI_CPU1_CPU0_P0P1_DP<17>")
	)
	(segment
		(start 347.675708 -174.13224)
		(end 347.432122 -173.77156)
		(width 0.14732)
		(layer "In6.Cu")
		(net "UPI_CPU1_CPU0_P0P1_DP<17>")
	)
	(segment
		(start 340.404196 -168.135554)
		(end 340.41715 -167.700452)
		(width 0.14732)
		(layer "In6.Cu")
		(net "UPI_CPU1_CPU0_P0P1_DP<17>")
	)
	(segment
		(start 337.831938 -165.405054)
		(end 337.327494 -165.880542)
		(width 0.14732)
		(layer "In6.Cu")
		(net "UPI_CPU1_CPU0_P0P1_DP<17>")
	)
	(segment
		(start 347.648022 -174.27321)
		(end 347.675708 -174.13224)
		(width 0.14732)
		(layer "In6.Cu")
		(net "UPI_CPU1_CPU0_P0P1_DP<17>")
	)
	(segment
		(start 336.721196 -165.236906)
		(end 337.22564 -164.761418)
		(width 0.14732)
		(layer "In6.Cu")
		(net "UPI_CPU1_CPU0_P0P1_DP<17>")
	)
	(segment
		(start 351.004124 -175.075088)
		(end 347.764608 -174.445676)
		(width 0.14732)
		(layer "In6.Cu")
		(net "UPI_CPU1_CPU0_P0P1_DP<17>")
	)
	(segment
		(start 346.268294 -173.858682)
		(end 346.240862 -173.999652)
		(width 0.14732)
		(layer "In6.Cu")
		(net "UPI_CPU1_CPU0_P0P1_DP<17>")
	)
	(segment
		(start 190.733172 -162.834828)
		(end 173.168818 -153.645362)
		(width 0.14732)
		(layer "In6.Cu")
		(net "UPI_CPU1_CPU0_P0P1_DP<17>")
	)
	(segment
		(start 118.39067 -185.857134)
		(end 110.695486 -195.544948)
		(width 0.14732)
		(layer "In6.Cu")
		(net "UPI_CPU1_CPU0_P0P1_DP<17>")
	)
	(segment
		(start 238.0361 -152.956768)
		(end 234.174538 -152.956768)
		(width 0.14732)
		(layer "In6.Cu")
		(net "UPI_CPU1_CPU0_P0P1_DP<17>")
	)
	(segment
		(start 338.26704 -165.418008)
		(end 337.831938 -165.405054)
		(width 0.14732)
		(layer "In6.Cu")
		(net "UPI_CPU1_CPU0_P0P1_DP<17>")
	)
	(segment
		(start 104.92486 -211.77123)
		(end 104.92486 -211.793328)
		(width 0.0889)
		(layer "In6.Cu")
		(net "UPI_CPU1_CPU0_P0P1_DP<17>")
	)
	(segment
		(start 338.310474 -166.923974)
		(end 338.814918 -166.448486)
		(width 0.14732)
		(layer "In6.Cu")
		(net "UPI_CPU1_CPU0_P0P1_DP<17>")
	)
	(segment
		(start 334.92186 -162.404044)
		(end 334.361028 -161.808668)
		(width 0.14732)
		(layer "In6.Cu")
		(net "UPI_CPU1_CPU0_P0P1_DP<17>")
	)
	(segment
		(start 338.814918 -166.448486)
		(end 338.827872 -166.013384)
		(width 0.14732)
		(layer "In6.Cu")
		(net "UPI_CPU1_CPU0_P0P1_DP<17>")
	)
	(segment
		(start 344.845386 -173.87824)
		(end 344.458036 -173.664626)
		(width 0.14732)
		(layer "In6.Cu")
		(net "UPI_CPU1_CPU0_P0P1_DP<17>")
	)
	(segment
		(start 352.500692 -176.566068)
		(end 352.0567 -176.330864)
		(width 0.14732)
		(layer "In6.Cu")
		(net "UPI_CPU1_CPU0_P0P1_DP<17>")
	)
	(segment
		(start 336.677762 -163.73094)
		(end 336.24266 -163.717986)
		(width 0.14732)
		(layer "In6.Cu")
		(net "UPI_CPU1_CPU0_P0P1_DP<17>")
	)
	(segment
		(start 110.695486 -195.544948)
		(end 104.92486 -211.387436)
		(width 0.14732)
		(layer "In6.Cu")
		(net "UPI_CPU1_CPU0_P0P1_DP<17>")
	)
	(segment
		(start 334.908906 -162.839146)
		(end 334.92186 -162.404044)
		(width 0.14732)
		(layer "In6.Cu")
		(net "UPI_CPU1_CPU0_P0P1_DP<17>")
	)
	(segment
		(start 337.119468 -165.874192)
		(end 336.714846 -165.444932)
		(width 0.14732)
		(layer "In6.Cu")
		(net "UPI_CPU1_CPU0_P0P1_DP<17>")
	)
	(segment
		(start 336.24266 -163.717986)
		(end 335.738216 -164.193474)
		(width 0.14732)
		(layer "In6.Cu")
		(net "UPI_CPU1_CPU0_P0P1_DP<17>")
	)
	(segment
		(start 346.240862 -173.999652)
		(end 346.068396 -174.116238)
		(width 0.14732)
		(layer "In6.Cu")
		(net "UPI_CPU1_CPU0_P0P1_DP<17>")
	)
	(segment
		(start 338.304124 -167.132)
		(end 338.310474 -166.923974)
		(width 0.14732)
		(layer "In6.Cu")
		(net "UPI_CPU1_CPU0_P0P1_DP<17>")
	)
	(arc
		(start 104.706928 -215.063324)
		(mid 104.715374 -215.070009)
		(end 104.723946 -215.076532)
		(width 0.0889)
		(layer "In6.Cu")
		(net "UPI_CPU1_CPU0_P0P1_DP<17>")
	)
	(arc
		(start 104.496108 -214.636858)
		(mid 104.554453 -214.873363)
		(end 104.706928 -215.063324)
		(width 0.0889)
		(layer "In6.Cu")
		(net "UPI_CPU1_CPU0_P0P1_DP<17>")
	)
	(arc
		(start 104.782112 -214.093298)
		(mid 104.607564 -214.232402)
		(end 104.496108 -214.425784)
		(width 0.0889)
		(layer "In6.Cu")
		(net "UPI_CPU1_CPU0_P0P1_DP<17>")
	)
	(arc
		(start 104.966516 -213.8934)
		(mid 104.891445 -214.009142)
		(end 104.782112 -214.093298)
		(width 0.0889)
		(layer "In6.Cu")
		(net "UPI_CPU1_CPU0_P0P1_DP<17>")
	)
	(segment
		(start 353.967288 -174.86503)
		(end 350.51619 -174.178214)
		(width 0.13208)
		(layer "F.Cu")
		(net "UPI_CPU1_CPU0_P0P1_DP<16>")
	)
	(segment
		(start 368.232944 -213.960456)
		(end 368.232944 -213.808056)
		(width 0.0889)
		(layer "F.Cu")
		(net "UPI_CPU1_CPU0_P0P1_DP<16>")
	)
	(segment
		(start 359.377234 -205.709266)
		(end 359.377234 -205.261718)
		(width 0.0889)
		(layer "F.Cu")
		(net "UPI_CPU1_CPU0_P0P1_DP<16>")
	)
	(segment
		(start 360.448098 -194.620896)
		(end 362.814108 -188.908944)
		(width 0.13208)
		(layer "F.Cu")
		(net "UPI_CPU1_CPU0_P0P1_DP<16>")
	)
	(segment
		(start 367.883186 -215.42756)
		(end 367.80216 -215.44915)
		(width 0.0889)
		(layer "F.Cu")
		(net "UPI_CPU1_CPU0_P0P1_DP<16>")
	)
	(segment
		(start 368.23269 -213.44509)
		(end 368.23269 -213.29269)
		(width 0.0889)
		(layer "F.Cu")
		(net "UPI_CPU1_CPU0_P0P1_DP<16>")
	)
	(segment
		(start 363.3597 -186.165998)
		(end 363.3597 -183.84012)
		(width 0.13208)
		(layer "F.Cu")
		(net "UPI_CPU1_CPU0_P0P1_DP<16>")
	)
	(segment
		(start 349.941896 -173.680882)
		(end 350.089724 -173.128432)
		(width 0.13208)
		(layer "F.Cu")
		(net "UPI_CPU1_CPU0_P0P1_DP<16>")
	)
	(segment
		(start 350.51619 -174.178214)
		(end 350.08566 -173.929548)
		(width 0.13208)
		(layer "F.Cu")
		(net "UPI_CPU1_CPU0_P0P1_DP<16>")
	)
	(segment
		(start 368.232944 -213.808056)
		(end 368.13363 -213.708742)
		(width 0.0889)
		(layer "F.Cu")
		(net "UPI_CPU1_CPU0_P0P1_DP<16>")
	)
	(segment
		(start 103.652066 -214.344758)
		(end 103.652066 -213.732618)
		(width 0.13208)
		(layer "F.Cu")
		(net "UPI_CPU1_CPU0_P0P1_DP<16>")
	)
	(segment
		(start 368.03838 -215.158574)
		(end 367.883186 -215.42756)
		(width 0.0889)
		(layer "F.Cu")
		(net "UPI_CPU1_CPU0_P0P1_DP<16>")
	)
	(segment
		(start 368.133884 -214.345266)
		(end 368.133884 -214.059516)
		(width 0.0889)
		(layer "F.Cu")
		(net "UPI_CPU1_CPU0_P0P1_DP<16>")
	)
	(segment
		(start 362.095034 -208.427066)
		(end 359.377234 -205.709266)
		(width 0.0889)
		(layer "F.Cu")
		(net "UPI_CPU1_CPU0_P0P1_DP<16>")
	)
	(segment
		(start 368.13363 -212.931248)
		(end 364.71479 -209.512408)
		(width 0.0889)
		(layer "F.Cu")
		(net "UPI_CPU1_CPU0_P0P1_DP<16>")
	)
	(segment
		(start 368.13363 -213.708742)
		(end 368.13363 -213.54415)
		(width 0.0889)
		(layer "F.Cu")
		(net "UPI_CPU1_CPU0_P0P1_DP<16>")
	)
	(segment
		(start 368.13363 -213.19363)
		(end 368.13363 -212.931248)
		(width 0.0889)
		(layer "F.Cu")
		(net "UPI_CPU1_CPU0_P0P1_DP<16>")
	)
	(segment
		(start 359.377234 -205.261718)
		(end 359.411778 -205.227174)
		(width 0.0889)
		(layer "F.Cu")
		(net "UPI_CPU1_CPU0_P0P1_DP<16>")
	)
	(segment
		(start 355.84384 -176.119028)
		(end 353.967288 -174.86503)
		(width 0.13208)
		(layer "F.Cu")
		(net "UPI_CPU1_CPU0_P0P1_DP<16>")
	)
	(segment
		(start 363.214666 -183.489854)
		(end 355.84384 -176.119028)
		(width 0.13208)
		(layer "F.Cu")
		(net "UPI_CPU1_CPU0_P0P1_DP<16>")
	)
	(segment
		(start 359.411778 -205.227174)
		(end 359.411778 -205.205076)
		(width 0.0889)
		(layer "F.Cu")
		(net "UPI_CPU1_CPU0_P0P1_DP<16>")
	)
	(segment
		(start 362.814108 -188.908944)
		(end 363.3597 -186.165998)
		(width 0.13208)
		(layer "F.Cu")
		(net "UPI_CPU1_CPU0_P0P1_DP<16>")
	)
	(segment
		(start 359.411778 -199.830436)
		(end 360.448098 -194.620896)
		(width 0.13208)
		(layer "F.Cu")
		(net "UPI_CPU1_CPU0_P0P1_DP<16>")
	)
	(segment
		(start 368.13363 -213.54415)
		(end 368.23269 -213.44509)
		(width 0.0889)
		(layer "F.Cu")
		(net "UPI_CPU1_CPU0_P0P1_DP<16>")
	)
	(segment
		(start 350.08566 -173.929548)
		(end 349.942404 -173.681644)
		(width 0.13208)
		(layer "F.Cu")
		(net "UPI_CPU1_CPU0_P0P1_DP<16>")
	)
	(segment
		(start 349.942404 -173.681644)
		(end 349.941896 -173.680882)
		(width 0.13208)
		(layer "F.Cu")
		(net "UPI_CPU1_CPU0_P0P1_DP<16>")
	)
	(segment
		(start 363.3597 -183.84012)
		(end 363.214666 -183.489854)
		(width 0.13208)
		(layer "F.Cu")
		(net "UPI_CPU1_CPU0_P0P1_DP<16>")
	)
	(segment
		(start 368.23269 -213.29269)
		(end 368.13363 -213.19363)
		(width 0.0889)
		(layer "F.Cu")
		(net "UPI_CPU1_CPU0_P0P1_DP<16>")
	)
	(segment
		(start 364.71479 -209.512408)
		(end 362.095034 -208.427066)
		(width 0.0889)
		(layer "F.Cu")
		(net "UPI_CPU1_CPU0_P0P1_DP<16>")
	)
	(segment
		(start 359.411778 -205.205076)
		(end 359.411778 -199.830436)
		(width 0.13208)
		(layer "F.Cu")
		(net "UPI_CPU1_CPU0_P0P1_DP<16>")
	)
	(segment
		(start 368.133884 -214.059516)
		(end 368.232944 -213.960456)
		(width 0.0889)
		(layer "F.Cu")
		(net "UPI_CPU1_CPU0_P0P1_DP<16>")
	)
	(arc
		(start 367.66373 -215.158574)
		(mid 367.717136 -214.965538)
		(end 367.862358 -214.827612)
		(width 0.0889)
		(layer "F.Cu")
		(net "UPI_CPU1_CPU0_P0P1_DP<16>")
	)
	(arc
		(start 367.870486 -214.822532)
		(mid 368.063598 -214.61777)
		(end 368.133884 -214.345266)
		(width 0.0889)
		(layer "F.Cu")
		(net "UPI_CPU1_CPU0_P0P1_DP<16>")
	)
	(arc
		(start 367.864644 -214.826342)
		(mid 367.867571 -214.824446)
		(end 367.870486 -214.822532)
		(width 0.0889)
		(layer "F.Cu")
		(net "UPI_CPU1_CPU0_P0P1_DP<16>")
	)
	(arc
		(start 367.862358 -214.827612)
		(mid 367.863504 -214.826982)
		(end 367.864644 -214.826342)
		(width 0.0889)
		(layer "F.Cu")
		(net "UPI_CPU1_CPU0_P0P1_DP<16>")
	)
	(arc
		(start 367.80216 -215.44915)
		(mid 367.700139 -215.319488)
		(end 367.66373 -215.158574)
		(width 0.0889)
		(layer "F.Cu")
		(net "UPI_CPU1_CPU0_P0P1_DP<16>")
	)
	(segment
		(start 104.026716 -213.8934)
		(end 104.026716 -213.499192)
		(width 0.0889)
		(layer "In6.Cu")
		(net "UPI_CPU1_CPU0_P0P1_DP<16>")
	)
	(segment
		(start 342.392762 -169.572178)
		(end 342.407748 -169.779188)
		(width 0.14732)
		(layer "In6.Cu")
		(net "UPI_CPU1_CPU0_P0P1_DP<16>")
	)
	(segment
		(start 103.927402 -213.133178)
		(end 104.026716 -213.033864)
		(width 0.0889)
		(layer "In6.Cu")
		(net "UPI_CPU1_CPU0_P0P1_DP<16>")
	)
	(segment
		(start 343.893902 -169.187876)
		(end 344.328242 -169.156634)
		(width 0.14732)
		(layer "In6.Cu")
		(net "UPI_CPU1_CPU0_P0P1_DP<16>")
	)
	(segment
		(start 104.026716 -212.767164)
		(end 103.927402 -212.66785)
		(width 0.0889)
		(layer "In6.Cu")
		(net "UPI_CPU1_CPU0_P0P1_DP<16>")
	)
	(segment
		(start 103.927402 -212.66785)
		(end 103.927402 -212.40115)
		(width 0.0889)
		(layer "In6.Cu")
		(net "UPI_CPU1_CPU0_P0P1_DP<16>")
	)
	(segment
		(start 342.855042 -170.165776)
		(end 343.062052 -170.15079)
		(width 0.14732)
		(layer "In6.Cu")
		(net "UPI_CPU1_CPU0_P0P1_DP<16>")
	)
	(segment
		(start 276.643338 -161.981388)
		(end 279.527254 -161.981388)
		(width 0.14732)
		(layer "In6.Cu")
		(net "UPI_CPU1_CPU0_P0P1_DP<16>")
	)
	(segment
		(start 346.081604 -170.672252)
		(end 347.794834 -172.153072)
		(width 0.14732)
		(layer "In6.Cu")
		(net "UPI_CPU1_CPU0_P0P1_DP<16>")
	)
	(segment
		(start 103.927402 -213.399878)
		(end 103.927402 -213.133178)
		(width 0.0889)
		(layer "In6.Cu")
		(net "UPI_CPU1_CPU0_P0P1_DP<16>")
	)
	(segment
		(start 344.977974 -170.125136)
		(end 344.146124 -171.087796)
		(width 0.14732)
		(layer "In6.Cu")
		(net "UPI_CPU1_CPU0_P0P1_DP<16>")
	)
	(segment
		(start 104.026716 -212.301836)
		(end 104.026716 -211.835238)
		(width 0.0889)
		(layer "In6.Cu")
		(net "UPI_CPU1_CPU0_P0P1_DP<16>")
	)
	(segment
		(start 349.413322 -172.748956)
		(end 349.548704 -172.98289)
		(width 0.14732)
		(layer "In6.Cu")
		(net "UPI_CPU1_CPU0_P0P1_DP<16>")
	)
	(segment
		(start 196.888862 -161.676588)
		(end 196.888862 -161.676842)
		(width 0.14732)
		(layer "In6.Cu")
		(net "UPI_CPU1_CPU0_P0P1_DP<16>")
	)
	(segment
		(start 109.979714 -194.898772)
		(end 117.128798 -185.899044)
		(width 0.14732)
		(layer "In6.Cu")
		(net "UPI_CPU1_CPU0_P0P1_DP<16>")
	)
	(segment
		(start 322.143374 -153.053288)
		(end 323.556376 -153.053288)
		(width 0.14732)
		(layer "In6.Cu")
		(net "UPI_CPU1_CPU0_P0P1_DP<16>")
	)
	(segment
		(start 344.146124 -171.087796)
		(end 344.16111 -171.294806)
		(width 0.14732)
		(layer "In6.Cu")
		(net "UPI_CPU1_CPU0_P0P1_DP<16>")
	)
	(segment
		(start 194.554856 -161.971228)
		(end 196.888862 -161.676588)
		(width 0.14732)
		(layer "In6.Cu")
		(net "UPI_CPU1_CPU0_P0P1_DP<16>")
	)
	(segment
		(start 238.135668 -152.090628)
		(end 276.643338 -161.981388)
		(width 0.14732)
		(layer "In6.Cu")
		(net "UPI_CPU1_CPU0_P0P1_DP<16>")
	)
	(segment
		(start 347.794834 -172.153072)
		(end 348.9579 -172.432472)
		(width 0.14732)
		(layer "In6.Cu")
		(net "UPI_CPU1_CPU0_P0P1_DP<16>")
	)
	(segment
		(start 323.556376 -153.053288)
		(end 326.211184 -153.7208)
		(width 0.14732)
		(layer "In6.Cu")
		(net "UPI_CPU1_CPU0_P0P1_DP<16>")
	)
	(segment
		(start 348.9579 -172.432472)
		(end 349.413322 -172.748956)
		(width 0.14732)
		(layer "In6.Cu")
		(net "UPI_CPU1_CPU0_P0P1_DP<16>")
	)
	(segment
		(start 132.04698 -171.872402)
		(end 165.12921 -151.485346)
		(width 0.14732)
		(layer "In6.Cu")
		(net "UPI_CPU1_CPU0_P0P1_DP<16>")
	)
	(segment
		(start 103.984806 -211.77123)
		(end 103.984806 -211.357718)
		(width 0.14732)
		(layer "In6.Cu")
		(net "UPI_CPU1_CPU0_P0P1_DP<16>")
	)
	(segment
		(start 104.026716 -211.835238)
		(end 103.984806 -211.793328)
		(width 0.0889)
		(layer "In6.Cu")
		(net "UPI_CPU1_CPU0_P0P1_DP<16>")
	)
	(segment
		(start 170.054778 -151.115014)
		(end 173.5709 -152.856692)
		(width 0.14732)
		(layer "In6.Cu")
		(net "UPI_CPU1_CPU0_P0P1_DP<16>")
	)
	(segment
		(start 234.074462 -152.090628)
		(end 238.135668 -152.090628)
		(width 0.14732)
		(layer "In6.Cu")
		(net "UPI_CPU1_CPU0_P0P1_DP<16>")
	)
	(segment
		(start 103.984806 -211.357718)
		(end 109.979714 -194.898772)
		(width 0.14732)
		(layer "In6.Cu")
		(net "UPI_CPU1_CPU0_P0P1_DP<16>")
	)
	(segment
		(start 190.99149 -161.971228)
		(end 194.554856 -161.971228)
		(width 0.14732)
		(layer "In6.Cu")
		(net "UPI_CPU1_CPU0_P0P1_DP<16>")
	)
	(segment
		(start 345.647264 -170.703494)
		(end 346.081604 -170.672252)
		(width 0.14732)
		(layer "In6.Cu")
		(net "UPI_CPU1_CPU0_P0P1_DP<16>")
	)
	(segment
		(start 343.19337 -168.175178)
		(end 343.224612 -168.609518)
		(width 0.14732)
		(layer "In6.Cu")
		(net "UPI_CPU1_CPU0_P0P1_DP<16>")
	)
	(segment
		(start 104.026716 -213.033864)
		(end 104.026716 -212.767164)
		(width 0.0889)
		(layer "In6.Cu")
		(net "UPI_CPU1_CPU0_P0P1_DP<16>")
	)
	(segment
		(start 343.062052 -170.15079)
		(end 343.893902 -169.187876)
		(width 0.14732)
		(layer "In6.Cu")
		(net "UPI_CPU1_CPU0_P0P1_DP<16>")
	)
	(segment
		(start 343.224612 -168.609518)
		(end 342.392762 -169.572178)
		(width 0.14732)
		(layer "In6.Cu")
		(net "UPI_CPU1_CPU0_P0P1_DP<16>")
	)
	(segment
		(start 196.888862 -161.676842)
		(end 234.074462 -152.090628)
		(width 0.14732)
		(layer "In6.Cu")
		(net "UPI_CPU1_CPU0_P0P1_DP<16>")
	)
	(segment
		(start 104.026716 -213.499192)
		(end 103.927402 -213.399878)
		(width 0.0889)
		(layer "In6.Cu")
		(net "UPI_CPU1_CPU0_P0P1_DP<16>")
	)
	(segment
		(start 173.5709 -152.856692)
		(end 190.99149 -161.971228)
		(width 0.14732)
		(layer "In6.Cu")
		(net "UPI_CPU1_CPU0_P0P1_DP<16>")
	)
	(segment
		(start 344.946732 -169.690796)
		(end 344.977974 -170.125136)
		(width 0.14732)
		(layer "In6.Cu")
		(net "UPI_CPU1_CPU0_P0P1_DP<16>")
	)
	(segment
		(start 344.328242 -169.156634)
		(end 344.946732 -169.690796)
		(width 0.14732)
		(layer "In6.Cu")
		(net "UPI_CPU1_CPU0_P0P1_DP<16>")
	)
	(segment
		(start 344.815414 -171.666408)
		(end 345.647264 -170.703494)
		(width 0.14732)
		(layer "In6.Cu")
		(net "UPI_CPU1_CPU0_P0P1_DP<16>")
	)
	(segment
		(start 166.461948 -151.020018)
		(end 170.054778 -151.115014)
		(width 0.14732)
		(layer "In6.Cu")
		(net "UPI_CPU1_CPU0_P0P1_DP<16>")
	)
	(segment
		(start 117.128798 -185.899044)
		(end 132.04698 -171.872402)
		(width 0.14732)
		(layer "In6.Cu")
		(net "UPI_CPU1_CPU0_P0P1_DP<16>")
	)
	(segment
		(start 342.407748 -169.779188)
		(end 342.855042 -170.165776)
		(width 0.14732)
		(layer "In6.Cu")
		(net "UPI_CPU1_CPU0_P0P1_DP<16>")
	)
	(segment
		(start 279.527254 -161.981388)
		(end 322.143374 -153.053288)
		(width 0.14732)
		(layer "In6.Cu")
		(net "UPI_CPU1_CPU0_P0P1_DP<16>")
	)
	(segment
		(start 349.548704 -172.98289)
		(end 349.549212 -172.983652)
		(width 0.14732)
		(layer "In6.Cu")
		(net "UPI_CPU1_CPU0_P0P1_DP<16>")
	)
	(segment
		(start 103.810816 -214.033608)
		(end 103.895398 -214.05977)
		(width 0.0889)
		(layer "In6.Cu")
		(net "UPI_CPU1_CPU0_P0P1_DP<16>")
	)
	(segment
		(start 103.927402 -212.40115)
		(end 104.026716 -212.301836)
		(width 0.0889)
		(layer "In6.Cu")
		(net "UPI_CPU1_CPU0_P0P1_DP<16>")
	)
	(segment
		(start 103.984806 -211.793328)
		(end 103.984806 -211.77123)
		(width 0.0889)
		(layer "In6.Cu")
		(net "UPI_CPU1_CPU0_P0P1_DP<16>")
	)
	(segment
		(start 349.549212 -172.983652)
		(end 350.089724 -173.128432)
		(width 0.14732)
		(layer "In6.Cu")
		(net "UPI_CPU1_CPU0_P0P1_DP<16>")
	)
	(segment
		(start 344.608404 -171.681394)
		(end 344.815414 -171.666408)
		(width 0.14732)
		(layer "In6.Cu")
		(net "UPI_CPU1_CPU0_P0P1_DP<16>")
	)
	(segment
		(start 165.12921 -151.485346)
		(end 166.461948 -151.020018)
		(width 0.14732)
		(layer "In6.Cu")
		(net "UPI_CPU1_CPU0_P0P1_DP<16>")
	)
	(segment
		(start 326.211184 -153.7208)
		(end 328.461624 -155.441396)
		(width 0.14732)
		(layer "In6.Cu")
		(net "UPI_CPU1_CPU0_P0P1_DP<16>")
	)
	(segment
		(start 328.461624 -155.441396)
		(end 343.19337 -168.175178)
		(width 0.14732)
		(layer "In6.Cu")
		(net "UPI_CPU1_CPU0_P0P1_DP<16>")
	)
	(segment
		(start 103.652066 -213.732618)
		(end 103.810816 -214.033608)
		(width 0.0889)
		(layer "In6.Cu")
		(net "UPI_CPU1_CPU0_P0P1_DP<16>")
	)
	(segment
		(start 344.16111 -171.294806)
		(end 344.608404 -171.681394)
		(width 0.14732)
		(layer "In6.Cu")
		(net "UPI_CPU1_CPU0_P0P1_DP<16>")
	)
	(arc
		(start 103.895398 -214.05977)
		(mid 103.972071 -213.985276)
		(end 104.026716 -213.8934)
		(width 0.0889)
		(layer "In6.Cu")
		(net "UPI_CPU1_CPU0_P0P1_DP<16>")
	)
	(segment
		(start 368.784124 -213.320376)
		(end 368.784124 -213.167976)
		(width 0.0889)
		(layer "F.Cu")
		(net "UPI_CPU1_CPU0_P0P1_DP<15>")
	)
	(segment
		(start 368.784124 -213.167976)
		(end 368.883184 -213.068916)
		(width 0.0889)
		(layer "F.Cu")
		(net "UPI_CPU1_CPU0_P0P1_DP<15>")
	)
	(segment
		(start 362.890308 -208.193894)
		(end 360.495088 -205.79842)
		(width 0.0889)
		(layer "F.Cu")
		(net "UPI_CPU1_CPU0_P0P1_DP<15>")
	)
	(segment
		(start 102.712266 -215.436958)
		(end 102.712012 -215.436704)
		(width 0.13208)
		(layer "F.Cu")
		(net "UPI_CPU1_CPU0_P0P1_DP<15>")
	)
	(segment
		(start 368.883184 -213.068916)
		(end 368.883184 -212.840316)
		(width 0.0889)
		(layer "F.Cu")
		(net "UPI_CPU1_CPU0_P0P1_DP<15>")
	)
	(segment
		(start 353.459542 -173.520608)
		(end 353.032314 -173.09338)
		(width 0.13208)
		(layer "F.Cu")
		(net "UPI_CPU1_CPU0_P0P1_DP<15>")
	)
	(segment
		(start 364.24489 -188.18987)
		(end 364.62081 -186.299856)
		(width 0.13208)
		(layer "F.Cu")
		(net "UPI_CPU1_CPU0_P0P1_DP<15>")
	)
	(segment
		(start 353.095814 -172.540676)
		(end 353.096576 -172.539406)
		(width 0.13208)
		(layer "F.Cu")
		(net "UPI_CPU1_CPU0_P0P1_DP<15>")
	)
	(segment
		(start 368.883184 -213.571836)
		(end 368.883184 -213.419436)
		(width 0.0889)
		(layer "F.Cu")
		(net "UPI_CPU1_CPU0_P0P1_DP<15>")
	)
	(segment
		(start 368.883184 -214.344758)
		(end 368.883184 -213.978236)
		(width 0.0889)
		(layer "F.Cu")
		(net "UPI_CPU1_CPU0_P0P1_DP<15>")
	)
	(segment
		(start 368.508534 -214.344758)
		(end 368.663728 -214.613744)
		(width 0.0889)
		(layer "F.Cu")
		(net "UPI_CPU1_CPU0_P0P1_DP<15>")
	)
	(segment
		(start 364.62081 -186.299856)
		(end 364.62081 -184.094628)
		(width 0.13208)
		(layer "F.Cu")
		(net "UPI_CPU1_CPU0_P0P1_DP<15>")
	)
	(segment
		(start 368.781584 -213.673436)
		(end 368.883184 -213.571836)
		(width 0.0889)
		(layer "F.Cu")
		(net "UPI_CPU1_CPU0_P0P1_DP<15>")
	)
	(segment
		(start 360.495088 -205.79842)
		(end 360.495088 -205.261464)
		(width 0.0889)
		(layer "F.Cu")
		(net "UPI_CPU1_CPU0_P0P1_DP<15>")
	)
	(segment
		(start 364.62081 -184.094628)
		(end 364.106206 -182.852314)
		(width 0.13208)
		(layer "F.Cu")
		(net "UPI_CPU1_CPU0_P0P1_DP<15>")
	)
	(segment
		(start 368.883184 -213.978236)
		(end 368.781584 -213.876636)
		(width 0.0889)
		(layer "F.Cu")
		(net "UPI_CPU1_CPU0_P0P1_DP<15>")
	)
	(segment
		(start 368.663728 -214.613744)
		(end 368.744754 -214.635334)
		(width 0.0889)
		(layer "F.Cu")
		(net "UPI_CPU1_CPU0_P0P1_DP<15>")
	)
	(segment
		(start 360.460798 -199.92086)
		(end 360.465624 -199.916034)
		(width 0.13208)
		(layer "F.Cu")
		(net "UPI_CPU1_CPU0_P0P1_DP<15>")
	)
	(segment
		(start 361.461558 -194.908932)
		(end 364.24489 -188.18987)
		(width 0.13208)
		(layer "F.Cu")
		(net "UPI_CPU1_CPU0_P0P1_DP<15>")
	)
	(segment
		(start 352.98507 -172.732954)
		(end 353.095814 -172.54093)
		(width 0.13208)
		(layer "F.Cu")
		(net "UPI_CPU1_CPU0_P0P1_DP<15>")
	)
	(segment
		(start 360.495088 -205.261464)
		(end 360.460798 -205.227174)
		(width 0.0889)
		(layer "F.Cu")
		(net "UPI_CPU1_CPU0_P0P1_DP<15>")
	)
	(segment
		(start 368.883184 -213.419436)
		(end 368.784124 -213.320376)
		(width 0.0889)
		(layer "F.Cu")
		(net "UPI_CPU1_CPU0_P0P1_DP<15>")
	)
	(segment
		(start 353.097846 -172.53712)
		(end 352.950272 -171.985432)
		(width 0.13208)
		(layer "F.Cu")
		(net "UPI_CPU1_CPU0_P0P1_DP<15>")
	)
	(segment
		(start 360.465624 -199.916034)
		(end 361.461558 -194.908932)
		(width 0.13208)
		(layer "F.Cu")
		(net "UPI_CPU1_CPU0_P0P1_DP<15>")
	)
	(segment
		(start 353.032314 -173.09338)
		(end 352.98507 -172.732954)
		(width 0.13208)
		(layer "F.Cu")
		(net "UPI_CPU1_CPU0_P0P1_DP<15>")
	)
	(segment
		(start 365.189008 -209.14614)
		(end 362.890308 -208.193894)
		(width 0.0889)
		(layer "F.Cu")
		(net "UPI_CPU1_CPU0_P0P1_DP<15>")
	)
	(segment
		(start 353.095814 -172.54093)
		(end 353.095814 -172.540676)
		(width 0.13208)
		(layer "F.Cu")
		(net "UPI_CPU1_CPU0_P0P1_DP<15>")
	)
	(segment
		(start 364.106206 -182.852314)
		(end 356.625398 -175.371506)
		(width 0.13208)
		(layer "F.Cu")
		(net "UPI_CPU1_CPU0_P0P1_DP<15>")
	)
	(segment
		(start 360.460798 -205.227174)
		(end 360.460798 -205.205076)
		(width 0.0889)
		(layer "F.Cu")
		(net "UPI_CPU1_CPU0_P0P1_DP<15>")
	)
	(segment
		(start 356.625398 -175.371506)
		(end 354.498402 -173.95063)
		(width 0.13208)
		(layer "F.Cu")
		(net "UPI_CPU1_CPU0_P0P1_DP<15>")
	)
	(segment
		(start 354.498402 -173.95063)
		(end 353.459542 -173.520608)
		(width 0.13208)
		(layer "F.Cu")
		(net "UPI_CPU1_CPU0_P0P1_DP<15>")
	)
	(segment
		(start 353.097084 -172.53839)
		(end 353.097846 -172.53712)
		(width 0.13208)
		(layer "F.Cu")
		(net "UPI_CPU1_CPU0_P0P1_DP<15>")
	)
	(segment
		(start 368.883184 -212.840316)
		(end 365.189008 -209.14614)
		(width 0.0889)
		(layer "F.Cu")
		(net "UPI_CPU1_CPU0_P0P1_DP<15>")
	)
	(segment
		(start 360.460798 -205.205076)
		(end 360.460798 -199.92086)
		(width 0.13208)
		(layer "F.Cu")
		(net "UPI_CPU1_CPU0_P0P1_DP<15>")
	)
	(segment
		(start 368.781584 -213.876636)
		(end 368.781584 -213.673436)
		(width 0.0889)
		(layer "F.Cu")
		(net "UPI_CPU1_CPU0_P0P1_DP<15>")
	)
	(segment
		(start 353.096576 -172.539406)
		(end 353.097084 -172.53839)
		(width 0.13208)
		(layer "F.Cu")
		(net "UPI_CPU1_CPU0_P0P1_DP<15>")
	)
	(segment
		(start 102.712266 -215.972644)
		(end 102.712266 -215.436958)
		(width 0.13208)
		(layer "F.Cu")
		(net "UPI_CPU1_CPU0_P0P1_DP<15>")
	)
	(arc
		(start 368.744754 -214.635334)
		(mid 368.846775 -214.505672)
		(end 368.883184 -214.344758)
		(width 0.0889)
		(layer "F.Cu")
		(net "UPI_CPU1_CPU0_P0P1_DP<15>")
	)
	(segment
		(start 339.51672 -163.67125)
		(end 339.688424 -163.472114)
		(width 0.14732)
		(layer "In6.Cu")
		(net "UPI_CPU1_CPU0_P0P1_DP<15>")
	)
	(segment
		(start 170.416982 -150.184358)
		(end 172.245274 -151.089868)
		(width 0.14732)
		(layer "In6.Cu")
		(net "UPI_CPU1_CPU0_P0P1_DP<15>")
	)
	(segment
		(start 326.582278 -152.951942)
		(end 328.975466 -154.782266)
		(width 0.14732)
		(layer "In6.Cu")
		(net "UPI_CPU1_CPU0_P0P1_DP<15>")
	)
	(segment
		(start 131.531614 -171.20108)
		(end 164.765482 -150.72106)
		(width 0.14732)
		(layer "In6.Cu")
		(net "UPI_CPU1_CPU0_P0P1_DP<15>")
	)
	(segment
		(start 174.022004 -151.969978)
		(end 191.539876 -161.135568)
		(width 0.14732)
		(layer "In6.Cu")
		(net "UPI_CPU1_CPU0_P0P1_DP<15>")
	)
	(segment
		(start 279.440386 -161.145728)
		(end 322.056506 -152.217628)
		(width 0.14732)
		(layer "In6.Cu")
		(net "UPI_CPU1_CPU0_P0P1_DP<15>")
	)
	(segment
		(start 337.553554 -162.17392)
		(end 337.761072 -162.158426)
		(width 0.14732)
		(layer "In6.Cu")
		(net "UPI_CPU1_CPU0_P0P1_DP<15>")
	)
	(segment
		(start 338.366862 -161.927032)
		(end 338.986368 -162.46094)
		(width 0.14732)
		(layer "In6.Cu")
		(net "UPI_CPU1_CPU0_P0P1_DP<15>")
	)
	(segment
		(start 337.932776 -161.95929)
		(end 338.366862 -161.927032)
		(width 0.14732)
		(layer "In6.Cu")
		(net "UPI_CPU1_CPU0_P0P1_DP<15>")
	)
	(segment
		(start 352.99142 -172.7073)
		(end 353.09556 -172.52696)
		(width 0.14732)
		(layer "In6.Cu")
		(net "UPI_CPU1_CPU0_P0P1_DP<15>")
	)
	(segment
		(start 340.742016 -163.973764)
		(end 340.774274 -164.40785)
		(width 0.14732)
		(layer "In6.Cu")
		(net "UPI_CPU1_CPU0_P0P1_DP<15>")
	)
	(segment
		(start 339.309202 -163.686744)
		(end 339.51672 -163.67125)
		(width 0.14732)
		(layer "In6.Cu")
		(net "UPI_CPU1_CPU0_P0P1_DP<15>")
	)
	(segment
		(start 352.48088 -172.814488)
		(end 352.884232 -172.814488)
		(width 0.14732)
		(layer "In6.Cu")
		(net "UPI_CPU1_CPU0_P0P1_DP<15>")
	)
	(segment
		(start 276.749256 -161.145728)
		(end 279.440386 -161.145728)
		(width 0.14732)
		(layer "In6.Cu")
		(net "UPI_CPU1_CPU0_P0P1_DP<15>")
	)
	(segment
		(start 166.591488 -150.083266)
		(end 170.416982 -150.184358)
		(width 0.14732)
		(layer "In6.Cu")
		(net "UPI_CPU1_CPU0_P0P1_DP<15>")
	)
	(segment
		(start 339.018626 -162.895026)
		(end 338.846922 -163.094162)
		(width 0.14732)
		(layer "In6.Cu")
		(net "UPI_CPU1_CPU0_P0P1_DP<15>")
	)
	(segment
		(start 164.765482 -150.72106)
		(end 166.591488 -150.083266)
		(width 0.14732)
		(layer "In6.Cu")
		(net "UPI_CPU1_CPU0_P0P1_DP<15>")
	)
	(segment
		(start 191.539876 -161.135568)
		(end 194.502278 -161.135568)
		(width 0.14732)
		(layer "In6.Cu")
		(net "UPI_CPU1_CPU0_P0P1_DP<15>")
	)
	(segment
		(start 103.04526 -211.306156)
		(end 109.25048 -194.270376)
		(width 0.14732)
		(layer "In6.Cu")
		(net "UPI_CPU1_CPU0_P0P1_DP<15>")
	)
	(segment
		(start 238.241586 -151.254968)
		(end 276.749256 -161.145728)
		(width 0.14732)
		(layer "In6.Cu")
		(net "UPI_CPU1_CPU0_P0P1_DP<15>")
	)
	(segment
		(start 323.660008 -152.217628)
		(end 326.582278 -152.951942)
		(width 0.14732)
		(layer "In6.Cu")
		(net "UPI_CPU1_CPU0_P0P1_DP<15>")
	)
	(segment
		(start 340.774274 -164.40785)
		(end 340.60257 -164.606986)
		(width 0.14732)
		(layer "In6.Cu")
		(net "UPI_CPU1_CPU0_P0P1_DP<15>")
	)
	(segment
		(start 348.251018 -171.391326)
		(end 351.25152 -172.118528)
		(width 0.14732)
		(layer "In6.Cu")
		(net "UPI_CPU1_CPU0_P0P1_DP<15>")
	)
	(segment
		(start 339.688424 -163.472114)
		(end 340.12251 -163.439856)
		(width 0.14732)
		(layer "In6.Cu")
		(net "UPI_CPU1_CPU0_P0P1_DP<15>")
	)
	(segment
		(start 109.25048 -194.270376)
		(end 115.903248 -185.895996)
		(width 0.14732)
		(layer "In6.Cu")
		(net "UPI_CPU1_CPU0_P0P1_DP<15>")
	)
	(segment
		(start 115.903248 -185.895996)
		(end 131.531614 -171.20108)
		(width 0.14732)
		(layer "In6.Cu")
		(net "UPI_CPU1_CPU0_P0P1_DP<15>")
	)
	(segment
		(start 340.60257 -164.606986)
		(end 340.618064 -164.814504)
		(width 0.14732)
		(layer "In6.Cu")
		(net "UPI_CPU1_CPU0_P0P1_DP<15>")
	)
	(segment
		(start 351.25152 -172.118528)
		(end 352.127566 -172.684948)
		(width 0.14732)
		(layer "In6.Cu")
		(net "UPI_CPU1_CPU0_P0P1_DP<15>")
	)
	(segment
		(start 102.868476 -215.165686)
		(end 102.844346 -215.076532)
		(width 0.0889)
		(layer "In6.Cu")
		(net "UPI_CPU1_CPU0_P0P1_DP<15>")
	)
	(segment
		(start 172.245274 -151.089868)
		(end 172.245274 -151.090122)
		(width 0.14732)
		(layer "In6.Cu")
		(net "UPI_CPU1_CPU0_P0P1_DP<15>")
	)
	(segment
		(start 103.04526 -211.77123)
		(end 103.04526 -211.306156)
		(width 0.14732)
		(layer "In6.Cu")
		(net "UPI_CPU1_CPU0_P0P1_DP<15>")
	)
	(segment
		(start 338.862416 -163.30168)
		(end 339.309202 -163.686744)
		(width 0.14732)
		(layer "In6.Cu")
		(net "UPI_CPU1_CPU0_P0P1_DP<15>")
	)
	(segment
		(start 103.086916 -213.8934)
		(end 103.08717 -213.892892)
		(width 0.0889)
		(layer "In6.Cu")
		(net "UPI_CPU1_CPU0_P0P1_DP<15>")
	)
	(segment
		(start 102.712012 -215.436704)
		(end 102.868476 -215.165686)
		(width 0.0889)
		(layer "In6.Cu")
		(net "UPI_CPU1_CPU0_P0P1_DP<15>")
	)
	(segment
		(start 328.975466 -154.782266)
		(end 337.553554 -162.17392)
		(width 0.14732)
		(layer "In6.Cu")
		(net "UPI_CPU1_CPU0_P0P1_DP<15>")
	)
	(segment
		(start 322.056506 -152.217628)
		(end 323.660008 -152.217628)
		(width 0.14732)
		(layer "In6.Cu")
		(net "UPI_CPU1_CPU0_P0P1_DP<15>")
	)
	(segment
		(start 102.616508 -214.636858)
		(end 102.616508 -214.425784)
		(width 0.0889)
		(layer "In6.Cu")
		(net "UPI_CPU1_CPU0_P0P1_DP<15>")
	)
	(segment
		(start 340.12251 -163.439856)
		(end 340.742016 -163.973764)
		(width 0.14732)
		(layer "In6.Cu")
		(net "UPI_CPU1_CPU0_P0P1_DP<15>")
	)
	(segment
		(start 338.846922 -163.094162)
		(end 338.862416 -163.30168)
		(width 0.14732)
		(layer "In6.Cu")
		(net "UPI_CPU1_CPU0_P0P1_DP<15>")
	)
	(segment
		(start 352.884232 -172.814488)
		(end 352.99142 -172.7073)
		(width 0.14732)
		(layer "In6.Cu")
		(net "UPI_CPU1_CPU0_P0P1_DP<15>")
	)
	(segment
		(start 103.08717 -211.835238)
		(end 103.04526 -211.793328)
		(width 0.0889)
		(layer "In6.Cu")
		(net "UPI_CPU1_CPU0_P0P1_DP<15>")
	)
	(segment
		(start 338.986368 -162.46094)
		(end 339.018626 -162.895026)
		(width 0.14732)
		(layer "In6.Cu")
		(net "UPI_CPU1_CPU0_P0P1_DP<15>")
	)
	(segment
		(start 103.04526 -211.793328)
		(end 103.04526 -211.77123)
		(width 0.0889)
		(layer "In6.Cu")
		(net "UPI_CPU1_CPU0_P0P1_DP<15>")
	)
	(segment
		(start 233.967528 -151.254968)
		(end 238.241586 -151.254968)
		(width 0.14732)
		(layer "In6.Cu")
		(net "UPI_CPU1_CPU0_P0P1_DP<15>")
	)
	(segment
		(start 337.761072 -162.158426)
		(end 337.932776 -161.95929)
		(width 0.14732)
		(layer "In6.Cu")
		(net "UPI_CPU1_CPU0_P0P1_DP<15>")
	)
	(segment
		(start 196.731636 -160.854136)
		(end 233.967528 -151.254968)
		(width 0.14732)
		(layer "In6.Cu")
		(net "UPI_CPU1_CPU0_P0P1_DP<15>")
	)
	(segment
		(start 340.618064 -164.814504)
		(end 348.251018 -171.391326)
		(width 0.14732)
		(layer "In6.Cu")
		(net "UPI_CPU1_CPU0_P0P1_DP<15>")
	)
	(segment
		(start 103.08717 -213.892892)
		(end 103.08717 -211.835238)
		(width 0.0889)
		(layer "In6.Cu")
		(net "UPI_CPU1_CPU0_P0P1_DP<15>")
	)
	(segment
		(start 172.245274 -151.090122)
		(end 174.022004 -151.969978)
		(width 0.14732)
		(layer "In6.Cu")
		(net "UPI_CPU1_CPU0_P0P1_DP<15>")
	)
	(segment
		(start 353.09556 -172.52696)
		(end 352.950272 -171.985432)
		(width 0.14732)
		(layer "In6.Cu")
		(net "UPI_CPU1_CPU0_P0P1_DP<15>")
	)
	(segment
		(start 194.502278 -161.135568)
		(end 196.731636 -160.854136)
		(width 0.14732)
		(layer "In6.Cu")
		(net "UPI_CPU1_CPU0_P0P1_DP<15>")
	)
	(segment
		(start 352.127566 -172.684948)
		(end 352.48088 -172.814488)
		(width 0.14732)
		(layer "In6.Cu")
		(net "UPI_CPU1_CPU0_P0P1_DP<15>")
	)
	(arc
		(start 102.616508 -214.425784)
		(mid 102.727948 -214.232389)
		(end 102.902512 -214.093298)
		(width 0.0889)
		(layer "In6.Cu")
		(net "UPI_CPU1_CPU0_P0P1_DP<15>")
	)
	(arc
		(start 102.902512 -214.093298)
		(mid 103.011908 -214.009201)
		(end 103.086916 -213.8934)
		(width 0.0889)
		(layer "In6.Cu")
		(net "UPI_CPU1_CPU0_P0P1_DP<15>")
	)
	(arc
		(start 102.844346 -215.076532)
		(mid 102.835774 -215.070009)
		(end 102.827328 -215.063324)
		(width 0.0889)
		(layer "In6.Cu")
		(net "UPI_CPU1_CPU0_P0P1_DP<15>")
	)
	(arc
		(start 102.827328 -215.063324)
		(mid 102.674897 -214.873342)
		(end 102.616508 -214.636858)
		(width 0.0889)
		(layer "In6.Cu")
		(net "UPI_CPU1_CPU0_P0P1_DP<15>")
	)
	(segment
		(start 365.938816 -186.370976)
		(end 365.938816 -183.6801)
		(width 0.13208)
		(layer "F.Cu")
		(net "UPI_CPU1_CPU0_P0P1_DP<14>")
	)
	(segment
		(start 365.294926 -182.12562)
		(end 357.86695 -174.697644)
		(width 0.13208)
		(layer "F.Cu")
		(net "UPI_CPU1_CPU0_P0P1_DP<14>")
	)
	(segment
		(start 369.604544 -212.48497)
		(end 365.72825 -208.608676)
		(width 0.0889)
		(layer "F.Cu")
		(net "UPI_CPU1_CPU0_P0P1_DP<14>")
	)
	(segment
		(start 369.448334 -215.972644)
		(end 369.45316 -215.964262)
		(width 0.0889)
		(layer "F.Cu")
		(net "UPI_CPU1_CPU0_P0P1_DP<14>")
	)
	(segment
		(start 365.938816 -183.6801)
		(end 365.294926 -182.12562)
		(width 0.13208)
		(layer "F.Cu")
		(net "UPI_CPU1_CPU0_P0P1_DP<14>")
	)
	(segment
		(start 355.16439 -172.479462)
		(end 353.923854 -171.460922)
		(width 0.13208)
		(layer "F.Cu")
		(net "UPI_CPU1_CPU0_P0P1_DP<14>")
	)
	(segment
		(start 351.93478 -171.224448)
		(end 350.300544 -171.224448)
		(width 0.13208)
		(layer "F.Cu")
		(net "UPI_CPU1_CPU0_P0P1_DP<14>")
	)
	(segment
		(start 369.35283 -215.172798)
		(end 369.35283 -215.158066)
		(width 0.0889)
		(layer "F.Cu")
		(net "UPI_CPU1_CPU0_P0P1_DP<14>")
	)
	(segment
		(start 369.647978 -214.661496)
		(end 369.648232 -214.661496)
		(width 0.0889)
		(layer "F.Cu")
		(net "UPI_CPU1_CPU0_P0P1_DP<14>")
	)
	(segment
		(start 352.711258 -171.09313)
		(end 352.066098 -171.09313)
		(width 0.13208)
		(layer "F.Cu")
		(net "UPI_CPU1_CPU0_P0P1_DP<14>")
	)
	(segment
		(start 361.768898 -205.205076)
		(end 361.768898 -200.081134)
		(width 0.13208)
		(layer "F.Cu")
		(net "UPI_CPU1_CPU0_P0P1_DP<14>")
	)
	(segment
		(start 365.72825 -208.608676)
		(end 363.942122 -207.868774)
		(width 0.0889)
		(layer "F.Cu")
		(net "UPI_CPU1_CPU0_P0P1_DP<14>")
	)
	(segment
		(start 369.822984 -214.345012)
		(end 369.822984 -213.53272)
		(width 0.0889)
		(layer "F.Cu")
		(net "UPI_CPU1_CPU0_P0P1_DP<14>")
	)
	(segment
		(start 369.604544 -212.924898)
		(end 369.604544 -212.48497)
		(width 0.0889)
		(layer "F.Cu")
		(net "UPI_CPU1_CPU0_P0P1_DP<14>")
	)
	(segment
		(start 361.768898 -205.227174)
		(end 361.768898 -205.205076)
		(width 0.0889)
		(layer "F.Cu")
		(net "UPI_CPU1_CPU0_P0P1_DP<14>")
	)
	(segment
		(start 353.923854 -171.460922)
		(end 352.711258 -171.09313)
		(width 0.13208)
		(layer "F.Cu")
		(net "UPI_CPU1_CPU0_P0P1_DP<14>")
	)
	(segment
		(start 357.86695 -174.697644)
		(end 355.6635 -172.88891)
		(width 0.13208)
		(layer "F.Cu")
		(net "UPI_CPU1_CPU0_P0P1_DP<14>")
	)
	(segment
		(start 361.768898 -200.081134)
		(end 361.773724 -200.076308)
		(width 0.13208)
		(layer "F.Cu")
		(net "UPI_CPU1_CPU0_P0P1_DP<14>")
	)
	(segment
		(start 369.603528 -215.703658)
		(end 369.578382 -215.610694)
		(width 0.0889)
		(layer "F.Cu")
		(net "UPI_CPU1_CPU0_P0P1_DP<14>")
	)
	(segment
		(start 365.501936 -188.56706)
		(end 365.938816 -186.370976)
		(width 0.13208)
		(layer "F.Cu")
		(net "UPI_CPU1_CPU0_P0P1_DP<14>")
	)
	(segment
		(start 355.181662 -172.654468)
		(end 355.16439 -172.479462)
		(width 0.13208)
		(layer "F.Cu")
		(net "UPI_CPU1_CPU0_P0P1_DP<14>")
	)
	(segment
		(start 369.604798 -212.925152)
		(end 369.604544 -212.924898)
		(width 0.0889)
		(layer "F.Cu")
		(net "UPI_CPU1_CPU0_P0P1_DP<14>")
	)
	(segment
		(start 102.242112 -214.622888)
		(end 102.241858 -214.622634)
		(width 0.13208)
		(layer "F.Cu")
		(net "UPI_CPU1_CPU0_P0P1_DP<14>")
	)
	(segment
		(start 361.803188 -205.729586)
		(end 361.803188 -205.261464)
		(width 0.0889)
		(layer "F.Cu")
		(net "UPI_CPU1_CPU0_P0P1_DP<14>")
	)
	(segment
		(start 102.242112 -215.158574)
		(end 102.242112 -214.622888)
		(width 0.13208)
		(layer "F.Cu")
		(net "UPI_CPU1_CPU0_P0P1_DP<14>")
	)
	(segment
		(start 355.6635 -172.88891)
		(end 355.48824 -172.906182)
		(width 0.13208)
		(layer "F.Cu")
		(net "UPI_CPU1_CPU0_P0P1_DP<14>")
	)
	(segment
		(start 369.822984 -213.53272)
		(end 369.604798 -213.314534)
		(width 0.0889)
		(layer "F.Cu")
		(net "UPI_CPU1_CPU0_P0P1_DP<14>")
	)
	(segment
		(start 349.717868 -170.763438)
		(end 349.165672 -170.613832)
		(width 0.13208)
		(layer "F.Cu")
		(net "UPI_CPU1_CPU0_P0P1_DP<14>")
	)
	(segment
		(start 361.773724 -200.076308)
		(end 362.73359 -195.250308)
		(width 0.13208)
		(layer "F.Cu")
		(net "UPI_CPU1_CPU0_P0P1_DP<14>")
	)
	(segment
		(start 350.300544 -171.224448)
		(end 349.825564 -170.949112)
		(width 0.13208)
		(layer "F.Cu")
		(net "UPI_CPU1_CPU0_P0P1_DP<14>")
	)
	(segment
		(start 363.942122 -207.868774)
		(end 361.803188 -205.729586)
		(width 0.0889)
		(layer "F.Cu")
		(net "UPI_CPU1_CPU0_P0P1_DP<14>")
	)
	(segment
		(start 352.066098 -171.09313)
		(end 351.93478 -171.224448)
		(width 0.13208)
		(layer "F.Cu")
		(net "UPI_CPU1_CPU0_P0P1_DP<14>")
	)
	(segment
		(start 369.604798 -213.314534)
		(end 369.604798 -212.925152)
		(width 0.0889)
		(layer "F.Cu")
		(net "UPI_CPU1_CPU0_P0P1_DP<14>")
	)
	(segment
		(start 369.45316 -215.964262)
		(end 369.603528 -215.703658)
		(width 0.0889)
		(layer "F.Cu")
		(net "UPI_CPU1_CPU0_P0P1_DP<14>")
	)
	(segment
		(start 349.825564 -170.949112)
		(end 349.717868 -170.763438)
		(width 0.13208)
		(layer "F.Cu")
		(net "UPI_CPU1_CPU0_P0P1_DP<14>")
	)
	(segment
		(start 355.48824 -172.906182)
		(end 355.181662 -172.654468)
		(width 0.13208)
		(layer "F.Cu")
		(net "UPI_CPU1_CPU0_P0P1_DP<14>")
	)
	(segment
		(start 361.803188 -205.261464)
		(end 361.768898 -205.227174)
		(width 0.0889)
		(layer "F.Cu")
		(net "UPI_CPU1_CPU0_P0P1_DP<14>")
	)
	(segment
		(start 362.73359 -195.250308)
		(end 365.501936 -188.56706)
		(width 0.13208)
		(layer "F.Cu")
		(net "UPI_CPU1_CPU0_P0P1_DP<14>")
	)
	(arc
		(start 369.648232 -214.661496)
		(mid 369.776355 -214.525737)
		(end 369.822984 -214.345012)
		(width 0.0889)
		(layer "F.Cu")
		(net "UPI_CPU1_CPU0_P0P1_DP<14>")
	)
	(arc
		(start 369.35283 -215.158066)
		(mid 369.432178 -214.869221)
		(end 369.647978 -214.661496)
		(width 0.0889)
		(layer "F.Cu")
		(net "UPI_CPU1_CPU0_P0P1_DP<14>")
	)
	(arc
		(start 369.561364 -215.597232)
		(mid 369.410586 -215.407867)
		(end 369.35283 -215.172798)
		(width 0.0889)
		(layer "F.Cu")
		(net "UPI_CPU1_CPU0_P0P1_DP<14>")
	)
	(arc
		(start 369.578382 -215.610694)
		(mid 369.569808 -215.604045)
		(end 369.561364 -215.597232)
		(width 0.0889)
		(layer "F.Cu")
		(net "UPI_CPU1_CPU0_P0P1_DP<14>")
	)
	(segment
		(start 349.306134 -170.075098)
		(end 349.308166 -170.08221)
		(width 0.14732)
		(layer "In6.Cu")
		(net "UPI_CPU1_CPU0_P0P1_DP<14>")
	)
	(segment
		(start 166.69258 -149.420326)
		(end 170.581066 -149.523196)
		(width 0.14732)
		(layer "In6.Cu")
		(net "UPI_CPU1_CPU0_P0P1_DP<14>")
	)
	(segment
		(start 323.73316 -151.628348)
		(end 326.79513 -152.39746)
		(width 0.14732)
		(layer "In6.Cu")
		(net "UPI_CPU1_CPU0_P0P1_DP<14>")
	)
	(segment
		(start 196.620638 -160.274)
		(end 233.891074 -150.665688)
		(width 0.14732)
		(layer "In6.Cu")
		(net "UPI_CPU1_CPU0_P0P1_DP<14>")
	)
	(segment
		(start 191.848486 -160.546288)
		(end 194.465194 -160.546288)
		(width 0.14732)
		(layer "In6.Cu")
		(net "UPI_CPU1_CPU0_P0P1_DP<14>")
	)
	(segment
		(start 109.919262 -192.321942)
		(end 110.090712 -192.302384)
		(width 0.14732)
		(layer "In6.Cu")
		(net "UPI_CPU1_CPU0_P0P1_DP<14>")
	)
	(segment
		(start 111.057944 -191.084708)
		(end 111.038386 -190.913258)
		(width 0.14732)
		(layer "In6.Cu")
		(net "UPI_CPU1_CPU0_P0P1_DP<14>")
	)
	(segment
		(start 112.448848 -189.33414)
		(end 112.429036 -189.16269)
		(width 0.14732)
		(layer "In6.Cu")
		(net "UPI_CPU1_CPU0_P0P1_DP<14>")
	)
	(segment
		(start 345.48826 -167.954452)
		(end 347.449394 -169.602404)
		(width 0.14732)
		(layer "In6.Cu")
		(net "UPI_CPU1_CPU0_P0P1_DP<14>")
	)
	(segment
		(start 347.449394 -169.602404)
		(end 349.191326 -169.96029)
		(width 0.14732)
		(layer "In6.Cu")
		(net "UPI_CPU1_CPU0_P0P1_DP<14>")
	)
	(segment
		(start 131.229608 -170.71848)
		(end 164.610796 -150.147528)
		(width 0.14732)
		(layer "In6.Cu")
		(net "UPI_CPU1_CPU0_P0P1_DP<14>")
	)
	(segment
		(start 174.32401 -151.376888)
		(end 191.848486 -160.546288)
		(width 0.14732)
		(layer "In6.Cu")
		(net "UPI_CPU1_CPU0_P0P1_DP<14>")
	)
	(segment
		(start 111.309912 -190.571374)
		(end 111.481362 -190.551816)
		(width 0.14732)
		(layer "In6.Cu")
		(net "UPI_CPU1_CPU0_P0P1_DP<14>")
	)
	(segment
		(start 113.567464 -187.925964)
		(end 113.839498 -187.583572)
		(width 0.14732)
		(layer "In6.Cu")
		(net "UPI_CPU1_CPU0_P0P1_DP<14>")
	)
	(segment
		(start 109.395514 -193.177414)
		(end 109.667548 -192.835276)
		(width 0.14732)
		(layer "In6.Cu")
		(net "UPI_CPU1_CPU0_P0P1_DP<14>")
	)
	(segment
		(start 326.79513 -152.39746)
		(end 339.553804 -161.779712)
		(width 0.14732)
		(layer "In6.Cu")
		(net "UPI_CPU1_CPU0_P0P1_DP<14>")
	)
	(segment
		(start 111.753396 -190.209424)
		(end 111.733838 -190.037974)
		(width 0.14732)
		(layer "In6.Cu")
		(net "UPI_CPU1_CPU0_P0P1_DP<14>")
	)
	(segment
		(start 102.379526 -211.77123)
		(end 102.379526 -211.38261)
		(width 0.14732)
		(layer "In6.Cu")
		(net "UPI_CPU1_CPU0_P0P1_DP<14>")
	)
	(segment
		(start 102.337362 -213.93023)
		(end 102.337362 -211.82457)
		(width 0.0889)
		(layer "In6.Cu")
		(net "UPI_CPU1_CPU0_P0P1_DP<14>")
	)
	(segment
		(start 109.647736 -192.663826)
		(end 109.919262 -192.321942)
		(width 0.14732)
		(layer "In6.Cu")
		(net "UPI_CPU1_CPU0_P0P1_DP<14>")
	)
	(segment
		(start 344.859356 -167.404542)
		(end 345.48826 -167.954452)
		(width 0.14732)
		(layer "In6.Cu")
		(net "UPI_CPU1_CPU0_P0P1_DP<14>")
	)
	(segment
		(start 108.952538 -193.53911)
		(end 109.224064 -193.197226)
		(width 0.14732)
		(layer "In6.Cu")
		(net "UPI_CPU1_CPU0_P0P1_DP<14>")
	)
	(segment
		(start 233.891074 -150.665688)
		(end 238.316262 -150.665688)
		(width 0.14732)
		(layer "In6.Cu")
		(net "UPI_CPU1_CPU0_P0P1_DP<14>")
	)
	(segment
		(start 276.962362 -160.592008)
		(end 279.2095 -160.592008)
		(width 0.14732)
		(layer "In6.Cu")
		(net "UPI_CPU1_CPU0_P0P1_DP<14>")
	)
	(segment
		(start 349.191326 -169.96029)
		(end 349.306134 -170.075098)
		(width 0.14732)
		(layer "In6.Cu")
		(net "UPI_CPU1_CPU0_P0P1_DP<14>")
	)
	(segment
		(start 170.581066 -149.523196)
		(end 174.32401 -151.376888)
		(width 0.14732)
		(layer "In6.Cu")
		(net "UPI_CPU1_CPU0_P0P1_DP<14>")
	)
	(segment
		(start 110.362746 -191.959992)
		(end 110.342934 -191.788542)
		(width 0.14732)
		(layer "In6.Cu")
		(net "UPI_CPU1_CPU0_P0P1_DP<14>")
	)
	(segment
		(start 110.090712 -192.302384)
		(end 110.362746 -191.959992)
		(width 0.14732)
		(layer "In6.Cu")
		(net "UPI_CPU1_CPU0_P0P1_DP<14>")
	)
	(segment
		(start 109.667548 -192.835276)
		(end 109.647736 -192.663826)
		(width 0.14732)
		(layer "In6.Cu")
		(net "UPI_CPU1_CPU0_P0P1_DP<14>")
	)
	(segment
		(start 102.337616 -213.929468)
		(end 102.337362 -213.93023)
		(width 0.0889)
		(layer "In6.Cu")
		(net "UPI_CPU1_CPU0_P0P1_DP<14>")
	)
	(segment
		(start 164.610796 -150.147528)
		(end 166.69258 -149.420326)
		(width 0.14732)
		(layer "In6.Cu")
		(net "UPI_CPU1_CPU0_P0P1_DP<14>")
	)
	(segment
		(start 112.872012 -188.801248)
		(end 113.144046 -188.458856)
		(width 0.14732)
		(layer "In6.Cu")
		(net "UPI_CPU1_CPU0_P0P1_DP<14>")
	)
	(segment
		(start 342.150192 -164.0078)
		(end 344.859356 -167.404542)
		(width 0.14732)
		(layer "In6.Cu")
		(net "UPI_CPU1_CPU0_P0P1_DP<14>")
	)
	(segment
		(start 102.337362 -211.82457)
		(end 102.379526 -211.782406)
		(width 0.0889)
		(layer "In6.Cu")
		(net "UPI_CPU1_CPU0_P0P1_DP<14>")
	)
	(segment
		(start 109.224064 -193.197226)
		(end 109.395514 -193.177414)
		(width 0.14732)
		(layer "In6.Cu")
		(net "UPI_CPU1_CPU0_P0P1_DP<14>")
	)
	(segment
		(start 111.481362 -190.551816)
		(end 111.753396 -190.209424)
		(width 0.14732)
		(layer "In6.Cu")
		(net "UPI_CPU1_CPU0_P0P1_DP<14>")
	)
	(segment
		(start 110.78591 -191.4271)
		(end 111.057944 -191.084708)
		(width 0.14732)
		(layer "In6.Cu")
		(net "UPI_CPU1_CPU0_P0P1_DP<14>")
	)
	(segment
		(start 102.379526 -211.38261)
		(end 108.816394 -193.710052)
		(width 0.14732)
		(layer "In6.Cu")
		(net "UPI_CPU1_CPU0_P0P1_DP<14>")
	)
	(segment
		(start 113.839498 -187.583572)
		(end 113.81994 -187.412122)
		(width 0.14732)
		(layer "In6.Cu")
		(net "UPI_CPU1_CPU0_P0P1_DP<14>")
	)
	(segment
		(start 112.176814 -189.676532)
		(end 112.448848 -189.33414)
		(width 0.14732)
		(layer "In6.Cu")
		(net "UPI_CPU1_CPU0_P0P1_DP<14>")
	)
	(segment
		(start 113.124488 -188.287406)
		(end 113.396014 -187.945522)
		(width 0.14732)
		(layer "In6.Cu")
		(net "UPI_CPU1_CPU0_P0P1_DP<14>")
	)
	(segment
		(start 108.816394 -193.710052)
		(end 108.952538 -193.53911)
		(width 0.14732)
		(layer "In6.Cu")
		(net "UPI_CPU1_CPU0_P0P1_DP<14>")
	)
	(segment
		(start 113.396014 -187.945522)
		(end 113.567464 -187.925964)
		(width 0.14732)
		(layer "In6.Cu")
		(net "UPI_CPU1_CPU0_P0P1_DP<14>")
	)
	(segment
		(start 102.241858 -214.622634)
		(end 102.083108 -214.321644)
		(width 0.0889)
		(layer "In6.Cu")
		(net "UPI_CPU1_CPU0_P0P1_DP<14>")
	)
	(segment
		(start 194.465194 -160.546288)
		(end 196.620638 -160.274)
		(width 0.14732)
		(layer "In6.Cu")
		(net "UPI_CPU1_CPU0_P0P1_DP<14>")
	)
	(segment
		(start 102.379526 -211.782406)
		(end 102.379526 -211.77123)
		(width 0.0889)
		(layer "In6.Cu")
		(net "UPI_CPU1_CPU0_P0P1_DP<14>")
	)
	(segment
		(start 321.995292 -151.628348)
		(end 323.73316 -151.628348)
		(width 0.14732)
		(layer "In6.Cu")
		(net "UPI_CPU1_CPU0_P0P1_DP<14>")
	)
	(segment
		(start 238.316262 -150.665688)
		(end 276.962362 -160.592008)
		(width 0.14732)
		(layer "In6.Cu")
		(net "UPI_CPU1_CPU0_P0P1_DP<14>")
	)
	(segment
		(start 112.429036 -189.16269)
		(end 112.700562 -188.820806)
		(width 0.14732)
		(layer "In6.Cu")
		(net "UPI_CPU1_CPU0_P0P1_DP<14>")
	)
	(segment
		(start 349.308166 -170.08221)
		(end 349.165672 -170.613832)
		(width 0.14732)
		(layer "In6.Cu")
		(net "UPI_CPU1_CPU0_P0P1_DP<14>")
	)
	(segment
		(start 111.038386 -190.913258)
		(end 111.309912 -190.571374)
		(width 0.14732)
		(layer "In6.Cu")
		(net "UPI_CPU1_CPU0_P0P1_DP<14>")
	)
	(segment
		(start 110.342934 -191.788542)
		(end 110.61446 -191.446658)
		(width 0.14732)
		(layer "In6.Cu")
		(net "UPI_CPU1_CPU0_P0P1_DP<14>")
	)
	(segment
		(start 112.700562 -188.820806)
		(end 112.872012 -188.801248)
		(width 0.14732)
		(layer "In6.Cu")
		(net "UPI_CPU1_CPU0_P0P1_DP<14>")
	)
	(segment
		(start 113.144046 -188.458856)
		(end 113.124488 -188.287406)
		(width 0.14732)
		(layer "In6.Cu")
		(net "UPI_CPU1_CPU0_P0P1_DP<14>")
	)
	(segment
		(start 339.553804 -161.779712)
		(end 342.150192 -164.0078)
		(width 0.14732)
		(layer "In6.Cu")
		(net "UPI_CPU1_CPU0_P0P1_DP<14>")
	)
	(segment
		(start 113.81994 -187.412122)
		(end 114.836956 -186.131962)
		(width 0.14732)
		(layer "In6.Cu")
		(net "UPI_CPU1_CPU0_P0P1_DP<14>")
	)
	(segment
		(start 114.836956 -186.131962)
		(end 131.229608 -170.71848)
		(width 0.14732)
		(layer "In6.Cu")
		(net "UPI_CPU1_CPU0_P0P1_DP<14>")
	)
	(segment
		(start 102.083108 -214.321644)
		(end 102.113334 -214.22487)
		(width 0.0889)
		(layer "In6.Cu")
		(net "UPI_CPU1_CPU0_P0P1_DP<14>")
	)
	(segment
		(start 112.005364 -189.69609)
		(end 112.176814 -189.676532)
		(width 0.14732)
		(layer "In6.Cu")
		(net "UPI_CPU1_CPU0_P0P1_DP<14>")
	)
	(segment
		(start 279.2095 -160.592008)
		(end 321.995292 -151.628348)
		(width 0.14732)
		(layer "In6.Cu")
		(net "UPI_CPU1_CPU0_P0P1_DP<14>")
	)
	(segment
		(start 111.733838 -190.037974)
		(end 112.005364 -189.69609)
		(width 0.14732)
		(layer "In6.Cu")
		(net "UPI_CPU1_CPU0_P0P1_DP<14>")
	)
	(segment
		(start 110.61446 -191.446658)
		(end 110.78591 -191.4271)
		(width 0.14732)
		(layer "In6.Cu")
		(net "UPI_CPU1_CPU0_P0P1_DP<14>")
	)
	(arc
		(start 102.113334 -214.22487)
		(mid 102.23608 -214.111365)
		(end 102.32263 -213.96833)
		(width 0.0889)
		(layer "In6.Cu")
		(net "UPI_CPU1_CPU0_P0P1_DP<14>")
	)
	(arc
		(start 102.32263 -213.96833)
		(mid 102.330465 -213.949031)
		(end 102.337616 -213.929468)
		(width 0.0889)
		(layer "In6.Cu")
		(net "UPI_CPU1_CPU0_P0P1_DP<14>")
	)
	(segment
		(start 370.762784 -213.047326)
		(end 370.554758 -212.8393)
		(width 0.0889)
		(layer "F.Cu")
		(net "UPI_CPU1_CPU0_P0P1_DP<13>")
	)
	(segment
		(start 363.077252 -200.31964)
		(end 364.028736 -195.53555)
		(width 0.13208)
		(layer "F.Cu")
		(net "UPI_CPU1_CPU0_P0P1_DP<13>")
	)
	(segment
		(start 370.762784 -213.19998)
		(end 370.762784 -213.047326)
		(width 0.0889)
		(layer "F.Cu")
		(net "UPI_CPU1_CPU0_P0P1_DP<13>")
	)
	(segment
		(start 367.285778 -183.132222)
		(end 366.775746 -180.56987)
		(width 0.13208)
		(layer "F.Cu")
		(net "UPI_CPU1_CPU0_P0P1_DP<13>")
	)
	(segment
		(start 352.927666 -169.149014)
		(end 353.096068 -168.857168)
		(width 0.13208)
		(layer "F.Cu")
		(net "UPI_CPU1_CPU0_P0P1_DP<13>")
	)
	(segment
		(start 370.554758 -212.8393)
		(end 370.554758 -212.41639)
		(width 0.0889)
		(layer "F.Cu")
		(net "UPI_CPU1_CPU0_P0P1_DP<13>")
	)
	(segment
		(start 370.663724 -213.45144)
		(end 370.663724 -213.29904)
		(width 0.0889)
		(layer "F.Cu")
		(net "UPI_CPU1_CPU0_P0P1_DP<13>")
	)
	(segment
		(start 366.786414 -188.877956)
		(end 367.285778 -186.36742)
		(width 0.13208)
		(layer "F.Cu")
		(net "UPI_CPU1_CPU0_P0P1_DP<13>")
	)
	(segment
		(start 366.478312 -179.85105)
		(end 356.968298 -172.056298)
		(width 0.13208)
		(layer "F.Cu")
		(net "UPI_CPU1_CPU0_P0P1_DP<13>")
	)
	(segment
		(start 370.762784 -213.7029)
		(end 370.762784 -213.5505)
		(width 0.0889)
		(layer "F.Cu")
		(net "UPI_CPU1_CPU0_P0P1_DP<13>")
	)
	(segment
		(start 353.096068 -168.857168)
		(end 353.096576 -168.856406)
		(width 0.13208)
		(layer "F.Cu")
		(net "UPI_CPU1_CPU0_P0P1_DP<13>")
	)
	(segment
		(start 364.983268 -207.533494)
		(end 363.111542 -205.661514)
		(width 0.0889)
		(layer "F.Cu")
		(net "UPI_CPU1_CPU0_P0P1_DP<13>")
	)
	(segment
		(start 366.775746 -180.56987)
		(end 366.478312 -179.85105)
		(width 0.13208)
		(layer "F.Cu")
		(net "UPI_CPU1_CPU0_P0P1_DP<13>")
	)
	(segment
		(start 356.968298 -172.056298)
		(end 356.964488 -172.05325)
		(width 0.13208)
		(layer "F.Cu")
		(net "UPI_CPU1_CPU0_P0P1_DP<13>")
	)
	(segment
		(start 353.096576 -168.856406)
		(end 353.097084 -168.85539)
		(width 0.13208)
		(layer "F.Cu")
		(net "UPI_CPU1_CPU0_P0P1_DP<13>")
	)
	(segment
		(start 370.762784 -214.05342)
		(end 370.663724 -213.95436)
		(width 0.0889)
		(layer "F.Cu")
		(net "UPI_CPU1_CPU0_P0P1_DP<13>")
	)
	(segment
		(start 363.077252 -205.205076)
		(end 363.077252 -200.31964)
		(width 0.13208)
		(layer "F.Cu")
		(net "UPI_CPU1_CPU0_P0P1_DP<13>")
	)
	(segment
		(start 356.964488 -172.05325)
		(end 356.954074 -172.044614)
		(width 0.13208)
		(layer "F.Cu")
		(net "UPI_CPU1_CPU0_P0P1_DP<13>")
	)
	(segment
		(start 370.388134 -214.344758)
		(end 370.543328 -214.613744)
		(width 0.0889)
		(layer "F.Cu")
		(net "UPI_CPU1_CPU0_P0P1_DP<13>")
	)
	(segment
		(start 363.077252 -205.227174)
		(end 363.077252 -205.205076)
		(width 0.0889)
		(layer "F.Cu")
		(net "UPI_CPU1_CPU0_P0P1_DP<13>")
	)
	(segment
		(start 366.15878 -208.020412)
		(end 364.983268 -207.533494)
		(width 0.0889)
		(layer "F.Cu")
		(net "UPI_CPU1_CPU0_P0P1_DP<13>")
	)
	(segment
		(start 370.543328 -214.613744)
		(end 370.624354 -214.635334)
		(width 0.0889)
		(layer "F.Cu")
		(net "UPI_CPU1_CPU0_P0P1_DP<13>")
	)
	(segment
		(start 100.832666 -215.972644)
		(end 100.832666 -215.436958)
		(width 0.13208)
		(layer "F.Cu")
		(net "UPI_CPU1_CPU0_P0P1_DP<13>")
	)
	(segment
		(start 352.890836 -169.569384)
		(end 352.927666 -169.149014)
		(width 0.13208)
		(layer "F.Cu")
		(net "UPI_CPU1_CPU0_P0P1_DP<13>")
	)
	(segment
		(start 353.097846 -168.85412)
		(end 352.950272 -168.302432)
		(width 0.13208)
		(layer "F.Cu")
		(net "UPI_CPU1_CPU0_P0P1_DP<13>")
	)
	(segment
		(start 370.663724 -213.29904)
		(end 370.762784 -213.19998)
		(width 0.0889)
		(layer "F.Cu")
		(net "UPI_CPU1_CPU0_P0P1_DP<13>")
	)
	(segment
		(start 370.762784 -214.344758)
		(end 370.762784 -214.05342)
		(width 0.0889)
		(layer "F.Cu")
		(net "UPI_CPU1_CPU0_P0P1_DP<13>")
	)
	(segment
		(start 370.663724 -213.95436)
		(end 370.663724 -213.80196)
		(width 0.0889)
		(layer "F.Cu")
		(net "UPI_CPU1_CPU0_P0P1_DP<13>")
	)
	(segment
		(start 353.097084 -168.85539)
		(end 353.097846 -168.85412)
		(width 0.13208)
		(layer "F.Cu")
		(net "UPI_CPU1_CPU0_P0P1_DP<13>")
	)
	(segment
		(start 353.064064 -169.825416)
		(end 352.890836 -169.569384)
		(width 0.13208)
		(layer "F.Cu")
		(net "UPI_CPU1_CPU0_P0P1_DP<13>")
	)
	(segment
		(start 100.832666 -215.436958)
		(end 100.832412 -215.436704)
		(width 0.13208)
		(layer "F.Cu")
		(net "UPI_CPU1_CPU0_P0P1_DP<13>")
	)
	(segment
		(start 354.568506 -170.280584)
		(end 353.064064 -169.825416)
		(width 0.13208)
		(layer "F.Cu")
		(net "UPI_CPU1_CPU0_P0P1_DP<13>")
	)
	(segment
		(start 356.954074 -172.044614)
		(end 354.568506 -170.280584)
		(width 0.13208)
		(layer "F.Cu")
		(net "UPI_CPU1_CPU0_P0P1_DP<13>")
	)
	(segment
		(start 364.028736 -195.53555)
		(end 366.786414 -188.877956)
		(width 0.13208)
		(layer "F.Cu")
		(net "UPI_CPU1_CPU0_P0P1_DP<13>")
	)
	(segment
		(start 370.663724 -213.80196)
		(end 370.762784 -213.7029)
		(width 0.0889)
		(layer "F.Cu")
		(net "UPI_CPU1_CPU0_P0P1_DP<13>")
	)
	(segment
		(start 370.554758 -212.41639)
		(end 366.15878 -208.020412)
		(width 0.0889)
		(layer "F.Cu")
		(net "UPI_CPU1_CPU0_P0P1_DP<13>")
	)
	(segment
		(start 370.762784 -213.5505)
		(end 370.663724 -213.45144)
		(width 0.0889)
		(layer "F.Cu")
		(net "UPI_CPU1_CPU0_P0P1_DP<13>")
	)
	(segment
		(start 363.111542 -205.661514)
		(end 363.111542 -205.261464)
		(width 0.0889)
		(layer "F.Cu")
		(net "UPI_CPU1_CPU0_P0P1_DP<13>")
	)
	(segment
		(start 367.285778 -186.36742)
		(end 367.285778 -183.132222)
		(width 0.13208)
		(layer "F.Cu")
		(net "UPI_CPU1_CPU0_P0P1_DP<13>")
	)
	(segment
		(start 363.111542 -205.261464)
		(end 363.077252 -205.227174)
		(width 0.0889)
		(layer "F.Cu")
		(net "UPI_CPU1_CPU0_P0P1_DP<13>")
	)
	(arc
		(start 370.624354 -214.635334)
		(mid 370.726375 -214.505672)
		(end 370.762784 -214.344758)
		(width 0.0889)
		(layer "F.Cu")
		(net "UPI_CPU1_CPU0_P0P1_DP<13>")
	)
	(segment
		(start 238.198914 -149.494748)
		(end 233.906568 -149.494748)
		(width 0.14732)
		(layer "In6.Cu")
		(net "UPI_CPU1_CPU0_P0P1_DP<13>")
	)
	(segment
		(start 184.547002 -150.553166)
		(end 182.597806 -150.20925)
		(width 0.14732)
		(layer "In6.Cu")
		(net "UPI_CPU1_CPU0_P0P1_DP<13>")
	)
	(segment
		(start 113.375948 -185.9788)
		(end 107.979718 -192.77076)
		(width 0.14732)
		(layer "In6.Cu")
		(net "UPI_CPU1_CPU0_P0P1_DP<13>")
	)
	(segment
		(start 348.389194 -168.603676)
		(end 346.43949 -167.003476)
		(width 0.14732)
		(layer "In6.Cu")
		(net "UPI_CPU1_CPU0_P0P1_DP<13>")
	)
	(segment
		(start 327.253346 -151.271732)
		(end 324.009766 -150.457408)
		(width 0.14732)
		(layer "In6.Cu")
		(net "UPI_CPU1_CPU0_P0P1_DP<13>")
	)
	(segment
		(start 349.755206 -168.844722)
		(end 348.389194 -168.603676)
		(width 0.14732)
		(layer "In6.Cu")
		(net "UPI_CPU1_CPU0_P0P1_DP<13>")
	)
	(segment
		(start 180.893974 -149.016212)
		(end 169.998644 -147.09521)
		(width 0.14732)
		(layer "In6.Cu")
		(net "UPI_CPU1_CPU0_P0P1_DP<13>")
	)
	(segment
		(start 352.99142 -169.0243)
		(end 352.785172 -169.230548)
		(width 0.14732)
		(layer "In6.Cu")
		(net "UPI_CPU1_CPU0_P0P1_DP<13>")
	)
	(segment
		(start 200.420224 -150.824946)
		(end 197.034912 -147.439634)
		(width 0.14732)
		(layer "In6.Cu")
		(net "UPI_CPU1_CPU0_P0P1_DP<13>")
	)
	(segment
		(start 101.20757 -213.892892)
		(end 101.207316 -213.8934)
		(width 0.0889)
		(layer "In6.Cu")
		(net "UPI_CPU1_CPU0_P0P1_DP<13>")
	)
	(segment
		(start 101.16566 -211.722208)
		(end 101.20757 -211.764118)
		(width 0.0889)
		(layer "In6.Cu")
		(net "UPI_CPU1_CPU0_P0P1_DP<13>")
	)
	(segment
		(start 279.093422 -159.489648)
		(end 277.111968 -159.489648)
		(width 0.14732)
		(layer "In6.Cu")
		(net "UPI_CPU1_CPU0_P0P1_DP<13>")
	)
	(segment
		(start 182.597806 -150.20925)
		(end 180.893974 -149.016212)
		(width 0.14732)
		(layer "In6.Cu")
		(net "UPI_CPU1_CPU0_P0P1_DP<13>")
	)
	(segment
		(start 322.20662 -150.457408)
		(end 279.093422 -159.489648)
		(width 0.14732)
		(layer "In6.Cu")
		(net "UPI_CPU1_CPU0_P0P1_DP<13>")
	)
	(segment
		(start 343.784174 -163.906454)
		(end 339.990938 -160.65119)
		(width 0.14732)
		(layer "In6.Cu")
		(net "UPI_CPU1_CPU0_P0P1_DP<13>")
	)
	(segment
		(start 100.988876 -215.165686)
		(end 100.832412 -215.436704)
		(width 0.0889)
		(layer "In6.Cu")
		(net "UPI_CPU1_CPU0_P0P1_DP<13>")
	)
	(segment
		(start 346.43949 -167.003476)
		(end 345.830398 -166.470584)
		(width 0.14732)
		(layer "In6.Cu")
		(net "UPI_CPU1_CPU0_P0P1_DP<13>")
	)
	(segment
		(start 277.111968 -159.489648)
		(end 238.198914 -149.494748)
		(width 0.14732)
		(layer "In6.Cu")
		(net "UPI_CPU1_CPU0_P0P1_DP<13>")
	)
	(segment
		(start 202.567032 -154.415998)
		(end 200.420224 -152.26919)
		(width 0.14732)
		(layer "In6.Cu")
		(net "UPI_CPU1_CPU0_P0P1_DP<13>")
	)
	(segment
		(start 191.465962 -147.439634)
		(end 187.851288 -149.97049)
		(width 0.14732)
		(layer "In6.Cu")
		(net "UPI_CPU1_CPU0_P0P1_DP<13>")
	)
	(segment
		(start 352.785172 -169.230548)
		(end 352.130868 -169.230548)
		(width 0.14732)
		(layer "In6.Cu")
		(net "UPI_CPU1_CPU0_P0P1_DP<13>")
	)
	(segment
		(start 205.99781 -154.415998)
		(end 202.567032 -154.415998)
		(width 0.14732)
		(layer "In6.Cu")
		(net "UPI_CPU1_CPU0_P0P1_DP<13>")
	)
	(segment
		(start 100.736908 -214.425784)
		(end 100.736908 -214.636858)
		(width 0.0889)
		(layer "In6.Cu")
		(net "UPI_CPU1_CPU0_P0P1_DP<13>")
	)
	(segment
		(start 197.034912 -147.439634)
		(end 191.465962 -147.439634)
		(width 0.14732)
		(layer "In6.Cu")
		(net "UPI_CPU1_CPU0_P0P1_DP<13>")
	)
	(segment
		(start 107.979718 -192.77076)
		(end 101.16566 -211.478876)
		(width 0.14732)
		(layer "In6.Cu")
		(net "UPI_CPU1_CPU0_P0P1_DP<13>")
	)
	(segment
		(start 101.16566 -211.478876)
		(end 101.16566 -211.70011)
		(width 0.14732)
		(layer "In6.Cu")
		(net "UPI_CPU1_CPU0_P0P1_DP<13>")
	)
	(segment
		(start 101.16566 -211.70011)
		(end 101.16566 -211.722208)
		(width 0.0889)
		(layer "In6.Cu")
		(net "UPI_CPU1_CPU0_P0P1_DP<13>")
	)
	(segment
		(start 352.130868 -169.230548)
		(end 350.124522 -168.781222)
		(width 0.14732)
		(layer "In6.Cu")
		(net "UPI_CPU1_CPU0_P0P1_DP<13>")
	)
	(segment
		(start 187.851288 -149.97049)
		(end 184.547002 -150.553166)
		(width 0.14732)
		(layer "In6.Cu")
		(net "UPI_CPU1_CPU0_P0P1_DP<13>")
	)
	(segment
		(start 324.009766 -150.457408)
		(end 322.20662 -150.457408)
		(width 0.14732)
		(layer "In6.Cu")
		(net "UPI_CPU1_CPU0_P0P1_DP<13>")
	)
	(segment
		(start 233.906568 -149.494748)
		(end 205.99781 -154.415998)
		(width 0.14732)
		(layer "In6.Cu")
		(net "UPI_CPU1_CPU0_P0P1_DP<13>")
	)
	(segment
		(start 101.20757 -211.764118)
		(end 101.20757 -213.892892)
		(width 0.0889)
		(layer "In6.Cu")
		(net "UPI_CPU1_CPU0_P0P1_DP<13>")
	)
	(segment
		(start 130.565144 -169.817542)
		(end 113.375948 -185.9788)
		(width 0.14732)
		(layer "In6.Cu")
		(net "UPI_CPU1_CPU0_P0P1_DP<13>")
	)
	(segment
		(start 169.998644 -147.09521)
		(end 164.107114 -149.147276)
		(width 0.14732)
		(layer "In6.Cu")
		(net "UPI_CPU1_CPU0_P0P1_DP<13>")
	)
	(segment
		(start 200.420224 -152.26919)
		(end 200.420224 -150.824946)
		(width 0.14732)
		(layer "In6.Cu")
		(net "UPI_CPU1_CPU0_P0P1_DP<13>")
	)
	(segment
		(start 345.830398 -166.470584)
		(end 343.784174 -163.906454)
		(width 0.14732)
		(layer "In6.Cu")
		(net "UPI_CPU1_CPU0_P0P1_DP<13>")
	)
	(segment
		(start 353.09556 -168.84396)
		(end 352.99142 -169.0243)
		(width 0.14732)
		(layer "In6.Cu")
		(net "UPI_CPU1_CPU0_P0P1_DP<13>")
	)
	(segment
		(start 100.964746 -215.076532)
		(end 100.988876 -215.165686)
		(width 0.0889)
		(layer "In6.Cu")
		(net "UPI_CPU1_CPU0_P0P1_DP<13>")
	)
	(segment
		(start 350.124522 -168.781222)
		(end 349.755206 -168.844722)
		(width 0.14732)
		(layer "In6.Cu")
		(net "UPI_CPU1_CPU0_P0P1_DP<13>")
	)
	(segment
		(start 352.950272 -168.302432)
		(end 353.09556 -168.84396)
		(width 0.14732)
		(layer "In6.Cu")
		(net "UPI_CPU1_CPU0_P0P1_DP<13>")
	)
	(segment
		(start 339.990938 -160.65119)
		(end 327.253346 -151.271732)
		(width 0.14732)
		(layer "In6.Cu")
		(net "UPI_CPU1_CPU0_P0P1_DP<13>")
	)
	(segment
		(start 164.107114 -149.147276)
		(end 130.565144 -169.817542)
		(width 0.14732)
		(layer "In6.Cu")
		(net "UPI_CPU1_CPU0_P0P1_DP<13>")
	)
	(arc
		(start 100.947728 -215.063324)
		(mid 100.956174 -215.070009)
		(end 100.964746 -215.076532)
		(width 0.0889)
		(layer "In6.Cu")
		(net "UPI_CPU1_CPU0_P0P1_DP<13>")
	)
	(arc
		(start 100.736908 -214.636858)
		(mid 100.795253 -214.873363)
		(end 100.947728 -215.063324)
		(width 0.0889)
		(layer "In6.Cu")
		(net "UPI_CPU1_CPU0_P0P1_DP<13>")
	)
	(arc
		(start 101.022912 -214.093298)
		(mid 100.848364 -214.232402)
		(end 100.736908 -214.425784)
		(width 0.0889)
		(layer "In6.Cu")
		(net "UPI_CPU1_CPU0_P0P1_DP<13>")
	)
	(arc
		(start 101.207316 -213.8934)
		(mid 101.132245 -214.009142)
		(end 101.022912 -214.093298)
		(width 0.0889)
		(layer "In6.Cu")
		(net "UPI_CPU1_CPU0_P0P1_DP<13>")
	)
	(segment
		(start 349.941896 -167.584882)
		(end 350.089724 -167.032432)
		(width 0.13208)
		(layer "F.Cu")
		(net "UPI_CPU1_CPU0_P0P1_DP<12>")
	)
	(segment
		(start 365.961676 -206.898748)
		(end 364.610142 -205.547214)
		(width 0.0889)
		(layer "F.Cu")
		(net "UPI_CPU1_CPU0_P0P1_DP<12>")
	)
	(segment
		(start 371.893084 -214.015066)
		(end 371.992144 -213.916006)
		(width 0.0889)
		(layer "F.Cu")
		(net "UPI_CPU1_CPU0_P0P1_DP<12>")
	)
	(segment
		(start 368.333274 -189.233302)
		(end 368.872516 -186.520582)
		(width 0.13208)
		(layer "F.Cu")
		(net "UPI_CPU1_CPU0_P0P1_DP<12>")
	)
	(segment
		(start 371.7417 -213.208362)
		(end 371.84076 -213.109302)
		(width 0.0889)
		(layer "F.Cu")
		(net "UPI_CPU1_CPU0_P0P1_DP<12>")
	)
	(segment
		(start 368.332004 -180.196998)
		(end 367.787936 -178.884072)
		(width 0.13208)
		(layer "F.Cu")
		(net "UPI_CPU1_CPU0_P0P1_DP<12>")
	)
	(segment
		(start 371.84076 -213.109302)
		(end 371.84076 -212.956902)
		(width 0.0889)
		(layer "F.Cu")
		(net "UPI_CPU1_CPU0_P0P1_DP<12>")
	)
	(segment
		(start 364.644432 -205.227174)
		(end 364.644432 -205.205076)
		(width 0.0889)
		(layer "F.Cu")
		(net "UPI_CPU1_CPU0_P0P1_DP<12>")
	)
	(segment
		(start 371.84076 -212.956902)
		(end 371.7417 -212.857842)
		(width 0.0889)
		(layer "F.Cu")
		(net "UPI_CPU1_CPU0_P0P1_DP<12>")
	)
	(segment
		(start 350.554798 -167.85971)
		(end 350.19234 -167.85971)
		(width 0.13208)
		(layer "F.Cu")
		(net "UPI_CPU1_CPU0_P0P1_DP<12>")
	)
	(segment
		(start 367.787936 -178.884072)
		(end 367.500916 -178.597052)
		(width 0.13208)
		(layer "F.Cu")
		(net "UPI_CPU1_CPU0_P0P1_DP<12>")
	)
	(segment
		(start 365.543084 -195.969382)
		(end 368.333274 -189.233302)
		(width 0.13208)
		(layer "F.Cu")
		(net "UPI_CPU1_CPU0_P0P1_DP<12>")
	)
	(segment
		(start 350.19234 -167.85971)
		(end 350.054672 -167.780462)
		(width 0.13208)
		(layer "F.Cu")
		(net "UPI_CPU1_CPU0_P0P1_DP<12>")
	)
	(segment
		(start 371.7417 -212.857842)
		(end 371.7417 -212.290152)
		(width 0.0889)
		(layer "F.Cu")
		(net "UPI_CPU1_CPU0_P0P1_DP<12>")
	)
	(segment
		(start 371.893084 -213.462362)
		(end 371.7417 -213.310978)
		(width 0.0889)
		(layer "F.Cu")
		(net "UPI_CPU1_CPU0_P0P1_DP<12>")
	)
	(segment
		(start 352.05797 -167.149272)
		(end 350.554798 -167.85971)
		(width 0.13208)
		(layer "F.Cu")
		(net "UPI_CPU1_CPU0_P0P1_DP<12>")
	)
	(segment
		(start 371.893084 -213.664546)
		(end 371.893084 -213.462362)
		(width 0.0889)
		(layer "F.Cu")
		(net "UPI_CPU1_CPU0_P0P1_DP<12>")
	)
	(segment
		(start 371.992144 -213.763606)
		(end 371.893084 -213.664546)
		(width 0.0889)
		(layer "F.Cu")
		(net "UPI_CPU1_CPU0_P0P1_DP<12>")
	)
	(segment
		(start 366.625378 -207.17383)
		(end 365.961676 -206.898748)
		(width 0.0889)
		(layer "F.Cu")
		(net "UPI_CPU1_CPU0_P0P1_DP<12>")
	)
	(segment
		(start 371.893084 -214.345266)
		(end 371.893084 -214.015066)
		(width 0.0889)
		(layer "F.Cu")
		(net "UPI_CPU1_CPU0_P0P1_DP<12>")
	)
	(segment
		(start 371.642386 -215.42756)
		(end 371.56136 -215.44915)
		(width 0.0889)
		(layer "F.Cu")
		(net "UPI_CPU1_CPU0_P0P1_DP<12>")
	)
	(segment
		(start 352.876866 -167.149272)
		(end 352.05797 -167.149272)
		(width 0.13208)
		(layer "F.Cu")
		(net "UPI_CPU1_CPU0_P0P1_DP<12>")
	)
	(segment
		(start 367.500916 -178.597052)
		(end 353.948238 -167.474392)
		(width 0.13208)
		(layer "F.Cu")
		(net "UPI_CPU1_CPU0_P0P1_DP<12>")
	)
	(segment
		(start 99.892866 -214.344758)
		(end 99.892866 -213.732618)
		(width 0.13208)
		(layer "F.Cu")
		(net "UPI_CPU1_CPU0_P0P1_DP<12>")
	)
	(segment
		(start 368.872516 -182.915306)
		(end 368.332004 -180.196998)
		(width 0.13208)
		(layer "F.Cu")
		(net "UPI_CPU1_CPU0_P0P1_DP<12>")
	)
	(segment
		(start 350.054672 -167.780462)
		(end 349.942404 -167.586152)
		(width 0.13208)
		(layer "F.Cu")
		(net "UPI_CPU1_CPU0_P0P1_DP<12>")
	)
	(segment
		(start 364.610142 -205.261464)
		(end 364.644432 -205.227174)
		(width 0.0889)
		(layer "F.Cu")
		(net "UPI_CPU1_CPU0_P0P1_DP<12>")
	)
	(segment
		(start 353.948238 -167.474392)
		(end 352.876866 -167.149272)
		(width 0.13208)
		(layer "F.Cu")
		(net "UPI_CPU1_CPU0_P0P1_DP<12>")
	)
	(segment
		(start 364.610142 -205.547214)
		(end 364.610142 -205.261464)
		(width 0.0889)
		(layer "F.Cu")
		(net "UPI_CPU1_CPU0_P0P1_DP<12>")
	)
	(segment
		(start 364.644432 -200.487534)
		(end 365.543084 -195.969382)
		(width 0.13208)
		(layer "F.Cu")
		(net "UPI_CPU1_CPU0_P0P1_DP<12>")
	)
	(segment
		(start 371.7417 -212.290152)
		(end 366.625378 -207.17383)
		(width 0.0889)
		(layer "F.Cu")
		(net "UPI_CPU1_CPU0_P0P1_DP<12>")
	)
	(segment
		(start 368.872516 -186.520582)
		(end 368.872516 -182.915306)
		(width 0.13208)
		(layer "F.Cu")
		(net "UPI_CPU1_CPU0_P0P1_DP<12>")
	)
	(segment
		(start 349.942404 -167.586152)
		(end 349.942658 -167.585898)
		(width 0.13208)
		(layer "F.Cu")
		(net "UPI_CPU1_CPU0_P0P1_DP<12>")
	)
	(segment
		(start 371.7417 -213.310978)
		(end 371.7417 -213.208362)
		(width 0.0889)
		(layer "F.Cu")
		(net "UPI_CPU1_CPU0_P0P1_DP<12>")
	)
	(segment
		(start 364.644432 -205.205076)
		(end 364.644432 -200.487534)
		(width 0.13208)
		(layer "F.Cu")
		(net "UPI_CPU1_CPU0_P0P1_DP<12>")
	)
	(segment
		(start 371.992144 -213.916006)
		(end 371.992144 -213.763606)
		(width 0.0889)
		(layer "F.Cu")
		(net "UPI_CPU1_CPU0_P0P1_DP<12>")
	)
	(segment
		(start 349.942658 -167.585898)
		(end 349.941896 -167.584882)
		(width 0.13208)
		(layer "F.Cu")
		(net "UPI_CPU1_CPU0_P0P1_DP<12>")
	)
	(segment
		(start 371.79758 -215.158574)
		(end 371.642386 -215.42756)
		(width 0.0889)
		(layer "F.Cu")
		(net "UPI_CPU1_CPU0_P0P1_DP<12>")
	)
	(arc
		(start 371.623844 -214.826342)
		(mid 371.821052 -214.620838)
		(end 371.893084 -214.345266)
		(width 0.0889)
		(layer "F.Cu")
		(net "UPI_CPU1_CPU0_P0P1_DP<12>")
	)
	(arc
		(start 371.56136 -215.44915)
		(mid 371.459339 -215.319488)
		(end 371.42293 -215.158574)
		(width 0.0889)
		(layer "F.Cu")
		(net "UPI_CPU1_CPU0_P0P1_DP<12>")
	)
	(arc
		(start 371.621558 -214.827612)
		(mid 371.622704 -214.826982)
		(end 371.623844 -214.826342)
		(width 0.0889)
		(layer "F.Cu")
		(net "UPI_CPU1_CPU0_P0P1_DP<12>")
	)
	(arc
		(start 371.42293 -215.158574)
		(mid 371.476336 -214.965538)
		(end 371.621558 -214.827612)
		(width 0.0889)
		(layer "F.Cu")
		(net "UPI_CPU1_CPU0_P0P1_DP<12>")
	)
	(segment
		(start 100.136198 -214.05977)
		(end 100.051616 -214.033608)
		(width 0.0889)
		(layer "In6.Cu")
		(net "UPI_CPU1_CPU0_P0P1_DP<12>")
	)
	(segment
		(start 327.749154 -150.500588)
		(end 318.608202 -148.20773)
		(width 0.14732)
		(layer "In6.Cu")
		(net "UPI_CPU1_CPU0_P0P1_DP<12>")
	)
	(segment
		(start 100.267516 -212.767164)
		(end 100.267516 -213.033864)
		(width 0.0889)
		(layer "In6.Cu")
		(net "UPI_CPU1_CPU0_P0P1_DP<12>")
	)
	(segment
		(start 100.267516 -213.033864)
		(end 100.168202 -213.133178)
		(width 0.0889)
		(layer "In6.Cu")
		(net "UPI_CPU1_CPU0_P0P1_DP<12>")
	)
	(segment
		(start 100.267516 -213.499192)
		(end 100.267516 -213.8934)
		(width 0.0889)
		(layer "In6.Cu")
		(net "UPI_CPU1_CPU0_P0P1_DP<12>")
	)
	(segment
		(start 163.642294 -148.403818)
		(end 130.160522 -169.00652)
		(width 0.14732)
		(layer "In6.Cu")
		(net "UPI_CPU1_CPU0_P0P1_DP<12>")
	)
	(segment
		(start 349.549212 -166.887652)
		(end 349.544132 -166.879778)
		(width 0.14732)
		(layer "In6.Cu")
		(net "UPI_CPU1_CPU0_P0P1_DP<12>")
	)
	(segment
		(start 112.063276 -186.041538)
		(end 107.334558 -191.97193)
		(width 0.14732)
		(layer "In6.Cu")
		(net "UPI_CPU1_CPU0_P0P1_DP<12>")
	)
	(segment
		(start 318.608202 -148.20773)
		(end 275.792692 -146.555206)
		(width 0.14732)
		(layer "In6.Cu")
		(net "UPI_CPU1_CPU0_P0P1_DP<12>")
	)
	(segment
		(start 100.225606 -211.77123)
		(end 100.225606 -211.793328)
		(width 0.0889)
		(layer "In6.Cu")
		(net "UPI_CPU1_CPU0_P0P1_DP<12>")
	)
	(segment
		(start 100.267516 -212.301836)
		(end 100.168202 -212.40115)
		(width 0.0889)
		(layer "In6.Cu")
		(net "UPI_CPU1_CPU0_P0P1_DP<12>")
	)
	(segment
		(start 100.051616 -214.033608)
		(end 99.892866 -213.732618)
		(width 0.0889)
		(layer "In6.Cu")
		(net "UPI_CPU1_CPU0_P0P1_DP<12>")
	)
	(segment
		(start 275.792692 -146.555206)
		(end 238.603028 -147.22475)
		(width 0.14732)
		(layer "In6.Cu")
		(net "UPI_CPU1_CPU0_P0P1_DP<12>")
	)
	(segment
		(start 100.225606 -211.793328)
		(end 100.267516 -211.835238)
		(width 0.0889)
		(layer "In6.Cu")
		(net "UPI_CPU1_CPU0_P0P1_DP<12>")
	)
	(segment
		(start 100.225606 -211.221066)
		(end 100.225606 -211.77123)
		(width 0.14732)
		(layer "In6.Cu")
		(net "UPI_CPU1_CPU0_P0P1_DP<12>")
	)
	(segment
		(start 107.334558 -191.97193)
		(end 100.225606 -211.221066)
		(width 0.14732)
		(layer "In6.Cu")
		(net "UPI_CPU1_CPU0_P0P1_DP<12>")
	)
	(segment
		(start 130.160522 -169.00652)
		(end 112.063276 -186.041538)
		(width 0.14732)
		(layer "In6.Cu")
		(net "UPI_CPU1_CPU0_P0P1_DP<12>")
	)
	(segment
		(start 100.168202 -213.399878)
		(end 100.267516 -213.499192)
		(width 0.0889)
		(layer "In6.Cu")
		(net "UPI_CPU1_CPU0_P0P1_DP<12>")
	)
	(segment
		(start 100.168202 -213.133178)
		(end 100.168202 -213.399878)
		(width 0.0889)
		(layer "In6.Cu")
		(net "UPI_CPU1_CPU0_P0P1_DP<12>")
	)
	(segment
		(start 100.168202 -212.66785)
		(end 100.267516 -212.767164)
		(width 0.0889)
		(layer "In6.Cu")
		(net "UPI_CPU1_CPU0_P0P1_DP<12>")
	)
	(segment
		(start 100.168202 -212.40115)
		(end 100.168202 -212.66785)
		(width 0.0889)
		(layer "In6.Cu")
		(net "UPI_CPU1_CPU0_P0P1_DP<12>")
	)
	(segment
		(start 350.089724 -167.032432)
		(end 349.549212 -166.887652)
		(width 0.14732)
		(layer "In6.Cu")
		(net "UPI_CPU1_CPU0_P0P1_DP<12>")
	)
	(segment
		(start 238.603028 -147.22475)
		(end 170.240198 -146.128232)
		(width 0.14732)
		(layer "In6.Cu")
		(net "UPI_CPU1_CPU0_P0P1_DP<12>")
	)
	(segment
		(start 349.36557 -166.569898)
		(end 327.749154 -150.500588)
		(width 0.14732)
		(layer "In6.Cu")
		(net "UPI_CPU1_CPU0_P0P1_DP<12>")
	)
	(segment
		(start 170.240198 -146.128232)
		(end 163.642294 -148.403818)
		(width 0.14732)
		(layer "In6.Cu")
		(net "UPI_CPU1_CPU0_P0P1_DP<12>")
	)
	(segment
		(start 349.544132 -166.879778)
		(end 349.36557 -166.569898)
		(width 0.14732)
		(layer "In6.Cu")
		(net "UPI_CPU1_CPU0_P0P1_DP<12>")
	)
	(segment
		(start 100.267516 -211.835238)
		(end 100.267516 -212.301836)
		(width 0.0889)
		(layer "In6.Cu")
		(net "UPI_CPU1_CPU0_P0P1_DP<12>")
	)
	(arc
		(start 100.267516 -213.8934)
		(mid 100.212846 -213.985256)
		(end 100.136198 -214.05977)
		(width 0.0889)
		(layer "In6.Cu")
		(net "UPI_CPU1_CPU0_P0P1_DP<12>")
	)
	(segment
		(start 372.83263 -212.839554)
		(end 372.774972 -212.781896)
		(width 0.0889)
		(layer "F.Cu")
		(net "UPI_CPU1_CPU0_P0P1_DP<11>")
	)
	(segment
		(start 370.788946 -189.698122)
		(end 373.291862 -185.994802)
		(width 0.13208)
		(layer "F.Cu")
		(net "UPI_CPU1_CPU0_P0P1_DP<11>")
	)
	(segment
		(start 372.582186 -214.889588)
		(end 372.607332 -214.796878)
		(width 0.0889)
		(layer "F.Cu")
		(net "UPI_CPU1_CPU0_P0P1_DP<11>")
	)
	(segment
		(start 365.952532 -205.227174)
		(end 365.952532 -205.205076)
		(width 0.0889)
		(layer "F.Cu")
		(net "UPI_CPU1_CPU0_P0P1_DP<11>")
	)
	(segment
		(start 373.465852 -185.69432)
		(end 374.018556 -185.544968)
		(width 0.13208)
		(layer "F.Cu")
		(net "UPI_CPU1_CPU0_P0P1_DP<11>")
	)
	(segment
		(start 372.832884 -213.130384)
		(end 372.83263 -213.13013)
		(width 0.0889)
		(layer "F.Cu")
		(net "UPI_CPU1_CPU0_P0P1_DP<11>")
	)
	(segment
		(start 365.952532 -205.205076)
		(end 365.952532 -200.772268)
		(width 0.13208)
		(layer "F.Cu")
		(net "UPI_CPU1_CPU0_P0P1_DP<11>")
	)
	(segment
		(start 372.83263 -213.13013)
		(end 372.83263 -212.839554)
		(width 0.0889)
		(layer "F.Cu")
		(net "UPI_CPU1_CPU0_P0P1_DP<11>")
	)
	(segment
		(start 372.832884 -214.344758)
		(end 372.832884 -213.130384)
		(width 0.0889)
		(layer "F.Cu")
		(net "UPI_CPU1_CPU0_P0P1_DP<11>")
	)
	(segment
		(start 98.953066 -215.972644)
		(end 98.953066 -215.436958)
		(width 0.13208)
		(layer "F.Cu")
		(net "UPI_CPU1_CPU0_P0P1_DP<11>")
	)
	(segment
		(start 365.917988 -205.483714)
		(end 365.917988 -205.261718)
		(width 0.0889)
		(layer "F.Cu")
		(net "UPI_CPU1_CPU0_P0P1_DP<11>")
	)
	(segment
		(start 372.774972 -212.781896)
		(end 372.774972 -212.340698)
		(width 0.0889)
		(layer "F.Cu")
		(net "UPI_CPU1_CPU0_P0P1_DP<11>")
	)
	(segment
		(start 372.73738 -215.158574)
		(end 372.582186 -214.889588)
		(width 0.0889)
		(layer "F.Cu")
		(net "UPI_CPU1_CPU0_P0P1_DP<11>")
	)
	(segment
		(start 373.465598 -185.694828)
		(end 373.465852 -185.69432)
		(width 0.13208)
		(layer "F.Cu")
		(net "UPI_CPU1_CPU0_P0P1_DP<11>")
	)
	(segment
		(start 366.835944 -196.331078)
		(end 368.73053 -191.756284)
		(width 0.13208)
		(layer "F.Cu")
		(net "UPI_CPU1_CPU0_P0P1_DP<11>")
	)
	(segment
		(start 98.953066 -215.436958)
		(end 98.952812 -215.436704)
		(width 0.13208)
		(layer "F.Cu")
		(net "UPI_CPU1_CPU0_P0P1_DP<11>")
	)
	(segment
		(start 365.952532 -200.772268)
		(end 366.835944 -196.331078)
		(width 0.13208)
		(layer "F.Cu")
		(net "UPI_CPU1_CPU0_P0P1_DP<11>")
	)
	(segment
		(start 373.292624 -185.994802)
		(end 373.465598 -185.694828)
		(width 0.13208)
		(layer "F.Cu")
		(net "UPI_CPU1_CPU0_P0P1_DP<11>")
	)
	(segment
		(start 368.73053 -191.756284)
		(end 370.788946 -189.698122)
		(width 0.13208)
		(layer "F.Cu")
		(net "UPI_CPU1_CPU0_P0P1_DP<11>")
	)
	(segment
		(start 373.291862 -185.994802)
		(end 373.292624 -185.994802)
		(width 0.13208)
		(layer "F.Cu")
		(net "UPI_CPU1_CPU0_P0P1_DP<11>")
	)
	(segment
		(start 365.917988 -205.261718)
		(end 365.952532 -205.227174)
		(width 0.0889)
		(layer "F.Cu")
		(net "UPI_CPU1_CPU0_P0P1_DP<11>")
	)
	(segment
		(start 372.774972 -212.340698)
		(end 365.917988 -205.483714)
		(width 0.0889)
		(layer "F.Cu")
		(net "UPI_CPU1_CPU0_P0P1_DP<11>")
	)
	(arc
		(start 372.607332 -214.796878)
		(mid 372.616032 -214.790229)
		(end 372.624604 -214.783416)
		(width 0.0889)
		(layer "F.Cu")
		(net "UPI_CPU1_CPU0_P0P1_DP<11>")
	)
	(arc
		(start 372.624604 -214.783416)
		(mid 372.778233 -214.587592)
		(end 372.832884 -214.344758)
		(width 0.0889)
		(layer "F.Cu")
		(net "UPI_CPU1_CPU0_P0P1_DP<11>")
	)
	(segment
		(start 106.659172 -191.259968)
		(end 110.82401 -186.03722)
		(width 0.14732)
		(layer "In6.Cu")
		(net "UPI_CPU1_CPU0_P0P1_DP<11>")
	)
	(segment
		(start 373.964454 -184.364122)
		(end 374.057672 -184.687464)
		(width 0.14732)
		(layer "In6.Cu")
		(net "UPI_CPU1_CPU0_P0P1_DP<11>")
	)
	(segment
		(start 170.028616 -145.283428)
		(end 238.600488 -146.3929)
		(width 0.14732)
		(layer "In6.Cu")
		(net "UPI_CPU1_CPU0_P0P1_DP<11>")
	)
	(segment
		(start 98.952812 -215.436704)
		(end 99.109276 -215.165686)
		(width 0.0889)
		(layer "In6.Cu")
		(net "UPI_CPU1_CPU0_P0P1_DP<11>")
	)
	(segment
		(start 163.374832 -147.581112)
		(end 170.028616 -145.283428)
		(width 0.14732)
		(layer "In6.Cu")
		(net "UPI_CPU1_CPU0_P0P1_DP<11>")
	)
	(segment
		(start 129.600452 -168.362884)
		(end 163.374832 -147.581112)
		(width 0.14732)
		(layer "In6.Cu")
		(net "UPI_CPU1_CPU0_P0P1_DP<11>")
	)
	(segment
		(start 99.327716 -213.8934)
		(end 99.32797 -213.892892)
		(width 0.0889)
		(layer "In6.Cu")
		(net "UPI_CPU1_CPU0_P0P1_DP<11>")
	)
	(segment
		(start 373.761762 -184.103772)
		(end 373.964454 -184.364122)
		(width 0.14732)
		(layer "In6.Cu")
		(net "UPI_CPU1_CPU0_P0P1_DP<11>")
	)
	(segment
		(start 99.28606 -211.793328)
		(end 99.28606 -211.77123)
		(width 0.0889)
		(layer "In6.Cu")
		(net "UPI_CPU1_CPU0_P0P1_DP<11>")
	)
	(segment
		(start 368.857784 -182.663846)
		(end 369.316762 -182.984902)
		(width 0.14732)
		(layer "In6.Cu")
		(net "UPI_CPU1_CPU0_P0P1_DP<11>")
	)
	(segment
		(start 355.717094 -168.587674)
		(end 368.857784 -182.663846)
		(width 0.14732)
		(layer "In6.Cu")
		(net "UPI_CPU1_CPU0_P0P1_DP<11>")
	)
	(segment
		(start 110.82401 -186.03722)
		(end 129.600452 -168.362884)
		(width 0.14732)
		(layer "In6.Cu")
		(net "UPI_CPU1_CPU0_P0P1_DP<11>")
	)
	(segment
		(start 373.873268 -185.004456)
		(end 374.018556 -185.544968)
		(width 0.14732)
		(layer "In6.Cu")
		(net "UPI_CPU1_CPU0_P0P1_DP<11>")
	)
	(segment
		(start 374.057672 -184.687464)
		(end 373.873268 -185.004456)
		(width 0.14732)
		(layer "In6.Cu")
		(net "UPI_CPU1_CPU0_P0P1_DP<11>")
	)
	(segment
		(start 99.32797 -213.892892)
		(end 99.32797 -211.835238)
		(width 0.0889)
		(layer "In6.Cu")
		(net "UPI_CPU1_CPU0_P0P1_DP<11>")
	)
	(segment
		(start 238.600488 -146.3929)
		(end 276.078696 -145.718276)
		(width 0.14732)
		(layer "In6.Cu")
		(net "UPI_CPU1_CPU0_P0P1_DP<11>")
	)
	(segment
		(start 99.109276 -215.165686)
		(end 99.085146 -215.076532)
		(width 0.0889)
		(layer "In6.Cu")
		(net "UPI_CPU1_CPU0_P0P1_DP<11>")
	)
	(segment
		(start 99.32797 -211.835238)
		(end 99.28606 -211.793328)
		(width 0.0889)
		(layer "In6.Cu")
		(net "UPI_CPU1_CPU0_P0P1_DP<11>")
	)
	(segment
		(start 276.078696 -145.718276)
		(end 319.082166 -147.390866)
		(width 0.14732)
		(layer "In6.Cu")
		(net "UPI_CPU1_CPU0_P0P1_DP<11>")
	)
	(segment
		(start 319.082166 -147.390866)
		(end 328.25309 -149.742906)
		(width 0.14732)
		(layer "In6.Cu")
		(net "UPI_CPU1_CPU0_P0P1_DP<11>")
	)
	(segment
		(start 373.077994 -183.93156)
		(end 373.078248 -183.932068)
		(width 0.14732)
		(layer "In6.Cu")
		(net "UPI_CPU1_CPU0_P0P1_DP<11>")
	)
	(segment
		(start 373.078248 -183.932068)
		(end 373.761762 -184.103772)
		(width 0.14732)
		(layer "In6.Cu")
		(net "UPI_CPU1_CPU0_P0P1_DP<11>")
	)
	(segment
		(start 99.28606 -211.22513)
		(end 106.659172 -191.259968)
		(width 0.14732)
		(layer "In6.Cu")
		(net "UPI_CPU1_CPU0_P0P1_DP<11>")
	)
	(segment
		(start 99.28606 -211.77123)
		(end 99.28606 -211.22513)
		(width 0.14732)
		(layer "In6.Cu")
		(net "UPI_CPU1_CPU0_P0P1_DP<11>")
	)
	(segment
		(start 98.857308 -214.636858)
		(end 98.857308 -214.425784)
		(width 0.0889)
		(layer "In6.Cu")
		(net "UPI_CPU1_CPU0_P0P1_DP<11>")
	)
	(segment
		(start 328.25309 -149.742906)
		(end 355.717094 -168.587674)
		(width 0.14732)
		(layer "In6.Cu")
		(net "UPI_CPU1_CPU0_P0P1_DP<11>")
	)
	(segment
		(start 369.316762 -182.984902)
		(end 373.077994 -183.93156)
		(width 0.14732)
		(layer "In6.Cu")
		(net "UPI_CPU1_CPU0_P0P1_DP<11>")
	)
	(arc
		(start 99.143312 -214.093298)
		(mid 99.252708 -214.009201)
		(end 99.327716 -213.8934)
		(width 0.0889)
		(layer "In6.Cu")
		(net "UPI_CPU1_CPU0_P0P1_DP<11>")
	)
	(arc
		(start 98.857308 -214.425784)
		(mid 98.968748 -214.232389)
		(end 99.143312 -214.093298)
		(width 0.0889)
		(layer "In6.Cu")
		(net "UPI_CPU1_CPU0_P0P1_DP<11>")
	)
	(arc
		(start 99.068128 -215.063324)
		(mid 98.915697 -214.873342)
		(end 98.857308 -214.636858)
		(width 0.0889)
		(layer "In6.Cu")
		(net "UPI_CPU1_CPU0_P0P1_DP<11>")
	)
	(arc
		(start 99.085146 -215.076532)
		(mid 99.076574 -215.070009)
		(end 99.068128 -215.063324)
		(width 0.0889)
		(layer "In6.Cu")
		(net "UPI_CPU1_CPU0_P0P1_DP<11>")
	)
	(segment
		(start 367.260632 -205.227174)
		(end 367.260632 -205.205076)
		(width 0.0889)
		(layer "F.Cu")
		(net "UPI_CPU1_CPU0_P0P1_DP<10>")
	)
	(segment
		(start 370.898928 -182.135018)
		(end 371.046756 -181.582568)
		(width 0.13208)
		(layer "F.Cu")
		(net "UPI_CPU1_CPU0_P0P1_DP<10>")
	)
	(segment
		(start 98.013266 -214.344758)
		(end 98.013266 -213.732618)
		(width 0.13208)
		(layer "F.Cu")
		(net "UPI_CPU1_CPU0_P0P1_DP<10>")
	)
	(segment
		(start 373.772684 -213.635844)
		(end 373.871744 -213.536784)
		(width 0.0889)
		(layer "F.Cu")
		(net "UPI_CPU1_CPU0_P0P1_DP<10>")
	)
	(segment
		(start 367.260632 -200.907904)
		(end 368.098832 -196.694044)
		(width 0.13208)
		(layer "F.Cu")
		(net "UPI_CPU1_CPU0_P0P1_DP<10>")
	)
	(segment
		(start 367.226088 -205.392528)
		(end 367.226088 -205.261718)
		(width 0.0889)
		(layer "F.Cu")
		(net "UPI_CPU1_CPU0_P0P1_DP<10>")
	)
	(segment
		(start 373.871744 -213.887304)
		(end 373.772684 -213.788244)
		(width 0.0889)
		(layer "F.Cu")
		(net "UPI_CPU1_CPU0_P0P1_DP<10>")
	)
	(segment
		(start 367.260632 -205.205076)
		(end 367.260632 -200.907904)
		(width 0.13208)
		(layer "F.Cu")
		(net "UPI_CPU1_CPU0_P0P1_DP<10>")
	)
	(segment
		(start 367.226088 -205.261718)
		(end 367.260632 -205.227174)
		(width 0.0889)
		(layer "F.Cu")
		(net "UPI_CPU1_CPU0_P0P1_DP<10>")
	)
	(segment
		(start 373.521986 -215.42756)
		(end 373.44096 -215.44915)
		(width 0.0889)
		(layer "F.Cu")
		(net "UPI_CPU1_CPU0_P0P1_DP<10>")
	)
	(segment
		(start 373.772684 -214.304372)
		(end 373.772684 -214.138764)
		(width 0.0889)
		(layer "F.Cu")
		(net "UPI_CPU1_CPU0_P0P1_DP<10>")
	)
	(segment
		(start 369.711986 -192.799716)
		(end 375.168668 -187.343034)
		(width 0.13208)
		(layer "F.Cu")
		(net "UPI_CPU1_CPU0_P0P1_DP<10>")
	)
	(segment
		(start 370.89969 -182.136288)
		(end 370.898928 -182.135018)
		(width 0.13208)
		(layer "F.Cu")
		(net "UPI_CPU1_CPU0_P0P1_DP<10>")
	)
	(segment
		(start 371.024658 -182.35422)
		(end 370.89969 -182.136288)
		(width 0.13208)
		(layer "F.Cu")
		(net "UPI_CPU1_CPU0_P0P1_DP<10>")
	)
	(segment
		(start 375.168668 -187.343034)
		(end 375.614438 -186.267852)
		(width 0.13208)
		(layer "F.Cu")
		(net "UPI_CPU1_CPU0_P0P1_DP<10>")
	)
	(segment
		(start 373.30253 -215.158574)
		(end 373.30253 -215.087708)
		(width 0.0889)
		(layer "F.Cu")
		(net "UPI_CPU1_CPU0_P0P1_DP<10>")
	)
	(segment
		(start 368.098832 -196.694044)
		(end 369.711986 -192.799716)
		(width 0.13208)
		(layer "F.Cu")
		(net "UPI_CPU1_CPU0_P0P1_DP<10>")
	)
	(segment
		(start 373.67718 -215.158574)
		(end 373.521986 -215.42756)
		(width 0.0889)
		(layer "F.Cu")
		(net "UPI_CPU1_CPU0_P0P1_DP<10>")
	)
	(segment
		(start 373.871744 -213.384384)
		(end 373.772684 -213.285324)
		(width 0.0889)
		(layer "F.Cu")
		(net "UPI_CPU1_CPU0_P0P1_DP<10>")
	)
	(segment
		(start 373.772684 -213.788244)
		(end 373.772684 -213.635844)
		(width 0.0889)
		(layer "F.Cu")
		(net "UPI_CPU1_CPU0_P0P1_DP<10>")
	)
	(segment
		(start 373.772684 -212.18525)
		(end 367.39957 -205.811882)
		(width 0.0889)
		(layer "F.Cu")
		(net "UPI_CPU1_CPU0_P0P1_DP<10>")
	)
	(segment
		(start 373.871744 -213.536784)
		(end 373.871744 -213.384384)
		(width 0.0889)
		(layer "F.Cu")
		(net "UPI_CPU1_CPU0_P0P1_DP<10>")
	)
	(segment
		(start 373.772684 -213.285324)
		(end 373.772684 -212.18525)
		(width 0.0889)
		(layer "F.Cu")
		(net "UPI_CPU1_CPU0_P0P1_DP<10>")
	)
	(segment
		(start 373.871744 -214.039704)
		(end 373.871744 -213.887304)
		(width 0.0889)
		(layer "F.Cu")
		(net "UPI_CPU1_CPU0_P0P1_DP<10>")
	)
	(segment
		(start 373.455692 -214.813896)
		(end 373.492268 -214.79256)
		(width 0.0889)
		(layer "F.Cu")
		(net "UPI_CPU1_CPU0_P0P1_DP<10>")
	)
	(segment
		(start 375.540524 -185.182256)
		(end 374.82018 -184.461912)
		(width 0.13208)
		(layer "F.Cu")
		(net "UPI_CPU1_CPU0_P0P1_DP<10>")
	)
	(segment
		(start 374.82018 -184.461912)
		(end 373.135906 -183.764428)
		(width 0.13208)
		(layer "F.Cu")
		(net "UPI_CPU1_CPU0_P0P1_DP<10>")
	)
	(segment
		(start 373.135906 -183.764428)
		(end 371.024658 -182.35422)
		(width 0.13208)
		(layer "F.Cu")
		(net "UPI_CPU1_CPU0_P0P1_DP<10>")
	)
	(segment
		(start 367.39957 -205.811882)
		(end 367.226088 -205.392528)
		(width 0.0889)
		(layer "F.Cu")
		(net "UPI_CPU1_CPU0_P0P1_DP<10>")
	)
	(segment
		(start 373.772684 -214.138764)
		(end 373.871744 -214.039704)
		(width 0.0889)
		(layer "F.Cu")
		(net "UPI_CPU1_CPU0_P0P1_DP<10>")
	)
	(segment
		(start 375.614438 -185.360818)
		(end 375.540524 -185.182256)
		(width 0.13208)
		(layer "F.Cu")
		(net "UPI_CPU1_CPU0_P0P1_DP<10>")
	)
	(segment
		(start 375.614438 -186.267852)
		(end 375.614438 -185.360818)
		(width 0.13208)
		(layer "F.Cu")
		(net "UPI_CPU1_CPU0_P0P1_DP<10>")
	)
	(arc
		(start 373.30253 -215.087708)
		(mid 373.343424 -214.930841)
		(end 373.455692 -214.813896)
		(width 0.0889)
		(layer "F.Cu")
		(net "UPI_CPU1_CPU0_P0P1_DP<10>")
	)
	(arc
		(start 373.492268 -214.79256)
		(mid 373.697595 -214.58587)
		(end 373.772684 -214.304372)
		(width 0.0889)
		(layer "F.Cu")
		(net "UPI_CPU1_CPU0_P0P1_DP<10>")
	)
	(arc
		(start 373.44096 -215.44915)
		(mid 373.338939 -215.319488)
		(end 373.30253 -215.158574)
		(width 0.0889)
		(layer "F.Cu")
		(net "UPI_CPU1_CPU0_P0P1_DP<10>")
	)
	(segment
		(start 119.392954 -176.79924)
		(end 119.393208 -176.79924)
		(width 0.14732)
		(layer "In6.Cu")
		(net "UPI_CPU1_CPU0_P0P1_DP<10>")
	)
	(segment
		(start 98.288602 -213.133178)
		(end 98.387916 -213.033864)
		(width 0.0889)
		(layer "In6.Cu")
		(net "UPI_CPU1_CPU0_P0P1_DP<10>")
	)
	(segment
		(start 98.387916 -213.033864)
		(end 98.387916 -212.767164)
		(width 0.0889)
		(layer "In6.Cu")
		(net "UPI_CPU1_CPU0_P0P1_DP<10>")
	)
	(segment
		(start 98.013266 -213.732618)
		(end 98.172016 -214.033608)
		(width 0.0889)
		(layer "In6.Cu")
		(net "UPI_CPU1_CPU0_P0P1_DP<10>")
	)
	(segment
		(start 98.346006 -211.229702)
		(end 105.96245 -190.604394)
		(width 0.14732)
		(layer "In6.Cu")
		(net "UPI_CPU1_CPU0_P0P1_DP<10>")
	)
	(segment
		(start 98.346006 -211.793328)
		(end 98.346006 -211.77123)
		(width 0.0889)
		(layer "In6.Cu")
		(net "UPI_CPU1_CPU0_P0P1_DP<10>")
	)
	(segment
		(start 109.681772 -185.940446)
		(end 119.392954 -176.79924)
		(width 0.14732)
		(layer "In6.Cu")
		(net "UPI_CPU1_CPU0_P0P1_DP<10>")
	)
	(segment
		(start 98.387916 -212.301836)
		(end 98.387916 -211.835238)
		(width 0.0889)
		(layer "In6.Cu")
		(net "UPI_CPU1_CPU0_P0P1_DP<10>")
	)
	(segment
		(start 98.288602 -212.66785)
		(end 98.288602 -212.40115)
		(width 0.0889)
		(layer "In6.Cu")
		(net "UPI_CPU1_CPU0_P0P1_DP<10>")
	)
	(segment
		(start 98.172016 -214.033608)
		(end 98.256598 -214.05977)
		(width 0.0889)
		(layer "In6.Cu")
		(net "UPI_CPU1_CPU0_P0P1_DP<10>")
	)
	(segment
		(start 98.387916 -212.767164)
		(end 98.288602 -212.66785)
		(width 0.0889)
		(layer "In6.Cu")
		(net "UPI_CPU1_CPU0_P0P1_DP<10>")
	)
	(segment
		(start 98.288602 -212.40115)
		(end 98.387916 -212.301836)
		(width 0.0889)
		(layer "In6.Cu")
		(net "UPI_CPU1_CPU0_P0P1_DP<10>")
	)
	(segment
		(start 129.110994 -167.652192)
		(end 162.919156 -146.849592)
		(width 0.14732)
		(layer "In6.Cu")
		(net "UPI_CPU1_CPU0_P0P1_DP<10>")
	)
	(segment
		(start 319.259458 -146.564096)
		(end 328.573892 -148.95449)
		(width 0.14732)
		(layer "In6.Cu")
		(net "UPI_CPU1_CPU0_P0P1_DP<10>")
	)
	(segment
		(start 370.506244 -181.437788)
		(end 371.046756 -181.582568)
		(width 0.14732)
		(layer "In6.Cu")
		(net "UPI_CPU1_CPU0_P0P1_DP<10>")
	)
	(segment
		(start 169.869866 -144.4498)
		(end 238.597948 -145.561812)
		(width 0.14732)
		(layer "In6.Cu")
		(net "UPI_CPU1_CPU0_P0P1_DP<10>")
	)
	(segment
		(start 105.96245 -190.604394)
		(end 109.681772 -185.940446)
		(width 0.14732)
		(layer "In6.Cu")
		(net "UPI_CPU1_CPU0_P0P1_DP<10>")
	)
	(segment
		(start 98.387916 -213.499192)
		(end 98.288602 -213.399878)
		(width 0.0889)
		(layer "In6.Cu")
		(net "UPI_CPU1_CPU0_P0P1_DP<10>")
	)
	(segment
		(start 162.919156 -146.849592)
		(end 169.869866 -144.4498)
		(width 0.14732)
		(layer "In6.Cu")
		(net "UPI_CPU1_CPU0_P0P1_DP<10>")
	)
	(segment
		(start 276.124162 -144.886426)
		(end 319.259458 -146.564096)
		(width 0.14732)
		(layer "In6.Cu")
		(net "UPI_CPU1_CPU0_P0P1_DP<10>")
	)
	(segment
		(start 98.346006 -211.77123)
		(end 98.346006 -211.229702)
		(width 0.14732)
		(layer "In6.Cu")
		(net "UPI_CPU1_CPU0_P0P1_DP<10>")
	)
	(segment
		(start 328.573892 -148.95449)
		(end 356.593394 -168.180004)
		(width 0.14732)
		(layer "In6.Cu")
		(net "UPI_CPU1_CPU0_P0P1_DP<10>")
	)
	(segment
		(start 369.151662 -180.714142)
		(end 370.016532 -180.858414)
		(width 0.14732)
		(layer "In6.Cu")
		(net "UPI_CPU1_CPU0_P0P1_DP<10>")
	)
	(segment
		(start 356.593394 -168.180004)
		(end 368.678968 -180.478684)
		(width 0.14732)
		(layer "In6.Cu")
		(net "UPI_CPU1_CPU0_P0P1_DP<10>")
	)
	(segment
		(start 370.383562 -181.225444)
		(end 370.505736 -181.437026)
		(width 0.14732)
		(layer "In6.Cu")
		(net "UPI_CPU1_CPU0_P0P1_DP<10>")
	)
	(segment
		(start 98.288602 -213.399878)
		(end 98.288602 -213.133178)
		(width 0.0889)
		(layer "In6.Cu")
		(net "UPI_CPU1_CPU0_P0P1_DP<10>")
	)
	(segment
		(start 238.597948 -145.561812)
		(end 276.124162 -144.886426)
		(width 0.14732)
		(layer "In6.Cu")
		(net "UPI_CPU1_CPU0_P0P1_DP<10>")
	)
	(segment
		(start 368.678968 -180.478684)
		(end 369.151662 -180.714142)
		(width 0.14732)
		(layer "In6.Cu")
		(net "UPI_CPU1_CPU0_P0P1_DP<10>")
	)
	(segment
		(start 370.505736 -181.437026)
		(end 370.506244 -181.437788)
		(width 0.14732)
		(layer "In6.Cu")
		(net "UPI_CPU1_CPU0_P0P1_DP<10>")
	)
	(segment
		(start 98.387916 -213.8934)
		(end 98.387916 -213.499192)
		(width 0.0889)
		(layer "In6.Cu")
		(net "UPI_CPU1_CPU0_P0P1_DP<10>")
	)
	(segment
		(start 119.393208 -176.79924)
		(end 129.110994 -167.652192)
		(width 0.14732)
		(layer "In6.Cu")
		(net "UPI_CPU1_CPU0_P0P1_DP<10>")
	)
	(segment
		(start 98.387916 -211.835238)
		(end 98.346006 -211.793328)
		(width 0.0889)
		(layer "In6.Cu")
		(net "UPI_CPU1_CPU0_P0P1_DP<10>")
	)
	(segment
		(start 370.016532 -180.858414)
		(end 370.383562 -181.225444)
		(width 0.14732)
		(layer "In6.Cu")
		(net "UPI_CPU1_CPU0_P0P1_DP<10>")
	)
	(arc
		(start 98.256598 -214.05977)
		(mid 98.333271 -213.985276)
		(end 98.387916 -213.8934)
		(width 0.0889)
		(layer "In6.Cu")
		(net "UPI_CPU1_CPU0_P0P1_DP<10>")
	)
	(segment
		(start 380.341378 -202.649836)
		(end 380.625604 -201.221086)
		(width 0.13208)
		(layer "F.Cu")
		(net "UPI_CPU1_CPU0_P0P1_DP<0>")
	)
	(segment
		(start 88.615266 -215.436958)
		(end 88.615012 -215.436704)
		(width 0.13208)
		(layer "F.Cu")
		(net "UPI_CPU1_CPU0_P0P1_DP<0>")
	)
	(segment
		(start 383.675128 -215.378538)
		(end 383.675128 -214.80526)
		(width 0.0889)
		(layer "F.Cu")
		(net "UPI_CPU1_CPU0_P0P1_DP<0>")
	)
	(segment
		(start 381.235966 -199.749156)
		(end 384.454654 -196.530214)
		(width 0.13208)
		(layer "F.Cu")
		(net "UPI_CPU1_CPU0_P0P1_DP<0>")
	)
	(segment
		(start 373.04599 -165.851078)
		(end 371.486938 -167.130476)
		(width 0.13208)
		(layer "F.Cu")
		(net "UPI_CPU1_CPU0_P0P1_DP<0>")
	)
	(segment
		(start 380.341378 -205.205076)
		(end 380.341378 -202.649836)
		(width 0.13208)
		(layer "F.Cu")
		(net "UPI_CPU1_CPU0_P0P1_DP<0>")
	)
	(segment
		(start 383.403094 -215.830404)
		(end 383.403094 -215.650572)
		(width 0.0889)
		(layer "F.Cu")
		(net "UPI_CPU1_CPU0_P0P1_DP<0>")
	)
	(segment
		(start 390.717278 -191.753236)
		(end 390.717278 -187.362084)
		(width 0.13208)
		(layer "F.Cu")
		(net "UPI_CPU1_CPU0_P0P1_DP<0>")
	)
	(segment
		(start 370.898928 -166.895018)
		(end 371.046756 -166.342568)
		(width 0.13208)
		(layer "F.Cu")
		(net "UPI_CPU1_CPU0_P0P1_DP<0>")
	)
	(segment
		(start 383.58064 -214.710772)
		(end 383.58064 -212.02015)
		(width 0.0889)
		(layer "F.Cu")
		(net "UPI_CPU1_CPU0_P0P1_DP<0>")
	)
	(segment
		(start 388.932674 -193.538094)
		(end 390.717278 -191.753236)
		(width 0.13208)
		(layer "F.Cu")
		(net "UPI_CPU1_CPU0_P0P1_DP<0>")
	)
	(segment
		(start 380.306834 -206.407004)
		(end 380.306834 -205.250796)
		(width 0.0889)
		(layer "F.Cu")
		(net "UPI_CPU1_CPU0_P0P1_DP<0>")
	)
	(segment
		(start 384.454654 -196.530214)
		(end 388.932674 -193.538094)
		(width 0.13208)
		(layer "F.Cu")
		(net "UPI_CPU1_CPU0_P0P1_DP<0>")
	)
	(segment
		(start 371.187472 -167.15486)
		(end 370.978684 -167.033956)
		(width 0.13208)
		(layer "F.Cu")
		(net "UPI_CPU1_CPU0_P0P1_DP<0>")
	)
	(segment
		(start 371.486938 -167.130476)
		(end 371.187472 -167.15486)
		(width 0.13208)
		(layer "F.Cu")
		(net "UPI_CPU1_CPU0_P0P1_DP<0>")
	)
	(segment
		(start 386.571744 -177.353976)
		(end 377.499118 -168.281096)
		(width 0.13208)
		(layer "F.Cu")
		(net "UPI_CPU1_CPU0_P0P1_DP<0>")
	)
	(segment
		(start 383.545334 -215.972644)
		(end 383.403094 -215.830404)
		(width 0.0889)
		(layer "F.Cu")
		(net "UPI_CPU1_CPU0_P0P1_DP<0>")
	)
	(segment
		(start 383.403094 -215.650572)
		(end 383.675128 -215.378538)
		(width 0.0889)
		(layer "F.Cu")
		(net "UPI_CPU1_CPU0_P0P1_DP<0>")
	)
	(segment
		(start 370.978684 -167.033956)
		(end 370.89969 -166.896034)
		(width 0.13208)
		(layer "F.Cu")
		(net "UPI_CPU1_CPU0_P0P1_DP<0>")
	)
	(segment
		(start 383.675128 -214.80526)
		(end 383.58064 -214.710772)
		(width 0.0889)
		(layer "F.Cu")
		(net "UPI_CPU1_CPU0_P0P1_DP<0>")
	)
	(segment
		(start 377.499118 -168.281096)
		(end 374.886474 -166.137082)
		(width 0.13208)
		(layer "F.Cu")
		(net "UPI_CPU1_CPU0_P0P1_DP<0>")
	)
	(segment
		(start 382.464818 -209.325718)
		(end 380.84506 -207.70596)
		(width 0.0889)
		(layer "F.Cu")
		(net "UPI_CPU1_CPU0_P0P1_DP<0>")
	)
	(segment
		(start 380.341378 -205.216252)
		(end 380.341378 -205.205076)
		(width 0.0889)
		(layer "F.Cu")
		(net "UPI_CPU1_CPU0_P0P1_DP<0>")
	)
	(segment
		(start 383.58064 -212.02015)
		(end 382.464818 -209.325718)
		(width 0.0889)
		(layer "F.Cu")
		(net "UPI_CPU1_CPU0_P0P1_DP<0>")
	)
	(segment
		(start 374.087644 -165.851078)
		(end 373.04599 -165.851078)
		(width 0.13208)
		(layer "F.Cu")
		(net "UPI_CPU1_CPU0_P0P1_DP<0>")
	)
	(segment
		(start 88.615266 -215.972644)
		(end 88.615266 -215.436958)
		(width 0.13208)
		(layer "F.Cu")
		(net "UPI_CPU1_CPU0_P0P1_DP<0>")
	)
	(segment
		(start 380.625604 -201.221086)
		(end 381.235966 -199.749156)
		(width 0.13208)
		(layer "F.Cu")
		(net "UPI_CPU1_CPU0_P0P1_DP<0>")
	)
	(segment
		(start 374.886474 -166.137082)
		(end 374.087644 -165.851078)
		(width 0.13208)
		(layer "F.Cu")
		(net "UPI_CPU1_CPU0_P0P1_DP<0>")
	)
	(segment
		(start 370.89969 -166.896034)
		(end 370.898928 -166.895018)
		(width 0.13208)
		(layer "F.Cu")
		(net "UPI_CPU1_CPU0_P0P1_DP<0>")
	)
	(segment
		(start 380.84506 -207.70596)
		(end 380.306834 -206.407004)
		(width 0.0889)
		(layer "F.Cu")
		(net "UPI_CPU1_CPU0_P0P1_DP<0>")
	)
	(segment
		(start 390.717278 -187.362084)
		(end 386.571744 -177.353976)
		(width 0.13208)
		(layer "F.Cu")
		(net "UPI_CPU1_CPU0_P0P1_DP<0>")
	)
	(segment
		(start 380.306834 -205.250796)
		(end 380.341378 -205.216252)
		(width 0.0889)
		(layer "F.Cu")
		(net "UPI_CPU1_CPU0_P0P1_DP<0>")
	)
	(segment
		(start 88.88603 -213.58606)
		(end 88.88603 -213.556342)
		(width 0.0889)
		(layer "In6.Cu")
		(net "UPI_CPU1_CPU0_P0P1_DP<0>")
	)
	(segment
		(start 88.615012 -215.436704)
		(end 88.771476 -215.707722)
		(width 0.0889)
		(layer "In6.Cu")
		(net "UPI_CPU1_CPU0_P0P1_DP<0>")
	)
	(segment
		(start 88.519508 -214.636858)
		(end 88.520016 -214.63762)
		(width 0.0889)
		(layer "In6.Cu")
		(net "UPI_CPU1_CPU0_P0P1_DP<0>")
	)
	(segment
		(start 88.88603 -213.556342)
		(end 88.881966 -213.552278)
		(width 0.0889)
		(layer "In6.Cu")
		(net "UPI_CPU1_CPU0_P0P1_DP<0>")
	)
	(segment
		(start 169.407586 -135.619236)
		(end 238.599726 -136.755886)
		(width 0.14732)
		(layer "In6.Cu")
		(net "UPI_CPU1_CPU0_P0P1_DP<0>")
	)
	(segment
		(start 101.84892 -181.291484)
		(end 122.81535 -161.576258)
		(width 0.14732)
		(layer "In6.Cu")
		(net "UPI_CPU1_CPU0_P0P1_DP<0>")
	)
	(segment
		(start 272.314416 -136.14019)
		(end 310.96839 -137.765536)
		(width 0.14732)
		(layer "In6.Cu")
		(net "UPI_CPU1_CPU0_P0P1_DP<0>")
	)
	(segment
		(start 369.840764 -165.492684)
		(end 369.84051 -165.492938)
		(width 0.14732)
		(layer "In6.Cu")
		(net "UPI_CPU1_CPU0_P0P1_DP<0>")
	)
	(segment
		(start 88.782652 -212.894926)
		(end 88.881966 -212.795612)
		(width 0.0889)
		(layer "In6.Cu")
		(net "UPI_CPU1_CPU0_P0P1_DP<0>")
	)
	(segment
		(start 88.782652 -212.162898)
		(end 88.881966 -212.063584)
		(width 0.0889)
		(layer "In6.Cu")
		(net "UPI_CPU1_CPU0_P0P1_DP<0>")
	)
	(segment
		(start 369.84051 -165.492938)
		(end 370.073428 -165.641528)
		(width 0.14732)
		(layer "In6.Cu")
		(net "UPI_CPU1_CPU0_P0P1_DP<0>")
	)
	(segment
		(start 310.96839 -137.765536)
		(end 319.257934 -137.765536)
		(width 0.14732)
		(layer "In6.Cu")
		(net "UPI_CPU1_CPU0_P0P1_DP<0>")
	)
	(segment
		(start 88.840056 -211.567268)
		(end 88.840056 -211.54517)
		(width 0.0889)
		(layer "In6.Cu")
		(net "UPI_CPU1_CPU0_P0P1_DP<0>")
	)
	(segment
		(start 88.881966 -212.795612)
		(end 88.881966 -212.528912)
		(width 0.0889)
		(layer "In6.Cu")
		(net "UPI_CPU1_CPU0_P0P1_DP<0>")
	)
	(segment
		(start 159.50057 -139.011152)
		(end 169.407586 -135.619236)
		(width 0.14732)
		(layer "In6.Cu")
		(net "UPI_CPU1_CPU0_P0P1_DP<0>")
	)
	(segment
		(start 88.840056 -211.54517)
		(end 88.840056 -211.423504)
		(width 0.14732)
		(layer "In6.Cu")
		(net "UPI_CPU1_CPU0_P0P1_DP<0>")
	)
	(segment
		(start 88.771476 -215.707722)
		(end 88.849708 -215.72855)
		(width 0.0889)
		(layer "In6.Cu")
		(net "UPI_CPU1_CPU0_P0P1_DP<0>")
	)
	(segment
		(start 319.257934 -137.765536)
		(end 334.57515 -141.692122)
		(width 0.14732)
		(layer "In6.Cu")
		(net "UPI_CPU1_CPU0_P0P1_DP<0>")
	)
	(segment
		(start 85.14334 -207.08874)
		(end 85.10524 -205.899512)
		(width 0.14732)
		(layer "In6.Cu")
		(net "UPI_CPU1_CPU0_P0P1_DP<0>")
	)
	(segment
		(start 88.881966 -213.552278)
		(end 88.881966 -213.26094)
		(width 0.0889)
		(layer "In6.Cu")
		(net "UPI_CPU1_CPU0_P0P1_DP<0>")
	)
	(segment
		(start 95.668338 -192.085722)
		(end 97.86112 -186.25439)
		(width 0.14732)
		(layer "In6.Cu")
		(net "UPI_CPU1_CPU0_P0P1_DP<0>")
	)
	(segment
		(start 88.520016 -214.63762)
		(end 88.520016 -213.952074)
		(width 0.0889)
		(layer "In6.Cu")
		(net "UPI_CPU1_CPU0_P0P1_DP<0>")
	)
	(segment
		(start 88.881966 -213.26094)
		(end 88.782652 -213.161626)
		(width 0.0889)
		(layer "In6.Cu")
		(net "UPI_CPU1_CPU0_P0P1_DP<0>")
	)
	(segment
		(start 122.81535 -161.576258)
		(end 159.50057 -139.011152)
		(width 0.14732)
		(layer "In6.Cu")
		(net "UPI_CPU1_CPU0_P0P1_DP<0>")
	)
	(segment
		(start 85.69706 -208.280508)
		(end 85.14334 -207.08874)
		(width 0.14732)
		(layer "In6.Cu")
		(net "UPI_CPU1_CPU0_P0P1_DP<0>")
	)
	(segment
		(start 97.86112 -186.25439)
		(end 101.84892 -181.291484)
		(width 0.14732)
		(layer "In6.Cu")
		(net "UPI_CPU1_CPU0_P0P1_DP<0>")
	)
	(segment
		(start 88.520016 -213.952074)
		(end 88.88603 -213.58606)
		(width 0.0889)
		(layer "In6.Cu")
		(net "UPI_CPU1_CPU0_P0P1_DP<0>")
	)
	(segment
		(start 238.599726 -136.755886)
		(end 272.314416 -136.14019)
		(width 0.14732)
		(layer "In6.Cu")
		(net "UPI_CPU1_CPU0_P0P1_DP<0>")
	)
	(segment
		(start 88.881966 -211.609178)
		(end 88.840056 -211.567268)
		(width 0.0889)
		(layer "In6.Cu")
		(net "UPI_CPU1_CPU0_P0P1_DP<0>")
	)
	(segment
		(start 88.8111 -215.117426)
		(end 88.80221 -215.112346)
		(width 0.0889)
		(layer "In6.Cu")
		(net "UPI_CPU1_CPU0_P0P1_DP<0>")
	)
	(segment
		(start 85.10524 -205.899512)
		(end 85.396832 -204.291946)
		(width 0.14732)
		(layer "In6.Cu")
		(net "UPI_CPU1_CPU0_P0P1_DP<0>")
	)
	(segment
		(start 370.506244 -166.197788)
		(end 371.046756 -166.342568)
		(width 0.14732)
		(layer "In6.Cu")
		(net "UPI_CPU1_CPU0_P0P1_DP<0>")
	)
	(segment
		(start 88.881966 -212.528912)
		(end 88.782652 -212.429598)
		(width 0.0889)
		(layer "In6.Cu")
		(net "UPI_CPU1_CPU0_P0P1_DP<0>")
	)
	(segment
		(start 88.881966 -212.063584)
		(end 88.881966 -211.609178)
		(width 0.0889)
		(layer "In6.Cu")
		(net "UPI_CPU1_CPU0_P0P1_DP<0>")
	)
	(segment
		(start 370.073428 -165.641528)
		(end 370.413534 -166.038022)
		(width 0.14732)
		(layer "In6.Cu")
		(net "UPI_CPU1_CPU0_P0P1_DP<0>")
	)
	(segment
		(start 85.396832 -204.291946)
		(end 95.668338 -192.085722)
		(width 0.14732)
		(layer "In6.Cu")
		(net "UPI_CPU1_CPU0_P0P1_DP<0>")
	)
	(segment
		(start 88.782652 -213.161626)
		(end 88.782652 -212.894926)
		(width 0.0889)
		(layer "In6.Cu")
		(net "UPI_CPU1_CPU0_P0P1_DP<0>")
	)
	(segment
		(start 370.505736 -166.197026)
		(end 370.506244 -166.197788)
		(width 0.14732)
		(layer "In6.Cu")
		(net "UPI_CPU1_CPU0_P0P1_DP<0>")
	)
	(segment
		(start 370.413534 -166.038022)
		(end 370.505736 -166.197026)
		(width 0.14732)
		(layer "In6.Cu")
		(net "UPI_CPU1_CPU0_P0P1_DP<0>")
	)
	(segment
		(start 88.840056 -211.423504)
		(end 85.69706 -208.280508)
		(width 0.14732)
		(layer "In6.Cu")
		(net "UPI_CPU1_CPU0_P0P1_DP<0>")
	)
	(segment
		(start 361.468162 -160.145476)
		(end 369.840764 -165.492684)
		(width 0.14732)
		(layer "In6.Cu")
		(net "UPI_CPU1_CPU0_P0P1_DP<0>")
	)
	(segment
		(start 334.57515 -141.692122)
		(end 361.468162 -160.145476)
		(width 0.14732)
		(layer "In6.Cu")
		(net "UPI_CPU1_CPU0_P0P1_DP<0>")
	)
	(segment
		(start 88.782652 -212.429598)
		(end 88.782652 -212.162898)
		(width 0.0889)
		(layer "In6.Cu")
		(net "UPI_CPU1_CPU0_P0P1_DP<0>")
	)
	(arc
		(start 88.849708 -215.72855)
		(mid 88.952853 -215.598525)
		(end 88.989662 -215.436704)
		(width 0.0889)
		(layer "In6.Cu")
		(net "UPI_CPU1_CPU0_P0P1_DP<0>")
	)
	(arc
		(start 88.989662 -215.436704)
		(mid 88.941983 -215.253804)
		(end 88.8111 -215.117426)
		(width 0.0889)
		(layer "In6.Cu")
		(net "UPI_CPU1_CPU0_P0P1_DP<0>")
	)
	(arc
		(start 88.80221 -215.112346)
		(mid 88.598729 -214.911542)
		(end 88.519508 -214.636858)
		(width 0.0889)
		(layer "In6.Cu")
		(net "UPI_CPU1_CPU0_P0P1_DP<0>")
	)
	(segment
		(start 368.309652 -200.998836)
		(end 368.374168 -200.67397)
		(width 0.13208)
		(layer "F.Cu")
		(net "UPI_CPU1_CPU0_P0P1_DN<9>")
	)
	(segment
		(start 374.582182 -212.955124)
		(end 374.582182 -212.209634)
		(width 0.0889)
		(layer "F.Cu")
		(net "UPI_CPU1_CPU0_P0P1_DN<9>")
	)
	(segment
		(start 368.309652 -205.205076)
		(end 368.309652 -200.998836)
		(width 0.13208)
		(layer "F.Cu")
		(net "UPI_CPU1_CPU0_P0P1_DN<9>")
	)
	(segment
		(start 376.678698 -185.12663)
		(end 376.472196 -184.628028)
		(width 0.13208)
		(layer "F.Cu")
		(net "UPI_CPU1_CPU0_P0P1_DN<9>")
	)
	(segment
		(start 374.482868 -213.054438)
		(end 374.582182 -212.955124)
		(width 0.0889)
		(layer "F.Cu")
		(net "UPI_CPU1_CPU0_P0P1_DN<9>")
	)
	(segment
		(start 374.482868 -213.206838)
		(end 374.482868 -213.054438)
		(width 0.0889)
		(layer "F.Cu")
		(net "UPI_CPU1_CPU0_P0P1_DN<9>")
	)
	(segment
		(start 97.543112 -214.622888)
		(end 97.542858 -214.622634)
		(width 0.13208)
		(layer "F.Cu")
		(net "UPI_CPU1_CPU0_P0P1_DN<9>")
	)
	(segment
		(start 368.309652 -205.227174)
		(end 368.309652 -205.205076)
		(width 0.0889)
		(layer "F.Cu")
		(net "UPI_CPU1_CPU0_P0P1_DN<9>")
	)
	(segment
		(start 374.422924 -213.83244)
		(end 374.521984 -213.73338)
		(width 0.0889)
		(layer "F.Cu")
		(net "UPI_CPU1_CPU0_P0P1_DN<9>")
	)
	(segment
		(start 374.581928 -213.397338)
		(end 374.581928 -213.305898)
		(width 0.0889)
		(layer "F.Cu")
		(net "UPI_CPU1_CPU0_P0P1_DN<9>")
	)
	(segment
		(start 374.422924 -213.98484)
		(end 374.422924 -213.83244)
		(width 0.0889)
		(layer "F.Cu")
		(net "UPI_CPU1_CPU0_P0P1_DN<9>")
	)
	(segment
		(start 369.395502 -207.022954)
		(end 368.343942 -205.448662)
		(width 0.0889)
		(layer "F.Cu")
		(net "UPI_CPU1_CPU0_P0P1_DN<9>")
	)
	(segment
		(start 368.374168 -200.67397)
		(end 369.104926 -197.000876)
		(width 0.13208)
		(layer "F.Cu")
		(net "UPI_CPU1_CPU0_P0P1_DN<9>")
	)
	(segment
		(start 374.581928 -213.305898)
		(end 374.482868 -213.206838)
		(width 0.0889)
		(layer "F.Cu")
		(net "UPI_CPU1_CPU0_P0P1_DN<9>")
	)
	(segment
		(start 374.147334 -214.344758)
		(end 374.302528 -214.613744)
		(width 0.0889)
		(layer "F.Cu")
		(net "UPI_CPU1_CPU0_P0P1_DN<9>")
	)
	(segment
		(start 374.521984 -214.0839)
		(end 374.422924 -213.98484)
		(width 0.0889)
		(layer "F.Cu")
		(net "UPI_CPU1_CPU0_P0P1_DN<9>")
	)
	(segment
		(start 373.955818 -182.796942)
		(end 373.955818 -182.43296)
		(width 0.13208)
		(layer "F.Cu")
		(net "UPI_CPU1_CPU0_P0P1_DN<9>")
	)
	(segment
		(start 376.071638 -187.920122)
		(end 376.678698 -186.45505)
		(width 0.13208)
		(layer "F.Cu")
		(net "UPI_CPU1_CPU0_P0P1_DN<9>")
	)
	(segment
		(start 374.054878 -182.261256)
		(end 373.907304 -181.709568)
		(width 0.13208)
		(layer "F.Cu")
		(net "UPI_CPU1_CPU0_P0P1_DN<9>")
	)
	(segment
		(start 374.302528 -214.613744)
		(end 374.383554 -214.635334)
		(width 0.0889)
		(layer "F.Cu")
		(net "UPI_CPU1_CPU0_P0P1_DN<9>")
	)
	(segment
		(start 368.343942 -205.261464)
		(end 368.309652 -205.227174)
		(width 0.0889)
		(layer "F.Cu")
		(net "UPI_CPU1_CPU0_P0P1_DN<9>")
	)
	(segment
		(start 374.582182 -212.209634)
		(end 369.395502 -207.022954)
		(width 0.0889)
		(layer "F.Cu")
		(net "UPI_CPU1_CPU0_P0P1_DN<9>")
	)
	(segment
		(start 376.678698 -186.45505)
		(end 376.678698 -185.12663)
		(width 0.13208)
		(layer "F.Cu")
		(net "UPI_CPU1_CPU0_P0P1_DN<9>")
	)
	(segment
		(start 375.412 -183.567832)
		(end 374.241822 -183.082946)
		(width 0.13208)
		(layer "F.Cu")
		(net "UPI_CPU1_CPU0_P0P1_DN<9>")
	)
	(segment
		(start 373.955818 -182.43296)
		(end 374.054878 -182.261256)
		(width 0.13208)
		(layer "F.Cu")
		(net "UPI_CPU1_CPU0_P0P1_DN<9>")
	)
	(segment
		(start 374.521984 -213.457282)
		(end 374.581928 -213.397338)
		(width 0.0889)
		(layer "F.Cu")
		(net "UPI_CPU1_CPU0_P0P1_DN<9>")
	)
	(segment
		(start 368.343942 -205.448662)
		(end 368.343942 -205.261464)
		(width 0.0889)
		(layer "F.Cu")
		(net "UPI_CPU1_CPU0_P0P1_DN<9>")
	)
	(segment
		(start 374.521984 -214.344758)
		(end 374.521984 -214.0839)
		(width 0.0889)
		(layer "F.Cu")
		(net "UPI_CPU1_CPU0_P0P1_DN<9>")
	)
	(segment
		(start 369.104926 -197.000876)
		(end 370.599462 -193.392298)
		(width 0.13208)
		(layer "F.Cu")
		(net "UPI_CPU1_CPU0_P0P1_DN<9>")
	)
	(segment
		(start 376.472196 -184.628028)
		(end 375.412 -183.567832)
		(width 0.13208)
		(layer "F.Cu")
		(net "UPI_CPU1_CPU0_P0P1_DN<9>")
	)
	(segment
		(start 370.599462 -193.392298)
		(end 376.071638 -187.920122)
		(width 0.13208)
		(layer "F.Cu")
		(net "UPI_CPU1_CPU0_P0P1_DN<9>")
	)
	(segment
		(start 97.543112 -215.158574)
		(end 97.543112 -214.622888)
		(width 0.13208)
		(layer "F.Cu")
		(net "UPI_CPU1_CPU0_P0P1_DN<9>")
	)
	(segment
		(start 374.241822 -183.082946)
		(end 373.955818 -182.796942)
		(width 0.13208)
		(layer "F.Cu")
		(net "UPI_CPU1_CPU0_P0P1_DN<9>")
	)
	(segment
		(start 374.521984 -213.73338)
		(end 374.521984 -213.457282)
		(width 0.0889)
		(layer "F.Cu")
		(net "UPI_CPU1_CPU0_P0P1_DN<9>")
	)
	(arc
		(start 374.383554 -214.635334)
		(mid 374.485575 -214.505672)
		(end 374.521984 -214.344758)
		(width 0.0889)
		(layer "F.Cu")
		(net "UPI_CPU1_CPU0_P0P1_DN<9>")
	)
	(segment
		(start 238.595916 -144.994122)
		(end 275.985478 -144.321022)
		(width 0.14732)
		(layer "In6.Cu")
		(net "UPI_CPU1_CPU0_P0P1_DN<9>")
	)
	(segment
		(start 374.56618 -181.361588)
		(end 374.449086 -181.56428)
		(width 0.14732)
		(layer "In6.Cu")
		(net "UPI_CPU1_CPU0_P0P1_DN<9>")
	)
	(segment
		(start 354.853494 -166.251382)
		(end 355.157278 -166.459916)
		(width 0.14732)
		(layer "In6.Cu")
		(net "UPI_CPU1_CPU0_P0P1_DN<9>")
	)
	(segment
		(start 128.80213 -167.162734)
		(end 162.658552 -146.331178)
		(width 0.14732)
		(layer "In6.Cu")
		(net "UPI_CPU1_CPU0_P0P1_DN<9>")
	)
	(segment
		(start 371.432836 -180.443632)
		(end 371.558566 -180.60543)
		(width 0.14732)
		(layer "In6.Cu")
		(net "UPI_CPU1_CPU0_P0P1_DN<9>")
	)
	(segment
		(start 97.386394 -214.893652)
		(end 97.308162 -214.91448)
		(width 0.0889)
		(layer "In6.Cu")
		(net "UPI_CPU1_CPU0_P0P1_DN<9>")
	)
	(segment
		(start 97.68078 -211.77123)
		(end 97.68078 -211.352892)
		(width 0.14732)
		(layer "In6.Cu")
		(net "UPI_CPU1_CPU0_P0P1_DN<9>")
	)
	(segment
		(start 107.41406 -187.861702)
		(end 107.686856 -187.519818)
		(width 0.14732)
		(layer "In6.Cu")
		(net "UPI_CPU1_CPU0_P0P1_DN<9>")
	)
	(segment
		(start 107.242864 -187.881006)
		(end 107.41406 -187.861702)
		(width 0.14732)
		(layer "In6.Cu")
		(net "UPI_CPU1_CPU0_P0P1_DN<9>")
	)
	(segment
		(start 373.230648 -180.668676)
		(end 374.35409 -180.809138)
		(width 0.14732)
		(layer "In6.Cu")
		(net "UPI_CPU1_CPU0_P0P1_DN<9>")
	)
	(segment
		(start 354.815902 -166.04996)
		(end 354.853494 -166.251382)
		(width 0.14732)
		(layer "In6.Cu")
		(net "UPI_CPU1_CPU0_P0P1_DN<9>")
	)
	(segment
		(start 107.686856 -187.519818)
		(end 107.667552 -187.348368)
		(width 0.14732)
		(layer "In6.Cu")
		(net "UPI_CPU1_CPU0_P0P1_DN<9>")
	)
	(segment
		(start 105.576624 -189.97041)
		(end 105.848912 -189.629034)
		(width 0.14732)
		(layer "In6.Cu")
		(net "UPI_CPU1_CPU0_P0P1_DN<9>")
	)
	(segment
		(start 372.703344 -180.748686)
		(end 373.06885 -180.794406)
		(width 0.14732)
		(layer "In6.Cu")
		(net "UPI_CPU1_CPU0_P0P1_DN<9>")
	)
	(segment
		(start 331.53985 -150.079456)
		(end 354.815902 -166.04996)
		(width 0.14732)
		(layer "In6.Cu")
		(net "UPI_CPU1_CPU0_P0P1_DN<9>")
	)
	(segment
		(start 106.717084 -188.735716)
		(end 106.98988 -188.393832)
		(width 0.14732)
		(layer "In6.Cu")
		(net "UPI_CPU1_CPU0_P0P1_DN<9>")
	)
	(segment
		(start 371.924326 -180.65115)
		(end 372.08587 -180.52542)
		(width 0.14732)
		(layer "In6.Cu")
		(net "UPI_CPU1_CPU0_P0P1_DN<9>")
	)
	(segment
		(start 329.200256 -148.474176)
		(end 330.072492 -149.072854)
		(width 0.14732)
		(layer "In6.Cu")
		(net "UPI_CPU1_CPU0_P0P1_DN<9>")
	)
	(segment
		(start 97.638616 -213.929468)
		(end 97.638616 -213.516972)
		(width 0.0889)
		(layer "In6.Cu")
		(net "UPI_CPU1_CPU0_P0P1_DN<9>")
	)
	(segment
		(start 106.545888 -188.75502)
		(end 106.717084 -188.735716)
		(width 0.14732)
		(layer "In6.Cu")
		(net "UPI_CPU1_CPU0_P0P1_DN<9>")
	)
	(segment
		(start 330.615036 -149.444964)
		(end 330.997306 -149.707346)
		(width 0.14732)
		(layer "In6.Cu")
		(net "UPI_CPU1_CPU0_P0P1_DN<9>")
	)
	(segment
		(start 97.638616 -211.835492)
		(end 97.68078 -211.793328)
		(width 0.0889)
		(layer "In6.Cu")
		(net "UPI_CPU1_CPU0_P0P1_DN<9>")
	)
	(segment
		(start 97.73793 -212.41893)
		(end 97.638616 -212.319616)
		(width 0.0889)
		(layer "In6.Cu")
		(net "UPI_CPU1_CPU0_P0P1_DN<9>")
	)
	(segment
		(start 97.638616 -212.319616)
		(end 97.638616 -211.835492)
		(width 0.0889)
		(layer "In6.Cu")
		(net "UPI_CPU1_CPU0_P0P1_DN<9>")
	)
	(segment
		(start 356.011734 -167.046148)
		(end 356.212902 -167.008556)
		(width 0.14732)
		(layer "In6.Cu")
		(net "UPI_CPU1_CPU0_P0P1_DN<9>")
	)
	(segment
		(start 162.658552 -146.331178)
		(end 169.752518 -143.880332)
		(width 0.14732)
		(layer "In6.Cu")
		(net "UPI_CPU1_CPU0_P0P1_DN<9>")
	)
	(segment
		(start 97.73793 -213.417658)
		(end 97.73793 -213.150958)
		(width 0.0889)
		(layer "In6.Cu")
		(net "UPI_CPU1_CPU0_P0P1_DN<9>")
	)
	(segment
		(start 331.338682 -150.117048)
		(end 331.53985 -150.079456)
		(width 0.14732)
		(layer "In6.Cu")
		(net "UPI_CPU1_CPU0_P0P1_DN<9>")
	)
	(segment
		(start 369.374166 -180.185822)
		(end 371.432836 -180.443632)
		(width 0.14732)
		(layer "In6.Cu")
		(net "UPI_CPU1_CPU0_P0P1_DN<9>")
	)
	(segment
		(start 97.68078 -211.793328)
		(end 97.68078 -211.77123)
		(width 0.0889)
		(layer "In6.Cu")
		(net "UPI_CPU1_CPU0_P0P1_DN<9>")
	)
	(segment
		(start 106.970576 -188.222382)
		(end 107.242864 -187.881006)
		(width 0.14732)
		(layer "In6.Cu")
		(net "UPI_CPU1_CPU0_P0P1_DN<9>")
	)
	(segment
		(start 97.638616 -213.516972)
		(end 97.73793 -213.417658)
		(width 0.0889)
		(layer "In6.Cu")
		(net "UPI_CPU1_CPU0_P0P1_DN<9>")
	)
	(segment
		(start 106.2736 -189.096396)
		(end 106.545888 -188.75502)
		(width 0.14732)
		(layer "In6.Cu")
		(net "UPI_CPU1_CPU0_P0P1_DN<9>")
	)
	(segment
		(start 372.577614 -180.586888)
		(end 372.703344 -180.748686)
		(width 0.14732)
		(layer "In6.Cu")
		(net "UPI_CPU1_CPU0_P0P1_DN<9>")
	)
	(segment
		(start 97.542858 -214.622634)
		(end 97.386394 -214.893652)
		(width 0.0889)
		(layer "In6.Cu")
		(net "UPI_CPU1_CPU0_P0P1_DN<9>")
	)
	(segment
		(start 330.072492 -149.072854)
		(end 330.110084 -149.274276)
		(width 0.14732)
		(layer "In6.Cu")
		(net "UPI_CPU1_CPU0_P0P1_DN<9>")
	)
	(segment
		(start 374.56618 -181.021228)
		(end 374.56618 -181.361588)
		(width 0.14732)
		(layer "In6.Cu")
		(net "UPI_CPU1_CPU0_P0P1_DN<9>")
	)
	(segment
		(start 355.3587 -166.422324)
		(end 355.670358 -166.636192)
		(width 0.14732)
		(layer "In6.Cu")
		(net "UPI_CPU1_CPU0_P0P1_DN<9>")
	)
	(segment
		(start 97.638616 -212.784944)
		(end 97.73793 -212.68563)
		(width 0.0889)
		(layer "In6.Cu")
		(net "UPI_CPU1_CPU0_P0P1_DN<9>")
	)
	(segment
		(start 330.997306 -149.707346)
		(end 331.034898 -149.908514)
		(width 0.14732)
		(layer "In6.Cu")
		(net "UPI_CPU1_CPU0_P0P1_DN<9>")
	)
	(segment
		(start 97.73793 -212.68563)
		(end 97.73793 -212.41893)
		(width 0.0889)
		(layer "In6.Cu")
		(net "UPI_CPU1_CPU0_P0P1_DN<9>")
	)
	(segment
		(start 356.69982 -167.342566)
		(end 369.022376 -179.99583)
		(width 0.14732)
		(layer "In6.Cu")
		(net "UPI_CPU1_CPU0_P0P1_DN<9>")
	)
	(segment
		(start 356.212902 -167.008556)
		(end 356.69982 -167.342566)
		(width 0.14732)
		(layer "In6.Cu")
		(net "UPI_CPU1_CPU0_P0P1_DN<9>")
	)
	(segment
		(start 107.667552 -187.348368)
		(end 108.60024 -186.178698)
		(width 0.14732)
		(layer "In6.Cu")
		(net "UPI_CPU1_CPU0_P0P1_DN<9>")
	)
	(segment
		(start 319.625218 -146.019012)
		(end 329.200256 -148.474176)
		(width 0.14732)
		(layer "In6.Cu")
		(net "UPI_CPU1_CPU0_P0P1_DN<9>")
	)
	(segment
		(start 97.73793 -213.150958)
		(end 97.638616 -213.051644)
		(width 0.0889)
		(layer "In6.Cu")
		(net "UPI_CPU1_CPU0_P0P1_DN<9>")
	)
	(segment
		(start 275.985478 -144.321022)
		(end 319.625218 -146.019012)
		(width 0.14732)
		(layer "In6.Cu")
		(net "UPI_CPU1_CPU0_P0P1_DN<9>")
	)
	(segment
		(start 355.157278 -166.459916)
		(end 355.3587 -166.422324)
		(width 0.14732)
		(layer "In6.Cu")
		(net "UPI_CPU1_CPU0_P0P1_DN<9>")
	)
	(segment
		(start 106.020108 -189.60973)
		(end 106.292904 -189.267846)
		(width 0.14732)
		(layer "In6.Cu")
		(net "UPI_CPU1_CPU0_P0P1_DN<9>")
	)
	(segment
		(start 372.08587 -180.52542)
		(end 372.577614 -180.586888)
		(width 0.14732)
		(layer "In6.Cu")
		(net "UPI_CPU1_CPU0_P0P1_DN<9>")
	)
	(segment
		(start 373.06885 -180.794406)
		(end 373.230648 -180.668676)
		(width 0.14732)
		(layer "In6.Cu")
		(net "UPI_CPU1_CPU0_P0P1_DN<9>")
	)
	(segment
		(start 106.292904 -189.267846)
		(end 106.2736 -189.096396)
		(width 0.14732)
		(layer "In6.Cu")
		(net "UPI_CPU1_CPU0_P0P1_DN<9>")
	)
	(segment
		(start 331.034898 -149.908514)
		(end 331.338682 -150.117048)
		(width 0.14732)
		(layer "In6.Cu")
		(net "UPI_CPU1_CPU0_P0P1_DN<9>")
	)
	(segment
		(start 374.449086 -181.56428)
		(end 373.907304 -181.709568)
		(width 0.14732)
		(layer "In6.Cu")
		(net "UPI_CPU1_CPU0_P0P1_DN<9>")
	)
	(segment
		(start 105.848912 -189.629034)
		(end 106.020108 -189.60973)
		(width 0.14732)
		(layer "In6.Cu")
		(net "UPI_CPU1_CPU0_P0P1_DN<9>")
	)
	(segment
		(start 355.670358 -166.636192)
		(end 355.707696 -166.837614)
		(width 0.14732)
		(layer "In6.Cu")
		(net "UPI_CPU1_CPU0_P0P1_DN<9>")
	)
	(segment
		(start 374.35409 -180.809138)
		(end 374.56618 -181.021228)
		(width 0.14732)
		(layer "In6.Cu")
		(net "UPI_CPU1_CPU0_P0P1_DN<9>")
	)
	(segment
		(start 106.98988 -188.393832)
		(end 106.970576 -188.222382)
		(width 0.14732)
		(layer "In6.Cu")
		(net "UPI_CPU1_CPU0_P0P1_DN<9>")
	)
	(segment
		(start 369.022376 -179.99583)
		(end 369.374166 -180.185822)
		(width 0.14732)
		(layer "In6.Cu")
		(net "UPI_CPU1_CPU0_P0P1_DN<9>")
	)
	(segment
		(start 97.638616 -213.051644)
		(end 97.638616 -212.784944)
		(width 0.0889)
		(layer "In6.Cu")
		(net "UPI_CPU1_CPU0_P0P1_DN<9>")
	)
	(segment
		(start 371.558566 -180.60543)
		(end 371.924326 -180.65115)
		(width 0.14732)
		(layer "In6.Cu")
		(net "UPI_CPU1_CPU0_P0P1_DN<9>")
	)
	(segment
		(start 330.110084 -149.274276)
		(end 330.413868 -149.482556)
		(width 0.14732)
		(layer "In6.Cu")
		(net "UPI_CPU1_CPU0_P0P1_DN<9>")
	)
	(segment
		(start 330.413868 -149.482556)
		(end 330.615036 -149.444964)
		(width 0.14732)
		(layer "In6.Cu")
		(net "UPI_CPU1_CPU0_P0P1_DN<9>")
	)
	(segment
		(start 97.68078 -211.352892)
		(end 105.576624 -189.97041)
		(width 0.14732)
		(layer "In6.Cu")
		(net "UPI_CPU1_CPU0_P0P1_DN<9>")
	)
	(segment
		(start 97.168208 -214.622634)
		(end 97.168208 -214.461852)
		(width 0.0889)
		(layer "In6.Cu")
		(net "UPI_CPU1_CPU0_P0P1_DN<9>")
	)
	(segment
		(start 355.707696 -166.837614)
		(end 356.011734 -167.046148)
		(width 0.14732)
		(layer "In6.Cu")
		(net "UPI_CPU1_CPU0_P0P1_DN<9>")
	)
	(segment
		(start 169.752518 -143.880332)
		(end 238.595916 -144.994122)
		(width 0.14732)
		(layer "In6.Cu")
		(net "UPI_CPU1_CPU0_P0P1_DN<9>")
	)
	(segment
		(start 108.60024 -186.178698)
		(end 128.80213 -167.162734)
		(width 0.14732)
		(layer "In6.Cu")
		(net "UPI_CPU1_CPU0_P0P1_DN<9>")
	)
	(arc
		(start 97.308162 -214.91448)
		(mid 97.205017 -214.784455)
		(end 97.168208 -214.622634)
		(width 0.0889)
		(layer "In6.Cu")
		(net "UPI_CPU1_CPU0_P0P1_DN<9>")
	)
	(arc
		(start 97.352612 -214.261954)
		(mid 97.513193 -214.138523)
		(end 97.623376 -213.968584)
		(width 0.0889)
		(layer "In6.Cu")
		(net "UPI_CPU1_CPU0_P0P1_DN<9>")
	)
	(arc
		(start 97.623376 -213.968584)
		(mid 97.631341 -213.94916)
		(end 97.638616 -213.929468)
		(width 0.0889)
		(layer "In6.Cu")
		(net "UPI_CPU1_CPU0_P0P1_DN<9>")
	)
	(arc
		(start 97.168208 -214.461852)
		(mid 97.243279 -214.34611)
		(end 97.352612 -214.261954)
		(width 0.0889)
		(layer "In6.Cu")
		(net "UPI_CPU1_CPU0_P0P1_DN<9>")
	)
	(segment
		(start 376.340878 -182.592726)
		(end 376.060462 -182.31231)
		(width 0.13208)
		(layer "F.Cu")
		(net "UPI_CPU1_CPU0_P0P1_DN<8>")
	)
	(segment
		(start 375.273824 -214.64397)
		(end 375.274078 -214.643716)
		(width 0.0889)
		(layer "F.Cu")
		(net "UPI_CPU1_CPU0_P0P1_DN<8>")
	)
	(segment
		(start 96.603312 -215.158574)
		(end 96.603312 -214.622888)
		(width 0.13208)
		(layer "F.Cu")
		(net "UPI_CPU1_CPU0_P0P1_DN<8>")
	)
	(segment
		(start 377.994418 -184.761632)
		(end 377.721622 -184.103772)
		(width 0.13208)
		(layer "F.Cu")
		(net "UPI_CPU1_CPU0_P0P1_DN<8>")
	)
	(segment
		(start 374.827546 -181.191408)
		(end 371.286532 -179.889404)
		(width 0.13208)
		(layer "F.Cu")
		(net "UPI_CPU1_CPU0_P0P1_DN<8>")
	)
	(segment
		(start 375.461784 -213.297262)
		(end 375.579386 -213.17966)
		(width 0.0889)
		(layer "F.Cu")
		(net "UPI_CPU1_CPU0_P0P1_DN<8>")
	)
	(segment
		(start 377.721622 -184.103772)
		(end 377.105418 -183.181498)
		(width 0.13208)
		(layer "F.Cu")
		(net "UPI_CPU1_CPU0_P0P1_DN<8>")
	)
	(segment
		(start 96.603312 -214.622888)
		(end 96.603058 -214.622634)
		(width 0.13208)
		(layer "F.Cu")
		(net "UPI_CPU1_CPU0_P0P1_DN<8>")
	)
	(segment
		(start 371.286532 -179.889404)
		(end 370.831872 -179.50561)
		(width 0.13208)
		(layer "F.Cu")
		(net "UPI_CPU1_CPU0_P0P1_DN<8>")
	)
	(segment
		(start 376.060462 -182.13578)
		(end 375.69648 -181.771798)
		(width 0.13208)
		(layer "F.Cu")
		(net "UPI_CPU1_CPU0_P0P1_DN<8>")
	)
	(segment
		(start 375.579386 -212.122258)
		(end 370.186204 -206.729076)
		(width 0.0889)
		(layer "F.Cu")
		(net "UPI_CPU1_CPU0_P0P1_DN<8>")
	)
	(segment
		(start 375.200164 -215.597232)
		(end 375.200418 -215.597232)
		(width 0.0889)
		(layer "F.Cu")
		(net "UPI_CPU1_CPU0_P0P1_DN<8>")
	)
	(segment
		(start 375.262648 -214.65032)
		(end 375.273316 -214.644224)
		(width 0.0889)
		(layer "F.Cu")
		(net "UPI_CPU1_CPU0_P0P1_DN<8>")
	)
	(segment
		(start 369.617498 -205.227174)
		(end 369.617498 -205.205076)
		(width 0.0889)
		(layer "F.Cu")
		(net "UPI_CPU1_CPU0_P0P1_DN<8>")
	)
	(segment
		(start 370.563394 -179.187348)
		(end 370.122704 -179.067968)
		(width 0.13208)
		(layer "F.Cu")
		(net "UPI_CPU1_CPU0_P0P1_DN<8>")
	)
	(segment
		(start 375.087134 -215.972644)
		(end 375.09196 -215.964262)
		(width 0.0889)
		(layer "F.Cu")
		(net "UPI_CPU1_CPU0_P0P1_DN<8>")
	)
	(segment
		(start 370.411756 -197.263258)
		(end 371.710204 -194.128136)
		(width 0.13208)
		(layer "F.Cu")
		(net "UPI_CPU1_CPU0_P0P1_DN<8>")
	)
	(segment
		(start 369.617498 -205.205076)
		(end 369.617498 -201.256392)
		(width 0.13208)
		(layer "F.Cu")
		(net "UPI_CPU1_CPU0_P0P1_DN<8>")
	)
	(segment
		(start 369.651788 -205.261464)
		(end 369.617498 -205.227174)
		(width 0.0889)
		(layer "F.Cu")
		(net "UPI_CPU1_CPU0_P0P1_DN<8>")
	)
	(segment
		(start 374.99163 -215.158828)
		(end 374.99163 -215.133428)
		(width 0.0889)
		(layer "F.Cu")
		(net "UPI_CPU1_CPU0_P0P1_DN<8>")
	)
	(segment
		(start 375.69648 -181.771798)
		(end 374.827546 -181.191408)
		(width 0.13208)
		(layer "F.Cu")
		(net "UPI_CPU1_CPU0_P0P1_DN<8>")
	)
	(segment
		(start 370.668804 -179.222908)
		(end 370.563394 -179.187348)
		(width 0.13208)
		(layer "F.Cu")
		(net "UPI_CPU1_CPU0_P0P1_DN<8>")
	)
	(segment
		(start 376.5169 -182.592726)
		(end 376.340878 -182.592726)
		(width 0.13208)
		(layer "F.Cu")
		(net "UPI_CPU1_CPU0_P0P1_DN<8>")
	)
	(segment
		(start 369.733322 -200.67397)
		(end 370.411756 -197.263258)
		(width 0.13208)
		(layer "F.Cu")
		(net "UPI_CPU1_CPU0_P0P1_DN<8>")
	)
	(segment
		(start 375.274078 -214.643716)
		(end 375.274332 -214.643716)
		(width 0.0889)
		(layer "F.Cu")
		(net "UPI_CPU1_CPU0_P0P1_DN<8>")
	)
	(segment
		(start 377.24715 -188.59119)
		(end 377.994418 -186.78779)
		(width 0.13208)
		(layer "F.Cu")
		(net "UPI_CPU1_CPU0_P0P1_DN<8>")
	)
	(segment
		(start 375.273316 -214.644224)
		(end 375.273824 -214.64397)
		(width 0.0889)
		(layer "F.Cu")
		(net "UPI_CPU1_CPU0_P0P1_DN<8>")
	)
	(segment
		(start 375.461784 -214.319104)
		(end 375.461784 -213.297262)
		(width 0.0889)
		(layer "F.Cu")
		(net "UPI_CPU1_CPU0_P0P1_DN<8>")
	)
	(segment
		(start 371.710204 -194.128136)
		(end 377.24715 -188.59119)
		(width 0.13208)
		(layer "F.Cu")
		(net "UPI_CPU1_CPU0_P0P1_DN<8>")
	)
	(segment
		(start 375.09196 -215.964262)
		(end 375.242328 -215.703658)
		(width 0.0889)
		(layer "F.Cu")
		(net "UPI_CPU1_CPU0_P0P1_DN<8>")
	)
	(segment
		(start 377.994418 -186.78779)
		(end 377.994418 -184.761632)
		(width 0.13208)
		(layer "F.Cu")
		(net "UPI_CPU1_CPU0_P0P1_DN<8>")
	)
	(segment
		(start 369.651788 -205.438502)
		(end 369.651788 -205.261464)
		(width 0.0889)
		(layer "F.Cu")
		(net "UPI_CPU1_CPU0_P0P1_DN<8>")
	)
	(segment
		(start 370.186204 -206.729076)
		(end 369.651788 -205.438502)
		(width 0.0889)
		(layer "F.Cu")
		(net "UPI_CPU1_CPU0_P0P1_DN<8>")
	)
	(segment
		(start 369.617498 -201.256392)
		(end 369.733322 -200.67397)
		(width 0.13208)
		(layer "F.Cu")
		(net "UPI_CPU1_CPU0_P0P1_DN<8>")
	)
	(segment
		(start 375.242328 -215.703658)
		(end 375.217182 -215.610694)
		(width 0.0889)
		(layer "F.Cu")
		(net "UPI_CPU1_CPU0_P0P1_DN<8>")
	)
	(segment
		(start 375.579386 -213.17966)
		(end 375.579386 -212.122258)
		(width 0.0889)
		(layer "F.Cu")
		(net "UPI_CPU1_CPU0_P0P1_DN<8>")
	)
	(segment
		(start 377.105418 -183.181498)
		(end 376.5169 -182.592726)
		(width 0.13208)
		(layer "F.Cu")
		(net "UPI_CPU1_CPU0_P0P1_DN<8>")
	)
	(segment
		(start 370.831872 -179.50561)
		(end 370.668804 -179.222908)
		(width 0.13208)
		(layer "F.Cu")
		(net "UPI_CPU1_CPU0_P0P1_DN<8>")
	)
	(segment
		(start 375.274332 -214.643716)
		(end 375.280682 -214.639906)
		(width 0.0889)
		(layer "F.Cu")
		(net "UPI_CPU1_CPU0_P0P1_DN<8>")
	)
	(segment
		(start 376.060462 -182.31231)
		(end 376.060462 -182.13578)
		(width 0.13208)
		(layer "F.Cu")
		(net "UPI_CPU1_CPU0_P0P1_DN<8>")
	)
	(arc
		(start 375.280682 -214.639906)
		(mid 375.413394 -214.503303)
		(end 375.461784 -214.319104)
		(width 0.0889)
		(layer "F.Cu")
		(net "UPI_CPU1_CPU0_P0P1_DN<8>")
	)
	(arc
		(start 375.200418 -215.597232)
		(mid 375.046531 -215.401598)
		(end 374.99163 -215.158828)
		(width 0.0889)
		(layer "F.Cu")
		(net "UPI_CPU1_CPU0_P0P1_DN<8>")
	)
	(arc
		(start 374.99163 -215.133428)
		(mid 375.063879 -214.85637)
		(end 375.262648 -214.65032)
		(width 0.0889)
		(layer "F.Cu")
		(net "UPI_CPU1_CPU0_P0P1_DN<8>")
	)
	(arc
		(start 375.217182 -215.610694)
		(mid 375.208608 -215.604045)
		(end 375.200164 -215.597232)
		(width 0.0889)
		(layer "F.Cu")
		(net "UPI_CPU1_CPU0_P0P1_DN<8>")
	)
	(segment
		(start 145.32737 -156.01442)
		(end 128.276096 -166.50589)
		(width 0.14732)
		(layer "In6.Cu")
		(net "UPI_CPU1_CPU0_P0P1_DN<8>")
	)
	(segment
		(start 145.32737 -156.014166)
		(end 145.32737 -156.01442)
		(width 0.14732)
		(layer "In6.Cu")
		(net "UPI_CPU1_CPU0_P0P1_DN<8>")
	)
	(segment
		(start 368.503454 -177.653442)
		(end 368.16792 -177.322734)
		(width 0.14732)
		(layer "In6.Cu")
		(net "UPI_CPU1_CPU0_P0P1_DN<8>")
	)
	(segment
		(start 105.400094 -188.833506)
		(end 105.19664 -188.85662)
		(width 0.14732)
		(layer "In6.Cu")
		(net "UPI_CPU1_CPU0_P0P1_DN<8>")
	)
	(segment
		(start 367.700814 -177.065432)
		(end 367.69929 -176.860708)
		(width 0.14732)
		(layer "In6.Cu")
		(net "UPI_CPU1_CPU0_P0P1_DN<8>")
	)
	(segment
		(start 366.706404 -175.881538)
		(end 366.50168 -175.883062)
		(width 0.14732)
		(layer "In6.Cu")
		(net "UPI_CPU1_CPU0_P0P1_DN<8>")
	)
	(segment
		(start 367.69929 -176.860708)
		(end 367.437162 -176.602136)
		(width 0.14732)
		(layer "In6.Cu")
		(net "UPI_CPU1_CPU0_P0P1_DN<8>")
	)
	(segment
		(start 162.37839 -145.522696)
		(end 145.32737 -156.014166)
		(width 0.14732)
		(layer "In6.Cu")
		(net "UPI_CPU1_CPU0_P0P1_DN<8>")
	)
	(segment
		(start 107.201208 -186.343036)
		(end 106.24693 -187.539884)
		(width 0.14732)
		(layer "In6.Cu")
		(net "UPI_CPU1_CPU0_P0P1_DN<8>")
	)
	(segment
		(start 105.836466 -188.054234)
		(end 105.607104 -188.342016)
		(width 0.14732)
		(layer "In6.Cu")
		(net "UPI_CPU1_CPU0_P0P1_DN<8>")
	)
	(segment
		(start 96.698562 -213.93023)
		(end 96.698816 -213.929468)
		(width 0.0889)
		(layer "In6.Cu")
		(net "UPI_CPU1_CPU0_P0P1_DN<8>")
	)
	(segment
		(start 367.232438 -176.60366)
		(end 366.970056 -176.344834)
		(width 0.14732)
		(layer "In6.Cu")
		(net "UPI_CPU1_CPU0_P0P1_DN<8>")
	)
	(segment
		(start 297.921426 -144.333468)
		(end 276.08657 -143.483838)
		(width 0.14732)
		(layer "In6.Cu")
		(net "UPI_CPU1_CPU0_P0P1_DN<8>")
	)
	(segment
		(start 96.698562 -211.835492)
		(end 96.698562 -213.93023)
		(width 0.0889)
		(layer "In6.Cu")
		(net "UPI_CPU1_CPU0_P0P1_DN<8>")
	)
	(segment
		(start 106.040174 -188.03112)
		(end 105.836466 -188.054234)
		(width 0.14732)
		(layer "In6.Cu")
		(net "UPI_CPU1_CPU0_P0P1_DN<8>")
	)
	(segment
		(start 96.444308 -214.321644)
		(end 96.603058 -214.622634)
		(width 0.0889)
		(layer "In6.Cu")
		(net "UPI_CPU1_CPU0_P0P1_DN<8>")
	)
	(segment
		(start 169.563034 -143.041624)
		(end 162.37839 -145.522696)
		(width 0.14732)
		(layer "In6.Cu")
		(net "UPI_CPU1_CPU0_P0P1_DN<8>")
	)
	(segment
		(start 357.763318 -167.063166)
		(end 329.526392 -147.688808)
		(width 0.14732)
		(layer "In6.Cu")
		(net "UPI_CPU1_CPU0_P0P1_DN<8>")
	)
	(segment
		(start 96.474534 -214.22487)
		(end 96.444308 -214.321644)
		(width 0.0889)
		(layer "In6.Cu")
		(net "UPI_CPU1_CPU0_P0P1_DN<8>")
	)
	(segment
		(start 368.99596 -177.858674)
		(end 368.503454 -177.653442)
		(width 0.14732)
		(layer "In6.Cu")
		(net "UPI_CPU1_CPU0_P0P1_DN<8>")
	)
	(segment
		(start 370.267992 -178.52644)
		(end 370.163598 -178.345592)
		(width 0.14732)
		(layer "In6.Cu")
		(net "UPI_CPU1_CPU0_P0P1_DN<8>")
	)
	(segment
		(start 366.239298 -175.624236)
		(end 366.237774 -175.419512)
		(width 0.14732)
		(layer "In6.Cu")
		(net "UPI_CPU1_CPU0_P0P1_DN<8>")
	)
	(segment
		(start 106.26979 -187.743084)
		(end 106.040174 -188.03112)
		(width 0.14732)
		(layer "In6.Cu")
		(net "UPI_CPU1_CPU0_P0P1_DN<8>")
	)
	(segment
		(start 368.16792 -177.322734)
		(end 367.963196 -177.324258)
		(width 0.14732)
		(layer "In6.Cu")
		(net "UPI_CPU1_CPU0_P0P1_DN<8>")
	)
	(segment
		(start 369.603528 -178.112166)
		(end 369.414044 -178.190144)
		(width 0.14732)
		(layer "In6.Cu")
		(net "UPI_CPU1_CPU0_P0P1_DN<8>")
	)
	(segment
		(start 366.970056 -176.344834)
		(end 366.968532 -176.14011)
		(width 0.14732)
		(layer "In6.Cu")
		(net "UPI_CPU1_CPU0_P0P1_DN<8>")
	)
	(segment
		(start 369.073938 -178.048412)
		(end 368.99596 -177.858674)
		(width 0.14732)
		(layer "In6.Cu")
		(net "UPI_CPU1_CPU0_P0P1_DN<8>")
	)
	(segment
		(start 370.122704 -179.067968)
		(end 370.267992 -178.52644)
		(width 0.14732)
		(layer "In6.Cu")
		(net "UPI_CPU1_CPU0_P0P1_DN<8>")
	)
	(segment
		(start 96.740726 -211.240878)
		(end 96.740726 -211.77123)
		(width 0.14732)
		(layer "In6.Cu")
		(net "UPI_CPU1_CPU0_P0P1_DN<8>")
	)
	(segment
		(start 106.24693 -187.539884)
		(end 106.26979 -187.743084)
		(width 0.14732)
		(layer "In6.Cu")
		(net "UPI_CPU1_CPU0_P0P1_DN<8>")
	)
	(segment
		(start 276.08657 -143.483838)
		(end 238.593376 -144.158208)
		(width 0.14732)
		(layer "In6.Cu")
		(net "UPI_CPU1_CPU0_P0P1_DN<8>")
	)
	(segment
		(start 366.50168 -175.883062)
		(end 366.239298 -175.624236)
		(width 0.14732)
		(layer "In6.Cu")
		(net "UPI_CPU1_CPU0_P0P1_DN<8>")
	)
	(segment
		(start 297.921426 -144.333214)
		(end 297.921426 -144.333468)
		(width 0.14732)
		(layer "In6.Cu")
		(net "UPI_CPU1_CPU0_P0P1_DN<8>")
	)
	(segment
		(start 367.963196 -177.324258)
		(end 367.700814 -177.065432)
		(width 0.14732)
		(layer "In6.Cu")
		(net "UPI_CPU1_CPU0_P0P1_DN<8>")
	)
	(segment
		(start 128.276096 -166.50589)
		(end 107.201208 -186.343036)
		(width 0.14732)
		(layer "In6.Cu")
		(net "UPI_CPU1_CPU0_P0P1_DN<8>")
	)
	(segment
		(start 96.740726 -211.77123)
		(end 96.740726 -211.793328)
		(width 0.0889)
		(layer "In6.Cu")
		(net "UPI_CPU1_CPU0_P0P1_DN<8>")
	)
	(segment
		(start 105.629964 -188.54547)
		(end 105.400094 -188.833506)
		(width 0.14732)
		(layer "In6.Cu")
		(net "UPI_CPU1_CPU0_P0P1_DN<8>")
	)
	(segment
		(start 367.437162 -176.602136)
		(end 367.232438 -176.60366)
		(width 0.14732)
		(layer "In6.Cu")
		(net "UPI_CPU1_CPU0_P0P1_DN<8>")
	)
	(segment
		(start 366.237774 -175.419512)
		(end 357.763318 -167.063166)
		(width 0.14732)
		(layer "In6.Cu")
		(net "UPI_CPU1_CPU0_P0P1_DN<8>")
	)
	(segment
		(start 105.607104 -188.342016)
		(end 105.629964 -188.54547)
		(width 0.14732)
		(layer "In6.Cu")
		(net "UPI_CPU1_CPU0_P0P1_DN<8>")
	)
	(segment
		(start 104.842564 -189.300612)
		(end 96.740726 -211.240878)
		(width 0.14732)
		(layer "In6.Cu")
		(net "UPI_CPU1_CPU0_P0P1_DN<8>")
	)
	(segment
		(start 369.414044 -178.190144)
		(end 369.073938 -178.048412)
		(width 0.14732)
		(layer "In6.Cu")
		(net "UPI_CPU1_CPU0_P0P1_DN<8>")
	)
	(segment
		(start 96.740726 -211.793328)
		(end 96.698562 -211.835492)
		(width 0.0889)
		(layer "In6.Cu")
		(net "UPI_CPU1_CPU0_P0P1_DN<8>")
	)
	(segment
		(start 238.593376 -144.158208)
		(end 169.563034 -143.041624)
		(width 0.14732)
		(layer "In6.Cu")
		(net "UPI_CPU1_CPU0_P0P1_DN<8>")
	)
	(segment
		(start 370.163598 -178.345592)
		(end 369.603528 -178.112166)
		(width 0.14732)
		(layer "In6.Cu")
		(net "UPI_CPU1_CPU0_P0P1_DN<8>")
	)
	(segment
		(start 329.526392 -147.688808)
		(end 319.756028 -145.18259)
		(width 0.14732)
		(layer "In6.Cu")
		(net "UPI_CPU1_CPU0_P0P1_DN<8>")
	)
	(segment
		(start 366.968532 -176.14011)
		(end 366.706404 -175.881538)
		(width 0.14732)
		(layer "In6.Cu")
		(net "UPI_CPU1_CPU0_P0P1_DN<8>")
	)
	(segment
		(start 105.19664 -188.85662)
		(end 104.842564 -189.300612)
		(width 0.14732)
		(layer "In6.Cu")
		(net "UPI_CPU1_CPU0_P0P1_DN<8>")
	)
	(segment
		(start 319.756028 -145.18259)
		(end 297.921426 -144.333214)
		(width 0.14732)
		(layer "In6.Cu")
		(net "UPI_CPU1_CPU0_P0P1_DN<8>")
	)
	(arc
		(start 96.698816 -213.929468)
		(mid 96.691658 -213.949028)
		(end 96.68383 -213.96833)
		(width 0.0889)
		(layer "In6.Cu")
		(net "UPI_CPU1_CPU0_P0P1_DN<8>")
	)
	(arc
		(start 96.68383 -213.96833)
		(mid 96.597279 -214.111364)
		(end 96.474534 -214.22487)
		(width 0.0889)
		(layer "In6.Cu")
		(net "UPI_CPU1_CPU0_P0P1_DN<8>")
	)
	(segment
		(start 376.026934 -214.344758)
		(end 376.083322 -214.442548)
		(width 0.0889)
		(layer "F.Cu")
		(net "UPI_CPU1_CPU0_P0P1_DN<7>")
	)
	(segment
		(start 375.478294 -180.036978)
		(end 374.002046 -179.480464)
		(width 0.13208)
		(layer "F.Cu")
		(net "UPI_CPU1_CPU0_P0P1_DN<7>")
	)
	(segment
		(start 379.317758 -184.52973)
		(end 378.574554 -182.735728)
		(width 0.13208)
		(layer "F.Cu")
		(net "UPI_CPU1_CPU0_P0P1_DN<7>")
	)
	(segment
		(start 376.401584 -213.963758)
		(end 376.302524 -213.864698)
		(width 0.0889)
		(layer "F.Cu")
		(net "UPI_CPU1_CPU0_P0P1_DN<7>")
	)
	(segment
		(start 371.552724 -206.999078)
		(end 370.959888 -205.567026)
		(width 0.0889)
		(layer "F.Cu")
		(net "UPI_CPU1_CPU0_P0P1_DN<7>")
	)
	(segment
		(start 378.371862 -189.313058)
		(end 379.317758 -187.029852)
		(width 0.13208)
		(layer "F.Cu")
		(net "UPI_CPU1_CPU0_P0P1_DN<7>")
	)
	(segment
		(start 376.592084 -213.131654)
		(end 376.592084 -212.979254)
		(width 0.0889)
		(layer "F.Cu")
		(net "UPI_CPU1_CPU0_P0P1_DN<7>")
	)
	(segment
		(start 376.493024 -212.727794)
		(end 376.592338 -212.62848)
		(width 0.0889)
		(layer "F.Cu")
		(net "UPI_CPU1_CPU0_P0P1_DN<7>")
	)
	(segment
		(start 376.592338 -212.62848)
		(end 376.592338 -212.038438)
		(width 0.0889)
		(layer "F.Cu")
		(net "UPI_CPU1_CPU0_P0P1_DN<7>")
	)
	(segment
		(start 373.802148 -179.017676)
		(end 374.053608 -178.580288)
		(width 0.13208)
		(layer "F.Cu")
		(net "UPI_CPU1_CPU0_P0P1_DN<7>")
	)
	(segment
		(start 373.839994 -179.279296)
		(end 373.802148 -179.017676)
		(width 0.13208)
		(layer "F.Cu")
		(net "UPI_CPU1_CPU0_P0P1_DN<7>")
	)
	(segment
		(start 378.574554 -182.735728)
		(end 376.67692 -180.83784)
		(width 0.13208)
		(layer "F.Cu")
		(net "UPI_CPU1_CPU0_P0P1_DN<7>")
	)
	(segment
		(start 376.401584 -213.613238)
		(end 376.401584 -213.322154)
		(width 0.0889)
		(layer "F.Cu")
		(net "UPI_CPU1_CPU0_P0P1_DN<7>")
	)
	(segment
		(start 376.182128 -214.613744)
		(end 376.263154 -214.635334)
		(width 0.0889)
		(layer "F.Cu")
		(net "UPI_CPU1_CPU0_P0P1_DN<7>")
	)
	(segment
		(start 374.054878 -178.578256)
		(end 373.907304 -178.026568)
		(width 0.13208)
		(layer "F.Cu")
		(net "UPI_CPU1_CPU0_P0P1_DN<7>")
	)
	(segment
		(start 374.05437 -178.578764)
		(end 374.054878 -178.578256)
		(width 0.13208)
		(layer "F.Cu")
		(net "UPI_CPU1_CPU0_P0P1_DN<7>")
	)
	(segment
		(start 374.053608 -178.580288)
		(end 374.054116 -178.579526)
		(width 0.13208)
		(layer "F.Cu")
		(net "UPI_CPU1_CPU0_P0P1_DN<7>")
	)
	(segment
		(start 374.002046 -179.480464)
		(end 373.839994 -179.279296)
		(width 0.13208)
		(layer "F.Cu")
		(net "UPI_CPU1_CPU0_P0P1_DN<7>")
	)
	(segment
		(start 376.401584 -214.345012)
		(end 376.401584 -213.963758)
		(width 0.0889)
		(layer "F.Cu")
		(net "UPI_CPU1_CPU0_P0P1_DN<7>")
	)
	(segment
		(start 372.937786 -194.747134)
		(end 378.371862 -189.313058)
		(width 0.13208)
		(layer "F.Cu")
		(net "UPI_CPU1_CPU0_P0P1_DN<7>")
	)
	(segment
		(start 370.959888 -205.261464)
		(end 370.925598 -205.227174)
		(width 0.0889)
		(layer "F.Cu")
		(net "UPI_CPU1_CPU0_P0P1_DN<7>")
	)
	(segment
		(start 376.592084 -212.979254)
		(end 376.493024 -212.880194)
		(width 0.0889)
		(layer "F.Cu")
		(net "UPI_CPU1_CPU0_P0P1_DN<7>")
	)
	(segment
		(start 370.925598 -205.205076)
		(end 370.925598 -201.469244)
		(width 0.13208)
		(layer "F.Cu")
		(net "UPI_CPU1_CPU0_P0P1_DN<7>")
	)
	(segment
		(start 370.959888 -205.567026)
		(end 370.959888 -205.261464)
		(width 0.0889)
		(layer "F.Cu")
		(net "UPI_CPU1_CPU0_P0P1_DN<7>")
	)
	(segment
		(start 379.317758 -187.029852)
		(end 379.317758 -184.52973)
		(width 0.13208)
		(layer "F.Cu")
		(net "UPI_CPU1_CPU0_P0P1_DN<7>")
	)
	(segment
		(start 376.493024 -212.880194)
		(end 376.493024 -212.727794)
		(width 0.0889)
		(layer "F.Cu")
		(net "UPI_CPU1_CPU0_P0P1_DN<7>")
	)
	(segment
		(start 376.302524 -213.864698)
		(end 376.302524 -213.712298)
		(width 0.0889)
		(layer "F.Cu")
		(net "UPI_CPU1_CPU0_P0P1_DN<7>")
	)
	(segment
		(start 376.401584 -213.322154)
		(end 376.592084 -213.131654)
		(width 0.0889)
		(layer "F.Cu")
		(net "UPI_CPU1_CPU0_P0P1_DN<7>")
	)
	(segment
		(start 95.663512 -214.622888)
		(end 95.663258 -214.622634)
		(width 0.13208)
		(layer "F.Cu")
		(net "UPI_CPU1_CPU0_P0P1_DN<7>")
	)
	(segment
		(start 376.67692 -180.83784)
		(end 375.478294 -180.036978)
		(width 0.13208)
		(layer "F.Cu")
		(net "UPI_CPU1_CPU0_P0P1_DN<7>")
	)
	(segment
		(start 376.302524 -213.712298)
		(end 376.401584 -213.613238)
		(width 0.0889)
		(layer "F.Cu")
		(net "UPI_CPU1_CPU0_P0P1_DN<7>")
	)
	(segment
		(start 95.663512 -215.158574)
		(end 95.663512 -214.622888)
		(width 0.13208)
		(layer "F.Cu")
		(net "UPI_CPU1_CPU0_P0P1_DN<7>")
	)
	(segment
		(start 370.925598 -201.469244)
		(end 371.08384 -200.67397)
		(width 0.13208)
		(layer "F.Cu")
		(net "UPI_CPU1_CPU0_P0P1_DN<7>")
	)
	(segment
		(start 376.083322 -214.442548)
		(end 376.182128 -214.613744)
		(width 0.0889)
		(layer "F.Cu")
		(net "UPI_CPU1_CPU0_P0P1_DN<7>")
	)
	(segment
		(start 370.925598 -205.227174)
		(end 370.925598 -205.205076)
		(width 0.0889)
		(layer "F.Cu")
		(net "UPI_CPU1_CPU0_P0P1_DN<7>")
	)
	(segment
		(start 374.054116 -178.579526)
		(end 374.05437 -178.578764)
		(width 0.13208)
		(layer "F.Cu")
		(net "UPI_CPU1_CPU0_P0P1_DN<7>")
	)
	(segment
		(start 371.08384 -200.67397)
		(end 371.63883 -197.883272)
		(width 0.13208)
		(layer "F.Cu")
		(net "UPI_CPU1_CPU0_P0P1_DN<7>")
	)
	(segment
		(start 371.63883 -197.883272)
		(end 372.937786 -194.747134)
		(width 0.13208)
		(layer "F.Cu")
		(net "UPI_CPU1_CPU0_P0P1_DN<7>")
	)
	(segment
		(start 376.592338 -212.038438)
		(end 371.552724 -206.999078)
		(width 0.0889)
		(layer "F.Cu")
		(net "UPI_CPU1_CPU0_P0P1_DN<7>")
	)
	(arc
		(start 376.263154 -214.635334)
		(mid 376.36512 -214.505786)
		(end 376.401584 -214.345012)
		(width 0.0889)
		(layer "F.Cu")
		(net "UPI_CPU1_CPU0_P0P1_DN<7>")
	)
	(segment
		(start 319.766188 -144.321784)
		(end 330.438252 -147.058634)
		(width 0.14732)
		(layer "In6.Cu")
		(net "UPI_CPU1_CPU0_P0P1_DN<7>")
	)
	(segment
		(start 333.491586 -149.153626)
		(end 333.795116 -149.361906)
		(width 0.14732)
		(layer "In6.Cu")
		(net "UPI_CPU1_CPU0_P0P1_DN<7>")
	)
	(segment
		(start 374.192546 -177.056288)
		(end 374.435624 -177.154332)
		(width 0.14732)
		(layer "In6.Cu")
		(net "UPI_CPU1_CPU0_P0P1_DN<7>")
	)
	(segment
		(start 332.375256 -148.563584)
		(end 332.576678 -148.525992)
		(width 0.14732)
		(layer "In6.Cu")
		(net "UPI_CPU1_CPU0_P0P1_DN<7>")
	)
	(segment
		(start 95.288608 -214.622634)
		(end 95.288608 -214.461852)
		(width 0.0889)
		(layer "In6.Cu")
		(net "UPI_CPU1_CPU0_P0P1_DN<7>")
	)
	(segment
		(start 368.986308 -176.954942)
		(end 369.435634 -177.143156)
		(width 0.14732)
		(layer "In6.Cu")
		(net "UPI_CPU1_CPU0_P0P1_DN<7>")
	)
	(segment
		(start 104.902762 -187.876434)
		(end 104.883458 -187.704984)
		(width 0.14732)
		(layer "In6.Cu")
		(net "UPI_CPU1_CPU0_P0P1_DN<7>")
	)
	(segment
		(start 372.887748 -177.080164)
		(end 374.192546 -177.056288)
		(width 0.14732)
		(layer "In6.Cu")
		(net "UPI_CPU1_CPU0_P0P1_DN<7>")
	)
	(segment
		(start 106.27741 -185.95721)
		(end 106.719116 -185.403236)
		(width 0.14732)
		(layer "In6.Cu")
		(net "UPI_CPU1_CPU0_P0P1_DN<7>")
	)
	(segment
		(start 371.861588 -177.09896)
		(end 372.230142 -177.092356)
		(width 0.14732)
		(layer "In6.Cu")
		(net "UPI_CPU1_CPU0_P0P1_DN<7>")
	)
	(segment
		(start 334.337914 -149.73427)
		(end 357.900732 -165.90137)
		(width 0.14732)
		(layer "In6.Cu")
		(net "UPI_CPU1_CPU0_P0P1_DN<7>")
	)
	(segment
		(start 332.03388 -148.153628)
		(end 332.071472 -148.35505)
		(width 0.14732)
		(layer "In6.Cu")
		(net "UPI_CPU1_CPU0_P0P1_DN<7>")
	)
	(segment
		(start 238.59109 -143.316198)
		(end 276.429978 -142.635732)
		(width 0.14732)
		(layer "In6.Cu")
		(net "UPI_CPU1_CPU0_P0P1_DN<7>")
	)
	(segment
		(start 374.59158 -177.310288)
		(end 374.59158 -177.634646)
		(width 0.14732)
		(layer "In6.Cu")
		(net "UPI_CPU1_CPU0_P0P1_DN<7>")
	)
	(segment
		(start 162.123882 -144.69491)
		(end 169.357294 -142.196566)
		(width 0.14732)
		(layer "In6.Cu")
		(net "UPI_CPU1_CPU0_P0P1_DN<7>")
	)
	(segment
		(start 374.435624 -177.154332)
		(end 374.59158 -177.310288)
		(width 0.14732)
		(layer "In6.Cu")
		(net "UPI_CPU1_CPU0_P0P1_DN<7>")
	)
	(segment
		(start 332.576678 -148.525992)
		(end 332.948788 -148.781262)
		(width 0.14732)
		(layer "In6.Cu")
		(net "UPI_CPU1_CPU0_P0P1_DN<7>")
	)
	(segment
		(start 371.203728 -177.110898)
		(end 371.351302 -177.253138)
		(width 0.14732)
		(layer "In6.Cu")
		(net "UPI_CPU1_CPU0_P0P1_DN<7>")
	)
	(segment
		(start 331.225144 -147.774406)
		(end 331.529182 -147.982686)
		(width 0.14732)
		(layer "In6.Cu")
		(net "UPI_CPU1_CPU0_P0P1_DN<7>")
	)
	(segment
		(start 105.580434 -186.83097)
		(end 105.852722 -186.489594)
		(width 0.14732)
		(layer "In6.Cu")
		(net "UPI_CPU1_CPU0_P0P1_DN<7>")
	)
	(segment
		(start 104.186482 -188.578998)
		(end 104.45877 -188.237622)
		(width 0.14732)
		(layer "In6.Cu")
		(net "UPI_CPU1_CPU0_P0P1_DN<7>")
	)
	(segment
		(start 332.98638 -148.982938)
		(end 333.290164 -149.191218)
		(width 0.14732)
		(layer "In6.Cu")
		(net "UPI_CPU1_CPU0_P0P1_DN<7>")
	)
	(segment
		(start 371.719602 -177.24628)
		(end 371.861588 -177.09896)
		(width 0.14732)
		(layer "In6.Cu")
		(net "UPI_CPU1_CPU0_P0P1_DN<7>")
	)
	(segment
		(start 104.883458 -187.704984)
		(end 105.155746 -187.363608)
		(width 0.14732)
		(layer "In6.Cu")
		(net "UPI_CPU1_CPU0_P0P1_DN<7>")
	)
	(segment
		(start 333.832708 -149.563328)
		(end 334.136492 -149.771862)
		(width 0.14732)
		(layer "In6.Cu")
		(net "UPI_CPU1_CPU0_P0P1_DN<7>")
	)
	(segment
		(start 95.759016 -213.051644)
		(end 95.759016 -212.784944)
		(width 0.0889)
		(layer "In6.Cu")
		(net "UPI_CPU1_CPU0_P0P1_DN<7>")
	)
	(segment
		(start 332.071472 -148.35505)
		(end 332.375256 -148.563584)
		(width 0.14732)
		(layer "In6.Cu")
		(net "UPI_CPU1_CPU0_P0P1_DN<7>")
	)
	(segment
		(start 331.187806 -147.57273)
		(end 331.225144 -147.774406)
		(width 0.14732)
		(layer "In6.Cu")
		(net "UPI_CPU1_CPU0_P0P1_DN<7>")
	)
	(segment
		(start 330.438252 -147.058634)
		(end 331.187806 -147.57273)
		(width 0.14732)
		(layer "In6.Cu")
		(net "UPI_CPU1_CPU0_P0P1_DN<7>")
	)
	(segment
		(start 105.326942 -187.344304)
		(end 105.599738 -187.00242)
		(width 0.14732)
		(layer "In6.Cu")
		(net "UPI_CPU1_CPU0_P0P1_DN<7>")
	)
	(segment
		(start 127.022606 -166.29253)
		(end 162.123882 -144.69491)
		(width 0.14732)
		(layer "In6.Cu")
		(net "UPI_CPU1_CPU0_P0P1_DN<7>")
	)
	(segment
		(start 369.435634 -177.143156)
		(end 371.203728 -177.110898)
		(width 0.14732)
		(layer "In6.Cu")
		(net "UPI_CPU1_CPU0_P0P1_DN<7>")
	)
	(segment
		(start 95.80118 -211.77123)
		(end 95.80118 -211.289392)
		(width 0.14732)
		(layer "In6.Cu")
		(net "UPI_CPU1_CPU0_P0P1_DN<7>")
	)
	(segment
		(start 95.85833 -212.68563)
		(end 95.85833 -212.41893)
		(width 0.0889)
		(layer "In6.Cu")
		(net "UPI_CPU1_CPU0_P0P1_DN<7>")
	)
	(segment
		(start 106.024172 -186.47029)
		(end 106.296714 -186.128406)
		(width 0.14732)
		(layer "In6.Cu")
		(net "UPI_CPU1_CPU0_P0P1_DN<7>")
	)
	(segment
		(start 332.948788 -148.781262)
		(end 332.98638 -148.982938)
		(width 0.14732)
		(layer "In6.Cu")
		(net "UPI_CPU1_CPU0_P0P1_DN<7>")
	)
	(segment
		(start 106.296714 -186.128406)
		(end 106.27741 -185.95721)
		(width 0.14732)
		(layer "In6.Cu")
		(net "UPI_CPU1_CPU0_P0P1_DN<7>")
	)
	(segment
		(start 95.759016 -212.319616)
		(end 95.759016 -211.835492)
		(width 0.0889)
		(layer "In6.Cu")
		(net "UPI_CPU1_CPU0_P0P1_DN<7>")
	)
	(segment
		(start 334.136492 -149.771862)
		(end 334.337914 -149.73427)
		(width 0.14732)
		(layer "In6.Cu")
		(net "UPI_CPU1_CPU0_P0P1_DN<7>")
	)
	(segment
		(start 105.155746 -187.363608)
		(end 105.326942 -187.344304)
		(width 0.14732)
		(layer "In6.Cu")
		(net "UPI_CPU1_CPU0_P0P1_DN<7>")
	)
	(segment
		(start 95.759016 -213.516972)
		(end 95.85833 -213.417658)
		(width 0.0889)
		(layer "In6.Cu")
		(net "UPI_CPU1_CPU0_P0P1_DN<7>")
	)
	(segment
		(start 371.351302 -177.253138)
		(end 371.719602 -177.24628)
		(width 0.14732)
		(layer "In6.Cu")
		(net "UPI_CPU1_CPU0_P0P1_DN<7>")
	)
	(segment
		(start 169.357294 -142.196566)
		(end 238.59109 -143.316198)
		(width 0.14732)
		(layer "In6.Cu")
		(net "UPI_CPU1_CPU0_P0P1_DN<7>")
	)
	(segment
		(start 372.230142 -177.092356)
		(end 372.377462 -177.234342)
		(width 0.14732)
		(layer "In6.Cu")
		(net "UPI_CPU1_CPU0_P0P1_DN<7>")
	)
	(segment
		(start 333.795116 -149.361906)
		(end 333.832708 -149.563328)
		(width 0.14732)
		(layer "In6.Cu")
		(net "UPI_CPU1_CPU0_P0P1_DN<7>")
	)
	(segment
		(start 333.290164 -149.191218)
		(end 333.491586 -149.153626)
		(width 0.14732)
		(layer "In6.Cu")
		(net "UPI_CPU1_CPU0_P0P1_DN<7>")
	)
	(segment
		(start 95.80118 -211.289392)
		(end 104.186482 -188.578998)
		(width 0.14732)
		(layer "In6.Cu")
		(net "UPI_CPU1_CPU0_P0P1_DN<7>")
	)
	(segment
		(start 357.900732 -165.90137)
		(end 368.986308 -176.954942)
		(width 0.14732)
		(layer "In6.Cu")
		(net "UPI_CPU1_CPU0_P0P1_DN<7>")
	)
	(segment
		(start 372.377462 -177.234342)
		(end 372.745762 -177.227484)
		(width 0.14732)
		(layer "In6.Cu")
		(net "UPI_CPU1_CPU0_P0P1_DN<7>")
	)
	(segment
		(start 95.759016 -211.835492)
		(end 95.80118 -211.793328)
		(width 0.0889)
		(layer "In6.Cu")
		(net "UPI_CPU1_CPU0_P0P1_DN<7>")
	)
	(segment
		(start 95.85833 -213.417658)
		(end 95.85833 -213.150958)
		(width 0.0889)
		(layer "In6.Cu")
		(net "UPI_CPU1_CPU0_P0P1_DN<7>")
	)
	(segment
		(start 95.85833 -212.41893)
		(end 95.759016 -212.319616)
		(width 0.0889)
		(layer "In6.Cu")
		(net "UPI_CPU1_CPU0_P0P1_DN<7>")
	)
	(segment
		(start 95.506794 -214.893652)
		(end 95.428562 -214.91448)
		(width 0.0889)
		(layer "In6.Cu")
		(net "UPI_CPU1_CPU0_P0P1_DN<7>")
	)
	(segment
		(start 374.59158 -177.634646)
		(end 374.449086 -177.88128)
		(width 0.14732)
		(layer "In6.Cu")
		(net "UPI_CPU1_CPU0_P0P1_DN<7>")
	)
	(segment
		(start 374.449086 -177.88128)
		(end 373.907304 -178.026568)
		(width 0.14732)
		(layer "In6.Cu")
		(net "UPI_CPU1_CPU0_P0P1_DN<7>")
	)
	(segment
		(start 331.529182 -147.982686)
		(end 331.73035 -147.945348)
		(width 0.14732)
		(layer "In6.Cu")
		(net "UPI_CPU1_CPU0_P0P1_DN<7>")
	)
	(segment
		(start 105.599738 -187.00242)
		(end 105.580434 -186.83097)
		(width 0.14732)
		(layer "In6.Cu")
		(net "UPI_CPU1_CPU0_P0P1_DN<7>")
	)
	(segment
		(start 95.663258 -214.622634)
		(end 95.506794 -214.893652)
		(width 0.0889)
		(layer "In6.Cu")
		(net "UPI_CPU1_CPU0_P0P1_DN<7>")
	)
	(segment
		(start 276.429978 -142.635732)
		(end 319.766188 -144.321784)
		(width 0.14732)
		(layer "In6.Cu")
		(net "UPI_CPU1_CPU0_P0P1_DN<7>")
	)
	(segment
		(start 372.745762 -177.227484)
		(end 372.887748 -177.080164)
		(width 0.14732)
		(layer "In6.Cu")
		(net "UPI_CPU1_CPU0_P0P1_DN<7>")
	)
	(segment
		(start 95.80118 -211.793328)
		(end 95.80118 -211.77123)
		(width 0.0889)
		(layer "In6.Cu")
		(net "UPI_CPU1_CPU0_P0P1_DN<7>")
	)
	(segment
		(start 104.45877 -188.237622)
		(end 104.629966 -188.218318)
		(width 0.14732)
		(layer "In6.Cu")
		(net "UPI_CPU1_CPU0_P0P1_DN<7>")
	)
	(segment
		(start 106.719116 -185.403236)
		(end 127.022606 -166.29253)
		(width 0.14732)
		(layer "In6.Cu")
		(net "UPI_CPU1_CPU0_P0P1_DN<7>")
	)
	(segment
		(start 331.73035 -147.945348)
		(end 332.03388 -148.153628)
		(width 0.14732)
		(layer "In6.Cu")
		(net "UPI_CPU1_CPU0_P0P1_DN<7>")
	)
	(segment
		(start 95.759016 -213.929468)
		(end 95.759016 -213.516972)
		(width 0.0889)
		(layer "In6.Cu")
		(net "UPI_CPU1_CPU0_P0P1_DN<7>")
	)
	(segment
		(start 105.852722 -186.489594)
		(end 106.024172 -186.47029)
		(width 0.14732)
		(layer "In6.Cu")
		(net "UPI_CPU1_CPU0_P0P1_DN<7>")
	)
	(segment
		(start 95.759016 -212.784944)
		(end 95.85833 -212.68563)
		(width 0.0889)
		(layer "In6.Cu")
		(net "UPI_CPU1_CPU0_P0P1_DN<7>")
	)
	(segment
		(start 104.629966 -188.218318)
		(end 104.902762 -187.876434)
		(width 0.14732)
		(layer "In6.Cu")
		(net "UPI_CPU1_CPU0_P0P1_DN<7>")
	)
	(segment
		(start 95.85833 -213.150958)
		(end 95.759016 -213.051644)
		(width 0.0889)
		(layer "In6.Cu")
		(net "UPI_CPU1_CPU0_P0P1_DN<7>")
	)
	(arc
		(start 95.288608 -214.461852)
		(mid 95.363679 -214.34611)
		(end 95.473012 -214.261954)
		(width 0.0889)
		(layer "In6.Cu")
		(net "UPI_CPU1_CPU0_P0P1_DN<7>")
	)
	(arc
		(start 95.428562 -214.91448)
		(mid 95.325417 -214.784455)
		(end 95.288608 -214.622634)
		(width 0.0889)
		(layer "In6.Cu")
		(net "UPI_CPU1_CPU0_P0P1_DN<7>")
	)
	(arc
		(start 95.743776 -213.968584)
		(mid 95.751741 -213.94916)
		(end 95.759016 -213.929468)
		(width 0.0889)
		(layer "In6.Cu")
		(net "UPI_CPU1_CPU0_P0P1_DN<7>")
	)
	(arc
		(start 95.473012 -214.261954)
		(mid 95.633593 -214.138523)
		(end 95.743776 -213.968584)
		(width 0.0889)
		(layer "In6.Cu")
		(net "UPI_CPU1_CPU0_P0P1_DN<7>")
	)
	(segment
		(start 374.338596 -195.55968)
		(end 379.72238 -190.175896)
		(width 0.13208)
		(layer "F.Cu")
		(net "UPI_CPU1_CPU0_P0P1_DN<6>")
	)
	(segment
		(start 377.240292 -214.813896)
		(end 377.247658 -214.809578)
		(width 0.0889)
		(layer "F.Cu")
		(net "UPI_CPU1_CPU0_P0P1_DN<6>")
	)
	(segment
		(start 381.177038 -184.918604)
		(end 379.90145 -181.838854)
		(width 0.13208)
		(layer "F.Cu")
		(net "UPI_CPU1_CPU0_P0P1_DN<6>")
	)
	(segment
		(start 372.492778 -205.205076)
		(end 372.492778 -201.62012)
		(width 0.13208)
		(layer "F.Cu")
		(net "UPI_CPU1_CPU0_P0P1_DN<6>")
	)
	(segment
		(start 372.492778 -205.227174)
		(end 372.492778 -205.205076)
		(width 0.0889)
		(layer "F.Cu")
		(net "UPI_CPU1_CPU0_P0P1_DN<6>")
	)
	(segment
		(start 377.630944 -213.780116)
		(end 377.630944 -213.627716)
		(width 0.0889)
		(layer "F.Cu")
		(net "UPI_CPU1_CPU0_P0P1_DN<6>")
	)
	(segment
		(start 374.853962 -177.162206)
		(end 371.416834 -176.477676)
		(width 0.13208)
		(layer "F.Cu")
		(net "UPI_CPU1_CPU0_P0P1_DN<6>")
	)
	(segment
		(start 377.778772 -211.855304)
		(end 373.020082 -207.096614)
		(width 0.0889)
		(layer "F.Cu")
		(net "UPI_CPU1_CPU0_P0P1_DN<6>")
	)
	(segment
		(start 377.630944 -213.627716)
		(end 377.531884 -213.528656)
		(width 0.0889)
		(layer "F.Cu")
		(net "UPI_CPU1_CPU0_P0P1_DN<6>")
	)
	(segment
		(start 377.531884 -213.376256)
		(end 377.778772 -213.129368)
		(width 0.0889)
		(layer "F.Cu")
		(net "UPI_CPU1_CPU0_P0P1_DN<6>")
	)
	(segment
		(start 377.531884 -214.319104)
		(end 377.531884 -213.879176)
		(width 0.0889)
		(layer "F.Cu")
		(net "UPI_CPU1_CPU0_P0P1_DN<6>")
	)
	(segment
		(start 371.416834 -176.477676)
		(end 371.020594 -176.22139)
		(width 0.13208)
		(layer "F.Cu")
		(net "UPI_CPU1_CPU0_P0P1_DN<6>")
	)
	(segment
		(start 372.458234 -205.740762)
		(end 372.458234 -205.261718)
		(width 0.0889)
		(layer "F.Cu")
		(net "UPI_CPU1_CPU0_P0P1_DN<6>")
	)
	(segment
		(start 373.020082 -207.096614)
		(end 372.458234 -205.740762)
		(width 0.0889)
		(layer "F.Cu")
		(net "UPI_CPU1_CPU0_P0P1_DN<6>")
	)
	(segment
		(start 377.247658 -214.809578)
		(end 377.249182 -214.808816)
		(width 0.0889)
		(layer "F.Cu")
		(net "UPI_CPU1_CPU0_P0P1_DN<6>")
	)
	(segment
		(start 377.531884 -213.879176)
		(end 377.630944 -213.780116)
		(width 0.0889)
		(layer "F.Cu")
		(net "UPI_CPU1_CPU0_P0P1_DN<6>")
	)
	(segment
		(start 379.72238 -190.175896)
		(end 381.177038 -186.664092)
		(width 0.13208)
		(layer "F.Cu")
		(net "UPI_CPU1_CPU0_P0P1_DN<6>")
	)
	(segment
		(start 373.10695 -198.533258)
		(end 374.338596 -195.55968)
		(width 0.13208)
		(layer "F.Cu")
		(net "UPI_CPU1_CPU0_P0P1_DN<6>")
	)
	(segment
		(start 377.877832 -212.641688)
		(end 377.778772 -212.542628)
		(width 0.0889)
		(layer "F.Cu")
		(net "UPI_CPU1_CPU0_P0P1_DN<6>")
	)
	(segment
		(start 372.458234 -205.261718)
		(end 372.492778 -205.227174)
		(width 0.0889)
		(layer "F.Cu")
		(net "UPI_CPU1_CPU0_P0P1_DN<6>")
	)
	(segment
		(start 370.898928 -176.039018)
		(end 371.046756 -175.486568)
		(width 0.13208)
		(layer "F.Cu")
		(net "UPI_CPU1_CPU0_P0P1_DN<6>")
	)
	(segment
		(start 375.972578 -177.909728)
		(end 374.853962 -177.162206)
		(width 0.13208)
		(layer "F.Cu")
		(net "UPI_CPU1_CPU0_P0P1_DN<6>")
	)
	(segment
		(start 379.90145 -181.838854)
		(end 375.972578 -177.909728)
		(width 0.13208)
		(layer "F.Cu")
		(net "UPI_CPU1_CPU0_P0P1_DN<6>")
	)
	(segment
		(start 377.778772 -213.129368)
		(end 377.778772 -212.893148)
		(width 0.0889)
		(layer "F.Cu")
		(net "UPI_CPU1_CPU0_P0P1_DN<6>")
	)
	(segment
		(start 377.249182 -214.808816)
		(end 377.251468 -214.807546)
		(width 0.0889)
		(layer "F.Cu")
		(net "UPI_CPU1_CPU0_P0P1_DN<6>")
	)
	(segment
		(start 377.281186 -215.42756)
		(end 377.20016 -215.44915)
		(width 0.0889)
		(layer "F.Cu")
		(net "UPI_CPU1_CPU0_P0P1_DN<6>")
	)
	(segment
		(start 372.680992 -200.67397)
		(end 373.10695 -198.533258)
		(width 0.13208)
		(layer "F.Cu")
		(net "UPI_CPU1_CPU0_P0P1_DN<6>")
	)
	(segment
		(start 94.254066 -214.344758)
		(end 94.254066 -213.732618)
		(width 0.13208)
		(layer "F.Cu")
		(net "UPI_CPU1_CPU0_P0P1_DN<6>")
	)
	(segment
		(start 377.531884 -213.528656)
		(end 377.531884 -213.376256)
		(width 0.0889)
		(layer "F.Cu")
		(net "UPI_CPU1_CPU0_P0P1_DN<6>")
	)
	(segment
		(start 377.778772 -212.893148)
		(end 377.877832 -212.794088)
		(width 0.0889)
		(layer "F.Cu")
		(net "UPI_CPU1_CPU0_P0P1_DN<6>")
	)
	(segment
		(start 372.492778 -201.62012)
		(end 372.680992 -200.67397)
		(width 0.13208)
		(layer "F.Cu")
		(net "UPI_CPU1_CPU0_P0P1_DN<6>")
	)
	(segment
		(start 377.43638 -215.158574)
		(end 377.281186 -215.42756)
		(width 0.0889)
		(layer "F.Cu")
		(net "UPI_CPU1_CPU0_P0P1_DN<6>")
	)
	(segment
		(start 381.177038 -186.664092)
		(end 381.177038 -184.918604)
		(width 0.13208)
		(layer "F.Cu")
		(net "UPI_CPU1_CPU0_P0P1_DN<6>")
	)
	(segment
		(start 377.06173 -215.158574)
		(end 377.06173 -215.133174)
		(width 0.0889)
		(layer "F.Cu")
		(net "UPI_CPU1_CPU0_P0P1_DN<6>")
	)
	(segment
		(start 377.778772 -212.542628)
		(end 377.778772 -211.855304)
		(width 0.0889)
		(layer "F.Cu")
		(net "UPI_CPU1_CPU0_P0P1_DN<6>")
	)
	(segment
		(start 377.877832 -212.794088)
		(end 377.877832 -212.641688)
		(width 0.0889)
		(layer "F.Cu")
		(net "UPI_CPU1_CPU0_P0P1_DN<6>")
	)
	(segment
		(start 371.020594 -176.22139)
		(end 370.898928 -176.039018)
		(width 0.13208)
		(layer "F.Cu")
		(net "UPI_CPU1_CPU0_P0P1_DN<6>")
	)
	(arc
		(start 377.20016 -215.44915)
		(mid 377.098139 -215.319488)
		(end 377.06173 -215.158574)
		(width 0.0889)
		(layer "F.Cu")
		(net "UPI_CPU1_CPU0_P0P1_DN<6>")
	)
	(arc
		(start 377.251468 -214.807546)
		(mid 377.456777 -214.600704)
		(end 377.531884 -214.319104)
		(width 0.0889)
		(layer "F.Cu")
		(net "UPI_CPU1_CPU0_P0P1_DN<6>")
	)
	(arc
		(start 377.06173 -215.133174)
		(mid 377.109409 -214.950274)
		(end 377.240292 -214.813896)
		(width 0.0889)
		(layer "F.Cu")
		(net "UPI_CPU1_CPU0_P0P1_DN<6>")
	)
	(segment
		(start 330.880974 -146.017234)
		(end 319.95745 -143.215106)
		(width 0.14732)
		(layer "In6.Cu")
		(net "UPI_CPU1_CPU0_P0P1_DN<6>")
	)
	(segment
		(start 94.628716 -212.165946)
		(end 94.628716 -212.301836)
		(width 0.0889)
		(layer "In6.Cu")
		(net "UPI_CPU1_CPU0_P0P1_DN<6>")
	)
	(segment
		(start 370.366798 -175.100488)
		(end 369.991386 -174.868586)
		(width 0.14732)
		(layer "In6.Cu")
		(net "UPI_CPU1_CPU0_P0P1_DN<6>")
	)
	(segment
		(start 105.630726 -184.750456)
		(end 103.345996 -187.615322)
		(width 0.14732)
		(layer "In6.Cu")
		(net "UPI_CPU1_CPU0_P0P1_DN<6>")
	)
	(segment
		(start 94.529402 -212.66785)
		(end 94.628716 -212.767164)
		(width 0.0889)
		(layer "In6.Cu")
		(net "UPI_CPU1_CPU0_P0P1_DN<6>")
	)
	(segment
		(start 94.628716 -213.499192)
		(end 94.628716 -213.8934)
		(width 0.0889)
		(layer "In6.Cu")
		(net "UPI_CPU1_CPU0_P0P1_DN<6>")
	)
	(segment
		(start 94.529402 -213.133178)
		(end 94.529402 -213.399878)
		(width 0.0889)
		(layer "In6.Cu")
		(net "UPI_CPU1_CPU0_P0P1_DN<6>")
	)
	(segment
		(start 369.991386 -174.868586)
		(end 369.000532 -174.676816)
		(width 0.14732)
		(layer "In6.Cu")
		(net "UPI_CPU1_CPU0_P0P1_DN<6>")
	)
	(segment
		(start 94.529402 -212.40115)
		(end 94.529402 -212.66785)
		(width 0.0889)
		(layer "In6.Cu")
		(net "UPI_CPU1_CPU0_P0P1_DN<6>")
	)
	(segment
		(start 103.345996 -187.615322)
		(end 94.586806 -211.339684)
		(width 0.14732)
		(layer "In6.Cu")
		(net "UPI_CPU1_CPU0_P0P1_DN<6>")
	)
	(segment
		(start 94.628716 -212.301836)
		(end 94.529402 -212.40115)
		(width 0.0889)
		(layer "In6.Cu")
		(net "UPI_CPU1_CPU0_P0P1_DN<6>")
	)
	(segment
		(start 370.506244 -175.341788)
		(end 370.505736 -175.341026)
		(width 0.14732)
		(layer "In6.Cu")
		(net "UPI_CPU1_CPU0_P0P1_DN<6>")
	)
	(segment
		(start 238.590074 -142.10157)
		(end 169.333926 -140.981938)
		(width 0.14732)
		(layer "In6.Cu")
		(net "UPI_CPU1_CPU0_P0P1_DN<6>")
	)
	(segment
		(start 94.412816 -214.033608)
		(end 94.254066 -213.732618)
		(width 0.0889)
		(layer "In6.Cu")
		(net "UPI_CPU1_CPU0_P0P1_DN<6>")
	)
	(segment
		(start 319.95745 -143.215106)
		(end 276.755606 -141.415262)
		(width 0.14732)
		(layer "In6.Cu")
		(net "UPI_CPU1_CPU0_P0P1_DN<6>")
	)
	(segment
		(start 94.529402 -213.399878)
		(end 94.628716 -213.499192)
		(width 0.0889)
		(layer "In6.Cu")
		(net "UPI_CPU1_CPU0_P0P1_DN<6>")
	)
	(segment
		(start 169.333926 -140.981938)
		(end 161.788094 -143.586962)
		(width 0.14732)
		(layer "In6.Cu")
		(net "UPI_CPU1_CPU0_P0P1_DN<6>")
	)
	(segment
		(start 94.628716 -212.767164)
		(end 94.628716 -213.033864)
		(width 0.0889)
		(layer "In6.Cu")
		(net "UPI_CPU1_CPU0_P0P1_DN<6>")
	)
	(segment
		(start 94.586806 -211.339684)
		(end 94.586806 -212.101938)
		(width 0.14732)
		(layer "In6.Cu")
		(net "UPI_CPU1_CPU0_P0P1_DN<6>")
	)
	(segment
		(start 371.046756 -175.486568)
		(end 370.506244 -175.341788)
		(width 0.14732)
		(layer "In6.Cu")
		(net "UPI_CPU1_CPU0_P0P1_DN<6>")
	)
	(segment
		(start 359.145078 -165.40861)
		(end 330.880974 -146.017234)
		(width 0.14732)
		(layer "In6.Cu")
		(net "UPI_CPU1_CPU0_P0P1_DN<6>")
	)
	(segment
		(start 94.586806 -212.101938)
		(end 94.586806 -212.124036)
		(width 0.0889)
		(layer "In6.Cu")
		(net "UPI_CPU1_CPU0_P0P1_DN<6>")
	)
	(segment
		(start 94.497398 -214.05977)
		(end 94.412816 -214.033608)
		(width 0.0889)
		(layer "In6.Cu")
		(net "UPI_CPU1_CPU0_P0P1_DN<6>")
	)
	(segment
		(start 161.788094 -143.586962)
		(end 125.907038 -165.664896)
		(width 0.14732)
		(layer "In6.Cu")
		(net "UPI_CPU1_CPU0_P0P1_DN<6>")
	)
	(segment
		(start 370.505736 -175.341026)
		(end 370.366798 -175.100488)
		(width 0.14732)
		(layer "In6.Cu")
		(net "UPI_CPU1_CPU0_P0P1_DN<6>")
	)
	(segment
		(start 369.000532 -174.676816)
		(end 368.2619 -174.249842)
		(width 0.14732)
		(layer "In6.Cu")
		(net "UPI_CPU1_CPU0_P0P1_DN<6>")
	)
	(segment
		(start 94.586806 -212.124036)
		(end 94.628716 -212.165946)
		(width 0.0889)
		(layer "In6.Cu")
		(net "UPI_CPU1_CPU0_P0P1_DN<6>")
	)
	(segment
		(start 368.2619 -174.249842)
		(end 359.145078 -165.40861)
		(width 0.14732)
		(layer "In6.Cu")
		(net "UPI_CPU1_CPU0_P0P1_DN<6>")
	)
	(segment
		(start 125.907038 -165.664896)
		(end 105.630726 -184.750456)
		(width 0.14732)
		(layer "In6.Cu")
		(net "UPI_CPU1_CPU0_P0P1_DN<6>")
	)
	(segment
		(start 276.755606 -141.415262)
		(end 238.590074 -142.10157)
		(width 0.14732)
		(layer "In6.Cu")
		(net "UPI_CPU1_CPU0_P0P1_DN<6>")
	)
	(segment
		(start 94.628716 -213.033864)
		(end 94.529402 -213.133178)
		(width 0.0889)
		(layer "In6.Cu")
		(net "UPI_CPU1_CPU0_P0P1_DN<6>")
	)
	(arc
		(start 94.628716 -213.8934)
		(mid 94.574046 -213.985256)
		(end 94.497398 -214.05977)
		(width 0.0889)
		(layer "In6.Cu")
		(net "UPI_CPU1_CPU0_P0P1_DN<6>")
	)
	(segment
		(start 377.906534 -214.344758)
		(end 378.061728 -214.613744)
		(width 0.0889)
		(layer "F.Cu")
		(net "UPI_CPU1_CPU0_P0P1_DN<5>")
	)
	(segment
		(start 378.061728 -214.613744)
		(end 378.142754 -214.635334)
		(width 0.0889)
		(layer "F.Cu")
		(net "UPI_CPU1_CPU0_P0P1_DN<5>")
	)
	(segment
		(start 378.285502 -211.394802)
		(end 374.461532 -207.570832)
		(width 0.0889)
		(layer "F.Cu")
		(net "UPI_CPU1_CPU0_P0P1_DN<5>")
	)
	(segment
		(start 382.231138 -186.854592)
		(end 382.231138 -184.719976)
		(width 0.13208)
		(layer "F.Cu")
		(net "UPI_CPU1_CPU0_P0P1_DN<5>")
	)
	(segment
		(start 373.541798 -201.812144)
		(end 373.546624 -201.807318)
		(width 0.13208)
		(layer "F.Cu")
		(net "UPI_CPU1_CPU0_P0P1_DN<5>")
	)
	(segment
		(start 373.86006 -175.670718)
		(end 373.86006 -175.282098)
		(width 0.13208)
		(layer "F.Cu")
		(net "UPI_CPU1_CPU0_P0P1_DN<5>")
	)
	(segment
		(start 378.182124 -213.712298)
		(end 378.281438 -213.612984)
		(width 0.0889)
		(layer "F.Cu")
		(net "UPI_CPU1_CPU0_P0P1_DN<5>")
	)
	(segment
		(start 378.281184 -213.963758)
		(end 378.182124 -213.864698)
		(width 0.0889)
		(layer "F.Cu")
		(net "UPI_CPU1_CPU0_P0P1_DN<5>")
	)
	(segment
		(start 378.498354 -211.908644)
		(end 378.285502 -211.394802)
		(width 0.0889)
		(layer "F.Cu")
		(net "UPI_CPU1_CPU0_P0P1_DN<5>")
	)
	(segment
		(start 378.281184 -214.345012)
		(end 378.281184 -213.963758)
		(width 0.0889)
		(layer "F.Cu")
		(net "UPI_CPU1_CPU0_P0P1_DN<5>")
	)
	(segment
		(start 378.4981 -213.053168)
		(end 378.4981 -212.68436)
		(width 0.0889)
		(layer "F.Cu")
		(net "UPI_CPU1_CPU0_P0P1_DN<5>")
	)
	(segment
		(start 378.4981 -212.68436)
		(end 378.39904 -212.5853)
		(width 0.0889)
		(layer "F.Cu")
		(net "UPI_CPU1_CPU0_P0P1_DN<5>")
	)
	(segment
		(start 373.576088 -205.261464)
		(end 373.541798 -205.227174)
		(width 0.0889)
		(layer "F.Cu")
		(net "UPI_CPU1_CPU0_P0P1_DN<5>")
	)
	(segment
		(start 373.938292 -175.097948)
		(end 374.054878 -174.895256)
		(width 0.13208)
		(layer "F.Cu")
		(net "UPI_CPU1_CPU0_P0P1_DN<5>")
	)
	(segment
		(start 373.541798 -205.205076)
		(end 373.541798 -201.812144)
		(width 0.13208)
		(layer "F.Cu")
		(net "UPI_CPU1_CPU0_P0P1_DN<5>")
	)
	(segment
		(start 375.356628 -196.02196)
		(end 380.609602 -190.768986)
		(width 0.13208)
		(layer "F.Cu")
		(net "UPI_CPU1_CPU0_P0P1_DN<5>")
	)
	(segment
		(start 93.783912 -215.158574)
		(end 93.783912 -214.622888)
		(width 0.13208)
		(layer "F.Cu")
		(net "UPI_CPU1_CPU0_P0P1_DN<5>")
	)
	(segment
		(start 374.088914 -199.082152)
		(end 375.356628 -196.02196)
		(width 0.13208)
		(layer "F.Cu")
		(net "UPI_CPU1_CPU0_P0P1_DN<5>")
	)
	(segment
		(start 373.576088 -205.433676)
		(end 373.576088 -205.261464)
		(width 0.0889)
		(layer "F.Cu")
		(net "UPI_CPU1_CPU0_P0P1_DN<5>")
	)
	(segment
		(start 378.498354 -212.333586)
		(end 378.498354 -211.908644)
		(width 0.0889)
		(layer "F.Cu")
		(net "UPI_CPU1_CPU0_P0P1_DN<5>")
	)
	(segment
		(start 378.182124 -213.864698)
		(end 378.182124 -213.712298)
		(width 0.0889)
		(layer "F.Cu")
		(net "UPI_CPU1_CPU0_P0P1_DN<5>")
	)
	(segment
		(start 380.787402 -181.234588)
		(end 376.664982 -177.112168)
		(width 0.13208)
		(layer "F.Cu")
		(net "UPI_CPU1_CPU0_P0P1_DN<5>")
	)
	(segment
		(start 380.609602 -190.768986)
		(end 382.231138 -186.854592)
		(width 0.13208)
		(layer "F.Cu")
		(net "UPI_CPU1_CPU0_P0P1_DN<5>")
	)
	(segment
		(start 378.281438 -213.26983)
		(end 378.4981 -213.053168)
		(width 0.0889)
		(layer "F.Cu")
		(net "UPI_CPU1_CPU0_P0P1_DN<5>")
	)
	(segment
		(start 378.39904 -212.4329)
		(end 378.498354 -212.333586)
		(width 0.0889)
		(layer "F.Cu")
		(net "UPI_CPU1_CPU0_P0P1_DN<5>")
	)
	(segment
		(start 373.546624 -201.807318)
		(end 374.088914 -199.082152)
		(width 0.13208)
		(layer "F.Cu")
		(net "UPI_CPU1_CPU0_P0P1_DN<5>")
	)
	(segment
		(start 374.054878 -174.895256)
		(end 373.907304 -174.343568)
		(width 0.13208)
		(layer "F.Cu")
		(net "UPI_CPU1_CPU0_P0P1_DN<5>")
	)
	(segment
		(start 374.461532 -207.570832)
		(end 373.576088 -205.433676)
		(width 0.0889)
		(layer "F.Cu")
		(net "UPI_CPU1_CPU0_P0P1_DN<5>")
	)
	(segment
		(start 382.231138 -184.719976)
		(end 380.787402 -181.234588)
		(width 0.13208)
		(layer "F.Cu")
		(net "UPI_CPU1_CPU0_P0P1_DN<5>")
	)
	(segment
		(start 373.86006 -175.282098)
		(end 373.938292 -175.097948)
		(width 0.13208)
		(layer "F.Cu")
		(net "UPI_CPU1_CPU0_P0P1_DN<5>")
	)
	(segment
		(start 373.541798 -205.227174)
		(end 373.541798 -205.205076)
		(width 0.0889)
		(layer "F.Cu")
		(net "UPI_CPU1_CPU0_P0P1_DN<5>")
	)
	(segment
		(start 378.281438 -213.612984)
		(end 378.281438 -213.26983)
		(width 0.0889)
		(layer "F.Cu")
		(net "UPI_CPU1_CPU0_P0P1_DN<5>")
	)
	(segment
		(start 93.783912 -214.622888)
		(end 93.783658 -214.622634)
		(width 0.13208)
		(layer "F.Cu")
		(net "UPI_CPU1_CPU0_P0P1_DN<5>")
	)
	(segment
		(start 374.158002 -175.943768)
		(end 373.86006 -175.670718)
		(width 0.13208)
		(layer "F.Cu")
		(net "UPI_CPU1_CPU0_P0P1_DN<5>")
	)
	(segment
		(start 376.664982 -177.112168)
		(end 375.224548 -176.150778)
		(width 0.13208)
		(layer "F.Cu")
		(net "UPI_CPU1_CPU0_P0P1_DN<5>")
	)
	(segment
		(start 375.224548 -176.150778)
		(end 374.158002 -175.943768)
		(width 0.13208)
		(layer "F.Cu")
		(net "UPI_CPU1_CPU0_P0P1_DN<5>")
	)
	(segment
		(start 378.39904 -212.5853)
		(end 378.39904 -212.4329)
		(width 0.0889)
		(layer "F.Cu")
		(net "UPI_CPU1_CPU0_P0P1_DN<5>")
	)
	(arc
		(start 378.142754 -214.635334)
		(mid 378.24472 -214.505786)
		(end 378.281184 -214.345012)
		(width 0.0889)
		(layer "F.Cu")
		(net "UPI_CPU1_CPU0_P0P1_DN<5>")
	)
	(segment
		(start 125.504448 -165.247066)
		(end 105.145586 -184.409842)
		(width 0.14732)
		(layer "In6.Cu")
		(net "UPI_CPU1_CPU0_P0P1_DN<5>")
	)
	(segment
		(start 371.89156 -173.815248)
		(end 371.530626 -173.88967)
		(width 0.14732)
		(layer "In6.Cu")
		(net "UPI_CPU1_CPU0_P0P1_DN<5>")
	)
	(segment
		(start 93.879416 -212.784944)
		(end 93.879416 -213.051644)
		(width 0.0889)
		(layer "In6.Cu")
		(net "UPI_CPU1_CPU0_P0P1_DN<5>")
	)
	(segment
		(start 358.960674 -164.350192)
		(end 335.342484 -148.14677)
		(width 0.14732)
		(layer "In6.Cu")
		(net "UPI_CPU1_CPU0_P0P1_DN<5>")
	)
	(segment
		(start 332.18374 -146.15541)
		(end 332.146402 -145.953734)
		(width 0.14732)
		(layer "In6.Cu")
		(net "UPI_CPU1_CPU0_P0P1_DN<5>")
	)
	(segment
		(start 93.97873 -213.417658)
		(end 93.879416 -213.516972)
		(width 0.0889)
		(layer "In6.Cu")
		(net "UPI_CPU1_CPU0_P0P1_DN<5>")
	)
	(segment
		(start 333.934308 -147.356322)
		(end 333.896716 -147.1549)
		(width 0.14732)
		(layer "In6.Cu")
		(net "UPI_CPU1_CPU0_P0P1_DN<5>")
	)
	(segment
		(start 94.378526 -210.122516)
		(end 94.251018 -210.46821)
		(width 0.14732)
		(layer "In6.Cu")
		(net "UPI_CPU1_CPU0_P0P1_DN<5>")
	)
	(segment
		(start 105.145586 -184.409842)
		(end 102.485952 -187.744862)
		(width 0.14732)
		(layer "In6.Cu")
		(net "UPI_CPU1_CPU0_P0P1_DN<5>")
	)
	(segment
		(start 369.195096 -174.13732)
		(end 368.615214 -173.788832)
		(width 0.14732)
		(layer "In6.Cu")
		(net "UPI_CPU1_CPU0_P0P1_DN<5>")
	)
	(segment
		(start 332.6892 -146.326352)
		(end 332.487778 -146.36369)
		(width 0.14732)
		(layer "In6.Cu")
		(net "UPI_CPU1_CPU0_P0P1_DN<5>")
	)
	(segment
		(start 169.492422 -140.318236)
		(end 161.577274 -143.051022)
		(width 0.14732)
		(layer "In6.Cu")
		(net "UPI_CPU1_CPU0_P0P1_DN<5>")
	)
	(segment
		(start 94.064582 -210.555586)
		(end 93.92158 -210.94192)
		(width 0.14732)
		(layer "In6.Cu")
		(net "UPI_CPU1_CPU0_P0P1_DN<5>")
	)
	(segment
		(start 238.589566 -141.435582)
		(end 169.492422 -140.318236)
		(width 0.14732)
		(layer "In6.Cu")
		(net "UPI_CPU1_CPU0_P0P1_DN<5>")
	)
	(segment
		(start 374.56364 -173.999906)
		(end 374.56364 -173.614588)
		(width 0.14732)
		(layer "In6.Cu")
		(net "UPI_CPU1_CPU0_P0P1_DN<5>")
	)
	(segment
		(start 334.439514 -147.527264)
		(end 334.238092 -147.564856)
		(width 0.14732)
		(layer "In6.Cu")
		(net "UPI_CPU1_CPU0_P0P1_DN<5>")
	)
	(segment
		(start 319.635124 -142.544038)
		(end 317.266828 -142.544038)
		(width 0.14732)
		(layer "In6.Cu")
		(net "UPI_CPU1_CPU0_P0P1_DN<5>")
	)
	(segment
		(start 102.485952 -187.744862)
		(end 95.178372 -207.53832)
		(width 0.14732)
		(layer "In6.Cu")
		(net "UPI_CPU1_CPU0_P0P1_DN<5>")
	)
	(segment
		(start 93.879416 -212.319616)
		(end 93.97873 -212.41893)
		(width 0.0889)
		(layer "In6.Cu")
		(net "UPI_CPU1_CPU0_P0P1_DN<5>")
	)
	(segment
		(start 333.593186 -146.94662)
		(end 333.392018 -146.984212)
		(width 0.14732)
		(layer "In6.Cu")
		(net "UPI_CPU1_CPU0_P0P1_DN<5>")
	)
	(segment
		(start 95.136462 -208.069942)
		(end 94.95028 -208.15554)
		(width 0.14732)
		(layer "In6.Cu")
		(net "UPI_CPU1_CPU0_P0P1_DN<5>")
	)
	(segment
		(start 93.97873 -212.68563)
		(end 93.879416 -212.784944)
		(width 0.0889)
		(layer "In6.Cu")
		(net "UPI_CPU1_CPU0_P0P1_DN<5>")
	)
	(segment
		(start 373.907304 -174.343568)
		(end 374.449086 -174.19828)
		(width 0.14732)
		(layer "In6.Cu")
		(net "UPI_CPU1_CPU0_P0P1_DN<5>")
	)
	(segment
		(start 374.3071 -173.358048)
		(end 373.97436 -173.238668)
		(width 0.14732)
		(layer "In6.Cu")
		(net "UPI_CPU1_CPU0_P0P1_DN<5>")
	)
	(segment
		(start 94.95028 -208.15554)
		(end 94.648274 -208.973674)
		(width 0.14732)
		(layer "In6.Cu")
		(net "UPI_CPU1_CPU0_P0P1_DN<5>")
	)
	(segment
		(start 94.292928 -209.936588)
		(end 94.378526 -210.122516)
		(width 0.14732)
		(layer "In6.Cu")
		(net "UPI_CPU1_CPU0_P0P1_DN<5>")
	)
	(segment
		(start 333.392018 -146.984212)
		(end 333.08798 -146.775678)
		(width 0.14732)
		(layer "In6.Cu")
		(net "UPI_CPU1_CPU0_P0P1_DN<5>")
	)
	(segment
		(start 94.064582 -210.553808)
		(end 94.06509 -210.554062)
		(width 0.14732)
		(layer "In6.Cu")
		(net "UPI_CPU1_CPU0_P0P1_DN<5>")
	)
	(segment
		(start 93.879416 -213.516972)
		(end 93.879416 -213.929468)
		(width 0.0889)
		(layer "In6.Cu")
		(net "UPI_CPU1_CPU0_P0P1_DN<5>")
	)
	(segment
		(start 370.354352 -173.984158)
		(end 369.57 -174.145448)
		(width 0.14732)
		(layer "In6.Cu")
		(net "UPI_CPU1_CPU0_P0P1_DN<5>")
	)
	(segment
		(start 334.837278 -147.975828)
		(end 334.799686 -147.774406)
		(width 0.14732)
		(layer "In6.Cu")
		(net "UPI_CPU1_CPU0_P0P1_DN<5>")
	)
	(segment
		(start 94.251018 -210.46821)
		(end 94.064582 -210.553808)
		(width 0.14732)
		(layer "In6.Cu")
		(net "UPI_CPU1_CPU0_P0P1_DN<5>")
	)
	(segment
		(start 371.530626 -173.88967)
		(end 371.359684 -173.776894)
		(width 0.14732)
		(layer "In6.Cu")
		(net "UPI_CPU1_CPU0_P0P1_DN<5>")
	)
	(segment
		(start 93.97873 -213.150958)
		(end 93.97873 -213.417658)
		(width 0.0889)
		(layer "In6.Cu")
		(net "UPI_CPU1_CPU0_P0P1_DN<5>")
	)
	(segment
		(start 93.92158 -211.73059)
		(end 93.92158 -211.752688)
		(width 0.0889)
		(layer "In6.Cu")
		(net "UPI_CPU1_CPU0_P0P1_DN<5>")
	)
	(segment
		(start 94.419928 -209.592164)
		(end 94.292928 -209.936588)
		(width 0.14732)
		(layer "In6.Cu")
		(net "UPI_CPU1_CPU0_P0P1_DN<5>")
	)
	(segment
		(start 274.963128 -140.781786)
		(end 238.589566 -141.435582)
		(width 0.14732)
		(layer "In6.Cu")
		(net "UPI_CPU1_CPU0_P0P1_DN<5>")
	)
	(segment
		(start 371.359684 -173.776894)
		(end 370.999004 -173.851062)
		(width 0.14732)
		(layer "In6.Cu")
		(net "UPI_CPU1_CPU0_P0P1_DN<5>")
	)
	(segment
		(start 373.97436 -173.238668)
		(end 372.004336 -173.644052)
		(width 0.14732)
		(layer "In6.Cu")
		(net "UPI_CPU1_CPU0_P0P1_DN<5>")
	)
	(segment
		(start 94.648274 -208.973674)
		(end 94.733872 -209.159602)
		(width 0.14732)
		(layer "In6.Cu")
		(net "UPI_CPU1_CPU0_P0P1_DN<5>")
	)
	(segment
		(start 93.92158 -211.752688)
		(end 93.879416 -211.794852)
		(width 0.0889)
		(layer "In6.Cu")
		(net "UPI_CPU1_CPU0_P0P1_DN<5>")
	)
	(segment
		(start 372.004336 -173.644052)
		(end 371.89156 -173.815248)
		(width 0.14732)
		(layer "In6.Cu")
		(net "UPI_CPU1_CPU0_P0P1_DN<5>")
	)
	(segment
		(start 368.615214 -173.788832)
		(end 358.960674 -164.350192)
		(width 0.14732)
		(layer "In6.Cu")
		(net "UPI_CPU1_CPU0_P0P1_DN<5>")
	)
	(segment
		(start 95.178372 -207.53832)
		(end 95.26397 -207.724248)
		(width 0.14732)
		(layer "In6.Cu")
		(net "UPI_CPU1_CPU0_P0P1_DN<5>")
	)
	(segment
		(start 93.97873 -212.41893)
		(end 93.97873 -212.68563)
		(width 0.0889)
		(layer "In6.Cu")
		(net "UPI_CPU1_CPU0_P0P1_DN<5>")
	)
	(segment
		(start 94.606364 -209.505296)
		(end 94.420182 -209.590894)
		(width 0.14732)
		(layer "In6.Cu")
		(net "UPI_CPU1_CPU0_P0P1_DN<5>")
	)
	(segment
		(start 94.420182 -209.590894)
		(end 94.419928 -209.592164)
		(width 0.14732)
		(layer "In6.Cu")
		(net "UPI_CPU1_CPU0_P0P1_DN<5>")
	)
	(segment
		(start 93.879416 -211.794852)
		(end 93.879416 -212.319616)
		(width 0.0889)
		(layer "In6.Cu")
		(net "UPI_CPU1_CPU0_P0P1_DN<5>")
	)
	(segment
		(start 331.679296 -145.63344)
		(end 319.635124 -142.544038)
		(width 0.14732)
		(layer "In6.Cu")
		(net "UPI_CPU1_CPU0_P0P1_DN<5>")
	)
	(segment
		(start 370.525294 -174.09668)
		(end 370.354352 -173.984158)
		(width 0.14732)
		(layer "In6.Cu")
		(net "UPI_CPU1_CPU0_P0P1_DN<5>")
	)
	(segment
		(start 93.879416 -213.051644)
		(end 93.97873 -213.150958)
		(width 0.0889)
		(layer "In6.Cu")
		(net "UPI_CPU1_CPU0_P0P1_DN<5>")
	)
	(segment
		(start 93.92158 -210.94192)
		(end 93.92158 -211.73059)
		(width 0.14732)
		(layer "In6.Cu")
		(net "UPI_CPU1_CPU0_P0P1_DN<5>")
	)
	(segment
		(start 93.548962 -214.91448)
		(end 93.627194 -214.893652)
		(width 0.0889)
		(layer "In6.Cu")
		(net "UPI_CPU1_CPU0_P0P1_DN<5>")
	)
	(segment
		(start 93.409008 -214.461852)
		(end 93.409008 -214.622634)
		(width 0.0889)
		(layer "In6.Cu")
		(net "UPI_CPU1_CPU0_P0P1_DN<5>")
	)
	(segment
		(start 94.06509 -210.554062)
		(end 94.064582 -210.555586)
		(width 0.14732)
		(layer "In6.Cu")
		(net "UPI_CPU1_CPU0_P0P1_DN<5>")
	)
	(segment
		(start 335.141316 -148.184362)
		(end 334.837278 -147.975828)
		(width 0.14732)
		(layer "In6.Cu")
		(net "UPI_CPU1_CPU0_P0P1_DN<5>")
	)
	(segment
		(start 95.26397 -207.724248)
		(end 95.136462 -208.069942)
		(width 0.14732)
		(layer "In6.Cu")
		(net "UPI_CPU1_CPU0_P0P1_DN<5>")
	)
	(segment
		(start 333.896716 -147.1549)
		(end 333.593186 -146.94662)
		(width 0.14732)
		(layer "In6.Cu")
		(net "UPI_CPU1_CPU0_P0P1_DN<5>")
	)
	(segment
		(start 370.886482 -174.022512)
		(end 370.525294 -174.09668)
		(width 0.14732)
		(layer "In6.Cu")
		(net "UPI_CPU1_CPU0_P0P1_DN<5>")
	)
	(segment
		(start 93.627194 -214.893652)
		(end 93.783658 -214.622634)
		(width 0.0889)
		(layer "In6.Cu")
		(net "UPI_CPU1_CPU0_P0P1_DN<5>")
	)
	(segment
		(start 317.266828 -142.544038)
		(end 274.963128 -140.781786)
		(width 0.14732)
		(layer "In6.Cu")
		(net "UPI_CPU1_CPU0_P0P1_DN<5>")
	)
	(segment
		(start 335.342484 -148.14677)
		(end 335.141316 -148.184362)
		(width 0.14732)
		(layer "In6.Cu")
		(net "UPI_CPU1_CPU0_P0P1_DN<5>")
	)
	(segment
		(start 370.999004 -173.851062)
		(end 370.886482 -174.022512)
		(width 0.14732)
		(layer "In6.Cu")
		(net "UPI_CPU1_CPU0_P0P1_DN<5>")
	)
	(segment
		(start 332.146402 -145.953734)
		(end 331.679296 -145.63344)
		(width 0.14732)
		(layer "In6.Cu")
		(net "UPI_CPU1_CPU0_P0P1_DN<5>")
	)
	(segment
		(start 369.57 -174.145448)
		(end 369.195096 -174.13732)
		(width 0.14732)
		(layer "In6.Cu")
		(net "UPI_CPU1_CPU0_P0P1_DN<5>")
	)
	(segment
		(start 333.050642 -146.574256)
		(end 332.6892 -146.326352)
		(width 0.14732)
		(layer "In6.Cu")
		(net "UPI_CPU1_CPU0_P0P1_DN<5>")
	)
	(segment
		(start 94.733872 -209.159602)
		(end 94.606364 -209.505296)
		(width 0.14732)
		(layer "In6.Cu")
		(net "UPI_CPU1_CPU0_P0P1_DN<5>")
	)
	(segment
		(start 161.577274 -143.051022)
		(end 125.504448 -165.247066)
		(width 0.14732)
		(layer "In6.Cu")
		(net "UPI_CPU1_CPU0_P0P1_DN<5>")
	)
	(segment
		(start 374.449086 -174.19828)
		(end 374.56364 -173.999906)
		(width 0.14732)
		(layer "In6.Cu")
		(net "UPI_CPU1_CPU0_P0P1_DN<5>")
	)
	(segment
		(start 333.08798 -146.775678)
		(end 333.050642 -146.574256)
		(width 0.14732)
		(layer "In6.Cu")
		(net "UPI_CPU1_CPU0_P0P1_DN<5>")
	)
	(segment
		(start 332.487778 -146.36369)
		(end 332.18374 -146.15541)
		(width 0.14732)
		(layer "In6.Cu")
		(net "UPI_CPU1_CPU0_P0P1_DN<5>")
	)
	(segment
		(start 334.799686 -147.774406)
		(end 334.439514 -147.527264)
		(width 0.14732)
		(layer "In6.Cu")
		(net "UPI_CPU1_CPU0_P0P1_DN<5>")
	)
	(segment
		(start 374.56364 -173.614588)
		(end 374.3071 -173.358048)
		(width 0.14732)
		(layer "In6.Cu")
		(net "UPI_CPU1_CPU0_P0P1_DN<5>")
	)
	(segment
		(start 334.238092 -147.564856)
		(end 333.934308 -147.356322)
		(width 0.14732)
		(layer "In6.Cu")
		(net "UPI_CPU1_CPU0_P0P1_DN<5>")
	)
	(arc
		(start 93.593412 -214.261954)
		(mid 93.484016 -214.346051)
		(end 93.409008 -214.461852)
		(width 0.0889)
		(layer "In6.Cu")
		(net "UPI_CPU1_CPU0_P0P1_DN<5>")
	)
	(arc
		(start 93.864176 -213.968584)
		(mid 93.75397 -214.138501)
		(end 93.593412 -214.261954)
		(width 0.0889)
		(layer "In6.Cu")
		(net "UPI_CPU1_CPU0_P0P1_DN<5>")
	)
	(arc
		(start 93.409008 -214.622634)
		(mid 93.445868 -214.784431)
		(end 93.548962 -214.91448)
		(width 0.0889)
		(layer "In6.Cu")
		(net "UPI_CPU1_CPU0_P0P1_DN<5>")
	)
	(arc
		(start 93.879416 -213.929468)
		(mid 93.872138 -213.949159)
		(end 93.864176 -213.968584)
		(width 0.0889)
		(layer "In6.Cu")
		(net "UPI_CPU1_CPU0_P0P1_DN<5>")
	)
	(segment
		(start 379.31598 -215.158574)
		(end 379.160786 -215.42756)
		(width 0.0889)
		(layer "F.Cu")
		(net "UPI_CPU1_CPU0_P0P1_DN<4>")
	)
	(segment
		(start 375.99747 -207.71993)
		(end 375.074434 -205.491588)
		(width 0.0889)
		(layer "F.Cu")
		(net "UPI_CPU1_CPU0_P0P1_DN<4>")
	)
	(segment
		(start 379.411484 -213.42223)
		(end 379.411484 -213.26983)
		(width 0.0889)
		(layer "F.Cu")
		(net "UPI_CPU1_CPU0_P0P1_DN<4>")
	)
	(segment
		(start 375.604532 -199.57923)
		(end 376.73026 -196.861684)
		(width 0.13208)
		(layer "F.Cu")
		(net "UPI_CPU1_CPU0_P0P1_DN<4>")
	)
	(segment
		(start 379.510544 -213.17077)
		(end 379.510544 -213.01837)
		(width 0.0889)
		(layer "F.Cu")
		(net "UPI_CPU1_CPU0_P0P1_DN<4>")
	)
	(segment
		(start 376.107706 -174.317152)
		(end 374.963944 -173.553628)
		(width 0.13208)
		(layer "F.Cu")
		(net "UPI_CPU1_CPU0_P0P1_DN<4>")
	)
	(segment
		(start 374.963944 -173.553628)
		(end 373.766842 -173.190408)
		(width 0.13208)
		(layer "F.Cu")
		(net "UPI_CPU1_CPU0_P0P1_DN<4>")
	)
	(segment
		(start 92.374466 -214.344758)
		(end 92.374466 -213.732618)
		(width 0.13208)
		(layer "F.Cu")
		(net "UPI_CPU1_CPU0_P0P1_DN<4>")
	)
	(segment
		(start 375.108978 -205.227174)
		(end 375.108978 -205.205076)
		(width 0.0889)
		(layer "F.Cu")
		(net "UPI_CPU1_CPU0_P0P1_DN<4>")
	)
	(segment
		(start 379.127258 -214.809578)
		(end 379.128782 -214.808816)
		(width 0.0889)
		(layer "F.Cu")
		(net "UPI_CPU1_CPU0_P0P1_DN<4>")
	)
	(segment
		(start 382.11633 -180.326284)
		(end 376.107706 -174.317152)
		(width 0.13208)
		(layer "F.Cu")
		(net "UPI_CPU1_CPU0_P0P1_DN<4>")
	)
	(segment
		(start 379.510544 -213.01837)
		(end 379.411484 -212.91931)
		(width 0.0889)
		(layer "F.Cu")
		(net "UPI_CPU1_CPU0_P0P1_DN<4>")
	)
	(segment
		(start 379.411484 -214.319104)
		(end 379.411484 -213.77275)
		(width 0.0889)
		(layer "F.Cu")
		(net "UPI_CPU1_CPU0_P0P1_DN<4>")
	)
	(segment
		(start 373.766842 -173.190408)
		(end 371.101874 -173.190408)
		(width 0.13208)
		(layer "F.Cu")
		(net "UPI_CPU1_CPU0_P0P1_DN<4>")
	)
	(segment
		(start 370.997734 -173.162468)
		(end 370.89969 -172.992034)
		(width 0.13208)
		(layer "F.Cu")
		(net "UPI_CPU1_CPU0_P0P1_DN<4>")
	)
	(segment
		(start 370.898928 -172.991018)
		(end 371.046756 -172.438568)
		(width 0.13208)
		(layer "F.Cu")
		(net "UPI_CPU1_CPU0_P0P1_DN<4>")
	)
	(segment
		(start 371.101874 -173.190408)
		(end 370.997734 -173.162468)
		(width 0.13208)
		(layer "F.Cu")
		(net "UPI_CPU1_CPU0_P0P1_DN<4>")
	)
	(segment
		(start 379.411484 -213.77275)
		(end 379.510544 -213.67369)
		(width 0.0889)
		(layer "F.Cu")
		(net "UPI_CPU1_CPU0_P0P1_DN<4>")
	)
	(segment
		(start 375.074434 -205.261718)
		(end 375.108978 -205.227174)
		(width 0.0889)
		(layer "F.Cu")
		(net "UPI_CPU1_CPU0_P0P1_DN<4>")
	)
	(segment
		(start 379.411484 -211.46389)
		(end 379.178058 -210.900518)
		(width 0.0889)
		(layer "F.Cu")
		(net "UPI_CPU1_CPU0_P0P1_DN<4>")
	)
	(segment
		(start 379.119892 -214.813896)
		(end 379.127258 -214.809578)
		(width 0.0889)
		(layer "F.Cu")
		(net "UPI_CPU1_CPU0_P0P1_DN<4>")
	)
	(segment
		(start 379.128782 -214.808816)
		(end 379.131068 -214.807546)
		(width 0.0889)
		(layer "F.Cu")
		(net "UPI_CPU1_CPU0_P0P1_DN<4>")
	)
	(segment
		(start 370.89969 -172.992034)
		(end 370.898928 -172.991018)
		(width 0.13208)
		(layer "F.Cu")
		(net "UPI_CPU1_CPU0_P0P1_DN<4>")
	)
	(segment
		(start 378.94133 -215.158574)
		(end 378.94133 -215.133174)
		(width 0.0889)
		(layer "F.Cu")
		(net "UPI_CPU1_CPU0_P0P1_DN<4>")
	)
	(segment
		(start 379.160786 -215.42756)
		(end 379.07976 -215.44915)
		(width 0.0889)
		(layer "F.Cu")
		(net "UPI_CPU1_CPU0_P0P1_DN<4>")
	)
	(segment
		(start 375.108978 -205.205076)
		(end 375.108978 -202.070462)
		(width 0.13208)
		(layer "F.Cu")
		(net "UPI_CPU1_CPU0_P0P1_DN<4>")
	)
	(segment
		(start 376.73026 -196.861684)
		(end 384.468878 -189.123066)
		(width 0.13208)
		(layer "F.Cu")
		(net "UPI_CPU1_CPU0_P0P1_DN<4>")
	)
	(segment
		(start 379.411484 -213.26983)
		(end 379.510544 -213.17077)
		(width 0.0889)
		(layer "F.Cu")
		(net "UPI_CPU1_CPU0_P0P1_DN<4>")
	)
	(segment
		(start 375.074434 -205.491588)
		(end 375.074434 -205.261718)
		(width 0.0889)
		(layer "F.Cu")
		(net "UPI_CPU1_CPU0_P0P1_DN<4>")
	)
	(segment
		(start 379.510544 -213.52129)
		(end 379.411484 -213.42223)
		(width 0.0889)
		(layer "F.Cu")
		(net "UPI_CPU1_CPU0_P0P1_DN<4>")
	)
	(segment
		(start 379.510544 -213.67369)
		(end 379.510544 -213.52129)
		(width 0.0889)
		(layer "F.Cu")
		(net "UPI_CPU1_CPU0_P0P1_DN<4>")
	)
	(segment
		(start 379.178058 -210.900518)
		(end 375.99747 -207.71993)
		(width 0.0889)
		(layer "F.Cu")
		(net "UPI_CPU1_CPU0_P0P1_DN<4>")
	)
	(segment
		(start 379.411484 -212.91931)
		(end 379.411484 -211.46389)
		(width 0.0889)
		(layer "F.Cu")
		(net "UPI_CPU1_CPU0_P0P1_DN<4>")
	)
	(segment
		(start 375.108978 -202.070462)
		(end 375.604532 -199.57923)
		(width 0.13208)
		(layer "F.Cu")
		(net "UPI_CPU1_CPU0_P0P1_DN<4>")
	)
	(segment
		(start 383.704846 -184.160922)
		(end 382.11633 -180.326284)
		(width 0.13208)
		(layer "F.Cu")
		(net "UPI_CPU1_CPU0_P0P1_DN<4>")
	)
	(segment
		(start 384.468878 -189.123066)
		(end 384.468878 -186.680094)
		(width 0.13208)
		(layer "F.Cu")
		(net "UPI_CPU1_CPU0_P0P1_DN<4>")
	)
	(segment
		(start 384.468878 -186.680094)
		(end 383.704846 -184.160922)
		(width 0.13208)
		(layer "F.Cu")
		(net "UPI_CPU1_CPU0_P0P1_DN<4>")
	)
	(arc
		(start 378.94133 -215.133174)
		(mid 378.989009 -214.950274)
		(end 379.119892 -214.813896)
		(width 0.0889)
		(layer "F.Cu")
		(net "UPI_CPU1_CPU0_P0P1_DN<4>")
	)
	(arc
		(start 379.131068 -214.807546)
		(mid 379.336377 -214.600704)
		(end 379.411484 -214.319104)
		(width 0.0889)
		(layer "F.Cu")
		(net "UPI_CPU1_CPU0_P0P1_DN<4>")
	)
	(arc
		(start 379.07976 -215.44915)
		(mid 378.977739 -215.319488)
		(end 378.94133 -215.158574)
		(width 0.0889)
		(layer "F.Cu")
		(net "UPI_CPU1_CPU0_P0P1_DN<4>")
	)
	(segment
		(start 92.649802 -213.133178)
		(end 92.749116 -213.033864)
		(width 0.0889)
		(layer "In6.Cu")
		(net "UPI_CPU1_CPU0_P0P1_DN<4>")
	)
	(segment
		(start 92.649802 -212.66785)
		(end 92.649802 -212.40115)
		(width 0.0889)
		(layer "In6.Cu")
		(net "UPI_CPU1_CPU0_P0P1_DN<4>")
	)
	(segment
		(start 161.03346 -142.068296)
		(end 169.613326 -139.105894)
		(width 0.14732)
		(layer "In6.Cu")
		(net "UPI_CPU1_CPU0_P0P1_DN<4>")
	)
	(segment
		(start 92.749116 -213.8934)
		(end 92.749116 -213.499192)
		(width 0.0889)
		(layer "In6.Cu")
		(net "UPI_CPU1_CPU0_P0P1_DN<4>")
	)
	(segment
		(start 370.505228 -172.29328)
		(end 371.046756 -172.438568)
		(width 0.14732)
		(layer "In6.Cu")
		(net "UPI_CPU1_CPU0_P0P1_DN<4>")
	)
	(segment
		(start 238.586518 -140.221208)
		(end 238.590836 -140.221208)
		(width 0.14732)
		(layer "In6.Cu")
		(net "UPI_CPU1_CPU0_P0P1_DN<4>")
	)
	(segment
		(start 370.371116 -172.06087)
		(end 370.505228 -172.29328)
		(width 0.14732)
		(layer "In6.Cu")
		(net "UPI_CPU1_CPU0_P0P1_DN<4>")
	)
	(segment
		(start 92.749116 -213.033864)
		(end 92.749116 -212.767164)
		(width 0.0889)
		(layer "In6.Cu")
		(net "UPI_CPU1_CPU0_P0P1_DN<4>")
	)
	(segment
		(start 368.340894 -171.18457)
		(end 369.097814 -171.56557)
		(width 0.14732)
		(layer "In6.Cu")
		(net "UPI_CPU1_CPU0_P0P1_DN<4>")
	)
	(segment
		(start 332.186534 -144.620996)
		(end 360.236262 -163.864544)
		(width 0.14732)
		(layer "In6.Cu")
		(net "UPI_CPU1_CPU0_P0P1_DN<4>")
	)
	(segment
		(start 92.749116 -211.644738)
		(end 92.707206 -211.602828)
		(width 0.0889)
		(layer "In6.Cu")
		(net "UPI_CPU1_CPU0_P0P1_DN<4>")
	)
	(segment
		(start 92.749116 -212.767164)
		(end 92.649802 -212.66785)
		(width 0.0889)
		(layer "In6.Cu")
		(net "UPI_CPU1_CPU0_P0P1_DN<4>")
	)
	(segment
		(start 369.097814 -171.56557)
		(end 370.055902 -171.81957)
		(width 0.14732)
		(layer "In6.Cu")
		(net "UPI_CPU1_CPU0_P0P1_DN<4>")
	)
	(segment
		(start 92.707206 -211.602828)
		(end 92.707206 -211.58073)
		(width 0.0889)
		(layer "In6.Cu")
		(net "UPI_CPU1_CPU0_P0P1_DN<4>")
	)
	(segment
		(start 92.649802 -213.399878)
		(end 92.649802 -213.133178)
		(width 0.0889)
		(layer "In6.Cu")
		(net "UPI_CPU1_CPU0_P0P1_DN<4>")
	)
	(segment
		(start 92.533216 -214.033608)
		(end 92.617798 -214.05977)
		(width 0.0889)
		(layer "In6.Cu")
		(net "UPI_CPU1_CPU0_P0P1_DN<4>")
	)
	(segment
		(start 92.374466 -213.732618)
		(end 92.533216 -214.033608)
		(width 0.0889)
		(layer "In6.Cu")
		(net "UPI_CPU1_CPU0_P0P1_DN<4>")
	)
	(segment
		(start 92.749116 -213.499192)
		(end 92.649802 -213.399878)
		(width 0.0889)
		(layer "In6.Cu")
		(net "UPI_CPU1_CPU0_P0P1_DN<4>")
	)
	(segment
		(start 92.707206 -211.58073)
		(end 92.707206 -210.66252)
		(width 0.14732)
		(layer "In6.Cu")
		(net "UPI_CPU1_CPU0_P0P1_DN<4>")
	)
	(segment
		(start 92.707206 -210.66252)
		(end 101.270308 -187.46724)
		(width 0.14732)
		(layer "In6.Cu")
		(net "UPI_CPU1_CPU0_P0P1_DN<4>")
	)
	(segment
		(start 101.270308 -187.46724)
		(end 104.318816 -183.644794)
		(width 0.14732)
		(layer "In6.Cu")
		(net "UPI_CPU1_CPU0_P0P1_DN<4>")
	)
	(segment
		(start 92.649802 -212.40115)
		(end 92.749116 -212.301836)
		(width 0.0889)
		(layer "In6.Cu")
		(net "UPI_CPU1_CPU0_P0P1_DN<4>")
	)
	(segment
		(start 124.812806 -164.355526)
		(end 161.03346 -142.068296)
		(width 0.14732)
		(layer "In6.Cu")
		(net "UPI_CPU1_CPU0_P0P1_DN<4>")
	)
	(segment
		(start 314.67933 -141.330172)
		(end 319.3542 -141.330172)
		(width 0.14732)
		(layer "In6.Cu")
		(net "UPI_CPU1_CPU0_P0P1_DN<4>")
	)
	(segment
		(start 319.3542 -141.330172)
		(end 332.186534 -144.620996)
		(width 0.14732)
		(layer "In6.Cu")
		(net "UPI_CPU1_CPU0_P0P1_DN<4>")
	)
	(segment
		(start 238.590836 -140.221208)
		(end 273.151854 -139.599924)
		(width 0.14732)
		(layer "In6.Cu")
		(net "UPI_CPU1_CPU0_P0P1_DN<4>")
	)
	(segment
		(start 273.151854 -139.599924)
		(end 314.67933 -141.330172)
		(width 0.14732)
		(layer "In6.Cu")
		(net "UPI_CPU1_CPU0_P0P1_DN<4>")
	)
	(segment
		(start 92.749116 -212.301836)
		(end 92.749116 -211.644738)
		(width 0.0889)
		(layer "In6.Cu")
		(net "UPI_CPU1_CPU0_P0P1_DN<4>")
	)
	(segment
		(start 169.613326 -139.105894)
		(end 238.586518 -140.221208)
		(width 0.14732)
		(layer "In6.Cu")
		(net "UPI_CPU1_CPU0_P0P1_DN<4>")
	)
	(segment
		(start 370.055902 -171.81957)
		(end 370.371116 -172.06087)
		(width 0.14732)
		(layer "In6.Cu")
		(net "UPI_CPU1_CPU0_P0P1_DN<4>")
	)
	(segment
		(start 104.318816 -183.644794)
		(end 124.812806 -164.355526)
		(width 0.14732)
		(layer "In6.Cu")
		(net "UPI_CPU1_CPU0_P0P1_DN<4>")
	)
	(segment
		(start 360.236262 -163.864544)
		(end 368.340894 -171.18457)
		(width 0.14732)
		(layer "In6.Cu")
		(net "UPI_CPU1_CPU0_P0P1_DN<4>")
	)
	(arc
		(start 92.617798 -214.05977)
		(mid 92.694471 -213.985276)
		(end 92.749116 -213.8934)
		(width 0.0889)
		(layer "In6.Cu")
		(net "UPI_CPU1_CPU0_P0P1_DN<4>")
	)
	(segment
		(start 383.00025 -179.72151)
		(end 376.798078 -173.519592)
		(width 0.13208)
		(layer "F.Cu")
		(net "UPI_CPU1_CPU0_P0P1_DN<3>")
	)
	(segment
		(start 380.061724 -213.71687)
		(end 380.061724 -213.56447)
		(width 0.0889)
		(layer "F.Cu")
		(net "UPI_CPU1_CPU0_P0P1_DN<3>")
	)
	(segment
		(start 373.919242 -171.959524)
		(end 373.852186 -171.770548)
		(width 0.13208)
		(layer "F.Cu")
		(net "UPI_CPU1_CPU0_P0P1_DN<3>")
	)
	(segment
		(start 91.904312 -214.622888)
		(end 91.904058 -214.622634)
		(width 0.13208)
		(layer "F.Cu")
		(net "UPI_CPU1_CPU0_P0P1_DN<3>")
	)
	(segment
		(start 379.886972 -214.519764)
		(end 379.941328 -214.613744)
		(width 0.0889)
		(layer "F.Cu")
		(net "UPI_CPU1_CPU0_P0P1_DN<3>")
	)
	(segment
		(start 379.941328 -214.613744)
		(end 380.022354 -214.635334)
		(width 0.0889)
		(layer "F.Cu")
		(net "UPI_CPU1_CPU0_P0P1_DN<3>")
	)
	(segment
		(start 379.789436 -210.521042)
		(end 377.16841 -207.900016)
		(width 0.0889)
		(layer "F.Cu")
		(net "UPI_CPU1_CPU0_P0P1_DN<3>")
	)
	(segment
		(start 376.579384 -200.052686)
		(end 377.682506 -197.389496)
		(width 0.13208)
		(layer "F.Cu")
		(net "UPI_CPU1_CPU0_P0P1_DN<3>")
	)
	(segment
		(start 380.160784 -211.417916)
		(end 379.789436 -210.521042)
		(width 0.0889)
		(layer "F.Cu")
		(net "UPI_CPU1_CPU0_P0P1_DN<3>")
	)
	(segment
		(start 376.157998 -202.170538)
		(end 376.455686 -200.67397)
		(width 0.13208)
		(layer "F.Cu")
		(net "UPI_CPU1_CPU0_P0P1_DN<3>")
	)
	(segment
		(start 380.160784 -213.31301)
		(end 380.061724 -213.21395)
		(width 0.0889)
		(layer "F.Cu")
		(net "UPI_CPU1_CPU0_P0P1_DN<3>")
	)
	(segment
		(start 373.878094 -171.519342)
		(end 374.054878 -171.212256)
		(width 0.13208)
		(layer "F.Cu")
		(net "UPI_CPU1_CPU0_P0P1_DN<3>")
	)
	(segment
		(start 377.682506 -197.389496)
		(end 385.954778 -189.117224)
		(width 0.13208)
		(layer "F.Cu")
		(net "UPI_CPU1_CPU0_P0P1_DN<3>")
	)
	(segment
		(start 377.16841 -207.900016)
		(end 376.192288 -205.542642)
		(width 0.0889)
		(layer "F.Cu")
		(net "UPI_CPU1_CPU0_P0P1_DN<3>")
	)
	(segment
		(start 380.160784 -213.46541)
		(end 380.160784 -213.31301)
		(width 0.0889)
		(layer "F.Cu")
		(net "UPI_CPU1_CPU0_P0P1_DN<3>")
	)
	(segment
		(start 379.786134 -214.344758)
		(end 379.886972 -214.519764)
		(width 0.0889)
		(layer "F.Cu")
		(net "UPI_CPU1_CPU0_P0P1_DN<3>")
	)
	(segment
		(start 91.904312 -215.158574)
		(end 91.904312 -214.622888)
		(width 0.13208)
		(layer "F.Cu")
		(net "UPI_CPU1_CPU0_P0P1_DN<3>")
	)
	(segment
		(start 376.157998 -205.227174)
		(end 376.157998 -205.205076)
		(width 0.0889)
		(layer "F.Cu")
		(net "UPI_CPU1_CPU0_P0P1_DN<3>")
	)
	(segment
		(start 380.160784 -212.96249)
		(end 380.160784 -211.417916)
		(width 0.0889)
		(layer "F.Cu")
		(net "UPI_CPU1_CPU0_P0P1_DN<3>")
	)
	(segment
		(start 376.192288 -205.542642)
		(end 376.192288 -205.261464)
		(width 0.0889)
		(layer "F.Cu")
		(net "UPI_CPU1_CPU0_P0P1_DN<3>")
	)
	(segment
		(start 376.192288 -205.261464)
		(end 376.157998 -205.227174)
		(width 0.0889)
		(layer "F.Cu")
		(net "UPI_CPU1_CPU0_P0P1_DN<3>")
	)
	(segment
		(start 376.157998 -205.205076)
		(end 376.157998 -202.170538)
		(width 0.13208)
		(layer "F.Cu")
		(net "UPI_CPU1_CPU0_P0P1_DN<3>")
	)
	(segment
		(start 376.455686 -200.67397)
		(end 376.579384 -200.052686)
		(width 0.13208)
		(layer "F.Cu")
		(net "UPI_CPU1_CPU0_P0P1_DN<3>")
	)
	(segment
		(start 385.954778 -186.854084)
		(end 383.00025 -179.72151)
		(width 0.13208)
		(layer "F.Cu")
		(net "UPI_CPU1_CPU0_P0P1_DN<3>")
	)
	(segment
		(start 385.954778 -189.117224)
		(end 385.954778 -186.854084)
		(width 0.13208)
		(layer "F.Cu")
		(net "UPI_CPU1_CPU0_P0P1_DN<3>")
	)
	(segment
		(start 373.852186 -171.770548)
		(end 373.878094 -171.519342)
		(width 0.13208)
		(layer "F.Cu")
		(net "UPI_CPU1_CPU0_P0P1_DN<3>")
	)
	(segment
		(start 380.160784 -213.81593)
		(end 380.061724 -213.71687)
		(width 0.0889)
		(layer "F.Cu")
		(net "UPI_CPU1_CPU0_P0P1_DN<3>")
	)
	(segment
		(start 380.061724 -213.06155)
		(end 380.160784 -212.96249)
		(width 0.0889)
		(layer "F.Cu")
		(net "UPI_CPU1_CPU0_P0P1_DN<3>")
	)
	(segment
		(start 374.18264 -172.222922)
		(end 373.919242 -171.959524)
		(width 0.13208)
		(layer "F.Cu")
		(net "UPI_CPU1_CPU0_P0P1_DN<3>")
	)
	(segment
		(start 380.061724 -213.21395)
		(end 380.061724 -213.06155)
		(width 0.0889)
		(layer "F.Cu")
		(net "UPI_CPU1_CPU0_P0P1_DN<3>")
	)
	(segment
		(start 374.054878 -171.212256)
		(end 373.907304 -170.660568)
		(width 0.13208)
		(layer "F.Cu")
		(net "UPI_CPU1_CPU0_P0P1_DN<3>")
	)
	(segment
		(start 376.798078 -173.519592)
		(end 375.366026 -172.562266)
		(width 0.13208)
		(layer "F.Cu")
		(net "UPI_CPU1_CPU0_P0P1_DN<3>")
	)
	(segment
		(start 380.061724 -213.56447)
		(end 380.160784 -213.46541)
		(width 0.0889)
		(layer "F.Cu")
		(net "UPI_CPU1_CPU0_P0P1_DN<3>")
	)
	(segment
		(start 380.160784 -214.344758)
		(end 380.160784 -213.81593)
		(width 0.0889)
		(layer "F.Cu")
		(net "UPI_CPU1_CPU0_P0P1_DN<3>")
	)
	(segment
		(start 375.366026 -172.562266)
		(end 374.18264 -172.222922)
		(width 0.13208)
		(layer "F.Cu")
		(net "UPI_CPU1_CPU0_P0P1_DN<3>")
	)
	(arc
		(start 380.022354 -214.635334)
		(mid 380.124375 -214.505672)
		(end 380.160784 -214.344758)
		(width 0.0889)
		(layer "F.Cu")
		(net "UPI_CPU1_CPU0_P0P1_DN<3>")
	)
	(segment
		(start 337.904074 -147.622006)
		(end 360.086148 -162.839654)
		(width 0.14732)
		(layer "In6.Cu")
		(net "UPI_CPU1_CPU0_P0P1_DN<3>")
	)
	(segment
		(start 124.437648 -163.92779)
		(end 160.837372 -141.530832)
		(width 0.14732)
		(layer "In6.Cu")
		(net "UPI_CPU1_CPU0_P0P1_DN<3>")
	)
	(segment
		(start 319.178432 -140.664438)
		(end 332.886812 -144.179798)
		(width 0.14732)
		(layer "In6.Cu")
		(net "UPI_CPU1_CPU0_P0P1_DN<3>")
	)
	(segment
		(start 92.04198 -211.77123)
		(end 92.04198 -210.468972)
		(width 0.14732)
		(layer "In6.Cu")
		(net "UPI_CPU1_CPU0_P0P1_DN<3>")
	)
	(segment
		(start 369.721638 -170.984164)
		(end 370.86286 -170.584876)
		(width 0.14732)
		(layer "In6.Cu")
		(net "UPI_CPU1_CPU0_P0P1_DN<3>")
	)
	(segment
		(start 369.2652 -171.02201)
		(end 369.721638 -170.984164)
		(width 0.14732)
		(layer "In6.Cu")
		(net "UPI_CPU1_CPU0_P0P1_DN<3>")
	)
	(segment
		(start 92.737178 -208.938622)
		(end 92.888308 -208.528412)
		(width 0.14732)
		(layer "In6.Cu")
		(net "UPI_CPU1_CPU0_P0P1_DN<3>")
	)
	(segment
		(start 160.837372 -141.530832)
		(end 169.781728 -138.4427)
		(width 0.14732)
		(layer "In6.Cu")
		(net "UPI_CPU1_CPU0_P0P1_DN<3>")
	)
	(segment
		(start 374.57888 -169.926508)
		(end 374.57888 -170.29049)
		(width 0.14732)
		(layer "In6.Cu")
		(net "UPI_CPU1_CPU0_P0P1_DN<3>")
	)
	(segment
		(start 92.501212 -209.576924)
		(end 92.429076 -209.42046)
		(width 0.14732)
		(layer "In6.Cu")
		(net "UPI_CPU1_CPU0_P0P1_DN<3>")
	)
	(segment
		(start 91.904058 -214.622634)
		(end 91.747594 -214.893652)
		(width 0.0889)
		(layer "In6.Cu")
		(net "UPI_CPU1_CPU0_P0P1_DN<3>")
	)
	(segment
		(start 337.702652 -147.659344)
		(end 337.904074 -147.622006)
		(width 0.14732)
		(layer "In6.Cu")
		(net "UPI_CPU1_CPU0_P0P1_DN<3>")
	)
	(segment
		(start 371.48389 -170.367452)
		(end 373.91848 -169.515028)
		(width 0.14732)
		(layer "In6.Cu")
		(net "UPI_CPU1_CPU0_P0P1_DN<3>")
	)
	(segment
		(start 91.999816 -211.835492)
		(end 92.04198 -211.793328)
		(width 0.0889)
		(layer "In6.Cu")
		(net "UPI_CPU1_CPU0_P0P1_DN<3>")
	)
	(segment
		(start 335.319624 -145.848832)
		(end 335.357216 -146.050254)
		(width 0.14732)
		(layer "In6.Cu")
		(net "UPI_CPU1_CPU0_P0P1_DN<3>")
	)
	(segment
		(start 271.372584 -138.965686)
		(end 312.13552 -140.664438)
		(width 0.14732)
		(layer "In6.Cu")
		(net "UPI_CPU1_CPU0_P0P1_DN<3>")
	)
	(segment
		(start 368.71656 -170.747944)
		(end 369.2652 -171.02201)
		(width 0.14732)
		(layer "In6.Cu")
		(net "UPI_CPU1_CPU0_P0P1_DN<3>")
	)
	(segment
		(start 238.592614 -139.554966)
		(end 271.372584 -138.965686)
		(width 0.14732)
		(layer "In6.Cu")
		(net "UPI_CPU1_CPU0_P0P1_DN<3>")
	)
	(segment
		(start 373.91848 -169.515028)
		(end 374.25122 -169.598848)
		(width 0.14732)
		(layer "In6.Cu")
		(net "UPI_CPU1_CPU0_P0P1_DN<3>")
	)
	(segment
		(start 334.169512 -145.059908)
		(end 334.473296 -145.268442)
		(width 0.14732)
		(layer "In6.Cu")
		(net "UPI_CPU1_CPU0_P0P1_DN<3>")
	)
	(segment
		(start 92.04198 -210.468972)
		(end 92.19311 -210.05927)
		(width 0.14732)
		(layer "In6.Cu")
		(net "UPI_CPU1_CPU0_P0P1_DN<3>")
	)
	(segment
		(start 336.429604 -146.610578)
		(end 336.429858 -146.610324)
		(width 0.14732)
		(layer "In6.Cu")
		(net "UPI_CPU1_CPU0_P0P1_DN<3>")
	)
	(segment
		(start 91.999816 -213.516972)
		(end 92.09913 -213.417658)
		(width 0.0889)
		(layer "In6.Cu")
		(net "UPI_CPU1_CPU0_P0P1_DN<3>")
	)
	(segment
		(start 93.275404 -207.4799)
		(end 93.203268 -207.323436)
		(width 0.14732)
		(layer "In6.Cu")
		(net "UPI_CPU1_CPU0_P0P1_DN<3>")
	)
	(segment
		(start 370.86286 -170.584876)
		(end 371.047264 -170.673522)
		(width 0.14732)
		(layer "In6.Cu")
		(net "UPI_CPU1_CPU0_P0P1_DN<3>")
	)
	(segment
		(start 92.888308 -208.528412)
		(end 92.816172 -208.371948)
		(width 0.14732)
		(layer "In6.Cu")
		(net "UPI_CPU1_CPU0_P0P1_DN<3>")
	)
	(segment
		(start 336.771234 -147.02028)
		(end 336.972402 -146.982942)
		(width 0.14732)
		(layer "In6.Cu")
		(net "UPI_CPU1_CPU0_P0P1_DN<3>")
	)
	(segment
		(start 334.510888 -145.46961)
		(end 334.814672 -145.678144)
		(width 0.14732)
		(layer "In6.Cu")
		(net "UPI_CPU1_CPU0_P0P1_DN<3>")
	)
	(segment
		(start 169.781728 -138.4427)
		(end 238.58347 -139.554966)
		(width 0.14732)
		(layer "In6.Cu")
		(net "UPI_CPU1_CPU0_P0P1_DN<3>")
	)
	(segment
		(start 91.999816 -213.051644)
		(end 91.999816 -212.784944)
		(width 0.0889)
		(layer "In6.Cu")
		(net "UPI_CPU1_CPU0_P0P1_DN<3>")
	)
	(segment
		(start 100.52177 -187.498736)
		(end 103.91267 -183.24703)
		(width 0.14732)
		(layer "In6.Cu")
		(net "UPI_CPU1_CPU0_P0P1_DN<3>")
	)
	(segment
		(start 92.09913 -213.417658)
		(end 92.09913 -213.150958)
		(width 0.0889)
		(layer "In6.Cu")
		(net "UPI_CPU1_CPU0_P0P1_DN<3>")
	)
	(segment
		(start 91.999816 -212.319616)
		(end 91.999816 -211.835492)
		(width 0.0889)
		(layer "In6.Cu")
		(net "UPI_CPU1_CPU0_P0P1_DN<3>")
	)
	(segment
		(start 333.968344 -145.0975)
		(end 334.169512 -145.059908)
		(width 0.14732)
		(layer "In6.Cu")
		(net "UPI_CPU1_CPU0_P0P1_DN<3>")
	)
	(segment
		(start 337.398614 -147.451064)
		(end 337.702652 -147.659344)
		(width 0.14732)
		(layer "In6.Cu")
		(net "UPI_CPU1_CPU0_P0P1_DN<3>")
	)
	(segment
		(start 332.886812 -144.179798)
		(end 333.626968 -144.687798)
		(width 0.14732)
		(layer "In6.Cu")
		(net "UPI_CPU1_CPU0_P0P1_DN<3>")
	)
	(segment
		(start 333.626968 -144.687798)
		(end 333.66456 -144.888966)
		(width 0.14732)
		(layer "In6.Cu")
		(net "UPI_CPU1_CPU0_P0P1_DN<3>")
	)
	(segment
		(start 335.016094 -145.640552)
		(end 335.319624 -145.848832)
		(width 0.14732)
		(layer "In6.Cu")
		(net "UPI_CPU1_CPU0_P0P1_DN<3>")
	)
	(segment
		(start 92.04198 -211.793328)
		(end 92.04198 -211.77123)
		(width 0.0889)
		(layer "In6.Cu")
		(net "UPI_CPU1_CPU0_P0P1_DN<3>")
	)
	(segment
		(start 91.999816 -213.929468)
		(end 91.999816 -213.516972)
		(width 0.0889)
		(layer "In6.Cu")
		(net "UPI_CPU1_CPU0_P0P1_DN<3>")
	)
	(segment
		(start 91.999816 -212.784944)
		(end 92.09913 -212.68563)
		(width 0.0889)
		(layer "In6.Cu")
		(net "UPI_CPU1_CPU0_P0P1_DN<3>")
	)
	(segment
		(start 334.814672 -145.678144)
		(end 335.016094 -145.640552)
		(width 0.14732)
		(layer "In6.Cu")
		(net "UPI_CPU1_CPU0_P0P1_DN<3>")
	)
	(segment
		(start 333.66456 -144.888966)
		(end 333.968344 -145.0975)
		(width 0.14732)
		(layer "In6.Cu")
		(net "UPI_CPU1_CPU0_P0P1_DN<3>")
	)
	(segment
		(start 93.203268 -207.323436)
		(end 100.52177 -187.498736)
		(width 0.14732)
		(layer "In6.Cu")
		(net "UPI_CPU1_CPU0_P0P1_DN<3>")
	)
	(segment
		(start 92.09913 -212.68563)
		(end 92.09913 -212.41893)
		(width 0.0889)
		(layer "In6.Cu")
		(net "UPI_CPU1_CPU0_P0P1_DN<3>")
	)
	(segment
		(start 93.124274 -207.89011)
		(end 93.275404 -207.4799)
		(width 0.14732)
		(layer "In6.Cu")
		(net "UPI_CPU1_CPU0_P0P1_DN<3>")
	)
	(segment
		(start 92.19311 -210.05927)
		(end 92.350082 -209.987134)
		(width 0.14732)
		(layer "In6.Cu")
		(net "UPI_CPU1_CPU0_P0P1_DN<3>")
	)
	(segment
		(start 374.57888 -170.29049)
		(end 374.449086 -170.51528)
		(width 0.14732)
		(layer "In6.Cu")
		(net "UPI_CPU1_CPU0_P0P1_DN<3>")
	)
	(segment
		(start 335.357216 -146.050254)
		(end 335.661 -146.258788)
		(width 0.14732)
		(layer "In6.Cu")
		(net "UPI_CPU1_CPU0_P0P1_DN<3>")
	)
	(segment
		(start 371.047264 -170.673522)
		(end 371.395244 -170.551856)
		(width 0.14732)
		(layer "In6.Cu")
		(net "UPI_CPU1_CPU0_P0P1_DN<3>")
	)
	(segment
		(start 92.09913 -212.41893)
		(end 91.999816 -212.319616)
		(width 0.0889)
		(layer "In6.Cu")
		(net "UPI_CPU1_CPU0_P0P1_DN<3>")
	)
	(segment
		(start 371.395244 -170.551856)
		(end 371.48389 -170.367452)
		(width 0.14732)
		(layer "In6.Cu")
		(net "UPI_CPU1_CPU0_P0P1_DN<3>")
	)
	(segment
		(start 103.91267 -183.24703)
		(end 124.437648 -163.92779)
		(width 0.14732)
		(layer "In6.Cu")
		(net "UPI_CPU1_CPU0_P0P1_DN<3>")
	)
	(segment
		(start 92.580206 -209.010758)
		(end 92.737178 -208.938622)
		(width 0.14732)
		(layer "In6.Cu")
		(net "UPI_CPU1_CPU0_P0P1_DN<3>")
	)
	(segment
		(start 92.09913 -213.150958)
		(end 91.999816 -213.051644)
		(width 0.0889)
		(layer "In6.Cu")
		(net "UPI_CPU1_CPU0_P0P1_DN<3>")
	)
	(segment
		(start 91.747594 -214.893652)
		(end 91.669362 -214.91448)
		(width 0.0889)
		(layer "In6.Cu")
		(net "UPI_CPU1_CPU0_P0P1_DN<3>")
	)
	(segment
		(start 335.862168 -146.221196)
		(end 336.429604 -146.610578)
		(width 0.14732)
		(layer "In6.Cu")
		(net "UPI_CPU1_CPU0_P0P1_DN<3>")
	)
	(segment
		(start 337.361022 -147.249642)
		(end 337.361276 -147.249388)
		(width 0.14732)
		(layer "In6.Cu")
		(net "UPI_CPU1_CPU0_P0P1_DN<3>")
	)
	(segment
		(start 92.350082 -209.987134)
		(end 92.501212 -209.576924)
		(width 0.14732)
		(layer "In6.Cu")
		(net "UPI_CPU1_CPU0_P0P1_DN<3>")
	)
	(segment
		(start 238.58347 -139.554966)
		(end 238.592614 -139.554966)
		(width 0.14732)
		(layer "In6.Cu")
		(net "UPI_CPU1_CPU0_P0P1_DN<3>")
	)
	(segment
		(start 374.449086 -170.51528)
		(end 373.907304 -170.660568)
		(width 0.14732)
		(layer "In6.Cu")
		(net "UPI_CPU1_CPU0_P0P1_DN<3>")
	)
	(segment
		(start 92.429076 -209.42046)
		(end 92.580206 -209.010758)
		(width 0.14732)
		(layer "In6.Cu")
		(net "UPI_CPU1_CPU0_P0P1_DN<3>")
	)
	(segment
		(start 336.972402 -146.982942)
		(end 337.361022 -147.249642)
		(width 0.14732)
		(layer "In6.Cu")
		(net "UPI_CPU1_CPU0_P0P1_DN<3>")
	)
	(segment
		(start 374.25122 -169.598848)
		(end 374.57888 -169.926508)
		(width 0.14732)
		(layer "In6.Cu")
		(net "UPI_CPU1_CPU0_P0P1_DN<3>")
	)
	(segment
		(start 337.361276 -147.249388)
		(end 337.398614 -147.451064)
		(width 0.14732)
		(layer "In6.Cu")
		(net "UPI_CPU1_CPU0_P0P1_DN<3>")
	)
	(segment
		(start 335.661 -146.258788)
		(end 335.862168 -146.221196)
		(width 0.14732)
		(layer "In6.Cu")
		(net "UPI_CPU1_CPU0_P0P1_DN<3>")
	)
	(segment
		(start 336.46745 -146.812)
		(end 336.771234 -147.02028)
		(width 0.14732)
		(layer "In6.Cu")
		(net "UPI_CPU1_CPU0_P0P1_DN<3>")
	)
	(segment
		(start 312.13552 -140.664438)
		(end 319.178432 -140.664438)
		(width 0.14732)
		(layer "In6.Cu")
		(net "UPI_CPU1_CPU0_P0P1_DN<3>")
	)
	(segment
		(start 91.529408 -214.622634)
		(end 91.529408 -214.461852)
		(width 0.0889)
		(layer "In6.Cu")
		(net "UPI_CPU1_CPU0_P0P1_DN<3>")
	)
	(segment
		(start 334.473296 -145.268442)
		(end 334.510888 -145.46961)
		(width 0.14732)
		(layer "In6.Cu")
		(net "UPI_CPU1_CPU0_P0P1_DN<3>")
	)
	(segment
		(start 360.086148 -162.839654)
		(end 368.71656 -170.747944)
		(width 0.14732)
		(layer "In6.Cu")
		(net "UPI_CPU1_CPU0_P0P1_DN<3>")
	)
	(segment
		(start 336.429858 -146.610324)
		(end 336.46745 -146.812)
		(width 0.14732)
		(layer "In6.Cu")
		(net "UPI_CPU1_CPU0_P0P1_DN<3>")
	)
	(segment
		(start 92.967302 -207.962246)
		(end 93.124274 -207.89011)
		(width 0.14732)
		(layer "In6.Cu")
		(net "UPI_CPU1_CPU0_P0P1_DN<3>")
	)
	(segment
		(start 92.816172 -208.371948)
		(end 92.967302 -207.962246)
		(width 0.14732)
		(layer "In6.Cu")
		(net "UPI_CPU1_CPU0_P0P1_DN<3>")
	)
	(arc
		(start 91.669362 -214.91448)
		(mid 91.566217 -214.784455)
		(end 91.529408 -214.622634)
		(width 0.0889)
		(layer "In6.Cu")
		(net "UPI_CPU1_CPU0_P0P1_DN<3>")
	)
	(arc
		(start 91.529408 -214.461852)
		(mid 91.604479 -214.34611)
		(end 91.713812 -214.261954)
		(width 0.0889)
		(layer "In6.Cu")
		(net "UPI_CPU1_CPU0_P0P1_DN<3>")
	)
	(arc
		(start 91.984576 -213.968584)
		(mid 91.992541 -213.94916)
		(end 91.999816 -213.929468)
		(width 0.0889)
		(layer "In6.Cu")
		(net "UPI_CPU1_CPU0_P0P1_DN<3>")
	)
	(arc
		(start 91.713812 -214.261954)
		(mid 91.874393 -214.138523)
		(end 91.984576 -213.968584)
		(width 0.0889)
		(layer "In6.Cu")
		(net "UPI_CPU1_CPU0_P0P1_DN<3>")
	)
	(segment
		(start 371.364764 -170.16857)
		(end 371.124734 -170.16857)
		(width 0.13208)
		(layer "F.Cu")
		(net "UPI_CPU1_CPU0_P0P1_DN<2>")
	)
	(segment
		(start 377.690634 -205.261718)
		(end 377.725178 -205.227174)
		(width 0.0889)
		(layer "F.Cu")
		(net "UPI_CPU1_CPU0_P0P1_DN<2>")
	)
	(segment
		(start 377.725178 -205.205076)
		(end 377.725178 -202.368658)
		(width 0.13208)
		(layer "F.Cu")
		(net "UPI_CPU1_CPU0_P0P1_DN<2>")
	)
	(segment
		(start 381.760984 -212.202776)
		(end 380.85395 -210.010756)
		(width 0.0889)
		(layer "F.Cu")
		(net "UPI_CPU1_CPU0_P0P1_DN<2>")
	)
	(segment
		(start 378.403866 -207.560926)
		(end 377.690634 -205.839314)
		(width 0.0889)
		(layer "F.Cu")
		(net "UPI_CPU1_CPU0_P0P1_DN<2>")
	)
	(segment
		(start 371.124734 -170.16857)
		(end 370.981224 -170.085512)
		(width 0.13208)
		(layer "F.Cu")
		(net "UPI_CPU1_CPU0_P0P1_DN<2>")
	)
	(segment
		(start 380.85395 -210.010756)
		(end 378.403866 -207.560926)
		(width 0.0889)
		(layer "F.Cu")
		(net "UPI_CPU1_CPU0_P0P1_DN<2>")
	)
	(segment
		(start 388.078218 -189.078616)
		(end 387.623812 -186.793886)
		(width 0.13208)
		(layer "F.Cu")
		(net "UPI_CPU1_CPU0_P0P1_DN<2>")
	)
	(segment
		(start 384.924554 -192.360804)
		(end 387.030214 -191.488568)
		(width 0.13208)
		(layer "F.Cu")
		(net "UPI_CPU1_CPU0_P0P1_DN<2>")
	)
	(segment
		(start 370.981224 -170.085512)
		(end 370.899436 -169.943526)
		(width 0.13208)
		(layer "F.Cu")
		(net "UPI_CPU1_CPU0_P0P1_DN<2>")
	)
	(segment
		(start 373.318532 -169.49547)
		(end 372.933976 -169.49547)
		(width 0.13208)
		(layer "F.Cu")
		(net "UPI_CPU1_CPU0_P0P1_DN<2>")
	)
	(segment
		(start 381.760984 -215.172798)
		(end 381.760984 -212.202776)
		(width 0.0889)
		(layer "F.Cu")
		(net "UPI_CPU1_CPU0_P0P1_DN<2>")
	)
	(segment
		(start 377.725178 -202.368658)
		(end 378.062236 -200.67397)
		(width 0.13208)
		(layer "F.Cu")
		(net "UPI_CPU1_CPU0_P0P1_DN<2>")
	)
	(segment
		(start 387.030214 -191.488568)
		(end 388.078218 -190.440564)
		(width 0.13208)
		(layer "F.Cu")
		(net "UPI_CPU1_CPU0_P0P1_DN<2>")
	)
	(segment
		(start 379.015244 -198.270114)
		(end 384.924554 -192.360804)
		(width 0.13208)
		(layer "F.Cu")
		(net "UPI_CPU1_CPU0_P0P1_DN<2>")
	)
	(segment
		(start 372.933976 -169.49547)
		(end 371.364764 -170.16857)
		(width 0.13208)
		(layer "F.Cu")
		(net "UPI_CPU1_CPU0_P0P1_DN<2>")
	)
	(segment
		(start 377.690634 -205.839314)
		(end 377.690634 -205.261718)
		(width 0.0889)
		(layer "F.Cu")
		(net "UPI_CPU1_CPU0_P0P1_DN<2>")
	)
	(segment
		(start 388.078218 -190.440564)
		(end 388.078218 -189.078616)
		(width 0.13208)
		(layer "F.Cu")
		(net "UPI_CPU1_CPU0_P0P1_DN<2>")
	)
	(segment
		(start 377.725178 -205.227174)
		(end 377.725178 -205.205076)
		(width 0.0889)
		(layer "F.Cu")
		(net "UPI_CPU1_CPU0_P0P1_DN<2>")
	)
	(segment
		(start 380.881128 -215.703658)
		(end 380.973584 -215.67902)
		(width 0.0889)
		(layer "F.Cu")
		(net "UPI_CPU1_CPU0_P0P1_DN<2>")
	)
	(segment
		(start 374.829578 -169.796206)
		(end 373.318532 -169.49547)
		(width 0.13208)
		(layer "F.Cu")
		(net "UPI_CPU1_CPU0_P0P1_DN<2>")
	)
	(segment
		(start 370.899436 -169.943526)
		(end 370.899436 -169.94378)
		(width 0.13208)
		(layer "F.Cu")
		(net "UPI_CPU1_CPU0_P0P1_DN<2>")
	)
	(segment
		(start 370.898928 -169.943018)
		(end 371.046756 -169.390568)
		(width 0.13208)
		(layer "F.Cu")
		(net "UPI_CPU1_CPU0_P0P1_DN<2>")
	)
	(segment
		(start 378.101606 -200.47585)
		(end 379.015244 -198.270114)
		(width 0.13208)
		(layer "F.Cu")
		(net "UPI_CPU1_CPU0_P0P1_DN<2>")
	)
	(segment
		(start 378.062236 -200.67397)
		(end 378.101606 -200.47585)
		(width 0.13208)
		(layer "F.Cu")
		(net "UPI_CPU1_CPU0_P0P1_DN<2>")
	)
	(segment
		(start 387.623812 -186.793886)
		(end 384.319526 -178.817016)
		(width 0.13208)
		(layer "F.Cu")
		(net "UPI_CPU1_CPU0_P0P1_DN<2>")
	)
	(segment
		(start 376.829574 -171.32681)
		(end 375.102374 -169.909236)
		(width 0.13208)
		(layer "F.Cu")
		(net "UPI_CPU1_CPU0_P0P1_DN<2>")
	)
	(segment
		(start 90.494866 -214.344758)
		(end 90.494866 -213.732618)
		(width 0.13208)
		(layer "F.Cu")
		(net "UPI_CPU1_CPU0_P0P1_DN<2>")
	)
	(segment
		(start 375.102374 -169.909236)
		(end 374.829578 -169.796206)
		(width 0.13208)
		(layer "F.Cu")
		(net "UPI_CPU1_CPU0_P0P1_DN<2>")
	)
	(segment
		(start 380.725934 -215.972644)
		(end 380.881128 -215.703658)
		(width 0.0889)
		(layer "F.Cu")
		(net "UPI_CPU1_CPU0_P0P1_DN<2>")
	)
	(segment
		(start 384.319526 -178.817016)
		(end 376.829574 -171.32681)
		(width 0.13208)
		(layer "F.Cu")
		(net "UPI_CPU1_CPU0_P0P1_DN<2>")
	)
	(segment
		(start 370.899436 -169.94378)
		(end 370.898928 -169.943018)
		(width 0.13208)
		(layer "F.Cu")
		(net "UPI_CPU1_CPU0_P0P1_DN<2>")
	)
	(arc
		(start 380.993904 -215.687148)
		(mid 381.510606 -215.628491)
		(end 381.760984 -215.172798)
		(width 0.0889)
		(layer "F.Cu")
		(net "UPI_CPU1_CPU0_P0P1_DN<2>")
	)
	(arc
		(start 380.973584 -215.67902)
		(mid 380.983704 -215.683183)
		(end 380.993904 -215.687148)
		(width 0.0889)
		(layer "F.Cu")
		(net "UPI_CPU1_CPU0_P0P1_DN<2>")
	)
	(segment
		(start 90.869516 -211.835238)
		(end 90.869516 -212.301836)
		(width 0.0889)
		(layer "In6.Cu")
		(net "UPI_CPU1_CPU0_P0P1_DN<2>")
	)
	(segment
		(start 90.770202 -212.66785)
		(end 90.869516 -212.767164)
		(width 0.0889)
		(layer "In6.Cu")
		(net "UPI_CPU1_CPU0_P0P1_DN<2>")
	)
	(segment
		(start 90.827606 -211.793328)
		(end 90.869516 -211.835238)
		(width 0.0889)
		(layer "In6.Cu")
		(net "UPI_CPU1_CPU0_P0P1_DN<2>")
	)
	(segment
		(start 90.869516 -212.767164)
		(end 90.869516 -213.033864)
		(width 0.0889)
		(layer "In6.Cu")
		(net "UPI_CPU1_CPU0_P0P1_DN<2>")
	)
	(segment
		(start 91.658694 -207.88884)
		(end 91.657932 -207.891126)
		(width 0.14732)
		(layer "In6.Cu")
		(net "UPI_CPU1_CPU0_P0P1_DN<2>")
	)
	(segment
		(start 160.103566 -140.612368)
		(end 123.886468 -162.898328)
		(width 0.14732)
		(layer "In6.Cu")
		(net "UPI_CPU1_CPU0_P0P1_DN<2>")
	)
	(segment
		(start 123.886468 -162.898328)
		(end 103.212392 -182.347362)
		(width 0.14732)
		(layer "In6.Cu")
		(net "UPI_CPU1_CPU0_P0P1_DN<2>")
	)
	(segment
		(start 370.506244 -169.245788)
		(end 370.505736 -169.245026)
		(width 0.14732)
		(layer "In6.Cu")
		(net "UPI_CPU1_CPU0_P0P1_DN<2>")
	)
	(segment
		(start 360.856276 -162.02025)
		(end 333.344266 -143.145764)
		(width 0.14732)
		(layer "In6.Cu")
		(net "UPI_CPU1_CPU0_P0P1_DN<2>")
	)
	(segment
		(start 95.719138 -196.934836)
		(end 91.658694 -207.88884)
		(width 0.14732)
		(layer "In6.Cu")
		(net "UPI_CPU1_CPU0_P0P1_DN<2>")
	)
	(segment
		(start 90.827606 -211.77123)
		(end 90.827606 -211.793328)
		(width 0.0889)
		(layer "In6.Cu")
		(net "UPI_CPU1_CPU0_P0P1_DN<2>")
	)
	(segment
		(start 333.344266 -143.145764)
		(end 319.29832 -139.544552)
		(width 0.14732)
		(layer "In6.Cu")
		(net "UPI_CPU1_CPU0_P0P1_DN<2>")
	)
	(segment
		(start 371.046756 -169.390568)
		(end 370.506244 -169.245788)
		(width 0.14732)
		(layer "In6.Cu")
		(net "UPI_CPU1_CPU0_P0P1_DN<2>")
	)
	(segment
		(start 90.770202 -213.133178)
		(end 90.770202 -213.399878)
		(width 0.0889)
		(layer "In6.Cu")
		(net "UPI_CPU1_CPU0_P0P1_DN<2>")
	)
	(segment
		(start 90.869516 -212.301836)
		(end 90.770202 -212.40115)
		(width 0.0889)
		(layer "In6.Cu")
		(net "UPI_CPU1_CPU0_P0P1_DN<2>")
	)
	(segment
		(start 90.738198 -214.05977)
		(end 90.653616 -214.033608)
		(width 0.0889)
		(layer "In6.Cu")
		(net "UPI_CPU1_CPU0_P0P1_DN<2>")
	)
	(segment
		(start 370.358162 -168.989756)
		(end 369.992402 -168.817798)
		(width 0.14732)
		(layer "In6.Cu")
		(net "UPI_CPU1_CPU0_P0P1_DN<2>")
	)
	(segment
		(start 368.516662 -168.3512)
		(end 360.856276 -162.02025)
		(width 0.14732)
		(layer "In6.Cu")
		(net "UPI_CPU1_CPU0_P0P1_DN<2>")
	)
	(segment
		(start 90.770202 -213.399878)
		(end 90.869516 -213.499192)
		(width 0.0889)
		(layer "In6.Cu")
		(net "UPI_CPU1_CPU0_P0P1_DN<2>")
	)
	(segment
		(start 99.332796 -187.1853)
		(end 95.719138 -196.934836)
		(width 0.14732)
		(layer "In6.Cu")
		(net "UPI_CPU1_CPU0_P0P1_DN<2>")
	)
	(segment
		(start 90.869516 -213.033864)
		(end 90.770202 -213.133178)
		(width 0.0889)
		(layer "In6.Cu")
		(net "UPI_CPU1_CPU0_P0P1_DN<2>")
	)
	(segment
		(start 271.483836 -137.836402)
		(end 238.617252 -138.424158)
		(width 0.14732)
		(layer "In6.Cu")
		(net "UPI_CPU1_CPU0_P0P1_DN<2>")
	)
	(segment
		(start 169.665142 -137.302748)
		(end 160.103566 -140.612368)
		(width 0.14732)
		(layer "In6.Cu")
		(net "UPI_CPU1_CPU0_P0P1_DN<2>")
	)
	(segment
		(start 238.609886 -138.424158)
		(end 169.665142 -137.302748)
		(width 0.14732)
		(layer "In6.Cu")
		(net "UPI_CPU1_CPU0_P0P1_DN<2>")
	)
	(segment
		(start 312.239152 -139.544552)
		(end 271.483836 -137.836402)
		(width 0.14732)
		(layer "In6.Cu")
		(net "UPI_CPU1_CPU0_P0P1_DN<2>")
	)
	(segment
		(start 369.45951 -168.728644)
		(end 368.516662 -168.3512)
		(width 0.14732)
		(layer "In6.Cu")
		(net "UPI_CPU1_CPU0_P0P1_DN<2>")
	)
	(segment
		(start 370.505736 -169.245026)
		(end 370.358162 -168.989756)
		(width 0.14732)
		(layer "In6.Cu")
		(net "UPI_CPU1_CPU0_P0P1_DN<2>")
	)
	(segment
		(start 103.212392 -182.347362)
		(end 99.332796 -187.1853)
		(width 0.14732)
		(layer "In6.Cu")
		(net "UPI_CPU1_CPU0_P0P1_DN<2>")
	)
	(segment
		(start 90.770202 -212.40115)
		(end 90.770202 -212.66785)
		(width 0.0889)
		(layer "In6.Cu")
		(net "UPI_CPU1_CPU0_P0P1_DN<2>")
	)
	(segment
		(start 319.29832 -139.544552)
		(end 312.239152 -139.544552)
		(width 0.14732)
		(layer "In6.Cu")
		(net "UPI_CPU1_CPU0_P0P1_DN<2>")
	)
	(segment
		(start 90.869516 -213.499192)
		(end 90.869516 -213.8934)
		(width 0.0889)
		(layer "In6.Cu")
		(net "UPI_CPU1_CPU0_P0P1_DN<2>")
	)
	(segment
		(start 90.827606 -210.131152)
		(end 90.827606 -211.77123)
		(width 0.14732)
		(layer "In6.Cu")
		(net "UPI_CPU1_CPU0_P0P1_DN<2>")
	)
	(segment
		(start 91.657932 -207.891126)
		(end 90.827606 -210.131152)
		(width 0.14732)
		(layer "In6.Cu")
		(net "UPI_CPU1_CPU0_P0P1_DN<2>")
	)
	(segment
		(start 238.617252 -138.424158)
		(end 238.609886 -138.424158)
		(width 0.14732)
		(layer "In6.Cu")
		(net "UPI_CPU1_CPU0_P0P1_DN<2>")
	)
	(segment
		(start 369.992402 -168.817798)
		(end 369.45951 -168.728644)
		(width 0.14732)
		(layer "In6.Cu")
		(net "UPI_CPU1_CPU0_P0P1_DN<2>")
	)
	(segment
		(start 90.653616 -214.033608)
		(end 90.494866 -213.732618)
		(width 0.0889)
		(layer "In6.Cu")
		(net "UPI_CPU1_CPU0_P0P1_DN<2>")
	)
	(arc
		(start 90.869516 -213.8934)
		(mid 90.814846 -213.985256)
		(end 90.738198 -214.05977)
		(width 0.0889)
		(layer "In6.Cu")
		(net "UPI_CPU1_CPU0_P0P1_DN<2>")
	)
	(segment
		(start 360.86034 -214.818214)
		(end 360.86034 -214.164672)
		(width 0.13208)
		(layer "F.Cu")
		(net "UPI_CPU1_CPU0_P0P1_DN<23>")
	)
	(segment
		(start 110.700566 -215.158574)
		(end 110.700566 -214.546434)
		(width 0.13208)
		(layer "F.Cu")
		(net "UPI_CPU1_CPU0_P0P1_DN<23>")
	)
	(segment
		(start 356.147624 -211.991956)
		(end 349.995998 -205.84033)
		(width 0.13208)
		(layer "F.Cu")
		(net "UPI_CPU1_CPU0_P0P1_DN<23>")
	)
	(segment
		(start 360.483912 -213.788244)
		(end 356.147624 -211.991956)
		(width 0.13208)
		(layer "F.Cu")
		(net "UPI_CPU1_CPU0_P0P1_DN<23>")
	)
	(segment
		(start 360.51998 -215.158574)
		(end 360.86034 -214.818214)
		(width 0.13208)
		(layer "F.Cu")
		(net "UPI_CPU1_CPU0_P0P1_DN<23>")
	)
	(segment
		(start 352.023426 -187.26658)
		(end 351.875852 -186.714892)
		(width 0.13208)
		(layer "F.Cu")
		(net "UPI_CPU1_CPU0_P0P1_DN<23>")
	)
	(segment
		(start 349.995998 -205.84033)
		(end 349.995998 -198.234046)
		(width 0.13208)
		(layer "F.Cu")
		(net "UPI_CPU1_CPU0_P0P1_DN<23>")
	)
	(segment
		(start 351.84588 -187.575952)
		(end 351.846134 -187.575698)
		(width 0.13208)
		(layer "F.Cu")
		(net "UPI_CPU1_CPU0_P0P1_DN<23>")
	)
	(segment
		(start 360.86034 -214.164672)
		(end 360.483912 -213.788244)
		(width 0.13208)
		(layer "F.Cu")
		(net "UPI_CPU1_CPU0_P0P1_DN<23>")
	)
	(segment
		(start 351.846388 -187.576206)
		(end 351.84588 -187.575952)
		(width 0.13208)
		(layer "F.Cu")
		(net "UPI_CPU1_CPU0_P0P1_DN<23>")
	)
	(segment
		(start 351.634298 -188.004704)
		(end 351.846134 -187.57646)
		(width 0.13208)
		(layer "F.Cu")
		(net "UPI_CPU1_CPU0_P0P1_DN<23>")
	)
	(segment
		(start 349.995998 -198.234046)
		(end 351.634298 -188.004704)
		(width 0.13208)
		(layer "F.Cu")
		(net "UPI_CPU1_CPU0_P0P1_DN<23>")
	)
	(segment
		(start 351.846134 -187.575698)
		(end 352.023426 -187.26658)
		(width 0.13208)
		(layer "F.Cu")
		(net "UPI_CPU1_CPU0_P0P1_DN<23>")
	)
	(segment
		(start 351.846134 -187.57646)
		(end 351.846388 -187.576206)
		(width 0.13208)
		(layer "F.Cu")
		(net "UPI_CPU1_CPU0_P0P1_DN<23>")
	)
	(segment
		(start 220.359478 -164.902642)
		(end 219.75191 -162.546284)
		(width 0.14732)
		(layer "In6.Cu")
		(net "UPI_CPU1_CPU0_P0P1_DN<23>")
	)
	(segment
		(start 218.115388 -165.481254)
		(end 217.50782 -163.124896)
		(width 0.14732)
		(layer "In6.Cu")
		(net "UPI_CPU1_CPU0_P0P1_DN<23>")
	)
	(segment
		(start 128.534668 -184.065164)
		(end 128.528572 -184.272936)
		(width 0.14732)
		(layer "In6.Cu")
		(net "UPI_CPU1_CPU0_P0P1_DN<23>")
	)
	(segment
		(start 215.871298 -166.059866)
		(end 215.26373 -163.703508)
		(width 0.14732)
		(layer "In6.Cu")
		(net "UPI_CPU1_CPU0_P0P1_DN<23>")
	)
	(segment
		(start 338.537042 -178.844702)
		(end 321.068954 -169.679366)
		(width 0.14732)
		(layer "In6.Cu")
		(net "UPI_CPU1_CPU0_P0P1_DN<23>")
	)
	(segment
		(start 214.888826 -163.48202)
		(end 214.097616 -163.686236)
		(width 0.14732)
		(layer "In6.Cu")
		(net "UPI_CPU1_CPU0_P0P1_DN<23>")
	)
	(segment
		(start 223.354392 -164.28212)
		(end 222.782384 -164.429694)
		(width 0.14732)
		(layer "In6.Cu")
		(net "UPI_CPU1_CPU0_P0P1_DN<23>")
	)
	(segment
		(start 222.603568 -164.32403)
		(end 221.996 -161.967672)
		(width 0.14732)
		(layer "In6.Cu")
		(net "UPI_CPU1_CPU0_P0P1_DN<23>")
	)
	(segment
		(start 227.270564 -163.27247)
		(end 227.091748 -163.166806)
		(width 0.14732)
		(layer "In6.Cu")
		(net "UPI_CPU1_CPU0_P0P1_DN<23>")
	)
	(segment
		(start 199.602598 -167.423084)
		(end 195.149216 -167.996108)
		(width 0.14732)
		(layer "In6.Cu")
		(net "UPI_CPU1_CPU0_P0P1_DN<23>")
	)
	(segment
		(start 111.075216 -212.276436)
		(end 110.975902 -212.37575)
		(width 0.0889)
		(layer "In6.Cu")
		(net "UPI_CPU1_CPU0_P0P1_DN<23>")
	)
	(segment
		(start 134.127494 -178.02352)
		(end 131.747768 -180.268626)
		(width 0.14732)
		(layer "In6.Cu")
		(net "UPI_CPU1_CPU0_P0P1_DN<23>")
	)
	(segment
		(start 219.75191 -162.546284)
		(end 219.377006 -162.324796)
		(width 0.14732)
		(layer "In6.Cu")
		(net "UPI_CPU1_CPU0_P0P1_DN<23>")
	)
	(segment
		(start 116.016024 -197.379336)
		(end 111.033306 -211.467446)
		(width 0.14732)
		(layer "In6.Cu")
		(net "UPI_CPU1_CPU0_P0P1_DN<23>")
	)
	(segment
		(start 126.679706 -185.476388)
		(end 126.849378 -185.655966)
		(width 0.14732)
		(layer "In6.Cu")
		(net "UPI_CPU1_CPU0_P0P1_DN<23>")
	)
	(segment
		(start 224.24009 -161.38906)
		(end 223.865186 -161.167572)
		(width 0.14732)
		(layer "In6.Cu")
		(net "UPI_CPU1_CPU0_P0P1_DN<23>")
	)
	(segment
		(start 226.109276 -160.58896)
		(end 225.318066 -160.793176)
		(width 0.14732)
		(layer "In6.Cu")
		(net "UPI_CPU1_CPU0_P0P1_DN<23>")
	)
	(segment
		(start 218.866212 -165.439344)
		(end 218.294204 -165.586918)
		(width 0.14732)
		(layer "In6.Cu")
		(net "UPI_CPU1_CPU0_P0P1_DN<23>")
	)
	(segment
		(start 111.033306 -211.666328)
		(end 111.075216 -211.708238)
		(width 0.0889)
		(layer "In6.Cu")
		(net "UPI_CPU1_CPU0_P0P1_DN<23>")
	)
	(segment
		(start 126.20625 -186.26328)
		(end 126.036578 -186.083194)
		(width 0.14732)
		(layer "In6.Cu")
		(net "UPI_CPU1_CPU0_P0P1_DN<23>")
	)
	(segment
		(start 110.975902 -212.37575)
		(end 110.975902 -212.64245)
		(width 0.0889)
		(layer "In6.Cu")
		(net "UPI_CPU1_CPU0_P0P1_DN<23>")
	)
	(segment
		(start 110.975902 -212.64245)
		(end 111.075216 -212.741764)
		(width 0.0889)
		(layer "In6.Cu")
		(net "UPI_CPU1_CPU0_P0P1_DN<23>")
	)
	(segment
		(start 131.26212 -181.490874)
		(end 131.092448 -181.310788)
		(width 0.14732)
		(layer "In6.Cu")
		(net "UPI_CPU1_CPU0_P0P1_DN<23>")
	)
	(segment
		(start 224.847658 -163.745418)
		(end 224.24009 -161.38906)
		(width 0.14732)
		(layer "In6.Cu")
		(net "UPI_CPU1_CPU0_P0P1_DN<23>")
	)
	(segment
		(start 223.865186 -161.167572)
		(end 223.073976 -161.371788)
		(width 0.14732)
		(layer "In6.Cu")
		(net "UPI_CPU1_CPU0_P0P1_DN<23>")
	)
	(segment
		(start 218.364308 -162.903916)
		(end 218.971876 -165.260274)
		(width 0.14732)
		(layer "In6.Cu")
		(net "UPI_CPU1_CPU0_P0P1_DN<23>")
	)
	(segment
		(start 189.34938 -167.996108)
		(end 155.42133 -168.754298)
		(width 0.14732)
		(layer "In6.Cu")
		(net "UPI_CPU1_CPU0_P0P1_DN<23>")
	)
	(segment
		(start 131.899152 -181.091332)
		(end 131.469638 -181.49697)
		(width 0.14732)
		(layer "In6.Cu")
		(net "UPI_CPU1_CPU0_P0P1_DN<23>")
	)
	(segment
		(start 111.075216 -211.708238)
		(end 111.075216 -212.276436)
		(width 0.0889)
		(layer "In6.Cu")
		(net "UPI_CPU1_CPU0_P0P1_DN<23>")
	)
	(segment
		(start 219.377006 -162.324796)
		(end 218.585796 -162.529012)
		(width 0.14732)
		(layer "In6.Cu")
		(net "UPI_CPU1_CPU0_P0P1_DN<23>")
	)
	(segment
		(start 213.627208 -166.638478)
		(end 213.01964 -164.28212)
		(width 0.14732)
		(layer "In6.Cu")
		(net "UPI_CPU1_CPU0_P0P1_DN<23>")
	)
	(segment
		(start 126.849378 -185.655966)
		(end 126.843282 -185.863738)
		(width 0.14732)
		(layer "In6.Cu")
		(net "UPI_CPU1_CPU0_P0P1_DN<23>")
	)
	(segment
		(start 350.639888 -189.055248)
		(end 350.251268 -189.055248)
		(width 0.14732)
		(layer "In6.Cu")
		(net "UPI_CPU1_CPU0_P0P1_DN<23>")
	)
	(segment
		(start 221.110302 -164.860732)
		(end 220.538294 -165.008306)
		(width 0.14732)
		(layer "In6.Cu")
		(net "UPI_CPU1_CPU0_P0P1_DN<23>")
	)
	(segment
		(start 218.971876 -165.260274)
		(end 218.866212 -165.439344)
		(width 0.14732)
		(layer "In6.Cu")
		(net "UPI_CPU1_CPU0_P0P1_DN<23>")
	)
	(segment
		(start 225.598482 -163.703508)
		(end 225.026474 -163.851082)
		(width 0.14732)
		(layer "In6.Cu")
		(net "UPI_CPU1_CPU0_P0P1_DN<23>")
	)
	(segment
		(start 216.727786 -165.838886)
		(end 216.622122 -166.017956)
		(width 0.14732)
		(layer "In6.Cu")
		(net "UPI_CPU1_CPU0_P0P1_DN<23>")
	)
	(segment
		(start 125.600968 -186.071002)
		(end 123.62307 -187.938156)
		(width 0.14732)
		(layer "In6.Cu")
		(net "UPI_CPU1_CPU0_P0P1_DN<23>")
	)
	(segment
		(start 223.073976 -161.371788)
		(end 222.852488 -161.746692)
		(width 0.14732)
		(layer "In6.Cu")
		(net "UPI_CPU1_CPU0_P0P1_DN<23>")
	)
	(segment
		(start 217.132916 -162.903408)
		(end 216.341706 -163.107624)
		(width 0.14732)
		(layer "In6.Cu")
		(net "UPI_CPU1_CPU0_P0P1_DN<23>")
	)
	(segment
		(start 350.251268 -189.055248)
		(end 342.800178 -181.907688)
		(width 0.14732)
		(layer "In6.Cu")
		(net "UPI_CPU1_CPU0_P0P1_DN<23>")
	)
	(segment
		(start 280.281888 -167.9194)
		(end 274.505674 -167.9194)
		(width 0.14732)
		(layer "In6.Cu")
		(net "UPI_CPU1_CPU0_P0P1_DN<23>")
	)
	(segment
		(start 129.57683 -183.081676)
		(end 129.407158 -182.90159)
		(width 0.14732)
		(layer "In6.Cu")
		(net "UPI_CPU1_CPU0_P0P1_DN<23>")
	)
	(segment
		(start 131.905248 -180.88356)
		(end 131.899152 -181.091332)
		(width 0.14732)
		(layer "In6.Cu")
		(net "UPI_CPU1_CPU0_P0P1_DN<23>")
	)
	(segment
		(start 110.975902 -213.374478)
		(end 111.075216 -213.473792)
		(width 0.0889)
		(layer "In6.Cu")
		(net "UPI_CPU1_CPU0_P0P1_DN<23>")
	)
	(segment
		(start 226.48418 -160.810448)
		(end 226.109276 -160.58896)
		(width 0.14732)
		(layer "In6.Cu")
		(net "UPI_CPU1_CPU0_P0P1_DN<23>")
	)
	(segment
		(start 131.735576 -180.703982)
		(end 131.905248 -180.88356)
		(width 0.14732)
		(layer "In6.Cu")
		(net "UPI_CPU1_CPU0_P0P1_DN<23>")
	)
	(segment
		(start 214.378032 -166.596568)
		(end 213.806024 -166.744142)
		(width 0.14732)
		(layer "In6.Cu")
		(net "UPI_CPU1_CPU0_P0P1_DN<23>")
	)
	(segment
		(start 221.215966 -164.681662)
		(end 221.110302 -164.860732)
		(width 0.14732)
		(layer "In6.Cu")
		(net "UPI_CPU1_CPU0_P0P1_DN<23>")
	)
	(segment
		(start 221.996 -161.967672)
		(end 221.621096 -161.746184)
		(width 0.14732)
		(layer "In6.Cu")
		(net "UPI_CPU1_CPU0_P0P1_DN<23>")
	)
	(segment
		(start 130.062478 -181.859174)
		(end 130.050286 -182.294784)
		(width 0.14732)
		(layer "In6.Cu")
		(net "UPI_CPU1_CPU0_P0P1_DN<23>")
	)
	(segment
		(start 110.859316 -214.847424)
		(end 110.700566 -214.546434)
		(width 0.0889)
		(layer "In6.Cu")
		(net "UPI_CPU1_CPU0_P0P1_DN<23>")
	)
	(segment
		(start 131.747768 -180.268626)
		(end 131.735576 -180.703982)
		(width 0.14732)
		(layer "In6.Cu")
		(net "UPI_CPU1_CPU0_P0P1_DN<23>")
	)
	(segment
		(start 220.538294 -165.008306)
		(end 220.359478 -164.902642)
		(width 0.14732)
		(layer "In6.Cu")
		(net "UPI_CPU1_CPU0_P0P1_DN<23>")
	)
	(segment
		(start 110.943898 -214.873586)
		(end 110.859316 -214.847424)
		(width 0.0889)
		(layer "In6.Cu")
		(net "UPI_CPU1_CPU0_P0P1_DN<23>")
	)
	(segment
		(start 128.528572 -184.272936)
		(end 128.099058 -184.678574)
		(width 0.14732)
		(layer "In6.Cu")
		(net "UPI_CPU1_CPU0_P0P1_DN<23>")
	)
	(segment
		(start 130.050286 -182.294784)
		(end 130.219958 -182.474362)
		(width 0.14732)
		(layer "In6.Cu")
		(net "UPI_CPU1_CPU0_P0P1_DN<23>")
	)
	(segment
		(start 351.875852 -186.714892)
		(end 352.02114 -187.25642)
		(width 0.14732)
		(layer "In6.Cu")
		(net "UPI_CPU1_CPU0_P0P1_DN<23>")
	)
	(segment
		(start 218.294204 -165.586918)
		(end 218.115388 -165.481254)
		(width 0.14732)
		(layer "In6.Cu")
		(net "UPI_CPU1_CPU0_P0P1_DN<23>")
	)
	(segment
		(start 227.948236 -162.945826)
		(end 227.842572 -163.124896)
		(width 0.14732)
		(layer "In6.Cu")
		(net "UPI_CPU1_CPU0_P0P1_DN<23>")
	)
	(segment
		(start 227.842572 -163.124896)
		(end 227.270564 -163.27247)
		(width 0.14732)
		(layer "In6.Cu")
		(net "UPI_CPU1_CPU0_P0P1_DN<23>")
	)
	(segment
		(start 352.019362 -187.259722)
		(end 351.707704 -187.799218)
		(width 0.14732)
		(layer "In6.Cu")
		(net "UPI_CPU1_CPU0_P0P1_DN<23>")
	)
	(segment
		(start 342.800178 -181.907688)
		(end 338.537042 -178.844702)
		(width 0.14732)
		(layer "In6.Cu")
		(net "UPI_CPU1_CPU0_P0P1_DN<23>")
	)
	(segment
		(start 126.691898 -185.040778)
		(end 126.679706 -185.476388)
		(width 0.14732)
		(layer "In6.Cu")
		(net "UPI_CPU1_CPU0_P0P1_DN<23>")
	)
	(segment
		(start 127.89154 -184.672478)
		(end 127.721868 -184.492392)
		(width 0.14732)
		(layer "In6.Cu")
		(net "UPI_CPU1_CPU0_P0P1_DN<23>")
	)
	(segment
		(start 225.026474 -163.851082)
		(end 224.847658 -163.745418)
		(width 0.14732)
		(layer "In6.Cu")
		(net "UPI_CPU1_CPU0_P0P1_DN<23>")
	)
	(segment
		(start 222.782384 -164.429694)
		(end 222.603568 -164.32403)
		(width 0.14732)
		(layer "In6.Cu")
		(net "UPI_CPU1_CPU0_P0P1_DN<23>")
	)
	(segment
		(start 225.318066 -160.793176)
		(end 225.096578 -161.16808)
		(width 0.14732)
		(layer "In6.Cu")
		(net "UPI_CPU1_CPU0_P0P1_DN<23>")
	)
	(segment
		(start 214.483696 -166.417498)
		(end 214.378032 -166.596568)
		(width 0.14732)
		(layer "In6.Cu")
		(net "UPI_CPU1_CPU0_P0P1_DN<23>")
	)
	(segment
		(start 130.219958 -182.474362)
		(end 130.213862 -182.682134)
		(width 0.14732)
		(layer "In6.Cu")
		(net "UPI_CPU1_CPU0_P0P1_DN<23>")
	)
	(segment
		(start 215.26373 -163.703508)
		(end 214.888826 -163.48202)
		(width 0.14732)
		(layer "In6.Cu")
		(net "UPI_CPU1_CPU0_P0P1_DN<23>")
	)
	(segment
		(start 225.704146 -163.524438)
		(end 225.598482 -163.703508)
		(width 0.14732)
		(layer "In6.Cu")
		(net "UPI_CPU1_CPU0_P0P1_DN<23>")
	)
	(segment
		(start 111.033306 -211.467446)
		(end 111.033306 -211.64423)
		(width 0.14732)
		(layer "In6.Cu")
		(net "UPI_CPU1_CPU0_P0P1_DN<23>")
	)
	(segment
		(start 214.097616 -163.686236)
		(end 213.876128 -164.06114)
		(width 0.14732)
		(layer "In6.Cu")
		(net "UPI_CPU1_CPU0_P0P1_DN<23>")
	)
	(segment
		(start 131.092448 -181.310788)
		(end 130.657092 -181.298596)
		(width 0.14732)
		(layer "In6.Cu")
		(net "UPI_CPU1_CPU0_P0P1_DN<23>")
	)
	(segment
		(start 213.876128 -164.06114)
		(end 214.483696 -166.417498)
		(width 0.14732)
		(layer "In6.Cu")
		(net "UPI_CPU1_CPU0_P0P1_DN<23>")
	)
	(segment
		(start 195.149216 -167.996108)
		(end 189.34938 -167.996108)
		(width 0.14732)
		(layer "In6.Cu")
		(net "UPI_CPU1_CPU0_P0P1_DN<23>")
	)
	(segment
		(start 225.096578 -161.16808)
		(end 225.704146 -163.524438)
		(width 0.14732)
		(layer "In6.Cu")
		(net "UPI_CPU1_CPU0_P0P1_DN<23>")
	)
	(segment
		(start 126.413768 -186.269376)
		(end 126.20625 -186.26328)
		(width 0.14732)
		(layer "In6.Cu")
		(net "UPI_CPU1_CPU0_P0P1_DN<23>")
	)
	(segment
		(start 351.707704 -187.799218)
		(end 351.2058 -188.489336)
		(width 0.14732)
		(layer "In6.Cu")
		(net "UPI_CPU1_CPU0_P0P1_DN<23>")
	)
	(segment
		(start 222.852488 -161.746692)
		(end 223.460056 -164.10305)
		(width 0.14732)
		(layer "In6.Cu")
		(net "UPI_CPU1_CPU0_P0P1_DN<23>")
	)
	(segment
		(start 218.585796 -162.529012)
		(end 218.364308 -162.903916)
		(width 0.14732)
		(layer "In6.Cu")
		(net "UPI_CPU1_CPU0_P0P1_DN<23>")
	)
	(segment
		(start 302.489108 -167.541194)
		(end 280.281888 -167.9194)
		(width 0.14732)
		(layer "In6.Cu")
		(net "UPI_CPU1_CPU0_P0P1_DN<23>")
	)
	(segment
		(start 128.971802 -182.889398)
		(end 128.377188 -183.449976)
		(width 0.14732)
		(layer "In6.Cu")
		(net "UPI_CPU1_CPU0_P0P1_DN<23>")
	)
	(segment
		(start 213.01964 -164.28212)
		(end 212.644736 -164.060632)
		(width 0.14732)
		(layer "In6.Cu")
		(net "UPI_CPU1_CPU0_P0P1_DN<23>")
	)
	(segment
		(start 216.622122 -166.017956)
		(end 216.050114 -166.16553)
		(width 0.14732)
		(layer "In6.Cu")
		(net "UPI_CPU1_CPU0_P0P1_DN<23>")
	)
	(segment
		(start 130.213862 -182.682134)
		(end 129.784348 -183.087772)
		(width 0.14732)
		(layer "In6.Cu")
		(net "UPI_CPU1_CPU0_P0P1_DN<23>")
	)
	(segment
		(start 128.377188 -183.449976)
		(end 128.364996 -183.885586)
		(width 0.14732)
		(layer "In6.Cu")
		(net "UPI_CPU1_CPU0_P0P1_DN<23>")
	)
	(segment
		(start 155.42133 -168.754298)
		(end 149.20976 -170.321478)
		(width 0.14732)
		(layer "In6.Cu")
		(net "UPI_CPU1_CPU0_P0P1_DN<23>")
	)
	(segment
		(start 216.341706 -163.107624)
		(end 216.120218 -163.482528)
		(width 0.14732)
		(layer "In6.Cu")
		(net "UPI_CPU1_CPU0_P0P1_DN<23>")
	)
	(segment
		(start 351.2058 -188.489336)
		(end 350.639888 -189.055248)
		(width 0.14732)
		(layer "In6.Cu")
		(net "UPI_CPU1_CPU0_P0P1_DN<23>")
	)
	(segment
		(start 149.20976 -170.321478)
		(end 134.127494 -178.02352)
		(width 0.14732)
		(layer "In6.Cu")
		(net "UPI_CPU1_CPU0_P0P1_DN<23>")
	)
	(segment
		(start 220.608398 -162.325304)
		(end 221.215966 -164.681662)
		(width 0.14732)
		(layer "In6.Cu")
		(net "UPI_CPU1_CPU0_P0P1_DN<23>")
	)
	(segment
		(start 111.075216 -212.741764)
		(end 111.075216 -213.008464)
		(width 0.0889)
		(layer "In6.Cu")
		(net "UPI_CPU1_CPU0_P0P1_DN<23>")
	)
	(segment
		(start 123.62307 -187.938156)
		(end 116.016024 -197.379336)
		(width 0.14732)
		(layer "In6.Cu")
		(net "UPI_CPU1_CPU0_P0P1_DN<23>")
	)
	(segment
		(start 216.120218 -163.482528)
		(end 216.727786 -165.838886)
		(width 0.14732)
		(layer "In6.Cu")
		(net "UPI_CPU1_CPU0_P0P1_DN<23>")
	)
	(segment
		(start 217.50782 -163.124896)
		(end 217.132916 -162.903408)
		(width 0.14732)
		(layer "In6.Cu")
		(net "UPI_CPU1_CPU0_P0P1_DN<23>")
	)
	(segment
		(start 127.721868 -184.492392)
		(end 127.286512 -184.4802)
		(width 0.14732)
		(layer "In6.Cu")
		(net "UPI_CPU1_CPU0_P0P1_DN<23>")
	)
	(segment
		(start 129.784348 -183.087772)
		(end 129.57683 -183.081676)
		(width 0.14732)
		(layer "In6.Cu")
		(net "UPI_CPU1_CPU0_P0P1_DN<23>")
	)
	(segment
		(start 128.364996 -183.885586)
		(end 128.534668 -184.065164)
		(width 0.14732)
		(layer "In6.Cu")
		(net "UPI_CPU1_CPU0_P0P1_DN<23>")
	)
	(segment
		(start 236.019848 -158.034228)
		(end 227.562156 -160.214564)
		(width 0.14732)
		(layer "In6.Cu")
		(net "UPI_CPU1_CPU0_P0P1_DN<23>")
	)
	(segment
		(start 321.068954 -169.679366)
		(end 314.3504 -167.783256)
		(width 0.14732)
		(layer "In6.Cu")
		(net "UPI_CPU1_CPU0_P0P1_DN<23>")
	)
	(segment
		(start 128.099058 -184.678574)
		(end 127.89154 -184.672478)
		(width 0.14732)
		(layer "In6.Cu")
		(net "UPI_CPU1_CPU0_P0P1_DN<23>")
	)
	(segment
		(start 111.075216 -213.008464)
		(end 110.975902 -213.107778)
		(width 0.0889)
		(layer "In6.Cu")
		(net "UPI_CPU1_CPU0_P0P1_DN<23>")
	)
	(segment
		(start 223.460056 -164.10305)
		(end 223.354392 -164.28212)
		(width 0.14732)
		(layer "In6.Cu")
		(net "UPI_CPU1_CPU0_P0P1_DN<23>")
	)
	(segment
		(start 110.975902 -213.107778)
		(end 110.975902 -213.374478)
		(width 0.0889)
		(layer "In6.Cu")
		(net "UPI_CPU1_CPU0_P0P1_DN<23>")
	)
	(segment
		(start 314.3504 -167.783256)
		(end 302.489108 -167.541194)
		(width 0.14732)
		(layer "In6.Cu")
		(net "UPI_CPU1_CPU0_P0P1_DN<23>")
	)
	(segment
		(start 131.469638 -181.49697)
		(end 131.26212 -181.490874)
		(width 0.14732)
		(layer "In6.Cu")
		(net "UPI_CPU1_CPU0_P0P1_DN<23>")
	)
	(segment
		(start 227.340668 -160.589468)
		(end 227.948236 -162.945826)
		(width 0.14732)
		(layer "In6.Cu")
		(net "UPI_CPU1_CPU0_P0P1_DN<23>")
	)
	(segment
		(start 126.036578 -186.083194)
		(end 125.600968 -186.071002)
		(width 0.14732)
		(layer "In6.Cu")
		(net "UPI_CPU1_CPU0_P0P1_DN<23>")
	)
	(segment
		(start 227.091748 -163.166806)
		(end 226.48418 -160.810448)
		(width 0.14732)
		(layer "In6.Cu")
		(net "UPI_CPU1_CPU0_P0P1_DN<23>")
	)
	(segment
		(start 274.505674 -167.9194)
		(end 236.019848 -158.034228)
		(width 0.14732)
		(layer "In6.Cu")
		(net "UPI_CPU1_CPU0_P0P1_DN<23>")
	)
	(segment
		(start 227.562156 -160.214564)
		(end 227.340668 -160.589468)
		(width 0.14732)
		(layer "In6.Cu")
		(net "UPI_CPU1_CPU0_P0P1_DN<23>")
	)
	(segment
		(start 213.806024 -166.744142)
		(end 213.627208 -166.638478)
		(width 0.14732)
		(layer "In6.Cu")
		(net "UPI_CPU1_CPU0_P0P1_DN<23>")
	)
	(segment
		(start 352.02114 -187.25642)
		(end 352.019362 -187.259722)
		(width 0.14732)
		(layer "In6.Cu")
		(net "UPI_CPU1_CPU0_P0P1_DN<23>")
	)
	(segment
		(start 130.657092 -181.298596)
		(end 130.062478 -181.859174)
		(width 0.14732)
		(layer "In6.Cu")
		(net "UPI_CPU1_CPU0_P0P1_DN<23>")
	)
	(segment
		(start 212.644736 -164.060632)
		(end 199.602598 -167.423084)
		(width 0.14732)
		(layer "In6.Cu")
		(net "UPI_CPU1_CPU0_P0P1_DN<23>")
	)
	(segment
		(start 127.286512 -184.4802)
		(end 126.691898 -185.040778)
		(width 0.14732)
		(layer "In6.Cu")
		(net "UPI_CPU1_CPU0_P0P1_DN<23>")
	)
	(segment
		(start 221.621096 -161.746184)
		(end 220.829886 -161.9504)
		(width 0.14732)
		(layer "In6.Cu")
		(net "UPI_CPU1_CPU0_P0P1_DN<23>")
	)
	(segment
		(start 111.075216 -213.473792)
		(end 111.075216 -214.707216)
		(width 0.0889)
		(layer "In6.Cu")
		(net "UPI_CPU1_CPU0_P0P1_DN<23>")
	)
	(segment
		(start 111.033306 -211.64423)
		(end 111.033306 -211.666328)
		(width 0.0889)
		(layer "In6.Cu")
		(net "UPI_CPU1_CPU0_P0P1_DN<23>")
	)
	(segment
		(start 126.843282 -185.863738)
		(end 126.413768 -186.269376)
		(width 0.14732)
		(layer "In6.Cu")
		(net "UPI_CPU1_CPU0_P0P1_DN<23>")
	)
	(segment
		(start 220.829886 -161.9504)
		(end 220.608398 -162.325304)
		(width 0.14732)
		(layer "In6.Cu")
		(net "UPI_CPU1_CPU0_P0P1_DN<23>")
	)
	(segment
		(start 216.050114 -166.16553)
		(end 215.871298 -166.059866)
		(width 0.14732)
		(layer "In6.Cu")
		(net "UPI_CPU1_CPU0_P0P1_DN<23>")
	)
	(segment
		(start 129.407158 -182.90159)
		(end 128.971802 -182.889398)
		(width 0.14732)
		(layer "In6.Cu")
		(net "UPI_CPU1_CPU0_P0P1_DN<23>")
	)
	(arc
		(start 111.075216 -214.707216)
		(mid 111.020546 -214.799072)
		(end 110.943898 -214.873586)
		(width 0.0889)
		(layer "In6.Cu")
		(net "UPI_CPU1_CPU0_P0P1_DN<23>")
	)
	(segment
		(start 352.39706 -185.760614)
		(end 349.88881 -183.25211)
		(width 0.13208)
		(layer "F.Cu")
		(net "UPI_CPU1_CPU0_P0P1_DN<22>")
	)
	(segment
		(start 351.304098 -205.227174)
		(end 351.304098 -205.205076)
		(width 0.0889)
		(layer "F.Cu")
		(net "UPI_CPU1_CPU0_P0P1_DN<22>")
	)
	(segment
		(start 361.80268 -213.614)
		(end 361.280964 -213.092538)
		(width 0.0889)
		(layer "F.Cu")
		(net "UPI_CPU1_CPU0_P0P1_DN<22>")
	)
	(segment
		(start 352.445066 -192.737994)
		(end 353.023678 -191.33947)
		(width 0.13208)
		(layer "F.Cu")
		(net "UPI_CPU1_CPU0_P0P1_DN<22>")
	)
	(segment
		(start 351.338388 -205.261464)
		(end 351.304098 -205.227174)
		(width 0.0889)
		(layer "F.Cu")
		(net "UPI_CPU1_CPU0_P0P1_DN<22>")
	)
	(segment
		(start 110.230666 -215.436958)
		(end 110.230412 -215.436704)
		(width 0.13208)
		(layer "F.Cu")
		(net "UPI_CPU1_CPU0_P0P1_DN<22>")
	)
	(segment
		(start 361.802426 -213.93531)
		(end 361.80268 -213.935056)
		(width 0.0889)
		(layer "F.Cu")
		(net "UPI_CPU1_CPU0_P0P1_DN<22>")
	)
	(segment
		(start 351.338388 -205.53426)
		(end 351.338388 -205.261464)
		(width 0.0889)
		(layer "F.Cu")
		(net "UPI_CPU1_CPU0_P0P1_DN<22>")
	)
	(segment
		(start 351.507552 -197.456044)
		(end 351.874328 -195.608956)
		(width 0.13208)
		(layer "F.Cu")
		(net "UPI_CPU1_CPU0_P0P1_DN<22>")
	)
	(segment
		(start 354.333302 -187.384944)
		(end 354.210366 -187.088272)
		(width 0.13208)
		(layer "F.Cu")
		(net "UPI_CPU1_CPU0_P0P1_DN<22>")
	)
	(segment
		(start 362.085128 -215.703658)
		(end 362.059982 -215.610694)
		(width 0.0889)
		(layer "F.Cu")
		(net "UPI_CPU1_CPU0_P0P1_DN<22>")
	)
	(segment
		(start 353.885754 -186.775598)
		(end 352.39706 -185.760614)
		(width 0.13208)
		(layer "F.Cu")
		(net "UPI_CPU1_CPU0_P0P1_DN<22>")
	)
	(segment
		(start 357.208836 -211.404708)
		(end 351.338388 -205.53426)
		(width 0.0889)
		(layer "F.Cu")
		(net "UPI_CPU1_CPU0_P0P1_DN<22>")
	)
	(segment
		(start 354.333302 -188.174122)
		(end 354.333302 -187.384944)
		(width 0.13208)
		(layer "F.Cu")
		(net "UPI_CPU1_CPU0_P0P1_DN<22>")
	)
	(segment
		(start 361.834684 -215.012016)
		(end 361.802426 -214.979758)
		(width 0.0889)
		(layer "F.Cu")
		(net "UPI_CPU1_CPU0_P0P1_DN<22>")
	)
	(segment
		(start 110.230666 -215.972644)
		(end 110.230666 -215.436958)
		(width 0.13208)
		(layer "F.Cu")
		(net "UPI_CPU1_CPU0_P0P1_DN<22>")
	)
	(segment
		(start 353.241356 -190.812928)
		(end 353.174046 -190.650368)
		(width 0.13208)
		(layer "F.Cu")
		(net "UPI_CPU1_CPU0_P0P1_DN<22>")
	)
	(segment
		(start 349.717868 -182.955184)
		(end 349.165672 -182.805832)
		(width 0.13208)
		(layer "F.Cu")
		(net "UPI_CPU1_CPU0_P0P1_DN<22>")
	)
	(segment
		(start 361.280964 -213.092538)
		(end 357.208836 -211.404708)
		(width 0.0889)
		(layer "F.Cu")
		(net "UPI_CPU1_CPU0_P0P1_DN<22>")
	)
	(segment
		(start 351.304098 -198.479664)
		(end 351.507552 -197.456044)
		(width 0.13208)
		(layer "F.Cu")
		(net "UPI_CPU1_CPU0_P0P1_DN<22>")
	)
	(segment
		(start 354.210366 -187.088272)
		(end 353.885754 -186.775598)
		(width 0.13208)
		(layer "F.Cu")
		(net "UPI_CPU1_CPU0_P0P1_DN<22>")
	)
	(segment
		(start 361.834684 -215.166702)
		(end 361.834684 -215.012016)
		(width 0.0889)
		(layer "F.Cu")
		(net "UPI_CPU1_CPU0_P0P1_DN<22>")
	)
	(segment
		(start 352.184716 -194.04711)
		(end 352.445066 -192.737994)
		(width 0.13208)
		(layer "F.Cu")
		(net "UPI_CPU1_CPU0_P0P1_DN<22>")
	)
	(segment
		(start 361.929934 -215.972644)
		(end 361.93476 -215.964262)
		(width 0.0889)
		(layer "F.Cu")
		(net "UPI_CPU1_CPU0_P0P1_DN<22>")
	)
	(segment
		(start 351.304098 -205.205076)
		(end 351.304098 -198.479664)
		(width 0.13208)
		(layer "F.Cu")
		(net "UPI_CPU1_CPU0_P0P1_DN<22>")
	)
	(segment
		(start 353.023678 -191.33947)
		(end 353.241356 -190.812928)
		(width 0.13208)
		(layer "F.Cu")
		(net "UPI_CPU1_CPU0_P0P1_DN<22>")
	)
	(segment
		(start 361.80268 -213.935056)
		(end 361.80268 -213.614)
		(width 0.0889)
		(layer "F.Cu")
		(net "UPI_CPU1_CPU0_P0P1_DN<22>")
	)
	(segment
		(start 351.874328 -195.608956)
		(end 352.184716 -194.04711)
		(width 0.13208)
		(layer "F.Cu")
		(net "UPI_CPU1_CPU0_P0P1_DN<22>")
	)
	(segment
		(start 353.488244 -190.216536)
		(end 354.333302 -188.174122)
		(width 0.13208)
		(layer "F.Cu")
		(net "UPI_CPU1_CPU0_P0P1_DN<22>")
	)
	(segment
		(start 349.88881 -183.25211)
		(end 349.717868 -182.955184)
		(width 0.13208)
		(layer "F.Cu")
		(net "UPI_CPU1_CPU0_P0P1_DN<22>")
	)
	(segment
		(start 353.174046 -190.650368)
		(end 353.32543 -190.2841)
		(width 0.13208)
		(layer "F.Cu")
		(net "UPI_CPU1_CPU0_P0P1_DN<22>")
	)
	(segment
		(start 361.802426 -214.979758)
		(end 361.802426 -213.93531)
		(width 0.0889)
		(layer "F.Cu")
		(net "UPI_CPU1_CPU0_P0P1_DN<22>")
	)
	(segment
		(start 361.93476 -215.964262)
		(end 362.085128 -215.703658)
		(width 0.0889)
		(layer "F.Cu")
		(net "UPI_CPU1_CPU0_P0P1_DN<22>")
	)
	(segment
		(start 353.32543 -190.2841)
		(end 353.488244 -190.216536)
		(width 0.13208)
		(layer "F.Cu")
		(net "UPI_CPU1_CPU0_P0P1_DN<22>")
	)
	(segment
		(start 361.83443 -215.166194)
		(end 361.834684 -215.166702)
		(width 0.0889)
		(layer "F.Cu")
		(net "UPI_CPU1_CPU0_P0P1_DN<22>")
	)
	(arc
		(start 362.059982 -215.610694)
		(mid 362.05141 -215.604171)
		(end 362.042964 -215.597486)
		(width 0.0889)
		(layer "F.Cu")
		(net "UPI_CPU1_CPU0_P0P1_DN<22>")
	)
	(arc
		(start 362.042964 -215.597486)
		(mid 361.890749 -215.405019)
		(end 361.83443 -215.166194)
		(width 0.0889)
		(layer "F.Cu")
		(net "UPI_CPU1_CPU0_P0P1_DN<22>")
	)
	(segment
		(start 302.490124 -166.936166)
		(end 314.440062 -167.180006)
		(width 0.14732)
		(layer "In6.Cu")
		(net "UPI_CPU1_CPU0_P0P1_DN<22>")
	)
	(segment
		(start 163.214812 -167.929814)
		(end 171.934632 -167.72255)
		(width 0.14732)
		(layer "In6.Cu")
		(net "UPI_CPU1_CPU0_P0P1_DN<22>")
	)
	(segment
		(start 338.592414 -178.139598)
		(end 344.442796 -180.304186)
		(width 0.14732)
		(layer "In6.Cu")
		(net "UPI_CPU1_CPU0_P0P1_DN<22>")
	)
	(segment
		(start 177.753772 -167.276018)
		(end 178.068732 -167.577008)
		(width 0.14732)
		(layer "In6.Cu")
		(net "UPI_CPU1_CPU0_P0P1_DN<22>")
	)
	(segment
		(start 160.583118 -167.684196)
		(end 160.898078 -167.984932)
		(width 0.14732)
		(layer "In6.Cu")
		(net "UPI_CPU1_CPU0_P0P1_DN<22>")
	)
	(segment
		(start 110.885732 -209.832956)
		(end 111.041688 -209.758534)
		(width 0.14732)
		(layer "In6.Cu")
		(net "UPI_CPU1_CPU0_P0P1_DN<22>")
	)
	(segment
		(start 147.083526 -168.995344)
		(end 147.281138 -169.059352)
		(width 0.14732)
		(layer "In6.Cu")
		(net "UPI_CPU1_CPU0_P0P1_DN<22>")
	)
	(segment
		(start 158.58109 -168.04005)
		(end 159.398208 -168.020238)
		(width 0.14732)
		(layer "In6.Cu")
		(net "UPI_CPU1_CPU0_P0P1_DN<22>")
	)
	(segment
		(start 152.902412 -166.511986)
		(end 153.08072 -166.618666)
		(width 0.14732)
		(layer "In6.Cu")
		(net "UPI_CPU1_CPU0_P0P1_DN<22>")
	)
	(segment
		(start 133.754622 -177.590196)
		(end 146.873976 -170.890692)
		(width 0.14732)
		(layer "In6.Cu")
		(net "UPI_CPU1_CPU0_P0P1_DN<22>")
	)
	(segment
		(start 237.459012 -157.429454)
		(end 275.966682 -167.320214)
		(width 0.14732)
		(layer "In6.Cu")
		(net "UPI_CPU1_CPU0_P0P1_DN<22>")
	)
	(segment
		(start 179.306728 -166.110666)
		(end 179.897278 -166.096442)
		(width 0.14732)
		(layer "In6.Cu")
		(net "UPI_CPU1_CPU0_P0P1_DN<22>")
	)
	(segment
		(start 174.25162 -167.667432)
		(end 174.55261 -167.352472)
		(width 0.14732)
		(layer "In6.Cu")
		(net "UPI_CPU1_CPU0_P0P1_DN<22>")
	)
	(segment
		(start 345.052396 -182.32501)
		(end 345.44762 -182.143146)
		(width 0.14732)
		(layer "In6.Cu")
		(net "UPI_CPU1_CPU0_P0P1_DN<22>")
	)
	(segment
		(start 344.103198 -181.64556)
		(end 344.285062 -182.040784)
		(width 0.14732)
		(layer "In6.Cu")
		(net "UPI_CPU1_CPU0_P0P1_DN<22>")
	)
	(segment
		(start 172.946314 -166.261796)
		(end 173.096428 -166.405306)
		(width 0.14732)
		(layer "In6.Cu")
		(net "UPI_CPU1_CPU0_P0P1_DN<22>")
	)
	(segment
		(start 174.55261 -167.352472)
		(end 174.529242 -166.37127)
		(width 0.14732)
		(layer "In6.Cu")
		(net "UPI_CPU1_CPU0_P0P1_DN<22>")
	)
	(segment
		(start 159.658558 -166.023798)
		(end 159.802068 -165.87343)
		(width 0.14732)
		(layer "In6.Cu")
		(net "UPI_CPU1_CPU0_P0P1_DN<22>")
	)
	(segment
		(start 162.709606 -165.804088)
		(end 162.859974 -165.947598)
		(width 0.14732)
		(layer "In6.Cu")
		(net "UPI_CPU1_CPU0_P0P1_DN<22>")
	)
	(segment
		(start 346.276676 -182.449978)
		(end 346.45854 -182.845202)
		(width 0.14732)
		(layer "In6.Cu")
		(net "UPI_CPU1_CPU0_P0P1_DN<22>")
	)
	(segment
		(start 150.408386 -169.115486)
		(end 149.975824 -167.40251)
		(width 0.14732)
		(layer "In6.Cu")
		(net "UPI_CPU1_CPU0_P0P1_DN<22>")
	)
	(segment
		(start 196.12864 -167.310054)
		(end 196.713856 -167.236394)
		(width 0.14732)
		(layer "In6.Cu")
		(net "UPI_CPU1_CPU0_P0P1_DN<22>")
	)
	(segment
		(start 152.65527 -168.548304)
		(end 152.222962 -166.835328)
		(width 0.14732)
		(layer "In6.Cu")
		(net "UPI_CPU1_CPU0_P0P1_DN<22>")
	)
	(segment
		(start 181.503574 -167.187118)
		(end 181.480206 -166.205916)
		(width 0.14732)
		(layer "In6.Cu")
		(net "UPI_CPU1_CPU0_P0P1_DN<22>")
	)
	(segment
		(start 177.730404 -166.29507)
		(end 177.753772 -167.276018)
		(width 0.14732)
		(layer "In6.Cu")
		(net "UPI_CPU1_CPU0_P0P1_DN<22>")
	)
	(segment
		(start 112.532922 -205.54315)
		(end 112.678464 -205.131162)
		(width 0.14732)
		(layer "In6.Cu")
		(net "UPI_CPU1_CPU0_P0P1_DN<22>")
	)
	(segment
		(start 111.932974 -207.238854)
		(end 111.858806 -207.083152)
		(width 0.14732)
		(layer "In6.Cu")
		(net "UPI_CPU1_CPU0_P0P1_DN<22>")
	)
	(segment
		(start 150.184612 -169.489374)
		(end 150.408386 -169.115486)
		(width 0.14732)
		(layer "In6.Cu")
		(net "UPI_CPU1_CPU0_P0P1_DN<22>")
	)
	(segment
		(start 180.07076 -167.2209)
		(end 180.38572 -167.52189)
		(width 0.14732)
		(layer "In6.Cu")
		(net "UPI_CPU1_CPU0_P0P1_DN<22>")
	)
	(segment
		(start 172.235622 -167.407844)
		(end 172.212254 -166.426388)
		(width 0.14732)
		(layer "In6.Cu")
		(net "UPI_CPU1_CPU0_P0P1_DN<22>")
	)
	(segment
		(start 158.225998 -166.057834)
		(end 158.26613 -167.739314)
		(width 0.14732)
		(layer "In6.Cu")
		(net "UPI_CPU1_CPU0_P0P1_DN<22>")
	)
	(segment
		(start 348.047564 -181.795166)
		(end 348.23654 -181.708298)
		(width 0.14732)
		(layer "In6.Cu")
		(net "UPI_CPU1_CPU0_P0P1_DN<22>")
	)
	(segment
		(start 171.934632 -167.72255)
		(end 172.235622 -167.407844)
		(width 0.14732)
		(layer "In6.Cu")
		(net "UPI_CPU1_CPU0_P0P1_DN<22>")
	)
	(segment
		(start 110.51286 -210.886802)
		(end 110.668816 -210.81238)
		(width 0.14732)
		(layer "In6.Cu")
		(net "UPI_CPU1_CPU0_P0P1_DN<22>")
	)
	(segment
		(start 146.493484 -169.461688)
		(end 146.557492 -169.264076)
		(width 0.14732)
		(layer "In6.Cu")
		(net "UPI_CPU1_CPU0_P0P1_DN<22>")
	)
	(segment
		(start 110.74019 -210.24469)
		(end 110.885732 -209.832956)
		(width 0.14732)
		(layer "In6.Cu")
		(net "UPI_CPU1_CPU0_P0P1_DN<22>")
	)
	(segment
		(start 148.211286 -170.20413)
		(end 149.05101 -169.775378)
		(width 0.14732)
		(layer "In6.Cu")
		(net "UPI_CPU1_CPU0_P0P1_DN<22>")
	)
	(segment
		(start 182.36438 -166.184834)
		(end 182.387748 -167.165782)
		(width 0.14732)
		(layer "In6.Cu")
		(net "UPI_CPU1_CPU0_P0P1_DN<22>")
	)
	(segment
		(start 349.16237 -182.050944)
		(end 349.22206 -182.110888)
		(width 0.14732)
		(layer "In6.Cu")
		(net "UPI_CPU1_CPU0_P0P1_DN<22>")
	)
	(segment
		(start 175.263302 -166.206678)
		(end 175.413416 -166.350188)
		(width 0.14732)
		(layer "In6.Cu")
		(net "UPI_CPU1_CPU0_P0P1_DN<22>")
	)
	(segment
		(start 112.604042 -204.97546)
		(end 115.280694 -197.406768)
		(width 0.14732)
		(layer "In6.Cu")
		(net "UPI_CPU1_CPU0_P0P1_DN<22>")
	)
	(segment
		(start 172.355764 -166.27602)
		(end 172.946314 -166.261796)
		(width 0.14732)
		(layer "In6.Cu")
		(net "UPI_CPU1_CPU0_P0P1_DN<22>")
	)
	(segment
		(start 110.668816 -210.81238)
		(end 110.814358 -210.400392)
		(width 0.14732)
		(layer "In6.Cu")
		(net "UPI_CPU1_CPU0_P0P1_DN<22>")
	)
	(segment
		(start 176.98974 -166.165784)
		(end 177.58029 -166.15156)
		(width 0.14732)
		(layer "In6.Cu")
		(net "UPI_CPU1_CPU0_P0P1_DN<22>")
	)
	(segment
		(start 110.367318 -211.64423)
		(end 110.367318 -211.298536)
		(width 0.14732)
		(layer "In6.Cu")
		(net "UPI_CPU1_CPU0_P0P1_DN<22>")
	)
	(segment
		(start 158.07563 -165.914324)
		(end 158.225998 -166.057834)
		(width 0.14732)
		(layer "In6.Cu")
		(net "UPI_CPU1_CPU0_P0P1_DN<22>")
	)
	(segment
		(start 162.119056 -165.818312)
		(end 162.709606 -165.804088)
		(width 0.14732)
		(layer "In6.Cu")
		(net "UPI_CPU1_CPU0_P0P1_DN<22>")
	)
	(segment
		(start 111.631476 -207.725264)
		(end 111.787432 -207.650842)
		(width 0.14732)
		(layer "In6.Cu")
		(net "UPI_CPU1_CPU0_P0P1_DN<22>")
	)
	(segment
		(start 150.833582 -167.185848)
		(end 151.265636 -168.898824)
		(width 0.14732)
		(layer "In6.Cu")
		(net "UPI_CPU1_CPU0_P0P1_DN<22>")
	)
	(segment
		(start 173.434756 -167.687244)
		(end 174.25162 -167.667432)
		(width 0.14732)
		(layer "In6.Cu")
		(net "UPI_CPU1_CPU0_P0P1_DN<22>")
	)
	(segment
		(start 346.616274 -181.108604)
		(end 346.703142 -181.29758)
		(width 0.14732)
		(layer "In6.Cu")
		(net "UPI_CPU1_CPU0_P0P1_DN<22>")
	)
	(segment
		(start 111.041688 -209.758534)
		(end 111.18723 -209.346546)
		(width 0.14732)
		(layer "In6.Cu")
		(net "UPI_CPU1_CPU0_P0P1_DN<22>")
	)
	(segment
		(start 175.751744 -167.632126)
		(end 176.568608 -167.612314)
		(width 0.14732)
		(layer "In6.Cu")
		(net "UPI_CPU1_CPU0_P0P1_DN<22>")
	)
	(segment
		(start 181.480206 -166.205916)
		(end 181.623716 -166.055548)
		(width 0.14732)
		(layer "In6.Cu")
		(net "UPI_CPU1_CPU0_P0P1_DN<22>")
	)
	(segment
		(start 149.975824 -167.40251)
		(end 150.082504 -167.223948)
		(width 0.14732)
		(layer "In6.Cu")
		(net "UPI_CPU1_CPU0_P0P1_DN<22>")
	)
	(segment
		(start 151.265636 -168.898824)
		(end 151.639524 -169.122598)
		(width 0.14732)
		(layer "In6.Cu")
		(net "UPI_CPU1_CPU0_P0P1_DN<22>")
	)
	(segment
		(start 152.329642 -166.656766)
		(end 152.902412 -166.511986)
		(width 0.14732)
		(layer "In6.Cu")
		(net "UPI_CPU1_CPU0_P0P1_DN<22>")
	)
	(segment
		(start 161.715196 -167.96512)
		(end 162.015932 -167.650414)
		(width 0.14732)
		(layer "In6.Cu")
		(net "UPI_CPU1_CPU0_P0P1_DN<22>")
	)
	(segment
		(start 153.886408 -168.555416)
		(end 155.655264 -168.109138)
		(width 0.14732)
		(layer "In6.Cu")
		(net "UPI_CPU1_CPU0_P0P1_DN<22>")
	)
	(segment
		(start 157.48508 -165.928548)
		(end 158.07563 -165.914324)
		(width 0.14732)
		(layer "In6.Cu")
		(net "UPI_CPU1_CPU0_P0P1_DN<22>")
	)
	(segment
		(start 111.560102 -208.2927)
		(end 111.485934 -208.136998)
		(width 0.14732)
		(layer "In6.Cu")
		(net "UPI_CPU1_CPU0_P0P1_DN<22>")
	)
	(segment
		(start 181.623716 -166.055548)
		(end 182.214266 -166.041324)
		(width 0.14732)
		(layer "In6.Cu")
		(net "UPI_CPU1_CPU0_P0P1_DN<22>")
	)
	(segment
		(start 176.568608 -167.612314)
		(end 176.869598 -167.297354)
		(width 0.14732)
		(layer "In6.Cu")
		(net "UPI_CPU1_CPU0_P0P1_DN<22>")
	)
	(segment
		(start 112.305846 -206.185008)
		(end 112.231424 -206.029306)
		(width 0.14732)
		(layer "In6.Cu")
		(net "UPI_CPU1_CPU0_P0P1_DN<22>")
	)
	(segment
		(start 349.22206 -182.110888)
		(end 349.31096 -182.264304)
		(width 0.14732)
		(layer "In6.Cu")
		(net "UPI_CPU1_CPU0_P0P1_DN<22>")
	)
	(segment
		(start 150.082504 -167.223948)
		(end 150.655274 -167.079168)
		(width 0.14732)
		(layer "In6.Cu")
		(net "UPI_CPU1_CPU0_P0P1_DN<22>")
	)
	(segment
		(start 160.392618 -165.859206)
		(end 160.542986 -166.002716)
		(width 0.14732)
		(layer "In6.Cu")
		(net "UPI_CPU1_CPU0_P0P1_DN<22>")
	)
	(segment
		(start 158.26613 -167.739314)
		(end 158.58109 -168.04005)
		(width 0.14732)
		(layer "In6.Cu")
		(net "UPI_CPU1_CPU0_P0P1_DN<22>")
	)
	(segment
		(start 181.202584 -167.502078)
		(end 181.503574 -167.187118)
		(width 0.14732)
		(layer "In6.Cu")
		(net "UPI_CPU1_CPU0_P0P1_DN<22>")
	)
	(segment
		(start 174.529242 -166.37127)
		(end 174.672752 -166.220902)
		(width 0.14732)
		(layer "In6.Cu")
		(net "UPI_CPU1_CPU0_P0P1_DN<22>")
	)
	(segment
		(start 180.38572 -167.52189)
		(end 181.202584 -167.502078)
		(width 0.14732)
		(layer "In6.Cu")
		(net "UPI_CPU1_CPU0_P0P1_DN<22>")
	)
	(segment
		(start 174.672752 -166.220902)
		(end 175.263302 -166.206678)
		(width 0.14732)
		(layer "In6.Cu")
		(net "UPI_CPU1_CPU0_P0P1_DN<22>")
	)
	(segment
		(start 155.655264 -168.109138)
		(end 157.080966 -168.075356)
		(width 0.14732)
		(layer "In6.Cu")
		(net "UPI_CPU1_CPU0_P0P1_DN<22>")
	)
	(segment
		(start 179.897278 -166.096442)
		(end 180.047392 -166.239952)
		(width 0.14732)
		(layer "In6.Cu")
		(net "UPI_CPU1_CPU0_P0P1_DN<22>")
	)
	(segment
		(start 110.367318 -211.298536)
		(end 110.51286 -210.886802)
		(width 0.14732)
		(layer "In6.Cu")
		(net "UPI_CPU1_CPU0_P0P1_DN<22>")
	)
	(segment
		(start 147.281138 -169.059352)
		(end 147.797266 -170.069764)
		(width 0.14732)
		(layer "In6.Cu")
		(net "UPI_CPU1_CPU0_P0P1_DN<22>")
	)
	(segment
		(start 182.214266 -166.041324)
		(end 182.36438 -166.184834)
		(width 0.14732)
		(layer "In6.Cu")
		(net "UPI_CPU1_CPU0_P0P1_DN<22>")
	)
	(segment
		(start 123.284742 -187.472574)
		(end 133.754622 -177.590196)
		(width 0.14732)
		(layer "In6.Cu")
		(net "UPI_CPU1_CPU0_P0P1_DN<22>")
	)
	(segment
		(start 347.225874 -183.129428)
		(end 347.621098 -182.947564)
		(width 0.14732)
		(layer "In6.Cu")
		(net "UPI_CPU1_CPU0_P0P1_DN<22>")
	)
	(segment
		(start 152.222962 -166.835328)
		(end 152.329642 -166.656766)
		(width 0.14732)
		(layer "In6.Cu")
		(net "UPI_CPU1_CPU0_P0P1_DN<22>")
	)
	(segment
		(start 162.015932 -167.650414)
		(end 161.975546 -165.96868)
		(width 0.14732)
		(layer "In6.Cu")
		(net "UPI_CPU1_CPU0_P0P1_DN<22>")
	)
	(segment
		(start 153.08072 -166.618666)
		(end 153.512774 -168.331642)
		(width 0.14732)
		(layer "In6.Cu")
		(net "UPI_CPU1_CPU0_P0P1_DN<22>")
	)
	(segment
		(start 180.047392 -166.239952)
		(end 180.07076 -167.2209)
		(width 0.14732)
		(layer "In6.Cu")
		(net "UPI_CPU1_CPU0_P0P1_DN<22>")
	)
	(segment
		(start 146.873976 -170.890692)
		(end 147.009612 -170.4721)
		(width 0.14732)
		(layer "In6.Cu")
		(net "UPI_CPU1_CPU0_P0P1_DN<22>")
	)
	(segment
		(start 159.698944 -167.705532)
		(end 159.658558 -166.023798)
		(width 0.14732)
		(layer "In6.Cu")
		(net "UPI_CPU1_CPU0_P0P1_DN<22>")
	)
	(segment
		(start 146.557492 -169.264076)
		(end 147.083526 -168.995344)
		(width 0.14732)
		(layer "In6.Cu")
		(net "UPI_CPU1_CPU0_P0P1_DN<22>")
	)
	(segment
		(start 182.387748 -167.165782)
		(end 182.702454 -167.466772)
		(width 0.14732)
		(layer "In6.Cu")
		(net "UPI_CPU1_CPU0_P0P1_DN<22>")
	)
	(segment
		(start 111.258604 -208.77911)
		(end 111.41456 -208.704688)
		(width 0.14732)
		(layer "In6.Cu")
		(net "UPI_CPU1_CPU0_P0P1_DN<22>")
	)
	(segment
		(start 159.802068 -165.87343)
		(end 160.392618 -165.859206)
		(width 0.14732)
		(layer "In6.Cu")
		(net "UPI_CPU1_CPU0_P0P1_DN<22>")
	)
	(segment
		(start 157.381956 -167.76065)
		(end 157.34157 -166.078916)
		(width 0.14732)
		(layer "In6.Cu")
		(net "UPI_CPU1_CPU0_P0P1_DN<22>")
	)
	(segment
		(start 348.23654 -181.708298)
		(end 349.16237 -182.050944)
		(width 0.14732)
		(layer "In6.Cu")
		(net "UPI_CPU1_CPU0_P0P1_DN<22>")
	)
	(segment
		(start 160.898078 -167.984932)
		(end 161.715196 -167.96512)
		(width 0.14732)
		(layer "In6.Cu")
		(net "UPI_CPU1_CPU0_P0P1_DN<22>")
	)
	(segment
		(start 159.398208 -168.020238)
		(end 159.698944 -167.705532)
		(width 0.14732)
		(layer "In6.Cu")
		(net "UPI_CPU1_CPU0_P0P1_DN<22>")
	)
	(segment
		(start 349.31096 -182.264304)
		(end 349.165672 -182.805832)
		(width 0.14732)
		(layer "In6.Cu")
		(net "UPI_CPU1_CPU0_P0P1_DN<22>")
	)
	(segment
		(start 178.068732 -167.577008)
		(end 178.885596 -167.557196)
		(width 0.14732)
		(layer "In6.Cu")
		(net "UPI_CPU1_CPU0_P0P1_DN<22>")
	)
	(segment
		(start 346.063062 -180.90388)
		(end 346.616274 -181.108604)
		(width 0.14732)
		(layer "In6.Cu")
		(net "UPI_CPU1_CPU0_P0P1_DN<22>")
	)
	(segment
		(start 176.84623 -166.316152)
		(end 176.98974 -166.165784)
		(width 0.14732)
		(layer "In6.Cu")
		(net "UPI_CPU1_CPU0_P0P1_DN<22>")
	)
	(segment
		(start 111.18723 -209.346546)
		(end 111.113062 -209.190844)
		(width 0.14732)
		(layer "In6.Cu")
		(net "UPI_CPU1_CPU0_P0P1_DN<22>")
	)
	(segment
		(start 173.119796 -167.386254)
		(end 173.434756 -167.687244)
		(width 0.14732)
		(layer "In6.Cu")
		(net "UPI_CPU1_CPU0_P0P1_DN<22>")
	)
	(segment
		(start 162.859974 -165.947598)
		(end 162.900106 -167.629078)
		(width 0.14732)
		(layer "In6.Cu")
		(net "UPI_CPU1_CPU0_P0P1_DN<22>")
	)
	(segment
		(start 344.285062 -182.040784)
		(end 345.052396 -182.32501)
		(width 0.14732)
		(layer "In6.Cu")
		(net "UPI_CPU1_CPU0_P0P1_DN<22>")
	)
	(segment
		(start 112.231424 -206.029306)
		(end 112.376966 -205.617572)
		(width 0.14732)
		(layer "In6.Cu")
		(net "UPI_CPU1_CPU0_P0P1_DN<22>")
	)
	(segment
		(start 150.655274 -167.079168)
		(end 150.833582 -167.185848)
		(width 0.14732)
		(layer "In6.Cu")
		(net "UPI_CPU1_CPU0_P0P1_DN<22>")
	)
	(segment
		(start 345.874086 -180.990748)
		(end 346.063062 -180.90388)
		(width 0.14732)
		(layer "In6.Cu")
		(net "UPI_CPU1_CPU0_P0P1_DN<22>")
	)
	(segment
		(start 175.413416 -166.350188)
		(end 175.436784 -167.331136)
		(width 0.14732)
		(layer "In6.Cu")
		(net "UPI_CPU1_CPU0_P0P1_DN<22>")
	)
	(segment
		(start 147.797266 -170.069764)
		(end 148.211286 -170.20413)
		(width 0.14732)
		(layer "In6.Cu")
		(net "UPI_CPU1_CPU0_P0P1_DN<22>")
	)
	(segment
		(start 162.900106 -167.629078)
		(end 163.214812 -167.929814)
		(width 0.14732)
		(layer "In6.Cu")
		(net "UPI_CPU1_CPU0_P0P1_DN<22>")
	)
	(segment
		(start 112.004348 -206.671418)
		(end 112.160304 -206.596996)
		(width 0.14732)
		(layer "In6.Cu")
		(net "UPI_CPU1_CPU0_P0P1_DN<22>")
	)
	(segment
		(start 346.45854 -182.845202)
		(end 347.225874 -183.129428)
		(width 0.14732)
		(layer "In6.Cu")
		(net "UPI_CPU1_CPU0_P0P1_DN<22>")
	)
	(segment
		(start 182.702454 -167.466772)
		(end 189.319408 -167.310054)
		(width 0.14732)
		(layer "In6.Cu")
		(net "UPI_CPU1_CPU0_P0P1_DN<22>")
	)
	(segment
		(start 153.512774 -168.331642)
		(end 153.886408 -168.555416)
		(width 0.14732)
		(layer "In6.Cu")
		(net "UPI_CPU1_CPU0_P0P1_DN<22>")
	)
	(segment
		(start 234.752896 -157.429454)
		(end 237.459012 -157.429454)
		(width 0.14732)
		(layer "In6.Cu")
		(net "UPI_CPU1_CPU0_P0P1_DN<22>")
	)
	(segment
		(start 112.376966 -205.617572)
		(end 112.532922 -205.54315)
		(width 0.14732)
		(layer "In6.Cu")
		(net "UPI_CPU1_CPU0_P0P1_DN<22>")
	)
	(segment
		(start 177.58029 -166.15156)
		(end 177.730404 -166.29507)
		(width 0.14732)
		(layer "In6.Cu")
		(net "UPI_CPU1_CPU0_P0P1_DN<22>")
	)
	(segment
		(start 110.230412 -215.436704)
		(end 109.978952 -215.436704)
		(width 0.0889)
		(layer "In6.Cu")
		(net "UPI_CPU1_CPU0_P0P1_DN<22>")
	)
	(segment
		(start 110.325154 -211.69757)
		(end 110.367318 -211.655406)
		(width 0.0889)
		(layer "In6.Cu")
		(net "UPI_CPU1_CPU0_P0P1_DN<22>")
	)
	(segment
		(start 175.436784 -167.331136)
		(end 175.751744 -167.632126)
		(width 0.14732)
		(layer "In6.Cu")
		(net "UPI_CPU1_CPU0_P0P1_DN<22>")
	)
	(segment
		(start 347.621098 -182.947564)
		(end 348.047564 -181.795166)
		(width 0.14732)
		(layer "In6.Cu")
		(net "UPI_CPU1_CPU0_P0P1_DN<22>")
	)
	(segment
		(start 160.542986 -166.002716)
		(end 160.583118 -167.684196)
		(width 0.14732)
		(layer "In6.Cu")
		(net "UPI_CPU1_CPU0_P0P1_DN<22>")
	)
	(segment
		(start 115.280694 -197.406768)
		(end 123.284742 -187.472574)
		(width 0.14732)
		(layer "In6.Cu")
		(net "UPI_CPU1_CPU0_P0P1_DN<22>")
	)
	(segment
		(start 176.869598 -167.297354)
		(end 176.84623 -166.316152)
		(width 0.14732)
		(layer "In6.Cu")
		(net "UPI_CPU1_CPU0_P0P1_DN<22>")
	)
	(segment
		(start 157.34157 -166.078916)
		(end 157.48508 -165.928548)
		(width 0.14732)
		(layer "In6.Cu")
		(net "UPI_CPU1_CPU0_P0P1_DN<22>")
	)
	(segment
		(start 112.160304 -206.596996)
		(end 112.305846 -206.185008)
		(width 0.14732)
		(layer "In6.Cu")
		(net "UPI_CPU1_CPU0_P0P1_DN<22>")
	)
	(segment
		(start 345.44762 -182.143146)
		(end 345.874086 -180.990748)
		(width 0.14732)
		(layer "In6.Cu")
		(net "UPI_CPU1_CPU0_P0P1_DN<22>")
	)
	(segment
		(start 161.975546 -165.96868)
		(end 162.119056 -165.818312)
		(width 0.14732)
		(layer "In6.Cu")
		(net "UPI_CPU1_CPU0_P0P1_DN<22>")
	)
	(segment
		(start 157.080966 -168.075356)
		(end 157.381956 -167.76065)
		(width 0.14732)
		(layer "In6.Cu")
		(net "UPI_CPU1_CPU0_P0P1_DN<22>")
	)
	(segment
		(start 111.787432 -207.650842)
		(end 111.932974 -207.238854)
		(width 0.14732)
		(layer "In6.Cu")
		(net "UPI_CPU1_CPU0_P0P1_DN<22>")
	)
	(segment
		(start 344.442796 -180.304186)
		(end 344.529664 -180.493162)
		(width 0.14732)
		(layer "In6.Cu")
		(net "UPI_CPU1_CPU0_P0P1_DN<22>")
	)
	(segment
		(start 173.096428 -166.405306)
		(end 173.119796 -167.386254)
		(width 0.14732)
		(layer "In6.Cu")
		(net "UPI_CPU1_CPU0_P0P1_DN<22>")
	)
	(segment
		(start 151.639524 -169.122598)
		(end 152.43175 -168.922192)
		(width 0.14732)
		(layer "In6.Cu")
		(net "UPI_CPU1_CPU0_P0P1_DN<22>")
	)
	(segment
		(start 111.113062 -209.190844)
		(end 111.258604 -208.77911)
		(width 0.14732)
		(layer "In6.Cu")
		(net "UPI_CPU1_CPU0_P0P1_DN<22>")
	)
	(segment
		(start 111.41456 -208.704688)
		(end 111.560102 -208.2927)
		(width 0.14732)
		(layer "In6.Cu")
		(net "UPI_CPU1_CPU0_P0P1_DN<22>")
	)
	(segment
		(start 178.885596 -167.557196)
		(end 179.186586 -167.242236)
		(width 0.14732)
		(layer "In6.Cu")
		(net "UPI_CPU1_CPU0_P0P1_DN<22>")
	)
	(segment
		(start 110.325154 -214.601298)
		(end 110.325154 -211.69757)
		(width 0.0889)
		(layer "In6.Cu")
		(net "UPI_CPU1_CPU0_P0P1_DN<22>")
	)
	(segment
		(start 110.367318 -211.655406)
		(end 110.367318 -211.64423)
		(width 0.0889)
		(layer "In6.Cu")
		(net "UPI_CPU1_CPU0_P0P1_DN<22>")
	)
	(segment
		(start 149.05101 -169.775378)
		(end 150.184612 -169.489374)
		(width 0.14732)
		(layer "In6.Cu")
		(net "UPI_CPU1_CPU0_P0P1_DN<22>")
	)
	(segment
		(start 346.703142 -181.29758)
		(end 346.276676 -182.449978)
		(width 0.14732)
		(layer "In6.Cu")
		(net "UPI_CPU1_CPU0_P0P1_DN<22>")
	)
	(segment
		(start 111.858806 -207.083152)
		(end 112.004348 -206.671418)
		(width 0.14732)
		(layer "In6.Cu")
		(net "UPI_CPU1_CPU0_P0P1_DN<22>")
	)
	(segment
		(start 179.186586 -167.242236)
		(end 179.163218 -166.261034)
		(width 0.14732)
		(layer "In6.Cu")
		(net "UPI_CPU1_CPU0_P0P1_DN<22>")
	)
	(segment
		(start 280.182828 -167.320214)
		(end 302.490124 -166.936166)
		(width 0.14732)
		(layer "In6.Cu")
		(net "UPI_CPU1_CPU0_P0P1_DN<22>")
	)
	(segment
		(start 111.485934 -208.136998)
		(end 111.631476 -207.725264)
		(width 0.14732)
		(layer "In6.Cu")
		(net "UPI_CPU1_CPU0_P0P1_DN<22>")
	)
	(segment
		(start 147.009612 -170.4721)
		(end 146.493484 -169.461688)
		(width 0.14732)
		(layer "In6.Cu")
		(net "UPI_CPU1_CPU0_P0P1_DN<22>")
	)
	(segment
		(start 179.163218 -166.261034)
		(end 179.306728 -166.110666)
		(width 0.14732)
		(layer "In6.Cu")
		(net "UPI_CPU1_CPU0_P0P1_DN<22>")
	)
	(segment
		(start 172.212254 -166.426388)
		(end 172.355764 -166.27602)
		(width 0.14732)
		(layer "In6.Cu")
		(net "UPI_CPU1_CPU0_P0P1_DN<22>")
	)
	(segment
		(start 314.440062 -167.180006)
		(end 321.505072 -169.173906)
		(width 0.14732)
		(layer "In6.Cu")
		(net "UPI_CPU1_CPU0_P0P1_DN<22>")
	)
	(segment
		(start 112.678464 -205.131162)
		(end 112.604042 -204.97546)
		(width 0.14732)
		(layer "In6.Cu")
		(net "UPI_CPU1_CPU0_P0P1_DN<22>")
	)
	(segment
		(start 321.505072 -169.173906)
		(end 338.592414 -178.139598)
		(width 0.14732)
		(layer "In6.Cu")
		(net "UPI_CPU1_CPU0_P0P1_DN<22>")
	)
	(segment
		(start 152.43175 -168.922192)
		(end 152.65527 -168.548304)
		(width 0.14732)
		(layer "In6.Cu")
		(net "UPI_CPU1_CPU0_P0P1_DN<22>")
	)
	(segment
		(start 110.814358 -210.400392)
		(end 110.74019 -210.24469)
		(width 0.14732)
		(layer "In6.Cu")
		(net "UPI_CPU1_CPU0_P0P1_DN<22>")
	)
	(segment
		(start 189.319408 -167.310054)
		(end 196.12864 -167.310054)
		(width 0.14732)
		(layer "In6.Cu")
		(net "UPI_CPU1_CPU0_P0P1_DN<22>")
	)
	(segment
		(start 344.529664 -180.493162)
		(end 344.103198 -181.64556)
		(width 0.14732)
		(layer "In6.Cu")
		(net "UPI_CPU1_CPU0_P0P1_DN<22>")
	)
	(segment
		(start 275.966682 -167.320214)
		(end 280.182828 -167.320214)
		(width 0.14732)
		(layer "In6.Cu")
		(net "UPI_CPU1_CPU0_P0P1_DN<22>")
	)
	(segment
		(start 196.713856 -167.236394)
		(end 234.752896 -157.429454)
		(width 0.14732)
		(layer "In6.Cu")
		(net "UPI_CPU1_CPU0_P0P1_DN<22>")
	)
	(arc
		(start 110.039404 -215.075516)
		(mid 110.248258 -214.878178)
		(end 110.325154 -214.601298)
		(width 0.0889)
		(layer "In6.Cu")
		(net "UPI_CPU1_CPU0_P0P1_DN<22>")
	)
	(arc
		(start 109.865668 -215.254332)
		(mid 109.93855 -215.151337)
		(end 110.039404 -215.075516)
		(width 0.0889)
		(layer "In6.Cu")
		(net "UPI_CPU1_CPU0_P0P1_DN<22>")
	)
	(arc
		(start 109.978952 -215.436704)
		(mid 109.87147 -215.377086)
		(end 109.865668 -215.254332)
		(width 0.0889)
		(layer "In6.Cu")
		(net "UPI_CPU1_CPU0_P0P1_DN<22>")
	)
	(segment
		(start 363.43463 -213.656164)
		(end 362.338112 -212.559646)
		(width 0.0889)
		(layer "F.Cu")
		(net "UPI_CPU1_CPU0_P0P1_DN<21>")
	)
	(segment
		(start 363.184186 -214.889588)
		(end 363.209332 -214.796878)
		(width 0.0889)
		(layer "F.Cu")
		(net "UPI_CPU1_CPU0_P0P1_DN<21>")
	)
	(segment
		(start 363.33938 -215.158574)
		(end 363.184186 -214.889588)
		(width 0.0889)
		(layer "F.Cu")
		(net "UPI_CPU1_CPU0_P0P1_DN<21>")
	)
	(segment
		(start 108.820458 -215.15832)
		(end 108.820458 -214.622634)
		(width 0.13208)
		(layer "F.Cu")
		(net "UPI_CPU1_CPU0_P0P1_DN<21>")
	)
	(segment
		(start 352.871278 -198.741538)
		(end 353.986592 -193.129154)
		(width 0.13208)
		(layer "F.Cu")
		(net "UPI_CPU1_CPU0_P0P1_DN<21>")
	)
	(segment
		(start 353.245166 -183.845962)
		(end 353.319334 -183.717946)
		(width 0.13208)
		(layer "F.Cu")
		(net "UPI_CPU1_CPU0_P0P1_DN<21>")
	)
	(segment
		(start 353.319334 -183.717946)
		(end 353.319842 -183.717184)
		(width 0.13208)
		(layer "F.Cu")
		(net "UPI_CPU1_CPU0_P0P1_DN<21>")
	)
	(segment
		(start 362.338112 -212.559646)
		(end 358.145842 -210.82254)
		(width 0.0889)
		(layer "F.Cu")
		(net "UPI_CPU1_CPU0_P0P1_DN<21>")
	)
	(segment
		(start 352.871278 -205.205076)
		(end 352.871278 -198.741538)
		(width 0.13208)
		(layer "F.Cu")
		(net "UPI_CPU1_CPU0_P0P1_DN<21>")
	)
	(segment
		(start 355.709982 -186.36234)
		(end 354.414328 -185.066432)
		(width 0.13208)
		(layer "F.Cu")
		(net "UPI_CPU1_CPU0_P0P1_DN<21>")
	)
	(segment
		(start 352.836734 -205.513686)
		(end 352.836734 -205.261718)
		(width 0.0889)
		(layer "F.Cu")
		(net "UPI_CPU1_CPU0_P0P1_DN<21>")
	)
	(segment
		(start 355.96576 -188.352176)
		(end 355.96576 -186.979814)
		(width 0.13208)
		(layer "F.Cu")
		(net "UPI_CPU1_CPU0_P0P1_DN<21>")
	)
	(segment
		(start 352.871278 -205.227174)
		(end 352.871278 -205.205076)
		(width 0.0889)
		(layer "F.Cu")
		(net "UPI_CPU1_CPU0_P0P1_DN<21>")
	)
	(segment
		(start 353.319842 -183.717184)
		(end 353.872546 -183.567832)
		(width 0.13208)
		(layer "F.Cu")
		(net "UPI_CPU1_CPU0_P0P1_DN<21>")
	)
	(segment
		(start 353.346004 -184.205626)
		(end 353.272852 -184.056782)
		(width 0.13208)
		(layer "F.Cu")
		(net "UPI_CPU1_CPU0_P0P1_DN<21>")
	)
	(segment
		(start 355.96576 -186.979814)
		(end 355.709982 -186.36234)
		(width 0.13208)
		(layer "F.Cu")
		(net "UPI_CPU1_CPU0_P0P1_DN<21>")
	)
	(segment
		(start 363.434884 -214.345266)
		(end 363.43463 -214.345012)
		(width 0.0889)
		(layer "F.Cu")
		(net "UPI_CPU1_CPU0_P0P1_DN<21>")
	)
	(segment
		(start 353.986592 -193.129154)
		(end 355.96576 -188.352176)
		(width 0.13208)
		(layer "F.Cu")
		(net "UPI_CPU1_CPU0_P0P1_DN<21>")
	)
	(segment
		(start 354.414328 -185.066432)
		(end 353.68357 -184.676034)
		(width 0.13208)
		(layer "F.Cu")
		(net "UPI_CPU1_CPU0_P0P1_DN<21>")
	)
	(segment
		(start 353.68357 -184.676034)
		(end 353.346004 -184.205626)
		(width 0.13208)
		(layer "F.Cu")
		(net "UPI_CPU1_CPU0_P0P1_DN<21>")
	)
	(segment
		(start 358.145842 -210.82254)
		(end 352.836734 -205.513686)
		(width 0.0889)
		(layer "F.Cu")
		(net "UPI_CPU1_CPU0_P0P1_DN<21>")
	)
	(segment
		(start 353.272852 -184.056782)
		(end 353.245166 -183.845962)
		(width 0.13208)
		(layer "F.Cu")
		(net "UPI_CPU1_CPU0_P0P1_DN<21>")
	)
	(segment
		(start 108.820712 -215.158574)
		(end 108.820458 -215.15832)
		(width 0.13208)
		(layer "F.Cu")
		(net "UPI_CPU1_CPU0_P0P1_DN<21>")
	)
	(segment
		(start 363.43463 -214.345012)
		(end 363.43463 -213.656164)
		(width 0.0889)
		(layer "F.Cu")
		(net "UPI_CPU1_CPU0_P0P1_DN<21>")
	)
	(segment
		(start 352.836734 -205.261718)
		(end 352.871278 -205.227174)
		(width 0.0889)
		(layer "F.Cu")
		(net "UPI_CPU1_CPU0_P0P1_DN<21>")
	)
	(arc
		(start 363.225842 -214.783416)
		(mid 363.37983 -214.587935)
		(end 363.434884 -214.345266)
		(width 0.0889)
		(layer "F.Cu")
		(net "UPI_CPU1_CPU0_P0P1_DN<21>")
	)
	(arc
		(start 363.209332 -214.796878)
		(mid 363.217652 -214.790227)
		(end 363.225842 -214.783416)
		(width 0.0889)
		(layer "F.Cu")
		(net "UPI_CPU1_CPU0_P0P1_DN<21>")
	)
	(segment
		(start 351.705164 -183.868822)
		(end 352.180652 -184.145428)
		(width 0.14732)
		(layer "In6.Cu")
		(net "UPI_CPU1_CPU0_P0P1_DN<21>")
	)
	(segment
		(start 341.505032 -177.673254)
		(end 342.103202 -177.913284)
		(width 0.14732)
		(layer "In6.Cu")
		(net "UPI_CPU1_CPU0_P0P1_DN<21>")
	)
	(segment
		(start 344.886026 -178.874928)
		(end 344.797888 -179.094384)
		(width 0.14732)
		(layer "In6.Cu")
		(net "UPI_CPU1_CPU0_P0P1_DN<21>")
	)
	(segment
		(start 176.378108 -160.844738)
		(end 176.521618 -160.694116)
		(width 0.14732)
		(layer "In6.Cu")
		(net "UPI_CPU1_CPU0_P0P1_DN<21>")
	)
	(segment
		(start 109.578648 -210.670648)
		(end 109.578394 -210.670648)
		(width 0.14732)
		(layer "In6.Cu")
		(net "UPI_CPU1_CPU0_P0P1_DN<21>")
	)
	(segment
		(start 144.480788 -169.67962)
		(end 144.529302 -169.477182)
		(width 0.14732)
		(layer "In6.Cu")
		(net "UPI_CPU1_CPU0_P0P1_DN<21>")
	)
	(segment
		(start 174.795434 -160.736788)
		(end 174.945802 -160.880044)
		(width 0.14732)
		(layer "In6.Cu")
		(net "UPI_CPU1_CPU0_P0P1_DN<21>")
	)
	(segment
		(start 168.529508 -166.176198)
		(end 169.838878 -165.83279)
		(width 0.14732)
		(layer "In6.Cu")
		(net "UPI_CPU1_CPU0_P0P1_DN<21>")
	)
	(segment
		(start 109.80547 -210.02879)
		(end 109.951012 -209.617056)
		(width 0.14732)
		(layer "In6.Cu")
		(net "UPI_CPU1_CPU0_P0P1_DN<21>")
	)
	(segment
		(start 166.68242 -166.099998)
		(end 166.770812 -166.118032)
		(width 0.14732)
		(layer "In6.Cu")
		(net "UPI_CPU1_CPU0_P0P1_DN<21>")
	)
	(segment
		(start 108.630212 -214.261954)
		(end 109.211364 -213.680802)
		(width 0.0889)
		(layer "In6.Cu")
		(net "UPI_CPU1_CPU0_P0P1_DN<21>")
	)
	(segment
		(start 184.942988 -165.660324)
		(end 185.97118 -165.478968)
		(width 0.14732)
		(layer "In6.Cu")
		(net "UPI_CPU1_CPU0_P0P1_DN<21>")
	)
	(segment
		(start 186.36488 -165.478968)
		(end 189.168278 -166.474902)
		(width 0.14732)
		(layer "In6.Cu")
		(net "UPI_CPU1_CPU0_P0P1_DN<21>")
	)
	(segment
		(start 153.557986 -164.364416)
		(end 154.634946 -164.346128)
		(width 0.14732)
		(layer "In6.Cu")
		(net "UPI_CPU1_CPU0_P0P1_DN<21>")
	)
	(segment
		(start 154.634946 -164.346128)
		(end 154.784298 -164.490908)
		(width 0.14732)
		(layer "In6.Cu")
		(net "UPI_CPU1_CPU0_P0P1_DN<21>")
	)
	(segment
		(start 353.332034 -183.712612)
		(end 353.872546 -183.567832)
		(width 0.14732)
		(layer "In6.Cu")
		(net "UPI_CPU1_CPU0_P0P1_DN<21>")
	)
	(segment
		(start 137.47115 -174.291498)
		(end 137.894314 -174.39259)
		(width 0.14732)
		(layer "In6.Cu")
		(net "UPI_CPU1_CPU0_P0P1_DN<21>")
	)
	(segment
		(start 178.922172 -161.949638)
		(end 179.072794 -162.09264)
		(width 0.14732)
		(layer "In6.Cu")
		(net "UPI_CPU1_CPU0_P0P1_DN<21>")
	)
	(segment
		(start 134.7978 -175.453294)
		(end 137.132314 -174.020734)
		(width 0.14732)
		(layer "In6.Cu")
		(net "UPI_CPU1_CPU0_P0P1_DN<21>")
	)
	(segment
		(start 155.931362 -165.744144)
		(end 156.233876 -165.431216)
		(width 0.14732)
		(layer "In6.Cu")
		(net "UPI_CPU1_CPU0_P0P1_DN<21>")
	)
	(segment
		(start 122.708924 -186.864498)
		(end 134.7978 -175.453294)
		(width 0.14732)
		(layer "In6.Cu")
		(net "UPI_CPU1_CPU0_P0P1_DN<21>")
	)
	(segment
		(start 173.817026 -163.46551)
		(end 173.470316 -163.473892)
		(width 0.14732)
		(layer "In6.Cu")
		(net "UPI_CPU1_CPU0_P0P1_DN<21>")
	)
	(segment
		(start 174.945802 -160.880044)
		(end 175.04537 -164.897054)
		(width 0.14732)
		(layer "In6.Cu")
		(net "UPI_CPU1_CPU0_P0P1_DN<21>")
	)
	(segment
		(start 158.90875 -165.009576)
		(end 159.211264 -164.696902)
		(width 0.14732)
		(layer "In6.Cu")
		(net "UPI_CPU1_CPU0_P0P1_DN<21>")
	)
	(segment
		(start 137.334752 -174.069248)
		(end 137.47115 -174.291498)
		(width 0.14732)
		(layer "In6.Cu")
		(net "UPI_CPU1_CPU0_P0P1_DN<21>")
	)
	(segment
		(start 177.284126 -161.681922)
		(end 177.59934 -161.98215)
		(width 0.14732)
		(layer "In6.Cu")
		(net "UPI_CPU1_CPU0_P0P1_DN<21>")
	)
	(segment
		(start 143.945102 -170.959272)
		(end 144.642332 -170.531028)
		(width 0.14732)
		(layer "In6.Cu")
		(net "UPI_CPU1_CPU0_P0P1_DN<21>")
	)
	(segment
		(start 109.879892 -210.184238)
		(end 109.80547 -210.02879)
		(width 0.14732)
		(layer "In6.Cu")
		(net "UPI_CPU1_CPU0_P0P1_DN<21>")
	)
	(segment
		(start 109.310678 -212.58276)
		(end 109.310678 -212.31606)
		(width 0.0889)
		(layer "In6.Cu")
		(net "UPI_CPU1_CPU0_P0P1_DN<21>")
	)
	(segment
		(start 139.309602 -172.856144)
		(end 139.446 -173.078394)
		(width 0.14732)
		(layer "In6.Cu")
		(net "UPI_CPU1_CPU0_P0P1_DN<21>")
	)
	(segment
		(start 340.983316 -177.89652)
		(end 341.505032 -177.673254)
		(width 0.14732)
		(layer "In6.Cu")
		(net "UPI_CPU1_CPU0_P0P1_DN<21>")
	)
	(segment
		(start 174.095156 -162.265868)
		(end 174.061374 -160.902142)
		(width 0.14732)
		(layer "In6.Cu")
		(net "UPI_CPU1_CPU0_P0P1_DN<21>")
	)
	(segment
		(start 156.21762 -164.466778)
		(end 156.3624 -164.317426)
		(width 0.14732)
		(layer "In6.Cu")
		(net "UPI_CPU1_CPU0_P0P1_DN<21>")
	)
	(segment
		(start 143.259302 -170.429936)
		(end 143.522192 -170.85818)
		(width 0.14732)
		(layer "In6.Cu")
		(net "UPI_CPU1_CPU0_P0P1_DN<21>")
	)
	(segment
		(start 109.253528 -211.589366)
		(end 109.578648 -210.670648)
		(width 0.14732)
		(layer "In6.Cu")
		(net "UPI_CPU1_CPU0_P0P1_DN<21>")
	)
	(segment
		(start 346.955364 -179.547012)
		(end 347.036898 -179.737766)
		(width 0.14732)
		(layer "In6.Cu")
		(net "UPI_CPU1_CPU0_P0P1_DN<21>")
	)
	(segment
		(start 176.477676 -164.861748)
		(end 176.378108 -160.844738)
		(width 0.14732)
		(layer "In6.Cu")
		(net "UPI_CPU1_CPU0_P0P1_DN<21>")
	)
	(segment
		(start 321.81927 -168.384982)
		(end 336.582512 -176.130712)
		(width 0.14732)
		(layer "In6.Cu")
		(net "UPI_CPU1_CPU0_P0P1_DN<21>")
	)
	(segment
		(start 138.556238 -173.318932)
		(end 138.604752 -173.116494)
		(width 0.14732)
		(layer "In6.Cu")
		(net "UPI_CPU1_CPU0_P0P1_DN<21>")
	)
	(segment
		(start 234.645708 -156.585158)
		(end 237.565946 -156.585158)
		(width 0.14732)
		(layer "In6.Cu")
		(net "UPI_CPU1_CPU0_P0P1_DN<21>")
	)
	(segment
		(start 142.701518 -171.79925)
		(end 142.80261 -171.376086)
		(width 0.14732)
		(layer "In6.Cu")
		(net "UPI_CPU1_CPU0_P0P1_DN<21>")
	)
	(segment
		(start 108.663994 -214.893652)
		(end 108.585762 -214.91448)
		(width 0.0889)
		(layer "In6.Cu")
		(net "UPI_CPU1_CPU0_P0P1_DN<21>")
	)
	(segment
		(start 138.591544 -173.964346)
		(end 138.692636 -173.541182)
		(width 0.14732)
		(layer "In6.Cu")
		(net "UPI_CPU1_CPU0_P0P1_DN<21>")
	)
	(segment
		(start 108.445808 -214.622634)
		(end 108.445808 -214.461852)
		(width 0.0889)
		(layer "In6.Cu")
		(net "UPI_CPU1_CPU0_P0P1_DN<21>")
	)
	(segment
		(start 109.253528 -211.77123)
		(end 109.253528 -211.589366)
		(width 0.14732)
		(layer "In6.Cu")
		(net "UPI_CPU1_CPU0_P0P1_DN<21>")
	)
	(segment
		(start 173.794928 -162.581082)
		(end 174.095156 -162.265868)
		(width 0.14732)
		(layer "In6.Cu")
		(net "UPI_CPU1_CPU0_P0P1_DN<21>")
	)
	(segment
		(start 152.219914 -164.754052)
		(end 153.557986 -164.364416)
		(width 0.14732)
		(layer "In6.Cu")
		(net "UPI_CPU1_CPU0_P0P1_DN<21>")
	)
	(segment
		(start 173.319694 -163.33089)
		(end 173.304962 -162.74034)
		(width 0.14732)
		(layer "In6.Cu")
		(net "UPI_CPU1_CPU0_P0P1_DN<21>")
	)
	(segment
		(start 137.894314 -174.39259)
		(end 138.591544 -173.964346)
		(width 0.14732)
		(layer "In6.Cu")
		(net "UPI_CPU1_CPU0_P0P1_DN<21>")
	)
	(segment
		(start 109.310678 -213.314788)
		(end 109.310678 -213.048088)
		(width 0.0889)
		(layer "In6.Cu")
		(net "UPI_CPU1_CPU0_P0P1_DN<21>")
	)
	(segment
		(start 169.838878 -165.83279)
		(end 171.217082 -165.300152)
		(width 0.14732)
		(layer "In6.Cu")
		(net "UPI_CPU1_CPU0_P0P1_DN<21>")
	)
	(segment
		(start 302.491648 -166.091362)
		(end 314.565284 -166.337742)
		(width 0.14732)
		(layer "In6.Cu")
		(net "UPI_CPU1_CPU0_P0P1_DN<21>")
	)
	(segment
		(start 109.578394 -210.670648)
		(end 109.734096 -210.59648)
		(width 0.14732)
		(layer "In6.Cu")
		(net "UPI_CPU1_CPU0_P0P1_DN<21>")
	)
	(segment
		(start 276.073616 -166.475918)
		(end 280.175208 -166.475918)
		(width 0.14732)
		(layer "In6.Cu")
		(net "UPI_CPU1_CPU0_P0P1_DN<21>")
	)
	(segment
		(start 156.3624 -164.317426)
		(end 157.623764 -164.29609)
		(width 0.14732)
		(layer "In6.Cu")
		(net "UPI_CPU1_CPU0_P0P1_DN<21>")
	)
	(segment
		(start 176.521618 -160.694116)
		(end 177.112168 -160.679384)
		(width 0.14732)
		(layer "In6.Cu")
		(net "UPI_CPU1_CPU0_P0P1_DN<21>")
	)
	(segment
		(start 237.565946 -156.585158)
		(end 276.073616 -166.475918)
		(width 0.14732)
		(layer "In6.Cu")
		(net "UPI_CPU1_CPU0_P0P1_DN<21>")
	)
	(segment
		(start 109.211364 -212.948774)
		(end 109.211364 -212.682074)
		(width 0.0889)
		(layer "In6.Cu")
		(net "UPI_CPU1_CPU0_P0P1_DN<21>")
	)
	(segment
		(start 110.106968 -209.542634)
		(end 110.25251 -209.130646)
		(width 0.14732)
		(layer "In6.Cu")
		(net "UPI_CPU1_CPU0_P0P1_DN<21>")
	)
	(segment
		(start 109.951012 -209.617056)
		(end 110.106968 -209.542634)
		(width 0.14732)
		(layer "In6.Cu")
		(net "UPI_CPU1_CPU0_P0P1_DN<21>")
	)
	(segment
		(start 344.256106 -178.463956)
		(end 344.804492 -178.684174)
		(width 0.14732)
		(layer "In6.Cu")
		(net "UPI_CPU1_CPU0_P0P1_DN<21>")
	)
	(segment
		(start 139.446 -173.078394)
		(end 139.869164 -173.179486)
		(width 0.14732)
		(layer "In6.Cu")
		(net "UPI_CPU1_CPU0_P0P1_DN<21>")
	)
	(segment
		(start 179.087526 -162.68319)
		(end 178.94427 -162.833558)
		(width 0.14732)
		(layer "In6.Cu")
		(net "UPI_CPU1_CPU0_P0P1_DN<21>")
	)
	(segment
		(start 159.351218 -164.267642)
		(end 161.749486 -164.227764)
		(width 0.14732)
		(layer "In6.Cu")
		(net "UPI_CPU1_CPU0_P0P1_DN<21>")
	)
	(segment
		(start 314.565284 -166.337742)
		(end 321.81927 -168.384982)
		(width 0.14732)
		(layer "In6.Cu")
		(net "UPI_CPU1_CPU0_P0P1_DN<21>")
	)
	(segment
		(start 194.871848 -166.474902)
		(end 197.632574 -166.12743)
		(width 0.14732)
		(layer "In6.Cu")
		(net "UPI_CPU1_CPU0_P0P1_DN<21>")
	)
	(segment
		(start 173.860714 -165.234366)
		(end 174.160942 -164.919152)
		(width 0.14732)
		(layer "In6.Cu")
		(net "UPI_CPU1_CPU0_P0P1_DN<21>")
	)
	(segment
		(start 351.028508 -181.548786)
		(end 351.199196 -181.767734)
		(width 0.14732)
		(layer "In6.Cu")
		(net "UPI_CPU1_CPU0_P0P1_DN<21>")
	)
	(segment
		(start 155.113228 -165.758114)
		(end 155.931362 -165.744144)
		(width 0.14732)
		(layer "In6.Cu")
		(net "UPI_CPU1_CPU0_P0P1_DN<21>")
	)
	(segment
		(start 109.211364 -211.82457)
		(end 109.253528 -211.782406)
		(width 0.0889)
		(layer "In6.Cu")
		(net "UPI_CPU1_CPU0_P0P1_DN<21>")
	)
	(segment
		(start 353.331526 -183.713374)
		(end 353.332034 -183.712612)
		(width 0.14732)
		(layer "In6.Cu")
		(net "UPI_CPU1_CPU0_P0P1_DN<21>")
	)
	(segment
		(start 171.217336 -165.300152)
		(end 173.860714 -165.234366)
		(width 0.14732)
		(layer "In6.Cu")
		(net "UPI_CPU1_CPU0_P0P1_DN<21>")
	)
	(segment
		(start 177.59934 -161.98215)
		(end 178.922172 -161.949638)
		(width 0.14732)
		(layer "In6.Cu")
		(net "UPI_CPU1_CPU0_P0P1_DN<21>")
	)
	(segment
		(start 189.168278 -166.474902)
		(end 194.871848 -166.474902)
		(width 0.14732)
		(layer "In6.Cu")
		(net "UPI_CPU1_CPU0_P0P1_DN<21>")
	)
	(segment
		(start 139.107164 -172.80763)
		(end 139.309602 -172.856144)
		(width 0.14732)
		(layer "In6.Cu")
		(net "UPI_CPU1_CPU0_P0P1_DN<21>")
	)
	(segment
		(start 344.797888 -179.094384)
		(end 344.969592 -179.494942)
		(width 0.14732)
		(layer "In6.Cu")
		(net "UPI_CPU1_CPU0_P0P1_DN<21>")
	)
	(segment
		(start 138.604752 -173.116494)
		(end 139.107164 -172.80763)
		(width 0.14732)
		(layer "In6.Cu")
		(net "UPI_CPU1_CPU0_P0P1_DN<21>")
	)
	(segment
		(start 177.677318 -165.139878)
		(end 181.464966 -165.046914)
		(width 0.14732)
		(layer "In6.Cu")
		(net "UPI_CPU1_CPU0_P0P1_DN<21>")
	)
	(segment
		(start 350.721676 -181.357524)
		(end 351.028508 -181.548786)
		(width 0.14732)
		(layer "In6.Cu")
		(net "UPI_CPU1_CPU0_P0P1_DN<21>")
	)
	(segment
		(start 346.94876 -179.957476)
		(end 347.120464 -180.357526)
		(width 0.14732)
		(layer "In6.Cu")
		(net "UPI_CPU1_CPU0_P0P1_DN<21>")
	)
	(segment
		(start 348.43212 -180.884068)
		(end 350.721676 -181.357524)
		(width 0.14732)
		(layer "In6.Cu")
		(net "UPI_CPU1_CPU0_P0P1_DN<21>")
	)
	(segment
		(start 176.177448 -165.176962)
		(end 176.477676 -164.861748)
		(width 0.14732)
		(layer "In6.Cu")
		(net "UPI_CPU1_CPU0_P0P1_DN<21>")
	)
	(segment
		(start 173.304962 -162.74034)
		(end 173.448218 -162.589972)
		(width 0.14732)
		(layer "In6.Cu")
		(net "UPI_CPU1_CPU0_P0P1_DN<21>")
	)
	(segment
		(start 109.310678 -213.048088)
		(end 109.211364 -212.948774)
		(width 0.0889)
		(layer "In6.Cu")
		(net "UPI_CPU1_CPU0_P0P1_DN<21>")
	)
	(segment
		(start 179.072794 -162.09264)
		(end 179.087526 -162.68319)
		(width 0.14732)
		(layer "In6.Cu")
		(net "UPI_CPU1_CPU0_P0P1_DN<21>")
	)
	(segment
		(start 185.97118 -165.478968)
		(end 186.36488 -165.478968)
		(width 0.14732)
		(layer "In6.Cu")
		(net "UPI_CPU1_CPU0_P0P1_DN<21>")
	)
	(segment
		(start 175.360584 -165.197282)
		(end 176.177448 -165.176962)
		(width 0.14732)
		(layer "In6.Cu")
		(net "UPI_CPU1_CPU0_P0P1_DN<21>")
	)
	(segment
		(start 345.727782 -179.799488)
		(end 346.127832 -179.627784)
		(width 0.14732)
		(layer "In6.Cu")
		(net "UPI_CPU1_CPU0_P0P1_DN<21>")
	)
	(segment
		(start 342.103202 -177.913284)
		(end 342.326214 -178.434746)
		(width 0.14732)
		(layer "In6.Cu")
		(net "UPI_CPU1_CPU0_P0P1_DN<21>")
	)
	(segment
		(start 175.04537 -164.897054)
		(end 175.360584 -165.197282)
		(width 0.14732)
		(layer "In6.Cu")
		(net "UPI_CPU1_CPU0_P0P1_DN<21>")
	)
	(segment
		(start 352.180652 -184.145428)
		(end 352.988626 -184.145428)
		(width 0.14732)
		(layer "In6.Cu")
		(net "UPI_CPU1_CPU0_P0P1_DN<21>")
	)
	(segment
		(start 177.112168 -160.679384)
		(end 177.262536 -160.82264)
		(width 0.14732)
		(layer "In6.Cu")
		(net "UPI_CPU1_CPU0_P0P1_DN<21>")
	)
	(segment
		(start 140.579602 -171.90339)
		(end 141.082014 -171.594526)
		(width 0.14732)
		(layer "In6.Cu")
		(net "UPI_CPU1_CPU0_P0P1_DN<21>")
	)
	(segment
		(start 144.642332 -170.531028)
		(end 144.743424 -170.10761)
		(width 0.14732)
		(layer "In6.Cu")
		(net "UPI_CPU1_CPU0_P0P1_DN<21>")
	)
	(segment
		(start 109.734096 -210.59648)
		(end 109.879892 -210.184238)
		(width 0.14732)
		(layer "In6.Cu")
		(net "UPI_CPU1_CPU0_P0P1_DN<21>")
	)
	(segment
		(start 157.777942 -164.720778)
		(end 158.090616 -165.023292)
		(width 0.14732)
		(layer "In6.Cu")
		(net "UPI_CPU1_CPU0_P0P1_DN<21>")
	)
	(segment
		(start 141.581124 -172.126402)
		(end 142.004288 -172.227494)
		(width 0.14732)
		(layer "In6.Cu")
		(net "UPI_CPU1_CPU0_P0P1_DN<21>")
	)
	(segment
		(start 109.211364 -213.414102)
		(end 109.310678 -213.314788)
		(width 0.0889)
		(layer "In6.Cu")
		(net "UPI_CPU1_CPU0_P0P1_DN<21>")
	)
	(segment
		(start 137.132314 -174.020734)
		(end 137.334752 -174.069248)
		(width 0.14732)
		(layer "In6.Cu")
		(net "UPI_CPU1_CPU0_P0P1_DN<21>")
	)
	(segment
		(start 174.204884 -160.75152)
		(end 174.795434 -160.736788)
		(width 0.14732)
		(layer "In6.Cu")
		(net "UPI_CPU1_CPU0_P0P1_DN<21>")
	)
	(segment
		(start 166.770812 -166.118032)
		(end 168.529508 -166.176198)
		(width 0.14732)
		(layer "In6.Cu")
		(net "UPI_CPU1_CPU0_P0P1_DN<21>")
	)
	(segment
		(start 346.127832 -179.627784)
		(end 346.21597 -179.408582)
		(width 0.14732)
		(layer "In6.Cu")
		(net "UPI_CPU1_CPU0_P0P1_DN<21>")
	)
	(segment
		(start 141.082014 -171.594526)
		(end 141.284452 -171.64304)
		(width 0.14732)
		(layer "In6.Cu")
		(net "UPI_CPU1_CPU0_P0P1_DN<21>")
	)
	(segment
		(start 156.233876 -165.431216)
		(end 156.21762 -164.466778)
		(width 0.14732)
		(layer "In6.Cu")
		(net "UPI_CPU1_CPU0_P0P1_DN<21>")
	)
	(segment
		(start 352.988626 -184.145428)
		(end 353.209352 -183.924956)
		(width 0.14732)
		(layer "In6.Cu")
		(net "UPI_CPU1_CPU0_P0P1_DN<21>")
	)
	(segment
		(start 178.94427 -162.833558)
		(end 177.621438 -162.866578)
		(width 0.14732)
		(layer "In6.Cu")
		(net "UPI_CPU1_CPU0_P0P1_DN<21>")
	)
	(segment
		(start 173.448218 -162.589972)
		(end 173.794928 -162.581082)
		(width 0.14732)
		(layer "In6.Cu")
		(net "UPI_CPU1_CPU0_P0P1_DN<21>")
	)
	(segment
		(start 142.80261 -171.376086)
		(end 142.505938 -170.892724)
		(width 0.14732)
		(layer "In6.Cu")
		(net "UPI_CPU1_CPU0_P0P1_DN<21>")
	)
	(segment
		(start 159.211264 -164.696902)
		(end 159.206438 -164.416994)
		(width 0.14732)
		(layer "In6.Cu")
		(net "UPI_CPU1_CPU0_P0P1_DN<21>")
	)
	(segment
		(start 351.46742 -183.390032)
		(end 351.705164 -183.868822)
		(width 0.14732)
		(layer "In6.Cu")
		(net "UPI_CPU1_CPU0_P0P1_DN<21>")
	)
	(segment
		(start 280.175208 -166.475918)
		(end 302.491648 -166.091362)
		(width 0.14732)
		(layer "In6.Cu")
		(net "UPI_CPU1_CPU0_P0P1_DN<21>")
	)
	(segment
		(start 159.206438 -164.416994)
		(end 159.351218 -164.267642)
		(width 0.14732)
		(layer "In6.Cu")
		(net "UPI_CPU1_CPU0_P0P1_DN<21>")
	)
	(segment
		(start 177.362104 -164.83965)
		(end 177.677318 -165.139878)
		(width 0.14732)
		(layer "In6.Cu")
		(net "UPI_CPU1_CPU0_P0P1_DN<21>")
	)
	(segment
		(start 140.566394 -172.751242)
		(end 140.667486 -172.328078)
		(width 0.14732)
		(layer "In6.Cu")
		(net "UPI_CPU1_CPU0_P0P1_DN<21>")
	)
	(segment
		(start 154.784298 -164.490908)
		(end 154.800554 -165.4556)
		(width 0.14732)
		(layer "In6.Cu")
		(net "UPI_CPU1_CPU0_P0P1_DN<21>")
	)
	(segment
		(start 109.211364 -212.682074)
		(end 109.310678 -212.58276)
		(width 0.0889)
		(layer "In6.Cu")
		(net "UPI_CPU1_CPU0_P0P1_DN<21>")
	)
	(segment
		(start 347.120464 -180.357526)
		(end 348.43212 -180.884068)
		(width 0.14732)
		(layer "In6.Cu")
		(net "UPI_CPU1_CPU0_P0P1_DN<21>")
	)
	(segment
		(start 142.004288 -172.227494)
		(end 142.701518 -171.79925)
		(width 0.14732)
		(layer "In6.Cu")
		(net "UPI_CPU1_CPU0_P0P1_DN<21>")
	)
	(segment
		(start 154.800554 -165.4556)
		(end 155.113228 -165.758114)
		(width 0.14732)
		(layer "In6.Cu")
		(net "UPI_CPU1_CPU0_P0P1_DN<21>")
	)
	(segment
		(start 174.160942 -164.919152)
		(end 174.13224 -163.765738)
		(width 0.14732)
		(layer "In6.Cu")
		(net "UPI_CPU1_CPU0_P0P1_DN<21>")
	)
	(segment
		(start 109.310678 -212.31606)
		(end 109.211364 -212.216746)
		(width 0.0889)
		(layer "In6.Cu")
		(net "UPI_CPU1_CPU0_P0P1_DN<21>")
	)
	(segment
		(start 177.262536 -160.82264)
		(end 177.284126 -161.681922)
		(width 0.14732)
		(layer "In6.Cu")
		(net "UPI_CPU1_CPU0_P0P1_DN<21>")
	)
	(segment
		(start 173.470316 -163.473892)
		(end 173.319694 -163.33089)
		(width 0.14732)
		(layer "In6.Cu")
		(net "UPI_CPU1_CPU0_P0P1_DN<21>")
	)
	(segment
		(start 140.531088 -172.105828)
		(end 140.579602 -171.90339)
		(width 0.14732)
		(layer "In6.Cu")
		(net "UPI_CPU1_CPU0_P0P1_DN<21>")
	)
	(segment
		(start 197.632574 -166.12743)
		(end 234.645708 -156.585158)
		(width 0.14732)
		(layer "In6.Cu")
		(net "UPI_CPU1_CPU0_P0P1_DN<21>")
	)
	(segment
		(start 346.21597 -179.408582)
		(end 346.406978 -179.326794)
		(width 0.14732)
		(layer "In6.Cu")
		(net "UPI_CPU1_CPU0_P0P1_DN<21>")
	)
	(segment
		(start 142.554452 -170.690286)
		(end 143.056864 -170.381422)
		(width 0.14732)
		(layer "In6.Cu")
		(net "UPI_CPU1_CPU0_P0P1_DN<21>")
	)
	(segment
		(start 109.211364 -212.216746)
		(end 109.211364 -211.82457)
		(width 0.0889)
		(layer "In6.Cu")
		(net "UPI_CPU1_CPU0_P0P1_DN<21>")
	)
	(segment
		(start 177.621438 -162.866578)
		(end 177.32121 -163.181792)
		(width 0.14732)
		(layer "In6.Cu")
		(net "UPI_CPU1_CPU0_P0P1_DN<21>")
	)
	(segment
		(start 139.869164 -173.179486)
		(end 140.566394 -172.751242)
		(width 0.14732)
		(layer "In6.Cu")
		(net "UPI_CPU1_CPU0_P0P1_DN<21>")
	)
	(segment
		(start 351.199196 -181.767734)
		(end 351.46742 -183.390032)
		(width 0.14732)
		(layer "In6.Cu")
		(net "UPI_CPU1_CPU0_P0P1_DN<21>")
	)
	(segment
		(start 347.036898 -179.737766)
		(end 346.94876 -179.957476)
		(width 0.14732)
		(layer "In6.Cu")
		(net "UPI_CPU1_CPU0_P0P1_DN<21>")
	)
	(segment
		(start 108.820458 -214.622634)
		(end 108.663994 -214.893652)
		(width 0.0889)
		(layer "In6.Cu")
		(net "UPI_CPU1_CPU0_P0P1_DN<21>")
	)
	(segment
		(start 114.311684 -197.287896)
		(end 122.708924 -186.864498)
		(width 0.14732)
		(layer "In6.Cu")
		(net "UPI_CPU1_CPU0_P0P1_DN<21>")
	)
	(segment
		(start 181.464966 -165.046914)
		(end 184.942988 -165.660324)
		(width 0.14732)
		(layer "In6.Cu")
		(net "UPI_CPU1_CPU0_P0P1_DN<21>")
	)
	(segment
		(start 346.406978 -179.326794)
		(end 346.955364 -179.547012)
		(width 0.14732)
		(layer "In6.Cu")
		(net "UPI_CPU1_CPU0_P0P1_DN<21>")
	)
	(segment
		(start 143.522192 -170.85818)
		(end 143.945102 -170.959272)
		(width 0.14732)
		(layer "In6.Cu")
		(net "UPI_CPU1_CPU0_P0P1_DN<21>")
	)
	(segment
		(start 343.57691 -178.93665)
		(end 343.97696 -178.764946)
		(width 0.14732)
		(layer "In6.Cu")
		(net "UPI_CPU1_CPU0_P0P1_DN<21>")
	)
	(segment
		(start 158.090616 -165.023292)
		(end 158.90875 -165.009576)
		(width 0.14732)
		(layer "In6.Cu")
		(net "UPI_CPU1_CPU0_P0P1_DN<21>")
	)
	(segment
		(start 161.749486 -164.227764)
		(end 166.68242 -166.099998)
		(width 0.14732)
		(layer "In6.Cu")
		(net "UPI_CPU1_CPU0_P0P1_DN<21>")
	)
	(segment
		(start 171.217082 -165.300406)
		(end 171.217336 -165.300152)
		(width 0.14732)
		(layer "In6.Cu")
		(net "UPI_CPU1_CPU0_P0P1_DN<21>")
	)
	(segment
		(start 353.209352 -183.924956)
		(end 353.331526 -183.713374)
		(width 0.14732)
		(layer "In6.Cu")
		(net "UPI_CPU1_CPU0_P0P1_DN<21>")
	)
	(segment
		(start 110.25251 -209.130646)
		(end 110.178342 -208.974944)
		(width 0.14732)
		(layer "In6.Cu")
		(net "UPI_CPU1_CPU0_P0P1_DN<21>")
	)
	(segment
		(start 342.326214 -178.434746)
		(end 343.57691 -178.93665)
		(width 0.14732)
		(layer "In6.Cu")
		(net "UPI_CPU1_CPU0_P0P1_DN<21>")
	)
	(segment
		(start 140.667486 -172.328078)
		(end 140.531088 -172.105828)
		(width 0.14732)
		(layer "In6.Cu")
		(net "UPI_CPU1_CPU0_P0P1_DN<21>")
	)
	(segment
		(start 144.743424 -170.10761)
		(end 144.480788 -169.67962)
		(width 0.14732)
		(layer "In6.Cu")
		(net "UPI_CPU1_CPU0_P0P1_DN<21>")
	)
	(segment
		(start 174.061374 -160.902142)
		(end 174.204884 -160.75152)
		(width 0.14732)
		(layer "In6.Cu")
		(net "UPI_CPU1_CPU0_P0P1_DN<21>")
	)
	(segment
		(start 143.056864 -170.381422)
		(end 143.259302 -170.429936)
		(width 0.14732)
		(layer "In6.Cu")
		(net "UPI_CPU1_CPU0_P0P1_DN<21>")
	)
	(segment
		(start 174.13224 -163.765738)
		(end 173.817026 -163.46551)
		(width 0.14732)
		(layer "In6.Cu")
		(net "UPI_CPU1_CPU0_P0P1_DN<21>")
	)
	(segment
		(start 109.211364 -213.680802)
		(end 109.211364 -213.414102)
		(width 0.0889)
		(layer "In6.Cu")
		(net "UPI_CPU1_CPU0_P0P1_DN<21>")
	)
	(segment
		(start 344.065098 -178.545744)
		(end 344.256106 -178.463956)
		(width 0.14732)
		(layer "In6.Cu")
		(net "UPI_CPU1_CPU0_P0P1_DN<21>")
	)
	(segment
		(start 138.692636 -173.541182)
		(end 138.556238 -173.318932)
		(width 0.14732)
		(layer "In6.Cu")
		(net "UPI_CPU1_CPU0_P0P1_DN<21>")
	)
	(segment
		(start 157.773116 -164.44087)
		(end 157.777942 -164.720778)
		(width 0.14732)
		(layer "In6.Cu")
		(net "UPI_CPU1_CPU0_P0P1_DN<21>")
	)
	(segment
		(start 336.582512 -176.130712)
		(end 340.983316 -177.89652)
		(width 0.14732)
		(layer "In6.Cu")
		(net "UPI_CPU1_CPU0_P0P1_DN<21>")
	)
	(segment
		(start 157.623764 -164.29609)
		(end 157.773116 -164.44087)
		(width 0.14732)
		(layer "In6.Cu")
		(net "UPI_CPU1_CPU0_P0P1_DN<21>")
	)
	(segment
		(start 144.529302 -169.477182)
		(end 152.219914 -164.754052)
		(width 0.14732)
		(layer "In6.Cu")
		(net "UPI_CPU1_CPU0_P0P1_DN<21>")
	)
	(segment
		(start 344.969592 -179.494942)
		(end 345.727782 -179.799488)
		(width 0.14732)
		(layer "In6.Cu")
		(net "UPI_CPU1_CPU0_P0P1_DN<21>")
	)
	(segment
		(start 171.217082 -165.300152)
		(end 171.217082 -165.300406)
		(width 0.14732)
		(layer "In6.Cu")
		(net "UPI_CPU1_CPU0_P0P1_DN<21>")
	)
	(segment
		(start 344.804492 -178.684174)
		(end 344.886026 -178.874928)
		(width 0.14732)
		(layer "In6.Cu")
		(net "UPI_CPU1_CPU0_P0P1_DN<21>")
	)
	(segment
		(start 177.32121 -163.181792)
		(end 177.362104 -164.83965)
		(width 0.14732)
		(layer "In6.Cu")
		(net "UPI_CPU1_CPU0_P0P1_DN<21>")
	)
	(segment
		(start 142.505938 -170.892724)
		(end 142.554452 -170.690286)
		(width 0.14732)
		(layer "In6.Cu")
		(net "UPI_CPU1_CPU0_P0P1_DN<21>")
	)
	(segment
		(start 343.97696 -178.764946)
		(end 344.065098 -178.545744)
		(width 0.14732)
		(layer "In6.Cu")
		(net "UPI_CPU1_CPU0_P0P1_DN<21>")
	)
	(segment
		(start 110.178342 -208.974944)
		(end 114.311684 -197.287896)
		(width 0.14732)
		(layer "In6.Cu")
		(net "UPI_CPU1_CPU0_P0P1_DN<21>")
	)
	(segment
		(start 141.284452 -171.64304)
		(end 141.581124 -172.126402)
		(width 0.14732)
		(layer "In6.Cu")
		(net "UPI_CPU1_CPU0_P0P1_DN<21>")
	)
	(segment
		(start 109.253528 -211.782406)
		(end 109.253528 -211.77123)
		(width 0.0889)
		(layer "In6.Cu")
		(net "UPI_CPU1_CPU0_P0P1_DN<21>")
	)
	(arc
		(start 108.585762 -214.91448)
		(mid 108.482617 -214.784455)
		(end 108.445808 -214.622634)
		(width 0.0889)
		(layer "In6.Cu")
		(net "UPI_CPU1_CPU0_P0P1_DN<21>")
	)
	(arc
		(start 108.445808 -214.461852)
		(mid 108.520879 -214.34611)
		(end 108.630212 -214.261954)
		(width 0.0889)
		(layer "In6.Cu")
		(net "UPI_CPU1_CPU0_P0P1_DN<21>")
	)
	(segment
		(start 353.920298 -198.8693)
		(end 353.925124 -198.864474)
		(width 0.13208)
		(layer "F.Cu")
		(net "UPI_CPU1_CPU0_P0P1_DN<20>")
	)
	(segment
		(start 357.219758 -186.402726)
		(end 356.648258 -185.023506)
		(width 0.13208)
		(layer "F.Cu")
		(net "UPI_CPU1_CPU0_P0P1_DN<20>")
	)
	(segment
		(start 355.41077 -183.962294)
		(end 355.130354 -183.681878)
		(width 0.13208)
		(layer "F.Cu")
		(net "UPI_CPU1_CPU0_P0P1_DN<20>")
	)
	(segment
		(start 107.880912 -215.158574)
		(end 107.880912 -214.622888)
		(width 0.13208)
		(layer "F.Cu")
		(net "UPI_CPU1_CPU0_P0P1_DN<20>")
	)
	(segment
		(start 358.643682 -210.363054)
		(end 353.954588 -205.673706)
		(width 0.0889)
		(layer "F.Cu")
		(net "UPI_CPU1_CPU0_P0P1_DN<20>")
	)
	(segment
		(start 352.714052 -181.932326)
		(end 349.919798 -180.25745)
		(width 0.13208)
		(layer "F.Cu")
		(net "UPI_CPU1_CPU0_P0P1_DN<20>")
	)
	(segment
		(start 355.010212 -193.409316)
		(end 357.219758 -188.075316)
		(width 0.13208)
		(layer "F.Cu")
		(net "UPI_CPU1_CPU0_P0P1_DN<20>")
	)
	(segment
		(start 353.954588 -205.261464)
		(end 353.920298 -205.227174)
		(width 0.0889)
		(layer "F.Cu")
		(net "UPI_CPU1_CPU0_P0P1_DN<20>")
	)
	(segment
		(start 356.648258 -185.023506)
		(end 355.586792 -183.962294)
		(width 0.13208)
		(layer "F.Cu")
		(net "UPI_CPU1_CPU0_P0P1_DN<20>")
	)
	(segment
		(start 363.81436 -215.964262)
		(end 363.964728 -215.703658)
		(width 0.0889)
		(layer "F.Cu")
		(net "UPI_CPU1_CPU0_P0P1_DN<20>")
	)
	(segment
		(start 354.028756 -182.51551)
		(end 352.714052 -181.932326)
		(width 0.13208)
		(layer "F.Cu")
		(net "UPI_CPU1_CPU0_P0P1_DN<20>")
	)
	(segment
		(start 353.954588 -205.673706)
		(end 353.954588 -205.261464)
		(width 0.0889)
		(layer "F.Cu")
		(net "UPI_CPU1_CPU0_P0P1_DN<20>")
	)
	(segment
		(start 357.219758 -188.075316)
		(end 357.219758 -186.402726)
		(width 0.13208)
		(layer "F.Cu")
		(net "UPI_CPU1_CPU0_P0P1_DN<20>")
	)
	(segment
		(start 353.920298 -205.205076)
		(end 353.920298 -198.8693)
		(width 0.13208)
		(layer "F.Cu")
		(net "UPI_CPU1_CPU0_P0P1_DN<20>")
	)
	(segment
		(start 107.880912 -214.622888)
		(end 107.880658 -214.622634)
		(width 0.13208)
		(layer "F.Cu")
		(net "UPI_CPU1_CPU0_P0P1_DN<20>")
	)
	(segment
		(start 355.130354 -183.681878)
		(end 355.130354 -183.505856)
		(width 0.13208)
		(layer "F.Cu")
		(net "UPI_CPU1_CPU0_P0P1_DN<20>")
	)
	(segment
		(start 363.809534 -215.972644)
		(end 363.81436 -215.964262)
		(width 0.0889)
		(layer "F.Cu")
		(net "UPI_CPU1_CPU0_P0P1_DN<20>")
	)
	(segment
		(start 364.184184 -214.345012)
		(end 364.184184 -213.57082)
		(width 0.0889)
		(layer "F.Cu")
		(net "UPI_CPU1_CPU0_P0P1_DN<20>")
	)
	(segment
		(start 349.715074 -179.906676)
		(end 349.165672 -179.757832)
		(width 0.13208)
		(layer "F.Cu")
		(net "UPI_CPU1_CPU0_P0P1_DN<20>")
	)
	(segment
		(start 362.627164 -212.0138)
		(end 358.643682 -210.363054)
		(width 0.0889)
		(layer "F.Cu")
		(net "UPI_CPU1_CPU0_P0P1_DN<20>")
	)
	(segment
		(start 349.725996 -179.9209)
		(end 349.715074 -179.906676)
		(width 0.13208)
		(layer "F.Cu")
		(net "UPI_CPU1_CPU0_P0P1_DN<20>")
	)
	(segment
		(start 355.586792 -183.962294)
		(end 355.41077 -183.962294)
		(width 0.13208)
		(layer "F.Cu")
		(net "UPI_CPU1_CPU0_P0P1_DN<20>")
	)
	(segment
		(start 349.919798 -180.25745)
		(end 349.725996 -179.9209)
		(width 0.13208)
		(layer "F.Cu")
		(net "UPI_CPU1_CPU0_P0P1_DN<20>")
	)
	(segment
		(start 353.925124 -198.864474)
		(end 355.010212 -193.409316)
		(width 0.13208)
		(layer "F.Cu")
		(net "UPI_CPU1_CPU0_P0P1_DN<20>")
	)
	(segment
		(start 353.920298 -205.227174)
		(end 353.920298 -205.205076)
		(width 0.0889)
		(layer "F.Cu")
		(net "UPI_CPU1_CPU0_P0P1_DN<20>")
	)
	(segment
		(start 364.184184 -213.57082)
		(end 362.627164 -212.0138)
		(width 0.0889)
		(layer "F.Cu")
		(net "UPI_CPU1_CPU0_P0P1_DN<20>")
	)
	(segment
		(start 354.365052 -182.740554)
		(end 354.028756 -182.51551)
		(width 0.13208)
		(layer "F.Cu")
		(net "UPI_CPU1_CPU0_P0P1_DN<20>")
	)
	(segment
		(start 363.964728 -215.703658)
		(end 363.939582 -215.610694)
		(width 0.0889)
		(layer "F.Cu")
		(net "UPI_CPU1_CPU0_P0P1_DN<20>")
	)
	(segment
		(start 355.130354 -183.505856)
		(end 354.365052 -182.740554)
		(width 0.13208)
		(layer "F.Cu")
		(net "UPI_CPU1_CPU0_P0P1_DN<20>")
	)
	(arc
		(start 363.939582 -215.610694)
		(mid 363.931264 -215.60404)
		(end 363.923072 -215.597232)
		(width 0.0889)
		(layer "F.Cu")
		(net "UPI_CPU1_CPU0_P0P1_DN<20>")
	)
	(arc
		(start 364.009178 -214.661496)
		(mid 364.137384 -214.525766)
		(end 364.184184 -214.345012)
		(width 0.0889)
		(layer "F.Cu")
		(net "UPI_CPU1_CPU0_P0P1_DN<20>")
	)
	(arc
		(start 363.923072 -215.597232)
		(mid 363.716058 -215.106317)
		(end 364.009178 -214.661496)
		(width 0.0889)
		(layer "F.Cu")
		(net "UPI_CPU1_CPU0_P0P1_DN<20>")
	)
	(segment
		(start 174.729394 -159.740346)
		(end 174.004224 -159.36087)
		(width 0.14732)
		(layer "In6.Cu")
		(net "UPI_CPU1_CPU0_P0P1_DN<20>")
	)
	(segment
		(start 189.4078 -165.633908)
		(end 175.86579 -158.548832)
		(width 0.14732)
		(layer "In6.Cu")
		(net "UPI_CPU1_CPU0_P0P1_DN<20>")
	)
	(segment
		(start 160.19018 -161.68116)
		(end 160.089596 -162.104324)
		(width 0.14732)
		(layer "In6.Cu")
		(net "UPI_CPU1_CPU0_P0P1_DN<20>")
	)
	(segment
		(start 349.206566 -179.035456)
		(end 348.82328 -178.859688)
		(width 0.14732)
		(layer "In6.Cu")
		(net "UPI_CPU1_CPU0_P0P1_DN<20>")
	)
	(segment
		(start 107.721908 -214.321644)
		(end 107.880658 -214.622634)
		(width 0.0889)
		(layer "In6.Cu")
		(net "UPI_CPU1_CPU0_P0P1_DN<20>")
	)
	(segment
		(start 157.067758 -160.75152)
		(end 157.019752 -160.953958)
		(width 0.14732)
		(layer "In6.Cu")
		(net "UPI_CPU1_CPU0_P0P1_DN<20>")
	)
	(segment
		(start 157.80512 -162.814762)
		(end 157.108398 -163.244276)
		(width 0.14732)
		(layer "In6.Cu")
		(net "UPI_CPU1_CPU0_P0P1_DN<20>")
	)
	(segment
		(start 110.060232 -206.2734)
		(end 109.934248 -206.619602)
		(width 0.14732)
		(layer "In6.Cu")
		(net "UPI_CPU1_CPU0_P0P1_DN<20>")
	)
	(segment
		(start 109.466888 -207.47863)
		(end 109.553502 -207.66405)
		(width 0.14732)
		(layer "In6.Cu")
		(net "UPI_CPU1_CPU0_P0P1_DN<20>")
	)
	(segment
		(start 330.187046 -171.83608)
		(end 329.463654 -171.45635)
		(width 0.14732)
		(layer "In6.Cu")
		(net "UPI_CPU1_CPU0_P0P1_DN<20>")
	)
	(segment
		(start 335.936082 -173.420532)
		(end 335.874106 -173.222158)
		(width 0.14732)
		(layer "In6.Cu")
		(net "UPI_CPU1_CPU0_P0P1_DN<20>")
	)
	(segment
		(start 329.33386 -171.040552)
		(end 329.779884 -170.190414)
		(width 0.14732)
		(layer "In6.Cu")
		(net "UPI_CPU1_CPU0_P0P1_DN<20>")
	)
	(segment
		(start 108.018326 -211.454238)
		(end 108.018326 -211.77123)
		(width 0.14732)
		(layer "In6.Cu")
		(net "UPI_CPU1_CPU0_P0P1_DN<20>")
	)
	(segment
		(start 161.205926 -161.058098)
		(end 160.782762 -160.957514)
		(width 0.14732)
		(layer "In6.Cu")
		(net "UPI_CPU1_CPU0_P0P1_DN<20>")
	)
	(segment
		(start 113.123472 -197.442328)
		(end 110.414562 -204.87767)
		(width 0.14732)
		(layer "In6.Cu")
		(net "UPI_CPU1_CPU0_P0P1_DN<20>")
	)
	(segment
		(start 159.392874 -162.533838)
		(end 158.96971 -162.433254)
		(width 0.14732)
		(layer "In6.Cu")
		(net "UPI_CPU1_CPU0_P0P1_DN<20>")
	)
	(segment
		(start 157.772354 -160.490154)
		(end 157.569916 -160.442148)
		(width 0.14732)
		(layer "In6.Cu")
		(net "UPI_CPU1_CPU0_P0P1_DN<20>")
	)
	(segment
		(start 161.902648 -160.628584)
		(end 161.205926 -161.058098)
		(width 0.14732)
		(layer "In6.Cu")
		(net "UPI_CPU1_CPU0_P0P1_DN<20>")
	)
	(segment
		(start 331.51572 -172.533056)
		(end 331.385926 -172.117258)
		(width 0.14732)
		(layer "In6.Cu")
		(net "UPI_CPU1_CPU0_P0P1_DN<20>")
	)
	(segment
		(start 160.782762 -160.957514)
		(end 159.745426 -159.274256)
		(width 0.14732)
		(layer "In6.Cu")
		(net "UPI_CPU1_CPU0_P0P1_DN<20>")
	)
	(segment
		(start 349.165672 -179.757832)
		(end 349.31096 -179.216304)
		(width 0.14732)
		(layer "In6.Cu")
		(net "UPI_CPU1_CPU0_P0P1_DN<20>")
	)
	(segment
		(start 108.890308 -209.06105)
		(end 108.764324 -209.406998)
		(width 0.14732)
		(layer "In6.Cu")
		(net "UPI_CPU1_CPU0_P0P1_DN<20>")
	)
	(segment
		(start 173.874176 -158.945834)
		(end 174.397162 -157.946598)
		(width 0.14732)
		(layer "In6.Cu")
		(net "UPI_CPU1_CPU0_P0P1_DN<20>")
	)
	(segment
		(start 160.089596 -162.104324)
		(end 159.392874 -162.533838)
		(width 0.14732)
		(layer "In6.Cu")
		(net "UPI_CPU1_CPU0_P0P1_DN<20>")
	)
	(segment
		(start 332.65491 -172.782992)
		(end 332.239112 -172.912786)
		(width 0.14732)
		(layer "In6.Cu")
		(net "UPI_CPU1_CPU0_P0P1_DN<20>")
	)
	(segment
		(start 328.996802 -169.779442)
		(end 328.550778 -170.62958)
		(width 0.14732)
		(layer "In6.Cu")
		(net "UPI_CPU1_CPU0_P0P1_DN<20>")
	)
	(segment
		(start 335.351374 -172.947838)
		(end 335.153 -173.00956)
		(width 0.14732)
		(layer "In6.Cu")
		(net "UPI_CPU1_CPU0_P0P1_DN<20>")
	)
	(segment
		(start 158.992824 -159.73806)
		(end 160.19018 -161.68116)
		(width 0.14732)
		(layer "In6.Cu")
		(net "UPI_CPU1_CPU0_P0P1_DN<20>")
	)
	(segment
		(start 108.413042 -210.371182)
		(end 108.499402 -210.556602)
		(width 0.14732)
		(layer "In6.Cu")
		(net "UPI_CPU1_CPU0_P0P1_DN<20>")
	)
	(segment
		(start 157.905704 -162.391598)
		(end 157.80512 -162.814762)
		(width 0.14732)
		(layer "In6.Cu")
		(net "UPI_CPU1_CPU0_P0P1_DN<20>")
	)
	(segment
		(start 159.542988 -159.22625)
		(end 159.04083 -159.535622)
		(width 0.14732)
		(layer "In6.Cu")
		(net "UPI_CPU1_CPU0_P0P1_DN<20>")
	)
	(segment
		(start 329.717908 -169.99204)
		(end 329.195176 -169.71772)
		(width 0.14732)
		(layer "In6.Cu")
		(net "UPI_CPU1_CPU0_P0P1_DN<20>")
	)
	(segment
		(start 197.577964 -165.282372)
		(end 194.785234 -165.633908)
		(width 0.14732)
		(layer "In6.Cu")
		(net "UPI_CPU1_CPU0_P0P1_DN<20>")
	)
	(segment
		(start 108.499402 -210.556602)
		(end 108.373418 -210.903058)
		(width 0.14732)
		(layer "In6.Cu")
		(net "UPI_CPU1_CPU0_P0P1_DN<20>")
	)
	(segment
		(start 330.602844 -171.706286)
		(end 330.187046 -171.83608)
		(width 0.14732)
		(layer "In6.Cu")
		(net "UPI_CPU1_CPU0_P0P1_DN<20>")
	)
	(segment
		(start 108.373418 -210.903058)
		(end 108.187744 -210.989164)
		(width 0.14732)
		(layer "In6.Cu")
		(net "UPI_CPU1_CPU0_P0P1_DN<20>")
	)
	(segment
		(start 335.874106 -173.222158)
		(end 335.351374 -172.947838)
		(width 0.14732)
		(layer "In6.Cu")
		(net "UPI_CPU1_CPU0_P0P1_DN<20>")
	)
	(segment
		(start 156.685234 -163.143692)
		(end 155.799282 -161.706052)
		(width 0.14732)
		(layer "In6.Cu")
		(net "UPI_CPU1_CPU0_P0P1_DN<20>")
	)
	(segment
		(start 335.619852 -174.686468)
		(end 335.490058 -174.27067)
		(width 0.14732)
		(layer "In6.Cu")
		(net "UPI_CPU1_CPU0_P0P1_DN<20>")
	)
	(segment
		(start 109.553502 -207.66405)
		(end 109.427518 -208.010506)
		(width 0.14732)
		(layer "In6.Cu")
		(net "UPI_CPU1_CPU0_P0P1_DN<20>")
	)
	(segment
		(start 171.76496 -156.403548)
		(end 169.1894 -155.128468)
		(width 0.14732)
		(layer "In6.Cu")
		(net "UPI_CPU1_CPU0_P0P1_DN<20>")
	)
	(segment
		(start 174.334932 -157.748224)
		(end 171.76496 -156.403548)
		(width 0.14732)
		(layer "In6.Cu")
		(net "UPI_CPU1_CPU0_P0P1_DN<20>")
	)
	(segment
		(start 109.74832 -206.705962)
		(end 109.466888 -207.47863)
		(width 0.14732)
		(layer "In6.Cu")
		(net "UPI_CPU1_CPU0_P0P1_DN<20>")
	)
	(segment
		(start 329.463654 -171.45635)
		(end 329.33386 -171.040552)
		(width 0.14732)
		(layer "In6.Cu")
		(net "UPI_CPU1_CPU0_P0P1_DN<20>")
	)
	(segment
		(start 334.291178 -173.989492)
		(end 333.567786 -173.609762)
		(width 0.14732)
		(layer "In6.Cu")
		(net "UPI_CPU1_CPU0_P0P1_DN<20>")
	)
	(segment
		(start 107.976162 -211.82457)
		(end 107.976162 -213.93023)
		(width 0.0889)
		(layer "In6.Cu")
		(net "UPI_CPU1_CPU0_P0P1_DN<20>")
	)
	(segment
		(start 108.724954 -209.938874)
		(end 108.539026 -210.025234)
		(width 0.14732)
		(layer "In6.Cu")
		(net "UPI_CPU1_CPU0_P0P1_DN<20>")
	)
	(segment
		(start 155.596844 -161.658046)
		(end 134.091934 -174.91075)
		(width 0.14732)
		(layer "In6.Cu")
		(net "UPI_CPU1_CPU0_P0P1_DN<20>")
	)
	(segment
		(start 165.22446 -155.725368)
		(end 161.013902 -158.319724)
		(width 0.14732)
		(layer "In6.Cu")
		(net "UPI_CPU1_CPU0_P0P1_DN<20>")
	)
	(segment
		(start 157.569916 -160.442148)
		(end 157.067758 -160.75152)
		(width 0.14732)
		(layer "In6.Cu")
		(net "UPI_CPU1_CPU0_P0P1_DN<20>")
	)
	(segment
		(start 159.745426 -159.274256)
		(end 159.542988 -159.22625)
		(width 0.14732)
		(layer "In6.Cu")
		(net "UPI_CPU1_CPU0_P0P1_DN<20>")
	)
	(segment
		(start 134.091934 -174.91075)
		(end 121.954036 -186.326272)
		(width 0.14732)
		(layer "In6.Cu")
		(net "UPI_CPU1_CPU0_P0P1_DN<20>")
	)
	(segment
		(start 155.799282 -161.706052)
		(end 155.596844 -161.658046)
		(width 0.14732)
		(layer "In6.Cu")
		(net "UPI_CPU1_CPU0_P0P1_DN<20>")
	)
	(segment
		(start 332.239112 -172.912786)
		(end 331.51572 -172.533056)
		(width 0.14732)
		(layer "In6.Cu")
		(net "UPI_CPU1_CPU0_P0P1_DN<20>")
	)
	(segment
		(start 169.1894 -155.128468)
		(end 167.0939 -155.072588)
		(width 0.14732)
		(layer "In6.Cu")
		(net "UPI_CPU1_CPU0_P0P1_DN<20>")
	)
	(segment
		(start 333.82204 -172.145452)
		(end 333.299308 -171.871132)
		(width 0.14732)
		(layer "In6.Cu")
		(net "UPI_CPU1_CPU0_P0P1_DN<20>")
	)
	(segment
		(start 333.299308 -171.871132)
		(end 333.100934 -171.932854)
		(width 0.14732)
		(layer "In6.Cu")
		(net "UPI_CPU1_CPU0_P0P1_DN<20>")
	)
	(segment
		(start 162.003232 -160.20542)
		(end 161.902648 -160.628584)
		(width 0.14732)
		(layer "In6.Cu")
		(net "UPI_CPU1_CPU0_P0P1_DN<20>")
	)
	(segment
		(start 333.437992 -173.193964)
		(end 333.884016 -172.343826)
		(width 0.14732)
		(layer "In6.Cu")
		(net "UPI_CPU1_CPU0_P0P1_DN<20>")
	)
	(segment
		(start 322.128896 -167.607742)
		(end 314.688728 -165.507924)
		(width 0.14732)
		(layer "In6.Cu")
		(net "UPI_CPU1_CPU0_P0P1_DN<20>")
	)
	(segment
		(start 110.414562 -204.87767)
		(end 110.500922 -205.063344)
		(width 0.14732)
		(layer "In6.Cu")
		(net "UPI_CPU1_CPU0_P0P1_DN<20>")
	)
	(segment
		(start 110.500922 -205.063344)
		(end 110.374938 -205.409546)
		(width 0.14732)
		(layer "In6.Cu")
		(net "UPI_CPU1_CPU0_P0P1_DN<20>")
	)
	(segment
		(start 331.83195 -171.26712)
		(end 331.769974 -171.068746)
		(width 0.14732)
		(layer "In6.Cu")
		(net "UPI_CPU1_CPU0_P0P1_DN<20>")
	)
	(segment
		(start 174.004224 -159.36087)
		(end 173.874176 -158.945834)
		(width 0.14732)
		(layer "In6.Cu")
		(net "UPI_CPU1_CPU0_P0P1_DN<20>")
	)
	(segment
		(start 175.14443 -159.610298)
		(end 174.729394 -159.740346)
		(width 0.14732)
		(layer "In6.Cu")
		(net "UPI_CPU1_CPU0_P0P1_DN<20>")
	)
	(segment
		(start 329.779884 -170.190414)
		(end 329.717908 -169.99204)
		(width 0.14732)
		(layer "In6.Cu")
		(net "UPI_CPU1_CPU0_P0P1_DN<20>")
	)
	(segment
		(start 108.850938 -209.592418)
		(end 108.724954 -209.938874)
		(width 0.14732)
		(layer "In6.Cu")
		(net "UPI_CPU1_CPU0_P0P1_DN<20>")
	)
	(segment
		(start 108.018326 -211.77123)
		(end 108.018326 -211.782406)
		(width 0.0889)
		(layer "In6.Cu")
		(net "UPI_CPU1_CPU0_P0P1_DN<20>")
	)
	(segment
		(start 159.04083 -159.535622)
		(end 158.992824 -159.73806)
		(width 0.14732)
		(layer "In6.Cu")
		(net "UPI_CPU1_CPU0_P0P1_DN<20>")
	)
	(segment
		(start 109.24159 -208.096866)
		(end 109.115606 -208.442814)
		(width 0.14732)
		(layer "In6.Cu")
		(net "UPI_CPU1_CPU0_P0P1_DN<20>")
	)
	(segment
		(start 174.397162 -157.946598)
		(end 174.334932 -157.748224)
		(width 0.14732)
		(layer "In6.Cu")
		(net "UPI_CPU1_CPU0_P0P1_DN<20>")
	)
	(segment
		(start 280.167842 -165.644068)
		(end 276.179026 -165.644068)
		(width 0.14732)
		(layer "In6.Cu")
		(net "UPI_CPU1_CPU0_P0P1_DN<20>")
	)
	(segment
		(start 175.667416 -158.611062)
		(end 175.14443 -159.610298)
		(width 0.14732)
		(layer "In6.Cu")
		(net "UPI_CPU1_CPU0_P0P1_DN<20>")
	)
	(segment
		(start 328.550778 -170.62958)
		(end 328.13498 -170.759374)
		(width 0.14732)
		(layer "In6.Cu")
		(net "UPI_CPU1_CPU0_P0P1_DN<20>")
	)
	(segment
		(start 349.31096 -179.216304)
		(end 349.206566 -179.035456)
		(width 0.14732)
		(layer "In6.Cu")
		(net "UPI_CPU1_CPU0_P0P1_DN<20>")
	)
	(segment
		(start 335.490058 -174.27067)
		(end 335.936082 -173.420532)
		(width 0.14732)
		(layer "In6.Cu")
		(net "UPI_CPU1_CPU0_P0P1_DN<20>")
	)
	(segment
		(start 110.18901 -205.49616)
		(end 109.973618 -206.087726)
		(width 0.14732)
		(layer "In6.Cu")
		(net "UPI_CPU1_CPU0_P0P1_DN<20>")
	)
	(segment
		(start 328.13498 -170.759374)
		(end 322.128896 -167.607742)
		(width 0.14732)
		(layer "In6.Cu")
		(net "UPI_CPU1_CPU0_P0P1_DN<20>")
	)
	(segment
		(start 336.618834 -175.210978)
		(end 335.619852 -174.686468)
		(width 0.14732)
		(layer "In6.Cu")
		(net "UPI_CPU1_CPU0_P0P1_DN<20>")
	)
	(segment
		(start 335.153 -173.00956)
		(end 334.706976 -173.859698)
		(width 0.14732)
		(layer "In6.Cu")
		(net "UPI_CPU1_CPU0_P0P1_DN<20>")
	)
	(segment
		(start 109.973618 -206.087726)
		(end 110.060232 -206.2734)
		(width 0.14732)
		(layer "In6.Cu")
		(net "UPI_CPU1_CPU0_P0P1_DN<20>")
	)
	(segment
		(start 109.115606 -208.442814)
		(end 109.20222 -208.628234)
		(width 0.14732)
		(layer "In6.Cu")
		(net "UPI_CPU1_CPU0_P0P1_DN<20>")
	)
	(segment
		(start 331.247242 -170.794426)
		(end 331.048868 -170.856148)
		(width 0.14732)
		(layer "In6.Cu")
		(net "UPI_CPU1_CPU0_P0P1_DN<20>")
	)
	(segment
		(start 109.427518 -208.010506)
		(end 109.24159 -208.096866)
		(width 0.14732)
		(layer "In6.Cu")
		(net "UPI_CPU1_CPU0_P0P1_DN<20>")
	)
	(segment
		(start 121.954036 -186.326272)
		(end 113.123472 -197.442328)
		(width 0.14732)
		(layer "In6.Cu")
		(net "UPI_CPU1_CPU0_P0P1_DN<20>")
	)
	(segment
		(start 276.179026 -165.644068)
		(end 237.671356 -155.753308)
		(width 0.14732)
		(layer "In6.Cu")
		(net "UPI_CPU1_CPU0_P0P1_DN<20>")
	)
	(segment
		(start 109.934248 -206.619602)
		(end 109.74832 -206.705962)
		(width 0.14732)
		(layer "In6.Cu")
		(net "UPI_CPU1_CPU0_P0P1_DN<20>")
	)
	(segment
		(start 160.965896 -158.522162)
		(end 162.003232 -160.20542)
		(width 0.14732)
		(layer "In6.Cu")
		(net "UPI_CPU1_CPU0_P0P1_DN<20>")
	)
	(segment
		(start 331.385926 -172.117258)
		(end 331.83195 -171.26712)
		(width 0.14732)
		(layer "In6.Cu")
		(net "UPI_CPU1_CPU0_P0P1_DN<20>")
	)
	(segment
		(start 108.018326 -211.782406)
		(end 107.976162 -211.82457)
		(width 0.0889)
		(layer "In6.Cu")
		(net "UPI_CPU1_CPU0_P0P1_DN<20>")
	)
	(segment
		(start 108.764324 -209.406998)
		(end 108.850938 -209.592418)
		(width 0.14732)
		(layer "In6.Cu")
		(net "UPI_CPU1_CPU0_P0P1_DN<20>")
	)
	(segment
		(start 175.86579 -158.548832)
		(end 175.667416 -158.611062)
		(width 0.14732)
		(layer "In6.Cu")
		(net "UPI_CPU1_CPU0_P0P1_DN<20>")
	)
	(segment
		(start 329.195176 -169.71772)
		(end 328.996802 -169.779442)
		(width 0.14732)
		(layer "In6.Cu")
		(net "UPI_CPU1_CPU0_P0P1_DN<20>")
	)
	(segment
		(start 234.540044 -155.753308)
		(end 197.577964 -165.282372)
		(width 0.14732)
		(layer "In6.Cu")
		(net "UPI_CPU1_CPU0_P0P1_DN<20>")
	)
	(segment
		(start 161.013902 -158.319724)
		(end 160.965896 -158.522162)
		(width 0.14732)
		(layer "In6.Cu")
		(net "UPI_CPU1_CPU0_P0P1_DN<20>")
	)
	(segment
		(start 107.752134 -214.22487)
		(end 107.721908 -214.321644)
		(width 0.0889)
		(layer "In6.Cu")
		(net "UPI_CPU1_CPU0_P0P1_DN<20>")
	)
	(segment
		(start 110.374938 -205.409546)
		(end 110.18901 -205.49616)
		(width 0.14732)
		(layer "In6.Cu")
		(net "UPI_CPU1_CPU0_P0P1_DN<20>")
	)
	(segment
		(start 108.187744 -210.989164)
		(end 108.018326 -211.454238)
		(width 0.14732)
		(layer "In6.Cu")
		(net "UPI_CPU1_CPU0_P0P1_DN<20>")
	)
	(segment
		(start 157.019752 -160.953958)
		(end 157.905704 -162.391598)
		(width 0.14732)
		(layer "In6.Cu")
		(net "UPI_CPU1_CPU0_P0P1_DN<20>")
	)
	(segment
		(start 157.108398 -163.244276)
		(end 156.685234 -163.143692)
		(width 0.14732)
		(layer "In6.Cu")
		(net "UPI_CPU1_CPU0_P0P1_DN<20>")
	)
	(segment
		(start 331.769974 -171.068746)
		(end 331.247242 -170.794426)
		(width 0.14732)
		(layer "In6.Cu")
		(net "UPI_CPU1_CPU0_P0P1_DN<20>")
	)
	(segment
		(start 348.82328 -178.859688)
		(end 336.618834 -175.210978)
		(width 0.14732)
		(layer "In6.Cu")
		(net "UPI_CPU1_CPU0_P0P1_DN<20>")
	)
	(segment
		(start 194.785234 -165.633908)
		(end 189.4078 -165.633908)
		(width 0.14732)
		(layer "In6.Cu")
		(net "UPI_CPU1_CPU0_P0P1_DN<20>")
	)
	(segment
		(start 331.048868 -170.856148)
		(end 330.602844 -171.706286)
		(width 0.14732)
		(layer "In6.Cu")
		(net "UPI_CPU1_CPU0_P0P1_DN<20>")
	)
	(segment
		(start 109.076236 -208.97469)
		(end 108.890308 -209.06105)
		(width 0.14732)
		(layer "In6.Cu")
		(net "UPI_CPU1_CPU0_P0P1_DN<20>")
	)
	(segment
		(start 333.884016 -172.343826)
		(end 333.82204 -172.145452)
		(width 0.14732)
		(layer "In6.Cu")
		(net "UPI_CPU1_CPU0_P0P1_DN<20>")
	)
	(segment
		(start 302.493172 -165.259004)
		(end 280.167842 -165.644068)
		(width 0.14732)
		(layer "In6.Cu")
		(net "UPI_CPU1_CPU0_P0P1_DN<20>")
	)
	(segment
		(start 237.671356 -155.753308)
		(end 234.540044 -155.753308)
		(width 0.14732)
		(layer "In6.Cu")
		(net "UPI_CPU1_CPU0_P0P1_DN<20>")
	)
	(segment
		(start 107.976162 -213.93023)
		(end 107.976416 -213.929468)
		(width 0.0889)
		(layer "In6.Cu")
		(net "UPI_CPU1_CPU0_P0P1_DN<20>")
	)
	(segment
		(start 167.0939 -155.072588)
		(end 165.22446 -155.725368)
		(width 0.14732)
		(layer "In6.Cu")
		(net "UPI_CPU1_CPU0_P0P1_DN<20>")
	)
	(segment
		(start 333.100934 -171.932854)
		(end 332.65491 -172.782992)
		(width 0.14732)
		(layer "In6.Cu")
		(net "UPI_CPU1_CPU0_P0P1_DN<20>")
	)
	(segment
		(start 108.539026 -210.025234)
		(end 108.413042 -210.371182)
		(width 0.14732)
		(layer "In6.Cu")
		(net "UPI_CPU1_CPU0_P0P1_DN<20>")
	)
	(segment
		(start 314.688728 -165.507924)
		(end 302.493172 -165.259004)
		(width 0.14732)
		(layer "In6.Cu")
		(net "UPI_CPU1_CPU0_P0P1_DN<20>")
	)
	(segment
		(start 334.706976 -173.859698)
		(end 334.291178 -173.989492)
		(width 0.14732)
		(layer "In6.Cu")
		(net "UPI_CPU1_CPU0_P0P1_DN<20>")
	)
	(segment
		(start 333.567786 -173.609762)
		(end 333.437992 -173.193964)
		(width 0.14732)
		(layer "In6.Cu")
		(net "UPI_CPU1_CPU0_P0P1_DN<20>")
	)
	(segment
		(start 109.20222 -208.628234)
		(end 109.076236 -208.97469)
		(width 0.14732)
		(layer "In6.Cu")
		(net "UPI_CPU1_CPU0_P0P1_DN<20>")
	)
	(segment
		(start 158.96971 -162.433254)
		(end 157.772354 -160.490154)
		(width 0.14732)
		(layer "In6.Cu")
		(net "UPI_CPU1_CPU0_P0P1_DN<20>")
	)
	(arc
		(start 107.976416 -213.929468)
		(mid 107.969258 -213.949028)
		(end 107.96143 -213.96833)
		(width 0.0889)
		(layer "In6.Cu")
		(net "UPI_CPU1_CPU0_P0P1_DN<20>")
	)
	(arc
		(start 107.96143 -213.96833)
		(mid 107.874879 -214.111364)
		(end 107.752134 -214.22487)
		(width 0.0889)
		(layer "In6.Cu")
		(net "UPI_CPU1_CPU0_P0P1_DN<20>")
	)
	(segment
		(start 378.774198 -205.205076)
		(end 378.774198 -202.487022)
		(width 0.13208)
		(layer "F.Cu")
		(net "UPI_CPU1_CPU0_P0P1_DN<1>")
	)
	(segment
		(start 381.665734 -215.972644)
		(end 381.760984 -215.972644)
		(width 0.0889)
		(layer "F.Cu")
		(net "UPI_CPU1_CPU0_P0P1_DN<1>")
	)
	(segment
		(start 374.053862 -167.525954)
		(end 373.907304 -166.977568)
		(width 0.13208)
		(layer "F.Cu")
		(net "UPI_CPU1_CPU0_P0P1_DN<1>")
	)
	(segment
		(start 383.66192 -195.103496)
		(end 388.113016 -192.129156)
		(width 0.13208)
		(layer "F.Cu")
		(net "UPI_CPU1_CPU0_P0P1_DN<1>")
	)
	(segment
		(start 378.808488 -205.894178)
		(end 378.808488 -205.261464)
		(width 0.0889)
		(layer "F.Cu")
		(net "UPI_CPU1_CPU0_P0P1_DN<1>")
	)
	(segment
		(start 382.510284 -215.23325)
		(end 382.510284 -214.68842)
		(width 0.0889)
		(layer "F.Cu")
		(net "UPI_CPU1_CPU0_P0P1_DN<1>")
	)
	(segment
		(start 385.23291 -178.240182)
		(end 377.574048 -170.58132)
		(width 0.13208)
		(layer "F.Cu")
		(net "UPI_CPU1_CPU0_P0P1_DN<1>")
	)
	(segment
		(start 377.574048 -170.58132)
		(end 375.600468 -168.963086)
		(width 0.13208)
		(layer "F.Cu")
		(net "UPI_CPU1_CPU0_P0P1_DN<1>")
	)
	(segment
		(start 374.053862 -167.526462)
		(end 374.053862 -167.525954)
		(width 0.13208)
		(layer "F.Cu")
		(net "UPI_CPU1_CPU0_P0P1_DN<1>")
	)
	(segment
		(start 382.510538 -211.895182)
		(end 381.706374 -209.954368)
		(width 0.0889)
		(layer "F.Cu")
		(net "UPI_CPU1_CPU0_P0P1_DN<1>")
	)
	(segment
		(start 379.157484 -200.67397)
		(end 379.910848 -198.854822)
		(width 0.13208)
		(layer "F.Cu")
		(net "UPI_CPU1_CPU0_P0P1_DN<1>")
	)
	(segment
		(start 375.600468 -168.963086)
		(end 375.14276 -168.791382)
		(width 0.13208)
		(layer "F.Cu")
		(net "UPI_CPU1_CPU0_P0P1_DN<1>")
	)
	(segment
		(start 379.113288 -200.780396)
		(end 379.157484 -200.67397)
		(width 0.13208)
		(layer "F.Cu")
		(net "UPI_CPU1_CPU0_P0P1_DN<1>")
	)
	(segment
		(start 389.124698 -187.63615)
		(end 385.23291 -178.240182)
		(width 0.13208)
		(layer "F.Cu")
		(net "UPI_CPU1_CPU0_P0P1_DN<1>")
	)
	(segment
		(start 90.024712 -214.622888)
		(end 90.024458 -214.622634)
		(width 0.13208)
		(layer "F.Cu")
		(net "UPI_CPU1_CPU0_P0P1_DN<1>")
	)
	(segment
		(start 379.630686 -207.87868)
		(end 378.808488 -205.894178)
		(width 0.0889)
		(layer "F.Cu")
		(net "UPI_CPU1_CPU0_P0P1_DN<1>")
	)
	(segment
		(start 382.31318 -215.488012)
		(end 382.395222 -215.437974)
		(width 0.0889)
		(layer "F.Cu")
		(net "UPI_CPU1_CPU0_P0P1_DN<1>")
	)
	(segment
		(start 382.510284 -214.68842)
		(end 382.510538 -214.688166)
		(width 0.0889)
		(layer "F.Cu")
		(net "UPI_CPU1_CPU0_P0P1_DN<1>")
	)
	(segment
		(start 90.024712 -215.158574)
		(end 90.024712 -214.622888)
		(width 0.13208)
		(layer "F.Cu")
		(net "UPI_CPU1_CPU0_P0P1_DN<1>")
	)
	(segment
		(start 381.706374 -209.954368)
		(end 379.630686 -207.87868)
		(width 0.0889)
		(layer "F.Cu")
		(net "UPI_CPU1_CPU0_P0P1_DN<1>")
	)
	(segment
		(start 373.857266 -167.856408)
		(end 374.053862 -167.526462)
		(width 0.13208)
		(layer "F.Cu")
		(net "UPI_CPU1_CPU0_P0P1_DN<1>")
	)
	(segment
		(start 379.910848 -198.854822)
		(end 383.66192 -195.103496)
		(width 0.13208)
		(layer "F.Cu")
		(net "UPI_CPU1_CPU0_P0P1_DN<1>")
	)
	(segment
		(start 389.124698 -191.117474)
		(end 389.124698 -187.63615)
		(width 0.13208)
		(layer "F.Cu")
		(net "UPI_CPU1_CPU0_P0P1_DN<1>")
	)
	(segment
		(start 382.510538 -214.688166)
		(end 382.510538 -211.895182)
		(width 0.0889)
		(layer "F.Cu")
		(net "UPI_CPU1_CPU0_P0P1_DN<1>")
	)
	(segment
		(start 373.844312 -168.258998)
		(end 373.857266 -167.856408)
		(width 0.13208)
		(layer "F.Cu")
		(net "UPI_CPU1_CPU0_P0P1_DN<1>")
	)
	(segment
		(start 378.808488 -205.261464)
		(end 378.774198 -205.227174)
		(width 0.0889)
		(layer "F.Cu")
		(net "UPI_CPU1_CPU0_P0P1_DN<1>")
	)
	(segment
		(start 378.774198 -205.227174)
		(end 378.774198 -205.205076)
		(width 0.0889)
		(layer "F.Cu")
		(net "UPI_CPU1_CPU0_P0P1_DN<1>")
	)
	(segment
		(start 375.14276 -168.791382)
		(end 374.034304 -168.510204)
		(width 0.13208)
		(layer "F.Cu")
		(net "UPI_CPU1_CPU0_P0P1_DN<1>")
	)
	(segment
		(start 374.034304 -168.510204)
		(end 373.844312 -168.258998)
		(width 0.13208)
		(layer "F.Cu")
		(net "UPI_CPU1_CPU0_P0P1_DN<1>")
	)
	(segment
		(start 378.774198 -202.487022)
		(end 379.113288 -200.780396)
		(width 0.13208)
		(layer "F.Cu")
		(net "UPI_CPU1_CPU0_P0P1_DN<1>")
	)
	(segment
		(start 388.113016 -192.129156)
		(end 389.124698 -191.117474)
		(width 0.13208)
		(layer "F.Cu")
		(net "UPI_CPU1_CPU0_P0P1_DN<1>")
	)
	(arc
		(start 382.395222 -215.437974)
		(mid 382.479517 -215.350648)
		(end 382.510284 -215.23325)
		(width 0.0889)
		(layer "F.Cu")
		(net "UPI_CPU1_CPU0_P0P1_DN<1>")
	)
	(arc
		(start 382.082294 -215.754712)
		(mid 382.087848 -215.744282)
		(end 382.092962 -215.73363)
		(width 0.0889)
		(layer "F.Cu")
		(net "UPI_CPU1_CPU0_P0P1_DN<1>")
	)
	(arc
		(start 382.092962 -215.73363)
		(mid 382.135082 -215.659039)
		(end 382.187958 -215.591644)
		(width 0.0889)
		(layer "F.Cu")
		(net "UPI_CPU1_CPU0_P0P1_DN<1>")
	)
	(arc
		(start 382.016 -215.833452)
		(mid 382.052756 -215.79712)
		(end 382.082294 -215.754712)
		(width 0.0889)
		(layer "F.Cu")
		(net "UPI_CPU1_CPU0_P0P1_DN<1>")
	)
	(arc
		(start 382.221232 -215.557862)
		(mid 382.265461 -215.52064)
		(end 382.31318 -215.488012)
		(width 0.0889)
		(layer "F.Cu")
		(net "UPI_CPU1_CPU0_P0P1_DN<1>")
	)
	(arc
		(start 381.84709 -215.949784)
		(mid 381.933839 -215.894948)
		(end 382.016 -215.833452)
		(width 0.0889)
		(layer "F.Cu")
		(net "UPI_CPU1_CPU0_P0P1_DN<1>")
	)
	(arc
		(start 382.187958 -215.591644)
		(mid 382.204241 -215.574404)
		(end 382.221232 -215.557862)
		(width 0.0889)
		(layer "F.Cu")
		(net "UPI_CPU1_CPU0_P0P1_DN<1>")
	)
	(arc
		(start 381.760984 -215.972644)
		(mid 381.80555 -215.966905)
		(end 381.84709 -215.949784)
		(width 0.0889)
		(layer "F.Cu")
		(net "UPI_CPU1_CPU0_P0P1_DN<1>")
	)
	(segment
		(start 90.010488 -213.066884)
		(end 90.010488 -212.800184)
		(width 0.0889)
		(layer "In6.Cu")
		(net "UPI_CPU1_CPU0_P0P1_DN<1>")
	)
	(segment
		(start 337.574128 -145.370296)
		(end 337.77555 -145.332704)
		(width 0.14732)
		(layer "In6.Cu")
		(net "UPI_CPU1_CPU0_P0P1_DN<1>")
	)
	(segment
		(start 88.016334 -208.596738)
		(end 87.75573 -208.336134)
		(width 0.14732)
		(layer "In6.Cu")
		(net "UPI_CPU1_CPU0_P0P1_DN<1>")
	)
	(segment
		(start 336.424016 -144.581118)
		(end 336.7278 -144.789652)
		(width 0.14732)
		(layer "In6.Cu")
		(net "UPI_CPU1_CPU0_P0P1_DN<1>")
	)
	(segment
		(start 89.649808 -214.205566)
		(end 90.010488 -213.844886)
		(width 0.0889)
		(layer "In6.Cu")
		(net "UPI_CPU1_CPU0_P0P1_DN<1>")
	)
	(segment
		(start 312.024776 -138.977878)
		(end 312.03646 -138.978132)
		(width 0.14732)
		(layer "In6.Cu")
		(net "UPI_CPU1_CPU0_P0P1_DN<1>")
	)
	(segment
		(start 90.052652 -211.762848)
		(end 90.052652 -211.74075)
		(width 0.0889)
		(layer "In6.Cu")
		(net "UPI_CPU1_CPU0_P0P1_DN<1>")
	)
	(segment
		(start 90.052652 -210.83778)
		(end 89.46769 -210.252818)
		(width 0.14732)
		(layer "In6.Cu")
		(net "UPI_CPU1_CPU0_P0P1_DN<1>")
	)
	(segment
		(start 271.344136 -137.26795)
		(end 312.024776 -138.977878)
		(width 0.14732)
		(layer "In6.Cu")
		(net "UPI_CPU1_CPU0_P0P1_DN<1>")
	)
	(segment
		(start 86.63432 -207.419448)
		(end 86.347808 -206.80299)
		(width 0.14732)
		(layer "In6.Cu")
		(net "UPI_CPU1_CPU0_P0P1_DN<1>")
	)
	(segment
		(start 368.77117 -167.82669)
		(end 369.474242 -168.1226)
		(width 0.14732)
		(layer "In6.Cu")
		(net "UPI_CPU1_CPU0_P0P1_DN<1>")
	)
	(segment
		(start 369.77447 -168.09847)
		(end 370.073936 -168.074848)
		(width 0.14732)
		(layer "In6.Cu")
		(net "UPI_CPU1_CPU0_P0P1_DN<1>")
	)
	(segment
		(start 335.881726 -144.208754)
		(end 336.082894 -144.171416)
		(width 0.14732)
		(layer "In6.Cu")
		(net "UPI_CPU1_CPU0_P0P1_DN<1>")
	)
	(segment
		(start 90.109802 -212.70087)
		(end 90.109802 -212.43417)
		(width 0.0889)
		(layer "In6.Cu")
		(net "UPI_CPU1_CPU0_P0P1_DN<1>")
	)
	(segment
		(start 370.073936 -168.074848)
		(end 372.11 -166.81196)
		(width 0.14732)
		(layer "In6.Cu")
		(net "UPI_CPU1_CPU0_P0P1_DN<1>")
	)
	(segment
		(start 372.11 -166.81196)
		(end 372.308882 -166.858696)
		(width 0.14732)
		(layer "In6.Cu")
		(net "UPI_CPU1_CPU0_P0P1_DN<1>")
	)
	(segment
		(start 123.559316 -162.425888)
		(end 160.011872 -140.004546)
		(width 0.14732)
		(layer "In6.Cu")
		(net "UPI_CPU1_CPU0_P0P1_DN<1>")
	)
	(segment
		(start 338.356448 -145.73123)
		(end 338.356448 -145.730976)
		(width 0.14732)
		(layer "In6.Cu")
		(net "UPI_CPU1_CPU0_P0P1_DN<1>")
	)
	(segment
		(start 336.7278 -144.789652)
		(end 336.929222 -144.75206)
		(width 0.14732)
		(layer "In6.Cu")
		(net "UPI_CPU1_CPU0_P0P1_DN<1>")
	)
	(segment
		(start 160.011872 -140.004546)
		(end 169.571416 -136.731756)
		(width 0.14732)
		(layer "In6.Cu")
		(net "UPI_CPU1_CPU0_P0P1_DN<1>")
	)
	(segment
		(start 88.016334 -208.801462)
		(end 88.016334 -208.596738)
		(width 0.14732)
		(layer "In6.Cu")
		(net "UPI_CPU1_CPU0_P0P1_DN<1>")
	)
	(segment
		(start 336.929222 -144.75206)
		(end 337.232752 -144.96034)
		(width 0.14732)
		(layer "In6.Cu")
		(net "UPI_CPU1_CPU0_P0P1_DN<1>")
	)
	(segment
		(start 87.75573 -208.336134)
		(end 87.551006 -208.336134)
		(width 0.14732)
		(layer "In6.Cu")
		(net "UPI_CPU1_CPU0_P0P1_DN<1>")
	)
	(segment
		(start 374.2436 -165.989508)
		(end 374.55348 -166.299388)
		(width 0.14732)
		(layer "In6.Cu")
		(net "UPI_CPU1_CPU0_P0P1_DN<1>")
	)
	(segment
		(start 89.46769 -210.048094)
		(end 89.207086 -209.78749)
		(width 0.14732)
		(layer "In6.Cu")
		(net "UPI_CPU1_CPU0_P0P1_DN<1>")
	)
	(segment
		(start 89.867994 -214.893652)
		(end 89.789762 -214.91448)
		(width 0.0889)
		(layer "In6.Cu")
		(net "UPI_CPU1_CPU0_P0P1_DN<1>")
	)
	(segment
		(start 90.010488 -213.532212)
		(end 90.109802 -213.432898)
		(width 0.0889)
		(layer "In6.Cu")
		(net "UPI_CPU1_CPU0_P0P1_DN<1>")
	)
	(segment
		(start 336.386424 -144.379696)
		(end 336.424016 -144.581118)
		(width 0.14732)
		(layer "In6.Cu")
		(net "UPI_CPU1_CPU0_P0P1_DN<1>")
	)
	(segment
		(start 86.347808 -206.80299)
		(end 86.3219 -205.989428)
		(width 0.14732)
		(layer "In6.Cu")
		(net "UPI_CPU1_CPU0_P0P1_DN<1>")
	)
	(segment
		(start 88.481408 -209.061812)
		(end 88.276684 -209.061812)
		(width 0.14732)
		(layer "In6.Cu")
		(net "UPI_CPU1_CPU0_P0P1_DN<1>")
	)
	(segment
		(start 372.308882 -166.858696)
		(end 372.622318 -166.66464)
		(width 0.14732)
		(layer "In6.Cu")
		(net "UPI_CPU1_CPU0_P0P1_DN<1>")
	)
	(segment
		(start 333.893414 -142.669006)
		(end 334.668114 -143.200628)
		(width 0.14732)
		(layer "In6.Cu")
		(net "UPI_CPU1_CPU0_P0P1_DN<1>")
	)
	(segment
		(start 373.43588 -165.989508)
		(end 374.2436 -165.989508)
		(width 0.14732)
		(layer "In6.Cu")
		(net "UPI_CPU1_CPU0_P0P1_DN<1>")
	)
	(segment
		(start 86.53272 -204.826108)
		(end 96.543876 -192.929002)
		(width 0.14732)
		(layer "In6.Cu")
		(net "UPI_CPU1_CPU0_P0P1_DN<1>")
	)
	(segment
		(start 90.109802 -212.43417)
		(end 90.010488 -212.334856)
		(width 0.0889)
		(layer "In6.Cu")
		(net "UPI_CPU1_CPU0_P0P1_DN<1>")
	)
	(segment
		(start 89.649808 -214.622634)
		(end 89.649808 -214.205566)
		(width 0.0889)
		(layer "In6.Cu")
		(net "UPI_CPU1_CPU0_P0P1_DN<1>")
	)
	(segment
		(start 335.54035 -143.798798)
		(end 335.577688 -144.000474)
		(width 0.14732)
		(layer "In6.Cu")
		(net "UPI_CPU1_CPU0_P0P1_DN<1>")
	)
	(segment
		(start 88.742012 -209.52714)
		(end 88.742012 -209.322416)
		(width 0.14732)
		(layer "In6.Cu")
		(net "UPI_CPU1_CPU0_P0P1_DN<1>")
	)
	(segment
		(start 98.85807 -186.774836)
		(end 102.545388 -182.185818)
		(width 0.14732)
		(layer "In6.Cu")
		(net "UPI_CPU1_CPU0_P0P1_DN<1>")
	)
	(segment
		(start 96.543876 -192.929002)
		(end 98.85807 -186.774836)
		(width 0.14732)
		(layer "In6.Cu")
		(net "UPI_CPU1_CPU0_P0P1_DN<1>")
	)
	(segment
		(start 169.571416 -136.731756)
		(end 238.60252 -137.865612)
		(width 0.14732)
		(layer "In6.Cu")
		(net "UPI_CPU1_CPU0_P0P1_DN<1>")
	)
	(segment
		(start 338.356448 -145.730976)
		(end 360.011726 -160.587182)
		(width 0.14732)
		(layer "In6.Cu")
		(net "UPI_CPU1_CPU0_P0P1_DN<1>")
	)
	(segment
		(start 88.742012 -209.322416)
		(end 88.481408 -209.061812)
		(width 0.14732)
		(layer "In6.Cu")
		(net "UPI_CPU1_CPU0_P0P1_DN<1>")
	)
	(segment
		(start 90.010488 -213.844886)
		(end 90.010488 -213.532212)
		(width 0.0889)
		(layer "In6.Cu")
		(net "UPI_CPU1_CPU0_P0P1_DN<1>")
	)
	(segment
		(start 337.77555 -145.332704)
		(end 338.356448 -145.73123)
		(width 0.14732)
		(layer "In6.Cu")
		(net "UPI_CPU1_CPU0_P0P1_DN<1>")
	)
	(segment
		(start 369.774216 -168.098724)
		(end 369.77447 -168.09847)
		(width 0.14732)
		(layer "In6.Cu")
		(net "UPI_CPU1_CPU0_P0P1_DN<1>")
	)
	(segment
		(start 374.552972 -166.65194)
		(end 374.448832 -166.83228)
		(width 0.14732)
		(layer "In6.Cu")
		(net "UPI_CPU1_CPU0_P0P1_DN<1>")
	)
	(segment
		(start 337.270344 -145.161762)
		(end 337.574128 -145.370296)
		(width 0.14732)
		(layer "In6.Cu")
		(net "UPI_CPU1_CPU0_P0P1_DN<1>")
	)
	(segment
		(start 372.622318 -166.66464)
		(end 372.669054 -166.46525)
		(width 0.14732)
		(layer "In6.Cu")
		(net "UPI_CPU1_CPU0_P0P1_DN<1>")
	)
	(segment
		(start 89.46769 -210.252818)
		(end 89.46769 -210.048094)
		(width 0.14732)
		(layer "In6.Cu")
		(net "UPI_CPU1_CPU0_P0P1_DN<1>")
	)
	(segment
		(start 90.109802 -213.432898)
		(end 90.109802 -213.166198)
		(width 0.0889)
		(layer "In6.Cu")
		(net "UPI_CPU1_CPU0_P0P1_DN<1>")
	)
	(segment
		(start 312.03646 -138.978132)
		(end 319.49898 -138.978132)
		(width 0.14732)
		(layer "In6.Cu")
		(net "UPI_CPU1_CPU0_P0P1_DN<1>")
	)
	(segment
		(start 334.705706 -143.40205)
		(end 335.00949 -143.61033)
		(width 0.14732)
		(layer "In6.Cu")
		(net "UPI_CPU1_CPU0_P0P1_DN<1>")
	)
	(segment
		(start 89.207086 -209.78749)
		(end 89.002362 -209.78749)
		(width 0.14732)
		(layer "In6.Cu")
		(net "UPI_CPU1_CPU0_P0P1_DN<1>")
	)
	(segment
		(start 87.551006 -208.336134)
		(end 86.63432 -207.419448)
		(width 0.14732)
		(layer "In6.Cu")
		(net "UPI_CPU1_CPU0_P0P1_DN<1>")
	)
	(segment
		(start 90.052652 -211.74075)
		(end 90.052652 -210.83778)
		(width 0.14732)
		(layer "In6.Cu")
		(net "UPI_CPU1_CPU0_P0P1_DN<1>")
	)
	(segment
		(start 90.024458 -214.622634)
		(end 89.867994 -214.893652)
		(width 0.0889)
		(layer "In6.Cu")
		(net "UPI_CPU1_CPU0_P0P1_DN<1>")
	)
	(segment
		(start 335.210912 -143.572992)
		(end 335.54035 -143.798798)
		(width 0.14732)
		(layer "In6.Cu")
		(net "UPI_CPU1_CPU0_P0P1_DN<1>")
	)
	(segment
		(start 372.669054 -166.46525)
		(end 373.43588 -165.989508)
		(width 0.14732)
		(layer "In6.Cu")
		(net "UPI_CPU1_CPU0_P0P1_DN<1>")
	)
	(segment
		(start 374.55348 -166.299388)
		(end 374.55348 -166.651432)
		(width 0.14732)
		(layer "In6.Cu")
		(net "UPI_CPU1_CPU0_P0P1_DN<1>")
	)
	(segment
		(start 374.55348 -166.651432)
		(end 374.552972 -166.65194)
		(width 0.14732)
		(layer "In6.Cu")
		(net "UPI_CPU1_CPU0_P0P1_DN<1>")
	)
	(segment
		(start 90.010488 -211.805012)
		(end 90.052652 -211.762848)
		(width 0.0889)
		(layer "In6.Cu")
		(net "UPI_CPU1_CPU0_P0P1_DN<1>")
	)
	(segment
		(start 90.010488 -212.800184)
		(end 90.109802 -212.70087)
		(width 0.0889)
		(layer "In6.Cu")
		(net "UPI_CPU1_CPU0_P0P1_DN<1>")
	)
	(segment
		(start 336.082894 -144.171416)
		(end 336.386424 -144.379696)
		(width 0.14732)
		(layer "In6.Cu")
		(net "UPI_CPU1_CPU0_P0P1_DN<1>")
	)
	(segment
		(start 89.002362 -209.78749)
		(end 88.742012 -209.52714)
		(width 0.14732)
		(layer "In6.Cu")
		(net "UPI_CPU1_CPU0_P0P1_DN<1>")
	)
	(segment
		(start 335.00949 -143.61033)
		(end 335.210912 -143.572992)
		(width 0.14732)
		(layer "In6.Cu")
		(net "UPI_CPU1_CPU0_P0P1_DN<1>")
	)
	(segment
		(start 335.577688 -144.000474)
		(end 335.881726 -144.208754)
		(width 0.14732)
		(layer "In6.Cu")
		(net "UPI_CPU1_CPU0_P0P1_DN<1>")
	)
	(segment
		(start 88.276684 -209.061812)
		(end 88.016334 -208.801462)
		(width 0.14732)
		(layer "In6.Cu")
		(net "UPI_CPU1_CPU0_P0P1_DN<1>")
	)
	(segment
		(start 238.60252 -137.865612)
		(end 271.344136 -137.26795)
		(width 0.14732)
		(layer "In6.Cu")
		(net "UPI_CPU1_CPU0_P0P1_DN<1>")
	)
	(segment
		(start 102.545388 -182.185818)
		(end 123.559316 -162.425888)
		(width 0.14732)
		(layer "In6.Cu")
		(net "UPI_CPU1_CPU0_P0P1_DN<1>")
	)
	(segment
		(start 334.668114 -143.200628)
		(end 334.705706 -143.40205)
		(width 0.14732)
		(layer "In6.Cu")
		(net "UPI_CPU1_CPU0_P0P1_DN<1>")
	)
	(segment
		(start 369.474242 -168.1226)
		(end 369.774216 -168.098724)
		(width 0.14732)
		(layer "In6.Cu")
		(net "UPI_CPU1_CPU0_P0P1_DN<1>")
	)
	(segment
		(start 374.448832 -166.83228)
		(end 373.907304 -166.977568)
		(width 0.14732)
		(layer "In6.Cu")
		(net "UPI_CPU1_CPU0_P0P1_DN<1>")
	)
	(segment
		(start 337.232752 -144.96034)
		(end 337.270344 -145.161762)
		(width 0.14732)
		(layer "In6.Cu")
		(net "UPI_CPU1_CPU0_P0P1_DN<1>")
	)
	(segment
		(start 90.010488 -212.334856)
		(end 90.010488 -211.805012)
		(width 0.0889)
		(layer "In6.Cu")
		(net "UPI_CPU1_CPU0_P0P1_DN<1>")
	)
	(segment
		(start 319.49898 -138.978132)
		(end 333.893414 -142.669006)
		(width 0.14732)
		(layer "In6.Cu")
		(net "UPI_CPU1_CPU0_P0P1_DN<1>")
	)
	(segment
		(start 360.011726 -160.587182)
		(end 368.77117 -167.82669)
		(width 0.14732)
		(layer "In6.Cu")
		(net "UPI_CPU1_CPU0_P0P1_DN<1>")
	)
	(segment
		(start 90.109802 -213.166198)
		(end 90.010488 -213.066884)
		(width 0.0889)
		(layer "In6.Cu")
		(net "UPI_CPU1_CPU0_P0P1_DN<1>")
	)
	(segment
		(start 86.3219 -205.989428)
		(end 86.53272 -204.826108)
		(width 0.14732)
		(layer "In6.Cu")
		(net "UPI_CPU1_CPU0_P0P1_DN<1>")
	)
	(arc
		(start 89.789762 -214.91448)
		(mid 89.686617 -214.784455)
		(end 89.649808 -214.622634)
		(width 0.0889)
		(layer "In6.Cu")
		(net "UPI_CPU1_CPU0_P0P1_DN<1>")
	)
	(segment
		(start 355.487478 -205.227174)
		(end 355.487478 -205.205076)
		(width 0.0889)
		(layer "F.Cu")
		(net "UPI_CPU1_CPU0_P0P1_DN<19>")
	)
	(segment
		(start 356.496366 -194.04711)
		(end 356.543864 -193.808858)
		(width 0.13208)
		(layer "F.Cu")
		(net "UPI_CPU1_CPU0_P0P1_DN<19>")
	)
	(segment
		(start 358.789478 -185.979308)
		(end 358.060244 -184.21858)
		(width 0.13208)
		(layer "F.Cu")
		(net "UPI_CPU1_CPU0_P0P1_DN<19>")
	)
	(segment
		(start 106.941112 -214.622888)
		(end 106.940858 -214.622634)
		(width 0.13208)
		(layer "F.Cu")
		(net "UPI_CPU1_CPU0_P0P1_DN<19>")
	)
	(segment
		(start 358.789478 -188.386974)
		(end 358.789478 -185.979308)
		(width 0.13208)
		(layer "F.Cu")
		(net "UPI_CPU1_CPU0_P0P1_DN<19>")
	)
	(segment
		(start 357.566722 -191.33947)
		(end 358.789478 -188.386974)
		(width 0.13208)
		(layer "F.Cu")
		(net "UPI_CPU1_CPU0_P0P1_DN<19>")
	)
	(segment
		(start 106.941112 -215.158574)
		(end 106.941112 -214.622888)
		(width 0.13208)
		(layer "F.Cu")
		(net "UPI_CPU1_CPU0_P0P1_DN<19>")
	)
	(segment
		(start 355.029008 -181.187344)
		(end 354.386134 -180.921406)
		(width 0.13208)
		(layer "F.Cu")
		(net "UPI_CPU1_CPU0_P0P1_DN<19>")
	)
	(segment
		(start 365.063786 -214.889588)
		(end 365.088932 -214.796878)
		(width 0.0889)
		(layer "F.Cu")
		(net "UPI_CPU1_CPU0_P0P1_DN<19>")
	)
	(segment
		(start 355.487478 -205.205076)
		(end 355.487478 -199.120506)
		(width 0.13208)
		(layer "F.Cu")
		(net "UPI_CPU1_CPU0_P0P1_DN<19>")
	)
	(segment
		(start 363.179106 -211.15782)
		(end 359.329482 -209.563208)
		(width 0.0889)
		(layer "F.Cu")
		(net "UPI_CPU1_CPU0_P0P1_DN<19>")
	)
	(segment
		(start 353.952302 -180.607208)
		(end 353.789742 -180.674518)
		(width 0.13208)
		(layer "F.Cu")
		(net "UPI_CPU1_CPU0_P0P1_DN<19>")
	)
	(segment
		(start 354.318824 -180.758592)
		(end 353.952302 -180.607208)
		(width 0.13208)
		(layer "F.Cu")
		(net "UPI_CPU1_CPU0_P0P1_DN<19>")
	)
	(segment
		(start 353.32162 -180.034184)
		(end 353.874324 -179.884832)
		(width 0.13208)
		(layer "F.Cu")
		(net "UPI_CPU1_CPU0_P0P1_DN<19>")
	)
	(segment
		(start 355.452934 -205.68666)
		(end 355.452934 -205.261718)
		(width 0.0889)
		(layer "F.Cu")
		(net "UPI_CPU1_CPU0_P0P1_DN<19>")
	)
	(segment
		(start 356.543864 -193.808858)
		(end 357.566722 -191.33947)
		(width 0.13208)
		(layer "F.Cu")
		(net "UPI_CPU1_CPU0_P0P1_DN<19>")
	)
	(segment
		(start 353.262946 -180.362352)
		(end 353.23907 -180.176932)
		(width 0.13208)
		(layer "F.Cu")
		(net "UPI_CPU1_CPU0_P0P1_DN<19>")
	)
	(segment
		(start 355.452934 -205.261718)
		(end 355.487478 -205.227174)
		(width 0.0889)
		(layer "F.Cu")
		(net "UPI_CPU1_CPU0_P0P1_DN<19>")
	)
	(segment
		(start 354.386134 -180.921406)
		(end 354.318824 -180.758592)
		(width 0.13208)
		(layer "F.Cu")
		(net "UPI_CPU1_CPU0_P0P1_DN<19>")
	)
	(segment
		(start 353.789742 -180.674518)
		(end 353.423728 -180.523134)
		(width 0.13208)
		(layer "F.Cu")
		(net "UPI_CPU1_CPU0_P0P1_DN<19>")
	)
	(segment
		(start 353.423728 -180.523134)
		(end 353.262946 -180.362352)
		(width 0.13208)
		(layer "F.Cu")
		(net "UPI_CPU1_CPU0_P0P1_DN<19>")
	)
	(segment
		(start 355.487478 -199.120506)
		(end 356.496366 -194.04711)
		(width 0.13208)
		(layer "F.Cu")
		(net "UPI_CPU1_CPU0_P0P1_DN<19>")
	)
	(segment
		(start 358.060244 -184.21858)
		(end 355.029008 -181.187344)
		(width 0.13208)
		(layer "F.Cu")
		(net "UPI_CPU1_CPU0_P0P1_DN<19>")
	)
	(segment
		(start 365.314484 -214.344758)
		(end 365.314484 -213.293452)
		(width 0.0889)
		(layer "F.Cu")
		(net "UPI_CPU1_CPU0_P0P1_DN<19>")
	)
	(segment
		(start 353.23907 -180.176932)
		(end 353.321112 -180.034946)
		(width 0.13208)
		(layer "F.Cu")
		(net "UPI_CPU1_CPU0_P0P1_DN<19>")
	)
	(segment
		(start 359.329482 -209.563208)
		(end 355.452934 -205.68666)
		(width 0.0889)
		(layer "F.Cu")
		(net "UPI_CPU1_CPU0_P0P1_DN<19>")
	)
	(segment
		(start 365.21898 -215.158574)
		(end 365.063786 -214.889588)
		(width 0.0889)
		(layer "F.Cu")
		(net "UPI_CPU1_CPU0_P0P1_DN<19>")
	)
	(segment
		(start 365.314484 -213.293452)
		(end 363.179106 -211.15782)
		(width 0.0889)
		(layer "F.Cu")
		(net "UPI_CPU1_CPU0_P0P1_DN<19>")
	)
	(segment
		(start 353.321112 -180.034946)
		(end 353.32162 -180.034184)
		(width 0.13208)
		(layer "F.Cu")
		(net "UPI_CPU1_CPU0_P0P1_DN<19>")
	)
	(arc
		(start 365.088932 -214.796878)
		(mid 365.097632 -214.790229)
		(end 365.106204 -214.783416)
		(width 0.0889)
		(layer "F.Cu")
		(net "UPI_CPU1_CPU0_P0P1_DN<19>")
	)
	(arc
		(start 365.106204 -214.783416)
		(mid 365.259833 -214.587592)
		(end 365.314484 -214.344758)
		(width 0.0889)
		(layer "F.Cu")
		(net "UPI_CPU1_CPU0_P0P1_DN<19>")
	)
	(segment
		(start 305.808126 -162.105594)
		(end 305.658266 -162.249104)
		(width 0.14732)
		(layer "In6.Cu")
		(net "UPI_CPU1_CPU0_P0P1_DN<19>")
	)
	(segment
		(start 305.304952 -164.481256)
		(end 304.487834 -164.463984)
		(width 0.14732)
		(layer "In6.Cu")
		(net "UPI_CPU1_CPU0_P0P1_DN<19>")
	)
	(segment
		(start 348.991428 -178.021742)
		(end 343.923874 -176.510442)
		(width 0.14732)
		(layer "In6.Cu")
		(net "UPI_CPU1_CPU0_P0P1_DN<19>")
	)
	(segment
		(start 313.45378 -164.341048)
		(end 313.493658 -162.410902)
		(width 0.14732)
		(layer "In6.Cu")
		(net "UPI_CPU1_CPU0_P0P1_DN<19>")
	)
	(segment
		(start 311.032652 -162.21329)
		(end 310.442102 -162.201098)
		(width 0.14732)
		(layer "In6.Cu")
		(net "UPI_CPU1_CPU0_P0P1_DN<19>")
	)
	(segment
		(start 309.12181 -164.559488)
		(end 308.820058 -164.24529)
		(width 0.14732)
		(layer "In6.Cu")
		(net "UPI_CPU1_CPU0_P0P1_DN<19>")
	)
	(segment
		(start 107.473242 -210.505548)
		(end 107.287568 -210.591908)
		(width 0.14732)
		(layer "In6.Cu")
		(net "UPI_CPU1_CPU0_P0P1_DN<19>")
	)
	(segment
		(start 311.438798 -164.60724)
		(end 311.137046 -164.293042)
		(width 0.14732)
		(layer "In6.Cu")
		(net "UPI_CPU1_CPU0_P0P1_DN<19>")
	)
	(segment
		(start 311.17667 -162.36315)
		(end 311.032652 -162.21329)
		(width 0.14732)
		(layer "In6.Cu")
		(net "UPI_CPU1_CPU0_P0P1_DN<19>")
	)
	(segment
		(start 107.07878 -211.164932)
		(end 107.07878 -211.77123)
		(width 0.14732)
		(layer "In6.Cu")
		(net "UPI_CPU1_CPU0_P0P1_DN<19>")
	)
	(segment
		(start 350.753934 -178.313334)
		(end 349.75419 -178.095656)
		(width 0.14732)
		(layer "In6.Cu")
		(net "UPI_CPU1_CPU0_P0P1_DN<19>")
	)
	(segment
		(start 308.125114 -162.153346)
		(end 307.975254 -162.296856)
		(width 0.14732)
		(layer "In6.Cu")
		(net "UPI_CPU1_CPU0_P0P1_DN<19>")
	)
	(segment
		(start 304.186082 -164.149786)
		(end 304.225706 -162.219894)
		(width 0.14732)
		(layer "In6.Cu")
		(net "UPI_CPU1_CPU0_P0P1_DN<19>")
	)
	(segment
		(start 107.036616 -213.051644)
		(end 107.13593 -213.150958)
		(width 0.0889)
		(layer "In6.Cu")
		(net "UPI_CPU1_CPU0_P0P1_DN<19>")
	)
	(segment
		(start 107.07878 -211.77123)
		(end 107.07878 -211.793328)
		(width 0.0889)
		(layer "In6.Cu")
		(net "UPI_CPU1_CPU0_P0P1_DN<19>")
	)
	(segment
		(start 351.089214 -178.569366)
		(end 350.753934 -178.313334)
		(width 0.14732)
		(layer "In6.Cu")
		(net "UPI_CPU1_CPU0_P0P1_DN<19>")
	)
	(segment
		(start 307.975254 -162.296856)
		(end 307.935884 -164.227002)
		(width 0.14732)
		(layer "In6.Cu")
		(net "UPI_CPU1_CPU0_P0P1_DN<19>")
	)
	(segment
		(start 306.542694 -162.267646)
		(end 306.398676 -162.117786)
		(width 0.14732)
		(layer "In6.Cu")
		(net "UPI_CPU1_CPU0_P0P1_DN<19>")
	)
	(segment
		(start 349.75419 -178.095656)
		(end 348.991428 -178.021742)
		(width 0.14732)
		(layer "In6.Cu")
		(net "UPI_CPU1_CPU0_P0P1_DN<19>")
	)
	(segment
		(start 106.784394 -214.893652)
		(end 106.940858 -214.622634)
		(width 0.0889)
		(layer "In6.Cu")
		(net "UPI_CPU1_CPU0_P0P1_DN<19>")
	)
	(segment
		(start 189.843664 -164.800788)
		(end 172.191426 -155.565602)
		(width 0.14732)
		(layer "In6.Cu")
		(net "UPI_CPU1_CPU0_P0P1_DN<19>")
	)
	(segment
		(start 310.292242 -162.344608)
		(end 310.252872 -164.274754)
		(width 0.14732)
		(layer "In6.Cu")
		(net "UPI_CPU1_CPU0_P0P1_DN<19>")
	)
	(segment
		(start 304.225706 -162.219894)
		(end 304.081688 -162.070034)
		(width 0.14732)
		(layer "In6.Cu")
		(net "UPI_CPU1_CPU0_P0P1_DN<19>")
	)
	(segment
		(start 305.658266 -162.249104)
		(end 305.618896 -164.17925)
		(width 0.14732)
		(layer "In6.Cu")
		(net "UPI_CPU1_CPU0_P0P1_DN<19>")
	)
	(segment
		(start 107.59948 -210.159092)
		(end 107.473242 -210.505548)
		(width 0.14732)
		(layer "In6.Cu")
		(net "UPI_CPU1_CPU0_P0P1_DN<19>")
	)
	(segment
		(start 312.60923 -162.39236)
		(end 312.56986 -164.322506)
		(width 0.14732)
		(layer "In6.Cu")
		(net "UPI_CPU1_CPU0_P0P1_DN<19>")
	)
	(segment
		(start 276.255226 -164.803328)
		(end 237.77702 -154.920188)
		(width 0.14732)
		(layer "In6.Cu")
		(net "UPI_CPU1_CPU0_P0P1_DN<19>")
	)
	(segment
		(start 351.835212 -180.030882)
		(end 351.089214 -178.569366)
		(width 0.14732)
		(layer "In6.Cu")
		(net "UPI_CPU1_CPU0_P0P1_DN<19>")
	)
	(segment
		(start 313.755786 -164.654738)
		(end 313.45378 -164.341048)
		(width 0.14732)
		(layer "In6.Cu")
		(net "UPI_CPU1_CPU0_P0P1_DN<19>")
	)
	(segment
		(start 308.859682 -162.315398)
		(end 308.715664 -162.165538)
		(width 0.14732)
		(layer "In6.Cu")
		(net "UPI_CPU1_CPU0_P0P1_DN<19>")
	)
	(segment
		(start 303.341278 -162.201352)
		(end 303.301654 -164.130482)
		(width 0.14732)
		(layer "In6.Cu")
		(net "UPI_CPU1_CPU0_P0P1_DN<19>")
	)
	(segment
		(start 237.77702 -154.920188)
		(end 234.434126 -154.920188)
		(width 0.14732)
		(layer "In6.Cu")
		(net "UPI_CPU1_CPU0_P0P1_DN<19>")
	)
	(segment
		(start 329.009756 -168.684194)
		(end 314.812426 -164.676836)
		(width 0.14732)
		(layer "In6.Cu")
		(net "UPI_CPU1_CPU0_P0P1_DN<19>")
	)
	(segment
		(start 194.73291 -164.800788)
		(end 189.843664 -164.800788)
		(width 0.14732)
		(layer "In6.Cu")
		(net "UPI_CPU1_CPU0_P0P1_DN<19>")
	)
	(segment
		(start 353.333812 -180.029612)
		(end 353.333304 -180.030374)
		(width 0.14732)
		(layer "In6.Cu")
		(net "UPI_CPU1_CPU0_P0P1_DN<19>")
	)
	(segment
		(start 312.56986 -164.322506)
		(end 312.255916 -164.624512)
		(width 0.14732)
		(layer "In6.Cu")
		(net "UPI_CPU1_CPU0_P0P1_DN<19>")
	)
	(segment
		(start 107.287568 -210.591908)
		(end 107.07878 -211.164932)
		(width 0.14732)
		(layer "In6.Cu")
		(net "UPI_CPU1_CPU0_P0P1_DN<19>")
	)
	(segment
		(start 107.13593 -212.41893)
		(end 107.13593 -212.68563)
		(width 0.0889)
		(layer "In6.Cu")
		(net "UPI_CPU1_CPU0_P0P1_DN<19>")
	)
	(segment
		(start 303.301654 -164.130482)
		(end 302.988472 -164.433758)
		(width 0.14732)
		(layer "In6.Cu")
		(net "UPI_CPU1_CPU0_P0P1_DN<19>")
	)
	(segment
		(start 302.582326 -164.427408)
		(end 302.582326 -164.427154)
		(width 0.14732)
		(layer "In6.Cu")
		(net "UPI_CPU1_CPU0_P0P1_DN<19>")
	)
	(segment
		(start 311.137046 -164.293042)
		(end 311.17667 -162.36315)
		(width 0.14732)
		(layer "In6.Cu")
		(net "UPI_CPU1_CPU0_P0P1_DN<19>")
	)
	(segment
		(start 165.23081 -154.727148)
		(end 133.635242 -174.198026)
		(width 0.14732)
		(layer "In6.Cu")
		(net "UPI_CPU1_CPU0_P0P1_DN<19>")
	)
	(segment
		(start 106.566208 -214.461852)
		(end 106.566208 -214.622634)
		(width 0.0889)
		(layer "In6.Cu")
		(net "UPI_CPU1_CPU0_P0P1_DN<19>")
	)
	(segment
		(start 308.820058 -164.24529)
		(end 308.859682 -162.315398)
		(width 0.14732)
		(layer "In6.Cu")
		(net "UPI_CPU1_CPU0_P0P1_DN<19>")
	)
	(segment
		(start 107.036616 -212.319616)
		(end 107.13593 -212.41893)
		(width 0.0889)
		(layer "In6.Cu")
		(net "UPI_CPU1_CPU0_P0P1_DN<19>")
	)
	(segment
		(start 352.987864 -180.464968)
		(end 352.369374 -180.464968)
		(width 0.14732)
		(layer "In6.Cu")
		(net "UPI_CPU1_CPU0_P0P1_DN<19>")
	)
	(segment
		(start 304.081688 -162.070034)
		(end 303.491138 -162.057842)
		(width 0.14732)
		(layer "In6.Cu")
		(net "UPI_CPU1_CPU0_P0P1_DN<19>")
	)
	(segment
		(start 306.398676 -162.117786)
		(end 305.808126 -162.105594)
		(width 0.14732)
		(layer "In6.Cu")
		(net "UPI_CPU1_CPU0_P0P1_DN<19>")
	)
	(segment
		(start 352.369374 -180.464968)
		(end 351.864168 -180.087778)
		(width 0.14732)
		(layer "In6.Cu")
		(net "UPI_CPU1_CPU0_P0P1_DN<19>")
	)
	(segment
		(start 280.844244 -164.803328)
		(end 276.255226 -164.803328)
		(width 0.14732)
		(layer "In6.Cu")
		(net "UPI_CPU1_CPU0_P0P1_DN<19>")
	)
	(segment
		(start 343.923874 -176.510442)
		(end 329.009756 -168.684194)
		(width 0.14732)
		(layer "In6.Cu")
		(net "UPI_CPU1_CPU0_P0P1_DN<19>")
	)
	(segment
		(start 304.487834 -164.463984)
		(end 304.186082 -164.149786)
		(width 0.14732)
		(layer "In6.Cu")
		(net "UPI_CPU1_CPU0_P0P1_DN<19>")
	)
	(segment
		(start 309.938928 -164.57676)
		(end 309.12181 -164.559488)
		(width 0.14732)
		(layer "In6.Cu")
		(net "UPI_CPU1_CPU0_P0P1_DN<19>")
	)
	(segment
		(start 314.812426 -164.676836)
		(end 313.755786 -164.654738)
		(width 0.14732)
		(layer "In6.Cu")
		(net "UPI_CPU1_CPU0_P0P1_DN<19>")
	)
	(segment
		(start 234.434126 -154.920188)
		(end 197.421246 -164.462206)
		(width 0.14732)
		(layer "In6.Cu")
		(net "UPI_CPU1_CPU0_P0P1_DN<19>")
	)
	(segment
		(start 302.583088 -164.427154)
		(end 302.582326 -164.427408)
		(width 0.14732)
		(layer "In6.Cu")
		(net "UPI_CPU1_CPU0_P0P1_DN<19>")
	)
	(segment
		(start 353.874324 -179.884832)
		(end 353.333812 -180.029612)
		(width 0.14732)
		(layer "In6.Cu")
		(net "UPI_CPU1_CPU0_P0P1_DN<19>")
	)
	(segment
		(start 172.191426 -155.565602)
		(end 169.421302 -154.194002)
		(width 0.14732)
		(layer "In6.Cu")
		(net "UPI_CPU1_CPU0_P0P1_DN<19>")
	)
	(segment
		(start 308.715664 -162.165538)
		(end 308.125114 -162.153346)
		(width 0.14732)
		(layer "In6.Cu")
		(net "UPI_CPU1_CPU0_P0P1_DN<19>")
	)
	(segment
		(start 107.13593 -213.417658)
		(end 107.036616 -213.516972)
		(width 0.0889)
		(layer "In6.Cu")
		(net "UPI_CPU1_CPU0_P0P1_DN<19>")
	)
	(segment
		(start 107.13593 -212.68563)
		(end 107.036616 -212.784944)
		(width 0.0889)
		(layer "In6.Cu")
		(net "UPI_CPU1_CPU0_P0P1_DN<19>")
	)
	(segment
		(start 107.512866 -209.973672)
		(end 107.59948 -210.159092)
		(width 0.14732)
		(layer "In6.Cu")
		(net "UPI_CPU1_CPU0_P0P1_DN<19>")
	)
	(segment
		(start 310.442102 -162.201098)
		(end 310.292242 -162.344608)
		(width 0.14732)
		(layer "In6.Cu")
		(net "UPI_CPU1_CPU0_P0P1_DN<19>")
	)
	(segment
		(start 107.036616 -211.835492)
		(end 107.036616 -212.319616)
		(width 0.0889)
		(layer "In6.Cu")
		(net "UPI_CPU1_CPU0_P0P1_DN<19>")
	)
	(segment
		(start 197.421246 -164.462206)
		(end 194.73291 -164.800788)
		(width 0.14732)
		(layer "In6.Cu")
		(net "UPI_CPU1_CPU0_P0P1_DN<19>")
	)
	(segment
		(start 106.706162 -214.91448)
		(end 106.784394 -214.893652)
		(width 0.0889)
		(layer "In6.Cu")
		(net "UPI_CPU1_CPU0_P0P1_DN<19>")
	)
	(segment
		(start 107.036616 -212.784944)
		(end 107.036616 -213.051644)
		(width 0.0889)
		(layer "In6.Cu")
		(net "UPI_CPU1_CPU0_P0P1_DN<19>")
	)
	(segment
		(start 133.635242 -174.198026)
		(end 121.271538 -185.825638)
		(width 0.14732)
		(layer "In6.Cu")
		(net "UPI_CPU1_CPU0_P0P1_DN<19>")
	)
	(segment
		(start 306.804822 -164.511736)
		(end 306.50307 -164.197538)
		(width 0.14732)
		(layer "In6.Cu")
		(net "UPI_CPU1_CPU0_P0P1_DN<19>")
	)
	(segment
		(start 310.252872 -164.274754)
		(end 309.938928 -164.57676)
		(width 0.14732)
		(layer "In6.Cu")
		(net "UPI_CPU1_CPU0_P0P1_DN<19>")
	)
	(segment
		(start 313.493658 -162.410902)
		(end 313.34964 -162.261042)
		(width 0.14732)
		(layer "In6.Cu")
		(net "UPI_CPU1_CPU0_P0P1_DN<19>")
	)
	(segment
		(start 107.036616 -213.516972)
		(end 107.036616 -213.929468)
		(width 0.0889)
		(layer "In6.Cu")
		(net "UPI_CPU1_CPU0_P0P1_DN<19>")
	)
	(segment
		(start 107.07878 -211.793328)
		(end 107.036616 -211.835492)
		(width 0.0889)
		(layer "In6.Cu")
		(net "UPI_CPU1_CPU0_P0P1_DN<19>")
	)
	(segment
		(start 307.62194 -164.529008)
		(end 306.804822 -164.511736)
		(width 0.14732)
		(layer "In6.Cu")
		(net "UPI_CPU1_CPU0_P0P1_DN<19>")
	)
	(segment
		(start 302.582326 -164.427154)
		(end 280.844244 -164.803328)
		(width 0.14732)
		(layer "In6.Cu")
		(net "UPI_CPU1_CPU0_P0P1_DN<19>")
	)
	(segment
		(start 351.864168 -180.087778)
		(end 351.834958 -180.030882)
		(width 0.14732)
		(layer "In6.Cu")
		(net "UPI_CPU1_CPU0_P0P1_DN<19>")
	)
	(segment
		(start 307.935884 -164.227002)
		(end 307.62194 -164.529008)
		(width 0.14732)
		(layer "In6.Cu")
		(net "UPI_CPU1_CPU0_P0P1_DN<19>")
	)
	(segment
		(start 312.75909 -162.24885)
		(end 312.60923 -162.39236)
		(width 0.14732)
		(layer "In6.Cu")
		(net "UPI_CPU1_CPU0_P0P1_DN<19>")
	)
	(segment
		(start 306.50307 -164.197538)
		(end 306.542694 -162.267646)
		(width 0.14732)
		(layer "In6.Cu")
		(net "UPI_CPU1_CPU0_P0P1_DN<19>")
	)
	(segment
		(start 305.618896 -164.17925)
		(end 305.304952 -164.481256)
		(width 0.14732)
		(layer "In6.Cu")
		(net "UPI_CPU1_CPU0_P0P1_DN<19>")
	)
	(segment
		(start 302.988472 -164.433758)
		(end 302.583088 -164.427154)
		(width 0.14732)
		(layer "In6.Cu")
		(net "UPI_CPU1_CPU0_P0P1_DN<19>")
	)
	(segment
		(start 169.421302 -154.194002)
		(end 166.94658 -154.127962)
		(width 0.14732)
		(layer "In6.Cu")
		(net "UPI_CPU1_CPU0_P0P1_DN<19>")
	)
	(segment
		(start 353.333304 -180.030374)
		(end 353.21113 -180.241956)
		(width 0.14732)
		(layer "In6.Cu")
		(net "UPI_CPU1_CPU0_P0P1_DN<19>")
	)
	(segment
		(start 112.10798 -197.359778)
		(end 107.512866 -209.973672)
		(width 0.14732)
		(layer "In6.Cu")
		(net "UPI_CPU1_CPU0_P0P1_DN<19>")
	)
	(segment
		(start 303.491138 -162.057842)
		(end 303.341278 -162.201352)
		(width 0.14732)
		(layer "In6.Cu")
		(net "UPI_CPU1_CPU0_P0P1_DN<19>")
	)
	(segment
		(start 107.13593 -213.150958)
		(end 107.13593 -213.417658)
		(width 0.0889)
		(layer "In6.Cu")
		(net "UPI_CPU1_CPU0_P0P1_DN<19>")
	)
	(segment
		(start 351.834958 -180.030882)
		(end 351.835212 -180.030882)
		(width 0.14732)
		(layer "In6.Cu")
		(net "UPI_CPU1_CPU0_P0P1_DN<19>")
	)
	(segment
		(start 166.94658 -154.127962)
		(end 165.23081 -154.727148)
		(width 0.14732)
		(layer "In6.Cu")
		(net "UPI_CPU1_CPU0_P0P1_DN<19>")
	)
	(segment
		(start 312.255916 -164.624512)
		(end 311.438798 -164.60724)
		(width 0.14732)
		(layer "In6.Cu")
		(net "UPI_CPU1_CPU0_P0P1_DN<19>")
	)
	(segment
		(start 121.271538 -185.825638)
		(end 112.10798 -197.359778)
		(width 0.14732)
		(layer "In6.Cu")
		(net "UPI_CPU1_CPU0_P0P1_DN<19>")
	)
	(segment
		(start 353.21113 -180.241956)
		(end 352.987864 -180.464968)
		(width 0.14732)
		(layer "In6.Cu")
		(net "UPI_CPU1_CPU0_P0P1_DN<19>")
	)
	(segment
		(start 313.34964 -162.261042)
		(end 312.75909 -162.24885)
		(width 0.14732)
		(layer "In6.Cu")
		(net "UPI_CPU1_CPU0_P0P1_DN<19>")
	)
	(arc
		(start 106.750612 -214.261954)
		(mid 106.641216 -214.346051)
		(end 106.566208 -214.461852)
		(width 0.0889)
		(layer "In6.Cu")
		(net "UPI_CPU1_CPU0_P0P1_DN<19>")
	)
	(arc
		(start 106.566208 -214.622634)
		(mid 106.603068 -214.784431)
		(end 106.706162 -214.91448)
		(width 0.0889)
		(layer "In6.Cu")
		(net "UPI_CPU1_CPU0_P0P1_DN<19>")
	)
	(arc
		(start 107.036616 -213.929468)
		(mid 107.029338 -213.949159)
		(end 107.021376 -213.968584)
		(width 0.0889)
		(layer "In6.Cu")
		(net "UPI_CPU1_CPU0_P0P1_DN<19>")
	)
	(arc
		(start 107.021376 -213.968584)
		(mid 106.91117 -214.138501)
		(end 106.750612 -214.261954)
		(width 0.0889)
		(layer "In6.Cu")
		(net "UPI_CPU1_CPU0_P0P1_DN<19>")
	)
	(segment
		(start 358.977692 -183.654446)
		(end 355.409246 -180.086)
		(width 0.13208)
		(layer "F.Cu")
		(net "UPI_CPU1_CPU0_P0P1_DN<18>")
	)
	(segment
		(start 357.578152 -194.04711)
		(end 358.699816 -191.33947)
		(width 0.13208)
		(layer "F.Cu")
		(net "UPI_CPU1_CPU0_P0P1_DN<18>")
	)
	(segment
		(start 365.844328 -215.703658)
		(end 365.819182 -215.610694)
		(width 0.0889)
		(layer "F.Cu")
		(net "UPI_CPU1_CPU0_P0P1_DN<18>")
	)
	(segment
		(start 354.952808 -179.805584)
		(end 354.952808 -179.629562)
		(width 0.13208)
		(layer "F.Cu")
		(net "UPI_CPU1_CPU0_P0P1_DN<18>")
	)
	(segment
		(start 363.40669 -210.675982)
		(end 359.989882 -209.261202)
		(width 0.0889)
		(layer "F.Cu")
		(net "UPI_CPU1_CPU0_P0P1_DN<18>")
	)
	(segment
		(start 356.536498 -199.262746)
		(end 356.541324 -199.25792)
		(width 0.13208)
		(layer "F.Cu")
		(net "UPI_CPU1_CPU0_P0P1_DN<18>")
	)
	(segment
		(start 354.579428 -179.256436)
		(end 353.858576 -178.774852)
		(width 0.13208)
		(layer "F.Cu")
		(net "UPI_CPU1_CPU0_P0P1_DN<18>")
	)
	(segment
		(start 106.001312 -215.158574)
		(end 106.001312 -214.622888)
		(width 0.13208)
		(layer "F.Cu")
		(net "UPI_CPU1_CPU0_P0P1_DN<18>")
	)
	(segment
		(start 366.074198 -214.325708)
		(end 366.074198 -213.34349)
		(width 0.0889)
		(layer "F.Cu")
		(net "UPI_CPU1_CPU0_P0P1_DN<18>")
	)
	(segment
		(start 355.233224 -180.086)
		(end 354.952808 -179.805584)
		(width 0.13208)
		(layer "F.Cu")
		(net "UPI_CPU1_CPU0_P0P1_DN<18>")
	)
	(segment
		(start 349.724726 -176.861216)
		(end 349.165672 -176.709832)
		(width 0.13208)
		(layer "F.Cu")
		(net "UPI_CPU1_CPU0_P0P1_DN<18>")
	)
	(segment
		(start 356.536498 -205.227174)
		(end 356.536498 -205.205076)
		(width 0.0889)
		(layer "F.Cu")
		(net "UPI_CPU1_CPU0_P0P1_DN<18>")
	)
	(segment
		(start 366.074198 -213.34349)
		(end 363.40669 -210.675982)
		(width 0.0889)
		(layer "F.Cu")
		(net "UPI_CPU1_CPU0_P0P1_DN<18>")
	)
	(segment
		(start 357.576628 -194.050666)
		(end 357.578152 -194.04711)
		(width 0.13208)
		(layer "F.Cu")
		(net "UPI_CPU1_CPU0_P0P1_DN<18>")
	)
	(segment
		(start 353.858576 -178.774852)
		(end 349.910908 -177.140108)
		(width 0.13208)
		(layer "F.Cu")
		(net "UPI_CPU1_CPU0_P0P1_DN<18>")
	)
	(segment
		(start 349.910908 -177.140108)
		(end 349.724726 -176.861216)
		(width 0.13208)
		(layer "F.Cu")
		(net "UPI_CPU1_CPU0_P0P1_DN<18>")
	)
	(segment
		(start 356.536498 -205.205076)
		(end 356.536498 -199.262746)
		(width 0.13208)
		(layer "F.Cu")
		(net "UPI_CPU1_CPU0_P0P1_DN<18>")
	)
	(segment
		(start 365.888778 -214.661496)
		(end 365.889032 -214.661496)
		(width 0.0889)
		(layer "F.Cu")
		(net "UPI_CPU1_CPU0_P0P1_DN<18>")
	)
	(segment
		(start 359.907078 -185.898282)
		(end 358.977692 -183.654446)
		(width 0.13208)
		(layer "F.Cu")
		(net "UPI_CPU1_CPU0_P0P1_DN<18>")
	)
	(segment
		(start 354.952808 -179.629562)
		(end 354.579428 -179.256436)
		(width 0.13208)
		(layer "F.Cu")
		(net "UPI_CPU1_CPU0_P0P1_DN<18>")
	)
	(segment
		(start 359.907078 -188.424566)
		(end 359.907078 -185.898282)
		(width 0.13208)
		(layer "F.Cu")
		(net "UPI_CPU1_CPU0_P0P1_DN<18>")
	)
	(segment
		(start 365.59363 -215.172798)
		(end 365.59363 -215.158066)
		(width 0.0889)
		(layer "F.Cu")
		(net "UPI_CPU1_CPU0_P0P1_DN<18>")
	)
	(segment
		(start 355.409246 -180.086)
		(end 355.233224 -180.086)
		(width 0.13208)
		(layer "F.Cu")
		(net "UPI_CPU1_CPU0_P0P1_DN<18>")
	)
	(segment
		(start 356.570788 -205.261464)
		(end 356.536498 -205.227174)
		(width 0.0889)
		(layer "F.Cu")
		(net "UPI_CPU1_CPU0_P0P1_DN<18>")
	)
	(segment
		(start 359.989882 -209.261202)
		(end 356.570788 -205.841854)
		(width 0.0889)
		(layer "F.Cu")
		(net "UPI_CPU1_CPU0_P0P1_DN<18>")
	)
	(segment
		(start 106.001312 -214.622888)
		(end 106.001058 -214.622634)
		(width 0.13208)
		(layer "F.Cu")
		(net "UPI_CPU1_CPU0_P0P1_DN<18>")
	)
	(segment
		(start 358.699816 -191.33947)
		(end 359.907078 -188.424566)
		(width 0.13208)
		(layer "F.Cu")
		(net "UPI_CPU1_CPU0_P0P1_DN<18>")
	)
	(segment
		(start 365.689134 -215.972644)
		(end 365.844328 -215.703658)
		(width 0.0889)
		(layer "F.Cu")
		(net "UPI_CPU1_CPU0_P0P1_DN<18>")
	)
	(segment
		(start 356.570788 -205.841854)
		(end 356.570788 -205.261464)
		(width 0.0889)
		(layer "F.Cu")
		(net "UPI_CPU1_CPU0_P0P1_DN<18>")
	)
	(segment
		(start 356.541324 -199.25792)
		(end 357.576628 -194.050666)
		(width 0.13208)
		(layer "F.Cu")
		(net "UPI_CPU1_CPU0_P0P1_DN<18>")
	)
	(arc
		(start 365.819182 -215.610694)
		(mid 365.810608 -215.604045)
		(end 365.802164 -215.597232)
		(width 0.0889)
		(layer "F.Cu")
		(net "UPI_CPU1_CPU0_P0P1_DN<18>")
	)
	(arc
		(start 365.889032 -214.661496)
		(mid 366.024854 -214.517442)
		(end 366.074198 -214.325708)
		(width 0.0889)
		(layer "F.Cu")
		(net "UPI_CPU1_CPU0_P0P1_DN<18>")
	)
	(arc
		(start 365.59363 -215.158066)
		(mid 365.672978 -214.869221)
		(end 365.888778 -214.661496)
		(width 0.0889)
		(layer "F.Cu")
		(net "UPI_CPU1_CPU0_P0P1_DN<18>")
	)
	(arc
		(start 365.802164 -215.597232)
		(mid 365.651386 -215.407867)
		(end 365.59363 -215.172798)
		(width 0.0889)
		(layer "F.Cu")
		(net "UPI_CPU1_CPU0_P0P1_DN<18>")
	)
	(segment
		(start 194.680332 -163.965128)
		(end 197.26402 -163.6395)
		(width 0.14732)
		(layer "In6.Cu")
		(net "UPI_CPU1_CPU0_P0P1_DN<18>")
	)
	(segment
		(start 337.74253 -169.681398)
		(end 338.382356 -169.079926)
		(width 0.14732)
		(layer "In6.Cu")
		(net "UPI_CPU1_CPU0_P0P1_DN<18>")
	)
	(segment
		(start 112.634014 -195.359274)
		(end 112.906048 -195.017136)
		(width 0.14732)
		(layer "In6.Cu")
		(net "UPI_CPU1_CPU0_P0P1_DN<18>")
	)
	(segment
		(start 347.376496 -175.54575)
		(end 347.490796 -175.715676)
		(width 0.14732)
		(layer "In6.Cu")
		(net "UPI_CPU1_CPU0_P0P1_DN<18>")
	)
	(segment
		(start 111.484664 -196.60997)
		(end 111.767366 -196.254116)
		(width 0.14732)
		(layer "In6.Cu")
		(net "UPI_CPU1_CPU0_P0P1_DN<18>")
	)
	(segment
		(start 172.617892 -154.72791)
		(end 190.273432 -163.965128)
		(width 0.14732)
		(layer "In6.Cu")
		(net "UPI_CPU1_CPU0_P0P1_DN<18>")
	)
	(segment
		(start 338.987892 -169.72407)
		(end 338.348066 -170.325542)
		(width 0.14732)
		(layer "In6.Cu")
		(net "UPI_CPU1_CPU0_P0P1_DN<18>")
	)
	(segment
		(start 330.957428 -162.913568)
		(end 331.39253 -162.92703)
		(width 0.14732)
		(layer "In6.Cu")
		(net "UPI_CPU1_CPU0_P0P1_DN<18>")
	)
	(segment
		(start 112.886236 -194.845686)
		(end 113.180368 -194.475354)
		(width 0.14732)
		(layer "In6.Cu")
		(net "UPI_CPU1_CPU0_P0P1_DN<18>")
	)
	(segment
		(start 336.15503 -167.992806)
		(end 336.794856 -167.391334)
		(width 0.14732)
		(layer "In6.Cu")
		(net "UPI_CPU1_CPU0_P0P1_DN<18>")
	)
	(segment
		(start 166.799514 -153.184098)
		(end 169.653204 -153.260044)
		(width 0.14732)
		(layer "In6.Cu")
		(net "UPI_CPU1_CPU0_P0P1_DN<18>")
	)
	(segment
		(start 332.637892 -162.969702)
		(end 331.998066 -163.571174)
		(width 0.14732)
		(layer "In6.Cu")
		(net "UPI_CPU1_CPU0_P0P1_DN<18>")
	)
	(segment
		(start 334.231742 -164.450268)
		(end 334.225392 -164.658294)
		(width 0.14732)
		(layer "In6.Cu")
		(net "UPI_CPU1_CPU0_P0P1_DN<18>")
	)
	(segment
		(start 169.653204 -153.260044)
		(end 172.617892 -154.72791)
		(width 0.14732)
		(layer "In6.Cu")
		(net "UPI_CPU1_CPU0_P0P1_DN<18>")
	)
	(segment
		(start 114.994436 -192.191386)
		(end 120.052846 -185.824368)
		(width 0.14732)
		(layer "In6.Cu")
		(net "UPI_CPU1_CPU0_P0P1_DN<18>")
	)
	(segment
		(start 332.032356 -162.325558)
		(end 332.240382 -162.331908)
		(width 0.14732)
		(layer "In6.Cu")
		(net "UPI_CPU1_CPU0_P0P1_DN<18>")
	)
	(segment
		(start 333.619856 -164.01415)
		(end 333.827882 -164.0205)
		(width 0.14732)
		(layer "In6.Cu")
		(net "UPI_CPU1_CPU0_P0P1_DN<18>")
	)
	(segment
		(start 234.327954 -154.084528)
		(end 237.882938 -154.084528)
		(width 0.14732)
		(layer "In6.Cu")
		(net "UPI_CPU1_CPU0_P0P1_DN<18>")
	)
	(segment
		(start 133.13664 -173.519846)
		(end 165.26891 -153.718768)
		(width 0.14732)
		(layer "In6.Cu")
		(net "UPI_CPU1_CPU0_P0P1_DN<18>")
	)
	(segment
		(start 322.350384 -155.047188)
		(end 323.30898 -155.047188)
		(width 0.14732)
		(layer "In6.Cu")
		(net "UPI_CPU1_CPU0_P0P1_DN<18>")
	)
	(segment
		(start 344.505788 -174.984918)
		(end 347.376496 -175.54575)
		(width 0.14732)
		(layer "In6.Cu")
		(net "UPI_CPU1_CPU0_P0P1_DN<18>")
	)
	(segment
		(start 106.096816 -213.929468)
		(end 106.096562 -213.93023)
		(width 0.0889)
		(layer "In6.Cu")
		(net "UPI_CPU1_CPU0_P0P1_DN<18>")
	)
	(segment
		(start 348.022418 -175.671988)
		(end 348.914466 -175.846232)
		(width 0.14732)
		(layer "In6.Cu")
		(net "UPI_CPU1_CPU0_P0P1_DN<18>")
	)
	(segment
		(start 347.852492 -175.786288)
		(end 348.022418 -175.671988)
		(width 0.14732)
		(layer "In6.Cu")
		(net "UPI_CPU1_CPU0_P0P1_DN<18>")
	)
	(segment
		(start 106.138726 -211.77123)
		(end 106.138726 -211.284566)
		(width 0.14732)
		(layer "In6.Cu")
		(net "UPI_CPU1_CPU0_P0P1_DN<18>")
	)
	(segment
		(start 335.812892 -166.346886)
		(end 335.173066 -166.948358)
		(width 0.14732)
		(layer "In6.Cu")
		(net "UPI_CPU1_CPU0_P0P1_DN<18>")
	)
	(segment
		(start 336.747104 -169.071798)
		(end 337.307428 -169.667936)
		(width 0.14732)
		(layer "In6.Cu")
		(net "UPI_CPU1_CPU0_P0P1_DN<18>")
	)
	(segment
		(start 335.173066 -166.948358)
		(end 335.159604 -167.383206)
		(width 0.14732)
		(layer "In6.Cu")
		(net "UPI_CPU1_CPU0_P0P1_DN<18>")
	)
	(segment
		(start 113.875566 -193.60007)
		(end 114.047016 -193.580258)
		(width 0.14732)
		(layer "In6.Cu")
		(net "UPI_CPU1_CPU0_P0P1_DN<18>")
	)
	(segment
		(start 335.415382 -165.709092)
		(end 335.819242 -166.13886)
		(width 0.14732)
		(layer "In6.Cu")
		(net "UPI_CPU1_CPU0_P0P1_DN<18>")
	)
	(segment
		(start 114.047016 -193.580258)
		(end 114.31905 -193.23812)
		(width 0.14732)
		(layer "In6.Cu")
		(net "UPI_CPU1_CPU0_P0P1_DN<18>")
	)
	(segment
		(start 337.406742 -167.827452)
		(end 337.400392 -168.035478)
		(width 0.14732)
		(layer "In6.Cu")
		(net "UPI_CPU1_CPU0_P0P1_DN<18>")
	)
	(segment
		(start 336.794856 -167.391334)
		(end 337.002882 -167.397684)
		(width 0.14732)
		(layer "In6.Cu")
		(net "UPI_CPU1_CPU0_P0P1_DN<18>")
	)
	(segment
		(start 338.348066 -170.325542)
		(end 338.334604 -170.76039)
		(width 0.14732)
		(layer "In6.Cu")
		(net "UPI_CPU1_CPU0_P0P1_DN<18>")
	)
	(segment
		(start 331.056742 -161.073084)
		(end 331.050392 -161.28111)
		(width 0.14732)
		(layer "In6.Cu")
		(net "UPI_CPU1_CPU0_P0P1_DN<18>")
	)
	(segment
		(start 347.490796 -175.715676)
		(end 347.852492 -175.786288)
		(width 0.14732)
		(layer "In6.Cu")
		(net "UPI_CPU1_CPU0_P0P1_DN<18>")
	)
	(segment
		(start 190.273432 -163.965128)
		(end 194.680332 -163.965128)
		(width 0.14732)
		(layer "In6.Cu")
		(net "UPI_CPU1_CPU0_P0P1_DN<18>")
	)
	(segment
		(start 338.590382 -169.086276)
		(end 338.994242 -169.516044)
		(width 0.14732)
		(layer "In6.Cu")
		(net "UPI_CPU1_CPU0_P0P1_DN<18>")
	)
	(segment
		(start 113.180368 -194.475354)
		(end 113.351818 -194.455796)
		(width 0.14732)
		(layer "In6.Cu")
		(net "UPI_CPU1_CPU0_P0P1_DN<18>")
	)
	(segment
		(start 343.741248 -174.56277)
		(end 344.505788 -174.984918)
		(width 0.14732)
		(layer "In6.Cu")
		(net "UPI_CPU1_CPU0_P0P1_DN<18>")
	)
	(segment
		(start 349.238316 -176.04232)
		(end 349.31096 -176.168304)
		(width 0.14732)
		(layer "In6.Cu")
		(net "UPI_CPU1_CPU0_P0P1_DN<18>")
	)
	(segment
		(start 338.334604 -170.76039)
		(end 338.894928 -171.356528)
		(width 0.14732)
		(layer "In6.Cu")
		(net "UPI_CPU1_CPU0_P0P1_DN<18>")
	)
	(segment
		(start 334.56753 -166.304214)
		(end 335.207356 -165.702742)
		(width 0.14732)
		(layer "In6.Cu")
		(net "UPI_CPU1_CPU0_P0P1_DN<18>")
	)
	(segment
		(start 339.969856 -170.768518)
		(end 340.177882 -170.774868)
		(width 0.14732)
		(layer "In6.Cu")
		(net "UPI_CPU1_CPU0_P0P1_DN<18>")
	)
	(segment
		(start 332.644242 -162.761676)
		(end 332.637892 -162.969702)
		(width 0.14732)
		(layer "In6.Cu")
		(net "UPI_CPU1_CPU0_P0P1_DN<18>")
	)
	(segment
		(start 106.138726 -211.782406)
		(end 106.138726 -211.77123)
		(width 0.0889)
		(layer "In6.Cu")
		(net "UPI_CPU1_CPU0_P0P1_DN<18>")
	)
	(segment
		(start 279.734264 -163.975288)
		(end 322.350384 -155.047188)
		(width 0.14732)
		(layer "In6.Cu")
		(net "UPI_CPU1_CPU0_P0P1_DN<18>")
	)
	(segment
		(start 112.210596 -195.892166)
		(end 112.191038 -195.72097)
		(width 0.14732)
		(layer "In6.Cu")
		(net "UPI_CPU1_CPU0_P0P1_DN<18>")
	)
	(segment
		(start 335.719928 -167.979344)
		(end 336.15503 -167.992806)
		(width 0.14732)
		(layer "In6.Cu")
		(net "UPI_CPU1_CPU0_P0P1_DN<18>")
	)
	(segment
		(start 337.307428 -169.667936)
		(end 337.74253 -169.681398)
		(width 0.14732)
		(layer "In6.Cu")
		(net "UPI_CPU1_CPU0_P0P1_DN<18>")
	)
	(segment
		(start 335.207356 -165.702742)
		(end 335.415382 -165.709092)
		(width 0.14732)
		(layer "In6.Cu")
		(net "UPI_CPU1_CPU0_P0P1_DN<18>")
	)
	(segment
		(start 112.906048 -195.017136)
		(end 112.886236 -194.845686)
		(width 0.14732)
		(layer "In6.Cu")
		(net "UPI_CPU1_CPU0_P0P1_DN<18>")
	)
	(segment
		(start 335.159604 -167.383206)
		(end 335.719928 -167.979344)
		(width 0.14732)
		(layer "In6.Cu")
		(net "UPI_CPU1_CPU0_P0P1_DN<18>")
	)
	(segment
		(start 333.585566 -165.259766)
		(end 333.572104 -165.694614)
		(width 0.14732)
		(layer "In6.Cu")
		(net "UPI_CPU1_CPU0_P0P1_DN<18>")
	)
	(segment
		(start 325.32574 -155.555188)
		(end 327.25106 -157.025848)
		(width 0.14732)
		(layer "In6.Cu")
		(net "UPI_CPU1_CPU0_P0P1_DN<18>")
	)
	(segment
		(start 330.397104 -162.31743)
		(end 330.957428 -162.913568)
		(width 0.14732)
		(layer "In6.Cu")
		(net "UPI_CPU1_CPU0_P0P1_DN<18>")
	)
	(segment
		(start 113.60404 -193.941954)
		(end 113.875566 -193.60007)
		(width 0.14732)
		(layer "In6.Cu")
		(net "UPI_CPU1_CPU0_P0P1_DN<18>")
	)
	(segment
		(start 327.25106 -157.025848)
		(end 331.056742 -161.073084)
		(width 0.14732)
		(layer "In6.Cu")
		(net "UPI_CPU1_CPU0_P0P1_DN<18>")
	)
	(segment
		(start 338.994242 -169.516044)
		(end 338.987892 -169.72407)
		(width 0.14732)
		(layer "In6.Cu")
		(net "UPI_CPU1_CPU0_P0P1_DN<18>")
	)
	(segment
		(start 337.002882 -167.397684)
		(end 337.406742 -167.827452)
		(width 0.14732)
		(layer "In6.Cu")
		(net "UPI_CPU1_CPU0_P0P1_DN<18>")
	)
	(segment
		(start 323.30898 -155.047188)
		(end 325.32574 -155.555188)
		(width 0.14732)
		(layer "In6.Cu")
		(net "UPI_CPU1_CPU0_P0P1_DN<18>")
	)
	(segment
		(start 112.191038 -195.72097)
		(end 112.462564 -195.379086)
		(width 0.14732)
		(layer "In6.Cu")
		(net "UPI_CPU1_CPU0_P0P1_DN<18>")
	)
	(segment
		(start 338.894928 -171.356528)
		(end 339.33003 -171.36999)
		(width 0.14732)
		(layer "In6.Cu")
		(net "UPI_CPU1_CPU0_P0P1_DN<18>")
	)
	(segment
		(start 106.096562 -213.93023)
		(end 106.096562 -211.82457)
		(width 0.0889)
		(layer "In6.Cu")
		(net "UPI_CPU1_CPU0_P0P1_DN<18>")
	)
	(segment
		(start 106.096562 -211.82457)
		(end 106.138726 -211.782406)
		(width 0.0889)
		(layer "In6.Cu")
		(net "UPI_CPU1_CPU0_P0P1_DN<18>")
	)
	(segment
		(start 331.984604 -164.006022)
		(end 332.544928 -164.60216)
		(width 0.14732)
		(layer "In6.Cu")
		(net "UPI_CPU1_CPU0_P0P1_DN<18>")
	)
	(segment
		(start 114.31905 -193.23812)
		(end 114.299238 -193.06667)
		(width 0.14732)
		(layer "In6.Cu")
		(net "UPI_CPU1_CPU0_P0P1_DN<18>")
	)
	(segment
		(start 333.827882 -164.0205)
		(end 334.231742 -164.450268)
		(width 0.14732)
		(layer "In6.Cu")
		(net "UPI_CPU1_CPU0_P0P1_DN<18>")
	)
	(segment
		(start 334.225392 -164.658294)
		(end 333.585566 -165.259766)
		(width 0.14732)
		(layer "In6.Cu")
		(net "UPI_CPU1_CPU0_P0P1_DN<18>")
	)
	(segment
		(start 120.052846 -185.824368)
		(end 133.13664 -173.519846)
		(width 0.14732)
		(layer "In6.Cu")
		(net "UPI_CPU1_CPU0_P0P1_DN<18>")
	)
	(segment
		(start 114.299238 -193.06667)
		(end 114.570764 -192.724786)
		(width 0.14732)
		(layer "In6.Cu")
		(net "UPI_CPU1_CPU0_P0P1_DN<18>")
	)
	(segment
		(start 106.001058 -214.622634)
		(end 105.842308 -214.321644)
		(width 0.0889)
		(layer "In6.Cu")
		(net "UPI_CPU1_CPU0_P0P1_DN<18>")
	)
	(segment
		(start 348.914466 -175.846232)
		(end 349.238316 -176.04232)
		(width 0.14732)
		(layer "In6.Cu")
		(net "UPI_CPU1_CPU0_P0P1_DN<18>")
	)
	(segment
		(start 336.760566 -168.63695)
		(end 336.747104 -169.071798)
		(width 0.14732)
		(layer "In6.Cu")
		(net "UPI_CPU1_CPU0_P0P1_DN<18>")
	)
	(segment
		(start 114.742214 -192.705228)
		(end 115.014248 -192.362836)
		(width 0.14732)
		(layer "In6.Cu")
		(net "UPI_CPU1_CPU0_P0P1_DN<18>")
	)
	(segment
		(start 331.998066 -163.571174)
		(end 331.984604 -164.006022)
		(width 0.14732)
		(layer "In6.Cu")
		(net "UPI_CPU1_CPU0_P0P1_DN<18>")
	)
	(segment
		(start 332.544928 -164.60216)
		(end 332.98003 -164.615622)
		(width 0.14732)
		(layer "In6.Cu")
		(net "UPI_CPU1_CPU0_P0P1_DN<18>")
	)
	(segment
		(start 165.26891 -153.718768)
		(end 166.799514 -153.184098)
		(width 0.14732)
		(layer "In6.Cu")
		(net "UPI_CPU1_CPU0_P0P1_DN<18>")
	)
	(segment
		(start 337.400392 -168.035478)
		(end 336.760566 -168.63695)
		(width 0.14732)
		(layer "In6.Cu")
		(net "UPI_CPU1_CPU0_P0P1_DN<18>")
	)
	(segment
		(start 115.014248 -192.362836)
		(end 114.994436 -192.191386)
		(width 0.14732)
		(layer "In6.Cu")
		(net "UPI_CPU1_CPU0_P0P1_DN<18>")
	)
	(segment
		(start 237.882938 -154.084528)
		(end 276.390608 -163.975288)
		(width 0.14732)
		(layer "In6.Cu")
		(net "UPI_CPU1_CPU0_P0P1_DN<18>")
	)
	(segment
		(start 331.050392 -161.28111)
		(end 330.410566 -161.882582)
		(width 0.14732)
		(layer "In6.Cu")
		(net "UPI_CPU1_CPU0_P0P1_DN<18>")
	)
	(segment
		(start 335.819242 -166.13886)
		(end 335.812892 -166.346886)
		(width 0.14732)
		(layer "In6.Cu")
		(net "UPI_CPU1_CPU0_P0P1_DN<18>")
	)
	(segment
		(start 106.138726 -211.284566)
		(end 111.484664 -196.60997)
		(width 0.14732)
		(layer "In6.Cu")
		(net "UPI_CPU1_CPU0_P0P1_DN<18>")
	)
	(segment
		(start 330.410566 -161.882582)
		(end 330.397104 -162.31743)
		(width 0.14732)
		(layer "In6.Cu")
		(net "UPI_CPU1_CPU0_P0P1_DN<18>")
	)
	(segment
		(start 113.623852 -194.113404)
		(end 113.60404 -193.941954)
		(width 0.14732)
		(layer "In6.Cu")
		(net "UPI_CPU1_CPU0_P0P1_DN<18>")
	)
	(segment
		(start 197.26402 -163.6395)
		(end 234.327954 -154.084528)
		(width 0.14732)
		(layer "In6.Cu")
		(net "UPI_CPU1_CPU0_P0P1_DN<18>")
	)
	(segment
		(start 334.132428 -166.290752)
		(end 334.56753 -166.304214)
		(width 0.14732)
		(layer "In6.Cu")
		(net "UPI_CPU1_CPU0_P0P1_DN<18>")
	)
	(segment
		(start 333.572104 -165.694614)
		(end 334.132428 -166.290752)
		(width 0.14732)
		(layer "In6.Cu")
		(net "UPI_CPU1_CPU0_P0P1_DN<18>")
	)
	(segment
		(start 111.767366 -196.254116)
		(end 111.938562 -196.234558)
		(width 0.14732)
		(layer "In6.Cu")
		(net "UPI_CPU1_CPU0_P0P1_DN<18>")
	)
	(segment
		(start 105.842308 -214.321644)
		(end 105.872534 -214.22487)
		(width 0.0889)
		(layer "In6.Cu")
		(net "UPI_CPU1_CPU0_P0P1_DN<18>")
	)
	(segment
		(start 113.351818 -194.455796)
		(end 113.623852 -194.113404)
		(width 0.14732)
		(layer "In6.Cu")
		(net "UPI_CPU1_CPU0_P0P1_DN<18>")
	)
	(segment
		(start 340.177882 -170.774868)
		(end 343.741248 -174.56277)
		(width 0.14732)
		(layer "In6.Cu")
		(net "UPI_CPU1_CPU0_P0P1_DN<18>")
	)
	(segment
		(start 349.31096 -176.168304)
		(end 349.165672 -176.709832)
		(width 0.14732)
		(layer "In6.Cu")
		(net "UPI_CPU1_CPU0_P0P1_DN<18>")
	)
	(segment
		(start 276.390608 -163.975288)
		(end 279.734264 -163.975288)
		(width 0.14732)
		(layer "In6.Cu")
		(net "UPI_CPU1_CPU0_P0P1_DN<18>")
	)
	(segment
		(start 331.39253 -162.92703)
		(end 332.032356 -162.325558)
		(width 0.14732)
		(layer "In6.Cu")
		(net "UPI_CPU1_CPU0_P0P1_DN<18>")
	)
	(segment
		(start 332.98003 -164.615622)
		(end 333.619856 -164.01415)
		(width 0.14732)
		(layer "In6.Cu")
		(net "UPI_CPU1_CPU0_P0P1_DN<18>")
	)
	(segment
		(start 338.382356 -169.079926)
		(end 338.590382 -169.086276)
		(width 0.14732)
		(layer "In6.Cu")
		(net "UPI_CPU1_CPU0_P0P1_DN<18>")
	)
	(segment
		(start 332.240382 -162.331908)
		(end 332.644242 -162.761676)
		(width 0.14732)
		(layer "In6.Cu")
		(net "UPI_CPU1_CPU0_P0P1_DN<18>")
	)
	(segment
		(start 114.570764 -192.724786)
		(end 114.742214 -192.705228)
		(width 0.14732)
		(layer "In6.Cu")
		(net "UPI_CPU1_CPU0_P0P1_DN<18>")
	)
	(segment
		(start 111.938562 -196.234558)
		(end 112.210596 -195.892166)
		(width 0.14732)
		(layer "In6.Cu")
		(net "UPI_CPU1_CPU0_P0P1_DN<18>")
	)
	(segment
		(start 112.462564 -195.379086)
		(end 112.634014 -195.359274)
		(width 0.14732)
		(layer "In6.Cu")
		(net "UPI_CPU1_CPU0_P0P1_DN<18>")
	)
	(segment
		(start 339.33003 -171.36999)
		(end 339.969856 -170.768518)
		(width 0.14732)
		(layer "In6.Cu")
		(net "UPI_CPU1_CPU0_P0P1_DN<18>")
	)
	(arc
		(start 106.08183 -213.96833)
		(mid 106.089665 -213.949031)
		(end 106.096816 -213.929468)
		(width 0.0889)
		(layer "In6.Cu")
		(net "UPI_CPU1_CPU0_P0P1_DN<18>")
	)
	(arc
		(start 105.872534 -214.22487)
		(mid 105.99528 -214.111365)
		(end 106.08183 -213.96833)
		(width 0.0889)
		(layer "In6.Cu")
		(net "UPI_CPU1_CPU0_P0P1_DN<18>")
	)
	(segment
		(start 105.061512 -214.622888)
		(end 105.061258 -214.622634)
		(width 0.13208)
		(layer "F.Cu")
		(net "UPI_CPU1_CPU0_P0P1_DN<17>")
	)
	(segment
		(start 353.32162 -176.351184)
		(end 353.874324 -176.201832)
		(width 0.13208)
		(layer "F.Cu")
		(net "UPI_CPU1_CPU0_P0P1_DN<17>")
	)
	(segment
		(start 353.244912 -176.700942)
		(end 353.226878 -176.51476)
		(width 0.13208)
		(layer "F.Cu")
		(net "UPI_CPU1_CPU0_P0P1_DN<17>")
	)
	(segment
		(start 353.940618 -176.976024)
		(end 353.778058 -177.043334)
		(width 0.13208)
		(layer "F.Cu")
		(net "UPI_CPU1_CPU0_P0P1_DN<17>")
	)
	(segment
		(start 105.061512 -215.158574)
		(end 105.061512 -214.622888)
		(width 0.13208)
		(layer "F.Cu")
		(net "UPI_CPU1_CPU0_P0P1_DN<17>")
	)
	(segment
		(start 360.332528 -182.72252)
		(end 355.852222 -178.242468)
		(width 0.13208)
		(layer "F.Cu")
		(net "UPI_CPU1_CPU0_P0P1_DN<17>")
	)
	(segment
		(start 358.103678 -199.456802)
		(end 359.093516 -194.47891)
		(width 0.13208)
		(layer "F.Cu")
		(net "UPI_CPU1_CPU0_P0P1_DN<17>")
	)
	(segment
		(start 358.069134 -205.77048)
		(end 358.069134 -205.261718)
		(width 0.0889)
		(layer "F.Cu")
		(net "UPI_CPU1_CPU0_P0P1_DN<17>")
	)
	(segment
		(start 354.814886 -177.472848)
		(end 354.37445 -177.290476)
		(width 0.13208)
		(layer "F.Cu")
		(net "UPI_CPU1_CPU0_P0P1_DN<17>")
	)
	(segment
		(start 353.412044 -176.89195)
		(end 353.244912 -176.700942)
		(width 0.13208)
		(layer "F.Cu")
		(net "UPI_CPU1_CPU0_P0P1_DN<17>")
	)
	(segment
		(start 355.852222 -178.242468)
		(end 354.814886 -177.472848)
		(width 0.13208)
		(layer "F.Cu")
		(net "UPI_CPU1_CPU0_P0P1_DN<17>")
	)
	(segment
		(start 367.193322 -213.070948)
		(end 364.151164 -210.02879)
		(width 0.0889)
		(layer "F.Cu")
		(net "UPI_CPU1_CPU0_P0P1_DN<17>")
	)
	(segment
		(start 361.504738 -185.552334)
		(end 360.332528 -182.72252)
		(width 0.13208)
		(layer "F.Cu")
		(net "UPI_CPU1_CPU0_P0P1_DN<17>")
	)
	(segment
		(start 367.194084 -213.662768)
		(end 367.193322 -213.070948)
		(width 0.0889)
		(layer "F.Cu")
		(net "UPI_CPU1_CPU0_P0P1_DN<17>")
	)
	(segment
		(start 354.37445 -177.290476)
		(end 354.306886 -177.127662)
		(width 0.13208)
		(layer "F.Cu")
		(net "UPI_CPU1_CPU0_P0P1_DN<17>")
	)
	(segment
		(start 358.069134 -205.261718)
		(end 358.103678 -205.227174)
		(width 0.0889)
		(layer "F.Cu")
		(net "UPI_CPU1_CPU0_P0P1_DN<17>")
	)
	(segment
		(start 361.504738 -188.656722)
		(end 361.504738 -185.552334)
		(width 0.13208)
		(layer "F.Cu")
		(net "UPI_CPU1_CPU0_P0P1_DN<17>")
	)
	(segment
		(start 367.194084 -214.344758)
		(end 367.194084 -213.662768)
		(width 0.0889)
		(layer "F.Cu")
		(net "UPI_CPU1_CPU0_P0P1_DN<17>")
	)
	(segment
		(start 366.943386 -214.889588)
		(end 366.968532 -214.796878)
		(width 0.0889)
		(layer "F.Cu")
		(net "UPI_CPU1_CPU0_P0P1_DN<17>")
	)
	(segment
		(start 353.778058 -177.043334)
		(end 353.412044 -176.89195)
		(width 0.13208)
		(layer "F.Cu")
		(net "UPI_CPU1_CPU0_P0P1_DN<17>")
	)
	(segment
		(start 367.09858 -215.158574)
		(end 366.943386 -214.889588)
		(width 0.0889)
		(layer "F.Cu")
		(net "UPI_CPU1_CPU0_P0P1_DN<17>")
	)
	(segment
		(start 358.103678 -205.205076)
		(end 358.103678 -199.456802)
		(width 0.13208)
		(layer "F.Cu")
		(net "UPI_CPU1_CPU0_P0P1_DN<17>")
	)
	(segment
		(start 358.103678 -205.227174)
		(end 358.103678 -205.205076)
		(width 0.0889)
		(layer "F.Cu")
		(net "UPI_CPU1_CPU0_P0P1_DN<17>")
	)
	(segment
		(start 359.093516 -194.47891)
		(end 361.504738 -188.656722)
		(width 0.13208)
		(layer "F.Cu")
		(net "UPI_CPU1_CPU0_P0P1_DN<17>")
	)
	(segment
		(start 354.306886 -177.127662)
		(end 353.940618 -176.976024)
		(width 0.13208)
		(layer "F.Cu")
		(net "UPI_CPU1_CPU0_P0P1_DN<17>")
	)
	(segment
		(start 353.321112 -176.351946)
		(end 353.32162 -176.351184)
		(width 0.13208)
		(layer "F.Cu")
		(net "UPI_CPU1_CPU0_P0P1_DN<17>")
	)
	(segment
		(start 353.226878 -176.51476)
		(end 353.321112 -176.351946)
		(width 0.13208)
		(layer "F.Cu")
		(net "UPI_CPU1_CPU0_P0P1_DN<17>")
	)
	(segment
		(start 361.038648 -208.73974)
		(end 358.069134 -205.77048)
		(width 0.0889)
		(layer "F.Cu")
		(net "UPI_CPU1_CPU0_P0P1_DN<17>")
	)
	(segment
		(start 364.151164 -210.02879)
		(end 361.038648 -208.73974)
		(width 0.0889)
		(layer "F.Cu")
		(net "UPI_CPU1_CPU0_P0P1_DN<17>")
	)
	(arc
		(start 366.968532 -214.796878)
		(mid 366.977232 -214.790229)
		(end 366.985804 -214.783416)
		(width 0.0889)
		(layer "F.Cu")
		(net "UPI_CPU1_CPU0_P0P1_DN<17>")
	)
	(arc
		(start 366.985804 -214.783416)
		(mid 367.139433 -214.587592)
		(end 367.194084 -214.344758)
		(width 0.0889)
		(layer "F.Cu")
		(net "UPI_CPU1_CPU0_P0P1_DN<17>")
	)
	(segment
		(start 344.750644 -174.139352)
		(end 344.287856 -173.884082)
		(width 0.14732)
		(layer "In6.Cu")
		(net "UPI_CPU1_CPU0_P0P1_DN<17>")
	)
	(segment
		(start 104.826562 -214.91448)
		(end 104.904794 -214.893652)
		(width 0.0889)
		(layer "In6.Cu")
		(net "UPI_CPU1_CPU0_P0P1_DN<17>")
	)
	(segment
		(start 322.261484 -154.191208)
		(end 279.645364 -163.119308)
		(width 0.14732)
		(layer "In6.Cu")
		(net "UPI_CPU1_CPU0_P0P1_DN<17>")
	)
	(segment
		(start 105.19918 -211.77123)
		(end 105.19918 -211.782406)
		(width 0.0889)
		(layer "In6.Cu")
		(net "UPI_CPU1_CPU0_P0P1_DN<17>")
	)
	(segment
		(start 338.026248 -167.23741)
		(end 338.039456 -166.802054)
		(width 0.14732)
		(layer "In6.Cu")
		(net "UPI_CPU1_CPU0_P0P1_DN<17>")
	)
	(segment
		(start 194.626484 -163.109148)
		(end 190.665608 -163.109148)
		(width 0.14732)
		(layer "In6.Cu")
		(net "UPI_CPU1_CPU0_P0P1_DN<17>")
	)
	(segment
		(start 335.843626 -164.47135)
		(end 335.40827 -164.457888)
		(width 0.14732)
		(layer "In6.Cu")
		(net "UPI_CPU1_CPU0_P0P1_DN<17>")
	)
	(segment
		(start 197.102984 -162.796982)
		(end 194.626484 -163.109148)
		(width 0.14732)
		(layer "In6.Cu")
		(net "UPI_CPU1_CPU0_P0P1_DN<17>")
	)
	(segment
		(start 353.21113 -176.558956)
		(end 352.929444 -176.840388)
		(width 0.14732)
		(layer "In6.Cu")
		(net "UPI_CPU1_CPU0_P0P1_DN<17>")
	)
	(segment
		(start 337.937348 -165.682676)
		(end 337.432904 -166.158418)
		(width 0.14732)
		(layer "In6.Cu")
		(net "UPI_CPU1_CPU0_P0P1_DN<17>")
	)
	(segment
		(start 339.628734 -168.489122)
		(end 340.133178 -168.013634)
		(width 0.14732)
		(layer "In6.Cu")
		(net "UPI_CPU1_CPU0_P0P1_DN<17>")
	)
	(segment
		(start 351.874074 -176.544732)
		(end 351.025206 -175.415448)
		(width 0.14732)
		(layer "In6.Cu")
		(net "UPI_CPU1_CPU0_P0P1_DN<17>")
	)
	(segment
		(start 105.25633 -213.417658)
		(end 105.157016 -213.516972)
		(width 0.0889)
		(layer "In6.Cu")
		(net "UPI_CPU1_CPU0_P0P1_DN<17>")
	)
	(segment
		(start 347.356684 -174.332392)
		(end 347.38437 -174.191422)
		(width 0.14732)
		(layer "In6.Cu")
		(net "UPI_CPU1_CPU0_P0P1_DN<17>")
	)
	(segment
		(start 105.157016 -212.775292)
		(end 105.157016 -213.051644)
		(width 0.0889)
		(layer "In6.Cu")
		(net "UPI_CPU1_CPU0_P0P1_DN<17>")
	)
	(segment
		(start 338.5439 -166.326566)
		(end 338.55025 -166.118794)
		(width 0.14732)
		(layer "In6.Cu")
		(net "UPI_CPU1_CPU0_P0P1_DN<17>")
	)
	(segment
		(start 336.954622 -164.639498)
		(end 336.960972 -164.431726)
		(width 0.14732)
		(layer "In6.Cu")
		(net "UPI_CPU1_CPU0_P0P1_DN<17>")
	)
	(segment
		(start 346.488512 -174.163482)
		(end 346.127832 -174.407322)
		(width 0.14732)
		(layer "In6.Cu")
		(net "UPI_CPU1_CPU0_P0P1_DN<17>")
	)
	(segment
		(start 111.75365 -194.653916)
		(end 111.777018 -194.85737)
		(width 0.14732)
		(layer "In6.Cu")
		(net "UPI_CPU1_CPU0_P0P1_DN<17>")
	)
	(segment
		(start 339.022182 -167.845486)
		(end 338.586826 -167.832278)
		(width 0.14732)
		(layer "In6.Cu")
		(net "UPI_CPU1_CPU0_P0P1_DN<17>")
	)
	(segment
		(start 335.40827 -164.457888)
		(end 334.388206 -163.37534)
		(width 0.14732)
		(layer "In6.Cu")
		(net "UPI_CPU1_CPU0_P0P1_DN<17>")
	)
	(segment
		(start 132.671566 -172.804836)
		(end 118.593362 -186.04357)
		(width 0.14732)
		(layer "In6.Cu")
		(net "UPI_CPU1_CPU0_P0P1_DN<17>")
	)
	(segment
		(start 111.34471 -195.169282)
		(end 110.93831 -195.680838)
		(width 0.14732)
		(layer "In6.Cu")
		(net "UPI_CPU1_CPU0_P0P1_DN<17>")
	)
	(segment
		(start 346.127832 -174.407322)
		(end 344.750644 -174.139352)
		(width 0.14732)
		(layer "In6.Cu")
		(net "UPI_CPU1_CPU0_P0P1_DN<17>")
	)
	(segment
		(start 344.287856 -173.884082)
		(end 339.61578 -168.924478)
		(width 0.14732)
		(layer "In6.Cu")
		(net "UPI_CPU1_CPU0_P0P1_DN<17>")
	)
	(segment
		(start 336.43697 -165.550342)
		(end 336.450178 -165.114986)
		(width 0.14732)
		(layer "In6.Cu")
		(net "UPI_CPU1_CPU0_P0P1_DN<17>")
	)
	(segment
		(start 165.247066 -152.730454)
		(end 132.671566 -172.804836)
		(width 0.14732)
		(layer "In6.Cu")
		(net "UPI_CPU1_CPU0_P0P1_DN<17>")
	)
	(segment
		(start 105.25633 -212.675978)
		(end 105.157016 -212.775292)
		(width 0.0889)
		(layer "In6.Cu")
		(net "UPI_CPU1_CPU0_P0P1_DN<17>")
	)
	(segment
		(start 336.997548 -166.14521)
		(end 336.43697 -165.550342)
		(width 0.14732)
		(layer "In6.Cu")
		(net "UPI_CPU1_CPU0_P0P1_DN<17>")
	)
	(segment
		(start 105.25633 -212.41893)
		(end 105.25633 -212.675978)
		(width 0.0889)
		(layer "In6.Cu")
		(net "UPI_CPU1_CPU0_P0P1_DN<17>")
	)
	(segment
		(start 118.593362 -186.04357)
		(end 111.75365 -194.653916)
		(width 0.14732)
		(layer "In6.Cu")
		(net "UPI_CPU1_CPU0_P0P1_DN<17>")
	)
	(segment
		(start 173.044358 -153.889964)
		(end 169.885106 -152.325578)
		(width 0.14732)
		(layer "In6.Cu")
		(net "UPI_CPU1_CPU0_P0P1_DN<17>")
	)
	(segment
		(start 338.55025 -166.118794)
		(end 338.14512 -165.689026)
		(width 0.14732)
		(layer "In6.Cu")
		(net "UPI_CPU1_CPU0_P0P1_DN<17>")
	)
	(segment
		(start 334.644238 -162.509454)
		(end 334.239108 -162.079686)
		(width 0.14732)
		(layer "In6.Cu")
		(net "UPI_CPU1_CPU0_P0P1_DN<17>")
	)
	(segment
		(start 336.450178 -165.114986)
		(end 336.954622 -164.639498)
		(width 0.14732)
		(layer "In6.Cu")
		(net "UPI_CPU1_CPU0_P0P1_DN<17>")
	)
	(segment
		(start 352.929444 -176.840388)
		(end 352.432366 -176.840388)
		(width 0.14732)
		(layer "In6.Cu")
		(net "UPI_CPU1_CPU0_P0P1_DN<17>")
	)
	(segment
		(start 352.432366 -176.840388)
		(end 351.874074 -176.544732)
		(width 0.14732)
		(layer "In6.Cu")
		(net "UPI_CPU1_CPU0_P0P1_DN<17>")
	)
	(segment
		(start 166.652194 -152.239726)
		(end 165.247066 -152.730454)
		(width 0.14732)
		(layer "In6.Cu")
		(net "UPI_CPU1_CPU0_P0P1_DN<17>")
	)
	(segment
		(start 350.89973 -175.334422)
		(end 347.600778 -174.693326)
		(width 0.14732)
		(layer "In6.Cu")
		(net "UPI_CPU1_CPU0_P0P1_DN<17>")
	)
	(segment
		(start 336.34807 -163.995608)
		(end 335.843626 -164.47135)
		(width 0.14732)
		(layer "In6.Cu")
		(net "UPI_CPU1_CPU0_P0P1_DN<17>")
	)
	(segment
		(start 234.209336 -153.231088)
		(end 197.102984 -162.796982)
		(width 0.14732)
		(layer "In6.Cu")
		(net "UPI_CPU1_CPU0_P0P1_DN<17>")
	)
	(segment
		(start 339.734398 -167.376094)
		(end 339.526626 -167.369744)
		(width 0.14732)
		(layer "In6.Cu")
		(net "UPI_CPU1_CPU0_P0P1_DN<17>")
	)
	(segment
		(start 339.61578 -168.924478)
		(end 339.628734 -168.489122)
		(width 0.14732)
		(layer "In6.Cu")
		(net "UPI_CPU1_CPU0_P0P1_DN<17>")
	)
	(segment
		(start 353.333304 -176.347374)
		(end 353.21113 -176.558956)
		(width 0.14732)
		(layer "In6.Cu")
		(net "UPI_CPU1_CPU0_P0P1_DN<17>")
	)
	(segment
		(start 105.157016 -211.82457)
		(end 105.157016 -212.319616)
		(width 0.0889)
		(layer "In6.Cu")
		(net "UPI_CPU1_CPU0_P0P1_DN<17>")
	)
	(segment
		(start 334.637888 -162.717226)
		(end 334.644238 -162.509454)
		(width 0.14732)
		(layer "In6.Cu")
		(net "UPI_CPU1_CPU0_P0P1_DN<17>")
	)
	(segment
		(start 347.600778 -174.693326)
		(end 347.356684 -174.332392)
		(width 0.14732)
		(layer "In6.Cu")
		(net "UPI_CPU1_CPU0_P0P1_DN<17>")
	)
	(segment
		(start 105.25633 -213.150958)
		(end 105.25633 -213.417658)
		(width 0.0889)
		(layer "In6.Cu")
		(net "UPI_CPU1_CPU0_P0P1_DN<17>")
	)
	(segment
		(start 110.93831 -195.680838)
		(end 105.19918 -211.43595)
		(width 0.14732)
		(layer "In6.Cu")
		(net "UPI_CPU1_CPU0_P0P1_DN<17>")
	)
	(segment
		(start 104.904794 -214.893652)
		(end 105.061258 -214.622634)
		(width 0.0889)
		(layer "In6.Cu")
		(net "UPI_CPU1_CPU0_P0P1_DN<17>")
	)
	(segment
		(start 334.401668 -162.939984)
		(end 334.637888 -162.717226)
		(width 0.14732)
		(layer "In6.Cu")
		(net "UPI_CPU1_CPU0_P0P1_DN<17>")
	)
	(segment
		(start 338.586826 -167.832278)
		(end 338.026248 -167.23741)
		(width 0.14732)
		(layer "In6.Cu")
		(net "UPI_CPU1_CPU0_P0P1_DN<17>")
	)
	(segment
		(start 334.239108 -162.079686)
		(end 334.031336 -162.073336)
		(width 0.14732)
		(layer "In6.Cu")
		(net "UPI_CPU1_CPU0_P0P1_DN<17>")
	)
	(segment
		(start 238.001302 -153.231088)
		(end 234.209336 -153.231088)
		(width 0.14732)
		(layer "In6.Cu")
		(net "UPI_CPU1_CPU0_P0P1_DN<17>")
	)
	(segment
		(start 169.885106 -152.325578)
		(end 166.652194 -152.239726)
		(width 0.14732)
		(layer "In6.Cu")
		(net "UPI_CPU1_CPU0_P0P1_DN<17>")
	)
	(segment
		(start 323.415152 -154.191208)
		(end 322.261484 -154.191208)
		(width 0.14732)
		(layer "In6.Cu")
		(net "UPI_CPU1_CPU0_P0P1_DN<17>")
	)
	(segment
		(start 334.031336 -162.073336)
		(end 333.794862 -162.296348)
		(width 0.14732)
		(layer "In6.Cu")
		(net "UPI_CPU1_CPU0_P0P1_DN<17>")
	)
	(segment
		(start 351.025206 -175.415448)
		(end 350.89973 -175.334422)
		(width 0.14732)
		(layer "In6.Cu")
		(net "UPI_CPU1_CPU0_P0P1_DN<17>")
	)
	(segment
		(start 339.526626 -167.369744)
		(end 339.022182 -167.845486)
		(width 0.14732)
		(layer "In6.Cu")
		(net "UPI_CPU1_CPU0_P0P1_DN<17>")
	)
	(segment
		(start 105.157016 -213.051644)
		(end 105.25633 -213.150958)
		(width 0.0889)
		(layer "In6.Cu")
		(net "UPI_CPU1_CPU0_P0P1_DN<17>")
	)
	(segment
		(start 340.133178 -168.013634)
		(end 340.139528 -167.805862)
		(width 0.14732)
		(layer "In6.Cu")
		(net "UPI_CPU1_CPU0_P0P1_DN<17>")
	)
	(segment
		(start 338.039456 -166.802054)
		(end 338.5439 -166.326566)
		(width 0.14732)
		(layer "In6.Cu")
		(net "UPI_CPU1_CPU0_P0P1_DN<17>")
	)
	(segment
		(start 340.139528 -167.805862)
		(end 339.734398 -167.376094)
		(width 0.14732)
		(layer "In6.Cu")
		(net "UPI_CPU1_CPU0_P0P1_DN<17>")
	)
	(segment
		(start 346.516198 -174.022766)
		(end 346.488512 -174.163482)
		(width 0.14732)
		(layer "In6.Cu")
		(net "UPI_CPU1_CPU0_P0P1_DN<17>")
	)
	(segment
		(start 334.388206 -163.37534)
		(end 334.401668 -162.939984)
		(width 0.14732)
		(layer "In6.Cu")
		(net "UPI_CPU1_CPU0_P0P1_DN<17>")
	)
	(segment
		(start 276.499066 -163.119308)
		(end 238.001302 -153.231088)
		(width 0.14732)
		(layer "In6.Cu")
		(net "UPI_CPU1_CPU0_P0P1_DN<17>")
	)
	(segment
		(start 336.960972 -164.431726)
		(end 336.555842 -164.001958)
		(width 0.14732)
		(layer "In6.Cu")
		(net "UPI_CPU1_CPU0_P0P1_DN<17>")
	)
	(segment
		(start 105.157016 -212.319616)
		(end 105.25633 -212.41893)
		(width 0.0889)
		(layer "In6.Cu")
		(net "UPI_CPU1_CPU0_P0P1_DN<17>")
	)
	(segment
		(start 347.268292 -174.01921)
		(end 346.688156 -173.906434)
		(width 0.14732)
		(layer "In6.Cu")
		(net "UPI_CPU1_CPU0_P0P1_DN<17>")
	)
	(segment
		(start 190.665608 -163.109148)
		(end 173.044358 -153.889964)
		(width 0.14732)
		(layer "In6.Cu")
		(net "UPI_CPU1_CPU0_P0P1_DN<17>")
	)
	(segment
		(start 353.333812 -176.346612)
		(end 353.333304 -176.347374)
		(width 0.14732)
		(layer "In6.Cu")
		(net "UPI_CPU1_CPU0_P0P1_DN<17>")
	)
	(segment
		(start 111.547656 -195.145914)
		(end 111.34471 -195.169282)
		(width 0.14732)
		(layer "In6.Cu")
		(net "UPI_CPU1_CPU0_P0P1_DN<17>")
	)
	(segment
		(start 333.359506 -162.282886)
		(end 327.752964 -156.332174)
		(width 0.14732)
		(layer "In6.Cu")
		(net "UPI_CPU1_CPU0_P0P1_DN<17>")
	)
	(segment
		(start 346.688156 -173.906434)
		(end 346.516198 -174.022766)
		(width 0.14732)
		(layer "In6.Cu")
		(net "UPI_CPU1_CPU0_P0P1_DN<17>")
	)
	(segment
		(start 279.645364 -163.119308)
		(end 276.499066 -163.119308)
		(width 0.14732)
		(layer "In6.Cu")
		(net "UPI_CPU1_CPU0_P0P1_DN<17>")
	)
	(segment
		(start 111.777018 -194.85737)
		(end 111.547656 -195.145914)
		(width 0.14732)
		(layer "In6.Cu")
		(net "UPI_CPU1_CPU0_P0P1_DN<17>")
	)
	(segment
		(start 337.432904 -166.158418)
		(end 336.997548 -166.14521)
		(width 0.14732)
		(layer "In6.Cu")
		(net "UPI_CPU1_CPU0_P0P1_DN<17>")
	)
	(segment
		(start 353.874324 -176.201832)
		(end 353.333812 -176.346612)
		(width 0.14732)
		(layer "In6.Cu")
		(net "UPI_CPU1_CPU0_P0P1_DN<17>")
	)
	(segment
		(start 338.14512 -165.689026)
		(end 337.937348 -165.682676)
		(width 0.14732)
		(layer "In6.Cu")
		(net "UPI_CPU1_CPU0_P0P1_DN<17>")
	)
	(segment
		(start 327.752964 -156.332174)
		(end 325.705724 -154.767788)
		(width 0.14732)
		(layer "In6.Cu")
		(net "UPI_CPU1_CPU0_P0P1_DN<17>")
	)
	(segment
		(start 105.19918 -211.782406)
		(end 105.157016 -211.82457)
		(width 0.0889)
		(layer "In6.Cu")
		(net "UPI_CPU1_CPU0_P0P1_DN<17>")
	)
	(segment
		(start 336.555842 -164.001958)
		(end 336.34807 -163.995608)
		(width 0.14732)
		(layer "In6.Cu")
		(net "UPI_CPU1_CPU0_P0P1_DN<17>")
	)
	(segment
		(start 325.705724 -154.767788)
		(end 323.415152 -154.191208)
		(width 0.14732)
		(layer "In6.Cu")
		(net "UPI_CPU1_CPU0_P0P1_DN<17>")
	)
	(segment
		(start 105.157016 -213.516972)
		(end 105.157016 -213.929468)
		(width 0.0889)
		(layer "In6.Cu")
		(net "UPI_CPU1_CPU0_P0P1_DN<17>")
	)
	(segment
		(start 347.38437 -174.191422)
		(end 347.268292 -174.01921)
		(width 0.14732)
		(layer "In6.Cu")
		(net "UPI_CPU1_CPU0_P0P1_DN<17>")
	)
	(segment
		(start 104.686608 -214.461852)
		(end 104.686608 -214.622634)
		(width 0.0889)
		(layer "In6.Cu")
		(net "UPI_CPU1_CPU0_P0P1_DN<17>")
	)
	(segment
		(start 333.794862 -162.296348)
		(end 333.359506 -162.282886)
		(width 0.14732)
		(layer "In6.Cu")
		(net "UPI_CPU1_CPU0_P0P1_DN<17>")
	)
	(segment
		(start 105.19918 -211.43595)
		(end 105.19918 -211.77123)
		(width 0.14732)
		(layer "In6.Cu")
		(net "UPI_CPU1_CPU0_P0P1_DN<17>")
	)
	(arc
		(start 104.686608 -214.622634)
		(mid 104.723468 -214.784431)
		(end 104.826562 -214.91448)
		(width 0.0889)
		(layer "In6.Cu")
		(net "UPI_CPU1_CPU0_P0P1_DN<17>")
	)
	(arc
		(start 105.141776 -213.968584)
		(mid 105.03157 -214.138501)
		(end 104.871012 -214.261954)
		(width 0.0889)
		(layer "In6.Cu")
		(net "UPI_CPU1_CPU0_P0P1_DN<17>")
	)
	(arc
		(start 104.871012 -214.261954)
		(mid 104.761616 -214.346051)
		(end 104.686608 -214.461852)
		(width 0.0889)
		(layer "In6.Cu")
		(net "UPI_CPU1_CPU0_P0P1_DN<17>")
	)
	(arc
		(start 105.157016 -213.929468)
		(mid 105.149738 -213.949159)
		(end 105.141776 -213.968584)
		(width 0.0889)
		(layer "In6.Cu")
		(net "UPI_CPU1_CPU0_P0P1_DN<17>")
	)
	(segment
		(start 367.47323 -215.172798)
		(end 367.47323 -215.158066)
		(width 0.0889)
		(layer "F.Cu")
		(net "UPI_CPU1_CPU0_P0P1_DN<16>")
	)
	(segment
		(start 104.121712 -214.622888)
		(end 104.121458 -214.622634)
		(width 0.13208)
		(layer "F.Cu")
		(net "UPI_CPU1_CPU0_P0P1_DN<16>")
	)
	(segment
		(start 361.987084 -208.58861)
		(end 359.186988 -205.78826)
		(width 0.0889)
		(layer "F.Cu")
		(net "UPI_CPU1_CPU0_P0P1_DN<16>")
	)
	(segment
		(start 359.186988 -205.261464)
		(end 359.152698 -205.227174)
		(width 0.0889)
		(layer "F.Cu")
		(net "UPI_CPU1_CPU0_P0P1_DN<16>")
	)
	(segment
		(start 350.423734 -174.424086)
		(end 349.895922 -174.119286)
		(width 0.13208)
		(layer "F.Cu")
		(net "UPI_CPU1_CPU0_P0P1_DN<16>")
	)
	(segment
		(start 359.152698 -199.78497)
		(end 359.157524 -199.780144)
		(width 0.13208)
		(layer "F.Cu")
		(net "UPI_CPU1_CPU0_P0P1_DN<16>")
	)
	(segment
		(start 359.186988 -205.78826)
		(end 359.186988 -205.261464)
		(width 0.0889)
		(layer "F.Cu")
		(net "UPI_CPU1_CPU0_P0P1_DN<16>")
	)
	(segment
		(start 354.8126 -175.741584)
		(end 353.866196 -175.109124)
		(width 0.13208)
		(layer "F.Cu")
		(net "UPI_CPU1_CPU0_P0P1_DN<16>")
	)
	(segment
		(start 353.866196 -175.109124)
		(end 350.423734 -174.424086)
		(width 0.13208)
		(layer "F.Cu")
		(net "UPI_CPU1_CPU0_P0P1_DN<16>")
	)
	(segment
		(start 104.121712 -215.158574)
		(end 104.121712 -214.622888)
		(width 0.13208)
		(layer "F.Cu")
		(net "UPI_CPU1_CPU0_P0P1_DN<16>")
	)
	(segment
		(start 349.895922 -174.119286)
		(end 349.718122 -173.811438)
		(width 0.13208)
		(layer "F.Cu")
		(net "UPI_CPU1_CPU0_P0P1_DN<16>")
	)
	(segment
		(start 364.60684 -209.673952)
		(end 361.987084 -208.58861)
		(width 0.0889)
		(layer "F.Cu")
		(net "UPI_CPU1_CPU0_P0P1_DN<16>")
	)
	(segment
		(start 367.568734 -215.972644)
		(end 367.723928 -215.703658)
		(width 0.0889)
		(layer "F.Cu")
		(net "UPI_CPU1_CPU0_P0P1_DN<16>")
	)
	(segment
		(start 359.152698 -205.205076)
		(end 359.152698 -199.78497)
		(width 0.13208)
		(layer "F.Cu")
		(net "UPI_CPU1_CPU0_P0P1_DN<16>")
	)
	(segment
		(start 359.157524 -199.780144)
		(end 360.198924 -194.545204)
		(width 0.13208)
		(layer "F.Cu")
		(net "UPI_CPU1_CPU0_P0P1_DN<16>")
	)
	(segment
		(start 367.943384 -213.010242)
		(end 364.60684 -209.673952)
		(width 0.0889)
		(layer "F.Cu")
		(net "UPI_CPU1_CPU0_P0P1_DN<16>")
	)
	(segment
		(start 360.198924 -194.545204)
		(end 362.564934 -188.833252)
		(width 0.13208)
		(layer "F.Cu")
		(net "UPI_CPU1_CPU0_P0P1_DN<16>")
	)
	(segment
		(start 355.349302 -176.100486)
		(end 355.176582 -176.134776)
		(width 0.13208)
		(layer "F.Cu")
		(net "UPI_CPU1_CPU0_P0P1_DN<16>")
	)
	(segment
		(start 362.994956 -183.636666)
		(end 355.678486 -176.32045)
		(width 0.13208)
		(layer "F.Cu")
		(net "UPI_CPU1_CPU0_P0P1_DN<16>")
	)
	(segment
		(start 355.678486 -176.32045)
		(end 355.349302 -176.100486)
		(width 0.13208)
		(layer "F.Cu")
		(net "UPI_CPU1_CPU0_P0P1_DN<16>")
	)
	(segment
		(start 354.84689 -175.914304)
		(end 354.8126 -175.741584)
		(width 0.13208)
		(layer "F.Cu")
		(net "UPI_CPU1_CPU0_P0P1_DN<16>")
	)
	(segment
		(start 349.718122 -173.811438)
		(end 349.165672 -173.661832)
		(width 0.13208)
		(layer "F.Cu")
		(net "UPI_CPU1_CPU0_P0P1_DN<16>")
	)
	(segment
		(start 359.152698 -205.227174)
		(end 359.152698 -205.205076)
		(width 0.0889)
		(layer "F.Cu")
		(net "UPI_CPU1_CPU0_P0P1_DN<16>")
	)
	(segment
		(start 363.10062 -183.891936)
		(end 362.994956 -183.636666)
		(width 0.13208)
		(layer "F.Cu")
		(net "UPI_CPU1_CPU0_P0P1_DN<16>")
	)
	(segment
		(start 355.176582 -176.134776)
		(end 354.84689 -175.914304)
		(width 0.13208)
		(layer "F.Cu")
		(net "UPI_CPU1_CPU0_P0P1_DN<16>")
	)
	(segment
		(start 367.943384 -214.345012)
		(end 367.943384 -213.010242)
		(width 0.0889)
		(layer "F.Cu")
		(net "UPI_CPU1_CPU0_P0P1_DN<16>")
	)
	(segment
		(start 362.564934 -188.833252)
		(end 363.10062 -186.140344)
		(width 0.13208)
		(layer "F.Cu")
		(net "UPI_CPU1_CPU0_P0P1_DN<16>")
	)
	(segment
		(start 367.723928 -215.703658)
		(end 367.698782 -215.610694)
		(width 0.0889)
		(layer "F.Cu")
		(net "UPI_CPU1_CPU0_P0P1_DN<16>")
	)
	(segment
		(start 363.10062 -186.140344)
		(end 363.10062 -183.891936)
		(width 0.13208)
		(layer "F.Cu")
		(net "UPI_CPU1_CPU0_P0P1_DN<16>")
	)
	(segment
		(start 367.768378 -214.661496)
		(end 367.768632 -214.661496)
		(width 0.0889)
		(layer "F.Cu")
		(net "UPI_CPU1_CPU0_P0P1_DN<16>")
	)
	(arc
		(start 367.698782 -215.610694)
		(mid 367.690208 -215.604045)
		(end 367.681764 -215.597232)
		(width 0.0889)
		(layer "F.Cu")
		(net "UPI_CPU1_CPU0_P0P1_DN<16>")
	)
	(arc
		(start 367.681764 -215.597232)
		(mid 367.530986 -215.407867)
		(end 367.47323 -215.172798)
		(width 0.0889)
		(layer "F.Cu")
		(net "UPI_CPU1_CPU0_P0P1_DN<16>")
	)
	(arc
		(start 367.768632 -214.661496)
		(mid 367.896755 -214.525737)
		(end 367.943384 -214.345012)
		(width 0.0889)
		(layer "F.Cu")
		(net "UPI_CPU1_CPU0_P0P1_DN<16>")
	)
	(arc
		(start 367.47323 -215.158066)
		(mid 367.552578 -214.869221)
		(end 367.768378 -214.661496)
		(width 0.0889)
		(layer "F.Cu")
		(net "UPI_CPU1_CPU0_P0P1_DN<16>")
	)
	(segment
		(start 107.318048 -203.008738)
		(end 107.317794 -203.008738)
		(width 0.14732)
		(layer "In6.Cu")
		(net "UPI_CPU1_CPU0_P0P1_DN<16>")
	)
	(segment
		(start 111.247174 -193.744596)
		(end 111.418624 -193.724784)
		(width 0.14732)
		(layer "In6.Cu")
		(net "UPI_CPU1_CPU0_P0P1_DN<16>")
	)
	(segment
		(start 323.52234 -153.327608)
		(end 326.089264 -153.973276)
		(width 0.14732)
		(layer "In6.Cu")
		(net "UPI_CPU1_CPU0_P0P1_DN<16>")
	)
	(segment
		(start 344.514932 -171.963334)
		(end 344.948764 -171.931838)
		(width 0.14732)
		(layer "In6.Cu")
		(net "UPI_CPU1_CPU0_P0P1_DN<16>")
	)
	(segment
		(start 103.962708 -214.321644)
		(end 103.992934 -214.22487)
		(width 0.0889)
		(layer "In6.Cu")
		(net "UPI_CPU1_CPU0_P0P1_DN<16>")
	)
	(segment
		(start 345.780614 -170.969178)
		(end 345.988132 -170.954192)
		(width 0.14732)
		(layer "In6.Cu")
		(net "UPI_CPU1_CPU0_P0P1_DN<16>")
	)
	(segment
		(start 113.081054 -191.632078)
		(end 113.061242 -191.460628)
		(width 0.14732)
		(layer "In6.Cu")
		(net "UPI_CPU1_CPU0_P0P1_DN<16>")
	)
	(segment
		(start 114.451892 -189.71006)
		(end 114.723418 -189.368176)
		(width 0.14732)
		(layer "In6.Cu")
		(net "UPI_CPU1_CPU0_P0P1_DN<16>")
	)
	(segment
		(start 113.061242 -191.460628)
		(end 113.332768 -191.118744)
		(width 0.14732)
		(layer "In6.Cu")
		(net "UPI_CPU1_CPU0_P0P1_DN<16>")
	)
	(segment
		(start 196.940424 -161.946844)
		(end 234.10926 -152.364948)
		(width 0.14732)
		(layer "In6.Cu")
		(net "UPI_CPU1_CPU0_P0P1_DN<16>")
	)
	(segment
		(start 110.995206 -194.25793)
		(end 110.975648 -194.08648)
		(width 0.14732)
		(layer "In6.Cu")
		(net "UPI_CPU1_CPU0_P0P1_DN<16>")
	)
	(segment
		(start 113.504218 -191.099186)
		(end 113.776252 -190.756794)
		(width 0.14732)
		(layer "In6.Cu")
		(net "UPI_CPU1_CPU0_P0P1_DN<16>")
	)
	(segment
		(start 104.216962 -211.82457)
		(end 104.259126 -211.782406)
		(width 0.0889)
		(layer "In6.Cu")
		(net "UPI_CPU1_CPU0_P0P1_DN<16>")
	)
	(segment
		(start 114.027966 -190.24346)
		(end 114.199416 -190.223902)
		(width 0.14732)
		(layer "In6.Cu")
		(net "UPI_CPU1_CPU0_P0P1_DN<16>")
	)
	(segment
		(start 165.247828 -151.73452)
		(end 166.504874 -151.295608)
		(width 0.14732)
		(layer "In6.Cu")
		(net "UPI_CPU1_CPU0_P0P1_DN<16>")
	)
	(segment
		(start 276.60854 -162.255708)
		(end 279.555702 -162.255708)
		(width 0.14732)
		(layer "In6.Cu")
		(net "UPI_CPU1_CPU0_P0P1_DN<16>")
	)
	(segment
		(start 343.864184 -170.994324)
		(end 343.89568 -171.428156)
		(width 0.14732)
		(layer "In6.Cu")
		(net "UPI_CPU1_CPU0_P0P1_DN<16>")
	)
	(segment
		(start 112.385856 -192.507362)
		(end 112.366044 -192.335912)
		(width 0.14732)
		(layer "In6.Cu")
		(net "UPI_CPU1_CPU0_P0P1_DN<16>")
	)
	(segment
		(start 342.110822 -169.478706)
		(end 342.142318 -169.912538)
		(width 0.14732)
		(layer "In6.Cu")
		(net "UPI_CPU1_CPU0_P0P1_DN<16>")
	)
	(segment
		(start 104.259126 -211.782406)
		(end 104.259126 -211.77123)
		(width 0.0889)
		(layer "In6.Cu")
		(net "UPI_CPU1_CPU0_P0P1_DN<16>")
	)
	(segment
		(start 114.723418 -189.368176)
		(end 114.894868 -189.348618)
		(width 0.14732)
		(layer "In6.Cu")
		(net "UPI_CPU1_CPU0_P0P1_DN<16>")
	)
	(segment
		(start 111.690658 -193.382646)
		(end 111.670846 -193.211196)
		(width 0.14732)
		(layer "In6.Cu")
		(net "UPI_CPU1_CPU0_P0P1_DN<16>")
	)
	(segment
		(start 104.259126 -211.406232)
		(end 107.318048 -203.008738)
		(width 0.14732)
		(layer "In6.Cu")
		(net "UPI_CPU1_CPU0_P0P1_DN<16>")
	)
	(segment
		(start 328.288396 -155.654502)
		(end 342.927686 -168.308528)
		(width 0.14732)
		(layer "In6.Cu")
		(net "UPI_CPU1_CPU0_P0P1_DN<16>")
	)
	(segment
		(start 322.171822 -153.327608)
		(end 323.52234 -153.327608)
		(width 0.14732)
		(layer "In6.Cu")
		(net "UPI_CPU1_CPU0_P0P1_DN<16>")
	)
	(segment
		(start 110.975648 -194.08648)
		(end 111.247174 -193.744596)
		(width 0.14732)
		(layer "In6.Cu")
		(net "UPI_CPU1_CPU0_P0P1_DN<16>")
	)
	(segment
		(start 112.366044 -192.335912)
		(end 112.63757 -191.994028)
		(width 0.14732)
		(layer "In6.Cu")
		(net "UPI_CPU1_CPU0_P0P1_DN<16>")
	)
	(segment
		(start 349.31096 -173.120304)
		(end 349.165672 -173.661832)
		(width 0.14732)
		(layer "In6.Cu")
		(net "UPI_CPU1_CPU0_P0P1_DN<16>")
	)
	(segment
		(start 113.332768 -191.118744)
		(end 113.504218 -191.099186)
		(width 0.14732)
		(layer "In6.Cu")
		(net "UPI_CPU1_CPU0_P0P1_DN<16>")
	)
	(segment
		(start 342.942672 -168.516046)
		(end 342.110822 -169.478706)
		(width 0.14732)
		(layer "In6.Cu")
		(net "UPI_CPU1_CPU0_P0P1_DN<16>")
	)
	(segment
		(start 173.446186 -153.101294)
		(end 190.923926 -162.245548)
		(width 0.14732)
		(layer "In6.Cu")
		(net "UPI_CPU1_CPU0_P0P1_DN<16>")
	)
	(segment
		(start 104.259126 -211.77123)
		(end 104.259126 -211.406232)
		(width 0.14732)
		(layer "In6.Cu")
		(net "UPI_CPU1_CPU0_P0P1_DN<16>")
	)
	(segment
		(start 343.89568 -171.428156)
		(end 344.514932 -171.963334)
		(width 0.14732)
		(layer "In6.Cu")
		(net "UPI_CPU1_CPU0_P0P1_DN<16>")
	)
	(segment
		(start 114.02822 -190.24346)
		(end 114.027966 -190.24346)
		(width 0.14732)
		(layer "In6.Cu")
		(net "UPI_CPU1_CPU0_P0P1_DN<16>")
	)
	(segment
		(start 114.199416 -190.223902)
		(end 114.47145 -189.88151)
		(width 0.14732)
		(layer "In6.Cu")
		(net "UPI_CPU1_CPU0_P0P1_DN<16>")
	)
	(segment
		(start 349.206566 -172.939456)
		(end 349.31096 -173.120304)
		(width 0.14732)
		(layer "In6.Cu")
		(net "UPI_CPU1_CPU0_P0P1_DN<16>")
	)
	(segment
		(start 111.942372 -192.869312)
		(end 112.113822 -192.8495)
		(width 0.14732)
		(layer "In6.Cu")
		(net "UPI_CPU1_CPU0_P0P1_DN<16>")
	)
	(segment
		(start 113.776252 -190.756794)
		(end 113.75644 -190.585598)
		(width 0.14732)
		(layer "In6.Cu")
		(net "UPI_CPU1_CPU0_P0P1_DN<16>")
	)
	(segment
		(start 113.75644 -190.585598)
		(end 114.02822 -190.24346)
		(width 0.14732)
		(layer "In6.Cu")
		(net "UPI_CPU1_CPU0_P0P1_DN<16>")
	)
	(segment
		(start 344.23477 -169.438574)
		(end 344.681048 -169.824146)
		(width 0.14732)
		(layer "In6.Cu")
		(net "UPI_CPU1_CPU0_P0P1_DN<16>")
	)
	(segment
		(start 166.504874 -151.295608)
		(end 169.98696 -151.38781)
		(width 0.14732)
		(layer "In6.Cu")
		(net "UPI_CPU1_CPU0_P0P1_DN<16>")
	)
	(segment
		(start 347.665802 -172.404278)
		(end 348.8436 -172.687488)
		(width 0.14732)
		(layer "In6.Cu")
		(net "UPI_CPU1_CPU0_P0P1_DN<16>")
	)
	(segment
		(start 169.98696 -151.38781)
		(end 173.446186 -153.101294)
		(width 0.14732)
		(layer "In6.Cu")
		(net "UPI_CPU1_CPU0_P0P1_DN<16>")
	)
	(segment
		(start 110.222538 -195.034662)
		(end 110.551976 -194.61988)
		(width 0.14732)
		(layer "In6.Cu")
		(net "UPI_CPU1_CPU0_P0P1_DN<16>")
	)
	(segment
		(start 234.10926 -152.364948)
		(end 238.10087 -152.364948)
		(width 0.14732)
		(layer "In6.Cu")
		(net "UPI_CPU1_CPU0_P0P1_DN<16>")
	)
	(segment
		(start 112.80902 -191.974216)
		(end 113.081054 -191.632078)
		(width 0.14732)
		(layer "In6.Cu")
		(net "UPI_CPU1_CPU0_P0P1_DN<16>")
	)
	(segment
		(start 104.217216 -213.929468)
		(end 104.216962 -213.93023)
		(width 0.0889)
		(layer "In6.Cu")
		(net "UPI_CPU1_CPU0_P0P1_DN<16>")
	)
	(segment
		(start 194.572128 -162.245548)
		(end 196.940424 -161.946844)
		(width 0.14732)
		(layer "In6.Cu")
		(net "UPI_CPU1_CPU0_P0P1_DN<16>")
	)
	(segment
		(start 111.670846 -193.211196)
		(end 111.942372 -192.869312)
		(width 0.14732)
		(layer "In6.Cu")
		(net "UPI_CPU1_CPU0_P0P1_DN<16>")
	)
	(segment
		(start 279.555702 -162.255708)
		(end 322.171822 -153.327608)
		(width 0.14732)
		(layer "In6.Cu")
		(net "UPI_CPU1_CPU0_P0P1_DN<16>")
	)
	(segment
		(start 132.21462 -172.09135)
		(end 165.247828 -151.73452)
		(width 0.14732)
		(layer "In6.Cu")
		(net "UPI_CPU1_CPU0_P0P1_DN<16>")
	)
	(segment
		(start 348.8436 -172.687488)
		(end 349.206566 -172.939456)
		(width 0.14732)
		(layer "In6.Cu")
		(net "UPI_CPU1_CPU0_P0P1_DN<16>")
	)
	(segment
		(start 343.195402 -170.41622)
		(end 344.027252 -169.45356)
		(width 0.14732)
		(layer "In6.Cu")
		(net "UPI_CPU1_CPU0_P0P1_DN<16>")
	)
	(segment
		(start 115.147344 -188.834776)
		(end 117.33149 -186.08548)
		(width 0.14732)
		(layer "In6.Cu")
		(net "UPI_CPU1_CPU0_P0P1_DN<16>")
	)
	(segment
		(start 112.113822 -192.8495)
		(end 112.385856 -192.507362)
		(width 0.14732)
		(layer "In6.Cu")
		(net "UPI_CPU1_CPU0_P0P1_DN<16>")
	)
	(segment
		(start 107.317794 -203.008738)
		(end 110.222284 -195.034662)
		(width 0.14732)
		(layer "In6.Cu")
		(net "UPI_CPU1_CPU0_P0P1_DN<16>")
	)
	(segment
		(start 110.723426 -194.600322)
		(end 110.995206 -194.25793)
		(width 0.14732)
		(layer "In6.Cu")
		(net "UPI_CPU1_CPU0_P0P1_DN<16>")
	)
	(segment
		(start 344.696034 -170.031664)
		(end 343.864184 -170.994324)
		(width 0.14732)
		(layer "In6.Cu")
		(net "UPI_CPU1_CPU0_P0P1_DN<16>")
	)
	(segment
		(start 117.33149 -186.08548)
		(end 132.21462 -172.09135)
		(width 0.14732)
		(layer "In6.Cu")
		(net "UPI_CPU1_CPU0_P0P1_DN<16>")
	)
	(segment
		(start 104.216962 -213.93023)
		(end 104.216962 -211.82457)
		(width 0.0889)
		(layer "In6.Cu")
		(net "UPI_CPU1_CPU0_P0P1_DN<16>")
	)
	(segment
		(start 238.10087 -152.364948)
		(end 276.60854 -162.255708)
		(width 0.14732)
		(layer "In6.Cu")
		(net "UPI_CPU1_CPU0_P0P1_DN<16>")
	)
	(segment
		(start 344.948764 -171.931838)
		(end 345.780614 -170.969178)
		(width 0.14732)
		(layer "In6.Cu")
		(net "UPI_CPU1_CPU0_P0P1_DN<16>")
	)
	(segment
		(start 190.923926 -162.245548)
		(end 194.572128 -162.245548)
		(width 0.14732)
		(layer "In6.Cu")
		(net "UPI_CPU1_CPU0_P0P1_DN<16>")
	)
	(segment
		(start 114.894868 -189.348618)
		(end 115.166902 -189.006226)
		(width 0.14732)
		(layer "In6.Cu")
		(net "UPI_CPU1_CPU0_P0P1_DN<16>")
	)
	(segment
		(start 115.166902 -189.006226)
		(end 115.147344 -188.834776)
		(width 0.14732)
		(layer "In6.Cu")
		(net "UPI_CPU1_CPU0_P0P1_DN<16>")
	)
	(segment
		(start 345.988132 -170.954192)
		(end 347.665802 -172.404278)
		(width 0.14732)
		(layer "In6.Cu")
		(net "UPI_CPU1_CPU0_P0P1_DN<16>")
	)
	(segment
		(start 344.681048 -169.824146)
		(end 344.696034 -170.031664)
		(width 0.14732)
		(layer "In6.Cu")
		(net "UPI_CPU1_CPU0_P0P1_DN<16>")
	)
	(segment
		(start 112.63757 -191.994028)
		(end 112.80902 -191.974216)
		(width 0.14732)
		(layer "In6.Cu")
		(net "UPI_CPU1_CPU0_P0P1_DN<16>")
	)
	(segment
		(start 111.418624 -193.724784)
		(end 111.690658 -193.382646)
		(width 0.14732)
		(layer "In6.Cu")
		(net "UPI_CPU1_CPU0_P0P1_DN<16>")
	)
	(segment
		(start 342.927686 -168.308528)
		(end 342.942672 -168.516046)
		(width 0.14732)
		(layer "In6.Cu")
		(net "UPI_CPU1_CPU0_P0P1_DN<16>")
	)
	(segment
		(start 114.47145 -189.88151)
		(end 114.451892 -189.71006)
		(width 0.14732)
		(layer "In6.Cu")
		(net "UPI_CPU1_CPU0_P0P1_DN<16>")
	)
	(segment
		(start 326.089264 -153.973276)
		(end 328.288396 -155.654502)
		(width 0.14732)
		(layer "In6.Cu")
		(net "UPI_CPU1_CPU0_P0P1_DN<16>")
	)
	(segment
		(start 110.222284 -195.034662)
		(end 110.222538 -195.034662)
		(width 0.14732)
		(layer "In6.Cu")
		(net "UPI_CPU1_CPU0_P0P1_DN<16>")
	)
	(segment
		(start 344.027252 -169.45356)
		(end 344.23477 -169.438574)
		(width 0.14732)
		(layer "In6.Cu")
		(net "UPI_CPU1_CPU0_P0P1_DN<16>")
	)
	(segment
		(start 342.142318 -169.912538)
		(end 342.76157 -170.447716)
		(width 0.14732)
		(layer "In6.Cu")
		(net "UPI_CPU1_CPU0_P0P1_DN<16>")
	)
	(segment
		(start 342.76157 -170.447716)
		(end 343.195402 -170.41622)
		(width 0.14732)
		(layer "In6.Cu")
		(net "UPI_CPU1_CPU0_P0P1_DN<16>")
	)
	(segment
		(start 110.551976 -194.61988)
		(end 110.723426 -194.600322)
		(width 0.14732)
		(layer "In6.Cu")
		(net "UPI_CPU1_CPU0_P0P1_DN<16>")
	)
	(segment
		(start 104.121458 -214.622634)
		(end 103.962708 -214.321644)
		(width 0.0889)
		(layer "In6.Cu")
		(net "UPI_CPU1_CPU0_P0P1_DN<16>")
	)
	(arc
		(start 103.992934 -214.22487)
		(mid 104.11568 -214.111365)
		(end 104.20223 -213.96833)
		(width 0.0889)
		(layer "In6.Cu")
		(net "UPI_CPU1_CPU0_P0P1_DN<16>")
	)
	(arc
		(start 104.20223 -213.96833)
		(mid 104.210065 -213.949031)
		(end 104.217216 -213.929468)
		(width 0.0889)
		(layer "In6.Cu")
		(net "UPI_CPU1_CPU0_P0P1_DN<16>")
	)
	(segment
		(start 368.97818 -215.158574)
		(end 368.822986 -214.889588)
		(width 0.0889)
		(layer "F.Cu")
		(net "UPI_CPU1_CPU0_P0P1_DN<15>")
	)
	(segment
		(start 354.621084 -173.72076)
		(end 353.606862 -173.301152)
		(width 0.13208)
		(layer "F.Cu")
		(net "UPI_CPU1_CPU0_P0P1_DN<15>")
	)
	(segment
		(start 360.719878 -199.966326)
		(end 361.710732 -194.984624)
		(width 0.13208)
		(layer "F.Cu")
		(net "UPI_CPU1_CPU0_P0P1_DN<15>")
	)
	(segment
		(start 103.181912 -214.622888)
		(end 103.181658 -214.622634)
		(width 0.13208)
		(layer "F.Cu")
		(net "UPI_CPU1_CPU0_P0P1_DN<15>")
	)
	(segment
		(start 353.606862 -173.301152)
		(end 353.277932 -172.972222)
		(width 0.13208)
		(layer "F.Cu")
		(net "UPI_CPU1_CPU0_P0P1_DN<15>")
	)
	(segment
		(start 364.87989 -186.32551)
		(end 364.87989 -184.043066)
		(width 0.13208)
		(layer "F.Cu")
		(net "UPI_CPU1_CPU0_P0P1_DN<15>")
	)
	(segment
		(start 353.253548 -172.786294)
		(end 353.321112 -172.668946)
		(width 0.13208)
		(layer "F.Cu")
		(net "UPI_CPU1_CPU0_P0P1_DN<15>")
	)
	(segment
		(start 103.181912 -215.158574)
		(end 103.181912 -214.622888)
		(width 0.13208)
		(layer "F.Cu")
		(net "UPI_CPU1_CPU0_P0P1_DN<15>")
	)
	(segment
		(start 360.685334 -205.261718)
		(end 360.719878 -205.227174)
		(width 0.0889)
		(layer "F.Cu")
		(net "UPI_CPU1_CPU0_P0P1_DN<15>")
	)
	(segment
		(start 353.321112 -172.668946)
		(end 353.32162 -172.668184)
		(width 0.13208)
		(layer "F.Cu")
		(net "UPI_CPU1_CPU0_P0P1_DN<15>")
	)
	(segment
		(start 355.487224 -174.299372)
		(end 355.452934 -174.126652)
		(width 0.13208)
		(layer "F.Cu")
		(net "UPI_CPU1_CPU0_P0P1_DN<15>")
	)
	(segment
		(start 368.822986 -214.889588)
		(end 368.848132 -214.796878)
		(width 0.0889)
		(layer "F.Cu")
		(net "UPI_CPU1_CPU0_P0P1_DN<15>")
	)
	(segment
		(start 369.07343 -214.344504)
		(end 369.07343 -212.761322)
		(width 0.0889)
		(layer "F.Cu")
		(net "UPI_CPU1_CPU0_P0P1_DN<15>")
	)
	(segment
		(start 353.32162 -172.668184)
		(end 353.874324 -172.518832)
		(width 0.13208)
		(layer "F.Cu")
		(net "UPI_CPU1_CPU0_P0P1_DN<15>")
	)
	(segment
		(start 354.950522 -173.940724)
		(end 354.621084 -173.72076)
		(width 0.13208)
		(layer "F.Cu")
		(net "UPI_CPU1_CPU0_P0P1_DN<15>")
	)
	(segment
		(start 369.07343 -212.761322)
		(end 365.296958 -208.984596)
		(width 0.0889)
		(layer "F.Cu")
		(net "UPI_CPU1_CPU0_P0P1_DN<15>")
	)
	(segment
		(start 364.494064 -188.265562)
		(end 364.87989 -186.32551)
		(width 0.13208)
		(layer "F.Cu")
		(net "UPI_CPU1_CPU0_P0P1_DN<15>")
	)
	(segment
		(start 364.325916 -182.705502)
		(end 356.790752 -175.170084)
		(width 0.13208)
		(layer "F.Cu")
		(net "UPI_CPU1_CPU0_P0P1_DN<15>")
	)
	(segment
		(start 353.277932 -172.972222)
		(end 353.253548 -172.786294)
		(width 0.13208)
		(layer "F.Cu")
		(net "UPI_CPU1_CPU0_P0P1_DN<15>")
	)
	(segment
		(start 362.998258 -208.03235)
		(end 360.685334 -205.719426)
		(width 0.0889)
		(layer "F.Cu")
		(net "UPI_CPU1_CPU0_P0P1_DN<15>")
	)
	(segment
		(start 361.710732 -194.984624)
		(end 364.494064 -188.265562)
		(width 0.13208)
		(layer "F.Cu")
		(net "UPI_CPU1_CPU0_P0P1_DN<15>")
	)
	(segment
		(start 364.87989 -184.043066)
		(end 364.325916 -182.705502)
		(width 0.13208)
		(layer "F.Cu")
		(net "UPI_CPU1_CPU0_P0P1_DN<15>")
	)
	(segment
		(start 356.790752 -175.170084)
		(end 355.487224 -174.299372)
		(width 0.13208)
		(layer "F.Cu")
		(net "UPI_CPU1_CPU0_P0P1_DN<15>")
	)
	(segment
		(start 355.452934 -174.126652)
		(end 355.122988 -173.906434)
		(width 0.13208)
		(layer "F.Cu")
		(net "UPI_CPU1_CPU0_P0P1_DN<15>")
	)
	(segment
		(start 355.122988 -173.906434)
		(end 354.950522 -173.940724)
		(width 0.13208)
		(layer "F.Cu")
		(net "UPI_CPU1_CPU0_P0P1_DN<15>")
	)
	(segment
		(start 365.296958 -208.984596)
		(end 362.998258 -208.03235)
		(width 0.0889)
		(layer "F.Cu")
		(net "UPI_CPU1_CPU0_P0P1_DN<15>")
	)
	(segment
		(start 360.719878 -205.227174)
		(end 360.719878 -205.205076)
		(width 0.0889)
		(layer "F.Cu")
		(net "UPI_CPU1_CPU0_P0P1_DN<15>")
	)
	(segment
		(start 360.719878 -205.205076)
		(end 360.719878 -199.966326)
		(width 0.13208)
		(layer "F.Cu")
		(net "UPI_CPU1_CPU0_P0P1_DN<15>")
	)
	(segment
		(start 360.685334 -205.719426)
		(end 360.685334 -205.261718)
		(width 0.0889)
		(layer "F.Cu")
		(net "UPI_CPU1_CPU0_P0P1_DN<15>")
	)
	(segment
		(start 369.073684 -214.344758)
		(end 369.07343 -214.344504)
		(width 0.0889)
		(layer "F.Cu")
		(net "UPI_CPU1_CPU0_P0P1_DN<15>")
	)
	(arc
		(start 368.865404 -214.783416)
		(mid 369.019033 -214.587592)
		(end 369.073684 -214.344758)
		(width 0.0889)
		(layer "F.Cu")
		(net "UPI_CPU1_CPU0_P0P1_DN<15>")
	)
	(arc
		(start 368.848132 -214.796878)
		(mid 368.856832 -214.790229)
		(end 368.865404 -214.783416)
		(width 0.0889)
		(layer "F.Cu")
		(net "UPI_CPU1_CPU0_P0P1_DN<15>")
	)
	(segment
		(start 340.49208 -164.314632)
		(end 340.320376 -164.514022)
		(width 0.14732)
		(layer "In6.Cu")
		(net "UPI_CPU1_CPU0_P0P1_DN<15>")
	)
	(segment
		(start 103.277416 -212.784944)
		(end 103.37673 -212.68563)
		(width 0.0889)
		(layer "In6.Cu")
		(net "UPI_CPU1_CPU0_P0P1_DN<15>")
	)
	(segment
		(start 323.625972 -152.491948)
		(end 326.460358 -153.204418)
		(width 0.14732)
		(layer "In6.Cu")
		(net "UPI_CPU1_CPU0_P0P1_DN<15>")
	)
	(segment
		(start 109.76483 -194.064382)
		(end 109.93628 -194.04457)
		(width 0.14732)
		(layer "In6.Cu")
		(net "UPI_CPU1_CPU0_P0P1_DN<15>")
	)
	(segment
		(start 339.822028 -163.73729)
		(end 340.029546 -163.72205)
		(width 0.14732)
		(layer "In6.Cu")
		(net "UPI_CPU1_CPU0_P0P1_DN<15>")
	)
	(segment
		(start 103.277416 -213.516972)
		(end 103.37673 -213.417658)
		(width 0.0889)
		(layer "In6.Cu")
		(net "UPI_CPU1_CPU0_P0P1_DN<15>")
	)
	(segment
		(start 191.472312 -161.409888)
		(end 194.51955 -161.409888)
		(width 0.14732)
		(layer "In6.Cu")
		(net "UPI_CPU1_CPU0_P0P1_DN<15>")
	)
	(segment
		(start 173.89729 -152.21458)
		(end 191.472312 -161.409888)
		(width 0.14732)
		(layer "In6.Cu")
		(net "UPI_CPU1_CPU0_P0P1_DN<15>")
	)
	(segment
		(start 338.273898 -162.209226)
		(end 338.721192 -162.594544)
		(width 0.14732)
		(layer "In6.Cu")
		(net "UPI_CPU1_CPU0_P0P1_DN<15>")
	)
	(segment
		(start 351.141538 -172.374306)
		(end 352.004376 -172.93209)
		(width 0.14732)
		(layer "In6.Cu")
		(net "UPI_CPU1_CPU0_P0P1_DN<15>")
	)
	(segment
		(start 340.352634 -164.948362)
		(end 348.121986 -171.642532)
		(width 0.14732)
		(layer "In6.Cu")
		(net "UPI_CPU1_CPU0_P0P1_DN<15>")
	)
	(segment
		(start 103.31958 -211.782406)
		(end 103.31958 -211.77123)
		(width 0.0889)
		(layer "In6.Cu")
		(net "UPI_CPU1_CPU0_P0P1_DN<15>")
	)
	(segment
		(start 353.333812 -172.663612)
		(end 353.874324 -172.518832)
		(width 0.14732)
		(layer "In6.Cu")
		(net "UPI_CPU1_CPU0_P0P1_DN<15>")
	)
	(segment
		(start 276.714458 -161.420048)
		(end 279.468834 -161.420048)
		(width 0.14732)
		(layer "In6.Cu")
		(net "UPI_CPU1_CPU0_P0P1_DN<15>")
	)
	(segment
		(start 352.998024 -173.088808)
		(end 353.21113 -172.875956)
		(width 0.14732)
		(layer "In6.Cu")
		(net "UPI_CPU1_CPU0_P0P1_DN<15>")
	)
	(segment
		(start 103.277416 -213.051644)
		(end 103.277416 -212.784944)
		(width 0.0889)
		(layer "In6.Cu")
		(net "UPI_CPU1_CPU0_P0P1_DN<15>")
	)
	(segment
		(start 238.206788 -151.529288)
		(end 276.714458 -161.420048)
		(width 0.14732)
		(layer "In6.Cu")
		(net "UPI_CPU1_CPU0_P0P1_DN<15>")
	)
	(segment
		(start 338.564728 -163.001198)
		(end 338.59724 -163.435284)
		(width 0.14732)
		(layer "In6.Cu")
		(net "UPI_CPU1_CPU0_P0P1_DN<15>")
	)
	(segment
		(start 166.634414 -150.358856)
		(end 170.349164 -150.457154)
		(width 0.14732)
		(layer "In6.Cu")
		(net "UPI_CPU1_CPU0_P0P1_DN<15>")
	)
	(segment
		(start 338.736432 -162.801808)
		(end 338.564728 -163.001198)
		(width 0.14732)
		(layer "In6.Cu")
		(net "UPI_CPU1_CPU0_P0P1_DN<15>")
	)
	(segment
		(start 103.31958 -211.77123)
		(end 103.31958 -211.35467)
		(width 0.14732)
		(layer "In6.Cu")
		(net "UPI_CPU1_CPU0_P0P1_DN<15>")
	)
	(segment
		(start 103.181658 -214.622634)
		(end 103.025194 -214.893652)
		(width 0.0889)
		(layer "In6.Cu")
		(net "UPI_CPU1_CPU0_P0P1_DN<15>")
	)
	(segment
		(start 279.468834 -161.420048)
		(end 322.084954 -152.491948)
		(width 0.14732)
		(layer "In6.Cu")
		(net "UPI_CPU1_CPU0_P0P1_DN<15>")
	)
	(segment
		(start 110.188502 -193.530982)
		(end 116.10594 -186.082432)
		(width 0.14732)
		(layer "In6.Cu")
		(net "UPI_CPU1_CPU0_P0P1_DN<15>")
	)
	(segment
		(start 170.349164 -150.457154)
		(end 173.89729 -152.21458)
		(width 0.14732)
		(layer "In6.Cu")
		(net "UPI_CPU1_CPU0_P0P1_DN<15>")
	)
	(segment
		(start 196.783198 -161.124138)
		(end 234.002326 -151.529288)
		(width 0.14732)
		(layer "In6.Cu")
		(net "UPI_CPU1_CPU0_P0P1_DN<15>")
	)
	(segment
		(start 326.460358 -153.204418)
		(end 328.802492 -154.995372)
		(width 0.14732)
		(layer "In6.Cu")
		(net "UPI_CPU1_CPU0_P0P1_DN<15>")
	)
	(segment
		(start 353.21113 -172.875956)
		(end 353.333304 -172.664374)
		(width 0.14732)
		(layer "In6.Cu")
		(net "UPI_CPU1_CPU0_P0P1_DN<15>")
	)
	(segment
		(start 338.06638 -162.224466)
		(end 338.273898 -162.209226)
		(width 0.14732)
		(layer "In6.Cu")
		(net "UPI_CPU1_CPU0_P0P1_DN<15>")
	)
	(segment
		(start 164.8841 -150.970234)
		(end 166.634414 -150.358856)
		(width 0.14732)
		(layer "In6.Cu")
		(net "UPI_CPU1_CPU0_P0P1_DN<15>")
	)
	(segment
		(start 352.432112 -173.088808)
		(end 352.998024 -173.088808)
		(width 0.14732)
		(layer "In6.Cu")
		(net "UPI_CPU1_CPU0_P0P1_DN<15>")
	)
	(segment
		(start 131.699254 -171.420028)
		(end 164.8841 -150.970234)
		(width 0.14732)
		(layer "In6.Cu")
		(net "UPI_CPU1_CPU0_P0P1_DN<15>")
	)
	(segment
		(start 339.650324 -163.936426)
		(end 339.822028 -163.73729)
		(width 0.14732)
		(layer "In6.Cu")
		(net "UPI_CPU1_CPU0_P0P1_DN<15>")
	)
	(segment
		(start 109.49305 -194.406266)
		(end 109.493304 -194.406266)
		(width 0.14732)
		(layer "In6.Cu")
		(net "UPI_CPU1_CPU0_P0P1_DN<15>")
	)
	(segment
		(start 103.37673 -212.41893)
		(end 103.277416 -212.319616)
		(width 0.0889)
		(layer "In6.Cu")
		(net "UPI_CPU1_CPU0_P0P1_DN<15>")
	)
	(segment
		(start 234.002326 -151.529288)
		(end 238.206788 -151.529288)
		(width 0.14732)
		(layer "In6.Cu")
		(net "UPI_CPU1_CPU0_P0P1_DN<15>")
	)
	(segment
		(start 116.10594 -186.082432)
		(end 131.699254 -171.420028)
		(width 0.14732)
		(layer "In6.Cu")
		(net "UPI_CPU1_CPU0_P0P1_DN<15>")
	)
	(segment
		(start 340.47684 -164.107368)
		(end 340.49208 -164.314632)
		(width 0.14732)
		(layer "In6.Cu")
		(net "UPI_CPU1_CPU0_P0P1_DN<15>")
	)
	(segment
		(start 103.277416 -213.929468)
		(end 103.277416 -213.516972)
		(width 0.0889)
		(layer "In6.Cu")
		(net "UPI_CPU1_CPU0_P0P1_DN<15>")
	)
	(segment
		(start 109.493304 -194.406266)
		(end 109.76483 -194.064382)
		(width 0.14732)
		(layer "In6.Cu")
		(net "UPI_CPU1_CPU0_P0P1_DN<15>")
	)
	(segment
		(start 337.894676 -162.423602)
		(end 338.06638 -162.224466)
		(width 0.14732)
		(layer "In6.Cu")
		(net "UPI_CPU1_CPU0_P0P1_DN<15>")
	)
	(segment
		(start 103.277416 -211.82457)
		(end 103.31958 -211.782406)
		(width 0.0889)
		(layer "In6.Cu")
		(net "UPI_CPU1_CPU0_P0P1_DN<15>")
	)
	(segment
		(start 338.721192 -162.594544)
		(end 338.736432 -162.801808)
		(width 0.14732)
		(layer "In6.Cu")
		(net "UPI_CPU1_CPU0_P0P1_DN<15>")
	)
	(segment
		(start 109.93628 -194.04457)
		(end 110.208314 -193.702432)
		(width 0.14732)
		(layer "In6.Cu")
		(net "UPI_CPU1_CPU0_P0P1_DN<15>")
	)
	(segment
		(start 103.277416 -212.319616)
		(end 103.277416 -211.82457)
		(width 0.0889)
		(layer "In6.Cu")
		(net "UPI_CPU1_CPU0_P0P1_DN<15>")
	)
	(segment
		(start 348.121986 -171.642532)
		(end 351.141538 -172.374306)
		(width 0.14732)
		(layer "In6.Cu")
		(net "UPI_CPU1_CPU0_P0P1_DN<15>")
	)
	(segment
		(start 103.025194 -214.893652)
		(end 102.946962 -214.91448)
		(width 0.0889)
		(layer "In6.Cu")
		(net "UPI_CPU1_CPU0_P0P1_DN<15>")
	)
	(segment
		(start 103.37673 -213.150958)
		(end 103.277416 -213.051644)
		(width 0.0889)
		(layer "In6.Cu")
		(net "UPI_CPU1_CPU0_P0P1_DN<15>")
	)
	(segment
		(start 103.31958 -211.35467)
		(end 106.479848 -202.6793)
		(width 0.14732)
		(layer "In6.Cu")
		(net "UPI_CPU1_CPU0_P0P1_DN<15>")
	)
	(segment
		(start 328.802492 -154.995372)
		(end 337.46059 -162.456114)
		(width 0.14732)
		(layer "In6.Cu")
		(net "UPI_CPU1_CPU0_P0P1_DN<15>")
	)
	(segment
		(start 103.37673 -212.68563)
		(end 103.37673 -212.41893)
		(width 0.0889)
		(layer "In6.Cu")
		(net "UPI_CPU1_CPU0_P0P1_DN<15>")
	)
	(segment
		(start 322.084954 -152.491948)
		(end 323.625972 -152.491948)
		(width 0.14732)
		(layer "In6.Cu")
		(net "UPI_CPU1_CPU0_P0P1_DN<15>")
	)
	(segment
		(start 340.320376 -164.514022)
		(end 340.352634 -164.948362)
		(width 0.14732)
		(layer "In6.Cu")
		(net "UPI_CPU1_CPU0_P0P1_DN<15>")
	)
	(segment
		(start 340.029546 -163.72205)
		(end 340.47684 -164.107368)
		(width 0.14732)
		(layer "In6.Cu")
		(net "UPI_CPU1_CPU0_P0P1_DN<15>")
	)
	(segment
		(start 102.807008 -214.622634)
		(end 102.807008 -214.461852)
		(width 0.0889)
		(layer "In6.Cu")
		(net "UPI_CPU1_CPU0_P0P1_DN<15>")
	)
	(segment
		(start 353.333304 -172.664374)
		(end 353.333812 -172.663612)
		(width 0.14732)
		(layer "In6.Cu")
		(net "UPI_CPU1_CPU0_P0P1_DN<15>")
	)
	(segment
		(start 337.46059 -162.456114)
		(end 337.894676 -162.423602)
		(width 0.14732)
		(layer "In6.Cu")
		(net "UPI_CPU1_CPU0_P0P1_DN<15>")
	)
	(segment
		(start 194.51955 -161.409888)
		(end 196.783198 -161.124138)
		(width 0.14732)
		(layer "In6.Cu")
		(net "UPI_CPU1_CPU0_P0P1_DN<15>")
	)
	(segment
		(start 106.479594 -202.6793)
		(end 109.49305 -194.406266)
		(width 0.14732)
		(layer "In6.Cu")
		(net "UPI_CPU1_CPU0_P0P1_DN<15>")
	)
	(segment
		(start 339.216238 -163.968938)
		(end 339.650324 -163.936426)
		(width 0.14732)
		(layer "In6.Cu")
		(net "UPI_CPU1_CPU0_P0P1_DN<15>")
	)
	(segment
		(start 110.208314 -193.702432)
		(end 110.188502 -193.530982)
		(width 0.14732)
		(layer "In6.Cu")
		(net "UPI_CPU1_CPU0_P0P1_DN<15>")
	)
	(segment
		(start 352.004376 -172.93209)
		(end 352.432112 -173.088808)
		(width 0.14732)
		(layer "In6.Cu")
		(net "UPI_CPU1_CPU0_P0P1_DN<15>")
	)
	(segment
		(start 103.37673 -213.417658)
		(end 103.37673 -213.150958)
		(width 0.0889)
		(layer "In6.Cu")
		(net "UPI_CPU1_CPU0_P0P1_DN<15>")
	)
	(segment
		(start 106.479848 -202.6793)
		(end 106.479594 -202.6793)
		(width 0.14732)
		(layer "In6.Cu")
		(net "UPI_CPU1_CPU0_P0P1_DN<15>")
	)
	(segment
		(start 338.59724 -163.435284)
		(end 339.216238 -163.968938)
		(width 0.14732)
		(layer "In6.Cu")
		(net "UPI_CPU1_CPU0_P0P1_DN<15>")
	)
	(arc
		(start 102.946962 -214.91448)
		(mid 102.843817 -214.784455)
		(end 102.807008 -214.622634)
		(width 0.0889)
		(layer "In6.Cu")
		(net "UPI_CPU1_CPU0_P0P1_DN<15>")
	)
	(arc
		(start 102.991412 -214.261954)
		(mid 103.151993 -214.138523)
		(end 103.262176 -213.968584)
		(width 0.0889)
		(layer "In6.Cu")
		(net "UPI_CPU1_CPU0_P0P1_DN<15>")
	)
	(arc
		(start 102.807008 -214.461852)
		(mid 102.882079 -214.34611)
		(end 102.991412 -214.261954)
		(width 0.0889)
		(layer "In6.Cu")
		(net "UPI_CPU1_CPU0_P0P1_DN<15>")
	)
	(arc
		(start 103.262176 -213.968584)
		(mid 103.270141 -213.94916)
		(end 103.277416 -213.929468)
		(width 0.0889)
		(layer "In6.Cu")
		(net "UPI_CPU1_CPU0_P0P1_DN<15>")
	)
	(segment
		(start 350.015302 -170.759374)
		(end 349.94215 -170.633644)
		(width 0.13208)
		(layer "F.Cu")
		(net "UPI_CPU1_CPU0_P0P1_DN<14>")
	)
	(segment
		(start 361.993434 -205.261718)
		(end 362.027978 -205.227174)
		(width 0.0889)
		(layer "F.Cu")
		(net "UPI_CPU1_CPU0_P0P1_DN<14>")
	)
	(segment
		(start 351.958656 -170.83405)
		(end 351.827338 -170.965368)
		(width 0.13208)
		(layer "F.Cu")
		(net "UPI_CPU1_CPU0_P0P1_DN<14>")
	)
	(segment
		(start 369.894104 -212.826092)
		(end 369.894104 -212.673692)
		(width 0.0889)
		(layer "F.Cu")
		(net "UPI_CPU1_CPU0_P0P1_DN<14>")
	)
	(segment
		(start 369.795044 -212.925152)
		(end 369.894104 -212.826092)
		(width 0.0889)
		(layer "F.Cu")
		(net "UPI_CPU1_CPU0_P0P1_DN<14>")
	)
	(segment
		(start 350.370394 -170.965368)
		(end 350.015302 -170.759374)
		(width 0.13208)
		(layer "F.Cu")
		(net "UPI_CPU1_CPU0_P0P1_DN<14>")
	)
	(segment
		(start 351.827338 -170.965368)
		(end 350.370394 -170.965368)
		(width 0.13208)
		(layer "F.Cu")
		(net "UPI_CPU1_CPU0_P0P1_DN<14>")
	)
	(segment
		(start 369.795044 -213.23554)
		(end 369.795044 -212.925152)
		(width 0.0889)
		(layer "F.Cu")
		(net "UPI_CPU1_CPU0_P0P1_DN<14>")
	)
	(segment
		(start 364.050072 -207.70723)
		(end 361.993434 -205.650592)
		(width 0.0889)
		(layer "F.Cu")
		(net "UPI_CPU1_CPU0_P0P1_DN<14>")
	)
	(segment
		(start 369.894104 -212.673692)
		(end 369.79479 -212.574378)
		(width 0.0889)
		(layer "F.Cu")
		(net "UPI_CPU1_CPU0_P0P1_DN<14>")
	)
	(segment
		(start 362.027978 -205.205076)
		(end 362.027978 -200.1266)
		(width 0.13208)
		(layer "F.Cu")
		(net "UPI_CPU1_CPU0_P0P1_DN<14>")
	)
	(segment
		(start 361.993434 -205.650592)
		(end 361.993434 -205.261718)
		(width 0.0889)
		(layer "F.Cu")
		(net "UPI_CPU1_CPU0_P0P1_DN<14>")
	)
	(segment
		(start 370.013484 -213.45398)
		(end 369.795044 -213.23554)
		(width 0.0889)
		(layer "F.Cu")
		(net "UPI_CPU1_CPU0_P0P1_DN<14>")
	)
	(segment
		(start 369.79479 -212.405976)
		(end 365.8362 -208.447386)
		(width 0.0889)
		(layer "F.Cu")
		(net "UPI_CPU1_CPU0_P0P1_DN<14>")
	)
	(segment
		(start 365.514636 -181.978808)
		(end 358.041194 -174.505366)
		(width 0.13208)
		(layer "F.Cu")
		(net "UPI_CPU1_CPU0_P0P1_DN<14>")
	)
	(segment
		(start 369.79479 -212.574378)
		(end 369.79479 -212.405976)
		(width 0.0889)
		(layer "F.Cu")
		(net "UPI_CPU1_CPU0_P0P1_DN<14>")
	)
	(segment
		(start 362.027978 -200.1266)
		(end 362.982764 -195.326)
		(width 0.13208)
		(layer "F.Cu")
		(net "UPI_CPU1_CPU0_P0P1_DN<14>")
	)
	(segment
		(start 370.013484 -213.9569)
		(end 370.112544 -213.85784)
		(width 0.0889)
		(layer "F.Cu")
		(net "UPI_CPU1_CPU0_P0P1_DN<14>")
	)
	(segment
		(start 349.94215 -170.633644)
		(end 349.941896 -170.632882)
		(width 0.13208)
		(layer "F.Cu")
		(net "UPI_CPU1_CPU0_P0P1_DN<14>")
	)
	(segment
		(start 365.8362 -208.447386)
		(end 364.050072 -207.70723)
		(width 0.0889)
		(layer "F.Cu")
		(net "UPI_CPU1_CPU0_P0P1_DN<14>")
	)
	(segment
		(start 370.013484 -214.345266)
		(end 370.013484 -213.9569)
		(width 0.0889)
		(layer "F.Cu")
		(net "UPI_CPU1_CPU0_P0P1_DN<14>")
	)
	(segment
		(start 370.013484 -213.60638)
		(end 370.013484 -213.45398)
		(width 0.0889)
		(layer "F.Cu")
		(net "UPI_CPU1_CPU0_P0P1_DN<14>")
	)
	(segment
		(start 362.027978 -205.227174)
		(end 362.027978 -205.205076)
		(width 0.0889)
		(layer "F.Cu")
		(net "UPI_CPU1_CPU0_P0P1_DN<14>")
	)
	(segment
		(start 362.982764 -195.326)
		(end 365.75111 -188.642752)
		(width 0.13208)
		(layer "F.Cu")
		(net "UPI_CPU1_CPU0_P0P1_DN<14>")
	)
	(segment
		(start 101.772466 -214.344758)
		(end 101.772466 -213.732618)
		(width 0.13208)
		(layer "F.Cu")
		(net "UPI_CPU1_CPU0_P0P1_DN<14>")
	)
	(segment
		(start 349.941896 -170.632882)
		(end 350.089724 -170.080432)
		(width 0.13208)
		(layer "F.Cu")
		(net "UPI_CPU1_CPU0_P0P1_DN<14>")
	)
	(segment
		(start 365.75111 -188.642752)
		(end 366.197896 -186.39663)
		(width 0.13208)
		(layer "F.Cu")
		(net "UPI_CPU1_CPU0_P0P1_DN<14>")
	)
	(segment
		(start 358.041194 -174.505366)
		(end 354.048568 -171.22775)
		(width 0.13208)
		(layer "F.Cu")
		(net "UPI_CPU1_CPU0_P0P1_DN<14>")
	)
	(segment
		(start 352.749866 -170.83405)
		(end 351.958656 -170.83405)
		(width 0.13208)
		(layer "F.Cu")
		(net "UPI_CPU1_CPU0_P0P1_DN<14>")
	)
	(segment
		(start 366.197896 -183.628538)
		(end 365.514636 -181.978808)
		(width 0.13208)
		(layer "F.Cu")
		(net "UPI_CPU1_CPU0_P0P1_DN<14>")
	)
	(segment
		(start 370.112544 -213.70544)
		(end 370.013484 -213.60638)
		(width 0.0889)
		(layer "F.Cu")
		(net "UPI_CPU1_CPU0_P0P1_DN<14>")
	)
	(segment
		(start 369.762786 -215.42756)
		(end 369.68176 -215.44915)
		(width 0.0889)
		(layer "F.Cu")
		(net "UPI_CPU1_CPU0_P0P1_DN<14>")
	)
	(segment
		(start 366.197896 -186.39663)
		(end 366.197896 -183.628538)
		(width 0.13208)
		(layer "F.Cu")
		(net "UPI_CPU1_CPU0_P0P1_DN<14>")
	)
	(segment
		(start 354.048568 -171.22775)
		(end 352.749866 -170.83405)
		(width 0.13208)
		(layer "F.Cu")
		(net "UPI_CPU1_CPU0_P0P1_DN<14>")
	)
	(segment
		(start 369.91798 -215.158574)
		(end 369.762786 -215.42756)
		(width 0.0889)
		(layer "F.Cu")
		(net "UPI_CPU1_CPU0_P0P1_DN<14>")
	)
	(segment
		(start 370.112544 -213.85784)
		(end 370.112544 -213.70544)
		(width 0.0889)
		(layer "F.Cu")
		(net "UPI_CPU1_CPU0_P0P1_DN<14>")
	)
	(arc
		(start 369.741958 -214.827612)
		(mid 369.743104 -214.826982)
		(end 369.744244 -214.826342)
		(width 0.0889)
		(layer "F.Cu")
		(net "UPI_CPU1_CPU0_P0P1_DN<14>")
	)
	(arc
		(start 369.750086 -214.822532)
		(mid 369.943198 -214.61777)
		(end 370.013484 -214.345266)
		(width 0.0889)
		(layer "F.Cu")
		(net "UPI_CPU1_CPU0_P0P1_DN<14>")
	)
	(arc
		(start 369.54333 -215.158574)
		(mid 369.596736 -214.965538)
		(end 369.741958 -214.827612)
		(width 0.0889)
		(layer "F.Cu")
		(net "UPI_CPU1_CPU0_P0P1_DN<14>")
	)
	(arc
		(start 369.68176 -215.44915)
		(mid 369.579739 -215.319488)
		(end 369.54333 -215.158574)
		(width 0.0889)
		(layer "F.Cu")
		(net "UPI_CPU1_CPU0_P0P1_DN<14>")
	)
	(arc
		(start 369.744244 -214.826342)
		(mid 369.747171 -214.824446)
		(end 369.750086 -214.822532)
		(width 0.0889)
		(layer "F.Cu")
		(net "UPI_CPU1_CPU0_P0P1_DN<14>")
	)
	(segment
		(start 349.327216 -169.708068)
		(end 349.550482 -169.931334)
		(width 0.14732)
		(layer "In6.Cu")
		(net "UPI_CPU1_CPU0_P0P1_DN<14>")
	)
	(segment
		(start 114.634264 -185.945526)
		(end 131.061968 -170.499532)
		(width 0.14732)
		(layer "In6.Cu")
		(net "UPI_CPU1_CPU0_P0P1_DN<14>")
	)
	(segment
		(start 102.047802 -213.133178)
		(end 102.147116 -213.033864)
		(width 0.0889)
		(layer "In6.Cu")
		(net "UPI_CPU1_CPU0_P0P1_DN<14>")
	)
	(segment
		(start 345.058746 -167.214042)
		(end 345.666822 -167.746172)
		(width 0.14732)
		(layer "In6.Cu")
		(net "UPI_CPU1_CPU0_P0P1_DN<14>")
	)
	(segment
		(start 347.572838 -169.347388)
		(end 349.327216 -169.708068)
		(width 0.14732)
		(layer "In6.Cu")
		(net "UPI_CPU1_CPU0_P0P1_DN<14>")
	)
	(segment
		(start 342.348566 -163.816538)
		(end 345.058746 -167.214042)
		(width 0.14732)
		(layer "In6.Cu")
		(net "UPI_CPU1_CPU0_P0P1_DN<14>")
	)
	(segment
		(start 279.181052 -160.317688)
		(end 321.966844 -151.354028)
		(width 0.14732)
		(layer "In6.Cu")
		(net "UPI_CPU1_CPU0_P0P1_DN<14>")
	)
	(segment
		(start 102.147116 -213.499192)
		(end 102.047802 -213.399878)
		(width 0.0889)
		(layer "In6.Cu")
		(net "UPI_CPU1_CPU0_P0P1_DN<14>")
	)
	(segment
		(start 102.047802 -213.399878)
		(end 102.047802 -213.133178)
		(width 0.0889)
		(layer "In6.Cu")
		(net "UPI_CPU1_CPU0_P0P1_DN<14>")
	)
	(segment
		(start 238.35106 -150.391368)
		(end 276.99716 -160.317688)
		(width 0.14732)
		(layer "In6.Cu")
		(net "UPI_CPU1_CPU0_P0P1_DN<14>")
	)
	(segment
		(start 108.573824 -193.574162)
		(end 114.634264 -185.945526)
		(width 0.14732)
		(layer "In6.Cu")
		(net "UPI_CPU1_CPU0_P0P1_DN<14>")
	)
	(segment
		(start 191.91605 -160.271968)
		(end 194.447922 -160.271968)
		(width 0.14732)
		(layer "In6.Cu")
		(net "UPI_CPU1_CPU0_P0P1_DN<14>")
	)
	(segment
		(start 131.061968 -170.499532)
		(end 164.492178 -149.898354)
		(width 0.14732)
		(layer "In6.Cu")
		(net "UPI_CPU1_CPU0_P0P1_DN<14>")
	)
	(segment
		(start 326.914256 -152.144476)
		(end 339.724746 -161.564828)
		(width 0.14732)
		(layer "In6.Cu")
		(net "UPI_CPU1_CPU0_P0P1_DN<14>")
	)
	(segment
		(start 101.931216 -214.033608)
		(end 102.015798 -214.05977)
		(width 0.0889)
		(layer "In6.Cu")
		(net "UPI_CPU1_CPU0_P0P1_DN<14>")
	)
	(segment
		(start 102.047802 -212.40115)
		(end 102.147116 -212.301836)
		(width 0.0889)
		(layer "In6.Cu")
		(net "UPI_CPU1_CPU0_P0P1_DN<14>")
	)
	(segment
		(start 164.492178 -149.898354)
		(end 166.649654 -149.144736)
		(width 0.14732)
		(layer "In6.Cu")
		(net "UPI_CPU1_CPU0_P0P1_DN<14>")
	)
	(segment
		(start 102.147116 -212.301836)
		(end 102.147116 -211.835238)
		(width 0.0889)
		(layer "In6.Cu")
		(net "UPI_CPU1_CPU0_P0P1_DN<14>")
	)
	(segment
		(start 102.105206 -211.77123)
		(end 102.105206 -211.334096)
		(width 0.14732)
		(layer "In6.Cu")
		(net "UPI_CPU1_CPU0_P0P1_DN<14>")
	)
	(segment
		(start 102.047802 -212.66785)
		(end 102.047802 -212.40115)
		(width 0.0889)
		(layer "In6.Cu")
		(net "UPI_CPU1_CPU0_P0P1_DN<14>")
	)
	(segment
		(start 174.448724 -151.132286)
		(end 191.91605 -160.271968)
		(width 0.14732)
		(layer "In6.Cu")
		(net "UPI_CPU1_CPU0_P0P1_DN<14>")
	)
	(segment
		(start 170.64863 -149.2504)
		(end 174.448724 -151.132286)
		(width 0.14732)
		(layer "In6.Cu")
		(net "UPI_CPU1_CPU0_P0P1_DN<14>")
	)
	(segment
		(start 102.147116 -211.835238)
		(end 102.105206 -211.793328)
		(width 0.0889)
		(layer "In6.Cu")
		(net "UPI_CPU1_CPU0_P0P1_DN<14>")
	)
	(segment
		(start 102.147116 -212.767164)
		(end 102.047802 -212.66785)
		(width 0.0889)
		(layer "In6.Cu")
		(net "UPI_CPU1_CPU0_P0P1_DN<14>")
	)
	(segment
		(start 349.550482 -169.931334)
		(end 349.552006 -169.936414)
		(width 0.14732)
		(layer "In6.Cu")
		(net "UPI_CPU1_CPU0_P0P1_DN<14>")
	)
	(segment
		(start 349.552006 -169.936414)
		(end 350.089724 -170.080432)
		(width 0.14732)
		(layer "In6.Cu")
		(net "UPI_CPU1_CPU0_P0P1_DN<14>")
	)
	(segment
		(start 102.147116 -213.033864)
		(end 102.147116 -212.767164)
		(width 0.0889)
		(layer "In6.Cu")
		(net "UPI_CPU1_CPU0_P0P1_DN<14>")
	)
	(segment
		(start 166.649654 -149.144736)
		(end 170.64863 -149.2504)
		(width 0.14732)
		(layer "In6.Cu")
		(net "UPI_CPU1_CPU0_P0P1_DN<14>")
	)
	(segment
		(start 102.105206 -211.793328)
		(end 102.105206 -211.77123)
		(width 0.0889)
		(layer "In6.Cu")
		(net "UPI_CPU1_CPU0_P0P1_DN<14>")
	)
	(segment
		(start 101.772466 -213.732618)
		(end 101.931216 -214.033608)
		(width 0.0889)
		(layer "In6.Cu")
		(net "UPI_CPU1_CPU0_P0P1_DN<14>")
	)
	(segment
		(start 339.724746 -161.564828)
		(end 342.348566 -163.816538)
		(width 0.14732)
		(layer "In6.Cu")
		(net "UPI_CPU1_CPU0_P0P1_DN<14>")
	)
	(segment
		(start 102.105206 -211.334096)
		(end 108.573824 -193.574162)
		(width 0.14732)
		(layer "In6.Cu")
		(net "UPI_CPU1_CPU0_P0P1_DN<14>")
	)
	(segment
		(start 102.147116 -213.8934)
		(end 102.147116 -213.499192)
		(width 0.0889)
		(layer "In6.Cu")
		(net "UPI_CPU1_CPU0_P0P1_DN<14>")
	)
	(segment
		(start 345.666822 -167.746172)
		(end 347.572838 -169.347388)
		(width 0.14732)
		(layer "In6.Cu")
		(net "UPI_CPU1_CPU0_P0P1_DN<14>")
	)
	(segment
		(start 233.856276 -150.391368)
		(end 238.35106 -150.391368)
		(width 0.14732)
		(layer "In6.Cu")
		(net "UPI_CPU1_CPU0_P0P1_DN<14>")
	)
	(segment
		(start 321.966844 -151.354028)
		(end 323.767196 -151.354028)
		(width 0.14732)
		(layer "In6.Cu")
		(net "UPI_CPU1_CPU0_P0P1_DN<14>")
	)
	(segment
		(start 276.99716 -160.317688)
		(end 279.181052 -160.317688)
		(width 0.14732)
		(layer "In6.Cu")
		(net "UPI_CPU1_CPU0_P0P1_DN<14>")
	)
	(segment
		(start 196.569076 -160.003998)
		(end 233.856276 -150.391368)
		(width 0.14732)
		(layer "In6.Cu")
		(net "UPI_CPU1_CPU0_P0P1_DN<14>")
	)
	(segment
		(start 194.447922 -160.271968)
		(end 196.569076 -160.003998)
		(width 0.14732)
		(layer "In6.Cu")
		(net "UPI_CPU1_CPU0_P0P1_DN<14>")
	)
	(segment
		(start 323.767196 -151.354028)
		(end 326.914256 -152.144476)
		(width 0.14732)
		(layer "In6.Cu")
		(net "UPI_CPU1_CPU0_P0P1_DN<14>")
	)
	(arc
		(start 102.015798 -214.05977)
		(mid 102.092471 -213.985276)
		(end 102.147116 -213.8934)
		(width 0.0889)
		(layer "In6.Cu")
		(net "UPI_CPU1_CPU0_P0P1_DN<14>")
	)
	(segment
		(start 354.915978 -170.215052)
		(end 354.686616 -170.04538)
		(width 0.13208)
		(layer "F.Cu")
		(net "UPI_CPU1_CPU0_P0P1_DN<13>")
	)
	(segment
		(start 366.692942 -179.691792)
		(end 357.127556 -171.851828)
		(width 0.13208)
		(layer "F.Cu")
		(net "UPI_CPU1_CPU0_P0P1_DN<13>")
	)
	(segment
		(start 363.336332 -200.345548)
		(end 364.27791 -195.611242)
		(width 0.13208)
		(layer "F.Cu")
		(net "UPI_CPU1_CPU0_P0P1_DN<13>")
	)
	(segment
		(start 357.113332 -171.840144)
		(end 355.62794 -170.741594)
		(width 0.13208)
		(layer "F.Cu")
		(net "UPI_CPU1_CPU0_P0P1_DN<13>")
	)
	(segment
		(start 370.702586 -214.889588)
		(end 370.727732 -214.796878)
		(width 0.0889)
		(layer "F.Cu")
		(net "UPI_CPU1_CPU0_P0P1_DN<13>")
	)
	(segment
		(start 353.180904 -169.22877)
		(end 353.320604 -168.986708)
		(width 0.13208)
		(layer "F.Cu")
		(net "UPI_CPU1_CPU0_P0P1_DN<13>")
	)
	(segment
		(start 367.035588 -188.953648)
		(end 367.544858 -186.393074)
		(width 0.13208)
		(layer "F.Cu")
		(net "UPI_CPU1_CPU0_P0P1_DN<13>")
	)
	(segment
		(start 370.85778 -215.158574)
		(end 370.702586 -214.889588)
		(width 0.0889)
		(layer "F.Cu")
		(net "UPI_CPU1_CPU0_P0P1_DN<13>")
	)
	(segment
		(start 357.127556 -171.851574)
		(end 357.113332 -171.840144)
		(width 0.13208)
		(layer "F.Cu")
		(net "UPI_CPU1_CPU0_P0P1_DN<13>")
	)
	(segment
		(start 370.95303 -213.19998)
		(end 370.95303 -212.968332)
		(width 0.0889)
		(layer "F.Cu")
		(net "UPI_CPU1_CPU0_P0P1_DN<13>")
	)
	(segment
		(start 365.091218 -207.37195)
		(end 363.301788 -205.58252)
		(width 0.0889)
		(layer "F.Cu")
		(net "UPI_CPU1_CPU0_P0P1_DN<13>")
	)
	(segment
		(start 370.745004 -212.337396)
		(end 366.26673 -207.858868)
		(width 0.0889)
		(layer "F.Cu")
		(net "UPI_CPU1_CPU0_P0P1_DN<13>")
	)
	(segment
		(start 357.127556 -171.851828)
		(end 357.127556 -171.851574)
		(width 0.13208)
		(layer "F.Cu")
		(net "UPI_CPU1_CPU0_P0P1_DN<13>")
	)
	(segment
		(start 370.953284 -213.200234)
		(end 370.95303 -213.19998)
		(width 0.0889)
		(layer "F.Cu")
		(net "UPI_CPU1_CPU0_P0P1_DN<13>")
	)
	(segment
		(start 370.95303 -212.968332)
		(end 370.745004 -212.760306)
		(width 0.0889)
		(layer "F.Cu")
		(net "UPI_CPU1_CPU0_P0P1_DN<13>")
	)
	(segment
		(start 363.301788 -205.58252)
		(end 363.301788 -205.261718)
		(width 0.0889)
		(layer "F.Cu")
		(net "UPI_CPU1_CPU0_P0P1_DN<13>")
	)
	(segment
		(start 101.302312 -214.622888)
		(end 101.302058 -214.622634)
		(width 0.13208)
		(layer "F.Cu")
		(net "UPI_CPU1_CPU0_P0P1_DN<13>")
	)
	(segment
		(start 354.686616 -170.04538)
		(end 353.227386 -169.603928)
		(width 0.13208)
		(layer "F.Cu")
		(net "UPI_CPU1_CPU0_P0P1_DN<13>")
	)
	(segment
		(start 353.227386 -169.603928)
		(end 353.157028 -169.500296)
		(width 0.13208)
		(layer "F.Cu")
		(net "UPI_CPU1_CPU0_P0P1_DN<13>")
	)
	(segment
		(start 367.02492 -180.494432)
		(end 366.692942 -179.691792)
		(width 0.13208)
		(layer "F.Cu")
		(net "UPI_CPU1_CPU0_P0P1_DN<13>")
	)
	(segment
		(start 353.32162 -168.985184)
		(end 353.874324 -168.835832)
		(width 0.13208)
		(layer "F.Cu")
		(net "UPI_CPU1_CPU0_P0P1_DN<13>")
	)
	(segment
		(start 355.62794 -170.741594)
		(end 355.627686 -170.741848)
		(width 0.13208)
		(layer "F.Cu")
		(net "UPI_CPU1_CPU0_P0P1_DN<13>")
	)
	(segment
		(start 355.601778 -170.567858)
		(end 355.283008 -170.331892)
		(width 0.13208)
		(layer "F.Cu")
		(net "UPI_CPU1_CPU0_P0P1_DN<13>")
	)
	(segment
		(start 367.544858 -186.393074)
		(end 367.544858 -183.106568)
		(width 0.13208)
		(layer "F.Cu")
		(net "UPI_CPU1_CPU0_P0P1_DN<13>")
	)
	(segment
		(start 363.336332 -205.227174)
		(end 363.336332 -205.205076)
		(width 0.0889)
		(layer "F.Cu")
		(net "UPI_CPU1_CPU0_P0P1_DN<13>")
	)
	(segment
		(start 363.336332 -205.205076)
		(end 363.336332 -200.345548)
		(width 0.13208)
		(layer "F.Cu")
		(net "UPI_CPU1_CPU0_P0P1_DN<13>")
	)
	(segment
		(start 363.301788 -205.261718)
		(end 363.336332 -205.227174)
		(width 0.0889)
		(layer "F.Cu")
		(net "UPI_CPU1_CPU0_P0P1_DN<13>")
	)
	(segment
		(start 364.27791 -195.611242)
		(end 367.035588 -188.953648)
		(width 0.13208)
		(layer "F.Cu")
		(net "UPI_CPU1_CPU0_P0P1_DN<13>")
	)
	(segment
		(start 353.157028 -169.500296)
		(end 353.180904 -169.22877)
		(width 0.13208)
		(layer "F.Cu")
		(net "UPI_CPU1_CPU0_P0P1_DN<13>")
	)
	(segment
		(start 366.26673 -207.858868)
		(end 365.091218 -207.37195)
		(width 0.0889)
		(layer "F.Cu")
		(net "UPI_CPU1_CPU0_P0P1_DN<13>")
	)
	(segment
		(start 355.109018 -170.3578)
		(end 354.915978 -170.215052)
		(width 0.13208)
		(layer "F.Cu")
		(net "UPI_CPU1_CPU0_P0P1_DN<13>")
	)
	(segment
		(start 355.283008 -170.331892)
		(end 355.109018 -170.3578)
		(width 0.13208)
		(layer "F.Cu")
		(net "UPI_CPU1_CPU0_P0P1_DN<13>")
	)
	(segment
		(start 367.544858 -183.106568)
		(end 367.02492 -180.494432)
		(width 0.13208)
		(layer "F.Cu")
		(net "UPI_CPU1_CPU0_P0P1_DN<13>")
	)
	(segment
		(start 101.302312 -215.158574)
		(end 101.302312 -214.622888)
		(width 0.13208)
		(layer "F.Cu")
		(net "UPI_CPU1_CPU0_P0P1_DN<13>")
	)
	(segment
		(start 353.320604 -168.986708)
		(end 353.32162 -168.985184)
		(width 0.13208)
		(layer "F.Cu")
		(net "UPI_CPU1_CPU0_P0P1_DN<13>")
	)
	(segment
		(start 370.745004 -212.760306)
		(end 370.745004 -212.337396)
		(width 0.0889)
		(layer "F.Cu")
		(net "UPI_CPU1_CPU0_P0P1_DN<13>")
	)
	(segment
		(start 355.627686 -170.741848)
		(end 355.601778 -170.567858)
		(width 0.13208)
		(layer "F.Cu")
		(net "UPI_CPU1_CPU0_P0P1_DN<13>")
	)
	(segment
		(start 370.953284 -214.344758)
		(end 370.953284 -213.200234)
		(width 0.0889)
		(layer "F.Cu")
		(net "UPI_CPU1_CPU0_P0P1_DN<13>")
	)
	(arc
		(start 370.727732 -214.796878)
		(mid 370.736432 -214.790229)
		(end 370.745004 -214.783416)
		(width 0.0889)
		(layer "F.Cu")
		(net "UPI_CPU1_CPU0_P0P1_DN<13>")
	)
	(arc
		(start 370.745004 -214.783416)
		(mid 370.898633 -214.587592)
		(end 370.953284 -214.344758)
		(width 0.0889)
		(layer "F.Cu")
		(net "UPI_CPU1_CPU0_P0P1_DN<13>")
	)
	(segment
		(start 196.92112 -147.713954)
		(end 191.552576 -147.713954)
		(width 0.14732)
		(layer "In6.Cu")
		(net "UPI_CPU1_CPU0_P0P1_DN<13>")
	)
	(segment
		(start 353.185476 -169.218356)
		(end 352.898964 -169.504868)
		(width 0.14732)
		(layer "In6.Cu")
		(net "UPI_CPU1_CPU0_P0P1_DN<13>")
	)
	(segment
		(start 101.145594 -214.893652)
		(end 101.302058 -214.622634)
		(width 0.0889)
		(layer "In6.Cu")
		(net "UPI_CPU1_CPU0_P0P1_DN<13>")
	)
	(segment
		(start 101.49713 -212.41893)
		(end 101.49713 -212.68563)
		(width 0.0889)
		(layer "In6.Cu")
		(net "UPI_CPU1_CPU0_P0P1_DN<13>")
	)
	(segment
		(start 187.958984 -150.230332)
		(end 184.547002 -150.831804)
		(width 0.14732)
		(layer "In6.Cu")
		(net "UPI_CPU1_CPU0_P0P1_DN<13>")
	)
	(segment
		(start 353.21113 -169.192956)
		(end 353.185476 -169.21861)
		(width 0.14732)
		(layer "In6.Cu")
		(net "UPI_CPU1_CPU0_P0P1_DN<13>")
	)
	(segment
		(start 109.56163 -191.220852)
		(end 108.222542 -192.90665)
		(width 0.14732)
		(layer "In6.Cu")
		(net "UPI_CPU1_CPU0_P0P1_DN<13>")
	)
	(segment
		(start 333.477362 -156.195776)
		(end 333.477362 -156.195522)
		(width 0.14732)
		(layer "In6.Cu")
		(net "UPI_CPU1_CPU0_P0P1_DN<13>")
	)
	(segment
		(start 346.261944 -167.213026)
		(end 345.631008 -166.661084)
		(width 0.14732)
		(layer "In6.Cu")
		(net "UPI_CPU1_CPU0_P0P1_DN<13>")
	)
	(segment
		(start 353.185476 -169.21861)
		(end 353.185476 -169.218356)
		(width 0.14732)
		(layer "In6.Cu")
		(net "UPI_CPU1_CPU0_P0P1_DN<13>")
	)
	(segment
		(start 279.12187 -159.763968)
		(end 277.07717 -159.763968)
		(width 0.14732)
		(layer "In6.Cu")
		(net "UPI_CPU1_CPU0_P0P1_DN<13>")
	)
	(segment
		(start 164.225732 -149.396704)
		(end 130.732784 -170.03649)
		(width 0.14732)
		(layer "In6.Cu")
		(net "UPI_CPU1_CPU0_P0P1_DN<13>")
	)
	(segment
		(start 101.43998 -211.70011)
		(end 101.43998 -211.711286)
		(width 0.0889)
		(layer "In6.Cu")
		(net "UPI_CPU1_CPU0_P0P1_DN<13>")
	)
	(segment
		(start 191.552576 -147.713954)
		(end 187.958984 -150.230332)
		(width 0.14732)
		(layer "In6.Cu")
		(net "UPI_CPU1_CPU0_P0P1_DN<13>")
	)
	(segment
		(start 352.898964 -169.504868)
		(end 352.100388 -169.504868)
		(width 0.14732)
		(layer "In6.Cu")
		(net "UPI_CPU1_CPU0_P0P1_DN<13>")
	)
	(segment
		(start 201.266806 -153.503884)
		(end 201.062082 -153.503884)
		(width 0.14732)
		(layer "In6.Cu")
		(net "UPI_CPU1_CPU0_P0P1_DN<13>")
	)
	(segment
		(start 200.145904 -152.382982)
		(end 200.145904 -150.938738)
		(width 0.14732)
		(layer "In6.Cu")
		(net "UPI_CPU1_CPU0_P0P1_DN<13>")
	)
	(segment
		(start 182.49011 -150.469092)
		(end 180.786278 -149.276054)
		(width 0.14732)
		(layer "In6.Cu")
		(net "UPI_CPU1_CPU0_P0P1_DN<13>")
	)
	(segment
		(start 277.07717 -159.763968)
		(end 238.164116 -149.769068)
		(width 0.14732)
		(layer "In6.Cu")
		(net "UPI_CPU1_CPU0_P0P1_DN<13>")
	)
	(segment
		(start 233.930698 -149.769068)
		(end 206.02194 -154.690318)
		(width 0.14732)
		(layer "In6.Cu")
		(net "UPI_CPU1_CPU0_P0P1_DN<13>")
	)
	(segment
		(start 101.43998 -211.711286)
		(end 101.397816 -211.75345)
		(width 0.0889)
		(layer "In6.Cu")
		(net "UPI_CPU1_CPU0_P0P1_DN<13>")
	)
	(segment
		(start 327.13422 -151.524716)
		(end 323.97573 -150.731728)
		(width 0.14732)
		(layer "In6.Cu")
		(net "UPI_CPU1_CPU0_P0P1_DN<13>")
	)
	(segment
		(start 101.49713 -213.150958)
		(end 101.49713 -213.417658)
		(width 0.0889)
		(layer "In6.Cu")
		(net "UPI_CPU1_CPU0_P0P1_DN<13>")
	)
	(segment
		(start 350.11741 -169.060876)
		(end 349.754698 -169.12336)
		(width 0.14732)
		(layer "In6.Cu")
		(net "UPI_CPU1_CPU0_P0P1_DN<13>")
	)
	(segment
		(start 339.819996 -160.866074)
		(end 333.477362 -156.195776)
		(width 0.14732)
		(layer "In6.Cu")
		(net "UPI_CPU1_CPU0_P0P1_DN<13>")
	)
	(segment
		(start 113.57864 -186.165236)
		(end 109.56163 -191.221106)
		(width 0.14732)
		(layer "In6.Cu")
		(net "UPI_CPU1_CPU0_P0P1_DN<13>")
	)
	(segment
		(start 101.397816 -211.75345)
		(end 101.397816 -212.319616)
		(width 0.0889)
		(layer "In6.Cu")
		(net "UPI_CPU1_CPU0_P0P1_DN<13>")
	)
	(segment
		(start 349.754698 -169.12336)
		(end 348.270576 -168.861486)
		(width 0.14732)
		(layer "In6.Cu")
		(net "UPI_CPU1_CPU0_P0P1_DN<13>")
	)
	(segment
		(start 353.333304 -168.981374)
		(end 353.21113 -169.192956)
		(width 0.14732)
		(layer "In6.Cu")
		(net "UPI_CPU1_CPU0_P0P1_DN<13>")
	)
	(segment
		(start 130.732784 -170.03649)
		(end 113.57864 -186.165236)
		(width 0.14732)
		(layer "In6.Cu")
		(net "UPI_CPU1_CPU0_P0P1_DN<13>")
	)
	(segment
		(start 348.270576 -168.861486)
		(end 346.261944 -167.213026)
		(width 0.14732)
		(layer "In6.Cu")
		(net "UPI_CPU1_CPU0_P0P1_DN<13>")
	)
	(segment
		(start 101.49713 -213.417658)
		(end 101.397816 -213.516972)
		(width 0.0889)
		(layer "In6.Cu")
		(net "UPI_CPU1_CPU0_P0P1_DN<13>")
	)
	(segment
		(start 343.5858 -164.097716)
		(end 339.819996 -160.866074)
		(width 0.14732)
		(layer "In6.Cu")
		(net "UPI_CPU1_CPU0_P0P1_DN<13>")
	)
	(segment
		(start 101.067362 -214.91448)
		(end 101.145594 -214.893652)
		(width 0.0889)
		(layer "In6.Cu")
		(net "UPI_CPU1_CPU0_P0P1_DN<13>")
	)
	(segment
		(start 108.222542 -192.90665)
		(end 101.43998 -211.52739)
		(width 0.14732)
		(layer "In6.Cu")
		(net "UPI_CPU1_CPU0_P0P1_DN<13>")
	)
	(segment
		(start 200.801224 -153.243026)
		(end 200.801224 -153.038302)
		(width 0.14732)
		(layer "In6.Cu")
		(net "UPI_CPU1_CPU0_P0P1_DN<13>")
	)
	(segment
		(start 101.43998 -211.52739)
		(end 101.43998 -211.70011)
		(width 0.14732)
		(layer "In6.Cu")
		(net "UPI_CPU1_CPU0_P0P1_DN<13>")
	)
	(segment
		(start 184.547002 -150.831804)
		(end 182.49011 -150.469092)
		(width 0.14732)
		(layer "In6.Cu")
		(net "UPI_CPU1_CPU0_P0P1_DN<13>")
	)
	(segment
		(start 101.397816 -213.051644)
		(end 101.49713 -213.150958)
		(width 0.0889)
		(layer "In6.Cu")
		(net "UPI_CPU1_CPU0_P0P1_DN<13>")
	)
	(segment
		(start 100.927408 -214.461852)
		(end 100.927408 -214.622634)
		(width 0.0889)
		(layer "In6.Cu")
		(net "UPI_CPU1_CPU0_P0P1_DN<13>")
	)
	(segment
		(start 201.062082 -153.503884)
		(end 200.801224 -153.243026)
		(width 0.14732)
		(layer "In6.Cu")
		(net "UPI_CPU1_CPU0_P0P1_DN<13>")
	)
	(segment
		(start 352.100388 -169.504868)
		(end 350.11741 -169.060876)
		(width 0.14732)
		(layer "In6.Cu")
		(net "UPI_CPU1_CPU0_P0P1_DN<13>")
	)
	(segment
		(start 322.235068 -150.731728)
		(end 279.12187 -159.763968)
		(width 0.14732)
		(layer "In6.Cu")
		(net "UPI_CPU1_CPU0_P0P1_DN<13>")
	)
	(segment
		(start 101.397816 -212.784944)
		(end 101.397816 -213.051644)
		(width 0.0889)
		(layer "In6.Cu")
		(net "UPI_CPU1_CPU0_P0P1_DN<13>")
	)
	(segment
		(start 206.02194 -154.690318)
		(end 202.45324 -154.690318)
		(width 0.14732)
		(layer "In6.Cu")
		(net "UPI_CPU1_CPU0_P0P1_DN<13>")
	)
	(segment
		(start 238.164116 -149.769068)
		(end 233.930698 -149.769068)
		(width 0.14732)
		(layer "In6.Cu")
		(net "UPI_CPU1_CPU0_P0P1_DN<13>")
	)
	(segment
		(start 200.145904 -150.938738)
		(end 196.92112 -147.713954)
		(width 0.14732)
		(layer "In6.Cu")
		(net "UPI_CPU1_CPU0_P0P1_DN<13>")
	)
	(segment
		(start 101.397816 -212.319616)
		(end 101.49713 -212.41893)
		(width 0.0889)
		(layer "In6.Cu")
		(net "UPI_CPU1_CPU0_P0P1_DN<13>")
	)
	(segment
		(start 202.45324 -154.690318)
		(end 201.266806 -153.503884)
		(width 0.14732)
		(layer "In6.Cu")
		(net "UPI_CPU1_CPU0_P0P1_DN<13>")
	)
	(segment
		(start 200.801224 -153.038302)
		(end 200.145904 -152.382982)
		(width 0.14732)
		(layer "In6.Cu")
		(net "UPI_CPU1_CPU0_P0P1_DN<13>")
	)
	(segment
		(start 180.786278 -149.276054)
		(end 170.021504 -147.377912)
		(width 0.14732)
		(layer "In6.Cu")
		(net "UPI_CPU1_CPU0_P0P1_DN<13>")
	)
	(segment
		(start 353.874324 -168.835832)
		(end 353.333812 -168.980612)
		(width 0.14732)
		(layer "In6.Cu")
		(net "UPI_CPU1_CPU0_P0P1_DN<13>")
	)
	(segment
		(start 101.397816 -213.516972)
		(end 101.397816 -213.929468)
		(width 0.0889)
		(layer "In6.Cu")
		(net "UPI_CPU1_CPU0_P0P1_DN<13>")
	)
	(segment
		(start 170.021504 -147.377912)
		(end 164.225732 -149.396704)
		(width 0.14732)
		(layer "In6.Cu")
		(net "UPI_CPU1_CPU0_P0P1_DN<13>")
	)
	(segment
		(start 333.477362 -156.195522)
		(end 327.13422 -151.524716)
		(width 0.14732)
		(layer "In6.Cu")
		(net "UPI_CPU1_CPU0_P0P1_DN<13>")
	)
	(segment
		(start 109.56163 -191.221106)
		(end 109.56163 -191.220852)
		(width 0.14732)
		(layer "In6.Cu")
		(net "UPI_CPU1_CPU0_P0P1_DN<13>")
	)
	(segment
		(start 345.631008 -166.661084)
		(end 343.5858 -164.097716)
		(width 0.14732)
		(layer "In6.Cu")
		(net "UPI_CPU1_CPU0_P0P1_DN<13>")
	)
	(segment
		(start 101.49713 -212.68563)
		(end 101.397816 -212.784944)
		(width 0.0889)
		(layer "In6.Cu")
		(net "UPI_CPU1_CPU0_P0P1_DN<13>")
	)
	(segment
		(start 323.97573 -150.731728)
		(end 322.235068 -150.731728)
		(width 0.14732)
		(layer "In6.Cu")
		(net "UPI_CPU1_CPU0_P0P1_DN<13>")
	)
	(segment
		(start 353.333812 -168.980612)
		(end 353.333304 -168.981374)
		(width 0.14732)
		(layer "In6.Cu")
		(net "UPI_CPU1_CPU0_P0P1_DN<13>")
	)
	(arc
		(start 100.927408 -214.622634)
		(mid 100.964268 -214.784431)
		(end 101.067362 -214.91448)
		(width 0.0889)
		(layer "In6.Cu")
		(net "UPI_CPU1_CPU0_P0P1_DN<13>")
	)
	(arc
		(start 101.111812 -214.261954)
		(mid 101.002416 -214.346051)
		(end 100.927408 -214.461852)
		(width 0.0889)
		(layer "In6.Cu")
		(net "UPI_CPU1_CPU0_P0P1_DN<13>")
	)
	(arc
		(start 101.382576 -213.968584)
		(mid 101.27237 -214.138501)
		(end 101.111812 -214.261954)
		(width 0.0889)
		(layer "In6.Cu")
		(net "UPI_CPU1_CPU0_P0P1_DN<13>")
	)
	(arc
		(start 101.397816 -213.929468)
		(mid 101.390538 -213.949159)
		(end 101.382576 -213.968584)
		(width 0.0889)
		(layer "In6.Cu")
		(net "UPI_CPU1_CPU0_P0P1_DN<13>")
	)
	(segment
		(start 371.5512 -213.389972)
		(end 371.5512 -212.858096)
		(width 0.0889)
		(layer "F.Cu")
		(net "UPI_CPU1_CPU0_P0P1_DN<12>")
	)
	(segment
		(start 368.613436 -186.494928)
		(end 368.613436 -182.94096)
		(width 0.13208)
		(layer "F.Cu")
		(net "UPI_CPU1_CPU0_P0P1_DN<12>")
	)
	(segment
		(start 365.853726 -207.060292)
		(end 364.419896 -205.626208)
		(width 0.0889)
		(layer "F.Cu")
		(net "UPI_CPU1_CPU0_P0P1_DN<12>")
	)
	(segment
		(start 371.527578 -214.661496)
		(end 371.527832 -214.661496)
		(width 0.0889)
		(layer "F.Cu")
		(net "UPI_CPU1_CPU0_P0P1_DN<12>")
	)
	(segment
		(start 350.122998 -168.11879)
		(end 349.865188 -167.970454)
		(width 0.13208)
		(layer "F.Cu")
		(net "UPI_CPU1_CPU0_P0P1_DN<12>")
	)
	(segment
		(start 352.116136 -167.408352)
		(end 350.613218 -168.11879)
		(width 0.13208)
		(layer "F.Cu")
		(net "UPI_CPU1_CPU0_P0P1_DN<12>")
	)
	(segment
		(start 371.551454 -212.369146)
		(end 366.517428 -207.335374)
		(width 0.0889)
		(layer "F.Cu")
		(net "UPI_CPU1_CPU0_P0P1_DN<12>")
	)
	(segment
		(start 352.838258 -167.408352)
		(end 352.116136 -167.408352)
		(width 0.13208)
		(layer "F.Cu")
		(net "UPI_CPU1_CPU0_P0P1_DN<12>")
	)
	(segment
		(start 353.823524 -167.707564)
		(end 352.838258 -167.408352)
		(width 0.13208)
		(layer "F.Cu")
		(net "UPI_CPU1_CPU0_P0P1_DN<12>")
	)
	(segment
		(start 349.717868 -167.715438)
		(end 349.165672 -167.565832)
		(width 0.13208)
		(layer "F.Cu")
		(net "UPI_CPU1_CPU0_P0P1_DN<12>")
	)
	(segment
		(start 371.23243 -215.172798)
		(end 371.23243 -215.158066)
		(width 0.0889)
		(layer "F.Cu")
		(net "UPI_CPU1_CPU0_P0P1_DN<12>")
	)
	(segment
		(start 368.083846 -189.15761)
		(end 368.613436 -186.494928)
		(width 0.13208)
		(layer "F.Cu")
		(net "UPI_CPU1_CPU0_P0P1_DN<12>")
	)
	(segment
		(start 367.326672 -178.78933)
		(end 355.785674 -169.31767)
		(width 0.13208)
		(layer "F.Cu")
		(net "UPI_CPU1_CPU0_P0P1_DN<12>")
	)
	(segment
		(start 366.517428 -207.335374)
		(end 365.853726 -207.060292)
		(width 0.0889)
		(layer "F.Cu")
		(net "UPI_CPU1_CPU0_P0P1_DN<12>")
	)
	(segment
		(start 368.08283 -180.27269)
		(end 367.568226 -179.030884)
		(width 0.13208)
		(layer "F.Cu")
		(net "UPI_CPU1_CPU0_P0P1_DN<12>")
	)
	(segment
		(start 367.568226 -179.030884)
		(end 367.326672 -178.78933)
		(width 0.13208)
		(layer "F.Cu")
		(net "UPI_CPU1_CPU0_P0P1_DN<12>")
	)
	(segment
		(start 371.702584 -214.345012)
		(end 371.702584 -213.541356)
		(width 0.0889)
		(layer "F.Cu")
		(net "UPI_CPU1_CPU0_P0P1_DN<12>")
	)
	(segment
		(start 364.385352 -200.461626)
		(end 365.29391 -195.893182)
		(width 0.13208)
		(layer "F.Cu")
		(net "UPI_CPU1_CPU0_P0P1_DN<12>")
	)
	(segment
		(start 371.702584 -213.541356)
		(end 371.5512 -213.389972)
		(width 0.0889)
		(layer "F.Cu")
		(net "UPI_CPU1_CPU0_P0P1_DN<12>")
	)
	(segment
		(start 355.785674 -169.31767)
		(end 355.610414 -169.334942)
		(width 0.13208)
		(layer "F.Cu")
		(net "UPI_CPU1_CPU0_P0P1_DN<12>")
	)
	(segment
		(start 349.865188 -167.970454)
		(end 349.717868 -167.715438)
		(width 0.13208)
		(layer "F.Cu")
		(net "UPI_CPU1_CPU0_P0P1_DN<12>")
	)
	(segment
		(start 364.385352 -205.205076)
		(end 364.385352 -200.461626)
		(width 0.13208)
		(layer "F.Cu")
		(net "UPI_CPU1_CPU0_P0P1_DN<12>")
	)
	(segment
		(start 100.362512 -214.622888)
		(end 100.362258 -214.622634)
		(width 0.13208)
		(layer "F.Cu")
		(net "UPI_CPU1_CPU0_P0P1_DN<12>")
	)
	(segment
		(start 371.33276 -215.964262)
		(end 371.483128 -215.703658)
		(width 0.0889)
		(layer "F.Cu")
		(net "UPI_CPU1_CPU0_P0P1_DN<12>")
	)
	(segment
		(start 355.286564 -168.908222)
		(end 353.823524 -167.707564)
		(width 0.13208)
		(layer "F.Cu")
		(net "UPI_CPU1_CPU0_P0P1_DN<12>")
	)
	(segment
		(start 371.483128 -215.703658)
		(end 371.457982 -215.610694)
		(width 0.0889)
		(layer "F.Cu")
		(net "UPI_CPU1_CPU0_P0P1_DN<12>")
	)
	(segment
		(start 355.303836 -169.083482)
		(end 355.286564 -168.908222)
		(width 0.13208)
		(layer "F.Cu")
		(net "UPI_CPU1_CPU0_P0P1_DN<12>")
	)
	(segment
		(start 371.5512 -212.858096)
		(end 371.551454 -212.857842)
		(width 0.0889)
		(layer "F.Cu")
		(net "UPI_CPU1_CPU0_P0P1_DN<12>")
	)
	(segment
		(start 100.362512 -215.158574)
		(end 100.362512 -214.622888)
		(width 0.13208)
		(layer "F.Cu")
		(net "UPI_CPU1_CPU0_P0P1_DN<12>")
	)
	(segment
		(start 365.29391 -195.893182)
		(end 368.083846 -189.15761)
		(width 0.13208)
		(layer "F.Cu")
		(net "UPI_CPU1_CPU0_P0P1_DN<12>")
	)
	(segment
		(start 364.385352 -205.227174)
		(end 364.385352 -205.205076)
		(width 0.0889)
		(layer "F.Cu")
		(net "UPI_CPU1_CPU0_P0P1_DN<12>")
	)
	(segment
		(start 371.327934 -215.972644)
		(end 371.33276 -215.964262)
		(width 0.0889)
		(layer "F.Cu")
		(net "UPI_CPU1_CPU0_P0P1_DN<12>")
	)
	(segment
		(start 355.610414 -169.334942)
		(end 355.303836 -169.083482)
		(width 0.13208)
		(layer "F.Cu")
		(net "UPI_CPU1_CPU0_P0P1_DN<12>")
	)
	(segment
		(start 371.551454 -212.857842)
		(end 371.551454 -212.369146)
		(width 0.0889)
		(layer "F.Cu")
		(net "UPI_CPU1_CPU0_P0P1_DN<12>")
	)
	(segment
		(start 368.613436 -182.94096)
		(end 368.08283 -180.27269)
		(width 0.13208)
		(layer "F.Cu")
		(net "UPI_CPU1_CPU0_P0P1_DN<12>")
	)
	(segment
		(start 364.419896 -205.626208)
		(end 364.419896 -205.261718)
		(width 0.0889)
		(layer "F.Cu")
		(net "UPI_CPU1_CPU0_P0P1_DN<12>")
	)
	(segment
		(start 350.613218 -168.11879)
		(end 350.122998 -168.11879)
		(width 0.13208)
		(layer "F.Cu")
		(net "UPI_CPU1_CPU0_P0P1_DN<12>")
	)
	(segment
		(start 364.419896 -205.261718)
		(end 364.385352 -205.227174)
		(width 0.0889)
		(layer "F.Cu")
		(net "UPI_CPU1_CPU0_P0P1_DN<12>")
	)
	(arc
		(start 371.457982 -215.610694)
		(mid 371.449408 -215.604045)
		(end 371.440964 -215.597232)
		(width 0.0889)
		(layer "F.Cu")
		(net "UPI_CPU1_CPU0_P0P1_DN<12>")
	)
	(arc
		(start 371.527832 -214.661496)
		(mid 371.655955 -214.525737)
		(end 371.702584 -214.345012)
		(width 0.0889)
		(layer "F.Cu")
		(net "UPI_CPU1_CPU0_P0P1_DN<12>")
	)
	(arc
		(start 371.440964 -215.597232)
		(mid 371.290186 -215.407867)
		(end 371.23243 -215.172798)
		(width 0.0889)
		(layer "F.Cu")
		(net "UPI_CPU1_CPU0_P0P1_DN<12>")
	)
	(arc
		(start 371.23243 -215.158066)
		(mid 371.311778 -214.869221)
		(end 371.527578 -214.661496)
		(width 0.0889)
		(layer "F.Cu")
		(net "UPI_CPU1_CPU0_P0P1_DN<12>")
	)
	(segment
		(start 111.168434 -187.836556)
		(end 110.938564 -188.124592)
		(width 0.14732)
		(layer "In6.Cu")
		(net "UPI_CPU1_CPU0_P0P1_DN<12>")
	)
	(segment
		(start 110.528608 -188.638942)
		(end 110.298738 -188.927232)
		(width 0.14732)
		(layer "In6.Cu")
		(net "UPI_CPU1_CPU0_P0P1_DN<12>")
	)
	(segment
		(start 163.760404 -148.6535)
		(end 130.328162 -169.225468)
		(width 0.14732)
		(layer "In6.Cu")
		(net "UPI_CPU1_CPU0_P0P1_DN<12>")
	)
	(segment
		(start 110.73511 -188.147706)
		(end 110.505748 -188.435488)
		(width 0.14732)
		(layer "In6.Cu")
		(net "UPI_CPU1_CPU0_P0P1_DN<12>")
	)
	(segment
		(start 100.457762 -213.93023)
		(end 100.458016 -213.929468)
		(width 0.0889)
		(layer "In6.Cu")
		(net "UPI_CPU1_CPU0_P0P1_DN<12>")
	)
	(segment
		(start 100.203508 -214.321644)
		(end 100.362258 -214.622634)
		(width 0.0889)
		(layer "In6.Cu")
		(net "UPI_CPU1_CPU0_P0P1_DN<12>")
	)
	(segment
		(start 111.390684 -187.325508)
		(end 111.145574 -187.633102)
		(width 0.14732)
		(layer "In6.Cu")
		(net "UPI_CPU1_CPU0_P0P1_DN<12>")
	)
	(segment
		(start 110.298738 -188.927232)
		(end 110.095284 -188.950092)
		(width 0.14732)
		(layer "In6.Cu")
		(net "UPI_CPU1_CPU0_P0P1_DN<12>")
	)
	(segment
		(start 349.15602 -166.756334)
		(end 349.155766 -166.755826)
		(width 0.14732)
		(layer "In6.Cu")
		(net "UPI_CPU1_CPU0_P0P1_DN<12>")
	)
	(segment
		(start 238.603282 -147.499324)
		(end 170.28414 -146.403314)
		(width 0.14732)
		(layer "In6.Cu")
		(net "UPI_CPU1_CPU0_P0P1_DN<12>")
	)
	(segment
		(start 110.505748 -188.435488)
		(end 110.528608 -188.638942)
		(width 0.14732)
		(layer "In6.Cu")
		(net "UPI_CPU1_CPU0_P0P1_DN<12>")
	)
	(segment
		(start 108.339382 -191.384428)
		(end 108.109512 -191.672718)
		(width 0.14732)
		(layer "In6.Cu")
		(net "UPI_CPU1_CPU0_P0P1_DN<12>")
	)
	(segment
		(start 110.095284 -188.950092)
		(end 109.778292 -189.347856)
		(width 0.14732)
		(layer "In6.Cu")
		(net "UPI_CPU1_CPU0_P0P1_DN<12>")
	)
	(segment
		(start 109.571282 -189.839346)
		(end 109.367828 -189.86246)
		(width 0.14732)
		(layer "In6.Cu")
		(net "UPI_CPU1_CPU0_P0P1_DN<12>")
	)
	(segment
		(start 111.145574 -187.633102)
		(end 111.168434 -187.836556)
		(width 0.14732)
		(layer "In6.Cu")
		(net "UPI_CPU1_CPU0_P0P1_DN<12>")
	)
	(segment
		(start 108.109512 -191.672718)
		(end 107.906058 -191.695578)
		(width 0.14732)
		(layer "In6.Cu")
		(net "UPI_CPU1_CPU0_P0P1_DN<12>")
	)
	(segment
		(start 111.824008 -187.014358)
		(end 111.594138 -187.302394)
		(width 0.14732)
		(layer "In6.Cu")
		(net "UPI_CPU1_CPU0_P0P1_DN<12>")
	)
	(segment
		(start 109.367828 -189.86246)
		(end 108.956348 -190.378588)
		(width 0.14732)
		(layer "In6.Cu")
		(net "UPI_CPU1_CPU0_P0P1_DN<12>")
	)
	(segment
		(start 349.155766 -166.755826)
		(end 327.629266 -150.753572)
		(width 0.14732)
		(layer "In6.Cu")
		(net "UPI_CPU1_CPU0_P0P1_DN<12>")
	)
	(segment
		(start 108.316522 -191.180974)
		(end 108.339382 -191.384428)
		(width 0.14732)
		(layer "In6.Cu")
		(net "UPI_CPU1_CPU0_P0P1_DN<12>")
	)
	(segment
		(start 100.499926 -211.77123)
		(end 100.499926 -211.793328)
		(width 0.0889)
		(layer "In6.Cu")
		(net "UPI_CPU1_CPU0_P0P1_DN<12>")
	)
	(segment
		(start 327.629266 -150.753572)
		(end 318.569086 -148.48078)
		(width 0.14732)
		(layer "In6.Cu")
		(net "UPI_CPU1_CPU0_P0P1_DN<12>")
	)
	(segment
		(start 318.569086 -148.48078)
		(end 275.789898 -146.82978)
		(width 0.14732)
		(layer "In6.Cu")
		(net "UPI_CPU1_CPU0_P0P1_DN<12>")
	)
	(segment
		(start 275.789898 -146.82978)
		(end 238.603282 -147.499324)
		(width 0.14732)
		(layer "In6.Cu")
		(net "UPI_CPU1_CPU0_P0P1_DN<12>")
	)
	(segment
		(start 100.499926 -211.270342)
		(end 100.499926 -211.77123)
		(width 0.14732)
		(layer "In6.Cu")
		(net "UPI_CPU1_CPU0_P0P1_DN<12>")
	)
	(segment
		(start 100.499926 -211.793328)
		(end 100.457762 -211.835492)
		(width 0.0889)
		(layer "In6.Cu")
		(net "UPI_CPU1_CPU0_P0P1_DN<12>")
	)
	(segment
		(start 100.233734 -214.22487)
		(end 100.203508 -214.321644)
		(width 0.0889)
		(layer "In6.Cu")
		(net "UPI_CPU1_CPU0_P0P1_DN<12>")
	)
	(segment
		(start 349.31096 -167.024558)
		(end 349.15602 -166.756334)
		(width 0.14732)
		(layer "In6.Cu")
		(net "UPI_CPU1_CPU0_P0P1_DN<12>")
	)
	(segment
		(start 349.165672 -167.565832)
		(end 349.31096 -167.024558)
		(width 0.14732)
		(layer "In6.Cu")
		(net "UPI_CPU1_CPU0_P0P1_DN<12>")
	)
	(segment
		(start 108.545884 -190.893192)
		(end 108.316522 -191.180974)
		(width 0.14732)
		(layer "In6.Cu")
		(net "UPI_CPU1_CPU0_P0P1_DN<12>")
	)
	(segment
		(start 108.749338 -190.870078)
		(end 108.545884 -190.893192)
		(width 0.14732)
		(layer "In6.Cu")
		(net "UPI_CPU1_CPU0_P0P1_DN<12>")
	)
	(segment
		(start 108.979208 -190.582042)
		(end 108.749338 -190.870078)
		(width 0.14732)
		(layer "In6.Cu")
		(net "UPI_CPU1_CPU0_P0P1_DN<12>")
	)
	(segment
		(start 109.801152 -189.55131)
		(end 109.571282 -189.839346)
		(width 0.14732)
		(layer "In6.Cu")
		(net "UPI_CPU1_CPU0_P0P1_DN<12>")
	)
	(segment
		(start 111.594138 -187.302394)
		(end 111.390684 -187.325508)
		(width 0.14732)
		(layer "In6.Cu")
		(net "UPI_CPU1_CPU0_P0P1_DN<12>")
	)
	(segment
		(start 110.938564 -188.124592)
		(end 110.73511 -188.147706)
		(width 0.14732)
		(layer "In6.Cu")
		(net "UPI_CPU1_CPU0_P0P1_DN<12>")
	)
	(segment
		(start 111.801148 -186.810904)
		(end 111.824008 -187.014358)
		(width 0.14732)
		(layer "In6.Cu")
		(net "UPI_CPU1_CPU0_P0P1_DN<12>")
	)
	(segment
		(start 108.956348 -190.378588)
		(end 108.979208 -190.582042)
		(width 0.14732)
		(layer "In6.Cu")
		(net "UPI_CPU1_CPU0_P0P1_DN<12>")
	)
	(segment
		(start 109.778292 -189.347856)
		(end 109.801152 -189.55131)
		(width 0.14732)
		(layer "In6.Cu")
		(net "UPI_CPU1_CPU0_P0P1_DN<12>")
	)
	(segment
		(start 100.457762 -211.835492)
		(end 100.457762 -213.93023)
		(width 0.0889)
		(layer "In6.Cu")
		(net "UPI_CPU1_CPU0_P0P1_DN<12>")
	)
	(segment
		(start 112.265714 -186.227974)
		(end 111.801148 -186.810904)
		(width 0.14732)
		(layer "In6.Cu")
		(net "UPI_CPU1_CPU0_P0P1_DN<12>")
	)
	(segment
		(start 107.576874 -192.108582)
		(end 100.499926 -211.270342)
		(width 0.14732)
		(layer "In6.Cu")
		(net "UPI_CPU1_CPU0_P0P1_DN<12>")
	)
	(segment
		(start 130.328162 -169.225468)
		(end 112.265714 -186.227974)
		(width 0.14732)
		(layer "In6.Cu")
		(net "UPI_CPU1_CPU0_P0P1_DN<12>")
	)
	(segment
		(start 170.28414 -146.403314)
		(end 163.760404 -148.6535)
		(width 0.14732)
		(layer "In6.Cu")
		(net "UPI_CPU1_CPU0_P0P1_DN<12>")
	)
	(segment
		(start 107.906058 -191.695578)
		(end 107.576874 -192.108582)
		(width 0.14732)
		(layer "In6.Cu")
		(net "UPI_CPU1_CPU0_P0P1_DN<12>")
	)
	(arc
		(start 100.44303 -213.96833)
		(mid 100.356479 -214.111364)
		(end 100.233734 -214.22487)
		(width 0.0889)
		(layer "In6.Cu")
		(net "UPI_CPU1_CPU0_P0P1_DN<12>")
	)
	(arc
		(start 100.458016 -213.929468)
		(mid 100.450858 -213.949028)
		(end 100.44303 -213.96833)
		(width 0.0889)
		(layer "In6.Cu")
		(net "UPI_CPU1_CPU0_P0P1_DN<12>")
	)
	(segment
		(start 372.584726 -212.419692)
		(end 365.727742 -205.562708)
		(width 0.0889)
		(layer "F.Cu")
		(net "UPI_CPU1_CPU0_P0P1_DN<11>")
	)
	(segment
		(start 373.241062 -185.565542)
		(end 373.242078 -185.563256)
		(width 0.13208)
		(layer "F.Cu")
		(net "UPI_CPU1_CPU0_P0P1_DN<11>")
	)
	(segment
		(start 366.586516 -196.255386)
		(end 368.51082 -191.609472)
		(width 0.13208)
		(layer "F.Cu")
		(net "UPI_CPU1_CPU0_P0P1_DN<11>")
	)
	(segment
		(start 365.727742 -205.562708)
		(end 365.727742 -205.261464)
		(width 0.0889)
		(layer "F.Cu")
		(net "UPI_CPU1_CPU0_P0P1_DN<11>")
	)
	(segment
		(start 368.51082 -191.609472)
		(end 370.588032 -189.53226)
		(width 0.13208)
		(layer "F.Cu")
		(net "UPI_CPU1_CPU0_P0P1_DN<11>")
	)
	(segment
		(start 372.584726 -212.86089)
		(end 372.584726 -212.419692)
		(width 0.0889)
		(layer "F.Cu")
		(net "UPI_CPU1_CPU0_P0P1_DN<11>")
	)
	(segment
		(start 372.543324 -213.73211)
		(end 372.642384 -213.63305)
		(width 0.0889)
		(layer "F.Cu")
		(net "UPI_CPU1_CPU0_P0P1_DN<11>")
	)
	(segment
		(start 372.642384 -213.63305)
		(end 372.642384 -213.48065)
		(width 0.0889)
		(layer "F.Cu")
		(net "UPI_CPU1_CPU0_P0P1_DN<11>")
	)
	(segment
		(start 365.693452 -205.205076)
		(end 365.693452 -200.726802)
		(width 0.13208)
		(layer "F.Cu")
		(net "UPI_CPU1_CPU0_P0P1_DN<11>")
	)
	(segment
		(start 365.693452 -200.726802)
		(end 365.698278 -200.721976)
		(width 0.13208)
		(layer "F.Cu")
		(net "UPI_CPU1_CPU0_P0P1_DN<11>")
	)
	(segment
		(start 372.543324 -213.22919)
		(end 372.642384 -213.13013)
		(width 0.0889)
		(layer "F.Cu")
		(net "UPI_CPU1_CPU0_P0P1_DN<11>")
	)
	(segment
		(start 372.642384 -213.48065)
		(end 372.543324 -213.38159)
		(width 0.0889)
		(layer "F.Cu")
		(net "UPI_CPU1_CPU0_P0P1_DN<11>")
	)
	(segment
		(start 372.543324 -213.88451)
		(end 372.543324 -213.73211)
		(width 0.0889)
		(layer "F.Cu")
		(net "UPI_CPU1_CPU0_P0P1_DN<11>")
	)
	(segment
		(start 373.076978 -185.849514)
		(end 373.241062 -185.565542)
		(width 0.13208)
		(layer "F.Cu")
		(net "UPI_CPU1_CPU0_P0P1_DN<11>")
	)
	(segment
		(start 373.242078 -185.563256)
		(end 373.094504 -185.011568)
		(width 0.13208)
		(layer "F.Cu")
		(net "UPI_CPU1_CPU0_P0P1_DN<11>")
	)
	(segment
		(start 372.642384 -212.918548)
		(end 372.584726 -212.86089)
		(width 0.0889)
		(layer "F.Cu")
		(net "UPI_CPU1_CPU0_P0P1_DN<11>")
	)
	(segment
		(start 370.588032 -189.53226)
		(end 373.076978 -185.849514)
		(width 0.13208)
		(layer "F.Cu")
		(net "UPI_CPU1_CPU0_P0P1_DN<11>")
	)
	(segment
		(start 99.422712 -215.158574)
		(end 99.422712 -214.622888)
		(width 0.13208)
		(layer "F.Cu")
		(net "UPI_CPU1_CPU0_P0P1_DN<11>")
	)
	(segment
		(start 372.642384 -213.98357)
		(end 372.543324 -213.88451)
		(width 0.0889)
		(layer "F.Cu")
		(net "UPI_CPU1_CPU0_P0P1_DN<11>")
	)
	(segment
		(start 372.422928 -214.613744)
		(end 372.503954 -214.635334)
		(width 0.0889)
		(layer "F.Cu")
		(net "UPI_CPU1_CPU0_P0P1_DN<11>")
	)
	(segment
		(start 372.543324 -213.38159)
		(end 372.543324 -213.22919)
		(width 0.0889)
		(layer "F.Cu")
		(net "UPI_CPU1_CPU0_P0P1_DN<11>")
	)
	(segment
		(start 365.727742 -205.261464)
		(end 365.693452 -205.227174)
		(width 0.0889)
		(layer "F.Cu")
		(net "UPI_CPU1_CPU0_P0P1_DN<11>")
	)
	(segment
		(start 372.642384 -214.345012)
		(end 372.642384 -213.98357)
		(width 0.0889)
		(layer "F.Cu")
		(net "UPI_CPU1_CPU0_P0P1_DN<11>")
	)
	(segment
		(start 372.642384 -213.13013)
		(end 372.642384 -212.918548)
		(width 0.0889)
		(layer "F.Cu")
		(net "UPI_CPU1_CPU0_P0P1_DN<11>")
	)
	(segment
		(start 365.698278 -200.721976)
		(end 366.586516 -196.255386)
		(width 0.13208)
		(layer "F.Cu")
		(net "UPI_CPU1_CPU0_P0P1_DN<11>")
	)
	(segment
		(start 365.693452 -205.227174)
		(end 365.693452 -205.205076)
		(width 0.0889)
		(layer "F.Cu")
		(net "UPI_CPU1_CPU0_P0P1_DN<11>")
	)
	(segment
		(start 99.422712 -214.622888)
		(end 99.422458 -214.622634)
		(width 0.13208)
		(layer "F.Cu")
		(net "UPI_CPU1_CPU0_P0P1_DN<11>")
	)
	(segment
		(start 372.267734 -214.344758)
		(end 372.422928 -214.613744)
		(width 0.0889)
		(layer "F.Cu")
		(net "UPI_CPU1_CPU0_P0P1_DN<11>")
	)
	(arc
		(start 372.503954 -214.635334)
		(mid 372.60592 -214.505786)
		(end 372.642384 -214.345012)
		(width 0.0889)
		(layer "F.Cu")
		(net "UPI_CPU1_CPU0_P0P1_DN<11>")
	)
	(segment
		(start 370.365782 -183.681624)
		(end 370.54155 -183.576468)
		(width 0.14732)
		(layer "In6.Cu")
		(net "UPI_CPU1_CPU0_P0P1_DN<11>")
	)
	(segment
		(start 369.903502 -183.415686)
		(end 370.008404 -183.591708)
		(width 0.14732)
		(layer "In6.Cu")
		(net "UPI_CPU1_CPU0_P0P1_DN<11>")
	)
	(segment
		(start 107.598464 -190.522606)
		(end 107.870752 -190.18123)
		(width 0.14732)
		(layer "In6.Cu")
		(net "UPI_CPU1_CPU0_P0P1_DN<11>")
	)
	(segment
		(start 111.026448 -186.223656)
		(end 129.768092 -168.581832)
		(width 0.14732)
		(layer "In6.Cu")
		(net "UPI_CPU1_CPU0_P0P1_DN<11>")
	)
	(segment
		(start 107.344972 -191.03594)
		(end 107.617768 -190.694056)
		(width 0.14732)
		(layer "In6.Cu")
		(net "UPI_CPU1_CPU0_P0P1_DN<11>")
	)
	(segment
		(start 368.676936 -182.872126)
		(end 369.200684 -183.238902)
		(width 0.14732)
		(layer "In6.Cu")
		(net "UPI_CPU1_CPU0_P0P1_DN<11>")
	)
	(segment
		(start 369.200684 -183.238902)
		(end 369.903502 -183.415686)
		(width 0.14732)
		(layer "In6.Cu")
		(net "UPI_CPU1_CPU0_P0P1_DN<11>")
	)
	(segment
		(start 99.265994 -214.893652)
		(end 99.187762 -214.91448)
		(width 0.0889)
		(layer "In6.Cu")
		(net "UPI_CPU1_CPU0_P0P1_DN<11>")
	)
	(segment
		(start 370.898674 -183.66613)
		(end 371.003576 -183.842152)
		(width 0.14732)
		(layer "In6.Cu")
		(net "UPI_CPU1_CPU0_P0P1_DN<11>")
	)
	(segment
		(start 373.011446 -184.19826)
		(end 373.603266 -184.34685)
		(width 0.14732)
		(layer "In6.Cu")
		(net "UPI_CPU1_CPU0_P0P1_DN<11>")
	)
	(segment
		(start 372.532148 -184.077102)
		(end 372.888764 -184.167018)
		(width 0.14732)
		(layer "In6.Cu")
		(net "UPI_CPU1_CPU0_P0P1_DN<11>")
	)
	(segment
		(start 328.138028 -149.996652)
		(end 355.537008 -168.79697)
		(width 0.14732)
		(layer "In6.Cu")
		(net "UPI_CPU1_CPU0_P0P1_DN<11>")
	)
	(segment
		(start 109.01172 -188.946028)
		(end 108.992416 -188.774578)
		(width 0.14732)
		(layer "In6.Cu")
		(net "UPI_CPU1_CPU0_P0P1_DN<11>")
	)
	(segment
		(start 109.4359 -188.413898)
		(end 109.708696 -188.072014)
		(width 0.14732)
		(layer "In6.Cu")
		(net "UPI_CPU1_CPU0_P0P1_DN<11>")
	)
	(segment
		(start 99.518216 -213.516972)
		(end 99.61753 -213.417658)
		(width 0.0889)
		(layer "In6.Cu")
		(net "UPI_CPU1_CPU0_P0P1_DN<11>")
	)
	(segment
		(start 368.120422 -182.488078)
		(end 368.324892 -182.49519)
		(width 0.14732)
		(layer "In6.Cu")
		(net "UPI_CPU1_CPU0_P0P1_DN<11>")
	)
	(segment
		(start 99.047808 -214.622634)
		(end 99.047808 -214.461852)
		(width 0.0889)
		(layer "In6.Cu")
		(net "UPI_CPU1_CPU0_P0P1_DN<11>")
	)
	(segment
		(start 371.998748 -184.092596)
		(end 372.35638 -184.182512)
		(width 0.14732)
		(layer "In6.Cu")
		(net "UPI_CPU1_CPU0_P0P1_DN<11>")
	)
	(segment
		(start 108.738924 -189.287912)
		(end 109.01172 -188.946028)
		(width 0.14732)
		(layer "In6.Cu")
		(net "UPI_CPU1_CPU0_P0P1_DN<11>")
	)
	(segment
		(start 99.56038 -211.77123)
		(end 99.56038 -211.274406)
		(width 0.14732)
		(layer "In6.Cu")
		(net "UPI_CPU1_CPU0_P0P1_DN<11>")
	)
	(segment
		(start 238.600742 -146.667474)
		(end 276.075902 -145.99285)
		(width 0.14732)
		(layer "In6.Cu")
		(net "UPI_CPU1_CPU0_P0P1_DN<11>")
	)
	(segment
		(start 373.603266 -184.34685)
		(end 373.71528 -184.491122)
		(width 0.14732)
		(layer "In6.Cu")
		(net "UPI_CPU1_CPU0_P0P1_DN<11>")
	)
	(segment
		(start 99.56038 -211.274406)
		(end 106.901488 -191.39662)
		(width 0.14732)
		(layer "In6.Cu")
		(net "UPI_CPU1_CPU0_P0P1_DN<11>")
	)
	(segment
		(start 372.888764 -184.167018)
		(end 372.889272 -184.167526)
		(width 0.14732)
		(layer "In6.Cu")
		(net "UPI_CPU1_CPU0_P0P1_DN<11>")
	)
	(segment
		(start 355.537008 -168.79697)
		(end 367.87582 -182.014114)
		(width 0.14732)
		(layer "In6.Cu")
		(net "UPI_CPU1_CPU0_P0P1_DN<11>")
	)
	(segment
		(start 373.636032 -184.86628)
		(end 373.094504 -185.011568)
		(width 0.14732)
		(layer "In6.Cu")
		(net "UPI_CPU1_CPU0_P0P1_DN<11>")
	)
	(segment
		(start 99.61753 -212.41893)
		(end 99.518216 -212.319616)
		(width 0.0889)
		(layer "In6.Cu")
		(net "UPI_CPU1_CPU0_P0P1_DN<11>")
	)
	(segment
		(start 372.35638 -184.182512)
		(end 372.531894 -184.077356)
		(width 0.14732)
		(layer "In6.Cu")
		(net "UPI_CPU1_CPU0_P0P1_DN<11>")
	)
	(segment
		(start 109.264704 -188.433202)
		(end 109.4359 -188.413898)
		(width 0.14732)
		(layer "In6.Cu")
		(net "UPI_CPU1_CPU0_P0P1_DN<11>")
	)
	(segment
		(start 372.531894 -184.077356)
		(end 372.532148 -184.077102)
		(width 0.14732)
		(layer "In6.Cu")
		(net "UPI_CPU1_CPU0_P0P1_DN<11>")
	)
	(segment
		(start 371.536722 -183.826912)
		(end 371.893846 -183.916574)
		(width 0.14732)
		(layer "In6.Cu")
		(net "UPI_CPU1_CPU0_P0P1_DN<11>")
	)
	(segment
		(start 106.901488 -191.39662)
		(end 107.173776 -191.055244)
		(width 0.14732)
		(layer "In6.Cu")
		(net "UPI_CPU1_CPU0_P0P1_DN<11>")
	)
	(segment
		(start 109.689392 -187.900564)
		(end 111.026448 -186.223656)
		(width 0.14732)
		(layer "In6.Cu")
		(net "UPI_CPU1_CPU0_P0P1_DN<11>")
	)
	(segment
		(start 170.072558 -145.55851)
		(end 238.600742 -146.667474)
		(width 0.14732)
		(layer "In6.Cu")
		(net "UPI_CPU1_CPU0_P0P1_DN<11>")
	)
	(segment
		(start 99.61753 -213.417658)
		(end 99.61753 -213.150958)
		(width 0.0889)
		(layer "In6.Cu")
		(net "UPI_CPU1_CPU0_P0P1_DN<11>")
	)
	(segment
		(start 107.870752 -190.18123)
		(end 108.041948 -190.161926)
		(width 0.14732)
		(layer "In6.Cu")
		(net "UPI_CPU1_CPU0_P0P1_DN<11>")
	)
	(segment
		(start 370.008404 -183.591708)
		(end 370.365782 -183.681624)
		(width 0.14732)
		(layer "In6.Cu")
		(net "UPI_CPU1_CPU0_P0P1_DN<11>")
	)
	(segment
		(start 109.708696 -188.072014)
		(end 109.689392 -187.900564)
		(width 0.14732)
		(layer "In6.Cu")
		(net "UPI_CPU1_CPU0_P0P1_DN<11>")
	)
	(segment
		(start 108.314744 -189.820042)
		(end 108.29544 -189.648592)
		(width 0.14732)
		(layer "In6.Cu")
		(net "UPI_CPU1_CPU0_P0P1_DN<11>")
	)
	(segment
		(start 99.61753 -213.150958)
		(end 99.518216 -213.051644)
		(width 0.0889)
		(layer "In6.Cu")
		(net "UPI_CPU1_CPU0_P0P1_DN<11>")
	)
	(segment
		(start 99.518216 -212.319616)
		(end 99.518216 -211.835492)
		(width 0.0889)
		(layer "In6.Cu")
		(net "UPI_CPU1_CPU0_P0P1_DN<11>")
	)
	(segment
		(start 372.889272 -184.167526)
		(end 373.010938 -184.198006)
		(width 0.14732)
		(layer "In6.Cu")
		(net "UPI_CPU1_CPU0_P0P1_DN<11>")
	)
	(segment
		(start 368.324892 -182.49519)
		(end 368.676936 -182.872126)
		(width 0.14732)
		(layer "In6.Cu")
		(net "UPI_CPU1_CPU0_P0P1_DN<11>")
	)
	(segment
		(start 373.71528 -184.491122)
		(end 373.761508 -184.650888)
		(width 0.14732)
		(layer "In6.Cu")
		(net "UPI_CPU1_CPU0_P0P1_DN<11>")
	)
	(segment
		(start 108.567728 -189.307216)
		(end 108.738924 -189.287912)
		(width 0.14732)
		(layer "In6.Cu")
		(net "UPI_CPU1_CPU0_P0P1_DN<11>")
	)
	(segment
		(start 99.61753 -212.68563)
		(end 99.61753 -212.41893)
		(width 0.0889)
		(layer "In6.Cu")
		(net "UPI_CPU1_CPU0_P0P1_DN<11>")
	)
	(segment
		(start 99.518216 -211.835492)
		(end 99.56038 -211.793328)
		(width 0.0889)
		(layer "In6.Cu")
		(net "UPI_CPU1_CPU0_P0P1_DN<11>")
	)
	(segment
		(start 99.422458 -214.622634)
		(end 99.265994 -214.893652)
		(width 0.0889)
		(layer "In6.Cu")
		(net "UPI_CPU1_CPU0_P0P1_DN<11>")
	)
	(segment
		(start 99.518216 -213.929468)
		(end 99.518216 -213.516972)
		(width 0.0889)
		(layer "In6.Cu")
		(net "UPI_CPU1_CPU0_P0P1_DN<11>")
	)
	(segment
		(start 367.87582 -182.014114)
		(end 367.868708 -182.218584)
		(width 0.14732)
		(layer "In6.Cu")
		(net "UPI_CPU1_CPU0_P0P1_DN<11>")
	)
	(segment
		(start 371.003576 -183.842152)
		(end 371.361208 -183.932068)
		(width 0.14732)
		(layer "In6.Cu")
		(net "UPI_CPU1_CPU0_P0P1_DN<11>")
	)
	(segment
		(start 319.042288 -147.663916)
		(end 328.138028 -149.996652)
		(width 0.14732)
		(layer "In6.Cu")
		(net "UPI_CPU1_CPU0_P0P1_DN<11>")
	)
	(segment
		(start 99.518216 -212.784944)
		(end 99.61753 -212.68563)
		(width 0.0889)
		(layer "In6.Cu")
		(net "UPI_CPU1_CPU0_P0P1_DN<11>")
	)
	(segment
		(start 367.868708 -182.218584)
		(end 368.120422 -182.488078)
		(width 0.14732)
		(layer "In6.Cu")
		(net "UPI_CPU1_CPU0_P0P1_DN<11>")
	)
	(segment
		(start 108.992416 -188.774578)
		(end 109.264704 -188.433202)
		(width 0.14732)
		(layer "In6.Cu")
		(net "UPI_CPU1_CPU0_P0P1_DN<11>")
	)
	(segment
		(start 108.29544 -189.648592)
		(end 108.567728 -189.307216)
		(width 0.14732)
		(layer "In6.Cu")
		(net "UPI_CPU1_CPU0_P0P1_DN<11>")
	)
	(segment
		(start 163.492942 -147.830794)
		(end 170.072558 -145.55851)
		(width 0.14732)
		(layer "In6.Cu")
		(net "UPI_CPU1_CPU0_P0P1_DN<11>")
	)
	(segment
		(start 371.893846 -183.916574)
		(end 371.998748 -184.092596)
		(width 0.14732)
		(layer "In6.Cu")
		(net "UPI_CPU1_CPU0_P0P1_DN<11>")
	)
	(segment
		(start 107.173776 -191.055244)
		(end 107.344972 -191.03594)
		(width 0.14732)
		(layer "In6.Cu")
		(net "UPI_CPU1_CPU0_P0P1_DN<11>")
	)
	(segment
		(start 373.761508 -184.650888)
		(end 373.636032 -184.86628)
		(width 0.14732)
		(layer "In6.Cu")
		(net "UPI_CPU1_CPU0_P0P1_DN<11>")
	)
	(segment
		(start 99.518216 -213.051644)
		(end 99.518216 -212.784944)
		(width 0.0889)
		(layer "In6.Cu")
		(net "UPI_CPU1_CPU0_P0P1_DN<11>")
	)
	(segment
		(start 107.617768 -190.694056)
		(end 107.598464 -190.522606)
		(width 0.14732)
		(layer "In6.Cu")
		(net "UPI_CPU1_CPU0_P0P1_DN<11>")
	)
	(segment
		(start 129.768092 -168.581832)
		(end 163.492942 -147.830794)
		(width 0.14732)
		(layer "In6.Cu")
		(net "UPI_CPU1_CPU0_P0P1_DN<11>")
	)
	(segment
		(start 276.075902 -145.99285)
		(end 319.042288 -147.663916)
		(width 0.14732)
		(layer "In6.Cu")
		(net "UPI_CPU1_CPU0_P0P1_DN<11>")
	)
	(segment
		(start 370.54155 -183.576468)
		(end 370.898674 -183.66613)
		(width 0.14732)
		(layer "In6.Cu")
		(net "UPI_CPU1_CPU0_P0P1_DN<11>")
	)
	(segment
		(start 373.010938 -184.198006)
		(end 373.011446 -184.19826)
		(width 0.14732)
		(layer "In6.Cu")
		(net "UPI_CPU1_CPU0_P0P1_DN<11>")
	)
	(segment
		(start 99.56038 -211.793328)
		(end 99.56038 -211.77123)
		(width 0.0889)
		(layer "In6.Cu")
		(net "UPI_CPU1_CPU0_P0P1_DN<11>")
	)
	(segment
		(start 371.361208 -183.932068)
		(end 371.536722 -183.826912)
		(width 0.14732)
		(layer "In6.Cu")
		(net "UPI_CPU1_CPU0_P0P1_DN<11>")
	)
	(segment
		(start 108.041948 -190.161926)
		(end 108.314744 -189.820042)
		(width 0.14732)
		(layer "In6.Cu")
		(net "UPI_CPU1_CPU0_P0P1_DN<11>")
	)
	(arc
		(start 99.047808 -214.461852)
		(mid 99.122879 -214.34611)
		(end 99.232212 -214.261954)
		(width 0.0889)
		(layer "In6.Cu")
		(net "UPI_CPU1_CPU0_P0P1_DN<11>")
	)
	(arc
		(start 99.232212 -214.261954)
		(mid 99.392793 -214.138523)
		(end 99.502976 -213.968584)
		(width 0.0889)
		(layer "In6.Cu")
		(net "UPI_CPU1_CPU0_P0P1_DN<11>")
	)
	(arc
		(start 99.502976 -213.968584)
		(mid 99.510941 -213.94916)
		(end 99.518216 -213.929468)
		(width 0.0889)
		(layer "In6.Cu")
		(net "UPI_CPU1_CPU0_P0P1_DN<11>")
	)
	(arc
		(start 99.187762 -214.91448)
		(mid 99.084617 -214.784455)
		(end 99.047808 -214.622634)
		(width 0.0889)
		(layer "In6.Cu")
		(net "UPI_CPU1_CPU0_P0P1_DN<11>")
	)
	(segment
		(start 373.437658 -188.5315)
		(end 373.61368 -188.5315)
		(width 0.13208)
		(layer "F.Cu")
		(net "UPI_CPU1_CPU0_P0P1_DN<10>")
	)
	(segment
		(start 374.673368 -184.681622)
		(end 373.013224 -183.994044)
		(width 0.13208)
		(layer "F.Cu")
		(net "UPI_CPU1_CPU0_P0P1_DN<10>")
	)
	(segment
		(start 373.320564 -215.597232)
		(end 373.320818 -215.597232)
		(width 0.0889)
		(layer "F.Cu")
		(net "UPI_CPU1_CPU0_P0P1_DN<10>")
	)
	(segment
		(start 367.001552 -205.205076)
		(end 367.001552 -200.88225)
		(width 0.13208)
		(layer "F.Cu")
		(net "UPI_CPU1_CPU0_P0P1_DN<10>")
	)
	(segment
		(start 374.948958 -187.196222)
		(end 375.355358 -186.216036)
		(width 0.13208)
		(layer "F.Cu")
		(net "UPI_CPU1_CPU0_P0P1_DN<10>")
	)
	(segment
		(start 373.369332 -214.643716)
		(end 373.396256 -214.627968)
		(width 0.0889)
		(layer "F.Cu")
		(net "UPI_CPU1_CPU0_P0P1_DN<10>")
	)
	(segment
		(start 373.582184 -213.285578)
		(end 373.582438 -213.285324)
		(width 0.0889)
		(layer "F.Cu")
		(net "UPI_CPU1_CPU0_P0P1_DN<10>")
	)
	(segment
		(start 367.035842 -205.261464)
		(end 367.001552 -205.227174)
		(width 0.0889)
		(layer "F.Cu")
		(net "UPI_CPU1_CPU0_P0P1_DN<10>")
	)
	(segment
		(start 367.001552 -200.88225)
		(end 367.849658 -196.618352)
		(width 0.13208)
		(layer "F.Cu")
		(net "UPI_CPU1_CPU0_P0P1_DN<10>")
	)
	(segment
		(start 375.355358 -186.216036)
		(end 375.355358 -185.41238)
		(width 0.13208)
		(layer "F.Cu")
		(net "UPI_CPU1_CPU0_P0P1_DN<10>")
	)
	(segment
		(start 373.582438 -213.285324)
		(end 373.582438 -212.264244)
		(width 0.0889)
		(layer "F.Cu")
		(net "UPI_CPU1_CPU0_P0P1_DN<10>")
	)
	(segment
		(start 98.482912 -214.622888)
		(end 98.482658 -214.622634)
		(width 0.13208)
		(layer "F.Cu")
		(net "UPI_CPU1_CPU0_P0P1_DN<10>")
	)
	(segment
		(start 373.11203 -215.158828)
		(end 373.11203 -215.087708)
		(width 0.0889)
		(layer "F.Cu")
		(net "UPI_CPU1_CPU0_P0P1_DN<10>")
	)
	(segment
		(start 98.482912 -215.158574)
		(end 98.482912 -214.622888)
		(width 0.13208)
		(layer "F.Cu")
		(net "UPI_CPU1_CPU0_P0P1_DN<10>")
	)
	(segment
		(start 367.849658 -196.618352)
		(end 369.492276 -192.652904)
		(width 0.13208)
		(layer "F.Cu")
		(net "UPI_CPU1_CPU0_P0P1_DN<10>")
	)
	(segment
		(start 373.582184 -214.304372)
		(end 373.582184 -213.285578)
		(width 0.0889)
		(layer "F.Cu")
		(net "UPI_CPU1_CPU0_P0P1_DN<10>")
	)
	(segment
		(start 367.001552 -205.227174)
		(end 367.001552 -205.205076)
		(width 0.0889)
		(layer "F.Cu")
		(net "UPI_CPU1_CPU0_P0P1_DN<10>")
	)
	(segment
		(start 373.61368 -188.5315)
		(end 374.948958 -187.196222)
		(width 0.13208)
		(layer "F.Cu")
		(net "UPI_CPU1_CPU0_P0P1_DN<10>")
	)
	(segment
		(start 370.6749 -182.26532)
		(end 370.122704 -182.115968)
		(width 0.13208)
		(layer "F.Cu")
		(net "UPI_CPU1_CPU0_P0P1_DN<10>")
	)
	(segment
		(start 373.156988 -188.81217)
		(end 373.437658 -188.5315)
		(width 0.13208)
		(layer "F.Cu")
		(net "UPI_CPU1_CPU0_P0P1_DN<10>")
	)
	(segment
		(start 367.238026 -205.919832)
		(end 367.035842 -205.430374)
		(width 0.0889)
		(layer "F.Cu")
		(net "UPI_CPU1_CPU0_P0P1_DN<10>")
	)
	(segment
		(start 375.355358 -185.41238)
		(end 375.320814 -185.329068)
		(width 0.13208)
		(layer "F.Cu")
		(net "UPI_CPU1_CPU0_P0P1_DN<10>")
	)
	(segment
		(start 370.830094 -182.53583)
		(end 370.6749 -182.26532)
		(width 0.13208)
		(layer "F.Cu")
		(net "UPI_CPU1_CPU0_P0P1_DN<10>")
	)
	(segment
		(start 375.320814 -185.329068)
		(end 374.673368 -184.681622)
		(width 0.13208)
		(layer "F.Cu")
		(net "UPI_CPU1_CPU0_P0P1_DN<10>")
	)
	(segment
		(start 373.362728 -215.703658)
		(end 373.337582 -215.610694)
		(width 0.0889)
		(layer "F.Cu")
		(net "UPI_CPU1_CPU0_P0P1_DN<10>")
	)
	(segment
		(start 373.21236 -215.964262)
		(end 373.362728 -215.703658)
		(width 0.0889)
		(layer "F.Cu")
		(net "UPI_CPU1_CPU0_P0P1_DN<10>")
	)
	(segment
		(start 373.013224 -183.994044)
		(end 370.830094 -182.53583)
		(width 0.13208)
		(layer "F.Cu")
		(net "UPI_CPU1_CPU0_P0P1_DN<10>")
	)
	(segment
		(start 373.156988 -188.988192)
		(end 373.156988 -188.81217)
		(width 0.13208)
		(layer "F.Cu")
		(net "UPI_CPU1_CPU0_P0P1_DN<10>")
	)
	(segment
		(start 369.492276 -192.652904)
		(end 373.156988 -188.988192)
		(width 0.13208)
		(layer "F.Cu")
		(net "UPI_CPU1_CPU0_P0P1_DN<10>")
	)
	(segment
		(start 367.035842 -205.430374)
		(end 367.035842 -205.261464)
		(width 0.0889)
		(layer "F.Cu")
		(net "UPI_CPU1_CPU0_P0P1_DN<10>")
	)
	(segment
		(start 373.207534 -215.972644)
		(end 373.21236 -215.964262)
		(width 0.0889)
		(layer "F.Cu")
		(net "UPI_CPU1_CPU0_P0P1_DN<10>")
	)
	(segment
		(start 373.582438 -212.264244)
		(end 367.238026 -205.919832)
		(width 0.0889)
		(layer "F.Cu")
		(net "UPI_CPU1_CPU0_P0P1_DN<10>")
	)
	(arc
		(start 373.320818 -215.597232)
		(mid 373.166931 -215.401598)
		(end 373.11203 -215.158828)
		(width 0.0889)
		(layer "F.Cu")
		(net "UPI_CPU1_CPU0_P0P1_DN<10>")
	)
	(arc
		(start 373.396256 -214.627968)
		(mid 373.532362 -214.490965)
		(end 373.582184 -214.304372)
		(width 0.0889)
		(layer "F.Cu")
		(net "UPI_CPU1_CPU0_P0P1_DN<10>")
	)
	(arc
		(start 373.35587 -214.65159)
		(mid 373.36257 -214.647601)
		(end 373.369332 -214.643716)
		(width 0.0889)
		(layer "F.Cu")
		(net "UPI_CPU1_CPU0_P0P1_DN<10>")
	)
	(arc
		(start 373.11203 -215.087708)
		(mid 373.177139 -214.837893)
		(end 373.35587 -214.65159)
		(width 0.0889)
		(layer "F.Cu")
		(net "UPI_CPU1_CPU0_P0P1_DN<10>")
	)
	(arc
		(start 373.337582 -215.610694)
		(mid 373.329008 -215.604045)
		(end 373.320564 -215.597232)
		(width 0.0889)
		(layer "F.Cu")
		(net "UPI_CPU1_CPU0_P0P1_DN<10>")
	)
	(segment
		(start 367.570258 -179.742338)
		(end 367.56848 -179.947062)
		(width 0.14732)
		(layer "In6.Cu")
		(net "UPI_CPU1_CPU0_P0P1_DN<10>")
	)
	(segment
		(start 369.884452 -181.1147)
		(end 370.163852 -181.3941)
		(width 0.14732)
		(layer "In6.Cu")
		(net "UPI_CPU1_CPU0_P0P1_DN<10>")
	)
	(segment
		(start 106.668316 -190.35522)
		(end 106.940858 -190.013336)
		(width 0.14732)
		(layer "In6.Cu")
		(net "UPI_CPU1_CPU0_P0P1_DN<10>")
	)
	(segment
		(start 367.308892 -179.4764)
		(end 367.570258 -179.742338)
		(width 0.14732)
		(layer "In6.Cu")
		(net "UPI_CPU1_CPU0_P0P1_DN<10>")
	)
	(segment
		(start 108.587794 -187.752736)
		(end 108.75899 -187.733432)
		(width 0.14732)
		(layer "In6.Cu")
		(net "UPI_CPU1_CPU0_P0P1_DN<10>")
	)
	(segment
		(start 98.578416 -213.929468)
		(end 98.578162 -213.93023)
		(width 0.0889)
		(layer "In6.Cu")
		(net "UPI_CPU1_CPU0_P0P1_DN<10>")
	)
	(segment
		(start 108.33481 -188.265562)
		(end 108.315506 -188.094112)
		(width 0.14732)
		(layer "In6.Cu")
		(net "UPI_CPU1_CPU0_P0P1_DN<10>")
	)
	(segment
		(start 106.921554 -189.84214)
		(end 107.193842 -189.500764)
		(width 0.14732)
		(layer "In6.Cu")
		(net "UPI_CPU1_CPU0_P0P1_DN<10>")
	)
	(segment
		(start 367.827052 -180.209952)
		(end 368.031776 -180.21173)
		(width 0.14732)
		(layer "In6.Cu")
		(net "UPI_CPU1_CPU0_P0P1_DN<10>")
	)
	(segment
		(start 108.062014 -188.607446)
		(end 108.33481 -188.265562)
		(width 0.14732)
		(layer "In6.Cu")
		(net "UPI_CPU1_CPU0_P0P1_DN<10>")
	)
	(segment
		(start 109.012482 -187.220098)
		(end 109.88421 -186.126882)
		(width 0.14732)
		(layer "In6.Cu")
		(net "UPI_CPU1_CPU0_P0P1_DN<10>")
	)
	(segment
		(start 106.940858 -190.013336)
		(end 106.921554 -189.84214)
		(width 0.14732)
		(layer "In6.Cu")
		(net "UPI_CPU1_CPU0_P0P1_DN<10>")
	)
	(segment
		(start 108.75899 -187.733432)
		(end 109.031786 -187.391548)
		(width 0.14732)
		(layer "In6.Cu")
		(net "UPI_CPU1_CPU0_P0P1_DN<10>")
	)
	(segment
		(start 98.482658 -214.622634)
		(end 98.323908 -214.321644)
		(width 0.0889)
		(layer "In6.Cu")
		(net "UPI_CPU1_CPU0_P0P1_DN<10>")
	)
	(segment
		(start 107.61853 -188.968126)
		(end 107.890818 -188.62675)
		(width 0.14732)
		(layer "In6.Cu")
		(net "UPI_CPU1_CPU0_P0P1_DN<10>")
	)
	(segment
		(start 356.416102 -168.391332)
		(end 366.847628 -179.006754)
		(width 0.14732)
		(layer "In6.Cu")
		(net "UPI_CPU1_CPU0_P0P1_DN<10>")
	)
	(segment
		(start 369.066064 -180.978048)
		(end 369.884452 -181.1147)
		(width 0.14732)
		(layer "In6.Cu")
		(net "UPI_CPU1_CPU0_P0P1_DN<10>")
	)
	(segment
		(start 107.890818 -188.62675)
		(end 108.062014 -188.607446)
		(width 0.14732)
		(layer "In6.Cu")
		(net "UPI_CPU1_CPU0_P0P1_DN<10>")
	)
	(segment
		(start 368.515392 -180.703982)
		(end 369.066064 -180.978048)
		(width 0.14732)
		(layer "In6.Cu")
		(net "UPI_CPU1_CPU0_P0P1_DN<10>")
	)
	(segment
		(start 98.578162 -213.93023)
		(end 98.578162 -211.835492)
		(width 0.0889)
		(layer "In6.Cu")
		(net "UPI_CPU1_CPU0_P0P1_DN<10>")
	)
	(segment
		(start 163.037266 -147.099274)
		(end 169.913808 -144.724882)
		(width 0.14732)
		(layer "In6.Cu")
		(net "UPI_CPU1_CPU0_P0P1_DN<10>")
	)
	(segment
		(start 366.84585 -179.211478)
		(end 367.104168 -179.474622)
		(width 0.14732)
		(layer "In6.Cu")
		(net "UPI_CPU1_CPU0_P0P1_DN<10>")
	)
	(segment
		(start 106.496866 -190.374524)
		(end 106.668316 -190.35522)
		(width 0.14732)
		(layer "In6.Cu")
		(net "UPI_CPU1_CPU0_P0P1_DN<10>")
	)
	(segment
		(start 367.56848 -179.947062)
		(end 367.827052 -180.209952)
		(width 0.14732)
		(layer "In6.Cu")
		(net "UPI_CPU1_CPU0_P0P1_DN<10>")
	)
	(segment
		(start 368.031776 -180.21173)
		(end 368.515392 -180.703982)
		(width 0.14732)
		(layer "In6.Cu")
		(net "UPI_CPU1_CPU0_P0P1_DN<10>")
	)
	(segment
		(start 109.88421 -186.126882)
		(end 129.278634 -167.87114)
		(width 0.14732)
		(layer "In6.Cu")
		(net "UPI_CPU1_CPU0_P0P1_DN<10>")
	)
	(segment
		(start 129.278634 -167.87114)
		(end 163.037266 -147.099274)
		(width 0.14732)
		(layer "In6.Cu")
		(net "UPI_CPU1_CPU0_P0P1_DN<10>")
	)
	(segment
		(start 107.365038 -189.48146)
		(end 107.637834 -189.139576)
		(width 0.14732)
		(layer "In6.Cu")
		(net "UPI_CPU1_CPU0_P0P1_DN<10>")
	)
	(segment
		(start 98.578162 -211.835492)
		(end 98.620326 -211.793328)
		(width 0.0889)
		(layer "In6.Cu")
		(net "UPI_CPU1_CPU0_P0P1_DN<10>")
	)
	(segment
		(start 366.847628 -179.006754)
		(end 366.84585 -179.211478)
		(width 0.14732)
		(layer "In6.Cu")
		(net "UPI_CPU1_CPU0_P0P1_DN<10>")
	)
	(segment
		(start 109.031786 -187.391548)
		(end 109.012482 -187.220098)
		(width 0.14732)
		(layer "In6.Cu")
		(net "UPI_CPU1_CPU0_P0P1_DN<10>")
	)
	(segment
		(start 169.913808 -144.724882)
		(end 238.598202 -145.836386)
		(width 0.14732)
		(layer "In6.Cu")
		(net "UPI_CPU1_CPU0_P0P1_DN<10>")
	)
	(segment
		(start 98.323908 -214.321644)
		(end 98.354134 -214.22487)
		(width 0.0889)
		(layer "In6.Cu")
		(net "UPI_CPU1_CPU0_P0P1_DN<10>")
	)
	(segment
		(start 98.620326 -211.793328)
		(end 98.620326 -211.77123)
		(width 0.0889)
		(layer "In6.Cu")
		(net "UPI_CPU1_CPU0_P0P1_DN<10>")
	)
	(segment
		(start 319.21958 -146.837146)
		(end 328.458576 -149.208236)
		(width 0.14732)
		(layer "In6.Cu")
		(net "UPI_CPU1_CPU0_P0P1_DN<10>")
	)
	(segment
		(start 370.163852 -181.3941)
		(end 370.267992 -181.57444)
		(width 0.14732)
		(layer "In6.Cu")
		(net "UPI_CPU1_CPU0_P0P1_DN<10>")
	)
	(segment
		(start 367.104168 -179.474622)
		(end 367.308892 -179.4764)
		(width 0.14732)
		(layer "In6.Cu")
		(net "UPI_CPU1_CPU0_P0P1_DN<10>")
	)
	(segment
		(start 106.204766 -190.741046)
		(end 106.496866 -190.374524)
		(width 0.14732)
		(layer "In6.Cu")
		(net "UPI_CPU1_CPU0_P0P1_DN<10>")
	)
	(segment
		(start 98.620326 -211.77123)
		(end 98.620326 -211.278978)
		(width 0.14732)
		(layer "In6.Cu")
		(net "UPI_CPU1_CPU0_P0P1_DN<10>")
	)
	(segment
		(start 108.315506 -188.094112)
		(end 108.587794 -187.752736)
		(width 0.14732)
		(layer "In6.Cu")
		(net "UPI_CPU1_CPU0_P0P1_DN<10>")
	)
	(segment
		(start 107.193842 -189.500764)
		(end 107.365038 -189.48146)
		(width 0.14732)
		(layer "In6.Cu")
		(net "UPI_CPU1_CPU0_P0P1_DN<10>")
	)
	(segment
		(start 276.121368 -145.161)
		(end 319.21958 -146.837146)
		(width 0.14732)
		(layer "In6.Cu")
		(net "UPI_CPU1_CPU0_P0P1_DN<10>")
	)
	(segment
		(start 107.637834 -189.139576)
		(end 107.61853 -188.968126)
		(width 0.14732)
		(layer "In6.Cu")
		(net "UPI_CPU1_CPU0_P0P1_DN<10>")
	)
	(segment
		(start 238.598202 -145.836386)
		(end 276.121368 -145.161)
		(width 0.14732)
		(layer "In6.Cu")
		(net "UPI_CPU1_CPU0_P0P1_DN<10>")
	)
	(segment
		(start 328.458576 -149.208236)
		(end 356.416102 -168.391332)
		(width 0.14732)
		(layer "In6.Cu")
		(net "UPI_CPU1_CPU0_P0P1_DN<10>")
	)
	(segment
		(start 98.620326 -211.278978)
		(end 106.204766 -190.741046)
		(width 0.14732)
		(layer "In6.Cu")
		(net "UPI_CPU1_CPU0_P0P1_DN<10>")
	)
	(segment
		(start 370.267992 -181.57444)
		(end 370.122704 -182.115968)
		(width 0.14732)
		(layer "In6.Cu")
		(net "UPI_CPU1_CPU0_P0P1_DN<10>")
	)
	(arc
		(start 98.56343 -213.96833)
		(mid 98.571265 -213.949031)
		(end 98.578416 -213.929468)
		(width 0.0889)
		(layer "In6.Cu")
		(net "UPI_CPU1_CPU0_P0P1_DN<10>")
	)
	(arc
		(start 98.354134 -214.22487)
		(mid 98.47688 -214.111365)
		(end 98.56343 -213.96833)
		(width 0.0889)
		(layer "In6.Cu")
		(net "UPI_CPU1_CPU0_P0P1_DN<10>")
	)
	(segment
		(start 383.291334 -214.09787)
		(end 383.291334 -213.94547)
		(width 0.0889)
		(layer "F.Cu")
		(net "UPI_CPU1_CPU0_P0P1_DN<0>")
	)
	(segment
		(start 375.955052 -167.34917)
		(end 374.756934 -166.365936)
		(width 0.13208)
		(layer "F.Cu")
		(net "UPI_CPU1_CPU0_P0P1_DN<0>")
	)
	(segment
		(start 386.352034 -177.500788)
		(end 377.324874 -168.473374)
		(width 0.13208)
		(layer "F.Cu")
		(net "UPI_CPU1_CPU0_P0P1_DN<0>")
	)
	(segment
		(start 390.458198 -191.645794)
		(end 390.458198 -187.413646)
		(width 0.13208)
		(layer "F.Cu")
		(net "UPI_CPU1_CPU0_P0P1_DN<0>")
	)
	(segment
		(start 380.082298 -202.624182)
		(end 380.37643 -201.145394)
		(width 0.13208)
		(layer "F.Cu")
		(net "UPI_CPU1_CPU0_P0P1_DN<0>")
	)
	(segment
		(start 383.390394 -214.789766)
		(end 383.390394 -214.19693)
		(width 0.0889)
		(layer "F.Cu")
		(net "UPI_CPU1_CPU0_P0P1_DN<0>")
	)
	(segment
		(start 376.212354 -167.72128)
		(end 376.195082 -167.546274)
		(width 0.13208)
		(layer "F.Cu")
		(net "UPI_CPU1_CPU0_P0P1_DN<0>")
	)
	(segment
		(start 372.166896 -167.068754)
		(end 371.99189 -167.051482)
		(width 0.13208)
		(layer "F.Cu")
		(net "UPI_CPU1_CPU0_P0P1_DN<0>")
	)
	(segment
		(start 380.683516 -207.81391)
		(end 380.116588 -206.445104)
		(width 0.0889)
		(layer "F.Cu")
		(net "UPI_CPU1_CPU0_P0P1_DN<0>")
	)
	(segment
		(start 381.014986 -199.603614)
		(end 384.2893 -196.328792)
		(width 0.13208)
		(layer "F.Cu")
		(net "UPI_CPU1_CPU0_P0P1_DN<0>")
	)
	(segment
		(start 89.084912 -216.78646)
		(end 89.084912 -216.250774)
		(width 0.13208)
		(layer "F.Cu")
		(net "UPI_CPU1_CPU0_P0P1_DN<0>")
	)
	(segment
		(start 374.756934 -166.365936)
		(end 374.042432 -166.110158)
		(width 0.13208)
		(layer "F.Cu")
		(net "UPI_CPU1_CPU0_P0P1_DN<0>")
	)
	(segment
		(start 370.6749 -167.02532)
		(end 370.122704 -166.875968)
		(width 0.13208)
		(layer "F.Cu")
		(net "UPI_CPU1_CPU0_P0P1_DN<0>")
	)
	(segment
		(start 372.490746 -166.642034)
		(end 372.473474 -166.81704)
		(width 0.13208)
		(layer "F.Cu")
		(net "UPI_CPU1_CPU0_P0P1_DN<0>")
	)
	(segment
		(start 383.07518 -215.348566)
		(end 383.192528 -215.465914)
		(width 0.0889)
		(layer "F.Cu")
		(net "UPI_CPU1_CPU0_P0P1_DN<0>")
	)
	(segment
		(start 380.37643 -201.145394)
		(end 381.014986 -199.603614)
		(width 0.13208)
		(layer "F.Cu")
		(net "UPI_CPU1_CPU0_P0P1_DN<0>")
	)
	(segment
		(start 376.195082 -167.546274)
		(end 375.955052 -167.34917)
		(width 0.13208)
		(layer "F.Cu")
		(net "UPI_CPU1_CPU0_P0P1_DN<0>")
	)
	(segment
		(start 377.324874 -168.473374)
		(end 376.693938 -167.955722)
		(width 0.13208)
		(layer "F.Cu")
		(net "UPI_CPU1_CPU0_P0P1_DN<0>")
	)
	(segment
		(start 380.116588 -205.261464)
		(end 380.082298 -205.227174)
		(width 0.0889)
		(layer "F.Cu")
		(net "UPI_CPU1_CPU0_P0P1_DN<0>")
	)
	(segment
		(start 384.2893 -196.328792)
		(end 388.76732 -193.336672)
		(width 0.13208)
		(layer "F.Cu")
		(net "UPI_CPU1_CPU0_P0P1_DN<0>")
	)
	(segment
		(start 383.318258 -215.465914)
		(end 383.484628 -215.299544)
		(width 0.0889)
		(layer "F.Cu")
		(net "UPI_CPU1_CPU0_P0P1_DN<0>")
	)
	(segment
		(start 371.588792 -167.38219)
		(end 371.127782 -167.419782)
		(width 0.13208)
		(layer "F.Cu")
		(net "UPI_CPU1_CPU0_P0P1_DN<0>")
	)
	(segment
		(start 371.127782 -167.419782)
		(end 370.788438 -167.223186)
		(width 0.13208)
		(layer "F.Cu")
		(net "UPI_CPU1_CPU0_P0P1_DN<0>")
	)
	(segment
		(start 383.390394 -213.84641)
		(end 383.390394 -212.057996)
		(width 0.0889)
		(layer "F.Cu")
		(net "UPI_CPU1_CPU0_P0P1_DN<0>")
	)
	(segment
		(start 388.76732 -193.336672)
		(end 390.458198 -191.645794)
		(width 0.13208)
		(layer "F.Cu")
		(net "UPI_CPU1_CPU0_P0P1_DN<0>")
	)
	(segment
		(start 371.99189 -167.051482)
		(end 371.588792 -167.38219)
		(width 0.13208)
		(layer "F.Cu")
		(net "UPI_CPU1_CPU0_P0P1_DN<0>")
	)
	(segment
		(start 383.390394 -214.19693)
		(end 383.291334 -214.09787)
		(width 0.0889)
		(layer "F.Cu")
		(net "UPI_CPU1_CPU0_P0P1_DN<0>")
	)
	(segment
		(start 374.042432 -166.110158)
		(end 373.1387 -166.110158)
		(width 0.13208)
		(layer "F.Cu")
		(net "UPI_CPU1_CPU0_P0P1_DN<0>")
	)
	(segment
		(start 383.390394 -212.057996)
		(end 382.303274 -209.433668)
		(width 0.0889)
		(layer "F.Cu")
		(net "UPI_CPU1_CPU0_P0P1_DN<0>")
	)
	(segment
		(start 373.1387 -166.110158)
		(end 372.490746 -166.642034)
		(width 0.13208)
		(layer "F.Cu")
		(net "UPI_CPU1_CPU0_P0P1_DN<0>")
	)
	(segment
		(start 380.082298 -205.227174)
		(end 380.082298 -205.205076)
		(width 0.0889)
		(layer "F.Cu")
		(net "UPI_CPU1_CPU0_P0P1_DN<0>")
	)
	(segment
		(start 390.458198 -187.413646)
		(end 386.352034 -177.500788)
		(width 0.13208)
		(layer "F.Cu")
		(net "UPI_CPU1_CPU0_P0P1_DN<0>")
	)
	(segment
		(start 383.484628 -214.884)
		(end 383.390394 -214.789766)
		(width 0.0889)
		(layer "F.Cu")
		(net "UPI_CPU1_CPU0_P0P1_DN<0>")
	)
	(segment
		(start 383.07518 -215.158574)
		(end 383.07518 -215.348566)
		(width 0.0889)
		(layer "F.Cu")
		(net "UPI_CPU1_CPU0_P0P1_DN<0>")
	)
	(segment
		(start 376.693938 -167.955722)
		(end 376.518932 -167.972994)
		(width 0.13208)
		(layer "F.Cu")
		(net "UPI_CPU1_CPU0_P0P1_DN<0>")
	)
	(segment
		(start 383.192528 -215.465914)
		(end 383.318258 -215.465914)
		(width 0.0889)
		(layer "F.Cu")
		(net "UPI_CPU1_CPU0_P0P1_DN<0>")
	)
	(segment
		(start 89.084912 -216.250774)
		(end 89.084658 -216.25052)
		(width 0.13208)
		(layer "F.Cu")
		(net "UPI_CPU1_CPU0_P0P1_DN<0>")
	)
	(segment
		(start 382.303274 -209.433668)
		(end 380.683516 -207.81391)
		(width 0.0889)
		(layer "F.Cu")
		(net "UPI_CPU1_CPU0_P0P1_DN<0>")
	)
	(segment
		(start 376.518932 -167.972994)
		(end 376.212354 -167.72128)
		(width 0.13208)
		(layer "F.Cu")
		(net "UPI_CPU1_CPU0_P0P1_DN<0>")
	)
	(segment
		(start 380.116588 -206.445104)
		(end 380.116588 -205.261464)
		(width 0.0889)
		(layer "F.Cu")
		(net "UPI_CPU1_CPU0_P0P1_DN<0>")
	)
	(segment
		(start 372.473474 -166.81704)
		(end 372.166896 -167.068754)
		(width 0.13208)
		(layer "F.Cu")
		(net "UPI_CPU1_CPU0_P0P1_DN<0>")
	)
	(segment
		(start 370.788438 -167.223186)
		(end 370.6749 -167.02532)
		(width 0.13208)
		(layer "F.Cu")
		(net "UPI_CPU1_CPU0_P0P1_DN<0>")
	)
	(segment
		(start 383.291334 -213.94547)
		(end 383.390394 -213.84641)
		(width 0.0889)
		(layer "F.Cu")
		(net "UPI_CPU1_CPU0_P0P1_DN<0>")
	)
	(segment
		(start 380.082298 -205.205076)
		(end 380.082298 -202.624182)
		(width 0.13208)
		(layer "F.Cu")
		(net "UPI_CPU1_CPU0_P0P1_DN<0>")
	)
	(segment
		(start 383.484628 -215.299544)
		(end 383.484628 -214.884)
		(width 0.0889)
		(layer "F.Cu")
		(net "UPI_CPU1_CPU0_P0P1_DN<0>")
	)
	(segment
		(start 169.45102 -135.894572)
		(end 238.59998 -137.03046)
		(width 0.14732)
		(layer "In6.Cu")
		(net "UPI_CPU1_CPU0_P0P1_DN<0>")
	)
	(segment
		(start 95.908622 -192.226438)
		(end 98.102674 -186.392058)
		(width 0.14732)
		(layer "In6.Cu")
		(net "UPI_CPU1_CPU0_P0P1_DN<0>")
	)
	(segment
		(start 122.98299 -161.795206)
		(end 159.618426 -139.261088)
		(width 0.14732)
		(layer "In6.Cu")
		(net "UPI_CPU1_CPU0_P0P1_DN<0>")
	)
	(segment
		(start 88.710262 -214.63127)
		(end 88.710262 -214.031068)
		(width 0.0889)
		(layer "In6.Cu")
		(net "UPI_CPU1_CPU0_P0P1_DN<0>")
	)
	(segment
		(start 89.084658 -216.25052)
		(end 88.928194 -215.979502)
		(width 0.0889)
		(layer "In6.Cu")
		(net "UPI_CPU1_CPU0_P0P1_DN<0>")
	)
	(segment
		(start 98.102674 -186.392058)
		(end 102.05085 -181.478174)
		(width 0.14732)
		(layer "In6.Cu")
		(net "UPI_CPU1_CPU0_P0P1_DN<0>")
	)
	(segment
		(start 310.962548 -138.039856)
		(end 319.223136 -138.039856)
		(width 0.14732)
		(layer "In6.Cu")
		(net "UPI_CPU1_CPU0_P0P1_DN<0>")
	)
	(segment
		(start 87.880698 -209.87131)
		(end 87.620094 -209.610706)
		(width 0.14732)
		(layer "In6.Cu")
		(net "UPI_CPU1_CPU0_P0P1_DN<0>")
	)
	(segment
		(start 367.102898 -164.241734)
		(end 367.30305 -164.197792)
		(width 0.14732)
		(layer "In6.Cu")
		(net "UPI_CPU1_CPU0_P0P1_DN<0>")
	)
	(segment
		(start 370.267992 -166.334186)
		(end 370.122704 -166.875968)
		(width 0.14732)
		(layer "In6.Cu")
		(net "UPI_CPU1_CPU0_P0P1_DN<0>")
	)
	(segment
		(start 89.076276 -213.665054)
		(end 89.076276 -213.477348)
		(width 0.0889)
		(layer "In6.Cu")
		(net "UPI_CPU1_CPU0_P0P1_DN<0>")
	)
	(segment
		(start 89.072212 -211.609432)
		(end 89.114376 -211.567268)
		(width 0.0889)
		(layer "In6.Cu")
		(net "UPI_CPU1_CPU0_P0P1_DN<0>")
	)
	(segment
		(start 368.5413 -164.988494)
		(end 368.585242 -165.188646)
		(width 0.14732)
		(layer "In6.Cu")
		(net "UPI_CPU1_CPU0_P0P1_DN<0>")
	)
	(segment
		(start 370.188744 -166.197534)
		(end 370.267992 -166.334186)
		(width 0.14732)
		(layer "In6.Cu")
		(net "UPI_CPU1_CPU0_P0P1_DN<0>")
	)
	(segment
		(start 87.880698 -210.076034)
		(end 87.880698 -209.87131)
		(width 0.14732)
		(layer "In6.Cu")
		(net "UPI_CPU1_CPU0_P0P1_DN<0>")
	)
	(segment
		(start 88.606376 -210.596988)
		(end 88.345772 -210.336384)
		(width 0.14732)
		(layer "In6.Cu")
		(net "UPI_CPU1_CPU0_P0P1_DN<0>")
	)
	(segment
		(start 85.380576 -205.919832)
		(end 85.65388 -204.41285)
		(width 0.14732)
		(layer "In6.Cu")
		(net "UPI_CPU1_CPU0_P0P1_DN<0>")
	)
	(segment
		(start 85.415882 -207.02397)
		(end 85.380576 -205.919832)
		(width 0.14732)
		(layer "In6.Cu")
		(net "UPI_CPU1_CPU0_P0P1_DN<0>")
	)
	(segment
		(start 88.345772 -210.336384)
		(end 88.141048 -210.336384)
		(width 0.14732)
		(layer "In6.Cu")
		(net "UPI_CPU1_CPU0_P0P1_DN<0>")
	)
	(segment
		(start 88.141048 -210.336384)
		(end 87.880698 -210.076034)
		(width 0.14732)
		(layer "In6.Cu")
		(net "UPI_CPU1_CPU0_P0P1_DN<0>")
	)
	(segment
		(start 272.311114 -136.414764)
		(end 310.962548 -138.039856)
		(width 0.14732)
		(layer "In6.Cu")
		(net "UPI_CPU1_CPU0_P0P1_DN<0>")
	)
	(segment
		(start 89.180162 -215.436704)
		(end 89.180162 -215.42248)
		(width 0.0889)
		(layer "In6.Cu")
		(net "UPI_CPU1_CPU0_P0P1_DN<0>")
	)
	(segment
		(start 89.114376 -211.309712)
		(end 88.606376 -210.801712)
		(width 0.14732)
		(layer "In6.Cu")
		(net "UPI_CPU1_CPU0_P0P1_DN<0>")
	)
	(segment
		(start 89.114376 -211.54517)
		(end 89.114376 -211.309712)
		(width 0.14732)
		(layer "In6.Cu")
		(net "UPI_CPU1_CPU0_P0P1_DN<0>")
	)
	(segment
		(start 368.895884 -165.386766)
		(end 369.095782 -165.342824)
		(width 0.14732)
		(layer "In6.Cu")
		(net "UPI_CPU1_CPU0_P0P1_DN<0>")
	)
	(segment
		(start 319.223136 -138.039856)
		(end 334.460088 -141.945868)
		(width 0.14732)
		(layer "In6.Cu")
		(net "UPI_CPU1_CPU0_P0P1_DN<0>")
	)
	(segment
		(start 85.65388 -204.41285)
		(end 95.908622 -192.226438)
		(width 0.14732)
		(layer "In6.Cu")
		(net "UPI_CPU1_CPU0_P0P1_DN<0>")
	)
	(segment
		(start 89.072212 -213.473284)
		(end 89.072212 -211.609432)
		(width 0.0889)
		(layer "In6.Cu")
		(net "UPI_CPU1_CPU0_P0P1_DN<0>")
	)
	(segment
		(start 102.05085 -181.478174)
		(end 122.98299 -161.795206)
		(width 0.14732)
		(layer "In6.Cu")
		(net "UPI_CPU1_CPU0_P0P1_DN<0>")
	)
	(segment
		(start 88.606376 -210.801712)
		(end 88.606376 -210.596988)
		(width 0.14732)
		(layer "In6.Cu")
		(net "UPI_CPU1_CPU0_P0P1_DN<0>")
	)
	(segment
		(start 85.92566 -208.120742)
		(end 85.415882 -207.02397)
		(width 0.14732)
		(layer "In6.Cu")
		(net "UPI_CPU1_CPU0_P0P1_DN<0>")
	)
	(segment
		(start 86.689692 -208.885028)
		(end 85.92566 -208.120742)
		(width 0.14732)
		(layer "In6.Cu")
		(net "UPI_CPU1_CPU0_P0P1_DN<0>")
	)
	(segment
		(start 367.720372 -164.636196)
		(end 368.031014 -164.834316)
		(width 0.14732)
		(layer "In6.Cu")
		(net "UPI_CPU1_CPU0_P0P1_DN<0>")
	)
	(segment
		(start 367.676176 -164.436044)
		(end 367.720372 -164.636196)
		(width 0.14732)
		(layer "In6.Cu")
		(net "UPI_CPU1_CPU0_P0P1_DN<0>")
	)
	(segment
		(start 159.618426 -139.261088)
		(end 169.45102 -135.894572)
		(width 0.14732)
		(layer "In6.Cu")
		(net "UPI_CPU1_CPU0_P0P1_DN<0>")
	)
	(segment
		(start 334.460088 -141.945868)
		(end 361.316778 -160.37433)
		(width 0.14732)
		(layer "In6.Cu")
		(net "UPI_CPU1_CPU0_P0P1_DN<0>")
	)
	(segment
		(start 87.41537 -209.610706)
		(end 87.15502 -209.350356)
		(width 0.14732)
		(layer "In6.Cu")
		(net "UPI_CPU1_CPU0_P0P1_DN<0>")
	)
	(segment
		(start 368.031014 -164.834316)
		(end 368.230912 -164.790374)
		(width 0.14732)
		(layer "In6.Cu")
		(net "UPI_CPU1_CPU0_P0P1_DN<0>")
	)
	(segment
		(start 86.894416 -208.885028)
		(end 86.689692 -208.885028)
		(width 0.14732)
		(layer "In6.Cu")
		(net "UPI_CPU1_CPU0_P0P1_DN<0>")
	)
	(segment
		(start 87.620094 -209.610706)
		(end 87.41537 -209.610706)
		(width 0.14732)
		(layer "In6.Cu")
		(net "UPI_CPU1_CPU0_P0P1_DN<0>")
	)
	(segment
		(start 89.076276 -213.477348)
		(end 89.072212 -213.473284)
		(width 0.0889)
		(layer "In6.Cu")
		(net "UPI_CPU1_CPU0_P0P1_DN<0>")
	)
	(segment
		(start 361.316778 -160.37433)
		(end 366.748314 -163.843462)
		(width 0.14732)
		(layer "In6.Cu")
		(net "UPI_CPU1_CPU0_P0P1_DN<0>")
	)
	(segment
		(start 368.585242 -165.188646)
		(end 368.895884 -165.386766)
		(width 0.14732)
		(layer "In6.Cu")
		(net "UPI_CPU1_CPU0_P0P1_DN<0>")
	)
	(segment
		(start 369.891564 -165.851078)
		(end 370.188744 -166.197534)
		(width 0.14732)
		(layer "In6.Cu")
		(net "UPI_CPU1_CPU0_P0P1_DN<0>")
	)
	(segment
		(start 89.114376 -211.567268)
		(end 89.114376 -211.54517)
		(width 0.0889)
		(layer "In6.Cu")
		(net "UPI_CPU1_CPU0_P0P1_DN<0>")
	)
	(segment
		(start 368.230912 -164.790374)
		(end 368.5413 -164.988494)
		(width 0.14732)
		(layer "In6.Cu")
		(net "UPI_CPU1_CPU0_P0P1_DN<0>")
	)
	(segment
		(start 88.928194 -215.979502)
		(end 88.952324 -215.890348)
		(width 0.0889)
		(layer "In6.Cu")
		(net "UPI_CPU1_CPU0_P0P1_DN<0>")
	)
	(segment
		(start 88.710262 -214.031068)
		(end 89.076276 -213.665054)
		(width 0.0889)
		(layer "In6.Cu")
		(net "UPI_CPU1_CPU0_P0P1_DN<0>")
	)
	(segment
		(start 366.748314 -163.843462)
		(end 366.792256 -164.043614)
		(width 0.14732)
		(layer "In6.Cu")
		(net "UPI_CPU1_CPU0_P0P1_DN<0>")
	)
	(segment
		(start 367.30305 -164.197792)
		(end 367.676176 -164.436044)
		(width 0.14732)
		(layer "In6.Cu")
		(net "UPI_CPU1_CPU0_P0P1_DN<0>")
	)
	(segment
		(start 87.15502 -209.145632)
		(end 86.894416 -208.885028)
		(width 0.14732)
		(layer "In6.Cu")
		(net "UPI_CPU1_CPU0_P0P1_DN<0>")
	)
	(segment
		(start 369.095782 -165.342824)
		(end 369.891564 -165.851078)
		(width 0.14732)
		(layer "In6.Cu")
		(net "UPI_CPU1_CPU0_P0P1_DN<0>")
	)
	(segment
		(start 366.792256 -164.043614)
		(end 367.102898 -164.241734)
		(width 0.14732)
		(layer "In6.Cu")
		(net "UPI_CPU1_CPU0_P0P1_DN<0>")
	)
	(segment
		(start 87.15502 -209.350356)
		(end 87.15502 -209.145632)
		(width 0.14732)
		(layer "In6.Cu")
		(net "UPI_CPU1_CPU0_P0P1_DN<0>")
	)
	(segment
		(start 238.59998 -137.03046)
		(end 272.311114 -136.414764)
		(width 0.14732)
		(layer "In6.Cu")
		(net "UPI_CPU1_CPU0_P0P1_DN<0>")
	)
	(arc
		(start 89.180162 -215.42248)
		(mid 89.100943 -215.147795)
		(end 88.89746 -214.946992)
		(width 0.0889)
		(layer "In6.Cu")
		(net "UPI_CPU1_CPU0_P0P1_DN<0>")
	)
	(arc
		(start 88.89746 -214.946992)
		(mid 88.762527 -214.813638)
		(end 88.710262 -214.63127)
		(width 0.0889)
		(layer "In6.Cu")
		(net "UPI_CPU1_CPU0_P0P1_DN<0>")
	)
	(arc
		(start 88.952324 -215.890348)
		(mid 88.960896 -215.883826)
		(end 88.969342 -215.87714)
		(width 0.0889)
		(layer "In6.Cu")
		(net "UPI_CPU1_CPU0_P0P1_DN<0>")
	)
	(arc
		(start 88.969342 -215.87714)
		(mid 89.12474 -215.680859)
		(end 89.180162 -215.436704)
		(width 0.0889)
		(layer "In6.Cu")
		(net "UPI_CPU1_CPU0_P0P1_DN<0>")
	)
	(segment
		(start 349.352362 -281.05608)
		(end 349.352362 -281.591766)
		(width 0.13208)
		(layer "F.Cu")
		(net "UPI_CPU0_CPU1_P2P2_DP<9>")
	)
	(segment
		(start 96.713294 -282.683966)
		(end 96.713294 -283.219652)
		(width 0.13208)
		(layer "F.Cu")
		(net "UPI_CPU0_CPU1_P2P2_DP<9>")
	)
	(segment
		(start 96.713294 -283.219652)
		(end 96.713548 -283.219906)
		(width 0.13208)
		(layer "F.Cu")
		(net "UPI_CPU0_CPU1_P2P2_DP<9>")
	)
	(segment
		(start 349.352362 -281.591766)
		(end 349.352616 -281.59202)
		(width 0.13208)
		(layer "F.Cu")
		(net "UPI_CPU0_CPU1_P2P2_DP<9>")
	)
	(segment
		(start 96.047306 -283.714444)
		(end 96.068388 -283.702252)
		(width 0.0889)
		(layer "In6.Cu")
		(net "UPI_CPU0_CPU1_P2P2_DP<9>")
	)
	(segment
		(start 161.327846 -385.05511)
		(end 129.7051 -385.05511)
		(width 0.14732)
		(layer "In6.Cu")
		(net "UPI_CPU0_CPU1_P2P2_DP<9>")
	)
	(segment
		(start 348.6023 -283.54274)
		(end 348.600522 -283.543756)
		(width 0.0889)
		(layer "In6.Cu")
		(net "UPI_CPU0_CPU1_P2P2_DP<9>")
	)
	(segment
		(start 344.02268 -300.149514)
		(end 341.302848 -302.869346)
		(width 0.14732)
		(layer "In6.Cu")
		(net "UPI_CPU0_CPU1_P2P2_DP<9>")
	)
	(segment
		(start 347.669104 -285.166816)
		(end 347.653864 -285.175706)
		(width 0.0889)
		(layer "In6.Cu")
		(net "UPI_CPU0_CPU1_P2P2_DP<9>")
	)
	(segment
		(start 344.975942 -292.53307)
		(end 344.975942 -292.70833)
		(width 0.0889)
		(layer "In6.Cu")
		(net "UPI_CPU0_CPU1_P2P2_DP<9>")
	)
	(segment
		(start 347.191076 -287.61309)
		(end 347.19006 -287.613598)
		(width 0.0889)
		(layer "In6.Cu")
		(net "UPI_CPU0_CPU1_P2P2_DP<9>")
	)
	(segment
		(start 93.519498 -288.121598)
		(end 93.519498 -288.103056)
		(width 0.0889)
		(layer "In6.Cu")
		(net "UPI_CPU0_CPU1_P2P2_DP<9>")
	)
	(segment
		(start 91.731084 -292.718236)
		(end 91.731084 -292.235128)
		(width 0.14732)
		(layer "In6.Cu")
		(net "UPI_CPU0_CPU1_P2P2_DP<9>")
	)
	(segment
		(start 94.081346 -287.778698)
		(end 94.096078 -287.787334)
		(width 0.0889)
		(layer "In6.Cu")
		(net "UPI_CPU0_CPU1_P2P2_DP<9>")
	)
	(segment
		(start 63.749936 -331.371448)
		(end 63.674244 -330.941426)
		(width 0.14732)
		(layer "In6.Cu")
		(net "UPI_CPU0_CPU1_P2P2_DP<9>")
	)
	(segment
		(start 65.939162 -323.960744)
		(end 67.691254 -320.25844)
		(width 0.14732)
		(layer "In6.Cu")
		(net "UPI_CPU0_CPU1_P2P2_DP<9>")
	)
	(segment
		(start 95.116396 -285.985712)
		(end 95.115634 -285.985204)
		(width 0.0889)
		(layer "In6.Cu")
		(net "UPI_CPU0_CPU1_P2P2_DP<9>")
	)
	(segment
		(start 348.60865 -283.539184)
		(end 348.607888 -283.539692)
		(width 0.0889)
		(layer "In6.Cu")
		(net "UPI_CPU0_CPU1_P2P2_DP<9>")
	)
	(segment
		(start 95.868744 -284.049216)
		(end 95.868744 -284.033722)
		(width 0.0889)
		(layer "In6.Cu")
		(net "UPI_CPU0_CPU1_P2P2_DP<9>")
	)
	(segment
		(start 129.02438 -385.05511)
		(end 128.5875 -385.05511)
		(width 0.14732)
		(layer "In6.Cu")
		(net "UPI_CPU0_CPU1_P2P2_DP<9>")
	)
	(segment
		(start 91.731084 -292.235128)
		(end 93.352112 -290.6141)
		(width 0.14732)
		(layer "In6.Cu")
		(net "UPI_CPU0_CPU1_P2P2_DP<9>")
	)
	(segment
		(start 346.907866 -288.087562)
		(end 346.907866 -288.103056)
		(width 0.0889)
		(layer "In6.Cu")
		(net "UPI_CPU0_CPU1_P2P2_DP<9>")
	)
	(segment
		(start 128.46558 -384.93319)
		(end 128.0287 -384.93319)
		(width 0.14732)
		(layer "In6.Cu")
		(net "UPI_CPU0_CPU1_P2P2_DP<9>")
	)
	(segment
		(start 95.107506 -286.969962)
		(end 95.128588 -286.95777)
		(width 0.0889)
		(layer "In6.Cu")
		(net "UPI_CPU0_CPU1_P2P2_DP<9>")
	)
	(segment
		(start 64.205358 -333.935324)
		(end 64.201294 -333.93126)
		(width 0.14732)
		(layer "In6.Cu")
		(net "UPI_CPU0_CPU1_P2P2_DP<9>")
	)
	(segment
		(start 346.5195 -290.35121)
		(end 346.5195 -290.491672)
		(width 0.0889)
		(layer "In6.Cu")
		(net "UPI_CPU0_CPU1_P2P2_DP<9>")
	)
	(segment
		(start 95.57766 -284.52826)
		(end 95.58655 -284.52318)
		(width 0.0889)
		(layer "In6.Cu")
		(net "UPI_CPU0_CPU1_P2P2_DP<9>")
	)
	(segment
		(start 87.4268 -298.80433)
		(end 87.56777 -298.46397)
		(width 0.14732)
		(layer "In6.Cu")
		(net "UPI_CPU0_CPU1_P2P2_DP<9>")
	)
	(segment
		(start 85.599778 -302.554386)
		(end 85.599778 -302.349662)
		(width 0.14732)
		(layer "In6.Cu")
		(net "UPI_CPU0_CPU1_P2P2_DP<9>")
	)
	(segment
		(start 348.600522 -283.543756)
		(end 348.59976 -283.544264)
		(width 0.0889)
		(layer "In6.Cu")
		(net "UPI_CPU0_CPU1_P2P2_DP<9>")
	)
	(segment
		(start 85.13445 -302.81499)
		(end 85.339174 -302.81499)
		(width 0.14732)
		(layer "In6.Cu")
		(net "UPI_CPU0_CPU1_P2P2_DP<9>")
	)
	(segment
		(start 344.975942 -293.08171)
		(end 344.975942 -293.25697)
		(width 0.0889)
		(layer "In6.Cu")
		(net "UPI_CPU0_CPU1_P2P2_DP<9>")
	)
	(segment
		(start 86.652608 -300.294294)
		(end 86.842092 -300.216062)
		(width 0.14732)
		(layer "In6.Cu")
		(net "UPI_CPU0_CPU1_P2P2_DP<9>")
	)
	(segment
		(start 344.975942 -292.70833)
		(end 344.876882 -292.80739)
		(width 0.0889)
		(layer "In6.Cu")
		(net "UPI_CPU0_CPU1_P2P2_DP<9>")
	)
	(segment
		(start 347.659452 -286.80029)
		(end 347.656658 -286.801814)
		(width 0.0889)
		(layer "In6.Cu")
		(net "UPI_CPU0_CPU1_P2P2_DP<9>")
	)
	(segment
		(start 344.876882 -292.80739)
		(end 344.876882 -292.98265)
		(width 0.0889)
		(layer "In6.Cu")
		(net "UPI_CPU0_CPU1_P2P2_DP<9>")
	)
	(segment
		(start 346.437966 -288.898584)
		(end 346.437966 -289.114738)
		(width 0.0889)
		(layer "In6.Cu")
		(net "UPI_CPU0_CPU1_P2P2_DP<9>")
	)
	(segment
		(start 344.876882 -293.53129)
		(end 344.975942 -293.63035)
		(width 0.0889)
		(layer "In6.Cu")
		(net "UPI_CPU0_CPU1_P2P2_DP<9>")
	)
	(segment
		(start 85.599778 -302.349662)
		(end 85.944202 -302.005238)
		(width 0.14732)
		(layer "In6.Cu")
		(net "UPI_CPU0_CPU1_P2P2_DP<9>")
	)
	(segment
		(start 64.328802 -329.13701)
		(end 64.514222 -328.818494)
		(width 0.14732)
		(layer "In6.Cu")
		(net "UPI_CPU0_CPU1_P2P2_DP<9>")
	)
	(segment
		(start 93.352112 -290.6141)
		(end 93.367606 -290.598606)
		(width 0.0889)
		(layer "In6.Cu")
		(net "UPI_CPU0_CPU1_P2P2_DP<9>")
	)
	(segment
		(start 128.0287 -384.93319)
		(end 127.90678 -385.05511)
		(width 0.14732)
		(layer "In6.Cu")
		(net "UPI_CPU0_CPU1_P2P2_DP<9>")
	)
	(segment
		(start 86.842092 -300.216062)
		(end 86.983062 -299.875448)
		(width 0.14732)
		(layer "In6.Cu")
		(net "UPI_CPU0_CPU1_P2P2_DP<9>")
	)
	(segment
		(start 94.928944 -287.304734)
		(end 94.928944 -287.28924)
		(width 0.0889)
		(layer "In6.Cu")
		(net "UPI_CPU0_CPU1_P2P2_DP<9>")
	)
	(segment
		(start 95.107506 -285.342076)
		(end 95.114872 -285.337758)
		(width 0.0889)
		(layer "In6.Cu")
		(net "UPI_CPU0_CPU1_P2P2_DP<9>")
	)
	(segment
		(start 63.8683 -332.042262)
		(end 63.96736 -331.901038)
		(width 0.14732)
		(layer "In6.Cu")
		(net "UPI_CPU0_CPU1_P2P2_DP<9>")
	)
	(segment
		(start 344.934032 -294.810434)
		(end 344.933778 -294.810688)
		(width 0.14732)
		(layer "In6.Cu")
		(net "UPI_CPU0_CPU1_P2P2_DP<9>")
	)
	(segment
		(start 93.51899 -290.387278)
		(end 93.51899 -289.610292)
		(width 0.0889)
		(layer "In6.Cu")
		(net "UPI_CPU0_CPU1_P2P2_DP<9>")
	)
	(segment
		(start 64.514222 -328.818494)
		(end 64.462152 -328.620628)
		(width 0.14732)
		(layer "In6.Cu")
		(net "UPI_CPU0_CPU1_P2P2_DP<9>")
	)
	(segment
		(start 347.653864 -285.175706)
		(end 347.654118 -285.175452)
		(width 0.0889)
		(layer "In6.Cu")
		(net "UPI_CPU0_CPU1_P2P2_DP<9>")
	)
	(segment
		(start 344.876882 -292.98265)
		(end 344.975942 -293.08171)
		(width 0.0889)
		(layer "In6.Cu")
		(net "UPI_CPU0_CPU1_P2P2_DP<9>")
	)
	(segment
		(start 64.462152 -328.620628)
		(end 64.812926 -328.01941)
		(width 0.14732)
		(layer "In6.Cu")
		(net "UPI_CPU0_CPU1_P2P2_DP<9>")
	)
	(segment
		(start 95.117158 -285.336488)
		(end 95.122492 -285.33344)
		(width 0.0889)
		(layer "In6.Cu")
		(net "UPI_CPU0_CPU1_P2P2_DP<9>")
	)
	(segment
		(start 95.114872 -285.337758)
		(end 95.116396 -285.336996)
		(width 0.0889)
		(layer "In6.Cu")
		(net "UPI_CPU0_CPU1_P2P2_DP<9>")
	)
	(segment
		(start 344.975942 -292.15969)
		(end 344.876882 -292.25875)
		(width 0.0889)
		(layer "In6.Cu")
		(net "UPI_CPU0_CPU1_P2P2_DP<9>")
	)
	(segment
		(start 344.876882 -293.90467)
		(end 344.876882 -294.07993)
		(width 0.0889)
		(layer "In6.Cu")
		(net "UPI_CPU0_CPU1_P2P2_DP<9>")
	)
	(segment
		(start 344.934032 -294.614346)
		(end 344.934032 -294.810434)
		(width 0.14732)
		(layer "In6.Cu")
		(net "UPI_CPU0_CPU1_P2P2_DP<9>")
	)
	(segment
		(start 63.674244 -330.941426)
		(end 63.919608 -329.550522)
		(width 0.14732)
		(layer "In6.Cu")
		(net "UPI_CPU0_CPU1_P2P2_DP<9>")
	)
	(segment
		(start 67.691508 -320.257932)
		(end 84.408772 -303.540668)
		(width 0.14732)
		(layer "In6.Cu")
		(net "UPI_CPU0_CPU1_P2P2_DP<9>")
	)
	(segment
		(start 348.59976 -282.895548)
		(end 348.60865 -282.900628)
		(width 0.0889)
		(layer "In6.Cu")
		(net "UPI_CPU0_CPU1_P2P2_DP<9>")
	)
	(segment
		(start 348.614746 -281.907742)
		(end 348.593918 -281.919934)
		(width 0.0889)
		(layer "In6.Cu")
		(net "UPI_CPU0_CPU1_P2P2_DP<9>")
	)
	(segment
		(start 349.541338 -281.268424)
		(end 349.548704 -281.272742)
		(width 0.0889)
		(layer "In6.Cu")
		(net "UPI_CPU0_CPU1_P2P2_DP<9>")
	)
	(segment
		(start 349.539814 -281.267662)
		(end 349.541338 -281.268424)
		(width 0.0889)
		(layer "In6.Cu")
		(net "UPI_CPU0_CPU1_P2P2_DP<9>")
	)
	(segment
		(start 84.613496 -303.540668)
		(end 84.8741 -303.280064)
		(width 0.14732)
		(layer "In6.Cu")
		(net "UPI_CPU0_CPU1_P2P2_DP<9>")
	)
	(segment
		(start 87.56777 -298.46397)
		(end 87.489284 -298.27474)
		(width 0.14732)
		(layer "In6.Cu")
		(net "UPI_CPU0_CPU1_P2P2_DP<9>")
	)
	(segment
		(start 347.660214 -286.799782)
		(end 347.659452 -286.80029)
		(width 0.0889)
		(layer "In6.Cu")
		(net "UPI_CPU0_CPU1_P2P2_DP<9>")
	)
	(segment
		(start 63.919608 -329.550522)
		(end 64.130428 -329.18908)
		(width 0.14732)
		(layer "In6.Cu")
		(net "UPI_CPU0_CPU1_P2P2_DP<9>")
	)
	(segment
		(start 96.478852 -282.92806)
		(end 96.557084 -282.948888)
		(width 0.0889)
		(layer "In6.Cu")
		(net "UPI_CPU0_CPU1_P2P2_DP<9>")
	)
	(segment
		(start 349.196152 -281.321002)
		(end 349.217234 -281.243024)
		(width 0.0889)
		(layer "In6.Cu")
		(net "UPI_CPU0_CPU1_P2P2_DP<9>")
	)
	(segment
		(start 86.449408 -301.164244)
		(end 86.590124 -300.82363)
		(width 0.14732)
		(layer "In6.Cu")
		(net "UPI_CPU0_CPU1_P2P2_DP<9>")
	)
	(segment
		(start 84.8741 -303.280064)
		(end 84.8741 -303.07534)
		(width 0.14732)
		(layer "In6.Cu")
		(net "UPI_CPU0_CPU1_P2P2_DP<9>")
	)
	(segment
		(start 346.907612 -290.10356)
		(end 346.783914 -290.227258)
		(width 0.0889)
		(layer "In6.Cu")
		(net "UPI_CPU0_CPU1_P2P2_DP<9>")
	)
	(segment
		(start 346.729304 -288.422334)
		(end 346.720414 -288.427414)
		(width 0.0889)
		(layer "In6.Cu")
		(net "UPI_CPU0_CPU1_P2P2_DP<9>")
	)
	(segment
		(start 126.73584 -385.05511)
		(end 126.241048 -385.05511)
		(width 0.14732)
		(layer "In6.Cu")
		(net "UPI_CPU0_CPU1_P2P2_DP<9>")
	)
	(segment
		(start 86.590124 -300.82363)
		(end 86.511892 -300.6344)
		(width 0.14732)
		(layer "In6.Cu")
		(net "UPI_CPU0_CPU1_P2P2_DP<9>")
	)
	(segment
		(start 86.983062 -299.875448)
		(end 86.904576 -299.686218)
		(width 0.14732)
		(layer "In6.Cu")
		(net "UPI_CPU0_CPU1_P2P2_DP<9>")
	)
	(segment
		(start 344.975942 -293.63035)
		(end 344.975942 -293.80561)
		(width 0.0889)
		(layer "In6.Cu")
		(net "UPI_CPU0_CPU1_P2P2_DP<9>")
	)
	(segment
		(start 344.876882 -292.25875)
		(end 344.876882 -292.43401)
		(width 0.0889)
		(layer "In6.Cu")
		(net "UPI_CPU0_CPU1_P2P2_DP<9>")
	)
	(segment
		(start 84.8741 -303.07534)
		(end 85.13445 -302.81499)
		(width 0.14732)
		(layer "In6.Cu")
		(net "UPI_CPU0_CPU1_P2P2_DP<9>")
	)
	(segment
		(start 280.756868 -337.642454)
		(end 272.747232 -345.65209)
		(width 0.14732)
		(layer "In6.Cu")
		(net "UPI_CPU0_CPU1_P2P2_DP<9>")
	)
	(segment
		(start 272.747232 -345.65209)
		(end 272.747232 -369.339622)
		(width 0.14732)
		(layer "In6.Cu")
		(net "UPI_CPU0_CPU1_P2P2_DP<9>")
	)
	(segment
		(start 93.367606 -290.538662)
		(end 93.51899 -290.387278)
		(width 0.0889)
		(layer "In6.Cu")
		(net "UPI_CPU0_CPU1_P2P2_DP<9>")
	)
	(segment
		(start 344.934032 -294.592248)
		(end 344.934032 -294.614346)
		(width 0.0889)
		(layer "In6.Cu")
		(net "UPI_CPU0_CPU1_P2P2_DP<9>")
	)
	(segment
		(start 349.548704 -281.911298)
		(end 349.541338 -281.915616)
		(width 0.0889)
		(layer "In6.Cu")
		(net "UPI_CPU0_CPU1_P2P2_DP<9>")
	)
	(segment
		(start 64.130428 -329.18908)
		(end 64.328802 -329.13701)
		(width 0.14732)
		(layer "In6.Cu")
		(net "UPI_CPU0_CPU1_P2P2_DP<9>")
	)
	(segment
		(start 126.85776 -384.93319)
		(end 126.73584 -385.05511)
		(width 0.14732)
		(layer "In6.Cu")
		(net "UPI_CPU0_CPU1_P2P2_DP<9>")
	)
	(segment
		(start 63.891414 -331.470508)
		(end 63.749936 -331.371448)
		(width 0.14732)
		(layer "In6.Cu")
		(net "UPI_CPU0_CPU1_P2P2_DP<9>")
	)
	(segment
		(start 86.511892 -300.6344)
		(end 86.652608 -300.294294)
		(width 0.14732)
		(layer "In6.Cu")
		(net "UPI_CPU0_CPU1_P2P2_DP<9>")
	)
	(segment
		(start 64.205358 -354.63988)
		(end 64.205358 -333.935324)
		(width 0.14732)
		(layer "In6.Cu")
		(net "UPI_CPU0_CPU1_P2P2_DP<9>")
	)
	(segment
		(start 84.408772 -303.540668)
		(end 84.613496 -303.540668)
		(width 0.14732)
		(layer "In6.Cu")
		(net "UPI_CPU0_CPU1_P2P2_DP<9>")
	)
	(segment
		(start 315.952886 -327.789286)
		(end 308.152292 -335.58988)
		(width 0.14732)
		(layer "In6.Cu")
		(net "UPI_CPU0_CPU1_P2P2_DP<9>")
	)
	(segment
		(start 85.944202 -302.005238)
		(end 86.259924 -301.242476)
		(width 0.14732)
		(layer "In6.Cu")
		(net "UPI_CPU0_CPU1_P2P2_DP<9>")
	)
	(segment
		(start 347.377512 -285.661354)
		(end 347.377512 -285.675578)
		(width 0.0889)
		(layer "In6.Cu")
		(net "UPI_CPU0_CPU1_P2P2_DP<9>")
	)
	(segment
		(start 93.049598 -289.078416)
		(end 93.049598 -288.917126)
		(width 0.0889)
		(layer "In6.Cu")
		(net "UPI_CPU0_CPU1_P2P2_DP<9>")
	)
	(segment
		(start 95.116396 -285.336996)
		(end 95.117158 -285.336488)
		(width 0.0889)
		(layer "In6.Cu")
		(net "UPI_CPU0_CPU1_P2P2_DP<9>")
	)
	(segment
		(start 95.115634 -285.985204)
		(end 95.107506 -285.980632)
		(width 0.0889)
		(layer "In6.Cu")
		(net "UPI_CPU0_CPU1_P2P2_DP<9>")
	)
	(segment
		(start 347.19895 -287.608518)
		(end 347.191076 -287.61309)
		(width 0.0889)
		(layer "In6.Cu")
		(net "UPI_CPU0_CPU1_P2P2_DP<9>")
	)
	(segment
		(start 96.557084 -282.948888)
		(end 96.713548 -283.219906)
		(width 0.0889)
		(layer "In6.Cu")
		(net "UPI_CPU0_CPU1_P2P2_DP<9>")
	)
	(segment
		(start 85.339174 -302.81499)
		(end 85.599778 -302.554386)
		(width 0.14732)
		(layer "In6.Cu")
		(net "UPI_CPU0_CPU1_P2P2_DP<9>")
	)
	(segment
		(start 265.90625 -376.180604)
		(end 161.327846 -385.05511)
		(width 0.14732)
		(layer "In6.Cu")
		(net "UPI_CPU0_CPU1_P2P2_DP<9>")
	)
	(segment
		(start 129.58318 -384.93319)
		(end 129.1463 -384.93319)
		(width 0.14732)
		(layer "In6.Cu")
		(net "UPI_CPU0_CPU1_P2P2_DP<9>")
	)
	(segment
		(start 93.367606 -290.598606)
		(end 93.367606 -290.538662)
		(width 0.0889)
		(layer "In6.Cu")
		(net "UPI_CPU0_CPU1_P2P2_DP<9>")
	)
	(segment
		(start 96.2914 -380.61265)
		(end 74.01941 -371.387116)
		(width 0.14732)
		(layer "In6.Cu")
		(net "UPI_CPU0_CPU1_P2P2_DP<9>")
	)
	(segment
		(start 93.233494 -289.27806)
		(end 93.233748 -289.277806)
		(width 0.0889)
		(layer "In6.Cu")
		(net "UPI_CPU0_CPU1_P2P2_DP<9>")
	)
	(segment
		(start 86.904576 -299.686218)
		(end 87.237316 -298.882816)
		(width 0.14732)
		(layer "In6.Cu")
		(net "UPI_CPU0_CPU1_P2P2_DP<9>")
	)
	(segment
		(start 349.541338 -281.915616)
		(end 349.539814 -281.916378)
		(width 0.0889)
		(layer "In6.Cu")
		(net "UPI_CPU0_CPU1_P2P2_DP<9>")
	)
	(segment
		(start 93.22816 -288.597848)
		(end 93.23705 -288.592768)
		(width 0.0889)
		(layer "In6.Cu")
		(net "UPI_CPU0_CPU1_P2P2_DP<9>")
	)
	(segment
		(start 348.317312 -284.023816)
		(end 348.317312 -284.033722)
		(width 0.0889)
		(layer "In6.Cu")
		(net "UPI_CPU0_CPU1_P2P2_DP<9>")
	)
	(segment
		(start 344.876882 -294.07993)
		(end 344.975942 -294.17899)
		(width 0.0889)
		(layer "In6.Cu")
		(net "UPI_CPU0_CPU1_P2P2_DP<9>")
	)
	(segment
		(start 348.317312 -282.405836)
		(end 348.317312 -282.424378)
		(width 0.0889)
		(layer "In6.Cu")
		(net "UPI_CPU0_CPU1_P2P2_DP<9>")
	)
	(segment
		(start 344.975942 -292.03523)
		(end 344.975942 -292.15969)
		(width 0.0889)
		(layer "In6.Cu")
		(net "UPI_CPU0_CPU1_P2P2_DP<9>")
	)
	(segment
		(start 347.656658 -286.801814)
		(end 347.654118 -286.803338)
		(width 0.0889)
		(layer "In6.Cu")
		(net "UPI_CPU0_CPU1_P2P2_DP<9>")
	)
	(segment
		(start 127.29464 -384.93319)
		(end 126.85776 -384.93319)
		(width 0.14732)
		(layer "In6.Cu")
		(net "UPI_CPU0_CPU1_P2P2_DP<9>")
	)
	(segment
		(start 349.352616 -281.59202)
		(end 349.196152 -281.321002)
		(width 0.0889)
		(layer "In6.Cu")
		(net "UPI_CPU0_CPU1_P2P2_DP<9>")
	)
	(segment
		(start 346.5195 -290.491672)
		(end 344.975942 -292.03523)
		(width 0.0889)
		(layer "In6.Cu")
		(net "UPI_CPU0_CPU1_P2P2_DP<9>")
	)
	(segment
		(start 317.069216 -325.093584)
		(end 315.952886 -327.789286)
		(width 0.14732)
		(layer "In6.Cu")
		(net "UPI_CPU0_CPU1_P2P2_DP<9>")
	)
	(segment
		(start 344.876882 -293.35603)
		(end 344.876882 -293.53129)
		(width 0.0889)
		(layer "In6.Cu")
		(net "UPI_CPU0_CPU1_P2P2_DP<9>")
	)
	(segment
		(start 126.241048 -385.05511)
		(end 96.2914 -380.61265)
		(width 0.14732)
		(layer "In6.Cu")
		(net "UPI_CPU0_CPU1_P2P2_DP<9>")
	)
	(segment
		(start 88.41867 -296.03065)
		(end 91.731084 -292.718236)
		(width 0.14732)
		(layer "In6.Cu")
		(net "UPI_CPU0_CPU1_P2P2_DP<9>")
	)
	(segment
		(start 348.13875 -284.353)
		(end 348.12986 -284.35808)
		(width 0.0889)
		(layer "In6.Cu")
		(net "UPI_CPU0_CPU1_P2P2_DP<9>")
	)
	(segment
		(start 63.96736 -331.901038)
		(end 63.891414 -331.470508)
		(width 0.14732)
		(layer "In6.Cu")
		(net "UPI_CPU0_CPU1_P2P2_DP<9>")
	)
	(segment
		(start 128.5875 -385.05511)
		(end 128.46558 -384.93319)
		(width 0.14732)
		(layer "In6.Cu")
		(net "UPI_CPU0_CPU1_P2P2_DP<9>")
	)
	(segment
		(start 87.237316 -298.882816)
		(end 87.4268 -298.80433)
		(width 0.14732)
		(layer "In6.Cu")
		(net "UPI_CPU0_CPU1_P2P2_DP<9>")
	)
	(segment
		(start 272.747232 -369.339622)
		(end 265.90625 -376.180604)
		(width 0.14732)
		(layer "In6.Cu")
		(net "UPI_CPU0_CPU1_P2P2_DP<9>")
	)
	(segment
		(start 344.933778 -294.810688)
		(end 344.933778 -297.948858)
		(width 0.14732)
		(layer "In6.Cu")
		(net "UPI_CPU0_CPU1_P2P2_DP<9>")
	)
	(segment
		(start 346.643452 -290.227258)
		(end 346.5195 -290.35121)
		(width 0.0889)
		(layer "In6.Cu")
		(net "UPI_CPU0_CPU1_P2P2_DP<9>")
	)
	(segment
		(start 308.152292 -335.58988)
		(end 285.712662 -335.58988)
		(width 0.14732)
		(layer "In6.Cu")
		(net "UPI_CPU0_CPU1_P2P2_DP<9>")
	)
	(segment
		(start 347.847412 -286.466788)
		(end 347.847412 -286.48406)
		(width 0.0889)
		(layer "In6.Cu")
		(net "UPI_CPU0_CPU1_P2P2_DP<9>")
	)
	(segment
		(start 344.876882 -292.43401)
		(end 344.975942 -292.53307)
		(width 0.0889)
		(layer "In6.Cu")
		(net "UPI_CPU0_CPU1_P2P2_DP<9>")
	)
	(segment
		(start 344.975942 -293.25697)
		(end 344.876882 -293.35603)
		(width 0.0889)
		(layer "In6.Cu")
		(net "UPI_CPU0_CPU1_P2P2_DP<9>")
	)
	(segment
		(start 344.975942 -294.17899)
		(end 344.975942 -294.550338)
		(width 0.0889)
		(layer "In6.Cu")
		(net "UPI_CPU0_CPU1_P2P2_DP<9>")
	)
	(segment
		(start 346.907612 -289.645852)
		(end 346.907612 -290.10356)
		(width 0.0889)
		(layer "In6.Cu")
		(net "UPI_CPU0_CPU1_P2P2_DP<9>")
	)
	(segment
		(start 341.302848 -302.869346)
		(end 337.872832 -304.289968)
		(width 0.14732)
		(layer "In6.Cu")
		(net "UPI_CPU0_CPU1_P2P2_DP<9>")
	)
	(segment
		(start 285.712662 -335.58988)
		(end 280.756868 -337.642454)
		(width 0.14732)
		(layer "In6.Cu")
		(net "UPI_CPU0_CPU1_P2P2_DP<9>")
	)
	(segment
		(start 64.201294 -333.93126)
		(end 63.8683 -332.042262)
		(width 0.14732)
		(layer "In6.Cu")
		(net "UPI_CPU0_CPU1_P2P2_DP<9>")
	)
	(segment
		(start 348.603062 -283.542232)
		(end 348.6023 -283.54274)
		(width 0.0889)
		(layer "In6.Cu")
		(net "UPI_CPU0_CPU1_P2P2_DP<9>")
	)
	(segment
		(start 344.975942 -293.80561)
		(end 344.876882 -293.90467)
		(width 0.0889)
		(layer "In6.Cu")
		(net "UPI_CPU0_CPU1_P2P2_DP<9>")
	)
	(segment
		(start 69.107812 -366.475518)
		(end 64.205358 -354.63988)
		(width 0.14732)
		(layer "In6.Cu")
		(net "UPI_CPU0_CPU1_P2P2_DP<9>")
	)
	(segment
		(start 86.259924 -301.242476)
		(end 86.449408 -301.164244)
		(width 0.14732)
		(layer "In6.Cu")
		(net "UPI_CPU0_CPU1_P2P2_DP<9>")
	)
	(segment
		(start 344.933778 -297.948858)
		(end 344.02268 -300.149514)
		(width 0.14732)
		(layer "In6.Cu")
		(net "UPI_CPU0_CPU1_P2P2_DP<9>")
	)
	(segment
		(start 129.1463 -384.93319)
		(end 129.02438 -385.05511)
		(width 0.14732)
		(layer "In6.Cu")
		(net "UPI_CPU0_CPU1_P2P2_DP<9>")
	)
	(segment
		(start 127.90678 -385.05511)
		(end 127.41656 -385.05511)
		(width 0.14732)
		(layer "In6.Cu")
		(net "UPI_CPU0_CPU1_P2P2_DP<9>")
	)
	(segment
		(start 74.01941 -371.387116)
		(end 69.107812 -366.475518)
		(width 0.14732)
		(layer "In6.Cu")
		(net "UPI_CPU0_CPU1_P2P2_DP<9>")
	)
	(segment
		(start 87.489284 -298.27474)
		(end 88.41867 -296.03065)
		(width 0.14732)
		(layer "In6.Cu")
		(net "UPI_CPU0_CPU1_P2P2_DP<9>")
	)
	(segment
		(start 129.7051 -385.05511)
		(end 129.58318 -384.93319)
		(width 0.14732)
		(layer "In6.Cu")
		(net "UPI_CPU0_CPU1_P2P2_DP<9>")
	)
	(segment
		(start 127.41656 -385.05511)
		(end 127.29464 -384.93319)
		(width 0.14732)
		(layer "In6.Cu")
		(net "UPI_CPU0_CPU1_P2P2_DP<9>")
	)
	(segment
		(start 347.847666 -284.832044)
		(end 347.847666 -284.847538)
		(width 0.0889)
		(layer "In6.Cu")
		(net "UPI_CPU0_CPU1_P2P2_DP<9>")
	)
	(segment
		(start 64.812926 -328.01941)
		(end 65.939162 -323.960744)
		(width 0.14732)
		(layer "In6.Cu")
		(net "UPI_CPU0_CPU1_P2P2_DP<9>")
	)
	(segment
		(start 346.783914 -290.227258)
		(end 346.643452 -290.227258)
		(width 0.0889)
		(layer "In6.Cu")
		(net "UPI_CPU0_CPU1_P2P2_DP<9>")
	)
	(segment
		(start 348.607888 -283.539692)
		(end 348.603062 -283.542232)
		(width 0.0889)
		(layer "In6.Cu")
		(net "UPI_CPU0_CPU1_P2P2_DP<9>")
	)
	(segment
		(start 344.975942 -294.550338)
		(end 344.934032 -294.592248)
		(width 0.0889)
		(layer "In6.Cu")
		(net "UPI_CPU0_CPU1_P2P2_DP<9>")
	)
	(segment
		(start 67.691254 -320.25844)
		(end 67.691508 -320.257932)
		(width 0.14732)
		(layer "In6.Cu")
		(net "UPI_CPU0_CPU1_P2P2_DP<9>")
	)
	(segment
		(start 337.872832 -304.289968)
		(end 317.069216 -325.093584)
		(width 0.14732)
		(layer "In6.Cu")
		(net "UPI_CPU0_CPU1_P2P2_DP<9>")
	)
	(arc
		(start 348.593918 -281.919934)
		(mid 348.391331 -282.126285)
		(end 348.317312 -282.405836)
		(width 0.0889)
		(layer "In6.Cu")
		(net "UPI_CPU0_CPU1_P2P2_DP<9>")
	)
	(arc
		(start 96.338898 -283.219906)
		(mid 96.375758 -283.058109)
		(end 96.478852 -282.92806)
		(width 0.0889)
		(layer "In6.Cu")
		(net "UPI_CPU0_CPU1_P2P2_DP<9>")
	)
	(arc
		(start 95.868744 -284.033722)
		(mid 95.916423 -283.850822)
		(end 96.047306 -283.714444)
		(width 0.0889)
		(layer "In6.Cu")
		(net "UPI_CPU0_CPU1_P2P2_DP<9>")
	)
	(arc
		(start 349.539814 -281.916378)
		(mid 349.352616 -281.966521)
		(end 349.165418 -281.916378)
		(width 0.0889)
		(layer "In6.Cu")
		(net "UPI_CPU0_CPU1_P2P2_DP<9>")
	)
	(arc
		(start 348.317312 -282.424378)
		(mid 348.397474 -282.696567)
		(end 348.59976 -282.895548)
		(width 0.0889)
		(layer "In6.Cu")
		(net "UPI_CPU0_CPU1_P2P2_DP<9>")
	)
	(arc
		(start 95.128588 -286.95777)
		(mid 95.398999 -286.468303)
		(end 95.116396 -285.985712)
		(width 0.0889)
		(layer "In6.Cu")
		(net "UPI_CPU0_CPU1_P2P2_DP<9>")
	)
	(arc
		(start 93.51899 -289.610292)
		(mid 93.40776 -289.417088)
		(end 93.233494 -289.27806)
		(width 0.0889)
		(layer "In6.Cu")
		(net "UPI_CPU0_CPU1_P2P2_DP<9>")
	)
	(arc
		(start 348.59976 -283.544264)
		(mid 348.395425 -283.746869)
		(end 348.317312 -284.023816)
		(width 0.0889)
		(layer "In6.Cu")
		(net "UPI_CPU0_CPU1_P2P2_DP<9>")
	)
	(arc
		(start 348.12986 -284.35808)
		(mid 347.927037 -284.558311)
		(end 347.847666 -284.832044)
		(width 0.0889)
		(layer "In6.Cu")
		(net "UPI_CPU0_CPU1_P2P2_DP<9>")
	)
	(arc
		(start 95.399098 -284.847538)
		(mid 95.446777 -284.664638)
		(end 95.57766 -284.52826)
		(width 0.0889)
		(layer "In6.Cu")
		(net "UPI_CPU0_CPU1_P2P2_DP<9>")
	)
	(arc
		(start 94.096078 -287.787334)
		(mid 94.647271 -287.778536)
		(end 94.928944 -287.304734)
		(width 0.0889)
		(layer "In6.Cu")
		(net "UPI_CPU0_CPU1_P2P2_DP<9>")
	)
	(arc
		(start 346.437966 -289.114738)
		(mid 346.549304 -289.307638)
		(end 346.723462 -289.446462)
		(width 0.0889)
		(layer "In6.Cu")
		(net "UPI_CPU0_CPU1_P2P2_DP<9>")
	)
	(arc
		(start 93.23705 -288.592768)
		(mid 93.439336 -288.393787)
		(end 93.519498 -288.121598)
		(width 0.0889)
		(layer "In6.Cu")
		(net "UPI_CPU0_CPU1_P2P2_DP<9>")
	)
	(arc
		(start 349.217234 -281.243024)
		(mid 349.38133 -281.218677)
		(end 349.539814 -281.267662)
		(width 0.0889)
		(layer "In6.Cu")
		(net "UPI_CPU0_CPU1_P2P2_DP<9>")
	)
	(arc
		(start 95.107506 -285.980632)
		(mid 94.92903 -285.661354)
		(end 95.107506 -285.342076)
		(width 0.0889)
		(layer "In6.Cu")
		(net "UPI_CPU0_CPU1_P2P2_DP<9>")
	)
	(arc
		(start 348.317312 -284.033722)
		(mid 348.269633 -284.216622)
		(end 348.13875 -284.353)
		(width 0.0889)
		(layer "In6.Cu")
		(net "UPI_CPU0_CPU1_P2P2_DP<9>")
	)
	(arc
		(start 346.907866 -288.103056)
		(mid 346.860187 -288.285956)
		(end 346.729304 -288.422334)
		(width 0.0889)
		(layer "In6.Cu")
		(net "UPI_CPU0_CPU1_P2P2_DP<9>")
	)
	(arc
		(start 346.723462 -289.446462)
		(mid 346.832609 -289.53039)
		(end 346.907612 -289.645852)
		(width 0.0889)
		(layer "In6.Cu")
		(net "UPI_CPU0_CPU1_P2P2_DP<9>")
	)
	(arc
		(start 347.847666 -284.847538)
		(mid 347.799987 -285.030438)
		(end 347.669104 -285.166816)
		(width 0.0889)
		(layer "In6.Cu")
		(net "UPI_CPU0_CPU1_P2P2_DP<9>")
	)
	(arc
		(start 93.519498 -288.103056)
		(mid 93.706797 -287.778615)
		(end 94.081346 -287.778698)
		(width 0.0889)
		(layer "In6.Cu")
		(net "UPI_CPU0_CPU1_P2P2_DP<9>")
	)
	(arc
		(start 96.068388 -283.702252)
		(mid 96.266616 -283.496404)
		(end 96.338898 -283.219906)
		(width 0.0889)
		(layer "In6.Cu")
		(net "UPI_CPU0_CPU1_P2P2_DP<9>")
	)
	(arc
		(start 347.660214 -286.151066)
		(mid 347.795147 -286.28442)
		(end 347.847412 -286.466788)
		(width 0.0889)
		(layer "In6.Cu")
		(net "UPI_CPU0_CPU1_P2P2_DP<9>")
	)
	(arc
		(start 93.049598 -288.917126)
		(mid 93.097277 -288.734226)
		(end 93.22816 -288.597848)
		(width 0.0889)
		(layer "In6.Cu")
		(net "UPI_CPU0_CPU1_P2P2_DP<9>")
	)
	(arc
		(start 347.654118 -285.175452)
		(mid 347.451531 -285.381803)
		(end 347.377512 -285.661354)
		(width 0.0889)
		(layer "In6.Cu")
		(net "UPI_CPU0_CPU1_P2P2_DP<9>")
	)
	(arc
		(start 347.377512 -285.675578)
		(mid 347.456731 -285.950263)
		(end 347.660214 -286.151066)
		(width 0.0889)
		(layer "In6.Cu")
		(net "UPI_CPU0_CPU1_P2P2_DP<9>")
	)
	(arc
		(start 94.928944 -287.28924)
		(mid 94.976623 -287.10634)
		(end 95.107506 -286.969962)
		(width 0.0889)
		(layer "In6.Cu")
		(net "UPI_CPU0_CPU1_P2P2_DP<9>")
	)
	(arc
		(start 95.58655 -284.52318)
		(mid 95.789373 -284.322949)
		(end 95.868744 -284.049216)
		(width 0.0889)
		(layer "In6.Cu")
		(net "UPI_CPU0_CPU1_P2P2_DP<9>")
	)
	(arc
		(start 349.165418 -281.916378)
		(mid 348.891219 -281.840543)
		(end 348.614746 -281.907742)
		(width 0.0889)
		(layer "In6.Cu")
		(net "UPI_CPU0_CPU1_P2P2_DP<9>")
	)
	(arc
		(start 347.377512 -287.28924)
		(mid 347.329833 -287.47214)
		(end 347.19895 -287.608518)
		(width 0.0889)
		(layer "In6.Cu")
		(net "UPI_CPU0_CPU1_P2P2_DP<9>")
	)
	(arc
		(start 346.720414 -288.427414)
		(mid 346.518128 -288.626395)
		(end 346.437966 -288.898584)
		(width 0.0889)
		(layer "In6.Cu")
		(net "UPI_CPU0_CPU1_P2P2_DP<9>")
	)
	(arc
		(start 95.122492 -285.33344)
		(mid 95.325079 -285.127089)
		(end 95.399098 -284.847538)
		(width 0.0889)
		(layer "In6.Cu")
		(net "UPI_CPU0_CPU1_P2P2_DP<9>")
	)
	(arc
		(start 348.60865 -282.900628)
		(mid 348.787247 -283.219906)
		(end 348.60865 -283.539184)
		(width 0.0889)
		(layer "In6.Cu")
		(net "UPI_CPU0_CPU1_P2P2_DP<9>")
	)
	(arc
		(start 347.654118 -286.803338)
		(mid 347.451531 -287.009689)
		(end 347.377512 -287.28924)
		(width 0.0889)
		(layer "In6.Cu")
		(net "UPI_CPU0_CPU1_P2P2_DP<9>")
	)
	(arc
		(start 347.847412 -286.48406)
		(mid 347.795142 -286.666425)
		(end 347.660214 -286.799782)
		(width 0.0889)
		(layer "In6.Cu")
		(net "UPI_CPU0_CPU1_P2P2_DP<9>")
	)
	(arc
		(start 93.233748 -289.277806)
		(mid 93.124601 -289.193878)
		(end 93.049598 -289.078416)
		(width 0.0889)
		(layer "In6.Cu")
		(net "UPI_CPU0_CPU1_P2P2_DP<9>")
	)
	(arc
		(start 349.548704 -281.272742)
		(mid 349.727301 -281.59202)
		(end 349.548704 -281.911298)
		(width 0.0889)
		(layer "In6.Cu")
		(net "UPI_CPU0_CPU1_P2P2_DP<9>")
	)
	(arc
		(start 347.19006 -287.613598)
		(mid 346.987237 -287.813829)
		(end 346.907866 -288.087562)
		(width 0.0889)
		(layer "In6.Cu")
		(net "UPI_CPU0_CPU1_P2P2_DP<9>")
	)
	(segment
		(start 350.292162 -283.219652)
		(end 350.292416 -283.219906)
		(width 0.13208)
		(layer "F.Cu")
		(net "UPI_CPU0_CPU1_P2P2_DP<8>")
	)
	(segment
		(start 350.292162 -282.683966)
		(end 350.292162 -283.219652)
		(width 0.13208)
		(layer "F.Cu")
		(net "UPI_CPU0_CPU1_P2P2_DP<8>")
	)
	(segment
		(start 97.183448 -280.77795)
		(end 97.183194 -280.778204)
		(width 0.13208)
		(layer "F.Cu")
		(net "UPI_CPU0_CPU1_P2P2_DP<8>")
	)
	(segment
		(start 97.183448 -280.242264)
		(end 97.183448 -280.77795)
		(width 0.13208)
		(layer "F.Cu")
		(net "UPI_CPU0_CPU1_P2P2_DP<8>")
	)
	(segment
		(start 95.208344 -283.219906)
		(end 95.208344 -283.201364)
		(width 0.0889)
		(layer "In6.Cu")
		(net "UPI_CPU0_CPU1_P2P2_DP<8>")
	)
	(segment
		(start 83.411314 -302.757586)
		(end 83.411568 -302.757586)
		(width 0.14732)
		(layer "In6.Cu")
		(net "UPI_CPU0_CPU1_P2P2_DP<8>")
	)
	(segment
		(start 348.70136 -285.33344)
		(end 348.696026 -285.336488)
		(width 0.0889)
		(layer "In6.Cu")
		(net "UPI_CPU0_CPU1_P2P2_DP<8>")
	)
	(segment
		(start 96.618044 -280.78684)
		(end 96.618044 -280.769568)
		(width 0.0889)
		(layer "In6.Cu")
		(net "UPI_CPU0_CPU1_P2P2_DP<8>")
	)
	(segment
		(start 94.550992 -284.35808)
		(end 94.559882 -284.353)
		(width 0.0889)
		(layer "In6.Cu")
		(net "UPI_CPU0_CPU1_P2P2_DP<8>")
	)
	(segment
		(start 66.776854 -319.60566)
		(end 68.864226 -317.51905)
		(width 0.14732)
		(layer "In6.Cu")
		(net "UPI_CPU0_CPU1_P2P2_DP<8>")
	)
	(segment
		(start 94.268544 -286.48406)
		(end 94.268544 -286.466788)
		(width 0.0889)
		(layer "In6.Cu")
		(net "UPI_CPU0_CPU1_P2P2_DP<8>")
	)
	(segment
		(start 308.61 -336.69224)
		(end 285.9786 -336.69224)
		(width 0.14732)
		(layer "In6.Cu")
		(net "UPI_CPU0_CPU1_P2P2_DP<8>")
	)
	(segment
		(start 62.637924 -325.348092)
		(end 63.419228 -324.566788)
		(width 0.14732)
		(layer "In6.Cu")
		(net "UPI_CPU0_CPU1_P2P2_DP<8>")
	)
	(segment
		(start 318.036448 -325.689468)
		(end 316.922658 -328.379582)
		(width 0.14732)
		(layer "In6.Cu")
		(net "UPI_CPU0_CPU1_P2P2_DP<8>")
	)
	(segment
		(start 73.414636 -372.345458)
		(end 68.161408 -367.09223)
		(width 0.14732)
		(layer "In6.Cu")
		(net "UPI_CPU0_CPU1_P2P2_DP<8>")
	)
	(segment
		(start 341.82939 -304.186844)
		(end 337.919314 -305.806602)
		(width 0.14732)
		(layer "In6.Cu")
		(net "UPI_CPU0_CPU1_P2P2_DP<8>")
	)
	(segment
		(start 92.389198 -288.103056)
		(end 92.389198 -288.09315)
		(width 0.0889)
		(layer "In6.Cu")
		(net "UPI_CPU0_CPU1_P2P2_DP<8>")
	)
	(segment
		(start 97.02673 -280.507186)
		(end 97.183194 -280.778204)
		(width 0.0889)
		(layer "In6.Cu")
		(net "UPI_CPU0_CPU1_P2P2_DP<8>")
	)
	(segment
		(start 346.03944 -294.482266)
		(end 346.03944 -298.20108)
		(width 0.14732)
		(layer "In6.Cu")
		(net "UPI_CPU0_CPU1_P2P2_DP<8>")
	)
	(segment
		(start 348.977966 -286.467804)
		(end 348.977966 -286.475424)
		(width 0.0889)
		(layer "In6.Cu")
		(net "UPI_CPU0_CPU1_P2P2_DP<8>")
	)
	(segment
		(start 95.95485 -381.682244)
		(end 73.414636 -372.345458)
		(width 0.14732)
		(layer "In6.Cu")
		(net "UPI_CPU0_CPU1_P2P2_DP<8>")
	)
	(segment
		(start 97.05086 -280.418032)
		(end 97.02673 -280.507186)
		(width 0.0889)
		(layer "In6.Cu")
		(net "UPI_CPU0_CPU1_P2P2_DP<8>")
	)
	(segment
		(start 96.148398 -281.59202)
		(end 96.148398 -281.582114)
		(width 0.0889)
		(layer "In6.Cu")
		(net "UPI_CPU0_CPU1_P2P2_DP<8>")
	)
	(segment
		(start 92.038932 -290.319968)
		(end 92.054426 -290.304474)
		(width 0.0889)
		(layer "In6.Cu")
		(net "UPI_CPU0_CPU1_P2P2_DP<8>")
	)
	(segment
		(start 96.148398 -279.982676)
		(end 96.148398 -279.94864)
		(width 0.0889)
		(layer "In6.Cu")
		(net "UPI_CPU0_CPU1_P2P2_DP<8>")
	)
	(segment
		(start 90.44305 -292.443408)
		(end 90.44305 -291.914834)
		(width 0.14732)
		(layer "In6.Cu")
		(net "UPI_CPU0_CPU1_P2P2_DP<8>")
	)
	(segment
		(start 63.419228 -324.566788)
		(end 63.961772 -323.257164)
		(width 0.14732)
		(layer "In6.Cu")
		(net "UPI_CPU0_CPU1_P2P2_DP<8>")
	)
	(segment
		(start 87.425022 -295.491154)
		(end 87.424768 -295.491154)
		(width 0.14732)
		(layer "In6.Cu")
		(net "UPI_CPU0_CPU1_P2P2_DP<8>")
	)
	(segment
		(start 64.98082 -322.607432)
		(end 65.047114 -322.580508)
		(width 0.14732)
		(layer "In6.Cu")
		(net "UPI_CPU0_CPU1_P2P2_DP<8>")
	)
	(segment
		(start 285.9786 -336.69224)
		(end 281.348434 -338.610194)
		(width 0.14732)
		(layer "In6.Cu")
		(net "UPI_CPU0_CPU1_P2P2_DP<8>")
	)
	(segment
		(start 65.047114 -322.580508)
		(end 65.435734 -322.192904)
		(width 0.14732)
		(layer "In6.Cu")
		(net "UPI_CPU0_CPU1_P2P2_DP<8>")
	)
	(segment
		(start 87.424768 -295.491154)
		(end 87.44585 -295.440608)
		(width 0.14732)
		(layer "In6.Cu")
		(net "UPI_CPU0_CPU1_P2P2_DP<8>")
	)
	(segment
		(start 93.141546 -286.799782)
		(end 93.156278 -286.791146)
		(width 0.0889)
		(layer "In6.Cu")
		(net "UPI_CPU0_CPU1_P2P2_DP<8>")
	)
	(segment
		(start 345.997276 -294.418004)
		(end 346.03944 -294.460168)
		(width 0.0889)
		(layer "In6.Cu")
		(net "UPI_CPU0_CPU1_P2P2_DP<8>")
	)
	(segment
		(start 349.447612 -284.033722)
		(end 349.447612 -284.049216)
		(width 0.0889)
		(layer "In6.Cu")
		(net "UPI_CPU0_CPU1_P2P2_DP<8>")
	)
	(segment
		(start 91.676728 -290.682172)
		(end 92.038932 -290.319968)
		(width 0.14732)
		(layer "In6.Cu")
		(net "UPI_CPU0_CPU1_P2P2_DP<8>")
	)
	(segment
		(start 266.397994 -377.248166)
		(end 161.322512 -386.16509)
		(width 0.14732)
		(layer "In6.Cu")
		(net "UPI_CPU0_CPU1_P2P2_DP<8>")
	)
	(segment
		(start 61.181742 -325.951342)
		(end 62.637924 -325.348092)
		(width 0.14732)
		(layer "In6.Cu")
		(net "UPI_CPU0_CPU1_P2P2_DP<8>")
	)
	(segment
		(start 348.707456 -286.95777)
		(end 348.695264 -286.964882)
		(width 0.0889)
		(layer "In6.Cu")
		(net "UPI_CPU0_CPU1_P2P2_DP<8>")
	)
	(segment
		(start 63.961772 -323.257164)
		(end 64.356488 -322.864226)
		(width 0.14732)
		(layer "In6.Cu")
		(net "UPI_CPU0_CPU1_P2P2_DP<8>")
	)
	(segment
		(start 348.037658 -289.610292)
		(end 348.037658 -290.217098)
		(width 0.0889)
		(layer "In6.Cu")
		(net "UPI_CPU0_CPU1_P2P2_DP<8>")
	)
	(segment
		(start 161.322512 -386.16509)
		(end 126.174754 -386.16509)
		(width 0.14732)
		(layer "In6.Cu")
		(net "UPI_CPU0_CPU1_P2P2_DP<8>")
	)
	(segment
		(start 95.960946 -281.916378)
		(end 95.969836 -281.911298)
		(width 0.0889)
		(layer "In6.Cu")
		(net "UPI_CPU0_CPU1_P2P2_DP<8>")
	)
	(segment
		(start 349.634302 -283.709872)
		(end 349.62592 -283.714952)
		(width 0.0889)
		(layer "In6.Cu")
		(net "UPI_CPU0_CPU1_P2P2_DP<8>")
	)
	(segment
		(start 349.637858 -283.70784)
		(end 349.635064 -283.709364)
		(width 0.0889)
		(layer "In6.Cu")
		(net "UPI_CPU0_CPU1_P2P2_DP<8>")
	)
	(segment
		(start 96.996758 -279.475184)
		(end 97.002092 -279.478232)
		(width 0.0889)
		(layer "In6.Cu")
		(net "UPI_CPU0_CPU1_P2P2_DP<8>")
	)
	(segment
		(start 92.054426 -290.304474)
		(end 92.113354 -290.304474)
		(width 0.0889)
		(layer "In6.Cu")
		(net "UPI_CPU0_CPU1_P2P2_DP<8>")
	)
	(segment
		(start 68.161408 -367.09223)
		(end 63.102998 -354.87991)
		(width 0.14732)
		(layer "In6.Cu")
		(net "UPI_CPU0_CPU1_P2P2_DP<8>")
	)
	(segment
		(start 61.477652 -328.580496)
		(end 60.88888 -327.479152)
		(width 0.14732)
		(layer "In6.Cu")
		(net "UPI_CPU0_CPU1_P2P2_DP<8>")
	)
	(segment
		(start 64.981074 -322.607432)
		(end 64.98082 -322.607432)
		(width 0.14732)
		(layer "In6.Cu")
		(net "UPI_CPU0_CPU1_P2P2_DP<8>")
	)
	(segment
		(start 95.490792 -282.730194)
		(end 95.499682 -282.725114)
		(width 0.0889)
		(layer "In6.Cu")
		(net "UPI_CPU0_CPU1_P2P2_DP<8>")
	)
	(segment
		(start 92.113354 -290.304474)
		(end 92.388944 -290.028884)
		(width 0.0889)
		(layer "In6.Cu")
		(net "UPI_CPU0_CPU1_P2P2_DP<8>")
	)
	(segment
		(start 344.784172 -301.232062)
		(end 341.82939 -304.186844)
		(width 0.14732)
		(layer "In6.Cu")
		(net "UPI_CPU0_CPU1_P2P2_DP<8>")
	)
	(segment
		(start 349.64116 -283.705808)
		(end 349.637858 -283.70784)
		(width 0.0889)
		(layer "In6.Cu")
		(net "UPI_CPU0_CPU1_P2P2_DP<8>")
	)
	(segment
		(start 60.995814 -326.13727)
		(end 61.181742 -325.951342)
		(width 0.14732)
		(layer "In6.Cu")
		(net "UPI_CPU0_CPU1_P2P2_DP<8>")
	)
	(segment
		(start 345.997276 -292.25748)
		(end 345.997276 -294.418004)
		(width 0.0889)
		(layer "In6.Cu")
		(net "UPI_CPU0_CPU1_P2P2_DP<8>")
	)
	(segment
		(start 97.278698 -279.964134)
		(end 97.278698 -279.978358)
		(width 0.0889)
		(layer "In6.Cu")
		(net "UPI_CPU0_CPU1_P2P2_DP<8>")
	)
	(segment
		(start 66.060828 -320.905886)
		(end 66.776854 -319.60566)
		(width 0.14732)
		(layer "In6.Cu")
		(net "UPI_CPU0_CPU1_P2P2_DP<8>")
	)
	(segment
		(start 94.07525 -285.175452)
		(end 94.081346 -285.171896)
		(width 0.0889)
		(layer "In6.Cu")
		(net "UPI_CPU0_CPU1_P2P2_DP<8>")
	)
	(segment
		(start 92.388944 -290.028884)
		(end 92.388944 -289.645852)
		(width 0.0889)
		(layer "In6.Cu")
		(net "UPI_CPU0_CPU1_P2P2_DP<8>")
	)
	(segment
		(start 65.94729 -321.263772)
		(end 66.060828 -320.905886)
		(width 0.14732)
		(layer "In6.Cu")
		(net "UPI_CPU0_CPU1_P2P2_DP<8>")
	)
	(segment
		(start 94.081346 -285.171896)
		(end 94.090236 -285.166816)
		(width 0.0889)
		(layer "In6.Cu")
		(net "UPI_CPU0_CPU1_P2P2_DP<8>")
	)
	(segment
		(start 349.635064 -283.709364)
		(end 349.634302 -283.709872)
		(width 0.0889)
		(layer "In6.Cu")
		(net "UPI_CPU0_CPU1_P2P2_DP<8>")
	)
	(segment
		(start 348.037658 -290.217098)
		(end 345.997276 -292.25748)
		(width 0.0889)
		(layer "In6.Cu")
		(net "UPI_CPU0_CPU1_P2P2_DP<8>")
	)
	(segment
		(start 85.125052 -301.044356)
		(end 87.425022 -295.491154)
		(width 0.14732)
		(layer "In6.Cu")
		(net "UPI_CPU0_CPU1_P2P2_DP<8>")
	)
	(segment
		(start 347.568266 -288.917126)
		(end 347.568266 -289.078416)
		(width 0.0889)
		(layer "In6.Cu")
		(net "UPI_CPU0_CPU1_P2P2_DP<8>")
	)
	(segment
		(start 348.688406 -285.340806)
		(end 348.686374 -285.342076)
		(width 0.0889)
		(layer "In6.Cu")
		(net "UPI_CPU0_CPU1_P2P2_DP<8>")
	)
	(segment
		(start 93.798644 -285.675578)
		(end 93.798644 -285.661354)
		(width 0.0889)
		(layer "In6.Cu")
		(net "UPI_CPU0_CPU1_P2P2_DP<8>")
	)
	(segment
		(start 316.922658 -328.379582)
		(end 308.61 -336.69224)
		(width 0.14732)
		(layer "In6.Cu")
		(net "UPI_CPU0_CPU1_P2P2_DP<8>")
	)
	(segment
		(start 93.13545 -286.803338)
		(end 93.141546 -286.799782)
		(width 0.0889)
		(layer "In6.Cu")
		(net "UPI_CPU0_CPU1_P2P2_DP<8>")
	)
	(segment
		(start 346.03944 -294.460168)
		(end 346.03944 -294.482266)
		(width 0.0889)
		(layer "In6.Cu")
		(net "UPI_CPU0_CPU1_P2P2_DP<8>")
	)
	(segment
		(start 83.411568 -302.757586)
		(end 85.125052 -301.044356)
		(width 0.14732)
		(layer "In6.Cu")
		(net "UPI_CPU0_CPU1_P2P2_DP<8>")
	)
	(segment
		(start 95.95485 -281.919934)
		(end 95.960946 -281.916378)
		(width 0.0889)
		(layer "In6.Cu")
		(net "UPI_CPU0_CPU1_P2P2_DP<8>")
	)
	(segment
		(start 348.695264 -285.336996)
		(end 348.688406 -285.340806)
		(width 0.0889)
		(layer "In6.Cu")
		(net "UPI_CPU0_CPU1_P2P2_DP<8>")
	)
	(segment
		(start 349.165418 -284.52318)
		(end 349.156528 -284.52826)
		(width 0.0889)
		(layer "In6.Cu")
		(net "UPI_CPU0_CPU1_P2P2_DP<8>")
	)
	(segment
		(start 91.919298 -289.114738)
		(end 91.919298 -288.898584)
		(width 0.0889)
		(layer "In6.Cu")
		(net "UPI_CPU0_CPU1_P2P2_DP<8>")
	)
	(segment
		(start 346.03944 -298.20108)
		(end 344.784172 -301.232062)
		(width 0.14732)
		(layer "In6.Cu")
		(net "UPI_CPU0_CPU1_P2P2_DP<8>")
	)
	(segment
		(start 60.88888 -327.479152)
		(end 60.88888 -326.395334)
		(width 0.14732)
		(layer "In6.Cu")
		(net "UPI_CPU0_CPU1_P2P2_DP<8>")
	)
	(segment
		(start 349.62592 -283.714952)
		(end 349.626174 -283.714444)
		(width 0.0889)
		(layer "In6.Cu")
		(net "UPI_CPU0_CPU1_P2P2_DP<8>")
	)
	(segment
		(start 350.292416 -283.219906)
		(end 349.979742 -283.219906)
		(width 0.0889)
		(layer "In6.Cu")
		(net "UPI_CPU0_CPU1_P2P2_DP<8>")
	)
	(segment
		(start 348.694502 -285.985204)
		(end 348.695264 -285.985712)
		(width 0.0889)
		(layer "In6.Cu")
		(net "UPI_CPU0_CPU1_P2P2_DP<8>")
	)
	(segment
		(start 126.174754 -386.16509)
		(end 95.95485 -381.682244)
		(width 0.14732)
		(layer "In6.Cu")
		(net "UPI_CPU0_CPU1_P2P2_DP<8>")
	)
	(segment
		(start 95.020892 -283.544264)
		(end 95.029782 -283.539184)
		(width 0.0889)
		(layer "In6.Cu")
		(net "UPI_CPU0_CPU1_P2P2_DP<8>")
	)
	(segment
		(start 273.849592 -369.796568)
		(end 266.397994 -377.248166)
		(width 0.14732)
		(layer "In6.Cu")
		(net "UPI_CPU0_CPU1_P2P2_DP<8>")
	)
	(segment
		(start 348.686374 -285.980632)
		(end 348.694502 -285.985204)
		(width 0.0889)
		(layer "In6.Cu")
		(net "UPI_CPU0_CPU1_P2P2_DP<8>")
	)
	(segment
		(start 68.864226 -317.51905)
		(end 68.864226 -317.30061)
		(width 0.14732)
		(layer "In6.Cu")
		(net "UPI_CPU0_CPU1_P2P2_DP<8>")
	)
	(segment
		(start 273.849592 -346.109036)
		(end 273.849592 -369.796568)
		(width 0.14732)
		(layer "In6.Cu")
		(net "UPI_CPU0_CPU1_P2P2_DP<8>")
	)
	(segment
		(start 63.102998 -335.064862)
		(end 61.477652 -328.580496)
		(width 0.14732)
		(layer "In6.Cu")
		(net "UPI_CPU0_CPU1_P2P2_DP<8>")
	)
	(segment
		(start 348.695264 -286.964882)
		(end 348.686374 -286.969962)
		(width 0.0889)
		(layer "In6.Cu")
		(net "UPI_CPU0_CPU1_P2P2_DP<8>")
	)
	(segment
		(start 348.225618 -287.778698)
		(end 348.216728 -287.783778)
		(width 0.0889)
		(layer "In6.Cu")
		(net "UPI_CPU0_CPU1_P2P2_DP<8>")
	)
	(segment
		(start 349.979742 -283.219906)
		(end 349.913956 -283.285692)
		(width 0.0889)
		(layer "In6.Cu")
		(net "UPI_CPU0_CPU1_P2P2_DP<8>")
	)
	(segment
		(start 63.102998 -354.87991)
		(end 63.102998 -335.064862)
		(width 0.14732)
		(layer "In6.Cu")
		(net "UPI_CPU0_CPU1_P2P2_DP<8>")
	)
	(segment
		(start 94.268798 -284.847538)
		(end 94.268798 -284.832044)
		(width 0.0889)
		(layer "In6.Cu")
		(net "UPI_CPU0_CPU1_P2P2_DP<8>")
	)
	(segment
		(start 60.88888 -326.395334)
		(end 60.995814 -326.13727)
		(width 0.14732)
		(layer "In6.Cu")
		(net "UPI_CPU0_CPU1_P2P2_DP<8>")
	)
	(segment
		(start 87.44585 -295.440608)
		(end 90.44305 -292.443408)
		(width 0.14732)
		(layer "In6.Cu")
		(net "UPI_CPU0_CPU1_P2P2_DP<8>")
	)
	(segment
		(start 348.696026 -285.336488)
		(end 348.695264 -285.336996)
		(width 0.0889)
		(layer "In6.Cu")
		(net "UPI_CPU0_CPU1_P2P2_DP<8>")
	)
	(segment
		(start 90.44305 -291.914834)
		(end 91.675712 -290.682172)
		(width 0.14732)
		(layer "In6.Cu")
		(net "UPI_CPU0_CPU1_P2P2_DP<8>")
	)
	(segment
		(start 92.201746 -288.427414)
		(end 92.210636 -288.422334)
		(width 0.0889)
		(layer "In6.Cu")
		(net "UPI_CPU0_CPU1_P2P2_DP<8>")
	)
	(segment
		(start 348.507812 -287.28924)
		(end 348.507812 -287.304734)
		(width 0.0889)
		(layer "In6.Cu")
		(net "UPI_CPU0_CPU1_P2P2_DP<8>")
	)
	(segment
		(start 337.919314 -305.806602)
		(end 318.036448 -325.689468)
		(width 0.14732)
		(layer "In6.Cu")
		(net "UPI_CPU0_CPU1_P2P2_DP<8>")
	)
	(segment
		(start 347.752416 -289.277806)
		(end 347.752162 -289.27806)
		(width 0.0889)
		(layer "In6.Cu")
		(net "UPI_CPU0_CPU1_P2P2_DP<8>")
	)
	(segment
		(start 96.995996 -279.474676)
		(end 96.996758 -279.475184)
		(width 0.0889)
		(layer "In6.Cu")
		(net "UPI_CPU0_CPU1_P2P2_DP<8>")
	)
	(segment
		(start 94.738444 -284.033722)
		(end 94.738444 -284.023816)
		(width 0.0889)
		(layer "In6.Cu")
		(net "UPI_CPU0_CPU1_P2P2_DP<8>")
	)
	(segment
		(start 348.038166 -288.103056)
		(end 348.038166 -288.121598)
		(width 0.0889)
		(layer "In6.Cu")
		(net "UPI_CPU0_CPU1_P2P2_DP<8>")
	)
	(segment
		(start 92.858844 -287.297876)
		(end 92.858844 -287.28924)
		(width 0.0889)
		(layer "In6.Cu")
		(net "UPI_CPU0_CPU1_P2P2_DP<8>")
	)
	(segment
		(start 68.864226 -317.30061)
		(end 83.411314 -302.757586)
		(width 0.14732)
		(layer "In6.Cu")
		(net "UPI_CPU0_CPU1_P2P2_DP<8>")
	)
	(segment
		(start 347.755718 -288.592768)
		(end 347.746828 -288.597848)
		(width 0.0889)
		(layer "In6.Cu")
		(net "UPI_CPU0_CPU1_P2P2_DP<8>")
	)
	(segment
		(start 65.435734 -322.192904)
		(end 65.94729 -321.263772)
		(width 0.14732)
		(layer "In6.Cu")
		(net "UPI_CPU0_CPU1_P2P2_DP<8>")
	)
	(segment
		(start 64.356488 -322.864226)
		(end 64.981074 -322.607432)
		(width 0.14732)
		(layer "In6.Cu")
		(net "UPI_CPU0_CPU1_P2P2_DP<8>")
	)
	(segment
		(start 96.981264 -279.46604)
		(end 96.995996 -279.474676)
		(width 0.0889)
		(layer "In6.Cu")
		(net "UPI_CPU0_CPU1_P2P2_DP<8>")
	)
	(segment
		(start 281.348434 -338.610194)
		(end 273.849592 -346.109036)
		(width 0.14732)
		(layer "In6.Cu")
		(net "UPI_CPU0_CPU1_P2P2_DP<8>")
	)
	(segment
		(start 91.675712 -290.682172)
		(end 91.676728 -290.682172)
		(width 0.14732)
		(layer "In6.Cu")
		(net "UPI_CPU0_CPU1_P2P2_DP<8>")
	)
	(arc
		(start 349.913956 -283.285692)
		(mid 349.912655 -283.296119)
		(end 349.911162 -283.30652)
		(width 0.0889)
		(layer "In6.Cu")
		(net "UPI_CPU0_CPU1_P2P2_DP<8>")
	)
	(arc
		(start 349.447612 -284.049216)
		(mid 349.368242 -284.32295)
		(end 349.165418 -284.52318)
		(width 0.0889)
		(layer "In6.Cu")
		(net "UPI_CPU0_CPU1_P2P2_DP<8>")
	)
	(arc
		(start 95.969836 -281.911298)
		(mid 96.10075 -281.774938)
		(end 96.148398 -281.59202)
		(width 0.0889)
		(layer "In6.Cu")
		(net "UPI_CPU0_CPU1_P2P2_DP<8>")
	)
	(arc
		(start 95.499682 -282.725114)
		(mid 95.630596 -282.588754)
		(end 95.678244 -282.405836)
		(width 0.0889)
		(layer "In6.Cu")
		(net "UPI_CPU0_CPU1_P2P2_DP<8>")
	)
	(arc
		(start 96.430846 -281.102562)
		(mid 96.565779 -280.969208)
		(end 96.618044 -280.78684)
		(width 0.0889)
		(layer "In6.Cu")
		(net "UPI_CPU0_CPU1_P2P2_DP<8>")
	)
	(arc
		(start 94.081346 -286.151066)
		(mid 93.877865 -285.950262)
		(end 93.798644 -285.675578)
		(width 0.0889)
		(layer "In6.Cu")
		(net "UPI_CPU0_CPU1_P2P2_DP<8>")
	)
	(arc
		(start 94.268544 -286.466788)
		(mid 94.216274 -286.284423)
		(end 94.081346 -286.151066)
		(width 0.0889)
		(layer "In6.Cu")
		(net "UPI_CPU0_CPU1_P2P2_DP<8>")
	)
	(arc
		(start 96.430846 -280.453846)
		(mid 96.22856 -280.254865)
		(end 96.148398 -279.982676)
		(width 0.0889)
		(layer "In6.Cu")
		(net "UPI_CPU0_CPU1_P2P2_DP<8>")
	)
	(arc
		(start 94.081346 -286.799782)
		(mid 94.216279 -286.666428)
		(end 94.268544 -286.48406)
		(width 0.0889)
		(layer "In6.Cu")
		(net "UPI_CPU0_CPU1_P2P2_DP<8>")
	)
	(arc
		(start 96.618044 -280.769568)
		(mid 96.565774 -280.587203)
		(end 96.430846 -280.453846)
		(width 0.0889)
		(layer "In6.Cu")
		(net "UPI_CPU0_CPU1_P2P2_DP<8>")
	)
	(arc
		(start 92.210636 -288.422334)
		(mid 92.34155 -288.285974)
		(end 92.389198 -288.103056)
		(width 0.0889)
		(layer "In6.Cu")
		(net "UPI_CPU0_CPU1_P2P2_DP<8>")
	)
	(arc
		(start 94.268798 -284.832044)
		(mid 94.348168 -284.55831)
		(end 94.550992 -284.35808)
		(width 0.0889)
		(layer "In6.Cu")
		(net "UPI_CPU0_CPU1_P2P2_DP<8>")
	)
	(arc
		(start 92.858844 -287.28924)
		(mid 92.932835 -287.009674)
		(end 93.13545 -286.803338)
		(width 0.0889)
		(layer "In6.Cu")
		(net "UPI_CPU0_CPU1_P2P2_DP<8>")
	)
	(arc
		(start 348.977966 -284.847538)
		(mid 348.903975 -285.127104)
		(end 348.70136 -285.33344)
		(width 0.0889)
		(layer "In6.Cu")
		(net "UPI_CPU0_CPU1_P2P2_DP<8>")
	)
	(arc
		(start 96.148398 -279.94864)
		(mid 96.227768 -279.674906)
		(end 96.430592 -279.474676)
		(width 0.0889)
		(layer "In6.Cu")
		(net "UPI_CPU0_CPU1_P2P2_DP<8>")
	)
	(arc
		(start 96.148398 -281.582114)
		(mid 96.226509 -281.305165)
		(end 96.430846 -281.102562)
		(width 0.0889)
		(layer "In6.Cu")
		(net "UPI_CPU0_CPU1_P2P2_DP<8>")
	)
	(arc
		(start 92.204794 -289.446462)
		(mid 92.030662 -289.307615)
		(end 91.919298 -289.114738)
		(width 0.0889)
		(layer "In6.Cu")
		(net "UPI_CPU0_CPU1_P2P2_DP<8>")
	)
	(arc
		(start 349.626174 -283.714444)
		(mid 349.49526 -283.850804)
		(end 349.447612 -284.033722)
		(width 0.0889)
		(layer "In6.Cu")
		(net "UPI_CPU0_CPU1_P2P2_DP<8>")
	)
	(arc
		(start 92.671646 -287.613598)
		(mid 92.806579 -287.480244)
		(end 92.858844 -287.297876)
		(width 0.0889)
		(layer "In6.Cu")
		(net "UPI_CPU0_CPU1_P2P2_DP<8>")
	)
	(arc
		(start 348.686374 -285.342076)
		(mid 348.507777 -285.661354)
		(end 348.686374 -285.980632)
		(width 0.0889)
		(layer "In6.Cu")
		(net "UPI_CPU0_CPU1_P2P2_DP<8>")
	)
	(arc
		(start 93.70695 -286.799782)
		(mid 93.894148 -286.849925)
		(end 94.081346 -286.799782)
		(width 0.0889)
		(layer "In6.Cu")
		(net "UPI_CPU0_CPU1_P2P2_DP<8>")
	)
	(arc
		(start 95.029782 -283.539184)
		(mid 95.160696 -283.402824)
		(end 95.208344 -283.219906)
		(width 0.0889)
		(layer "In6.Cu")
		(net "UPI_CPU0_CPU1_P2P2_DP<8>")
	)
	(arc
		(start 94.559882 -284.353)
		(mid 94.690796 -284.21664)
		(end 94.738444 -284.033722)
		(width 0.0889)
		(layer "In6.Cu")
		(net "UPI_CPU0_CPU1_P2P2_DP<8>")
	)
	(arc
		(start 348.216728 -287.783778)
		(mid 348.085814 -287.920138)
		(end 348.038166 -288.103056)
		(width 0.0889)
		(layer "In6.Cu")
		(net "UPI_CPU0_CPU1_P2P2_DP<8>")
	)
	(arc
		(start 349.911162 -283.30652)
		(mid 349.820898 -283.53643)
		(end 349.64116 -283.705808)
		(width 0.0889)
		(layer "In6.Cu")
		(net "UPI_CPU0_CPU1_P2P2_DP<8>")
	)
	(arc
		(start 95.678244 -282.405836)
		(mid 95.752235 -282.12627)
		(end 95.95485 -281.919934)
		(width 0.0889)
		(layer "In6.Cu")
		(net "UPI_CPU0_CPU1_P2P2_DP<8>")
	)
	(arc
		(start 97.278698 -279.978358)
		(mid 97.220353 -280.214863)
		(end 97.067878 -280.404824)
		(width 0.0889)
		(layer "In6.Cu")
		(net "UPI_CPU0_CPU1_P2P2_DP<8>")
	)
	(arc
		(start 94.090236 -285.166816)
		(mid 94.22115 -285.030456)
		(end 94.268798 -284.847538)
		(width 0.0889)
		(layer "In6.Cu")
		(net "UPI_CPU0_CPU1_P2P2_DP<8>")
	)
	(arc
		(start 91.919298 -288.898584)
		(mid 91.99946 -288.626395)
		(end 92.201746 -288.427414)
		(width 0.0889)
		(layer "In6.Cu")
		(net "UPI_CPU0_CPU1_P2P2_DP<8>")
	)
	(arc
		(start 92.389198 -288.09315)
		(mid 92.467309 -287.816201)
		(end 92.671646 -287.613598)
		(width 0.0889)
		(layer "In6.Cu")
		(net "UPI_CPU0_CPU1_P2P2_DP<8>")
	)
	(arc
		(start 93.798644 -285.661354)
		(mid 93.872635 -285.381788)
		(end 94.07525 -285.175452)
		(width 0.0889)
		(layer "In6.Cu")
		(net "UPI_CPU0_CPU1_P2P2_DP<8>")
	)
	(arc
		(start 349.156528 -284.52826)
		(mid 349.025614 -284.66462)
		(end 348.977966 -284.847538)
		(width 0.0889)
		(layer "In6.Cu")
		(net "UPI_CPU0_CPU1_P2P2_DP<8>")
	)
	(arc
		(start 93.156278 -286.791146)
		(mid 93.432753 -286.723826)
		(end 93.70695 -286.799782)
		(width 0.0889)
		(layer "In6.Cu")
		(net "UPI_CPU0_CPU1_P2P2_DP<8>")
	)
	(arc
		(start 94.738444 -284.023816)
		(mid 94.816555 -283.746867)
		(end 95.020892 -283.544264)
		(width 0.0889)
		(layer "In6.Cu")
		(net "UPI_CPU0_CPU1_P2P2_DP<8>")
	)
	(arc
		(start 348.695264 -285.985712)
		(mid 348.900336 -286.189391)
		(end 348.977966 -286.467804)
		(width 0.0889)
		(layer "In6.Cu")
		(net "UPI_CPU0_CPU1_P2P2_DP<8>")
	)
	(arc
		(start 348.507812 -287.304734)
		(mid 348.428442 -287.578468)
		(end 348.225618 -287.778698)
		(width 0.0889)
		(layer "In6.Cu")
		(net "UPI_CPU0_CPU1_P2P2_DP<8>")
	)
	(arc
		(start 92.388944 -289.645852)
		(mid 92.313939 -289.530393)
		(end 92.204794 -289.446462)
		(width 0.0889)
		(layer "In6.Cu")
		(net "UPI_CPU0_CPU1_P2P2_DP<8>")
	)
	(arc
		(start 97.002092 -279.478232)
		(mid 97.204679 -279.684583)
		(end 97.278698 -279.964134)
		(width 0.0889)
		(layer "In6.Cu")
		(net "UPI_CPU0_CPU1_P2P2_DP<8>")
	)
	(arc
		(start 97.067878 -280.404824)
		(mid 97.059432 -280.411509)
		(end 97.05086 -280.418032)
		(width 0.0889)
		(layer "In6.Cu")
		(net "UPI_CPU0_CPU1_P2P2_DP<8>")
	)
	(arc
		(start 348.038166 -288.121598)
		(mid 347.958004 -288.393787)
		(end 347.755718 -288.592768)
		(width 0.0889)
		(layer "In6.Cu")
		(net "UPI_CPU0_CPU1_P2P2_DP<8>")
	)
	(arc
		(start 348.977966 -286.475424)
		(mid 348.905731 -286.751948)
		(end 348.707456 -286.95777)
		(width 0.0889)
		(layer "In6.Cu")
		(net "UPI_CPU0_CPU1_P2P2_DP<8>")
	)
	(arc
		(start 96.430592 -279.474676)
		(mid 96.704791 -279.398841)
		(end 96.981264 -279.46604)
		(width 0.0889)
		(layer "In6.Cu")
		(net "UPI_CPU0_CPU1_P2P2_DP<8>")
	)
	(arc
		(start 95.208344 -283.201364)
		(mid 95.288506 -282.929175)
		(end 95.490792 -282.730194)
		(width 0.0889)
		(layer "In6.Cu")
		(net "UPI_CPU0_CPU1_P2P2_DP<8>")
	)
	(arc
		(start 348.686374 -286.969962)
		(mid 348.55546 -287.106322)
		(end 348.507812 -287.28924)
		(width 0.0889)
		(layer "In6.Cu")
		(net "UPI_CPU0_CPU1_P2P2_DP<8>")
	)
	(arc
		(start 347.568266 -289.078416)
		(mid 347.643271 -289.193875)
		(end 347.752416 -289.277806)
		(width 0.0889)
		(layer "In6.Cu")
		(net "UPI_CPU0_CPU1_P2P2_DP<8>")
	)
	(arc
		(start 347.746828 -288.597848)
		(mid 347.615914 -288.734208)
		(end 347.568266 -288.917126)
		(width 0.0889)
		(layer "In6.Cu")
		(net "UPI_CPU0_CPU1_P2P2_DP<8>")
	)
	(arc
		(start 347.752162 -289.27806)
		(mid 347.926407 -289.417106)
		(end 348.037658 -289.610292)
		(width 0.0889)
		(layer "In6.Cu")
		(net "UPI_CPU0_CPU1_P2P2_DP<8>")
	)
	(segment
		(start 349.822516 -281.869896)
		(end 349.822516 -282.405582)
		(width 0.13208)
		(layer "F.Cu")
		(net "UPI_CPU0_CPU1_P2P2_DP<7>")
	)
	(segment
		(start 95.303848 -282.405582)
		(end 95.303594 -282.405836)
		(width 0.13208)
		(layer "F.Cu")
		(net "UPI_CPU0_CPU1_P2P2_DP<7>")
	)
	(segment
		(start 349.822516 -282.405582)
		(end 349.822262 -282.405836)
		(width 0.13208)
		(layer "F.Cu")
		(net "UPI_CPU0_CPU1_P2P2_DP<7>")
	)
	(segment
		(start 95.303848 -281.869896)
		(end 95.303848 -282.405582)
		(width 0.13208)
		(layer "F.Cu")
		(net "UPI_CPU0_CPU1_P2P2_DP<7>")
	)
	(segment
		(start 345.891358 -300.045882)
		(end 345.967304 -300.236128)
		(width 0.14732)
		(layer "In6.Cu")
		(net "UPI_CPU0_CPU1_P2P2_DP<7>")
	)
	(segment
		(start 60.930282 -329.673712)
		(end 60.734194 -329.614276)
		(width 0.14732)
		(layer "In6.Cu")
		(net "UPI_CPU0_CPU1_P2P2_DP<7>")
	)
	(segment
		(start 92.579698 -286.48533)
		(end 92.579698 -286.475424)
		(width 0.0889)
		(layer "In6.Cu")
		(net "UPI_CPU0_CPU1_P2P2_DP<7>")
	)
	(segment
		(start 346.453968 -299.101002)
		(end 346.226892 -299.6311)
		(width 0.14732)
		(layer "In6.Cu")
		(net "UPI_CPU0_CPU1_P2P2_DP<7>")
	)
	(segment
		(start 93.23959 -285.335472)
		(end 93.242892 -285.33344)
		(width 0.0889)
		(layer "In6.Cu")
		(net "UPI_CPU0_CPU1_P2P2_DP<7>")
	)
	(segment
		(start 68.009516 -317.174118)
		(end 80.011778 -305.171856)
		(width 0.14732)
		(layer "In6.Cu")
		(net "UPI_CPU0_CPU1_P2P2_DP<7>")
	)
	(segment
		(start 349.822262 -282.405836)
		(end 349.978726 -282.134818)
		(width 0.0889)
		(layer "In6.Cu")
		(net "UPI_CPU0_CPU1_P2P2_DP<7>")
	)
	(segment
		(start 349.07855 -287.608518)
		(end 349.06966 -287.613598)
		(width 0.0889)
		(layer "In6.Cu")
		(net "UPI_CPU0_CPU1_P2P2_DP<7>")
	)
	(segment
		(start 83.3501 -302.006)
		(end 83.659472 -301.696628)
		(width 0.14732)
		(layer "In6.Cu")
		(net "UPI_CPU0_CPU1_P2P2_DP<7>")
	)
	(segment
		(start 90.624406 -290.523422)
		(end 90.624406 -289.706558)
		(width 0.0889)
		(layer "In6.Cu")
		(net "UPI_CPU0_CPU1_P2P2_DP<7>")
	)
	(segment
		(start 83.177634 -302.006)
		(end 83.3501 -302.006)
		(width 0.14732)
		(layer "In6.Cu")
		(net "UPI_CPU0_CPU1_P2P2_DP<7>")
	)
	(segment
		(start 346.596462 -294.709596)
		(end 346.596462 -298.404788)
		(width 0.14732)
		(layer "In6.Cu")
		(net "UPI_CPU0_CPU1_P2P2_DP<7>")
	)
	(segment
		(start 346.539566 -293.148258)
		(end 346.539566 -293.323518)
		(width 0.0889)
		(layer "In6.Cu")
		(net "UPI_CPU0_CPU1_P2P2_DP<7>")
	)
	(segment
		(start 350.476058 -283.546296)
		(end 350.473518 -283.54782)
		(width 0.0889)
		(layer "In6.Cu")
		(net "UPI_CPU0_CPU1_P2P2_DP<7>")
	)
	(segment
		(start 350.479614 -283.544264)
		(end 350.478852 -283.544772)
		(width 0.0889)
		(layer "In6.Cu")
		(net "UPI_CPU0_CPU1_P2P2_DP<7>")
	)
	(segment
		(start 61.044582 -330.194666)
		(end 61.104018 -329.998832)
		(width 0.14732)
		(layer "In6.Cu")
		(net "UPI_CPU0_CPU1_P2P2_DP<7>")
	)
	(segment
		(start 80.493362 -304.690272)
		(end 80.802226 -304.381408)
		(width 0.14732)
		(layer "In6.Cu")
		(net "UPI_CPU0_CPU1_P2P2_DP<7>")
	)
	(segment
		(start 93.236796 -285.336996)
		(end 93.23959 -285.335472)
		(width 0.0889)
		(layer "In6.Cu")
		(net "UPI_CPU0_CPU1_P2P2_DP<7>")
	)
	(segment
		(start 350.666812 -283.21127)
		(end 350.666812 -283.228542)
		(width 0.0889)
		(layer "In6.Cu")
		(net "UPI_CPU0_CPU1_P2P2_DP<7>")
	)
	(segment
		(start 350.01835 -284.353)
		(end 350.00946 -284.35808)
		(width 0.0889)
		(layer "In6.Cu")
		(net "UPI_CPU0_CPU1_P2P2_DP<7>")
	)
	(segment
		(start 346.596716 -294.460168)
		(end 346.596716 -294.482266)
		(width 0.0889)
		(layer "In6.Cu")
		(net "UPI_CPU0_CPU1_P2P2_DP<7>")
	)
	(segment
		(start 92.109798 -287.299146)
		(end 92.109798 -287.28924)
		(width 0.0889)
		(layer "In6.Cu")
		(net "UPI_CPU0_CPU1_P2P2_DP<7>")
	)
	(segment
		(start 91.639898 -288.11728)
		(end 91.639898 -288.103056)
		(width 0.0889)
		(layer "In6.Cu")
		(net "UPI_CPU0_CPU1_P2P2_DP<7>")
	)
	(segment
		(start 83.659472 -301.524162)
		(end 84.769452 -300.414182)
		(width 0.14732)
		(layer "In6.Cu")
		(net "UPI_CPU0_CPU1_P2P2_DP<7>")
	)
	(segment
		(start 346.539566 -292.767258)
		(end 346.638626 -292.866318)
		(width 0.0889)
		(layer "In6.Cu")
		(net "UPI_CPU0_CPU1_P2P2_DP<7>")
	)
	(segment
		(start 346.638626 -292.866318)
		(end 346.638626 -293.049198)
		(width 0.0889)
		(layer "In6.Cu")
		(net "UPI_CPU0_CPU1_P2P2_DP<7>")
	)
	(segment
		(start 345.516454 -301.288196)
		(end 342.149938 -304.654712)
		(width 0.14732)
		(layer "In6.Cu")
		(net "UPI_CPU0_CPU1_P2P2_DP<7>")
	)
	(segment
		(start 348.787466 -289.64509)
		(end 348.787466 -290.168838)
		(width 0.0889)
		(layer "In6.Cu")
		(net "UPI_CPU0_CPU1_P2P2_DP<7>")
	)
	(segment
		(start 84.769452 -300.414182)
		(end 86.947248 -295.155366)
		(width 0.14732)
		(layer "In6.Cu")
		(net "UPI_CPU0_CPU1_P2P2_DP<7>")
	)
	(segment
		(start 95.753428 -382.216406)
		(end 72.700388 -372.66753)
		(width 0.14732)
		(layer "In6.Cu")
		(net "UPI_CPU0_CPU1_P2P2_DP<7>")
	)
	(segment
		(start 68.668646 -368.431064)
		(end 68.463922 -368.431064)
		(width 0.14732)
		(layer "In6.Cu")
		(net "UPI_CPU0_CPU1_P2P2_DP<7>")
	)
	(segment
		(start 60.325 -328.480166)
		(end 60.46978 -328.335386)
		(width 0.14732)
		(layer "In6.Cu")
		(net "UPI_CPU0_CPU1_P2P2_DP<7>")
	)
	(segment
		(start 89.88679 -292.215824)
		(end 89.88679 -291.320982)
		(width 0.14732)
		(layer "In6.Cu")
		(net "UPI_CPU0_CPU1_P2P2_DP<7>")
	)
	(segment
		(start 349.548704 -285.166816)
		(end 349.533464 -285.175706)
		(width 0.0889)
		(layer "In6.Cu")
		(net "UPI_CPU0_CPU1_P2P2_DP<7>")
	)
	(segment
		(start 81.28381 -304.07229)
		(end 81.28381 -303.899824)
		(width 0.14732)
		(layer "In6.Cu")
		(net "UPI_CPU0_CPU1_P2P2_DP<7>")
	)
	(segment
		(start 274.403312 -346.338398)
		(end 274.403312 -370.02593)
		(width 0.14732)
		(layer "In6.Cu")
		(net "UPI_CPU0_CPU1_P2P2_DP<7>")
	)
	(segment
		(start 346.596716 -294.709342)
		(end 346.596462 -294.709596)
		(width 0.14732)
		(layer "In6.Cu")
		(net "UPI_CPU0_CPU1_P2P2_DP<7>")
	)
	(segment
		(start 90.624406 -289.706558)
		(end 90.884502 -289.446462)
		(width 0.0889)
		(layer "In6.Cu")
		(net "UPI_CPU0_CPU1_P2P2_DP<7>")
	)
	(segment
		(start 91.81846 -287.783778)
		(end 91.824048 -287.78073)
		(width 0.0889)
		(layer "In6.Cu")
		(net "UPI_CPU0_CPU1_P2P2_DP<7>")
	)
	(segment
		(start 266.646406 -377.782836)
		(end 161.210244 -386.730748)
		(width 0.14732)
		(layer "In6.Cu")
		(net "UPI_CPU0_CPU1_P2P2_DP<7>")
	)
	(segment
		(start 161.210244 -386.730748)
		(end 126.185168 -386.730748)
		(width 0.14732)
		(layer "In6.Cu")
		(net "UPI_CPU0_CPU1_P2P2_DP<7>")
	)
	(segment
		(start 80.184244 -305.171856)
		(end 80.493362 -304.862738)
		(width 0.14732)
		(layer "In6.Cu")
		(net "UPI_CPU0_CPU1_P2P2_DP<7>")
	)
	(segment
		(start 61.104018 -329.998832)
		(end 60.930282 -329.673712)
		(width 0.14732)
		(layer "In6.Cu")
		(net "UPI_CPU0_CPU1_P2P2_DP<7>")
	)
	(segment
		(start 91.826588 -287.779206)
		(end 91.82735 -287.778698)
		(width 0.0889)
		(layer "In6.Cu")
		(net "UPI_CPU0_CPU1_P2P2_DP<7>")
	)
	(segment
		(start 350.478852 -283.544772)
		(end 350.476058 -283.546296)
		(width 0.0889)
		(layer "In6.Cu")
		(net "UPI_CPU0_CPU1_P2P2_DP<7>")
	)
	(segment
		(start 63.432944 -322.977256)
		(end 64.004698 -322.405502)
		(width 0.14732)
		(layer "In6.Cu")
		(net "UPI_CPU0_CPU1_P2P2_DP<7>")
	)
	(segment
		(start 92.75826 -286.156146)
		(end 92.76715 -286.151066)
		(width 0.0889)
		(layer "In6.Cu")
		(net "UPI_CPU0_CPU1_P2P2_DP<7>")
	)
	(segment
		(start 65.771776 -320.047874)
		(end 66.219578 -319.378076)
		(width 0.14732)
		(layer "In6.Cu")
		(net "UPI_CPU0_CPU1_P2P2_DP<7>")
	)
	(segment
		(start 70.120256 -369.882674)
		(end 69.915532 -369.882674)
		(width 0.14732)
		(layer "In6.Cu")
		(net "UPI_CPU0_CPU1_P2P2_DP<7>")
	)
	(segment
		(start 318.51092 -326.001888)
		(end 317.398654 -328.68743)
		(width 0.14732)
		(layer "In6.Cu")
		(net "UPI_CPU0_CPU1_P2P2_DP<7>")
	)
	(segment
		(start 68.929504 -368.691922)
		(end 68.668646 -368.431064)
		(width 0.14732)
		(layer "In6.Cu")
		(net "UPI_CPU0_CPU1_P2P2_DP<7>")
	)
	(segment
		(start 346.226892 -299.6311)
		(end 346.036392 -299.707046)
		(width 0.14732)
		(layer "In6.Cu")
		(net "UPI_CPU0_CPU1_P2P2_DP<7>")
	)
	(segment
		(start 348.317566 -288.898584)
		(end 348.317566 -289.113722)
		(width 0.0889)
		(layer "In6.Cu")
		(net "UPI_CPU0_CPU1_P2P2_DP<7>")
	)
	(segment
		(start 93.049344 -285.683452)
		(end 93.049344 -285.661354)
		(width 0.0889)
		(layer "In6.Cu")
		(net "UPI_CPU0_CPU1_P2P2_DP<7>")
	)
	(segment
		(start 64.004698 -322.405502)
		(end 64.474598 -322.210684)
		(width 0.14732)
		(layer "In6.Cu")
		(net "UPI_CPU0_CPU1_P2P2_DP<7>")
	)
	(segment
		(start 62.549278 -354.995734)
		(end 62.549278 -335.214468)
		(width 0.14732)
		(layer "In6.Cu")
		(net "UPI_CPU0_CPU1_P2P2_DP<7>")
	)
	(segment
		(start 81.76514 -303.59096)
		(end 82.074512 -303.281588)
		(width 0.14732)
		(layer "In6.Cu")
		(net "UPI_CPU0_CPU1_P2P2_DP<7>")
	)
	(segment
		(start 80.493362 -304.862738)
		(end 80.493362 -304.690272)
		(width 0.14732)
		(layer "In6.Cu")
		(net "UPI_CPU0_CPU1_P2P2_DP<7>")
	)
	(segment
		(start 346.638626 -293.049198)
		(end 346.539566 -293.148258)
		(width 0.0889)
		(layer "In6.Cu")
		(net "UPI_CPU0_CPU1_P2P2_DP<7>")
	)
	(segment
		(start 91.824048 -287.78073)
		(end 91.826588 -287.779206)
		(width 0.0889)
		(layer "In6.Cu")
		(net "UPI_CPU0_CPU1_P2P2_DP<7>")
	)
	(segment
		(start 349.257112 -285.661354)
		(end 349.257112 -285.675578)
		(width 0.0889)
		(layer "In6.Cu")
		(net "UPI_CPU0_CPU1_P2P2_DP<7>")
	)
	(segment
		(start 68.463922 -368.431064)
		(end 67.866768 -367.83391)
		(width 0.14732)
		(layer "In6.Cu")
		(net "UPI_CPU0_CPU1_P2P2_DP<7>")
	)
	(segment
		(start 89.88679 -291.320982)
		(end 90.414602 -290.79317)
		(width 0.14732)
		(layer "In6.Cu")
		(net "UPI_CPU0_CPU1_P2P2_DP<7>")
	)
	(segment
		(start 60.325 -327.822306)
		(end 60.325 -326.267572)
		(width 0.14732)
		(layer "In6.Cu")
		(net "UPI_CPU0_CPU1_P2P2_DP<7>")
	)
	(segment
		(start 86.947248 -295.155366)
		(end 89.88679 -292.215824)
		(width 0.14732)
		(layer "In6.Cu")
		(net "UPI_CPU0_CPU1_P2P2_DP<7>")
	)
	(segment
		(start 348.317566 -289.113722)
		(end 348.31782 -289.113976)
		(width 0.0889)
		(layer "In6.Cu")
		(net "UPI_CPU0_CPU1_P2P2_DP<7>")
	)
	(segment
		(start 80.974692 -304.381408)
		(end 81.28381 -304.07229)
		(width 0.14732)
		(layer "In6.Cu")
		(net "UPI_CPU0_CPU1_P2P2_DP<7>")
	)
	(segment
		(start 60.46978 -328.335386)
		(end 60.46978 -327.967086)
		(width 0.14732)
		(layer "In6.Cu")
		(net "UPI_CPU0_CPU1_P2P2_DP<7>")
	)
	(segment
		(start 69.189854 -369.156996)
		(end 68.929504 -368.896646)
		(width 0.14732)
		(layer "In6.Cu")
		(net "UPI_CPU0_CPU1_P2P2_DP<7>")
	)
	(segment
		(start 346.638626 -292.317678)
		(end 346.638626 -292.492938)
		(width 0.0889)
		(layer "In6.Cu")
		(net "UPI_CPU0_CPU1_P2P2_DP<7>")
	)
	(segment
		(start 64.474598 -322.210684)
		(end 65.159636 -321.525646)
		(width 0.14732)
		(layer "In6.Cu")
		(net "UPI_CPU0_CPU1_P2P2_DP<7>")
	)
	(segment
		(start 60.325 -326.267572)
		(end 60.520072 -325.796656)
		(width 0.14732)
		(layer "In6.Cu")
		(net "UPI_CPU0_CPU1_P2P2_DP<7>")
	)
	(segment
		(start 95.460058 -282.134818)
		(end 95.303594 -282.405836)
		(width 0.0889)
		(layer "In6.Cu")
		(net "UPI_CPU0_CPU1_P2P2_DP<7>")
	)
	(segment
		(start 60.520072 -325.796656)
		(end 60.835032 -325.481696)
		(width 0.14732)
		(layer "In6.Cu")
		(net "UPI_CPU0_CPU1_P2P2_DP<7>")
	)
	(segment
		(start 82.074512 -303.109122)
		(end 82.387186 -302.796448)
		(width 0.14732)
		(layer "In6.Cu")
		(net "UPI_CPU0_CPU1_P2P2_DP<7>")
	)
	(segment
		(start 67.866768 -367.83391)
		(end 62.549278 -354.995734)
		(width 0.14732)
		(layer "In6.Cu")
		(net "UPI_CPU0_CPU1_P2P2_DP<7>")
	)
	(segment
		(start 349.533464 -285.175706)
		(end 349.533718 -285.175452)
		(width 0.0889)
		(layer "In6.Cu")
		(net "UPI_CPU0_CPU1_P2P2_DP<7>")
	)
	(segment
		(start 82.387186 -302.796448)
		(end 82.559652 -302.796448)
		(width 0.14732)
		(layer "In6.Cu")
		(net "UPI_CPU0_CPU1_P2P2_DP<7>")
	)
	(segment
		(start 60.46978 -327.967086)
		(end 60.325 -327.822306)
		(width 0.14732)
		(layer "In6.Cu")
		(net "UPI_CPU0_CPU1_P2P2_DP<7>")
	)
	(segment
		(start 61.509402 -331.06487)
		(end 61.044582 -330.194666)
		(width 0.14732)
		(layer "In6.Cu")
		(net "UPI_CPU0_CPU1_P2P2_DP<7>")
	)
	(segment
		(start 68.929504 -368.896646)
		(end 68.929504 -368.691922)
		(width 0.14732)
		(layer "In6.Cu")
		(net "UPI_CPU0_CPU1_P2P2_DP<7>")
	)
	(segment
		(start 349.536258 -286.801814)
		(end 349.533718 -286.803338)
		(width 0.0889)
		(layer "In6.Cu")
		(net "UPI_CPU0_CPU1_P2P2_DP<7>")
	)
	(segment
		(start 82.86877 -302.48733)
		(end 82.86877 -302.314864)
		(width 0.14732)
		(layer "In6.Cu")
		(net "UPI_CPU0_CPU1_P2P2_DP<7>")
	)
	(segment
		(start 94.929198 -282.42006)
		(end 94.929198 -282.3972)
		(width 0.0889)
		(layer "In6.Cu")
		(net "UPI_CPU0_CPU1_P2P2_DP<7>")
	)
	(segment
		(start 80.011778 -305.171856)
		(end 80.184244 -305.171856)
		(width 0.14732)
		(layer "In6.Cu")
		(net "UPI_CPU0_CPU1_P2P2_DP<7>")
	)
	(segment
		(start 94.167706 -283.714444)
		(end 94.176596 -283.709364)
		(width 0.0889)
		(layer "In6.Cu")
		(net "UPI_CPU0_CPU1_P2P2_DP<7>")
	)
	(segment
		(start 93.989144 -284.049216)
		(end 93.989144 -284.033722)
		(width 0.0889)
		(layer "In6.Cu")
		(net "UPI_CPU0_CPU1_P2P2_DP<7>")
	)
	(segment
		(start 286.092138 -337.24596)
		(end 281.660092 -339.081618)
		(width 0.14732)
		(layer "In6.Cu")
		(net "UPI_CPU0_CPU1_P2P2_DP<7>")
	)
	(segment
		(start 66.219578 -319.378076)
		(end 68.009516 -317.587884)
		(width 0.14732)
		(layer "In6.Cu")
		(net "UPI_CPU0_CPU1_P2P2_DP<7>")
	)
	(segment
		(start 62.549278 -335.214468)
		(end 61.509402 -331.06487)
		(width 0.14732)
		(layer "In6.Cu")
		(net "UPI_CPU0_CPU1_P2P2_DP<7>")
	)
	(segment
		(start 90.430096 -290.777676)
		(end 90.430096 -290.717732)
		(width 0.0889)
		(layer "In6.Cu")
		(net "UPI_CPU0_CPU1_P2P2_DP<7>")
	)
	(segment
		(start 91.34856 -288.597848)
		(end 91.35745 -288.592768)
		(width 0.0889)
		(layer "In6.Cu")
		(net "UPI_CPU0_CPU1_P2P2_DP<7>")
	)
	(segment
		(start 69.655182 -369.4176)
		(end 69.394578 -369.156996)
		(width 0.14732)
		(layer "In6.Cu")
		(net "UPI_CPU0_CPU1_P2P2_DP<7>")
	)
	(segment
		(start 70.38086 -370.348002)
		(end 70.38086 -370.143278)
		(width 0.14732)
		(layer "In6.Cu")
		(net "UPI_CPU0_CPU1_P2P2_DP<7>")
	)
	(segment
		(start 90.414602 -290.79317)
		(end 90.430096 -290.777676)
		(width 0.0889)
		(layer "In6.Cu")
		(net "UPI_CPU0_CPU1_P2P2_DP<7>")
	)
	(segment
		(start 82.86877 -302.314864)
		(end 83.177634 -302.006)
		(width 0.14732)
		(layer "In6.Cu")
		(net "UPI_CPU0_CPU1_P2P2_DP<7>")
	)
	(segment
		(start 69.394578 -369.156996)
		(end 69.189854 -369.156996)
		(width 0.14732)
		(layer "In6.Cu")
		(net "UPI_CPU0_CPU1_P2P2_DP<7>")
	)
	(segment
		(start 342.149938 -304.654712)
		(end 338.23656 -306.276248)
		(width 0.14732)
		(layer "In6.Cu")
		(net "UPI_CPU0_CPU1_P2P2_DP<7>")
	)
	(segment
		(start 349.539814 -286.799782)
		(end 349.539052 -286.80029)
		(width 0.0889)
		(layer "In6.Cu")
		(net "UPI_CPU0_CPU1_P2P2_DP<7>")
	)
	(segment
		(start 82.074512 -303.281588)
		(end 82.074512 -303.109122)
		(width 0.14732)
		(layer "In6.Cu")
		(net "UPI_CPU0_CPU1_P2P2_DP<7>")
	)
	(segment
		(start 126.185168 -386.730748)
		(end 95.753428 -382.216406)
		(width 0.14732)
		(layer "In6.Cu")
		(net "UPI_CPU0_CPU1_P2P2_DP<7>")
	)
	(segment
		(start 348.787466 -290.168838)
		(end 348.663768 -290.292536)
		(width 0.0889)
		(layer "In6.Cu")
		(net "UPI_CPU0_CPU1_P2P2_DP<7>")
	)
	(segment
		(start 65.159636 -321.525646)
		(end 65.771776 -320.047874)
		(width 0.14732)
		(layer "In6.Cu")
		(net "UPI_CPU0_CPU1_P2P2_DP<7>")
	)
	(segment
		(start 348.399354 -290.416488)
		(end 348.399354 -290.55695)
		(width 0.0889)
		(layer "In6.Cu")
		(net "UPI_CPU0_CPU1_P2P2_DP<7>")
	)
	(segment
		(start 90.430096 -290.717732)
		(end 90.624406 -290.523422)
		(width 0.0889)
		(layer "In6.Cu")
		(net "UPI_CPU0_CPU1_P2P2_DP<7>")
	)
	(segment
		(start 82.559652 -302.796448)
		(end 82.86877 -302.48733)
		(width 0.14732)
		(layer "In6.Cu")
		(net "UPI_CPU0_CPU1_P2P2_DP<7>")
	)
	(segment
		(start 70.38086 -370.143278)
		(end 70.120256 -369.882674)
		(width 0.14732)
		(layer "In6.Cu")
		(net "UPI_CPU0_CPU1_P2P2_DP<7>")
	)
	(segment
		(start 346.638626 -293.422578)
		(end 346.638626 -294.418258)
		(width 0.0889)
		(layer "In6.Cu")
		(net "UPI_CPU0_CPU1_P2P2_DP<7>")
	)
	(segment
		(start 345.967304 -300.236128)
		(end 345.516454 -301.288196)
		(width 0.14732)
		(layer "In6.Cu")
		(net "UPI_CPU0_CPU1_P2P2_DP<7>")
	)
	(segment
		(start 93.235272 -285.337758)
		(end 93.236796 -285.336996)
		(width 0.0889)
		(layer "In6.Cu")
		(net "UPI_CPU0_CPU1_P2P2_DP<7>")
	)
	(segment
		(start 346.596716 -294.482266)
		(end 346.596716 -294.709342)
		(width 0.14732)
		(layer "In6.Cu")
		(net "UPI_CPU0_CPU1_P2P2_DP<7>")
	)
	(segment
		(start 62.187836 -324.921372)
		(end 62.938914 -324.170294)
		(width 0.14732)
		(layer "In6.Cu")
		(net "UPI_CPU0_CPU1_P2P2_DP<7>")
	)
	(segment
		(start 91.169998 -289.114484)
		(end 91.169998 -288.917126)
		(width 0.0889)
		(layer "In6.Cu")
		(net "UPI_CPU0_CPU1_P2P2_DP<7>")
	)
	(segment
		(start 81.592674 -303.59096)
		(end 81.76514 -303.59096)
		(width 0.14732)
		(layer "In6.Cu")
		(net "UPI_CPU0_CPU1_P2P2_DP<7>")
	)
	(segment
		(start 350.196912 -282.405582)
		(end 350.196658 -282.419806)
		(width 0.0889)
		(layer "In6.Cu")
		(net "UPI_CPU0_CPU1_P2P2_DP<7>")
	)
	(segment
		(start 346.596462 -298.404788)
		(end 346.453968 -299.101002)
		(width 0.14732)
		(layer "In6.Cu")
		(net "UPI_CPU0_CPU1_P2P2_DP<7>")
	)
	(segment
		(start 346.036392 -299.707046)
		(end 345.891358 -300.045882)
		(width 0.14732)
		(layer "In6.Cu")
		(net "UPI_CPU0_CPU1_P2P2_DP<7>")
	)
	(segment
		(start 346.539566 -293.323518)
		(end 346.638626 -293.422578)
		(width 0.0889)
		(layer "In6.Cu")
		(net "UPI_CPU0_CPU1_P2P2_DP<7>")
	)
	(segment
		(start 349.727012 -286.466788)
		(end 349.727012 -286.48406)
		(width 0.0889)
		(layer "In6.Cu")
		(net "UPI_CPU0_CPU1_P2P2_DP<7>")
	)
	(segment
		(start 93.69806 -284.52826)
		(end 93.70695 -284.52318)
		(width 0.0889)
		(layer "In6.Cu")
		(net "UPI_CPU0_CPU1_P2P2_DP<7>")
	)
	(segment
		(start 349.539052 -286.80029)
		(end 349.536258 -286.801814)
		(width 0.0889)
		(layer "In6.Cu")
		(net "UPI_CPU0_CPU1_P2P2_DP<7>")
	)
	(segment
		(start 281.660092 -339.081618)
		(end 274.403312 -346.338398)
		(width 0.14732)
		(layer "In6.Cu")
		(net "UPI_CPU0_CPU1_P2P2_DP<7>")
	)
	(segment
		(start 348.523306 -290.292536)
		(end 348.399354 -290.416488)
		(width 0.0889)
		(layer "In6.Cu")
		(net "UPI_CPU0_CPU1_P2P2_DP<7>")
	)
	(segment
		(start 95.438976 -282.05684)
		(end 95.460058 -282.134818)
		(width 0.0889)
		(layer "In6.Cu")
		(net "UPI_CPU0_CPU1_P2P2_DP<7>")
	)
	(segment
		(start 348.663768 -290.292536)
		(end 348.523306 -290.292536)
		(width 0.0889)
		(layer "In6.Cu")
		(net "UPI_CPU0_CPU1_P2P2_DP<7>")
	)
	(segment
		(start 60.734194 -329.614276)
		(end 60.325 -328.848466)
		(width 0.14732)
		(layer "In6.Cu")
		(net "UPI_CPU0_CPU1_P2P2_DP<7>")
	)
	(segment
		(start 62.938914 -324.170294)
		(end 63.432944 -322.977256)
		(width 0.14732)
		(layer "In6.Cu")
		(net "UPI_CPU0_CPU1_P2P2_DP<7>")
	)
	(segment
		(start 69.655182 -369.622324)
		(end 69.655182 -369.4176)
		(width 0.14732)
		(layer "In6.Cu")
		(net "UPI_CPU0_CPU1_P2P2_DP<7>")
	)
	(segment
		(start 346.638626 -292.492938)
		(end 346.539566 -292.591998)
		(width 0.0889)
		(layer "In6.Cu")
		(net "UPI_CPU0_CPU1_P2P2_DP<7>")
	)
	(segment
		(start 94.637606 -282.900628)
		(end 94.646496 -282.895548)
		(width 0.0889)
		(layer "In6.Cu")
		(net "UPI_CPU0_CPU1_P2P2_DP<7>")
	)
	(segment
		(start 68.009516 -317.587884)
		(end 68.009516 -317.174118)
		(width 0.14732)
		(layer "In6.Cu")
		(net "UPI_CPU0_CPU1_P2P2_DP<7>")
	)
	(segment
		(start 94.459044 -283.229812)
		(end 94.459044 -283.219906)
		(width 0.0889)
		(layer "In6.Cu")
		(net "UPI_CPU0_CPU1_P2P2_DP<7>")
	)
	(segment
		(start 80.802226 -304.381408)
		(end 80.974692 -304.381408)
		(width 0.14732)
		(layer "In6.Cu")
		(net "UPI_CPU0_CPU1_P2P2_DP<7>")
	)
	(segment
		(start 346.539566 -292.591998)
		(end 346.539566 -292.767258)
		(width 0.0889)
		(layer "In6.Cu")
		(net "UPI_CPU0_CPU1_P2P2_DP<7>")
	)
	(segment
		(start 346.638626 -294.418258)
		(end 346.596716 -294.460168)
		(width 0.0889)
		(layer "In6.Cu")
		(net "UPI_CPU0_CPU1_P2P2_DP<7>")
	)
	(segment
		(start 83.659472 -301.696628)
		(end 83.659472 -301.524162)
		(width 0.14732)
		(layer "In6.Cu")
		(net "UPI_CPU0_CPU1_P2P2_DP<7>")
	)
	(segment
		(start 317.398654 -328.68743)
		(end 308.840124 -337.24596)
		(width 0.14732)
		(layer "In6.Cu")
		(net "UPI_CPU0_CPU1_P2P2_DP<7>")
	)
	(segment
		(start 72.700388 -372.66753)
		(end 70.38086 -370.348002)
		(width 0.14732)
		(layer "In6.Cu")
		(net "UPI_CPU0_CPU1_P2P2_DP<7>")
	)
	(segment
		(start 274.403312 -370.02593)
		(end 266.646406 -377.782836)
		(width 0.14732)
		(layer "In6.Cu")
		(net "UPI_CPU0_CPU1_P2P2_DP<7>")
	)
	(segment
		(start 308.840124 -337.24596)
		(end 286.092138 -337.24596)
		(width 0.14732)
		(layer "In6.Cu")
		(net "UPI_CPU0_CPU1_P2P2_DP<7>")
	)
	(segment
		(start 338.23656 -306.276248)
		(end 318.51092 -326.001888)
		(width 0.14732)
		(layer "In6.Cu")
		(net "UPI_CPU0_CPU1_P2P2_DP<7>")
	)
	(segment
		(start 348.399354 -290.55695)
		(end 346.638626 -292.317678)
		(width 0.0889)
		(layer "In6.Cu")
		(net "UPI_CPU0_CPU1_P2P2_DP<7>")
	)
	(segment
		(start 92.28836 -286.969962)
		(end 92.29725 -286.964882)
		(width 0.0889)
		(layer "In6.Cu")
		(net "UPI_CPU0_CPU1_P2P2_DP<7>")
	)
	(segment
		(start 348.608904 -288.422334)
		(end 348.600014 -288.427414)
		(width 0.0889)
		(layer "In6.Cu")
		(net "UPI_CPU0_CPU1_P2P2_DP<7>")
	)
	(segment
		(start 69.915532 -369.882674)
		(end 69.655182 -369.622324)
		(width 0.14732)
		(layer "In6.Cu")
		(net "UPI_CPU0_CPU1_P2P2_DP<7>")
	)
	(segment
		(start 60.325 -328.848466)
		(end 60.325 -328.480166)
		(width 0.14732)
		(layer "In6.Cu")
		(net "UPI_CPU0_CPU1_P2P2_DP<7>")
	)
	(segment
		(start 60.835032 -325.481696)
		(end 62.187836 -324.921372)
		(width 0.14732)
		(layer "In6.Cu")
		(net "UPI_CPU0_CPU1_P2P2_DP<7>")
	)
	(segment
		(start 93.227906 -285.342076)
		(end 93.235272 -285.337758)
		(width 0.0889)
		(layer "In6.Cu")
		(net "UPI_CPU0_CPU1_P2P2_DP<7>")
	)
	(segment
		(start 349.978726 -282.134818)
		(end 350.056958 -282.11399)
		(width 0.0889)
		(layer "In6.Cu")
		(net "UPI_CPU0_CPU1_P2P2_DP<7>")
	)
	(segment
		(start 90.884502 -289.446462)
		(end 90.884248 -289.446462)
		(width 0.0889)
		(layer "In6.Cu")
		(net "UPI_CPU0_CPU1_P2P2_DP<7>")
	)
	(segment
		(start 81.28381 -303.899824)
		(end 81.592674 -303.59096)
		(width 0.14732)
		(layer "In6.Cu")
		(net "UPI_CPU0_CPU1_P2P2_DP<7>")
	)
	(segment
		(start 349.727266 -284.832044)
		(end 349.727266 -284.847538)
		(width 0.0889)
		(layer "In6.Cu")
		(net "UPI_CPU0_CPU1_P2P2_DP<7>")
	)
	(segment
		(start 348.787466 -288.087562)
		(end 348.787466 -288.103056)
		(width 0.0889)
		(layer "In6.Cu")
		(net "UPI_CPU0_CPU1_P2P2_DP<7>")
	)
	(arc
		(start 348.600014 -288.427414)
		(mid 348.397728 -288.626395)
		(end 348.317566 -288.898584)
		(width 0.0889)
		(layer "In6.Cu")
		(net "UPI_CPU0_CPU1_P2P2_DP<7>")
	)
	(arc
		(start 348.31782 -289.113976)
		(mid 348.325215 -289.133926)
		(end 348.333314 -289.1536)
		(width 0.0889)
		(layer "In6.Cu")
		(net "UPI_CPU0_CPU1_P2P2_DP<7>")
	)
	(arc
		(start 93.242892 -285.33344)
		(mid 93.445479 -285.127089)
		(end 93.519498 -284.847538)
		(width 0.0889)
		(layer "In6.Cu")
		(net "UPI_CPU0_CPU1_P2P2_DP<7>")
	)
	(arc
		(start 95.116396 -282.081478)
		(mid 95.274884 -282.032545)
		(end 95.438976 -282.05684)
		(width 0.0889)
		(layer "In6.Cu")
		(net "UPI_CPU0_CPU1_P2P2_DP<7>")
	)
	(arc
		(start 349.539814 -286.151066)
		(mid 349.674747 -286.28442)
		(end 349.727012 -286.466788)
		(width 0.0889)
		(layer "In6.Cu")
		(net "UPI_CPU0_CPU1_P2P2_DP<7>")
	)
	(arc
		(start 349.257112 -287.28924)
		(mid 349.209433 -287.47214)
		(end 349.07855 -287.608518)
		(width 0.0889)
		(layer "In6.Cu")
		(net "UPI_CPU0_CPU1_P2P2_DP<7>")
	)
	(arc
		(start 349.257112 -285.675578)
		(mid 349.336331 -285.950263)
		(end 349.539814 -286.151066)
		(width 0.0889)
		(layer "In6.Cu")
		(net "UPI_CPU0_CPU1_P2P2_DP<7>")
	)
	(arc
		(start 94.646496 -282.895548)
		(mid 94.849977 -282.694744)
		(end 94.929198 -282.42006)
		(width 0.0889)
		(layer "In6.Cu")
		(net "UPI_CPU0_CPU1_P2P2_DP<7>")
	)
	(arc
		(start 350.056958 -282.11399)
		(mid 350.160026 -282.243897)
		(end 350.196912 -282.405582)
		(width 0.0889)
		(layer "In6.Cu")
		(net "UPI_CPU0_CPU1_P2P2_DP<7>")
	)
	(arc
		(start 350.473518 -283.54782)
		(mid 350.270931 -283.754171)
		(end 350.196912 -284.033722)
		(width 0.0889)
		(layer "In6.Cu")
		(net "UPI_CPU0_CPU1_P2P2_DP<7>")
	)
	(arc
		(start 350.196658 -282.419806)
		(mid 350.275966 -282.69464)
		(end 350.479614 -282.895548)
		(width 0.0889)
		(layer "In6.Cu")
		(net "UPI_CPU0_CPU1_P2P2_DP<7>")
	)
	(arc
		(start 350.666812 -283.228542)
		(mid 350.614542 -283.410907)
		(end 350.479614 -283.544264)
		(width 0.0889)
		(layer "In6.Cu")
		(net "UPI_CPU0_CPU1_P2P2_DP<7>")
	)
	(arc
		(start 350.479614 -282.895548)
		(mid 350.614547 -283.028902)
		(end 350.666812 -283.21127)
		(width 0.0889)
		(layer "In6.Cu")
		(net "UPI_CPU0_CPU1_P2P2_DP<7>")
	)
	(arc
		(start 93.70695 -284.52318)
		(mid 93.909773 -284.322949)
		(end 93.989144 -284.049216)
		(width 0.0889)
		(layer "In6.Cu")
		(net "UPI_CPU0_CPU1_P2P2_DP<7>")
	)
	(arc
		(start 92.579952 -286.460692)
		(mid 92.631006 -286.286112)
		(end 92.75826 -286.156146)
		(width 0.0889)
		(layer "In6.Cu")
		(net "UPI_CPU0_CPU1_P2P2_DP<7>")
	)
	(arc
		(start 94.929198 -282.3972)
		(mid 94.981468 -282.214835)
		(end 95.116396 -282.081478)
		(width 0.0889)
		(layer "In6.Cu")
		(net "UPI_CPU0_CPU1_P2P2_DP<7>")
	)
	(arc
		(start 349.727012 -286.48406)
		(mid 349.674742 -286.666425)
		(end 349.539814 -286.799782)
		(width 0.0889)
		(layer "In6.Cu")
		(net "UPI_CPU0_CPU1_P2P2_DP<7>")
	)
	(arc
		(start 92.29725 -286.964882)
		(mid 92.501585 -286.762277)
		(end 92.579698 -286.48533)
		(width 0.0889)
		(layer "In6.Cu")
		(net "UPI_CPU0_CPU1_P2P2_DP<7>")
	)
	(arc
		(start 91.170252 -288.902394)
		(mid 91.221306 -288.727814)
		(end 91.34856 -288.597848)
		(width 0.0889)
		(layer "In6.Cu")
		(net "UPI_CPU0_CPU1_P2P2_DP<7>")
	)
	(arc
		(start 91.35745 -288.592768)
		(mid 91.560755 -288.391902)
		(end 91.639898 -288.11728)
		(width 0.0889)
		(layer "In6.Cu")
		(net "UPI_CPU0_CPU1_P2P2_DP<7>")
	)
	(arc
		(start 92.579698 -286.475424)
		(mid 92.57975 -286.468057)
		(end 92.579952 -286.460692)
		(width 0.0889)
		(layer "In6.Cu")
		(net "UPI_CPU0_CPU1_P2P2_DP<7>")
	)
	(arc
		(start 91.82735 -287.778698)
		(mid 92.031685 -287.576093)
		(end 92.109798 -287.299146)
		(width 0.0889)
		(layer "In6.Cu")
		(net "UPI_CPU0_CPU1_P2P2_DP<7>")
	)
	(arc
		(start 348.603316 -289.446208)
		(mid 348.712396 -289.529909)
		(end 348.787466 -289.64509)
		(width 0.0889)
		(layer "In6.Cu")
		(net "UPI_CPU0_CPU1_P2P2_DP<7>")
	)
	(arc
		(start 94.459044 -283.219906)
		(mid 94.506723 -283.037006)
		(end 94.637606 -282.900628)
		(width 0.0889)
		(layer "In6.Cu")
		(net "UPI_CPU0_CPU1_P2P2_DP<7>")
	)
	(arc
		(start 349.06966 -287.613598)
		(mid 348.866837 -287.813829)
		(end 348.787466 -288.087562)
		(width 0.0889)
		(layer "In6.Cu")
		(net "UPI_CPU0_CPU1_P2P2_DP<7>")
	)
	(arc
		(start 350.196912 -284.033722)
		(mid 350.149233 -284.216622)
		(end 350.01835 -284.353)
		(width 0.0889)
		(layer "In6.Cu")
		(net "UPI_CPU0_CPU1_P2P2_DP<7>")
	)
	(arc
		(start 92.76715 -286.151066)
		(mid 92.968432 -285.953579)
		(end 93.049344 -285.683452)
		(width 0.0889)
		(layer "In6.Cu")
		(net "UPI_CPU0_CPU1_P2P2_DP<7>")
	)
	(arc
		(start 348.333314 -289.1536)
		(mid 348.443244 -289.323043)
		(end 348.603316 -289.446208)
		(width 0.0889)
		(layer "In6.Cu")
		(net "UPI_CPU0_CPU1_P2P2_DP<7>")
	)
	(arc
		(start 93.049344 -285.661354)
		(mid 93.097023 -285.478454)
		(end 93.227906 -285.342076)
		(width 0.0889)
		(layer "In6.Cu")
		(net "UPI_CPU0_CPU1_P2P2_DP<7>")
	)
	(arc
		(start 349.533718 -286.803338)
		(mid 349.331131 -287.009689)
		(end 349.257112 -287.28924)
		(width 0.0889)
		(layer "In6.Cu")
		(net "UPI_CPU0_CPU1_P2P2_DP<7>")
	)
	(arc
		(start 348.787466 -288.103056)
		(mid 348.739787 -288.285956)
		(end 348.608904 -288.422334)
		(width 0.0889)
		(layer "In6.Cu")
		(net "UPI_CPU0_CPU1_P2P2_DP<7>")
	)
	(arc
		(start 349.727266 -284.847538)
		(mid 349.679587 -285.030438)
		(end 349.548704 -285.166816)
		(width 0.0889)
		(layer "In6.Cu")
		(net "UPI_CPU0_CPU1_P2P2_DP<7>")
	)
	(arc
		(start 91.169998 -288.917126)
		(mid 91.17005 -288.909759)
		(end 91.170252 -288.902394)
		(width 0.0889)
		(layer "In6.Cu")
		(net "UPI_CPU0_CPU1_P2P2_DP<7>")
	)
	(arc
		(start 93.989144 -284.033722)
		(mid 94.036823 -283.850822)
		(end 94.167706 -283.714444)
		(width 0.0889)
		(layer "In6.Cu")
		(net "UPI_CPU0_CPU1_P2P2_DP<7>")
	)
	(arc
		(start 92.109798 -287.28924)
		(mid 92.157477 -287.10634)
		(end 92.28836 -286.969962)
		(width 0.0889)
		(layer "In6.Cu")
		(net "UPI_CPU0_CPU1_P2P2_DP<7>")
	)
	(arc
		(start 349.533718 -285.175452)
		(mid 349.331131 -285.381803)
		(end 349.257112 -285.661354)
		(width 0.0889)
		(layer "In6.Cu")
		(net "UPI_CPU0_CPU1_P2P2_DP<7>")
	)
	(arc
		(start 93.519498 -284.847538)
		(mid 93.567177 -284.664638)
		(end 93.69806 -284.52826)
		(width 0.0889)
		(layer "In6.Cu")
		(net "UPI_CPU0_CPU1_P2P2_DP<7>")
	)
	(arc
		(start 350.00946 -284.35808)
		(mid 349.806637 -284.558311)
		(end 349.727266 -284.832044)
		(width 0.0889)
		(layer "In6.Cu")
		(net "UPI_CPU0_CPU1_P2P2_DP<7>")
	)
	(arc
		(start 91.639898 -288.103056)
		(mid 91.687577 -287.920156)
		(end 91.81846 -287.783778)
		(width 0.0889)
		(layer "In6.Cu")
		(net "UPI_CPU0_CPU1_P2P2_DP<7>")
	)
	(arc
		(start 94.176596 -283.709364)
		(mid 94.380931 -283.506759)
		(end 94.459044 -283.229812)
		(width 0.0889)
		(layer "In6.Cu")
		(net "UPI_CPU0_CPU1_P2P2_DP<7>")
	)
	(arc
		(start 90.884248 -289.446462)
		(mid 91.058549 -289.307532)
		(end 91.169998 -289.114484)
		(width 0.0889)
		(layer "In6.Cu")
		(net "UPI_CPU0_CPU1_P2P2_DP<7>")
	)
	(segment
		(start 96.243648 -280.778204)
		(end 96.243648 -280.242264)
		(width 0.13208)
		(layer "F.Cu")
		(net "UPI_CPU0_CPU1_P2P2_DP<6>")
	)
	(segment
		(start 352.171762 -281.05608)
		(end 352.171762 -281.591766)
		(width 0.13208)
		(layer "F.Cu")
		(net "UPI_CPU0_CPU1_P2P2_DP<6>")
	)
	(segment
		(start 352.171762 -281.591766)
		(end 352.172016 -281.59202)
		(width 0.13208)
		(layer "F.Cu")
		(net "UPI_CPU0_CPU1_P2P2_DP<6>")
	)
	(segment
		(start 95.020892 -280.288492)
		(end 95.031306 -280.282396)
		(width 0.0889)
		(layer "In6.Cu")
		(net "UPI_CPU0_CPU1_P2P2_DP<6>")
	)
	(segment
		(start 90.979498 -287.28924)
		(end 90.979498 -287.273746)
		(width 0.0889)
		(layer "In6.Cu")
		(net "UPI_CPU0_CPU1_P2P2_DP<6>")
	)
	(segment
		(start 59.422538 -325.312278)
		(end 60.221114 -324.513702)
		(width 0.14732)
		(layer "In6.Cu")
		(net "UPI_CPU0_CPU1_P2P2_DP<6>")
	)
	(segment
		(start 351.526856 -282.074366)
		(end 351.514664 -282.081478)
		(width 0.0889)
		(layer "In6.Cu")
		(net "UPI_CPU0_CPU1_P2P2_DP<6>")
	)
	(segment
		(start 346.561664 -301.807118)
		(end 342.778334 -305.590194)
		(width 0.14732)
		(layer "In6.Cu")
		(net "UPI_CPU0_CPU1_P2P2_DP<6>")
	)
	(segment
		(start 347.707458 -294.243506)
		(end 347.707458 -294.546274)
		(width 0.14732)
		(layer "In6.Cu")
		(net "UPI_CPU0_CPU1_P2P2_DP<6>")
	)
	(segment
		(start 62.496446 -321.146424)
		(end 62.886336 -320.756534)
		(width 0.14732)
		(layer "In6.Cu")
		(net "UPI_CPU0_CPU1_P2P2_DP<6>")
	)
	(segment
		(start 350.587056 -286.95777)
		(end 350.574864 -286.964882)
		(width 0.0889)
		(layer "In6.Cu")
		(net "UPI_CPU0_CPU1_P2P2_DP<6>")
	)
	(segment
		(start 342.778334 -305.590194)
		(end 338.864448 -307.211476)
		(width 0.14732)
		(layer "In6.Cu")
		(net "UPI_CPU0_CPU1_P2P2_DP<6>")
	)
	(segment
		(start 347.764354 -293.033196)
		(end 347.764354 -293.208456)
		(width 0.0889)
		(layer "In6.Cu")
		(net "UPI_CPU0_CPU1_P2P2_DP<6>")
	)
	(segment
		(start 88.78443 -290.79698)
		(end 88.78443 -290.774882)
		(width 0.0889)
		(layer "In6.Cu")
		(net "UPI_CPU0_CPU1_P2P2_DP<6>")
	)
	(segment
		(start 66.750184 -317.28537)
		(end 66.750184 -316.699646)
		(width 0.14732)
		(layer "In6.Cu")
		(net "UPI_CPU0_CPU1_P2P2_DP<6>")
	)
	(segment
		(start 267.122656 -378.937266)
		(end 161.76117 -387.833108)
		(width 0.14732)
		(layer "In6.Cu")
		(net "UPI_CPU0_CPU1_P2P2_DP<6>")
	)
	(segment
		(start 350.574864 -285.336996)
		(end 350.568006 -285.340806)
		(width 0.0889)
		(layer "In6.Cu")
		(net "UPI_CPU0_CPU1_P2P2_DP<6>")
	)
	(segment
		(start 350.565974 -285.980632)
		(end 350.574102 -285.985204)
		(width 0.0889)
		(layer "In6.Cu")
		(net "UPI_CPU0_CPU1_P2P2_DP<6>")
	)
	(segment
		(start 282.290012 -340.014814)
		(end 275.630132 -346.674694)
		(width 0.14732)
		(layer "In6.Cu")
		(net "UPI_CPU0_CPU1_P2P2_DP<6>")
	)
	(segment
		(start 351.797112 -283.201364)
		(end 351.797112 -283.229812)
		(width 0.0889)
		(layer "In6.Cu")
		(net "UPI_CPU0_CPU1_P2P2_DP<6>")
	)
	(segment
		(start 61.444378 -335.516982)
		(end 61.004958 -333.763112)
		(width 0.14732)
		(layer "In6.Cu")
		(net "UPI_CPU0_CPU1_P2P2_DP<6>")
	)
	(segment
		(start 91.919044 -284.033722)
		(end 91.919044 -284.023816)
		(width 0.0889)
		(layer "In6.Cu")
		(net "UPI_CPU0_CPU1_P2P2_DP<6>")
	)
	(segment
		(start 351.514664 -282.081478)
		(end 351.505774 -282.086558)
		(width 0.0889)
		(layer "In6.Cu")
		(net "UPI_CPU0_CPU1_P2P2_DP<6>")
	)
	(segment
		(start 275.630132 -346.674694)
		(end 275.630132 -370.430044)
		(width 0.14732)
		(layer "In6.Cu")
		(net "UPI_CPU0_CPU1_P2P2_DP<6>")
	)
	(segment
		(start 92.671646 -282.730194)
		(end 92.686378 -282.721558)
		(width 0.0889)
		(layer "In6.Cu")
		(net "UPI_CPU0_CPU1_P2P2_DP<6>")
	)
	(segment
		(start 271.372076 -374.6881)
		(end 271.371568 -374.6881)
		(width 0.14732)
		(layer "In6.Cu")
		(net "UPI_CPU0_CPU1_P2P2_DP<6>")
	)
	(segment
		(start 126.101094 -387.833108)
		(end 95.44939 -383.286254)
		(width 0.14732)
		(layer "In6.Cu")
		(net "UPI_CPU0_CPU1_P2P2_DP<6>")
	)
	(segment
		(start 59.40171 -325.362824)
		(end 59.401456 -325.362824)
		(width 0.14732)
		(layer "In6.Cu")
		(net "UPI_CPU0_CPU1_P2P2_DP<6>")
	)
	(segment
		(start 90.321892 -288.427414)
		(end 90.330782 -288.422334)
		(width 0.0889)
		(layer "In6.Cu")
		(net "UPI_CPU0_CPU1_P2P2_DP<6>")
	)
	(segment
		(start 94.550484 -281.10307)
		(end 94.551246 -281.102562)
		(width 0.0889)
		(layer "In6.Cu")
		(net "UPI_CPU0_CPU1_P2P2_DP<6>")
	)
	(segment
		(start 90.78595 -287.617154)
		(end 90.792046 -287.613598)
		(width 0.0889)
		(layer "In6.Cu")
		(net "UPI_CPU0_CPU1_P2P2_DP<6>")
	)
	(segment
		(start 286.307276 -338.35086)
		(end 282.290012 -340.014814)
		(width 0.14732)
		(layer "In6.Cu")
		(net "UPI_CPU0_CPU1_P2P2_DP<6>")
	)
	(segment
		(start 61.392054 -324.028562)
		(end 61.73343 -323.687186)
		(width 0.14732)
		(layer "In6.Cu")
		(net "UPI_CPU0_CPU1_P2P2_DP<6>")
	)
	(segment
		(start 95.930974 -280.778204)
		(end 96.243648 -280.778204)
		(width 0.0889)
		(layer "In6.Cu")
		(net "UPI_CPU0_CPU1_P2P2_DP<6>")
	)
	(segment
		(start 349.917766 -288.103056)
		(end 349.917766 -288.121598)
		(width 0.0889)
		(layer "In6.Cu")
		(net "UPI_CPU0_CPU1_P2P2_DP<6>")
	)
	(segment
		(start 61.444378 -355.22154)
		(end 61.444378 -335.516982)
		(width 0.14732)
		(layer "In6.Cu")
		(net "UPI_CPU0_CPU1_P2P2_DP<6>")
	)
	(segment
		(start 61.73343 -323.687186)
		(end 62.169548 -322.63461)
		(width 0.14732)
		(layer "In6.Cu")
		(net "UPI_CPU0_CPU1_P2P2_DP<6>")
	)
	(segment
		(start 91.270582 -286.156146)
		(end 91.262708 -286.151574)
		(width 0.0889)
		(layer "In6.Cu")
		(net "UPI_CPU0_CPU1_P2P2_DP<6>")
	)
	(segment
		(start 85.972396 -294.598852)
		(end 85.972142 -294.598852)
		(width 0.14732)
		(layer "In6.Cu")
		(net "UPI_CPU0_CPU1_P2P2_DP<6>")
	)
	(segment
		(start 309.30088 -338.35086)
		(end 286.307276 -338.35086)
		(width 0.14732)
		(layer "In6.Cu")
		(net "UPI_CPU0_CPU1_P2P2_DP<6>")
	)
	(segment
		(start 347.764354 -293.208456)
		(end 347.665294 -293.307516)
		(width 0.0889)
		(layer "In6.Cu")
		(net "UPI_CPU0_CPU1_P2P2_DP<6>")
	)
	(segment
		(start 347.707458 -294.546274)
		(end 347.707204 -294.546528)
		(width 0.14732)
		(layer "In6.Cu")
		(net "UPI_CPU0_CPU1_P2P2_DP<6>")
	)
	(segment
		(start 349.447866 -289.079432)
		(end 349.447612 -289.079178)
		(width 0.0889)
		(layer "In6.Cu")
		(net "UPI_CPU0_CPU1_P2P2_DP<6>")
	)
	(segment
		(start 59.401456 -325.362824)
		(end 59.422538 -325.312278)
		(width 0.14732)
		(layer "In6.Cu")
		(net "UPI_CPU0_CPU1_P2P2_DP<6>")
	)
	(segment
		(start 66.926206 -368.455956)
		(end 61.444378 -355.22154)
		(width 0.14732)
		(layer "In6.Cu")
		(net "UPI_CPU0_CPU1_P2P2_DP<6>")
	)
	(segment
		(start 85.993224 -294.548306)
		(end 88.78443 -291.7571)
		(width 0.14732)
		(layer "In6.Cu")
		(net "UPI_CPU0_CPU1_P2P2_DP<6>")
	)
	(segment
		(start 92.201492 -283.544264)
		(end 92.210382 -283.539184)
		(width 0.0889)
		(layer "In6.Cu")
		(net "UPI_CPU0_CPU1_P2P2_DP<6>")
	)
	(segment
		(start 62.169548 -322.63461)
		(end 62.229238 -322.490338)
		(width 0.14732)
		(layer "In6.Cu")
		(net "UPI_CPU0_CPU1_P2P2_DP<6>")
	)
	(segment
		(start 275.630132 -370.430044)
		(end 271.372076 -374.6881)
		(width 0.14732)
		(layer "In6.Cu")
		(net "UPI_CPU0_CPU1_P2P2_DP<6>")
	)
	(segment
		(start 91.261692 -286.799782)
		(end 91.262708 -286.799274)
		(width 0.0889)
		(layer "In6.Cu")
		(net "UPI_CPU0_CPU1_P2P2_DP<6>")
	)
	(segment
		(start 349.631762 -289.27806)
		(end 349.657162 -289.291522)
		(width 0.0889)
		(layer "In6.Cu")
		(net "UPI_CPU0_CPU1_P2P2_DP<6>")
	)
	(segment
		(start 347.665294 -292.934136)
		(end 347.764354 -293.033196)
		(width 0.0889)
		(layer "In6.Cu")
		(net "UPI_CPU0_CPU1_P2P2_DP<6>")
	)
	(segment
		(start 88.82634 -290.732972)
		(end 88.82634 -290.518088)
		(width 0.0889)
		(layer "In6.Cu")
		(net "UPI_CPU0_CPU1_P2P2_DP<6>")
	)
	(segment
		(start 351.045018 -284.52318)
		(end 351.036128 -284.52826)
		(width 0.0889)
		(layer "In6.Cu")
		(net "UPI_CPU0_CPU1_P2P2_DP<6>")
	)
	(segment
		(start 347.665294 -294.179244)
		(end 347.707458 -294.221408)
		(width 0.0889)
		(layer "In6.Cu")
		(net "UPI_CPU0_CPU1_P2P2_DP<6>")
	)
	(segment
		(start 64.181736 -319.854834)
		(end 66.750184 -317.28537)
		(width 0.14732)
		(layer "In6.Cu")
		(net "UPI_CPU0_CPU1_P2P2_DP<6>")
	)
	(segment
		(start 350.387412 -287.28924)
		(end 350.387412 -287.304734)
		(width 0.0889)
		(layer "In6.Cu")
		(net "UPI_CPU0_CPU1_P2P2_DP<6>")
	)
	(segment
		(start 91.262708 -286.799274)
		(end 91.270582 -286.794702)
		(width 0.0889)
		(layer "In6.Cu")
		(net "UPI_CPU0_CPU1_P2P2_DP<6>")
	)
	(segment
		(start 349.917512 -289.551872)
		(end 349.917512 -290.308284)
		(width 0.0889)
		(layer "In6.Cu")
		(net "UPI_CPU0_CPU1_P2P2_DP<6>")
	)
	(segment
		(start 351.505774 -282.725114)
		(end 351.514664 -282.730194)
		(width 0.0889)
		(layer "In6.Cu")
		(net "UPI_CPU0_CPU1_P2P2_DP<6>")
	)
	(segment
		(start 349.635318 -288.592768)
		(end 349.626428 -288.597848)
		(width 0.0889)
		(layer "In6.Cu")
		(net "UPI_CPU0_CPU1_P2P2_DP<6>")
	)
	(segment
		(start 352.015552 -281.321002)
		(end 351.93732 -281.300174)
		(width 0.0889)
		(layer "In6.Cu")
		(net "UPI_CPU0_CPU1_P2P2_DP<6>")
	)
	(segment
		(start 349.657162 -289.291522)
		(end 349.917512 -289.551872)
		(width 0.0889)
		(layer "In6.Cu")
		(net "UPI_CPU0_CPU1_P2P2_DP<6>")
	)
	(segment
		(start 62.229238 -322.490338)
		(end 62.496446 -321.146424)
		(width 0.14732)
		(layer "In6.Cu")
		(net "UPI_CPU0_CPU1_P2P2_DP<6>")
	)
	(segment
		(start 59.21248 -325.819262)
		(end 59.40171 -325.362824)
		(width 0.14732)
		(layer "In6.Cu")
		(net "UPI_CPU0_CPU1_P2P2_DP<6>")
	)
	(segment
		(start 352.172016 -281.59202)
		(end 352.015552 -281.321002)
		(width 0.0889)
		(layer "In6.Cu")
		(net "UPI_CPU0_CPU1_P2P2_DP<6>")
	)
	(segment
		(start 92.388944 -283.219906)
		(end 92.388944 -283.205682)
		(width 0.0889)
		(layer "In6.Cu")
		(net "UPI_CPU0_CPU1_P2P2_DP<6>")
	)
	(segment
		(start 350.58096 -285.33344)
		(end 350.575626 -285.336488)
		(width 0.0889)
		(layer "In6.Cu")
		(net "UPI_CPU0_CPU1_P2P2_DP<6>")
	)
	(segment
		(start 318.39789 -329.25385)
		(end 309.30088 -338.35086)
		(width 0.14732)
		(layer "In6.Cu")
		(net "UPI_CPU0_CPU1_P2P2_DP<6>")
	)
	(segment
		(start 95.865442 -280.712672)
		(end 95.930974 -280.778204)
		(width 0.0889)
		(layer "In6.Cu")
		(net "UPI_CPU0_CPU1_P2P2_DP<6>")
	)
	(segment
		(start 90.039444 -289.304984)
		(end 90.039444 -288.902902)
		(width 0.0889)
		(layer "In6.Cu")
		(net "UPI_CPU0_CPU1_P2P2_DP<6>")
	)
	(segment
		(start 350.105218 -287.778698)
		(end 350.096328 -287.783778)
		(width 0.0889)
		(layer "In6.Cu")
		(net "UPI_CPU0_CPU1_P2P2_DP<6>")
	)
	(segment
		(start 60.221114 -324.513702)
		(end 61.392054 -324.028562)
		(width 0.14732)
		(layer "In6.Cu")
		(net "UPI_CPU0_CPU1_P2P2_DP<6>")
	)
	(segment
		(start 347.707458 -294.221408)
		(end 347.707458 -294.243506)
		(width 0.0889)
		(layer "In6.Cu")
		(net "UPI_CPU0_CPU1_P2P2_DP<6>")
	)
	(segment
		(start 350.574102 -285.985204)
		(end 350.574864 -285.985712)
		(width 0.0889)
		(layer "In6.Cu")
		(net "UPI_CPU0_CPU1_P2P2_DP<6>")
	)
	(segment
		(start 63.998856 -320.295778)
		(end 64.181736 -319.854834)
		(width 0.14732)
		(layer "In6.Cu")
		(net "UPI_CPU0_CPU1_P2P2_DP<6>")
	)
	(segment
		(start 347.665294 -293.307516)
		(end 347.665294 -294.179244)
		(width 0.0889)
		(layer "In6.Cu")
		(net "UPI_CPU0_CPU1_P2P2_DP<6>")
	)
	(segment
		(start 319.512188 -326.563736)
		(end 318.39789 -329.25385)
		(width 0.14732)
		(layer "In6.Cu")
		(net "UPI_CPU0_CPU1_P2P2_DP<6>")
	)
	(segment
		(start 347.707204 -294.546528)
		(end 347.707204 -299.041058)
		(width 0.14732)
		(layer "In6.Cu")
		(net "UPI_CPU0_CPU1_P2P2_DP<6>")
	)
	(segment
		(start 90.792046 -287.613598)
		(end 90.800936 -287.608518)
		(width 0.0889)
		(layer "In6.Cu")
		(net "UPI_CPU0_CPU1_P2P2_DP<6>")
	)
	(segment
		(start 66.750184 -316.699646)
		(end 83.939634 -299.506894)
		(width 0.14732)
		(layer "In6.Cu")
		(net "UPI_CPU0_CPU1_P2P2_DP<6>")
	)
	(segment
		(start 83.939634 -299.506894)
		(end 85.972396 -294.598852)
		(width 0.14732)
		(layer "In6.Cu")
		(net "UPI_CPU0_CPU1_P2P2_DP<6>")
	)
	(segment
		(start 271.371568 -374.6881)
		(end 267.122656 -378.937266)
		(width 0.14732)
		(layer "In6.Cu")
		(net "UPI_CPU0_CPU1_P2P2_DP<6>")
	)
	(segment
		(start 93.798898 -282.405836)
		(end 93.798898 -282.390342)
		(width 0.0889)
		(layer "In6.Cu")
		(net "UPI_CPU0_CPU1_P2P2_DP<6>")
	)
	(segment
		(start 338.864448 -307.211476)
		(end 319.512188 -326.563736)
		(width 0.14732)
		(layer "In6.Cu")
		(net "UPI_CPU0_CPU1_P2P2_DP<6>")
	)
	(segment
		(start 349.447866 -288.917126)
		(end 349.447866 -289.079432)
		(width 0.0889)
		(layer "In6.Cu")
		(net "UPI_CPU0_CPU1_P2P2_DP<6>")
	)
	(segment
		(start 347.707204 -299.041058)
		(end 346.561664 -301.807118)
		(width 0.14732)
		(layer "In6.Cu")
		(net "UPI_CPU0_CPU1_P2P2_DP<6>")
	)
	(segment
		(start 94.54515 -281.106118)
		(end 94.550484 -281.10307)
		(width 0.0889)
		(layer "In6.Cu")
		(net "UPI_CPU0_CPU1_P2P2_DP<6>")
	)
	(segment
		(start 94.738444 -280.78684)
		(end 94.738444 -280.759662)
		(width 0.0889)
		(layer "In6.Cu")
		(net "UPI_CPU0_CPU1_P2P2_DP<6>")
	)
	(segment
		(start 62.886336 -320.756534)
		(end 63.998856 -320.295778)
		(width 0.14732)
		(layer "In6.Cu")
		(net "UPI_CPU0_CPU1_P2P2_DP<6>")
	)
	(segment
		(start 61.004958 -333.763112)
		(end 59.21248 -329.116436)
		(width 0.14732)
		(layer "In6.Cu")
		(net "UPI_CPU0_CPU1_P2P2_DP<6>")
	)
	(segment
		(start 351.327212 -284.033722)
		(end 351.327212 -284.049216)
		(width 0.0889)
		(layer "In6.Cu")
		(net "UPI_CPU0_CPU1_P2P2_DP<6>")
	)
	(segment
		(start 349.917512 -290.308284)
		(end 347.665294 -292.560502)
		(width 0.0889)
		(layer "In6.Cu")
		(net "UPI_CPU0_CPU1_P2P2_DP<6>")
	)
	(segment
		(start 88.78443 -290.774882)
		(end 88.82634 -290.732972)
		(width 0.0889)
		(layer "In6.Cu")
		(net "UPI_CPU0_CPU1_P2P2_DP<6>")
	)
	(segment
		(start 350.574864 -286.964882)
		(end 350.565974 -286.969962)
		(width 0.0889)
		(layer "In6.Cu")
		(net "UPI_CPU0_CPU1_P2P2_DP<6>")
	)
	(segment
		(start 93.611446 -282.730194)
		(end 93.620336 -282.725114)
		(width 0.0889)
		(layer "In6.Cu")
		(net "UPI_CPU0_CPU1_P2P2_DP<6>")
	)
	(segment
		(start 91.262708 -286.151574)
		(end 91.261692 -286.151066)
		(width 0.0889)
		(layer "In6.Cu")
		(net "UPI_CPU0_CPU1_P2P2_DP<6>")
	)
	(segment
		(start 95.44939 -383.286254)
		(end 72.074532 -373.604282)
		(width 0.14732)
		(layer "In6.Cu")
		(net "UPI_CPU0_CPU1_P2P2_DP<6>")
	)
	(segment
		(start 94.081092 -281.916378)
		(end 94.089982 -281.911298)
		(width 0.0889)
		(layer "In6.Cu")
		(net "UPI_CPU0_CPU1_P2P2_DP<6>")
	)
	(segment
		(start 88.82634 -290.518088)
		(end 90.039444 -289.304984)
		(width 0.0889)
		(layer "In6.Cu")
		(net "UPI_CPU0_CPU1_P2P2_DP<6>")
	)
	(segment
		(start 85.972142 -294.598852)
		(end 85.993224 -294.548306)
		(width 0.14732)
		(layer "In6.Cu")
		(net "UPI_CPU0_CPU1_P2P2_DP<6>")
	)
	(segment
		(start 72.074532 -373.604282)
		(end 66.926206 -368.455956)
		(width 0.14732)
		(layer "In6.Cu")
		(net "UPI_CPU0_CPU1_P2P2_DP<6>")
	)
	(segment
		(start 91.731592 -284.35808)
		(end 91.740482 -284.353)
		(width 0.0889)
		(layer "In6.Cu")
		(net "UPI_CPU0_CPU1_P2P2_DP<6>")
	)
	(segment
		(start 91.261692 -285.171896)
		(end 91.270582 -285.166816)
		(width 0.0889)
		(layer "In6.Cu")
		(net "UPI_CPU0_CPU1_P2P2_DP<6>")
	)
	(segment
		(start 90.979498 -285.683452)
		(end 90.979498 -285.64586)
		(width 0.0889)
		(layer "In6.Cu")
		(net "UPI_CPU0_CPU1_P2P2_DP<6>")
	)
	(segment
		(start 350.575626 -285.336488)
		(end 350.574864 -285.336996)
		(width 0.0889)
		(layer "In6.Cu")
		(net "UPI_CPU0_CPU1_P2P2_DP<6>")
	)
	(segment
		(start 350.857566 -286.467804)
		(end 350.857566 -286.475424)
		(width 0.0889)
		(layer "In6.Cu")
		(net "UPI_CPU0_CPU1_P2P2_DP<6>")
	)
	(segment
		(start 161.76117 -387.833108)
		(end 126.101094 -387.833108)
		(width 0.14732)
		(layer "In6.Cu")
		(net "UPI_CPU0_CPU1_P2P2_DP<6>")
	)
	(segment
		(start 347.665294 -292.560502)
		(end 347.665294 -292.934136)
		(width 0.0889)
		(layer "In6.Cu")
		(net "UPI_CPU0_CPU1_P2P2_DP<6>")
	)
	(segment
		(start 91.449144 -284.847538)
		(end 91.449144 -284.837632)
		(width 0.0889)
		(layer "In6.Cu")
		(net "UPI_CPU0_CPU1_P2P2_DP<6>")
	)
	(segment
		(start 351.514664 -283.709364)
		(end 351.505774 -283.714444)
		(width 0.0889)
		(layer "In6.Cu")
		(net "UPI_CPU0_CPU1_P2P2_DP<6>")
	)
	(segment
		(start 350.568006 -285.340806)
		(end 350.565974 -285.342076)
		(width 0.0889)
		(layer "In6.Cu")
		(net "UPI_CPU0_CPU1_P2P2_DP<6>")
	)
	(segment
		(start 88.78443 -291.7571)
		(end 88.78443 -290.79698)
		(width 0.14732)
		(layer "In6.Cu")
		(net "UPI_CPU0_CPU1_P2P2_DP<6>")
	)
	(segment
		(start 59.21248 -329.116436)
		(end 59.21248 -325.819262)
		(width 0.14732)
		(layer "In6.Cu")
		(net "UPI_CPU0_CPU1_P2P2_DP<6>")
	)
	(arc
		(start 90.800936 -287.608518)
		(mid 90.93185 -287.472158)
		(end 90.979498 -287.28924)
		(width 0.0889)
		(layer "In6.Cu")
		(net "UPI_CPU0_CPU1_P2P2_DP<6>")
	)
	(arc
		(start 92.210382 -283.539184)
		(mid 92.341296 -283.402824)
		(end 92.388944 -283.219906)
		(width 0.0889)
		(layer "In6.Cu")
		(net "UPI_CPU0_CPU1_P2P2_DP<6>")
	)
	(arc
		(start 94.089982 -281.911298)
		(mid 94.220896 -281.774938)
		(end 94.268544 -281.59202)
		(width 0.0889)
		(layer "In6.Cu")
		(net "UPI_CPU0_CPU1_P2P2_DP<6>")
	)
	(arc
		(start 349.626428 -288.597848)
		(mid 349.495514 -288.734208)
		(end 349.447866 -288.917126)
		(width 0.0889)
		(layer "In6.Cu")
		(net "UPI_CPU0_CPU1_P2P2_DP<6>")
	)
	(arc
		(start 351.327466 -282.418028)
		(mid 351.377959 -282.594006)
		(end 351.505774 -282.725114)
		(width 0.0889)
		(layer "In6.Cu")
		(net "UPI_CPU0_CPU1_P2P2_DP<6>")
	)
	(arc
		(start 350.574864 -285.985712)
		(mid 350.779936 -286.189391)
		(end 350.857566 -286.467804)
		(width 0.0889)
		(layer "In6.Cu")
		(net "UPI_CPU0_CPU1_P2P2_DP<6>")
	)
	(arc
		(start 350.096328 -287.783778)
		(mid 349.965414 -287.920138)
		(end 349.917766 -288.103056)
		(width 0.0889)
		(layer "In6.Cu")
		(net "UPI_CPU0_CPU1_P2P2_DP<6>")
	)
	(arc
		(start 91.261692 -286.151066)
		(mid 91.06041 -285.953579)
		(end 90.979498 -285.683452)
		(width 0.0889)
		(layer "In6.Cu")
		(net "UPI_CPU0_CPU1_P2P2_DP<6>")
	)
	(arc
		(start 349.917766 -288.121598)
		(mid 349.837604 -288.393787)
		(end 349.635318 -288.592768)
		(width 0.0889)
		(layer "In6.Cu")
		(net "UPI_CPU0_CPU1_P2P2_DP<6>")
	)
	(arc
		(start 90.979498 -285.64586)
		(mid 91.058868 -285.372126)
		(end 91.261692 -285.171896)
		(width 0.0889)
		(layer "In6.Cu")
		(net "UPI_CPU0_CPU1_P2P2_DP<6>")
	)
	(arc
		(start 90.509344 -288.103056)
		(mid 90.583335 -287.82349)
		(end 90.78595 -287.617154)
		(width 0.0889)
		(layer "In6.Cu")
		(net "UPI_CPU0_CPU1_P2P2_DP<6>")
	)
	(arc
		(start 95.862648 -280.69159)
		(mid 95.864144 -280.702118)
		(end 95.865442 -280.712672)
		(width 0.0889)
		(layer "In6.Cu")
		(net "UPI_CPU0_CPU1_P2P2_DP<6>")
	)
	(arc
		(start 95.031306 -280.282396)
		(mid 95.309738 -280.212582)
		(end 95.58655 -280.288492)
		(width 0.0889)
		(layer "In6.Cu")
		(net "UPI_CPU0_CPU1_P2P2_DP<6>")
	)
	(arc
		(start 91.270582 -286.794702)
		(mid 91.449179 -286.475424)
		(end 91.270582 -286.156146)
		(width 0.0889)
		(layer "In6.Cu")
		(net "UPI_CPU0_CPU1_P2P2_DP<6>")
	)
	(arc
		(start 95.58655 -280.288492)
		(mid 95.770374 -280.458686)
		(end 95.862648 -280.69159)
		(width 0.0889)
		(layer "In6.Cu")
		(net "UPI_CPU0_CPU1_P2P2_DP<6>")
	)
	(arc
		(start 91.740482 -284.353)
		(mid 91.871396 -284.21664)
		(end 91.919044 -284.033722)
		(width 0.0889)
		(layer "In6.Cu")
		(net "UPI_CPU0_CPU1_P2P2_DP<6>")
	)
	(arc
		(start 351.797112 -283.229812)
		(mid 351.719001 -283.506761)
		(end 351.514664 -283.709364)
		(width 0.0889)
		(layer "In6.Cu")
		(net "UPI_CPU0_CPU1_P2P2_DP<6>")
	)
	(arc
		(start 90.039444 -288.902902)
		(mid 90.118585 -288.628279)
		(end 90.321892 -288.427414)
		(width 0.0889)
		(layer "In6.Cu")
		(net "UPI_CPU0_CPU1_P2P2_DP<6>")
	)
	(arc
		(start 350.565974 -285.342076)
		(mid 350.387377 -285.661354)
		(end 350.565974 -285.980632)
		(width 0.0889)
		(layer "In6.Cu")
		(net "UPI_CPU0_CPU1_P2P2_DP<6>")
	)
	(arc
		(start 350.387412 -287.304734)
		(mid 350.308042 -287.578468)
		(end 350.105218 -287.778698)
		(width 0.0889)
		(layer "In6.Cu")
		(net "UPI_CPU0_CPU1_P2P2_DP<6>")
	)
	(arc
		(start 91.919044 -284.023816)
		(mid 91.997155 -283.746867)
		(end 92.201492 -283.544264)
		(width 0.0889)
		(layer "In6.Cu")
		(net "UPI_CPU0_CPU1_P2P2_DP<6>")
	)
	(arc
		(start 92.686378 -282.721558)
		(mid 92.962819 -282.654392)
		(end 93.23705 -282.730194)
		(width 0.0889)
		(layer "In6.Cu")
		(net "UPI_CPU0_CPU1_P2P2_DP<6>")
	)
	(arc
		(start 351.505774 -282.086558)
		(mid 351.376485 -282.220044)
		(end 351.327212 -282.399232)
		(width 0.0889)
		(layer "In6.Cu")
		(net "UPI_CPU0_CPU1_P2P2_DP<6>")
	)
	(arc
		(start 93.798898 -282.390342)
		(mid 93.878268 -282.116608)
		(end 94.081092 -281.916378)
		(width 0.0889)
		(layer "In6.Cu")
		(net "UPI_CPU0_CPU1_P2P2_DP<6>")
	)
	(arc
		(start 350.857566 -284.847538)
		(mid 350.783575 -285.127104)
		(end 350.58096 -285.33344)
		(width 0.0889)
		(layer "In6.Cu")
		(net "UPI_CPU0_CPU1_P2P2_DP<6>")
	)
	(arc
		(start 94.738444 -280.759662)
		(mid 94.818606 -280.487473)
		(end 95.020892 -280.288492)
		(width 0.0889)
		(layer "In6.Cu")
		(net "UPI_CPU0_CPU1_P2P2_DP<6>")
	)
	(arc
		(start 351.514664 -282.730194)
		(mid 351.71695 -282.929175)
		(end 351.797112 -283.201364)
		(width 0.0889)
		(layer "In6.Cu")
		(net "UPI_CPU0_CPU1_P2P2_DP<6>")
	)
	(arc
		(start 350.857566 -286.475424)
		(mid 350.785331 -286.751948)
		(end 350.587056 -286.95777)
		(width 0.0889)
		(layer "In6.Cu")
		(net "UPI_CPU0_CPU1_P2P2_DP<6>")
	)
	(arc
		(start 91.449144 -284.837632)
		(mid 91.527255 -284.560683)
		(end 91.731592 -284.35808)
		(width 0.0889)
		(layer "In6.Cu")
		(net "UPI_CPU0_CPU1_P2P2_DP<6>")
	)
	(arc
		(start 351.327212 -282.399232)
		(mid 351.327222 -282.408632)
		(end 351.327466 -282.418028)
		(width 0.0889)
		(layer "In6.Cu")
		(net "UPI_CPU0_CPU1_P2P2_DP<6>")
	)
	(arc
		(start 351.036128 -284.52826)
		(mid 350.905214 -284.66462)
		(end 350.857566 -284.847538)
		(width 0.0889)
		(layer "In6.Cu")
		(net "UPI_CPU0_CPU1_P2P2_DP<6>")
	)
	(arc
		(start 93.620336 -282.725114)
		(mid 93.75125 -282.588754)
		(end 93.798898 -282.405836)
		(width 0.0889)
		(layer "In6.Cu")
		(net "UPI_CPU0_CPU1_P2P2_DP<6>")
	)
	(arc
		(start 350.565974 -286.969962)
		(mid 350.43506 -287.106322)
		(end 350.387412 -287.28924)
		(width 0.0889)
		(layer "In6.Cu")
		(net "UPI_CPU0_CPU1_P2P2_DP<6>")
	)
	(arc
		(start 90.979498 -287.273746)
		(mid 91.058868 -287.000012)
		(end 91.261692 -286.799782)
		(width 0.0889)
		(layer "In6.Cu")
		(net "UPI_CPU0_CPU1_P2P2_DP<6>")
	)
	(arc
		(start 349.447612 -289.079178)
		(mid 349.522719 -289.194324)
		(end 349.631762 -289.27806)
		(width 0.0889)
		(layer "In6.Cu")
		(net "UPI_CPU0_CPU1_P2P2_DP<6>")
	)
	(arc
		(start 351.327212 -284.049216)
		(mid 351.247842 -284.32295)
		(end 351.045018 -284.52318)
		(width 0.0889)
		(layer "In6.Cu")
		(net "UPI_CPU0_CPU1_P2P2_DP<6>")
	)
	(arc
		(start 94.551246 -281.102562)
		(mid 94.686179 -280.969208)
		(end 94.738444 -280.78684)
		(width 0.0889)
		(layer "In6.Cu")
		(net "UPI_CPU0_CPU1_P2P2_DP<6>")
	)
	(arc
		(start 92.388944 -283.205682)
		(mid 92.468163 -282.930997)
		(end 92.671646 -282.730194)
		(width 0.0889)
		(layer "In6.Cu")
		(net "UPI_CPU0_CPU1_P2P2_DP<6>")
	)
	(arc
		(start 90.50909 -288.117788)
		(mid 90.509287 -288.110423)
		(end 90.509344 -288.103056)
		(width 0.0889)
		(layer "In6.Cu")
		(net "UPI_CPU0_CPU1_P2P2_DP<6>")
	)
	(arc
		(start 351.93732 -281.300174)
		(mid 351.834175 -281.430199)
		(end 351.797366 -281.59202)
		(width 0.0889)
		(layer "In6.Cu")
		(net "UPI_CPU0_CPU1_P2P2_DP<6>")
	)
	(arc
		(start 91.270582 -285.166816)
		(mid 91.401496 -285.030456)
		(end 91.449144 -284.847538)
		(width 0.0889)
		(layer "In6.Cu")
		(net "UPI_CPU0_CPU1_P2P2_DP<6>")
	)
	(arc
		(start 94.268544 -281.59202)
		(mid 94.342535 -281.312454)
		(end 94.54515 -281.106118)
		(width 0.0889)
		(layer "In6.Cu")
		(net "UPI_CPU0_CPU1_P2P2_DP<6>")
	)
	(arc
		(start 93.23705 -282.730194)
		(mid 93.424248 -282.780337)
		(end 93.611446 -282.730194)
		(width 0.0889)
		(layer "In6.Cu")
		(net "UPI_CPU0_CPU1_P2P2_DP<6>")
	)
	(arc
		(start 90.330782 -288.422334)
		(mid 90.458036 -288.292368)
		(end 90.50909 -288.117788)
		(width 0.0889)
		(layer "In6.Cu")
		(net "UPI_CPU0_CPU1_P2P2_DP<6>")
	)
	(arc
		(start 351.505774 -283.714444)
		(mid 351.37486 -283.850804)
		(end 351.327212 -284.033722)
		(width 0.0889)
		(layer "In6.Cu")
		(net "UPI_CPU0_CPU1_P2P2_DP<6>")
	)
	(arc
		(start 351.797366 -281.59202)
		(mid 351.725131 -281.868544)
		(end 351.526856 -282.074366)
		(width 0.0889)
		(layer "In6.Cu")
		(net "UPI_CPU0_CPU1_P2P2_DP<6>")
	)
	(segment
		(start 351.702116 -282.405582)
		(end 351.701862 -282.405836)
		(width 0.13208)
		(layer "F.Cu")
		(net "UPI_CPU0_CPU1_P2P2_DP<5>")
	)
	(segment
		(start 351.702116 -281.869896)
		(end 351.702116 -282.405582)
		(width 0.13208)
		(layer "F.Cu")
		(net "UPI_CPU0_CPU1_P2P2_DP<5>")
	)
	(segment
		(start 89.194894 -281.05608)
		(end 89.194894 -281.591766)
		(width 0.13208)
		(layer "F.Cu")
		(net "UPI_CPU0_CPU1_P2P2_DP<5>")
	)
	(segment
		(start 89.194894 -281.591766)
		(end 89.195148 -281.59202)
		(width 0.13208)
		(layer "F.Cu")
		(net "UPI_CPU0_CPU1_P2P2_DP<5>")
	)
	(segment
		(start 267.500608 -379.778514)
		(end 162.19805 -388.66953)
		(width 0.14732)
		(layer "In6.Cu")
		(net "UPI_CPU0_CPU1_P2P2_DP<5>")
	)
	(segment
		(start 65.268348 -315.64199)
		(end 67.291204 -314.804044)
		(width 0.14732)
		(layer "In6.Cu")
		(net "UPI_CPU0_CPU1_P2P2_DP<5>")
	)
	(segment
		(start 353.206812 -282.390342)
		(end 353.206812 -282.427934)
		(width 0.0889)
		(layer "In6.Cu")
		(net "UPI_CPU0_CPU1_P2P2_DP<5>")
	)
	(segment
		(start 162.19805 -388.66953)
		(end 126.063248 -388.66953)
		(width 0.14732)
		(layer "In6.Cu")
		(net "UPI_CPU0_CPU1_P2P2_DP<5>")
	)
	(segment
		(start 319.084706 -329.78725)
		(end 309.637176 -339.23478)
		(width 0.14732)
		(layer "In6.Cu")
		(net "UPI_CPU0_CPU1_P2P2_DP<5>")
	)
	(segment
		(start 351.517458 -286.963358)
		(end 351.514664 -286.964882)
		(width 0.0889)
		(layer "In6.Cu")
		(net "UPI_CPU0_CPU1_P2P2_DP<5>")
	)
	(segment
		(start 352.454464 -283.709364)
		(end 352.445574 -283.714444)
		(width 0.0889)
		(layer "In6.Cu")
		(net "UPI_CPU0_CPU1_P2P2_DP<5>")
	)
	(segment
		(start 95.174308 -384.08737)
		(end 71.274432 -374.188228)
		(width 0.14732)
		(layer "In6.Cu")
		(net "UPI_CPU0_CPU1_P2P2_DP<5>")
	)
	(segment
		(start 61.2775 -320.335656)
		(end 61.851032 -318.950594)
		(width 0.14732)
		(layer "In6.Cu")
		(net "UPI_CPU0_CPU1_P2P2_DP<5>")
	)
	(segment
		(start 351.517458 -285.335472)
		(end 351.515934 -285.336234)
		(width 0.0889)
		(layer "In6.Cu")
		(net "UPI_CPU0_CPU1_P2P2_DP<5>")
	)
	(segment
		(start 88.519762 -289.570414)
		(end 88.699594 -289.390582)
		(width 0.0889)
		(layer "In6.Cu")
		(net "UPI_CPU0_CPU1_P2P2_DP<5>")
	)
	(segment
		(start 351.52076 -285.33344)
		(end 351.517458 -285.335472)
		(width 0.0889)
		(layer "In6.Cu")
		(net "UPI_CPU0_CPU1_P2P2_DP<5>")
	)
	(segment
		(start 351.984818 -284.52318)
		(end 351.975928 -284.52826)
		(width 0.0889)
		(layer "In6.Cu")
		(net "UPI_CPU0_CPU1_P2P2_DP<5>")
	)
	(segment
		(start 61.880496 -318.906652)
		(end 63.52667 -317.260478)
		(width 0.14732)
		(layer "In6.Cu")
		(net "UPI_CPU0_CPU1_P2P2_DP<5>")
	)
	(segment
		(start 90.791792 -284.35808)
		(end 90.800682 -284.353)
		(width 0.0889)
		(layer "In6.Cu")
		(net "UPI_CPU0_CPU1_P2P2_DP<5>")
	)
	(segment
		(start 348.563184 -297.763946)
		(end 348.563184 -299.22724)
		(width 0.14732)
		(layer "In6.Cu")
		(net "UPI_CPU0_CPU1_P2P2_DP<5>")
	)
	(segment
		(start 66.331592 -369.245388)
		(end 60.6044 -355.417882)
		(width 0.14732)
		(layer "In6.Cu")
		(net "UPI_CPU0_CPU1_P2P2_DP<5>")
	)
	(segment
		(start 351.797366 -286.4612)
		(end 351.797366 -286.475424)
		(width 0.0889)
		(layer "In6.Cu")
		(net "UPI_CPU0_CPU1_P2P2_DP<5>")
	)
	(segment
		(start 352.353118 -281.919934)
		(end 352.358452 -281.916886)
		(width 0.0889)
		(layer "In6.Cu")
		(net "UPI_CPU0_CPU1_P2P2_DP<5>")
	)
	(segment
		(start 88.836246 -289.390582)
		(end 89.099644 -289.127184)
		(width 0.0889)
		(layer "In6.Cu")
		(net "UPI_CPU0_CPU1_P2P2_DP<5>")
	)
	(segment
		(start 348.52102 -292.704012)
		(end 348.52102 -297.699684)
		(width 0.0889)
		(layer "In6.Cu")
		(net "UPI_CPU0_CPU1_P2P2_DP<5>")
	)
	(segment
		(start 90.039698 -282.427934)
		(end 90.039698 -282.405836)
		(width 0.0889)
		(layer "In6.Cu")
		(net "UPI_CPU0_CPU1_P2P2_DP<5>")
	)
	(segment
		(start 89.42959 -281.300174)
		(end 89.351612 -281.321002)
		(width 0.0889)
		(layer "In6.Cu")
		(net "UPI_CPU0_CPU1_P2P2_DP<5>")
	)
	(segment
		(start 88.055196 -290.171632)
		(end 88.519762 -289.707066)
		(width 0.0889)
		(layer "In6.Cu")
		(net "UPI_CPU0_CPU1_P2P2_DP<5>")
	)
	(segment
		(start 352.924618 -282.895548)
		(end 352.915728 -282.900628)
		(width 0.0889)
		(layer "In6.Cu")
		(net "UPI_CPU0_CPU1_P2P2_DP<5>")
	)
	(segment
		(start 60.851288 -322.496688)
		(end 61.2775 -321.469004)
		(width 0.14732)
		(layer "In6.Cu")
		(net "UPI_CPU0_CPU1_P2P2_DP<5>")
	)
	(segment
		(start 85.314536 -294.014398)
		(end 87.422482 -291.906452)
		(width 0.14732)
		(layer "In6.Cu")
		(net "UPI_CPU0_CPU1_P2P2_DP<5>")
	)
	(segment
		(start 309.637176 -339.23478)
		(end 286.367474 -339.23478)
		(width 0.14732)
		(layer "In6.Cu")
		(net "UPI_CPU0_CPU1_P2P2_DP<5>")
	)
	(segment
		(start 351.327212 -287.28924)
		(end 351.327212 -287.304734)
		(width 0.0889)
		(layer "In6.Cu")
		(net "UPI_CPU0_CPU1_P2P2_DP<5>")
	)
	(segment
		(start 286.367474 -339.23478)
		(end 282.748482 -340.733634)
		(width 0.14732)
		(layer "In6.Cu")
		(net "UPI_CPU0_CPU1_P2P2_DP<5>")
	)
	(segment
		(start 87.422482 -291.906452)
		(end 87.437976 -291.890958)
		(width 0.0889)
		(layer "In6.Cu")
		(net "UPI_CPU0_CPU1_P2P2_DP<5>")
	)
	(segment
		(start 352.359214 -281.916378)
		(end 352.373946 -281.907742)
		(width 0.0889)
		(layer "In6.Cu")
		(net "UPI_CPU0_CPU1_P2P2_DP<5>")
	)
	(segment
		(start 276.582632 -370.696236)
		(end 267.500608 -379.778514)
		(width 0.14732)
		(layer "In6.Cu")
		(net "UPI_CPU0_CPU1_P2P2_DP<5>")
	)
	(segment
		(start 89.852754 -287.61309)
		(end 89.855294 -287.611566)
		(width 0.0889)
		(layer "In6.Cu")
		(net "UPI_CPU0_CPU1_P2P2_DP<5>")
	)
	(segment
		(start 90.317066 -285.17469)
		(end 90.317828 -285.174182)
		(width 0.0889)
		(layer "In6.Cu")
		(net "UPI_CPU0_CPU1_P2P2_DP<5>")
	)
	(segment
		(start 351.515934 -285.336234)
		(end 351.514664 -285.336996)
		(width 0.0889)
		(layer "In6.Cu")
		(net "UPI_CPU0_CPU1_P2P2_DP<5>")
	)
	(segment
		(start 350.387666 -288.917126)
		(end 350.387666 -289.078416)
		(width 0.0889)
		(layer "In6.Cu")
		(net "UPI_CPU0_CPU1_P2P2_DP<5>")
	)
	(segment
		(start 90.315796 -286.803338)
		(end 90.317066 -286.802576)
		(width 0.0889)
		(layer "In6.Cu")
		(net "UPI_CPU0_CPU1_P2P2_DP<5>")
	)
	(segment
		(start 89.099644 -289.127184)
		(end 89.099644 -288.898584)
		(width 0.0889)
		(layer "In6.Cu")
		(net "UPI_CPU0_CPU1_P2P2_DP<5>")
	)
	(segment
		(start 350.857566 -288.103056)
		(end 350.857566 -288.121598)
		(width 0.0889)
		(layer "In6.Cu")
		(net "UPI_CPU0_CPU1_P2P2_DP<5>")
	)
	(segment
		(start 351.514664 -286.964882)
		(end 351.51314 -286.965644)
		(width 0.0889)
		(layer "In6.Cu")
		(net "UPI_CPU0_CPU1_P2P2_DP<5>")
	)
	(segment
		(start 348.563184 -299.22724)
		(end 347.324934 -302.216312)
		(width 0.14732)
		(layer "In6.Cu")
		(net "UPI_CPU0_CPU1_P2P2_DP<5>")
	)
	(segment
		(start 126.063248 -388.66953)
		(end 95.174308 -384.08737)
		(width 0.14732)
		(layer "In6.Cu")
		(net "UPI_CPU0_CPU1_P2P2_DP<5>")
	)
	(segment
		(start 89.569544 -288.103056)
		(end 89.569544 -288.09315)
		(width 0.0889)
		(layer "In6.Cu")
		(net "UPI_CPU0_CPU1_P2P2_DP<5>")
	)
	(segment
		(start 90.317828 -286.802068)
		(end 90.330782 -286.794702)
		(width 0.0889)
		(layer "In6.Cu")
		(net "UPI_CPU0_CPU1_P2P2_DP<5>")
	)
	(segment
		(start 90.322908 -286.151574)
		(end 90.321892 -286.151066)
		(width 0.0889)
		(layer "In6.Cu")
		(net "UPI_CPU0_CPU1_P2P2_DP<5>")
	)
	(segment
		(start 90.509344 -284.847538)
		(end 90.509344 -284.837632)
		(width 0.0889)
		(layer "In6.Cu")
		(net "UPI_CPU0_CPU1_P2P2_DP<5>")
	)
	(segment
		(start 58.34888 -329.767438)
		(end 58.34888 -325.689722)
		(width 0.14732)
		(layer "In6.Cu")
		(net "UPI_CPU0_CPU1_P2P2_DP<5>")
	)
	(segment
		(start 348.563184 -297.741848)
		(end 348.563184 -297.763946)
		(width 0.0889)
		(layer "In6.Cu")
		(net "UPI_CPU0_CPU1_P2P2_DP<5>")
	)
	(segment
		(start 63.52667 -317.260478)
		(end 63.736728 -317.173356)
		(width 0.14732)
		(layer "In6.Cu")
		(net "UPI_CPU0_CPU1_P2P2_DP<5>")
	)
	(segment
		(start 71.274432 -374.188228)
		(end 66.331592 -369.245388)
		(width 0.14732)
		(layer "In6.Cu")
		(net "UPI_CPU0_CPU1_P2P2_DP<5>")
	)
	(segment
		(start 83.35899 -298.736258)
		(end 85.314536 -294.014398)
		(width 0.14732)
		(layer "In6.Cu")
		(net "UPI_CPU0_CPU1_P2P2_DP<5>")
	)
	(segment
		(start 89.855294 -287.611566)
		(end 89.860882 -287.608518)
		(width 0.0889)
		(layer "In6.Cu")
		(net "UPI_CPU0_CPU1_P2P2_DP<5>")
	)
	(segment
		(start 350.857058 -289.610546)
		(end 350.857058 -290.360862)
		(width 0.0889)
		(layer "In6.Cu")
		(net "UPI_CPU0_CPU1_P2P2_DP<5>")
	)
	(segment
		(start 87.496904 -291.890958)
		(end 88.055196 -291.332666)
		(width 0.0889)
		(layer "In6.Cu")
		(net "UPI_CPU0_CPU1_P2P2_DP<5>")
	)
	(segment
		(start 90.317828 -285.174182)
		(end 90.330782 -285.166816)
		(width 0.0889)
		(layer "In6.Cu")
		(net "UPI_CPU0_CPU1_P2P2_DP<5>")
	)
	(segment
		(start 343.188798 -306.352448)
		(end 340.230968 -307.577744)
		(width 0.14732)
		(layer "In6.Cu")
		(net "UPI_CPU0_CPU1_P2P2_DP<5>")
	)
	(segment
		(start 87.958676 -290.522152)
		(end 88.055196 -290.425632)
		(width 0.0889)
		(layer "In6.Cu")
		(net "UPI_CPU0_CPU1_P2P2_DP<5>")
	)
	(segment
		(start 351.045018 -287.778698)
		(end 351.036128 -287.783778)
		(width 0.0889)
		(layer "In6.Cu")
		(net "UPI_CPU0_CPU1_P2P2_DP<5>")
	)
	(segment
		(start 89.391236 -288.422588)
		(end 89.390982 -288.422334)
		(width 0.0889)
		(layer "In6.Cu")
		(net "UPI_CPU0_CPU1_P2P2_DP<5>")
	)
	(segment
		(start 352.466656 -283.702252)
		(end 352.454464 -283.709364)
		(width 0.0889)
		(layer "In6.Cu")
		(net "UPI_CPU0_CPU1_P2P2_DP<5>")
	)
	(segment
		(start 90.330782 -286.156146)
		(end 90.322908 -286.151574)
		(width 0.0889)
		(layer "In6.Cu")
		(net "UPI_CPU0_CPU1_P2P2_DP<5>")
	)
	(segment
		(start 350.571816 -289.277806)
		(end 350.571562 -289.27806)
		(width 0.0889)
		(layer "In6.Cu")
		(net "UPI_CPU0_CPU1_P2P2_DP<5>")
	)
	(segment
		(start 320.231008 -327.01992)
		(end 319.084706 -329.78725)
		(width 0.14732)
		(layer "In6.Cu")
		(net "UPI_CPU0_CPU1_P2P2_DP<5>")
	)
	(segment
		(start 88.055196 -290.425632)
		(end 88.055196 -290.171632)
		(width 0.0889)
		(layer "In6.Cu")
		(net "UPI_CPU0_CPU1_P2P2_DP<5>")
	)
	(segment
		(start 88.699594 -289.390582)
		(end 88.836246 -289.390582)
		(width 0.0889)
		(layer "In6.Cu")
		(net "UPI_CPU0_CPU1_P2P2_DP<5>")
	)
	(segment
		(start 87.958676 -290.776152)
		(end 87.958676 -290.522152)
		(width 0.0889)
		(layer "In6.Cu")
		(net "UPI_CPU0_CPU1_P2P2_DP<5>")
	)
	(segment
		(start 89.569544 -281.59202)
		(end 89.569544 -281.583384)
		(width 0.0889)
		(layer "In6.Cu")
		(net "UPI_CPU0_CPU1_P2P2_DP<5>")
	)
	(segment
		(start 351.505774 -285.980632)
		(end 351.514664 -285.985712)
		(width 0.0889)
		(layer "In6.Cu")
		(net "UPI_CPU0_CPU1_P2P2_DP<5>")
	)
	(segment
		(start 88.519762 -289.707066)
		(end 88.519762 -289.570414)
		(width 0.0889)
		(layer "In6.Cu")
		(net "UPI_CPU0_CPU1_P2P2_DP<5>")
	)
	(segment
		(start 350.654112 -290.57092)
		(end 348.52102 -292.704012)
		(width 0.0889)
		(layer "In6.Cu")
		(net "UPI_CPU0_CPU1_P2P2_DP<5>")
	)
	(segment
		(start 339.278722 -307.972206)
		(end 320.231008 -327.01992)
		(width 0.14732)
		(layer "In6.Cu")
		(net "UPI_CPU0_CPU1_P2P2_DP<5>")
	)
	(segment
		(start 90.509344 -283.229812)
		(end 90.509344 -283.219906)
		(width 0.0889)
		(layer "In6.Cu")
		(net "UPI_CPU0_CPU1_P2P2_DP<5>")
	)
	(segment
		(start 347.324934 -302.216312)
		(end 343.188798 -306.352448)
		(width 0.14732)
		(layer "In6.Cu")
		(net "UPI_CPU0_CPU1_P2P2_DP<5>")
	)
	(segment
		(start 340.230968 -307.577744)
		(end 340.230714 -307.577744)
		(width 0.14732)
		(layer "In6.Cu")
		(net "UPI_CPU0_CPU1_P2P2_DP<5>")
	)
	(segment
		(start 351.514664 -285.336996)
		(end 351.505774 -285.342076)
		(width 0.0889)
		(layer "In6.Cu")
		(net "UPI_CPU0_CPU1_P2P2_DP<5>")
	)
	(segment
		(start 352.267012 -284.033722)
		(end 352.267012 -284.049216)
		(width 0.0889)
		(layer "In6.Cu")
		(net "UPI_CPU0_CPU1_P2P2_DP<5>")
	)
	(segment
		(start 89.382092 -288.427414)
		(end 89.391236 -288.422588)
		(width 0.0889)
		(layer "In6.Cu")
		(net "UPI_CPU0_CPU1_P2P2_DP<5>")
	)
	(segment
		(start 350.571562 -289.27806)
		(end 350.57207 -289.278314)
		(width 0.0889)
		(layer "In6.Cu")
		(net "UPI_CPU0_CPU1_P2P2_DP<5>")
	)
	(segment
		(start 352.358452 -281.916886)
		(end 352.359214 -281.916378)
		(width 0.0889)
		(layer "In6.Cu")
		(net "UPI_CPU0_CPU1_P2P2_DP<5>")
	)
	(segment
		(start 340.230714 -307.577744)
		(end 339.278722 -307.972206)
		(width 0.14732)
		(layer "In6.Cu")
		(net "UPI_CPU0_CPU1_P2P2_DP<5>")
	)
	(segment
		(start 88.055196 -290.872672)
		(end 87.958676 -290.776152)
		(width 0.0889)
		(layer "In6.Cu")
		(net "UPI_CPU0_CPU1_P2P2_DP<5>")
	)
	(segment
		(start 61.851032 -318.950594)
		(end 61.880496 -318.906652)
		(width 0.14732)
		(layer "In6.Cu")
		(net "UPI_CPU0_CPU1_P2P2_DP<5>")
	)
	(segment
		(start 89.851992 -287.613598)
		(end 89.852754 -287.61309)
		(width 0.0889)
		(layer "In6.Cu")
		(net "UPI_CPU0_CPU1_P2P2_DP<5>")
	)
	(segment
		(start 282.748482 -340.733634)
		(end 276.582632 -346.899484)
		(width 0.14732)
		(layer "In6.Cu")
		(net "UPI_CPU0_CPU1_P2P2_DP<5>")
	)
	(segment
		(start 351.51314 -286.965644)
		(end 351.505774 -286.969962)
		(width 0.0889)
		(layer "In6.Cu")
		(net "UPI_CPU0_CPU1_P2P2_DP<5>")
	)
	(segment
		(start 61.2775 -321.469004)
		(end 61.2775 -320.335656)
		(width 0.14732)
		(layer "In6.Cu")
		(net "UPI_CPU0_CPU1_P2P2_DP<5>")
	)
	(segment
		(start 58.34888 -325.689722)
		(end 58.837068 -324.510908)
		(width 0.14732)
		(layer "In6.Cu")
		(net "UPI_CPU0_CPU1_P2P2_DP<5>")
	)
	(segment
		(start 90.317066 -286.802576)
		(end 90.317828 -286.802068)
		(width 0.0889)
		(layer "In6.Cu")
		(net "UPI_CPU0_CPU1_P2P2_DP<5>")
	)
	(segment
		(start 89.85377 -282.08224)
		(end 89.84615 -282.077922)
		(width 0.0889)
		(layer "In6.Cu")
		(net "UPI_CPU0_CPU1_P2P2_DP<5>")
	)
	(segment
		(start 90.315796 -285.175452)
		(end 90.317066 -285.17469)
		(width 0.0889)
		(layer "In6.Cu")
		(net "UPI_CPU0_CPU1_P2P2_DP<5>")
	)
	(segment
		(start 89.861136 -282.086558)
		(end 89.85377 -282.08224)
		(width 0.0889)
		(layer "In6.Cu")
		(net "UPI_CPU0_CPU1_P2P2_DP<5>")
	)
	(segment
		(start 351.701862 -282.405836)
		(end 352.014536 -282.405836)
		(width 0.0889)
		(layer "In6.Cu")
		(net "UPI_CPU0_CPU1_P2P2_DP<5>")
	)
	(segment
		(start 350.857058 -290.360862)
		(end 350.654112 -290.563808)
		(width 0.0889)
		(layer "In6.Cu")
		(net "UPI_CPU0_CPU1_P2P2_DP<5>")
	)
	(segment
		(start 276.582632 -346.899484)
		(end 276.582632 -370.696236)
		(width 0.14732)
		(layer "In6.Cu")
		(net "UPI_CPU0_CPU1_P2P2_DP<5>")
	)
	(segment
		(start 67.291204 -314.804044)
		(end 83.35899 -298.736258)
		(width 0.14732)
		(layer "In6.Cu")
		(net "UPI_CPU0_CPU1_P2P2_DP<5>")
	)
	(segment
		(start 90.800682 -283.714444)
		(end 90.791792 -283.709364)
		(width 0.0889)
		(layer "In6.Cu")
		(net "UPI_CPU0_CPU1_P2P2_DP<5>")
	)
	(segment
		(start 350.575118 -288.592768)
		(end 350.566228 -288.597848)
		(width 0.0889)
		(layer "In6.Cu")
		(net "UPI_CPU0_CPU1_P2P2_DP<5>")
	)
	(segment
		(start 90.330782 -282.900628)
		(end 90.321892 -282.895548)
		(width 0.0889)
		(layer "In6.Cu")
		(net "UPI_CPU0_CPU1_P2P2_DP<5>")
	)
	(segment
		(start 60.6044 -335.613756)
		(end 58.34888 -329.767438)
		(width 0.14732)
		(layer "In6.Cu")
		(net "UPI_CPU0_CPU1_P2P2_DP<5>")
	)
	(segment
		(start 89.351612 -281.321002)
		(end 89.195148 -281.59202)
		(width 0.0889)
		(layer "In6.Cu")
		(net "UPI_CPU0_CPU1_P2P2_DP<5>")
	)
	(segment
		(start 352.014536 -282.405836)
		(end 352.080322 -282.34005)
		(width 0.0889)
		(layer "In6.Cu")
		(net "UPI_CPU0_CPU1_P2P2_DP<5>")
	)
	(segment
		(start 351.52076 -286.961326)
		(end 351.517458 -286.963358)
		(width 0.0889)
		(layer "In6.Cu")
		(net "UPI_CPU0_CPU1_P2P2_DP<5>")
	)
	(segment
		(start 88.055196 -291.332666)
		(end 88.055196 -290.872672)
		(width 0.0889)
		(layer "In6.Cu")
		(net "UPI_CPU0_CPU1_P2P2_DP<5>")
	)
	(segment
		(start 58.837068 -324.510908)
		(end 60.851288 -322.496688)
		(width 0.14732)
		(layer "In6.Cu")
		(net "UPI_CPU0_CPU1_P2P2_DP<5>")
	)
	(segment
		(start 63.736728 -317.173356)
		(end 65.268348 -315.64199)
		(width 0.14732)
		(layer "In6.Cu")
		(net "UPI_CPU0_CPU1_P2P2_DP<5>")
	)
	(segment
		(start 350.654112 -290.563808)
		(end 350.654112 -290.57092)
		(width 0.0889)
		(layer "In6.Cu")
		(net "UPI_CPU0_CPU1_P2P2_DP<5>")
	)
	(segment
		(start 60.6044 -355.417882)
		(end 60.6044 -335.613756)
		(width 0.14732)
		(layer "In6.Cu")
		(net "UPI_CPU0_CPU1_P2P2_DP<5>")
	)
	(segment
		(start 87.437976 -291.890958)
		(end 87.496904 -291.890958)
		(width 0.0889)
		(layer "In6.Cu")
		(net "UPI_CPU0_CPU1_P2P2_DP<5>")
	)
	(segment
		(start 348.52102 -297.699684)
		(end 348.563184 -297.741848)
		(width 0.0889)
		(layer "In6.Cu")
		(net "UPI_CPU0_CPU1_P2P2_DP<5>")
	)
	(arc
		(start 90.50909 -286.485584)
		(mid 90.50917 -286.473136)
		(end 90.508836 -286.460692)
		(width 0.0889)
		(layer "In6.Cu")
		(net "UPI_CPU0_CPU1_P2P2_DP<5>")
	)
	(arc
		(start 352.267012 -284.049216)
		(mid 352.187642 -284.32295)
		(end 351.984818 -284.52318)
		(width 0.0889)
		(layer "In6.Cu")
		(net "UPI_CPU0_CPU1_P2P2_DP<5>")
	)
	(arc
		(start 90.509344 -284.837632)
		(mid 90.587455 -284.560683)
		(end 90.791792 -284.35808)
		(width 0.0889)
		(layer "In6.Cu")
		(net "UPI_CPU0_CPU1_P2P2_DP<5>")
	)
	(arc
		(start 89.099644 -288.898584)
		(mid 89.179806 -288.626395)
		(end 89.382092 -288.427414)
		(width 0.0889)
		(layer "In6.Cu")
		(net "UPI_CPU0_CPU1_P2P2_DP<5>")
	)
	(arc
		(start 351.327212 -287.304734)
		(mid 351.247842 -287.578468)
		(end 351.045018 -287.778698)
		(width 0.0889)
		(layer "In6.Cu")
		(net "UPI_CPU0_CPU1_P2P2_DP<5>")
	)
	(arc
		(start 351.975928 -284.52826)
		(mid 351.845014 -284.66462)
		(end 351.797366 -284.847538)
		(width 0.0889)
		(layer "In6.Cu")
		(net "UPI_CPU0_CPU1_P2P2_DP<5>")
	)
	(arc
		(start 351.327212 -285.65475)
		(mid 351.327124 -285.662751)
		(end 351.327212 -285.670752)
		(width 0.0889)
		(layer "In6.Cu")
		(net "UPI_CPU0_CPU1_P2P2_DP<5>")
	)
	(arc
		(start 90.321892 -282.895548)
		(mid 90.12061 -282.698061)
		(end 90.039698 -282.427934)
		(width 0.0889)
		(layer "In6.Cu")
		(net "UPI_CPU0_CPU1_P2P2_DP<5>")
	)
	(arc
		(start 90.039444 -287.28924)
		(mid 90.11336 -287.009738)
		(end 90.315796 -286.803338)
		(width 0.0889)
		(layer "In6.Cu")
		(net "UPI_CPU0_CPU1_P2P2_DP<5>")
	)
	(arc
		(start 350.566228 -288.597848)
		(mid 350.435314 -288.734208)
		(end 350.387666 -288.917126)
		(width 0.0889)
		(layer "In6.Cu")
		(net "UPI_CPU0_CPU1_P2P2_DP<5>")
	)
	(arc
		(start 350.857566 -288.121598)
		(mid 350.777404 -288.393787)
		(end 350.575118 -288.592768)
		(width 0.0889)
		(layer "In6.Cu")
		(net "UPI_CPU0_CPU1_P2P2_DP<5>")
	)
	(arc
		(start 90.330782 -286.794702)
		(mid 90.459018 -286.6627)
		(end 90.50909 -286.485584)
		(width 0.0889)
		(layer "In6.Cu")
		(net "UPI_CPU0_CPU1_P2P2_DP<5>")
	)
	(arc
		(start 89.860882 -287.608518)
		(mid 89.991796 -287.472158)
		(end 90.039444 -287.28924)
		(width 0.0889)
		(layer "In6.Cu")
		(net "UPI_CPU0_CPU1_P2P2_DP<5>")
	)
	(arc
		(start 352.915728 -282.900628)
		(mid 352.784814 -283.036988)
		(end 352.737166 -283.219906)
		(width 0.0889)
		(layer "In6.Cu")
		(net "UPI_CPU0_CPU1_P2P2_DP<5>")
	)
	(arc
		(start 89.569544 -281.583384)
		(mid 89.53087 -281.426316)
		(end 89.42959 -281.300174)
		(width 0.0889)
		(layer "In6.Cu")
		(net "UPI_CPU0_CPU1_P2P2_DP<5>")
	)
	(arc
		(start 89.390982 -288.422334)
		(mid 89.521896 -288.285974)
		(end 89.569544 -288.103056)
		(width 0.0889)
		(layer "In6.Cu")
		(net "UPI_CPU0_CPU1_P2P2_DP<5>")
	)
	(arc
		(start 90.50909 -283.205174)
		(mid 90.458036 -283.030594)
		(end 90.330782 -282.900628)
		(width 0.0889)
		(layer "In6.Cu")
		(net "UPI_CPU0_CPU1_P2P2_DP<5>")
	)
	(arc
		(start 351.797366 -284.847538)
		(mid 351.723375 -285.127104)
		(end 351.52076 -285.33344)
		(width 0.0889)
		(layer "In6.Cu")
		(net "UPI_CPU0_CPU1_P2P2_DP<5>")
	)
	(arc
		(start 351.505774 -286.969962)
		(mid 351.37486 -287.106322)
		(end 351.327212 -287.28924)
		(width 0.0889)
		(layer "In6.Cu")
		(net "UPI_CPU0_CPU1_P2P2_DP<5>")
	)
	(arc
		(start 352.737166 -283.219906)
		(mid 352.664931 -283.49643)
		(end 352.466656 -283.702252)
		(width 0.0889)
		(layer "In6.Cu")
		(net "UPI_CPU0_CPU1_P2P2_DP<5>")
	)
	(arc
		(start 352.445574 -283.714444)
		(mid 352.31466 -283.850804)
		(end 352.267012 -284.033722)
		(width 0.0889)
		(layer "In6.Cu")
		(net "UPI_CPU0_CPU1_P2P2_DP<5>")
	)
	(arc
		(start 90.791792 -283.709364)
		(mid 90.587457 -283.506759)
		(end 90.509344 -283.229812)
		(width 0.0889)
		(layer "In6.Cu")
		(net "UPI_CPU0_CPU1_P2P2_DP<5>")
	)
	(arc
		(start 353.206812 -282.427934)
		(mid 353.125901 -282.698062)
		(end 352.924618 -282.895548)
		(width 0.0889)
		(layer "In6.Cu")
		(net "UPI_CPU0_CPU1_P2P2_DP<5>")
	)
	(arc
		(start 352.080322 -282.34005)
		(mid 352.081623 -282.329623)
		(end 352.083116 -282.319222)
		(width 0.0889)
		(layer "In6.Cu")
		(net "UPI_CPU0_CPU1_P2P2_DP<5>")
	)
	(arc
		(start 90.330782 -285.166816)
		(mid 90.461696 -285.030456)
		(end 90.509344 -284.847538)
		(width 0.0889)
		(layer "In6.Cu")
		(net "UPI_CPU0_CPU1_P2P2_DP<5>")
	)
	(arc
		(start 350.57207 -289.278314)
		(mid 350.746016 -289.417444)
		(end 350.857058 -289.610546)
		(width 0.0889)
		(layer "In6.Cu")
		(net "UPI_CPU0_CPU1_P2P2_DP<5>")
	)
	(arc
		(start 351.505774 -285.342076)
		(mid 351.376485 -285.475562)
		(end 351.327212 -285.65475)
		(width 0.0889)
		(layer "In6.Cu")
		(net "UPI_CPU0_CPU1_P2P2_DP<5>")
	)
	(arc
		(start 90.039698 -282.405836)
		(mid 89.992019 -282.222936)
		(end 89.861136 -282.086558)
		(width 0.0889)
		(layer "In6.Cu")
		(net "UPI_CPU0_CPU1_P2P2_DP<5>")
	)
	(arc
		(start 351.797366 -286.475424)
		(mid 351.723375 -286.75499)
		(end 351.52076 -286.961326)
		(width 0.0889)
		(layer "In6.Cu")
		(net "UPI_CPU0_CPU1_P2P2_DP<5>")
	)
	(arc
		(start 352.083116 -282.319222)
		(mid 352.17338 -282.089312)
		(end 352.353118 -281.919934)
		(width 0.0889)
		(layer "In6.Cu")
		(net "UPI_CPU0_CPU1_P2P2_DP<5>")
	)
	(arc
		(start 90.800682 -284.353)
		(mid 90.979279 -284.033722)
		(end 90.800682 -283.714444)
		(width 0.0889)
		(layer "In6.Cu")
		(net "UPI_CPU0_CPU1_P2P2_DP<5>")
	)
	(arc
		(start 351.327212 -285.670752)
		(mid 351.377108 -285.848399)
		(end 351.505774 -285.980632)
		(width 0.0889)
		(layer "In6.Cu")
		(net "UPI_CPU0_CPU1_P2P2_DP<5>")
	)
	(arc
		(start 90.508836 -286.460692)
		(mid 90.457859 -286.286175)
		(end 90.330782 -286.156146)
		(width 0.0889)
		(layer "In6.Cu")
		(net "UPI_CPU0_CPU1_P2P2_DP<5>")
	)
	(arc
		(start 89.84615 -282.077922)
		(mid 89.643563 -281.871571)
		(end 89.569544 -281.59202)
		(width 0.0889)
		(layer "In6.Cu")
		(net "UPI_CPU0_CPU1_P2P2_DP<5>")
	)
	(arc
		(start 90.321892 -286.151066)
		(mid 90.039151 -285.664948)
		(end 90.315796 -285.175452)
		(width 0.0889)
		(layer "In6.Cu")
		(net "UPI_CPU0_CPU1_P2P2_DP<5>")
	)
	(arc
		(start 350.387666 -289.078416)
		(mid 350.462671 -289.193875)
		(end 350.571816 -289.277806)
		(width 0.0889)
		(layer "In6.Cu")
		(net "UPI_CPU0_CPU1_P2P2_DP<5>")
	)
	(arc
		(start 352.373946 -281.907742)
		(mid 352.925139 -281.91654)
		(end 353.206812 -282.390342)
		(width 0.0889)
		(layer "In6.Cu")
		(net "UPI_CPU0_CPU1_P2P2_DP<5>")
	)
	(arc
		(start 351.036128 -287.783778)
		(mid 350.905214 -287.920138)
		(end 350.857566 -288.103056)
		(width 0.0889)
		(layer "In6.Cu")
		(net "UPI_CPU0_CPU1_P2P2_DP<5>")
	)
	(arc
		(start 90.509344 -283.219906)
		(mid 90.509292 -283.212539)
		(end 90.50909 -283.205174)
		(width 0.0889)
		(layer "In6.Cu")
		(net "UPI_CPU0_CPU1_P2P2_DP<5>")
	)
	(arc
		(start 89.569544 -288.09315)
		(mid 89.647655 -287.816201)
		(end 89.851992 -287.613598)
		(width 0.0889)
		(layer "In6.Cu")
		(net "UPI_CPU0_CPU1_P2P2_DP<5>")
	)
	(arc
		(start 351.514664 -285.985712)
		(mid 351.718145 -286.186516)
		(end 351.797366 -286.4612)
		(width 0.0889)
		(layer "In6.Cu")
		(net "UPI_CPU0_CPU1_P2P2_DP<5>")
	)
	(segment
		(start 89.664794 -281.869896)
		(end 89.665048 -281.87015)
		(width 0.13208)
		(layer "F.Cu")
		(net "UPI_CPU0_CPU1_P2P2_DP<4>")
	)
	(segment
		(start 353.111562 -283.219652)
		(end 353.111816 -283.219906)
		(width 0.13208)
		(layer "F.Cu")
		(net "UPI_CPU0_CPU1_P2P2_DP<4>")
	)
	(segment
		(start 89.665048 -281.87015)
		(end 89.665048 -282.405836)
		(width 0.13208)
		(layer "F.Cu")
		(net "UPI_CPU0_CPU1_P2P2_DP<4>")
	)
	(segment
		(start 353.111562 -282.683966)
		(end 353.111562 -283.219652)
		(width 0.13208)
		(layer "F.Cu")
		(net "UPI_CPU0_CPU1_P2P2_DP<4>")
	)
	(segment
		(start 58.853324 -332.93558)
		(end 57.71388 -330.182982)
		(width 0.14732)
		(layer "In6.Cu")
		(net "UPI_CPU0_CPU1_P2P2_DP<4>")
	)
	(segment
		(start 142.9004 -389.35533)
		(end 142.77594 -389.23087)
		(width 0.14732)
		(layer "In6.Cu")
		(net "UPI_CPU0_CPU1_P2P2_DP<4>")
	)
	(segment
		(start 142.77594 -389.23087)
		(end 142.33906 -389.23087)
		(width 0.14732)
		(layer "In6.Cu")
		(net "UPI_CPU0_CPU1_P2P2_DP<4>")
	)
	(segment
		(start 89.760044 -284.857444)
		(end 89.760044 -284.847538)
		(width 0.0889)
		(layer "In6.Cu")
		(net "UPI_CPU0_CPU1_P2P2_DP<4>")
	)
	(segment
		(start 81.116678 -300.18228)
		(end 81.425796 -299.873162)
		(width 0.14732)
		(layer "In6.Cu")
		(net "UPI_CPU0_CPU1_P2P2_DP<4>")
	)
	(segment
		(start 343.50452 -306.821586)
		(end 343.504774 -306.821586)
		(width 0.14732)
		(layer "In6.Cu")
		(net "UPI_CPU0_CPU1_P2P2_DP<4>")
	)
	(segment
		(start 87.031068 -291.509196)
		(end 87.031068 -291.449252)
		(width 0.0889)
		(layer "In6.Cu")
		(net "UPI_CPU0_CPU1_P2P2_DP<4>")
	)
	(segment
		(start 348.962472 -300.917356)
		(end 348.063566 -302.26254)
		(width 0.14732)
		(layer "In6.Cu")
		(net "UPI_CPU0_CPU1_P2P2_DP<4>")
	)
	(segment
		(start 59.697366 -318.697102)
		(end 59.90209 -318.697102)
		(width 0.14732)
		(layer "In6.Cu")
		(net "UPI_CPU0_CPU1_P2P2_DP<4>")
	)
	(segment
		(start 89.938606 -284.52826)
		(end 89.947496 -284.52318)
		(width 0.0889)
		(layer "In6.Cu")
		(net "UPI_CPU0_CPU1_P2P2_DP<4>")
	)
	(segment
		(start 59.02452 -322.913756)
		(end 59.02452 -319.458086)
		(width 0.14732)
		(layer "In6.Cu")
		(net "UPI_CPU0_CPU1_P2P2_DP<4>")
	)
	(segment
		(start 353.299014 -283.544264)
		(end 353.298252 -283.544772)
		(width 0.0889)
		(layer "In6.Cu")
		(net "UPI_CPU0_CPU1_P2P2_DP<4>")
	)
	(segment
		(start 352.35896 -286.799782)
		(end 352.352864 -286.803338)
		(width 0.0889)
		(layer "In6.Cu")
		(net "UPI_CPU0_CPU1_P2P2_DP<4>")
	)
	(segment
		(start 82.216244 -299.082714)
		(end 82.216244 -298.910248)
		(width 0.14732)
		(layer "In6.Cu")
		(net "UPI_CPU0_CPU1_P2P2_DP<4>")
	)
	(segment
		(start 352.36785 -286.794702)
		(end 352.35896 -286.799782)
		(width 0.0889)
		(layer "In6.Cu")
		(net "UPI_CPU0_CPU1_P2P2_DP<4>")
	)
	(segment
		(start 351.890076 -287.61309)
		(end 351.88906 -287.613598)
		(width 0.0889)
		(layer "In6.Cu")
		(net "UPI_CPU0_CPU1_P2P2_DP<4>")
	)
	(segment
		(start 142.33906 -389.23087)
		(end 142.2146 -389.35533)
		(width 0.14732)
		(layer "In6.Cu")
		(net "UPI_CPU0_CPU1_P2P2_DP<4>")
	)
	(segment
		(start 351.507806 -290.072318)
		(end 351.507806 -290.247578)
		(width 0.0889)
		(layer "In6.Cu")
		(net "UPI_CPU0_CPU1_P2P2_DP<4>")
	)
	(segment
		(start 89.947496 -283.544264)
		(end 89.938606 -283.539184)
		(width 0.0889)
		(layer "In6.Cu")
		(net "UPI_CPU0_CPU1_P2P2_DP<4>")
	)
	(segment
		(start 277.136352 -347.138498)
		(end 277.136352 -370.948712)
		(width 0.14732)
		(layer "In6.Cu")
		(net "UPI_CPU0_CPU1_P2P2_DP<4>")
	)
	(segment
		(start 57.71388 -330.182982)
		(end 57.71388 -324.640448)
		(width 0.14732)
		(layer "In6.Cu")
		(net "UPI_CPU0_CPU1_P2P2_DP<4>")
	)
	(segment
		(start 81.425796 -299.873162)
		(end 81.425796 -299.700696)
		(width 0.14732)
		(layer "In6.Cu")
		(net "UPI_CPU0_CPU1_P2P2_DP<4>")
	)
	(segment
		(start 351.606866 -289.973258)
		(end 351.507806 -290.072318)
		(width 0.0889)
		(layer "In6.Cu")
		(net "UPI_CPU0_CPU1_P2P2_DP<4>")
	)
	(segment
		(start 349.917004 -297.77055)
		(end 348.962472 -300.917356)
		(width 0.14732)
		(layer "In6.Cu")
		(net "UPI_CPU0_CPU1_P2P2_DP<4>")
	)
	(segment
		(start 349.917004 -292.997128)
		(end 349.917004 -293.019226)
		(width 0.0889)
		(layer "In6.Cu")
		(net "UPI_CPU0_CPU1_P2P2_DP<4>")
	)
	(segment
		(start 353.26828 -282.948888)
		(end 353.346258 -282.92806)
		(width 0.0889)
		(layer "In6.Cu")
		(net "UPI_CPU0_CPU1_P2P2_DP<4>")
	)
	(segment
		(start 89.468706 -285.342076)
		(end 89.477596 -285.336996)
		(width 0.0889)
		(layer "In6.Cu")
		(net "UPI_CPU0_CPU1_P2P2_DP<4>")
	)
	(segment
		(start 87.880444 -288.121598)
		(end 87.880444 -288.103056)
		(width 0.0889)
		(layer "In6.Cu")
		(net "UPI_CPU0_CPU1_P2P2_DP<4>")
	)
	(segment
		(start 89.760044 -283.219906)
		(end 89.760044 -283.201364)
		(width 0.0889)
		(layer "In6.Cu")
		(net "UPI_CPU0_CPU1_P2P2_DP<4>")
	)
	(segment
		(start 351.095056 -291.170614)
		(end 350.954594 -291.170614)
		(width 0.0889)
		(layer "In6.Cu")
		(net "UPI_CPU0_CPU1_P2P2_DP<4>")
	)
	(segment
		(start 87.50935 -289.950906)
		(end 87.50935 -289.773106)
		(width 0.0889)
		(layer "In6.Cu")
		(net "UPI_CPU0_CPU1_P2P2_DP<4>")
	)
	(segment
		(start 64.262762 -315.439552)
		(end 65.409572 -314.292742)
		(width 0.14732)
		(layer "In6.Cu")
		(net "UPI_CPU0_CPU1_P2P2_DP<4>")
	)
	(segment
		(start 60.162694 -318.231774)
		(end 60.423044 -317.971424)
		(width 0.14732)
		(layer "In6.Cu")
		(net "UPI_CPU0_CPU1_P2P2_DP<4>")
	)
	(segment
		(start 351.606866 -290.658804)
		(end 351.095056 -291.170614)
		(width 0.0889)
		(layer "In6.Cu")
		(net "UPI_CPU0_CPU1_P2P2_DP<4>")
	)
	(segment
		(start 65.409572 -314.292742)
		(end 67.840352 -313.28614)
		(width 0.14732)
		(layer "In6.Cu")
		(net "UPI_CPU0_CPU1_P2P2_DP<4>")
	)
	(segment
		(start 352.83775 -284.353)
		(end 352.82886 -284.35808)
		(width 0.0889)
		(layer "In6.Cu")
		(net "UPI_CPU0_CPU1_P2P2_DP<4>")
	)
	(segment
		(start 60.888372 -317.71082)
		(end 60.888372 -317.506096)
		(width 0.14732)
		(layer "In6.Cu")
		(net "UPI_CPU0_CPU1_P2P2_DP<4>")
	)
	(segment
		(start 88.059006 -287.783778)
		(end 88.067896 -287.778698)
		(width 0.0889)
		(layer "In6.Cu")
		(net "UPI_CPU0_CPU1_P2P2_DP<4>")
	)
	(segment
		(start 283.033978 -341.240872)
		(end 277.136352 -347.138498)
		(width 0.14732)
		(layer "In6.Cu")
		(net "UPI_CPU0_CPU1_P2P2_DP<4>")
	)
	(segment
		(start 160.828228 -389.35533)
		(end 145.14576 -389.35533)
		(width 0.14732)
		(layer "In6.Cu")
		(net "UPI_CPU0_CPU1_P2P2_DP<4>")
	)
	(segment
		(start 351.89795 -287.608518)
		(end 351.890076 -287.61309)
		(width 0.0889)
		(layer "In6.Cu")
		(net "UPI_CPU0_CPU1_P2P2_DP<4>")
	)
	(segment
		(start 57.71388 -324.640448)
		(end 58.730388 -323.62394)
		(width 0.14732)
		(layer "In6.Cu")
		(net "UPI_CPU0_CPU1_P2P2_DP<4>")
	)
	(segment
		(start 339.597238 -308.440582)
		(end 320.717926 -327.319894)
		(width 0.14732)
		(layer "In6.Cu")
		(net "UPI_CPU0_CPU1_P2P2_DP<4>")
	)
	(segment
		(start 81.425796 -299.700696)
		(end 81.73466 -299.391832)
		(width 0.14732)
		(layer "In6.Cu")
		(net "UPI_CPU0_CPU1_P2P2_DP<4>")
	)
	(segment
		(start 145.14576 -389.35533)
		(end 145.0213 -389.23087)
		(width 0.14732)
		(layer "In6.Cu")
		(net "UPI_CPU0_CPU1_P2P2_DP<4>")
	)
	(segment
		(start 143.46174 -389.23087)
		(end 143.33728 -389.35533)
		(width 0.14732)
		(layer "In6.Cu")
		(net "UPI_CPU0_CPU1_P2P2_DP<4>")
	)
	(segment
		(start 319.573402 -330.083414)
		(end 309.868316 -339.7885)
		(width 0.14732)
		(layer "In6.Cu")
		(net "UPI_CPU0_CPU1_P2P2_DP<4>")
	)
	(segment
		(start 348.063566 -302.26254)
		(end 343.50452 -306.821586)
		(width 0.14732)
		(layer "In6.Cu")
		(net "UPI_CPU0_CPU1_P2P2_DP<4>")
	)
	(segment
		(start 60.034678 -335.789524)
		(end 58.853324 -332.93558)
		(width 0.14732)
		(layer "In6.Cu")
		(net "UPI_CPU0_CPU1_P2P2_DP<4>")
	)
	(segment
		(start 351.606866 -289.64636)
		(end 351.606866 -289.973258)
		(width 0.0889)
		(layer "In6.Cu")
		(net "UPI_CPU0_CPU1_P2P2_DP<4>")
	)
	(segment
		(start 350.44253 -291.682678)
		(end 350.44253 -291.82314)
		(width 0.0889)
		(layer "In6.Cu")
		(net "UPI_CPU0_CPU1_P2P2_DP<4>")
	)
	(segment
		(start 87.41029 -291.07003)
		(end 87.41029 -290.049966)
		(width 0.0889)
		(layer "In6.Cu")
		(net "UPI_CPU0_CPU1_P2P2_DP<4>")
	)
	(segment
		(start 82.999834 -298.126658)
		(end 84.828126 -293.712138)
		(width 0.14732)
		(layer "In6.Cu")
		(net "UPI_CPU0_CPU1_P2P2_DP<4>")
	)
	(segment
		(start 351.606866 -288.087562)
		(end 351.606866 -288.103056)
		(width 0.0889)
		(layer "In6.Cu")
		(net "UPI_CPU0_CPU1_P2P2_DP<4>")
	)
	(segment
		(start 349.958914 -292.955218)
		(end 349.917004 -292.997128)
		(width 0.0889)
		(layer "In6.Cu")
		(net "UPI_CPU0_CPU1_P2P2_DP<4>")
	)
	(segment
		(start 87.41029 -290.049966)
		(end 87.50935 -289.950906)
		(width 0.0889)
		(layer "In6.Cu")
		(net "UPI_CPU0_CPU1_P2P2_DP<4>")
	)
	(segment
		(start 126.875794 -389.35533)
		(end 94.945962 -384.618738)
		(width 0.14732)
		(layer "In6.Cu")
		(net "UPI_CPU0_CPU1_P2P2_DP<4>")
	)
	(segment
		(start 65.838832 -369.541806)
		(end 60.034678 -355.529642)
		(width 0.14732)
		(layer "In6.Cu")
		(net "UPI_CPU0_CPU1_P2P2_DP<4>")
	)
	(segment
		(start 58.730388 -323.62394)
		(end 59.02452 -322.913756)
		(width 0.14732)
		(layer "In6.Cu")
		(net "UPI_CPU0_CPU1_P2P2_DP<4>")
	)
	(segment
		(start 89.476072 -286.965644)
		(end 89.483692 -286.961326)
		(width 0.0889)
		(layer "In6.Cu")
		(net "UPI_CPU0_CPU1_P2P2_DP<4>")
	)
	(segment
		(start 82.216244 -298.910248)
		(end 82.999834 -298.126658)
		(width 0.14732)
		(layer "In6.Cu")
		(net "UPI_CPU0_CPU1_P2P2_DP<4>")
	)
	(segment
		(start 145.0213 -389.23087)
		(end 144.58442 -389.23087)
		(width 0.14732)
		(layer "In6.Cu")
		(net "UPI_CPU0_CPU1_P2P2_DP<4>")
	)
	(segment
		(start 351.428304 -288.422334)
		(end 351.419414 -288.427414)
		(width 0.0889)
		(layer "In6.Cu")
		(net "UPI_CPU0_CPU1_P2P2_DP<4>")
	)
	(segment
		(start 143.89862 -389.23087)
		(end 143.46174 -389.23087)
		(width 0.14732)
		(layer "In6.Cu")
		(net "UPI_CPU0_CPU1_P2P2_DP<4>")
	)
	(segment
		(start 60.423044 -317.971424)
		(end 60.627768 -317.971424)
		(width 0.14732)
		(layer "In6.Cu")
		(net "UPI_CPU0_CPU1_P2P2_DP<4>")
	)
	(segment
		(start 59.02452 -319.458086)
		(end 59.20232 -319.192148)
		(width 0.14732)
		(layer "In6.Cu")
		(net "UPI_CPU0_CPU1_P2P2_DP<4>")
	)
	(segment
		(start 142.2146 -389.35533)
		(end 126.875794 -389.35533)
		(width 0.14732)
		(layer "In6.Cu")
		(net "UPI_CPU0_CPU1_P2P2_DP<4>")
	)
	(segment
		(start 60.162694 -318.436498)
		(end 60.162694 -318.231774)
		(width 0.14732)
		(layer "In6.Cu")
		(net "UPI_CPU0_CPU1_P2P2_DP<4>")
	)
	(segment
		(start 87.41029 -289.496246)
		(end 87.50935 -289.397186)
		(width 0.0889)
		(layer "In6.Cu")
		(net "UPI_CPU0_CPU1_P2P2_DP<4>")
	)
	(segment
		(start 87.41029 -289.674046)
		(end 87.41029 -289.496246)
		(width 0.0889)
		(layer "In6.Cu")
		(net "UPI_CPU0_CPU1_P2P2_DP<4>")
	)
	(segment
		(start 59.90209 -318.697102)
		(end 60.162694 -318.436498)
		(width 0.14732)
		(layer "In6.Cu")
		(net "UPI_CPU0_CPU1_P2P2_DP<4>")
	)
	(segment
		(start 70.995032 -374.698006)
		(end 65.838832 -369.541806)
		(width 0.14732)
		(layer "In6.Cu")
		(net "UPI_CPU0_CPU1_P2P2_DP<4>")
	)
	(segment
		(start 351.507806 -290.247578)
		(end 351.606866 -290.346638)
		(width 0.0889)
		(layer "In6.Cu")
		(net "UPI_CPU0_CPU1_P2P2_DP<4>")
	)
	(segment
		(start 352.358452 -285.172404)
		(end 352.353118 -285.175452)
		(width 0.0889)
		(layer "In6.Cu")
		(net "UPI_CPU0_CPU1_P2P2_DP<4>")
	)
	(segment
		(start 80.944212 -300.18228)
		(end 81.116678 -300.18228)
		(width 0.14732)
		(layer "In6.Cu")
		(net "UPI_CPU0_CPU1_P2P2_DP<4>")
	)
	(segment
		(start 277.136352 -370.948712)
		(end 267.758672 -380.326392)
		(width 0.14732)
		(layer "In6.Cu")
		(net "UPI_CPU0_CPU1_P2P2_DP<4>")
	)
	(segment
		(start 61.453014 -316.9412)
		(end 64.262762 -315.439552)
		(width 0.14732)
		(layer "In6.Cu")
		(net "UPI_CPU0_CPU1_P2P2_DP<4>")
	)
	(segment
		(start 320.717926 -327.319894)
		(end 319.573402 -330.083414)
		(width 0.14732)
		(layer "In6.Cu")
		(net "UPI_CPU0_CPU1_P2P2_DP<4>")
	)
	(segment
		(start 144.45996 -389.35533)
		(end 144.02308 -389.35533)
		(width 0.14732)
		(layer "In6.Cu")
		(net "UPI_CPU0_CPU1_P2P2_DP<4>")
	)
	(segment
		(start 267.75791 -380.326392)
		(end 160.828228 -389.35533)
		(width 0.14732)
		(layer "In6.Cu")
		(net "UPI_CPU0_CPU1_P2P2_DP<4>")
	)
	(segment
		(start 349.917004 -293.019226)
		(end 349.917004 -297.77055)
		(width 0.14732)
		(layer "In6.Cu")
		(net "UPI_CPU0_CPU1_P2P2_DP<4>")
	)
	(segment
		(start 352.546412 -284.837632)
		(end 352.546412 -284.856174)
		(width 0.0889)
		(layer "In6.Cu")
		(net "UPI_CPU0_CPU1_P2P2_DP<4>")
	)
	(segment
		(start 60.627768 -317.971424)
		(end 60.888372 -317.71082)
		(width 0.14732)
		(layer "In6.Cu")
		(net "UPI_CPU0_CPU1_P2P2_DP<4>")
	)
	(segment
		(start 350.706944 -291.558726)
		(end 350.566482 -291.558726)
		(width 0.0889)
		(layer "In6.Cu")
		(net "UPI_CPU0_CPU1_P2P2_DP<4>")
	)
	(segment
		(start 352.35896 -286.151066)
		(end 352.36785 -286.156146)
		(width 0.0889)
		(layer "In6.Cu")
		(net "UPI_CPU0_CPU1_P2P2_DP<4>")
	)
	(segment
		(start 351.606612 -289.645852)
		(end 351.606866 -289.64636)
		(width 0.0889)
		(layer "In6.Cu")
		(net "UPI_CPU0_CPU1_P2P2_DP<4>")
	)
	(segment
		(start 87.50935 -289.397186)
		(end 87.50935 -289.219386)
		(width 0.0889)
		(layer "In6.Cu")
		(net "UPI_CPU0_CPU1_P2P2_DP<4>")
	)
	(segment
		(start 87.50935 -289.773106)
		(end 87.41029 -289.674046)
		(width 0.0889)
		(layer "In6.Cu")
		(net "UPI_CPU0_CPU1_P2P2_DP<4>")
	)
	(segment
		(start 87.41029 -289.120326)
		(end 87.41029 -288.761678)
		(width 0.0889)
		(layer "In6.Cu")
		(net "UPI_CPU0_CPU1_P2P2_DP<4>")
	)
	(segment
		(start 87.50935 -289.219386)
		(end 87.41029 -289.120326)
		(width 0.0889)
		(layer "In6.Cu")
		(net "UPI_CPU0_CPU1_P2P2_DP<4>")
	)
	(segment
		(start 60.034678 -355.529642)
		(end 60.034678 -335.789524)
		(width 0.14732)
		(layer "In6.Cu")
		(net "UPI_CPU0_CPU1_P2P2_DP<4>")
	)
	(segment
		(start 87.41029 -288.761678)
		(end 87.520018 -288.65195)
		(width 0.0889)
		(layer "In6.Cu")
		(net "UPI_CPU0_CPU1_P2P2_DP<4>")
	)
	(segment
		(start 89.290144 -287.299146)
		(end 89.290144 -287.28924)
		(width 0.0889)
		(layer "In6.Cu")
		(net "UPI_CPU0_CPU1_P2P2_DP<4>")
	)
	(segment
		(start 353.486212 -283.21127)
		(end 353.486212 -283.228542)
		(width 0.0889)
		(layer "In6.Cu")
		(net "UPI_CPU0_CPU1_P2P2_DP<4>")
	)
	(segment
		(start 353.298252 -283.544772)
		(end 353.292918 -283.54782)
		(width 0.0889)
		(layer "In6.Cu")
		(net "UPI_CPU0_CPU1_P2P2_DP<4>")
	)
	(segment
		(start 89.29497 -282.462986)
		(end 89.35212 -282.405836)
		(width 0.0889)
		(layer "In6.Cu")
		(net "UPI_CPU0_CPU1_P2P2_DP<4>")
	)
	(segment
		(start 350.830642 -291.435028)
		(end 350.706944 -291.558726)
		(width 0.0889)
		(layer "In6.Cu")
		(net "UPI_CPU0_CPU1_P2P2_DP<4>")
	)
	(segment
		(start 89.477596 -285.985712)
		(end 89.468706 -285.980632)
		(width 0.0889)
		(layer "In6.Cu")
		(net "UPI_CPU0_CPU1_P2P2_DP<4>")
	)
	(segment
		(start 343.504774 -306.821586)
		(end 339.597238 -308.440582)
		(width 0.14732)
		(layer "In6.Cu")
		(net "UPI_CPU0_CPU1_P2P2_DP<4>")
	)
	(segment
		(start 350.954594 -291.170614)
		(end 350.830642 -291.294566)
		(width 0.0889)
		(layer "In6.Cu")
		(net "UPI_CPU0_CPU1_P2P2_DP<4>")
	)
	(segment
		(start 352.076512 -285.661354)
		(end 352.076512 -285.679896)
		(width 0.0889)
		(layer "In6.Cu")
		(net "UPI_CPU0_CPU1_P2P2_DP<4>")
	)
	(segment
		(start 350.44253 -291.82314)
		(end 349.958914 -292.306756)
		(width 0.0889)
		(layer "In6.Cu")
		(net "UPI_CPU0_CPU1_P2P2_DP<4>")
	)
	(segment
		(start 81.73466 -299.391832)
		(end 81.907126 -299.391832)
		(width 0.14732)
		(layer "In6.Cu")
		(net "UPI_CPU0_CPU1_P2P2_DP<4>")
	)
	(segment
		(start 60.888372 -317.506096)
		(end 61.453014 -316.9412)
		(width 0.14732)
		(layer "In6.Cu")
		(net "UPI_CPU0_CPU1_P2P2_DP<4>")
	)
	(segment
		(start 351.136966 -288.898584)
		(end 351.136966 -289.114738)
		(width 0.0889)
		(layer "In6.Cu")
		(net "UPI_CPU0_CPU1_P2P2_DP<4>")
	)
	(segment
		(start 59.20232 -319.192148)
		(end 59.697366 -318.697102)
		(width 0.14732)
		(layer "In6.Cu")
		(net "UPI_CPU0_CPU1_P2P2_DP<4>")
	)
	(segment
		(start 87.031068 -291.449252)
		(end 87.41029 -291.07003)
		(width 0.0889)
		(layer "In6.Cu")
		(net "UPI_CPU0_CPU1_P2P2_DP<4>")
	)
	(segment
		(start 286.540956 -339.7885)
		(end 283.033978 -341.240872)
		(width 0.14732)
		(layer "In6.Cu")
		(net "UPI_CPU0_CPU1_P2P2_DP<4>")
	)
	(segment
		(start 144.02308 -389.35533)
		(end 143.89862 -389.23087)
		(width 0.14732)
		(layer "In6.Cu")
		(net "UPI_CPU0_CPU1_P2P2_DP<4>")
	)
	(segment
		(start 349.958914 -292.306756)
		(end 349.958914 -292.955218)
		(width 0.0889)
		(layer "In6.Cu")
		(net "UPI_CPU0_CPU1_P2P2_DP<4>")
	)
	(segment
		(start 89.35212 -282.405836)
		(end 89.665048 -282.405836)
		(width 0.0889)
		(layer "In6.Cu")
		(net "UPI_CPU0_CPU1_P2P2_DP<4>")
	)
	(segment
		(start 267.758672 -380.326392)
		(end 267.75791 -380.326392)
		(width 0.14732)
		(layer "In6.Cu")
		(net "UPI_CPU0_CPU1_P2P2_DP<4>")
	)
	(segment
		(start 81.907126 -299.391832)
		(end 82.216244 -299.082714)
		(width 0.14732)
		(layer "In6.Cu")
		(net "UPI_CPU0_CPU1_P2P2_DP<4>")
	)
	(segment
		(start 351.606866 -290.346638)
		(end 351.606866 -290.658804)
		(width 0.0889)
		(layer "In6.Cu")
		(net "UPI_CPU0_CPU1_P2P2_DP<4>")
	)
	(segment
		(start 143.33728 -389.35533)
		(end 142.9004 -389.35533)
		(width 0.14732)
		(layer "In6.Cu")
		(net "UPI_CPU0_CPU1_P2P2_DP<4>")
	)
	(segment
		(start 309.868316 -339.7885)
		(end 286.540956 -339.7885)
		(width 0.14732)
		(layer "In6.Cu")
		(net "UPI_CPU0_CPU1_P2P2_DP<4>")
	)
	(segment
		(start 144.58442 -389.23087)
		(end 144.45996 -389.35533)
		(width 0.14732)
		(layer "In6.Cu")
		(net "UPI_CPU0_CPU1_P2P2_DP<4>")
	)
	(segment
		(start 352.359214 -285.171896)
		(end 352.358452 -285.172404)
		(width 0.0889)
		(layer "In6.Cu")
		(net "UPI_CPU0_CPU1_P2P2_DP<4>")
	)
	(segment
		(start 94.945962 -384.618738)
		(end 70.995032 -374.698006)
		(width 0.14732)
		(layer "In6.Cu")
		(net "UPI_CPU0_CPU1_P2P2_DP<4>")
	)
	(segment
		(start 84.828126 -293.712138)
		(end 87.015574 -291.52469)
		(width 0.14732)
		(layer "In6.Cu")
		(net "UPI_CPU0_CPU1_P2P2_DP<4>")
	)
	(segment
		(start 67.840352 -313.28614)
		(end 80.944212 -300.18228)
		(width 0.14732)
		(layer "In6.Cu")
		(net "UPI_CPU0_CPU1_P2P2_DP<4>")
	)
	(segment
		(start 89.468706 -286.969962)
		(end 89.476072 -286.965644)
		(width 0.0889)
		(layer "In6.Cu")
		(net "UPI_CPU0_CPU1_P2P2_DP<4>")
	)
	(segment
		(start 350.830642 -291.294566)
		(end 350.830642 -291.435028)
		(width 0.0889)
		(layer "In6.Cu")
		(net "UPI_CPU0_CPU1_P2P2_DP<4>")
	)
	(segment
		(start 353.111816 -283.219906)
		(end 353.26828 -282.948888)
		(width 0.0889)
		(layer "In6.Cu")
		(net "UPI_CPU0_CPU1_P2P2_DP<4>")
	)
	(segment
		(start 350.566482 -291.558726)
		(end 350.44253 -291.682678)
		(width 0.0889)
		(layer "In6.Cu")
		(net "UPI_CPU0_CPU1_P2P2_DP<4>")
	)
	(segment
		(start 87.015574 -291.52469)
		(end 87.031068 -291.509196)
		(width 0.0889)
		(layer "In6.Cu")
		(net "UPI_CPU0_CPU1_P2P2_DP<4>")
	)
	(arc
		(start 89.760044 -284.847538)
		(mid 89.807723 -284.664638)
		(end 89.938606 -284.52826)
		(width 0.0889)
		(layer "In6.Cu")
		(net "UPI_CPU0_CPU1_P2P2_DP<4>")
	)
	(arc
		(start 352.546412 -284.856174)
		(mid 352.494142 -285.038539)
		(end 352.359214 -285.171896)
		(width 0.0889)
		(layer "In6.Cu")
		(net "UPI_CPU0_CPU1_P2P2_DP<4>")
	)
	(arc
		(start 351.422462 -289.446462)
		(mid 351.531609 -289.53039)
		(end 351.606612 -289.645852)
		(width 0.0889)
		(layer "In6.Cu")
		(net "UPI_CPU0_CPU1_P2P2_DP<4>")
	)
	(arc
		(start 352.076512 -287.28924)
		(mid 352.028833 -287.47214)
		(end 351.89795 -287.608518)
		(width 0.0889)
		(layer "In6.Cu")
		(net "UPI_CPU0_CPU1_P2P2_DP<4>")
	)
	(arc
		(start 352.352864 -286.803338)
		(mid 352.150451 -287.009751)
		(end 352.076512 -287.28924)
		(width 0.0889)
		(layer "In6.Cu")
		(net "UPI_CPU0_CPU1_P2P2_DP<4>")
	)
	(arc
		(start 351.136966 -289.114738)
		(mid 351.248304 -289.307638)
		(end 351.422462 -289.446462)
		(width 0.0889)
		(layer "In6.Cu")
		(net "UPI_CPU0_CPU1_P2P2_DP<4>")
	)
	(arc
		(start 89.760044 -283.201364)
		(mid 89.679882 -282.929175)
		(end 89.477596 -282.730194)
		(width 0.0889)
		(layer "In6.Cu")
		(net "UPI_CPU0_CPU1_P2P2_DP<4>")
	)
	(arc
		(start 87.597996 -288.592768)
		(mid 87.800282 -288.393787)
		(end 87.880444 -288.121598)
		(width 0.0889)
		(layer "In6.Cu")
		(net "UPI_CPU0_CPU1_P2P2_DP<4>")
	)
	(arc
		(start 88.442292 -287.778698)
		(mid 89.003268 -287.781229)
		(end 89.290144 -287.299146)
		(width 0.0889)
		(layer "In6.Cu")
		(net "UPI_CPU0_CPU1_P2P2_DP<4>")
	)
	(arc
		(start 351.606866 -288.103056)
		(mid 351.559187 -288.285956)
		(end 351.428304 -288.422334)
		(width 0.0889)
		(layer "In6.Cu")
		(net "UPI_CPU0_CPU1_P2P2_DP<4>")
	)
	(arc
		(start 89.483692 -286.961326)
		(mid 89.760255 -286.471832)
		(end 89.477596 -285.985712)
		(width 0.0889)
		(layer "In6.Cu")
		(net "UPI_CPU0_CPU1_P2P2_DP<4>")
	)
	(arc
		(start 89.468706 -285.980632)
		(mid 89.290109 -285.661354)
		(end 89.468706 -285.342076)
		(width 0.0889)
		(layer "In6.Cu")
		(net "UPI_CPU0_CPU1_P2P2_DP<4>")
	)
	(arc
		(start 352.353118 -285.175452)
		(mid 352.150531 -285.381803)
		(end 352.076512 -285.661354)
		(width 0.0889)
		(layer "In6.Cu")
		(net "UPI_CPU0_CPU1_P2P2_DP<4>")
	)
	(arc
		(start 352.82886 -284.35808)
		(mid 352.624525 -284.560685)
		(end 352.546412 -284.837632)
		(width 0.0889)
		(layer "In6.Cu")
		(net "UPI_CPU0_CPU1_P2P2_DP<4>")
	)
	(arc
		(start 353.346258 -282.92806)
		(mid 353.447579 -283.054181)
		(end 353.486212 -283.21127)
		(width 0.0889)
		(layer "In6.Cu")
		(net "UPI_CPU0_CPU1_P2P2_DP<4>")
	)
	(arc
		(start 89.947496 -284.52318)
		(mid 90.230028 -284.033722)
		(end 89.947496 -283.544264)
		(width 0.0889)
		(layer "In6.Cu")
		(net "UPI_CPU0_CPU1_P2P2_DP<4>")
	)
	(arc
		(start 87.520018 -288.65195)
		(mid 87.557068 -288.619804)
		(end 87.597996 -288.592768)
		(width 0.0889)
		(layer "In6.Cu")
		(net "UPI_CPU0_CPU1_P2P2_DP<4>")
	)
	(arc
		(start 352.076512 -285.679896)
		(mid 352.156674 -285.952085)
		(end 352.35896 -286.151066)
		(width 0.0889)
		(layer "In6.Cu")
		(net "UPI_CPU0_CPU1_P2P2_DP<4>")
	)
	(arc
		(start 351.88906 -287.613598)
		(mid 351.686237 -287.813829)
		(end 351.606866 -288.087562)
		(width 0.0889)
		(layer "In6.Cu")
		(net "UPI_CPU0_CPU1_P2P2_DP<4>")
	)
	(arc
		(start 89.290144 -287.28924)
		(mid 89.337823 -287.10634)
		(end 89.468706 -286.969962)
		(width 0.0889)
		(layer "In6.Cu")
		(net "UPI_CPU0_CPU1_P2P2_DP<4>")
	)
	(arc
		(start 352.36785 -286.156146)
		(mid 352.546447 -286.475424)
		(end 352.36785 -286.794702)
		(width 0.0889)
		(layer "In6.Cu")
		(net "UPI_CPU0_CPU1_P2P2_DP<4>")
	)
	(arc
		(start 351.419414 -288.427414)
		(mid 351.217128 -288.626395)
		(end 351.136966 -288.898584)
		(width 0.0889)
		(layer "In6.Cu")
		(net "UPI_CPU0_CPU1_P2P2_DP<4>")
	)
	(arc
		(start 353.292918 -283.54782)
		(mid 353.090331 -283.754171)
		(end 353.016312 -284.033722)
		(width 0.0889)
		(layer "In6.Cu")
		(net "UPI_CPU0_CPU1_P2P2_DP<4>")
	)
	(arc
		(start 89.938606 -283.539184)
		(mid 89.807692 -283.402824)
		(end 89.760044 -283.219906)
		(width 0.0889)
		(layer "In6.Cu")
		(net "UPI_CPU0_CPU1_P2P2_DP<4>")
	)
	(arc
		(start 353.486212 -283.228542)
		(mid 353.433942 -283.410907)
		(end 353.299014 -283.544264)
		(width 0.0889)
		(layer "In6.Cu")
		(net "UPI_CPU0_CPU1_P2P2_DP<4>")
	)
	(arc
		(start 88.067896 -287.778698)
		(mid 88.255094 -287.728555)
		(end 88.442292 -287.778698)
		(width 0.0889)
		(layer "In6.Cu")
		(net "UPI_CPU0_CPU1_P2P2_DP<4>")
	)
	(arc
		(start 353.016312 -284.033722)
		(mid 352.968633 -284.216622)
		(end 352.83775 -284.353)
		(width 0.0889)
		(layer "In6.Cu")
		(net "UPI_CPU0_CPU1_P2P2_DP<4>")
	)
	(arc
		(start 89.477596 -282.730194)
		(mid 89.355928 -282.617339)
		(end 89.29497 -282.462986)
		(width 0.0889)
		(layer "In6.Cu")
		(net "UPI_CPU0_CPU1_P2P2_DP<4>")
	)
	(arc
		(start 89.477596 -285.336996)
		(mid 89.681931 -285.134391)
		(end 89.760044 -284.857444)
		(width 0.0889)
		(layer "In6.Cu")
		(net "UPI_CPU0_CPU1_P2P2_DP<4>")
	)
	(arc
		(start 87.880444 -288.103056)
		(mid 87.928123 -287.920156)
		(end 88.059006 -287.783778)
		(width 0.0889)
		(layer "In6.Cu")
		(net "UPI_CPU0_CPU1_P2P2_DP<4>")
	)
	(segment
		(start 90.134694 -279.428194)
		(end 90.134694 -279.964134)
		(width 0.13208)
		(layer "F.Cu")
		(net "UPI_CPU0_CPU1_P2P2_DP<3>")
	)
	(segment
		(start 352.641916 -280.77795)
		(end 352.641662 -280.778204)
		(width 0.13208)
		(layer "F.Cu")
		(net "UPI_CPU0_CPU1_P2P2_DP<3>")
	)
	(segment
		(start 352.641916 -280.242264)
		(end 352.641916 -280.77795)
		(width 0.13208)
		(layer "F.Cu")
		(net "UPI_CPU0_CPU1_P2P2_DP<3>")
	)
	(segment
		(start 352.1583 -291.275008)
		(end 352.1583 -291.41547)
		(width 0.0889)
		(layer "In6.Cu")
		(net "UPI_CPU0_CPU1_P2P2_DP<3>")
	)
	(segment
		(start 59.204098 -336.146902)
		(end 58.262266 -333.87284)
		(width 0.14732)
		(layer "In6.Cu")
		(net "UPI_CPU0_CPU1_P2P2_DP<3>")
	)
	(segment
		(start 62.11697 -362.722922)
		(end 61.92774 -362.644436)
		(width 0.14732)
		(layer "In6.Cu")
		(net "UPI_CPU0_CPU1_P2P2_DP<3>")
	)
	(segment
		(start 350.844104 -293.553388)
		(end 350.844104 -293.575486)
		(width 0.0889)
		(layer "In6.Cu")
		(net "UPI_CPU0_CPU1_P2P2_DP<3>")
	)
	(segment
		(start 55.44185 -330.134214)
		(end 55.238142 -330.112116)
		(width 0.14732)
		(layer "In6.Cu")
		(net "UPI_CPU0_CPU1_P2P2_DP<3>")
	)
	(segment
		(start 67.719956 -312.0136)
		(end 67.798442 -311.82437)
		(width 0.14732)
		(layer "In6.Cu")
		(net "UPI_CPU0_CPU1_P2P2_DP<3>")
	)
	(segment
		(start 60.801504 -359.547414)
		(end 60.660534 -359.2068)
		(width 0.14732)
		(layer "In6.Cu")
		(net "UPI_CPU0_CPU1_P2P2_DP<3>")
	)
	(segment
		(start 353.769676 -282.081986)
		(end 353.77755 -282.086558)
		(width 0.0889)
		(layer "In6.Cu")
		(net "UPI_CPU0_CPU1_P2P2_DP<3>")
	)
	(segment
		(start 61.019944 -360.452924)
		(end 60.723272 -359.736644)
		(width 0.14732)
		(layer "In6.Cu")
		(net "UPI_CPU0_CPU1_P2P2_DP<3>")
	)
	(segment
		(start 89.006934 -281.26817)
		(end 89.00795 -281.267662)
		(width 0.0889)
		(layer "In6.Cu")
		(net "UPI_CPU0_CPU1_P2P2_DP<3>")
	)
	(segment
		(start 352.641662 -280.778204)
		(end 352.798126 -280.507186)
		(width 0.0889)
		(layer "In6.Cu")
		(net "UPI_CPU0_CPU1_P2P2_DP<3>")
	)
	(segment
		(start 88.998806 -283.53893)
		(end 88.998806 -283.539184)
		(width 0.0889)
		(layer "In6.Cu")
		(net "UPI_CPU0_CPU1_P2P2_DP<3>")
	)
	(segment
		(start 350.844104 -293.575486)
		(end 350.844104 -293.802054)
		(width 0.14732)
		(layer "In6.Cu")
		(net "UPI_CPU0_CPU1_P2P2_DP<3>")
	)
	(segment
		(start 60.47105 -359.128568)
		(end 60.158376 -358.373172)
		(width 0.14732)
		(layer "In6.Cu")
		(net "UPI_CPU0_CPU1_P2P2_DP<3>")
	)
	(segment
		(start 65.746884 -312.674)
		(end 67.190366 -312.076338)
		(width 0.14732)
		(layer "In6.Cu")
		(net "UPI_CPU0_CPU1_P2P2_DP<3>")
	)
	(segment
		(start 59.39536 -317.485014)
		(end 59.39536 -316.75324)
		(width 0.14732)
		(layer "In6.Cu")
		(net "UPI_CPU0_CPU1_P2P2_DP<3>")
	)
	(segment
		(start 86.64956 -289.193224)
		(end 86.64956 -288.692082)
		(width 0.0889)
		(layer "In6.Cu")
		(net "UPI_CPU0_CPU1_P2P2_DP<3>")
	)
	(segment
		(start 352.838004 -287.608518)
		(end 352.829114 -287.613598)
		(width 0.0889)
		(layer "In6.Cu")
		(net "UPI_CPU0_CPU1_P2P2_DP<3>")
	)
	(segment
		(start 60.723272 -359.736644)
		(end 60.801504 -359.547414)
		(width 0.14732)
		(layer "In6.Cu")
		(net "UPI_CPU0_CPU1_P2P2_DP<3>")
	)
	(segment
		(start 352.798126 -280.507186)
		(end 352.876358 -280.486358)
		(width 0.0889)
		(layer "In6.Cu")
		(net "UPI_CPU0_CPU1_P2P2_DP<3>")
	)
	(segment
		(start 82.080354 -297.840908)
		(end 83.886548 -293.480236)
		(width 0.14732)
		(layer "In6.Cu")
		(net "UPI_CPU0_CPU1_P2P2_DP<3>")
	)
	(segment
		(start 89.82202 -279.964134)
		(end 90.134694 -279.964134)
		(width 0.0889)
		(layer "In6.Cu")
		(net "UPI_CPU0_CPU1_P2P2_DP<3>")
	)
	(segment
		(start 353.76866 -282.081478)
		(end 353.769676 -282.081986)
		(width 0.0889)
		(layer "In6.Cu")
		(net "UPI_CPU0_CPU1_P2P2_DP<3>")
	)
	(segment
		(start 53.59908 -328.073766)
		(end 53.59908 -325.272908)
		(width 0.14732)
		(layer "In6.Cu")
		(net "UPI_CPU0_CPU1_P2P2_DP<3>")
	)
	(segment
		(start 353.77755 -284.353)
		(end 353.769422 -284.357572)
		(width 0.0889)
		(layer "In6.Cu")
		(net "UPI_CPU0_CPU1_P2P2_DP<3>")
	)
	(segment
		(start 352.422714 -291.151056)
		(end 352.282252 -291.151056)
		(width 0.0889)
		(layer "In6.Cu")
		(net "UPI_CPU0_CPU1_P2P2_DP<3>")
	)
	(segment
		(start 351.695512 -291.878258)
		(end 350.886014 -292.687756)
		(width 0.0889)
		(layer "In6.Cu")
		(net "UPI_CPU0_CPU1_P2P2_DP<3>")
	)
	(segment
		(start 86.691724 -289.235388)
		(end 86.64956 -289.193224)
		(width 0.0889)
		(layer "In6.Cu")
		(net "UPI_CPU0_CPU1_P2P2_DP<3>")
	)
	(segment
		(start 87.119206 -287.783778)
		(end 87.128096 -287.778698)
		(width 0.0889)
		(layer "In6.Cu")
		(net "UPI_CPU0_CPU1_P2P2_DP<3>")
	)
	(segment
		(start 352.362262 -289.446462)
		(end 352.362262 -289.446208)
		(width 0.0889)
		(layer "In6.Cu")
		(net "UPI_CPU0_CPU1_P2P2_DP<3>")
	)
	(segment
		(start 88.528906 -285.342076)
		(end 88.537796 -285.336996)
		(width 0.0889)
		(layer "In6.Cu")
		(net "UPI_CPU0_CPU1_P2P2_DP<3>")
	)
	(segment
		(start 61.664596 -362.009182)
		(end 61.743082 -361.819952)
		(width 0.14732)
		(layer "In6.Cu")
		(net "UPI_CPU0_CPU1_P2P2_DP<3>")
	)
	(segment
		(start 55.238142 -330.112116)
		(end 53.59908 -328.073766)
		(width 0.14732)
		(layer "In6.Cu")
		(net "UPI_CPU0_CPU1_P2P2_DP<3>")
	)
	(segment
		(start 67.379596 -312.15457)
		(end 67.719956 -312.0136)
		(width 0.14732)
		(layer "In6.Cu")
		(net "UPI_CPU0_CPU1_P2P2_DP<3>")
	)
	(segment
		(start 88.537796 -286.964882)
		(end 88.549988 -286.95777)
		(width 0.0889)
		(layer "In6.Cu")
		(net "UPI_CPU0_CPU1_P2P2_DP<3>")
	)
	(segment
		(start 56.2737 -323.093588)
		(end 57.618884 -321.748404)
		(width 0.14732)
		(layer "In6.Cu")
		(net "UPI_CPU0_CPU1_P2P2_DP<3>")
	)
	(segment
		(start 277.964392 -347.704156)
		(end 277.964392 -371.314472)
		(width 0.14732)
		(layer "In6.Cu")
		(net "UPI_CPU0_CPU1_P2P2_DP<3>")
	)
	(segment
		(start 353.016566 -287.279334)
		(end 353.016566 -287.28924)
		(width 0.0889)
		(layer "In6.Cu")
		(net "UPI_CPU0_CPU1_P2P2_DP<3>")
	)
	(segment
		(start 88.998806 -284.52826)
		(end 89.013792 -284.51937)
		(width 0.0889)
		(layer "In6.Cu")
		(net "UPI_CPU0_CPU1_P2P2_DP<3>")
	)
	(segment
		(start 89.290144 -280.793698)
		(end 89.290144 -280.778204)
		(width 0.0889)
		(layer "In6.Cu")
		(net "UPI_CPU0_CPU1_P2P2_DP<3>")
	)
	(segment
		(start 61.412628 -361.401106)
		(end 61.271912 -361.061)
		(width 0.14732)
		(layer "In6.Cu")
		(net "UPI_CPU0_CPU1_P2P2_DP<3>")
	)
	(segment
		(start 89.468706 -280.458926)
		(end 89.477596 -280.453846)
		(width 0.0889)
		(layer "In6.Cu")
		(net "UPI_CPU0_CPU1_P2P2_DP<3>")
	)
	(segment
		(start 343.881456 -307.62829)
		(end 339.960966 -309.251858)
		(width 0.14732)
		(layer "In6.Cu")
		(net "UPI_CPU0_CPU1_P2P2_DP<3>")
	)
	(segment
		(start 65.668398 -312.863484)
		(end 65.746884 -312.674)
		(width 0.14732)
		(layer "In6.Cu")
		(net "UPI_CPU0_CPU1_P2P2_DP<3>")
	)
	(segment
		(start 350.886014 -293.511478)
		(end 350.844104 -293.553388)
		(width 0.0889)
		(layer "In6.Cu")
		(net "UPI_CPU0_CPU1_P2P2_DP<3>")
	)
	(segment
		(start 86.64956 -288.692082)
		(end 86.940644 -288.400998)
		(width 0.0889)
		(layer "In6.Cu")
		(net "UPI_CPU0_CPU1_P2P2_DP<3>")
	)
	(segment
		(start 353.29876 -285.171896)
		(end 353.292664 -285.175452)
		(width 0.0889)
		(layer "In6.Cu")
		(net "UPI_CPU0_CPU1_P2P2_DP<3>")
	)
	(segment
		(start 70.536054 -375.414032)
		(end 64.869822 -369.7478)
		(width 0.14732)
		(layer "In6.Cu")
		(net "UPI_CPU0_CPU1_P2P2_DP<3>")
	)
	(segment
		(start 350.844104 -293.802054)
		(end 350.84385 -293.802308)
		(width 0.14732)
		(layer "In6.Cu")
		(net "UPI_CPU0_CPU1_P2P2_DP<3>")
	)
	(segment
		(start 60.095638 -357.843328)
		(end 59.906408 -357.765096)
		(width 0.14732)
		(layer "In6.Cu")
		(net "UPI_CPU0_CPU1_P2P2_DP<3>")
	)
	(segment
		(start 57.618884 -321.748404)
		(end 57.618884 -318.56934)
		(width 0.14732)
		(layer "In6.Cu")
		(net "UPI_CPU0_CPU1_P2P2_DP<3>")
	)
	(segment
		(start 60.236608 -358.183942)
		(end 60.095638 -357.843328)
		(width 0.14732)
		(layer "In6.Cu")
		(net "UPI_CPU0_CPU1_P2P2_DP<3>")
	)
	(segment
		(start 283.882338 -341.78621)
		(end 277.964392 -347.704156)
		(width 0.14732)
		(layer "In6.Cu")
		(net "UPI_CPU0_CPU1_P2P2_DP<3>")
	)
	(segment
		(start 65.328038 -313.004454)
		(end 65.668398 -312.863484)
		(width 0.14732)
		(layer "In6.Cu")
		(net "UPI_CPU0_CPU1_P2P2_DP<3>")
	)
	(segment
		(start 352.546412 -291.027358)
		(end 352.422714 -291.151056)
		(width 0.0889)
		(layer "In6.Cu")
		(net "UPI_CPU0_CPU1_P2P2_DP<3>")
	)
	(segment
		(start 60.660534 -359.2068)
		(end 60.47105 -359.128568)
		(width 0.14732)
		(layer "In6.Cu")
		(net "UPI_CPU0_CPU1_P2P2_DP<3>")
	)
	(segment
		(start 58.884312 -317.996062)
		(end 59.39536 -317.485014)
		(width 0.14732)
		(layer "In6.Cu")
		(net "UPI_CPU0_CPU1_P2P2_DP<3>")
	)
	(segment
		(start 126.823724 -390.19861)
		(end 94.737682 -385.439158)
		(width 0.14732)
		(layer "In6.Cu")
		(net "UPI_CPU0_CPU1_P2P2_DP<3>")
	)
	(segment
		(start 353.30765 -285.166816)
		(end 353.29876 -285.171896)
		(width 0.0889)
		(layer "In6.Cu")
		(net "UPI_CPU0_CPU1_P2P2_DP<3>")
	)
	(segment
		(start 94.737682 -385.439158)
		(end 70.536054 -375.414032)
		(width 0.14732)
		(layer "In6.Cu")
		(net "UPI_CPU0_CPU1_P2P2_DP<3>")
	)
	(segment
		(start 320.246248 -330.684124)
		(end 310.313832 -340.61654)
		(width 0.14732)
		(layer "In6.Cu")
		(net "UPI_CPU0_CPU1_P2P2_DP<3>")
	)
	(segment
		(start 56.536844 -331.496162)
		(end 56.305704 -331.208888)
		(width 0.14732)
		(layer "In6.Cu")
		(net "UPI_CPU0_CPU1_P2P2_DP<3>")
	)
	(segment
		(start 88.820244 -284.857444)
		(end 88.820244 -284.847538)
		(width 0.0889)
		(layer "In6.Cu")
		(net "UPI_CPU0_CPU1_P2P2_DP<3>")
	)
	(segment
		(start 86.691724 -289.257486)
		(end 86.691724 -289.235388)
		(width 0.0889)
		(layer "In6.Cu")
		(net "UPI_CPU0_CPU1_P2P2_DP<3>")
	)
	(segment
		(start 55.650638 -330.624942)
		(end 55.672736 -330.421488)
		(width 0.14732)
		(layer "In6.Cu")
		(net "UPI_CPU0_CPU1_P2P2_DP<3>")
	)
	(segment
		(start 62.385702 -314.668154)
		(end 63.461138 -314.222638)
		(width 0.14732)
		(layer "In6.Cu")
		(net "UPI_CPU0_CPU1_P2P2_DP<3>")
	)
	(segment
		(start 63.461138 -314.222638)
		(end 63.461138 -314.222892)
		(width 0.14732)
		(layer "In6.Cu")
		(net "UPI_CPU0_CPU1_P2P2_DP<3>")
	)
	(segment
		(start 61.602112 -361.479592)
		(end 61.412628 -361.401106)
		(width 0.14732)
		(layer "In6.Cu")
		(net "UPI_CPU0_CPU1_P2P2_DP<3>")
	)
	(segment
		(start 86.940644 -288.400998)
		(end 86.940644 -288.103056)
		(width 0.0889)
		(layer "In6.Cu")
		(net "UPI_CPU0_CPU1_P2P2_DP<3>")
	)
	(segment
		(start 61.271912 -361.061)
		(end 61.350144 -360.872024)
		(width 0.14732)
		(layer "In6.Cu")
		(net "UPI_CPU0_CPU1_P2P2_DP<3>")
	)
	(segment
		(start 87.589106 -286.969962)
		(end 87.597996 -286.964882)
		(width 0.0889)
		(layer "In6.Cu")
		(net "UPI_CPU0_CPU1_P2P2_DP<3>")
	)
	(segment
		(start 350.886014 -292.687756)
		(end 350.886014 -293.511478)
		(width 0.0889)
		(layer "In6.Cu")
		(net "UPI_CPU0_CPU1_P2P2_DP<3>")
	)
	(segment
		(start 59.429904 -356.614984)
		(end 59.204098 -356.069646)
		(width 0.14732)
		(layer "In6.Cu")
		(net "UPI_CPU0_CPU1_P2P2_DP<3>")
	)
	(segment
		(start 61.209428 -360.53141)
		(end 61.019944 -360.452924)
		(width 0.14732)
		(layer "In6.Cu")
		(net "UPI_CPU0_CPU1_P2P2_DP<3>")
	)
	(segment
		(start 353.016312 -285.661354)
		(end 353.016312 -285.668974)
		(width 0.0889)
		(layer "In6.Cu")
		(net "UPI_CPU0_CPU1_P2P2_DP<3>")
	)
	(segment
		(start 352.1583 -291.41547)
		(end 351.959926 -291.613844)
		(width 0.0889)
		(layer "In6.Cu")
		(net "UPI_CPU0_CPU1_P2P2_DP<3>")
	)
	(segment
		(start 86.691724 -290.67506)
		(end 86.691724 -289.257486)
		(width 0.14732)
		(layer "In6.Cu")
		(net "UPI_CPU0_CPU1_P2P2_DP<3>")
	)
	(segment
		(start 63.461138 -314.222892)
		(end 63.511684 -314.20181)
		(width 0.14732)
		(layer "In6.Cu")
		(net "UPI_CPU0_CPU1_P2P2_DP<3>")
	)
	(segment
		(start 88.52916 -282.086558)
		(end 88.53805 -282.081478)
		(width 0.0889)
		(layer "In6.Cu")
		(net "UPI_CPU0_CPU1_P2P2_DP<3>")
	)
	(segment
		(start 352.076766 -288.898584)
		(end 352.076766 -289.114738)
		(width 0.0889)
		(layer "In6.Cu")
		(net "UPI_CPU0_CPU1_P2P2_DP<3>")
	)
	(segment
		(start 354.426012 -283.212794)
		(end 354.426012 -283.219906)
		(width 0.0889)
		(layer "In6.Cu")
		(net "UPI_CPU0_CPU1_P2P2_DP<3>")
	)
	(segment
		(start 352.282252 -291.151056)
		(end 352.1583 -291.275008)
		(width 0.0889)
		(layer "In6.Cu")
		(net "UPI_CPU0_CPU1_P2P2_DP<3>")
	)
	(segment
		(start 88.99906 -281.272742)
		(end 89.006934 -281.26817)
		(width 0.0889)
		(layer "In6.Cu")
		(net "UPI_CPU0_CPU1_P2P2_DP<3>")
	)
	(segment
		(start 352.368104 -288.422334)
		(end 352.359214 -288.427414)
		(width 0.0889)
		(layer "In6.Cu")
		(net "UPI_CPU0_CPU1_P2P2_DP<3>")
	)
	(segment
		(start 89.756742 -280.029412)
		(end 89.82202 -279.964134)
		(width 0.0889)
		(layer "In6.Cu")
		(net "UPI_CPU0_CPU1_P2P2_DP<3>")
	)
	(segment
		(start 61.350144 -360.872024)
		(end 61.209428 -360.53141)
		(width 0.14732)
		(layer "In6.Cu")
		(net "UPI_CPU0_CPU1_P2P2_DP<3>")
	)
	(segment
		(start 353.486212 -284.837632)
		(end 353.486212 -284.847538)
		(width 0.0889)
		(layer "In6.Cu")
		(net "UPI_CPU0_CPU1_P2P2_DP<3>")
	)
	(segment
		(start 83.886548 -293.480236)
		(end 86.691724 -290.67506)
		(width 0.14732)
		(layer "In6.Cu")
		(net "UPI_CPU0_CPU1_P2P2_DP<3>")
	)
	(segment
		(start 353.486212 -286.466788)
		(end 353.486212 -286.48406)
		(width 0.0889)
		(layer "In6.Cu")
		(net "UPI_CPU0_CPU1_P2P2_DP<3>")
	)
	(segment
		(start 161.074862 -390.19861)
		(end 126.823724 -390.19861)
		(width 0.14732)
		(layer "In6.Cu")
		(net "UPI_CPU0_CPU1_P2P2_DP<3>")
	)
	(segment
		(start 54.781704 -324.090284)
		(end 56.2737 -323.093588)
		(width 0.14732)
		(layer "In6.Cu")
		(net "UPI_CPU0_CPU1_P2P2_DP<3>")
	)
	(segment
		(start 268.119606 -381.159258)
		(end 161.074862 -390.19861)
		(width 0.14732)
		(layer "In6.Cu")
		(net "UPI_CPU0_CPU1_P2P2_DP<3>")
	)
	(segment
		(start 88.820498 -286.475424)
		(end 88.820498 -286.467804)
		(width 0.0889)
		(layer "In6.Cu")
		(net "UPI_CPU0_CPU1_P2P2_DP<3>")
	)
	(segment
		(start 88.537796 -285.985712)
		(end 88.528906 -285.980632)
		(width 0.0889)
		(layer "In6.Cu")
		(net "UPI_CPU0_CPU1_P2P2_DP<3>")
	)
	(segment
		(start 59.39536 -316.75324)
		(end 59.655964 -316.492636)
		(width 0.14732)
		(layer "In6.Cu")
		(net "UPI_CPU0_CPU1_P2P2_DP<3>")
	)
	(segment
		(start 354.24745 -283.539184)
		(end 354.23856 -283.544264)
		(width 0.0889)
		(layer "In6.Cu")
		(net "UPI_CPU0_CPU1_P2P2_DP<3>")
	)
	(segment
		(start 58.192162 -317.996062)
		(end 58.884312 -317.996062)
		(width 0.14732)
		(layer "In6.Cu")
		(net "UPI_CPU0_CPU1_P2P2_DP<3>")
	)
	(segment
		(start 62.25794 -363.063536)
		(end 62.11697 -362.722922)
		(width 0.14732)
		(layer "In6.Cu")
		(net "UPI_CPU0_CPU1_P2P2_DP<3>")
	)
	(segment
		(start 321.46113 -327.751694)
		(end 320.246248 -330.684124)
		(width 0.14732)
		(layer "In6.Cu")
		(net "UPI_CPU0_CPU1_P2P2_DP<3>")
	)
	(segment
		(start 56.305704 -331.208888)
		(end 56.102504 -331.18679)
		(width 0.14732)
		(layer "In6.Cu")
		(net "UPI_CPU0_CPU1_P2P2_DP<3>")
	)
	(segment
		(start 55.672736 -330.421488)
		(end 55.44185 -330.134214)
		(width 0.14732)
		(layer "In6.Cu")
		(net "UPI_CPU0_CPU1_P2P2_DP<3>")
	)
	(segment
		(start 62.179708 -363.252512)
		(end 62.25794 -363.063536)
		(width 0.14732)
		(layer "In6.Cu")
		(net "UPI_CPU0_CPU1_P2P2_DP<3>")
	)
	(segment
		(start 59.655964 -316.492636)
		(end 62.385702 -314.668154)
		(width 0.14732)
		(layer "In6.Cu")
		(net "UPI_CPU0_CPU1_P2P2_DP<3>")
	)
	(segment
		(start 349.814642 -301.695104)
		(end 343.881456 -307.62829)
		(width 0.14732)
		(layer "In6.Cu")
		(net "UPI_CPU0_CPU1_P2P2_DP<3>")
	)
	(segment
		(start 64.539114 -313.17438)
		(end 65.138808 -312.925968)
		(width 0.14732)
		(layer "In6.Cu")
		(net "UPI_CPU0_CPU1_P2P2_DP<3>")
	)
	(segment
		(start 310.313832 -340.61654)
		(end 286.706056 -340.61654)
		(width 0.14732)
		(layer "In6.Cu")
		(net "UPI_CPU0_CPU1_P2P2_DP<3>")
	)
	(segment
		(start 353.299014 -281.267662)
		(end 353.307904 -281.272742)
		(width 0.0889)
		(layer "In6.Cu")
		(net "UPI_CPU0_CPU1_P2P2_DP<3>")
	)
	(segment
		(start 61.743082 -361.819952)
		(end 61.602112 -361.479592)
		(width 0.14732)
		(layer "In6.Cu")
		(net "UPI_CPU0_CPU1_P2P2_DP<3>")
	)
	(segment
		(start 286.706056 -340.61654)
		(end 283.882338 -341.78621)
		(width 0.14732)
		(layer "In6.Cu")
		(net "UPI_CPU0_CPU1_P2P2_DP<3>")
	)
	(segment
		(start 352.546412 -290.04641)
		(end 352.447352 -290.14547)
		(width 0.0889)
		(layer "In6.Cu")
		(net "UPI_CPU0_CPU1_P2P2_DP<3>")
	)
	(segment
		(start 354.23856 -283.544264)
		(end 354.232464 -283.54782)
		(width 0.0889)
		(layer "In6.Cu")
		(net "UPI_CPU0_CPU1_P2P2_DP<3>")
	)
	(segment
		(start 56.102504 -331.18679)
		(end 55.650638 -330.624942)
		(width 0.14732)
		(layer "In6.Cu")
		(net "UPI_CPU0_CPU1_P2P2_DP<3>")
	)
	(segment
		(start 350.84385 -299.210222)
		(end 349.814642 -301.695104)
		(width 0.14732)
		(layer "In6.Cu")
		(net "UPI_CPU0_CPU1_P2P2_DP<3>")
	)
	(segment
		(start 353.956112 -282.405836)
		(end 353.956366 -282.42006)
		(width 0.0889)
		(layer "In6.Cu")
		(net "UPI_CPU0_CPU1_P2P2_DP<3>")
	)
	(segment
		(start 353.016312 -280.778204)
		(end 353.016566 -280.785824)
		(width 0.0889)
		(layer "In6.Cu")
		(net "UPI_CPU0_CPU1_P2P2_DP<3>")
	)
	(segment
		(start 89.013792 -284.51937)
		(end 89.013792 -284.519624)
		(width 0.0889)
		(layer "In6.Cu")
		(net "UPI_CPU0_CPU1_P2P2_DP<3>")
	)
	(segment
		(start 59.204098 -356.069646)
		(end 59.204098 -336.146902)
		(width 0.14732)
		(layer "In6.Cu")
		(net "UPI_CPU0_CPU1_P2P2_DP<3>")
	)
	(segment
		(start 63.511684 -314.20181)
		(end 64.539114 -313.17438)
		(width 0.14732)
		(layer "In6.Cu")
		(net "UPI_CPU0_CPU1_P2P2_DP<3>")
	)
	(segment
		(start 352.546412 -290.41979)
		(end 352.546412 -291.027358)
		(width 0.0889)
		(layer "In6.Cu")
		(net "UPI_CPU0_CPU1_P2P2_DP<3>")
	)
	(segment
		(start 67.190366 -312.076338)
		(end 67.379596 -312.15457)
		(width 0.14732)
		(layer "In6.Cu")
		(net "UPI_CPU0_CPU1_P2P2_DP<3>")
	)
	(segment
		(start 56.514746 -331.699616)
		(end 56.536844 -331.496162)
		(width 0.14732)
		(layer "In6.Cu")
		(net "UPI_CPU0_CPU1_P2P2_DP<3>")
	)
	(segment
		(start 88.53805 -282.081478)
		(end 88.544146 -282.077922)
		(width 0.0889)
		(layer "In6.Cu")
		(net "UPI_CPU0_CPU1_P2P2_DP<3>")
	)
	(segment
		(start 64.869822 -369.7478)
		(end 62.179708 -363.252512)
		(width 0.14732)
		(layer "In6.Cu")
		(net "UPI_CPU0_CPU1_P2P2_DP<3>")
	)
	(segment
		(start 59.760358 -357.03383)
		(end 59.619388 -356.69347)
		(width 0.14732)
		(layer "In6.Cu")
		(net "UPI_CPU0_CPU1_P2P2_DP<3>")
	)
	(segment
		(start 351.819464 -291.613844)
		(end 351.695512 -291.737796)
		(width 0.0889)
		(layer "In6.Cu")
		(net "UPI_CPU0_CPU1_P2P2_DP<3>")
	)
	(segment
		(start 352.447352 -290.32073)
		(end 352.546412 -290.41979)
		(width 0.0889)
		(layer "In6.Cu")
		(net "UPI_CPU0_CPU1_P2P2_DP<3>")
	)
	(segment
		(start 60.158376 -358.373172)
		(end 60.236608 -358.183942)
		(width 0.14732)
		(layer "In6.Cu")
		(net "UPI_CPU0_CPU1_P2P2_DP<3>")
	)
	(segment
		(start 53.59908 -325.272908)
		(end 54.781704 -324.090284)
		(width 0.14732)
		(layer "In6.Cu")
		(net "UPI_CPU0_CPU1_P2P2_DP<3>")
	)
	(segment
		(start 350.84385 -293.802308)
		(end 350.84385 -299.210222)
		(width 0.14732)
		(layer "In6.Cu")
		(net "UPI_CPU0_CPU1_P2P2_DP<3>")
	)
	(segment
		(start 67.798442 -311.82437)
		(end 68.307966 -311.613296)
		(width 0.14732)
		(layer "In6.Cu")
		(net "UPI_CPU0_CPU1_P2P2_DP<3>")
	)
	(segment
		(start 339.960966 -309.251858)
		(end 321.46113 -327.751694)
		(width 0.14732)
		(layer "In6.Cu")
		(net "UPI_CPU0_CPU1_P2P2_DP<3>")
	)
	(segment
		(start 353.769422 -284.357572)
		(end 353.76866 -284.35808)
		(width 0.0889)
		(layer "In6.Cu")
		(net "UPI_CPU0_CPU1_P2P2_DP<3>")
	)
	(segment
		(start 351.695512 -291.737796)
		(end 351.695512 -291.878258)
		(width 0.0889)
		(layer "In6.Cu")
		(net "UPI_CPU0_CPU1_P2P2_DP<3>")
	)
	(segment
		(start 65.138808 -312.925968)
		(end 65.328038 -313.004454)
		(width 0.14732)
		(layer "In6.Cu")
		(net "UPI_CPU0_CPU1_P2P2_DP<3>")
	)
	(segment
		(start 61.92774 -362.644436)
		(end 61.664596 -362.009182)
		(width 0.14732)
		(layer "In6.Cu")
		(net "UPI_CPU0_CPU1_P2P2_DP<3>")
	)
	(segment
		(start 59.619388 -356.69347)
		(end 59.429904 -356.614984)
		(width 0.14732)
		(layer "In6.Cu")
		(net "UPI_CPU0_CPU1_P2P2_DP<3>")
	)
	(segment
		(start 352.546412 -289.64509)
		(end 352.546412 -290.04641)
		(width 0.0889)
		(layer "In6.Cu")
		(net "UPI_CPU0_CPU1_P2P2_DP<3>")
	)
	(segment
		(start 68.307966 -311.613296)
		(end 82.080354 -297.840908)
		(width 0.14732)
		(layer "In6.Cu")
		(net "UPI_CPU0_CPU1_P2P2_DP<3>")
	)
	(segment
		(start 58.262266 -333.87284)
		(end 56.514746 -331.699616)
		(width 0.14732)
		(layer "In6.Cu")
		(net "UPI_CPU0_CPU1_P2P2_DP<3>")
	)
	(segment
		(start 277.964392 -371.314472)
		(end 268.119606 -381.159258)
		(width 0.14732)
		(layer "In6.Cu")
		(net "UPI_CPU0_CPU1_P2P2_DP<3>")
	)
	(segment
		(start 88.53805 -282.730194)
		(end 88.52916 -282.725114)
		(width 0.0889)
		(layer "In6.Cu")
		(net "UPI_CPU0_CPU1_P2P2_DP<3>")
	)
	(segment
		(start 351.959926 -291.613844)
		(end 351.819464 -291.613844)
		(width 0.0889)
		(layer "In6.Cu")
		(net "UPI_CPU0_CPU1_P2P2_DP<3>")
	)
	(segment
		(start 59.906408 -357.765096)
		(end 59.681872 -357.22306)
		(width 0.14732)
		(layer "In6.Cu")
		(net "UPI_CPU0_CPU1_P2P2_DP<3>")
	)
	(segment
		(start 59.681872 -357.22306)
		(end 59.760358 -357.03383)
		(width 0.14732)
		(layer "In6.Cu")
		(net "UPI_CPU0_CPU1_P2P2_DP<3>")
	)
	(segment
		(start 88.820244 -283.219906)
		(end 88.820244 -283.197808)
		(width 0.0889)
		(layer "In6.Cu")
		(net "UPI_CPU0_CPU1_P2P2_DP<3>")
	)
	(segment
		(start 57.618884 -318.56934)
		(end 58.192162 -317.996062)
		(width 0.14732)
		(layer "In6.Cu")
		(net "UPI_CPU0_CPU1_P2P2_DP<3>")
	)
	(segment
		(start 353.486466 -281.59202)
		(end 353.486466 -281.607514)
		(width 0.0889)
		(layer "In6.Cu")
		(net "UPI_CPU0_CPU1_P2P2_DP<3>")
	)
	(segment
		(start 352.447352 -290.14547)
		(end 352.447352 -290.32073)
		(width 0.0889)
		(layer "In6.Cu")
		(net "UPI_CPU0_CPU1_P2P2_DP<3>")
	)
	(segment
		(start 89.013792 -283.54782)
		(end 88.998806 -283.53893)
		(width 0.0889)
		(layer "In6.Cu")
		(net "UPI_CPU0_CPU1_P2P2_DP<3>")
	)
	(segment
		(start 352.546666 -288.09315)
		(end 352.546666 -288.103056)
		(width 0.0889)
		(layer "In6.Cu")
		(net "UPI_CPU0_CPU1_P2P2_DP<3>")
	)
	(segment
		(start 87.410544 -287.299146)
		(end 87.410544 -287.28924)
		(width 0.0889)
		(layer "In6.Cu")
		(net "UPI_CPU0_CPU1_P2P2_DP<3>")
	)
	(arc
		(start 88.820244 -283.197808)
		(mid 88.739333 -282.92768)
		(end 88.53805 -282.730194)
		(width 0.0889)
		(layer "In6.Cu")
		(net "UPI_CPU0_CPU1_P2P2_DP<3>")
	)
	(arc
		(start 352.546666 -288.103056)
		(mid 352.498987 -288.285956)
		(end 352.368104 -288.422334)
		(width 0.0889)
		(layer "In6.Cu")
		(net "UPI_CPU0_CPU1_P2P2_DP<3>")
	)
	(arc
		(start 89.290144 -280.778204)
		(mid 89.337823 -280.595304)
		(end 89.468706 -280.458926)
		(width 0.0889)
		(layer "In6.Cu")
		(net "UPI_CPU0_CPU1_P2P2_DP<3>")
	)
	(arc
		(start 87.972392 -286.964882)
		(mid 88.255094 -287.040658)
		(end 88.537796 -286.964882)
		(width 0.0889)
		(layer "In6.Cu")
		(net "UPI_CPU0_CPU1_P2P2_DP<3>")
	)
	(arc
		(start 89.013792 -284.519624)
		(mid 89.290242 -284.033722)
		(end 89.013792 -283.54782)
		(width 0.0889)
		(layer "In6.Cu")
		(net "UPI_CPU0_CPU1_P2P2_DP<3>")
	)
	(arc
		(start 88.537796 -285.336996)
		(mid 88.742131 -285.134391)
		(end 88.820244 -284.857444)
		(width 0.0889)
		(layer "In6.Cu")
		(net "UPI_CPU0_CPU1_P2P2_DP<3>")
	)
	(arc
		(start 87.128096 -287.778698)
		(mid 87.332431 -287.576093)
		(end 87.410544 -287.299146)
		(width 0.0889)
		(layer "In6.Cu")
		(net "UPI_CPU0_CPU1_P2P2_DP<3>")
	)
	(arc
		(start 352.359214 -288.427414)
		(mid 352.156928 -288.626395)
		(end 352.076766 -288.898584)
		(width 0.0889)
		(layer "In6.Cu")
		(net "UPI_CPU0_CPU1_P2P2_DP<3>")
	)
	(arc
		(start 88.528906 -285.980632)
		(mid 88.401013 -285.84957)
		(end 88.350598 -285.673546)
		(width 0.0889)
		(layer "In6.Cu")
		(net "UPI_CPU0_CPU1_P2P2_DP<3>")
	)
	(arc
		(start 353.486466 -281.607514)
		(mid 353.565836 -281.881248)
		(end 353.76866 -282.081478)
		(width 0.0889)
		(layer "In6.Cu")
		(net "UPI_CPU0_CPU1_P2P2_DP<3>")
	)
	(arc
		(start 88.820244 -284.847538)
		(mid 88.867923 -284.664638)
		(end 88.998806 -284.52826)
		(width 0.0889)
		(layer "In6.Cu")
		(net "UPI_CPU0_CPU1_P2P2_DP<3>")
	)
	(arc
		(start 353.016566 -287.28924)
		(mid 352.968887 -287.47214)
		(end 352.838004 -287.608518)
		(width 0.0889)
		(layer "In6.Cu")
		(net "UPI_CPU0_CPU1_P2P2_DP<3>")
	)
	(arc
		(start 353.486212 -286.48406)
		(mid 353.433942 -286.666425)
		(end 353.299014 -286.799782)
		(width 0.0889)
		(layer "In6.Cu")
		(net "UPI_CPU0_CPU1_P2P2_DP<3>")
	)
	(arc
		(start 353.016312 -285.668974)
		(mid 353.093941 -285.947387)
		(end 353.299014 -286.151066)
		(width 0.0889)
		(layer "In6.Cu")
		(net "UPI_CPU0_CPU1_P2P2_DP<3>")
	)
	(arc
		(start 352.076766 -289.114738)
		(mid 352.188104 -289.307638)
		(end 352.362262 -289.446462)
		(width 0.0889)
		(layer "In6.Cu")
		(net "UPI_CPU0_CPU1_P2P2_DP<3>")
	)
	(arc
		(start 353.486212 -284.847538)
		(mid 353.438533 -285.030438)
		(end 353.30765 -285.166816)
		(width 0.0889)
		(layer "In6.Cu")
		(net "UPI_CPU0_CPU1_P2P2_DP<3>")
	)
	(arc
		(start 353.307904 -281.272742)
		(mid 353.438818 -281.409102)
		(end 353.486466 -281.59202)
		(width 0.0889)
		(layer "In6.Cu")
		(net "UPI_CPU0_CPU1_P2P2_DP<3>")
	)
	(arc
		(start 354.232464 -283.54782)
		(mid 354.030051 -283.754233)
		(end 353.956112 -284.033722)
		(width 0.0889)
		(layer "In6.Cu")
		(net "UPI_CPU0_CPU1_P2P2_DP<3>")
	)
	(arc
		(start 89.477596 -280.453846)
		(mid 89.66151 -280.283801)
		(end 89.753948 -280.051002)
		(width 0.0889)
		(layer "In6.Cu")
		(net "UPI_CPU0_CPU1_P2P2_DP<3>")
	)
	(arc
		(start 352.876358 -280.486358)
		(mid 352.979503 -280.616383)
		(end 353.016312 -280.778204)
		(width 0.0889)
		(layer "In6.Cu")
		(net "UPI_CPU0_CPU1_P2P2_DP<3>")
	)
	(arc
		(start 353.76866 -284.35808)
		(mid 353.564325 -284.560685)
		(end 353.486212 -284.837632)
		(width 0.0889)
		(layer "In6.Cu")
		(net "UPI_CPU0_CPU1_P2P2_DP<3>")
	)
	(arc
		(start 353.016566 -280.785824)
		(mid 353.094107 -281.064088)
		(end 353.299014 -281.267662)
		(width 0.0889)
		(layer "In6.Cu")
		(net "UPI_CPU0_CPU1_P2P2_DP<3>")
	)
	(arc
		(start 354.426012 -283.219906)
		(mid 354.378333 -283.402806)
		(end 354.24745 -283.539184)
		(width 0.0889)
		(layer "In6.Cu")
		(net "UPI_CPU0_CPU1_P2P2_DP<3>")
	)
	(arc
		(start 353.956112 -284.033722)
		(mid 353.908433 -284.216622)
		(end 353.77755 -284.353)
		(width 0.0889)
		(layer "In6.Cu")
		(net "UPI_CPU0_CPU1_P2P2_DP<3>")
	)
	(arc
		(start 87.410544 -287.28924)
		(mid 87.458223 -287.10634)
		(end 87.589106 -286.969962)
		(width 0.0889)
		(layer "In6.Cu")
		(net "UPI_CPU0_CPU1_P2P2_DP<3>")
	)
	(arc
		(start 353.292664 -285.175452)
		(mid 353.090251 -285.381865)
		(end 353.016312 -285.661354)
		(width 0.0889)
		(layer "In6.Cu")
		(net "UPI_CPU0_CPU1_P2P2_DP<3>")
	)
	(arc
		(start 353.299014 -286.799782)
		(mid 353.094679 -287.002387)
		(end 353.016566 -287.279334)
		(width 0.0889)
		(layer "In6.Cu")
		(net "UPI_CPU0_CPU1_P2P2_DP<3>")
	)
	(arc
		(start 88.549988 -286.95777)
		(mid 88.748216 -286.751922)
		(end 88.820498 -286.475424)
		(width 0.0889)
		(layer "In6.Cu")
		(net "UPI_CPU0_CPU1_P2P2_DP<3>")
	)
	(arc
		(start 353.299014 -286.151066)
		(mid 353.433947 -286.28442)
		(end 353.486212 -286.466788)
		(width 0.0889)
		(layer "In6.Cu")
		(net "UPI_CPU0_CPU1_P2P2_DP<3>")
	)
	(arc
		(start 89.753948 -280.051002)
		(mid 89.755448 -280.04022)
		(end 89.756742 -280.029412)
		(width 0.0889)
		(layer "In6.Cu")
		(net "UPI_CPU0_CPU1_P2P2_DP<3>")
	)
	(arc
		(start 89.00795 -281.267662)
		(mid 89.210773 -281.067431)
		(end 89.290144 -280.793698)
		(width 0.0889)
		(layer "In6.Cu")
		(net "UPI_CPU0_CPU1_P2P2_DP<3>")
	)
	(arc
		(start 88.820498 -286.467804)
		(mid 88.742869 -286.189391)
		(end 88.537796 -285.985712)
		(width 0.0889)
		(layer "In6.Cu")
		(net "UPI_CPU0_CPU1_P2P2_DP<3>")
	)
	(arc
		(start 87.597996 -286.964882)
		(mid 87.785194 -286.914739)
		(end 87.972392 -286.964882)
		(width 0.0889)
		(layer "In6.Cu")
		(net "UPI_CPU0_CPU1_P2P2_DP<3>")
	)
	(arc
		(start 88.52916 -282.725114)
		(mid 88.350442 -282.405836)
		(end 88.52916 -282.086558)
		(width 0.0889)
		(layer "In6.Cu")
		(net "UPI_CPU0_CPU1_P2P2_DP<3>")
	)
	(arc
		(start 353.956366 -282.42006)
		(mid 354.035418 -282.694533)
		(end 354.23856 -282.895294)
		(width 0.0889)
		(layer "In6.Cu")
		(net "UPI_CPU0_CPU1_P2P2_DP<3>")
	)
	(arc
		(start 88.544146 -282.077922)
		(mid 88.746559 -281.871509)
		(end 88.820498 -281.59202)
		(width 0.0889)
		(layer "In6.Cu")
		(net "UPI_CPU0_CPU1_P2P2_DP<3>")
	)
	(arc
		(start 352.362262 -289.446208)
		(mid 352.471297 -289.529937)
		(end 352.546412 -289.64509)
		(width 0.0889)
		(layer "In6.Cu")
		(net "UPI_CPU0_CPU1_P2P2_DP<3>")
	)
	(arc
		(start 88.998806 -283.539184)
		(mid 88.867892 -283.402824)
		(end 88.820244 -283.219906)
		(width 0.0889)
		(layer "In6.Cu")
		(net "UPI_CPU0_CPU1_P2P2_DP<3>")
	)
	(arc
		(start 352.829114 -287.613598)
		(mid 352.624779 -287.816203)
		(end 352.546666 -288.09315)
		(width 0.0889)
		(layer "In6.Cu")
		(net "UPI_CPU0_CPU1_P2P2_DP<3>")
	)
	(arc
		(start 88.350598 -285.673546)
		(mid 88.350353 -285.66415)
		(end 88.350344 -285.65475)
		(width 0.0889)
		(layer "In6.Cu")
		(net "UPI_CPU0_CPU1_P2P2_DP<3>")
	)
	(arc
		(start 88.820498 -281.59202)
		(mid 88.868177 -281.40912)
		(end 88.99906 -281.272742)
		(width 0.0889)
		(layer "In6.Cu")
		(net "UPI_CPU0_CPU1_P2P2_DP<3>")
	)
	(arc
		(start 353.77755 -282.086558)
		(mid 353.908464 -282.222918)
		(end 353.956112 -282.405836)
		(width 0.0889)
		(layer "In6.Cu")
		(net "UPI_CPU0_CPU1_P2P2_DP<3>")
	)
	(arc
		(start 86.940644 -288.103056)
		(mid 86.988323 -287.920156)
		(end 87.119206 -287.783778)
		(width 0.0889)
		(layer "In6.Cu")
		(net "UPI_CPU0_CPU1_P2P2_DP<3>")
	)
	(arc
		(start 88.350344 -285.65475)
		(mid 88.399597 -285.47555)
		(end 88.528906 -285.342076)
		(width 0.0889)
		(layer "In6.Cu")
		(net "UPI_CPU0_CPU1_P2P2_DP<3>")
	)
	(arc
		(start 354.23856 -282.895294)
		(mid 354.37404 -283.029393)
		(end 354.426012 -283.212794)
		(width 0.0889)
		(layer "In6.Cu")
		(net "UPI_CPU0_CPU1_P2P2_DP<3>")
	)
	(segment
		(start 88.255094 -282.683966)
		(end 88.255094 -283.219906)
		(width 0.13208)
		(layer "F.Cu")
		(net "UPI_CPU0_CPU1_P2P2_DP<2>")
	)
	(segment
		(start 354.521516 -282.405582)
		(end 354.521262 -282.405836)
		(width 0.13208)
		(layer "F.Cu")
		(net "UPI_CPU0_CPU1_P2P2_DP<2>")
	)
	(segment
		(start 354.521516 -281.869896)
		(end 354.521516 -282.405582)
		(width 0.13208)
		(layer "F.Cu")
		(net "UPI_CPU0_CPU1_P2P2_DP<2>")
	)
	(segment
		(start 87.41029 -285.65348)
		(end 87.410544 -285.65348)
		(width 0.0889)
		(layer "In6.Cu")
		(net "UPI_CPU0_CPU1_P2P2_DP<2>")
	)
	(segment
		(start 353.307904 -288.422334)
		(end 353.299776 -288.426906)
		(width 0.0889)
		(layer "In6.Cu")
		(net "UPI_CPU0_CPU1_P2P2_DP<2>")
	)
	(segment
		(start 86.187534 -286.799274)
		(end 86.179406 -286.794702)
		(width 0.0889)
		(layer "In6.Cu")
		(net "UPI_CPU0_CPU1_P2P2_DP<2>")
	)
	(segment
		(start 310.58104 -341.52332)
		(end 286.681672 -341.52332)
		(width 0.14732)
		(layer "In6.Cu")
		(net "UPI_CPU0_CPU1_P2P2_DP<2>")
	)
	(segment
		(start 354.23856 -286.151066)
		(end 354.24745 -286.156146)
		(width 0.0889)
		(layer "In6.Cu")
		(net "UPI_CPU0_CPU1_P2P2_DP<2>")
	)
	(segment
		(start 353.777804 -287.608518)
		(end 353.768914 -287.613598)
		(width 0.0889)
		(layer "In6.Cu")
		(net "UPI_CPU0_CPU1_P2P2_DP<2>")
	)
	(segment
		(start 85.687408 -288.31413)
		(end 85.82787 -288.31413)
		(width 0.0889)
		(layer "In6.Cu")
		(net "UPI_CPU0_CPU1_P2P2_DP<2>")
	)
	(segment
		(start 55.012844 -321.319398)
		(end 55.183278 -321.205606)
		(width 0.14732)
		(layer "In6.Cu")
		(net "UPI_CPU0_CPU1_P2P2_DP<2>")
	)
	(segment
		(start 72.725788 -377.23191)
		(end 72.536304 -377.310142)
		(width 0.14732)
		(layer "In6.Cu")
		(net "UPI_CPU0_CPU1_P2P2_DP<2>")
	)
	(segment
		(start 60.64631 -314.327794)
		(end 61.731398 -313.242452)
		(width 0.14732)
		(layer "In6.Cu")
		(net "UPI_CPU0_CPU1_P2P2_DP<2>")
	)
	(segment
		(start 87.60841 -284.363922)
		(end 87.597996 -284.35808)
		(width 0.0889)
		(layer "In6.Cu")
		(net "UPI_CPU0_CPU1_P2P2_DP<2>")
	)
	(segment
		(start 354.24745 -286.794702)
		(end 354.23856 -286.799782)
		(width 0.0889)
		(layer "In6.Cu")
		(net "UPI_CPU0_CPU1_P2P2_DP<2>")
	)
	(segment
		(start 55.03799 -321.93611)
		(end 54.924198 -321.765676)
		(width 0.14732)
		(layer "In6.Cu")
		(net "UPI_CPU0_CPU1_P2P2_DP<2>")
	)
	(segment
		(start 85.594952 -289.295078)
		(end 85.594952 -289.117278)
		(width 0.0889)
		(layer "In6.Cu")
		(net "UPI_CPU0_CPU1_P2P2_DP<2>")
	)
	(segment
		(start 73.144634 -377.562364)
		(end 73.066148 -377.37288)
		(width 0.14732)
		(layer "In6.Cu")
		(net "UPI_CPU0_CPU1_P2P2_DP<2>")
	)
	(segment
		(start 352.844354 -295.109138)
		(end 352.802444 -295.151048)
		(width 0.0889)
		(layer "In6.Cu")
		(net "UPI_CPU0_CPU1_P2P2_DP<2>")
	)
	(segment
		(start 353.956366 -285.64586)
		(end 353.956366 -285.683452)
		(width 0.0889)
		(layer "In6.Cu")
		(net "UPI_CPU0_CPU1_P2P2_DP<2>")
	)
	(segment
		(start 352.80219 -295.184322)
		(end 352.80219 -298.443904)
		(width 0.14732)
		(layer "In6.Cu")
		(net "UPI_CPU0_CPU1_P2P2_DP<2>")
	)
	(segment
		(start 352.196908 -299.526452)
		(end 352.055938 -299.866812)
		(width 0.14732)
		(layer "In6.Cu")
		(net "UPI_CPU0_CPU1_P2P2_DP<2>")
	)
	(segment
		(start 86.079076 -287.922462)
		(end 86.219538 -287.922462)
		(width 0.0889)
		(layer "In6.Cu")
		(net "UPI_CPU0_CPU1_P2P2_DP<2>")
	)
	(segment
		(start 126.841504 -391.03935)
		(end 93.875098 -386.148834)
		(width 0.14732)
		(layer "In6.Cu")
		(net "UPI_CPU0_CPU1_P2P2_DP<2>")
	)
	(segment
		(start 71.384668 -376.832876)
		(end 70.33514 -376.398282)
		(width 0.14732)
		(layer "In6.Cu")
		(net "UPI_CPU0_CPU1_P2P2_DP<2>")
	)
	(segment
		(start 86.47049 -287.531048)
		(end 86.47049 -287.278826)
		(width 0.0889)
		(layer "In6.Cu")
		(net "UPI_CPU0_CPU1_P2P2_DP<2>")
	)
	(segment
		(start 55.25516 -320.844164)
		(end 55.141622 -320.67373)
		(width 0.14732)
		(layer "In6.Cu")
		(net "UPI_CPU0_CPU1_P2P2_DP<2>")
	)
	(segment
		(start 340.430866 -309.956962)
		(end 322.181474 -328.206354)
		(width 0.14732)
		(layer "In6.Cu")
		(net "UPI_CPU0_CPU1_P2P2_DP<2>")
	)
	(segment
		(start 58.376058 -356.241096)
		(end 58.376058 -336.391504)
		(width 0.14732)
		(layer "In6.Cu")
		(net "UPI_CPU0_CPU1_P2P2_DP<2>")
	)
	(segment
		(start 77.548994 -300.94682)
		(end 81.54289 -296.952924)
		(width 0.14732)
		(layer "In6.Cu")
		(net "UPI_CPU0_CPU1_P2P2_DP<2>")
	)
	(segment
		(start 353.016566 -288.898584)
		(end 353.016566 -289.114738)
		(width 0.0889)
		(layer "In6.Cu")
		(net "UPI_CPU0_CPU1_P2P2_DP<2>")
	)
	(segment
		(start 353.486212 -290.513516)
		(end 353.387152 -290.612576)
		(width 0.0889)
		(layer "In6.Cu")
		(net "UPI_CPU0_CPU1_P2P2_DP<2>")
	)
	(segment
		(start 354.24745 -285.166816)
		(end 354.23856 -285.171896)
		(width 0.0889)
		(layer "In6.Cu")
		(net "UPI_CPU0_CPU1_P2P2_DP<2>")
	)
	(segment
		(start 54.115208 -330.528422)
		(end 52.71008 -329.12304)
		(width 0.14732)
		(layer "In6.Cu")
		(net "UPI_CPU0_CPU1_P2P2_DP<2>")
	)
	(segment
		(start 54.795674 -322.411344)
		(end 54.966108 -322.297552)
		(width 0.14732)
		(layer "In6.Cu")
		(net "UPI_CPU0_CPU1_P2P2_DP<2>")
	)
	(segment
		(start 87.880444 -283.229812)
		(end 87.880444 -283.219906)
		(width 0.0889)
		(layer "In6.Cu")
		(net "UPI_CPU0_CPU1_P2P2_DP<2>")
	)
	(segment
		(start 87.41029 -285.661608)
		(end 87.41029 -285.65348)
		(width 0.0889)
		(layer "In6.Cu")
		(net "UPI_CPU0_CPU1_P2P2_DP<2>")
	)
	(segment
		(start 352.13417 -300.056042)
		(end 351.77984 -300.911768)
		(width 0.14732)
		(layer "In6.Cu")
		(net "UPI_CPU0_CPU1_P2P2_DP<2>")
	)
	(segment
		(start 57.517284 -334.318102)
		(end 55.54599 -331.963776)
		(width 0.14732)
		(layer "In6.Cu")
		(net "UPI_CPU0_CPU1_P2P2_DP<2>")
	)
	(segment
		(start 85.594952 -289.117278)
		(end 85.694012 -289.018218)
		(width 0.0889)
		(layer "In6.Cu")
		(net "UPI_CPU0_CPU1_P2P2_DP<2>")
	)
	(segment
		(start 352.745294 -294.044116)
		(end 352.745294 -294.219376)
		(width 0.0889)
		(layer "In6.Cu")
		(net "UPI_CPU0_CPU1_P2P2_DP<2>")
	)
	(segment
		(start 55.585868 -318.439546)
		(end 55.967884 -317.725044)
		(width 0.14732)
		(layer "In6.Cu")
		(net "UPI_CPU0_CPU1_P2P2_DP<2>")
	)
	(segment
		(start 52.71008 -324.930008)
		(end 54.688232 -322.951856)
		(width 0.14732)
		(layer "In6.Cu")
		(net "UPI_CPU0_CPU1_P2P2_DP<2>")
	)
	(segment
		(start 85.594952 -289.670998)
		(end 85.694012 -289.571938)
		(width 0.0889)
		(layer "In6.Cu")
		(net "UPI_CPU0_CPU1_P2P2_DP<2>")
	)
	(segment
		(start 85.694012 -288.840418)
		(end 85.594952 -288.741358)
		(width 0.0889)
		(layer "In6.Cu")
		(net "UPI_CPU0_CPU1_P2P2_DP<2>")
	)
	(segment
		(start 353.486212 -290.886896)
		(end 353.486212 -291.212524)
		(width 0.0889)
		(layer "In6.Cu")
		(net "UPI_CPU0_CPU1_P2P2_DP<2>")
	)
	(segment
		(start 344.36304 -308.328568)
		(end 340.430866 -309.956962)
		(width 0.14732)
		(layer "In6.Cu")
		(net "UPI_CPU0_CPU1_P2P2_DP<2>")
	)
	(segment
		(start 77.548994 -301.151544)
		(end 77.548994 -300.94682)
		(width 0.14732)
		(layer "In6.Cu")
		(net "UPI_CPU0_CPU1_P2P2_DP<2>")
	)
	(segment
		(start 85.694012 -289.947858)
		(end 85.594952 -289.848798)
		(width 0.0889)
		(layer "In6.Cu")
		(net "UPI_CPU0_CPU1_P2P2_DP<2>")
	)
	(segment
		(start 54.966108 -322.297552)
		(end 55.03799 -321.93611)
		(width 0.14732)
		(layer "In6.Cu")
		(net "UPI_CPU0_CPU1_P2P2_DP<2>")
	)
	(segment
		(start 353.486212 -291.212524)
		(end 353.2759 -291.422836)
		(width 0.0889)
		(layer "In6.Cu")
		(net "UPI_CPU0_CPU1_P2P2_DP<2>")
	)
	(segment
		(start 86.00059 -286.475424)
		(end 86.00059 -286.460438)
		(width 0.0889)
		(layer "In6.Cu")
		(net "UPI_CPU0_CPU1_P2P2_DP<2>")
	)
	(segment
		(start 54.688232 -322.951856)
		(end 54.795674 -322.411344)
		(width 0.14732)
		(layer "In6.Cu")
		(net "UPI_CPU0_CPU1_P2P2_DP<2>")
	)
	(segment
		(start 354.708714 -284.35808)
		(end 354.707952 -284.358588)
		(width 0.0889)
		(layer "In6.Cu")
		(net "UPI_CPU0_CPU1_P2P2_DP<2>")
	)
	(segment
		(start 352.055938 -299.866812)
		(end 352.13417 -300.056042)
		(width 0.14732)
		(layer "In6.Cu")
		(net "UPI_CPU0_CPU1_P2P2_DP<2>")
	)
	(segment
		(start 355.178614 -282.895548)
		(end 355.187504 -282.900628)
		(width 0.0889)
		(layer "In6.Cu")
		(net "UPI_CPU0_CPU1_P2P2_DP<2>")
	)
	(segment
		(start 353.011486 -291.546788)
		(end 353.011486 -291.68725)
		(width 0.0889)
		(layer "In6.Cu")
		(net "UPI_CPU0_CPU1_P2P2_DP<2>")
	)
	(segment
		(start 64.173354 -370.236496)
		(end 58.376058 -356.241096)
		(width 0.14732)
		(layer "In6.Cu")
		(net "UPI_CPU0_CPU1_P2P2_DP<2>")
	)
	(segment
		(start 71.573898 -376.754644)
		(end 71.384668 -376.832876)
		(width 0.14732)
		(layer "In6.Cu")
		(net "UPI_CPU0_CPU1_P2P2_DP<2>")
	)
	(segment
		(start 87.597488 -285.33725)
		(end 87.60841 -285.3309)
		(width 0.0889)
		(layer "In6.Cu")
		(net "UPI_CPU0_CPU1_P2P2_DP<2>")
	)
	(segment
		(start 55.520844 -331.933804)
		(end 54.115462 -330.528422)
		(width 0.14732)
		(layer "In6.Cu")
		(net "UPI_CPU0_CPU1_P2P2_DP<2>")
	)
	(segment
		(start 353.956366 -287.273746)
		(end 353.956366 -287.28924)
		(width 0.0889)
		(layer "In6.Cu")
		(net "UPI_CPU0_CPU1_P2P2_DP<2>")
	)
	(segment
		(start 76.714604 -301.985934)
		(end 76.714604 -301.78121)
		(width 0.14732)
		(layer "In6.Cu")
		(net "UPI_CPU0_CPU1_P2P2_DP<2>")
	)
	(segment
		(start 54.115462 -330.528422)
		(end 54.115208 -330.528422)
		(width 0.14732)
		(layer "In6.Cu")
		(net "UPI_CPU0_CPU1_P2P2_DP<2>")
	)
	(segment
		(start 354.895912 -282.405836)
		(end 354.895912 -282.42006)
		(width 0.0889)
		(layer "In6.Cu")
		(net "UPI_CPU0_CPU1_P2P2_DP<2>")
	)
	(segment
		(start 61.731398 -313.242452)
		(end 67.743832 -310.751982)
		(width 0.14732)
		(layer "In6.Cu")
		(net "UPI_CPU0_CPU1_P2P2_DP<2>")
	)
	(segment
		(start 85.82787 -288.31413)
		(end 85.9536 -288.1884)
		(width 0.0889)
		(layer "In6.Cu")
		(net "UPI_CPU0_CPU1_P2P2_DP<2>")
	)
	(segment
		(start 85.9536 -288.1884)
		(end 85.9536 -288.047938)
		(width 0.0889)
		(layer "In6.Cu")
		(net "UPI_CPU0_CPU1_P2P2_DP<2>")
	)
	(segment
		(start 84.768944 -291.366702)
		(end 85.594952 -290.540694)
		(width 0.0889)
		(layer "In6.Cu")
		(net "UPI_CPU0_CPU1_P2P2_DP<2>")
	)
	(segment
		(start 353.2759 -291.422836)
		(end 353.135438 -291.422836)
		(width 0.0889)
		(layer "In6.Cu")
		(net "UPI_CPU0_CPU1_P2P2_DP<2>")
	)
	(segment
		(start 352.80219 -298.443904)
		(end 352.386138 -299.44822)
		(width 0.14732)
		(layer "In6.Cu")
		(net "UPI_CPU0_CPU1_P2P2_DP<2>")
	)
	(segment
		(start 268.469364 -382.003046)
		(end 268.468856 -382.003046)
		(width 0.14732)
		(layer "In6.Cu")
		(net "UPI_CPU0_CPU1_P2P2_DP<2>")
	)
	(segment
		(start 353.486466 -288.09315)
		(end 353.486466 -288.103056)
		(width 0.0889)
		(layer "In6.Cu")
		(net "UPI_CPU0_CPU1_P2P2_DP<2>")
	)
	(segment
		(start 85.694012 -289.394138)
		(end 85.594952 -289.295078)
		(width 0.0889)
		(layer "In6.Cu")
		(net "UPI_CPU0_CPU1_P2P2_DP<2>")
	)
	(segment
		(start 85.694012 -290.125658)
		(end 85.694012 -289.947858)
		(width 0.0889)
		(layer "In6.Cu")
		(net "UPI_CPU0_CPU1_P2P2_DP<2>")
	)
	(segment
		(start 355.172264 -283.548074)
		(end 355.172518 -283.54782)
		(width 0.0889)
		(layer "In6.Cu")
		(net "UPI_CPU0_CPU1_P2P2_DP<2>")
	)
	(segment
		(start 86.000844 -286.475424)
		(end 86.00059 -286.475424)
		(width 0.0889)
		(layer "In6.Cu")
		(net "UPI_CPU0_CPU1_P2P2_DP<2>")
	)
	(segment
		(start 83.16976 -293.02583)
		(end 84.75345 -291.44214)
		(width 0.14732)
		(layer "In6.Cu")
		(net "UPI_CPU0_CPU1_P2P2_DP<2>")
	)
	(segment
		(start 85.594952 -289.848798)
		(end 85.594952 -289.670998)
		(width 0.0889)
		(layer "In6.Cu")
		(net "UPI_CPU0_CPU1_P2P2_DP<2>")
	)
	(segment
		(start 286.681672 -341.52332)
		(end 284.541214 -342.410034)
		(width 0.14732)
		(layer "In6.Cu")
		(net "UPI_CPU0_CPU1_P2P2_DP<2>")
	)
	(segment
		(start 55.54599 -331.963776)
		(end 55.543958 -331.961236)
		(width 0.14732)
		(layer "In6.Cu")
		(net "UPI_CPU0_CPU1_P2P2_DP<2>")
	)
	(segment
		(start 353.387152 -290.612576)
		(end 353.387152 -290.787836)
		(width 0.0889)
		(layer "In6.Cu")
		(net "UPI_CPU0_CPU1_P2P2_DP<2>")
	)
	(segment
		(start 353.135438 -291.422836)
		(end 353.011486 -291.546788)
		(width 0.0889)
		(layer "In6.Cu")
		(net "UPI_CPU0_CPU1_P2P2_DP<2>")
	)
	(segment
		(start 278.792432 -348.158816)
		(end 278.792432 -371.679978)
		(width 0.14732)
		(layer "In6.Cu")
		(net "UPI_CPU0_CPU1_P2P2_DP<2>")
	)
	(segment
		(start 72.536304 -377.310142)
		(end 71.992744 -377.084844)
		(width 0.14732)
		(layer "In6.Cu")
		(net "UPI_CPU0_CPU1_P2P2_DP<2>")
	)
	(segment
		(start 354.364798 -282.134818)
		(end 354.38588 -282.05684)
		(width 0.0889)
		(layer "In6.Cu")
		(net "UPI_CPU0_CPU1_P2P2_DP<2>")
	)
	(segment
		(start 85.9536 -288.047938)
		(end 86.079076 -287.922462)
		(width 0.0889)
		(layer "In6.Cu")
		(net "UPI_CPU0_CPU1_P2P2_DP<2>")
	)
	(segment
		(start 351.77984 -300.911768)
		(end 344.36304 -308.328568)
		(width 0.14732)
		(layer "In6.Cu")
		(net "UPI_CPU0_CPU1_P2P2_DP<2>")
	)
	(segment
		(start 355.187504 -283.539184)
		(end 355.172264 -283.548074)
		(width 0.0889)
		(layer "In6.Cu")
		(net "UPI_CPU0_CPU1_P2P2_DP<2>")
	)
	(segment
		(start 322.181474 -328.206354)
		(end 320.968116 -331.136244)
		(width 0.14732)
		(layer "In6.Cu")
		(net "UPI_CPU0_CPU1_P2P2_DP<2>")
	)
	(segment
		(start 55.183278 -321.205606)
		(end 55.25516 -320.844164)
		(width 0.14732)
		(layer "In6.Cu")
		(net "UPI_CPU0_CPU1_P2P2_DP<2>")
	)
	(segment
		(start 75.864974 -378.688854)
		(end 75.786742 -378.499878)
		(width 0.14732)
		(layer "In6.Cu")
		(net "UPI_CPU0_CPU1_P2P2_DP<2>")
	)
	(segment
		(start 57.504838 -316.42685)
		(end 60.64631 -314.327794)
		(width 0.14732)
		(layer "In6.Cu")
		(net "UPI_CPU0_CPU1_P2P2_DP<2>")
	)
	(segment
		(start 81.54289 -296.952924)
		(end 83.16976 -293.02583)
		(width 0.14732)
		(layer "In6.Cu")
		(net "UPI_CPU0_CPU1_P2P2_DP<2>")
	)
	(segment
		(start 52.71008 -329.12304)
		(end 52.71008 -324.930008)
		(width 0.14732)
		(layer "In6.Cu")
		(net "UPI_CPU0_CPU1_P2P2_DP<2>")
	)
	(segment
		(start 58.376058 -336.391504)
		(end 57.517284 -334.318102)
		(width 0.14732)
		(layer "In6.Cu")
		(net "UPI_CPU0_CPU1_P2P2_DP<2>")
	)
	(segment
		(start 75.786742 -378.499878)
		(end 75.446128 -378.358908)
		(width 0.14732)
		(layer "In6.Cu")
		(net "UPI_CPU0_CPU1_P2P2_DP<2>")
	)
	(segment
		(start 353.387152 -290.063936)
		(end 353.387152 -290.239196)
		(width 0.0889)
		(layer "In6.Cu")
		(net "UPI_CPU0_CPU1_P2P2_DP<2>")
	)
	(segment
		(start 73.066148 -377.37288)
		(end 72.725788 -377.23191)
		(width 0.14732)
		(layer "In6.Cu")
		(net "UPI_CPU0_CPU1_P2P2_DP<2>")
	)
	(segment
		(start 354.70846 -282.081478)
		(end 354.71735 -282.086558)
		(width 0.0889)
		(layer "In6.Cu")
		(net "UPI_CPU0_CPU1_P2P2_DP<2>")
	)
	(segment
		(start 75.257152 -378.43714)
		(end 73.145396 -377.561856)
		(width 0.14732)
		(layer "In6.Cu")
		(net "UPI_CPU0_CPU1_P2P2_DP<2>")
	)
	(segment
		(start 86.345268 -287.796732)
		(end 86.345268 -287.65627)
		(width 0.0889)
		(layer "In6.Cu")
		(net "UPI_CPU0_CPU1_P2P2_DP<2>")
	)
	(segment
		(start 353.486212 -289.645852)
		(end 353.486212 -289.964876)
		(width 0.0889)
		(layer "In6.Cu")
		(net "UPI_CPU0_CPU1_P2P2_DP<2>")
	)
	(segment
		(start 56.171846 -317.521082)
		(end 57.504838 -316.42685)
		(width 0.14732)
		(layer "In6.Cu")
		(net "UPI_CPU0_CPU1_P2P2_DP<2>")
	)
	(segment
		(start 86.47049 -287.278826)
		(end 86.470744 -287.279334)
		(width 0.0889)
		(layer "In6.Cu")
		(net "UPI_CPU0_CPU1_P2P2_DP<2>")
	)
	(segment
		(start 352.844354 -291.854382)
		(end 352.844354 -293.945056)
		(width 0.0889)
		(layer "In6.Cu")
		(net "UPI_CPU0_CPU1_P2P2_DP<2>")
	)
	(segment
		(start 352.745294 -294.219376)
		(end 352.844354 -294.318436)
		(width 0.0889)
		(layer "In6.Cu")
		(net "UPI_CPU0_CPU1_P2P2_DP<2>")
	)
	(segment
		(start 354.707952 -284.358588)
		(end 354.702618 -284.361636)
		(width 0.0889)
		(layer "In6.Cu")
		(net "UPI_CPU0_CPU1_P2P2_DP<2>")
	)
	(segment
		(start 85.594952 -290.224718)
		(end 85.694012 -290.125658)
		(width 0.0889)
		(layer "In6.Cu")
		(net "UPI_CPU0_CPU1_P2P2_DP<2>")
	)
	(segment
		(start 93.875098 -386.148834)
		(end 75.864974 -378.688854)
		(width 0.14732)
		(layer "In6.Cu")
		(net "UPI_CPU0_CPU1_P2P2_DP<2>")
	)
	(segment
		(start 88.020398 -282.92806)
		(end 88.09863 -282.948888)
		(width 0.0889)
		(layer "In6.Cu")
		(net "UPI_CPU0_CPU1_P2P2_DP<2>")
	)
	(segment
		(start 76.453746 -302.246792)
		(end 76.714604 -301.985934)
		(width 0.14732)
		(layer "In6.Cu")
		(net "UPI_CPU0_CPU1_P2P2_DP<2>")
	)
	(segment
		(start 86.219538 -287.922462)
		(end 86.345268 -287.796732)
		(width 0.0889)
		(layer "In6.Cu")
		(net "UPI_CPU0_CPU1_P2P2_DP<2>")
	)
	(segment
		(start 76.249022 -302.246792)
		(end 76.453746 -302.246792)
		(width 0.14732)
		(layer "In6.Cu")
		(net "UPI_CPU0_CPU1_P2P2_DP<2>")
	)
	(segment
		(start 85.594952 -290.540694)
		(end 85.594952 -290.224718)
		(width 0.0889)
		(layer "In6.Cu")
		(net "UPI_CPU0_CPU1_P2P2_DP<2>")
	)
	(segment
		(start 86.188296 -286.799782)
		(end 86.187534 -286.799274)
		(width 0.0889)
		(layer "In6.Cu")
		(net "UPI_CPU0_CPU1_P2P2_DP<2>")
	)
	(segment
		(start 353.011486 -291.68725)
		(end 352.844354 -291.854382)
		(width 0.0889)
		(layer "In6.Cu")
		(net "UPI_CPU0_CPU1_P2P2_DP<2>")
	)
	(segment
		(start 354.521262 -282.405836)
		(end 354.364798 -282.134818)
		(width 0.0889)
		(layer "In6.Cu")
		(net "UPI_CPU0_CPU1_P2P2_DP<2>")
	)
	(segment
		(start 161.46399 -391.03935)
		(end 126.841504 -391.03935)
		(width 0.14732)
		(layer "In6.Cu")
		(net "UPI_CPU0_CPU1_P2P2_DP<2>")
	)
	(segment
		(start 353.486212 -289.964876)
		(end 353.387152 -290.063936)
		(width 0.0889)
		(layer "In6.Cu")
		(net "UPI_CPU0_CPU1_P2P2_DP<2>")
	)
	(segment
		(start 84.768944 -291.426646)
		(end 84.768944 -291.366702)
		(width 0.0889)
		(layer "In6.Cu")
		(net "UPI_CPU0_CPU1_P2P2_DP<2>")
	)
	(segment
		(start 353.486212 -290.338256)
		(end 353.486212 -290.513516)
		(width 0.0889)
		(layer "In6.Cu")
		(net "UPI_CPU0_CPU1_P2P2_DP<2>")
	)
	(segment
		(start 86.345268 -287.65627)
		(end 86.47049 -287.531048)
		(width 0.0889)
		(layer "In6.Cu")
		(net "UPI_CPU0_CPU1_P2P2_DP<2>")
	)
	(segment
		(start 77.288136 -301.412402)
		(end 77.548994 -301.151544)
		(width 0.14732)
		(layer "In6.Cu")
		(net "UPI_CPU0_CPU1_P2P2_DP<2>")
	)
	(segment
		(start 85.594952 -288.741358)
		(end 85.594952 -288.406586)
		(width 0.0889)
		(layer "In6.Cu")
		(net "UPI_CPU0_CPU1_P2P2_DP<2>")
	)
	(segment
		(start 85.594952 -288.406586)
		(end 85.687408 -288.31413)
		(width 0.0889)
		(layer "In6.Cu")
		(net "UPI_CPU0_CPU1_P2P2_DP<2>")
	)
	(segment
		(start 353.299776 -288.426906)
		(end 353.299014 -288.427414)
		(width 0.0889)
		(layer "In6.Cu")
		(net "UPI_CPU0_CPU1_P2P2_DP<2>")
	)
	(segment
		(start 284.541214 -342.410034)
		(end 278.792432 -348.158816)
		(width 0.14732)
		(layer "In6.Cu")
		(net "UPI_CPU0_CPU1_P2P2_DP<2>")
	)
	(segment
		(start 67.743832 -310.751982)
		(end 76.249022 -302.246792)
		(width 0.14732)
		(layer "In6.Cu")
		(net "UPI_CPU0_CPU1_P2P2_DP<2>")
	)
	(segment
		(start 84.75345 -291.44214)
		(end 84.768944 -291.426646)
		(width 0.0889)
		(layer "In6.Cu")
		(net "UPI_CPU0_CPU1_P2P2_DP<2>")
	)
	(segment
		(start 70.33514 -376.398282)
		(end 64.173354 -370.236496)
		(width 0.14732)
		(layer "In6.Cu")
		(net "UPI_CPU0_CPU1_P2P2_DP<2>")
	)
	(segment
		(start 352.802444 -295.151048)
		(end 352.802444 -295.173146)
		(width 0.0889)
		(layer "In6.Cu")
		(net "UPI_CPU0_CPU1_P2P2_DP<2>")
	)
	(segment
		(start 352.844354 -293.945056)
		(end 352.745294 -294.044116)
		(width 0.0889)
		(layer "In6.Cu")
		(net "UPI_CPU0_CPU1_P2P2_DP<2>")
	)
	(segment
		(start 353.387152 -290.787836)
		(end 353.486212 -290.886896)
		(width 0.0889)
		(layer "In6.Cu")
		(net "UPI_CPU0_CPU1_P2P2_DP<2>")
	)
	(segment
		(start 54.924198 -321.765676)
		(end 55.012844 -321.319398)
		(width 0.14732)
		(layer "In6.Cu")
		(net "UPI_CPU0_CPU1_P2P2_DP<2>")
	)
	(segment
		(start 352.802444 -295.173146)
		(end 352.802444 -295.184068)
		(width 0.14732)
		(layer "In6.Cu")
		(net "UPI_CPU0_CPU1_P2P2_DP<2>")
	)
	(segment
		(start 352.802444 -295.184068)
		(end 352.80219 -295.184322)
		(width 0.14732)
		(layer "In6.Cu")
		(net "UPI_CPU0_CPU1_P2P2_DP<2>")
	)
	(segment
		(start 55.543958 -331.961236)
		(end 55.520844 -331.933804)
		(width 0.14732)
		(layer "In6.Cu")
		(net "UPI_CPU0_CPU1_P2P2_DP<2>")
	)
	(segment
		(start 55.141622 -320.67373)
		(end 55.585868 -318.439546)
		(width 0.14732)
		(layer "In6.Cu")
		(net "UPI_CPU0_CPU1_P2P2_DP<2>")
	)
	(segment
		(start 352.386138 -299.44822)
		(end 352.196908 -299.526452)
		(width 0.14732)
		(layer "In6.Cu")
		(net "UPI_CPU0_CPU1_P2P2_DP<2>")
	)
	(segment
		(start 88.09863 -282.948888)
		(end 88.255094 -283.219906)
		(width 0.0889)
		(layer "In6.Cu")
		(net "UPI_CPU0_CPU1_P2P2_DP<2>")
	)
	(segment
		(start 71.992744 -377.084844)
		(end 71.914512 -376.895614)
		(width 0.14732)
		(layer "In6.Cu")
		(net "UPI_CPU0_CPU1_P2P2_DP<2>")
	)
	(segment
		(start 76.714604 -301.78121)
		(end 77.083412 -301.412402)
		(width 0.14732)
		(layer "In6.Cu")
		(net "UPI_CPU0_CPU1_P2P2_DP<2>")
	)
	(segment
		(start 320.968116 -331.136244)
		(end 310.58104 -341.52332)
		(width 0.14732)
		(layer "In6.Cu")
		(net "UPI_CPU0_CPU1_P2P2_DP<2>")
	)
	(segment
		(start 354.895912 -284.033722)
		(end 354.895912 -284.042358)
		(width 0.0889)
		(layer "In6.Cu")
		(net "UPI_CPU0_CPU1_P2P2_DP<2>")
	)
	(segment
		(start 85.694012 -289.571938)
		(end 85.694012 -289.394138)
		(width 0.0889)
		(layer "In6.Cu")
		(net "UPI_CPU0_CPU1_P2P2_DP<2>")
	)
	(segment
		(start 55.967884 -317.725044)
		(end 56.171846 -317.521082)
		(width 0.14732)
		(layer "In6.Cu")
		(net "UPI_CPU0_CPU1_P2P2_DP<2>")
	)
	(segment
		(start 353.387152 -290.239196)
		(end 353.486212 -290.338256)
		(width 0.0889)
		(layer "In6.Cu")
		(net "UPI_CPU0_CPU1_P2P2_DP<2>")
	)
	(segment
		(start 77.083412 -301.412402)
		(end 77.288136 -301.412402)
		(width 0.14732)
		(layer "In6.Cu")
		(net "UPI_CPU0_CPU1_P2P2_DP<2>")
	)
	(segment
		(start 71.914512 -376.895614)
		(end 71.573898 -376.754644)
		(width 0.14732)
		(layer "In6.Cu")
		(net "UPI_CPU0_CPU1_P2P2_DP<2>")
	)
	(segment
		(start 352.844354 -294.318436)
		(end 352.844354 -295.109138)
		(width 0.0889)
		(layer "In6.Cu")
		(net "UPI_CPU0_CPU1_P2P2_DP<2>")
	)
	(segment
		(start 75.446128 -378.358908)
		(end 75.257152 -378.43714)
		(width 0.14732)
		(layer "In6.Cu")
		(net "UPI_CPU0_CPU1_P2P2_DP<2>")
	)
	(segment
		(start 85.694012 -289.018218)
		(end 85.694012 -288.840418)
		(width 0.0889)
		(layer "In6.Cu")
		(net "UPI_CPU0_CPU1_P2P2_DP<2>")
	)
	(segment
		(start 73.145396 -377.561856)
		(end 73.144634 -377.562364)
		(width 0.14732)
		(layer "In6.Cu")
		(net "UPI_CPU0_CPU1_P2P2_DP<2>")
	)
	(segment
		(start 278.792432 -371.679978)
		(end 268.469364 -382.003046)
		(width 0.14732)
		(layer "In6.Cu")
		(net "UPI_CPU0_CPU1_P2P2_DP<2>")
	)
	(segment
		(start 268.468856 -382.003046)
		(end 161.46399 -391.03935)
		(width 0.14732)
		(layer "In6.Cu")
		(net "UPI_CPU0_CPU1_P2P2_DP<2>")
	)
	(arc
		(start 354.23856 -286.799782)
		(mid 354.035737 -287.000013)
		(end 353.956366 -287.273746)
		(width 0.0889)
		(layer "In6.Cu")
		(net "UPI_CPU0_CPU1_P2P2_DP<2>")
	)
	(arc
		(start 87.597996 -284.35808)
		(mid 87.410693 -284.033722)
		(end 87.597996 -283.709364)
		(width 0.0889)
		(layer "In6.Cu")
		(net "UPI_CPU0_CPU1_P2P2_DP<2>")
	)
	(arc
		(start 354.425758 -286.460692)
		(mid 354.426091 -286.473136)
		(end 354.426012 -286.485584)
		(width 0.0889)
		(layer "In6.Cu")
		(net "UPI_CPU0_CPU1_P2P2_DP<2>")
	)
	(arc
		(start 86.470744 -287.279334)
		(mid 86.392633 -287.002385)
		(end 86.188296 -286.799782)
		(width 0.0889)
		(layer "In6.Cu")
		(net "UPI_CPU0_CPU1_P2P2_DP<2>")
	)
	(arc
		(start 354.702618 -284.361636)
		(mid 354.500031 -284.567987)
		(end 354.426012 -284.847538)
		(width 0.0889)
		(layer "In6.Cu")
		(net "UPI_CPU0_CPU1_P2P2_DP<2>")
	)
	(arc
		(start 353.956366 -287.28924)
		(mid 353.908687 -287.47214)
		(end 353.777804 -287.608518)
		(width 0.0889)
		(layer "In6.Cu")
		(net "UPI_CPU0_CPU1_P2P2_DP<2>")
	)
	(arc
		(start 354.23856 -285.171896)
		(mid 354.035737 -285.372127)
		(end 353.956366 -285.64586)
		(width 0.0889)
		(layer "In6.Cu")
		(net "UPI_CPU0_CPU1_P2P2_DP<2>")
	)
	(arc
		(start 354.24745 -286.156146)
		(mid 354.374704 -286.286112)
		(end 354.425758 -286.460692)
		(width 0.0889)
		(layer "In6.Cu")
		(net "UPI_CPU0_CPU1_P2P2_DP<2>")
	)
	(arc
		(start 353.768914 -287.613598)
		(mid 353.564579 -287.816203)
		(end 353.486466 -288.09315)
		(width 0.0889)
		(layer "In6.Cu")
		(net "UPI_CPU0_CPU1_P2P2_DP<2>")
	)
	(arc
		(start 354.426012 -284.847538)
		(mid 354.378333 -285.030438)
		(end 354.24745 -285.166816)
		(width 0.0889)
		(layer "In6.Cu")
		(net "UPI_CPU0_CPU1_P2P2_DP<2>")
	)
	(arc
		(start 353.299014 -288.427414)
		(mid 353.096728 -288.626395)
		(end 353.016566 -288.898584)
		(width 0.0889)
		(layer "In6.Cu")
		(net "UPI_CPU0_CPU1_P2P2_DP<2>")
	)
	(arc
		(start 354.71735 -282.086558)
		(mid 354.848264 -282.222918)
		(end 354.895912 -282.405836)
		(width 0.0889)
		(layer "In6.Cu")
		(net "UPI_CPU0_CPU1_P2P2_DP<2>")
	)
	(arc
		(start 86.179406 -286.794702)
		(mid 86.048492 -286.658342)
		(end 86.000844 -286.475424)
		(width 0.0889)
		(layer "In6.Cu")
		(net "UPI_CPU0_CPU1_P2P2_DP<2>")
	)
	(arc
		(start 353.302062 -289.446462)
		(mid 353.411209 -289.53039)
		(end 353.486212 -289.645852)
		(width 0.0889)
		(layer "In6.Cu")
		(net "UPI_CPU0_CPU1_P2P2_DP<2>")
	)
	(arc
		(start 355.187504 -282.900628)
		(mid 355.366222 -283.219906)
		(end 355.187504 -283.539184)
		(width 0.0889)
		(layer "In6.Cu")
		(net "UPI_CPU0_CPU1_P2P2_DP<2>")
	)
	(arc
		(start 353.486466 -288.103056)
		(mid 353.438787 -288.285956)
		(end 353.307904 -288.422334)
		(width 0.0889)
		(layer "In6.Cu")
		(net "UPI_CPU0_CPU1_P2P2_DP<2>")
	)
	(arc
		(start 354.426012 -286.485584)
		(mid 354.375943 -286.662809)
		(end 354.24745 -286.794702)
		(width 0.0889)
		(layer "In6.Cu")
		(net "UPI_CPU0_CPU1_P2P2_DP<2>")
	)
	(arc
		(start 87.60841 -285.3309)
		(mid 87.880709 -284.847472)
		(end 87.60841 -284.363922)
		(width 0.0889)
		(layer "In6.Cu")
		(net "UPI_CPU0_CPU1_P2P2_DP<2>")
	)
	(arc
		(start 87.410544 -285.65348)
		(mid 87.41726 -285.590747)
		(end 87.43442 -285.530036)
		(width 0.0889)
		(layer "In6.Cu")
		(net "UPI_CPU0_CPU1_P2P2_DP<2>")
	)
	(arc
		(start 353.956366 -285.683452)
		(mid 354.037277 -285.95358)
		(end 354.23856 -286.151066)
		(width 0.0889)
		(layer "In6.Cu")
		(net "UPI_CPU0_CPU1_P2P2_DP<2>")
	)
	(arc
		(start 87.597996 -283.709364)
		(mid 87.802331 -283.506759)
		(end 87.880444 -283.229812)
		(width 0.0889)
		(layer "In6.Cu")
		(net "UPI_CPU0_CPU1_P2P2_DP<2>")
	)
	(arc
		(start 86.00059 -286.460438)
		(mid 86.194475 -286.146776)
		(end 86.5632 -286.150558)
		(width 0.0889)
		(layer "In6.Cu")
		(net "UPI_CPU0_CPU1_P2P2_DP<2>")
	)
	(arc
		(start 87.880444 -283.219906)
		(mid 87.917304 -283.058109)
		(end 88.020398 -282.92806)
		(width 0.0889)
		(layer "In6.Cu")
		(net "UPI_CPU0_CPU1_P2P2_DP<2>")
	)
	(arc
		(start 87.43442 -285.530036)
		(mid 87.499214 -285.419482)
		(end 87.597488 -285.33725)
		(width 0.0889)
		(layer "In6.Cu")
		(net "UPI_CPU0_CPU1_P2P2_DP<2>")
	)
	(arc
		(start 86.5632 -286.150558)
		(mid 87.127757 -286.15046)
		(end 87.41029 -285.661608)
		(width 0.0889)
		(layer "In6.Cu")
		(net "UPI_CPU0_CPU1_P2P2_DP<2>")
	)
	(arc
		(start 354.895912 -284.042358)
		(mid 354.843642 -284.224723)
		(end 354.708714 -284.35808)
		(width 0.0889)
		(layer "In6.Cu")
		(net "UPI_CPU0_CPU1_P2P2_DP<2>")
	)
	(arc
		(start 353.016566 -289.114738)
		(mid 353.127904 -289.307638)
		(end 353.302062 -289.446462)
		(width 0.0889)
		(layer "In6.Cu")
		(net "UPI_CPU0_CPU1_P2P2_DP<2>")
	)
	(arc
		(start 354.38588 -282.05684)
		(mid 354.549976 -282.032493)
		(end 354.70846 -282.081478)
		(width 0.0889)
		(layer "In6.Cu")
		(net "UPI_CPU0_CPU1_P2P2_DP<2>")
	)
	(arc
		(start 355.172518 -283.54782)
		(mid 354.969931 -283.754171)
		(end 354.895912 -284.033722)
		(width 0.0889)
		(layer "In6.Cu")
		(net "UPI_CPU0_CPU1_P2P2_DP<2>")
	)
	(arc
		(start 354.895912 -282.42006)
		(mid 354.975131 -282.694745)
		(end 355.178614 -282.895548)
		(width 0.0889)
		(layer "In6.Cu")
		(net "UPI_CPU0_CPU1_P2P2_DP<2>")
	)
	(segment
		(start 104.701848 -275.35886)
		(end 104.701848 -275.894546)
		(width 0.13208)
		(layer "F.Cu")
		(net "UPI_CPU0_CPU1_P2P2_DP<23>")
	)
	(segment
		(start 104.701848 -275.894546)
		(end 104.701594 -275.8948)
		(width 0.13208)
		(layer "F.Cu")
		(net "UPI_CPU0_CPU1_P2P2_DP<23>")
	)
	(segment
		(start 334.315562 -284.311598)
		(end 334.315562 -284.847538)
		(width 0.13208)
		(layer "F.Cu")
		(net "UPI_CPU0_CPU1_P2P2_DP<23>")
	)
	(segment
		(start 109.11967 -291.596318)
		(end 109.11967 -291.179758)
		(width 0.0889)
		(layer "In6.Cu")
		(net "UPI_CPU0_CPU1_P2P2_DP<23>")
	)
	(segment
		(start 332.420976 -287.58769)
		(end 332.187042 -288.152332)
		(width 0.14732)
		(layer "In6.Cu")
		(net "UPI_CPU0_CPU1_P2P2_DP<23>")
	)
	(segment
		(start 108.881164 -297.131486)
		(end 108.881164 -292.775132)
		(width 0.14732)
		(layer "In6.Cu")
		(net "UPI_CPU0_CPU1_P2P2_DP<23>")
	)
	(segment
		(start 108.64215 -287.617154)
		(end 108.648246 -287.613598)
		(width 0.0889)
		(layer "In6.Cu")
		(net "UPI_CPU0_CPU1_P2P2_DP<23>")
	)
	(segment
		(start 249.383804 -346.323666)
		(end 249.175524 -346.323666)
		(width 0.14732)
		(layer "In6.Cu")
		(net "UPI_CPU0_CPU1_P2P2_DP<23>")
	)
	(segment
		(start 111.937292 -280.288492)
		(end 111.946182 -280.283412)
		(width 0.0889)
		(layer "In6.Cu")
		(net "UPI_CPU0_CPU1_P2P2_DP<23>")
	)
	(segment
		(start 105.45445 -275.570442)
		(end 105.444036 -275.576538)
		(width 0.0889)
		(layer "In6.Cu")
		(net "UPI_CPU0_CPU1_P2P2_DP<23>")
	)
	(segment
		(start 333.934562 -284.934152)
		(end 333.934308 -284.934406)
		(width 0.0889)
		(layer "In6.Cu")
		(net "UPI_CPU0_CPU1_P2P2_DP<23>")
	)
	(segment
		(start 332.379066 -287.115504)
		(end 332.42123 -287.157668)
		(width 0.0889)
		(layer "In6.Cu")
		(net "UPI_CPU0_CPU1_P2P2_DP<23>")
	)
	(segment
		(start 248.567702 -346.931488)
		(end 248.567702 -350.343724)
		(width 0.14732)
		(layer "In6.Cu")
		(net "UPI_CPU0_CPU1_P2P2_DP<23>")
	)
	(segment
		(start 112.407446 -278.82596)
		(end 112.406684 -278.825452)
		(width 0.0889)
		(layer "In6.Cu")
		(net "UPI_CPU0_CPU1_P2P2_DP<23>")
	)
	(segment
		(start 332.42123 -287.157668)
		(end 332.42123 -287.179766)
		(width 0.0889)
		(layer "In6.Cu")
		(net "UPI_CPU0_CPU1_P2P2_DP<23>")
	)
	(segment
		(start 318.216788 -307.884576)
		(end 314.11545 -307.884576)
		(width 0.14732)
		(layer "In6.Cu")
		(net "UPI_CPU0_CPU1_P2P2_DP<23>")
	)
	(segment
		(start 112.40135 -279.478232)
		(end 112.406684 -279.475184)
		(width 0.0889)
		(layer "In6.Cu")
		(net "UPI_CPU0_CPU1_P2P2_DP<23>")
	)
	(segment
		(start 112.406684 -278.825452)
		(end 112.40135 -278.822404)
		(width 0.0889)
		(layer "In6.Cu")
		(net "UPI_CPU0_CPU1_P2P2_DP<23>")
	)
	(segment
		(start 111.46155 -281.106118)
		(end 111.476536 -281.097228)
		(width 0.0889)
		(layer "In6.Cu")
		(net "UPI_CPU0_CPU1_P2P2_DP<23>")
	)
	(segment
		(start 110.058454 -285.171388)
		(end 110.060994 -285.169864)
		(width 0.0889)
		(layer "In6.Cu")
		(net "UPI_CPU0_CPU1_P2P2_DP<23>")
	)
	(segment
		(start 290.917122 -318.050672)
		(end 290.586668 -318.381126)
		(width 0.14732)
		(layer "In6.Cu")
		(net "UPI_CPU0_CPU1_P2P2_DP<23>")
	)
	(segment
		(start 252.968252 -344.60307)
		(end 252.968252 -345.038426)
		(width 0.14732)
		(layer "In6.Cu")
		(net "UPI_CPU0_CPU1_P2P2_DP<23>")
	)
	(segment
		(start 252.66142 -343.04605)
		(end 252.45314 -343.04605)
		(width 0.14732)
		(layer "In6.Cu")
		(net "UPI_CPU0_CPU1_P2P2_DP<23>")
	)
	(segment
		(start 299.842428 -315.112146)
		(end 299.80382 -315.311028)
		(width 0.14732)
		(layer "In6.Cu")
		(net "UPI_CPU0_CPU1_P2P2_DP<23>")
	)
	(segment
		(start 253.593346 -343.977976)
		(end 252.66142 -343.04605)
		(width 0.14732)
		(layer "In6.Cu")
		(net "UPI_CPU0_CPU1_P2P2_DP<23>")
	)
	(segment
		(start 252.036326 -343.671144)
		(end 252.968252 -344.60307)
		(width 0.14732)
		(layer "In6.Cu")
		(net "UPI_CPU0_CPU1_P2P2_DP<23>")
	)
	(segment
		(start 302.064928 -313.09818)
		(end 299.842428 -315.112146)
		(width 0.14732)
		(layer "In6.Cu")
		(net "UPI_CPU0_CPU1_P2P2_DP<23>")
	)
	(segment
		(start 108.573062 -297.875198)
		(end 108.881164 -297.131486)
		(width 0.14732)
		(layer "In6.Cu")
		(net "UPI_CPU0_CPU1_P2P2_DP<23>")
	)
	(segment
		(start 251.329444 -346.241878)
		(end 251.329444 -346.677234)
		(width 0.14732)
		(layer "In6.Cu")
		(net "UPI_CPU0_CPU1_P2P2_DP<23>")
	)
	(segment
		(start 111.184944 -275.094954)
		(end 111.184944 -275.072094)
		(width 0.0889)
		(layer "In6.Cu")
		(net "UPI_CPU0_CPU1_P2P2_DP<23>")
	)
	(segment
		(start 107.80395 -274.756372)
		(end 107.79506 -274.761452)
		(width 0.0889)
		(layer "In6.Cu")
		(net "UPI_CPU0_CPU1_P2P2_DP<23>")
	)
	(segment
		(start 111.946182 -276.389338)
		(end 111.937292 -276.384258)
		(width 0.0889)
		(layer "In6.Cu")
		(net "UPI_CPU0_CPU1_P2P2_DP<23>")
	)
	(segment
		(start 290.161726 -322.217288)
		(end 288.377884 -322.217288)
		(width 0.14732)
		(layer "In6.Cu")
		(net "UPI_CPU0_CPU1_P2P2_DP<23>")
	)
	(segment
		(start 250.751086 -347.255592)
		(end 250.31573 -347.255592)
		(width 0.14732)
		(layer "In6.Cu")
		(net "UPI_CPU0_CPU1_P2P2_DP<23>")
	)
	(segment
		(start 250.31573 -347.255592)
		(end 249.383804 -346.323666)
		(width 0.14732)
		(layer "In6.Cu")
		(net "UPI_CPU0_CPU1_P2P2_DP<23>")
	)
	(segment
		(start 255.939036 -339.768434)
		(end 255.730756 -339.768434)
		(width 0.14732)
		(layer "In6.Cu")
		(net "UPI_CPU0_CPU1_P2P2_DP<23>")
	)
	(segment
		(start 109.11967 -291.179758)
		(end 109.305344 -290.994084)
		(width 0.0889)
		(layer "In6.Cu")
		(net "UPI_CPU0_CPU1_P2P2_DP<23>")
	)
	(segment
		(start 109.07776 -292.30066)
		(end 109.07776 -291.648388)
		(width 0.14732)
		(layer "In6.Cu")
		(net "UPI_CPU0_CPU1_P2P2_DP<23>")
	)
	(segment
		(start 288.377884 -322.217288)
		(end 287.955228 -321.794632)
		(width 0.14732)
		(layer "In6.Cu")
		(net "UPI_CPU0_CPU1_P2P2_DP<23>")
	)
	(segment
		(start 268.713966 -323.0372)
		(end 268.566646 -322.88988)
		(width 0.14732)
		(layer "In6.Cu")
		(net "UPI_CPU0_CPU1_P2P2_DP<23>")
	)
	(segment
		(start 109.117892 -286.799782)
		(end 109.126782 -286.794702)
		(width 0.0889)
		(layer "In6.Cu")
		(net "UPI_CPU0_CPU1_P2P2_DP<23>")
	)
	(segment
		(start 250.397518 -345.101672)
		(end 250.397518 -345.309952)
		(width 0.14732)
		(layer "In6.Cu")
		(net "UPI_CPU0_CPU1_P2P2_DP<23>")
	)
	(segment
		(start 265.6078 -322.88988)
		(end 262.04926 -326.44842)
		(width 0.14732)
		(layer "In6.Cu")
		(net "UPI_CPU0_CPU1_P2P2_DP<23>")
	)
	(segment
		(start 262.04926 -326.44842)
		(end 262.04926 -333.44993)
		(width 0.14732)
		(layer "In6.Cu")
		(net "UPI_CPU0_CPU1_P2P2_DP<23>")
	)
	(segment
		(start 250.814332 -344.684858)
		(end 250.397518 -345.101672)
		(width 0.14732)
		(layer "In6.Cu")
		(net "UPI_CPU0_CPU1_P2P2_DP<23>")
	)
	(segment
		(start 287.955228 -321.794632)
		(end 286.601916 -321.794632)
		(width 0.14732)
		(layer "In6.Cu")
		(net "UPI_CPU0_CPU1_P2P2_DP<23>")
	)
	(segment
		(start 254.091948 -341.407242)
		(end 253.675134 -341.824056)
		(width 0.14732)
		(layer "In6.Cu")
		(net "UPI_CPU0_CPU1_P2P2_DP<23>")
	)
	(segment
		(start 111.476536 -275.575522)
		(end 111.467646 -275.570442)
		(width 0.0889)
		(layer "In6.Cu")
		(net "UPI_CPU0_CPU1_P2P2_DP<23>")
	)
	(segment
		(start 272.798794 -323.84111)
		(end 272.490946 -323.533262)
		(width 0.14732)
		(layer "In6.Cu")
		(net "UPI_CPU0_CPU1_P2P2_DP<23>")
	)
	(segment
		(start 98.771964 -308.390036)
		(end 107.832652 -298.873672)
		(width 0.14732)
		(layer "In6.Cu")
		(net "UPI_CPU0_CPU1_P2P2_DP<23>")
	)
	(segment
		(start 260.583934 -337.422744)
		(end 260.148578 -337.422744)
		(width 0.14732)
		(layer "In6.Cu")
		(net "UPI_CPU0_CPU1_P2P2_DP<23>")
	)
	(segment
		(start 257.884676 -339.686646)
		(end 257.884676 -340.122002)
		(width 0.14732)
		(layer "In6.Cu")
		(net "UPI_CPU0_CPU1_P2P2_DP<23>")
	)
	(segment
		(start 283.958792 -322.88988)
		(end 274.070826 -322.88988)
		(width 0.14732)
		(layer "In6.Cu")
		(net "UPI_CPU0_CPU1_P2P2_DP<23>")
	)
	(segment
		(start 75.616308 -350.873822)
		(end 75.616308 -335.144364)
		(width 0.14732)
		(layer "In6.Cu")
		(net "UPI_CPU0_CPU1_P2P2_DP<23>")
	)
	(segment
		(start 274.070826 -322.88988)
		(end 273.923506 -323.0372)
		(width 0.14732)
		(layer "In6.Cu")
		(net "UPI_CPU0_CPU1_P2P2_DP<23>")
	)
	(segment
		(start 256.245868 -341.76081)
		(end 255.66751 -342.339168)
		(width 0.14732)
		(layer "In6.Cu")
		(net "UPI_CPU0_CPU1_P2P2_DP<23>")
	)
	(segment
		(start 109.07776 -291.638228)
		(end 109.11967 -291.596318)
		(width 0.0889)
		(layer "In6.Cu")
		(net "UPI_CPU0_CPU1_P2P2_DP<23>")
	)
	(segment
		(start 254.028702 -343.977976)
		(end 253.593346 -343.977976)
		(width 0.14732)
		(layer "In6.Cu")
		(net "UPI_CPU0_CPU1_P2P2_DP<23>")
	)
	(segment
		(start 111.46917 -282.08224)
		(end 111.467646 -282.081478)
		(width 0.0889)
		(layer "In6.Cu")
		(net "UPI_CPU0_CPU1_P2P2_DP<23>")
	)
	(segment
		(start 108.365544 -288.216086)
		(end 108.365544 -288.103056)
		(width 0.0889)
		(layer "In6.Cu")
		(net "UPI_CPU0_CPU1_P2P2_DP<23>")
	)
	(segment
		(start 332.420976 -287.315148)
		(end 332.420976 -287.58769)
		(width 0.14732)
		(layer "In6.Cu")
		(net "UPI_CPU0_CPU1_P2P2_DP<23>")
	)
	(segment
		(start 251.022612 -344.684858)
		(end 250.814332 -344.684858)
		(width 0.14732)
		(layer "In6.Cu")
		(net "UPI_CPU0_CPU1_P2P2_DP<23>")
	)
	(segment
		(start 258.591558 -337.115912)
		(end 259.523484 -338.047838)
		(width 0.14732)
		(layer "In6.Cu")
		(net "UPI_CPU0_CPU1_P2P2_DP<23>")
	)
	(segment
		(start 111.467646 -282.081478)
		(end 111.464852 -282.079954)
		(width 0.0889)
		(layer "In6.Cu")
		(net "UPI_CPU0_CPU1_P2P2_DP<23>")
	)
	(segment
		(start 314.11545 -307.884576)
		(end 313.9313 -307.9623)
		(width 0.14732)
		(layer "In6.Cu")
		(net "UPI_CPU0_CPU1_P2P2_DP<23>")
	)
	(segment
		(start 112.594644 -279.158954)
		(end 112.594644 -279.141682)
		(width 0.0889)
		(layer "In6.Cu")
		(net "UPI_CPU0_CPU1_P2P2_DP<23>")
	)
	(segment
		(start 332.42123 -287.179766)
		(end 332.42123 -287.314894)
		(width 0.14732)
		(layer "In6.Cu")
		(net "UPI_CPU0_CPU1_P2P2_DP<23>")
	)
	(segment
		(start 297.097196 -317.213742)
		(end 296.64279 -317.213742)
		(width 0.14732)
		(layer "In6.Cu")
		(net "UPI_CPU0_CPU1_P2P2_DP<23>")
	)
	(segment
		(start 112.594644 -277.531068)
		(end 112.594644 -277.513796)
		(width 0.0889)
		(layer "In6.Cu")
		(net "UPI_CPU0_CPU1_P2P2_DP<23>")
	)
	(segment
		(start 112.406684 -277.197566)
		(end 112.40135 -277.194518)
		(width 0.0889)
		(layer "In6.Cu")
		(net "UPI_CPU0_CPU1_P2P2_DP<23>")
	)
	(segment
		(start 256.95275 -338.75472)
		(end 257.884676 -339.686646)
		(width 0.14732)
		(layer "In6.Cu")
		(net "UPI_CPU0_CPU1_P2P2_DP<23>")
	)
	(segment
		(start 76.587604 -328.714354)
		(end 77.69606 -326.369172)
		(width 0.14732)
		(layer "In6.Cu")
		(net "UPI_CPU0_CPU1_P2P2_DP<23>")
	)
	(segment
		(start 270.293846 -322.88988)
		(end 270.146526 -323.0372)
		(width 0.14732)
		(layer "In6.Cu")
		(net "UPI_CPU0_CPU1_P2P2_DP<23>")
	)
	(segment
		(start 110.060994 -285.169864)
		(end 110.066582 -285.166816)
		(width 0.0889)
		(layer "In6.Cu")
		(net "UPI_CPU0_CPU1_P2P2_DP<23>")
	)
	(segment
		(start 257.306318 -340.70036)
		(end 256.870962 -340.70036)
		(width 0.14732)
		(layer "In6.Cu")
		(net "UPI_CPU0_CPU1_P2P2_DP<23>")
	)
	(segment
		(start 253.675134 -342.032336)
		(end 254.60706 -342.964262)
		(width 0.14732)
		(layer "In6.Cu")
		(net "UPI_CPU0_CPU1_P2P2_DP<23>")
	)
	(segment
		(start 306.963826 -311.068466)
		(end 302.064928 -313.09818)
		(width 0.14732)
		(layer "In6.Cu")
		(net "UPI_CPU0_CPU1_P2P2_DP<23>")
	)
	(segment
		(start 76.06284 -330.605638)
		(end 76.587604 -328.714354)
		(width 0.14732)
		(layer "In6.Cu")
		(net "UPI_CPU0_CPU1_P2P2_DP<23>")
	)
	(segment
		(start 260.230366 -335.268824)
		(end 260.230366 -335.477104)
		(width 0.14732)
		(layer "In6.Cu")
		(net "UPI_CPU0_CPU1_P2P2_DP<23>")
	)
	(segment
		(start 108.835698 -288.962592)
		(end 108.84027 -288.873946)
		(width 0.0889)
		(layer "In6.Cu")
		(net "UPI_CPU0_CPU1_P2P2_DP<23>")
	)
	(segment
		(start 108.835444 -287.297876)
		(end 108.835444 -287.279334)
		(width 0.0889)
		(layer "In6.Cu")
		(net "UPI_CPU0_CPU1_P2P2_DP<23>")
	)
	(segment
		(start 249.175524 -346.323666)
		(end 248.567702 -346.931488)
		(width 0.14732)
		(layer "In6.Cu")
		(net "UPI_CPU0_CPU1_P2P2_DP<23>")
	)
	(segment
		(start 82.172048 -361.960922)
		(end 78.817978 -358.606852)
		(width 0.14732)
		(layer "In6.Cu")
		(net "UPI_CPU0_CPU1_P2P2_DP<23>")
	)
	(segment
		(start 107.616498 -275.08073)
		(end 107.616498 -275.094954)
		(width 0.0889)
		(layer "In6.Cu")
		(net "UPI_CPU0_CPU1_P2P2_DP<23>")
	)
	(segment
		(start 290.586668 -318.381126)
		(end 290.586668 -321.792346)
		(width 0.14732)
		(layer "In6.Cu")
		(net "UPI_CPU0_CPU1_P2P2_DP<23>")
	)
	(segment
		(start 259.216652 -336.490818)
		(end 259.008372 -336.490818)
		(width 0.14732)
		(layer "In6.Cu")
		(net "UPI_CPU0_CPU1_P2P2_DP<23>")
	)
	(segment
		(start 272.490946 -323.533262)
		(end 272.490946 -323.0372)
		(width 0.14732)
		(layer "In6.Cu")
		(net "UPI_CPU0_CPU1_P2P2_DP<23>")
	)
	(segment
		(start 108.743496 -274.756372)
		(end 108.733082 -274.762468)
		(width 0.0889)
		(layer "In6.Cu")
		(net "UPI_CPU0_CPU1_P2P2_DP<23>")
	)
	(segment
		(start 228.181408 -365.95431)
		(end 215.292686 -368.226848)
		(width 0.14732)
		(layer "In6.Cu")
		(net "UPI_CPU0_CPU1_P2P2_DP<23>")
	)
	(segment
		(start 299.80382 -317.454534)
		(end 299.283374 -318.084708)
		(width 0.14732)
		(layer "In6.Cu")
		(net "UPI_CPU0_CPU1_P2P2_DP<23>")
	)
	(segment
		(start 251.954538 -345.616784)
		(end 251.022612 -344.684858)
		(width 0.14732)
		(layer "In6.Cu")
		(net "UPI_CPU0_CPU1_P2P2_DP<23>")
	)
	(segment
		(start 104.858058 -275.623782)
		(end 104.701594 -275.8948)
		(width 0.0889)
		(layer "In6.Cu")
		(net "UPI_CPU0_CPU1_P2P2_DP<23>")
	)
	(segment
		(start 255.313942 -340.185248)
		(end 255.313942 -340.393528)
		(width 0.14732)
		(layer "In6.Cu")
		(net "UPI_CPU0_CPU1_P2P2_DP<23>")
	)
	(segment
		(start 251.329444 -346.677234)
		(end 250.751086 -347.255592)
		(width 0.14732)
		(layer "In6.Cu")
		(net "UPI_CPU0_CPU1_P2P2_DP<23>")
	)
	(segment
		(start 334.002888 -284.847538)
		(end 333.937356 -284.91307)
		(width 0.0889)
		(layer "In6.Cu")
		(net "UPI_CPU0_CPU1_P2P2_DP<23>")
	)
	(segment
		(start 111.467646 -282.730194)
		(end 111.476536 -282.725114)
		(width 0.0889)
		(layer "In6.Cu")
		(net "UPI_CPU0_CPU1_P2P2_DP<23>")
	)
	(segment
		(start 297.968162 -318.084708)
		(end 297.097196 -317.213742)
		(width 0.14732)
		(layer "In6.Cu")
		(net "UPI_CPU0_CPU1_P2P2_DP<23>")
	)
	(segment
		(start 308.19852 -310.24322)
		(end 306.963826 -311.068466)
		(width 0.14732)
		(layer "In6.Cu")
		(net "UPI_CPU0_CPU1_P2P2_DP<23>")
	)
	(segment
		(start 259.008372 -336.490818)
		(end 258.591558 -336.907632)
		(width 0.14732)
		(layer "In6.Cu")
		(net "UPI_CPU0_CPU1_P2P2_DP<23>")
	)
	(segment
		(start 311.775348 -307.9623)
		(end 310.332628 -308.560216)
		(width 0.14732)
		(layer "In6.Cu")
		(net "UPI_CPU0_CPU1_P2P2_DP<23>")
	)
	(segment
		(start 259.523484 -338.483194)
		(end 258.945126 -339.061552)
		(width 0.14732)
		(layer "In6.Cu")
		(net "UPI_CPU0_CPU1_P2P2_DP<23>")
	)
	(segment
		(start 295.80586 -318.050672)
		(end 290.917122 -318.050672)
		(width 0.14732)
		(layer "In6.Cu")
		(net "UPI_CPU0_CPU1_P2P2_DP<23>")
	)
	(segment
		(start 272.343626 -322.88988)
		(end 270.293846 -322.88988)
		(width 0.14732)
		(layer "In6.Cu")
		(net "UPI_CPU0_CPU1_P2P2_DP<23>")
	)
	(segment
		(start 334.315562 -284.847538)
		(end 334.002888 -284.847538)
		(width 0.0889)
		(layer "In6.Cu")
		(net "UPI_CPU0_CPU1_P2P2_DP<23>")
	)
	(segment
		(start 110.057692 -285.171896)
		(end 110.058454 -285.171388)
		(width 0.0889)
		(layer "In6.Cu")
		(net "UPI_CPU0_CPU1_P2P2_DP<23>")
	)
	(segment
		(start 112.124744 -278.336502)
		(end 112.124744 -278.322278)
		(width 0.0889)
		(layer "In6.Cu")
		(net "UPI_CPU0_CPU1_P2P2_DP<23>")
	)
	(segment
		(start 269.838678 -324.791578)
		(end 269.021814 -324.791578)
		(width 0.14732)
		(layer "In6.Cu")
		(net "UPI_CPU0_CPU1_P2P2_DP<23>")
	)
	(segment
		(start 329.573636 -292.045898)
		(end 327.612248 -298.489116)
		(width 0.14732)
		(layer "In6.Cu")
		(net "UPI_CPU0_CPU1_P2P2_DP<23>")
	)
	(segment
		(start 152.913842 -373.498364)
		(end 126.43612 -373.498364)
		(width 0.14732)
		(layer "In6.Cu")
		(net "UPI_CPU0_CPU1_P2P2_DP<23>")
	)
	(segment
		(start 109.13745 -289.49396)
		(end 109.117892 -289.482784)
		(width 0.0889)
		(layer "In6.Cu")
		(net "UPI_CPU0_CPU1_P2P2_DP<23>")
	)
	(segment
		(start 258.945126 -339.061552)
		(end 258.50977 -339.061552)
		(width 0.14732)
		(layer "In6.Cu")
		(net "UPI_CPU0_CPU1_P2P2_DP<23>")
	)
	(segment
		(start 268.566646 -322.88988)
		(end 265.6078 -322.88988)
		(width 0.14732)
		(layer "In6.Cu")
		(net "UPI_CPU0_CPU1_P2P2_DP<23>")
	)
	(segment
		(start 256.95275 -338.54644)
		(end 256.95275 -338.75472)
		(width 0.14732)
		(layer "In6.Cu")
		(net "UPI_CPU0_CPU1_P2P2_DP<23>")
	)
	(segment
		(start 81.503774 -322.561204)
		(end 98.771964 -308.390036)
		(width 0.14732)
		(layer "In6.Cu")
		(net "UPI_CPU0_CPU1_P2P2_DP<23>")
	)
	(segment
		(start 109.117892 -289.482784)
		(end 109.097318 -289.470846)
		(width 0.0889)
		(layer "In6.Cu")
		(net "UPI_CPU0_CPU1_P2P2_DP<23>")
	)
	(segment
		(start 252.968252 -345.038426)
		(end 252.389894 -345.616784)
		(width 0.14732)
		(layer "In6.Cu")
		(net "UPI_CPU0_CPU1_P2P2_DP<23>")
	)
	(segment
		(start 256.245868 -341.325454)
		(end 256.245868 -341.76081)
		(width 0.14732)
		(layer "In6.Cu")
		(net "UPI_CPU0_CPU1_P2P2_DP<23>")
	)
	(segment
		(start 260.230366 -335.477104)
		(end 261.162292 -336.40903)
		(width 0.14732)
		(layer "In6.Cu")
		(net "UPI_CPU0_CPU1_P2P2_DP<23>")
	)
	(segment
		(start 111.476536 -282.086558)
		(end 111.46917 -282.08224)
		(width 0.0889)
		(layer "In6.Cu")
		(net "UPI_CPU0_CPU1_P2P2_DP<23>")
	)
	(segment
		(start 255.313942 -340.393528)
		(end 256.245868 -341.325454)
		(width 0.14732)
		(layer "In6.Cu")
		(net "UPI_CPU0_CPU1_P2P2_DP<23>")
	)
	(segment
		(start 308.97322 -309.46852)
		(end 308.19852 -310.24322)
		(width 0.14732)
		(layer "In6.Cu")
		(net "UPI_CPU0_CPU1_P2P2_DP<23>")
	)
	(segment
		(start 260.148578 -337.422744)
		(end 259.216652 -336.490818)
		(width 0.14732)
		(layer "In6.Cu")
		(net "UPI_CPU0_CPU1_P2P2_DP<23>")
	)
	(segment
		(start 257.369564 -338.129626)
		(end 256.95275 -338.54644)
		(width 0.14732)
		(layer "In6.Cu")
		(net "UPI_CPU0_CPU1_P2P2_DP<23>")
	)
	(segment
		(start 111.476536 -281.097228)
		(end 111.476536 -281.097482)
		(width 0.0889)
		(layer "In6.Cu")
		(net "UPI_CPU0_CPU1_P2P2_DP<23>")
	)
	(segment
		(start 313.9313 -307.9623)
		(end 311.775348 -307.9623)
		(width 0.14732)
		(layer "In6.Cu")
		(net "UPI_CPU0_CPU1_P2P2_DP<23>")
	)
	(segment
		(start 270.146526 -324.48373)
		(end 269.838678 -324.791578)
		(width 0.14732)
		(layer "In6.Cu")
		(net "UPI_CPU0_CPU1_P2P2_DP<23>")
	)
	(segment
		(start 109.305344 -290.994084)
		(end 109.305344 -289.827208)
		(width 0.0889)
		(layer "In6.Cu")
		(net "UPI_CPU0_CPU1_P2P2_DP<23>")
	)
	(segment
		(start 258.50977 -339.061552)
		(end 257.577844 -338.129626)
		(width 0.14732)
		(layer "In6.Cu")
		(net "UPI_CPU0_CPU1_P2P2_DP<23>")
	)
	(segment
		(start 258.591558 -336.907632)
		(end 258.591558 -337.115912)
		(width 0.14732)
		(layer "In6.Cu")
		(net "UPI_CPU0_CPU1_P2P2_DP<23>")
	)
	(segment
		(start 290.586668 -321.792346)
		(end 290.161726 -322.217288)
		(width 0.14732)
		(layer "In6.Cu")
		(net "UPI_CPU0_CPU1_P2P2_DP<23>")
	)
	(segment
		(start 111.464852 -282.079954)
		(end 111.46155 -282.077922)
		(width 0.0889)
		(layer "In6.Cu")
		(net "UPI_CPU0_CPU1_P2P2_DP<23>")
	)
	(segment
		(start 254.60706 -343.399618)
		(end 254.028702 -343.977976)
		(width 0.14732)
		(layer "In6.Cu")
		(net "UPI_CPU0_CPU1_P2P2_DP<23>")
	)
	(segment
		(start 108.881164 -292.775132)
		(end 109.07776 -292.30066)
		(width 0.14732)
		(layer "In6.Cu")
		(net "UPI_CPU0_CPU1_P2P2_DP<23>")
	)
	(segment
		(start 215.292686 -368.226848)
		(end 199.051418 -365.363252)
		(width 0.14732)
		(layer "In6.Cu")
		(net "UPI_CPU0_CPU1_P2P2_DP<23>")
	)
	(segment
		(start 112.407446 -277.198074)
		(end 112.406684 -277.197566)
		(width 0.0889)
		(layer "In6.Cu")
		(net "UPI_CPU0_CPU1_P2P2_DP<23>")
	)
	(segment
		(start 109.07776 -291.648388)
		(end 109.07776 -291.638228)
		(width 0.0889)
		(layer "In6.Cu")
		(net "UPI_CPU0_CPU1_P2P2_DP<23>")
	)
	(segment
		(start 272.490946 -323.0372)
		(end 272.343626 -322.88988)
		(width 0.14732)
		(layer "In6.Cu")
		(net "UPI_CPU0_CPU1_P2P2_DP<23>")
	)
	(segment
		(start 262.04926 -333.44993)
		(end 260.230366 -335.268824)
		(width 0.14732)
		(layer "In6.Cu")
		(net "UPI_CPU0_CPU1_P2P2_DP<23>")
	)
	(segment
		(start 253.675134 -341.824056)
		(end 253.675134 -342.032336)
		(width 0.14732)
		(layer "In6.Cu")
		(net "UPI_CPU0_CPU1_P2P2_DP<23>")
	)
	(segment
		(start 112.406684 -279.475184)
		(end 112.407446 -279.474676)
		(width 0.0889)
		(layer "In6.Cu")
		(net "UPI_CPU0_CPU1_P2P2_DP<23>")
	)
	(segment
		(start 107.832652 -298.873672)
		(end 108.573062 -297.875198)
		(width 0.14732)
		(layer "In6.Cu")
		(net "UPI_CPU0_CPU1_P2P2_DP<23>")
	)
	(segment
		(start 332.42123 -287.314894)
		(end 332.420976 -287.315148)
		(width 0.14732)
		(layer "In6.Cu")
		(net "UPI_CPU0_CPU1_P2P2_DP<23>")
	)
	(segment
		(start 327.612248 -298.489116)
		(end 318.216788 -307.884576)
		(width 0.14732)
		(layer "In6.Cu")
		(net "UPI_CPU0_CPU1_P2P2_DP<23>")
	)
	(segment
		(start 111.655098 -275.910294)
		(end 111.655098 -275.8948)
		(width 0.0889)
		(layer "In6.Cu")
		(net "UPI_CPU0_CPU1_P2P2_DP<23>")
	)
	(segment
		(start 333.225902 -285.490666)
		(end 332.379066 -286.337248)
		(width 0.0889)
		(layer "In6.Cu")
		(net "UPI_CPU0_CPU1_P2P2_DP<23>")
	)
	(segment
		(start 244.11432 -354.797106)
		(end 228.181408 -365.95431)
		(width 0.14732)
		(layer "In6.Cu")
		(net "UPI_CPU0_CPU1_P2P2_DP<23>")
	)
	(segment
		(start 257.884676 -340.122002)
		(end 257.306318 -340.70036)
		(width 0.14732)
		(layer "In6.Cu")
		(net "UPI_CPU0_CPU1_P2P2_DP<23>")
	)
	(segment
		(start 252.389894 -345.616784)
		(end 251.954538 -345.616784)
		(width 0.14732)
		(layer "In6.Cu")
		(net "UPI_CPU0_CPU1_P2P2_DP<23>")
	)
	(segment
		(start 109.775244 -285.661354)
		(end 109.775244 -285.651448)
		(width 0.0889)
		(layer "In6.Cu")
		(net "UPI_CPU0_CPU1_P2P2_DP<23>")
	)
	(segment
		(start 269.021814 -324.791578)
		(end 268.713966 -324.48373)
		(width 0.14732)
		(layer "In6.Cu")
		(net "UPI_CPU0_CPU1_P2P2_DP<23>")
	)
	(segment
		(start 110.068106 -274.762468)
		(end 110.057692 -274.756372)
		(width 0.0889)
		(layer "In6.Cu")
		(net "UPI_CPU0_CPU1_P2P2_DP<23>")
	)
	(segment
		(start 273.923506 -323.0372)
		(end 273.923506 -323.533262)
		(width 0.14732)
		(layer "In6.Cu")
		(net "UPI_CPU0_CPU1_P2P2_DP<23>")
	)
	(segment
		(start 299.283374 -318.084708)
		(end 297.968162 -318.084708)
		(width 0.14732)
		(layer "In6.Cu")
		(net "UPI_CPU0_CPU1_P2P2_DP<23>")
	)
	(segment
		(start 250.397518 -345.309952)
		(end 251.329444 -346.241878)
		(width 0.14732)
		(layer "In6.Cu")
		(net "UPI_CPU0_CPU1_P2P2_DP<23>")
	)
	(segment
		(start 100.87229 -369.706398)
		(end 82.172048 -361.960922)
		(width 0.14732)
		(layer "In6.Cu")
		(net "UPI_CPU0_CPU1_P2P2_DP<23>")
	)
	(segment
		(start 255.232154 -342.339168)
		(end 254.300228 -341.407242)
		(width 0.14732)
		(layer "In6.Cu")
		(net "UPI_CPU0_CPU1_P2P2_DP<23>")
	)
	(segment
		(start 110.521496 -284.361636)
		(end 110.527592 -284.35808)
		(width 0.0889)
		(layer "In6.Cu")
		(net "UPI_CPU0_CPU1_P2P2_DP<23>")
	)
	(segment
		(start 252.45314 -343.04605)
		(end 252.036326 -343.462864)
		(width 0.14732)
		(layer "In6.Cu")
		(net "UPI_CPU0_CPU1_P2P2_DP<23>")
	)
	(segment
		(start 332.187042 -288.152332)
		(end 329.573636 -292.045898)
		(width 0.14732)
		(layer "In6.Cu")
		(net "UPI_CPU0_CPU1_P2P2_DP<23>")
	)
	(segment
		(start 273.615658 -323.84111)
		(end 272.798794 -323.84111)
		(width 0.14732)
		(layer "In6.Cu")
		(net "UPI_CPU0_CPU1_P2P2_DP<23>")
	)
	(segment
		(start 273.923506 -323.533262)
		(end 273.615658 -323.84111)
		(width 0.14732)
		(layer "In6.Cu")
		(net "UPI_CPU0_CPU1_P2P2_DP<23>")
	)
	(segment
		(start 299.80382 -315.311028)
		(end 299.80382 -317.454534)
		(width 0.14732)
		(layer "In6.Cu")
		(net "UPI_CPU0_CPU1_P2P2_DP<23>")
	)
	(segment
		(start 286.601916 -321.794632)
		(end 283.958792 -322.88988)
		(width 0.14732)
		(layer "In6.Cu")
		(net "UPI_CPU0_CPU1_P2P2_DP<23>")
	)
	(segment
		(start 296.64279 -317.213742)
		(end 295.80586 -318.050672)
		(width 0.14732)
		(layer "In6.Cu")
		(net "UPI_CPU0_CPU1_P2P2_DP<23>")
	)
	(segment
		(start 261.162292 -336.844386)
		(end 260.583934 -337.422744)
		(width 0.14732)
		(layer "In6.Cu")
		(net "UPI_CPU0_CPU1_P2P2_DP<23>")
	)
	(segment
		(start 248.567702 -350.343724)
		(end 244.11432 -354.797106)
		(width 0.14732)
		(layer "In6.Cu")
		(net "UPI_CPU0_CPU1_P2P2_DP<23>")
	)
	(segment
		(start 254.60706 -342.964262)
		(end 254.60706 -343.399618)
		(width 0.14732)
		(layer "In6.Cu")
		(net "UPI_CPU0_CPU1_P2P2_DP<23>")
	)
	(segment
		(start 270.146526 -323.0372)
		(end 270.146526 -324.48373)
		(width 0.14732)
		(layer "In6.Cu")
		(net "UPI_CPU0_CPU1_P2P2_DP<23>")
	)
	(segment
		(start 75.616308 -335.144364)
		(end 76.06284 -330.605638)
		(width 0.14732)
		(layer "In6.Cu")
		(net "UPI_CPU0_CPU1_P2P2_DP<23>")
	)
	(segment
		(start 261.162292 -336.40903)
		(end 261.162292 -336.844386)
		(width 0.14732)
		(layer "In6.Cu")
		(net "UPI_CPU0_CPU1_P2P2_DP<23>")
	)
	(segment
		(start 257.577844 -338.129626)
		(end 257.369564 -338.129626)
		(width 0.14732)
		(layer "In6.Cu")
		(net "UPI_CPU0_CPU1_P2P2_DP<23>")
	)
	(segment
		(start 109.587792 -285.985712)
		(end 109.596682 -285.980632)
		(width 0.0889)
		(layer "In6.Cu")
		(net "UPI_CPU0_CPU1_P2P2_DP<23>")
	)
	(segment
		(start 77.69606 -326.369172)
		(end 81.503774 -322.561204)
		(width 0.14732)
		(layer "In6.Cu")
		(net "UPI_CPU0_CPU1_P2P2_DP<23>")
	)
	(segment
		(start 310.332628 -308.560216)
		(end 308.97322 -309.46852)
		(width 0.14732)
		(layer "In6.Cu")
		(net "UPI_CPU0_CPU1_P2P2_DP<23>")
	)
	(segment
		(start 256.870962 -340.70036)
		(end 255.939036 -339.768434)
		(width 0.14732)
		(layer "In6.Cu")
		(net "UPI_CPU0_CPU1_P2P2_DP<23>")
	)
	(segment
		(start 259.523484 -338.047838)
		(end 259.523484 -338.483194)
		(width 0.14732)
		(layer "In6.Cu")
		(net "UPI_CPU0_CPU1_P2P2_DP<23>")
	)
	(segment
		(start 332.379066 -286.337248)
		(end 332.379066 -287.115504)
		(width 0.0889)
		(layer "In6.Cu")
		(net "UPI_CPU0_CPU1_P2P2_DP<23>")
	)
	(segment
		(start 107.333796 -275.570442)
		(end 107.319064 -275.579078)
		(width 0.0889)
		(layer "In6.Cu")
		(net "UPI_CPU0_CPU1_P2P2_DP<23>")
	)
	(segment
		(start 110.993682 -283.54655)
		(end 110.997746 -283.544264)
		(width 0.0889)
		(layer "In6.Cu")
		(net "UPI_CPU0_CPU1_P2P2_DP<23>")
	)
	(segment
		(start 252.036326 -343.462864)
		(end 252.036326 -343.671144)
		(width 0.14732)
		(layer "In6.Cu")
		(net "UPI_CPU0_CPU1_P2P2_DP<23>")
	)
	(segment
		(start 333.417672 -285.411164)
		(end 333.225902 -285.490666)
		(width 0.0889)
		(layer "In6.Cu")
		(net "UPI_CPU0_CPU1_P2P2_DP<23>")
	)
	(segment
		(start 254.300228 -341.407242)
		(end 254.091948 -341.407242)
		(width 0.14732)
		(layer "In6.Cu")
		(net "UPI_CPU0_CPU1_P2P2_DP<23>")
	)
	(segment
		(start 255.730756 -339.768434)
		(end 255.313942 -340.185248)
		(width 0.14732)
		(layer "In6.Cu")
		(net "UPI_CPU0_CPU1_P2P2_DP<23>")
	)
	(segment
		(start 199.051418 -365.363252)
		(end 152.913842 -373.498364)
		(width 0.14732)
		(layer "In6.Cu")
		(net "UPI_CPU0_CPU1_P2P2_DP<23>")
	)
	(segment
		(start 111.184944 -283.228542)
		(end 111.184944 -283.205682)
		(width 0.0889)
		(layer "In6.Cu")
		(net "UPI_CPU0_CPU1_P2P2_DP<23>")
	)
	(segment
		(start 268.713966 -324.48373)
		(end 268.713966 -323.0372)
		(width 0.14732)
		(layer "In6.Cu")
		(net "UPI_CPU0_CPU1_P2P2_DP<23>")
	)
	(segment
		(start 109.305344 -286.475424)
		(end 109.305344 -286.456882)
		(width 0.0889)
		(layer "In6.Cu")
		(net "UPI_CPU0_CPU1_P2P2_DP<23>")
	)
	(segment
		(start 105.83926 -275.576538)
		(end 105.828846 -275.570442)
		(width 0.0889)
		(layer "In6.Cu")
		(net "UPI_CPU0_CPU1_P2P2_DP<23>")
	)
	(segment
		(start 110.985554 -283.551376)
		(end 110.993682 -283.54655)
		(width 0.0889)
		(layer "In6.Cu")
		(net "UPI_CPU0_CPU1_P2P2_DP<23>")
	)
	(segment
		(start 104.947212 -275.599906)
		(end 104.858058 -275.623782)
		(width 0.0889)
		(layer "In6.Cu")
		(net "UPI_CPU0_CPU1_P2P2_DP<23>")
	)
	(segment
		(start 110.527592 -284.35808)
		(end 110.536482 -284.353)
		(width 0.0889)
		(layer "In6.Cu")
		(net "UPI_CPU0_CPU1_P2P2_DP<23>")
	)
	(segment
		(start 111.655098 -280.778204)
		(end 111.655098 -280.756106)
		(width 0.0889)
		(layer "In6.Cu")
		(net "UPI_CPU0_CPU1_P2P2_DP<23>")
	)
	(segment
		(start 255.66751 -342.339168)
		(end 255.232154 -342.339168)
		(width 0.14732)
		(layer "In6.Cu")
		(net "UPI_CPU0_CPU1_P2P2_DP<23>")
	)
	(segment
		(start 126.43612 -373.498364)
		(end 100.87229 -369.706398)
		(width 0.14732)
		(layer "In6.Cu")
		(net "UPI_CPU0_CPU1_P2P2_DP<23>")
	)
	(segment
		(start 78.817978 -358.606852)
		(end 75.616308 -350.873822)
		(width 0.14732)
		(layer "In6.Cu")
		(net "UPI_CPU0_CPU1_P2P2_DP<23>")
	)
	(arc
		(start 112.12449 -279.978866)
		(mid 112.124687 -279.971501)
		(end 112.124744 -279.964134)
		(width 0.0889)
		(layer "In6.Cu")
		(net "UPI_CPU0_CPU1_P2P2_DP<23>")
	)
	(arc
		(start 333.937356 -284.91307)
		(mid 333.936057 -284.923624)
		(end 333.934562 -284.934152)
		(width 0.0889)
		(layer "In6.Cu")
		(net "UPI_CPU0_CPU1_P2P2_DP<23>")
	)
	(arc
		(start 110.057692 -274.756372)
		(mid 109.870494 -274.706229)
		(end 109.683296 -274.756372)
		(width 0.0889)
		(layer "In6.Cu")
		(net "UPI_CPU0_CPU1_P2P2_DP<23>")
	)
	(arc
		(start 111.476536 -282.725114)
		(mid 111.655254 -282.405836)
		(end 111.476536 -282.086558)
		(width 0.0889)
		(layer "In6.Cu")
		(net "UPI_CPU0_CPU1_P2P2_DP<23>")
	)
	(arc
		(start 110.245144 -284.847538)
		(mid 110.31906 -284.568036)
		(end 110.521496 -284.361636)
		(width 0.0889)
		(layer "In6.Cu")
		(net "UPI_CPU0_CPU1_P2P2_DP<23>")
	)
	(arc
		(start 109.596682 -285.980632)
		(mid 109.727596 -285.844272)
		(end 109.775244 -285.661354)
		(width 0.0889)
		(layer "In6.Cu")
		(net "UPI_CPU0_CPU1_P2P2_DP<23>")
	)
	(arc
		(start 110.62335 -274.756372)
		(mid 110.346537 -274.832242)
		(end 110.068106 -274.762468)
		(width 0.0889)
		(layer "In6.Cu")
		(net "UPI_CPU0_CPU1_P2P2_DP<23>")
	)
	(arc
		(start 108.835444 -287.279334)
		(mid 108.913555 -287.002385)
		(end 109.117892 -286.799782)
		(width 0.0889)
		(layer "In6.Cu")
		(net "UPI_CPU0_CPU1_P2P2_DP<23>")
	)
	(arc
		(start 105.444036 -275.576538)
		(mid 105.209139 -275.645149)
		(end 104.967278 -275.608034)
		(width 0.0889)
		(layer "In6.Cu")
		(net "UPI_CPU0_CPU1_P2P2_DP<23>")
	)
	(arc
		(start 108.648246 -287.613598)
		(mid 108.783179 -287.480244)
		(end 108.835444 -287.297876)
		(width 0.0889)
		(layer "In6.Cu")
		(net "UPI_CPU0_CPU1_P2P2_DP<23>")
	)
	(arc
		(start 112.407446 -277.84679)
		(mid 112.542379 -277.713436)
		(end 112.594644 -277.531068)
		(width 0.0889)
		(layer "In6.Cu")
		(net "UPI_CPU0_CPU1_P2P2_DP<23>")
	)
	(arc
		(start 110.715044 -284.033722)
		(mid 110.787279 -283.757198)
		(end 110.985554 -283.551376)
		(width 0.0889)
		(layer "In6.Cu")
		(net "UPI_CPU0_CPU1_P2P2_DP<23>")
	)
	(arc
		(start 110.997746 -274.756372)
		(mid 110.810548 -274.706229)
		(end 110.62335 -274.756372)
		(width 0.0889)
		(layer "In6.Cu")
		(net "UPI_CPU0_CPU1_P2P2_DP<23>")
	)
	(arc
		(start 110.997746 -283.544264)
		(mid 111.132679 -283.41091)
		(end 111.184944 -283.228542)
		(width 0.0889)
		(layer "In6.Cu")
		(net "UPI_CPU0_CPU1_P2P2_DP<23>")
	)
	(arc
		(start 111.184944 -275.072094)
		(mid 111.132674 -274.889729)
		(end 110.997746 -274.756372)
		(width 0.0889)
		(layer "In6.Cu")
		(net "UPI_CPU0_CPU1_P2P2_DP<23>")
	)
	(arc
		(start 108.733082 -274.762468)
		(mid 108.454904 -274.832191)
		(end 108.178346 -274.756372)
		(width 0.0889)
		(layer "In6.Cu")
		(net "UPI_CPU0_CPU1_P2P2_DP<23>")
	)
	(arc
		(start 109.305344 -289.827208)
		(mid 109.265725 -289.638264)
		(end 109.13745 -289.49396)
		(width 0.0889)
		(layer "In6.Cu")
		(net "UPI_CPU0_CPU1_P2P2_DP<23>")
	)
	(arc
		(start 109.683296 -274.756372)
		(mid 109.400594 -274.832148)
		(end 109.117892 -274.756372)
		(width 0.0889)
		(layer "In6.Cu")
		(net "UPI_CPU0_CPU1_P2P2_DP<23>")
	)
	(arc
		(start 111.946182 -280.283412)
		(mid 112.073436 -280.153446)
		(end 112.12449 -279.978866)
		(width 0.0889)
		(layer "In6.Cu")
		(net "UPI_CPU0_CPU1_P2P2_DP<23>")
	)
	(arc
		(start 110.536482 -284.353)
		(mid 110.667396 -284.21664)
		(end 110.715044 -284.033722)
		(width 0.0889)
		(layer "In6.Cu")
		(net "UPI_CPU0_CPU1_P2P2_DP<23>")
	)
	(arc
		(start 111.46155 -282.077922)
		(mid 111.1851 -281.59202)
		(end 111.46155 -281.106118)
		(width 0.0889)
		(layer "In6.Cu")
		(net "UPI_CPU0_CPU1_P2P2_DP<23>")
	)
	(arc
		(start 109.097318 -289.470846)
		(mid 108.897612 -289.25219)
		(end 108.835698 -288.962592)
		(width 0.0889)
		(layer "In6.Cu")
		(net "UPI_CPU0_CPU1_P2P2_DP<23>")
	)
	(arc
		(start 108.84027 -288.873946)
		(mid 108.774817 -288.718531)
		(end 108.649262 -288.605976)
		(width 0.0889)
		(layer "In6.Cu")
		(net "UPI_CPU0_CPU1_P2P2_DP<23>")
	)
	(arc
		(start 109.117892 -274.756372)
		(mid 108.930694 -274.706229)
		(end 108.743496 -274.756372)
		(width 0.0889)
		(layer "In6.Cu")
		(net "UPI_CPU0_CPU1_P2P2_DP<23>")
	)
	(arc
		(start 112.594644 -279.141682)
		(mid 112.542374 -278.959317)
		(end 112.407446 -278.82596)
		(width 0.0889)
		(layer "In6.Cu")
		(net "UPI_CPU0_CPU1_P2P2_DP<23>")
	)
	(arc
		(start 107.616498 -275.094954)
		(mid 107.537279 -275.369639)
		(end 107.333796 -275.570442)
		(width 0.0889)
		(layer "In6.Cu")
		(net "UPI_CPU0_CPU1_P2P2_DP<23>")
	)
	(arc
		(start 106.393996 -275.570442)
		(mid 106.117437 -275.646151)
		(end 105.83926 -275.576538)
		(width 0.0889)
		(layer "In6.Cu")
		(net "UPI_CPU0_CPU1_P2P2_DP<23>")
	)
	(arc
		(start 111.467646 -275.570442)
		(mid 111.264165 -275.369638)
		(end 111.184944 -275.094954)
		(width 0.0889)
		(layer "In6.Cu")
		(net "UPI_CPU0_CPU1_P2P2_DP<23>")
	)
	(arc
		(start 111.937292 -276.384258)
		(mid 111.734469 -276.184027)
		(end 111.655098 -275.910294)
		(width 0.0889)
		(layer "In6.Cu")
		(net "UPI_CPU0_CPU1_P2P2_DP<23>")
	)
	(arc
		(start 109.775244 -285.651448)
		(mid 109.853355 -285.374499)
		(end 110.057692 -285.171896)
		(width 0.0889)
		(layer "In6.Cu")
		(net "UPI_CPU0_CPU1_P2P2_DP<23>")
	)
	(arc
		(start 111.655098 -275.8948)
		(mid 111.607419 -275.7119)
		(end 111.476536 -275.575522)
		(width 0.0889)
		(layer "In6.Cu")
		(net "UPI_CPU0_CPU1_P2P2_DP<23>")
	)
	(arc
		(start 112.124744 -279.964134)
		(mid 112.198735 -279.684568)
		(end 112.40135 -279.478232)
		(width 0.0889)
		(layer "In6.Cu")
		(net "UPI_CPU0_CPU1_P2P2_DP<23>")
	)
	(arc
		(start 106.768392 -275.570442)
		(mid 106.581194 -275.520299)
		(end 106.393996 -275.570442)
		(width 0.0889)
		(layer "In6.Cu")
		(net "UPI_CPU0_CPU1_P2P2_DP<23>")
	)
	(arc
		(start 108.178346 -274.756372)
		(mid 107.991148 -274.706229)
		(end 107.80395 -274.756372)
		(width 0.0889)
		(layer "In6.Cu")
		(net "UPI_CPU0_CPU1_P2P2_DP<23>")
	)
	(arc
		(start 111.184944 -283.205682)
		(mid 111.264163 -282.930997)
		(end 111.467646 -282.730194)
		(width 0.0889)
		(layer "In6.Cu")
		(net "UPI_CPU0_CPU1_P2P2_DP<23>")
	)
	(arc
		(start 109.305344 -286.456882)
		(mid 109.385506 -286.184693)
		(end 109.587792 -285.985712)
		(width 0.0889)
		(layer "In6.Cu")
		(net "UPI_CPU0_CPU1_P2P2_DP<23>")
	)
	(arc
		(start 104.967278 -275.608034)
		(mid 104.957206 -275.604067)
		(end 104.947212 -275.599906)
		(width 0.0889)
		(layer "In6.Cu")
		(net "UPI_CPU0_CPU1_P2P2_DP<23>")
	)
	(arc
		(start 108.365544 -288.103056)
		(mid 108.439535 -287.82349)
		(end 108.64215 -287.617154)
		(width 0.0889)
		(layer "In6.Cu")
		(net "UPI_CPU0_CPU1_P2P2_DP<23>")
	)
	(arc
		(start 112.40135 -278.822404)
		(mid 112.198763 -278.616053)
		(end 112.124744 -278.336502)
		(width 0.0889)
		(layer "In6.Cu")
		(net "UPI_CPU0_CPU1_P2P2_DP<23>")
	)
	(arc
		(start 112.124744 -276.708616)
		(mid 112.077065 -276.525716)
		(end 111.946182 -276.389338)
		(width 0.0889)
		(layer "In6.Cu")
		(net "UPI_CPU0_CPU1_P2P2_DP<23>")
	)
	(arc
		(start 111.655098 -280.756106)
		(mid 111.736009 -280.485978)
		(end 111.937292 -280.288492)
		(width 0.0889)
		(layer "In6.Cu")
		(net "UPI_CPU0_CPU1_P2P2_DP<23>")
	)
	(arc
		(start 112.124744 -278.322278)
		(mid 112.203963 -278.047593)
		(end 112.407446 -277.84679)
		(width 0.0889)
		(layer "In6.Cu")
		(net "UPI_CPU0_CPU1_P2P2_DP<23>")
	)
	(arc
		(start 110.066582 -285.166816)
		(mid 110.197496 -285.030456)
		(end 110.245144 -284.847538)
		(width 0.0889)
		(layer "In6.Cu")
		(net "UPI_CPU0_CPU1_P2P2_DP<23>")
	)
	(arc
		(start 112.594644 -277.513796)
		(mid 112.542374 -277.331431)
		(end 112.407446 -277.198074)
		(width 0.0889)
		(layer "In6.Cu")
		(net "UPI_CPU0_CPU1_P2P2_DP<23>")
	)
	(arc
		(start 105.828846 -275.570442)
		(mid 105.641648 -275.520299)
		(end 105.45445 -275.570442)
		(width 0.0889)
		(layer "In6.Cu")
		(net "UPI_CPU0_CPU1_P2P2_DP<23>")
	)
	(arc
		(start 112.407446 -279.474676)
		(mid 112.542379 -279.341322)
		(end 112.594644 -279.158954)
		(width 0.0889)
		(layer "In6.Cu")
		(net "UPI_CPU0_CPU1_P2P2_DP<23>")
	)
	(arc
		(start 107.79506 -274.761452)
		(mid 107.664146 -274.897812)
		(end 107.616498 -275.08073)
		(width 0.0889)
		(layer "In6.Cu")
		(net "UPI_CPU0_CPU1_P2P2_DP<23>")
	)
	(arc
		(start 108.649262 -288.605976)
		(mid 108.464683 -288.442122)
		(end 108.365544 -288.216086)
		(width 0.0889)
		(layer "In6.Cu")
		(net "UPI_CPU0_CPU1_P2P2_DP<23>")
	)
	(arc
		(start 109.126782 -286.794702)
		(mid 109.257696 -286.658342)
		(end 109.305344 -286.475424)
		(width 0.0889)
		(layer "In6.Cu")
		(net "UPI_CPU0_CPU1_P2P2_DP<23>")
	)
	(arc
		(start 107.319064 -275.579078)
		(mid 107.042623 -275.646244)
		(end 106.768392 -275.570442)
		(width 0.0889)
		(layer "In6.Cu")
		(net "UPI_CPU0_CPU1_P2P2_DP<23>")
	)
	(arc
		(start 333.934308 -284.934406)
		(mid 333.759144 -285.262915)
		(end 333.417672 -285.411164)
		(width 0.0889)
		(layer "In6.Cu")
		(net "UPI_CPU0_CPU1_P2P2_DP<23>")
	)
	(arc
		(start 112.40135 -277.194518)
		(mid 112.198763 -276.988167)
		(end 112.124744 -276.708616)
		(width 0.0889)
		(layer "In6.Cu")
		(net "UPI_CPU0_CPU1_P2P2_DP<23>")
	)
	(arc
		(start 111.476536 -281.097482)
		(mid 111.60745 -280.961122)
		(end 111.655098 -280.778204)
		(width 0.0889)
		(layer "In6.Cu")
		(net "UPI_CPU0_CPU1_P2P2_DP<23>")
	)
	(segment
		(start 335.255362 -284.311598)
		(end 335.255362 -284.847538)
		(width 0.13208)
		(layer "F.Cu")
		(net "UPI_CPU0_CPU1_P2P2_DP<22>")
	)
	(segment
		(start 108.461048 -275.35886)
		(end 108.461048 -275.8948)
		(width 0.13208)
		(layer "F.Cu")
		(net "UPI_CPU0_CPU1_P2P2_DP<22>")
	)
	(segment
		(start 104.65181 -300.988984)
		(end 104.64673 -300.78426)
		(width 0.14732)
		(layer "In6.Cu")
		(net "UPI_CPU0_CPU1_P2P2_DP<22>")
	)
	(segment
		(start 174.033434 -370.617242)
		(end 173.914308 -370.787422)
		(width 0.14732)
		(layer "In6.Cu")
		(net "UPI_CPU0_CPU1_P2P2_DP<22>")
	)
	(segment
		(start 197.711314 -367.18113)
		(end 197.640702 -366.782858)
		(width 0.14732)
		(layer "In6.Cu")
		(net "UPI_CPU0_CPU1_P2P2_DP<22>")
	)
	(segment
		(start 111.46917 -278.826722)
		(end 111.467646 -278.82596)
		(width 0.0889)
		(layer "In6.Cu")
		(net "UPI_CPU0_CPU1_P2P2_DP<22>")
	)
	(segment
		(start 171.73321 -371.764052)
		(end 171.48302 -372.120414)
		(width 0.14732)
		(layer "In6.Cu")
		(net "UPI_CPU0_CPU1_P2P2_DP<22>")
	)
	(segment
		(start 186.027568 -368.501676)
		(end 185.445654 -368.604292)
		(width 0.14732)
		(layer "In6.Cu")
		(net "UPI_CPU0_CPU1_P2P2_DP<22>")
	)
	(segment
		(start 194.57543 -366.993932)
		(end 194.456304 -367.164112)
		(width 0.14732)
		(layer "In6.Cu")
		(net "UPI_CPU0_CPU1_P2P2_DP<22>")
	)
	(segment
		(start 110.536482 -282.086558)
		(end 110.527592 -282.081478)
		(width 0.0889)
		(layer "In6.Cu")
		(net "UPI_CPU0_CPU1_P2P2_DP<22>")
	)
	(segment
		(start 104.900984 -300.517306)
		(end 105.105708 -300.512226)
		(width 0.14732)
		(layer "In6.Cu")
		(net "UPI_CPU0_CPU1_P2P2_DP<22>")
	)
	(segment
		(start 330.323952 -292.47719)
		(end 328.374756 -298.901866)
		(width 0.14732)
		(layer "In6.Cu")
		(net "UPI_CPU0_CPU1_P2P2_DP<22>")
	)
	(segment
		(start 298.737528 -320.321432)
		(end 297.734228 -322.044314)
		(width 0.14732)
		(layer "In6.Cu")
		(net "UPI_CPU0_CPU1_P2P2_DP<22>")
	)
	(segment
		(start 173.765464 -371.717824)
		(end 172.961046 -371.860318)
		(width 0.14732)
		(layer "In6.Cu")
		(net "UPI_CPU0_CPU1_P2P2_DP<22>")
	)
	(segment
		(start 314.277502 -309.500016)
		(end 311.70118 -309.755286)
		(width 0.14732)
		(layer "In6.Cu")
		(net "UPI_CPU0_CPU1_P2P2_DP<22>")
	)
	(segment
		(start 170.05046 -371.319806)
		(end 169.468546 -371.422422)
		(width 0.14732)
		(layer "In6.Cu")
		(net "UPI_CPU0_CPU1_P2P2_DP<22>")
	)
	(segment
		(start 172.60443 -371.610128)
		(end 172.503084 -371.036342)
		(width 0.14732)
		(layer "In6.Cu")
		(net "UPI_CPU0_CPU1_P2P2_DP<22>")
	)
	(segment
		(start 111.464852 -278.824436)
		(end 111.46155 -278.822404)
		(width 0.0889)
		(layer "In6.Cu")
		(net "UPI_CPU0_CPU1_P2P2_DP<22>")
	)
	(segment
		(start 296.39387 -323.384672)
		(end 287.913318 -323.384672)
		(width 0.14732)
		(layer "In6.Cu")
		(net "UPI_CPU0_CPU1_P2P2_DP<22>")
	)
	(segment
		(start 109.117892 -285.171896)
		(end 109.126782 -285.166816)
		(width 0.0889)
		(layer "In6.Cu")
		(net "UPI_CPU0_CPU1_P2P2_DP<22>")
	)
	(segment
		(start 164.784532 -372.397782)
		(end 164.885878 -372.971822)
		(width 0.14732)
		(layer "In6.Cu")
		(net "UPI_CPU0_CPU1_P2P2_DP<22>")
	)
	(segment
		(start 161.090864 -373.049292)
		(end 160.920684 -372.930166)
		(width 0.14732)
		(layer "In6.Cu")
		(net "UPI_CPU0_CPU1_P2P2_DP<22>")
	)
	(segment
		(start 100.662994 -370.52504)
		(end 81.451196 -362.567474)
		(width 0.14732)
		(layer "In6.Cu")
		(net "UPI_CPU0_CPU1_P2P2_DP<22>")
	)
	(segment
		(start 333.666338 -286.96031)
		(end 333.657702 -286.964882)
		(width 0.0889)
		(layer "In6.Cu")
		(net "UPI_CPU0_CPU1_P2P2_DP<22>")
	)
	(segment
		(start 195.157344 -366.891316)
		(end 194.57543 -366.993932)
		(width 0.14732)
		(layer "In6.Cu")
		(net "UPI_CPU0_CPU1_P2P2_DP<22>")
	)
	(segment
		(start 203.859638 -367.336324)
		(end 203.740512 -367.166144)
		(width 0.14732)
		(layer "In6.Cu")
		(net "UPI_CPU0_CPU1_P2P2_DP<22>")
	)
	(segment
		(start 187.608972 -368.371882)
		(end 187.710318 -368.945922)
		(width 0.14732)
		(layer "In6.Cu")
		(net "UPI_CPU0_CPU1_P2P2_DP<22>")
	)
	(segment
		(start 186.65571 -369.444778)
		(end 186.29884 -369.194588)
		(width 0.14732)
		(layer "In6.Cu")
		(net "UPI_CPU0_CPU1_P2P2_DP<22>")
	)
	(segment
		(start 210.587844 -368.374676)
		(end 210.00593 -368.271806)
		(width 0.14732)
		(layer "In6.Cu")
		(net "UPI_CPU0_CPU1_P2P2_DP<22>")
	)
	(segment
		(start 179.808378 -370.652548)
		(end 179.451508 -370.402358)
		(width 0.14732)
		(layer "In6.Cu")
		(net "UPI_CPU0_CPU1_P2P2_DP<22>")
	)
	(segment
		(start 108.166154 -286.806894)
		(end 108.178346 -286.799782)
		(width 0.0889)
		(layer "In6.Cu")
		(net "UPI_CPU0_CPU1_P2P2_DP<22>")
	)
	(segment
		(start 205.270862 -367.585244)
		(end 205.21803 -367.883694)
		(width 0.14732)
		(layer "In6.Cu")
		(net "UPI_CPU0_CPU1_P2P2_DP<22>")
	)
	(segment
		(start 208.3054 -367.971832)
		(end 207.723486 -367.868962)
		(width 0.14732)
		(layer "In6.Cu")
		(net "UPI_CPU0_CPU1_P2P2_DP<22>")
	)
	(segment
		(start 108.323634 -290.307268)
		(end 108.365544 -290.265358)
		(width 0.0889)
		(layer "In6.Cu")
		(net "UPI_CPU0_CPU1_P2P2_DP<22>")
	)
	(segment
		(start 333.940912 -286.475424)
		(end 333.940912 -286.48533)
		(width 0.0889)
		(layer "In6.Cu")
		(net "UPI_CPU0_CPU1_P2P2_DP<22>")
	)
	(segment
		(start 105.507536 -300.090078)
		(end 105.50271 -299.885354)
		(width 0.14732)
		(layer "In6.Cu")
		(net "UPI_CPU0_CPU1_P2P2_DP<22>")
	)
	(segment
		(start 206.33944 -368.394234)
		(end 206.08925 -368.037618)
		(width 0.14732)
		(layer "In6.Cu")
		(net "UPI_CPU0_CPU1_P2P2_DP<22>")
	)
	(segment
		(start 110.536482 -275.575522)
		(end 110.527592 -275.570442)
		(width 0.0889)
		(layer "In6.Cu")
		(net "UPI_CPU0_CPU1_P2P2_DP<22>")
	)
	(segment
		(start 181.733952 -369.999768)
		(end 181.63286 -369.425982)
		(width 0.14732)
		(layer "In6.Cu")
		(net "UPI_CPU0_CPU1_P2P2_DP<22>")
	)
	(segment
		(start 188.581538 -368.791998)
		(end 188.480192 -368.218212)
		(width 0.14732)
		(layer "In6.Cu")
		(net "UPI_CPU0_CPU1_P2P2_DP<22>")
	)
	(segment
		(start 228.559106 -366.712754)
		(end 228.559106 -366.713008)
		(width 0.14732)
		(layer "In6.Cu")
		(net "UPI_CPU0_CPU1_P2P2_DP<22>")
	)
	(segment
		(start 189.992762 -368.543332)
		(end 189.741556 -368.901218)
		(width 0.14732)
		(layer "In6.Cu")
		(net "UPI_CPU0_CPU1_P2P2_DP<22>")
	)
	(segment
		(start 205.21803 -367.883694)
		(end 204.861414 -368.133884)
		(width 0.14732)
		(layer "In6.Cu")
		(net "UPI_CPU0_CPU1_P2P2_DP<22>")
	)
	(segment
		(start 191.219836 -368.639598)
		(end 190.863982 -368.389154)
		(width 0.14732)
		(layer "In6.Cu")
		(net "UPI_CPU0_CPU1_P2P2_DP<22>")
	)
	(segment
		(start 197.609968 -366.607852)
		(end 197.439788 -366.488726)
		(width 0.14732)
		(layer "In6.Cu")
		(net "UPI_CPU0_CPU1_P2P2_DP<22>")
	)
	(segment
		(start 163.203128 -372.527576)
		(end 162.621214 -372.630192)
		(width 0.14732)
		(layer "In6.Cu")
		(net "UPI_CPU0_CPU1_P2P2_DP<22>")
	)
	(segment
		(start 184.373266 -369.847368)
		(end 184.016396 -369.597178)
		(width 0.14732)
		(layer "In6.Cu")
		(net "UPI_CPU0_CPU1_P2P2_DP<22>")
	)
	(segment
		(start 108.835444 -285.66999)
		(end 108.835444 -285.651448)
		(width 0.0889)
		(layer "In6.Cu")
		(net "UPI_CPU0_CPU1_P2P2_DP<22>")
	)
	(segment
		(start 333.420212 -287.147508)
		(end 333.16291 -287.40481)
		(width 0.0889)
		(layer "In6.Cu")
		(net "UPI_CPU0_CPU1_P2P2_DP<22>")
	)
	(segment
		(start 163.83127 -373.470678)
		(end 163.4744 -373.220488)
		(width 0.14732)
		(layer "In6.Cu")
		(net "UPI_CPU0_CPU1_P2P2_DP<22>")
	)
	(segment
		(start 195.785486 -367.834926)
		(end 195.428616 -367.584228)
		(width 0.14732)
		(layer "In6.Cu")
		(net "UPI_CPU0_CPU1_P2P2_DP<22>")
	)
	(segment
		(start 169.450766 -372.166642)
		(end 169.200576 -372.523004)
		(width 0.14732)
		(layer "In6.Cu")
		(net "UPI_CPU0_CPU1_P2P2_DP<22>")
	)
	(segment
		(start 105.75671 -299.6184)
		(end 105.961434 -299.61332)
		(width 0.14732)
		(layer "In6.Cu")
		(net "UPI_CPU0_CPU1_P2P2_DP<22>")
	)
	(segment
		(start 190.010542 -367.799112)
		(end 189.891416 -367.969292)
		(width 0.14732)
		(layer "In6.Cu")
		(net "UPI_CPU0_CPU1_P2P2_DP<22>")
	)
	(segment
		(start 333.16291 -288.393124)
		(end 333.205074 -288.435288)
		(width 0.0889)
		(layer "In6.Cu")
		(net "UPI_CPU0_CPU1_P2P2_DP<22>")
	)
	(segment
		(start 109.587792 -284.35808)
		(end 109.596682 -284.353)
		(width 0.0889)
		(layer "In6.Cu")
		(net "UPI_CPU0_CPU1_P2P2_DP<22>")
	)
	(segment
		(start 201.524362 -367.23193)
		(end 201.577194 -366.93348)
		(width 0.14732)
		(layer "In6.Cu")
		(net "UPI_CPU0_CPU1_P2P2_DP<22>")
	)
	(segment
		(start 177.067972 -370.231162)
		(end 176.897792 -370.112036)
		(width 0.14732)
		(layer "In6.Cu")
		(net "UPI_CPU0_CPU1_P2P2_DP<22>")
	)
	(segment
		(start 197.640448 -366.782604)
		(end 197.609968 -366.607852)
		(width 0.14732)
		(layer "In6.Cu")
		(net "UPI_CPU0_CPU1_P2P2_DP<22>")
	)
	(segment
		(start 167.168322 -372.569232)
		(end 166.918132 -372.925594)
		(width 0.14732)
		(layer "In6.Cu")
		(net "UPI_CPU0_CPU1_P2P2_DP<22>")
	)
	(segment
		(start 174.88662 -371.207538)
		(end 174.785528 -370.633752)
		(width 0.14732)
		(layer "In6.Cu")
		(net "UPI_CPU0_CPU1_P2P2_DP<22>")
	)
	(segment
		(start 98.924364 -307.004466)
		(end 98.926396 -307.002434)
		(width 0.14732)
		(layer "In6.Cu")
		(net "UPI_CPU0_CPU1_P2P2_DP<22>")
	)
	(segment
		(start 192.8749 -367.293906)
		(end 192.292986 -367.396522)
		(width 0.14732)
		(layer "In6.Cu")
		(net "UPI_CPU0_CPU1_P2P2_DP<22>")
	)
	(segment
		(start 172.332904 -370.917216)
		(end 171.75099 -371.019832)
		(width 0.14732)
		(layer "In6.Cu")
		(net "UPI_CPU0_CPU1_P2P2_DP<22>")
	)
	(segment
		(start 107.890564 -296.374058)
		(end 107.745784 -296.229278)
		(width 0.14732)
		(layer "In6.Cu")
		(net "UPI_CPU0_CPU1_P2P2_DP<22>")
	)
	(segment
		(start 183.044084 -369.177062)
		(end 183.14543 -369.751102)
		(width 0.14732)
		(layer "In6.Cu")
		(net "UPI_CPU0_CPU1_P2P2_DP<22>")
	)
	(segment
		(start 111.473234 -279.471374)
		(end 111.476536 -279.469342)
		(width 0.0889)
		(layer "In6.Cu")
		(net "UPI_CPU0_CPU1_P2P2_DP<22>")
	)
	(segment
		(start 188.939678 -369.043204)
		(end 188.581538 -368.791998)
		(width 0.14732)
		(layer "In6.Cu")
		(net "UPI_CPU0_CPU1_P2P2_DP<22>")
	)
	(segment
		(start 181.63286 -369.425982)
		(end 181.46268 -369.306856)
		(width 0.14732)
		(layer "In6.Cu")
		(net "UPI_CPU0_CPU1_P2P2_DP<22>")
	)
	(segment
		(start 107.708192 -287.613598)
		(end 107.717082 -287.608518)
		(width 0.0889)
		(layer "In6.Cu")
		(net "UPI_CPU0_CPU1_P2P2_DP<22>")
	)
	(segment
		(start 178.580542 -370.556282)
		(end 178.330352 -370.912644)
		(width 0.14732)
		(layer "In6.Cu")
		(net "UPI_CPU0_CPU1_P2P2_DP<22>")
	)
	(segment
		(start 201.577194 -366.93348)
		(end 201.458068 -366.7633)
		(width 0.14732)
		(layer "In6.Cu")
		(net "UPI_CPU0_CPU1_P2P2_DP<22>")
	)
	(segment
		(start 249.395742 -350.940116)
		(end 245.451884 -354.884228)
		(width 0.14732)
		(layer "In6.Cu")
		(net "UPI_CPU0_CPU1_P2P2_DP<22>")
	)
	(segment
		(start 160.32099 -373.777002)
		(end 160.071054 -374.133364)
		(width 0.14732)
		(layer "In6.Cu")
		(net "UPI_CPU0_CPU1_P2P2_DP<22>")
	)
	(segment
		(start 196.857874 -366.591342)
		(end 196.738748 -366.761522)
		(width 0.14732)
		(layer "In6.Cu")
		(net "UPI_CPU0_CPU1_P2P2_DP<22>")
	)
	(segment
		(start 334.880712 -284.847538)
		(end 334.880712 -284.857444)
		(width 0.0889)
		(layer "In6.Cu")
		(net "UPI_CPU0_CPU1_P2P2_DP<22>")
	)
	(segment
		(start 207.143858 -368.536728)
		(end 206.33944 -368.394234)
		(width 0.14732)
		(layer "In6.Cu")
		(net "UPI_CPU0_CPU1_P2P2_DP<22>")
	)
	(segment
		(start 179.350416 -369.828572)
		(end 179.180236 -369.709446)
		(width 0.14732)
		(layer "In6.Cu")
		(net "UPI_CPU0_CPU1_P2P2_DP<22>")
	)
	(segment
		(start 196.589904 -367.692178)
		(end 195.785486 -367.834926)
		(width 0.14732)
		(layer "In6.Cu")
		(net "UPI_CPU0_CPU1_P2P2_DP<22>")
	)
	(segment
		(start 190.592456 -367.696496)
		(end 190.010542 -367.799112)
		(width 0.14732)
		(layer "In6.Cu")
		(net "UPI_CPU0_CPU1_P2P2_DP<22>")
	)
	(segment
		(start 107.890564 -295.716198)
		(end 107.890564 -294.009318)
		(width 0.14732)
		(layer "In6.Cu")
		(net "UPI_CPU0_CPU1_P2P2_DP<22>")
	)
	(segment
		(start 202.935586 -367.48085)
		(end 202.57897 -367.73104)
		(width 0.14732)
		(layer "In6.Cu")
		(net "UPI_CPU0_CPU1_P2P2_DP<22>")
	)
	(segment
		(start 111.470694 -279.472644)
		(end 111.473234 -279.471374)
		(width 0.0889)
		(layer "In6.Cu")
		(net "UPI_CPU0_CPU1_P2P2_DP<22>")
	)
	(segment
		(start 198.067422 -367.432082)
		(end 197.711314 -367.18113)
		(width 0.14732)
		(layer "In6.Cu")
		(net "UPI_CPU0_CPU1_P2P2_DP<22>")
	)
	(segment
		(start 276.390608 -324.194932)
		(end 275.91639 -324.66915)
		(width 0.14732)
		(layer "In6.Cu")
		(net "UPI_CPU0_CPU1_P2P2_DP<22>")
	)
	(segment
		(start 287.913318 -323.384672)
		(end 287.42894 -322.900294)
		(width 0.14732)
		(layer "In6.Cu")
		(net "UPI_CPU0_CPU1_P2P2_DP<22>")
	)
	(segment
		(start 111.476536 -277.203154)
		(end 111.461296 -277.194264)
		(width 0.0889)
		(layer "In6.Cu")
		(net "UPI_CPU0_CPU1_P2P2_DP<22>")
	)
	(segment
		(start 190.762636 -367.815622)
		(end 190.592456 -367.696496)
		(width 0.14732)
		(layer "In6.Cu")
		(net "UPI_CPU0_CPU1_P2P2_DP<22>")
	)
	(segment
		(start 287.42894 -322.900294)
		(end 286.107886 -322.900294)
		(width 0.14732)
		(layer "In6.Cu")
		(net "UPI_CPU0_CPU1_P2P2_DP<22>")
	)
	(segment
		(start 107.745784 -293.864538)
		(end 107.745784 -293.496238)
		(width 0.14732)
		(layer "In6.Cu")
		(net "UPI_CPU0_CPU1_P2P2_DP<22>")
	)
	(segment
		(start 263.178798 -335.999328)
		(end 249.395742 -349.782384)
		(width 0.14732)
		(layer "In6.Cu")
		(net "UPI_CPU0_CPU1_P2P2_DP<22>")
	)
	(segment
		(start 108.323634 -290.329366)
		(end 108.323634 -290.307268)
		(width 0.0889)
		(layer "In6.Cu")
		(net "UPI_CPU0_CPU1_P2P2_DP<22>")
	)
	(segment
		(start 207.723486 -367.868962)
		(end 207.553306 -367.988088)
		(width 0.14732)
		(layer "In6.Cu")
		(net "UPI_CPU0_CPU1_P2P2_DP<22>")
	)
	(segment
		(start 185.177684 -369.704874)
		(end 184.373266 -369.847368)
		(width 0.14732)
		(layer "In6.Cu")
		(net "UPI_CPU0_CPU1_P2P2_DP<22>")
	)
	(segment
		(start 167.066976 -371.995192)
		(end 167.168322 -372.569232)
		(width 0.14732)
		(layer "In6.Cu")
		(net "UPI_CPU0_CPU1_P2P2_DP<22>")
	)
	(segment
		(start 183.14543 -369.751102)
		(end 182.89524 -370.107464)
		(width 0.14732)
		(layer "In6.Cu")
		(net "UPI_CPU0_CPU1_P2P2_DP<22>")
	)
	(segment
		(start 110.527592 -281.102562)
		(end 110.536482 -281.097482)
		(width 0.0889)
		(layer "In6.Cu")
		(net "UPI_CPU0_CPU1_P2P2_DP<22>")
	)
	(segment
		(start 164.885878 -372.971822)
		(end 164.635688 -373.328184)
		(width 0.14732)
		(layer "In6.Cu")
		(net "UPI_CPU0_CPU1_P2P2_DP<22>")
	)
	(segment
		(start 81.91754 -320.96075)
		(end 98.924364 -307.004466)
		(width 0.14732)
		(layer "In6.Cu")
		(net "UPI_CPU0_CPU1_P2P2_DP<22>")
	)
	(segment
		(start 110.058454 -283.543756)
		(end 110.060232 -283.54274)
		(width 0.0889)
		(layer "In6.Cu")
		(net "UPI_CPU0_CPU1_P2P2_DP<22>")
	)
	(segment
		(start 164.635688 -373.328184)
		(end 163.83127 -373.470678)
		(width 0.14732)
		(layer "In6.Cu")
		(net "UPI_CPU0_CPU1_P2P2_DP<22>")
	)
	(segment
		(start 334.598264 -285.336996)
		(end 334.589374 -285.342076)
		(width 0.0889)
		(layer "In6.Cu")
		(net "UPI_CPU0_CPU1_P2P2_DP<22>")
	)
	(segment
		(start 111.46155 -279.478232)
		(end 111.466376 -279.475438)
		(width 0.0889)
		(layer "In6.Cu")
		(net "UPI_CPU0_CPU1_P2P2_DP<22>")
	)
	(segment
		(start 106.449368 -298.890944)
		(end 106.703622 -298.62399)
		(width 0.14732)
		(layer "In6.Cu")
		(net "UPI_CPU0_CPU1_P2P2_DP<22>")
	)
	(segment
		(start 275.91639 -324.66915)
		(end 271.628108 -324.66915)
		(width 0.14732)
		(layer "In6.Cu")
		(net "UPI_CPU0_CPU1_P2P2_DP<22>")
	)
	(segment
		(start 196.840094 -367.335308)
		(end 196.589904 -367.692178)
		(width 0.14732)
		(layer "In6.Cu")
		(net "UPI_CPU0_CPU1_P2P2_DP<22>")
	)
	(segment
		(start 173.914308 -370.787422)
		(end 174.015654 -371.361462)
		(width 0.14732)
		(layer "In6.Cu")
		(net "UPI_CPU0_CPU1_P2P2_DP<22>")
	)
	(segment
		(start 209.426302 -368.939572)
		(end 208.621884 -368.797078)
		(width 0.14732)
		(layer "In6.Cu")
		(net "UPI_CPU0_CPU1_P2P2_DP<22>")
	)
	(segment
		(start 300.094142 -318.964818)
		(end 298.737528 -320.321432)
		(width 0.14732)
		(layer "In6.Cu")
		(net "UPI_CPU0_CPU1_P2P2_DP<22>")
	)
	(segment
		(start 171.75099 -371.019832)
		(end 171.631864 -371.190012)
		(width 0.14732)
		(layer "In6.Cu")
		(net "UPI_CPU0_CPU1_P2P2_DP<22>")
	)
	(segment
		(start 333.16291 -287.95345)
		(end 333.16291 -288.393124)
		(width 0.0889)
		(layer "In6.Cu")
		(net "UPI_CPU0_CPU1_P2P2_DP<22>")
	)
	(segment
		(start 108.365544 -290.265358)
		(end 108.365544 -289.67684)
		(width 0.0889)
		(layer "In6.Cu")
		(net "UPI_CPU0_CPU1_P2P2_DP<22>")
	)
	(segment
		(start 200.705974 -366.779556)
		(end 200.653142 -367.078006)
		(width 0.14732)
		(layer "In6.Cu")
		(net "UPI_CPU0_CPU1_P2P2_DP<22>")
	)
	(segment
		(start 161.548826 -373.873268)
		(end 161.191956 -373.623078)
		(width 0.14732)
		(layer "In6.Cu")
		(net "UPI_CPU0_CPU1_P2P2_DP<22>")
	)
	(segment
		(start 333.16291 -287.40481)
		(end 333.16291 -287.58007)
		(width 0.0889)
		(layer "In6.Cu")
		(net "UPI_CPU0_CPU1_P2P2_DP<22>")
	)
	(segment
		(start 301.104808 -316.145672)
		(end 301.104808 -317.522606)
		(width 0.14732)
		(layer "In6.Cu")
		(net "UPI_CPU0_CPU1_P2P2_DP<22>")
	)
	(segment
		(start 206.022956 -367.568988)
		(end 205.441042 -367.466118)
		(width 0.14732)
		(layer "In6.Cu")
		(net "UPI_CPU0_CPU1_P2P2_DP<22>")
	)
	(segment
		(start 187.460128 -369.302284)
		(end 186.65571 -369.444778)
		(width 0.14732)
		(layer "In6.Cu")
		(net "UPI_CPU0_CPU1_P2P2_DP<22>")
	)
	(segment
		(start 186.197748 -368.620802)
		(end 186.027568 -368.501676)
		(width 0.14732)
		(layer "In6.Cu")
		(net "UPI_CPU0_CPU1_P2P2_DP<22>")
	)
	(segment
		(start 188.310012 -368.099086)
		(end 187.728098 -368.201702)
		(width 0.14732)
		(layer "In6.Cu")
		(net "UPI_CPU0_CPU1_P2P2_DP<22>")
	)
	(segment
		(start 111.466376 -279.475438)
		(end 111.468662 -279.473914)
		(width 0.0889)
		(layer "In6.Cu")
		(net "UPI_CPU0_CPU1_P2P2_DP<22>")
	)
	(segment
		(start 192.02527 -368.49685)
		(end 191.219836 -368.639598)
		(width 0.14732)
		(layer "In6.Cu")
		(net "UPI_CPU0_CPU1_P2P2_DP<22>")
	)
	(segment
		(start 197.640702 -366.782858)
		(end 197.640448 -366.782604)
		(width 0.14732)
		(layer "In6.Cu")
		(net "UPI_CPU0_CPU1_P2P2_DP<22>")
	)
	(segment
		(start 307.694076 -312.11774)
		(end 306.971192 -312.214006)
		(width 0.14732)
		(layer "In6.Cu")
		(net "UPI_CPU0_CPU1_P2P2_DP<22>")
	)
	(segment
		(start 333.26197 -287.85439)
		(end 333.16291 -287.95345)
		(width 0.0889)
		(layer "In6.Cu")
		(net "UPI_CPU0_CPU1_P2P2_DP<22>")
	)
	(segment
		(start 192.17386 -367.566702)
		(end 192.275206 -368.140742)
		(width 0.14732)
		(layer "In6.Cu")
		(net "UPI_CPU0_CPU1_P2P2_DP<22>")
	)
	(segment
		(start 202.988418 -367.1824)
		(end 202.935586 -367.48085)
		(width 0.14732)
		(layer "In6.Cu")
		(net "UPI_CPU0_CPU1_P2P2_DP<22>")
	)
	(segment
		(start 228.559106 -366.713008)
		(end 228.509322 -366.747806)
		(width 0.14732)
		(layer "In6.Cu")
		(net "UPI_CPU0_CPU1_P2P2_DP<22>")
	)
	(segment
		(start 204.056996 -367.99139)
		(end 203.806806 -367.634774)
		(width 0.14732)
		(layer "In6.Cu")
		(net "UPI_CPU0_CPU1_P2P2_DP<22>")
	)
	(segment
		(start 190.863982 -368.389154)
		(end 190.762636 -367.815622)
		(width 0.14732)
		(layer "In6.Cu")
		(net "UPI_CPU0_CPU1_P2P2_DP<22>")
	)
	(segment
		(start 179.180236 -369.709446)
		(end 178.598322 -369.812062)
		(width 0.14732)
		(layer "In6.Cu")
		(net "UPI_CPU0_CPU1_P2P2_DP<22>")
	)
	(segment
		(start 333.16291 -287.58007)
		(end 333.26197 -287.67913)
		(width 0.0889)
		(layer "In6.Cu")
		(net "UPI_CPU0_CPU1_P2P2_DP<22>")
	)
	(segment
		(start 107.702096 -287.617154)
		(end 107.708192 -287.613598)
		(width 0.0889)
		(layer "In6.Cu")
		(net "UPI_CPU0_CPU1_P2P2_DP<22>")
	)
	(segment
		(start 167.186102 -371.825012)
		(end 167.066976 -371.995192)
		(width 0.14732)
		(layer "In6.Cu")
		(net "UPI_CPU0_CPU1_P2P2_DP<22>")
	)
	(segment
		(start 192.292986 -367.396522)
		(end 192.17386 -367.566702)
		(width 0.14732)
		(layer "In6.Cu")
		(net "UPI_CPU0_CPU1_P2P2_DP<22>")
	)
	(segment
		(start 106.454448 -299.095668)
		(end 106.449368 -298.890944)
		(width 0.14732)
		(layer "In6.Cu")
		(net "UPI_CPU0_CPU1_P2P2_DP<22>")
	)
	(segment
		(start 194.55765 -367.738152)
		(end 194.30746 -368.094514)
		(width 0.14732)
		(layer "In6.Cu")
		(net "UPI_CPU0_CPU1_P2P2_DP<22>")
	)
	(segment
		(start 160.920684 -372.930166)
		(end 160.33877 -373.032782)
		(width 0.14732)
		(layer "In6.Cu")
		(net "UPI_CPU0_CPU1_P2P2_DP<22>")
	)
	(segment
		(start 167.768016 -371.722396)
		(end 167.186102 -371.825012)
		(width 0.14732)
		(layer "In6.Cu")
		(net "UPI_CPU0_CPU1_P2P2_DP<22>")
	)
	(segment
		(start 195.428616 -367.584228)
		(end 195.327524 -367.010442)
		(width 0.14732)
		(layer "In6.Cu")
		(net "UPI_CPU0_CPU1_P2P2_DP<22>")
	)
	(segment
		(start 74.774298 -351.42678)
		(end 74.774298 -335.226914)
		(width 0.14732)
		(layer "In6.Cu")
		(net "UPI_CPU0_CPU1_P2P2_DP<22>")
	)
	(segment
		(start 177.525934 -371.055138)
		(end 177.169064 -370.804948)
		(width 0.14732)
		(layer "In6.Cu")
		(net "UPI_CPU0_CPU1_P2P2_DP<22>")
	)
	(segment
		(start 174.785528 -370.633752)
		(end 174.615348 -370.514626)
		(width 0.14732)
		(layer "In6.Cu")
		(net "UPI_CPU0_CPU1_P2P2_DP<22>")
	)
	(segment
		(start 176.298098 -370.958872)
		(end 176.047908 -371.315234)
		(width 0.14732)
		(layer "In6.Cu")
		(net "UPI_CPU0_CPU1_P2P2_DP<22>")
	)
	(segment
		(start 200.876154 -366.66043)
		(end 200.705974 -366.779556)
		(width 0.14732)
		(layer "In6.Cu")
		(net "UPI_CPU0_CPU1_P2P2_DP<22>")
	)
	(segment
		(start 309.0164 -311.493916)
		(end 307.694076 -312.11774)
		(width 0.14732)
		(layer "In6.Cu")
		(net "UPI_CPU0_CPU1_P2P2_DP<22>")
	)
	(segment
		(start 110.527592 -282.081478)
		(end 110.521496 -282.077922)
		(width 0.0889)
		(layer "In6.Cu")
		(net "UPI_CPU0_CPU1_P2P2_DP<22>")
	)
	(segment
		(start 174.015654 -371.361462)
		(end 173.765464 -371.717824)
		(width 0.14732)
		(layer "In6.Cu")
		(net "UPI_CPU0_CPU1_P2P2_DP<22>")
	)
	(segment
		(start 162.621214 -372.630192)
		(end 162.502088 -372.800372)
		(width 0.14732)
		(layer "In6.Cu")
		(net "UPI_CPU0_CPU1_P2P2_DP<22>")
	)
	(segment
		(start 178.598322 -369.812062)
		(end 178.479196 -369.982242)
		(width 0.14732)
		(layer "In6.Cu")
		(net "UPI_CPU0_CPU1_P2P2_DP<22>")
	)
	(segment
		(start 106.908346 -298.61891)
		(end 107.21467 -298.297092)
		(width 0.14732)
		(layer "In6.Cu")
		(net "UPI_CPU0_CPU1_P2P2_DP<22>")
	)
	(segment
		(start 165.485572 -372.124986)
		(end 164.903658 -372.227602)
		(width 0.14732)
		(layer "In6.Cu")
		(net "UPI_CPU0_CPU1_P2P2_DP<22>")
	)
	(segment
		(start 170.678602 -372.262908)
		(end 170.321732 -372.012718)
		(width 0.14732)
		(layer "In6.Cu")
		(net "UPI_CPU0_CPU1_P2P2_DP<22>")
	)
	(segment
		(start 203.740512 -367.166144)
		(end 203.158598 -367.063274)
		(width 0.14732)
		(layer "In6.Cu")
		(net "UPI_CPU0_CPU1_P2P2_DP<22>")
	)
	(segment
		(start 333.205074 -288.435288)
		(end 333.205074 -288.457386)
		(width 0.0889)
		(layer "In6.Cu")
		(net "UPI_CPU0_CPU1_P2P2_DP<22>")
	)
	(segment
		(start 111.476536 -279.469342)
		(end 111.476536 -279.469596)
		(width 0.0889)
		(layer "In6.Cu")
		(net "UPI_CPU0_CPU1_P2P2_DP<22>")
	)
	(segment
		(start 169.468546 -371.422422)
		(end 169.34942 -371.592602)
		(width 0.14732)
		(layer "In6.Cu")
		(net "UPI_CPU0_CPU1_P2P2_DP<22>")
	)
	(segment
		(start 109.305344 -284.847538)
		(end 109.305344 -284.837632)
		(width 0.0889)
		(layer "In6.Cu")
		(net "UPI_CPU0_CPU1_P2P2_DP<22>")
	)
	(segment
		(start 81.451196 -362.567474)
		(end 77.929486 -359.045764)
		(width 0.14732)
		(layer "In6.Cu")
		(net "UPI_CPU0_CPU1_P2P2_DP<22>")
	)
	(segment
		(start 108.323634 -290.947094)
		(end 108.323634 -290.329366)
		(width 0.14732)
		(layer "In6.Cu")
		(net "UPI_CPU0_CPU1_P2P2_DP<22>")
	)
	(segment
		(start 110.245144 -283.219906)
		(end 110.245144 -283.205682)
		(width 0.0889)
		(layer "In6.Cu")
		(net "UPI_CPU0_CPU1_P2P2_DP<22>")
	)
	(segment
		(start 306.579016 -312.409078)
		(end 302.311308 -314.915804)
		(width 0.14732)
		(layer "In6.Cu")
		(net "UPI_CPU0_CPU1_P2P2_DP<22>")
	)
	(segment
		(start 176.047908 -371.315234)
		(end 175.24349 -371.457728)
		(width 0.14732)
		(layer "In6.Cu")
		(net "UPI_CPU0_CPU1_P2P2_DP<22>")
	)
	(segment
		(start 163.373308 -372.646702)
		(end 163.203128 -372.527576)
		(width 0.14732)
		(layer "In6.Cu")
		(net "UPI_CPU0_CPU1_P2P2_DP<22>")
	)
	(segment
		(start 194.30746 -368.094514)
		(end 193.502534 -368.237008)
		(width 0.14732)
		(layer "In6.Cu")
		(net "UPI_CPU0_CPU1_P2P2_DP<22>")
	)
	(segment
		(start 161.191956 -373.623078)
		(end 161.090864 -373.049292)
		(width 0.14732)
		(layer "In6.Cu")
		(net "UPI_CPU0_CPU1_P2P2_DP<22>")
	)
	(segment
		(start 206.142082 -367.739168)
		(end 206.022956 -367.568988)
		(width 0.14732)
		(layer "In6.Cu")
		(net "UPI_CPU0_CPU1_P2P2_DP<22>")
	)
	(segment
		(start 209.782918 -368.689382)
		(end 209.426302 -368.939572)
		(width 0.14732)
		(layer "In6.Cu")
		(net "UPI_CPU0_CPU1_P2P2_DP<22>")
	)
	(segment
		(start 207.553306 -367.988088)
		(end 207.500474 -368.286538)
		(width 0.14732)
		(layer "In6.Cu")
		(net "UPI_CPU0_CPU1_P2P2_DP<22>")
	)
	(segment
		(start 183.745124 -368.904266)
		(end 183.16321 -369.006882)
		(width 0.14732)
		(layer "In6.Cu")
		(net "UPI_CPU0_CPU1_P2P2_DP<22>")
	)
	(segment
		(start 178.330352 -370.912644)
		(end 177.525934 -371.055138)
		(width 0.14732)
		(layer "In6.Cu")
		(net "UPI_CPU0_CPU1_P2P2_DP<22>")
	)
	(segment
		(start 108.325666 -275.545804)
		(end 108.304584 -275.623782)
		(width 0.0889)
		(layer "In6.Cu")
		(net "UPI_CPU0_CPU1_P2P2_DP<22>")
	)
	(segment
		(start 111.472726 -278.828754)
		(end 111.46917 -278.826722)
		(width 0.0889)
		(layer "In6.Cu")
		(net "UPI_CPU0_CPU1_P2P2_DP<22>")
	)
	(segment
		(start 165.655752 -372.244112)
		(end 165.485572 -372.124986)
		(width 0.14732)
		(layer "In6.Cu")
		(net "UPI_CPU0_CPU1_P2P2_DP<22>")
	)
	(segment
		(start 187.728098 -368.201702)
		(end 187.608972 -368.371882)
		(width 0.14732)
		(layer "In6.Cu")
		(net "UPI_CPU0_CPU1_P2P2_DP<22>")
	)
	(segment
		(start 111.184944 -276.708616)
		(end 111.184944 -276.69998)
		(width 0.0889)
		(layer "In6.Cu")
		(net "UPI_CPU0_CPU1_P2P2_DP<22>")
	)
	(segment
		(start 208.371694 -368.440462)
		(end 208.424526 -368.142012)
		(width 0.14732)
		(layer "In6.Cu")
		(net "UPI_CPU0_CPU1_P2P2_DP<22>")
	)
	(segment
		(start 208.424526 -368.142012)
		(end 208.3054 -367.971832)
		(width 0.14732)
		(layer "In6.Cu")
		(net "UPI_CPU0_CPU1_P2P2_DP<22>")
	)
	(segment
		(start 162.603434 -373.374412)
		(end 162.353244 -373.730774)
		(width 0.14732)
		(layer "In6.Cu")
		(net "UPI_CPU0_CPU1_P2P2_DP<22>")
	)
	(segment
		(start 76.956158 -325.92264)
		(end 81.91754 -320.96075)
		(width 0.14732)
		(layer "In6.Cu")
		(net "UPI_CPU0_CPU1_P2P2_DP<22>")
	)
	(segment
		(start 193.04508 -367.413032)
		(end 192.8749 -367.293906)
		(width 0.14732)
		(layer "In6.Cu")
		(net "UPI_CPU0_CPU1_P2P2_DP<22>")
	)
	(segment
		(start 126.357126 -374.336564)
		(end 100.662994 -370.52504)
		(width 0.14732)
		(layer "In6.Cu")
		(net "UPI_CPU0_CPU1_P2P2_DP<22>")
	)
	(segment
		(start 206.08925 -368.037618)
		(end 206.142082 -367.739168)
		(width 0.14732)
		(layer "In6.Cu")
		(net "UPI_CPU0_CPU1_P2P2_DP<22>")
	)
	(segment
		(start 75.847956 -328.265028)
		(end 76.956158 -325.92264)
		(width 0.14732)
		(layer "In6.Cu")
		(net "UPI_CPU0_CPU1_P2P2_DP<22>")
	)
	(segment
		(start 176.315878 -370.214652)
		(end 176.196752 -370.384832)
		(width 0.14732)
		(layer "In6.Cu")
		(net "UPI_CPU0_CPU1_P2P2_DP<22>")
	)
	(segment
		(start 166.918132 -372.925594)
		(end 166.113714 -373.068088)
		(width 0.14732)
		(layer "In6.Cu")
		(net "UPI_CPU0_CPU1_P2P2_DP<22>")
	)
	(segment
		(start 297.734228 -322.044314)
		(end 296.39387 -323.384672)
		(width 0.14732)
		(layer "In6.Cu")
		(net "UPI_CPU0_CPU1_P2P2_DP<22>")
	)
	(segment
		(start 249.395742 -349.782384)
		(end 249.395742 -350.940116)
		(width 0.14732)
		(layer "In6.Cu")
		(net "UPI_CPU0_CPU1_P2P2_DP<22>")
	)
	(segment
		(start 335.098898 -284.57652)
		(end 335.020666 -284.555692)
		(width 0.0889)
		(layer "In6.Cu")
		(net "UPI_CPU0_CPU1_P2P2_DP<22>")
	)
	(segment
		(start 212.75548 -369.525804)
		(end 210.904328 -369.200176)
		(width 0.14732)
		(layer "In6.Cu")
		(net "UPI_CPU0_CPU1_P2P2_DP<22>")
	)
	(segment
		(start 185.326528 -368.774472)
		(end 185.427874 -369.348512)
		(width 0.14732)
		(layer "In6.Cu")
		(net "UPI_CPU0_CPU1_P2P2_DP<22>")
	)
	(segment
		(start 179.451508 -370.402358)
		(end 179.350416 -369.828572)
		(width 0.14732)
		(layer "In6.Cu")
		(net "UPI_CPU0_CPU1_P2P2_DP<22>")
	)
	(segment
		(start 105.961434 -299.61332)
		(end 106.454448 -299.095668)
		(width 0.14732)
		(layer "In6.Cu")
		(net "UPI_CPU0_CPU1_P2P2_DP<22>")
	)
	(segment
		(start 270.520668 -325.77659)
		(end 264.696194 -325.77659)
		(width 0.14732)
		(layer "In6.Cu")
		(net "UPI_CPU0_CPU1_P2P2_DP<22>")
	)
	(segment
		(start 180.880766 -369.409472)
		(end 180.76164 -369.579652)
		(width 0.14732)
		(layer "In6.Cu")
		(net "UPI_CPU0_CPU1_P2P2_DP<22>")
	)
	(segment
		(start 207.500474 -368.286538)
		(end 207.143858 -368.536728)
		(width 0.14732)
		(layer "In6.Cu")
		(net "UPI_CPU0_CPU1_P2P2_DP<22>")
	)
	(segment
		(start 104.64673 -300.78426)
		(end 104.900984 -300.517306)
		(width 0.14732)
		(layer "In6.Cu")
		(net "UPI_CPU0_CPU1_P2P2_DP<22>")
	)
	(segment
		(start 201.774552 -367.588546)
		(end 201.524362 -367.23193)
		(width 0.14732)
		(layer "In6.Cu")
		(net "UPI_CPU0_CPU1_P2P2_DP<22>")
	)
	(segment
		(start 328.374756 -298.901866)
		(end 317.776352 -309.500016)
		(width 0.14732)
		(layer "In6.Cu")
		(net "UPI_CPU0_CPU1_P2P2_DP<22>")
	)
	(segment
		(start 111.467646 -277.84679)
		(end 111.476536 -277.84171)
		(width 0.0889)
		(layer "In6.Cu")
		(net "UPI_CPU0_CPU1_P2P2_DP<22>")
	)
	(segment
		(start 301.804578 -315.446156)
		(end 301.104808 -316.145672)
		(width 0.14732)
		(layer "In6.Cu")
		(net "UPI_CPU0_CPU1_P2P2_DP<22>")
	)
	(segment
		(start 109.775244 -284.033722)
		(end 109.775244 -284.023816)
		(width 0.0889)
		(layer "In6.Cu")
		(net "UPI_CPU0_CPU1_P2P2_DP<22>")
	)
	(segment
		(start 160.219644 -373.202962)
		(end 160.32099 -373.777002)
		(width 0.14732)
		(layer "In6.Cu")
		(net "UPI_CPU0_CPU1_P2P2_DP<22>")
	)
	(segment
		(start 75.244706 -330.44638)
		(end 75.847956 -328.265028)
		(width 0.14732)
		(layer "In6.Cu")
		(net "UPI_CPU0_CPU1_P2P2_DP<22>")
	)
	(segment
		(start 204.861414 -368.133884)
		(end 204.056996 -367.99139)
		(width 0.14732)
		(layer "In6.Cu")
		(net "UPI_CPU0_CPU1_P2P2_DP<22>")
	)
	(segment
		(start 111.461296 -277.194264)
		(end 111.46155 -277.194518)
		(width 0.0889)
		(layer "In6.Cu")
		(net "UPI_CPU0_CPU1_P2P2_DP<22>")
	)
	(segment
		(start 169.200576 -372.523004)
		(end 168.396158 -372.665498)
		(width 0.14732)
		(layer "In6.Cu")
		(net "UPI_CPU0_CPU1_P2P2_DP<22>")
	)
	(segment
		(start 210.00593 -368.271806)
		(end 209.83575 -368.390932)
		(width 0.14732)
		(layer "In6.Cu")
		(net "UPI_CPU0_CPU1_P2P2_DP<22>")
	)
	(segment
		(start 335.255362 -284.847538)
		(end 335.098898 -284.57652)
		(width 0.0889)
		(layer "In6.Cu")
		(net "UPI_CPU0_CPU1_P2P2_DP<22>")
	)
	(segment
		(start 188.480192 -368.218212)
		(end 188.310012 -368.099086)
		(width 0.14732)
		(layer "In6.Cu")
		(net "UPI_CPU0_CPU1_P2P2_DP<22>")
	)
	(segment
		(start 168.396158 -372.665498)
		(end 168.039288 -372.415308)
		(width 0.14732)
		(layer "In6.Cu")
		(net "UPI_CPU0_CPU1_P2P2_DP<22>")
	)
	(segment
		(start 158.918402 -374.336564)
		(end 126.357126 -374.336564)
		(width 0.14732)
		(layer "In6.Cu")
		(net "UPI_CPU0_CPU1_P2P2_DP<22>")
	)
	(segment
		(start 185.427874 -369.348512)
		(end 185.177684 -369.704874)
		(width 0.14732)
		(layer "In6.Cu")
		(net "UPI_CPU0_CPU1_P2P2_DP<22>")
	)
	(segment
		(start 107.745784 -295.860978)
		(end 107.890564 -295.716198)
		(width 0.14732)
		(layer "In6.Cu")
		(net "UPI_CPU0_CPU1_P2P2_DP<22>")
	)
	(segment
		(start 172.503084 -371.036342)
		(end 172.332904 -370.917216)
		(width 0.14732)
		(layer "In6.Cu")
		(net "UPI_CPU0_CPU1_P2P2_DP<22>")
	)
	(segment
		(start 171.48302 -372.120414)
		(end 170.678602 -372.262908)
		(width 0.14732)
		(layer "In6.Cu")
		(net "UPI_CPU0_CPU1_P2P2_DP<22>")
	)
	(segment
		(start 110.057692 -283.544264)
		(end 110.058454 -283.543756)
		(width 0.0889)
		(layer "In6.Cu")
		(net "UPI_CPU0_CPU1_P2P2_DP<22>")
	)
	(segment
		(start 197.439788 -366.488726)
		(end 196.857874 -366.591342)
		(width 0.14732)
		(layer "In6.Cu")
		(net "UPI_CPU0_CPU1_P2P2_DP<22>")
	)
	(segment
		(start 183.915304 -369.023392)
		(end 183.745124 -368.904266)
		(width 0.14732)
		(layer "In6.Cu")
		(net "UPI_CPU0_CPU1_P2P2_DP<22>")
	)
	(segment
		(start 110.521496 -281.106118)
		(end 110.527592 -281.102562)
		(width 0.0889)
		(layer "In6.Cu")
		(net "UPI_CPU0_CPU1_P2P2_DP<22>")
	)
	(segment
		(start 264.696194 -325.77659)
		(end 263.178798 -327.293986)
		(width 0.14732)
		(layer "In6.Cu")
		(net "UPI_CPU0_CPU1_P2P2_DP<22>")
	)
	(segment
		(start 110.715044 -280.778204)
		(end 110.715044 -280.770584)
		(width 0.0889)
		(layer "In6.Cu")
		(net "UPI_CPU0_CPU1_P2P2_DP<22>")
	)
	(segment
		(start 177.169064 -370.804948)
		(end 177.067972 -370.231162)
		(width 0.14732)
		(layer "In6.Cu")
		(net "UPI_CPU0_CPU1_P2P2_DP<22>")
	)
	(segment
		(start 309.986172 -310.59247)
		(end 309.0164 -311.493916)
		(width 0.14732)
		(layer "In6.Cu")
		(net "UPI_CPU0_CPU1_P2P2_DP<22>")
	)
	(segment
		(start 181.46268 -369.306856)
		(end 180.880766 -369.409472)
		(width 0.14732)
		(layer "In6.Cu")
		(net "UPI_CPU0_CPU1_P2P2_DP<22>")
	)
	(segment
		(start 77.929486 -359.045764)
		(end 74.774298 -351.42678)
		(width 0.14732)
		(layer "In6.Cu")
		(net "UPI_CPU0_CPU1_P2P2_DP<22>")
	)
	(segment
		(start 175.24349 -371.457728)
		(end 174.88662 -371.207538)
		(width 0.14732)
		(layer "In6.Cu")
		(net "UPI_CPU0_CPU1_P2P2_DP<22>")
	)
	(segment
		(start 160.33877 -373.032782)
		(end 160.219644 -373.202962)
		(width 0.14732)
		(layer "In6.Cu")
		(net "UPI_CPU0_CPU1_P2P2_DP<22>")
	)
	(segment
		(start 334.410812 -285.661354)
		(end 334.410812 -285.679896)
		(width 0.0889)
		(layer "In6.Cu")
		(net "UPI_CPU0_CPU1_P2P2_DP<22>")
	)
	(segment
		(start 168.039288 -372.415308)
		(end 167.938196 -371.841522)
		(width 0.14732)
		(layer "In6.Cu")
		(net "UPI_CPU0_CPU1_P2P2_DP<22>")
	)
	(segment
		(start 192.275206 -368.140742)
		(end 192.02527 -368.49685)
		(width 0.14732)
		(layer "In6.Cu")
		(net "UPI_CPU0_CPU1_P2P2_DP<22>")
	)
	(segment
		(start 111.467646 -278.82596)
		(end 111.464852 -278.824436)
		(width 0.0889)
		(layer "In6.Cu")
		(net "UPI_CPU0_CPU1_P2P2_DP<22>")
	)
	(segment
		(start 334.128364 -286.151066)
		(end 334.119474 -286.156146)
		(width 0.0889)
		(layer "In6.Cu")
		(net "UPI_CPU0_CPU1_P2P2_DP<22>")
	)
	(segment
		(start 196.738748 -366.761522)
		(end 196.840094 -367.335308)
		(width 0.14732)
		(layer "In6.Cu")
		(net "UPI_CPU0_CPU1_P2P2_DP<22>")
	)
	(segment
		(start 284.63621 -324.194932)
		(end 276.390608 -324.194932)
		(width 0.14732)
		(layer "In6.Cu")
		(net "UPI_CPU0_CPU1_P2P2_DP<22>")
	)
	(segment
		(start 110.527592 -282.730194)
		(end 110.536482 -282.725114)
		(width 0.0889)
		(layer "In6.Cu")
		(net "UPI_CPU0_CPU1_P2P2_DP<22>")
	)
	(segment
		(start 107.890564 -291.380164)
		(end 108.323634 -290.947094)
		(width 0.14732)
		(layer "In6.Cu")
		(net "UPI_CPU0_CPU1_P2P2_DP<22>")
	)
	(segment
		(start 172.961046 -371.860318)
		(end 172.60443 -371.610128)
		(width 0.14732)
		(layer "In6.Cu")
		(net "UPI_CPU0_CPU1_P2P2_DP<22>")
	)
	(segment
		(start 105.50271 -299.885354)
		(end 105.75671 -299.6184)
		(width 0.14732)
		(layer "In6.Cu")
		(net "UPI_CPU0_CPU1_P2P2_DP<22>")
	)
	(segment
		(start 176.196752 -370.384832)
		(end 176.298098 -370.958872)
		(width 0.14732)
		(layer "In6.Cu")
		(net "UPI_CPU0_CPU1_P2P2_DP<22>")
	)
	(segment
		(start 163.4744 -373.220488)
		(end 163.373308 -372.646702)
		(width 0.14732)
		(layer "In6.Cu")
		(net "UPI_CPU0_CPU1_P2P2_DP<22>")
	)
	(segment
		(start 107.720892 -288.59988)
		(end 107.708446 -288.592768)
		(width 0.0889)
		(layer "In6.Cu")
		(net "UPI_CPU0_CPU1_P2P2_DP<22>")
	)
	(segment
		(start 183.16321 -369.006882)
		(end 183.044084 -369.177062)
		(width 0.14732)
		(layer "In6.Cu")
		(net "UPI_CPU0_CPU1_P2P2_DP<22>")
	)
	(segment
		(start 203.806806 -367.634774)
		(end 203.859638 -367.336324)
		(width 0.14732)
		(layer "In6.Cu")
		(net "UPI_CPU0_CPU1_P2P2_DP<22>")
	)
	(segment
		(start 182.89524 -370.107464)
		(end 182.090822 -370.249958)
		(width 0.14732)
		(layer "In6.Cu")
		(net "UPI_CPU0_CPU1_P2P2_DP<22>")
	)
	(segment
		(start 160.071054 -374.133364)
		(end 158.918402 -374.336564)
		(width 0.14732)
		(layer "In6.Cu")
		(net "UPI_CPU0_CPU1_P2P2_DP<22>")
	)
	(segment
		(start 110.153196 -275.570442)
		(end 110.142782 -275.576538)
		(width 0.0889)
		(layer "In6.Cu")
		(net "UPI_CPU0_CPU1_P2P2_DP<22>")
	)
	(segment
		(start 182.090822 -370.249958)
		(end 181.733952 -369.999768)
		(width 0.14732)
		(layer "In6.Cu")
		(net "UPI_CPU0_CPU1_P2P2_DP<22>")
	)
	(segment
		(start 167.938196 -371.841522)
		(end 167.768016 -371.722396)
		(width 0.14732)
		(layer "In6.Cu")
		(net "UPI_CPU0_CPU1_P2P2_DP<22>")
	)
	(segment
		(start 108.365544 -286.48406)
		(end 108.365544 -286.4612)
		(width 0.0889)
		(layer "In6.Cu")
		(net "UPI_CPU0_CPU1_P2P2_DP<22>")
	)
	(segment
		(start 205.441042 -367.466118)
		(end 205.270862 -367.585244)
		(width 0.14732)
		(layer "In6.Cu")
		(net "UPI_CPU0_CPU1_P2P2_DP<22>")
	)
	(segment
		(start 271.628108 -324.66915)
		(end 270.520668 -325.77659)
		(width 0.14732)
		(layer "In6.Cu")
		(net "UPI_CPU0_CPU1_P2P2_DP<22>")
	)
	(segment
		(start 180.612796 -370.510054)
		(end 179.808378 -370.652548)
		(width 0.14732)
		(layer "In6.Cu")
		(net "UPI_CPU0_CPU1_P2P2_DP<22>")
	)
	(segment
		(start 189.741556 -368.901218)
		(end 188.939678 -369.043204)
		(width 0.14732)
		(layer "In6.Cu")
		(net "UPI_CPU0_CPU1_P2P2_DP<22>")
	)
	(segment
		(start 317.776352 -309.500016)
		(end 314.277502 -309.500016)
		(width 0.14732)
		(layer "In6.Cu")
		(net "UPI_CPU0_CPU1_P2P2_DP<22>")
	)
	(segment
		(start 107.745784 -293.496238)
		(end 107.890564 -293.351458)
		(width 0.14732)
		(layer "In6.Cu")
		(net "UPI_CPU0_CPU1_P2P2_DP<22>")
	)
	(segment
		(start 171.631864 -371.190012)
		(end 171.73321 -371.764052)
		(width 0.14732)
		(layer "In6.Cu")
		(net "UPI_CPU0_CPU1_P2P2_DP<22>")
	)
	(segment
		(start 111.184944 -279.97277)
		(end 111.184944 -279.964134)
		(width 0.0889)
		(layer "In6.Cu")
		(net "UPI_CPU0_CPU1_P2P2_DP<22>")
	)
	(segment
		(start 165.756844 -372.817898)
		(end 165.655752 -372.244112)
		(width 0.14732)
		(layer "In6.Cu")
		(net "UPI_CPU0_CPU1_P2P2_DP<22>")
	)
	(segment
		(start 170.22064 -371.438932)
		(end 170.05046 -371.319806)
		(width 0.14732)
		(layer "In6.Cu")
		(net "UPI_CPU0_CPU1_P2P2_DP<22>")
	)
	(segment
		(start 162.502088 -372.800372)
		(end 162.603434 -373.374412)
		(width 0.14732)
		(layer "In6.Cu")
		(net "UPI_CPU0_CPU1_P2P2_DP<22>")
	)
	(segment
		(start 286.107886 -322.900294)
		(end 285.806134 -323.025262)
		(width 0.14732)
		(layer "In6.Cu")
		(net "UPI_CPU0_CPU1_P2P2_DP<22>")
	)
	(segment
		(start 333.26197 -287.67913)
		(end 333.26197 -287.85439)
		(width 0.0889)
		(layer "In6.Cu")
		(net "UPI_CPU0_CPU1_P2P2_DP<22>")
	)
	(segment
		(start 210.904328 -369.200176)
		(end 210.654138 -368.843306)
		(width 0.14732)
		(layer "In6.Cu")
		(net "UPI_CPU0_CPU1_P2P2_DP<22>")
	)
	(segment
		(start 110.060994 -283.542232)
		(end 110.066582 -283.539184)
		(width 0.0889)
		(layer "In6.Cu")
		(net "UPI_CPU0_CPU1_P2P2_DP<22>")
	)
	(segment
		(start 107.21467 -298.297092)
		(end 107.788202 -297.523916)
		(width 0.14732)
		(layer "In6.Cu")
		(net "UPI_CPU0_CPU1_P2P2_DP<22>")
	)
	(segment
		(start 111.184944 -278.336502)
		(end 111.184944 -278.322278)
		(width 0.0889)
		(layer "In6.Cu")
		(net "UPI_CPU0_CPU1_P2P2_DP<22>")
	)
	(segment
		(start 174.615348 -370.514626)
		(end 174.033434 -370.617242)
		(width 0.14732)
		(layer "In6.Cu")
		(net "UPI_CPU0_CPU1_P2P2_DP<22>")
	)
	(segment
		(start 193.502534 -368.237008)
		(end 193.146172 -367.986818)
		(width 0.14732)
		(layer "In6.Cu")
		(net "UPI_CPU0_CPU1_P2P2_DP<22>")
	)
	(segment
		(start 245.451884 -354.884228)
		(end 228.559106 -366.712754)
		(width 0.14732)
		(layer "In6.Cu")
		(net "UPI_CPU0_CPU1_P2P2_DP<22>")
	)
	(segment
		(start 107.788202 -297.523916)
		(end 107.890564 -297.277282)
		(width 0.14732)
		(layer "In6.Cu")
		(net "UPI_CPU0_CPU1_P2P2_DP<22>")
	)
	(segment
		(start 107.745784 -296.229278)
		(end 107.745784 -295.860978)
		(width 0.14732)
		(layer "In6.Cu")
		(net "UPI_CPU0_CPU1_P2P2_DP<22>")
	)
	(segment
		(start 263.178798 -327.293986)
		(end 263.178798 -335.999328)
		(width 0.14732)
		(layer "In6.Cu")
		(net "UPI_CPU0_CPU1_P2P2_DP<22>")
	)
	(segment
		(start 111.476536 -278.83104)
		(end 111.472726 -278.828754)
		(width 0.0889)
		(layer "In6.Cu")
		(net "UPI_CPU0_CPU1_P2P2_DP<22>")
	)
	(segment
		(start 108.304584 -275.623782)
		(end 108.461048 -275.8948)
		(width 0.0889)
		(layer "In6.Cu")
		(net "UPI_CPU0_CPU1_P2P2_DP<22>")
	)
	(segment
		(start 201.458068 -366.7633)
		(end 200.876154 -366.66043)
		(width 0.14732)
		(layer "In6.Cu")
		(net "UPI_CPU0_CPU1_P2P2_DP<22>")
	)
	(segment
		(start 110.060232 -283.54274)
		(end 110.060994 -283.542232)
		(width 0.0889)
		(layer "In6.Cu")
		(net "UPI_CPU0_CPU1_P2P2_DP<22>")
	)
	(segment
		(start 200.653142 -367.078006)
		(end 200.29678 -367.328196)
		(width 0.14732)
		(layer "In6.Cu")
		(net "UPI_CPU0_CPU1_P2P2_DP<22>")
	)
	(segment
		(start 194.456304 -367.164112)
		(end 194.55765 -367.738152)
		(width 0.14732)
		(layer "In6.Cu")
		(net "UPI_CPU0_CPU1_P2P2_DP<22>")
	)
	(segment
		(start 333.205074 -288.457386)
		(end 333.205074 -288.785554)
		(width 0.14732)
		(layer "In6.Cu")
		(net "UPI_CPU0_CPU1_P2P2_DP<22>")
	)
	(segment
		(start 170.321732 -372.012718)
		(end 170.22064 -371.438932)
		(width 0.14732)
		(layer "In6.Cu")
		(net "UPI_CPU0_CPU1_P2P2_DP<22>")
	)
	(segment
		(start 331.959204 -290.031424)
		(end 330.323952 -292.47719)
		(width 0.14732)
		(layer "In6.Cu")
		(net "UPI_CPU0_CPU1_P2P2_DP<22>")
	)
	(segment
		(start 74.774298 -335.226914)
		(end 75.244706 -330.44638)
		(width 0.14732)
		(layer "In6.Cu")
		(net "UPI_CPU0_CPU1_P2P2_DP<22>")
	)
	(segment
		(start 228.509322 -366.747806)
		(end 212.75548 -369.525804)
		(width 0.14732)
		(layer "In6.Cu")
		(net "UPI_CPU0_CPU1_P2P2_DP<22>")
	)
	(segment
		(start 202.57897 -367.73104)
		(end 201.774552 -367.588546)
		(width 0.14732)
		(layer "In6.Cu")
		(net "UPI_CPU0_CPU1_P2P2_DP<22>")
	)
	(segment
		(start 111.468662 -279.473914)
		(end 111.470694 -279.472644)
		(width 0.0889)
		(layer "In6.Cu")
		(net "UPI_CPU0_CPU1_P2P2_DP<22>")
	)
	(segment
		(start 162.353244 -373.730774)
		(end 161.548826 -373.873268)
		(width 0.14732)
		(layer "In6.Cu")
		(net "UPI_CPU0_CPU1_P2P2_DP<22>")
	)
	(segment
		(start 107.890564 -293.351458)
		(end 107.890564 -291.380164)
		(width 0.14732)
		(layer "In6.Cu")
		(net "UPI_CPU0_CPU1_P2P2_DP<22>")
	)
	(segment
		(start 208.621884 -368.797078)
		(end 208.371694 -368.440462)
		(width 0.14732)
		(layer "In6.Cu")
		(net "UPI_CPU0_CPU1_P2P2_DP<22>")
	)
	(segment
		(start 209.83575 -368.390932)
		(end 209.782918 -368.689382)
		(width 0.14732)
		(layer "In6.Cu")
		(net "UPI_CPU0_CPU1_P2P2_DP<22>")
	)
	(segment
		(start 210.654138 -368.843306)
		(end 210.70697 -368.544856)
		(width 0.14732)
		(layer "In6.Cu")
		(net "UPI_CPU0_CPU1_P2P2_DP<22>")
	)
	(segment
		(start 178.479196 -369.982242)
		(end 178.580542 -370.556282)
		(width 0.14732)
		(layer "In6.Cu")
		(net "UPI_CPU0_CPU1_P2P2_DP<22>")
	)
	(segment
		(start 285.806134 -323.025262)
		(end 284.63621 -324.194932)
		(width 0.14732)
		(layer "In6.Cu")
		(net "UPI_CPU0_CPU1_P2P2_DP<22>")
	)
	(segment
		(start 169.34942 -371.592602)
		(end 169.450766 -372.166642)
		(width 0.14732)
		(layer "In6.Cu")
		(net "UPI_CPU0_CPU1_P2P2_DP<22>")
	)
	(segment
		(start 306.971192 -312.214006)
		(end 306.579016 -312.409078)
		(width 0.14732)
		(layer "In6.Cu")
		(net "UPI_CPU0_CPU1_P2P2_DP<22>")
	)
	(segment
		(start 107.890564 -297.277282)
		(end 107.890564 -296.374058)
		(width 0.14732)
		(layer "In6.Cu")
		(net "UPI_CPU0_CPU1_P2P2_DP<22>")
	)
	(segment
		(start 110.997746 -276.384258)
		(end 110.985554 -276.377146)
		(width 0.0889)
		(layer "In6.Cu")
		(net "UPI_CPU0_CPU1_P2P2_DP<22>")
	)
	(segment
		(start 199.486012 -367.18494)
		(end 198.067422 -367.432082)
		(width 0.14732)
		(layer "In6.Cu")
		(net "UPI_CPU0_CPU1_P2P2_DP<22>")
	)
	(segment
		(start 300.094142 -318.533272)
		(end 300.094142 -318.964818)
		(width 0.14732)
		(layer "In6.Cu")
		(net "UPI_CPU0_CPU1_P2P2_DP<22>")
	)
	(segment
		(start 311.70118 -309.755286)
		(end 309.986172 -310.59247)
		(width 0.14732)
		(layer "In6.Cu")
		(net "UPI_CPU0_CPU1_P2P2_DP<22>")
	)
	(segment
		(start 301.104808 -317.522606)
		(end 300.094142 -318.533272)
		(width 0.14732)
		(layer "In6.Cu")
		(net "UPI_CPU0_CPU1_P2P2_DP<22>")
	)
	(segment
		(start 107.891326 -289.086798)
		(end 107.895898 -288.927032)
		(width 0.0889)
		(layer "In6.Cu")
		(net "UPI_CPU0_CPU1_P2P2_DP<22>")
	)
	(segment
		(start 189.891416 -367.969292)
		(end 189.992762 -368.543332)
		(width 0.14732)
		(layer "In6.Cu")
		(net "UPI_CPU0_CPU1_P2P2_DP<22>")
	)
	(segment
		(start 166.113714 -373.068088)
		(end 165.756844 -372.817898)
		(width 0.14732)
		(layer "In6.Cu")
		(net "UPI_CPU0_CPU1_P2P2_DP<22>")
	)
	(segment
		(start 195.327524 -367.010442)
		(end 195.157344 -366.891316)
		(width 0.14732)
		(layer "In6.Cu")
		(net "UPI_CPU0_CPU1_P2P2_DP<22>")
	)
	(segment
		(start 200.29678 -367.328196)
		(end 199.486012 -367.18494)
		(width 0.14732)
		(layer "In6.Cu")
		(net "UPI_CPU0_CPU1_P2P2_DP<22>")
	)
	(segment
		(start 176.897792 -370.112036)
		(end 176.315878 -370.214652)
		(width 0.14732)
		(layer "In6.Cu")
		(net "UPI_CPU0_CPU1_P2P2_DP<22>")
	)
	(segment
		(start 186.29884 -369.194588)
		(end 186.197748 -368.620802)
		(width 0.14732)
		(layer "In6.Cu")
		(net "UPI_CPU0_CPU1_P2P2_DP<22>")
	)
	(segment
		(start 210.70697 -368.544856)
		(end 210.587844 -368.374676)
		(width 0.14732)
		(layer "In6.Cu")
		(net "UPI_CPU0_CPU1_P2P2_DP<22>")
	)
	(segment
		(start 98.926396 -307.002434)
		(end 104.65181 -300.988984)
		(width 0.14732)
		(layer "In6.Cu")
		(net "UPI_CPU0_CPU1_P2P2_DP<22>")
	)
	(segment
		(start 107.425744 -288.110676)
		(end 107.425744 -288.103056)
		(width 0.0889)
		(layer "In6.Cu")
		(net "UPI_CPU0_CPU1_P2P2_DP<22>")
	)
	(segment
		(start 193.146172 -367.986818)
		(end 193.04508 -367.413032)
		(width 0.14732)
		(layer "In6.Cu")
		(net "UPI_CPU0_CPU1_P2P2_DP<22>")
	)
	(segment
		(start 185.445654 -368.604292)
		(end 185.326528 -368.774472)
		(width 0.14732)
		(layer "In6.Cu")
		(net "UPI_CPU0_CPU1_P2P2_DP<22>")
	)
	(segment
		(start 105.105708 -300.512226)
		(end 105.507536 -300.090078)
		(width 0.14732)
		(layer "In6.Cu")
		(net "UPI_CPU0_CPU1_P2P2_DP<22>")
	)
	(segment
		(start 180.862986 -370.153692)
		(end 180.612796 -370.510054)
		(width 0.14732)
		(layer "In6.Cu")
		(net "UPI_CPU0_CPU1_P2P2_DP<22>")
	)
	(segment
		(start 333.205074 -288.785554)
		(end 331.959204 -290.031424)
		(width 0.14732)
		(layer "In6.Cu")
		(net "UPI_CPU0_CPU1_P2P2_DP<22>")
	)
	(segment
		(start 302.311308 -314.915804)
		(end 301.804578 -315.446156)
		(width 0.14732)
		(layer "In6.Cu")
		(net "UPI_CPU0_CPU1_P2P2_DP<22>")
	)
	(segment
		(start 106.703622 -298.62399)
		(end 106.908346 -298.61891)
		(width 0.14732)
		(layer "In6.Cu")
		(net "UPI_CPU0_CPU1_P2P2_DP<22>")
	)
	(segment
		(start 184.016396 -369.597178)
		(end 183.915304 -369.023392)
		(width 0.14732)
		(layer "In6.Cu")
		(net "UPI_CPU0_CPU1_P2P2_DP<22>")
	)
	(segment
		(start 180.76164 -369.579652)
		(end 180.862986 -370.153692)
		(width 0.14732)
		(layer "In6.Cu")
		(net "UPI_CPU0_CPU1_P2P2_DP<22>")
	)
	(segment
		(start 164.903658 -372.227602)
		(end 164.784532 -372.397782)
		(width 0.14732)
		(layer "In6.Cu")
		(net "UPI_CPU0_CPU1_P2P2_DP<22>")
	)
	(segment
		(start 107.890564 -294.009318)
		(end 107.745784 -293.864538)
		(width 0.14732)
		(layer "In6.Cu")
		(net "UPI_CPU0_CPU1_P2P2_DP<22>")
	)
	(segment
		(start 187.710318 -368.945922)
		(end 187.460128 -369.302284)
		(width 0.14732)
		(layer "In6.Cu")
		(net "UPI_CPU0_CPU1_P2P2_DP<22>")
	)
	(segment
		(start 203.158598 -367.063274)
		(end 202.988418 -367.1824)
		(width 0.14732)
		(layer "In6.Cu")
		(net "UPI_CPU0_CPU1_P2P2_DP<22>")
	)
	(arc
		(start 110.715044 -275.8948)
		(mid 110.667365 -275.7119)
		(end 110.536482 -275.575522)
		(width 0.0889)
		(layer "In6.Cu")
		(net "UPI_CPU0_CPU1_P2P2_DP<22>")
	)
	(arc
		(start 110.142782 -275.576538)
		(mid 109.86435 -275.646352)
		(end 109.587538 -275.570442)
		(width 0.0889)
		(layer "In6.Cu")
		(net "UPI_CPU0_CPU1_P2P2_DP<22>")
	)
	(arc
		(start 111.655098 -279.150318)
		(mid 111.607419 -278.967418)
		(end 111.476536 -278.83104)
		(width 0.0889)
		(layer "In6.Cu")
		(net "UPI_CPU0_CPU1_P2P2_DP<22>")
	)
	(arc
		(start 110.245144 -283.205682)
		(mid 110.324285 -282.931059)
		(end 110.527592 -282.730194)
		(width 0.0889)
		(layer "In6.Cu")
		(net "UPI_CPU0_CPU1_P2P2_DP<22>")
	)
	(arc
		(start 110.997746 -280.288492)
		(mid 111.132679 -280.155138)
		(end 111.184944 -279.97277)
		(width 0.0889)
		(layer "In6.Cu")
		(net "UPI_CPU0_CPU1_P2P2_DP<22>")
	)
	(arc
		(start 111.476536 -277.84171)
		(mid 111.655254 -277.522432)
		(end 111.476536 -277.203154)
		(width 0.0889)
		(layer "In6.Cu")
		(net "UPI_CPU0_CPU1_P2P2_DP<22>")
	)
	(arc
		(start 334.410812 -285.679896)
		(mid 334.33065 -285.952085)
		(end 334.128364 -286.151066)
		(width 0.0889)
		(layer "In6.Cu")
		(net "UPI_CPU0_CPU1_P2P2_DP<22>")
	)
	(arc
		(start 111.476536 -279.469596)
		(mid 111.60745 -279.333236)
		(end 111.655098 -279.150318)
		(width 0.0889)
		(layer "In6.Cu")
		(net "UPI_CPU0_CPU1_P2P2_DP<22>")
	)
	(arc
		(start 334.589374 -285.342076)
		(mid 334.45846 -285.478436)
		(end 334.410812 -285.661354)
		(width 0.0889)
		(layer "In6.Cu")
		(net "UPI_CPU0_CPU1_P2P2_DP<22>")
	)
	(arc
		(start 108.648246 -285.985712)
		(mid 108.783179 -285.852358)
		(end 108.835444 -285.66999)
		(width 0.0889)
		(layer "In6.Cu")
		(net "UPI_CPU0_CPU1_P2P2_DP<22>")
	)
	(arc
		(start 109.213142 -275.570442)
		(mid 108.930694 -275.646057)
		(end 108.648246 -275.570442)
		(width 0.0889)
		(layer "In6.Cu")
		(net "UPI_CPU0_CPU1_P2P2_DP<22>")
	)
	(arc
		(start 107.895644 -287.28924)
		(mid 107.967879 -287.012716)
		(end 108.166154 -286.806894)
		(width 0.0889)
		(layer "In6.Cu")
		(net "UPI_CPU0_CPU1_P2P2_DP<22>")
	)
	(arc
		(start 333.940912 -286.48533)
		(mid 333.865095 -286.758347)
		(end 333.666338 -286.96031)
		(width 0.0889)
		(layer "In6.Cu")
		(net "UPI_CPU0_CPU1_P2P2_DP<22>")
	)
	(arc
		(start 110.536482 -281.097482)
		(mid 110.667396 -280.961122)
		(end 110.715044 -280.778204)
		(width 0.0889)
		(layer "In6.Cu")
		(net "UPI_CPU0_CPU1_P2P2_DP<22>")
	)
	(arc
		(start 111.184944 -278.322278)
		(mid 111.264163 -278.047593)
		(end 111.467646 -277.84679)
		(width 0.0889)
		(layer "In6.Cu")
		(net "UPI_CPU0_CPU1_P2P2_DP<22>")
	)
	(arc
		(start 333.657702 -286.964882)
		(mid 333.533024 -287.048479)
		(end 333.420212 -287.147508)
		(width 0.0889)
		(layer "In6.Cu")
		(net "UPI_CPU0_CPU1_P2P2_DP<22>")
	)
	(arc
		(start 110.066582 -283.539184)
		(mid 110.197496 -283.402824)
		(end 110.245144 -283.219906)
		(width 0.0889)
		(layer "In6.Cu")
		(net "UPI_CPU0_CPU1_P2P2_DP<22>")
	)
	(arc
		(start 108.835444 -285.651448)
		(mid 108.913555 -285.374499)
		(end 109.117892 -285.171896)
		(width 0.0889)
		(layer "In6.Cu")
		(net "UPI_CPU0_CPU1_P2P2_DP<22>")
	)
	(arc
		(start 109.596682 -284.353)
		(mid 109.727596 -284.21664)
		(end 109.775244 -284.033722)
		(width 0.0889)
		(layer "In6.Cu")
		(net "UPI_CPU0_CPU1_P2P2_DP<22>")
	)
	(arc
		(start 107.708446 -288.592768)
		(mid 107.503374 -288.389089)
		(end 107.425744 -288.110676)
		(width 0.0889)
		(layer "In6.Cu")
		(net "UPI_CPU0_CPU1_P2P2_DP<22>")
	)
	(arc
		(start 111.184944 -276.69998)
		(mid 111.132674 -276.517615)
		(end 110.997746 -276.384258)
		(width 0.0889)
		(layer "In6.Cu")
		(net "UPI_CPU0_CPU1_P2P2_DP<22>")
	)
	(arc
		(start 110.521496 -282.077922)
		(mid 110.24517 -281.59202)
		(end 110.521496 -281.106118)
		(width 0.0889)
		(layer "In6.Cu")
		(net "UPI_CPU0_CPU1_P2P2_DP<22>")
	)
	(arc
		(start 109.587538 -275.570442)
		(mid 109.40034 -275.520299)
		(end 109.213142 -275.570442)
		(width 0.0889)
		(layer "In6.Cu")
		(net "UPI_CPU0_CPU1_P2P2_DP<22>")
	)
	(arc
		(start 335.020666 -284.555692)
		(mid 334.917521 -284.685717)
		(end 334.880712 -284.847538)
		(width 0.0889)
		(layer "In6.Cu")
		(net "UPI_CPU0_CPU1_P2P2_DP<22>")
	)
	(arc
		(start 111.46155 -277.194518)
		(mid 111.258963 -276.988167)
		(end 111.184944 -276.708616)
		(width 0.0889)
		(layer "In6.Cu")
		(net "UPI_CPU0_CPU1_P2P2_DP<22>")
	)
	(arc
		(start 107.895898 -288.927032)
		(mid 107.851693 -288.740302)
		(end 107.720892 -288.59988)
		(width 0.0889)
		(layer "In6.Cu")
		(net "UPI_CPU0_CPU1_P2P2_DP<22>")
	)
	(arc
		(start 334.880712 -284.857444)
		(mid 334.802601 -285.134393)
		(end 334.598264 -285.336996)
		(width 0.0889)
		(layer "In6.Cu")
		(net "UPI_CPU0_CPU1_P2P2_DP<22>")
	)
	(arc
		(start 108.648246 -275.570442)
		(mid 108.489758 -275.521509)
		(end 108.325666 -275.545804)
		(width 0.0889)
		(layer "In6.Cu")
		(net "UPI_CPU0_CPU1_P2P2_DP<22>")
	)
	(arc
		(start 109.305344 -284.837632)
		(mid 109.383455 -284.560683)
		(end 109.587792 -284.35808)
		(width 0.0889)
		(layer "In6.Cu")
		(net "UPI_CPU0_CPU1_P2P2_DP<22>")
	)
	(arc
		(start 108.365544 -289.67684)
		(mid 108.293319 -289.550471)
		(end 108.180378 -289.458654)
		(width 0.0889)
		(layer "In6.Cu")
		(net "UPI_CPU0_CPU1_P2P2_DP<22>")
	)
	(arc
		(start 334.119474 -286.156146)
		(mid 333.98856 -286.292506)
		(end 333.940912 -286.475424)
		(width 0.0889)
		(layer "In6.Cu")
		(net "UPI_CPU0_CPU1_P2P2_DP<22>")
	)
	(arc
		(start 108.180378 -289.458654)
		(mid 107.996923 -289.302975)
		(end 107.891326 -289.086798)
		(width 0.0889)
		(layer "In6.Cu")
		(net "UPI_CPU0_CPU1_P2P2_DP<22>")
	)
	(arc
		(start 108.178346 -286.799782)
		(mid 108.313279 -286.666428)
		(end 108.365544 -286.48406)
		(width 0.0889)
		(layer "In6.Cu")
		(net "UPI_CPU0_CPU1_P2P2_DP<22>")
	)
	(arc
		(start 110.715044 -280.770584)
		(mid 110.792673 -280.492171)
		(end 110.997746 -280.288492)
		(width 0.0889)
		(layer "In6.Cu")
		(net "UPI_CPU0_CPU1_P2P2_DP<22>")
	)
	(arc
		(start 109.126782 -285.166816)
		(mid 109.257696 -285.030456)
		(end 109.305344 -284.847538)
		(width 0.0889)
		(layer "In6.Cu")
		(net "UPI_CPU0_CPU1_P2P2_DP<22>")
	)
	(arc
		(start 109.775244 -284.023816)
		(mid 109.853355 -283.746867)
		(end 110.057692 -283.544264)
		(width 0.0889)
		(layer "In6.Cu")
		(net "UPI_CPU0_CPU1_P2P2_DP<22>")
	)
	(arc
		(start 107.425744 -288.103056)
		(mid 107.49966 -287.823554)
		(end 107.702096 -287.617154)
		(width 0.0889)
		(layer "In6.Cu")
		(net "UPI_CPU0_CPU1_P2P2_DP<22>")
	)
	(arc
		(start 108.365544 -286.4612)
		(mid 108.444763 -286.186515)
		(end 108.648246 -285.985712)
		(width 0.0889)
		(layer "In6.Cu")
		(net "UPI_CPU0_CPU1_P2P2_DP<22>")
	)
	(arc
		(start 111.46155 -278.822404)
		(mid 111.258963 -278.616053)
		(end 111.184944 -278.336502)
		(width 0.0889)
		(layer "In6.Cu")
		(net "UPI_CPU0_CPU1_P2P2_DP<22>")
	)
	(arc
		(start 110.527592 -275.570442)
		(mid 110.340394 -275.520299)
		(end 110.153196 -275.570442)
		(width 0.0889)
		(layer "In6.Cu")
		(net "UPI_CPU0_CPU1_P2P2_DP<22>")
	)
	(arc
		(start 110.985554 -276.377146)
		(mid 110.787326 -276.171298)
		(end 110.715044 -275.8948)
		(width 0.0889)
		(layer "In6.Cu")
		(net "UPI_CPU0_CPU1_P2P2_DP<22>")
	)
	(arc
		(start 107.717082 -287.608518)
		(mid 107.847996 -287.472158)
		(end 107.895644 -287.28924)
		(width 0.0889)
		(layer "In6.Cu")
		(net "UPI_CPU0_CPU1_P2P2_DP<22>")
	)
	(arc
		(start 110.536482 -282.725114)
		(mid 110.7152 -282.405836)
		(end 110.536482 -282.086558)
		(width 0.0889)
		(layer "In6.Cu")
		(net "UPI_CPU0_CPU1_P2P2_DP<22>")
	)
	(arc
		(start 111.184944 -279.964134)
		(mid 111.258935 -279.684568)
		(end 111.46155 -279.478232)
		(width 0.0889)
		(layer "In6.Cu")
		(net "UPI_CPU0_CPU1_P2P2_DP<22>")
	)
	(segment
		(start 334.785716 -287.288986)
		(end 334.785462 -287.28924)
		(width 0.13208)
		(layer "F.Cu")
		(net "UPI_CPU0_CPU1_P2P2_DP<21>")
	)
	(segment
		(start 334.785716 -286.7533)
		(end 334.785716 -287.288986)
		(width 0.13208)
		(layer "F.Cu")
		(net "UPI_CPU0_CPU1_P2P2_DP<21>")
	)
	(segment
		(start 108.930694 -276.172676)
		(end 108.930694 -276.708616)
		(width 0.13208)
		(layer "F.Cu")
		(net "UPI_CPU0_CPU1_P2P2_DP<21>")
	)
	(segment
		(start 258.03606 -342.313514)
		(end 258.03606 -342.521286)
		(width 0.14732)
		(layer "In6.Cu")
		(net "UPI_CPU0_CPU1_P2P2_DP<21>")
	)
	(segment
		(start 261.079996 -341.036402)
		(end 260.30047 -340.256876)
		(width 0.14732)
		(layer "In6.Cu")
		(net "UPI_CPU0_CPU1_P2P2_DP<21>")
	)
	(segment
		(start 249.376946 -352.739452)
		(end 249.17654 -352.539046)
		(width 0.14732)
		(layer "In6.Cu")
		(net "UPI_CPU0_CPU1_P2P2_DP<21>")
	)
	(segment
		(start 110.52937 -278.826722)
		(end 110.527846 -278.82596)
		(width 0.0889)
		(layer "In6.Cu")
		(net "UPI_CPU0_CPU1_P2P2_DP<21>")
	)
	(segment
		(start 247.35663 -354.569268)
		(end 244.930168 -356.268782)
		(width 0.14732)
		(layer "In6.Cu")
		(net "UPI_CPU0_CPU1_P2P2_DP<21>")
	)
	(segment
		(start 257.176778 -344.93962)
		(end 257.176778 -345.375484)
		(width 0.14732)
		(layer "In6.Cu")
		(net "UPI_CPU0_CPU1_P2P2_DP<21>")
	)
	(segment
		(start 301.666148 -319.011046)
		(end 301.666148 -321.558158)
		(width 0.14732)
		(layer "In6.Cu")
		(net "UPI_CPU0_CPU1_P2P2_DP<21>")
	)
	(segment
		(start 307.5559 -313.156854)
		(end 306.562506 -314.150248)
		(width 0.14732)
		(layer "In6.Cu")
		(net "UPI_CPU0_CPU1_P2P2_DP<21>")
	)
	(segment
		(start 262.952484 -337.39709)
		(end 262.952484 -337.604862)
		(width 0.14732)
		(layer "In6.Cu")
		(net "UPI_CPU0_CPU1_P2P2_DP<21>")
	)
	(segment
		(start 250.815348 -350.900238)
		(end 250.607576 -350.900238)
		(width 0.14732)
		(layer "In6.Cu")
		(net "UPI_CPU0_CPU1_P2P2_DP<21>")
	)
	(segment
		(start 252.260354 -349.856044)
		(end 252.260354 -350.291908)
		(width 0.14732)
		(layer "In6.Cu")
		(net "UPI_CPU0_CPU1_P2P2_DP<21>")
	)
	(segment
		(start 107.425744 -290.072064)
		(end 107.425744 -289.645852)
		(width 0.0889)
		(layer "In6.Cu")
		(net "UPI_CPU0_CPU1_P2P2_DP<21>")
	)
	(segment
		(start 268.286738 -332.062836)
		(end 267.868908 -332.480666)
		(width 0.14732)
		(layer "In6.Cu")
		(net "UPI_CPU0_CPU1_P2P2_DP<21>")
	)
	(segment
		(start 271.213834 -326.612504)
		(end 271.213834 -331.338428)
		(width 0.14732)
		(layer "In6.Cu")
		(net "UPI_CPU0_CPU1_P2P2_DP<21>")
	)
	(segment
		(start 334.17129 -289.09645)
		(end 333.930752 -289.336988)
		(width 0.14732)
		(layer "In6.Cu")
		(net "UPI_CPU0_CPU1_P2P2_DP<21>")
	)
	(segment
		(start 263.154668 -339.397594)
		(end 262.718804 -339.397594)
		(width 0.14732)
		(layer "In6.Cu")
		(net "UPI_CPU0_CPU1_P2P2_DP<21>")
	)
	(segment
		(start 239.890046 -361.13593)
		(end 239.345978 -360.359198)
		(width 0.14732)
		(layer "In6.Cu")
		(net "UPI_CPU0_CPU1_P2P2_DP<21>")
	)
	(segment
		(start 106.807 -290.690808)
		(end 106.932476 -290.565332)
		(width 0.0889)
		(layer "In6.Cu")
		(net "UPI_CPU0_CPU1_P2P2_DP<21>")
	)
	(segment
		(start 245.207028 -356.921054)
		(end 245.13159 -357.349552)
		(width 0.14732)
		(layer "In6.Cu")
		(net "UPI_CPU0_CPU1_P2P2_DP<21>")
	)
	(segment
		(start 199.483726 -368.033046)
		(end 158.993078 -375.172224)
		(width 0.14732)
		(layer "In6.Cu")
		(net "UPI_CPU0_CPU1_P2P2_DP<21>")
	)
	(segment
		(start 98.448876 -306.295806)
		(end 103.681784 -300.077632)
		(width 0.14732)
		(layer "In6.Cu")
		(net "UPI_CPU0_CPU1_P2P2_DP<21>")
	)
	(segment
		(start 243.719604 -357.296212)
		(end 243.514626 -357.25989)
		(width 0.14732)
		(layer "In6.Cu")
		(net "UPI_CPU0_CPU1_P2P2_DP<21>")
	)
	(segment
		(start 334.129126 -288.517584)
		(end 334.17129 -288.559748)
		(width 0.0889)
		(layer "In6.Cu")
		(net "UPI_CPU0_CPU1_P2P2_DP<21>")
	)
	(segment
		(start 254.758444 -345.59113)
		(end 254.758444 -345.798902)
		(width 0.14732)
		(layer "In6.Cu")
		(net "UPI_CPU0_CPU1_P2P2_DP<21>")
	)
	(segment
		(start 110.524036 -279.476962)
		(end 110.527846 -279.474676)
		(width 0.0889)
		(layer "In6.Cu")
		(net "UPI_CPU0_CPU1_P2P2_DP<21>")
	)
	(segment
		(start 242.962684 -358.983788)
		(end 242.887246 -359.412286)
		(width 0.14732)
		(layer "In6.Cu")
		(net "UPI_CPU0_CPU1_P2P2_DP<21>")
	)
	(segment
		(start 242.454938 -358.002078)
		(end 242.418616 -358.207056)
		(width 0.14732)
		(layer "In6.Cu")
		(net "UPI_CPU0_CPU1_P2P2_DP<21>")
	)
	(segment
		(start 306.562506 -314.150248)
		(end 306.264564 -314.150248)
		(width 0.14732)
		(layer "In6.Cu")
		(net "UPI_CPU0_CPU1_P2P2_DP<21>")
	)
	(segment
		(start 253.899162 -348.6531)
		(end 253.32182 -349.230442)
		(width 0.14732)
		(layer "In6.Cu")
		(net "UPI_CPU0_CPU1_P2P2_DP<21>")
	)
	(segment
		(start 107.058206 -290.299394)
		(end 107.198414 -290.299394)
		(width 0.0889)
		(layer "In6.Cu")
		(net "UPI_CPU0_CPU1_P2P2_DP<21>")
	)
	(segment
		(start 110.058454 -276.384766)
		(end 110.057692 -276.384258)
		(width 0.0889)
		(layer "In6.Cu")
		(net "UPI_CPU0_CPU1_P2P2_DP<21>")
	)
	(segment
		(start 253.745238 -346.812108)
		(end 253.537466 -346.812108)
		(width 0.14732)
		(layer "In6.Cu")
		(net "UPI_CPU0_CPU1_P2P2_DP<21>")
	)
	(segment
		(start 228.837236 -367.53927)
		(end 212.758782 -370.37391)
		(width 0.14732)
		(layer "In6.Cu")
		(net "UPI_CPU0_CPU1_P2P2_DP<21>")
	)
	(segment
		(start 109.305344 -281.601926)
		(end 109.305344 -281.582114)
		(width 0.0889)
		(layer "In6.Cu")
		(net "UPI_CPU0_CPU1_P2P2_DP<21>")
	)
	(segment
		(start 334.410812 -287.84169)
		(end 334.410812 -288.036508)
		(width 0.0889)
		(layer "In6.Cu")
		(net "UPI_CPU0_CPU1_P2P2_DP<21>")
	)
	(segment
		(start 255.53797 -346.578428)
		(end 255.53797 -347.014292)
		(width 0.14732)
		(layer "In6.Cu")
		(net "UPI_CPU0_CPU1_P2P2_DP<21>")
	)
	(segment
		(start 256.599436 -345.952826)
		(end 256.163572 -345.952826)
		(width 0.14732)
		(layer "In6.Cu")
		(net "UPI_CPU0_CPU1_P2P2_DP<21>")
	)
	(segment
		(start 244.032786 -357.743506)
		(end 243.719604 -357.296212)
		(width 0.14732)
		(layer "In6.Cu")
		(net "UPI_CPU0_CPU1_P2P2_DP<21>")
	)
	(segment
		(start 265.370818 -336.74558)
		(end 265.370818 -337.181444)
		(width 0.14732)
		(layer "In6.Cu")
		(net "UPI_CPU0_CPU1_P2P2_DP<21>")
	)
	(segment
		(start 243.514626 -357.25989)
		(end 242.454938 -358.002078)
		(width 0.14732)
		(layer "In6.Cu")
		(net "UPI_CPU0_CPU1_P2P2_DP<21>")
	)
	(segment
		(start 314.550044 -311.283858)
		(end 311.216294 -311.97042)
		(width 0.14732)
		(layer "In6.Cu")
		(net "UPI_CPU0_CPU1_P2P2_DP<21>")
	)
	(segment
		(start 304.624486 -315.485526)
		(end 304.240692 -315.679074)
		(width 0.14732)
		(layer "In6.Cu")
		(net "UPI_CPU0_CPU1_P2P2_DP<21>")
	)
	(segment
		(start 105.883202 -291.474144)
		(end 106.023664 -291.474144)
		(width 0.0889)
		(layer "In6.Cu")
		(net "UPI_CPU0_CPU1_P2P2_DP<21>")
	)
	(segment
		(start 334.410812 -287.46831)
		(end 334.509872 -287.56737)
		(width 0.0889)
		(layer "In6.Cu")
		(net "UPI_CPU0_CPU1_P2P2_DP<21>")
	)
	(segment
		(start 106.540808 -290.957)
		(end 106.540808 -290.816538)
		(width 0.0889)
		(layer "In6.Cu")
		(net "UPI_CPU0_CPU1_P2P2_DP<21>")
	)
	(segment
		(start 264.357612 -337.758786)
		(end 263.578086 -336.97926)
		(width 0.14732)
		(layer "In6.Cu")
		(net "UPI_CPU0_CPU1_P2P2_DP<21>")
	)
	(segment
		(start 108.365544 -284.856174)
		(end 108.365544 -284.847538)
		(width 0.0889)
		(layer "In6.Cu")
		(net "UPI_CPU0_CPU1_P2P2_DP<21>")
	)
	(segment
		(start 110.527846 -279.474676)
		(end 110.536736 -279.469596)
		(width 0.0889)
		(layer "In6.Cu")
		(net "UPI_CPU0_CPU1_P2P2_DP<21>")
	)
	(segment
		(start 272.283936 -325.542402)
		(end 271.213834 -326.612504)
		(width 0.14732)
		(layer "In6.Cu")
		(net "UPI_CPU0_CPU1_P2P2_DP<21>")
	)
	(segment
		(start 257.176778 -345.375484)
		(end 256.599436 -345.952826)
		(width 0.14732)
		(layer "In6.Cu")
		(net "UPI_CPU0_CPU1_P2P2_DP<21>")
	)
	(segment
		(start 329.124818 -299.326554)
		(end 317.167514 -311.283858)
		(width 0.14732)
		(layer "In6.Cu")
		(net "UPI_CPU0_CPU1_P2P2_DP<21>")
	)
	(segment
		(start 74.42327 -330.288646)
		(end 75.086972 -327.890886)
		(width 0.14732)
		(layer "In6.Cu")
		(net "UPI_CPU0_CPU1_P2P2_DP<21>")
	)
	(segment
		(start 241.788442 -359.80624)
		(end 241.244374 -359.029508)
		(width 0.14732)
		(layer "In6.Cu")
		(net "UPI_CPU0_CPU1_P2P2_DP<21>")
	)
	(segment
		(start 110.066582 -276.389338)
		(end 110.060994 -276.38629)
		(width 0.0889)
		(layer "In6.Cu")
		(net "UPI_CPU0_CPU1_P2P2_DP<21>")
	)
	(segment
		(start 249.81281 -352.739452)
		(end 249.376946 -352.739452)
		(width 0.14732)
		(layer "In6.Cu")
		(net "UPI_CPU0_CPU1_P2P2_DP<21>")
	)
	(segment
		(start 262.952484 -337.604862)
		(end 263.73201 -338.384388)
		(width 0.14732)
		(layer "In6.Cu")
		(net "UPI_CPU0_CPU1_P2P2_DP<21>")
	)
	(segment
		(start 262.093202 -340.45906)
		(end 261.51586 -341.036402)
		(width 0.14732)
		(layer "In6.Cu")
		(net "UPI_CPU0_CPU1_P2P2_DP<21>")
	)
	(segment
		(start 257.80238 -344.314018)
		(end 257.022854 -343.534492)
		(width 0.14732)
		(layer "In6.Cu")
		(net "UPI_CPU0_CPU1_P2P2_DP<21>")
	)
	(segment
		(start 107.425744 -286.475424)
		(end 107.425744 -286.4612)
		(width 0.0889)
		(layer "In6.Cu")
		(net "UPI_CPU0_CPU1_P2P2_DP<21>")
	)
	(segment
		(start 239.141 -360.322876)
		(end 228.837236 -367.53927)
		(width 0.14732)
		(layer "In6.Cu")
		(net "UPI_CPU0_CPU1_P2P2_DP<21>")
	)
	(segment
		(start 247.982994 -354.569268)
		(end 247.35663 -354.569268)
		(width 0.14732)
		(layer "In6.Cu")
		(net "UPI_CPU0_CPU1_P2P2_DP<21>")
	)
	(segment
		(start 261.939278 -338.618068)
		(end 261.731506 -338.618068)
		(width 0.14732)
		(layer "In6.Cu")
		(net "UPI_CPU0_CPU1_P2P2_DP<21>")
	)
	(segment
		(start 106.932476 -290.425124)
		(end 107.058206 -290.299394)
		(width 0.0889)
		(layer "In6.Cu")
		(net "UPI_CPU0_CPU1_P2P2_DP<21>")
	)
	(segment
		(start 296.89298 -324.226428)
		(end 287.158684 -324.226428)
		(width 0.14732)
		(layer "In6.Cu")
		(net "UPI_CPU0_CPU1_P2P2_DP<21>")
	)
	(segment
		(start 106.14914 -291.348668)
		(end 106.14914 -291.208206)
		(width 0.0889)
		(layer "In6.Cu")
		(net "UPI_CPU0_CPU1_P2P2_DP<21>")
	)
	(segment
		(start 250.189746 -351.318068)
		(end 250.189746 -351.52584)
		(width 0.14732)
		(layer "In6.Cu")
		(net "UPI_CPU0_CPU1_P2P2_DP<21>")
	)
	(segment
		(start 252.260354 -350.291908)
		(end 251.451618 -351.100644)
		(width 0.14732)
		(layer "In6.Cu")
		(net "UPI_CPU0_CPU1_P2P2_DP<21>")
	)
	(segment
		(start 109.587792 -282.730194)
		(end 109.596682 -282.725114)
		(width 0.0889)
		(layer "In6.Cu")
		(net "UPI_CPU0_CPU1_P2P2_DP<21>")
	)
	(segment
		(start 250.390152 -351.726246)
		(end 250.390152 -352.16211)
		(width 0.14732)
		(layer "In6.Cu")
		(net "UPI_CPU0_CPU1_P2P2_DP<21>")
	)
	(segment
		(start 334.628998 -287.018222)
		(end 334.550766 -286.997394)
		(width 0.0889)
		(layer "In6.Cu")
		(net "UPI_CPU0_CPU1_P2P2_DP<21>")
	)
	(segment
		(start 248.550938 -353.164648)
		(end 248.751344 -353.365054)
		(width 0.14732)
		(layer "In6.Cu")
		(net "UPI_CPU0_CPU1_P2P2_DP<21>")
	)
	(segment
		(start 106.27487 -291.082476)
		(end 106.415332 -291.082476)
		(width 0.0889)
		(layer "In6.Cu")
		(net "UPI_CPU0_CPU1_P2P2_DP<21>")
	)
	(segment
		(start 106.540808 -290.816538)
		(end 106.666538 -290.690808)
		(width 0.0889)
		(layer "In6.Cu")
		(net "UPI_CPU0_CPU1_P2P2_DP<21>")
	)
	(segment
		(start 244.893846 -356.47376)
		(end 245.207028 -356.921054)
		(width 0.14732)
		(layer "In6.Cu")
		(net "UPI_CPU0_CPU1_P2P2_DP<21>")
	)
	(segment
		(start 73.938638 -335.207864)
		(end 74.42327 -330.288646)
		(width 0.14732)
		(layer "In6.Cu")
		(net "UPI_CPU0_CPU1_P2P2_DP<21>")
	)
	(segment
		(start 110.527846 -278.82596)
		(end 110.525052 -278.824436)
		(width 0.0889)
		(layer "In6.Cu")
		(net "UPI_CPU0_CPU1_P2P2_DP<21>")
	)
	(segment
		(start 80.969358 -363.273594)
		(end 77.192124 -359.496868)
		(width 0.14732)
		(layer "In6.Cu")
		(net "UPI_CPU0_CPU1_P2P2_DP<21>")
	)
	(segment
		(start 269.274036 -332.842362)
		(end 268.49451 -332.062836)
		(width 0.14732)
		(layer "In6.Cu")
		(net "UPI_CPU0_CPU1_P2P2_DP<21>")
	)
	(segment
		(start 250.189746 -351.52584)
		(end 250.390152 -351.726246)
		(width 0.14732)
		(layer "In6.Cu")
		(net "UPI_CPU0_CPU1_P2P2_DP<21>")
	)
	(segment
		(start 262.718804 -339.397594)
		(end 261.939278 -338.618068)
		(width 0.14732)
		(layer "In6.Cu")
		(net "UPI_CPU0_CPU1_P2P2_DP<21>")
	)
	(segment
		(start 241.03965 -358.993186)
		(end 240.556542 -359.331768)
		(width 0.14732)
		(layer "In6.Cu")
		(net "UPI_CPU0_CPU1_P2P2_DP<21>")
	)
	(segment
		(start 106.023664 -291.474144)
		(end 106.14914 -291.348668)
		(width 0.0889)
		(layer "In6.Cu")
		(net "UPI_CPU0_CPU1_P2P2_DP<21>")
	)
	(segment
		(start 251.015754 -351.100644)
		(end 250.815348 -350.900238)
		(width 0.14732)
		(layer "In6.Cu")
		(net "UPI_CPU0_CPU1_P2P2_DP<21>")
	)
	(segment
		(start 158.993078 -375.172224)
		(end 126.176532 -375.172224)
		(width 0.14732)
		(layer "In6.Cu")
		(net "UPI_CPU0_CPU1_P2P2_DP<21>")
	)
	(segment
		(start 109.176058 -276.413976)
		(end 109.087158 -276.437598)
		(width 0.0889)
		(layer "In6.Cu")
		(net "UPI_CPU0_CPU1_P2P2_DP<21>")
	)
	(segment
		(start 100.497132 -371.362986)
		(end 80.969358 -363.273594)
		(width 0.14732)
		(layer "In6.Cu")
		(net "UPI_CPU0_CPU1_P2P2_DP<21>")
	)
	(segment
		(start 241.244374 -359.029508)
		(end 241.03965 -358.993186)
		(width 0.14732)
		(layer "In6.Cu")
		(net "UPI_CPU0_CPU1_P2P2_DP<21>")
	)
	(segment
		(start 109.775244 -280.778204)
		(end 109.775244 -280.759662)
		(width 0.0889)
		(layer "In6.Cu")
		(net "UPI_CPU0_CPU1_P2P2_DP<21>")
	)
	(segment
		(start 266.2301 -334.327246)
		(end 267.009626 -335.106772)
		(width 0.14732)
		(layer "In6.Cu")
		(net "UPI_CPU0_CPU1_P2P2_DP<21>")
	)
	(segment
		(start 252.885956 -349.230442)
		(end 252.10643 -348.450916)
		(width 0.14732)
		(layer "In6.Cu")
		(net "UPI_CPU0_CPU1_P2P2_DP<21>")
	)
	(segment
		(start 110.060994 -276.38629)
		(end 110.058454 -276.384766)
		(width 0.0889)
		(layer "In6.Cu")
		(net "UPI_CPU0_CPU1_P2P2_DP<21>")
	)
	(segment
		(start 75.086972 -327.890886)
		(end 76.236322 -325.460868)
		(width 0.14732)
		(layer "In6.Cu")
		(net "UPI_CPU0_CPU1_P2P2_DP<21>")
	)
	(segment
		(start 266.2301 -334.119474)
		(end 266.2301 -334.327246)
		(width 0.14732)
		(layer "In6.Cu")
		(net "UPI_CPU0_CPU1_P2P2_DP<21>")
	)
	(segment
		(start 241.064288 -360.313478)
		(end 240.98885 -360.741976)
		(width 0.14732)
		(layer "In6.Cu")
		(net "UPI_CPU0_CPU1_P2P2_DP<21>")
	)
	(segment
		(start 254.524764 -347.591634)
		(end 253.745238 -346.812108)
		(width 0.14732)
		(layer "In6.Cu")
		(net "UPI_CPU0_CPU1_P2P2_DP<21>")
	)
	(segment
		(start 103.681784 -300.077632)
		(end 105.469182 -297.667934)
		(width 0.14732)
		(layer "In6.Cu")
		(net "UPI_CPU0_CPU1_P2P2_DP<21>")
	)
	(segment
		(start 110.245144 -278.336502)
		(end 110.245144 -278.31796)
		(width 0.0889)
		(layer "In6.Cu")
		(net "UPI_CPU0_CPU1_P2P2_DP<21>")
	)
	(segment
		(start 334.410812 -287.28924)
		(end 334.410812 -287.46831)
		(width 0.0889)
		(layer "In6.Cu")
		(net "UPI_CPU0_CPU1_P2P2_DP<21>")
	)
	(segment
		(start 244.930168 -356.268782)
		(end 244.893846 -356.47376)
		(width 0.14732)
		(layer "In6.Cu")
		(net "UPI_CPU0_CPU1_P2P2_DP<21>")
	)
	(segment
		(start 260.30047 -340.256876)
		(end 260.092698 -340.256876)
		(width 0.14732)
		(layer "In6.Cu")
		(net "UPI_CPU0_CPU1_P2P2_DP<21>")
	)
	(segment
		(start 106.76255 -287.617154)
		(end 106.767884 -287.614106)
		(width 0.0889)
		(layer "In6.Cu")
		(net "UPI_CPU0_CPU1_P2P2_DP<21>")
	)
	(segment
		(start 110.536736 -278.83104)
		(end 110.52937 -278.826722)
		(width 0.0889)
		(layer "In6.Cu")
		(net "UPI_CPU0_CPU1_P2P2_DP<21>")
	)
	(segment
		(start 240.98885 -360.741976)
		(end 240.318544 -361.211368)
		(width 0.14732)
		(layer "In6.Cu")
		(net "UPI_CPU0_CPU1_P2P2_DP<21>")
	)
	(segment
		(start 109.087158 -276.437598)
		(end 108.930694 -276.708616)
		(width 0.0889)
		(layer "In6.Cu")
		(net "UPI_CPU0_CPU1_P2P2_DP<21>")
	)
	(segment
		(start 261.731506 -338.618068)
		(end 261.313676 -339.035898)
		(width 0.14732)
		(layer "In6.Cu")
		(net "UPI_CPU0_CPU1_P2P2_DP<21>")
	)
	(segment
		(start 110.536482 -277.203154)
		(end 110.523528 -277.195788)
		(width 0.0889)
		(layer "In6.Cu")
		(net "UPI_CPU0_CPU1_P2P2_DP<21>")
	)
	(segment
		(start 310.02986 -313.156854)
		(end 307.5559 -313.156854)
		(width 0.14732)
		(layer "In6.Cu")
		(net "UPI_CPU0_CPU1_P2P2_DP<21>")
	)
	(segment
		(start 105.5624 -292.221158)
		(end 105.5624 -292.19906)
		(width 0.0889)
		(layer "In6.Cu")
		(net "UPI_CPU0_CPU1_P2P2_DP<21>")
	)
	(segment
		(start 317.167514 -311.283858)
		(end 314.550044 -311.283858)
		(width 0.14732)
		(layer "In6.Cu")
		(net "UPI_CPU0_CPU1_P2P2_DP<21>")
	)
	(segment
		(start 258.815586 -343.736676)
		(end 258.238244 -344.314018)
		(width 0.14732)
		(layer "In6.Cu")
		(net "UPI_CPU0_CPU1_P2P2_DP<21>")
	)
	(segment
		(start 266.64793 -333.701644)
		(end 266.2301 -334.119474)
		(width 0.14732)
		(layer "In6.Cu")
		(net "UPI_CPU0_CPU1_P2P2_DP<21>")
	)
	(segment
		(start 264.591292 -335.966054)
		(end 265.370818 -336.74558)
		(width 0.14732)
		(layer "In6.Cu")
		(net "UPI_CPU0_CPU1_P2P2_DP<21>")
	)
	(segment
		(start 301.666148 -321.558158)
		(end 300.486826 -322.73748)
		(width 0.14732)
		(layer "In6.Cu")
		(net "UPI_CPU0_CPU1_P2P2_DP<21>")
	)
	(segment
		(start 265.370818 -337.181444)
		(end 264.793476 -337.758786)
		(width 0.14732)
		(layer "In6.Cu")
		(net "UPI_CPU0_CPU1_P2P2_DP<21>")
	)
	(segment
		(start 304.240692 -315.679074)
		(end 303.27854 -316.640972)
		(width 0.14732)
		(layer "In6.Cu")
		(net "UPI_CPU0_CPU1_P2P2_DP<21>")
	)
	(segment
		(start 258.45389 -341.895684)
		(end 258.03606 -342.313514)
		(width 0.14732)
		(layer "In6.Cu")
		(net "UPI_CPU0_CPU1_P2P2_DP<21>")
	)
	(segment
		(start 264.793476 -337.758786)
		(end 264.357612 -337.758786)
		(width 0.14732)
		(layer "In6.Cu")
		(net "UPI_CPU0_CPU1_P2P2_DP<21>")
	)
	(segment
		(start 265.99642 -336.119978)
		(end 265.216894 -335.340452)
		(width 0.14732)
		(layer "In6.Cu")
		(net "UPI_CPU0_CPU1_P2P2_DP<21>")
	)
	(segment
		(start 285.100014 -325.079106)
		(end 279.171908 -325.079106)
		(width 0.14732)
		(layer "In6.Cu")
		(net "UPI_CPU0_CPU1_P2P2_DP<21>")
	)
	(segment
		(start 267.868908 -332.480666)
		(end 267.868908 -332.688438)
		(width 0.14732)
		(layer "In6.Cu")
		(net "UPI_CPU0_CPU1_P2P2_DP<21>")
	)
	(segment
		(start 110.523528 -277.195788)
		(end 110.521496 -277.194518)
		(width 0.0889)
		(layer "In6.Cu")
		(net "UPI_CPU0_CPU1_P2P2_DP<21>")
	)
	(segment
		(start 110.525052 -278.824436)
		(end 110.52175 -278.822404)
		(width 0.0889)
		(layer "In6.Cu")
		(net "UPI_CPU0_CPU1_P2P2_DP<21>")
	)
	(segment
		(start 263.73201 -338.384388)
		(end 263.73201 -338.820252)
		(width 0.14732)
		(layer "In6.Cu")
		(net "UPI_CPU0_CPU1_P2P2_DP<21>")
	)
	(segment
		(start 268.648434 -333.467964)
		(end 268.648434 -333.903828)
		(width 0.14732)
		(layer "In6.Cu")
		(net "UPI_CPU0_CPU1_P2P2_DP<21>")
	)
	(segment
		(start 260.454394 -341.662004)
		(end 260.454394 -342.097868)
		(width 0.14732)
		(layer "In6.Cu")
		(net "UPI_CPU0_CPU1_P2P2_DP<21>")
	)
	(segment
		(start 263.370314 -336.97926)
		(end 262.952484 -337.39709)
		(width 0.14732)
		(layer "In6.Cu")
		(net "UPI_CPU0_CPU1_P2P2_DP<21>")
	)
	(segment
		(start 109.117892 -283.544264)
		(end 109.126782 -283.539184)
		(width 0.0889)
		(layer "In6.Cu")
		(net "UPI_CPU0_CPU1_P2P2_DP<21>")
	)
	(segment
		(start 106.955844 -287.297876)
		(end 106.955844 -287.279334)
		(width 0.0889)
		(layer "In6.Cu")
		(net "UPI_CPU0_CPU1_P2P2_DP<21>")
	)
	(segment
		(start 256.397252 -343.952322)
		(end 256.397252 -344.160094)
		(width 0.14732)
		(layer "In6.Cu")
		(net "UPI_CPU0_CPU1_P2P2_DP<21>")
	)
	(segment
		(start 300.486826 -322.73748)
		(end 296.89298 -324.226428)
		(width 0.14732)
		(layer "In6.Cu")
		(net "UPI_CPU0_CPU1_P2P2_DP<21>")
	)
	(segment
		(start 110.515654 -279.481788)
		(end 110.524036 -279.476962)
		(width 0.0889)
		(layer "In6.Cu")
		(net "UPI_CPU0_CPU1_P2P2_DP<21>")
	)
	(segment
		(start 256.163572 -345.952826)
		(end 255.384046 -345.1733)
		(width 0.14732)
		(layer "In6.Cu")
		(net "UPI_CPU0_CPU1_P2P2_DP<21>")
	)
	(segment
		(start 268.49451 -332.062836)
		(end 268.286738 -332.062836)
		(width 0.14732)
		(layer "In6.Cu")
		(net "UPI_CPU0_CPU1_P2P2_DP<21>")
	)
	(segment
		(start 251.898658 -348.450916)
		(end 251.480828 -348.868746)
		(width 0.14732)
		(layer "In6.Cu")
		(net "UPI_CPU0_CPU1_P2P2_DP<21>")
	)
	(segment
		(start 263.578086 -336.97926)
		(end 263.370314 -336.97926)
		(width 0.14732)
		(layer "In6.Cu")
		(net "UPI_CPU0_CPU1_P2P2_DP<21>")
	)
	(segment
		(start 244.461284 -357.818944)
		(end 244.032786 -357.743506)
		(width 0.14732)
		(layer "In6.Cu")
		(net "UPI_CPU0_CPU1_P2P2_DP<21>")
	)
	(segment
		(start 267.635228 -334.48117)
		(end 266.855702 -333.701644)
		(width 0.14732)
		(layer "In6.Cu")
		(net "UPI_CPU0_CPU1_P2P2_DP<21>")
	)
	(segment
		(start 105.757472 -291.599874)
		(end 105.883202 -291.474144)
		(width 0.0889)
		(layer "In6.Cu")
		(net "UPI_CPU0_CPU1_P2P2_DP<21>")
	)
	(segment
		(start 106.14914 -291.208206)
		(end 106.27487 -291.082476)
		(width 0.0889)
		(layer "In6.Cu")
		(net "UPI_CPU0_CPU1_P2P2_DP<21>")
	)
	(segment
		(start 81.470246 -320.226944)
		(end 98.448876 -306.295806)
		(width 0.14732)
		(layer "In6.Cu")
		(net "UPI_CPU0_CPU1_P2P2_DP<21>")
	)
	(segment
		(start 258.661662 -341.895684)
		(end 258.45389 -341.895684)
		(width 0.14732)
		(layer "In6.Cu")
		(net "UPI_CPU0_CPU1_P2P2_DP<21>")
	)
	(segment
		(start 253.119636 -347.229938)
		(end 253.119636 -347.43771)
		(width 0.14732)
		(layer "In6.Cu")
		(net "UPI_CPU0_CPU1_P2P2_DP<21>")
	)
	(segment
		(start 302.25238 -316.640972)
		(end 301.940468 -316.952884)
		(width 0.14732)
		(layer "In6.Cu")
		(net "UPI_CPU0_CPU1_P2P2_DP<21>")
	)
	(segment
		(start 255.176274 -345.1733)
		(end 254.758444 -345.59113)
		(width 0.14732)
		(layer "In6.Cu")
		(net "UPI_CPU0_CPU1_P2P2_DP<21>")
	)
	(segment
		(start 240.556542 -359.331768)
		(end 240.52022 -359.536746)
		(width 0.14732)
		(layer "In6.Cu")
		(net "UPI_CPU0_CPU1_P2P2_DP<21>")
	)
	(segment
		(start 106.777536 -288.597848)
		(end 106.768646 -288.592768)
		(width 0.0889)
		(layer "In6.Cu")
		(net "UPI_CPU0_CPU1_P2P2_DP<21>")
	)
	(segment
		(start 258.238244 -344.314018)
		(end 257.80238 -344.314018)
		(width 0.14732)
		(layer "In6.Cu")
		(net "UPI_CPU0_CPU1_P2P2_DP<21>")
	)
	(segment
		(start 108.835444 -284.042358)
		(end 108.835444 -284.023816)
		(width 0.0889)
		(layer "In6.Cu")
		(net "UPI_CPU0_CPU1_P2P2_DP<21>")
	)
	(segment
		(start 73.938638 -351.651062)
		(end 73.938638 -335.207864)
		(width 0.14732)
		(layer "In6.Cu")
		(net "UPI_CPU0_CPU1_P2P2_DP<21>")
	)
	(segment
		(start 267.868908 -332.688438)
		(end 268.648434 -333.467964)
		(width 0.14732)
		(layer "In6.Cu")
		(net "UPI_CPU0_CPU1_P2P2_DP<21>")
	)
	(segment
		(start 334.509872 -287.74263)
		(end 334.410812 -287.84169)
		(width 0.0889)
		(layer "In6.Cu")
		(net "UPI_CPU0_CPU1_P2P2_DP<21>")
	)
	(segment
		(start 250.607576 -350.900238)
		(end 250.189746 -351.318068)
		(width 0.14732)
		(layer "In6.Cu")
		(net "UPI_CPU0_CPU1_P2P2_DP<21>")
	)
	(segment
		(start 240.52022 -359.536746)
		(end 241.064288 -360.313478)
		(width 0.14732)
		(layer "In6.Cu")
		(net "UPI_CPU0_CPU1_P2P2_DP<21>")
	)
	(segment
		(start 248.968768 -352.539046)
		(end 248.550938 -352.956876)
		(width 0.14732)
		(layer "In6.Cu")
		(net "UPI_CPU0_CPU1_P2P2_DP<21>")
	)
	(segment
		(start 242.21694 -359.881678)
		(end 241.788442 -359.80624)
		(width 0.14732)
		(layer "In6.Cu")
		(net "UPI_CPU0_CPU1_P2P2_DP<21>")
	)
	(segment
		(start 331.070204 -292.913562)
		(end 329.124818 -299.326554)
		(width 0.14732)
		(layer "In6.Cu")
		(net "UPI_CPU0_CPU1_P2P2_DP<21>")
	)
	(segment
		(start 251.480828 -348.868746)
		(end 251.480828 -349.076518)
		(width 0.14732)
		(layer "In6.Cu")
		(net "UPI_CPU0_CPU1_P2P2_DP<21>")
	)
	(segment
		(start 267.009626 -335.106772)
		(end 267.009626 -335.542636)
		(width 0.14732)
		(layer "In6.Cu")
		(net "UPI_CPU0_CPU1_P2P2_DP<21>")
	)
	(segment
		(start 279.171908 -325.079106)
		(end 278.708612 -325.542402)
		(width 0.14732)
		(layer "In6.Cu")
		(net "UPI_CPU0_CPU1_P2P2_DP<21>")
	)
	(segment
		(start 253.32182 -349.230442)
		(end 252.885956 -349.230442)
		(width 0.14732)
		(layer "In6.Cu")
		(net "UPI_CPU0_CPU1_P2P2_DP<21>")
	)
	(segment
		(start 334.129126 -288.47669)
		(end 334.129126 -288.517584)
		(width 0.0889)
		(layer "In6.Cu")
		(net "UPI_CPU0_CPU1_P2P2_DP<21>")
	)
	(segment
		(start 301.940468 -317.56096)
		(end 301.666148 -319.011046)
		(width 0.14732)
		(layer "In6.Cu")
		(net "UPI_CPU0_CPU1_P2P2_DP<21>")
	)
	(segment
		(start 240.318544 -361.211368)
		(end 239.890046 -361.13593)
		(width 0.14732)
		(layer "In6.Cu")
		(net "UPI_CPU0_CPU1_P2P2_DP<21>")
	)
	(segment
		(start 77.192124 -359.496868)
		(end 73.938638 -351.651062)
		(width 0.14732)
		(layer "In6.Cu")
		(net "UPI_CPU0_CPU1_P2P2_DP<21>")
	)
	(segment
		(start 107.708192 -285.985712)
		(end 107.717082 -285.980632)
		(width 0.0889)
		(layer "In6.Cu")
		(net "UPI_CPU0_CPU1_P2P2_DP<21>")
	)
	(segment
		(start 256.815082 -343.534492)
		(end 256.397252 -343.952322)
		(width 0.14732)
		(layer "In6.Cu")
		(net "UPI_CPU0_CPU1_P2P2_DP<21>")
	)
	(segment
		(start 261.313676 -339.24367)
		(end 262.093202 -340.023196)
		(width 0.14732)
		(layer "In6.Cu")
		(net "UPI_CPU0_CPU1_P2P2_DP<21>")
	)
	(segment
		(start 249.17654 -352.539046)
		(end 248.968768 -352.539046)
		(width 0.14732)
		(layer "In6.Cu")
		(net "UPI_CPU0_CPU1_P2P2_DP<21>")
	)
	(segment
		(start 253.119636 -347.43771)
		(end 253.899162 -348.217236)
		(width 0.14732)
		(layer "In6.Cu")
		(net "UPI_CPU0_CPU1_P2P2_DP<21>")
	)
	(segment
		(start 268.648434 -333.903828)
		(end 268.071092 -334.48117)
		(width 0.14732)
		(layer "In6.Cu")
		(net "UPI_CPU0_CPU1_P2P2_DP<21>")
	)
	(segment
		(start 106.767884 -287.614106)
		(end 106.768646 -287.613598)
		(width 0.0889)
		(layer "In6.Cu")
		(net "UPI_CPU0_CPU1_P2P2_DP<21>")
	)
	(segment
		(start 311.216294 -311.97042)
		(end 310.02986 -313.156854)
		(width 0.14732)
		(layer "In6.Cu")
		(net "UPI_CPU0_CPU1_P2P2_DP<21>")
	)
	(segment
		(start 105.5624 -292.19906)
		(end 105.60431 -292.15715)
		(width 0.0889)
		(layer "In6.Cu")
		(net "UPI_CPU0_CPU1_P2P2_DP<21>")
	)
	(segment
		(start 256.397252 -344.160094)
		(end 257.176778 -344.93962)
		(width 0.14732)
		(layer "In6.Cu")
		(net "UPI_CPU0_CPU1_P2P2_DP<21>")
	)
	(segment
		(start 268.071092 -334.48117)
		(end 267.635228 -334.48117)
		(width 0.14732)
		(layer "In6.Cu")
		(net "UPI_CPU0_CPU1_P2P2_DP<21>")
	)
	(segment
		(start 259.674868 -340.882478)
		(end 260.454394 -341.662004)
		(width 0.14732)
		(layer "In6.Cu")
		(net "UPI_CPU0_CPU1_P2P2_DP<21>")
	)
	(segment
		(start 242.418616 -358.207056)
		(end 242.962684 -358.983788)
		(width 0.14732)
		(layer "In6.Cu")
		(net "UPI_CPU0_CPU1_P2P2_DP<21>")
	)
	(segment
		(start 259.441188 -342.67521)
		(end 258.661662 -341.895684)
		(width 0.14732)
		(layer "In6.Cu")
		(net "UPI_CPU0_CPU1_P2P2_DP<21>")
	)
	(segment
		(start 260.092698 -340.256876)
		(end 259.674868 -340.674706)
		(width 0.14732)
		(layer "In6.Cu")
		(net "UPI_CPU0_CPU1_P2P2_DP<21>")
	)
	(segment
		(start 260.454394 -342.097868)
		(end 259.877052 -342.67521)
		(width 0.14732)
		(layer "In6.Cu")
		(net "UPI_CPU0_CPU1_P2P2_DP<21>")
	)
	(segment
		(start 332.513432 -290.754562)
		(end 331.070204 -292.913562)
		(width 0.14732)
		(layer "In6.Cu")
		(net "UPI_CPU0_CPU1_P2P2_DP<21>")
	)
	(segment
		(start 239.345978 -360.359198)
		(end 239.141 -360.322876)
		(width 0.14732)
		(layer "In6.Cu")
		(net "UPI_CPU0_CPU1_P2P2_DP<21>")
	)
	(segment
		(start 251.451618 -351.100644)
		(end 251.015754 -351.100644)
		(width 0.14732)
		(layer "In6.Cu")
		(net "UPI_CPU0_CPU1_P2P2_DP<21>")
	)
	(segment
		(start 255.53797 -347.014292)
		(end 254.960628 -347.591634)
		(width 0.14732)
		(layer "In6.Cu")
		(net "UPI_CPU0_CPU1_P2P2_DP<21>")
	)
	(segment
		(start 262.093202 -340.023196)
		(end 262.093202 -340.45906)
		(width 0.14732)
		(layer "In6.Cu")
		(net "UPI_CPU0_CPU1_P2P2_DP<21>")
	)
	(segment
		(start 253.537466 -346.812108)
		(end 253.119636 -347.229938)
		(width 0.14732)
		(layer "In6.Cu")
		(net "UPI_CPU0_CPU1_P2P2_DP<21>")
	)
	(segment
		(start 267.009626 -335.542636)
		(end 266.432284 -336.119978)
		(width 0.14732)
		(layer "In6.Cu")
		(net "UPI_CPU0_CPU1_P2P2_DP<21>")
	)
	(segment
		(start 254.758444 -345.798902)
		(end 255.53797 -346.578428)
		(width 0.14732)
		(layer "In6.Cu")
		(net "UPI_CPU0_CPU1_P2P2_DP<21>")
	)
	(segment
		(start 263.73201 -338.820252)
		(end 263.154668 -339.397594)
		(width 0.14732)
		(layer "In6.Cu")
		(net "UPI_CPU0_CPU1_P2P2_DP<21>")
	)
	(segment
		(start 333.930752 -289.336988)
		(end 332.513432 -290.754562)
		(width 0.14732)
		(layer "In6.Cu")
		(net "UPI_CPU0_CPU1_P2P2_DP<21>")
	)
	(segment
		(start 253.899162 -348.217236)
		(end 253.899162 -348.6531)
		(width 0.14732)
		(layer "In6.Cu")
		(net "UPI_CPU0_CPU1_P2P2_DP<21>")
	)
	(segment
		(start 334.509872 -287.56737)
		(end 334.509872 -287.74263)
		(width 0.0889)
		(layer "In6.Cu")
		(net "UPI_CPU0_CPU1_P2P2_DP<21>")
	)
	(segment
		(start 255.384046 -345.1733)
		(end 255.176274 -345.1733)
		(width 0.14732)
		(layer "In6.Cu")
		(net "UPI_CPU0_CPU1_P2P2_DP<21>")
	)
	(segment
		(start 250.390152 -352.16211)
		(end 249.81281 -352.739452)
		(width 0.14732)
		(layer "In6.Cu")
		(net "UPI_CPU0_CPU1_P2P2_DP<21>")
	)
	(segment
		(start 107.238292 -286.799782)
		(end 107.247182 -286.794702)
		(width 0.0889)
		(layer "In6.Cu")
		(net "UPI_CPU0_CPU1_P2P2_DP<21>")
	)
	(segment
		(start 248.751344 -353.800918)
		(end 247.982994 -354.569268)
		(width 0.14732)
		(layer "In6.Cu")
		(net "UPI_CPU0_CPU1_P2P2_DP<21>")
	)
	(segment
		(start 106.956098 -289.114738)
		(end 106.956098 -288.917126)
		(width 0.0889)
		(layer "In6.Cu")
		(net "UPI_CPU0_CPU1_P2P2_DP<21>")
	)
	(segment
		(start 105.757472 -291.740336)
		(end 105.757472 -291.599874)
		(width 0.0889)
		(layer "In6.Cu")
		(net "UPI_CPU0_CPU1_P2P2_DP<21>")
	)
	(segment
		(start 254.960628 -347.591634)
		(end 254.524764 -347.591634)
		(width 0.14732)
		(layer "In6.Cu")
		(net "UPI_CPU0_CPU1_P2P2_DP<21>")
	)
	(segment
		(start 251.480828 -349.076518)
		(end 252.260354 -349.856044)
		(width 0.14732)
		(layer "In6.Cu")
		(net "UPI_CPU0_CPU1_P2P2_DP<21>")
	)
	(segment
		(start 278.708612 -325.542402)
		(end 272.283936 -325.542402)
		(width 0.14732)
		(layer "In6.Cu")
		(net "UPI_CPU0_CPU1_P2P2_DP<21>")
	)
	(segment
		(start 261.51586 -341.036402)
		(end 261.079996 -341.036402)
		(width 0.14732)
		(layer "In6.Cu")
		(net "UPI_CPU0_CPU1_P2P2_DP<21>")
	)
	(segment
		(start 106.932476 -290.565332)
		(end 106.932476 -290.425124)
		(width 0.0889)
		(layer "In6.Cu")
		(net "UPI_CPU0_CPU1_P2P2_DP<21>")
	)
	(segment
		(start 110.527592 -277.84679)
		(end 110.536482 -277.84171)
		(width 0.0889)
		(layer "In6.Cu")
		(net "UPI_CPU0_CPU1_P2P2_DP<21>")
	)
	(segment
		(start 109.587792 -281.102562)
		(end 109.596682 -281.097482)
		(width 0.0889)
		(layer "In6.Cu")
		(net "UPI_CPU0_CPU1_P2P2_DP<21>")
	)
	(segment
		(start 287.158684 -324.226428)
		(end 285.100014 -325.079106)
		(width 0.14732)
		(layer "In6.Cu")
		(net "UPI_CPU0_CPU1_P2P2_DP<21>")
	)
	(segment
		(start 265.216894 -335.340452)
		(end 265.009122 -335.340452)
		(width 0.14732)
		(layer "In6.Cu")
		(net "UPI_CPU0_CPU1_P2P2_DP<21>")
	)
	(segment
		(start 266.432284 -336.119978)
		(end 265.99642 -336.119978)
		(width 0.14732)
		(layer "In6.Cu")
		(net "UPI_CPU0_CPU1_P2P2_DP<21>")
	)
	(segment
		(start 105.5624 -297.44289)
		(end 105.5624 -292.221158)
		(width 0.14732)
		(layer "In6.Cu")
		(net "UPI_CPU0_CPU1_P2P2_DP<21>")
	)
	(segment
		(start 110.057692 -280.288492)
		(end 110.066582 -280.283412)
		(width 0.0889)
		(layer "In6.Cu")
		(net "UPI_CPU0_CPU1_P2P2_DP<21>")
	)
	(segment
		(start 245.13159 -357.349552)
		(end 244.461284 -357.818944)
		(width 0.14732)
		(layer "In6.Cu")
		(net "UPI_CPU0_CPU1_P2P2_DP<21>")
	)
	(segment
		(start 242.887246 -359.412286)
		(end 242.21694 -359.881678)
		(width 0.14732)
		(layer "In6.Cu")
		(net "UPI_CPU0_CPU1_P2P2_DP<21>")
	)
	(segment
		(start 271.213834 -331.338428)
		(end 269.7099 -332.842362)
		(width 0.14732)
		(layer "In6.Cu")
		(net "UPI_CPU0_CPU1_P2P2_DP<21>")
	)
	(segment
		(start 266.855702 -333.701644)
		(end 266.64793 -333.701644)
		(width 0.14732)
		(layer "In6.Cu")
		(net "UPI_CPU0_CPU1_P2P2_DP<21>")
	)
	(segment
		(start 248.550938 -352.956876)
		(end 248.550938 -353.164648)
		(width 0.14732)
		(layer "In6.Cu")
		(net "UPI_CPU0_CPU1_P2P2_DP<21>")
	)
	(segment
		(start 106.415332 -291.082476)
		(end 106.540808 -290.957)
		(width 0.0889)
		(layer "In6.Cu")
		(net "UPI_CPU0_CPU1_P2P2_DP<21>")
	)
	(segment
		(start 212.758782 -370.37391)
		(end 199.483726 -368.033046)
		(width 0.14732)
		(layer "In6.Cu")
		(net "UPI_CPU0_CPU1_P2P2_DP<21>")
	)
	(segment
		(start 269.7099 -332.842362)
		(end 269.274036 -332.842362)
		(width 0.14732)
		(layer "In6.Cu")
		(net "UPI_CPU0_CPU1_P2P2_DP<21>")
	)
	(segment
		(start 258.815586 -343.300812)
		(end 258.815586 -343.736676)
		(width 0.14732)
		(layer "In6.Cu")
		(net "UPI_CPU0_CPU1_P2P2_DP<21>")
	)
	(segment
		(start 334.785462 -287.28924)
		(end 334.628998 -287.018222)
		(width 0.0889)
		(layer "In6.Cu")
		(net "UPI_CPU0_CPU1_P2P2_DP<21>")
	)
	(segment
		(start 105.60431 -292.15715)
		(end 105.60431 -291.893498)
		(width 0.0889)
		(layer "In6.Cu")
		(net "UPI_CPU0_CPU1_P2P2_DP<21>")
	)
	(segment
		(start 108.64215 -284.361636)
		(end 108.648246 -284.35808)
		(width 0.0889)
		(layer "In6.Cu")
		(net "UPI_CPU0_CPU1_P2P2_DP<21>")
	)
	(segment
		(start 334.410812 -288.036508)
		(end 334.129126 -288.47669)
		(width 0.0889)
		(layer "In6.Cu")
		(net "UPI_CPU0_CPU1_P2P2_DP<21>")
	)
	(segment
		(start 109.305344 -283.219906)
		(end 109.305344 -283.201364)
		(width 0.0889)
		(layer "In6.Cu")
		(net "UPI_CPU0_CPU1_P2P2_DP<21>")
	)
	(segment
		(start 105.469182 -297.667934)
		(end 105.5624 -297.44289)
		(width 0.14732)
		(layer "In6.Cu")
		(net "UPI_CPU0_CPU1_P2P2_DP<21>")
	)
	(segment
		(start 257.022854 -343.534492)
		(end 256.815082 -343.534492)
		(width 0.14732)
		(layer "In6.Cu")
		(net "UPI_CPU0_CPU1_P2P2_DP<21>")
	)
	(segment
		(start 109.596682 -282.086558)
		(end 109.587792 -282.081478)
		(width 0.0889)
		(layer "In6.Cu")
		(net "UPI_CPU0_CPU1_P2P2_DP<21>")
	)
	(segment
		(start 126.176532 -375.172224)
		(end 100.497132 -371.362986)
		(width 0.14732)
		(layer "In6.Cu")
		(net "UPI_CPU0_CPU1_P2P2_DP<21>")
	)
	(segment
		(start 301.940468 -316.952884)
		(end 301.940468 -317.56096)
		(width 0.14732)
		(layer "In6.Cu")
		(net "UPI_CPU0_CPU1_P2P2_DP<21>")
	)
	(segment
		(start 265.009122 -335.340452)
		(end 264.591292 -335.758282)
		(width 0.14732)
		(layer "In6.Cu")
		(net "UPI_CPU0_CPU1_P2P2_DP<21>")
	)
	(segment
		(start 106.485944 -288.11728)
		(end 106.485944 -288.103056)
		(width 0.0889)
		(layer "In6.Cu")
		(net "UPI_CPU0_CPU1_P2P2_DP<21>")
	)
	(segment
		(start 264.591292 -335.758282)
		(end 264.591292 -335.966054)
		(width 0.14732)
		(layer "In6.Cu")
		(net "UPI_CPU0_CPU1_P2P2_DP<21>")
	)
	(segment
		(start 248.751344 -353.365054)
		(end 248.751344 -353.800918)
		(width 0.14732)
		(layer "In6.Cu")
		(net "UPI_CPU0_CPU1_P2P2_DP<21>")
	)
	(segment
		(start 106.666538 -290.690808)
		(end 106.807 -290.690808)
		(width 0.0889)
		(layer "In6.Cu")
		(net "UPI_CPU0_CPU1_P2P2_DP<21>")
	)
	(segment
		(start 76.236322 -325.460868)
		(end 81.470246 -320.226944)
		(width 0.14732)
		(layer "In6.Cu")
		(net "UPI_CPU0_CPU1_P2P2_DP<21>")
	)
	(segment
		(start 107.198414 -290.299394)
		(end 107.425744 -290.072064)
		(width 0.0889)
		(layer "In6.Cu")
		(net "UPI_CPU0_CPU1_P2P2_DP<21>")
	)
	(segment
		(start 105.60431 -291.893498)
		(end 105.757472 -291.740336)
		(width 0.0889)
		(layer "In6.Cu")
		(net "UPI_CPU0_CPU1_P2P2_DP<21>")
	)
	(segment
		(start 334.17129 -288.581846)
		(end 334.17129 -289.09645)
		(width 0.14732)
		(layer "In6.Cu")
		(net "UPI_CPU0_CPU1_P2P2_DP<21>")
	)
	(segment
		(start 334.17129 -288.559748)
		(end 334.17129 -288.581846)
		(width 0.0889)
		(layer "In6.Cu")
		(net "UPI_CPU0_CPU1_P2P2_DP<21>")
	)
	(segment
		(start 252.10643 -348.450916)
		(end 251.898658 -348.450916)
		(width 0.14732)
		(layer "In6.Cu")
		(net "UPI_CPU0_CPU1_P2P2_DP<21>")
	)
	(segment
		(start 259.877052 -342.67521)
		(end 259.441188 -342.67521)
		(width 0.14732)
		(layer "In6.Cu")
		(net "UPI_CPU0_CPU1_P2P2_DP<21>")
	)
	(segment
		(start 306.264564 -314.150248)
		(end 304.624486 -315.485526)
		(width 0.14732)
		(layer "In6.Cu")
		(net "UPI_CPU0_CPU1_P2P2_DP<21>")
	)
	(segment
		(start 303.27854 -316.640972)
		(end 302.25238 -316.640972)
		(width 0.14732)
		(layer "In6.Cu")
		(net "UPI_CPU0_CPU1_P2P2_DP<21>")
	)
	(segment
		(start 258.03606 -342.521286)
		(end 258.815586 -343.300812)
		(width 0.14732)
		(layer "In6.Cu")
		(net "UPI_CPU0_CPU1_P2P2_DP<21>")
	)
	(segment
		(start 259.674868 -340.674706)
		(end 259.674868 -340.882478)
		(width 0.14732)
		(layer "In6.Cu")
		(net "UPI_CPU0_CPU1_P2P2_DP<21>")
	)
	(segment
		(start 108.166154 -285.179008)
		(end 108.178346 -285.171896)
		(width 0.0889)
		(layer "In6.Cu")
		(net "UPI_CPU0_CPU1_P2P2_DP<21>")
	)
	(segment
		(start 261.313676 -339.035898)
		(end 261.313676 -339.24367)
		(width 0.14732)
		(layer "In6.Cu")
		(net "UPI_CPU0_CPU1_P2P2_DP<21>")
	)
	(arc
		(start 109.126782 -283.539184)
		(mid 109.257696 -283.402824)
		(end 109.305344 -283.219906)
		(width 0.0889)
		(layer "In6.Cu")
		(net "UPI_CPU0_CPU1_P2P2_DP<21>")
	)
	(arc
		(start 106.956098 -288.917126)
		(mid 106.908419 -288.734226)
		(end 106.777536 -288.597848)
		(width 0.0889)
		(layer "In6.Cu")
		(net "UPI_CPU0_CPU1_P2P2_DP<21>")
	)
	(arc
		(start 109.305344 -281.582114)
		(mid 109.383455 -281.305165)
		(end 109.587792 -281.102562)
		(width 0.0889)
		(layer "In6.Cu")
		(net "UPI_CPU0_CPU1_P2P2_DP<21>")
	)
	(arc
		(start 109.775244 -280.759662)
		(mid 109.855406 -280.487473)
		(end 110.057692 -280.288492)
		(width 0.0889)
		(layer "In6.Cu")
		(net "UPI_CPU0_CPU1_P2P2_DP<21>")
	)
	(arc
		(start 106.768646 -287.613598)
		(mid 106.903579 -287.480244)
		(end 106.955844 -287.297876)
		(width 0.0889)
		(layer "In6.Cu")
		(net "UPI_CPU0_CPU1_P2P2_DP<21>")
	)
	(arc
		(start 107.895644 -285.661354)
		(mid 107.967879 -285.38483)
		(end 108.166154 -285.179008)
		(width 0.0889)
		(layer "In6.Cu")
		(net "UPI_CPU0_CPU1_P2P2_DP<21>")
	)
	(arc
		(start 107.425744 -286.4612)
		(mid 107.504885 -286.186577)
		(end 107.708192 -285.985712)
		(width 0.0889)
		(layer "In6.Cu")
		(net "UPI_CPU0_CPU1_P2P2_DP<21>")
	)
	(arc
		(start 110.536482 -277.84171)
		(mid 110.715079 -277.522432)
		(end 110.536482 -277.203154)
		(width 0.0889)
		(layer "In6.Cu")
		(net "UPI_CPU0_CPU1_P2P2_DP<21>")
	)
	(arc
		(start 108.648246 -284.35808)
		(mid 108.783179 -284.224726)
		(end 108.835444 -284.042358)
		(width 0.0889)
		(layer "In6.Cu")
		(net "UPI_CPU0_CPU1_P2P2_DP<21>")
	)
	(arc
		(start 106.485944 -288.103056)
		(mid 106.559935 -287.82349)
		(end 106.76255 -287.617154)
		(width 0.0889)
		(layer "In6.Cu")
		(net "UPI_CPU0_CPU1_P2P2_DP<21>")
	)
	(arc
		(start 109.305344 -283.201364)
		(mid 109.385506 -282.929175)
		(end 109.587792 -282.730194)
		(width 0.0889)
		(layer "In6.Cu")
		(net "UPI_CPU0_CPU1_P2P2_DP<21>")
	)
	(arc
		(start 109.77499 -282.418028)
		(mid 109.775235 -282.408632)
		(end 109.775244 -282.399232)
		(width 0.0889)
		(layer "In6.Cu")
		(net "UPI_CPU0_CPU1_P2P2_DP<21>")
	)
	(arc
		(start 110.066582 -280.283412)
		(mid 110.197496 -280.147052)
		(end 110.245144 -279.964134)
		(width 0.0889)
		(layer "In6.Cu")
		(net "UPI_CPU0_CPU1_P2P2_DP<21>")
	)
	(arc
		(start 106.768646 -288.592768)
		(mid 106.565165 -288.391964)
		(end 106.485944 -288.11728)
		(width 0.0889)
		(layer "In6.Cu")
		(net "UPI_CPU0_CPU1_P2P2_DP<21>")
	)
	(arc
		(start 110.245144 -279.964134)
		(mid 110.317379 -279.68761)
		(end 110.515654 -279.481788)
		(width 0.0889)
		(layer "In6.Cu")
		(net "UPI_CPU0_CPU1_P2P2_DP<21>")
	)
	(arc
		(start 109.683296 -276.384258)
		(mid 109.443883 -276.45859)
		(end 109.19587 -276.422104)
		(width 0.0889)
		(layer "In6.Cu")
		(net "UPI_CPU0_CPU1_P2P2_DP<21>")
	)
	(arc
		(start 110.245144 -276.708616)
		(mid 110.197465 -276.525716)
		(end 110.066582 -276.389338)
		(width 0.0889)
		(layer "In6.Cu")
		(net "UPI_CPU0_CPU1_P2P2_DP<21>")
	)
	(arc
		(start 110.057692 -276.384258)
		(mid 109.870494 -276.334115)
		(end 109.683296 -276.384258)
		(width 0.0889)
		(layer "In6.Cu")
		(net "UPI_CPU0_CPU1_P2P2_DP<21>")
	)
	(arc
		(start 107.241594 -289.446462)
		(mid 107.067462 -289.307615)
		(end 106.956098 -289.114738)
		(width 0.0889)
		(layer "In6.Cu")
		(net "UPI_CPU0_CPU1_P2P2_DP<21>")
	)
	(arc
		(start 108.835444 -284.023816)
		(mid 108.913555 -283.746867)
		(end 109.117892 -283.544264)
		(width 0.0889)
		(layer "In6.Cu")
		(net "UPI_CPU0_CPU1_P2P2_DP<21>")
	)
	(arc
		(start 109.775244 -282.399232)
		(mid 109.725991 -282.220032)
		(end 109.596682 -282.086558)
		(width 0.0889)
		(layer "In6.Cu")
		(net "UPI_CPU0_CPU1_P2P2_DP<21>")
	)
	(arc
		(start 109.587792 -282.081478)
		(mid 109.383457 -281.878873)
		(end 109.305344 -281.601926)
		(width 0.0889)
		(layer "In6.Cu")
		(net "UPI_CPU0_CPU1_P2P2_DP<21>")
	)
	(arc
		(start 109.596682 -281.097482)
		(mid 109.727596 -280.961122)
		(end 109.775244 -280.778204)
		(width 0.0889)
		(layer "In6.Cu")
		(net "UPI_CPU0_CPU1_P2P2_DP<21>")
	)
	(arc
		(start 109.596682 -282.725114)
		(mid 109.724575 -282.594052)
		(end 109.77499 -282.418028)
		(width 0.0889)
		(layer "In6.Cu")
		(net "UPI_CPU0_CPU1_P2P2_DP<21>")
	)
	(arc
		(start 110.715298 -279.150318)
		(mid 110.667619 -278.967418)
		(end 110.536736 -278.83104)
		(width 0.0889)
		(layer "In6.Cu")
		(net "UPI_CPU0_CPU1_P2P2_DP<21>")
	)
	(arc
		(start 106.955844 -287.279334)
		(mid 107.033955 -287.002385)
		(end 107.238292 -286.799782)
		(width 0.0889)
		(layer "In6.Cu")
		(net "UPI_CPU0_CPU1_P2P2_DP<21>")
	)
	(arc
		(start 110.245144 -278.31796)
		(mid 110.325306 -278.045771)
		(end 110.527592 -277.84679)
		(width 0.0889)
		(layer "In6.Cu")
		(net "UPI_CPU0_CPU1_P2P2_DP<21>")
	)
	(arc
		(start 107.717082 -285.980632)
		(mid 107.847996 -285.844272)
		(end 107.895644 -285.661354)
		(width 0.0889)
		(layer "In6.Cu")
		(net "UPI_CPU0_CPU1_P2P2_DP<21>")
	)
	(arc
		(start 110.536736 -279.469596)
		(mid 110.66765 -279.333236)
		(end 110.715298 -279.150318)
		(width 0.0889)
		(layer "In6.Cu")
		(net "UPI_CPU0_CPU1_P2P2_DP<21>")
	)
	(arc
		(start 107.247182 -286.794702)
		(mid 107.378096 -286.658342)
		(end 107.425744 -286.475424)
		(width 0.0889)
		(layer "In6.Cu")
		(net "UPI_CPU0_CPU1_P2P2_DP<21>")
	)
	(arc
		(start 108.365544 -284.847538)
		(mid 108.439535 -284.567972)
		(end 108.64215 -284.361636)
		(width 0.0889)
		(layer "In6.Cu")
		(net "UPI_CPU0_CPU1_P2P2_DP<21>")
	)
	(arc
		(start 108.178346 -285.171896)
		(mid 108.313279 -285.038542)
		(end 108.365544 -284.856174)
		(width 0.0889)
		(layer "In6.Cu")
		(net "UPI_CPU0_CPU1_P2P2_DP<21>")
	)
	(arc
		(start 109.19587 -276.422104)
		(mid 109.185926 -276.418133)
		(end 109.176058 -276.413976)
		(width 0.0889)
		(layer "In6.Cu")
		(net "UPI_CPU0_CPU1_P2P2_DP<21>")
	)
	(arc
		(start 110.52175 -278.822404)
		(mid 110.319163 -278.616053)
		(end 110.245144 -278.336502)
		(width 0.0889)
		(layer "In6.Cu")
		(net "UPI_CPU0_CPU1_P2P2_DP<21>")
	)
	(arc
		(start 107.425744 -289.645852)
		(mid 107.350739 -289.530393)
		(end 107.241594 -289.446462)
		(width 0.0889)
		(layer "In6.Cu")
		(net "UPI_CPU0_CPU1_P2P2_DP<21>")
	)
	(arc
		(start 110.521496 -277.194518)
		(mid 110.319083 -276.988105)
		(end 110.245144 -276.708616)
		(width 0.0889)
		(layer "In6.Cu")
		(net "UPI_CPU0_CPU1_P2P2_DP<21>")
	)
	(arc
		(start 334.550766 -286.997394)
		(mid 334.447621 -287.127419)
		(end 334.410812 -287.28924)
		(width 0.0889)
		(layer "In6.Cu")
		(net "UPI_CPU0_CPU1_P2P2_DP<21>")
	)
	(segment
		(start 336.195162 -285.939484)
		(end 336.195162 -286.475424)
		(width 0.13208)
		(layer "F.Cu")
		(net "UPI_CPU0_CPU1_P2P2_DP<20>")
	)
	(segment
		(start 107.521248 -275.35886)
		(end 107.521248 -275.894546)
		(width 0.13208)
		(layer "F.Cu")
		(net "UPI_CPU0_CPU1_P2P2_DP<20>")
	)
	(segment
		(start 107.521248 -275.894546)
		(end 107.520994 -275.8948)
		(width 0.13208)
		(layer "F.Cu")
		(net "UPI_CPU0_CPU1_P2P2_DP<20>")
	)
	(segment
		(start 236.685582 -362.743242)
		(end 236.01553 -363.212634)
		(width 0.14732)
		(layer "In6.Cu")
		(net "UPI_CPU0_CPU1_P2P2_DP<20>")
	)
	(segment
		(start 248.697242 -355.726238)
		(end 248.43359 -355.462586)
		(width 0.14732)
		(layer "In6.Cu")
		(net "UPI_CPU0_CPU1_P2P2_DP<20>")
	)
	(segment
		(start 239.012476 -361.489244)
		(end 238.583978 -361.413806)
		(width 0.14732)
		(layer "In6.Cu")
		(net "UPI_CPU0_CPU1_P2P2_DP<20>")
	)
	(segment
		(start 107.333796 -276.219158)
		(end 107.332272 -276.218396)
		(width 0.0889)
		(layer "In6.Cu")
		(net "UPI_CPU0_CPU1_P2P2_DP<20>")
	)
	(segment
		(start 278.243284 -327.791826)
		(end 278.243284 -327.999598)
		(width 0.14732)
		(layer "In6.Cu")
		(net "UPI_CPU0_CPU1_P2P2_DP<20>")
	)
	(segment
		(start 312.18505 -313.524646)
		(end 311.084722 -313.980576)
		(width 0.14732)
		(layer "In6.Cu")
		(net "UPI_CPU0_CPU1_P2P2_DP<20>")
	)
	(segment
		(start 256.272538 -347.187774)
		(end 256.272538 -347.623638)
		(width 0.14732)
		(layer "In6.Cu")
		(net "UPI_CPU0_CPU1_P2P2_DP<20>")
	)
	(segment
		(start 303.561242 -317.814198)
		(end 303.426622 -318.961516)
		(width 0.14732)
		(layer "In6.Cu")
		(net "UPI_CPU0_CPU1_P2P2_DP<20>")
	)
	(segment
		(start 259.550154 -343.910158)
		(end 259.550154 -344.346022)
		(width 0.14732)
		(layer "In6.Cu")
		(net "UPI_CPU0_CPU1_P2P2_DP<20>")
	)
	(segment
		(start 245.49227 -359.302558)
		(end 245.284498 -359.302558)
		(width 0.14732)
		(layer "In6.Cu")
		(net "UPI_CPU0_CPU1_P2P2_DP<20>")
	)
	(segment
		(start 75.747372 -325.162418)
		(end 81.084674 -319.825116)
		(width 0.14732)
		(layer "In6.Cu")
		(net "UPI_CPU0_CPU1_P2P2_DP<20>")
	)
	(segment
		(start 260.56336 -343.332816)
		(end 260.127496 -343.332816)
		(width 0.14732)
		(layer "In6.Cu")
		(net "UPI_CPU0_CPU1_P2P2_DP<20>")
	)
	(segment
		(start 262.730234 -342.222074)
		(end 262.202168 -341.694008)
		(width 0.14732)
		(layer "In6.Cu")
		(net "UPI_CPU0_CPU1_P2P2_DP<20>")
	)
	(segment
		(start 332.294484 -292.108382)
		(end 332.282292 -292.12667)
		(width 0.0889)
		(layer "In6.Cu")
		(net "UPI_CPU0_CPU1_P2P2_DP<20>")
	)
	(segment
		(start 237.11408 -362.81868)
		(end 236.685582 -362.743242)
		(width 0.14732)
		(layer "In6.Cu")
		(net "UPI_CPU0_CPU1_P2P2_DP<20>")
	)
	(segment
		(start 105.73639 -289.646868)
		(end 105.736644 -289.64636)
		(width 0.0889)
		(layer "In6.Cu")
		(net "UPI_CPU0_CPU1_P2P2_DP<20>")
	)
	(segment
		(start 233.479086 -367.138966)
		(end 233.288586 -366.057942)
		(width 0.14732)
		(layer "In6.Cu")
		(net "UPI_CPU0_CPU1_P2P2_DP<20>")
	)
	(segment
		(start 245.56466 -357.895652)
		(end 245.56466 -358.331516)
		(width 0.14732)
		(layer "In6.Cu")
		(net "UPI_CPU0_CPU1_P2P2_DP<20>")
	)
	(segment
		(start 300.798484 -323.229224)
		(end 296.992548 -324.805548)
		(width 0.14732)
		(layer "In6.Cu")
		(net "UPI_CPU0_CPU1_P2P2_DP<20>")
	)
	(segment
		(start 235.04271 -366.656874)
		(end 234.36326 -367.132616)
		(width 0.14732)
		(layer "In6.Cu")
		(net "UPI_CPU0_CPU1_P2P2_DP<20>")
	)
	(segment
		(start 258.924552 -344.971624)
		(end 258.488688 -344.971624)
		(width 0.14732)
		(layer "In6.Cu")
		(net "UPI_CPU0_CPU1_P2P2_DP<20>")
	)
	(segment
		(start 260.127496 -343.332816)
		(end 259.550154 -343.910158)
		(width 0.14732)
		(layer "In6.Cu")
		(net "UPI_CPU0_CPU1_P2P2_DP<20>")
	)
	(segment
		(start 234.36326 -367.132616)
		(end 233.64952 -367.2586)
		(width 0.14732)
		(layer "In6.Cu")
		(net "UPI_CPU0_CPU1_P2P2_DP<20>")
	)
	(segment
		(start 277.825454 -328.417428)
		(end 277.617682 -328.417428)
		(width 0.14732)
		(layer "In6.Cu")
		(net "UPI_CPU0_CPU1_P2P2_DP<20>")
	)
	(segment
		(start 254.63373 -349.262446)
		(end 255.161796 -349.790512)
		(width 0.14732)
		(layer "In6.Cu")
		(net "UPI_CPU0_CPU1_P2P2_DP<20>")
	)
	(segment
		(start 73.873868 -330.175108)
		(end 74.574146 -327.641966)
		(width 0.14732)
		(layer "In6.Cu")
		(net "UPI_CPU0_CPU1_P2P2_DP<20>")
	)
	(segment
		(start 106.206798 -289.114484)
		(end 106.206798 -288.902902)
		(width 0.0889)
		(layer "In6.Cu")
		(net "UPI_CPU0_CPU1_P2P2_DP<20>")
	)
	(segment
		(start 308.72049 -314.256928)
		(end 308.57571 -314.401708)
		(width 0.14732)
		(layer "In6.Cu")
		(net "UPI_CPU0_CPU1_P2P2_DP<20>")
	)
	(segment
		(start 249.322844 -355.100636)
		(end 249.322844 -355.308408)
		(width 0.14732)
		(layer "In6.Cu")
		(net "UPI_CPU0_CPU1_P2P2_DP<20>")
	)
	(segment
		(start 199.05853 -368.683032)
		(end 159.042862 -375.73839)
		(width 0.14732)
		(layer "In6.Cu")
		(net "UPI_CPU0_CPU1_P2P2_DP<20>")
	)
	(segment
		(start 256.382774 -348.777306)
		(end 256.175002 -348.777306)
		(width 0.14732)
		(layer "In6.Cu")
		(net "UPI_CPU0_CPU1_P2P2_DP<20>")
	)
	(segment
		(start 109.674406 -278.017224)
		(end 109.683296 -278.012144)
		(width 0.0889)
		(layer "In6.Cu")
		(net "UPI_CPU0_CPU1_P2P2_DP<20>")
	)
	(segment
		(start 234.787186 -364.072678)
		(end 234.11688 -364.541816)
		(width 0.14732)
		(layer "In6.Cu")
		(net "UPI_CPU0_CPU1_P2P2_DP<20>")
	)
	(segment
		(start 97.942908 -305.989482)
		(end 97.942908 -305.989736)
		(width 0.14732)
		(layer "In6.Cu")
		(net "UPI_CPU0_CPU1_P2P2_DP<20>")
	)
	(segment
		(start 109.68736 -278.663146)
		(end 109.683296 -278.66086)
		(width 0.0889)
		(layer "In6.Cu")
		(net "UPI_CPU0_CPU1_P2P2_DP<20>")
	)
	(segment
		(start 108.743496 -281.267662)
		(end 108.749592 -281.264106)
		(width 0.0889)
		(layer "In6.Cu")
		(net "UPI_CPU0_CPU1_P2P2_DP<20>")
	)
	(segment
		(start 307.683408 -314.401708)
		(end 306.887626 -315.19749)
		(width 0.14732)
		(layer "In6.Cu")
		(net "UPI_CPU0_CPU1_P2P2_DP<20>")
	)
	(segment
		(start 334.776318 -289.220656)
		(end 333.283052 -290.714176)
		(width 0.0889)
		(layer "In6.Cu")
		(net "UPI_CPU0_CPU1_P2P2_DP<20>")
	)
	(segment
		(start 99.321874 -371.773704)
		(end 81.127346 -364.23727)
		(width 0.14732)
		(layer "In6.Cu")
		(net "UPI_CPU0_CPU1_P2P2_DP<20>")
	)
	(segment
		(start 302.400462 -321.627246)
		(end 300.798484 -323.229224)
		(width 0.14732)
		(layer "In6.Cu")
		(net "UPI_CPU0_CPU1_P2P2_DP<20>")
	)
	(segment
		(start 305.08702 -316.163706)
		(end 305.053238 -316.36589)
		(width 0.14732)
		(layer "In6.Cu")
		(net "UPI_CPU0_CPU1_P2P2_DP<20>")
	)
	(segment
		(start 335.44256 -287.778698)
		(end 335.45145 -287.783778)
		(width 0.0889)
		(layer "In6.Cu")
		(net "UPI_CPU0_CPU1_P2P2_DP<20>")
	)
	(segment
		(start 332.35265 -292.09746)
		(end 332.294484 -292.108382)
		(width 0.0889)
		(layer "In6.Cu")
		(net "UPI_CPU0_CPU1_P2P2_DP<20>")
	)
	(segment
		(start 240.914936 -362.544868)
		(end 240.255044 -363.007148)
		(width 0.14732)
		(layer "In6.Cu")
		(net "UPI_CPU0_CPU1_P2P2_DP<20>")
	)
	(segment
		(start 107.20832 -275.8948)
		(end 107.520994 -275.8948)
		(width 0.0889)
		(layer "In6.Cu")
		(net "UPI_CPU0_CPU1_P2P2_DP<20>")
	)
	(segment
		(start 247.125998 -357.866442)
		(end 246.577866 -357.31831)
		(width 0.14732)
		(layer "In6.Cu")
		(net "UPI_CPU0_CPU1_P2P2_DP<20>")
	)
	(segment
		(start 303.772062 -317.403734)
		(end 303.561242 -317.814198)
		(width 0.14732)
		(layer "In6.Cu")
		(net "UPI_CPU0_CPU1_P2P2_DP<20>")
	)
	(segment
		(start 257.285744 -346.610432)
		(end 256.84988 -346.610432)
		(width 0.14732)
		(layer "In6.Cu")
		(net "UPI_CPU0_CPU1_P2P2_DP<20>")
	)
	(segment
		(start 232.932224 -365.80826)
		(end 232.126536 -365.9505)
		(width 0.14732)
		(layer "In6.Cu")
		(net "UPI_CPU0_CPU1_P2P2_DP<20>")
	)
	(segment
		(start 255.161796 -349.790512)
		(end 255.161796 -349.998284)
		(width 0.14732)
		(layer "In6.Cu")
		(net "UPI_CPU0_CPU1_P2P2_DP<20>")
	)
	(segment
		(start 73.377298 -351.761044)
		(end 73.377298 -335.214468)
		(width 0.14732)
		(layer "In6.Cu")
		(net "UPI_CPU0_CPU1_P2P2_DP<20>")
	)
	(segment
		(start 305.053238 -316.36589)
		(end 304.39741 -316.834774)
		(width 0.14732)
		(layer "In6.Cu")
		(net "UPI_CPU0_CPU1_P2P2_DP<20>")
	)
	(segment
		(start 255.161796 -349.998284)
		(end 254.743966 -350.416114)
		(width 0.14732)
		(layer "In6.Cu")
		(net "UPI_CPU0_CPU1_P2P2_DP<20>")
	)
	(segment
		(start 278.032464 -327.145142)
		(end 278.032464 -327.581006)
		(width 0.14732)
		(layer "In6.Cu")
		(net "UPI_CPU0_CPU1_P2P2_DP<20>")
	)
	(segment
		(start 234.11688 -364.541816)
		(end 234.041442 -364.970314)
		(width 0.14732)
		(layer "In6.Cu")
		(net "UPI_CPU0_CPU1_P2P2_DP<20>")
	)
	(segment
		(start 333.283052 -290.714176)
		(end 332.42885 -291.98443)
		(width 0.0889)
		(layer "In6.Cu")
		(net "UPI_CPU0_CPU1_P2P2_DP<20>")
	)
	(segment
		(start 107.150916 -275.952204)
		(end 107.20832 -275.8948)
		(width 0.0889)
		(layer "In6.Cu")
		(net "UPI_CPU0_CPU1_P2P2_DP<20>")
	)
	(segment
		(start 329.621134 -299.61713)
		(end 317.05931 -312.179208)
		(width 0.14732)
		(layer "In6.Cu")
		(net "UPI_CPU0_CPU1_P2P2_DP<20>")
	)
	(segment
		(start 108.556298 -283.229812)
		(end 108.556298 -283.21127)
		(width 0.0889)
		(layer "In6.Cu")
		(net "UPI_CPU0_CPU1_P2P2_DP<20>")
	)
	(segment
		(start 109.965744 -277.540974)
		(end 109.965744 -277.512526)
		(width 0.0889)
		(layer "In6.Cu")
		(net "UPI_CPU0_CPU1_P2P2_DP<20>")
	)
	(segment
		(start 258.488688 -344.971624)
		(end 257.911346 -345.548966)
		(width 0.14732)
		(layer "In6.Cu")
		(net "UPI_CPU0_CPU1_P2P2_DP<20>")
	)
	(segment
		(start 256.84988 -346.610432)
		(end 256.272538 -347.187774)
		(width 0.14732)
		(layer "In6.Cu")
		(net "UPI_CPU0_CPU1_P2P2_DP<20>")
	)
	(segment
		(start 247.7516 -357.448612)
		(end 247.33377 -357.866442)
		(width 0.14732)
		(layer "In6.Cu")
		(net "UPI_CPU0_CPU1_P2P2_DP<20>")
	)
	(segment
		(start 257.911346 -345.98483)
		(end 258.439412 -346.512896)
		(width 0.14732)
		(layer "In6.Cu")
		(net "UPI_CPU0_CPU1_P2P2_DP<20>")
	)
	(segment
		(start 306.024026 -315.672216)
		(end 305.58867 -315.983366)
		(width 0.14732)
		(layer "In6.Cu")
		(net "UPI_CPU0_CPU1_P2P2_DP<20>")
	)
	(segment
		(start 249.322844 -355.308408)
		(end 248.905014 -355.726238)
		(width 0.14732)
		(layer "In6.Cu")
		(net "UPI_CPU0_CPU1_P2P2_DP<20>")
	)
	(segment
		(start 261.188962 -342.707214)
		(end 261.717028 -343.23528)
		(width 0.14732)
		(layer "In6.Cu")
		(net "UPI_CPU0_CPU1_P2P2_DP<20>")
	)
	(segment
		(start 233.288586 -366.057942)
		(end 232.932224 -365.80826)
		(width 0.14732)
		(layer "In6.Cu")
		(net "UPI_CPU0_CPU1_P2P2_DP<20>")
	)
	(segment
		(start 255.211072 -348.24924)
		(end 254.63373 -348.826582)
		(width 0.14732)
		(layer "In6.Cu")
		(net "UPI_CPU0_CPU1_P2P2_DP<20>")
	)
	(segment
		(start 104.96423 -292.088824)
		(end 104.96423 -291.642038)
		(width 0.0889)
		(layer "In6.Cu")
		(net "UPI_CPU0_CPU1_P2P2_DP<20>")
	)
	(segment
		(start 106.855006 -286.156146)
		(end 106.863896 -286.151066)
		(width 0.0889)
		(layer "In6.Cu")
		(net "UPI_CPU0_CPU1_P2P2_DP<20>")
	)
	(segment
		(start 305.58867 -315.983366)
		(end 305.38674 -315.949584)
		(width 0.14732)
		(layer "In6.Cu")
		(net "UPI_CPU0_CPU1_P2P2_DP<20>")
	)
	(segment
		(start 245.284498 -359.302558)
		(end 244.939058 -358.957118)
		(width 0.14732)
		(layer "In6.Cu")
		(net "UPI_CPU0_CPU1_P2P2_DP<20>")
	)
	(segment
		(start 107.332272 -276.218396)
		(end 107.324906 -276.214078)
		(width 0.0889)
		(layer "In6.Cu")
		(net "UPI_CPU0_CPU1_P2P2_DP<20>")
	)
	(segment
		(start 287.308798 -324.805548)
		(end 285.175198 -325.689214)
		(width 0.14732)
		(layer "In6.Cu")
		(net "UPI_CPU0_CPU1_P2P2_DP<20>")
	)
	(segment
		(start 261.188962 -342.27135)
		(end 261.188962 -342.707214)
		(width 0.14732)
		(layer "In6.Cu")
		(net "UPI_CPU0_CPU1_P2P2_DP<20>")
	)
	(segment
		(start 233.64952 -367.2586)
		(end 233.479086 -367.138966)
		(width 0.14732)
		(layer "In6.Cu")
		(net "UPI_CPU0_CPU1_P2P2_DP<20>")
	)
	(segment
		(start 81.127346 -364.23727)
		(end 76.726288 -359.836974)
		(width 0.14732)
		(layer "In6.Cu")
		(net "UPI_CPU0_CPU1_P2P2_DP<20>")
	)
	(segment
		(start 257.911346 -345.548966)
		(end 257.911346 -345.98483)
		(width 0.14732)
		(layer "In6.Cu")
		(net "UPI_CPU0_CPU1_P2P2_DP<20>")
	)
	(segment
		(start 238.875824 -363.793024)
		(end 238.839502 -363.998002)
		(width 0.14732)
		(layer "In6.Cu")
		(net "UPI_CPU0_CPU1_P2P2_DP<20>")
	)
	(segment
		(start 260.07822 -344.874088)
		(end 260.07822 -345.08186)
		(width 0.14732)
		(layer "In6.Cu")
		(net "UPI_CPU0_CPU1_P2P2_DP<20>")
	)
	(segment
		(start 240.255044 -363.007148)
		(end 240.050066 -362.970826)
		(width 0.14732)
		(layer "In6.Cu")
		(net "UPI_CPU0_CPU1_P2P2_DP<20>")
	)
	(segment
		(start 256.800604 -348.359476)
		(end 256.382774 -348.777306)
		(width 0.14732)
		(layer "In6.Cu")
		(net "UPI_CPU0_CPU1_P2P2_DP<20>")
	)
	(segment
		(start 97.942908 -305.989736)
		(end 97.962466 -305.97348)
		(width 0.14732)
		(layer "In6.Cu")
		(net "UPI_CPU0_CPU1_P2P2_DP<20>")
	)
	(segment
		(start 234.041442 -364.970314)
		(end 235.079032 -366.451896)
		(width 0.14732)
		(layer "In6.Cu")
		(net "UPI_CPU0_CPU1_P2P2_DP<20>")
	)
	(segment
		(start 262.202168 -341.694008)
		(end 261.766304 -341.694008)
		(width 0.14732)
		(layer "In6.Cu")
		(net "UPI_CPU0_CPU1_P2P2_DP<20>")
	)
	(segment
		(start 237.913672 -361.882944)
		(end 237.838234 -362.311442)
		(width 0.14732)
		(layer "In6.Cu")
		(net "UPI_CPU0_CPU1_P2P2_DP<20>")
	)
	(segment
		(start 105.736898 -288.111692)
		(end 105.736898 -288.09442)
		(width 0.0889)
		(layer "In6.Cu")
		(net "UPI_CPU0_CPU1_P2P2_DP<20>")
	)
	(segment
		(start 99.321874 -371.77345)
		(end 99.321874 -371.773704)
		(width 0.14732)
		(layer "In6.Cu")
		(net "UPI_CPU0_CPU1_P2P2_DP<20>")
	)
	(segment
		(start 105.00614 -292.463728)
		(end 105.006394 -292.463474)
		(width 0.14732)
		(layer "In6.Cu")
		(net "UPI_CPU0_CPU1_P2P2_DP<20>")
	)
	(segment
		(start 258.439412 -346.512896)
		(end 258.439412 -346.720668)
		(width 0.14732)
		(layer "In6.Cu")
		(net "UPI_CPU0_CPU1_P2P2_DP<20>")
	)
	(segment
		(start 108.556298 -281.600656)
		(end 108.556298 -281.583384)
		(width 0.0889)
		(layer "In6.Cu")
		(net "UPI_CPU0_CPU1_P2P2_DP<20>")
	)
	(segment
		(start 109.695488 -278.667972)
		(end 109.68736 -278.663146)
		(width 0.0889)
		(layer "In6.Cu")
		(net "UPI_CPU0_CPU1_P2P2_DP<20>")
	)
	(segment
		(start 235.215684 -364.14837)
		(end 234.898946 -364.09249)
		(width 0.14732)
		(layer "In6.Cu")
		(net "UPI_CPU0_CPU1_P2P2_DP<20>")
	)
	(segment
		(start 238.15167 -364.300262)
		(end 237.11408 -362.81868)
		(width 0.14732)
		(layer "In6.Cu")
		(net "UPI_CPU0_CPU1_P2P2_DP<20>")
	)
	(segment
		(start 254.63373 -348.826582)
		(end 254.63373 -349.262446)
		(width 0.14732)
		(layer "In6.Cu")
		(net "UPI_CPU0_CPU1_P2P2_DP<20>")
	)
	(segment
		(start 335.45145 -288.422334)
		(end 335.44256 -288.427414)
		(width 0.0889)
		(layer "In6.Cu")
		(net "UPI_CPU0_CPU1_P2P2_DP<20>")
	)
	(segment
		(start 305.38674 -315.949584)
		(end 305.08702 -316.163706)
		(width 0.14732)
		(layer "In6.Cu")
		(net "UPI_CPU0_CPU1_P2P2_DP<20>")
	)
	(segment
		(start 257.81381 -347.138498)
		(end 257.285744 -346.610432)
		(width 0.14732)
		(layer "In6.Cu")
		(net "UPI_CPU0_CPU1_P2P2_DP<20>")
	)
	(segment
		(start 234.898946 -364.092236)
		(end 234.787186 -364.072678)
		(width 0.14732)
		(layer "In6.Cu")
		(net "UPI_CPU0_CPU1_P2P2_DP<20>")
	)
	(segment
		(start 109.674406 -279.644856)
		(end 109.683296 -279.639776)
		(width 0.0889)
		(layer "In6.Cu")
		(net "UPI_CPU0_CPU1_P2P2_DP<20>")
	)
	(segment
		(start 81.084674 -319.825116)
		(end 97.942908 -305.989482)
		(width 0.14732)
		(layer "In6.Cu")
		(net "UPI_CPU0_CPU1_P2P2_DP<20>")
	)
	(segment
		(start 109.026198 -280.778204)
		(end 109.026198 -280.769568)
		(width 0.0889)
		(layer "In6.Cu")
		(net "UPI_CPU0_CPU1_P2P2_DP<20>")
	)
	(segment
		(start 108.26496 -283.714444)
		(end 108.27385 -283.709364)
		(width 0.0889)
		(layer "In6.Cu")
		(net "UPI_CPU0_CPU1_P2P2_DP<20>")
	)
	(segment
		(start 258.021582 -347.138498)
		(end 257.81381 -347.138498)
		(width 0.14732)
		(layer "In6.Cu")
		(net "UPI_CPU0_CPU1_P2P2_DP<20>")
	)
	(segment
		(start 212.311234 -371.020086)
		(end 199.05853 -368.683032)
		(width 0.14732)
		(layer "In6.Cu")
		(net "UPI_CPU0_CPU1_P2P2_DP<20>")
	)
	(segment
		(start 249.059192 -354.40112)
		(end 249.059192 -354.836984)
		(width 0.14732)
		(layer "In6.Cu")
		(net "UPI_CPU0_CPU1_P2P2_DP<20>")
	)
	(segment
		(start 258.439412 -346.720668)
		(end 258.021582 -347.138498)
		(width 0.14732)
		(layer "In6.Cu")
		(net "UPI_CPU0_CPU1_P2P2_DP<20>")
	)
	(segment
		(start 74.574146 -327.641966)
		(end 75.747372 -325.162418)
		(width 0.14732)
		(layer "In6.Cu")
		(net "UPI_CPU0_CPU1_P2P2_DP<20>")
	)
	(segment
		(start 262.82777 -341.068406)
		(end 263.355836 -341.596472)
		(width 0.14732)
		(layer "In6.Cu")
		(net "UPI_CPU0_CPU1_P2P2_DP<20>")
	)
	(segment
		(start 105.006394 -292.130988)
		(end 104.96423 -292.088824)
		(width 0.0889)
		(layer "In6.Cu")
		(net "UPI_CPU0_CPU1_P2P2_DP<20>")
	)
	(segment
		(start 310.068468 -314.401708)
		(end 309.23357 -314.401708)
		(width 0.14732)
		(layer "In6.Cu")
		(net "UPI_CPU0_CPU1_P2P2_DP<20>")
	)
	(segment
		(start 246.577866 -357.31831)
		(end 246.142002 -357.31831)
		(width 0.14732)
		(layer "In6.Cu")
		(net "UPI_CPU0_CPU1_P2P2_DP<20>")
	)
	(segment
		(start 105.73639 -290.869878)
		(end 105.73639 -289.646868)
		(width 0.0889)
		(layer "In6.Cu")
		(net "UPI_CPU0_CPU1_P2P2_DP<20>")
	)
	(segment
		(start 247.203468 -356.256844)
		(end 247.203468 -356.692708)
		(width 0.14732)
		(layer "In6.Cu")
		(net "UPI_CPU0_CPU1_P2P2_DP<20>")
	)
	(segment
		(start 109.026198 -282.42006)
		(end 109.026198 -282.405836)
		(width 0.0889)
		(layer "In6.Cu")
		(net "UPI_CPU0_CPU1_P2P2_DP<20>")
	)
	(segment
		(start 253.572264 -349.888048)
		(end 249.059192 -354.40112)
		(width 0.14732)
		(layer "In6.Cu")
		(net "UPI_CPU0_CPU1_P2P2_DP<20>")
	)
	(segment
		(start 105.924858 -287.77819)
		(end 105.930192 -287.775142)
		(width 0.0889)
		(layer "In6.Cu")
		(net "UPI_CPU0_CPU1_P2P2_DP<20>")
	)
	(segment
		(start 263.355836 -341.596472)
		(end 263.355836 -341.804244)
		(width 0.14732)
		(layer "In6.Cu")
		(net "UPI_CPU0_CPU1_P2P2_DP<20>")
	)
	(segment
		(start 285.175198 -325.689214)
		(end 279.488392 -325.689214)
		(width 0.14732)
		(layer "In6.Cu")
		(net "UPI_CPU0_CPU1_P2P2_DP<20>")
	)
	(segment
		(start 334.97266 -286.964882)
		(end 334.98155 -286.969962)
		(width 0.0889)
		(layer "In6.Cu")
		(net "UPI_CPU0_CPU1_P2P2_DP<20>")
	)
	(segment
		(start 108.279692 -276.222714)
		(end 108.273596 -276.219158)
		(width 0.0889)
		(layer "In6.Cu")
		(net "UPI_CPU0_CPU1_P2P2_DP<20>")
	)
	(segment
		(start 235.079032 -366.451896)
		(end 235.04271 -366.656874)
		(width 0.14732)
		(layer "In6.Cu")
		(net "UPI_CPU0_CPU1_P2P2_DP<20>")
	)
	(segment
		(start 335.085944 -288.757106)
		(end 334.776318 -289.220656)
		(width 0.0889)
		(layer "In6.Cu")
		(net "UPI_CPU0_CPU1_P2P2_DP<20>")
	)
	(segment
		(start 259.452618 -345.49969)
		(end 258.924552 -344.971624)
		(width 0.14732)
		(layer "In6.Cu")
		(net "UPI_CPU0_CPU1_P2P2_DP<20>")
	)
	(segment
		(start 105.006394 -292.463474)
		(end 105.006394 -292.153086)
		(width 0.14732)
		(layer "In6.Cu")
		(net "UPI_CPU0_CPU1_P2P2_DP<20>")
	)
	(segment
		(start 237.637574 -366.065054)
		(end 237.601252 -366.270032)
		(width 0.14732)
		(layer "In6.Cu")
		(net "UPI_CPU0_CPU1_P2P2_DP<20>")
	)
	(segment
		(start 332.42885 -291.98443)
		(end 332.35265 -292.09746)
		(width 0.0889)
		(layer "In6.Cu")
		(net "UPI_CPU0_CPU1_P2P2_DP<20>")
	)
	(segment
		(start 231.94772 -367.55832)
		(end 212.311234 -371.020086)
		(width 0.14732)
		(layer "In6.Cu")
		(net "UPI_CPU0_CPU1_P2P2_DP<20>")
	)
	(segment
		(start 254.743966 -350.416114)
		(end 254.536194 -350.416114)
		(width 0.14732)
		(layer "In6.Cu")
		(net "UPI_CPU0_CPU1_P2P2_DP<20>")
	)
	(segment
		(start 246.142002 -357.31831)
		(end 245.56466 -357.895652)
		(width 0.14732)
		(layer "In6.Cu")
		(net "UPI_CPU0_CPU1_P2P2_DP<20>")
	)
	(segment
		(start 309.23357 -314.401708)
		(end 309.08879 -314.256928)
		(width 0.14732)
		(layer "In6.Cu")
		(net "UPI_CPU0_CPU1_P2P2_DP<20>")
	)
	(segment
		(start 105.924096 -287.778698)
		(end 105.924858 -287.77819)
		(width 0.0889)
		(layer "In6.Cu")
		(net "UPI_CPU0_CPU1_P2P2_DP<20>")
	)
	(segment
		(start 254.008128 -349.888048)
		(end 253.572264 -349.888048)
		(width 0.14732)
		(layer "In6.Cu")
		(net "UPI_CPU0_CPU1_P2P2_DP<20>")
	)
	(segment
		(start 247.997726 -355.462586)
		(end 247.203468 -356.256844)
		(width 0.14732)
		(layer "In6.Cu")
		(net "UPI_CPU0_CPU1_P2P2_DP<20>")
	)
	(segment
		(start 73.377298 -335.214468)
		(end 73.873868 -330.175108)
		(width 0.14732)
		(layer "In6.Cu")
		(net "UPI_CPU0_CPU1_P2P2_DP<20>")
	)
	(segment
		(start 107.79506 -284.52826)
		(end 107.80395 -284.52318)
		(width 0.0889)
		(layer "In6.Cu")
		(net "UPI_CPU0_CPU1_P2P2_DP<20>")
	)
	(segment
		(start 314.040012 -312.179208)
		(end 313.170316 -312.53938)
		(width 0.14732)
		(layer "In6.Cu")
		(net "UPI_CPU0_CPU1_P2P2_DP<20>")
	)
	(segment
		(start 306.887626 -315.19749)
		(end 306.024026 -315.672216)
		(width 0.14732)
		(layer "In6.Cu")
		(net "UPI_CPU0_CPU1_P2P2_DP<20>")
	)
	(segment
		(start 238.583978 -361.413806)
		(end 237.913672 -361.882944)
		(width 0.14732)
		(layer "In6.Cu")
		(net "UPI_CPU0_CPU1_P2P2_DP<20>")
	)
	(segment
		(start 261.299198 -343.860882)
		(end 261.091426 -343.860882)
		(width 0.14732)
		(layer "In6.Cu")
		(net "UPI_CPU0_CPU1_P2P2_DP<20>")
	)
	(segment
		(start 304.39741 -316.834774)
		(end 303.772062 -317.403734)
		(width 0.14732)
		(layer "In6.Cu")
		(net "UPI_CPU0_CPU1_P2P2_DP<20>")
	)
	(segment
		(start 237.601252 -366.270032)
		(end 237.118398 -366.608614)
		(width 0.14732)
		(layer "In6.Cu")
		(net "UPI_CPU0_CPU1_P2P2_DP<20>")
	)
	(segment
		(start 255.646936 -348.24924)
		(end 255.211072 -348.24924)
		(width 0.14732)
		(layer "In6.Cu")
		(net "UPI_CPU0_CPU1_P2P2_DP<20>")
	)
	(segment
		(start 236.913166 -366.572292)
		(end 235.215684 -364.14837)
		(width 0.14732)
		(layer "In6.Cu")
		(net "UPI_CPU0_CPU1_P2P2_DP<20>")
	)
	(segment
		(start 247.203468 -356.692708)
		(end 247.7516 -357.24084)
		(width 0.14732)
		(layer "In6.Cu")
		(net "UPI_CPU0_CPU1_P2P2_DP<20>")
	)
	(segment
		(start 234.898946 -364.09249)
		(end 234.898946 -364.092236)
		(width 0.14732)
		(layer "In6.Cu")
		(net "UPI_CPU0_CPU1_P2P2_DP<20>")
	)
	(segment
		(start 262.938006 -342.222074)
		(end 262.730234 -342.222074)
		(width 0.14732)
		(layer "In6.Cu")
		(net "UPI_CPU0_CPU1_P2P2_DP<20>")
	)
	(segment
		(start 238.356648 -364.336584)
		(end 238.15167 -364.300262)
		(width 0.14732)
		(layer "In6.Cu")
		(net "UPI_CPU0_CPU1_P2P2_DP<20>")
	)
	(segment
		(start 159.042862 -375.73839)
		(end 126.039626 -375.73839)
		(width 0.14732)
		(layer "In6.Cu")
		(net "UPI_CPU0_CPU1_P2P2_DP<20>")
	)
	(segment
		(start 256.272538 -347.623638)
		(end 256.800604 -348.151704)
		(width 0.14732)
		(layer "In6.Cu")
		(net "UPI_CPU0_CPU1_P2P2_DP<20>")
	)
	(segment
		(start 245.9101 -358.676956)
		(end 245.9101 -358.884728)
		(width 0.14732)
		(layer "In6.Cu")
		(net "UPI_CPU0_CPU1_P2P2_DP<20>")
	)
	(segment
		(start 249.059192 -354.836984)
		(end 249.322844 -355.100636)
		(width 0.14732)
		(layer "In6.Cu")
		(net "UPI_CPU0_CPU1_P2P2_DP<20>")
	)
	(segment
		(start 313.170316 -312.53938)
		(end 312.18505 -313.524646)
		(width 0.14732)
		(layer "In6.Cu")
		(net "UPI_CPU0_CPU1_P2P2_DP<20>")
	)
	(segment
		(start 274.055078 -331.122528)
		(end 272.337784 -331.122528)
		(width 0.14732)
		(layer "In6.Cu")
		(net "UPI_CPU0_CPU1_P2P2_DP<20>")
	)
	(segment
		(start 106.676444 -286.490918)
		(end 106.676444 -286.475424)
		(width 0.0889)
		(layer "In6.Cu")
		(net "UPI_CPU0_CPU1_P2P2_DP<20>")
	)
	(segment
		(start 334.690212 -286.456882)
		(end 334.690212 -286.48533)
		(width 0.0889)
		(layer "In6.Cu")
		(net "UPI_CPU0_CPU1_P2P2_DP<20>")
	)
	(segment
		(start 244.503194 -358.957118)
		(end 240.914936 -362.544868)
		(width 0.14732)
		(layer "In6.Cu")
		(net "UPI_CPU0_CPU1_P2P2_DP<20>")
	)
	(segment
		(start 106.38536 -286.969962)
		(end 106.39425 -286.964882)
		(width 0.0889)
		(layer "In6.Cu")
		(net "UPI_CPU0_CPU1_P2P2_DP<20>")
	)
	(segment
		(start 261.766304 -341.694008)
		(end 261.188962 -342.27135)
		(width 0.14732)
		(layer "In6.Cu")
		(net "UPI_CPU0_CPU1_P2P2_DP<20>")
	)
	(segment
		(start 261.091426 -343.860882)
		(end 260.56336 -343.332816)
		(width 0.14732)
		(layer "In6.Cu")
		(net "UPI_CPU0_CPU1_P2P2_DP<20>")
	)
	(segment
		(start 232.067354 -367.387886)
		(end 231.94772 -367.55832)
		(width 0.14732)
		(layer "In6.Cu")
		(net "UPI_CPU0_CPU1_P2P2_DP<20>")
	)
	(segment
		(start 256.800604 -348.151704)
		(end 256.800604 -348.359476)
		(width 0.14732)
		(layer "In6.Cu")
		(net "UPI_CPU0_CPU1_P2P2_DP<20>")
	)
	(segment
		(start 247.33377 -357.866442)
		(end 247.125998 -357.866442)
		(width 0.14732)
		(layer "In6.Cu")
		(net "UPI_CPU0_CPU1_P2P2_DP<20>")
	)
	(segment
		(start 259.66039 -345.49969)
		(end 259.452618 -345.49969)
		(width 0.14732)
		(layer "In6.Cu")
		(net "UPI_CPU0_CPU1_P2P2_DP<20>")
	)
	(segment
		(start 107.80395 -284.52318)
		(end 107.810046 -284.519624)
		(width 0.0889)
		(layer "In6.Cu")
		(net "UPI_CPU0_CPU1_P2P2_DP<20>")
	)
	(segment
		(start 336.195162 -286.475424)
		(end 335.882488 -286.475424)
		(width 0.0889)
		(layer "In6.Cu")
		(net "UPI_CPU0_CPU1_P2P2_DP<20>")
	)
	(segment
		(start 279.488392 -325.689214)
		(end 278.90089 -326.276716)
		(width 0.14732)
		(layer "In6.Cu")
		(net "UPI_CPU0_CPU1_P2P2_DP<20>")
	)
	(segment
		(start 277.406862 -328.206608)
		(end 276.970998 -328.206608)
		(width 0.14732)
		(layer "In6.Cu")
		(net "UPI_CPU0_CPU1_P2P2_DP<20>")
	)
	(segment
		(start 331.572616 -293.184834)
		(end 329.621134 -299.61713)
		(width 0.14732)
		(layer "In6.Cu")
		(net "UPI_CPU0_CPU1_P2P2_DP<20>")
	)
	(segment
		(start 335.882488 -286.475424)
		(end 335.81721 -286.410146)
		(width 0.0889)
		(layer "In6.Cu")
		(net "UPI_CPU0_CPU1_P2P2_DP<20>")
	)
	(segment
		(start 278.435308 -326.742298)
		(end 278.032464 -327.145142)
		(width 0.14732)
		(layer "In6.Cu")
		(net "UPI_CPU0_CPU1_P2P2_DP<20>")
	)
	(segment
		(start 260.07822 -345.08186)
		(end 259.66039 -345.49969)
		(width 0.14732)
		(layer "In6.Cu")
		(net "UPI_CPU0_CPU1_P2P2_DP<20>")
	)
	(segment
		(start 311.08396 -313.98083)
		(end 310.068468 -314.401708)
		(width 0.14732)
		(layer "In6.Cu")
		(net "UPI_CPU0_CPU1_P2P2_DP<20>")
	)
	(segment
		(start 104.96423 -291.642038)
		(end 105.73639 -290.869878)
		(width 0.0889)
		(layer "In6.Cu")
		(net "UPI_CPU0_CPU1_P2P2_DP<20>")
	)
	(segment
		(start 278.032464 -327.581006)
		(end 278.243284 -327.791826)
		(width 0.14732)
		(layer "In6.Cu")
		(net "UPI_CPU0_CPU1_P2P2_DP<20>")
	)
	(segment
		(start 232.126536 -365.9505)
		(end 231.876854 -366.306862)
		(width 0.14732)
		(layer "In6.Cu")
		(net "UPI_CPU0_CPU1_P2P2_DP<20>")
	)
	(segment
		(start 309.08879 -314.256928)
		(end 308.72049 -314.256928)
		(width 0.14732)
		(layer "In6.Cu")
		(net "UPI_CPU0_CPU1_P2P2_DP<20>")
	)
	(segment
		(start 103.28021 -299.65396)
		(end 105.00614 -297.326812)
		(width 0.14732)
		(layer "In6.Cu")
		(net "UPI_CPU0_CPU1_P2P2_DP<20>")
	)
	(segment
		(start 108.273596 -276.219158)
		(end 108.258864 -276.210522)
		(width 0.0889)
		(layer "In6.Cu")
		(net "UPI_CPU0_CPU1_P2P2_DP<20>")
	)
	(segment
		(start 254.536194 -350.416114)
		(end 254.008128 -349.888048)
		(width 0.14732)
		(layer "In6.Cu")
		(net "UPI_CPU0_CPU1_P2P2_DP<20>")
	)
	(segment
		(start 248.43359 -355.462586)
		(end 247.997726 -355.462586)
		(width 0.14732)
		(layer "In6.Cu")
		(net "UPI_CPU0_CPU1_P2P2_DP<20>")
	)
	(segment
		(start 109.683296 -279.639776)
		(end 109.687106 -279.63749)
		(width 0.0889)
		(layer "In6.Cu")
		(net "UPI_CPU0_CPU1_P2P2_DP<20>")
	)
	(segment
		(start 296.992548 -324.805548)
		(end 287.308798 -324.805548)
		(width 0.14732)
		(layer "In6.Cu")
		(net "UPI_CPU0_CPU1_P2P2_DP<20>")
	)
	(segment
		(start 240.050066 -362.970826)
		(end 239.012476 -361.489244)
		(width 0.14732)
		(layer "In6.Cu")
		(net "UPI_CPU0_CPU1_P2P2_DP<20>")
	)
	(segment
		(start 276.970998 -328.206608)
		(end 274.055078 -331.122528)
		(width 0.14732)
		(layer "In6.Cu")
		(net "UPI_CPU0_CPU1_P2P2_DP<20>")
	)
	(segment
		(start 278.243284 -327.999598)
		(end 277.825454 -328.417428)
		(width 0.14732)
		(layer "In6.Cu")
		(net "UPI_CPU0_CPU1_P2P2_DP<20>")
	)
	(segment
		(start 335.335372 -288.507932)
		(end 335.085944 -288.757106)
		(width 0.0889)
		(layer "In6.Cu")
		(net "UPI_CPU0_CPU1_P2P2_DP<20>")
	)
	(segment
		(start 109.683296 -278.66086)
		(end 109.674406 -278.65578)
		(width 0.0889)
		(layer "In6.Cu")
		(net "UPI_CPU0_CPU1_P2P2_DP<20>")
	)
	(segment
		(start 235.939838 -363.640878)
		(end 237.637574 -366.065054)
		(width 0.14732)
		(layer "In6.Cu")
		(net "UPI_CPU0_CPU1_P2P2_DP<20>")
	)
	(segment
		(start 261.717028 -343.443052)
		(end 261.299198 -343.860882)
		(width 0.14732)
		(layer "In6.Cu")
		(net "UPI_CPU0_CPU1_P2P2_DP<20>")
	)
	(segment
		(start 335.160112 -287.28924)
		(end 335.160112 -287.299146)
		(width 0.0889)
		(layer "In6.Cu")
		(net "UPI_CPU0_CPU1_P2P2_DP<20>")
	)
	(segment
		(start 76.726288 -359.836974)
		(end 73.377298 -351.761044)
		(width 0.14732)
		(layer "In6.Cu")
		(net "UPI_CPU0_CPU1_P2P2_DP<20>")
	)
	(segment
		(start 108.556298 -276.717252)
		(end 108.556298 -276.708616)
		(width 0.0889)
		(layer "In6.Cu")
		(net "UPI_CPU0_CPU1_P2P2_DP<20>")
	)
	(segment
		(start 247.7516 -357.24084)
		(end 247.7516 -357.448612)
		(width 0.14732)
		(layer "In6.Cu")
		(net "UPI_CPU0_CPU1_P2P2_DP<20>")
	)
	(segment
		(start 231.876854 -366.306862)
		(end 232.067354 -367.387886)
		(width 0.14732)
		(layer "In6.Cu")
		(net "UPI_CPU0_CPU1_P2P2_DP<20>")
	)
	(segment
		(start 237.838234 -362.311442)
		(end 238.875824 -363.793024)
		(width 0.14732)
		(layer "In6.Cu")
		(net "UPI_CPU0_CPU1_P2P2_DP<20>")
	)
	(segment
		(start 109.495844 -279.982676)
		(end 109.495844 -279.964134)
		(width 0.0889)
		(layer "In6.Cu")
		(net "UPI_CPU0_CPU1_P2P2_DP<20>")
	)
	(segment
		(start 236.01553 -363.212634)
		(end 235.939838 -363.640878)
		(width 0.14732)
		(layer "In6.Cu")
		(net "UPI_CPU0_CPU1_P2P2_DP<20>")
	)
	(segment
		(start 237.118398 -366.608614)
		(end 236.913166 -366.572292)
		(width 0.14732)
		(layer "In6.Cu")
		(net "UPI_CPU0_CPU1_P2P2_DP<20>")
	)
	(segment
		(start 278.696166 -326.276716)
		(end 278.435308 -326.537574)
		(width 0.14732)
		(layer "In6.Cu")
		(net "UPI_CPU0_CPU1_P2P2_DP<20>")
	)
	(segment
		(start 263.355836 -341.804244)
		(end 262.938006 -342.222074)
		(width 0.14732)
		(layer "In6.Cu")
		(net "UPI_CPU0_CPU1_P2P2_DP<20>")
	)
	(segment
		(start 308.57571 -314.401708)
		(end 307.683408 -314.401708)
		(width 0.14732)
		(layer "In6.Cu")
		(net "UPI_CPU0_CPU1_P2P2_DP<20>")
	)
	(segment
		(start 245.9101 -358.884728)
		(end 245.49227 -359.302558)
		(width 0.14732)
		(layer "In6.Cu")
		(net "UPI_CPU0_CPU1_P2P2_DP<20>")
	)
	(segment
		(start 278.435308 -326.537574)
		(end 278.435308 -326.742298)
		(width 0.14732)
		(layer "In6.Cu")
		(net "UPI_CPU0_CPU1_P2P2_DP<20>")
	)
	(segment
		(start 244.939058 -358.957118)
		(end 244.503194 -358.957118)
		(width 0.14732)
		(layer "In6.Cu")
		(net "UPI_CPU0_CPU1_P2P2_DP<20>")
	)
	(segment
		(start 277.617682 -328.417428)
		(end 277.406862 -328.206608)
		(width 0.14732)
		(layer "In6.Cu")
		(net "UPI_CPU0_CPU1_P2P2_DP<20>")
	)
	(segment
		(start 105.00614 -297.326812)
		(end 105.00614 -292.463728)
		(width 0.14732)
		(layer "In6.Cu")
		(net "UPI_CPU0_CPU1_P2P2_DP<20>")
	)
	(segment
		(start 108.749592 -281.919934)
		(end 108.743496 -281.916378)
		(width 0.0889)
		(layer "In6.Cu")
		(net "UPI_CPU0_CPU1_P2P2_DP<20>")
	)
	(segment
		(start 107.146598 -285.675578)
		(end 107.146598 -285.652718)
		(width 0.0889)
		(layer "In6.Cu")
		(net "UPI_CPU0_CPU1_P2P2_DP<20>")
	)
	(segment
		(start 126.039626 -375.73839)
		(end 99.321874 -371.77345)
		(width 0.14732)
		(layer "In6.Cu")
		(net "UPI_CPU0_CPU1_P2P2_DP<20>")
	)
	(segment
		(start 259.550154 -344.346022)
		(end 260.07822 -344.874088)
		(width 0.14732)
		(layer "In6.Cu")
		(net "UPI_CPU0_CPU1_P2P2_DP<20>")
	)
	(segment
		(start 261.717028 -343.23528)
		(end 261.717028 -343.443052)
		(width 0.14732)
		(layer "In6.Cu")
		(net "UPI_CPU0_CPU1_P2P2_DP<20>")
	)
	(segment
		(start 272.337784 -331.122528)
		(end 262.82777 -340.632542)
		(width 0.14732)
		(layer "In6.Cu")
		(net "UPI_CPU0_CPU1_P2P2_DP<20>")
	)
	(segment
		(start 105.006394 -292.153086)
		(end 105.006394 -292.130988)
		(width 0.0889)
		(layer "In6.Cu")
		(net "UPI_CPU0_CPU1_P2P2_DP<20>")
	)
	(segment
		(start 109.687106 -279.63749)
		(end 109.695488 -279.632664)
		(width 0.0889)
		(layer "In6.Cu")
		(net "UPI_CPU0_CPU1_P2P2_DP<20>")
	)
	(segment
		(start 248.905014 -355.726238)
		(end 248.697242 -355.726238)
		(width 0.14732)
		(layer "In6.Cu")
		(net "UPI_CPU0_CPU1_P2P2_DP<20>")
	)
	(segment
		(start 303.426622 -318.961516)
		(end 302.400462 -321.627246)
		(width 0.14732)
		(layer "In6.Cu")
		(net "UPI_CPU0_CPU1_P2P2_DP<20>")
	)
	(segment
		(start 278.90089 -326.276716)
		(end 278.696166 -326.276716)
		(width 0.14732)
		(layer "In6.Cu")
		(net "UPI_CPU0_CPU1_P2P2_DP<20>")
	)
	(segment
		(start 238.839502 -363.998002)
		(end 238.356648 -364.336584)
		(width 0.14732)
		(layer "In6.Cu")
		(net "UPI_CPU0_CPU1_P2P2_DP<20>")
	)
	(segment
		(start 245.56466 -358.331516)
		(end 245.9101 -358.676956)
		(width 0.14732)
		(layer "In6.Cu")
		(net "UPI_CPU0_CPU1_P2P2_DP<20>")
	)
	(segment
		(start 262.82777 -340.632542)
		(end 262.82777 -341.068406)
		(width 0.14732)
		(layer "In6.Cu")
		(net "UPI_CPU0_CPU1_P2P2_DP<20>")
	)
	(segment
		(start 317.05931 -312.179208)
		(end 314.040012 -312.179208)
		(width 0.14732)
		(layer "In6.Cu")
		(net "UPI_CPU0_CPU1_P2P2_DP<20>")
	)
	(segment
		(start 256.175002 -348.777306)
		(end 255.646936 -348.24924)
		(width 0.14732)
		(layer "In6.Cu")
		(net "UPI_CPU0_CPU1_P2P2_DP<20>")
	)
	(segment
		(start 97.962466 -305.97348)
		(end 103.28021 -299.65396)
		(width 0.14732)
		(layer "In6.Cu")
		(net "UPI_CPU0_CPU1_P2P2_DP<20>")
	)
	(segment
		(start 332.282292 -292.12667)
		(end 331.572616 -293.184834)
		(width 0.14732)
		(layer "In6.Cu")
		(net "UPI_CPU0_CPU1_P2P2_DP<20>")
	)
	(segment
		(start 107.333796 -285.336996)
		(end 107.345988 -285.329884)
		(width 0.0889)
		(layer "In6.Cu")
		(net "UPI_CPU0_CPU1_P2P2_DP<20>")
	)
	(segment
		(start 311.084722 -313.980576)
		(end 311.08396 -313.98083)
		(width 0.14732)
		(layer "In6.Cu")
		(net "UPI_CPU0_CPU1_P2P2_DP<20>")
	)
	(arc
		(start 106.676444 -286.475424)
		(mid 106.724123 -286.292524)
		(end 106.855006 -286.156146)
		(width 0.0889)
		(layer "In6.Cu")
		(net "UPI_CPU0_CPU1_P2P2_DP<20>")
	)
	(arc
		(start 335.630012 -288.112454)
		(mid 335.580116 -288.290101)
		(end 335.45145 -288.422334)
		(width 0.0889)
		(layer "In6.Cu")
		(net "UPI_CPU0_CPU1_P2P2_DP<20>")
	)
	(arc
		(start 108.749592 -281.264106)
		(mid 108.952179 -281.057755)
		(end 109.026198 -280.778204)
		(width 0.0889)
		(layer "In6.Cu")
		(net "UPI_CPU0_CPU1_P2P2_DP<20>")
	)
	(arc
		(start 107.616498 -284.847538)
		(mid 107.664177 -284.664638)
		(end 107.79506 -284.52826)
		(width 0.0889)
		(layer "In6.Cu")
		(net "UPI_CPU0_CPU1_P2P2_DP<20>")
	)
	(arc
		(start 107.708192 -276.219158)
		(mid 107.520994 -276.269301)
		(end 107.333796 -276.219158)
		(width 0.0889)
		(layer "In6.Cu")
		(net "UPI_CPU0_CPU1_P2P2_DP<20>")
	)
	(arc
		(start 105.924096 -288.427414)
		(mid 105.789163 -288.29406)
		(end 105.736898 -288.111692)
		(width 0.0889)
		(layer "In6.Cu")
		(net "UPI_CPU0_CPU1_P2P2_DP<20>")
	)
	(arc
		(start 107.810046 -284.519624)
		(mid 108.012459 -284.313211)
		(end 108.086398 -284.033722)
		(width 0.0889)
		(layer "In6.Cu")
		(net "UPI_CPU0_CPU1_P2P2_DP<20>")
	)
	(arc
		(start 334.690212 -286.48533)
		(mid 334.768323 -286.762279)
		(end 334.97266 -286.964882)
		(width 0.0889)
		(layer "In6.Cu")
		(net "UPI_CPU0_CPU1_P2P2_DP<20>")
	)
	(arc
		(start 109.213396 -280.453846)
		(mid 109.415682 -280.254865)
		(end 109.495844 -279.982676)
		(width 0.0889)
		(layer "In6.Cu")
		(net "UPI_CPU0_CPU1_P2P2_DP<20>")
	)
	(arc
		(start 334.98155 -286.969962)
		(mid 335.112464 -287.106322)
		(end 335.160112 -287.28924)
		(width 0.0889)
		(layer "In6.Cu")
		(net "UPI_CPU0_CPU1_P2P2_DP<20>")
	)
	(arc
		(start 108.743496 -281.916378)
		(mid 108.608563 -281.783024)
		(end 108.556298 -281.600656)
		(width 0.0889)
		(layer "In6.Cu")
		(net "UPI_CPU0_CPU1_P2P2_DP<20>")
	)
	(arc
		(start 109.496098 -278.32431)
		(mid 109.546569 -278.148302)
		(end 109.674406 -278.017224)
		(width 0.0889)
		(layer "In6.Cu")
		(net "UPI_CPU0_CPU1_P2P2_DP<20>")
	)
	(arc
		(start 109.683296 -277.032974)
		(mid 109.400594 -276.957198)
		(end 109.117892 -277.032974)
		(width 0.0889)
		(layer "In6.Cu")
		(net "UPI_CPU0_CPU1_P2P2_DP<20>")
	)
	(arc
		(start 109.674406 -278.65578)
		(mid 109.545117 -278.522294)
		(end 109.495844 -278.343106)
		(width 0.0889)
		(layer "In6.Cu")
		(net "UPI_CPU0_CPU1_P2P2_DP<20>")
	)
	(arc
		(start 109.026198 -280.769568)
		(mid 109.078468 -280.587203)
		(end 109.213396 -280.453846)
		(width 0.0889)
		(layer "In6.Cu")
		(net "UPI_CPU0_CPU1_P2P2_DP<20>")
	)
	(arc
		(start 105.921048 -289.446462)
		(mid 106.095349 -289.307532)
		(end 106.206798 -289.114484)
		(width 0.0889)
		(layer "In6.Cu")
		(net "UPI_CPU0_CPU1_P2P2_DP<20>")
	)
	(arc
		(start 105.736644 -289.64636)
		(mid 105.811715 -289.530618)
		(end 105.921048 -289.446462)
		(width 0.0889)
		(layer "In6.Cu")
		(net "UPI_CPU0_CPU1_P2P2_DP<20>")
	)
	(arc
		(start 106.206798 -287.28924)
		(mid 106.254477 -287.10634)
		(end 106.38536 -286.969962)
		(width 0.0889)
		(layer "In6.Cu")
		(net "UPI_CPU0_CPU1_P2P2_DP<20>")
	)
	(arc
		(start 109.695488 -279.632664)
		(mid 109.965944 -279.150318)
		(end 109.695488 -278.667972)
		(width 0.0889)
		(layer "In6.Cu")
		(net "UPI_CPU0_CPU1_P2P2_DP<20>")
	)
	(arc
		(start 107.345988 -285.329884)
		(mid 107.544216 -285.124036)
		(end 107.616498 -284.847538)
		(width 0.0889)
		(layer "In6.Cu")
		(net "UPI_CPU0_CPU1_P2P2_DP<20>")
	)
	(arc
		(start 105.736898 -288.09442)
		(mid 105.789168 -287.912055)
		(end 105.924096 -287.778698)
		(width 0.0889)
		(layer "In6.Cu")
		(net "UPI_CPU0_CPU1_P2P2_DP<20>")
	)
	(arc
		(start 335.160112 -287.299146)
		(mid 335.238223 -287.576095)
		(end 335.44256 -287.778698)
		(width 0.0889)
		(layer "In6.Cu")
		(net "UPI_CPU0_CPU1_P2P2_DP<20>")
	)
	(arc
		(start 335.630012 -288.096452)
		(mid 335.6301 -288.104453)
		(end 335.630012 -288.112454)
		(width 0.0889)
		(layer "In6.Cu")
		(net "UPI_CPU0_CPU1_P2P2_DP<20>")
	)
	(arc
		(start 106.39425 -286.964882)
		(mid 106.597073 -286.764651)
		(end 106.676444 -286.490918)
		(width 0.0889)
		(layer "In6.Cu")
		(net "UPI_CPU0_CPU1_P2P2_DP<20>")
	)
	(arc
		(start 335.363312 -288.482532)
		(mid 335.349041 -288.494901)
		(end 335.335372 -288.507932)
		(width 0.0889)
		(layer "In6.Cu")
		(net "UPI_CPU0_CPU1_P2P2_DP<20>")
	)
	(arc
		(start 108.743496 -282.895548)
		(mid 108.946977 -282.694744)
		(end 109.026198 -282.42006)
		(width 0.0889)
		(layer "In6.Cu")
		(net "UPI_CPU0_CPU1_P2P2_DP<20>")
	)
	(arc
		(start 109.495844 -279.964134)
		(mid 109.543523 -279.781234)
		(end 109.674406 -279.644856)
		(width 0.0889)
		(layer "In6.Cu")
		(net "UPI_CPU0_CPU1_P2P2_DP<20>")
	)
	(arc
		(start 109.495844 -278.343106)
		(mid 109.495854 -278.333706)
		(end 109.496098 -278.32431)
		(width 0.0889)
		(layer "In6.Cu")
		(net "UPI_CPU0_CPU1_P2P2_DP<20>")
	)
	(arc
		(start 109.965744 -277.512526)
		(mid 109.887633 -277.235577)
		(end 109.683296 -277.032974)
		(width 0.0889)
		(layer "In6.Cu")
		(net "UPI_CPU0_CPU1_P2P2_DP<20>")
	)
	(arc
		(start 106.206798 -288.902902)
		(mid 106.127579 -288.628217)
		(end 105.924096 -288.427414)
		(width 0.0889)
		(layer "In6.Cu")
		(net "UPI_CPU0_CPU1_P2P2_DP<20>")
	)
	(arc
		(start 335.44256 -288.427414)
		(mid 335.401755 -288.453276)
		(end 335.363312 -288.482532)
		(width 0.0889)
		(layer "In6.Cu")
		(net "UPI_CPU0_CPU1_P2P2_DP<20>")
	)
	(arc
		(start 108.258864 -276.210522)
		(mid 107.982389 -276.143202)
		(end 107.708192 -276.219158)
		(width 0.0889)
		(layer "In6.Cu")
		(net "UPI_CPU0_CPU1_P2P2_DP<20>")
	)
	(arc
		(start 106.863896 -286.151066)
		(mid 107.067377 -285.950262)
		(end 107.146598 -285.675578)
		(width 0.0889)
		(layer "In6.Cu")
		(net "UPI_CPU0_CPU1_P2P2_DP<20>")
	)
	(arc
		(start 109.026198 -282.405836)
		(mid 108.952207 -282.12627)
		(end 108.749592 -281.919934)
		(width 0.0889)
		(layer "In6.Cu")
		(net "UPI_CPU0_CPU1_P2P2_DP<20>")
	)
	(arc
		(start 108.556298 -281.583384)
		(mid 108.608568 -281.401019)
		(end 108.743496 -281.267662)
		(width 0.0889)
		(layer "In6.Cu")
		(net "UPI_CPU0_CPU1_P2P2_DP<20>")
	)
	(arc
		(start 107.324906 -276.214078)
		(mid 107.209167 -276.102254)
		(end 107.150916 -275.952204)
		(width 0.0889)
		(layer "In6.Cu")
		(net "UPI_CPU0_CPU1_P2P2_DP<20>")
	)
	(arc
		(start 107.146598 -285.652718)
		(mid 107.198868 -285.470353)
		(end 107.333796 -285.336996)
		(width 0.0889)
		(layer "In6.Cu")
		(net "UPI_CPU0_CPU1_P2P2_DP<20>")
	)
	(arc
		(start 335.45145 -287.783778)
		(mid 335.580739 -287.917264)
		(end 335.630012 -288.096452)
		(width 0.0889)
		(layer "In6.Cu")
		(net "UPI_CPU0_CPU1_P2P2_DP<20>")
	)
	(arc
		(start 335.814416 -286.388556)
		(mid 335.721981 -286.155755)
		(end 335.538064 -285.985712)
		(width 0.0889)
		(layer "In6.Cu")
		(net "UPI_CPU0_CPU1_P2P2_DP<20>")
	)
	(arc
		(start 335.538064 -285.985712)
		(mid 335.255362 -285.90997)
		(end 334.97266 -285.985712)
		(width 0.0889)
		(layer "In6.Cu")
		(net "UPI_CPU0_CPU1_P2P2_DP<20>")
	)
	(arc
		(start 105.930192 -287.775142)
		(mid 106.132779 -287.568791)
		(end 106.206798 -287.28924)
		(width 0.0889)
		(layer "In6.Cu")
		(net "UPI_CPU0_CPU1_P2P2_DP<20>")
	)
	(arc
		(start 108.27385 -283.709364)
		(mid 108.478185 -283.506759)
		(end 108.556298 -283.229812)
		(width 0.0889)
		(layer "In6.Cu")
		(net "UPI_CPU0_CPU1_P2P2_DP<20>")
	)
	(arc
		(start 108.086398 -284.033722)
		(mid 108.134077 -283.850822)
		(end 108.26496 -283.714444)
		(width 0.0889)
		(layer "In6.Cu")
		(net "UPI_CPU0_CPU1_P2P2_DP<20>")
	)
	(arc
		(start 109.683296 -278.012144)
		(mid 109.885582 -277.813163)
		(end 109.965744 -277.540974)
		(width 0.0889)
		(layer "In6.Cu")
		(net "UPI_CPU0_CPU1_P2P2_DP<20>")
	)
	(arc
		(start 109.117892 -277.032974)
		(mid 108.930694 -277.083117)
		(end 108.743496 -277.032974)
		(width 0.0889)
		(layer "In6.Cu")
		(net "UPI_CPU0_CPU1_P2P2_DP<20>")
	)
	(arc
		(start 108.743496 -277.032974)
		(mid 108.608563 -276.89962)
		(end 108.556298 -276.717252)
		(width 0.0889)
		(layer "In6.Cu")
		(net "UPI_CPU0_CPU1_P2P2_DP<20>")
	)
	(arc
		(start 108.556298 -276.708616)
		(mid 108.482307 -276.42905)
		(end 108.279692 -276.222714)
		(width 0.0889)
		(layer "In6.Cu")
		(net "UPI_CPU0_CPU1_P2P2_DP<20>")
	)
	(arc
		(start 334.97266 -285.985712)
		(mid 334.770374 -286.184693)
		(end 334.690212 -286.456882)
		(width 0.0889)
		(layer "In6.Cu")
		(net "UPI_CPU0_CPU1_P2P2_DP<20>")
	)
	(arc
		(start 108.556298 -283.21127)
		(mid 108.608568 -283.028905)
		(end 108.743496 -282.895548)
		(width 0.0889)
		(layer "In6.Cu")
		(net "UPI_CPU0_CPU1_P2P2_DP<20>")
	)
	(arc
		(start 335.81721 -286.410146)
		(mid 335.815918 -286.399337)
		(end 335.814416 -286.388556)
		(width 0.0889)
		(layer "In6.Cu")
		(net "UPI_CPU0_CPU1_P2P2_DP<20>")
	)
	(segment
		(start 353.581716 -280.242264)
		(end 353.581716 -280.77795)
		(width 0.13208)
		(layer "F.Cu")
		(net "UPI_CPU0_CPU1_P2P2_DP<1>")
	)
	(segment
		(start 353.581716 -280.77795)
		(end 353.581462 -280.778204)
		(width 0.13208)
		(layer "F.Cu")
		(net "UPI_CPU0_CPU1_P2P2_DP<1>")
	)
	(segment
		(start 86.845648 -281.869896)
		(end 86.845648 -282.405836)
		(width 0.13208)
		(layer "F.Cu")
		(net "UPI_CPU0_CPU1_P2P2_DP<1>")
	)
	(segment
		(start 84.392262 -290.302696)
		(end 84.85759 -289.837368)
		(width 0.0889)
		(layer "In6.Cu")
		(net "UPI_CPU0_CPU1_P2P2_DP<1>")
	)
	(segment
		(start 53.643276 -317.026036)
		(end 53.783738 -316.6872)
		(width 0.14732)
		(layer "In6.Cu")
		(net "UPI_CPU0_CPU1_P2P2_DP<1>")
	)
	(segment
		(start 53.783738 -316.6872)
		(end 53.783484 -316.6872)
		(width 0.14732)
		(layer "In6.Cu")
		(net "UPI_CPU0_CPU1_P2P2_DP<1>")
	)
	(segment
		(start 64.379094 -310.388508)
		(end 67.756278 -308.98973)
		(width 0.14732)
		(layer "In6.Cu")
		(net "UPI_CPU0_CPU1_P2P2_DP<1>")
	)
	(segment
		(start 54.057296 -316.383924)
		(end 55.825898 -315.651388)
		(width 0.14732)
		(layer "In6.Cu")
		(net "UPI_CPU0_CPU1_P2P2_DP<1>")
	)
	(segment
		(start 355.273864 -281.102562)
		(end 355.276658 -281.104086)
		(width 0.0889)
		(layer "In6.Cu")
		(net "UPI_CPU0_CPU1_P2P2_DP<1>")
	)
	(segment
		(start 353.894136 -280.778204)
		(end 353.959668 -280.712672)
		(width 0.0889)
		(layer "In6.Cu")
		(net "UPI_CPU0_CPU1_P2P2_DP<1>")
	)
	(segment
		(start 345.08821 -309.223918)
		(end 341.05723 -310.893714)
		(width 0.14732)
		(layer "In6.Cu")
		(net "UPI_CPU0_CPU1_P2P2_DP<1>")
	)
	(segment
		(start 355.086666 -288.917126)
		(end 355.086666 -289.078416)
		(width 0.0889)
		(layer "In6.Cu")
		(net "UPI_CPU0_CPU1_P2P2_DP<1>")
	)
	(segment
		(start 279.894792 -348.615762)
		(end 279.894792 -372.17096)
		(width 0.14732)
		(layer "In6.Cu")
		(net "UPI_CPU0_CPU1_P2P2_DP<1>")
	)
	(segment
		(start 355.086412 -280.756106)
		(end 355.086412 -280.778204)
		(width 0.0889)
		(layer "In6.Cu")
		(net "UPI_CPU0_CPU1_P2P2_DP<1>")
	)
	(segment
		(start 356.213918 -283.709364)
		(end 356.205028 -283.714444)
		(width 0.0889)
		(layer "In6.Cu")
		(net "UPI_CPU0_CPU1_P2P2_DP<1>")
	)
	(segment
		(start 87.220298 -282.417266)
		(end 87.220298 -282.397962)
		(width 0.0889)
		(layer "In6.Cu")
		(net "UPI_CPU0_CPU1_P2P2_DP<1>")
	)
	(segment
		(start 355.274118 -288.592768)
		(end 355.273102 -288.593276)
		(width 0.0889)
		(layer "In6.Cu")
		(net "UPI_CPU0_CPU1_P2P2_DP<1>")
	)
	(segment
		(start 355.273864 -287.613598)
		(end 355.275134 -287.61436)
		(width 0.0889)
		(layer "In6.Cu")
		(net "UPI_CPU0_CPU1_P2P2_DP<1>")
	)
	(segment
		(start 80.696562 -296.049446)
		(end 82.188558 -292.447472)
		(width 0.14732)
		(layer "In6.Cu")
		(net "UPI_CPU0_CPU1_P2P2_DP<1>")
	)
	(segment
		(start 126.746 -392.14171)
		(end 93.034866 -387.140958)
		(width 0.14732)
		(layer "In6.Cu")
		(net "UPI_CPU0_CPU1_P2P2_DP<1>")
	)
	(segment
		(start 353.581462 -280.778204)
		(end 353.894136 -280.778204)
		(width 0.0889)
		(layer "In6.Cu")
		(net "UPI_CPU0_CPU1_P2P2_DP<1>")
	)
	(segment
		(start 355.286056 -285.329884)
		(end 355.273864 -285.336996)
		(width 0.0889)
		(layer "In6.Cu")
		(net "UPI_CPU0_CPU1_P2P2_DP<1>")
	)
	(segment
		(start 353.882198 -294.725344)
		(end 353.924362 -294.767508)
		(width 0.0889)
		(layer "In6.Cu")
		(net "UPI_CPU0_CPU1_P2P2_DP<1>")
	)
	(segment
		(start 86.562692 -284.52318)
		(end 86.562946 -284.522926)
		(width 0.0889)
		(layer "In6.Cu")
		(net "UPI_CPU0_CPU1_P2P2_DP<1>")
	)
	(segment
		(start 353.924108 -294.914574)
		(end 353.924108 -299.138848)
		(width 0.14732)
		(layer "In6.Cu")
		(net "UPI_CPU0_CPU1_P2P2_DP<1>")
	)
	(segment
		(start 341.05723 -310.893714)
		(end 323.118734 -328.83221)
		(width 0.14732)
		(layer "In6.Cu")
		(net "UPI_CPU0_CPU1_P2P2_DP<1>")
	)
	(segment
		(start 355.735128 -281.911298)
		(end 355.744018 -281.916378)
		(width 0.0889)
		(layer "In6.Cu")
		(net "UPI_CPU0_CPU1_P2P2_DP<1>")
	)
	(segment
		(start 67.756278 -308.98973)
		(end 80.696562 -296.049446)
		(width 0.14732)
		(layer "In6.Cu")
		(net "UPI_CPU0_CPU1_P2P2_DP<1>")
	)
	(segment
		(start 84.31784 -290.31819)
		(end 84.333334 -290.302696)
		(width 0.0889)
		(layer "In6.Cu")
		(net "UPI_CPU0_CPU1_P2P2_DP<1>")
	)
	(segment
		(start 353.924362 -294.91432)
		(end 353.924108 -294.914574)
		(width 0.14732)
		(layer "In6.Cu")
		(net "UPI_CPU0_CPU1_P2P2_DP<1>")
	)
	(segment
		(start 53.783484 -316.6872)
		(end 53.804566 -316.636654)
		(width 0.14732)
		(layer "In6.Cu")
		(net "UPI_CPU0_CPU1_P2P2_DP<1>")
	)
	(segment
		(start 86.562946 -284.522926)
		(end 86.56193 -284.522418)
		(width 0.0889)
		(layer "In6.Cu")
		(net "UPI_CPU0_CPU1_P2P2_DP<1>")
	)
	(segment
		(start 56.592216 -334.991456)
		(end 54.673246 -332.737206)
		(width 0.14732)
		(layer "In6.Cu")
		(net "UPI_CPU0_CPU1_P2P2_DP<1>")
	)
	(segment
		(start 279.894792 -372.17096)
		(end 268.973554 -383.092198)
		(width 0.14732)
		(layer "In6.Cu")
		(net "UPI_CPU0_CPU1_P2P2_DP<1>")
	)
	(segment
		(start 355.750114 -284.519624)
		(end 355.744018 -284.52318)
		(width 0.0889)
		(layer "In6.Cu")
		(net "UPI_CPU0_CPU1_P2P2_DP<1>")
	)
	(segment
		(start 82.188558 -292.447472)
		(end 84.31784 -290.31819)
		(width 0.14732)
		(layer "In6.Cu")
		(net "UPI_CPU0_CPU1_P2P2_DP<1>")
	)
	(segment
		(start 354.238814 -280.288492)
		(end 354.253546 -280.279856)
		(width 0.0889)
		(layer "In6.Cu")
		(net "UPI_CPU0_CPU1_P2P2_DP<1>")
	)
	(segment
		(start 87.002112 -282.134818)
		(end 86.845648 -282.405836)
		(width 0.0889)
		(layer "In6.Cu")
		(net "UPI_CPU0_CPU1_P2P2_DP<1>")
	)
	(segment
		(start 58.564018 -313.821318)
		(end 59.54522 -312.84037)
		(width 0.14732)
		(layer "In6.Cu")
		(net "UPI_CPU0_CPU1_P2P2_DP<1>")
	)
	(segment
		(start 86.552024 -283.550614)
		(end 86.56066 -283.545788)
		(width 0.0889)
		(layer "In6.Cu")
		(net "UPI_CPU0_CPU1_P2P2_DP<1>")
	)
	(segment
		(start 355.556058 -290.846256)
		(end 353.882198 -292.520116)
		(width 0.0889)
		(layer "In6.Cu")
		(net "UPI_CPU0_CPU1_P2P2_DP<1>")
	)
	(segment
		(start 69.934582 -377.574048)
		(end 63.241428 -370.880894)
		(width 0.14732)
		(layer "In6.Cu")
		(net "UPI_CPU0_CPU1_P2P2_DP<1>")
	)
	(segment
		(start 355.286056 -286.95777)
		(end 355.273864 -286.964882)
		(width 0.0889)
		(layer "In6.Cu")
		(net "UPI_CPU0_CPU1_P2P2_DP<1>")
	)
	(segment
		(start 51.36388 -324.335902)
		(end 52.070508 -323.629274)
		(width 0.14732)
		(layer "In6.Cu")
		(net "UPI_CPU0_CPU1_P2P2_DP<1>")
	)
	(segment
		(start 355.276658 -281.104086)
		(end 355.27996 -281.106118)
		(width 0.0889)
		(layer "In6.Cu")
		(net "UPI_CPU0_CPU1_P2P2_DP<1>")
	)
	(segment
		(start 355.27234 -281.1018)
		(end 355.273864 -281.102562)
		(width 0.0889)
		(layer "In6.Cu")
		(net "UPI_CPU0_CPU1_P2P2_DP<1>")
	)
	(segment
		(start 355.270816 -289.277806)
		(end 355.270562 -289.27806)
		(width 0.0889)
		(layer "In6.Cu")
		(net "UPI_CPU0_CPU1_P2P2_DP<1>")
	)
	(segment
		(start 84.333334 -290.302696)
		(end 84.392262 -290.302696)
		(width 0.0889)
		(layer "In6.Cu")
		(net "UPI_CPU0_CPU1_P2P2_DP<1>")
	)
	(segment
		(start 86.56066 -283.545788)
		(end 86.571836 -283.53893)
		(width 0.0889)
		(layer "In6.Cu")
		(net "UPI_CPU0_CPU1_P2P2_DP<1>")
	)
	(segment
		(start 353.082098 -301.17161)
		(end 345.08821 -309.223918)
		(width 0.14732)
		(layer "In6.Cu")
		(net "UPI_CPU0_CPU1_P2P2_DP<1>")
	)
	(segment
		(start 355.264974 -281.097482)
		(end 355.27234 -281.1018)
		(width 0.0889)
		(layer "In6.Cu")
		(net "UPI_CPU0_CPU1_P2P2_DP<1>")
	)
	(segment
		(start 355.744018 -281.916378)
		(end 355.750114 -281.919934)
		(width 0.0889)
		(layer "In6.Cu")
		(net "UPI_CPU0_CPU1_P2P2_DP<1>")
	)
	(segment
		(start 355.556566 -286.467804)
		(end 355.556566 -286.475424)
		(width 0.0889)
		(layer "In6.Cu")
		(net "UPI_CPU0_CPU1_P2P2_DP<1>")
	)
	(segment
		(start 353.924362 -294.789606)
		(end 353.924362 -294.91432)
		(width 0.14732)
		(layer "In6.Cu")
		(net "UPI_CPU0_CPU1_P2P2_DP<1>")
	)
	(segment
		(start 355.275134 -287.61436)
		(end 355.286056 -287.62071)
		(width 0.0889)
		(layer "In6.Cu")
		(net "UPI_CPU0_CPU1_P2P2_DP<1>")
	)
	(segment
		(start 57.268618 -336.62239)
		(end 56.592216 -334.991456)
		(width 0.14732)
		(layer "In6.Cu")
		(net "UPI_CPU0_CPU1_P2P2_DP<1>")
	)
	(segment
		(start 285.138368 -343.372186)
		(end 279.894792 -348.615762)
		(width 0.14732)
		(layer "In6.Cu")
		(net "UPI_CPU0_CPU1_P2P2_DP<1>")
	)
	(segment
		(start 353.924362 -294.767508)
		(end 353.924362 -294.789606)
		(width 0.0889)
		(layer "In6.Cu")
		(net "UPI_CPU0_CPU1_P2P2_DP<1>")
	)
	(segment
		(start 355.556058 -289.610292)
		(end 355.556058 -290.846256)
		(width 0.0889)
		(layer "In6.Cu")
		(net "UPI_CPU0_CPU1_P2P2_DP<1>")
	)
	(segment
		(start 52.070508 -323.629274)
		(end 52.565554 -323.424296)
		(width 0.14732)
		(layer "In6.Cu")
		(net "UPI_CPU0_CPU1_P2P2_DP<1>")
	)
	(segment
		(start 353.882198 -292.520116)
		(end 353.882198 -294.725344)
		(width 0.0889)
		(layer "In6.Cu")
		(net "UPI_CPU0_CPU1_P2P2_DP<1>")
	)
	(segment
		(start 53.544216 -322.068444)
		(end 53.643276 -321.569588)
		(width 0.14732)
		(layer "In6.Cu")
		(net "UPI_CPU0_CPU1_P2P2_DP<1>")
	)
	(segment
		(start 86.750144 -283.232352)
		(end 86.750144 -283.219906)
		(width 0.0889)
		(layer "In6.Cu")
		(net "UPI_CPU0_CPU1_P2P2_DP<1>")
	)
	(segment
		(start 268.87297 -383.10058)
		(end 268.872716 -383.100834)
		(width 0.14732)
		(layer "In6.Cu")
		(net "UPI_CPU0_CPU1_P2P2_DP<1>")
	)
	(segment
		(start 54.673246 -332.737206)
		(end 51.36388 -329.42784)
		(width 0.14732)
		(layer "In6.Cu")
		(net "UPI_CPU0_CPU1_P2P2_DP<1>")
	)
	(segment
		(start 356.496366 -283.201364)
		(end 356.496366 -283.229812)
		(width 0.0889)
		(layer "In6.Cu")
		(net "UPI_CPU0_CPU1_P2P2_DP<1>")
	)
	(segment
		(start 355.273102 -288.593276)
		(end 355.265228 -288.597848)
		(width 0.0889)
		(layer "In6.Cu")
		(net "UPI_CPU0_CPU1_P2P2_DP<1>")
	)
	(segment
		(start 323.118734 -328.83221)
		(end 321.90563 -331.76083)
		(width 0.14732)
		(layer "In6.Cu")
		(net "UPI_CPU0_CPU1_P2P2_DP<1>")
	)
	(segment
		(start 356.205028 -282.725114)
		(end 356.213918 -282.730194)
		(width 0.0889)
		(layer "In6.Cu")
		(net "UPI_CPU0_CPU1_P2P2_DP<1>")
	)
	(segment
		(start 63.61176 -311.155842)
		(end 64.379094 -310.388508)
		(width 0.14732)
		(layer "In6.Cu")
		(net "UPI_CPU0_CPU1_P2P2_DP<1>")
	)
	(segment
		(start 87.080344 -282.113736)
		(end 87.08009 -282.11399)
		(width 0.0889)
		(layer "In6.Cu")
		(net "UPI_CPU0_CPU1_P2P2_DP<1>")
	)
	(segment
		(start 51.36388 -329.42784)
		(end 51.36388 -324.335902)
		(width 0.14732)
		(layer "In6.Cu")
		(net "UPI_CPU0_CPU1_P2P2_DP<1>")
	)
	(segment
		(start 268.973554 -383.092198)
		(end 268.87297 -383.10058)
		(width 0.14732)
		(layer "In6.Cu")
		(net "UPI_CPU0_CPU1_P2P2_DP<1>")
	)
	(segment
		(start 55.825898 -315.651388)
		(end 58.564018 -313.821318)
		(width 0.14732)
		(layer "In6.Cu")
		(net "UPI_CPU0_CPU1_P2P2_DP<1>")
	)
	(segment
		(start 53.109876 -322.880228)
		(end 53.544216 -322.068444)
		(width 0.14732)
		(layer "In6.Cu")
		(net "UPI_CPU0_CPU1_P2P2_DP<1>")
	)
	(segment
		(start 311.04078 -342.62568)
		(end 286.940498 -342.62568)
		(width 0.14732)
		(layer "In6.Cu")
		(net "UPI_CPU0_CPU1_P2P2_DP<1>")
	)
	(segment
		(start 87.022178 -282.73629)
		(end 87.0331 -282.730194)
		(width 0.0889)
		(layer "In6.Cu")
		(net "UPI_CPU0_CPU1_P2P2_DP<1>")
	)
	(segment
		(start 52.565554 -323.424296)
		(end 53.109876 -322.880228)
		(width 0.14732)
		(layer "In6.Cu")
		(net "UPI_CPU0_CPU1_P2P2_DP<1>")
	)
	(segment
		(start 353.924108 -299.138848)
		(end 353.082098 -301.17161)
		(width 0.14732)
		(layer "In6.Cu")
		(net "UPI_CPU0_CPU1_P2P2_DP<1>")
	)
	(segment
		(start 53.804566 -316.636654)
		(end 54.057296 -316.383924)
		(width 0.14732)
		(layer "In6.Cu")
		(net "UPI_CPU0_CPU1_P2P2_DP<1>")
	)
	(segment
		(start 84.85759 -289.837368)
		(end 84.85759 -285.909766)
		(width 0.0889)
		(layer "In6.Cu")
		(net "UPI_CPU0_CPU1_P2P2_DP<1>")
	)
	(segment
		(start 84.85759 -285.909766)
		(end 85.505798 -285.261558)
		(width 0.0889)
		(layer "In6.Cu")
		(net "UPI_CPU0_CPU1_P2P2_DP<1>")
	)
	(segment
		(start 59.54522 -312.84037)
		(end 63.61176 -311.155842)
		(width 0.14732)
		(layer "In6.Cu")
		(net "UPI_CPU0_CPU1_P2P2_DP<1>")
	)
	(segment
		(start 355.556566 -288.103056)
		(end 355.556566 -288.11728)
		(width 0.0889)
		(layer "In6.Cu")
		(net "UPI_CPU0_CPU1_P2P2_DP<1>")
	)
	(segment
		(start 63.241428 -370.880894)
		(end 57.268618 -356.460806)
		(width 0.14732)
		(layer "In6.Cu")
		(net "UPI_CPU0_CPU1_P2P2_DP<1>")
	)
	(segment
		(start 86.56193 -284.522418)
		(end 86.552024 -284.51683)
		(width 0.0889)
		(layer "In6.Cu")
		(net "UPI_CPU0_CPU1_P2P2_DP<1>")
	)
	(segment
		(start 355.086666 -287.280604)
		(end 355.086666 -287.297876)
		(width 0.0889)
		(layer "In6.Cu")
		(net "UPI_CPU0_CPU1_P2P2_DP<1>")
	)
	(segment
		(start 86.562692 -285.171896)
		(end 86.571582 -285.166816)
		(width 0.0889)
		(layer "In6.Cu")
		(net "UPI_CPU0_CPU1_P2P2_DP<1>")
	)
	(segment
		(start 57.268618 -356.460806)
		(end 57.268618 -336.62239)
		(width 0.14732)
		(layer "In6.Cu")
		(net "UPI_CPU0_CPU1_P2P2_DP<1>")
	)
	(segment
		(start 87.08009 -282.11399)
		(end 87.002112 -282.134818)
		(width 0.0889)
		(layer "In6.Cu")
		(net "UPI_CPU0_CPU1_P2P2_DP<1>")
	)
	(segment
		(start 161.811208 -392.14171)
		(end 126.746 -392.14171)
		(width 0.14732)
		(layer "In6.Cu")
		(net "UPI_CPU0_CPU1_P2P2_DP<1>")
	)
	(segment
		(start 286.940498 -342.62568)
		(end 285.138368 -343.372186)
		(width 0.14732)
		(layer "In6.Cu")
		(net "UPI_CPU0_CPU1_P2P2_DP<1>")
	)
	(segment
		(start 53.643276 -321.569588)
		(end 53.643276 -317.026036)
		(width 0.14732)
		(layer "In6.Cu")
		(net "UPI_CPU0_CPU1_P2P2_DP<1>")
	)
	(segment
		(start 355.086666 -285.652718)
		(end 355.086666 -285.66999)
		(width 0.0889)
		(layer "In6.Cu")
		(net "UPI_CPU0_CPU1_P2P2_DP<1>")
	)
	(segment
		(start 268.872716 -383.100834)
		(end 161.811208 -392.14171)
		(width 0.14732)
		(layer "In6.Cu")
		(net "UPI_CPU0_CPU1_P2P2_DP<1>")
	)
	(segment
		(start 355.744018 -284.52318)
		(end 355.735128 -284.52826)
		(width 0.0889)
		(layer "In6.Cu")
		(net "UPI_CPU0_CPU1_P2P2_DP<1>")
	)
	(segment
		(start 93.034866 -387.140958)
		(end 69.934582 -377.574048)
		(width 0.14732)
		(layer "In6.Cu")
		(net "UPI_CPU0_CPU1_P2P2_DP<1>")
	)
	(segment
		(start 86.571582 -284.52826)
		(end 86.562692 -284.52318)
		(width 0.0889)
		(layer "In6.Cu")
		(net "UPI_CPU0_CPU1_P2P2_DP<1>")
	)
	(segment
		(start 321.90563 -331.76083)
		(end 311.04078 -342.62568)
		(width 0.14732)
		(layer "In6.Cu")
		(net "UPI_CPU0_CPU1_P2P2_DP<1>")
	)
	(arc
		(start 355.556566 -288.11728)
		(mid 355.477425 -288.391903)
		(end 355.274118 -288.592768)
		(width 0.0889)
		(layer "In6.Cu")
		(net "UPI_CPU0_CPU1_P2P2_DP<1>")
	)
	(arc
		(start 354.253546 -280.279856)
		(mid 354.529987 -280.21269)
		(end 354.804218 -280.288492)
		(width 0.0889)
		(layer "In6.Cu")
		(net "UPI_CPU0_CPU1_P2P2_DP<1>")
	)
	(arc
		(start 356.026466 -284.033722)
		(mid 355.95255 -284.313224)
		(end 355.750114 -284.519624)
		(width 0.0889)
		(layer "In6.Cu")
		(net "UPI_CPU0_CPU1_P2P2_DP<1>")
	)
	(arc
		(start 355.556566 -281.59202)
		(mid 355.604245 -281.77492)
		(end 355.735128 -281.911298)
		(width 0.0889)
		(layer "In6.Cu")
		(net "UPI_CPU0_CPU1_P2P2_DP<1>")
	)
	(arc
		(start 355.273864 -286.964882)
		(mid 355.138931 -287.098236)
		(end 355.086666 -287.280604)
		(width 0.0889)
		(layer "In6.Cu")
		(net "UPI_CPU0_CPU1_P2P2_DP<1>")
	)
	(arc
		(start 85.505798 -285.261558)
		(mid 85.561403 -285.212884)
		(end 85.622892 -285.171896)
		(width 0.0889)
		(layer "In6.Cu")
		(net "UPI_CPU0_CPU1_P2P2_DP<1>")
	)
	(arc
		(start 355.556566 -284.847538)
		(mid 355.484331 -285.124062)
		(end 355.286056 -285.329884)
		(width 0.0889)
		(layer "In6.Cu")
		(net "UPI_CPU0_CPU1_P2P2_DP<1>")
	)
	(arc
		(start 85.622892 -285.171896)
		(mid 85.905594 -285.09612)
		(end 86.188296 -285.171896)
		(width 0.0889)
		(layer "In6.Cu")
		(net "UPI_CPU0_CPU1_P2P2_DP<1>")
	)
	(arc
		(start 87.0331 -282.730194)
		(mid 87.167323 -282.59803)
		(end 87.220298 -282.417266)
		(width 0.0889)
		(layer "In6.Cu")
		(net "UPI_CPU0_CPU1_P2P2_DP<1>")
	)
	(arc
		(start 355.750114 -281.919934)
		(mid 355.952527 -282.126347)
		(end 356.026466 -282.405836)
		(width 0.0889)
		(layer "In6.Cu")
		(net "UPI_CPU0_CPU1_P2P2_DP<1>")
	)
	(arc
		(start 356.205028 -283.714444)
		(mid 356.074114 -283.850804)
		(end 356.026466 -284.033722)
		(width 0.0889)
		(layer "In6.Cu")
		(net "UPI_CPU0_CPU1_P2P2_DP<1>")
	)
	(arc
		(start 354.804218 -280.288492)
		(mid 355.0055 -280.485979)
		(end 355.086412 -280.756106)
		(width 0.0889)
		(layer "In6.Cu")
		(net "UPI_CPU0_CPU1_P2P2_DP<1>")
	)
	(arc
		(start 355.086412 -280.778204)
		(mid 355.134091 -280.961104)
		(end 355.264974 -281.097482)
		(width 0.0889)
		(layer "In6.Cu")
		(net "UPI_CPU0_CPU1_P2P2_DP<1>")
	)
	(arc
		(start 356.213918 -282.730194)
		(mid 356.416204 -282.929175)
		(end 356.496366 -283.201364)
		(width 0.0889)
		(layer "In6.Cu")
		(net "UPI_CPU0_CPU1_P2P2_DP<1>")
	)
	(arc
		(start 353.962462 -280.69159)
		(mid 354.054809 -280.458619)
		(end 354.238814 -280.288492)
		(width 0.0889)
		(layer "In6.Cu")
		(net "UPI_CPU0_CPU1_P2P2_DP<1>")
	)
	(arc
		(start 86.750144 -284.854142)
		(mid 86.750238 -284.84576)
		(end 86.750144 -284.837378)
		(width 0.0889)
		(layer "In6.Cu")
		(net "UPI_CPU0_CPU1_P2P2_DP<1>")
	)
	(arc
		(start 355.086666 -285.66999)
		(mid 355.138936 -285.852355)
		(end 355.273864 -285.985712)
		(width 0.0889)
		(layer "In6.Cu")
		(net "UPI_CPU0_CPU1_P2P2_DP<1>")
	)
	(arc
		(start 86.750144 -283.219906)
		(mid 86.822765 -282.942441)
		(end 87.022178 -282.73629)
		(width 0.0889)
		(layer "In6.Cu")
		(net "UPI_CPU0_CPU1_P2P2_DP<1>")
	)
	(arc
		(start 355.273864 -285.336996)
		(mid 355.138931 -285.47035)
		(end 355.086666 -285.652718)
		(width 0.0889)
		(layer "In6.Cu")
		(net "UPI_CPU0_CPU1_P2P2_DP<1>")
	)
	(arc
		(start 86.571836 -283.53893)
		(mid 86.699519 -283.408057)
		(end 86.750144 -283.232352)
		(width 0.0889)
		(layer "In6.Cu")
		(net "UPI_CPU0_CPU1_P2P2_DP<1>")
	)
	(arc
		(start 353.959668 -280.712672)
		(mid 353.960966 -280.702118)
		(end 353.962462 -280.69159)
		(width 0.0889)
		(layer "In6.Cu")
		(net "UPI_CPU0_CPU1_P2P2_DP<1>")
	)
	(arc
		(start 355.265228 -288.597848)
		(mid 355.134314 -288.734208)
		(end 355.086666 -288.917126)
		(width 0.0889)
		(layer "In6.Cu")
		(net "UPI_CPU0_CPU1_P2P2_DP<1>")
	)
	(arc
		(start 355.273864 -285.985712)
		(mid 355.478936 -286.189391)
		(end 355.556566 -286.467804)
		(width 0.0889)
		(layer "In6.Cu")
		(net "UPI_CPU0_CPU1_P2P2_DP<1>")
	)
	(arc
		(start 355.270562 -289.27806)
		(mid 355.444807 -289.417106)
		(end 355.556058 -289.610292)
		(width 0.0889)
		(layer "In6.Cu")
		(net "UPI_CPU0_CPU1_P2P2_DP<1>")
	)
	(arc
		(start 355.086666 -289.078416)
		(mid 355.161671 -289.193875)
		(end 355.270816 -289.277806)
		(width 0.0889)
		(layer "In6.Cu")
		(net "UPI_CPU0_CPU1_P2P2_DP<1>")
	)
	(arc
		(start 356.026466 -282.405836)
		(mid 356.074145 -282.588736)
		(end 356.205028 -282.725114)
		(width 0.0889)
		(layer "In6.Cu")
		(net "UPI_CPU0_CPU1_P2P2_DP<1>")
	)
	(arc
		(start 355.556566 -286.475424)
		(mid 355.484331 -286.751948)
		(end 355.286056 -286.95777)
		(width 0.0889)
		(layer "In6.Cu")
		(net "UPI_CPU0_CPU1_P2P2_DP<1>")
	)
	(arc
		(start 355.086666 -287.297876)
		(mid 355.138936 -287.480241)
		(end 355.273864 -287.613598)
		(width 0.0889)
		(layer "In6.Cu")
		(net "UPI_CPU0_CPU1_P2P2_DP<1>")
	)
	(arc
		(start 86.552024 -284.51683)
		(mid 86.280309 -284.033722)
		(end 86.552024 -283.550614)
		(width 0.0889)
		(layer "In6.Cu")
		(net "UPI_CPU0_CPU1_P2P2_DP<1>")
	)
	(arc
		(start 355.735128 -284.52826)
		(mid 355.604214 -284.66462)
		(end 355.556566 -284.847538)
		(width 0.0889)
		(layer "In6.Cu")
		(net "UPI_CPU0_CPU1_P2P2_DP<1>")
	)
	(arc
		(start 86.571582 -285.166816)
		(mid 86.700871 -285.03333)
		(end 86.750144 -284.854142)
		(width 0.0889)
		(layer "In6.Cu")
		(net "UPI_CPU0_CPU1_P2P2_DP<1>")
	)
	(arc
		(start 86.188296 -285.171896)
		(mid 86.375494 -285.222039)
		(end 86.562692 -285.171896)
		(width 0.0889)
		(layer "In6.Cu")
		(net "UPI_CPU0_CPU1_P2P2_DP<1>")
	)
	(arc
		(start 356.496366 -283.229812)
		(mid 356.418255 -283.506761)
		(end 356.213918 -283.709364)
		(width 0.0889)
		(layer "In6.Cu")
		(net "UPI_CPU0_CPU1_P2P2_DP<1>")
	)
	(arc
		(start 87.220298 -282.397962)
		(mid 87.181847 -282.240322)
		(end 87.080344 -282.113736)
		(width 0.0889)
		(layer "In6.Cu")
		(net "UPI_CPU0_CPU1_P2P2_DP<1>")
	)
	(arc
		(start 355.286056 -287.62071)
		(mid 355.484284 -287.826558)
		(end 355.556566 -288.103056)
		(width 0.0889)
		(layer "In6.Cu")
		(net "UPI_CPU0_CPU1_P2P2_DP<1>")
	)
	(arc
		(start 86.750144 -284.837378)
		(mid 86.700075 -284.660153)
		(end 86.571582 -284.52826)
		(width 0.0889)
		(layer "In6.Cu")
		(net "UPI_CPU0_CPU1_P2P2_DP<1>")
	)
	(arc
		(start 355.27996 -281.106118)
		(mid 355.482547 -281.312469)
		(end 355.556566 -281.59202)
		(width 0.0889)
		(layer "In6.Cu")
		(net "UPI_CPU0_CPU1_P2P2_DP<1>")
	)
	(segment
		(start 335.725262 -285.125414)
		(end 335.725262 -285.661354)
		(width 0.13208)
		(layer "F.Cu")
		(net "UPI_CPU0_CPU1_P2P2_DP<19>")
	)
	(segment
		(start 109.400594 -276.986492)
		(end 109.400594 -277.522432)
		(width 0.13208)
		(layer "F.Cu")
		(net "UPI_CPU0_CPU1_P2P2_DP<19>")
	)
	(segment
		(start 159.116776 -376.57913)
		(end 125.96749 -376.57913)
		(width 0.14732)
		(layer "In6.Cu")
		(net "UPI_CPU0_CPU1_P2P2_DP<19>")
	)
	(segment
		(start 251.173488 -354.413312)
		(end 250.74499 -354.48875)
		(width 0.14732)
		(layer "In6.Cu")
		(net "UPI_CPU0_CPU1_P2P2_DP<19>")
	)
	(segment
		(start 247.188482 -361.58678)
		(end 246.983504 -361.550458)
		(width 0.14732)
		(layer "In6.Cu")
		(net "UPI_CPU0_CPU1_P2P2_DP<19>")
	)
	(segment
		(start 335.474056 -289.620452)
		(end 335.294224 -289.800284)
		(width 0.0889)
		(layer "In6.Cu")
		(net "UPI_CPU0_CPU1_P2P2_DP<19>")
	)
	(segment
		(start 103.133144 -297.533568)
		(end 103.133144 -296.300398)
		(width 0.14732)
		(layer "In6.Cu")
		(net "UPI_CPU0_CPU1_P2P2_DP<19>")
	)
	(segment
		(start 103.133144 -294.585898)
		(end 103.277924 -294.441118)
		(width 0.14732)
		(layer "In6.Cu")
		(net "UPI_CPU0_CPU1_P2P2_DP<19>")
	)
	(segment
		(start 245.04396 -360.7435)
		(end 244.968522 -361.171998)
		(width 0.14732)
		(layer "In6.Cu")
		(net "UPI_CPU0_CPU1_P2P2_DP<19>")
	)
	(segment
		(start 241.976148 -365.236506)
		(end 241.49304 -365.575088)
		(width 0.14732)
		(layer "In6.Cu")
		(net "UPI_CPU0_CPU1_P2P2_DP<19>")
	)
	(segment
		(start 243.910866 -363.702092)
		(end 243.874544 -363.90707)
		(width 0.14732)
		(layer "In6.Cu")
		(net "UPI_CPU0_CPU1_P2P2_DP<19>")
	)
	(segment
		(start 265.239246 -341.159592)
		(end 254.578612 -351.82048)
		(width 0.14732)
		(layer "In6.Cu")
		(net "UPI_CPU0_CPU1_P2P2_DP<19>")
	)
	(segment
		(start 311.45734 -315.212476)
		(end 310.561482 -316.108334)
		(width 0.14732)
		(layer "In6.Cu")
		(net "UPI_CPU0_CPU1_P2P2_DP<19>")
	)
	(segment
		(start 252.502924 -352.514916)
		(end 252.074426 -352.590354)
		(width 0.14732)
		(layer "In6.Cu")
		(net "UPI_CPU0_CPU1_P2P2_DP<19>")
	)
	(segment
		(start 248.086118 -358.285542)
		(end 247.61698 -358.955848)
		(width 0.14732)
		(layer "In6.Cu")
		(net "UPI_CPU0_CPU1_P2P2_DP<19>")
	)
	(segment
		(start 241.17173 -363.83087)
		(end 242.01247 -365.031528)
		(width 0.14732)
		(layer "In6.Cu")
		(net "UPI_CPU0_CPU1_P2P2_DP<19>")
	)
	(segment
		(start 249.844052 -356.311708)
		(end 249.415554 -356.387146)
		(width 0.14732)
		(layer "In6.Cu")
		(net "UPI_CPU0_CPU1_P2P2_DP<19>")
	)
	(segment
		(start 105.44556 -285.342076)
		(end 105.453434 -285.337504)
		(width 0.0889)
		(layer "In6.Cu")
		(net "UPI_CPU0_CPU1_P2P2_DP<19>")
	)
	(segment
		(start 243.874544 -363.90707)
		(end 243.391436 -364.245652)
		(width 0.14732)
		(layer "In6.Cu")
		(net "UPI_CPU0_CPU1_P2P2_DP<19>")
	)
	(segment
		(start 125.96749 -376.57913)
		(end 99.026218 -372.582948)
		(width 0.14732)
		(layer "In6.Cu")
		(net "UPI_CPU0_CPU1_P2P2_DP<19>")
	)
	(segment
		(start 102.938072 -298.00423)
		(end 103.133144 -297.533568)
		(width 0.14732)
		(layer "In6.Cu")
		(net "UPI_CPU0_CPU1_P2P2_DP<19>")
	)
	(segment
		(start 243.391436 -364.245652)
		(end 243.186712 -364.20933)
		(width 0.14732)
		(layer "In6.Cu")
		(net "UPI_CPU0_CPU1_P2P2_DP<19>")
	)
	(segment
		(start 303.346358 -322.82384)
		(end 302.349154 -323.547486)
		(width 0.14732)
		(layer "In6.Cu")
		(net "UPI_CPU0_CPU1_P2P2_DP<19>")
	)
	(segment
		(start 239.348772 -364.731808)
		(end 239.273334 -365.160306)
		(width 0.14732)
		(layer "In6.Cu")
		(net "UPI_CPU0_CPU1_P2P2_DP<19>")
	)
	(segment
		(start 313.046618 -314.199524)
		(end 313.046618 -314.404248)
		(width 0.14732)
		(layer "In6.Cu")
		(net "UPI_CPU0_CPU1_P2P2_DP<19>")
	)
	(segment
		(start 265.239246 -340.951312)
		(end 265.239246 -341.159592)
		(width 0.14732)
		(layer "In6.Cu")
		(net "UPI_CPU0_CPU1_P2P2_DP<19>")
	)
	(segment
		(start 297.282108 -325.647812)
		(end 292.752018 -325.647812)
		(width 0.14732)
		(layer "In6.Cu")
		(net "UPI_CPU0_CPU1_P2P2_DP<19>")
	)
	(segment
		(start 250.275852 -355.159056)
		(end 250.35129 -355.587554)
		(width 0.14732)
		(layer "In6.Cu")
		(net "UPI_CPU0_CPU1_P2P2_DP<19>")
	)
	(segment
		(start 268.036802 -337.193636)
		(end 268.516862 -337.673696)
		(width 0.14732)
		(layer "In6.Cu")
		(net "UPI_CPU0_CPU1_P2P2_DP<19>")
	)
	(segment
		(start 104.511094 -289.27806)
		(end 104.511348 -289.277806)
		(width 0.0889)
		(layer "In6.Cu")
		(net "UPI_CPU0_CPU1_P2P2_DP<19>")
	)
	(segment
		(start 248.67489 -360.251756)
		(end 248.270776 -360.828844)
		(width 0.14732)
		(layer "In6.Cu")
		(net "UPI_CPU0_CPU1_P2P2_DP<19>")
	)
	(segment
		(start 287.510474 -325.647812)
		(end 277.626826 -329.741784)
		(width 0.14732)
		(layer "In6.Cu")
		(net "UPI_CPU0_CPU1_P2P2_DP<19>")
	)
	(segment
		(start 103.133144 -295.642538)
		(end 103.133144 -294.585898)
		(width 0.14732)
		(layer "In6.Cu")
		(net "UPI_CPU0_CPU1_P2P2_DP<19>")
	)
	(segment
		(start 273.016472 -333.382366)
		(end 272.808192 -333.382366)
		(width 0.14732)
		(layer "In6.Cu")
		(net "UPI_CPU0_CPU1_P2P2_DP<19>")
	)
	(segment
		(start 252.663198 -354.556314)
		(end 252.324616 -355.039422)
		(width 0.14732)
		(layer "In6.Cu")
		(net "UPI_CPU0_CPU1_P2P2_DP<19>")
	)
	(segment
		(start 103.882952 -291.885116)
		(end 104.259126 -291.508942)
		(width 0.0889)
		(layer "In6.Cu")
		(net "UPI_CPU0_CPU1_P2P2_DP<19>")
	)
	(segment
		(start 312.23839 -315.212476)
		(end 311.45734 -315.212476)
		(width 0.14732)
		(layer "In6.Cu")
		(net "UPI_CPU0_CPU1_P2P2_DP<19>")
	)
	(segment
		(start 103.717344 -292.110668)
		(end 103.867458 -291.960554)
		(width 0.14732)
		(layer "In6.Cu")
		(net "UPI_CPU0_CPU1_P2P2_DP<19>")
	)
	(segment
		(start 251.333762 -356.45471)
		(end 250.99518 -356.937818)
		(width 0.14732)
		(layer "In6.Cu")
		(net "UPI_CPU0_CPU1_P2P2_DP<19>")
	)
	(segment
		(start 332.302358 -293.66337)
		(end 330.365354 -300.04766)
		(width 0.14732)
		(layer "In6.Cu")
		(net "UPI_CPU0_CPU1_P2P2_DP<19>")
	)
	(segment
		(start 72.549258 -335.17078)
		(end 73.062084 -329.960224)
		(width 0.14732)
		(layer "In6.Cu")
		(net "UPI_CPU0_CPU1_P2P2_DP<19>")
	)
	(segment
		(start 277.43785 -329.663298)
		(end 277.097236 -329.804268)
		(width 0.14732)
		(layer "In6.Cu")
		(net "UPI_CPU0_CPU1_P2P2_DP<19>")
	)
	(segment
		(start 274.121118 -332.105254)
		(end 273.811746 -332.414626)
		(width 0.14732)
		(layer "In6.Cu")
		(net "UPI_CPU0_CPU1_P2P2_DP<19>")
	)
	(segment
		(start 105.453434 -285.337504)
		(end 105.45445 -285.336996)
		(width 0.0889)
		(layer "In6.Cu")
		(net "UPI_CPU0_CPU1_P2P2_DP<19>")
	)
	(segment
		(start 271.794478 -334.60436)
		(end 271.377664 -335.021174)
		(width 0.14732)
		(layer "In6.Cu")
		(net "UPI_CPU0_CPU1_P2P2_DP<19>")
	)
	(segment
		(start 264.75944 -340.035896)
		(end 264.759186 -340.471252)
		(width 0.14732)
		(layer "In6.Cu")
		(net "UPI_CPU0_CPU1_P2P2_DP<19>")
	)
	(segment
		(start 308.48554 -317.065406)
		(end 308.48554 -317.27013)
		(width 0.14732)
		(layer "In6.Cu")
		(net "UPI_CPU0_CPU1_P2P2_DP<19>")
	)
	(segment
		(start 277.626826 -329.741784)
		(end 277.43785 -329.663298)
		(width 0.14732)
		(layer "In6.Cu")
		(net "UPI_CPU0_CPU1_P2P2_DP<19>")
	)
	(segment
		(start 336.099912 -285.661354)
		(end 336.099912 -285.679896)
		(width 0.0889)
		(layer "In6.Cu")
		(net "UPI_CPU0_CPU1_P2P2_DP<19>")
	)
	(segment
		(start 291.70757 -327.223628)
		(end 291.56025 -327.076308)
		(width 0.14732)
		(layer "In6.Cu")
		(net "UPI_CPU0_CPU1_P2P2_DP<19>")
	)
	(segment
		(start 315.65723 -313.57062)
		(end 313.880246 -313.57062)
		(width 0.14732)
		(layer "In6.Cu")
		(net "UPI_CPU0_CPU1_P2P2_DP<19>")
	)
	(segment
		(start 336.569812 -286.475424)
		(end 336.569812 -286.48533)
		(width 0.0889)
		(layer "In6.Cu")
		(net "UPI_CPU0_CPU1_P2P2_DP<19>")
	)
	(segment
		(start 104.797098 -288.121598)
		(end 104.797098 -288.103056)
		(width 0.0889)
		(layer "In6.Cu")
		(net "UPI_CPU0_CPU1_P2P2_DP<19>")
	)
	(segment
		(start 336.86115 -287.608518)
		(end 336.860388 -287.609026)
		(width 0.0889)
		(layer "In6.Cu")
		(net "UPI_CPU0_CPU1_P2P2_DP<19>")
	)
	(segment
		(start 266.878054 -339.312504)
		(end 266.878054 -339.520784)
		(width 0.14732)
		(layer "In6.Cu")
		(net "UPI_CPU0_CPU1_P2P2_DP<19>")
	)
	(segment
		(start 249.968004 -358.148382)
		(end 250.004326 -358.353106)
		(width 0.14732)
		(layer "In6.Cu")
		(net "UPI_CPU0_CPU1_P2P2_DP<19>")
	)
	(segment
		(start 105.736644 -284.863032)
		(end 105.736644 -284.847538)
		(width 0.0889)
		(layer "In6.Cu")
		(net "UPI_CPU0_CPU1_P2P2_DP<19>")
	)
	(segment
		(start 270.15567 -336.034888)
		(end 270.15567 -336.243168)
		(width 0.14732)
		(layer "In6.Cu")
		(net "UPI_CPU0_CPU1_P2P2_DP<19>")
	)
	(segment
		(start 274.293584 -332.105254)
		(end 274.121118 -332.105254)
		(width 0.14732)
		(layer "In6.Cu")
		(net "UPI_CPU0_CPU1_P2P2_DP<19>")
	)
	(segment
		(start 292.29685 -327.223628)
		(end 291.70757 -327.223628)
		(width 0.14732)
		(layer "In6.Cu")
		(net "UPI_CPU0_CPU1_P2P2_DP<19>")
	)
	(segment
		(start 335.881726 -285.390336)
		(end 335.959958 -285.369508)
		(width 0.0889)
		(layer "In6.Cu")
		(net "UPI_CPU0_CPU1_P2P2_DP<19>")
	)
	(segment
		(start 291.252402 -325.647812)
		(end 287.510474 -325.647812)
		(width 0.14732)
		(layer "In6.Cu")
		(net "UPI_CPU0_CPU1_P2P2_DP<19>")
	)
	(segment
		(start 240.019078 -364.26267)
		(end 239.348772 -364.731808)
		(width 0.14732)
		(layer "In6.Cu")
		(net "UPI_CPU0_CPU1_P2P2_DP<19>")
	)
	(segment
		(start 305.431698 -319.665604)
		(end 305.431698 -320.033904)
		(width 0.14732)
		(layer "In6.Cu")
		(net "UPI_CPU0_CPU1_P2P2_DP<19>")
	)
	(segment
		(start 336.85226 -286.964882)
		(end 336.86115 -286.969962)
		(width 0.0889)
		(layer "In6.Cu")
		(net "UPI_CPU0_CPU1_P2P2_DP<19>")
	)
	(segment
		(start 104.97566 -287.783778)
		(end 104.98455 -287.778698)
		(width 0.0889)
		(layer "In6.Cu")
		(net "UPI_CPU0_CPU1_P2P2_DP<19>")
	)
	(segment
		(start 302.349154 -323.547486)
		(end 297.282108 -325.647812)
		(width 0.14732)
		(layer "In6.Cu")
		(net "UPI_CPU0_CPU1_P2P2_DP<19>")
	)
	(segment
		(start 265.7729 -339.457538)
		(end 265.338052 -339.457284)
		(width 0.14732)
		(layer "In6.Cu")
		(net "UPI_CPU0_CPU1_P2P2_DP<19>")
	)
	(segment
		(start 107.146344 -282.427934)
		(end 107.146344 -282.390342)
		(width 0.0889)
		(layer "In6.Cu")
		(net "UPI_CPU0_CPU1_P2P2_DP<19>")
	)
	(segment
		(start 305.83632 -318.386968)
		(end 305.576478 -318.89573)
		(width 0.14732)
		(layer "In6.Cu")
		(net "UPI_CPU0_CPU1_P2P2_DP<19>")
	)
	(segment
		(start 273.811746 -332.414626)
		(end 273.811746 -332.587092)
		(width 0.14732)
		(layer "In6.Cu")
		(net "UPI_CPU0_CPU1_P2P2_DP<19>")
	)
	(segment
		(start 103.716328 -292.110668)
		(end 103.717344 -292.110668)
		(width 0.14732)
		(layer "In6.Cu")
		(net "UPI_CPU0_CPU1_P2P2_DP<19>")
	)
	(segment
		(start 330.365354 -300.04766)
		(end 316.842394 -313.57062)
		(width 0.14732)
		(layer "In6.Cu")
		(net "UPI_CPU0_CPU1_P2P2_DP<19>")
	)
	(segment
		(start 271.794478 -334.39608)
		(end 271.794478 -334.60436)
		(width 0.14732)
		(layer "In6.Cu")
		(net "UPI_CPU0_CPU1_P2P2_DP<19>")
	)
	(segment
		(start 245.085108 -362.879894)
		(end 244.244368 -361.679236)
		(width 0.14732)
		(layer "In6.Cu")
		(net "UPI_CPU0_CPU1_P2P2_DP<19>")
	)
	(segment
		(start 264.759186 -340.471252)
		(end 265.239246 -340.951312)
		(width 0.14732)
		(layer "In6.Cu")
		(net "UPI_CPU0_CPU1_P2P2_DP<19>")
	)
	(segment
		(start 106.85526 -281.272742)
		(end 106.86415 -281.267662)
		(width 0.0889)
		(layer "In6.Cu")
		(net "UPI_CPU0_CPU1_P2P2_DP<19>")
	)
	(segment
		(start 75.021694 -324.714616)
		(end 80.519778 -319.216532)
		(width 0.14732)
		(layer "In6.Cu")
		(net "UPI_CPU0_CPU1_P2P2_DP<19>")
	)
	(segment
		(start 98.174302 -304.423572)
		(end 98.185986 -304.411126)
		(width 0.14732)
		(layer "In6.Cu")
		(net "UPI_CPU0_CPU1_P2P2_DP<19>")
	)
	(segment
		(start 268.516862 -337.881976)
		(end 268.100048 -338.29879)
		(width 0.14732)
		(layer "In6.Cu")
		(net "UPI_CPU0_CPU1_P2P2_DP<19>")
	)
	(segment
		(start 271.893284 -332.902052)
		(end 271.314672 -333.480664)
		(width 0.14732)
		(layer "In6.Cu")
		(net "UPI_CPU0_CPU1_P2P2_DP<19>")
	)
	(segment
		(start 248.638568 -360.046778)
		(end 248.67489 -360.251756)
		(width 0.14732)
		(layer "In6.Cu")
		(net "UPI_CPU0_CPU1_P2P2_DP<19>")
	)
	(segment
		(start 251.605288 -353.26066)
		(end 251.680726 -353.689158)
		(width 0.14732)
		(layer "In6.Cu")
		(net "UPI_CPU0_CPU1_P2P2_DP<19>")
	)
	(segment
		(start 303.378616 -322.621402)
		(end 303.346358 -322.82384)
		(width 0.14732)
		(layer "In6.Cu")
		(net "UPI_CPU0_CPU1_P2P2_DP<19>")
	)
	(segment
		(start 265.338052 -339.457284)
		(end 264.75944 -340.035896)
		(width 0.14732)
		(layer "In6.Cu")
		(net "UPI_CPU0_CPU1_P2P2_DP<19>")
	)
	(segment
		(start 80.519778 -319.216532)
		(end 96.834198 -305.827684)
		(width 0.14732)
		(layer "In6.Cu")
		(net "UPI_CPU0_CPU1_P2P2_DP<19>")
	)
	(segment
		(start 336.099658 -288.902902)
		(end 336.099658 -289.131502)
		(width 0.0889)
		(layer "In6.Cu")
		(net "UPI_CPU0_CPU1_P2P2_DP<19>")
	)
	(segment
		(start 244.244368 -361.679236)
		(end 243.81587 -361.603798)
		(width 0.14732)
		(layer "In6.Cu")
		(net "UPI_CPU0_CPU1_P2P2_DP<19>")
	)
	(segment
		(start 245.289832 -362.916216)
		(end 245.085108 -362.879894)
		(width 0.14732)
		(layer "In6.Cu")
		(net "UPI_CPU0_CPU1_P2P2_DP<19>")
	)
	(segment
		(start 305.576478 -319.520824)
		(end 305.431698 -319.665604)
		(width 0.14732)
		(layer "In6.Cu")
		(net "UPI_CPU0_CPU1_P2P2_DP<19>")
	)
	(segment
		(start 243.145564 -362.072936)
		(end 243.070126 -362.501434)
		(width 0.14732)
		(layer "In6.Cu")
		(net "UPI_CPU0_CPU1_P2P2_DP<19>")
	)
	(segment
		(start 254.578612 -351.82048)
		(end 253.654052 -353.141026)
		(width 0.14732)
		(layer "In6.Cu")
		(net "UPI_CPU0_CPU1_P2P2_DP<19>")
	)
	(segment
		(start 313.046618 -314.404248)
		(end 312.23839 -315.212476)
		(width 0.14732)
		(layer "In6.Cu")
		(net "UPI_CPU0_CPU1_P2P2_DP<19>")
	)
	(segment
		(start 316.17031 -313.42584)
		(end 315.80201 -313.42584)
		(width 0.14732)
		(layer "In6.Cu")
		(net "UPI_CPU0_CPU1_P2P2_DP<19>")
	)
	(segment
		(start 104.259126 -291.305742)
		(end 104.79659 -290.768278)
		(width 0.0889)
		(layer "In6.Cu")
		(net "UPI_CPU0_CPU1_P2P2_DP<19>")
	)
	(segment
		(start 103.401876 -292.426136)
		(end 103.716328 -292.111684)
		(width 0.14732)
		(layer "In6.Cu")
		(net "UPI_CPU0_CPU1_P2P2_DP<19>")
	)
	(segment
		(start 248.946416 -357.057452)
		(end 249.021854 -357.48595)
		(width 0.14732)
		(layer "In6.Cu")
		(net "UPI_CPU0_CPU1_P2P2_DP<19>")
	)
	(segment
		(start 241.288316 -365.538766)
		(end 240.447576 -364.338108)
		(width 0.14732)
		(layer "In6.Cu")
		(net "UPI_CPU0_CPU1_P2P2_DP<19>")
	)
	(segment
		(start 108.264706 -278.83104)
		(end 108.279946 -278.82215)
		(width 0.0889)
		(layer "In6.Cu")
		(net "UPI_CPU0_CPU1_P2P2_DP<19>")
	)
	(segment
		(start 271.314672 -333.480664)
		(end 271.314418 -333.91602)
		(width 0.14732)
		(layer "In6.Cu")
		(net "UPI_CPU0_CPU1_P2P2_DP<19>")
	)
	(segment
		(start 292.44417 -325.95566)
		(end 292.44417 -327.076308)
		(width 0.14732)
		(layer "In6.Cu")
		(net "UPI_CPU0_CPU1_P2P2_DP<19>")
	)
	(segment
		(start 249.460766 -358.872536)
		(end 248.514616 -358.210104)
		(width 0.14732)
		(layer "In6.Cu")
		(net "UPI_CPU0_CPU1_P2P2_DP<19>")
	)
	(segment
		(start 103.277924 -295.787318)
		(end 103.133144 -295.642538)
		(width 0.14732)
		(layer "In6.Cu")
		(net "UPI_CPU0_CPU1_P2P2_DP<19>")
	)
	(segment
		(start 268.100048 -338.29879)
		(end 267.891768 -338.29879)
		(width 0.14732)
		(layer "In6.Cu")
		(net "UPI_CPU0_CPU1_P2P2_DP<19>")
	)
	(segment
		(start 103.133144 -293.928038)
		(end 103.133144 -292.819582)
		(width 0.14732)
		(layer "In6.Cu")
		(net "UPI_CPU0_CPU1_P2P2_DP<19>")
	)
	(segment
		(start 247.692418 -359.384346)
		(end 248.638568 -360.046778)
		(width 0.14732)
		(layer "In6.Cu")
		(net "UPI_CPU0_CPU1_P2P2_DP<19>")
	)
	(segment
		(start 305.576478 -320.546984)
		(end 305.255676 -321.320922)
		(width 0.14732)
		(layer "In6.Cu")
		(net "UPI_CPU0_CPU1_P2P2_DP<19>")
	)
	(segment
		(start 266.97686 -337.818476)
		(end 266.398248 -338.397088)
		(width 0.14732)
		(layer "In6.Cu")
		(net "UPI_CPU0_CPU1_P2P2_DP<19>")
	)
	(segment
		(start 277.01875 -329.993752)
		(end 275.971254 -330.427584)
		(width 0.14732)
		(layer "In6.Cu")
		(net "UPI_CPU0_CPU1_P2P2_DP<19>")
	)
	(segment
		(start 105.915206 -284.52826)
		(end 105.924096 -284.52318)
		(width 0.0889)
		(layer "In6.Cu")
		(net "UPI_CPU0_CPU1_P2P2_DP<19>")
	)
	(segment
		(start 250.99518 -356.937818)
		(end 250.790202 -356.97414)
		(width 0.14732)
		(layer "In6.Cu")
		(net "UPI_CPU0_CPU1_P2P2_DP<19>")
	)
	(segment
		(start 333.90459 -291.267642)
		(end 332.302358 -293.66337)
		(width 0.14732)
		(layer "In6.Cu")
		(net "UPI_CPU0_CPU1_P2P2_DP<19>")
	)
	(segment
		(start 107.324906 -280.458926)
		(end 107.333796 -280.453846)
		(width 0.0889)
		(layer "In6.Cu")
		(net "UPI_CPU0_CPU1_P2P2_DP<19>")
	)
	(segment
		(start 241.247168 -363.402372)
		(end 241.17173 -363.83087)
		(width 0.14732)
		(layer "In6.Cu")
		(net "UPI_CPU0_CPU1_P2P2_DP<19>")
	)
	(segment
		(start 316.842394 -313.57062)
		(end 316.31509 -313.57062)
		(width 0.14732)
		(layer "In6.Cu")
		(net "UPI_CPU0_CPU1_P2P2_DP<19>")
	)
	(segment
		(start 310.561482 -316.108334)
		(end 309.647336 -316.108334)
		(width 0.14732)
		(layer "In6.Cu")
		(net "UPI_CPU0_CPU1_P2P2_DP<19>")
	)
	(segment
		(start 335.294224 -289.936936)
		(end 334.926686 -290.304474)
		(width 0.0889)
		(layer "In6.Cu")
		(net "UPI_CPU0_CPU1_P2P2_DP<19>")
	)
	(segment
		(start 109.08792 -277.522432)
		(end 109.400594 -277.522432)
		(width 0.0889)
		(layer "In6.Cu")
		(net "UPI_CPU0_CPU1_P2P2_DP<19>")
	)
	(segment
		(start 292.752018 -325.647812)
		(end 292.44417 -325.95566)
		(width 0.14732)
		(layer "In6.Cu")
		(net "UPI_CPU0_CPU1_P2P2_DP<19>")
	)
	(segment
		(start 315.80201 -313.42584)
		(end 315.65723 -313.57062)
		(width 0.14732)
		(layer "In6.Cu")
		(net "UPI_CPU0_CPU1_P2P2_DP<19>")
	)
	(segment
		(start 105.44556 -286.969962)
		(end 105.45445 -286.964882)
		(width 0.0889)
		(layer "In6.Cu")
		(net "UPI_CPU0_CPU1_P2P2_DP<19>")
	)
	(segment
		(start 313.5122 -313.938666)
		(end 313.307476 -313.938666)
		(width 0.14732)
		(layer "In6.Cu")
		(net "UPI_CPU0_CPU1_P2P2_DP<19>")
	)
	(segment
		(start 80.574896 -364.939072)
		(end 76.076048 -360.440224)
		(width 0.14732)
		(layer "In6.Cu")
		(net "UPI_CPU0_CPU1_P2P2_DP<19>")
	)
	(segment
		(start 106.39425 -283.709364)
		(end 106.400346 -283.705808)
		(width 0.0889)
		(layer "In6.Cu")
		(net "UPI_CPU0_CPU1_P2P2_DP<19>")
	)
	(segment
		(start 252.119638 -355.075744)
		(end 251.173488 -354.413312)
		(width 0.14732)
		(layer "In6.Cu")
		(net "UPI_CPU0_CPU1_P2P2_DP<19>")
	)
	(segment
		(start 270.15567 -336.243168)
		(end 269.738856 -336.659982)
		(width 0.14732)
		(layer "In6.Cu")
		(net "UPI_CPU0_CPU1_P2P2_DP<19>")
	)
	(segment
		(start 252.074426 -352.590354)
		(end 251.605288 -353.26066)
		(width 0.14732)
		(layer "In6.Cu")
		(net "UPI_CPU0_CPU1_P2P2_DP<19>")
	)
	(segment
		(start 108.086144 -279.160224)
		(end 108.086144 -279.150318)
		(width 0.0889)
		(layer "In6.Cu")
		(net "UPI_CPU0_CPU1_P2P2_DP<19>")
	)
	(segment
		(start 104.79659 -290.768278)
		(end 104.79659 -289.610292)
		(width 0.0889)
		(layer "In6.Cu")
		(net "UPI_CPU0_CPU1_P2P2_DP<19>")
	)
	(segment
		(start 96.834198 -305.827684)
		(end 96.834452 -305.827938)
		(width 0.14732)
		(layer "In6.Cu")
		(net "UPI_CPU0_CPU1_P2P2_DP<19>")
	)
	(segment
		(start 109.022642 -277.58771)
		(end 109.08792 -277.522432)
		(width 0.0889)
		(layer "In6.Cu")
		(net "UPI_CPU0_CPU1_P2P2_DP<19>")
	)
	(segment
		(start 272.808192 -333.382366)
		(end 272.328132 -332.902306)
		(width 0.14732)
		(layer "In6.Cu")
		(net "UPI_CPU0_CPU1_P2P2_DP<19>")
	)
	(segment
		(start 266.46124 -339.937598)
		(end 266.25296 -339.937598)
		(width 0.14732)
		(layer "In6.Cu")
		(net "UPI_CPU0_CPU1_P2P2_DP<19>")
	)
	(segment
		(start 305.255676 -321.320922)
		(end 304.826924 -321.74942)
		(width 0.14732)
		(layer "In6.Cu")
		(net "UPI_CPU0_CPU1_P2P2_DP<19>")
	)
	(segment
		(start 275.971254 -330.427584)
		(end 274.293584 -332.105254)
		(width 0.14732)
		(layer "In6.Cu")
		(net "UPI_CPU0_CPU1_P2P2_DP<19>")
	)
	(segment
		(start 240.077752 -366.565942)
		(end 239.305084 -367.106962)
		(width 0.14732)
		(layer "In6.Cu")
		(net "UPI_CPU0_CPU1_P2P2_DP<19>")
	)
	(segment
		(start 76.076048 -360.440224)
		(end 72.549258 -351.935542)
		(width 0.14732)
		(layer "In6.Cu")
		(net "UPI_CPU0_CPU1_P2P2_DP<19>")
	)
	(segment
		(start 246.983504 -361.550458)
		(end 246.142764 -360.3498)
		(width 0.14732)
		(layer "In6.Cu")
		(net "UPI_CPU0_CPU1_P2P2_DP<19>")
	)
	(segment
		(start 241.917474 -362.933234)
		(end 241.247168 -363.402372)
		(width 0.14732)
		(layer "In6.Cu")
		(net "UPI_CPU0_CPU1_P2P2_DP<19>")
	)
	(segment
		(start 244.968522 -361.171998)
		(end 245.809262 -362.372656)
		(width 0.14732)
		(layer "In6.Cu")
		(net "UPI_CPU0_CPU1_P2P2_DP<19>")
	)
	(segment
		(start 199.037448 -369.54079)
		(end 159.116776 -376.57913)
		(width 0.14732)
		(layer "In6.Cu")
		(net "UPI_CPU0_CPU1_P2P2_DP<19>")
	)
	(segment
		(start 243.186712 -364.20933)
		(end 242.345972 -363.008672)
		(width 0.14732)
		(layer "In6.Cu")
		(net "UPI_CPU0_CPU1_P2P2_DP<19>")
	)
	(segment
		(start 271.169384 -335.021174)
		(end 270.689324 -334.541114)
		(width 0.14732)
		(layer "In6.Cu")
		(net "UPI_CPU0_CPU1_P2P2_DP<19>")
	)
	(segment
		(start 271.377664 -335.021174)
		(end 271.169384 -335.021174)
		(width 0.14732)
		(layer "In6.Cu")
		(net "UPI_CPU0_CPU1_P2P2_DP<19>")
	)
	(segment
		(start 270.254476 -334.54086)
		(end 269.675864 -335.119472)
		(width 0.14732)
		(layer "In6.Cu")
		(net "UPI_CPU0_CPU1_P2P2_DP<19>")
	)
	(segment
		(start 243.070126 -362.501434)
		(end 243.910866 -363.702092)
		(width 0.14732)
		(layer "In6.Cu")
		(net "UPI_CPU0_CPU1_P2P2_DP<19>")
	)
	(segment
		(start 270.689324 -334.541114)
		(end 270.254476 -334.54086)
		(width 0.14732)
		(layer "In6.Cu")
		(net "UPI_CPU0_CPU1_P2P2_DP<19>")
	)
	(segment
		(start 336.39125 -288.422334)
		(end 336.38236 -288.427414)
		(width 0.0889)
		(layer "In6.Cu")
		(net "UPI_CPU0_CPU1_P2P2_DP<19>")
	)
	(segment
		(start 291.56025 -327.076308)
		(end 291.56025 -325.95566)
		(width 0.14732)
		(layer "In6.Cu")
		(net "UPI_CPU0_CPU1_P2P2_DP<19>")
	)
	(segment
		(start 73.062084 -329.960224)
		(end 73.798176 -327.30186)
		(width 0.14732)
		(layer "In6.Cu")
		(net "UPI_CPU0_CPU1_P2P2_DP<19>")
	)
	(segment
		(start 240.447576 -364.338108)
		(end 240.019078 -364.26267)
		(width 0.14732)
		(layer "In6.Cu")
		(net "UPI_CPU0_CPU1_P2P2_DP<19>")
	)
	(segment
		(start 103.882952 -291.94506)
		(end 103.882952 -291.885116)
		(width 0.0889)
		(layer "In6.Cu")
		(net "UPI_CPU0_CPU1_P2P2_DP<19>")
	)
	(segment
		(start 245.77294 -362.577634)
		(end 245.289832 -362.916216)
		(width 0.14732)
		(layer "In6.Cu")
		(net "UPI_CPU0_CPU1_P2P2_DP<19>")
	)
	(segment
		(start 107.616498 -279.978358)
		(end 107.616498 -279.955498)
		(width 0.0889)
		(layer "In6.Cu")
		(net "UPI_CPU0_CPU1_P2P2_DP<19>")
	)
	(segment
		(start 248.514616 -358.210104)
		(end 248.086118 -358.285542)
		(width 0.14732)
		(layer "In6.Cu")
		(net "UPI_CPU0_CPU1_P2P2_DP<19>")
	)
	(segment
		(start 313.307476 -313.938666)
		(end 313.046618 -314.199524)
		(width 0.14732)
		(layer "In6.Cu")
		(net "UPI_CPU0_CPU1_P2P2_DP<19>")
	)
	(segment
		(start 247.61698 -358.955848)
		(end 247.692418 -359.384346)
		(width 0.14732)
		(layer "In6.Cu")
		(net "UPI_CPU0_CPU1_P2P2_DP<19>")
	)
	(segment
		(start 103.277924 -294.441118)
		(end 103.277924 -294.072818)
		(width 0.14732)
		(layer "In6.Cu")
		(net "UPI_CPU0_CPU1_P2P2_DP<19>")
	)
	(segment
		(start 334.867758 -290.304474)
		(end 334.852264 -290.319968)
		(width 0.0889)
		(layer "In6.Cu")
		(net "UPI_CPU0_CPU1_P2P2_DP<19>")
	)
	(segment
		(start 249.415554 -356.387146)
		(end 248.946416 -357.057452)
		(width 0.14732)
		(layer "In6.Cu")
		(net "UPI_CPU0_CPU1_P2P2_DP<19>")
	)
	(segment
		(start 103.867458 -291.960554)
		(end 103.882952 -291.94506)
		(width 0.0889)
		(layer "In6.Cu")
		(net "UPI_CPU0_CPU1_P2P2_DP<19>")
	)
	(segment
		(start 252.626876 -354.35159)
		(end 252.663198 -354.556314)
		(width 0.14732)
		(layer "In6.Cu")
		(net "UPI_CPU0_CPU1_P2P2_DP<19>")
	)
	(segment
		(start 245.714266 -360.274362)
		(end 245.04396 -360.7435)
		(width 0.14732)
		(layer "In6.Cu")
		(net "UPI_CPU0_CPU1_P2P2_DP<19>")
	)
	(segment
		(start 303.676812 -322.404994)
		(end 303.378616 -322.621402)
		(width 0.14732)
		(layer "In6.Cu")
		(net "UPI_CPU0_CPU1_P2P2_DP<19>")
	)
	(segment
		(start 105.927906 -284.520894)
		(end 105.936288 -284.516068)
		(width 0.0889)
		(layer "In6.Cu")
		(net "UPI_CPU0_CPU1_P2P2_DP<19>")
	)
	(segment
		(start 108.279946 -278.82215)
		(end 108.279692 -278.822404)
		(width 0.0889)
		(layer "In6.Cu")
		(net "UPI_CPU0_CPU1_P2P2_DP<19>")
	)
	(segment
		(start 243.81587 -361.603798)
		(end 243.145564 -362.072936)
		(width 0.14732)
		(layer "In6.Cu")
		(net "UPI_CPU0_CPU1_P2P2_DP<19>")
	)
	(segment
		(start 308.48554 -317.27013)
		(end 307.869082 -317.886588)
		(width 0.14732)
		(layer "In6.Cu")
		(net "UPI_CPU0_CPU1_P2P2_DP<19>")
	)
	(segment
		(start 268.037056 -336.75828)
		(end 268.036802 -337.193636)
		(width 0.14732)
		(layer "In6.Cu")
		(net "UPI_CPU0_CPU1_P2P2_DP<19>")
	)
	(segment
		(start 268.615668 -336.179668)
		(end 268.037056 -336.75828)
		(width 0.14732)
		(layer "In6.Cu")
		(net "UPI_CPU0_CPU1_P2P2_DP<19>")
	)
	(segment
		(start 313.880246 -313.57062)
		(end 313.5122 -313.938666)
		(width 0.14732)
		(layer "In6.Cu")
		(net "UPI_CPU0_CPU1_P2P2_DP<19>")
	)
	(segment
		(start 99.026218 -372.582948)
		(end 80.574896 -364.939072)
		(width 0.14732)
		(layer "In6.Cu")
		(net "UPI_CPU0_CPU1_P2P2_DP<19>")
	)
	(segment
		(start 98.174302 -304.423318)
		(end 98.174302 -304.423572)
		(width 0.14732)
		(layer "In6.Cu")
		(net "UPI_CPU0_CPU1_P2P2_DP<19>")
	)
	(segment
		(start 316.31509 -313.57062)
		(end 316.17031 -313.42584)
		(width 0.14732)
		(layer "In6.Cu")
		(net "UPI_CPU0_CPU1_P2P2_DP<19>")
	)
	(segment
		(start 103.133144 -296.300398)
		(end 103.277924 -296.155618)
		(width 0.14732)
		(layer "In6.Cu")
		(net "UPI_CPU0_CPU1_P2P2_DP<19>")
	)
	(segment
		(start 108.556298 -278.336502)
		(end 108.556298 -278.327866)
		(width 0.0889)
		(layer "In6.Cu")
		(net "UPI_CPU0_CPU1_P2P2_DP<19>")
	)
	(segment
		(start 305.576478 -320.178684)
		(end 305.576478 -320.546984)
		(width 0.14732)
		(layer "In6.Cu")
		(net "UPI_CPU0_CPU1_P2P2_DP<19>")
	)
	(segment
		(start 239.305084 -367.106962)
		(end 212.31225 -371.881654)
		(width 0.14732)
		(layer "In6.Cu")
		(net "UPI_CPU0_CPU1_P2P2_DP<19>")
	)
	(segment
		(start 252.324616 -355.039422)
		(end 252.119638 -355.075744)
		(width 0.14732)
		(layer "In6.Cu")
		(net "UPI_CPU0_CPU1_P2P2_DP<19>")
	)
	(segment
		(start 250.790202 -356.97414)
		(end 249.844052 -356.311708)
		(width 0.14732)
		(layer "In6.Cu")
		(net "UPI_CPU0_CPU1_P2P2_DP<19>")
	)
	(segment
		(start 103.222298 -292.604698)
		(end 103.40086 -292.426136)
		(width 0.14732)
		(layer "In6.Cu")
		(net "UPI_CPU0_CPU1_P2P2_DP<19>")
	)
	(segment
		(start 303.87925 -322.437252)
		(end 303.676812 -322.404994)
		(width 0.14732)
		(layer "In6.Cu")
		(net "UPI_CPU0_CPU1_P2P2_DP<19>")
	)
	(segment
		(start 304.826924 -321.74942)
		(end 303.87925 -322.437252)
		(width 0.14732)
		(layer "In6.Cu")
		(net "UPI_CPU0_CPU1_P2P2_DP<19>")
	)
	(segment
		(start 272.328132 -332.902306)
		(end 271.893284 -332.902052)
		(width 0.14732)
		(layer "In6.Cu")
		(net "UPI_CPU0_CPU1_P2P2_DP<19>")
	)
	(segment
		(start 266.398248 -338.397088)
		(end 266.397994 -338.832444)
		(width 0.14732)
		(layer "In6.Cu")
		(net "UPI_CPU0_CPU1_P2P2_DP<19>")
	)
	(segment
		(start 269.738856 -336.659982)
		(end 269.530576 -336.659982)
		(width 0.14732)
		(layer "In6.Cu")
		(net "UPI_CPU0_CPU1_P2P2_DP<19>")
	)
	(segment
		(start 106.85526 -282.900628)
		(end 106.86415 -282.895548)
		(width 0.0889)
		(layer "In6.Cu")
		(net "UPI_CPU0_CPU1_P2P2_DP<19>")
	)
	(segment
		(start 106.86415 -281.916378)
		(end 106.85526 -281.911298)
		(width 0.0889)
		(layer "In6.Cu")
		(net "UPI_CPU0_CPU1_P2P2_DP<19>")
	)
	(segment
		(start 245.809262 -362.372656)
		(end 245.77294 -362.577634)
		(width 0.14732)
		(layer "In6.Cu")
		(net "UPI_CPU0_CPU1_P2P2_DP<19>")
	)
	(segment
		(start 267.411708 -337.81873)
		(end 266.97686 -337.818476)
		(width 0.14732)
		(layer "In6.Cu")
		(net "UPI_CPU0_CPU1_P2P2_DP<19>")
	)
	(segment
		(start 269.530576 -336.659982)
		(end 269.050516 -336.179922)
		(width 0.14732)
		(layer "In6.Cu")
		(net "UPI_CPU0_CPU1_P2P2_DP<19>")
	)
	(segment
		(start 335.294224 -289.800284)
		(end 335.294224 -289.936936)
		(width 0.0889)
		(layer "In6.Cu")
		(net "UPI_CPU0_CPU1_P2P2_DP<19>")
	)
	(segment
		(start 246.142764 -360.3498)
		(end 245.714266 -360.274362)
		(width 0.14732)
		(layer "In6.Cu")
		(net "UPI_CPU0_CPU1_P2P2_DP<19>")
	)
	(segment
		(start 250.74499 -354.48875)
		(end 250.275852 -355.159056)
		(width 0.14732)
		(layer "In6.Cu")
		(net "UPI_CPU0_CPU1_P2P2_DP<19>")
	)
	(segment
		(start 250.35129 -355.587554)
		(end 251.29744 -356.249986)
		(width 0.14732)
		(layer "In6.Cu")
		(net "UPI_CPU0_CPU1_P2P2_DP<19>")
	)
	(segment
		(start 106.38536 -283.714444)
		(end 106.39425 -283.709364)
		(width 0.0889)
		(layer "In6.Cu")
		(net "UPI_CPU0_CPU1_P2P2_DP<19>")
	)
	(segment
		(start 103.277924 -296.155618)
		(end 103.277924 -295.787318)
		(width 0.14732)
		(layer "In6.Cu")
		(net "UPI_CPU0_CPU1_P2P2_DP<19>")
	)
	(segment
		(start 292.44417 -327.076308)
		(end 292.29685 -327.223628)
		(width 0.14732)
		(layer "In6.Cu")
		(net "UPI_CPU0_CPU1_P2P2_DP<19>")
	)
	(segment
		(start 104.327198 -289.078416)
		(end 104.327198 -288.917126)
		(width 0.0889)
		(layer "In6.Cu")
		(net "UPI_CPU0_CPU1_P2P2_DP<19>")
	)
	(segment
		(start 250.004326 -358.353106)
		(end 249.665744 -358.836214)
		(width 0.14732)
		(layer "In6.Cu")
		(net "UPI_CPU0_CPU1_P2P2_DP<19>")
	)
	(segment
		(start 253.449074 -353.177348)
		(end 252.502924 -352.514916)
		(width 0.14732)
		(layer "In6.Cu")
		(net "UPI_CPU0_CPU1_P2P2_DP<19>")
	)
	(segment
		(start 271.314418 -333.91602)
		(end 271.794478 -334.39608)
		(width 0.14732)
		(layer "In6.Cu")
		(net "UPI_CPU0_CPU1_P2P2_DP<19>")
	)
	(segment
		(start 336.099658 -289.131502)
		(end 335.610708 -289.620452)
		(width 0.0889)
		(layer "In6.Cu")
		(net "UPI_CPU0_CPU1_P2P2_DP<19>")
	)
	(segment
		(start 269.050516 -336.179922)
		(end 268.615668 -336.179668)
		(width 0.14732)
		(layer "In6.Cu")
		(net "UPI_CPU0_CPU1_P2P2_DP<19>")
	)
	(segment
		(start 105.45445 -285.985712)
		(end 105.44556 -285.980632)
		(width 0.0889)
		(layer "In6.Cu")
		(net "UPI_CPU0_CPU1_P2P2_DP<19>")
	)
	(segment
		(start 266.397994 -338.832444)
		(end 266.878054 -339.312504)
		(width 0.14732)
		(layer "In6.Cu")
		(net "UPI_CPU0_CPU1_P2P2_DP<19>")
	)
	(segment
		(start 105.736898 -286.48533)
		(end 105.736898 -286.456882)
		(width 0.0889)
		(layer "In6.Cu")
		(net "UPI_CPU0_CPU1_P2P2_DP<19>")
	)
	(segment
		(start 103.277924 -294.072818)
		(end 103.133144 -293.928038)
		(width 0.14732)
		(layer "In6.Cu")
		(net "UPI_CPU0_CPU1_P2P2_DP<19>")
	)
	(segment
		(start 273.811746 -332.587092)
		(end 273.016472 -333.382366)
		(width 0.14732)
		(layer "In6.Cu")
		(net "UPI_CPU0_CPU1_P2P2_DP<19>")
	)
	(segment
		(start 269.675864 -335.119472)
		(end 269.67561 -335.554828)
		(width 0.14732)
		(layer "In6.Cu")
		(net "UPI_CPU0_CPU1_P2P2_DP<19>")
	)
	(segment
		(start 104.259126 -291.508942)
		(end 104.259126 -291.305742)
		(width 0.0889)
		(layer "In6.Cu")
		(net "UPI_CPU0_CPU1_P2P2_DP<19>")
	)
	(segment
		(start 242.345972 -363.008672)
		(end 241.917474 -362.933234)
		(width 0.14732)
		(layer "In6.Cu")
		(net "UPI_CPU0_CPU1_P2P2_DP<19>")
	)
	(segment
		(start 307.869082 -317.886588)
		(end 306.336954 -317.886588)
		(width 0.14732)
		(layer "In6.Cu")
		(net "UPI_CPU0_CPU1_P2P2_DP<19>")
	)
	(segment
		(start 268.516862 -337.673696)
		(end 268.516862 -337.881976)
		(width 0.14732)
		(layer "In6.Cu")
		(net "UPI_CPU0_CPU1_P2P2_DP<19>")
	)
	(segment
		(start 277.097236 -329.804268)
		(end 277.01875 -329.993752)
		(width 0.14732)
		(layer "In6.Cu")
		(net "UPI_CPU0_CPU1_P2P2_DP<19>")
	)
	(segment
		(start 98.185986 -304.411126)
		(end 102.938072 -298.00423)
		(width 0.14732)
		(layer "In6.Cu")
		(net "UPI_CPU0_CPU1_P2P2_DP<19>")
	)
	(segment
		(start 309.647336 -316.108334)
		(end 308.951122 -316.804548)
		(width 0.14732)
		(layer "In6.Cu")
		(net "UPI_CPU0_CPU1_P2P2_DP<19>")
	)
	(segment
		(start 336.860388 -287.609026)
		(end 336.801206 -287.643062)
		(width 0.0889)
		(layer "In6.Cu")
		(net "UPI_CPU0_CPU1_P2P2_DP<19>")
	)
	(segment
		(start 212.31225 -371.881654)
		(end 199.037448 -369.54079)
		(width 0.14732)
		(layer "In6.Cu")
		(net "UPI_CPU0_CPU1_P2P2_DP<19>")
	)
	(segment
		(start 308.951122 -316.804548)
		(end 308.746398 -316.804548)
		(width 0.14732)
		(layer "In6.Cu")
		(net "UPI_CPU0_CPU1_P2P2_DP<19>")
	)
	(segment
		(start 96.834452 -305.827938)
		(end 96.847406 -305.81727)
		(width 0.14732)
		(layer "In6.Cu")
		(net "UPI_CPU0_CPU1_P2P2_DP<19>")
	)
	(segment
		(start 251.680726 -353.689158)
		(end 252.626876 -354.35159)
		(width 0.14732)
		(layer "In6.Cu")
		(net "UPI_CPU0_CPU1_P2P2_DP<19>")
	)
	(segment
		(start 105.266998 -287.299146)
		(end 105.266998 -287.28924)
		(width 0.0889)
		(layer "In6.Cu")
		(net "UPI_CPU0_CPU1_P2P2_DP<19>")
	)
	(segment
		(start 253.654052 -353.141026)
		(end 253.449074 -353.177348)
		(width 0.14732)
		(layer "In6.Cu")
		(net "UPI_CPU0_CPU1_P2P2_DP<19>")
	)
	(segment
		(start 335.610708 -289.620452)
		(end 335.474056 -289.620452)
		(width 0.0889)
		(layer "In6.Cu")
		(net "UPI_CPU0_CPU1_P2P2_DP<19>")
	)
	(segment
		(start 305.576478 -318.89573)
		(end 305.576478 -319.520824)
		(width 0.14732)
		(layer "In6.Cu")
		(net "UPI_CPU0_CPU1_P2P2_DP<19>")
	)
	(segment
		(start 105.924096 -284.52318)
		(end 105.927906 -284.520894)
		(width 0.0889)
		(layer "In6.Cu")
		(net "UPI_CPU0_CPU1_P2P2_DP<19>")
	)
	(segment
		(start 239.273334 -365.160306)
		(end 240.114074 -366.360964)
		(width 0.14732)
		(layer "In6.Cu")
		(net "UPI_CPU0_CPU1_P2P2_DP<19>")
	)
	(segment
		(start 306.336954 -317.886588)
		(end 305.83632 -318.386968)
		(width 0.14732)
		(layer "In6.Cu")
		(net "UPI_CPU0_CPU1_P2P2_DP<19>")
	)
	(segment
		(start 334.852264 -290.319968)
		(end 333.90459 -291.267642)
		(width 0.14732)
		(layer "In6.Cu")
		(net "UPI_CPU0_CPU1_P2P2_DP<19>")
	)
	(segment
		(start 266.878054 -339.520784)
		(end 266.46124 -339.937598)
		(width 0.14732)
		(layer "In6.Cu")
		(net "UPI_CPU0_CPU1_P2P2_DP<19>")
	)
	(segment
		(start 335.725262 -285.661354)
		(end 335.881726 -285.390336)
		(width 0.0889)
		(layer "In6.Cu")
		(net "UPI_CPU0_CPU1_P2P2_DP<19>")
	)
	(segment
		(start 73.798176 -327.30186)
		(end 75.021694 -324.714616)
		(width 0.14732)
		(layer "In6.Cu")
		(net "UPI_CPU0_CPU1_P2P2_DP<19>")
	)
	(segment
		(start 267.891768 -338.29879)
		(end 267.411708 -337.81873)
		(width 0.14732)
		(layer "In6.Cu")
		(net "UPI_CPU0_CPU1_P2P2_DP<19>")
	)
	(segment
		(start 266.25296 -339.937598)
		(end 265.7729 -339.457538)
		(width 0.14732)
		(layer "In6.Cu")
		(net "UPI_CPU0_CPU1_P2P2_DP<19>")
	)
	(segment
		(start 308.746398 -316.804548)
		(end 308.48554 -317.065406)
		(width 0.14732)
		(layer "In6.Cu")
		(net "UPI_CPU0_CPU1_P2P2_DP<19>")
	)
	(segment
		(start 103.40086 -292.426136)
		(end 103.401876 -292.426136)
		(width 0.14732)
		(layer "In6.Cu")
		(net "UPI_CPU0_CPU1_P2P2_DP<19>")
	)
	(segment
		(start 103.133144 -292.819582)
		(end 103.222298 -292.604698)
		(width 0.14732)
		(layer "In6.Cu")
		(net "UPI_CPU0_CPU1_P2P2_DP<19>")
	)
	(segment
		(start 249.021854 -357.48595)
		(end 249.968004 -358.148382)
		(width 0.14732)
		(layer "In6.Cu")
		(net "UPI_CPU0_CPU1_P2P2_DP<19>")
	)
	(segment
		(start 72.549258 -351.935542)
		(end 72.549258 -335.17078)
		(width 0.14732)
		(layer "In6.Cu")
		(net "UPI_CPU0_CPU1_P2P2_DP<19>")
	)
	(segment
		(start 336.569812 -288.044128)
		(end 336.569812 -288.103056)
		(width 0.0889)
		(layer "In6.Cu")
		(net "UPI_CPU0_CPU1_P2P2_DP<19>")
	)
	(segment
		(start 334.926686 -290.304474)
		(end 334.867758 -290.304474)
		(width 0.0889)
		(layer "In6.Cu")
		(net "UPI_CPU0_CPU1_P2P2_DP<19>")
	)
	(segment
		(start 291.56025 -325.95566)
		(end 291.252402 -325.647812)
		(width 0.14732)
		(layer "In6.Cu")
		(net "UPI_CPU0_CPU1_P2P2_DP<19>")
	)
	(segment
		(start 107.146344 -280.793698)
		(end 107.146344 -280.778204)
		(width 0.0889)
		(layer "In6.Cu")
		(net "UPI_CPU0_CPU1_P2P2_DP<19>")
	)
	(segment
		(start 251.29744 -356.249986)
		(end 251.333762 -356.45471)
		(width 0.14732)
		(layer "In6.Cu")
		(net "UPI_CPU0_CPU1_P2P2_DP<19>")
	)
	(segment
		(start 96.847406 -305.81727)
		(end 98.174302 -304.423318)
		(width 0.14732)
		(layer "In6.Cu")
		(net "UPI_CPU0_CPU1_P2P2_DP<19>")
	)
	(segment
		(start 305.431698 -320.033904)
		(end 305.576478 -320.178684)
		(width 0.14732)
		(layer "In6.Cu")
		(net "UPI_CPU0_CPU1_P2P2_DP<19>")
	)
	(segment
		(start 249.665744 -358.836214)
		(end 249.460766 -358.872536)
		(width 0.14732)
		(layer "In6.Cu")
		(net "UPI_CPU0_CPU1_P2P2_DP<19>")
	)
	(segment
		(start 241.49304 -365.575088)
		(end 241.288316 -365.538766)
		(width 0.14732)
		(layer "In6.Cu")
		(net "UPI_CPU0_CPU1_P2P2_DP<19>")
	)
	(segment
		(start 336.38236 -286.151066)
		(end 336.39125 -286.156146)
		(width 0.0889)
		(layer "In6.Cu")
		(net "UPI_CPU0_CPU1_P2P2_DP<19>")
	)
	(segment
		(start 242.01247 -365.031528)
		(end 241.976148 -365.236506)
		(width 0.14732)
		(layer "In6.Cu")
		(net "UPI_CPU0_CPU1_P2P2_DP<19>")
	)
	(segment
		(start 269.67561 -335.554828)
		(end 270.15567 -336.034888)
		(width 0.14732)
		(layer "In6.Cu")
		(net "UPI_CPU0_CPU1_P2P2_DP<19>")
	)
	(segment
		(start 104.50576 -288.597848)
		(end 104.51465 -288.592768)
		(width 0.0889)
		(layer "In6.Cu")
		(net "UPI_CPU0_CPU1_P2P2_DP<19>")
	)
	(segment
		(start 103.716328 -292.111684)
		(end 103.716328 -292.110668)
		(width 0.14732)
		(layer "In6.Cu")
		(net "UPI_CPU0_CPU1_P2P2_DP<19>")
	)
	(segment
		(start 240.114074 -366.360964)
		(end 240.077752 -366.565942)
		(width 0.14732)
		(layer "In6.Cu")
		(net "UPI_CPU0_CPU1_P2P2_DP<19>")
	)
	(segment
		(start 248.270776 -360.828844)
		(end 247.188482 -361.58678)
		(width 0.14732)
		(layer "In6.Cu")
		(net "UPI_CPU0_CPU1_P2P2_DP<19>")
	)
	(arc
		(start 105.45445 -285.336996)
		(mid 105.657273 -285.136765)
		(end 105.736644 -284.863032)
		(width 0.0889)
		(layer "In6.Cu")
		(net "UPI_CPU0_CPU1_P2P2_DP<19>")
	)
	(arc
		(start 104.79659 -289.610292)
		(mid 104.68536 -289.417088)
		(end 104.511094 -289.27806)
		(width 0.0889)
		(layer "In6.Cu")
		(net "UPI_CPU0_CPU1_P2P2_DP<19>")
	)
	(arc
		(start 335.959958 -285.369508)
		(mid 336.063103 -285.499533)
		(end 336.099912 -285.661354)
		(width 0.0889)
		(layer "In6.Cu")
		(net "UPI_CPU0_CPU1_P2P2_DP<19>")
	)
	(arc
		(start 104.327198 -288.917126)
		(mid 104.374877 -288.734226)
		(end 104.50576 -288.597848)
		(width 0.0889)
		(layer "In6.Cu")
		(net "UPI_CPU0_CPU1_P2P2_DP<19>")
	)
	(arc
		(start 106.86415 -281.267662)
		(mid 107.066973 -281.067431)
		(end 107.146344 -280.793698)
		(width 0.0889)
		(layer "In6.Cu")
		(net "UPI_CPU0_CPU1_P2P2_DP<19>")
	)
	(arc
		(start 108.086144 -279.150318)
		(mid 108.133823 -278.967418)
		(end 108.264706 -278.83104)
		(width 0.0889)
		(layer "In6.Cu")
		(net "UPI_CPU0_CPU1_P2P2_DP<19>")
	)
	(arc
		(start 336.569812 -286.48533)
		(mid 336.647923 -286.762279)
		(end 336.85226 -286.964882)
		(width 0.0889)
		(layer "In6.Cu")
		(net "UPI_CPU0_CPU1_P2P2_DP<19>")
	)
	(arc
		(start 336.86115 -286.969962)
		(mid 337.039747 -287.28924)
		(end 336.86115 -287.608518)
		(width 0.0889)
		(layer "In6.Cu")
		(net "UPI_CPU0_CPU1_P2P2_DP<19>")
	)
	(arc
		(start 105.936288 -284.516068)
		(mid 106.134516 -284.31022)
		(end 106.206798 -284.033722)
		(width 0.0889)
		(layer "In6.Cu")
		(net "UPI_CPU0_CPU1_P2P2_DP<19>")
	)
	(arc
		(start 104.797098 -288.103056)
		(mid 104.844777 -287.920156)
		(end 104.97566 -287.783778)
		(width 0.0889)
		(layer "In6.Cu")
		(net "UPI_CPU0_CPU1_P2P2_DP<19>")
	)
	(arc
		(start 104.51465 -288.592768)
		(mid 104.716936 -288.393787)
		(end 104.797098 -288.121598)
		(width 0.0889)
		(layer "In6.Cu")
		(net "UPI_CPU0_CPU1_P2P2_DP<19>")
	)
	(arc
		(start 107.146344 -282.390342)
		(mid 107.066974 -282.116608)
		(end 106.86415 -281.916378)
		(width 0.0889)
		(layer "In6.Cu")
		(net "UPI_CPU0_CPU1_P2P2_DP<19>")
	)
	(arc
		(start 106.400346 -283.705808)
		(mid 106.602759 -283.499395)
		(end 106.676698 -283.219906)
		(width 0.0889)
		(layer "In6.Cu")
		(net "UPI_CPU0_CPU1_P2P2_DP<19>")
	)
	(arc
		(start 107.333796 -280.453846)
		(mid 107.537277 -280.253042)
		(end 107.616498 -279.978358)
		(width 0.0889)
		(layer "In6.Cu")
		(net "UPI_CPU0_CPU1_P2P2_DP<19>")
	)
	(arc
		(start 105.44556 -285.980632)
		(mid 105.314646 -285.844272)
		(end 105.266998 -285.661354)
		(width 0.0889)
		(layer "In6.Cu")
		(net "UPI_CPU0_CPU1_P2P2_DP<19>")
	)
	(arc
		(start 105.45445 -286.964882)
		(mid 105.658785 -286.762277)
		(end 105.736898 -286.48533)
		(width 0.0889)
		(layer "In6.Cu")
		(net "UPI_CPU0_CPU1_P2P2_DP<19>")
	)
	(arc
		(start 336.801206 -287.643062)
		(mid 336.631817 -287.812616)
		(end 336.569812 -288.044128)
		(width 0.0889)
		(layer "In6.Cu")
		(net "UPI_CPU0_CPU1_P2P2_DP<19>")
	)
	(arc
		(start 106.676698 -283.219906)
		(mid 106.724377 -283.037006)
		(end 106.85526 -282.900628)
		(width 0.0889)
		(layer "In6.Cu")
		(net "UPI_CPU0_CPU1_P2P2_DP<19>")
	)
	(arc
		(start 336.099912 -285.679896)
		(mid 336.180074 -285.952085)
		(end 336.38236 -286.151066)
		(width 0.0889)
		(layer "In6.Cu")
		(net "UPI_CPU0_CPU1_P2P2_DP<19>")
	)
	(arc
		(start 336.38236 -288.427414)
		(mid 336.178879 -288.628218)
		(end 336.099658 -288.902902)
		(width 0.0889)
		(layer "In6.Cu")
		(net "UPI_CPU0_CPU1_P2P2_DP<19>")
	)
	(arc
		(start 105.736644 -284.847538)
		(mid 105.784323 -284.664638)
		(end 105.915206 -284.52826)
		(width 0.0889)
		(layer "In6.Cu")
		(net "UPI_CPU0_CPU1_P2P2_DP<19>")
	)
	(arc
		(start 108.279692 -278.822404)
		(mid 108.482279 -278.616053)
		(end 108.556298 -278.336502)
		(width 0.0889)
		(layer "In6.Cu")
		(net "UPI_CPU0_CPU1_P2P2_DP<19>")
	)
	(arc
		(start 104.511348 -289.277806)
		(mid 104.402201 -289.193878)
		(end 104.327198 -289.078416)
		(width 0.0889)
		(layer "In6.Cu")
		(net "UPI_CPU0_CPU1_P2P2_DP<19>")
	)
	(arc
		(start 104.98455 -287.778698)
		(mid 105.188885 -287.576093)
		(end 105.266998 -287.299146)
		(width 0.0889)
		(layer "In6.Cu")
		(net "UPI_CPU0_CPU1_P2P2_DP<19>")
	)
	(arc
		(start 109.019848 -277.6093)
		(mid 109.021348 -277.598518)
		(end 109.022642 -277.58771)
		(width 0.0889)
		(layer "In6.Cu")
		(net "UPI_CPU0_CPU1_P2P2_DP<19>")
	)
	(arc
		(start 106.206798 -284.033722)
		(mid 106.254477 -283.850822)
		(end 106.38536 -283.714444)
		(width 0.0889)
		(layer "In6.Cu")
		(net "UPI_CPU0_CPU1_P2P2_DP<19>")
	)
	(arc
		(start 106.85526 -281.911298)
		(mid 106.676784 -281.59202)
		(end 106.85526 -281.272742)
		(width 0.0889)
		(layer "In6.Cu")
		(net "UPI_CPU0_CPU1_P2P2_DP<19>")
	)
	(arc
		(start 105.266998 -285.661354)
		(mid 105.314677 -285.478454)
		(end 105.44556 -285.342076)
		(width 0.0889)
		(layer "In6.Cu")
		(net "UPI_CPU0_CPU1_P2P2_DP<19>")
	)
	(arc
		(start 336.39125 -286.156146)
		(mid 336.522164 -286.292506)
		(end 336.569812 -286.475424)
		(width 0.0889)
		(layer "In6.Cu")
		(net "UPI_CPU0_CPU1_P2P2_DP<19>")
	)
	(arc
		(start 105.266998 -287.28924)
		(mid 105.314677 -287.10634)
		(end 105.44556 -286.969962)
		(width 0.0889)
		(layer "In6.Cu")
		(net "UPI_CPU0_CPU1_P2P2_DP<19>")
	)
	(arc
		(start 107.616498 -279.955498)
		(mid 107.668768 -279.773133)
		(end 107.803696 -279.639776)
		(width 0.0889)
		(layer "In6.Cu")
		(net "UPI_CPU0_CPU1_P2P2_DP<19>")
	)
	(arc
		(start 107.146344 -280.778204)
		(mid 107.194023 -280.595304)
		(end 107.324906 -280.458926)
		(width 0.0889)
		(layer "In6.Cu")
		(net "UPI_CPU0_CPU1_P2P2_DP<19>")
	)
	(arc
		(start 336.569812 -288.103056)
		(mid 336.522133 -288.285956)
		(end 336.39125 -288.422334)
		(width 0.0889)
		(layer "In6.Cu")
		(net "UPI_CPU0_CPU1_P2P2_DP<19>")
	)
	(arc
		(start 108.743496 -278.012144)
		(mid 108.92741 -277.842099)
		(end 109.019848 -277.6093)
		(width 0.0889)
		(layer "In6.Cu")
		(net "UPI_CPU0_CPU1_P2P2_DP<19>")
	)
	(arc
		(start 106.86415 -282.895548)
		(mid 107.065432 -282.698061)
		(end 107.146344 -282.427934)
		(width 0.0889)
		(layer "In6.Cu")
		(net "UPI_CPU0_CPU1_P2P2_DP<19>")
	)
	(arc
		(start 105.736898 -286.456882)
		(mid 105.656736 -286.184693)
		(end 105.45445 -285.985712)
		(width 0.0889)
		(layer "In6.Cu")
		(net "UPI_CPU0_CPU1_P2P2_DP<19>")
	)
	(arc
		(start 107.803696 -279.639776)
		(mid 108.008031 -279.437171)
		(end 108.086144 -279.160224)
		(width 0.0889)
		(layer "In6.Cu")
		(net "UPI_CPU0_CPU1_P2P2_DP<19>")
	)
	(arc
		(start 108.556298 -278.327866)
		(mid 108.608568 -278.145501)
		(end 108.743496 -278.012144)
		(width 0.0889)
		(layer "In6.Cu")
		(net "UPI_CPU0_CPU1_P2P2_DP<19>")
	)
	(segment
		(start 339.954616 -281.591766)
		(end 339.954362 -281.59202)
		(width 0.13208)
		(layer "F.Cu")
		(net "UPI_CPU0_CPU1_P2P2_DP<18>")
	)
	(segment
		(start 107.990894 -278.336248)
		(end 107.991148 -278.336502)
		(width 0.13208)
		(layer "F.Cu")
		(net "UPI_CPU0_CPU1_P2P2_DP<18>")
	)
	(segment
		(start 107.990894 -277.800562)
		(end 107.990894 -278.336248)
		(width 0.13208)
		(layer "F.Cu")
		(net "UPI_CPU0_CPU1_P2P2_DP<18>")
	)
	(segment
		(start 339.954362 -281.05608)
		(end 339.954616 -281.056334)
		(width 0.13208)
		(layer "F.Cu")
		(net "UPI_CPU0_CPU1_P2P2_DP<18>")
	)
	(segment
		(start 339.954616 -281.056334)
		(end 339.954616 -281.591766)
		(width 0.13208)
		(layer "F.Cu")
		(net "UPI_CPU0_CPU1_P2P2_DP<18>")
	)
	(segment
		(start 104.418892 -286.799782)
		(end 104.427782 -286.794702)
		(width 0.0889)
		(layer "In6.Cu")
		(net "UPI_CPU0_CPU1_P2P2_DP<18>")
	)
	(segment
		(start 103.479346 -288.427414)
		(end 103.488236 -288.422334)
		(width 0.0889)
		(layer "In6.Cu")
		(net "UPI_CPU0_CPU1_P2P2_DP<18>")
	)
	(segment
		(start 258.291076 -349.883984)
		(end 257.874262 -350.300798)
		(width 0.14732)
		(layer "In6.Cu")
		(net "UPI_CPU0_CPU1_P2P2_DP<18>")
	)
	(segment
		(start 338.827364 -282.895548)
		(end 338.818474 -282.900628)
		(width 0.0889)
		(layer "In6.Cu")
		(net "UPI_CPU0_CPU1_P2P2_DP<18>")
	)
	(segment
		(start 105.358184 -283.544772)
		(end 105.358946 -283.544264)
		(width 0.0889)
		(layer "In6.Cu")
		(net "UPI_CPU0_CPU1_P2P2_DP<18>")
	)
	(segment
		(start 79.962756 -365.891572)
		(end 74.903076 -360.830114)
		(width 0.14732)
		(layer "In6.Cu")
		(net "UPI_CPU0_CPU1_P2P2_DP<18>")
	)
	(segment
		(start 336.383376 -290.514024)
		(end 335.663032 -291.234368)
		(width 0.14732)
		(layer "In6.Cu")
		(net "UPI_CPU0_CPU1_P2P2_DP<18>")
	)
	(segment
		(start 257.874262 -350.509078)
		(end 260.561074 -353.19589)
		(width 0.14732)
		(layer "In6.Cu")
		(net "UPI_CPU0_CPU1_P2P2_DP<18>")
	)
	(segment
		(start 101.943408 -297.489372)
		(end 102.020116 -297.304714)
		(width 0.14732)
		(layer "In6.Cu")
		(net "UPI_CPU0_CPU1_P2P2_DP<18>")
	)
	(segment
		(start 307.636672 -320.133218)
		(end 307.130958 -320.3321)
		(width 0.14732)
		(layer "In6.Cu")
		(net "UPI_CPU0_CPU1_P2P2_DP<18>")
	)
	(segment
		(start 249.047508 -361.982766)
		(end 240.333784 -368.0841)
		(width 0.14732)
		(layer "In6.Cu")
		(net "UPI_CPU0_CPU1_P2P2_DP<18>")
	)
	(segment
		(start 337.887564 -287.778698)
		(end 337.878674 -287.783778)
		(width 0.0889)
		(layer "In6.Cu")
		(net "UPI_CPU0_CPU1_P2P2_DP<18>")
	)
	(segment
		(start 276.84349 -331.33157)
		(end 261.151878 -347.023182)
		(width 0.14732)
		(layer "In6.Cu")
		(net "UPI_CPU0_CPU1_P2P2_DP<18>")
	)
	(segment
		(start 337.41741 -288.592768)
		(end 337.40852 -288.597848)
		(width 0.0889)
		(layer "In6.Cu")
		(net "UPI_CPU0_CPU1_P2P2_DP<18>")
	)
	(segment
		(start 316.267592 -315.708792)
		(end 314.088018 -315.708792)
		(width 0.14732)
		(layer "In6.Cu")
		(net "UPI_CPU0_CPU1_P2P2_DP<18>")
	)
	(segment
		(start 255.7145 -352.460306)
		(end 249.047508 -361.982766)
		(width 0.14732)
		(layer "In6.Cu")
		(net "UPI_CPU0_CPU1_P2P2_DP<18>")
	)
	(segment
		(start 333.221584 -294.45585)
		(end 331.34935 -300.627288)
		(width 0.14732)
		(layer "In6.Cu")
		(net "UPI_CPU0_CPU1_P2P2_DP<18>")
	)
	(segment
		(start 338.357464 -283.709364)
		(end 338.356702 -283.709872)
		(width 0.0889)
		(layer "In6.Cu")
		(net "UPI_CPU0_CPU1_P2P2_DP<18>")
	)
	(segment
		(start 299.936662 -326.84593)
		(end 299.936662 -327.29424)
		(width 0.14732)
		(layer "In6.Cu")
		(net "UPI_CPU0_CPU1_P2P2_DP<18>")
	)
	(segment
		(start 337.887564 -284.52318)
		(end 337.878674 -284.52826)
		(width 0.0889)
		(layer "In6.Cu")
		(net "UPI_CPU0_CPU1_P2P2_DP<18>")
	)
	(segment
		(start 307.130958 -320.3321)
		(end 306.86883 -320.57594)
		(width 0.14732)
		(layer "In6.Cu")
		(net "UPI_CPU0_CPU1_P2P2_DP<18>")
	)
	(segment
		(start 258.499356 -349.883984)
		(end 258.291076 -349.883984)
		(width 0.14732)
		(layer "In6.Cu")
		(net "UPI_CPU0_CPU1_P2P2_DP<18>")
	)
	(segment
		(start 104.136444 -285.679896)
		(end 104.136444 -285.661354)
		(width 0.0889)
		(layer "In6.Cu")
		(net "UPI_CPU0_CPU1_P2P2_DP<18>")
	)
	(segment
		(start 105.546398 -279.964134)
		(end 105.546398 -279.954228)
		(width 0.0889)
		(layer "In6.Cu")
		(net "UPI_CPU0_CPU1_P2P2_DP<18>")
	)
	(segment
		(start 212.311996 -373.023638)
		(end 199.040242 -370.683282)
		(width 0.14732)
		(layer "In6.Cu")
		(net "UPI_CPU0_CPU1_P2P2_DP<18>")
	)
	(segment
		(start 262.898636 -352.691192)
		(end 262.320278 -353.26955)
		(width 0.14732)
		(layer "In6.Cu")
		(net "UPI_CPU0_CPU1_P2P2_DP<18>")
	)
	(segment
		(start 74.087228 -324.086728)
		(end 81.592674 -316.580774)
		(width 0.14732)
		(layer "In6.Cu")
		(net "UPI_CPU0_CPU1_P2P2_DP<18>")
	)
	(segment
		(start 337.700112 -288.103056)
		(end 337.700112 -288.11728)
		(width 0.0889)
		(layer "In6.Cu")
		(net "UPI_CPU0_CPU1_P2P2_DP<18>")
	)
	(segment
		(start 105.837482 -282.086558)
		(end 105.828592 -282.081478)
		(width 0.0889)
		(layer "In6.Cu")
		(net "UPI_CPU0_CPU1_P2P2_DP<18>")
	)
	(segment
		(start 337.899756 -287.771586)
		(end 337.891628 -287.776412)
		(width 0.0889)
		(layer "In6.Cu")
		(net "UPI_CPU0_CPU1_P2P2_DP<18>")
	)
	(segment
		(start 314.088018 -315.708792)
		(end 313.703208 -315.868304)
		(width 0.14732)
		(layer "In6.Cu")
		(net "UPI_CPU0_CPU1_P2P2_DP<18>")
	)
	(segment
		(start 106.016298 -279.150318)
		(end 106.016298 -279.140412)
		(width 0.0889)
		(layer "In6.Cu")
		(net "UPI_CPU0_CPU1_P2P2_DP<18>")
	)
	(segment
		(start 262.824976 -350.931988)
		(end 260.138164 -348.245176)
		(width 0.14732)
		(layer "In6.Cu")
		(net "UPI_CPU0_CPU1_P2P2_DP<18>")
	)
	(segment
		(start 313.026806 -316.55766)
		(end 312.59653 -316.987936)
		(width 0.14732)
		(layer "In6.Cu")
		(net "UPI_CPU0_CPU1_P2P2_DP<18>")
	)
	(segment
		(start 260.561074 -353.631246)
		(end 259.982716 -354.209604)
		(width 0.14732)
		(layer "In6.Cu")
		(net "UPI_CPU0_CPU1_P2P2_DP<18>")
	)
	(segment
		(start 263.260332 -350.931988)
		(end 262.824976 -350.931988)
		(width 0.14732)
		(layer "In6.Cu")
		(net "UPI_CPU0_CPU1_P2P2_DP<18>")
	)
	(segment
		(start 263.83869 -350.35363)
		(end 263.260332 -350.931988)
		(width 0.14732)
		(layer "In6.Cu")
		(net "UPI_CPU0_CPU1_P2P2_DP<18>")
	)
	(segment
		(start 305.980084 -322.354194)
		(end 302.843438 -324.550024)
		(width 0.14732)
		(layer "In6.Cu")
		(net "UPI_CPU0_CPU1_P2P2_DP<18>")
	)
	(segment
		(start 74.903076 -360.830114)
		(end 71.439278 -352.480372)
		(width 0.14732)
		(layer "In6.Cu")
		(net "UPI_CPU0_CPU1_P2P2_DP<18>")
	)
	(segment
		(start 71.96709 -329.78217)
		(end 72.775572 -326.862186)
		(width 0.14732)
		(layer "In6.Cu")
		(net "UPI_CPU0_CPU1_P2P2_DP<18>")
	)
	(segment
		(start 339.110066 -282.405836)
		(end 339.110066 -282.42006)
		(width 0.0889)
		(layer "In6.Cu")
		(net "UPI_CPU0_CPU1_P2P2_DP<18>")
	)
	(segment
		(start 259.54736 -354.209604)
		(end 256.860548 -351.522792)
		(width 0.14732)
		(layer "In6.Cu")
		(net "UPI_CPU0_CPU1_P2P2_DP<18>")
	)
	(segment
		(start 108.086144 -277.506938)
		(end 108.086144 -277.54453)
		(width 0.0889)
		(layer "In6.Cu")
		(net "UPI_CPU0_CPU1_P2P2_DP<18>")
	)
	(segment
		(start 261.884922 -353.26955)
		(end 258.499356 -349.883984)
		(width 0.14732)
		(layer "In6.Cu")
		(net "UPI_CPU0_CPU1_P2P2_DP<18>")
	)
	(segment
		(start 103.666798 -288.103056)
		(end 103.666798 -288.087562)
		(width 0.0889)
		(layer "In6.Cu")
		(net "UPI_CPU0_CPU1_P2P2_DP<18>")
	)
	(segment
		(start 106.768392 -277.84679)
		(end 106.777282 -277.84171)
		(width 0.0889)
		(layer "In6.Cu")
		(net "UPI_CPU0_CPU1_P2P2_DP<18>")
	)
	(segment
		(start 331.34935 -300.627288)
		(end 316.267592 -315.708792)
		(width 0.14732)
		(layer "In6.Cu")
		(net "UPI_CPU0_CPU1_P2P2_DP<18>")
	)
	(segment
		(start 260.138164 -348.245176)
		(end 259.929884 -348.245176)
		(width 0.14732)
		(layer "In6.Cu")
		(net "UPI_CPU0_CPU1_P2P2_DP<18>")
	)
	(segment
		(start 72.775572 -326.862186)
		(end 74.087228 -324.086728)
		(width 0.14732)
		(layer "In6.Cu")
		(net "UPI_CPU0_CPU1_P2P2_DP<18>")
	)
	(segment
		(start 104.412796 -286.803338)
		(end 104.418892 -286.799782)
		(width 0.0889)
		(layer "In6.Cu")
		(net "UPI_CPU0_CPU1_P2P2_DP<18>")
	)
	(segment
		(start 105.828846 -279.474676)
		(end 105.837736 -279.469596)
		(width 0.0889)
		(layer "In6.Cu")
		(net "UPI_CPU0_CPU1_P2P2_DP<18>")
	)
	(segment
		(start 262.898636 -352.255836)
		(end 262.898636 -352.691192)
		(width 0.14732)
		(layer "In6.Cu")
		(net "UPI_CPU0_CPU1_P2P2_DP<18>")
	)
	(segment
		(start 302.843438 -324.550024)
		(end 301.80026 -324.982332)
		(width 0.14732)
		(layer "In6.Cu")
		(net "UPI_CPU0_CPU1_P2P2_DP<18>")
	)
	(segment
		(start 338.170012 -284.033722)
		(end 338.170012 -284.043628)
		(width 0.0889)
		(layer "In6.Cu")
		(net "UPI_CPU0_CPU1_P2P2_DP<18>")
	)
	(segment
		(start 260.561074 -353.19589)
		(end 260.561074 -353.631246)
		(width 0.14732)
		(layer "In6.Cu")
		(net "UPI_CPU0_CPU1_P2P2_DP<18>")
	)
	(segment
		(start 338.639912 -283.219906)
		(end 338.639912 -283.229812)
		(width 0.0889)
		(layer "In6.Cu")
		(net "UPI_CPU0_CPU1_P2P2_DP<18>")
	)
	(segment
		(start 283.912056 -328.403458)
		(end 276.84349 -331.33157)
		(width 0.14732)
		(layer "In6.Cu")
		(net "UPI_CPU0_CPU1_P2P2_DP<18>")
	)
	(segment
		(start 262.320278 -353.26955)
		(end 261.884922 -353.26955)
		(width 0.14732)
		(layer "In6.Cu")
		(net "UPI_CPU0_CPU1_P2P2_DP<18>")
	)
	(segment
		(start 298.827444 -328.403458)
		(end 283.912056 -328.403458)
		(width 0.14732)
		(layer "In6.Cu")
		(net "UPI_CPU0_CPU1_P2P2_DP<18>")
	)
	(segment
		(start 299.936662 -327.29424)
		(end 298.827444 -328.403458)
		(width 0.14732)
		(layer "In6.Cu")
		(net "UPI_CPU0_CPU1_P2P2_DP<18>")
	)
	(segment
		(start 261.151878 -347.023182)
		(end 261.151878 -347.231462)
		(width 0.14732)
		(layer "In6.Cu")
		(net "UPI_CPU0_CPU1_P2P2_DP<18>")
	)
	(segment
		(start 102.020116 -297.304714)
		(end 102.020116 -293.509446)
		(width 0.14732)
		(layer "In6.Cu")
		(net "UPI_CPU0_CPU1_P2P2_DP<18>")
	)
	(segment
		(start 104.606344 -284.856174)
		(end 104.606344 -284.837632)
		(width 0.0889)
		(layer "In6.Cu")
		(net "UPI_CPU0_CPU1_P2P2_DP<18>")
	)
	(segment
		(start 338.356702 -283.709872)
		(end 338.348574 -283.714444)
		(width 0.0889)
		(layer "In6.Cu")
		(net "UPI_CPU0_CPU1_P2P2_DP<18>")
	)
	(segment
		(start 257.874262 -350.300798)
		(end 257.874262 -350.509078)
		(width 0.14732)
		(layer "In6.Cu")
		(net "UPI_CPU0_CPU1_P2P2_DP<18>")
	)
	(segment
		(start 256.860548 -351.522792)
		(end 256.652268 -351.522792)
		(width 0.14732)
		(layer "In6.Cu")
		(net "UPI_CPU0_CPU1_P2P2_DP<18>")
	)
	(segment
		(start 102.020116 -293.487348)
		(end 102.062026 -293.445438)
		(width 0.0889)
		(layer "In6.Cu")
		(net "UPI_CPU0_CPU1_P2P2_DP<18>")
	)
	(segment
		(start 306.86883 -320.57594)
		(end 305.980084 -322.354194)
		(width 0.14732)
		(layer "In6.Cu")
		(net "UPI_CPU0_CPU1_P2P2_DP<18>")
	)
	(segment
		(start 301.80026 -324.982332)
		(end 299.936662 -326.84593)
		(width 0.14732)
		(layer "In6.Cu")
		(net "UPI_CPU0_CPU1_P2P2_DP<18>")
	)
	(segment
		(start 337.229704 -289.176206)
		(end 336.753454 -289.652456)
		(width 0.0889)
		(layer "In6.Cu")
		(net "UPI_CPU0_CPU1_P2P2_DP<18>")
	)
	(segment
		(start 159.215582 -377.70435)
		(end 125.977904 -377.70435)
		(width 0.14732)
		(layer "In6.Cu")
		(net "UPI_CPU0_CPU1_P2P2_DP<18>")
	)
	(segment
		(start 259.982716 -354.209604)
		(end 259.54736 -354.209604)
		(width 0.14732)
		(layer "In6.Cu")
		(net "UPI_CPU0_CPU1_P2P2_DP<18>")
	)
	(segment
		(start 104.888792 -284.35808)
		(end 104.897682 -284.353)
		(width 0.0889)
		(layer "In6.Cu")
		(net "UPI_CPU0_CPU1_P2P2_DP<18>")
	)
	(segment
		(start 103.948992 -287.613598)
		(end 103.950008 -287.61309)
		(width 0.0889)
		(layer "In6.Cu")
		(net "UPI_CPU0_CPU1_P2P2_DP<18>")
	)
	(segment
		(start 337.417664 -285.336996)
		(end 337.408774 -285.342076)
		(width 0.0889)
		(layer "In6.Cu")
		(net "UPI_CPU0_CPU1_P2P2_DP<18>")
	)
	(segment
		(start 336.753454 -290.084002)
		(end 336.39887 -290.438586)
		(width 0.0889)
		(layer "In6.Cu")
		(net "UPI_CPU0_CPU1_P2P2_DP<18>")
	)
	(segment
		(start 106.486198 -278.336502)
		(end 106.486198 -278.314404)
		(width 0.0889)
		(layer "In6.Cu")
		(net "UPI_CPU0_CPU1_P2P2_DP<18>")
	)
	(segment
		(start 313.703208 -315.868304)
		(end 313.026806 -316.54496)
		(width 0.14732)
		(layer "In6.Cu")
		(net "UPI_CPU0_CPU1_P2P2_DP<18>")
	)
	(segment
		(start 102.062026 -293.445438)
		(end 102.062026 -291.827458)
		(width 0.0889)
		(layer "In6.Cu")
		(net "UPI_CPU0_CPU1_P2P2_DP<18>")
	)
	(segment
		(start 102.062026 -291.827458)
		(end 103.666544 -290.22294)
		(width 0.0889)
		(layer "In6.Cu")
		(net "UPI_CPU0_CPU1_P2P2_DP<18>")
	)
	(segment
		(start 105.358946 -281.267662)
		(end 105.35285 -281.264106)
		(width 0.0889)
		(layer "In6.Cu")
		(net "UPI_CPU0_CPU1_P2P2_DP<18>")
	)
	(segment
		(start 106.298746 -278.66086)
		(end 106.307636 -278.65578)
		(width 0.0889)
		(layer "In6.Cu")
		(net "UPI_CPU0_CPU1_P2P2_DP<18>")
	)
	(segment
		(start 337.891628 -287.776412)
		(end 337.887564 -287.778698)
		(width 0.0889)
		(layer "In6.Cu")
		(net "UPI_CPU0_CPU1_P2P2_DP<18>")
	)
	(segment
		(start 102.020116 -293.509446)
		(end 102.020116 -293.487348)
		(width 0.0889)
		(layer "In6.Cu")
		(net "UPI_CPU0_CPU1_P2P2_DP<18>")
	)
	(segment
		(start 125.977904 -377.70435)
		(end 98.720656 -373.660924)
		(width 0.14732)
		(layer "In6.Cu")
		(net "UPI_CPU0_CPU1_P2P2_DP<18>")
	)
	(segment
		(start 335.663032 -291.234368)
		(end 335.662016 -291.234368)
		(width 0.14732)
		(layer "In6.Cu")
		(net "UPI_CPU0_CPU1_P2P2_DP<18>")
	)
	(segment
		(start 337.887564 -286.799782)
		(end 337.899756 -286.806894)
		(width 0.0889)
		(layer "In6.Cu")
		(net "UPI_CPU0_CPU1_P2P2_DP<18>")
	)
	(segment
		(start 107.253786 -277.024338)
		(end 107.253278 -277.024338)
		(width 0.0889)
		(layer "In6.Cu")
		(net "UPI_CPU0_CPU1_P2P2_DP<18>")
	)
	(segment
		(start 339.641688 -281.59202)
		(end 339.576156 -281.657552)
		(width 0.0889)
		(layer "In6.Cu")
		(net "UPI_CPU0_CPU1_P2P2_DP<18>")
	)
	(segment
		(start 337.700112 -284.847538)
		(end 337.700112 -284.857444)
		(width 0.0889)
		(layer "In6.Cu")
		(net "UPI_CPU0_CPU1_P2P2_DP<18>")
	)
	(segment
		(start 71.439278 -335.14284)
		(end 71.96709 -329.78217)
		(width 0.14732)
		(layer "In6.Cu")
		(net "UPI_CPU0_CPU1_P2P2_DP<18>")
	)
	(segment
		(start 309.745634 -318.168782)
		(end 307.636672 -320.133218)
		(width 0.14732)
		(layer "In6.Cu")
		(net "UPI_CPU0_CPU1_P2P2_DP<18>")
	)
	(segment
		(start 335.662016 -291.234368)
		(end 334.800448 -292.095936)
		(width 0.14732)
		(layer "In6.Cu")
		(net "UPI_CPU0_CPU1_P2P2_DP<18>")
	)
	(segment
		(start 105.358946 -280.288492)
		(end 105.367836 -280.283412)
		(width 0.0889)
		(layer "In6.Cu")
		(net "UPI_CPU0_CPU1_P2P2_DP<18>")
	)
	(segment
		(start 105.546144 -283.228542)
		(end 105.546144 -283.201364)
		(width 0.0889)
		(layer "In6.Cu")
		(net "UPI_CPU0_CPU1_P2P2_DP<18>")
	)
	(segment
		(start 103.950008 -287.61309)
		(end 103.957882 -287.608518)
		(width 0.0889)
		(layer "In6.Cu")
		(net "UPI_CPU0_CPU1_P2P2_DP<18>")
	)
	(segment
		(start 337.700366 -286.4612)
		(end 337.700366 -286.48406)
		(width 0.0889)
		(layer "In6.Cu")
		(net "UPI_CPU0_CPU1_P2P2_DP<18>")
	)
	(segment
		(start 103.666544 -290.22294)
		(end 103.666544 -289.645852)
		(width 0.0889)
		(layer "In6.Cu")
		(net "UPI_CPU0_CPU1_P2P2_DP<18>")
	)
	(segment
		(start 71.439278 -352.480372)
		(end 71.439278 -335.14284)
		(width 0.14732)
		(layer "In6.Cu")
		(net "UPI_CPU0_CPU1_P2P2_DP<18>")
	)
	(segment
		(start 107.858814 -277.97633)
		(end 107.834684 -278.065484)
		(width 0.0889)
		(layer "In6.Cu")
		(net "UPI_CPU0_CPU1_P2P2_DP<18>")
	)
	(segment
		(start 312.59653 -316.987936)
		(end 309.745634 -318.168782)
		(width 0.14732)
		(layer "In6.Cu")
		(net "UPI_CPU0_CPU1_P2P2_DP<18>")
	)
	(segment
		(start 240.333784 -368.0841)
		(end 212.311996 -373.023638)
		(width 0.14732)
		(layer "In6.Cu")
		(net "UPI_CPU0_CPU1_P2P2_DP<18>")
	)
	(segment
		(start 313.026806 -316.54496)
		(end 313.026806 -316.55766)
		(width 0.14732)
		(layer "In6.Cu")
		(net "UPI_CPU0_CPU1_P2P2_DP<18>")
	)
	(segment
		(start 337.408774 -285.980632)
		(end 337.417664 -285.985712)
		(width 0.0889)
		(layer "In6.Cu")
		(net "UPI_CPU0_CPU1_P2P2_DP<18>")
	)
	(segment
		(start 107.834684 -278.065484)
		(end 107.991148 -278.336502)
		(width 0.0889)
		(layer "In6.Cu")
		(net "UPI_CPU0_CPU1_P2P2_DP<18>")
	)
	(segment
		(start 261.151878 -347.231462)
		(end 263.83869 -349.918274)
		(width 0.14732)
		(layer "In6.Cu")
		(net "UPI_CPU0_CPU1_P2P2_DP<18>")
	)
	(segment
		(start 97.412302 -303.59858)
		(end 101.943408 -297.489372)
		(width 0.14732)
		(layer "In6.Cu")
		(net "UPI_CPU0_CPU1_P2P2_DP<18>")
	)
	(segment
		(start 81.592674 -316.580774)
		(end 97.412302 -303.59858)
		(width 0.14732)
		(layer "In6.Cu")
		(net "UPI_CPU0_CPU1_P2P2_DP<18>")
	)
	(segment
		(start 104.427782 -286.156146)
		(end 104.418892 -286.151066)
		(width 0.0889)
		(layer "In6.Cu")
		(net "UPI_CPU0_CPU1_P2P2_DP<18>")
	)
	(segment
		(start 259.51307 -348.66199)
		(end 259.51307 -348.87027)
		(width 0.14732)
		(layer "In6.Cu")
		(net "UPI_CPU0_CPU1_P2P2_DP<18>")
	)
	(segment
		(start 336.753454 -289.652456)
		(end 336.753454 -290.084002)
		(width 0.0889)
		(layer "In6.Cu")
		(net "UPI_CPU0_CPU1_P2P2_DP<18>")
	)
	(segment
		(start 104.418384 -285.172404)
		(end 104.419146 -285.171896)
		(width 0.0889)
		(layer "In6.Cu")
		(net "UPI_CPU0_CPU1_P2P2_DP<18>")
	)
	(segment
		(start 256.652268 -351.522792)
		(end 255.7145 -352.460306)
		(width 0.14732)
		(layer "In6.Cu")
		(net "UPI_CPU0_CPU1_P2P2_DP<18>")
	)
	(segment
		(start 259.51307 -348.87027)
		(end 262.898636 -352.255836)
		(width 0.14732)
		(layer "In6.Cu")
		(net "UPI_CPU0_CPU1_P2P2_DP<18>")
	)
	(segment
		(start 259.929884 -348.245176)
		(end 259.51307 -348.66199)
		(width 0.14732)
		(layer "In6.Cu")
		(net "UPI_CPU0_CPU1_P2P2_DP<18>")
	)
	(segment
		(start 263.83869 -349.918274)
		(end 263.83869 -350.35363)
		(width 0.14732)
		(layer "In6.Cu")
		(net "UPI_CPU0_CPU1_P2P2_DP<18>")
	)
	(segment
		(start 103.196898 -289.114738)
		(end 103.196898 -288.898584)
		(width 0.0889)
		(layer "In6.Cu")
		(net "UPI_CPU0_CPU1_P2P2_DP<18>")
	)
	(segment
		(start 336.39887 -290.49853)
		(end 336.383376 -290.514024)
		(width 0.0889)
		(layer "In6.Cu")
		(net "UPI_CPU0_CPU1_P2P2_DP<18>")
	)
	(segment
		(start 336.39887 -290.438586)
		(end 336.39887 -290.49853)
		(width 0.0889)
		(layer "In6.Cu")
		(net "UPI_CPU0_CPU1_P2P2_DP<18>")
	)
	(segment
		(start 337.229704 -288.905696)
		(end 337.229704 -289.176206)
		(width 0.0889)
		(layer "In6.Cu")
		(net "UPI_CPU0_CPU1_P2P2_DP<18>")
	)
	(segment
		(start 105.076244 -280.778204)
		(end 105.076244 -280.76398)
		(width 0.0889)
		(layer "In6.Cu")
		(net "UPI_CPU0_CPU1_P2P2_DP<18>")
	)
	(segment
		(start 104.41305 -285.175452)
		(end 104.418384 -285.172404)
		(width 0.0889)
		(layer "In6.Cu")
		(net "UPI_CPU0_CPU1_P2P2_DP<18>")
	)
	(segment
		(start 107.23245 -277.03653)
		(end 107.253786 -277.024338)
		(width 0.0889)
		(layer "In6.Cu")
		(net "UPI_CPU0_CPU1_P2P2_DP<18>")
	)
	(segment
		(start 105.828592 -282.730194)
		(end 105.837482 -282.725114)
		(width 0.0889)
		(layer "In6.Cu")
		(net "UPI_CPU0_CPU1_P2P2_DP<18>")
	)
	(segment
		(start 105.367836 -281.272742)
		(end 105.358946 -281.267662)
		(width 0.0889)
		(layer "In6.Cu")
		(net "UPI_CPU0_CPU1_P2P2_DP<18>")
	)
	(segment
		(start 105.35285 -283.54782)
		(end 105.358184 -283.544772)
		(width 0.0889)
		(layer "In6.Cu")
		(net "UPI_CPU0_CPU1_P2P2_DP<18>")
	)
	(segment
		(start 199.040242 -370.683282)
		(end 159.215582 -377.70435)
		(width 0.14732)
		(layer "In6.Cu")
		(net "UPI_CPU0_CPU1_P2P2_DP<18>")
	)
	(segment
		(start 339.297518 -282.081478)
		(end 339.288628 -282.086558)
		(width 0.0889)
		(layer "In6.Cu")
		(net "UPI_CPU0_CPU1_P2P2_DP<18>")
	)
	(segment
		(start 334.800448 -292.095936)
		(end 333.221584 -294.45585)
		(width 0.14732)
		(layer "In6.Cu")
		(net "UPI_CPU0_CPU1_P2P2_DP<18>")
	)
	(segment
		(start 339.954362 -281.59202)
		(end 339.641688 -281.59202)
		(width 0.0889)
		(layer "In6.Cu")
		(net "UPI_CPU0_CPU1_P2P2_DP<18>")
	)
	(segment
		(start 105.546398 -281.607514)
		(end 105.546398 -281.59202)
		(width 0.0889)
		(layer "In6.Cu")
		(net "UPI_CPU0_CPU1_P2P2_DP<18>")
	)
	(segment
		(start 98.720656 -373.660924)
		(end 79.962756 -365.891572)
		(width 0.14732)
		(layer "In6.Cu")
		(net "UPI_CPU0_CPU1_P2P2_DP<18>")
	)
	(arc
		(start 337.417664 -285.985712)
		(mid 337.621145 -286.186516)
		(end 337.700366 -286.4612)
		(width 0.0889)
		(layer "In6.Cu")
		(net "UPI_CPU0_CPU1_P2P2_DP<18>")
	)
	(arc
		(start 104.419146 -285.171896)
		(mid 104.554079 -285.038542)
		(end 104.606344 -284.856174)
		(width 0.0889)
		(layer "In6.Cu")
		(net "UPI_CPU0_CPU1_P2P2_DP<18>")
	)
	(arc
		(start 104.606344 -284.837632)
		(mid 104.684455 -284.560683)
		(end 104.888792 -284.35808)
		(width 0.0889)
		(layer "In6.Cu")
		(net "UPI_CPU0_CPU1_P2P2_DP<18>")
	)
	(arc
		(start 337.408774 -285.342076)
		(mid 337.279485 -285.475562)
		(end 337.230212 -285.65475)
		(width 0.0889)
		(layer "In6.Cu")
		(net "UPI_CPU0_CPU1_P2P2_DP<18>")
	)
	(arc
		(start 105.358946 -283.544264)
		(mid 105.493879 -283.41091)
		(end 105.546144 -283.228542)
		(width 0.0889)
		(layer "In6.Cu")
		(net "UPI_CPU0_CPU1_P2P2_DP<18>")
	)
	(arc
		(start 106.01579 -282.418028)
		(mid 106.015957 -282.406852)
		(end 106.01579 -282.395676)
		(width 0.0889)
		(layer "In6.Cu")
		(net "UPI_CPU0_CPU1_P2P2_DP<18>")
	)
	(arc
		(start 108.086144 -277.54453)
		(mid 108.026275 -277.776777)
		(end 107.875578 -277.963376)
		(width 0.0889)
		(layer "In6.Cu")
		(net "UPI_CPU0_CPU1_P2P2_DP<18>")
	)
	(arc
		(start 103.666798 -288.087562)
		(mid 103.746168 -287.813828)
		(end 103.948992 -287.613598)
		(width 0.0889)
		(layer "In6.Cu")
		(net "UPI_CPU0_CPU1_P2P2_DP<18>")
	)
	(arc
		(start 106.777282 -277.84171)
		(mid 106.904536 -277.711744)
		(end 106.95559 -277.537164)
		(width 0.0889)
		(layer "In6.Cu")
		(net "UPI_CPU0_CPU1_P2P2_DP<18>")
	)
	(arc
		(start 106.955844 -277.522432)
		(mid 107.029835 -277.242866)
		(end 107.23245 -277.03653)
		(width 0.0889)
		(layer "In6.Cu")
		(net "UPI_CPU0_CPU1_P2P2_DP<18>")
	)
	(arc
		(start 105.837482 -282.725114)
		(mid 105.965375 -282.594052)
		(end 106.01579 -282.418028)
		(width 0.0889)
		(layer "In6.Cu")
		(net "UPI_CPU0_CPU1_P2P2_DP<18>")
	)
	(arc
		(start 103.488236 -288.422334)
		(mid 103.61915 -288.285974)
		(end 103.666798 -288.103056)
		(width 0.0889)
		(layer "In6.Cu")
		(net "UPI_CPU0_CPU1_P2P2_DP<18>")
	)
	(arc
		(start 103.957882 -287.608518)
		(mid 104.088796 -287.472158)
		(end 104.136444 -287.28924)
		(width 0.0889)
		(layer "In6.Cu")
		(net "UPI_CPU0_CPU1_P2P2_DP<18>")
	)
	(arc
		(start 339.576156 -281.657552)
		(mid 339.574858 -281.668106)
		(end 339.573362 -281.678634)
		(width 0.0889)
		(layer "In6.Cu")
		(net "UPI_CPU0_CPU1_P2P2_DP<18>")
	)
	(arc
		(start 337.40852 -288.597848)
		(mid 337.280168 -288.729172)
		(end 337.229704 -288.905696)
		(width 0.0889)
		(layer "In6.Cu")
		(net "UPI_CPU0_CPU1_P2P2_DP<18>")
	)
	(arc
		(start 105.546144 -283.201364)
		(mid 105.626306 -282.929175)
		(end 105.828592 -282.730194)
		(width 0.0889)
		(layer "In6.Cu")
		(net "UPI_CPU0_CPU1_P2P2_DP<18>")
	)
	(arc
		(start 338.170012 -284.043628)
		(mid 338.091901 -284.320577)
		(end 337.887564 -284.52318)
		(width 0.0889)
		(layer "In6.Cu")
		(net "UPI_CPU0_CPU1_P2P2_DP<18>")
	)
	(arc
		(start 337.899756 -286.806894)
		(mid 338.170212 -287.28924)
		(end 337.899756 -287.771586)
		(width 0.0889)
		(layer "In6.Cu")
		(net "UPI_CPU0_CPU1_P2P2_DP<18>")
	)
	(arc
		(start 105.837736 -279.469596)
		(mid 105.96865 -279.333236)
		(end 106.016298 -279.150318)
		(width 0.0889)
		(layer "In6.Cu")
		(net "UPI_CPU0_CPU1_P2P2_DP<18>")
	)
	(arc
		(start 338.818474 -282.900628)
		(mid 338.68756 -283.036988)
		(end 338.639912 -283.219906)
		(width 0.0889)
		(layer "In6.Cu")
		(net "UPI_CPU0_CPU1_P2P2_DP<18>")
	)
	(arc
		(start 104.418892 -286.151066)
		(mid 104.216606 -285.952085)
		(end 104.136444 -285.679896)
		(width 0.0889)
		(layer "In6.Cu")
		(net "UPI_CPU0_CPU1_P2P2_DP<18>")
	)
	(arc
		(start 105.076244 -284.033722)
		(mid 105.150235 -283.754156)
		(end 105.35285 -283.54782)
		(width 0.0889)
		(layer "In6.Cu")
		(net "UPI_CPU0_CPU1_P2P2_DP<18>")
	)
	(arc
		(start 105.367836 -280.283412)
		(mid 105.49875 -280.147052)
		(end 105.546398 -279.964134)
		(width 0.0889)
		(layer "In6.Cu")
		(net "UPI_CPU0_CPU1_P2P2_DP<18>")
	)
	(arc
		(start 104.897682 -284.353)
		(mid 105.028596 -284.21664)
		(end 105.076244 -284.033722)
		(width 0.0889)
		(layer "In6.Cu")
		(net "UPI_CPU0_CPU1_P2P2_DP<18>")
	)
	(arc
		(start 107.875578 -277.963376)
		(mid 107.867256 -277.969931)
		(end 107.858814 -277.97633)
		(width 0.0889)
		(layer "In6.Cu")
		(net "UPI_CPU0_CPU1_P2P2_DP<18>")
	)
	(arc
		(start 339.288628 -282.086558)
		(mid 339.157714 -282.222918)
		(end 339.110066 -282.405836)
		(width 0.0889)
		(layer "In6.Cu")
		(net "UPI_CPU0_CPU1_P2P2_DP<18>")
	)
	(arc
		(start 337.230212 -285.670752)
		(mid 337.280108 -285.848399)
		(end 337.408774 -285.980632)
		(width 0.0889)
		(layer "In6.Cu")
		(net "UPI_CPU0_CPU1_P2P2_DP<18>")
	)
	(arc
		(start 337.700112 -284.857444)
		(mid 337.622001 -285.134393)
		(end 337.417664 -285.336996)
		(width 0.0889)
		(layer "In6.Cu")
		(net "UPI_CPU0_CPU1_P2P2_DP<18>")
	)
	(arc
		(start 105.546398 -281.59202)
		(mid 105.498719 -281.40912)
		(end 105.367836 -281.272742)
		(width 0.0889)
		(layer "In6.Cu")
		(net "UPI_CPU0_CPU1_P2P2_DP<18>")
	)
	(arc
		(start 339.110066 -282.42006)
		(mid 339.030847 -282.694745)
		(end 338.827364 -282.895548)
		(width 0.0889)
		(layer "In6.Cu")
		(net "UPI_CPU0_CPU1_P2P2_DP<18>")
	)
	(arc
		(start 104.136444 -285.661354)
		(mid 104.210435 -285.381788)
		(end 104.41305 -285.175452)
		(width 0.0889)
		(layer "In6.Cu")
		(net "UPI_CPU0_CPU1_P2P2_DP<18>")
	)
	(arc
		(start 337.700366 -286.48406)
		(mid 337.752636 -286.666425)
		(end 337.887564 -286.799782)
		(width 0.0889)
		(layer "In6.Cu")
		(net "UPI_CPU0_CPU1_P2P2_DP<18>")
	)
	(arc
		(start 338.639912 -283.229812)
		(mid 338.561801 -283.506761)
		(end 338.357464 -283.709364)
		(width 0.0889)
		(layer "In6.Cu")
		(net "UPI_CPU0_CPU1_P2P2_DP<18>")
	)
	(arc
		(start 103.666544 -289.645852)
		(mid 103.591539 -289.530393)
		(end 103.482394 -289.446462)
		(width 0.0889)
		(layer "In6.Cu")
		(net "UPI_CPU0_CPU1_P2P2_DP<18>")
	)
	(arc
		(start 106.016298 -279.140412)
		(mid 106.094409 -278.863463)
		(end 106.298746 -278.66086)
		(width 0.0889)
		(layer "In6.Cu")
		(net "UPI_CPU0_CPU1_P2P2_DP<18>")
	)
	(arc
		(start 337.878674 -287.783778)
		(mid 337.74776 -287.920138)
		(end 337.700112 -288.103056)
		(width 0.0889)
		(layer "In6.Cu")
		(net "UPI_CPU0_CPU1_P2P2_DP<18>")
	)
	(arc
		(start 106.95559 -277.537164)
		(mid 106.955787 -277.529799)
		(end 106.955844 -277.522432)
		(width 0.0889)
		(layer "In6.Cu")
		(net "UPI_CPU0_CPU1_P2P2_DP<18>")
	)
	(arc
		(start 104.136444 -287.28924)
		(mid 104.21036 -287.009738)
		(end 104.412796 -286.803338)
		(width 0.0889)
		(layer "In6.Cu")
		(net "UPI_CPU0_CPU1_P2P2_DP<18>")
	)
	(arc
		(start 105.076244 -280.76398)
		(mid 105.155463 -280.489295)
		(end 105.358946 -280.288492)
		(width 0.0889)
		(layer "In6.Cu")
		(net "UPI_CPU0_CPU1_P2P2_DP<18>")
	)
	(arc
		(start 107.80395 -277.032974)
		(mid 108.006773 -277.233205)
		(end 108.086144 -277.506938)
		(width 0.0889)
		(layer "In6.Cu")
		(net "UPI_CPU0_CPU1_P2P2_DP<18>")
	)
	(arc
		(start 105.35285 -281.264106)
		(mid 105.150263 -281.057755)
		(end 105.076244 -280.778204)
		(width 0.0889)
		(layer "In6.Cu")
		(net "UPI_CPU0_CPU1_P2P2_DP<18>")
	)
	(arc
		(start 106.307636 -278.65578)
		(mid 106.43855 -278.51942)
		(end 106.486198 -278.336502)
		(width 0.0889)
		(layer "In6.Cu")
		(net "UPI_CPU0_CPU1_P2P2_DP<18>")
	)
	(arc
		(start 104.427782 -286.794702)
		(mid 104.606379 -286.475424)
		(end 104.427782 -286.156146)
		(width 0.0889)
		(layer "In6.Cu")
		(net "UPI_CPU0_CPU1_P2P2_DP<18>")
	)
	(arc
		(start 103.482394 -289.446462)
		(mid 103.308262 -289.307615)
		(end 103.196898 -289.114738)
		(width 0.0889)
		(layer "In6.Cu")
		(net "UPI_CPU0_CPU1_P2P2_DP<18>")
	)
	(arc
		(start 106.01579 -282.395676)
		(mid 105.965775 -282.218545)
		(end 105.837482 -282.086558)
		(width 0.0889)
		(layer "In6.Cu")
		(net "UPI_CPU0_CPU1_P2P2_DP<18>")
	)
	(arc
		(start 105.828592 -282.081478)
		(mid 105.625769 -281.881247)
		(end 105.546398 -281.607514)
		(width 0.0889)
		(layer "In6.Cu")
		(net "UPI_CPU0_CPU1_P2P2_DP<18>")
	)
	(arc
		(start 337.230212 -285.65475)
		(mid 337.230124 -285.662751)
		(end 337.230212 -285.670752)
		(width 0.0889)
		(layer "In6.Cu")
		(net "UPI_CPU0_CPU1_P2P2_DP<18>")
	)
	(arc
		(start 107.253278 -277.024338)
		(mid 107.529753 -276.957018)
		(end 107.80395 -277.032974)
		(width 0.0889)
		(layer "In6.Cu")
		(net "UPI_CPU0_CPU1_P2P2_DP<18>")
	)
	(arc
		(start 337.878674 -284.52826)
		(mid 337.74776 -284.66462)
		(end 337.700112 -284.847538)
		(width 0.0889)
		(layer "In6.Cu")
		(net "UPI_CPU0_CPU1_P2P2_DP<18>")
	)
	(arc
		(start 103.196898 -288.898584)
		(mid 103.27706 -288.626395)
		(end 103.479346 -288.427414)
		(width 0.0889)
		(layer "In6.Cu")
		(net "UPI_CPU0_CPU1_P2P2_DP<18>")
	)
	(arc
		(start 339.573362 -281.678634)
		(mid 339.481201 -281.911406)
		(end 339.297518 -282.081478)
		(width 0.0889)
		(layer "In6.Cu")
		(net "UPI_CPU0_CPU1_P2P2_DP<18>")
	)
	(arc
		(start 337.700112 -288.11728)
		(mid 337.620893 -288.391965)
		(end 337.41741 -288.592768)
		(width 0.0889)
		(layer "In6.Cu")
		(net "UPI_CPU0_CPU1_P2P2_DP<18>")
	)
	(arc
		(start 106.486198 -278.314404)
		(mid 106.567109 -278.044276)
		(end 106.768392 -277.84679)
		(width 0.0889)
		(layer "In6.Cu")
		(net "UPI_CPU0_CPU1_P2P2_DP<18>")
	)
	(arc
		(start 105.546398 -279.954228)
		(mid 105.624509 -279.677279)
		(end 105.828846 -279.474676)
		(width 0.0889)
		(layer "In6.Cu")
		(net "UPI_CPU0_CPU1_P2P2_DP<18>")
	)
	(arc
		(start 338.348574 -283.714444)
		(mid 338.21766 -283.850804)
		(end 338.170012 -284.033722)
		(width 0.0889)
		(layer "In6.Cu")
		(net "UPI_CPU0_CPU1_P2P2_DP<18>")
	)
	(segment
		(start 106.581194 -277.522178)
		(end 106.581194 -277.522432)
		(width 0.13208)
		(layer "F.Cu")
		(net "UPI_CPU0_CPU1_P2P2_DP<17>")
	)
	(segment
		(start 339.014562 -282.683966)
		(end 339.014562 -283.219906)
		(width 0.13208)
		(layer "F.Cu")
		(net "UPI_CPU0_CPU1_P2P2_DP<17>")
	)
	(segment
		(start 106.581448 -276.986492)
		(end 106.581448 -277.521924)
		(width 0.13208)
		(layer "F.Cu")
		(net "UPI_CPU0_CPU1_P2P2_DP<17>")
	)
	(segment
		(start 106.581448 -277.521924)
		(end 106.581194 -277.522178)
		(width 0.13208)
		(layer "F.Cu")
		(net "UPI_CPU0_CPU1_P2P2_DP<17>")
	)
	(segment
		(start 312.981848 -318.15405)
		(end 312.80354 -318.053466)
		(width 0.14732)
		(layer "In6.Cu")
		(net "UPI_CPU0_CPU1_P2P2_DP<17>")
	)
	(segment
		(start 100.486972 -294.461692)
		(end 100.486972 -294.283892)
		(width 0.0889)
		(layer "In6.Cu")
		(net "UPI_CPU0_CPU1_P2P2_DP<17>")
	)
	(segment
		(start 277.15972 -331.808328)
		(end 264.767822 -344.200226)
		(width 0.14732)
		(layer "In6.Cu")
		(net "UPI_CPU0_CPU1_P2P2_DP<17>")
	)
	(segment
		(start 250.117102 -367.502948)
		(end 249.527822 -367.502948)
		(width 0.14732)
		(layer "In6.Cu")
		(net "UPI_CPU0_CPU1_P2P2_DP<17>")
	)
	(segment
		(start 249.072654 -363.565948)
		(end 248.25579 -363.565948)
		(width 0.14732)
		(layer "In6.Cu")
		(net "UPI_CPU0_CPU1_P2P2_DP<17>")
	)
	(segment
		(start 331.838046 -300.92523)
		(end 315.654436 -317.10884)
		(width 0.14732)
		(layer "In6.Cu")
		(net "UPI_CPU0_CPU1_P2P2_DP<17>")
	)
	(segment
		(start 102.62616 -288.597848)
		(end 102.63505 -288.592768)
		(width 0.0889)
		(layer "In6.Cu")
		(net "UPI_CPU0_CPU1_P2P2_DP<17>")
	)
	(segment
		(start 104.98455 -279.639776)
		(end 104.990646 -279.63622)
		(width 0.0889)
		(layer "In6.Cu")
		(net "UPI_CPU0_CPU1_P2P2_DP<17>")
	)
	(segment
		(start 300.48835 -327.815956)
		(end 300.48835 -328.02068)
		(width 0.14732)
		(layer "In6.Cu")
		(net "UPI_CPU0_CPU1_P2P2_DP<17>")
	)
	(segment
		(start 339.202776 -286.799274)
		(end 339.20176 -286.799782)
		(width 0.0889)
		(layer "In6.Cu")
		(net "UPI_CPU0_CPU1_P2P2_DP<17>")
	)
	(segment
		(start 300.953932 -327.555098)
		(end 300.749208 -327.555098)
		(width 0.14732)
		(layer "In6.Cu")
		(net "UPI_CPU0_CPU1_P2P2_DP<17>")
	)
	(segment
		(start 99.752404 -298.093892)
		(end 99.674172 -297.904662)
		(width 0.14732)
		(layer "In6.Cu")
		(net "UPI_CPU0_CPU1_P2P2_DP<17>")
	)
	(segment
		(start 71.511414 -328.746104)
		(end 71.62419 -328.337926)
		(width 0.14732)
		(layer "In6.Cu")
		(net "UPI_CPU0_CPU1_P2P2_DP<17>")
	)
	(segment
		(start 338.741004 -287.608518)
		(end 338.725764 -287.617408)
		(width 0.0889)
		(layer "In6.Cu")
		(net "UPI_CPU0_CPU1_P2P2_DP<17>")
	)
	(segment
		(start 105.91546 -278.017224)
		(end 105.92435 -278.012144)
		(width 0.0889)
		(layer "In6.Cu")
		(net "UPI_CPU0_CPU1_P2P2_DP<17>")
	)
	(segment
		(start 337.449922 -290.319968)
		(end 337.046062 -290.723828)
		(width 0.14732)
		(layer "In6.Cu")
		(net "UPI_CPU0_CPU1_P2P2_DP<17>")
	)
	(segment
		(start 106.385106 -277.203154)
		(end 106.393996 -277.198074)
		(width 0.0889)
		(layer "In6.Cu")
		(net "UPI_CPU0_CPU1_P2P2_DP<17>")
	)
	(segment
		(start 307.144928 -323.259958)
		(end 307.144928 -323.260212)
		(width 0.14732)
		(layer "In6.Cu")
		(net "UPI_CPU0_CPU1_P2P2_DP<17>")
	)
	(segment
		(start 315.185298 -317.302896)
		(end 315.185044 -317.303404)
		(width 0.14732)
		(layer "In6.Cu")
		(net "UPI_CPU0_CPU1_P2P2_DP<17>")
	)
	(segment
		(start 98.207322 -301.445168)
		(end 98.439478 -300.88459)
		(width 0.14732)
		(layer "In6.Cu")
		(net "UPI_CPU0_CPU1_P2P2_DP<17>")
	)
	(segment
		(start 79.601314 -366.3442)
		(end 74.178668 -360.921554)
		(width 0.14732)
		(layer "In6.Cu")
		(net "UPI_CPU0_CPU1_P2P2_DP<17>")
	)
	(segment
		(start 99.168966 -299.502322)
		(end 99.309936 -299.161962)
		(width 0.14732)
		(layer "In6.Cu")
		(net "UPI_CPU0_CPU1_P2P2_DP<17>")
	)
	(segment
		(start 159.265366 -378.27077)
		(end 125.935486 -378.27077)
		(width 0.14732)
		(layer "In6.Cu")
		(net "UPI_CPU0_CPU1_P2P2_DP<17>")
	)
	(segment
		(start 339.389212 -283.219906)
		(end 339.389212 -283.229812)
		(width 0.0889)
		(layer "In6.Cu")
		(net "UPI_CPU0_CPU1_P2P2_DP<17>")
	)
	(segment
		(start 103.857298 -286.475424)
		(end 103.857298 -286.4612)
		(width 0.0889)
		(layer "In6.Cu")
		(net "UPI_CPU0_CPU1_P2P2_DP<17>")
	)
	(segment
		(start 98.776282 -300.450504)
		(end 98.917252 -300.110144)
		(width 0.14732)
		(layer "In6.Cu")
		(net "UPI_CPU0_CPU1_P2P2_DP<17>")
	)
	(segment
		(start 338.919566 -287.273746)
		(end 338.919566 -287.28924)
		(width 0.0889)
		(layer "In6.Cu")
		(net "UPI_CPU0_CPU1_P2P2_DP<17>")
	)
	(segment
		(start 103.565706 -286.969962)
		(end 103.580946 -286.961072)
		(width 0.0889)
		(layer "In6.Cu")
		(net "UPI_CPU0_CPU1_P2P2_DP<17>")
	)
	(segment
		(start 310.262016 -318.910716)
		(end 309.874412 -319.268602)
		(width 0.14732)
		(layer "In6.Cu")
		(net "UPI_CPU0_CPU1_P2P2_DP<17>")
	)
	(segment
		(start 101.308662 -292.005258)
		(end 101.308662 -291.868606)
		(width 0.0889)
		(layer "In6.Cu")
		(net "UPI_CPU0_CPU1_P2P2_DP<17>")
	)
	(segment
		(start 101.12883 -292.18509)
		(end 101.308662 -292.005258)
		(width 0.0889)
		(layer "In6.Cu")
		(net "UPI_CPU0_CPU1_P2P2_DP<17>")
	)
	(segment
		(start 100.221796 -296.582592)
		(end 100.508308 -295.890188)
		(width 0.14732)
		(layer "In6.Cu")
		(net "UPI_CPU0_CPU1_P2P2_DP<17>")
	)
	(segment
		(start 100.486972 -293.342314)
		(end 100.486972 -292.690296)
		(width 0.0889)
		(layer "In6.Cu")
		(net "UPI_CPU0_CPU1_P2P2_DP<17>")
	)
	(segment
		(start 309.098696 -319.984882)
		(end 308.57571 -321.567556)
		(width 0.14732)
		(layer "In6.Cu")
		(net "UPI_CPU0_CPU1_P2P2_DP<17>")
	)
	(segment
		(start 104.03586 -284.52826)
		(end 104.043734 -284.523688)
		(width 0.0889)
		(layer "In6.Cu")
		(net "UPI_CPU0_CPU1_P2P2_DP<17>")
	)
	(segment
		(start 309.874412 -319.268602)
		(end 309.669688 -319.260474)
		(width 0.14732)
		(layer "In6.Cu")
		(net "UPI_CPU0_CPU1_P2P2_DP<17>")
	)
	(segment
		(start 307.144928 -323.260212)
		(end 306.646326 -323.758814)
		(width 0.14732)
		(layer "In6.Cu")
		(net "UPI_CPU0_CPU1_P2P2_DP<17>")
	)
	(segment
		(start 302.15713 -325.61784)
		(end 301.30496 -326.47001)
		(width 0.14732)
		(layer "In6.Cu")
		(net "UPI_CPU0_CPU1_P2P2_DP<17>")
	)
	(segment
		(start 309.669688 -319.260474)
		(end 309.398924 -319.510664)
		(width 0.14732)
		(layer "In6.Cu")
		(net "UPI_CPU0_CPU1_P2P2_DP<17>")
	)
	(segment
		(start 104.326944 -284.049216)
		(end 104.326944 -284.033722)
		(width 0.0889)
		(layer "In6.Cu")
		(net "UPI_CPU0_CPU1_P2P2_DP<17>")
	)
	(segment
		(start 100.486972 -293.718234)
		(end 100.586032 -293.619174)
		(width 0.0889)
		(layer "In6.Cu")
		(net "UPI_CPU0_CPU1_P2P2_DP<17>")
	)
	(segment
		(start 100.300028 -296.771568)
		(end 100.221796 -296.582592)
		(width 0.14732)
		(layer "In6.Cu")
		(net "UPI_CPU0_CPU1_P2P2_DP<17>")
	)
	(segment
		(start 337.683094 -289.539934)
		(end 337.683094 -290.145724)
		(width 0.0889)
		(layer "In6.Cu")
		(net "UPI_CPU0_CPU1_P2P2_DP<17>")
	)
	(segment
		(start 337.046062 -290.723828)
		(end 337.045046 -290.723828)
		(width 0.14732)
		(layer "In6.Cu")
		(net "UPI_CPU0_CPU1_P2P2_DP<17>")
	)
	(segment
		(start 104.505506 -283.714444)
		(end 104.526588 -283.702252)
		(width 0.0889)
		(layer "In6.Cu")
		(net "UPI_CPU0_CPU1_P2P2_DP<17>")
	)
	(segment
		(start 306.646326 -323.758814)
		(end 302.15713 -325.61784)
		(width 0.14732)
		(layer "In6.Cu")
		(net "UPI_CPU0_CPU1_P2P2_DP<17>")
	)
	(segment
		(start 70.877938 -352.952812)
		(end 70.877938 -335.176876)
		(width 0.14732)
		(layer "In6.Cu")
		(net "UPI_CPU0_CPU1_P2P2_DP<17>")
	)
	(segment
		(start 98.439478 -300.88459)
		(end 98.446082 -300.869096)
		(width 0.14732)
		(layer "In6.Cu")
		(net "UPI_CPU0_CPU1_P2P2_DP<17>")
	)
	(segment
		(start 105.736644 -278.350726)
		(end 105.736898 -278.336502)
		(width 0.0889)
		(layer "In6.Cu")
		(net "UPI_CPU0_CPU1_P2P2_DP<17>")
	)
	(segment
		(start 337.979512 -289.243516)
		(end 337.683094 -289.539934)
		(width 0.0889)
		(layer "In6.Cu")
		(net "UPI_CPU0_CPU1_P2P2_DP<17>")
	)
	(segment
		(start 339.21065 -286.794702)
		(end 339.202776 -286.799274)
		(width 0.0889)
		(layer "In6.Cu")
		(net "UPI_CPU0_CPU1_P2P2_DP<17>")
	)
	(segment
		(start 337.683094 -290.145724)
		(end 337.524344 -290.304474)
		(width 0.0889)
		(layer "In6.Cu")
		(net "UPI_CPU0_CPU1_P2P2_DP<17>")
	)
	(segment
		(start 199.037448 -371.2591)
		(end 159.265366 -378.27077)
		(width 0.14732)
		(layer "In6.Cu")
		(net "UPI_CPU0_CPU1_P2P2_DP<17>")
	)
	(segment
		(start 251.696982 -363.873796)
		(end 251.389134 -363.565948)
		(width 0.14732)
		(layer "In6.Cu")
		(net "UPI_CPU0_CPU1_P2P2_DP<17>")
	)
	(segment
		(start 71.788782 -354.772976)
		(end 71.599298 -354.69449)
		(width 0.14732)
		(layer "In6.Cu")
		(net "UPI_CPU0_CPU1_P2P2_DP<17>")
	)
	(segment
		(start 246.898414 -367.502948)
		(end 212.31225 -373.599964)
		(width 0.14732)
		(layer "In6.Cu")
		(net "UPI_CPU0_CPU1_P2P2_DP<17>")
	)
	(segment
		(start 100.159312 -297.112182)
		(end 100.300028 -296.771568)
		(width 0.14732)
		(layer "In6.Cu")
		(net "UPI_CPU0_CPU1_P2P2_DP<17>")
	)
	(segment
		(start 71.395844 -353.824794)
		(end 71.206614 -353.746308)
		(width 0.14732)
		(layer "In6.Cu")
		(net "UPI_CPU0_CPU1_P2P2_DP<17>")
	)
	(segment
		(start 337.465416 -290.304474)
		(end 337.449922 -290.319968)
		(width 0.0889)
		(layer "In6.Cu")
		(net "UPI_CPU0_CPU1_P2P2_DP<17>")
	)
	(segment
		(start 100.486972 -295.258744)
		(end 100.486972 -294.837612)
		(width 0.0889)
		(layer "In6.Cu")
		(net "UPI_CPU0_CPU1_P2P2_DP<17>")
	)
	(segment
		(start 100.586032 -294.738552)
		(end 100.586032 -294.560752)
		(width 0.0889)
		(layer "In6.Cu")
		(net "UPI_CPU0_CPU1_P2P2_DP<17>")
	)
	(segment
		(start 98.586798 -300.52899)
		(end 98.776282 -300.450504)
		(width 0.14732)
		(layer "In6.Cu")
		(net "UPI_CPU0_CPU1_P2P2_DP<17>")
	)
	(segment
		(start 125.935486 -378.27077)
		(end 98.606864 -374.216676)
		(width 0.14732)
		(layer "In6.Cu")
		(net "UPI_CPU0_CPU1_P2P2_DP<17>")
	)
	(segment
		(start 104.512618 -281.101546)
		(end 104.505506 -281.097482)
		(width 0.0889)
		(layer "In6.Cu")
		(net "UPI_CPU0_CPU1_P2P2_DP<17>")
	)
	(segment
		(start 249.380502 -363.873796)
		(end 249.072654 -363.565948)
		(width 0.14732)
		(layer "In6.Cu")
		(net "UPI_CPU0_CPU1_P2P2_DP<17>")
	)
	(segment
		(start 102.447598 -289.078416)
		(end 102.447598 -288.917126)
		(width 0.0889)
		(layer "In6.Cu")
		(net "UPI_CPU0_CPU1_P2P2_DP<17>")
	)
	(segment
		(start 98.917252 -300.110144)
		(end 98.838766 -299.920914)
		(width 0.14732)
		(layer "In6.Cu")
		(net "UPI_CPU0_CPU1_P2P2_DP<17>")
	)
	(segment
		(start 250.264422 -367.355628)
		(end 250.117102 -367.502948)
		(width 0.14732)
		(layer "In6.Cu")
		(net "UPI_CPU0_CPU1_P2P2_DP<17>")
	)
	(segment
		(start 104.98455 -281.916378)
		(end 104.97566 -281.911298)
		(width 0.0889)
		(layer "In6.Cu")
		(net "UPI_CPU0_CPU1_P2P2_DP<17>")
	)
	(segment
		(start 71.897748 -327.348596)
		(end 73.572116 -323.809106)
		(width 0.14732)
		(layer "In6.Cu")
		(net "UPI_CPU0_CPU1_P2P2_DP<17>")
	)
	(segment
		(start 100.586032 -293.441374)
		(end 100.486972 -293.342314)
		(width 0.0889)
		(layer "In6.Cu")
		(net "UPI_CPU0_CPU1_P2P2_DP<17>")
	)
	(segment
		(start 251.696982 -367.355628)
		(end 251.696982 -363.873796)
		(width 0.14732)
		(layer "In6.Cu")
		(net "UPI_CPU0_CPU1_P2P2_DP<17>")
	)
	(segment
		(start 335.242154 -292.52672)
		(end 333.676752 -294.867076)
		(width 0.14732)
		(layer "In6.Cu")
		(net "UPI_CPU0_CPU1_P2P2_DP<17>")
	)
	(segment
		(start 103.580946 -286.961072)
		(end 103.580692 -286.961326)
		(width 0.0889)
		(layer "In6.Cu")
		(net "UPI_CPU0_CPU1_P2P2_DP<17>")
	)
	(segment
		(start 104.515158 -281.10307)
		(end 104.513634 -281.102054)
		(width 0.0889)
		(layer "In6.Cu")
		(net "UPI_CPU0_CPU1_P2P2_DP<17>")
	)
	(segment
		(start 100.508308 -295.890188)
		(end 100.529136 -295.86936)
		(width 0.14732)
		(layer "In6.Cu")
		(net "UPI_CPU0_CPU1_P2P2_DP<17>")
	)
	(segment
		(start 308.57571 -321.567556)
		(end 307.826156 -322.57873)
		(width 0.14732)
		(layer "In6.Cu")
		(net "UPI_CPU0_CPU1_P2P2_DP<17>")
	)
	(segment
		(start 100.586032 -294.184832)
		(end 100.586032 -294.007032)
		(width 0.0889)
		(layer "In6.Cu")
		(net "UPI_CPU0_CPU1_P2P2_DP<17>")
	)
	(segment
		(start 100.529136 -295.86936)
		(end 100.529136 -295.323006)
		(width 0.14732)
		(layer "In6.Cu")
		(net "UPI_CPU0_CPU1_P2P2_DP<17>")
	)
	(segment
		(start 100.586032 -293.619174)
		(end 100.586032 -293.441374)
		(width 0.0889)
		(layer "In6.Cu")
		(net "UPI_CPU0_CPU1_P2P2_DP<17>")
	)
	(segment
		(start 100.529136 -295.300908)
		(end 100.486972 -295.258744)
		(width 0.0889)
		(layer "In6.Cu")
		(net "UPI_CPU0_CPU1_P2P2_DP<17>")
	)
	(segment
		(start 212.31225 -373.599964)
		(end 199.037448 -371.2591)
		(width 0.14732)
		(layer "In6.Cu")
		(net "UPI_CPU0_CPU1_P2P2_DP<17>")
	)
	(segment
		(start 104.505506 -280.458926)
		(end 104.514396 -280.453846)
		(width 0.0889)
		(layer "In6.Cu")
		(net "UPI_CPU0_CPU1_P2P2_DP<17>")
	)
	(segment
		(start 105.266744 -282.427934)
		(end 105.266744 -282.390342)
		(width 0.0889)
		(layer "In6.Cu")
		(net "UPI_CPU0_CPU1_P2P2_DP<17>")
	)
	(segment
		(start 71.458582 -354.354384)
		(end 71.536814 -354.165154)
		(width 0.14732)
		(layer "In6.Cu")
		(net "UPI_CPU0_CPU1_P2P2_DP<17>")
	)
	(segment
		(start 71.799704 -327.703688)
		(end 71.897748 -327.34885)
		(width 0.14732)
		(layer "In6.Cu")
		(net "UPI_CPU0_CPU1_P2P2_DP<17>")
	)
	(segment
		(start 337.524344 -290.304474)
		(end 337.465416 -290.304474)
		(width 0.0889)
		(layer "In6.Cu")
		(net "UPI_CPU0_CPU1_P2P2_DP<17>")
	)
	(segment
		(start 71.897748 -327.34885)
		(end 71.897748 -327.348596)
		(width 0.14732)
		(layer "In6.Cu")
		(net "UPI_CPU0_CPU1_P2P2_DP<17>")
	)
	(segment
		(start 309.390796 -319.715134)
		(end 309.098696 -319.984882)
		(width 0.14732)
		(layer "In6.Cu")
		(net "UPI_CPU0_CPU1_P2P2_DP<17>")
	)
	(segment
		(start 338.919566 -285.64586)
		(end 338.919566 -285.683452)
		(width 0.0889)
		(layer "In6.Cu")
		(net "UPI_CPU0_CPU1_P2P2_DP<17>")
	)
	(segment
		(start 74.178668 -360.921554)
		(end 71.851266 -355.302566)
		(width 0.14732)
		(layer "In6.Cu")
		(net "UPI_CPU0_CPU1_P2P2_DP<17>")
	)
	(segment
		(start 102.917498 -288.121598)
		(end 102.917498 -288.103056)
		(width 0.0889)
		(layer "In6.Cu")
		(net "UPI_CPU0_CPU1_P2P2_DP<17>")
	)
	(segment
		(start 339.21065 -285.166816)
		(end 339.20176 -285.171896)
		(width 0.0889)
		(layer "In6.Cu")
		(net "UPI_CPU0_CPU1_P2P2_DP<17>")
	)
	(segment
		(start 104.520492 -281.106118)
		(end 104.515158 -281.10307)
		(width 0.0889)
		(layer "In6.Cu")
		(net "UPI_CPU0_CPU1_P2P2_DP<17>")
	)
	(segment
		(start 309.398924 -319.510664)
		(end 309.390796 -319.715134)
		(width 0.14732)
		(layer "In6.Cu")
		(net "UPI_CPU0_CPU1_P2P2_DP<17>")
	)
	(segment
		(start 251.844302 -367.502948)
		(end 251.696982 -367.355628)
		(width 0.14732)
		(layer "In6.Cu")
		(net "UPI_CPU0_CPU1_P2P2_DP<17>")
	)
	(segment
		(start 284.043628 -328.957178)
		(end 277.15972 -331.808328)
		(width 0.14732)
		(layer "In6.Cu")
		(net "UPI_CPU0_CPU1_P2P2_DP<17>")
	)
	(segment
		(start 96.720914 -303.44872)
		(end 98.207322 -301.445168)
		(width 0.14732)
		(layer "In6.Cu")
		(net "UPI_CPU0_CPU1_P2P2_DP<17>")
	)
	(segment
		(start 73.572116 -323.809106)
		(end 81.170018 -316.21095)
		(width 0.14732)
		(layer "In6.Cu")
		(net "UPI_CPU0_CPU1_P2P2_DP<17>")
	)
	(segment
		(start 102.91699 -289.610292)
		(end 102.917244 -289.610038)
		(width 0.0889)
		(layer "In6.Cu")
		(net "UPI_CPU0_CPU1_P2P2_DP<17>")
	)
	(segment
		(start 100.486972 -293.907972)
		(end 100.486972 -293.718234)
		(width 0.0889)
		(layer "In6.Cu")
		(net "UPI_CPU0_CPU1_P2P2_DP<17>")
	)
	(segment
		(start 247.947942 -363.873796)
		(end 247.947942 -367.355628)
		(width 0.14732)
		(layer "In6.Cu")
		(net "UPI_CPU0_CPU1_P2P2_DP<17>")
	)
	(segment
		(start 71.536814 -354.165154)
		(end 71.395844 -353.824794)
		(width 0.14732)
		(layer "In6.Cu")
		(net "UPI_CPU0_CPU1_P2P2_DP<17>")
	)
	(segment
		(start 300.749208 -327.555098)
		(end 300.48835 -327.815956)
		(width 0.14732)
		(layer "In6.Cu")
		(net "UPI_CPU0_CPU1_P2P2_DP<17>")
	)
	(segment
		(start 249.380502 -367.355628)
		(end 249.380502 -363.873796)
		(width 0.14732)
		(layer "In6.Cu")
		(net "UPI_CPU0_CPU1_P2P2_DP<17>")
	)
	(segment
		(start 313.426094 -318.030606)
		(end 312.981848 -318.15405)
		(width 0.14732)
		(layer "In6.Cu")
		(net "UPI_CPU0_CPU1_P2P2_DP<17>")
	)
	(segment
		(start 338.27085 -288.422334)
		(end 338.26196 -288.427414)
		(width 0.0889)
		(layer "In6.Cu")
		(net "UPI_CPU0_CPU1_P2P2_DP<17>")
	)
	(segment
		(start 307.826156 -322.57873)
		(end 307.144928 -323.259958)
		(width 0.14732)
		(layer "In6.Cu")
		(net "UPI_CPU0_CPU1_P2P2_DP<17>")
	)
	(segment
		(start 100.486972 -292.690296)
		(end 100.992178 -292.18509)
		(width 0.0889)
		(layer "In6.Cu")
		(net "UPI_CPU0_CPU1_P2P2_DP<17>")
	)
	(segment
		(start 70.877938 -335.176876)
		(end 71.511414 -328.746104)
		(width 0.14732)
		(layer "In6.Cu")
		(net "UPI_CPU0_CPU1_P2P2_DP<17>")
	)
	(segment
		(start 98.606864 -374.216676)
		(end 79.601314 -366.3442)
		(width 0.14732)
		(layer "In6.Cu")
		(net "UPI_CPU0_CPU1_P2P2_DP<17>")
	)
	(segment
		(start 106.206544 -277.54453)
		(end 106.206544 -277.522432)
		(width 0.0889)
		(layer "In6.Cu")
		(net "UPI_CPU0_CPU1_P2P2_DP<17>")
	)
	(segment
		(start 249.527822 -367.502948)
		(end 249.380502 -367.355628)
		(width 0.14732)
		(layer "In6.Cu")
		(net "UPI_CPU0_CPU1_P2P2_DP<17>")
	)
	(segment
		(start 103.387144 -287.304734)
		(end 103.387144 -287.28924)
		(width 0.0889)
		(layer "In6.Cu")
		(net "UPI_CPU0_CPU1_P2P2_DP<17>")
	)
	(segment
		(start 71.206614 -353.746308)
		(end 70.877938 -352.952812)
		(width 0.14732)
		(layer "In6.Cu")
		(net "UPI_CPU0_CPU1_P2P2_DP<17>")
	)
	(segment
		(start 104.797098 -279.978358)
		(end 104.797098 -279.964134)
		(width 0.0889)
		(layer "In6.Cu")
		(net "UPI_CPU0_CPU1_P2P2_DP<17>")
	)
	(segment
		(start 312.448448 -318.152018)
		(end 312.347864 -318.33058)
		(width 0.14732)
		(layer "In6.Cu")
		(net "UPI_CPU0_CPU1_P2P2_DP<17>")
	)
	(segment
		(start 299.551852 -328.957178)
		(end 284.043628 -328.957178)
		(width 0.14732)
		(layer "In6.Cu")
		(net "UPI_CPU0_CPU1_P2P2_DP<17>")
	)
	(segment
		(start 103.574596 -285.985712)
		(end 103.565706 -285.980632)
		(width 0.0889)
		(layer "In6.Cu")
		(net "UPI_CPU0_CPU1_P2P2_DP<17>")
	)
	(segment
		(start 98.446082 -300.869096)
		(end 98.586798 -300.52899)
		(width 0.14732)
		(layer "In6.Cu")
		(net "UPI_CPU0_CPU1_P2P2_DP<17>")
	)
	(segment
		(start 106.716576 -277.173436)
		(end 106.737658 -277.251414)
		(width 0.0889)
		(layer "In6.Cu")
		(net "UPI_CPU0_CPU1_P2P2_DP<17>")
	)
	(segment
		(start 71.929752 -355.113336)
		(end 71.788782 -354.772976)
		(width 0.14732)
		(layer "In6.Cu")
		(net "UPI_CPU0_CPU1_P2P2_DP<17>")
	)
	(segment
		(start 337.045046 -290.723828)
		(end 335.242154 -292.52672)
		(width 0.14732)
		(layer "In6.Cu")
		(net "UPI_CPU0_CPU1_P2P2_DP<17>")
	)
	(segment
		(start 71.599298 -354.69449)
		(end 71.458582 -354.354384)
		(width 0.14732)
		(layer "In6.Cu")
		(net "UPI_CPU0_CPU1_P2P2_DP<17>")
	)
	(segment
		(start 338.725764 -287.617408)
		(end 338.726018 -287.617154)
		(width 0.0889)
		(layer "In6.Cu")
		(net "UPI_CPU0_CPU1_P2P2_DP<17>")
	)
	(segment
		(start 99.674172 -297.904662)
		(end 99.969828 -297.190668)
		(width 0.14732)
		(layer "In6.Cu")
		(net "UPI_CPU0_CPU1_P2P2_DP<17>")
	)
	(segment
		(start 71.802498 -328.237088)
		(end 71.900796 -327.881742)
		(width 0.14732)
		(layer "In6.Cu")
		(net "UPI_CPU0_CPU1_P2P2_DP<17>")
	)
	(segment
		(start 339.20176 -286.151066)
		(end 339.21065 -286.156146)
		(width 0.0889)
		(layer "In6.Cu")
		(net "UPI_CPU0_CPU1_P2P2_DP<17>")
	)
	(segment
		(start 337.979512 -288.902902)
		(end 337.979512 -289.243516)
		(width 0.0889)
		(layer "In6.Cu")
		(net "UPI_CPU0_CPU1_P2P2_DP<17>")
	)
	(segment
		(start 250.264422 -363.873796)
		(end 250.264422 -367.355628)
		(width 0.14732)
		(layer "In6.Cu")
		(net "UPI_CPU0_CPU1_P2P2_DP<17>")
	)
	(segment
		(start 248.25579 -363.565948)
		(end 247.947942 -363.873796)
		(width 0.14732)
		(layer "In6.Cu")
		(net "UPI_CPU0_CPU1_P2P2_DP<17>")
	)
	(segment
		(start 81.170018 -316.21095)
		(end 96.720914 -303.44872)
		(width 0.14732)
		(layer "In6.Cu")
		(net "UPI_CPU0_CPU1_P2P2_DP<17>")
	)
	(segment
		(start 71.851266 -355.302566)
		(end 71.929752 -355.113336)
		(width 0.14732)
		(layer "In6.Cu")
		(net "UPI_CPU0_CPU1_P2P2_DP<17>")
	)
	(segment
		(start 339.67166 -283.709364)
		(end 339.68055 -283.714444)
		(width 0.0889)
		(layer "In6.Cu")
		(net "UPI_CPU0_CPU1_P2P2_DP<17>")
	)
	(segment
		(start 312.80354 -318.053466)
		(end 312.448448 -318.152018)
		(width 0.14732)
		(layer "In6.Cu")
		(net "UPI_CPU0_CPU1_P2P2_DP<17>")
	)
	(segment
		(start 300.48835 -328.02068)
		(end 299.551852 -328.957178)
		(width 0.14732)
		(layer "In6.Cu")
		(net "UPI_CPU0_CPU1_P2P2_DP<17>")
	)
	(segment
		(start 98.838766 -299.920914)
		(end 98.979482 -299.580808)
		(width 0.14732)
		(layer "In6.Cu")
		(net "UPI_CPU0_CPU1_P2P2_DP<17>")
	)
	(segment
		(start 102.917244 -289.610038)
		(end 102.917244 -289.60953)
		(width 0.0889)
		(layer "In6.Cu")
		(net "UPI_CPU0_CPU1_P2P2_DP<17>")
	)
	(segment
		(start 312.347864 -318.33058)
		(end 310.262016 -318.910716)
		(width 0.14732)
		(layer "In6.Cu")
		(net "UPI_CPU0_CPU1_P2P2_DP<17>")
	)
	(segment
		(start 99.969828 -297.190668)
		(end 100.159312 -297.112182)
		(width 0.14732)
		(layer "In6.Cu")
		(net "UPI_CPU0_CPU1_P2P2_DP<17>")
	)
	(segment
		(start 99.422204 -298.512738)
		(end 99.611434 -298.434506)
		(width 0.14732)
		(layer "In6.Cu")
		(net "UPI_CPU0_CPU1_P2P2_DP<17>")
	)
	(segment
		(start 339.171026 -282.948888)
		(end 339.249258 -282.92806)
		(width 0.0889)
		(layer "In6.Cu")
		(net "UPI_CPU0_CPU1_P2P2_DP<17>")
	)
	(segment
		(start 104.97566 -279.644856)
		(end 104.98455 -279.639776)
		(width 0.0889)
		(layer "In6.Cu")
		(net "UPI_CPU0_CPU1_P2P2_DP<17>")
	)
	(segment
		(start 99.611434 -298.434506)
		(end 99.752404 -298.093892)
		(width 0.14732)
		(layer "In6.Cu")
		(net "UPI_CPU0_CPU1_P2P2_DP<17>")
	)
	(segment
		(start 339.014562 -283.219906)
		(end 339.171026 -282.948888)
		(width 0.0889)
		(layer "In6.Cu")
		(net "UPI_CPU0_CPU1_P2P2_DP<17>")
	)
	(segment
		(start 101.308662 -291.868606)
		(end 102.91699 -290.260278)
		(width 0.0889)
		(layer "In6.Cu")
		(net "UPI_CPU0_CPU1_P2P2_DP<17>")
	)
	(segment
		(start 103.09606 -287.783778)
		(end 103.10495 -287.778698)
		(width 0.0889)
		(layer "In6.Cu")
		(net "UPI_CPU0_CPU1_P2P2_DP<17>")
	)
	(segment
		(start 104.043734 -284.523688)
		(end 104.04475 -284.52318)
		(width 0.0889)
		(layer "In6.Cu")
		(net "UPI_CPU0_CPU1_P2P2_DP<17>")
	)
	(segment
		(start 251.389134 -363.565948)
		(end 250.57227 -363.565948)
		(width 0.14732)
		(layer "In6.Cu")
		(net "UPI_CPU0_CPU1_P2P2_DP<17>")
	)
	(segment
		(start 71.900796 -327.881742)
		(end 71.799704 -327.703688)
		(width 0.14732)
		(layer "In6.Cu")
		(net "UPI_CPU0_CPU1_P2P2_DP<17>")
	)
	(segment
		(start 100.486972 -294.837612)
		(end 100.586032 -294.738552)
		(width 0.0889)
		(layer "In6.Cu")
		(net "UPI_CPU0_CPU1_P2P2_DP<17>")
	)
	(segment
		(start 102.91699 -290.260278)
		(end 102.91699 -289.610292)
		(width 0.0889)
		(layer "In6.Cu")
		(net "UPI_CPU0_CPU1_P2P2_DP<17>")
	)
	(segment
		(start 339.68055 -284.353)
		(end 339.67166 -284.35808)
		(width 0.0889)
		(layer "In6.Cu")
		(net "UPI_CPU0_CPU1_P2P2_DP<17>")
	)
	(segment
		(start 250.57227 -363.565948)
		(end 250.264422 -363.873796)
		(width 0.14732)
		(layer "In6.Cu")
		(net "UPI_CPU0_CPU1_P2P2_DP<17>")
	)
	(segment
		(start 264.767822 -364.792006)
		(end 262.05688 -367.502948)
		(width 0.14732)
		(layer "In6.Cu")
		(net "UPI_CPU0_CPU1_P2P2_DP<17>")
	)
	(segment
		(start 247.947942 -367.355628)
		(end 247.800622 -367.502948)
		(width 0.14732)
		(layer "In6.Cu")
		(net "UPI_CPU0_CPU1_P2P2_DP<17>")
	)
	(segment
		(start 103.574596 -285.336996)
		(end 103.586788 -285.329884)
		(width 0.0889)
		(layer "In6.Cu")
		(net "UPI_CPU0_CPU1_P2P2_DP<17>")
	)
	(segment
		(start 98.979482 -299.580808)
		(end 99.168966 -299.502322)
		(width 0.14732)
		(layer "In6.Cu")
		(net "UPI_CPU0_CPU1_P2P2_DP<17>")
	)
	(segment
		(start 315.185044 -317.303404)
		(end 313.426094 -318.030606)
		(width 0.14732)
		(layer "In6.Cu")
		(net "UPI_CPU0_CPU1_P2P2_DP<17>")
	)
	(segment
		(start 71.62419 -328.337926)
		(end 71.802498 -328.237088)
		(width 0.14732)
		(layer "In6.Cu")
		(net "UPI_CPU0_CPU1_P2P2_DP<17>")
	)
	(segment
		(start 100.992178 -292.18509)
		(end 101.12883 -292.18509)
		(width 0.0889)
		(layer "In6.Cu")
		(net "UPI_CPU0_CPU1_P2P2_DP<17>")
	)
	(segment
		(start 100.586032 -294.560752)
		(end 100.486972 -294.461692)
		(width 0.0889)
		(layer "In6.Cu")
		(net "UPI_CPU0_CPU1_P2P2_DP<17>")
	)
	(segment
		(start 103.565706 -285.342076)
		(end 103.574596 -285.336996)
		(width 0.0889)
		(layer "In6.Cu")
		(net "UPI_CPU0_CPU1_P2P2_DP<17>")
	)
	(segment
		(start 264.767822 -344.200226)
		(end 264.767822 -364.792006)
		(width 0.14732)
		(layer "In6.Cu")
		(net "UPI_CPU0_CPU1_P2P2_DP<17>")
	)
	(segment
		(start 247.800622 -367.502948)
		(end 246.898414 -367.502948)
		(width 0.14732)
		(layer "In6.Cu")
		(net "UPI_CPU0_CPU1_P2P2_DP<17>")
	)
	(segment
		(start 301.30496 -327.20407)
		(end 300.953932 -327.555098)
		(width 0.14732)
		(layer "In6.Cu")
		(net "UPI_CPU0_CPU1_P2P2_DP<17>")
	)
	(segment
		(start 106.737658 -277.251414)
		(end 106.581194 -277.522432)
		(width 0.0889)
		(layer "In6.Cu")
		(net "UPI_CPU0_CPU1_P2P2_DP<17>")
	)
	(segment
		(start 100.586032 -294.007032)
		(end 100.486972 -293.907972)
		(width 0.0889)
		(layer "In6.Cu")
		(net "UPI_CPU0_CPU1_P2P2_DP<17>")
	)
	(segment
		(start 262.05688 -367.502948)
		(end 251.844302 -367.502948)
		(width 0.14732)
		(layer "In6.Cu")
		(net "UPI_CPU0_CPU1_P2P2_DP<17>")
	)
	(segment
		(start 333.676752 -294.867076)
		(end 331.838046 -300.92523)
		(width 0.14732)
		(layer "In6.Cu")
		(net "UPI_CPU0_CPU1_P2P2_DP<17>")
	)
	(segment
		(start 315.654436 -317.10884)
		(end 315.185298 -317.302896)
		(width 0.14732)
		(layer "In6.Cu")
		(net "UPI_CPU0_CPU1_P2P2_DP<17>")
	)
	(segment
		(start 99.309936 -299.161962)
		(end 99.231704 -298.972732)
		(width 0.14732)
		(layer "In6.Cu")
		(net "UPI_CPU0_CPU1_P2P2_DP<17>")
	)
	(segment
		(start 104.513634 -281.102054)
		(end 104.512618 -281.101546)
		(width 0.0889)
		(layer "In6.Cu")
		(net "UPI_CPU0_CPU1_P2P2_DP<17>")
	)
	(segment
		(start 104.97566 -282.900628)
		(end 104.98455 -282.895548)
		(width 0.0889)
		(layer "In6.Cu")
		(net "UPI_CPU0_CPU1_P2P2_DP<17>")
	)
	(segment
		(start 99.231704 -298.972732)
		(end 99.422204 -298.512738)
		(width 0.14732)
		(layer "In6.Cu")
		(net "UPI_CPU0_CPU1_P2P2_DP<17>")
	)
	(segment
		(start 100.486972 -294.283892)
		(end 100.586032 -294.184832)
		(width 0.0889)
		(layer "In6.Cu")
		(net "UPI_CPU0_CPU1_P2P2_DP<17>")
	)
	(segment
		(start 339.389212 -284.837632)
		(end 339.389212 -284.847538)
		(width 0.0889)
		(layer "In6.Cu")
		(net "UPI_CPU0_CPU1_P2P2_DP<17>")
	)
	(segment
		(start 105.44556 -278.83104)
		(end 105.45445 -278.82596)
		(width 0.0889)
		(layer "In6.Cu")
		(net "UPI_CPU0_CPU1_P2P2_DP<17>")
	)
	(segment
		(start 301.30496 -326.47001)
		(end 301.30496 -327.20407)
		(width 0.14732)
		(layer "In6.Cu")
		(net "UPI_CPU0_CPU1_P2P2_DP<17>")
	)
	(segment
		(start 100.529136 -295.323006)
		(end 100.529136 -295.300908)
		(width 0.0889)
		(layer "In6.Cu")
		(net "UPI_CPU0_CPU1_P2P2_DP<17>")
	)
	(arc
		(start 104.797098 -279.964134)
		(mid 104.844777 -279.781234)
		(end 104.97566 -279.644856)
		(width 0.0889)
		(layer "In6.Cu")
		(net "UPI_CPU0_CPU1_P2P2_DP<17>")
	)
	(arc
		(start 104.514396 -280.453846)
		(mid 104.717877 -280.253042)
		(end 104.797098 -279.978358)
		(width 0.0889)
		(layer "In6.Cu")
		(net "UPI_CPU0_CPU1_P2P2_DP<17>")
	)
	(arc
		(start 105.736898 -278.336502)
		(mid 105.784577 -278.153602)
		(end 105.91546 -278.017224)
		(width 0.0889)
		(layer "In6.Cu")
		(net "UPI_CPU0_CPU1_P2P2_DP<17>")
	)
	(arc
		(start 104.326944 -284.033722)
		(mid 104.374623 -283.850822)
		(end 104.505506 -283.714444)
		(width 0.0889)
		(layer "In6.Cu")
		(net "UPI_CPU0_CPU1_P2P2_DP<17>")
	)
	(arc
		(start 338.449158 -288.117788)
		(mid 338.398104 -288.292368)
		(end 338.27085 -288.422334)
		(width 0.0889)
		(layer "In6.Cu")
		(net "UPI_CPU0_CPU1_P2P2_DP<17>")
	)
	(arc
		(start 338.919566 -287.28924)
		(mid 338.871887 -287.47214)
		(end 338.741004 -287.608518)
		(width 0.0889)
		(layer "In6.Cu")
		(net "UPI_CPU0_CPU1_P2P2_DP<17>")
	)
	(arc
		(start 106.393996 -277.198074)
		(mid 106.552484 -277.149141)
		(end 106.716576 -277.173436)
		(width 0.0889)
		(layer "In6.Cu")
		(net "UPI_CPU0_CPU1_P2P2_DP<17>")
	)
	(arc
		(start 105.266998 -279.150318)
		(mid 105.314677 -278.967418)
		(end 105.44556 -278.83104)
		(width 0.0889)
		(layer "In6.Cu")
		(net "UPI_CPU0_CPU1_P2P2_DP<17>")
	)
	(arc
		(start 103.857298 -284.847538)
		(mid 103.904977 -284.664638)
		(end 104.03586 -284.52826)
		(width 0.0889)
		(layer "In6.Cu")
		(net "UPI_CPU0_CPU1_P2P2_DP<17>")
	)
	(arc
		(start 103.586788 -285.329884)
		(mid 103.785016 -285.124036)
		(end 103.857298 -284.847538)
		(width 0.0889)
		(layer "In6.Cu")
		(net "UPI_CPU0_CPU1_P2P2_DP<17>")
	)
	(arc
		(start 105.92435 -278.012144)
		(mid 106.125632 -277.814657)
		(end 106.206544 -277.54453)
		(width 0.0889)
		(layer "In6.Cu")
		(net "UPI_CPU0_CPU1_P2P2_DP<17>")
	)
	(arc
		(start 339.389212 -284.847538)
		(mid 339.341533 -285.030438)
		(end 339.21065 -285.166816)
		(width 0.0889)
		(layer "In6.Cu")
		(net "UPI_CPU0_CPU1_P2P2_DP<17>")
	)
	(arc
		(start 103.387144 -285.65475)
		(mid 103.436397 -285.47555)
		(end 103.565706 -285.342076)
		(width 0.0889)
		(layer "In6.Cu")
		(net "UPI_CPU0_CPU1_P2P2_DP<17>")
	)
	(arc
		(start 103.387144 -285.670752)
		(mid 103.387061 -285.662751)
		(end 103.387144 -285.65475)
		(width 0.0889)
		(layer "In6.Cu")
		(net "UPI_CPU0_CPU1_P2P2_DP<17>")
	)
	(arc
		(start 338.726018 -287.617154)
		(mid 338.523431 -287.823505)
		(end 338.449412 -288.103056)
		(width 0.0889)
		(layer "In6.Cu")
		(net "UPI_CPU0_CPU1_P2P2_DP<17>")
	)
	(arc
		(start 338.449412 -288.103056)
		(mid 338.44936 -288.110423)
		(end 338.449158 -288.117788)
		(width 0.0889)
		(layer "In6.Cu")
		(net "UPI_CPU0_CPU1_P2P2_DP<17>")
	)
	(arc
		(start 102.917498 -288.103056)
		(mid 102.965177 -287.920156)
		(end 103.09606 -287.783778)
		(width 0.0889)
		(layer "In6.Cu")
		(net "UPI_CPU0_CPU1_P2P2_DP<17>")
	)
	(arc
		(start 102.631748 -289.277806)
		(mid 102.522601 -289.193878)
		(end 102.447598 -289.078416)
		(width 0.0889)
		(layer "In6.Cu")
		(net "UPI_CPU0_CPU1_P2P2_DP<17>")
	)
	(arc
		(start 102.63505 -288.592768)
		(mid 102.837336 -288.393787)
		(end 102.917498 -288.121598)
		(width 0.0889)
		(layer "In6.Cu")
		(net "UPI_CPU0_CPU1_P2P2_DP<17>")
	)
	(arc
		(start 104.98455 -282.895548)
		(mid 105.185832 -282.698061)
		(end 105.266744 -282.427934)
		(width 0.0889)
		(layer "In6.Cu")
		(net "UPI_CPU0_CPU1_P2P2_DP<17>")
	)
	(arc
		(start 339.21065 -286.156146)
		(mid 339.389368 -286.475424)
		(end 339.21065 -286.794702)
		(width 0.0889)
		(layer "In6.Cu")
		(net "UPI_CPU0_CPU1_P2P2_DP<17>")
	)
	(arc
		(start 105.266744 -282.390342)
		(mid 105.187374 -282.116608)
		(end 104.98455 -281.916378)
		(width 0.0889)
		(layer "In6.Cu")
		(net "UPI_CPU0_CPU1_P2P2_DP<17>")
	)
	(arc
		(start 104.526588 -283.702252)
		(mid 104.724816 -283.496404)
		(end 104.797098 -283.219906)
		(width 0.0889)
		(layer "In6.Cu")
		(net "UPI_CPU0_CPU1_P2P2_DP<17>")
	)
	(arc
		(start 339.68055 -283.714444)
		(mid 339.859147 -284.033722)
		(end 339.68055 -284.353)
		(width 0.0889)
		(layer "In6.Cu")
		(net "UPI_CPU0_CPU1_P2P2_DP<17>")
	)
	(arc
		(start 104.04475 -284.52318)
		(mid 104.247573 -284.322949)
		(end 104.326944 -284.049216)
		(width 0.0889)
		(layer "In6.Cu")
		(net "UPI_CPU0_CPU1_P2P2_DP<17>")
	)
	(arc
		(start 104.505506 -281.097482)
		(mid 104.326909 -280.778204)
		(end 104.505506 -280.458926)
		(width 0.0889)
		(layer "In6.Cu")
		(net "UPI_CPU0_CPU1_P2P2_DP<17>")
	)
	(arc
		(start 103.580692 -286.961326)
		(mid 103.783279 -286.754975)
		(end 103.857298 -286.475424)
		(width 0.0889)
		(layer "In6.Cu")
		(net "UPI_CPU0_CPU1_P2P2_DP<17>")
	)
	(arc
		(start 103.857298 -286.4612)
		(mid 103.778079 -286.186515)
		(end 103.574596 -285.985712)
		(width 0.0889)
		(layer "In6.Cu")
		(net "UPI_CPU0_CPU1_P2P2_DP<17>")
	)
	(arc
		(start 339.20176 -285.171896)
		(mid 338.998937 -285.372127)
		(end 338.919566 -285.64586)
		(width 0.0889)
		(layer "In6.Cu")
		(net "UPI_CPU0_CPU1_P2P2_DP<17>")
	)
	(arc
		(start 104.97566 -281.911298)
		(mid 104.844746 -281.774938)
		(end 104.797098 -281.59202)
		(width 0.0889)
		(layer "In6.Cu")
		(net "UPI_CPU0_CPU1_P2P2_DP<17>")
	)
	(arc
		(start 104.797098 -283.219906)
		(mid 104.844777 -283.037006)
		(end 104.97566 -282.900628)
		(width 0.0889)
		(layer "In6.Cu")
		(net "UPI_CPU0_CPU1_P2P2_DP<17>")
	)
	(arc
		(start 104.797098 -281.59202)
		(mid 104.723107 -281.312454)
		(end 104.520492 -281.106118)
		(width 0.0889)
		(layer "In6.Cu")
		(net "UPI_CPU0_CPU1_P2P2_DP<17>")
	)
	(arc
		(start 102.447598 -288.917126)
		(mid 102.495277 -288.734226)
		(end 102.62616 -288.597848)
		(width 0.0889)
		(layer "In6.Cu")
		(net "UPI_CPU0_CPU1_P2P2_DP<17>")
	)
	(arc
		(start 103.387144 -287.28924)
		(mid 103.434823 -287.10634)
		(end 103.565706 -286.969962)
		(width 0.0889)
		(layer "In6.Cu")
		(net "UPI_CPU0_CPU1_P2P2_DP<17>")
	)
	(arc
		(start 339.388958 -283.205428)
		(mid 339.389153 -283.212666)
		(end 339.389212 -283.219906)
		(width 0.0889)
		(layer "In6.Cu")
		(net "UPI_CPU0_CPU1_P2P2_DP<17>")
	)
	(arc
		(start 103.565706 -285.980632)
		(mid 103.437112 -285.848358)
		(end 103.387144 -285.670752)
		(width 0.0889)
		(layer "In6.Cu")
		(net "UPI_CPU0_CPU1_P2P2_DP<17>")
	)
	(arc
		(start 339.67166 -284.35808)
		(mid 339.467325 -284.560685)
		(end 339.389212 -284.837632)
		(width 0.0889)
		(layer "In6.Cu")
		(net "UPI_CPU0_CPU1_P2P2_DP<17>")
	)
	(arc
		(start 103.10495 -287.778698)
		(mid 103.307773 -287.578467)
		(end 103.387144 -287.304734)
		(width 0.0889)
		(layer "In6.Cu")
		(net "UPI_CPU0_CPU1_P2P2_DP<17>")
	)
	(arc
		(start 104.990646 -279.63622)
		(mid 105.193059 -279.429807)
		(end 105.266998 -279.150318)
		(width 0.0889)
		(layer "In6.Cu")
		(net "UPI_CPU0_CPU1_P2P2_DP<17>")
	)
	(arc
		(start 338.919566 -285.683452)
		(mid 339.000477 -285.95358)
		(end 339.20176 -286.151066)
		(width 0.0889)
		(layer "In6.Cu")
		(net "UPI_CPU0_CPU1_P2P2_DP<17>")
	)
	(arc
		(start 106.206544 -277.522432)
		(mid 106.254223 -277.339532)
		(end 106.385106 -277.203154)
		(width 0.0889)
		(layer "In6.Cu")
		(net "UPI_CPU0_CPU1_P2P2_DP<17>")
	)
	(arc
		(start 339.249258 -282.92806)
		(mid 339.349207 -283.051586)
		(end 339.388958 -283.205428)
		(width 0.0889)
		(layer "In6.Cu")
		(net "UPI_CPU0_CPU1_P2P2_DP<17>")
	)
	(arc
		(start 338.26196 -288.427414)
		(mid 338.05865 -288.628291)
		(end 337.979512 -288.902902)
		(width 0.0889)
		(layer "In6.Cu")
		(net "UPI_CPU0_CPU1_P2P2_DP<17>")
	)
	(arc
		(start 339.20176 -286.799782)
		(mid 338.998937 -287.000013)
		(end 338.919566 -287.273746)
		(width 0.0889)
		(layer "In6.Cu")
		(net "UPI_CPU0_CPU1_P2P2_DP<17>")
	)
	(arc
		(start 102.917244 -289.60953)
		(mid 102.805906 -289.41663)
		(end 102.631748 -289.277806)
		(width 0.0889)
		(layer "In6.Cu")
		(net "UPI_CPU0_CPU1_P2P2_DP<17>")
	)
	(arc
		(start 105.45445 -278.82596)
		(mid 105.65751 -278.625151)
		(end 105.736644 -278.350726)
		(width 0.0889)
		(layer "In6.Cu")
		(net "UPI_CPU0_CPU1_P2P2_DP<17>")
	)
	(arc
		(start 339.389212 -283.229812)
		(mid 339.467323 -283.506761)
		(end 339.67166 -283.709364)
		(width 0.0889)
		(layer "In6.Cu")
		(net "UPI_CPU0_CPU1_P2P2_DP<17>")
	)
	(segment
		(start 340.894416 -281.056334)
		(end 340.894416 -281.591766)
		(width 0.13208)
		(layer "F.Cu")
		(net "UPI_CPU0_CPU1_P2P2_DP<16>")
	)
	(segment
		(start 102.352094 -276.708616)
		(end 102.352094 -276.172676)
		(width 0.13208)
		(layer "F.Cu")
		(net "UPI_CPU0_CPU1_P2P2_DP<16>")
	)
	(segment
		(start 340.894416 -281.591766)
		(end 340.894162 -281.59202)
		(width 0.13208)
		(layer "F.Cu")
		(net "UPI_CPU0_CPU1_P2P2_DP<16>")
	)
	(segment
		(start 340.894162 -281.05608)
		(end 340.894416 -281.056334)
		(width 0.13208)
		(layer "F.Cu")
		(net "UPI_CPU0_CPU1_P2P2_DP<16>")
	)
	(segment
		(start 102.536752 -285.173674)
		(end 102.539546 -285.171896)
		(width 0.0889)
		(layer "In6.Cu")
		(net "UPI_CPU0_CPU1_P2P2_DP<16>")
	)
	(segment
		(start 101.787198 -288.103056)
		(end 101.787198 -288.087562)
		(width 0.0889)
		(layer "In6.Cu")
		(net "UPI_CPU0_CPU1_P2P2_DP<16>")
	)
	(segment
		(start 305.736752 -326.300338)
		(end 305.49596 -327.664318)
		(width 0.14732)
		(layer "In6.Cu")
		(net "UPI_CPU0_CPU1_P2P2_DP<16>")
	)
	(segment
		(start 103.196644 -282.424378)
		(end 103.196644 -282.39593)
		(width 0.0889)
		(layer "In6.Cu")
		(net "UPI_CPU0_CPU1_P2P2_DP<16>")
	)
	(segment
		(start 102.256844 -285.679896)
		(end 102.256844 -285.661354)
		(width 0.0889)
		(layer "In6.Cu")
		(net "UPI_CPU0_CPU1_P2P2_DP<16>")
	)
	(segment
		(start 249.832622 -369.743228)
		(end 250.016264 -370.783612)
		(width 0.14732)
		(layer "In6.Cu")
		(net "UPI_CPU0_CPU1_P2P2_DP<16>")
	)
	(segment
		(start 101.317298 -289.114738)
		(end 101.317298 -288.898584)
		(width 0.0889)
		(layer "In6.Cu")
		(net "UPI_CPU0_CPU1_P2P2_DP<16>")
	)
	(segment
		(start 105.546144 -276.717252)
		(end 105.546144 -276.69998)
		(width 0.0889)
		(layer "In6.Cu")
		(net "UPI_CPU0_CPU1_P2P2_DP<16>")
	)
	(segment
		(start 104.888792 -277.84679)
		(end 104.897682 -277.84171)
		(width 0.0889)
		(layer "In6.Cu")
		(net "UPI_CPU0_CPU1_P2P2_DP<16>")
	)
	(segment
		(start 102.352094 -276.708362)
		(end 102.352094 -276.708616)
		(width 0.0889)
		(layer "In6.Cu")
		(net "UPI_CPU0_CPU1_P2P2_DP<16>")
	)
	(segment
		(start 340.228428 -282.725114)
		(end 340.236302 -282.729686)
		(width 0.0889)
		(layer "In6.Cu")
		(net "UPI_CPU0_CPU1_P2P2_DP<16>")
	)
	(segment
		(start 306.071016 -325.822818)
		(end 306.070762 -325.823072)
		(width 0.14732)
		(layer "In6.Cu")
		(net "UPI_CPU0_CPU1_P2P2_DP<16>")
	)
	(segment
		(start 340.237318 -286.964882)
		(end 340.228428 -286.969962)
		(width 0.0889)
		(layer "In6.Cu")
		(net "UPI_CPU0_CPU1_P2P2_DP<16>")
	)
	(segment
		(start 78.458568 -367.082324)
		(end 73.460356 -362.084112)
		(width 0.14732)
		(layer "In6.Cu")
		(net "UPI_CPU0_CPU1_P2P2_DP<16>")
	)
	(segment
		(start 250.533662 -369.470432)
		(end 249.951748 -369.573048)
		(width 0.14732)
		(layer "In6.Cu")
		(net "UPI_CPU0_CPU1_P2P2_DP<16>")
	)
	(segment
		(start 309.82666 -321.773804)
		(end 309.094124 -322.9356)
		(width 0.14732)
		(layer "In6.Cu")
		(net "UPI_CPU0_CPU1_P2P2_DP<16>")
	)
	(segment
		(start 340.894162 -281.59202)
		(end 340.737698 -281.321002)
		(width 0.0889)
		(layer "In6.Cu")
		(net "UPI_CPU0_CPU1_P2P2_DP<16>")
	)
	(segment
		(start 303.208944 -330.06792)
		(end 284.261052 -330.06792)
		(width 0.14732)
		(layer "In6.Cu")
		(net "UPI_CPU0_CPU1_P2P2_DP<16>")
	)
	(segment
		(start 101.599746 -288.427414)
		(end 101.600508 -288.426906)
		(width 0.0889)
		(layer "In6.Cu")
		(net "UPI_CPU0_CPU1_P2P2_DP<16>")
	)
	(segment
		(start 339.766656 -287.779206)
		(end 339.764116 -287.78073)
		(width 0.0889)
		(layer "In6.Cu")
		(net "UPI_CPU0_CPU1_P2P2_DP<16>")
	)
	(segment
		(start 338.615274 -290.731194)
		(end 338.456524 -290.889944)
		(width 0.0889)
		(layer "In6.Cu")
		(net "UPI_CPU0_CPU1_P2P2_DP<16>")
	)
	(segment
		(start 125.808232 -379.379988)
		(end 98.282506 -375.293636)
		(width 0.14732)
		(layer "In6.Cu")
		(net "UPI_CPU0_CPU1_P2P2_DP<16>")
	)
	(segment
		(start 239.799876 -369.881658)
		(end 212.31225 -374.726708)
		(width 0.14732)
		(layer "In6.Cu")
		(net "UPI_CPU0_CPU1_P2P2_DP<16>")
	)
	(segment
		(start 250.703842 -369.589558)
		(end 250.533662 -369.470432)
		(width 0.14732)
		(layer "In6.Cu")
		(net "UPI_CPU0_CPU1_P2P2_DP<16>")
	)
	(segment
		(start 266.13739 -344.417142)
		(end 266.13739 -365.15167)
		(width 0.14732)
		(layer "In6.Cu")
		(net "UPI_CPU0_CPU1_P2P2_DP<16>")
	)
	(segment
		(start 199.037448 -372.385844)
		(end 159.362902 -379.379988)
		(width 0.14732)
		(layer "In6.Cu")
		(net "UPI_CPU0_CPU1_P2P2_DP<16>")
	)
	(segment
		(start 306.070762 -325.823072)
		(end 305.736752 -326.300338)
		(width 0.14732)
		(layer "In6.Cu")
		(net "UPI_CPU0_CPU1_P2P2_DP<16>")
	)
	(segment
		(start 253.526544 -370.477288)
		(end 253.169674 -370.227098)
		(width 0.14732)
		(layer "In6.Cu")
		(net "UPI_CPU0_CPU1_P2P2_DP<16>")
	)
	(segment
		(start 69.773038 -353.182428)
		(end 69.773038 -335.000092)
		(width 0.14732)
		(layer "In6.Cu")
		(net "UPI_CPU0_CPU1_P2P2_DP<16>")
	)
	(segment
		(start 339.764116 -287.78073)
		(end 339.758528 -287.783778)
		(width 0.0889)
		(layer "In6.Cu")
		(net "UPI_CPU0_CPU1_P2P2_DP<16>")
	)
	(segment
		(start 105.35285 -277.03653)
		(end 105.358184 -277.033482)
		(width 0.0889)
		(layer "In6.Cu")
		(net "UPI_CPU0_CPU1_P2P2_DP<16>")
	)
	(segment
		(start 99.379786 -293.187628)
		(end 99.421696 -293.145718)
		(width 0.0889)
		(layer "In6.Cu")
		(net "UPI_CPU0_CPU1_P2P2_DP<16>")
	)
	(segment
		(start 250.016264 -370.783612)
		(end 249.766074 -371.140228)
		(width 0.14732)
		(layer "In6.Cu")
		(net "UPI_CPU0_CPU1_P2P2_DP<16>")
	)
	(segment
		(start 252.298708 -370.381022)
		(end 252.048518 -370.737384)
		(width 0.14732)
		(layer "In6.Cu")
		(net "UPI_CPU0_CPU1_P2P2_DP<16>")
	)
	(segment
		(start 340.519512 -281.59202)
		(end 340.519512 -281.607514)
		(width 0.0889)
		(layer "In6.Cu")
		(net "UPI_CPU0_CPU1_P2P2_DP<16>")
	)
	(segment
		(start 334.598518 -295.659302)
		(end 332.826106 -301.50054)
		(width 0.14732)
		(layer "In6.Cu")
		(net "UPI_CPU0_CPU1_P2P2_DP<16>")
	)
	(segment
		(start 249.951748 -369.573048)
		(end 249.832622 -369.743228)
		(width 0.14732)
		(layer "In6.Cu")
		(net "UPI_CPU0_CPU1_P2P2_DP<16>")
	)
	(segment
		(start 102.535736 -285.174182)
		(end 102.536752 -285.173674)
		(width 0.0889)
		(layer "In6.Cu")
		(net "UPI_CPU0_CPU1_P2P2_DP<16>")
	)
	(segment
		(start 255.452118 -369.824508)
		(end 255.26873 -368.784378)
		(width 0.14732)
		(layer "In6.Cu")
		(net "UPI_CPU0_CPU1_P2P2_DP<16>")
	)
	(segment
		(start 105.358184 -277.033482)
		(end 105.358946 -277.032974)
		(width 0.0889)
		(layer "In6.Cu")
		(net "UPI_CPU0_CPU1_P2P2_DP<16>")
	)
	(segment
		(start 103.948992 -279.474676)
		(end 103.957882 -279.469596)
		(width 0.0889)
		(layer "In6.Cu")
		(net "UPI_CPU0_CPU1_P2P2_DP<16>")
	)
	(segment
		(start 102.726744 -284.856174)
		(end 102.726744 -284.837632)
		(width 0.0889)
		(layer "In6.Cu")
		(net "UPI_CPU0_CPU1_P2P2_DP<16>")
	)
	(segment
		(start 249.766074 -371.140228)
		(end 248.352818 -371.389402)
		(width 0.14732)
		(layer "In6.Cu")
		(net "UPI_CPU0_CPU1_P2P2_DP<16>")
	)
	(segment
		(start 340.519512 -283.197808)
		(end 340.519512 -283.219906)
		(width 0.0889)
		(layer "In6.Cu")
		(net "UPI_CPU0_CPU1_P2P2_DP<16>")
	)
	(segment
		(start 340.707218 -284.52318)
		(end 340.706202 -284.523688)
		(width 0.0889)
		(layer "In6.Cu")
		(net "UPI_CPU0_CPU1_P2P2_DP<16>")
	)
	(segment
		(start 101.787198 -289.645598)
		(end 101.786944 -289.64509)
		(width 0.0889)
		(layer "In6.Cu")
		(net "UPI_CPU0_CPU1_P2P2_DP<16>")
	)
	(segment
		(start 252.986286 -369.186968)
		(end 252.816106 -369.067842)
		(width 0.14732)
		(layer "In6.Cu")
		(net "UPI_CPU0_CPU1_P2P2_DP<16>")
	)
	(segment
		(start 102.256844 -287.28924)
		(end 102.256844 -287.279334)
		(width 0.0889)
		(layer "In6.Cu")
		(net "UPI_CPU0_CPU1_P2P2_DP<16>")
	)
	(segment
		(start 266.13739 -365.15167)
		(end 262.371332 -368.917728)
		(width 0.14732)
		(layer "In6.Cu")
		(net "UPI_CPU0_CPU1_P2P2_DP<16>")
	)
	(segment
		(start 340.519766 -286.4612)
		(end 340.519766 -286.48533)
		(width 0.0889)
		(layer "In6.Cu")
		(net "UPI_CPU0_CPU1_P2P2_DP<16>")
	)
	(segment
		(start 340.706202 -284.523688)
		(end 340.698328 -284.52826)
		(width 0.0889)
		(layer "In6.Cu")
		(net "UPI_CPU0_CPU1_P2P2_DP<16>")
	)
	(segment
		(start 338.615528 -289.723322)
		(end 338.615274 -289.724592)
		(width 0.0889)
		(layer "In6.Cu")
		(net "UPI_CPU0_CPU1_P2P2_DP<16>")
	)
	(segment
		(start 103.196644 -284.033722)
		(end 103.196644 -284.023816)
		(width 0.0889)
		(layer "In6.Cu")
		(net "UPI_CPU0_CPU1_P2P2_DP<16>")
	)
	(segment
		(start 103.942896 -279.478232)
		(end 103.948992 -279.474676)
		(width 0.0889)
		(layer "In6.Cu")
		(net "UPI_CPU0_CPU1_P2P2_DP<16>")
	)
	(segment
		(start 99.421696 -293.145718)
		(end 99.421696 -292.474904)
		(width 0.0889)
		(layer "In6.Cu")
		(net "UPI_CPU0_CPU1_P2P2_DP<16>")
	)
	(segment
		(start 99.421696 -292.474904)
		(end 101.787198 -290.109402)
		(width 0.0889)
		(layer "In6.Cu")
		(net "UPI_CPU0_CPU1_P2P2_DP<16>")
	)
	(segment
		(start 248.352818 -371.389402)
		(end 239.799876 -369.881658)
		(width 0.14732)
		(layer "In6.Cu")
		(net "UPI_CPU0_CPU1_P2P2_DP<16>")
	)
	(segment
		(start 305.49596 -327.664318)
		(end 305.021488 -328.255376)
		(width 0.14732)
		(layer "In6.Cu")
		(net "UPI_CPU0_CPU1_P2P2_DP<16>")
	)
	(segment
		(start 102.540054 -286.799274)
		(end 102.542594 -286.79775)
		(width 0.0889)
		(layer "In6.Cu")
		(net "UPI_CPU0_CPU1_P2P2_DP<16>")
	)
	(segment
		(start 73.460356 -362.084112)
		(end 69.773038 -353.182428)
		(width 0.14732)
		(layer "In6.Cu")
		(net "UPI_CPU0_CPU1_P2P2_DP<16>")
	)
	(segment
		(start 252.816106 -369.067842)
		(end 252.234192 -369.170458)
		(width 0.14732)
		(layer "In6.Cu")
		(net "UPI_CPU0_CPU1_P2P2_DP<16>")
	)
	(segment
		(start 332.826106 -301.50054)
		(end 315.296296 -319.03035)
		(width 0.14732)
		(layer "In6.Cu")
		(net "UPI_CPU0_CPU1_P2P2_DP<16>")
	)
	(segment
		(start 69.773038 -335.000092)
		(end 70.407276 -328.556874)
		(width 0.14732)
		(layer "In6.Cu")
		(net "UPI_CPU0_CPU1_P2P2_DP<16>")
	)
	(segment
		(start 95.911924 -302.681386)
		(end 97.183956 -300.966124)
		(width 0.14732)
		(layer "In6.Cu")
		(net "UPI_CPU0_CPU1_P2P2_DP<16>")
	)
	(segment
		(start 262.371332 -368.917728)
		(end 255.808734 -370.074698)
		(width 0.14732)
		(layer "In6.Cu")
		(net "UPI_CPU0_CPU1_P2P2_DP<16>")
	)
	(segment
		(start 103.487982 -282.900628)
		(end 103.479092 -282.895548)
		(width 0.0889)
		(layer "In6.Cu")
		(net "UPI_CPU0_CPU1_P2P2_DP<16>")
	)
	(segment
		(start 252.234192 -369.170458)
		(end 252.115066 -369.340638)
		(width 0.14732)
		(layer "In6.Cu")
		(net "UPI_CPU0_CPU1_P2P2_DP<16>")
	)
	(segment
		(start 102.548182 -286.156146)
		(end 102.540054 -286.151574)
		(width 0.0889)
		(layer "In6.Cu")
		(net "UPI_CPU0_CPU1_P2P2_DP<16>")
	)
	(segment
		(start 103.479854 -283.543756)
		(end 103.487982 -283.539184)
		(width 0.0889)
		(layer "In6.Cu")
		(net "UPI_CPU0_CPU1_P2P2_DP<16>")
	)
	(segment
		(start 104.433878 -276.392894)
		(end 104.419146 -276.384258)
		(width 0.0889)
		(layer "In6.Cu")
		(net "UPI_CPU0_CPU1_P2P2_DP<16>")
	)
	(segment
		(start 103.479092 -283.544264)
		(end 103.479854 -283.543756)
		(width 0.0889)
		(layer "In6.Cu")
		(net "UPI_CPU0_CPU1_P2P2_DP<16>")
	)
	(segment
		(start 212.31225 -374.726708)
		(end 199.037448 -372.385844)
		(width 0.14732)
		(layer "In6.Cu")
		(net "UPI_CPU0_CPU1_P2P2_DP<16>")
	)
	(segment
		(start 104.606344 -278.345138)
		(end 104.606344 -278.31796)
		(width 0.0889)
		(layer "In6.Cu")
		(net "UPI_CPU0_CPU1_P2P2_DP<16>")
	)
	(segment
		(start 103.196644 -280.78811)
		(end 103.196644 -280.759662)
		(width 0.0889)
		(layer "In6.Cu")
		(net "UPI_CPU0_CPU1_P2P2_DP<16>")
	)
	(segment
		(start 340.049866 -287.28924)
		(end 340.049866 -287.299146)
		(width 0.0889)
		(layer "In6.Cu")
		(net "UPI_CPU0_CPU1_P2P2_DP<16>")
	)
	(segment
		(start 307.58892 -324.516496)
		(end 306.40528 -325.345298)
		(width 0.14732)
		(layer "In6.Cu")
		(net "UPI_CPU0_CPU1_P2P2_DP<16>")
	)
	(segment
		(start 103.009192 -284.35808)
		(end 103.018082 -284.353)
		(width 0.0889)
		(layer "In6.Cu")
		(net "UPI_CPU0_CPU1_P2P2_DP<16>")
	)
	(segment
		(start 340.237318 -282.081478)
		(end 340.228428 -282.086558)
		(width 0.0889)
		(layer "In6.Cu")
		(net "UPI_CPU0_CPU1_P2P2_DP<16>")
	)
	(segment
		(start 338.615274 -289.724592)
		(end 338.615274 -290.731194)
		(width 0.0889)
		(layer "In6.Cu")
		(net "UPI_CPU0_CPU1_P2P2_DP<16>")
	)
	(segment
		(start 102.540054 -286.151574)
		(end 102.539292 -286.151066)
		(width 0.0889)
		(layer "In6.Cu")
		(net "UPI_CPU0_CPU1_P2P2_DP<16>")
	)
	(segment
		(start 340.698074 -283.539184)
		(end 340.706964 -283.544264)
		(width 0.0889)
		(layer "In6.Cu")
		(net "UPI_CPU0_CPU1_P2P2_DP<16>")
	)
	(segment
		(start 254.516636 -368.767868)
		(end 254.39751 -368.938048)
		(width 0.14732)
		(layer "In6.Cu")
		(net "UPI_CPU0_CPU1_P2P2_DP<16>")
	)
	(segment
		(start 254.330962 -370.334794)
		(end 253.526544 -370.477288)
		(width 0.14732)
		(layer "In6.Cu")
		(net "UPI_CPU0_CPU1_P2P2_DP<16>")
	)
	(segment
		(start 104.41305 -278.664416)
		(end 104.418384 -278.661368)
		(width 0.0889)
		(layer "In6.Cu")
		(net "UPI_CPU0_CPU1_P2P2_DP<16>")
	)
	(segment
		(start 277.818088 -332.736444)
		(end 266.13739 -344.417142)
		(width 0.14732)
		(layer "In6.Cu")
		(net "UPI_CPU0_CPU1_P2P2_DP<16>")
	)
	(segment
		(start 339.579966 -288.103056)
		(end 339.579966 -288.11728)
		(width 0.0889)
		(layer "In6.Cu")
		(net "UPI_CPU0_CPU1_P2P2_DP<16>")
	)
	(segment
		(start 102.542594 -286.79775)
		(end 102.548182 -286.794702)
		(width 0.0889)
		(layer "In6.Cu")
		(net "UPI_CPU0_CPU1_P2P2_DP<16>")
	)
	(segment
		(start 159.362902 -379.379988)
		(end 125.808232 -379.379988)
		(width 0.14732)
		(layer "In6.Cu")
		(net "UPI_CPU0_CPU1_P2P2_DP<16>")
	)
	(segment
		(start 102.539292 -286.799782)
		(end 102.540054 -286.799274)
		(width 0.0889)
		(layer "In6.Cu")
		(net "UPI_CPU0_CPU1_P2P2_DP<16>")
	)
	(segment
		(start 255.808734 -370.074698)
		(end 255.452118 -369.824508)
		(width 0.14732)
		(layer "In6.Cu")
		(net "UPI_CPU0_CPU1_P2P2_DP<16>")
	)
	(segment
		(start 336.304382 -293.10203)
		(end 336.306668 -293.104316)
		(width 0.14732)
		(layer "In6.Cu")
		(net "UPI_CPU0_CPU1_P2P2_DP<16>")
	)
	(segment
		(start 102.508304 -276.437598)
		(end 102.352094 -276.708362)
		(width 0.0889)
		(layer "In6.Cu")
		(net "UPI_CPU0_CPU1_P2P2_DP<16>")
	)
	(segment
		(start 338.448396 -290.958016)
		(end 336.304382 -293.10203)
		(width 0.14732)
		(layer "In6.Cu")
		(net "UPI_CPU0_CPU1_P2P2_DP<16>")
	)
	(segment
		(start 250.88723 -370.629688)
		(end 250.703842 -369.589558)
		(width 0.14732)
		(layer "In6.Cu")
		(net "UPI_CPU0_CPU1_P2P2_DP<16>")
	)
	(segment
		(start 338.456524 -290.949888)
		(end 338.448396 -290.958016)
		(width 0.0889)
		(layer "In6.Cu")
		(net "UPI_CPU0_CPU1_P2P2_DP<16>")
	)
	(segment
		(start 340.737698 -281.321002)
		(end 340.659466 -281.300174)
		(width 0.0889)
		(layer "In6.Cu")
		(net "UPI_CPU0_CPU1_P2P2_DP<16>")
	)
	(segment
		(start 305.021488 -328.255376)
		(end 303.208944 -330.06792)
		(width 0.14732)
		(layer "In6.Cu")
		(net "UPI_CPU0_CPU1_P2P2_DP<16>")
	)
	(segment
		(start 98.282506 -375.293636)
		(end 78.458568 -367.082324)
		(width 0.14732)
		(layer "In6.Cu")
		(net "UPI_CPU0_CPU1_P2P2_DP<16>")
	)
	(segment
		(start 315.296296 -319.03035)
		(end 310.941466 -320.834004)
		(width 0.14732)
		(layer "In6.Cu")
		(net "UPI_CPU0_CPU1_P2P2_DP<16>")
	)
	(segment
		(start 102.597458 -276.413722)
		(end 102.508304 -276.437598)
		(width 0.0889)
		(layer "In6.Cu")
		(net "UPI_CPU0_CPU1_P2P2_DP<16>")
	)
	(segment
		(start 103.479092 -281.916378)
		(end 103.487982 -281.911298)
		(width 0.0889)
		(layer "In6.Cu")
		(net "UPI_CPU0_CPU1_P2P2_DP<16>")
	)
	(segment
		(start 309.094124 -322.9356)
		(end 307.58892 -324.516496)
		(width 0.14732)
		(layer "In6.Cu")
		(net "UPI_CPU0_CPU1_P2P2_DP<16>")
	)
	(segment
		(start 251.2441 -370.879878)
		(end 250.88723 -370.629688)
		(width 0.14732)
		(layer "In6.Cu")
		(net "UPI_CPU0_CPU1_P2P2_DP<16>")
	)
	(segment
		(start 254.581152 -369.978432)
		(end 254.330962 -370.334794)
		(width 0.14732)
		(layer "In6.Cu")
		(net "UPI_CPU0_CPU1_P2P2_DP<16>")
	)
	(segment
		(start 336.306668 -293.104316)
		(end 334.598518 -295.659302)
		(width 0.14732)
		(layer "In6.Cu")
		(net "UPI_CPU0_CPU1_P2P2_DP<16>")
	)
	(segment
		(start 99.379786 -295.665398)
		(end 99.379786 -293.209726)
		(width 0.14732)
		(layer "In6.Cu")
		(net "UPI_CPU0_CPU1_P2P2_DP<16>")
	)
	(segment
		(start 101.787198 -290.109402)
		(end 101.787198 -289.645598)
		(width 0.0889)
		(layer "In6.Cu")
		(net "UPI_CPU0_CPU1_P2P2_DP<16>")
	)
	(segment
		(start 284.261052 -330.06792)
		(end 277.818088 -332.736444)
		(width 0.14732)
		(layer "In6.Cu")
		(net "UPI_CPU0_CPU1_P2P2_DP<16>")
	)
	(segment
		(start 104.418384 -278.661368)
		(end 104.419146 -278.66086)
		(width 0.0889)
		(layer "In6.Cu")
		(net "UPI_CPU0_CPU1_P2P2_DP<16>")
	)
	(segment
		(start 340.049866 -285.652718)
		(end 340.049866 -285.66999)
		(width 0.0889)
		(layer "In6.Cu")
		(net "UPI_CPU0_CPU1_P2P2_DP<16>")
	)
	(segment
		(start 340.236302 -282.729686)
		(end 340.237318 -282.730194)
		(width 0.0889)
		(layer "In6.Cu")
		(net "UPI_CPU0_CPU1_P2P2_DP<16>")
	)
	(segment
		(start 255.09855 -368.665252)
		(end 254.516636 -368.767868)
		(width 0.14732)
		(layer "In6.Cu")
		(net "UPI_CPU0_CPU1_P2P2_DP<16>")
	)
	(segment
		(start 254.39751 -368.938048)
		(end 254.581152 -369.978432)
		(width 0.14732)
		(layer "In6.Cu")
		(net "UPI_CPU0_CPU1_P2P2_DP<16>")
	)
	(segment
		(start 339.110066 -288.917126)
		(end 339.110066 -289.114484)
		(width 0.0889)
		(layer "In6.Cu")
		(net "UPI_CPU0_CPU1_P2P2_DP<16>")
	)
	(segment
		(start 310.941466 -320.834004)
		(end 309.82666 -321.773804)
		(width 0.14732)
		(layer "In6.Cu")
		(net "UPI_CPU0_CPU1_P2P2_DP<16>")
	)
	(segment
		(start 252.115066 -369.340638)
		(end 252.298708 -370.381022)
		(width 0.14732)
		(layer "In6.Cu")
		(net "UPI_CPU0_CPU1_P2P2_DP<16>")
	)
	(segment
		(start 70.852284 -326.9488)
		(end 72.630792 -323.18833)
		(width 0.14732)
		(layer "In6.Cu")
		(net "UPI_CPU0_CPU1_P2P2_DP<16>")
	)
	(segment
		(start 80.44053 -315.378592)
		(end 95.911924 -302.681386)
		(width 0.14732)
		(layer "In6.Cu")
		(net "UPI_CPU0_CPU1_P2P2_DP<16>")
	)
	(segment
		(start 255.26873 -368.784378)
		(end 255.09855 -368.665252)
		(width 0.14732)
		(layer "In6.Cu")
		(net "UPI_CPU0_CPU1_P2P2_DP<16>")
	)
	(segment
		(start 103.487982 -281.272742)
		(end 103.479092 -281.267662)
		(width 0.0889)
		(layer "In6.Cu")
		(net "UPI_CPU0_CPU1_P2P2_DP<16>")
	)
	(segment
		(start 103.479092 -280.288492)
		(end 103.487982 -280.283412)
		(width 0.0889)
		(layer "In6.Cu")
		(net "UPI_CPU0_CPU1_P2P2_DP<16>")
	)
	(segment
		(start 97.183956 -300.966124)
		(end 99.379786 -295.665398)
		(width 0.14732)
		(layer "In6.Cu")
		(net "UPI_CPU0_CPU1_P2P2_DP<16>")
	)
	(segment
		(start 339.297518 -288.592768)
		(end 339.288628 -288.597848)
		(width 0.0889)
		(layer "In6.Cu")
		(net "UPI_CPU0_CPU1_P2P2_DP<16>")
	)
	(segment
		(start 72.630792 -323.18833)
		(end 80.44053 -315.378592)
		(width 0.14732)
		(layer "In6.Cu")
		(net "UPI_CPU0_CPU1_P2P2_DP<16>")
	)
	(segment
		(start 253.169674 -370.227098)
		(end 252.986286 -369.186968)
		(width 0.14732)
		(layer "In6.Cu")
		(net "UPI_CPU0_CPU1_P2P2_DP<16>")
	)
	(segment
		(start 340.989412 -284.023816)
		(end 340.989412 -284.049216)
		(width 0.0889)
		(layer "In6.Cu")
		(net "UPI_CPU0_CPU1_P2P2_DP<16>")
	)
	(segment
		(start 338.456524 -290.889944)
		(end 338.456524 -290.949888)
		(width 0.0889)
		(layer "In6.Cu")
		(net "UPI_CPU0_CPU1_P2P2_DP<16>")
	)
	(segment
		(start 70.407276 -328.556874)
		(end 70.852284 -326.9488)
		(width 0.14732)
		(layer "In6.Cu")
		(net "UPI_CPU0_CPU1_P2P2_DP<16>")
	)
	(segment
		(start 103.494078 -276.392894)
		(end 103.479346 -276.384258)
		(width 0.0889)
		(layer "In6.Cu")
		(net "UPI_CPU0_CPU1_P2P2_DP<16>")
	)
	(segment
		(start 339.767418 -287.778698)
		(end 339.766656 -287.779206)
		(width 0.0889)
		(layer "In6.Cu")
		(net "UPI_CPU0_CPU1_P2P2_DP<16>")
	)
	(segment
		(start 102.069392 -287.613598)
		(end 102.078282 -287.608518)
		(width 0.0889)
		(layer "In6.Cu")
		(net "UPI_CPU0_CPU1_P2P2_DP<16>")
	)
	(segment
		(start 252.048518 -370.737384)
		(end 251.2441 -370.879878)
		(width 0.14732)
		(layer "In6.Cu")
		(net "UPI_CPU0_CPU1_P2P2_DP<16>")
	)
	(segment
		(start 101.600508 -288.426906)
		(end 101.608636 -288.422334)
		(width 0.0889)
		(layer "In6.Cu")
		(net "UPI_CPU0_CPU1_P2P2_DP<16>")
	)
	(segment
		(start 102.53345 -285.175452)
		(end 102.535736 -285.174182)
		(width 0.0889)
		(layer "In6.Cu")
		(net "UPI_CPU0_CPU1_P2P2_DP<16>")
	)
	(segment
		(start 99.379786 -293.209726)
		(end 99.379786 -293.187628)
		(width 0.0889)
		(layer "In6.Cu")
		(net "UPI_CPU0_CPU1_P2P2_DP<16>")
	)
	(segment
		(start 340.249256 -285.329884)
		(end 340.237064 -285.336996)
		(width 0.0889)
		(layer "In6.Cu")
		(net "UPI_CPU0_CPU1_P2P2_DP<16>")
	)
	(segment
		(start 306.40528 -325.345298)
		(end 306.071016 -325.822818)
		(width 0.14732)
		(layer "In6.Cu")
		(net "UPI_CPU0_CPU1_P2P2_DP<16>")
	)
	(arc
		(start 104.98455 -276.384258)
		(mid 104.710351 -276.460093)
		(end 104.433878 -276.392894)
		(width 0.0889)
		(layer "In6.Cu")
		(net "UPI_CPU0_CPU1_P2P2_DP<16>")
	)
	(arc
		(start 340.706964 -283.544264)
		(mid 340.911299 -283.746869)
		(end 340.989412 -284.023816)
		(width 0.0889)
		(layer "In6.Cu")
		(net "UPI_CPU0_CPU1_P2P2_DP<16>")
	)
	(arc
		(start 103.018082 -284.353)
		(mid 103.148996 -284.21664)
		(end 103.196644 -284.033722)
		(width 0.0889)
		(layer "In6.Cu")
		(net "UPI_CPU0_CPU1_P2P2_DP<16>")
	)
	(arc
		(start 340.237318 -282.730194)
		(mid 340.4386 -282.927681)
		(end 340.519512 -283.197808)
		(width 0.0889)
		(layer "In6.Cu")
		(net "UPI_CPU0_CPU1_P2P2_DP<16>")
	)
	(arc
		(start 338.824316 -289.446462)
		(mid 338.689009 -289.561584)
		(end 338.615528 -289.723322)
		(width 0.0889)
		(layer "In6.Cu")
		(net "UPI_CPU0_CPU1_P2P2_DP<16>")
	)
	(arc
		(start 101.608636 -288.422334)
		(mid 101.73955 -288.285974)
		(end 101.787198 -288.103056)
		(width 0.0889)
		(layer "In6.Cu")
		(net "UPI_CPU0_CPU1_P2P2_DP<16>")
	)
	(arc
		(start 340.237064 -285.336996)
		(mid 340.102131 -285.47035)
		(end 340.049866 -285.652718)
		(width 0.0889)
		(layer "In6.Cu")
		(net "UPI_CPU0_CPU1_P2P2_DP<16>")
	)
	(arc
		(start 101.786944 -289.64509)
		(mid 101.71185 -289.530026)
		(end 101.602794 -289.446462)
		(width 0.0889)
		(layer "In6.Cu")
		(net "UPI_CPU0_CPU1_P2P2_DP<16>")
	)
	(arc
		(start 101.787198 -288.087562)
		(mid 101.866568 -287.813828)
		(end 102.069392 -287.613598)
		(width 0.0889)
		(layer "In6.Cu")
		(net "UPI_CPU0_CPU1_P2P2_DP<16>")
	)
	(arc
		(start 340.050374 -282.420568)
		(mid 340.101284 -282.595137)
		(end 340.228428 -282.725114)
		(width 0.0889)
		(layer "In6.Cu")
		(net "UPI_CPU0_CPU1_P2P2_DP<16>")
	)
	(arc
		(start 339.288628 -288.597848)
		(mid 339.157714 -288.734208)
		(end 339.110066 -288.917126)
		(width 0.0889)
		(layer "In6.Cu")
		(net "UPI_CPU0_CPU1_P2P2_DP<16>")
	)
	(arc
		(start 102.726744 -284.837632)
		(mid 102.804855 -284.560683)
		(end 103.009192 -284.35808)
		(width 0.0889)
		(layer "In6.Cu")
		(net "UPI_CPU0_CPU1_P2P2_DP<16>")
	)
	(arc
		(start 103.196644 -280.759662)
		(mid 103.276806 -280.487473)
		(end 103.479092 -280.288492)
		(width 0.0889)
		(layer "In6.Cu")
		(net "UPI_CPU0_CPU1_P2P2_DP<16>")
	)
	(arc
		(start 104.419146 -276.384258)
		(mid 104.231948 -276.334115)
		(end 104.04475 -276.384258)
		(width 0.0889)
		(layer "In6.Cu")
		(net "UPI_CPU0_CPU1_P2P2_DP<16>")
	)
	(arc
		(start 340.05012 -282.395676)
		(mid 340.05004 -282.408124)
		(end 340.050374 -282.420568)
		(width 0.0889)
		(layer "In6.Cu")
		(net "UPI_CPU0_CPU1_P2P2_DP<16>")
	)
	(arc
		(start 103.957882 -279.469596)
		(mid 104.088796 -279.333236)
		(end 104.136444 -279.150318)
		(width 0.0889)
		(layer "In6.Cu")
		(net "UPI_CPU0_CPU1_P2P2_DP<16>")
	)
	(arc
		(start 340.698328 -284.52826)
		(mid 340.567414 -284.66462)
		(end 340.519766 -284.847538)
		(width 0.0889)
		(layer "In6.Cu")
		(net "UPI_CPU0_CPU1_P2P2_DP<16>")
	)
	(arc
		(start 340.228428 -286.969962)
		(mid 340.097514 -287.106322)
		(end 340.049866 -287.28924)
		(width 0.0889)
		(layer "In6.Cu")
		(net "UPI_CPU0_CPU1_P2P2_DP<16>")
	)
	(arc
		(start 103.666544 -279.964134)
		(mid 103.74046 -279.684632)
		(end 103.942896 -279.478232)
		(width 0.0889)
		(layer "In6.Cu")
		(net "UPI_CPU0_CPU1_P2P2_DP<16>")
	)
	(arc
		(start 104.419146 -278.66086)
		(mid 104.554079 -278.527506)
		(end 104.606344 -278.345138)
		(width 0.0889)
		(layer "In6.Cu")
		(net "UPI_CPU0_CPU1_P2P2_DP<16>")
	)
	(arc
		(start 102.548182 -286.794702)
		(mid 102.726779 -286.475424)
		(end 102.548182 -286.156146)
		(width 0.0889)
		(layer "In6.Cu")
		(net "UPI_CPU0_CPU1_P2P2_DP<16>")
	)
	(arc
		(start 104.04475 -276.384258)
		(mid 103.770551 -276.460093)
		(end 103.494078 -276.392894)
		(width 0.0889)
		(layer "In6.Cu")
		(net "UPI_CPU0_CPU1_P2P2_DP<16>")
	)
	(arc
		(start 102.618032 -276.422104)
		(mid 102.607704 -276.418014)
		(end 102.597458 -276.413722)
		(width 0.0889)
		(layer "In6.Cu")
		(net "UPI_CPU0_CPU1_P2P2_DP<16>")
	)
	(arc
		(start 105.546144 -276.69998)
		(mid 105.493874 -276.517615)
		(end 105.358946 -276.384258)
		(width 0.0889)
		(layer "In6.Cu")
		(net "UPI_CPU0_CPU1_P2P2_DP<16>")
	)
	(arc
		(start 340.519766 -286.48533)
		(mid 340.441655 -286.762279)
		(end 340.237318 -286.964882)
		(width 0.0889)
		(layer "In6.Cu")
		(net "UPI_CPU0_CPU1_P2P2_DP<16>")
	)
	(arc
		(start 104.136444 -279.150318)
		(mid 104.210435 -278.870752)
		(end 104.41305 -278.664416)
		(width 0.0889)
		(layer "In6.Cu")
		(net "UPI_CPU0_CPU1_P2P2_DP<16>")
	)
	(arc
		(start 103.66629 -283.207714)
		(mid 103.615819 -283.031706)
		(end 103.487982 -282.900628)
		(width 0.0889)
		(layer "In6.Cu")
		(net "UPI_CPU0_CPU1_P2P2_DP<16>")
	)
	(arc
		(start 103.666544 -283.22651)
		(mid 103.666534 -283.21711)
		(end 103.66629 -283.207714)
		(width 0.0889)
		(layer "In6.Cu")
		(net "UPI_CPU0_CPU1_P2P2_DP<16>")
	)
	(arc
		(start 102.256844 -285.661354)
		(mid 102.330835 -285.381788)
		(end 102.53345 -285.175452)
		(width 0.0889)
		(layer "In6.Cu")
		(net "UPI_CPU0_CPU1_P2P2_DP<16>")
	)
	(arc
		(start 103.479092 -281.267662)
		(mid 103.274757 -281.065057)
		(end 103.196644 -280.78811)
		(width 0.0889)
		(layer "In6.Cu")
		(net "UPI_CPU0_CPU1_P2P2_DP<16>")
	)
	(arc
		(start 339.758528 -287.783778)
		(mid 339.627614 -287.920138)
		(end 339.579966 -288.103056)
		(width 0.0889)
		(layer "In6.Cu")
		(net "UPI_CPU0_CPU1_P2P2_DP<16>")
	)
	(arc
		(start 340.519766 -284.847538)
		(mid 340.447531 -285.124062)
		(end 340.249256 -285.329884)
		(width 0.0889)
		(layer "In6.Cu")
		(net "UPI_CPU0_CPU1_P2P2_DP<16>")
	)
	(arc
		(start 340.659466 -281.300174)
		(mid 340.556321 -281.430199)
		(end 340.519512 -281.59202)
		(width 0.0889)
		(layer "In6.Cu")
		(net "UPI_CPU0_CPU1_P2P2_DP<16>")
	)
	(arc
		(start 102.539292 -286.151066)
		(mid 102.337006 -285.952085)
		(end 102.256844 -285.679896)
		(width 0.0889)
		(layer "In6.Cu")
		(net "UPI_CPU0_CPU1_P2P2_DP<16>")
	)
	(arc
		(start 103.10495 -276.384258)
		(mid 102.865789 -276.458462)
		(end 102.618032 -276.422104)
		(width 0.0889)
		(layer "In6.Cu")
		(net "UPI_CPU0_CPU1_P2P2_DP<16>")
	)
	(arc
		(start 104.606344 -278.31796)
		(mid 104.686506 -278.045771)
		(end 104.888792 -277.84679)
		(width 0.0889)
		(layer "In6.Cu")
		(net "UPI_CPU0_CPU1_P2P2_DP<16>")
	)
	(arc
		(start 105.358946 -277.032974)
		(mid 105.493879 -276.89962)
		(end 105.546144 -276.717252)
		(width 0.0889)
		(layer "In6.Cu")
		(net "UPI_CPU0_CPU1_P2P2_DP<16>")
	)
	(arc
		(start 103.487982 -281.911298)
		(mid 103.666579 -281.59202)
		(end 103.487982 -281.272742)
		(width 0.0889)
		(layer "In6.Cu")
		(net "UPI_CPU0_CPU1_P2P2_DP<16>")
	)
	(arc
		(start 105.076244 -277.522432)
		(mid 105.150235 -277.242866)
		(end 105.35285 -277.03653)
		(width 0.0889)
		(layer "In6.Cu")
		(net "UPI_CPU0_CPU1_P2P2_DP<16>")
	)
	(arc
		(start 340.989412 -284.049216)
		(mid 340.910042 -284.32295)
		(end 340.707218 -284.52318)
		(width 0.0889)
		(layer "In6.Cu")
		(net "UPI_CPU0_CPU1_P2P2_DP<16>")
	)
	(arc
		(start 340.519512 -281.607514)
		(mid 340.440142 -281.881248)
		(end 340.237318 -282.081478)
		(width 0.0889)
		(layer "In6.Cu")
		(net "UPI_CPU0_CPU1_P2P2_DP<16>")
	)
	(arc
		(start 103.479346 -276.384258)
		(mid 103.292148 -276.334115)
		(end 103.10495 -276.384258)
		(width 0.0889)
		(layer "In6.Cu")
		(net "UPI_CPU0_CPU1_P2P2_DP<16>")
	)
	(arc
		(start 339.579966 -288.11728)
		(mid 339.500825 -288.391903)
		(end 339.297518 -288.592768)
		(width 0.0889)
		(layer "In6.Cu")
		(net "UPI_CPU0_CPU1_P2P2_DP<16>")
	)
	(arc
		(start 103.479092 -282.895548)
		(mid 103.276806 -282.696567)
		(end 103.196644 -282.424378)
		(width 0.0889)
		(layer "In6.Cu")
		(net "UPI_CPU0_CPU1_P2P2_DP<16>")
	)
	(arc
		(start 340.049866 -285.66999)
		(mid 340.102136 -285.852355)
		(end 340.237064 -285.985712)
		(width 0.0889)
		(layer "In6.Cu")
		(net "UPI_CPU0_CPU1_P2P2_DP<16>")
	)
	(arc
		(start 340.228428 -282.086558)
		(mid 340.100109 -282.21853)
		(end 340.05012 -282.395676)
		(width 0.0889)
		(layer "In6.Cu")
		(net "UPI_CPU0_CPU1_P2P2_DP<16>")
	)
	(arc
		(start 105.358946 -276.384258)
		(mid 105.171748 -276.334115)
		(end 104.98455 -276.384258)
		(width 0.0889)
		(layer "In6.Cu")
		(net "UPI_CPU0_CPU1_P2P2_DP<16>")
	)
	(arc
		(start 103.487982 -280.283412)
		(mid 103.618896 -280.147052)
		(end 103.666544 -279.964134)
		(width 0.0889)
		(layer "In6.Cu")
		(net "UPI_CPU0_CPU1_P2P2_DP<16>")
	)
	(arc
		(start 101.602794 -289.446462)
		(mid 101.428662 -289.307615)
		(end 101.317298 -289.114738)
		(width 0.0889)
		(layer "In6.Cu")
		(net "UPI_CPU0_CPU1_P2P2_DP<16>")
	)
	(arc
		(start 102.256844 -287.279334)
		(mid 102.334955 -287.002385)
		(end 102.539292 -286.799782)
		(width 0.0889)
		(layer "In6.Cu")
		(net "UPI_CPU0_CPU1_P2P2_DP<16>")
	)
	(arc
		(start 340.237064 -285.985712)
		(mid 340.440545 -286.186516)
		(end 340.519766 -286.4612)
		(width 0.0889)
		(layer "In6.Cu")
		(net "UPI_CPU0_CPU1_P2P2_DP<16>")
	)
	(arc
		(start 339.110066 -289.114484)
		(mid 338.99867 -289.307577)
		(end 338.824316 -289.446462)
		(width 0.0889)
		(layer "In6.Cu")
		(net "UPI_CPU0_CPU1_P2P2_DP<16>")
	)
	(arc
		(start 104.897682 -277.84171)
		(mid 105.028596 -277.70535)
		(end 105.076244 -277.522432)
		(width 0.0889)
		(layer "In6.Cu")
		(net "UPI_CPU0_CPU1_P2P2_DP<16>")
	)
	(arc
		(start 102.539546 -285.171896)
		(mid 102.674479 -285.038542)
		(end 102.726744 -284.856174)
		(width 0.0889)
		(layer "In6.Cu")
		(net "UPI_CPU0_CPU1_P2P2_DP<16>")
	)
	(arc
		(start 101.317298 -288.898584)
		(mid 101.39746 -288.626395)
		(end 101.599746 -288.427414)
		(width 0.0889)
		(layer "In6.Cu")
		(net "UPI_CPU0_CPU1_P2P2_DP<16>")
	)
	(arc
		(start 103.196644 -282.39593)
		(mid 103.274755 -282.118981)
		(end 103.479092 -281.916378)
		(width 0.0889)
		(layer "In6.Cu")
		(net "UPI_CPU0_CPU1_P2P2_DP<16>")
	)
	(arc
		(start 102.078282 -287.608518)
		(mid 102.209196 -287.472158)
		(end 102.256844 -287.28924)
		(width 0.0889)
		(layer "In6.Cu")
		(net "UPI_CPU0_CPU1_P2P2_DP<16>")
	)
	(arc
		(start 340.049866 -287.299146)
		(mid 339.971755 -287.576095)
		(end 339.767418 -287.778698)
		(width 0.0889)
		(layer "In6.Cu")
		(net "UPI_CPU0_CPU1_P2P2_DP<16>")
	)
	(arc
		(start 340.519512 -283.219906)
		(mid 340.567191 -283.402806)
		(end 340.698074 -283.539184)
		(width 0.0889)
		(layer "In6.Cu")
		(net "UPI_CPU0_CPU1_P2P2_DP<16>")
	)
	(arc
		(start 103.487982 -283.539184)
		(mid 103.617271 -283.405698)
		(end 103.666544 -283.22651)
		(width 0.0889)
		(layer "In6.Cu")
		(net "UPI_CPU0_CPU1_P2P2_DP<16>")
	)
	(arc
		(start 103.196644 -284.023816)
		(mid 103.274755 -283.746867)
		(end 103.479092 -283.544264)
		(width 0.0889)
		(layer "In6.Cu")
		(net "UPI_CPU0_CPU1_P2P2_DP<16>")
	)
	(segment
		(start 341.833962 -282.683966)
		(end 341.833962 -283.219906)
		(width 0.13208)
		(layer "F.Cu")
		(net "UPI_CPU0_CPU1_P2P2_DP<15>")
	)
	(segment
		(start 105.171494 -276.172676)
		(end 105.171494 -276.708362)
		(width 0.13208)
		(layer "F.Cu")
		(net "UPI_CPU0_CPU1_P2P2_DP<15>")
	)
	(segment
		(start 105.171494 -276.708362)
		(end 105.171748 -276.708616)
		(width 0.13208)
		(layer "F.Cu")
		(net "UPI_CPU0_CPU1_P2P2_DP<15>")
	)
	(segment
		(start 284.508702 -330.62164)
		(end 278.03475 -333.302864)
		(width 0.14732)
		(layer "In6.Cu")
		(net "UPI_CPU0_CPU1_P2P2_DP<15>")
	)
	(segment
		(start 102.917498 -283.219906)
		(end 102.917498 -283.201364)
		(width 0.0889)
		(layer "In6.Cu")
		(net "UPI_CPU0_CPU1_P2P2_DP<15>")
	)
	(segment
		(start 96.679258 -300.699424)
		(end 98.439732 -296.448734)
		(width 0.14732)
		(layer "In6.Cu")
		(net "UPI_CPU0_CPU1_P2P2_DP<15>")
	)
	(segment
		(start 234.936792 -371.30863)
		(end 234.132628 -371.451124)
		(width 0.14732)
		(layer "In6.Cu")
		(net "UPI_CPU0_CPU1_P2P2_DP<15>")
	)
	(segment
		(start 100.1395 -291.002212)
		(end 100.1395 -290.655248)
		(width 0.14732)
		(layer "In6.Cu")
		(net "UPI_CPU0_CPU1_P2P2_DP<15>")
	)
	(segment
		(start 100.1395 -290.655248)
		(end 100.139754 -290.654994)
		(width 0.14732)
		(layer "In6.Cu")
		(net "UPI_CPU0_CPU1_P2P2_DP<15>")
	)
	(segment
		(start 341.833962 -283.219906)
		(end 341.521288 -283.219906)
		(width 0.0889)
		(layer "In6.Cu")
		(net "UPI_CPU0_CPU1_P2P2_DP<15>")
	)
	(segment
		(start 100.09759 -290.36518)
		(end 100.09759 -289.646868)
		(width 0.0889)
		(layer "In6.Cu")
		(net "UPI_CPU0_CPU1_P2P2_DP<15>")
	)
	(segment
		(start 278.03475 -333.302864)
		(end 266.95781 -344.379804)
		(width 0.14732)
		(layer "In6.Cu")
		(net "UPI_CPU0_CPU1_P2P2_DP<15>")
	)
	(segment
		(start 238.44631 -371.000528)
		(end 238.581946 -371.768116)
		(width 0.14732)
		(layer "In6.Cu")
		(net "UPI_CPU0_CPU1_P2P2_DP<15>")
	)
	(segment
		(start 104.512872 -277.198836)
		(end 104.514396 -277.198074)
		(width 0.0889)
		(layer "In6.Cu")
		(net "UPI_CPU0_CPU1_P2P2_DP<15>")
	)
	(segment
		(start 102.63505 -281.102562)
		(end 102.62616 -281.097482)
		(width 0.0889)
		(layer "In6.Cu")
		(net "UPI_CPU0_CPU1_P2P2_DP<15>")
	)
	(segment
		(start 98.584512 -294.519858)
		(end 98.584512 -294.151558)
		(width 0.14732)
		(layer "In6.Cu")
		(net "UPI_CPU0_CPU1_P2P2_DP<15>")
	)
	(segment
		(start 98.080576 -375.832624)
		(end 77.694028 -367.388648)
		(width 0.14732)
		(layer "In6.Cu")
		(net "UPI_CPU0_CPU1_P2P2_DP<15>")
	)
	(segment
		(start 102.634796 -278.82596)
		(end 102.635558 -278.825452)
		(width 0.0889)
		(layer "In6.Cu")
		(net "UPI_CPU0_CPU1_P2P2_DP<15>")
	)
	(segment
		(start 341.269066 -284.832044)
		(end 341.269066 -284.847538)
		(width 0.0889)
		(layer "In6.Cu")
		(net "UPI_CPU0_CPU1_P2P2_DP<15>")
	)
	(segment
		(start 102.62616 -282.086558)
		(end 102.63505 -282.081478)
		(width 0.0889)
		(layer "In6.Cu")
		(net "UPI_CPU0_CPU1_P2P2_DP<15>")
	)
	(segment
		(start 340.329012 -289.645852)
		(end 340.329012 -290.082224)
		(width 0.0889)
		(layer "In6.Cu")
		(net "UPI_CPU0_CPU1_P2P2_DP<15>")
	)
	(segment
		(start 73.167748 -362.862114)
		(end 69.219318 -353.329494)
		(width 0.14732)
		(layer "In6.Cu")
		(net "UPI_CPU0_CPU1_P2P2_DP<15>")
	)
	(segment
		(start 104.515158 -277.197566)
		(end 104.520492 -277.194518)
		(width 0.0889)
		(layer "In6.Cu")
		(net "UPI_CPU0_CPU1_P2P2_DP<15>")
	)
	(segment
		(start 101.693472 -285.337758)
		(end 101.694996 -285.336996)
		(width 0.0889)
		(layer "In6.Cu")
		(net "UPI_CPU0_CPU1_P2P2_DP<15>")
	)
	(segment
		(start 102.62616 -280.458926)
		(end 102.63505 -280.453846)
		(width 0.0889)
		(layer "In6.Cu")
		(net "UPI_CPU0_CPU1_P2P2_DP<15>")
	)
	(segment
		(start 98.439732 -294.006778)
		(end 98.439732 -292.70198)
		(width 0.14732)
		(layer "In6.Cu")
		(net "UPI_CPU0_CPU1_P2P2_DP<15>")
	)
	(segment
		(start 304.39487 -329.862942)
		(end 304.39487 -330.067666)
		(width 0.14732)
		(layer "In6.Cu")
		(net "UPI_CPU0_CPU1_P2P2_DP<15>")
	)
	(segment
		(start 76.635102 -366.124744)
		(end 76.374244 -365.863886)
		(width 0.14732)
		(layer "In6.Cu")
		(net "UPI_CPU0_CPU1_P2P2_DP<15>")
	)
	(segment
		(start 306.249324 -327.985374)
		(end 305.983132 -328.365358)
		(width 0.14732)
		(layer "In6.Cu")
		(net "UPI_CPU0_CPU1_P2P2_DP<15>")
	)
	(segment
		(start 313.39409 -321.36842)
		(end 310.272938 -323.257672)
		(width 0.14732)
		(layer "In6.Cu")
		(net "UPI_CPU0_CPU1_P2P2_DP<15>")
	)
	(segment
		(start 339.9409 -290.470336)
		(end 339.817202 -290.594034)
		(width 0.0889)
		(layer "In6.Cu")
		(net "UPI_CPU0_CPU1_P2P2_DP<15>")
	)
	(segment
		(start 233.011472 -371.962426)
		(end 232.65511 -371.712236)
		(width 0.14732)
		(layer "In6.Cu")
		(net "UPI_CPU0_CPU1_P2P2_DP<15>")
	)
	(segment
		(start 74.65695 -364.351316)
		(end 74.234802 -363.929168)
		(width 0.14732)
		(layer "In6.Cu")
		(net "UPI_CPU0_CPU1_P2P2_DP<15>")
	)
	(segment
		(start 234.018074 -372.575328)
		(end 233.898948 -372.745762)
		(width 0.14732)
		(layer "In6.Cu")
		(net "UPI_CPU0_CPU1_P2P2_DP<15>")
	)
	(segment
		(start 159.411416 -379.93447)
		(end 125.730254 -379.93447)
		(width 0.14732)
		(layer "In6.Cu")
		(net "UPI_CPU0_CPU1_P2P2_DP<15>")
	)
	(segment
		(start 333.31785 -301.795434)
		(end 314.282328 -320.830702)
		(width 0.14732)
		(layer "In6.Cu")
		(net "UPI_CPU0_CPU1_P2P2_DP<15>")
	)
	(segment
		(start 102.640892 -279.478232)
		(end 102.625906 -279.469596)
		(width 0.0889)
		(layer "In6.Cu")
		(net "UPI_CPU0_CPU1_P2P2_DP<15>")
	)
	(segment
		(start 80.073754 -314.960762)
		(end 95.477584 -302.319436)
		(width 0.14732)
		(layer "In6.Cu")
		(net "UPI_CPU0_CPU1_P2P2_DP<15>")
	)
	(segment
		(start 236.30001 -372.171722)
		(end 236.180884 -372.342156)
		(width 0.14732)
		(layer "In6.Cu")
		(net "UPI_CPU0_CPU1_P2P2_DP<15>")
	)
	(segment
		(start 234.132628 -371.451124)
		(end 233.882438 -371.807994)
		(width 0.14732)
		(layer "In6.Cu")
		(net "UPI_CPU0_CPU1_P2P2_DP<15>")
	)
	(segment
		(start 104.793288 -276.774402)
		(end 104.859074 -276.708616)
		(width 0.0889)
		(layer "In6.Cu")
		(net "UPI_CPU0_CPU1_P2P2_DP<15>")
	)
	(segment
		(start 341.521288 -283.219906)
		(end 341.463884 -283.162502)
		(width 0.0889)
		(layer "In6.Cu")
		(net "UPI_CPU0_CPU1_P2P2_DP<15>")
	)
	(segment
		(start 100.139754 -290.407344)
		(end 100.09759 -290.36518)
		(width 0.0889)
		(layer "In6.Cu")
		(net "UPI_CPU0_CPU1_P2P2_DP<15>")
	)
	(segment
		(start 339.552788 -290.717986)
		(end 339.552788 -290.858448)
		(width 0.0889)
		(layer "In6.Cu")
		(net "UPI_CPU0_CPU1_P2P2_DP<15>")
	)
	(segment
		(start 102.447344 -284.049216)
		(end 102.447344 -284.033722)
		(width 0.0889)
		(layer "In6.Cu")
		(net "UPI_CPU0_CPU1_P2P2_DP<15>")
	)
	(segment
		(start 309.758842 -323.399658)
		(end 309.70982 -323.59854)
		(width 0.14732)
		(layer "In6.Cu")
		(net "UPI_CPU0_CPU1_P2P2_DP<15>")
	)
	(segment
		(start 336.525616 -293.825422)
		(end 335.874614 -294.75176)
		(width 0.14732)
		(layer "In6.Cu")
		(net "UPI_CPU0_CPU1_P2P2_DP<15>")
	)
	(segment
		(start 339.552788 -290.858448)
		(end 339.047582 -291.363654)
		(width 0.0889)
		(layer "In6.Cu")
		(net "UPI_CPU0_CPU1_P2P2_DP<15>")
	)
	(segment
		(start 95.477584 -302.319436)
		(end 96.679258 -300.699424)
		(width 0.14732)
		(layer "In6.Cu")
		(net "UPI_CPU0_CPU1_P2P2_DP<15>")
	)
	(segment
		(start 100.74656 -288.597848)
		(end 100.75545 -288.592768)
		(width 0.0889)
		(layer "In6.Cu")
		(net "UPI_CPU0_CPU1_P2P2_DP<15>")
	)
	(segment
		(start 237.218728 -370.905024)
		(end 236.414564 -371.047518)
		(width 0.14732)
		(layer "In6.Cu")
		(net "UPI_CPU0_CPU1_P2P2_DP<15>")
	)
	(segment
		(start 233.898948 -372.745762)
		(end 233.317542 -372.848632)
		(width 0.14732)
		(layer "In6.Cu")
		(net "UPI_CPU0_CPU1_P2P2_DP<15>")
	)
	(segment
		(start 236.164374 -371.404388)
		(end 236.30001 -372.171722)
		(width 0.14732)
		(layer "In6.Cu")
		(net "UPI_CPU0_CPU1_P2P2_DP<15>")
	)
	(segment
		(start 266.81303 -364.915958)
		(end 266.95781 -365.060738)
		(width 0.14732)
		(layer "In6.Cu")
		(net "UPI_CPU0_CPU1_P2P2_DP<15>")
	)
	(segment
		(start 75.871832 -365.361474)
		(end 75.610974 -365.100616)
		(width 0.14732)
		(layer "In6.Cu")
		(net "UPI_CPU0_CPU1_P2P2_DP<15>")
	)
	(segment
		(start 266.95781 -344.379804)
		(end 266.95781 -364.402878)
		(width 0.14732)
		(layer "In6.Cu")
		(net "UPI_CPU0_CPU1_P2P2_DP<15>")
	)
	(segment
		(start 341.081614 -286.151066)
		(end 341.090504 -286.156146)
		(width 0.0889)
		(layer "In6.Cu")
		(net "UPI_CPU0_CPU1_P2P2_DP<15>")
	)
	(segment
		(start 341.56015 -284.353)
		(end 341.55126 -284.35808)
		(width 0.0889)
		(layer "In6.Cu")
		(net "UPI_CPU0_CPU1_P2P2_DP<15>")
	)
	(segment
		(start 102.625906 -278.83104)
		(end 102.633272 -278.826722)
		(width 0.0889)
		(layer "In6.Cu")
		(net "UPI_CPU0_CPU1_P2P2_DP<15>")
	)
	(segment
		(start 102.917498 -281.601926)
		(end 102.917498 -281.582114)
		(width 0.0889)
		(layer "In6.Cu")
		(net "UPI_CPU0_CPU1_P2P2_DP<15>")
	)
	(segment
		(start 98.439732 -292.70198)
		(end 100.1395 -291.002212)
		(width 0.14732)
		(layer "In6.Cu")
		(net "UPI_CPU0_CPU1_P2P2_DP<15>")
	)
	(segment
		(start 314.282328 -320.830702)
		(end 313.957208 -321.027552)
		(width 0.14732)
		(layer "In6.Cu")
		(net "UPI_CPU0_CPU1_P2P2_DP<15>")
	)
	(segment
		(start 248.577862 -372.075456)
		(end 239.576102 -370.488464)
		(width 0.14732)
		(layer "In6.Cu")
		(net "UPI_CPU0_CPU1_P2P2_DP<15>")
	)
	(segment
		(start 339.9409 -290.329874)
		(end 339.9409 -290.470336)
		(width 0.0889)
		(layer "In6.Cu")
		(net "UPI_CPU0_CPU1_P2P2_DP<15>")
	)
	(segment
		(start 199.037448 -372.948962)
		(end 159.411416 -379.93447)
		(width 0.14732)
		(layer "In6.Cu")
		(net "UPI_CPU0_CPU1_P2P2_DP<15>")
	)
	(segment
		(start 98.439732 -295.769538)
		(end 98.584512 -295.624758)
		(width 0.14732)
		(layer "In6.Cu")
		(net "UPI_CPU0_CPU1_P2P2_DP<15>")
	)
	(segment
		(start 233.147362 -372.729506)
		(end 233.011472 -371.962426)
		(width 0.14732)
		(layer "In6.Cu")
		(net "UPI_CPU0_CPU1_P2P2_DP<15>")
	)
	(segment
		(start 103.09606 -278.017224)
		(end 103.10495 -278.012144)
		(width 0.0889)
		(layer "In6.Cu")
		(net "UPI_CPU0_CPU1_P2P2_DP<15>")
	)
	(segment
		(start 341.738712 -284.023816)
		(end 341.738712 -284.033722)
		(width 0.0889)
		(layer "In6.Cu")
		(net "UPI_CPU0_CPU1_P2P2_DP<15>")
	)
	(segment
		(start 101.694996 -285.985712)
		(end 101.686106 -285.980632)
		(width 0.0889)
		(layer "In6.Cu")
		(net "UPI_CPU0_CPU1_P2P2_DP<15>")
	)
	(segment
		(start 341.090504 -286.794702)
		(end 341.075264 -286.803592)
		(width 0.0889)
		(layer "In6.Cu")
		(net "UPI_CPU0_CPU1_P2P2_DP<15>")
	)
	(segment
		(start 104.859074 -276.708616)
		(end 105.171748 -276.708616)
		(width 0.0889)
		(layer "In6.Cu")
		(net "UPI_CPU0_CPU1_P2P2_DP<15>")
	)
	(segment
		(start 335.875376 -294.754554)
		(end 335.103978 -295.909238)
		(width 0.14732)
		(layer "In6.Cu")
		(net "UPI_CPU0_CPU1_P2P2_DP<15>")
	)
	(segment
		(start 100.139754 -290.654994)
		(end 100.139754 -290.429442)
		(width 0.14732)
		(layer "In6.Cu")
		(net "UPI_CPU0_CPU1_P2P2_DP<15>")
	)
	(segment
		(start 340.329012 -290.082224)
		(end 340.205314 -290.205922)
		(width 0.0889)
		(layer "In6.Cu")
		(net "UPI_CPU0_CPU1_P2P2_DP<15>")
	)
	(segment
		(start 212.36559 -375.299224)
		(end 199.037448 -372.948962)
		(width 0.14732)
		(layer "In6.Cu")
		(net "UPI_CPU0_CPU1_P2P2_DP<15>")
	)
	(segment
		(start 340.329266 -288.09315)
		(end 340.329266 -288.103056)
		(width 0.0889)
		(layer "In6.Cu")
		(net "UPI_CPU0_CPU1_P2P2_DP<15>")
	)
	(segment
		(start 236.180884 -372.342156)
		(end 235.599478 -372.445026)
		(width 0.14732)
		(layer "In6.Cu")
		(net "UPI_CPU0_CPU1_P2P2_DP<15>")
	)
	(segment
		(start 76.634848 -366.329468)
		(end 76.635102 -366.124744)
		(width 0.14732)
		(layer "In6.Cu")
		(net "UPI_CPU0_CPU1_P2P2_DP<15>")
	)
	(segment
		(start 304.860198 -329.602338)
		(end 304.655474 -329.602338)
		(width 0.14732)
		(layer "In6.Cu")
		(net "UPI_CPU0_CPU1_P2P2_DP<15>")
	)
	(segment
		(start 342.03005 -283.539184)
		(end 342.021922 -283.543756)
		(width 0.0889)
		(layer "In6.Cu")
		(net "UPI_CPU0_CPU1_P2P2_DP<15>")
	)
	(segment
		(start 340.798912 -285.661354)
		(end 340.798912 -285.675578)
		(width 0.0889)
		(layer "In6.Cu")
		(net "UPI_CPU0_CPU1_P2P2_DP<15>")
	)
	(segment
		(start 237.575344 -371.155214)
		(end 237.218728 -370.905024)
		(width 0.14732)
		(layer "In6.Cu")
		(net "UPI_CPU0_CPU1_P2P2_DP<15>")
	)
	(segment
		(start 101.977698 -286.475424)
		(end 101.977698 -286.4612)
		(width 0.0889)
		(layer "In6.Cu")
		(net "UPI_CPU0_CPU1_P2P2_DP<15>")
	)
	(segment
		(start 306.53228 -326.380348)
		(end 306.249324 -327.985374)
		(width 0.14732)
		(layer "In6.Cu")
		(net "UPI_CPU0_CPU1_P2P2_DP<15>")
	)
	(segment
		(start 340.142576 -288.426906)
		(end 340.141814 -288.427414)
		(width 0.0889)
		(layer "In6.Cu")
		(net "UPI_CPU0_CPU1_P2P2_DP<15>")
	)
	(segment
		(start 102.635558 -278.825452)
		(end 102.640892 -278.822404)
		(width 0.0889)
		(layer "In6.Cu")
		(net "UPI_CPU0_CPU1_P2P2_DP<15>")
	)
	(segment
		(start 310.074056 -323.208904)
		(end 309.758842 -323.399658)
		(width 0.14732)
		(layer "In6.Cu")
		(net "UPI_CPU0_CPU1_P2P2_DP<15>")
	)
	(segment
		(start 75.610974 -365.100616)
		(end 75.40625 -365.100616)
		(width 0.14732)
		(layer "In6.Cu")
		(net "UPI_CPU0_CPU1_P2P2_DP<15>")
	)
	(segment
		(start 239.576102 -370.488464)
		(end 238.6965 -370.644166)
		(width 0.14732)
		(layer "In6.Cu")
		(net "UPI_CPU0_CPU1_P2P2_DP<15>")
	)
	(segment
		(start 102.63505 -282.730194)
		(end 102.62616 -282.725114)
		(width 0.0889)
		(layer "In6.Cu")
		(net "UPI_CPU0_CPU1_P2P2_DP<15>")
	)
	(segment
		(start 341.090504 -285.166816)
		(end 341.075264 -285.175706)
		(width 0.0889)
		(layer "In6.Cu")
		(net "UPI_CPU0_CPU1_P2P2_DP<15>")
	)
	(segment
		(start 75.871832 -365.566198)
		(end 75.871832 -365.361474)
		(width 0.14732)
		(layer "In6.Cu")
		(net "UPI_CPU0_CPU1_P2P2_DP<15>")
	)
	(segment
		(start 235.599478 -372.445026)
		(end 235.429298 -372.3259)
		(width 0.14732)
		(layer "In6.Cu")
		(net "UPI_CPU0_CPU1_P2P2_DP<15>")
	)
	(segment
		(start 69.219318 -353.329494)
		(end 69.219318 -334.936338)
		(width 0.14732)
		(layer "In6.Cu")
		(net "UPI_CPU0_CPU1_P2P2_DP<15>")
	)
	(segment
		(start 339.67674 -290.594034)
		(end 339.552788 -290.717986)
		(width 0.0889)
		(layer "In6.Cu")
		(net "UPI_CPU0_CPU1_P2P2_DP<15>")
	)
	(segment
		(start 101.69779 -285.335472)
		(end 101.701092 -285.33344)
		(width 0.0889)
		(layer "In6.Cu")
		(net "UPI_CPU0_CPU1_P2P2_DP<15>")
	)
	(segment
		(start 266.95781 -365.060738)
		(end 266.95781 -365.848392)
		(width 0.14732)
		(layer "In6.Cu")
		(net "UPI_CPU0_CPU1_P2P2_DP<15>")
	)
	(segment
		(start 102.641146 -283.705554)
		(end 102.640892 -283.705808)
		(width 0.0889)
		(layer "In6.Cu")
		(net "UPI_CPU0_CPU1_P2P2_DP<15>")
	)
	(segment
		(start 339.817202 -290.594034)
		(end 339.67674 -290.594034)
		(width 0.0889)
		(layer "In6.Cu")
		(net "UPI_CPU0_CPU1_P2P2_DP<15>")
	)
	(segment
		(start 304.39487 -330.067666)
		(end 303.840896 -330.62164)
		(width 0.14732)
		(layer "In6.Cu")
		(net "UPI_CPU0_CPU1_P2P2_DP<15>")
	)
	(segment
		(start 335.874614 -294.75176)
		(end 335.875376 -294.754554)
		(width 0.14732)
		(layer "In6.Cu")
		(net "UPI_CPU0_CPU1_P2P2_DP<15>")
	)
	(segment
		(start 305.983132 -328.365612)
		(end 305.71694 -328.745342)
		(width 0.14732)
		(layer "In6.Cu")
		(net "UPI_CPU0_CPU1_P2P2_DP<15>")
	)
	(segment
		(start 100.567998 -289.114484)
		(end 100.567998 -288.917126)
		(width 0.0889)
		(layer "In6.Cu")
		(net "UPI_CPU0_CPU1_P2P2_DP<15>")
	)
	(segment
		(start 303.840896 -330.62164)
		(end 284.508702 -330.62164)
		(width 0.14732)
		(layer "In6.Cu")
		(net "UPI_CPU0_CPU1_P2P2_DP<15>")
	)
	(segment
		(start 77.360526 -366.850422)
		(end 77.099922 -366.589818)
		(width 0.14732)
		(layer "In6.Cu")
		(net "UPI_CPU0_CPU1_P2P2_DP<15>")
	)
	(segment
		(start 100.139754 -290.429442)
		(end 100.139754 -290.407344)
		(width 0.0889)
		(layer "In6.Cu")
		(net "UPI_CPU0_CPU1_P2P2_DP<15>")
	)
	(segment
		(start 73.76922 -363.463586)
		(end 73.167748 -362.862114)
		(width 0.14732)
		(layer "In6.Cu")
		(net "UPI_CPU0_CPU1_P2P2_DP<15>")
	)
	(segment
		(start 101.686106 -286.969962)
		(end 101.701346 -286.961072)
		(width 0.0889)
		(layer "In6.Cu")
		(net "UPI_CPU0_CPU1_P2P2_DP<15>")
	)
	(segment
		(start 73.973944 -363.463586)
		(end 73.76922 -363.463586)
		(width 0.14732)
		(layer "In6.Cu")
		(net "UPI_CPU0_CPU1_P2P2_DP<15>")
	)
	(segment
		(start 342.02116 -282.895548)
		(end 342.03005 -282.900628)
		(width 0.0889)
		(layer "In6.Cu")
		(net "UPI_CPU0_CPU1_P2P2_DP<15>")
	)
	(segment
		(start 305.983132 -328.365358)
		(end 305.983132 -328.365612)
		(width 0.14732)
		(layer "In6.Cu")
		(net "UPI_CPU0_CPU1_P2P2_DP<15>")
	)
	(segment
		(start 69.857112 -328.45883)
		(end 70.326758 -326.761602)
		(width 0.14732)
		(layer "In6.Cu")
		(net "UPI_CPU0_CPU1_P2P2_DP<15>")
	)
	(segment
		(start 238.6965 -370.644166)
		(end 238.44631 -371.000528)
		(width 0.14732)
		(layer "In6.Cu")
		(net "UPI_CPU0_CPU1_P2P2_DP<15>")
	)
	(segment
		(start 266.95781 -365.848392)
		(end 263.332722 -369.47348)
		(width 0.14732)
		(layer "In6.Cu")
		(net "UPI_CPU0_CPU1_P2P2_DP<15>")
	)
	(segment
		(start 104.326944 -277.54453)
		(end 104.326944 -277.522432)
		(width 0.0889)
		(layer "In6.Cu")
		(net "UPI_CPU0_CPU1_P2P2_DP<15>")
	)
	(segment
		(start 339.047582 -291.363654)
		(end 338.988654 -291.363654)
		(width 0.0889)
		(layer "In6.Cu")
		(net "UPI_CPU0_CPU1_P2P2_DP<15>")
	)
	(segment
		(start 104.505506 -277.203154)
		(end 104.512872 -277.198836)
		(width 0.0889)
		(layer "In6.Cu")
		(net "UPI_CPU0_CPU1_P2P2_DP<15>")
	)
	(segment
		(start 102.625906 -283.714444)
		(end 102.641146 -283.705554)
		(width 0.0889)
		(layer "In6.Cu")
		(net "UPI_CPU0_CPU1_P2P2_DP<15>")
	)
	(segment
		(start 233.317542 -372.848632)
		(end 233.147362 -372.729506)
		(width 0.14732)
		(layer "In6.Cu")
		(net "UPI_CPU0_CPU1_P2P2_DP<15>")
	)
	(segment
		(start 74.861674 -364.351316)
		(end 74.65695 -364.351316)
		(width 0.14732)
		(layer "In6.Cu")
		(net "UPI_CPU0_CPU1_P2P2_DP<15>")
	)
	(segment
		(start 238.581946 -371.768116)
		(end 238.46282 -371.93855)
		(width 0.14732)
		(layer "In6.Cu")
		(net "UPI_CPU0_CPU1_P2P2_DP<15>")
	)
	(segment
		(start 102.633272 -278.826722)
		(end 102.634796 -278.82596)
		(width 0.0889)
		(layer "In6.Cu")
		(net "UPI_CPU0_CPU1_P2P2_DP<15>")
	)
	(segment
		(start 340.798912 -287.28924)
		(end 340.798912 -287.297876)
		(width 0.0889)
		(layer "In6.Cu")
		(net "UPI_CPU0_CPU1_P2P2_DP<15>")
	)
	(segment
		(start 340.144862 -289.446462)
		(end 340.145116 -289.446462)
		(width 0.0889)
		(layer "In6.Cu")
		(net "UPI_CPU0_CPU1_P2P2_DP<15>")
	)
	(segment
		(start 340.205314 -290.205922)
		(end 340.064852 -290.205922)
		(width 0.0889)
		(layer "In6.Cu")
		(net "UPI_CPU0_CPU1_P2P2_DP<15>")
	)
	(segment
		(start 313.758326 -320.97853)
		(end 313.443112 -321.169284)
		(width 0.14732)
		(layer "In6.Cu")
		(net "UPI_CPU0_CPU1_P2P2_DP<15>")
	)
	(segment
		(start 233.882438 -371.807994)
		(end 234.018074 -372.575328)
		(width 0.14732)
		(layer "In6.Cu")
		(net "UPI_CPU0_CPU1_P2P2_DP<15>")
	)
	(segment
		(start 98.439732 -295.111678)
		(end 98.439732 -294.664638)
		(width 0.14732)
		(layer "In6.Cu")
		(net "UPI_CPU0_CPU1_P2P2_DP<15>")
	)
	(segment
		(start 339.859366 -288.898584)
		(end 339.859366 -289.114738)
		(width 0.0889)
		(layer "In6.Cu")
		(net "UPI_CPU0_CPU1_P2P2_DP<15>")
	)
	(segment
		(start 340.064852 -290.205922)
		(end 339.9409 -290.329874)
		(width 0.0889)
		(layer "In6.Cu")
		(net "UPI_CPU0_CPU1_P2P2_DP<15>")
	)
	(segment
		(start 237.881414 -372.04142)
		(end 237.711234 -371.922294)
		(width 0.14732)
		(layer "In6.Cu")
		(net "UPI_CPU0_CPU1_P2P2_DP<15>")
	)
	(segment
		(start 341.637874 -282.900628)
		(end 341.646764 -282.895548)
		(width 0.0889)
		(layer "In6.Cu")
		(net "UPI_CPU0_CPU1_P2P2_DP<15>")
	)
	(segment
		(start 76.895198 -366.589818)
		(end 76.634848 -366.329468)
		(width 0.14732)
		(layer "In6.Cu")
		(net "UPI_CPU0_CPU1_P2P2_DP<15>")
	)
	(segment
		(start 309.219092 -323.89572)
		(end 308.347364 -324.771512)
		(width 0.14732)
		(layer "In6.Cu")
		(net "UPI_CPU0_CPU1_P2P2_DP<15>")
	)
	(segment
		(start 341.075264 -285.175706)
		(end 341.075518 -285.175452)
		(width 0.0889)
		(layer "In6.Cu")
		(net "UPI_CPU0_CPU1_P2P2_DP<15>")
	)
	(segment
		(start 310.272938 -323.257672)
		(end 310.074056 -323.208904)
		(width 0.14732)
		(layer "In6.Cu")
		(net "UPI_CPU0_CPU1_P2P2_DP<15>")
	)
	(segment
		(start 75.122532 -364.612174)
		(end 74.861674 -364.351316)
		(width 0.14732)
		(layer "In6.Cu")
		(net "UPI_CPU0_CPU1_P2P2_DP<15>")
	)
	(segment
		(start 77.360526 -367.055146)
		(end 77.360526 -366.850422)
		(width 0.14732)
		(layer "In6.Cu")
		(net "UPI_CPU0_CPU1_P2P2_DP<15>")
	)
	(segment
		(start 102.917498 -279.982676)
		(end 102.917498 -279.964134)
		(width 0.0889)
		(layer "In6.Cu")
		(net "UPI_CPU0_CPU1_P2P2_DP<15>")
	)
	(segment
		(start 98.584512 -295.256458)
		(end 98.439732 -295.111678)
		(width 0.14732)
		(layer "In6.Cu")
		(net "UPI_CPU0_CPU1_P2P2_DP<15>")
	)
	(segment
		(start 77.694028 -367.388648)
		(end 77.360526 -367.055146)
		(width 0.14732)
		(layer "In6.Cu")
		(net "UPI_CPU0_CPU1_P2P2_DP<15>")
	)
	(segment
		(start 236.414564 -371.047518)
		(end 236.164374 -371.404388)
		(width 0.14732)
		(layer "In6.Cu")
		(net "UPI_CPU0_CPU1_P2P2_DP<15>")
	)
	(segment
		(start 338.97316 -291.379148)
		(end 336.525616 -293.825422)
		(width 0.14732)
		(layer "In6.Cu")
		(net "UPI_CPU0_CPU1_P2P2_DP<15>")
	)
	(segment
		(start 263.332722 -369.47348)
		(end 248.577862 -372.075456)
		(width 0.14732)
		(layer "In6.Cu")
		(net "UPI_CPU0_CPU1_P2P2_DP<15>")
	)
	(segment
		(start 341.075264 -286.803592)
		(end 341.075518 -286.803338)
		(width 0.0889)
		(layer "In6.Cu")
		(net "UPI_CPU0_CPU1_P2P2_DP<15>")
	)
	(segment
		(start 342.021922 -283.543756)
		(end 342.02116 -283.544264)
		(width 0.0889)
		(layer "In6.Cu")
		(net "UPI_CPU0_CPU1_P2P2_DP<15>")
	)
	(segment
		(start 101.686106 -285.342076)
		(end 101.693472 -285.337758)
		(width 0.0889)
		(layer "In6.Cu")
		(net "UPI_CPU0_CPU1_P2P2_DP<15>")
	)
	(segment
		(start 335.103978 -295.909238)
		(end 333.31785 -301.795434)
		(width 0.14732)
		(layer "In6.Cu")
		(net "UPI_CPU0_CPU1_P2P2_DP<15>")
	)
	(segment
		(start 266.81303 -364.547658)
		(end 266.81303 -364.915958)
		(width 0.14732)
		(layer "In6.Cu")
		(net "UPI_CPU0_CPU1_P2P2_DP<15>")
	)
	(segment
		(start 74.234802 -363.929168)
		(end 74.234802 -363.724444)
		(width 0.14732)
		(layer "In6.Cu")
		(net "UPI_CPU0_CPU1_P2P2_DP<15>")
	)
	(segment
		(start 75.40625 -365.100616)
		(end 75.122532 -364.816898)
		(width 0.14732)
		(layer "In6.Cu")
		(net "UPI_CPU0_CPU1_P2P2_DP<15>")
	)
	(segment
		(start 103.479346 -278.012144)
		(end 103.494078 -278.02078)
		(width 0.0889)
		(layer "In6.Cu")
		(net "UPI_CPU0_CPU1_P2P2_DP<15>")
	)
	(segment
		(start 306.995576 -325.718932)
		(end 306.53228 -326.380348)
		(width 0.14732)
		(layer "In6.Cu")
		(net "UPI_CPU0_CPU1_P2P2_DP<15>")
	)
	(segment
		(start 340.150704 -288.422334)
		(end 340.142576 -288.426906)
		(width 0.0889)
		(layer "In6.Cu")
		(net "UPI_CPU0_CPU1_P2P2_DP<15>")
	)
	(segment
		(start 69.219318 -334.936338)
		(end 69.857112 -328.45883)
		(width 0.14732)
		(layer "In6.Cu")
		(net "UPI_CPU0_CPU1_P2P2_DP<15>")
	)
	(segment
		(start 266.95781 -364.402878)
		(end 266.81303 -364.547658)
		(width 0.14732)
		(layer "In6.Cu")
		(net "UPI_CPU0_CPU1_P2P2_DP<15>")
	)
	(segment
		(start 101.037898 -288.121598)
		(end 101.037898 -288.103056)
		(width 0.0889)
		(layer "In6.Cu")
		(net "UPI_CPU0_CPU1_P2P2_DP<15>")
	)
	(segment
		(start 76.16952 -365.863886)
		(end 75.871832 -365.566198)
		(width 0.14732)
		(layer "In6.Cu")
		(net "UPI_CPU0_CPU1_P2P2_DP<15>")
	)
	(segment
		(start 101.21646 -287.783778)
		(end 101.22535 -287.778698)
		(width 0.0889)
		(layer "In6.Cu")
		(net "UPI_CPU0_CPU1_P2P2_DP<15>")
	)
	(segment
		(start 125.730254 -379.93447)
		(end 98.080576 -375.832624)
		(width 0.14732)
		(layer "In6.Cu")
		(net "UPI_CPU0_CPU1_P2P2_DP<15>")
	)
	(segment
		(start 304.655474 -329.602338)
		(end 304.39487 -329.862942)
		(width 0.14732)
		(layer "In6.Cu")
		(net "UPI_CPU0_CPU1_P2P2_DP<15>")
	)
	(segment
		(start 98.439732 -296.448734)
		(end 98.439732 -295.769538)
		(width 0.14732)
		(layer "In6.Cu")
		(net "UPI_CPU0_CPU1_P2P2_DP<15>")
	)
	(segment
		(start 309.70982 -323.59854)
		(end 309.219092 -323.89572)
		(width 0.14732)
		(layer "In6.Cu")
		(net "UPI_CPU0_CPU1_P2P2_DP<15>")
	)
	(segment
		(start 308.347364 -324.771512)
		(end 306.995576 -325.718932)
		(width 0.14732)
		(layer "In6.Cu")
		(net "UPI_CPU0_CPU1_P2P2_DP<15>")
	)
	(segment
		(start 75.122532 -364.816898)
		(end 75.122532 -364.612174)
		(width 0.14732)
		(layer "In6.Cu")
		(net "UPI_CPU0_CPU1_P2P2_DP<15>")
	)
	(segment
		(start 101.507544 -287.304734)
		(end 101.507544 -287.28924)
		(width 0.0889)
		(layer "In6.Cu")
		(net "UPI_CPU0_CPU1_P2P2_DP<15>")
	)
	(segment
		(start 235.429298 -372.3259)
		(end 235.293408 -371.55882)
		(width 0.14732)
		(layer "In6.Cu")
		(net "UPI_CPU0_CPU1_P2P2_DP<15>")
	)
	(segment
		(start 98.584512 -295.624758)
		(end 98.584512 -295.256458)
		(width 0.14732)
		(layer "In6.Cu")
		(net "UPI_CPU0_CPU1_P2P2_DP<15>")
	)
	(segment
		(start 74.234802 -363.724444)
		(end 73.973944 -363.463586)
		(width 0.14732)
		(layer "In6.Cu")
		(net "UPI_CPU0_CPU1_P2P2_DP<15>")
	)
	(segment
		(start 77.099922 -366.589818)
		(end 76.895198 -366.589818)
		(width 0.14732)
		(layer "In6.Cu")
		(net "UPI_CPU0_CPU1_P2P2_DP<15>")
	)
	(segment
		(start 76.374244 -365.863886)
		(end 76.16952 -365.863886)
		(width 0.14732)
		(layer "In6.Cu")
		(net "UPI_CPU0_CPU1_P2P2_DP<15>")
	)
	(segment
		(start 100.09759 -289.646868)
		(end 100.097844 -289.64636)
		(width 0.0889)
		(layer "In6.Cu")
		(net "UPI_CPU0_CPU1_P2P2_DP<15>")
	)
	(segment
		(start 98.439732 -294.664638)
		(end 98.584512 -294.519858)
		(width 0.14732)
		(layer "In6.Cu")
		(net "UPI_CPU0_CPU1_P2P2_DP<15>")
	)
	(segment
		(start 232.65511 -371.712236)
		(end 212.36559 -375.299224)
		(width 0.14732)
		(layer "In6.Cu")
		(net "UPI_CPU0_CPU1_P2P2_DP<15>")
	)
	(segment
		(start 237.711234 -371.922294)
		(end 237.575344 -371.155214)
		(width 0.14732)
		(layer "In6.Cu")
		(net "UPI_CPU0_CPU1_P2P2_DP<15>")
	)
	(segment
		(start 72.169528 -322.865242)
		(end 80.073754 -314.960762)
		(width 0.14732)
		(layer "In6.Cu")
		(net "UPI_CPU0_CPU1_P2P2_DP<15>")
	)
	(segment
		(start 305.71694 -328.745342)
		(end 304.860198 -329.602338)
		(width 0.14732)
		(layer "In6.Cu")
		(net "UPI_CPU0_CPU1_P2P2_DP<15>")
	)
	(segment
		(start 238.46282 -371.93855)
		(end 237.881414 -372.04142)
		(width 0.14732)
		(layer "In6.Cu")
		(net "UPI_CPU0_CPU1_P2P2_DP<15>")
	)
	(segment
		(start 102.15626 -284.52826)
		(end 102.16515 -284.52318)
		(width 0.0889)
		(layer "In6.Cu")
		(net "UPI_CPU0_CPU1_P2P2_DP<15>")
	)
	(segment
		(start 313.443112 -321.169284)
		(end 313.39409 -321.36842)
		(width 0.14732)
		(layer "In6.Cu")
		(net "UPI_CPU0_CPU1_P2P2_DP<15>")
	)
	(segment
		(start 338.988654 -291.363654)
		(end 338.97316 -291.379148)
		(width 0.0889)
		(layer "In6.Cu")
		(net "UPI_CPU0_CPU1_P2P2_DP<15>")
	)
	(segment
		(start 313.957208 -321.027552)
		(end 313.758326 -320.97853)
		(width 0.14732)
		(layer "In6.Cu")
		(net "UPI_CPU0_CPU1_P2P2_DP<15>")
	)
	(segment
		(start 101.701346 -286.961072)
		(end 101.701092 -286.961326)
		(width 0.0889)
		(layer "In6.Cu")
		(net "UPI_CPU0_CPU1_P2P2_DP<15>")
	)
	(segment
		(start 104.514396 -277.198074)
		(end 104.515158 -277.197566)
		(width 0.0889)
		(layer "In6.Cu")
		(net "UPI_CPU0_CPU1_P2P2_DP<15>")
	)
	(segment
		(start 101.694996 -285.336996)
		(end 101.69779 -285.335472)
		(width 0.0889)
		(layer "In6.Cu")
		(net "UPI_CPU0_CPU1_P2P2_DP<15>")
	)
	(segment
		(start 98.584512 -294.151558)
		(end 98.439732 -294.006778)
		(width 0.14732)
		(layer "In6.Cu")
		(net "UPI_CPU0_CPU1_P2P2_DP<15>")
	)
	(segment
		(start 235.293408 -371.55882)
		(end 234.936792 -371.30863)
		(width 0.14732)
		(layer "In6.Cu")
		(net "UPI_CPU0_CPU1_P2P2_DP<15>")
	)
	(segment
		(start 70.326758 -326.761602)
		(end 72.169528 -322.865242)
		(width 0.14732)
		(layer "In6.Cu")
		(net "UPI_CPU0_CPU1_P2P2_DP<15>")
	)
	(arc
		(start 102.62616 -281.097482)
		(mid 102.447563 -280.778204)
		(end 102.62616 -280.458926)
		(width 0.0889)
		(layer "In6.Cu")
		(net "UPI_CPU0_CPU1_P2P2_DP<15>")
	)
	(arc
		(start 341.646764 -282.895548)
		(mid 341.833962 -282.845405)
		(end 342.02116 -282.895548)
		(width 0.0889)
		(layer "In6.Cu")
		(net "UPI_CPU0_CPU1_P2P2_DP<15>")
	)
	(arc
		(start 102.917498 -278.336502)
		(mid 102.91755 -278.329135)
		(end 102.917752 -278.32177)
		(width 0.0889)
		(layer "In6.Cu")
		(net "UPI_CPU0_CPU1_P2P2_DP<15>")
	)
	(arc
		(start 100.097844 -289.64636)
		(mid 100.172915 -289.530618)
		(end 100.282248 -289.446462)
		(width 0.0889)
		(layer "In6.Cu")
		(net "UPI_CPU0_CPU1_P2P2_DP<15>")
	)
	(arc
		(start 341.090504 -286.156146)
		(mid 341.269222 -286.475424)
		(end 341.090504 -286.794702)
		(width 0.0889)
		(layer "In6.Cu")
		(net "UPI_CPU0_CPU1_P2P2_DP<15>")
	)
	(arc
		(start 340.145116 -289.446462)
		(mid 340.254127 -289.53042)
		(end 340.329012 -289.645852)
		(width 0.0889)
		(layer "In6.Cu")
		(net "UPI_CPU0_CPU1_P2P2_DP<15>")
	)
	(arc
		(start 102.62616 -282.725114)
		(mid 102.447563 -282.405836)
		(end 102.62616 -282.086558)
		(width 0.0889)
		(layer "In6.Cu")
		(net "UPI_CPU0_CPU1_P2P2_DP<15>")
	)
	(arc
		(start 102.625906 -279.469596)
		(mid 102.447309 -279.150318)
		(end 102.625906 -278.83104)
		(width 0.0889)
		(layer "In6.Cu")
		(net "UPI_CPU0_CPU1_P2P2_DP<15>")
	)
	(arc
		(start 342.03005 -282.900628)
		(mid 342.157304 -283.030594)
		(end 342.208358 -283.205174)
		(width 0.0889)
		(layer "In6.Cu")
		(net "UPI_CPU0_CPU1_P2P2_DP<15>")
	)
	(arc
		(start 101.507544 -287.28924)
		(mid 101.555223 -287.10634)
		(end 101.686106 -286.969962)
		(width 0.0889)
		(layer "In6.Cu")
		(net "UPI_CPU0_CPU1_P2P2_DP<15>")
	)
	(arc
		(start 103.494078 -278.02078)
		(mid 103.770519 -278.087946)
		(end 104.04475 -278.012144)
		(width 0.0889)
		(layer "In6.Cu")
		(net "UPI_CPU0_CPU1_P2P2_DP<15>")
	)
	(arc
		(start 102.917752 -278.32177)
		(mid 102.968806 -278.14719)
		(end 103.09606 -278.017224)
		(width 0.0889)
		(layer "In6.Cu")
		(net "UPI_CPU0_CPU1_P2P2_DP<15>")
	)
	(arc
		(start 100.75545 -288.592768)
		(mid 100.957736 -288.393787)
		(end 101.037898 -288.121598)
		(width 0.0889)
		(layer "In6.Cu")
		(net "UPI_CPU0_CPU1_P2P2_DP<15>")
	)
	(arc
		(start 342.02116 -283.544264)
		(mid 341.816825 -283.746869)
		(end 341.738712 -284.023816)
		(width 0.0889)
		(layer "In6.Cu")
		(net "UPI_CPU0_CPU1_P2P2_DP<15>")
	)
	(arc
		(start 101.686106 -285.980632)
		(mid 101.507388 -285.661354)
		(end 101.686106 -285.342076)
		(width 0.0889)
		(layer "In6.Cu")
		(net "UPI_CPU0_CPU1_P2P2_DP<15>")
	)
	(arc
		(start 342.208612 -283.219906)
		(mid 342.160933 -283.402806)
		(end 342.03005 -283.539184)
		(width 0.0889)
		(layer "In6.Cu")
		(net "UPI_CPU0_CPU1_P2P2_DP<15>")
	)
	(arc
		(start 101.977698 -286.4612)
		(mid 101.898479 -286.186515)
		(end 101.694996 -285.985712)
		(width 0.0889)
		(layer "In6.Cu")
		(net "UPI_CPU0_CPU1_P2P2_DP<15>")
	)
	(arc
		(start 341.463884 -283.162502)
		(mid 341.52204 -283.012389)
		(end 341.637874 -282.900628)
		(width 0.0889)
		(layer "In6.Cu")
		(net "UPI_CPU0_CPU1_P2P2_DP<15>")
	)
	(arc
		(start 102.640892 -278.822404)
		(mid 102.843479 -278.616053)
		(end 102.917498 -278.336502)
		(width 0.0889)
		(layer "In6.Cu")
		(net "UPI_CPU0_CPU1_P2P2_DP<15>")
	)
	(arc
		(start 341.738712 -284.033722)
		(mid 341.691033 -284.216622)
		(end 341.56015 -284.353)
		(width 0.0889)
		(layer "In6.Cu")
		(net "UPI_CPU0_CPU1_P2P2_DP<15>")
	)
	(arc
		(start 102.16515 -284.52318)
		(mid 102.367973 -284.322949)
		(end 102.447344 -284.049216)
		(width 0.0889)
		(layer "In6.Cu")
		(net "UPI_CPU0_CPU1_P2P2_DP<15>")
	)
	(arc
		(start 102.63505 -282.081478)
		(mid 102.839385 -281.878873)
		(end 102.917498 -281.601926)
		(width 0.0889)
		(layer "In6.Cu")
		(net "UPI_CPU0_CPU1_P2P2_DP<15>")
	)
	(arc
		(start 102.640892 -283.705808)
		(mid 102.843479 -283.499457)
		(end 102.917498 -283.219906)
		(width 0.0889)
		(layer "In6.Cu")
		(net "UPI_CPU0_CPU1_P2P2_DP<15>")
	)
	(arc
		(start 341.269066 -284.847538)
		(mid 341.221387 -285.030438)
		(end 341.090504 -285.166816)
		(width 0.0889)
		(layer "In6.Cu")
		(net "UPI_CPU0_CPU1_P2P2_DP<15>")
	)
	(arc
		(start 340.798912 -285.675578)
		(mid 340.878131 -285.950263)
		(end 341.081614 -286.151066)
		(width 0.0889)
		(layer "In6.Cu")
		(net "UPI_CPU0_CPU1_P2P2_DP<15>")
	)
	(arc
		(start 102.917498 -281.582114)
		(mid 102.839387 -281.305165)
		(end 102.63505 -281.102562)
		(width 0.0889)
		(layer "In6.Cu")
		(net "UPI_CPU0_CPU1_P2P2_DP<15>")
	)
	(arc
		(start 104.790494 -276.79523)
		(mid 104.791989 -276.784829)
		(end 104.793288 -276.774402)
		(width 0.0889)
		(layer "In6.Cu")
		(net "UPI_CPU0_CPU1_P2P2_DP<15>")
	)
	(arc
		(start 101.037898 -288.103056)
		(mid 101.085577 -287.920156)
		(end 101.21646 -287.783778)
		(width 0.0889)
		(layer "In6.Cu")
		(net "UPI_CPU0_CPU1_P2P2_DP<15>")
	)
	(arc
		(start 102.63505 -280.453846)
		(mid 102.837336 -280.254865)
		(end 102.917498 -279.982676)
		(width 0.0889)
		(layer "In6.Cu")
		(net "UPI_CPU0_CPU1_P2P2_DP<15>")
	)
	(arc
		(start 340.141814 -288.427414)
		(mid 339.939528 -288.626395)
		(end 339.859366 -288.898584)
		(width 0.0889)
		(layer "In6.Cu")
		(net "UPI_CPU0_CPU1_P2P2_DP<15>")
	)
	(arc
		(start 101.701092 -285.33344)
		(mid 101.903679 -285.127089)
		(end 101.977698 -284.847538)
		(width 0.0889)
		(layer "In6.Cu")
		(net "UPI_CPU0_CPU1_P2P2_DP<15>")
	)
	(arc
		(start 340.798912 -287.297876)
		(mid 340.746642 -287.480241)
		(end 340.611714 -287.613598)
		(width 0.0889)
		(layer "In6.Cu")
		(net "UPI_CPU0_CPU1_P2P2_DP<15>")
	)
	(arc
		(start 104.04475 -278.012144)
		(mid 104.246032 -277.814657)
		(end 104.326944 -277.54453)
		(width 0.0889)
		(layer "In6.Cu")
		(net "UPI_CPU0_CPU1_P2P2_DP<15>")
	)
	(arc
		(start 102.447344 -284.033722)
		(mid 102.495023 -283.850822)
		(end 102.625906 -283.714444)
		(width 0.0889)
		(layer "In6.Cu")
		(net "UPI_CPU0_CPU1_P2P2_DP<15>")
	)
	(arc
		(start 101.701092 -286.961326)
		(mid 101.903679 -286.754975)
		(end 101.977698 -286.475424)
		(width 0.0889)
		(layer "In6.Cu")
		(net "UPI_CPU0_CPU1_P2P2_DP<15>")
	)
	(arc
		(start 339.859366 -289.114738)
		(mid 339.970704 -289.307638)
		(end 340.144862 -289.446462)
		(width 0.0889)
		(layer "In6.Cu")
		(net "UPI_CPU0_CPU1_P2P2_DP<15>")
	)
	(arc
		(start 340.611714 -287.613598)
		(mid 340.407379 -287.816203)
		(end 340.329266 -288.09315)
		(width 0.0889)
		(layer "In6.Cu")
		(net "UPI_CPU0_CPU1_P2P2_DP<15>")
	)
	(arc
		(start 103.10495 -278.012144)
		(mid 103.292148 -277.962001)
		(end 103.479346 -278.012144)
		(width 0.0889)
		(layer "In6.Cu")
		(net "UPI_CPU0_CPU1_P2P2_DP<15>")
	)
	(arc
		(start 102.917498 -279.964134)
		(mid 102.843507 -279.684568)
		(end 102.640892 -279.478232)
		(width 0.0889)
		(layer "In6.Cu")
		(net "UPI_CPU0_CPU1_P2P2_DP<15>")
	)
	(arc
		(start 340.329266 -288.103056)
		(mid 340.281587 -288.285956)
		(end 340.150704 -288.422334)
		(width 0.0889)
		(layer "In6.Cu")
		(net "UPI_CPU0_CPU1_P2P2_DP<15>")
	)
	(arc
		(start 101.977698 -284.847538)
		(mid 102.025377 -284.664638)
		(end 102.15626 -284.52826)
		(width 0.0889)
		(layer "In6.Cu")
		(net "UPI_CPU0_CPU1_P2P2_DP<15>")
	)
	(arc
		(start 101.22535 -287.778698)
		(mid 101.428173 -287.578467)
		(end 101.507544 -287.304734)
		(width 0.0889)
		(layer "In6.Cu")
		(net "UPI_CPU0_CPU1_P2P2_DP<15>")
	)
	(arc
		(start 342.208358 -283.205174)
		(mid 342.208555 -283.212539)
		(end 342.208612 -283.219906)
		(width 0.0889)
		(layer "In6.Cu")
		(net "UPI_CPU0_CPU1_P2P2_DP<15>")
	)
	(arc
		(start 341.55126 -284.35808)
		(mid 341.348437 -284.558311)
		(end 341.269066 -284.832044)
		(width 0.0889)
		(layer "In6.Cu")
		(net "UPI_CPU0_CPU1_P2P2_DP<15>")
	)
	(arc
		(start 341.075518 -285.175452)
		(mid 340.872931 -285.381803)
		(end 340.798912 -285.661354)
		(width 0.0889)
		(layer "In6.Cu")
		(net "UPI_CPU0_CPU1_P2P2_DP<15>")
	)
	(arc
		(start 104.326944 -277.522432)
		(mid 104.374623 -277.339532)
		(end 104.505506 -277.203154)
		(width 0.0889)
		(layer "In6.Cu")
		(net "UPI_CPU0_CPU1_P2P2_DP<15>")
	)
	(arc
		(start 100.567998 -288.917126)
		(mid 100.615677 -288.734226)
		(end 100.74656 -288.597848)
		(width 0.0889)
		(layer "In6.Cu")
		(net "UPI_CPU0_CPU1_P2P2_DP<15>")
	)
	(arc
		(start 341.075518 -286.803338)
		(mid 340.872931 -287.009689)
		(end 340.798912 -287.28924)
		(width 0.0889)
		(layer "In6.Cu")
		(net "UPI_CPU0_CPU1_P2P2_DP<15>")
	)
	(arc
		(start 104.520492 -277.194518)
		(mid 104.700144 -277.025082)
		(end 104.790494 -276.79523)
		(width 0.0889)
		(layer "In6.Cu")
		(net "UPI_CPU0_CPU1_P2P2_DP<15>")
	)
	(arc
		(start 102.917498 -283.201364)
		(mid 102.837336 -282.929175)
		(end 102.63505 -282.730194)
		(width 0.0889)
		(layer "In6.Cu")
		(net "UPI_CPU0_CPU1_P2P2_DP<15>")
	)
	(arc
		(start 100.282248 -289.446462)
		(mid 100.456549 -289.307532)
		(end 100.567998 -289.114484)
		(width 0.0889)
		(layer "In6.Cu")
		(net "UPI_CPU0_CPU1_P2P2_DP<15>")
	)
	(segment
		(start 341.36457 -282.405582)
		(end 341.364316 -282.405836)
		(width 0.13208)
		(layer "F.Cu")
		(net "UPI_CPU0_CPU1_P2P2_DP<14>")
	)
	(segment
		(start 103.762048 -276.986492)
		(end 103.762048 -277.521924)
		(width 0.13208)
		(layer "F.Cu")
		(net "UPI_CPU0_CPU1_P2P2_DP<14>")
	)
	(segment
		(start 103.762048 -277.521924)
		(end 103.761794 -277.522178)
		(width 0.13208)
		(layer "F.Cu")
		(net "UPI_CPU0_CPU1_P2P2_DP<14>")
	)
	(segment
		(start 341.36457 -281.87015)
		(end 341.36457 -282.405582)
		(width 0.13208)
		(layer "F.Cu")
		(net "UPI_CPU0_CPU1_P2P2_DP<14>")
	)
	(segment
		(start 103.761794 -277.522178)
		(end 103.761794 -277.522432)
		(width 0.13208)
		(layer "F.Cu")
		(net "UPI_CPU0_CPU1_P2P2_DP<14>")
	)
	(segment
		(start 341.364316 -281.869896)
		(end 341.36457 -281.87015)
		(width 0.13208)
		(layer "F.Cu")
		(net "UPI_CPU0_CPU1_P2P2_DP<14>")
	)
	(segment
		(start 312.868818 -322.77939)
		(end 310.76519 -324.258432)
		(width 0.14732)
		(layer "In6.Cu")
		(net "UPI_CPU0_CPU1_P2P2_DP<14>")
	)
	(segment
		(start 336.139282 -299.865034)
		(end 335.956148 -299.962824)
		(width 0.14732)
		(layer "In6.Cu")
		(net "UPI_CPU0_CPU1_P2P2_DP<14>")
	)
	(segment
		(start 68.848224 -354.60178)
		(end 68.707254 -354.26142)
		(width 0.14732)
		(layer "In6.Cu")
		(net "UPI_CPU0_CPU1_P2P2_DP<14>")
	)
	(segment
		(start 310.76519 -324.258432)
		(end 310.76519 -324.25894)
		(width 0.14732)
		(layer "In6.Cu")
		(net "UPI_CPU0_CPU1_P2P2_DP<14>")
	)
	(segment
		(start 342.208866 -284.832044)
		(end 342.208866 -284.847538)
		(width 0.0889)
		(layer "In6.Cu")
		(net "UPI_CPU0_CPU1_P2P2_DP<14>")
	)
	(segment
		(start 341.090504 -288.422334)
		(end 341.081614 -288.427414)
		(width 0.0889)
		(layer "In6.Cu")
		(net "UPI_CPU0_CPU1_P2P2_DP<14>")
	)
	(segment
		(start 68.910962 -355.131116)
		(end 68.769992 -354.79101)
		(width 0.14732)
		(layer "In6.Cu")
		(net "UPI_CPU0_CPU1_P2P2_DP<14>")
	)
	(segment
		(start 77.277214 -368.154204)
		(end 72.209914 -363.086904)
		(width 0.14732)
		(layer "In6.Cu")
		(net "UPI_CPU0_CPU1_P2P2_DP<14>")
	)
	(segment
		(start 342.021414 -286.799782)
		(end 342.020652 -286.80029)
		(width 0.0889)
		(layer "In6.Cu")
		(net "UPI_CPU0_CPU1_P2P2_DP<14>")
	)
	(segment
		(start 314.797948 -321.490086)
		(end 312.868818 -322.77939)
		(width 0.14732)
		(layer "In6.Cu")
		(net "UPI_CPU0_CPU1_P2P2_DP<14>")
	)
	(segment
		(start 335.956148 -299.962824)
		(end 335.140046 -299.715174)
		(width 0.14732)
		(layer "In6.Cu")
		(net "UPI_CPU0_CPU1_P2P2_DP<14>")
	)
	(segment
		(start 340.66988 -291.001196)
		(end 339.178138 -292.492938)
		(width 0.0889)
		(layer "In6.Cu")
		(net "UPI_CPU0_CPU1_P2P2_DP<14>")
	)
	(segment
		(start 68.769992 -354.79101)
		(end 68.848224 -354.60178)
		(width 0.14732)
		(layer "In6.Cu")
		(net "UPI_CPU0_CPU1_P2P2_DP<14>")
	)
	(segment
		(start 100.755196 -283.709364)
		(end 100.767388 -283.702252)
		(width 0.0889)
		(layer "In6.Cu")
		(net "UPI_CPU0_CPU1_P2P2_DP<14>")
	)
	(segment
		(start 102.447598 -277.540974)
		(end 102.447598 -277.513796)
		(width 0.0889)
		(layer "In6.Cu")
		(net "UPI_CPU0_CPU1_P2P2_DP<14>")
	)
	(segment
		(start 101.22535 -281.916378)
		(end 101.21646 -281.911298)
		(width 0.0889)
		(layer "In6.Cu")
		(net "UPI_CPU0_CPU1_P2P2_DP<14>")
	)
	(segment
		(start 268.040612 -362.998258)
		(end 267.895832 -363.143038)
		(width 0.14732)
		(layer "In6.Cu")
		(net "UPI_CPU0_CPU1_P2P2_DP<14>")
	)
	(segment
		(start 97.465388 -295.876218)
		(end 97.465388 -295.507918)
		(width 0.14732)
		(layer "In6.Cu")
		(net "UPI_CPU0_CPU1_P2P2_DP<14>")
	)
	(segment
		(start 99.15779 -290.21786)
		(end 99.15779 -289.610292)
		(width 0.0889)
		(layer "In6.Cu")
		(net "UPI_CPU0_CPU1_P2P2_DP<14>")
	)
	(segment
		(start 99.33686 -287.783778)
		(end 99.34575 -287.778698)
		(width 0.0889)
		(layer "In6.Cu")
		(net "UPI_CPU0_CPU1_P2P2_DP<14>")
	)
	(segment
		(start 101.694996 -278.82596)
		(end 101.707188 -278.818848)
		(width 0.0889)
		(layer "In6.Cu")
		(net "UPI_CPU0_CPU1_P2P2_DP<14>")
	)
	(segment
		(start 101.037898 -279.978358)
		(end 101.037898 -279.964134)
		(width 0.0889)
		(layer "In6.Cu")
		(net "UPI_CPU0_CPU1_P2P2_DP<14>")
	)
	(segment
		(start 101.507544 -282.427934)
		(end 101.507544 -282.390342)
		(width 0.0889)
		(layer "In6.Cu")
		(net "UPI_CPU0_CPU1_P2P2_DP<14>")
	)
	(segment
		(start 97.320608 -294.994838)
		(end 97.465388 -294.850058)
		(width 0.14732)
		(layer "In6.Cu")
		(net "UPI_CPU0_CPU1_P2P2_DP<14>")
	)
	(segment
		(start 340.66988 -290.568888)
		(end 340.66988 -291.001196)
		(width 0.0889)
		(layer "In6.Cu")
		(net "UPI_CPU0_CPU1_P2P2_DP<14>")
	)
	(segment
		(start 99.158044 -289.610038)
		(end 99.158044 -289.60953)
		(width 0.0889)
		(layer "In6.Cu")
		(net "UPI_CPU0_CPU1_P2P2_DP<14>")
	)
	(segment
		(start 341.269066 -289.64636)
		(end 341.269066 -289.969702)
		(width 0.0889)
		(layer "In6.Cu")
		(net "UPI_CPU0_CPU1_P2P2_DP<14>")
	)
	(segment
		(start 334.053942 -302.234346)
		(end 314.797948 -321.490086)
		(width 0.14732)
		(layer "In6.Cu")
		(net "UPI_CPU0_CPU1_P2P2_DP<14>")
	)
	(segment
		(start 306.436776 -329.740768)
		(end 305.974242 -330.401422)
		(width 0.14732)
		(layer "In6.Cu")
		(net "UPI_CPU0_CPU1_P2P2_DP<14>")
	)
	(segment
		(start 94.859602 -301.752508)
		(end 95.957898 -300.271942)
		(width 0.14732)
		(layer "In6.Cu")
		(net "UPI_CPU0_CPU1_P2P2_DP<14>")
	)
	(segment
		(start 97.320608 -292.965632)
		(end 97.320608 -292.597332)
		(width 0.14732)
		(layer "In6.Cu")
		(net "UPI_CPU0_CPU1_P2P2_DP<14>")
	)
	(segment
		(start 310.271922 -324.605904)
		(end 309.970932 -324.65899)
		(width 0.14732)
		(layer "In6.Cu")
		(net "UPI_CPU0_CPU1_P2P2_DP<14>")
	)
	(segment
		(start 342.030304 -285.166816)
		(end 342.021414 -285.171896)
		(width 0.0889)
		(layer "In6.Cu")
		(net "UPI_CPU0_CPU1_P2P2_DP<14>")
	)
	(segment
		(start 307.152802 -328.718418)
		(end 306.814474 -329.201526)
		(width 0.14732)
		(layer "In6.Cu")
		(net "UPI_CPU0_CPU1_P2P2_DP<14>")
	)
	(segment
		(start 340.799166 -288.898584)
		(end 340.799166 -289.114738)
		(width 0.0889)
		(layer "In6.Cu")
		(net "UPI_CPU0_CPU1_P2P2_DP<14>")
	)
	(segment
		(start 341.269066 -289.969702)
		(end 340.66988 -290.568888)
		(width 0.0889)
		(layer "In6.Cu")
		(net "UPI_CPU0_CPU1_P2P2_DP<14>")
	)
	(segment
		(start 342.678512 -284.023816)
		(end 342.678512 -284.033722)
		(width 0.0889)
		(layer "In6.Cu")
		(net "UPI_CPU0_CPU1_P2P2_DP<14>")
	)
	(segment
		(start 101.21646 -282.900628)
		(end 101.22535 -282.895548)
		(width 0.0889)
		(layer "In6.Cu")
		(net "UPI_CPU0_CPU1_P2P2_DP<14>")
	)
	(segment
		(start 101.21646 -279.644856)
		(end 101.22535 -279.639776)
		(width 0.0889)
		(layer "In6.Cu")
		(net "UPI_CPU0_CPU1_P2P2_DP<14>")
	)
	(segment
		(start 100.098098 -286.475424)
		(end 100.098098 -286.4612)
		(width 0.0889)
		(layer "In6.Cu")
		(net "UPI_CPU0_CPU1_P2P2_DP<14>")
	)
	(segment
		(start 339.11921 -292.492938)
		(end 339.103716 -292.508432)
		(width 0.0889)
		(layer "In6.Cu")
		(net "UPI_CPU0_CPU1_P2P2_DP<14>")
	)
	(segment
		(start 267.895832 -365.563658)
		(end 268.040612 -365.708438)
		(width 0.14732)
		(layer "In6.Cu")
		(net "UPI_CPU0_CPU1_P2P2_DP<14>")
	)
	(segment
		(start 70.0278 -357.445818)
		(end 69.88683 -357.105204)
		(width 0.14732)
		(layer "In6.Cu")
		(net "UPI_CPU0_CPU1_P2P2_DP<14>")
	)
	(segment
		(start 284.74035 -331.44968)
		(end 278.456644 -334.052164)
		(width 0.14732)
		(layer "In6.Cu")
		(net "UPI_CPU0_CPU1_P2P2_DP<14>")
	)
	(segment
		(start 99.813872 -285.337758)
		(end 99.815396 -285.336996)
		(width 0.0889)
		(layer "In6.Cu")
		(net "UPI_CPU0_CPU1_P2P2_DP<14>")
	)
	(segment
		(start 99.199954 -290.260024)
		(end 99.15779 -290.21786)
		(width 0.0889)
		(layer "In6.Cu")
		(net "UPI_CPU0_CPU1_P2P2_DP<14>")
	)
	(segment
		(start 306.612544 -329.237086)
		(end 306.401216 -329.539092)
		(width 0.14732)
		(layer "In6.Cu")
		(net "UPI_CPU0_CPU1_P2P2_DP<14>")
	)
	(segment
		(start 304.925984 -331.44968)
		(end 284.74035 -331.44968)
		(width 0.14732)
		(layer "In6.Cu")
		(net "UPI_CPU0_CPU1_P2P2_DP<14>")
	)
	(segment
		(start 69.304154 -356.079044)
		(end 69.163184 -355.738938)
		(width 0.14732)
		(layer "In6.Cu")
		(net "UPI_CPU0_CPU1_P2P2_DP<14>")
	)
	(segment
		(start 268.040612 -364.024418)
		(end 267.895832 -364.169198)
		(width 0.14732)
		(layer "In6.Cu")
		(net "UPI_CPU0_CPU1_P2P2_DP<14>")
	)
	(segment
		(start 341.738712 -285.661354)
		(end 341.738712 -285.675578)
		(width 0.0889)
		(layer "In6.Cu")
		(net "UPI_CPU0_CPU1_P2P2_DP<14>")
	)
	(segment
		(start 335.855056 -296.300906)
		(end 335.12633 -298.701206)
		(width 0.14732)
		(layer "In6.Cu")
		(net "UPI_CPU0_CPU1_P2P2_DP<14>")
	)
	(segment
		(start 101.507798 -279.160224)
		(end 101.507798 -279.141682)
		(width 0.0889)
		(layer "In6.Cu")
		(net "UPI_CPU0_CPU1_P2P2_DP<14>")
	)
	(segment
		(start 79.515208 -314.34532)
		(end 94.859602 -301.752508)
		(width 0.14732)
		(layer "In6.Cu")
		(net "UPI_CPU0_CPU1_P2P2_DP<14>")
	)
	(segment
		(start 100.754434 -281.102054)
		(end 100.746306 -281.097228)
		(width 0.0889)
		(layer "In6.Cu")
		(net "UPI_CPU0_CPU1_P2P2_DP<14>")
	)
	(segment
		(start 125.60935 -380.76251)
		(end 97.734374 -376.627644)
		(width 0.14732)
		(layer "In6.Cu")
		(net "UPI_CPU0_CPU1_P2P2_DP<14>")
	)
	(segment
		(start 268.040612 -366.861598)
		(end 263.167114 -371.73535)
		(width 0.14732)
		(layer "In6.Cu")
		(net "UPI_CPU0_CPU1_P2P2_DP<14>")
	)
	(segment
		(start 268.040612 -365.708438)
		(end 268.040612 -366.861598)
		(width 0.14732)
		(layer "In6.Cu")
		(net "UPI_CPU0_CPU1_P2P2_DP<14>")
	)
	(segment
		(start 336.958432 -294.6527)
		(end 335.855056 -296.300906)
		(width 0.14732)
		(layer "In6.Cu")
		(net "UPI_CPU0_CPU1_P2P2_DP<14>")
	)
	(segment
		(start 267.895832 -363.143038)
		(end 267.895832 -363.511338)
		(width 0.14732)
		(layer "In6.Cu")
		(net "UPI_CPU0_CPU1_P2P2_DP<14>")
	)
	(segment
		(start 68.51777 -354.183188)
		(end 68.376038 -353.84105)
		(width 0.14732)
		(layer "In6.Cu")
		(net "UPI_CPU0_CPU1_P2P2_DP<14>")
	)
	(segment
		(start 97.734374 -376.627644)
		(end 77.277214 -368.154204)
		(width 0.14732)
		(layer "In6.Cu")
		(net "UPI_CPU0_CPU1_P2P2_DP<14>")
	)
	(segment
		(start 71.454264 -322.406264)
		(end 79.515208 -314.34532)
		(width 0.14732)
		(layer "In6.Cu")
		(net "UPI_CPU0_CPU1_P2P2_DP<14>")
	)
	(segment
		(start 97.465388 -293.110412)
		(end 97.320608 -292.965632)
		(width 0.14732)
		(layer "In6.Cu")
		(net "UPI_CPU0_CPU1_P2P2_DP<14>")
	)
	(segment
		(start 100.567744 -284.049216)
		(end 100.567744 -284.033722)
		(width 0.0889)
		(layer "In6.Cu")
		(net "UPI_CPU0_CPU1_P2P2_DP<14>")
	)
	(segment
		(start 97.465388 -293.478712)
		(end 97.465388 -293.110412)
		(width 0.14732)
		(layer "In6.Cu")
		(net "UPI_CPU0_CPU1_P2P2_DP<14>")
	)
	(segment
		(start 305.974242 -330.401422)
		(end 304.925984 -331.44968)
		(width 0.14732)
		(layer "In6.Cu")
		(net "UPI_CPU0_CPU1_P2P2_DP<14>")
	)
	(segment
		(start 342.678512 -282.3972)
		(end 342.678512 -282.424378)
		(width 0.0889)
		(layer "In6.Cu")
		(net "UPI_CPU0_CPU1_P2P2_DP<14>")
	)
	(segment
		(start 198.54037 -374.036844)
		(end 198.496174 -374.03024)
		(width 0.14732)
		(layer "In6.Cu")
		(net "UPI_CPU0_CPU1_P2P2_DP<14>")
	)
	(segment
		(start 97.465388 -294.481758)
		(end 97.320608 -294.336978)
		(width 0.14732)
		(layer "In6.Cu")
		(net "UPI_CPU0_CPU1_P2P2_DP<14>")
	)
	(segment
		(start 341.52078 -282.134818)
		(end 341.60968 -282.111196)
		(width 0.0889)
		(layer "In6.Cu")
		(net "UPI_CPU0_CPU1_P2P2_DP<14>")
	)
	(segment
		(start 99.81819 -285.335472)
		(end 99.821492 -285.33344)
		(width 0.0889)
		(layer "In6.Cu")
		(net "UPI_CPU0_CPU1_P2P2_DP<14>")
	)
	(segment
		(start 98.86696 -288.597848)
		(end 98.87585 -288.592768)
		(width 0.0889)
		(layer "In6.Cu")
		(net "UPI_CPU0_CPU1_P2P2_DP<14>")
	)
	(segment
		(start 342.49995 -284.353)
		(end 342.49106 -284.35808)
		(width 0.0889)
		(layer "In6.Cu")
		(net "UPI_CPU0_CPU1_P2P2_DP<14>")
	)
	(segment
		(start 335.12633 -298.701206)
		(end 335.331562 -299.085)
		(width 0.14732)
		(layer "In6.Cu")
		(net "UPI_CPU0_CPU1_P2P2_DP<14>")
	)
	(segment
		(start 341.364316 -282.405836)
		(end 341.52078 -282.134818)
		(width 0.0889)
		(layer "In6.Cu")
		(net "UPI_CPU0_CPU1_P2P2_DP<14>")
	)
	(segment
		(start 268.040612 -363.656118)
		(end 268.040612 -364.024418)
		(width 0.14732)
		(layer "In6.Cu")
		(net "UPI_CPU0_CPU1_P2P2_DP<14>")
	)
	(segment
		(start 69.493638 -356.157276)
		(end 69.304154 -356.079044)
		(width 0.14732)
		(layer "In6.Cu")
		(net "UPI_CPU0_CPU1_P2P2_DP<14>")
	)
	(segment
		(start 268.040612 -344.468196)
		(end 268.040612 -362.998258)
		(width 0.14732)
		(layer "In6.Cu")
		(net "UPI_CPU0_CPU1_P2P2_DP<14>")
	)
	(segment
		(start 100.27666 -284.52826)
		(end 100.28555 -284.52318)
		(width 0.0889)
		(layer "In6.Cu")
		(net "UPI_CPU0_CPU1_P2P2_DP<14>")
	)
	(segment
		(start 69.556376 -356.686866)
		(end 69.634608 -356.49789)
		(width 0.14732)
		(layer "In6.Cu")
		(net "UPI_CPU0_CPU1_P2P2_DP<14>")
	)
	(segment
		(start 68.376038 -353.84105)
		(end 68.376038 -334.869028)
		(width 0.14732)
		(layer "In6.Cu")
		(net "UPI_CPU0_CPU1_P2P2_DP<14>")
	)
	(segment
		(start 341.268812 -289.645852)
		(end 341.269066 -289.64636)
		(width 0.0889)
		(layer "In6.Cu")
		(net "UPI_CPU0_CPU1_P2P2_DP<14>")
	)
	(segment
		(start 68.376038 -334.869028)
		(end 69.01307 -328.399394)
		(width 0.14732)
		(layer "In6.Cu")
		(net "UPI_CPU0_CPU1_P2P2_DP<14>")
	)
	(segment
		(start 97.320608 -292.597332)
		(end 99.199954 -290.717986)
		(width 0.14732)
		(layer "In6.Cu")
		(net "UPI_CPU0_CPU1_P2P2_DP<14>")
	)
	(segment
		(start 267.895832 -365.195358)
		(end 267.895832 -365.563658)
		(width 0.14732)
		(layer "In6.Cu")
		(net "UPI_CPU0_CPU1_P2P2_DP<14>")
	)
	(segment
		(start 99.806506 -286.969962)
		(end 99.821746 -286.961072)
		(width 0.0889)
		(layer "In6.Cu")
		(net "UPI_CPU0_CPU1_P2P2_DP<14>")
	)
	(segment
		(start 309.970932 -324.65899)
		(end 308.114446 -325.958962)
		(width 0.14732)
		(layer "In6.Cu")
		(net "UPI_CPU0_CPU1_P2P2_DP<14>")
	)
	(segment
		(start 100.746306 -280.458926)
		(end 100.755196 -280.453846)
		(width 0.0889)
		(layer "In6.Cu")
		(net "UPI_CPU0_CPU1_P2P2_DP<14>")
	)
	(segment
		(start 69.241416 -355.549962)
		(end 69.100446 -355.209348)
		(width 0.14732)
		(layer "In6.Cu")
		(net "UPI_CPU0_CPU1_P2P2_DP<14>")
	)
	(segment
		(start 102.15626 -278.017224)
		(end 102.16515 -278.012144)
		(width 0.0889)
		(layer "In6.Cu")
		(net "UPI_CPU0_CPU1_P2P2_DP<14>")
	)
	(segment
		(start 99.815396 -285.336996)
		(end 99.81819 -285.335472)
		(width 0.0889)
		(layer "In6.Cu")
		(net "UPI_CPU0_CPU1_P2P2_DP<14>")
	)
	(segment
		(start 69.01307 -328.399394)
		(end 69.567552 -326.396096)
		(width 0.14732)
		(layer "In6.Cu")
		(net "UPI_CPU0_CPU1_P2P2_DP<14>")
	)
	(segment
		(start 69.163184 -355.738938)
		(end 69.241416 -355.549962)
		(width 0.14732)
		(layer "In6.Cu")
		(net "UPI_CPU0_CPU1_P2P2_DP<14>")
	)
	(segment
		(start 308.114446 -325.958962)
		(end 307.4797 -326.865742)
		(width 0.14732)
		(layer "In6.Cu")
		(net "UPI_CPU0_CPU1_P2P2_DP<14>")
	)
	(segment
		(start 97.320608 -296.020998)
		(end 97.465388 -295.876218)
		(width 0.14732)
		(layer "In6.Cu")
		(net "UPI_CPU0_CPU1_P2P2_DP<14>")
	)
	(segment
		(start 98.688398 -289.078416)
		(end 98.688398 -288.917126)
		(width 0.0889)
		(layer "In6.Cu")
		(net "UPI_CPU0_CPU1_P2P2_DP<14>")
	)
	(segment
		(start 69.88683 -357.105204)
		(end 69.697346 -357.026972)
		(width 0.14732)
		(layer "In6.Cu")
		(net "UPI_CPU0_CPU1_P2P2_DP<14>")
	)
	(segment
		(start 341.269066 -288.087562)
		(end 341.269066 -288.103056)
		(width 0.0889)
		(layer "In6.Cu")
		(net "UPI_CPU0_CPU1_P2P2_DP<14>")
	)
	(segment
		(start 267.895832 -363.511338)
		(end 268.040612 -363.656118)
		(width 0.14732)
		(layer "In6.Cu")
		(net "UPI_CPU0_CPU1_P2P2_DP<14>")
	)
	(segment
		(start 97.320608 -296.980864)
		(end 97.320608 -296.020998)
		(width 0.14732)
		(layer "In6.Cu")
		(net "UPI_CPU0_CPU1_P2P2_DP<14>")
	)
	(segment
		(start 336.14741 -299.33265)
		(end 336.2452 -299.515784)
		(width 0.14732)
		(layer "In6.Cu")
		(net "UPI_CPU0_CPU1_P2P2_DP<14>")
	)
	(segment
		(start 99.806506 -285.342076)
		(end 99.813872 -285.337758)
		(width 0.0889)
		(layer "In6.Cu")
		(net "UPI_CPU0_CPU1_P2P2_DP<14>")
	)
	(segment
		(start 100.746306 -281.097228)
		(end 100.746306 -281.097482)
		(width 0.0889)
		(layer "In6.Cu")
		(net "UPI_CPU0_CPU1_P2P2_DP<14>")
	)
	(segment
		(start 336.2452 -299.515784)
		(end 336.139282 -299.865034)
		(width 0.14732)
		(layer "In6.Cu")
		(net "UPI_CPU0_CPU1_P2P2_DP<14>")
	)
	(segment
		(start 267.895832 -364.169198)
		(end 267.895832 -364.537498)
		(width 0.14732)
		(layer "In6.Cu")
		(net "UPI_CPU0_CPU1_P2P2_DP<14>")
	)
	(segment
		(start 335.331562 -299.085)
		(end 336.14741 -299.33265)
		(width 0.14732)
		(layer "In6.Cu")
		(net "UPI_CPU0_CPU1_P2P2_DP<14>")
	)
	(segment
		(start 95.957898 -300.271942)
		(end 97.320608 -296.980864)
		(width 0.14732)
		(layer "In6.Cu")
		(net "UPI_CPU0_CPU1_P2P2_DP<14>")
	)
	(segment
		(start 341.56015 -287.608518)
		(end 341.55126 -287.613598)
		(width 0.0889)
		(layer "In6.Cu")
		(net "UPI_CPU0_CPU1_P2P2_DP<14>")
	)
	(segment
		(start 100.761292 -281.106118)
		(end 100.755958 -281.10307)
		(width 0.0889)
		(layer "In6.Cu")
		(net "UPI_CPU0_CPU1_P2P2_DP<14>")
	)
	(segment
		(start 310.76519 -324.25894)
		(end 310.271922 -324.605904)
		(width 0.14732)
		(layer "In6.Cu")
		(net "UPI_CPU0_CPU1_P2P2_DP<14>")
	)
	(segment
		(start 69.634608 -356.49789)
		(end 69.493638 -356.157276)
		(width 0.14732)
		(layer "In6.Cu")
		(net "UPI_CPU0_CPU1_P2P2_DP<14>")
	)
	(segment
		(start 97.465388 -295.507918)
		(end 97.320608 -295.363138)
		(width 0.14732)
		(layer "In6.Cu")
		(net "UPI_CPU0_CPU1_P2P2_DP<14>")
	)
	(segment
		(start 338.285328 -293.32682)
		(end 338.284312 -293.32682)
		(width 0.14732)
		(layer "In6.Cu")
		(net "UPI_CPU0_CPU1_P2P2_DP<14>")
	)
	(segment
		(start 97.320608 -294.336978)
		(end 97.320608 -293.623492)
		(width 0.14732)
		(layer "In6.Cu")
		(net "UPI_CPU0_CPU1_P2P2_DP<14>")
	)
	(segment
		(start 99.821746 -286.961072)
		(end 99.821492 -286.961326)
		(width 0.0889)
		(layer "In6.Cu")
		(net "UPI_CPU0_CPU1_P2P2_DP<14>")
	)
	(segment
		(start 99.815396 -285.985712)
		(end 99.806506 -285.980632)
		(width 0.0889)
		(layer "In6.Cu")
		(net "UPI_CPU0_CPU1_P2P2_DP<14>")
	)
	(segment
		(start 338.284312 -293.32682)
		(end 336.958432 -294.6527)
		(width 0.14732)
		(layer "In6.Cu")
		(net "UPI_CPU0_CPU1_P2P2_DP<14>")
	)
	(segment
		(start 306.401216 -329.539092)
		(end 306.436776 -329.740768)
		(width 0.14732)
		(layer "In6.Cu")
		(net "UPI_CPU0_CPU1_P2P2_DP<14>")
	)
	(segment
		(start 263.167114 -371.73535)
		(end 212.603842 -376.210322)
		(width 0.14732)
		(layer "In6.Cu")
		(net "UPI_CPU0_CPU1_P2P2_DP<14>")
	)
	(segment
		(start 100.755958 -281.10307)
		(end 100.754434 -281.102054)
		(width 0.0889)
		(layer "In6.Cu")
		(net "UPI_CPU0_CPU1_P2P2_DP<14>")
	)
	(segment
		(start 99.158298 -288.121598)
		(end 99.158298 -288.103056)
		(width 0.0889)
		(layer "In6.Cu")
		(net "UPI_CPU0_CPU1_P2P2_DP<14>")
	)
	(segment
		(start 198.54037 -374.037098)
		(end 198.54037 -374.036844)
		(width 0.14732)
		(layer "In6.Cu")
		(net "UPI_CPU0_CPU1_P2P2_DP<14>")
	)
	(segment
		(start 97.320608 -293.623492)
		(end 97.465388 -293.478712)
		(width 0.14732)
		(layer "In6.Cu")
		(net "UPI_CPU0_CPU1_P2P2_DP<14>")
	)
	(segment
		(start 339.178138 -292.492938)
		(end 339.11921 -292.492938)
		(width 0.0889)
		(layer "In6.Cu")
		(net "UPI_CPU0_CPU1_P2P2_DP<14>")
	)
	(segment
		(start 306.814474 -329.201526)
		(end 306.612544 -329.237086)
		(width 0.14732)
		(layer "In6.Cu")
		(net "UPI_CPU0_CPU1_P2P2_DP<14>")
	)
	(segment
		(start 334.756252 -299.920406)
		(end 334.053942 -302.234346)
		(width 0.14732)
		(layer "In6.Cu")
		(net "UPI_CPU0_CPU1_P2P2_DP<14>")
	)
	(segment
		(start 69.567552 -326.396096)
		(end 71.454264 -322.406264)
		(width 0.14732)
		(layer "In6.Cu")
		(net "UPI_CPU0_CPU1_P2P2_DP<14>")
	)
	(segment
		(start 103.60533 -277.251414)
		(end 103.761794 -277.522432)
		(width 0.0889)
		(layer "In6.Cu")
		(net "UPI_CPU0_CPU1_P2P2_DP<14>")
	)
	(segment
		(start 99.15779 -289.610292)
		(end 99.158044 -289.610038)
		(width 0.0889)
		(layer "In6.Cu")
		(net "UPI_CPU0_CPU1_P2P2_DP<14>")
	)
	(segment
		(start 307.4797 -326.865742)
		(end 307.152802 -328.718418)
		(width 0.14732)
		(layer "In6.Cu")
		(net "UPI_CPU0_CPU1_P2P2_DP<14>")
	)
	(segment
		(start 99.199954 -290.717986)
		(end 99.199954 -290.282122)
		(width 0.14732)
		(layer "In6.Cu")
		(net "UPI_CPU0_CPU1_P2P2_DP<14>")
	)
	(segment
		(start 342.96096 -282.895548)
		(end 342.96985 -282.900628)
		(width 0.0889)
		(layer "In6.Cu")
		(net "UPI_CPU0_CPU1_P2P2_DP<14>")
	)
	(segment
		(start 268.040612 -364.682278)
		(end 268.040612 -365.050578)
		(width 0.14732)
		(layer "In6.Cu")
		(net "UPI_CPU0_CPU1_P2P2_DP<14>")
	)
	(segment
		(start 342.96985 -283.539184)
		(end 342.96096 -283.544264)
		(width 0.0889)
		(layer "In6.Cu")
		(net "UPI_CPU0_CPU1_P2P2_DP<14>")
	)
	(segment
		(start 97.465388 -294.850058)
		(end 97.465388 -294.481758)
		(width 0.14732)
		(layer "In6.Cu")
		(net "UPI_CPU0_CPU1_P2P2_DP<14>")
	)
	(segment
		(start 69.949568 -357.634794)
		(end 70.0278 -357.445818)
		(width 0.14732)
		(layer "In6.Cu")
		(net "UPI_CPU0_CPU1_P2P2_DP<14>")
	)
	(segment
		(start 268.040612 -365.050578)
		(end 267.895832 -365.195358)
		(width 0.14732)
		(layer "In6.Cu")
		(net "UPI_CPU0_CPU1_P2P2_DP<14>")
	)
	(segment
		(start 69.100446 -355.209348)
		(end 68.910962 -355.131116)
		(width 0.14732)
		(layer "In6.Cu")
		(net "UPI_CPU0_CPU1_P2P2_DP<14>")
	)
	(segment
		(start 198.496174 -374.03024)
		(end 159.794956 -380.76251)
		(width 0.14732)
		(layer "In6.Cu")
		(net "UPI_CPU0_CPU1_P2P2_DP<14>")
	)
	(segment
		(start 212.603842 -376.210322)
		(end 198.54037 -374.037098)
		(width 0.14732)
		(layer "In6.Cu")
		(net "UPI_CPU0_CPU1_P2P2_DP<14>")
	)
	(segment
		(start 267.895832 -364.537498)
		(end 268.040612 -364.682278)
		(width 0.14732)
		(layer "In6.Cu")
		(net "UPI_CPU0_CPU1_P2P2_DP<14>")
	)
	(segment
		(start 103.51643 -277.227792)
		(end 103.60533 -277.251414)
		(width 0.0889)
		(layer "In6.Cu")
		(net "UPI_CPU0_CPU1_P2P2_DP<14>")
	)
	(segment
		(start 339.103716 -292.508432)
		(end 338.285328 -293.32682)
		(width 0.14732)
		(layer "In6.Cu")
		(net "UPI_CPU0_CPU1_P2P2_DP<14>")
	)
	(segment
		(start 278.456644 -334.052164)
		(end 268.040612 -344.468196)
		(width 0.14732)
		(layer "In6.Cu")
		(net "UPI_CPU0_CPU1_P2P2_DP<14>")
	)
	(segment
		(start 342.021414 -285.171896)
		(end 342.015318 -285.175452)
		(width 0.0889)
		(layer "In6.Cu")
		(net "UPI_CPU0_CPU1_P2P2_DP<14>")
	)
	(segment
		(start 68.707254 -354.26142)
		(end 68.51777 -354.183188)
		(width 0.14732)
		(layer "In6.Cu")
		(net "UPI_CPU0_CPU1_P2P2_DP<14>")
	)
	(segment
		(start 342.208612 -286.466788)
		(end 342.208612 -286.48406)
		(width 0.0889)
		(layer "In6.Cu")
		(net "UPI_CPU0_CPU1_P2P2_DP<14>")
	)
	(segment
		(start 99.199954 -290.282122)
		(end 99.199954 -290.260024)
		(width 0.0889)
		(layer "In6.Cu")
		(net "UPI_CPU0_CPU1_P2P2_DP<14>")
	)
	(segment
		(start 100.746306 -283.714444)
		(end 100.755196 -283.709364)
		(width 0.0889)
		(layer "In6.Cu")
		(net "UPI_CPU0_CPU1_P2P2_DP<14>")
	)
	(segment
		(start 97.320608 -295.363138)
		(end 97.320608 -294.994838)
		(width 0.14732)
		(layer "In6.Cu")
		(net "UPI_CPU0_CPU1_P2P2_DP<14>")
	)
	(segment
		(start 335.140046 -299.715174)
		(end 334.756252 -299.920406)
		(width 0.14732)
		(layer "In6.Cu")
		(net "UPI_CPU0_CPU1_P2P2_DP<14>")
	)
	(segment
		(start 72.209914 -363.086904)
		(end 69.949568 -357.634794)
		(width 0.14732)
		(layer "In6.Cu")
		(net "UPI_CPU0_CPU1_P2P2_DP<14>")
	)
	(segment
		(start 69.697346 -357.026972)
		(end 69.556376 -356.686866)
		(width 0.14732)
		(layer "In6.Cu")
		(net "UPI_CPU0_CPU1_P2P2_DP<14>")
	)
	(segment
		(start 159.794956 -380.76251)
		(end 125.60935 -380.76251)
		(width 0.14732)
		(layer "In6.Cu")
		(net "UPI_CPU0_CPU1_P2P2_DP<14>")
	)
	(segment
		(start 99.627944 -287.304734)
		(end 99.627944 -287.28924)
		(width 0.0889)
		(layer "In6.Cu")
		(net "UPI_CPU0_CPU1_P2P2_DP<14>")
	)
	(segment
		(start 342.020652 -286.80029)
		(end 342.015318 -286.803338)
		(width 0.0889)
		(layer "In6.Cu")
		(net "UPI_CPU0_CPU1_P2P2_DP<14>")
	)
	(arc
		(start 341.269066 -288.103056)
		(mid 341.221387 -288.285956)
		(end 341.090504 -288.422334)
		(width 0.0889)
		(layer "In6.Cu")
		(net "UPI_CPU0_CPU1_P2P2_DP<14>")
	)
	(arc
		(start 342.491314 -282.081478)
		(mid 342.626247 -282.214832)
		(end 342.678512 -282.3972)
		(width 0.0889)
		(layer "In6.Cu")
		(net "UPI_CPU0_CPU1_P2P2_DP<14>")
	)
	(arc
		(start 103.496618 -277.23592)
		(mid 103.506562 -277.231949)
		(end 103.51643 -277.227792)
		(width 0.0889)
		(layer "In6.Cu")
		(net "UPI_CPU0_CPU1_P2P2_DP<14>")
	)
	(arc
		(start 102.447598 -277.513796)
		(mid 102.499868 -277.331431)
		(end 102.634796 -277.198074)
		(width 0.0889)
		(layer "In6.Cu")
		(net "UPI_CPU0_CPU1_P2P2_DP<14>")
	)
	(arc
		(start 101.507798 -279.141682)
		(mid 101.560068 -278.959317)
		(end 101.694996 -278.82596)
		(width 0.0889)
		(layer "In6.Cu")
		(net "UPI_CPU0_CPU1_P2P2_DP<14>")
	)
	(arc
		(start 342.116918 -282.081478)
		(mid 342.304116 -282.031335)
		(end 342.491314 -282.081478)
		(width 0.0889)
		(layer "In6.Cu")
		(net "UPI_CPU0_CPU1_P2P2_DP<14>")
	)
	(arc
		(start 342.678512 -282.424378)
		(mid 342.758674 -282.696567)
		(end 342.96096 -282.895548)
		(width 0.0889)
		(layer "In6.Cu")
		(net "UPI_CPU0_CPU1_P2P2_DP<14>")
	)
	(arc
		(start 101.22535 -279.639776)
		(mid 101.429685 -279.437171)
		(end 101.507798 -279.160224)
		(width 0.0889)
		(layer "In6.Cu")
		(net "UPI_CPU0_CPU1_P2P2_DP<14>")
	)
	(arc
		(start 342.015318 -285.175452)
		(mid 341.812731 -285.381803)
		(end 341.738712 -285.661354)
		(width 0.0889)
		(layer "In6.Cu")
		(net "UPI_CPU0_CPU1_P2P2_DP<14>")
	)
	(arc
		(start 342.96985 -282.900628)
		(mid 343.097743 -283.03169)
		(end 343.148158 -283.207714)
		(width 0.0889)
		(layer "In6.Cu")
		(net "UPI_CPU0_CPU1_P2P2_DP<14>")
	)
	(arc
		(start 100.567744 -284.033722)
		(mid 100.615423 -283.850822)
		(end 100.746306 -283.714444)
		(width 0.0889)
		(layer "In6.Cu")
		(net "UPI_CPU0_CPU1_P2P2_DP<14>")
	)
	(arc
		(start 342.96096 -283.544264)
		(mid 342.756625 -283.746869)
		(end 342.678512 -284.023816)
		(width 0.0889)
		(layer "In6.Cu")
		(net "UPI_CPU0_CPU1_P2P2_DP<14>")
	)
	(arc
		(start 341.084662 -289.446462)
		(mid 341.193809 -289.53039)
		(end 341.268812 -289.645852)
		(width 0.0889)
		(layer "In6.Cu")
		(net "UPI_CPU0_CPU1_P2P2_DP<14>")
	)
	(arc
		(start 101.707188 -278.818848)
		(mid 101.905416 -278.613)
		(end 101.977698 -278.336502)
		(width 0.0889)
		(layer "In6.Cu")
		(net "UPI_CPU0_CPU1_P2P2_DP<14>")
	)
	(arc
		(start 102.634796 -277.198074)
		(mid 102.821994 -277.147931)
		(end 103.009192 -277.198074)
		(width 0.0889)
		(layer "In6.Cu")
		(net "UPI_CPU0_CPU1_P2P2_DP<14>")
	)
	(arc
		(start 101.22535 -282.895548)
		(mid 101.426632 -282.698061)
		(end 101.507544 -282.427934)
		(width 0.0889)
		(layer "In6.Cu")
		(net "UPI_CPU0_CPU1_P2P2_DP<14>")
	)
	(arc
		(start 98.872548 -289.277806)
		(mid 98.763401 -289.193878)
		(end 98.688398 -289.078416)
		(width 0.0889)
		(layer "In6.Cu")
		(net "UPI_CPU0_CPU1_P2P2_DP<14>")
	)
	(arc
		(start 342.208612 -286.48406)
		(mid 342.156342 -286.666425)
		(end 342.021414 -286.799782)
		(width 0.0889)
		(layer "In6.Cu")
		(net "UPI_CPU0_CPU1_P2P2_DP<14>")
	)
	(arc
		(start 102.16515 -278.012144)
		(mid 102.367436 -277.813163)
		(end 102.447598 -277.540974)
		(width 0.0889)
		(layer "In6.Cu")
		(net "UPI_CPU0_CPU1_P2P2_DP<14>")
	)
	(arc
		(start 342.678512 -284.033722)
		(mid 342.630833 -284.216622)
		(end 342.49995 -284.353)
		(width 0.0889)
		(layer "In6.Cu")
		(net "UPI_CPU0_CPU1_P2P2_DP<14>")
	)
	(arc
		(start 100.746306 -281.097482)
		(mid 100.567709 -280.778204)
		(end 100.746306 -280.458926)
		(width 0.0889)
		(layer "In6.Cu")
		(net "UPI_CPU0_CPU1_P2P2_DP<14>")
	)
	(arc
		(start 341.60968 -282.111196)
		(mid 341.619547 -282.115355)
		(end 341.629492 -282.119324)
		(width 0.0889)
		(layer "In6.Cu")
		(net "UPI_CPU0_CPU1_P2P2_DP<14>")
	)
	(arc
		(start 340.799166 -289.114738)
		(mid 340.910504 -289.307638)
		(end 341.084662 -289.446462)
		(width 0.0889)
		(layer "In6.Cu")
		(net "UPI_CPU0_CPU1_P2P2_DP<14>")
	)
	(arc
		(start 341.629492 -282.119324)
		(mid 341.877503 -282.155789)
		(end 342.116918 -282.081478)
		(width 0.0889)
		(layer "In6.Cu")
		(net "UPI_CPU0_CPU1_P2P2_DP<14>")
	)
	(arc
		(start 99.158298 -288.103056)
		(mid 99.205977 -287.920156)
		(end 99.33686 -287.783778)
		(width 0.0889)
		(layer "In6.Cu")
		(net "UPI_CPU0_CPU1_P2P2_DP<14>")
	)
	(arc
		(start 101.21646 -281.911298)
		(mid 101.085546 -281.774938)
		(end 101.037898 -281.59202)
		(width 0.0889)
		(layer "In6.Cu")
		(net "UPI_CPU0_CPU1_P2P2_DP<14>")
	)
	(arc
		(start 99.34575 -287.778698)
		(mid 99.548573 -287.578467)
		(end 99.627944 -287.304734)
		(width 0.0889)
		(layer "In6.Cu")
		(net "UPI_CPU0_CPU1_P2P2_DP<14>")
	)
	(arc
		(start 341.738712 -287.28924)
		(mid 341.691033 -287.47214)
		(end 341.56015 -287.608518)
		(width 0.0889)
		(layer "In6.Cu")
		(net "UPI_CPU0_CPU1_P2P2_DP<14>")
	)
	(arc
		(start 342.021414 -286.151066)
		(mid 342.156347 -286.28442)
		(end 342.208612 -286.466788)
		(width 0.0889)
		(layer "In6.Cu")
		(net "UPI_CPU0_CPU1_P2P2_DP<14>")
	)
	(arc
		(start 99.821492 -285.33344)
		(mid 100.024079 -285.127089)
		(end 100.098098 -284.847538)
		(width 0.0889)
		(layer "In6.Cu")
		(net "UPI_CPU0_CPU1_P2P2_DP<14>")
	)
	(arc
		(start 342.208866 -284.847538)
		(mid 342.161187 -285.030438)
		(end 342.030304 -285.166816)
		(width 0.0889)
		(layer "In6.Cu")
		(net "UPI_CPU0_CPU1_P2P2_DP<14>")
	)
	(arc
		(start 100.098098 -284.847538)
		(mid 100.145777 -284.664638)
		(end 100.27666 -284.52826)
		(width 0.0889)
		(layer "In6.Cu")
		(net "UPI_CPU0_CPU1_P2P2_DP<14>")
	)
	(arc
		(start 101.037898 -281.59202)
		(mid 100.963907 -281.312454)
		(end 100.761292 -281.106118)
		(width 0.0889)
		(layer "In6.Cu")
		(net "UPI_CPU0_CPU1_P2P2_DP<14>")
	)
	(arc
		(start 343.148412 -283.22651)
		(mid 343.099159 -283.40571)
		(end 342.96985 -283.539184)
		(width 0.0889)
		(layer "In6.Cu")
		(net "UPI_CPU0_CPU1_P2P2_DP<14>")
	)
	(arc
		(start 101.037898 -279.964134)
		(mid 101.085577 -279.781234)
		(end 101.21646 -279.644856)
		(width 0.0889)
		(layer "In6.Cu")
		(net "UPI_CPU0_CPU1_P2P2_DP<14>")
	)
	(arc
		(start 343.148158 -283.207714)
		(mid 343.148403 -283.21711)
		(end 343.148412 -283.22651)
		(width 0.0889)
		(layer "In6.Cu")
		(net "UPI_CPU0_CPU1_P2P2_DP<14>")
	)
	(arc
		(start 342.015318 -286.803338)
		(mid 341.812731 -287.009689)
		(end 341.738712 -287.28924)
		(width 0.0889)
		(layer "In6.Cu")
		(net "UPI_CPU0_CPU1_P2P2_DP<14>")
	)
	(arc
		(start 98.688398 -288.917126)
		(mid 98.736077 -288.734226)
		(end 98.86696 -288.597848)
		(width 0.0889)
		(layer "In6.Cu")
		(net "UPI_CPU0_CPU1_P2P2_DP<14>")
	)
	(arc
		(start 341.55126 -287.613598)
		(mid 341.348437 -287.813829)
		(end 341.269066 -288.087562)
		(width 0.0889)
		(layer "In6.Cu")
		(net "UPI_CPU0_CPU1_P2P2_DP<14>")
	)
	(arc
		(start 100.755196 -280.453846)
		(mid 100.958677 -280.253042)
		(end 101.037898 -279.978358)
		(width 0.0889)
		(layer "In6.Cu")
		(net "UPI_CPU0_CPU1_P2P2_DP<14>")
	)
	(arc
		(start 99.821492 -286.961326)
		(mid 100.024079 -286.754975)
		(end 100.098098 -286.475424)
		(width 0.0889)
		(layer "In6.Cu")
		(net "UPI_CPU0_CPU1_P2P2_DP<14>")
	)
	(arc
		(start 99.158044 -289.60953)
		(mid 99.046706 -289.41663)
		(end 98.872548 -289.277806)
		(width 0.0889)
		(layer "In6.Cu")
		(net "UPI_CPU0_CPU1_P2P2_DP<14>")
	)
	(arc
		(start 101.977698 -278.336502)
		(mid 102.025377 -278.153602)
		(end 102.15626 -278.017224)
		(width 0.0889)
		(layer "In6.Cu")
		(net "UPI_CPU0_CPU1_P2P2_DP<14>")
	)
	(arc
		(start 98.87585 -288.592768)
		(mid 99.078136 -288.393787)
		(end 99.158298 -288.121598)
		(width 0.0889)
		(layer "In6.Cu")
		(net "UPI_CPU0_CPU1_P2P2_DP<14>")
	)
	(arc
		(start 341.081614 -288.427414)
		(mid 340.879328 -288.626395)
		(end 340.799166 -288.898584)
		(width 0.0889)
		(layer "In6.Cu")
		(net "UPI_CPU0_CPU1_P2P2_DP<14>")
	)
	(arc
		(start 342.49106 -284.35808)
		(mid 342.288237 -284.558311)
		(end 342.208866 -284.832044)
		(width 0.0889)
		(layer "In6.Cu")
		(net "UPI_CPU0_CPU1_P2P2_DP<14>")
	)
	(arc
		(start 341.738712 -285.675578)
		(mid 341.817931 -285.950263)
		(end 342.021414 -286.151066)
		(width 0.0889)
		(layer "In6.Cu")
		(net "UPI_CPU0_CPU1_P2P2_DP<14>")
	)
	(arc
		(start 100.767388 -283.702252)
		(mid 100.965616 -283.496404)
		(end 101.037898 -283.219906)
		(width 0.0889)
		(layer "In6.Cu")
		(net "UPI_CPU0_CPU1_P2P2_DP<14>")
	)
	(arc
		(start 100.098098 -286.4612)
		(mid 100.018879 -286.186515)
		(end 99.815396 -285.985712)
		(width 0.0889)
		(layer "In6.Cu")
		(net "UPI_CPU0_CPU1_P2P2_DP<14>")
	)
	(arc
		(start 101.037898 -283.219906)
		(mid 101.085577 -283.037006)
		(end 101.21646 -282.900628)
		(width 0.0889)
		(layer "In6.Cu")
		(net "UPI_CPU0_CPU1_P2P2_DP<14>")
	)
	(arc
		(start 100.28555 -284.52318)
		(mid 100.488373 -284.322949)
		(end 100.567744 -284.049216)
		(width 0.0889)
		(layer "In6.Cu")
		(net "UPI_CPU0_CPU1_P2P2_DP<14>")
	)
	(arc
		(start 99.627944 -287.28924)
		(mid 99.675623 -287.10634)
		(end 99.806506 -286.969962)
		(width 0.0889)
		(layer "In6.Cu")
		(net "UPI_CPU0_CPU1_P2P2_DP<14>")
	)
	(arc
		(start 101.507544 -282.390342)
		(mid 101.428174 -282.116608)
		(end 101.22535 -281.916378)
		(width 0.0889)
		(layer "In6.Cu")
		(net "UPI_CPU0_CPU1_P2P2_DP<14>")
	)
	(arc
		(start 103.009192 -277.198074)
		(mid 103.248605 -277.272406)
		(end 103.496618 -277.23592)
		(width 0.0889)
		(layer "In6.Cu")
		(net "UPI_CPU0_CPU1_P2P2_DP<14>")
	)
	(arc
		(start 99.806506 -285.980632)
		(mid 99.627788 -285.661354)
		(end 99.806506 -285.342076)
		(width 0.0889)
		(layer "In6.Cu")
		(net "UPI_CPU0_CPU1_P2P2_DP<14>")
	)
	(segment
		(start 103.291894 -274.54479)
		(end 103.291894 -275.080476)
		(width 0.13208)
		(layer "F.Cu")
		(net "UPI_CPU0_CPU1_P2P2_DP<13>")
	)
	(segment
		(start 351.702116 -278.614378)
		(end 351.702116 -279.150064)
		(width 0.13208)
		(layer "F.Cu")
		(net "UPI_CPU0_CPU1_P2P2_DP<13>")
	)
	(segment
		(start 351.702116 -279.150064)
		(end 351.701862 -279.150318)
		(width 0.13208)
		(layer "F.Cu")
		(net "UPI_CPU0_CPU1_P2P2_DP<13>")
	)
	(segment
		(start 103.291894 -275.080476)
		(end 103.292148 -275.08073)
		(width 0.13208)
		(layer "F.Cu")
		(net "UPI_CPU0_CPU1_P2P2_DP<13>")
	)
	(segment
		(start 99.33686 -284.52826)
		(end 99.34575 -284.52318)
		(width 0.0889)
		(layer "In6.Cu")
		(net "UPI_CPU0_CPU1_P2P2_DP<13>")
	)
	(segment
		(start 346.720414 -278.66086)
		(end 346.714318 -278.664416)
		(width 0.0889)
		(layer "In6.Cu")
		(net "UPI_CPU0_CPU1_P2P2_DP<13>")
	)
	(segment
		(start 306.28463 -331.703426)
		(end 305.71059 -332.27772)
		(width 0.14732)
		(layer "In6.Cu")
		(net "UPI_CPU0_CPU1_P2P2_DP<13>")
	)
	(segment
		(start 344.37955 -284.353)
		(end 344.37066 -284.35808)
		(width 0.0889)
		(layer "In6.Cu")
		(net "UPI_CPU0_CPU1_P2P2_DP<13>")
	)
	(segment
		(start 102.913942 -275.146262)
		(end 102.979474 -275.08073)
		(width 0.0889)
		(layer "In6.Cu")
		(net "UPI_CPU0_CPU1_P2P2_DP<13>")
	)
	(segment
		(start 99.821746 -283.705554)
		(end 99.821492 -283.705808)
		(width 0.0889)
		(layer "In6.Cu")
		(net "UPI_CPU0_CPU1_P2P2_DP<13>")
	)
	(segment
		(start 74.348848 -366.411002)
		(end 74.144124 -366.411002)
		(width 0.14732)
		(layer "In6.Cu")
		(net "UPI_CPU0_CPU1_P2P2_DP<13>")
	)
	(segment
		(start 98.875596 -285.336996)
		(end 98.881692 -285.33344)
		(width 0.0889)
		(layer "In6.Cu")
		(net "UPI_CPU0_CPU1_P2P2_DP<13>")
	)
	(segment
		(start 350.494346 -278.652224)
		(end 350.479614 -278.66086)
		(width 0.0889)
		(layer "In6.Cu")
		(net "UPI_CPU0_CPU1_P2P2_DP<13>")
	)
	(segment
		(start 95.233236 -299.851826)
		(end 95.232982 -299.851572)
		(width 0.14732)
		(layer "In6.Cu")
		(net "UPI_CPU0_CPU1_P2P2_DP<13>")
	)
	(segment
		(start 95.232982 -299.851572)
		(end 96.380808 -297.080686)
		(width 0.14732)
		(layer "In6.Cu")
		(net "UPI_CPU0_CPU1_P2P2_DP<13>")
	)
	(segment
		(start 268.993112 -367.656618)
		(end 264.009124 -372.640606)
		(width 0.14732)
		(layer "In6.Cu")
		(net "UPI_CPU0_CPU1_P2P2_DP<13>")
	)
	(segment
		(start 349.549974 -278.654764)
		(end 349.53956 -278.66086)
		(width 0.0889)
		(layer "In6.Cu")
		(net "UPI_CPU0_CPU1_P2P2_DP<13>")
	)
	(segment
		(start 343.900252 -286.80029)
		(end 343.894918 -286.803338)
		(width 0.0889)
		(layer "In6.Cu")
		(net "UPI_CPU0_CPU1_P2P2_DP<13>")
	)
	(segment
		(start 98.875596 -286.964882)
		(end 98.879406 -286.962596)
		(width 0.0889)
		(layer "In6.Cu")
		(net "UPI_CPU0_CPU1_P2P2_DP<13>")
	)
	(segment
		(start 96.380808 -292.360604)
		(end 97.252028 -291.489384)
		(width 0.14732)
		(layer "In6.Cu")
		(net "UPI_CPU0_CPU1_P2P2_DP<13>")
	)
	(segment
		(start 73.418446 -365.685324)
		(end 73.158096 -365.424974)
		(width 0.14732)
		(layer "In6.Cu")
		(net "UPI_CPU0_CPU1_P2P2_DP<13>")
	)
	(segment
		(start 68.855336 -325.863712)
		(end 70.696328 -321.971416)
		(width 0.14732)
		(layer "In6.Cu")
		(net "UPI_CPU0_CPU1_P2P2_DP<13>")
	)
	(segment
		(start 340.586568 -298.887388)
		(end 339.8012 -299.672756)
		(width 0.14732)
		(layer "In6.Cu")
		(net "UPI_CPU0_CPU1_P2P2_DP<13>")
	)
	(segment
		(start 125.557534 -381.59563)
		(end 97.452688 -377.42622)
		(width 0.14732)
		(layer "In6.Cu")
		(net "UPI_CPU0_CPU1_P2P2_DP<13>")
	)
	(segment
		(start 98.21799 -290.463478)
		(end 98.21799 -289.610292)
		(width 0.0889)
		(layer "In6.Cu")
		(net "UPI_CPU0_CPU1_P2P2_DP<13>")
	)
	(segment
		(start 76.467716 -368.734594)
		(end 74.609452 -366.87633)
		(width 0.14732)
		(layer "In6.Cu")
		(net "UPI_CPU0_CPU1_P2P2_DP<13>")
	)
	(segment
		(start 97.748598 -289.078416)
		(end 97.748598 -288.917126)
		(width 0.0889)
		(layer "In6.Cu")
		(net "UPI_CPU0_CPU1_P2P2_DP<13>")
	)
	(segment
		(start 101.68636 -277.203154)
		(end 101.69525 -277.198074)
		(width 0.0889)
		(layer "In6.Cu")
		(net "UPI_CPU0_CPU1_P2P2_DP<13>")
	)
	(segment
		(start 99.806506 -280.458926)
		(end 99.815396 -280.453846)
		(width 0.0889)
		(layer "In6.Cu")
		(net "UPI_CPU0_CPU1_P2P2_DP<13>")
	)
	(segment
		(start 212.927692 -377.111768)
		(end 199.456294 -375.661428)
		(width 0.14732)
		(layer "In6.Cu")
		(net "UPI_CPU0_CPU1_P2P2_DP<13>")
	)
	(segment
		(start 340.748874 -298.49572)
		(end 340.586568 -298.887388)
		(width 0.14732)
		(layer "In6.Cu")
		(net "UPI_CPU0_CPU1_P2P2_DP<13>")
	)
	(segment
		(start 97.267522 -291.47389)
		(end 97.267522 -291.413946)
		(width 0.0889)
		(layer "In6.Cu")
		(net "UPI_CPU0_CPU1_P2P2_DP<13>")
	)
	(segment
		(start 102.625906 -275.575522)
		(end 102.634796 -275.570442)
		(width 0.0889)
		(layer "In6.Cu")
		(net "UPI_CPU0_CPU1_P2P2_DP<13>")
	)
	(segment
		(start 313.216544 -324.64375)
		(end 312.975752 -324.812406)
		(width 0.14732)
		(layer "In6.Cu")
		(net "UPI_CPU0_CPU1_P2P2_DP<13>")
	)
	(segment
		(start 70.696328 -321.971416)
		(end 78.850998 -313.816492)
		(width 0.14732)
		(layer "In6.Cu")
		(net "UPI_CPU0_CPU1_P2P2_DP<13>")
	)
	(segment
		(start 100.098098 -283.219906)
		(end 100.098098 -283.21127)
		(width 0.0889)
		(layer "In6.Cu")
		(net "UPI_CPU0_CPU1_P2P2_DP<13>")
	)
	(segment
		(start 98.39706 -287.783778)
		(end 98.40595 -287.778698)
		(width 0.0889)
		(layer "In6.Cu")
		(net "UPI_CPU0_CPU1_P2P2_DP<13>")
	)
	(segment
		(start 336.369914 -301.093378)
		(end 314.143136 -323.320156)
		(width 0.14732)
		(layer "In6.Cu")
		(net "UPI_CPU0_CPU1_P2P2_DP<13>")
	)
	(segment
		(start 346.437712 -279.150318)
		(end 346.437712 -279.158954)
		(width 0.0889)
		(layer "In6.Cu")
		(net "UPI_CPU0_CPU1_P2P2_DP<13>")
	)
	(segment
		(start 312.174128 -324.913244)
		(end 311.822592 -325.023988)
		(width 0.14732)
		(layer "In6.Cu")
		(net "UPI_CPU0_CPU1_P2P2_DP<13>")
	)
	(segment
		(start 199.456294 -375.661428)
		(end 162.155378 -381.556006)
		(width 0.14732)
		(layer "In6.Cu")
		(net "UPI_CPU0_CPU1_P2P2_DP<13>")
	)
	(segment
		(start 67.542918 -334.815688)
		(end 68.187062 -328.278998)
		(width 0.14732)
		(layer "In6.Cu")
		(net "UPI_CPU0_CPU1_P2P2_DP<13>")
	)
	(segment
		(start 345.497912 -280.76398)
		(end 345.497912 -280.778204)
		(width 0.0889)
		(layer "In6.Cu")
		(net "UPI_CPU0_CPU1_P2P2_DP<13>")
	)
	(segment
		(start 162.155378 -381.556006)
		(end 161.701734 -381.59563)
		(width 0.14732)
		(layer "In6.Cu")
		(net "UPI_CPU0_CPU1_P2P2_DP<13>")
	)
	(segment
		(start 98.879406 -286.962596)
		(end 98.887788 -286.95777)
		(width 0.0889)
		(layer "In6.Cu")
		(net "UPI_CPU0_CPU1_P2P2_DP<13>")
	)
	(segment
		(start 98.875596 -285.985712)
		(end 98.866706 -285.980632)
		(width 0.0889)
		(layer "In6.Cu")
		(net "UPI_CPU0_CPU1_P2P2_DP<13>")
	)
	(segment
		(start 344.088212 -286.466788)
		(end 344.088212 -286.48406)
		(width 0.0889)
		(layer "In6.Cu")
		(net "UPI_CPU0_CPU1_P2P2_DP<13>")
	)
	(segment
		(start 71.640954 -363.907832)
		(end 67.542918 -354.014024)
		(width 0.14732)
		(layer "In6.Cu")
		(net "UPI_CPU0_CPU1_P2P2_DP<13>")
	)
	(segment
		(start 102.979474 -275.08073)
		(end 103.292148 -275.08073)
		(width 0.0889)
		(layer "In6.Cu")
		(net "UPI_CPU0_CPU1_P2P2_DP<13>")
	)
	(segment
		(start 341.441532 -296.72788)
		(end 341.134446 -297.731434)
		(width 0.14732)
		(layer "In6.Cu")
		(net "UPI_CPU0_CPU1_P2P2_DP<13>")
	)
	(segment
		(start 278.917654 -334.762348)
		(end 268.993112 -344.68689)
		(width 0.14732)
		(layer "In6.Cu")
		(net "UPI_CPU0_CPU1_P2P2_DP<13>")
	)
	(segment
		(start 97.452688 -377.42622)
		(end 76.467716 -368.734594)
		(width 0.14732)
		(layer "In6.Cu")
		(net "UPI_CPU0_CPU1_P2P2_DP<13>")
	)
	(segment
		(start 312.975752 -324.812406)
		(end 312.355738 -325.007732)
		(width 0.14732)
		(layer "In6.Cu")
		(net "UPI_CPU0_CPU1_P2P2_DP<13>")
	)
	(segment
		(start 99.627944 -280.793698)
		(end 99.627944 -280.778204)
		(width 0.0889)
		(layer "In6.Cu")
		(net "UPI_CPU0_CPU1_P2P2_DP<13>")
	)
	(segment
		(start 345.028012 -283.21127)
		(end 345.028012 -283.228542)
		(width 0.0889)
		(layer "In6.Cu")
		(net "UPI_CPU0_CPU1_P2P2_DP<13>")
	)
	(segment
		(start 72.366632 -364.428786)
		(end 72.106028 -364.168182)
		(width 0.14732)
		(layer "In6.Cu")
		(net "UPI_CPU0_CPU1_P2P2_DP<13>")
	)
	(segment
		(start 98.21799 -289.610292)
		(end 98.218244 -289.610038)
		(width 0.0889)
		(layer "In6.Cu")
		(net "UPI_CPU0_CPU1_P2P2_DP<13>")
	)
	(segment
		(start 311.72785 -325.205598)
		(end 311.727596 -325.205852)
		(width 0.14732)
		(layer "In6.Cu")
		(net "UPI_CPU0_CPU1_P2P2_DP<13>")
	)
	(segment
		(start 342.494362 -289.277806)
		(end 342.494616 -289.27806)
		(width 0.0889)
		(layer "In6.Cu")
		(net "UPI_CPU0_CPU1_P2P2_DP<13>")
	)
	(segment
		(start 344.840052 -283.544772)
		(end 344.834718 -283.54782)
		(width 0.0889)
		(layer "In6.Cu")
		(net "UPI_CPU0_CPU1_P2P2_DP<13>")
	)
	(segment
		(start 311.727596 -325.205852)
		(end 311.19699 -325.372984)
		(width 0.14732)
		(layer "In6.Cu")
		(net "UPI_CPU0_CPU1_P2P2_DP<13>")
	)
	(segment
		(start 309.426864 -326.076564)
		(end 308.97068 -326.532494)
		(width 0.14732)
		(layer "In6.Cu")
		(net "UPI_CPU0_CPU1_P2P2_DP<13>")
	)
	(segment
		(start 96.380808 -297.080686)
		(end 96.380808 -292.360604)
		(width 0.14732)
		(layer "In6.Cu")
		(net "UPI_CPU0_CPU1_P2P2_DP<13>")
	)
	(segment
		(start 73.158096 -365.424974)
		(end 73.158096 -365.22025)
		(width 0.14732)
		(layer "In6.Cu")
		(net "UPI_CPU0_CPU1_P2P2_DP<13>")
	)
	(segment
		(start 102.447344 -275.904706)
		(end 102.447344 -275.8948)
		(width 0.0889)
		(layer "In6.Cu")
		(net "UPI_CPU0_CPU1_P2P2_DP<13>")
	)
	(segment
		(start 345.968066 -279.954228)
		(end 345.968066 -279.964134)
		(width 0.0889)
		(layer "In6.Cu")
		(net "UPI_CPU0_CPU1_P2P2_DP<13>")
	)
	(segment
		(start 68.187062 -328.278998)
		(end 68.855336 -325.863712)
		(width 0.14732)
		(layer "In6.Cu")
		(net "UPI_CPU0_CPU1_P2P2_DP<13>")
	)
	(segment
		(start 344.840814 -283.544264)
		(end 344.840052 -283.544772)
		(width 0.0889)
		(layer "In6.Cu")
		(net "UPI_CPU0_CPU1_P2P2_DP<13>")
	)
	(segment
		(start 309.879746 -325.77405)
		(end 309.426864 -326.076564)
		(width 0.14732)
		(layer "In6.Cu")
		(net "UPI_CPU0_CPU1_P2P2_DP<13>")
	)
	(segment
		(start 98.218498 -288.121598)
		(end 98.218498 -288.103056)
		(width 0.0889)
		(layer "In6.Cu")
		(net "UPI_CPU0_CPU1_P2P2_DP<13>")
	)
	(segment
		(start 99.34575 -281.916378)
		(end 99.33686 -281.911298)
		(width 0.0889)
		(layer "In6.Cu")
		(net "UPI_CPU0_CPU1_P2P2_DP<13>")
	)
	(segment
		(start 351.389188 -279.150318)
		(end 351.323656 -279.084786)
		(width 0.0889)
		(layer "In6.Cu")
		(net "UPI_CPU0_CPU1_P2P2_DP<13>")
	)
	(segment
		(start 73.158096 -365.22025)
		(end 72.897238 -364.959392)
		(width 0.14732)
		(layer "In6.Cu")
		(net "UPI_CPU0_CPU1_P2P2_DP<13>")
	)
	(segment
		(start 343.148666 -288.087562)
		(end 343.148666 -288.103056)
		(width 0.0889)
		(layer "In6.Cu")
		(net "UPI_CPU0_CPU1_P2P2_DP<13>")
	)
	(segment
		(start 340.91118 -298.103798)
		(end 340.748874 -298.49572)
		(width 0.14732)
		(layer "In6.Cu")
		(net "UPI_CPU0_CPU1_P2P2_DP<13>")
	)
	(segment
		(start 343.618312 -285.661354)
		(end 343.618312 -285.675578)
		(width 0.0889)
		(layer "In6.Cu")
		(net "UPI_CPU0_CPU1_P2P2_DP<13>")
	)
	(segment
		(start 72.366632 -364.63351)
		(end 72.366632 -364.428786)
		(width 0.14732)
		(layer "In6.Cu")
		(net "UPI_CPU0_CPU1_P2P2_DP<13>")
	)
	(segment
		(start 98.866706 -285.342076)
		(end 98.875596 -285.336996)
		(width 0.0889)
		(layer "In6.Cu")
		(net "UPI_CPU0_CPU1_P2P2_DP<13>")
	)
	(segment
		(start 100.27666 -279.644856)
		(end 100.28555 -279.639776)
		(width 0.0889)
		(layer "In6.Cu")
		(net "UPI_CPU0_CPU1_P2P2_DP<13>")
	)
	(segment
		(start 72.897238 -364.959392)
		(end 72.692514 -364.959392)
		(width 0.14732)
		(layer "In6.Cu")
		(net "UPI_CPU0_CPU1_P2P2_DP<13>")
	)
	(segment
		(start 306.284376 -331.498702)
		(end 306.28463 -331.703426)
		(width 0.14732)
		(layer "In6.Cu")
		(net "UPI_CPU0_CPU1_P2P2_DP<13>")
	)
	(segment
		(start 73.883774 -365.945928)
		(end 73.62317 -365.685324)
		(width 0.14732)
		(layer "In6.Cu")
		(net "UPI_CPU0_CPU1_P2P2_DP<13>")
	)
	(segment
		(start 345.789504 -280.283412)
		(end 345.780614 -280.288492)
		(width 0.0889)
		(layer "In6.Cu")
		(net "UPI_CPU0_CPU1_P2P2_DP<13>")
	)
	(segment
		(start 341.134446 -297.731434)
		(end 340.91118 -298.103798)
		(width 0.14732)
		(layer "In6.Cu")
		(net "UPI_CPU0_CPU1_P2P2_DP<13>")
	)
	(segment
		(start 308.97068 -326.532494)
		(end 308.43728 -327.294748)
		(width 0.14732)
		(layer "In6.Cu")
		(net "UPI_CPU0_CPU1_P2P2_DP<13>")
	)
	(segment
		(start 97.92716 -288.597848)
		(end 97.93605 -288.592768)
		(width 0.0889)
		(layer "In6.Cu")
		(net "UPI_CPU0_CPU1_P2P2_DP<13>")
	)
	(segment
		(start 98.866706 -286.969962)
		(end 98.875596 -286.964882)
		(width 0.0889)
		(layer "In6.Cu")
		(net "UPI_CPU0_CPU1_P2P2_DP<13>")
	)
	(segment
		(start 344.088466 -284.832044)
		(end 344.088466 -284.847538)
		(width 0.0889)
		(layer "In6.Cu")
		(net "UPI_CPU0_CPU1_P2P2_DP<13>")
	)
	(segment
		(start 345.028266 -281.576526)
		(end 345.028266 -281.59202)
		(width 0.0889)
		(layer "In6.Cu")
		(net "UPI_CPU0_CPU1_P2P2_DP<13>")
	)
	(segment
		(start 99.33686 -281.272742)
		(end 99.34575 -281.267662)
		(width 0.0889)
		(layer "In6.Cu")
		(net "UPI_CPU0_CPU1_P2P2_DP<13>")
	)
	(segment
		(start 161.701734 -381.59563)
		(end 125.557534 -381.59563)
		(width 0.14732)
		(layer "In6.Cu")
		(net "UPI_CPU0_CPU1_P2P2_DP<13>")
	)
	(segment
		(start 311.822592 -325.023988)
		(end 311.728104 -325.205852)
		(width 0.14732)
		(layer "In6.Cu")
		(net "UPI_CPU0_CPU1_P2P2_DP<13>")
	)
	(segment
		(start 99.627944 -284.049216)
		(end 99.627944 -284.033722)
		(width 0.0889)
		(layer "In6.Cu")
		(net "UPI_CPU0_CPU1_P2P2_DP<13>")
	)
	(segment
		(start 99.158298 -286.475424)
		(end 99.158298 -286.467804)
		(width 0.0889)
		(layer "In6.Cu")
		(net "UPI_CPU0_CPU1_P2P2_DP<13>")
	)
	(segment
		(start 71.901304 -364.168182)
		(end 71.640954 -363.907832)
		(width 0.14732)
		(layer "In6.Cu")
		(net "UPI_CPU0_CPU1_P2P2_DP<13>")
	)
	(segment
		(start 343.901014 -285.171896)
		(end 343.894918 -285.175452)
		(width 0.0889)
		(layer "In6.Cu")
		(net "UPI_CPU0_CPU1_P2P2_DP<13>")
	)
	(segment
		(start 347.674946 -278.652224)
		(end 347.660214 -278.66086)
		(width 0.0889)
		(layer "In6.Cu")
		(net "UPI_CPU0_CPU1_P2P2_DP<13>")
	)
	(segment
		(start 94.245176 -301.183802)
		(end 95.233236 -299.851826)
		(width 0.14732)
		(layer "In6.Cu")
		(net "UPI_CPU0_CPU1_P2P2_DP<13>")
	)
	(segment
		(start 72.692514 -364.959392)
		(end 72.366632 -364.63351)
		(width 0.14732)
		(layer "In6.Cu")
		(net "UPI_CPU0_CPU1_P2P2_DP<13>")
	)
	(segment
		(start 73.62317 -365.685324)
		(end 73.418446 -365.685324)
		(width 0.14732)
		(layer "In6.Cu")
		(net "UPI_CPU0_CPU1_P2P2_DP<13>")
	)
	(segment
		(start 98.218244 -289.610038)
		(end 98.218244 -289.60953)
		(width 0.0889)
		(layer "In6.Cu")
		(net "UPI_CPU0_CPU1_P2P2_DP<13>")
	)
	(segment
		(start 311.728104 -325.205598)
		(end 311.72785 -325.205852)
		(width 0.14732)
		(layer "In6.Cu")
		(net "UPI_CPU0_CPU1_P2P2_DP<13>")
	)
	(segment
		(start 78.850998 -313.816492)
		(end 94.245176 -301.183802)
		(width 0.14732)
		(layer "In6.Cu")
		(net "UPI_CPU0_CPU1_P2P2_DP<13>")
	)
	(segment
		(start 268.993112 -344.68689)
		(end 268.993112 -367.656618)
		(width 0.14732)
		(layer "In6.Cu")
		(net "UPI_CPU0_CPU1_P2P2_DP<13>")
	)
	(segment
		(start 343.43975 -287.608518)
		(end 343.43086 -287.613598)
		(width 0.0889)
		(layer "In6.Cu")
		(net "UPI_CPU0_CPU1_P2P2_DP<13>")
	)
	(segment
		(start 264.009124 -372.640606)
		(end 212.927692 -377.111768)
		(width 0.14732)
		(layer "In6.Cu")
		(net "UPI_CPU0_CPU1_P2P2_DP<13>")
	)
	(segment
		(start 341.441532 -295.086786)
		(end 341.441532 -296.72788)
		(width 0.14732)
		(layer "In6.Cu")
		(net "UPI_CPU0_CPU1_P2P2_DP<13>")
	)
	(segment
		(start 344.840814 -281.916378)
		(end 344.834718 -281.919934)
		(width 0.0889)
		(layer "In6.Cu")
		(net "UPI_CPU0_CPU1_P2P2_DP<13>")
	)
	(segment
		(start 344.558112 -282.405836)
		(end 344.558112 -282.42006)
		(width 0.0889)
		(layer "In6.Cu")
		(net "UPI_CPU0_CPU1_P2P2_DP<13>")
	)
	(segment
		(start 342.678766 -288.898584)
		(end 342.678766 -289.077908)
		(width 0.0889)
		(layer "In6.Cu")
		(net "UPI_CPU0_CPU1_P2P2_DP<13>")
	)
	(segment
		(start 343.901014 -286.799782)
		(end 343.900252 -286.80029)
		(width 0.0889)
		(layer "In6.Cu")
		(net "UPI_CPU0_CPU1_P2P2_DP<13>")
	)
	(segment
		(start 351.701862 -279.150318)
		(end 351.389188 -279.150318)
		(width 0.0889)
		(layer "In6.Cu")
		(net "UPI_CPU0_CPU1_P2P2_DP<13>")
	)
	(segment
		(start 74.609452 -366.87633)
		(end 74.609452 -366.671606)
		(width 0.14732)
		(layer "In6.Cu")
		(net "UPI_CPU0_CPU1_P2P2_DP<13>")
	)
	(segment
		(start 100.74656 -278.83104)
		(end 100.75545 -278.82596)
		(width 0.0889)
		(layer "In6.Cu")
		(net "UPI_CPU0_CPU1_P2P2_DP<13>")
	)
	(segment
		(start 74.144124 -366.411002)
		(end 73.883774 -366.150652)
		(width 0.14732)
		(layer "In6.Cu")
		(net "UPI_CPU0_CPU1_P2P2_DP<13>")
	)
	(segment
		(start 349.165164 -278.66086)
		(end 349.15475 -278.654764)
		(width 0.0889)
		(layer "In6.Cu")
		(net "UPI_CPU0_CPU1_P2P2_DP<13>")
	)
	(segment
		(start 99.734878 -281.907742)
		(end 99.720146 -281.916378)
		(width 0.0889)
		(layer "In6.Cu")
		(net "UPI_CPU0_CPU1_P2P2_DP<13>")
	)
	(segment
		(start 341.441532 -295.064688)
		(end 341.441532 -295.086786)
		(width 0.0889)
		(layer "In6.Cu")
		(net "UPI_CPU0_CPU1_P2P2_DP<13>")
	)
	(segment
		(start 306.749704 -331.237844)
		(end 306.54498 -331.237844)
		(width 0.14732)
		(layer "In6.Cu")
		(net "UPI_CPU0_CPU1_P2P2_DP<13>")
	)
	(segment
		(start 311.19699 -325.372984)
		(end 310.847994 -325.372984)
		(width 0.14732)
		(layer "In6.Cu")
		(net "UPI_CPU0_CPU1_P2P2_DP<13>")
	)
	(segment
		(start 97.267522 -291.413946)
		(end 98.21799 -290.463478)
		(width 0.0889)
		(layer "In6.Cu")
		(net "UPI_CPU0_CPU1_P2P2_DP<13>")
	)
	(segment
		(start 306.54498 -331.237844)
		(end 306.284376 -331.498702)
		(width 0.14732)
		(layer "In6.Cu")
		(net "UPI_CPU0_CPU1_P2P2_DP<13>")
	)
	(segment
		(start 72.106028 -364.168182)
		(end 71.901304 -364.168182)
		(width 0.14732)
		(layer "In6.Cu")
		(net "UPI_CPU0_CPU1_P2P2_DP<13>")
	)
	(segment
		(start 341.483442 -290.926266)
		(end 341.483442 -295.022778)
		(width 0.0889)
		(layer "In6.Cu")
		(net "UPI_CPU0_CPU1_P2P2_DP<13>")
	)
	(segment
		(start 310.847994 -325.372984)
		(end 309.879746 -325.77405)
		(width 0.14732)
		(layer "In6.Cu")
		(net "UPI_CPU0_CPU1_P2P2_DP<13>")
	)
	(segment
		(start 99.806506 -283.714444)
		(end 99.821746 -283.705554)
		(width 0.0889)
		(layer "In6.Cu")
		(net "UPI_CPU0_CPU1_P2P2_DP<13>")
	)
	(segment
		(start 101.977698 -276.718522)
		(end 101.977698 -276.69998)
		(width 0.0889)
		(layer "In6.Cu")
		(net "UPI_CPU0_CPU1_P2P2_DP<13>")
	)
	(segment
		(start 100.28555 -279.639776)
		(end 100.291646 -279.63622)
		(width 0.0889)
		(layer "In6.Cu")
		(net "UPI_CPU0_CPU1_P2P2_DP<13>")
	)
	(segment
		(start 341.483442 -295.022778)
		(end 341.441532 -295.064688)
		(width 0.0889)
		(layer "In6.Cu")
		(net "UPI_CPU0_CPU1_P2P2_DP<13>")
	)
	(segment
		(start 344.849704 -281.911298)
		(end 344.840814 -281.916378)
		(width 0.0889)
		(layer "In6.Cu")
		(net "UPI_CPU0_CPU1_P2P2_DP<13>")
	)
	(segment
		(start 73.883774 -366.150652)
		(end 73.883774 -365.945928)
		(width 0.14732)
		(layer "In6.Cu")
		(net "UPI_CPU0_CPU1_P2P2_DP<13>")
	)
	(segment
		(start 342.208866 -289.611054)
		(end 342.208866 -290.200842)
		(width 0.0889)
		(layer "In6.Cu")
		(net "UPI_CPU0_CPU1_P2P2_DP<13>")
	)
	(segment
		(start 346.735146 -278.652224)
		(end 346.720414 -278.66086)
		(width 0.0889)
		(layer "In6.Cu")
		(net "UPI_CPU0_CPU1_P2P2_DP<13>")
	)
	(segment
		(start 305.71059 -332.27772)
		(end 284.91688 -332.27772)
		(width 0.14732)
		(layer "In6.Cu")
		(net "UPI_CPU0_CPU1_P2P2_DP<13>")
	)
	(segment
		(start 312.355738 -325.007732)
		(end 312.174128 -324.913244)
		(width 0.14732)
		(layer "In6.Cu")
		(net "UPI_CPU0_CPU1_P2P2_DP<13>")
	)
	(segment
		(start 342.970104 -288.422334)
		(end 342.961214 -288.427414)
		(width 0.0889)
		(layer "In6.Cu")
		(net "UPI_CPU0_CPU1_P2P2_DP<13>")
	)
	(segment
		(start 345.31935 -281.097482)
		(end 345.31046 -281.102562)
		(width 0.0889)
		(layer "In6.Cu")
		(net "UPI_CPU0_CPU1_P2P2_DP<13>")
	)
	(segment
		(start 101.037898 -278.346408)
		(end 101.037898 -278.327866)
		(width 0.0889)
		(layer "In6.Cu")
		(net "UPI_CPU0_CPU1_P2P2_DP<13>")
	)
	(segment
		(start 284.91688 -332.27772)
		(end 278.917654 -334.762348)
		(width 0.14732)
		(layer "In6.Cu")
		(net "UPI_CPU0_CPU1_P2P2_DP<13>")
	)
	(segment
		(start 308.43728 -327.294748)
		(end 308.008782 -329.725274)
		(width 0.14732)
		(layer "In6.Cu")
		(net "UPI_CPU0_CPU1_P2P2_DP<13>")
	)
	(segment
		(start 100.098098 -279.978358)
		(end 100.098098 -279.964134)
		(width 0.0889)
		(layer "In6.Cu")
		(net "UPI_CPU0_CPU1_P2P2_DP<13>")
	)
	(segment
		(start 307.416454 -330.57084)
		(end 306.749704 -331.237844)
		(width 0.14732)
		(layer "In6.Cu")
		(net "UPI_CPU0_CPU1_P2P2_DP<13>")
	)
	(segment
		(start 311.72785 -325.205852)
		(end 311.72785 -325.205598)
		(width 0.14732)
		(layer "In6.Cu")
		(net "UPI_CPU0_CPU1_P2P2_DP<13>")
	)
	(segment
		(start 314.143136 -323.320156)
		(end 313.216544 -324.64375)
		(width 0.14732)
		(layer "In6.Cu")
		(net "UPI_CPU0_CPU1_P2P2_DP<13>")
	)
	(segment
		(start 100.567744 -282.424378)
		(end 100.567744 -282.390342)
		(width 0.0889)
		(layer "In6.Cu")
		(net "UPI_CPU0_CPU1_P2P2_DP<13>")
	)
	(segment
		(start 308.008782 -329.725274)
		(end 307.416454 -330.57084)
		(width 0.14732)
		(layer "In6.Cu")
		(net "UPI_CPU0_CPU1_P2P2_DP<13>")
	)
	(segment
		(start 97.252028 -291.489384)
		(end 97.267522 -291.47389)
		(width 0.0889)
		(layer "In6.Cu")
		(net "UPI_CPU0_CPU1_P2P2_DP<13>")
	)
	(segment
		(start 311.728104 -325.205852)
		(end 311.728104 -325.205598)
		(width 0.14732)
		(layer "In6.Cu")
		(net "UPI_CPU0_CPU1_P2P2_DP<13>")
	)
	(segment
		(start 98.688144 -287.304734)
		(end 98.688144 -287.28924)
		(width 0.0889)
		(layer "In6.Cu")
		(net "UPI_CPU0_CPU1_P2P2_DP<13>")
	)
	(segment
		(start 343.909904 -285.166816)
		(end 343.901014 -285.171896)
		(width 0.0889)
		(layer "In6.Cu")
		(net "UPI_CPU0_CPU1_P2P2_DP<13>")
	)
	(segment
		(start 339.8012 -299.672756)
		(end 336.369914 -301.093378)
		(width 0.14732)
		(layer "In6.Cu")
		(net "UPI_CPU0_CPU1_P2P2_DP<13>")
	)
	(segment
		(start 74.609452 -366.671606)
		(end 74.348848 -366.411002)
		(width 0.14732)
		(layer "In6.Cu")
		(net "UPI_CPU0_CPU1_P2P2_DP<13>")
	)
	(segment
		(start 101.507798 -277.530052)
		(end 101.507798 -277.522432)
		(width 0.0889)
		(layer "In6.Cu")
		(net "UPI_CPU0_CPU1_P2P2_DP<13>")
	)
	(segment
		(start 342.208866 -290.200842)
		(end 341.483442 -290.926266)
		(width 0.0889)
		(layer "In6.Cu")
		(net "UPI_CPU0_CPU1_P2P2_DP<13>")
	)
	(segment
		(start 67.542918 -354.014024)
		(end 67.542918 -334.815688)
		(width 0.14732)
		(layer "In6.Cu")
		(net "UPI_CPU0_CPU1_P2P2_DP<13>")
	)
	(arc
		(start 102.634796 -275.570442)
		(mid 102.818783 -275.400303)
		(end 102.911148 -275.167344)
		(width 0.0889)
		(layer "In6.Cu")
		(net "UPI_CPU0_CPU1_P2P2_DP<13>")
	)
	(arc
		(start 344.088212 -286.48406)
		(mid 344.035942 -286.666425)
		(end 343.901014 -286.799782)
		(width 0.0889)
		(layer "In6.Cu")
		(net "UPI_CPU0_CPU1_P2P2_DP<13>")
	)
	(arc
		(start 344.558112 -284.033722)
		(mid 344.510433 -284.216622)
		(end 344.37955 -284.353)
		(width 0.0889)
		(layer "In6.Cu")
		(net "UPI_CPU0_CPU1_P2P2_DP<13>")
	)
	(arc
		(start 351.320862 -279.063704)
		(mid 351.228701 -278.830932)
		(end 351.045018 -278.66086)
		(width 0.0889)
		(layer "In6.Cu")
		(net "UPI_CPU0_CPU1_P2P2_DP<13>")
	)
	(arc
		(start 99.627944 -280.778204)
		(mid 99.675623 -280.595304)
		(end 99.806506 -280.458926)
		(width 0.0889)
		(layer "In6.Cu")
		(net "UPI_CPU0_CPU1_P2P2_DP<13>")
	)
	(arc
		(start 345.028266 -281.59202)
		(mid 344.980587 -281.77492)
		(end 344.849704 -281.911298)
		(width 0.0889)
		(layer "In6.Cu")
		(net "UPI_CPU0_CPU1_P2P2_DP<13>")
	)
	(arc
		(start 345.497912 -280.778204)
		(mid 345.450233 -280.961104)
		(end 345.31935 -281.097482)
		(width 0.0889)
		(layer "In6.Cu")
		(net "UPI_CPU0_CPU1_P2P2_DP<13>")
	)
	(arc
		(start 98.40595 -287.778698)
		(mid 98.608773 -287.578467)
		(end 98.688144 -287.304734)
		(width 0.0889)
		(layer "In6.Cu")
		(net "UPI_CPU0_CPU1_P2P2_DP<13>")
	)
	(arc
		(start 99.158298 -286.467804)
		(mid 99.080669 -286.189391)
		(end 98.875596 -285.985712)
		(width 0.0889)
		(layer "In6.Cu")
		(net "UPI_CPU0_CPU1_P2P2_DP<13>")
	)
	(arc
		(start 345.31046 -281.102562)
		(mid 345.107637 -281.302793)
		(end 345.028266 -281.576526)
		(width 0.0889)
		(layer "In6.Cu")
		(net "UPI_CPU0_CPU1_P2P2_DP<13>")
	)
	(arc
		(start 99.821492 -283.705808)
		(mid 100.024079 -283.499457)
		(end 100.098098 -283.219906)
		(width 0.0889)
		(layer "In6.Cu")
		(net "UPI_CPU0_CPU1_P2P2_DP<13>")
	)
	(arc
		(start 346.437712 -279.158954)
		(mid 346.385442 -279.341319)
		(end 346.250514 -279.474676)
		(width 0.0889)
		(layer "In6.Cu")
		(net "UPI_CPU0_CPU1_P2P2_DP<13>")
	)
	(arc
		(start 99.720146 -281.916378)
		(mid 99.532948 -281.966521)
		(end 99.34575 -281.916378)
		(width 0.0889)
		(layer "In6.Cu")
		(net "UPI_CPU0_CPU1_P2P2_DP<13>")
	)
	(arc
		(start 348.225618 -278.66086)
		(mid 347.951419 -278.585025)
		(end 347.674946 -278.652224)
		(width 0.0889)
		(layer "In6.Cu")
		(net "UPI_CPU0_CPU1_P2P2_DP<13>")
	)
	(arc
		(start 343.148666 -288.103056)
		(mid 343.100987 -288.285956)
		(end 342.970104 -288.422334)
		(width 0.0889)
		(layer "In6.Cu")
		(net "UPI_CPU0_CPU1_P2P2_DP<13>")
	)
	(arc
		(start 101.507798 -277.522432)
		(mid 101.555477 -277.339532)
		(end 101.68636 -277.203154)
		(width 0.0889)
		(layer "In6.Cu")
		(net "UPI_CPU0_CPU1_P2P2_DP<13>")
	)
	(arc
		(start 342.678766 -289.077908)
		(mid 342.603695 -289.19365)
		(end 342.494362 -289.277806)
		(width 0.0889)
		(layer "In6.Cu")
		(net "UPI_CPU0_CPU1_P2P2_DP<13>")
	)
	(arc
		(start 343.901014 -286.151066)
		(mid 344.035947 -286.28442)
		(end 344.088212 -286.466788)
		(width 0.0889)
		(layer "In6.Cu")
		(net "UPI_CPU0_CPU1_P2P2_DP<13>")
	)
	(arc
		(start 346.250514 -279.474676)
		(mid 346.046179 -279.677281)
		(end 345.968066 -279.954228)
		(width 0.0889)
		(layer "In6.Cu")
		(net "UPI_CPU0_CPU1_P2P2_DP<13>")
	)
	(arc
		(start 343.618312 -285.675578)
		(mid 343.697531 -285.950263)
		(end 343.901014 -286.151066)
		(width 0.0889)
		(layer "In6.Cu")
		(net "UPI_CPU0_CPU1_P2P2_DP<13>")
	)
	(arc
		(start 349.53956 -278.66086)
		(mid 349.352362 -278.711003)
		(end 349.165164 -278.66086)
		(width 0.0889)
		(layer "In6.Cu")
		(net "UPI_CPU0_CPU1_P2P2_DP<13>")
	)
	(arc
		(start 99.34575 -284.52318)
		(mid 99.548573 -284.322949)
		(end 99.627944 -284.049216)
		(width 0.0889)
		(layer "In6.Cu")
		(net "UPI_CPU0_CPU1_P2P2_DP<13>")
	)
	(arc
		(start 97.93605 -288.592768)
		(mid 98.138336 -288.393787)
		(end 98.218498 -288.121598)
		(width 0.0889)
		(layer "In6.Cu")
		(net "UPI_CPU0_CPU1_P2P2_DP<13>")
	)
	(arc
		(start 348.600014 -278.66086)
		(mid 348.412816 -278.711003)
		(end 348.225618 -278.66086)
		(width 0.0889)
		(layer "In6.Cu")
		(net "UPI_CPU0_CPU1_P2P2_DP<13>")
	)
	(arc
		(start 100.098098 -283.21127)
		(mid 100.150368 -283.028905)
		(end 100.285296 -282.895548)
		(width 0.0889)
		(layer "In6.Cu")
		(net "UPI_CPU0_CPU1_P2P2_DP<13>")
	)
	(arc
		(start 345.780614 -280.288492)
		(mid 345.577133 -280.489296)
		(end 345.497912 -280.76398)
		(width 0.0889)
		(layer "In6.Cu")
		(net "UPI_CPU0_CPU1_P2P2_DP<13>")
	)
	(arc
		(start 343.894918 -285.175452)
		(mid 343.692331 -285.381803)
		(end 343.618312 -285.661354)
		(width 0.0889)
		(layer "In6.Cu")
		(net "UPI_CPU0_CPU1_P2P2_DP<13>")
	)
	(arc
		(start 101.977698 -276.69998)
		(mid 102.029968 -276.517615)
		(end 102.164896 -276.384258)
		(width 0.0889)
		(layer "In6.Cu")
		(net "UPI_CPU0_CPU1_P2P2_DP<13>")
	)
	(arc
		(start 98.218498 -288.103056)
		(mid 98.266177 -287.920156)
		(end 98.39706 -287.783778)
		(width 0.0889)
		(layer "In6.Cu")
		(net "UPI_CPU0_CPU1_P2P2_DP<13>")
	)
	(arc
		(start 99.627944 -284.033722)
		(mid 99.675623 -283.850822)
		(end 99.806506 -283.714444)
		(width 0.0889)
		(layer "In6.Cu")
		(net "UPI_CPU0_CPU1_P2P2_DP<13>")
	)
	(arc
		(start 99.34575 -281.267662)
		(mid 99.548573 -281.067431)
		(end 99.627944 -280.793698)
		(width 0.0889)
		(layer "In6.Cu")
		(net "UPI_CPU0_CPU1_P2P2_DP<13>")
	)
	(arc
		(start 342.494616 -289.27806)
		(mid 342.32011 -289.417411)
		(end 342.208866 -289.611054)
		(width 0.0889)
		(layer "In6.Cu")
		(net "UPI_CPU0_CPU1_P2P2_DP<13>")
	)
	(arc
		(start 344.834718 -283.54782)
		(mid 344.632131 -283.754171)
		(end 344.558112 -284.033722)
		(width 0.0889)
		(layer "In6.Cu")
		(net "UPI_CPU0_CPU1_P2P2_DP<13>")
	)
	(arc
		(start 98.887788 -286.95777)
		(mid 99.086016 -286.751922)
		(end 99.158298 -286.475424)
		(width 0.0889)
		(layer "In6.Cu")
		(net "UPI_CPU0_CPU1_P2P2_DP<13>")
	)
	(arc
		(start 97.932748 -289.277806)
		(mid 97.823601 -289.193878)
		(end 97.748598 -289.078416)
		(width 0.0889)
		(layer "In6.Cu")
		(net "UPI_CPU0_CPU1_P2P2_DP<13>")
	)
	(arc
		(start 345.968066 -279.964134)
		(mid 345.920387 -280.147034)
		(end 345.789504 -280.283412)
		(width 0.0889)
		(layer "In6.Cu")
		(net "UPI_CPU0_CPU1_P2P2_DP<13>")
	)
	(arc
		(start 344.834718 -281.919934)
		(mid 344.632131 -282.126285)
		(end 344.558112 -282.405836)
		(width 0.0889)
		(layer "In6.Cu")
		(net "UPI_CPU0_CPU1_P2P2_DP<13>")
	)
	(arc
		(start 100.098098 -279.964134)
		(mid 100.145777 -279.781234)
		(end 100.27666 -279.644856)
		(width 0.0889)
		(layer "In6.Cu")
		(net "UPI_CPU0_CPU1_P2P2_DP<13>")
	)
	(arc
		(start 351.045018 -278.66086)
		(mid 350.770819 -278.585025)
		(end 350.494346 -278.652224)
		(width 0.0889)
		(layer "In6.Cu")
		(net "UPI_CPU0_CPU1_P2P2_DP<13>")
	)
	(arc
		(start 351.323656 -279.084786)
		(mid 351.322358 -279.074232)
		(end 351.320862 -279.063704)
		(width 0.0889)
		(layer "In6.Cu")
		(net "UPI_CPU0_CPU1_P2P2_DP<13>")
	)
	(arc
		(start 99.33686 -281.911298)
		(mid 99.158384 -281.59202)
		(end 99.33686 -281.272742)
		(width 0.0889)
		(layer "In6.Cu")
		(net "UPI_CPU0_CPU1_P2P2_DP<13>")
	)
	(arc
		(start 347.285818 -278.66086)
		(mid 347.011619 -278.585025)
		(end 346.735146 -278.652224)
		(width 0.0889)
		(layer "In6.Cu")
		(net "UPI_CPU0_CPU1_P2P2_DP<13>")
	)
	(arc
		(start 100.567998 -279.150318)
		(mid 100.615677 -278.967418)
		(end 100.74656 -278.83104)
		(width 0.0889)
		(layer "In6.Cu")
		(net "UPI_CPU0_CPU1_P2P2_DP<13>")
	)
	(arc
		(start 343.43086 -287.613598)
		(mid 343.228037 -287.813829)
		(end 343.148666 -288.087562)
		(width 0.0889)
		(layer "In6.Cu")
		(net "UPI_CPU0_CPU1_P2P2_DP<13>")
	)
	(arc
		(start 101.69525 -277.198074)
		(mid 101.899585 -276.995469)
		(end 101.977698 -276.718522)
		(width 0.0889)
		(layer "In6.Cu")
		(net "UPI_CPU0_CPU1_P2P2_DP<13>")
	)
	(arc
		(start 349.15475 -278.654764)
		(mid 348.876572 -278.585041)
		(end 348.600014 -278.66086)
		(width 0.0889)
		(layer "In6.Cu")
		(net "UPI_CPU0_CPU1_P2P2_DP<13>")
	)
	(arc
		(start 98.688144 -287.28924)
		(mid 98.735823 -287.10634)
		(end 98.866706 -286.969962)
		(width 0.0889)
		(layer "In6.Cu")
		(net "UPI_CPU0_CPU1_P2P2_DP<13>")
	)
	(arc
		(start 346.714318 -278.664416)
		(mid 346.511731 -278.870767)
		(end 346.437712 -279.150318)
		(width 0.0889)
		(layer "In6.Cu")
		(net "UPI_CPU0_CPU1_P2P2_DP<13>")
	)
	(arc
		(start 344.840814 -282.895548)
		(mid 344.975747 -283.028902)
		(end 345.028012 -283.21127)
		(width 0.0889)
		(layer "In6.Cu")
		(net "UPI_CPU0_CPU1_P2P2_DP<13>")
	)
	(arc
		(start 100.291646 -279.63622)
		(mid 100.494059 -279.429807)
		(end 100.567998 -279.150318)
		(width 0.0889)
		(layer "In6.Cu")
		(net "UPI_CPU0_CPU1_P2P2_DP<13>")
	)
	(arc
		(start 100.285296 -282.895548)
		(mid 100.487582 -282.696567)
		(end 100.567744 -282.424378)
		(width 0.0889)
		(layer "In6.Cu")
		(net "UPI_CPU0_CPU1_P2P2_DP<13>")
	)
	(arc
		(start 350.479614 -278.66086)
		(mid 350.292416 -278.711003)
		(end 350.105218 -278.66086)
		(width 0.0889)
		(layer "In6.Cu")
		(net "UPI_CPU0_CPU1_P2P2_DP<13>")
	)
	(arc
		(start 343.618312 -287.28924)
		(mid 343.570633 -287.47214)
		(end 343.43975 -287.608518)
		(width 0.0889)
		(layer "In6.Cu")
		(net "UPI_CPU0_CPU1_P2P2_DP<13>")
	)
	(arc
		(start 345.028012 -283.228542)
		(mid 344.975742 -283.410907)
		(end 344.840814 -283.544264)
		(width 0.0889)
		(layer "In6.Cu")
		(net "UPI_CPU0_CPU1_P2P2_DP<13>")
	)
	(arc
		(start 347.660214 -278.66086)
		(mid 347.473016 -278.711003)
		(end 347.285818 -278.66086)
		(width 0.0889)
		(layer "In6.Cu")
		(net "UPI_CPU0_CPU1_P2P2_DP<13>")
	)
	(arc
		(start 97.748598 -288.917126)
		(mid 97.796277 -288.734226)
		(end 97.92716 -288.597848)
		(width 0.0889)
		(layer "In6.Cu")
		(net "UPI_CPU0_CPU1_P2P2_DP<13>")
	)
	(arc
		(start 99.158298 -284.847538)
		(mid 99.205977 -284.664638)
		(end 99.33686 -284.52826)
		(width 0.0889)
		(layer "In6.Cu")
		(net "UPI_CPU0_CPU1_P2P2_DP<13>")
	)
	(arc
		(start 102.911148 -275.167344)
		(mid 102.912644 -275.156816)
		(end 102.913942 -275.146262)
		(width 0.0889)
		(layer "In6.Cu")
		(net "UPI_CPU0_CPU1_P2P2_DP<13>")
	)
	(arc
		(start 102.164896 -276.384258)
		(mid 102.369231 -276.181653)
		(end 102.447344 -275.904706)
		(width 0.0889)
		(layer "In6.Cu")
		(net "UPI_CPU0_CPU1_P2P2_DP<13>")
	)
	(arc
		(start 100.28555 -281.916378)
		(mid 100.011351 -281.840543)
		(end 99.734878 -281.907742)
		(width 0.0889)
		(layer "In6.Cu")
		(net "UPI_CPU0_CPU1_P2P2_DP<13>")
	)
	(arc
		(start 98.218244 -289.60953)
		(mid 98.106906 -289.41663)
		(end 97.932748 -289.277806)
		(width 0.0889)
		(layer "In6.Cu")
		(net "UPI_CPU0_CPU1_P2P2_DP<13>")
	)
	(arc
		(start 99.815396 -280.453846)
		(mid 100.018877 -280.253042)
		(end 100.098098 -279.978358)
		(width 0.0889)
		(layer "In6.Cu")
		(net "UPI_CPU0_CPU1_P2P2_DP<13>")
	)
	(arc
		(start 100.75545 -278.82596)
		(mid 100.959785 -278.623355)
		(end 101.037898 -278.346408)
		(width 0.0889)
		(layer "In6.Cu")
		(net "UPI_CPU0_CPU1_P2P2_DP<13>")
	)
	(arc
		(start 98.866706 -285.980632)
		(mid 98.68823 -285.661354)
		(end 98.866706 -285.342076)
		(width 0.0889)
		(layer "In6.Cu")
		(net "UPI_CPU0_CPU1_P2P2_DP<13>")
	)
	(arc
		(start 101.037898 -278.327866)
		(mid 101.090168 -278.145501)
		(end 101.225096 -278.012144)
		(width 0.0889)
		(layer "In6.Cu")
		(net "UPI_CPU0_CPU1_P2P2_DP<13>")
	)
	(arc
		(start 98.881692 -285.33344)
		(mid 99.084279 -285.127089)
		(end 99.158298 -284.847538)
		(width 0.0889)
		(layer "In6.Cu")
		(net "UPI_CPU0_CPU1_P2P2_DP<13>")
	)
	(arc
		(start 343.894918 -286.803338)
		(mid 343.692331 -287.009689)
		(end 343.618312 -287.28924)
		(width 0.0889)
		(layer "In6.Cu")
		(net "UPI_CPU0_CPU1_P2P2_DP<13>")
	)
	(arc
		(start 102.447344 -275.8948)
		(mid 102.495023 -275.7119)
		(end 102.625906 -275.575522)
		(width 0.0889)
		(layer "In6.Cu")
		(net "UPI_CPU0_CPU1_P2P2_DP<13>")
	)
	(arc
		(start 350.105218 -278.66086)
		(mid 349.828405 -278.58499)
		(end 349.549974 -278.654764)
		(width 0.0889)
		(layer "In6.Cu")
		(net "UPI_CPU0_CPU1_P2P2_DP<13>")
	)
	(arc
		(start 101.225096 -278.012144)
		(mid 101.430168 -277.808465)
		(end 101.507798 -277.530052)
		(width 0.0889)
		(layer "In6.Cu")
		(net "UPI_CPU0_CPU1_P2P2_DP<13>")
	)
	(arc
		(start 342.961214 -288.427414)
		(mid 342.758928 -288.626395)
		(end 342.678766 -288.898584)
		(width 0.0889)
		(layer "In6.Cu")
		(net "UPI_CPU0_CPU1_P2P2_DP<13>")
	)
	(arc
		(start 344.088466 -284.847538)
		(mid 344.040787 -285.030438)
		(end 343.909904 -285.166816)
		(width 0.0889)
		(layer "In6.Cu")
		(net "UPI_CPU0_CPU1_P2P2_DP<13>")
	)
	(arc
		(start 100.567744 -282.390342)
		(mid 100.488374 -282.116608)
		(end 100.28555 -281.916378)
		(width 0.0889)
		(layer "In6.Cu")
		(net "UPI_CPU0_CPU1_P2P2_DP<13>")
	)
	(arc
		(start 344.558112 -282.42006)
		(mid 344.637331 -282.694745)
		(end 344.840814 -282.895548)
		(width 0.0889)
		(layer "In6.Cu")
		(net "UPI_CPU0_CPU1_P2P2_DP<13>")
	)
	(arc
		(start 344.37066 -284.35808)
		(mid 344.167837 -284.558311)
		(end 344.088466 -284.832044)
		(width 0.0889)
		(layer "In6.Cu")
		(net "UPI_CPU0_CPU1_P2P2_DP<13>")
	)
	(segment
		(start 104.231694 -275.080476)
		(end 104.231948 -275.08073)
		(width 0.13208)
		(layer "F.Cu")
		(net "UPI_CPU0_CPU1_P2P2_DP<12>")
	)
	(segment
		(start 350.292416 -279.428448)
		(end 350.292416 -279.964134)
		(width 0.13208)
		(layer "F.Cu")
		(net "UPI_CPU0_CPU1_P2P2_DP<12>")
	)
	(segment
		(start 350.292162 -279.428194)
		(end 350.292416 -279.428448)
		(width 0.13208)
		(layer "F.Cu")
		(net "UPI_CPU0_CPU1_P2P2_DP<12>")
	)
	(segment
		(start 104.231694 -274.54479)
		(end 104.231694 -275.080476)
		(width 0.13208)
		(layer "F.Cu")
		(net "UPI_CPU0_CPU1_P2P2_DP<12>")
	)
	(segment
		(start 95.450152 -295.624758)
		(end 95.450152 -295.256458)
		(width 0.14732)
		(layer "In6.Cu")
		(net "UPI_CPU0_CPU1_P2P2_DP<12>")
	)
	(segment
		(start 344.37955 -287.608518)
		(end 344.37066 -287.613598)
		(width 0.0889)
		(layer "In6.Cu")
		(net "UPI_CPU0_CPU1_P2P2_DP<12>")
	)
	(segment
		(start 350.292416 -279.964134)
		(end 350.135952 -279.693116)
		(width 0.0889)
		(layer "In6.Cu")
		(net "UPI_CPU0_CPU1_P2P2_DP<12>")
	)
	(segment
		(start 98.688144 -284.049216)
		(end 98.688144 -284.033722)
		(width 0.0889)
		(layer "In6.Cu")
		(net "UPI_CPU0_CPU1_P2P2_DP<12>")
	)
	(segment
		(start 73.501758 -366.943894)
		(end 73.19264 -366.634776)
		(width 0.14732)
		(layer "In6.Cu")
		(net "UPI_CPU0_CPU1_P2P2_DP<12>")
	)
	(segment
		(start 95.450152 -292.904418)
		(end 95.305372 -292.759638)
		(width 0.14732)
		(layer "In6.Cu")
		(net "UPI_CPU0_CPU1_P2P2_DP<12>")
	)
	(segment
		(start 342.468962 -293.903908)
		(end 342.468962 -294.423338)
		(width 0.0889)
		(layer "In6.Cu")
		(net "UPI_CPU0_CPU1_P2P2_DP<12>")
	)
	(segment
		(start 95.305372 -293.785798)
		(end 95.305372 -293.417498)
		(width 0.14732)
		(layer "In6.Cu")
		(net "UPI_CPU0_CPU1_P2P2_DP<12>")
	)
	(segment
		(start 342.427052 -296.965624)
		(end 341.541354 -299.104304)
		(width 0.14732)
		(layer "In6.Cu")
		(net "UPI_CPU0_CPU1_P2P2_DP<12>")
	)
	(segment
		(start 98.218498 -286.475424)
		(end 98.218498 -286.4612)
		(width 0.0889)
		(layer "In6.Cu")
		(net "UPI_CPU0_CPU1_P2P2_DP<12>")
	)
	(segment
		(start 99.815396 -278.82596)
		(end 99.81819 -278.824436)
		(width 0.0889)
		(layer "In6.Cu")
		(net "UPI_CPU0_CPU1_P2P2_DP<12>")
	)
	(segment
		(start 95.305372 -292.759638)
		(end 95.305372 -292.254686)
		(width 0.14732)
		(layer "In6.Cu")
		(net "UPI_CPU0_CPU1_P2P2_DP<12>")
	)
	(segment
		(start 94.877636 -298.210478)
		(end 95.037148 -298.144438)
		(width 0.14732)
		(layer "In6.Cu")
		(net "UPI_CPU0_CPU1_P2P2_DP<12>")
	)
	(segment
		(start 100.757482 -277.196804)
		(end 100.759514 -277.195534)
		(width 0.0889)
		(layer "In6.Cu")
		(net "UPI_CPU0_CPU1_P2P2_DP<12>")
	)
	(segment
		(start 68.811394 -323.99986)
		(end 68.753228 -323.837554)
		(width 0.14732)
		(layer "In6.Cu")
		(net "UPI_CPU0_CPU1_P2P2_DP<12>")
	)
	(segment
		(start 342.427052 -294.487346)
		(end 342.427052 -296.965624)
		(width 0.14732)
		(layer "In6.Cu")
		(net "UPI_CPU0_CPU1_P2P2_DP<12>")
	)
	(segment
		(start 345.31935 -284.353)
		(end 345.31046 -284.35808)
		(width 0.0889)
		(layer "In6.Cu")
		(net "UPI_CPU0_CPU1_P2P2_DP<12>")
	)
	(segment
		(start 99.806506 -277.203154)
		(end 99.813872 -277.198836)
		(width 0.0889)
		(layer "In6.Cu")
		(net "UPI_CPU0_CPU1_P2P2_DP<12>")
	)
	(segment
		(start 98.866706 -280.458926)
		(end 98.875596 -280.453846)
		(width 0.0889)
		(layer "In6.Cu")
		(net "UPI_CPU0_CPU1_P2P2_DP<12>")
	)
	(segment
		(start 342.468962 -293.355268)
		(end 342.468962 -293.530528)
		(width 0.0889)
		(layer "In6.Cu")
		(net "UPI_CPU0_CPU1_P2P2_DP<12>")
	)
	(segment
		(start 71.61149 -365.053626)
		(end 71.439024 -365.053626)
		(width 0.14732)
		(layer "In6.Cu")
		(net "UPI_CPU0_CPU1_P2P2_DP<12>")
	)
	(segment
		(start 97.061782 -290.438332)
		(end 97.279206 -290.220908)
		(width 0.0889)
		(layer "In6.Cu")
		(net "UPI_CPU0_CPU1_P2P2_DP<12>")
	)
	(segment
		(start 102.523798 -274.747228)
		(end 102.526846 -274.748752)
		(width 0.0889)
		(layer "In6.Cu")
		(net "UPI_CPU0_CPU1_P2P2_DP<12>")
	)
	(segment
		(start 347.674946 -280.279856)
		(end 347.660214 -280.288492)
		(width 0.0889)
		(layer "In6.Cu")
		(net "UPI_CPU0_CPU1_P2P2_DP<12>")
	)
	(segment
		(start 69.289168 -322.989448)
		(end 69.231002 -322.827142)
		(width 0.14732)
		(layer "In6.Cu")
		(net "UPI_CPU0_CPU1_P2P2_DP<12>")
	)
	(segment
		(start 95.305372 -295.769538)
		(end 95.450152 -295.624758)
		(width 0.14732)
		(layer "In6.Cu")
		(net "UPI_CPU0_CPU1_P2P2_DP<12>")
	)
	(segment
		(start 346.437712 -280.76398)
		(end 346.437712 -280.778204)
		(width 0.0889)
		(layer "In6.Cu")
		(net "UPI_CPU0_CPU1_P2P2_DP<12>")
	)
	(segment
		(start 103.98633 -274.785836)
		(end 104.075484 -274.809712)
		(width 0.0889)
		(layer "In6.Cu")
		(net "UPI_CPU0_CPU1_P2P2_DP<12>")
	)
	(segment
		(start 68.753228 -323.837554)
		(end 68.939918 -323.442838)
		(width 0.14732)
		(layer "In6.Cu")
		(net "UPI_CPU0_CPU1_P2P2_DP<12>")
	)
	(segment
		(start 99.813872 -278.826722)
		(end 99.815396 -278.82596)
		(width 0.0889)
		(layer "In6.Cu")
		(net "UPI_CPU0_CPU1_P2P2_DP<12>")
	)
	(segment
		(start 68.624704 -324.395084)
		(end 68.811394 -323.99986)
		(width 0.14732)
		(layer "In6.Cu")
		(net "UPI_CPU0_CPU1_P2P2_DP<12>")
	)
	(segment
		(start 95.305372 -294.443658)
		(end 95.450152 -294.298878)
		(width 0.14732)
		(layer "In6.Cu")
		(net "UPI_CPU0_CPU1_P2P2_DP<12>")
	)
	(segment
		(start 344.841322 -286.799274)
		(end 344.84056 -286.799782)
		(width 0.0889)
		(layer "In6.Cu")
		(net "UPI_CPU0_CPU1_P2P2_DP<12>")
	)
	(segment
		(start 344.558112 -287.279334)
		(end 344.558112 -287.28924)
		(width 0.0889)
		(layer "In6.Cu")
		(net "UPI_CPU0_CPU1_P2P2_DP<12>")
	)
	(segment
		(start 345.78925 -283.539184)
		(end 345.78036 -283.544264)
		(width 0.0889)
		(layer "In6.Cu")
		(net "UPI_CPU0_CPU1_P2P2_DP<12>")
	)
	(segment
		(start 73.501758 -367.11636)
		(end 73.501758 -366.943894)
		(width 0.14732)
		(layer "In6.Cu")
		(net "UPI_CPU0_CPU1_P2P2_DP<12>")
	)
	(segment
		(start 264.64006 -373.683784)
		(end 162.003232 -382.425448)
		(width 0.14732)
		(layer "In6.Cu")
		(net "UPI_CPU0_CPU1_P2P2_DP<12>")
	)
	(segment
		(start 98.879406 -283.707078)
		(end 98.887788 -283.702252)
		(width 0.0889)
		(layer "In6.Cu")
		(net "UPI_CPU0_CPU1_P2P2_DP<12>")
	)
	(segment
		(start 101.977444 -275.08073)
		(end 101.977444 -275.068284)
		(width 0.0889)
		(layer "In6.Cu")
		(net "UPI_CPU0_CPU1_P2P2_DP<12>")
	)
	(segment
		(start 71.057516 -364.672118)
		(end 66.709798 -354.175568)
		(width 0.14732)
		(layer "In6.Cu")
		(net "UPI_CPU0_CPU1_P2P2_DP<12>")
	)
	(segment
		(start 342.468962 -292.806628)
		(end 342.468962 -292.981888)
		(width 0.0889)
		(layer "In6.Cu")
		(net "UPI_CPU0_CPU1_P2P2_DP<12>")
	)
	(segment
		(start 66.709798 -334.796892)
		(end 67.36588 -328.13371)
		(width 0.14732)
		(layer "In6.Cu")
		(net "UPI_CPU0_CPU1_P2P2_DP<12>")
	)
	(segment
		(start 93.641164 -300.607476)
		(end 94.193614 -299.862748)
		(width 0.14732)
		(layer "In6.Cu")
		(net "UPI_CPU0_CPU1_P2P2_DP<12>")
	)
	(segment
		(start 346.25915 -282.725114)
		(end 346.25026 -282.730194)
		(width 0.0889)
		(layer "In6.Cu")
		(net "UPI_CPU0_CPU1_P2P2_DP<12>")
	)
	(segment
		(start 97.942146 -286.961072)
		(end 97.941892 -286.961326)
		(width 0.0889)
		(layer "In6.Cu")
		(net "UPI_CPU0_CPU1_P2P2_DP<12>")
	)
	(segment
		(start 349.554546 -280.279856)
		(end 349.539814 -280.288492)
		(width 0.0889)
		(layer "In6.Cu")
		(net "UPI_CPU0_CPU1_P2P2_DP<12>")
	)
	(segment
		(start 100.740464 -277.20671)
		(end 100.755196 -277.198074)
		(width 0.0889)
		(layer "In6.Cu")
		(net "UPI_CPU0_CPU1_P2P2_DP<12>")
	)
	(segment
		(start 72.71131 -366.325912)
		(end 72.71131 -366.153446)
		(width 0.14732)
		(layer "In6.Cu")
		(net "UPI_CPU0_CPU1_P2P2_DP<12>")
	)
	(segment
		(start 345.028266 -284.832044)
		(end 345.028266 -284.847538)
		(width 0.0889)
		(layer "In6.Cu")
		(net "UPI_CPU0_CPU1_P2P2_DP<12>")
	)
	(segment
		(start 68.939918 -323.442838)
		(end 69.102478 -323.384672)
		(width 0.14732)
		(layer "In6.Cu")
		(net "UPI_CPU0_CPU1_P2P2_DP<12>")
	)
	(segment
		(start 97.279206 -290.220908)
		(end 97.279206 -289.913568)
		(width 0.0889)
		(layer "In6.Cu")
		(net "UPI_CPU0_CPU1_P2P2_DP<12>")
	)
	(segment
		(start 97.278698 -288.121598)
		(end 97.278698 -288.103056)
		(width 0.0889)
		(layer "In6.Cu")
		(net "UPI_CPU0_CPU1_P2P2_DP<12>")
	)
	(segment
		(start 101.694742 -275.570188)
		(end 101.70541 -275.563838)
		(width 0.0889)
		(layer "In6.Cu")
		(net "UPI_CPU0_CPU1_P2P2_DP<12>")
	)
	(segment
		(start 98.39706 -281.272742)
		(end 98.40595 -281.267662)
		(width 0.0889)
		(layer "In6.Cu")
		(net "UPI_CPU0_CPU1_P2P2_DP<12>")
	)
	(segment
		(start 343.909904 -288.422334)
		(end 343.901014 -288.427414)
		(width 0.0889)
		(layer "In6.Cu")
		(net "UPI_CPU0_CPU1_P2P2_DP<12>")
	)
	(segment
		(start 99.813872 -277.198836)
		(end 99.815396 -277.198074)
		(width 0.0889)
		(layer "In6.Cu")
		(net "UPI_CPU0_CPU1_P2P2_DP<12>")
	)
	(segment
		(start 314.886086 -323.75221)
		(end 313.85637 -326.237346)
		(width 0.14732)
		(layer "In6.Cu")
		(net "UPI_CPU0_CPU1_P2P2_DP<12>")
	)
	(segment
		(start 95.305372 -295.111678)
		(end 95.305372 -294.443658)
		(width 0.14732)
		(layer "In6.Cu")
		(net "UPI_CPU0_CPU1_P2P2_DP<12>")
	)
	(segment
		(start 69.738494 -321.753992)
		(end 78.274926 -313.217306)
		(width 0.14732)
		(layer "In6.Cu")
		(net "UPI_CPU0_CPU1_P2P2_DP<12>")
	)
	(segment
		(start 97.935796 -285.336996)
		(end 97.941892 -285.33344)
		(width 0.0889)
		(layer "In6.Cu")
		(net "UPI_CPU0_CPU1_P2P2_DP<12>")
	)
	(segment
		(start 313.85637 -326.237346)
		(end 306.987956 -333.10576)
		(width 0.14732)
		(layer "In6.Cu")
		(net "UPI_CPU0_CPU1_P2P2_DP<12>")
	)
	(segment
		(start 99.81819 -278.824436)
		(end 99.821492 -278.822404)
		(width 0.0889)
		(layer "In6.Cu")
		(net "UPI_CPU0_CPU1_P2P2_DP<12>")
	)
	(segment
		(start 98.688144 -280.793698)
		(end 98.688144 -280.778204)
		(width 0.0889)
		(layer "In6.Cu")
		(net "UPI_CPU0_CPU1_P2P2_DP<12>")
	)
	(segment
		(start 270.176752 -368.147092)
		(end 264.64006 -373.683784)
		(width 0.14732)
		(layer "In6.Cu")
		(net "UPI_CPU0_CPU1_P2P2_DP<12>")
	)
	(segment
		(start 94.776544 -298.773342)
		(end 94.710758 -298.614084)
		(width 0.14732)
		(layer "In6.Cu")
		(net "UPI_CPU0_CPU1_P2P2_DP<12>")
	)
	(segment
		(start 342.468962 -292.981888)
		(end 342.369902 -293.080948)
		(width 0.0889)
		(layer "In6.Cu")
		(net "UPI_CPU0_CPU1_P2P2_DP<12>")
	)
	(segment
		(start 97.935796 -285.985712)
		(end 97.926906 -285.980632)
		(width 0.0889)
		(layer "In6.Cu")
		(net "UPI_CPU0_CPU1_P2P2_DP<12>")
	)
	(segment
		(start 71.439024 -365.053626)
		(end 71.057516 -364.672118)
		(width 0.14732)
		(layer "In6.Cu")
		(net "UPI_CPU0_CPU1_P2P2_DP<12>")
	)
	(segment
		(start 95.450152 -293.930578)
		(end 95.305372 -293.785798)
		(width 0.14732)
		(layer "In6.Cu")
		(net "UPI_CPU0_CPU1_P2P2_DP<12>")
	)
	(segment
		(start 342.468962 -291.884608)
		(end 342.369902 -291.983668)
		(width 0.0889)
		(layer "In6.Cu")
		(net "UPI_CPU0_CPU1_P2P2_DP<12>")
	)
	(segment
		(start 341.541354 -299.104304)
		(end 340.26221 -300.383448)
		(width 0.14732)
		(layer "In6.Cu")
		(net "UPI_CPU0_CPU1_P2P2_DP<12>")
	)
	(segment
		(start 343.90965 -290.12642)
		(end 343.901522 -290.1315)
		(width 0.0889)
		(layer "In6.Cu")
		(net "UPI_CPU0_CPU1_P2P2_DP<12>")
	)
	(segment
		(start 97.046288 -290.51377)
		(end 97.061782 -290.498276)
		(width 0.0889)
		(layer "In6.Cu")
		(net "UPI_CPU0_CPU1_P2P2_DP<12>")
	)
	(segment
		(start 342.369902 -292.532308)
		(end 342.369902 -292.707568)
		(width 0.0889)
		(layer "In6.Cu")
		(net "UPI_CPU0_CPU1_P2P2_DP<12>")
	)
	(segment
		(start 344.088212 -289.645852)
		(end 344.088212 -289.807142)
		(width 0.0889)
		(layer "In6.Cu")
		(net "UPI_CPU0_CPU1_P2P2_DP<12>")
	)
	(segment
		(start 97.118932 -378.214636)
		(end 75.748642 -369.363244)
		(width 0.14732)
		(layer "In6.Cu")
		(net "UPI_CPU0_CPU1_P2P2_DP<12>")
	)
	(segment
		(start 343.618566 -288.898584)
		(end 343.618566 -289.114738)
		(width 0.0889)
		(layer "In6.Cu")
		(net "UPI_CPU0_CPU1_P2P2_DP<12>")
	)
	(segment
		(start 342.997536 -291.007546)
		(end 342.857074 -291.007546)
		(width 0.0889)
		(layer "In6.Cu")
		(net "UPI_CPU0_CPU1_P2P2_DP<12>")
	)
	(segment
		(start 98.688144 -282.405836)
		(end 98.688144 -282.390342)
		(width 0.0889)
		(layer "In6.Cu")
		(net "UPI_CPU0_CPU1_P2P2_DP<12>")
	)
	(segment
		(start 98.39706 -284.52826)
		(end 98.40595 -284.52318)
		(width 0.0889)
		(layer "In6.Cu")
		(net "UPI_CPU0_CPU1_P2P2_DP<12>")
	)
	(segment
		(start 342.369902 -292.158928)
		(end 342.468962 -292.257988)
		(width 0.0889)
		(layer "In6.Cu")
		(net "UPI_CPU0_CPU1_P2P2_DP<12>")
	)
	(segment
		(start 342.468962 -293.530528)
		(end 342.369902 -293.629588)
		(width 0.0889)
		(layer "In6.Cu")
		(net "UPI_CPU0_CPU1_P2P2_DP<12>")
	)
	(segment
		(start 98.875596 -282.730194)
		(end 98.874834 -282.729686)
		(width 0.0889)
		(layer "In6.Cu")
		(net "UPI_CPU0_CPU1_P2P2_DP<12>")
	)
	(segment
		(start 95.450152 -293.272718)
		(end 95.450152 -292.904418)
		(width 0.14732)
		(layer "In6.Cu")
		(net "UPI_CPU0_CPU1_P2P2_DP<12>")
	)
	(segment
		(start 346.735146 -280.279856)
		(end 346.720414 -280.288492)
		(width 0.0889)
		(layer "In6.Cu")
		(net "UPI_CPU0_CPU1_P2P2_DP<12>")
	)
	(segment
		(start 98.875596 -283.709364)
		(end 98.879406 -283.707078)
		(width 0.0889)
		(layer "In6.Cu")
		(net "UPI_CPU0_CPU1_P2P2_DP<12>")
	)
	(segment
		(start 350.135952 -279.693116)
		(end 350.157034 -279.615138)
		(width 0.0889)
		(layer "In6.Cu")
		(net "UPI_CPU0_CPU1_P2P2_DP<12>")
	)
	(segment
		(start 345.497912 -284.023816)
		(end 345.497912 -284.033722)
		(width 0.0889)
		(layer "In6.Cu")
		(net "UPI_CPU0_CPU1_P2P2_DP<12>")
	)
	(segment
		(start 68.275454 -324.847966)
		(end 68.462144 -324.45325)
		(width 0.14732)
		(layer "In6.Cu")
		(net "UPI_CPU0_CPU1_P2P2_DP<12>")
	)
	(segment
		(start 94.193614 -299.862748)
		(end 94.4499 -299.243242)
		(width 0.14732)
		(layer "In6.Cu")
		(net "UPI_CPU0_CPU1_P2P2_DP<12>")
	)
	(segment
		(start 95.037148 -298.144438)
		(end 95.20428 -297.740578)
		(width 0.14732)
		(layer "In6.Cu")
		(net "UPI_CPU0_CPU1_P2P2_DP<12>")
	)
	(segment
		(start 99.158298 -283.219906)
		(end 99.158298 -283.212286)
		(width 0.0889)
		(layer "In6.Cu")
		(net "UPI_CPU0_CPU1_P2P2_DP<12>")
	)
	(segment
		(start 104.075484 -274.809712)
		(end 104.231948 -275.08073)
		(width 0.0889)
		(layer "In6.Cu")
		(net "UPI_CPU0_CPU1_P2P2_DP<12>")
	)
	(segment
		(start 342.468962 -292.433248)
		(end 342.369902 -292.532308)
		(width 0.0889)
		(layer "In6.Cu")
		(net "UPI_CPU0_CPU1_P2P2_DP<12>")
	)
	(segment
		(start 99.806506 -278.83104)
		(end 99.813872 -278.826722)
		(width 0.0889)
		(layer "In6.Cu")
		(net "UPI_CPU0_CPU1_P2P2_DP<12>")
	)
	(segment
		(start 71.920862 -365.362998)
		(end 71.61149 -365.053626)
		(width 0.14732)
		(layer "In6.Cu")
		(net "UPI_CPU0_CPU1_P2P2_DP<12>")
	)
	(segment
		(start 342.857074 -291.007546)
		(end 342.733122 -291.131498)
		(width 0.0889)
		(layer "In6.Cu")
		(net "UPI_CPU0_CPU1_P2P2_DP<12>")
	)
	(segment
		(start 344.84945 -286.794702)
		(end 344.841322 -286.799274)
		(width 0.0889)
		(layer "In6.Cu")
		(net "UPI_CPU0_CPU1_P2P2_DP<12>")
	)
	(segment
		(start 101.037644 -276.708616)
		(end 101.037644 -276.700742)
		(width 0.0889)
		(layer "In6.Cu")
		(net "UPI_CPU0_CPU1_P2P2_DP<12>")
	)
	(segment
		(start 344.849704 -285.166816)
		(end 344.840814 -285.171896)
		(width 0.0889)
		(layer "In6.Cu")
		(net "UPI_CPU0_CPU1_P2P2_DP<12>")
	)
	(segment
		(start 69.231002 -322.827142)
		(end 69.738494 -321.753992)
		(width 0.14732)
		(layer "In6.Cu")
		(net "UPI_CPU0_CPU1_P2P2_DP<12>")
	)
	(segment
		(start 336.836766 -301.80153)
		(end 314.886086 -323.75221)
		(width 0.14732)
		(layer "In6.Cu")
		(net "UPI_CPU0_CPU1_P2P2_DP<12>")
	)
	(segment
		(start 95.450152 -295.256458)
		(end 95.305372 -295.111678)
		(width 0.14732)
		(layer "In6.Cu")
		(net "UPI_CPU0_CPU1_P2P2_DP<12>")
	)
	(segment
		(start 344.84056 -286.151066)
		(end 344.84945 -286.156146)
		(width 0.0889)
		(layer "In6.Cu")
		(net "UPI_CPU0_CPU1_P2P2_DP<12>")
	)
	(segment
		(start 342.369902 -292.707568)
		(end 342.468962 -292.806628)
		(width 0.0889)
		(layer "In6.Cu")
		(net "UPI_CPU0_CPU1_P2P2_DP<12>")
	)
	(segment
		(start 98.40595 -281.916378)
		(end 98.39706 -281.911298)
		(width 0.0889)
		(layer "In6.Cu")
		(net "UPI_CPU0_CPU1_P2P2_DP<12>")
	)
	(segment
		(start 95.305372 -297.177714)
		(end 95.305372 -295.769538)
		(width 0.14732)
		(layer "In6.Cu")
		(net "UPI_CPU0_CPU1_P2P2_DP<12>")
	)
	(segment
		(start 94.609666 -299.177202)
		(end 94.776544 -298.773342)
		(width 0.14732)
		(layer "In6.Cu")
		(net "UPI_CPU0_CPU1_P2P2_DP<12>")
	)
	(segment
		(start 75.748642 -369.363244)
		(end 73.501758 -367.11636)
		(width 0.14732)
		(layer "In6.Cu")
		(net "UPI_CPU0_CPU1_P2P2_DP<12>")
	)
	(segment
		(start 99.158298 -279.978358)
		(end 99.158298 -279.964134)
		(width 0.0889)
		(layer "In6.Cu")
		(net "UPI_CPU0_CPU1_P2P2_DP<12>")
	)
	(segment
		(start 342.369902 -293.629588)
		(end 342.369902 -293.804848)
		(width 0.0889)
		(layer "In6.Cu")
		(net "UPI_CPU0_CPU1_P2P2_DP<12>")
	)
	(segment
		(start 306.987956 -333.10576)
		(end 285.123128 -333.10576)
		(width 0.14732)
		(layer "In6.Cu")
		(net "UPI_CPU0_CPU1_P2P2_DP<12>")
	)
	(segment
		(start 100.098098 -278.336502)
		(end 100.098098 -278.322278)
		(width 0.0889)
		(layer "In6.Cu")
		(net "UPI_CPU0_CPU1_P2P2_DP<12>")
	)
	(segment
		(start 342.468962 -294.423338)
		(end 342.427052 -294.465248)
		(width 0.0889)
		(layer "In6.Cu")
		(net "UPI_CPU0_CPU1_P2P2_DP<12>")
	)
	(segment
		(start 96.808798 -289.078416)
		(end 96.808798 -288.917126)
		(width 0.0889)
		(layer "In6.Cu")
		(net "UPI_CPU0_CPU1_P2P2_DP<12>")
	)
	(segment
		(start 344.558112 -285.661354)
		(end 344.558112 -285.679896)
		(width 0.0889)
		(layer "In6.Cu")
		(net "UPI_CPU0_CPU1_P2P2_DP<12>")
	)
	(segment
		(start 95.305372 -293.417498)
		(end 95.450152 -293.272718)
		(width 0.14732)
		(layer "In6.Cu")
		(net "UPI_CPU0_CPU1_P2P2_DP<12>")
	)
	(segment
		(start 342.733122 -291.27196)
		(end 342.468962 -291.53612)
		(width 0.0889)
		(layer "In6.Cu")
		(net "UPI_CPU0_CPU1_P2P2_DP<12>")
	)
	(segment
		(start 95.20428 -297.740578)
		(end 95.13824 -297.58132)
		(width 0.14732)
		(layer "In6.Cu")
		(net "UPI_CPU0_CPU1_P2P2_DP<12>")
	)
	(segment
		(start 96.98736 -288.597848)
		(end 96.99625 -288.592768)
		(width 0.0889)
		(layer "In6.Cu")
		(net "UPI_CPU0_CPU1_P2P2_DP<12>")
	)
	(segment
		(start 97.926906 -285.342076)
		(end 97.935796 -285.336996)
		(width 0.0889)
		(layer "In6.Cu")
		(net "UPI_CPU0_CPU1_P2P2_DP<12>")
	)
	(segment
		(start 101.50729 -275.905468)
		(end 101.50729 -275.88337)
		(width 0.0889)
		(layer "In6.Cu")
		(net "UPI_CPU0_CPU1_P2P2_DP<12>")
	)
	(segment
		(start 125.505972 -382.425448)
		(end 97.118932 -378.214636)
		(width 0.14732)
		(layer "In6.Cu")
		(net "UPI_CPU0_CPU1_P2P2_DP<12>")
	)
	(segment
		(start 99.815396 -277.84679)
		(end 99.806506 -277.84171)
		(width 0.0889)
		(layer "In6.Cu")
		(net "UPI_CPU0_CPU1_P2P2_DP<12>")
	)
	(segment
		(start 73.020174 -366.634776)
		(end 72.71131 -366.325912)
		(width 0.14732)
		(layer "In6.Cu")
		(net "UPI_CPU0_CPU1_P2P2_DP<12>")
	)
	(segment
		(start 67.36588 -328.13371)
		(end 68.275454 -324.847966)
		(width 0.14732)
		(layer "In6.Cu")
		(net "UPI_CPU0_CPU1_P2P2_DP<12>")
	)
	(segment
		(start 97.748344 -287.304734)
		(end 97.748344 -287.28924)
		(width 0.0889)
		(layer "In6.Cu")
		(net "UPI_CPU0_CPU1_P2P2_DP<12>")
	)
	(segment
		(start 344.088466 -288.087562)
		(end 344.088466 -288.103056)
		(width 0.0889)
		(layer "In6.Cu")
		(net "UPI_CPU0_CPU1_P2P2_DP<12>")
	)
	(segment
		(start 98.866706 -283.714444)
		(end 98.875596 -283.709364)
		(width 0.0889)
		(layer "In6.Cu")
		(net "UPI_CPU0_CPU1_P2P2_DP<12>")
	)
	(segment
		(start 344.840814 -285.171896)
		(end 344.834718 -285.175452)
		(width 0.0889)
		(layer "In6.Cu")
		(net "UPI_CPU0_CPU1_P2P2_DP<12>")
	)
	(segment
		(start 342.427052 -294.465248)
		(end 342.427052 -294.487346)
		(width 0.0889)
		(layer "In6.Cu")
		(net "UPI_CPU0_CPU1_P2P2_DP<12>")
	)
	(segment
		(start 94.710758 -298.614084)
		(end 94.877636 -298.210478)
		(width 0.14732)
		(layer "In6.Cu")
		(net "UPI_CPU0_CPU1_P2P2_DP<12>")
	)
	(segment
		(start 103.89489 -274.820888)
		(end 103.98633 -274.785836)
		(width 0.0889)
		(layer "In6.Cu")
		(net "UPI_CPU0_CPU1_P2P2_DP<12>")
	)
	(segment
		(start 343.784174 -290.220908)
		(end 342.997536 -291.007546)
		(width 0.0889)
		(layer "In6.Cu")
		(net "UPI_CPU0_CPU1_P2P2_DP<12>")
	)
	(segment
		(start 279.416256 -335.469484)
		(end 270.176752 -344.708988)
		(width 0.14732)
		(layer "In6.Cu")
		(net "UPI_CPU0_CPU1_P2P2_DP<12>")
	)
	(segment
		(start 66.709798 -354.175568)
		(end 66.709798 -334.796892)
		(width 0.14732)
		(layer "In6.Cu")
		(net "UPI_CPU0_CPU1_P2P2_DP<12>")
	)
	(segment
		(start 94.4499 -299.243242)
		(end 94.609666 -299.177202)
		(width 0.14732)
		(layer "In6.Cu")
		(net "UPI_CPU0_CPU1_P2P2_DP<12>")
	)
	(segment
		(start 340.26221 -300.383448)
		(end 336.836766 -301.80153)
		(width 0.14732)
		(layer "In6.Cu")
		(net "UPI_CPU0_CPU1_P2P2_DP<12>")
	)
	(segment
		(start 73.19264 -366.634776)
		(end 73.020174 -366.634776)
		(width 0.14732)
		(layer "In6.Cu")
		(net "UPI_CPU0_CPU1_P2P2_DP<12>")
	)
	(segment
		(start 102.526846 -274.748752)
		(end 102.540816 -274.75688)
		(width 0.0889)
		(layer "In6.Cu")
		(net "UPI_CPU0_CPU1_P2P2_DP<12>")
	)
	(segment
		(start 270.176752 -344.708988)
		(end 270.176752 -368.147092)
		(width 0.14732)
		(layer "In6.Cu")
		(net "UPI_CPU0_CPU1_P2P2_DP<12>")
	)
	(segment
		(start 346.25026 -282.081478)
		(end 346.25915 -282.086558)
		(width 0.0889)
		(layer "In6.Cu")
		(net "UPI_CPU0_CPU1_P2P2_DP<12>")
	)
	(segment
		(start 103.478076 -274.755864)
		(end 103.544878 -274.794472)
		(width 0.0889)
		(layer "In6.Cu")
		(net "UPI_CPU0_CPU1_P2P2_DP<12>")
	)
	(segment
		(start 100.759514 -277.195534)
		(end 100.761292 -277.194518)
		(width 0.0889)
		(layer "In6.Cu")
		(net "UPI_CPU0_CPU1_P2P2_DP<12>")
	)
	(segment
		(start 345.968066 -281.576526)
		(end 345.968066 -281.607514)
		(width 0.0889)
		(layer "In6.Cu")
		(net "UPI_CPU0_CPU1_P2P2_DP<12>")
	)
	(segment
		(start 350.666812 -279.955498)
		(end 350.666812 -279.97277)
		(width 0.0889)
		(layer "In6.Cu")
		(net "UPI_CPU0_CPU1_P2P2_DP<12>")
	)
	(segment
		(start 95.305372 -292.254686)
		(end 97.046288 -290.51377)
		(width 0.14732)
		(layer "In6.Cu")
		(net "UPI_CPU0_CPU1_P2P2_DP<12>")
	)
	(segment
		(start 72.402192 -365.844328)
		(end 72.229726 -365.844328)
		(width 0.14732)
		(layer "In6.Cu")
		(net "UPI_CPU0_CPU1_P2P2_DP<12>")
	)
	(segment
		(start 342.468962 -291.53612)
		(end 342.468962 -291.884608)
		(width 0.0889)
		(layer "In6.Cu")
		(net "UPI_CPU0_CPU1_P2P2_DP<12>")
	)
	(segment
		(start 72.229726 -365.844328)
		(end 71.920862 -365.535464)
		(width 0.14732)
		(layer "In6.Cu")
		(net "UPI_CPU0_CPU1_P2P2_DP<12>")
	)
	(segment
		(start 97.45726 -287.783778)
		(end 97.46615 -287.778698)
		(width 0.0889)
		(layer "In6.Cu")
		(net "UPI_CPU0_CPU1_P2P2_DP<12>")
	)
	(segment
		(start 346.25915 -281.097482)
		(end 346.25026 -281.102562)
		(width 0.0889)
		(layer "In6.Cu")
		(net "UPI_CPU0_CPU1_P2P2_DP<12>")
	)
	(segment
		(start 342.369902 -293.804848)
		(end 342.468962 -293.903908)
		(width 0.0889)
		(layer "In6.Cu")
		(net "UPI_CPU0_CPU1_P2P2_DP<12>")
	)
	(segment
		(start 78.274926 -313.217306)
		(end 93.641164 -300.607476)
		(width 0.14732)
		(layer "In6.Cu")
		(net "UPI_CPU0_CPU1_P2P2_DP<12>")
	)
	(segment
		(start 342.733122 -291.131498)
		(end 342.733122 -291.27196)
		(width 0.0889)
		(layer "In6.Cu")
		(net "UPI_CPU0_CPU1_P2P2_DP<12>")
	)
	(segment
		(start 97.926906 -286.969962)
		(end 97.942146 -286.961072)
		(width 0.0889)
		(layer "In6.Cu")
		(net "UPI_CPU0_CPU1_P2P2_DP<12>")
	)
	(segment
		(start 342.468962 -292.257988)
		(end 342.468962 -292.433248)
		(width 0.0889)
		(layer "In6.Cu")
		(net "UPI_CPU0_CPU1_P2P2_DP<12>")
	)
	(segment
		(start 99.627944 -279.165812)
		(end 99.627944 -279.150318)
		(width 0.0889)
		(layer "In6.Cu")
		(net "UPI_CPU0_CPU1_P2P2_DP<12>")
	)
	(segment
		(start 162.003232 -382.425448)
		(end 125.505972 -382.425448)
		(width 0.14732)
		(layer "In6.Cu")
		(net "UPI_CPU0_CPU1_P2P2_DP<12>")
	)
	(segment
		(start 99.33686 -279.644856)
		(end 99.34575 -279.639776)
		(width 0.0889)
		(layer "In6.Cu")
		(net "UPI_CPU0_CPU1_P2P2_DP<12>")
	)
	(segment
		(start 95.13824 -297.58132)
		(end 95.305372 -297.177714)
		(width 0.14732)
		(layer "In6.Cu")
		(net "UPI_CPU0_CPU1_P2P2_DP<12>")
	)
	(segment
		(start 95.450152 -294.298878)
		(end 95.450152 -293.930578)
		(width 0.14732)
		(layer "In6.Cu")
		(net "UPI_CPU0_CPU1_P2P2_DP<12>")
	)
	(segment
		(start 97.279206 -289.913568)
		(end 97.277682 -289.732974)
		(width 0.0889)
		(layer "In6.Cu")
		(net "UPI_CPU0_CPU1_P2P2_DP<12>")
	)
	(segment
		(start 342.369902 -293.080948)
		(end 342.369902 -293.256208)
		(width 0.0889)
		(layer "In6.Cu")
		(net "UPI_CPU0_CPU1_P2P2_DP<12>")
	)
	(segment
		(start 348.614746 -280.279856)
		(end 348.600014 -280.288492)
		(width 0.0889)
		(layer "In6.Cu")
		(net "UPI_CPU0_CPU1_P2P2_DP<12>")
	)
	(segment
		(start 342.369902 -293.256208)
		(end 342.468962 -293.355268)
		(width 0.0889)
		(layer "In6.Cu")
		(net "UPI_CPU0_CPU1_P2P2_DP<12>")
	)
	(segment
		(start 100.755196 -277.198074)
		(end 100.757482 -277.196804)
		(width 0.0889)
		(layer "In6.Cu")
		(net "UPI_CPU0_CPU1_P2P2_DP<12>")
	)
	(segment
		(start 72.71131 -366.153446)
		(end 72.402192 -365.844328)
		(width 0.14732)
		(layer "In6.Cu")
		(net "UPI_CPU0_CPU1_P2P2_DP<12>")
	)
	(segment
		(start 101.037898 -276.708616)
		(end 101.037644 -276.708616)
		(width 0.0889)
		(layer "In6.Cu")
		(net "UPI_CPU0_CPU1_P2P2_DP<12>")
	)
	(segment
		(start 285.123128 -333.10576)
		(end 279.416256 -335.469484)
		(width 0.14732)
		(layer "In6.Cu")
		(net "UPI_CPU0_CPU1_P2P2_DP<12>")
	)
	(segment
		(start 97.061782 -290.498276)
		(end 97.061782 -290.438332)
		(width 0.0889)
		(layer "In6.Cu")
		(net "UPI_CPU0_CPU1_P2P2_DP<12>")
	)
	(segment
		(start 345.967812 -283.201364)
		(end 345.967812 -283.219906)
		(width 0.0889)
		(layer "In6.Cu")
		(net "UPI_CPU0_CPU1_P2P2_DP<12>")
	)
	(segment
		(start 69.102478 -323.384672)
		(end 69.289168 -322.989448)
		(width 0.14732)
		(layer "In6.Cu")
		(net "UPI_CPU0_CPU1_P2P2_DP<12>")
	)
	(segment
		(start 98.874834 -282.729686)
		(end 98.866706 -282.725114)
		(width 0.0889)
		(layer "In6.Cu")
		(net "UPI_CPU0_CPU1_P2P2_DP<12>")
	)
	(segment
		(start 71.920862 -365.535464)
		(end 71.920862 -365.362998)
		(width 0.14732)
		(layer "In6.Cu")
		(net "UPI_CPU0_CPU1_P2P2_DP<12>")
	)
	(segment
		(start 68.462144 -324.45325)
		(end 68.624704 -324.395084)
		(width 0.14732)
		(layer "In6.Cu")
		(net "UPI_CPU0_CPU1_P2P2_DP<12>")
	)
	(segment
		(start 342.369902 -291.983668)
		(end 342.369902 -292.158928)
		(width 0.0889)
		(layer "In6.Cu")
		(net "UPI_CPU0_CPU1_P2P2_DP<12>")
	)
	(arc
		(start 99.34575 -279.639776)
		(mid 99.548573 -279.439545)
		(end 99.627944 -279.165812)
		(width 0.0889)
		(layer "In6.Cu")
		(net "UPI_CPU0_CPU1_P2P2_DP<12>")
	)
	(arc
		(start 346.720414 -280.288492)
		(mid 346.516933 -280.489296)
		(end 346.437712 -280.76398)
		(width 0.0889)
		(layer "In6.Cu")
		(net "UPI_CPU0_CPU1_P2P2_DP<12>")
	)
	(arc
		(start 97.277682 -289.732974)
		(mid 97.229724 -289.521049)
		(end 97.098104 -289.348164)
		(width 0.0889)
		(layer "In6.Cu")
		(net "UPI_CPU0_CPU1_P2P2_DP<12>")
	)
	(arc
		(start 350.666812 -279.97277)
		(mid 350.614542 -280.155135)
		(end 350.479614 -280.288492)
		(width 0.0889)
		(layer "In6.Cu")
		(net "UPI_CPU0_CPU1_P2P2_DP<12>")
	)
	(arc
		(start 98.40595 -281.267662)
		(mid 98.608773 -281.067431)
		(end 98.688144 -280.793698)
		(width 0.0889)
		(layer "In6.Cu")
		(net "UPI_CPU0_CPU1_P2P2_DP<12>")
	)
	(arc
		(start 346.437458 -282.418028)
		(mid 346.386965 -282.594006)
		(end 346.25915 -282.725114)
		(width 0.0889)
		(layer "In6.Cu")
		(net "UPI_CPU0_CPU1_P2P2_DP<12>")
	)
	(arc
		(start 98.688144 -284.033722)
		(mid 98.735823 -283.850822)
		(end 98.866706 -283.714444)
		(width 0.0889)
		(layer "In6.Cu")
		(net "UPI_CPU0_CPU1_P2P2_DP<12>")
	)
	(arc
		(start 99.815396 -277.198074)
		(mid 100.002594 -277.147931)
		(end 100.189792 -277.198074)
		(width 0.0889)
		(layer "In6.Cu")
		(net "UPI_CPU0_CPU1_P2P2_DP<12>")
	)
	(arc
		(start 97.926906 -285.980632)
		(mid 97.748188 -285.661354)
		(end 97.926906 -285.342076)
		(width 0.0889)
		(layer "In6.Cu")
		(net "UPI_CPU0_CPU1_P2P2_DP<12>")
	)
	(arc
		(start 350.479614 -280.288492)
		(mid 350.292416 -280.338635)
		(end 350.105218 -280.288492)
		(width 0.0889)
		(layer "In6.Cu")
		(net "UPI_CPU0_CPU1_P2P2_DP<12>")
	)
	(arc
		(start 349.165418 -280.288492)
		(mid 348.891189 -280.212567)
		(end 348.614746 -280.279856)
		(width 0.0889)
		(layer "In6.Cu")
		(net "UPI_CPU0_CPU1_P2P2_DP<12>")
	)
	(arc
		(start 98.688144 -282.390342)
		(mid 98.608774 -282.116608)
		(end 98.40595 -281.916378)
		(width 0.0889)
		(layer "In6.Cu")
		(net "UPI_CPU0_CPU1_P2P2_DP<12>")
	)
	(arc
		(start 97.748344 -287.28924)
		(mid 97.796023 -287.10634)
		(end 97.926906 -286.969962)
		(width 0.0889)
		(layer "In6.Cu")
		(net "UPI_CPU0_CPU1_P2P2_DP<12>")
	)
	(arc
		(start 98.866706 -282.725114)
		(mid 98.735792 -282.588754)
		(end 98.688144 -282.405836)
		(width 0.0889)
		(layer "In6.Cu")
		(net "UPI_CPU0_CPU1_P2P2_DP<12>")
	)
	(arc
		(start 97.098104 -289.348164)
		(mid 97.047401 -289.310181)
		(end 96.992948 -289.277806)
		(width 0.0889)
		(layer "In6.Cu")
		(net "UPI_CPU0_CPU1_P2P2_DP<12>")
	)
	(arc
		(start 345.31046 -284.35808)
		(mid 345.107637 -284.558311)
		(end 345.028266 -284.832044)
		(width 0.0889)
		(layer "In6.Cu")
		(net "UPI_CPU0_CPU1_P2P2_DP<12>")
	)
	(arc
		(start 344.834718 -285.175452)
		(mid 344.632131 -285.381803)
		(end 344.558112 -285.661354)
		(width 0.0889)
		(layer "In6.Cu")
		(net "UPI_CPU0_CPU1_P2P2_DP<12>")
	)
	(arc
		(start 97.278698 -288.103056)
		(mid 97.326377 -287.920156)
		(end 97.45726 -287.783778)
		(width 0.0889)
		(layer "In6.Cu")
		(net "UPI_CPU0_CPU1_P2P2_DP<12>")
	)
	(arc
		(start 98.887788 -283.702252)
		(mid 99.086016 -283.496404)
		(end 99.158298 -283.219906)
		(width 0.0889)
		(layer "In6.Cu")
		(net "UPI_CPU0_CPU1_P2P2_DP<12>")
	)
	(arc
		(start 348.600014 -280.288492)
		(mid 348.412816 -280.338635)
		(end 348.225618 -280.288492)
		(width 0.0889)
		(layer "In6.Cu")
		(net "UPI_CPU0_CPU1_P2P2_DP<12>")
	)
	(arc
		(start 344.84945 -286.156146)
		(mid 345.028047 -286.475424)
		(end 344.84945 -286.794702)
		(width 0.0889)
		(layer "In6.Cu")
		(net "UPI_CPU0_CPU1_P2P2_DP<12>")
	)
	(arc
		(start 345.78036 -283.544264)
		(mid 345.576025 -283.746869)
		(end 345.497912 -284.023816)
		(width 0.0889)
		(layer "In6.Cu")
		(net "UPI_CPU0_CPU1_P2P2_DP<12>")
	)
	(arc
		(start 98.875596 -280.453846)
		(mid 99.079077 -280.253042)
		(end 99.158298 -279.978358)
		(width 0.0889)
		(layer "In6.Cu")
		(net "UPI_CPU0_CPU1_P2P2_DP<12>")
	)
	(arc
		(start 99.806506 -277.84171)
		(mid 99.627788 -277.522432)
		(end 99.806506 -277.203154)
		(width 0.0889)
		(layer "In6.Cu")
		(net "UPI_CPU0_CPU1_P2P2_DP<12>")
	)
	(arc
		(start 100.189792 -277.198074)
		(mid 100.463991 -277.273909)
		(end 100.740464 -277.20671)
		(width 0.0889)
		(layer "In6.Cu")
		(net "UPI_CPU0_CPU1_P2P2_DP<12>")
	)
	(arc
		(start 101.225096 -276.384004)
		(mid 101.429074 -276.181828)
		(end 101.50729 -275.905468)
		(width 0.0889)
		(layer "In6.Cu")
		(net "UPI_CPU0_CPU1_P2P2_DP<12>")
	)
	(arc
		(start 345.967812 -283.219906)
		(mid 345.920133 -283.402806)
		(end 345.78925 -283.539184)
		(width 0.0889)
		(layer "In6.Cu")
		(net "UPI_CPU0_CPU1_P2P2_DP<12>")
	)
	(arc
		(start 344.37066 -287.613598)
		(mid 344.167837 -287.813829)
		(end 344.088466 -288.087562)
		(width 0.0889)
		(layer "In6.Cu")
		(net "UPI_CPU0_CPU1_P2P2_DP<12>")
	)
	(arc
		(start 98.688144 -280.778204)
		(mid 98.735823 -280.595304)
		(end 98.866706 -280.458926)
		(width 0.0889)
		(layer "In6.Cu")
		(net "UPI_CPU0_CPU1_P2P2_DP<12>")
	)
	(arc
		(start 343.901014 -288.427414)
		(mid 343.698728 -288.626395)
		(end 343.618566 -288.898584)
		(width 0.0889)
		(layer "In6.Cu")
		(net "UPI_CPU0_CPU1_P2P2_DP<12>")
	)
	(arc
		(start 344.088212 -289.807142)
		(mid 344.040533 -289.990042)
		(end 343.90965 -290.12642)
		(width 0.0889)
		(layer "In6.Cu")
		(net "UPI_CPU0_CPU1_P2P2_DP<12>")
	)
	(arc
		(start 101.037644 -276.700742)
		(mid 101.089871 -276.517824)
		(end 101.225096 -276.384004)
		(width 0.0889)
		(layer "In6.Cu")
		(net "UPI_CPU0_CPU1_P2P2_DP<12>")
	)
	(arc
		(start 98.39706 -281.911298)
		(mid 98.218584 -281.59202)
		(end 98.39706 -281.272742)
		(width 0.0889)
		(layer "In6.Cu")
		(net "UPI_CPU0_CPU1_P2P2_DP<12>")
	)
	(arc
		(start 344.558112 -285.679896)
		(mid 344.638274 -285.952085)
		(end 344.84056 -286.151066)
		(width 0.0889)
		(layer "In6.Cu")
		(net "UPI_CPU0_CPU1_P2P2_DP<12>")
	)
	(arc
		(start 345.968066 -281.607514)
		(mid 346.047436 -281.881248)
		(end 346.25026 -282.081478)
		(width 0.0889)
		(layer "In6.Cu")
		(net "UPI_CPU0_CPU1_P2P2_DP<12>")
	)
	(arc
		(start 101.50729 -275.88337)
		(mid 101.560345 -275.702433)
		(end 101.694742 -275.570188)
		(width 0.0889)
		(layer "In6.Cu")
		(net "UPI_CPU0_CPU1_P2P2_DP<12>")
	)
	(arc
		(start 344.558112 -287.28924)
		(mid 344.510433 -287.47214)
		(end 344.37955 -287.608518)
		(width 0.0889)
		(layer "In6.Cu")
		(net "UPI_CPU0_CPU1_P2P2_DP<12>")
	)
	(arc
		(start 344.088466 -288.103056)
		(mid 344.040787 -288.285956)
		(end 343.909904 -288.422334)
		(width 0.0889)
		(layer "In6.Cu")
		(net "UPI_CPU0_CPU1_P2P2_DP<12>")
	)
	(arc
		(start 345.028266 -284.847538)
		(mid 344.980587 -285.030438)
		(end 344.849704 -285.166816)
		(width 0.0889)
		(layer "In6.Cu")
		(net "UPI_CPU0_CPU1_P2P2_DP<12>")
	)
	(arc
		(start 96.99625 -288.592768)
		(mid 97.198536 -288.393787)
		(end 97.278698 -288.121598)
		(width 0.0889)
		(layer "In6.Cu")
		(net "UPI_CPU0_CPU1_P2P2_DP<12>")
	)
	(arc
		(start 96.992948 -289.277806)
		(mid 96.883801 -289.193878)
		(end 96.808798 -289.078416)
		(width 0.0889)
		(layer "In6.Cu")
		(net "UPI_CPU0_CPU1_P2P2_DP<12>")
	)
	(arc
		(start 347.285818 -280.288492)
		(mid 347.011589 -280.212567)
		(end 346.735146 -280.279856)
		(width 0.0889)
		(layer "In6.Cu")
		(net "UPI_CPU0_CPU1_P2P2_DP<12>")
	)
	(arc
		(start 350.157034 -279.615138)
		(mid 350.32113 -279.590791)
		(end 350.479614 -279.639776)
		(width 0.0889)
		(layer "In6.Cu")
		(net "UPI_CPU0_CPU1_P2P2_DP<12>")
	)
	(arc
		(start 98.40595 -284.52318)
		(mid 98.608773 -284.322949)
		(end 98.688144 -284.049216)
		(width 0.0889)
		(layer "In6.Cu")
		(net "UPI_CPU0_CPU1_P2P2_DP<12>")
	)
	(arc
		(start 99.158298 -283.212286)
		(mid 99.080669 -282.933873)
		(end 98.875596 -282.730194)
		(width 0.0889)
		(layer "In6.Cu")
		(net "UPI_CPU0_CPU1_P2P2_DP<12>")
	)
	(arc
		(start 346.437458 -282.395676)
		(mid 346.437625 -282.406852)
		(end 346.437458 -282.418028)
		(width 0.0889)
		(layer "In6.Cu")
		(net "UPI_CPU0_CPU1_P2P2_DP<12>")
	)
	(arc
		(start 346.437712 -280.778204)
		(mid 346.390033 -280.961104)
		(end 346.25915 -281.097482)
		(width 0.0889)
		(layer "In6.Cu")
		(net "UPI_CPU0_CPU1_P2P2_DP<12>")
	)
	(arc
		(start 97.46615 -287.778698)
		(mid 97.668973 -287.578467)
		(end 97.748344 -287.304734)
		(width 0.0889)
		(layer "In6.Cu")
		(net "UPI_CPU0_CPU1_P2P2_DP<12>")
	)
	(arc
		(start 346.25026 -281.102562)
		(mid 346.047437 -281.302793)
		(end 345.968066 -281.576526)
		(width 0.0889)
		(layer "In6.Cu")
		(net "UPI_CPU0_CPU1_P2P2_DP<12>")
	)
	(arc
		(start 343.904062 -289.446462)
		(mid 344.013209 -289.53039)
		(end 344.088212 -289.645852)
		(width 0.0889)
		(layer "In6.Cu")
		(net "UPI_CPU0_CPU1_P2P2_DP<12>")
	)
	(arc
		(start 101.70541 -275.563838)
		(mid 101.904794 -275.357958)
		(end 101.977444 -275.08073)
		(width 0.0889)
		(layer "In6.Cu")
		(net "UPI_CPU0_CPU1_P2P2_DP<12>")
	)
	(arc
		(start 344.84056 -286.799782)
		(mid 344.636225 -287.002387)
		(end 344.558112 -287.279334)
		(width 0.0889)
		(layer "In6.Cu")
		(net "UPI_CPU0_CPU1_P2P2_DP<12>")
	)
	(arc
		(start 98.218498 -286.4612)
		(mid 98.139279 -286.186515)
		(end 97.935796 -285.985712)
		(width 0.0889)
		(layer "In6.Cu")
		(net "UPI_CPU0_CPU1_P2P2_DP<12>")
	)
	(arc
		(start 99.627944 -279.150318)
		(mid 99.675623 -278.967418)
		(end 99.806506 -278.83104)
		(width 0.0889)
		(layer "In6.Cu")
		(net "UPI_CPU0_CPU1_P2P2_DP<12>")
	)
	(arc
		(start 347.660214 -280.288492)
		(mid 347.473016 -280.338635)
		(end 347.285818 -280.288492)
		(width 0.0889)
		(layer "In6.Cu")
		(net "UPI_CPU0_CPU1_P2P2_DP<12>")
	)
	(arc
		(start 99.158298 -279.964134)
		(mid 99.205977 -279.781234)
		(end 99.33686 -279.644856)
		(width 0.0889)
		(layer "In6.Cu")
		(net "UPI_CPU0_CPU1_P2P2_DP<12>")
	)
	(arc
		(start 100.098098 -278.322278)
		(mid 100.018879 -278.047593)
		(end 99.815396 -277.84679)
		(width 0.0889)
		(layer "In6.Cu")
		(net "UPI_CPU0_CPU1_P2P2_DP<12>")
	)
	(arc
		(start 350.479614 -279.639776)
		(mid 350.614547 -279.77313)
		(end 350.666812 -279.955498)
		(width 0.0889)
		(layer "In6.Cu")
		(net "UPI_CPU0_CPU1_P2P2_DP<12>")
	)
	(arc
		(start 97.941892 -286.961326)
		(mid 98.144479 -286.754975)
		(end 98.218498 -286.475424)
		(width 0.0889)
		(layer "In6.Cu")
		(net "UPI_CPU0_CPU1_P2P2_DP<12>")
	)
	(arc
		(start 346.25915 -282.086558)
		(mid 346.387469 -282.21853)
		(end 346.437458 -282.395676)
		(width 0.0889)
		(layer "In6.Cu")
		(net "UPI_CPU0_CPU1_P2P2_DP<12>")
	)
	(arc
		(start 349.539814 -280.288492)
		(mid 349.352616 -280.338635)
		(end 349.165418 -280.288492)
		(width 0.0889)
		(layer "In6.Cu")
		(net "UPI_CPU0_CPU1_P2P2_DP<12>")
	)
	(arc
		(start 350.105218 -280.288492)
		(mid 349.830989 -280.212567)
		(end 349.554546 -280.279856)
		(width 0.0889)
		(layer "In6.Cu")
		(net "UPI_CPU0_CPU1_P2P2_DP<12>")
	)
	(arc
		(start 101.977444 -275.068284)
		(mid 102.162327 -274.757555)
		(end 102.523798 -274.747228)
		(width 0.0889)
		(layer "In6.Cu")
		(net "UPI_CPU0_CPU1_P2P2_DP<12>")
	)
	(arc
		(start 96.808798 -288.917126)
		(mid 96.856477 -288.734226)
		(end 96.98736 -288.597848)
		(width 0.0889)
		(layer "In6.Cu")
		(net "UPI_CPU0_CPU1_P2P2_DP<12>")
	)
	(arc
		(start 343.901522 -290.1315)
		(mid 343.839916 -290.172356)
		(end 343.784174 -290.220908)
		(width 0.0889)
		(layer "In6.Cu")
		(net "UPI_CPU0_CPU1_P2P2_DP<12>")
	)
	(arc
		(start 343.618566 -289.114738)
		(mid 343.729904 -289.307638)
		(end 343.904062 -289.446462)
		(width 0.0889)
		(layer "In6.Cu")
		(net "UPI_CPU0_CPU1_P2P2_DP<12>")
	)
	(arc
		(start 102.540816 -274.75688)
		(mid 102.822734 -274.831827)
		(end 103.104442 -274.756118)
		(width 0.0889)
		(layer "In6.Cu")
		(net "UPI_CPU0_CPU1_P2P2_DP<12>")
	)
	(arc
		(start 103.544878 -274.794472)
		(mid 103.716892 -274.847427)
		(end 103.89489 -274.820888)
		(width 0.0889)
		(layer "In6.Cu")
		(net "UPI_CPU0_CPU1_P2P2_DP<12>")
	)
	(arc
		(start 346.25026 -282.730194)
		(mid 346.047974 -282.929175)
		(end 345.967812 -283.201364)
		(width 0.0889)
		(layer "In6.Cu")
		(net "UPI_CPU0_CPU1_P2P2_DP<12>")
	)
	(arc
		(start 97.941892 -285.33344)
		(mid 98.144479 -285.127089)
		(end 98.218498 -284.847538)
		(width 0.0889)
		(layer "In6.Cu")
		(net "UPI_CPU0_CPU1_P2P2_DP<12>")
	)
	(arc
		(start 103.104442 -274.756118)
		(mid 103.291213 -274.705931)
		(end 103.478076 -274.755864)
		(width 0.0889)
		(layer "In6.Cu")
		(net "UPI_CPU0_CPU1_P2P2_DP<12>")
	)
	(arc
		(start 345.497912 -284.033722)
		(mid 345.450233 -284.216622)
		(end 345.31935 -284.353)
		(width 0.0889)
		(layer "In6.Cu")
		(net "UPI_CPU0_CPU1_P2P2_DP<12>")
	)
	(arc
		(start 100.761292 -277.194518)
		(mid 100.963879 -276.988167)
		(end 101.037898 -276.708616)
		(width 0.0889)
		(layer "In6.Cu")
		(net "UPI_CPU0_CPU1_P2P2_DP<12>")
	)
	(arc
		(start 348.225618 -280.288492)
		(mid 347.951389 -280.212567)
		(end 347.674946 -280.279856)
		(width 0.0889)
		(layer "In6.Cu")
		(net "UPI_CPU0_CPU1_P2P2_DP<12>")
	)
	(arc
		(start 99.821492 -278.822404)
		(mid 100.024079 -278.616053)
		(end 100.098098 -278.336502)
		(width 0.0889)
		(layer "In6.Cu")
		(net "UPI_CPU0_CPU1_P2P2_DP<12>")
	)
	(arc
		(start 98.218498 -284.847538)
		(mid 98.266177 -284.664638)
		(end 98.39706 -284.52826)
		(width 0.0889)
		(layer "In6.Cu")
		(net "UPI_CPU0_CPU1_P2P2_DP<12>")
	)
	(segment
		(start 348.412562 -281.591766)
		(end 348.412816 -281.59202)
		(width 0.13208)
		(layer "F.Cu")
		(net "UPI_CPU0_CPU1_P2P2_DP<11>")
	)
	(segment
		(start 98.123248 -282.405582)
		(end 98.122994 -282.405836)
		(width 0.13208)
		(layer "F.Cu")
		(net "UPI_CPU0_CPU1_P2P2_DP<11>")
	)
	(segment
		(start 98.123248 -281.869896)
		(end 98.123248 -282.405582)
		(width 0.13208)
		(layer "F.Cu")
		(net "UPI_CPU0_CPU1_P2P2_DP<11>")
	)
	(segment
		(start 348.412562 -281.05608)
		(end 348.412562 -281.591766)
		(width 0.13208)
		(layer "F.Cu")
		(net "UPI_CPU0_CPU1_P2P2_DP<11>")
	)
	(segment
		(start 347.19006 -282.081478)
		(end 347.19895 -282.086558)
		(width 0.0889)
		(layer "In6.Cu")
		(net "UPI_CPU0_CPU1_P2P2_DP<11>")
	)
	(segment
		(start 96.04756 -288.597848)
		(end 96.05645 -288.592768)
		(width 0.0889)
		(layer "In6.Cu")
		(net "UPI_CPU0_CPU1_P2P2_DP<11>")
	)
	(segment
		(start 80.070198 -310.495696)
		(end 80.241648 -310.51246)
		(width 0.14732)
		(layer "In6.Cu")
		(net "UPI_CPU0_CPU1_P2P2_DP<11>")
	)
	(segment
		(start 96.987106 -286.969962)
		(end 96.995996 -286.964882)
		(width 0.0889)
		(layer "In6.Cu")
		(net "UPI_CPU0_CPU1_P2P2_DP<11>")
	)
	(segment
		(start 343.262204 -297.473116)
		(end 342.495886 -299.324776)
		(width 0.14732)
		(layer "In6.Cu")
		(net "UPI_CPU0_CPU1_P2P2_DP<11>")
	)
	(segment
		(start 70.37832 -365.199422)
		(end 65.876678 -354.330762)
		(width 0.14732)
		(layer "In6.Cu")
		(net "UPI_CPU0_CPU1_P2P2_DP<11>")
	)
	(segment
		(start 69.048884 -321.26809)
		(end 78.68285 -311.634124)
		(width 0.14732)
		(layer "In6.Cu")
		(net "UPI_CPU0_CPU1_P2P2_DP<11>")
	)
	(segment
		(start 345.780614 -285.171896)
		(end 345.779852 -285.172404)
		(width 0.0889)
		(layer "In6.Cu")
		(net "UPI_CPU0_CPU1_P2P2_DP<11>")
	)
	(segment
		(start 163.168584 -383.178558)
		(end 162.71367 -383.254504)
		(width 0.14732)
		(layer "In6.Cu")
		(net "UPI_CPU0_CPU1_P2P2_DP<11>")
	)
	(segment
		(start 161.168588 -383.254504)
		(end 161.167572 -383.25552)
		(width 0.14732)
		(layer "In6.Cu")
		(net "UPI_CPU0_CPU1_P2P2_DP<11>")
	)
	(segment
		(start 78.68285 -311.634124)
		(end 79.020416 -311.35701)
		(width 0.14732)
		(layer "In6.Cu")
		(net "UPI_CPU0_CPU1_P2P2_DP<11>")
	)
	(segment
		(start 94.473522 -292.402006)
		(end 94.473522 -292.379908)
		(width 0.0889)
		(layer "In6.Cu")
		(net "UPI_CPU0_CPU1_P2P2_DP<11>")
	)
	(segment
		(start 347.76156 -281.106118)
		(end 347.740224 -281.093926)
		(width 0.0889)
		(layer "In6.Cu")
		(net "UPI_CPU0_CPU1_P2P2_DP<11>")
	)
	(segment
		(start 94.473268 -292.557708)
		(end 94.473522 -292.557454)
		(width 0.14732)
		(layer "In6.Cu")
		(net "UPI_CPU0_CPU1_P2P2_DP<11>")
	)
	(segment
		(start 343.262458 -295.292526)
		(end 343.262458 -295.458642)
		(width 0.14732)
		(layer "In6.Cu")
		(net "UPI_CPU0_CPU1_P2P2_DP<11>")
	)
	(segment
		(start 345.789504 -285.166816)
		(end 345.782138 -285.171134)
		(width 0.0889)
		(layer "In6.Cu")
		(net "UPI_CPU0_CPU1_P2P2_DP<11>")
	)
	(segment
		(start 343.304368 -291.68852)
		(end 343.304368 -295.228518)
		(width 0.0889)
		(layer "In6.Cu")
		(net "UPI_CPU0_CPU1_P2P2_DP<11>")
	)
	(segment
		(start 96.848422 -379.011942)
		(end 75.240642 -370.061744)
		(width 0.14732)
		(layer "In6.Cu")
		(net "UPI_CPU0_CPU1_P2P2_DP<11>")
	)
	(segment
		(start 345.497912 -285.661354)
		(end 345.497912 -285.675578)
		(width 0.0889)
		(layer "In6.Cu")
		(net "UPI_CPU0_CPU1_P2P2_DP<11>")
	)
	(segment
		(start 94.473522 -292.379908)
		(end 94.431358 -292.337744)
		(width 0.0889)
		(layer "In6.Cu")
		(net "UPI_CPU0_CPU1_P2P2_DP<11>")
	)
	(segment
		(start 96.999806 -286.962596)
		(end 97.008188 -286.95777)
		(width 0.0889)
		(layer "In6.Cu")
		(net "UPI_CPU0_CPU1_P2P2_DP<11>")
	)
	(segment
		(start 96.995234 -285.985204)
		(end 96.987106 -285.980632)
		(width 0.0889)
		(layer "In6.Cu")
		(net "UPI_CPU0_CPU1_P2P2_DP<11>")
	)
	(segment
		(start 96.994472 -285.337758)
		(end 96.995996 -285.336996)
		(width 0.0889)
		(layer "In6.Cu")
		(net "UPI_CPU0_CPU1_P2P2_DP<11>")
	)
	(segment
		(start 161.167572 -383.25552)
		(end 125.456188 -383.25552)
		(width 0.14732)
		(layer "In6.Cu")
		(net "UPI_CPU0_CPU1_P2P2_DP<11>")
	)
	(segment
		(start 89.86012 -302.618902)
		(end 90.198194 -302.341534)
		(width 0.14732)
		(layer "In6.Cu")
		(net "UPI_CPU0_CPU1_P2P2_DP<11>")
	)
	(segment
		(start 346.907612 -283.205682)
		(end 346.907612 -283.219906)
		(width 0.0889)
		(layer "In6.Cu")
		(net "UPI_CPU0_CPU1_P2P2_DP<11>")
	)
	(segment
		(start 79.546958 -310.924956)
		(end 80.070198 -310.495696)
		(width 0.14732)
		(layer "In6.Cu")
		(net "UPI_CPU0_CPU1_P2P2_DP<11>")
	)
	(segment
		(start 97.935034 -282.729686)
		(end 97.926906 -282.725114)
		(width 0.0889)
		(layer "In6.Cu")
		(net "UPI_CPU0_CPU1_P2P2_DP<11>")
	)
	(segment
		(start 314.487052 -326.904604)
		(end 307.457856 -333.9338)
		(width 0.14732)
		(layer "In6.Cu")
		(net "UPI_CPU0_CPU1_P2P2_DP<11>")
	)
	(segment
		(start 96.338898 -288.121598)
		(end 96.338898 -288.103056)
		(width 0.0889)
		(layer "In6.Cu")
		(net "UPI_CPU0_CPU1_P2P2_DP<11>")
	)
	(segment
		(start 315.603382 -324.20941)
		(end 314.487052 -326.904604)
		(width 0.14732)
		(layer "In6.Cu")
		(net "UPI_CPU0_CPU1_P2P2_DP<11>")
	)
	(segment
		(start 96.33839 -290.057078)
		(end 96.33839 -289.610292)
		(width 0.0889)
		(layer "In6.Cu")
		(net "UPI_CPU0_CPU1_P2P2_DP<11>")
	)
	(segment
		(start 345.779852 -285.172404)
		(end 345.774518 -285.175452)
		(width 0.0889)
		(layer "In6.Cu")
		(net "UPI_CPU0_CPU1_P2P2_DP<11>")
	)
	(segment
		(start 344.558366 -289.113722)
		(end 344.55862 -289.113976)
		(width 0.0889)
		(layer "In6.Cu")
		(net "UPI_CPU0_CPU1_P2P2_DP<11>")
	)
	(segment
		(start 279.88514 -336.171794)
		(end 271.091152 -344.965782)
		(width 0.14732)
		(layer "In6.Cu")
		(net "UPI_CPU0_CPU1_P2P2_DP<11>")
	)
	(segment
		(start 75.240642 -370.061744)
		(end 70.37832 -365.199422)
		(width 0.14732)
		(layer "In6.Cu")
		(net "UPI_CPU0_CPU1_P2P2_DP<11>")
	)
	(segment
		(start 80.241648 -310.51246)
		(end 80.579722 -310.235092)
		(width 0.14732)
		(layer "In6.Cu")
		(net "UPI_CPU0_CPU1_P2P2_DP<11>")
	)
	(segment
		(start 96.995996 -285.985712)
		(end 96.995234 -285.985204)
		(width 0.0889)
		(layer "In6.Cu")
		(net "UPI_CPU0_CPU1_P2P2_DP<11>")
	)
	(segment
		(start 91.042236 -301.491142)
		(end 91.383104 -301.387764)
		(width 0.14732)
		(layer "In6.Cu")
		(net "UPI_CPU0_CPU1_P2P2_DP<11>")
	)
	(segment
		(start 94.431358 -291.96411)
		(end 96.33839 -290.057078)
		(width 0.0889)
		(layer "In6.Cu")
		(net "UPI_CPU0_CPU1_P2P2_DP<11>")
	)
	(segment
		(start 96.995996 -286.964882)
		(end 96.999806 -286.962596)
		(width 0.0889)
		(layer "In6.Cu")
		(net "UPI_CPU0_CPU1_P2P2_DP<11>")
	)
	(segment
		(start 94.473268 -297.010582)
		(end 94.473268 -292.557708)
		(width 0.14732)
		(layer "In6.Cu")
		(net "UPI_CPU0_CPU1_P2P2_DP<11>")
	)
	(segment
		(start 271.091152 -368.433858)
		(end 264.968736 -374.556274)
		(width 0.14732)
		(layer "In6.Cu")
		(net "UPI_CPU0_CPU1_P2P2_DP<11>")
	)
	(segment
		(start 90.198194 -302.341534)
		(end 90.214958 -302.170084)
		(width 0.14732)
		(layer "In6.Cu")
		(net "UPI_CPU0_CPU1_P2P2_DP<11>")
	)
	(segment
		(start 342.495886 -299.324776)
		(end 340.737444 -301.083218)
		(width 0.14732)
		(layer "In6.Cu")
		(net "UPI_CPU0_CPU1_P2P2_DP<11>")
	)
	(segment
		(start 345.31935 -287.608518)
		(end 345.31046 -287.613598)
		(width 0.0889)
		(layer "In6.Cu")
		(net "UPI_CPU0_CPU1_P2P2_DP<11>")
	)
	(segment
		(start 337.309714 -302.503078)
		(end 315.603382 -324.20941)
		(width 0.14732)
		(layer "In6.Cu")
		(net "UPI_CPU0_CPU1_P2P2_DP<11>")
	)
	(segment
		(start 346.720922 -283.543756)
		(end 346.72016 -283.544264)
		(width 0.0889)
		(layer "In6.Cu")
		(net "UPI_CPU0_CPU1_P2P2_DP<11>")
	)
	(segment
		(start 345.780614 -286.799782)
		(end 345.779852 -286.80029)
		(width 0.0889)
		(layer "In6.Cu")
		(net "UPI_CPU0_CPU1_P2P2_DP<11>")
	)
	(segment
		(start 91.383104 -301.387764)
		(end 92.999306 -300.061376)
		(width 0.14732)
		(layer "In6.Cu")
		(net "UPI_CPU0_CPU1_P2P2_DP<11>")
	)
	(segment
		(start 340.737444 -301.083218)
		(end 337.309714 -302.503078)
		(width 0.14732)
		(layer "In6.Cu")
		(net "UPI_CPU0_CPU1_P2P2_DP<11>")
	)
	(segment
		(start 345.968066 -284.832044)
		(end 345.968066 -284.847538)
		(width 0.0889)
		(layer "In6.Cu")
		(net "UPI_CPU0_CPU1_P2P2_DP<11>")
	)
	(segment
		(start 92.999306 -300.061376)
		(end 93.476826 -299.417232)
		(width 0.14732)
		(layer "In6.Cu")
		(net "UPI_CPU0_CPU1_P2P2_DP<11>")
	)
	(segment
		(start 346.25915 -284.353)
		(end 346.25026 -284.35808)
		(width 0.0889)
		(layer "In6.Cu")
		(net "UPI_CPU0_CPU1_P2P2_DP<11>")
	)
	(segment
		(start 90.214958 -302.170084)
		(end 91.042236 -301.491142)
		(width 0.14732)
		(layer "In6.Cu")
		(net "UPI_CPU0_CPU1_P2P2_DP<11>")
	)
	(segment
		(start 88.773 -303.352962)
		(end 88.773762 -303.352962)
		(width 0.14732)
		(layer "In6.Cu")
		(net "UPI_CPU0_CPU1_P2P2_DP<11>")
	)
	(segment
		(start 345.028266 -289.964622)
		(end 343.304368 -291.68852)
		(width 0.0889)
		(layer "In6.Cu")
		(net "UPI_CPU0_CPU1_P2P2_DP<11>")
	)
	(segment
		(start 96.51746 -287.783778)
		(end 96.52635 -287.778698)
		(width 0.0889)
		(layer "In6.Cu")
		(net "UPI_CPU0_CPU1_P2P2_DP<11>")
	)
	(segment
		(start 95.868998 -289.078416)
		(end 95.868998 -288.917126)
		(width 0.0889)
		(layer "In6.Cu")
		(net "UPI_CPU0_CPU1_P2P2_DP<11>")
	)
	(segment
		(start 65.876678 -354.330762)
		(end 65.876678 -334.72501)
		(width 0.14732)
		(layer "In6.Cu")
		(net "UPI_CPU0_CPU1_P2P2_DP<11>")
	)
	(segment
		(start 343.262458 -295.270428)
		(end 343.262458 -295.292526)
		(width 0.0889)
		(layer "In6.Cu")
		(net "UPI_CPU0_CPU1_P2P2_DP<11>")
	)
	(segment
		(start 345.782138 -285.171134)
		(end 345.780614 -285.171896)
		(width 0.0889)
		(layer "In6.Cu")
		(net "UPI_CPU0_CPU1_P2P2_DP<11>")
	)
	(segment
		(start 347.740224 -281.093926)
		(end 347.740732 -281.093926)
		(width 0.0889)
		(layer "In6.Cu")
		(net "UPI_CPU0_CPU1_P2P2_DP<11>")
	)
	(segment
		(start 125.456188 -383.25552)
		(end 96.848422 -379.011942)
		(width 0.14732)
		(layer "In6.Cu")
		(net "UPI_CPU0_CPU1_P2P2_DP<11>")
	)
	(segment
		(start 97.81032 -282.405836)
		(end 98.122994 -282.405836)
		(width 0.0889)
		(layer "In6.Cu")
		(net "UPI_CPU0_CPU1_P2P2_DP<11>")
	)
	(segment
		(start 345.028266 -289.64509)
		(end 345.028266 -289.964622)
		(width 0.0889)
		(layer "In6.Cu")
		(net "UPI_CPU0_CPU1_P2P2_DP<11>")
	)
	(segment
		(start 80.579722 -310.235092)
		(end 80.596486 -310.063642)
		(width 0.14732)
		(layer "In6.Cu")
		(net "UPI_CPU0_CPU1_P2P2_DP<11>")
	)
	(segment
		(start 79.19212 -311.374028)
		(end 79.52994 -311.09666)
		(width 0.14732)
		(layer "In6.Cu")
		(net "UPI_CPU0_CPU1_P2P2_DP<11>")
	)
	(segment
		(start 345.967812 -286.466788)
		(end 345.967812 -286.48406)
		(width 0.0889)
		(layer "In6.Cu")
		(net "UPI_CPU0_CPU1_P2P2_DP<11>")
	)
	(segment
		(start 66.537078 -328.016616)
		(end 67.496944 -324.54977)
		(width 0.14732)
		(layer "In6.Cu")
		(net "UPI_CPU0_CPU1_P2P2_DP<11>")
	)
	(segment
		(start 79.52994 -311.09666)
		(end 79.546958 -310.924956)
		(width 0.14732)
		(layer "In6.Cu")
		(net "UPI_CPU0_CPU1_P2P2_DP<11>")
	)
	(segment
		(start 97.278698 -286.475424)
		(end 97.278698 -286.467804)
		(width 0.0889)
		(layer "In6.Cu")
		(net "UPI_CPU0_CPU1_P2P2_DP<11>")
	)
	(segment
		(start 89.300304 -302.920908)
		(end 89.68867 -302.602138)
		(width 0.14732)
		(layer "In6.Cu")
		(net "UPI_CPU0_CPU1_P2P2_DP<11>")
	)
	(segment
		(start 344.849704 -288.422334)
		(end 344.840814 -288.427414)
		(width 0.0889)
		(layer "In6.Cu")
		(net "UPI_CPU0_CPU1_P2P2_DP<11>")
	)
	(segment
		(start 88.945212 -303.36998)
		(end 89.283286 -303.092612)
		(width 0.14732)
		(layer "In6.Cu")
		(net "UPI_CPU0_CPU1_P2P2_DP<11>")
	)
	(segment
		(start 345.777058 -286.801814)
		(end 345.774518 -286.803338)
		(width 0.0889)
		(layer "In6.Cu")
		(net "UPI_CPU0_CPU1_P2P2_DP<11>")
	)
	(segment
		(start 94.431358 -292.337744)
		(end 94.431358 -291.96411)
		(width 0.0889)
		(layer "In6.Cu")
		(net "UPI_CPU0_CPU1_P2P2_DP<11>")
	)
	(segment
		(start 97.45726 -284.52826)
		(end 97.46615 -284.52318)
		(width 0.0889)
		(layer "In6.Cu")
		(net "UPI_CPU0_CPU1_P2P2_DP<11>")
	)
	(segment
		(start 79.020416 -311.35701)
		(end 79.19212 -311.374028)
		(width 0.14732)
		(layer "In6.Cu")
		(net "UPI_CPU0_CPU1_P2P2_DP<11>")
	)
	(segment
		(start 348.412816 -281.59202)
		(end 348.100142 -281.59202)
		(width 0.0889)
		(layer "In6.Cu")
		(net "UPI_CPU0_CPU1_P2P2_DP<11>")
	)
	(segment
		(start 345.028266 -288.087562)
		(end 345.028266 -288.103056)
		(width 0.0889)
		(layer "In6.Cu")
		(net "UPI_CPU0_CPU1_P2P2_DP<11>")
	)
	(segment
		(start 162.71367 -383.254504)
		(end 161.168588 -383.254504)
		(width 0.14732)
		(layer "In6.Cu")
		(net "UPI_CPU0_CPU1_P2P2_DP<11>")
	)
	(segment
		(start 96.33839 -289.610292)
		(end 96.338644 -289.610038)
		(width 0.0889)
		(layer "In6.Cu")
		(net "UPI_CPU0_CPU1_P2P2_DP<11>")
	)
	(segment
		(start 271.091152 -344.965782)
		(end 271.091152 -368.433858)
		(width 0.14732)
		(layer "In6.Cu")
		(net "UPI_CPU0_CPU1_P2P2_DP<11>")
	)
	(segment
		(start 96.99879 -285.335472)
		(end 97.002092 -285.33344)
		(width 0.0889)
		(layer "In6.Cu")
		(net "UPI_CPU0_CPU1_P2P2_DP<11>")
	)
	(segment
		(start 97.748344 -284.049216)
		(end 97.748344 -284.033722)
		(width 0.0889)
		(layer "In6.Cu")
		(net "UPI_CPU0_CPU1_P2P2_DP<11>")
	)
	(segment
		(start 346.72905 -283.539184)
		(end 346.720922 -283.543756)
		(width 0.0889)
		(layer "In6.Cu")
		(net "UPI_CPU0_CPU1_P2P2_DP<11>")
	)
	(segment
		(start 307.457856 -333.9338)
		(end 285.288482 -333.9338)
		(width 0.14732)
		(layer "In6.Cu")
		(net "UPI_CPU0_CPU1_P2P2_DP<11>")
	)
	(segment
		(start 97.752916 -282.46324)
		(end 97.81032 -282.405836)
		(width 0.0889)
		(layer "In6.Cu")
		(net "UPI_CPU0_CPU1_P2P2_DP<11>")
	)
	(segment
		(start 345.779852 -286.80029)
		(end 345.777058 -286.801814)
		(width 0.0889)
		(layer "In6.Cu")
		(net "UPI_CPU0_CPU1_P2P2_DP<11>")
	)
	(segment
		(start 343.262204 -295.458896)
		(end 343.262204 -297.473116)
		(width 0.14732)
		(layer "In6.Cu")
		(net "UPI_CPU0_CPU1_P2P2_DP<11>")
	)
	(segment
		(start 65.876678 -334.72501)
		(end 66.537078 -328.016616)
		(width 0.14732)
		(layer "In6.Cu")
		(net "UPI_CPU0_CPU1_P2P2_DP<11>")
	)
	(segment
		(start 343.262458 -295.458642)
		(end 343.262204 -295.458896)
		(width 0.14732)
		(layer "In6.Cu")
		(net "UPI_CPU0_CPU1_P2P2_DP<11>")
	)
	(segment
		(start 344.558366 -288.898584)
		(end 344.558366 -289.113722)
		(width 0.0889)
		(layer "In6.Cu")
		(net "UPI_CPU0_CPU1_P2P2_DP<11>")
	)
	(segment
		(start 96.987106 -285.342076)
		(end 96.994472 -285.337758)
		(width 0.0889)
		(layer "In6.Cu")
		(net "UPI_CPU0_CPU1_P2P2_DP<11>")
	)
	(segment
		(start 89.68867 -302.602138)
		(end 89.86012 -302.618902)
		(width 0.14732)
		(layer "In6.Cu")
		(net "UPI_CPU0_CPU1_P2P2_DP<11>")
	)
	(segment
		(start 285.288482 -333.9338)
		(end 279.88514 -336.171794)
		(width 0.14732)
		(layer "In6.Cu")
		(net "UPI_CPU0_CPU1_P2P2_DP<11>")
	)
	(segment
		(start 97.935796 -282.730194)
		(end 97.935034 -282.729686)
		(width 0.0889)
		(layer "In6.Cu")
		(net "UPI_CPU0_CPU1_P2P2_DP<11>")
	)
	(segment
		(start 80.596486 -310.063642)
		(end 88.773254 -303.353216)
		(width 0.14732)
		(layer "In6.Cu")
		(net "UPI_CPU0_CPU1_P2P2_DP<11>")
	)
	(segment
		(start 346.907866 -281.576526)
		(end 346.907866 -281.607514)
		(width 0.0889)
		(layer "In6.Cu")
		(net "UPI_CPU0_CPU1_P2P2_DP<11>")
	)
	(segment
		(start 344.844116 -289.446208)
		(end 344.84437 -289.446208)
		(width 0.0889)
		(layer "In6.Cu")
		(net "UPI_CPU0_CPU1_P2P2_DP<11>")
	)
	(segment
		(start 264.968736 -374.556274)
		(end 163.168584 -383.178558)
		(width 0.14732)
		(layer "In6.Cu")
		(net "UPI_CPU0_CPU1_P2P2_DP<11>")
	)
	(segment
		(start 89.283286 -303.092612)
		(end 89.300304 -302.920908)
		(width 0.14732)
		(layer "In6.Cu")
		(net "UPI_CPU0_CPU1_P2P2_DP<11>")
	)
	(segment
		(start 96.338644 -289.610038)
		(end 96.338644 -289.60953)
		(width 0.0889)
		(layer "In6.Cu")
		(net "UPI_CPU0_CPU1_P2P2_DP<11>")
	)
	(segment
		(start 94.473522 -292.557454)
		(end 94.473522 -292.402006)
		(width 0.14732)
		(layer "In6.Cu")
		(net "UPI_CPU0_CPU1_P2P2_DP<11>")
	)
	(segment
		(start 348.100142 -281.59202)
		(end 348.034356 -281.526234)
		(width 0.0889)
		(layer "In6.Cu")
		(net "UPI_CPU0_CPU1_P2P2_DP<11>")
	)
	(segment
		(start 347.19895 -282.725114)
		(end 347.19006 -282.730194)
		(width 0.0889)
		(layer "In6.Cu")
		(net "UPI_CPU0_CPU1_P2P2_DP<11>")
	)
	(segment
		(start 346.437712 -284.023816)
		(end 346.437712 -284.033722)
		(width 0.0889)
		(layer "In6.Cu")
		(net "UPI_CPU0_CPU1_P2P2_DP<11>")
	)
	(segment
		(start 97.926906 -283.714444)
		(end 97.935796 -283.709364)
		(width 0.0889)
		(layer "In6.Cu")
		(net "UPI_CPU0_CPU1_P2P2_DP<11>")
	)
	(segment
		(start 98.218244 -283.229812)
		(end 98.218244 -283.201364)
		(width 0.0889)
		(layer "In6.Cu")
		(net "UPI_CPU0_CPU1_P2P2_DP<11>")
	)
	(segment
		(start 96.995996 -285.336996)
		(end 96.99879 -285.335472)
		(width 0.0889)
		(layer "In6.Cu")
		(net "UPI_CPU0_CPU1_P2P2_DP<11>")
	)
	(segment
		(start 96.808544 -287.304734)
		(end 96.808544 -287.28924)
		(width 0.0889)
		(layer "In6.Cu")
		(net "UPI_CPU0_CPU1_P2P2_DP<11>")
	)
	(segment
		(start 88.773762 -303.352962)
		(end 88.945212 -303.36998)
		(width 0.14732)
		(layer "In6.Cu")
		(net "UPI_CPU0_CPU1_P2P2_DP<11>")
	)
	(segment
		(start 93.476826 -299.417232)
		(end 94.473268 -297.010582)
		(width 0.14732)
		(layer "In6.Cu")
		(net "UPI_CPU0_CPU1_P2P2_DP<11>")
	)
	(segment
		(start 67.496944 -324.54977)
		(end 69.048884 -321.26809)
		(width 0.14732)
		(layer "In6.Cu")
		(net "UPI_CPU0_CPU1_P2P2_DP<11>")
	)
	(segment
		(start 343.304368 -295.228518)
		(end 343.262458 -295.270428)
		(width 0.0889)
		(layer "In6.Cu")
		(net "UPI_CPU0_CPU1_P2P2_DP<11>")
	)
	(segment
		(start 88.773254 -303.353216)
		(end 88.773 -303.352962)
		(width 0.14732)
		(layer "In6.Cu")
		(net "UPI_CPU0_CPU1_P2P2_DP<11>")
	)
	(arc
		(start 97.008188 -286.95777)
		(mid 97.206416 -286.751922)
		(end 97.278698 -286.475424)
		(width 0.0889)
		(layer "In6.Cu")
		(net "UPI_CPU0_CPU1_P2P2_DP<11>")
	)
	(arc
		(start 98.218244 -283.201364)
		(mid 98.138082 -282.929175)
		(end 97.935796 -282.730194)
		(width 0.0889)
		(layer "In6.Cu")
		(net "UPI_CPU0_CPU1_P2P2_DP<11>")
	)
	(arc
		(start 344.55862 -289.113976)
		(mid 344.566015 -289.133926)
		(end 344.574114 -289.1536)
		(width 0.0889)
		(layer "In6.Cu")
		(net "UPI_CPU0_CPU1_P2P2_DP<11>")
	)
	(arc
		(start 346.907612 -283.219906)
		(mid 346.859933 -283.402806)
		(end 346.72905 -283.539184)
		(width 0.0889)
		(layer "In6.Cu")
		(net "UPI_CPU0_CPU1_P2P2_DP<11>")
	)
	(arc
		(start 346.437712 -284.033722)
		(mid 346.390033 -284.216622)
		(end 346.25915 -284.353)
		(width 0.0889)
		(layer "In6.Cu")
		(net "UPI_CPU0_CPU1_P2P2_DP<11>")
	)
	(arc
		(start 346.907866 -281.607514)
		(mid 346.987236 -281.881248)
		(end 347.19006 -282.081478)
		(width 0.0889)
		(layer "In6.Cu")
		(net "UPI_CPU0_CPU1_P2P2_DP<11>")
	)
	(arc
		(start 345.028266 -288.103056)
		(mid 344.980587 -288.285956)
		(end 344.849704 -288.422334)
		(width 0.0889)
		(layer "In6.Cu")
		(net "UPI_CPU0_CPU1_P2P2_DP<11>")
	)
	(arc
		(start 345.774518 -286.803338)
		(mid 345.571931 -287.009689)
		(end 345.497912 -287.28924)
		(width 0.0889)
		(layer "In6.Cu")
		(net "UPI_CPU0_CPU1_P2P2_DP<11>")
	)
	(arc
		(start 346.25026 -284.35808)
		(mid 346.047437 -284.558311)
		(end 345.968066 -284.832044)
		(width 0.0889)
		(layer "In6.Cu")
		(net "UPI_CPU0_CPU1_P2P2_DP<11>")
	)
	(arc
		(start 97.748344 -284.033722)
		(mid 97.796023 -283.850822)
		(end 97.926906 -283.714444)
		(width 0.0889)
		(layer "In6.Cu")
		(net "UPI_CPU0_CPU1_P2P2_DP<11>")
	)
	(arc
		(start 347.19895 -282.086558)
		(mid 347.377426 -282.405836)
		(end 347.19895 -282.725114)
		(width 0.0889)
		(layer "In6.Cu")
		(net "UPI_CPU0_CPU1_P2P2_DP<11>")
	)
	(arc
		(start 97.278698 -284.847538)
		(mid 97.326377 -284.664638)
		(end 97.45726 -284.52826)
		(width 0.0889)
		(layer "In6.Cu")
		(net "UPI_CPU0_CPU1_P2P2_DP<11>")
	)
	(arc
		(start 346.72016 -283.544264)
		(mid 346.515825 -283.746869)
		(end 346.437712 -284.023816)
		(width 0.0889)
		(layer "In6.Cu")
		(net "UPI_CPU0_CPU1_P2P2_DP<11>")
	)
	(arc
		(start 345.497912 -285.675578)
		(mid 345.577131 -285.950263)
		(end 345.780614 -286.151066)
		(width 0.0889)
		(layer "In6.Cu")
		(net "UPI_CPU0_CPU1_P2P2_DP<11>")
	)
	(arc
		(start 96.338898 -288.103056)
		(mid 96.386577 -287.920156)
		(end 96.51746 -287.783778)
		(width 0.0889)
		(layer "In6.Cu")
		(net "UPI_CPU0_CPU1_P2P2_DP<11>")
	)
	(arc
		(start 345.967812 -286.48406)
		(mid 345.915542 -286.666425)
		(end 345.780614 -286.799782)
		(width 0.0889)
		(layer "In6.Cu")
		(net "UPI_CPU0_CPU1_P2P2_DP<11>")
	)
	(arc
		(start 96.05645 -288.592768)
		(mid 96.258736 -288.393787)
		(end 96.338898 -288.121598)
		(width 0.0889)
		(layer "In6.Cu")
		(net "UPI_CPU0_CPU1_P2P2_DP<11>")
	)
	(arc
		(start 97.278698 -286.467804)
		(mid 97.201069 -286.189391)
		(end 96.995996 -285.985712)
		(width 0.0889)
		(layer "In6.Cu")
		(net "UPI_CPU0_CPU1_P2P2_DP<11>")
	)
	(arc
		(start 344.574114 -289.1536)
		(mid 344.684044 -289.323043)
		(end 344.844116 -289.446208)
		(width 0.0889)
		(layer "In6.Cu")
		(net "UPI_CPU0_CPU1_P2P2_DP<11>")
	)
	(arc
		(start 97.46615 -284.52318)
		(mid 97.668973 -284.322949)
		(end 97.748344 -284.049216)
		(width 0.0889)
		(layer "In6.Cu")
		(net "UPI_CPU0_CPU1_P2P2_DP<11>")
	)
	(arc
		(start 95.868998 -288.917126)
		(mid 95.916677 -288.734226)
		(end 96.04756 -288.597848)
		(width 0.0889)
		(layer "In6.Cu")
		(net "UPI_CPU0_CPU1_P2P2_DP<11>")
	)
	(arc
		(start 348.034356 -281.526234)
		(mid 348.033055 -281.515807)
		(end 348.031562 -281.505406)
		(width 0.0889)
		(layer "In6.Cu")
		(net "UPI_CPU0_CPU1_P2P2_DP<11>")
	)
	(arc
		(start 344.847672 -289.447986)
		(mid 344.95452 -289.531364)
		(end 345.028266 -289.64509)
		(width 0.0889)
		(layer "In6.Cu")
		(net "UPI_CPU0_CPU1_P2P2_DP<11>")
	)
	(arc
		(start 345.31046 -287.613598)
		(mid 345.107637 -287.813829)
		(end 345.028266 -288.087562)
		(width 0.0889)
		(layer "In6.Cu")
		(net "UPI_CPU0_CPU1_P2P2_DP<11>")
	)
	(arc
		(start 97.002092 -285.33344)
		(mid 97.204679 -285.127089)
		(end 97.278698 -284.847538)
		(width 0.0889)
		(layer "In6.Cu")
		(net "UPI_CPU0_CPU1_P2P2_DP<11>")
	)
	(arc
		(start 345.774518 -285.175452)
		(mid 345.571931 -285.381803)
		(end 345.497912 -285.661354)
		(width 0.0889)
		(layer "In6.Cu")
		(net "UPI_CPU0_CPU1_P2P2_DP<11>")
	)
	(arc
		(start 96.987106 -285.980632)
		(mid 96.80863 -285.661354)
		(end 96.987106 -285.342076)
		(width 0.0889)
		(layer "In6.Cu")
		(net "UPI_CPU0_CPU1_P2P2_DP<11>")
	)
	(arc
		(start 96.338644 -289.60953)
		(mid 96.227306 -289.41663)
		(end 96.053148 -289.277806)
		(width 0.0889)
		(layer "In6.Cu")
		(net "UPI_CPU0_CPU1_P2P2_DP<11>")
	)
	(arc
		(start 96.52635 -287.778698)
		(mid 96.729173 -287.578467)
		(end 96.808544 -287.304734)
		(width 0.0889)
		(layer "In6.Cu")
		(net "UPI_CPU0_CPU1_P2P2_DP<11>")
	)
	(arc
		(start 344.840814 -288.427414)
		(mid 344.638528 -288.626395)
		(end 344.558366 -288.898584)
		(width 0.0889)
		(layer "In6.Cu")
		(net "UPI_CPU0_CPU1_P2P2_DP<11>")
	)
	(arc
		(start 97.926906 -282.725114)
		(mid 97.811167 -282.61329)
		(end 97.752916 -282.46324)
		(width 0.0889)
		(layer "In6.Cu")
		(net "UPI_CPU0_CPU1_P2P2_DP<11>")
	)
	(arc
		(start 345.968066 -284.847538)
		(mid 345.920387 -285.030438)
		(end 345.789504 -285.166816)
		(width 0.0889)
		(layer "In6.Cu")
		(net "UPI_CPU0_CPU1_P2P2_DP<11>")
	)
	(arc
		(start 97.935796 -283.709364)
		(mid 98.140131 -283.506759)
		(end 98.218244 -283.229812)
		(width 0.0889)
		(layer "In6.Cu")
		(net "UPI_CPU0_CPU1_P2P2_DP<11>")
	)
	(arc
		(start 344.84437 -289.446208)
		(mid 344.846023 -289.447093)
		(end 344.847672 -289.447986)
		(width 0.0889)
		(layer "In6.Cu")
		(net "UPI_CPU0_CPU1_P2P2_DP<11>")
	)
	(arc
		(start 347.19006 -281.102562)
		(mid 346.987237 -281.302793)
		(end 346.907866 -281.576526)
		(width 0.0889)
		(layer "In6.Cu")
		(net "UPI_CPU0_CPU1_P2P2_DP<11>")
	)
	(arc
		(start 345.497912 -287.28924)
		(mid 345.450233 -287.47214)
		(end 345.31935 -287.608518)
		(width 0.0889)
		(layer "In6.Cu")
		(net "UPI_CPU0_CPU1_P2P2_DP<11>")
	)
	(arc
		(start 345.780614 -286.151066)
		(mid 345.915547 -286.28442)
		(end 345.967812 -286.466788)
		(width 0.0889)
		(layer "In6.Cu")
		(net "UPI_CPU0_CPU1_P2P2_DP<11>")
	)
	(arc
		(start 96.808544 -287.28924)
		(mid 96.856223 -287.10634)
		(end 96.987106 -286.969962)
		(width 0.0889)
		(layer "In6.Cu")
		(net "UPI_CPU0_CPU1_P2P2_DP<11>")
	)
	(arc
		(start 347.19006 -282.730194)
		(mid 346.986755 -282.93106)
		(end 346.907612 -283.205682)
		(width 0.0889)
		(layer "In6.Cu")
		(net "UPI_CPU0_CPU1_P2P2_DP<11>")
	)
	(arc
		(start 96.053148 -289.277806)
		(mid 95.944001 -289.193878)
		(end 95.868998 -289.078416)
		(width 0.0889)
		(layer "In6.Cu")
		(net "UPI_CPU0_CPU1_P2P2_DP<11>")
	)
	(arc
		(start 347.740732 -281.093926)
		(mid 347.464257 -281.026606)
		(end 347.19006 -281.102562)
		(width 0.0889)
		(layer "In6.Cu")
		(net "UPI_CPU0_CPU1_P2P2_DP<11>")
	)
	(arc
		(start 348.031562 -281.505406)
		(mid 347.941298 -281.275496)
		(end 347.76156 -281.106118)
		(width 0.0889)
		(layer "In6.Cu")
		(net "UPI_CPU0_CPU1_P2P2_DP<11>")
	)
	(segment
		(start 97.653094 -281.05608)
		(end 97.653094 -281.591766)
		(width 0.13208)
		(layer "F.Cu")
		(net "UPI_CPU0_CPU1_P2P2_DP<10>")
	)
	(segment
		(start 347.472762 -283.219652)
		(end 347.473016 -283.219906)
		(width 0.13208)
		(layer "F.Cu")
		(net "UPI_CPU0_CPU1_P2P2_DP<10>")
	)
	(segment
		(start 97.653094 -281.591766)
		(end 97.653348 -281.59202)
		(width 0.13208)
		(layer "F.Cu")
		(net "UPI_CPU0_CPU1_P2P2_DP<10>")
	)
	(segment
		(start 347.472762 -282.683966)
		(end 347.472762 -283.219652)
		(width 0.13208)
		(layer "F.Cu")
		(net "UPI_CPU0_CPU1_P2P2_DP<10>")
	)
	(segment
		(start 94.45879 -290.768278)
		(end 94.45879 -289.646868)
		(width 0.0889)
		(layer "In6.Cu")
		(net "UPI_CPU0_CPU1_P2P2_DP<10>")
	)
	(segment
		(start 93.629988 -294.743378)
		(end 93.485208 -294.598598)
		(width 0.14732)
		(layer "In6.Cu")
		(net "UPI_CPU0_CPU1_P2P2_DP<10>")
	)
	(segment
		(start 93.894402 -291.332666)
		(end 94.45879 -290.768278)
		(width 0.0889)
		(layer "In6.Cu")
		(net "UPI_CPU0_CPU1_P2P2_DP<10>")
	)
	(segment
		(start 88.030558 -302.729392)
		(end 88.416384 -302.412908)
		(width 0.14732)
		(layer "In6.Cu")
		(net "UPI_CPU0_CPU1_P2P2_DP<10>")
	)
	(segment
		(start 93.485208 -292.546278)
		(end 93.485208 -291.801804)
		(width 0.14732)
		(layer "In6.Cu")
		(net "UPI_CPU0_CPU1_P2P2_DP<10>")
	)
	(segment
		(start 88.013794 -302.901096)
		(end 88.030558 -302.729392)
		(width 0.14732)
		(layer "In6.Cu")
		(net "UPI_CPU0_CPU1_P2P2_DP<10>")
	)
	(segment
		(start 65.25895 -331.7748)
		(end 65.295272 -331.408024)
		(width 0.14732)
		(layer "In6.Cu")
		(net "UPI_CPU0_CPU1_P2P2_DP<10>")
	)
	(segment
		(start 344.135202 -292.26256)
		(end 344.036142 -292.36162)
		(width 0.0889)
		(layer "In6.Cu")
		(net "UPI_CPU0_CPU1_P2P2_DP<10>")
	)
	(segment
		(start 68.363084 -320.776346)
		(end 78.996286 -310.143144)
		(width 0.14732)
		(layer "In6.Cu")
		(net "UPI_CPU0_CPU1_P2P2_DP<10>")
	)
	(segment
		(start 97.002346 -283.705554)
		(end 97.002092 -283.705808)
		(width 0.0889)
		(layer "In6.Cu")
		(net "UPI_CPU0_CPU1_P2P2_DP<10>")
	)
	(segment
		(start 346.714064 -285.175706)
		(end 346.714318 -285.175452)
		(width 0.0889)
		(layer "In6.Cu")
		(net "UPI_CPU0_CPU1_P2P2_DP<10>")
	)
	(segment
		(start 346.907866 -284.832044)
		(end 346.907866 -284.847538)
		(width 0.0889)
		(layer "In6.Cu")
		(net "UPI_CPU0_CPU1_P2P2_DP<10>")
	)
	(segment
		(start 344.093038 -297.794426)
		(end 343.792556 -298.393104)
		(width 0.14732)
		(layer "In6.Cu")
		(net "UPI_CPU0_CPU1_P2P2_DP<10>")
	)
	(segment
		(start 347.473016 -283.219906)
		(end 347.62948 -282.948888)
		(width 0.0889)
		(layer "In6.Cu")
		(net "UPI_CPU0_CPU1_P2P2_DP<10>")
	)
	(segment
		(start 93.485208 -294.598598)
		(end 93.485208 -294.230298)
		(width 0.14732)
		(layer "In6.Cu")
		(net "UPI_CPU0_CPU1_P2P2_DP<10>")
	)
	(segment
		(start 65.295272 -331.408024)
		(end 65.165224 -331.249782)
		(width 0.14732)
		(layer "In6.Cu")
		(net "UPI_CPU0_CPU1_P2P2_DP<10>")
	)
	(segment
		(start 88.588088 -302.429672)
		(end 88.925908 -302.152304)
		(width 0.14732)
		(layer "In6.Cu")
		(net "UPI_CPU0_CPU1_P2P2_DP<10>")
	)
	(segment
		(start 95.10776 -288.597848)
		(end 95.11665 -288.592768)
		(width 0.0889)
		(layer "In6.Cu")
		(net "UPI_CPU0_CPU1_P2P2_DP<10>")
	)
	(segment
		(start 344.093292 -294.810434)
		(end 344.093038 -294.810688)
		(width 0.14732)
		(layer "In6.Cu")
		(net "UPI_CPU0_CPU1_P2P2_DP<10>")
	)
	(segment
		(start 95.399098 -288.121598)
		(end 95.399098 -288.103056)
		(width 0.0889)
		(layer "In6.Cu")
		(net "UPI_CPU0_CPU1_P2P2_DP<10>")
	)
	(segment
		(start 85.717634 -304.785268)
		(end 86.055708 -304.5079)
		(width 0.14732)
		(layer "In6.Cu")
		(net "UPI_CPU0_CPU1_P2P2_DP<10>")
	)
	(segment
		(start 96.996758 -282.08097)
		(end 97.002092 -282.077922)
		(width 0.0889)
		(layer "In6.Cu")
		(net "UPI_CPU0_CPU1_P2P2_DP<10>")
	)
	(segment
		(start 345.968066 -289.64509)
		(end 345.968066 -290.06927)
		(width 0.0889)
		(layer "In6.Cu")
		(net "UPI_CPU0_CPU1_P2P2_DP<10>")
	)
	(segment
		(start 70.66661 -366.686846)
		(end 70.494144 -366.686846)
		(width 0.14732)
		(layer "In6.Cu")
		(net "UPI_CPU0_CPU1_P2P2_DP<10>")
	)
	(segment
		(start 85.54593 -304.768504)
		(end 85.717634 -304.785268)
		(width 0.14732)
		(layer "In6.Cu")
		(net "UPI_CPU0_CPU1_P2P2_DP<10>")
	)
	(segment
		(start 346.25915 -287.608518)
		(end 346.25026 -287.613598)
		(width 0.0889)
		(layer "In6.Cu")
		(net "UPI_CPU0_CPU1_P2P2_DP<10>")
	)
	(segment
		(start 65.041018 -332.508352)
		(end 65.041272 -332.508098)
		(width 0.14732)
		(layer "In6.Cu")
		(net "UPI_CPU0_CPU1_P2P2_DP<10>")
	)
	(segment
		(start 96.995996 -282.730194)
		(end 96.987106 -282.725114)
		(width 0.0889)
		(layer "In6.Cu")
		(net "UPI_CPU0_CPU1_P2P2_DP<10>")
	)
	(segment
		(start 343.22131 -299.772832)
		(end 341.064342 -301.9298)
		(width 0.14732)
		(layer "In6.Cu")
		(net "UPI_CPU0_CPU1_P2P2_DP<10>")
	)
	(segment
		(start 91.15552 -300.497748)
		(end 92.366338 -299.504354)
		(width 0.14732)
		(layer "In6.Cu")
		(net "UPI_CPU0_CPU1_P2P2_DP<10>")
	)
	(segment
		(start 93.878908 -291.408104)
		(end 93.894402 -291.39261)
		(width 0.0889)
		(layer "In6.Cu")
		(net "UPI_CPU0_CPU1_P2P2_DP<10>")
	)
	(segment
		(start 93.485208 -294.230298)
		(end 93.629988 -294.085518)
		(width 0.14732)
		(layer "In6.Cu")
		(net "UPI_CPU0_CPU1_P2P2_DP<10>")
	)
	(segment
		(start 96.047306 -286.969962)
		(end 96.062546 -286.961072)
		(width 0.0889)
		(layer "In6.Cu")
		(net "UPI_CPU0_CPU1_P2P2_DP<10>")
	)
	(segment
		(start 345.789504 -288.422334)
		(end 345.780614 -288.427414)
		(width 0.0889)
		(layer "In6.Cu")
		(net "UPI_CPU0_CPU1_P2P2_DP<10>")
	)
	(segment
		(start 88.942926 -301.980854)
		(end 89.280492 -301.70374)
		(width 0.14732)
		(layer "In6.Cu")
		(net "UPI_CPU0_CPU1_P2P2_DP<10>")
	)
	(segment
		(start 346.720922 -286.799274)
		(end 346.72016 -286.799782)
		(width 0.0889)
		(layer "In6.Cu")
		(net "UPI_CPU0_CPU1_P2P2_DP<10>")
	)
	(segment
		(start 96.056196 -285.985712)
		(end 96.047306 -285.980632)
		(width 0.0889)
		(layer "In6.Cu")
		(net "UPI_CPU0_CPU1_P2P2_DP<10>")
	)
	(segment
		(start 72.57796 -368.598196)
		(end 72.268842 -368.289078)
		(width 0.14732)
		(layer "In6.Cu")
		(net "UPI_CPU0_CPU1_P2P2_DP<10>")
	)
	(segment
		(start 78.996286 -310.143144)
		(end 85.54593 -304.768504)
		(width 0.14732)
		(layer "In6.Cu")
		(net "UPI_CPU0_CPU1_P2P2_DP<10>")
	)
	(segment
		(start 347.660214 -283.544264)
		(end 347.659452 -283.544772)
		(width 0.0889)
		(layer "In6.Cu")
		(net "UPI_CPU0_CPU1_P2P2_DP<10>")
	)
	(segment
		(start 345.750642 -290.286694)
		(end 345.61018 -290.286694)
		(width 0.0889)
		(layer "In6.Cu")
		(net "UPI_CPU0_CPU1_P2P2_DP<10>")
	)
	(segment
		(start 161.16808 -384.09753)
		(end 125.434852 -384.09753)
		(width 0.14732)
		(layer "In6.Cu")
		(net "UPI_CPU0_CPU1_P2P2_DP<10>")
	)
	(segment
		(start 344.036142 -292.91026)
		(end 344.036142 -293.08552)
		(width 0.0889)
		(layer "In6.Cu")
		(net "UPI_CPU0_CPU1_P2P2_DP<10>")
	)
	(segment
		(start 162.752024 -384.089402)
		(end 161.16808 -384.09753)
		(width 0.14732)
		(layer "In6.Cu")
		(net "UPI_CPU0_CPU1_P2P2_DP<10>")
	)
	(segment
		(start 93.485208 -295.256458)
		(end 93.629988 -295.111678)
		(width 0.14732)
		(layer "In6.Cu")
		(net "UPI_CPU0_CPU1_P2P2_DP<10>")
	)
	(segment
		(start 93.894402 -291.39261)
		(end 93.894402 -291.332666)
		(width 0.0889)
		(layer "In6.Cu")
		(net "UPI_CPU0_CPU1_P2P2_DP<10>")
	)
	(segment
		(start 66.717418 -324.2564)
		(end 68.363084 -320.776346)
		(width 0.14732)
		(layer "In6.Cu")
		(net "UPI_CPU0_CPU1_P2P2_DP<10>")
	)
	(segment
		(start 86.055708 -304.5079)
		(end 86.072472 -304.33645)
		(width 0.14732)
		(layer "In6.Cu")
		(net "UPI_CPU0_CPU1_P2P2_DP<10>")
	)
	(segment
		(start 344.135202 -292.63594)
		(end 344.135202 -292.8112)
		(width 0.0889)
		(layer "In6.Cu")
		(net "UPI_CPU0_CPU1_P2P2_DP<10>")
	)
	(segment
		(start 71.305674 -367.498376)
		(end 70.975982 -367.168684)
		(width 0.14732)
		(layer "In6.Cu")
		(net "UPI_CPU0_CPU1_P2P2_DP<10>")
	)
	(segment
		(start 96.808544 -284.049216)
		(end 96.808544 -284.033722)
		(width 0.0889)
		(layer "In6.Cu")
		(net "UPI_CPU0_CPU1_P2P2_DP<10>")
	)
	(segment
		(start 93.629988 -292.691058)
		(end 93.485208 -292.546278)
		(width 0.14732)
		(layer "In6.Cu")
		(net "UPI_CPU0_CPU1_P2P2_DP<10>")
	)
	(segment
		(start 65.041272 -332.508098)
		(end 65.100454 -331.904594)
		(width 0.14732)
		(layer "In6.Cu")
		(net "UPI_CPU0_CPU1_P2P2_DP<10>")
	)
	(segment
		(start 96.338898 -286.475424)
		(end 96.338898 -286.4612)
		(width 0.0889)
		(layer "In6.Cu")
		(net "UPI_CPU0_CPU1_P2P2_DP<10>")
	)
	(segment
		(start 65.376298 -329.10399)
		(end 66.717418 -324.2564)
		(width 0.14732)
		(layer "In6.Cu")
		(net "UPI_CPU0_CPU1_P2P2_DP<10>")
	)
	(segment
		(start 70.494144 -366.686846)
		(end 69.810884 -366.003586)
		(width 0.14732)
		(layer "In6.Cu")
		(net "UPI_CPU0_CPU1_P2P2_DP<10>")
	)
	(segment
		(start 94.929198 -289.114484)
		(end 94.929198 -288.917126)
		(width 0.0889)
		(layer "In6.Cu")
		(net "UPI_CPU0_CPU1_P2P2_DP<10>")
	)
	(segment
		(start 341.064342 -301.9298)
		(end 337.638136 -303.34966)
		(width 0.14732)
		(layer "In6.Cu")
		(net "UPI_CPU0_CPU1_P2P2_DP<10>")
	)
	(segment
		(start 88.416384 -302.412908)
		(end 88.588088 -302.429672)
		(width 0.14732)
		(layer "In6.Cu")
		(net "UPI_CPU0_CPU1_P2P2_DP<10>")
	)
	(segment
		(start 95.57766 -287.783778)
		(end 95.58655 -287.778698)
		(width 0.0889)
		(layer "In6.Cu")
		(net "UPI_CPU0_CPU1_P2P2_DP<10>")
	)
	(segment
		(start 344.135202 -293.18458)
		(end 344.135202 -294.550338)
		(width 0.0889)
		(layer "In6.Cu")
		(net "UPI_CPU0_CPU1_P2P2_DP<10>")
	)
	(segment
		(start 96.062546 -286.961072)
		(end 96.062292 -286.961326)
		(width 0.0889)
		(layer "In6.Cu")
		(net "UPI_CPU0_CPU1_P2P2_DP<10>")
	)
	(segment
		(start 96.987106 -282.086558)
		(end 96.994472 -282.08224)
		(width 0.0889)
		(layer "In6.Cu")
		(net "UPI_CPU0_CPU1_P2P2_DP<10>")
	)
	(segment
		(start 307.803296 -334.76184)
		(end 285.488126 -334.76184)
		(width 0.14732)
		(layer "In6.Cu")
		(net "UPI_CPU0_CPU1_P2P2_DP<10>")
	)
	(segment
		(start 96.047306 -285.342076)
		(end 96.054672 -285.337758)
		(width 0.0889)
		(layer "In6.Cu")
		(net "UPI_CPU0_CPU1_P2P2_DP<10>")
	)
	(segment
		(start 97.45726 -281.272742)
		(end 97.46615 -281.267662)
		(width 0.0889)
		(layer "In6.Cu")
		(net "UPI_CPU0_CPU1_P2P2_DP<10>")
	)
	(segment
		(start 285.488126 -334.76184)
		(end 280.32964 -336.898488)
		(width 0.14732)
		(layer "In6.Cu")
		(net "UPI_CPU0_CPU1_P2P2_DP<10>")
	)
	(segment
		(start 271.919192 -345.308936)
		(end 271.919192 -368.926364)
		(width 0.14732)
		(layer "In6.Cu")
		(net "UPI_CPU0_CPU1_P2P2_DP<10>")
	)
	(segment
		(start 344.093292 -294.592248)
		(end 344.093292 -294.614346)
		(width 0.0889)
		(layer "In6.Cu")
		(net "UPI_CPU0_CPU1_P2P2_DP<10>")
	)
	(segment
		(start 345.7575 -289.431476)
		(end 345.930728 -289.604704)
		(width 0.0889)
		(layer "In6.Cu")
		(net "UPI_CPU0_CPU1_P2P2_DP<10>")
	)
	(segment
		(start 346.72905 -286.794702)
		(end 346.720922 -286.799274)
		(width 0.0889)
		(layer "In6.Cu")
		(net "UPI_CPU0_CPU1_P2P2_DP<10>")
	)
	(segment
		(start 125.434852 -384.09753)
		(end 96.592644 -379.819154)
		(width 0.14732)
		(layer "In6.Cu")
		(net "UPI_CPU0_CPU1_P2P2_DP<10>")
	)
	(segment
		(start 344.036142 -292.36162)
		(end 344.036142 -292.53688)
		(width 0.0889)
		(layer "In6.Cu")
		(net "UPI_CPU0_CPU1_P2P2_DP<10>")
	)
	(segment
		(start 345.968066 -288.087562)
		(end 345.968066 -288.103056)
		(width 0.0889)
		(layer "In6.Cu")
		(net "UPI_CPU0_CPU1_P2P2_DP<10>")
	)
	(segment
		(start 65.041018 -354.487734)
		(end 65.041018 -332.508352)
		(width 0.14732)
		(layer "In6.Cu")
		(net "UPI_CPU0_CPU1_P2P2_DP<10>")
	)
	(segment
		(start 92.764356 -298.967652)
		(end 93.485208 -297.226228)
		(width 0.14732)
		(layer "In6.Cu")
		(net "UPI_CPU0_CPU1_P2P2_DP<10>")
	)
	(segment
		(start 74.458322 -370.651024)
		(end 72.57796 -368.770662)
		(width 0.14732)
		(layer "In6.Cu")
		(net "UPI_CPU0_CPU1_P2P2_DP<10>")
	)
	(segment
		(start 70.975982 -367.168684)
		(end 70.975982 -366.996218)
		(width 0.14732)
		(layer "In6.Cu")
		(net "UPI_CPU0_CPU1_P2P2_DP<10>")
	)
	(segment
		(start 265.472672 -375.372884)
		(end 162.752024 -384.089402)
		(width 0.14732)
		(layer "In6.Cu")
		(net "UPI_CPU0_CPU1_P2P2_DP<10>")
	)
	(segment
		(start 89.807034 -301.271686)
		(end 90.512138 -300.693074)
		(width 0.14732)
		(layer "In6.Cu")
		(net "UPI_CPU0_CPU1_P2P2_DP<10>")
	)
	(segment
		(start 271.919192 -368.926364)
		(end 265.472672 -375.372884)
		(width 0.14732)
		(layer "In6.Cu")
		(net "UPI_CPU0_CPU1_P2P2_DP<10>")
	)
	(segment
		(start 344.093292 -294.614346)
		(end 344.093292 -294.810434)
		(width 0.14732)
		(layer "In6.Cu")
		(net "UPI_CPU0_CPU1_P2P2_DP<10>")
	)
	(segment
		(start 345.968066 -290.06927)
		(end 345.750642 -290.286694)
		(width 0.0889)
		(layer "In6.Cu")
		(net "UPI_CPU0_CPU1_P2P2_DP<10>")
	)
	(segment
		(start 65.268094 -330.203556)
		(end 65.42659 -330.073508)
		(width 0.14732)
		(layer "In6.Cu")
		(net "UPI_CPU0_CPU1_P2P2_DP<10>")
	)
	(segment
		(start 347.19895 -284.353)
		(end 347.19006 -284.35808)
		(width 0.0889)
		(layer "In6.Cu")
		(net "UPI_CPU0_CPU1_P2P2_DP<10>")
	)
	(segment
		(start 88.925908 -302.152304)
		(end 88.942926 -301.980854)
		(width 0.14732)
		(layer "In6.Cu")
		(net "UPI_CPU0_CPU1_P2P2_DP<10>")
	)
	(segment
		(start 93.629988 -293.059358)
		(end 93.629988 -292.691058)
		(width 0.14732)
		(layer "In6.Cu")
		(net "UPI_CPU0_CPU1_P2P2_DP<10>")
	)
	(segment
		(start 347.659452 -283.544772)
		(end 347.656658 -283.546296)
		(width 0.0889)
		(layer "In6.Cu")
		(net "UPI_CPU0_CPU1_P2P2_DP<10>")
	)
	(segment
		(start 337.638136 -303.34966)
		(end 316.362842 -324.624954)
		(width 0.14732)
		(layer "In6.Cu")
		(net "UPI_CPU0_CPU1_P2P2_DP<10>")
	)
	(segment
		(start 96.592644 -379.819154)
		(end 74.458322 -370.651024)
		(width 0.14732)
		(layer "In6.Cu")
		(net "UPI_CPU0_CPU1_P2P2_DP<10>")
	)
	(segment
		(start 346.437712 -285.661354)
		(end 346.437712 -285.679896)
		(width 0.0889)
		(layer "In6.Cu")
		(net "UPI_CPU0_CPU1_P2P2_DP<10>")
	)
	(segment
		(start 72.096376 -368.289078)
		(end 71.787512 -367.980214)
		(width 0.14732)
		(layer "In6.Cu")
		(net "UPI_CPU0_CPU1_P2P2_DP<10>")
	)
	(segment
		(start 87.67572 -303.178464)
		(end 88.013794 -302.901096)
		(width 0.14732)
		(layer "In6.Cu")
		(net "UPI_CPU0_CPU1_P2P2_DP<10>")
	)
	(segment
		(start 344.093038 -294.810688)
		(end 344.093038 -297.794426)
		(width 0.14732)
		(layer "In6.Cu")
		(net "UPI_CPU0_CPU1_P2P2_DP<10>")
	)
	(segment
		(start 345.486228 -290.551108)
		(end 344.135202 -291.902134)
		(width 0.0889)
		(layer "In6.Cu")
		(net "UPI_CPU0_CPU1_P2P2_DP<10>")
	)
	(segment
		(start 96.987106 -283.714444)
		(end 97.002346 -283.705554)
		(width 0.0889)
		(layer "In6.Cu")
		(net "UPI_CPU0_CPU1_P2P2_DP<10>")
	)
	(segment
		(start 346.437712 -287.279334)
		(end 346.437712 -287.28924)
		(width 0.0889)
		(layer "In6.Cu")
		(net "UPI_CPU0_CPU1_P2P2_DP<10>")
	)
	(segment
		(start 93.485208 -293.204138)
		(end 93.629988 -293.059358)
		(width 0.14732)
		(layer "In6.Cu")
		(net "UPI_CPU0_CPU1_P2P2_DP<10>")
	)
	(segment
		(start 345.498166 -289.113722)
		(end 345.49842 -289.113976)
		(width 0.0889)
		(layer "In6.Cu")
		(net "UPI_CPU0_CPU1_P2P2_DP<10>")
	)
	(segment
		(start 315.247528 -327.317608)
		(end 307.803296 -334.76184)
		(width 0.14732)
		(layer "In6.Cu")
		(net "UPI_CPU0_CPU1_P2P2_DP<10>")
	)
	(segment
		(start 93.485208 -291.801804)
		(end 93.878908 -291.408104)
		(width 0.14732)
		(layer "In6.Cu")
		(net "UPI_CPU0_CPU1_P2P2_DP<10>")
	)
	(segment
		(start 96.994472 -282.08224)
		(end 96.995996 -282.081478)
		(width 0.0889)
		(layer "In6.Cu")
		(net "UPI_CPU0_CPU1_P2P2_DP<10>")
	)
	(segment
		(start 345.61018 -290.286694)
		(end 345.486228 -290.410646)
		(width 0.0889)
		(layer "In6.Cu")
		(net "UPI_CPU0_CPU1_P2P2_DP<10>")
	)
	(segment
		(start 347.656658 -283.546296)
		(end 347.654118 -283.54782)
		(width 0.0889)
		(layer "In6.Cu")
		(net "UPI_CPU0_CPU1_P2P2_DP<10>")
	)
	(segment
		(start 280.32964 -336.898488)
		(end 271.919192 -345.308936)
		(width 0.14732)
		(layer "In6.Cu")
		(net "UPI_CPU0_CPU1_P2P2_DP<10>")
	)
	(segment
		(start 69.810884 -366.003586)
		(end 65.041018 -354.487734)
		(width 0.14732)
		(layer "In6.Cu")
		(net "UPI_CPU0_CPU1_P2P2_DP<10>")
	)
	(segment
		(start 72.57796 -368.770662)
		(end 72.57796 -368.598196)
		(width 0.14732)
		(layer "In6.Cu")
		(net "UPI_CPU0_CPU1_P2P2_DP<10>")
	)
	(segment
		(start 316.362842 -324.624954)
		(end 315.247528 -327.317608)
		(width 0.14732)
		(layer "In6.Cu")
		(net "UPI_CPU0_CPU1_P2P2_DP<10>")
	)
	(segment
		(start 96.51746 -284.52826)
		(end 96.52635 -284.52318)
		(width 0.0889)
		(layer "In6.Cu")
		(net "UPI_CPU0_CPU1_P2P2_DP<10>")
	)
	(segment
		(start 344.135202 -291.902134)
		(end 344.135202 -292.26256)
		(width 0.0889)
		(layer "In6.Cu")
		(net "UPI_CPU0_CPU1_P2P2_DP<10>")
	)
	(segment
		(start 97.78873 -281.243024)
		(end 97.809812 -281.321002)
		(width 0.0889)
		(layer "In6.Cu")
		(net "UPI_CPU0_CPU1_P2P2_DP<10>")
	)
	(segment
		(start 96.056958 -285.336488)
		(end 96.062292 -285.33344)
		(width 0.0889)
		(layer "In6.Cu")
		(net "UPI_CPU0_CPU1_P2P2_DP<10>")
	)
	(segment
		(start 96.056196 -285.336996)
		(end 96.056958 -285.336488)
		(width 0.0889)
		(layer "In6.Cu")
		(net "UPI_CPU0_CPU1_P2P2_DP<10>")
	)
	(segment
		(start 93.485208 -297.226228)
		(end 93.485208 -295.256458)
		(width 0.14732)
		(layer "In6.Cu")
		(net "UPI_CPU0_CPU1_P2P2_DP<10>")
	)
	(segment
		(start 92.366338 -299.504354)
		(end 92.764356 -298.967652)
		(width 0.14732)
		(layer "In6.Cu")
		(net "UPI_CPU0_CPU1_P2P2_DP<10>")
	)
	(segment
		(start 71.787512 -367.807748)
		(end 71.47814 -367.498376)
		(width 0.14732)
		(layer "In6.Cu")
		(net "UPI_CPU0_CPU1_P2P2_DP<10>")
	)
	(segment
		(start 345.930728 -289.604704)
		(end 345.968066 -289.64509)
		(width 0.0889)
		(layer "In6.Cu")
		(net "UPI_CPU0_CPU1_P2P2_DP<10>")
	)
	(segment
		(start 70.975982 -366.996218)
		(end 70.66661 -366.686846)
		(width 0.14732)
		(layer "In6.Cu")
		(net "UPI_CPU0_CPU1_P2P2_DP<10>")
	)
	(segment
		(start 93.629988 -295.111678)
		(end 93.629988 -294.743378)
		(width 0.14732)
		(layer "In6.Cu")
		(net "UPI_CPU0_CPU1_P2P2_DP<10>")
	)
	(segment
		(start 89.790016 -301.44339)
		(end 89.807034 -301.271686)
		(width 0.14732)
		(layer "In6.Cu")
		(net "UPI_CPU0_CPU1_P2P2_DP<10>")
	)
	(segment
		(start 86.072472 -304.33645)
		(end 87.50427 -303.161446)
		(width 0.14732)
		(layer "In6.Cu")
		(net "UPI_CPU0_CPU1_P2P2_DP<10>")
	)
	(segment
		(start 89.280492 -301.70374)
		(end 89.452196 -301.720758)
		(width 0.14732)
		(layer "In6.Cu")
		(net "UPI_CPU0_CPU1_P2P2_DP<10>")
	)
	(segment
		(start 96.995996 -282.081478)
		(end 96.996758 -282.08097)
		(width 0.0889)
		(layer "In6.Cu")
		(net "UPI_CPU0_CPU1_P2P2_DP<10>")
	)
	(segment
		(start 87.50427 -303.161446)
		(end 87.67572 -303.178464)
		(width 0.14732)
		(layer "In6.Cu")
		(net "UPI_CPU0_CPU1_P2P2_DP<10>")
	)
	(segment
		(start 344.036142 -293.08552)
		(end 344.135202 -293.18458)
		(width 0.0889)
		(layer "In6.Cu")
		(net "UPI_CPU0_CPU1_P2P2_DP<10>")
	)
	(segment
		(start 344.135202 -292.8112)
		(end 344.036142 -292.91026)
		(width 0.0889)
		(layer "In6.Cu")
		(net "UPI_CPU0_CPU1_P2P2_DP<10>")
	)
	(segment
		(start 89.452196 -301.720758)
		(end 89.790016 -301.44339)
		(width 0.14732)
		(layer "In6.Cu")
		(net "UPI_CPU0_CPU1_P2P2_DP<10>")
	)
	(segment
		(start 345.498166 -288.898584)
		(end 345.498166 -289.113722)
		(width 0.0889)
		(layer "In6.Cu")
		(net "UPI_CPU0_CPU1_P2P2_DP<10>")
	)
	(segment
		(start 346.72016 -286.151066)
		(end 346.72905 -286.156146)
		(width 0.0889)
		(layer "In6.Cu")
		(net "UPI_CPU0_CPU1_P2P2_DP<10>")
	)
	(segment
		(start 71.787512 -367.980214)
		(end 71.787512 -367.807748)
		(width 0.14732)
		(layer "In6.Cu")
		(net "UPI_CPU0_CPU1_P2P2_DP<10>")
	)
	(segment
		(start 93.629988 -293.717218)
		(end 93.485208 -293.572438)
		(width 0.14732)
		(layer "In6.Cu")
		(net "UPI_CPU0_CPU1_P2P2_DP<10>")
	)
	(segment
		(start 65.100454 -331.904594)
		(end 65.25895 -331.7748)
		(width 0.14732)
		(layer "In6.Cu")
		(net "UPI_CPU0_CPU1_P2P2_DP<10>")
	)
	(segment
		(start 65.165224 -331.249782)
		(end 65.268094 -330.203556)
		(width 0.14732)
		(layer "In6.Cu")
		(net "UPI_CPU0_CPU1_P2P2_DP<10>")
	)
	(segment
		(start 96.054672 -285.337758)
		(end 96.056196 -285.336996)
		(width 0.0889)
		(layer "In6.Cu")
		(net "UPI_CPU0_CPU1_P2P2_DP<10>")
	)
	(segment
		(start 344.036142 -292.53688)
		(end 344.135202 -292.63594)
		(width 0.0889)
		(layer "In6.Cu")
		(net "UPI_CPU0_CPU1_P2P2_DP<10>")
	)
	(segment
		(start 97.809812 -281.321002)
		(end 97.653348 -281.59202)
		(width 0.0889)
		(layer "In6.Cu")
		(net "UPI_CPU0_CPU1_P2P2_DP<10>")
	)
	(segment
		(start 93.629988 -294.085518)
		(end 93.629988 -293.717218)
		(width 0.14732)
		(layer "In6.Cu")
		(net "UPI_CPU0_CPU1_P2P2_DP<10>")
	)
	(segment
		(start 97.278698 -283.219906)
		(end 97.278698 -283.205682)
		(width 0.0889)
		(layer "In6.Cu")
		(net "UPI_CPU0_CPU1_P2P2_DP<10>")
	)
	(segment
		(start 94.45879 -289.646868)
		(end 94.459044 -289.64636)
		(width 0.0889)
		(layer "In6.Cu")
		(net "UPI_CPU0_CPU1_P2P2_DP<10>")
	)
	(segment
		(start 65.462658 -329.706732)
		(end 65.33261 -329.54849)
		(width 0.14732)
		(layer "In6.Cu")
		(net "UPI_CPU0_CPU1_P2P2_DP<10>")
	)
	(segment
		(start 90.512138 -300.693074)
		(end 91.15552 -300.497748)
		(width 0.14732)
		(layer "In6.Cu")
		(net "UPI_CPU0_CPU1_P2P2_DP<10>")
	)
	(segment
		(start 65.33261 -329.54849)
		(end 65.376298 -329.10399)
		(width 0.14732)
		(layer "In6.Cu")
		(net "UPI_CPU0_CPU1_P2P2_DP<10>")
	)
	(segment
		(start 95.868744 -287.304734)
		(end 95.868744 -287.28924)
		(width 0.0889)
		(layer "In6.Cu")
		(net "UPI_CPU0_CPU1_P2P2_DP<10>")
	)
	(segment
		(start 71.47814 -367.498376)
		(end 71.305674 -367.498376)
		(width 0.14732)
		(layer "In6.Cu")
		(net "UPI_CPU0_CPU1_P2P2_DP<10>")
	)
	(segment
		(start 347.62948 -282.948888)
		(end 347.707458 -282.92806)
		(width 0.0889)
		(layer "In6.Cu")
		(net "UPI_CPU0_CPU1_P2P2_DP<10>")
	)
	(segment
		(start 347.847412 -283.21127)
		(end 347.847412 -283.228542)
		(width 0.0889)
		(layer "In6.Cu")
		(net "UPI_CPU0_CPU1_P2P2_DP<10>")
	)
	(segment
		(start 345.486228 -290.410646)
		(end 345.486228 -290.551108)
		(width 0.0889)
		(layer "In6.Cu")
		(net "UPI_CPU0_CPU1_P2P2_DP<10>")
	)
	(segment
		(start 93.485208 -293.572438)
		(end 93.485208 -293.204138)
		(width 0.14732)
		(layer "In6.Cu")
		(net "UPI_CPU0_CPU1_P2P2_DP<10>")
	)
	(segment
		(start 343.792556 -298.393104)
		(end 343.22131 -299.772832)
		(width 0.14732)
		(layer "In6.Cu")
		(net "UPI_CPU0_CPU1_P2P2_DP<10>")
	)
	(segment
		(start 344.135202 -294.550338)
		(end 344.093292 -294.592248)
		(width 0.0889)
		(layer "In6.Cu")
		(net "UPI_CPU0_CPU1_P2P2_DP<10>")
	)
	(segment
		(start 65.42659 -330.073508)
		(end 65.462658 -329.706732)
		(width 0.14732)
		(layer "In6.Cu")
		(net "UPI_CPU0_CPU1_P2P2_DP<10>")
	)
	(segment
		(start 72.268842 -368.289078)
		(end 72.096376 -368.289078)
		(width 0.14732)
		(layer "In6.Cu")
		(net "UPI_CPU0_CPU1_P2P2_DP<10>")
	)
	(segment
		(start 346.729304 -285.166816)
		(end 346.714064 -285.175706)
		(width 0.0889)
		(layer "In6.Cu")
		(net "UPI_CPU0_CPU1_P2P2_DP<10>")
	)
	(arc
		(start 96.047306 -285.980632)
		(mid 95.868588 -285.661354)
		(end 96.047306 -285.342076)
		(width 0.0889)
		(layer "In6.Cu")
		(net "UPI_CPU0_CPU1_P2P2_DP<10>")
	)
	(arc
		(start 97.278698 -281.59202)
		(mid 97.326377 -281.40912)
		(end 97.45726 -281.272742)
		(width 0.0889)
		(layer "In6.Cu")
		(net "UPI_CPU0_CPU1_P2P2_DP<10>")
	)
	(arc
		(start 96.808544 -284.033722)
		(mid 96.856223 -283.850822)
		(end 96.987106 -283.714444)
		(width 0.0889)
		(layer "In6.Cu")
		(net "UPI_CPU0_CPU1_P2P2_DP<10>")
	)
	(arc
		(start 347.377512 -284.033722)
		(mid 347.329833 -284.216622)
		(end 347.19895 -284.353)
		(width 0.0889)
		(layer "In6.Cu")
		(net "UPI_CPU0_CPU1_P2P2_DP<10>")
	)
	(arc
		(start 346.72016 -286.799782)
		(mid 346.515825 -287.002387)
		(end 346.437712 -287.279334)
		(width 0.0889)
		(layer "In6.Cu")
		(net "UPI_CPU0_CPU1_P2P2_DP<10>")
	)
	(arc
		(start 94.929198 -288.917126)
		(mid 94.976877 -288.734226)
		(end 95.10776 -288.597848)
		(width 0.0889)
		(layer "In6.Cu")
		(net "UPI_CPU0_CPU1_P2P2_DP<10>")
	)
	(arc
		(start 347.707458 -282.92806)
		(mid 347.808779 -283.054181)
		(end 347.847412 -283.21127)
		(width 0.0889)
		(layer "In6.Cu")
		(net "UPI_CPU0_CPU1_P2P2_DP<10>")
	)
	(arc
		(start 345.49842 -289.113976)
		(mid 345.505688 -289.133923)
		(end 345.51366 -289.1536)
		(width 0.0889)
		(layer "In6.Cu")
		(net "UPI_CPU0_CPU1_P2P2_DP<10>")
	)
	(arc
		(start 97.278698 -283.205682)
		(mid 97.199479 -282.930997)
		(end 96.995996 -282.730194)
		(width 0.0889)
		(layer "In6.Cu")
		(net "UPI_CPU0_CPU1_P2P2_DP<10>")
	)
	(arc
		(start 96.062292 -286.961326)
		(mid 96.264879 -286.754975)
		(end 96.338898 -286.475424)
		(width 0.0889)
		(layer "In6.Cu")
		(net "UPI_CPU0_CPU1_P2P2_DP<10>")
	)
	(arc
		(start 96.987106 -282.725114)
		(mid 96.808388 -282.405836)
		(end 96.987106 -282.086558)
		(width 0.0889)
		(layer "In6.Cu")
		(net "UPI_CPU0_CPU1_P2P2_DP<10>")
	)
	(arc
		(start 96.338898 -284.847538)
		(mid 96.386577 -284.664638)
		(end 96.51746 -284.52826)
		(width 0.0889)
		(layer "In6.Cu")
		(net "UPI_CPU0_CPU1_P2P2_DP<10>")
	)
	(arc
		(start 346.25026 -287.613598)
		(mid 346.047437 -287.813829)
		(end 345.968066 -288.087562)
		(width 0.0889)
		(layer "In6.Cu")
		(net "UPI_CPU0_CPU1_P2P2_DP<10>")
	)
	(arc
		(start 94.643448 -289.446462)
		(mid 94.817749 -289.307532)
		(end 94.929198 -289.114484)
		(width 0.0889)
		(layer "In6.Cu")
		(net "UPI_CPU0_CPU1_P2P2_DP<10>")
	)
	(arc
		(start 95.868744 -287.28924)
		(mid 95.916423 -287.10634)
		(end 96.047306 -286.969962)
		(width 0.0889)
		(layer "In6.Cu")
		(net "UPI_CPU0_CPU1_P2P2_DP<10>")
	)
	(arc
		(start 96.338898 -286.4612)
		(mid 96.259679 -286.186515)
		(end 96.056196 -285.985712)
		(width 0.0889)
		(layer "In6.Cu")
		(net "UPI_CPU0_CPU1_P2P2_DP<10>")
	)
	(arc
		(start 347.19006 -284.35808)
		(mid 346.987237 -284.558311)
		(end 346.907866 -284.832044)
		(width 0.0889)
		(layer "In6.Cu")
		(net "UPI_CPU0_CPU1_P2P2_DP<10>")
	)
	(arc
		(start 346.72905 -286.156146)
		(mid 346.907647 -286.475424)
		(end 346.72905 -286.794702)
		(width 0.0889)
		(layer "In6.Cu")
		(net "UPI_CPU0_CPU1_P2P2_DP<10>")
	)
	(arc
		(start 345.730068 -289.414204)
		(mid 345.743667 -289.423027)
		(end 345.7575 -289.431476)
		(width 0.0889)
		(layer "In6.Cu")
		(net "UPI_CPU0_CPU1_P2P2_DP<10>")
	)
	(arc
		(start 97.002092 -283.705808)
		(mid 97.204679 -283.499457)
		(end 97.278698 -283.219906)
		(width 0.0889)
		(layer "In6.Cu")
		(net "UPI_CPU0_CPU1_P2P2_DP<10>")
	)
	(arc
		(start 97.46615 -281.267662)
		(mid 97.624638 -281.218729)
		(end 97.78873 -281.243024)
		(width 0.0889)
		(layer "In6.Cu")
		(net "UPI_CPU0_CPU1_P2P2_DP<10>")
	)
	(arc
		(start 94.459044 -289.64636)
		(mid 94.534115 -289.530618)
		(end 94.643448 -289.446462)
		(width 0.0889)
		(layer "In6.Cu")
		(net "UPI_CPU0_CPU1_P2P2_DP<10>")
	)
	(arc
		(start 96.062292 -285.33344)
		(mid 96.264879 -285.127089)
		(end 96.338898 -284.847538)
		(width 0.0889)
		(layer "In6.Cu")
		(net "UPI_CPU0_CPU1_P2P2_DP<10>")
	)
	(arc
		(start 346.714318 -285.175452)
		(mid 346.511731 -285.381803)
		(end 346.437712 -285.661354)
		(width 0.0889)
		(layer "In6.Cu")
		(net "UPI_CPU0_CPU1_P2P2_DP<10>")
	)
	(arc
		(start 97.002092 -282.077922)
		(mid 97.204679 -281.871571)
		(end 97.278698 -281.59202)
		(width 0.0889)
		(layer "In6.Cu")
		(net "UPI_CPU0_CPU1_P2P2_DP<10>")
	)
	(arc
		(start 345.780614 -288.427414)
		(mid 345.578328 -288.626395)
		(end 345.498166 -288.898584)
		(width 0.0889)
		(layer "In6.Cu")
		(net "UPI_CPU0_CPU1_P2P2_DP<10>")
	)
	(arc
		(start 346.907866 -284.847538)
		(mid 346.860187 -285.030438)
		(end 346.729304 -285.166816)
		(width 0.0889)
		(layer "In6.Cu")
		(net "UPI_CPU0_CPU1_P2P2_DP<10>")
	)
	(arc
		(start 347.847412 -283.228542)
		(mid 347.795142 -283.410907)
		(end 347.660214 -283.544264)
		(width 0.0889)
		(layer "In6.Cu")
		(net "UPI_CPU0_CPU1_P2P2_DP<10>")
	)
	(arc
		(start 347.654118 -283.54782)
		(mid 347.451531 -283.754171)
		(end 347.377512 -284.033722)
		(width 0.0889)
		(layer "In6.Cu")
		(net "UPI_CPU0_CPU1_P2P2_DP<10>")
	)
	(arc
		(start 345.968066 -288.103056)
		(mid 345.920387 -288.285956)
		(end 345.789504 -288.422334)
		(width 0.0889)
		(layer "In6.Cu")
		(net "UPI_CPU0_CPU1_P2P2_DP<10>")
	)
	(arc
		(start 95.399098 -288.103056)
		(mid 95.446777 -287.920156)
		(end 95.57766 -287.783778)
		(width 0.0889)
		(layer "In6.Cu")
		(net "UPI_CPU0_CPU1_P2P2_DP<10>")
	)
	(arc
		(start 96.52635 -284.52318)
		(mid 96.729173 -284.322949)
		(end 96.808544 -284.049216)
		(width 0.0889)
		(layer "In6.Cu")
		(net "UPI_CPU0_CPU1_P2P2_DP<10>")
	)
	(arc
		(start 345.51366 -289.1536)
		(mid 345.603024 -289.299549)
		(end 345.730068 -289.414204)
		(width 0.0889)
		(layer "In6.Cu")
		(net "UPI_CPU0_CPU1_P2P2_DP<10>")
	)
	(arc
		(start 346.437712 -285.679896)
		(mid 346.517874 -285.952085)
		(end 346.72016 -286.151066)
		(width 0.0889)
		(layer "In6.Cu")
		(net "UPI_CPU0_CPU1_P2P2_DP<10>")
	)
	(arc
		(start 95.58655 -287.778698)
		(mid 95.789373 -287.578467)
		(end 95.868744 -287.304734)
		(width 0.0889)
		(layer "In6.Cu")
		(net "UPI_CPU0_CPU1_P2P2_DP<10>")
	)
	(arc
		(start 95.11665 -288.592768)
		(mid 95.318936 -288.393787)
		(end 95.399098 -288.121598)
		(width 0.0889)
		(layer "In6.Cu")
		(net "UPI_CPU0_CPU1_P2P2_DP<10>")
	)
	(arc
		(start 346.437712 -287.28924)
		(mid 346.390033 -287.47214)
		(end 346.25915 -287.608518)
		(width 0.0889)
		(layer "In6.Cu")
		(net "UPI_CPU0_CPU1_P2P2_DP<10>")
	)
	(segment
		(start 357.340662 -273.730974)
		(end 357.340662 -274.266914)
		(width 0.13208)
		(layer "F.Cu")
		(net "UPI_CPU0_CPU1_P2P2_DP<0>")
	)
	(segment
		(start 87.785194 -280.242264)
		(end 87.785194 -280.778204)
		(width 0.13208)
		(layer "F.Cu")
		(net "UPI_CPU0_CPU1_P2P2_DP<0>")
	)
	(segment
		(start 356.588314 -284.35808)
		(end 356.582218 -284.361636)
		(width 0.0889)
		(layer "In6.Cu")
		(net "UPI_CPU0_CPU1_P2P2_DP<0>")
	)
	(segment
		(start 356.263448 -295.949878)
		(end 356.118668 -296.094658)
		(width 0.14732)
		(layer "In6.Cu")
		(net "UPI_CPU0_CPU1_P2P2_DP<0>")
	)
	(segment
		(start 82.065622 -383.201418)
		(end 81.876646 -383.27965)
		(width 0.14732)
		(layer "In6.Cu")
		(net "UPI_CPU0_CPU1_P2P2_DP<0>")
	)
	(segment
		(start 87.11946 -281.272742)
		(end 87.127334 -281.26817)
		(width 0.0889)
		(layer "In6.Cu")
		(net "UPI_CPU0_CPU1_P2P2_DP<0>")
	)
	(segment
		(start 356.118668 -293.900098)
		(end 356.118668 -294.268398)
		(width 0.14732)
		(layer "In6.Cu")
		(net "UPI_CPU0_CPU1_P2P2_DP<0>")
	)
	(segment
		(start 59.788298 -312.083958)
		(end 61.575696 -310.889396)
		(width 0.14732)
		(layer "In6.Cu")
		(net "UPI_CPU0_CPU1_P2P2_DP<0>")
	)
	(segment
		(start 346.774262 -308.318408)
		(end 346.774262 -308.490874)
		(width 0.14732)
		(layer "In6.Cu")
		(net "UPI_CPU0_CPU1_P2P2_DP<0>")
	)
	(segment
		(start 85.203538 -284.548326)
		(end 85.247734 -284.523688)
		(width 0.0889)
		(layer "In6.Cu")
		(net "UPI_CPU0_CPU1_P2P2_DP<0>")
	)
	(segment
		(start 53.072284 -317.320168)
		(end 53.072284 -316.58814)
		(width 0.14732)
		(layer "In6.Cu")
		(net "UPI_CPU0_CPU1_P2P2_DP<0>")
	)
	(segment
		(start 356.118668 -298.383198)
		(end 356.263448 -298.527978)
		(width 0.14732)
		(layer "In6.Cu")
		(net "UPI_CPU0_CPU1_P2P2_DP<0>")
	)
	(segment
		(start 87.127334 -281.26817)
		(end 87.12835 -281.267662)
		(width 0.0889)
		(layer "In6.Cu")
		(net "UPI_CPU0_CPU1_P2P2_DP<0>")
	)
	(segment
		(start 83.458558 -383.935478)
		(end 83.380072 -383.745994)
		(width 0.14732)
		(layer "In6.Cu")
		(net "UPI_CPU0_CPU1_P2P2_DP<0>")
	)
	(segment
		(start 356.118668 -296.094658)
		(end 356.118668 -296.462958)
		(width 0.14732)
		(layer "In6.Cu")
		(net "UPI_CPU0_CPU1_P2P2_DP<0>")
	)
	(segment
		(start 356.263448 -294.413178)
		(end 356.263448 -295.949878)
		(width 0.14732)
		(layer "In6.Cu")
		(net "UPI_CPU0_CPU1_P2P2_DP<0>")
	)
	(segment
		(start 70.669658 -378.481336)
		(end 70.329044 -378.340366)
		(width 0.14732)
		(layer "In6.Cu")
		(net "UPI_CPU0_CPU1_P2P2_DP<0>")
	)
	(segment
		(start 323.605398 -329.132438)
		(end 322.3895 -332.067916)
		(width 0.14732)
		(layer "In6.Cu")
		(net "UPI_CPU0_CPU1_P2P2_DP<0>")
	)
	(segment
		(start 356.118668 -294.268398)
		(end 356.263448 -294.413178)
		(width 0.14732)
		(layer "In6.Cu")
		(net "UPI_CPU0_CPU1_P2P2_DP<0>")
	)
	(segment
		(start 50.936906 -318.851026)
		(end 52.058062 -318.06642)
		(width 0.14732)
		(layer "In6.Cu")
		(net "UPI_CPU0_CPU1_P2P2_DP<0>")
	)
	(segment
		(start 50.668936 -329.210924)
		(end 50.668682 -329.210924)
		(width 0.14732)
		(layer "In6.Cu")
		(net "UPI_CPU0_CPU1_P2P2_DP<0>")
	)
	(segment
		(start 357.05796 -279.639776)
		(end 357.06685 -279.644856)
		(width 0.0889)
		(layer "In6.Cu")
		(net "UPI_CPU0_CPU1_P2P2_DP<0>")
	)
	(segment
		(start 50.365152 -328.478134)
		(end 50.365152 -324.724776)
		(width 0.14732)
		(layer "In6.Cu")
		(net "UPI_CPU0_CPU1_P2P2_DP<0>")
	)
	(segment
		(start 356.118668 -296.462958)
		(end 356.263448 -296.607738)
		(width 0.14732)
		(layer "In6.Cu")
		(net "UPI_CPU0_CPU1_P2P2_DP<0>")
	)
	(segment
		(start 356.305612 -290.491926)
		(end 356.305612 -290.667186)
		(width 0.0889)
		(layer "In6.Cu")
		(net "UPI_CPU0_CPU1_P2P2_DP<0>")
	)
	(segment
		(start 59.761882 -363.931454)
		(end 59.761882 -363.9312)
		(width 0.14732)
		(layer "In6.Cu")
		(net "UPI_CPU0_CPU1_P2P2_DP<0>")
	)
	(segment
		(start 83.767422 -290.086288)
		(end 83.98891 -289.8648)
		(width 0.14732)
		(layer "In6.Cu")
		(net "UPI_CPU0_CPU1_P2P2_DP<0>")
	)
	(segment
		(start 58.377074 -312.47842)
		(end 58.90387 -312.260234)
		(width 0.14732)
		(layer "In6.Cu")
		(net "UPI_CPU0_CPU1_P2P2_DP<0>")
	)
	(segment
		(start 86.000844 -283.229812)
		(end 86.000844 -283.219906)
		(width 0.0889)
		(layer "In6.Cu")
		(net "UPI_CPU0_CPU1_P2P2_DP<0>")
	)
	(segment
		(start 356.305612 -290.667186)
		(end 356.206552 -290.766246)
		(width 0.0889)
		(layer "In6.Cu")
		(net "UPI_CPU0_CPU1_P2P2_DP<0>")
	)
	(segment
		(start 54.15153 -315.065664)
		(end 55.920132 -314.120022)
		(width 0.14732)
		(layer "In6.Cu")
		(net "UPI_CPU0_CPU1_P2P2_DP<0>")
	)
	(segment
		(start 50.668682 -329.210924)
		(end 50.59299 -329.028044)
		(width 0.14732)
		(layer "In6.Cu")
		(net "UPI_CPU0_CPU1_P2P2_DP<0>")
	)
	(segment
		(start 71.696072 -379.06325)
		(end 71.61784 -378.87402)
		(width 0.14732)
		(layer "In6.Cu")
		(net "UPI_CPU0_CPU1_P2P2_DP<0>")
	)
	(segment
		(start 357.528622 -276.21865)
		(end 357.527606 -276.219158)
		(width 0.0889)
		(layer "In6.Cu")
		(net "UPI_CPU0_CPU1_P2P2_DP<0>")
	)
	(segment
		(start 269.470886 -383.624328)
		(end 161.721038 -392.724132)
		(width 0.14732)
		(layer "In6.Cu")
		(net "UPI_CPU0_CPU1_P2P2_DP<0>")
	)
	(segment
		(start 356.263448 -293.023036)
		(end 356.263448 -293.755318)
		(width 0.14732)
		(layer "In6.Cu")
		(net "UPI_CPU0_CPU1_P2P2_DP<0>")
	)
	(segment
		(start 357.52786 -273.942556)
		(end 357.53675 -273.947636)
		(width 0.0889)
		(layer "In6.Cu")
		(net "UPI_CPU0_CPU1_P2P2_DP<0>")
	)
	(segment
		(start 71.277226 -378.73305)
		(end 71.087996 -378.811282)
		(width 0.14732)
		(layer "In6.Cu")
		(net "UPI_CPU0_CPU1_P2P2_DP<0>")
	)
	(segment
		(start 356.263448 -293.755318)
		(end 356.118668 -293.900098)
		(width 0.14732)
		(layer "In6.Cu")
		(net "UPI_CPU0_CPU1_P2P2_DP<0>")
	)
	(segment
		(start 346.774262 -308.490874)
		(end 345.69019 -309.574946)
		(width 0.14732)
		(layer "In6.Cu")
		(net "UPI_CPU0_CPU1_P2P2_DP<0>")
	)
	(segment
		(start 84.004404 -289.789362)
		(end 84.337906 -289.45586)
		(width 0.0889)
		(layer "In6.Cu")
		(net "UPI_CPU0_CPU1_P2P2_DP<0>")
	)
	(segment
		(start 356.206552 -290.941506)
		(end 356.305612 -291.040566)
		(width 0.0889)
		(layer "In6.Cu")
		(net "UPI_CPU0_CPU1_P2P2_DP<0>")
	)
	(segment
		(start 50.541936 -319.413636)
		(end 50.936906 -318.851026)
		(width 0.14732)
		(layer "In6.Cu")
		(net "UPI_CPU0_CPU1_P2P2_DP<0>")
	)
	(segment
		(start 85.530944 -284.043628)
		(end 85.530944 -284.033722)
		(width 0.0889)
		(layer "In6.Cu")
		(net "UPI_CPU0_CPU1_P2P2_DP<0>")
	)
	(segment
		(start 59.761374 -363.930692)
		(end 59.761628 -363.930692)
		(width 0.14732)
		(layer "In6.Cu")
		(net "UPI_CPU0_CPU1_P2P2_DP<0>")
	)
	(segment
		(start 356.305612 -291.764466)
		(end 356.206552 -291.863526)
		(width 0.0889)
		(layer "In6.Cu")
		(net "UPI_CPU0_CPU1_P2P2_DP<0>")
	)
	(segment
		(start 59.761628 -363.930692)
		(end 56.714898 -356.575106)
		(width 0.14732)
		(layer "In6.Cu")
		(net "UPI_CPU0_CPU1_P2P2_DP<0>")
	)
	(segment
		(start 69.947282 -305.708304)
		(end 80.43164 -295.2242)
		(width 0.14732)
		(layer "In6.Cu")
		(net "UPI_CPU0_CPU1_P2P2_DP<0>")
	)
	(segment
		(start 356.263702 -293.022782)
		(end 356.263448 -293.023036)
		(width 0.14732)
		(layer "In6.Cu")
		(net "UPI_CPU0_CPU1_P2P2_DP<0>")
	)
	(segment
		(start 357.52786 -277.198074)
		(end 357.53675 -277.203154)
		(width 0.0889)
		(layer "In6.Cu")
		(net "UPI_CPU0_CPU1_P2P2_DP<0>")
	)
	(segment
		(start 53.072284 -316.58814)
		(end 53.38572 -315.831474)
		(width 0.14732)
		(layer "In6.Cu")
		(net "UPI_CPU0_CPU1_P2P2_DP<0>")
	)
	(segment
		(start 356.263448 -296.607738)
		(end 356.263448 -297.870118)
		(width 0.14732)
		(layer "In6.Cu")
		(net "UPI_CPU0_CPU1_P2P2_DP<0>")
	)
	(segment
		(start 356.775512 -284.023816)
		(end 356.775512 -284.042358)
		(width 0.0889)
		(layer "In6.Cu")
		(net "UPI_CPU0_CPU1_P2P2_DP<0>")
	)
	(segment
		(start 356.263702 -292.829488)
		(end 356.263702 -292.851586)
		(width 0.0889)
		(layer "In6.Cu")
		(net "UPI_CPU0_CPU1_P2P2_DP<0>")
	)
	(segment
		(start 357.340662 -274.266914)
		(end 357.184198 -273.995896)
		(width 0.0889)
		(layer "In6.Cu")
		(net "UPI_CPU0_CPU1_P2P2_DP<0>")
	)
	(segment
		(start 357.06685 -280.283412)
		(end 357.05796 -280.288492)
		(width 0.0889)
		(layer "In6.Cu")
		(net "UPI_CPU0_CPU1_P2P2_DP<0>")
	)
	(segment
		(start 356.305612 -290.118546)
		(end 356.206552 -290.217606)
		(width 0.0889)
		(layer "In6.Cu")
		(net "UPI_CPU0_CPU1_P2P2_DP<0>")
	)
	(segment
		(start 356.206552 -291.490146)
		(end 356.305612 -291.589206)
		(width 0.0889)
		(layer "In6.Cu")
		(net "UPI_CPU0_CPU1_P2P2_DP<0>")
	)
	(segment
		(start 356.305612 -291.589206)
		(end 356.305612 -291.764466)
		(width 0.0889)
		(layer "In6.Cu")
		(net "UPI_CPU0_CPU1_P2P2_DP<0>")
	)
	(segment
		(start 70.329044 -378.340366)
		(end 70.139814 -378.418598)
		(width 0.14732)
		(layer "In6.Cu")
		(net "UPI_CPU0_CPU1_P2P2_DP<0>")
	)
	(segment
		(start 356.206552 -292.038786)
		(end 356.305612 -292.137846)
		(width 0.0889)
		(layer "In6.Cu")
		(net "UPI_CPU0_CPU1_P2P2_DP<0>")
	)
	(segment
		(start 356.263448 -298.527978)
		(end 356.263448 -299.001688)
		(width 0.14732)
		(layer "In6.Cu")
		(net "UPI_CPU0_CPU1_P2P2_DP<0>")
	)
	(segment
		(start 61.575696 -310.889396)
		(end 62.54242 -310.488838)
		(width 0.14732)
		(layer "In6.Cu")
		(net "UPI_CPU0_CPU1_P2P2_DP<0>")
	)
	(segment
		(start 80.43164 -295.2242)
		(end 81.70672 -292.145974)
		(width 0.14732)
		(layer "In6.Cu")
		(net "UPI_CPU0_CPU1_P2P2_DP<0>")
	)
	(segment
		(start 58.90387 -312.260234)
		(end 59.788298 -312.083958)
		(width 0.14732)
		(layer "In6.Cu")
		(net "UPI_CPU0_CPU1_P2P2_DP<0>")
	)
	(segment
		(start 356.206552 -290.766246)
		(end 356.206552 -290.941506)
		(width 0.0889)
		(layer "In6.Cu")
		(net "UPI_CPU0_CPU1_P2P2_DP<0>")
	)
	(segment
		(start 50.971958 -329.942952)
		(end 50.668936 -329.210924)
		(width 0.14732)
		(layer "In6.Cu")
		(net "UPI_CPU0_CPU1_P2P2_DP<0>")
	)
	(segment
		(start 357.245412 -275.070824)
		(end 357.245412 -275.102828)
		(width 0.0889)
		(layer "In6.Cu")
		(net "UPI_CPU0_CPU1_P2P2_DP<0>")
	)
	(segment
		(start 83.98891 -289.8648)
		(end 84.004404 -289.849306)
		(width 0.0889)
		(layer "In6.Cu")
		(net "UPI_CPU0_CPU1_P2P2_DP<0>")
	)
	(segment
		(start 85.709506 -283.714444)
		(end 85.718396 -283.709364)
		(width 0.0889)
		(layer "In6.Cu")
		(net "UPI_CPU0_CPU1_P2P2_DP<0>")
	)
	(segment
		(start 355.282754 -299.777658)
		(end 355.02215 -300.038262)
		(width 0.14732)
		(layer "In6.Cu")
		(net "UPI_CPU0_CPU1_P2P2_DP<0>")
	)
	(segment
		(start 356.206552 -291.314886)
		(end 356.206552 -291.490146)
		(width 0.0889)
		(layer "In6.Cu")
		(net "UPI_CPU0_CPU1_P2P2_DP<0>")
	)
	(segment
		(start 62.808358 -371.286532)
		(end 59.761882 -363.931454)
		(width 0.14732)
		(layer "In6.Cu")
		(net "UPI_CPU0_CPU1_P2P2_DP<0>")
	)
	(segment
		(start 357.06685 -283.539184)
		(end 357.05796 -283.544264)
		(width 0.0889)
		(layer "In6.Cu")
		(net "UPI_CPU0_CPU1_P2P2_DP<0>")
	)
	(segment
		(start 356.305612 -286.4612)
		(end 356.305612 -286.475424)
		(width 0.0889)
		(layer "In6.Cu")
		(net "UPI_CPU0_CPU1_P2P2_DP<0>")
	)
	(segment
		(start 84.004404 -289.849306)
		(end 84.004404 -289.789362)
		(width 0.0889)
		(layer "In6.Cu")
		(net "UPI_CPU0_CPU1_P2P2_DP<0>")
	)
	(segment
		(start 86.64956 -282.086558)
		(end 86.65845 -282.081478)
		(width 0.0889)
		(layer "In6.Cu")
		(net "UPI_CPU0_CPU1_P2P2_DP<0>")
	)
	(segment
		(start 59.761882 -363.9312)
		(end 59.761374 -363.930692)
		(width 0.14732)
		(layer "In6.Cu")
		(net "UPI_CPU0_CPU1_P2P2_DP<0>")
	)
	(segment
		(start 81.876646 -383.27965)
		(end 71.696072 -379.06325)
		(width 0.14732)
		(layer "In6.Cu")
		(net "UPI_CPU0_CPU1_P2P2_DP<0>")
	)
	(segment
		(start 356.305612 -288.103056)
		(end 356.305612 -288.216086)
		(width 0.0889)
		(layer "In6.Cu")
		(net "UPI_CPU0_CPU1_P2P2_DP<0>")
	)
	(segment
		(start 84.337906 -285.660846)
		(end 84.702904 -284.780482)
		(width 0.0889)
		(layer "In6.Cu")
		(net "UPI_CPU0_CPU1_P2P2_DP<0>")
	)
	(segment
		(start 347.08338 -308.00929)
		(end 346.774262 -308.318408)
		(width 0.14732)
		(layer "In6.Cu")
		(net "UPI_CPU0_CPU1_P2P2_DP<0>")
	)
	(segment
		(start 56.098694 -335.322164)
		(end 54.319932 -333.290672)
		(width 0.14732)
		(layer "In6.Cu")
		(net "UPI_CPU0_CPU1_P2P2_DP<0>")
	)
	(segment
		(start 52.955952 -317.6016)
		(end 53.051456 -317.37046)
		(width 0.14732)
		(layer "In6.Cu")
		(net "UPI_CPU0_CPU1_P2P2_DP<0>")
	)
	(segment
		(start 69.799708 -378.277882)
		(end 62.808358 -371.286532)
		(width 0.14732)
		(layer "In6.Cu")
		(net "UPI_CPU0_CPU1_P2P2_DP<0>")
	)
	(segment
		(start 356.206552 -291.863526)
		(end 356.206552 -292.038786)
		(width 0.0889)
		(layer "In6.Cu")
		(net "UPI_CPU0_CPU1_P2P2_DP<0>")
	)
	(segment
		(start 280.448512 -372.644924)
		(end 269.470886 -383.624328)
		(width 0.14732)
		(layer "In6.Cu")
		(net "UPI_CPU0_CPU1_P2P2_DP<0>")
	)
	(segment
		(start 322.3895 -332.067916)
		(end 311.194704 -343.262712)
		(width 0.14732)
		(layer "In6.Cu")
		(net "UPI_CPU0_CPU1_P2P2_DP<0>")
	)
	(segment
		(start 84.702904 -284.780482)
		(end 84.934806 -284.548326)
		(width 0.0889)
		(layer "In6.Cu")
		(net "UPI_CPU0_CPU1_P2P2_DP<0>")
	)
	(segment
		(start 347.255846 -308.00929)
		(end 347.08338 -308.00929)
		(width 0.14732)
		(layer "In6.Cu")
		(net "UPI_CPU0_CPU1_P2P2_DP<0>")
	)
	(segment
		(start 85.247734 -284.523688)
		(end 85.248496 -284.52318)
		(width 0.0889)
		(layer "In6.Cu")
		(net "UPI_CPU0_CPU1_P2P2_DP<0>")
	)
	(segment
		(start 71.61784 -378.87402)
		(end 71.277226 -378.73305)
		(width 0.14732)
		(layer "In6.Cu")
		(net "UPI_CPU0_CPU1_P2P2_DP<0>")
	)
	(segment
		(start 356.305612 -289.646868)
		(end 356.305612 -290.118546)
		(width 0.0889)
		(layer "In6.Cu")
		(net "UPI_CPU0_CPU1_P2P2_DP<0>")
	)
	(segment
		(start 70.74789 -378.670566)
		(end 70.669658 -378.481336)
		(width 0.14732)
		(layer "In6.Cu")
		(net "UPI_CPU0_CPU1_P2P2_DP<0>")
	)
	(segment
		(start 356.305612 -292.787578)
		(end 356.263702 -292.829488)
		(width 0.0889)
		(layer "In6.Cu")
		(net "UPI_CPU0_CPU1_P2P2_DP<0>")
	)
	(segment
		(start 356.775766 -288.962592)
		(end 356.768908 -289.090608)
		(width 0.0889)
		(layer "In6.Cu")
		(net "UPI_CPU0_CPU1_P2P2_DP<0>")
	)
	(segment
		(start 356.206552 -290.217606)
		(end 356.206552 -290.392866)
		(width 0.0889)
		(layer "In6.Cu")
		(net "UPI_CPU0_CPU1_P2P2_DP<0>")
	)
	(segment
		(start 50.59299 -329.028044)
		(end 50.592736 -329.02779)
		(width 0.14732)
		(layer "In6.Cu")
		(net "UPI_CPU0_CPU1_P2P2_DP<0>")
	)
	(segment
		(start 355.02215 -300.242986)
		(end 347.255846 -308.00929)
		(width 0.14732)
		(layer "In6.Cu")
		(net "UPI_CPU0_CPU1_P2P2_DP<0>")
	)
	(segment
		(start 82.406236 -383.342388)
		(end 82.065622 -383.201418)
		(width 0.14732)
		(layer "In6.Cu")
		(net "UPI_CPU0_CPU1_P2P2_DP<0>")
	)
	(segment
		(start 82.850482 -383.683256)
		(end 82.484468 -383.531618)
		(width 0.14732)
		(layer "In6.Cu")
		(net "UPI_CPU0_CPU1_P2P2_DP<0>")
	)
	(segment
		(start 345.69019 -309.574946)
		(end 341.375746 -311.36209)
		(width 0.14732)
		(layer "In6.Cu")
		(net "UPI_CPU0_CPU1_P2P2_DP<0>")
	)
	(segment
		(start 356.263448 -297.870118)
		(end 356.118668 -298.014898)
		(width 0.14732)
		(layer "In6.Cu")
		(net "UPI_CPU0_CPU1_P2P2_DP<0>")
	)
	(segment
		(start 355.487478 -299.777658)
		(end 355.282754 -299.777658)
		(width 0.14732)
		(layer "In6.Cu")
		(net "UPI_CPU0_CPU1_P2P2_DP<0>")
	)
	(segment
		(start 356.305612 -292.137846)
		(end 356.305612 -292.787578)
		(width 0.0889)
		(layer "In6.Cu")
		(net "UPI_CPU0_CPU1_P2P2_DP<0>")
	)
	(segment
		(start 356.775512 -282.39593)
		(end 356.775512 -282.424378)
		(width 0.0889)
		(layer "In6.Cu")
		(net "UPI_CPU0_CPU1_P2P2_DP<0>")
	)
	(segment
		(start 84.934806 -284.548326)
		(end 85.203538 -284.548326)
		(width 0.0889)
		(layer "In6.Cu")
		(net "UPI_CPU0_CPU1_P2P2_DP<0>")
	)
	(segment
		(start 83.766406 -290.086288)
		(end 83.767422 -290.086288)
		(width 0.14732)
		(layer "In6.Cu")
		(net "UPI_CPU0_CPU1_P2P2_DP<0>")
	)
	(segment
		(start 86.65845 -282.081478)
		(end 86.664546 -282.077922)
		(width 0.0889)
		(layer "In6.Cu")
		(net "UPI_CPU0_CPU1_P2P2_DP<0>")
	)
	(segment
		(start 357.536496 -276.214078)
		(end 357.528622 -276.21865)
		(width 0.0889)
		(layer "In6.Cu")
		(net "UPI_CPU0_CPU1_P2P2_DP<0>")
	)
	(segment
		(start 52.866798 -317.712598)
		(end 52.955952 -317.6016)
		(width 0.14732)
		(layer "In6.Cu")
		(net "UPI_CPU0_CPU1_P2P2_DP<0>")
	)
	(segment
		(start 82.484468 -383.531618)
		(end 82.406236 -383.342388)
		(width 0.14732)
		(layer "In6.Cu")
		(net "UPI_CPU0_CPU1_P2P2_DP<0>")
	)
	(segment
		(start 62.54242 -310.488838)
		(end 65.813686 -308.302152)
		(width 0.14732)
		(layer "In6.Cu")
		(net "UPI_CPU0_CPU1_P2P2_DP<0>")
	)
	(segment
		(start 83.380072 -383.745994)
		(end 83.039712 -383.605024)
		(width 0.14732)
		(layer "In6.Cu")
		(net "UPI_CPU0_CPU1_P2P2_DP<0>")
	)
	(segment
		(start 286.92602 -343.262712)
		(end 285.606236 -343.80932)
		(width 0.14732)
		(layer "In6.Cu")
		(net "UPI_CPU0_CPU1_P2P2_DP<0>")
	)
	(segment
		(start 53.051456 -317.370714)
		(end 53.072284 -317.320168)
		(width 0.14732)
		(layer "In6.Cu")
		(net "UPI_CPU0_CPU1_P2P2_DP<0>")
	)
	(segment
		(start 356.118668 -298.014898)
		(end 356.118668 -298.383198)
		(width 0.14732)
		(layer "In6.Cu")
		(net "UPI_CPU0_CPU1_P2P2_DP<0>")
	)
	(segment
		(start 356.775512 -287.280604)
		(end 356.775512 -287.297876)
		(width 0.0889)
		(layer "In6.Cu")
		(net "UPI_CPU0_CPU1_P2P2_DP<0>")
	)
	(segment
		(start 53.051456 -317.37046)
		(end 53.051456 -317.370714)
		(width 0.14732)
		(layer "In6.Cu")
		(net "UPI_CPU0_CPU1_P2P2_DP<0>")
	)
	(segment
		(start 357.05796 -282.895548)
		(end 357.06685 -282.900628)
		(width 0.0889)
		(layer "In6.Cu")
		(net "UPI_CPU0_CPU1_P2P2_DP<0>")
	)
	(segment
		(start 86.179406 -282.900628)
		(end 86.188296 -282.895548)
		(width 0.0889)
		(layer "In6.Cu")
		(net "UPI_CPU0_CPU1_P2P2_DP<0>")
	)
	(segment
		(start 55.920132 -314.120022)
		(end 58.377074 -312.47842)
		(width 0.14732)
		(layer "In6.Cu")
		(net "UPI_CPU0_CPU1_P2P2_DP<0>")
	)
	(segment
		(start 355.02215 -300.038262)
		(end 355.02215 -300.242986)
		(width 0.14732)
		(layer "In6.Cu")
		(net "UPI_CPU0_CPU1_P2P2_DP<0>")
	)
	(segment
		(start 357.06685 -278.65578)
		(end 357.05796 -278.66086)
		(width 0.0889)
		(layer "In6.Cu")
		(net "UPI_CPU0_CPU1_P2P2_DP<0>")
	)
	(segment
		(start 161.721038 -392.724132)
		(end 126.884684 -392.724132)
		(width 0.14732)
		(layer "In6.Cu")
		(net "UPI_CPU0_CPU1_P2P2_DP<0>")
	)
	(segment
		(start 357.53675 -277.84171)
		(end 357.52786 -277.84679)
		(width 0.0889)
		(layer "In6.Cu")
		(net "UPI_CPU0_CPU1_P2P2_DP<0>")
	)
	(segment
		(start 357.184198 -273.995896)
		(end 357.20528 -273.917918)
		(width 0.0889)
		(layer "In6.Cu")
		(net "UPI_CPU0_CPU1_P2P2_DP<0>")
	)
	(segment
		(start 356.588314 -287.613598)
		(end 356.582218 -287.617154)
		(width 0.0889)
		(layer "In6.Cu")
		(net "UPI_CPU0_CPU1_P2P2_DP<0>")
	)
	(segment
		(start 50.592736 -329.02779)
		(end 50.365152 -328.478134)
		(width 0.14732)
		(layer "In6.Cu")
		(net "UPI_CPU0_CPU1_P2P2_DP<0>")
	)
	(segment
		(start 87.47252 -280.778204)
		(end 87.785194 -280.778204)
		(width 0.0889)
		(layer "In6.Cu")
		(net "UPI_CPU0_CPU1_P2P2_DP<0>")
	)
	(segment
		(start 341.375746 -311.36209)
		(end 323.605398 -329.132438)
		(width 0.14732)
		(layer "In6.Cu")
		(net "UPI_CPU0_CPU1_P2P2_DP<0>")
	)
	(segment
		(start 52.348384 -318.015112)
		(end 52.859178 -317.71336)
		(width 0.14732)
		(layer "In6.Cu")
		(net "UPI_CPU0_CPU1_P2P2_DP<0>")
	)
	(segment
		(start 280.448512 -348.967044)
		(end 280.448512 -372.644924)
		(width 0.14732)
		(layer "In6.Cu")
		(net "UPI_CPU0_CPU1_P2P2_DP<0>")
	)
	(segment
		(start 50.365152 -324.724776)
		(end 50.365406 -320.414904)
		(width 0.14732)
		(layer "In6.Cu")
		(net "UPI_CPU0_CPU1_P2P2_DP<0>")
	)
	(segment
		(start 54.319932 -333.290672)
		(end 50.971958 -329.942952)
		(width 0.14732)
		(layer "In6.Cu")
		(net "UPI_CPU0_CPU1_P2P2_DP<0>")
	)
	(segment
		(start 356.305612 -291.215826)
		(end 356.206552 -291.314886)
		(width 0.0889)
		(layer "In6.Cu")
		(net "UPI_CPU0_CPU1_P2P2_DP<0>")
	)
	(segment
		(start 126.884684 -392.724132)
		(end 92.287344 -387.591808)
		(width 0.14732)
		(layer "In6.Cu")
		(net "UPI_CPU0_CPU1_P2P2_DP<0>")
	)
	(segment
		(start 83.45932 -383.93497)
		(end 83.458558 -383.935478)
		(width 0.14732)
		(layer "In6.Cu")
		(net "UPI_CPU0_CPU1_P2P2_DP<0>")
	)
	(segment
		(start 92.287344 -387.591808)
		(end 83.45932 -383.93497)
		(width 0.14732)
		(layer "In6.Cu")
		(net "UPI_CPU0_CPU1_P2P2_DP<0>")
	)
	(segment
		(start 52.298854 -318.024002)
		(end 52.348384 -318.015112)
		(width 0.14732)
		(layer "In6.Cu")
		(net "UPI_CPU0_CPU1_P2P2_DP<0>")
	)
	(segment
		(start 356.263448 -299.001688)
		(end 355.487478 -299.777658)
		(width 0.14732)
		(layer "In6.Cu")
		(net "UPI_CPU0_CPU1_P2P2_DP<0>")
	)
	(segment
		(start 356.775512 -280.759662)
		(end 356.775512 -280.78811)
		(width 0.0889)
		(layer "In6.Cu")
		(net "UPI_CPU0_CPU1_P2P2_DP<0>")
	)
	(segment
		(start 356.305612 -291.040566)
		(end 356.305612 -291.215826)
		(width 0.0889)
		(layer "In6.Cu")
		(net "UPI_CPU0_CPU1_P2P2_DP<0>")
	)
	(segment
		(start 357.53675 -274.586192)
		(end 357.52786 -274.591272)
		(width 0.0889)
		(layer "In6.Cu")
		(net "UPI_CPU0_CPU1_P2P2_DP<0>")
	)
	(segment
		(start 311.194704 -343.262712)
		(end 286.92602 -343.262712)
		(width 0.14732)
		(layer "In6.Cu")
		(net "UPI_CPU0_CPU1_P2P2_DP<0>")
	)
	(segment
		(start 357.245412 -276.693122)
		(end 357.245412 -276.718522)
		(width 0.0889)
		(layer "In6.Cu")
		(net "UPI_CPU0_CPU1_P2P2_DP<0>")
	)
	(segment
		(start 357.05796 -281.267662)
		(end 357.06685 -281.272742)
		(width 0.0889)
		(layer "In6.Cu")
		(net "UPI_CPU0_CPU1_P2P2_DP<0>")
	)
	(segment
		(start 52.859178 -317.71336)
		(end 52.866798 -317.712598)
		(width 0.14732)
		(layer "In6.Cu")
		(net "UPI_CPU0_CPU1_P2P2_DP<0>")
	)
	(segment
		(start 357.245412 -278.31796)
		(end 357.245412 -278.336502)
		(width 0.0889)
		(layer "In6.Cu")
		(net "UPI_CPU0_CPU1_P2P2_DP<0>")
	)
	(segment
		(start 87.406988 -280.843736)
		(end 87.47252 -280.778204)
		(width 0.0889)
		(layer "In6.Cu")
		(net "UPI_CPU0_CPU1_P2P2_DP<0>")
	)
	(segment
		(start 356.206552 -290.392866)
		(end 356.305612 -290.491926)
		(width 0.0889)
		(layer "In6.Cu")
		(net "UPI_CPU0_CPU1_P2P2_DP<0>")
	)
	(segment
		(start 357.06685 -281.911298)
		(end 357.05796 -281.916378)
		(width 0.0889)
		(layer "In6.Cu")
		(net "UPI_CPU0_CPU1_P2P2_DP<0>")
	)
	(segment
		(start 356.780338 -288.873946)
		(end 356.775766 -288.962592)
		(width 0.0889)
		(layer "In6.Cu")
		(net "UPI_CPU0_CPU1_P2P2_DP<0>")
	)
	(segment
		(start 56.714898 -356.575106)
		(end 56.714898 -336.802222)
		(width 0.14732)
		(layer "In6.Cu")
		(net "UPI_CPU0_CPU1_P2P2_DP<0>")
	)
	(segment
		(start 53.38572 -315.831474)
		(end 54.15153 -315.065664)
		(width 0.14732)
		(layer "In6.Cu")
		(net "UPI_CPU0_CPU1_P2P2_DP<0>")
	)
	(segment
		(start 356.582218 -286.961326)
		(end 356.588314 -286.964882)
		(width 0.0889)
		(layer "In6.Cu")
		(net "UPI_CPU0_CPU1_P2P2_DP<0>")
	)
	(segment
		(start 86.470998 -282.413456)
		(end 86.470998 -282.405836)
		(width 0.0889)
		(layer "In6.Cu")
		(net "UPI_CPU0_CPU1_P2P2_DP<0>")
	)
	(segment
		(start 356.263702 -292.851586)
		(end 356.263702 -293.022782)
		(width 0.14732)
		(layer "In6.Cu")
		(net "UPI_CPU0_CPU1_P2P2_DP<0>")
	)
	(segment
		(start 50.365406 -320.414904)
		(end 50.541936 -319.413636)
		(width 0.14732)
		(layer "In6.Cu")
		(net "UPI_CPU0_CPU1_P2P2_DP<0>")
	)
	(segment
		(start 356.775512 -279.140412)
		(end 356.775512 -279.160224)
		(width 0.0889)
		(layer "In6.Cu")
		(net "UPI_CPU0_CPU1_P2P2_DP<0>")
	)
	(segment
		(start 84.337906 -289.45586)
		(end 84.337906 -285.660846)
		(width 0.0889)
		(layer "In6.Cu")
		(net "UPI_CPU0_CPU1_P2P2_DP<0>")
	)
	(segment
		(start 356.775512 -285.652718)
		(end 356.775512 -285.66999)
		(width 0.0889)
		(layer "In6.Cu")
		(net "UPI_CPU0_CPU1_P2P2_DP<0>")
	)
	(segment
		(start 357.527606 -275.570442)
		(end 357.536496 -275.575522)
		(width 0.0889)
		(layer "In6.Cu")
		(net "UPI_CPU0_CPU1_P2P2_DP<0>")
	)
	(segment
		(start 52.058062 -318.06642)
		(end 52.298854 -318.023748)
		(width 0.14732)
		(layer "In6.Cu")
		(net "UPI_CPU0_CPU1_P2P2_DP<0>")
	)
	(segment
		(start 52.298854 -318.023748)
		(end 52.298854 -318.024002)
		(width 0.14732)
		(layer "In6.Cu")
		(net "UPI_CPU0_CPU1_P2P2_DP<0>")
	)
	(segment
		(start 356.582218 -285.33344)
		(end 356.588314 -285.336996)
		(width 0.0889)
		(layer "In6.Cu")
		(net "UPI_CPU0_CPU1_P2P2_DP<0>")
	)
	(segment
		(start 71.087996 -378.811282)
		(end 70.74789 -378.670566)
		(width 0.14732)
		(layer "In6.Cu")
		(net "UPI_CPU0_CPU1_P2P2_DP<0>")
	)
	(segment
		(start 70.139814 -378.418598)
		(end 69.799708 -378.277882)
		(width 0.14732)
		(layer "In6.Cu")
		(net "UPI_CPU0_CPU1_P2P2_DP<0>")
	)
	(segment
		(start 66.477388 -308.02707)
		(end 69.947282 -305.708304)
		(width 0.14732)
		(layer "In6.Cu")
		(net "UPI_CPU0_CPU1_P2P2_DP<0>")
	)
	(segment
		(start 56.714898 -336.802222)
		(end 56.098694 -335.322164)
		(width 0.14732)
		(layer "In6.Cu")
		(net "UPI_CPU0_CPU1_P2P2_DP<0>")
	)
	(segment
		(start 285.606236 -343.80932)
		(end 280.448512 -348.967044)
		(width 0.14732)
		(layer "In6.Cu")
		(net "UPI_CPU0_CPU1_P2P2_DP<0>")
	)
	(segment
		(start 83.039712 -383.605024)
		(end 82.850482 -383.683256)
		(width 0.14732)
		(layer "In6.Cu")
		(net "UPI_CPU0_CPU1_P2P2_DP<0>")
	)
	(segment
		(start 65.813686 -308.302152)
		(end 66.477388 -308.02707)
		(width 0.14732)
		(layer "In6.Cu")
		(net "UPI_CPU0_CPU1_P2P2_DP<0>")
	)
	(segment
		(start 81.70672 -292.145974)
		(end 83.766406 -290.086288)
		(width 0.14732)
		(layer "In6.Cu")
		(net "UPI_CPU0_CPU1_P2P2_DP<0>")
	)
	(arc
		(start 356.775512 -280.78811)
		(mid 356.853623 -281.065059)
		(end 357.05796 -281.267662)
		(width 0.0889)
		(layer "In6.Cu")
		(net "UPI_CPU0_CPU1_P2P2_DP<0>")
	)
	(arc
		(start 86.940898 -281.59202)
		(mid 86.988577 -281.40912)
		(end 87.11946 -281.272742)
		(width 0.0889)
		(layer "In6.Cu")
		(net "UPI_CPU0_CPU1_P2P2_DP<0>")
	)
	(arc
		(start 356.768908 -289.090608)
		(mid 356.697079 -289.206353)
		(end 356.590346 -289.291014)
		(width 0.0889)
		(layer "In6.Cu")
		(net "UPI_CPU0_CPU1_P2P2_DP<0>")
	)
	(arc
		(start 357.245412 -278.336502)
		(mid 357.197733 -278.519402)
		(end 357.06685 -278.65578)
		(width 0.0889)
		(layer "In6.Cu")
		(net "UPI_CPU0_CPU1_P2P2_DP<0>")
	)
	(arc
		(start 357.715058 -277.534624)
		(mid 357.664565 -277.710602)
		(end 357.53675 -277.84171)
		(width 0.0889)
		(layer "In6.Cu")
		(net "UPI_CPU0_CPU1_P2P2_DP<0>")
	)
	(arc
		(start 356.582218 -284.361636)
		(mid 356.305768 -284.847538)
		(end 356.582218 -285.33344)
		(width 0.0889)
		(layer "In6.Cu")
		(net "UPI_CPU0_CPU1_P2P2_DP<0>")
	)
	(arc
		(start 357.536496 -275.575522)
		(mid 357.715214 -275.8948)
		(end 357.536496 -276.214078)
		(width 0.0889)
		(layer "In6.Cu")
		(net "UPI_CPU0_CPU1_P2P2_DP<0>")
	)
	(arc
		(start 356.775512 -285.66999)
		(mid 356.723242 -285.852355)
		(end 356.588314 -285.985712)
		(width 0.0889)
		(layer "In6.Cu")
		(net "UPI_CPU0_CPU1_P2P2_DP<0>")
	)
	(arc
		(start 357.245158 -279.976326)
		(mid 357.194665 -280.152304)
		(end 357.06685 -280.283412)
		(width 0.0889)
		(layer "In6.Cu")
		(net "UPI_CPU0_CPU1_P2P2_DP<0>")
	)
	(arc
		(start 356.588314 -285.336996)
		(mid 356.723247 -285.47035)
		(end 356.775512 -285.652718)
		(width 0.0889)
		(layer "In6.Cu")
		(net "UPI_CPU0_CPU1_P2P2_DP<0>")
	)
	(arc
		(start 357.53675 -277.203154)
		(mid 357.666039 -277.33664)
		(end 357.715312 -277.515828)
		(width 0.0889)
		(layer "In6.Cu")
		(net "UPI_CPU0_CPU1_P2P2_DP<0>")
	)
	(arc
		(start 356.305612 -288.216086)
		(mid 356.404724 -288.442142)
		(end 356.58933 -288.605976)
		(width 0.0889)
		(layer "In6.Cu")
		(net "UPI_CPU0_CPU1_P2P2_DP<0>")
	)
	(arc
		(start 356.775512 -284.042358)
		(mid 356.723242 -284.224723)
		(end 356.588314 -284.35808)
		(width 0.0889)
		(layer "In6.Cu")
		(net "UPI_CPU0_CPU1_P2P2_DP<0>")
	)
	(arc
		(start 356.590346 -289.291014)
		(mid 356.412085 -289.440214)
		(end 356.305612 -289.646868)
		(width 0.0889)
		(layer "In6.Cu")
		(net "UPI_CPU0_CPU1_P2P2_DP<0>")
	)
	(arc
		(start 356.582218 -287.617154)
		(mid 356.379631 -287.823505)
		(end 356.305612 -288.103056)
		(width 0.0889)
		(layer "In6.Cu")
		(net "UPI_CPU0_CPU1_P2P2_DP<0>")
	)
	(arc
		(start 357.05796 -278.66086)
		(mid 356.853625 -278.863465)
		(end 356.775512 -279.140412)
		(width 0.0889)
		(layer "In6.Cu")
		(net "UPI_CPU0_CPU1_P2P2_DP<0>")
	)
	(arc
		(start 357.245412 -283.22651)
		(mid 357.196159 -283.40571)
		(end 357.06685 -283.539184)
		(width 0.0889)
		(layer "In6.Cu")
		(net "UPI_CPU0_CPU1_P2P2_DP<0>")
	)
	(arc
		(start 357.52786 -274.591272)
		(mid 357.323525 -274.793877)
		(end 357.245412 -275.070824)
		(width 0.0889)
		(layer "In6.Cu")
		(net "UPI_CPU0_CPU1_P2P2_DP<0>")
	)
	(arc
		(start 357.06685 -281.272742)
		(mid 357.245447 -281.59202)
		(end 357.06685 -281.911298)
		(width 0.0889)
		(layer "In6.Cu")
		(net "UPI_CPU0_CPU1_P2P2_DP<0>")
	)
	(arc
		(start 87.404194 -280.864818)
		(mid 87.40569 -280.85429)
		(end 87.406988 -280.843736)
		(width 0.0889)
		(layer "In6.Cu")
		(net "UPI_CPU0_CPU1_P2P2_DP<0>")
	)
	(arc
		(start 356.775512 -279.160224)
		(mid 356.853623 -279.437173)
		(end 357.05796 -279.639776)
		(width 0.0889)
		(layer "In6.Cu")
		(net "UPI_CPU0_CPU1_P2P2_DP<0>")
	)
	(arc
		(start 85.530944 -284.033722)
		(mid 85.578623 -283.850822)
		(end 85.709506 -283.714444)
		(width 0.0889)
		(layer "In6.Cu")
		(net "UPI_CPU0_CPU1_P2P2_DP<0>")
	)
	(arc
		(start 357.06685 -282.900628)
		(mid 357.194743 -283.03169)
		(end 357.245158 -283.207714)
		(width 0.0889)
		(layer "In6.Cu")
		(net "UPI_CPU0_CPU1_P2P2_DP<0>")
	)
	(arc
		(start 86.470998 -282.405836)
		(mid 86.518677 -282.222936)
		(end 86.64956 -282.086558)
		(width 0.0889)
		(layer "In6.Cu")
		(net "UPI_CPU0_CPU1_P2P2_DP<0>")
	)
	(arc
		(start 357.53675 -273.947636)
		(mid 357.715347 -274.266914)
		(end 357.53675 -274.586192)
		(width 0.0889)
		(layer "In6.Cu")
		(net "UPI_CPU0_CPU1_P2P2_DP<0>")
	)
	(arc
		(start 357.05796 -283.544264)
		(mid 356.853625 -283.746869)
		(end 356.775512 -284.023816)
		(width 0.0889)
		(layer "In6.Cu")
		(net "UPI_CPU0_CPU1_P2P2_DP<0>")
	)
	(arc
		(start 356.775512 -287.297876)
		(mid 356.723242 -287.480241)
		(end 356.588314 -287.613598)
		(width 0.0889)
		(layer "In6.Cu")
		(net "UPI_CPU0_CPU1_P2P2_DP<0>")
	)
	(arc
		(start 357.06685 -279.644856)
		(mid 357.196139 -279.778342)
		(end 357.245412 -279.95753)
		(width 0.0889)
		(layer "In6.Cu")
		(net "UPI_CPU0_CPU1_P2P2_DP<0>")
	)
	(arc
		(start 86.188296 -282.895548)
		(mid 86.393368 -282.691869)
		(end 86.470998 -282.413456)
		(width 0.0889)
		(layer "In6.Cu")
		(net "UPI_CPU0_CPU1_P2P2_DP<0>")
	)
	(arc
		(start 357.527606 -276.219158)
		(mid 357.324783 -276.419389)
		(end 357.245412 -276.693122)
		(width 0.0889)
		(layer "In6.Cu")
		(net "UPI_CPU0_CPU1_P2P2_DP<0>")
	)
	(arc
		(start 87.12835 -281.267662)
		(mid 87.311941 -281.097527)
		(end 87.404194 -280.864818)
		(width 0.0889)
		(layer "In6.Cu")
		(net "UPI_CPU0_CPU1_P2P2_DP<0>")
	)
	(arc
		(start 357.245158 -283.207714)
		(mid 357.245403 -283.21711)
		(end 357.245412 -283.22651)
		(width 0.0889)
		(layer "In6.Cu")
		(net "UPI_CPU0_CPU1_P2P2_DP<0>")
	)
	(arc
		(start 357.05796 -280.288492)
		(mid 356.855674 -280.487473)
		(end 356.775512 -280.759662)
		(width 0.0889)
		(layer "In6.Cu")
		(net "UPI_CPU0_CPU1_P2P2_DP<0>")
	)
	(arc
		(start 357.245412 -276.718522)
		(mid 357.323523 -276.995471)
		(end 357.52786 -277.198074)
		(width 0.0889)
		(layer "In6.Cu")
		(net "UPI_CPU0_CPU1_P2P2_DP<0>")
	)
	(arc
		(start 357.245412 -279.95753)
		(mid 357.245402 -279.96693)
		(end 357.245158 -279.976326)
		(width 0.0889)
		(layer "In6.Cu")
		(net "UPI_CPU0_CPU1_P2P2_DP<0>")
	)
	(arc
		(start 357.715312 -277.515828)
		(mid 357.715302 -277.525228)
		(end 357.715058 -277.534624)
		(width 0.0889)
		(layer "In6.Cu")
		(net "UPI_CPU0_CPU1_P2P2_DP<0>")
	)
	(arc
		(start 356.775512 -282.424378)
		(mid 356.855674 -282.696567)
		(end 357.05796 -282.895548)
		(width 0.0889)
		(layer "In6.Cu")
		(net "UPI_CPU0_CPU1_P2P2_DP<0>")
	)
	(arc
		(start 357.20528 -273.917918)
		(mid 357.369376 -273.893571)
		(end 357.52786 -273.942556)
		(width 0.0889)
		(layer "In6.Cu")
		(net "UPI_CPU0_CPU1_P2P2_DP<0>")
	)
	(arc
		(start 86.664546 -282.077922)
		(mid 86.866959 -281.871509)
		(end 86.940898 -281.59202)
		(width 0.0889)
		(layer "In6.Cu")
		(net "UPI_CPU0_CPU1_P2P2_DP<0>")
	)
	(arc
		(start 357.52786 -277.84679)
		(mid 357.325574 -278.045771)
		(end 357.245412 -278.31796)
		(width 0.0889)
		(layer "In6.Cu")
		(net "UPI_CPU0_CPU1_P2P2_DP<0>")
	)
	(arc
		(start 85.718396 -283.709364)
		(mid 85.922731 -283.506759)
		(end 86.000844 -283.229812)
		(width 0.0889)
		(layer "In6.Cu")
		(net "UPI_CPU0_CPU1_P2P2_DP<0>")
	)
	(arc
		(start 357.245412 -275.102828)
		(mid 357.326323 -275.372956)
		(end 357.527606 -275.570442)
		(width 0.0889)
		(layer "In6.Cu")
		(net "UPI_CPU0_CPU1_P2P2_DP<0>")
	)
	(arc
		(start 356.58933 -288.605976)
		(mid 356.714827 -288.718573)
		(end 356.780338 -288.873946)
		(width 0.0889)
		(layer "In6.Cu")
		(net "UPI_CPU0_CPU1_P2P2_DP<0>")
	)
	(arc
		(start 356.305612 -286.475424)
		(mid 356.379603 -286.75499)
		(end 356.582218 -286.961326)
		(width 0.0889)
		(layer "In6.Cu")
		(net "UPI_CPU0_CPU1_P2P2_DP<0>")
	)
	(arc
		(start 86.000844 -283.219906)
		(mid 86.048523 -283.037006)
		(end 86.179406 -282.900628)
		(width 0.0889)
		(layer "In6.Cu")
		(net "UPI_CPU0_CPU1_P2P2_DP<0>")
	)
	(arc
		(start 85.248496 -284.52318)
		(mid 85.452831 -284.320575)
		(end 85.530944 -284.043628)
		(width 0.0889)
		(layer "In6.Cu")
		(net "UPI_CPU0_CPU1_P2P2_DP<0>")
	)
	(arc
		(start 357.05796 -281.916378)
		(mid 356.853625 -282.118983)
		(end 356.775512 -282.39593)
		(width 0.0889)
		(layer "In6.Cu")
		(net "UPI_CPU0_CPU1_P2P2_DP<0>")
	)
	(arc
		(start 356.588314 -285.985712)
		(mid 356.384833 -286.186516)
		(end 356.305612 -286.4612)
		(width 0.0889)
		(layer "In6.Cu")
		(net "UPI_CPU0_CPU1_P2P2_DP<0>")
	)
	(arc
		(start 356.588314 -286.964882)
		(mid 356.723247 -287.098236)
		(end 356.775512 -287.280604)
		(width 0.0889)
		(layer "In6.Cu")
		(net "UPI_CPU0_CPU1_P2P2_DP<0>")
	)
	(segment
		(start 96.243648 -282.405582)
		(end 96.243394 -282.405836)
		(width 0.13208)
		(layer "F.Cu")
		(net "UPI_CPU0_CPU1_P2P2_DN<9>")
	)
	(segment
		(start 96.243648 -281.869896)
		(end 96.243648 -282.405582)
		(width 0.13208)
		(layer "F.Cu")
		(net "UPI_CPU0_CPU1_P2P2_DN<9>")
	)
	(segment
		(start 348.882716 -280.77795)
		(end 348.882462 -280.778204)
		(width 0.13208)
		(layer "F.Cu")
		(net "UPI_CPU0_CPU1_P2P2_DN<9>")
	)
	(segment
		(start 348.882716 -280.242264)
		(end 348.882716 -280.77795)
		(width 0.13208)
		(layer "F.Cu")
		(net "UPI_CPU0_CPU1_P2P2_DN<9>")
	)
	(segment
		(start 68.875148 -366.630966)
		(end 63.931038 -354.69449)
		(width 0.14732)
		(layer "In6.Cu")
		(net "UPI_CPU0_CPU1_P2P2_DN<9>")
	)
	(segment
		(start 93.232478 -290.40455)
		(end 93.328744 -290.308284)
		(width 0.0889)
		(layer "In6.Cu")
		(net "UPI_CPU0_CPU1_P2P2_DN<9>")
	)
	(segment
		(start 349.63735 -282.080208)
		(end 349.635064 -282.081478)
		(width 0.0889)
		(layer "In6.Cu")
		(net "UPI_CPU0_CPU1_P2P2_DN<9>")
	)
	(segment
		(start 348.977966 -283.212286)
		(end 348.977966 -283.219906)
		(width 0.0889)
		(layer "In6.Cu")
		(net "UPI_CPU0_CPU1_P2P2_DN<9>")
	)
	(segment
		(start 348.882462 -280.778204)
		(end 349.038926 -281.049222)
		(width 0.0889)
		(layer "In6.Cu")
		(net "UPI_CPU0_CPU1_P2P2_DN<9>")
	)
	(segment
		(start 347.568012 -287.28924)
		(end 347.568012 -287.304734)
		(width 0.0889)
		(layer "In6.Cu")
		(net "UPI_CPU0_CPU1_P2P2_DN<9>")
	)
	(segment
		(start 273.021552 -345.765882)
		(end 273.021552 -369.453414)
		(width 0.14732)
		(layer "In6.Cu")
		(net "UPI_CPU0_CPU1_P2P2_DN<9>")
	)
	(segment
		(start 347.097858 -290.182554)
		(end 345.166188 -292.114224)
		(width 0.0889)
		(layer "In6.Cu")
		(net "UPI_CPU0_CPU1_P2P2_DN<9>")
	)
	(segment
		(start 346.815918 -288.592768)
		(end 346.807028 -288.597848)
		(width 0.0889)
		(layer "In6.Cu")
		(net "UPI_CPU0_CPU1_P2P2_DN<9>")
	)
	(segment
		(start 67.463416 -320.097912)
		(end 85.711538 -301.84979)
		(width 0.14732)
		(layer "In6.Cu")
		(net "UPI_CPU0_CPU1_P2P2_DN<9>")
	)
	(segment
		(start 347.756734 -286.96412)
		(end 347.754448 -286.965644)
		(width 0.0889)
		(layer "In6.Cu")
		(net "UPI_CPU0_CPU1_P2P2_DN<9>")
	)
	(segment
		(start 73.863962 -371.61978)
		(end 68.875148 -366.630966)
		(width 0.14732)
		(layer "In6.Cu")
		(net "UPI_CPU0_CPU1_P2P2_DN<9>")
	)
	(segment
		(start 63.931038 -333.978758)
		(end 63.395606 -330.941426)
		(width 0.14732)
		(layer "In6.Cu")
		(net "UPI_CPU0_CPU1_P2P2_DN<9>")
	)
	(segment
		(start 273.021552 -369.453414)
		(end 266.02944 -376.445526)
		(width 0.14732)
		(layer "In6.Cu")
		(net "UPI_CPU0_CPU1_P2P2_DN<9>")
	)
	(segment
		(start 348.695264 -282.081478)
		(end 348.69374 -282.08224)
		(width 0.0889)
		(layer "In6.Cu")
		(net "UPI_CPU0_CPU1_P2P2_DN<9>")
	)
	(segment
		(start 95.490792 -284.35808)
		(end 95.499682 -284.353)
		(width 0.0889)
		(layer "In6.Cu")
		(net "UPI_CPU0_CPU1_P2P2_DN<9>")
	)
	(segment
		(start 96.21774 -380.879096)
		(end 73.863962 -371.61978)
		(width 0.14732)
		(layer "In6.Cu")
		(net "UPI_CPU0_CPU1_P2P2_DN<9>")
	)
	(segment
		(start 93.328744 -290.308284)
		(end 93.328744 -289.646106)
		(width 0.0889)
		(layer "In6.Cu")
		(net "UPI_CPU0_CPU1_P2P2_DN<9>")
	)
	(segment
		(start 95.960692 -283.544264)
		(end 95.961454 -283.543756)
		(width 0.0889)
		(layer "In6.Cu")
		(net "UPI_CPU0_CPU1_P2P2_DN<9>")
	)
	(segment
		(start 63.931038 -354.69449)
		(end 63.931038 -333.978758)
		(width 0.14732)
		(layer "In6.Cu")
		(net "UPI_CPU0_CPU1_P2P2_DN<9>")
	)
	(segment
		(start 95.020892 -286.799782)
		(end 95.021654 -286.799274)
		(width 0.0889)
		(layer "In6.Cu")
		(net "UPI_CPU0_CPU1_P2P2_DN<9>")
	)
	(segment
		(start 349.038926 -281.049222)
		(end 349.12808 -281.073098)
		(width 0.0889)
		(layer "In6.Cu")
		(net "UPI_CPU0_CPU1_P2P2_DN<9>")
	)
	(segment
		(start 91.456764 -292.604444)
		(end 91.456764 -292.121336)
		(width 0.14732)
		(layer "In6.Cu")
		(net "UPI_CPU0_CPU1_P2P2_DN<9>")
	)
	(segment
		(start 93.141546 -288.427414)
		(end 93.142308 -288.426906)
		(width 0.0889)
		(layer "In6.Cu")
		(net "UPI_CPU0_CPU1_P2P2_DN<9>")
	)
	(segment
		(start 347.755464 -285.336996)
		(end 347.748606 -285.340806)
		(width 0.0889)
		(layer "In6.Cu")
		(net "UPI_CPU0_CPU1_P2P2_DN<9>")
	)
	(segment
		(start 96.148144 -283.219906)
		(end 96.148144 -283.205682)
		(width 0.0889)
		(layer "In6.Cu")
		(net "UPI_CPU0_CPU1_P2P2_DN<9>")
	)
	(segment
		(start 316.18555 -327.944734)
		(end 308.266084 -335.8642)
		(width 0.14732)
		(layer "In6.Cu")
		(net "UPI_CPU0_CPU1_P2P2_DN<9>")
	)
	(segment
		(start 308.266084 -335.8642)
		(end 285.767272 -335.8642)
		(width 0.14732)
		(layer "In6.Cu")
		(net "UPI_CPU0_CPU1_P2P2_DN<9>")
	)
	(segment
		(start 346.628466 -288.917126)
		(end 346.628466 -289.078416)
		(width 0.0889)
		(layer "In6.Cu")
		(net "UPI_CPU0_CPU1_P2P2_DN<9>")
	)
	(segment
		(start 346.812616 -289.277806)
		(end 346.812362 -289.27806)
		(width 0.0889)
		(layer "In6.Cu")
		(net "UPI_CPU0_CPU1_P2P2_DN<9>")
	)
	(segment
		(start 94.161864 -287.604962)
		(end 94.176596 -287.613598)
		(width 0.0889)
		(layer "In6.Cu")
		(net "UPI_CPU0_CPU1_P2P2_DN<9>")
	)
	(segment
		(start 85.711538 -301.84979)
		(end 88.186006 -295.875202)
		(width 0.14732)
		(layer "In6.Cu")
		(net "UPI_CPU0_CPU1_P2P2_DN<9>")
	)
	(segment
		(start 93.17355 -290.40455)
		(end 93.232478 -290.40455)
		(width 0.0889)
		(layer "In6.Cu")
		(net "UPI_CPU0_CPU1_P2P2_DN<9>")
	)
	(segment
		(start 348.707456 -283.702252)
		(end 348.695264 -283.709364)
		(width 0.0889)
		(layer "In6.Cu")
		(net "UPI_CPU0_CPU1_P2P2_DN<9>")
	)
	(segment
		(start 126.220728 -385.32943)
		(end 96.21774 -380.879096)
		(width 0.14732)
		(layer "In6.Cu")
		(net "UPI_CPU0_CPU1_P2P2_DN<9>")
	)
	(segment
		(start 63.395606 -330.941426)
		(end 63.657988 -329.45451)
		(width 0.14732)
		(layer "In6.Cu")
		(net "UPI_CPU0_CPU1_P2P2_DN<9>")
	)
	(segment
		(start 345.166188 -294.550084)
		(end 345.208352 -294.592248)
		(width 0.0889)
		(layer "In6.Cu")
		(net "UPI_CPU0_CPU1_P2P2_DN<9>")
	)
	(segment
		(start 347.746574 -286.970216)
		(end 347.746574 -286.969962)
		(width 0.0889)
		(layer "In6.Cu")
		(net "UPI_CPU0_CPU1_P2P2_DN<9>")
	)
	(segment
		(start 347.752416 -286.966914)
		(end 347.749876 -286.968184)
		(width 0.0889)
		(layer "In6.Cu")
		(net "UPI_CPU0_CPU1_P2P2_DN<9>")
	)
	(segment
		(start 349.635064 -282.081478)
		(end 349.620332 -282.090114)
		(width 0.0889)
		(layer "In6.Cu")
		(net "UPI_CPU0_CPU1_P2P2_DN<9>")
	)
	(segment
		(start 96.375728 -282.766008)
		(end 96.399858 -282.676854)
		(width 0.0889)
		(layer "In6.Cu")
		(net "UPI_CPU0_CPU1_P2P2_DN<9>")
	)
	(segment
		(start 95.208598 -284.847538)
		(end 95.208598 -284.832044)
		(width 0.0889)
		(layer "In6.Cu")
		(net "UPI_CPU0_CPU1_P2P2_DN<9>")
	)
	(segment
		(start 345.208352 -294.810434)
		(end 345.208098 -294.810688)
		(width 0.14732)
		(layer "In6.Cu")
		(net "UPI_CPU0_CPU1_P2P2_DN<9>")
	)
	(segment
		(start 63.657988 -329.45451)
		(end 64.55791 -327.911714)
		(width 0.14732)
		(layer "In6.Cu")
		(net "UPI_CPU0_CPU1_P2P2_DN<9>")
	)
	(segment
		(start 88.186006 -295.875202)
		(end 91.456764 -292.604444)
		(width 0.14732)
		(layer "In6.Cu")
		(net "UPI_CPU0_CPU1_P2P2_DN<9>")
	)
	(segment
		(start 347.756226 -285.336488)
		(end 347.755464 -285.336996)
		(width 0.0889)
		(layer "In6.Cu")
		(net "UPI_CPU0_CPU1_P2P2_DN<9>")
	)
	(segment
		(start 280.912316 -337.875118)
		(end 273.021552 -345.765882)
		(width 0.14732)
		(layer "In6.Cu")
		(net "UPI_CPU0_CPU1_P2P2_DN<9>")
	)
	(segment
		(start 95.01505 -285.175452)
		(end 95.030036 -285.166816)
		(width 0.0889)
		(layer "In6.Cu")
		(net "UPI_CPU0_CPU1_P2P2_DN<9>")
	)
	(segment
		(start 349.64116 -282.077922)
		(end 349.639382 -282.078938)
		(width 0.0889)
		(layer "In6.Cu")
		(net "UPI_CPU0_CPU1_P2P2_DN<9>")
	)
	(segment
		(start 347.098366 -288.103056)
		(end 347.098366 -288.121598)
		(width 0.0889)
		(layer "In6.Cu")
		(net "UPI_CPU0_CPU1_P2P2_DN<9>")
	)
	(segment
		(start 95.963994 -283.542232)
		(end 95.969582 -283.539184)
		(width 0.0889)
		(layer "In6.Cu")
		(net "UPI_CPU0_CPU1_P2P2_DN<9>")
	)
	(segment
		(start 348.038166 -286.4612)
		(end 348.038166 -286.475424)
		(width 0.0889)
		(layer "In6.Cu")
		(net "UPI_CPU0_CPU1_P2P2_DN<9>")
	)
	(segment
		(start 95.961454 -283.543756)
		(end 95.963994 -283.542232)
		(width 0.0889)
		(layer "In6.Cu")
		(net "UPI_CPU0_CPU1_P2P2_DN<9>")
	)
	(segment
		(start 348.695264 -283.709364)
		(end 348.686374 -283.714444)
		(width 0.0889)
		(layer "In6.Cu")
		(net "UPI_CPU0_CPU1_P2P2_DN<9>")
	)
	(segment
		(start 65.681098 -323.864732)
		(end 67.463416 -320.097912)
		(width 0.14732)
		(layer "In6.Cu")
		(net "UPI_CPU0_CPU1_P2P2_DN<9>")
	)
	(segment
		(start 345.208352 -294.614346)
		(end 345.208352 -294.810434)
		(width 0.14732)
		(layer "In6.Cu")
		(net "UPI_CPU0_CPU1_P2P2_DN<9>")
	)
	(segment
		(start 347.097858 -289.610292)
		(end 347.097858 -290.182554)
		(width 0.0889)
		(layer "In6.Cu")
		(net "UPI_CPU0_CPU1_P2P2_DN<9>")
	)
	(segment
		(start 348.225618 -284.52318)
		(end 348.216728 -284.52826)
		(width 0.0889)
		(layer "In6.Cu")
		(net "UPI_CPU0_CPU1_P2P2_DN<9>")
	)
	(segment
		(start 347.754448 -286.965644)
		(end 347.752416 -286.966914)
		(width 0.0889)
		(layer "In6.Cu")
		(net "UPI_CPU0_CPU1_P2P2_DN<9>")
	)
	(segment
		(start 345.208098 -294.810688)
		(end 345.208098 -298.003722)
		(width 0.14732)
		(layer "In6.Cu")
		(net "UPI_CPU0_CPU1_P2P2_DN<9>")
	)
	(segment
		(start 93.158056 -290.420044)
		(end 93.17355 -290.40455)
		(width 0.0889)
		(layer "In6.Cu")
		(net "UPI_CPU0_CPU1_P2P2_DN<9>")
	)
	(segment
		(start 93.328998 -288.103056)
		(end 93.328998 -288.087562)
		(width 0.0889)
		(layer "In6.Cu")
		(net "UPI_CPU0_CPU1_P2P2_DN<9>")
	)
	(segment
		(start 347.76156 -286.961326)
		(end 347.756734 -286.96412)
		(width 0.0889)
		(layer "In6.Cu")
		(net "UPI_CPU0_CPU1_P2P2_DN<9>")
	)
	(segment
		(start 94.738444 -287.28924)
		(end 94.738444 -287.279334)
		(width 0.0889)
		(layer "In6.Cu")
		(net "UPI_CPU0_CPU1_P2P2_DN<9>")
	)
	(segment
		(start 349.639382 -282.078938)
		(end 349.63735 -282.080208)
		(width 0.0889)
		(layer "In6.Cu")
		(net "UPI_CPU0_CPU1_P2P2_DN<9>")
	)
	(segment
		(start 348.694502 -282.729686)
		(end 348.695264 -282.730194)
		(width 0.0889)
		(layer "In6.Cu")
		(net "UPI_CPU0_CPU1_P2P2_DN<9>")
	)
	(segment
		(start 345.166188 -292.114224)
		(end 345.166188 -294.550084)
		(width 0.0889)
		(layer "In6.Cu")
		(net "UPI_CPU0_CPU1_P2P2_DN<9>")
	)
	(segment
		(start 95.021654 -286.799274)
		(end 95.024194 -286.79775)
		(width 0.0889)
		(layer "In6.Cu")
		(net "UPI_CPU0_CPU1_P2P2_DN<9>")
	)
	(segment
		(start 266.02944 -376.445526)
		(end 161.33953 -385.32943)
		(width 0.14732)
		(layer "In6.Cu")
		(net "UPI_CPU0_CPU1_P2P2_DN<9>")
	)
	(segment
		(start 344.255344 -300.304962)
		(end 341.458296 -303.10201)
		(width 0.14732)
		(layer "In6.Cu")
		(net "UPI_CPU0_CPU1_P2P2_DN<9>")
	)
	(segment
		(start 93.142308 -288.426906)
		(end 93.150436 -288.422334)
		(width 0.0889)
		(layer "In6.Cu")
		(net "UPI_CPU0_CPU1_P2P2_DN<9>")
	)
	(segment
		(start 341.458296 -303.10201)
		(end 338.02828 -304.522632)
		(width 0.14732)
		(layer "In6.Cu")
		(net "UPI_CPU0_CPU1_P2P2_DN<9>")
	)
	(segment
		(start 161.33953 -385.32943)
		(end 126.220728 -385.32943)
		(width 0.14732)
		(layer "In6.Cu")
		(net "UPI_CPU0_CPU1_P2P2_DN<9>")
	)
	(segment
		(start 91.456764 -292.121336)
		(end 93.158056 -290.420044)
		(width 0.14732)
		(layer "In6.Cu")
		(net "UPI_CPU0_CPU1_P2P2_DN<9>")
	)
	(segment
		(start 96.399858 -282.676854)
		(end 96.243394 -282.405836)
		(width 0.0889)
		(layer "In6.Cu")
		(net "UPI_CPU0_CPU1_P2P2_DN<9>")
	)
	(segment
		(start 64.55791 -327.911714)
		(end 65.681098 -323.864732)
		(width 0.14732)
		(layer "In6.Cu")
		(net "UPI_CPU0_CPU1_P2P2_DN<9>")
	)
	(segment
		(start 317.30188 -325.249032)
		(end 316.18555 -327.944734)
		(width 0.14732)
		(layer "In6.Cu")
		(net "UPI_CPU0_CPU1_P2P2_DN<9>")
	)
	(segment
		(start 347.748606 -285.340806)
		(end 347.746574 -285.342076)
		(width 0.0889)
		(layer "In6.Cu")
		(net "UPI_CPU0_CPU1_P2P2_DN<9>")
	)
	(segment
		(start 285.767272 -335.8642)
		(end 280.912316 -337.875118)
		(width 0.14732)
		(layer "In6.Cu")
		(net "UPI_CPU0_CPU1_P2P2_DN<9>")
	)
	(segment
		(start 345.208352 -294.592248)
		(end 345.208352 -294.614346)
		(width 0.0889)
		(layer "In6.Cu")
		(net "UPI_CPU0_CPU1_P2P2_DN<9>")
	)
	(segment
		(start 347.746574 -285.980632)
		(end 347.755464 -285.985712)
		(width 0.0889)
		(layer "In6.Cu")
		(net "UPI_CPU0_CPU1_P2P2_DN<9>")
	)
	(segment
		(start 347.76156 -285.33344)
		(end 347.756226 -285.336488)
		(width 0.0889)
		(layer "In6.Cu")
		(net "UPI_CPU0_CPU1_P2P2_DN<9>")
	)
	(segment
		(start 95.024194 -286.79775)
		(end 95.029782 -286.794702)
		(width 0.0889)
		(layer "In6.Cu")
		(net "UPI_CPU0_CPU1_P2P2_DN<9>")
	)
	(segment
		(start 95.678244 -284.033722)
		(end 95.678244 -284.023816)
		(width 0.0889)
		(layer "In6.Cu")
		(net "UPI_CPU0_CPU1_P2P2_DN<9>")
	)
	(segment
		(start 348.686374 -282.725114)
		(end 348.694502 -282.729686)
		(width 0.0889)
		(layer "In6.Cu")
		(net "UPI_CPU0_CPU1_P2P2_DN<9>")
	)
	(segment
		(start 347.749876 -286.968184)
		(end 347.746574 -286.970216)
		(width 0.0889)
		(layer "In6.Cu")
		(net "UPI_CPU0_CPU1_P2P2_DN<9>")
	)
	(segment
		(start 348.69374 -282.08224)
		(end 348.686374 -282.086558)
		(width 0.0889)
		(layer "In6.Cu")
		(net "UPI_CPU0_CPU1_P2P2_DN<9>")
	)
	(segment
		(start 92.859098 -289.114738)
		(end 92.859098 -288.898584)
		(width 0.0889)
		(layer "In6.Cu")
		(net "UPI_CPU0_CPU1_P2P2_DN<9>")
	)
	(segment
		(start 95.029782 -286.156146)
		(end 95.020892 -286.151066)
		(width 0.0889)
		(layer "In6.Cu")
		(net "UPI_CPU0_CPU1_P2P2_DN<9>")
	)
	(segment
		(start 348.507812 -284.033722)
		(end 348.507812 -284.049216)
		(width 0.0889)
		(layer "In6.Cu")
		(net "UPI_CPU0_CPU1_P2P2_DN<9>")
	)
	(segment
		(start 338.02828 -304.522632)
		(end 317.30188 -325.249032)
		(width 0.14732)
		(layer "In6.Cu")
		(net "UPI_CPU0_CPU1_P2P2_DN<9>")
	)
	(segment
		(start 349.620332 -281.093926)
		(end 349.64116 -281.106118)
		(width 0.0889)
		(layer "In6.Cu")
		(net "UPI_CPU0_CPU1_P2P2_DN<9>")
	)
	(segment
		(start 347.285818 -287.778698)
		(end 347.276928 -287.783778)
		(width 0.0889)
		(layer "In6.Cu")
		(net "UPI_CPU0_CPU1_P2P2_DN<9>")
	)
	(segment
		(start 345.208098 -298.003722)
		(end 344.255344 -300.304962)
		(width 0.14732)
		(layer "In6.Cu")
		(net "UPI_CPU0_CPU1_P2P2_DN<9>")
	)
	(arc
		(start 96.358964 -282.778962)
		(mid 96.367286 -282.772407)
		(end 96.375728 -282.766008)
		(width 0.0889)
		(layer "In6.Cu")
		(net "UPI_CPU0_CPU1_P2P2_DN<9>")
	)
	(arc
		(start 349.148146 -281.06497)
		(mid 349.387421 -281.027662)
		(end 349.620332 -281.093926)
		(width 0.0889)
		(layer "In6.Cu")
		(net "UPI_CPU0_CPU1_P2P2_DN<9>")
	)
	(arc
		(start 348.507812 -284.049216)
		(mid 348.428442 -284.32295)
		(end 348.225618 -284.52318)
		(width 0.0889)
		(layer "In6.Cu")
		(net "UPI_CPU0_CPU1_P2P2_DN<9>")
	)
	(arc
		(start 346.628466 -289.078416)
		(mid 346.703471 -289.193875)
		(end 346.812616 -289.277806)
		(width 0.0889)
		(layer "In6.Cu")
		(net "UPI_CPU0_CPU1_P2P2_DN<9>")
	)
	(arc
		(start 94.738444 -287.279334)
		(mid 94.816555 -287.002385)
		(end 95.020892 -286.799782)
		(width 0.0889)
		(layer "In6.Cu")
		(net "UPI_CPU0_CPU1_P2P2_DN<9>")
	)
	(arc
		(start 348.038166 -284.847538)
		(mid 347.964175 -285.127104)
		(end 347.76156 -285.33344)
		(width 0.0889)
		(layer "In6.Cu")
		(net "UPI_CPU0_CPU1_P2P2_DN<9>")
	)
	(arc
		(start 348.216728 -284.52826)
		(mid 348.085814 -284.66462)
		(end 348.038166 -284.847538)
		(width 0.0889)
		(layer "In6.Cu")
		(net "UPI_CPU0_CPU1_P2P2_DN<9>")
	)
	(arc
		(start 348.038166 -286.475424)
		(mid 347.964175 -286.75499)
		(end 347.76156 -286.961326)
		(width 0.0889)
		(layer "In6.Cu")
		(net "UPI_CPU0_CPU1_P2P2_DN<9>")
	)
	(arc
		(start 347.746574 -286.969962)
		(mid 347.61566 -287.106322)
		(end 347.568012 -287.28924)
		(width 0.0889)
		(layer "In6.Cu")
		(net "UPI_CPU0_CPU1_P2P2_DN<9>")
	)
	(arc
		(start 347.098366 -288.121598)
		(mid 347.018204 -288.393787)
		(end 346.815918 -288.592768)
		(width 0.0889)
		(layer "In6.Cu")
		(net "UPI_CPU0_CPU1_P2P2_DN<9>")
	)
	(arc
		(start 95.208598 -284.832044)
		(mid 95.287968 -284.55831)
		(end 95.490792 -284.35808)
		(width 0.0889)
		(layer "In6.Cu")
		(net "UPI_CPU0_CPU1_P2P2_DN<9>")
	)
	(arc
		(start 348.977966 -283.219906)
		(mid 348.905731 -283.49643)
		(end 348.707456 -283.702252)
		(width 0.0889)
		(layer "In6.Cu")
		(net "UPI_CPU0_CPU1_P2P2_DN<9>")
	)
	(arc
		(start 347.755464 -285.985712)
		(mid 347.958945 -286.186516)
		(end 348.038166 -286.4612)
		(width 0.0889)
		(layer "In6.Cu")
		(net "UPI_CPU0_CPU1_P2P2_DN<9>")
	)
	(arc
		(start 346.812362 -289.27806)
		(mid 346.986607 -289.417106)
		(end 347.097858 -289.610292)
		(width 0.0889)
		(layer "In6.Cu")
		(net "UPI_CPU0_CPU1_P2P2_DN<9>")
	)
	(arc
		(start 93.328744 -289.646106)
		(mid 93.253772 -289.530508)
		(end 93.144594 -289.446462)
		(width 0.0889)
		(layer "In6.Cu")
		(net "UPI_CPU0_CPU1_P2P2_DN<9>")
	)
	(arc
		(start 349.620332 -282.090114)
		(mid 349.343857 -282.157434)
		(end 349.06966 -282.081478)
		(width 0.0889)
		(layer "In6.Cu")
		(net "UPI_CPU0_CPU1_P2P2_DN<9>")
	)
	(arc
		(start 95.678244 -284.023816)
		(mid 95.756355 -283.746867)
		(end 95.960692 -283.544264)
		(width 0.0889)
		(layer "In6.Cu")
		(net "UPI_CPU0_CPU1_P2P2_DN<9>")
	)
	(arc
		(start 349.06966 -282.081478)
		(mid 348.882462 -282.031335)
		(end 348.695264 -282.081478)
		(width 0.0889)
		(layer "In6.Cu")
		(net "UPI_CPU0_CPU1_P2P2_DN<9>")
	)
	(arc
		(start 95.030036 -285.166816)
		(mid 95.16095 -285.030456)
		(end 95.208598 -284.847538)
		(width 0.0889)
		(layer "In6.Cu")
		(net "UPI_CPU0_CPU1_P2P2_DN<9>")
	)
	(arc
		(start 347.568012 -287.304734)
		(mid 347.488642 -287.578468)
		(end 347.285818 -287.778698)
		(width 0.0889)
		(layer "In6.Cu")
		(net "UPI_CPU0_CPU1_P2P2_DN<9>")
	)
	(arc
		(start 95.499682 -284.353)
		(mid 95.630596 -284.21664)
		(end 95.678244 -284.033722)
		(width 0.0889)
		(layer "In6.Cu")
		(net "UPI_CPU0_CPU1_P2P2_DN<9>")
	)
	(arc
		(start 93.144594 -289.446462)
		(mid 92.970462 -289.307615)
		(end 92.859098 -289.114738)
		(width 0.0889)
		(layer "In6.Cu")
		(net "UPI_CPU0_CPU1_P2P2_DN<9>")
	)
	(arc
		(start 349.64116 -281.106118)
		(mid 349.917734 -281.59202)
		(end 349.64116 -282.077922)
		(width 0.0889)
		(layer "In6.Cu")
		(net "UPI_CPU0_CPU1_P2P2_DN<9>")
	)
	(arc
		(start 348.695264 -282.730194)
		(mid 348.900336 -282.933873)
		(end 348.977966 -283.212286)
		(width 0.0889)
		(layer "In6.Cu")
		(net "UPI_CPU0_CPU1_P2P2_DN<9>")
	)
	(arc
		(start 95.969582 -283.539184)
		(mid 96.100496 -283.402824)
		(end 96.148144 -283.219906)
		(width 0.0889)
		(layer "In6.Cu")
		(net "UPI_CPU0_CPU1_P2P2_DN<9>")
	)
	(arc
		(start 94.176596 -287.613598)
		(mid 94.551071 -287.613552)
		(end 94.738444 -287.28924)
		(width 0.0889)
		(layer "In6.Cu")
		(net "UPI_CPU0_CPU1_P2P2_DN<9>")
	)
	(arc
		(start 348.686374 -283.714444)
		(mid 348.55546 -283.850804)
		(end 348.507812 -284.033722)
		(width 0.0889)
		(layer "In6.Cu")
		(net "UPI_CPU0_CPU1_P2P2_DN<9>")
	)
	(arc
		(start 346.807028 -288.597848)
		(mid 346.676114 -288.734208)
		(end 346.628466 -288.917126)
		(width 0.0889)
		(layer "In6.Cu")
		(net "UPI_CPU0_CPU1_P2P2_DN<9>")
	)
	(arc
		(start 96.148144 -283.205682)
		(mid 96.206505 -282.969084)
		(end 96.358964 -282.778962)
		(width 0.0889)
		(layer "In6.Cu")
		(net "UPI_CPU0_CPU1_P2P2_DN<9>")
	)
	(arc
		(start 93.150436 -288.422334)
		(mid 93.28135 -288.285974)
		(end 93.328998 -288.103056)
		(width 0.0889)
		(layer "In6.Cu")
		(net "UPI_CPU0_CPU1_P2P2_DN<9>")
	)
	(arc
		(start 95.029782 -286.794702)
		(mid 95.208379 -286.475424)
		(end 95.029782 -286.156146)
		(width 0.0889)
		(layer "In6.Cu")
		(net "UPI_CPU0_CPU1_P2P2_DN<9>")
	)
	(arc
		(start 347.276928 -287.783778)
		(mid 347.146014 -287.920138)
		(end 347.098366 -288.103056)
		(width 0.0889)
		(layer "In6.Cu")
		(net "UPI_CPU0_CPU1_P2P2_DN<9>")
	)
	(arc
		(start 95.020892 -286.151066)
		(mid 94.738243 -285.664963)
		(end 95.01505 -285.175452)
		(width 0.0889)
		(layer "In6.Cu")
		(net "UPI_CPU0_CPU1_P2P2_DN<9>")
	)
	(arc
		(start 92.859098 -288.898584)
		(mid 92.93926 -288.626395)
		(end 93.141546 -288.427414)
		(width 0.0889)
		(layer "In6.Cu")
		(net "UPI_CPU0_CPU1_P2P2_DN<9>")
	)
	(arc
		(start 347.746574 -285.342076)
		(mid 347.567977 -285.661354)
		(end 347.746574 -285.980632)
		(width 0.0889)
		(layer "In6.Cu")
		(net "UPI_CPU0_CPU1_P2P2_DN<9>")
	)
	(arc
		(start 348.686374 -282.086558)
		(mid 348.507777 -282.405836)
		(end 348.686374 -282.725114)
		(width 0.0889)
		(layer "In6.Cu")
		(net "UPI_CPU0_CPU1_P2P2_DN<9>")
	)
	(arc
		(start 93.328998 -288.087562)
		(mid 93.61073 -287.613864)
		(end 94.161864 -287.604962)
		(width 0.0889)
		(layer "In6.Cu")
		(net "UPI_CPU0_CPU1_P2P2_DN<9>")
	)
	(arc
		(start 349.12808 -281.073098)
		(mid 349.138074 -281.068939)
		(end 349.148146 -281.06497)
		(width 0.0889)
		(layer "In6.Cu")
		(net "UPI_CPU0_CPU1_P2P2_DN<9>")
	)
	(segment
		(start 96.713294 -279.428194)
		(end 96.713294 -279.96388)
		(width 0.13208)
		(layer "F.Cu")
		(net "UPI_CPU0_CPU1_P2P2_DN<8>")
	)
	(segment
		(start 96.713294 -279.96388)
		(end 96.713548 -279.964134)
		(width 0.13208)
		(layer "F.Cu")
		(net "UPI_CPU0_CPU1_P2P2_DN<8>")
	)
	(segment
		(start 349.352362 -282.683966)
		(end 349.352362 -283.219652)
		(width 0.13208)
		(layer "F.Cu")
		(net "UPI_CPU0_CPU1_P2P2_DN<8>")
	)
	(segment
		(start 349.352362 -283.219652)
		(end 349.352616 -283.219906)
		(width 0.13208)
		(layer "F.Cu")
		(net "UPI_CPU0_CPU1_P2P2_DN<8>")
	)
	(segment
		(start 63.081662 -333.850742)
		(end 62.992254 -333.493618)
		(width 0.14732)
		(layer "In6.Cu")
		(net "UPI_CPU0_CPU1_P2P2_DN<8>")
	)
	(segment
		(start 82.26171 -304.483262)
		(end 82.538824 -304.206402)
		(width 0.14732)
		(layer "In6.Cu")
		(net "UPI_CPU0_CPU1_P2P2_DN<8>")
	)
	(segment
		(start 339.141308 -305.0032)
		(end 338.787994 -305.149504)
		(width 0.14732)
		(layer "In6.Cu")
		(net "UPI_CPU0_CPU1_P2P2_DN<8>")
	)
	(segment
		(start 85.357716 -301.199804)
		(end 87.678514 -295.596056)
		(width 0.14732)
		(layer "In6.Cu")
		(net "UPI_CPU0_CPU1_P2P2_DN<8>")
	)
	(segment
		(start 64.194436 -323.412866)
		(end 64.511428 -323.097144)
		(width 0.14732)
		(layer "In6.Cu")
		(net "UPI_CPU0_CPU1_P2P2_DN<8>")
	)
	(segment
		(start 61.1632 -327.410318)
		(end 61.1632 -326.450198)
		(width 0.14732)
		(layer "In6.Cu")
		(net "UPI_CPU0_CPU1_P2P2_DN<8>")
	)
	(segment
		(start 81.812892 -304.743612)
		(end 82.073242 -304.483262)
		(width 0.14732)
		(layer "In6.Cu")
		(net "UPI_CPU0_CPU1_P2P2_DN<8>")
	)
	(segment
		(start 91.869768 -290.876228)
		(end 91.870784 -290.876228)
		(width 0.14732)
		(layer "In6.Cu")
		(net "UPI_CPU0_CPU1_P2P2_DN<8>")
	)
	(segment
		(start 66.998596 -319.772284)
		(end 69.138546 -317.632842)
		(width 0.14732)
		(layer "In6.Cu")
		(net "UPI_CPU0_CPU1_P2P2_DN<8>")
	)
	(segment
		(start 348.596712 -285.173928)
		(end 348.593918 -285.175452)
		(width 0.0889)
		(layer "In6.Cu")
		(net "UPI_CPU0_CPU1_P2P2_DN<8>")
	)
	(segment
		(start 273.575272 -369.682776)
		(end 266.274804 -376.983244)
		(width 0.14732)
		(layer "In6.Cu")
		(net "UPI_CPU0_CPU1_P2P2_DN<8>")
	)
	(segment
		(start 342.221566 -303.406556)
		(end 341.673942 -303.95418)
		(width 0.14732)
		(layer "In6.Cu")
		(net "UPI_CPU0_CPU1_P2P2_DN<8>")
	)
	(segment
		(start 317.803784 -325.53402)
		(end 316.689994 -328.224134)
		(width 0.14732)
		(layer "In6.Cu")
		(net "UPI_CPU0_CPU1_P2P2_DN<8>")
	)
	(segment
		(start 338.179918 -305.401726)
		(end 337.763866 -305.573938)
		(width 0.14732)
		(layer "In6.Cu")
		(net "UPI_CPU0_CPU1_P2P2_DN<8>")
	)
	(segment
		(start 345.76512 -294.482266)
		(end 345.76512 -298.14647)
		(width 0.14732)
		(layer "In6.Cu")
		(net "UPI_CPU0_CPU1_P2P2_DN<8>")
	)
	(segment
		(start 96.51746 -281.272742)
		(end 96.52635 -281.267662)
		(width 0.0889)
		(layer "In6.Cu")
		(net "UPI_CPU0_CPU1_P2P2_DN<8>")
	)
	(segment
		(start 341.673942 -303.95418)
		(end 340.863936 -304.289714)
		(width 0.14732)
		(layer "In6.Cu")
		(net "UPI_CPU0_CPU1_P2P2_DN<8>")
	)
	(segment
		(start 349.538544 -283.545026)
		(end 349.53702 -283.546042)
		(width 0.0889)
		(layer "In6.Cu")
		(net "UPI_CPU0_CPU1_P2P2_DN<8>")
	)
	(segment
		(start 63.007748 -332.960472)
		(end 62.83198 -332.855316)
		(width 0.14732)
		(layer "In6.Cu")
		(net "UPI_CPU0_CPU1_P2P2_DN<8>")
	)
	(segment
		(start 61.310266 -326.195182)
		(end 62.793372 -325.580756)
		(width 0.14732)
		(layer "In6.Cu")
		(net "UPI_CPU0_CPU1_P2P2_DN<8>")
	)
	(segment
		(start 63.651892 -324.722236)
		(end 64.194436 -323.412866)
		(width 0.14732)
		(layer "In6.Cu")
		(net "UPI_CPU0_CPU1_P2P2_DN<8>")
	)
	(segment
		(start 340.334346 -304.352198)
		(end 340.25586 -304.541428)
		(width 0.14732)
		(layer "In6.Cu")
		(net "UPI_CPU0_CPU1_P2P2_DN<8>")
	)
	(segment
		(start 348.787466 -284.832044)
		(end 348.787466 -284.847538)
		(width 0.0889)
		(layer "In6.Cu")
		(net "UPI_CPU0_CPU1_P2P2_DN<8>")
	)
	(segment
		(start 66.31432 -321.014598)
		(end 66.998596 -319.772284)
		(width 0.14732)
		(layer "In6.Cu")
		(net "UPI_CPU0_CPU1_P2P2_DN<8>")
	)
	(segment
		(start 96.900746 -279.639776)
		(end 96.90227 -279.640538)
		(width 0.0889)
		(layer "In6.Cu")
		(net "UPI_CPU0_CPU1_P2P2_DN<8>")
	)
	(segment
		(start 62.321186 -330.818236)
		(end 62.32144 -330.817982)
		(width 0.14732)
		(layer "In6.Cu")
		(net "UPI_CPU0_CPU1_P2P2_DN<8>")
	)
	(segment
		(start 62.586616 -331.281024)
		(end 62.497208 -330.923646)
		(width 0.14732)
		(layer "In6.Cu")
		(net "UPI_CPU0_CPU1_P2P2_DN<8>")
	)
	(segment
		(start 83.525106 -303.031906)
		(end 83.52536 -303.031906)
		(width 0.14732)
		(layer "In6.Cu")
		(net "UPI_CPU0_CPU1_P2P2_DN<8>")
	)
	(segment
		(start 92.579444 -289.610038)
		(end 92.579444 -289.60953)
		(width 0.0889)
		(layer "In6.Cu")
		(net "UPI_CPU0_CPU1_P2P2_DN<8>")
	)
	(segment
		(start 281.192986 -338.37753)
		(end 273.575272 -345.995244)
		(width 0.14732)
		(layer "In6.Cu")
		(net "UPI_CPU0_CPU1_P2P2_DN<8>")
	)
	(segment
		(start 62.992254 -333.493618)
		(end 63.09741 -333.318104)
		(width 0.14732)
		(layer "In6.Cu")
		(net "UPI_CPU0_CPU1_P2P2_DN<8>")
	)
	(segment
		(start 63.09741 -333.318104)
		(end 63.007748 -332.960472)
		(width 0.14732)
		(layer "In6.Cu")
		(net "UPI_CPU0_CPU1_P2P2_DN<8>")
	)
	(segment
		(start 92.57919 -290.107878)
		(end 92.57919 -289.610292)
		(width 0.0889)
		(layer "In6.Cu")
		(net "UPI_CPU0_CPU1_P2P2_DN<8>")
	)
	(segment
		(start 80.810354 -305.934618)
		(end 81.08696 -305.658266)
		(width 0.14732)
		(layer "In6.Cu")
		(net "UPI_CPU0_CPU1_P2P2_DN<8>")
	)
	(segment
		(start 345.80703 -292.178486)
		(end 345.80703 -294.418258)
		(width 0.0889)
		(layer "In6.Cu")
		(net "UPI_CPU0_CPU1_P2P2_DN<8>")
	)
	(segment
		(start 339.749384 -304.751232)
		(end 339.560408 -304.673)
		(width 0.14732)
		(layer "In6.Cu")
		(net "UPI_CPU0_CPU1_P2P2_DN<8>")
	)
	(segment
		(start 81.08696 -305.46929)
		(end 81.34731 -305.20894)
		(width 0.14732)
		(layer "In6.Cu")
		(net "UPI_CPU0_CPU1_P2P2_DN<8>")
	)
	(segment
		(start 82.073242 -304.483262)
		(end 82.26171 -304.483262)
		(width 0.14732)
		(layer "In6.Cu")
		(net "UPI_CPU0_CPU1_P2P2_DN<8>")
	)
	(segment
		(start 81.812892 -304.93208)
		(end 81.812892 -304.743612)
		(width 0.14732)
		(layer "In6.Cu")
		(net "UPI_CPU0_CPU1_P2P2_DN<8>")
	)
	(segment
		(start 348.608904 -285.166816)
		(end 348.601538 -285.171134)
		(width 0.0889)
		(layer "In6.Cu")
		(net "UPI_CPU0_CPU1_P2P2_DN<8>")
	)
	(segment
		(start 348.317312 -287.279334)
		(end 348.317312 -287.28924)
		(width 0.0889)
		(layer "In6.Cu")
		(net "UPI_CPU0_CPU1_P2P2_DN<8>")
	)
	(segment
		(start 94.167706 -285.342076)
		(end 94.182692 -285.33344)
		(width 0.0889)
		(layer "In6.Cu")
		(net "UPI_CPU0_CPU1_P2P2_DN<8>")
	)
	(segment
		(start 345.76512 -298.14647)
		(end 344.551508 -301.076614)
		(width 0.14732)
		(layer "In6.Cu")
		(net "UPI_CPU0_CPU1_P2P2_DN<8>")
	)
	(segment
		(start 80.084676 -306.660296)
		(end 80.361028 -306.383944)
		(width 0.14732)
		(layer "In6.Cu")
		(net "UPI_CPU0_CPU1_P2P2_DN<8>")
	)
	(segment
		(start 347.847412 -289.645852)
		(end 347.847412 -290.138104)
		(width 0.0889)
		(layer "In6.Cu")
		(net "UPI_CPU0_CPU1_P2P2_DN<8>")
	)
	(segment
		(start 92.109798 -289.078416)
		(end 92.109798 -288.917126)
		(width 0.0889)
		(layer "In6.Cu")
		(net "UPI_CPU0_CPU1_P2P2_DN<8>")
	)
	(segment
		(start 349.53702 -283.546042)
		(end 349.533718 -283.54782)
		(width 0.0889)
		(layer "In6.Cu")
		(net "UPI_CPU0_CPU1_P2P2_DN<8>")
	)
	(segment
		(start 61.735716 -328.480928)
		(end 61.1632 -327.410318)
		(width 0.14732)
		(layer "In6.Cu")
		(net "UPI_CPU0_CPU1_P2P2_DN<8>")
	)
	(segment
		(start 348.60865 -286.794702)
		(end 348.600522 -286.799274)
		(width 0.0889)
		(layer "In6.Cu")
		(net "UPI_CPU0_CPU1_P2P2_DN<8>")
	)
	(segment
		(start 62.793372 -325.580756)
		(end 63.651892 -324.722236)
		(width 0.14732)
		(layer "In6.Cu")
		(net "UPI_CPU0_CPU1_P2P2_DN<8>")
	)
	(segment
		(start 349.07855 -284.353)
		(end 349.06966 -284.35808)
		(width 0.0889)
		(layer "In6.Cu")
		(net "UPI_CPU0_CPU1_P2P2_DN<8>")
	)
	(segment
		(start 69.138546 -317.414402)
		(end 79.8957 -306.660296)
		(width 0.14732)
		(layer "In6.Cu")
		(net "UPI_CPU0_CPU1_P2P2_DN<8>")
	)
	(segment
		(start 62.497208 -330.923646)
		(end 62.321186 -330.818236)
		(width 0.14732)
		(layer "In6.Cu")
		(net "UPI_CPU0_CPU1_P2P2_DN<8>")
	)
	(segment
		(start 92.57919 -289.610292)
		(end 92.579444 -289.610038)
		(width 0.0889)
		(layer "In6.Cu")
		(net "UPI_CPU0_CPU1_P2P2_DN<8>")
	)
	(segment
		(start 62.04204 -329.703938)
		(end 61.735716 -328.480928)
		(width 0.14732)
		(layer "In6.Cu")
		(net "UPI_CPU0_CPU1_P2P2_DN<8>")
	)
	(segment
		(start 62.742572 -332.498192)
		(end 62.847728 -332.322678)
		(width 0.14732)
		(layer "In6.Cu")
		(net "UPI_CPU0_CPU1_P2P2_DN<8>")
	)
	(segment
		(start 347.377766 -288.898584)
		(end 347.377766 -289.114738)
		(width 0.0889)
		(layer "In6.Cu")
		(net "UPI_CPU0_CPU1_P2P2_DN<8>")
	)
	(segment
		(start 62.481714 -331.456538)
		(end 62.586616 -331.281024)
		(width 0.14732)
		(layer "In6.Cu")
		(net "UPI_CPU0_CPU1_P2P2_DN<8>")
	)
	(segment
		(start 65.657222 -322.359528)
		(end 66.200782 -321.372484)
		(width 0.14732)
		(layer "In6.Cu")
		(net "UPI_CPU0_CPU1_P2P2_DN<8>")
	)
	(segment
		(start 96.948244 -280.25598)
		(end 96.870012 -280.235152)
		(width 0.0889)
		(layer "In6.Cu")
		(net "UPI_CPU0_CPU1_P2P2_DN<8>")
	)
	(segment
		(start 308.496208 -336.41792)
		(end 285.92399 -336.41792)
		(width 0.14732)
		(layer "In6.Cu")
		(net "UPI_CPU0_CPU1_P2P2_DN<8>")
	)
	(segment
		(start 81.34731 -305.20894)
		(end 81.535778 -305.20894)
		(width 0.14732)
		(layer "In6.Cu")
		(net "UPI_CPU0_CPU1_P2P2_DN<8>")
	)
	(segment
		(start 266.274804 -376.983244)
		(end 161.310828 -385.89077)
		(width 0.14732)
		(layer "In6.Cu")
		(net "UPI_CPU0_CPU1_P2P2_DN<8>")
	)
	(segment
		(start 349.548704 -283.539184)
		(end 349.541592 -283.543248)
		(width 0.0889)
		(layer "In6.Cu")
		(net "UPI_CPU0_CPU1_P2P2_DN<8>")
	)
	(segment
		(start 339.219794 -304.813716)
		(end 339.141308 -305.0032)
		(width 0.14732)
		(layer "In6.Cu")
		(net "UPI_CPU0_CPU1_P2P2_DN<8>")
	)
	(segment
		(start 80.621378 -305.934618)
		(end 80.810354 -305.934618)
		(width 0.14732)
		(layer "In6.Cu")
		(net "UPI_CPU0_CPU1_P2P2_DN<8>")
	)
	(segment
		(start 92.579698 -288.121598)
		(end 92.579698 -288.103056)
		(width 0.0889)
		(layer "In6.Cu")
		(net "UPI_CPU0_CPU1_P2P2_DN<8>")
	)
	(segment
		(start 92.248482 -290.49853)
		(end 92.248482 -290.438586)
		(width 0.0889)
		(layer "In6.Cu")
		(net "UPI_CPU0_CPU1_P2P2_DN<8>")
	)
	(segment
		(start 337.763866 -305.573938)
		(end 317.803784 -325.53402)
		(width 0.14732)
		(layer "In6.Cu")
		(net "UPI_CPU0_CPU1_P2P2_DN<8>")
	)
	(segment
		(start 96.52635 -280.288492)
		(end 96.51746 -280.283412)
		(width 0.0889)
		(layer "In6.Cu")
		(net "UPI_CPU0_CPU1_P2P2_DN<8>")
	)
	(segment
		(start 83.264756 -303.292256)
		(end 83.525106 -303.031906)
		(width 0.14732)
		(layer "In6.Cu")
		(net "UPI_CPU0_CPU1_P2P2_DN<8>")
	)
	(segment
		(start 81.535778 -305.20894)
		(end 81.812892 -304.93208)
		(width 0.14732)
		(layer "In6.Cu")
		(net "UPI_CPU0_CPU1_P2P2_DN<8>")
	)
	(segment
		(start 273.575272 -345.995244)
		(end 273.575272 -369.682776)
		(width 0.14732)
		(layer "In6.Cu")
		(net "UPI_CPU0_CPU1_P2P2_DN<8>")
	)
	(segment
		(start 348.13875 -287.608518)
		(end 348.12986 -287.613598)
		(width 0.0889)
		(layer "In6.Cu")
		(net "UPI_CPU0_CPU1_P2P2_DN<8>")
	)
	(segment
		(start 63.241682 -334.489044)
		(end 63.347092 -334.31353)
		(width 0.14732)
		(layer "In6.Cu")
		(net "UPI_CPU0_CPU1_P2P2_DN<8>")
	)
	(segment
		(start 62.202314 -330.341986)
		(end 62.307216 -330.166726)
		(width 0.14732)
		(layer "In6.Cu")
		(net "UPI_CPU0_CPU1_P2P2_DN<8>")
	)
	(segment
		(start 91.870784 -290.876228)
		(end 92.232988 -290.514024)
		(width 0.14732)
		(layer "In6.Cu")
		(net "UPI_CPU0_CPU1_P2P2_DN<8>")
	)
	(segment
		(start 348.601538 -285.171134)
		(end 348.600014 -285.171896)
		(width 0.0889)
		(layer "In6.Cu")
		(net "UPI_CPU0_CPU1_P2P2_DN<8>")
	)
	(segment
		(start 347.847666 -288.087562)
		(end 347.847666 -288.103056)
		(width 0.0889)
		(layer "In6.Cu")
		(net "UPI_CPU0_CPU1_P2P2_DN<8>")
	)
	(segment
		(start 96.047306 -282.086558)
		(end 96.062292 -282.077922)
		(width 0.0889)
		(layer "In6.Cu")
		(net "UPI_CPU0_CPU1_P2P2_DN<8>")
	)
	(segment
		(start 62.582552 -331.859636)
		(end 62.481714 -331.456538)
		(width 0.14732)
		(layer "In6.Cu")
		(net "UPI_CPU0_CPU1_P2P2_DN<8>")
	)
	(segment
		(start 95.107506 -283.714444)
		(end 95.116396 -283.709364)
		(width 0.0889)
		(layer "In6.Cu")
		(net "UPI_CPU0_CPU1_P2P2_DN<8>")
	)
	(segment
		(start 61.1632 -326.450198)
		(end 61.239654 -326.265794)
		(width 0.14732)
		(layer "In6.Cu")
		(net "UPI_CPU0_CPU1_P2P2_DN<8>")
	)
	(segment
		(start 90.71737 -292.028626)
		(end 91.869768 -290.876228)
		(width 0.14732)
		(layer "In6.Cu")
		(net "UPI_CPU0_CPU1_P2P2_DN<8>")
	)
	(segment
		(start 94.63786 -284.52826)
		(end 94.64675 -284.52318)
		(width 0.0889)
		(layer "In6.Cu")
		(net "UPI_CPU0_CPU1_P2P2_DN<8>")
	)
	(segment
		(start 94.161864 -286.973518)
		(end 94.182692 -286.961326)
		(width 0.0889)
		(layer "In6.Cu")
		(net "UPI_CPU0_CPU1_P2P2_DN<8>")
	)
	(segment
		(start 347.847412 -290.138104)
		(end 345.80703 -292.178486)
		(width 0.0889)
		(layer "In6.Cu")
		(net "UPI_CPU0_CPU1_P2P2_DN<8>")
	)
	(segment
		(start 94.928944 -284.049216)
		(end 94.928944 -284.033722)
		(width 0.0889)
		(layer "In6.Cu")
		(net "UPI_CPU0_CPU1_P2P2_DN<8>")
	)
	(segment
		(start 62.847728 -332.322678)
		(end 62.75832 -331.965046)
		(width 0.14732)
		(layer "In6.Cu")
		(net "UPI_CPU0_CPU1_P2P2_DN<8>")
	)
	(segment
		(start 345.76512 -294.460168)
		(end 345.76512 -294.482266)
		(width 0.0889)
		(layer "In6.Cu")
		(net "UPI_CPU0_CPU1_P2P2_DN<8>")
	)
	(segment
		(start 63.25743 -333.955898)
		(end 63.081662 -333.850742)
		(width 0.14732)
		(layer "In6.Cu")
		(net "UPI_CPU0_CPU1_P2P2_DN<8>")
	)
	(segment
		(start 316.689994 -328.224134)
		(end 308.496208 -336.41792)
		(width 0.14732)
		(layer "In6.Cu")
		(net "UPI_CPU0_CPU1_P2P2_DN<8>")
	)
	(segment
		(start 95.868744 -282.424378)
		(end 95.868744 -282.405836)
		(width 0.0889)
		(layer "In6.Cu")
		(net "UPI_CPU0_CPU1_P2P2_DN<8>")
	)
	(segment
		(start 63.347092 -334.31353)
		(end 63.25743 -333.955898)
		(width 0.14732)
		(layer "In6.Cu")
		(net "UPI_CPU0_CPU1_P2P2_DN<8>")
	)
	(segment
		(start 82.538824 -304.017934)
		(end 82.799174 -303.757584)
		(width 0.14732)
		(layer "In6.Cu")
		(net "UPI_CPU0_CPU1_P2P2_DN<8>")
	)
	(segment
		(start 83.264502 -303.480724)
		(end 83.264756 -303.292256)
		(width 0.14732)
		(layer "In6.Cu")
		(net "UPI_CPU0_CPU1_P2P2_DN<8>")
	)
	(segment
		(start 349.541592 -283.543248)
		(end 349.538544 -283.545026)
		(width 0.0889)
		(layer "In6.Cu")
		(net "UPI_CPU0_CPU1_P2P2_DN<8>")
	)
	(segment
		(start 82.538824 -304.206402)
		(end 82.538824 -304.017934)
		(width 0.14732)
		(layer "In6.Cu")
		(net "UPI_CPU0_CPU1_P2P2_DN<8>")
	)
	(segment
		(start 68.394072 -366.936782)
		(end 63.377318 -354.8253)
		(width 0.14732)
		(layer "In6.Cu")
		(net "UPI_CPU0_CPU1_P2P2_DN<8>")
	)
	(segment
		(start 93.049598 -287.299146)
		(end 93.049598 -287.280604)
		(width 0.0889)
		(layer "In6.Cu")
		(net "UPI_CPU0_CPU1_P2P2_DN<8>")
	)
	(segment
		(start 94.459298 -286.475424)
		(end 94.459298 -286.4612)
		(width 0.0889)
		(layer "In6.Cu")
		(net "UPI_CPU0_CPU1_P2P2_DN<8>")
	)
	(segment
		(start 342.687148 -302.940974)
		(end 342.482424 -302.940974)
		(width 0.14732)
		(layer "In6.Cu")
		(net "UPI_CPU0_CPU1_P2P2_DN<8>")
	)
	(segment
		(start 285.92399 -336.41792)
		(end 281.192986 -338.37753)
		(width 0.14732)
		(layer "In6.Cu")
		(net "UPI_CPU0_CPU1_P2P2_DN<8>")
	)
	(segment
		(start 95.398844 -283.229812)
		(end 95.398844 -283.219906)
		(width 0.0889)
		(layer "In6.Cu")
		(net "UPI_CPU0_CPU1_P2P2_DN<8>")
	)
	(segment
		(start 62.32144 -330.817982)
		(end 62.202314 -330.341986)
		(width 0.14732)
		(layer "In6.Cu")
		(net "UPI_CPU0_CPU1_P2P2_DN<8>")
	)
	(segment
		(start 62.75832 -331.965046)
		(end 62.582298 -331.85989)
		(width 0.14732)
		(layer "In6.Cu")
		(net "UPI_CPU0_CPU1_P2P2_DN<8>")
	)
	(segment
		(start 62.217808 -329.809094)
		(end 62.04204 -329.703938)
		(width 0.14732)
		(layer "In6.Cu")
		(net "UPI_CPU0_CPU1_P2P2_DN<8>")
	)
	(segment
		(start 62.83198 -332.855316)
		(end 62.742572 -332.498192)
		(width 0.14732)
		(layer "In6.Cu")
		(net "UPI_CPU0_CPU1_P2P2_DN<8>")
	)
	(segment
		(start 340.67496 -304.211228)
		(end 340.334346 -304.352198)
		(width 0.14732)
		(layer "In6.Cu")
		(net "UPI_CPU0_CPU1_P2P2_DN<8>")
	)
	(segment
		(start 345.80703 -294.418258)
		(end 345.76512 -294.460168)
		(width 0.0889)
		(layer "In6.Cu")
		(net "UPI_CPU0_CPU1_P2P2_DN<8>")
	)
	(segment
		(start 92.232988 -290.514024)
		(end 92.248482 -290.49853)
		(width 0.0889)
		(layer "In6.Cu")
		(net "UPI_CPU0_CPU1_P2P2_DN<8>")
	)
	(segment
		(start 79.8957 -306.660296)
		(end 80.084676 -306.660296)
		(width 0.14732)
		(layer "In6.Cu")
		(net "UPI_CPU0_CPU1_P2P2_DN<8>")
	)
	(segment
		(start 161.310828 -385.89077)
		(end 126.195074 -385.89077)
		(width 0.14732)
		(layer "In6.Cu")
		(net "UPI_CPU0_CPU1_P2P2_DN<8>")
	)
	(segment
		(start 65.202054 -322.813426)
		(end 65.657222 -322.359528)
		(width 0.14732)
		(layer "In6.Cu")
		(net "UPI_CPU0_CPU1_P2P2_DN<8>")
	)
	(segment
		(start 61.239654 -326.265794)
		(end 61.310266 -326.195182)
		(width 0.14732)
		(layer "In6.Cu")
		(net "UPI_CPU0_CPU1_P2P2_DN<8>")
	)
	(segment
		(start 83.52536 -303.031906)
		(end 85.357716 -301.199804)
		(width 0.14732)
		(layer "In6.Cu")
		(net "UPI_CPU0_CPU1_P2P2_DN<8>")
	)
	(segment
		(start 69.138546 -317.632842)
		(end 69.138546 -317.414402)
		(width 0.14732)
		(layer "In6.Cu")
		(net "UPI_CPU0_CPU1_P2P2_DN<8>")
	)
	(segment
		(start 126.195074 -385.89077)
		(end 96.02851 -381.415798)
		(width 0.14732)
		(layer "In6.Cu")
		(net "UPI_CPU0_CPU1_P2P2_DN<8>")
	)
	(segment
		(start 338.258404 -305.212242)
		(end 338.179918 -305.401726)
		(width 0.14732)
		(layer "In6.Cu")
		(net "UPI_CPU0_CPU1_P2P2_DN<8>")
	)
	(segment
		(start 96.870012 -280.235152)
		(end 96.713548 -279.964134)
		(width 0.0889)
		(layer "In6.Cu")
		(net "UPI_CPU0_CPU1_P2P2_DN<8>")
	)
	(segment
		(start 92.248482 -290.438586)
		(end 92.57919 -290.107878)
		(width 0.0889)
		(layer "In6.Cu")
		(net "UPI_CPU0_CPU1_P2P2_DN<8>")
	)
	(segment
		(start 344.551508 -301.076614)
		(end 342.687148 -302.940974)
		(width 0.14732)
		(layer "In6.Cu")
		(net "UPI_CPU0_CPU1_P2P2_DN<8>")
	)
	(segment
		(start 342.221566 -303.201832)
		(end 342.221566 -303.406556)
		(width 0.14732)
		(layer "In6.Cu")
		(net "UPI_CPU0_CPU1_P2P2_DN<8>")
	)
	(segment
		(start 339.560408 -304.673)
		(end 339.219794 -304.813716)
		(width 0.14732)
		(layer "In6.Cu")
		(net "UPI_CPU0_CPU1_P2P2_DN<8>")
	)
	(segment
		(start 82.987642 -303.757584)
		(end 83.264502 -303.480724)
		(width 0.14732)
		(layer "In6.Cu")
		(net "UPI_CPU0_CPU1_P2P2_DN<8>")
	)
	(segment
		(start 87.678514 -295.596056)
		(end 90.71737 -292.5572)
		(width 0.14732)
		(layer "In6.Cu")
		(net "UPI_CPU0_CPU1_P2P2_DN<8>")
	)
	(segment
		(start 349.66529 -283.219906)
		(end 349.722694 -283.27731)
		(width 0.0889)
		(layer "In6.Cu")
		(net "UPI_CPU0_CPU1_P2P2_DN<8>")
	)
	(segment
		(start 342.482424 -302.940974)
		(end 342.221566 -303.201832)
		(width 0.14732)
		(layer "In6.Cu")
		(net "UPI_CPU0_CPU1_P2P2_DN<8>")
	)
	(segment
		(start 62.582298 -331.85989)
		(end 62.582552 -331.859636)
		(width 0.14732)
		(layer "In6.Cu")
		(net "UPI_CPU0_CPU1_P2P2_DN<8>")
	)
	(segment
		(start 90.71737 -292.5572)
		(end 90.71737 -292.028626)
		(width 0.14732)
		(layer "In6.Cu")
		(net "UPI_CPU0_CPU1_P2P2_DN<8>")
	)
	(segment
		(start 82.799174 -303.757584)
		(end 82.987642 -303.757584)
		(width 0.14732)
		(layer "In6.Cu")
		(net "UPI_CPU0_CPU1_P2P2_DN<8>")
	)
	(segment
		(start 92.75826 -287.783778)
		(end 92.76715 -287.778698)
		(width 0.0889)
		(layer "In6.Cu")
		(net "UPI_CPU0_CPU1_P2P2_DN<8>")
	)
	(segment
		(start 348.59976 -286.151066)
		(end 348.60865 -286.156146)
		(width 0.0889)
		(layer "In6.Cu")
		(net "UPI_CPU0_CPU1_P2P2_DN<8>")
	)
	(segment
		(start 80.361028 -306.383944)
		(end 80.361028 -306.194968)
		(width 0.14732)
		(layer "In6.Cu")
		(net "UPI_CPU0_CPU1_P2P2_DN<8>")
	)
	(segment
		(start 340.25586 -304.541428)
		(end 339.749384 -304.751232)
		(width 0.14732)
		(layer "In6.Cu")
		(net "UPI_CPU0_CPU1_P2P2_DN<8>")
	)
	(segment
		(start 349.352616 -283.219906)
		(end 349.66529 -283.219906)
		(width 0.0889)
		(layer "In6.Cu")
		(net "UPI_CPU0_CPU1_P2P2_DN<8>")
	)
	(segment
		(start 92.28836 -288.597848)
		(end 92.29725 -288.592768)
		(width 0.0889)
		(layer "In6.Cu")
		(net "UPI_CPU0_CPU1_P2P2_DN<8>")
	)
	(segment
		(start 347.669104 -288.422334)
		(end 347.660214 -288.427414)
		(width 0.0889)
		(layer "In6.Cu")
		(net "UPI_CPU0_CPU1_P2P2_DN<8>")
	)
	(segment
		(start 73.570084 -372.112794)
		(end 68.394072 -366.936782)
		(width 0.14732)
		(layer "In6.Cu")
		(net "UPI_CPU0_CPU1_P2P2_DN<8>")
	)
	(segment
		(start 95.577406 -282.900628)
		(end 95.586296 -282.895548)
		(width 0.0889)
		(layer "In6.Cu")
		(net "UPI_CPU0_CPU1_P2P2_DN<8>")
	)
	(segment
		(start 63.377318 -354.8253)
		(end 63.377318 -335.030826)
		(width 0.14732)
		(layer "In6.Cu")
		(net "UPI_CPU0_CPU1_P2P2_DN<8>")
	)
	(segment
		(start 62.307216 -330.166726)
		(end 62.217808 -329.809094)
		(width 0.14732)
		(layer "In6.Cu")
		(net "UPI_CPU0_CPU1_P2P2_DN<8>")
	)
	(segment
		(start 81.08696 -305.658266)
		(end 81.08696 -305.46929)
		(width 0.14732)
		(layer "In6.Cu")
		(net "UPI_CPU0_CPU1_P2P2_DN<8>")
	)
	(segment
		(start 94.176596 -285.985712)
		(end 94.167706 -285.980632)
		(width 0.0889)
		(layer "In6.Cu")
		(net "UPI_CPU0_CPU1_P2P2_DN<8>")
	)
	(segment
		(start 64.511428 -323.097144)
		(end 65.202054 -322.813426)
		(width 0.14732)
		(layer "In6.Cu")
		(net "UPI_CPU0_CPU1_P2P2_DN<8>")
	)
	(segment
		(start 338.599018 -305.071272)
		(end 338.258404 -305.212242)
		(width 0.14732)
		(layer "In6.Cu")
		(net "UPI_CPU0_CPU1_P2P2_DN<8>")
	)
	(segment
		(start 63.377318 -335.030826)
		(end 63.241682 -334.489044)
		(width 0.14732)
		(layer "In6.Cu")
		(net "UPI_CPU0_CPU1_P2P2_DN<8>")
	)
	(segment
		(start 96.02851 -381.415798)
		(end 73.570084 -372.112794)
		(width 0.14732)
		(layer "In6.Cu")
		(net "UPI_CPU0_CPU1_P2P2_DN<8>")
	)
	(segment
		(start 80.361028 -306.194968)
		(end 80.621378 -305.934618)
		(width 0.14732)
		(layer "In6.Cu")
		(net "UPI_CPU0_CPU1_P2P2_DN<8>")
	)
	(segment
		(start 348.600522 -286.799274)
		(end 348.59976 -286.799782)
		(width 0.0889)
		(layer "In6.Cu")
		(net "UPI_CPU0_CPU1_P2P2_DN<8>")
	)
	(segment
		(start 348.600014 -285.171896)
		(end 348.596712 -285.173928)
		(width 0.0889)
		(layer "In6.Cu")
		(net "UPI_CPU0_CPU1_P2P2_DN<8>")
	)
	(segment
		(start 338.787994 -305.149504)
		(end 338.599018 -305.071272)
		(width 0.14732)
		(layer "In6.Cu")
		(net "UPI_CPU0_CPU1_P2P2_DN<8>")
	)
	(segment
		(start 66.200782 -321.372484)
		(end 66.31432 -321.014598)
		(width 0.14732)
		(layer "In6.Cu")
		(net "UPI_CPU0_CPU1_P2P2_DN<8>")
	)
	(segment
		(start 340.863936 -304.289714)
		(end 340.67496 -304.211228)
		(width 0.14732)
		(layer "In6.Cu")
		(net "UPI_CPU0_CPU1_P2P2_DN<8>")
	)
	(arc
		(start 92.76715 -287.778698)
		(mid 92.971485 -287.576093)
		(end 93.049598 -287.299146)
		(width 0.0889)
		(layer "In6.Cu")
		(net "UPI_CPU0_CPU1_P2P2_DN<8>")
	)
	(arc
		(start 96.062292 -282.077922)
		(mid 96.264879 -281.871571)
		(end 96.338898 -281.59202)
		(width 0.0889)
		(layer "In6.Cu")
		(net "UPI_CPU0_CPU1_P2P2_DN<8>")
	)
	(arc
		(start 92.579698 -288.103056)
		(mid 92.627377 -287.920156)
		(end 92.75826 -287.783778)
		(width 0.0889)
		(layer "In6.Cu")
		(net "UPI_CPU0_CPU1_P2P2_DN<8>")
	)
	(arc
		(start 93.611192 -286.964882)
		(mid 93.885391 -287.040717)
		(end 94.161864 -286.973518)
		(width 0.0889)
		(layer "In6.Cu")
		(net "UPI_CPU0_CPU1_P2P2_DN<8>")
	)
	(arc
		(start 96.52635 -281.267662)
		(mid 96.808882 -280.778141)
		(end 96.52635 -280.288492)
		(width 0.0889)
		(layer "In6.Cu")
		(net "UPI_CPU0_CPU1_P2P2_DN<8>")
	)
	(arc
		(start 348.59976 -286.799782)
		(mid 348.395425 -287.002387)
		(end 348.317312 -287.279334)
		(width 0.0889)
		(layer "In6.Cu")
		(net "UPI_CPU0_CPU1_P2P2_DN<8>")
	)
	(arc
		(start 348.787466 -284.847538)
		(mid 348.739787 -285.030438)
		(end 348.608904 -285.166816)
		(width 0.0889)
		(layer "In6.Cu")
		(net "UPI_CPU0_CPU1_P2P2_DN<8>")
	)
	(arc
		(start 348.593918 -285.175452)
		(mid 348.317011 -285.664963)
		(end 348.59976 -286.151066)
		(width 0.0889)
		(layer "In6.Cu")
		(net "UPI_CPU0_CPU1_P2P2_DN<8>")
	)
	(arc
		(start 92.293948 -289.277806)
		(mid 92.184801 -289.193878)
		(end 92.109798 -289.078416)
		(width 0.0889)
		(layer "In6.Cu")
		(net "UPI_CPU0_CPU1_P2P2_DN<8>")
	)
	(arc
		(start 94.928944 -284.033722)
		(mid 94.976623 -283.850822)
		(end 95.107506 -283.714444)
		(width 0.0889)
		(layer "In6.Cu")
		(net "UPI_CPU0_CPU1_P2P2_DN<8>")
	)
	(arc
		(start 96.51746 -280.283412)
		(mid 96.389482 -280.152376)
		(end 96.338898 -279.976326)
		(width 0.0889)
		(layer "In6.Cu")
		(net "UPI_CPU0_CPU1_P2P2_DN<8>")
	)
	(arc
		(start 348.60865 -286.156146)
		(mid 348.787247 -286.475424)
		(end 348.60865 -286.794702)
		(width 0.0889)
		(layer "In6.Cu")
		(net "UPI_CPU0_CPU1_P2P2_DN<8>")
	)
	(arc
		(start 94.459298 -284.847538)
		(mid 94.506977 -284.664638)
		(end 94.63786 -284.52826)
		(width 0.0889)
		(layer "In6.Cu")
		(net "UPI_CPU0_CPU1_P2P2_DN<8>")
	)
	(arc
		(start 95.116396 -283.709364)
		(mid 95.320731 -283.506759)
		(end 95.398844 -283.229812)
		(width 0.0889)
		(layer "In6.Cu")
		(net "UPI_CPU0_CPU1_P2P2_DN<8>")
	)
	(arc
		(start 93.049598 -287.280604)
		(mid 93.240419 -286.962577)
		(end 93.611192 -286.964882)
		(width 0.0889)
		(layer "In6.Cu")
		(net "UPI_CPU0_CPU1_P2P2_DN<8>")
	)
	(arc
		(start 96.338898 -281.59202)
		(mid 96.386577 -281.40912)
		(end 96.51746 -281.272742)
		(width 0.0889)
		(layer "In6.Cu")
		(net "UPI_CPU0_CPU1_P2P2_DN<8>")
	)
	(arc
		(start 348.317312 -287.28924)
		(mid 348.269633 -287.47214)
		(end 348.13875 -287.608518)
		(width 0.0889)
		(layer "In6.Cu")
		(net "UPI_CPU0_CPU1_P2P2_DN<8>")
	)
	(arc
		(start 348.12986 -287.613598)
		(mid 347.927037 -287.813829)
		(end 347.847666 -288.087562)
		(width 0.0889)
		(layer "In6.Cu")
		(net "UPI_CPU0_CPU1_P2P2_DN<8>")
	)
	(arc
		(start 95.398844 -283.219906)
		(mid 95.446523 -283.037006)
		(end 95.577406 -282.900628)
		(width 0.0889)
		(layer "In6.Cu")
		(net "UPI_CPU0_CPU1_P2P2_DN<8>")
	)
	(arc
		(start 94.182692 -286.961326)
		(mid 94.385279 -286.754975)
		(end 94.459298 -286.475424)
		(width 0.0889)
		(layer "In6.Cu")
		(net "UPI_CPU0_CPU1_P2P2_DN<8>")
	)
	(arc
		(start 94.64675 -284.52318)
		(mid 94.849573 -284.322949)
		(end 94.928944 -284.049216)
		(width 0.0889)
		(layer "In6.Cu")
		(net "UPI_CPU0_CPU1_P2P2_DN<8>")
	)
	(arc
		(start 92.109798 -288.917126)
		(mid 92.157477 -288.734226)
		(end 92.28836 -288.597848)
		(width 0.0889)
		(layer "In6.Cu")
		(net "UPI_CPU0_CPU1_P2P2_DN<8>")
	)
	(arc
		(start 347.663262 -289.446462)
		(mid 347.772409 -289.53039)
		(end 347.847412 -289.645852)
		(width 0.0889)
		(layer "In6.Cu")
		(net "UPI_CPU0_CPU1_P2P2_DN<8>")
	)
	(arc
		(start 96.90227 -279.640538)
		(mid 97.087237 -279.936193)
		(end 96.948244 -280.25598)
		(width 0.0889)
		(layer "In6.Cu")
		(net "UPI_CPU0_CPU1_P2P2_DN<8>")
	)
	(arc
		(start 95.586296 -282.895548)
		(mid 95.788582 -282.696567)
		(end 95.868744 -282.424378)
		(width 0.0889)
		(layer "In6.Cu")
		(net "UPI_CPU0_CPU1_P2P2_DN<8>")
	)
	(arc
		(start 94.459298 -286.4612)
		(mid 94.380079 -286.186515)
		(end 94.176596 -285.985712)
		(width 0.0889)
		(layer "In6.Cu")
		(net "UPI_CPU0_CPU1_P2P2_DN<8>")
	)
	(arc
		(start 349.722694 -283.27731)
		(mid 349.664538 -283.427423)
		(end 349.548704 -283.539184)
		(width 0.0889)
		(layer "In6.Cu")
		(net "UPI_CPU0_CPU1_P2P2_DN<8>")
	)
	(arc
		(start 349.533718 -283.54782)
		(mid 349.331131 -283.754171)
		(end 349.257112 -284.033722)
		(width 0.0889)
		(layer "In6.Cu")
		(net "UPI_CPU0_CPU1_P2P2_DN<8>")
	)
	(arc
		(start 94.167706 -285.980632)
		(mid 93.988988 -285.661354)
		(end 94.167706 -285.342076)
		(width 0.0889)
		(layer "In6.Cu")
		(net "UPI_CPU0_CPU1_P2P2_DN<8>")
	)
	(arc
		(start 349.06966 -284.35808)
		(mid 348.866837 -284.558311)
		(end 348.787466 -284.832044)
		(width 0.0889)
		(layer "In6.Cu")
		(net "UPI_CPU0_CPU1_P2P2_DN<8>")
	)
	(arc
		(start 92.579444 -289.60953)
		(mid 92.468106 -289.41663)
		(end 92.293948 -289.277806)
		(width 0.0889)
		(layer "In6.Cu")
		(net "UPI_CPU0_CPU1_P2P2_DN<8>")
	)
	(arc
		(start 94.182692 -285.33344)
		(mid 94.385279 -285.127089)
		(end 94.459298 -284.847538)
		(width 0.0889)
		(layer "In6.Cu")
		(net "UPI_CPU0_CPU1_P2P2_DN<8>")
	)
	(arc
		(start 92.29725 -288.592768)
		(mid 92.499536 -288.393787)
		(end 92.579698 -288.121598)
		(width 0.0889)
		(layer "In6.Cu")
		(net "UPI_CPU0_CPU1_P2P2_DN<8>")
	)
	(arc
		(start 347.377766 -289.114738)
		(mid 347.489104 -289.307638)
		(end 347.663262 -289.446462)
		(width 0.0889)
		(layer "In6.Cu")
		(net "UPI_CPU0_CPU1_P2P2_DN<8>")
	)
	(arc
		(start 347.847666 -288.103056)
		(mid 347.799987 -288.285956)
		(end 347.669104 -288.422334)
		(width 0.0889)
		(layer "In6.Cu")
		(net "UPI_CPU0_CPU1_P2P2_DN<8>")
	)
	(arc
		(start 347.660214 -288.427414)
		(mid 347.457928 -288.626395)
		(end 347.377766 -288.898584)
		(width 0.0889)
		(layer "In6.Cu")
		(net "UPI_CPU0_CPU1_P2P2_DN<8>")
	)
	(arc
		(start 95.868744 -282.405836)
		(mid 95.916423 -282.222936)
		(end 96.047306 -282.086558)
		(width 0.0889)
		(layer "In6.Cu")
		(net "UPI_CPU0_CPU1_P2P2_DN<8>")
	)
	(arc
		(start 96.338898 -279.953974)
		(mid 96.530514 -279.637229)
		(end 96.900746 -279.639776)
		(width 0.0889)
		(layer "In6.Cu")
		(net "UPI_CPU0_CPU1_P2P2_DN<8>")
	)
	(arc
		(start 349.257112 -284.033722)
		(mid 349.209433 -284.216622)
		(end 349.07855 -284.353)
		(width 0.0889)
		(layer "In6.Cu")
		(net "UPI_CPU0_CPU1_P2P2_DN<8>")
	)
	(arc
		(start 96.338898 -279.976326)
		(mid 96.338731 -279.96515)
		(end 96.338898 -279.953974)
		(width 0.0889)
		(layer "In6.Cu")
		(net "UPI_CPU0_CPU1_P2P2_DN<8>")
	)
	(segment
		(start 95.773494 -281.591766)
		(end 95.773748 -281.59202)
		(width 0.13208)
		(layer "F.Cu")
		(net "UPI_CPU0_CPU1_P2P2_DN<7>")
	)
	(segment
		(start 350.292162 -281.591766)
		(end 350.292416 -281.59202)
		(width 0.13208)
		(layer "F.Cu")
		(net "UPI_CPU0_CPU1_P2P2_DN<7>")
	)
	(segment
		(start 350.292162 -281.05608)
		(end 350.292162 -281.591766)
		(width 0.13208)
		(layer "F.Cu")
		(net "UPI_CPU0_CPU1_P2P2_DN<7>")
	)
	(segment
		(start 95.773494 -281.05608)
		(end 95.773494 -281.591766)
		(width 0.13208)
		(layer "F.Cu")
		(net "UPI_CPU0_CPU1_P2P2_DN<7>")
	)
	(segment
		(start 350.576134 -283.708602)
		(end 350.573848 -283.710126)
		(width 0.0889)
		(layer "In6.Cu")
		(net "UPI_CPU0_CPU1_P2P2_DN<7>")
	)
	(segment
		(start 350.565974 -283.714698)
		(end 350.565974 -283.714444)
		(width 0.0889)
		(layer "In6.Cu")
		(net "UPI_CPU0_CPU1_P2P2_DN<7>")
	)
	(segment
		(start 274.677632 -370.139722)
		(end 266.769596 -378.047758)
		(width 0.14732)
		(layer "In6.Cu")
		(net "UPI_CPU0_CPU1_P2P2_DN<7>")
	)
	(segment
		(start 67.735196 -317.060326)
		(end 84.536788 -300.258734)
		(width 0.14732)
		(layer "In6.Cu")
		(net "UPI_CPU0_CPU1_P2P2_DN<7>")
	)
	(segment
		(start 95.617284 -281.863038)
		(end 95.773748 -281.59202)
		(width 0.0889)
		(layer "In6.Cu")
		(net "UPI_CPU0_CPU1_P2P2_DN<7>")
	)
	(segment
		(start 348.977712 -290.247832)
		(end 346.828872 -292.396672)
		(width 0.0889)
		(layer "In6.Cu")
		(net "UPI_CPU0_CPU1_P2P2_DN<7>")
	)
	(segment
		(start 91.728036 -287.615884)
		(end 91.731846 -287.613598)
		(width 0.0889)
		(layer "In6.Cu")
		(net "UPI_CPU0_CPU1_P2P2_DN<7>")
	)
	(segment
		(start 350.573848 -283.710126)
		(end 350.565974 -283.714698)
		(width 0.0889)
		(layer "In6.Cu")
		(net "UPI_CPU0_CPU1_P2P2_DN<7>")
	)
	(segment
		(start 93.13545 -285.175452)
		(end 93.150436 -285.166816)
		(width 0.0889)
		(layer "In6.Cu")
		(net "UPI_CPU0_CPU1_P2P2_DN<7>")
	)
	(segment
		(start 346.717366 -299.183552)
		(end 345.747848 -301.444914)
		(width 0.14732)
		(layer "In6.Cu")
		(net "UPI_CPU0_CPU1_P2P2_DN<7>")
	)
	(segment
		(start 93.611192 -284.35808)
		(end 93.620082 -284.353)
		(width 0.0889)
		(layer "In6.Cu")
		(net "UPI_CPU0_CPU1_P2P2_DN<7>")
	)
	(segment
		(start 281.81554 -339.314282)
		(end 274.677632 -346.45219)
		(width 0.14732)
		(layer "In6.Cu")
		(net "UPI_CPU0_CPU1_P2P2_DN<7>")
	)
	(segment
		(start 349.64116 -285.33344)
		(end 349.635826 -285.336488)
		(width 0.0889)
		(layer "In6.Cu")
		(net "UPI_CPU0_CPU1_P2P2_DN<7>")
	)
	(segment
		(start 350.387412 -284.033722)
		(end 350.387412 -284.049216)
		(width 0.0889)
		(layer "In6.Cu")
		(net "UPI_CPU0_CPU1_P2P2_DN<7>")
	)
	(segment
		(start 86.714584 -294.999918)
		(end 89.61247 -292.102032)
		(width 0.14732)
		(layer "In6.Cu")
		(net "UPI_CPU0_CPU1_P2P2_DN<7>")
	)
	(segment
		(start 91.262708 -288.426906)
		(end 91.270582 -288.422334)
		(width 0.0889)
		(layer "In6.Cu")
		(net "UPI_CPU0_CPU1_P2P2_DN<7>")
	)
	(segment
		(start 91.731846 -287.613598)
		(end 91.740736 -287.608518)
		(width 0.0889)
		(layer "In6.Cu")
		(net "UPI_CPU0_CPU1_P2P2_DN<7>")
	)
	(segment
		(start 349.165418 -287.778698)
		(end 349.156528 -287.783778)
		(width 0.0889)
		(layer "In6.Cu")
		(net "UPI_CPU0_CPU1_P2P2_DN<7>")
	)
	(segment
		(start 60.05068 -326.212962)
		(end 60.287408 -325.641208)
		(width 0.14732)
		(layer "In6.Cu")
		(net "UPI_CPU0_CPU1_P2P2_DN<7>")
	)
	(segment
		(start 90.979752 -289.078924)
		(end 90.979752 -288.89452)
		(width 0.0889)
		(layer "In6.Cu")
		(net "UPI_CPU0_CPU1_P2P2_DN<7>")
	)
	(segment
		(start 348.977966 -288.103056)
		(end 348.977966 -288.121598)
		(width 0.0889)
		(layer "In6.Cu")
		(net "UPI_CPU0_CPU1_P2P2_DN<7>")
	)
	(segment
		(start 90.43416 -289.62731)
		(end 90.769948 -289.291522)
		(width 0.0889)
		(layer "In6.Cu")
		(net "UPI_CPU0_CPU1_P2P2_DN<7>")
	)
	(segment
		(start 95.679768 -382.482852)
		(end 72.54494 -372.900194)
		(width 0.14732)
		(layer "In6.Cu")
		(net "UPI_CPU0_CPU1_P2P2_DN<7>")
	)
	(segment
		(start 66.006218 -319.20307)
		(end 67.735196 -317.474092)
		(width 0.14732)
		(layer "In6.Cu")
		(net "UPI_CPU0_CPU1_P2P2_DN<7>")
	)
	(segment
		(start 89.61247 -291.20719)
		(end 90.220546 -290.599114)
		(width 0.14732)
		(layer "In6.Cu")
		(net "UPI_CPU0_CPU1_P2P2_DN<7>")
	)
	(segment
		(start 350.58096 -283.705808)
		(end 350.576134 -283.708602)
		(width 0.0889)
		(layer "In6.Cu")
		(net "UPI_CPU0_CPU1_P2P2_DN<7>")
	)
	(segment
		(start 346.828872 -292.396672)
		(end 346.828872 -294.418004)
		(width 0.0889)
		(layer "In6.Cu")
		(net "UPI_CPU0_CPU1_P2P2_DN<7>")
	)
	(segment
		(start 95.020892 -281.916378)
		(end 95.031306 -281.910282)
		(width 0.0889)
		(layer "In6.Cu")
		(net "UPI_CPU0_CPU1_P2P2_DN<7>")
	)
	(segment
		(start 318.743584 -326.157336)
		(end 317.631318 -328.842878)
		(width 0.14732)
		(layer "In6.Cu")
		(net "UPI_CPU0_CPU1_P2P2_DN<7>")
	)
	(segment
		(start 62.274958 -335.248504)
		(end 61.251338 -331.164438)
		(width 0.14732)
		(layer "In6.Cu")
		(net "UPI_CPU0_CPU1_P2P2_DN<7>")
	)
	(segment
		(start 126.164848 -387.005068)
		(end 95.679768 -382.482852)
		(width 0.14732)
		(layer "In6.Cu")
		(net "UPI_CPU0_CPU1_P2P2_DN<7>")
	)
	(segment
		(start 348.695518 -288.592768)
		(end 348.686628 -288.597848)
		(width 0.0889)
		(layer "In6.Cu")
		(net "UPI_CPU0_CPU1_P2P2_DN<7>")
	)
	(segment
		(start 63.84925 -322.172838)
		(end 64.31915 -321.97802)
		(width 0.14732)
		(layer "In6.Cu")
		(net "UPI_CPU0_CPU1_P2P2_DN<7>")
	)
	(segment
		(start 93.798644 -284.033722)
		(end 93.798644 -284.023816)
		(width 0.0889)
		(layer "In6.Cu")
		(net "UPI_CPU0_CPU1_P2P2_DN<7>")
	)
	(segment
		(start 338.392008 -306.508912)
		(end 318.743584 -326.157336)
		(width 0.14732)
		(layer "In6.Cu")
		(net "UPI_CPU0_CPU1_P2P2_DN<7>")
	)
	(segment
		(start 90.979752 -288.89452)
		(end 90.979498 -288.895028)
		(width 0.0889)
		(layer "In6.Cu")
		(net "UPI_CPU0_CPU1_P2P2_DN<7>")
	)
	(segment
		(start 348.508066 -288.917126)
		(end 348.508066 -289.078416)
		(width 0.0889)
		(layer "In6.Cu")
		(net "UPI_CPU0_CPU1_P2P2_DN<7>")
	)
	(segment
		(start 92.671392 -285.985712)
		(end 92.672408 -285.985204)
		(width 0.0889)
		(layer "In6.Cu")
		(net "UPI_CPU0_CPU1_P2P2_DN<7>")
	)
	(segment
		(start 62.274958 -355.050344)
		(end 62.274958 -335.248504)
		(width 0.14732)
		(layer "In6.Cu")
		(net "UPI_CPU0_CPU1_P2P2_DN<7>")
	)
	(segment
		(start 349.635064 -285.336996)
		(end 349.628206 -285.340806)
		(width 0.0889)
		(layer "In6.Cu")
		(net "UPI_CPU0_CPU1_P2P2_DN<7>")
	)
	(segment
		(start 63.20028 -322.821808)
		(end 63.84925 -322.172838)
		(width 0.14732)
		(layer "In6.Cu")
		(net "UPI_CPU0_CPU1_P2P2_DN<7>")
	)
	(segment
		(start 90.220546 -290.599114)
		(end 90.23604 -290.58362)
		(width 0.0889)
		(layer "In6.Cu")
		(net "UPI_CPU0_CPU1_P2P2_DN<7>")
	)
	(segment
		(start 349.64116 -286.961326)
		(end 349.636334 -286.96412)
		(width 0.0889)
		(layer "In6.Cu")
		(net "UPI_CPU0_CPU1_P2P2_DN<7>")
	)
	(segment
		(start 62.032388 -324.688708)
		(end 62.70625 -324.014846)
		(width 0.14732)
		(layer "In6.Cu")
		(net "UPI_CPU0_CPU1_P2P2_DN<7>")
	)
	(segment
		(start 90.294968 -290.58362)
		(end 90.43416 -290.444428)
		(width 0.0889)
		(layer "In6.Cu")
		(net "UPI_CPU0_CPU1_P2P2_DN<7>")
	)
	(segment
		(start 349.628206 -285.340806)
		(end 349.626174 -285.342076)
		(width 0.0889)
		(layer "In6.Cu")
		(net "UPI_CPU0_CPU1_P2P2_DN<7>")
	)
	(segment
		(start 84.536788 -300.258734)
		(end 85.604858 -297.679618)
		(width 0.14732)
		(layer "In6.Cu")
		(net "UPI_CPU0_CPU1_P2P2_DN<7>")
	)
	(segment
		(start 349.635826 -285.336488)
		(end 349.635064 -285.336996)
		(width 0.0889)
		(layer "In6.Cu")
		(net "UPI_CPU0_CPU1_P2P2_DN<7>")
	)
	(segment
		(start 345.747848 -301.444914)
		(end 342.305386 -304.887376)
		(width 0.14732)
		(layer "In6.Cu")
		(net "UPI_CPU0_CPU1_P2P2_DN<7>")
	)
	(segment
		(start 349.634048 -286.965644)
		(end 349.626174 -286.970216)
		(width 0.0889)
		(layer "In6.Cu")
		(net "UPI_CPU0_CPU1_P2P2_DN<7>")
	)
	(segment
		(start 348.977712 -289.60953)
		(end 348.977712 -290.247832)
		(width 0.0889)
		(layer "In6.Cu")
		(net "UPI_CPU0_CPU1_P2P2_DN<7>")
	)
	(segment
		(start 350.38792 -282.39593)
		(end 350.387666 -282.405836)
		(width 0.0889)
		(layer "In6.Cu")
		(net "UPI_CPU0_CPU1_P2P2_DN<7>")
	)
	(segment
		(start 346.871036 -294.482266)
		(end 346.871036 -294.823134)
		(width 0.14732)
		(layer "In6.Cu")
		(net "UPI_CPU0_CPU1_P2P2_DN<7>")
	)
	(segment
		(start 65.528698 -319.917826)
		(end 66.006218 -319.20307)
		(width 0.14732)
		(layer "In6.Cu")
		(net "UPI_CPU0_CPU1_P2P2_DN<7>")
	)
	(segment
		(start 60.287408 -325.641208)
		(end 60.679584 -325.249032)
		(width 0.14732)
		(layer "In6.Cu")
		(net "UPI_CPU0_CPU1_P2P2_DN<7>")
	)
	(segment
		(start 350.105218 -284.52318)
		(end 350.096328 -284.52826)
		(width 0.0889)
		(layer "In6.Cu")
		(net "UPI_CPU0_CPU1_P2P2_DN<7>")
	)
	(segment
		(start 94.081092 -283.544264)
		(end 94.089982 -283.539184)
		(width 0.0889)
		(layer "In6.Cu")
		(net "UPI_CPU0_CPU1_P2P2_DN<7>")
	)
	(segment
		(start 350.136206 -281.862784)
		(end 350.160336 -281.952192)
		(width 0.0889)
		(layer "In6.Cu")
		(net "UPI_CPU0_CPU1_P2P2_DN<7>")
	)
	(segment
		(start 286.146748 -337.52028)
		(end 281.81554 -339.314282)
		(width 0.14732)
		(layer "In6.Cu")
		(net "UPI_CPU0_CPU1_P2P2_DN<7>")
	)
	(segment
		(start 91.919298 -287.28924)
		(end 91.919298 -287.279334)
		(width 0.0889)
		(layer "In6.Cu")
		(net "UPI_CPU0_CPU1_P2P2_DN<7>")
	)
	(segment
		(start 317.631318 -328.842878)
		(end 308.953916 -337.52028)
		(width 0.14732)
		(layer "In6.Cu")
		(net "UPI_CPU0_CPU1_P2P2_DN<7>")
	)
	(segment
		(start 346.870782 -298.432728)
		(end 346.717366 -299.183552)
		(width 0.14732)
		(layer "In6.Cu")
		(net "UPI_CPU0_CPU1_P2P2_DN<7>")
	)
	(segment
		(start 62.70625 -324.014846)
		(end 63.20028 -322.821808)
		(width 0.14732)
		(layer "In6.Cu")
		(net "UPI_CPU0_CPU1_P2P2_DN<7>")
	)
	(segment
		(start 95.52813 -281.886914)
		(end 95.617284 -281.863038)
		(width 0.0889)
		(layer "In6.Cu")
		(net "UPI_CPU0_CPU1_P2P2_DN<7>")
	)
	(segment
		(start 64.31915 -321.97802)
		(end 64.926972 -321.370198)
		(width 0.14732)
		(layer "In6.Cu")
		(net "UPI_CPU0_CPU1_P2P2_DN<7>")
	)
	(segment
		(start 350.387666 -282.405836)
		(end 350.387666 -282.414472)
		(width 0.0889)
		(layer "In6.Cu")
		(net "UPI_CPU0_CPU1_P2P2_DN<7>")
	)
	(segment
		(start 67.634104 -367.989358)
		(end 62.274958 -355.050344)
		(width 0.14732)
		(layer "In6.Cu")
		(net "UPI_CPU0_CPU1_P2P2_DN<7>")
	)
	(segment
		(start 266.769596 -378.047758)
		(end 161.221928 -387.005068)
		(width 0.14732)
		(layer "In6.Cu")
		(net "UPI_CPU0_CPU1_P2P2_DN<7>")
	)
	(segment
		(start 67.735196 -317.474092)
		(end 67.735196 -317.060326)
		(width 0.14732)
		(layer "In6.Cu")
		(net "UPI_CPU0_CPU1_P2P2_DN<7>")
	)
	(segment
		(start 346.871036 -294.460168)
		(end 346.871036 -294.482266)
		(width 0.0889)
		(layer "In6.Cu")
		(net "UPI_CPU0_CPU1_P2P2_DN<7>")
	)
	(segment
		(start 350.857566 -283.205682)
		(end 350.857566 -283.219906)
		(width 0.0889)
		(layer "In6.Cu")
		(net "UPI_CPU0_CPU1_P2P2_DN<7>")
	)
	(segment
		(start 91.719654 -287.62071)
		(end 91.728036 -287.615884)
		(width 0.0889)
		(layer "In6.Cu")
		(net "UPI_CPU0_CPU1_P2P2_DN<7>")
	)
	(segment
		(start 90.23604 -290.58362)
		(end 90.294968 -290.58362)
		(width 0.0889)
		(layer "In6.Cu")
		(net "UPI_CPU0_CPU1_P2P2_DN<7>")
	)
	(segment
		(start 92.389198 -286.475424)
		(end 92.389198 -286.453326)
		(width 0.0889)
		(layer "In6.Cu")
		(net "UPI_CPU0_CPU1_P2P2_DN<7>")
	)
	(segment
		(start 64.926972 -321.370198)
		(end 65.528698 -319.917826)
		(width 0.14732)
		(layer "In6.Cu")
		(net "UPI_CPU0_CPU1_P2P2_DN<7>")
	)
	(segment
		(start 93.328998 -284.847538)
		(end 93.328998 -284.832044)
		(width 0.0889)
		(layer "In6.Cu")
		(net "UPI_CPU0_CPU1_P2P2_DN<7>")
	)
	(segment
		(start 349.626174 -285.980632)
		(end 349.635064 -285.985712)
		(width 0.0889)
		(layer "In6.Cu")
		(net "UPI_CPU0_CPU1_P2P2_DN<7>")
	)
	(segment
		(start 346.828872 -294.418004)
		(end 346.871036 -294.460168)
		(width 0.0889)
		(layer "In6.Cu")
		(net "UPI_CPU0_CPU1_P2P2_DN<7>")
	)
	(segment
		(start 161.221928 -387.005068)
		(end 126.164848 -387.005068)
		(width 0.14732)
		(layer "In6.Cu")
		(net "UPI_CPU0_CPU1_P2P2_DN<7>")
	)
	(segment
		(start 349.917766 -286.4612)
		(end 349.917766 -286.475424)
		(width 0.0889)
		(layer "In6.Cu")
		(net "UPI_CPU0_CPU1_P2P2_DN<7>")
	)
	(segment
		(start 91.261692 -288.427414)
		(end 91.262708 -288.426906)
		(width 0.0889)
		(layer "In6.Cu")
		(net "UPI_CPU0_CPU1_P2P2_DN<7>")
	)
	(segment
		(start 60.05068 -328.9173)
		(end 60.05068 -326.212962)
		(width 0.14732)
		(layer "In6.Cu")
		(net "UPI_CPU0_CPU1_P2P2_DN<7>")
	)
	(segment
		(start 346.870782 -294.823388)
		(end 346.870782 -298.432728)
		(width 0.14732)
		(layer "In6.Cu")
		(net "UPI_CPU0_CPU1_P2P2_DN<7>")
	)
	(segment
		(start 61.251338 -331.164438)
		(end 60.05068 -328.9173)
		(width 0.14732)
		(layer "In6.Cu")
		(net "UPI_CPU0_CPU1_P2P2_DN<7>")
	)
	(segment
		(start 92.201746 -286.799782)
		(end 92.202508 -286.799274)
		(width 0.0889)
		(layer "In6.Cu")
		(net "UPI_CPU0_CPU1_P2P2_DN<7>")
	)
	(segment
		(start 60.679584 -325.249032)
		(end 62.032388 -324.688708)
		(width 0.14732)
		(layer "In6.Cu")
		(net "UPI_CPU0_CPU1_P2P2_DN<7>")
	)
	(segment
		(start 92.672408 -285.985204)
		(end 92.680282 -285.980632)
		(width 0.0889)
		(layer "In6.Cu")
		(net "UPI_CPU0_CPU1_P2P2_DN<7>")
	)
	(segment
		(start 349.636334 -286.96412)
		(end 349.634048 -286.965644)
		(width 0.0889)
		(layer "In6.Cu")
		(net "UPI_CPU0_CPU1_P2P2_DN<7>")
	)
	(segment
		(start 346.871036 -294.823134)
		(end 346.870782 -294.823388)
		(width 0.14732)
		(layer "In6.Cu")
		(net "UPI_CPU0_CPU1_P2P2_DN<7>")
	)
	(segment
		(start 349.626174 -286.970216)
		(end 349.626174 -286.969962)
		(width 0.0889)
		(layer "In6.Cu")
		(net "UPI_CPU0_CPU1_P2P2_DN<7>")
	)
	(segment
		(start 349.447612 -287.28924)
		(end 349.447612 -287.304734)
		(width 0.0889)
		(layer "In6.Cu")
		(net "UPI_CPU0_CPU1_P2P2_DN<7>")
	)
	(segment
		(start 89.61247 -292.102032)
		(end 89.61247 -291.20719)
		(width 0.14732)
		(layer "In6.Cu")
		(net "UPI_CPU0_CPU1_P2P2_DN<7>")
	)
	(segment
		(start 274.677632 -346.45219)
		(end 274.677632 -370.139722)
		(width 0.14732)
		(layer "In6.Cu")
		(net "UPI_CPU0_CPU1_P2P2_DN<7>")
	)
	(segment
		(start 308.953916 -337.52028)
		(end 286.146748 -337.52028)
		(width 0.14732)
		(layer "In6.Cu")
		(net "UPI_CPU0_CPU1_P2P2_DN<7>")
	)
	(segment
		(start 92.202508 -286.799274)
		(end 92.210636 -286.794702)
		(width 0.0889)
		(layer "In6.Cu")
		(net "UPI_CPU0_CPU1_P2P2_DN<7>")
	)
	(segment
		(start 72.54494 -372.900194)
		(end 67.634104 -367.989358)
		(width 0.14732)
		(layer "In6.Cu")
		(net "UPI_CPU0_CPU1_P2P2_DN<7>")
	)
	(segment
		(start 90.43416 -290.444428)
		(end 90.43416 -289.62731)
		(width 0.0889)
		(layer "In6.Cu")
		(net "UPI_CPU0_CPU1_P2P2_DN<7>")
	)
	(segment
		(start 94.268544 -283.219906)
		(end 94.268544 -283.205682)
		(width 0.0889)
		(layer "In6.Cu")
		(net "UPI_CPU0_CPU1_P2P2_DN<7>")
	)
	(segment
		(start 342.305386 -304.887376)
		(end 338.392008 -306.508912)
		(width 0.14732)
		(layer "In6.Cu")
		(net "UPI_CPU0_CPU1_P2P2_DN<7>")
	)
	(segment
		(start 94.738444 -282.414472)
		(end 94.738444 -282.39593)
		(width 0.0889)
		(layer "In6.Cu")
		(net "UPI_CPU0_CPU1_P2P2_DN<7>")
	)
	(segment
		(start 90.769948 -289.291522)
		(end 90.795348 -289.27806)
		(width 0.0889)
		(layer "In6.Cu")
		(net "UPI_CPU0_CPU1_P2P2_DN<7>")
	)
	(segment
		(start 85.604858 -297.679618)
		(end 86.714584 -294.999918)
		(width 0.14732)
		(layer "In6.Cu")
		(net "UPI_CPU0_CPU1_P2P2_DN<7>")
	)
	(segment
		(start 350.292416 -281.59202)
		(end 350.136206 -281.862784)
		(width 0.0889)
		(layer "In6.Cu")
		(net "UPI_CPU0_CPU1_P2P2_DN<7>")
	)
	(arc
		(start 94.738444 -282.39593)
		(mid 94.816555 -282.118981)
		(end 95.020892 -281.916378)
		(width 0.0889)
		(layer "In6.Cu")
		(net "UPI_CPU0_CPU1_P2P2_DN<7>")
	)
	(arc
		(start 90.979498 -288.895028)
		(mid 91.060409 -288.6249)
		(end 91.261692 -288.427414)
		(width 0.0889)
		(layer "In6.Cu")
		(net "UPI_CPU0_CPU1_P2P2_DN<7>")
	)
	(arc
		(start 348.977966 -288.121598)
		(mid 348.897804 -288.393787)
		(end 348.695518 -288.592768)
		(width 0.0889)
		(layer "In6.Cu")
		(net "UPI_CPU0_CPU1_P2P2_DN<7>")
	)
	(arc
		(start 349.917766 -286.475424)
		(mid 349.843775 -286.75499)
		(end 349.64116 -286.961326)
		(width 0.0889)
		(layer "In6.Cu")
		(net "UPI_CPU0_CPU1_P2P2_DN<7>")
	)
	(arc
		(start 93.150436 -285.166816)
		(mid 93.28135 -285.030456)
		(end 93.328998 -284.847538)
		(width 0.0889)
		(layer "In6.Cu")
		(net "UPI_CPU0_CPU1_P2P2_DN<7>")
	)
	(arc
		(start 93.620082 -284.353)
		(mid 93.750996 -284.21664)
		(end 93.798644 -284.033722)
		(width 0.0889)
		(layer "In6.Cu")
		(net "UPI_CPU0_CPU1_P2P2_DN<7>")
	)
	(arc
		(start 92.210636 -286.794702)
		(mid 92.34155 -286.658342)
		(end 92.389198 -286.475424)
		(width 0.0889)
		(layer "In6.Cu")
		(net "UPI_CPU0_CPU1_P2P2_DN<7>")
	)
	(arc
		(start 348.686628 -288.597848)
		(mid 348.555714 -288.734208)
		(end 348.508066 -288.917126)
		(width 0.0889)
		(layer "In6.Cu")
		(net "UPI_CPU0_CPU1_P2P2_DN<7>")
	)
	(arc
		(start 91.740736 -287.608518)
		(mid 91.87165 -287.472158)
		(end 91.919298 -287.28924)
		(width 0.0889)
		(layer "In6.Cu")
		(net "UPI_CPU0_CPU1_P2P2_DN<7>")
	)
	(arc
		(start 350.574864 -282.730194)
		(mid 350.778345 -282.930998)
		(end 350.857566 -283.205682)
		(width 0.0889)
		(layer "In6.Cu")
		(net "UPI_CPU0_CPU1_P2P2_DN<7>")
	)
	(arc
		(start 91.270582 -288.422334)
		(mid 91.401496 -288.285974)
		(end 91.449144 -288.103056)
		(width 0.0889)
		(layer "In6.Cu")
		(net "UPI_CPU0_CPU1_P2P2_DN<7>")
	)
	(arc
		(start 348.508066 -289.078416)
		(mid 348.583071 -289.193875)
		(end 348.692216 -289.277806)
		(width 0.0889)
		(layer "In6.Cu")
		(net "UPI_CPU0_CPU1_P2P2_DN<7>")
	)
	(arc
		(start 91.449144 -288.103056)
		(mid 91.521379 -287.826532)
		(end 91.719654 -287.62071)
		(width 0.0889)
		(layer "In6.Cu")
		(net "UPI_CPU0_CPU1_P2P2_DN<7>")
	)
	(arc
		(start 94.089982 -283.539184)
		(mid 94.220896 -283.402824)
		(end 94.268544 -283.219906)
		(width 0.0889)
		(layer "In6.Cu")
		(net "UPI_CPU0_CPU1_P2P2_DN<7>")
	)
	(arc
		(start 91.919298 -287.279334)
		(mid 91.997409 -287.002385)
		(end 92.201746 -286.799782)
		(width 0.0889)
		(layer "In6.Cu")
		(net "UPI_CPU0_CPU1_P2P2_DN<7>")
	)
	(arc
		(start 92.680282 -285.980632)
		(mid 92.807536 -285.850666)
		(end 92.85859 -285.676086)
		(width 0.0889)
		(layer "In6.Cu")
		(net "UPI_CPU0_CPU1_P2P2_DN<7>")
	)
	(arc
		(start 94.551246 -282.730194)
		(mid 94.686179 -282.59684)
		(end 94.738444 -282.414472)
		(width 0.0889)
		(layer "In6.Cu")
		(net "UPI_CPU0_CPU1_P2P2_DN<7>")
	)
	(arc
		(start 349.917766 -284.847538)
		(mid 349.843775 -285.127104)
		(end 349.64116 -285.33344)
		(width 0.0889)
		(layer "In6.Cu")
		(net "UPI_CPU0_CPU1_P2P2_DN<7>")
	)
	(arc
		(start 348.692216 -289.277806)
		(mid 348.866348 -289.416653)
		(end 348.977712 -289.60953)
		(width 0.0889)
		(layer "In6.Cu")
		(net "UPI_CPU0_CPU1_P2P2_DN<7>")
	)
	(arc
		(start 93.328998 -284.832044)
		(mid 93.408368 -284.55831)
		(end 93.611192 -284.35808)
		(width 0.0889)
		(layer "In6.Cu")
		(net "UPI_CPU0_CPU1_P2P2_DN<7>")
	)
	(arc
		(start 350.160336 -281.952192)
		(mid 350.325721 -282.147603)
		(end 350.38792 -282.39593)
		(width 0.0889)
		(layer "In6.Cu")
		(net "UPI_CPU0_CPU1_P2P2_DN<7>")
	)
	(arc
		(start 92.858844 -285.661354)
		(mid 92.932835 -285.381788)
		(end 93.13545 -285.175452)
		(width 0.0889)
		(layer "In6.Cu")
		(net "UPI_CPU0_CPU1_P2P2_DN<7>")
	)
	(arc
		(start 95.508064 -281.878786)
		(mid 95.518135 -281.882755)
		(end 95.52813 -281.886914)
		(width 0.0889)
		(layer "In6.Cu")
		(net "UPI_CPU0_CPU1_P2P2_DN<7>")
	)
	(arc
		(start 90.795348 -289.27806)
		(mid 90.904598 -289.194275)
		(end 90.979752 -289.078924)
		(width 0.0889)
		(layer "In6.Cu")
		(net "UPI_CPU0_CPU1_P2P2_DN<7>")
	)
	(arc
		(start 349.626174 -285.342076)
		(mid 349.447577 -285.661354)
		(end 349.626174 -285.980632)
		(width 0.0889)
		(layer "In6.Cu")
		(net "UPI_CPU0_CPU1_P2P2_DN<7>")
	)
	(arc
		(start 350.857566 -283.219906)
		(mid 350.783575 -283.499472)
		(end 350.58096 -283.705808)
		(width 0.0889)
		(layer "In6.Cu")
		(net "UPI_CPU0_CPU1_P2P2_DN<7>")
	)
	(arc
		(start 92.389198 -286.453326)
		(mid 92.470109 -286.183198)
		(end 92.671392 -285.985712)
		(width 0.0889)
		(layer "In6.Cu")
		(net "UPI_CPU0_CPU1_P2P2_DN<7>")
	)
	(arc
		(start 349.635064 -285.985712)
		(mid 349.838545 -286.186516)
		(end 349.917766 -286.4612)
		(width 0.0889)
		(layer "In6.Cu")
		(net "UPI_CPU0_CPU1_P2P2_DN<7>")
	)
	(arc
		(start 95.031306 -281.910282)
		(mid 95.266186 -281.841747)
		(end 95.508064 -281.878786)
		(width 0.0889)
		(layer "In6.Cu")
		(net "UPI_CPU0_CPU1_P2P2_DN<7>")
	)
	(arc
		(start 350.387412 -284.049216)
		(mid 350.308042 -284.32295)
		(end 350.105218 -284.52318)
		(width 0.0889)
		(layer "In6.Cu")
		(net "UPI_CPU0_CPU1_P2P2_DN<7>")
	)
	(arc
		(start 94.268544 -283.205682)
		(mid 94.347763 -282.930997)
		(end 94.551246 -282.730194)
		(width 0.0889)
		(layer "In6.Cu")
		(net "UPI_CPU0_CPU1_P2P2_DN<7>")
	)
	(arc
		(start 350.387666 -282.414472)
		(mid 350.439936 -282.596837)
		(end 350.574864 -282.730194)
		(width 0.0889)
		(layer "In6.Cu")
		(net "UPI_CPU0_CPU1_P2P2_DN<7>")
	)
	(arc
		(start 93.798644 -284.023816)
		(mid 93.876755 -283.746867)
		(end 94.081092 -283.544264)
		(width 0.0889)
		(layer "In6.Cu")
		(net "UPI_CPU0_CPU1_P2P2_DN<7>")
	)
	(arc
		(start 349.156528 -287.783778)
		(mid 349.025614 -287.920138)
		(end 348.977966 -288.103056)
		(width 0.0889)
		(layer "In6.Cu")
		(net "UPI_CPU0_CPU1_P2P2_DN<7>")
	)
	(arc
		(start 92.85859 -285.676086)
		(mid 92.858787 -285.668721)
		(end 92.858844 -285.661354)
		(width 0.0889)
		(layer "In6.Cu")
		(net "UPI_CPU0_CPU1_P2P2_DN<7>")
	)
	(arc
		(start 350.565974 -283.714444)
		(mid 350.43506 -283.850804)
		(end 350.387412 -284.033722)
		(width 0.0889)
		(layer "In6.Cu")
		(net "UPI_CPU0_CPU1_P2P2_DN<7>")
	)
	(arc
		(start 350.096328 -284.52826)
		(mid 349.965414 -284.66462)
		(end 349.917766 -284.847538)
		(width 0.0889)
		(layer "In6.Cu")
		(net "UPI_CPU0_CPU1_P2P2_DN<7>")
	)
	(arc
		(start 349.626174 -286.969962)
		(mid 349.49526 -287.106322)
		(end 349.447612 -287.28924)
		(width 0.0889)
		(layer "In6.Cu")
		(net "UPI_CPU0_CPU1_P2P2_DN<7>")
	)
	(arc
		(start 349.447612 -287.304734)
		(mid 349.368242 -287.578468)
		(end 349.165418 -287.778698)
		(width 0.0889)
		(layer "In6.Cu")
		(net "UPI_CPU0_CPU1_P2P2_DN<7>")
	)
	(segment
		(start 95.303848 -280.242264)
		(end 95.303848 -280.77795)
		(width 0.13208)
		(layer "F.Cu")
		(net "UPI_CPU0_CPU1_P2P2_DN<6>")
	)
	(segment
		(start 351.702116 -280.242264)
		(end 351.702116 -280.77795)
		(width 0.13208)
		(layer "F.Cu")
		(net "UPI_CPU0_CPU1_P2P2_DN<6>")
	)
	(segment
		(start 351.702116 -280.77795)
		(end 351.701862 -280.778204)
		(width 0.13208)
		(layer "F.Cu")
		(net "UPI_CPU0_CPU1_P2P2_DN<6>")
	)
	(segment
		(start 95.303848 -280.77795)
		(end 95.303594 -280.778204)
		(width 0.13208)
		(layer "F.Cu")
		(net "UPI_CPU0_CPU1_P2P2_DN<6>")
	)
	(segment
		(start 275.355812 -346.560902)
		(end 275.355812 -367.685828)
		(width 0.14732)
		(layer "In6.Cu")
		(net "UPI_CPU0_CPU1_P2P2_DN<6>")
	)
	(segment
		(start 59.4868 -329.065128)
		(end 59.4868 -325.874126)
		(width 0.14732)
		(layer "In6.Cu")
		(net "UPI_CPU0_CPU1_P2P2_DN<6>")
	)
	(segment
		(start 349.257366 -288.898584)
		(end 349.257366 -289.114738)
		(width 0.0889)
		(layer "In6.Cu")
		(net "UPI_CPU0_CPU1_P2P2_DN<6>")
	)
	(segment
		(start 342.622886 -305.35753)
		(end 338.709 -306.978812)
		(width 0.14732)
		(layer "In6.Cu")
		(net "UPI_CPU0_CPU1_P2P2_DN<6>")
	)
	(segment
		(start 351.419922 -281.91587)
		(end 351.41916 -281.916378)
		(width 0.0889)
		(layer "In6.Cu")
		(net "UPI_CPU0_CPU1_P2P2_DN<6>")
	)
	(segment
		(start 350.01835 -287.608518)
		(end 350.00946 -287.613598)
		(width 0.0889)
		(layer "In6.Cu")
		(net "UPI_CPU0_CPU1_P2P2_DN<6>")
	)
	(segment
		(start 60.44565 -331.147674)
		(end 60.258198 -331.064616)
		(width 0.14732)
		(layer "In6.Cu")
		(net "UPI_CPU0_CPU1_P2P2_DN<6>")
	)
	(segment
		(start 266.999466 -378.67209)
		(end 161.749486 -387.558788)
		(width 0.14732)
		(layer "In6.Cu")
		(net "UPI_CPU0_CPU1_P2P2_DN<6>")
	)
	(segment
		(start 72.22998 -373.371618)
		(end 67.15887 -368.300508)
		(width 0.14732)
		(layer "In6.Cu")
		(net "UPI_CPU0_CPU1_P2P2_DN<6>")
	)
	(segment
		(start 275.355812 -370.315744)
		(end 266.999466 -378.67209)
		(width 0.14732)
		(layer "In6.Cu")
		(net "UPI_CPU0_CPU1_P2P2_DN<6>")
	)
	(segment
		(start 350.196912 -285.661354)
		(end 350.196912 -285.679896)
		(width 0.0889)
		(layer "In6.Cu")
		(net "UPI_CPU0_CPU1_P2P2_DN<6>")
	)
	(segment
		(start 78.760828 -305.075082)
		(end 78.93304 -305.075082)
		(width 0.14732)
		(layer "In6.Cu")
		(net "UPI_CPU0_CPU1_P2P2_DN<6>")
	)
	(segment
		(start 91.34856 -286.969962)
		(end 91.35745 -286.964882)
		(width 0.0889)
		(layer "In6.Cu")
		(net "UPI_CPU0_CPU1_P2P2_DN<6>")
	)
	(segment
		(start 350.473264 -285.175706)
		(end 350.473518 -285.175452)
		(width 0.0889)
		(layer "In6.Cu")
		(net "UPI_CPU0_CPU1_P2P2_DN<6>")
	)
	(segment
		(start 338.709 -306.978812)
		(end 319.279524 -326.408288)
		(width 0.14732)
		(layer "In6.Cu")
		(net "UPI_CPU0_CPU1_P2P2_DN<6>")
	)
	(segment
		(start 78.451964 -305.556412)
		(end 78.451964 -305.383946)
		(width 0.14732)
		(layer "In6.Cu")
		(net "UPI_CPU0_CPU1_P2P2_DN<6>")
	)
	(segment
		(start 67.15887 -368.300508)
		(end 61.718698 -355.16693)
		(width 0.14732)
		(layer "In6.Cu")
		(net "UPI_CPU0_CPU1_P2P2_DN<6>")
	)
	(segment
		(start 60.726828 -332.279752)
		(end 60.49518 -331.678788)
		(width 0.14732)
		(layer "In6.Cu")
		(net "UPI_CPU0_CPU1_P2P2_DN<6>")
	)
	(segment
		(start 79.723488 -304.284634)
		(end 80.032606 -303.975516)
		(width 0.14732)
		(layer "In6.Cu")
		(net "UPI_CPU0_CPU1_P2P2_DN<6>")
	)
	(segment
		(start 80.032606 -303.80305)
		(end 80.409542 -303.426114)
		(width 0.14732)
		(layer "In6.Cu")
		(net "UPI_CPU0_CPU1_P2P2_DN<6>")
	)
	(segment
		(start 78.93304 -305.075082)
		(end 79.242158 -304.765964)
		(width 0.14732)
		(layer "In6.Cu")
		(net "UPI_CPU0_CPU1_P2P2_DN<6>")
	)
	(segment
		(start 82.484722 -301.522638)
		(end 82.484722 -301.350426)
		(width 0.14732)
		(layer "In6.Cu")
		(net "UPI_CPU0_CPU1_P2P2_DN<6>")
	)
	(segment
		(start 95.490792 -280.453846)
		(end 95.499682 -280.458926)
		(width 0.0889)
		(layer "In6.Cu")
		(net "UPI_CPU0_CPU1_P2P2_DN<6>")
	)
	(segment
		(start 61.547502 -324.261226)
		(end 61.966094 -323.842634)
		(width 0.14732)
		(layer "In6.Cu")
		(net "UPI_CPU0_CPU1_P2P2_DN<6>")
	)
	(segment
		(start 350.47936 -286.151066)
		(end 350.48825 -286.156146)
		(width 0.0889)
		(layer "In6.Cu")
		(net "UPI_CPU0_CPU1_P2P2_DN<6>")
	)
	(segment
		(start 59.888628 -330.10729)
		(end 59.4868 -329.065128)
		(width 0.14732)
		(layer "In6.Cu")
		(net "UPI_CPU0_CPU1_P2P2_DN<6>")
	)
	(segment
		(start 318.165226 -329.098402)
		(end 309.187088 -338.07654)
		(width 0.14732)
		(layer "In6.Cu")
		(net "UPI_CPU0_CPU1_P2P2_DN<6>")
	)
	(segment
		(start 79.242158 -304.593498)
		(end 79.551022 -304.284634)
		(width 0.14732)
		(layer "In6.Cu")
		(net "UPI_CPU0_CPU1_P2P2_DN<6>")
	)
	(segment
		(start 80.409542 -303.426114)
		(end 80.582008 -303.426114)
		(width 0.14732)
		(layer "In6.Cu")
		(net "UPI_CPU0_CPU1_P2P2_DN<6>")
	)
	(segment
		(start 67.024504 -316.813438)
		(end 77.97038 -305.86553)
		(width 0.14732)
		(layer "In6.Cu")
		(net "UPI_CPU0_CPU1_P2P2_DN<6>")
	)
	(segment
		(start 351.606612 -281.5844)
		(end 351.606612 -281.59202)
		(width 0.0889)
		(layer "In6.Cu")
		(net "UPI_CPU0_CPU1_P2P2_DN<6>")
	)
	(segment
		(start 61.046868 -332.706472)
		(end 60.91428 -332.362556)
		(width 0.14732)
		(layer "In6.Cu")
		(net "UPI_CPU0_CPU1_P2P2_DN<6>")
	)
	(segment
		(start 80.582008 -303.426114)
		(end 80.891126 -303.116742)
		(width 0.14732)
		(layer "In6.Cu")
		(net "UPI_CPU0_CPU1_P2P2_DN<6>")
	)
	(segment
		(start 62.74943 -321.281552)
		(end 63.041784 -320.989198)
		(width 0.14732)
		(layer "In6.Cu")
		(net "UPI_CPU0_CPU1_P2P2_DN<6>")
	)
	(segment
		(start 82.003138 -301.83201)
		(end 82.175604 -301.83201)
		(width 0.14732)
		(layer "In6.Cu")
		(net "UPI_CPU0_CPU1_P2P2_DN<6>")
	)
	(segment
		(start 60.376562 -324.746366)
		(end 61.547502 -324.261226)
		(width 0.14732)
		(layer "In6.Cu")
		(net "UPI_CPU0_CPU1_P2P2_DN<6>")
	)
	(segment
		(start 349.727266 -290.22929)
		(end 347.475048 -292.481508)
		(width 0.0889)
		(layer "In6.Cu")
		(net "UPI_CPU0_CPU1_P2P2_DN<6>")
	)
	(segment
		(start 79.551022 -304.284634)
		(end 79.723488 -304.284634)
		(width 0.14732)
		(layer "In6.Cu")
		(net "UPI_CPU0_CPU1_P2P2_DN<6>")
	)
	(segment
		(start 82.890614 -300.94428)
		(end 83.06308 -300.944026)
		(width 0.14732)
		(layer "In6.Cu")
		(net "UPI_CPU0_CPU1_P2P2_DN<6>")
	)
	(segment
		(start 351.42805 -281.911298)
		(end 351.419922 -281.91587)
		(width 0.0889)
		(layer "In6.Cu")
		(net "UPI_CPU0_CPU1_P2P2_DN<6>")
	)
	(segment
		(start 275.233892 -368.244628)
		(end 275.355812 -368.366548)
		(width 0.14732)
		(layer "In6.Cu")
		(net "UPI_CPU0_CPU1_P2P2_DN<6>")
	)
	(segment
		(start 94.652846 -281.263852)
		(end 94.652592 -281.264106)
		(width 0.0889)
		(layer "In6.Cu")
		(net "UPI_CPU0_CPU1_P2P2_DN<6>")
	)
	(segment
		(start 91.639898 -286.475424)
		(end 91.639898 -286.4612)
		(width 0.0889)
		(layer "In6.Cu")
		(net "UPI_CPU0_CPU1_P2P2_DN<6>")
	)
	(segment
		(start 94.16796 -282.086558)
		(end 94.17685 -282.081478)
		(width 0.0889)
		(layer "In6.Cu")
		(net "UPI_CPU0_CPU1_P2P2_DN<6>")
	)
	(segment
		(start 90.40876 -288.597848)
		(end 90.41765 -288.592768)
		(width 0.0889)
		(layer "In6.Cu")
		(net "UPI_CPU0_CPU1_P2P2_DN<6>")
	)
	(segment
		(start 60.96381 -332.89367)
		(end 61.046868 -332.706472)
		(width 0.14732)
		(layer "In6.Cu")
		(net "UPI_CPU0_CPU1_P2P2_DN<6>")
	)
	(segment
		(start 91.818206 -284.52826)
		(end 91.827096 -284.52318)
		(width 0.0889)
		(layer "In6.Cu")
		(net "UPI_CPU0_CPU1_P2P2_DN<6>")
	)
	(segment
		(start 91.639644 -284.863032)
		(end 91.639644 -284.847538)
		(width 0.0889)
		(layer "In6.Cu")
		(net "UPI_CPU0_CPU1_P2P2_DN<6>")
	)
	(segment
		(start 95.673672 -280.7208)
		(end 95.616268 -280.778204)
		(width 0.0889)
		(layer "In6.Cu")
		(net "UPI_CPU0_CPU1_P2P2_DN<6>")
	)
	(segment
		(start 60.91428 -332.362556)
		(end 60.726828 -332.279752)
		(width 0.14732)
		(layer "In6.Cu")
		(net "UPI_CPU0_CPU1_P2P2_DN<6>")
	)
	(segment
		(start 309.187088 -338.07654)
		(end 286.252666 -338.07654)
		(width 0.14732)
		(layer "In6.Cu")
		(net "UPI_CPU0_CPU1_P2P2_DN<6>")
	)
	(segment
		(start 80.891126 -302.94453)
		(end 81.212944 -302.622458)
		(width 0.14732)
		(layer "In6.Cu")
		(net "UPI_CPU0_CPU1_P2P2_DN<6>")
	)
	(segment
		(start 275.355812 -368.803428)
		(end 275.233892 -368.925348)
		(width 0.14732)
		(layer "In6.Cu")
		(net "UPI_CPU0_CPU1_P2P2_DN<6>")
	)
	(segment
		(start 275.355812 -367.685828)
		(end 275.233892 -367.807748)
		(width 0.14732)
		(layer "In6.Cu")
		(net "UPI_CPU0_CPU1_P2P2_DN<6>")
	)
	(segment
		(start 275.355812 -369.484148)
		(end 275.355812 -370.315744)
		(width 0.14732)
		(layer "In6.Cu")
		(net "UPI_CPU0_CPU1_P2P2_DN<6>")
	)
	(segment
		(start 81.385156 -302.622458)
		(end 81.694274 -302.31334)
		(width 0.14732)
		(layer "In6.Cu")
		(net "UPI_CPU0_CPU1_P2P2_DN<6>")
	)
	(segment
		(start 90.887296 -287.778698)
		(end 90.893392 -287.775142)
		(width 0.0889)
		(layer "In6.Cu")
		(net "UPI_CPU0_CPU1_P2P2_DN<6>")
	)
	(segment
		(start 349.540576 -288.426906)
		(end 349.539814 -288.427414)
		(width 0.0889)
		(layer "In6.Cu")
		(net "UPI_CPU0_CPU1_P2P2_DN<6>")
	)
	(segment
		(start 275.233892 -368.925348)
		(end 275.233892 -369.362228)
		(width 0.14732)
		(layer "In6.Cu")
		(net "UPI_CPU0_CPU1_P2P2_DN<6>")
	)
	(segment
		(start 350.95815 -284.353)
		(end 350.94926 -284.35808)
		(width 0.0889)
		(layer "In6.Cu")
		(net "UPI_CPU0_CPU1_P2P2_DN<6>")
	)
	(segment
		(start 60.125864 -330.721208)
		(end 60.208668 -330.53401)
		(width 0.14732)
		(layer "In6.Cu")
		(net "UPI_CPU0_CPU1_P2P2_DN<6>")
	)
	(segment
		(start 89.016586 -290.732718)
		(end 89.016586 -290.597082)
		(width 0.0889)
		(layer "In6.Cu")
		(net "UPI_CPU0_CPU1_P2P2_DN<6>")
	)
	(segment
		(start 83.372198 -300.634908)
		(end 83.372198 -300.462442)
		(width 0.14732)
		(layer "In6.Cu")
		(net "UPI_CPU0_CPU1_P2P2_DN<6>")
	)
	(segment
		(start 95.616268 -280.778204)
		(end 95.303594 -280.778204)
		(width 0.0889)
		(layer "In6.Cu")
		(net "UPI_CPU0_CPU1_P2P2_DN<6>")
	)
	(segment
		(start 161.749486 -387.558788)
		(end 126.121414 -387.558788)
		(width 0.14732)
		(layer "In6.Cu")
		(net "UPI_CPU0_CPU1_P2P2_DN<6>")
	)
	(segment
		(start 78.142846 -305.86553)
		(end 78.451964 -305.556412)
		(width 0.14732)
		(layer "In6.Cu")
		(net "UPI_CPU0_CPU1_P2P2_DN<6>")
	)
	(segment
		(start 79.242158 -304.765964)
		(end 79.242158 -304.593498)
		(width 0.14732)
		(layer "In6.Cu")
		(net "UPI_CPU0_CPU1_P2P2_DN<6>")
	)
	(segment
		(start 64.4144 -320.010282)
		(end 67.024504 -317.399162)
		(width 0.14732)
		(layer "In6.Cu")
		(net "UPI_CPU0_CPU1_P2P2_DN<6>")
	)
	(segment
		(start 349.542862 -289.446462)
		(end 349.727266 -289.630866)
		(width 0.0889)
		(layer "In6.Cu")
		(net "UPI_CPU0_CPU1_P2P2_DN<6>")
	)
	(segment
		(start 347.475048 -294.179498)
		(end 347.433138 -294.221408)
		(width 0.0889)
		(layer "In6.Cu")
		(net "UPI_CPU0_CPU1_P2P2_DN<6>")
	)
	(segment
		(start 351.42805 -283.539184)
		(end 351.419922 -283.543756)
		(width 0.0889)
		(layer "In6.Cu")
		(net "UPI_CPU0_CPU1_P2P2_DN<6>")
	)
	(segment
		(start 59.4868 -325.874126)
		(end 59.655202 -325.467726)
		(width 0.14732)
		(layer "In6.Cu")
		(net "UPI_CPU0_CPU1_P2P2_DN<6>")
	)
	(segment
		(start 351.136712 -282.39593)
		(end 351.136712 -282.424378)
		(width 0.0889)
		(layer "In6.Cu")
		(net "UPI_CPU0_CPU1_P2P2_DN<6>")
	)
	(segment
		(start 60.208668 -330.53401)
		(end 60.07608 -330.190348)
		(width 0.14732)
		(layer "In6.Cu")
		(net "UPI_CPU0_CPU1_P2P2_DN<6>")
	)
	(segment
		(start 89.016586 -290.597082)
		(end 90.22969 -289.383978)
		(width 0.0889)
		(layer "In6.Cu")
		(net "UPI_CPU0_CPU1_P2P2_DN<6>")
	)
	(segment
		(start 63.041784 -320.989198)
		(end 64.208914 -320.505836)
		(width 0.14732)
		(layer "In6.Cu")
		(net "UPI_CPU0_CPU1_P2P2_DN<6>")
	)
	(segment
		(start 61.718698 -355.16693)
		(end 61.718698 -335.482946)
		(width 0.14732)
		(layer "In6.Cu")
		(net "UPI_CPU0_CPU1_P2P2_DN<6>")
	)
	(segment
		(start 95.52305 -383.019808)
		(end 72.22998 -373.371618)
		(width 0.14732)
		(layer "In6.Cu")
		(net "UPI_CPU0_CPU1_P2P2_DN<6>")
	)
	(segment
		(start 83.06308 -300.944026)
		(end 83.372198 -300.634908)
		(width 0.14732)
		(layer "In6.Cu")
		(net "UPI_CPU0_CPU1_P2P2_DN<6>")
	)
	(segment
		(start 64.208914 -320.505836)
		(end 64.4144 -320.010282)
		(width 0.14732)
		(layer "In6.Cu")
		(net "UPI_CPU0_CPU1_P2P2_DN<6>")
	)
	(segment
		(start 351.701862 -280.778204)
		(end 351.85858 -281.048968)
		(width 0.0889)
		(layer "In6.Cu")
		(net "UPI_CPU0_CPU1_P2P2_DN<6>")
	)
	(segment
		(start 351.136712 -284.023816)
		(end 351.136712 -284.033722)
		(width 0.0889)
		(layer "In6.Cu")
		(net "UPI_CPU0_CPU1_P2P2_DN<6>")
	)
	(segment
		(start 351.419922 -283.543756)
		(end 351.41916 -283.544264)
		(width 0.0889)
		(layer "In6.Cu")
		(net "UPI_CPU0_CPU1_P2P2_DN<6>")
	)
	(segment
		(start 350.196912 -287.279334)
		(end 350.196912 -287.28924)
		(width 0.0889)
		(layer "In6.Cu")
		(net "UPI_CPU0_CPU1_P2P2_DN<6>")
	)
	(segment
		(start 61.718698 -335.482946)
		(end 61.267086 -333.680054)
		(width 0.14732)
		(layer "In6.Cu")
		(net "UPI_CPU0_CPU1_P2P2_DN<6>")
	)
	(segment
		(start 319.279524 -326.408288)
		(end 318.165226 -329.098402)
		(width 0.14732)
		(layer "In6.Cu")
		(net "UPI_CPU0_CPU1_P2P2_DN<6>")
	)
	(segment
		(start 67.024504 -317.399162)
		(end 67.024504 -316.813438)
		(width 0.14732)
		(layer "In6.Cu")
		(net "UPI_CPU0_CPU1_P2P2_DN<6>")
	)
	(segment
		(start 351.41916 -282.895548)
		(end 351.42805 -282.900628)
		(width 0.0889)
		(layer "In6.Cu")
		(net "UPI_CPU0_CPU1_P2P2_DN<6>")
	)
	(segment
		(start 92.579444 -283.229812)
		(end 92.579444 -283.219906)
		(width 0.0889)
		(layer "In6.Cu")
		(net "UPI_CPU0_CPU1_P2P2_DN<6>")
	)
	(segment
		(start 350.667066 -284.832044)
		(end 350.667066 -284.847538)
		(width 0.0889)
		(layer "In6.Cu")
		(net "UPI_CPU0_CPU1_P2P2_DN<6>")
	)
	(segment
		(start 89.05875 -290.79698)
		(end 89.05875 -290.774882)
		(width 0.0889)
		(layer "In6.Cu")
		(net "UPI_CPU0_CPU1_P2P2_DN<6>")
	)
	(segment
		(start 80.032606 -303.975516)
		(end 80.032606 -303.80305)
		(width 0.14732)
		(layer "In6.Cu")
		(net "UPI_CPU0_CPU1_P2P2_DN<6>")
	)
	(segment
		(start 89.05875 -290.774882)
		(end 89.016586 -290.732718)
		(width 0.0889)
		(layer "In6.Cu")
		(net "UPI_CPU0_CPU1_P2P2_DN<6>")
	)
	(segment
		(start 62.493144 -322.570348)
		(end 62.74943 -321.281552)
		(width 0.14732)
		(layer "In6.Cu")
		(net "UPI_CPU0_CPU1_P2P2_DN<6>")
	)
	(segment
		(start 92.109544 -284.043628)
		(end 92.109544 -284.033722)
		(width 0.0889)
		(layer "In6.Cu")
		(net "UPI_CPU0_CPU1_P2P2_DN<6>")
	)
	(segment
		(start 60.258198 -331.064616)
		(end 60.125864 -330.721208)
		(width 0.14732)
		(layer "In6.Cu")
		(net "UPI_CPU0_CPU1_P2P2_DN<6>")
	)
	(segment
		(start 286.252666 -338.07654)
		(end 282.134564 -339.78215)
		(width 0.14732)
		(layer "In6.Cu")
		(net "UPI_CPU0_CPU1_P2P2_DN<6>")
	)
	(segment
		(start 275.233892 -367.807748)
		(end 275.233892 -368.244628)
		(width 0.14732)
		(layer "In6.Cu")
		(net "UPI_CPU0_CPU1_P2P2_DN<6>")
	)
	(segment
		(start 89.05875 -291.870892)
		(end 89.05875 -290.79698)
		(width 0.14732)
		(layer "In6.Cu")
		(net "UPI_CPU0_CPU1_P2P2_DN<6>")
	)
	(segment
		(start 351.85858 -281.048968)
		(end 351.83445 -281.138122)
		(width 0.0889)
		(layer "In6.Cu")
		(net "UPI_CPU0_CPU1_P2P2_DN<6>")
	)
	(segment
		(start 94.637606 -281.272742)
		(end 94.652846 -281.263852)
		(width 0.0889)
		(layer "In6.Cu")
		(net "UPI_CPU0_CPU1_P2P2_DN<6>")
	)
	(segment
		(start 92.758006 -282.900628)
		(end 92.766896 -282.895548)
		(width 0.0889)
		(layer "In6.Cu")
		(net "UPI_CPU0_CPU1_P2P2_DN<6>")
	)
	(segment
		(start 90.699844 -288.125154)
		(end 90.699844 -288.103056)
		(width 0.0889)
		(layer "In6.Cu")
		(net "UPI_CPU0_CPU1_P2P2_DN<6>")
	)
	(segment
		(start 350.488504 -285.166816)
		(end 350.473264 -285.175706)
		(width 0.0889)
		(layer "In6.Cu")
		(net "UPI_CPU0_CPU1_P2P2_DN<6>")
	)
	(segment
		(start 80.891126 -303.116742)
		(end 80.891126 -302.94453)
		(width 0.14732)
		(layer "In6.Cu")
		(net "UPI_CPU0_CPU1_P2P2_DN<6>")
	)
	(segment
		(start 81.694274 -302.140874)
		(end 82.003138 -301.83201)
		(width 0.14732)
		(layer "In6.Cu")
		(net "UPI_CPU0_CPU1_P2P2_DN<6>")
	)
	(segment
		(start 275.233892 -369.362228)
		(end 275.355812 -369.484148)
		(width 0.14732)
		(layer "In6.Cu")
		(net "UPI_CPU0_CPU1_P2P2_DN<6>")
	)
	(segment
		(start 86.225888 -294.703754)
		(end 89.05875 -291.870892)
		(width 0.14732)
		(layer "In6.Cu")
		(net "UPI_CPU0_CPU1_P2P2_DN<6>")
	)
	(segment
		(start 90.22969 -288.917634)
		(end 90.230198 -288.917126)
		(width 0.0889)
		(layer "In6.Cu")
		(net "UPI_CPU0_CPU1_P2P2_DN<6>")
	)
	(segment
		(start 92.288106 -283.714444)
		(end 92.296996 -283.709364)
		(width 0.0889)
		(layer "In6.Cu")
		(net "UPI_CPU0_CPU1_P2P2_DN<6>")
	)
	(segment
		(start 275.355812 -368.366548)
		(end 275.355812 -368.803428)
		(width 0.14732)
		(layer "In6.Cu")
		(net "UPI_CPU0_CPU1_P2P2_DN<6>")
	)
	(segment
		(start 77.97038 -305.86553)
		(end 78.142846 -305.86553)
		(width 0.14732)
		(layer "In6.Cu")
		(net "UPI_CPU0_CPU1_P2P2_DN<6>")
	)
	(segment
		(start 126.121414 -387.558788)
		(end 95.52305 -383.019808)
		(width 0.14732)
		(layer "In6.Cu")
		(net "UPI_CPU0_CPU1_P2P2_DN<6>")
	)
	(segment
		(start 349.727266 -289.630866)
		(end 349.727266 -290.22929)
		(width 0.0889)
		(layer "In6.Cu")
		(net "UPI_CPU0_CPU1_P2P2_DN<6>")
	)
	(segment
		(start 350.48825 -286.794702)
		(end 350.480122 -286.799274)
		(width 0.0889)
		(layer "In6.Cu")
		(net "UPI_CPU0_CPU1_P2P2_DN<6>")
	)
	(segment
		(start 347.475048 -292.481508)
		(end 347.475048 -294.179498)
		(width 0.0889)
		(layer "In6.Cu")
		(net "UPI_CPU0_CPU1_P2P2_DN<6>")
	)
	(segment
		(start 60.578238 -331.49159)
		(end 60.44565 -331.147674)
		(width 0.14732)
		(layer "In6.Cu")
		(net "UPI_CPU0_CPU1_P2P2_DN<6>")
	)
	(segment
		(start 82.175604 -301.83201)
		(end 82.484722 -301.522638)
		(width 0.14732)
		(layer "In6.Cu")
		(net "UPI_CPU0_CPU1_P2P2_DN<6>")
	)
	(segment
		(start 81.212944 -302.622458)
		(end 81.385156 -302.622458)
		(width 0.14732)
		(layer "In6.Cu")
		(net "UPI_CPU0_CPU1_P2P2_DN<6>")
	)
	(segment
		(start 91.35745 -285.985712)
		(end 91.34856 -285.980632)
		(width 0.0889)
		(layer "In6.Cu")
		(net "UPI_CPU0_CPU1_P2P2_DN<6>")
	)
	(segment
		(start 60.49518 -331.678788)
		(end 60.578238 -331.49159)
		(width 0.14732)
		(layer "In6.Cu")
		(net "UPI_CPU0_CPU1_P2P2_DN<6>")
	)
	(segment
		(start 60.07608 -330.190348)
		(end 59.888628 -330.10729)
		(width 0.14732)
		(layer "In6.Cu")
		(net "UPI_CPU0_CPU1_P2P2_DN<6>")
	)
	(segment
		(start 347.433138 -294.432482)
		(end 347.432884 -294.432736)
		(width 0.14732)
		(layer "In6.Cu")
		(net "UPI_CPU0_CPU1_P2P2_DN<6>")
	)
	(segment
		(start 84.172298 -299.662342)
		(end 86.225888 -294.703754)
		(width 0.14732)
		(layer "In6.Cu")
		(net "UPI_CPU0_CPU1_P2P2_DN<6>")
	)
	(segment
		(start 350.480122 -286.799274)
		(end 350.47936 -286.799782)
		(width 0.0889)
		(layer "In6.Cu")
		(net "UPI_CPU0_CPU1_P2P2_DN<6>")
	)
	(segment
		(start 347.432884 -294.432736)
		(end 347.432884 -298.986448)
		(width 0.14732)
		(layer "In6.Cu")
		(net "UPI_CPU0_CPU1_P2P2_DN<6>")
	)
	(segment
		(start 349.548704 -288.422334)
		(end 349.540576 -288.426906)
		(width 0.0889)
		(layer "In6.Cu")
		(net "UPI_CPU0_CPU1_P2P2_DN<6>")
	)
	(segment
		(start 93.989398 -282.42006)
		(end 93.989398 -282.405836)
		(width 0.0889)
		(layer "In6.Cu")
		(net "UPI_CPU0_CPU1_P2P2_DN<6>")
	)
	(segment
		(start 90.878406 -287.783778)
		(end 90.887296 -287.778698)
		(width 0.0889)
		(layer "In6.Cu")
		(net "UPI_CPU0_CPU1_P2P2_DN<6>")
	)
	(segment
		(start 282.134564 -339.78215)
		(end 275.355812 -346.560902)
		(width 0.14732)
		(layer "In6.Cu")
		(net "UPI_CPU0_CPU1_P2P2_DN<6>")
	)
	(segment
		(start 94.459044 -281.607514)
		(end 94.459044 -281.59202)
		(width 0.0889)
		(layer "In6.Cu")
		(net "UPI_CPU0_CPU1_P2P2_DN<6>")
	)
	(segment
		(start 61.267086 -333.680054)
		(end 60.96381 -332.89367)
		(width 0.14732)
		(layer "In6.Cu")
		(net "UPI_CPU0_CPU1_P2P2_DN<6>")
	)
	(segment
		(start 94.929198 -280.778204)
		(end 94.929198 -280.769568)
		(width 0.0889)
		(layer "In6.Cu")
		(net "UPI_CPU0_CPU1_P2P2_DN<6>")
	)
	(segment
		(start 62.466474 -322.63461)
		(end 62.493144 -322.570348)
		(width 0.14732)
		(layer "In6.Cu")
		(net "UPI_CPU0_CPU1_P2P2_DN<6>")
	)
	(segment
		(start 91.34856 -285.342076)
		(end 91.35745 -285.336996)
		(width 0.0889)
		(layer "In6.Cu")
		(net "UPI_CPU0_CPU1_P2P2_DN<6>")
	)
	(segment
		(start 349.727266 -288.087562)
		(end 349.727266 -288.103056)
		(width 0.0889)
		(layer "In6.Cu")
		(net "UPI_CPU0_CPU1_P2P2_DN<6>")
	)
	(segment
		(start 81.694274 -302.31334)
		(end 81.694274 -302.140874)
		(width 0.14732)
		(layer "In6.Cu")
		(net "UPI_CPU0_CPU1_P2P2_DN<6>")
	)
	(segment
		(start 93.691964 -282.904184)
		(end 93.706696 -282.895548)
		(width 0.0889)
		(layer "In6.Cu")
		(net "UPI_CPU0_CPU1_P2P2_DN<6>")
	)
	(segment
		(start 59.655202 -325.467726)
		(end 60.376562 -324.746366)
		(width 0.14732)
		(layer "In6.Cu")
		(net "UPI_CPU0_CPU1_P2P2_DN<6>")
	)
	(segment
		(start 82.484722 -301.350426)
		(end 82.890614 -300.94428)
		(width 0.14732)
		(layer "In6.Cu")
		(net "UPI_CPU0_CPU1_P2P2_DN<6>")
	)
	(segment
		(start 61.966094 -323.842634)
		(end 62.466474 -322.63461)
		(width 0.14732)
		(layer "In6.Cu")
		(net "UPI_CPU0_CPU1_P2P2_DN<6>")
	)
	(segment
		(start 347.433138 -294.221408)
		(end 347.433138 -294.243506)
		(width 0.0889)
		(layer "In6.Cu")
		(net "UPI_CPU0_CPU1_P2P2_DN<6>")
	)
	(segment
		(start 91.35745 -286.964882)
		(end 91.363546 -286.961326)
		(width 0.0889)
		(layer "In6.Cu")
		(net "UPI_CPU0_CPU1_P2P2_DN<6>")
	)
	(segment
		(start 347.433138 -294.243506)
		(end 347.433138 -294.432482)
		(width 0.14732)
		(layer "In6.Cu")
		(net "UPI_CPU0_CPU1_P2P2_DN<6>")
	)
	(segment
		(start 78.451964 -305.383946)
		(end 78.760828 -305.075082)
		(width 0.14732)
		(layer "In6.Cu")
		(net "UPI_CPU0_CPU1_P2P2_DN<6>")
	)
	(segment
		(start 90.22969 -289.383978)
		(end 90.22969 -288.917634)
		(width 0.0889)
		(layer "In6.Cu")
		(net "UPI_CPU0_CPU1_P2P2_DN<6>")
	)
	(segment
		(start 346.329 -301.65167)
		(end 342.622886 -305.35753)
		(width 0.14732)
		(layer "In6.Cu")
		(net "UPI_CPU0_CPU1_P2P2_DN<6>")
	)
	(segment
		(start 347.432884 -298.986448)
		(end 346.329 -301.65167)
		(width 0.14732)
		(layer "In6.Cu")
		(net "UPI_CPU0_CPU1_P2P2_DN<6>")
	)
	(segment
		(start 83.372198 -300.462442)
		(end 84.172298 -299.662342)
		(width 0.14732)
		(layer "In6.Cu")
		(net "UPI_CPU0_CPU1_P2P2_DN<6>")
	)
	(arc
		(start 351.817432 -281.15133)
		(mid 351.663614 -281.344297)
		(end 351.606612 -281.5844)
		(width 0.0889)
		(layer "In6.Cu")
		(net "UPI_CPU0_CPU1_P2P2_DN<6>")
	)
	(arc
		(start 351.136712 -282.424378)
		(mid 351.216874 -282.696567)
		(end 351.41916 -282.895548)
		(width 0.0889)
		(layer "In6.Cu")
		(net "UPI_CPU0_CPU1_P2P2_DN<6>")
	)
	(arc
		(start 93.141292 -282.895548)
		(mid 93.415521 -282.971473)
		(end 93.691964 -282.904184)
		(width 0.0889)
		(layer "In6.Cu")
		(net "UPI_CPU0_CPU1_P2P2_DN<6>")
	)
	(arc
		(start 350.196912 -285.679896)
		(mid 350.277074 -285.952085)
		(end 350.47936 -286.151066)
		(width 0.0889)
		(layer "In6.Cu")
		(net "UPI_CPU0_CPU1_P2P2_DN<6>")
	)
	(arc
		(start 91.170252 -285.676086)
		(mid 91.170055 -285.668721)
		(end 91.169998 -285.661354)
		(width 0.0889)
		(layer "In6.Cu")
		(net "UPI_CPU0_CPU1_P2P2_DN<6>")
	)
	(arc
		(start 350.00946 -287.613598)
		(mid 349.806637 -287.813829)
		(end 349.727266 -288.087562)
		(width 0.0889)
		(layer "In6.Cu")
		(net "UPI_CPU0_CPU1_P2P2_DN<6>")
	)
	(arc
		(start 94.652592 -281.264106)
		(mid 94.855179 -281.057755)
		(end 94.929198 -280.778204)
		(width 0.0889)
		(layer "In6.Cu")
		(net "UPI_CPU0_CPU1_P2P2_DN<6>")
	)
	(arc
		(start 350.48825 -286.156146)
		(mid 350.666847 -286.475424)
		(end 350.48825 -286.794702)
		(width 0.0889)
		(layer "In6.Cu")
		(net "UPI_CPU0_CPU1_P2P2_DN<6>")
	)
	(arc
		(start 94.17685 -282.081478)
		(mid 94.379673 -281.881247)
		(end 94.459044 -281.607514)
		(width 0.0889)
		(layer "In6.Cu")
		(net "UPI_CPU0_CPU1_P2P2_DN<6>")
	)
	(arc
		(start 90.699844 -288.103056)
		(mid 90.747523 -287.920156)
		(end 90.878406 -287.783778)
		(width 0.0889)
		(layer "In6.Cu")
		(net "UPI_CPU0_CPU1_P2P2_DN<6>")
	)
	(arc
		(start 92.579444 -283.219906)
		(mid 92.627123 -283.037006)
		(end 92.758006 -282.900628)
		(width 0.0889)
		(layer "In6.Cu")
		(net "UPI_CPU0_CPU1_P2P2_DN<6>")
	)
	(arc
		(start 351.41916 -281.916378)
		(mid 351.214825 -282.118983)
		(end 351.136712 -282.39593)
		(width 0.0889)
		(layer "In6.Cu")
		(net "UPI_CPU0_CPU1_P2P2_DN<6>")
	)
	(arc
		(start 91.639644 -284.847538)
		(mid 91.687323 -284.664638)
		(end 91.818206 -284.52826)
		(width 0.0889)
		(layer "In6.Cu")
		(net "UPI_CPU0_CPU1_P2P2_DN<6>")
	)
	(arc
		(start 91.363546 -286.961326)
		(mid 91.565959 -286.754913)
		(end 91.639898 -286.475424)
		(width 0.0889)
		(layer "In6.Cu")
		(net "UPI_CPU0_CPU1_P2P2_DN<6>")
	)
	(arc
		(start 91.34856 -285.980632)
		(mid 91.221306 -285.850666)
		(end 91.170252 -285.676086)
		(width 0.0889)
		(layer "In6.Cu")
		(net "UPI_CPU0_CPU1_P2P2_DN<6>")
	)
	(arc
		(start 92.296996 -283.709364)
		(mid 92.501331 -283.506759)
		(end 92.579444 -283.229812)
		(width 0.0889)
		(layer "In6.Cu")
		(net "UPI_CPU0_CPU1_P2P2_DN<6>")
	)
	(arc
		(start 351.41916 -283.544264)
		(mid 351.214825 -283.746869)
		(end 351.136712 -284.023816)
		(width 0.0889)
		(layer "In6.Cu")
		(net "UPI_CPU0_CPU1_P2P2_DN<6>")
	)
	(arc
		(start 349.539814 -288.427414)
		(mid 349.337528 -288.626395)
		(end 349.257366 -288.898584)
		(width 0.0889)
		(layer "In6.Cu")
		(net "UPI_CPU0_CPU1_P2P2_DN<6>")
	)
	(arc
		(start 351.606612 -281.59202)
		(mid 351.558933 -281.77492)
		(end 351.42805 -281.911298)
		(width 0.0889)
		(layer "In6.Cu")
		(net "UPI_CPU0_CPU1_P2P2_DN<6>")
	)
	(arc
		(start 91.35745 -285.336996)
		(mid 91.560273 -285.136765)
		(end 91.639644 -284.863032)
		(width 0.0889)
		(layer "In6.Cu")
		(net "UPI_CPU0_CPU1_P2P2_DN<6>")
	)
	(arc
		(start 91.169998 -285.661354)
		(mid 91.217677 -285.478454)
		(end 91.34856 -285.342076)
		(width 0.0889)
		(layer "In6.Cu")
		(net "UPI_CPU0_CPU1_P2P2_DN<6>")
	)
	(arc
		(start 351.83445 -281.138122)
		(mid 351.825878 -281.144645)
		(end 351.817432 -281.15133)
		(width 0.0889)
		(layer "In6.Cu")
		(net "UPI_CPU0_CPU1_P2P2_DN<6>")
	)
	(arc
		(start 91.827096 -284.52318)
		(mid 92.031431 -284.320575)
		(end 92.109544 -284.043628)
		(width 0.0889)
		(layer "In6.Cu")
		(net "UPI_CPU0_CPU1_P2P2_DN<6>")
	)
	(arc
		(start 90.230198 -288.917126)
		(mid 90.277877 -288.734226)
		(end 90.40876 -288.597848)
		(width 0.0889)
		(layer "In6.Cu")
		(net "UPI_CPU0_CPU1_P2P2_DN<6>")
	)
	(arc
		(start 90.41765 -288.592768)
		(mid 90.618932 -288.395281)
		(end 90.699844 -288.125154)
		(width 0.0889)
		(layer "In6.Cu")
		(net "UPI_CPU0_CPU1_P2P2_DN<6>")
	)
	(arc
		(start 351.136712 -284.033722)
		(mid 351.089033 -284.216622)
		(end 350.95815 -284.353)
		(width 0.0889)
		(layer "In6.Cu")
		(net "UPI_CPU0_CPU1_P2P2_DN<6>")
	)
	(arc
		(start 94.929198 -280.769568)
		(mid 94.981468 -280.587203)
		(end 95.116396 -280.453846)
		(width 0.0889)
		(layer "In6.Cu")
		(net "UPI_CPU0_CPU1_P2P2_DN<6>")
	)
	(arc
		(start 351.42805 -282.900628)
		(mid 351.555943 -283.03169)
		(end 351.606358 -283.207714)
		(width 0.0889)
		(layer "In6.Cu")
		(net "UPI_CPU0_CPU1_P2P2_DN<6>")
	)
	(arc
		(start 91.169998 -287.28924)
		(mid 91.217677 -287.10634)
		(end 91.34856 -286.969962)
		(width 0.0889)
		(layer "In6.Cu")
		(net "UPI_CPU0_CPU1_P2P2_DN<6>")
	)
	(arc
		(start 350.47936 -286.799782)
		(mid 350.275025 -287.002387)
		(end 350.196912 -287.279334)
		(width 0.0889)
		(layer "In6.Cu")
		(net "UPI_CPU0_CPU1_P2P2_DN<6>")
	)
	(arc
		(start 90.893392 -287.775142)
		(mid 91.095979 -287.568791)
		(end 91.169998 -287.28924)
		(width 0.0889)
		(layer "In6.Cu")
		(net "UPI_CPU0_CPU1_P2P2_DN<6>")
	)
	(arc
		(start 92.109544 -284.033722)
		(mid 92.157223 -283.850822)
		(end 92.288106 -283.714444)
		(width 0.0889)
		(layer "In6.Cu")
		(net "UPI_CPU0_CPU1_P2P2_DN<6>")
	)
	(arc
		(start 349.27286 -289.154616)
		(mid 349.382897 -289.323646)
		(end 349.542862 -289.446462)
		(width 0.0889)
		(layer "In6.Cu")
		(net "UPI_CPU0_CPU1_P2P2_DN<6>")
	)
	(arc
		(start 95.116396 -280.453846)
		(mid 95.303594 -280.403703)
		(end 95.490792 -280.453846)
		(width 0.0889)
		(layer "In6.Cu")
		(net "UPI_CPU0_CPU1_P2P2_DN<6>")
	)
	(arc
		(start 93.706696 -282.895548)
		(mid 93.910177 -282.694744)
		(end 93.989398 -282.42006)
		(width 0.0889)
		(layer "In6.Cu")
		(net "UPI_CPU0_CPU1_P2P2_DN<6>")
	)
	(arc
		(start 350.473518 -285.175452)
		(mid 350.270931 -285.381803)
		(end 350.196912 -285.661354)
		(width 0.0889)
		(layer "In6.Cu")
		(net "UPI_CPU0_CPU1_P2P2_DN<6>")
	)
	(arc
		(start 350.667066 -284.847538)
		(mid 350.619387 -285.030438)
		(end 350.488504 -285.166816)
		(width 0.0889)
		(layer "In6.Cu")
		(net "UPI_CPU0_CPU1_P2P2_DN<6>")
	)
	(arc
		(start 349.257366 -289.114738)
		(mid 349.26476 -289.134814)
		(end 349.27286 -289.154616)
		(width 0.0889)
		(layer "In6.Cu")
		(net "UPI_CPU0_CPU1_P2P2_DN<6>")
	)
	(arc
		(start 349.727266 -288.103056)
		(mid 349.679587 -288.285956)
		(end 349.548704 -288.422334)
		(width 0.0889)
		(layer "In6.Cu")
		(net "UPI_CPU0_CPU1_P2P2_DN<6>")
	)
	(arc
		(start 93.989398 -282.405836)
		(mid 94.037077 -282.222936)
		(end 94.16796 -282.086558)
		(width 0.0889)
		(layer "In6.Cu")
		(net "UPI_CPU0_CPU1_P2P2_DN<6>")
	)
	(arc
		(start 350.196912 -287.28924)
		(mid 350.149233 -287.47214)
		(end 350.01835 -287.608518)
		(width 0.0889)
		(layer "In6.Cu")
		(net "UPI_CPU0_CPU1_P2P2_DN<6>")
	)
	(arc
		(start 91.639898 -286.4612)
		(mid 91.560757 -286.186577)
		(end 91.35745 -285.985712)
		(width 0.0889)
		(layer "In6.Cu")
		(net "UPI_CPU0_CPU1_P2P2_DN<6>")
	)
	(arc
		(start 94.459044 -281.59202)
		(mid 94.506723 -281.40912)
		(end 94.637606 -281.272742)
		(width 0.0889)
		(layer "In6.Cu")
		(net "UPI_CPU0_CPU1_P2P2_DN<6>")
	)
	(arc
		(start 351.606358 -283.207714)
		(mid 351.606603 -283.21711)
		(end 351.606612 -283.22651)
		(width 0.0889)
		(layer "In6.Cu")
		(net "UPI_CPU0_CPU1_P2P2_DN<6>")
	)
	(arc
		(start 350.94926 -284.35808)
		(mid 350.746437 -284.558311)
		(end 350.667066 -284.832044)
		(width 0.0889)
		(layer "In6.Cu")
		(net "UPI_CPU0_CPU1_P2P2_DN<6>")
	)
	(arc
		(start 95.499682 -280.458926)
		(mid 95.615421 -280.57075)
		(end 95.673672 -280.7208)
		(width 0.0889)
		(layer "In6.Cu")
		(net "UPI_CPU0_CPU1_P2P2_DN<6>")
	)
	(arc
		(start 92.766896 -282.895548)
		(mid 92.954094 -282.845405)
		(end 93.141292 -282.895548)
		(width 0.0889)
		(layer "In6.Cu")
		(net "UPI_CPU0_CPU1_P2P2_DN<6>")
	)
	(arc
		(start 351.606612 -283.22651)
		(mid 351.557359 -283.40571)
		(end 351.42805 -283.539184)
		(width 0.0889)
		(layer "In6.Cu")
		(net "UPI_CPU0_CPU1_P2P2_DN<6>")
	)
	(segment
		(start 352.641916 -282.405582)
		(end 352.641662 -282.405836)
		(width 0.13208)
		(layer "F.Cu")
		(net "UPI_CPU0_CPU1_P2P2_DN<5>")
	)
	(segment
		(start 352.641916 -281.869896)
		(end 352.641916 -282.405582)
		(width 0.13208)
		(layer "F.Cu")
		(net "UPI_CPU0_CPU1_P2P2_DN<5>")
	)
	(segment
		(start 89.664794 -280.242264)
		(end 89.664794 -280.778204)
		(width 0.13208)
		(layer "F.Cu")
		(net "UPI_CPU0_CPU1_P2P2_DN<5>")
	)
	(segment
		(start 348.330774 -294.756078)
		(end 348.330774 -294.931338)
		(width 0.0889)
		(layer "In6.Cu")
		(net "UPI_CPU0_CPU1_P2P2_DN<5>")
	)
	(segment
		(start 282.593034 -340.50097)
		(end 276.308312 -346.785692)
		(width 0.14732)
		(layer "In6.Cu")
		(net "UPI_CPU0_CPU1_P2P2_DN<5>")
	)
	(segment
		(start 350.666812 -290.281868)
		(end 350.519492 -290.429188)
		(width 0.0889)
		(layer "In6.Cu")
		(net "UPI_CPU0_CPU1_P2P2_DN<5>")
	)
	(segment
		(start 351.606866 -284.832044)
		(end 351.606866 -284.847538)
		(width 0.0889)
		(layer "In6.Cu")
		(net "UPI_CPU0_CPU1_P2P2_DN<5>")
	)
	(segment
		(start 87.632032 -292.085014)
		(end 87.632032 -292.02507)
		(width 0.0889)
		(layer "In6.Cu")
		(net "UPI_CPU0_CPU1_P2P2_DN<5>")
	)
	(segment
		(start 61.083952 -322.65239)
		(end 61.55182 -321.523868)
		(width 0.14732)
		(layer "In6.Cu")
		(net "UPI_CPU0_CPU1_P2P2_DN<5>")
	)
	(segment
		(start 68.579746 -371.10543)
		(end 68.579746 -370.900706)
		(width 0.14732)
		(layer "In6.Cu")
		(net "UPI_CPU0_CPU1_P2P2_DN<5>")
	)
	(segment
		(start 348.231714 -294.481758)
		(end 348.231714 -294.657018)
		(width 0.0889)
		(layer "In6.Cu")
		(net "UPI_CPU0_CPU1_P2P2_DN<5>")
	)
	(segment
		(start 351.418652 -286.80029)
		(end 351.413318 -286.803338)
		(width 0.0889)
		(layer "In6.Cu")
		(net "UPI_CPU0_CPU1_P2P2_DN<5>")
	)
	(segment
		(start 58.829702 -330.251816)
		(end 58.6232 -329.71613)
		(width 0.14732)
		(layer "In6.Cu")
		(net "UPI_CPU0_CPU1_P2P2_DN<5>")
	)
	(segment
		(start 348.330774 -295.853358)
		(end 348.330774 -296.099738)
		(width 0.0889)
		(layer "In6.Cu")
		(net "UPI_CPU0_CPU1_P2P2_DN<5>")
	)
	(segment
		(start 66.384932 -315.476382)
		(end 67.446652 -315.036708)
		(width 0.14732)
		(layer "In6.Cu")
		(net "UPI_CPU0_CPU1_P2P2_DN<5>")
	)
	(segment
		(start 59.069732 -324.666356)
		(end 61.083952 -322.65239)
		(width 0.14732)
		(layer "In6.Cu")
		(net "UPI_CPU0_CPU1_P2P2_DN<5>")
	)
	(segment
		(start 319.998344 -326.864472)
		(end 318.852042 -329.631802)
		(width 0.14732)
		(layer "In6.Cu")
		(net "UPI_CPU0_CPU1_P2P2_DN<5>")
	)
	(segment
		(start 60.447936 -334.445356)
		(end 60.530994 -334.258158)
		(width 0.14732)
		(layer "In6.Cu")
		(net "UPI_CPU0_CPU1_P2P2_DN<5>")
	)
	(segment
		(start 351.89795 -284.353)
		(end 351.88906 -284.35808)
		(width 0.0889)
		(layer "In6.Cu")
		(net "UPI_CPU0_CPU1_P2P2_DN<5>")
	)
	(segment
		(start 67.383152 -369.704112)
		(end 67.178428 -369.704112)
		(width 0.14732)
		(layer "In6.Cu")
		(net "UPI_CPU0_CPU1_P2P2_DN<5>")
	)
	(segment
		(start 59.066938 -330.865734)
		(end 59.149742 -330.678536)
		(width 0.14732)
		(layer "In6.Cu")
		(net "UPI_CPU0_CPU1_P2P2_DN<5>")
	)
	(segment
		(start 348.330774 -294.931338)
		(end 348.231714 -295.030398)
		(width 0.0889)
		(layer "In6.Cu")
		(net "UPI_CPU0_CPU1_P2P2_DN<5>")
	)
	(segment
		(start 89.290398 -289.205924)
		(end 89.290398 -288.90849)
		(width 0.0889)
		(layer "In6.Cu")
		(net "UPI_CPU0_CPU1_P2P2_DN<5>")
	)
	(segment
		(start 89.948258 -281.916886)
		(end 89.947496 -281.916378)
		(width 0.0889)
		(layer "In6.Cu")
		(net "UPI_CPU0_CPU1_P2P2_DN<5>")
	)
	(segment
		(start 88.710008 -289.786314)
		(end 89.290398 -289.205924)
		(width 0.0889)
		(layer "In6.Cu")
		(net "UPI_CPU0_CPU1_P2P2_DN<5>")
	)
	(segment
		(start 89.760298 -281.600656)
		(end 89.760298 -281.59202)
		(width 0.0889)
		(layer "In6.Cu")
		(net "UPI_CPU0_CPU1_P2P2_DN<5>")
	)
	(segment
		(start 90.412824 -286.967676)
		(end 90.416634 -286.96539)
		(width 0.0889)
		(layer "In6.Cu")
		(net "UPI_CPU0_CPU1_P2P2_DN<5>")
	)
	(segment
		(start 88.710008 -289.78606)
		(end 88.710008 -289.786314)
		(width 0.0889)
		(layer "In6.Cu")
		(net "UPI_CPU0_CPU1_P2P2_DN<5>")
	)
	(segment
		(start 61.823092 -319.735454)
		(end 61.823346 -319.735454)
		(width 0.14732)
		(layer "In6.Cu")
		(net "UPI_CPU0_CPU1_P2P2_DN<5>")
	)
	(segment
		(start 61.55182 -321.523868)
		(end 61.55182 -320.390266)
		(width 0.14732)
		(layer "In6.Cu")
		(net "UPI_CPU0_CPU1_P2P2_DN<5>")
	)
	(segment
		(start 66.564256 -369.08994)
		(end 60.87872 -355.363272)
		(width 0.14732)
		(layer "In6.Cu")
		(net "UPI_CPU0_CPU1_P2P2_DN<5>")
	)
	(segment
		(start 59.386724 -331.2922)
		(end 59.199272 -331.209142)
		(width 0.14732)
		(layer "In6.Cu")
		(net "UPI_CPU0_CPU1_P2P2_DN<5>")
	)
	(segment
		(start 276.186392 -368.696748)
		(end 276.308312 -368.818668)
		(width 0.14732)
		(layer "In6.Cu")
		(net "UPI_CPU0_CPU1_P2P2_DN<5>")
	)
	(segment
		(start 83.591654 -298.891706)
		(end 85.5472 -294.169846)
		(width 0.14732)
		(layer "In6.Cu")
		(net "UPI_CPU0_CPU1_P2P2_DN<5>")
	)
	(segment
		(start 89.938606 -287.783778)
		(end 89.959688 -287.771586)
		(width 0.0889)
		(layer "In6.Cu")
		(net "UPI_CPU0_CPU1_P2P2_DN<5>")
	)
	(segment
		(start 71.42988 -373.955564)
		(end 68.579746 -371.10543)
		(width 0.14732)
		(layer "In6.Cu")
		(net "UPI_CPU0_CPU1_P2P2_DN<5>")
	)
	(segment
		(start 90.416634 -285.337504)
		(end 90.41765 -285.336996)
		(width 0.0889)
		(layer "In6.Cu")
		(net "UPI_CPU0_CPU1_P2P2_DN<5>")
	)
	(segment
		(start 95.247968 -383.820924)
		(end 71.42988 -373.955564)
		(width 0.14732)
		(layer "In6.Cu")
		(net "UPI_CPU0_CPU1_P2P2_DN<5>")
	)
	(segment
		(start 348.330774 -296.473118)
		(end 348.330774 -297.699938)
		(width 0.0889)
		(layer "In6.Cu")
		(net "UPI_CPU0_CPU1_P2P2_DN<5>")
	)
	(segment
		(start 348.231714 -295.754298)
		(end 348.330774 -295.853358)
		(width 0.0889)
		(layer "In6.Cu")
		(net "UPI_CPU0_CPU1_P2P2_DN<5>")
	)
	(segment
		(start 348.288864 -299.17263)
		(end 347.09227 -302.060864)
		(width 0.14732)
		(layer "In6.Cu")
		(net "UPI_CPU0_CPU1_P2P2_DN<5>")
	)
	(segment
		(start 90.40876 -285.342076)
		(end 90.412824 -285.33979)
		(width 0.0889)
		(layer "In6.Cu")
		(net "UPI_CPU0_CPU1_P2P2_DN<5>")
	)
	(segment
		(start 276.186392 -368.259868)
		(end 276.186392 -368.696748)
		(width 0.14732)
		(layer "In6.Cu")
		(net "UPI_CPU0_CPU1_P2P2_DN<5>")
	)
	(segment
		(start 63.682372 -317.493142)
		(end 63.89243 -317.40602)
		(width 0.14732)
		(layer "In6.Cu")
		(net "UPI_CPU0_CPU1_P2P2_DN<5>")
	)
	(segment
		(start 62.574932 -318.773048)
		(end 62.88405 -318.46393)
		(width 0.14732)
		(layer "In6.Cu")
		(net "UPI_CPU0_CPU1_P2P2_DN<5>")
	)
	(segment
		(start 67.643756 -370.16944)
		(end 67.643756 -369.964716)
		(width 0.14732)
		(layer "In6.Cu")
		(net "UPI_CPU0_CPU1_P2P2_DN<5>")
	)
	(segment
		(start 90.40876 -286.969962)
		(end 90.412824 -286.967676)
		(width 0.0889)
		(layer "In6.Cu")
		(net "UPI_CPU0_CPU1_P2P2_DN<5>")
	)
	(segment
		(start 267.377418 -379.513338)
		(end 162.186366 -388.39521)
		(width 0.14732)
		(layer "In6.Cu")
		(net "UPI_CPU0_CPU1_P2P2_DN<5>")
	)
	(segment
		(start 87.632032 -292.02507)
		(end 88.245442 -291.41166)
		(width 0.0889)
		(layer "In6.Cu")
		(net "UPI_CPU0_CPU1_P2P2_DN<5>")
	)
	(segment
		(start 90.699844 -283.219906)
		(end 90.699844 -283.197808)
		(width 0.0889)
		(layer "In6.Cu")
		(net "UPI_CPU0_CPU1_P2P2_DN<5>")
	)
	(segment
		(start 350.666812 -289.645852)
		(end 350.666812 -290.281868)
		(width 0.0889)
		(layer "In6.Cu")
		(net "UPI_CPU0_CPU1_P2P2_DN<5>")
	)
	(segment
		(start 352.359722 -283.543756)
		(end 352.35896 -283.544264)
		(width 0.0889)
		(layer "In6.Cu")
		(net "UPI_CPU0_CPU1_P2P2_DN<5>")
	)
	(segment
		(start 350.488504 -288.422334)
		(end 350.479614 -288.427414)
		(width 0.0889)
		(layer "In6.Cu")
		(net "UPI_CPU0_CPU1_P2P2_DN<5>")
	)
	(segment
		(start 348.231714 -295.205658)
		(end 348.330774 -295.304718)
		(width 0.0889)
		(layer "In6.Cu")
		(net "UPI_CPU0_CPU1_P2P2_DN<5>")
	)
	(segment
		(start 351.606612 -286.466788)
		(end 351.606612 -286.48406)
		(width 0.0889)
		(layer "In6.Cu")
		(net "UPI_CPU0_CPU1_P2P2_DN<5>")
	)
	(segment
		(start 350.519492 -290.429188)
		(end 350.386142 -290.429188)
		(width 0.0889)
		(layer "In6.Cu")
		(net "UPI_CPU0_CPU1_P2P2_DN<5>")
	)
	(segment
		(start 350.26219 -290.693602)
		(end 348.330774 -292.625018)
		(width 0.0889)
		(layer "In6.Cu")
		(net "UPI_CPU0_CPU1_P2P2_DN<5>")
	)
	(segment
		(start 59.017154 -330.33462)
		(end 58.829702 -330.251816)
		(width 0.14732)
		(layer "In6.Cu")
		(net "UPI_CPU0_CPU1_P2P2_DN<5>")
	)
	(segment
		(start 351.419414 -286.799782)
		(end 351.418652 -286.80029)
		(width 0.0889)
		(layer "In6.Cu")
		(net "UPI_CPU0_CPU1_P2P2_DN<5>")
	)
	(segment
		(start 348.288864 -297.763946)
		(end 348.288864 -299.17263)
		(width 0.14732)
		(layer "In6.Cu")
		(net "UPI_CPU0_CPU1_P2P2_DN<5>")
	)
	(segment
		(start 347.09227 -302.060864)
		(end 343.03335 -306.119784)
		(width 0.14732)
		(layer "In6.Cu")
		(net "UPI_CPU0_CPU1_P2P2_DN<5>")
	)
	(segment
		(start 348.330774 -296.099738)
		(end 348.231714 -296.198798)
		(width 0.0889)
		(layer "In6.Cu")
		(net "UPI_CPU0_CPU1_P2P2_DN<5>")
	)
	(segment
		(start 352.36785 -283.539184)
		(end 352.359722 -283.543756)
		(width 0.0889)
		(layer "In6.Cu")
		(net "UPI_CPU0_CPU1_P2P2_DN<5>")
	)
	(segment
		(start 61.823346 -319.735454)
		(end 62.09411 -319.081404)
		(width 0.14732)
		(layer "In6.Cu")
		(net "UPI_CPU0_CPU1_P2P2_DN<5>")
	)
	(segment
		(start 348.330774 -292.625018)
		(end 348.330774 -293.285418)
		(width 0.0889)
		(layer "In6.Cu")
		(net "UPI_CPU0_CPU1_P2P2_DN<5>")
	)
	(segment
		(start 276.186392 -369.814348)
		(end 276.308312 -369.936268)
		(width 0.14732)
		(layer "In6.Cu")
		(net "UPI_CPU0_CPU1_P2P2_DN<5>")
	)
	(segment
		(start 348.330774 -293.658798)
		(end 348.330774 -293.834058)
		(width 0.0889)
		(layer "In6.Cu")
		(net "UPI_CPU0_CPU1_P2P2_DN<5>")
	)
	(segment
		(start 352.641662 -282.405836)
		(end 352.328988 -282.405836)
		(width 0.0889)
		(layer "In6.Cu")
		(net "UPI_CPU0_CPU1_P2P2_DN<5>")
	)
	(segment
		(start 67.643756 -369.964716)
		(end 67.383152 -369.704112)
		(width 0.14732)
		(layer "In6.Cu")
		(net "UPI_CPU0_CPU1_P2P2_DN<5>")
	)
	(segment
		(start 126.083568 -388.39521)
		(end 95.247968 -383.820924)
		(width 0.14732)
		(layer "In6.Cu")
		(net "UPI_CPU0_CPU1_P2P2_DN<5>")
	)
	(segment
		(start 351.428304 -285.166816)
		(end 351.41916 -285.171896)
		(width 0.0889)
		(layer "In6.Cu")
		(net "UPI_CPU0_CPU1_P2P2_DN<5>")
	)
	(segment
		(start 62.09411 -319.081404)
		(end 62.402466 -318.773048)
		(width 0.14732)
		(layer "In6.Cu")
		(net "UPI_CPU0_CPU1_P2P2_DN<5>")
	)
	(segment
		(start 90.878406 -284.52826)
		(end 90.887296 -284.52318)
		(width 0.0889)
		(layer "In6.Cu")
		(net "UPI_CPU0_CPU1_P2P2_DN<5>")
	)
	(segment
		(start 352.45294 -282.08224)
		(end 352.454464 -282.081478)
		(width 0.0889)
		(layer "In6.Cu")
		(net "UPI_CPU0_CPU1_P2P2_DN<5>")
	)
	(segment
		(start 62.88405 -318.291464)
		(end 63.682372 -317.493142)
		(width 0.14732)
		(layer "In6.Cu")
		(net "UPI_CPU0_CPU1_P2P2_DN<5>")
	)
	(segment
		(start 348.231714 -293.559738)
		(end 348.330774 -293.658798)
		(width 0.0889)
		(layer "In6.Cu")
		(net "UPI_CPU0_CPU1_P2P2_DN<5>")
	)
	(segment
		(start 343.03335 -306.119784)
		(end 340.126066 -307.324252)
		(width 0.14732)
		(layer "In6.Cu")
		(net "UPI_CPU0_CPU1_P2P2_DN<5>")
	)
	(segment
		(start 89.50833 -281.049222)
		(end 89.664794 -280.778204)
		(width 0.0889)
		(layer "In6.Cu")
		(net "UPI_CPU0_CPU1_P2P2_DN<5>")
	)
	(segment
		(start 340.126066 -307.324252)
		(end 340.125812 -307.324252)
		(width 0.14732)
		(layer "In6.Cu")
		(net "UPI_CPU0_CPU1_P2P2_DN<5>")
	)
	(segment
		(start 59.199272 -331.209142)
		(end 59.066938 -330.865734)
		(width 0.14732)
		(layer "In6.Cu")
		(net "UPI_CPU0_CPU1_P2P2_DN<5>")
	)
	(segment
		(start 348.330774 -293.285418)
		(end 348.231714 -293.384478)
		(width 0.0889)
		(layer "In6.Cu")
		(net "UPI_CPU0_CPU1_P2P2_DN<5>")
	)
	(segment
		(start 348.231714 -294.657018)
		(end 348.330774 -294.756078)
		(width 0.0889)
		(layer "In6.Cu")
		(net "UPI_CPU0_CPU1_P2P2_DN<5>")
	)
	(segment
		(start 276.308312 -368.137948)
		(end 276.186392 -368.259868)
		(width 0.14732)
		(layer "In6.Cu")
		(net "UPI_CPU0_CPU1_P2P2_DN<5>")
	)
	(segment
		(start 60.398406 -333.914242)
		(end 60.210954 -333.831184)
		(width 0.14732)
		(layer "In6.Cu")
		(net "UPI_CPU0_CPU1_P2P2_DN<5>")
	)
	(segment
		(start 89.760044 -288.121598)
		(end 89.760044 -288.103056)
		(width 0.0889)
		(layer "In6.Cu")
		(net "UPI_CPU0_CPU1_P2P2_DN<5>")
	)
	(segment
		(start 67.178428 -369.704112)
		(end 66.564256 -369.08994)
		(width 0.14732)
		(layer "In6.Cu")
		(net "UPI_CPU0_CPU1_P2P2_DN<5>")
	)
	(segment
		(start 90.699844 -286.490918)
		(end 90.699844 -286.453326)
		(width 0.0889)
		(layer "In6.Cu")
		(net "UPI_CPU0_CPU1_P2P2_DN<5>")
	)
	(segment
		(start 348.231714 -296.198798)
		(end 348.231714 -296.374058)
		(width 0.0889)
		(layer "In6.Cu")
		(net "UPI_CPU0_CPU1_P2P2_DN<5>")
	)
	(segment
		(start 68.114418 -370.640102)
		(end 67.643756 -370.16944)
		(width 0.14732)
		(layer "In6.Cu")
		(net "UPI_CPU0_CPU1_P2P2_DN<5>")
	)
	(segment
		(start 59.519312 -331.636116)
		(end 59.386724 -331.2922)
		(width 0.14732)
		(layer "In6.Cu")
		(net "UPI_CPU0_CPU1_P2P2_DN<5>")
	)
	(segment
		(start 88.245442 -291.41166)
		(end 88.245442 -290.250626)
		(width 0.0889)
		(layer "In6.Cu")
		(net "UPI_CPU0_CPU1_P2P2_DN<5>")
	)
	(segment
		(start 60.530994 -334.258158)
		(end 60.398406 -333.914242)
		(width 0.14732)
		(layer "In6.Cu")
		(net "UPI_CPU0_CPU1_P2P2_DN<5>")
	)
	(segment
		(start 276.308312 -369.936268)
		(end 276.308312 -370.582444)
		(width 0.14732)
		(layer "In6.Cu")
		(net "UPI_CPU0_CPU1_P2P2_DN<5>")
	)
	(segment
		(start 90.416634 -286.96539)
		(end 90.41765 -286.964882)
		(width 0.0889)
		(layer "In6.Cu")
		(net "UPI_CPU0_CPU1_P2P2_DN<5>")
	)
	(segment
		(start 68.579746 -370.900706)
		(end 68.319142 -370.640102)
		(width 0.14732)
		(layer "In6.Cu")
		(net "UPI_CPU0_CPU1_P2P2_DN<5>")
	)
	(segment
		(start 348.330774 -295.479978)
		(end 348.231714 -295.579038)
		(width 0.0889)
		(layer "In6.Cu")
		(net "UPI_CPU0_CPU1_P2P2_DN<5>")
	)
	(segment
		(start 276.186392 -369.377468)
		(end 276.186392 -369.814348)
		(width 0.14732)
		(layer "In6.Cu")
		(net "UPI_CPU0_CPU1_P2P2_DN<5>")
	)
	(segment
		(start 68.319142 -370.640102)
		(end 68.114418 -370.640102)
		(width 0.14732)
		(layer "In6.Cu")
		(net "UPI_CPU0_CPU1_P2P2_DN<5>")
	)
	(segment
		(start 162.186366 -388.39521)
		(end 126.083568 -388.39521)
		(width 0.14732)
		(layer "In6.Cu")
		(net "UPI_CPU0_CPU1_P2P2_DN<5>")
	)
	(segment
		(start 60.87872 -335.562448)
		(end 60.447936 -334.445356)
		(width 0.14732)
		(layer "In6.Cu")
		(net "UPI_CPU0_CPU1_P2P2_DN<5>")
	)
	(segment
		(start 60.210954 -333.831184)
		(end 59.436508 -331.823314)
		(width 0.14732)
		(layer "In6.Cu")
		(net "UPI_CPU0_CPU1_P2P2_DN<5>")
	)
	(segment
		(start 348.330774 -294.382698)
		(end 348.231714 -294.481758)
		(width 0.0889)
		(layer "In6.Cu")
		(net "UPI_CPU0_CPU1_P2P2_DN<5>")
	)
	(segment
		(start 348.231714 -293.384478)
		(end 348.231714 -293.559738)
		(width 0.0889)
		(layer "In6.Cu")
		(net "UPI_CPU0_CPU1_P2P2_DN<5>")
	)
	(segment
		(start 348.330774 -293.834058)
		(end 348.231714 -293.933118)
		(width 0.0889)
		(layer "In6.Cu")
		(net "UPI_CPU0_CPU1_P2P2_DN<5>")
	)
	(segment
		(start 350.667066 -288.087562)
		(end 350.667066 -288.103056)
		(width 0.0889)
		(layer "In6.Cu")
		(net "UPI_CPU0_CPU1_P2P2_DN<5>")
	)
	(segment
		(start 348.330774 -294.207438)
		(end 348.330774 -294.382698)
		(width 0.0889)
		(layer "In6.Cu")
		(net "UPI_CPU0_CPU1_P2P2_DN<5>")
	)
	(segment
		(start 90.887296 -283.544264)
		(end 90.878406 -283.539184)
		(width 0.0889)
		(layer "In6.Cu")
		(net "UPI_CPU0_CPU1_P2P2_DN<5>")
	)
	(segment
		(start 59.149742 -330.678536)
		(end 59.017154 -330.33462)
		(width 0.14732)
		(layer "In6.Cu")
		(net "UPI_CPU0_CPU1_P2P2_DN<5>")
	)
	(segment
		(start 90.41765 -282.730194)
		(end 90.40876 -282.725114)
		(width 0.0889)
		(layer "In6.Cu")
		(net "UPI_CPU0_CPU1_P2P2_DN<5>")
	)
	(segment
		(start 65.423796 -315.874654)
		(end 66.384678 -315.476382)
		(width 0.14732)
		(layer "In6.Cu")
		(net "UPI_CPU0_CPU1_P2P2_DN<5>")
	)
	(segment
		(start 62.402466 -318.773048)
		(end 62.574932 -318.773048)
		(width 0.14732)
		(layer "In6.Cu")
		(net "UPI_CPU0_CPU1_P2P2_DN<5>")
	)
	(segment
		(start 348.231714 -294.108378)
		(end 348.330774 -294.207438)
		(width 0.0889)
		(layer "In6.Cu")
		(net "UPI_CPU0_CPU1_P2P2_DN<5>")
	)
	(segment
		(start 286.312864 -338.96046)
		(end 282.593034 -340.50097)
		(width 0.14732)
		(layer "In6.Cu")
		(net "UPI_CPU0_CPU1_P2P2_DN<5>")
	)
	(segment
		(start 348.330774 -297.699938)
		(end 348.288864 -297.741848)
		(width 0.0889)
		(layer "In6.Cu")
		(net "UPI_CPU0_CPU1_P2P2_DN<5>")
	)
	(segment
		(start 352.328988 -282.405836)
		(end 352.271584 -282.348432)
		(width 0.0889)
		(layer "In6.Cu")
		(net "UPI_CPU0_CPU1_P2P2_DN<5>")
	)
	(segment
		(start 348.330774 -295.304718)
		(end 348.330774 -295.479978)
		(width 0.0889)
		(layer "In6.Cu")
		(net "UPI_CPU0_CPU1_P2P2_DN<5>")
	)
	(segment
		(start 352.829876 -282.729686)
		(end 352.82886 -282.730194)
		(width 0.0889)
		(layer "In6.Cu")
		(net "UPI_CPU0_CPU1_P2P2_DN<5>")
	)
	(segment
		(start 352.076512 -284.023816)
		(end 352.076512 -284.033722)
		(width 0.0889)
		(layer "In6.Cu")
		(net "UPI_CPU0_CPU1_P2P2_DN<5>")
	)
	(segment
		(start 352.546412 -283.205682)
		(end 352.546412 -283.219906)
		(width 0.0889)
		(layer "In6.Cu")
		(net "UPI_CPU0_CPU1_P2P2_DN<5>")
	)
	(segment
		(start 90.412824 -285.33979)
		(end 90.416634 -285.337504)
		(width 0.0889)
		(layer "In6.Cu")
		(net "UPI_CPU0_CPU1_P2P2_DN<5>")
	)
	(segment
		(start 62.88405 -318.46393)
		(end 62.88405 -318.291464)
		(width 0.14732)
		(layer "In6.Cu")
		(net "UPI_CPU0_CPU1_P2P2_DN<5>")
	)
	(segment
		(start 89.53246 -281.138376)
		(end 89.50833 -281.049222)
		(width 0.0889)
		(layer "In6.Cu")
		(net "UPI_CPU0_CPU1_P2P2_DN<5>")
	)
	(segment
		(start 88.245442 -290.250626)
		(end 88.710008 -289.78606)
		(width 0.0889)
		(layer "In6.Cu")
		(net "UPI_CPU0_CPU1_P2P2_DN<5>")
	)
	(segment
		(start 318.852042 -329.631802)
		(end 309.523384 -338.96046)
		(width 0.14732)
		(layer "In6.Cu")
		(net "UPI_CPU0_CPU1_P2P2_DN<5>")
	)
	(segment
		(start 58.6232 -329.71613)
		(end 58.6232 -325.744332)
		(width 0.14732)
		(layer "In6.Cu")
		(net "UPI_CPU0_CPU1_P2P2_DN<5>")
	)
	(segment
		(start 276.308312 -368.818668)
		(end 276.308312 -369.255548)
		(width 0.14732)
		(layer "In6.Cu")
		(net "UPI_CPU0_CPU1_P2P2_DN<5>")
	)
	(segment
		(start 348.231714 -296.374058)
		(end 348.330774 -296.473118)
		(width 0.0889)
		(layer "In6.Cu")
		(net "UPI_CPU0_CPU1_P2P2_DN<5>")
	)
	(segment
		(start 276.308312 -369.255548)
		(end 276.186392 -369.377468)
		(width 0.14732)
		(layer "In6.Cu")
		(net "UPI_CPU0_CPU1_P2P2_DN<5>")
	)
	(segment
		(start 348.231714 -295.579038)
		(end 348.231714 -295.754298)
		(width 0.0889)
		(layer "In6.Cu")
		(net "UPI_CPU0_CPU1_P2P2_DN<5>")
	)
	(segment
		(start 339.123274 -307.739542)
		(end 319.998344 -326.864472)
		(width 0.14732)
		(layer "In6.Cu")
		(net "UPI_CPU0_CPU1_P2P2_DN<5>")
	)
	(segment
		(start 90.41765 -285.985712)
		(end 90.40876 -285.980632)
		(width 0.0889)
		(layer "In6.Cu")
		(net "UPI_CPU0_CPU1_P2P2_DN<5>")
	)
	(segment
		(start 350.386142 -290.429188)
		(end 350.26219 -290.55314)
		(width 0.0889)
		(layer "In6.Cu")
		(net "UPI_CPU0_CPU1_P2P2_DN<5>")
	)
	(segment
		(start 348.288864 -297.741848)
		(end 348.288864 -297.763946)
		(width 0.0889)
		(layer "In6.Cu")
		(net "UPI_CPU0_CPU1_P2P2_DN<5>")
	)
	(segment
		(start 58.6232 -325.744332)
		(end 59.069732 -324.666356)
		(width 0.14732)
		(layer "In6.Cu")
		(net "UPI_CPU0_CPU1_P2P2_DN<5>")
	)
	(segment
		(start 90.699844 -284.863032)
		(end 90.699844 -284.847538)
		(width 0.0889)
		(layer "In6.Cu")
		(net "UPI_CPU0_CPU1_P2P2_DN<5>")
	)
	(segment
		(start 89.953592 -281.919934)
		(end 89.948258 -281.916886)
		(width 0.0889)
		(layer "In6.Cu")
		(net "UPI_CPU0_CPU1_P2P2_DN<5>")
	)
	(segment
		(start 340.125812 -307.324252)
		(end 339.123274 -307.739542)
		(width 0.14732)
		(layer "In6.Cu")
		(net "UPI_CPU0_CPU1_P2P2_DN<5>")
	)
	(segment
		(start 348.231714 -293.933118)
		(end 348.231714 -294.108378)
		(width 0.0889)
		(layer "In6.Cu")
		(net "UPI_CPU0_CPU1_P2P2_DN<5>")
	)
	(segment
		(start 85.5472 -294.169846)
		(end 87.616538 -292.100508)
		(width 0.14732)
		(layer "In6.Cu")
		(net "UPI_CPU0_CPU1_P2P2_DN<5>")
	)
	(segment
		(start 350.482662 -289.446462)
		(end 350.482916 -289.446462)
		(width 0.0889)
		(layer "In6.Cu")
		(net "UPI_CPU0_CPU1_P2P2_DN<5>")
	)
	(segment
		(start 276.308312 -346.785692)
		(end 276.308312 -368.137948)
		(width 0.14732)
		(layer "In6.Cu")
		(net "UPI_CPU0_CPU1_P2P2_DN<5>")
	)
	(segment
		(start 309.523384 -338.96046)
		(end 286.312864 -338.96046)
		(width 0.14732)
		(layer "In6.Cu")
		(net "UPI_CPU0_CPU1_P2P2_DN<5>")
	)
	(segment
		(start 350.197166 -288.898584)
		(end 350.197166 -289.114738)
		(width 0.0889)
		(layer "In6.Cu")
		(net "UPI_CPU0_CPU1_P2P2_DN<5>")
	)
	(segment
		(start 61.55182 -320.390266)
		(end 61.823092 -319.735454)
		(width 0.14732)
		(layer "In6.Cu")
		(net "UPI_CPU0_CPU1_P2P2_DN<5>")
	)
	(segment
		(start 59.436508 -331.823314)
		(end 59.519312 -331.636116)
		(width 0.14732)
		(layer "In6.Cu")
		(net "UPI_CPU0_CPU1_P2P2_DN<5>")
	)
	(segment
		(start 350.26219 -290.55314)
		(end 350.26219 -290.693602)
		(width 0.0889)
		(layer "In6.Cu")
		(net "UPI_CPU0_CPU1_P2P2_DN<5>")
	)
	(segment
		(start 348.231714 -295.030398)
		(end 348.231714 -295.205658)
		(width 0.0889)
		(layer "In6.Cu")
		(net "UPI_CPU0_CPU1_P2P2_DN<5>")
	)
	(segment
		(start 351.136712 -285.651448)
		(end 351.136712 -285.675578)
		(width 0.0889)
		(layer "In6.Cu")
		(net "UPI_CPU0_CPU1_P2P2_DN<5>")
	)
	(segment
		(start 66.384678 -315.476382)
		(end 66.384932 -315.476382)
		(width 0.14732)
		(layer "In6.Cu")
		(net "UPI_CPU0_CPU1_P2P2_DN<5>")
	)
	(segment
		(start 63.89243 -317.40602)
		(end 65.423796 -315.874654)
		(width 0.14732)
		(layer "In6.Cu")
		(net "UPI_CPU0_CPU1_P2P2_DN<5>")
	)
	(segment
		(start 87.616538 -292.100508)
		(end 87.632032 -292.085014)
		(width 0.0889)
		(layer "In6.Cu")
		(net "UPI_CPU0_CPU1_P2P2_DN<5>")
	)
	(segment
		(start 67.446652 -315.036708)
		(end 83.591654 -298.891706)
		(width 0.14732)
		(layer "In6.Cu")
		(net "UPI_CPU0_CPU1_P2P2_DN<5>")
	)
	(segment
		(start 350.95815 -287.608518)
		(end 350.94926 -287.613598)
		(width 0.0889)
		(layer "In6.Cu")
		(net "UPI_CPU0_CPU1_P2P2_DN<5>")
	)
	(segment
		(start 276.308312 -370.582444)
		(end 267.377418 -379.513338)
		(width 0.14732)
		(layer "In6.Cu")
		(net "UPI_CPU0_CPU1_P2P2_DN<5>")
	)
	(segment
		(start 352.83775 -282.725114)
		(end 352.829876 -282.729686)
		(width 0.0889)
		(layer "In6.Cu")
		(net "UPI_CPU0_CPU1_P2P2_DN<5>")
	)
	(segment
		(start 60.87872 -355.363272)
		(end 60.87872 -335.562448)
		(width 0.14732)
		(layer "In6.Cu")
		(net "UPI_CPU0_CPU1_P2P2_DN<5>")
	)
	(arc
		(start 351.606866 -284.847538)
		(mid 351.559187 -285.030438)
		(end 351.428304 -285.166816)
		(width 0.0889)
		(layer "In6.Cu")
		(net "UPI_CPU0_CPU1_P2P2_DN<5>")
	)
	(arc
		(start 90.41765 -285.336996)
		(mid 90.620473 -285.136765)
		(end 90.699844 -284.863032)
		(width 0.0889)
		(layer "In6.Cu")
		(net "UPI_CPU0_CPU1_P2P2_DN<5>")
	)
	(arc
		(start 352.076512 -284.033722)
		(mid 352.028833 -284.216622)
		(end 351.89795 -284.353)
		(width 0.0889)
		(layer "In6.Cu")
		(net "UPI_CPU0_CPU1_P2P2_DN<5>")
	)
	(arc
		(start 350.479614 -288.427414)
		(mid 350.277328 -288.626395)
		(end 350.197166 -288.898584)
		(width 0.0889)
		(layer "In6.Cu")
		(net "UPI_CPU0_CPU1_P2P2_DN<5>")
	)
	(arc
		(start 89.477596 -288.592768)
		(mid 89.679882 -288.393787)
		(end 89.760044 -288.121598)
		(width 0.0889)
		(layer "In6.Cu")
		(net "UPI_CPU0_CPU1_P2P2_DN<5>")
	)
	(arc
		(start 352.546412 -283.219906)
		(mid 352.498733 -283.402806)
		(end 352.36785 -283.539184)
		(width 0.0889)
		(layer "In6.Cu")
		(net "UPI_CPU0_CPU1_P2P2_DN<5>")
	)
	(arc
		(start 90.41765 -286.964882)
		(mid 90.620473 -286.764651)
		(end 90.699844 -286.490918)
		(width 0.0889)
		(layer "In6.Cu")
		(net "UPI_CPU0_CPU1_P2P2_DN<5>")
	)
	(arc
		(start 89.947496 -281.916378)
		(mid 89.812563 -281.783024)
		(end 89.760298 -281.600656)
		(width 0.0889)
		(layer "In6.Cu")
		(net "UPI_CPU0_CPU1_P2P2_DN<5>")
	)
	(arc
		(start 89.760298 -281.59202)
		(mid 89.700255 -281.338133)
		(end 89.53246 -281.138376)
		(width 0.0889)
		(layer "In6.Cu")
		(net "UPI_CPU0_CPU1_P2P2_DN<5>")
	)
	(arc
		(start 351.41916 -285.171896)
		(mid 351.214825 -285.374501)
		(end 351.136712 -285.651448)
		(width 0.0889)
		(layer "In6.Cu")
		(net "UPI_CPU0_CPU1_P2P2_DN<5>")
	)
	(arc
		(start 350.667066 -288.103056)
		(mid 350.619387 -288.285956)
		(end 350.488504 -288.422334)
		(width 0.0889)
		(layer "In6.Cu")
		(net "UPI_CPU0_CPU1_P2P2_DN<5>")
	)
	(arc
		(start 90.230452 -282.420568)
		(mid 90.230255 -282.413203)
		(end 90.230198 -282.405836)
		(width 0.0889)
		(layer "In6.Cu")
		(net "UPI_CPU0_CPU1_P2P2_DN<5>")
	)
	(arc
		(start 351.606612 -286.48406)
		(mid 351.554342 -286.666425)
		(end 351.419414 -286.799782)
		(width 0.0889)
		(layer "In6.Cu")
		(net "UPI_CPU0_CPU1_P2P2_DN<5>")
	)
	(arc
		(start 351.136712 -287.28924)
		(mid 351.089033 -287.47214)
		(end 350.95815 -287.608518)
		(width 0.0889)
		(layer "In6.Cu")
		(net "UPI_CPU0_CPU1_P2P2_DN<5>")
	)
	(arc
		(start 90.887296 -284.52318)
		(mid 91.169828 -284.033722)
		(end 90.887296 -283.544264)
		(width 0.0889)
		(layer "In6.Cu")
		(net "UPI_CPU0_CPU1_P2P2_DN<5>")
	)
	(arc
		(start 90.699844 -284.847538)
		(mid 90.747523 -284.664638)
		(end 90.878406 -284.52826)
		(width 0.0889)
		(layer "In6.Cu")
		(net "UPI_CPU0_CPU1_P2P2_DN<5>")
	)
	(arc
		(start 351.88906 -284.35808)
		(mid 351.686237 -284.558311)
		(end 351.606866 -284.832044)
		(width 0.0889)
		(layer "In6.Cu")
		(net "UPI_CPU0_CPU1_P2P2_DN<5>")
	)
	(arc
		(start 352.35896 -283.544264)
		(mid 352.154625 -283.746869)
		(end 352.076512 -284.023816)
		(width 0.0889)
		(layer "In6.Cu")
		(net "UPI_CPU0_CPU1_P2P2_DN<5>")
	)
	(arc
		(start 89.959688 -287.771586)
		(mid 90.157916 -287.565738)
		(end 90.230198 -287.28924)
		(width 0.0889)
		(layer "In6.Cu")
		(net "UPI_CPU0_CPU1_P2P2_DN<5>")
	)
	(arc
		(start 90.230198 -282.405836)
		(mid 90.156207 -282.12627)
		(end 89.953592 -281.919934)
		(width 0.0889)
		(layer "In6.Cu")
		(net "UPI_CPU0_CPU1_P2P2_DN<5>")
	)
	(arc
		(start 352.82886 -282.730194)
		(mid 352.625555 -282.93106)
		(end 352.546412 -283.205682)
		(width 0.0889)
		(layer "In6.Cu")
		(net "UPI_CPU0_CPU1_P2P2_DN<5>")
	)
	(arc
		(start 353.015804 -282.420568)
		(mid 352.964872 -282.595107)
		(end 352.83775 -282.725114)
		(width 0.0889)
		(layer "In6.Cu")
		(net "UPI_CPU0_CPU1_P2P2_DN<5>")
	)
	(arc
		(start 351.419414 -286.151066)
		(mid 351.554347 -286.28442)
		(end 351.606612 -286.466788)
		(width 0.0889)
		(layer "In6.Cu")
		(net "UPI_CPU0_CPU1_P2P2_DN<5>")
	)
	(arc
		(start 350.482916 -289.446462)
		(mid 350.591927 -289.53042)
		(end 350.666812 -289.645852)
		(width 0.0889)
		(layer "In6.Cu")
		(net "UPI_CPU0_CPU1_P2P2_DN<5>")
	)
	(arc
		(start 90.878406 -283.539184)
		(mid 90.747492 -283.402824)
		(end 90.699844 -283.219906)
		(width 0.0889)
		(layer "In6.Cu")
		(net "UPI_CPU0_CPU1_P2P2_DN<5>")
	)
	(arc
		(start 350.94926 -287.613598)
		(mid 350.746437 -287.813829)
		(end 350.667066 -288.087562)
		(width 0.0889)
		(layer "In6.Cu")
		(net "UPI_CPU0_CPU1_P2P2_DN<5>")
	)
	(arc
		(start 352.271584 -282.348432)
		(mid 352.332197 -282.19485)
		(end 352.45294 -282.08224)
		(width 0.0889)
		(layer "In6.Cu")
		(net "UPI_CPU0_CPU1_P2P2_DN<5>")
	)
	(arc
		(start 89.760044 -288.103056)
		(mid 89.807723 -287.920156)
		(end 89.938606 -287.783778)
		(width 0.0889)
		(layer "In6.Cu")
		(net "UPI_CPU0_CPU1_P2P2_DN<5>")
	)
	(arc
		(start 90.40876 -285.980632)
		(mid 90.230042 -285.661354)
		(end 90.40876 -285.342076)
		(width 0.0889)
		(layer "In6.Cu")
		(net "UPI_CPU0_CPU1_P2P2_DN<5>")
	)
	(arc
		(start 90.699844 -283.197808)
		(mid 90.618933 -282.92768)
		(end 90.41765 -282.730194)
		(width 0.0889)
		(layer "In6.Cu")
		(net "UPI_CPU0_CPU1_P2P2_DN<5>")
	)
	(arc
		(start 90.40876 -282.725114)
		(mid 90.281506 -282.595148)
		(end 90.230452 -282.420568)
		(width 0.0889)
		(layer "In6.Cu")
		(net "UPI_CPU0_CPU1_P2P2_DN<5>")
	)
	(arc
		(start 350.197166 -289.114738)
		(mid 350.308504 -289.307638)
		(end 350.482662 -289.446462)
		(width 0.0889)
		(layer "In6.Cu")
		(net "UPI_CPU0_CPU1_P2P2_DN<5>")
	)
	(arc
		(start 351.136712 -285.675578)
		(mid 351.215931 -285.950263)
		(end 351.419414 -286.151066)
		(width 0.0889)
		(layer "In6.Cu")
		(net "UPI_CPU0_CPU1_P2P2_DN<5>")
	)
	(arc
		(start 90.230198 -287.28924)
		(mid 90.277877 -287.10634)
		(end 90.40876 -286.969962)
		(width 0.0889)
		(layer "In6.Cu")
		(net "UPI_CPU0_CPU1_P2P2_DN<5>")
	)
	(arc
		(start 89.290398 -288.90849)
		(mid 89.342668 -288.726125)
		(end 89.477596 -288.592768)
		(width 0.0889)
		(layer "In6.Cu")
		(net "UPI_CPU0_CPU1_P2P2_DN<5>")
	)
	(arc
		(start 351.413318 -286.803338)
		(mid 351.210731 -287.009689)
		(end 351.136712 -287.28924)
		(width 0.0889)
		(layer "In6.Cu")
		(net "UPI_CPU0_CPU1_P2P2_DN<5>")
	)
	(arc
		(start 353.016058 -282.395676)
		(mid 353.016138 -282.408124)
		(end 353.015804 -282.420568)
		(width 0.0889)
		(layer "In6.Cu")
		(net "UPI_CPU0_CPU1_P2P2_DN<5>")
	)
	(arc
		(start 352.454464 -282.081478)
		(mid 352.824522 -282.079013)
		(end 353.016058 -282.395676)
		(width 0.0889)
		(layer "In6.Cu")
		(net "UPI_CPU0_CPU1_P2P2_DN<5>")
	)
	(arc
		(start 90.699844 -286.453326)
		(mid 90.618933 -286.183198)
		(end 90.41765 -285.985712)
		(width 0.0889)
		(layer "In6.Cu")
		(net "UPI_CPU0_CPU1_P2P2_DN<5>")
	)
	(segment
		(start 353.581716 -281.869896)
		(end 353.581716 -282.405582)
		(width 0.13208)
		(layer "F.Cu")
		(net "UPI_CPU0_CPU1_P2P2_DN<4>")
	)
	(segment
		(start 353.581716 -282.405582)
		(end 353.581462 -282.405836)
		(width 0.13208)
		(layer "F.Cu")
		(net "UPI_CPU0_CPU1_P2P2_DN<4>")
	)
	(segment
		(start 88.725248 -282.405836)
		(end 88.725248 -281.869896)
		(width 0.13208)
		(layer "F.Cu")
		(net "UPI_CPU0_CPU1_P2P2_DN<4>")
	)
	(segment
		(start 89.569544 -284.847538)
		(end 89.569544 -284.837632)
		(width 0.0889)
		(layer "In6.Cu")
		(net "UPI_CPU0_CPU1_P2P2_DN<4>")
	)
	(segment
		(start 349.21317 -301.035974)
		(end 348.276926 -302.437546)
		(width 0.14732)
		(layer "In6.Cu")
		(net "UPI_CPU0_CPU1_P2P2_DN<4>")
	)
	(segment
		(start 87.220044 -290.991036)
		(end 87.220044 -288.682684)
		(width 0.0889)
		(layer "In6.Cu")
		(net "UPI_CPU0_CPU1_P2P2_DN<4>")
	)
	(segment
		(start 58.497724 -323.468492)
		(end 58.7502 -322.859146)
		(width 0.14732)
		(layer "In6.Cu")
		(net "UPI_CPU0_CPU1_P2P2_DN<4>")
	)
	(segment
		(start 126.855474 -389.62965)
		(end 94.872302 -384.885184)
		(width 0.14732)
		(layer "In6.Cu")
		(net "UPI_CPU0_CPU1_P2P2_DN<4>")
	)
	(segment
		(start 86.821518 -291.330634)
		(end 86.837012 -291.31514)
		(width 0.0889)
		(layer "In6.Cu")
		(net "UPI_CPU0_CPU1_P2P2_DN<4>")
	)
	(segment
		(start 350.149414 -292.385496)
		(end 350.149414 -292.955218)
		(width 0.0889)
		(layer "In6.Cu")
		(net "UPI_CPU0_CPU1_P2P2_DN<4>")
	)
	(segment
		(start 353.206812 -284.033722)
		(end 353.206812 -284.043628)
		(width 0.0889)
		(layer "In6.Cu")
		(net "UPI_CPU0_CPU1_P2P2_DN<4>")
	)
	(segment
		(start 61.28766 -316.718442)
		(end 64.097408 -315.21654)
		(width 0.14732)
		(layer "In6.Cu")
		(net "UPI_CPU0_CPU1_P2P2_DN<4>")
	)
	(segment
		(start 352.454718 -286.964882)
		(end 352.445828 -286.969962)
		(width 0.0889)
		(layer "In6.Cu")
		(net "UPI_CPU0_CPU1_P2P2_DN<4>")
	)
	(segment
		(start 286.595566 -340.06282)
		(end 283.189426 -341.473536)
		(width 0.14732)
		(layer "In6.Cu")
		(net "UPI_CPU0_CPU1_P2P2_DN<4>")
	)
	(segment
		(start 351.514918 -288.592768)
		(end 351.506028 -288.597848)
		(width 0.0889)
		(layer "In6.Cu")
		(net "UPI_CPU0_CPU1_P2P2_DN<4>")
	)
	(segment
		(start 59.760358 -355.584252)
		(end 59.760358 -335.844134)
		(width 0.14732)
		(layer "In6.Cu")
		(net "UPI_CPU0_CPU1_P2P2_DN<4>")
	)
	(segment
		(start 83.660488 -295.814242)
		(end 84.595462 -293.55669)
		(width 0.14732)
		(layer "In6.Cu")
		(net "UPI_CPU0_CPU1_P2P2_DN<4>")
	)
	(segment
		(start 350.149414 -292.955218)
		(end 350.191324 -292.997128)
		(width 0.0889)
		(layer "In6.Cu")
		(net "UPI_CPU0_CPU1_P2P2_DN<4>")
	)
	(segment
		(start 351.990914 -287.775142)
		(end 351.984818 -287.778698)
		(width 0.0889)
		(layer "In6.Cu")
		(net "UPI_CPU0_CPU1_P2P2_DN<4>")
	)
	(segment
		(start 89.102946 -282.470606)
		(end 89.037922 -282.405582)
		(width 0.0889)
		(layer "In6.Cu")
		(net "UPI_CPU0_CPU1_P2P2_DN<4>")
	)
	(segment
		(start 160.839912 -389.62965)
		(end 126.855474 -389.62965)
		(width 0.14732)
		(layer "In6.Cu")
		(net "UPI_CPU0_CPU1_P2P2_DN<4>")
	)
	(segment
		(start 89.381584 -286.80029)
		(end 89.382346 -286.799782)
		(width 0.0889)
		(layer "In6.Cu")
		(net "UPI_CPU0_CPU1_P2P2_DN<4>")
	)
	(segment
		(start 89.860882 -283.714444)
		(end 89.851992 -283.709364)
		(width 0.0889)
		(layer "In6.Cu")
		(net "UPI_CPU0_CPU1_P2P2_DN<4>")
	)
	(segment
		(start 82.76717 -297.97121)
		(end 83.660488 -295.814242)
		(width 0.14732)
		(layer "In6.Cu")
		(net "UPI_CPU0_CPU1_P2P2_DN<4>")
	)
	(segment
		(start 352.46056 -285.33344)
		(end 352.445574 -285.342076)
		(width 0.0889)
		(layer "In6.Cu")
		(net "UPI_CPU0_CPU1_P2P2_DN<4>")
	)
	(segment
		(start 89.851992 -284.35808)
		(end 89.860882 -284.353)
		(width 0.0889)
		(layer "In6.Cu")
		(net "UPI_CPU0_CPU1_P2P2_DN<4>")
	)
	(segment
		(start 340.70417 -308.279038)
		(end 340.703916 -308.279038)
		(width 0.14732)
		(layer "In6.Cu")
		(net "UPI_CPU0_CPU1_P2P2_DN<4>")
	)
	(segment
		(start 352.453702 -285.985204)
		(end 352.454464 -285.985712)
		(width 0.0889)
		(layer "In6.Cu")
		(net "UPI_CPU0_CPU1_P2P2_DN<4>")
	)
	(segment
		(start 351.797112 -289.60953)
		(end 351.797112 -290.737798)
		(width 0.0889)
		(layer "In6.Cu")
		(net "UPI_CPU0_CPU1_P2P2_DN<4>")
	)
	(segment
		(start 319.806066 -330.238862)
		(end 309.982108 -340.06282)
		(width 0.14732)
		(layer "In6.Cu")
		(net "UPI_CPU0_CPU1_P2P2_DN<4>")
	)
	(segment
		(start 352.460814 -286.961326)
		(end 352.454718 -286.964882)
		(width 0.0889)
		(layer "In6.Cu")
		(net "UPI_CPU0_CPU1_P2P2_DN<4>")
	)
	(segment
		(start 58.989214 -319.017142)
		(end 61.28766 -316.718188)
		(width 0.14732)
		(layer "In6.Cu")
		(net "UPI_CPU0_CPU1_P2P2_DN<4>")
	)
	(segment
		(start 320.95059 -327.475342)
		(end 319.806066 -330.238862)
		(width 0.14732)
		(layer "In6.Cu")
		(net "UPI_CPU0_CPU1_P2P2_DN<4>")
	)
	(segment
		(start 353.581462 -282.405836)
		(end 353.424998 -282.676854)
		(width 0.0889)
		(layer "In6.Cu")
		(net "UPI_CPU0_CPU1_P2P2_DN<4>")
	)
	(segment
		(start 351.327466 -288.917126)
		(end 351.327466 -289.078416)
		(width 0.0889)
		(layer "In6.Cu")
		(net "UPI_CPU0_CPU1_P2P2_DN<4>")
	)
	(segment
		(start 352.445574 -285.980632)
		(end 352.453702 -285.985204)
		(width 0.0889)
		(layer "In6.Cu")
		(net "UPI_CPU0_CPU1_P2P2_DN<4>")
	)
	(segment
		(start 352.737166 -286.467804)
		(end 352.737166 -286.475424)
		(width 0.0889)
		(layer "In6.Cu")
		(net "UPI_CPU0_CPU1_P2P2_DN<4>")
	)
	(segment
		(start 57.43956 -324.526656)
		(end 58.497724 -323.468492)
		(width 0.14732)
		(layer "In6.Cu")
		(net "UPI_CPU0_CPU1_P2P2_DN<4>")
	)
	(segment
		(start 70.839584 -374.93067)
		(end 65.606168 -369.697254)
		(width 0.14732)
		(layer "In6.Cu")
		(net "UPI_CPU0_CPU1_P2P2_DN<4>")
	)
	(segment
		(start 351.984818 -287.778698)
		(end 351.975928 -287.783778)
		(width 0.0889)
		(layer "In6.Cu")
		(net "UPI_CPU0_CPU1_P2P2_DN<4>")
	)
	(segment
		(start 89.382092 -285.171896)
		(end 89.390982 -285.166816)
		(width 0.0889)
		(layer "In6.Cu")
		(net "UPI_CPU0_CPU1_P2P2_DN<4>")
	)
	(segment
		(start 89.37625 -286.803338)
		(end 89.381584 -286.80029)
		(width 0.0889)
		(layer "In6.Cu")
		(net "UPI_CPU0_CPU1_P2P2_DN<4>")
	)
	(segment
		(start 350.191324 -293.019226)
		(end 350.191324 -297.811444)
		(width 0.14732)
		(layer "In6.Cu")
		(net "UPI_CPU0_CPU1_P2P2_DN<4>")
	)
	(segment
		(start 84.595462 -293.55669)
		(end 86.821518 -291.330634)
		(width 0.14732)
		(layer "In6.Cu")
		(net "UPI_CPU0_CPU1_P2P2_DN<4>")
	)
	(segment
		(start 94.872302 -384.885184)
		(end 70.839584 -374.93067)
		(width 0.14732)
		(layer "In6.Cu")
		(net "UPI_CPU0_CPU1_P2P2_DN<4>")
	)
	(segment
		(start 277.410672 -347.25229)
		(end 277.410672 -371.062504)
		(width 0.14732)
		(layer "In6.Cu")
		(net "UPI_CPU0_CPU1_P2P2_DN<4>")
	)
	(segment
		(start 87.220044 -288.682684)
		(end 87.385398 -288.51733)
		(width 0.0889)
		(layer "In6.Cu")
		(net "UPI_CPU0_CPU1_P2P2_DN<4>")
	)
	(segment
		(start 353.40036 -283.705808)
		(end 353.397058 -283.70784)
		(width 0.0889)
		(layer "In6.Cu")
		(net "UPI_CPU0_CPU1_P2P2_DN<4>")
	)
	(segment
		(start 277.410672 -371.062504)
		(end 267.881608 -380.591568)
		(width 0.14732)
		(layer "In6.Cu")
		(net "UPI_CPU0_CPU1_P2P2_DN<4>")
	)
	(segment
		(start 87.689944 -288.103056)
		(end 87.689944 -288.09315)
		(width 0.0889)
		(layer "In6.Cu")
		(net "UPI_CPU0_CPU1_P2P2_DN<4>")
	)
	(segment
		(start 339.752686 -308.673246)
		(end 320.95059 -327.475342)
		(width 0.14732)
		(layer "In6.Cu")
		(net "UPI_CPU0_CPU1_P2P2_DN<4>")
	)
	(segment
		(start 350.191324 -292.997128)
		(end 350.191324 -293.019226)
		(width 0.0889)
		(layer "In6.Cu")
		(net "UPI_CPU0_CPU1_P2P2_DN<4>")
	)
	(segment
		(start 283.189426 -341.473536)
		(end 277.410672 -347.25229)
		(width 0.14732)
		(layer "In6.Cu")
		(net "UPI_CPU0_CPU1_P2P2_DN<4>")
	)
	(segment
		(start 86.837012 -291.31514)
		(end 86.89594 -291.31514)
		(width 0.0889)
		(layer "In6.Cu")
		(net "UPI_CPU0_CPU1_P2P2_DN<4>")
	)
	(segment
		(start 61.28766 -316.718188)
		(end 61.28766 -316.718442)
		(width 0.14732)
		(layer "In6.Cu")
		(net "UPI_CPU0_CPU1_P2P2_DN<4>")
	)
	(segment
		(start 65.254124 -314.060078)
		(end 67.684904 -313.053476)
		(width 0.14732)
		(layer "In6.Cu")
		(net "UPI_CPU0_CPU1_P2P2_DN<4>")
	)
	(segment
		(start 348.276926 -302.437546)
		(end 343.660222 -307.05425)
		(width 0.14732)
		(layer "In6.Cu")
		(net "UPI_CPU0_CPU1_P2P2_DN<4>")
	)
	(segment
		(start 352.737166 -284.838902)
		(end 352.737166 -284.847538)
		(width 0.0889)
		(layer "In6.Cu")
		(net "UPI_CPU0_CPU1_P2P2_DN<4>")
	)
	(segment
		(start 353.424998 -282.676854)
		(end 353.449128 -282.766008)
		(width 0.0889)
		(layer "In6.Cu")
		(net "UPI_CPU0_CPU1_P2P2_DN<4>")
	)
	(segment
		(start 351.797366 -288.103056)
		(end 351.797366 -288.121598)
		(width 0.0889)
		(layer "In6.Cu")
		(net "UPI_CPU0_CPU1_P2P2_DN<4>")
	)
	(segment
		(start 58.7502 -322.859146)
		(end 58.7502 -319.374774)
		(width 0.14732)
		(layer "In6.Cu")
		(net "UPI_CPU0_CPU1_P2P2_DN<4>")
	)
	(segment
		(start 353.676966 -283.205682)
		(end 353.676966 -283.219906)
		(width 0.0889)
		(layer "In6.Cu")
		(net "UPI_CPU0_CPU1_P2P2_DN<4>")
	)
	(segment
		(start 353.397058 -283.70784)
		(end 353.394264 -283.709364)
		(width 0.0889)
		(layer "In6.Cu")
		(net "UPI_CPU0_CPU1_P2P2_DN<4>")
	)
	(segment
		(start 267.881608 -380.591568)
		(end 160.839912 -389.62965)
		(width 0.14732)
		(layer "In6.Cu")
		(net "UPI_CPU0_CPU1_P2P2_DN<4>")
	)
	(segment
		(start 89.037922 -282.405582)
		(end 88.725502 -282.405582)
		(width 0.0889)
		(layer "In6.Cu")
		(net "UPI_CPU0_CPU1_P2P2_DN<4>")
	)
	(segment
		(start 57.43956 -330.237592)
		(end 57.43956 -324.526656)
		(width 0.14732)
		(layer "In6.Cu")
		(net "UPI_CPU0_CPU1_P2P2_DN<4>")
	)
	(segment
		(start 67.684904 -313.053476)
		(end 82.76717 -297.97121)
		(width 0.14732)
		(layer "In6.Cu")
		(net "UPI_CPU0_CPU1_P2P2_DN<4>")
	)
	(segment
		(start 86.89594 -291.31514)
		(end 87.220044 -290.991036)
		(width 0.0889)
		(layer "In6.Cu")
		(net "UPI_CPU0_CPU1_P2P2_DN<4>")
	)
	(segment
		(start 343.660222 -307.05425)
		(end 340.70417 -308.279038)
		(width 0.14732)
		(layer "In6.Cu")
		(net "UPI_CPU0_CPU1_P2P2_DN<4>")
	)
	(segment
		(start 89.390982 -282.900628)
		(end 89.382092 -282.895548)
		(width 0.0889)
		(layer "In6.Cu")
		(net "UPI_CPU0_CPU1_P2P2_DN<4>")
	)
	(segment
		(start 59.760358 -335.844134)
		(end 57.43956 -330.237592)
		(width 0.14732)
		(layer "In6.Cu")
		(net "UPI_CPU0_CPU1_P2P2_DN<4>")
	)
	(segment
		(start 88.725502 -282.405582)
		(end 88.725248 -282.405836)
		(width 0.0889)
		(layer "In6.Cu")
		(net "UPI_CPU0_CPU1_P2P2_DN<4>")
	)
	(segment
		(start 351.797112 -290.737798)
		(end 350.149414 -292.385496)
		(width 0.0889)
		(layer "In6.Cu")
		(net "UPI_CPU0_CPU1_P2P2_DN<4>")
	)
	(segment
		(start 309.982108 -340.06282)
		(end 286.595566 -340.06282)
		(width 0.14732)
		(layer "In6.Cu")
		(net "UPI_CPU0_CPU1_P2P2_DN<4>")
	)
	(segment
		(start 64.097408 -315.21654)
		(end 65.254124 -314.060078)
		(width 0.14732)
		(layer "In6.Cu")
		(net "UPI_CPU0_CPU1_P2P2_DN<4>")
	)
	(segment
		(start 89.569544 -283.229812)
		(end 89.569544 -283.219906)
		(width 0.0889)
		(layer "In6.Cu")
		(net "UPI_CPU0_CPU1_P2P2_DN<4>")
	)
	(segment
		(start 353.394264 -283.709364)
		(end 353.39274 -283.710126)
		(width 0.0889)
		(layer "In6.Cu")
		(net "UPI_CPU0_CPU1_P2P2_DN<4>")
	)
	(segment
		(start 350.191324 -297.811444)
		(end 349.21317 -301.035974)
		(width 0.14732)
		(layer "In6.Cu")
		(net "UPI_CPU0_CPU1_P2P2_DN<4>")
	)
	(segment
		(start 353.39274 -283.710126)
		(end 353.385374 -283.714444)
		(width 0.0889)
		(layer "In6.Cu")
		(net "UPI_CPU0_CPU1_P2P2_DN<4>")
	)
	(segment
		(start 58.7502 -319.374774)
		(end 58.989214 -319.017142)
		(width 0.14732)
		(layer "In6.Cu")
		(net "UPI_CPU0_CPU1_P2P2_DN<4>")
	)
	(segment
		(start 340.703916 -308.279038)
		(end 339.752686 -308.673246)
		(width 0.14732)
		(layer "In6.Cu")
		(net "UPI_CPU0_CPU1_P2P2_DN<4>")
	)
	(segment
		(start 65.606168 -369.697254)
		(end 59.760358 -355.584252)
		(width 0.14732)
		(layer "In6.Cu")
		(net "UPI_CPU0_CPU1_P2P2_DN<4>")
	)
	(arc
		(start 351.506028 -288.597848)
		(mid 351.375114 -288.734208)
		(end 351.327466 -288.917126)
		(width 0.0889)
		(layer "In6.Cu")
		(net "UPI_CPU0_CPU1_P2P2_DN<4>")
	)
	(arc
		(start 352.454464 -285.985712)
		(mid 352.659536 -286.189391)
		(end 352.737166 -286.467804)
		(width 0.0889)
		(layer "In6.Cu")
		(net "UPI_CPU0_CPU1_P2P2_DN<4>")
	)
	(arc
		(start 89.569544 -284.837632)
		(mid 89.647655 -284.560683)
		(end 89.851992 -284.35808)
		(width 0.0889)
		(layer "In6.Cu")
		(net "UPI_CPU0_CPU1_P2P2_DN<4>")
	)
	(arc
		(start 353.449128 -282.766008)
		(mid 353.457699 -282.772404)
		(end 353.466146 -282.778962)
		(width 0.0889)
		(layer "In6.Cu")
		(net "UPI_CPU0_CPU1_P2P2_DN<4>")
	)
	(arc
		(start 353.385374 -283.714444)
		(mid 353.25446 -283.850804)
		(end 353.206812 -284.033722)
		(width 0.0889)
		(layer "In6.Cu")
		(net "UPI_CPU0_CPU1_P2P2_DN<4>")
	)
	(arc
		(start 351.327466 -289.078416)
		(mid 351.402471 -289.193875)
		(end 351.511616 -289.277806)
		(width 0.0889)
		(layer "In6.Cu")
		(net "UPI_CPU0_CPU1_P2P2_DN<4>")
	)
	(arc
		(start 89.099644 -287.28924)
		(mid 89.173635 -287.009674)
		(end 89.37625 -286.803338)
		(width 0.0889)
		(layer "In6.Cu")
		(net "UPI_CPU0_CPU1_P2P2_DN<4>")
	)
	(arc
		(start 89.382346 -286.151066)
		(mid 89.099467 -285.661527)
		(end 89.382092 -285.171896)
		(width 0.0889)
		(layer "In6.Cu")
		(net "UPI_CPU0_CPU1_P2P2_DN<4>")
	)
	(arc
		(start 89.569544 -283.219906)
		(mid 89.521865 -283.037006)
		(end 89.390982 -282.900628)
		(width 0.0889)
		(layer "In6.Cu")
		(net "UPI_CPU0_CPU1_P2P2_DN<4>")
	)
	(arc
		(start 352.924364 -284.52318)
		(mid 352.789431 -284.656534)
		(end 352.737166 -284.838902)
		(width 0.0889)
		(layer "In6.Cu")
		(net "UPI_CPU0_CPU1_P2P2_DN<4>")
	)
	(arc
		(start 352.445828 -286.969962)
		(mid 352.314914 -287.106322)
		(end 352.267266 -287.28924)
		(width 0.0889)
		(layer "In6.Cu")
		(net "UPI_CPU0_CPU1_P2P2_DN<4>")
	)
	(arc
		(start 89.390982 -285.166816)
		(mid 89.521896 -285.030456)
		(end 89.569544 -284.847538)
		(width 0.0889)
		(layer "In6.Cu")
		(net "UPI_CPU0_CPU1_P2P2_DN<4>")
	)
	(arc
		(start 88.537796 -287.613598)
		(mid 88.912271 -287.613552)
		(end 89.099644 -287.28924)
		(width 0.0889)
		(layer "In6.Cu")
		(net "UPI_CPU0_CPU1_P2P2_DN<4>")
	)
	(arc
		(start 89.851992 -283.709364)
		(mid 89.647657 -283.506759)
		(end 89.569544 -283.229812)
		(width 0.0889)
		(layer "In6.Cu")
		(net "UPI_CPU0_CPU1_P2P2_DN<4>")
	)
	(arc
		(start 351.797366 -288.121598)
		(mid 351.717204 -288.393787)
		(end 351.514918 -288.592768)
		(width 0.0889)
		(layer "In6.Cu")
		(net "UPI_CPU0_CPU1_P2P2_DN<4>")
	)
	(arc
		(start 87.972392 -287.613598)
		(mid 88.255094 -287.537822)
		(end 88.537796 -287.613598)
		(width 0.0889)
		(layer "In6.Cu")
		(net "UPI_CPU0_CPU1_P2P2_DN<4>")
	)
	(arc
		(start 352.737166 -286.475424)
		(mid 352.66325 -286.754926)
		(end 352.460814 -286.961326)
		(width 0.0889)
		(layer "In6.Cu")
		(net "UPI_CPU0_CPU1_P2P2_DN<4>")
	)
	(arc
		(start 89.860882 -284.353)
		(mid 90.039479 -284.033722)
		(end 89.860882 -283.714444)
		(width 0.0889)
		(layer "In6.Cu")
		(net "UPI_CPU0_CPU1_P2P2_DN<4>")
	)
	(arc
		(start 89.382346 -286.799782)
		(mid 89.569649 -286.475424)
		(end 89.382346 -286.151066)
		(width 0.0889)
		(layer "In6.Cu")
		(net "UPI_CPU0_CPU1_P2P2_DN<4>")
	)
	(arc
		(start 351.511616 -289.277806)
		(mid 351.685748 -289.416653)
		(end 351.797112 -289.60953)
		(width 0.0889)
		(layer "In6.Cu")
		(net "UPI_CPU0_CPU1_P2P2_DN<4>")
	)
	(arc
		(start 87.511382 -288.422334)
		(mid 87.642296 -288.285974)
		(end 87.689944 -288.103056)
		(width 0.0889)
		(layer "In6.Cu")
		(net "UPI_CPU0_CPU1_P2P2_DN<4>")
	)
	(arc
		(start 353.206812 -284.043628)
		(mid 353.128701 -284.320577)
		(end 352.924364 -284.52318)
		(width 0.0889)
		(layer "In6.Cu")
		(net "UPI_CPU0_CPU1_P2P2_DN<4>")
	)
	(arc
		(start 89.382092 -282.895548)
		(mid 89.198197 -282.725251)
		(end 89.105994 -282.492196)
		(width 0.0889)
		(layer "In6.Cu")
		(net "UPI_CPU0_CPU1_P2P2_DN<4>")
	)
	(arc
		(start 352.737166 -284.847538)
		(mid 352.663175 -285.127104)
		(end 352.46056 -285.33344)
		(width 0.0889)
		(layer "In6.Cu")
		(net "UPI_CPU0_CPU1_P2P2_DN<4>")
	)
	(arc
		(start 353.466146 -282.778962)
		(mid 353.618633 -282.969058)
		(end 353.676966 -283.205682)
		(width 0.0889)
		(layer "In6.Cu")
		(net "UPI_CPU0_CPU1_P2P2_DN<4>")
	)
	(arc
		(start 89.105994 -282.492196)
		(mid 89.104364 -282.481416)
		(end 89.102946 -282.470606)
		(width 0.0889)
		(layer "In6.Cu")
		(net "UPI_CPU0_CPU1_P2P2_DN<4>")
	)
	(arc
		(start 351.975928 -287.783778)
		(mid 351.845014 -287.920138)
		(end 351.797366 -288.103056)
		(width 0.0889)
		(layer "In6.Cu")
		(net "UPI_CPU0_CPU1_P2P2_DN<4>")
	)
	(arc
		(start 352.267266 -287.28924)
		(mid 352.19335 -287.568742)
		(end 351.990914 -287.775142)
		(width 0.0889)
		(layer "In6.Cu")
		(net "UPI_CPU0_CPU1_P2P2_DN<4>")
	)
	(arc
		(start 87.689944 -288.09315)
		(mid 87.768055 -287.816201)
		(end 87.972392 -287.613598)
		(width 0.0889)
		(layer "In6.Cu")
		(net "UPI_CPU0_CPU1_P2P2_DN<4>")
	)
	(arc
		(start 353.676966 -283.219906)
		(mid 353.602975 -283.499472)
		(end 353.40036 -283.705808)
		(width 0.0889)
		(layer "In6.Cu")
		(net "UPI_CPU0_CPU1_P2P2_DN<4>")
	)
	(arc
		(start 352.445574 -285.342076)
		(mid 352.266977 -285.661354)
		(end 352.445574 -285.980632)
		(width 0.0889)
		(layer "In6.Cu")
		(net "UPI_CPU0_CPU1_P2P2_DN<4>")
	)
	(arc
		(start 87.385398 -288.51733)
		(mid 87.445061 -288.465418)
		(end 87.511382 -288.422334)
		(width 0.0889)
		(layer "In6.Cu")
		(net "UPI_CPU0_CPU1_P2P2_DN<4>")
	)
	(segment
		(start 353.111816 -279.428448)
		(end 353.111816 -279.964134)
		(width 0.13208)
		(layer "F.Cu")
		(net "UPI_CPU0_CPU1_P2P2_DN<3>")
	)
	(segment
		(start 89.194894 -279.428194)
		(end 89.194894 -279.964134)
		(width 0.13208)
		(layer "F.Cu")
		(net "UPI_CPU0_CPU1_P2P2_DN<3>")
	)
	(segment
		(start 353.111562 -279.428194)
		(end 353.111816 -279.428448)
		(width 0.13208)
		(layer "F.Cu")
		(net "UPI_CPU0_CPU1_P2P2_DN<3>")
	)
	(segment
		(start 57.344564 -319.000378)
		(end 57.344564 -318.455548)
		(width 0.14732)
		(layer "In6.Cu")
		(net "UPI_CPU0_CPU1_P2P2_DN<3>")
	)
	(segment
		(start 55.08117 -323.385688)
		(end 55.387748 -323.181218)
		(width 0.14732)
		(layer "In6.Cu")
		(net "UPI_CPU0_CPU1_P2P2_DN<3>")
	)
	(segment
		(start 59.12104 -316.639448)
		(end 59.480958 -316.27953)
		(width 0.14732)
		(layer "In6.Cu")
		(net "UPI_CPU0_CPU1_P2P2_DN<3>")
	)
	(segment
		(start 352.267266 -288.917126)
		(end 352.267266 -289.078416)
		(width 0.0889)
		(layer "In6.Cu")
		(net "UPI_CPU0_CPU1_P2P2_DN<3>")
	)
	(segment
		(start 88.159844 -282.42006)
		(end 88.159844 -282.405836)
		(width 0.0889)
		(layer "In6.Cu")
		(net "UPI_CPU0_CPU1_P2P2_DN<3>")
	)
	(segment
		(start 53.32476 -325.159116)
		(end 53.91785 -324.566026)
		(width 0.14732)
		(layer "In6.Cu")
		(net "UPI_CPU0_CPU1_P2P2_DN<3>")
	)
	(segment
		(start 161.086546 -390.47293)
		(end 126.803404 -390.47293)
		(width 0.14732)
		(layer "In6.Cu")
		(net "UPI_CPU0_CPU1_P2P2_DN<3>")
	)
	(segment
		(start 351.118424 -293.802054)
		(end 351.11817 -293.802308)
		(width 0.14732)
		(layer "In6.Cu")
		(net "UPI_CPU0_CPU1_P2P2_DN<3>")
	)
	(segment
		(start 354.340414 -283.705808)
		(end 354.334318 -283.709364)
		(width 0.0889)
		(layer "In6.Cu")
		(net "UPI_CPU0_CPU1_P2P2_DN<3>")
	)
	(segment
		(start 86.459314 -288.613088)
		(end 86.750398 -288.322004)
		(width 0.0889)
		(layer "In6.Cu")
		(net "UPI_CPU0_CPU1_P2P2_DN<3>")
	)
	(segment
		(start 351.07626 -292.76675)
		(end 351.07626 -293.511224)
		(width 0.0889)
		(layer "In6.Cu")
		(net "UPI_CPU0_CPU1_P2P2_DN<3>")
	)
	(segment
		(start 59.480958 -316.27953)
		(end 62.233302 -314.440062)
		(width 0.14732)
		(layer "In6.Cu")
		(net "UPI_CPU0_CPU1_P2P2_DN<3>")
	)
	(segment
		(start 353.676966 -286.456882)
		(end 353.676966 -286.48533)
		(width 0.0889)
		(layer "In6.Cu")
		(net "UPI_CPU0_CPU1_P2P2_DN<3>")
	)
	(segment
		(start 88.451182 -286.156146)
		(end 88.443054 -286.151574)
		(width 0.0889)
		(layer "In6.Cu")
		(net "UPI_CPU0_CPU1_P2P2_DN<3>")
	)
	(segment
		(start 59.12104 -317.371222)
		(end 59.12104 -316.639448)
		(width 0.14732)
		(layer "In6.Cu")
		(net "UPI_CPU0_CPU1_P2P2_DN<3>")
	)
	(segment
		(start 353.111816 -279.964134)
		(end 352.955352 -280.235152)
		(width 0.0889)
		(layer "In6.Cu")
		(net "UPI_CPU0_CPU1_P2P2_DN<3>")
	)
	(segment
		(start 88.912446 -283.709364)
		(end 88.911684 -283.708856)
		(width 0.0889)
		(layer "In6.Cu")
		(net "UPI_CPU0_CPU1_P2P2_DN<3>")
	)
	(segment
		(start 58.929778 -336.201512)
		(end 58.02376 -334.014064)
		(width 0.14732)
		(layer "In6.Cu")
		(net "UPI_CPU0_CPU1_P2P2_DN<3>")
	)
	(segment
		(start 86.417404 -289.257486)
		(end 86.417404 -289.235388)
		(width 0.0889)
		(layer "In6.Cu")
		(net "UPI_CPU0_CPU1_P2P2_DN<3>")
	)
	(segment
		(start 88.442292 -285.171896)
		(end 88.451182 -285.166816)
		(width 0.0889)
		(layer "In6.Cu")
		(net "UPI_CPU0_CPU1_P2P2_DN<3>")
	)
	(segment
		(start 352.955352 -280.235152)
		(end 352.979482 -280.324306)
		(width 0.0889)
		(layer "In6.Cu")
		(net "UPI_CPU0_CPU1_P2P2_DN<3>")
	)
	(segment
		(start 353.393502 -285.337504)
		(end 353.385628 -285.342076)
		(width 0.0889)
		(layer "In6.Cu")
		(net "UPI_CPU0_CPU1_P2P2_DN<3>")
	)
	(segment
		(start 57.344564 -319.658238)
		(end 57.199784 -319.513458)
		(width 0.14732)
		(layer "In6.Cu")
		(net "UPI_CPU0_CPU1_P2P2_DN<3>")
	)
	(segment
		(start 62.233048 -314.440062)
		(end 62.255654 -314.425076)
		(width 0.14732)
		(layer "In6.Cu")
		(net "UPI_CPU0_CPU1_P2P2_DN<3>")
	)
	(segment
		(start 352.736912 -289.60953)
		(end 352.736912 -290.419536)
		(width 0.0889)
		(layer "In6.Cu")
		(net "UPI_CPU0_CPU1_P2P2_DN<3>")
	)
	(segment
		(start 57.344564 -318.455548)
		(end 58.07837 -317.721742)
		(width 0.14732)
		(layer "In6.Cu")
		(net "UPI_CPU0_CPU1_P2P2_DN<3>")
	)
	(segment
		(start 57.344564 -321.634612)
		(end 57.344564 -319.658238)
		(width 0.14732)
		(layer "In6.Cu")
		(net "UPI_CPU0_CPU1_P2P2_DN<3>")
	)
	(segment
		(start 86.417404 -289.235388)
		(end 86.459314 -289.193478)
		(width 0.0889)
		(layer "In6.Cu")
		(net "UPI_CPU0_CPU1_P2P2_DN<3>")
	)
	(segment
		(start 353.855528 -281.911298)
		(end 353.864418 -281.916378)
		(width 0.0889)
		(layer "In6.Cu")
		(net "UPI_CPU0_CPU1_P2P2_DN<3>")
	)
	(segment
		(start 352.737166 -288.103056)
		(end 352.737166 -288.121598)
		(width 0.0889)
		(layer "In6.Cu")
		(net "UPI_CPU0_CPU1_P2P2_DN<3>")
	)
	(segment
		(start 353.385628 -285.980632)
		(end 353.394518 -285.985712)
		(width 0.0889)
		(layer "In6.Cu")
		(net "UPI_CPU0_CPU1_P2P2_DN<3>")
	)
	(segment
		(start 354.334318 -283.709364)
		(end 354.325428 -283.714444)
		(width 0.0889)
		(layer "In6.Cu")
		(net "UPI_CPU0_CPU1_P2P2_DN<3>")
	)
	(segment
		(start 54.605936 -323.877686)
		(end 55.041292 -323.586856)
		(width 0.14732)
		(layer "In6.Cu")
		(net "UPI_CPU0_CPU1_P2P2_DN<3>")
	)
	(segment
		(start 353.206812 -280.763726)
		(end 353.207066 -280.77795)
		(width 0.0889)
		(layer "In6.Cu")
		(net "UPI_CPU0_CPU1_P2P2_DN<3>")
	)
	(segment
		(start 352.736912 -290.419536)
		(end 352.736658 -290.41979)
		(width 0.0889)
		(layer "In6.Cu")
		(net "UPI_CPU0_CPU1_P2P2_DN<3>")
	)
	(segment
		(start 87.220044 -287.28924)
		(end 87.220044 -287.279334)
		(width 0.0889)
		(layer "In6.Cu")
		(net "UPI_CPU0_CPU1_P2P2_DN<3>")
	)
	(segment
		(start 320.478912 -330.839572)
		(end 310.427624 -340.89086)
		(width 0.14732)
		(layer "In6.Cu")
		(net "UPI_CPU0_CPU1_P2P2_DN<3>")
	)
	(segment
		(start 58.77052 -317.721742)
		(end 59.12104 -317.371222)
		(width 0.14732)
		(layer "In6.Cu")
		(net "UPI_CPU0_CPU1_P2P2_DN<3>")
	)
	(segment
		(start 353.676712 -284.847538)
		(end 353.676712 -284.863032)
		(width 0.0889)
		(layer "In6.Cu")
		(net "UPI_CPU0_CPU1_P2P2_DN<3>")
	)
	(segment
		(start 353.864418 -281.916378)
		(end 353.870514 -281.919934)
		(width 0.0889)
		(layer "In6.Cu")
		(net "UPI_CPU0_CPU1_P2P2_DN<3>")
	)
	(segment
		(start 351.07626 -293.511224)
		(end 351.118424 -293.553388)
		(width 0.0889)
		(layer "In6.Cu")
		(net "UPI_CPU0_CPU1_P2P2_DN<3>")
	)
	(segment
		(start 278.238712 -371.428264)
		(end 268.242542 -381.424434)
		(width 0.14732)
		(layer "In6.Cu")
		(net "UPI_CPU0_CPU1_P2P2_DN<3>")
	)
	(segment
		(start 58.07837 -317.721742)
		(end 58.77052 -317.721742)
		(width 0.14732)
		(layer "In6.Cu")
		(net "UPI_CPU0_CPU1_P2P2_DN<3>")
	)
	(segment
		(start 353.864164 -284.52318)
		(end 353.855274 -284.52826)
		(width 0.0889)
		(layer "In6.Cu")
		(net "UPI_CPU0_CPU1_P2P2_DN<3>")
	)
	(segment
		(start 126.803404 -390.47293)
		(end 94.664022 -385.705604)
		(width 0.14732)
		(layer "In6.Cu")
		(net "UPI_CPU0_CPU1_P2P2_DN<3>")
	)
	(segment
		(start 55.041292 -323.586856)
		(end 55.08117 -323.385688)
		(width 0.14732)
		(layer "In6.Cu")
		(net "UPI_CPU0_CPU1_P2P2_DN<3>")
	)
	(segment
		(start 55.588408 -323.221096)
		(end 56.098694 -322.880228)
		(width 0.14732)
		(layer "In6.Cu")
		(net "UPI_CPU0_CPU1_P2P2_DN<3>")
	)
	(segment
		(start 53.32476 -328.17054)
		(end 53.32476 -325.159116)
		(width 0.14732)
		(layer "In6.Cu")
		(net "UPI_CPU0_CPU1_P2P2_DN<3>")
	)
	(segment
		(start 89.564972 -280.021538)
		(end 89.507568 -279.964134)
		(width 0.0889)
		(layer "In6.Cu")
		(net "UPI_CPU0_CPU1_P2P2_DN<3>")
	)
	(segment
		(start 286.760666 -340.89086)
		(end 284.037786 -342.018874)
		(width 0.14732)
		(layer "In6.Cu")
		(net "UPI_CPU0_CPU1_P2P2_DN<3>")
	)
	(segment
		(start 83.559142 -293.553388)
		(end 83.559396 -293.553388)
		(width 0.14732)
		(layer "In6.Cu")
		(net "UPI_CPU0_CPU1_P2P2_DN<3>")
	)
	(segment
		(start 87.032592 -287.613598)
		(end 87.033354 -287.61309)
		(width 0.0889)
		(layer "In6.Cu")
		(net "UPI_CPU0_CPU1_P2P2_DN<3>")
	)
	(segment
		(start 86.459314 -289.193478)
		(end 86.459314 -288.613088)
		(width 0.0889)
		(layer "In6.Cu")
		(net "UPI_CPU0_CPU1_P2P2_DN<3>")
	)
	(segment
		(start 88.911684 -284.358588)
		(end 88.912446 -284.35808)
		(width 0.0889)
		(layer "In6.Cu")
		(net "UPI_CPU0_CPU1_P2P2_DN<3>")
	)
	(segment
		(start 353.394518 -285.336996)
		(end 353.393502 -285.337504)
		(width 0.0889)
		(layer "In6.Cu")
		(net "UPI_CPU0_CPU1_P2P2_DN<3>")
	)
	(segment
		(start 352.736658 -291.106352)
		(end 351.07626 -292.76675)
		(width 0.0889)
		(layer "In6.Cu")
		(net "UPI_CPU0_CPU1_P2P2_DN<3>")
	)
	(segment
		(start 94.664022 -385.705604)
		(end 70.380606 -375.646696)
		(width 0.14732)
		(layer "In6.Cu")
		(net "UPI_CPU0_CPU1_P2P2_DN<3>")
	)
	(segment
		(start 89.382854 -280.287984)
		(end 89.390982 -280.283412)
		(width 0.0889)
		(layer "In6.Cu")
		(net "UPI_CPU0_CPU1_P2P2_DN<3>")
	)
	(segment
		(start 63.356236 -313.969146)
		(end 64.383666 -312.941716)
		(width 0.14732)
		(layer "In6.Cu")
		(net "UPI_CPU0_CPU1_P2P2_DN<3>")
	)
	(segment
		(start 62.233302 -314.440062)
		(end 62.233048 -314.440062)
		(width 0.14732)
		(layer "In6.Cu")
		(net "UPI_CPU0_CPU1_P2P2_DN<3>")
	)
	(segment
		(start 351.11817 -299.264832)
		(end 350.047306 -301.850552)
		(width 0.14732)
		(layer "In6.Cu")
		(net "UPI_CPU0_CPU1_P2P2_DN<3>")
	)
	(segment
		(start 88.906096 -281.106118)
		(end 88.912192 -281.102562)
		(width 0.0889)
		(layer "In6.Cu")
		(net "UPI_CPU0_CPU1_P2P2_DN<3>")
	)
	(segment
		(start 89.382092 -280.288492)
		(end 89.382854 -280.287984)
		(width 0.0889)
		(layer "In6.Cu")
		(net "UPI_CPU0_CPU1_P2P2_DN<3>")
	)
	(segment
		(start 68.152518 -311.380632)
		(end 81.84769 -297.68546)
		(width 0.14732)
		(layer "In6.Cu")
		(net "UPI_CPU0_CPU1_P2P2_DN<3>")
	)
	(segment
		(start 88.90635 -284.361636)
		(end 88.911684 -284.358588)
		(width 0.0889)
		(layer "In6.Cu")
		(net "UPI_CPU0_CPU1_P2P2_DN<3>")
	)
	(segment
		(start 89.099644 -284.042358)
		(end 89.099644 -284.025086)
		(width 0.0889)
		(layer "In6.Cu")
		(net "UPI_CPU0_CPU1_P2P2_DN<3>")
	)
	(segment
		(start 56.098694 -322.880228)
		(end 57.344564 -321.634612)
		(width 0.14732)
		(layer "In6.Cu")
		(net "UPI_CPU0_CPU1_P2P2_DN<3>")
	)
	(segment
		(start 64.637158 -369.903248)
		(end 58.929778 -356.124256)
		(width 0.14732)
		(layer "In6.Cu")
		(net "UPI_CPU0_CPU1_P2P2_DN<3>")
	)
	(segment
		(start 83.559396 -293.553388)
		(end 83.653884 -293.324788)
		(width 0.14732)
		(layer "In6.Cu")
		(net "UPI_CPU0_CPU1_P2P2_DN<3>")
	)
	(segment
		(start 88.442292 -286.799782)
		(end 88.451182 -286.794702)
		(width 0.0889)
		(layer "In6.Cu")
		(net "UPI_CPU0_CPU1_P2P2_DN<3>")
	)
	(segment
		(start 88.911684 -283.708856)
		(end 88.90635 -283.705808)
		(width 0.0889)
		(layer "In6.Cu")
		(net "UPI_CPU0_CPU1_P2P2_DN<3>")
	)
	(segment
		(start 353.876356 -284.516068)
		(end 353.864164 -284.52318)
		(width 0.0889)
		(layer "In6.Cu")
		(net "UPI_CPU0_CPU1_P2P2_DN<3>")
	)
	(segment
		(start 353.394518 -286.964882)
		(end 353.385628 -286.969962)
		(width 0.0889)
		(layer "In6.Cu")
		(net "UPI_CPU0_CPU1_P2P2_DN<3>")
	)
	(segment
		(start 352.924618 -287.778698)
		(end 352.915728 -287.783778)
		(width 0.0889)
		(layer "In6.Cu")
		(net "UPI_CPU0_CPU1_P2P2_DN<3>")
	)
	(segment
		(start 354.146866 -282.405582)
		(end 354.146866 -282.412694)
		(width 0.0889)
		(layer "In6.Cu")
		(net "UPI_CPU0_CPU1_P2P2_DN<3>")
	)
	(segment
		(start 268.242542 -381.424434)
		(end 161.086546 -390.47293)
		(width 0.14732)
		(layer "In6.Cu")
		(net "UPI_CPU0_CPU1_P2P2_DN<3>")
	)
	(segment
		(start 89.507568 -279.964134)
		(end 89.194894 -279.964134)
		(width 0.0889)
		(layer "In6.Cu")
		(net "UPI_CPU0_CPU1_P2P2_DN<3>")
	)
	(segment
		(start 86.750398 -288.092642)
		(end 86.750144 -288.09315)
		(width 0.0889)
		(layer "In6.Cu")
		(net "UPI_CPU0_CPU1_P2P2_DN<3>")
	)
	(segment
		(start 278.238712 -347.817948)
		(end 278.238712 -371.428264)
		(width 0.14732)
		(layer "In6.Cu")
		(net "UPI_CPU0_CPU1_P2P2_DN<3>")
	)
	(segment
		(start 353.676966 -281.573478)
		(end 353.676966 -281.59202)
		(width 0.0889)
		(layer "In6.Cu")
		(net "UPI_CPU0_CPU1_P2P2_DN<3>")
	)
	(segment
		(start 88.436196 -281.919934)
		(end 88.442292 -281.916378)
		(width 0.0889)
		(layer "In6.Cu")
		(net "UPI_CPU0_CPU1_P2P2_DN<3>")
	)
	(segment
		(start 353.385628 -281.097228)
		(end 353.394518 -281.102308)
		(width 0.0889)
		(layer "In6.Cu")
		(net "UPI_CPU0_CPU1_P2P2_DN<3>")
	)
	(segment
		(start 62.255654 -314.425076)
		(end 63.356236 -313.969146)
		(width 0.14732)
		(layer "In6.Cu")
		(net "UPI_CPU0_CPU1_P2P2_DN<3>")
	)
	(segment
		(start 352.454718 -288.592768)
		(end 352.445828 -288.597848)
		(width 0.0889)
		(layer "In6.Cu")
		(net "UPI_CPU0_CPU1_P2P2_DN<3>")
	)
	(segment
		(start 55.387748 -323.181218)
		(end 55.588408 -323.221096)
		(width 0.14732)
		(layer "In6.Cu")
		(net "UPI_CPU0_CPU1_P2P2_DN<3>")
	)
	(segment
		(start 88.451182 -282.900628)
		(end 88.442292 -282.895548)
		(width 0.0889)
		(layer "In6.Cu")
		(net "UPI_CPU0_CPU1_P2P2_DN<3>")
	)
	(segment
		(start 88.159844 -285.679896)
		(end 88.159844 -285.651448)
		(width 0.0889)
		(layer "In6.Cu")
		(net "UPI_CPU0_CPU1_P2P2_DN<3>")
	)
	(segment
		(start 89.099644 -280.778204)
		(end 89.099644 -280.759662)
		(width 0.0889)
		(layer "In6.Cu")
		(net "UPI_CPU0_CPU1_P2P2_DN<3>")
	)
	(segment
		(start 350.047306 -301.850552)
		(end 344.036904 -307.860954)
		(width 0.14732)
		(layer "In6.Cu")
		(net "UPI_CPU0_CPU1_P2P2_DN<3>")
	)
	(segment
		(start 58.02376 -334.014064)
		(end 53.32476 -328.17054)
		(width 0.14732)
		(layer "In6.Cu")
		(net "UPI_CPU0_CPU1_P2P2_DN<3>")
	)
	(segment
		(start 57.199784 -319.513458)
		(end 57.199784 -319.145158)
		(width 0.14732)
		(layer "In6.Cu")
		(net "UPI_CPU0_CPU1_P2P2_DN<3>")
	)
	(segment
		(start 88.912192 -281.102562)
		(end 88.921082 -281.097482)
		(width 0.0889)
		(layer "In6.Cu")
		(net "UPI_CPU0_CPU1_P2P2_DN<3>")
	)
	(segment
		(start 81.84769 -297.68546)
		(end 83.559142 -293.553388)
		(width 0.14732)
		(layer "In6.Cu")
		(net "UPI_CPU0_CPU1_P2P2_DN<3>")
	)
	(segment
		(start 351.118424 -293.575486)
		(end 351.118424 -293.802054)
		(width 0.14732)
		(layer "In6.Cu")
		(net "UPI_CPU0_CPU1_P2P2_DN<3>")
	)
	(segment
		(start 57.199784 -319.145158)
		(end 57.344564 -319.000378)
		(width 0.14732)
		(layer "In6.Cu")
		(net "UPI_CPU0_CPU1_P2P2_DN<3>")
	)
	(segment
		(start 58.929778 -356.124256)
		(end 58.929778 -336.201512)
		(width 0.14732)
		(layer "In6.Cu")
		(net "UPI_CPU0_CPU1_P2P2_DN<3>")
	)
	(segment
		(start 88.443054 -286.151574)
		(end 88.442292 -286.151066)
		(width 0.0889)
		(layer "In6.Cu")
		(net "UPI_CPU0_CPU1_P2P2_DN<3>")
	)
	(segment
		(start 352.736658 -290.41979)
		(end 352.736658 -291.106352)
		(width 0.0889)
		(layer "In6.Cu")
		(net "UPI_CPU0_CPU1_P2P2_DN<3>")
	)
	(segment
		(start 344.036904 -307.860954)
		(end 340.116414 -309.484522)
		(width 0.14732)
		(layer "In6.Cu")
		(net "UPI_CPU0_CPU1_P2P2_DN<3>")
	)
	(segment
		(start 53.91785 -324.565518)
		(end 54.605936 -323.877686)
		(width 0.14732)
		(layer "In6.Cu")
		(net "UPI_CPU0_CPU1_P2P2_DN<3>")
	)
	(segment
		(start 351.118424 -293.553388)
		(end 351.118424 -293.575486)
		(width 0.0889)
		(layer "In6.Cu")
		(net "UPI_CPU0_CPU1_P2P2_DN<3>")
	)
	(segment
		(start 64.383666 -312.941716)
		(end 68.152518 -311.380632)
		(width 0.14732)
		(layer "In6.Cu")
		(net "UPI_CPU0_CPU1_P2P2_DN<3>")
	)
	(segment
		(start 353.207066 -287.28924)
		(end 353.207066 -287.299146)
		(width 0.0889)
		(layer "In6.Cu")
		(net "UPI_CPU0_CPU1_P2P2_DN<3>")
	)
	(segment
		(start 340.116414 -309.484522)
		(end 321.693794 -327.907142)
		(width 0.14732)
		(layer "In6.Cu")
		(net "UPI_CPU0_CPU1_P2P2_DN<3>")
	)
	(segment
		(start 351.11817 -293.802308)
		(end 351.11817 -299.264832)
		(width 0.14732)
		(layer "In6.Cu")
		(net "UPI_CPU0_CPU1_P2P2_DN<3>")
	)
	(segment
		(start 88.442292 -281.916378)
		(end 88.451182 -281.911298)
		(width 0.0889)
		(layer "In6.Cu")
		(net "UPI_CPU0_CPU1_P2P2_DN<3>")
	)
	(segment
		(start 87.033354 -287.61309)
		(end 87.041482 -287.608518)
		(width 0.0889)
		(layer "In6.Cu")
		(net "UPI_CPU0_CPU1_P2P2_DN<3>")
	)
	(segment
		(start 53.91785 -324.566026)
		(end 53.91785 -324.565518)
		(width 0.14732)
		(layer "In6.Cu")
		(net "UPI_CPU0_CPU1_P2P2_DN<3>")
	)
	(segment
		(start 86.750398 -288.322004)
		(end 86.750398 -288.092642)
		(width 0.0889)
		(layer "In6.Cu")
		(net "UPI_CPU0_CPU1_P2P2_DN<3>")
	)
	(segment
		(start 86.417404 -290.561268)
		(end 86.417404 -289.257486)
		(width 0.14732)
		(layer "In6.Cu")
		(net "UPI_CPU0_CPU1_P2P2_DN<3>")
	)
	(segment
		(start 310.427624 -340.89086)
		(end 286.760666 -340.89086)
		(width 0.14732)
		(layer "In6.Cu")
		(net "UPI_CPU0_CPU1_P2P2_DN<3>")
	)
	(segment
		(start 321.693794 -327.907142)
		(end 320.478912 -330.839572)
		(width 0.14732)
		(layer "In6.Cu")
		(net "UPI_CPU0_CPU1_P2P2_DN<3>")
	)
	(segment
		(start 70.380606 -375.646696)
		(end 64.637158 -369.903248)
		(width 0.14732)
		(layer "In6.Cu")
		(net "UPI_CPU0_CPU1_P2P2_DN<3>")
	)
	(segment
		(start 354.616766 -283.205682)
		(end 354.616766 -283.219906)
		(width 0.0889)
		(layer "In6.Cu")
		(net "UPI_CPU0_CPU1_P2P2_DN<3>")
	)
	(segment
		(start 83.653884 -293.324788)
		(end 86.417404 -290.561268)
		(width 0.14732)
		(layer "In6.Cu")
		(net "UPI_CPU0_CPU1_P2P2_DN<3>")
	)
	(segment
		(start 284.037786 -342.018874)
		(end 278.238712 -347.817948)
		(width 0.14732)
		(layer "In6.Cu")
		(net "UPI_CPU0_CPU1_P2P2_DN<3>")
	)
	(arc
		(start 352.445828 -288.597848)
		(mid 352.314914 -288.734208)
		(end 352.267266 -288.917126)
		(width 0.0889)
		(layer "In6.Cu")
		(net "UPI_CPU0_CPU1_P2P2_DN<3>")
	)
	(arc
		(start 88.629744 -281.59202)
		(mid 88.70366 -281.312518)
		(end 88.906096 -281.106118)
		(width 0.0889)
		(layer "In6.Cu")
		(net "UPI_CPU0_CPU1_P2P2_DN<3>")
	)
	(arc
		(start 88.62949 -283.205174)
		(mid 88.578436 -283.030594)
		(end 88.451182 -282.900628)
		(width 0.0889)
		(layer "In6.Cu")
		(net "UPI_CPU0_CPU1_P2P2_DN<3>")
	)
	(arc
		(start 354.146866 -282.412694)
		(mid 354.198842 -282.596093)
		(end 354.334318 -282.730194)
		(width 0.0889)
		(layer "In6.Cu")
		(net "UPI_CPU0_CPU1_P2P2_DN<3>")
	)
	(arc
		(start 88.159844 -282.405836)
		(mid 88.23376 -282.126334)
		(end 88.436196 -281.919934)
		(width 0.0889)
		(layer "In6.Cu")
		(net "UPI_CPU0_CPU1_P2P2_DN<3>")
	)
	(arc
		(start 352.737166 -288.121598)
		(mid 352.657004 -288.393787)
		(end 352.454718 -288.592768)
		(width 0.0889)
		(layer "In6.Cu")
		(net "UPI_CPU0_CPU1_P2P2_DN<3>")
	)
	(arc
		(start 352.267266 -289.078416)
		(mid 352.342271 -289.193875)
		(end 352.451416 -289.277806)
		(width 0.0889)
		(layer "In6.Cu")
		(net "UPI_CPU0_CPU1_P2P2_DN<3>")
	)
	(arc
		(start 88.159844 -285.651448)
		(mid 88.237955 -285.374499)
		(end 88.442292 -285.171896)
		(width 0.0889)
		(layer "In6.Cu")
		(net "UPI_CPU0_CPU1_P2P2_DN<3>")
	)
	(arc
		(start 353.676712 -284.863032)
		(mid 353.597342 -285.136766)
		(end 353.394518 -285.336996)
		(width 0.0889)
		(layer "In6.Cu")
		(net "UPI_CPU0_CPU1_P2P2_DN<3>")
	)
	(arc
		(start 88.442292 -282.895548)
		(mid 88.238987 -282.694682)
		(end 88.159844 -282.42006)
		(width 0.0889)
		(layer "In6.Cu")
		(net "UPI_CPU0_CPU1_P2P2_DN<3>")
	)
	(arc
		(start 87.041482 -287.608518)
		(mid 87.172396 -287.472158)
		(end 87.220044 -287.28924)
		(width 0.0889)
		(layer "In6.Cu")
		(net "UPI_CPU0_CPU1_P2P2_DN<3>")
	)
	(arc
		(start 353.676966 -281.59202)
		(mid 353.724645 -281.77492)
		(end 353.855528 -281.911298)
		(width 0.0889)
		(layer "In6.Cu")
		(net "UPI_CPU0_CPU1_P2P2_DN<3>")
	)
	(arc
		(start 88.90635 -283.705808)
		(mid 88.703763 -283.499457)
		(end 88.629744 -283.219906)
		(width 0.0889)
		(layer "In6.Cu")
		(net "UPI_CPU0_CPU1_P2P2_DN<3>")
	)
	(arc
		(start 88.451182 -285.166816)
		(mid 88.582096 -285.030456)
		(end 88.629744 -284.847538)
		(width 0.0889)
		(layer "In6.Cu")
		(net "UPI_CPU0_CPU1_P2P2_DN<3>")
	)
	(arc
		(start 88.921082 -281.097482)
		(mid 89.051996 -280.961122)
		(end 89.099644 -280.778204)
		(width 0.0889)
		(layer "In6.Cu")
		(net "UPI_CPU0_CPU1_P2P2_DN<3>")
	)
	(arc
		(start 354.616766 -283.219906)
		(mid 354.54285 -283.499408)
		(end 354.340414 -283.705808)
		(width 0.0889)
		(layer "In6.Cu")
		(net "UPI_CPU0_CPU1_P2P2_DN<3>")
	)
	(arc
		(start 88.451182 -281.911298)
		(mid 88.582096 -281.774938)
		(end 88.629744 -281.59202)
		(width 0.0889)
		(layer "In6.Cu")
		(net "UPI_CPU0_CPU1_P2P2_DN<3>")
	)
	(arc
		(start 88.451182 -286.794702)
		(mid 88.629779 -286.475424)
		(end 88.451182 -286.156146)
		(width 0.0889)
		(layer "In6.Cu")
		(net "UPI_CPU0_CPU1_P2P2_DN<3>")
	)
	(arc
		(start 353.385628 -286.969962)
		(mid 353.254714 -287.106322)
		(end 353.207066 -287.28924)
		(width 0.0889)
		(layer "In6.Cu")
		(net "UPI_CPU0_CPU1_P2P2_DN<3>")
	)
	(arc
		(start 89.099644 -280.759662)
		(mid 89.179806 -280.487473)
		(end 89.382092 -280.288492)
		(width 0.0889)
		(layer "In6.Cu")
		(net "UPI_CPU0_CPU1_P2P2_DN<3>")
	)
	(arc
		(start 353.676966 -286.48533)
		(mid 353.598855 -286.762279)
		(end 353.394518 -286.964882)
		(width 0.0889)
		(layer "In6.Cu")
		(net "UPI_CPU0_CPU1_P2P2_DN<3>")
	)
	(arc
		(start 86.750144 -288.09315)
		(mid 86.828255 -287.816201)
		(end 87.032592 -287.613598)
		(width 0.0889)
		(layer "In6.Cu")
		(net "UPI_CPU0_CPU1_P2P2_DN<3>")
	)
	(arc
		(start 88.912446 -284.35808)
		(mid 89.047379 -284.224726)
		(end 89.099644 -284.042358)
		(width 0.0889)
		(layer "In6.Cu")
		(net "UPI_CPU0_CPU1_P2P2_DN<3>")
	)
	(arc
		(start 354.146866 -284.033722)
		(mid 354.074631 -284.310246)
		(end 353.876356 -284.516068)
		(width 0.0889)
		(layer "In6.Cu")
		(net "UPI_CPU0_CPU1_P2P2_DN<3>")
	)
	(arc
		(start 353.870514 -281.919934)
		(mid 354.072864 -282.126237)
		(end 354.146866 -282.405582)
		(width 0.0889)
		(layer "In6.Cu")
		(net "UPI_CPU0_CPU1_P2P2_DN<3>")
	)
	(arc
		(start 88.629744 -283.219906)
		(mid 88.629692 -283.212539)
		(end 88.62949 -283.205174)
		(width 0.0889)
		(layer "In6.Cu")
		(net "UPI_CPU0_CPU1_P2P2_DN<3>")
	)
	(arc
		(start 352.979482 -280.324306)
		(mid 353.143752 -280.517846)
		(end 353.206812 -280.763726)
		(width 0.0889)
		(layer "In6.Cu")
		(net "UPI_CPU0_CPU1_P2P2_DN<3>")
	)
	(arc
		(start 88.067896 -286.799782)
		(mid 88.255094 -286.849925)
		(end 88.442292 -286.799782)
		(width 0.0889)
		(layer "In6.Cu")
		(net "UPI_CPU0_CPU1_P2P2_DN<3>")
	)
	(arc
		(start 353.207066 -287.299146)
		(mid 353.128955 -287.576095)
		(end 352.924618 -287.778698)
		(width 0.0889)
		(layer "In6.Cu")
		(net "UPI_CPU0_CPU1_P2P2_DN<3>")
	)
	(arc
		(start 87.502492 -286.799782)
		(mid 87.785194 -286.724006)
		(end 88.067896 -286.799782)
		(width 0.0889)
		(layer "In6.Cu")
		(net "UPI_CPU0_CPU1_P2P2_DN<3>")
	)
	(arc
		(start 354.325428 -283.714444)
		(mid 354.194514 -283.850804)
		(end 354.146866 -284.033722)
		(width 0.0889)
		(layer "In6.Cu")
		(net "UPI_CPU0_CPU1_P2P2_DN<3>")
	)
	(arc
		(start 89.390982 -280.283412)
		(mid 89.506721 -280.171588)
		(end 89.564972 -280.021538)
		(width 0.0889)
		(layer "In6.Cu")
		(net "UPI_CPU0_CPU1_P2P2_DN<3>")
	)
	(arc
		(start 353.394518 -281.102308)
		(mid 353.596804 -281.301289)
		(end 353.676966 -281.573478)
		(width 0.0889)
		(layer "In6.Cu")
		(net "UPI_CPU0_CPU1_P2P2_DN<3>")
	)
	(arc
		(start 353.385628 -285.342076)
		(mid 353.207031 -285.661354)
		(end 353.385628 -285.980632)
		(width 0.0889)
		(layer "In6.Cu")
		(net "UPI_CPU0_CPU1_P2P2_DN<3>")
	)
	(arc
		(start 87.220044 -287.279334)
		(mid 87.298155 -287.002385)
		(end 87.502492 -286.799782)
		(width 0.0889)
		(layer "In6.Cu")
		(net "UPI_CPU0_CPU1_P2P2_DN<3>")
	)
	(arc
		(start 353.394518 -285.985712)
		(mid 353.596804 -286.184693)
		(end 353.676966 -286.456882)
		(width 0.0889)
		(layer "In6.Cu")
		(net "UPI_CPU0_CPU1_P2P2_DN<3>")
	)
	(arc
		(start 89.099644 -284.025086)
		(mid 89.047374 -283.842721)
		(end 88.912446 -283.709364)
		(width 0.0889)
		(layer "In6.Cu")
		(net "UPI_CPU0_CPU1_P2P2_DN<3>")
	)
	(arc
		(start 352.451416 -289.277806)
		(mid 352.625548 -289.416653)
		(end 352.736912 -289.60953)
		(width 0.0889)
		(layer "In6.Cu")
		(net "UPI_CPU0_CPU1_P2P2_DN<3>")
	)
	(arc
		(start 353.855274 -284.52826)
		(mid 353.72436 -284.66462)
		(end 353.676712 -284.847538)
		(width 0.0889)
		(layer "In6.Cu")
		(net "UPI_CPU0_CPU1_P2P2_DN<3>")
	)
	(arc
		(start 352.915728 -287.783778)
		(mid 352.784814 -287.920138)
		(end 352.737166 -288.103056)
		(width 0.0889)
		(layer "In6.Cu")
		(net "UPI_CPU0_CPU1_P2P2_DN<3>")
	)
	(arc
		(start 354.334318 -282.730194)
		(mid 354.537623 -282.93106)
		(end 354.616766 -283.205682)
		(width 0.0889)
		(layer "In6.Cu")
		(net "UPI_CPU0_CPU1_P2P2_DN<3>")
	)
	(arc
		(start 88.629744 -284.847538)
		(mid 88.703735 -284.567972)
		(end 88.90635 -284.361636)
		(width 0.0889)
		(layer "In6.Cu")
		(net "UPI_CPU0_CPU1_P2P2_DN<3>")
	)
	(arc
		(start 88.442292 -286.151066)
		(mid 88.240006 -285.952085)
		(end 88.159844 -285.679896)
		(width 0.0889)
		(layer "In6.Cu")
		(net "UPI_CPU0_CPU1_P2P2_DN<3>")
	)
	(arc
		(start 353.207066 -280.77795)
		(mid 353.254745 -280.96085)
		(end 353.385628 -281.097228)
		(width 0.0889)
		(layer "In6.Cu")
		(net "UPI_CPU0_CPU1_P2P2_DN<3>")
	)
	(segment
		(start 354.051362 -281.05608)
		(end 354.051362 -281.591766)
		(width 0.13208)
		(layer "F.Cu")
		(net "UPI_CPU0_CPU1_P2P2_DN<2>")
	)
	(segment
		(start 87.785194 -281.869896)
		(end 87.785194 -282.405836)
		(width 0.13208)
		(layer "F.Cu")
		(net "UPI_CPU0_CPU1_P2P2_DN<2>")
	)
	(segment
		(start 354.051362 -281.591766)
		(end 354.051616 -281.59202)
		(width 0.13208)
		(layer "F.Cu")
		(net "UPI_CPU0_CPU1_P2P2_DN<2>")
	)
	(segment
		(start 268.5923 -382.268222)
		(end 161.475674 -391.31367)
		(width 0.14732)
		(layer "In6.Cu")
		(net "UPI_CPU0_CPU1_P2P2_DN<2>")
	)
	(segment
		(start 353.07651 -298.498514)
		(end 352.012504 -301.067216)
		(width 0.14732)
		(layer "In6.Cu")
		(net "UPI_CPU0_CPU1_P2P2_DN<2>")
	)
	(segment
		(start 63.94069 -370.391944)
		(end 58.101738 -356.295706)
		(width 0.14732)
		(layer "In6.Cu")
		(net "UPI_CPU0_CPU1_P2P2_DN<2>")
	)
	(segment
		(start 353.076764 -295.151048)
		(end 353.076764 -295.173146)
		(width 0.0889)
		(layer "In6.Cu")
		(net "UPI_CPU0_CPU1_P2P2_DN<2>")
	)
	(segment
		(start 82.10296 -294.884094)
		(end 82.937096 -292.870382)
		(width 0.14732)
		(layer "In6.Cu")
		(net "UPI_CPU0_CPU1_P2P2_DN<2>")
	)
	(segment
		(start 58.101738 -356.295706)
		(end 58.101738 -336.446114)
		(width 0.14732)
		(layer "In6.Cu")
		(net "UPI_CPU0_CPU1_P2P2_DN<2>")
	)
	(segment
		(start 70.179692 -376.630946)
		(end 63.94069 -370.391944)
		(width 0.14732)
		(layer "In6.Cu")
		(net "UPI_CPU0_CPU1_P2P2_DN<2>")
	)
	(segment
		(start 87.501984 -285.172658)
		(end 87.511128 -285.167324)
		(width 0.0889)
		(layer "In6.Cu")
		(net "UPI_CPU0_CPU1_P2P2_DN<2>")
	)
	(segment
		(start 57.341008 -316.206124)
		(end 60.471304 -314.114688)
		(width 0.14732)
		(layer "In6.Cu")
		(net "UPI_CPU0_CPU1_P2P2_DN<2>")
	)
	(segment
		(start 86.280244 -287.452054)
		(end 86.280244 -287.28924)
		(width 0.0889)
		(layer "In6.Cu")
		(net "UPI_CPU0_CPU1_P2P2_DN<2>")
	)
	(segment
		(start 355.27996 -283.705808)
		(end 355.274626 -283.708856)
		(width 0.0889)
		(layer "In6.Cu")
		(net "UPI_CPU0_CPU1_P2P2_DN<2>")
	)
	(segment
		(start 355.264974 -282.725114)
		(end 355.273864 -282.730194)
		(width 0.0889)
		(layer "In6.Cu")
		(net "UPI_CPU0_CPU1_P2P2_DN<2>")
	)
	(segment
		(start 55.324756 -318.346074)
		(end 55.744872 -317.55969)
		(width 0.14732)
		(layer "In6.Cu")
		(net "UPI_CPU0_CPU1_P2P2_DN<2>")
	)
	(segment
		(start 161.475674 -391.31367)
		(end 126.821184 -391.31367)
		(width 0.14732)
		(layer "In6.Cu")
		(net "UPI_CPU0_CPU1_P2P2_DN<2>")
	)
	(segment
		(start 87.901018 -282.779724)
		(end 87.90051 -282.779216)
		(width 0.0889)
		(layer "In6.Cu")
		(net "UPI_CPU0_CPU1_P2P2_DN<2>")
	)
	(segment
		(start 321.20078 -331.291692)
		(end 310.694832 -341.79764)
		(width 0.14732)
		(layer "In6.Cu")
		(net "UPI_CPU0_CPU1_P2P2_DN<2>")
	)
	(segment
		(start 81.70672 -295.840912)
		(end 82.10296 -294.884348)
		(width 0.14732)
		(layer "In6.Cu")
		(net "UPI_CPU0_CPU1_P2P2_DN<2>")
	)
	(segment
		(start 355.086412 -282.390342)
		(end 355.086412 -282.405836)
		(width 0.0889)
		(layer "In6.Cu")
		(net "UPI_CPU0_CPU1_P2P2_DN<2>")
	)
	(segment
		(start 67.588384 -310.519318)
		(end 81.310226 -296.797476)
		(width 0.14732)
		(layer "In6.Cu")
		(net "UPI_CPU0_CPU1_P2P2_DN<2>")
	)
	(segment
		(start 61.57595 -313.009788)
		(end 67.588384 -310.519318)
		(width 0.14732)
		(layer "In6.Cu")
		(net "UPI_CPU0_CPU1_P2P2_DN<2>")
	)
	(segment
		(start 84.559394 -291.248084)
		(end 84.574888 -291.23259)
		(width 0.0889)
		(layer "In6.Cu")
		(net "UPI_CPU0_CPU1_P2P2_DN<2>")
	)
	(segment
		(start 55.335424 -332.140306)
		(end 55.334408 -332.139036)
		(width 0.14732)
		(layer "In6.Cu")
		(net "UPI_CPU0_CPU1_P2P2_DN<2>")
	)
	(segment
		(start 85.404706 -288.327592)
		(end 86.280244 -287.452054)
		(width 0.0889)
		(layer "In6.Cu")
		(net "UPI_CPU0_CPU1_P2P2_DN<2>")
	)
	(segment
		(start 353.207066 -288.917126)
		(end 353.207066 -289.078416)
		(width 0.0889)
		(layer "In6.Cu")
		(net "UPI_CPU0_CPU1_P2P2_DN<2>")
	)
	(segment
		(start 87.220044 -285.661354)
		(end 87.220044 -285.463234)
		(width 0.0889)
		(layer "In6.Cu")
		(net "UPI_CPU0_CPU1_P2P2_DN<2>")
	)
	(segment
		(start 355.556566 -283.205682)
		(end 355.556566 -283.219906)
		(width 0.0889)
		(layer "In6.Cu")
		(net "UPI_CPU0_CPU1_P2P2_DN<2>")
	)
	(segment
		(start 353.07651 -295.298114)
		(end 353.07651 -298.498514)
		(width 0.14732)
		(layer "In6.Cu")
		(net "UPI_CPU0_CPU1_P2P2_DN<2>")
	)
	(segment
		(start 87.220044 -285.463234)
		(end 87.256112 -285.463234)
		(width 0.0889)
		(layer "In6.Cu")
		(net "UPI_CPU0_CPU1_P2P2_DN<2>")
	)
	(segment
		(start 87.917528 -282.766008)
		(end 87.941658 -282.676854)
		(width 0.0889)
		(layer "In6.Cu")
		(net "UPI_CPU0_CPU1_P2P2_DN<2>")
	)
	(segment
		(start 87.941658 -282.676854)
		(end 87.785194 -282.405836)
		(width 0.0889)
		(layer "In6.Cu")
		(net "UPI_CPU0_CPU1_P2P2_DN<2>")
	)
	(segment
		(start 353.676458 -291.291518)
		(end 353.0346 -291.933376)
		(width 0.0889)
		(layer "In6.Cu")
		(net "UPI_CPU0_CPU1_P2P2_DN<2>")
	)
	(segment
		(start 52.43576 -329.236832)
		(end 52.43576 -324.816216)
		(width 0.14732)
		(layer "In6.Cu")
		(net "UPI_CPU0_CPU1_P2P2_DN<2>")
	)
	(segment
		(start 353.391216 -289.277806)
		(end 353.391216 -289.278314)
		(width 0.0889)
		(layer "In6.Cu")
		(net "UPI_CPU0_CPU1_P2P2_DN<2>")
	)
	(segment
		(start 56.307736 -333.301086)
		(end 55.335678 -332.140052)
		(width 0.14732)
		(layer "In6.Cu")
		(net "UPI_CPU0_CPU1_P2P2_DN<2>")
	)
	(segment
		(start 56.30799 -333.30134)
		(end 56.307736 -333.301086)
		(width 0.14732)
		(layer "In6.Cu")
		(net "UPI_CPU0_CPU1_P2P2_DN<2>")
	)
	(segment
		(start 58.101738 -336.446114)
		(end 57.279794 -334.46212)
		(width 0.14732)
		(layer "In6.Cu")
		(net "UPI_CPU0_CPU1_P2P2_DN<2>")
	)
	(segment
		(start 355.274626 -283.708856)
		(end 355.273864 -283.709364)
		(width 0.0889)
		(layer "In6.Cu")
		(net "UPI_CPU0_CPU1_P2P2_DN<2>")
	)
	(segment
		(start 55.318152 -332.119478)
		(end 52.43576 -329.236832)
		(width 0.14732)
		(layer "In6.Cu")
		(net "UPI_CPU0_CPU1_P2P2_DN<2>")
	)
	(segment
		(start 322.414138 -328.361802)
		(end 321.20078 -331.291692)
		(width 0.14732)
		(layer "In6.Cu")
		(net "UPI_CPU0_CPU1_P2P2_DN<2>")
	)
	(segment
		(start 84.574888 -291.23259)
		(end 84.633816 -291.23259)
		(width 0.0889)
		(layer "In6.Cu")
		(net "UPI_CPU0_CPU1_P2P2_DN<2>")
	)
	(segment
		(start 354.81006 -284.519624)
		(end 354.795074 -284.528514)
		(width 0.0889)
		(layer "In6.Cu")
		(net "UPI_CPU0_CPU1_P2P2_DN<2>")
	)
	(segment
		(start 354.051616 -281.59202)
		(end 354.20808 -281.863038)
		(width 0.0889)
		(layer "In6.Cu")
		(net "UPI_CPU0_CPU1_P2P2_DN<2>")
	)
	(segment
		(start 86.101682 -286.969962)
		(end 86.092792 -286.964882)
		(width 0.0889)
		(layer "In6.Cu")
		(net "UPI_CPU0_CPU1_P2P2_DN<2>")
	)
	(segment
		(start 82.937096 -292.870382)
		(end 84.559394 -291.248084)
		(width 0.14732)
		(layer "In6.Cu")
		(net "UPI_CPU0_CPU1_P2P2_DN<2>")
	)
	(segment
		(start 85.810344 -286.48533)
		(end 85.810344 -286.456882)
		(width 0.0889)
		(layer "In6.Cu")
		(net "UPI_CPU0_CPU1_P2P2_DN<2>")
	)
	(segment
		(start 344.518488 -308.561232)
		(end 340.586314 -310.189626)
		(width 0.14732)
		(layer "In6.Cu")
		(net "UPI_CPU0_CPU1_P2P2_DN<2>")
	)
	(segment
		(start 55.334408 -332.139036)
		(end 55.333646 -332.13802)
		(width 0.14732)
		(layer "In6.Cu")
		(net "UPI_CPU0_CPU1_P2P2_DN<2>")
	)
	(segment
		(start 354.325428 -285.980632)
		(end 354.334318 -285.985712)
		(width 0.0889)
		(layer "In6.Cu")
		(net "UPI_CPU0_CPU1_P2P2_DN<2>")
	)
	(segment
		(start 55.987188 -317.317374)
		(end 57.341008 -316.206124)
		(width 0.14732)
		(layer "In6.Cu")
		(net "UPI_CPU0_CPU1_P2P2_DN<2>")
	)
	(segment
		(start 52.43576 -324.816216)
		(end 54.435248 -322.816728)
		(width 0.14732)
		(layer "In6.Cu")
		(net "UPI_CPU0_CPU1_P2P2_DN<2>")
	)
	(segment
		(start 353.864418 -287.778698)
		(end 353.855528 -287.783778)
		(width 0.0889)
		(layer "In6.Cu")
		(net "UPI_CPU0_CPU1_P2P2_DN<2>")
	)
	(segment
		(start 354.334318 -285.336996)
		(end 354.325428 -285.342076)
		(width 0.0889)
		(layer "In6.Cu")
		(net "UPI_CPU0_CPU1_P2P2_DN<2>")
	)
	(segment
		(start 54.435248 -322.816728)
		(end 55.324756 -318.346074)
		(width 0.14732)
		(layer "In6.Cu")
		(net "UPI_CPU0_CPU1_P2P2_DN<2>")
	)
	(segment
		(start 354.146866 -287.28924)
		(end 354.146866 -287.299146)
		(width 0.0889)
		(layer "In6.Cu")
		(net "UPI_CPU0_CPU1_P2P2_DN<2>")
	)
	(segment
		(start 353.076764 -295.29786)
		(end 353.07651 -295.298114)
		(width 0.14732)
		(layer "In6.Cu")
		(net "UPI_CPU0_CPU1_P2P2_DN<2>")
	)
	(segment
		(start 310.694832 -341.79764)
		(end 286.736282 -341.79764)
		(width 0.14732)
		(layer "In6.Cu")
		(net "UPI_CPU0_CPU1_P2P2_DN<2>")
	)
	(segment
		(start 55.335678 -332.140052)
		(end 55.335424 -332.140306)
		(width 0.14732)
		(layer "In6.Cu")
		(net "UPI_CPU0_CPU1_P2P2_DN<2>")
	)
	(segment
		(start 87.512144 -284.52826)
		(end 87.503762 -284.523688)
		(width 0.0889)
		(layer "In6.Cu")
		(net "UPI_CPU0_CPU1_P2P2_DN<2>")
	)
	(segment
		(start 87.690198 -283.22778)
		(end 87.690198 -283.219652)
		(width 0.0889)
		(layer "In6.Cu")
		(net "UPI_CPU0_CPU1_P2P2_DN<2>")
	)
	(segment
		(start 352.012504 -301.067216)
		(end 344.518488 -308.561232)
		(width 0.14732)
		(layer "In6.Cu")
		(net "UPI_CPU0_CPU1_P2P2_DN<2>")
	)
	(segment
		(start 279.066752 -371.79377)
		(end 268.5923 -382.268222)
		(width 0.14732)
		(layer "In6.Cu")
		(net "UPI_CPU0_CPU1_P2P2_DN<2>")
	)
	(segment
		(start 354.20808 -281.863038)
		(end 354.29698 -281.88666)
		(width 0.0889)
		(layer "In6.Cu")
		(net "UPI_CPU0_CPU1_P2P2_DN<2>")
	)
	(segment
		(start 126.821184 -391.31367)
		(end 93.801438 -386.41528)
		(width 0.14732)
		(layer "In6.Cu")
		(net "UPI_CPU0_CPU1_P2P2_DN<2>")
	)
	(segment
		(start 340.586314 -310.189626)
		(end 322.414138 -328.361802)
		(width 0.14732)
		(layer "In6.Cu")
		(net "UPI_CPU0_CPU1_P2P2_DN<2>")
	)
	(segment
		(start 353.076764 -295.173146)
		(end 353.076764 -295.29786)
		(width 0.14732)
		(layer "In6.Cu")
		(net "UPI_CPU0_CPU1_P2P2_DN<2>")
	)
	(segment
		(start 84.633816 -291.23259)
		(end 85.404706 -290.4617)
		(width 0.0889)
		(layer "In6.Cu")
		(net "UPI_CPU0_CPU1_P2P2_DN<2>")
	)
	(segment
		(start 285.716218 -342.220296)
		(end 285.716218 -342.22055)
		(width 0.14732)
		(layer "In6.Cu")
		(net "UPI_CPU0_CPU1_P2P2_DN<2>")
	)
	(segment
		(start 354.616512 -286.453326)
		(end 354.616512 -286.490918)
		(width 0.0889)
		(layer "In6.Cu")
		(net "UPI_CPU0_CPU1_P2P2_DN<2>")
	)
	(segment
		(start 55.744872 -317.55969)
		(end 55.987188 -317.317374)
		(width 0.14732)
		(layer "In6.Cu")
		(net "UPI_CPU0_CPU1_P2P2_DN<2>")
	)
	(segment
		(start 353.0346 -291.933376)
		(end 353.0346 -295.108884)
		(width 0.0889)
		(layer "In6.Cu")
		(net "UPI_CPU0_CPU1_P2P2_DN<2>")
	)
	(segment
		(start 55.333646 -332.13802)
		(end 55.318152 -332.119478)
		(width 0.14732)
		(layer "In6.Cu")
		(net "UPI_CPU0_CPU1_P2P2_DN<2>")
	)
	(segment
		(start 81.310226 -296.797476)
		(end 81.70672 -295.840912)
		(width 0.14732)
		(layer "In6.Cu")
		(net "UPI_CPU0_CPU1_P2P2_DN<2>")
	)
	(segment
		(start 93.801438 -386.41528)
		(end 70.179692 -376.630946)
		(width 0.14732)
		(layer "In6.Cu")
		(net "UPI_CPU0_CPU1_P2P2_DN<2>")
	)
	(segment
		(start 57.279794 -334.46212)
		(end 56.30799 -333.30134)
		(width 0.14732)
		(layer "In6.Cu")
		(net "UPI_CPU0_CPU1_P2P2_DN<2>")
	)
	(segment
		(start 82.10296 -294.884348)
		(end 82.10296 -294.884094)
		(width 0.14732)
		(layer "In6.Cu")
		(net "UPI_CPU0_CPU1_P2P2_DN<2>")
	)
	(segment
		(start 279.066752 -348.272608)
		(end 279.066752 -371.79377)
		(width 0.14732)
		(layer "In6.Cu")
		(net "UPI_CPU0_CPU1_P2P2_DN<2>")
	)
	(segment
		(start 353.676966 -288.103056)
		(end 353.676966 -288.121598)
		(width 0.0889)
		(layer "In6.Cu")
		(net "UPI_CPU0_CPU1_P2P2_DN<2>")
	)
	(segment
		(start 354.795074 -284.528514)
		(end 354.795074 -284.52826)
		(width 0.0889)
		(layer "In6.Cu")
		(net "UPI_CPU0_CPU1_P2P2_DN<2>")
	)
	(segment
		(start 353.0346 -295.108884)
		(end 353.076764 -295.151048)
		(width 0.0889)
		(layer "In6.Cu")
		(net "UPI_CPU0_CPU1_P2P2_DN<2>")
	)
	(segment
		(start 354.616512 -284.847538)
		(end 354.616512 -284.863032)
		(width 0.0889)
		(layer "In6.Cu")
		(net "UPI_CPU0_CPU1_P2P2_DN<2>")
	)
	(segment
		(start 60.471304 -314.114688)
		(end 61.57595 -313.009788)
		(width 0.14732)
		(layer "In6.Cu")
		(net "UPI_CPU0_CPU1_P2P2_DN<2>")
	)
	(segment
		(start 353.676458 -289.610292)
		(end 353.676458 -291.291518)
		(width 0.0889)
		(layer "In6.Cu")
		(net "UPI_CPU0_CPU1_P2P2_DN<2>")
	)
	(segment
		(start 355.086666 -284.025086)
		(end 355.086666 -284.033722)
		(width 0.0889)
		(layer "In6.Cu")
		(net "UPI_CPU0_CPU1_P2P2_DN<2>")
	)
	(segment
		(start 353.394518 -288.592768)
		(end 353.385628 -288.597848)
		(width 0.0889)
		(layer "In6.Cu")
		(net "UPI_CPU0_CPU1_P2P2_DN<2>")
	)
	(segment
		(start 85.404706 -290.4617)
		(end 85.404706 -288.327592)
		(width 0.0889)
		(layer "In6.Cu")
		(net "UPI_CPU0_CPU1_P2P2_DN<2>")
	)
	(segment
		(start 284.696662 -342.642698)
		(end 279.066752 -348.272608)
		(width 0.14732)
		(layer "In6.Cu")
		(net "UPI_CPU0_CPU1_P2P2_DN<2>")
	)
	(segment
		(start 354.334318 -286.964882)
		(end 354.325428 -286.969962)
		(width 0.0889)
		(layer "In6.Cu")
		(net "UPI_CPU0_CPU1_P2P2_DN<2>")
	)
	(segment
		(start 286.736282 -341.79764)
		(end 285.716218 -342.220296)
		(width 0.14732)
		(layer "In6.Cu")
		(net "UPI_CPU0_CPU1_P2P2_DN<2>")
	)
	(segment
		(start 285.716218 -342.22055)
		(end 284.696662 -342.642698)
		(width 0.14732)
		(layer "In6.Cu")
		(net "UPI_CPU0_CPU1_P2P2_DN<2>")
	)
	(arc
		(start 85.810344 -286.456882)
		(mid 86.100822 -285.981163)
		(end 86.658196 -285.985712)
		(width 0.0889)
		(layer "In6.Cu")
		(net "UPI_CPU0_CPU1_P2P2_DN<2>")
	)
	(arc
		(start 86.280244 -287.28924)
		(mid 86.232565 -287.10634)
		(end 86.101682 -286.969962)
		(width 0.0889)
		(layer "In6.Cu")
		(net "UPI_CPU0_CPU1_P2P2_DN<2>")
	)
	(arc
		(start 353.676966 -288.121598)
		(mid 353.596804 -288.393787)
		(end 353.394518 -288.592768)
		(width 0.0889)
		(layer "In6.Cu")
		(net "UPI_CPU0_CPU1_P2P2_DN<2>")
	)
	(arc
		(start 354.146866 -287.299146)
		(mid 354.068755 -287.576095)
		(end 353.864418 -287.778698)
		(width 0.0889)
		(layer "In6.Cu")
		(net "UPI_CPU0_CPU1_P2P2_DN<2>")
	)
	(arc
		(start 87.503762 -284.523688)
		(mid 87.220026 -284.034352)
		(end 87.502746 -283.544518)
		(width 0.0889)
		(layer "In6.Cu")
		(net "UPI_CPU0_CPU1_P2P2_DN<2>")
	)
	(arc
		(start 354.147374 -285.676086)
		(mid 354.198284 -285.850655)
		(end 354.325428 -285.980632)
		(width 0.0889)
		(layer "In6.Cu")
		(net "UPI_CPU0_CPU1_P2P2_DN<2>")
	)
	(arc
		(start 355.086412 -282.405836)
		(mid 355.134091 -282.588736)
		(end 355.264974 -282.725114)
		(width 0.0889)
		(layer "In6.Cu")
		(net "UPI_CPU0_CPU1_P2P2_DN<2>")
	)
	(arc
		(start 354.316538 -281.878532)
		(mid 354.56469 -281.841917)
		(end 354.804218 -281.916378)
		(width 0.0889)
		(layer "In6.Cu")
		(net "UPI_CPU0_CPU1_P2P2_DN<2>")
	)
	(arc
		(start 353.855528 -287.783778)
		(mid 353.724614 -287.920138)
		(end 353.676966 -288.103056)
		(width 0.0889)
		(layer "In6.Cu")
		(net "UPI_CPU0_CPU1_P2P2_DN<2>")
	)
	(arc
		(start 355.273864 -283.709364)
		(mid 355.138931 -283.842718)
		(end 355.086666 -284.025086)
		(width 0.0889)
		(layer "In6.Cu")
		(net "UPI_CPU0_CPU1_P2P2_DN<2>")
	)
	(arc
		(start 353.391216 -289.278314)
		(mid 353.565292 -289.417277)
		(end 353.676458 -289.610292)
		(width 0.0889)
		(layer "In6.Cu")
		(net "UPI_CPU0_CPU1_P2P2_DN<2>")
	)
	(arc
		(start 353.385628 -288.597848)
		(mid 353.254714 -288.734208)
		(end 353.207066 -288.917126)
		(width 0.0889)
		(layer "In6.Cu")
		(net "UPI_CPU0_CPU1_P2P2_DN<2>")
	)
	(arc
		(start 354.795074 -284.52826)
		(mid 354.66416 -284.66462)
		(end 354.616512 -284.847538)
		(width 0.0889)
		(layer "In6.Cu")
		(net "UPI_CPU0_CPU1_P2P2_DN<2>")
	)
	(arc
		(start 87.511128 -285.167324)
		(mid 87.690279 -284.848104)
		(end 87.512144 -284.52826)
		(width 0.0889)
		(layer "In6.Cu")
		(net "UPI_CPU0_CPU1_P2P2_DN<2>")
	)
	(arc
		(start 354.616512 -284.863032)
		(mid 354.537142 -285.136766)
		(end 354.334318 -285.336996)
		(width 0.0889)
		(layer "In6.Cu")
		(net "UPI_CPU0_CPU1_P2P2_DN<2>")
	)
	(arc
		(start 87.502746 -283.544518)
		(mid 87.638037 -283.410736)
		(end 87.690198 -283.22778)
		(width 0.0889)
		(layer "In6.Cu")
		(net "UPI_CPU0_CPU1_P2P2_DN<2>")
	)
	(arc
		(start 354.325428 -285.342076)
		(mid 354.197109 -285.474048)
		(end 354.14712 -285.651194)
		(width 0.0889)
		(layer "In6.Cu")
		(net "UPI_CPU0_CPU1_P2P2_DN<2>")
	)
	(arc
		(start 87.90051 -282.779216)
		(mid 87.908956 -282.772531)
		(end 87.917528 -282.766008)
		(width 0.0889)
		(layer "In6.Cu")
		(net "UPI_CPU0_CPU1_P2P2_DN<2>")
	)
	(arc
		(start 355.556566 -283.219906)
		(mid 355.482575 -283.499472)
		(end 355.27996 -283.705808)
		(width 0.0889)
		(layer "In6.Cu")
		(net "UPI_CPU0_CPU1_P2P2_DN<2>")
	)
	(arc
		(start 354.14712 -285.651194)
		(mid 354.14704 -285.663642)
		(end 354.147374 -285.676086)
		(width 0.0889)
		(layer "In6.Cu")
		(net "UPI_CPU0_CPU1_P2P2_DN<2>")
	)
	(arc
		(start 86.092792 -286.964882)
		(mid 85.888457 -286.762277)
		(end 85.810344 -286.48533)
		(width 0.0889)
		(layer "In6.Cu")
		(net "UPI_CPU0_CPU1_P2P2_DN<2>")
	)
	(arc
		(start 355.086666 -284.033722)
		(mid 355.012675 -284.313288)
		(end 354.81006 -284.519624)
		(width 0.0889)
		(layer "In6.Cu")
		(net "UPI_CPU0_CPU1_P2P2_DN<2>")
	)
	(arc
		(start 354.616512 -286.490918)
		(mid 354.537142 -286.764652)
		(end 354.334318 -286.964882)
		(width 0.0889)
		(layer "In6.Cu")
		(net "UPI_CPU0_CPU1_P2P2_DN<2>")
	)
	(arc
		(start 353.207066 -289.078416)
		(mid 353.282071 -289.193875)
		(end 353.391216 -289.277806)
		(width 0.0889)
		(layer "In6.Cu")
		(net "UPI_CPU0_CPU1_P2P2_DN<2>")
	)
	(arc
		(start 87.690198 -283.219652)
		(mid 87.74568 -282.975764)
		(end 87.901018 -282.779724)
		(width 0.0889)
		(layer "In6.Cu")
		(net "UPI_CPU0_CPU1_P2P2_DN<2>")
	)
	(arc
		(start 354.325428 -286.969962)
		(mid 354.194514 -287.106322)
		(end 354.146866 -287.28924)
		(width 0.0889)
		(layer "In6.Cu")
		(net "UPI_CPU0_CPU1_P2P2_DN<2>")
	)
	(arc
		(start 86.658196 -285.985712)
		(mid 87.032671 -285.985666)
		(end 87.220044 -285.661354)
		(width 0.0889)
		(layer "In6.Cu")
		(net "UPI_CPU0_CPU1_P2P2_DN<2>")
	)
	(arc
		(start 87.256112 -285.463234)
		(mid 87.353844 -285.296619)
		(end 87.501984 -285.172658)
		(width 0.0889)
		(layer "In6.Cu")
		(net "UPI_CPU0_CPU1_P2P2_DN<2>")
	)
	(arc
		(start 354.29698 -281.88666)
		(mid 354.30672 -281.882503)
		(end 354.316538 -281.878532)
		(width 0.0889)
		(layer "In6.Cu")
		(net "UPI_CPU0_CPU1_P2P2_DN<2>")
	)
	(arc
		(start 355.273864 -282.730194)
		(mid 355.477345 -282.930998)
		(end 355.556566 -283.205682)
		(width 0.0889)
		(layer "In6.Cu")
		(net "UPI_CPU0_CPU1_P2P2_DN<2>")
	)
	(arc
		(start 354.804218 -281.916378)
		(mid 355.007041 -282.116609)
		(end 355.086412 -282.390342)
		(width 0.0889)
		(layer "In6.Cu")
		(net "UPI_CPU0_CPU1_P2P2_DN<2>")
	)
	(arc
		(start 354.334318 -285.985712)
		(mid 354.5356 -286.183199)
		(end 354.616512 -286.453326)
		(width 0.0889)
		(layer "In6.Cu")
		(net "UPI_CPU0_CPU1_P2P2_DN<2>")
	)
	(segment
		(start 333.375762 -284.311598)
		(end 333.375762 -284.847538)
		(width 0.13208)
		(layer "F.Cu")
		(net "UPI_CPU0_CPU1_P2P2_DN<23>")
	)
	(segment
		(start 105.171494 -274.54479)
		(end 105.171494 -275.080476)
		(width 0.13208)
		(layer "F.Cu")
		(net "UPI_CPU0_CPU1_P2P2_DN<23>")
	)
	(segment
		(start 105.171494 -275.080476)
		(end 105.171748 -275.08073)
		(width 0.13208)
		(layer "F.Cu")
		(net "UPI_CPU0_CPU1_P2P2_DN<23>")
	)
	(segment
		(start 111.375698 -283.229812)
		(end 111.375698 -283.21127)
		(width 0.0889)
		(layer "In6.Cu")
		(net "UPI_CPU0_CPU1_P2P2_DN<23>")
	)
	(segment
		(start 109.35208 -292.35527)
		(end 109.35208 -291.648388)
		(width 0.14732)
		(layer "In6.Cu")
		(net "UPI_CPU0_CPU1_P2P2_DN<23>")
	)
	(segment
		(start 252.693932 -344.716862)
		(end 252.693932 -344.924634)
		(width 0.14732)
		(layer "In6.Cu")
		(net "UPI_CPU0_CPU1_P2P2_DN<23>")
	)
	(segment
		(start 112.315244 -279.986232)
		(end 112.315244 -279.964134)
		(width 0.0889)
		(layer "In6.Cu")
		(net "UPI_CPU0_CPU1_P2P2_DN<23>")
	)
	(segment
		(start 258.623562 -338.787232)
		(end 257.691636 -337.855306)
		(width 0.14732)
		(layer "In6.Cu")
		(net "UPI_CPU0_CPU1_P2P2_DN<23>")
	)
	(segment
		(start 273.957034 -322.61556)
		(end 273.649186 -322.923408)
		(width 0.14732)
		(layer "In6.Cu")
		(net "UPI_CPU0_CPU1_P2P2_DN<23>")
	)
	(segment
		(start 253.91491 -343.703656)
		(end 253.707138 -343.703656)
		(width 0.14732)
		(layer "In6.Cu")
		(net "UPI_CPU0_CPU1_P2P2_DN<23>")
	)
	(segment
		(start 112.03305 -276.219158)
		(end 112.02416 -276.214078)
		(width 0.0889)
		(layer "In6.Cu")
		(net "UPI_CPU0_CPU1_P2P2_DN<23>")
	)
	(segment
		(start 78.056232 -356.049326)
		(end 77.676248 -355.132132)
		(width 0.14732)
		(layer "In6.Cu")
		(net "UPI_CPU0_CPU1_P2P2_DN<23>")
	)
	(segment
		(start 257.610356 -339.800438)
		(end 257.610356 -340.00821)
		(width 0.14732)
		(layer "In6.Cu")
		(net "UPI_CPU0_CPU1_P2P2_DN<23>")
	)
	(segment
		(start 295.692068 -317.776352)
		(end 290.80333 -317.776352)
		(width 0.14732)
		(layer "In6.Cu")
		(net "UPI_CPU0_CPU1_P2P2_DN<23>")
	)
	(segment
		(start 111.562896 -281.267662)
		(end 111.563658 -281.267154)
		(width 0.0889)
		(layer "In6.Cu")
		(net "UPI_CPU0_CPU1_P2P2_DN<23>")
	)
	(segment
		(start 252.06833 -345.342464)
		(end 251.136404 -344.410538)
		(width 0.14732)
		(layer "In6.Cu")
		(net "UPI_CPU0_CPU1_P2P2_DN<23>")
	)
	(segment
		(start 78.950058 -325.708264)
		(end 79.210916 -325.447406)
		(width 0.14732)
		(layer "In6.Cu")
		(net "UPI_CPU0_CPU1_P2P2_DN<23>")
	)
	(segment
		(start 286.547306 -321.520312)
		(end 283.904182 -322.61556)
		(width 0.14732)
		(layer "In6.Cu")
		(net "UPI_CPU0_CPU1_P2P2_DN<23>")
	)
	(segment
		(start 258.317238 -336.79384)
		(end 258.317238 -337.229704)
		(width 0.14732)
		(layer "In6.Cu")
		(net "UPI_CPU0_CPU1_P2P2_DN<23>")
	)
	(segment
		(start 332.14691 -287.157668)
		(end 332.14691 -287.179766)
		(width 0.0889)
		(layer "In6.Cu")
		(net "UPI_CPU0_CPU1_P2P2_DN<23>")
	)
	(segment
		(start 298.081954 -317.810388)
		(end 297.210988 -316.939422)
		(width 0.14732)
		(layer "In6.Cu")
		(net "UPI_CPU0_CPU1_P2P2_DN<23>")
	)
	(segment
		(start 333.376016 -285.222188)
		(end 333.117952 -285.329122)
		(width 0.0889)
		(layer "In6.Cu")
		(net "UPI_CPU0_CPU1_P2P2_DN<23>")
	)
	(segment
		(start 255.553718 -342.064848)
		(end 255.345946 -342.064848)
		(width 0.14732)
		(layer "In6.Cu")
		(net "UPI_CPU0_CPU1_P2P2_DN<23>")
	)
	(segment
		(start 259.249164 -338.16163)
		(end 259.249164 -338.369402)
		(width 0.14732)
		(layer "In6.Cu")
		(net "UPI_CPU0_CPU1_P2P2_DN<23>")
	)
	(segment
		(start 250.123198 -345.423744)
		(end 251.055124 -346.35567)
		(width 0.14732)
		(layer "In6.Cu")
		(net "UPI_CPU0_CPU1_P2P2_DN<23>")
	)
	(segment
		(start 255.039622 -340.071456)
		(end 255.039622 -340.50732)
		(width 0.14732)
		(layer "In6.Cu")
		(net "UPI_CPU0_CPU1_P2P2_DN<23>")
	)
	(segment
		(start 109.674406 -286.156146)
		(end 109.683296 -286.151066)
		(width 0.0889)
		(layer "In6.Cu")
		(net "UPI_CPU0_CPU1_P2P2_DN<23>")
	)
	(segment
		(start 251.136404 -344.410538)
		(end 250.70054 -344.410538)
		(width 0.14732)
		(layer "In6.Cu")
		(net "UPI_CPU0_CPU1_P2P2_DN<23>")
	)
	(segment
		(start 109.23397 -289.329622)
		(end 109.232446 -289.32886)
		(width 0.0889)
		(layer "In6.Cu")
		(net "UPI_CPU0_CPU1_P2P2_DN<23>")
	)
	(segment
		(start 76.845668 -328.81062)
		(end 76.845668 -328.810366)
		(width 0.14732)
		(layer "In6.Cu")
		(net "UPI_CPU0_CPU1_P2P2_DN<23>")
	)
	(segment
		(start 311.720738 -307.68798)
		(end 310.20258 -308.317138)
		(width 0.14732)
		(layer "In6.Cu")
		(net "UPI_CPU0_CPU1_P2P2_DN<23>")
	)
	(segment
		(start 283.904182 -322.61556)
		(end 273.957034 -322.61556)
		(width 0.14732)
		(layer "In6.Cu")
		(net "UPI_CPU0_CPU1_P2P2_DN<23>")
	)
	(segment
		(start 251.055124 -346.563442)
		(end 250.637294 -346.981272)
		(width 0.14732)
		(layer "In6.Cu")
		(net "UPI_CPU0_CPU1_P2P2_DN<23>")
	)
	(segment
		(start 251.762006 -343.349072)
		(end 251.762006 -343.784936)
		(width 0.14732)
		(layer "In6.Cu")
		(net "UPI_CPU0_CPU1_P2P2_DN<23>")
	)
	(segment
		(start 333.375762 -284.847538)
		(end 333.688436 -284.847538)
		(width 0.0889)
		(layer "In6.Cu")
		(net "UPI_CPU0_CPU1_P2P2_DN<23>")
	)
	(segment
		(start 297.210988 -316.939422)
		(end 296.528998 -316.939422)
		(width 0.14732)
		(layer "In6.Cu")
		(net "UPI_CPU0_CPU1_P2P2_DN<23>")
	)
	(segment
		(start 296.528998 -316.939422)
		(end 295.692068 -317.776352)
		(width 0.14732)
		(layer "In6.Cu")
		(net "UPI_CPU0_CPU1_P2P2_DN<23>")
	)
	(segment
		(start 250.70054 -344.410538)
		(end 250.123198 -344.98788)
		(width 0.14732)
		(layer "In6.Cu")
		(net "UPI_CPU0_CPU1_P2P2_DN<23>")
	)
	(segment
		(start 100.94595 -369.439952)
		(end 82.327496 -361.728258)
		(width 0.14732)
		(layer "In6.Cu")
		(net "UPI_CPU0_CPU1_P2P2_DN<23>")
	)
	(segment
		(start 332.146656 -287.315148)
		(end 332.146656 -287.53308)
		(width 0.14732)
		(layer "In6.Cu")
		(net "UPI_CPU0_CPU1_P2P2_DN<23>")
	)
	(segment
		(start 272.912586 -323.56679)
		(end 272.765266 -323.41947)
		(width 0.14732)
		(layer "In6.Cu")
		(net "UPI_CPU0_CPU1_P2P2_DN<23>")
	)
	(segment
		(start 318.102996 -307.610256)
		(end 314.059824 -307.610256)
		(width 0.14732)
		(layer "In6.Cu")
		(net "UPI_CPU0_CPU1_P2P2_DN<23>")
	)
	(segment
		(start 288.06902 -321.520312)
		(end 286.547306 -321.520312)
		(width 0.14732)
		(layer "In6.Cu")
		(net "UPI_CPU0_CPU1_P2P2_DN<23>")
	)
	(segment
		(start 299.154088 -317.810388)
		(end 298.081954 -317.810388)
		(width 0.14732)
		(layer "In6.Cu")
		(net "UPI_CPU0_CPU1_P2P2_DN<23>")
	)
	(segment
		(start 111.563658 -281.267154)
		(end 111.568992 -281.264106)
		(width 0.0889)
		(layer "In6.Cu")
		(net "UPI_CPU0_CPU1_P2P2_DN<23>")
	)
	(segment
		(start 75.890628 -335.157826)
		(end 76.333604 -330.656184)
		(width 0.14732)
		(layer "In6.Cu")
		(net "UPI_CPU0_CPU1_P2P2_DN<23>")
	)
	(segment
		(start 273.501866 -323.56679)
		(end 272.912586 -323.56679)
		(width 0.14732)
		(layer "In6.Cu")
		(net "UPI_CPU0_CPU1_P2P2_DN<23>")
	)
	(segment
		(start 109.965744 -285.679896)
		(end 109.965744 -285.661354)
		(width 0.0889)
		(layer "In6.Cu")
		(net "UPI_CPU0_CPU1_P2P2_DN<23>")
	)
	(segment
		(start 106.308906 -275.398992)
		(end 106.298492 -275.405088)
		(width 0.0889)
		(layer "In6.Cu")
		(net "UPI_CPU0_CPU1_P2P2_DN<23>")
	)
	(segment
		(start 75.890628 -350.819212)
		(end 75.890628 -335.157826)
		(width 0.14732)
		(layer "In6.Cu")
		(net "UPI_CPU0_CPU1_P2P2_DN<23>")
	)
	(segment
		(start 108.813854 -298.011596)
		(end 109.155484 -297.186096)
		(width 0.14732)
		(layer "In6.Cu")
		(net "UPI_CPU0_CPU1_P2P2_DN<23>")
	)
	(segment
		(start 78.055978 -356.04958)
		(end 78.056232 -356.049326)
		(width 0.14732)
		(layer "In6.Cu")
		(net "UPI_CPU0_CPU1_P2P2_DN<23>")
	)
	(segment
		(start 79.210916 -325.447406)
		(end 79.210916 -325.242682)
		(width 0.14732)
		(layer "In6.Cu")
		(net "UPI_CPU0_CPU1_P2P2_DN<23>")
	)
	(segment
		(start 109.155484 -292.829742)
		(end 109.35208 -292.35527)
		(width 0.14732)
		(layer "In6.Cu")
		(net "UPI_CPU0_CPU1_P2P2_DN<23>")
	)
	(segment
		(start 111.845598 -275.8948)
		(end 111.845598 -275.880576)
		(width 0.0889)
		(layer "In6.Cu")
		(net "UPI_CPU0_CPU1_P2P2_DN<23>")
	)
	(segment
		(start 261.77494 -326.334628)
		(end 261.77494 -333.336138)
		(width 0.14732)
		(layer "In6.Cu")
		(net "UPI_CPU0_CPU1_P2P2_DN<23>")
	)
	(segment
		(start 78.307946 -356.657656)
		(end 78.386432 -356.468426)
		(width 0.14732)
		(layer "In6.Cu")
		(net "UPI_CPU0_CPU1_P2P2_DN<23>")
	)
	(segment
		(start 108.556298 -288.195258)
		(end 108.556298 -288.09442)
		(width 0.0889)
		(layer "In6.Cu")
		(net "UPI_CPU0_CPU1_P2P2_DN<23>")
	)
	(segment
		(start 76.823824 -353.072954)
		(end 76.576428 -352.475292)
		(width 0.14732)
		(layer "In6.Cu")
		(net "UPI_CPU0_CPU1_P2P2_DN<23>")
	)
	(segment
		(start 126.45644 -373.224044)
		(end 100.94595 -369.439952)
		(width 0.14732)
		(layer "In6.Cu")
		(net "UPI_CPU0_CPU1_P2P2_DN<23>")
	)
	(segment
		(start 112.02416 -280.458926)
		(end 112.03305 -280.453846)
		(width 0.0889)
		(layer "In6.Cu")
		(net "UPI_CPU0_CPU1_P2P2_DN<23>")
	)
	(segment
		(start 109.026198 -287.28924)
		(end 109.026198 -287.280604)
		(width 0.0889)
		(layer "In6.Cu")
		(net "UPI_CPU0_CPU1_P2P2_DN<23>")
	)
	(segment
		(start 288.491676 -321.942968)
		(end 288.06902 -321.520312)
		(width 0.14732)
		(layer "In6.Cu")
		(net "UPI_CPU0_CPU1_P2P2_DN<23>")
	)
	(segment
		(start 112.493806 -279.644856)
		(end 112.508792 -279.635966)
		(width 0.0889)
		(layer "In6.Cu")
		(net "UPI_CPU0_CPU1_P2P2_DN<23>")
	)
	(segment
		(start 332.18882 -287.115758)
		(end 332.14691 -287.157668)
		(width 0.0889)
		(layer "In6.Cu")
		(net "UPI_CPU0_CPU1_P2P2_DN<23>")
	)
	(segment
		(start 290.312348 -321.678554)
		(end 290.047934 -321.942968)
		(width 0.14732)
		(layer "In6.Cu")
		(net "UPI_CPU0_CPU1_P2P2_DN<23>")
	)
	(segment
		(start 269.872206 -324.369938)
		(end 269.724886 -324.517258)
		(width 0.14732)
		(layer "In6.Cu")
		(net "UPI_CPU0_CPU1_P2P2_DN<23>")
	)
	(segment
		(start 77.75448 -354.94214)
		(end 77.61351 -354.60178)
		(width 0.14732)
		(layer "In6.Cu")
		(net "UPI_CPU0_CPU1_P2P2_DN<23>")
	)
	(segment
		(start 80.148176 -324.305422)
		(end 81.688432 -322.764912)
		(width 0.14732)
		(layer "In6.Cu")
		(net "UPI_CPU0_CPU1_P2P2_DN<23>")
	)
	(segment
		(start 272.457418 -322.61556)
		(end 270.180054 -322.61556)
		(width 0.14732)
		(layer "In6.Cu")
		(net "UPI_CPU0_CPU1_P2P2_DN<23>")
	)
	(segment
		(start 332.14691 -287.179766)
		(end 332.14691 -287.314894)
		(width 0.14732)
		(layer "In6.Cu")
		(net "UPI_CPU0_CPU1_P2P2_DN<23>")
	)
	(segment
		(start 258.89458 -336.216498)
		(end 258.317238 -336.79384)
		(width 0.14732)
		(layer "In6.Cu")
		(net "UPI_CPU0_CPU1_P2P2_DN<23>")
	)
	(segment
		(start 109.49559 -291.073078)
		(end 109.49559 -289.832034)
		(width 0.0889)
		(layer "In6.Cu")
		(net "UPI_CPU0_CPU1_P2P2_DN<23>")
	)
	(segment
		(start 258.831334 -338.787232)
		(end 258.623562 -338.787232)
		(width 0.14732)
		(layer "In6.Cu")
		(net "UPI_CPU0_CPU1_P2P2_DN<23>")
	)
	(segment
		(start 109.025944 -288.97326)
		(end 109.03204 -288.863278)
		(width 0.0889)
		(layer "In6.Cu")
		(net "UPI_CPU0_CPU1_P2P2_DN<23>")
	)
	(segment
		(start 109.155484 -297.186096)
		(end 109.155484 -292.829742)
		(width 0.14732)
		(layer "In6.Cu")
		(net "UPI_CPU0_CPU1_P2P2_DN<23>")
	)
	(segment
		(start 81.688432 -322.764912)
		(end 98.959162 -308.591712)
		(width 0.14732)
		(layer "In6.Cu")
		(net "UPI_CPU0_CPU1_P2P2_DN<23>")
	)
	(segment
		(start 260.470142 -337.148424)
		(end 260.26237 -337.148424)
		(width 0.14732)
		(layer "In6.Cu")
		(net "UPI_CPU0_CPU1_P2P2_DN<23>")
	)
	(segment
		(start 253.400814 -342.146128)
		(end 254.33274 -343.078054)
		(width 0.14732)
		(layer "In6.Cu")
		(net "UPI_CPU0_CPU1_P2P2_DN<23>")
	)
	(segment
		(start 256.67843 -338.868512)
		(end 257.610356 -339.800438)
		(width 0.14732)
		(layer "In6.Cu")
		(net "UPI_CPU0_CPU1_P2P2_DN<23>")
	)
	(segment
		(start 250.637294 -346.981272)
		(end 250.429522 -346.981272)
		(width 0.14732)
		(layer "In6.Cu")
		(net "UPI_CPU0_CPU1_P2P2_DN<23>")
	)
	(segment
		(start 111.08436 -283.714444)
		(end 111.085122 -283.713936)
		(width 0.0889)
		(layer "In6.Cu")
		(net "UPI_CPU0_CPU1_P2P2_DN<23>")
	)
	(segment
		(start 77.923898 -326.5297)
		(end 78.745334 -325.708264)
		(width 0.14732)
		(layer "In6.Cu")
		(net "UPI_CPU0_CPU1_P2P2_DN<23>")
	)
	(segment
		(start 299.5295 -315.284612)
		(end 299.5295 -317.355728)
		(width 0.14732)
		(layer "In6.Cu")
		(net "UPI_CPU0_CPU1_P2P2_DN<23>")
	)
	(segment
		(start 308.798214 -309.25516)
		(end 308.023514 -310.02986)
		(width 0.14732)
		(layer "In6.Cu")
		(net "UPI_CPU0_CPU1_P2P2_DN<23>")
	)
	(segment
		(start 76.333604 -330.656184)
		(end 76.845668 -328.81062)
		(width 0.14732)
		(layer "In6.Cu")
		(net "UPI_CPU0_CPU1_P2P2_DN<23>")
	)
	(segment
		(start 270.180054 -322.61556)
		(end 269.872206 -322.923408)
		(width 0.14732)
		(layer "In6.Cu")
		(net "UPI_CPU0_CPU1_P2P2_DN<23>")
	)
	(segment
		(start 78.245462 -356.127812)
		(end 78.055978 -356.04958)
		(width 0.14732)
		(layer "In6.Cu")
		(net "UPI_CPU0_CPU1_P2P2_DN<23>")
	)
	(segment
		(start 112.508792 -278.664416)
		(end 112.493806 -278.65578)
		(width 0.0889)
		(layer "In6.Cu")
		(net "UPI_CPU0_CPU1_P2P2_DN<23>")
	)
	(segment
		(start 111.085122 -283.713936)
		(end 111.089948 -283.711396)
		(width 0.0889)
		(layer "In6.Cu")
		(net "UPI_CPU0_CPU1_P2P2_DN<23>")
	)
	(segment
		(start 82.327496 -361.728258)
		(end 79.050642 -358.451404)
		(width 0.14732)
		(layer "In6.Cu")
		(net "UPI_CPU0_CPU1_P2P2_DN<23>")
	)
	(segment
		(start 105.015284 -275.351748)
		(end 105.171748 -275.08073)
		(width 0.0889)
		(layer "In6.Cu")
		(net "UPI_CPU0_CPU1_P2P2_DN<23>")
	)
	(segment
		(start 111.568992 -281.919934)
		(end 111.563658 -281.916886)
		(width 0.0889)
		(layer "In6.Cu")
		(net "UPI_CPU0_CPU1_P2P2_DN<23>")
	)
	(segment
		(start 110.61446 -284.52826)
		(end 110.62335 -284.52318)
		(width 0.0889)
		(layer "In6.Cu")
		(net "UPI_CPU0_CPU1_P2P2_DN<23>")
	)
	(segment
		(start 331.943964 -288.02203)
		(end 329.322938 -291.926772)
		(width 0.14732)
		(layer "In6.Cu")
		(net "UPI_CPU0_CPU1_P2P2_DN<23>")
	)
	(segment
		(start 79.210916 -325.242682)
		(end 79.682594 -324.771004)
		(width 0.14732)
		(layer "In6.Cu")
		(net "UPI_CPU0_CPU1_P2P2_DN<23>")
	)
	(segment
		(start 111.845598 -282.42006)
		(end 111.845598 -282.405836)
		(width 0.0889)
		(layer "In6.Cu")
		(net "UPI_CPU0_CPU1_P2P2_DN<23>")
	)
	(segment
		(start 257.610356 -340.00821)
		(end 257.192526 -340.42604)
		(width 0.14732)
		(layer "In6.Cu")
		(net "UPI_CPU0_CPU1_P2P2_DN<23>")
	)
	(segment
		(start 108.23829 -298.787566)
		(end 108.23829 -298.787312)
		(width 0.14732)
		(layer "In6.Cu")
		(net "UPI_CPU0_CPU1_P2P2_DN<23>")
	)
	(segment
		(start 109.232446 -289.32886)
		(end 109.193838 -289.306508)
		(width 0.0889)
		(layer "In6.Cu")
		(net "UPI_CPU0_CPU1_P2P2_DN<23>")
	)
	(segment
		(start 254.41402 -341.132922)
		(end 253.978156 -341.132922)
		(width 0.14732)
		(layer "In6.Cu")
		(net "UPI_CPU0_CPU1_P2P2_DN<23>")
	)
	(segment
		(start 255.345946 -342.064848)
		(end 254.41402 -341.132922)
		(width 0.14732)
		(layer "In6.Cu")
		(net "UPI_CPU0_CPU1_P2P2_DN<23>")
	)
	(segment
		(start 111.092488 -283.709872)
		(end 111.09325 -283.709364)
		(width 0.0889)
		(layer "In6.Cu")
		(net "UPI_CPU0_CPU1_P2P2_DN<23>")
	)
	(segment
		(start 253.707138 -343.703656)
		(end 252.775212 -342.77173)
		(width 0.14732)
		(layer "In6.Cu")
		(net "UPI_CPU0_CPU1_P2P2_DN<23>")
	)
	(segment
		(start 272.765266 -323.41947)
		(end 272.765266 -322.923408)
		(width 0.14732)
		(layer "In6.Cu")
		(net "UPI_CPU0_CPU1_P2P2_DN<23>")
	)
	(segment
		(start 272.765266 -322.923408)
		(end 272.457418 -322.61556)
		(width 0.14732)
		(layer "In6.Cu")
		(net "UPI_CPU0_CPU1_P2P2_DN<23>")
	)
	(segment
		(start 112.508792 -279.635966)
		(end 112.508792 -279.63622)
		(width 0.0889)
		(layer "In6.Cu")
		(net "UPI_CPU0_CPU1_P2P2_DN<23>")
	)
	(segment
		(start 259.330444 -336.216498)
		(end 258.89458 -336.216498)
		(width 0.14732)
		(layer "In6.Cu")
		(net "UPI_CPU0_CPU1_P2P2_DN<23>")
	)
	(segment
		(start 78.386432 -356.468426)
		(end 78.245462 -356.127812)
		(width 0.14732)
		(layer "In6.Cu")
		(net "UPI_CPU0_CPU1_P2P2_DN<23>")
	)
	(segment
		(start 215.292686 -367.94821)
		(end 199.051418 -365.084614)
		(width 0.14732)
		(layer "In6.Cu")
		(net "UPI_CPU0_CPU1_P2P2_DN<23>")
	)
	(segment
		(start 253.978156 -341.132922)
		(end 253.400814 -341.710264)
		(width 0.14732)
		(layer "In6.Cu")
		(net "UPI_CPU0_CPU1_P2P2_DN<23>")
	)
	(segment
		(start 77.013054 -353.151186)
		(end 76.823824 -353.072954)
		(width 0.14732)
		(layer "In6.Cu")
		(net "UPI_CPU0_CPU1_P2P2_DN<23>")
	)
	(segment
		(start 77.42428 -354.523294)
		(end 77.075538 -353.68103)
		(width 0.14732)
		(layer "In6.Cu")
		(net "UPI_CPU0_CPU1_P2P2_DN<23>")
	)
	(segment
		(start 248.293382 -350.229932)
		(end 243.937028 -354.586032)
		(width 0.14732)
		(layer "In6.Cu")
		(net "UPI_CPU0_CPU1_P2P2_DN<23>")
	)
	(segment
		(start 269.724886 -324.517258)
		(end 269.135606 -324.517258)
		(width 0.14732)
		(layer "In6.Cu")
		(net "UPI_CPU0_CPU1_P2P2_DN<23>")
	)
	(segment
		(start 110.144306 -285.342076)
		(end 110.153196 -285.336996)
		(width 0.0889)
		(layer "In6.Cu")
		(net "UPI_CPU0_CPU1_P2P2_DN<23>")
	)
	(segment
		(start 109.35208 -291.638228)
		(end 109.309916 -291.596064)
		(width 0.0889)
		(layer "In6.Cu")
		(net "UPI_CPU0_CPU1_P2P2_DN<23>")
	)
	(segment
		(start 269.135606 -324.517258)
		(end 268.988286 -324.369938)
		(width 0.14732)
		(layer "In6.Cu")
		(net "UPI_CPU0_CPU1_P2P2_DN<23>")
	)
	(segment
		(start 290.312348 -318.267334)
		(end 290.312348 -321.678554)
		(width 0.14732)
		(layer "In6.Cu")
		(net "UPI_CPU0_CPU1_P2P2_DN<23>")
	)
	(segment
		(start 152.889712 -373.224044)
		(end 126.45644 -373.224044)
		(width 0.14732)
		(layer "In6.Cu")
		(net "UPI_CPU0_CPU1_P2P2_DN<23>")
	)
	(segment
		(start 251.762006 -343.784936)
		(end 252.693932 -344.716862)
		(width 0.14732)
		(layer "In6.Cu")
		(net "UPI_CPU0_CPU1_P2P2_DN<23>")
	)
	(segment
		(start 259.249164 -338.369402)
		(end 258.831334 -338.787232)
		(width 0.14732)
		(layer "In6.Cu")
		(net "UPI_CPU0_CPU1_P2P2_DN<23>")
	)
	(segment
		(start 105.036366 -275.429726)
		(end 105.015284 -275.351748)
		(width 0.0889)
		(layer "In6.Cu")
		(net "UPI_CPU0_CPU1_P2P2_DN<23>")
	)
	(segment
		(start 256.67843 -338.432648)
		(end 256.67843 -338.868512)
		(width 0.14732)
		(layer "In6.Cu")
		(net "UPI_CPU0_CPU1_P2P2_DN<23>")
	)
	(segment
		(start 228.073712 -365.694468)
		(end 215.292686 -367.94821)
		(width 0.14732)
		(layer "In6.Cu")
		(net "UPI_CPU0_CPU1_P2P2_DN<23>")
	)
	(segment
		(start 108.743496 -287.778698)
		(end 108.749592 -287.775142)
		(width 0.0889)
		(layer "In6.Cu")
		(net "UPI_CPU0_CPU1_P2P2_DN<23>")
	)
	(segment
		(start 76.845668 -328.810366)
		(end 77.38491 -327.669906)
		(width 0.14732)
		(layer "In6.Cu")
		(net "UPI_CPU0_CPU1_P2P2_DN<23>")
	)
	(segment
		(start 269.872206 -322.923408)
		(end 269.872206 -324.369938)
		(width 0.14732)
		(layer "In6.Cu")
		(net "UPI_CPU0_CPU1_P2P2_DN<23>")
	)
	(segment
		(start 333.688436 -284.847538)
		(end 333.74584 -284.904942)
		(width 0.0889)
		(layer "In6.Cu")
		(net "UPI_CPU0_CPU1_P2P2_DN<23>")
	)
	(segment
		(start 273.649186 -322.923408)
		(end 273.649186 -323.41947)
		(width 0.14732)
		(layer "In6.Cu")
		(net "UPI_CPU0_CPU1_P2P2_DN<23>")
	)
	(segment
		(start 253.400814 -341.710264)
		(end 253.400814 -342.146128)
		(width 0.14732)
		(layer "In6.Cu")
		(net "UPI_CPU0_CPU1_P2P2_DN<23>")
	)
	(segment
		(start 110.157006 -285.33471)
		(end 110.165388 -285.329884)
		(width 0.0889)
		(layer "In6.Cu")
		(net "UPI_CPU0_CPU1_P2P2_DN<23>")
	)
	(segment
		(start 80.148176 -324.510146)
		(end 80.148176 -324.305422)
		(width 0.14732)
		(layer "In6.Cu")
		(net "UPI_CPU0_CPU1_P2P2_DN<23>")
	)
	(segment
		(start 111.375698 -281.600656)
		(end 111.375698 -281.583384)
		(width 0.0889)
		(layer "In6.Cu")
		(net "UPI_CPU0_CPU1_P2P2_DN<23>")
	)
	(segment
		(start 310.20258 -308.317138)
		(end 308.798214 -309.25516)
		(width 0.14732)
		(layer "In6.Cu")
		(net "UPI_CPU0_CPU1_P2P2_DN<23>")
	)
	(segment
		(start 257.255772 -337.855306)
		(end 256.67843 -338.432648)
		(width 0.14732)
		(layer "In6.Cu")
		(net "UPI_CPU0_CPU1_P2P2_DN<23>")
	)
	(segment
		(start 265.494008 -322.61556)
		(end 261.77494 -326.334628)
		(width 0.14732)
		(layer "In6.Cu")
		(net "UPI_CPU0_CPU1_P2P2_DN<23>")
	)
	(segment
		(start 255.616964 -339.494114)
		(end 255.039622 -340.071456)
		(width 0.14732)
		(layer "In6.Cu")
		(net "UPI_CPU0_CPU1_P2P2_DN<23>")
	)
	(segment
		(start 107.247436 -275.400008)
		(end 107.238546 -275.405088)
		(width 0.0889)
		(layer "In6.Cu")
		(net "UPI_CPU0_CPU1_P2P2_DN<23>")
	)
	(segment
		(start 78.745334 -325.708264)
		(end 78.950058 -325.708264)
		(width 0.14732)
		(layer "In6.Cu")
		(net "UPI_CPU0_CPU1_P2P2_DN<23>")
	)
	(segment
		(start 76.513944 -351.945702)
		(end 76.32446 -351.867216)
		(width 0.14732)
		(layer "In6.Cu")
		(net "UPI_CPU0_CPU1_P2P2_DN<23>")
	)
	(segment
		(start 260.887972 -336.730594)
		(end 260.470142 -337.148424)
		(width 0.14732)
		(layer "In6.Cu")
		(net "UPI_CPU0_CPU1_P2P2_DN<23>")
	)
	(segment
		(start 255.971548 -341.439246)
		(end 255.971548 -341.647018)
		(width 0.14732)
		(layer "In6.Cu")
		(net "UPI_CPU0_CPU1_P2P2_DN<23>")
	)
	(segment
		(start 112.315244 -276.708616)
		(end 112.315244 -276.693122)
		(width 0.0889)
		(layer "In6.Cu")
		(net "UPI_CPU0_CPU1_P2P2_DN<23>")
	)
	(segment
		(start 199.051418 -365.084614)
		(end 152.889712 -373.224044)
		(width 0.14732)
		(layer "In6.Cu")
		(net "UPI_CPU0_CPU1_P2P2_DN<23>")
	)
	(segment
		(start 79.050642 -358.451404)
		(end 78.307946 -356.657656)
		(width 0.14732)
		(layer "In6.Cu")
		(net "UPI_CPU0_CPU1_P2P2_DN<23>")
	)
	(segment
		(start 255.039622 -340.50732)
		(end 255.971548 -341.439246)
		(width 0.14732)
		(layer "In6.Cu")
		(net "UPI_CPU0_CPU1_P2P2_DN<23>")
	)
	(segment
		(start 268.680438 -322.61556)
		(end 265.494008 -322.61556)
		(width 0.14732)
		(layer "In6.Cu")
		(net "UPI_CPU0_CPU1_P2P2_DN<23>")
	)
	(segment
		(start 254.33274 -343.285826)
		(end 253.91491 -343.703656)
		(width 0.14732)
		(layer "In6.Cu")
		(net "UPI_CPU0_CPU1_P2P2_DN<23>")
	)
	(segment
		(start 111.375698 -275.089366)
		(end 111.375698 -275.070824)
		(width 0.0889)
		(layer "In6.Cu")
		(net "UPI_CPU0_CPU1_P2P2_DN<23>")
	)
	(segment
		(start 76.576428 -352.475292)
		(end 76.65466 -352.286062)
		(width 0.14732)
		(layer "In6.Cu")
		(net "UPI_CPU0_CPU1_P2P2_DN<23>")
	)
	(segment
		(start 107.425998 -275.065236)
		(end 107.425998 -275.08073)
		(width 0.0889)
		(layer "In6.Cu")
		(net "UPI_CPU0_CPU1_P2P2_DN<23>")
	)
	(segment
		(start 301.91583 -312.862722)
		(end 299.59046 -314.97016)
		(width 0.14732)
		(layer "In6.Cu")
		(net "UPI_CPU0_CPU1_P2P2_DN<23>")
	)
	(segment
		(start 111.09325 -274.591272)
		(end 111.082836 -274.585176)
		(width 0.0889)
		(layer "In6.Cu")
		(net "UPI_CPU0_CPU1_P2P2_DN<23>")
	)
	(segment
		(start 109.309916 -291.258752)
		(end 109.49559 -291.073078)
		(width 0.0889)
		(layer "In6.Cu")
		(net "UPI_CPU0_CPU1_P2P2_DN<23>")
	)
	(segment
		(start 77.38491 -327.669906)
		(end 77.923898 -326.5297)
		(width 0.14732)
		(layer "In6.Cu")
		(net "UPI_CPU0_CPU1_P2P2_DN<23>")
	)
	(segment
		(start 77.154024 -353.4918)
		(end 77.013054 -353.151186)
		(width 0.14732)
		(layer "In6.Cu")
		(net "UPI_CPU0_CPU1_P2P2_DN<23>")
	)
	(segment
		(start 259.956046 -335.590896)
		(end 260.887972 -336.522822)
		(width 0.14732)
		(layer "In6.Cu")
		(net "UPI_CPU0_CPU1_P2P2_DN<23>")
	)
	(segment
		(start 110.153196 -285.336996)
		(end 110.157006 -285.33471)
		(width 0.0889)
		(layer "In6.Cu")
		(net "UPI_CPU0_CPU1_P2P2_DN<23>")
	)
	(segment
		(start 332.14691 -287.314894)
		(end 332.146656 -287.315148)
		(width 0.14732)
		(layer "In6.Cu")
		(net "UPI_CPU0_CPU1_P2P2_DN<23>")
	)
	(segment
		(start 250.429522 -346.981272)
		(end 249.497596 -346.049346)
		(width 0.14732)
		(layer "In6.Cu")
		(net "UPI_CPU0_CPU1_P2P2_DN<23>")
	)
	(segment
		(start 313.875674 -307.68798)
		(end 311.720738 -307.68798)
		(width 0.14732)
		(layer "In6.Cu")
		(net "UPI_CPU0_CPU1_P2P2_DN<23>")
	)
	(segment
		(start 258.317238 -337.229704)
		(end 259.249164 -338.16163)
		(width 0.14732)
		(layer "In6.Cu")
		(net "UPI_CPU0_CPU1_P2P2_DN<23>")
	)
	(segment
		(start 327.369678 -298.343574)
		(end 318.102996 -307.610256)
		(width 0.14732)
		(layer "In6.Cu")
		(net "UPI_CPU0_CPU1_P2P2_DN<23>")
	)
	(segment
		(start 77.676248 -355.132132)
		(end 77.675994 -355.13137)
		(width 0.14732)
		(layer "In6.Cu")
		(net "UPI_CPU0_CPU1_P2P2_DN<23>")
	)
	(segment
		(start 77.075538 -353.68103)
		(end 77.154024 -353.4918)
		(width 0.14732)
		(layer "In6.Cu")
		(net "UPI_CPU0_CPU1_P2P2_DN<23>")
	)
	(segment
		(start 329.322938 -291.926772)
		(end 329.322938 -291.927026)
		(width 0.14732)
		(layer "In6.Cu")
		(net "UPI_CPU0_CPU1_P2P2_DN<23>")
	)
	(segment
		(start 112.508792 -277.03653)
		(end 112.493806 -277.02764)
		(width 0.0889)
		(layer "In6.Cu")
		(net "UPI_CPU0_CPU1_P2P2_DN<23>")
	)
	(segment
		(start 77.675994 -355.13137)
		(end 77.75448 -354.94214)
		(width 0.14732)
		(layer "In6.Cu")
		(net "UPI_CPU0_CPU1_P2P2_DN<23>")
	)
	(segment
		(start 333.117952 -285.329122)
		(end 332.18882 -286.258254)
		(width 0.0889)
		(layer "In6.Cu")
		(net "UPI_CPU0_CPU1_P2P2_DN<23>")
	)
	(segment
		(start 252.693932 -344.924634)
		(end 252.276102 -345.342464)
		(width 0.14732)
		(layer "In6.Cu")
		(net "UPI_CPU0_CPU1_P2P2_DN<23>")
	)
	(segment
		(start 332.18882 -286.258254)
		(end 332.18882 -287.115758)
		(width 0.0889)
		(layer "In6.Cu")
		(net "UPI_CPU0_CPU1_P2P2_DN<23>")
	)
	(segment
		(start 108.27385 -274.591272)
		(end 108.263436 -274.585176)
		(width 0.0889)
		(layer "In6.Cu")
		(net "UPI_CPU0_CPU1_P2P2_DN<23>")
	)
	(segment
		(start 109.35208 -291.648388)
		(end 109.35208 -291.638228)
		(width 0.0889)
		(layer "In6.Cu")
		(net "UPI_CPU0_CPU1_P2P2_DN<23>")
	)
	(segment
		(start 110.62335 -284.52318)
		(end 110.629446 -284.519624)
		(width 0.0889)
		(layer "In6.Cu")
		(net "UPI_CPU0_CPU1_P2P2_DN<23>")
	)
	(segment
		(start 329.322938 -291.927026)
		(end 327.369678 -298.343574)
		(width 0.14732)
		(layer "In6.Cu")
		(net "UPI_CPU0_CPU1_P2P2_DN<23>")
	)
	(segment
		(start 252.276102 -345.342464)
		(end 252.06833 -345.342464)
		(width 0.14732)
		(layer "In6.Cu")
		(net "UPI_CPU0_CPU1_P2P2_DN<23>")
	)
	(segment
		(start 259.956046 -335.155032)
		(end 259.956046 -335.590896)
		(width 0.14732)
		(layer "In6.Cu")
		(net "UPI_CPU0_CPU1_P2P2_DN<23>")
	)
	(segment
		(start 79.682594 -324.771004)
		(end 79.887318 -324.771004)
		(width 0.14732)
		(layer "In6.Cu")
		(net "UPI_CPU0_CPU1_P2P2_DN<23>")
	)
	(segment
		(start 243.937028 -354.586032)
		(end 228.073712 -365.694468)
		(width 0.14732)
		(layer "In6.Cu")
		(net "UPI_CPU0_CPU1_P2P2_DN<23>")
	)
	(segment
		(start 306.833778 -310.825388)
		(end 301.91583 -312.862722)
		(width 0.14732)
		(layer "In6.Cu")
		(net "UPI_CPU0_CPU1_P2P2_DN<23>")
	)
	(segment
		(start 299.59046 -314.97016)
		(end 299.5295 -315.284612)
		(width 0.14732)
		(layer "In6.Cu")
		(net "UPI_CPU0_CPU1_P2P2_DN<23>")
	)
	(segment
		(start 98.959162 -308.591712)
		(end 108.042964 -299.05071)
		(width 0.14732)
		(layer "In6.Cu")
		(net "UPI_CPU0_CPU1_P2P2_DN<23>")
	)
	(segment
		(start 333.74584 -284.904942)
		(end 333.746094 -284.904942)
		(width 0.0889)
		(layer "In6.Cu")
		(net "UPI_CPU0_CPU1_P2P2_DN<23>")
	)
	(segment
		(start 268.988286 -324.369938)
		(end 268.988286 -322.923408)
		(width 0.14732)
		(layer "In6.Cu")
		(net "UPI_CPU0_CPU1_P2P2_DN<23>")
	)
	(segment
		(start 290.047934 -321.942968)
		(end 288.491676 -321.942968)
		(width 0.14732)
		(layer "In6.Cu")
		(net "UPI_CPU0_CPU1_P2P2_DN<23>")
	)
	(segment
		(start 249.497596 -346.049346)
		(end 249.061732 -346.049346)
		(width 0.14732)
		(layer "In6.Cu")
		(net "UPI_CPU0_CPU1_P2P2_DN<23>")
	)
	(segment
		(start 109.495844 -286.48533)
		(end 109.495844 -286.475424)
		(width 0.0889)
		(layer "In6.Cu")
		(net "UPI_CPU0_CPU1_P2P2_DN<23>")
	)
	(segment
		(start 112.493806 -277.02764)
		(end 112.493806 -277.027894)
		(width 0.0889)
		(layer "In6.Cu")
		(net "UPI_CPU0_CPU1_P2P2_DN<23>")
	)
	(segment
		(start 257.192526 -340.42604)
		(end 256.984754 -340.42604)
		(width 0.14732)
		(layer "In6.Cu")
		(net "UPI_CPU0_CPU1_P2P2_DN<23>")
	)
	(segment
		(start 252.339348 -342.77173)
		(end 251.762006 -343.349072)
		(width 0.14732)
		(layer "In6.Cu")
		(net "UPI_CPU0_CPU1_P2P2_DN<23>")
	)
	(segment
		(start 112.785398 -277.536656)
		(end 112.785398 -277.522432)
		(width 0.0889)
		(layer "In6.Cu")
		(net "UPI_CPU0_CPU1_P2P2_DN<23>")
	)
	(segment
		(start 251.055124 -346.35567)
		(end 251.055124 -346.563442)
		(width 0.14732)
		(layer "In6.Cu")
		(net "UPI_CPU0_CPU1_P2P2_DN<23>")
	)
	(segment
		(start 252.775212 -342.77173)
		(end 252.339348 -342.77173)
		(width 0.14732)
		(layer "In6.Cu")
		(net "UPI_CPU0_CPU1_P2P2_DN<23>")
	)
	(segment
		(start 249.061732 -346.049346)
		(end 248.293382 -346.817696)
		(width 0.14732)
		(layer "In6.Cu")
		(net "UPI_CPU0_CPU1_P2P2_DN<23>")
	)
	(segment
		(start 76.32446 -351.867216)
		(end 75.890628 -350.819212)
		(width 0.14732)
		(layer "In6.Cu")
		(net "UPI_CPU0_CPU1_P2P2_DN<23>")
	)
	(segment
		(start 255.971548 -341.647018)
		(end 255.553718 -342.064848)
		(width 0.14732)
		(layer "In6.Cu")
		(net "UPI_CPU0_CPU1_P2P2_DN<23>")
	)
	(segment
		(start 79.887318 -324.771004)
		(end 80.148176 -324.510146)
		(width 0.14732)
		(layer "In6.Cu")
		(net "UPI_CPU0_CPU1_P2P2_DN<23>")
	)
	(segment
		(start 77.61351 -354.60178)
		(end 77.42428 -354.523294)
		(width 0.14732)
		(layer "In6.Cu")
		(net "UPI_CPU0_CPU1_P2P2_DN<23>")
	)
	(segment
		(start 254.33274 -343.078054)
		(end 254.33274 -343.285826)
		(width 0.14732)
		(layer "In6.Cu")
		(net "UPI_CPU0_CPU1_P2P2_DN<23>")
	)
	(segment
		(start 76.65466 -352.286062)
		(end 76.513944 -351.945702)
		(width 0.14732)
		(layer "In6.Cu")
		(net "UPI_CPU0_CPU1_P2P2_DN<23>")
	)
	(segment
		(start 299.5295 -317.355728)
		(end 299.154088 -317.810388)
		(width 0.14732)
		(layer "In6.Cu")
		(net "UPI_CPU0_CPU1_P2P2_DN<23>")
	)
	(segment
		(start 308.023514 -310.02986)
		(end 306.833778 -310.825388)
		(width 0.14732)
		(layer "In6.Cu")
		(net "UPI_CPU0_CPU1_P2P2_DN<23>")
	)
	(segment
		(start 290.80333 -317.776352)
		(end 290.312348 -318.267334)
		(width 0.14732)
		(layer "In6.Cu")
		(net "UPI_CPU0_CPU1_P2P2_DN<23>")
	)
	(segment
		(start 260.26237 -337.148424)
		(end 259.330444 -336.216498)
		(width 0.14732)
		(layer "In6.Cu")
		(net "UPI_CPU0_CPU1_P2P2_DN<23>")
	)
	(segment
		(start 314.059824 -307.610256)
		(end 313.875674 -307.68798)
		(width 0.14732)
		(layer "In6.Cu")
		(net "UPI_CPU0_CPU1_P2P2_DN<23>")
	)
	(segment
		(start 111.09071 -283.710888)
		(end 111.092488 -283.709872)
		(width 0.0889)
		(layer "In6.Cu")
		(net "UPI_CPU0_CPU1_P2P2_DN<23>")
	)
	(segment
		(start 111.089948 -283.711396)
		(end 111.09071 -283.710888)
		(width 0.0889)
		(layer "In6.Cu")
		(net "UPI_CPU0_CPU1_P2P2_DN<23>")
	)
	(segment
		(start 256.984754 -340.42604)
		(end 256.052828 -339.494114)
		(width 0.14732)
		(layer "In6.Cu")
		(net "UPI_CPU0_CPU1_P2P2_DN<23>")
	)
	(segment
		(start 257.691636 -337.855306)
		(end 257.255772 -337.855306)
		(width 0.14732)
		(layer "In6.Cu")
		(net "UPI_CPU0_CPU1_P2P2_DN<23>")
	)
	(segment
		(start 108.65866 -274.585176)
		(end 108.648246 -274.591272)
		(width 0.0889)
		(layer "In6.Cu")
		(net "UPI_CPU0_CPU1_P2P2_DN<23>")
	)
	(segment
		(start 268.988286 -322.923408)
		(end 268.680438 -322.61556)
		(width 0.14732)
		(layer "In6.Cu")
		(net "UPI_CPU0_CPU1_P2P2_DN<23>")
	)
	(segment
		(start 108.042964 -299.05071)
		(end 108.23829 -298.787566)
		(width 0.14732)
		(layer "In6.Cu")
		(net "UPI_CPU0_CPU1_P2P2_DN<23>")
	)
	(segment
		(start 108.23829 -298.787312)
		(end 108.813854 -298.011596)
		(width 0.14732)
		(layer "In6.Cu")
		(net "UPI_CPU0_CPU1_P2P2_DN<23>")
	)
	(segment
		(start 332.146656 -287.53308)
		(end 331.943964 -288.02203)
		(width 0.14732)
		(layer "In6.Cu")
		(net "UPI_CPU0_CPU1_P2P2_DN<23>")
	)
	(segment
		(start 260.887972 -336.522822)
		(end 260.887972 -336.730594)
		(width 0.14732)
		(layer "In6.Cu")
		(net "UPI_CPU0_CPU1_P2P2_DN<23>")
	)
	(segment
		(start 105.924096 -275.405088)
		(end 105.913682 -275.398992)
		(width 0.0889)
		(layer "In6.Cu")
		(net "UPI_CPU0_CPU1_P2P2_DN<23>")
	)
	(segment
		(start 248.293382 -346.817696)
		(end 248.293382 -350.229932)
		(width 0.14732)
		(layer "In6.Cu")
		(net "UPI_CPU0_CPU1_P2P2_DN<23>")
	)
	(segment
		(start 111.563658 -281.916886)
		(end 111.562896 -281.916378)
		(width 0.0889)
		(layer "In6.Cu")
		(net "UPI_CPU0_CPU1_P2P2_DN<23>")
	)
	(segment
		(start 109.309916 -291.596064)
		(end 109.309916 -291.258752)
		(width 0.0889)
		(layer "In6.Cu")
		(net "UPI_CPU0_CPU1_P2P2_DN<23>")
	)
	(segment
		(start 273.649186 -323.41947)
		(end 273.501866 -323.56679)
		(width 0.14732)
		(layer "In6.Cu")
		(net "UPI_CPU0_CPU1_P2P2_DN<23>")
	)
	(segment
		(start 112.493806 -278.017224)
		(end 112.502696 -278.012144)
		(width 0.0889)
		(layer "In6.Cu")
		(net "UPI_CPU0_CPU1_P2P2_DN<23>")
	)
	(segment
		(start 261.77494 -333.336138)
		(end 259.956046 -335.155032)
		(width 0.14732)
		(layer "In6.Cu")
		(net "UPI_CPU0_CPU1_P2P2_DN<23>")
	)
	(segment
		(start 256.052828 -339.494114)
		(end 255.616964 -339.494114)
		(width 0.14732)
		(layer "In6.Cu")
		(net "UPI_CPU0_CPU1_P2P2_DN<23>")
	)
	(segment
		(start 250.123198 -344.98788)
		(end 250.123198 -345.423744)
		(width 0.14732)
		(layer "In6.Cu")
		(net "UPI_CPU0_CPU1_P2P2_DN<23>")
	)
	(arc
		(start 111.568992 -281.264106)
		(mid 111.771579 -281.057755)
		(end 111.845598 -280.778204)
		(width 0.0889)
		(layer "In6.Cu")
		(net "UPI_CPU0_CPU1_P2P2_DN<23>")
	)
	(arc
		(start 111.562896 -282.895548)
		(mid 111.766377 -282.694744)
		(end 111.845598 -282.42006)
		(width 0.0889)
		(layer "In6.Cu")
		(net "UPI_CPU0_CPU1_P2P2_DN<23>")
	)
	(arc
		(start 109.495844 -286.475424)
		(mid 109.543523 -286.292524)
		(end 109.674406 -286.156146)
		(width 0.0889)
		(layer "In6.Cu")
		(net "UPI_CPU0_CPU1_P2P2_DN<23>")
	)
	(arc
		(start 109.236764 -289.3314)
		(mid 109.235368 -289.330509)
		(end 109.23397 -289.329622)
		(width 0.0889)
		(layer "In6.Cu")
		(net "UPI_CPU0_CPU1_P2P2_DN<23>")
	)
	(arc
		(start 106.86415 -275.405088)
		(mid 106.587337 -275.329252)
		(end 106.308906 -275.398992)
		(width 0.0889)
		(layer "In6.Cu")
		(net "UPI_CPU0_CPU1_P2P2_DN<23>")
	)
	(arc
		(start 112.785398 -277.522432)
		(mid 112.711407 -277.242866)
		(end 112.508792 -277.03653)
		(width 0.0889)
		(layer "In6.Cu")
		(net "UPI_CPU0_CPU1_P2P2_DN<23>")
	)
	(arc
		(start 110.905798 -284.033722)
		(mid 110.953477 -283.850822)
		(end 111.08436 -283.714444)
		(width 0.0889)
		(layer "In6.Cu")
		(net "UPI_CPU0_CPU1_P2P2_DN<23>")
	)
	(arc
		(start 108.74248 -288.439606)
		(mid 108.623995 -288.336778)
		(end 108.556298 -288.195258)
		(width 0.0889)
		(layer "In6.Cu")
		(net "UPI_CPU0_CPU1_P2P2_DN<23>")
	)
	(arc
		(start 111.845598 -280.778204)
		(mid 111.84565 -280.770837)
		(end 111.845852 -280.763472)
		(width 0.0889)
		(layer "In6.Cu")
		(net "UPI_CPU0_CPU1_P2P2_DN<23>")
	)
	(arc
		(start 108.749592 -287.775142)
		(mid 108.952179 -287.568791)
		(end 109.026198 -287.28924)
		(width 0.0889)
		(layer "In6.Cu")
		(net "UPI_CPU0_CPU1_P2P2_DN<23>")
	)
	(arc
		(start 112.03305 -280.453846)
		(mid 112.234332 -280.256359)
		(end 112.315244 -279.986232)
		(width 0.0889)
		(layer "In6.Cu")
		(net "UPI_CPU0_CPU1_P2P2_DN<23>")
	)
	(arc
		(start 106.298492 -275.405088)
		(mid 106.111294 -275.455231)
		(end 105.924096 -275.405088)
		(width 0.0889)
		(layer "In6.Cu")
		(net "UPI_CPU0_CPU1_P2P2_DN<23>")
	)
	(arc
		(start 108.556298 -288.09442)
		(mid 108.608568 -287.912055)
		(end 108.743496 -287.778698)
		(width 0.0889)
		(layer "In6.Cu")
		(net "UPI_CPU0_CPU1_P2P2_DN<23>")
	)
	(arc
		(start 108.263436 -274.585176)
		(mid 107.985004 -274.51533)
		(end 107.708192 -274.591272)
		(width 0.0889)
		(layer "In6.Cu")
		(net "UPI_CPU0_CPU1_P2P2_DN<23>")
	)
	(arc
		(start 112.493806 -277.027894)
		(mid 112.362892 -276.891534)
		(end 112.315244 -276.708616)
		(width 0.0889)
		(layer "In6.Cu")
		(net "UPI_CPU0_CPU1_P2P2_DN<23>")
	)
	(arc
		(start 112.02416 -276.214078)
		(mid 111.893246 -276.077718)
		(end 111.845598 -275.8948)
		(width 0.0889)
		(layer "In6.Cu")
		(net "UPI_CPU0_CPU1_P2P2_DN<23>")
	)
	(arc
		(start 107.238546 -275.405088)
		(mid 107.051348 -275.455231)
		(end 106.86415 -275.405088)
		(width 0.0889)
		(layer "In6.Cu")
		(net "UPI_CPU0_CPU1_P2P2_DN<23>")
	)
	(arc
		(start 112.508792 -279.63622)
		(mid 112.785242 -279.150318)
		(end 112.508792 -278.664416)
		(width 0.0889)
		(layer "In6.Cu")
		(net "UPI_CPU0_CPU1_P2P2_DN<23>")
	)
	(arc
		(start 111.375698 -281.583384)
		(mid 111.427968 -281.401019)
		(end 111.562896 -281.267662)
		(width 0.0889)
		(layer "In6.Cu")
		(net "UPI_CPU0_CPU1_P2P2_DN<23>")
	)
	(arc
		(start 111.845852 -280.763472)
		(mid 111.896906 -280.588892)
		(end 112.02416 -280.458926)
		(width 0.0889)
		(layer "In6.Cu")
		(net "UPI_CPU0_CPU1_P2P2_DN<23>")
	)
	(arc
		(start 111.09325 -283.709364)
		(mid 111.297585 -283.506759)
		(end 111.375698 -283.229812)
		(width 0.0889)
		(layer "In6.Cu")
		(net "UPI_CPU0_CPU1_P2P2_DN<23>")
	)
	(arc
		(start 112.502696 -278.012144)
		(mid 112.706177 -277.81134)
		(end 112.785398 -277.536656)
		(width 0.0889)
		(layer "In6.Cu")
		(net "UPI_CPU0_CPU1_P2P2_DN<23>")
	)
	(arc
		(start 107.425998 -275.08073)
		(mid 107.378319 -275.26363)
		(end 107.247436 -275.400008)
		(width 0.0889)
		(layer "In6.Cu")
		(net "UPI_CPU0_CPU1_P2P2_DN<23>")
	)
	(arc
		(start 105.358946 -275.405088)
		(mid 105.200458 -275.454021)
		(end 105.036366 -275.429726)
		(width 0.0889)
		(layer "In6.Cu")
		(net "UPI_CPU0_CPU1_P2P2_DN<23>")
	)
	(arc
		(start 109.193838 -289.306508)
		(mid 109.065485 -289.162243)
		(end 109.025944 -288.97326)
		(width 0.0889)
		(layer "In6.Cu")
		(net "UPI_CPU0_CPU1_P2P2_DN<23>")
	)
	(arc
		(start 109.026198 -287.280604)
		(mid 109.078468 -287.098239)
		(end 109.213396 -286.964882)
		(width 0.0889)
		(layer "In6.Cu")
		(net "UPI_CPU0_CPU1_P2P2_DN<23>")
	)
	(arc
		(start 107.708192 -274.591272)
		(mid 107.505369 -274.791503)
		(end 107.425998 -275.065236)
		(width 0.0889)
		(layer "In6.Cu")
		(net "UPI_CPU0_CPU1_P2P2_DN<23>")
	)
	(arc
		(start 111.845598 -282.405836)
		(mid 111.771607 -282.12627)
		(end 111.568992 -281.919934)
		(width 0.0889)
		(layer "In6.Cu")
		(net "UPI_CPU0_CPU1_P2P2_DN<23>")
	)
	(arc
		(start 110.435898 -284.847538)
		(mid 110.483577 -284.664638)
		(end 110.61446 -284.52826)
		(width 0.0889)
		(layer "In6.Cu")
		(net "UPI_CPU0_CPU1_P2P2_DN<23>")
	)
	(arc
		(start 109.03204 -288.863278)
		(mid 108.936988 -288.61746)
		(end 108.74248 -288.439606)
		(width 0.0889)
		(layer "In6.Cu")
		(net "UPI_CPU0_CPU1_P2P2_DN<23>")
	)
	(arc
		(start 112.315244 -279.964134)
		(mid 112.362923 -279.781234)
		(end 112.493806 -279.644856)
		(width 0.0889)
		(layer "In6.Cu")
		(net "UPI_CPU0_CPU1_P2P2_DN<23>")
	)
	(arc
		(start 112.493806 -278.65578)
		(mid 112.315209 -278.336502)
		(end 112.493806 -278.017224)
		(width 0.0889)
		(layer "In6.Cu")
		(net "UPI_CPU0_CPU1_P2P2_DN<23>")
	)
	(arc
		(start 333.746094 -284.904942)
		(mid 333.619711 -285.132019)
		(end 333.376016 -285.222188)
		(width 0.0889)
		(layer "In6.Cu")
		(net "UPI_CPU0_CPU1_P2P2_DN<23>")
	)
	(arc
		(start 109.213396 -274.591272)
		(mid 108.936837 -274.515529)
		(end 108.65866 -274.585176)
		(width 0.0889)
		(layer "In6.Cu")
		(net "UPI_CPU0_CPU1_P2P2_DN<23>")
	)
	(arc
		(start 111.375698 -275.070824)
		(mid 111.297587 -274.793875)
		(end 111.09325 -274.591272)
		(width 0.0889)
		(layer "In6.Cu")
		(net "UPI_CPU0_CPU1_P2P2_DN<23>")
	)
	(arc
		(start 111.562896 -275.405088)
		(mid 111.427963 -275.271734)
		(end 111.375698 -275.089366)
		(width 0.0889)
		(layer "In6.Cu")
		(net "UPI_CPU0_CPU1_P2P2_DN<23>")
	)
	(arc
		(start 111.845598 -275.880576)
		(mid 111.766379 -275.605891)
		(end 111.562896 -275.405088)
		(width 0.0889)
		(layer "In6.Cu")
		(net "UPI_CPU0_CPU1_P2P2_DN<23>")
	)
	(arc
		(start 110.629446 -284.519624)
		(mid 110.831859 -284.313211)
		(end 110.905798 -284.033722)
		(width 0.0889)
		(layer "In6.Cu")
		(net "UPI_CPU0_CPU1_P2P2_DN<23>")
	)
	(arc
		(start 109.683296 -286.151066)
		(mid 109.885582 -285.952085)
		(end 109.965744 -285.679896)
		(width 0.0889)
		(layer "In6.Cu")
		(net "UPI_CPU0_CPU1_P2P2_DN<23>")
	)
	(arc
		(start 110.527592 -274.591272)
		(mid 110.340394 -274.641415)
		(end 110.153196 -274.591272)
		(width 0.0889)
		(layer "In6.Cu")
		(net "UPI_CPU0_CPU1_P2P2_DN<23>")
	)
	(arc
		(start 109.587792 -274.591272)
		(mid 109.400594 -274.641415)
		(end 109.213396 -274.591272)
		(width 0.0889)
		(layer "In6.Cu")
		(net "UPI_CPU0_CPU1_P2P2_DN<23>")
	)
	(arc
		(start 111.082836 -274.585176)
		(mid 110.804404 -274.51533)
		(end 110.527592 -274.591272)
		(width 0.0889)
		(layer "In6.Cu")
		(net "UPI_CPU0_CPU1_P2P2_DN<23>")
	)
	(arc
		(start 110.153196 -274.591272)
		(mid 109.870494 -274.515496)
		(end 109.587792 -274.591272)
		(width 0.0889)
		(layer "In6.Cu")
		(net "UPI_CPU0_CPU1_P2P2_DN<23>")
	)
	(arc
		(start 111.562896 -281.916378)
		(mid 111.427963 -281.783024)
		(end 111.375698 -281.600656)
		(width 0.0889)
		(layer "In6.Cu")
		(net "UPI_CPU0_CPU1_P2P2_DN<23>")
	)
	(arc
		(start 105.913682 -275.398992)
		(mid 105.635504 -275.3293)
		(end 105.358946 -275.405088)
		(width 0.0889)
		(layer "In6.Cu")
		(net "UPI_CPU0_CPU1_P2P2_DN<23>")
	)
	(arc
		(start 109.213396 -286.964882)
		(mid 109.417731 -286.762277)
		(end 109.495844 -286.48533)
		(width 0.0889)
		(layer "In6.Cu")
		(net "UPI_CPU0_CPU1_P2P2_DN<23>")
	)
	(arc
		(start 112.315244 -276.693122)
		(mid 112.235874 -276.419388)
		(end 112.03305 -276.219158)
		(width 0.0889)
		(layer "In6.Cu")
		(net "UPI_CPU0_CPU1_P2P2_DN<23>")
	)
	(arc
		(start 111.375698 -283.21127)
		(mid 111.427968 -283.028905)
		(end 111.562896 -282.895548)
		(width 0.0889)
		(layer "In6.Cu")
		(net "UPI_CPU0_CPU1_P2P2_DN<23>")
	)
	(arc
		(start 109.965744 -285.661354)
		(mid 110.013423 -285.478454)
		(end 110.144306 -285.342076)
		(width 0.0889)
		(layer "In6.Cu")
		(net "UPI_CPU0_CPU1_P2P2_DN<23>")
	)
	(arc
		(start 110.165388 -285.329884)
		(mid 110.363616 -285.124036)
		(end 110.435898 -284.847538)
		(width 0.0889)
		(layer "In6.Cu")
		(net "UPI_CPU0_CPU1_P2P2_DN<23>")
	)
	(arc
		(start 109.49559 -289.832034)
		(mid 109.432982 -289.547183)
		(end 109.236764 -289.3314)
		(width 0.0889)
		(layer "In6.Cu")
		(net "UPI_CPU0_CPU1_P2P2_DN<23>")
	)
	(arc
		(start 108.648246 -274.591272)
		(mid 108.461048 -274.641415)
		(end 108.27385 -274.591272)
		(width 0.0889)
		(layer "In6.Cu")
		(net "UPI_CPU0_CPU1_P2P2_DN<23>")
	)
	(segment
		(start 334.785716 -283.497782)
		(end 334.785716 -284.033722)
		(width 0.13208)
		(layer "F.Cu")
		(net "UPI_CPU0_CPU1_P2P2_DN<22>")
	)
	(segment
		(start 107.990894 -274.54479)
		(end 107.991148 -274.545044)
		(width 0.13208)
		(layer "F.Cu")
		(net "UPI_CPU0_CPU1_P2P2_DN<22>")
	)
	(segment
		(start 107.991148 -274.545044)
		(end 107.991148 -275.08073)
		(width 0.13208)
		(layer "F.Cu")
		(net "UPI_CPU0_CPU1_P2P2_DN<22>")
	)
	(segment
		(start 308.860698 -311.263792)
		(end 307.61559 -311.851294)
		(width 0.14732)
		(layer "In6.Cu")
		(net "UPI_CPU0_CPU1_P2P2_DN<22>")
	)
	(segment
		(start 175.888396 -371.06479)
		(end 175.307752 -371.16766)
		(width 0.14732)
		(layer "In6.Cu")
		(net "UPI_CPU0_CPU1_P2P2_DN<22>")
	)
	(segment
		(start 314.250578 -309.226966)
		(end 313.442858 -309.306722)
		(width 0.14732)
		(layer "In6.Cu")
		(net "UPI_CPU0_CPU1_P2P2_DN<22>")
	)
	(segment
		(start 186.09183 -368.211608)
		(end 185.286142 -368.353848)
		(width 0.14732)
		(layer "In6.Cu")
		(net "UPI_CPU0_CPU1_P2P2_DN<22>")
	)
	(segment
		(start 333.572358 -286.794702)
		(end 333.57058 -286.795718)
		(width 0.0889)
		(layer "In6.Cu")
		(net "UPI_CPU0_CPU1_P2P2_DN<22>")
	)
	(segment
		(start 168.289986 -372.255796)
		(end 168.18864 -371.68201)
		(width 0.14732)
		(layer "In6.Cu")
		(net "UPI_CPU0_CPU1_P2P2_DN<22>")
	)
	(segment
		(start 183.003698 -368.756438)
		(end 182.754016 -369.1128)
		(width 0.14732)
		(layer "In6.Cu")
		(net "UPI_CPU0_CPU1_P2P2_DN<22>")
	)
	(segment
		(start 285.650686 -322.792344)
		(end 284.522418 -323.920612)
		(width 0.14732)
		(layer "In6.Cu")
		(net "UPI_CPU0_CPU1_P2P2_DN<22>")
	)
	(segment
		(start 208.781396 -368.546634)
		(end 208.661762 -368.3762)
		(width 0.14732)
		(layer "In6.Cu")
		(net "UPI_CPU0_CPU1_P2P2_DN<22>")
	)
	(segment
		(start 189.702694 -368.478816)
		(end 189.582044 -368.650774)
		(width 0.14732)
		(layer "In6.Cu")
		(net "UPI_CPU0_CPU1_P2P2_DN<22>")
	)
	(segment
		(start 194.166236 -367.09985)
		(end 194.267582 -367.673636)
		(width 0.14732)
		(layer "In6.Cu")
		(net "UPI_CPU0_CPU1_P2P2_DN<22>")
	)
	(segment
		(start 173.62424 -370.72316)
		(end 173.725586 -371.296946)
		(width 0.14732)
		(layer "In6.Cu")
		(net "UPI_CPU0_CPU1_P2P2_DN<22>")
	)
	(segment
		(start 199.486266 -366.906302)
		(end 198.132446 -367.142014)
		(width 0.14732)
		(layer "In6.Cu")
		(net "UPI_CPU0_CPU1_P2P2_DN<22>")
	)
	(segment
		(start 167.832278 -371.432328)
		(end 167.02659 -371.574568)
		(width 0.14732)
		(layer "In6.Cu")
		(net "UPI_CPU0_CPU1_P2P2_DN<22>")
	)
	(segment
		(start 204.797152 -367.843816)
		(end 204.216508 -367.740946)
		(width 0.14732)
		(layer "In6.Cu")
		(net "UPI_CPU0_CPU1_P2P2_DN<22>")
	)
	(segment
		(start 182.735728 -369.85702)
		(end 182.155084 -369.95989)
		(width 0.14732)
		(layer "In6.Cu")
		(net "UPI_CPU0_CPU1_P2P2_DN<22>")
	)
	(segment
		(start 193.39687 -367.827306)
		(end 193.295524 -367.25352)
		(width 0.14732)
		(layer "In6.Cu")
		(net "UPI_CPU0_CPU1_P2P2_DN<22>")
	)
	(segment
		(start 99.113594 -307.203856)
		(end 107.424982 -298.47413)
		(width 0.14732)
		(layer "In6.Cu")
		(net "UPI_CPU0_CPU1_P2P2_DN<22>")
	)
	(segment
		(start 166.007542 -372.658386)
		(end 165.906196 -372.0846)
		(width 0.14732)
		(layer "In6.Cu")
		(net "UPI_CPU0_CPU1_P2P2_DN<22>")
	)
	(segment
		(start 333.750412 -286.456882)
		(end 333.750412 -286.483806)
		(width 0.0889)
		(layer "In6.Cu")
		(net "UPI_CPU0_CPU1_P2P2_DN<22>")
	)
	(segment
		(start 333.750412 -286.483806)
		(end 333.750666 -286.483298)
		(width 0.0889)
		(layer "In6.Cu")
		(net "UPI_CPU0_CPU1_P2P2_DN<22>")
	)
	(segment
		(start 99.113594 -307.20411)
		(end 99.113594 -307.203856)
		(width 0.14732)
		(layer "In6.Cu")
		(net "UPI_CPU0_CPU1_P2P2_DN<22>")
	)
	(segment
		(start 160.984946 -372.640098)
		(end 160.179258 -372.782338)
		(width 0.14732)
		(layer "In6.Cu")
		(net "UPI_CPU0_CPU1_P2P2_DN<22>")
	)
	(segment
		(start 162.313366 -373.309896)
		(end 162.193732 -373.48033)
		(width 0.14732)
		(layer "In6.Cu")
		(net "UPI_CPU0_CPU1_P2P2_DN<22>")
	)
	(segment
		(start 165.549834 -371.834918)
		(end 164.744146 -371.977158)
		(width 0.14732)
		(layer "In6.Cu")
		(net "UPI_CPU0_CPU1_P2P2_DN<22>")
	)
	(segment
		(start 179.87264 -370.36248)
		(end 179.702206 -370.242846)
		(width 0.14732)
		(layer "In6.Cu")
		(net "UPI_CPU0_CPU1_P2P2_DN<22>")
	)
	(segment
		(start 167.02659 -371.574568)
		(end 166.776908 -371.93093)
		(width 0.14732)
		(layer "In6.Cu")
		(net "UPI_CPU0_CPU1_P2P2_DN<22>")
	)
	(segment
		(start 302.13935 -314.698634)
		(end 301.608236 -315.254132)
		(width 0.14732)
		(layer "In6.Cu")
		(net "UPI_CPU0_CPU1_P2P2_DN<22>")
	)
	(segment
		(start 108.556044 -290.265358)
		(end 108.556044 -289.646614)
		(width 0.0889)
		(layer "In6.Cu")
		(net "UPI_CPU0_CPU1_P2P2_DN<22>")
	)
	(segment
		(start 209.585306 -368.23142)
		(end 209.532474 -368.52987)
		(width 0.14732)
		(layer "In6.Cu")
		(net "UPI_CPU0_CPU1_P2P2_DN<22>")
	)
	(segment
		(start 185.018172 -369.45443)
		(end 184.437528 -369.5573)
		(width 0.14732)
		(layer "In6.Cu")
		(net "UPI_CPU0_CPU1_P2P2_DN<22>")
	)
	(segment
		(start 107.79506 -287.783778)
		(end 107.80395 -287.778698)
		(width 0.0889)
		(layer "In6.Cu")
		(net "UPI_CPU0_CPU1_P2P2_DN<22>")
	)
	(segment
		(start 111.09325 -276.219158)
		(end 111.08436 -276.214078)
		(width 0.0889)
		(layer "In6.Cu")
		(net "UPI_CPU0_CPU1_P2P2_DN<22>")
	)
	(segment
		(start 270.406876 -325.50227)
		(end 264.582402 -325.50227)
		(width 0.14732)
		(layer "In6.Cu")
		(net "UPI_CPU0_CPU1_P2P2_DN<22>")
	)
	(segment
		(start 109.674406 -284.52826)
		(end 109.683296 -284.52318)
		(width 0.0889)
		(layer "In6.Cu")
		(net "UPI_CPU0_CPU1_P2P2_DN<22>")
	)
	(segment
		(start 209.36204 -368.649504)
		(end 208.781396 -368.546634)
		(width 0.14732)
		(layer "In6.Cu")
		(net "UPI_CPU0_CPU1_P2P2_DN<22>")
	)
	(segment
		(start 170.114722 -371.029738)
		(end 169.309034 -371.171978)
		(width 0.14732)
		(layer "In6.Cu")
		(net "UPI_CPU0_CPU1_P2P2_DN<22>")
	)
	(segment
		(start 174.67961 -370.224558)
		(end 173.873922 -370.366798)
		(width 0.14732)
		(layer "In6.Cu")
		(net "UPI_CPU0_CPU1_P2P2_DN<22>")
	)
	(segment
		(start 194.147948 -367.84407)
		(end 193.56705 -367.94694)
		(width 0.14732)
		(layer "In6.Cu")
		(net "UPI_CPU0_CPU1_P2P2_DN<22>")
	)
	(segment
		(start 208.464912 -367.721388)
		(end 207.659224 -367.578894)
		(width 0.14732)
		(layer "In6.Cu")
		(net "UPI_CPU0_CPU1_P2P2_DN<22>")
	)
	(segment
		(start 82.102198 -321.164458)
		(end 87.43315 -316.789816)
		(width 0.14732)
		(layer "In6.Cu")
		(net "UPI_CPU0_CPU1_P2P2_DN<22>")
	)
	(segment
		(start 178.17084 -370.6622)
		(end 177.590196 -370.76507)
		(width 0.14732)
		(layer "In6.Cu")
		(net "UPI_CPU0_CPU1_P2P2_DN<22>")
	)
	(segment
		(start 180.453284 -370.25961)
		(end 179.87264 -370.36248)
		(width 0.14732)
		(layer "In6.Cu")
		(net "UPI_CPU0_CPU1_P2P2_DN<22>")
	)
	(segment
		(start 297.515026 -321.875404)
		(end 296.280078 -323.110352)
		(width 0.14732)
		(layer "In6.Cu")
		(net "UPI_CPU0_CPU1_P2P2_DN<22>")
	)
	(segment
		(start 299.819822 -318.41948)
		(end 299.819822 -318.851026)
		(width 0.14732)
		(layer "In6.Cu")
		(net "UPI_CPU0_CPU1_P2P2_DN<22>")
	)
	(segment
		(start 163.895532 -373.18061)
		(end 163.725098 -373.060976)
		(width 0.14732)
		(layer "In6.Cu")
		(net "UPI_CPU0_CPU1_P2P2_DN<22>")
	)
	(segment
		(start 192.939162 -367.003838)
		(end 192.133474 -367.146078)
		(width 0.14732)
		(layer "In6.Cu")
		(net "UPI_CPU0_CPU1_P2P2_DN<22>")
	)
	(segment
		(start 111.375698 -279.982676)
		(end 111.375698 -279.955498)
		(width 0.0889)
		(layer "In6.Cu")
		(net "UPI_CPU0_CPU1_P2P2_DN<22>")
	)
	(segment
		(start 314.251848 -309.225696)
		(end 314.250578 -309.226966)
		(width 0.14732)
		(layer "In6.Cu")
		(net "UPI_CPU0_CPU1_P2P2_DN<22>")
	)
	(segment
		(start 169.160698 -372.102126)
		(end 169.041064 -372.27256)
		(width 0.14732)
		(layer "In6.Cu")
		(net "UPI_CPU0_CPU1_P2P2_DN<22>")
	)
	(segment
		(start 176.156366 -369.964208)
		(end 175.906684 -370.32057)
		(width 0.14732)
		(layer "In6.Cu")
		(net "UPI_CPU0_CPU1_P2P2_DN<22>")
	)
	(segment
		(start 77.529944 -356.985062)
		(end 77.34046 -356.906576)
		(width 0.14732)
		(layer "In6.Cu")
		(net "UPI_CPU0_CPU1_P2P2_DN<22>")
	)
	(segment
		(start 166.177976 -372.77802)
		(end 166.007542 -372.658386)
		(width 0.14732)
		(layer "In6.Cu")
		(net "UPI_CPU0_CPU1_P2P2_DN<22>")
	)
	(segment
		(start 208.661762 -368.3762)
		(end 208.714594 -368.07775)
		(width 0.14732)
		(layer "In6.Cu")
		(net "UPI_CPU0_CPU1_P2P2_DN<22>")
	)
	(segment
		(start 195.221606 -366.601248)
		(end 194.415918 -366.743488)
		(width 0.14732)
		(layer "In6.Cu")
		(net "UPI_CPU0_CPU1_P2P2_DN<22>")
	)
	(segment
		(start 161.613088 -373.5832)
		(end 161.4424 -373.463566)
		(width 0.14732)
		(layer "In6.Cu")
		(net "UPI_CPU0_CPU1_P2P2_DN<22>")
	)
	(segment
		(start 208.714594 -368.07775)
		(end 208.464912 -367.721388)
		(width 0.14732)
		(layer "In6.Cu")
		(net "UPI_CPU0_CPU1_P2P2_DN<22>")
	)
	(segment
		(start 109.495844 -284.857444)
		(end 109.495844 -284.847538)
		(width 0.0889)
		(layer "In6.Cu")
		(net "UPI_CPU0_CPU1_P2P2_DN<22>")
	)
	(segment
		(start 159.929576 -373.1387)
		(end 160.030922 -373.712486)
		(width 0.14732)
		(layer "In6.Cu")
		(net "UPI_CPU0_CPU1_P2P2_DN<22>")
	)
	(segment
		(start 87.636858 -316.809882)
		(end 87.921846 -316.575948)
		(width 0.14732)
		(layer "In6.Cu")
		(net "UPI_CPU0_CPU1_P2P2_DN<22>")
	)
	(segment
		(start 300.830488 -317.408814)
		(end 299.819822 -318.41948)
		(width 0.14732)
		(layer "In6.Cu")
		(net "UPI_CPU0_CPU1_P2P2_DN<22>")
	)
	(segment
		(start 75.781662 -353.14255)
		(end 75.781916 -353.14255)
		(width 0.14732)
		(layer "In6.Cu")
		(net "UPI_CPU0_CPU1_P2P2_DN<22>")
	)
	(segment
		(start 296.280078 -323.110352)
		(end 288.02711 -323.110352)
		(width 0.14732)
		(layer "In6.Cu")
		(net "UPI_CPU0_CPU1_P2P2_DN<22>")
	)
	(segment
		(start 191.114426 -368.229896)
		(end 191.01308 -367.65611)
		(width 0.14732)
		(layer "In6.Cu")
		(net "UPI_CPU0_CPU1_P2P2_DN<22>")
	)
	(segment
		(start 211.06384 -368.949478)
		(end 210.944206 -368.779044)
		(width 0.14732)
		(layer "In6.Cu")
		(net "UPI_CPU0_CPU1_P2P2_DN<22>")
	)
	(segment
		(start 210.944206 -368.779044)
		(end 210.997038 -368.480594)
		(width 0.14732)
		(layer "In6.Cu")
		(net "UPI_CPU0_CPU1_P2P2_DN<22>")
	)
	(segment
		(start 175.035972 -370.47424)
		(end 174.67961 -370.224558)
		(width 0.14732)
		(layer "In6.Cu")
		(net "UPI_CPU0_CPU1_P2P2_DN<22>")
	)
	(segment
		(start 77.670914 -357.325422)
		(end 77.529944 -356.985062)
		(width 0.14732)
		(layer "In6.Cu")
		(net "UPI_CPU0_CPU1_P2P2_DN<22>")
	)
	(segment
		(start 111.568992 -277.03653)
		(end 111.563658 -277.033482)
		(width 0.0889)
		(layer "In6.Cu")
		(net "UPI_CPU0_CPU1_P2P2_DN<22>")
	)
	(segment
		(start 173.025308 -371.57025)
		(end 172.854874 -371.450616)
		(width 0.14732)
		(layer "In6.Cu")
		(net "UPI_CPU0_CPU1_P2P2_DN<22>")
	)
	(segment
		(start 334.04175 -285.980632)
		(end 334.03286 -285.985712)
		(width 0.0889)
		(layer "In6.Cu")
		(net "UPI_CPU0_CPU1_P2P2_DN<22>")
	)
	(segment
		(start 163.623752 -372.48719)
		(end 163.26739 -372.237508)
		(width 0.14732)
		(layer "In6.Cu")
		(net "UPI_CPU0_CPU1_P2P2_DN<22>")
	)
	(segment
		(start 76.5048 -354.509578)
		(end 76.36383 -354.169218)
		(width 0.14732)
		(layer "In6.Cu")
		(net "UPI_CPU0_CPU1_P2P2_DN<22>")
	)
	(segment
		(start 164.59581 -372.907306)
		(end 164.476176 -373.07774)
		(width 0.14732)
		(layer "In6.Cu")
		(net "UPI_CPU0_CPU1_P2P2_DN<22>")
	)
	(segment
		(start 169.309034 -371.171978)
		(end 169.059352 -371.52834)
		(width 0.14732)
		(layer "In6.Cu")
		(net "UPI_CPU0_CPU1_P2P2_DN<22>")
	)
	(segment
		(start 76.36383 -354.169218)
		(end 76.174346 -354.090732)
		(width 0.14732)
		(layer "In6.Cu")
		(net "UPI_CPU0_CPU1_P2P2_DN<22>")
	)
	(segment
		(start 228.401626 -366.487964)
		(end 212.75548 -369.247166)
		(width 0.14732)
		(layer "In6.Cu")
		(net "UPI_CPU0_CPU1_P2P2_DN<22>")
	)
	(segment
		(start 168.46042 -372.37543)
		(end 168.289986 -372.255796)
		(width 0.14732)
		(layer "In6.Cu")
		(net "UPI_CPU0_CPU1_P2P2_DN<22>")
	)
	(segment
		(start 107.80395 -288.427414)
		(end 107.803188 -288.426906)
		(width 0.0889)
		(layer "In6.Cu")
		(net "UPI_CPU0_CPU1_P2P2_DN<22>")
	)
	(segment
		(start 249.121422 -349.668592)
		(end 249.121422 -350.826324)
		(width 0.14732)
		(layer "In6.Cu")
		(net "UPI_CPU0_CPU1_P2P2_DN<22>")
	)
	(segment
		(start 201.934064 -367.338102)
		(end 201.81443 -367.167668)
		(width 0.14732)
		(layer "In6.Cu")
		(net "UPI_CPU0_CPU1_P2P2_DN<22>")
	)
	(segment
		(start 110.905798 -282.42006)
		(end 110.905798 -282.405836)
		(width 0.0889)
		(layer "In6.Cu")
		(net "UPI_CPU0_CPU1_P2P2_DN<22>")
	)
	(segment
		(start 207.302862 -367.828576)
		(end 207.25003 -368.127026)
		(width 0.14732)
		(layer "In6.Cu")
		(net "UPI_CPU0_CPU1_P2P2_DN<22>")
	)
	(segment
		(start 109.026198 -285.675578)
		(end 109.026198 -285.652718)
		(width 0.0889)
		(layer "In6.Cu")
		(net "UPI_CPU0_CPU1_P2P2_DN<22>")
	)
	(segment
		(start 182.855362 -369.686586)
		(end 182.735728 -369.85702)
		(width 0.14732)
		(layer "In6.Cu")
		(net "UPI_CPU0_CPU1_P2P2_DN<22>")
	)
	(segment
		(start 271.514316 -324.39483)
		(end 270.406876 -325.50227)
		(width 0.14732)
		(layer "In6.Cu")
		(net "UPI_CPU0_CPU1_P2P2_DN<22>")
	)
	(segment
		(start 111.562896 -278.66086)
		(end 111.561372 -278.660098)
		(width 0.0889)
		(layer "In6.Cu")
		(net "UPI_CPU0_CPU1_P2P2_DN<22>")
	)
	(segment
		(start 109.965744 -284.043628)
		(end 109.965744 -284.033722)
		(width 0.0889)
		(layer "In6.Cu")
		(net "UPI_CPU0_CPU1_P2P2_DN<22>")
	)
	(segment
		(start 172.753528 -370.87683)
		(end 172.397166 -370.627148)
		(width 0.14732)
		(layer "In6.Cu")
		(net "UPI_CPU0_CPU1_P2P2_DN<22>")
	)
	(segment
		(start 188.831982 -368.632486)
		(end 188.730636 -368.0587)
		(width 0.14732)
		(layer "In6.Cu")
		(net "UPI_CPU0_CPU1_P2P2_DN<22>")
	)
	(segment
		(start 191.284352 -368.34953)
		(end 191.114426 -368.229896)
		(width 0.14732)
		(layer "In6.Cu")
		(net "UPI_CPU0_CPU1_P2P2_DN<22>")
	)
	(segment
		(start 190.656718 -367.406428)
		(end 189.85103 -367.548668)
		(width 0.14732)
		(layer "In6.Cu")
		(net "UPI_CPU0_CPU1_P2P2_DN<22>")
	)
	(segment
		(start 75.781916 -353.14255)
		(end 75.781662 -353.142296)
		(width 0.14732)
		(layer "In6.Cu")
		(net "UPI_CPU0_CPU1_P2P2_DN<22>")
	)
	(segment
		(start 171.443142 -371.699536)
		(end 171.323508 -371.86997)
		(width 0.14732)
		(layer "In6.Cu")
		(net "UPI_CPU0_CPU1_P2P2_DN<22>")
	)
	(segment
		(start 170.471084 -371.27942)
		(end 170.114722 -371.029738)
		(width 0.14732)
		(layer "In6.Cu")
		(net "UPI_CPU0_CPU1_P2P2_DN<22>")
	)
	(segment
		(start 207.25003 -368.127026)
		(end 207.079596 -368.24666)
		(width 0.14732)
		(layer "In6.Cu")
		(net "UPI_CPU0_CPU1_P2P2_DN<22>")
	)
	(segment
		(start 188.374274 -367.809018)
		(end 187.568586 -367.951258)
		(width 0.14732)
		(layer "In6.Cu")
		(net "UPI_CPU0_CPU1_P2P2_DN<22>")
	)
	(segment
		(start 331.746098 -289.856418)
		(end 330.073254 -292.358572)
		(width 0.14732)
		(layer "In6.Cu")
		(net "UPI_CPU0_CPU1_P2P2_DN<22>")
	)
	(segment
		(start 184.437528 -369.5573)
		(end 184.267094 -369.437666)
		(width 0.14732)
		(layer "In6.Cu")
		(net "UPI_CPU0_CPU1_P2P2_DN<22>")
	)
	(segment
		(start 110.629446 -281.919934)
		(end 110.62335 -281.916378)
		(width 0.0889)
		(layer "In6.Cu")
		(net "UPI_CPU0_CPU1_P2P2_DN<22>")
	)
	(segment
		(start 206.498952 -368.14379)
		(end 206.379318 -367.973356)
		(width 0.14732)
		(layer "In6.Cu")
		(net "UPI_CPU0_CPU1_P2P2_DN<22>")
	)
	(segment
		(start 176.00803 -370.894356)
		(end 175.888396 -371.06479)
		(width 0.14732)
		(layer "In6.Cu")
		(net "UPI_CPU0_CPU1_P2P2_DN<22>")
	)
	(segment
		(start 186.448192 -368.46129)
		(end 186.09183 -368.211608)
		(width 0.14732)
		(layer "In6.Cu")
		(net "UPI_CPU0_CPU1_P2P2_DN<22>")
	)
	(segment
		(start 164.476176 -373.07774)
		(end 163.895532 -373.18061)
		(width 0.14732)
		(layer "In6.Cu")
		(net "UPI_CPU0_CPU1_P2P2_DN<22>")
	)
	(segment
		(start 108.164884 -297.332146)
		(end 108.164884 -291.493956)
		(width 0.14732)
		(layer "In6.Cu")
		(net "UPI_CPU0_CPU1_P2P2_DN<22>")
	)
	(segment
		(start 187.318904 -368.30762)
		(end 187.42025 -368.881406)
		(width 0.14732)
		(layer "In6.Cu")
		(net "UPI_CPU0_CPU1_P2P2_DN<22>")
	)
	(segment
		(start 111.563658 -279.639268)
		(end 111.566452 -279.637744)
		(width 0.0889)
		(layer "In6.Cu")
		(net "UPI_CPU0_CPU1_P2P2_DN<22>")
	)
	(segment
		(start 168.18864 -371.68201)
		(end 167.832278 -371.432328)
		(width 0.14732)
		(layer "In6.Cu")
		(net "UPI_CPU0_CPU1_P2P2_DN<22>")
	)
	(segment
		(start 201.61758 -366.512856)
		(end 200.811892 -366.370362)
		(width 0.14732)
		(layer "In6.Cu")
		(net "UPI_CPU0_CPU1_P2P2_DN<22>")
	)
	(segment
		(start 182.754016 -369.1128)
		(end 182.855362 -369.686586)
		(width 0.14732)
		(layer "In6.Cu")
		(net "UPI_CPU0_CPU1_P2P2_DN<22>")
	)
	(segment
		(start 309.8292 -310.363616)
		(end 308.860698 -311.263792)
		(width 0.14732)
		(layer "In6.Cu")
		(net "UPI_CPU0_CPU1_P2P2_DN<22>")
	)
	(segment
		(start 111.562896 -279.639776)
		(end 111.563658 -279.639268)
		(width 0.0889)
		(layer "In6.Cu")
		(net "UPI_CPU0_CPU1_P2P2_DN<22>")
	)
	(segment
		(start 207.079596 -368.24666)
		(end 206.498952 -368.14379)
		(width 0.14732)
		(layer "In6.Cu")
		(net "UPI_CPU0_CPU1_P2P2_DN<22>")
	)
	(segment
		(start 76.843382 -355.32695)
		(end 76.653898 -355.248718)
		(width 0.14732)
		(layer "In6.Cu")
		(net "UPI_CPU0_CPU1_P2P2_DN<22>")
	)
	(segment
		(start 184.165748 -368.86388)
		(end 183.809386 -368.614198)
		(width 0.14732)
		(layer "In6.Cu")
		(net "UPI_CPU0_CPU1_P2P2_DN<22>")
	)
	(segment
		(start 329.102466 -295.557702)
		(end 329.102466 -295.557956)
		(width 0.14732)
		(layer "In6.Cu")
		(net "UPI_CPU0_CPU1_P2P2_DN<22>")
	)
	(segment
		(start 178.189128 -369.91798)
		(end 178.290474 -370.491766)
		(width 0.14732)
		(layer "In6.Cu")
		(net "UPI_CPU0_CPU1_P2P2_DN<22>")
	)
	(segment
		(start 175.307752 -371.16766)
		(end 175.137318 -371.048026)
		(width 0.14732)
		(layer "In6.Cu")
		(net "UPI_CPU0_CPU1_P2P2_DN<22>")
	)
	(segment
		(start 77.183996 -326.083168)
		(end 82.102198 -321.164458)
		(width 0.14732)
		(layer "In6.Cu")
		(net "UPI_CPU0_CPU1_P2P2_DN<22>")
	)
	(segment
		(start 180.471572 -369.51539)
		(end 180.572918 -370.089176)
		(width 0.14732)
		(layer "In6.Cu")
		(net "UPI_CPU0_CPU1_P2P2_DN<22>")
	)
	(segment
		(start 158.894272 -374.062244)
		(end 126.377446 -374.062244)
		(width 0.14732)
		(layer "In6.Cu")
		(net "UPI_CPU0_CPU1_P2P2_DN<22>")
	)
	(segment
		(start 188.730636 -368.0587)
		(end 188.374274 -367.809018)
		(width 0.14732)
		(layer "In6.Cu")
		(net "UPI_CPU0_CPU1_P2P2_DN<22>")
	)
	(segment
		(start 287.542732 -322.625974)
		(end 286.053276 -322.625974)
		(width 0.14732)
		(layer "In6.Cu")
		(net "UPI_CPU0_CPU1_P2P2_DN<22>")
	)
	(segment
		(start 110.905798 -275.8948)
		(end 110.905798 -275.880576)
		(width 0.0889)
		(layer "In6.Cu")
		(net "UPI_CPU0_CPU1_P2P2_DN<22>")
	)
	(segment
		(start 108.597954 -290.307268)
		(end 108.556044 -290.265358)
		(width 0.0889)
		(layer "In6.Cu")
		(net "UPI_CPU0_CPU1_P2P2_DN<22>")
	)
	(segment
		(start 193.56705 -367.94694)
		(end 193.39687 -367.827306)
		(width 0.14732)
		(layer "In6.Cu")
		(net "UPI_CPU0_CPU1_P2P2_DN<22>")
	)
	(segment
		(start 171.591478 -370.769388)
		(end 171.341796 -371.12575)
		(width 0.14732)
		(layer "In6.Cu")
		(net "UPI_CPU0_CPU1_P2P2_DN<22>")
	)
	(segment
		(start 159.911288 -373.88292)
		(end 158.894272 -374.062244)
		(width 0.14732)
		(layer "In6.Cu")
		(net "UPI_CPU0_CPU1_P2P2_DN<22>")
	)
	(segment
		(start 286.053276 -322.625974)
		(end 285.650686 -322.792344)
		(width 0.14732)
		(layer "In6.Cu")
		(net "UPI_CPU0_CPU1_P2P2_DN<22>")
	)
	(segment
		(start 179.244498 -369.419378)
		(end 178.43881 -369.561618)
		(width 0.14732)
		(layer "In6.Cu")
		(net "UPI_CPU0_CPU1_P2P2_DN<22>")
	)
	(segment
		(start 191.01308 -367.65611)
		(end 190.656718 -367.406428)
		(width 0.14732)
		(layer "In6.Cu")
		(net "UPI_CPU0_CPU1_P2P2_DN<22>")
	)
	(segment
		(start 210.747356 -368.124232)
		(end 209.941668 -367.981738)
		(width 0.14732)
		(layer "In6.Cu")
		(net "UPI_CPU0_CPU1_P2P2_DN<22>")
	)
	(segment
		(start 200.811892 -366.370362)
		(end 200.45553 -366.620044)
		(width 0.14732)
		(layer "In6.Cu")
		(net "UPI_CPU0_CPU1_P2P2_DN<22>")
	)
	(segment
		(start 164.494464 -372.33352)
		(end 164.59581 -372.907306)
		(width 0.14732)
		(layer "In6.Cu")
		(net "UPI_CPU0_CPU1_P2P2_DN<22>")
	)
	(segment
		(start 313.442858 -309.306722)
		(end 313.284616 -309.176928)
		(width 0.14732)
		(layer "In6.Cu")
		(net "UPI_CPU0_CPU1_P2P2_DN<22>")
	)
	(segment
		(start 332.930754 -288.435288)
		(end 332.930754 -288.457386)
		(width 0.0889)
		(layer "In6.Cu")
		(net "UPI_CPU0_CPU1_P2P2_DN<22>")
	)
	(segment
		(start 195.679314 -367.424716)
		(end 195.577968 -366.85093)
		(width 0.14732)
		(layer "In6.Cu")
		(net "UPI_CPU0_CPU1_P2P2_DN<22>")
	)
	(segment
		(start 187.568586 -367.951258)
		(end 187.318904 -368.30762)
		(width 0.14732)
		(layer "In6.Cu")
		(net "UPI_CPU0_CPU1_P2P2_DN<22>")
	)
	(segment
		(start 245.274592 -354.673154)
		(end 228.401626 -366.487964)
		(width 0.14732)
		(layer "In6.Cu")
		(net "UPI_CPU0_CPU1_P2P2_DN<22>")
	)
	(segment
		(start 183.809386 -368.614198)
		(end 183.003698 -368.756438)
		(width 0.14732)
		(layer "In6.Cu")
		(net "UPI_CPU0_CPU1_P2P2_DN<22>")
	)
	(segment
		(start 108.556298 -286.48533)
		(end 108.556298 -286.466788)
		(width 0.0889)
		(layer "In6.Cu")
		(net "UPI_CPU0_CPU1_P2P2_DN<22>")
	)
	(segment
		(start 76.03363 -353.750626)
		(end 76.112116 -353.561396)
		(width 0.14732)
		(layer "In6.Cu")
		(net "UPI_CPU0_CPU1_P2P2_DN<22>")
	)
	(segment
		(start 162.193732 -373.48033)
		(end 161.613088 -373.5832)
		(width 0.14732)
		(layer "In6.Cu")
		(net "UPI_CPU0_CPU1_P2P2_DN<22>")
	)
	(segment
		(start 310.593232 -309.829454)
		(end 310.526684 -310.023256)
		(width 0.14732)
		(layer "In6.Cu")
		(net "UPI_CPU0_CPU1_P2P2_DN<22>")
	)
	(segment
		(start 333.285592 -287.012888)
		(end 332.972664 -287.325816)
		(width 0.0889)
		(layer "In6.Cu")
		(net "UPI_CPU0_CPU1_P2P2_DN<22>")
	)
	(segment
		(start 77.34046 -356.906576)
		(end 76.905866 -355.856794)
		(width 0.14732)
		(layer "In6.Cu")
		(net "UPI_CPU0_CPU1_P2P2_DN<22>")
	)
	(segment
		(start 163.26739 -372.237508)
		(end 162.461702 -372.379748)
		(width 0.14732)
		(layer "In6.Cu")
		(net "UPI_CPU0_CPU1_P2P2_DN<22>")
	)
	(segment
		(start 108.597954 -291.060886)
		(end 108.597954 -290.329366)
		(width 0.14732)
		(layer "In6.Cu")
		(net "UPI_CPU0_CPU1_P2P2_DN<22>")
	)
	(segment
		(start 162.461702 -372.379748)
		(end 162.21202 -372.736364)
		(width 0.14732)
		(layer "In6.Cu")
		(net "UPI_CPU0_CPU1_P2P2_DN<22>")
	)
	(segment
		(start 170.742864 -371.97284)
		(end 170.57243 -371.853206)
		(width 0.14732)
		(layer "In6.Cu")
		(net "UPI_CPU0_CPU1_P2P2_DN<22>")
	)
	(segment
		(start 173.725586 -371.296946)
		(end 173.605952 -371.46738)
		(width 0.14732)
		(layer "In6.Cu")
		(net "UPI_CPU0_CPU1_P2P2_DN<22>")
	)
	(segment
		(start 110.153196 -283.709364)
		(end 110.165388 -283.702252)
		(width 0.0889)
		(layer "In6.Cu")
		(net "UPI_CPU0_CPU1_P2P2_DN<22>")
	)
	(segment
		(start 333.567532 -286.797242)
		(end 333.562198 -286.80029)
		(width 0.0889)
		(layer "In6.Cu")
		(net "UPI_CPU0_CPU1_P2P2_DN<22>")
	)
	(segment
		(start 194.267582 -367.673636)
		(end 194.147948 -367.84407)
		(width 0.14732)
		(layer "In6.Cu")
		(net "UPI_CPU0_CPU1_P2P2_DN<22>")
	)
	(segment
		(start 299.819822 -318.851026)
		(end 298.518326 -320.152522)
		(width 0.14732)
		(layer "In6.Cu")
		(net "UPI_CPU0_CPU1_P2P2_DN<22>")
	)
	(segment
		(start 87.43315 -316.789816)
		(end 87.636858 -316.809882)
		(width 0.14732)
		(layer "In6.Cu")
		(net "UPI_CPU0_CPU1_P2P2_DN<22>")
	)
	(segment
		(start 76.426314 -354.698808)
		(end 76.5048 -354.509578)
		(width 0.14732)
		(layer "In6.Cu")
		(net "UPI_CPU0_CPU1_P2P2_DN<22>")
	)
	(segment
		(start 206.379318 -367.973356)
		(end 206.43215 -367.674906)
		(width 0.14732)
		(layer "In6.Cu")
		(net "UPI_CPU0_CPU1_P2P2_DN<22>")
	)
	(segment
		(start 284.522418 -323.920612)
		(end 276.276816 -323.920612)
		(width 0.14732)
		(layer "In6.Cu")
		(net "UPI_CPU0_CPU1_P2P2_DN<22>")
	)
	(segment
		(start 75.51547 -330.496672)
		(end 76.106274 -328.36104)
		(width 0.14732)
		(layer "In6.Cu")
		(net "UPI_CPU0_CPU1_P2P2_DN<22>")
	)
	(segment
		(start 207.659224 -367.578894)
		(end 207.302862 -367.828576)
		(width 0.14732)
		(layer "In6.Cu")
		(net "UPI_CPU0_CPU1_P2P2_DN<22>")
	)
	(segment
		(start 197.961758 -367.021872)
		(end 197.860412 -366.44834)
		(width 0.14732)
		(layer "In6.Cu")
		(net "UPI_CPU0_CPU1_P2P2_DN<22>")
	)
	(segment
		(start 300.830488 -316.03188)
		(end 300.830488 -317.408814)
		(width 0.14732)
		(layer "In6.Cu")
		(net "UPI_CPU0_CPU1_P2P2_DN<22>")
	)
	(segment
		(start 189.00394 -368.753136)
		(end 188.831982 -368.632486)
		(width 0.14732)
		(layer "In6.Cu")
		(net "UPI_CPU0_CPU1_P2P2_DN<22>")
	)
	(segment
		(start 75.389232 -352.194368)
		(end 75.048618 -351.37217)
		(width 0.14732)
		(layer "In6.Cu")
		(net "UPI_CPU0_CPU1_P2P2_DN<22>")
	)
	(segment
		(start 171.341796 -371.12575)
		(end 171.443142 -371.699536)
		(width 0.14732)
		(layer "In6.Cu")
		(net "UPI_CPU0_CPU1_P2P2_DN<22>")
	)
	(segment
		(start 161.4424 -373.463566)
		(end 161.341308 -372.88978)
		(width 0.14732)
		(layer "In6.Cu")
		(net "UPI_CPU0_CPU1_P2P2_DN<22>")
	)
	(segment
		(start 205.37678 -367.17605)
		(end 205.020418 -367.425732)
		(width 0.14732)
		(layer "In6.Cu")
		(net "UPI_CPU0_CPU1_P2P2_DN<22>")
	)
	(segment
		(start 189.582044 -368.650774)
		(end 189.00394 -368.753136)
		(width 0.14732)
		(layer "In6.Cu")
		(net "UPI_CPU0_CPU1_P2P2_DN<22>")
	)
	(segment
		(start 169.041064 -372.27256)
		(end 168.46042 -372.37543)
		(width 0.14732)
		(layer "In6.Cu")
		(net "UPI_CPU0_CPU1_P2P2_DN<22>")
	)
	(segment
		(start 212.75548 -369.247166)
		(end 211.06384 -368.949478)
		(width 0.14732)
		(layer "In6.Cu")
		(net "UPI_CPU0_CPU1_P2P2_DN<22>")
	)
	(segment
		(start 306.889658 -311.947814)
		(end 306.448206 -312.167524)
		(width 0.14732)
		(layer "In6.Cu")
		(net "UPI_CPU0_CPU1_P2P2_DN<22>")
	)
	(segment
		(start 177.318416 -370.07165)
		(end 176.962054 -369.821968)
		(width 0.14732)
		(layer "In6.Cu")
		(net "UPI_CPU0_CPU1_P2P2_DN<22>")
	)
	(segment
		(start 161.341308 -372.88978)
		(end 160.984946 -372.640098)
		(width 0.14732)
		(layer "In6.Cu")
		(net "UPI_CPU0_CPU1_P2P2_DN<22>")
	)
	(segment
		(start 76.984352 -355.667564)
		(end 76.843382 -355.32695)
		(width 0.14732)
		(layer "In6.Cu")
		(net "UPI_CPU0_CPU1_P2P2_DN<22>")
	)
	(segment
		(start 185.137806 -369.283996)
		(end 185.018172 -369.45443)
		(width 0.14732)
		(layer "In6.Cu")
		(net "UPI_CPU0_CPU1_P2P2_DN<22>")
	)
	(segment
		(start 249.121422 -350.826324)
		(end 245.274592 -354.673154)
		(width 0.14732)
		(layer "In6.Cu")
		(net "UPI_CPU0_CPU1_P2P2_DN<22>")
	)
	(segment
		(start 107.80395 -287.778698)
		(end 107.810046 -287.775142)
		(width 0.0889)
		(layer "In6.Cu")
		(net "UPI_CPU0_CPU1_P2P2_DN<22>")
	)
	(segment
		(start 162.21202 -372.736364)
		(end 162.313366 -373.309896)
		(width 0.14732)
		(layer "In6.Cu")
		(net "UPI_CPU0_CPU1_P2P2_DN<22>")
	)
	(segment
		(start 334.785716 -284.033722)
		(end 334.94218 -284.30474)
		(width 0.0889)
		(layer "In6.Cu")
		(net "UPI_CPU0_CPU1_P2P2_DN<22>")
	)
	(segment
		(start 197.860412 -366.44834)
		(end 197.50405 -366.198658)
		(width 0.14732)
		(layer "In6.Cu")
		(net "UPI_CPU0_CPU1_P2P2_DN<22>")
	)
	(segment
		(start 166.776908 -371.93093)
		(end 166.878254 -372.504716)
		(width 0.14732)
		(layer "In6.Cu")
		(net "UPI_CPU0_CPU1_P2P2_DN<22>")
	)
	(segment
		(start 334.51165 -285.166816)
		(end 334.50276 -285.171896)
		(width 0.0889)
		(layer "In6.Cu")
		(net "UPI_CPU0_CPU1_P2P2_DN<22>")
	)
	(segment
		(start 75.048618 -351.37217)
		(end 75.048618 -335.24063)
		(width 0.14732)
		(layer "In6.Cu")
		(net "UPI_CPU0_CPU1_P2P2_DN<22>")
	)
	(segment
		(start 330.073254 -292.358572)
		(end 329.102466 -295.557702)
		(width 0.14732)
		(layer "In6.Cu")
		(net "UPI_CPU0_CPU1_P2P2_DN<22>")
	)
	(segment
		(start 206.43215 -367.674906)
		(end 206.182468 -367.318544)
		(width 0.14732)
		(layer "In6.Cu")
		(net "UPI_CPU0_CPU1_P2P2_DN<22>")
	)
	(segment
		(start 110.61446 -282.900628)
		(end 110.62335 -282.895548)
		(width 0.0889)
		(layer "In6.Cu")
		(net "UPI_CPU0_CPU1_P2P2_DN<22>")
	)
	(segment
		(start 111.566452 -279.637744)
		(end 111.568992 -279.63622)
		(width 0.0889)
		(layer "In6.Cu")
		(net "UPI_CPU0_CPU1_P2P2_DN<22>")
	)
	(segment
		(start 182.155084 -369.95989)
		(end 181.98465 -369.840256)
		(width 0.14732)
		(layer "In6.Cu")
		(net "UPI_CPU0_CPU1_P2P2_DN<22>")
	)
	(segment
		(start 181.526942 -369.016788)
		(end 180.721254 -369.159028)
		(width 0.14732)
		(layer "In6.Cu")
		(net "UPI_CPU0_CPU1_P2P2_DN<22>")
	)
	(segment
		(start 108.02874 -297.660314)
		(end 108.164884 -297.332146)
		(width 0.14732)
		(layer "In6.Cu")
		(net "UPI_CPU0_CPU1_P2P2_DN<22>")
	)
	(segment
		(start 107.803188 -288.426906)
		(end 107.79506 -288.422334)
		(width 0.0889)
		(layer "In6.Cu")
		(net "UPI_CPU0_CPU1_P2P2_DN<22>")
	)
	(segment
		(start 201.81443 -367.167668)
		(end 201.867262 -366.869218)
		(width 0.14732)
		(layer "In6.Cu")
		(net "UPI_CPU0_CPU1_P2P2_DN<22>")
	)
	(segment
		(start 186.719972 -369.15471)
		(end 186.549538 -369.035076)
		(width 0.14732)
		(layer "In6.Cu")
		(net "UPI_CPU0_CPU1_P2P2_DN<22>")
	)
	(segment
		(start 126.377446 -374.062244)
		(end 100.736654 -370.258594)
		(width 0.14732)
		(layer "In6.Cu")
		(net "UPI_CPU0_CPU1_P2P2_DN<22>")
	)
	(segment
		(start 166.75862 -372.67515)
		(end 166.177976 -372.77802)
		(width 0.14732)
		(layer "In6.Cu")
		(net "UPI_CPU0_CPU1_P2P2_DN<22>")
	)
	(segment
		(start 200.402698 -366.918494)
		(end 200.232264 -367.038128)
		(width 0.14732)
		(layer "In6.Cu")
		(net "UPI_CPU0_CPU1_P2P2_DN<22>")
	)
	(segment
		(start 200.232264 -367.038128)
		(end 199.486266 -366.906302)
		(width 0.14732)
		(layer "In6.Cu")
		(net "UPI_CPU0_CPU1_P2P2_DN<22>")
	)
	(segment
		(start 313.284616 -309.176928)
		(end 312.91784 -309.21325)
		(width 0.14732)
		(layer "In6.Cu")
		(net "UPI_CPU0_CPU1_P2P2_DN<22>")
	)
	(segment
		(start 276.276816 -323.920612)
		(end 275.802598 -324.39483)
		(width 0.14732)
		(layer "In6.Cu")
		(net "UPI_CPU0_CPU1_P2P2_DN<22>")
	)
	(segment
		(start 210.997038 -368.480594)
		(end 210.747356 -368.124232)
		(width 0.14732)
		(layer "In6.Cu")
		(net "UPI_CPU0_CPU1_P2P2_DN<22>")
	)
	(segment
		(start 197.50405 -366.198658)
		(end 196.698362 -366.340898)
		(width 0.14732)
		(layer "In6.Cu")
		(net "UPI_CPU0_CPU1_P2P2_DN<22>")
	)
	(segment
		(start 298.518326 -320.152522)
		(end 297.515026 -321.875404)
		(width 0.14732)
		(layer "In6.Cu")
		(net "UPI_CPU0_CPU1_P2P2_DN<22>")
	)
	(segment
		(start 312.91784 -309.21325)
		(end 312.788046 -309.371746)
		(width 0.14732)
		(layer "In6.Cu")
		(net "UPI_CPU0_CPU1_P2P2_DN<22>")
	)
	(segment
		(start 76.905866 -355.856794)
		(end 76.984352 -355.667564)
		(width 0.14732)
		(layer "In6.Cu")
		(net "UPI_CPU0_CPU1_P2P2_DN<22>")
	)
	(segment
		(start 311.625234 -309.486808)
		(end 311.625234 -309.487062)
		(width 0.14732)
		(layer "In6.Cu")
		(net "UPI_CPU0_CPU1_P2P2_DN<22>")
	)
	(segment
		(start 100.736654 -370.258594)
		(end 81.606644 -362.33481)
		(width 0.14732)
		(layer "In6.Cu")
		(net "UPI_CPU0_CPU1_P2P2_DN<22>")
	)
	(segment
		(start 108.083096 -289.062414)
		(end 108.086398 -288.93262)
		(width 0.0889)
		(layer "In6.Cu")
		(net "UPI_CPU0_CPU1_P2P2_DN<22>")
	)
	(segment
		(start 108.164884 -291.493956)
		(end 108.597954 -291.060886)
		(width 0.14732)
		(layer "In6.Cu")
		(net "UPI_CPU0_CPU1_P2P2_DN<22>")
	)
	(segment
		(start 202.514708 -367.440972)
		(end 201.934064 -367.338102)
		(width 0.14732)
		(layer "In6.Cu")
		(net "UPI_CPU0_CPU1_P2P2_DN<22>")
	)
	(segment
		(start 108.26496 -286.969962)
		(end 108.27385 -286.964882)
		(width 0.0889)
		(layer "In6.Cu")
		(net "UPI_CPU0_CPU1_P2P2_DN<22>")
	)
	(segment
		(start 310.924448 -309.66791)
		(end 310.593232 -309.829454)
		(width 0.14732)
		(layer "In6.Cu")
		(net "UPI_CPU0_CPU1_P2P2_DN<22>")
	)
	(segment
		(start 180.721254 -369.159028)
		(end 180.471572 -369.51539)
		(width 0.14732)
		(layer "In6.Cu")
		(net "UPI_CPU0_CPU1_P2P2_DN<22>")
	)
	(segment
		(start 87.941912 -316.37224)
		(end 99.113594 -307.20411)
		(width 0.14732)
		(layer "In6.Cu")
		(net "UPI_CPU0_CPU1_P2P2_DN<22>")
	)
	(segment
		(start 108.236766 -275.375624)
		(end 108.147612 -275.351748)
		(width 0.0889)
		(layer "In6.Cu")
		(net "UPI_CPU0_CPU1_P2P2_DN<22>")
	)
	(segment
		(start 77.592428 -357.514652)
		(end 77.670914 -357.325422)
		(width 0.14732)
		(layer "In6.Cu")
		(net "UPI_CPU0_CPU1_P2P2_DN<22>")
	)
	(segment
		(start 111.561372 -278.660098)
		(end 111.554006 -278.65578)
		(width 0.0889)
		(layer "In6.Cu")
		(net "UPI_CPU0_CPU1_P2P2_DN<22>")
	)
	(segment
		(start 187.42025 -368.881406)
		(end 187.300616 -369.05184)
		(width 0.14732)
		(layer "In6.Cu")
		(net "UPI_CPU0_CPU1_P2P2_DN<22>")
	)
	(segment
		(start 202.737974 -367.022888)
		(end 202.685142 -367.321338)
		(width 0.14732)
		(layer "In6.Cu")
		(net "UPI_CPU0_CPU1_P2P2_DN<22>")
	)
	(segment
		(start 332.972664 -288.393378)
		(end 332.930754 -288.435288)
		(width 0.0889)
		(layer "In6.Cu")
		(net "UPI_CPU0_CPU1_P2P2_DN<22>")
	)
	(segment
		(start 196.550026 -367.271046)
		(end 196.430392 -367.441734)
		(width 0.14732)
		(layer "In6.Cu")
		(net "UPI_CPU0_CPU1_P2P2_DN<22>")
	)
	(segment
		(start 206.182468 -367.318544)
		(end 205.37678 -367.17605)
		(width 0.14732)
		(layer "In6.Cu")
		(net "UPI_CPU0_CPU1_P2P2_DN<22>")
	)
	(segment
		(start 179.60086 -369.66906)
		(end 179.244498 -369.419378)
		(width 0.14732)
		(layer "In6.Cu")
		(net "UPI_CPU0_CPU1_P2P2_DN<22>")
	)
	(segment
		(start 332.972664 -287.325816)
		(end 332.972664 -288.393378)
		(width 0.0889)
		(layer "In6.Cu")
		(net "UPI_CPU0_CPU1_P2P2_DN<22>")
	)
	(segment
		(start 264.582402 -325.50227)
		(end 262.904478 -327.180194)
		(width 0.14732)
		(layer "In6.Cu")
		(net "UPI_CPU0_CPU1_P2P2_DN<22>")
	)
	(segment
		(start 262.904478 -335.885536)
		(end 249.121422 -349.668592)
		(width 0.14732)
		(layer "In6.Cu")
		(net "UPI_CPU0_CPU1_P2P2_DN<22>")
	)
	(segment
		(start 179.702206 -370.242846)
		(end 179.60086 -369.66906)
		(width 0.14732)
		(layer "In6.Cu")
		(net "UPI_CPU0_CPU1_P2P2_DN<22>")
	)
	(segment
		(start 76.653898 -355.248718)
		(end 76.426314 -354.698808)
		(width 0.14732)
		(layer "In6.Cu")
		(net "UPI_CPU0_CPU1_P2P2_DN<22>")
	)
	(segment
		(start 165.906196 -372.0846)
		(end 165.549834 -371.834918)
		(width 0.14732)
		(layer "In6.Cu")
		(net "UPI_CPU0_CPU1_P2P2_DN<22>")
	)
	(segment
		(start 185.286142 -368.353848)
		(end 185.03646 -368.71021)
		(width 0.14732)
		(layer "In6.Cu")
		(net "UPI_CPU0_CPU1_P2P2_DN<22>")
	)
	(segment
		(start 204.096874 -367.570512)
		(end 204.149706 -367.272062)
		(width 0.14732)
		(layer "In6.Cu")
		(net "UPI_CPU0_CPU1_P2P2_DN<22>")
	)
	(segment
		(start 110.068106 -275.398992)
		(end 110.057692 -275.405088)
		(width 0.0889)
		(layer "In6.Cu")
		(net "UPI_CPU0_CPU1_P2P2_DN<22>")
	)
	(segment
		(start 160.030922 -373.712486)
		(end 159.911288 -373.88292)
		(width 0.14732)
		(layer "In6.Cu")
		(net "UPI_CPU0_CPU1_P2P2_DN<22>")
	)
	(segment
		(start 108.597954 -290.329366)
		(end 108.597954 -290.307268)
		(width 0.0889)
		(layer "In6.Cu")
		(net "UPI_CPU0_CPU1_P2P2_DN<22>")
	)
	(segment
		(start 76.106274 -328.36104)
		(end 77.183996 -326.083168)
		(width 0.14732)
		(layer "In6.Cu")
		(net "UPI_CPU0_CPU1_P2P2_DN<22>")
	)
	(segment
		(start 81.606644 -362.33481)
		(end 78.16215 -358.890316)
		(width 0.14732)
		(layer "In6.Cu")
		(net "UPI_CPU0_CPU1_P2P2_DN<22>")
	)
	(segment
		(start 170.57243 -371.853206)
		(end 170.471084 -371.27942)
		(width 0.14732)
		(layer "In6.Cu")
		(net "UPI_CPU0_CPU1_P2P2_DN<22>")
	)
	(segment
		(start 111.568992 -278.664416)
		(end 111.563658 -278.661368)
		(width 0.0889)
		(layer "In6.Cu")
		(net "UPI_CPU0_CPU1_P2P2_DN<22>")
	)
	(segment
		(start 76.112116 -353.561396)
		(end 75.971146 -353.221036)
		(width 0.14732)
		(layer "In6.Cu")
		(net "UPI_CPU0_CPU1_P2P2_DN<22>")
	)
	(segment
		(start 75.719432 -352.613214)
		(end 75.578462 -352.2726)
		(width 0.14732)
		(layer "In6.Cu")
		(net "UPI_CPU0_CPU1_P2P2_DN<22>")
	)
	(segment
		(start 163.725098 -373.060976)
		(end 163.623752 -372.48719)
		(width 0.14732)
		(layer "In6.Cu")
		(net "UPI_CPU0_CPU1_P2P2_DN<22>")
	)
	(segment
		(start 311.11825 -309.734458)
		(end 310.924448 -309.66791)
		(width 0.14732)
		(layer "In6.Cu")
		(net "UPI_CPU0_CPU1_P2P2_DN<22>")
	)
	(segment
		(start 196.698362 -366.340898)
		(end 196.44868 -366.69726)
		(width 0.14732)
		(layer "In6.Cu")
		(net "UPI_CPU0_CPU1_P2P2_DN<22>")
	)
	(segment
		(start 189.85103 -367.548668)
		(end 189.601348 -367.90503)
		(width 0.14732)
		(layer "In6.Cu")
		(net "UPI_CPU0_CPU1_P2P2_DN<22>")
	)
	(segment
		(start 166.878254 -372.504716)
		(end 166.75862 -372.67515)
		(width 0.14732)
		(layer "In6.Cu")
		(net "UPI_CPU0_CPU1_P2P2_DN<22>")
	)
	(segment
		(start 110.144306 -283.714444)
		(end 110.153196 -283.709364)
		(width 0.0889)
		(layer "In6.Cu")
		(net "UPI_CPU0_CPU1_P2P2_DN<22>")
	)
	(segment
		(start 196.44868 -366.69726)
		(end 196.550026 -367.271046)
		(width 0.14732)
		(layer "In6.Cu")
		(net "UPI_CPU0_CPU1_P2P2_DN<22>")
	)
	(segment
		(start 111.563658 -277.033482)
		(end 111.562896 -277.032974)
		(width 0.0889)
		(layer "In6.Cu")
		(net "UPI_CPU0_CPU1_P2P2_DN<22>")
	)
	(segment
		(start 185.03646 -368.71021)
		(end 185.137806 -369.283996)
		(width 0.14732)
		(layer "In6.Cu")
		(net "UPI_CPU0_CPU1_P2P2_DN<22>")
	)
	(segment
		(start 195.577968 -366.85093)
		(end 195.221606 -366.601248)
		(width 0.14732)
		(layer "In6.Cu")
		(net "UPI_CPU0_CPU1_P2P2_DN<22>")
	)
	(segment
		(start 205.020418 -367.425732)
		(end 204.967586 -367.724182)
		(width 0.14732)
		(layer "In6.Cu")
		(net "UPI_CPU0_CPU1_P2P2_DN<22>")
	)
	(segment
		(start 195.850002 -367.544604)
		(end 195.679314 -367.424716)
		(width 0.14732)
		(layer "In6.Cu")
		(net "UPI_CPU0_CPU1_P2P2_DN<22>")
	)
	(segment
		(start 87.921846 -316.575948)
		(end 87.941912 -316.37224)
		(width 0.14732)
		(layer "In6.Cu")
		(net "UPI_CPU0_CPU1_P2P2_DN<22>")
	)
	(segment
		(start 311.625234 -309.487062)
		(end 311.11825 -309.734458)
		(width 0.14732)
		(layer "In6.Cu")
		(net "UPI_CPU0_CPU1_P2P2_DN<22>")
	)
	(segment
		(start 334.94218 -284.30474)
		(end 334.91805 -284.393894)
		(width 0.0889)
		(layer "In6.Cu")
		(net "UPI_CPU0_CPU1_P2P2_DN<22>")
	)
	(segment
		(start 108.147612 -275.351748)
		(end 107.991148 -275.08073)
		(width 0.0889)
		(layer "In6.Cu")
		(net "UPI_CPU0_CPU1_P2P2_DN<22>")
	)
	(segment
		(start 192.133474 -367.146078)
		(end 191.883792 -367.50244)
		(width 0.14732)
		(layer "In6.Cu")
		(net "UPI_CPU0_CPU1_P2P2_DN<22>")
	)
	(segment
		(start 328.131932 -298.756324)
		(end 317.66256 -309.225696)
		(width 0.14732)
		(layer "In6.Cu")
		(net "UPI_CPU0_CPU1_P2P2_DN<22>")
	)
	(segment
		(start 109.132624 -275.396452)
		(end 109.117892 -275.405088)
		(width 0.0889)
		(layer "In6.Cu")
		(net "UPI_CPU0_CPU1_P2P2_DN<22>")
	)
	(segment
		(start 160.179258 -372.782338)
		(end 159.929576 -373.1387)
		(width 0.14732)
		(layer "In6.Cu")
		(net "UPI_CPU0_CPU1_P2P2_DN<22>")
	)
	(segment
		(start 171.323508 -371.86997)
		(end 170.742864 -371.97284)
		(width 0.14732)
		(layer "In6.Cu")
		(net "UPI_CPU0_CPU1_P2P2_DN<22>")
	)
	(segment
		(start 198.132446 -367.142014)
		(end 197.961758 -367.021872)
		(width 0.14732)
		(layer "In6.Cu")
		(net "UPI_CPU0_CPU1_P2P2_DN<22>")
	)
	(segment
		(start 194.415918 -366.743488)
		(end 194.166236 -367.09985)
		(width 0.14732)
		(layer "In6.Cu")
		(net "UPI_CPU0_CPU1_P2P2_DN<22>")
	)
	(segment
		(start 288.02711 -323.110352)
		(end 287.542732 -322.625974)
		(width 0.14732)
		(layer "In6.Cu")
		(net "UPI_CPU0_CPU1_P2P2_DN<22>")
	)
	(segment
		(start 173.873922 -370.366798)
		(end 173.62424 -370.72316)
		(width 0.14732)
		(layer "In6.Cu")
		(net "UPI_CPU0_CPU1_P2P2_DN<22>")
	)
	(segment
		(start 111.845598 -277.536656)
		(end 111.845598 -277.522432)
		(width 0.0889)
		(layer "In6.Cu")
		(net "UPI_CPU0_CPU1_P2P2_DN<22>")
	)
	(segment
		(start 111.08436 -280.458926)
		(end 111.09325 -280.453846)
		(width 0.0889)
		(layer "In6.Cu")
		(net "UPI_CPU0_CPU1_P2P2_DN<22>")
	)
	(segment
		(start 75.640946 -352.802444)
		(end 75.719432 -352.613214)
		(width 0.14732)
		(layer "In6.Cu")
		(net "UPI_CPU0_CPU1_P2P2_DN<22>")
	)
	(segment
		(start 108.086398 -288.93262)
		(end 108.086906 -288.922206)
		(width 0.0889)
		(layer "In6.Cu")
		(net "UPI_CPU0_CPU1_P2P2_DN<22>")
	)
	(segment
		(start 108.743496 -275.405088)
		(end 108.733082 -275.398992)
		(width 0.0889)
		(layer "In6.Cu")
		(net "UPI_CPU0_CPU1_P2P2_DN<22>")
	)
	(segment
		(start 275.802598 -324.39483)
		(end 271.514316 -324.39483)
		(width 0.14732)
		(layer "In6.Cu")
		(net "UPI_CPU0_CPU1_P2P2_DN<22>")
	)
	(segment
		(start 334.220312 -285.651448)
		(end 334.220312 -285.661354)
		(width 0.0889)
		(layer "In6.Cu")
		(net "UPI_CPU0_CPU1_P2P2_DN<22>")
	)
	(segment
		(start 191.865758 -368.246406)
		(end 191.284352 -368.34953)
		(width 0.14732)
		(layer "In6.Cu")
		(net "UPI_CPU0_CPU1_P2P2_DN<22>")
	)
	(segment
		(start 310.526684 -310.023256)
		(end 309.8292 -310.363616)
		(width 0.14732)
		(layer "In6.Cu")
		(net "UPI_CPU0_CPU1_P2P2_DN<22>")
	)
	(segment
		(start 110.62335 -281.267662)
		(end 110.629446 -281.264106)
		(width 0.0889)
		(layer "In6.Cu")
		(net "UPI_CPU0_CPU1_P2P2_DN<22>")
	)
	(segment
		(start 204.967586 -367.724182)
		(end 204.797152 -367.843816)
		(width 0.14732)
		(layer "In6.Cu")
		(net "UPI_CPU0_CPU1_P2P2_DN<22>")
	)
	(segment
		(start 301.608236 -315.254132)
		(end 300.830488 -316.03188)
		(width 0.14732)
		(layer "In6.Cu")
		(net "UPI_CPU0_CPU1_P2P2_DN<22>")
	)
	(segment
		(start 203.900024 -366.9157)
		(end 203.094336 -366.773206)
		(width 0.14732)
		(layer "In6.Cu")
		(net "UPI_CPU0_CPU1_P2P2_DN<22>")
	)
	(segment
		(start 189.601348 -367.90503)
		(end 189.702694 -368.478816)
		(width 0.14732)
		(layer "In6.Cu")
		(net "UPI_CPU0_CPU1_P2P2_DN<22>")
	)
	(segment
		(start 262.904478 -327.180194)
		(end 262.904478 -335.885536)
		(width 0.14732)
		(layer "In6.Cu")
		(net "UPI_CPU0_CPU1_P2P2_DN<22>")
	)
	(segment
		(start 177.590196 -370.76507)
		(end 177.419762 -370.645436)
		(width 0.14732)
		(layer "In6.Cu")
		(net "UPI_CPU0_CPU1_P2P2_DN<22>")
	)
	(segment
		(start 172.397166 -370.627148)
		(end 171.591478 -370.769388)
		(width 0.14732)
		(layer "In6.Cu")
		(net "UPI_CPU0_CPU1_P2P2_DN<22>")
	)
	(segment
		(start 196.430392 -367.441734)
		(end 195.850002 -367.544604)
		(width 0.14732)
		(layer "In6.Cu")
		(net "UPI_CPU0_CPU1_P2P2_DN<22>")
	)
	(segment
		(start 201.867262 -366.869218)
		(end 201.61758 -366.512856)
		(width 0.14732)
		(layer "In6.Cu")
		(net "UPI_CPU0_CPU1_P2P2_DN<22>")
	)
	(segment
		(start 177.419762 -370.645436)
		(end 177.318416 -370.07165)
		(width 0.14732)
		(layer "In6.Cu")
		(net "UPI_CPU0_CPU1_P2P2_DN<22>")
	)
	(segment
		(start 172.854874 -371.450616)
		(end 172.753528 -370.87683)
		(width 0.14732)
		(layer "In6.Cu")
		(net "UPI_CPU0_CPU1_P2P2_DN<22>")
	)
	(segment
		(start 193.295524 -367.25352)
		(end 192.939162 -367.003838)
		(width 0.14732)
		(layer "In6.Cu")
		(net "UPI_CPU0_CPU1_P2P2_DN<22>")
	)
	(segment
		(start 75.781662 -353.142296)
		(end 75.640946 -352.802444)
		(width 0.14732)
		(layer "In6.Cu")
		(net "UPI_CPU0_CPU1_P2P2_DN<22>")
	)
	(segment
		(start 169.059352 -371.52834)
		(end 169.160698 -372.102126)
		(width 0.14732)
		(layer "In6.Cu")
		(net "UPI_CPU0_CPU1_P2P2_DN<22>")
	)
	(segment
		(start 175.906684 -370.32057)
		(end 176.00803 -370.894356)
		(width 0.14732)
		(layer "In6.Cu")
		(net "UPI_CPU0_CPU1_P2P2_DN<22>")
	)
	(segment
		(start 317.66256 -309.225696)
		(end 314.251848 -309.225696)
		(width 0.14732)
		(layer "In6.Cu")
		(net "UPI_CPU0_CPU1_P2P2_DN<22>")
	)
	(segment
		(start 110.61446 -281.272742)
		(end 110.62335 -281.267662)
		(width 0.0889)
		(layer "In6.Cu")
		(net "UPI_CPU0_CPU1_P2P2_DN<22>")
	)
	(segment
		(start 200.45553 -366.620044)
		(end 200.402698 -366.918494)
		(width 0.14732)
		(layer "In6.Cu")
		(net "UPI_CPU0_CPU1_P2P2_DN<22>")
	)
	(segment
		(start 332.930754 -288.457386)
		(end 332.930754 -288.671762)
		(width 0.14732)
		(layer "In6.Cu")
		(net "UPI_CPU0_CPU1_P2P2_DN<22>")
	)
	(segment
		(start 107.424982 -298.47413)
		(end 108.02874 -297.660314)
		(width 0.14732)
		(layer "In6.Cu")
		(net "UPI_CPU0_CPU1_P2P2_DN<22>")
	)
	(segment
		(start 75.578462 -352.2726)
		(end 75.389232 -352.194368)
		(width 0.14732)
		(layer "In6.Cu")
		(net "UPI_CPU0_CPU1_P2P2_DN<22>")
	)
	(segment
		(start 111.554006 -278.017224)
		(end 111.562896 -278.012144)
		(width 0.0889)
		(layer "In6.Cu")
		(net "UPI_CPU0_CPU1_P2P2_DN<22>")
	)
	(segment
		(start 178.43881 -369.561618)
		(end 178.189128 -369.91798)
		(width 0.14732)
		(layer "In6.Cu")
		(net "UPI_CPU0_CPU1_P2P2_DN<22>")
	)
	(segment
		(start 329.102466 -295.557956)
		(end 328.131932 -298.756324)
		(width 0.14732)
		(layer "In6.Cu")
		(net "UPI_CPU0_CPU1_P2P2_DN<22>")
	)
	(segment
		(start 76.174346 -354.090732)
		(end 76.03363 -353.750626)
		(width 0.14732)
		(layer "In6.Cu")
		(net "UPI_CPU0_CPU1_P2P2_DN<22>")
	)
	(segment
		(start 203.094336 -366.773206)
		(end 202.737974 -367.022888)
		(width 0.14732)
		(layer "In6.Cu")
		(net "UPI_CPU0_CPU1_P2P2_DN<22>")
	)
	(segment
		(start 307.61559 -311.851294)
		(end 306.889658 -311.947814)
		(width 0.14732)
		(layer "In6.Cu")
		(net "UPI_CPU0_CPU1_P2P2_DN<22>")
	)
	(segment
		(start 75.048618 -335.24063)
		(end 75.51547 -330.496672)
		(width 0.14732)
		(layer "In6.Cu")
		(net "UPI_CPU0_CPU1_P2P2_DN<22>")
	)
	(segment
		(start 110.62335 -281.916378)
		(end 110.61446 -281.911298)
		(width 0.0889)
		(layer "In6.Cu")
		(net "UPI_CPU0_CPU1_P2P2_DN<22>")
	)
	(segment
		(start 191.883792 -367.50244)
		(end 191.985138 -368.076226)
		(width 0.14732)
		(layer "In6.Cu")
		(net "UPI_CPU0_CPU1_P2P2_DN<22>")
	)
	(segment
		(start 111.563658 -278.661368)
		(end 111.562896 -278.66086)
		(width 0.0889)
		(layer "In6.Cu")
		(net "UPI_CPU0_CPU1_P2P2_DN<22>")
	)
	(segment
		(start 333.57058 -286.795718)
		(end 333.567532 -286.797242)
		(width 0.0889)
		(layer "In6.Cu")
		(net "UPI_CPU0_CPU1_P2P2_DN<22>")
	)
	(segment
		(start 184.267094 -369.437666)
		(end 184.165748 -368.86388)
		(width 0.14732)
		(layer "In6.Cu")
		(net "UPI_CPU0_CPU1_P2P2_DN<22>")
	)
	(segment
		(start 164.744146 -371.977158)
		(end 164.494464 -372.33352)
		(width 0.14732)
		(layer "In6.Cu")
		(net "UPI_CPU0_CPU1_P2P2_DN<22>")
	)
	(segment
		(start 306.448206 -312.167524)
		(end 302.13935 -314.698634)
		(width 0.14732)
		(layer "In6.Cu")
		(net "UPI_CPU0_CPU1_P2P2_DN<22>")
	)
	(segment
		(start 202.685142 -367.321338)
		(end 202.514708 -367.440972)
		(width 0.14732)
		(layer "In6.Cu")
		(net "UPI_CPU0_CPU1_P2P2_DN<22>")
	)
	(segment
		(start 186.549538 -369.035076)
		(end 186.448192 -368.46129)
		(width 0.14732)
		(layer "In6.Cu")
		(net "UPI_CPU0_CPU1_P2P2_DN<22>")
	)
	(segment
		(start 181.883304 -369.26647)
		(end 181.526942 -369.016788)
		(width 0.14732)
		(layer "In6.Cu")
		(net "UPI_CPU0_CPU1_P2P2_DN<22>")
	)
	(segment
		(start 204.216508 -367.740946)
		(end 204.096874 -367.570512)
		(width 0.14732)
		(layer "In6.Cu")
		(net "UPI_CPU0_CPU1_P2P2_DN<22>")
	)
	(segment
		(start 78.16215 -358.890316)
		(end 77.592428 -357.514652)
		(width 0.14732)
		(layer "In6.Cu")
		(net "UPI_CPU0_CPU1_P2P2_DN<22>")
	)
	(segment
		(start 312.788046 -309.371746)
		(end 311.625234 -309.486808)
		(width 0.14732)
		(layer "In6.Cu")
		(net "UPI_CPU0_CPU1_P2P2_DN<22>")
	)
	(segment
		(start 175.137318 -371.048026)
		(end 175.035972 -370.47424)
		(width 0.14732)
		(layer "In6.Cu")
		(net "UPI_CPU0_CPU1_P2P2_DN<22>")
	)
	(segment
		(start 181.98465 -369.840256)
		(end 181.883304 -369.26647)
		(width 0.14732)
		(layer "In6.Cu")
		(net "UPI_CPU0_CPU1_P2P2_DN<22>")
	)
	(segment
		(start 191.985138 -368.076226)
		(end 191.865758 -368.246406)
		(width 0.14732)
		(layer "In6.Cu")
		(net "UPI_CPU0_CPU1_P2P2_DN<22>")
	)
	(segment
		(start 75.971146 -353.221036)
		(end 75.781662 -353.14255)
		(width 0.14732)
		(layer "In6.Cu")
		(net "UPI_CPU0_CPU1_P2P2_DN<22>")
	)
	(segment
		(start 332.930754 -288.671762)
		(end 331.746098 -289.856418)
		(width 0.14732)
		(layer "In6.Cu")
		(net "UPI_CPU0_CPU1_P2P2_DN<22>")
	)
	(segment
		(start 178.290474 -370.491766)
		(end 178.17084 -370.6622)
		(width 0.14732)
		(layer "In6.Cu")
		(net "UPI_CPU0_CPU1_P2P2_DN<22>")
	)
	(segment
		(start 204.149706 -367.272062)
		(end 203.900024 -366.9157)
		(width 0.14732)
		(layer "In6.Cu")
		(net "UPI_CPU0_CPU1_P2P2_DN<22>")
	)
	(segment
		(start 209.941668 -367.981738)
		(end 209.585306 -368.23142)
		(width 0.14732)
		(layer "In6.Cu")
		(net "UPI_CPU0_CPU1_P2P2_DN<22>")
	)
	(segment
		(start 180.572918 -370.089176)
		(end 180.453284 -370.25961)
		(width 0.14732)
		(layer "In6.Cu")
		(net "UPI_CPU0_CPU1_P2P2_DN<22>")
	)
	(segment
		(start 173.605952 -371.46738)
		(end 173.025308 -371.57025)
		(width 0.14732)
		(layer "In6.Cu")
		(net "UPI_CPU0_CPU1_P2P2_DN<22>")
	)
	(segment
		(start 187.300616 -369.05184)
		(end 186.719972 -369.15471)
		(width 0.14732)
		(layer "In6.Cu")
		(net "UPI_CPU0_CPU1_P2P2_DN<22>")
	)
	(segment
		(start 111.375698 -276.717252)
		(end 111.375698 -276.69871)
		(width 0.0889)
		(layer "In6.Cu")
		(net "UPI_CPU0_CPU1_P2P2_DN<22>")
	)
	(segment
		(start 209.532474 -368.52987)
		(end 209.36204 -368.649504)
		(width 0.14732)
		(layer "In6.Cu")
		(net "UPI_CPU0_CPU1_P2P2_DN<22>")
	)
	(segment
		(start 176.962054 -369.821968)
		(end 176.156366 -369.964208)
		(width 0.14732)
		(layer "In6.Cu")
		(net "UPI_CPU0_CPU1_P2P2_DN<22>")
	)
	(arc
		(start 107.810046 -287.775142)
		(mid 108.012459 -287.568729)
		(end 108.086398 -287.28924)
		(width 0.0889)
		(layer "In6.Cu")
		(net "UPI_CPU0_CPU1_P2P2_DN<22>")
	)
	(arc
		(start 109.495844 -284.847538)
		(mid 109.543523 -284.664638)
		(end 109.674406 -284.52826)
		(width 0.0889)
		(layer "In6.Cu")
		(net "UPI_CPU0_CPU1_P2P2_DN<22>")
	)
	(arc
		(start 110.62335 -275.405088)
		(mid 110.346537 -275.329252)
		(end 110.068106 -275.398992)
		(width 0.0889)
		(layer "In6.Cu")
		(net "UPI_CPU0_CPU1_P2P2_DN<22>")
	)
	(arc
		(start 110.057692 -275.405088)
		(mid 109.870494 -275.455231)
		(end 109.683296 -275.405088)
		(width 0.0889)
		(layer "In6.Cu")
		(net "UPI_CPU0_CPU1_P2P2_DN<22>")
	)
	(arc
		(start 333.750666 -286.483298)
		(mid 333.701194 -286.661727)
		(end 333.572358 -286.794702)
		(width 0.0889)
		(layer "In6.Cu")
		(net "UPI_CPU0_CPU1_P2P2_DN<22>")
	)
	(arc
		(start 109.683296 -275.405088)
		(mid 109.409067 -275.329163)
		(end 109.132624 -275.396452)
		(width 0.0889)
		(layer "In6.Cu")
		(net "UPI_CPU0_CPU1_P2P2_DN<22>")
	)
	(arc
		(start 110.165388 -283.702252)
		(mid 110.363616 -283.496404)
		(end 110.435898 -283.219906)
		(width 0.0889)
		(layer "In6.Cu")
		(net "UPI_CPU0_CPU1_P2P2_DN<22>")
	)
	(arc
		(start 110.62335 -282.895548)
		(mid 110.826655 -282.694682)
		(end 110.905798 -282.42006)
		(width 0.0889)
		(layer "In6.Cu")
		(net "UPI_CPU0_CPU1_P2P2_DN<22>")
	)
	(arc
		(start 107.79506 -288.422334)
		(mid 107.616463 -288.103056)
		(end 107.79506 -287.783778)
		(width 0.0889)
		(layer "In6.Cu")
		(net "UPI_CPU0_CPU1_P2P2_DN<22>")
	)
	(arc
		(start 108.743496 -286.151066)
		(mid 108.946977 -285.950262)
		(end 109.026198 -285.675578)
		(width 0.0889)
		(layer "In6.Cu")
		(net "UPI_CPU0_CPU1_P2P2_DN<22>")
	)
	(arc
		(start 107.822238 -288.43859)
		(mid 107.813148 -288.432914)
		(end 107.80395 -288.427414)
		(width 0.0889)
		(layer "In6.Cu")
		(net "UPI_CPU0_CPU1_P2P2_DN<22>")
	)
	(arc
		(start 333.562198 -286.80029)
		(mid 333.416999 -286.897614)
		(end 333.285592 -287.012888)
		(width 0.0889)
		(layer "In6.Cu")
		(net "UPI_CPU0_CPU1_P2P2_DN<22>")
	)
	(arc
		(start 111.845598 -277.522432)
		(mid 111.771607 -277.242866)
		(end 111.568992 -277.03653)
		(width 0.0889)
		(layer "In6.Cu")
		(net "UPI_CPU0_CPU1_P2P2_DN<22>")
	)
	(arc
		(start 110.905798 -280.778204)
		(mid 110.953477 -280.595304)
		(end 111.08436 -280.458926)
		(width 0.0889)
		(layer "In6.Cu")
		(net "UPI_CPU0_CPU1_P2P2_DN<22>")
	)
	(arc
		(start 111.568992 -279.63622)
		(mid 111.845566 -279.150318)
		(end 111.568992 -278.664416)
		(width 0.0889)
		(layer "In6.Cu")
		(net "UPI_CPU0_CPU1_P2P2_DN<22>")
	)
	(arc
		(start 110.61446 -281.911298)
		(mid 110.435863 -281.59202)
		(end 110.61446 -281.272742)
		(width 0.0889)
		(layer "In6.Cu")
		(net "UPI_CPU0_CPU1_P2P2_DN<22>")
	)
	(arc
		(start 110.905798 -275.880576)
		(mid 110.826657 -275.605953)
		(end 110.62335 -275.405088)
		(width 0.0889)
		(layer "In6.Cu")
		(net "UPI_CPU0_CPU1_P2P2_DN<22>")
	)
	(arc
		(start 111.375698 -276.69871)
		(mid 111.297587 -276.421761)
		(end 111.09325 -276.219158)
		(width 0.0889)
		(layer "In6.Cu")
		(net "UPI_CPU0_CPU1_P2P2_DN<22>")
	)
	(arc
		(start 111.562896 -278.012144)
		(mid 111.766377 -277.81134)
		(end 111.845598 -277.536656)
		(width 0.0889)
		(layer "In6.Cu")
		(net "UPI_CPU0_CPU1_P2P2_DN<22>")
	)
	(arc
		(start 109.213396 -285.336996)
		(mid 109.417731 -285.134391)
		(end 109.495844 -284.857444)
		(width 0.0889)
		(layer "In6.Cu")
		(net "UPI_CPU0_CPU1_P2P2_DN<22>")
	)
	(arc
		(start 110.905798 -282.405836)
		(mid 110.831882 -282.126334)
		(end 110.629446 -281.919934)
		(width 0.0889)
		(layer "In6.Cu")
		(net "UPI_CPU0_CPU1_P2P2_DN<22>")
	)
	(arc
		(start 334.690212 -284.847538)
		(mid 334.642533 -285.030438)
		(end 334.51165 -285.166816)
		(width 0.0889)
		(layer "In6.Cu")
		(net "UPI_CPU0_CPU1_P2P2_DN<22>")
	)
	(arc
		(start 334.220312 -285.661354)
		(mid 334.172633 -285.844254)
		(end 334.04175 -285.980632)
		(width 0.0889)
		(layer "In6.Cu")
		(net "UPI_CPU0_CPU1_P2P2_DN<22>")
	)
	(arc
		(start 109.117892 -275.405088)
		(mid 108.930694 -275.455231)
		(end 108.743496 -275.405088)
		(width 0.0889)
		(layer "In6.Cu")
		(net "UPI_CPU0_CPU1_P2P2_DN<22>")
	)
	(arc
		(start 109.683296 -284.52318)
		(mid 109.887631 -284.320575)
		(end 109.965744 -284.043628)
		(width 0.0889)
		(layer "In6.Cu")
		(net "UPI_CPU0_CPU1_P2P2_DN<22>")
	)
	(arc
		(start 334.50276 -285.171896)
		(mid 334.298425 -285.374501)
		(end 334.220312 -285.651448)
		(width 0.0889)
		(layer "In6.Cu")
		(net "UPI_CPU0_CPU1_P2P2_DN<22>")
	)
	(arc
		(start 108.556044 -289.646614)
		(mid 108.449659 -289.44013)
		(end 108.271564 -289.291014)
		(width 0.0889)
		(layer "In6.Cu")
		(net "UPI_CPU0_CPU1_P2P2_DN<22>")
	)
	(arc
		(start 109.965744 -284.033722)
		(mid 110.013423 -283.850822)
		(end 110.144306 -283.714444)
		(width 0.0889)
		(layer "In6.Cu")
		(net "UPI_CPU0_CPU1_P2P2_DN<22>")
	)
	(arc
		(start 109.026198 -285.652718)
		(mid 109.078468 -285.470353)
		(end 109.213396 -285.336996)
		(width 0.0889)
		(layer "In6.Cu")
		(net "UPI_CPU0_CPU1_P2P2_DN<22>")
	)
	(arc
		(start 334.901032 -284.407102)
		(mid 334.745634 -284.603383)
		(end 334.690212 -284.847538)
		(width 0.0889)
		(layer "In6.Cu")
		(net "UPI_CPU0_CPU1_P2P2_DN<22>")
	)
	(arc
		(start 108.271564 -289.291014)
		(mid 108.155231 -289.194947)
		(end 108.083096 -289.062414)
		(width 0.0889)
		(layer "In6.Cu")
		(net "UPI_CPU0_CPU1_P2P2_DN<22>")
	)
	(arc
		(start 108.256324 -275.367496)
		(mid 108.246506 -275.371466)
		(end 108.236766 -275.375624)
		(width 0.0889)
		(layer "In6.Cu")
		(net "UPI_CPU0_CPU1_P2P2_DN<22>")
	)
	(arc
		(start 108.27385 -286.964882)
		(mid 108.478185 -286.762277)
		(end 108.556298 -286.48533)
		(width 0.0889)
		(layer "In6.Cu")
		(net "UPI_CPU0_CPU1_P2P2_DN<22>")
	)
	(arc
		(start 334.03286 -285.985712)
		(mid 333.830574 -286.184693)
		(end 333.750412 -286.456882)
		(width 0.0889)
		(layer "In6.Cu")
		(net "UPI_CPU0_CPU1_P2P2_DN<22>")
	)
	(arc
		(start 111.562896 -277.032974)
		(mid 111.427963 -276.89962)
		(end 111.375698 -276.717252)
		(width 0.0889)
		(layer "In6.Cu")
		(net "UPI_CPU0_CPU1_P2P2_DN<22>")
	)
	(arc
		(start 111.09325 -280.453846)
		(mid 111.295536 -280.254865)
		(end 111.375698 -279.982676)
		(width 0.0889)
		(layer "In6.Cu")
		(net "UPI_CPU0_CPU1_P2P2_DN<22>")
	)
	(arc
		(start 111.554006 -278.65578)
		(mid 111.375409 -278.336502)
		(end 111.554006 -278.017224)
		(width 0.0889)
		(layer "In6.Cu")
		(net "UPI_CPU0_CPU1_P2P2_DN<22>")
	)
	(arc
		(start 334.91805 -284.393894)
		(mid 334.909478 -284.400416)
		(end 334.901032 -284.407102)
		(width 0.0889)
		(layer "In6.Cu")
		(net "UPI_CPU0_CPU1_P2P2_DN<22>")
	)
	(arc
		(start 110.629446 -281.264106)
		(mid 110.831859 -281.057693)
		(end 110.905798 -280.778204)
		(width 0.0889)
		(layer "In6.Cu")
		(net "UPI_CPU0_CPU1_P2P2_DN<22>")
	)
	(arc
		(start 108.733082 -275.398992)
		(mid 108.498202 -275.330427)
		(end 108.256324 -275.367496)
		(width 0.0889)
		(layer "In6.Cu")
		(net "UPI_CPU0_CPU1_P2P2_DN<22>")
	)
	(arc
		(start 108.556298 -286.466788)
		(mid 108.608568 -286.284423)
		(end 108.743496 -286.151066)
		(width 0.0889)
		(layer "In6.Cu")
		(net "UPI_CPU0_CPU1_P2P2_DN<22>")
	)
	(arc
		(start 110.435898 -283.219906)
		(mid 110.483577 -283.037006)
		(end 110.61446 -282.900628)
		(width 0.0889)
		(layer "In6.Cu")
		(net "UPI_CPU0_CPU1_P2P2_DN<22>")
	)
	(arc
		(start 111.08436 -276.214078)
		(mid 110.953446 -276.077718)
		(end 110.905798 -275.8948)
		(width 0.0889)
		(layer "In6.Cu")
		(net "UPI_CPU0_CPU1_P2P2_DN<22>")
	)
	(arc
		(start 108.086398 -287.28924)
		(mid 108.134077 -287.10634)
		(end 108.26496 -286.969962)
		(width 0.0889)
		(layer "In6.Cu")
		(net "UPI_CPU0_CPU1_P2P2_DN<22>")
	)
	(arc
		(start 111.375698 -279.955498)
		(mid 111.427968 -279.773133)
		(end 111.562896 -279.639776)
		(width 0.0889)
		(layer "In6.Cu")
		(net "UPI_CPU0_CPU1_P2P2_DN<22>")
	)
	(arc
		(start 108.086906 -288.922206)
		(mid 108.017516 -288.645948)
		(end 107.822238 -288.43859)
		(width 0.0889)
		(layer "In6.Cu")
		(net "UPI_CPU0_CPU1_P2P2_DN<22>")
	)
	(segment
		(start 109.400594 -275.894546)
		(end 109.40034 -275.8948)
		(width 0.13208)
		(layer "F.Cu")
		(net "UPI_CPU0_CPU1_P2P2_DN<21>")
	)
	(segment
		(start 334.315562 -285.939484)
		(end 334.315562 -286.475424)
		(width 0.13208)
		(layer "F.Cu")
		(net "UPI_CPU0_CPU1_P2P2_DN<21>")
	)
	(segment
		(start 109.400594 -275.35886)
		(end 109.400594 -275.894546)
		(width 0.13208)
		(layer "F.Cu")
		(net "UPI_CPU0_CPU1_P2P2_DN<21>")
	)
	(segment
		(start 268.374114 -333.790036)
		(end 267.9573 -334.20685)
		(width 0.14732)
		(layer "In6.Cu")
		(net "UPI_CPU0_CPU1_P2P2_DN<21>")
	)
	(segment
		(start 109.965744 -282.424378)
		(end 109.965744 -282.39593)
		(width 0.0889)
		(layer "In6.Cu")
		(net "UPI_CPU0_CPU1_P2P2_DN<21>")
	)
	(segment
		(start 301.391828 -318.985138)
		(end 301.391828 -319.942718)
		(width 0.14732)
		(layer "In6.Cu")
		(net "UPI_CPU0_CPU1_P2P2_DN<21>")
	)
	(segment
		(start 254.638556 -347.317314)
		(end 253.85903 -346.537788)
		(width 0.14732)
		(layer "In6.Cu")
		(net "UPI_CPU0_CPU1_P2P2_DN<21>")
	)
	(segment
		(start 239.505744 -360.108754)
		(end 239.076738 -360.032808)
		(width 0.14732)
		(layer "In6.Cu")
		(net "UPI_CPU0_CPU1_P2P2_DN<21>")
	)
	(segment
		(start 252.999748 -348.956122)
		(end 252.220222 -348.176596)
		(width 0.14732)
		(layer "In6.Cu")
		(net "UPI_CPU0_CPU1_P2P2_DN<21>")
	)
	(segment
		(start 103.897176 -300.247812)
		(end 105.709974 -297.804332)
		(width 0.14732)
		(layer "In6.Cu")
		(net "UPI_CPU0_CPU1_P2P2_DN<21>")
	)
	(segment
		(start 242.128548 -358.271318)
		(end 242.672616 -359.04805)
		(width 0.14732)
		(layer "In6.Cu")
		(net "UPI_CPU0_CPU1_P2P2_DN<21>")
	)
	(segment
		(start 308.78145 -312.737754)
		(end 308.63667 -312.882534)
		(width 0.14732)
		(layer "In6.Cu")
		(net "UPI_CPU0_CPU1_P2P2_DN<21>")
	)
	(segment
		(start 301.247048 -320.455798)
		(end 301.391828 -320.600578)
		(width 0.14732)
		(layer "In6.Cu")
		(net "UPI_CPU0_CPU1_P2P2_DN<21>")
	)
	(segment
		(start 247.270016 -354.294948)
		(end 244.679724 -356.109016)
		(width 0.14732)
		(layer "In6.Cu")
		(net "UPI_CPU0_CPU1_P2P2_DN<21>")
	)
	(segment
		(start 262.678164 -337.718654)
		(end 263.45769 -338.49818)
		(width 0.14732)
		(layer "In6.Cu")
		(net "UPI_CPU0_CPU1_P2P2_DN<21>")
	)
	(segment
		(start 270.939514 -331.224636)
		(end 269.596108 -332.568042)
		(width 0.14732)
		(layer "In6.Cu")
		(net "UPI_CPU0_CPU1_P2P2_DN<21>")
	)
	(segment
		(start 257.76174 -342.635078)
		(end 258.541266 -343.414604)
		(width 0.14732)
		(layer "In6.Cu")
		(net "UPI_CPU0_CPU1_P2P2_DN<21>")
	)
	(segment
		(start 256.277364 -345.678506)
		(end 255.497838 -344.89898)
		(width 0.14732)
		(layer "In6.Cu")
		(net "UPI_CPU0_CPU1_P2P2_DN<21>")
	)
	(segment
		(start 251.986034 -349.969836)
		(end 251.986034 -350.178116)
		(width 0.14732)
		(layer "In6.Cu")
		(net "UPI_CPU0_CPU1_P2P2_DN<21>")
	)
	(segment
		(start 241.947954 -359.555542)
		(end 241.40414 -358.779064)
		(width 0.14732)
		(layer "In6.Cu")
		(net "UPI_CPU0_CPU1_P2P2_DN<21>")
	)
	(segment
		(start 258.340098 -341.621364)
		(end 257.76174 -342.199722)
		(width 0.14732)
		(layer "In6.Cu")
		(net "UPI_CPU0_CPU1_P2P2_DN<21>")
	)
	(segment
		(start 297.82389 -323.386958)
		(end 297.48353 -323.527928)
		(width 0.14732)
		(layer "In6.Cu")
		(net "UPI_CPU0_CPU1_P2P2_DN<21>")
	)
	(segment
		(start 313.439556 -311.232296)
		(end 312.973974 -311.328054)
		(width 0.14732)
		(layer "In6.Cu")
		(net "UPI_CPU0_CPU1_P2P2_DN<21>")
	)
	(segment
		(start 126.196852 -374.897904)
		(end 100.570792 -371.09654)
		(width 0.14732)
		(layer "In6.Cu")
		(net "UPI_CPU0_CPU1_P2P2_DN<21>")
	)
	(segment
		(start 311.080404 -311.718198)
		(end 309.916068 -312.882534)
		(width 0.14732)
		(layer "In6.Cu")
		(net "UPI_CPU0_CPU1_P2P2_DN<21>")
	)
	(segment
		(start 261.818882 -340.345268)
		(end 261.402068 -340.762082)
		(width 0.14732)
		(layer "In6.Cu")
		(net "UPI_CPU0_CPU1_P2P2_DN<21>")
	)
	(segment
		(start 266.735306 -335.428844)
		(end 266.318492 -335.845658)
		(width 0.14732)
		(layer "In6.Cu")
		(net "UPI_CPU0_CPU1_P2P2_DN<21>")
	)
	(segment
		(start 308.63667 -312.882534)
		(end 307.442108 -312.882534)
		(width 0.14732)
		(layer "In6.Cu")
		(net "UPI_CPU0_CPU1_P2P2_DN<21>")
	)
	(segment
		(start 107.61599 -290.151058)
		(end 107.61599 -289.610292)
		(width 0.0889)
		(layer "In6.Cu")
		(net "UPI_CPU0_CPU1_P2P2_DN<21>")
	)
	(segment
		(start 259.76326 -342.40089)
		(end 259.55498 -342.40089)
		(width 0.14732)
		(layer "In6.Cu")
		(net "UPI_CPU0_CPU1_P2P2_DN<21>")
	)
	(segment
		(start 259.55498 -342.40089)
		(end 258.775454 -341.621364)
		(width 0.14732)
		(layer "In6.Cu")
		(net "UPI_CPU0_CPU1_P2P2_DN<21>")
	)
	(segment
		(start 267.9573 -334.20685)
		(end 267.74902 -334.20685)
		(width 0.14732)
		(layer "In6.Cu")
		(net "UPI_CPU0_CPU1_P2P2_DN<21>")
	)
	(segment
		(start 255.497838 -344.89898)
		(end 255.062482 -344.89898)
		(width 0.14732)
		(layer "In6.Cu")
		(net "UPI_CPU0_CPU1_P2P2_DN<21>")
	)
	(segment
		(start 312.442098 -311.289954)
		(end 312.329576 -311.46115)
		(width 0.14732)
		(layer "In6.Cu")
		(net "UPI_CPU0_CPU1_P2P2_DN<21>")
	)
	(segment
		(start 256.902458 -345.261692)
		(end 256.485644 -345.678506)
		(width 0.14732)
		(layer "In6.Cu")
		(net "UPI_CPU0_CPU1_P2P2_DN<21>")
	)
	(segment
		(start 258.124452 -344.039698)
		(end 257.916172 -344.039698)
		(width 0.14732)
		(layer "In6.Cu")
		(net "UPI_CPU0_CPU1_P2P2_DN<21>")
	)
	(segment
		(start 106.863896 -288.427414)
		(end 106.855006 -288.422334)
		(width 0.0889)
		(layer "In6.Cu")
		(net "UPI_CPU0_CPU1_P2P2_DN<21>")
	)
	(segment
		(start 278.59482 -325.268082)
		(end 272.170144 -325.268082)
		(width 0.14732)
		(layer "In6.Cu")
		(net "UPI_CPU0_CPU1_P2P2_DN<21>")
	)
	(segment
		(start 249.490738 -352.465132)
		(end 249.290332 -352.264726)
		(width 0.14732)
		(layer "In6.Cu")
		(net "UPI_CPU0_CPU1_P2P2_DN<21>")
	)
	(segment
		(start 259.978906 -339.982556)
		(end 259.400548 -340.560914)
		(width 0.14732)
		(layer "In6.Cu")
		(net "UPI_CPU0_CPU1_P2P2_DN<21>")
	)
	(segment
		(start 98.622866 -306.50815)
		(end 98.642424 -306.491894)
		(width 0.14732)
		(layer "In6.Cu")
		(net "UPI_CPU0_CPU1_P2P2_DN<21>")
	)
	(segment
		(start 315.90869 -310.864758)
		(end 315.76391 -311.009538)
		(width 0.14732)
		(layer "In6.Cu")
		(net "UPI_CPU0_CPU1_P2P2_DN<21>")
	)
	(segment
		(start 240.306098 -359.172256)
		(end 240.230152 -359.601008)
		(width 0.14732)
		(layer "In6.Cu")
		(net "UPI_CPU0_CPU1_P2P2_DN<21>")
	)
	(segment
		(start 313.913266 -310.986932)
		(end 313.552332 -311.0611)
		(width 0.14732)
		(layer "In6.Cu")
		(net "UPI_CPU0_CPU1_P2P2_DN<21>")
	)
	(segment
		(start 110.629192 -278.664416)
		(end 110.623858 -278.661368)
		(width 0.0889)
		(layer "In6.Cu")
		(net "UPI_CPU0_CPU1_P2P2_DN<21>")
	)
	(segment
		(start 264.679684 -337.484466)
		(end 264.471404 -337.484466)
		(width 0.14732)
		(layer "In6.Cu")
		(net "UPI_CPU0_CPU1_P2P2_DN<21>")
	)
	(segment
		(start 242.636548 -359.25252)
		(end 242.152678 -359.59161)
		(width 0.14732)
		(layer "In6.Cu")
		(net "UPI_CPU0_CPU1_P2P2_DN<21>")
	)
	(segment
		(start 334.220566 -287.980628)
		(end 333.93888 -288.42081)
		(width 0.0889)
		(layer "In6.Cu")
		(net "UPI_CPU0_CPU1_P2P2_DN<21>")
	)
	(segment
		(start 261.039356 -339.357462)
		(end 261.818882 -340.136988)
		(width 0.14732)
		(layer "In6.Cu")
		(net "UPI_CPU0_CPU1_P2P2_DN<21>")
	)
	(segment
		(start 240.254282 -360.9213)
		(end 240.049558 -360.885232)
		(width 0.14732)
		(layer "In6.Cu")
		(net "UPI_CPU0_CPU1_P2P2_DN<21>")
	)
	(segment
		(start 110.153196 -276.219158)
		(end 110.142782 -276.213062)
		(width 0.0889)
		(layer "In6.Cu")
		(net "UPI_CPU0_CPU1_P2P2_DN<21>")
	)
	(segment
		(start 261.818882 -340.136988)
		(end 261.818882 -340.345268)
		(width 0.14732)
		(layer "In6.Cu")
		(net "UPI_CPU0_CPU1_P2P2_DN<21>")
	)
	(segment
		(start 265.95578 -334.005682)
		(end 265.95578 -334.441038)
		(width 0.14732)
		(layer "In6.Cu")
		(net "UPI_CPU0_CPU1_P2P2_DN<21>")
	)
	(segment
		(start 257.76174 -342.199722)
		(end 257.76174 -342.635078)
		(width 0.14732)
		(layer "In6.Cu")
		(net "UPI_CPU0_CPU1_P2P2_DN<21>")
	)
	(segment
		(start 74.694034 -330.338938)
		(end 75.345036 -327.986898)
		(width 0.14732)
		(layer "In6.Cu")
		(net "UPI_CPU0_CPU1_P2P2_DN<21>")
	)
	(segment
		(start 105.83672 -292.19906)
		(end 105.794556 -292.156896)
		(width 0.0889)
		(layer "In6.Cu")
		(net "UPI_CPU0_CPU1_P2P2_DN<21>")
	)
	(segment
		(start 261.039356 -338.922106)
		(end 261.039356 -339.357462)
		(width 0.14732)
		(layer "In6.Cu")
		(net "UPI_CPU0_CPU1_P2P2_DN<21>")
	)
	(segment
		(start 301.391828 -320.600578)
		(end 301.391828 -321.444366)
		(width 0.14732)
		(layer "In6.Cu")
		(net "UPI_CPU0_CPU1_P2P2_DN<21>")
	)
	(segment
		(start 249.915426 -351.204276)
		(end 249.915426 -351.639632)
		(width 0.14732)
		(layer "In6.Cu")
		(net "UPI_CPU0_CPU1_P2P2_DN<21>")
	)
	(segment
		(start 253.624842 -348.331028)
		(end 253.624842 -348.539308)
		(width 0.14732)
		(layer "In6.Cu")
		(net "UPI_CPU0_CPU1_P2P2_DN<21>")
	)
	(segment
		(start 257.916172 -344.039698)
		(end 257.136646 -343.260172)
		(width 0.14732)
		(layer "In6.Cu")
		(net "UPI_CPU0_CPU1_P2P2_DN<21>")
	)
	(segment
		(start 252.845316 -347.116146)
		(end 252.845316 -347.551502)
		(width 0.14732)
		(layer "In6.Cu")
		(net "UPI_CPU0_CPU1_P2P2_DN<21>")
	)
	(segment
		(start 262.05307 -338.343748)
		(end 261.617714 -338.343748)
		(width 0.14732)
		(layer "In6.Cu")
		(net "UPI_CPU0_CPU1_P2P2_DN<21>")
	)
	(segment
		(start 248.276618 -352.843084)
		(end 248.276618 -353.27844)
		(width 0.14732)
		(layer "In6.Cu")
		(net "UPI_CPU0_CPU1_P2P2_DN<21>")
	)
	(segment
		(start 109.674406 -281.272742)
		(end 109.683296 -281.267662)
		(width 0.0889)
		(layer "In6.Cu")
		(net "UPI_CPU0_CPU1_P2P2_DN<21>")
	)
	(segment
		(start 107.146598 -289.078416)
		(end 107.146598 -288.902902)
		(width 0.0889)
		(layer "In6.Cu")
		(net "UPI_CPU0_CPU1_P2P2_DN<21>")
	)
	(segment
		(start 107.333796 -286.964882)
		(end 107.345988 -286.95777)
		(width 0.0889)
		(layer "In6.Cu")
		(net "UPI_CPU0_CPU1_P2P2_DN<21>")
	)
	(segment
		(start 199.483726 -367.754408)
		(end 158.968948 -374.897904)
		(width 0.14732)
		(layer "In6.Cu")
		(net "UPI_CPU0_CPU1_P2P2_DN<21>")
	)
	(segment
		(start 260.180074 -341.775796)
		(end 260.180074 -341.984076)
		(width 0.14732)
		(layer "In6.Cu")
		(net "UPI_CPU0_CPU1_P2P2_DN<21>")
	)
	(segment
		(start 258.775454 -341.621364)
		(end 258.340098 -341.621364)
		(width 0.14732)
		(layer "In6.Cu")
		(net "UPI_CPU0_CPU1_P2P2_DN<21>")
	)
	(segment
		(start 253.423674 -346.537788)
		(end 252.845316 -347.116146)
		(width 0.14732)
		(layer "In6.Cu")
		(net "UPI_CPU0_CPU1_P2P2_DN<21>")
	)
	(segment
		(start 248.276618 -353.27844)
		(end 248.477024 -353.478846)
		(width 0.14732)
		(layer "In6.Cu")
		(net "UPI_CPU0_CPU1_P2P2_DN<21>")
	)
	(segment
		(start 105.794556 -291.972492)
		(end 107.61599 -290.151058)
		(width 0.0889)
		(layer "In6.Cu")
		(net "UPI_CPU0_CPU1_P2P2_DN<21>")
	)
	(segment
		(start 244.603778 -356.538022)
		(end 244.91696 -356.985316)
		(width 0.14732)
		(layer "In6.Cu")
		(net "UPI_CPU0_CPU1_P2P2_DN<21>")
	)
	(segment
		(start 75.345036 -327.986898)
		(end 76.46416 -325.621396)
		(width 0.14732)
		(layer "In6.Cu")
		(net "UPI_CPU0_CPU1_P2P2_DN<21>")
	)
	(segment
		(start 267.594588 -332.366874)
		(end 267.594588 -332.80223)
		(width 0.14732)
		(layer "In6.Cu")
		(net "UPI_CPU0_CPU1_P2P2_DN<21>")
	)
	(segment
		(start 334.447896 -286.835596)
		(end 334.44815 -286.83585)
		(width 0.0889)
		(layer "In6.Cu")
		(net "UPI_CPU0_CPU1_P2P2_DN<21>")
	)
	(segment
		(start 243.450364 -356.969822)
		(end 242.204494 -357.842312)
		(width 0.14732)
		(layer "In6.Cu")
		(net "UPI_CPU0_CPU1_P2P2_DN<21>")
	)
	(segment
		(start 109.674406 -282.900628)
		(end 109.683296 -282.895548)
		(width 0.0889)
		(layer "In6.Cu")
		(net "UPI_CPU0_CPU1_P2P2_DN<21>")
	)
	(segment
		(start 228.72954 -367.279428)
		(end 212.758782 -370.095272)
		(width 0.14732)
		(layer "In6.Cu")
		(net "UPI_CPU0_CPU1_P2P2_DN<21>")
	)
	(segment
		(start 251.784866 -348.176596)
		(end 251.206508 -348.754954)
		(width 0.14732)
		(layer "In6.Cu")
		(net "UPI_CPU0_CPU1_P2P2_DN<21>")
	)
	(segment
		(start 249.915426 -351.639632)
		(end 250.115832 -351.840038)
		(width 0.14732)
		(layer "In6.Cu")
		(net "UPI_CPU0_CPU1_P2P2_DN<21>")
	)
	(segment
		(start 105.9815 -295.816528)
		(end 105.83672 -295.671748)
		(width 0.14732)
		(layer "In6.Cu")
		(net "UPI_CPU0_CPU1_P2P2_DN<21>")
	)
	(segment
		(start 287.104074 -323.952108)
		(end 285.045404 -324.804786)
		(width 0.14732)
		(layer "In6.Cu")
		(net "UPI_CPU0_CPU1_P2P2_DN<21>")
	)
	(segment
		(start 253.208028 -348.956122)
		(end 252.999748 -348.956122)
		(width 0.14732)
		(layer "In6.Cu")
		(net "UPI_CPU0_CPU1_P2P2_DN<21>")
	)
	(segment
		(start 266.735306 -335.220564)
		(end 266.735306 -335.428844)
		(width 0.14732)
		(layer "In6.Cu")
		(net "UPI_CPU0_CPU1_P2P2_DN<21>")
	)
	(segment
		(start 315.76391 -311.009538)
		(end 314.500514 -311.009538)
		(width 0.14732)
		(layer "In6.Cu")
		(net "UPI_CPU0_CPU1_P2P2_DN<21>")
	)
	(segment
		(start 264.471404 -337.484466)
		(end 263.691878 -336.70494)
		(width 0.14732)
		(layer "In6.Cu")
		(net "UPI_CPU0_CPU1_P2P2_DN<21>")
	)
	(segment
		(start 265.330686 -335.066132)
		(end 264.89533 -335.066132)
		(width 0.14732)
		(layer "In6.Cu")
		(net "UPI_CPU0_CPU1_P2P2_DN<21>")
	)
	(segment
		(start 263.691878 -336.70494)
		(end 263.256522 -336.70494)
		(width 0.14732)
		(layer "In6.Cu")
		(net "UPI_CPU0_CPU1_P2P2_DN<21>")
	)
	(segment
		(start 309.916068 -312.882534)
		(end 309.29453 -312.882534)
		(width 0.14732)
		(layer "In6.Cu")
		(net "UPI_CPU0_CPU1_P2P2_DN<21>")
	)
	(segment
		(start 107.146598 -287.28924)
		(end 107.146598 -287.280604)
		(width 0.0889)
		(layer "In6.Cu")
		(net "UPI_CPU0_CPU1_P2P2_DN<21>")
	)
	(segment
		(start 264.316972 -335.64449)
		(end 264.316972 -336.079846)
		(width 0.14732)
		(layer "In6.Cu")
		(net "UPI_CPU0_CPU1_P2P2_DN<21>")
	)
	(segment
		(start 333.89697 -288.581846)
		(end 333.89697 -288.982658)
		(width 0.14732)
		(layer "In6.Cu")
		(net "UPI_CPU0_CPU1_P2P2_DN<21>")
	)
	(segment
		(start 105.83672 -295.671748)
		(end 105.83672 -292.221158)
		(width 0.14732)
		(layer "In6.Cu")
		(net "UPI_CPU0_CPU1_P2P2_DN<21>")
	)
	(segment
		(start 244.91696 -356.985316)
		(end 244.880892 -357.189786)
		(width 0.14732)
		(layer "In6.Cu")
		(net "UPI_CPU0_CPU1_P2P2_DN<21>")
	)
	(segment
		(start 306.448714 -313.875928)
		(end 306.166774 -313.875928)
		(width 0.14732)
		(layer "In6.Cu")
		(net "UPI_CPU0_CPU1_P2P2_DN<21>")
	)
	(segment
		(start 250.493784 -350.625918)
		(end 249.915426 -351.204276)
		(width 0.14732)
		(layer "In6.Cu")
		(net "UPI_CPU0_CPU1_P2P2_DN<21>")
	)
	(segment
		(start 244.397022 -357.528876)
		(end 244.192552 -357.492808)
		(width 0.14732)
		(layer "In6.Cu")
		(net "UPI_CPU0_CPU1_P2P2_DN<21>")
	)
	(segment
		(start 110.620048 -279.641808)
		(end 110.622588 -279.640284)
		(width 0.0889)
		(layer "In6.Cu")
		(net "UPI_CPU0_CPU1_P2P2_DN<21>")
	)
	(segment
		(start 105.83672 -292.221158)
		(end 105.83672 -292.19906)
		(width 0.0889)
		(layer "In6.Cu")
		(net "UPI_CPU0_CPU1_P2P2_DN<21>")
	)
	(segment
		(start 257.136646 -343.260172)
		(end 256.70129 -343.260172)
		(width 0.14732)
		(layer "In6.Cu")
		(net "UPI_CPU0_CPU1_P2P2_DN<21>")
	)
	(segment
		(start 261.402068 -340.762082)
		(end 261.193788 -340.762082)
		(width 0.14732)
		(layer "In6.Cu")
		(net "UPI_CPU0_CPU1_P2P2_DN<21>")
	)
	(segment
		(start 259.400548 -340.99627)
		(end 260.180074 -341.775796)
		(width 0.14732)
		(layer "In6.Cu")
		(net "UPI_CPU0_CPU1_P2P2_DN<21>")
	)
	(segment
		(start 110.165388 -276.22627)
		(end 110.157006 -276.221444)
		(width 0.0889)
		(layer "In6.Cu")
		(net "UPI_CPU0_CPU1_P2P2_DN<21>")
	)
	(segment
		(start 312.973974 -311.328054)
		(end 312.803032 -311.215532)
		(width 0.14732)
		(layer "In6.Cu")
		(net "UPI_CPU0_CPU1_P2P2_DN<21>")
	)
	(segment
		(start 268.374114 -333.581756)
		(end 268.374114 -333.790036)
		(width 0.14732)
		(layer "In6.Cu")
		(net "UPI_CPU0_CPU1_P2P2_DN<21>")
	)
	(segment
		(start 312.803032 -311.215532)
		(end 312.442098 -311.289954)
		(width 0.14732)
		(layer "In6.Cu")
		(net "UPI_CPU0_CPU1_P2P2_DN<21>")
	)
	(segment
		(start 301.391828 -319.942718)
		(end 301.247048 -320.087498)
		(width 0.14732)
		(layer "In6.Cu")
		(net "UPI_CPU0_CPU1_P2P2_DN<21>")
	)
	(segment
		(start 263.45769 -338.70646)
		(end 263.040876 -339.123274)
		(width 0.14732)
		(layer "In6.Cu")
		(net "UPI_CPU0_CPU1_P2P2_DN<21>")
	)
	(segment
		(start 106.855006 -287.783778)
		(end 106.870246 -287.774888)
		(width 0.0889)
		(layer "In6.Cu")
		(net "UPI_CPU0_CPU1_P2P2_DN<21>")
	)
	(segment
		(start 261.193788 -340.762082)
		(end 260.414262 -339.982556)
		(width 0.14732)
		(layer "In6.Cu")
		(net "UPI_CPU0_CPU1_P2P2_DN<21>")
	)
	(segment
		(start 254.846836 -347.317314)
		(end 254.638556 -347.317314)
		(width 0.14732)
		(layer "In6.Cu")
		(net "UPI_CPU0_CPU1_P2P2_DN<21>")
	)
	(segment
		(start 262.832596 -339.123274)
		(end 262.05307 -338.343748)
		(width 0.14732)
		(layer "In6.Cu")
		(net "UPI_CPU0_CPU1_P2P2_DN<21>")
	)
	(segment
		(start 110.435644 -278.336502)
		(end 110.43539 -278.336502)
		(width 0.0889)
		(layer "In6.Cu")
		(net "UPI_CPU0_CPU1_P2P2_DN<21>")
	)
	(segment
		(start 250.115832 -351.840038)
		(end 250.115832 -352.048318)
		(width 0.14732)
		(layer "In6.Cu")
		(net "UPI_CPU0_CPU1_P2P2_DN<21>")
	)
	(segment
		(start 109.495844 -283.229812)
		(end 109.495844 -283.219906)
		(width 0.0889)
		(layer "In6.Cu")
		(net "UPI_CPU0_CPU1_P2P2_DN<21>")
	)
	(segment
		(start 269.387828 -332.568042)
		(end 268.608302 -331.788516)
		(width 0.14732)
		(layer "In6.Cu")
		(net "UPI_CPU0_CPU1_P2P2_DN<21>")
	)
	(segment
		(start 268.608302 -331.788516)
		(end 268.172946 -331.788516)
		(width 0.14732)
		(layer "In6.Cu")
		(net "UPI_CPU0_CPU1_P2P2_DN<21>")
	)
	(segment
		(start 306.166774 -313.875928)
		(end 304.474372 -315.253878)
		(width 0.14732)
		(layer "In6.Cu")
		(net "UPI_CPU0_CPU1_P2P2_DN<21>")
	)
	(segment
		(start 260.180074 -341.984076)
		(end 259.76326 -342.40089)
		(width 0.14732)
		(layer "In6.Cu")
		(net "UPI_CPU0_CPU1_P2P2_DN<21>")
	)
	(segment
		(start 244.192552 -357.492808)
		(end 243.87937 -357.045768)
		(width 0.14732)
		(layer "In6.Cu")
		(net "UPI_CPU0_CPU1_P2P2_DN<21>")
	)
	(segment
		(start 108.086398 -285.675578)
		(end 108.086398 -285.661354)
		(width 0.0889)
		(layer "In6.Cu")
		(net "UPI_CPU0_CPU1_P2P2_DN<21>")
	)
	(segment
		(start 301.391828 -321.444366)
		(end 300.331378 -322.504816)
		(width 0.14732)
		(layer "In6.Cu")
		(net "UPI_CPU0_CPU1_P2P2_DN<21>")
	)
	(segment
		(start 304.474372 -315.253878)
		(end 304.077624 -315.453776)
		(width 0.14732)
		(layer "In6.Cu")
		(net "UPI_CPU0_CPU1_P2P2_DN<21>")
	)
	(segment
		(start 307.442108 -312.882534)
		(end 306.448714 -313.875928)
		(width 0.14732)
		(layer "In6.Cu")
		(net "UPI_CPU0_CPU1_P2P2_DN<21>")
	)
	(segment
		(start 314.494926 -311.015126)
		(end 314.084208 -311.099454)
		(width 0.14732)
		(layer "In6.Cu")
		(net "UPI_CPU0_CPU1_P2P2_DN<21>")
	)
	(segment
		(start 333.93888 -288.42081)
		(end 333.93888 -288.517838)
		(width 0.0889)
		(layer "In6.Cu")
		(net "UPI_CPU0_CPU1_P2P2_DN<21>")
	)
	(segment
		(start 256.902458 -345.053412)
		(end 256.902458 -345.261692)
		(width 0.14732)
		(layer "In6.Cu")
		(net "UPI_CPU0_CPU1_P2P2_DN<21>")
	)
	(segment
		(start 105.9815 -296.184828)
		(end 105.9815 -295.816528)
		(width 0.14732)
		(layer "In6.Cu")
		(net "UPI_CPU0_CPU1_P2P2_DN<21>")
	)
	(segment
		(start 256.122932 -344.273886)
		(end 256.902458 -345.053412)
		(width 0.14732)
		(layer "In6.Cu")
		(net "UPI_CPU0_CPU1_P2P2_DN<21>")
	)
	(segment
		(start 300.331378 -322.504816)
		(end 298.01312 -323.46519)
		(width 0.14732)
		(layer "In6.Cu")
		(net "UPI_CPU0_CPU1_P2P2_DN<21>")
	)
	(segment
		(start 285.045404 -324.804786)
		(end 279.058116 -324.804786)
		(width 0.14732)
		(layer "In6.Cu")
		(net "UPI_CPU0_CPU1_P2P2_DN<21>")
	)
	(segment
		(start 253.624842 -348.539308)
		(end 253.208028 -348.956122)
		(width 0.14732)
		(layer "In6.Cu")
		(net "UPI_CPU0_CPU1_P2P2_DN<21>")
	)
	(segment
		(start 309.14975 -312.737754)
		(end 308.78145 -312.737754)
		(width 0.14732)
		(layer "In6.Cu")
		(net "UPI_CPU0_CPU1_P2P2_DN<21>")
	)
	(segment
		(start 241.40414 -358.779064)
		(end 240.975388 -358.703118)
		(width 0.14732)
		(layer "In6.Cu")
		(net "UPI_CPU0_CPU1_P2P2_DN<21>")
	)
	(segment
		(start 110.435898 -279.971754)
		(end 110.435898 -279.964134)
		(width 0.0889)
		(layer "In6.Cu")
		(net "UPI_CPU0_CPU1_P2P2_DN<21>")
	)
	(segment
		(start 110.623858 -278.661368)
		(end 110.623096 -278.66086)
		(width 0.0889)
		(layer "In6.Cu")
		(net "UPI_CPU0_CPU1_P2P2_DN<21>")
	)
	(segment
		(start 328.881994 -299.181012)
		(end 317.053722 -311.009538)
		(width 0.14732)
		(layer "In6.Cu")
		(net "UPI_CPU0_CPU1_P2P2_DN<21>")
	)
	(segment
		(start 107.616244 -289.610038)
		(end 107.616244 -289.60953)
		(width 0.0889)
		(layer "In6.Cu")
		(net "UPI_CPU0_CPU1_P2P2_DN<21>")
	)
	(segment
		(start 260.414262 -339.982556)
		(end 259.978906 -339.982556)
		(width 0.14732)
		(layer "In6.Cu")
		(net "UPI_CPU0_CPU1_P2P2_DN<21>")
	)
	(segment
		(start 265.096498 -336.859372)
		(end 265.096498 -337.067652)
		(width 0.14732)
		(layer "In6.Cu")
		(net "UPI_CPU0_CPU1_P2P2_DN<21>")
	)
	(segment
		(start 98.622866 -306.507896)
		(end 98.622866 -306.50815)
		(width 0.14732)
		(layer "In6.Cu")
		(net "UPI_CPU0_CPU1_P2P2_DN<21>")
	)
	(segment
		(start 109.243876 -276.165818)
		(end 109.40034 -275.8948)
		(width 0.0889)
		(layer "In6.Cu")
		(net "UPI_CPU0_CPU1_P2P2_DN<21>")
	)
	(segment
		(start 333.89697 -288.559748)
		(end 333.89697 -288.581846)
		(width 0.0889)
		(layer "In6.Cu")
		(net "UPI_CPU0_CPU1_P2P2_DN<21>")
	)
	(segment
		(start 266.969494 -333.427324)
		(end 266.534138 -333.427324)
		(width 0.14732)
		(layer "In6.Cu")
		(net "UPI_CPU0_CPU1_P2P2_DN<21>")
	)
	(segment
		(start 76.46416 -325.621396)
		(end 81.654904 -320.430652)
		(width 0.14732)
		(layer "In6.Cu")
		(net "UPI_CPU0_CPU1_P2P2_DN<21>")
	)
	(segment
		(start 302.138588 -316.366652)
		(end 301.666148 -316.839092)
		(width 0.14732)
		(layer "In6.Cu")
		(net "UPI_CPU0_CPU1_P2P2_DN<21>")
	)
	(segment
		(start 262.678164 -337.283298)
		(end 262.678164 -337.718654)
		(width 0.14732)
		(layer "In6.Cu")
		(net "UPI_CPU0_CPU1_P2P2_DN<21>")
	)
	(segment
		(start 248.854976 -352.264726)
		(end 248.276618 -352.843084)
		(width 0.14732)
		(layer "In6.Cu")
		(net "UPI_CPU0_CPU1_P2P2_DN<21>")
	)
	(segment
		(start 248.477024 -353.687126)
		(end 247.869202 -354.294948)
		(width 0.14732)
		(layer "In6.Cu")
		(net "UPI_CPU0_CPU1_P2P2_DN<21>")
	)
	(segment
		(start 263.45769 -338.49818)
		(end 263.45769 -338.70646)
		(width 0.14732)
		(layer "In6.Cu")
		(net "UPI_CPU0_CPU1_P2P2_DN<21>")
	)
	(segment
		(start 110.618778 -277.030688)
		(end 110.61446 -277.027894)
		(width 0.0889)
		(layer "In6.Cu")
		(net "UPI_CPU0_CPU1_P2P2_DN<21>")
	)
	(segment
		(start 110.623096 -278.66086)
		(end 110.621572 -278.660098)
		(width 0.0889)
		(layer "In6.Cu")
		(net "UPI_CPU0_CPU1_P2P2_DN<21>")
	)
	(segment
		(start 109.026198 -284.033722)
		(end 109.026198 -284.025086)
		(width 0.0889)
		(layer "In6.Cu")
		(net "UPI_CPU0_CPU1_P2P2_DN<21>")
	)
	(segment
		(start 252.220222 -348.176596)
		(end 251.784866 -348.176596)
		(width 0.14732)
		(layer "In6.Cu")
		(net "UPI_CPU0_CPU1_P2P2_DN<21>")
	)
	(segment
		(start 248.477024 -353.478846)
		(end 248.477024 -353.687126)
		(width 0.14732)
		(layer "In6.Cu")
		(net "UPI_CPU0_CPU1_P2P2_DN<21>")
	)
	(segment
		(start 110.157006 -276.221444)
		(end 110.153196 -276.219158)
		(width 0.0889)
		(layer "In6.Cu")
		(net "UPI_CPU0_CPU1_P2P2_DN<21>")
	)
	(segment
		(start 312.329576 -311.46115)
		(end 311.080404 -311.718198)
		(width 0.14732)
		(layer "In6.Cu")
		(net "UPI_CPU0_CPU1_P2P2_DN<21>")
	)
	(segment
		(start 251.986034 -350.178116)
		(end 251.337826 -350.826324)
		(width 0.14732)
		(layer "In6.Cu")
		(net "UPI_CPU0_CPU1_P2P2_DN<21>")
	)
	(segment
		(start 261.617714 -338.343748)
		(end 261.039356 -338.922106)
		(width 0.14732)
		(layer "In6.Cu")
		(net "UPI_CPU0_CPU1_P2P2_DN<21>")
	)
	(segment
		(start 253.85903 -346.537788)
		(end 253.423674 -346.537788)
		(width 0.14732)
		(layer "In6.Cu")
		(net "UPI_CPU0_CPU1_P2P2_DN<21>")
	)
	(segment
		(start 244.679724 -356.109016)
		(end 244.603778 -356.538022)
		(width 0.14732)
		(layer "In6.Cu")
		(net "UPI_CPU0_CPU1_P2P2_DN<21>")
	)
	(segment
		(start 256.485644 -345.678506)
		(end 256.277364 -345.678506)
		(width 0.14732)
		(layer "In6.Cu")
		(net "UPI_CPU0_CPU1_P2P2_DN<21>")
	)
	(segment
		(start 251.337826 -350.826324)
		(end 251.129546 -350.826324)
		(width 0.14732)
		(layer "In6.Cu")
		(net "UPI_CPU0_CPU1_P2P2_DN<21>")
	)
	(segment
		(start 304.077624 -315.453776)
		(end 303.164748 -316.366652)
		(width 0.14732)
		(layer "In6.Cu")
		(net "UPI_CPU0_CPU1_P2P2_DN<21>")
	)
	(segment
		(start 247.869202 -354.294948)
		(end 247.270016 -354.294948)
		(width 0.14732)
		(layer "In6.Cu")
		(net "UPI_CPU0_CPU1_P2P2_DN<21>")
	)
	(segment
		(start 267.74902 -334.20685)
		(end 266.969494 -333.427324)
		(width 0.14732)
		(layer "In6.Cu")
		(net "UPI_CPU0_CPU1_P2P2_DN<21>")
	)
	(segment
		(start 309.29453 -312.882534)
		(end 309.14975 -312.737754)
		(width 0.14732)
		(layer "In6.Cu")
		(net "UPI_CPU0_CPU1_P2P2_DN<21>")
	)
	(segment
		(start 255.26365 -346.69222)
		(end 255.26365 -346.9005)
		(width 0.14732)
		(layer "In6.Cu")
		(net "UPI_CPU0_CPU1_P2P2_DN<21>")
	)
	(segment
		(start 256.70129 -343.260172)
		(end 256.122932 -343.83853)
		(width 0.14732)
		(layer "In6.Cu")
		(net "UPI_CPU0_CPU1_P2P2_DN<21>")
	)
	(segment
		(start 265.95578 -334.441038)
		(end 266.735306 -335.220564)
		(width 0.14732)
		(layer "In6.Cu")
		(net "UPI_CPU0_CPU1_P2P2_DN<21>")
	)
	(segment
		(start 316.42177 -311.009538)
		(end 316.27699 -310.864758)
		(width 0.14732)
		(layer "In6.Cu")
		(net "UPI_CPU0_CPU1_P2P2_DN<21>")
	)
	(segment
		(start 333.93888 -288.517838)
		(end 333.89697 -288.559748)
		(width 0.0889)
		(layer "In6.Cu")
		(net "UPI_CPU0_CPU1_P2P2_DN<21>")
	)
	(segment
		(start 109.683296 -281.916378)
		(end 109.674406 -281.911298)
		(width 0.0889)
		(layer "In6.Cu")
		(net "UPI_CPU0_CPU1_P2P2_DN<21>")
	)
	(segment
		(start 98.642424 -306.491894)
		(end 103.897176 -300.247812)
		(width 0.14732)
		(layer "In6.Cu")
		(net "UPI_CPU0_CPU1_P2P2_DN<21>")
	)
	(segment
		(start 105.709974 -297.804332)
		(end 105.83672 -297.4975)
		(width 0.14732)
		(layer "In6.Cu")
		(net "UPI_CPU0_CPU1_P2P2_DN<21>")
	)
	(segment
		(start 110.905798 -279.150572)
		(end 110.905798 -279.150318)
		(width 0.0889)
		(layer "In6.Cu")
		(net "UPI_CPU0_CPU1_P2P2_DN<21>")
	)
	(segment
		(start 265.096498 -337.067652)
		(end 264.679684 -337.484466)
		(width 0.14732)
		(layer "In6.Cu")
		(net "UPI_CPU0_CPU1_P2P2_DN<21>")
	)
	(segment
		(start 301.247048 -320.087498)
		(end 301.247048 -320.455798)
		(width 0.14732)
		(layer "In6.Cu")
		(net "UPI_CPU0_CPU1_P2P2_DN<21>")
	)
	(segment
		(start 256.122932 -343.83853)
		(end 256.122932 -344.273886)
		(width 0.14732)
		(layer "In6.Cu")
		(net "UPI_CPU0_CPU1_P2P2_DN<21>")
	)
	(segment
		(start 332.300072 -290.579556)
		(end 330.819506 -292.794944)
		(width 0.14732)
		(layer "In6.Cu")
		(net "UPI_CPU0_CPU1_P2P2_DN<21>")
	)
	(segment
		(start 296.83837 -323.952108)
		(end 287.104074 -323.952108)
		(width 0.14732)
		(layer "In6.Cu")
		(net "UPI_CPU0_CPU1_P2P2_DN<21>")
	)
	(segment
		(start 255.062482 -344.89898)
		(end 254.484124 -345.477338)
		(width 0.14732)
		(layer "In6.Cu")
		(net "UPI_CPU0_CPU1_P2P2_DN<21>")
	)
	(segment
		(start 249.699018 -352.465132)
		(end 249.490738 -352.465132)
		(width 0.14732)
		(layer "In6.Cu")
		(net "UPI_CPU0_CPU1_P2P2_DN<21>")
	)
	(segment
		(start 106.870246 -287.774888)
		(end 106.869992 -287.775142)
		(width 0.0889)
		(layer "In6.Cu")
		(net "UPI_CPU0_CPU1_P2P2_DN<21>")
	)
	(segment
		(start 105.83672 -297.4975)
		(end 105.83672 -296.329608)
		(width 0.14732)
		(layer "In6.Cu")
		(net "UPI_CPU0_CPU1_P2P2_DN<21>")
	)
	(segment
		(start 254.484124 -345.477338)
		(end 254.484124 -345.912694)
		(width 0.14732)
		(layer "In6.Cu")
		(net "UPI_CPU0_CPU1_P2P2_DN<21>")
	)
	(segment
		(start 240.975388 -358.703118)
		(end 240.306098 -359.172256)
		(width 0.14732)
		(layer "In6.Cu")
		(net "UPI_CPU0_CPU1_P2P2_DN<21>")
	)
	(segment
		(start 268.172946 -331.788516)
		(end 267.594588 -332.366874)
		(width 0.14732)
		(layer "In6.Cu")
		(net "UPI_CPU0_CPU1_P2P2_DN<21>")
	)
	(segment
		(start 334.472026 -286.746442)
		(end 334.447896 -286.835596)
		(width 0.0889)
		(layer "In6.Cu")
		(net "UPI_CPU0_CPU1_P2P2_DN<21>")
	)
	(segment
		(start 158.968948 -374.897904)
		(end 126.196852 -374.897904)
		(width 0.14732)
		(layer "In6.Cu")
		(net "UPI_CPU0_CPU1_P2P2_DN<21>")
	)
	(segment
		(start 317.053722 -311.009538)
		(end 316.42177 -311.009538)
		(width 0.14732)
		(layer "In6.Cu")
		(net "UPI_CPU0_CPU1_P2P2_DN<21>")
	)
	(segment
		(start 301.666148 -317.535052)
		(end 301.391828 -318.985138)
		(width 0.14732)
		(layer "In6.Cu")
		(net "UPI_CPU0_CPU1_P2P2_DN<21>")
	)
	(segment
		(start 74.212958 -335.22158)
		(end 74.694034 -330.338938)
		(width 0.14732)
		(layer "In6.Cu")
		(net "UPI_CPU0_CPU1_P2P2_DN<21>")
	)
	(segment
		(start 109.264958 -276.243796)
		(end 109.243876 -276.165818)
		(width 0.0889)
		(layer "In6.Cu")
		(net "UPI_CPU0_CPU1_P2P2_DN<21>")
	)
	(segment
		(start 110.621572 -278.660098)
		(end 110.614206 -278.65578)
		(width 0.0889)
		(layer "In6.Cu")
		(net "UPI_CPU0_CPU1_P2P2_DN<21>")
	)
	(segment
		(start 297.405044 -323.717412)
		(end 296.83837 -323.952108)
		(width 0.14732)
		(layer "In6.Cu")
		(net "UPI_CPU0_CPU1_P2P2_DN<21>")
	)
	(segment
		(start 334.315562 -286.475424)
		(end 334.472026 -286.746442)
		(width 0.0889)
		(layer "In6.Cu")
		(net "UPI_CPU0_CPU1_P2P2_DN<21>")
	)
	(segment
		(start 212.758782 -370.095272)
		(end 199.483726 -367.754408)
		(width 0.14732)
		(layer "In6.Cu")
		(net "UPI_CPU0_CPU1_P2P2_DN<21>")
	)
	(segment
		(start 108.743496 -284.52318)
		(end 108.749592 -284.519624)
		(width 0.0889)
		(layer "In6.Cu")
		(net "UPI_CPU0_CPU1_P2P2_DN<21>")
	)
	(segment
		(start 250.92914 -350.625918)
		(end 250.493784 -350.625918)
		(width 0.14732)
		(layer "In6.Cu")
		(net "UPI_CPU0_CPU1_P2P2_DN<21>")
	)
	(segment
		(start 264.89533 -335.066132)
		(end 264.316972 -335.64449)
		(width 0.14732)
		(layer "In6.Cu")
		(net "UPI_CPU0_CPU1_P2P2_DN<21>")
	)
	(segment
		(start 109.965744 -280.78811)
		(end 109.965744 -280.778204)
		(width 0.0889)
		(layer "In6.Cu")
		(net "UPI_CPU0_CPU1_P2P2_DN<21>")
	)
	(segment
		(start 244.880892 -357.189786)
		(end 244.397022 -357.528876)
		(width 0.14732)
		(layer "In6.Cu")
		(net "UPI_CPU0_CPU1_P2P2_DN<21>")
	)
	(segment
		(start 270.939514 -326.498712)
		(end 270.939514 -331.224636)
		(width 0.14732)
		(layer "In6.Cu")
		(net "UPI_CPU0_CPU1_P2P2_DN<21>")
	)
	(segment
		(start 81.654904 -320.430652)
		(end 98.622866 -306.507896)
		(width 0.14732)
		(layer "In6.Cu")
		(net "UPI_CPU0_CPU1_P2P2_DN<21>")
	)
	(segment
		(start 105.83672 -296.329608)
		(end 105.9815 -296.184828)
		(width 0.14732)
		(layer "In6.Cu")
		(net "UPI_CPU0_CPU1_P2P2_DN<21>")
	)
	(segment
		(start 110.630716 -278.007064)
		(end 110.635796 -278.004016)
		(width 0.0889)
		(layer "In6.Cu")
		(net "UPI_CPU0_CPU1_P2P2_DN<21>")
	)
	(segment
		(start 252.845316 -347.551502)
		(end 253.624842 -348.331028)
		(width 0.14732)
		(layer "In6.Cu")
		(net "UPI_CPU0_CPU1_P2P2_DN<21>")
	)
	(segment
		(start 258.541266 -343.622884)
		(end 258.124452 -344.039698)
		(width 0.14732)
		(layer "In6.Cu")
		(net "UPI_CPU0_CPU1_P2P2_DN<21>")
	)
	(segment
		(start 108.26496 -285.342076)
		(end 108.27385 -285.336996)
		(width 0.0889)
		(layer "In6.Cu")
		(net "UPI_CPU0_CPU1_P2P2_DN<21>")
	)
	(segment
		(start 74.212958 -351.596198)
		(end 74.212958 -335.22158)
		(width 0.14732)
		(layer "In6.Cu")
		(net "UPI_CPU0_CPU1_P2P2_DN<21>")
	)
	(segment
		(start 316.27699 -310.864758)
		(end 315.90869 -310.864758)
		(width 0.14732)
		(layer "In6.Cu")
		(net "UPI_CPU0_CPU1_P2P2_DN<21>")
	)
	(segment
		(start 249.290332 -352.264726)
		(end 248.854976 -352.264726)
		(width 0.14732)
		(layer "In6.Cu")
		(net "UPI_CPU0_CPU1_P2P2_DN<21>")
	)
	(segment
		(start 110.621826 -278.012144)
		(end 110.630716 -278.007064)
		(width 0.0889)
		(layer "In6.Cu")
		(net "UPI_CPU0_CPU1_P2P2_DN<21>")
	)
	(segment
		(start 272.170144 -325.268082)
		(end 270.939514 -326.498712)
		(width 0.14732)
		(layer "In6.Cu")
		(net "UPI_CPU0_CPU1_P2P2_DN<21>")
	)
	(segment
		(start 110.61446 -279.644856)
		(end 110.620048 -279.641808)
		(width 0.0889)
		(layer "In6.Cu")
		(net "UPI_CPU0_CPU1_P2P2_DN<21>")
	)
	(segment
		(start 303.164748 -316.366652)
		(end 302.138588 -316.366652)
		(width 0.14732)
		(layer "In6.Cu")
		(net "UPI_CPU0_CPU1_P2P2_DN<21>")
	)
	(segment
		(start 242.204494 -357.842312)
		(end 242.128548 -358.271318)
		(width 0.14732)
		(layer "In6.Cu")
		(net "UPI_CPU0_CPU1_P2P2_DN<21>")
	)
	(segment
		(start 313.552332 -311.0611)
		(end 313.439556 -311.232296)
		(width 0.14732)
		(layer "In6.Cu")
		(net "UPI_CPU0_CPU1_P2P2_DN<21>")
	)
	(segment
		(start 107.61599 -289.610292)
		(end 107.616244 -289.610038)
		(width 0.0889)
		(layer "In6.Cu")
		(net "UPI_CPU0_CPU1_P2P2_DN<21>")
	)
	(segment
		(start 240.049558 -360.885232)
		(end 239.505744 -360.108754)
		(width 0.14732)
		(layer "In6.Cu")
		(net "UPI_CPU0_CPU1_P2P2_DN<21>")
	)
	(segment
		(start 258.541266 -343.414604)
		(end 258.541266 -343.622884)
		(width 0.14732)
		(layer "In6.Cu")
		(net "UPI_CPU0_CPU1_P2P2_DN<21>")
	)
	(segment
		(start 298.01312 -323.46519)
		(end 297.82389 -323.386958)
		(width 0.14732)
		(layer "In6.Cu")
		(net "UPI_CPU0_CPU1_P2P2_DN<21>")
	)
	(segment
		(start 110.633256 -277.039324)
		(end 110.618778 -277.030688)
		(width 0.0889)
		(layer "In6.Cu")
		(net "UPI_CPU0_CPU1_P2P2_DN<21>")
	)
	(segment
		(start 267.594588 -332.80223)
		(end 268.374114 -333.581756)
		(width 0.14732)
		(layer "In6.Cu")
		(net "UPI_CPU0_CPU1_P2P2_DN<21>")
	)
	(segment
		(start 314.084208 -311.099454)
		(end 313.913266 -310.986932)
		(width 0.14732)
		(layer "In6.Cu")
		(net "UPI_CPU0_CPU1_P2P2_DN<21>")
	)
	(segment
		(start 334.220566 -287.288986)
		(end 334.220566 -287.980628)
		(width 0.0889)
		(layer "In6.Cu")
		(net "UPI_CPU0_CPU1_P2P2_DN<21>")
	)
	(segment
		(start 110.622588 -279.640284)
		(end 110.62335 -279.639776)
		(width 0.0889)
		(layer "In6.Cu")
		(net "UPI_CPU0_CPU1_P2P2_DN<21>")
	)
	(segment
		(start 110.144306 -280.458926)
		(end 110.153196 -280.453846)
		(width 0.0889)
		(layer "In6.Cu")
		(net "UPI_CPU0_CPU1_P2P2_DN<21>")
	)
	(segment
		(start 108.556298 -284.857444)
		(end 108.556298 -284.838902)
		(width 0.0889)
		(layer "In6.Cu")
		(net "UPI_CPU0_CPU1_P2P2_DN<21>")
	)
	(segment
		(start 279.058116 -324.804786)
		(end 278.59482 -325.268082)
		(width 0.14732)
		(layer "In6.Cu")
		(net "UPI_CPU0_CPU1_P2P2_DN<21>")
	)
	(segment
		(start 240.230152 -359.601008)
		(end 240.77422 -360.37774)
		(width 0.14732)
		(layer "In6.Cu")
		(net "UPI_CPU0_CPU1_P2P2_DN<21>")
	)
	(segment
		(start 107.79506 -286.156146)
		(end 107.80395 -286.151066)
		(width 0.0889)
		(layer "In6.Cu")
		(net "UPI_CPU0_CPU1_P2P2_DN<21>")
	)
	(segment
		(start 110.43539 -278.336502)
		(end 110.43539 -278.321516)
		(width 0.0889)
		(layer "In6.Cu")
		(net "UPI_CPU0_CPU1_P2P2_DN<21>")
	)
	(segment
		(start 314.500514 -311.009538)
		(end 314.494926 -311.015126)
		(width 0.14732)
		(layer "In6.Cu")
		(net "UPI_CPU0_CPU1_P2P2_DN<21>")
	)
	(segment
		(start 301.666148 -316.839092)
		(end 301.666148 -317.535052)
		(width 0.14732)
		(layer "In6.Cu")
		(net "UPI_CPU0_CPU1_P2P2_DN<21>")
	)
	(segment
		(start 266.318492 -335.845658)
		(end 266.110212 -335.845658)
		(width 0.14732)
		(layer "In6.Cu")
		(net "UPI_CPU0_CPU1_P2P2_DN<21>")
	)
	(segment
		(start 251.206508 -349.19031)
		(end 251.986034 -349.969836)
		(width 0.14732)
		(layer "In6.Cu")
		(net "UPI_CPU0_CPU1_P2P2_DN<21>")
	)
	(segment
		(start 100.570792 -371.09654)
		(end 81.124806 -363.04093)
		(width 0.14732)
		(layer "In6.Cu")
		(net "UPI_CPU0_CPU1_P2P2_DN<21>")
	)
	(segment
		(start 77.424788 -359.341166)
		(end 74.212958 -351.596198)
		(width 0.14732)
		(layer "In6.Cu")
		(net "UPI_CPU0_CPU1_P2P2_DN<21>")
	)
	(segment
		(start 269.596108 -332.568042)
		(end 269.387828 -332.568042)
		(width 0.14732)
		(layer "In6.Cu")
		(net "UPI_CPU0_CPU1_P2P2_DN<21>")
	)
	(segment
		(start 242.672616 -359.04805)
		(end 242.636548 -359.25252)
		(width 0.14732)
		(layer "In6.Cu")
		(net "UPI_CPU0_CPU1_P2P2_DN<21>")
	)
	(segment
		(start 259.400548 -340.560914)
		(end 259.400548 -340.99627)
		(width 0.14732)
		(layer "In6.Cu")
		(net "UPI_CPU0_CPU1_P2P2_DN<21>")
	)
	(segment
		(start 243.87937 -357.045768)
		(end 243.450364 -356.969822)
		(width 0.14732)
		(layer "In6.Cu")
		(net "UPI_CPU0_CPU1_P2P2_DN<21>")
	)
	(segment
		(start 242.152678 -359.59161)
		(end 241.947954 -359.555542)
		(width 0.14732)
		(layer "In6.Cu")
		(net "UPI_CPU0_CPU1_P2P2_DN<21>")
	)
	(segment
		(start 239.076738 -360.032808)
		(end 228.72954 -367.279428)
		(width 0.14732)
		(layer "In6.Cu")
		(net "UPI_CPU0_CPU1_P2P2_DN<21>")
	)
	(segment
		(start 251.129546 -350.826324)
		(end 250.92914 -350.625918)
		(width 0.14732)
		(layer "In6.Cu")
		(net "UPI_CPU0_CPU1_P2P2_DN<21>")
	)
	(segment
		(start 333.89697 -288.982658)
		(end 332.300072 -290.579556)
		(width 0.14732)
		(layer "In6.Cu")
		(net "UPI_CPU0_CPU1_P2P2_DN<21>")
	)
	(segment
		(start 264.316972 -336.079846)
		(end 265.096498 -336.859372)
		(width 0.14732)
		(layer "In6.Cu")
		(net "UPI_CPU0_CPU1_P2P2_DN<21>")
	)
	(segment
		(start 250.115832 -352.048318)
		(end 249.699018 -352.465132)
		(width 0.14732)
		(layer "In6.Cu")
		(net "UPI_CPU0_CPU1_P2P2_DN<21>")
	)
	(segment
		(start 263.256522 -336.70494)
		(end 262.678164 -337.283298)
		(width 0.14732)
		(layer "In6.Cu")
		(net "UPI_CPU0_CPU1_P2P2_DN<21>")
	)
	(segment
		(start 266.110212 -335.845658)
		(end 265.330686 -335.066132)
		(width 0.14732)
		(layer "In6.Cu")
		(net "UPI_CPU0_CPU1_P2P2_DN<21>")
	)
	(segment
		(start 330.819506 -292.794944)
		(end 328.881994 -299.181012)
		(width 0.14732)
		(layer "In6.Cu")
		(net "UPI_CPU0_CPU1_P2P2_DN<21>")
	)
	(segment
		(start 255.26365 -346.9005)
		(end 254.846836 -347.317314)
		(width 0.14732)
		(layer "In6.Cu")
		(net "UPI_CPU0_CPU1_P2P2_DN<21>")
	)
	(segment
		(start 254.484124 -345.912694)
		(end 255.26365 -346.69222)
		(width 0.14732)
		(layer "In6.Cu")
		(net "UPI_CPU0_CPU1_P2P2_DN<21>")
	)
	(segment
		(start 266.534138 -333.427324)
		(end 265.95578 -334.005682)
		(width 0.14732)
		(layer "In6.Cu")
		(net "UPI_CPU0_CPU1_P2P2_DN<21>")
	)
	(segment
		(start 81.124806 -363.04093)
		(end 77.424788 -359.341166)
		(width 0.14732)
		(layer "In6.Cu")
		(net "UPI_CPU0_CPU1_P2P2_DN<21>")
	)
	(segment
		(start 240.77422 -360.37774)
		(end 240.738152 -360.58221)
		(width 0.14732)
		(layer "In6.Cu")
		(net "UPI_CPU0_CPU1_P2P2_DN<21>")
	)
	(segment
		(start 263.040876 -339.123274)
		(end 262.832596 -339.123274)
		(width 0.14732)
		(layer "In6.Cu")
		(net "UPI_CPU0_CPU1_P2P2_DN<21>")
	)
	(segment
		(start 297.48353 -323.527928)
		(end 297.405044 -323.717412)
		(width 0.14732)
		(layer "In6.Cu")
		(net "UPI_CPU0_CPU1_P2P2_DN<21>")
	)
	(segment
		(start 251.206508 -348.754954)
		(end 251.206508 -349.19031)
		(width 0.14732)
		(layer "In6.Cu")
		(net "UPI_CPU0_CPU1_P2P2_DN<21>")
	)
	(segment
		(start 240.738152 -360.58221)
		(end 240.254282 -360.9213)
		(width 0.14732)
		(layer "In6.Cu")
		(net "UPI_CPU0_CPU1_P2P2_DN<21>")
	)
	(segment
		(start 105.794556 -292.156896)
		(end 105.794556 -291.972492)
		(width 0.0889)
		(layer "In6.Cu")
		(net "UPI_CPU0_CPU1_P2P2_DN<21>")
	)
	(arc
		(start 109.683296 -281.267662)
		(mid 109.887631 -281.065057)
		(end 109.965744 -280.78811)
		(width 0.0889)
		(layer "In6.Cu")
		(net "UPI_CPU0_CPU1_P2P2_DN<21>")
	)
	(arc
		(start 109.587538 -276.219158)
		(mid 109.42905 -276.268091)
		(end 109.264958 -276.243796)
		(width 0.0889)
		(layer "In6.Cu")
		(net "UPI_CPU0_CPU1_P2P2_DN<21>")
	)
	(arc
		(start 108.27385 -285.336996)
		(mid 108.478185 -285.134391)
		(end 108.556298 -284.857444)
		(width 0.0889)
		(layer "In6.Cu")
		(net "UPI_CPU0_CPU1_P2P2_DN<21>")
	)
	(arc
		(start 109.674406 -281.911298)
		(mid 109.495809 -281.59202)
		(end 109.674406 -281.272742)
		(width 0.0889)
		(layer "In6.Cu")
		(net "UPI_CPU0_CPU1_P2P2_DN<21>")
	)
	(arc
		(start 334.44815 -286.83585)
		(mid 334.439578 -286.842372)
		(end 334.431132 -286.849058)
		(width 0.0889)
		(layer "In6.Cu")
		(net "UPI_CPU0_CPU1_P2P2_DN<21>")
	)
	(arc
		(start 109.026198 -284.025086)
		(mid 109.078468 -283.842721)
		(end 109.213396 -283.709364)
		(width 0.0889)
		(layer "In6.Cu")
		(net "UPI_CPU0_CPU1_P2P2_DN<21>")
	)
	(arc
		(start 110.435898 -279.964134)
		(mid 110.483577 -279.781234)
		(end 110.61446 -279.644856)
		(width 0.0889)
		(layer "In6.Cu")
		(net "UPI_CPU0_CPU1_P2P2_DN<21>")
	)
	(arc
		(start 108.086398 -285.661354)
		(mid 108.134077 -285.478454)
		(end 108.26496 -285.342076)
		(width 0.0889)
		(layer "In6.Cu")
		(net "UPI_CPU0_CPU1_P2P2_DN<21>")
	)
	(arc
		(start 107.80395 -286.151066)
		(mid 108.007255 -285.9502)
		(end 108.086398 -285.675578)
		(width 0.0889)
		(layer "In6.Cu")
		(net "UPI_CPU0_CPU1_P2P2_DN<21>")
	)
	(arc
		(start 110.142782 -276.213062)
		(mid 109.86435 -276.143216)
		(end 109.587538 -276.219158)
		(width 0.0889)
		(layer "In6.Cu")
		(net "UPI_CPU0_CPU1_P2P2_DN<21>")
	)
	(arc
		(start 109.965744 -282.39593)
		(mid 109.887633 -282.118981)
		(end 109.683296 -281.916378)
		(width 0.0889)
		(layer "In6.Cu")
		(net "UPI_CPU0_CPU1_P2P2_DN<21>")
	)
	(arc
		(start 107.146598 -287.280604)
		(mid 107.198868 -287.098239)
		(end 107.333796 -286.964882)
		(width 0.0889)
		(layer "In6.Cu")
		(net "UPI_CPU0_CPU1_P2P2_DN<21>")
	)
	(arc
		(start 109.213396 -283.709364)
		(mid 109.417731 -283.506759)
		(end 109.495844 -283.229812)
		(width 0.0889)
		(layer "In6.Cu")
		(net "UPI_CPU0_CPU1_P2P2_DN<21>")
	)
	(arc
		(start 106.869992 -287.775142)
		(mid 107.072579 -287.568791)
		(end 107.146598 -287.28924)
		(width 0.0889)
		(layer "In6.Cu")
		(net "UPI_CPU0_CPU1_P2P2_DN<21>")
	)
	(arc
		(start 110.614206 -278.65578)
		(mid 110.483292 -278.51942)
		(end 110.435644 -278.336502)
		(width 0.0889)
		(layer "In6.Cu")
		(net "UPI_CPU0_CPU1_P2P2_DN<21>")
	)
	(arc
		(start 108.556298 -284.838902)
		(mid 108.608568 -284.656537)
		(end 108.743496 -284.52318)
		(width 0.0889)
		(layer "In6.Cu")
		(net "UPI_CPU0_CPU1_P2P2_DN<21>")
	)
	(arc
		(start 110.43539 -278.321516)
		(mid 110.488902 -278.142892)
		(end 110.621826 -278.012144)
		(width 0.0889)
		(layer "In6.Cu")
		(net "UPI_CPU0_CPU1_P2P2_DN<21>")
	)
	(arc
		(start 110.435898 -276.708616)
		(mid 110.363663 -276.432092)
		(end 110.165388 -276.22627)
		(width 0.0889)
		(layer "In6.Cu")
		(net "UPI_CPU0_CPU1_P2P2_DN<21>")
	)
	(arc
		(start 109.683296 -282.895548)
		(mid 109.885582 -282.696567)
		(end 109.965744 -282.424378)
		(width 0.0889)
		(layer "In6.Cu")
		(net "UPI_CPU0_CPU1_P2P2_DN<21>")
	)
	(arc
		(start 110.153196 -280.453846)
		(mid 110.358268 -280.250167)
		(end 110.435898 -279.971754)
		(width 0.0889)
		(layer "In6.Cu")
		(net "UPI_CPU0_CPU1_P2P2_DN<21>")
	)
	(arc
		(start 109.495844 -283.219906)
		(mid 109.543523 -283.037006)
		(end 109.674406 -282.900628)
		(width 0.0889)
		(layer "In6.Cu")
		(net "UPI_CPU0_CPU1_P2P2_DN<21>")
	)
	(arc
		(start 110.61446 -277.027894)
		(mid 110.483546 -276.891534)
		(end 110.435898 -276.708616)
		(width 0.0889)
		(layer "In6.Cu")
		(net "UPI_CPU0_CPU1_P2P2_DN<21>")
	)
	(arc
		(start 106.855006 -288.422334)
		(mid 106.676288 -288.103056)
		(end 106.855006 -287.783778)
		(width 0.0889)
		(layer "In6.Cu")
		(net "UPI_CPU0_CPU1_P2P2_DN<21>")
	)
	(arc
		(start 109.965744 -280.778204)
		(mid 110.013423 -280.595304)
		(end 110.144306 -280.458926)
		(width 0.0889)
		(layer "In6.Cu")
		(net "UPI_CPU0_CPU1_P2P2_DN<21>")
	)
	(arc
		(start 110.905798 -279.150318)
		(mid 110.831807 -278.870752)
		(end 110.629192 -278.664416)
		(width 0.0889)
		(layer "In6.Cu")
		(net "UPI_CPU0_CPU1_P2P2_DN<21>")
	)
	(arc
		(start 107.616498 -286.475424)
		(mid 107.664177 -286.292524)
		(end 107.79506 -286.156146)
		(width 0.0889)
		(layer "In6.Cu")
		(net "UPI_CPU0_CPU1_P2P2_DN<21>")
	)
	(arc
		(start 110.62335 -279.639776)
		(mid 110.83011 -279.433013)
		(end 110.905798 -279.150572)
		(width 0.0889)
		(layer "In6.Cu")
		(net "UPI_CPU0_CPU1_P2P2_DN<21>")
	)
	(arc
		(start 334.431132 -286.849058)
		(mid 334.275933 -287.045128)
		(end 334.220566 -287.288986)
		(width 0.0889)
		(layer "In6.Cu")
		(net "UPI_CPU0_CPU1_P2P2_DN<21>")
	)
	(arc
		(start 107.616244 -289.60953)
		(mid 107.504906 -289.41663)
		(end 107.330748 -289.277806)
		(width 0.0889)
		(layer "In6.Cu")
		(net "UPI_CPU0_CPU1_P2P2_DN<21>")
	)
	(arc
		(start 108.749592 -284.519624)
		(mid 108.952179 -284.313273)
		(end 109.026198 -284.033722)
		(width 0.0889)
		(layer "In6.Cu")
		(net "UPI_CPU0_CPU1_P2P2_DN<21>")
	)
	(arc
		(start 107.330748 -289.277806)
		(mid 107.221601 -289.193878)
		(end 107.146598 -289.078416)
		(width 0.0889)
		(layer "In6.Cu")
		(net "UPI_CPU0_CPU1_P2P2_DN<21>")
	)
	(arc
		(start 107.146598 -288.902902)
		(mid 107.067379 -288.628217)
		(end 106.863896 -288.427414)
		(width 0.0889)
		(layer "In6.Cu")
		(net "UPI_CPU0_CPU1_P2P2_DN<21>")
	)
	(arc
		(start 110.635796 -278.004016)
		(mid 110.905357 -277.520951)
		(end 110.633256 -277.039324)
		(width 0.0889)
		(layer "In6.Cu")
		(net "UPI_CPU0_CPU1_P2P2_DN<21>")
	)
	(arc
		(start 107.345988 -286.95777)
		(mid 107.544216 -286.751922)
		(end 107.616498 -286.475424)
		(width 0.0889)
		(layer "In6.Cu")
		(net "UPI_CPU0_CPU1_P2P2_DN<21>")
	)
	(segment
		(start 106.581448 -275.894546)
		(end 106.581194 -275.8948)
		(width 0.13208)
		(layer "F.Cu")
		(net "UPI_CPU0_CPU1_P2P2_DN<20>")
	)
	(segment
		(start 106.581448 -275.35886)
		(end 106.581448 -275.894546)
		(width 0.13208)
		(layer "F.Cu")
		(net "UPI_CPU0_CPU1_P2P2_DN<20>")
	)
	(segment
		(start 335.255362 -285.939484)
		(end 335.255362 -286.475424)
		(width 0.13208)
		(layer "F.Cu")
		(net "UPI_CPU0_CPU1_P2P2_DN<20>")
	)
	(segment
		(start 104.732074 -292.463474)
		(end 104.732074 -292.153086)
		(width 0.14732)
		(layer "In6.Cu")
		(net "UPI_CPU0_CPU1_P2P2_DN<20>")
	)
	(segment
		(start 239.8903 -363.22127)
		(end 238.852964 -361.739942)
		(width 0.14732)
		(layer "In6.Cu")
		(net "UPI_CPU0_CPU1_P2P2_DN<20>")
	)
	(segment
		(start 105.546144 -290.790884)
		(end 105.546144 -289.609784)
		(width 0.0889)
		(layer "In6.Cu")
		(net "UPI_CPU0_CPU1_P2P2_DN<20>")
	)
	(segment
		(start 335.529174 -287.608518)
		(end 335.538064 -287.613598)
		(width 0.0889)
		(layer "In6.Cu")
		(net "UPI_CPU0_CPU1_P2P2_DN<20>")
	)
	(segment
		(start 249.333512 -354.514912)
		(end 249.333512 -354.723192)
		(width 0.14732)
		(layer "In6.Cu")
		(net "UPI_CPU0_CPU1_P2P2_DN<20>")
	)
	(segment
		(start 249.597164 -354.986844)
		(end 249.597164 -355.4222)
		(width 0.14732)
		(layer "In6.Cu")
		(net "UPI_CPU0_CPU1_P2P2_DN<20>")
	)
	(segment
		(start 257.074924 -348.037912)
		(end 257.074924 -348.473268)
		(width 0.14732)
		(layer "In6.Cu")
		(net "UPI_CPU0_CPU1_P2P2_DN<20>")
	)
	(segment
		(start 277.50389 -328.691748)
		(end 277.29307 -328.480928)
		(width 0.14732)
		(layer "In6.Cu")
		(net "UPI_CPU0_CPU1_P2P2_DN<20>")
	)
	(segment
		(start 108.64215 -281.106118)
		(end 108.648246 -281.102562)
		(width 0.0889)
		(layer "In6.Cu")
		(net "UPI_CPU0_CPU1_P2P2_DN<20>")
	)
	(segment
		(start 239.089946 -364.157514)
		(end 238.42091 -364.626652)
		(width 0.14732)
		(layer "In6.Cu")
		(net "UPI_CPU0_CPU1_P2P2_DN<20>")
	)
	(segment
		(start 259.338826 -345.77401)
		(end 258.81076 -345.245944)
		(width 0.14732)
		(layer "In6.Cu")
		(net "UPI_CPU0_CPU1_P2P2_DN<20>")
	)
	(segment
		(start 332.510384 -292.203632)
		(end 332.522068 -292.262052)
		(width 0.0889)
		(layer "In6.Cu")
		(net "UPI_CPU0_CPU1_P2P2_DN<20>")
	)
	(segment
		(start 245.606062 -359.576878)
		(end 245.170706 -359.576878)
		(width 0.14732)
		(layer "In6.Cu")
		(net "UPI_CPU0_CPU1_P2P2_DN<20>")
	)
	(segment
		(start 335.059274 -286.794702)
		(end 335.068164 -286.799782)
		(width 0.0889)
		(layer "In6.Cu")
		(net "UPI_CPU0_CPU1_P2P2_DN<20>")
	)
	(segment
		(start 278.306784 -327.258934)
		(end 278.306784 -327.467214)
		(width 0.14732)
		(layer "In6.Cu")
		(net "UPI_CPU0_CPU1_P2P2_DN<20>")
	)
	(segment
		(start 74.315828 -327.545954)
		(end 75.519534 -325.00189)
		(width 0.14732)
		(layer "In6.Cu")
		(net "UPI_CPU0_CPU1_P2P2_DN<20>")
	)
	(segment
		(start 277.939246 -328.691748)
		(end 277.50389 -328.691748)
		(width 0.14732)
		(layer "In6.Cu")
		(net "UPI_CPU0_CPU1_P2P2_DN<20>")
	)
	(segment
		(start 333.926688 -290.340034)
		(end 333.926688 -290.476432)
		(width 0.0889)
		(layer "In6.Cu")
		(net "UPI_CPU0_CPU1_P2P2_DN<20>")
	)
	(segment
		(start 255.436116 -349.67672)
		(end 255.436116 -350.112076)
		(width 0.14732)
		(layer "In6.Cu")
		(net "UPI_CPU0_CPU1_P2P2_DN<20>")
	)
	(segment
		(start 235.056172 -364.398814)
		(end 234.851448 -364.362746)
		(width 0.14732)
		(layer "In6.Cu")
		(net "UPI_CPU0_CPU1_P2P2_DN<20>")
	)
	(segment
		(start 80.971898 -364.469934)
		(end 76.493624 -359.992676)
		(width 0.14732)
		(layer "In6.Cu")
		(net "UPI_CPU0_CPU1_P2P2_DN<20>")
	)
	(segment
		(start 104.732074 -292.130988)
		(end 104.773984 -292.089078)
		(width 0.0889)
		(layer "In6.Cu")
		(net "UPI_CPU0_CPU1_P2P2_DN<20>")
	)
	(segment
		(start 334.242664 -290.160456)
		(end 334.106266 -290.160456)
		(width 0.0889)
		(layer "In6.Cu")
		(net "UPI_CPU0_CPU1_P2P2_DN<20>")
	)
	(segment
		(start 108.365544 -283.228542)
		(end 108.365544 -283.205682)
		(width 0.0889)
		(layer "In6.Cu")
		(net "UPI_CPU0_CPU1_P2P2_DN<20>")
	)
	(segment
		(start 106.016298 -289.077908)
		(end 106.016298 -288.917126)
		(width 0.0889)
		(layer "In6.Cu")
		(net "UPI_CPU0_CPU1_P2P2_DN<20>")
	)
	(segment
		(start 258.135374 -347.412818)
		(end 257.700018 -347.412818)
		(width 0.14732)
		(layer "In6.Cu")
		(net "UPI_CPU0_CPU1_P2P2_DN<20>")
	)
	(segment
		(start 246.18442 -358.99852)
		(end 245.606062 -359.576878)
		(width 0.14732)
		(layer "In6.Cu")
		(net "UPI_CPU0_CPU1_P2P2_DN<20>")
	)
	(segment
		(start 104.773984 -292.089078)
		(end 104.773984 -291.563044)
		(width 0.0889)
		(layer "In6.Cu")
		(net "UPI_CPU0_CPU1_P2P2_DN<20>")
	)
	(segment
		(start 307.05425 -315.419232)
		(end 306.17033 -315.90488)
		(width 0.14732)
		(layer "In6.Cu")
		(net "UPI_CPU0_CPU1_P2P2_DN<20>")
	)
	(segment
		(start 312.340498 -313.75731)
		(end 311.189878 -314.234068)
		(width 0.14732)
		(layer "In6.Cu")
		(net "UPI_CPU0_CPU1_P2P2_DN<20>")
	)
	(segment
		(start 260.977634 -344.135202)
		(end 260.449568 -343.607136)
		(width 0.14732)
		(layer "In6.Cu")
		(net "UPI_CPU0_CPU1_P2P2_DN<20>")
	)
	(segment
		(start 105.837736 -288.597848)
		(end 105.828846 -288.592768)
		(width 0.0889)
		(layer "In6.Cu")
		(net "UPI_CPU0_CPU1_P2P2_DN<20>")
	)
	(segment
		(start 334.106266 -290.160456)
		(end 333.926688 -290.340034)
		(width 0.0889)
		(layer "In6.Cu")
		(net "UPI_CPU0_CPU1_P2P2_DN<20>")
	)
	(segment
		(start 249.018806 -356.000558)
		(end 248.58345 -356.000558)
		(width 0.14732)
		(layer "In6.Cu")
		(net "UPI_CPU0_CPU1_P2P2_DN<20>")
	)
	(segment
		(start 233.228388 -367.298478)
		(end 233.038142 -366.217454)
		(width 0.14732)
		(layer "In6.Cu")
		(net "UPI_CPU0_CPU1_P2P2_DN<20>")
	)
	(segment
		(start 332.509876 -292.28034)
		(end 332.509622 -292.28034)
		(width 0.14732)
		(layer "In6.Cu")
		(net "UPI_CPU0_CPU1_P2P2_DN<20>")
	)
	(segment
		(start 254.857758 -350.690434)
		(end 254.422402 -350.690434)
		(width 0.14732)
		(layer "In6.Cu")
		(net "UPI_CPU0_CPU1_P2P2_DN<20>")
	)
	(segment
		(start 108.645452 -282.0797)
		(end 108.644436 -282.079192)
		(width 0.0889)
		(layer "In6.Cu")
		(net "UPI_CPU0_CPU1_P2P2_DN<20>")
	)
	(segment
		(start 106.955844 -285.66999)
		(end 106.955844 -285.651448)
		(width 0.0889)
		(layer "In6.Cu")
		(net "UPI_CPU0_CPU1_P2P2_DN<20>")
	)
	(segment
		(start 106.893868 -275.8948)
		(end 106.581194 -275.8948)
		(width 0.0889)
		(layer "In6.Cu")
		(net "UPI_CPU0_CPU1_P2P2_DN<20>")
	)
	(segment
		(start 255.533144 -348.52356)
		(end 255.324864 -348.52356)
		(width 0.14732)
		(layer "In6.Cu")
		(net "UPI_CPU0_CPU1_P2P2_DN<20>")
	)
	(segment
		(start 236.265974 -363.372146)
		(end 236.229906 -363.576616)
		(width 0.14732)
		(layer "In6.Cu")
		(net "UPI_CPU0_CPU1_P2P2_DN<20>")
	)
	(segment
		(start 277.29307 -328.480928)
		(end 277.08479 -328.480928)
		(width 0.14732)
		(layer "In6.Cu")
		(net "UPI_CPU0_CPU1_P2P2_DN<20>")
	)
	(segment
		(start 233.038142 -366.217454)
		(end 232.867962 -366.098328)
		(width 0.14732)
		(layer "In6.Cu")
		(net "UPI_CPU0_CPU1_P2P2_DN<20>")
	)
	(segment
		(start 261.880096 -341.968328)
		(end 261.463282 -342.385142)
		(width 0.14732)
		(layer "In6.Cu")
		(net "UPI_CPU0_CPU1_P2P2_DN<20>")
	)
	(segment
		(start 109.305344 -278.346408)
		(end 109.305344 -278.31796)
		(width 0.0889)
		(layer "In6.Cu")
		(net "UPI_CPU0_CPU1_P2P2_DN<20>")
	)
	(segment
		(start 333.926688 -290.476432)
		(end 333.746856 -290.656264)
		(width 0.0889)
		(layer "In6.Cu")
		(net "UPI_CPU0_CPU1_P2P2_DN<20>")
	)
	(segment
		(start 109.596682 -278.83104)
		(end 109.59592 -278.830532)
		(width 0.0889)
		(layer "In6.Cu")
		(net "UPI_CPU0_CPU1_P2P2_DN<20>")
	)
	(segment
		(start 106.298492 -286.799782)
		(end 106.307382 -286.794702)
		(width 0.0889)
		(layer "In6.Cu")
		(net "UPI_CPU0_CPU1_P2P2_DN<20>")
	)
	(segment
		(start 274.16887 -331.396848)
		(end 272.451576 -331.396848)
		(width 0.14732)
		(layer "In6.Cu")
		(net "UPI_CPU0_CPU1_P2P2_DN<20>")
	)
	(segment
		(start 99.248214 -372.04015)
		(end 80.971898 -364.469934)
		(width 0.14732)
		(layer "In6.Cu")
		(net "UPI_CPU0_CPU1_P2P2_DN<20>")
	)
	(segment
		(start 249.597164 -355.4222)
		(end 249.018806 -356.000558)
		(width 0.14732)
		(layer "In6.Cu")
		(net "UPI_CPU0_CPU1_P2P2_DN<20>")
	)
	(segment
		(start 259.824474 -344.23223)
		(end 260.35254 -344.760296)
		(width 0.14732)
		(layer "In6.Cu")
		(net "UPI_CPU0_CPU1_P2P2_DN<20>")
	)
	(segment
		(start 106.959654 -275.960586)
		(end 106.893868 -275.8948)
		(width 0.0889)
		(layer "In6.Cu")
		(net "UPI_CPU0_CPU1_P2P2_DN<20>")
	)
	(segment
		(start 260.35254 -344.760296)
		(end 260.35254 -345.195652)
		(width 0.14732)
		(layer "In6.Cu")
		(net "UPI_CPU0_CPU1_P2P2_DN<20>")
	)
	(segment
		(start 73.102978 -351.815908)
		(end 73.102978 -335.200752)
		(width 0.14732)
		(layer "In6.Cu")
		(net "UPI_CPU0_CPU1_P2P2_DN<20>")
	)
	(segment
		(start 303.827942 -317.895478)
		(end 303.6951 -319.02781)
		(width 0.14732)
		(layer "In6.Cu")
		(net "UPI_CPU0_CPU1_P2P2_DN<20>")
	)
	(segment
		(start 245.83898 -358.217724)
		(end 246.18442 -358.563164)
		(width 0.14732)
		(layer "In6.Cu")
		(net "UPI_CPU0_CPU1_P2P2_DN<20>")
	)
	(segment
		(start 245.83898 -358.009444)
		(end 245.83898 -358.217724)
		(width 0.14732)
		(layer "In6.Cu")
		(net "UPI_CPU0_CPU1_P2P2_DN<20>")
	)
	(segment
		(start 332.586584 -292.090856)
		(end 332.510384 -292.203632)
		(width 0.0889)
		(layer "In6.Cu")
		(net "UPI_CPU0_CPU1_P2P2_DN<20>")
	)
	(segment
		(start 334.422496 -289.844226)
		(end 334.422496 -289.980624)
		(width 0.0889)
		(layer "In6.Cu")
		(net "UPI_CPU0_CPU1_P2P2_DN<20>")
	)
	(segment
		(start 332.850236 -291.699188)
		(end 332.586584 -292.090856)
		(width 0.0889)
		(layer "In6.Cu")
		(net "UPI_CPU0_CPU1_P2P2_DN<20>")
	)
	(segment
		(start 332.509622 -292.28034)
		(end 331.823568 -293.303706)
		(width 0.14732)
		(layer "In6.Cu")
		(net "UPI_CPU0_CPU1_P2P2_DN<20>")
	)
	(segment
		(start 332.984602 -291.672772)
		(end 332.850236 -291.699188)
		(width 0.0889)
		(layer "In6.Cu")
		(net "UPI_CPU0_CPU1_P2P2_DN<20>")
	)
	(segment
		(start 247.447562 -358.140762)
		(end 247.012206 -358.140762)
		(width 0.14732)
		(layer "In6.Cu")
		(net "UPI_CPU0_CPU1_P2P2_DN<20>")
	)
	(segment
		(start 103.064818 -299.48378)
		(end 104.73182 -297.236134)
		(width 0.14732)
		(layer "In6.Cu")
		(net "UPI_CPU0_CPU1_P2P2_DN<20>")
	)
	(segment
		(start 254.422402 -350.690434)
		(end 253.894336 -350.162368)
		(width 0.14732)
		(layer "In6.Cu")
		(net "UPI_CPU0_CPU1_P2P2_DN<20>")
	)
	(segment
		(start 306.17033 -315.90488)
		(end 304.57013 -317.048642)
		(width 0.14732)
		(layer "In6.Cu")
		(net "UPI_CPU0_CPU1_P2P2_DN<20>")
	)
	(segment
		(start 335.469992 -288.642806)
		(end 335.469992 -288.642552)
		(width 0.0889)
		(layer "In6.Cu")
		(net "UPI_CPU0_CPU1_P2P2_DN<20>")
	)
	(segment
		(start 246.18442 -358.563164)
		(end 246.18442 -358.99852)
		(width 0.14732)
		(layer "In6.Cu")
		(net "UPI_CPU0_CPU1_P2P2_DN<20>")
	)
	(segment
		(start 313.325764 -312.772044)
		(end 312.340498 -313.75731)
		(width 0.14732)
		(layer "In6.Cu")
		(net "UPI_CPU0_CPU1_P2P2_DN<20>")
	)
	(segment
		(start 238.64824 -361.703874)
		(end 238.16437 -362.04271)
		(width 0.14732)
		(layer "In6.Cu")
		(net "UPI_CPU0_CPU1_P2P2_DN<20>")
	)
	(segment
		(start 317.173102 -312.453528)
		(end 314.094622 -312.453528)
		(width 0.14732)
		(layer "In6.Cu")
		(net "UPI_CPU0_CPU1_P2P2_DN<20>")
	)
	(segment
		(start 212.311234 -371.298724)
		(end 199.05853 -368.96167)
		(width 0.14732)
		(layer "In6.Cu")
		(net "UPI_CPU0_CPU1_P2P2_DN<20>")
	)
	(segment
		(start 258.185666 -345.871038)
		(end 258.713732 -346.399104)
		(width 0.14732)
		(layer "In6.Cu")
		(net "UPI_CPU0_CPU1_P2P2_DN<20>")
	)
	(segment
		(start 109.591094 -279.472644)
		(end 109.596682 -279.469596)
		(width 0.0889)
		(layer "In6.Cu")
		(net "UPI_CPU0_CPU1_P2P2_DN<20>")
	)
	(segment
		(start 239.165892 -363.728762)
		(end 239.089946 -364.157514)
		(width 0.14732)
		(layer "In6.Cu")
		(net "UPI_CPU0_CPU1_P2P2_DN<20>")
	)
	(segment
		(start 277.08479 -328.480928)
		(end 274.16887 -331.396848)
		(width 0.14732)
		(layer "In6.Cu")
		(net "UPI_CPU0_CPU1_P2P2_DN<20>")
	)
	(segment
		(start 236.753654 -366.822736)
		(end 235.056172 -364.398814)
		(width 0.14732)
		(layer "In6.Cu")
		(net "UPI_CPU0_CPU1_P2P2_DN<20>")
	)
	(segment
		(start 108.835444 -282.414472)
		(end 108.835444 -282.3972)
		(width 0.0889)
		(layer "In6.Cu")
		(net "UPI_CPU0_CPU1_P2P2_DN<20>")
	)
	(segment
		(start 333.126334 -291.461952)
		(end 332.984602 -291.672772)
		(width 0.0889)
		(layer "In6.Cu")
		(net "UPI_CPU0_CPU1_P2P2_DN<20>")
	)
	(segment
		(start 105.837736 -287.608264)
		(end 105.837736 -287.608518)
		(width 0.0889)
		(layer "In6.Cu")
		(net "UPI_CPU0_CPU1_P2P2_DN<20>")
	)
	(segment
		(start 109.596682 -277.203154)
		(end 109.587792 -277.198074)
		(width 0.0889)
		(layer "In6.Cu")
		(net "UPI_CPU0_CPU1_P2P2_DN<20>")
	)
	(segment
		(start 262.088376 -341.968328)
		(end 261.880096 -341.968328)
		(width 0.14732)
		(layer "In6.Cu")
		(net "UPI_CPU0_CPU1_P2P2_DN<20>")
	)
	(segment
		(start 236.954568 -363.069378)
		(end 236.749844 -363.03331)
		(width 0.14732)
		(layer "In6.Cu")
		(net "UPI_CPU0_CPU1_P2P2_DN<20>")
	)
	(segment
		(start 238.16437 -362.04271)
		(end 238.128302 -362.24718)
		(width 0.14732)
		(layer "In6.Cu")
		(net "UPI_CPU0_CPU1_P2P2_DN<20>")
	)
	(segment
		(start 333.43088 -290.835842)
		(end 333.100172 -291.32784)
		(width 0.0889)
		(layer "In6.Cu")
		(net "UPI_CPU0_CPU1_P2P2_DN<20>")
	)
	(segment
		(start 246.255794 -357.59263)
		(end 245.83898 -358.009444)
		(width 0.14732)
		(layer "In6.Cu")
		(net "UPI_CPU0_CPU1_P2P2_DN<20>")
	)
	(segment
		(start 258.713732 -346.399104)
		(end 258.713732 -346.83446)
		(width 0.14732)
		(layer "In6.Cu")
		(net "UPI_CPU0_CPU1_P2P2_DN<20>")
	)
	(segment
		(start 234.33151 -364.906052)
		(end 235.3691 -366.387634)
		(width 0.14732)
		(layer "In6.Cu")
		(net "UPI_CPU0_CPU1_P2P2_DN<20>")
	)
	(segment
		(start 109.588554 -277.846282)
		(end 109.596682 -277.84171)
		(width 0.0889)
		(layer "In6.Cu")
		(net "UPI_CPU0_CPU1_P2P2_DN<20>")
	)
	(segment
		(start 258.185666 -345.662758)
		(end 258.185666 -345.871038)
		(width 0.14732)
		(layer "In6.Cu")
		(net "UPI_CPU0_CPU1_P2P2_DN<20>")
	)
	(segment
		(start 235.3691 -366.387634)
		(end 235.293154 -366.81664)
		(width 0.14732)
		(layer "In6.Cu")
		(net "UPI_CPU0_CPU1_P2P2_DN<20>")
	)
	(segment
		(start 331.823568 -293.303706)
		(end 329.863958 -299.762672)
		(width 0.14732)
		(layer "In6.Cu")
		(net "UPI_CPU0_CPU1_P2P2_DN<20>")
	)
	(segment
		(start 105.82275 -287.617154)
		(end 105.837736 -287.608264)
		(width 0.0889)
		(layer "In6.Cu")
		(net "UPI_CPU0_CPU1_P2P2_DN<20>")
	)
	(segment
		(start 241.092228 -362.755942)
		(end 240.319306 -363.297216)
		(width 0.14732)
		(layer "In6.Cu")
		(net "UPI_CPU0_CPU1_P2P2_DN<20>")
	)
	(segment
		(start 249.333512 -354.723192)
		(end 249.597164 -354.986844)
		(width 0.14732)
		(layer "In6.Cu")
		(net "UPI_CPU0_CPU1_P2P2_DN<20>")
	)
	(segment
		(start 261.463282 -342.385142)
		(end 261.463282 -342.593422)
		(width 0.14732)
		(layer "In6.Cu")
		(net "UPI_CPU0_CPU1_P2P2_DN<20>")
	)
	(segment
		(start 159.066992 -376.01271)
		(end 126.019306 -376.01271)
		(width 0.14732)
		(layer "In6.Cu")
		(net "UPI_CPU0_CPU1_P2P2_DN<20>")
	)
	(segment
		(start 302.635666 -321.780154)
		(end 300.953932 -323.461888)
		(width 0.14732)
		(layer "In6.Cu")
		(net "UPI_CPU0_CPU1_P2P2_DN<20>")
	)
	(segment
		(start 76.493624 -359.992676)
		(end 73.102978 -351.815908)
		(width 0.14732)
		(layer "In6.Cu")
		(net "UPI_CPU0_CPU1_P2P2_DN<20>")
	)
	(segment
		(start 109.587792 -277.84679)
		(end 109.588554 -277.846282)
		(width 0.0889)
		(layer "In6.Cu")
		(net "UPI_CPU0_CPU1_P2P2_DN<20>")
	)
	(segment
		(start 73.102978 -335.200752)
		(end 73.603104 -330.124816)
		(width 0.14732)
		(layer "In6.Cu")
		(net "UPI_CPU0_CPU1_P2P2_DN<20>")
	)
	(segment
		(start 106.016298 -287.28924)
		(end 106.016298 -287.273746)
		(width 0.0889)
		(layer "In6.Cu")
		(net "UPI_CPU0_CPU1_P2P2_DN<20>")
	)
	(segment
		(start 104.73182 -297.236134)
		(end 104.73182 -292.463728)
		(width 0.14732)
		(layer "In6.Cu")
		(net "UPI_CPU0_CPU1_P2P2_DN<20>")
	)
	(segment
		(start 109.590332 -278.827484)
		(end 109.588554 -278.826468)
		(width 0.0889)
		(layer "In6.Cu")
		(net "UPI_CPU0_CPU1_P2P2_DN<20>")
	)
	(segment
		(start 237.991904 -364.550706)
		(end 236.954568 -363.069378)
		(width 0.14732)
		(layer "In6.Cu")
		(net "UPI_CPU0_CPU1_P2P2_DN<20>")
	)
	(segment
		(start 278.306784 -327.467214)
		(end 278.517604 -327.678034)
		(width 0.14732)
		(layer "In6.Cu")
		(net "UPI_CPU0_CPU1_P2P2_DN<20>")
	)
	(segment
		(start 248.02592 -357.562404)
		(end 247.447562 -358.140762)
		(width 0.14732)
		(layer "In6.Cu")
		(net "UPI_CPU0_CPU1_P2P2_DN<20>")
	)
	(segment
		(start 107.702096 -284.361636)
		(end 107.708192 -284.35808)
		(width 0.0889)
		(layer "In6.Cu")
		(net "UPI_CPU0_CPU1_P2P2_DN<20>")
	)
	(segment
		(start 97.768918 -305.777392)
		(end 103.064818 -299.48378)
		(width 0.14732)
		(layer "In6.Cu")
		(net "UPI_CPU0_CPU1_P2P2_DN<20>")
	)
	(segment
		(start 335.484724 -288.629344)
		(end 335.484724 -288.62909)
		(width 0.0889)
		(layer "In6.Cu")
		(net "UPI_CPU0_CPU1_P2P2_DN<20>")
	)
	(segment
		(start 238.852964 -361.739942)
		(end 238.64824 -361.703874)
		(width 0.14732)
		(layer "In6.Cu")
		(net "UPI_CPU0_CPU1_P2P2_DN<20>")
	)
	(segment
		(start 255.324864 -348.52356)
		(end 254.90805 -348.940374)
		(width 0.14732)
		(layer "In6.Cu")
		(net "UPI_CPU0_CPU1_P2P2_DN<20>")
	)
	(segment
		(start 272.451576 -331.396848)
		(end 263.10209 -340.746334)
		(width 0.14732)
		(layer "In6.Cu")
		(net "UPI_CPU0_CPU1_P2P2_DN<20>")
	)
	(segment
		(start 107.708192 -284.35808)
		(end 107.717082 -284.353)
		(width 0.0889)
		(layer "In6.Cu")
		(net "UPI_CPU0_CPU1_P2P2_DN<20>")
	)
	(segment
		(start 254.90805 -349.148654)
		(end 255.436116 -349.67672)
		(width 0.14732)
		(layer "In6.Cu")
		(net "UPI_CPU0_CPU1_P2P2_DN<20>")
	)
	(segment
		(start 254.90805 -348.940374)
		(end 254.90805 -349.148654)
		(width 0.14732)
		(layer "In6.Cu")
		(net "UPI_CPU0_CPU1_P2P2_DN<20>")
	)
	(segment
		(start 236.749844 -363.03331)
		(end 236.265974 -363.372146)
		(width 0.14732)
		(layer "In6.Cu")
		(net "UPI_CPU0_CPU1_P2P2_DN<20>")
	)
	(segment
		(start 232.166922 -366.371124)
		(end 232.357422 -367.452402)
		(width 0.14732)
		(layer "In6.Cu")
		(net "UPI_CPU0_CPU1_P2P2_DN<20>")
	)
	(segment
		(start 236.229906 -363.576616)
		(end 237.927642 -366.000792)
		(width 0.14732)
		(layer "In6.Cu")
		(net "UPI_CPU0_CPU1_P2P2_DN<20>")
	)
	(segment
		(start 261.41299 -344.135202)
		(end 260.977634 -344.135202)
		(width 0.14732)
		(layer "In6.Cu")
		(net "UPI_CPU0_CPU1_P2P2_DN<20>")
	)
	(segment
		(start 259.774182 -345.77401)
		(end 259.338826 -345.77401)
		(width 0.14732)
		(layer "In6.Cu")
		(net "UPI_CPU0_CPU1_P2P2_DN<20>")
	)
	(segment
		(start 287.363408 -325.079868)
		(end 285.229808 -325.963534)
		(width 0.14732)
		(layer "In6.Cu")
		(net "UPI_CPU0_CPU1_P2P2_DN<20>")
	)
	(segment
		(start 258.713732 -346.83446)
		(end 258.135374 -347.412818)
		(width 0.14732)
		(layer "In6.Cu")
		(net "UPI_CPU0_CPU1_P2P2_DN<20>")
	)
	(segment
		(start 333.100172 -291.32784)
		(end 333.126334 -291.461952)
		(width 0.0889)
		(layer "In6.Cu")
		(net "UPI_CPU0_CPU1_P2P2_DN<20>")
	)
	(segment
		(start 261.991348 -343.556844)
		(end 261.41299 -344.135202)
		(width 0.14732)
		(layer "In6.Cu")
		(net "UPI_CPU0_CPU1_P2P2_DN<20>")
	)
	(segment
		(start 262.616442 -342.496394)
		(end 262.088376 -341.968328)
		(width 0.14732)
		(layer "In6.Cu")
		(net "UPI_CPU0_CPU1_P2P2_DN<20>")
	)
	(segment
		(start 263.10209 -340.954614)
		(end 263.630156 -341.48268)
		(width 0.14732)
		(layer "In6.Cu")
		(net "UPI_CPU0_CPU1_P2P2_DN<20>")
	)
	(segment
		(start 108.644436 -282.079192)
		(end 108.64215 -282.077922)
		(width 0.0889)
		(layer "In6.Cu")
		(net "UPI_CPU0_CPU1_P2P2_DN<20>")
	)
	(segment
		(start 256.546858 -347.301566)
		(end 256.546858 -347.509846)
		(width 0.14732)
		(layer "In6.Cu")
		(net "UPI_CPU0_CPU1_P2P2_DN<20>")
	)
	(segment
		(start 333.610458 -290.656264)
		(end 333.43088 -290.835842)
		(width 0.0889)
		(layer "In6.Cu")
		(net "UPI_CPU0_CPU1_P2P2_DN<20>")
	)
	(segment
		(start 104.732074 -292.153086)
		(end 104.732074 -292.130988)
		(width 0.0889)
		(layer "In6.Cu")
		(net "UPI_CPU0_CPU1_P2P2_DN<20>")
	)
	(segment
		(start 257.171952 -346.884752)
		(end 256.963672 -346.884752)
		(width 0.14732)
		(layer "In6.Cu")
		(net "UPI_CPU0_CPU1_P2P2_DN<20>")
	)
	(segment
		(start 258.60248 -345.245944)
		(end 258.185666 -345.662758)
		(width 0.14732)
		(layer "In6.Cu")
		(net "UPI_CPU0_CPU1_P2P2_DN<20>")
	)
	(segment
		(start 237.18266 -366.898682)
		(end 236.753654 -366.822736)
		(width 0.14732)
		(layer "In6.Cu")
		(net "UPI_CPU0_CPU1_P2P2_DN<20>")
	)
	(segment
		(start 334.9244 -289.342068)
		(end 334.422496 -289.844226)
		(width 0.0889)
		(layer "In6.Cu")
		(net "UPI_CPU0_CPU1_P2P2_DN<20>")
	)
	(segment
		(start 109.588554 -279.474168)
		(end 109.591094 -279.472644)
		(width 0.0889)
		(layer "In6.Cu")
		(net "UPI_CPU0_CPU1_P2P2_DN<20>")
	)
	(segment
		(start 256.546858 -347.509846)
		(end 257.074924 -348.037912)
		(width 0.14732)
		(layer "In6.Cu")
		(net "UPI_CPU0_CPU1_P2P2_DN<20>")
	)
	(segment
		(start 108.648246 -282.081478)
		(end 108.645452 -282.0797)
		(width 0.0889)
		(layer "In6.Cu")
		(net "UPI_CPU0_CPU1_P2P2_DN<20>")
	)
	(segment
		(start 232.107232 -367.809018)
		(end 212.311234 -371.298724)
		(width 0.14732)
		(layer "In6.Cu")
		(net "UPI_CPU0_CPU1_P2P2_DN<20>")
	)
	(segment
		(start 109.117892 -280.288492)
		(end 109.126782 -280.283412)
		(width 0.0889)
		(layer "In6.Cu")
		(net "UPI_CPU0_CPU1_P2P2_DN<20>")
	)
	(segment
		(start 237.927642 -366.000792)
		(end 237.851696 -366.429544)
		(width 0.14732)
		(layer "In6.Cu")
		(net "UPI_CPU0_CPU1_P2P2_DN<20>")
	)
	(segment
		(start 335.568036 -286.475424)
		(end 335.62544 -286.41802)
		(width 0.0889)
		(layer "In6.Cu")
		(net "UPI_CPU0_CPU1_P2P2_DN<20>")
	)
	(segment
		(start 307.7972 -314.676028)
		(end 307.05425 -315.419232)
		(width 0.14732)
		(layer "In6.Cu")
		(net "UPI_CPU0_CPU1_P2P2_DN<20>")
	)
	(segment
		(start 109.59592 -278.830532)
		(end 109.591094 -278.827992)
		(width 0.0889)
		(layer "In6.Cu")
		(net "UPI_CPU0_CPU1_P2P2_DN<20>")
	)
	(segment
		(start 109.587792 -279.474676)
		(end 109.588554 -279.474168)
		(width 0.0889)
		(layer "In6.Cu")
		(net "UPI_CPU0_CPU1_P2P2_DN<20>")
	)
	(segment
		(start 335.233772 -288.878518)
		(end 334.9244 -289.342068)
		(width 0.0889)
		(layer "In6.Cu")
		(net "UPI_CPU0_CPU1_P2P2_DN<20>")
	)
	(segment
		(start 260.35254 -345.195652)
		(end 259.774182 -345.77401)
		(width 0.14732)
		(layer "In6.Cu")
		(net "UPI_CPU0_CPU1_P2P2_DN<20>")
	)
	(segment
		(start 256.963672 -346.884752)
		(end 256.546858 -347.301566)
		(width 0.14732)
		(layer "In6.Cu")
		(net "UPI_CPU0_CPU1_P2P2_DN<20>")
	)
	(segment
		(start 233.585004 -367.548668)
		(end 233.228388 -367.298478)
		(width 0.14732)
		(layer "In6.Cu")
		(net "UPI_CPU0_CPU1_P2P2_DN<20>")
	)
	(segment
		(start 248.319798 -355.736906)
		(end 248.111518 -355.736906)
		(width 0.14732)
		(layer "In6.Cu")
		(net "UPI_CPU0_CPU1_P2P2_DN<20>")
	)
	(segment
		(start 247.477788 -356.578916)
		(end 248.02592 -357.127048)
		(width 0.14732)
		(layer "In6.Cu")
		(net "UPI_CPU0_CPU1_P2P2_DN<20>")
	)
	(segment
		(start 246.464074 -357.59263)
		(end 246.255794 -357.59263)
		(width 0.14732)
		(layer "In6.Cu")
		(net "UPI_CPU0_CPU1_P2P2_DN<20>")
	)
	(segment
		(start 285.229808 -325.963534)
		(end 279.602184 -325.963534)
		(width 0.14732)
		(layer "In6.Cu")
		(net "UPI_CPU0_CPU1_P2P2_DN<20>")
	)
	(segment
		(start 247.477788 -356.370636)
		(end 247.477788 -356.578916)
		(width 0.14732)
		(layer "In6.Cu")
		(net "UPI_CPU0_CPU1_P2P2_DN<20>")
	)
	(segment
		(start 248.111518 -355.736906)
		(end 247.477788 -356.370636)
		(width 0.14732)
		(layer "In6.Cu")
		(net "UPI_CPU0_CPU1_P2P2_DN<20>")
	)
	(segment
		(start 232.286048 -366.200944)
		(end 232.166922 -366.371124)
		(width 0.14732)
		(layer "In6.Cu")
		(net "UPI_CPU0_CPU1_P2P2_DN<20>")
	)
	(segment
		(start 244.825266 -359.231438)
		(end 244.616986 -359.231438)
		(width 0.14732)
		(layer "In6.Cu")
		(net "UPI_CPU0_CPU1_P2P2_DN<20>")
	)
	(segment
		(start 335.45145 -286.156146)
		(end 335.44256 -286.151066)
		(width 0.0889)
		(layer "In6.Cu")
		(net "UPI_CPU0_CPU1_P2P2_DN<20>")
	)
	(segment
		(start 248.58345 -356.000558)
		(end 248.319798 -355.736906)
		(width 0.14732)
		(layer "In6.Cu")
		(net "UPI_CPU0_CPU1_P2P2_DN<20>")
	)
	(segment
		(start 259.824474 -344.02395)
		(end 259.824474 -344.23223)
		(width 0.14732)
		(layer "In6.Cu")
		(net "UPI_CPU0_CPU1_P2P2_DN<20>")
	)
	(segment
		(start 332.522068 -292.262052)
		(end 332.509876 -292.28034)
		(width 0.0889)
		(layer "In6.Cu")
		(net "UPI_CPU0_CPU1_P2P2_DN<20>")
	)
	(segment
		(start 234.367578 -364.701582)
		(end 234.33151 -364.906052)
		(width 0.14732)
		(layer "In6.Cu")
		(net "UPI_CPU0_CPU1_P2P2_DN<20>")
	)
	(segment
		(start 80.900016 -319.621408)
		(end 97.768918 -305.777392)
		(width 0.14732)
		(layer "In6.Cu")
		(net "UPI_CPU0_CPU1_P2P2_DN<20>")
	)
	(segment
		(start 256.496566 -349.051626)
		(end 256.06121 -349.051626)
		(width 0.14732)
		(layer "In6.Cu")
		(net "UPI_CPU0_CPU1_P2P2_DN<20>")
	)
	(segment
		(start 258.81076 -345.245944)
		(end 258.60248 -345.245944)
		(width 0.14732)
		(layer "In6.Cu")
		(net "UPI_CPU0_CPU1_P2P2_DN<20>")
	)
	(segment
		(start 257.074924 -348.473268)
		(end 256.496566 -349.051626)
		(width 0.14732)
		(layer "In6.Cu")
		(net "UPI_CPU0_CPU1_P2P2_DN<20>")
	)
	(segment
		(start 108.835444 -280.78684)
		(end 108.835444 -280.759662)
		(width 0.0889)
		(layer "In6.Cu")
		(net "UPI_CPU0_CPU1_P2P2_DN<20>")
	)
	(segment
		(start 109.588554 -278.826468)
		(end 109.587792 -278.82596)
		(width 0.0889)
		(layer "In6.Cu")
		(net "UPI_CPU0_CPU1_P2P2_DN<20>")
	)
	(segment
		(start 234.470956 -367.392458)
		(end 233.585004 -367.548668)
		(width 0.14732)
		(layer "In6.Cu")
		(net "UPI_CPU0_CPU1_P2P2_DN<20>")
	)
	(segment
		(start 334.422496 -289.980624)
		(end 334.242664 -290.160456)
		(width 0.0889)
		(layer "In6.Cu")
		(net "UPI_CPU0_CPU1_P2P2_DN<20>")
	)
	(segment
		(start 108.166154 -283.551376)
		(end 108.178346 -283.544264)
		(width 0.0889)
		(layer "In6.Cu")
		(net "UPI_CPU0_CPU1_P2P2_DN<20>")
	)
	(segment
		(start 260.241288 -343.607136)
		(end 259.824474 -344.02395)
		(width 0.14732)
		(layer "In6.Cu")
		(net "UPI_CPU0_CPU1_P2P2_DN<20>")
	)
	(segment
		(start 75.519534 -325.00189)
		(end 80.900016 -319.621408)
		(width 0.14732)
		(layer "In6.Cu")
		(net "UPI_CPU0_CPU1_P2P2_DN<20>")
	)
	(segment
		(start 235.293154 -366.81664)
		(end 234.470956 -367.392458)
		(width 0.14732)
		(layer "In6.Cu")
		(net "UPI_CPU0_CPU1_P2P2_DN<20>")
	)
	(segment
		(start 314.094622 -312.453528)
		(end 313.325764 -312.772044)
		(width 0.14732)
		(layer "In6.Cu")
		(net "UPI_CPU0_CPU1_P2P2_DN<20>")
	)
	(segment
		(start 199.05853 -368.96167)
		(end 159.066992 -376.01271)
		(width 0.14732)
		(layer "In6.Cu")
		(net "UPI_CPU0_CPU1_P2P2_DN<20>")
	)
	(segment
		(start 244.616986 -359.231438)
		(end 241.092228 -362.755942)
		(width 0.14732)
		(layer "In6.Cu")
		(net "UPI_CPU0_CPU1_P2P2_DN<20>")
	)
	(segment
		(start 310.123078 -314.676028)
		(end 307.7972 -314.676028)
		(width 0.14732)
		(layer "In6.Cu")
		(net "UPI_CPU0_CPU1_P2P2_DN<20>")
	)
	(segment
		(start 261.991348 -343.121488)
		(end 261.991348 -343.556844)
		(width 0.14732)
		(layer "In6.Cu")
		(net "UPI_CPU0_CPU1_P2P2_DN<20>")
	)
	(segment
		(start 107.238292 -285.171896)
		(end 107.247182 -285.166816)
		(width 0.0889)
		(layer "In6.Cu")
		(net "UPI_CPU0_CPU1_P2P2_DN<20>")
	)
	(segment
		(start 240.319306 -363.297216)
		(end 239.8903 -363.22127)
		(width 0.14732)
		(layer "In6.Cu")
		(net "UPI_CPU0_CPU1_P2P2_DN<20>")
	)
	(segment
		(start 261.463282 -342.593422)
		(end 261.991348 -343.121488)
		(width 0.14732)
		(layer "In6.Cu")
		(net "UPI_CPU0_CPU1_P2P2_DN<20>")
	)
	(segment
		(start 335.068164 -286.151066)
		(end 335.059274 -286.156146)
		(width 0.0889)
		(layer "In6.Cu")
		(net "UPI_CPU0_CPU1_P2P2_DN<20>")
	)
	(segment
		(start 260.449568 -343.607136)
		(end 260.241288 -343.607136)
		(width 0.14732)
		(layer "In6.Cu")
		(net "UPI_CPU0_CPU1_P2P2_DN<20>")
	)
	(segment
		(start 106.485944 -286.475424)
		(end 106.485944 -286.4612)
		(width 0.0889)
		(layer "In6.Cu")
		(net "UPI_CPU0_CPU1_P2P2_DN<20>")
	)
	(segment
		(start 335.469992 -288.642552)
		(end 335.233772 -288.878518)
		(width 0.0889)
		(layer "In6.Cu")
		(net "UPI_CPU0_CPU1_P2P2_DN<20>")
	)
	(segment
		(start 263.630156 -341.918036)
		(end 263.051798 -342.496394)
		(width 0.14732)
		(layer "In6.Cu")
		(net "UPI_CPU0_CPU1_P2P2_DN<20>")
	)
	(segment
		(start 303.99355 -317.573406)
		(end 303.827942 -317.895478)
		(width 0.14732)
		(layer "In6.Cu")
		(net "UPI_CPU0_CPU1_P2P2_DN<20>")
	)
	(segment
		(start 107.253278 -276.392894)
		(end 107.23245 -276.380702)
		(width 0.0889)
		(layer "In6.Cu")
		(net "UPI_CPU0_CPU1_P2P2_DN<20>")
	)
	(segment
		(start 108.365544 -276.718522)
		(end 108.365544 -276.69998)
		(width 0.0889)
		(layer "In6.Cu")
		(net "UPI_CPU0_CPU1_P2P2_DN<20>")
	)
	(segment
		(start 253.686056 -350.162368)
		(end 249.333512 -354.514912)
		(width 0.14732)
		(layer "In6.Cu")
		(net "UPI_CPU0_CPU1_P2P2_DN<20>")
	)
	(segment
		(start 263.051798 -342.496394)
		(end 262.616442 -342.496394)
		(width 0.14732)
		(layer "In6.Cu")
		(net "UPI_CPU0_CPU1_P2P2_DN<20>")
	)
	(segment
		(start 278.517604 -328.11339)
		(end 277.939246 -328.691748)
		(width 0.14732)
		(layer "In6.Cu")
		(net "UPI_CPU0_CPU1_P2P2_DN<20>")
	)
	(segment
		(start 278.517604 -327.678034)
		(end 278.517604 -328.11339)
		(width 0.14732)
		(layer "In6.Cu")
		(net "UPI_CPU0_CPU1_P2P2_DN<20>")
	)
	(segment
		(start 256.06121 -349.051626)
		(end 255.533144 -348.52356)
		(width 0.14732)
		(layer "In6.Cu")
		(net "UPI_CPU0_CPU1_P2P2_DN<20>")
	)
	(segment
		(start 335.820512 -288.09315)
		(end 335.820512 -288.11728)
		(width 0.0889)
		(layer "In6.Cu")
		(net "UPI_CPU0_CPU1_P2P2_DN<20>")
	)
	(segment
		(start 257.700018 -347.412818)
		(end 257.171952 -346.884752)
		(width 0.14732)
		(layer "In6.Cu")
		(net "UPI_CPU0_CPU1_P2P2_DN<20>")
	)
	(segment
		(start 104.73182 -292.463728)
		(end 104.732074 -292.463474)
		(width 0.14732)
		(layer "In6.Cu")
		(net "UPI_CPU0_CPU1_P2P2_DN<20>")
	)
	(segment
		(start 253.894336 -350.162368)
		(end 253.686056 -350.162368)
		(width 0.14732)
		(layer "In6.Cu")
		(net "UPI_CPU0_CPU1_P2P2_DN<20>")
	)
	(segment
		(start 335.350612 -287.279334)
		(end 335.350612 -287.28924)
		(width 0.0889)
		(layer "In6.Cu")
		(net "UPI_CPU0_CPU1_P2P2_DN<20>")
	)
	(segment
		(start 104.773984 -291.563044)
		(end 105.546144 -290.790884)
		(width 0.0889)
		(layer "In6.Cu")
		(net "UPI_CPU0_CPU1_P2P2_DN<20>")
	)
	(segment
		(start 232.357422 -367.452402)
		(end 232.107232 -367.809018)
		(width 0.14732)
		(layer "In6.Cu")
		(net "UPI_CPU0_CPU1_P2P2_DN<20>")
	)
	(segment
		(start 263.630156 -341.48268)
		(end 263.630156 -341.918036)
		(width 0.14732)
		(layer "In6.Cu")
		(net "UPI_CPU0_CPU1_P2P2_DN<20>")
	)
	(segment
		(start 238.42091 -364.626652)
		(end 237.991904 -364.550706)
		(width 0.14732)
		(layer "In6.Cu")
		(net "UPI_CPU0_CPU1_P2P2_DN<20>")
	)
	(segment
		(start 279.602184 -325.963534)
		(end 278.306784 -327.258934)
		(width 0.14732)
		(layer "In6.Cu")
		(net "UPI_CPU0_CPU1_P2P2_DN<20>")
	)
	(segment
		(start 109.305344 -279.964134)
		(end 109.305344 -279.954228)
		(width 0.0889)
		(layer "In6.Cu")
		(net "UPI_CPU0_CPU1_P2P2_DN<20>")
	)
	(segment
		(start 335.255362 -286.475424)
		(end 335.568036 -286.475424)
		(width 0.0889)
		(layer "In6.Cu")
		(net "UPI_CPU0_CPU1_P2P2_DN<20>")
	)
	(segment
		(start 105.546144 -288.11728)
		(end 105.546144 -288.103056)
		(width 0.0889)
		(layer "In6.Cu")
		(net "UPI_CPU0_CPU1_P2P2_DN<20>")
	)
	(segment
		(start 311.189116 -314.234322)
		(end 310.123078 -314.676028)
		(width 0.14732)
		(layer "In6.Cu")
		(net "UPI_CPU0_CPU1_P2P2_DN<20>")
	)
	(segment
		(start 304.57013 -317.048642)
		(end 303.99355 -317.573406)
		(width 0.14732)
		(layer "In6.Cu")
		(net "UPI_CPU0_CPU1_P2P2_DN<20>")
	)
	(segment
		(start 329.863958 -299.762672)
		(end 317.173102 -312.453528)
		(width 0.14732)
		(layer "In6.Cu")
		(net "UPI_CPU0_CPU1_P2P2_DN<20>")
	)
	(segment
		(start 234.851448 -364.362746)
		(end 234.367578 -364.701582)
		(width 0.14732)
		(layer "In6.Cu")
		(net "UPI_CPU0_CPU1_P2P2_DN<20>")
	)
	(segment
		(start 126.019306 -376.01271)
		(end 99.248214 -372.04015)
		(width 0.14732)
		(layer "In6.Cu")
		(net "UPI_CPU0_CPU1_P2P2_DN<20>")
	)
	(segment
		(start 248.02592 -357.127048)
		(end 248.02592 -357.562404)
		(width 0.14732)
		(layer "In6.Cu")
		(net "UPI_CPU0_CPU1_P2P2_DN<20>")
	)
	(segment
		(start 238.128302 -362.24718)
		(end 239.165892 -363.728762)
		(width 0.14732)
		(layer "In6.Cu")
		(net "UPI_CPU0_CPU1_P2P2_DN<20>")
	)
	(segment
		(start 297.047158 -325.079868)
		(end 287.363408 -325.079868)
		(width 0.14732)
		(layer "In6.Cu")
		(net "UPI_CPU0_CPU1_P2P2_DN<20>")
	)
	(segment
		(start 333.746856 -290.656264)
		(end 333.610458 -290.656264)
		(width 0.0889)
		(layer "In6.Cu")
		(net "UPI_CPU0_CPU1_P2P2_DN<20>")
	)
	(segment
		(start 109.591094 -278.827992)
		(end 109.590332 -278.827484)
		(width 0.0889)
		(layer "In6.Cu")
		(net "UPI_CPU0_CPU1_P2P2_DN<20>")
	)
	(segment
		(start 255.436116 -350.112076)
		(end 254.857758 -350.690434)
		(width 0.14732)
		(layer "In6.Cu")
		(net "UPI_CPU0_CPU1_P2P2_DN<20>")
	)
	(segment
		(start 73.603104 -330.124816)
		(end 74.315828 -327.545954)
		(width 0.14732)
		(layer "In6.Cu")
		(net "UPI_CPU0_CPU1_P2P2_DN<20>")
	)
	(segment
		(start 237.851696 -366.429544)
		(end 237.18266 -366.898682)
		(width 0.14732)
		(layer "In6.Cu")
		(net "UPI_CPU0_CPU1_P2P2_DN<20>")
	)
	(segment
		(start 311.189878 -314.234068)
		(end 311.189116 -314.234322)
		(width 0.14732)
		(layer "In6.Cu")
		(net "UPI_CPU0_CPU1_P2P2_DN<20>")
	)
	(segment
		(start 247.012206 -358.140762)
		(end 246.464074 -357.59263)
		(width 0.14732)
		(layer "In6.Cu")
		(net "UPI_CPU0_CPU1_P2P2_DN<20>")
	)
	(segment
		(start 245.170706 -359.576878)
		(end 244.825266 -359.231438)
		(width 0.14732)
		(layer "In6.Cu")
		(net "UPI_CPU0_CPU1_P2P2_DN<20>")
	)
	(segment
		(start 303.6951 -319.02781)
		(end 302.635666 -321.780154)
		(width 0.14732)
		(layer "In6.Cu")
		(net "UPI_CPU0_CPU1_P2P2_DN<20>")
	)
	(segment
		(start 232.867962 -366.098328)
		(end 232.286048 -366.200944)
		(width 0.14732)
		(layer "In6.Cu")
		(net "UPI_CPU0_CPU1_P2P2_DN<20>")
	)
	(segment
		(start 300.953932 -323.461888)
		(end 297.047158 -325.079868)
		(width 0.14732)
		(layer "In6.Cu")
		(net "UPI_CPU0_CPU1_P2P2_DN<20>")
	)
	(segment
		(start 263.10209 -340.746334)
		(end 263.10209 -340.954614)
		(width 0.14732)
		(layer "In6.Cu")
		(net "UPI_CPU0_CPU1_P2P2_DN<20>")
	)
	(arc
		(start 107.717082 -284.353)
		(mid 107.847996 -284.21664)
		(end 107.895644 -284.033722)
		(width 0.0889)
		(layer "In6.Cu")
		(net "UPI_CPU0_CPU1_P2P2_DN<20>")
	)
	(arc
		(start 107.425744 -284.847538)
		(mid 107.49966 -284.568036)
		(end 107.702096 -284.361636)
		(width 0.0889)
		(layer "In6.Cu")
		(net "UPI_CPU0_CPU1_P2P2_DN<20>")
	)
	(arc
		(start 109.77499 -277.534624)
		(mid 109.775235 -277.525228)
		(end 109.775244 -277.515828)
		(width 0.0889)
		(layer "In6.Cu")
		(net "UPI_CPU0_CPU1_P2P2_DN<20>")
	)
	(arc
		(start 335.62544 -286.41802)
		(mid 335.567284 -286.267907)
		(end 335.45145 -286.156146)
		(width 0.0889)
		(layer "In6.Cu")
		(net "UPI_CPU0_CPU1_P2P2_DN<20>")
	)
	(arc
		(start 109.775244 -277.515828)
		(mid 109.725991 -277.336628)
		(end 109.596682 -277.203154)
		(width 0.0889)
		(layer "In6.Cu")
		(net "UPI_CPU0_CPU1_P2P2_DN<20>")
	)
	(arc
		(start 108.835444 -280.759662)
		(mid 108.915606 -280.487473)
		(end 109.117892 -280.288492)
		(width 0.0889)
		(layer "In6.Cu")
		(net "UPI_CPU0_CPU1_P2P2_DN<20>")
	)
	(arc
		(start 108.648246 -282.730194)
		(mid 108.783179 -282.59684)
		(end 108.835444 -282.414472)
		(width 0.0889)
		(layer "In6.Cu")
		(net "UPI_CPU0_CPU1_P2P2_DN<20>")
	)
	(arc
		(start 335.538064 -287.613598)
		(mid 335.742399 -287.816203)
		(end 335.820512 -288.09315)
		(width 0.0889)
		(layer "In6.Cu")
		(net "UPI_CPU0_CPU1_P2P2_DN<20>")
	)
	(arc
		(start 106.955844 -285.651448)
		(mid 107.033955 -285.374499)
		(end 107.238292 -285.171896)
		(width 0.0889)
		(layer "In6.Cu")
		(net "UPI_CPU0_CPU1_P2P2_DN<20>")
	)
	(arc
		(start 335.44256 -286.151066)
		(mid 335.255362 -286.100923)
		(end 335.068164 -286.151066)
		(width 0.0889)
		(layer "In6.Cu")
		(net "UPI_CPU0_CPU1_P2P2_DN<20>")
	)
	(arc
		(start 108.178346 -276.384258)
		(mid 107.991148 -276.334115)
		(end 107.80395 -276.384258)
		(width 0.0889)
		(layer "In6.Cu")
		(net "UPI_CPU0_CPU1_P2P2_DN<20>")
	)
	(arc
		(start 107.23245 -276.380702)
		(mid 107.052798 -276.211266)
		(end 106.962448 -275.981414)
		(width 0.0889)
		(layer "In6.Cu")
		(net "UPI_CPU0_CPU1_P2P2_DN<20>")
	)
	(arc
		(start 106.485944 -286.4612)
		(mid 106.565163 -286.186515)
		(end 106.768646 -285.985712)
		(width 0.0889)
		(layer "In6.Cu")
		(net "UPI_CPU0_CPU1_P2P2_DN<20>")
	)
	(arc
		(start 105.837736 -287.608518)
		(mid 105.96865 -287.472158)
		(end 106.016298 -287.28924)
		(width 0.0889)
		(layer "In6.Cu")
		(net "UPI_CPU0_CPU1_P2P2_DN<20>")
	)
	(arc
		(start 109.126782 -280.283412)
		(mid 109.257696 -280.147052)
		(end 109.305344 -279.964134)
		(width 0.0889)
		(layer "In6.Cu")
		(net "UPI_CPU0_CPU1_P2P2_DN<20>")
	)
	(arc
		(start 109.305344 -279.954228)
		(mid 109.383455 -279.677279)
		(end 109.587792 -279.474676)
		(width 0.0889)
		(layer "In6.Cu")
		(net "UPI_CPU0_CPU1_P2P2_DN<20>")
	)
	(arc
		(start 334.880966 -286.463232)
		(mid 334.880721 -286.472628)
		(end 334.880712 -286.482028)
		(width 0.0889)
		(layer "In6.Cu")
		(net "UPI_CPU0_CPU1_P2P2_DN<20>")
	)
	(arc
		(start 105.546144 -288.103056)
		(mid 105.620135 -287.82349)
		(end 105.82275 -287.617154)
		(width 0.0889)
		(layer "In6.Cu")
		(net "UPI_CPU0_CPU1_P2P2_DN<20>")
	)
	(arc
		(start 107.895644 -284.033722)
		(mid 107.967879 -283.757198)
		(end 108.166154 -283.551376)
		(width 0.0889)
		(layer "In6.Cu")
		(net "UPI_CPU0_CPU1_P2P2_DN<20>")
	)
	(arc
		(start 108.365544 -283.205682)
		(mid 108.444763 -282.930997)
		(end 108.648246 -282.730194)
		(width 0.0889)
		(layer "In6.Cu")
		(net "UPI_CPU0_CPU1_P2P2_DN<20>")
	)
	(arc
		(start 107.247182 -285.166816)
		(mid 107.378096 -285.030456)
		(end 107.425744 -284.847538)
		(width 0.0889)
		(layer "In6.Cu")
		(net "UPI_CPU0_CPU1_P2P2_DN<20>")
	)
	(arc
		(start 109.596682 -277.84171)
		(mid 109.724575 -277.710648)
		(end 109.77499 -277.534624)
		(width 0.0889)
		(layer "In6.Cu")
		(net "UPI_CPU0_CPU1_P2P2_DN<20>")
	)
	(arc
		(start 334.880712 -286.482028)
		(mid 334.929965 -286.661228)
		(end 335.059274 -286.794702)
		(width 0.0889)
		(layer "In6.Cu")
		(net "UPI_CPU0_CPU1_P2P2_DN<20>")
	)
	(arc
		(start 108.647992 -277.198074)
		(mid 108.443657 -276.995469)
		(end 108.365544 -276.718522)
		(width 0.0889)
		(layer "In6.Cu")
		(net "UPI_CPU0_CPU1_P2P2_DN<20>")
	)
	(arc
		(start 109.587792 -277.198074)
		(mid 109.400594 -277.147931)
		(end 109.213396 -277.198074)
		(width 0.0889)
		(layer "In6.Cu")
		(net "UPI_CPU0_CPU1_P2P2_DN<20>")
	)
	(arc
		(start 108.648246 -281.102562)
		(mid 108.783179 -280.969208)
		(end 108.835444 -280.78684)
		(width 0.0889)
		(layer "In6.Cu")
		(net "UPI_CPU0_CPU1_P2P2_DN<20>")
	)
	(arc
		(start 105.831894 -289.277806)
		(mid 105.94129 -289.193709)
		(end 106.016298 -289.077908)
		(width 0.0889)
		(layer "In6.Cu")
		(net "UPI_CPU0_CPU1_P2P2_DN<20>")
	)
	(arc
		(start 105.56113 -289.570922)
		(mid 105.671387 -289.401162)
		(end 105.831894 -289.277806)
		(width 0.0889)
		(layer "In6.Cu")
		(net "UPI_CPU0_CPU1_P2P2_DN<20>")
	)
	(arc
		(start 106.016298 -287.273746)
		(mid 106.095668 -287.000012)
		(end 106.298492 -286.799782)
		(width 0.0889)
		(layer "In6.Cu")
		(net "UPI_CPU0_CPU1_P2P2_DN<20>")
	)
	(arc
		(start 335.350612 -287.28924)
		(mid 335.398291 -287.47214)
		(end 335.529174 -287.608518)
		(width 0.0889)
		(layer "In6.Cu")
		(net "UPI_CPU0_CPU1_P2P2_DN<20>")
	)
	(arc
		(start 108.64215 -282.077922)
		(mid 108.3657 -281.59202)
		(end 108.64215 -281.106118)
		(width 0.0889)
		(layer "In6.Cu")
		(net "UPI_CPU0_CPU1_P2P2_DN<20>")
	)
	(arc
		(start 109.305344 -278.31796)
		(mid 109.385506 -278.045771)
		(end 109.587792 -277.84679)
		(width 0.0889)
		(layer "In6.Cu")
		(net "UPI_CPU0_CPU1_P2P2_DN<20>")
	)
	(arc
		(start 335.53781 -288.592768)
		(mid 335.510481 -288.609915)
		(end 335.484724 -288.629344)
		(width 0.0889)
		(layer "In6.Cu")
		(net "UPI_CPU0_CPU1_P2P2_DN<20>")
	)
	(arc
		(start 105.546144 -289.609784)
		(mid 105.5533 -289.590223)
		(end 105.56113 -289.570922)
		(width 0.0889)
		(layer "In6.Cu")
		(net "UPI_CPU0_CPU1_P2P2_DN<20>")
	)
	(arc
		(start 335.484724 -288.62909)
		(mid 335.477196 -288.635773)
		(end 335.469992 -288.642806)
		(width 0.0889)
		(layer "In6.Cu")
		(net "UPI_CPU0_CPU1_P2P2_DN<20>")
	)
	(arc
		(start 335.068164 -286.799782)
		(mid 335.272499 -287.002387)
		(end 335.350612 -287.279334)
		(width 0.0889)
		(layer "In6.Cu")
		(net "UPI_CPU0_CPU1_P2P2_DN<20>")
	)
	(arc
		(start 105.828846 -288.592768)
		(mid 105.625365 -288.391964)
		(end 105.546144 -288.11728)
		(width 0.0889)
		(layer "In6.Cu")
		(net "UPI_CPU0_CPU1_P2P2_DN<20>")
	)
	(arc
		(start 335.820512 -288.11728)
		(mid 335.741293 -288.391965)
		(end 335.53781 -288.592768)
		(width 0.0889)
		(layer "In6.Cu")
		(net "UPI_CPU0_CPU1_P2P2_DN<20>")
	)
	(arc
		(start 106.016298 -288.917126)
		(mid 105.968619 -288.734226)
		(end 105.837736 -288.597848)
		(width 0.0889)
		(layer "In6.Cu")
		(net "UPI_CPU0_CPU1_P2P2_DN<20>")
	)
	(arc
		(start 109.213396 -277.198074)
		(mid 108.930694 -277.27385)
		(end 108.647992 -277.198074)
		(width 0.0889)
		(layer "In6.Cu")
		(net "UPI_CPU0_CPU1_P2P2_DN<20>")
	)
	(arc
		(start 108.365544 -276.69998)
		(mid 108.313274 -276.517615)
		(end 108.178346 -276.384258)
		(width 0.0889)
		(layer "In6.Cu")
		(net "UPI_CPU0_CPU1_P2P2_DN<20>")
	)
	(arc
		(start 106.768646 -285.985712)
		(mid 106.903579 -285.852358)
		(end 106.955844 -285.66999)
		(width 0.0889)
		(layer "In6.Cu")
		(net "UPI_CPU0_CPU1_P2P2_DN<20>")
	)
	(arc
		(start 107.80395 -276.384258)
		(mid 107.529751 -276.460093)
		(end 107.253278 -276.392894)
		(width 0.0889)
		(layer "In6.Cu")
		(net "UPI_CPU0_CPU1_P2P2_DN<20>")
	)
	(arc
		(start 109.587792 -278.82596)
		(mid 109.383457 -278.623355)
		(end 109.305344 -278.346408)
		(width 0.0889)
		(layer "In6.Cu")
		(net "UPI_CPU0_CPU1_P2P2_DN<20>")
	)
	(arc
		(start 335.059274 -286.156146)
		(mid 334.931381 -286.287208)
		(end 334.880966 -286.463232)
		(width 0.0889)
		(layer "In6.Cu")
		(net "UPI_CPU0_CPU1_P2P2_DN<20>")
	)
	(arc
		(start 106.307382 -286.794702)
		(mid 106.438296 -286.658342)
		(end 106.485944 -286.475424)
		(width 0.0889)
		(layer "In6.Cu")
		(net "UPI_CPU0_CPU1_P2P2_DN<20>")
	)
	(arc
		(start 108.835444 -282.3972)
		(mid 108.783174 -282.214835)
		(end 108.648246 -282.081478)
		(width 0.0889)
		(layer "In6.Cu")
		(net "UPI_CPU0_CPU1_P2P2_DN<20>")
	)
	(arc
		(start 109.596682 -279.469596)
		(mid 109.775279 -279.150318)
		(end 109.596682 -278.83104)
		(width 0.0889)
		(layer "In6.Cu")
		(net "UPI_CPU0_CPU1_P2P2_DN<20>")
	)
	(arc
		(start 106.962448 -275.981414)
		(mid 106.960953 -275.971013)
		(end 106.959654 -275.960586)
		(width 0.0889)
		(layer "In6.Cu")
		(net "UPI_CPU0_CPU1_P2P2_DN<20>")
	)
	(arc
		(start 108.178346 -283.544264)
		(mid 108.313279 -283.41091)
		(end 108.365544 -283.228542)
		(width 0.0889)
		(layer "In6.Cu")
		(net "UPI_CPU0_CPU1_P2P2_DN<20>")
	)
	(segment
		(start 87.315294 -281.05608)
		(end 87.315294 -281.591766)
		(width 0.13208)
		(layer "F.Cu")
		(net "UPI_CPU0_CPU1_P2P2_DN<1>")
	)
	(segment
		(start 87.315294 -281.591766)
		(end 87.315548 -281.59202)
		(width 0.13208)
		(layer "F.Cu")
		(net "UPI_CPU0_CPU1_P2P2_DN<1>")
	)
	(segment
		(start 354.521516 -280.77795)
		(end 354.521262 -280.778204)
		(width 0.13208)
		(layer "F.Cu")
		(net "UPI_CPU0_CPU1_P2P2_DN<1>")
	)
	(segment
		(start 354.521516 -280.242264)
		(end 354.521516 -280.77795)
		(width 0.13208)
		(layer "F.Cu")
		(net "UPI_CPU0_CPU1_P2P2_DN<1>")
	)
	(segment
		(start 53.332634 -323.045582)
		(end 53.805582 -322.161916)
		(width 0.14732)
		(layer "In6.Cu")
		(net "UPI_CPU0_CPU1_P2P2_DN<1>")
	)
	(segment
		(start 340.901782 -310.66105)
		(end 322.88607 -328.676762)
		(width 0.14732)
		(layer "In6.Cu")
		(net "UPI_CPU0_CPU1_P2P2_DN<1>")
	)
	(segment
		(start 353.592892 -293.896796)
		(end 353.592892 -294.072056)
		(width 0.0889)
		(layer "In6.Cu")
		(net "UPI_CPU0_CPU1_P2P2_DN<1>")
	)
	(segment
		(start 354.71354 -291.279072)
		(end 354.589588 -291.403024)
		(width 0.0889)
		(layer "In6.Cu")
		(net "UPI_CPU0_CPU1_P2P2_DN<1>")
	)
	(segment
		(start 355.64826 -282.081478)
		(end 355.649276 -282.081986)
		(width 0.0889)
		(layer "In6.Cu")
		(net "UPI_CPU0_CPU1_P2P2_DN<1>")
	)
	(segment
		(start 77.44841 -299.68571)
		(end 77.757274 -299.376846)
		(width 0.14732)
		(layer "In6.Cu")
		(net "UPI_CPU0_CPU1_P2P2_DN<1>")
	)
	(segment
		(start 354.46589 -291.667184)
		(end 354.325428 -291.667184)
		(width 0.0889)
		(layer "In6.Cu")
		(net "UPI_CPU0_CPU1_P2P2_DN<1>")
	)
	(segment
		(start 67.911726 -309.222394)
		(end 76.966826 -300.167294)
		(width 0.14732)
		(layer "In6.Cu")
		(net "UPI_CPU0_CPU1_P2P2_DN<1>")
	)
	(segment
		(start 355.177852 -281.267154)
		(end 355.178614 -281.267662)
		(width 0.0889)
		(layer "In6.Cu")
		(net "UPI_CPU0_CPU1_P2P2_DN<1>")
	)
	(segment
		(start 353.79025 -292.342824)
		(end 353.691952 -292.441122)
		(width 0.0889)
		(layer "In6.Cu")
		(net "UPI_CPU0_CPU1_P2P2_DN<1>")
	)
	(segment
		(start 85.047836 -289.916362)
		(end 85.047836 -285.98876)
		(width 0.0889)
		(layer "In6.Cu")
		(net "UPI_CPU0_CPU1_P2P2_DN<1>")
	)
	(segment
		(start 355.242114 -290.89096)
		(end 355.101652 -290.89096)
		(width 0.0889)
		(layer "In6.Cu")
		(net "UPI_CPU0_CPU1_P2P2_DN<1>")
	)
	(segment
		(start 78.238858 -298.895262)
		(end 80.929226 -296.204894)
		(width 0.14732)
		(layer "In6.Cu")
		(net "UPI_CPU0_CPU1_P2P2_DN<1>")
	)
	(segment
		(start 354.208588 -280.778204)
		(end 354.151184 -280.7208)
		(width 0.0889)
		(layer "In6.Cu")
		(net "UPI_CPU0_CPU1_P2P2_DN<1>")
	)
	(segment
		(start 85.047836 -285.98876)
		(end 85.640418 -285.396178)
		(width 0.0889)
		(layer "In6.Cu")
		(net "UPI_CPU0_CPU1_P2P2_DN<1>")
	)
	(segment
		(start 353.592892 -293.523416)
		(end 353.691952 -293.622476)
		(width 0.0889)
		(layer "In6.Cu")
		(net "UPI_CPU0_CPU1_P2P2_DN<1>")
	)
	(segment
		(start 322.88607 -328.676762)
		(end 321.672966 -331.605382)
		(width 0.14732)
		(layer "In6.Cu")
		(net "UPI_CPU0_CPU1_P2P2_DN<1>")
	)
	(segment
		(start 353.650042 -294.800528)
		(end 353.649788 -294.800782)
		(width 0.14732)
		(layer "In6.Cu")
		(net "UPI_CPU0_CPU1_P2P2_DN<1>")
	)
	(segment
		(start 354.201476 -291.791136)
		(end 354.201476 -291.931598)
		(width 0.0889)
		(layer "In6.Cu")
		(net "UPI_CPU0_CPU1_P2P2_DN<1>")
	)
	(segment
		(start 51.6382 -329.314048)
		(end 51.6382 -328.945748)
		(width 0.14732)
		(layer "In6.Cu")
		(net "UPI_CPU0_CPU1_P2P2_DN<1>")
	)
	(segment
		(start 354.854002 -291.279072)
		(end 354.71354 -291.279072)
		(width 0.0889)
		(layer "In6.Cu")
		(net "UPI_CPU0_CPU1_P2P2_DN<1>")
	)
	(segment
		(start 57.542938 -356.406196)
		(end 57.542938 -336.567526)
		(width 0.14732)
		(layer "In6.Cu")
		(net "UPI_CPU0_CPU1_P2P2_DN<1>")
	)
	(segment
		(start 355.178614 -281.267662)
		(end 355.180138 -281.268424)
		(width 0.0889)
		(layer "In6.Cu")
		(net "UPI_CPU0_CPU1_P2P2_DN<1>")
	)
	(segment
		(start 54.03723 -316.792102)
		(end 54.212744 -316.616588)
		(width 0.14732)
		(layer "In6.Cu")
		(net "UPI_CPU0_CPU1_P2P2_DN<1>")
	)
	(segment
		(start 355.18725 -285.166816)
		(end 355.17836 -285.171896)
		(width 0.0889)
		(layer "In6.Cu")
		(net "UPI_CPU0_CPU1_P2P2_DN<1>")
	)
	(segment
		(start 353.402646 -299.68063)
		(end 353.213416 -299.759116)
		(width 0.14732)
		(layer "In6.Cu")
		(net "UPI_CPU0_CPU1_P2P2_DN<1>")
	)
	(segment
		(start 56.829198 -334.846422)
		(end 55.842154 -333.686658)
		(width 0.14732)
		(layer "In6.Cu")
		(net "UPI_CPU0_CPU1_P2P2_DN<1>")
	)
	(segment
		(start 353.592892 -292.740842)
		(end 353.592892 -292.916102)
		(width 0.0889)
		(layer "In6.Cu")
		(net "UPI_CPU0_CPU1_P2P2_DN<1>")
	)
	(segment
		(start 51.6382 -328.287888)
		(end 51.6382 -325.475854)
		(width 0.14732)
		(layer "In6.Cu")
		(net "UPI_CPU0_CPU1_P2P2_DN<1>")
	)
	(segment
		(start 73.520808 -378.76226)
		(end 73.454768 -378.602748)
		(width 0.14732)
		(layer "In6.Cu")
		(net "UPI_CPU0_CPU1_P2P2_DN<1>")
	)
	(segment
		(start 353.691952 -293.015162)
		(end 353.691952 -293.249096)
		(width 0.0889)
		(layer "In6.Cu")
		(net "UPI_CPU0_CPU1_P2P2_DN<1>")
	)
	(segment
		(start 353.072446 -300.099476)
		(end 353.150678 -300.288706)
		(width 0.14732)
		(layer "In6.Cu")
		(net "UPI_CPU0_CPU1_P2P2_DN<1>")
	)
	(segment
		(start 279.620472 -372.057168)
		(end 268.850364 -382.827276)
		(width 0.14732)
		(layer "In6.Cu")
		(net "UPI_CPU0_CPU1_P2P2_DN<1>")
	)
	(segment
		(start 51.6382 -325.475854)
		(end 51.78298 -325.331074)
		(width 0.14732)
		(layer "In6.Cu")
		(net "UPI_CPU0_CPU1_P2P2_DN<1>")
	)
	(segment
		(start 353.691952 -293.797736)
		(end 353.592892 -293.896796)
		(width 0.0889)
		(layer "In6.Cu")
		(net "UPI_CPU0_CPU1_P2P2_DN<1>")
	)
	(segment
		(start 353.914202 -292.07841)
		(end 353.79025 -292.202362)
		(width 0.0889)
		(layer "In6.Cu")
		(net "UPI_CPU0_CPU1_P2P2_DN<1>")
	)
	(segment
		(start 77.92974 -299.376846)
		(end 78.238858 -299.067728)
		(width 0.14732)
		(layer "In6.Cu")
		(net "UPI_CPU0_CPU1_P2P2_DN<1>")
	)
	(segment
		(start 355.18725 -286.794702)
		(end 355.17836 -286.799782)
		(width 0.0889)
		(layer "In6.Cu")
		(net "UPI_CPU0_CPU1_P2P2_DN<1>")
	)
	(segment
		(start 53.917596 -317.0809)
		(end 54.03723 -316.792102)
		(width 0.14732)
		(layer "In6.Cu")
		(net "UPI_CPU0_CPU1_P2P2_DN<1>")
	)
	(segment
		(start 51.78298 -324.962774)
		(end 51.6382 -324.817994)
		(width 0.14732)
		(layer "In6.Cu")
		(net "UPI_CPU0_CPU1_P2P2_DN<1>")
	)
	(segment
		(start 268.850364 -382.827276)
		(end 268.849856 -382.827276)
		(width 0.14732)
		(layer "In6.Cu")
		(net "UPI_CPU0_CPU1_P2P2_DN<1>")
	)
	(segment
		(start 355.180138 -281.268424)
		(end 355.187504 -281.272742)
		(width 0.0889)
		(layer "In6.Cu")
		(net "UPI_CPU0_CPU1_P2P2_DN<1>")
	)
	(segment
		(start 87.159084 -281.863038)
		(end 87.315548 -281.59202)
		(width 0.0889)
		(layer "In6.Cu")
		(net "UPI_CPU0_CPU1_P2P2_DN<1>")
	)
	(segment
		(start 51.78298 -328.432668)
		(end 51.6382 -328.287888)
		(width 0.14732)
		(layer "In6.Cu")
		(net "UPI_CPU0_CPU1_P2P2_DN<1>")
	)
	(segment
		(start 54.212744 -316.616588)
		(end 55.955946 -315.894466)
		(width 0.14732)
		(layer "In6.Cu")
		(net "UPI_CPU0_CPU1_P2P2_DN<1>")
	)
	(segment
		(start 352.84918 -301.01667)
		(end 344.932254 -308.991508)
		(width 0.14732)
		(layer "In6.Cu")
		(net "UPI_CPU0_CPU1_P2P2_DN<1>")
	)
	(segment
		(start 355.17836 -287.778698)
		(end 355.18725 -287.783778)
		(width 0.0889)
		(layer "In6.Cu")
		(net "UPI_CPU0_CPU1_P2P2_DN<1>")
	)
	(segment
		(start 93.108526 -386.874512)
		(end 73.520808 -378.76226)
		(width 0.14732)
		(layer "In6.Cu")
		(net "UPI_CPU0_CPU1_P2P2_DN<1>")
	)
	(segment
		(start 51.6382 -328.945748)
		(end 51.78298 -328.800968)
		(width 0.14732)
		(layer "In6.Cu")
		(net "UPI_CPU0_CPU1_P2P2_DN<1>")
	)
	(segment
		(start 355.18725 -288.422334)
		(end 355.187504 -288.422334)
		(width 0.0889)
		(layer "In6.Cu")
		(net "UPI_CPU0_CPU1_P2P2_DN<1>")
	)
	(segment
		(start 310.926988 -342.35136)
		(end 286.885888 -342.35136)
		(width 0.14732)
		(layer "In6.Cu")
		(net "UPI_CPU0_CPU1_P2P2_DN<1>")
	)
	(segment
		(start 353.592892 -292.916102)
		(end 353.691952 -293.015162)
		(width 0.0889)
		(layer "In6.Cu")
		(net "UPI_CPU0_CPU1_P2P2_DN<1>")
	)
	(segment
		(start 55.842154 -333.686658)
		(end 55.8419 -333.686404)
		(width 0.14732)
		(layer "In6.Cu")
		(net "UPI_CPU0_CPU1_P2P2_DN<1>")
	)
	(segment
		(start 355.65715 -284.353)
		(end 355.642164 -284.361636)
		(width 0.0889)
		(layer "In6.Cu")
		(net "UPI_CPU0_CPU1_P2P2_DN<1>")
	)
	(segment
		(start 70.09003 -377.341384)
		(end 63.474092 -370.725446)
		(width 0.14732)
		(layer "In6.Cu")
		(net "UPI_CPU0_CPU1_P2P2_DN<1>")
	)
	(segment
		(start 57.542938 -336.567526)
		(end 56.829198 -334.846422)
		(width 0.14732)
		(layer "In6.Cu")
		(net "UPI_CPU0_CPU1_P2P2_DN<1>")
	)
	(segment
		(start 279.620472 -348.50197)
		(end 279.620472 -372.057168)
		(width 0.14732)
		(layer "In6.Cu")
		(net "UPI_CPU0_CPU1_P2P2_DN<1>")
	)
	(segment
		(start 77.44841 -299.858176)
		(end 77.44841 -299.68571)
		(width 0.14732)
		(layer "In6.Cu")
		(net "UPI_CPU0_CPU1_P2P2_DN<1>")
	)
	(segment
		(start 58.739024 -314.034678)
		(end 59.700668 -313.073034)
		(width 0.14732)
		(layer "In6.Cu")
		(net "UPI_CPU0_CPU1_P2P2_DN<1>")
	)
	(segment
		(start 321.672966 -331.605382)
		(end 310.926988 -342.35136)
		(width 0.14732)
		(layer "In6.Cu")
		(net "UPI_CPU0_CPU1_P2P2_DN<1>")
	)
	(segment
		(start 355.365812 -290.767262)
		(end 355.242114 -290.89096)
		(width 0.0889)
		(layer "In6.Cu")
		(net "UPI_CPU0_CPU1_P2P2_DN<1>")
	)
	(segment
		(start 86.940644 -283.2354)
		(end 86.940644 -283.219906)
		(width 0.0889)
		(layer "In6.Cu")
		(net "UPI_CPU0_CPU1_P2P2_DN<1>")
	)
	(segment
		(start 86.64956 -283.714444)
		(end 86.656418 -283.71038)
		(width 0.0889)
		(layer "In6.Cu")
		(net "UPI_CPU0_CPU1_P2P2_DN<1>")
	)
	(segment
		(start 55.362348 -333.123032)
		(end 55.362094 -333.122778)
		(width 0.14732)
		(layer "In6.Cu")
		(net "UPI_CPU0_CPU1_P2P2_DN<1>")
	)
	(segment
		(start 51.6382 -324.817994)
		(end 51.6382 -324.449694)
		(width 0.14732)
		(layer "In6.Cu")
		(net "UPI_CPU0_CPU1_P2P2_DN<1>")
	)
	(segment
		(start 354.201476 -291.931598)
		(end 354.054664 -292.07841)
		(width 0.0889)
		(layer "In6.Cu")
		(net "UPI_CPU0_CPU1_P2P2_DN<1>")
	)
	(segment
		(start 353.691952 -293.249096)
		(end 353.592892 -293.348156)
		(width 0.0889)
		(layer "In6.Cu")
		(net "UPI_CPU0_CPU1_P2P2_DN<1>")
	)
	(segment
		(start 354.589588 -291.403024)
		(end 354.589588 -291.543486)
		(width 0.0889)
		(layer "In6.Cu")
		(net "UPI_CPU0_CPU1_P2P2_DN<1>")
	)
	(segment
		(start 353.650042 -294.767508)
		(end 353.650042 -294.789606)
		(width 0.0889)
		(layer "In6.Cu")
		(net "UPI_CPU0_CPU1_P2P2_DN<1>")
	)
	(segment
		(start 286.885888 -342.35136)
		(end 284.98292 -343.139522)
		(width 0.14732)
		(layer "In6.Cu")
		(net "UPI_CPU0_CPU1_P2P2_DN<1>")
	)
	(segment
		(start 73.454768 -378.602748)
		(end 73.050908 -378.435616)
		(width 0.14732)
		(layer "In6.Cu")
		(net "UPI_CPU0_CPU1_P2P2_DN<1>")
	)
	(segment
		(start 344.932254 -308.991508)
		(end 340.901782 -310.66105)
		(width 0.14732)
		(layer "In6.Cu")
		(net "UPI_CPU0_CPU1_P2P2_DN<1>")
	)
	(segment
		(start 355.366066 -281.59202)
		(end 355.366066 -281.607514)
		(width 0.0889)
		(layer "In6.Cu")
		(net "UPI_CPU0_CPU1_P2P2_DN<1>")
	)
	(segment
		(start 86.940644 -284.857444)
		(end 86.940644 -284.832044)
		(width 0.0889)
		(layer "In6.Cu")
		(net "UPI_CPU0_CPU1_P2P2_DN<1>")
	)
	(segment
		(start 355.266752 -290.144454)
		(end 355.266752 -290.319714)
		(width 0.0889)
		(layer "In6.Cu")
		(net "UPI_CPU0_CPU1_P2P2_DN<1>")
	)
	(segment
		(start 355.101652 -290.89096)
		(end 354.9777 -291.014912)
		(width 0.0889)
		(layer "In6.Cu")
		(net "UPI_CPU0_CPU1_P2P2_DN<1>")
	)
	(segment
		(start 53.917596 -321.596766)
		(end 53.917596 -317.0809)
		(width 0.14732)
		(layer "In6.Cu")
		(net "UPI_CPU0_CPU1_P2P2_DN<1>")
	)
	(segment
		(start 73.050908 -378.435616)
		(end 72.89165 -378.501656)
		(width 0.14732)
		(layer "In6.Cu")
		(net "UPI_CPU0_CPU1_P2P2_DN<1>")
	)
	(segment
		(start 268.849856 -382.827276)
		(end 161.799524 -391.86739)
		(width 0.14732)
		(layer "In6.Cu")
		(net "UPI_CPU0_CPU1_P2P2_DN<1>")
	)
	(segment
		(start 355.649276 -282.081986)
		(end 355.65715 -282.086558)
		(width 0.0889)
		(layer "In6.Cu")
		(net "UPI_CPU0_CPU1_P2P2_DN<1>")
	)
	(segment
		(start 84.511896 -290.512246)
		(end 84.52739 -290.496752)
		(width 0.0889)
		(layer "In6.Cu")
		(net "UPI_CPU0_CPU1_P2P2_DN<1>")
	)
	(segment
		(start 84.52739 -290.436808)
		(end 85.047836 -289.916362)
		(width 0.0889)
		(layer "In6.Cu")
		(net "UPI_CPU0_CPU1_P2P2_DN<1>")
	)
	(segment
		(start 51.78298 -325.331074)
		(end 51.78298 -324.962774)
		(width 0.14732)
		(layer "In6.Cu")
		(net "UPI_CPU0_CPU1_P2P2_DN<1>")
	)
	(segment
		(start 86.65845 -284.35808)
		(end 86.657434 -284.357572)
		(width 0.0889)
		(layer "In6.Cu")
		(net "UPI_CPU0_CPU1_P2P2_DN<1>")
	)
	(segment
		(start 86.657434 -284.357572)
		(end 86.64956 -284.353)
		(width 0.0889)
		(layer "In6.Cu")
		(net "UPI_CPU0_CPU1_P2P2_DN<1>")
	)
	(segment
		(start 54.875176 -332.55077)
		(end 51.6382 -329.314048)
		(width 0.14732)
		(layer "In6.Cu")
		(net "UPI_CPU0_CPU1_P2P2_DN<1>")
	)
	(segment
		(start 64.534542 -310.621172)
		(end 67.911726 -309.222394)
		(width 0.14732)
		(layer "In6.Cu")
		(net "UPI_CPU0_CPU1_P2P2_DN<1>")
	)
	(segment
		(start 353.213416 -299.759116)
		(end 353.072446 -300.099476)
		(width 0.14732)
		(layer "In6.Cu")
		(net "UPI_CPU0_CPU1_P2P2_DN<1>")
	)
	(segment
		(start 55.8419 -333.686404)
		(end 55.362348 -333.123032)
		(width 0.14732)
		(layer "In6.Cu")
		(net "UPI_CPU0_CPU1_P2P2_DN<1>")
	)
	(segment
		(start 87.119206 -282.900628)
		(end 87.128096 -282.895548)
		(width 0.0889)
		(layer "In6.Cu")
		(net "UPI_CPU0_CPU1_P2P2_DN<1>")
	)
	(segment
		(start 355.266752 -290.319714)
		(end 355.365812 -290.418774)
		(width 0.0889)
		(layer "In6.Cu")
		(net "UPI_CPU0_CPU1_P2P2_DN<1>")
	)
	(segment
		(start 161.799524 -391.86739)
		(end 126.76632 -391.86739)
		(width 0.14732)
		(layer "In6.Cu")
		(net "UPI_CPU0_CPU1_P2P2_DN<1>")
	)
	(segment
		(start 354.325428 -291.667184)
		(end 354.201476 -291.791136)
		(width 0.0889)
		(layer "In6.Cu")
		(net "UPI_CPU0_CPU1_P2P2_DN<1>")
	)
	(segment
		(start 77.757274 -299.376846)
		(end 77.92974 -299.376846)
		(width 0.14732)
		(layer "In6.Cu")
		(net "UPI_CPU0_CPU1_P2P2_DN<1>")
	)
	(segment
		(start 355.187504 -288.422334)
		(end 355.179376 -288.426906)
		(width 0.0889)
		(layer "In6.Cu")
		(net "UPI_CPU0_CPU1_P2P2_DN<1>")
	)
	(segment
		(start 353.649788 -299.084238)
		(end 353.402646 -299.68063)
		(width 0.14732)
		(layer "In6.Cu")
		(net "UPI_CPU0_CPU1_P2P2_DN<1>")
	)
	(segment
		(start 284.98292 -343.139522)
		(end 279.620472 -348.50197)
		(width 0.14732)
		(layer "In6.Cu")
		(net "UPI_CPU0_CPU1_P2P2_DN<1>")
	)
	(segment
		(start 353.649788 -294.800782)
		(end 353.649788 -299.084238)
		(width 0.14732)
		(layer "In6.Cu")
		(net "UPI_CPU0_CPU1_P2P2_DN<1>")
	)
	(segment
		(start 353.691952 -294.725598)
		(end 353.650042 -294.767508)
		(width 0.0889)
		(layer "In6.Cu")
		(net "UPI_CPU0_CPU1_P2P2_DN<1>")
	)
	(segment
		(start 355.365812 -290.418774)
		(end 355.365812 -290.767262)
		(width 0.0889)
		(layer "In6.Cu")
		(net "UPI_CPU0_CPU1_P2P2_DN<1>")
	)
	(segment
		(start 78.238858 -299.067728)
		(end 78.238858 -298.895262)
		(width 0.14732)
		(layer "In6.Cu")
		(net "UPI_CPU0_CPU1_P2P2_DN<1>")
	)
	(segment
		(start 86.656418 -283.71038)
		(end 86.65845 -283.709364)
		(width 0.0889)
		(layer "In6.Cu")
		(net "UPI_CPU0_CPU1_P2P2_DN<1>")
	)
	(segment
		(start 52.225956 -323.861938)
		(end 52.721002 -323.65696)
		(width 0.14732)
		(layer "In6.Cu")
		(net "UPI_CPU0_CPU1_P2P2_DN<1>")
	)
	(segment
		(start 353.691952 -292.641782)
		(end 353.592892 -292.740842)
		(width 0.0889)
		(layer "In6.Cu")
		(net "UPI_CPU0_CPU1_P2P2_DN<1>")
	)
	(segment
		(start 87.183214 -281.952192)
		(end 87.159084 -281.863038)
		(width 0.0889)
		(layer "In6.Cu")
		(net "UPI_CPU0_CPU1_P2P2_DN<1>")
	)
	(segment
		(start 77.139292 -300.167294)
		(end 77.44841 -299.858176)
		(width 0.14732)
		(layer "In6.Cu")
		(net "UPI_CPU0_CPU1_P2P2_DN<1>")
	)
	(segment
		(start 84.52739 -290.496752)
		(end 84.52739 -290.436808)
		(width 0.0889)
		(layer "In6.Cu")
		(net "UPI_CPU0_CPU1_P2P2_DN<1>")
	)
	(segment
		(start 355.365812 -290.045394)
		(end 355.266752 -290.144454)
		(width 0.0889)
		(layer "In6.Cu")
		(net "UPI_CPU0_CPU1_P2P2_DN<1>")
	)
	(segment
		(start 353.79025 -292.202362)
		(end 353.79025 -292.342824)
		(width 0.0889)
		(layer "In6.Cu")
		(net "UPI_CPU0_CPU1_P2P2_DN<1>")
	)
	(segment
		(start 353.650042 -294.789606)
		(end 353.650042 -294.800528)
		(width 0.14732)
		(layer "In6.Cu")
		(net "UPI_CPU0_CPU1_P2P2_DN<1>")
	)
	(segment
		(start 354.9777 -291.155374)
		(end 354.854002 -291.279072)
		(width 0.0889)
		(layer "In6.Cu")
		(net "UPI_CPU0_CPU1_P2P2_DN<1>")
	)
	(segment
		(start 353.691952 -294.171116)
		(end 353.691952 -294.725598)
		(width 0.0889)
		(layer "In6.Cu")
		(net "UPI_CPU0_CPU1_P2P2_DN<1>")
	)
	(segment
		(start 53.805582 -322.161916)
		(end 53.917596 -321.596766)
		(width 0.14732)
		(layer "In6.Cu")
		(net "UPI_CPU0_CPU1_P2P2_DN<1>")
	)
	(segment
		(start 87.410798 -282.42006)
		(end 87.410798 -282.39593)
		(width 0.0889)
		(layer "In6.Cu")
		(net "UPI_CPU0_CPU1_P2P2_DN<1>")
	)
	(segment
		(start 355.172518 -281.264106)
		(end 355.177852 -281.267154)
		(width 0.0889)
		(layer "In6.Cu")
		(net "UPI_CPU0_CPU1_P2P2_DN<1>")
	)
	(segment
		(start 59.700668 -313.073034)
		(end 63.767208 -311.388506)
		(width 0.14732)
		(layer "In6.Cu")
		(net "UPI_CPU0_CPU1_P2P2_DN<1>")
	)
	(segment
		(start 353.691952 -292.441122)
		(end 353.691952 -292.641782)
		(width 0.0889)
		(layer "In6.Cu")
		(net "UPI_CPU0_CPU1_P2P2_DN<1>")
	)
	(segment
		(start 353.592892 -294.072056)
		(end 353.691952 -294.171116)
		(width 0.0889)
		(layer "In6.Cu")
		(net "UPI_CPU0_CPU1_P2P2_DN<1>")
	)
	(segment
		(start 356.118414 -283.544264)
		(end 356.106222 -283.551376)
		(width 0.0889)
		(layer "In6.Cu")
		(net "UPI_CPU0_CPU1_P2P2_DN<1>")
	)
	(segment
		(start 51.78298 -328.800968)
		(end 51.78298 -328.432668)
		(width 0.14732)
		(layer "In6.Cu")
		(net "UPI_CPU0_CPU1_P2P2_DN<1>")
	)
	(segment
		(start 82.421222 -292.60292)
		(end 84.511896 -290.512246)
		(width 0.14732)
		(layer "In6.Cu")
		(net "UPI_CPU0_CPU1_P2P2_DN<1>")
	)
	(segment
		(start 354.054664 -292.07841)
		(end 353.914202 -292.07841)
		(width 0.0889)
		(layer "In6.Cu")
		(net "UPI_CPU0_CPU1_P2P2_DN<1>")
	)
	(segment
		(start 353.592892 -293.348156)
		(end 353.592892 -293.523416)
		(width 0.0889)
		(layer "In6.Cu")
		(net "UPI_CPU0_CPU1_P2P2_DN<1>")
	)
	(segment
		(start 355.835712 -282.405836)
		(end 355.835712 -282.413456)
		(width 0.0889)
		(layer "In6.Cu")
		(net "UPI_CPU0_CPU1_P2P2_DN<1>")
	)
	(segment
		(start 355.17836 -286.151066)
		(end 355.18725 -286.156146)
		(width 0.0889)
		(layer "In6.Cu")
		(net "UPI_CPU0_CPU1_P2P2_DN<1>")
	)
	(segment
		(start 355.179376 -288.426906)
		(end 355.178614 -288.427414)
		(width 0.0889)
		(layer "In6.Cu")
		(net "UPI_CPU0_CPU1_P2P2_DN<1>")
	)
	(segment
		(start 76.966826 -300.167294)
		(end 77.139292 -300.167294)
		(width 0.14732)
		(layer "In6.Cu")
		(net "UPI_CPU0_CPU1_P2P2_DN<1>")
	)
	(segment
		(start 72.89165 -378.501656)
		(end 70.09003 -377.341384)
		(width 0.14732)
		(layer "In6.Cu")
		(net "UPI_CPU0_CPU1_P2P2_DN<1>")
	)
	(segment
		(start 354.9777 -291.014912)
		(end 354.9777 -291.155374)
		(width 0.0889)
		(layer "In6.Cu")
		(net "UPI_CPU0_CPU1_P2P2_DN<1>")
	)
	(segment
		(start 55.955946 -315.894466)
		(end 58.739024 -314.034678)
		(width 0.14732)
		(layer "In6.Cu")
		(net "UPI_CPU0_CPU1_P2P2_DN<1>")
	)
	(segment
		(start 85.709506 -285.342076)
		(end 85.718396 -285.336996)
		(width 0.0889)
		(layer "In6.Cu")
		(net "UPI_CPU0_CPU1_P2P2_DN<1>")
	)
	(segment
		(start 63.767208 -311.388506)
		(end 64.534542 -310.621172)
		(width 0.14732)
		(layer "In6.Cu")
		(net "UPI_CPU0_CPU1_P2P2_DN<1>")
	)
	(segment
		(start 63.474092 -370.725446)
		(end 57.542938 -356.406196)
		(width 0.14732)
		(layer "In6.Cu")
		(net "UPI_CPU0_CPU1_P2P2_DN<1>")
	)
	(segment
		(start 354.521262 -280.778204)
		(end 354.208588 -280.778204)
		(width 0.0889)
		(layer "In6.Cu")
		(net "UPI_CPU0_CPU1_P2P2_DN<1>")
	)
	(segment
		(start 354.589588 -291.543486)
		(end 354.46589 -291.667184)
		(width 0.0889)
		(layer "In6.Cu")
		(net "UPI_CPU0_CPU1_P2P2_DN<1>")
	)
	(segment
		(start 353.150678 -300.288706)
		(end 352.84918 -301.01667)
		(width 0.14732)
		(layer "In6.Cu")
		(net "UPI_CPU0_CPU1_P2P2_DN<1>")
	)
	(segment
		(start 354.896166 -288.898584)
		(end 354.896166 -289.114738)
		(width 0.0889)
		(layer "In6.Cu")
		(net "UPI_CPU0_CPU1_P2P2_DN<1>")
	)
	(segment
		(start 80.929226 -296.204894)
		(end 82.421222 -292.60292)
		(width 0.14732)
		(layer "In6.Cu")
		(net "UPI_CPU0_CPU1_P2P2_DN<1>")
	)
	(segment
		(start 126.76632 -391.86739)
		(end 93.108526 -386.874512)
		(width 0.14732)
		(layer "In6.Cu")
		(net "UPI_CPU0_CPU1_P2P2_DN<1>")
	)
	(segment
		(start 52.721002 -323.65696)
		(end 53.332634 -323.045582)
		(width 0.14732)
		(layer "In6.Cu")
		(net "UPI_CPU0_CPU1_P2P2_DN<1>")
	)
	(segment
		(start 353.691952 -293.622476)
		(end 353.691952 -293.797736)
		(width 0.0889)
		(layer "In6.Cu")
		(net "UPI_CPU0_CPU1_P2P2_DN<1>")
	)
	(segment
		(start 55.362094 -333.122778)
		(end 54.875176 -332.55077)
		(width 0.14732)
		(layer "In6.Cu")
		(net "UPI_CPU0_CPU1_P2P2_DN<1>")
	)
	(segment
		(start 51.6382 -324.449694)
		(end 52.225956 -323.861938)
		(width 0.14732)
		(layer "In6.Cu")
		(net "UPI_CPU0_CPU1_P2P2_DN<1>")
	)
	(segment
		(start 355.365812 -289.645852)
		(end 355.365812 -290.045394)
		(width 0.0889)
		(layer "In6.Cu")
		(net "UPI_CPU0_CPU1_P2P2_DN<1>")
	)
	(arc
		(start 355.181662 -289.446462)
		(mid 355.290809 -289.53039)
		(end 355.365812 -289.645852)
		(width 0.0889)
		(layer "In6.Cu")
		(net "UPI_CPU0_CPU1_P2P2_DN<1>")
	)
	(arc
		(start 87.128096 -282.895548)
		(mid 87.331577 -282.694744)
		(end 87.410798 -282.42006)
		(width 0.0889)
		(layer "In6.Cu")
		(net "UPI_CPU0_CPU1_P2P2_DN<1>")
	)
	(arc
		(start 354.895912 -280.778204)
		(mid 354.969903 -281.05777)
		(end 355.172518 -281.264106)
		(width 0.0889)
		(layer "In6.Cu")
		(net "UPI_CPU0_CPU1_P2P2_DN<1>")
	)
	(arc
		(start 356.305612 -283.207714)
		(mid 356.305857 -283.21711)
		(end 356.305866 -283.22651)
		(width 0.0889)
		(layer "In6.Cu")
		(net "UPI_CPU0_CPU1_P2P2_DN<1>")
	)
	(arc
		(start 355.18725 -287.783778)
		(mid 355.365847 -288.103056)
		(end 355.18725 -288.422334)
		(width 0.0889)
		(layer "In6.Cu")
		(net "UPI_CPU0_CPU1_P2P2_DN<1>")
	)
	(arc
		(start 85.718396 -285.336996)
		(mid 85.905594 -285.286853)
		(end 86.092792 -285.336996)
		(width 0.0889)
		(layer "In6.Cu")
		(net "UPI_CPU0_CPU1_P2P2_DN<1>")
	)
	(arc
		(start 86.940644 -284.832044)
		(mid 86.861274 -284.55831)
		(end 86.65845 -284.35808)
		(width 0.0889)
		(layer "In6.Cu")
		(net "UPI_CPU0_CPU1_P2P2_DN<1>")
	)
	(arc
		(start 356.305866 -283.22651)
		(mid 356.253929 -283.410019)
		(end 356.118414 -283.544264)
		(width 0.0889)
		(layer "In6.Cu")
		(net "UPI_CPU0_CPU1_P2P2_DN<1>")
	)
	(arc
		(start 87.410798 -282.39593)
		(mid 87.353195 -282.157061)
		(end 87.199724 -281.965146)
		(width 0.0889)
		(layer "In6.Cu")
		(net "UPI_CPU0_CPU1_P2P2_DN<1>")
	)
	(arc
		(start 355.18725 -286.156146)
		(mid 355.365847 -286.475424)
		(end 355.18725 -286.794702)
		(width 0.0889)
		(layer "In6.Cu")
		(net "UPI_CPU0_CPU1_P2P2_DN<1>")
	)
	(arc
		(start 354.896166 -289.114738)
		(mid 355.007504 -289.307638)
		(end 355.181662 -289.446462)
		(width 0.0889)
		(layer "In6.Cu")
		(net "UPI_CPU0_CPU1_P2P2_DN<1>")
	)
	(arc
		(start 355.835712 -282.413456)
		(mid 355.913341 -282.691869)
		(end 356.118414 -282.895548)
		(width 0.0889)
		(layer "In6.Cu")
		(net "UPI_CPU0_CPU1_P2P2_DN<1>")
	)
	(arc
		(start 355.642164 -284.361636)
		(mid 355.439751 -284.568049)
		(end 355.365812 -284.847538)
		(width 0.0889)
		(layer "In6.Cu")
		(net "UPI_CPU0_CPU1_P2P2_DN<1>")
	)
	(arc
		(start 86.092792 -285.336996)
		(mid 86.375494 -285.412772)
		(end 86.658196 -285.336996)
		(width 0.0889)
		(layer "In6.Cu")
		(net "UPI_CPU0_CPU1_P2P2_DN<1>")
	)
	(arc
		(start 356.118414 -282.895548)
		(mid 356.252437 -283.027375)
		(end 356.305612 -283.207714)
		(width 0.0889)
		(layer "In6.Cu")
		(net "UPI_CPU0_CPU1_P2P2_DN<1>")
	)
	(arc
		(start 86.65845 -283.709364)
		(mid 86.861273 -283.509133)
		(end 86.940644 -283.2354)
		(width 0.0889)
		(layer "In6.Cu")
		(net "UPI_CPU0_CPU1_P2P2_DN<1>")
	)
	(arc
		(start 355.187504 -281.272742)
		(mid 355.318418 -281.409102)
		(end 355.366066 -281.59202)
		(width 0.0889)
		(layer "In6.Cu")
		(net "UPI_CPU0_CPU1_P2P2_DN<1>")
	)
	(arc
		(start 85.640418 -285.396178)
		(mid 85.673377 -285.367103)
		(end 85.709506 -285.342076)
		(width 0.0889)
		(layer "In6.Cu")
		(net "UPI_CPU0_CPU1_P2P2_DN<1>")
	)
	(arc
		(start 355.178614 -288.427414)
		(mid 354.976328 -288.626395)
		(end 354.896166 -288.898584)
		(width 0.0889)
		(layer "In6.Cu")
		(net "UPI_CPU0_CPU1_P2P2_DN<1>")
	)
	(arc
		(start 355.17836 -286.799782)
		(mid 354.895701 -287.28924)
		(end 355.17836 -287.778698)
		(width 0.0889)
		(layer "In6.Cu")
		(net "UPI_CPU0_CPU1_P2P2_DN<1>")
	)
	(arc
		(start 355.65715 -282.086558)
		(mid 355.788064 -282.222918)
		(end 355.835712 -282.405836)
		(width 0.0889)
		(layer "In6.Cu")
		(net "UPI_CPU0_CPU1_P2P2_DN<1>")
	)
	(arc
		(start 87.199724 -281.965146)
		(mid 87.191529 -281.958592)
		(end 87.183214 -281.952192)
		(width 0.0889)
		(layer "In6.Cu")
		(net "UPI_CPU0_CPU1_P2P2_DN<1>")
	)
	(arc
		(start 355.17836 -285.171896)
		(mid 354.895608 -285.661544)
		(end 355.17836 -286.151066)
		(width 0.0889)
		(layer "In6.Cu")
		(net "UPI_CPU0_CPU1_P2P2_DN<1>")
	)
	(arc
		(start 86.658196 -285.336996)
		(mid 86.862531 -285.134391)
		(end 86.940644 -284.857444)
		(width 0.0889)
		(layer "In6.Cu")
		(net "UPI_CPU0_CPU1_P2P2_DN<1>")
	)
	(arc
		(start 355.835712 -284.033722)
		(mid 355.788033 -284.216622)
		(end 355.65715 -284.353)
		(width 0.0889)
		(layer "In6.Cu")
		(net "UPI_CPU0_CPU1_P2P2_DN<1>")
	)
	(arc
		(start 355.365812 -284.847538)
		(mid 355.318133 -285.030438)
		(end 355.18725 -285.166816)
		(width 0.0889)
		(layer "In6.Cu")
		(net "UPI_CPU0_CPU1_P2P2_DN<1>")
	)
	(arc
		(start 354.895658 -280.763472)
		(mid 354.895855 -280.770837)
		(end 354.895912 -280.778204)
		(width 0.0889)
		(layer "In6.Cu")
		(net "UPI_CPU0_CPU1_P2P2_DN<1>")
	)
	(arc
		(start 86.64956 -284.353)
		(mid 86.470963 -284.033722)
		(end 86.64956 -283.714444)
		(width 0.0889)
		(layer "In6.Cu")
		(net "UPI_CPU0_CPU1_P2P2_DN<1>")
	)
	(arc
		(start 86.940644 -283.219906)
		(mid 86.988323 -283.037006)
		(end 87.119206 -282.900628)
		(width 0.0889)
		(layer "In6.Cu")
		(net "UPI_CPU0_CPU1_P2P2_DN<1>")
	)
	(arc
		(start 356.106222 -283.551376)
		(mid 355.907994 -283.757224)
		(end 355.835712 -284.033722)
		(width 0.0889)
		(layer "In6.Cu")
		(net "UPI_CPU0_CPU1_P2P2_DN<1>")
	)
	(arc
		(start 355.366066 -281.607514)
		(mid 355.445436 -281.881248)
		(end 355.64826 -282.081478)
		(width 0.0889)
		(layer "In6.Cu")
		(net "UPI_CPU0_CPU1_P2P2_DN<1>")
	)
	(arc
		(start 354.151184 -280.7208)
		(mid 354.542702 -280.40453)
		(end 354.895658 -280.763472)
		(width 0.0889)
		(layer "In6.Cu")
		(net "UPI_CPU0_CPU1_P2P2_DN<1>")
	)
	(segment
		(start 108.461048 -277.521924)
		(end 108.460794 -277.522178)
		(width 0.13208)
		(layer "F.Cu")
		(net "UPI_CPU0_CPU1_P2P2_DN<19>")
	)
	(segment
		(start 336.195162 -284.311598)
		(end 336.195162 -284.847538)
		(width 0.13208)
		(layer "F.Cu")
		(net "UPI_CPU0_CPU1_P2P2_DN<19>")
	)
	(segment
		(start 108.461048 -276.986492)
		(end 108.461048 -277.521924)
		(width 0.13208)
		(layer "F.Cu")
		(net "UPI_CPU0_CPU1_P2P2_DN<19>")
	)
	(segment
		(start 108.460794 -277.522178)
		(end 108.460794 -277.522432)
		(width 0.13208)
		(layer "F.Cu")
		(net "UPI_CPU0_CPU1_P2P2_DN<19>")
	)
	(segment
		(start 246.09933 -362.308394)
		(end 246.023384 -362.737146)
		(width 0.14732)
		(layer "In6.Cu")
		(net "UPI_CPU0_CPU1_P2P2_DN<19>")
	)
	(segment
		(start 248.964958 -360.316018)
		(end 248.46788 -361.025948)
		(width 0.14732)
		(layer "In6.Cu")
		(net "UPI_CPU0_CPU1_P2P2_DN<19>")
	)
	(segment
		(start 305.48834 -321.47637)
		(end 305.00574 -321.95897)
		(width 0.14732)
		(layer "In6.Cu")
		(net "UPI_CPU0_CPU1_P2P2_DN<19>")
	)
	(segment
		(start 104.136698 -289.114738)
		(end 104.136698 -288.898584)
		(width 0.0889)
		(layer "In6.Cu")
		(net "UPI_CPU0_CPU1_P2P2_DN<19>")
	)
	(segment
		(start 250.294394 -358.417368)
		(end 249.825256 -359.086658)
		(width 0.14732)
		(layer "In6.Cu")
		(net "UPI_CPU0_CPU1_P2P2_DN<19>")
	)
	(segment
		(start 336.468974 -285.980632)
		(end 336.477864 -285.985712)
		(width 0.0889)
		(layer "In6.Cu")
		(net "UPI_CPU0_CPU1_P2P2_DN<19>")
	)
	(segment
		(start 310.675274 -316.382654)
		(end 309.761128 -316.382654)
		(width 0.14732)
		(layer "In6.Cu")
		(net "UPI_CPU0_CPU1_P2P2_DN<19>")
	)
	(segment
		(start 267.777976 -338.57311)
		(end 267.297916 -338.09305)
		(width 0.14732)
		(layer "In6.Cu")
		(net "UPI_CPU0_CPU1_P2P2_DN<19>")
	)
	(segment
		(start 265.513566 -340.83752)
		(end 265.513566 -341.273384)
		(width 0.14732)
		(layer "In6.Cu")
		(net "UPI_CPU0_CPU1_P2P2_DN<19>")
	)
	(segment
		(start 249.236484 -357.121714)
		(end 249.272552 -357.326184)
		(width 0.14732)
		(layer "In6.Cu")
		(net "UPI_CPU0_CPU1_P2P2_DN<19>")
	)
	(segment
		(start 336.760312 -286.456882)
		(end 336.760312 -286.475424)
		(width 0.0889)
		(layer "In6.Cu")
		(net "UPI_CPU0_CPU1_P2P2_DN<19>")
	)
	(segment
		(start 247.907048 -359.02011)
		(end 247.943116 -359.22458)
		(width 0.14732)
		(layer "In6.Cu")
		(net "UPI_CPU0_CPU1_P2P2_DN<19>")
	)
	(segment
		(start 245.778528 -360.56443)
		(end 245.294658 -360.903266)
		(width 0.14732)
		(layer "In6.Cu")
		(net "UPI_CPU0_CPU1_P2P2_DN<19>")
	)
	(segment
		(start 80.33512 -319.012824)
		(end 96.660208 -305.615594)
		(width 0.14732)
		(layer "In6.Cu")
		(net "UPI_CPU0_CPU1_P2P2_DN<19>")
	)
	(segment
		(start 268.791182 -337.995768)
		(end 268.21384 -338.57311)
		(width 0.14732)
		(layer "In6.Cu")
		(net "UPI_CPU0_CPU1_P2P2_DN<19>")
	)
	(segment
		(start 240.328196 -366.725708)
		(end 239.41278 -367.36655)
		(width 0.14732)
		(layer "In6.Cu")
		(net "UPI_CPU0_CPU1_P2P2_DN<19>")
	)
	(segment
		(start 245.294658 -360.903266)
		(end 245.25859 -361.107736)
		(width 0.14732)
		(layer "In6.Cu")
		(net "UPI_CPU0_CPU1_P2P2_DN<19>")
	)
	(segment
		(start 159.140906 -376.85345)
		(end 125.94717 -376.85345)
		(width 0.14732)
		(layer "In6.Cu")
		(net "UPI_CPU0_CPU1_P2P2_DN<19>")
	)
	(segment
		(start 248.889012 -359.887012)
		(end 248.964958 -360.316018)
		(width 0.14732)
		(layer "In6.Cu")
		(net "UPI_CPU0_CPU1_P2P2_DN<19>")
	)
	(segment
		(start 250.904756 -354.739448)
		(end 250.56592 -355.223318)
		(width 0.14732)
		(layer "In6.Cu")
		(net "UPI_CPU0_CPU1_P2P2_DN<19>")
	)
	(segment
		(start 247.943116 -359.22458)
		(end 248.889012 -359.887012)
		(width 0.14732)
		(layer "In6.Cu")
		(net "UPI_CPU0_CPU1_P2P2_DN<19>")
	)
	(segment
		(start 253.813818 -353.39147)
		(end 253.384812 -353.467416)
		(width 0.14732)
		(layer "In6.Cu")
		(net "UPI_CPU0_CPU1_P2P2_DN<19>")
	)
	(segment
		(start 269.950184 -335.233264)
		(end 269.950184 -335.44129)
		(width 0.14732)
		(layer "In6.Cu")
		(net "UPI_CPU0_CPU1_P2P2_DN<19>")
	)
	(segment
		(start 251.895356 -353.324922)
		(end 251.931424 -353.529392)
		(width 0.14732)
		(layer "In6.Cu")
		(net "UPI_CPU0_CPU1_P2P2_DN<19>")
	)
	(segment
		(start 252.953266 -354.620576)
		(end 252.484128 -355.289866)
		(width 0.14732)
		(layer "In6.Cu")
		(net "UPI_CPU0_CPU1_P2P2_DN<19>")
	)
	(segment
		(start 266.139168 -340.211918)
		(end 265.659108 -339.731858)
		(width 0.14732)
		(layer "In6.Cu")
		(net "UPI_CPU0_CPU1_P2P2_DN<19>")
	)
	(segment
		(start 240.08334 -364.552738)
		(end 239.59947 -364.891574)
		(width 0.14732)
		(layer "In6.Cu")
		(net "UPI_CPU0_CPU1_P2P2_DN<19>")
	)
	(segment
		(start 105.546144 -286.48406)
		(end 105.546144 -286.466788)
		(width 0.0889)
		(layer "In6.Cu")
		(net "UPI_CPU0_CPU1_P2P2_DN<19>")
	)
	(segment
		(start 269.852648 -336.934302)
		(end 269.416784 -336.934302)
		(width 0.14732)
		(layer "In6.Cu")
		(net "UPI_CPU0_CPU1_P2P2_DN<19>")
	)
	(segment
		(start 212.359748 -372.152164)
		(end 212.31225 -372.160292)
		(width 0.14732)
		(layer "In6.Cu")
		(net "UPI_CPU0_CPU1_P2P2_DN<19>")
	)
	(segment
		(start 245.354094 -363.206284)
		(end 244.925342 -363.130338)
		(width 0.14732)
		(layer "In6.Cu")
		(net "UPI_CPU0_CPU1_P2P2_DN<19>")
	)
	(segment
		(start 336.955638 -287.774126)
		(end 336.955384 -287.773872)
		(width 0.0889)
		(layer "In6.Cu")
		(net "UPI_CPU0_CPU1_P2P2_DN<19>")
	)
	(segment
		(start 268.791182 -337.559904)
		(end 268.791182 -337.995768)
		(width 0.14732)
		(layer "In6.Cu")
		(net "UPI_CPU0_CPU1_P2P2_DN<19>")
	)
	(segment
		(start 336.955384 -287.773872)
		(end 336.896456 -287.807908)
		(width 0.0889)
		(layer "In6.Cu")
		(net "UPI_CPU0_CPU1_P2P2_DN<19>")
	)
	(segment
		(start 268.311376 -336.872072)
		(end 268.311376 -337.080098)
		(width 0.14732)
		(layer "In6.Cu")
		(net "UPI_CPU0_CPU1_P2P2_DN<19>")
	)
	(segment
		(start 212.359748 -372.15191)
		(end 212.359748 -372.152164)
		(width 0.14732)
		(layer "In6.Cu")
		(net "UPI_CPU0_CPU1_P2P2_DN<19>")
	)
	(segment
		(start 106.768392 -282.730194)
		(end 106.777282 -282.725114)
		(width 0.0889)
		(layer "In6.Cu")
		(net "UPI_CPU0_CPU1_P2P2_DN<19>")
	)
	(segment
		(start 268.729206 -336.454242)
		(end 268.311376 -336.872072)
		(width 0.14732)
		(layer "In6.Cu")
		(net "UPI_CPU0_CPU1_P2P2_DN<19>")
	)
	(segment
		(start 271.588992 -333.802482)
		(end 272.068798 -334.282288)
		(width 0.14732)
		(layer "In6.Cu")
		(net "UPI_CPU0_CPU1_P2P2_DN<19>")
	)
	(segment
		(start 334.117696 -291.442648)
		(end 332.553056 -293.781988)
		(width 0.14732)
		(layer "In6.Cu")
		(net "UPI_CPU0_CPU1_P2P2_DN<19>")
	)
	(segment
		(start 247.252744 -361.876848)
		(end 246.823738 -361.800902)
		(width 0.14732)
		(layer "In6.Cu")
		(net "UPI_CPU0_CPU1_P2P2_DN<19>")
	)
	(segment
		(start 249.77979 -356.601776)
		(end 249.57532 -356.637844)
		(width 0.14732)
		(layer "In6.Cu")
		(net "UPI_CPU0_CPU1_P2P2_DN<19>")
	)
	(segment
		(start 105.352596 -285.175452)
		(end 105.358692 -285.171896)
		(width 0.0889)
		(layer "In6.Cu")
		(net "UPI_CPU0_CPU1_P2P2_DN<19>")
	)
	(segment
		(start 336.488024 -288.586164)
		(end 336.476594 -288.593022)
		(width 0.0889)
		(layer "In6.Cu")
		(net "UPI_CPU0_CPU1_P2P2_DN<19>")
	)
	(segment
		(start 252.438662 -352.804984)
		(end 252.234192 -352.841052)
		(width 0.14732)
		(layer "In6.Cu")
		(net "UPI_CPU0_CPU1_P2P2_DN<19>")
	)
	(segment
		(start 97.975674 -304.234088)
		(end 102.697534 -297.867832)
		(width 0.14732)
		(layer "In6.Cu")
		(net "UPI_CPU0_CPU1_P2P2_DN<19>")
	)
	(segment
		(start 265.03376 -340.357714)
		(end 265.513566 -340.83752)
		(width 0.14732)
		(layer "In6.Cu")
		(net "UPI_CPU0_CPU1_P2P2_DN<19>")
	)
	(segment
		(start 249.57532 -356.637844)
		(end 249.236484 -357.121714)
		(width 0.14732)
		(layer "In6.Cu")
		(net "UPI_CPU0_CPU1_P2P2_DN<19>")
	)
	(segment
		(start 80.419448 -365.171736)
		(end 75.843384 -360.595672)
		(width 0.14732)
		(layer "In6.Cu")
		(net "UPI_CPU0_CPU1_P2P2_DN<19>")
	)
	(segment
		(start 245.982998 -360.600498)
		(end 245.778528 -360.56443)
		(width 0.14732)
		(layer "In6.Cu")
		(net "UPI_CPU0_CPU1_P2P2_DN<19>")
	)
	(segment
		(start 268.936724 -336.454242)
		(end 268.729206 -336.454242)
		(width 0.14732)
		(layer "In6.Cu")
		(net "UPI_CPU0_CPU1_P2P2_DN<19>")
	)
	(segment
		(start 335.061814 -290.438586)
		(end 335.061814 -290.49853)
		(width 0.0889)
		(layer "In6.Cu")
		(net "UPI_CPU0_CPU1_P2P2_DN<19>")
	)
	(segment
		(start 73.540112 -327.205848)
		(end 74.793856 -324.554088)
		(width 0.14732)
		(layer "In6.Cu")
		(net "UPI_CPU0_CPU1_P2P2_DN<19>")
	)
	(segment
		(start 104.606598 -288.103056)
		(end 104.606598 -288.09315)
		(width 0.0889)
		(layer "In6.Cu")
		(net "UPI_CPU0_CPU1_P2P2_DN<19>")
	)
	(segment
		(start 248.46788 -361.025948)
		(end 247.252744 -361.876848)
		(width 0.14732)
		(layer "In6.Cu")
		(net "UPI_CPU0_CPU1_P2P2_DN<19>")
	)
	(segment
		(start 270.42999 -336.35696)
		(end 269.852648 -336.934302)
		(width 0.14732)
		(layer "In6.Cu")
		(net "UPI_CPU0_CPU1_P2P2_DN<19>")
	)
	(segment
		(start 241.557302 -365.865156)
		(end 241.12855 -365.78921)
		(width 0.14732)
		(layer "In6.Cu")
		(net "UPI_CPU0_CPU1_P2P2_DN<19>")
	)
	(segment
		(start 265.45159 -339.731858)
		(end 265.03376 -340.149688)
		(width 0.14732)
		(layer "In6.Cu")
		(net "UPI_CPU0_CPU1_P2P2_DN<19>")
	)
	(segment
		(start 248.245884 -358.53624)
		(end 247.907048 -359.02011)
		(width 0.14732)
		(layer "In6.Cu")
		(net "UPI_CPU0_CPU1_P2P2_DN<19>")
	)
	(segment
		(start 246.023384 -362.737146)
		(end 245.354094 -363.206284)
		(width 0.14732)
		(layer "In6.Cu")
		(net "UPI_CPU0_CPU1_P2P2_DN<19>")
	)
	(segment
		(start 242.302538 -364.967266)
		(end 242.226592 -365.396018)
		(width 0.14732)
		(layer "In6.Cu")
		(net "UPI_CPU0_CPU1_P2P2_DN<19>")
	)
	(segment
		(start 251.547884 -356.09022)
		(end 251.62383 -356.518972)
		(width 0.14732)
		(layer "In6.Cu")
		(net "UPI_CPU0_CPU1_P2P2_DN<19>")
	)
	(segment
		(start 243.396262 -362.232702)
		(end 243.360194 -362.437172)
		(width 0.14732)
		(layer "In6.Cu")
		(net "UPI_CPU0_CPU1_P2P2_DN<19>")
	)
	(segment
		(start 244.925342 -363.130338)
		(end 244.084602 -361.929934)
		(width 0.14732)
		(layer "In6.Cu")
		(net "UPI_CPU0_CPU1_P2P2_DN<19>")
	)
	(segment
		(start 317.03645 -313.764676)
		(end 317.03645 -313.76493)
		(width 0.14732)
		(layer "In6.Cu")
		(net "UPI_CPU0_CPU1_P2P2_DN<19>")
	)
	(segment
		(start 103.673402 -291.766498)
		(end 103.688896 -291.751004)
		(width 0.0889)
		(layer "In6.Cu")
		(net "UPI_CPU0_CPU1_P2P2_DN<19>")
	)
	(segment
		(start 305.00574 -321.95897)
		(end 303.507648 -323.04609)
		(width 0.14732)
		(layer "In6.Cu")
		(net "UPI_CPU0_CPU1_P2P2_DN<19>")
	)
	(segment
		(start 249.272552 -357.326184)
		(end 250.218448 -357.988616)
		(width 0.14732)
		(layer "In6.Cu")
		(net "UPI_CPU0_CPU1_P2P2_DN<19>")
	)
	(segment
		(start 241.461798 -363.766608)
		(end 242.302538 -364.967266)
		(width 0.14732)
		(layer "In6.Cu")
		(net "UPI_CPU0_CPU1_P2P2_DN<19>")
	)
	(segment
		(start 246.823738 -361.800902)
		(end 245.982998 -360.600498)
		(width 0.14732)
		(layer "In6.Cu")
		(net "UPI_CPU0_CPU1_P2P2_DN<19>")
	)
	(segment
		(start 292.71849 -326.069452)
		(end 292.71849 -327.1901)
		(width 0.14732)
		(layer "In6.Cu")
		(net "UPI_CPU0_CPU1_P2P2_DN<19>")
	)
	(segment
		(start 251.931424 -353.529392)
		(end 252.87732 -354.191824)
		(width 0.14732)
		(layer "In6.Cu")
		(net "UPI_CPU0_CPU1_P2P2_DN<19>")
	)
	(segment
		(start 276.126702 -330.660248)
		(end 273.130264 -333.656686)
		(width 0.14732)
		(layer "In6.Cu")
		(net "UPI_CPU0_CPU1_P2P2_DN<19>")
	)
	(segment
		(start 254.789686 -351.997518)
		(end 253.813818 -353.39147)
		(width 0.14732)
		(layer "In6.Cu")
		(net "UPI_CPU0_CPU1_P2P2_DN<19>")
	)
	(segment
		(start 270.42999 -335.921096)
		(end 270.42999 -336.35696)
		(width 0.14732)
		(layer "In6.Cu")
		(net "UPI_CPU0_CPU1_P2P2_DN<19>")
	)
	(segment
		(start 251.109226 -354.70338)
		(end 250.904756 -354.739448)
		(width 0.14732)
		(layer "In6.Cu")
		(net "UPI_CPU0_CPU1_P2P2_DN<19>")
	)
	(segment
		(start 269.416784 -336.934302)
		(end 268.936724 -336.454242)
		(width 0.14732)
		(layer "In6.Cu")
		(net "UPI_CPU0_CPU1_P2P2_DN<19>")
	)
	(segment
		(start 251.62383 -356.518972)
		(end 251.154692 -357.188262)
		(width 0.14732)
		(layer "In6.Cu")
		(net "UPI_CPU0_CPU1_P2P2_DN<19>")
	)
	(segment
		(start 292.410642 -327.497948)
		(end 291.593778 -327.497948)
		(width 0.14732)
		(layer "In6.Cu")
		(net "UPI_CPU0_CPU1_P2P2_DN<19>")
	)
	(segment
		(start 72.274938 -351.990406)
		(end 72.274938 -335.157064)
		(width 0.14732)
		(layer "In6.Cu")
		(net "UPI_CPU0_CPU1_P2P2_DN<19>")
	)
	(segment
		(start 244.200934 -363.63783)
		(end 244.124988 -364.066582)
		(width 0.14732)
		(layer "In6.Cu")
		(net "UPI_CPU0_CPU1_P2P2_DN<19>")
	)
	(segment
		(start 336.290158 -288.917126)
		(end 336.290158 -289.210242)
		(width 0.0889)
		(layer "In6.Cu")
		(net "UPI_CPU0_CPU1_P2P2_DN<19>")
	)
	(segment
		(start 336.760058 -288.044128)
		(end 336.760058 -288.103056)
		(width 0.0889)
		(layer "In6.Cu")
		(net "UPI_CPU0_CPU1_P2P2_DN<19>")
	)
	(segment
		(start 305.850798 -318.962024)
		(end 305.850798 -320.601594)
		(width 0.14732)
		(layer "In6.Cu")
		(net "UPI_CPU0_CPU1_P2P2_DN<19>")
	)
	(segment
		(start 297.336718 -325.922132)
		(end 292.86581 -325.922132)
		(width 0.14732)
		(layer "In6.Cu")
		(net "UPI_CPU0_CPU1_P2P2_DN<19>")
	)
	(segment
		(start 250.56592 -355.223318)
		(end 250.601988 -355.427788)
		(width 0.14732)
		(layer "In6.Cu")
		(net "UPI_CPU0_CPU1_P2P2_DN<19>")
	)
	(segment
		(start 250.72594 -357.264208)
		(end 249.77979 -356.601776)
		(width 0.14732)
		(layer "In6.Cu")
		(net "UPI_CPU0_CPU1_P2P2_DN<19>")
	)
	(segment
		(start 336.290412 -285.651448)
		(end 336.290412 -285.661354)
		(width 0.0889)
		(layer "In6.Cu")
		(net "UPI_CPU0_CPU1_P2P2_DN<19>")
	)
	(segment
		(start 268.21384 -338.57311)
		(end 267.777976 -338.57311)
		(width 0.14732)
		(layer "In6.Cu")
		(net "UPI_CPU0_CPU1_P2P2_DN<19>")
	)
	(segment
		(start 108.647992 -277.84679)
		(end 108.656882 -277.84171)
		(width 0.0889)
		(layer "In6.Cu")
		(net "UPI_CPU0_CPU1_P2P2_DN<19>")
	)
	(segment
		(start 125.94717 -376.85345)
		(end 98.952558 -372.849394)
		(width 0.14732)
		(layer "In6.Cu")
		(net "UPI_CPU0_CPU1_P2P2_DN<19>")
	)
	(segment
		(start 244.084602 -361.929934)
		(end 243.880132 -361.893866)
		(width 0.14732)
		(layer "In6.Cu")
		(net "UPI_CPU0_CPU1_P2P2_DN<19>")
	)
	(segment
		(start 103.288084 -292.151816)
		(end 103.673402 -291.766498)
		(width 0.14732)
		(layer "In6.Cu")
		(net "UPI_CPU0_CPU1_P2P2_DN<19>")
	)
	(segment
		(start 302.484282 -323.788786)
		(end 297.336718 -325.922132)
		(width 0.14732)
		(layer "In6.Cu")
		(net "UPI_CPU0_CPU1_P2P2_DN<19>")
	)
	(segment
		(start 336.290158 -289.210242)
		(end 335.061814 -290.438586)
		(width 0.0889)
		(layer "In6.Cu")
		(net "UPI_CPU0_CPU1_P2P2_DN<19>")
	)
	(segment
		(start 265.03376 -340.149688)
		(end 265.03376 -340.357714)
		(width 0.14732)
		(layer "In6.Cu")
		(net "UPI_CPU0_CPU1_P2P2_DN<19>")
	)
	(segment
		(start 102.989634 -292.44925)
		(end 103.287068 -292.151816)
		(width 0.14732)
		(layer "In6.Cu")
		(net "UPI_CPU0_CPU1_P2P2_DN<19>")
	)
	(segment
		(start 272.6944 -333.656686)
		(end 272.21434 -333.176626)
		(width 0.14732)
		(layer "In6.Cu")
		(net "UPI_CPU0_CPU1_P2P2_DN<19>")
	)
	(segment
		(start 105.358692 -285.171896)
		(end 105.367582 -285.166816)
		(width 0.0889)
		(layer "In6.Cu")
		(net "UPI_CPU0_CPU1_P2P2_DN<19>")
	)
	(segment
		(start 108.830872 -277.579836)
		(end 108.773468 -277.522432)
		(width 0.0889)
		(layer "In6.Cu")
		(net "UPI_CPU0_CPU1_P2P2_DN<19>")
	)
	(segment
		(start 96.660208 -305.615594)
		(end 97.975674 -304.234088)
		(width 0.14732)
		(layer "In6.Cu")
		(net "UPI_CPU0_CPU1_P2P2_DN<19>")
	)
	(segment
		(start 106.777282 -282.086558)
		(end 106.768392 -282.081478)
		(width 0.0889)
		(layer "In6.Cu")
		(net "UPI_CPU0_CPU1_P2P2_DN<19>")
	)
	(segment
		(start 106.955844 -280.778204)
		(end 106.955844 -280.76398)
		(width 0.0889)
		(layer "In6.Cu")
		(net "UPI_CPU0_CPU1_P2P2_DN<19>")
	)
	(segment
		(start 265.513566 -341.273384)
		(end 254.789686 -351.997518)
		(width 0.14732)
		(layer "In6.Cu")
		(net "UPI_CPU0_CPU1_P2P2_DN<19>")
	)
	(segment
		(start 107.425744 -279.97277)
		(end 107.425744 -279.954228)
		(width 0.0889)
		(layer "In6.Cu")
		(net "UPI_CPU0_CPU1_P2P2_DN<19>")
	)
	(segment
		(start 106.292396 -283.54782)
		(end 106.298492 -283.544264)
		(width 0.0889)
		(layer "In6.Cu")
		(net "UPI_CPU0_CPU1_P2P2_DN<19>")
	)
	(segment
		(start 270.368014 -334.815434)
		(end 269.950184 -335.233264)
		(width 0.14732)
		(layer "In6.Cu")
		(net "UPI_CPU0_CPU1_P2P2_DN<19>")
	)
	(segment
		(start 104.419146 -288.427414)
		(end 104.428036 -288.422334)
		(width 0.0889)
		(layer "In6.Cu")
		(net "UPI_CPU0_CPU1_P2P2_DN<19>")
	)
	(segment
		(start 336.038698 -285.118556)
		(end 336.062828 -285.20771)
		(width 0.0889)
		(layer "In6.Cu")
		(net "UPI_CPU0_CPU1_P2P2_DN<19>")
	)
	(segment
		(start 106.768392 -281.102562)
		(end 106.777282 -281.097482)
		(width 0.0889)
		(layer "In6.Cu")
		(net "UPI_CPU0_CPU1_P2P2_DN<19>")
	)
	(segment
		(start 74.793856 -324.554088)
		(end 80.33512 -319.012824)
		(width 0.14732)
		(layer "In6.Cu")
		(net "UPI_CPU0_CPU1_P2P2_DN<19>")
	)
	(segment
		(start 245.25859 -361.107736)
		(end 246.09933 -362.308394)
		(width 0.14732)
		(layer "In6.Cu")
		(net "UPI_CPU0_CPU1_P2P2_DN<19>")
	)
	(segment
		(start 105.829354 -284.357572)
		(end 105.831894 -284.356048)
		(width 0.0889)
		(layer "In6.Cu")
		(net "UPI_CPU0_CPU1_P2P2_DN<19>")
	)
	(segment
		(start 239.41278 -367.36655)
		(end 212.359748 -372.15191)
		(width 0.14732)
		(layer "In6.Cu")
		(net "UPI_CPU0_CPU1_P2P2_DN<19>")
	)
	(segment
		(start 305.850798 -320.601594)
		(end 305.48834 -321.47637)
		(width 0.14732)
		(layer "In6.Cu")
		(net "UPI_CPU0_CPU1_P2P2_DN<19>")
	)
	(segment
		(start 104.06888 -291.226748)
		(end 104.606344 -290.689284)
		(width 0.0889)
		(layer "In6.Cu")
		(net "UPI_CPU0_CPU1_P2P2_DN<19>")
	)
	(segment
		(start 103.747824 -291.751004)
		(end 104.06888 -291.429948)
		(width 0.0889)
		(layer "In6.Cu")
		(net "UPI_CPU0_CPU1_P2P2_DN<19>")
	)
	(segment
		(start 270.575532 -334.815434)
		(end 270.368014 -334.815434)
		(width 0.14732)
		(layer "In6.Cu")
		(net "UPI_CPU0_CPU1_P2P2_DN<19>")
	)
	(segment
		(start 102.697534 -297.867832)
		(end 102.858824 -297.478958)
		(width 0.14732)
		(layer "In6.Cu")
		(net "UPI_CPU0_CPU1_P2P2_DN<19>")
	)
	(segment
		(start 306.450746 -318.160908)
		(end 306.06111 -318.550544)
		(width 0.14732)
		(layer "In6.Cu")
		(net "UPI_CPU0_CPU1_P2P2_DN<19>")
	)
	(segment
		(start 106.486198 -281.607514)
		(end 106.486198 -281.576526)
		(width 0.0889)
		(layer "In6.Cu")
		(net "UPI_CPU0_CPU1_P2P2_DN<19>")
	)
	(segment
		(start 72.274938 -335.157064)
		(end 72.79132 -329.909932)
		(width 0.14732)
		(layer "In6.Cu")
		(net "UPI_CPU0_CPU1_P2P2_DN<19>")
	)
	(segment
		(start 313.994038 -313.84494)
		(end 312.352182 -315.486796)
		(width 0.14732)
		(layer "In6.Cu")
		(net "UPI_CPU0_CPU1_P2P2_DN<19>")
	)
	(segment
		(start 335.061814 -290.49853)
		(end 335.04632 -290.514024)
		(width 0.0889)
		(layer "In6.Cu")
		(net "UPI_CPU0_CPU1_P2P2_DN<19>")
	)
	(segment
		(start 267.152374 -339.634576)
		(end 266.575032 -340.211918)
		(width 0.14732)
		(layer "In6.Cu")
		(net "UPI_CPU0_CPU1_P2P2_DN<19>")
	)
	(segment
		(start 243.880132 -361.893866)
		(end 243.396262 -362.232702)
		(width 0.14732)
		(layer "In6.Cu")
		(net "UPI_CPU0_CPU1_P2P2_DN<19>")
	)
	(segment
		(start 105.546144 -284.847538)
		(end 105.546144 -284.837632)
		(width 0.0889)
		(layer "In6.Cu")
		(net "UPI_CPU0_CPU1_P2P2_DN<19>")
	)
	(segment
		(start 105.831894 -284.356048)
		(end 105.837482 -284.353)
		(width 0.0889)
		(layer "In6.Cu")
		(net "UPI_CPU0_CPU1_P2P2_DN<19>")
	)
	(segment
		(start 291.593778 -327.497948)
		(end 291.28593 -327.1901)
		(width 0.14732)
		(layer "In6.Cu")
		(net "UPI_CPU0_CPU1_P2P2_DN<19>")
	)
	(segment
		(start 242.226592 -365.396018)
		(end 241.557302 -365.865156)
		(width 0.14732)
		(layer "In6.Cu")
		(net "UPI_CPU0_CPU1_P2P2_DN<19>")
	)
	(segment
		(start 303.507648 -323.04609)
		(end 303.507648 -323.045836)
		(width 0.14732)
		(layer "In6.Cu")
		(net "UPI_CPU0_CPU1_P2P2_DN<19>")
	)
	(segment
		(start 307.982874 -318.160908)
		(end 306.450746 -318.160908)
		(width 0.14732)
		(layer "In6.Cu")
		(net "UPI_CPU0_CPU1_P2P2_DN<19>")
	)
	(segment
		(start 252.484128 -355.289866)
		(end 252.055376 -355.365812)
		(width 0.14732)
		(layer "In6.Cu")
		(net "UPI_CPU0_CPU1_P2P2_DN<19>")
	)
	(segment
		(start 336.938874 -286.794702)
		(end 336.947764 -286.799782)
		(width 0.0889)
		(layer "In6.Cu")
		(net "UPI_CPU0_CPU1_P2P2_DN<19>")
	)
	(segment
		(start 272.068798 -334.718152)
		(end 271.491456 -335.295494)
		(width 0.14732)
		(layer "In6.Cu")
		(net "UPI_CPU0_CPU1_P2P2_DN<19>")
	)
	(segment
		(start 303.507648 -323.045836)
		(end 302.484282 -323.788786)
		(width 0.14732)
		(layer "In6.Cu")
		(net "UPI_CPU0_CPU1_P2P2_DN<19>")
	)
	(segment
		(start 244.124988 -364.066582)
		(end 243.455698 -364.53572)
		(width 0.14732)
		(layer "In6.Cu")
		(net "UPI_CPU0_CPU1_P2P2_DN<19>")
	)
	(segment
		(start 243.360194 -362.437172)
		(end 244.200934 -363.63783)
		(width 0.14732)
		(layer "In6.Cu")
		(net "UPI_CPU0_CPU1_P2P2_DN<19>")
	)
	(segment
		(start 104.06888 -291.429948)
		(end 104.06888 -291.226748)
		(width 0.0889)
		(layer "In6.Cu")
		(net "UPI_CPU0_CPU1_P2P2_DN<19>")
	)
	(segment
		(start 239.59947 -364.891574)
		(end 239.563402 -365.096044)
		(width 0.14732)
		(layer "In6.Cu")
		(net "UPI_CPU0_CPU1_P2P2_DN<19>")
	)
	(segment
		(start 106.298492 -283.544264)
		(end 106.307382 -283.539184)
		(width 0.0889)
		(layer "In6.Cu")
		(net "UPI_CPU0_CPU1_P2P2_DN<19>")
	)
	(segment
		(start 105.076244 -285.668974)
		(end 105.076244 -285.661354)
		(width 0.0889)
		(layer "In6.Cu")
		(net "UPI_CPU0_CPU1_P2P2_DN<19>")
	)
	(segment
		(start 102.858824 -292.764972)
		(end 102.989634 -292.44925)
		(width 0.14732)
		(layer "In6.Cu")
		(net "UPI_CPU0_CPU1_P2P2_DN<19>")
	)
	(segment
		(start 306.06111 -318.550544)
		(end 305.850798 -318.962024)
		(width 0.14732)
		(layer "In6.Cu")
		(net "UPI_CPU0_CPU1_P2P2_DN<19>")
	)
	(segment
		(start 241.981736 -363.223302)
		(end 241.497866 -363.562138)
		(width 0.14732)
		(layer "In6.Cu")
		(net "UPI_CPU0_CPU1_P2P2_DN<19>")
	)
	(segment
		(start 266.672568 -338.718906)
		(end 267.152374 -339.198712)
		(width 0.14732)
		(layer "In6.Cu")
		(net "UPI_CPU0_CPU1_P2P2_DN<19>")
	)
	(segment
		(start 250.601988 -355.427788)
		(end 251.547884 -356.09022)
		(width 0.14732)
		(layer "In6.Cu")
		(net "UPI_CPU0_CPU1_P2P2_DN<19>")
	)
	(segment
		(start 75.843384 -360.595672)
		(end 72.274938 -351.990406)
		(width 0.14732)
		(layer "In6.Cu")
		(net "UPI_CPU0_CPU1_P2P2_DN<19>")
	)
	(segment
		(start 266.672568 -338.51088)
		(end 266.672568 -338.718906)
		(width 0.14732)
		(layer "In6.Cu")
		(net "UPI_CPU0_CPU1_P2P2_DN<19>")
	)
	(segment
		(start 273.130264 -333.656686)
		(end 272.6944 -333.656686)
		(width 0.14732)
		(layer "In6.Cu")
		(net "UPI_CPU0_CPU1_P2P2_DN<19>")
	)
	(segment
		(start 252.055376 -355.365812)
		(end 251.109226 -354.70338)
		(width 0.14732)
		(layer "In6.Cu")
		(net "UPI_CPU0_CPU1_P2P2_DN<19>")
	)
	(segment
		(start 105.828592 -284.35808)
		(end 105.829354 -284.357572)
		(width 0.0889)
		(layer "In6.Cu")
		(net "UPI_CPU0_CPU1_P2P2_DN<19>")
	)
	(segment
		(start 104.606344 -290.689284)
		(end 104.606344 -289.645852)
		(width 0.0889)
		(layer "In6.Cu")
		(net "UPI_CPU0_CPU1_P2P2_DN<19>")
	)
	(segment
		(start 249.396504 -359.162604)
		(end 248.450354 -358.500172)
		(width 0.14732)
		(layer "In6.Cu")
		(net "UPI_CPU0_CPU1_P2P2_DN<19>")
	)
	(segment
		(start 268.311376 -337.080098)
		(end 268.791182 -337.559904)
		(width 0.14732)
		(layer "In6.Cu")
		(net "UPI_CPU0_CPU1_P2P2_DN<19>")
	)
	(segment
		(start 240.28781 -364.588806)
		(end 240.08334 -364.552738)
		(width 0.14732)
		(layer "In6.Cu")
		(net "UPI_CPU0_CPU1_P2P2_DN<19>")
	)
	(segment
		(start 107.708192 -279.474676)
		(end 107.717082 -279.469596)
		(width 0.0889)
		(layer "In6.Cu")
		(net "UPI_CPU0_CPU1_P2P2_DN<19>")
	)
	(segment
		(start 335.04632 -290.514024)
		(end 334.117696 -291.442648)
		(width 0.14732)
		(layer "In6.Cu")
		(net "UPI_CPU0_CPU1_P2P2_DN<19>")
	)
	(segment
		(start 291.28593 -327.1901)
		(end 291.28593 -326.069452)
		(width 0.14732)
		(layer "In6.Cu")
		(net "UPI_CPU0_CPU1_P2P2_DN<19>")
	)
	(segment
		(start 292.86581 -325.922132)
		(end 292.71849 -326.069452)
		(width 0.14732)
		(layer "In6.Cu")
		(net "UPI_CPU0_CPU1_P2P2_DN<19>")
	)
	(segment
		(start 271.588992 -333.594456)
		(end 271.588992 -333.802482)
		(width 0.14732)
		(layer "In6.Cu")
		(net "UPI_CPU0_CPU1_P2P2_DN<19>")
	)
	(segment
		(start 98.952558 -372.849394)
		(end 80.419448 -365.171736)
		(width 0.14732)
		(layer "In6.Cu")
		(net "UPI_CPU0_CPU1_P2P2_DN<19>")
	)
	(segment
		(start 241.12855 -365.78921)
		(end 240.28781 -364.588806)
		(width 0.14732)
		(layer "In6.Cu")
		(net "UPI_CPU0_CPU1_P2P2_DN<19>")
	)
	(segment
		(start 240.404142 -366.296702)
		(end 240.328196 -366.725708)
		(width 0.14732)
		(layer "In6.Cu")
		(net "UPI_CPU0_CPU1_P2P2_DN<19>")
	)
	(segment
		(start 252.87732 -354.191824)
		(end 252.953266 -354.620576)
		(width 0.14732)
		(layer "In6.Cu")
		(net "UPI_CPU0_CPU1_P2P2_DN<19>")
	)
	(segment
		(start 272.068798 -334.282288)
		(end 272.068798 -334.718152)
		(width 0.14732)
		(layer "In6.Cu")
		(net "UPI_CPU0_CPU1_P2P2_DN<19>")
	)
	(segment
		(start 102.858824 -297.478958)
		(end 102.858824 -292.764972)
		(width 0.14732)
		(layer "In6.Cu")
		(net "UPI_CPU0_CPU1_P2P2_DN<19>")
	)
	(segment
		(start 253.384812 -353.467416)
		(end 252.438662 -352.804984)
		(width 0.14732)
		(layer "In6.Cu")
		(net "UPI_CPU0_CPU1_P2P2_DN<19>")
	)
	(segment
		(start 242.186206 -363.25937)
		(end 241.981736 -363.223302)
		(width 0.14732)
		(layer "In6.Cu")
		(net "UPI_CPU0_CPU1_P2P2_DN<19>")
	)
	(segment
		(start 72.79132 -329.909932)
		(end 73.540112 -327.205848)
		(width 0.14732)
		(layer "In6.Cu")
		(net "UPI_CPU0_CPU1_P2P2_DN<19>")
	)
	(segment
		(start 251.154692 -357.188262)
		(end 250.72594 -357.264208)
		(width 0.14732)
		(layer "In6.Cu")
		(net "UPI_CPU0_CPU1_P2P2_DN<19>")
	)
	(segment
		(start 108.773468 -277.522432)
		(end 108.460794 -277.522432)
		(width 0.0889)
		(layer "In6.Cu")
		(net "UPI_CPU0_CPU1_P2P2_DN<19>")
	)
	(segment
		(start 336.476594 -288.593022)
		(end 336.476848 -288.593276)
		(width 0.0889)
		(layer "In6.Cu")
		(net "UPI_CPU0_CPU1_P2P2_DN<19>")
	)
	(segment
		(start 311.571132 -315.486796)
		(end 310.675274 -316.382654)
		(width 0.14732)
		(layer "In6.Cu")
		(net "UPI_CPU0_CPU1_P2P2_DN<19>")
	)
	(segment
		(start 271.055592 -335.295494)
		(end 270.575532 -334.815434)
		(width 0.14732)
		(layer "In6.Cu")
		(net "UPI_CPU0_CPU1_P2P2_DN<19>")
	)
	(segment
		(start 212.31225 -372.160292)
		(end 199.037448 -369.819428)
		(width 0.14732)
		(layer "In6.Cu")
		(net "UPI_CPU0_CPU1_P2P2_DN<19>")
	)
	(segment
		(start 287.565084 -325.922132)
		(end 276.126702 -330.660248)
		(width 0.14732)
		(layer "In6.Cu")
		(net "UPI_CPU0_CPU1_P2P2_DN<19>")
	)
	(segment
		(start 243.455698 -364.53572)
		(end 243.026946 -364.459774)
		(width 0.14732)
		(layer "In6.Cu")
		(net "UPI_CPU0_CPU1_P2P2_DN<19>")
	)
	(segment
		(start 103.287068 -292.151816)
		(end 103.288084 -292.151816)
		(width 0.14732)
		(layer "In6.Cu")
		(net "UPI_CPU0_CPU1_P2P2_DN<19>")
	)
	(segment
		(start 108.177584 -278.661368)
		(end 108.178346 -278.66086)
		(width 0.0889)
		(layer "In6.Cu")
		(net "UPI_CPU0_CPU1_P2P2_DN<19>")
	)
	(segment
		(start 241.497866 -363.562138)
		(end 241.461798 -363.766608)
		(width 0.14732)
		(layer "In6.Cu")
		(net "UPI_CPU0_CPU1_P2P2_DN<19>")
	)
	(segment
		(start 291.28593 -326.069452)
		(end 291.13861 -325.922132)
		(width 0.14732)
		(layer "In6.Cu")
		(net "UPI_CPU0_CPU1_P2P2_DN<19>")
	)
	(segment
		(start 312.352182 -315.486796)
		(end 311.571132 -315.486796)
		(width 0.14732)
		(layer "In6.Cu")
		(net "UPI_CPU0_CPU1_P2P2_DN<19>")
	)
	(segment
		(start 106.485944 -283.219906)
		(end 106.485944 -283.205682)
		(width 0.0889)
		(layer "In6.Cu")
		(net "UPI_CPU0_CPU1_P2P2_DN<19>")
	)
	(segment
		(start 309.761128 -316.382654)
		(end 307.982874 -318.160908)
		(width 0.14732)
		(layer "In6.Cu")
		(net "UPI_CPU0_CPU1_P2P2_DN<19>")
	)
	(segment
		(start 291.13861 -325.922132)
		(end 287.565084 -325.922132)
		(width 0.14732)
		(layer "In6.Cu")
		(net "UPI_CPU0_CPU1_P2P2_DN<19>")
	)
	(segment
		(start 336.195162 -284.847538)
		(end 336.038698 -285.118556)
		(width 0.0889)
		(layer "In6.Cu")
		(net "UPI_CPU0_CPU1_P2P2_DN<19>")
	)
	(segment
		(start 104.889046 -287.613598)
		(end 104.897936 -287.608518)
		(width 0.0889)
		(layer "In6.Cu")
		(net "UPI_CPU0_CPU1_P2P2_DN<19>")
	)
	(segment
		(start 243.026946 -364.459774)
		(end 242.186206 -363.25937)
		(width 0.14732)
		(layer "In6.Cu")
		(net "UPI_CPU0_CPU1_P2P2_DN<19>")
	)
	(segment
		(start 252.234192 -352.841052)
		(end 251.895356 -353.324922)
		(width 0.14732)
		(layer "In6.Cu")
		(net "UPI_CPU0_CPU1_P2P2_DN<19>")
	)
	(segment
		(start 267.297916 -338.09305)
		(end 267.090398 -338.09305)
		(width 0.14732)
		(layer "In6.Cu")
		(net "UPI_CPU0_CPU1_P2P2_DN<19>")
	)
	(segment
		(start 330.608178 -300.193202)
		(end 317.03645 -313.764676)
		(width 0.14732)
		(layer "In6.Cu")
		(net "UPI_CPU0_CPU1_P2P2_DN<19>")
	)
	(segment
		(start 239.563402 -365.096044)
		(end 240.404142 -366.296702)
		(width 0.14732)
		(layer "In6.Cu")
		(net "UPI_CPU0_CPU1_P2P2_DN<19>")
	)
	(segment
		(start 332.553056 -293.781988)
		(end 330.608178 -300.193202)
		(width 0.14732)
		(layer "In6.Cu")
		(net "UPI_CPU0_CPU1_P2P2_DN<19>")
	)
	(segment
		(start 267.090398 -338.09305)
		(end 266.672568 -338.51088)
		(width 0.14732)
		(layer "In6.Cu")
		(net "UPI_CPU0_CPU1_P2P2_DN<19>")
	)
	(segment
		(start 316.956186 -313.84494)
		(end 313.994038 -313.84494)
		(width 0.14732)
		(layer "In6.Cu")
		(net "UPI_CPU0_CPU1_P2P2_DN<19>")
	)
	(segment
		(start 108.17225 -278.664416)
		(end 108.177584 -278.661368)
		(width 0.0889)
		(layer "In6.Cu")
		(net "UPI_CPU0_CPU1_P2P2_DN<19>")
	)
	(segment
		(start 266.575032 -340.211918)
		(end 266.139168 -340.211918)
		(width 0.14732)
		(layer "In6.Cu")
		(net "UPI_CPU0_CPU1_P2P2_DN<19>")
	)
	(segment
		(start 292.71849 -327.1901)
		(end 292.410642 -327.497948)
		(width 0.14732)
		(layer "In6.Cu")
		(net "UPI_CPU0_CPU1_P2P2_DN<19>")
	)
	(segment
		(start 265.659108 -339.731858)
		(end 265.45159 -339.731858)
		(width 0.14732)
		(layer "In6.Cu")
		(net "UPI_CPU0_CPU1_P2P2_DN<19>")
	)
	(segment
		(start 267.152374 -339.198712)
		(end 267.152374 -339.634576)
		(width 0.14732)
		(layer "In6.Cu")
		(net "UPI_CPU0_CPU1_P2P2_DN<19>")
	)
	(segment
		(start 336.476848 -288.593276)
		(end 336.46872 -288.597848)
		(width 0.0889)
		(layer "In6.Cu")
		(net "UPI_CPU0_CPU1_P2P2_DN<19>")
	)
	(segment
		(start 271.491456 -335.295494)
		(end 271.055592 -335.295494)
		(width 0.14732)
		(layer "In6.Cu")
		(net "UPI_CPU0_CPU1_P2P2_DN<19>")
	)
	(segment
		(start 199.037448 -369.819428)
		(end 159.140906 -376.85345)
		(width 0.14732)
		(layer "In6.Cu")
		(net "UPI_CPU0_CPU1_P2P2_DN<19>")
	)
	(segment
		(start 103.688896 -291.751004)
		(end 103.747824 -291.751004)
		(width 0.0889)
		(layer "In6.Cu")
		(net "UPI_CPU0_CPU1_P2P2_DN<19>")
	)
	(segment
		(start 317.03645 -313.76493)
		(end 316.956186 -313.84494)
		(width 0.14732)
		(layer "In6.Cu")
		(net "UPI_CPU0_CPU1_P2P2_DN<19>")
	)
	(segment
		(start 248.450354 -358.500172)
		(end 248.245884 -358.53624)
		(width 0.14732)
		(layer "In6.Cu")
		(net "UPI_CPU0_CPU1_P2P2_DN<19>")
	)
	(segment
		(start 272.21434 -333.176626)
		(end 272.006822 -333.176626)
		(width 0.14732)
		(layer "In6.Cu")
		(net "UPI_CPU0_CPU1_P2P2_DN<19>")
	)
	(segment
		(start 105.076498 -287.28924)
		(end 105.076498 -287.279334)
		(width 0.0889)
		(layer "In6.Cu")
		(net "UPI_CPU0_CPU1_P2P2_DN<19>")
	)
	(segment
		(start 272.006822 -333.176626)
		(end 271.588992 -333.594456)
		(width 0.14732)
		(layer "In6.Cu")
		(net "UPI_CPU0_CPU1_P2P2_DN<19>")
	)
	(segment
		(start 269.950184 -335.44129)
		(end 270.42999 -335.921096)
		(width 0.14732)
		(layer "In6.Cu")
		(net "UPI_CPU0_CPU1_P2P2_DN<19>")
	)
	(segment
		(start 108.365544 -278.345138)
		(end 108.365544 -278.31796)
		(width 0.0889)
		(layer "In6.Cu")
		(net "UPI_CPU0_CPU1_P2P2_DN<19>")
	)
	(segment
		(start 250.218448 -357.988616)
		(end 250.294394 -358.417368)
		(width 0.14732)
		(layer "In6.Cu")
		(net "UPI_CPU0_CPU1_P2P2_DN<19>")
	)
	(segment
		(start 249.825256 -359.086658)
		(end 249.396504 -359.162604)
		(width 0.14732)
		(layer "In6.Cu")
		(net "UPI_CPU0_CPU1_P2P2_DN<19>")
	)
	(arc
		(start 106.768392 -282.081478)
		(mid 106.565569 -281.881247)
		(end 106.486198 -281.607514)
		(width 0.0889)
		(layer "In6.Cu")
		(net "UPI_CPU0_CPU1_P2P2_DN<19>")
	)
	(arc
		(start 105.076244 -285.661354)
		(mid 105.15016 -285.381852)
		(end 105.352596 -285.175452)
		(width 0.0889)
		(layer "In6.Cu")
		(net "UPI_CPU0_CPU1_P2P2_DN<19>")
	)
	(arc
		(start 336.896456 -287.807908)
		(mid 336.796623 -287.907748)
		(end 336.760058 -288.044128)
		(width 0.0889)
		(layer "In6.Cu")
		(net "UPI_CPU0_CPU1_P2P2_DN<19>")
	)
	(arc
		(start 336.760058 -288.103056)
		(mid 336.687366 -288.380261)
		(end 336.488024 -288.586164)
		(width 0.0889)
		(layer "In6.Cu")
		(net "UPI_CPU0_CPU1_P2P2_DN<19>")
	)
	(arc
		(start 105.358946 -286.799782)
		(mid 105.493879 -286.666428)
		(end 105.546144 -286.48406)
		(width 0.0889)
		(layer "In6.Cu")
		(net "UPI_CPU0_CPU1_P2P2_DN<19>")
	)
	(arc
		(start 104.422194 -289.446462)
		(mid 104.248062 -289.307615)
		(end 104.136698 -289.114738)
		(width 0.0889)
		(layer "In6.Cu")
		(net "UPI_CPU0_CPU1_P2P2_DN<19>")
	)
	(arc
		(start 104.428036 -288.422334)
		(mid 104.55895 -288.285974)
		(end 104.606598 -288.103056)
		(width 0.0889)
		(layer "In6.Cu")
		(net "UPI_CPU0_CPU1_P2P2_DN<19>")
	)
	(arc
		(start 336.46872 -288.597848)
		(mid 336.337806 -288.734208)
		(end 336.290158 -288.917126)
		(width 0.0889)
		(layer "In6.Cu")
		(net "UPI_CPU0_CPU1_P2P2_DN<19>")
	)
	(arc
		(start 108.365544 -278.31796)
		(mid 108.445706 -278.045771)
		(end 108.647992 -277.84679)
		(width 0.0889)
		(layer "In6.Cu")
		(net "UPI_CPU0_CPU1_P2P2_DN<19>")
	)
	(arc
		(start 336.760312 -286.475424)
		(mid 336.807991 -286.658324)
		(end 336.938874 -286.794702)
		(width 0.0889)
		(layer "In6.Cu")
		(net "UPI_CPU0_CPU1_P2P2_DN<19>")
	)
	(arc
		(start 107.717082 -279.469596)
		(mid 107.847996 -279.333236)
		(end 107.895644 -279.150318)
		(width 0.0889)
		(layer "In6.Cu")
		(net "UPI_CPU0_CPU1_P2P2_DN<19>")
	)
	(arc
		(start 105.546144 -286.466788)
		(mid 105.493874 -286.284423)
		(end 105.358946 -286.151066)
		(width 0.0889)
		(layer "In6.Cu")
		(net "UPI_CPU0_CPU1_P2P2_DN<19>")
	)
	(arc
		(start 108.656882 -277.84171)
		(mid 108.772621 -277.729886)
		(end 108.830872 -277.579836)
		(width 0.0889)
		(layer "In6.Cu")
		(net "UPI_CPU0_CPU1_P2P2_DN<19>")
	)
	(arc
		(start 107.425744 -279.954228)
		(mid 107.503855 -279.677279)
		(end 107.708192 -279.474676)
		(width 0.0889)
		(layer "In6.Cu")
		(net "UPI_CPU0_CPU1_P2P2_DN<19>")
	)
	(arc
		(start 107.895644 -279.150318)
		(mid 107.969635 -278.870752)
		(end 108.17225 -278.664416)
		(width 0.0889)
		(layer "In6.Cu")
		(net "UPI_CPU0_CPU1_P2P2_DN<19>")
	)
	(arc
		(start 105.837482 -284.353)
		(mid 105.968396 -284.21664)
		(end 106.016044 -284.033722)
		(width 0.0889)
		(layer "In6.Cu")
		(net "UPI_CPU0_CPU1_P2P2_DN<19>")
	)
	(arc
		(start 104.606344 -289.645852)
		(mid 104.531339 -289.530393)
		(end 104.422194 -289.446462)
		(width 0.0889)
		(layer "In6.Cu")
		(net "UPI_CPU0_CPU1_P2P2_DN<19>")
	)
	(arc
		(start 106.777282 -282.725114)
		(mid 106.904536 -282.595148)
		(end 106.95559 -282.420568)
		(width 0.0889)
		(layer "In6.Cu")
		(net "UPI_CPU0_CPU1_P2P2_DN<19>")
	)
	(arc
		(start 107.238546 -280.288492)
		(mid 107.373479 -280.155138)
		(end 107.425744 -279.97277)
		(width 0.0889)
		(layer "In6.Cu")
		(net "UPI_CPU0_CPU1_P2P2_DN<19>")
	)
	(arc
		(start 106.486198 -281.576526)
		(mid 106.565568 -281.302792)
		(end 106.768392 -281.102562)
		(width 0.0889)
		(layer "In6.Cu")
		(net "UPI_CPU0_CPU1_P2P2_DN<19>")
	)
	(arc
		(start 336.079592 -285.220664)
		(mid 336.232976 -285.412583)
		(end 336.290412 -285.651448)
		(width 0.0889)
		(layer "In6.Cu")
		(net "UPI_CPU0_CPU1_P2P2_DN<19>")
	)
	(arc
		(start 336.290412 -285.661354)
		(mid 336.338091 -285.844254)
		(end 336.468974 -285.980632)
		(width 0.0889)
		(layer "In6.Cu")
		(net "UPI_CPU0_CPU1_P2P2_DN<19>")
	)
	(arc
		(start 106.955844 -282.405836)
		(mid 106.908165 -282.222936)
		(end 106.777282 -282.086558)
		(width 0.0889)
		(layer "In6.Cu")
		(net "UPI_CPU0_CPU1_P2P2_DN<19>")
	)
	(arc
		(start 106.777282 -281.097482)
		(mid 106.908196 -280.961122)
		(end 106.955844 -280.778204)
		(width 0.0889)
		(layer "In6.Cu")
		(net "UPI_CPU0_CPU1_P2P2_DN<19>")
	)
	(arc
		(start 105.546144 -284.837632)
		(mid 105.624255 -284.560683)
		(end 105.828592 -284.35808)
		(width 0.0889)
		(layer "In6.Cu")
		(net "UPI_CPU0_CPU1_P2P2_DN<19>")
	)
	(arc
		(start 104.897936 -287.608518)
		(mid 105.02885 -287.472158)
		(end 105.076498 -287.28924)
		(width 0.0889)
		(layer "In6.Cu")
		(net "UPI_CPU0_CPU1_P2P2_DN<19>")
	)
	(arc
		(start 105.358946 -286.151066)
		(mid 105.153874 -285.947387)
		(end 105.076244 -285.668974)
		(width 0.0889)
		(layer "In6.Cu")
		(net "UPI_CPU0_CPU1_P2P2_DN<19>")
	)
	(arc
		(start 108.178346 -278.66086)
		(mid 108.313279 -278.527506)
		(end 108.365544 -278.345138)
		(width 0.0889)
		(layer "In6.Cu")
		(net "UPI_CPU0_CPU1_P2P2_DN<19>")
	)
	(arc
		(start 106.016044 -284.033722)
		(mid 106.08996 -283.75422)
		(end 106.292396 -283.54782)
		(width 0.0889)
		(layer "In6.Cu")
		(net "UPI_CPU0_CPU1_P2P2_DN<19>")
	)
	(arc
		(start 105.076498 -287.279334)
		(mid 105.154609 -287.002385)
		(end 105.358946 -286.799782)
		(width 0.0889)
		(layer "In6.Cu")
		(net "UPI_CPU0_CPU1_P2P2_DN<19>")
	)
	(arc
		(start 105.367582 -285.166816)
		(mid 105.498496 -285.030456)
		(end 105.546144 -284.847538)
		(width 0.0889)
		(layer "In6.Cu")
		(net "UPI_CPU0_CPU1_P2P2_DN<19>")
	)
	(arc
		(start 336.062828 -285.20771)
		(mid 336.071272 -285.214107)
		(end 336.079592 -285.220664)
		(width 0.0889)
		(layer "In6.Cu")
		(net "UPI_CPU0_CPU1_P2P2_DN<19>")
	)
	(arc
		(start 336.477864 -285.985712)
		(mid 336.68015 -286.184693)
		(end 336.760312 -286.456882)
		(width 0.0889)
		(layer "In6.Cu")
		(net "UPI_CPU0_CPU1_P2P2_DN<19>")
	)
	(arc
		(start 104.606598 -288.09315)
		(mid 104.684709 -287.816201)
		(end 104.889046 -287.613598)
		(width 0.0889)
		(layer "In6.Cu")
		(net "UPI_CPU0_CPU1_P2P2_DN<19>")
	)
	(arc
		(start 106.307382 -283.539184)
		(mid 106.438296 -283.402824)
		(end 106.485944 -283.219906)
		(width 0.0889)
		(layer "In6.Cu")
		(net "UPI_CPU0_CPU1_P2P2_DN<19>")
	)
	(arc
		(start 104.136698 -288.898584)
		(mid 104.21686 -288.626395)
		(end 104.419146 -288.427414)
		(width 0.0889)
		(layer "In6.Cu")
		(net "UPI_CPU0_CPU1_P2P2_DN<19>")
	)
	(arc
		(start 106.485944 -283.205682)
		(mid 106.565085 -282.931059)
		(end 106.768392 -282.730194)
		(width 0.0889)
		(layer "In6.Cu")
		(net "UPI_CPU0_CPU1_P2P2_DN<19>")
	)
	(arc
		(start 106.955844 -280.76398)
		(mid 107.035063 -280.489295)
		(end 107.238546 -280.288492)
		(width 0.0889)
		(layer "In6.Cu")
		(net "UPI_CPU0_CPU1_P2P2_DN<19>")
	)
	(arc
		(start 336.947764 -286.799782)
		(mid 337.230278 -287.284688)
		(end 336.955638 -287.774126)
		(width 0.0889)
		(layer "In6.Cu")
		(net "UPI_CPU0_CPU1_P2P2_DN<19>")
	)
	(arc
		(start 106.95559 -282.420568)
		(mid 106.955787 -282.413203)
		(end 106.955844 -282.405836)
		(width 0.0889)
		(layer "In6.Cu")
		(net "UPI_CPU0_CPU1_P2P2_DN<19>")
	)
	(segment
		(start 339.014562 -281.05608)
		(end 339.014816 -281.056334)
		(width 0.13208)
		(layer "F.Cu")
		(net "UPI_CPU0_CPU1_P2P2_DN<18>")
	)
	(segment
		(start 107.520994 -277.522178)
		(end 107.520994 -277.522432)
		(width 0.13208)
		(layer "F.Cu")
		(net "UPI_CPU0_CPU1_P2P2_DN<18>")
	)
	(segment
		(start 339.014816 -281.056334)
		(end 339.014816 -281.591766)
		(width 0.13208)
		(layer "F.Cu")
		(net "UPI_CPU0_CPU1_P2P2_DN<18>")
	)
	(segment
		(start 107.521248 -276.986492)
		(end 107.521248 -277.521924)
		(width 0.13208)
		(layer "F.Cu")
		(net "UPI_CPU0_CPU1_P2P2_DN<18>")
	)
	(segment
		(start 107.521248 -277.521924)
		(end 107.520994 -277.522178)
		(width 0.13208)
		(layer "F.Cu")
		(net "UPI_CPU0_CPU1_P2P2_DN<18>")
	)
	(segment
		(start 339.014816 -281.591766)
		(end 339.014562 -281.59202)
		(width 0.13208)
		(layer "F.Cu")
		(net "UPI_CPU0_CPU1_P2P2_DN<18>")
	)
	(segment
		(start 74.748898 -359.42397)
		(end 74.581512 -359.020364)
		(width 0.14732)
		(layer "In6.Cu")
		(net "UPI_CPU0_CPU1_P2P2_DN<18>")
	)
	(segment
		(start 337.33105 -285.166816)
		(end 337.32216 -285.171896)
		(width 0.0889)
		(layer "In6.Cu")
		(net "UPI_CPU0_CPU1_P2P2_DN<18>")
	)
	(segment
		(start 95.46844 -305.549046)
		(end 95.672148 -305.569112)
		(width 0.14732)
		(layer "In6.Cu")
		(net "UPI_CPU0_CPU1_P2P2_DN<18>")
	)
	(segment
		(start 338.449412 -283.205682)
		(end 338.449412 -283.219906)
		(width 0.0889)
		(layer "In6.Cu")
		(net "UPI_CPU0_CPU1_P2P2_DN<18>")
	)
	(segment
		(start 103.677212 -290.61791)
		(end 103.677212 -290.481512)
		(width 0.0889)
		(layer "In6.Cu")
		(net "UPI_CPU0_CPU1_P2P2_DN<18>")
	)
	(segment
		(start 103.360982 -290.797742)
		(end 103.49738 -290.797742)
		(width 0.0889)
		(layer "In6.Cu")
		(net "UPI_CPU0_CPU1_P2P2_DN<18>")
	)
	(segment
		(start 94.937072 -306.172362)
		(end 94.957138 -305.968654)
		(width 0.14732)
		(layer "In6.Cu")
		(net "UPI_CPU0_CPU1_P2P2_DN<18>")
	)
	(segment
		(start 73.272904 -355.86543)
		(end 73.113138 -355.79939)
		(width 0.14732)
		(layer "In6.Cu")
		(net "UPI_CPU0_CPU1_P2P2_DN<18>")
	)
	(segment
		(start 255.503172 -352.283268)
		(end 248.850404 -361.785662)
		(width 0.14732)
		(layer "In6.Cu")
		(net "UPI_CPU0_CPU1_P2P2_DN<18>")
	)
	(segment
		(start 336.18932 -290.319968)
		(end 335.54924 -290.960048)
		(width 0.14732)
		(layer "In6.Cu")
		(net "UPI_CPU0_CPU1_P2P2_DN<18>")
	)
	(segment
		(start 298.713652 -328.129138)
		(end 283.857446 -328.129138)
		(width 0.14732)
		(layer "In6.Cu")
		(net "UPI_CPU0_CPU1_P2P2_DN<18>")
	)
	(segment
		(start 88.348566 -311.392062)
		(end 89.6366 -310.334914)
		(width 0.14732)
		(layer "In6.Cu")
		(net "UPI_CPU0_CPU1_P2P2_DN<18>")
	)
	(segment
		(start 104.514396 -285.336996)
		(end 104.51719 -285.335472)
		(width 0.0889)
		(layer "In6.Cu")
		(net "UPI_CPU0_CPU1_P2P2_DN<18>")
	)
	(segment
		(start 102.252272 -292.607492)
		(end 102.348792 -292.510972)
		(width 0.0889)
		(layer "In6.Cu")
		(net "UPI_CPU0_CPU1_P2P2_DN<18>")
	)
	(segment
		(start 73.011792 -355.236526)
		(end 72.844406 -354.83292)
		(width 0.14732)
		(layer "In6.Cu")
		(net "UPI_CPU0_CPU1_P2P2_DN<18>")
	)
	(segment
		(start 313.54776 -315.63564)
		(end 312.752486 -316.431168)
		(width 0.14732)
		(layer "In6.Cu")
		(net "UPI_CPU0_CPU1_P2P2_DN<18>")
	)
	(segment
		(start 73.44029 -356.269036)
		(end 73.272904 -355.86543)
		(width 0.14732)
		(layer "In6.Cu")
		(net "UPI_CPU0_CPU1_P2P2_DN<18>")
	)
	(segment
		(start 74.315066 -324.247256)
		(end 81.777332 -316.784482)
		(width 0.14732)
		(layer "In6.Cu")
		(net "UPI_CPU0_CPU1_P2P2_DN<18>")
	)
	(segment
		(start 337.509612 -284.837632)
		(end 337.509612 -284.847538)
		(width 0.0889)
		(layer "In6.Cu")
		(net "UPI_CPU0_CPU1_P2P2_DN<18>")
	)
	(segment
		(start 104.512872 -285.337758)
		(end 104.514396 -285.336996)
		(width 0.0889)
		(layer "In6.Cu")
		(net "UPI_CPU0_CPU1_P2P2_DN<18>")
	)
	(segment
		(start 103.571294 -289.27806)
		(end 103.571548 -289.277806)
		(width 0.0889)
		(layer "In6.Cu")
		(net "UPI_CPU0_CPU1_P2P2_DN<18>")
	)
	(segment
		(start 159.191452 -377.43003)
		(end 125.998224 -377.43003)
		(width 0.14732)
		(layer "In6.Cu")
		(net "UPI_CPU0_CPU1_P2P2_DN<18>")
	)
	(segment
		(start 309.594758 -317.934086)
		(end 307.487574 -319.896744)
		(width 0.14732)
		(layer "In6.Cu")
		(net "UPI_CPU0_CPU1_P2P2_DN<18>")
	)
	(segment
		(start 336.563208 -289.573462)
		(end 336.563208 -290.005008)
		(width 0.0889)
		(layer "In6.Cu")
		(net "UPI_CPU0_CPU1_P2P2_DN<18>")
	)
	(segment
		(start 104.505506 -285.342076)
		(end 104.512872 -285.337758)
		(width 0.0889)
		(layer "In6.Cu")
		(net "UPI_CPU0_CPU1_P2P2_DN<18>")
	)
	(segment
		(start 95.672148 -305.569112)
		(end 95.957136 -305.335178)
		(width 0.14732)
		(layer "In6.Cu")
		(net "UPI_CPU0_CPU1_P2P2_DN<18>")
	)
	(segment
		(start 283.857446 -328.129138)
		(end 276.688042 -331.098906)
		(width 0.14732)
		(layer "In6.Cu")
		(net "UPI_CPU0_CPU1_P2P2_DN<18>")
	)
	(segment
		(start 72.945752 -355.396038)
		(end 73.011792 -355.236526)
		(width 0.14732)
		(layer "In6.Cu")
		(net "UPI_CPU0_CPU1_P2P2_DN<18>")
	)
	(segment
		(start 240.226088 -367.824258)
		(end 212.311996 -372.745)
		(width 0.14732)
		(layer "In6.Cu")
		(net "UPI_CPU0_CPU1_P2P2_DN<18>")
	)
	(segment
		(start 337.039458 -289.097212)
		(end 336.563208 -289.573462)
		(width 0.0889)
		(layer "In6.Cu")
		(net "UPI_CPU0_CPU1_P2P2_DN<18>")
	)
	(segment
		(start 104.51465 -286.964882)
		(end 104.520746 -286.961326)
		(width 0.0889)
		(layer "In6.Cu")
		(net "UPI_CPU0_CPU1_P2P2_DN<18>")
	)
	(segment
		(start 104.50576 -286.969962)
		(end 104.51465 -286.964882)
		(width 0.0889)
		(layer "In6.Cu")
		(net "UPI_CPU0_CPU1_P2P2_DN<18>")
	)
	(segment
		(start 89.840562 -310.35498)
		(end 90.12555 -310.121046)
		(width 0.14732)
		(layer "In6.Cu")
		(net "UPI_CPU0_CPU1_P2P2_DN<18>")
	)
	(segment
		(start 107.75569 -277.814278)
		(end 107.677458 -277.79345)
		(width 0.0889)
		(layer "In6.Cu")
		(net "UPI_CPU0_CPU1_P2P2_DN<18>")
	)
	(segment
		(start 103.181404 -291.113718)
		(end 103.181404 -290.97732)
		(width 0.0889)
		(layer "In6.Cu")
		(net "UPI_CPU0_CPU1_P2P2_DN<18>")
	)
	(segment
		(start 102.1842 -297.62577)
		(end 102.294436 -297.359324)
		(width 0.14732)
		(layer "In6.Cu")
		(net "UPI_CPU0_CPU1_P2P2_DN<18>")
	)
	(segment
		(start 262.624316 -352.5774)
		(end 262.206486 -352.99523)
		(width 0.14732)
		(layer "In6.Cu")
		(net "UPI_CPU0_CPU1_P2P2_DN<18>")
	)
	(segment
		(start 92.94749 -307.617876)
		(end 93.476064 -307.184044)
		(width 0.14732)
		(layer "In6.Cu")
		(net "UPI_CPU0_CPU1_P2P2_DN<18>")
	)
	(segment
		(start 337.79206 -286.964882)
		(end 337.80095 -286.969962)
		(width 0.0889)
		(layer "In6.Cu")
		(net "UPI_CPU0_CPU1_P2P2_DN<18>")
	)
	(segment
		(start 74.296778 -358.334056)
		(end 74.129392 -357.930196)
		(width 0.14732)
		(layer "In6.Cu")
		(net "UPI_CPU0_CPU1_P2P2_DN<18>")
	)
	(segment
		(start 74.129392 -357.930196)
		(end 73.96988 -357.86441)
		(width 0.14732)
		(layer "In6.Cu")
		(net "UPI_CPU0_CPU1_P2P2_DN<18>")
	)
	(segment
		(start 337.979512 -284.023816)
		(end 337.979512 -284.033722)
		(width 0.0889)
		(layer "In6.Cu")
		(net "UPI_CPU0_CPU1_P2P2_DN<18>")
	)
	(segment
		(start 74.581512 -359.020364)
		(end 74.422 -358.954324)
		(width 0.14732)
		(layer "In6.Cu")
		(net "UPI_CPU0_CPU1_P2P2_DN<18>")
	)
	(segment
		(start 72.237854 -329.832462)
		(end 73.033636 -326.958198)
		(width 0.14732)
		(layer "In6.Cu")
		(net "UPI_CPU0_CPU1_P2P2_DN<18>")
	)
	(segment
		(start 258.177284 -349.609664)
		(end 257.599942 -350.187006)
		(width 0.14732)
		(layer "In6.Cu")
		(net "UPI_CPU0_CPU1_P2P2_DN<18>")
	)
	(segment
		(start 88.331294 -311.563512)
		(end 88.348312 -311.391808)
		(width 0.14732)
		(layer "In6.Cu")
		(net "UPI_CPU0_CPU1_P2P2_DN<18>")
	)
	(segment
		(start 73.37425 -356.428548)
		(end 73.44029 -356.269036)
		(width 0.14732)
		(layer "In6.Cu")
		(net "UPI_CPU0_CPU1_P2P2_DN<18>")
	)
	(segment
		(start 87.997284 -311.837578)
		(end 88.331294 -311.563512)
		(width 0.14732)
		(layer "In6.Cu")
		(net "UPI_CPU0_CPU1_P2P2_DN<18>")
	)
	(segment
		(start 103.857298 -288.121598)
		(end 103.857298 -288.103056)
		(width 0.0889)
		(layer "In6.Cu")
		(net "UPI_CPU0_CPU1_P2P2_DN<18>")
	)
	(segment
		(start 336.263742 -290.304474)
		(end 336.204814 -290.304474)
		(width 0.0889)
		(layer "In6.Cu")
		(net "UPI_CPU0_CPU1_P2P2_DN<18>")
	)
	(segment
		(start 102.294436 -297.359324)
		(end 102.294436 -293.509446)
		(width 0.14732)
		(layer "In6.Cu")
		(net "UPI_CPU0_CPU1_P2P2_DN<18>")
	)
	(segment
		(start 102.252272 -292.160452)
		(end 102.252272 -291.906452)
		(width 0.0889)
		(layer "In6.Cu")
		(net "UPI_CPU0_CPU1_P2P2_DN<18>")
	)
	(segment
		(start 337.795362 -287.611566)
		(end 337.7946 -287.612074)
		(width 0.0889)
		(layer "In6.Cu")
		(net "UPI_CPU0_CPU1_P2P2_DN<18>")
	)
	(segment
		(start 98.794316 -373.394478)
		(end 80.118204 -365.658908)
		(width 0.14732)
		(layer "In6.Cu")
		(net "UPI_CPU0_CPU1_P2P2_DN<18>")
	)
	(segment
		(start 334.587342 -291.92093)
		(end 332.970886 -294.337232)
		(width 0.14732)
		(layer "In6.Cu")
		(net "UPI_CPU0_CPU1_P2P2_DN<18>")
	)
	(segment
		(start 104.04475 -287.778698)
		(end 104.050846 -287.775142)
		(width 0.0889)
		(layer "In6.Cu")
		(net "UPI_CPU0_CPU1_P2P2_DN<18>")
	)
	(segment
		(start 106.85526 -278.017224)
		(end 106.86415 -278.012144)
		(width 0.0889)
		(layer "In6.Cu")
		(net "UPI_CPU0_CPU1_P2P2_DN<18>")
	)
	(segment
		(start 337.039712 -285.651448)
		(end 337.039712 -285.675578)
		(width 0.0889)
		(layer "In6.Cu")
		(net "UPI_CPU0_CPU1_P2P2_DN<18>")
	)
	(segment
		(start 260.286754 -353.309682)
		(end 260.286754 -353.517454)
		(width 0.14732)
		(layer "In6.Cu")
		(net "UPI_CPU0_CPU1_P2P2_DN<18>")
	)
	(segment
		(start 95.977202 -305.13147)
		(end 97.612708 -303.789334)
		(width 0.14732)
		(layer "In6.Cu")
		(net "UPI_CPU0_CPU1_P2P2_DN<18>")
	)
	(segment
		(start 263.14654 -350.657668)
		(end 262.938768 -350.657668)
		(width 0.14732)
		(layer "In6.Cu")
		(net "UPI_CPU0_CPU1_P2P2_DN<18>")
	)
	(segment
		(start 107.677458 -277.79345)
		(end 107.520994 -277.522432)
		(width 0.0889)
		(layer "In6.Cu")
		(net "UPI_CPU0_CPU1_P2P2_DN<18>")
	)
	(segment
		(start 248.850404 -361.785662)
		(end 240.226088 -367.824258)
		(width 0.14732)
		(layer "In6.Cu")
		(net "UPI_CPU0_CPU1_P2P2_DN<18>")
	)
	(segment
		(start 87.825834 -311.82056)
		(end 87.997284 -311.837578)
		(width 0.14732)
		(layer "In6.Cu")
		(net "UPI_CPU0_CPU1_P2P2_DN<18>")
	)
	(segment
		(start 306.645564 -320.408808)
		(end 305.765708 -322.169282)
		(width 0.14732)
		(layer "In6.Cu")
		(net "UPI_CPU0_CPU1_P2P2_DN<18>")
	)
	(segment
		(start 107.332272 -277.198836)
		(end 107.333796 -277.198074)
		(width 0.0889)
		(layer "In6.Cu")
		(net "UPI_CPU0_CPU1_P2P2_DN<18>")
	)
	(segment
		(start 106.676698 -278.346408)
		(end 106.676698 -278.336502)
		(width 0.0889)
		(layer "In6.Cu")
		(net "UPI_CPU0_CPU1_P2P2_DN<18>")
	)
	(segment
		(start 263.56437 -350.032066)
		(end 263.56437 -350.239838)
		(width 0.14732)
		(layer "In6.Cu")
		(net "UPI_CPU0_CPU1_P2P2_DN<18>")
	)
	(segment
		(start 106.206798 -279.160224)
		(end 106.206798 -279.150318)
		(width 0.0889)
		(layer "In6.Cu")
		(net "UPI_CPU0_CPU1_P2P2_DN<18>")
	)
	(segment
		(start 74.683112 -359.583482)
		(end 74.748898 -359.42397)
		(width 0.14732)
		(layer "In6.Cu")
		(net "UPI_CPU0_CPU1_P2P2_DN<18>")
	)
	(segment
		(start 102.294436 -293.487348)
		(end 102.252272 -293.445184)
		(width 0.0889)
		(layer "In6.Cu")
		(net "UPI_CPU0_CPU1_P2P2_DN<18>")
	)
	(segment
		(start 73.96988 -357.86441)
		(end 73.802494 -357.461058)
		(width 0.14732)
		(layer "In6.Cu")
		(net "UPI_CPU0_CPU1_P2P2_DN<18>")
	)
	(segment
		(start 336.563208 -290.005008)
		(end 336.263742 -290.304474)
		(width 0.0889)
		(layer "In6.Cu")
		(net "UPI_CPU0_CPU1_P2P2_DN<18>")
	)
	(segment
		(start 276.688042 -331.098906)
		(end 260.877558 -346.90939)
		(width 0.14732)
		(layer "In6.Cu")
		(net "UPI_CPU0_CPU1_P2P2_DN<18>")
	)
	(segment
		(start 105.445306 -283.714444)
		(end 105.460546 -283.705554)
		(width 0.0889)
		(layer "In6.Cu")
		(net "UPI_CPU0_CPU1_P2P2_DN<18>")
	)
	(segment
		(start 103.56596 -288.597848)
		(end 103.57485 -288.592768)
		(width 0.0889)
		(layer "In6.Cu")
		(net "UPI_CPU0_CPU1_P2P2_DN<18>")
	)
	(segment
		(start 91.030552 -309.191152)
		(end 92.438728 -308.035452)
		(width 0.14732)
		(layer "In6.Cu")
		(net "UPI_CPU0_CPU1_P2P2_DN<18>")
	)
	(segment
		(start 263.56437 -350.239838)
		(end 263.14654 -350.657668)
		(width 0.14732)
		(layer "In6.Cu")
		(net "UPI_CPU0_CPU1_P2P2_DN<18>")
	)
	(segment
		(start 337.039458 -288.902902)
		(end 337.039458 -289.097212)
		(width 0.0889)
		(layer "In6.Cu")
		(net "UPI_CPU0_CPU1_P2P2_DN<18>")
	)
	(segment
		(start 103.49738 -290.797742)
		(end 103.677212 -290.61791)
		(width 0.0889)
		(layer "In6.Cu")
		(net "UPI_CPU0_CPU1_P2P2_DN<18>")
	)
	(segment
		(start 299.662342 -326.732138)
		(end 299.662342 -327.180448)
		(width 0.14732)
		(layer "In6.Cu")
		(net "UPI_CPU0_CPU1_P2P2_DN<18>")
	)
	(segment
		(start 93.476064 -307.184044)
		(end 93.679772 -307.20411)
		(width 0.14732)
		(layer "In6.Cu")
		(net "UPI_CPU0_CPU1_P2P2_DN<18>")
	)
	(segment
		(start 107.146344 -277.54453)
		(end 107.146344 -277.522432)
		(width 0.0889)
		(layer "In6.Cu")
		(net "UPI_CPU0_CPU1_P2P2_DN<18>")
	)
	(segment
		(start 337.80095 -284.353)
		(end 337.79206 -284.35808)
		(width 0.0889)
		(layer "In6.Cu")
		(net "UPI_CPU0_CPU1_P2P2_DN<18>")
	)
	(segment
		(start 312.752486 -316.431168)
		(end 312.752486 -316.443868)
		(width 0.14732)
		(layer "In6.Cu")
		(net "UPI_CPU0_CPU1_P2P2_DN<18>")
	)
	(segment
		(start 102.294436 -293.509446)
		(end 102.294436 -293.487348)
		(width 0.0889)
		(layer "In6.Cu")
		(net "UPI_CPU0_CPU1_P2P2_DN<18>")
	)
	(segment
		(start 256.538476 -351.248472)
		(end 255.503426 -352.283014)
		(width 0.14732)
		(layer "In6.Cu")
		(net "UPI_CPU0_CPU1_P2P2_DN<18>")
	)
	(segment
		(start 337.792822 -287.61309)
		(end 337.79206 -287.613598)
		(width 0.0889)
		(layer "In6.Cu")
		(net "UPI_CPU0_CPU1_P2P2_DN<18>")
	)
	(segment
		(start 105.460546 -283.705554)
		(end 105.460292 -283.705808)
		(width 0.0889)
		(layer "In6.Cu")
		(net "UPI_CPU0_CPU1_P2P2_DN<18>")
	)
	(segment
		(start 107.324906 -277.203154)
		(end 107.332272 -277.198836)
		(width 0.0889)
		(layer "In6.Cu")
		(net "UPI_CPU0_CPU1_P2P2_DN<18>")
	)
	(segment
		(start 102.252272 -291.906452)
		(end 102.865174 -291.29355)
		(width 0.0889)
		(layer "In6.Cu")
		(net "UPI_CPU0_CPU1_P2P2_DN<18>")
	)
	(segment
		(start 92.438728 -308.035452)
		(end 92.642436 -308.055518)
		(width 0.14732)
		(layer "In6.Cu")
		(net "UPI_CPU0_CPU1_P2P2_DN<18>")
	)
	(segment
		(start 105.454196 -281.102562)
		(end 105.445306 -281.097482)
		(width 0.0889)
		(layer "In6.Cu")
		(net "UPI_CPU0_CPU1_P2P2_DN<18>")
	)
	(segment
		(start 261.998714 -352.99523)
		(end 258.613148 -349.609664)
		(width 0.14732)
		(layer "In6.Cu")
		(net "UPI_CPU0_CPU1_P2P2_DN<18>")
	)
	(segment
		(start 339.327236 -281.59202)
		(end 339.38464 -281.649424)
		(width 0.0889)
		(layer "In6.Cu")
		(net "UPI_CPU0_CPU1_P2P2_DN<18>")
	)
	(segment
		(start 337.509612 -286.466788)
		(end 337.509612 -286.48533)
		(width 0.0889)
		(layer "In6.Cu")
		(net "UPI_CPU0_CPU1_P2P2_DN<18>")
	)
	(segment
		(start 102.252272 -293.445184)
		(end 102.252272 -292.607492)
		(width 0.0889)
		(layer "In6.Cu")
		(net "UPI_CPU0_CPU1_P2P2_DN<18>")
	)
	(segment
		(start 259.868924 -353.935284)
		(end 259.661152 -353.935284)
		(width 0.14732)
		(layer "In6.Cu")
		(net "UPI_CPU0_CPU1_P2P2_DN<18>")
	)
	(segment
		(start 92.642436 -308.055518)
		(end 92.927424 -307.821584)
		(width 0.14732)
		(layer "In6.Cu")
		(net "UPI_CPU0_CPU1_P2P2_DN<18>")
	)
	(segment
		(start 301.644812 -324.749668)
		(end 299.662342 -326.732138)
		(width 0.14732)
		(layer "In6.Cu")
		(net "UPI_CPU0_CPU1_P2P2_DN<18>")
	)
	(segment
		(start 103.001572 -291.29355)
		(end 103.181404 -291.113718)
		(width 0.0889)
		(layer "In6.Cu")
		(net "UPI_CPU0_CPU1_P2P2_DN<18>")
	)
	(segment
		(start 337.509612 -288.09315)
		(end 337.509612 -288.103056)
		(width 0.0889)
		(layer "In6.Cu")
		(net "UPI_CPU0_CPU1_P2P2_DN<18>")
	)
	(segment
		(start 103.677212 -290.481512)
		(end 103.85679 -290.301934)
		(width 0.0889)
		(layer "In6.Cu")
		(net "UPI_CPU0_CPU1_P2P2_DN<18>")
	)
	(segment
		(start 262.938768 -350.657668)
		(end 260.251956 -347.970856)
		(width 0.14732)
		(layer "In6.Cu")
		(net "UPI_CPU0_CPU1_P2P2_DN<18>")
	)
	(segment
		(start 97.612708 -303.789334)
		(end 102.1842 -297.62577)
		(width 0.14732)
		(layer "In6.Cu")
		(net "UPI_CPU0_CPU1_P2P2_DN<18>")
	)
	(segment
		(start 106.38536 -278.83104)
		(end 106.39425 -278.82596)
		(width 0.0889)
		(layer "In6.Cu")
		(net "UPI_CPU0_CPU1_P2P2_DN<18>")
	)
	(segment
		(start 93.984826 -306.766468)
		(end 94.448376 -306.38623)
		(width 0.14732)
		(layer "In6.Cu")
		(net "UPI_CPU0_CPU1_P2P2_DN<18>")
	)
	(segment
		(start 314.033154 -315.434472)
		(end 313.54776 -315.63564)
		(width 0.14732)
		(layer "In6.Cu")
		(net "UPI_CPU0_CPU1_P2P2_DN<18>")
	)
	(segment
		(start 105.736898 -283.219906)
		(end 105.736898 -283.21127)
		(width 0.0889)
		(layer "In6.Cu")
		(net "UPI_CPU0_CPU1_P2P2_DN<18>")
	)
	(segment
		(start 74.230992 -358.493314)
		(end 74.296778 -358.334056)
		(width 0.14732)
		(layer "In6.Cu")
		(net "UPI_CPU0_CPU1_P2P2_DN<18>")
	)
	(segment
		(start 338.741004 -282.725114)
		(end 338.732114 -282.730194)
		(width 0.0889)
		(layer "In6.Cu")
		(net "UPI_CPU0_CPU1_P2P2_DN<18>")
	)
	(segment
		(start 104.03586 -287.783778)
		(end 104.04475 -287.778698)
		(width 0.0889)
		(layer "In6.Cu")
		(net "UPI_CPU0_CPU1_P2P2_DN<18>")
	)
	(segment
		(start 103.181404 -290.97732)
		(end 103.360982 -290.797742)
		(width 0.0889)
		(layer "In6.Cu")
		(net "UPI_CPU0_CPU1_P2P2_DN<18>")
	)
	(segment
		(start 103.387398 -289.078416)
		(end 103.387398 -288.917126)
		(width 0.0889)
		(layer "In6.Cu")
		(net "UPI_CPU0_CPU1_P2P2_DN<18>")
	)
	(segment
		(start 312.441082 -316.755272)
		(end 309.594758 -317.934086)
		(width 0.14732)
		(layer "In6.Cu")
		(net "UPI_CPU0_CPU1_P2P2_DN<18>")
	)
	(segment
		(start 106.206544 -282.424378)
		(end 106.206544 -282.390342)
		(width 0.0889)
		(layer "In6.Cu")
		(net "UPI_CPU0_CPU1_P2P2_DN<18>")
	)
	(segment
		(start 260.877558 -347.345254)
		(end 263.56437 -350.032066)
		(width 0.14732)
		(layer "In6.Cu")
		(net "UPI_CPU0_CPU1_P2P2_DN<18>")
	)
	(segment
		(start 72.684894 -354.76688)
		(end 71.713598 -352.425508)
		(width 0.14732)
		(layer "In6.Cu")
		(net "UPI_CPU0_CPU1_P2P2_DN<18>")
	)
	(segment
		(start 102.865174 -291.29355)
		(end 103.001572 -291.29355)
		(width 0.0889)
		(layer "In6.Cu")
		(net "UPI_CPU0_CPU1_P2P2_DN<18>")
	)
	(segment
		(start 337.80095 -287.608518)
		(end 337.800188 -287.609026)
		(width 0.0889)
		(layer "In6.Cu")
		(net "UPI_CPU0_CPU1_P2P2_DN<18>")
	)
	(segment
		(start 307.487574 -319.896744)
		(end 306.982114 -320.095626)
		(width 0.14732)
		(layer "In6.Cu")
		(net "UPI_CPU0_CPU1_P2P2_DN<18>")
	)
	(segment
		(start 335.548224 -290.960048)
		(end 334.587342 -291.92093)
		(width 0.14732)
		(layer "In6.Cu")
		(net "UPI_CPU0_CPU1_P2P2_DN<18>")
	)
	(segment
		(start 71.713598 -335.156556)
		(end 72.237854 -329.832462)
		(width 0.14732)
		(layer "In6.Cu")
		(net "UPI_CPU0_CPU1_P2P2_DN<18>")
	)
	(segment
		(start 305.765708 -322.169282)
		(end 302.710596 -324.307962)
		(width 0.14732)
		(layer "In6.Cu")
		(net "UPI_CPU0_CPU1_P2P2_DN<18>")
	)
	(segment
		(start 337.7946 -287.612074)
		(end 337.792822 -287.61309)
		(width 0.0889)
		(layer "In6.Cu")
		(net "UPI_CPU0_CPU1_P2P2_DN<18>")
	)
	(segment
		(start 335.54924 -290.960048)
		(end 335.548224 -290.960048)
		(width 0.14732)
		(layer "In6.Cu")
		(net "UPI_CPU0_CPU1_P2P2_DN<18>")
	)
	(segment
		(start 259.23875 -348.984062)
		(end 262.624316 -352.369628)
		(width 0.14732)
		(layer "In6.Cu")
		(net "UPI_CPU0_CPU1_P2P2_DN<18>")
	)
	(segment
		(start 102.348792 -292.510972)
		(end 102.348792 -292.256972)
		(width 0.0889)
		(layer "In6.Cu")
		(net "UPI_CPU0_CPU1_P2P2_DN<18>")
	)
	(segment
		(start 73.113138 -355.79939)
		(end 72.945752 -355.396038)
		(width 0.14732)
		(layer "In6.Cu")
		(net "UPI_CPU0_CPU1_P2P2_DN<18>")
	)
	(segment
		(start 338.27085 -283.539184)
		(end 338.26196 -283.544264)
		(width 0.0889)
		(layer "In6.Cu")
		(net "UPI_CPU0_CPU1_P2P2_DN<18>")
	)
	(segment
		(start 102.348792 -292.256972)
		(end 102.252272 -292.160452)
		(width 0.0889)
		(layer "In6.Cu")
		(net "UPI_CPU0_CPU1_P2P2_DN<18>")
	)
	(segment
		(start 337.800188 -287.609026)
		(end 337.795362 -287.611566)
		(width 0.0889)
		(layer "In6.Cu")
		(net "UPI_CPU0_CPU1_P2P2_DN<18>")
	)
	(segment
		(start 299.662342 -327.180448)
		(end 298.713652 -328.129138)
		(width 0.14732)
		(layer "In6.Cu")
		(net "UPI_CPU0_CPU1_P2P2_DN<18>")
	)
	(segment
		(start 336.204814 -290.304474)
		(end 336.18932 -290.319968)
		(width 0.0889)
		(layer "In6.Cu")
		(net "UPI_CPU0_CPU1_P2P2_DN<18>")
	)
	(segment
		(start 262.206486 -352.99523)
		(end 261.998714 -352.99523)
		(width 0.14732)
		(layer "In6.Cu")
		(net "UPI_CPU0_CPU1_P2P2_DN<18>")
	)
	(segment
		(start 93.96476 -306.97043)
		(end 93.984826 -306.766468)
		(width 0.14732)
		(layer "In6.Cu")
		(net "UPI_CPU0_CPU1_P2P2_DN<18>")
	)
	(segment
		(start 95.957136 -305.335178)
		(end 95.977202 -305.13147)
		(width 0.14732)
		(layer "In6.Cu")
		(net "UPI_CPU0_CPU1_P2P2_DN<18>")
	)
	(segment
		(start 312.752486 -316.443868)
		(end 312.441082 -316.755272)
		(width 0.14732)
		(layer "In6.Cu")
		(net "UPI_CPU0_CPU1_P2P2_DN<18>")
	)
	(segment
		(start 212.311996 -372.745)
		(end 199.040242 -370.404644)
		(width 0.14732)
		(layer "In6.Cu")
		(net "UPI_CPU0_CPU1_P2P2_DN<18>")
	)
	(segment
		(start 260.286754 -353.517454)
		(end 259.868924 -353.935284)
		(width 0.14732)
		(layer "In6.Cu")
		(net "UPI_CPU0_CPU1_P2P2_DN<18>")
	)
	(segment
		(start 105.445306 -280.458926)
		(end 105.454196 -280.453846)
		(width 0.0889)
		(layer "In6.Cu")
		(net "UPI_CPU0_CPU1_P2P2_DN<18>")
	)
	(segment
		(start 331.106526 -300.481746)
		(end 316.1538 -315.434472)
		(width 0.14732)
		(layer "In6.Cu")
		(net "UPI_CPU0_CPU1_P2P2_DN<18>")
	)
	(segment
		(start 71.713598 -352.425508)
		(end 71.713598 -335.156556)
		(width 0.14732)
		(layer "In6.Cu")
		(net "UPI_CPU0_CPU1_P2P2_DN<18>")
	)
	(segment
		(start 255.503426 -352.283014)
		(end 255.503172 -352.283268)
		(width 0.14732)
		(layer "In6.Cu")
		(net "UPI_CPU0_CPU1_P2P2_DN<18>")
	)
	(segment
		(start 257.599942 -350.62287)
		(end 260.286754 -353.309682)
		(width 0.14732)
		(layer "In6.Cu")
		(net "UPI_CPU0_CPU1_P2P2_DN<18>")
	)
	(segment
		(start 93.679772 -307.20411)
		(end 93.96476 -306.97043)
		(width 0.14732)
		(layer "In6.Cu")
		(net "UPI_CPU0_CPU1_P2P2_DN<18>")
	)
	(segment
		(start 94.957138 -305.968654)
		(end 95.46844 -305.549046)
		(width 0.14732)
		(layer "In6.Cu")
		(net "UPI_CPU0_CPU1_P2P2_DN<18>")
	)
	(segment
		(start 73.802494 -357.461058)
		(end 73.868534 -357.301546)
		(width 0.14732)
		(layer "In6.Cu")
		(net "UPI_CPU0_CPU1_P2P2_DN<18>")
	)
	(segment
		(start 332.970886 -294.337232)
		(end 331.106526 -300.481746)
		(width 0.14732)
		(layer "In6.Cu")
		(net "UPI_CPU0_CPU1_P2P2_DN<18>")
	)
	(segment
		(start 107.708192 -277.198074)
		(end 107.717082 -277.203154)
		(width 0.0889)
		(layer "In6.Cu")
		(net "UPI_CPU0_CPU1_P2P2_DN<18>")
	)
	(segment
		(start 94.448376 -306.38623)
		(end 94.652084 -306.406296)
		(width 0.14732)
		(layer "In6.Cu")
		(net "UPI_CPU0_CPU1_P2P2_DN<18>")
	)
	(segment
		(start 104.513634 -285.985204)
		(end 104.505506 -285.980632)
		(width 0.0889)
		(layer "In6.Cu")
		(net "UPI_CPU0_CPU1_P2P2_DN<18>")
	)
	(segment
		(start 338.919566 -282.390342)
		(end 338.919566 -282.405836)
		(width 0.0889)
		(layer "In6.Cu")
		(net "UPI_CPU0_CPU1_P2P2_DN<18>")
	)
	(segment
		(start 72.844406 -354.83292)
		(end 72.684894 -354.76688)
		(width 0.14732)
		(layer "In6.Cu")
		(net "UPI_CPU0_CPU1_P2P2_DN<18>")
	)
	(segment
		(start 259.23875 -348.548198)
		(end 259.23875 -348.984062)
		(width 0.14732)
		(layer "In6.Cu")
		(net "UPI_CPU0_CPU1_P2P2_DN<18>")
	)
	(segment
		(start 104.51719 -285.335472)
		(end 104.520492 -285.33344)
		(width 0.0889)
		(layer "In6.Cu")
		(net "UPI_CPU0_CPU1_P2P2_DN<18>")
	)
	(segment
		(start 105.266744 -284.043628)
		(end 105.266744 -284.033722)
		(width 0.0889)
		(layer "In6.Cu")
		(net "UPI_CPU0_CPU1_P2P2_DN<18>")
	)
	(segment
		(start 105.460292 -281.106118)
		(end 105.454196 -281.102562)
		(width 0.0889)
		(layer "In6.Cu")
		(net "UPI_CPU0_CPU1_P2P2_DN<18>")
	)
	(segment
		(start 104.797098 -284.847538)
		(end 104.797098 -284.838902)
		(width 0.0889)
		(layer "In6.Cu")
		(net "UPI_CPU0_CPU1_P2P2_DN<18>")
	)
	(segment
		(start 258.613148 -349.609664)
		(end 258.177284 -349.609664)
		(width 0.14732)
		(layer "In6.Cu")
		(net "UPI_CPU0_CPU1_P2P2_DN<18>")
	)
	(segment
		(start 256.97434 -351.248472)
		(end 256.538476 -351.248472)
		(width 0.14732)
		(layer "In6.Cu")
		(net "UPI_CPU0_CPU1_P2P2_DN<18>")
	)
	(segment
		(start 90.145616 -309.917338)
		(end 90.52179 -309.608728)
		(width 0.14732)
		(layer "In6.Cu")
		(net "UPI_CPU0_CPU1_P2P2_DN<18>")
	)
	(segment
		(start 73.868534 -357.301546)
		(end 73.701148 -356.89794)
		(width 0.14732)
		(layer "In6.Cu")
		(net "UPI_CPU0_CPU1_P2P2_DN<18>")
	)
	(segment
		(start 103.85679 -290.301934)
		(end 103.85679 -289.610292)
		(width 0.0889)
		(layer "In6.Cu")
		(net "UPI_CPU0_CPU1_P2P2_DN<18>")
	)
	(segment
		(start 73.541636 -356.8319)
		(end 73.37425 -356.428548)
		(width 0.14732)
		(layer "In6.Cu")
		(net "UPI_CPU0_CPU1_P2P2_DN<18>")
	)
	(segment
		(start 94.652084 -306.406296)
		(end 94.937072 -306.172362)
		(width 0.14732)
		(layer "In6.Cu")
		(net "UPI_CPU0_CPU1_P2P2_DN<18>")
	)
	(segment
		(start 90.725498 -309.628794)
		(end 91.010486 -309.39486)
		(width 0.14732)
		(layer "In6.Cu")
		(net "UPI_CPU0_CPU1_P2P2_DN<18>")
	)
	(segment
		(start 74.422 -358.954324)
		(end 74.230992 -358.493314)
		(width 0.14732)
		(layer "In6.Cu")
		(net "UPI_CPU0_CPU1_P2P2_DN<18>")
	)
	(segment
		(start 73.701148 -356.89794)
		(end 73.541636 -356.8319)
		(width 0.14732)
		(layer "In6.Cu")
		(net "UPI_CPU0_CPU1_P2P2_DN<18>")
	)
	(segment
		(start 80.118204 -365.658908)
		(end 75.13574 -360.674666)
		(width 0.14732)
		(layer "In6.Cu")
		(net "UPI_CPU0_CPU1_P2P2_DN<18>")
	)
	(segment
		(start 337.33105 -288.422334)
		(end 337.32216 -288.427414)
		(width 0.0889)
		(layer "In6.Cu")
		(net "UPI_CPU0_CPU1_P2P2_DN<18>")
	)
	(segment
		(start 73.033636 -326.958198)
		(end 74.315066 -324.247256)
		(width 0.14732)
		(layer "In6.Cu")
		(net "UPI_CPU0_CPU1_P2P2_DN<18>")
	)
	(segment
		(start 90.52179 -309.608728)
		(end 90.725498 -309.628794)
		(width 0.14732)
		(layer "In6.Cu")
		(net "UPI_CPU0_CPU1_P2P2_DN<18>")
	)
	(segment
		(start 105.92435 -281.916378)
		(end 105.91546 -281.911298)
		(width 0.0889)
		(layer "In6.Cu")
		(net "UPI_CPU0_CPU1_P2P2_DN<18>")
	)
	(segment
		(start 316.1538 -315.434472)
		(end 314.033154 -315.434472)
		(width 0.14732)
		(layer "In6.Cu")
		(net "UPI_CPU0_CPU1_P2P2_DN<18>")
	)
	(segment
		(start 262.624316 -352.369628)
		(end 262.624316 -352.5774)
		(width 0.14732)
		(layer "In6.Cu")
		(net "UPI_CPU0_CPU1_P2P2_DN<18>")
	)
	(segment
		(start 260.877558 -346.90939)
		(end 260.877558 -347.345254)
		(width 0.14732)
		(layer "In6.Cu")
		(net "UPI_CPU0_CPU1_P2P2_DN<18>")
	)
	(segment
		(start 92.927424 -307.821584)
		(end 92.94749 -307.617876)
		(width 0.14732)
		(layer "In6.Cu")
		(net "UPI_CPU0_CPU1_P2P2_DN<18>")
	)
	(segment
		(start 125.998224 -377.43003)
		(end 98.794316 -373.394478)
		(width 0.14732)
		(layer "In6.Cu")
		(net "UPI_CPU0_CPU1_P2P2_DN<18>")
	)
	(segment
		(start 75.13574 -360.674666)
		(end 74.683112 -359.583482)
		(width 0.14732)
		(layer "In6.Cu")
		(net "UPI_CPU0_CPU1_P2P2_DN<18>")
	)
	(segment
		(start 257.599942 -350.187006)
		(end 257.599942 -350.62287)
		(width 0.14732)
		(layer "In6.Cu")
		(net "UPI_CPU0_CPU1_P2P2_DN<18>")
	)
	(segment
		(start 90.12555 -310.121046)
		(end 90.145616 -309.917338)
		(width 0.14732)
		(layer "In6.Cu")
		(net "UPI_CPU0_CPU1_P2P2_DN<18>")
	)
	(segment
		(start 104.797098 -286.475424)
		(end 104.797098 -286.467804)
		(width 0.0889)
		(layer "In6.Cu")
		(net "UPI_CPU0_CPU1_P2P2_DN<18>")
	)
	(segment
		(start 260.251956 -347.970856)
		(end 259.816092 -347.970856)
		(width 0.14732)
		(layer "In6.Cu")
		(net "UPI_CPU0_CPU1_P2P2_DN<18>")
	)
	(segment
		(start 104.514396 -285.985712)
		(end 104.513634 -285.985204)
		(width 0.0889)
		(layer "In6.Cu")
		(net "UPI_CPU0_CPU1_P2P2_DN<18>")
	)
	(segment
		(start 259.661152 -353.935284)
		(end 256.97434 -351.248472)
		(width 0.14732)
		(layer "In6.Cu")
		(net "UPI_CPU0_CPU1_P2P2_DN<18>")
	)
	(segment
		(start 339.014562 -281.59202)
		(end 339.327236 -281.59202)
		(width 0.0889)
		(layer "In6.Cu")
		(net "UPI_CPU0_CPU1_P2P2_DN<18>")
	)
	(segment
		(start 199.040242 -370.404644)
		(end 159.191452 -377.43003)
		(width 0.14732)
		(layer "In6.Cu")
		(net "UPI_CPU0_CPU1_P2P2_DN<18>")
	)
	(segment
		(start 259.816092 -347.970856)
		(end 259.23875 -348.548198)
		(width 0.14732)
		(layer "In6.Cu")
		(net "UPI_CPU0_CPU1_P2P2_DN<18>")
	)
	(segment
		(start 105.91546 -279.644856)
		(end 105.92435 -279.639776)
		(width 0.0889)
		(layer "In6.Cu")
		(net "UPI_CPU0_CPU1_P2P2_DN<18>")
	)
	(segment
		(start 89.6366 -310.334914)
		(end 89.840562 -310.35498)
		(width 0.14732)
		(layer "In6.Cu")
		(net "UPI_CPU0_CPU1_P2P2_DN<18>")
	)
	(segment
		(start 339.21065 -281.911298)
		(end 339.20176 -281.916378)
		(width 0.0889)
		(layer "In6.Cu")
		(net "UPI_CPU0_CPU1_P2P2_DN<18>")
	)
	(segment
		(start 88.348312 -311.391808)
		(end 88.348566 -311.392062)
		(width 0.14732)
		(layer "In6.Cu")
		(net "UPI_CPU0_CPU1_P2P2_DN<18>")
	)
	(segment
		(start 81.777332 -316.784482)
		(end 87.825834 -311.82056)
		(width 0.14732)
		(layer "In6.Cu")
		(net "UPI_CPU0_CPU1_P2P2_DN<18>")
	)
	(segment
		(start 306.982114 -320.095626)
		(end 306.645564 -320.408808)
		(width 0.14732)
		(layer "In6.Cu")
		(net "UPI_CPU0_CPU1_P2P2_DN<18>")
	)
	(segment
		(start 91.010486 -309.39486)
		(end 91.030552 -309.191152)
		(width 0.14732)
		(layer "In6.Cu")
		(net "UPI_CPU0_CPU1_P2P2_DN<18>")
	)
	(segment
		(start 302.710596 -324.307962)
		(end 301.644812 -324.749668)
		(width 0.14732)
		(layer "In6.Cu")
		(net "UPI_CPU0_CPU1_P2P2_DN<18>")
	)
	(segment
		(start 105.736898 -279.978358)
		(end 105.736898 -279.964134)
		(width 0.0889)
		(layer "In6.Cu")
		(net "UPI_CPU0_CPU1_P2P2_DN<18>")
	)
	(arc
		(start 337.509612 -286.48533)
		(mid 337.587723 -286.762279)
		(end 337.79206 -286.964882)
		(width 0.0889)
		(layer "In6.Cu")
		(net "UPI_CPU0_CPU1_P2P2_DN<18>")
	)
	(arc
		(start 103.571548 -289.277806)
		(mid 103.462401 -289.193878)
		(end 103.387398 -289.078416)
		(width 0.0889)
		(layer "In6.Cu")
		(net "UPI_CPU0_CPU1_P2P2_DN<18>")
	)
	(arc
		(start 105.736898 -283.21127)
		(mid 105.789168 -283.028905)
		(end 105.924096 -282.895548)
		(width 0.0889)
		(layer "In6.Cu")
		(net "UPI_CPU0_CPU1_P2P2_DN<18>")
	)
	(arc
		(start 338.26196 -283.544264)
		(mid 338.057625 -283.746869)
		(end 337.979512 -284.023816)
		(width 0.0889)
		(layer "In6.Cu")
		(net "UPI_CPU0_CPU1_P2P2_DN<18>")
	)
	(arc
		(start 337.322414 -286.151066)
		(mid 337.457347 -286.28442)
		(end 337.509612 -286.466788)
		(width 0.0889)
		(layer "In6.Cu")
		(net "UPI_CPU0_CPU1_P2P2_DN<18>")
	)
	(arc
		(start 105.454196 -280.453846)
		(mid 105.657677 -280.253042)
		(end 105.736898 -279.978358)
		(width 0.0889)
		(layer "In6.Cu")
		(net "UPI_CPU0_CPU1_P2P2_DN<18>")
	)
	(arc
		(start 105.736898 -279.964134)
		(mid 105.784577 -279.781234)
		(end 105.91546 -279.644856)
		(width 0.0889)
		(layer "In6.Cu")
		(net "UPI_CPU0_CPU1_P2P2_DN<18>")
	)
	(arc
		(start 103.857298 -288.103056)
		(mid 103.904977 -287.920156)
		(end 104.03586 -287.783778)
		(width 0.0889)
		(layer "In6.Cu")
		(net "UPI_CPU0_CPU1_P2P2_DN<18>")
	)
	(arc
		(start 106.676952 -278.32177)
		(mid 106.728006 -278.14719)
		(end 106.85526 -278.017224)
		(width 0.0889)
		(layer "In6.Cu")
		(net "UPI_CPU0_CPU1_P2P2_DN<18>")
	)
	(arc
		(start 105.460292 -283.705808)
		(mid 105.662879 -283.499457)
		(end 105.736898 -283.219906)
		(width 0.0889)
		(layer "In6.Cu")
		(net "UPI_CPU0_CPU1_P2P2_DN<18>")
	)
	(arc
		(start 105.445306 -281.097482)
		(mid 105.266709 -280.778204)
		(end 105.445306 -280.458926)
		(width 0.0889)
		(layer "In6.Cu")
		(net "UPI_CPU0_CPU1_P2P2_DN<18>")
	)
	(arc
		(start 103.85679 -289.610292)
		(mid 103.74556 -289.417088)
		(end 103.571294 -289.27806)
		(width 0.0889)
		(layer "In6.Cu")
		(net "UPI_CPU0_CPU1_P2P2_DN<18>")
	)
	(arc
		(start 104.797098 -286.467804)
		(mid 104.719469 -286.189391)
		(end 104.514396 -285.985712)
		(width 0.0889)
		(layer "In6.Cu")
		(net "UPI_CPU0_CPU1_P2P2_DN<18>")
	)
	(arc
		(start 106.39425 -278.82596)
		(mid 106.598585 -278.623355)
		(end 106.676698 -278.346408)
		(width 0.0889)
		(layer "In6.Cu")
		(net "UPI_CPU0_CPU1_P2P2_DN<18>")
	)
	(arc
		(start 105.91546 -281.911298)
		(mid 105.784546 -281.774938)
		(end 105.736898 -281.59202)
		(width 0.0889)
		(layer "In6.Cu")
		(net "UPI_CPU0_CPU1_P2P2_DN<18>")
	)
	(arc
		(start 104.505506 -285.980632)
		(mid 104.32703 -285.661354)
		(end 104.505506 -285.342076)
		(width 0.0889)
		(layer "In6.Cu")
		(net "UPI_CPU0_CPU1_P2P2_DN<18>")
	)
	(arc
		(start 104.327198 -287.28924)
		(mid 104.374877 -287.10634)
		(end 104.50576 -286.969962)
		(width 0.0889)
		(layer "In6.Cu")
		(net "UPI_CPU0_CPU1_P2P2_DN<18>")
	)
	(arc
		(start 337.80095 -286.969962)
		(mid 337.979547 -287.28924)
		(end 337.80095 -287.608518)
		(width 0.0889)
		(layer "In6.Cu")
		(net "UPI_CPU0_CPU1_P2P2_DN<18>")
	)
	(arc
		(start 107.89539 -277.53691)
		(mid 107.855621 -277.690742)
		(end 107.75569 -277.814278)
		(width 0.0889)
		(layer "In6.Cu")
		(net "UPI_CPU0_CPU1_P2P2_DN<18>")
	)
	(arc
		(start 106.206798 -279.150318)
		(mid 106.254477 -278.967418)
		(end 106.38536 -278.83104)
		(width 0.0889)
		(layer "In6.Cu")
		(net "UPI_CPU0_CPU1_P2P2_DN<18>")
	)
	(arc
		(start 107.895644 -277.522432)
		(mid 107.895589 -277.529672)
		(end 107.89539 -277.53691)
		(width 0.0889)
		(layer "In6.Cu")
		(net "UPI_CPU0_CPU1_P2P2_DN<18>")
	)
	(arc
		(start 103.57485 -288.592768)
		(mid 103.777136 -288.393787)
		(end 103.857298 -288.121598)
		(width 0.0889)
		(layer "In6.Cu")
		(net "UPI_CPU0_CPU1_P2P2_DN<18>")
	)
	(arc
		(start 337.79206 -287.613598)
		(mid 337.587725 -287.816203)
		(end 337.509612 -288.09315)
		(width 0.0889)
		(layer "In6.Cu")
		(net "UPI_CPU0_CPU1_P2P2_DN<18>")
	)
	(arc
		(start 104.520746 -286.961326)
		(mid 104.723159 -286.754913)
		(end 104.797098 -286.475424)
		(width 0.0889)
		(layer "In6.Cu")
		(net "UPI_CPU0_CPU1_P2P2_DN<18>")
	)
	(arc
		(start 339.38464 -281.649424)
		(mid 339.326484 -281.799537)
		(end 339.21065 -281.911298)
		(width 0.0889)
		(layer "In6.Cu")
		(net "UPI_CPU0_CPU1_P2P2_DN<18>")
	)
	(arc
		(start 104.797098 -284.838902)
		(mid 104.849368 -284.656537)
		(end 104.984296 -284.52318)
		(width 0.0889)
		(layer "In6.Cu")
		(net "UPI_CPU0_CPU1_P2P2_DN<18>")
	)
	(arc
		(start 104.984296 -284.52318)
		(mid 105.188631 -284.320575)
		(end 105.266744 -284.043628)
		(width 0.0889)
		(layer "In6.Cu")
		(net "UPI_CPU0_CPU1_P2P2_DN<18>")
	)
	(arc
		(start 107.146344 -277.522432)
		(mid 107.194023 -277.339532)
		(end 107.324906 -277.203154)
		(width 0.0889)
		(layer "In6.Cu")
		(net "UPI_CPU0_CPU1_P2P2_DN<18>")
	)
	(arc
		(start 337.79206 -284.35808)
		(mid 337.587725 -284.560685)
		(end 337.509612 -284.837632)
		(width 0.0889)
		(layer "In6.Cu")
		(net "UPI_CPU0_CPU1_P2P2_DN<18>")
	)
	(arc
		(start 337.32216 -288.427414)
		(mid 337.118679 -288.628218)
		(end 337.039458 -288.902902)
		(width 0.0889)
		(layer "In6.Cu")
		(net "UPI_CPU0_CPU1_P2P2_DN<18>")
	)
	(arc
		(start 107.333796 -277.198074)
		(mid 107.520994 -277.147931)
		(end 107.708192 -277.198074)
		(width 0.0889)
		(layer "In6.Cu")
		(net "UPI_CPU0_CPU1_P2P2_DN<18>")
	)
	(arc
		(start 338.449412 -283.219906)
		(mid 338.401733 -283.402806)
		(end 338.27085 -283.539184)
		(width 0.0889)
		(layer "In6.Cu")
		(net "UPI_CPU0_CPU1_P2P2_DN<18>")
	)
	(arc
		(start 103.387398 -288.917126)
		(mid 103.435077 -288.734226)
		(end 103.56596 -288.597848)
		(width 0.0889)
		(layer "In6.Cu")
		(net "UPI_CPU0_CPU1_P2P2_DN<18>")
	)
	(arc
		(start 107.717082 -277.203154)
		(mid 107.847996 -277.339514)
		(end 107.895644 -277.522432)
		(width 0.0889)
		(layer "In6.Cu")
		(net "UPI_CPU0_CPU1_P2P2_DN<18>")
	)
	(arc
		(start 105.92435 -279.639776)
		(mid 106.128685 -279.437171)
		(end 106.206798 -279.160224)
		(width 0.0889)
		(layer "In6.Cu")
		(net "UPI_CPU0_CPU1_P2P2_DN<18>")
	)
	(arc
		(start 105.924096 -282.895548)
		(mid 106.126382 -282.696567)
		(end 106.206544 -282.424378)
		(width 0.0889)
		(layer "In6.Cu")
		(net "UPI_CPU0_CPU1_P2P2_DN<18>")
	)
	(arc
		(start 106.206544 -282.390342)
		(mid 106.127174 -282.116608)
		(end 105.92435 -281.916378)
		(width 0.0889)
		(layer "In6.Cu")
		(net "UPI_CPU0_CPU1_P2P2_DN<18>")
	)
	(arc
		(start 106.86415 -278.012144)
		(mid 107.065432 -277.814657)
		(end 107.146344 -277.54453)
		(width 0.0889)
		(layer "In6.Cu")
		(net "UPI_CPU0_CPU1_P2P2_DN<18>")
	)
	(arc
		(start 105.266744 -284.033722)
		(mid 105.314423 -283.850822)
		(end 105.445306 -283.714444)
		(width 0.0889)
		(layer "In6.Cu")
		(net "UPI_CPU0_CPU1_P2P2_DN<18>")
	)
	(arc
		(start 105.736898 -281.59202)
		(mid 105.662907 -281.312454)
		(end 105.460292 -281.106118)
		(width 0.0889)
		(layer "In6.Cu")
		(net "UPI_CPU0_CPU1_P2P2_DN<18>")
	)
	(arc
		(start 337.979512 -284.033722)
		(mid 337.931833 -284.216622)
		(end 337.80095 -284.353)
		(width 0.0889)
		(layer "In6.Cu")
		(net "UPI_CPU0_CPU1_P2P2_DN<18>")
	)
	(arc
		(start 337.509612 -284.847538)
		(mid 337.461933 -285.030438)
		(end 337.33105 -285.166816)
		(width 0.0889)
		(layer "In6.Cu")
		(net "UPI_CPU0_CPU1_P2P2_DN<18>")
	)
	(arc
		(start 104.050846 -287.775142)
		(mid 104.253259 -287.568729)
		(end 104.327198 -287.28924)
		(width 0.0889)
		(layer "In6.Cu")
		(net "UPI_CPU0_CPU1_P2P2_DN<18>")
	)
	(arc
		(start 337.32216 -285.171896)
		(mid 337.117825 -285.374501)
		(end 337.039712 -285.651448)
		(width 0.0889)
		(layer "In6.Cu")
		(net "UPI_CPU0_CPU1_P2P2_DN<18>")
	)
	(arc
		(start 338.919566 -282.405836)
		(mid 338.871887 -282.588736)
		(end 338.741004 -282.725114)
		(width 0.0889)
		(layer "In6.Cu")
		(net "UPI_CPU0_CPU1_P2P2_DN<18>")
	)
	(arc
		(start 106.676698 -278.336502)
		(mid 106.67675 -278.329135)
		(end 106.676952 -278.32177)
		(width 0.0889)
		(layer "In6.Cu")
		(net "UPI_CPU0_CPU1_P2P2_DN<18>")
	)
	(arc
		(start 104.520492 -285.33344)
		(mid 104.723079 -285.127089)
		(end 104.797098 -284.847538)
		(width 0.0889)
		(layer "In6.Cu")
		(net "UPI_CPU0_CPU1_P2P2_DN<18>")
	)
	(arc
		(start 339.20176 -281.916378)
		(mid 338.998937 -282.116609)
		(end 338.919566 -282.390342)
		(width 0.0889)
		(layer "In6.Cu")
		(net "UPI_CPU0_CPU1_P2P2_DN<18>")
	)
	(arc
		(start 338.732114 -282.730194)
		(mid 338.528633 -282.930998)
		(end 338.449412 -283.205682)
		(width 0.0889)
		(layer "In6.Cu")
		(net "UPI_CPU0_CPU1_P2P2_DN<18>")
	)
	(arc
		(start 337.039712 -285.675578)
		(mid 337.118931 -285.950263)
		(end 337.322414 -286.151066)
		(width 0.0889)
		(layer "In6.Cu")
		(net "UPI_CPU0_CPU1_P2P2_DN<18>")
	)
	(arc
		(start 337.509612 -288.103056)
		(mid 337.461933 -288.285956)
		(end 337.33105 -288.422334)
		(width 0.0889)
		(layer "In6.Cu")
		(net "UPI_CPU0_CPU1_P2P2_DN<18>")
	)
	(segment
		(start 339.48497 -281.87015)
		(end 339.48497 -282.405582)
		(width 0.13208)
		(layer "F.Cu")
		(net "UPI_CPU0_CPU1_P2P2_DN<17>")
	)
	(segment
		(start 107.051094 -276.172676)
		(end 107.051094 -276.708362)
		(width 0.13208)
		(layer "F.Cu")
		(net "UPI_CPU0_CPU1_P2P2_DN<17>")
	)
	(segment
		(start 339.48497 -282.405582)
		(end 339.484716 -282.405836)
		(width 0.13208)
		(layer "F.Cu")
		(net "UPI_CPU0_CPU1_P2P2_DN<17>")
	)
	(segment
		(start 339.484716 -281.869896)
		(end 339.48497 -281.87015)
		(width 0.13208)
		(layer "F.Cu")
		(net "UPI_CPU0_CPU1_P2P2_DN<17>")
	)
	(segment
		(start 107.051094 -276.708362)
		(end 107.051348 -276.708616)
		(width 0.13208)
		(layer "F.Cu")
		(net "UPI_CPU0_CPU1_P2P2_DN<17>")
	)
	(segment
		(start 106.80573 -277.00351)
		(end 106.894884 -276.979634)
		(width 0.0889)
		(layer "In6.Cu")
		(net "UPI_CPU0_CPU1_P2P2_DN<17>")
	)
	(segment
		(start 277.315168 -332.040992)
		(end 265.042142 -344.314018)
		(width 0.14732)
		(layer "In6.Cu")
		(net "UPI_CPU0_CPU1_P2P2_DN<17>")
	)
	(segment
		(start 338.170012 -289.322256)
		(end 337.87334 -289.618928)
		(width 0.0889)
		(layer "In6.Cu")
		(net "UPI_CPU0_CPU1_P2P2_DN<17>")
	)
	(segment
		(start 250.538742 -367.46942)
		(end 250.230894 -367.777268)
		(width 0.14732)
		(layer "In6.Cu")
		(net "UPI_CPU0_CPU1_P2P2_DN<17>")
	)
	(segment
		(start 96.520508 -303.257966)
		(end 97.96653 -301.30877)
		(width 0.14732)
		(layer "In6.Cu")
		(net "UPI_CPU0_CPU1_P2P2_DN<17>")
	)
	(segment
		(start 70.603618 -353.007422)
		(end 70.603618 -335.16316)
		(width 0.14732)
		(layer "In6.Cu")
		(net "UPI_CPU0_CPU1_P2P2_DN<17>")
	)
	(segment
		(start 103.946706 -284.35935)
		(end 103.948484 -284.358334)
		(width 0.0889)
		(layer "In6.Cu")
		(net "UPI_CPU0_CPU1_P2P2_DN<17>")
	)
	(segment
		(start 251.422662 -363.987588)
		(end 251.275342 -363.840268)
		(width 0.14732)
		(layer "In6.Cu")
		(net "UPI_CPU0_CPU1_P2P2_DN<17>")
	)
	(segment
		(start 199.037956 -371.537738)
		(end 199.037448 -371.537738)
		(width 0.14732)
		(layer "In6.Cu")
		(net "UPI_CPU0_CPU1_P2P2_DN<17>")
	)
	(segment
		(start 103.942896 -284.361636)
		(end 103.946706 -284.35935)
		(width 0.0889)
		(layer "In6.Cu")
		(net "UPI_CPU0_CPU1_P2P2_DN<17>")
	)
	(segment
		(start 250.538742 -363.987588)
		(end 250.538742 -367.46942)
		(width 0.14732)
		(layer "In6.Cu")
		(net "UPI_CPU0_CPU1_P2P2_DN<17>")
	)
	(segment
		(start 337.158838 -290.998148)
		(end 335.45526 -292.701726)
		(width 0.14732)
		(layer "In6.Cu")
		(net "UPI_CPU0_CPU1_P2P2_DN<17>")
	)
	(segment
		(start 103.482394 -285.169864)
		(end 103.487982 -285.166816)
		(width 0.0889)
		(layer "In6.Cu")
		(net "UPI_CPU0_CPU1_P2P2_DN<17>")
	)
	(segment
		(start 307.419248 -323.374004)
		(end 306.801774 -323.991478)
		(width 0.14732)
		(layer "In6.Cu")
		(net "UPI_CPU0_CPU1_P2P2_DN<17>")
	)
	(segment
		(start 100.254816 -295.785286)
		(end 100.254816 -295.323006)
		(width 0.14732)
		(layer "In6.Cu")
		(net "UPI_CPU0_CPU1_P2P2_DN<17>")
	)
	(segment
		(start 103.479854 -285.171388)
		(end 103.481632 -285.170372)
		(width 0.0889)
		(layer "In6.Cu")
		(net "UPI_CPU0_CPU1_P2P2_DN<17>")
	)
	(segment
		(start 250.686062 -363.840268)
		(end 250.538742 -363.987588)
		(width 0.14732)
		(layer "In6.Cu")
		(net "UPI_CPU0_CPU1_P2P2_DN<17>")
	)
	(segment
		(start 106.016044 -277.522432)
		(end 106.016044 -277.512526)
		(width 0.0889)
		(layer "In6.Cu")
		(net "UPI_CPU0_CPU1_P2P2_DN<17>")
	)
	(segment
		(start 337.87334 -290.224718)
		(end 337.659472 -290.438586)
		(width 0.0889)
		(layer "In6.Cu")
		(net "UPI_CPU0_CPU1_P2P2_DN<17>")
	)
	(segment
		(start 98.533204 -374.483122)
		(end 79.445866 -366.576864)
		(width 0.14732)
		(layer "In6.Cu")
		(net "UPI_CPU0_CPU1_P2P2_DN<17>")
	)
	(segment
		(start 333.92745 -294.985694)
		(end 332.08087 -301.070772)
		(width 0.14732)
		(layer "In6.Cu")
		(net "UPI_CPU0_CPU1_P2P2_DN<17>")
	)
	(segment
		(start 104.426004 -281.271472)
		(end 104.422702 -281.269694)
		(width 0.0889)
		(layer "In6.Cu")
		(net "UPI_CPU0_CPU1_P2P2_DN<17>")
	)
	(segment
		(start 102.726744 -290.181284)
		(end 102.726744 -289.645852)
		(width 0.0889)
		(layer "In6.Cu")
		(net "UPI_CPU0_CPU1_P2P2_DN<17>")
	)
	(segment
		(start 103.009192 -287.613598)
		(end 103.018082 -287.608518)
		(width 0.0889)
		(layer "In6.Cu")
		(net "UPI_CPU0_CPU1_P2P2_DN<17>")
	)
	(segment
		(start 339.484716 -282.405836)
		(end 339.328252 -282.676854)
		(width 0.0889)
		(layer "In6.Cu")
		(net "UPI_CPU0_CPU1_P2P2_DN<17>")
	)
	(segment
		(start 301.57928 -327.317862)
		(end 299.665644 -329.231498)
		(width 0.14732)
		(layer "In6.Cu")
		(net "UPI_CPU0_CPU1_P2P2_DN<17>")
	)
	(segment
		(start 105.546144 -278.336248)
		(end 105.546398 -278.322024)
		(width 0.0889)
		(layer "In6.Cu")
		(net "UPI_CPU0_CPU1_P2P2_DN<17>")
	)
	(segment
		(start 104.42067 -281.268424)
		(end 104.419146 -281.267662)
		(width 0.0889)
		(layer "In6.Cu")
		(net "UPI_CPU0_CPU1_P2P2_DN<17>")
	)
	(segment
		(start 306.801774 -323.991478)
		(end 302.312578 -325.850504)
		(width 0.14732)
		(layer "In6.Cu")
		(net "UPI_CPU0_CPU1_P2P2_DN<17>")
	)
	(segment
		(start 265.042142 -344.314018)
		(end 265.042142 -364.905798)
		(width 0.14732)
		(layer "In6.Cu")
		(net "UPI_CPU0_CPU1_P2P2_DN<17>")
	)
	(segment
		(start 104.422702 -281.269694)
		(end 104.42067 -281.268424)
		(width 0.0889)
		(layer "In6.Cu")
		(net "UPI_CPU0_CPU1_P2P2_DN<17>")
	)
	(segment
		(start 103.666544 -286.48406)
		(end 103.666544 -286.466788)
		(width 0.0889)
		(layer "In6.Cu")
		(net "UPI_CPU0_CPU1_P2P2_DN<17>")
	)
	(segment
		(start 248.222262 -363.987588)
		(end 248.222262 -367.46942)
		(width 0.14732)
		(layer "In6.Cu")
		(net "UPI_CPU0_CPU1_P2P2_DN<17>")
	)
	(segment
		(start 338.170012 -288.917126)
		(end 338.170012 -289.322256)
		(width 0.0889)
		(layer "In6.Cu")
		(net "UPI_CPU0_CPU1_P2P2_DN<17>")
	)
	(segment
		(start 338.357718 -288.592768)
		(end 338.342732 -288.601404)
		(width 0.0889)
		(layer "In6.Cu")
		(net "UPI_CPU0_CPU1_P2P2_DN<17>")
	)
	(segment
		(start 338.83346 -287.775142)
		(end 338.828126 -287.77819)
		(width 0.0889)
		(layer "In6.Cu")
		(net "UPI_CPU0_CPU1_P2P2_DN<17>")
	)
	(segment
		(start 105.358692 -278.660606)
		(end 105.367582 -278.655526)
		(width 0.0889)
		(layer "In6.Cu")
		(net "UPI_CPU0_CPU1_P2P2_DN<17>")
	)
	(segment
		(start 104.136444 -284.033722)
		(end 104.136444 -284.023816)
		(width 0.0889)
		(layer "In6.Cu")
		(net "UPI_CPU0_CPU1_P2P2_DN<17>")
	)
	(segment
		(start 251.73051 -367.777268)
		(end 251.422662 -367.46942)
		(width 0.14732)
		(layer "In6.Cu")
		(net "UPI_CPU0_CPU1_P2P2_DN<17>")
	)
	(segment
		(start 104.419146 -280.288492)
		(end 104.428036 -280.283412)
		(width 0.0889)
		(layer "In6.Cu")
		(net "UPI_CPU0_CPU1_P2P2_DN<17>")
	)
	(segment
		(start 105.076244 -279.150318)
		(end 105.076244 -279.136094)
		(width 0.0889)
		(layer "In6.Cu")
		(net "UPI_CPU0_CPU1_P2P2_DN<17>")
	)
	(segment
		(start 299.665644 -329.231498)
		(end 284.098238 -329.231498)
		(width 0.14732)
		(layer "In6.Cu")
		(net "UPI_CPU0_CPU1_P2P2_DN<17>")
	)
	(segment
		(start 104.419146 -281.267662)
		(end 104.417622 -281.266646)
		(width 0.0889)
		(layer "In6.Cu")
		(net "UPI_CPU0_CPU1_P2P2_DN<17>")
	)
	(segment
		(start 100.296726 -292.611302)
		(end 102.726744 -290.181284)
		(width 0.0889)
		(layer "In6.Cu")
		(net "UPI_CPU0_CPU1_P2P2_DN<17>")
	)
	(segment
		(start 100.254816 -295.323006)
		(end 100.254816 -295.300908)
		(width 0.0889)
		(layer "In6.Cu")
		(net "UPI_CPU0_CPU1_P2P2_DN<17>")
	)
	(segment
		(start 315.809884 -317.341504)
		(end 315.384942 -317.517272)
		(width 0.14732)
		(layer "In6.Cu")
		(net "UPI_CPU0_CPU1_P2P2_DN<17>")
	)
	(segment
		(start 315.384688 -317.518034)
		(end 313.515756 -318.290702)
		(width 0.14732)
		(layer "In6.Cu")
		(net "UPI_CPU0_CPU1_P2P2_DN<17>")
	)
	(segment
		(start 103.478584 -286.80029)
		(end 103.479346 -286.799782)
		(width 0.0889)
		(layer "In6.Cu")
		(net "UPI_CPU0_CPU1_P2P2_DN<17>")
	)
	(segment
		(start 335.45526 -292.701726)
		(end 333.92745 -294.985694)
		(width 0.14732)
		(layer "In6.Cu")
		(net "UPI_CPU0_CPU1_P2P2_DN<17>")
	)
	(segment
		(start 338.820506 -287.782508)
		(end 338.818474 -287.783778)
		(width 0.0889)
		(layer "In6.Cu")
		(net "UPI_CPU0_CPU1_P2P2_DN<17>")
	)
	(segment
		(start 246.922544 -367.777268)
		(end 212.31225 -373.878602)
		(width 0.14732)
		(layer "In6.Cu")
		(net "UPI_CPU0_CPU1_P2P2_DN<17>")
	)
	(segment
		(start 104.422194 -283.542232)
		(end 104.427782 -283.539184)
		(width 0.0889)
		(layer "In6.Cu")
		(net "UPI_CPU0_CPU1_P2P2_DN<17>")
	)
	(segment
		(start 103.196644 -285.675578)
		(end 103.196644 -285.651448)
		(width 0.0889)
		(layer "In6.Cu")
		(net "UPI_CPU0_CPU1_P2P2_DN<17>")
	)
	(segment
		(start 251.275342 -363.840268)
		(end 250.686062 -363.840268)
		(width 0.14732)
		(layer "In6.Cu")
		(net "UPI_CPU0_CPU1_P2P2_DN<17>")
	)
	(segment
		(start 339.579966 -286.4612)
		(end 339.579966 -286.475424)
		(width 0.0889)
		(layer "In6.Cu")
		(net "UPI_CPU0_CPU1_P2P2_DN<17>")
	)
	(segment
		(start 308.03469 -322.758562)
		(end 307.419248 -323.37375)
		(width 0.14732)
		(layer "In6.Cu")
		(net "UPI_CPU0_CPU1_P2P2_DN<17>")
	)
	(segment
		(start 248.222262 -367.46942)
		(end 247.914414 -367.777268)
		(width 0.14732)
		(layer "In6.Cu")
		(net "UPI_CPU0_CPU1_P2P2_DN<17>")
	)
	(segment
		(start 104.606598 -281.607514)
		(end 104.606598 -281.59202)
		(width 0.0889)
		(layer "In6.Cu")
		(net "UPI_CPU0_CPU1_P2P2_DN<17>")
	)
	(segment
		(start 104.888792 -279.474676)
		(end 104.889808 -279.474168)
		(width 0.0889)
		(layer "In6.Cu")
		(net "UPI_CPU0_CPU1_P2P2_DN<17>")
	)
	(segment
		(start 103.948484 -284.358334)
		(end 103.957882 -284.353)
		(width 0.0889)
		(layer "In6.Cu")
		(net "UPI_CPU0_CPU1_P2P2_DN<17>")
	)
	(segment
		(start 301.57928 -326.583802)
		(end 301.57928 -327.317862)
		(width 0.14732)
		(layer "In6.Cu")
		(net "UPI_CPU0_CPU1_P2P2_DN<17>")
	)
	(segment
		(start 339.766402 -283.543756)
		(end 339.767164 -283.544264)
		(width 0.0889)
		(layer "In6.Cu")
		(net "UPI_CPU0_CPU1_P2P2_DN<17>")
	)
	(segment
		(start 248.369582 -363.840268)
		(end 248.222262 -363.987588)
		(width 0.14732)
		(layer "In6.Cu")
		(net "UPI_CPU0_CPU1_P2P2_DN<17>")
	)
	(segment
		(start 125.915166 -378.54509)
		(end 98.533204 -374.483122)
		(width 0.14732)
		(layer "In6.Cu")
		(net "UPI_CPU0_CPU1_P2P2_DN<17>")
	)
	(segment
		(start 103.481632 -285.170372)
		(end 103.482394 -285.169864)
		(width 0.0889)
		(layer "In6.Cu")
		(net "UPI_CPU0_CPU1_P2P2_DN<17>")
	)
	(segment
		(start 337.659472 -290.49853)
		(end 337.643978 -290.514024)
		(width 0.0889)
		(layer "In6.Cu")
		(net "UPI_CPU0_CPU1_P2P2_DN<17>")
	)
	(segment
		(start 106.894884 -276.979634)
		(end 107.051348 -276.708616)
		(width 0.0889)
		(layer "In6.Cu")
		(net "UPI_CPU0_CPU1_P2P2_DN<17>")
	)
	(segment
		(start 73.344278 -323.648578)
		(end 80.98536 -316.007242)
		(width 0.14732)
		(layer "In6.Cu")
		(net "UPI_CPU0_CPU1_P2P2_DN<17>")
	)
	(segment
		(start 249.106182 -367.46942)
		(end 249.106182 -363.987588)
		(width 0.14732)
		(layer "In6.Cu")
		(net "UPI_CPU0_CPU1_P2P2_DN<17>")
	)
	(segment
		(start 339.579712 -284.847538)
		(end 339.579712 -284.863032)
		(width 0.0889)
		(layer "In6.Cu")
		(net "UPI_CPU0_CPU1_P2P2_DN<17>")
	)
	(segment
		(start 332.08087 -301.070772)
		(end 315.809884 -317.341504)
		(width 0.14732)
		(layer "In6.Cu")
		(net "UPI_CPU0_CPU1_P2P2_DN<17>")
	)
	(segment
		(start 106.298492 -277.032974)
		(end 106.308906 -277.026878)
		(width 0.0889)
		(layer "In6.Cu")
		(net "UPI_CPU0_CPU1_P2P2_DN<17>")
	)
	(segment
		(start 79.445866 -366.576864)
		(end 73.946004 -361.077002)
		(width 0.14732)
		(layer "In6.Cu")
		(net "UPI_CPU0_CPU1_P2P2_DN<17>")
	)
	(segment
		(start 248.958862 -363.840268)
		(end 248.369582 -363.840268)
		(width 0.14732)
		(layer "In6.Cu")
		(net "UPI_CPU0_CPU1_P2P2_DN<17>")
	)
	(segment
		(start 339.579712 -283.197808)
		(end 339.579712 -283.219906)
		(width 0.0889)
		(layer "In6.Cu")
		(net "UPI_CPU0_CPU1_P2P2_DN<17>")
	)
	(segment
		(start 339.328252 -282.676854)
		(end 339.352382 -282.766008)
		(width 0.0889)
		(layer "In6.Cu")
		(net "UPI_CPU0_CPU1_P2P2_DN<17>")
	)
	(segment
		(start 339.758274 -283.539184)
		(end 339.766402 -283.543756)
		(width 0.0889)
		(layer "In6.Cu")
		(net "UPI_CPU0_CPU1_P2P2_DN<17>")
	)
	(segment
		(start 310.39943 -319.15735)
		(end 309.336948 -320.138298)
		(width 0.14732)
		(layer "In6.Cu")
		(net "UPI_CPU0_CPU1_P2P2_DN<17>")
	)
	(segment
		(start 337.87334 -289.618928)
		(end 337.87334 -290.224718)
		(width 0.0889)
		(layer "In6.Cu")
		(net "UPI_CPU0_CPU1_P2P2_DN<17>")
	)
	(segment
		(start 339.297518 -285.336996)
		(end 339.288628 -285.342076)
		(width 0.0889)
		(layer "In6.Cu")
		(net "UPI_CPU0_CPU1_P2P2_DN<17>")
	)
	(segment
		(start 102.726998 -288.103056)
		(end 102.726998 -288.087562)
		(width 0.0889)
		(layer "In6.Cu")
		(net "UPI_CPU0_CPU1_P2P2_DN<17>")
	)
	(segment
		(start 338.639912 -288.103056)
		(end 338.639912 -288.125154)
		(width 0.0889)
		(layer "In6.Cu")
		(net "UPI_CPU0_CPU1_P2P2_DN<17>")
	)
	(segment
		(start 103.47325 -286.803338)
		(end 103.478584 -286.80029)
		(width 0.0889)
		(layer "In6.Cu")
		(net "UPI_CPU0_CPU1_P2P2_DN<17>")
	)
	(segment
		(start 71.24065 -328.695812)
		(end 71.63943 -327.252838)
		(width 0.14732)
		(layer "In6.Cu")
		(net "UPI_CPU0_CPU1_P2P2_DN<17>")
	)
	(segment
		(start 339.303614 -286.961326)
		(end 339.297518 -286.964882)
		(width 0.0889)
		(layer "In6.Cu")
		(net "UPI_CPU0_CPU1_P2P2_DN<17>")
	)
	(segment
		(start 103.666544 -284.847538)
		(end 103.666544 -284.847284)
		(width 0.0889)
		(layer "In6.Cu")
		(net "UPI_CPU0_CPU1_P2P2_DN<17>")
	)
	(segment
		(start 159.289496 -378.54509)
		(end 125.915166 -378.54509)
		(width 0.14732)
		(layer "In6.Cu")
		(net "UPI_CPU0_CPU1_P2P2_DN<17>")
	)
	(segment
		(start 315.384942 -317.517272)
		(end 315.384688 -317.518034)
		(width 0.14732)
		(layer "In6.Cu")
		(net "UPI_CPU0_CPU1_P2P2_DN<17>")
	)
	(segment
		(start 103.479092 -285.171896)
		(end 103.479854 -285.171388)
		(width 0.0889)
		(layer "In6.Cu")
		(net "UPI_CPU0_CPU1_P2P2_DN<17>")
	)
	(segment
		(start 247.914414 -367.777268)
		(end 246.922544 -367.777268)
		(width 0.14732)
		(layer "In6.Cu")
		(net "UPI_CPU0_CPU1_P2P2_DN<17>")
	)
	(segment
		(start 71.63943 -327.252838)
		(end 73.344278 -323.648578)
		(width 0.14732)
		(layer "In6.Cu")
		(net "UPI_CPU0_CPU1_P2P2_DN<17>")
	)
	(segment
		(start 104.897682 -282.086558)
		(end 104.888792 -282.081478)
		(width 0.0889)
		(layer "In6.Cu")
		(net "UPI_CPU0_CPU1_P2P2_DN<17>")
	)
	(segment
		(start 104.889808 -279.474168)
		(end 104.897682 -279.469596)
		(width 0.0889)
		(layer "In6.Cu")
		(net "UPI_CPU0_CPU1_P2P2_DN<17>")
	)
	(segment
		(start 104.888792 -282.730194)
		(end 104.897682 -282.725114)
		(width 0.0889)
		(layer "In6.Cu")
		(net "UPI_CPU0_CPU1_P2P2_DN<17>")
	)
	(segment
		(start 102.539546 -288.427414)
		(end 102.548436 -288.422334)
		(width 0.0889)
		(layer "In6.Cu")
		(net "UPI_CPU0_CPU1_P2P2_DN<17>")
	)
	(segment
		(start 97.96653 -301.30877)
		(end 100.254816 -295.785286)
		(width 0.14732)
		(layer "In6.Cu")
		(net "UPI_CPU0_CPU1_P2P2_DN<17>")
	)
	(segment
		(start 212.31225 -373.878602)
		(end 199.037956 -371.537738)
		(width 0.14732)
		(layer "In6.Cu")
		(net "UPI_CPU0_CPU1_P2P2_DN<17>")
	)
	(segment
		(start 104.419654 -283.543756)
		(end 104.422194 -283.542232)
		(width 0.0889)
		(layer "In6.Cu")
		(net "UPI_CPU0_CPU1_P2P2_DN<17>")
	)
	(segment
		(start 340.049612 -284.023816)
		(end 340.049612 -284.043628)
		(width 0.0889)
		(layer "In6.Cu")
		(net "UPI_CPU0_CPU1_P2P2_DN<17>")
	)
	(segment
		(start 104.606598 -279.964134)
		(end 104.606598 -279.94864)
		(width 0.0889)
		(layer "In6.Cu")
		(net "UPI_CPU0_CPU1_P2P2_DN<17>")
	)
	(segment
		(start 102.257098 -289.114738)
		(end 102.257098 -288.898584)
		(width 0.0889)
		(layer "In6.Cu")
		(net "UPI_CPU0_CPU1_P2P2_DN<17>")
	)
	(segment
		(start 302.312578 -325.850504)
		(end 301.57928 -326.583802)
		(width 0.14732)
		(layer "In6.Cu")
		(net "UPI_CPU0_CPU1_P2P2_DN<17>")
	)
	(segment
		(start 338.828126 -287.77819)
		(end 338.827364 -287.778698)
		(width 0.0889)
		(layer "In6.Cu")
		(net "UPI_CPU0_CPU1_P2P2_DN<17>")
	)
	(segment
		(start 100.254816 -295.300908)
		(end 100.296726 -295.258998)
		(width 0.0889)
		(layer "In6.Cu")
		(net "UPI_CPU0_CPU1_P2P2_DN<17>")
	)
	(segment
		(start 73.946004 -361.077002)
		(end 70.603618 -353.007422)
		(width 0.14732)
		(layer "In6.Cu")
		(net "UPI_CPU0_CPU1_P2P2_DN<17>")
	)
	(segment
		(start 104.417622 -281.266646)
		(end 104.41305 -281.264106)
		(width 0.0889)
		(layer "In6.Cu")
		(net "UPI_CPU0_CPU1_P2P2_DN<17>")
	)
	(segment
		(start 199.037448 -371.537738)
		(end 159.289496 -378.54509)
		(width 0.14732)
		(layer "In6.Cu")
		(net "UPI_CPU0_CPU1_P2P2_DN<17>")
	)
	(segment
		(start 88.758522 -309.628286)
		(end 88.758268 -309.628286)
		(width 0.14732)
		(layer "In6.Cu")
		(net "UPI_CPU0_CPU1_P2P2_DN<17>")
	)
	(segment
		(start 70.603618 -335.16316)
		(end 71.24065 -328.695812)
		(width 0.14732)
		(layer "In6.Cu")
		(net "UPI_CPU0_CPU1_P2P2_DN<17>")
	)
	(segment
		(start 262.170672 -367.777268)
		(end 251.73051 -367.777268)
		(width 0.14732)
		(layer "In6.Cu")
		(net "UPI_CPU0_CPU1_P2P2_DN<17>")
	)
	(segment
		(start 265.042142 -364.905798)
		(end 262.170672 -367.777268)
		(width 0.14732)
		(layer "In6.Cu")
		(net "UPI_CPU0_CPU1_P2P2_DN<17>")
	)
	(segment
		(start 339.767164 -284.52318)
		(end 339.758274 -284.52826)
		(width 0.0889)
		(layer "In6.Cu")
		(net "UPI_CPU0_CPU1_P2P2_DN<17>")
	)
	(segment
		(start 339.297518 -286.964882)
		(end 339.288628 -286.969962)
		(width 0.0889)
		(layer "In6.Cu")
		(net "UPI_CPU0_CPU1_P2P2_DN<17>")
	)
	(segment
		(start 284.098238 -329.231498)
		(end 277.315168 -332.040992)
		(width 0.14732)
		(layer "In6.Cu")
		(net "UPI_CPU0_CPU1_P2P2_DN<17>")
	)
	(segment
		(start 307.419248 -323.37375)
		(end 307.419248 -323.374004)
		(width 0.14732)
		(layer "In6.Cu")
		(net "UPI_CPU0_CPU1_P2P2_DN<17>")
	)
	(segment
		(start 339.288628 -285.980632)
		(end 339.297518 -285.985712)
		(width 0.0889)
		(layer "In6.Cu")
		(net "UPI_CPU0_CPU1_P2P2_DN<17>")
	)
	(segment
		(start 337.159854 -290.998148)
		(end 337.158838 -290.998148)
		(width 0.14732)
		(layer "In6.Cu")
		(net "UPI_CPU0_CPU1_P2P2_DN<17>")
	)
	(segment
		(start 309.336948 -320.138298)
		(end 308.822344 -321.695572)
		(width 0.14732)
		(layer "In6.Cu")
		(net "UPI_CPU0_CPU1_P2P2_DN<17>")
	)
	(segment
		(start 104.606344 -283.219906)
		(end 104.606344 -283.205682)
		(width 0.0889)
		(layer "In6.Cu")
		(net "UPI_CPU0_CPU1_P2P2_DN<17>")
	)
	(segment
		(start 104.428036 -281.272742)
		(end 104.426004 -281.271472)
		(width 0.0889)
		(layer "In6.Cu")
		(net "UPI_CPU0_CPU1_P2P2_DN<17>")
	)
	(segment
		(start 337.659472 -290.438586)
		(end 337.659472 -290.49853)
		(width 0.0889)
		(layer "In6.Cu")
		(net "UPI_CPU0_CPU1_P2P2_DN<17>")
	)
	(segment
		(start 337.643978 -290.514024)
		(end 337.159854 -290.998148)
		(width 0.14732)
		(layer "In6.Cu")
		(net "UPI_CPU0_CPU1_P2P2_DN<17>")
	)
	(segment
		(start 249.41403 -367.777268)
		(end 249.106182 -367.46942)
		(width 0.14732)
		(layer "In6.Cu")
		(net "UPI_CPU0_CPU1_P2P2_DN<17>")
	)
	(segment
		(start 338.827364 -287.778698)
		(end 338.820506 -287.782508)
		(width 0.0889)
		(layer "In6.Cu")
		(net "UPI_CPU0_CPU1_P2P2_DN<17>")
	)
	(segment
		(start 250.230894 -367.777268)
		(end 249.41403 -367.777268)
		(width 0.14732)
		(layer "In6.Cu")
		(net "UPI_CPU0_CPU1_P2P2_DN<17>")
	)
	(segment
		(start 100.296726 -295.258998)
		(end 100.296726 -292.611302)
		(width 0.0889)
		(layer "In6.Cu")
		(net "UPI_CPU0_CPU1_P2P2_DN<17>")
	)
	(segment
		(start 249.106182 -363.987588)
		(end 248.958862 -363.840268)
		(width 0.14732)
		(layer "In6.Cu")
		(net "UPI_CPU0_CPU1_P2P2_DN<17>")
	)
	(segment
		(start 251.422662 -367.46942)
		(end 251.422662 -363.987588)
		(width 0.14732)
		(layer "In6.Cu")
		(net "UPI_CPU0_CPU1_P2P2_DN<17>")
	)
	(segment
		(start 80.98536 -316.007242)
		(end 88.758522 -309.628286)
		(width 0.14732)
		(layer "In6.Cu")
		(net "UPI_CPU0_CPU1_P2P2_DN<17>")
	)
	(segment
		(start 308.822344 -321.695572)
		(end 308.03469 -322.758562)
		(width 0.14732)
		(layer "In6.Cu")
		(net "UPI_CPU0_CPU1_P2P2_DN<17>")
	)
	(segment
		(start 88.758268 -309.628286)
		(end 96.520508 -303.257966)
		(width 0.14732)
		(layer "In6.Cu")
		(net "UPI_CPU0_CPU1_P2P2_DN<17>")
	)
	(segment
		(start 313.515756 -318.290702)
		(end 310.39943 -319.15735)
		(width 0.14732)
		(layer "In6.Cu")
		(net "UPI_CPU0_CPU1_P2P2_DN<17>")
	)
	(segment
		(start 105.828592 -277.84679)
		(end 105.837482 -277.84171)
		(width 0.0889)
		(layer "In6.Cu")
		(net "UPI_CPU0_CPU1_P2P2_DN<17>")
	)
	(segment
		(start 104.418892 -283.544264)
		(end 104.419654 -283.543756)
		(width 0.0889)
		(layer "In6.Cu")
		(net "UPI_CPU0_CPU1_P2P2_DN<17>")
	)
	(arc
		(start 339.579712 -283.219906)
		(mid 339.627391 -283.402806)
		(end 339.758274 -283.539184)
		(width 0.0889)
		(layer "In6.Cu")
		(net "UPI_CPU0_CPU1_P2P2_DN<17>")
	)
	(arc
		(start 103.479346 -286.151066)
		(mid 103.275865 -285.950262)
		(end 103.196644 -285.675578)
		(width 0.0889)
		(layer "In6.Cu")
		(net "UPI_CPU0_CPU1_P2P2_DN<17>")
	)
	(arc
		(start 102.726744 -289.645852)
		(mid 102.651739 -289.530393)
		(end 102.542594 -289.446462)
		(width 0.0889)
		(layer "In6.Cu")
		(net "UPI_CPU0_CPU1_P2P2_DN<17>")
	)
	(arc
		(start 103.666544 -284.847284)
		(mid 103.740523 -284.567925)
		(end 103.942896 -284.361636)
		(width 0.0889)
		(layer "In6.Cu")
		(net "UPI_CPU0_CPU1_P2P2_DN<17>")
	)
	(arc
		(start 338.342732 -288.601404)
		(mid 338.216009 -288.737185)
		(end 338.170012 -288.917126)
		(width 0.0889)
		(layer "In6.Cu")
		(net "UPI_CPU0_CPU1_P2P2_DN<17>")
	)
	(arc
		(start 104.897682 -282.725114)
		(mid 105.024936 -282.595148)
		(end 105.07599 -282.420568)
		(width 0.0889)
		(layer "In6.Cu")
		(net "UPI_CPU0_CPU1_P2P2_DN<17>")
	)
	(arc
		(start 106.785664 -276.995382)
		(mid 106.795736 -276.999349)
		(end 106.80573 -277.00351)
		(width 0.0889)
		(layer "In6.Cu")
		(net "UPI_CPU0_CPU1_P2P2_DN<17>")
	)
	(arc
		(start 339.579712 -284.863032)
		(mid 339.500342 -285.136766)
		(end 339.297518 -285.336996)
		(width 0.0889)
		(layer "In6.Cu")
		(net "UPI_CPU0_CPU1_P2P2_DN<17>")
	)
	(arc
		(start 339.369146 -282.778962)
		(mid 339.519895 -282.965535)
		(end 339.579712 -283.197808)
		(width 0.0889)
		(layer "In6.Cu")
		(net "UPI_CPU0_CPU1_P2P2_DN<17>")
	)
	(arc
		(start 339.288628 -285.342076)
		(mid 339.160309 -285.474048)
		(end 339.11032 -285.651194)
		(width 0.0889)
		(layer "In6.Cu")
		(net "UPI_CPU0_CPU1_P2P2_DN<17>")
	)
	(arc
		(start 339.767164 -283.544264)
		(mid 339.971499 -283.746869)
		(end 340.049612 -284.023816)
		(width 0.0889)
		(layer "In6.Cu")
		(net "UPI_CPU0_CPU1_P2P2_DN<17>")
	)
	(arc
		(start 339.758274 -284.52826)
		(mid 339.62736 -284.66462)
		(end 339.579712 -284.847538)
		(width 0.0889)
		(layer "In6.Cu")
		(net "UPI_CPU0_CPU1_P2P2_DN<17>")
	)
	(arc
		(start 105.07599 -282.420568)
		(mid 105.076323 -282.408124)
		(end 105.076244 -282.395676)
		(width 0.0889)
		(layer "In6.Cu")
		(net "UPI_CPU0_CPU1_P2P2_DN<17>")
	)
	(arc
		(start 339.297518 -285.985712)
		(mid 339.500823 -286.186578)
		(end 339.579966 -286.4612)
		(width 0.0889)
		(layer "In6.Cu")
		(net "UPI_CPU0_CPU1_P2P2_DN<17>")
	)
	(arc
		(start 340.049612 -284.043628)
		(mid 339.971501 -284.320577)
		(end 339.767164 -284.52318)
		(width 0.0889)
		(layer "In6.Cu")
		(net "UPI_CPU0_CPU1_P2P2_DN<17>")
	)
	(arc
		(start 104.606598 -281.59202)
		(mid 104.558919 -281.40912)
		(end 104.428036 -281.272742)
		(width 0.0889)
		(layer "In6.Cu")
		(net "UPI_CPU0_CPU1_P2P2_DN<17>")
	)
	(arc
		(start 105.837482 -277.84171)
		(mid 105.964736 -277.711744)
		(end 106.01579 -277.537164)
		(width 0.0889)
		(layer "In6.Cu")
		(net "UPI_CPU0_CPU1_P2P2_DN<17>")
	)
	(arc
		(start 104.606344 -283.205682)
		(mid 104.685485 -282.931059)
		(end 104.888792 -282.730194)
		(width 0.0889)
		(layer "In6.Cu")
		(net "UPI_CPU0_CPU1_P2P2_DN<17>")
	)
	(arc
		(start 104.428036 -280.283412)
		(mid 104.55895 -280.147052)
		(end 104.606598 -279.964134)
		(width 0.0889)
		(layer "In6.Cu")
		(net "UPI_CPU0_CPU1_P2P2_DN<17>")
	)
	(arc
		(start 104.606598 -279.94864)
		(mid 104.685968 -279.674906)
		(end 104.888792 -279.474676)
		(width 0.0889)
		(layer "In6.Cu")
		(net "UPI_CPU0_CPU1_P2P2_DN<17>")
	)
	(arc
		(start 103.196644 -285.651448)
		(mid 103.274755 -285.374499)
		(end 103.479092 -285.171896)
		(width 0.0889)
		(layer "In6.Cu")
		(net "UPI_CPU0_CPU1_P2P2_DN<17>")
	)
	(arc
		(start 103.018082 -287.608518)
		(mid 103.148996 -287.472158)
		(end 103.196644 -287.28924)
		(width 0.0889)
		(layer "In6.Cu")
		(net "UPI_CPU0_CPU1_P2P2_DN<17>")
	)
	(arc
		(start 104.897682 -279.469596)
		(mid 105.028596 -279.333236)
		(end 105.076244 -279.150318)
		(width 0.0889)
		(layer "In6.Cu")
		(net "UPI_CPU0_CPU1_P2P2_DN<17>")
	)
	(arc
		(start 339.110574 -285.676086)
		(mid 339.161484 -285.850655)
		(end 339.288628 -285.980632)
		(width 0.0889)
		(layer "In6.Cu")
		(net "UPI_CPU0_CPU1_P2P2_DN<17>")
	)
	(arc
		(start 104.888792 -282.081478)
		(mid 104.685969 -281.881247)
		(end 104.606598 -281.607514)
		(width 0.0889)
		(layer "In6.Cu")
		(net "UPI_CPU0_CPU1_P2P2_DN<17>")
	)
	(arc
		(start 103.479346 -286.799782)
		(mid 103.614279 -286.666428)
		(end 103.666544 -286.48406)
		(width 0.0889)
		(layer "In6.Cu")
		(net "UPI_CPU0_CPU1_P2P2_DN<17>")
	)
	(arc
		(start 102.726998 -288.087562)
		(mid 102.806368 -287.813828)
		(end 103.009192 -287.613598)
		(width 0.0889)
		(layer "In6.Cu")
		(net "UPI_CPU0_CPU1_P2P2_DN<17>")
	)
	(arc
		(start 103.487982 -285.166816)
		(mid 103.618896 -285.030456)
		(end 103.666544 -284.847538)
		(width 0.0889)
		(layer "In6.Cu")
		(net "UPI_CPU0_CPU1_P2P2_DN<17>")
	)
	(arc
		(start 339.11032 -285.651194)
		(mid 339.11024 -285.663642)
		(end 339.110574 -285.676086)
		(width 0.0889)
		(layer "In6.Cu")
		(net "UPI_CPU0_CPU1_P2P2_DN<17>")
	)
	(arc
		(start 338.818474 -287.783778)
		(mid 338.68756 -287.920138)
		(end 338.639912 -288.103056)
		(width 0.0889)
		(layer "In6.Cu")
		(net "UPI_CPU0_CPU1_P2P2_DN<17>")
	)
	(arc
		(start 339.288628 -286.969962)
		(mid 339.157714 -287.106322)
		(end 339.110066 -287.28924)
		(width 0.0889)
		(layer "In6.Cu")
		(net "UPI_CPU0_CPU1_P2P2_DN<17>")
	)
	(arc
		(start 102.548436 -288.422334)
		(mid 102.67935 -288.285974)
		(end 102.726998 -288.103056)
		(width 0.0889)
		(layer "In6.Cu")
		(net "UPI_CPU0_CPU1_P2P2_DN<17>")
	)
	(arc
		(start 104.427782 -283.539184)
		(mid 104.558696 -283.402824)
		(end 104.606344 -283.219906)
		(width 0.0889)
		(layer "In6.Cu")
		(net "UPI_CPU0_CPU1_P2P2_DN<17>")
	)
	(arc
		(start 339.352382 -282.766008)
		(mid 339.360825 -282.772406)
		(end 339.369146 -282.778962)
		(width 0.0889)
		(layer "In6.Cu")
		(net "UPI_CPU0_CPU1_P2P2_DN<17>")
	)
	(arc
		(start 103.957882 -284.353)
		(mid 104.088796 -284.21664)
		(end 104.136444 -284.033722)
		(width 0.0889)
		(layer "In6.Cu")
		(net "UPI_CPU0_CPU1_P2P2_DN<17>")
	)
	(arc
		(start 106.308906 -277.026878)
		(mid 106.543786 -276.958343)
		(end 106.785664 -276.995382)
		(width 0.0889)
		(layer "In6.Cu")
		(net "UPI_CPU0_CPU1_P2P2_DN<17>")
	)
	(arc
		(start 105.546398 -278.322024)
		(mid 105.62545 -278.047551)
		(end 105.828592 -277.84679)
		(width 0.0889)
		(layer "In6.Cu")
		(net "UPI_CPU0_CPU1_P2P2_DN<17>")
	)
	(arc
		(start 102.542594 -289.446462)
		(mid 102.368462 -289.307615)
		(end 102.257098 -289.114738)
		(width 0.0889)
		(layer "In6.Cu")
		(net "UPI_CPU0_CPU1_P2P2_DN<17>")
	)
	(arc
		(start 103.666544 -286.466788)
		(mid 103.614274 -286.284423)
		(end 103.479346 -286.151066)
		(width 0.0889)
		(layer "In6.Cu")
		(net "UPI_CPU0_CPU1_P2P2_DN<17>")
	)
	(arc
		(start 105.076244 -282.395676)
		(mid 105.026153 -282.218481)
		(end 104.897682 -282.086558)
		(width 0.0889)
		(layer "In6.Cu")
		(net "UPI_CPU0_CPU1_P2P2_DN<17>")
	)
	(arc
		(start 103.196644 -287.28924)
		(mid 103.270635 -287.009674)
		(end 103.47325 -286.803338)
		(width 0.0889)
		(layer "In6.Cu")
		(net "UPI_CPU0_CPU1_P2P2_DN<17>")
	)
	(arc
		(start 102.257098 -288.898584)
		(mid 102.33726 -288.626395)
		(end 102.539546 -288.427414)
		(width 0.0889)
		(layer "In6.Cu")
		(net "UPI_CPU0_CPU1_P2P2_DN<17>")
	)
	(arc
		(start 338.639912 -288.125154)
		(mid 338.559001 -288.395282)
		(end 338.357718 -288.592768)
		(width 0.0889)
		(layer "In6.Cu")
		(net "UPI_CPU0_CPU1_P2P2_DN<17>")
	)
	(arc
		(start 104.41305 -281.264106)
		(mid 104.136487 -280.774612)
		(end 104.419146 -280.288492)
		(width 0.0889)
		(layer "In6.Cu")
		(net "UPI_CPU0_CPU1_P2P2_DN<17>")
	)
	(arc
		(start 105.076244 -279.136094)
		(mid 105.155385 -278.861471)
		(end 105.358692 -278.660606)
		(width 0.0889)
		(layer "In6.Cu")
		(net "UPI_CPU0_CPU1_P2P2_DN<17>")
	)
	(arc
		(start 339.110066 -287.28924)
		(mid 339.036075 -287.568806)
		(end 338.83346 -287.775142)
		(width 0.0889)
		(layer "In6.Cu")
		(net "UPI_CPU0_CPU1_P2P2_DN<17>")
	)
	(arc
		(start 104.136444 -284.023816)
		(mid 104.214555 -283.746867)
		(end 104.418892 -283.544264)
		(width 0.0889)
		(layer "In6.Cu")
		(net "UPI_CPU0_CPU1_P2P2_DN<17>")
	)
	(arc
		(start 339.579966 -286.475424)
		(mid 339.50605 -286.754926)
		(end 339.303614 -286.961326)
		(width 0.0889)
		(layer "In6.Cu")
		(net "UPI_CPU0_CPU1_P2P2_DN<17>")
	)
	(arc
		(start 105.367582 -278.655526)
		(mid 105.498496 -278.519166)
		(end 105.546144 -278.336248)
		(width 0.0889)
		(layer "In6.Cu")
		(net "UPI_CPU0_CPU1_P2P2_DN<17>")
	)
	(arc
		(start 106.016044 -277.512526)
		(mid 106.094155 -277.235577)
		(end 106.298492 -277.032974)
		(width 0.0889)
		(layer "In6.Cu")
		(net "UPI_CPU0_CPU1_P2P2_DN<17>")
	)
	(arc
		(start 106.01579 -277.537164)
		(mid 106.015987 -277.529799)
		(end 106.016044 -277.522432)
		(width 0.0889)
		(layer "In6.Cu")
		(net "UPI_CPU0_CPU1_P2P2_DN<17>")
	)
	(segment
		(start 102.822248 -275.35886)
		(end 102.822248 -275.894546)
		(width 0.13208)
		(layer "F.Cu")
		(net "UPI_CPU0_CPU1_P2P2_DN<16>")
	)
	(segment
		(start 340.42477 -280.242518)
		(end 340.42477 -280.77795)
		(width 0.13208)
		(layer "F.Cu")
		(net "UPI_CPU0_CPU1_P2P2_DN<16>")
	)
	(segment
		(start 340.42477 -280.77795)
		(end 340.424516 -280.778204)
		(width 0.13208)
		(layer "F.Cu")
		(net "UPI_CPU0_CPU1_P2P2_DN<16>")
	)
	(segment
		(start 340.424516 -280.242264)
		(end 340.42477 -280.242518)
		(width 0.13208)
		(layer "F.Cu")
		(net "UPI_CPU0_CPU1_P2P2_DN<16>")
	)
	(segment
		(start 102.822248 -275.894546)
		(end 102.821994 -275.8948)
		(width 0.13208)
		(layer "F.Cu")
		(net "UPI_CPU0_CPU1_P2P2_DN<16>")
	)
	(segment
		(start 104.043734 -279.640284)
		(end 104.04475 -279.639776)
		(width 0.0889)
		(layer "In6.Cu")
		(net "UPI_CPU0_CPU1_P2P2_DN<16>")
	)
	(segment
		(start 265.86307 -365.037878)
		(end 262.23849 -368.662458)
		(width 0.14732)
		(layer "In6.Cu")
		(net "UPI_CPU0_CPU1_P2P2_DN<16>")
	)
	(segment
		(start 105.736898 -276.708616)
		(end 105.736898 -276.69871)
		(width 0.0889)
		(layer "In6.Cu")
		(net "UPI_CPU0_CPU1_P2P2_DN<16>")
	)
	(segment
		(start 105.454196 -277.198074)
		(end 105.45699 -277.19655)
		(width 0.0889)
		(layer "In6.Cu")
		(net "UPI_CPU0_CPU1_P2P2_DN<16>")
	)
	(segment
		(start 315.140848 -318.797686)
		(end 310.797194 -320.596768)
		(width 0.14732)
		(layer "In6.Cu")
		(net "UPI_CPU0_CPU1_P2P2_DN<16>")
	)
	(segment
		(start 251.137928 -370.470176)
		(end 250.954286 -369.430046)
		(width 0.14732)
		(layer "In6.Cu")
		(net "UPI_CPU0_CPU1_P2P2_DN<16>")
	)
	(segment
		(start 305.357276 -326.869806)
		(end 305.357276 -326.870314)
		(width 0.14732)
		(layer "In6.Cu")
		(net "UPI_CPU0_CPU1_P2P2_DN<16>")
	)
	(segment
		(start 103.387398 -280.78684)
		(end 103.387398 -280.769568)
		(width 0.0889)
		(layer "In6.Cu")
		(net "UPI_CPU0_CPU1_P2P2_DN<16>")
	)
	(segment
		(start 253.590806 -370.18722)
		(end 253.420372 -370.067586)
		(width 0.14732)
		(layer "In6.Cu")
		(net "UPI_CPU0_CPU1_P2P2_DN<16>")
	)
	(segment
		(start 75.605894 -363.636814)
		(end 75.34529 -363.37621)
		(width 0.14732)
		(layer "In6.Cu")
		(net "UPI_CPU0_CPU1_P2P2_DN<16>")
	)
	(segment
		(start 212.31225 -374.44807)
		(end 199.037448 -372.107206)
		(width 0.14732)
		(layer "In6.Cu")
		(net "UPI_CPU0_CPU1_P2P2_DN<16>")
	)
	(segment
		(start 340.15045 -285.166816)
		(end 340.14156 -285.171896)
		(width 0.0889)
		(layer "In6.Cu")
		(net "UPI_CPU0_CPU1_P2P2_DN<16>")
	)
	(segment
		(start 103.574596 -282.081478)
		(end 103.586788 -282.074366)
		(width 0.0889)
		(layer "In6.Cu")
		(net "UPI_CPU0_CPU1_P2P2_DN<16>")
	)
	(segment
		(start 339.859112 -285.651448)
		(end 339.859112 -285.675578)
		(width 0.0889)
		(layer "In6.Cu")
		(net "UPI_CPU0_CPU1_P2P2_DN<16>")
	)
	(segment
		(start 339.21065 -288.422334)
		(end 339.20176 -288.427414)
		(width 0.0889)
		(layer "In6.Cu")
		(net "UPI_CPU0_CPU1_P2P2_DN<16>")
	)
	(segment
		(start 305.237896 -327.547224)
		(end 304.816764 -328.071734)
		(width 0.14732)
		(layer "In6.Cu")
		(net "UPI_CPU0_CPU1_P2P2_DN<16>")
	)
	(segment
		(start 104.326944 -279.165812)
		(end 104.326944 -279.150318)
		(width 0.0889)
		(layer "In6.Cu")
		(net "UPI_CPU0_CPU1_P2P2_DN<16>")
	)
	(segment
		(start 249.726196 -370.719096)
		(end 249.606562 -370.88953)
		(width 0.14732)
		(layer "In6.Cu")
		(net "UPI_CPU0_CPU1_P2P2_DN<16>")
	)
	(segment
		(start 340.62035 -284.353)
		(end 340.61146 -284.35808)
		(width 0.0889)
		(layer "In6.Cu")
		(net "UPI_CPU0_CPU1_P2P2_DN<16>")
	)
	(segment
		(start 74.880216 -362.911136)
		(end 74.619612 -362.650532)
		(width 0.14732)
		(layer "In6.Cu")
		(net "UPI_CPU0_CPU1_P2P2_DN<16>")
	)
	(segment
		(start 253.23673 -369.027456)
		(end 252.880368 -368.777774)
		(width 0.14732)
		(layer "In6.Cu")
		(net "UPI_CPU0_CPU1_P2P2_DN<16>")
	)
	(segment
		(start 102.917498 -284.847538)
		(end 102.917498 -284.838902)
		(width 0.0889)
		(layer "In6.Cu")
		(net "UPI_CPU0_CPU1_P2P2_DN<16>")
	)
	(segment
		(start 103.565706 -283.714444)
		(end 103.574596 -283.709364)
		(width 0.0889)
		(layer "In6.Cu")
		(net "UPI_CPU0_CPU1_P2P2_DN<16>")
	)
	(segment
		(start 75.34529 -363.37621)
		(end 75.140566 -363.37621)
		(width 0.14732)
		(layer "In6.Cu")
		(net "UPI_CPU0_CPU1_P2P2_DN<16>")
	)
	(segment
		(start 72.85863 -323.348858)
		(end 80.625188 -315.5823)
		(width 0.14732)
		(layer "In6.Cu")
		(net "UPI_CPU0_CPU1_P2P2_DN<16>")
	)
	(segment
		(start 336.093562 -292.92931)
		(end 334.34782 -295.540684)
		(width 0.14732)
		(layer "In6.Cu")
		(net "UPI_CPU0_CPU1_P2P2_DN<16>")
	)
	(segment
		(start 254.357124 -368.517424)
		(end 254.107442 -368.873786)
		(width 0.14732)
		(layer "In6.Cu")
		(net "UPI_CPU0_CPU1_P2P2_DN<16>")
	)
	(segment
		(start 339.859366 -287.279334)
		(end 339.859366 -287.28924)
		(width 0.0889)
		(layer "In6.Cu")
		(net "UPI_CPU0_CPU1_P2P2_DN<16>")
	)
	(segment
		(start 105.45445 -276.219158)
		(end 105.444036 -276.213062)
		(width 0.0889)
		(layer "In6.Cu")
		(net "UPI_CPU0_CPU1_P2P2_DN<16>")
	)
	(segment
		(start 104.505506 -278.83104)
		(end 104.512872 -278.826722)
		(width 0.0889)
		(layer "In6.Cu")
		(net "UPI_CPU0_CPU1_P2P2_DN<16>")
	)
	(segment
		(start 77.130656 -365.3663)
		(end 77.130656 -365.161576)
		(width 0.14732)
		(layer "In6.Cu")
		(net "UPI_CPU0_CPU1_P2P2_DN<16>")
	)
	(segment
		(start 103.387144 -284.043628)
		(end 103.387144 -284.033722)
		(width 0.0889)
		(layer "In6.Cu")
		(net "UPI_CPU0_CPU1_P2P2_DN<16>")
	)
	(segment
		(start 102.634796 -285.985712)
		(end 102.625906 -285.980632)
		(width 0.0889)
		(layer "In6.Cu")
		(net "UPI_CPU0_CPU1_P2P2_DN<16>")
	)
	(segment
		(start 103.857298 -279.971754)
		(end 103.857298 -279.964134)
		(width 0.0889)
		(layer "In6.Cu")
		(net "UPI_CPU0_CPU1_P2P2_DN<16>")
	)
	(segment
		(start 305.357276 -326.870314)
		(end 305.237896 -327.547224)
		(width 0.14732)
		(layer "In6.Cu")
		(net "UPI_CPU0_CPU1_P2P2_DN<16>")
	)
	(segment
		(start 104.512872 -278.826722)
		(end 104.514396 -278.82596)
		(width 0.0889)
		(layer "In6.Cu")
		(net "UPI_CPU0_CPU1_P2P2_DN<16>")
	)
	(segment
		(start 336.093562 -292.924738)
		(end 336.093562 -292.92931)
		(width 0.14732)
		(layer "In6.Cu")
		(net "UPI_CPU0_CPU1_P2P2_DN<16>")
	)
	(segment
		(start 277.66264 -332.50378)
		(end 265.86307 -344.30335)
		(width 0.14732)
		(layer "In6.Cu")
		(net "UPI_CPU0_CPU1_P2P2_DN<16>")
	)
	(segment
		(start 99.611942 -292.553898)
		(end 101.977444 -290.188396)
		(width 0.0889)
		(layer "In6.Cu")
		(net "UPI_CPU0_CPU1_P2P2_DN<16>")
	)
	(segment
		(start 103.574596 -276.219158)
		(end 103.559864 -276.210522)
		(width 0.0889)
		(layer "In6.Cu")
		(net "UPI_CPU0_CPU1_P2P2_DN<16>")
	)
	(segment
		(start 76.665328 -364.900972)
		(end 76.331572 -364.567216)
		(width 0.14732)
		(layer "In6.Cu")
		(net "UPI_CPU0_CPU1_P2P2_DN<16>")
	)
	(segment
		(start 80.625188 -315.5823)
		(end 96.11233 -302.87214)
		(width 0.14732)
		(layer "In6.Cu")
		(net "UPI_CPU0_CPU1_P2P2_DN<16>")
	)
	(segment
		(start 339.671914 -287.613598)
		(end 339.668104 -287.615884)
		(width 0.0889)
		(layer "In6.Cu")
		(net "UPI_CPU0_CPU1_P2P2_DN<16>")
	)
	(segment
		(start 249.606562 -370.88953)
		(end 248.352818 -371.110764)
		(width 0.14732)
		(layer "In6.Cu")
		(net "UPI_CPU0_CPU1_P2P2_DN<16>")
	)
	(segment
		(start 339.680804 -287.608518)
		(end 339.671914 -287.613598)
		(width 0.0889)
		(layer "In6.Cu")
		(net "UPI_CPU0_CPU1_P2P2_DN<16>")
	)
	(segment
		(start 338.424774 -290.652454)
		(end 338.328762 -290.748466)
		(width 0.0889)
		(layer "In6.Cu")
		(net "UPI_CPU0_CPU1_P2P2_DN<16>")
	)
	(segment
		(start 340.424516 -280.778204)
		(end 340.58098 -281.049222)
		(width 0.0889)
		(layer "In6.Cu")
		(net "UPI_CPU0_CPU1_P2P2_DN<16>")
	)
	(segment
		(start 101.68636 -288.597848)
		(end 101.694488 -288.593276)
		(width 0.0889)
		(layer "In6.Cu")
		(net "UPI_CPU0_CPU1_P2P2_DN<16>")
	)
	(segment
		(start 102.15626 -287.783778)
		(end 102.16515 -287.778698)
		(width 0.0889)
		(layer "In6.Cu")
		(net "UPI_CPU0_CPU1_P2P2_DN<16>")
	)
	(segment
		(start 70.67804 -328.607166)
		(end 71.110348 -327.044812)
		(width 0.14732)
		(layer "In6.Cu")
		(net "UPI_CPU0_CPU1_P2P2_DN<16>")
	)
	(segment
		(start 254.291084 -369.913916)
		(end 254.17145 -370.08435)
		(width 0.14732)
		(layer "In6.Cu")
		(net "UPI_CPU0_CPU1_P2P2_DN<16>")
	)
	(segment
		(start 105.266744 -277.540974)
		(end 105.266744 -277.522432)
		(width 0.0889)
		(layer "In6.Cu")
		(net "UPI_CPU0_CPU1_P2P2_DN<16>")
	)
	(segment
		(start 103.586788 -281.109674)
		(end 103.574596 -281.102562)
		(width 0.0889)
		(layer "In6.Cu")
		(net "UPI_CPU0_CPU1_P2P2_DN<16>")
	)
	(segment
		(start 99.654106 -295.720008)
		(end 99.654106 -293.209726)
		(width 0.14732)
		(layer "In6.Cu")
		(net "UPI_CPU0_CPU1_P2P2_DN<16>")
	)
	(segment
		(start 334.34782 -295.540684)
		(end 332.583282 -301.354998)
		(width 0.14732)
		(layer "In6.Cu")
		(net "UPI_CPU0_CPU1_P2P2_DN<16>")
	)
	(segment
		(start 99.611942 -293.145464)
		(end 99.611942 -292.553898)
		(width 0.0889)
		(layer "In6.Cu")
		(net "UPI_CPU0_CPU1_P2P2_DN<16>")
	)
	(segment
		(start 159.338772 -379.105668)
		(end 125.828552 -379.105668)
		(width 0.14732)
		(layer "In6.Cu")
		(net "UPI_CPU0_CPU1_P2P2_DN<16>")
	)
	(segment
		(start 339.668104 -287.615884)
		(end 339.659722 -287.62071)
		(width 0.0889)
		(layer "In6.Cu")
		(net "UPI_CPU0_CPU1_P2P2_DN<16>")
	)
	(segment
		(start 104.51719 -278.824436)
		(end 104.520492 -278.822404)
		(width 0.0889)
		(layer "In6.Cu")
		(net "UPI_CPU0_CPU1_P2P2_DN<16>")
	)
	(segment
		(start 338.25434 -290.76396)
		(end 336.093562 -292.924738)
		(width 0.14732)
		(layer "In6.Cu")
		(net "UPI_CPU0_CPU1_P2P2_DN<16>")
	)
	(segment
		(start 332.583282 -301.354998)
		(end 315.140848 -318.797686)
		(width 0.14732)
		(layer "In6.Cu")
		(net "UPI_CPU0_CPU1_P2P2_DN<16>")
	)
	(segment
		(start 103.387398 -282.414472)
		(end 103.387398 -282.3972)
		(width 0.0889)
		(layer "In6.Cu")
		(net "UPI_CPU0_CPU1_P2P2_DN<16>")
	)
	(segment
		(start 249.792236 -369.322604)
		(end 249.542554 -369.678966)
		(width 0.14732)
		(layer "In6.Cu")
		(net "UPI_CPU0_CPU1_P2P2_DN<16>")
	)
	(segment
		(start 102.686866 -276.24405)
		(end 102.665784 -276.165564)
		(width 0.0889)
		(layer "In6.Cu")
		(net "UPI_CPU0_CPU1_P2P2_DN<16>")
	)
	(segment
		(start 304.816764 -328.071734)
		(end 303.095152 -329.7936)
		(width 0.14732)
		(layer "In6.Cu")
		(net "UPI_CPU0_CPU1_P2P2_DN<16>")
	)
	(segment
		(start 102.625906 -286.969962)
		(end 102.646988 -286.95777)
		(width 0.0889)
		(layer "In6.Cu")
		(net "UPI_CPU0_CPU1_P2P2_DN<16>")
	)
	(segment
		(start 75.605894 -363.841538)
		(end 75.605894 -363.636814)
		(width 0.14732)
		(layer "In6.Cu")
		(net "UPI_CPU0_CPU1_P2P2_DN<16>")
	)
	(segment
		(start 199.037448 -372.107206)
		(end 159.338772 -379.105668)
		(width 0.14732)
		(layer "In6.Cu")
		(net "UPI_CPU0_CPU1_P2P2_DN<16>")
	)
	(segment
		(start 252.07468 -368.920014)
		(end 251.824998 -369.276376)
		(width 0.14732)
		(layer "In6.Cu")
		(net "UPI_CPU0_CPU1_P2P2_DN<16>")
	)
	(segment
		(start 340.14156 -282.895548)
		(end 340.15045 -282.900628)
		(width 0.0889)
		(layer "In6.Cu")
		(net "UPI_CPU0_CPU1_P2P2_DN<16>")
	)
	(segment
		(start 125.828552 -379.105668)
		(end 98.356166 -375.02719)
		(width 0.14732)
		(layer "In6.Cu")
		(net "UPI_CPU0_CPU1_P2P2_DN<16>")
	)
	(segment
		(start 307.409088 -324.307454)
		(end 306.208176 -325.148194)
		(width 0.14732)
		(layer "In6.Cu")
		(net "UPI_CPU0_CPU1_P2P2_DN<16>")
	)
	(segment
		(start 102.447344 -287.304734)
		(end 102.447344 -287.28924)
		(width 0.0889)
		(layer "In6.Cu")
		(net "UPI_CPU0_CPU1_P2P2_DN<16>")
	)
	(segment
		(start 255.87325 -369.78463)
		(end 255.702816 -369.664996)
		(width 0.14732)
		(layer "In6.Cu")
		(net "UPI_CPU0_CPU1_P2P2_DN<16>")
	)
	(segment
		(start 309.61711 -321.591432)
		(end 308.876446 -322.766182)
		(width 0.14732)
		(layer "In6.Cu")
		(net "UPI_CPU0_CPU1_P2P2_DN<16>")
	)
	(segment
		(start 251.824998 -369.276376)
		(end 252.00864 -370.316506)
		(width 0.14732)
		(layer "In6.Cu")
		(net "UPI_CPU0_CPU1_P2P2_DN<16>")
	)
	(segment
		(start 284.206442 -329.7936)
		(end 277.66264 -332.50378)
		(width 0.14732)
		(layer "In6.Cu")
		(net "UPI_CPU0_CPU1_P2P2_DN<16>")
	)
	(segment
		(start 254.17145 -370.08435)
		(end 253.590806 -370.18722)
		(width 0.14732)
		(layer "In6.Cu")
		(net "UPI_CPU0_CPU1_P2P2_DN<16>")
	)
	(segment
		(start 76.331572 -364.567216)
		(end 76.331572 -364.362492)
		(width 0.14732)
		(layer "In6.Cu")
		(net "UPI_CPU0_CPU1_P2P2_DN<16>")
	)
	(segment
		(start 104.514396 -278.82596)
		(end 104.51719 -278.824436)
		(width 0.0889)
		(layer "In6.Cu")
		(net "UPI_CPU0_CPU1_P2P2_DN<16>")
	)
	(segment
		(start 73.69302 -361.928664)
		(end 70.047358 -353.127818)
		(width 0.14732)
		(layer "In6.Cu")
		(net "UPI_CPU0_CPU1_P2P2_DN<16>")
	)
	(segment
		(start 303.095152 -329.7936)
		(end 284.206442 -329.7936)
		(width 0.14732)
		(layer "In6.Cu")
		(net "UPI_CPU0_CPU1_P2P2_DN<16>")
	)
	(segment
		(start 76.070968 -364.101888)
		(end 75.866244 -364.101888)
		(width 0.14732)
		(layer "In6.Cu")
		(net "UPI_CPU0_CPU1_P2P2_DN<16>")
	)
	(segment
		(start 340.61146 -283.709364)
		(end 340.62035 -283.714444)
		(width 0.0889)
		(layer "In6.Cu")
		(net "UPI_CPU0_CPU1_P2P2_DN<16>")
	)
	(segment
		(start 104.03586 -279.644856)
		(end 104.043734 -279.640284)
		(width 0.0889)
		(layer "In6.Cu")
		(net "UPI_CPU0_CPU1_P2P2_DN<16>")
	)
	(segment
		(start 248.352818 -371.110764)
		(end 239.799876 -369.60302)
		(width 0.14732)
		(layer "In6.Cu")
		(net "UPI_CPU0_CPU1_P2P2_DN<16>")
	)
	(segment
		(start 255.162812 -368.375184)
		(end 254.357124 -368.517424)
		(width 0.14732)
		(layer "In6.Cu")
		(net "UPI_CPU0_CPU1_P2P2_DN<16>")
	)
	(segment
		(start 338.269834 -290.748466)
		(end 338.25434 -290.76396)
		(width 0.0889)
		(layer "In6.Cu")
		(net "UPI_CPU0_CPU1_P2P2_DN<16>")
	)
	(segment
		(start 70.047358 -353.127818)
		(end 70.047358 -335.013808)
		(width 0.14732)
		(layer "In6.Cu")
		(net "UPI_CPU0_CPU1_P2P2_DN<16>")
	)
	(segment
		(start 340.61146 -284.35808)
		(end 340.605364 -284.361636)
		(width 0.0889)
		(layer "In6.Cu")
		(net "UPI_CPU0_CPU1_P2P2_DN<16>")
	)
	(segment
		(start 305.47691 -326.192642)
		(end 305.357276 -326.869806)
		(width 0.14732)
		(layer "In6.Cu")
		(net "UPI_CPU0_CPU1_P2P2_DN<16>")
	)
	(segment
		(start 338.424774 -289.705034)
		(end 338.424774 -290.652454)
		(width 0.0889)
		(layer "In6.Cu")
		(net "UPI_CPU0_CPU1_P2P2_DN<16>")
	)
	(segment
		(start 102.634796 -285.336996)
		(end 102.640892 -285.33344)
		(width 0.0889)
		(layer "In6.Cu")
		(net "UPI_CPU0_CPU1_P2P2_DN<16>")
	)
	(segment
		(start 102.625906 -285.342076)
		(end 102.633272 -285.337758)
		(width 0.0889)
		(layer "In6.Cu")
		(net "UPI_CPU0_CPU1_P2P2_DN<16>")
	)
	(segment
		(start 340.329012 -283.219906)
		(end 340.329012 -283.229812)
		(width 0.0889)
		(layer "In6.Cu")
		(net "UPI_CPU0_CPU1_P2P2_DN<16>")
	)
	(segment
		(start 96.11233 -302.87214)
		(end 97.424748 -301.102522)
		(width 0.14732)
		(layer "In6.Cu")
		(net "UPI_CPU0_CPU1_P2P2_DN<16>")
	)
	(segment
		(start 340.141814 -286.151066)
		(end 340.150704 -286.156146)
		(width 0.0889)
		(layer "In6.Cu")
		(net "UPI_CPU0_CPU1_P2P2_DN<16>")
	)
	(segment
		(start 101.507798 -289.078416)
		(end 101.507798 -288.917126)
		(width 0.0889)
		(layer "In6.Cu")
		(net "UPI_CPU0_CPU1_P2P2_DN<16>")
	)
	(segment
		(start 310.797194 -320.596768)
		(end 309.61711 -321.591432)
		(width 0.14732)
		(layer "In6.Cu")
		(net "UPI_CPU0_CPU1_P2P2_DN<16>")
	)
	(segment
		(start 98.356166 -375.02719)
		(end 78.614016 -366.84966)
		(width 0.14732)
		(layer "In6.Cu")
		(net "UPI_CPU0_CPU1_P2P2_DN<16>")
	)
	(segment
		(start 99.654106 -293.209726)
		(end 99.654106 -293.187628)
		(width 0.0889)
		(layer "In6.Cu")
		(net "UPI_CPU0_CPU1_P2P2_DN<16>")
	)
	(segment
		(start 255.702816 -369.664996)
		(end 255.519174 -368.624866)
		(width 0.14732)
		(layer "In6.Cu")
		(net "UPI_CPU0_CPU1_P2P2_DN<16>")
	)
	(segment
		(start 252.880368 -368.777774)
		(end 252.07468 -368.920014)
		(width 0.14732)
		(layer "In6.Cu")
		(net "UPI_CPU0_CPU1_P2P2_DN<16>")
	)
	(segment
		(start 105.45699 -277.19655)
		(end 105.460292 -277.194518)
		(width 0.0889)
		(layer "In6.Cu")
		(net "UPI_CPU0_CPU1_P2P2_DN<16>")
	)
	(segment
		(start 104.797098 -278.336502)
		(end 104.797098 -278.327866)
		(width 0.0889)
		(layer "In6.Cu")
		(net "UPI_CPU0_CPU1_P2P2_DN<16>")
	)
	(segment
		(start 250.597924 -369.180364)
		(end 249.792236 -369.322604)
		(width 0.14732)
		(layer "In6.Cu")
		(net "UPI_CPU0_CPU1_P2P2_DN<16>")
	)
	(segment
		(start 74.414888 -362.650532)
		(end 73.69302 -361.928664)
		(width 0.14732)
		(layer "In6.Cu")
		(net "UPI_CPU0_CPU1_P2P2_DN<16>")
	)
	(segment
		(start 250.954286 -369.430046)
		(end 250.597924 -369.180364)
		(width 0.14732)
		(layer "In6.Cu")
		(net "UPI_CPU0_CPU1_P2P2_DN<16>")
	)
	(segment
		(start 101.694488 -288.593276)
		(end 101.69525 -288.592768)
		(width 0.0889)
		(layer "In6.Cu")
		(net "UPI_CPU0_CPU1_P2P2_DN<16>")
	)
	(segment
		(start 74.619612 -362.650532)
		(end 74.414888 -362.650532)
		(width 0.14732)
		(layer "In6.Cu")
		(net "UPI_CPU0_CPU1_P2P2_DN<16>")
	)
	(segment
		(start 102.665784 -276.165564)
		(end 102.821994 -275.8948)
		(width 0.0889)
		(layer "In6.Cu")
		(net "UPI_CPU0_CPU1_P2P2_DN<16>")
	)
	(segment
		(start 74.880216 -363.11586)
		(end 74.880216 -362.911136)
		(width 0.14732)
		(layer "In6.Cu")
		(net "UPI_CPU0_CPU1_P2P2_DN<16>")
	)
	(segment
		(start 99.654106 -293.187628)
		(end 99.611942 -293.145464)
		(width 0.0889)
		(layer "In6.Cu")
		(net "UPI_CPU0_CPU1_P2P2_DN<16>")
	)
	(segment
		(start 101.977444 -290.188396)
		(end 101.977444 -289.609276)
		(width 0.0889)
		(layer "In6.Cu")
		(net "UPI_CPU0_CPU1_P2P2_DN<16>")
	)
	(segment
		(start 338.328762 -290.748466)
		(end 338.269834 -290.748466)
		(width 0.0889)
		(layer "In6.Cu")
		(net "UPI_CPU0_CPU1_P2P2_DN<16>")
	)
	(segment
		(start 105.452672 -277.198836)
		(end 105.454196 -277.198074)
		(width 0.0889)
		(layer "In6.Cu")
		(net "UPI_CPU0_CPU1_P2P2_DN<16>")
	)
	(segment
		(start 101.977698 -288.121598)
		(end 101.977698 -288.103056)
		(width 0.0889)
		(layer "In6.Cu")
		(net "UPI_CPU0_CPU1_P2P2_DN<16>")
	)
	(segment
		(start 253.420372 -370.067586)
		(end 253.23673 -369.027456)
		(width 0.14732)
		(layer "In6.Cu")
		(net "UPI_CPU0_CPU1_P2P2_DN<16>")
	)
	(segment
		(start 102.633272 -285.337758)
		(end 102.634796 -285.336996)
		(width 0.0889)
		(layer "In6.Cu")
		(net "UPI_CPU0_CPU1_P2P2_DN<16>")
	)
	(segment
		(start 339.859366 -282.390342)
		(end 339.859366 -282.427934)
		(width 0.0889)
		(layer "In6.Cu")
		(net "UPI_CPU0_CPU1_P2P2_DN<16>")
	)
	(segment
		(start 262.23849 -368.662458)
		(end 255.87325 -369.78463)
		(width 0.14732)
		(layer "In6.Cu")
		(net "UPI_CPU0_CPU1_P2P2_DN<16>")
	)
	(segment
		(start 340.150704 -286.794702)
		(end 340.141814 -286.799782)
		(width 0.0889)
		(layer "In6.Cu")
		(net "UPI_CPU0_CPU1_P2P2_DN<16>")
	)
	(segment
		(start 239.799876 -369.60302)
		(end 212.31225 -374.44807)
		(width 0.14732)
		(layer "In6.Cu")
		(net "UPI_CPU0_CPU1_P2P2_DN<16>")
	)
	(segment
		(start 255.519174 -368.624866)
		(end 255.162812 -368.375184)
		(width 0.14732)
		(layer "In6.Cu")
		(net "UPI_CPU0_CPU1_P2P2_DN<16>")
	)
	(segment
		(start 340.15045 -281.911298)
		(end 340.14156 -281.916378)
		(width 0.0889)
		(layer "In6.Cu")
		(net "UPI_CPU0_CPU1_P2P2_DN<16>")
	)
	(segment
		(start 265.86307 -344.30335)
		(end 265.86307 -365.037878)
		(width 0.14732)
		(layer "In6.Cu")
		(net "UPI_CPU0_CPU1_P2P2_DN<16>")
	)
	(segment
		(start 97.424748 -301.102522)
		(end 99.654106 -295.720008)
		(width 0.14732)
		(layer "In6.Cu")
		(net "UPI_CPU0_CPU1_P2P2_DN<16>")
	)
	(segment
		(start 71.110348 -327.044812)
		(end 72.85863 -323.348858)
		(width 0.14732)
		(layer "In6.Cu")
		(net "UPI_CPU0_CPU1_P2P2_DN<16>")
	)
	(segment
		(start 249.542554 -369.678966)
		(end 249.726196 -370.719096)
		(width 0.14732)
		(layer "In6.Cu")
		(net "UPI_CPU0_CPU1_P2P2_DN<16>")
	)
	(segment
		(start 103.857044 -283.229812)
		(end 103.857044 -283.201364)
		(width 0.0889)
		(layer "In6.Cu")
		(net "UPI_CPU0_CPU1_P2P2_DN<16>")
	)
	(segment
		(start 252.00864 -370.316506)
		(end 251.889006 -370.48694)
		(width 0.14732)
		(layer "In6.Cu")
		(net "UPI_CPU0_CPU1_P2P2_DN<16>")
	)
	(segment
		(start 75.866244 -364.101888)
		(end 75.605894 -363.841538)
		(width 0.14732)
		(layer "In6.Cu")
		(net "UPI_CPU0_CPU1_P2P2_DN<16>")
	)
	(segment
		(start 251.308362 -370.58981)
		(end 251.137928 -370.470176)
		(width 0.14732)
		(layer "In6.Cu")
		(net "UPI_CPU0_CPU1_P2P2_DN<16>")
	)
	(segment
		(start 338.919566 -288.895028)
		(end 338.919566 -289.077908)
		(width 0.0889)
		(layer "In6.Cu")
		(net "UPI_CPU0_CPU1_P2P2_DN<16>")
	)
	(segment
		(start 78.614016 -366.84966)
		(end 77.130656 -365.3663)
		(width 0.14732)
		(layer "In6.Cu")
		(net "UPI_CPU0_CPU1_P2P2_DN<16>")
	)
	(segment
		(start 308.876446 -322.766182)
		(end 307.409088 -324.307454)
		(width 0.14732)
		(layer "In6.Cu")
		(net "UPI_CPU0_CPU1_P2P2_DN<16>")
	)
	(segment
		(start 306.208176 -325.148194)
		(end 305.47691 -326.192642)
		(width 0.14732)
		(layer "In6.Cu")
		(net "UPI_CPU0_CPU1_P2P2_DN<16>")
	)
	(segment
		(start 77.130656 -365.161576)
		(end 76.870052 -364.900972)
		(width 0.14732)
		(layer "In6.Cu")
		(net "UPI_CPU0_CPU1_P2P2_DN<16>")
	)
	(segment
		(start 76.331572 -364.362492)
		(end 76.070968 -364.101888)
		(width 0.14732)
		(layer "In6.Cu")
		(net "UPI_CPU0_CPU1_P2P2_DN<16>")
	)
	(segment
		(start 76.870052 -364.900972)
		(end 76.665328 -364.900972)
		(width 0.14732)
		(layer "In6.Cu")
		(net "UPI_CPU0_CPU1_P2P2_DN<16>")
	)
	(segment
		(start 105.445306 -277.203154)
		(end 105.452672 -277.198836)
		(width 0.0889)
		(layer "In6.Cu")
		(net "UPI_CPU0_CPU1_P2P2_DN<16>")
	)
	(segment
		(start 251.889006 -370.48694)
		(end 251.308362 -370.58981)
		(width 0.14732)
		(layer "In6.Cu")
		(net "UPI_CPU0_CPU1_P2P2_DN<16>")
	)
	(segment
		(start 70.047358 -335.013808)
		(end 70.67804 -328.607166)
		(width 0.14732)
		(layer "In6.Cu")
		(net "UPI_CPU0_CPU1_P2P2_DN<16>")
	)
	(segment
		(start 75.140566 -363.37621)
		(end 74.880216 -363.11586)
		(width 0.14732)
		(layer "In6.Cu")
		(net "UPI_CPU0_CPU1_P2P2_DN<16>")
	)
	(segment
		(start 104.514396 -276.219158)
		(end 104.499664 -276.210522)
		(width 0.0889)
		(layer "In6.Cu")
		(net "UPI_CPU0_CPU1_P2P2_DN<16>")
	)
	(segment
		(start 254.107442 -368.873786)
		(end 254.291084 -369.913916)
		(width 0.14732)
		(layer "In6.Cu")
		(net "UPI_CPU0_CPU1_P2P2_DN<16>")
	)
	(segment
		(start 340.58098 -281.049222)
		(end 340.55685 -281.138376)
		(width 0.0889)
		(layer "In6.Cu")
		(net "UPI_CPU0_CPU1_P2P2_DN<16>")
	)
	(arc
		(start 340.14156 -285.171896)
		(mid 339.937225 -285.374501)
		(end 339.859112 -285.651448)
		(width 0.0889)
		(layer "In6.Cu")
		(net "UPI_CPU0_CPU1_P2P2_DN<16>")
	)
	(arc
		(start 105.736898 -276.69871)
		(mid 105.658787 -276.421761)
		(end 105.45445 -276.219158)
		(width 0.0889)
		(layer "In6.Cu")
		(net "UPI_CPU0_CPU1_P2P2_DN<16>")
	)
	(arc
		(start 103.586788 -282.074366)
		(mid 103.857244 -281.59202)
		(end 103.586788 -281.109674)
		(width 0.0889)
		(layer "In6.Cu")
		(net "UPI_CPU0_CPU1_P2P2_DN<16>")
	)
	(arc
		(start 103.387398 -280.769568)
		(mid 103.439668 -280.587203)
		(end 103.574596 -280.453846)
		(width 0.0889)
		(layer "In6.Cu")
		(net "UPI_CPU0_CPU1_P2P2_DN<16>")
	)
	(arc
		(start 340.329266 -286.466026)
		(mid 340.329354 -286.474027)
		(end 340.329266 -286.482028)
		(width 0.0889)
		(layer "In6.Cu")
		(net "UPI_CPU0_CPU1_P2P2_DN<16>")
	)
	(arc
		(start 101.977698 -288.103056)
		(mid 102.025377 -287.920156)
		(end 102.15626 -287.783778)
		(width 0.0889)
		(layer "In6.Cu")
		(net "UPI_CPU0_CPU1_P2P2_DN<16>")
	)
	(arc
		(start 338.428838 -289.684206)
		(mid 338.426714 -289.694602)
		(end 338.424774 -289.705034)
		(width 0.0889)
		(layer "In6.Cu")
		(net "UPI_CPU0_CPU1_P2P2_DN<16>")
	)
	(arc
		(start 104.520492 -278.822404)
		(mid 104.723079 -278.616053)
		(end 104.797098 -278.336502)
		(width 0.0889)
		(layer "In6.Cu")
		(net "UPI_CPU0_CPU1_P2P2_DN<16>")
	)
	(arc
		(start 340.328758 -283.205174)
		(mid 340.328955 -283.212539)
		(end 340.329012 -283.219906)
		(width 0.0889)
		(layer "In6.Cu")
		(net "UPI_CPU0_CPU1_P2P2_DN<16>")
	)
	(arc
		(start 340.798912 -284.027118)
		(mid 340.799006 -284.0355)
		(end 340.798912 -284.043882)
		(width 0.0889)
		(layer "In6.Cu")
		(net "UPI_CPU0_CPU1_P2P2_DN<16>")
	)
	(arc
		(start 103.559864 -276.210522)
		(mid 103.283389 -276.143202)
		(end 103.009192 -276.219158)
		(width 0.0889)
		(layer "In6.Cu")
		(net "UPI_CPU0_CPU1_P2P2_DN<16>")
	)
	(arc
		(start 340.329012 -281.59202)
		(mid 340.281333 -281.77492)
		(end 340.15045 -281.911298)
		(width 0.0889)
		(layer "In6.Cu")
		(net "UPI_CPU0_CPU1_P2P2_DN<16>")
	)
	(arc
		(start 340.605364 -284.361636)
		(mid 340.402951 -284.568049)
		(end 340.329012 -284.847538)
		(width 0.0889)
		(layer "In6.Cu")
		(net "UPI_CPU0_CPU1_P2P2_DN<16>")
	)
	(arc
		(start 340.62035 -283.714444)
		(mid 340.749639 -283.84793)
		(end 340.798912 -284.027118)
		(width 0.0889)
		(layer "In6.Cu")
		(net "UPI_CPU0_CPU1_P2P2_DN<16>")
	)
	(arc
		(start 340.55685 -281.138376)
		(mid 340.548278 -281.144898)
		(end 340.539832 -281.151584)
		(width 0.0889)
		(layer "In6.Cu")
		(net "UPI_CPU0_CPU1_P2P2_DN<16>")
	)
	(arc
		(start 101.96195 -289.569398)
		(mid 101.851835 -289.400563)
		(end 101.691948 -289.277806)
		(width 0.0889)
		(layer "In6.Cu")
		(net "UPI_CPU0_CPU1_P2P2_DN<16>")
	)
	(arc
		(start 103.574596 -280.453846)
		(mid 103.779668 -280.250167)
		(end 103.857298 -279.971754)
		(width 0.0889)
		(layer "In6.Cu")
		(net "UPI_CPU0_CPU1_P2P2_DN<16>")
	)
	(arc
		(start 103.387144 -284.033722)
		(mid 103.434823 -283.850822)
		(end 103.565706 -283.714444)
		(width 0.0889)
		(layer "In6.Cu")
		(net "UPI_CPU0_CPU1_P2P2_DN<16>")
	)
	(arc
		(start 104.499664 -276.210522)
		(mid 104.223189 -276.143202)
		(end 103.948992 -276.219158)
		(width 0.0889)
		(layer "In6.Cu")
		(net "UPI_CPU0_CPU1_P2P2_DN<16>")
	)
	(arc
		(start 102.447344 -287.28924)
		(mid 102.495023 -287.10634)
		(end 102.625906 -286.969962)
		(width 0.0889)
		(layer "In6.Cu")
		(net "UPI_CPU0_CPU1_P2P2_DN<16>")
	)
	(arc
		(start 101.507798 -288.917126)
		(mid 101.555477 -288.734226)
		(end 101.68636 -288.597848)
		(width 0.0889)
		(layer "In6.Cu")
		(net "UPI_CPU0_CPU1_P2P2_DN<16>")
	)
	(arc
		(start 102.640892 -285.33344)
		(mid 102.843479 -285.127089)
		(end 102.917498 -284.847538)
		(width 0.0889)
		(layer "In6.Cu")
		(net "UPI_CPU0_CPU1_P2P2_DN<16>")
	)
	(arc
		(start 103.574596 -282.730194)
		(mid 103.439663 -282.59684)
		(end 103.387398 -282.414472)
		(width 0.0889)
		(layer "In6.Cu")
		(net "UPI_CPU0_CPU1_P2P2_DN<16>")
	)
	(arc
		(start 339.389212 -288.103056)
		(mid 339.341533 -288.285956)
		(end 339.21065 -288.422334)
		(width 0.0889)
		(layer "In6.Cu")
		(net "UPI_CPU0_CPU1_P2P2_DN<16>")
	)
	(arc
		(start 104.326944 -279.150318)
		(mid 104.374623 -278.967418)
		(end 104.505506 -278.83104)
		(width 0.0889)
		(layer "In6.Cu")
		(net "UPI_CPU0_CPU1_P2P2_DN<16>")
	)
	(arc
		(start 339.859112 -285.675578)
		(mid 339.938331 -285.950263)
		(end 340.141814 -286.151066)
		(width 0.0889)
		(layer "In6.Cu")
		(net "UPI_CPU0_CPU1_P2P2_DN<16>")
	)
	(arc
		(start 103.857298 -279.964134)
		(mid 103.904977 -279.781234)
		(end 104.03586 -279.644856)
		(width 0.0889)
		(layer "In6.Cu")
		(net "UPI_CPU0_CPU1_P2P2_DN<16>")
	)
	(arc
		(start 103.574596 -283.709364)
		(mid 103.778931 -283.506759)
		(end 103.857044 -283.229812)
		(width 0.0889)
		(layer "In6.Cu")
		(net "UPI_CPU0_CPU1_P2P2_DN<16>")
	)
	(arc
		(start 340.798912 -284.043882)
		(mid 340.748843 -284.221107)
		(end 340.62035 -284.353)
		(width 0.0889)
		(layer "In6.Cu")
		(net "UPI_CPU0_CPU1_P2P2_DN<16>")
	)
	(arc
		(start 340.14156 -281.916378)
		(mid 339.938737 -282.116609)
		(end 339.859366 -282.390342)
		(width 0.0889)
		(layer "In6.Cu")
		(net "UPI_CPU0_CPU1_P2P2_DN<16>")
	)
	(arc
		(start 104.04475 -279.639776)
		(mid 104.247573 -279.439545)
		(end 104.326944 -279.165812)
		(width 0.0889)
		(layer "In6.Cu")
		(net "UPI_CPU0_CPU1_P2P2_DN<16>")
	)
	(arc
		(start 103.009192 -276.219158)
		(mid 102.850852 -276.268188)
		(end 102.686866 -276.24405)
		(width 0.0889)
		(layer "In6.Cu")
		(net "UPI_CPU0_CPU1_P2P2_DN<16>")
	)
	(arc
		(start 340.150704 -286.156146)
		(mid 340.279298 -286.28842)
		(end 340.329266 -286.466026)
		(width 0.0889)
		(layer "In6.Cu")
		(net "UPI_CPU0_CPU1_P2P2_DN<16>")
	)
	(arc
		(start 102.646988 -286.95777)
		(mid 102.845216 -286.751922)
		(end 102.917498 -286.475424)
		(width 0.0889)
		(layer "In6.Cu")
		(net "UPI_CPU0_CPU1_P2P2_DN<16>")
	)
	(arc
		(start 101.69525 -288.592768)
		(mid 101.897536 -288.393787)
		(end 101.977698 -288.121598)
		(width 0.0889)
		(layer "In6.Cu")
		(net "UPI_CPU0_CPU1_P2P2_DN<16>")
	)
	(arc
		(start 339.859366 -287.28924)
		(mid 339.811687 -287.47214)
		(end 339.680804 -287.608518)
		(width 0.0889)
		(layer "In6.Cu")
		(net "UPI_CPU0_CPU1_P2P2_DN<16>")
	)
	(arc
		(start 340.15045 -282.900628)
		(mid 340.277704 -283.030594)
		(end 340.328758 -283.205174)
		(width 0.0889)
		(layer "In6.Cu")
		(net "UPI_CPU0_CPU1_P2P2_DN<16>")
	)
	(arc
		(start 340.539832 -281.151584)
		(mid 340.384434 -281.347865)
		(end 340.329012 -281.59202)
		(width 0.0889)
		(layer "In6.Cu")
		(net "UPI_CPU0_CPU1_P2P2_DN<16>")
	)
	(arc
		(start 102.625906 -285.980632)
		(mid 102.44743 -285.661354)
		(end 102.625906 -285.342076)
		(width 0.0889)
		(layer "In6.Cu")
		(net "UPI_CPU0_CPU1_P2P2_DN<16>")
	)
	(arc
		(start 340.329012 -283.229812)
		(mid 340.407123 -283.506761)
		(end 340.61146 -283.709364)
		(width 0.0889)
		(layer "In6.Cu")
		(net "UPI_CPU0_CPU1_P2P2_DN<16>")
	)
	(arc
		(start 104.797098 -278.327866)
		(mid 104.849368 -278.145501)
		(end 104.984296 -278.012144)
		(width 0.0889)
		(layer "In6.Cu")
		(net "UPI_CPU0_CPU1_P2P2_DN<16>")
	)
	(arc
		(start 104.984296 -278.012144)
		(mid 105.186582 -277.813163)
		(end 105.266744 -277.540974)
		(width 0.0889)
		(layer "In6.Cu")
		(net "UPI_CPU0_CPU1_P2P2_DN<16>")
	)
	(arc
		(start 105.266744 -277.522432)
		(mid 105.314423 -277.339532)
		(end 105.445306 -277.203154)
		(width 0.0889)
		(layer "In6.Cu")
		(net "UPI_CPU0_CPU1_P2P2_DN<16>")
	)
	(arc
		(start 103.574596 -281.102562)
		(mid 103.439663 -280.969208)
		(end 103.387398 -280.78684)
		(width 0.0889)
		(layer "In6.Cu")
		(net "UPI_CPU0_CPU1_P2P2_DN<16>")
	)
	(arc
		(start 340.141814 -286.799782)
		(mid 339.937479 -287.002387)
		(end 339.859366 -287.279334)
		(width 0.0889)
		(layer "In6.Cu")
		(net "UPI_CPU0_CPU1_P2P2_DN<16>")
	)
	(arc
		(start 340.329012 -284.847538)
		(mid 340.281333 -285.030438)
		(end 340.15045 -285.166816)
		(width 0.0889)
		(layer "In6.Cu")
		(net "UPI_CPU0_CPU1_P2P2_DN<16>")
	)
	(arc
		(start 338.735162 -289.277806)
		(mid 338.536625 -289.446813)
		(end 338.428838 -289.684206)
		(width 0.0889)
		(layer "In6.Cu")
		(net "UPI_CPU0_CPU1_P2P2_DN<16>")
	)
	(arc
		(start 339.659722 -287.62071)
		(mid 339.461494 -287.826558)
		(end 339.389212 -288.103056)
		(width 0.0889)
		(layer "In6.Cu")
		(net "UPI_CPU0_CPU1_P2P2_DN<16>")
	)
	(arc
		(start 339.20176 -288.427414)
		(mid 339.000478 -288.624901)
		(end 338.919566 -288.895028)
		(width 0.0889)
		(layer "In6.Cu")
		(net "UPI_CPU0_CPU1_P2P2_DN<16>")
	)
	(arc
		(start 103.948992 -276.219158)
		(mid 103.761794 -276.269301)
		(end 103.574596 -276.219158)
		(width 0.0889)
		(layer "In6.Cu")
		(net "UPI_CPU0_CPU1_P2P2_DN<16>")
	)
	(arc
		(start 101.691948 -289.277806)
		(mid 101.582801 -289.193878)
		(end 101.507798 -289.078416)
		(width 0.0889)
		(layer "In6.Cu")
		(net "UPI_CPU0_CPU1_P2P2_DN<16>")
	)
	(arc
		(start 105.460292 -277.194518)
		(mid 105.662879 -276.988167)
		(end 105.736898 -276.708616)
		(width 0.0889)
		(layer "In6.Cu")
		(net "UPI_CPU0_CPU1_P2P2_DN<16>")
	)
	(arc
		(start 105.444036 -276.213062)
		(mid 105.165604 -276.143216)
		(end 104.888792 -276.219158)
		(width 0.0889)
		(layer "In6.Cu")
		(net "UPI_CPU0_CPU1_P2P2_DN<16>")
	)
	(arc
		(start 104.888792 -276.219158)
		(mid 104.701594 -276.269301)
		(end 104.514396 -276.219158)
		(width 0.0889)
		(layer "In6.Cu")
		(net "UPI_CPU0_CPU1_P2P2_DN<16>")
	)
	(arc
		(start 339.859366 -282.427934)
		(mid 339.940277 -282.698062)
		(end 340.14156 -282.895548)
		(width 0.0889)
		(layer "In6.Cu")
		(net "UPI_CPU0_CPU1_P2P2_DN<16>")
	)
	(arc
		(start 340.329266 -286.482028)
		(mid 340.280013 -286.661228)
		(end 340.150704 -286.794702)
		(width 0.0889)
		(layer "In6.Cu")
		(net "UPI_CPU0_CPU1_P2P2_DN<16>")
	)
	(arc
		(start 102.917498 -286.475424)
		(mid 102.841741 -286.192709)
		(end 102.634796 -285.985712)
		(width 0.0889)
		(layer "In6.Cu")
		(net "UPI_CPU0_CPU1_P2P2_DN<16>")
	)
	(arc
		(start 101.977444 -289.609276)
		(mid 101.97005 -289.5892)
		(end 101.96195 -289.569398)
		(width 0.0889)
		(layer "In6.Cu")
		(net "UPI_CPU0_CPU1_P2P2_DN<16>")
	)
	(arc
		(start 103.387398 -282.3972)
		(mid 103.439668 -282.214835)
		(end 103.574596 -282.081478)
		(width 0.0889)
		(layer "In6.Cu")
		(net "UPI_CPU0_CPU1_P2P2_DN<16>")
	)
	(arc
		(start 338.919566 -289.077908)
		(mid 338.844495 -289.19365)
		(end 338.735162 -289.277806)
		(width 0.0889)
		(layer "In6.Cu")
		(net "UPI_CPU0_CPU1_P2P2_DN<16>")
	)
	(arc
		(start 102.917498 -284.838902)
		(mid 102.969768 -284.656537)
		(end 103.104696 -284.52318)
		(width 0.0889)
		(layer "In6.Cu")
		(net "UPI_CPU0_CPU1_P2P2_DN<16>")
	)
	(arc
		(start 103.104696 -284.52318)
		(mid 103.309031 -284.320575)
		(end 103.387144 -284.043628)
		(width 0.0889)
		(layer "In6.Cu")
		(net "UPI_CPU0_CPU1_P2P2_DN<16>")
	)
	(arc
		(start 103.857044 -283.201364)
		(mid 103.776882 -282.929175)
		(end 103.574596 -282.730194)
		(width 0.0889)
		(layer "In6.Cu")
		(net "UPI_CPU0_CPU1_P2P2_DN<16>")
	)
	(arc
		(start 102.16515 -287.778698)
		(mid 102.367973 -287.578467)
		(end 102.447344 -287.304734)
		(width 0.0889)
		(layer "In6.Cu")
		(net "UPI_CPU0_CPU1_P2P2_DN<16>")
	)
	(segment
		(start 104.231694 -276.172676)
		(end 104.231694 -276.708362)
		(width 0.13208)
		(layer "F.Cu")
		(net "UPI_CPU0_CPU1_P2P2_DN<15>")
	)
	(segment
		(start 340.894162 -282.683966)
		(end 340.894162 -283.219906)
		(width 0.13208)
		(layer "F.Cu")
		(net "UPI_CPU0_CPU1_P2P2_DN<15>")
	)
	(segment
		(start 104.231694 -276.708362)
		(end 104.231948 -276.708616)
		(width 0.13208)
		(layer "F.Cu")
		(net "UPI_CPU0_CPU1_P2P2_DN<15>")
	)
	(segment
		(start 102.726744 -283.228542)
		(end 102.726744 -283.21127)
		(width 0.0889)
		(layer "In6.Cu")
		(net "UPI_CPU0_CPU1_P2P2_DN<15>")
	)
	(segment
		(start 284.563312 -330.89596)
		(end 278.190198 -333.535528)
		(width 0.14732)
		(layer "In6.Cu")
		(net "UPI_CPU0_CPU1_P2P2_DN<15>")
	)
	(segment
		(start 341.170006 -285.340806)
		(end 341.167974 -285.342076)
		(width 0.0889)
		(layer "In6.Cu")
		(net "UPI_CPU0_CPU1_P2P2_DN<15>")
	)
	(segment
		(start 340.707218 -287.778698)
		(end 340.698328 -287.783778)
		(width 0.0889)
		(layer "In6.Cu")
		(net "UPI_CPU0_CPU1_P2P2_DN<15>")
	)
	(segment
		(start 159.435546 -380.20879)
		(end 125.709934 -380.20879)
		(width 0.14732)
		(layer "In6.Cu")
		(net "UPI_CPU0_CPU1_P2P2_DN<15>")
	)
	(segment
		(start 340.519258 -289.610292)
		(end 340.519258 -290.161218)
		(width 0.0889)
		(layer "In6.Cu")
		(net "UPI_CPU0_CPU1_P2P2_DN<15>")
	)
	(segment
		(start 102.53345 -278.664416)
		(end 102.538784 -278.661368)
		(width 0.0889)
		(layer "In6.Cu")
		(net "UPI_CPU0_CPU1_P2P2_DN<15>")
	)
	(segment
		(start 234.308142 -372.63959)
		(end 234.058714 -372.996206)
		(width 0.14732)
		(layer "In6.Cu")
		(net "UPI_CPU0_CPU1_P2P2_DN<15>")
	)
	(segment
		(start 103.948992 -277.84679)
		(end 103.957882 -277.84171)
		(width 0.0889)
		(layer "In6.Cu")
		(net "UPI_CPU0_CPU1_P2P2_DN<15>")
	)
	(segment
		(start 333.560674 -301.940976)
		(end 314.453016 -321.04838)
		(width 0.14732)
		(layer "In6.Cu")
		(net "UPI_CPU0_CPU1_P2P2_DN<15>")
	)
	(segment
		(start 278.190198 -333.535528)
		(end 267.23213 -344.493596)
		(width 0.14732)
		(layer "In6.Cu")
		(net "UPI_CPU0_CPU1_P2P2_DN<15>")
	)
	(segment
		(start 339.18271 -291.55771)
		(end 339.167216 -291.573204)
		(width 0.0889)
		(layer "In6.Cu")
		(net "UPI_CPU0_CPU1_P2P2_DN<15>")
	)
	(segment
		(start 234.87253 -371.598698)
		(end 234.29214 -371.701568)
		(width 0.14732)
		(layer "In6.Cu")
		(net "UPI_CPU0_CPU1_P2P2_DN<15>")
	)
	(segment
		(start 341.551514 -282.730194)
		(end 341.566246 -282.721558)
		(width 0.0889)
		(layer "In6.Cu")
		(net "UPI_CPU0_CPU1_P2P2_DN<15>")
	)
	(segment
		(start 303.954688 -330.89596)
		(end 284.563312 -330.89596)
		(width 0.14732)
		(layer "In6.Cu")
		(net "UPI_CPU0_CPU1_P2P2_DN<15>")
	)
	(segment
		(start 336.73669 -294.002714)
		(end 336.736436 -294.002714)
		(width 0.14732)
		(layer "In6.Cu")
		(net "UPI_CPU0_CPU1_P2P2_DN<15>")
	)
	(segment
		(start 238.622586 -372.188994)
		(end 237.817152 -372.331488)
		(width 0.14732)
		(layer "In6.Cu")
		(net "UPI_CPU0_CPU1_P2P2_DN<15>")
	)
	(segment
		(start 99.86518 -290.655248)
		(end 99.865434 -290.654994)
		(width 0.14732)
		(layer "In6.Cu")
		(net "UPI_CPU0_CPU1_P2P2_DN<15>")
	)
	(segment
		(start 102.539546 -281.267662)
		(end 102.527354 -281.26055)
		(width 0.0889)
		(layer "In6.Cu")
		(net "UPI_CPU0_CPU1_P2P2_DN<15>")
	)
	(segment
		(start 102.54107 -278.660098)
		(end 102.548436 -278.65578)
		(width 0.0889)
		(layer "In6.Cu")
		(net "UPI_CPU0_CPU1_P2P2_DN<15>")
	)
	(segment
		(start 308.524656 -324.982332)
		(end 307.19268 -325.915782)
		(width 0.14732)
		(layer "In6.Cu")
		(net "UPI_CPU0_CPU1_P2P2_DN<15>")
	)
	(segment
		(start 340.049866 -288.917126)
		(end 340.049866 -289.078416)
		(width 0.0889)
		(layer "In6.Cu")
		(net "UPI_CPU0_CPU1_P2P2_DN<15>")
	)
	(segment
		(start 95.277178 -302.128682)
		(end 96.438466 -300.563026)
		(width 0.14732)
		(layer "In6.Cu")
		(net "UPI_CPU0_CPU1_P2P2_DN<15>")
	)
	(segment
		(start 340.237318 -288.592768)
		(end 340.228428 -288.597848)
		(width 0.0889)
		(layer "In6.Cu")
		(net "UPI_CPU0_CPU1_P2P2_DN<15>")
	)
	(segment
		(start 234.172506 -371.872256)
		(end 234.308142 -372.63959)
		(width 0.14732)
		(layer "In6.Cu")
		(net "UPI_CPU0_CPU1_P2P2_DN<15>")
	)
	(segment
		(start 236.590078 -372.235984)
		(end 236.34065 -372.5926)
		(width 0.14732)
		(layer "In6.Cu")
		(net "UPI_CPU0_CPU1_P2P2_DN<15>")
	)
	(segment
		(start 99.86518 -290.88842)
		(end 99.86518 -290.655248)
		(width 0.14732)
		(layer "In6.Cu")
		(net "UPI_CPU0_CPU1_P2P2_DN<15>")
	)
	(segment
		(start 102.256844 -280.778204)
		(end 102.256844 -280.770584)
		(width 0.0889)
		(layer "In6.Cu")
		(net "UPI_CPU0_CPU1_P2P2_DN<15>")
	)
	(segment
		(start 102.538784 -279.639268)
		(end 102.53345 -279.63622)
		(width 0.0889)
		(layer "In6.Cu")
		(net "UPI_CPU0_CPU1_P2P2_DN<15>")
	)
	(segment
		(start 102.53345 -283.54782)
		(end 102.538784 -283.544772)
		(width 0.0889)
		(layer "In6.Cu")
		(net "UPI_CPU0_CPU1_P2P2_DN<15>")
	)
	(segment
		(start 98.165412 -292.588188)
		(end 99.86518 -290.88842)
		(width 0.14732)
		(layer "In6.Cu")
		(net "UPI_CPU0_CPU1_P2P2_DN<15>")
	)
	(segment
		(start 235.042964 -371.718332)
		(end 234.87253 -371.598698)
		(width 0.14732)
		(layer "In6.Cu")
		(net "UPI_CPU0_CPU1_P2P2_DN<15>")
	)
	(segment
		(start 336.736436 -294.002714)
		(end 336.154268 -294.831262)
		(width 0.14732)
		(layer "In6.Cu")
		(net "UPI_CPU0_CPU1_P2P2_DN<15>")
	)
	(segment
		(start 233.25328 -373.1387)
		(end 232.896918 -372.889272)
		(width 0.14732)
		(layer "In6.Cu")
		(net "UPI_CPU0_CPU1_P2P2_DN<15>")
	)
	(segment
		(start 340.519766 -288.103056)
		(end 340.519766 -288.121598)
		(width 0.0889)
		(layer "In6.Cu")
		(net "UPI_CPU0_CPU1_P2P2_DN<15>")
	)
	(segment
		(start 72.935084 -363.017562)
		(end 68.944998 -353.384104)
		(width 0.14732)
		(layer "In6.Cu")
		(net "UPI_CPU0_CPU1_P2P2_DN<15>")
	)
	(segment
		(start 237.3249 -371.314726)
		(end 237.154466 -371.195092)
		(width 0.14732)
		(layer "In6.Cu")
		(net "UPI_CPU0_CPU1_P2P2_DN<15>")
	)
	(segment
		(start 341.167974 -285.980632)
		(end 341.176864 -285.985712)
		(width 0.0889)
		(layer "In6.Cu")
		(net "UPI_CPU0_CPU1_P2P2_DN<15>")
	)
	(segment
		(start 306.509166 -328.09307)
		(end 305.928014 -328.922634)
		(width 0.14732)
		(layer "In6.Cu")
		(net "UPI_CPU0_CPU1_P2P2_DN<15>")
	)
	(segment
		(start 68.944998 -353.384104)
		(end 68.944998 -334.922622)
		(width 0.14732)
		(layer "In6.Cu")
		(net "UPI_CPU0_CPU1_P2P2_DN<15>")
	)
	(segment
		(start 102.538784 -278.661368)
		(end 102.539546 -278.66086)
		(width 0.0889)
		(layer "In6.Cu")
		(net "UPI_CPU0_CPU1_P2P2_DN<15>")
	)
	(segment
		(start 236.454442 -371.46865)
		(end 236.590078 -372.235984)
		(width 0.14732)
		(layer "In6.Cu")
		(net "UPI_CPU0_CPU1_P2P2_DN<15>")
	)
	(segment
		(start 237.817152 -372.331488)
		(end 237.46079 -372.08206)
		(width 0.14732)
		(layer "In6.Cu")
		(net "UPI_CPU0_CPU1_P2P2_DN<15>")
	)
	(segment
		(start 102.256844 -282.413456)
		(end 102.256844 -282.405836)
		(width 0.0889)
		(layer "In6.Cu")
		(net "UPI_CPU0_CPU1_P2P2_DN<15>")
	)
	(segment
		(start 341.18296 -285.33344)
		(end 341.177626 -285.336488)
		(width 0.0889)
		(layer "In6.Cu")
		(net "UPI_CPU0_CPU1_P2P2_DN<15>")
	)
	(segment
		(start 100.659946 -288.427414)
		(end 100.660708 -288.426906)
		(width 0.0889)
		(layer "In6.Cu")
		(net "UPI_CPU0_CPU1_P2P2_DN<15>")
	)
	(segment
		(start 340.894162 -283.219906)
		(end 341.206836 -283.219906)
		(width 0.0889)
		(layer "In6.Cu")
		(net "UPI_CPU0_CPU1_P2P2_DN<15>")
	)
	(segment
		(start 104.419146 -277.032974)
		(end 104.42067 -277.032212)
		(width 0.0889)
		(layer "In6.Cu")
		(net "UPI_CPU0_CPU1_P2P2_DN<15>")
	)
	(segment
		(start 341.459566 -286.4612)
		(end 341.459566 -286.475424)
		(width 0.0889)
		(layer "In6.Cu")
		(net "UPI_CPU0_CPU1_P2P2_DN<15>")
	)
	(segment
		(start 101.317044 -285.675578)
		(end 101.317044 -285.661354)
		(width 0.0889)
		(layer "In6.Cu")
		(net "UPI_CPU0_CPU1_P2P2_DN<15>")
	)
	(segment
		(start 99.865434 -290.407344)
		(end 99.907344 -290.365434)
		(width 0.0889)
		(layer "In6.Cu")
		(net "UPI_CPU0_CPU1_P2P2_DN<15>")
	)
	(segment
		(start 70.06844 -326.66559)
		(end 71.94169 -322.704714)
		(width 0.14732)
		(layer "In6.Cu")
		(net "UPI_CPU0_CPU1_P2P2_DN<15>")
	)
	(segment
		(start 267.23213 -365.962184)
		(end 263.465564 -369.72875)
		(width 0.14732)
		(layer "In6.Cu")
		(net "UPI_CPU0_CPU1_P2P2_DN<15>")
	)
	(segment
		(start 307.19268 -325.915782)
		(end 306.792122 -326.488044)
		(width 0.14732)
		(layer "In6.Cu")
		(net "UPI_CPU0_CPU1_P2P2_DN<15>")
	)
	(segment
		(start 79.889096 -314.757054)
		(end 95.277178 -302.128682)
		(width 0.14732)
		(layer "In6.Cu")
		(net "UPI_CPU0_CPU1_P2P2_DN<15>")
	)
	(segment
		(start 98.165412 -296.394124)
		(end 98.165412 -292.588188)
		(width 0.14732)
		(layer "In6.Cu")
		(net "UPI_CPU0_CPU1_P2P2_DN<15>")
	)
	(segment
		(start 77.53858 -367.621312)
		(end 72.935084 -363.017562)
		(width 0.14732)
		(layer "In6.Cu")
		(net "UPI_CPU0_CPU1_P2P2_DN<15>")
	)
	(segment
		(start 232.761028 -372.121938)
		(end 232.590594 -372.002304)
		(width 0.14732)
		(layer "In6.Cu")
		(net "UPI_CPU0_CPU1_P2P2_DN<15>")
	)
	(segment
		(start 340.234016 -289.277806)
		(end 340.233762 -289.27806)
		(width 0.0889)
		(layer "In6.Cu")
		(net "UPI_CPU0_CPU1_P2P2_DN<15>")
	)
	(segment
		(start 99.907344 -290.365434)
		(end 99.907344 -289.609784)
		(width 0.0889)
		(layer "In6.Cu")
		(net "UPI_CPU0_CPU1_P2P2_DN<15>")
	)
	(segment
		(start 101.599746 -285.171896)
		(end 101.60127 -285.171134)
		(width 0.0889)
		(layer "In6.Cu")
		(net "UPI_CPU0_CPU1_P2P2_DN<15>")
	)
	(segment
		(start 237.154466 -371.195092)
		(end 236.574076 -371.297962)
		(width 0.14732)
		(layer "In6.Cu")
		(net "UPI_CPU0_CPU1_P2P2_DN<15>")
	)
	(segment
		(start 101.787198 -284.847538)
		(end 101.787198 -284.832044)
		(width 0.0889)
		(layer "In6.Cu")
		(net "UPI_CPU0_CPU1_P2P2_DN<15>")
	)
	(segment
		(start 339.167216 -291.573204)
		(end 336.73669 -294.002714)
		(width 0.14732)
		(layer "In6.Cu")
		(net "UPI_CPU0_CPU1_P2P2_DN<15>")
	)
	(segment
		(start 342.399112 -283.197808)
		(end 342.399112 -283.229812)
		(width 0.0889)
		(layer "In6.Cu")
		(net "UPI_CPU0_CPU1_P2P2_DN<15>")
	)
	(segment
		(start 305.928014 -328.922634)
		(end 303.954688 -330.89596)
		(width 0.14732)
		(layer "In6.Cu")
		(net "UPI_CPU0_CPU1_P2P2_DN<15>")
	)
	(segment
		(start 102.527354 -281.92349)
		(end 102.539546 -281.916378)
		(width 0.0889)
		(layer "In6.Cu")
		(net "UPI_CPU0_CPU1_P2P2_DN<15>")
	)
	(segment
		(start 103.559864 -277.838154)
		(end 103.574596 -277.84679)
		(width 0.0889)
		(layer "In6.Cu")
		(net "UPI_CPU0_CPU1_P2P2_DN<15>")
	)
	(segment
		(start 104.42067 -277.032212)
		(end 104.428036 -277.027894)
		(width 0.0889)
		(layer "In6.Cu")
		(net "UPI_CPU0_CPU1_P2P2_DN<15>")
	)
	(segment
		(start 267.23213 -344.493596)
		(end 267.23213 -365.962184)
		(width 0.14732)
		(layer "In6.Cu")
		(net "UPI_CPU0_CPU1_P2P2_DN<15>")
	)
	(segment
		(start 102.726744 -281.600656)
		(end 102.726744 -281.583384)
		(width 0.0889)
		(layer "In6.Cu")
		(net "UPI_CPU0_CPU1_P2P2_DN<15>")
	)
	(segment
		(start 341.929212 -284.033722)
		(end 341.929212 -284.049216)
		(width 0.0889)
		(layer "In6.Cu")
		(net "UPI_CPU0_CPU1_P2P2_DN<15>")
	)
	(segment
		(start 99.865434 -290.429442)
		(end 99.865434 -290.407344)
		(width 0.0889)
		(layer "In6.Cu")
		(net "UPI_CPU0_CPU1_P2P2_DN<15>")
	)
	(segment
		(start 102.538784 -283.544772)
		(end 102.539546 -283.544264)
		(width 0.0889)
		(layer "In6.Cu")
		(net "UPI_CPU0_CPU1_P2P2_DN<15>")
	)
	(segment
		(start 102.069392 -284.35808)
		(end 102.078282 -284.353)
		(width 0.0889)
		(layer "In6.Cu")
		(net "UPI_CPU0_CPU1_P2P2_DN<15>")
	)
	(segment
		(start 235.535216 -372.735094)
		(end 235.178854 -372.485666)
		(width 0.14732)
		(layer "In6.Cu")
		(net "UPI_CPU0_CPU1_P2P2_DN<15>")
	)
	(segment
		(start 199.037448 -373.2276)
		(end 159.435546 -380.20879)
		(width 0.14732)
		(layer "In6.Cu")
		(net "UPI_CPU0_CPU1_P2P2_DN<15>")
	)
	(segment
		(start 306.792122 -326.488044)
		(end 306.509166 -328.09307)
		(width 0.14732)
		(layer "In6.Cu")
		(net "UPI_CPU0_CPU1_P2P2_DN<15>")
	)
	(segment
		(start 212.36559 -375.577862)
		(end 199.037448 -373.2276)
		(width 0.14732)
		(layer "In6.Cu")
		(net "UPI_CPU0_CPU1_P2P2_DN<15>")
	)
	(segment
		(start 314.453016 -321.04838)
		(end 309.38978 -324.113144)
		(width 0.14732)
		(layer "In6.Cu")
		(net "UPI_CPU0_CPU1_P2P2_DN<15>")
	)
	(segment
		(start 98.006916 -376.09907)
		(end 77.53858 -367.621312)
		(width 0.14732)
		(layer "In6.Cu")
		(net "UPI_CPU0_CPU1_P2P2_DN<15>")
	)
	(segment
		(start 101.786944 -286.48406)
		(end 101.786944 -286.466788)
		(width 0.0889)
		(layer "In6.Cu")
		(net "UPI_CPU0_CPU1_P2P2_DN<15>")
	)
	(segment
		(start 102.726744 -279.97277)
		(end 102.726744 -279.955498)
		(width 0.0889)
		(layer "In6.Cu")
		(net "UPI_CPU0_CPU1_P2P2_DN<15>")
	)
	(segment
		(start 339.18271 -291.497766)
		(end 339.18271 -291.55771)
		(width 0.0889)
		(layer "In6.Cu")
		(net "UPI_CPU0_CPU1_P2P2_DN<15>")
	)
	(segment
		(start 237.46079 -372.08206)
		(end 237.3249 -371.314726)
		(width 0.14732)
		(layer "In6.Cu")
		(net "UPI_CPU0_CPU1_P2P2_DN<15>")
	)
	(segment
		(start 102.539546 -278.66086)
		(end 102.54107 -278.660098)
		(width 0.0889)
		(layer "In6.Cu")
		(net "UPI_CPU0_CPU1_P2P2_DN<15>")
	)
	(segment
		(start 101.59365 -285.175452)
		(end 101.598984 -285.172404)
		(width 0.0889)
		(layer "In6.Cu")
		(net "UPI_CPU0_CPU1_P2P2_DN<15>")
	)
	(segment
		(start 104.41305 -277.03653)
		(end 104.418384 -277.033482)
		(width 0.0889)
		(layer "In6.Cu")
		(net "UPI_CPU0_CPU1_P2P2_DN<15>")
	)
	(segment
		(start 340.989666 -287.280604)
		(end 340.989666 -287.299146)
		(width 0.0889)
		(layer "In6.Cu")
		(net "UPI_CPU0_CPU1_P2P2_DN<15>")
	)
	(segment
		(start 340.519258 -290.161218)
		(end 339.18271 -291.497766)
		(width 0.0889)
		(layer "In6.Cu")
		(net "UPI_CPU0_CPU1_P2P2_DN<15>")
	)
	(segment
		(start 96.438466 -300.563026)
		(end 98.165412 -296.394124)
		(width 0.14732)
		(layer "In6.Cu")
		(net "UPI_CPU0_CPU1_P2P2_DN<15>")
	)
	(segment
		(start 102.539546 -279.639776)
		(end 102.538784 -279.639268)
		(width 0.0889)
		(layer "In6.Cu")
		(net "UPI_CPU0_CPU1_P2P2_DN<15>")
	)
	(segment
		(start 235.178854 -372.485666)
		(end 235.042964 -371.718332)
		(width 0.14732)
		(layer "In6.Cu")
		(net "UPI_CPU0_CPU1_P2P2_DN<15>")
	)
	(segment
		(start 102.726998 -278.336502)
		(end 102.726998 -278.314404)
		(width 0.0889)
		(layer "In6.Cu")
		(net "UPI_CPU0_CPU1_P2P2_DN<15>")
	)
	(segment
		(start 238.872014 -371.832378)
		(end 238.622586 -372.188994)
		(width 0.14732)
		(layer "In6.Cu")
		(net "UPI_CPU0_CPU1_P2P2_DN<15>")
	)
	(segment
		(start 234.29214 -371.701568)
		(end 234.172506 -371.872256)
		(width 0.14732)
		(layer "In6.Cu")
		(net "UPI_CPU0_CPU1_P2P2_DN<15>")
	)
	(segment
		(start 104.602026 -276.76602)
		(end 104.544622 -276.708616)
		(width 0.0889)
		(layer "In6.Cu")
		(net "UPI_CPU0_CPU1_P2P2_DN<15>")
	)
	(segment
		(start 248.577862 -372.354094)
		(end 239.575848 -370.767102)
		(width 0.14732)
		(layer "In6.Cu")
		(net "UPI_CPU0_CPU1_P2P2_DN<15>")
	)
	(segment
		(start 238.736378 -371.065044)
		(end 238.872014 -371.832378)
		(width 0.14732)
		(layer "In6.Cu")
		(net "UPI_CPU0_CPU1_P2P2_DN<15>")
	)
	(segment
		(start 232.896918 -372.889272)
		(end 232.761028 -372.121938)
		(width 0.14732)
		(layer "In6.Cu")
		(net "UPI_CPU0_CPU1_P2P2_DN<15>")
	)
	(segment
		(start 232.590594 -372.002304)
		(end 212.36559 -375.577862)
		(width 0.14732)
		(layer "In6.Cu")
		(net "UPI_CPU0_CPU1_P2P2_DN<15>")
	)
	(segment
		(start 68.944998 -334.922622)
		(end 69.586348 -328.408538)
		(width 0.14732)
		(layer "In6.Cu")
		(net "UPI_CPU0_CPU1_P2P2_DN<15>")
	)
	(segment
		(start 341.206836 -283.219906)
		(end 341.272368 -283.154374)
		(width 0.0889)
		(layer "In6.Cu")
		(net "UPI_CPU0_CPU1_P2P2_DN<15>")
	)
	(segment
		(start 100.660708 -288.426906)
		(end 100.668836 -288.422334)
		(width 0.0889)
		(layer "In6.Cu")
		(net "UPI_CPU0_CPU1_P2P2_DN<15>")
	)
	(segment
		(start 100.377498 -289.077908)
		(end 100.377498 -288.898584)
		(width 0.0889)
		(layer "In6.Cu")
		(net "UPI_CPU0_CPU1_P2P2_DN<15>")
	)
	(segment
		(start 263.465564 -369.72875)
		(end 248.577862 -372.354094)
		(width 0.14732)
		(layer "In6.Cu")
		(net "UPI_CPU0_CPU1_P2P2_DN<15>")
	)
	(segment
		(start 238.856012 -370.89461)
		(end 238.736378 -371.065044)
		(width 0.14732)
		(layer "In6.Cu")
		(net "UPI_CPU0_CPU1_P2P2_DN<15>")
	)
	(segment
		(start 125.709934 -380.20879)
		(end 98.006916 -376.09907)
		(width 0.14732)
		(layer "In6.Cu")
		(net "UPI_CPU0_CPU1_P2P2_DN<15>")
	)
	(segment
		(start 236.574076 -371.297962)
		(end 236.454442 -371.46865)
		(width 0.14732)
		(layer "In6.Cu")
		(net "UPI_CPU0_CPU1_P2P2_DN<15>")
	)
	(segment
		(start 100.847398 -288.103056)
		(end 100.847398 -288.087562)
		(width 0.0889)
		(layer "In6.Cu")
		(net "UPI_CPU0_CPU1_P2P2_DN<15>")
	)
	(segment
		(start 239.575848 -370.767102)
		(end 238.856012 -370.89461)
		(width 0.14732)
		(layer "In6.Cu")
		(net "UPI_CPU0_CPU1_P2P2_DN<15>")
	)
	(segment
		(start 71.94169 -322.704714)
		(end 79.889096 -314.757054)
		(width 0.14732)
		(layer "In6.Cu")
		(net "UPI_CPU0_CPU1_P2P2_DN<15>")
	)
	(segment
		(start 341.647018 -284.52318)
		(end 341.638128 -284.52826)
		(width 0.0889)
		(layer "In6.Cu")
		(net "UPI_CPU0_CPU1_P2P2_DN<15>")
	)
	(segment
		(start 104.418384 -277.033482)
		(end 104.419146 -277.032974)
		(width 0.0889)
		(layer "In6.Cu")
		(net "UPI_CPU0_CPU1_P2P2_DN<15>")
	)
	(segment
		(start 341.176864 -285.336996)
		(end 341.170006 -285.340806)
		(width 0.0889)
		(layer "In6.Cu")
		(net "UPI_CPU0_CPU1_P2P2_DN<15>")
	)
	(segment
		(start 341.18296 -286.961326)
		(end 341.177626 -286.964374)
		(width 0.0889)
		(layer "In6.Cu")
		(net "UPI_CPU0_CPU1_P2P2_DN<15>")
	)
	(segment
		(start 309.38978 -324.113144)
		(end 308.524656 -324.982332)
		(width 0.14732)
		(layer "In6.Cu")
		(net "UPI_CPU0_CPU1_P2P2_DN<15>")
	)
	(segment
		(start 341.177626 -286.964374)
		(end 341.176864 -286.964882)
		(width 0.0889)
		(layer "In6.Cu")
		(net "UPI_CPU0_CPU1_P2P2_DN<15>")
	)
	(segment
		(start 101.598984 -286.80029)
		(end 101.599746 -286.799782)
		(width 0.0889)
		(layer "In6.Cu")
		(net "UPI_CPU0_CPU1_P2P2_DN<15>")
	)
	(segment
		(start 101.129592 -287.613598)
		(end 101.138482 -287.608518)
		(width 0.0889)
		(layer "In6.Cu")
		(net "UPI_CPU0_CPU1_P2P2_DN<15>")
	)
	(segment
		(start 335.354676 -296.027856)
		(end 333.560674 -301.940976)
		(width 0.14732)
		(layer "In6.Cu")
		(net "UPI_CPU0_CPU1_P2P2_DN<15>")
	)
	(segment
		(start 101.60127 -285.171134)
		(end 101.608636 -285.166816)
		(width 0.0889)
		(layer "In6.Cu")
		(net "UPI_CPU0_CPU1_P2P2_DN<15>")
	)
	(segment
		(start 101.598984 -285.172404)
		(end 101.599746 -285.171896)
		(width 0.0889)
		(layer "In6.Cu")
		(net "UPI_CPU0_CPU1_P2P2_DN<15>")
	)
	(segment
		(start 336.154268 -294.831262)
		(end 335.354676 -296.027856)
		(width 0.14732)
		(layer "In6.Cu")
		(net "UPI_CPU0_CPU1_P2P2_DN<15>")
	)
	(segment
		(start 104.544622 -276.708616)
		(end 104.231948 -276.708616)
		(width 0.0889)
		(layer "In6.Cu")
		(net "UPI_CPU0_CPU1_P2P2_DN<15>")
	)
	(segment
		(start 236.34065 -372.5926)
		(end 235.535216 -372.735094)
		(width 0.14732)
		(layer "In6.Cu")
		(net "UPI_CPU0_CPU1_P2P2_DN<15>")
	)
	(segment
		(start 234.058714 -372.996206)
		(end 233.25328 -373.1387)
		(width 0.14732)
		(layer "In6.Cu")
		(net "UPI_CPU0_CPU1_P2P2_DN<15>")
	)
	(segment
		(start 69.586348 -328.408538)
		(end 70.06844 -326.66559)
		(width 0.14732)
		(layer "In6.Cu")
		(net "UPI_CPU0_CPU1_P2P2_DN<15>")
	)
	(segment
		(start 101.59365 -286.803338)
		(end 101.598984 -286.80029)
		(width 0.0889)
		(layer "In6.Cu")
		(net "UPI_CPU0_CPU1_P2P2_DN<15>")
	)
	(segment
		(start 99.865434 -290.654994)
		(end 99.865434 -290.429442)
		(width 0.14732)
		(layer "In6.Cu")
		(net "UPI_CPU0_CPU1_P2P2_DN<15>")
	)
	(segment
		(start 342.116664 -283.709364)
		(end 342.107774 -283.714444)
		(width 0.0889)
		(layer "In6.Cu")
		(net "UPI_CPU0_CPU1_P2P2_DN<15>")
	)
	(segment
		(start 341.177626 -285.336488)
		(end 341.176864 -285.336996)
		(width 0.0889)
		(layer "In6.Cu")
		(net "UPI_CPU0_CPU1_P2P2_DN<15>")
	)
	(arc
		(start 102.539546 -283.544264)
		(mid 102.674479 -283.41091)
		(end 102.726744 -283.228542)
		(width 0.0889)
		(layer "In6.Cu")
		(net "UPI_CPU0_CPU1_P2P2_DN<15>")
	)
	(arc
		(start 341.566246 -282.721558)
		(mid 341.842687 -282.654392)
		(end 342.116918 -282.730194)
		(width 0.0889)
		(layer "In6.Cu")
		(net "UPI_CPU0_CPU1_P2P2_DN<15>")
	)
	(arc
		(start 340.049866 -289.078416)
		(mid 340.124871 -289.193875)
		(end 340.234016 -289.277806)
		(width 0.0889)
		(layer "In6.Cu")
		(net "UPI_CPU0_CPU1_P2P2_DN<15>")
	)
	(arc
		(start 99.907344 -289.609784)
		(mid 99.9145 -289.590223)
		(end 99.92233 -289.570922)
		(width 0.0889)
		(layer "In6.Cu")
		(net "UPI_CPU0_CPU1_P2P2_DN<15>")
	)
	(arc
		(start 101.599746 -286.799782)
		(mid 101.734679 -286.666428)
		(end 101.786944 -286.48406)
		(width 0.0889)
		(layer "In6.Cu")
		(net "UPI_CPU0_CPU1_P2P2_DN<15>")
	)
	(arc
		(start 102.539546 -281.916378)
		(mid 102.674479 -281.783024)
		(end 102.726744 -281.600656)
		(width 0.0889)
		(layer "In6.Cu")
		(net "UPI_CPU0_CPU1_P2P2_DN<15>")
	)
	(arc
		(start 101.317044 -285.661354)
		(mid 101.391035 -285.381788)
		(end 101.59365 -285.175452)
		(width 0.0889)
		(layer "In6.Cu")
		(net "UPI_CPU0_CPU1_P2P2_DN<15>")
	)
	(arc
		(start 102.548436 -278.65578)
		(mid 102.67935 -278.51942)
		(end 102.726998 -278.336502)
		(width 0.0889)
		(layer "In6.Cu")
		(net "UPI_CPU0_CPU1_P2P2_DN<15>")
	)
	(arc
		(start 99.92233 -289.570922)
		(mid 100.032587 -289.401162)
		(end 100.193094 -289.277806)
		(width 0.0889)
		(layer "In6.Cu")
		(net "UPI_CPU0_CPU1_P2P2_DN<15>")
	)
	(arc
		(start 104.428036 -277.027894)
		(mid 104.543775 -276.91607)
		(end 104.602026 -276.76602)
		(width 0.0889)
		(layer "In6.Cu")
		(net "UPI_CPU0_CPU1_P2P2_DN<15>")
	)
	(arc
		(start 342.107774 -283.714444)
		(mid 341.97686 -283.850804)
		(end 341.929212 -284.033722)
		(width 0.0889)
		(layer "In6.Cu")
		(net "UPI_CPU0_CPU1_P2P2_DN<15>")
	)
	(arc
		(start 100.377498 -288.898584)
		(mid 100.45766 -288.626395)
		(end 100.659946 -288.427414)
		(width 0.0889)
		(layer "In6.Cu")
		(net "UPI_CPU0_CPU1_P2P2_DN<15>")
	)
	(arc
		(start 101.787198 -284.832044)
		(mid 101.866568 -284.55831)
		(end 102.069392 -284.35808)
		(width 0.0889)
		(layer "In6.Cu")
		(net "UPI_CPU0_CPU1_P2P2_DN<15>")
	)
	(arc
		(start 342.399112 -283.229812)
		(mid 342.321001 -283.506761)
		(end 342.116664 -283.709364)
		(width 0.0889)
		(layer "In6.Cu")
		(net "UPI_CPU0_CPU1_P2P2_DN<15>")
	)
	(arc
		(start 100.193094 -289.277806)
		(mid 100.30249 -289.193709)
		(end 100.377498 -289.077908)
		(width 0.0889)
		(layer "In6.Cu")
		(net "UPI_CPU0_CPU1_P2P2_DN<15>")
	)
	(arc
		(start 102.256844 -284.033722)
		(mid 102.330835 -283.754156)
		(end 102.53345 -283.54782)
		(width 0.0889)
		(layer "In6.Cu")
		(net "UPI_CPU0_CPU1_P2P2_DN<15>")
	)
	(arc
		(start 101.138482 -287.608518)
		(mid 101.269396 -287.472158)
		(end 101.317044 -287.28924)
		(width 0.0889)
		(layer "In6.Cu")
		(net "UPI_CPU0_CPU1_P2P2_DN<15>")
	)
	(arc
		(start 341.176864 -285.985712)
		(mid 341.380345 -286.186516)
		(end 341.459566 -286.4612)
		(width 0.0889)
		(layer "In6.Cu")
		(net "UPI_CPU0_CPU1_P2P2_DN<15>")
	)
	(arc
		(start 341.459566 -284.847538)
		(mid 341.385575 -285.127104)
		(end 341.18296 -285.33344)
		(width 0.0889)
		(layer "In6.Cu")
		(net "UPI_CPU0_CPU1_P2P2_DN<15>")
	)
	(arc
		(start 341.929212 -284.049216)
		(mid 341.849842 -284.32295)
		(end 341.647018 -284.52318)
		(width 0.0889)
		(layer "In6.Cu")
		(net "UPI_CPU0_CPU1_P2P2_DN<15>")
	)
	(arc
		(start 102.256844 -280.770584)
		(mid 102.334473 -280.492171)
		(end 102.539546 -280.288492)
		(width 0.0889)
		(layer "In6.Cu")
		(net "UPI_CPU0_CPU1_P2P2_DN<15>")
	)
	(arc
		(start 341.275162 -283.133292)
		(mid 341.367509 -282.900321)
		(end 341.551514 -282.730194)
		(width 0.0889)
		(layer "In6.Cu")
		(net "UPI_CPU0_CPU1_P2P2_DN<15>")
	)
	(arc
		(start 103.957882 -277.84171)
		(mid 104.085136 -277.711744)
		(end 104.13619 -277.537164)
		(width 0.0889)
		(layer "In6.Cu")
		(net "UPI_CPU0_CPU1_P2P2_DN<15>")
	)
	(arc
		(start 103.574596 -277.84679)
		(mid 103.761794 -277.896933)
		(end 103.948992 -277.84679)
		(width 0.0889)
		(layer "In6.Cu")
		(net "UPI_CPU0_CPU1_P2P2_DN<15>")
	)
	(arc
		(start 102.539546 -282.895548)
		(mid 102.334474 -282.691869)
		(end 102.256844 -282.413456)
		(width 0.0889)
		(layer "In6.Cu")
		(net "UPI_CPU0_CPU1_P2P2_DN<15>")
	)
	(arc
		(start 102.726744 -281.583384)
		(mid 102.674474 -281.401019)
		(end 102.539546 -281.267662)
		(width 0.0889)
		(layer "In6.Cu")
		(net "UPI_CPU0_CPU1_P2P2_DN<15>")
	)
	(arc
		(start 102.726744 -283.21127)
		(mid 102.674474 -283.028905)
		(end 102.539546 -282.895548)
		(width 0.0889)
		(layer "In6.Cu")
		(net "UPI_CPU0_CPU1_P2P2_DN<15>")
	)
	(arc
		(start 101.786944 -286.466788)
		(mid 101.734674 -286.284423)
		(end 101.599746 -286.151066)
		(width 0.0889)
		(layer "In6.Cu")
		(net "UPI_CPU0_CPU1_P2P2_DN<15>")
	)
	(arc
		(start 104.136444 -277.522432)
		(mid 104.210435 -277.242866)
		(end 104.41305 -277.03653)
		(width 0.0889)
		(layer "In6.Cu")
		(net "UPI_CPU0_CPU1_P2P2_DN<15>")
	)
	(arc
		(start 102.256844 -282.405836)
		(mid 102.329079 -282.129312)
		(end 102.527354 -281.92349)
		(width 0.0889)
		(layer "In6.Cu")
		(net "UPI_CPU0_CPU1_P2P2_DN<15>")
	)
	(arc
		(start 101.608636 -285.166816)
		(mid 101.73955 -285.030456)
		(end 101.787198 -284.847538)
		(width 0.0889)
		(layer "In6.Cu")
		(net "UPI_CPU0_CPU1_P2P2_DN<15>")
	)
	(arc
		(start 101.317044 -287.28924)
		(mid 101.391035 -287.009674)
		(end 101.59365 -286.803338)
		(width 0.0889)
		(layer "In6.Cu")
		(net "UPI_CPU0_CPU1_P2P2_DN<15>")
	)
	(arc
		(start 340.233762 -289.27806)
		(mid 340.408007 -289.417106)
		(end 340.519258 -289.610292)
		(width 0.0889)
		(layer "In6.Cu")
		(net "UPI_CPU0_CPU1_P2P2_DN<15>")
	)
	(arc
		(start 102.078282 -284.353)
		(mid 102.209196 -284.21664)
		(end 102.256844 -284.033722)
		(width 0.0889)
		(layer "In6.Cu")
		(net "UPI_CPU0_CPU1_P2P2_DN<15>")
	)
	(arc
		(start 104.13619 -277.537164)
		(mid 104.136387 -277.529799)
		(end 104.136444 -277.522432)
		(width 0.0889)
		(layer "In6.Cu")
		(net "UPI_CPU0_CPU1_P2P2_DN<15>")
	)
	(arc
		(start 102.53345 -279.63622)
		(mid 102.256876 -279.150318)
		(end 102.53345 -278.664416)
		(width 0.0889)
		(layer "In6.Cu")
		(net "UPI_CPU0_CPU1_P2P2_DN<15>")
	)
	(arc
		(start 100.668836 -288.422334)
		(mid 100.79975 -288.285974)
		(end 100.847398 -288.103056)
		(width 0.0889)
		(layer "In6.Cu")
		(net "UPI_CPU0_CPU1_P2P2_DN<15>")
	)
	(arc
		(start 340.519766 -288.121598)
		(mid 340.439604 -288.393787)
		(end 340.237318 -288.592768)
		(width 0.0889)
		(layer "In6.Cu")
		(net "UPI_CPU0_CPU1_P2P2_DN<15>")
	)
	(arc
		(start 100.847398 -288.087562)
		(mid 100.926768 -287.813828)
		(end 101.129592 -287.613598)
		(width 0.0889)
		(layer "In6.Cu")
		(net "UPI_CPU0_CPU1_P2P2_DN<15>")
	)
	(arc
		(start 102.726998 -278.314404)
		(mid 102.807909 -278.044276)
		(end 103.009192 -277.84679)
		(width 0.0889)
		(layer "In6.Cu")
		(net "UPI_CPU0_CPU1_P2P2_DN<15>")
	)
	(arc
		(start 341.176864 -286.964882)
		(mid 341.041931 -287.098236)
		(end 340.989666 -287.280604)
		(width 0.0889)
		(layer "In6.Cu")
		(net "UPI_CPU0_CPU1_P2P2_DN<15>")
	)
	(arc
		(start 342.116918 -282.730194)
		(mid 342.3182 -282.927681)
		(end 342.399112 -283.197808)
		(width 0.0889)
		(layer "In6.Cu")
		(net "UPI_CPU0_CPU1_P2P2_DN<15>")
	)
	(arc
		(start 340.989666 -287.299146)
		(mid 340.911555 -287.576095)
		(end 340.707218 -287.778698)
		(width 0.0889)
		(layer "In6.Cu")
		(net "UPI_CPU0_CPU1_P2P2_DN<15>")
	)
	(arc
		(start 341.272368 -283.154374)
		(mid 341.273666 -283.14382)
		(end 341.275162 -283.133292)
		(width 0.0889)
		(layer "In6.Cu")
		(net "UPI_CPU0_CPU1_P2P2_DN<15>")
	)
	(arc
		(start 340.228428 -288.597848)
		(mid 340.097514 -288.734208)
		(end 340.049866 -288.917126)
		(width 0.0889)
		(layer "In6.Cu")
		(net "UPI_CPU0_CPU1_P2P2_DN<15>")
	)
	(arc
		(start 341.638128 -284.52826)
		(mid 341.507214 -284.66462)
		(end 341.459566 -284.847538)
		(width 0.0889)
		(layer "In6.Cu")
		(net "UPI_CPU0_CPU1_P2P2_DN<15>")
	)
	(arc
		(start 102.726744 -279.955498)
		(mid 102.674474 -279.773133)
		(end 102.539546 -279.639776)
		(width 0.0889)
		(layer "In6.Cu")
		(net "UPI_CPU0_CPU1_P2P2_DN<15>")
	)
	(arc
		(start 103.009192 -277.84679)
		(mid 103.283421 -277.770865)
		(end 103.559864 -277.838154)
		(width 0.0889)
		(layer "In6.Cu")
		(net "UPI_CPU0_CPU1_P2P2_DN<15>")
	)
	(arc
		(start 341.167974 -285.342076)
		(mid 340.989377 -285.661354)
		(end 341.167974 -285.980632)
		(width 0.0889)
		(layer "In6.Cu")
		(net "UPI_CPU0_CPU1_P2P2_DN<15>")
	)
	(arc
		(start 101.599746 -286.151066)
		(mid 101.396265 -285.950262)
		(end 101.317044 -285.675578)
		(width 0.0889)
		(layer "In6.Cu")
		(net "UPI_CPU0_CPU1_P2P2_DN<15>")
	)
	(arc
		(start 102.527354 -281.26055)
		(mid 102.329126 -281.054702)
		(end 102.256844 -280.778204)
		(width 0.0889)
		(layer "In6.Cu")
		(net "UPI_CPU0_CPU1_P2P2_DN<15>")
	)
	(arc
		(start 340.698328 -287.783778)
		(mid 340.567414 -287.920138)
		(end 340.519766 -288.103056)
		(width 0.0889)
		(layer "In6.Cu")
		(net "UPI_CPU0_CPU1_P2P2_DN<15>")
	)
	(arc
		(start 341.459566 -286.475424)
		(mid 341.385575 -286.75499)
		(end 341.18296 -286.961326)
		(width 0.0889)
		(layer "In6.Cu")
		(net "UPI_CPU0_CPU1_P2P2_DN<15>")
	)
	(arc
		(start 102.539546 -280.288492)
		(mid 102.674479 -280.155138)
		(end 102.726744 -279.97277)
		(width 0.0889)
		(layer "In6.Cu")
		(net "UPI_CPU0_CPU1_P2P2_DN<15>")
	)
	(segment
		(start 341.833962 -281.05608)
		(end 341.833962 -281.59202)
		(width 0.13208)
		(layer "F.Cu")
		(net "UPI_CPU0_CPU1_P2P2_DN<14>")
	)
	(segment
		(start 103.291894 -276.708362)
		(end 103.292148 -276.708616)
		(width 0.13208)
		(layer "F.Cu")
		(net "UPI_CPU0_CPU1_P2P2_DN<14>")
	)
	(segment
		(start 103.291894 -276.172676)
		(end 103.291894 -276.708362)
		(width 0.13208)
		(layer "F.Cu")
		(net "UPI_CPU0_CPU1_P2P2_DN<14>")
	)
	(segment
		(start 313.024012 -323.005704)
		(end 311.03951 -324.40118)
		(width 0.14732)
		(layer "In6.Cu")
		(net "UPI_CPU0_CPU1_P2P2_DN<14>")
	)
	(segment
		(start 101.138482 -282.086558)
		(end 101.129592 -282.081478)
		(width 0.0889)
		(layer "In6.Cu")
		(net "UPI_CPU0_CPU1_P2P2_DN<14>")
	)
	(segment
		(start 99.437444 -285.675578)
		(end 99.437444 -285.661354)
		(width 0.0889)
		(layer "In6.Cu")
		(net "UPI_CPU0_CPU1_P2P2_DN<14>")
	)
	(segment
		(start 341.647018 -287.778698)
		(end 341.638128 -287.783778)
		(width 0.0889)
		(layer "In6.Cu")
		(net "UPI_CPU0_CPU1_P2P2_DN<14>")
	)
	(segment
		(start 341.833962 -281.59202)
		(end 341.677498 -281.863038)
		(width 0.0889)
		(layer "In6.Cu")
		(net "UPI_CPU0_CPU1_P2P2_DN<14>")
	)
	(segment
		(start 98.967798 -288.103056)
		(end 98.967798 -288.087562)
		(width 0.0889)
		(layer "In6.Cu")
		(net "UPI_CPU0_CPU1_P2P2_DN<14>")
	)
	(segment
		(start 100.659692 -283.544264)
		(end 100.660454 -283.543756)
		(width 0.0889)
		(layer "In6.Cu")
		(net "UPI_CPU0_CPU1_P2P2_DN<14>")
	)
	(segment
		(start 99.719384 -285.172404)
		(end 99.720146 -285.171896)
		(width 0.0889)
		(layer "In6.Cu")
		(net "UPI_CPU0_CPU1_P2P2_DN<14>")
	)
	(segment
		(start 342.869266 -282.405836)
		(end 342.869266 -282.414472)
		(width 0.0889)
		(layer "In6.Cu")
		(net "UPI_CPU0_CPU1_P2P2_DN<14>")
	)
	(segment
		(start 99.907344 -286.48406)
		(end 99.907344 -286.466788)
		(width 0.0889)
		(layer "In6.Cu")
		(net "UPI_CPU0_CPU1_P2P2_DN<14>")
	)
	(segment
		(start 97.046288 -292.48354)
		(end 98.925634 -290.604194)
		(width 0.14732)
		(layer "In6.Cu")
		(net "UPI_CPU0_CPU1_P2P2_DN<14>")
	)
	(segment
		(start 100.847398 -279.964134)
		(end 100.847398 -279.954228)
		(width 0.0889)
		(layer "In6.Cu")
		(net "UPI_CPU0_CPU1_P2P2_DN<14>")
	)
	(segment
		(start 212.594952 -376.486674)
		(end 198.498714 -374.30837)
		(width 0.14732)
		(layer "In6.Cu")
		(net "UPI_CPU0_CPU1_P2P2_DN<14>")
	)
	(segment
		(start 342.869012 -284.033722)
		(end 342.869012 -284.049216)
		(width 0.0889)
		(layer "In6.Cu")
		(net "UPI_CPU0_CPU1_P2P2_DN<14>")
	)
	(segment
		(start 100.658422 -281.266646)
		(end 100.657152 -281.265884)
		(width 0.0889)
		(layer "In6.Cu")
		(net "UPI_CPU0_CPU1_P2P2_DN<14>")
	)
	(segment
		(start 342.12276 -285.33344)
		(end 342.116664 -285.336996)
		(width 0.0889)
		(layer "In6.Cu")
		(net "UPI_CPU0_CPU1_P2P2_DN<14>")
	)
	(segment
		(start 99.71405 -285.175452)
		(end 99.719384 -285.172404)
		(width 0.0889)
		(layer "In6.Cu")
		(net "UPI_CPU0_CPU1_P2P2_DN<14>")
	)
	(segment
		(start 340.860126 -291.08019)
		(end 339.313266 -292.62705)
		(width 0.0889)
		(layer "In6.Cu")
		(net "UPI_CPU0_CPU1_P2P2_DN<14>")
	)
	(segment
		(start 307.412644 -328.826114)
		(end 306.185316 -330.578714)
		(width 0.14732)
		(layer "In6.Cu")
		(net "UPI_CPU0_CPU1_P2P2_DN<14>")
	)
	(segment
		(start 343.338912 -283.201364)
		(end 343.338912 -283.229812)
		(width 0.0889)
		(layer "In6.Cu")
		(net "UPI_CPU0_CPU1_P2P2_DN<14>")
	)
	(segment
		(start 335.421986 -298.671996)
		(end 335.520284 -298.855384)
		(width 0.14732)
		(layer "In6.Cu")
		(net "UPI_CPU0_CPU1_P2P2_DN<14>")
	)
	(segment
		(start 336.540856 -299.486828)
		(end 336.368898 -300.053502)
		(width 0.14732)
		(layer "In6.Cu")
		(net "UPI_CPU0_CPU1_P2P2_DN<14>")
	)
	(segment
		(start 100.662232 -283.54274)
		(end 100.662994 -283.542232)
		(width 0.0889)
		(layer "In6.Cu")
		(net "UPI_CPU0_CPU1_P2P2_DN<14>")
	)
	(segment
		(start 278.612092 -334.284828)
		(end 268.314932 -344.581988)
		(width 0.14732)
		(layer "In6.Cu")
		(net "UPI_CPU0_CPU1_P2P2_DN<14>")
	)
	(segment
		(start 336.1055 -296.420286)
		(end 335.421986 -298.671996)
		(width 0.14732)
		(layer "In6.Cu")
		(net "UPI_CPU0_CPU1_P2P2_DN<14>")
	)
	(segment
		(start 77.121766 -368.386868)
		(end 71.97725 -363.242352)
		(width 0.14732)
		(layer "In6.Cu")
		(net "UPI_CPU0_CPU1_P2P2_DN<14>")
	)
	(segment
		(start 340.860126 -290.647882)
		(end 340.860126 -291.08019)
		(width 0.0889)
		(layer "In6.Cu")
		(net "UPI_CPU0_CPU1_P2P2_DN<14>")
	)
	(segment
		(start 99.249992 -287.613598)
		(end 99.258882 -287.608518)
		(width 0.0889)
		(layer "In6.Cu")
		(net "UPI_CPU0_CPU1_P2P2_DN<14>")
	)
	(segment
		(start 310.379872 -324.865492)
		(end 310.078628 -324.918832)
		(width 0.14732)
		(layer "In6.Cu")
		(net "UPI_CPU0_CPU1_P2P2_DN<14>")
	)
	(segment
		(start 342.116664 -285.336996)
		(end 342.107774 -285.342076)
		(width 0.0889)
		(layer "In6.Cu")
		(net "UPI_CPU0_CPU1_P2P2_DN<14>")
	)
	(segment
		(start 100.666804 -281.271472)
		(end 100.663502 -281.269694)
		(width 0.0889)
		(layer "In6.Cu")
		(net "UPI_CPU0_CPU1_P2P2_DN<14>")
	)
	(segment
		(start 263.290812 -372.000018)
		(end 212.594952 -376.486674)
		(width 0.14732)
		(layer "In6.Cu")
		(net "UPI_CPU0_CPU1_P2P2_DN<14>")
	)
	(segment
		(start 102.256844 -277.531068)
		(end 102.256844 -277.50389)
		(width 0.0889)
		(layer "In6.Cu")
		(net "UPI_CPU0_CPU1_P2P2_DN<14>")
	)
	(segment
		(start 100.659946 -281.267662)
		(end 100.658422 -281.266646)
		(width 0.0889)
		(layer "In6.Cu")
		(net "UPI_CPU0_CPU1_P2P2_DN<14>")
	)
	(segment
		(start 68.742306 -328.349102)
		(end 69.309488 -326.300084)
		(width 0.14732)
		(layer "In6.Cu")
		(net "UPI_CPU0_CPU1_P2P2_DN<14>")
	)
	(segment
		(start 95.717106 -300.135544)
		(end 97.046288 -296.926254)
		(width 0.14732)
		(layer "In6.Cu")
		(net "UPI_CPU0_CPU1_P2P2_DN<14>")
	)
	(segment
		(start 339.297772 -292.702488)
		(end 339.056472 -292.943788)
		(width 0.14732)
		(layer "In6.Cu")
		(net "UPI_CPU0_CPU1_P2P2_DN<14>")
	)
	(segment
		(start 308.31155 -326.156066)
		(end 307.739542 -326.973438)
		(width 0.14732)
		(layer "In6.Cu")
		(net "UPI_CPU0_CPU1_P2P2_DN<14>")
	)
	(segment
		(start 125.58903 -381.03683)
		(end 97.660714 -376.89409)
		(width 0.14732)
		(layer "In6.Cu")
		(net "UPI_CPU0_CPU1_P2P2_DN<14>")
	)
	(segment
		(start 310.078628 -324.918832)
		(end 308.31155 -326.156066)
		(width 0.14732)
		(layer "In6.Cu")
		(net "UPI_CPU0_CPU1_P2P2_DN<14>")
	)
	(segment
		(start 100.847398 -281.607514)
		(end 100.847398 -281.59202)
		(width 0.0889)
		(layer "In6.Cu")
		(net "UPI_CPU0_CPU1_P2P2_DN<14>")
	)
	(segment
		(start 101.599492 -278.66086)
		(end 101.608382 -278.65578)
		(width 0.0889)
		(layer "In6.Cu")
		(net "UPI_CPU0_CPU1_P2P2_DN<14>")
	)
	(segment
		(start 97.660714 -376.89409)
		(end 77.121766 -368.386868)
		(width 0.14732)
		(layer "In6.Cu")
		(net "UPI_CPU0_CPU1_P2P2_DN<14>")
	)
	(segment
		(start 68.101718 -334.855312)
		(end 68.742306 -328.349102)
		(width 0.14732)
		(layer "In6.Cu")
		(net "UPI_CPU0_CPU1_P2P2_DN<14>")
	)
	(segment
		(start 306.185316 -330.578714)
		(end 305.039776 -331.724)
		(width 0.14732)
		(layer "In6.Cu")
		(net "UPI_CPU0_CPU1_P2P2_DN<14>")
	)
	(segment
		(start 100.189792 -284.35808)
		(end 100.198682 -284.353)
		(width 0.0889)
		(layer "In6.Cu")
		(net "UPI_CPU0_CPU1_P2P2_DN<14>")
	)
	(segment
		(start 338.398104 -293.60114)
		(end 337.171538 -294.827706)
		(width 0.14732)
		(layer "In6.Cu")
		(net "UPI_CPU0_CPU1_P2P2_DN<14>")
	)
	(segment
		(start 68.101718 -353.895914)
		(end 68.101718 -334.855312)
		(width 0.14732)
		(layer "In6.Cu")
		(net "UPI_CPU0_CPU1_P2P2_DN<14>")
	)
	(segment
		(start 341.459312 -290.048696)
		(end 340.860126 -290.647882)
		(width 0.0889)
		(layer "In6.Cu")
		(net "UPI_CPU0_CPU1_P2P2_DN<14>")
	)
	(segment
		(start 71.226426 -322.245736)
		(end 79.33055 -314.141612)
		(width 0.14732)
		(layer "In6.Cu")
		(net "UPI_CPU0_CPU1_P2P2_DN<14>")
	)
	(segment
		(start 342.586564 -281.916378)
		(end 342.59266 -281.919934)
		(width 0.0889)
		(layer "In6.Cu")
		(net "UPI_CPU0_CPU1_P2P2_DN<14>")
	)
	(segment
		(start 71.97725 -363.242352)
		(end 68.101718 -353.895914)
		(width 0.14732)
		(layer "In6.Cu")
		(net "UPI_CPU0_CPU1_P2P2_DN<14>")
	)
	(segment
		(start 334.985868 -300.108874)
		(end 334.296766 -302.379888)
		(width 0.14732)
		(layer "In6.Cu")
		(net "UPI_CPU0_CPU1_P2P2_DN<14>")
	)
	(segment
		(start 100.662994 -283.542232)
		(end 100.668582 -283.539184)
		(width 0.0889)
		(layer "In6.Cu")
		(net "UPI_CPU0_CPU1_P2P2_DN<14>")
	)
	(segment
		(start 336.105754 -296.419524)
		(end 336.1055 -296.420286)
		(width 0.14732)
		(layer "In6.Cu")
		(net "UPI_CPU0_CPU1_P2P2_DN<14>")
	)
	(segment
		(start 341.677498 -281.863038)
		(end 341.69858 -281.941016)
		(width 0.0889)
		(layer "In6.Cu")
		(net "UPI_CPU0_CPU1_P2P2_DN<14>")
	)
	(segment
		(start 99.720146 -285.171896)
		(end 99.72167 -285.171134)
		(width 0.0889)
		(layer "In6.Cu")
		(net "UPI_CPU0_CPU1_P2P2_DN<14>")
	)
	(segment
		(start 336.335878 -299.103034)
		(end 336.540856 -299.486828)
		(width 0.14732)
		(layer "In6.Cu")
		(net "UPI_CPU0_CPU1_P2P2_DN<14>")
	)
	(segment
		(start 97.046288 -296.926254)
		(end 97.046288 -292.48354)
		(width 0.14732)
		(layer "In6.Cu")
		(net "UPI_CPU0_CPU1_P2P2_DN<14>")
	)
	(segment
		(start 284.79496 -331.724)
		(end 278.612092 -334.284828)
		(width 0.14732)
		(layer "In6.Cu")
		(net "UPI_CPU0_CPU1_P2P2_DN<14>")
	)
	(segment
		(start 98.780346 -288.427414)
		(end 98.789236 -288.422334)
		(width 0.0889)
		(layer "In6.Cu")
		(net "UPI_CPU0_CPU1_P2P2_DN<14>")
	)
	(segment
		(start 335.169256 -300.01083)
		(end 334.985868 -300.108874)
		(width 0.14732)
		(layer "In6.Cu")
		(net "UPI_CPU0_CPU1_P2P2_DN<14>")
	)
	(segment
		(start 339.313266 -292.62705)
		(end 339.313266 -292.686994)
		(width 0.0889)
		(layer "In6.Cu")
		(net "UPI_CPU0_CPU1_P2P2_DN<14>")
	)
	(segment
		(start 334.296766 -302.379888)
		(end 314.973716 -321.702938)
		(width 0.14732)
		(layer "In6.Cu")
		(net "UPI_CPU0_CPU1_P2P2_DN<14>")
	)
	(segment
		(start 98.497898 -289.114738)
		(end 98.497898 -288.898584)
		(width 0.0889)
		(layer "In6.Cu")
		(net "UPI_CPU0_CPU1_P2P2_DN<14>")
	)
	(segment
		(start 98.967544 -290.218114)
		(end 98.967544 -289.645852)
		(width 0.0889)
		(layer "In6.Cu")
		(net "UPI_CPU0_CPU1_P2P2_DN<14>")
	)
	(segment
		(start 339.313266 -292.686994)
		(end 339.297772 -292.702488)
		(width 0.0889)
		(layer "In6.Cu")
		(net "UPI_CPU0_CPU1_P2P2_DN<14>")
	)
	(segment
		(start 268.314932 -344.581988)
		(end 268.314932 -366.97539)
		(width 0.14732)
		(layer "In6.Cu")
		(net "UPI_CPU0_CPU1_P2P2_DN<14>")
	)
	(segment
		(start 99.719384 -286.80029)
		(end 99.720146 -286.799782)
		(width 0.0889)
		(layer "In6.Cu")
		(net "UPI_CPU0_CPU1_P2P2_DN<14>")
	)
	(segment
		(start 100.663502 -281.269694)
		(end 100.66147 -281.268424)
		(width 0.0889)
		(layer "In6.Cu")
		(net "UPI_CPU0_CPU1_P2P2_DN<14>")
	)
	(segment
		(start 101.317044 -279.158954)
		(end 101.317044 -279.140412)
		(width 0.0889)
		(layer "In6.Cu")
		(net "UPI_CPU0_CPU1_P2P2_DN<14>")
	)
	(segment
		(start 340.989666 -288.917126)
		(end 340.989666 -289.078416)
		(width 0.0889)
		(layer "In6.Cu")
		(net "UPI_CPU0_CPU1_P2P2_DN<14>")
	)
	(segment
		(start 98.925634 -290.604194)
		(end 98.925634 -290.282122)
		(width 0.14732)
		(layer "In6.Cu")
		(net "UPI_CPU0_CPU1_P2P2_DN<14>")
	)
	(segment
		(start 198.498714 -374.30837)
		(end 159.818832 -381.03683)
		(width 0.14732)
		(layer "In6.Cu")
		(net "UPI_CPU0_CPU1_P2P2_DN<14>")
	)
	(segment
		(start 99.907598 -284.847538)
		(end 99.907598 -284.832044)
		(width 0.0889)
		(layer "In6.Cu")
		(net "UPI_CPU0_CPU1_P2P2_DN<14>")
	)
	(segment
		(start 339.055456 -292.943788)
		(end 339.055456 -292.944804)
		(width 0.14732)
		(layer "In6.Cu")
		(net "UPI_CPU0_CPU1_P2P2_DN<14>")
	)
	(segment
		(start 341.177118 -288.592768)
		(end 341.168228 -288.597848)
		(width 0.0889)
		(layer "In6.Cu")
		(net "UPI_CPU0_CPU1_P2P2_DN<14>")
	)
	(segment
		(start 100.660454 -283.543756)
		(end 100.662232 -283.54274)
		(width 0.0889)
		(layer "In6.Cu")
		(net "UPI_CPU0_CPU1_P2P2_DN<14>")
	)
	(segment
		(start 342.107774 -285.980632)
		(end 342.116664 -285.985712)
		(width 0.0889)
		(layer "In6.Cu")
		(net "UPI_CPU0_CPU1_P2P2_DN<14>")
	)
	(segment
		(start 311.03951 -324.401434)
		(end 310.379872 -324.865492)
		(width 0.14732)
		(layer "In6.Cu")
		(net "UPI_CPU0_CPU1_P2P2_DN<14>")
	)
	(segment
		(start 101.129592 -282.730194)
		(end 101.138482 -282.725114)
		(width 0.0889)
		(layer "In6.Cu")
		(net "UPI_CPU0_CPU1_P2P2_DN<14>")
	)
	(segment
		(start 100.377244 -284.033722)
		(end 100.377244 -284.023816)
		(width 0.0889)
		(layer "In6.Cu")
		(net "UPI_CPU0_CPU1_P2P2_DN<14>")
	)
	(segment
		(start 99.72167 -285.171134)
		(end 99.729036 -285.166816)
		(width 0.0889)
		(layer "In6.Cu")
		(net "UPI_CPU0_CPU1_P2P2_DN<14>")
	)
	(segment
		(start 311.03951 -324.40118)
		(end 311.03951 -324.401434)
		(width 0.14732)
		(layer "In6.Cu")
		(net "UPI_CPU0_CPU1_P2P2_DN<14>")
	)
	(segment
		(start 100.847144 -283.219906)
		(end 100.847144 -283.205682)
		(width 0.0889)
		(layer "In6.Cu")
		(net "UPI_CPU0_CPU1_P2P2_DN<14>")
	)
	(segment
		(start 342.399366 -286.4612)
		(end 342.399366 -286.475424)
		(width 0.0889)
		(layer "In6.Cu")
		(net "UPI_CPU0_CPU1_P2P2_DN<14>")
	)
	(segment
		(start 335.520284 -298.855384)
		(end 336.335878 -299.103034)
		(width 0.14732)
		(layer "In6.Cu")
		(net "UPI_CPU0_CPU1_P2P2_DN<14>")
	)
	(segment
		(start 305.039776 -331.724)
		(end 284.79496 -331.724)
		(width 0.14732)
		(layer "In6.Cu")
		(net "UPI_CPU0_CPU1_P2P2_DN<14>")
	)
	(segment
		(start 268.314932 -366.97539)
		(end 263.290812 -372.000018)
		(width 0.14732)
		(layer "In6.Cu")
		(net "UPI_CPU0_CPU1_P2P2_DN<14>")
	)
	(segment
		(start 100.668836 -281.272742)
		(end 100.666804 -281.271472)
		(width 0.0889)
		(layer "In6.Cu")
		(net "UPI_CPU0_CPU1_P2P2_DN<14>")
	)
	(segment
		(start 94.659196 -301.561754)
		(end 95.717106 -300.135544)
		(width 0.14732)
		(layer "In6.Cu")
		(net "UPI_CPU0_CPU1_P2P2_DN<14>")
	)
	(segment
		(start 159.818832 -381.03683)
		(end 125.58903 -381.03683)
		(width 0.14732)
		(layer "In6.Cu")
		(net "UPI_CPU0_CPU1_P2P2_DN<14>")
	)
	(segment
		(start 103.448612 -276.979634)
		(end 103.292148 -276.708616)
		(width 0.0889)
		(layer "In6.Cu")
		(net "UPI_CPU0_CPU1_P2P2_DN<14>")
	)
	(segment
		(start 341.459312 -289.60953)
		(end 341.459312 -290.048696)
		(width 0.0889)
		(layer "In6.Cu")
		(net "UPI_CPU0_CPU1_P2P2_DN<14>")
	)
	(segment
		(start 69.309488 -326.300084)
		(end 71.226426 -322.245736)
		(width 0.14732)
		(layer "In6.Cu")
		(net "UPI_CPU0_CPU1_P2P2_DN<14>")
	)
	(segment
		(start 101.786944 -278.336502)
		(end 101.786944 -278.328882)
		(width 0.0889)
		(layer "In6.Cu")
		(net "UPI_CPU0_CPU1_P2P2_DN<14>")
	)
	(segment
		(start 314.973716 -321.702938)
		(end 313.024012 -323.005704)
		(width 0.14732)
		(layer "In6.Cu")
		(net "UPI_CPU0_CPU1_P2P2_DN<14>")
	)
	(segment
		(start 341.929212 -287.28924)
		(end 341.929212 -287.304734)
		(width 0.0889)
		(layer "In6.Cu")
		(net "UPI_CPU0_CPU1_P2P2_DN<14>")
	)
	(segment
		(start 341.45982 -288.092896)
		(end 341.459566 -288.102294)
		(width 0.0889)
		(layer "In6.Cu")
		(net "UPI_CPU0_CPU1_P2P2_DN<14>")
	)
	(segment
		(start 343.056464 -283.709364)
		(end 343.047574 -283.714444)
		(width 0.0889)
		(layer "In6.Cu")
		(net "UPI_CPU0_CPU1_P2P2_DN<14>")
	)
	(segment
		(start 100.659946 -280.288492)
		(end 100.668836 -280.283412)
		(width 0.0889)
		(layer "In6.Cu")
		(net "UPI_CPU0_CPU1_P2P2_DN<14>")
	)
	(segment
		(start 339.055456 -292.944804)
		(end 338.39912 -293.60114)
		(width 0.14732)
		(layer "In6.Cu")
		(net "UPI_CPU0_CPU1_P2P2_DN<14>")
	)
	(segment
		(start 335.985104 -300.25848)
		(end 335.169256 -300.01083)
		(width 0.14732)
		(layer "In6.Cu")
		(net "UPI_CPU0_CPU1_P2P2_DN<14>")
	)
	(segment
		(start 342.12276 -286.961326)
		(end 342.107774 -286.970216)
		(width 0.0889)
		(layer "In6.Cu")
		(net "UPI_CPU0_CPU1_P2P2_DN<14>")
	)
	(segment
		(start 103.42753 -277.057612)
		(end 103.448612 -276.979634)
		(width 0.0889)
		(layer "In6.Cu")
		(net "UPI_CPU0_CPU1_P2P2_DN<14>")
	)
	(segment
		(start 337.171538 -294.827706)
		(end 336.105754 -296.419524)
		(width 0.14732)
		(layer "In6.Cu")
		(net "UPI_CPU0_CPU1_P2P2_DN<14>")
	)
	(segment
		(start 339.056472 -292.943788)
		(end 339.055456 -292.943788)
		(width 0.14732)
		(layer "In6.Cu")
		(net "UPI_CPU0_CPU1_P2P2_DN<14>")
	)
	(segment
		(start 341.459566 -288.102294)
		(end 341.459566 -288.121598)
		(width 0.0889)
		(layer "In6.Cu")
		(net "UPI_CPU0_CPU1_P2P2_DN<14>")
	)
	(segment
		(start 342.107774 -286.970216)
		(end 342.107774 -286.969962)
		(width 0.0889)
		(layer "In6.Cu")
		(net "UPI_CPU0_CPU1_P2P2_DN<14>")
	)
	(segment
		(start 100.657152 -281.265884)
		(end 100.65385 -281.264106)
		(width 0.0889)
		(layer "In6.Cu")
		(net "UPI_CPU0_CPU1_P2P2_DN<14>")
	)
	(segment
		(start 103.09606 -277.02764)
		(end 103.10495 -277.032974)
		(width 0.0889)
		(layer "In6.Cu")
		(net "UPI_CPU0_CPU1_P2P2_DN<14>")
	)
	(segment
		(start 100.377244 -280.778204)
		(end 100.377244 -280.76398)
		(width 0.0889)
		(layer "In6.Cu")
		(net "UPI_CPU0_CPU1_P2P2_DN<14>")
	)
	(segment
		(start 98.925634 -290.282122)
		(end 98.925634 -290.260024)
		(width 0.0889)
		(layer "In6.Cu")
		(net "UPI_CPU0_CPU1_P2P2_DN<14>")
	)
	(segment
		(start 99.71405 -286.803338)
		(end 99.719384 -286.80029)
		(width 0.0889)
		(layer "In6.Cu")
		(net "UPI_CPU0_CPU1_P2P2_DN<14>")
	)
	(segment
		(start 79.33055 -314.141612)
		(end 94.659196 -301.561754)
		(width 0.14732)
		(layer "In6.Cu")
		(net "UPI_CPU0_CPU1_P2P2_DN<14>")
	)
	(segment
		(start 342.571832 -281.907742)
		(end 342.586564 -281.916378)
		(width 0.0889)
		(layer "In6.Cu")
		(net "UPI_CPU0_CPU1_P2P2_DN<14>")
	)
	(segment
		(start 336.368898 -300.053502)
		(end 335.985104 -300.25848)
		(width 0.14732)
		(layer "In6.Cu")
		(net "UPI_CPU0_CPU1_P2P2_DN<14>")
	)
	(segment
		(start 342.586818 -284.52318)
		(end 342.577928 -284.52826)
		(width 0.0889)
		(layer "In6.Cu")
		(net "UPI_CPU0_CPU1_P2P2_DN<14>")
	)
	(segment
		(start 338.39912 -293.60114)
		(end 338.398104 -293.60114)
		(width 0.14732)
		(layer "In6.Cu")
		(net "UPI_CPU0_CPU1_P2P2_DN<14>")
	)
	(segment
		(start 307.739542 -326.973438)
		(end 307.412644 -328.826114)
		(width 0.14732)
		(layer "In6.Cu")
		(net "UPI_CPU0_CPU1_P2P2_DN<14>")
	)
	(segment
		(start 100.66147 -281.268424)
		(end 100.659946 -281.267662)
		(width 0.0889)
		(layer "In6.Cu")
		(net "UPI_CPU0_CPU1_P2P2_DN<14>")
	)
	(segment
		(start 98.925634 -290.260024)
		(end 98.967544 -290.218114)
		(width 0.0889)
		(layer "In6.Cu")
		(net "UPI_CPU0_CPU1_P2P2_DN<14>")
	)
	(arc
		(start 342.59266 -281.919934)
		(mid 342.795247 -282.126285)
		(end 342.869266 -282.405836)
		(width 0.0889)
		(layer "In6.Cu")
		(net "UPI_CPU0_CPU1_P2P2_DN<14>")
	)
	(arc
		(start 101.608382 -278.65578)
		(mid 101.739296 -278.51942)
		(end 101.786944 -278.336502)
		(width 0.0889)
		(layer "In6.Cu")
		(net "UPI_CPU0_CPU1_P2P2_DN<14>")
	)
	(arc
		(start 99.720146 -286.151066)
		(mid 99.516665 -285.950262)
		(end 99.437444 -285.675578)
		(width 0.0889)
		(layer "In6.Cu")
		(net "UPI_CPU0_CPU1_P2P2_DN<14>")
	)
	(arc
		(start 341.929212 -287.304734)
		(mid 341.849842 -287.578468)
		(end 341.647018 -287.778698)
		(width 0.0889)
		(layer "In6.Cu")
		(net "UPI_CPU0_CPU1_P2P2_DN<14>")
	)
	(arc
		(start 342.399366 -284.847538)
		(mid 342.325375 -285.127104)
		(end 342.12276 -285.33344)
		(width 0.0889)
		(layer "In6.Cu")
		(net "UPI_CPU0_CPU1_P2P2_DN<14>")
	)
	(arc
		(start 341.173816 -289.277806)
		(mid 341.347948 -289.416653)
		(end 341.459312 -289.60953)
		(width 0.0889)
		(layer "In6.Cu")
		(net "UPI_CPU0_CPU1_P2P2_DN<14>")
	)
	(arc
		(start 98.789236 -288.422334)
		(mid 98.92015 -288.285974)
		(end 98.967798 -288.103056)
		(width 0.0889)
		(layer "In6.Cu")
		(net "UPI_CPU0_CPU1_P2P2_DN<14>")
	)
	(arc
		(start 99.437444 -285.661354)
		(mid 99.511435 -285.381788)
		(end 99.71405 -285.175452)
		(width 0.0889)
		(layer "In6.Cu")
		(net "UPI_CPU0_CPU1_P2P2_DN<14>")
	)
	(arc
		(start 100.65385 -281.264106)
		(mid 100.451263 -281.057755)
		(end 100.377244 -280.778204)
		(width 0.0889)
		(layer "In6.Cu")
		(net "UPI_CPU0_CPU1_P2P2_DN<14>")
	)
	(arc
		(start 99.437444 -287.28924)
		(mid 99.511435 -287.009674)
		(end 99.71405 -286.803338)
		(width 0.0889)
		(layer "In6.Cu")
		(net "UPI_CPU0_CPU1_P2P2_DN<14>")
	)
	(arc
		(start 342.399366 -286.475424)
		(mid 342.325375 -286.75499)
		(end 342.12276 -286.961326)
		(width 0.0889)
		(layer "In6.Cu")
		(net "UPI_CPU0_CPU1_P2P2_DN<14>")
	)
	(arc
		(start 98.967798 -288.087562)
		(mid 99.047168 -287.813828)
		(end 99.249992 -287.613598)
		(width 0.0889)
		(layer "In6.Cu")
		(net "UPI_CPU0_CPU1_P2P2_DN<14>")
	)
	(arc
		(start 102.539292 -277.03272)
		(mid 102.817018 -276.956875)
		(end 103.09606 -277.02764)
		(width 0.0889)
		(layer "In6.Cu")
		(net "UPI_CPU0_CPU1_P2P2_DN<14>")
	)
	(arc
		(start 100.847398 -281.59202)
		(mid 100.799719 -281.40912)
		(end 100.668836 -281.272742)
		(width 0.0889)
		(layer "In6.Cu")
		(net "UPI_CPU0_CPU1_P2P2_DN<14>")
	)
	(arc
		(start 100.847398 -279.954228)
		(mid 100.925509 -279.677279)
		(end 101.129846 -279.474676)
		(width 0.0889)
		(layer "In6.Cu")
		(net "UPI_CPU0_CPU1_P2P2_DN<14>")
	)
	(arc
		(start 101.317044 -282.395676)
		(mid 101.266975 -282.218451)
		(end 101.138482 -282.086558)
		(width 0.0889)
		(layer "In6.Cu")
		(net "UPI_CPU0_CPU1_P2P2_DN<14>")
	)
	(arc
		(start 342.869012 -284.049216)
		(mid 342.789642 -284.32295)
		(end 342.586818 -284.52318)
		(width 0.0889)
		(layer "In6.Cu")
		(net "UPI_CPU0_CPU1_P2P2_DN<14>")
	)
	(arc
		(start 101.786944 -278.328882)
		(mid 101.864573 -278.050469)
		(end 102.069646 -277.84679)
		(width 0.0889)
		(layer "In6.Cu")
		(net "UPI_CPU0_CPU1_P2P2_DN<14>")
	)
	(arc
		(start 100.847144 -283.205682)
		(mid 100.926285 -282.931059)
		(end 101.129592 -282.730194)
		(width 0.0889)
		(layer "In6.Cu")
		(net "UPI_CPU0_CPU1_P2P2_DN<14>")
	)
	(arc
		(start 100.377244 -284.023816)
		(mid 100.455355 -283.746867)
		(end 100.659692 -283.544264)
		(width 0.0889)
		(layer "In6.Cu")
		(net "UPI_CPU0_CPU1_P2P2_DN<14>")
	)
	(arc
		(start 101.138482 -282.725114)
		(mid 101.265736 -282.595148)
		(end 101.31679 -282.420568)
		(width 0.0889)
		(layer "In6.Cu")
		(net "UPI_CPU0_CPU1_P2P2_DN<14>")
	)
	(arc
		(start 103.10495 -277.032974)
		(mid 103.263438 -277.081907)
		(end 103.42753 -277.057612)
		(width 0.0889)
		(layer "In6.Cu")
		(net "UPI_CPU0_CPU1_P2P2_DN<14>")
	)
	(arc
		(start 100.668836 -280.283412)
		(mid 100.79975 -280.147052)
		(end 100.847398 -279.964134)
		(width 0.0889)
		(layer "In6.Cu")
		(net "UPI_CPU0_CPU1_P2P2_DN<14>")
	)
	(arc
		(start 101.129592 -282.081478)
		(mid 100.926769 -281.881247)
		(end 100.847398 -281.607514)
		(width 0.0889)
		(layer "In6.Cu")
		(net "UPI_CPU0_CPU1_P2P2_DN<14>")
	)
	(arc
		(start 99.729036 -285.166816)
		(mid 99.85995 -285.030456)
		(end 99.907598 -284.847538)
		(width 0.0889)
		(layer "In6.Cu")
		(net "UPI_CPU0_CPU1_P2P2_DN<14>")
	)
	(arc
		(start 340.989666 -289.078416)
		(mid 341.064671 -289.193875)
		(end 341.173816 -289.277806)
		(width 0.0889)
		(layer "In6.Cu")
		(net "UPI_CPU0_CPU1_P2P2_DN<14>")
	)
	(arc
		(start 100.198682 -284.353)
		(mid 100.329596 -284.21664)
		(end 100.377244 -284.033722)
		(width 0.0889)
		(layer "In6.Cu")
		(net "UPI_CPU0_CPU1_P2P2_DN<14>")
	)
	(arc
		(start 99.907344 -286.466788)
		(mid 99.855074 -286.284423)
		(end 99.720146 -286.151066)
		(width 0.0889)
		(layer "In6.Cu")
		(net "UPI_CPU0_CPU1_P2P2_DN<14>")
	)
	(arc
		(start 342.02116 -281.916378)
		(mid 342.295359 -281.840543)
		(end 342.571832 -281.907742)
		(width 0.0889)
		(layer "In6.Cu")
		(net "UPI_CPU0_CPU1_P2P2_DN<14>")
	)
	(arc
		(start 341.459566 -288.121598)
		(mid 341.379404 -288.393787)
		(end 341.177118 -288.592768)
		(width 0.0889)
		(layer "In6.Cu")
		(net "UPI_CPU0_CPU1_P2P2_DN<14>")
	)
	(arc
		(start 342.116664 -285.985712)
		(mid 342.320145 -286.186516)
		(end 342.399366 -286.4612)
		(width 0.0889)
		(layer "In6.Cu")
		(net "UPI_CPU0_CPU1_P2P2_DN<14>")
	)
	(arc
		(start 101.317044 -279.140412)
		(mid 101.395155 -278.863463)
		(end 101.599492 -278.66086)
		(width 0.0889)
		(layer "In6.Cu")
		(net "UPI_CPU0_CPU1_P2P2_DN<14>")
	)
	(arc
		(start 341.638128 -287.783778)
		(mid 341.509809 -287.91575)
		(end 341.45982 -288.092896)
		(width 0.0889)
		(layer "In6.Cu")
		(net "UPI_CPU0_CPU1_P2P2_DN<14>")
	)
	(arc
		(start 102.069646 -277.84679)
		(mid 102.204579 -277.713436)
		(end 102.256844 -277.531068)
		(width 0.0889)
		(layer "In6.Cu")
		(net "UPI_CPU0_CPU1_P2P2_DN<14>")
	)
	(arc
		(start 102.256844 -277.50389)
		(mid 102.337006 -277.231701)
		(end 102.539292 -277.03272)
		(width 0.0889)
		(layer "In6.Cu")
		(net "UPI_CPU0_CPU1_P2P2_DN<14>")
	)
	(arc
		(start 343.338912 -283.229812)
		(mid 343.260801 -283.506761)
		(end 343.056464 -283.709364)
		(width 0.0889)
		(layer "In6.Cu")
		(net "UPI_CPU0_CPU1_P2P2_DN<14>")
	)
	(arc
		(start 101.31679 -282.420568)
		(mid 101.317123 -282.408124)
		(end 101.317044 -282.395676)
		(width 0.0889)
		(layer "In6.Cu")
		(net "UPI_CPU0_CPU1_P2P2_DN<14>")
	)
	(arc
		(start 342.869266 -282.414472)
		(mid 342.921536 -282.596837)
		(end 343.056464 -282.730194)
		(width 0.0889)
		(layer "In6.Cu")
		(net "UPI_CPU0_CPU1_P2P2_DN<14>")
	)
	(arc
		(start 100.668582 -283.539184)
		(mid 100.799496 -283.402824)
		(end 100.847144 -283.219906)
		(width 0.0889)
		(layer "In6.Cu")
		(net "UPI_CPU0_CPU1_P2P2_DN<14>")
	)
	(arc
		(start 343.047574 -283.714444)
		(mid 342.91666 -283.850804)
		(end 342.869012 -284.033722)
		(width 0.0889)
		(layer "In6.Cu")
		(net "UPI_CPU0_CPU1_P2P2_DN<14>")
	)
	(arc
		(start 341.168228 -288.597848)
		(mid 341.037314 -288.734208)
		(end 340.989666 -288.917126)
		(width 0.0889)
		(layer "In6.Cu")
		(net "UPI_CPU0_CPU1_P2P2_DN<14>")
	)
	(arc
		(start 343.056464 -282.730194)
		(mid 343.25875 -282.929175)
		(end 343.338912 -283.201364)
		(width 0.0889)
		(layer "In6.Cu")
		(net "UPI_CPU0_CPU1_P2P2_DN<14>")
	)
	(arc
		(start 342.107774 -286.969962)
		(mid 341.97686 -287.106322)
		(end 341.929212 -287.28924)
		(width 0.0889)
		(layer "In6.Cu")
		(net "UPI_CPU0_CPU1_P2P2_DN<14>")
	)
	(arc
		(start 98.783394 -289.446462)
		(mid 98.609262 -289.307615)
		(end 98.497898 -289.114738)
		(width 0.0889)
		(layer "In6.Cu")
		(net "UPI_CPU0_CPU1_P2P2_DN<14>")
	)
	(arc
		(start 99.907598 -284.832044)
		(mid 99.986968 -284.55831)
		(end 100.189792 -284.35808)
		(width 0.0889)
		(layer "In6.Cu")
		(net "UPI_CPU0_CPU1_P2P2_DN<14>")
	)
	(arc
		(start 341.69858 -281.941016)
		(mid 341.862676 -281.965363)
		(end 342.02116 -281.916378)
		(width 0.0889)
		(layer "In6.Cu")
		(net "UPI_CPU0_CPU1_P2P2_DN<14>")
	)
	(arc
		(start 98.497898 -288.898584)
		(mid 98.57806 -288.626395)
		(end 98.780346 -288.427414)
		(width 0.0889)
		(layer "In6.Cu")
		(net "UPI_CPU0_CPU1_P2P2_DN<14>")
	)
	(arc
		(start 100.377244 -280.76398)
		(mid 100.456463 -280.489295)
		(end 100.659946 -280.288492)
		(width 0.0889)
		(layer "In6.Cu")
		(net "UPI_CPU0_CPU1_P2P2_DN<14>")
	)
	(arc
		(start 98.967544 -289.645852)
		(mid 98.892539 -289.530393)
		(end 98.783394 -289.446462)
		(width 0.0889)
		(layer "In6.Cu")
		(net "UPI_CPU0_CPU1_P2P2_DN<14>")
	)
	(arc
		(start 342.577928 -284.52826)
		(mid 342.447014 -284.66462)
		(end 342.399366 -284.847538)
		(width 0.0889)
		(layer "In6.Cu")
		(net "UPI_CPU0_CPU1_P2P2_DN<14>")
	)
	(arc
		(start 342.107774 -285.342076)
		(mid 341.929177 -285.661354)
		(end 342.107774 -285.980632)
		(width 0.0889)
		(layer "In6.Cu")
		(net "UPI_CPU0_CPU1_P2P2_DN<14>")
	)
	(arc
		(start 99.720146 -286.799782)
		(mid 99.855079 -286.666428)
		(end 99.907344 -286.48406)
		(width 0.0889)
		(layer "In6.Cu")
		(net "UPI_CPU0_CPU1_P2P2_DN<14>")
	)
	(arc
		(start 99.258882 -287.608518)
		(mid 99.389796 -287.472158)
		(end 99.437444 -287.28924)
		(width 0.0889)
		(layer "In6.Cu")
		(net "UPI_CPU0_CPU1_P2P2_DN<14>")
	)
	(arc
		(start 101.129846 -279.474676)
		(mid 101.264779 -279.341322)
		(end 101.317044 -279.158954)
		(width 0.0889)
		(layer "In6.Cu")
		(net "UPI_CPU0_CPU1_P2P2_DN<14>")
	)
	(segment
		(start 350.762316 -279.150064)
		(end 350.762062 -279.150318)
		(width 0.13208)
		(layer "F.Cu")
		(net "UPI_CPU0_CPU1_P2P2_DN<13>")
	)
	(segment
		(start 102.352094 -275.080476)
		(end 102.352348 -275.08073)
		(width 0.13208)
		(layer "F.Cu")
		(net "UPI_CPU0_CPU1_P2P2_DN<13>")
	)
	(segment
		(start 350.762316 -278.614378)
		(end 350.762316 -279.150064)
		(width 0.13208)
		(layer "F.Cu")
		(net "UPI_CPU0_CPU1_P2P2_DN<13>")
	)
	(segment
		(start 102.352094 -274.54479)
		(end 102.352094 -275.080476)
		(width 0.13208)
		(layer "F.Cu")
		(net "UPI_CPU0_CPU1_P2P2_DN<13>")
	)
	(segment
		(start 78.677008 -313.604402)
		(end 94.04477 -300.993048)
		(width 0.14732)
		(layer "In6.Cu")
		(net "UPI_CPU0_CPU1_P2P2_DN<13>")
	)
	(segment
		(start 71.40829 -364.06328)
		(end 67.268598 -354.068634)
		(width 0.14732)
		(layer "In6.Cu")
		(net "UPI_CPU0_CPU1_P2P2_DN<13>")
	)
	(segment
		(start 341.772748 -293.991538)
		(end 341.772748 -294.166798)
		(width 0.0889)
		(layer "In6.Cu")
		(net "UPI_CPU0_CPU1_P2P2_DN<13>")
	)
	(segment
		(start 343.996264 -285.336996)
		(end 343.987374 -285.342076)
		(width 0.0889)
		(layer "In6.Cu")
		(net "UPI_CPU0_CPU1_P2P2_DN<13>")
	)
	(segment
		(start 344.00236 -286.961326)
		(end 343.987374 -286.970216)
		(width 0.0889)
		(layer "In6.Cu")
		(net "UPI_CPU0_CPU1_P2P2_DN<13>")
	)
	(segment
		(start 284.97149 -332.55204)
		(end 279.073102 -334.995012)
		(width 0.14732)
		(layer "In6.Cu")
		(net "UPI_CPU0_CPU1_P2P2_DN<13>")
	)
	(segment
		(start 313.413648 -324.840854)
		(end 313.098688 -325.06158)
		(width 0.14732)
		(layer "In6.Cu")
		(net "UPI_CPU0_CPU1_P2P2_DN<13>")
	)
	(segment
		(start 345.406218 -281.267662)
		(end 345.397328 -281.272742)
		(width 0.0889)
		(layer "In6.Cu")
		(net "UPI_CPU0_CPU1_P2P2_DN<13>")
	)
	(segment
		(start 98.027744 -290.384484)
		(end 98.027744 -289.645852)
		(width 0.0889)
		(layer "In6.Cu")
		(net "UPI_CPU0_CPU1_P2P2_DN<13>")
	)
	(segment
		(start 342.399112 -290.279836)
		(end 341.673688 -291.00526)
		(width 0.0889)
		(layer "In6.Cu")
		(net "UPI_CPU0_CPU1_P2P2_DN<13>")
	)
	(segment
		(start 102.722426 -275.138134)
		(end 102.665022 -275.08073)
		(width 0.0889)
		(layer "In6.Cu")
		(net "UPI_CPU0_CPU1_P2P2_DN<13>")
	)
	(segment
		(start 349.080328 -278.832056)
		(end 349.069914 -278.82596)
		(width 0.0889)
		(layer "In6.Cu")
		(net "UPI_CPU0_CPU1_P2P2_DN<13>")
	)
	(segment
		(start 99.71405 -283.54782)
		(end 99.719384 -283.544772)
		(width 0.0889)
		(layer "In6.Cu")
		(net "UPI_CPU0_CPU1_P2P2_DN<13>")
	)
	(segment
		(start 350.95815 -278.83104)
		(end 350.94926 -278.82596)
		(width 0.0889)
		(layer "In6.Cu")
		(net "UPI_CPU0_CPU1_P2P2_DN<13>")
	)
	(segment
		(start 99.907344 -283.228542)
		(end 99.907344 -283.201364)
		(width 0.0889)
		(layer "In6.Cu")
		(net "UPI_CPU0_CPU1_P2P2_DN<13>")
	)
	(segment
		(start 308.697122 -327.402444)
		(end 308.268624 -329.83297)
		(width 0.14732)
		(layer "In6.Cu")
		(net "UPI_CPU0_CPU1_P2P2_DN<13>")
	)
	(segment
		(start 100.847144 -278.345138)
		(end 100.847144 -278.31796)
		(width 0.0889)
		(layer "In6.Cu")
		(net "UPI_CPU0_CPU1_P2P2_DN<13>")
	)
	(segment
		(start 311.239408 -325.647304)
		(end 310.902604 -325.647304)
		(width 0.14732)
		(layer "In6.Cu")
		(net "UPI_CPU0_CPU1_P2P2_DN<13>")
	)
	(segment
		(start 98.77425 -285.175452)
		(end 98.780346 -285.171896)
		(width 0.0889)
		(layer "In6.Cu")
		(net "UPI_CPU0_CPU1_P2P2_DN<13>")
	)
	(segment
		(start 347.755464 -278.82596)
		(end 347.740732 -278.834596)
		(width 0.0889)
		(layer "In6.Cu")
		(net "UPI_CPU0_CPU1_P2P2_DN<13>")
	)
	(segment
		(start 341.673688 -294.265858)
		(end 341.673688 -295.022524)
		(width 0.0889)
		(layer "In6.Cu")
		(net "UPI_CPU0_CPU1_P2P2_DN<13>")
	)
	(segment
		(start 279.073102 -334.995012)
		(end 269.267432 -344.800682)
		(width 0.14732)
		(layer "In6.Cu")
		(net "UPI_CPU0_CPU1_P2P2_DN<13>")
	)
	(segment
		(start 76.312268 -368.967258)
		(end 71.40829 -364.06328)
		(width 0.14732)
		(layer "In6.Cu")
		(net "UPI_CPU0_CPU1_P2P2_DN<13>")
	)
	(segment
		(start 98.310192 -287.613598)
		(end 98.319082 -287.608518)
		(width 0.0889)
		(layer "In6.Cu")
		(net "UPI_CPU0_CPU1_P2P2_DN<13>")
	)
	(segment
		(start 94.04477 -300.993048)
		(end 94.992444 -299.715428)
		(width 0.14732)
		(layer "In6.Cu")
		(net "UPI_CPU0_CPU1_P2P2_DN<13>")
	)
	(segment
		(start 70.46849 -321.810888)
		(end 78.343506 -313.935872)
		(width 0.14732)
		(layer "In6.Cu")
		(net "UPI_CPU0_CPU1_P2P2_DN<13>")
	)
	(segment
		(start 100.647754 -278.667972)
		(end 100.659946 -278.66086)
		(width 0.0889)
		(layer "In6.Cu")
		(net "UPI_CPU0_CPU1_P2P2_DN<13>")
	)
	(segment
		(start 341.673688 -291.00526)
		(end 341.673688 -292.246558)
		(width 0.0889)
		(layer "In6.Cu")
		(net "UPI_CPU0_CPU1_P2P2_DN<13>")
	)
	(segment
		(start 344.927174 -283.714698)
		(end 344.927174 -283.714444)
		(width 0.0889)
		(layer "In6.Cu")
		(net "UPI_CPU0_CPU1_P2P2_DN<13>")
	)
	(segment
		(start 98.788982 -286.156146)
		(end 98.780854 -286.151574)
		(width 0.0889)
		(layer "In6.Cu")
		(net "UPI_CPU0_CPU1_P2P2_DN<13>")
	)
	(segment
		(start 341.772748 -292.345618)
		(end 341.772748 -292.520878)
		(width 0.0889)
		(layer "In6.Cu")
		(net "UPI_CPU0_CPU1_P2P2_DN<13>")
	)
	(segment
		(start 344.466418 -284.52318)
		(end 344.457528 -284.52826)
		(width 0.0889)
		(layer "In6.Cu")
		(net "UPI_CPU0_CPU1_P2P2_DN<13>")
	)
	(segment
		(start 100.190808 -279.474168)
		(end 100.198682 -279.469596)
		(width 0.0889)
		(layer "In6.Cu")
		(net "UPI_CPU0_CPU1_P2P2_DN<13>")
	)
	(segment
		(start 100.198682 -282.086558)
		(end 100.189792 -282.081478)
		(width 0.0889)
		(layer "In6.Cu")
		(net "UPI_CPU0_CPU1_P2P2_DN<13>")
	)
	(segment
		(start 341.673688 -292.619938)
		(end 341.673688 -292.795198)
		(width 0.0889)
		(layer "In6.Cu")
		(net "UPI_CPU0_CPU1_P2P2_DN<13>")
	)
	(segment
		(start 269.267432 -344.800682)
		(end 269.267432 -367.77041)
		(width 0.14732)
		(layer "In6.Cu")
		(net "UPI_CPU0_CPU1_P2P2_DN<13>")
	)
	(segment
		(start 212.924898 -377.387612)
		(end 199.463152 -375.938288)
		(width 0.14732)
		(layer "In6.Cu")
		(net "UPI_CPU0_CPU1_P2P2_DN<13>")
	)
	(segment
		(start 97.840546 -288.427414)
		(end 97.849436 -288.422334)
		(width 0.0889)
		(layer "In6.Cu")
		(net "UPI_CPU0_CPU1_P2P2_DN<13>")
	)
	(segment
		(start 307.627528 -330.747878)
		(end 305.824382 -332.55204)
		(width 0.14732)
		(layer "In6.Cu")
		(net "UPI_CPU0_CPU1_P2P2_DN<13>")
	)
	(segment
		(start 125.537214 -381.86995)
		(end 97.379028 -377.692666)
		(width 0.14732)
		(layer "In6.Cu")
		(net "UPI_CPU0_CPU1_P2P2_DN<13>")
	)
	(segment
		(start 344.00236 -285.33344)
		(end 343.996264 -285.336996)
		(width 0.0889)
		(layer "In6.Cu")
		(net "UPI_CPU0_CPU1_P2P2_DN<13>")
	)
	(segment
		(start 314.35421 -323.497194)
		(end 313.413648 -324.840854)
		(width 0.14732)
		(layer "In6.Cu")
		(net "UPI_CPU0_CPU1_P2P2_DN<13>")
	)
	(segment
		(start 100.189792 -279.474676)
		(end 100.190808 -279.474168)
		(width 0.0889)
		(layer "In6.Cu")
		(net "UPI_CPU0_CPU1_P2P2_DN<13>")
	)
	(segment
		(start 97.073466 -291.279834)
		(end 97.132394 -291.279834)
		(width 0.0889)
		(layer "In6.Cu")
		(net "UPI_CPU0_CPU1_P2P2_DN<13>")
	)
	(segment
		(start 341.157052 -298.22775)
		(end 340.819232 -299.042836)
		(width 0.14732)
		(layer "In6.Cu")
		(net "UPI_CPU0_CPU1_P2P2_DN<13>")
	)
	(segment
		(start 68.597272 -325.7677)
		(end 70.46849 -321.810888)
		(width 0.14732)
		(layer "In6.Cu")
		(net "UPI_CPU0_CPU1_P2P2_DN<13>")
	)
	(segment
		(start 97.132394 -291.279834)
		(end 98.027744 -290.384484)
		(width 0.0889)
		(layer "In6.Cu")
		(net "UPI_CPU0_CPU1_P2P2_DN<13>")
	)
	(segment
		(start 101.587554 -277.040086)
		(end 101.599746 -277.032974)
		(width 0.0889)
		(layer "In6.Cu")
		(net "UPI_CPU0_CPU1_P2P2_DN<13>")
	)
	(segment
		(start 343.808812 -287.28924)
		(end 343.808812 -287.304734)
		(width 0.0889)
		(layer "In6.Cu")
		(net "UPI_CPU0_CPU1_P2P2_DN<13>")
	)
	(segment
		(start 99.437444 -280.778204)
		(end 99.437444 -280.76398)
		(width 0.0889)
		(layer "In6.Cu")
		(net "UPI_CPU0_CPU1_P2P2_DN<13>")
	)
	(segment
		(start 345.875864 -280.453846)
		(end 345.866974 -280.458926)
		(width 0.0889)
		(layer "In6.Cu")
		(net "UPI_CPU0_CPU1_P2P2_DN<13>")
	)
	(segment
		(start 346.158566 -279.964134)
		(end 346.158566 -279.978358)
		(width 0.0889)
		(layer "In6.Cu")
		(net "UPI_CPU0_CPU1_P2P2_DN<13>")
	)
	(segment
		(start 341.772748 -293.442898)
		(end 341.772748 -293.618158)
		(width 0.0889)
		(layer "In6.Cu")
		(net "UPI_CPU0_CPU1_P2P2_DN<13>")
	)
	(segment
		(start 350.762062 -279.150318)
		(end 351.074736 -279.150318)
		(width 0.0889)
		(layer "In6.Cu")
		(net "UPI_CPU0_CPU1_P2P2_DN<13>")
	)
	(segment
		(start 345.688412 -280.778204)
		(end 345.688412 -280.793698)
		(width 0.0889)
		(layer "In6.Cu")
		(net "UPI_CPU0_CPU1_P2P2_DN<13>")
	)
	(segment
		(start 99.249992 -284.35808)
		(end 99.258882 -284.353)
		(width 0.0889)
		(layer "In6.Cu")
		(net "UPI_CPU0_CPU1_P2P2_DN<13>")
	)
	(segment
		(start 161.713672 -381.86995)
		(end 125.537214 -381.86995)
		(width 0.14732)
		(layer "In6.Cu")
		(net "UPI_CPU0_CPU1_P2P2_DN<13>")
	)
	(segment
		(start 162.188652 -381.828548)
		(end 161.713672 -381.86995)
		(width 0.14732)
		(layer "In6.Cu")
		(net "UPI_CPU0_CPU1_P2P2_DN<13>")
	)
	(segment
		(start 341.673688 -292.795198)
		(end 341.772748 -292.894258)
		(width 0.0889)
		(layer "In6.Cu")
		(net "UPI_CPU0_CPU1_P2P2_DN<13>")
	)
	(segment
		(start 102.069392 -276.219158)
		(end 102.078282 -276.214078)
		(width 0.0889)
		(layer "In6.Cu")
		(net "UPI_CPU0_CPU1_P2P2_DN<13>")
	)
	(segment
		(start 344.94216 -282.077922)
		(end 344.936064 -282.081478)
		(width 0.0889)
		(layer "In6.Cu")
		(net "UPI_CPU0_CPU1_P2P2_DN<13>")
	)
	(segment
		(start 67.268598 -354.068634)
		(end 67.268598 -334.801972)
		(width 0.14732)
		(layer "In6.Cu")
		(net "UPI_CPU0_CPU1_P2P2_DN<13>")
	)
	(segment
		(start 310.009794 -326.017128)
		(end 309.60187 -326.289924)
		(width 0.14732)
		(layer "In6.Cu")
		(net "UPI_CPU0_CPU1_P2P2_DN<13>")
	)
	(segment
		(start 98.780854 -286.799274)
		(end 98.783394 -286.79775)
		(width 0.0889)
		(layer "In6.Cu")
		(net "UPI_CPU0_CPU1_P2P2_DN<13>")
	)
	(segment
		(start 98.497644 -287.28924)
		(end 98.497644 -287.279334)
		(width 0.0889)
		(layer "In6.Cu")
		(net "UPI_CPU0_CPU1_P2P2_DN<13>")
	)
	(segment
		(start 341.673688 -293.168578)
		(end 341.673688 -293.343838)
		(width 0.0889)
		(layer "In6.Cu")
		(net "UPI_CPU0_CPU1_P2P2_DN<13>")
	)
	(segment
		(start 343.056718 -288.592768)
		(end 343.047828 -288.597848)
		(width 0.0889)
		(layer "In6.Cu")
		(net "UPI_CPU0_CPU1_P2P2_DN<13>")
	)
	(segment
		(start 348.695518 -278.82596)
		(end 348.685104 -278.832056)
		(width 0.0889)
		(layer "In6.Cu")
		(net "UPI_CPU0_CPU1_P2P2_DN<13>")
	)
	(segment
		(start 98.780346 -285.171896)
		(end 98.789236 -285.166816)
		(width 0.0889)
		(layer "In6.Cu")
		(net "UPI_CPU0_CPU1_P2P2_DN<13>")
	)
	(segment
		(start 309.181754 -326.709786)
		(end 308.697122 -327.402444)
		(width 0.14732)
		(layer "In6.Cu")
		(net "UPI_CPU0_CPU1_P2P2_DN<13>")
	)
	(segment
		(start 342.869266 -288.917126)
		(end 342.869266 -289.114484)
		(width 0.0889)
		(layer "In6.Cu")
		(net "UPI_CPU0_CPU1_P2P2_DN<13>")
	)
	(segment
		(start 98.497644 -285.679896)
		(end 98.497644 -285.661354)
		(width 0.0889)
		(layer "In6.Cu")
		(net "UPI_CPU0_CPU1_P2P2_DN<13>")
	)
	(segment
		(start 100.189792 -282.730194)
		(end 100.198682 -282.725114)
		(width 0.0889)
		(layer "In6.Cu")
		(net "UPI_CPU0_CPU1_P2P2_DN<13>")
	)
	(segment
		(start 342.399112 -289.64636)
		(end 342.399112 -290.279836)
		(width 0.0889)
		(layer "In6.Cu")
		(net "UPI_CPU0_CPU1_P2P2_DN<13>")
	)
	(segment
		(start 97.057972 -291.295328)
		(end 97.073466 -291.279834)
		(width 0.0889)
		(layer "In6.Cu")
		(net "UPI_CPU0_CPU1_P2P2_DN<13>")
	)
	(segment
		(start 96.106488 -292.246812)
		(end 97.057972 -291.295328)
		(width 0.14732)
		(layer "In6.Cu")
		(net "UPI_CPU0_CPU1_P2P2_DN<13>")
	)
	(segment
		(start 99.720146 -280.288492)
		(end 99.729036 -280.283412)
		(width 0.0889)
		(layer "In6.Cu")
		(net "UPI_CPU0_CPU1_P2P2_DN<13>")
	)
	(segment
		(start 99.249992 -281.102562)
		(end 99.258882 -281.097482)
		(width 0.0889)
		(layer "In6.Cu")
		(net "UPI_CPU0_CPU1_P2P2_DN<13>")
	)
	(segment
		(start 341.673688 -293.892478)
		(end 341.772748 -293.991538)
		(width 0.0889)
		(layer "In6.Cu")
		(net "UPI_CPU0_CPU1_P2P2_DN<13>")
	)
	(segment
		(start 102.539546 -275.405088)
		(end 102.548436 -275.400008)
		(width 0.0889)
		(layer "In6.Cu")
		(net "UPI_CPU0_CPU1_P2P2_DN<13>")
	)
	(segment
		(start 343.987374 -286.970216)
		(end 343.987374 -286.969962)
		(width 0.0889)
		(layer "In6.Cu")
		(net "UPI_CPU0_CPU1_P2P2_DN<13>")
	)
	(segment
		(start 101.129592 -277.84679)
		(end 101.138482 -277.84171)
		(width 0.0889)
		(layer "In6.Cu")
		(net "UPI_CPU0_CPU1_P2P2_DN<13>")
	)
	(segment
		(start 351.074736 -279.150318)
		(end 351.13214 -279.092914)
		(width 0.0889)
		(layer "In6.Cu")
		(net "UPI_CPU0_CPU1_P2P2_DN<13>")
	)
	(segment
		(start 341.772748 -292.894258)
		(end 341.772748 -293.069518)
		(width 0.0889)
		(layer "In6.Cu")
		(net "UPI_CPU0_CPU1_P2P2_DN<13>")
	)
	(segment
		(start 344.94216 -283.705808)
		(end 344.927174 -283.714698)
		(width 0.0889)
		(layer "In6.Cu")
		(net "UPI_CPU0_CPU1_P2P2_DN<13>")
	)
	(segment
		(start 102.665022 -275.08073)
		(end 102.352348 -275.08073)
		(width 0.0889)
		(layer "In6.Cu")
		(net "UPI_CPU0_CPU1_P2P2_DN<13>")
	)
	(segment
		(start 341.772748 -293.618158)
		(end 341.673688 -293.717218)
		(width 0.0889)
		(layer "In6.Cu")
		(net "UPI_CPU0_CPU1_P2P2_DN<13>")
	)
	(segment
		(start 67.916298 -328.228706)
		(end 68.597272 -325.7677)
		(width 0.14732)
		(layer "In6.Cu")
		(net "UPI_CPU0_CPU1_P2P2_DN<13>")
	)
	(segment
		(start 98.967798 -281.607514)
		(end 98.967798 -281.576526)
		(width 0.0889)
		(layer "In6.Cu")
		(net "UPI_CPU0_CPU1_P2P2_DN<13>")
	)
	(segment
		(start 341.673688 -292.246558)
		(end 341.772748 -292.345618)
		(width 0.0889)
		(layer "In6.Cu")
		(net "UPI_CPU0_CPU1_P2P2_DN<13>")
	)
	(segment
		(start 99.719384 -283.544772)
		(end 99.720146 -283.544264)
		(width 0.0889)
		(layer "In6.Cu")
		(net "UPI_CPU0_CPU1_P2P2_DN<13>")
	)
	(segment
		(start 264.132568 -372.905274)
		(end 212.924898 -377.387612)
		(width 0.14732)
		(layer "In6.Cu")
		(net "UPI_CPU0_CPU1_P2P2_DN<13>")
	)
	(segment
		(start 341.715852 -295.086786)
		(end 341.715852 -296.769028)
		(width 0.14732)
		(layer "In6.Cu")
		(net "UPI_CPU0_CPU1_P2P2_DN<13>")
	)
	(segment
		(start 341.715852 -295.064688)
		(end 341.715852 -295.086786)
		(width 0.0889)
		(layer "In6.Cu")
		(net "UPI_CPU0_CPU1_P2P2_DN<13>")
	)
	(segment
		(start 341.387176 -297.843956)
		(end 341.157052 -298.22775)
		(width 0.14732)
		(layer "In6.Cu")
		(net "UPI_CPU0_CPU1_P2P2_DN<13>")
	)
	(segment
		(start 339.956648 -299.90542)
		(end 336.525362 -301.326042)
		(width 0.14732)
		(layer "In6.Cu")
		(net "UPI_CPU0_CPU1_P2P2_DN<13>")
	)
	(segment
		(start 313.098688 -325.06158)
		(end 311.239408 -325.647304)
		(width 0.14732)
		(layer "In6.Cu")
		(net "UPI_CPU0_CPU1_P2P2_DN<13>")
	)
	(segment
		(start 341.772748 -293.069518)
		(end 341.673688 -293.168578)
		(width 0.0889)
		(layer "In6.Cu")
		(net "UPI_CPU0_CPU1_P2P2_DN<13>")
	)
	(segment
		(start 98.780092 -286.799782)
		(end 98.780854 -286.799274)
		(width 0.0889)
		(layer "In6.Cu")
		(net "UPI_CPU0_CPU1_P2P2_DN<13>")
	)
	(segment
		(start 343.339166 -288.103056)
		(end 343.339166 -288.121598)
		(width 0.0889)
		(layer "In6.Cu")
		(net "UPI_CPU0_CPU1_P2P2_DN<13>")
	)
	(segment
		(start 344.927174 -282.725114)
		(end 344.936064 -282.730194)
		(width 0.0889)
		(layer "In6.Cu")
		(net "UPI_CPU0_CPU1_P2P2_DN<13>")
	)
	(segment
		(start 344.278966 -286.4612)
		(end 344.278966 -286.475424)
		(width 0.0889)
		(layer "In6.Cu")
		(net "UPI_CPU0_CPU1_P2P2_DN<13>")
	)
	(segment
		(start 341.772748 -294.166798)
		(end 341.673688 -294.265858)
		(width 0.0889)
		(layer "In6.Cu")
		(net "UPI_CPU0_CPU1_P2P2_DN<13>")
	)
	(segment
		(start 336.525362 -301.326042)
		(end 314.35421 -323.497194)
		(width 0.14732)
		(layer "In6.Cu")
		(net "UPI_CPU0_CPU1_P2P2_DN<13>")
	)
	(segment
		(start 78.66634 -313.612784)
		(end 78.676754 -313.604148)
		(width 0.14732)
		(layer "In6.Cu")
		(net "UPI_CPU0_CPU1_P2P2_DN<13>")
	)
	(segment
		(start 341.673688 -293.717218)
		(end 341.673688 -293.892478)
		(width 0.0889)
		(layer "In6.Cu")
		(net "UPI_CPU0_CPU1_P2P2_DN<13>")
	)
	(segment
		(start 341.715852 -296.769028)
		(end 341.387176 -297.843956)
		(width 0.14732)
		(layer "In6.Cu")
		(net "UPI_CPU0_CPU1_P2P2_DN<13>")
	)
	(segment
		(start 341.673688 -295.022524)
		(end 341.715852 -295.064688)
		(width 0.0889)
		(layer "In6.Cu")
		(net "UPI_CPU0_CPU1_P2P2_DN<13>")
	)
	(segment
		(start 350.574864 -278.82596)
		(end 350.560132 -278.834596)
		(width 0.0889)
		(layer "In6.Cu")
		(net "UPI_CPU0_CPU1_P2P2_DN<13>")
	)
	(segment
		(start 99.907598 -279.964134)
		(end 99.907598 -279.94864)
		(width 0.0889)
		(layer "In6.Cu")
		(net "UPI_CPU0_CPU1_P2P2_DN<13>")
	)
	(segment
		(start 343.526618 -287.778698)
		(end 343.517728 -287.783778)
		(width 0.0889)
		(layer "In6.Cu")
		(net "UPI_CPU0_CPU1_P2P2_DN<13>")
	)
	(segment
		(start 97.379028 -377.692666)
		(end 76.312268 -368.967258)
		(width 0.14732)
		(layer "In6.Cu")
		(net "UPI_CPU0_CPU1_P2P2_DN<13>")
	)
	(segment
		(start 309.60187 -326.289924)
		(end 309.181754 -326.709786)
		(width 0.14732)
		(layer "In6.Cu")
		(net "UPI_CPU0_CPU1_P2P2_DN<13>")
	)
	(segment
		(start 346.346018 -279.639776)
		(end 346.337128 -279.644856)
		(width 0.0889)
		(layer "In6.Cu")
		(net "UPI_CPU0_CPU1_P2P2_DN<13>")
	)
	(segment
		(start 199.463152 -375.938288)
		(end 162.188652 -381.828548)
		(width 0.14732)
		(layer "In6.Cu")
		(net "UPI_CPU0_CPU1_P2P2_DN<13>")
	)
	(segment
		(start 98.967798 -284.847538)
		(end 98.967798 -284.832044)
		(width 0.0889)
		(layer "In6.Cu")
		(net "UPI_CPU0_CPU1_P2P2_DN<13>")
	)
	(segment
		(start 341.673688 -293.343838)
		(end 341.772748 -293.442898)
		(width 0.0889)
		(layer "In6.Cu")
		(net "UPI_CPU0_CPU1_P2P2_DN<13>")
	)
	(segment
		(start 343.987374 -285.980632)
		(end 343.996264 -285.985712)
		(width 0.0889)
		(layer "In6.Cu")
		(net "UPI_CPU0_CPU1_P2P2_DN<13>")
	)
	(segment
		(start 344.748612 -284.033722)
		(end 344.748612 -284.049216)
		(width 0.0889)
		(layer "In6.Cu")
		(net "UPI_CPU0_CPU1_P2P2_DN<13>")
	)
	(segment
		(start 96.106488 -297.026076)
		(end 96.106488 -292.246812)
		(width 0.14732)
		(layer "In6.Cu")
		(net "UPI_CPU0_CPU1_P2P2_DN<13>")
	)
	(segment
		(start 310.902604 -325.647304)
		(end 310.009794 -326.017128)
		(width 0.14732)
		(layer "In6.Cu")
		(net "UPI_CPU0_CPU1_P2P2_DN<13>")
	)
	(segment
		(start 341.772748 -292.520878)
		(end 341.673688 -292.619938)
		(width 0.0889)
		(layer "In6.Cu")
		(net "UPI_CPU0_CPU1_P2P2_DN<13>")
	)
	(segment
		(start 101.786944 -276.717252)
		(end 101.786944 -276.69871)
		(width 0.0889)
		(layer "In6.Cu")
		(net "UPI_CPU0_CPU1_P2P2_DN<13>")
	)
	(segment
		(start 78.676754 -313.604148)
		(end 78.677008 -313.604402)
		(width 0.14732)
		(layer "In6.Cu")
		(net "UPI_CPU0_CPU1_P2P2_DN<13>")
	)
	(segment
		(start 94.992444 -299.715428)
		(end 96.106488 -297.026076)
		(width 0.14732)
		(layer "In6.Cu")
		(net "UPI_CPU0_CPU1_P2P2_DN<13>")
	)
	(segment
		(start 308.268624 -329.83297)
		(end 307.627528 -330.747878)
		(width 0.14732)
		(layer "In6.Cu")
		(net "UPI_CPU0_CPU1_P2P2_DN<13>")
	)
	(segment
		(start 344.936064 -282.081478)
		(end 344.927174 -282.086558)
		(width 0.0889)
		(layer "In6.Cu")
		(net "UPI_CPU0_CPU1_P2P2_DN<13>")
	)
	(segment
		(start 98.780854 -286.151574)
		(end 98.780092 -286.151066)
		(width 0.0889)
		(layer "In6.Cu")
		(net "UPI_CPU0_CPU1_P2P2_DN<13>")
	)
	(segment
		(start 269.267432 -367.77041)
		(end 264.132568 -372.905274)
		(width 0.14732)
		(layer "In6.Cu")
		(net "UPI_CPU0_CPU1_P2P2_DN<13>")
	)
	(segment
		(start 98.027998 -288.103056)
		(end 98.027998 -288.087562)
		(width 0.0889)
		(layer "In6.Cu")
		(net "UPI_CPU0_CPU1_P2P2_DN<13>")
	)
	(segment
		(start 78.343506 -313.935872)
		(end 78.343506 -313.935618)
		(width 0.14732)
		(layer "In6.Cu")
		(net "UPI_CPU0_CPU1_P2P2_DN<13>")
	)
	(segment
		(start 78.343506 -313.935618)
		(end 78.66634 -313.612784)
		(width 0.14732)
		(layer "In6.Cu")
		(net "UPI_CPU0_CPU1_P2P2_DN<13>")
	)
	(segment
		(start 340.819232 -299.042836)
		(end 339.956648 -299.90542)
		(width 0.14732)
		(layer "In6.Cu")
		(net "UPI_CPU0_CPU1_P2P2_DN<13>")
	)
	(segment
		(start 345.218766 -283.205682)
		(end 345.218766 -283.219906)
		(width 0.0889)
		(layer "In6.Cu")
		(net "UPI_CPU0_CPU1_P2P2_DN<13>")
	)
	(segment
		(start 346.628466 -279.141682)
		(end 346.628466 -279.160224)
		(width 0.0889)
		(layer "In6.Cu")
		(net "UPI_CPU0_CPU1_P2P2_DN<13>")
	)
	(segment
		(start 97.558098 -289.114738)
		(end 97.558098 -288.898584)
		(width 0.0889)
		(layer "In6.Cu")
		(net "UPI_CPU0_CPU1_P2P2_DN<13>")
	)
	(segment
		(start 102.256844 -275.8948)
		(end 102.256844 -275.880576)
		(width 0.0889)
		(layer "In6.Cu")
		(net "UPI_CPU0_CPU1_P2P2_DN<13>")
	)
	(segment
		(start 98.783394 -286.79775)
		(end 98.788982 -286.794702)
		(width 0.0889)
		(layer "In6.Cu")
		(net "UPI_CPU0_CPU1_P2P2_DN<13>")
	)
	(segment
		(start 305.824382 -332.55204)
		(end 284.97149 -332.55204)
		(width 0.14732)
		(layer "In6.Cu")
		(net "UPI_CPU0_CPU1_P2P2_DN<13>")
	)
	(segment
		(start 99.815396 -282.081478)
		(end 99.800664 -282.090114)
		(width 0.0889)
		(layer "In6.Cu")
		(net "UPI_CPU0_CPU1_P2P2_DN<13>")
	)
	(segment
		(start 67.268598 -334.801972)
		(end 67.916298 -328.228706)
		(width 0.14732)
		(layer "In6.Cu")
		(net "UPI_CPU0_CPU1_P2P2_DN<13>")
	)
	(arc
		(start 99.258882 -284.353)
		(mid 99.389796 -284.21664)
		(end 99.437444 -284.033722)
		(width 0.0889)
		(layer "In6.Cu")
		(net "UPI_CPU0_CPU1_P2P2_DN<13>")
	)
	(arc
		(start 100.198682 -282.725114)
		(mid 100.326493 -282.594021)
		(end 100.37699 -282.418028)
		(width 0.0889)
		(layer "In6.Cu")
		(net "UPI_CPU0_CPU1_P2P2_DN<13>")
	)
	(arc
		(start 98.788982 -286.794702)
		(mid 98.967579 -286.475424)
		(end 98.788982 -286.156146)
		(width 0.0889)
		(layer "In6.Cu")
		(net "UPI_CPU0_CPU1_P2P2_DN<13>")
	)
	(arc
		(start 98.497644 -285.661354)
		(mid 98.571635 -285.381788)
		(end 98.77425 -285.175452)
		(width 0.0889)
		(layer "In6.Cu")
		(net "UPI_CPU0_CPU1_P2P2_DN<13>")
	)
	(arc
		(start 99.907598 -279.94864)
		(mid 99.986968 -279.674906)
		(end 100.189792 -279.474676)
		(width 0.0889)
		(layer "In6.Cu")
		(net "UPI_CPU0_CPU1_P2P2_DN<13>")
	)
	(arc
		(start 344.936064 -282.730194)
		(mid 345.139545 -282.930998)
		(end 345.218766 -283.205682)
		(width 0.0889)
		(layer "In6.Cu")
		(net "UPI_CPU0_CPU1_P2P2_DN<13>")
	)
	(arc
		(start 345.397328 -281.272742)
		(mid 345.266414 -281.409102)
		(end 345.218766 -281.59202)
		(width 0.0889)
		(layer "In6.Cu")
		(net "UPI_CPU0_CPU1_P2P2_DN<13>")
	)
	(arc
		(start 98.027998 -288.087562)
		(mid 98.107368 -287.813828)
		(end 98.310192 -287.613598)
		(width 0.0889)
		(layer "In6.Cu")
		(net "UPI_CPU0_CPU1_P2P2_DN<13>")
	)
	(arc
		(start 100.189792 -282.081478)
		(mid 100.002594 -282.031335)
		(end 99.815396 -282.081478)
		(width 0.0889)
		(layer "In6.Cu")
		(net "UPI_CPU0_CPU1_P2P2_DN<13>")
	)
	(arc
		(start 100.37699 -282.418028)
		(mid 100.377157 -282.406852)
		(end 100.37699 -282.395676)
		(width 0.0889)
		(layer "In6.Cu")
		(net "UPI_CPU0_CPU1_P2P2_DN<13>")
	)
	(arc
		(start 99.437444 -280.76398)
		(mid 99.516663 -280.489295)
		(end 99.720146 -280.288492)
		(width 0.0889)
		(layer "In6.Cu")
		(net "UPI_CPU0_CPU1_P2P2_DN<13>")
	)
	(arc
		(start 343.047828 -288.597848)
		(mid 342.916914 -288.734208)
		(end 342.869266 -288.917126)
		(width 0.0889)
		(layer "In6.Cu")
		(net "UPI_CPU0_CPU1_P2P2_DN<13>")
	)
	(arc
		(start 351.13214 -279.092914)
		(mid 351.073984 -278.942801)
		(end 350.95815 -278.83104)
		(width 0.0889)
		(layer "In6.Cu")
		(net "UPI_CPU0_CPU1_P2P2_DN<13>")
	)
	(arc
		(start 98.967798 -281.576526)
		(mid 99.047168 -281.302792)
		(end 99.249992 -281.102562)
		(width 0.0889)
		(layer "In6.Cu")
		(net "UPI_CPU0_CPU1_P2P2_DN<13>")
	)
	(arc
		(start 345.218766 -281.59202)
		(mid 345.144775 -281.871586)
		(end 344.94216 -282.077922)
		(width 0.0889)
		(layer "In6.Cu")
		(net "UPI_CPU0_CPU1_P2P2_DN<13>")
	)
	(arc
		(start 101.317044 -277.522432)
		(mid 101.389279 -277.245908)
		(end 101.587554 -277.040086)
		(width 0.0889)
		(layer "In6.Cu")
		(net "UPI_CPU0_CPU1_P2P2_DN<13>")
	)
	(arc
		(start 99.800664 -282.090114)
		(mid 99.524189 -282.157434)
		(end 99.249992 -282.081478)
		(width 0.0889)
		(layer "In6.Cu")
		(net "UPI_CPU0_CPU1_P2P2_DN<13>")
	)
	(arc
		(start 349.069914 -278.82596)
		(mid 348.882716 -278.775817)
		(end 348.695518 -278.82596)
		(width 0.0889)
		(layer "In6.Cu")
		(net "UPI_CPU0_CPU1_P2P2_DN<13>")
	)
	(arc
		(start 346.815664 -278.82596)
		(mid 346.680731 -278.959314)
		(end 346.628466 -279.141682)
		(width 0.0889)
		(layer "In6.Cu")
		(net "UPI_CPU0_CPU1_P2P2_DN<13>")
	)
	(arc
		(start 101.599746 -277.032974)
		(mid 101.734679 -276.89962)
		(end 101.786944 -276.717252)
		(width 0.0889)
		(layer "In6.Cu")
		(net "UPI_CPU0_CPU1_P2P2_DN<13>")
	)
	(arc
		(start 343.339166 -288.121598)
		(mid 343.259004 -288.393787)
		(end 343.056718 -288.592768)
		(width 0.0889)
		(layer "In6.Cu")
		(net "UPI_CPU0_CPU1_P2P2_DN<13>")
	)
	(arc
		(start 99.720146 -283.544264)
		(mid 99.855079 -283.41091)
		(end 99.907344 -283.228542)
		(width 0.0889)
		(layer "In6.Cu")
		(net "UPI_CPU0_CPU1_P2P2_DN<13>")
	)
	(arc
		(start 346.337128 -279.644856)
		(mid 346.206214 -279.781216)
		(end 346.158566 -279.964134)
		(width 0.0889)
		(layer "In6.Cu")
		(net "UPI_CPU0_CPU1_P2P2_DN<13>")
	)
	(arc
		(start 99.258882 -281.097482)
		(mid 99.389796 -280.961122)
		(end 99.437444 -280.778204)
		(width 0.0889)
		(layer "In6.Cu")
		(net "UPI_CPU0_CPU1_P2P2_DN<13>")
	)
	(arc
		(start 98.497644 -287.279334)
		(mid 98.575755 -287.002385)
		(end 98.780092 -286.799782)
		(width 0.0889)
		(layer "In6.Cu")
		(net "UPI_CPU0_CPU1_P2P2_DN<13>")
	)
	(arc
		(start 343.996264 -285.985712)
		(mid 344.199745 -286.186516)
		(end 344.278966 -286.4612)
		(width 0.0889)
		(layer "In6.Cu")
		(net "UPI_CPU0_CPU1_P2P2_DN<13>")
	)
	(arc
		(start 99.907344 -283.201364)
		(mid 99.987506 -282.929175)
		(end 100.189792 -282.730194)
		(width 0.0889)
		(layer "In6.Cu")
		(net "UPI_CPU0_CPU1_P2P2_DN<13>")
	)
	(arc
		(start 343.517728 -287.783778)
		(mid 343.386814 -287.920138)
		(end 343.339166 -288.103056)
		(width 0.0889)
		(layer "In6.Cu")
		(net "UPI_CPU0_CPU1_P2P2_DN<13>")
	)
	(arc
		(start 97.558098 -288.898584)
		(mid 97.63826 -288.626395)
		(end 97.840546 -288.427414)
		(width 0.0889)
		(layer "In6.Cu")
		(net "UPI_CPU0_CPU1_P2P2_DN<13>")
	)
	(arc
		(start 102.548436 -275.400008)
		(mid 102.664175 -275.288184)
		(end 102.722426 -275.138134)
		(width 0.0889)
		(layer "In6.Cu")
		(net "UPI_CPU0_CPU1_P2P2_DN<13>")
	)
	(arc
		(start 343.808812 -287.304734)
		(mid 343.729442 -287.578468)
		(end 343.526618 -287.778698)
		(width 0.0889)
		(layer "In6.Cu")
		(net "UPI_CPU0_CPU1_P2P2_DN<13>")
	)
	(arc
		(start 345.866974 -280.458926)
		(mid 345.73606 -280.595286)
		(end 345.688412 -280.778204)
		(width 0.0889)
		(layer "In6.Cu")
		(net "UPI_CPU0_CPU1_P2P2_DN<13>")
	)
	(arc
		(start 98.027744 -289.645852)
		(mid 97.952739 -289.530393)
		(end 97.843594 -289.446462)
		(width 0.0889)
		(layer "In6.Cu")
		(net "UPI_CPU0_CPU1_P2P2_DN<13>")
	)
	(arc
		(start 100.377244 -279.150318)
		(mid 100.449479 -278.873794)
		(end 100.647754 -278.667972)
		(width 0.0889)
		(layer "In6.Cu")
		(net "UPI_CPU0_CPU1_P2P2_DN<13>")
	)
	(arc
		(start 99.729036 -280.283412)
		(mid 99.85995 -280.147052)
		(end 99.907598 -279.964134)
		(width 0.0889)
		(layer "In6.Cu")
		(net "UPI_CPU0_CPU1_P2P2_DN<13>")
	)
	(arc
		(start 345.218766 -283.219906)
		(mid 345.144775 -283.499472)
		(end 344.94216 -283.705808)
		(width 0.0889)
		(layer "In6.Cu")
		(net "UPI_CPU0_CPU1_P2P2_DN<13>")
	)
	(arc
		(start 349.635064 -278.82596)
		(mid 349.358505 -278.901703)
		(end 349.080328 -278.832056)
		(width 0.0889)
		(layer "In6.Cu")
		(net "UPI_CPU0_CPU1_P2P2_DN<13>")
	)
	(arc
		(start 346.158566 -279.978358)
		(mid 346.079347 -280.253043)
		(end 345.875864 -280.453846)
		(width 0.0889)
		(layer "In6.Cu")
		(net "UPI_CPU0_CPU1_P2P2_DN<13>")
	)
	(arc
		(start 345.688412 -280.793698)
		(mid 345.609042 -281.067432)
		(end 345.406218 -281.267662)
		(width 0.0889)
		(layer "In6.Cu")
		(net "UPI_CPU0_CPU1_P2P2_DN<13>")
	)
	(arc
		(start 346.628466 -279.160224)
		(mid 346.550355 -279.437173)
		(end 346.346018 -279.639776)
		(width 0.0889)
		(layer "In6.Cu")
		(net "UPI_CPU0_CPU1_P2P2_DN<13>")
	)
	(arc
		(start 344.278966 -284.847538)
		(mid 344.204975 -285.127104)
		(end 344.00236 -285.33344)
		(width 0.0889)
		(layer "In6.Cu")
		(net "UPI_CPU0_CPU1_P2P2_DN<13>")
	)
	(arc
		(start 97.849436 -288.422334)
		(mid 97.98035 -288.285974)
		(end 98.027998 -288.103056)
		(width 0.0889)
		(layer "In6.Cu")
		(net "UPI_CPU0_CPU1_P2P2_DN<13>")
	)
	(arc
		(start 344.748612 -284.049216)
		(mid 344.669242 -284.32295)
		(end 344.466418 -284.52318)
		(width 0.0889)
		(layer "In6.Cu")
		(net "UPI_CPU0_CPU1_P2P2_DN<13>")
	)
	(arc
		(start 98.780092 -286.151066)
		(mid 98.577806 -285.952085)
		(end 98.497644 -285.679896)
		(width 0.0889)
		(layer "In6.Cu")
		(net "UPI_CPU0_CPU1_P2P2_DN<13>")
	)
	(arc
		(start 101.786944 -276.69871)
		(mid 101.865055 -276.421761)
		(end 102.069392 -276.219158)
		(width 0.0889)
		(layer "In6.Cu")
		(net "UPI_CPU0_CPU1_P2P2_DN<13>")
	)
	(arc
		(start 99.437444 -284.033722)
		(mid 99.511435 -283.754156)
		(end 99.71405 -283.54782)
		(width 0.0889)
		(layer "In6.Cu")
		(net "UPI_CPU0_CPU1_P2P2_DN<13>")
	)
	(arc
		(start 348.685104 -278.832056)
		(mid 348.406672 -278.901902)
		(end 348.12986 -278.82596)
		(width 0.0889)
		(layer "In6.Cu")
		(net "UPI_CPU0_CPU1_P2P2_DN<13>")
	)
	(arc
		(start 101.138482 -277.84171)
		(mid 101.269396 -277.70535)
		(end 101.317044 -277.522432)
		(width 0.0889)
		(layer "In6.Cu")
		(net "UPI_CPU0_CPU1_P2P2_DN<13>")
	)
	(arc
		(start 350.94926 -278.82596)
		(mid 350.762062 -278.775817)
		(end 350.574864 -278.82596)
		(width 0.0889)
		(layer "In6.Cu")
		(net "UPI_CPU0_CPU1_P2P2_DN<13>")
	)
	(arc
		(start 100.659946 -278.66086)
		(mid 100.794879 -278.527506)
		(end 100.847144 -278.345138)
		(width 0.0889)
		(layer "In6.Cu")
		(net "UPI_CPU0_CPU1_P2P2_DN<13>")
	)
	(arc
		(start 343.987374 -285.342076)
		(mid 343.808777 -285.661354)
		(end 343.987374 -285.980632)
		(width 0.0889)
		(layer "In6.Cu")
		(net "UPI_CPU0_CPU1_P2P2_DN<13>")
	)
	(arc
		(start 98.967798 -284.832044)
		(mid 99.047168 -284.55831)
		(end 99.249992 -284.35808)
		(width 0.0889)
		(layer "In6.Cu")
		(net "UPI_CPU0_CPU1_P2P2_DN<13>")
	)
	(arc
		(start 100.847144 -278.31796)
		(mid 100.927306 -278.045771)
		(end 101.129592 -277.84679)
		(width 0.0889)
		(layer "In6.Cu")
		(net "UPI_CPU0_CPU1_P2P2_DN<13>")
	)
	(arc
		(start 350.560132 -278.834596)
		(mid 350.283657 -278.901916)
		(end 350.00946 -278.82596)
		(width 0.0889)
		(layer "In6.Cu")
		(net "UPI_CPU0_CPU1_P2P2_DN<13>")
	)
	(arc
		(start 348.12986 -278.82596)
		(mid 347.942662 -278.775817)
		(end 347.755464 -278.82596)
		(width 0.0889)
		(layer "In6.Cu")
		(net "UPI_CPU0_CPU1_P2P2_DN<13>")
	)
	(arc
		(start 102.078282 -276.214078)
		(mid 102.209196 -276.077718)
		(end 102.256844 -275.8948)
		(width 0.0889)
		(layer "In6.Cu")
		(net "UPI_CPU0_CPU1_P2P2_DN<13>")
	)
	(arc
		(start 350.00946 -278.82596)
		(mid 349.822262 -278.775817)
		(end 349.635064 -278.82596)
		(width 0.0889)
		(layer "In6.Cu")
		(net "UPI_CPU0_CPU1_P2P2_DN<13>")
	)
	(arc
		(start 343.987374 -286.969962)
		(mid 343.85646 -287.106322)
		(end 343.808812 -287.28924)
		(width 0.0889)
		(layer "In6.Cu")
		(net "UPI_CPU0_CPU1_P2P2_DN<13>")
	)
	(arc
		(start 102.256844 -275.880576)
		(mid 102.336063 -275.605891)
		(end 102.539546 -275.405088)
		(width 0.0889)
		(layer "In6.Cu")
		(net "UPI_CPU0_CPU1_P2P2_DN<13>")
	)
	(arc
		(start 97.843594 -289.446462)
		(mid 97.669462 -289.307615)
		(end 97.558098 -289.114738)
		(width 0.0889)
		(layer "In6.Cu")
		(net "UPI_CPU0_CPU1_P2P2_DN<13>")
	)
	(arc
		(start 344.927174 -282.086558)
		(mid 344.748577 -282.405836)
		(end 344.927174 -282.725114)
		(width 0.0889)
		(layer "In6.Cu")
		(net "UPI_CPU0_CPU1_P2P2_DN<13>")
	)
	(arc
		(start 347.740732 -278.834596)
		(mid 347.464257 -278.901916)
		(end 347.19006 -278.82596)
		(width 0.0889)
		(layer "In6.Cu")
		(net "UPI_CPU0_CPU1_P2P2_DN<13>")
	)
	(arc
		(start 342.869266 -289.114484)
		(mid 342.75787 -289.307577)
		(end 342.583516 -289.446462)
		(width 0.0889)
		(layer "In6.Cu")
		(net "UPI_CPU0_CPU1_P2P2_DN<13>")
	)
	(arc
		(start 344.278966 -286.475424)
		(mid 344.204975 -286.75499)
		(end 344.00236 -286.961326)
		(width 0.0889)
		(layer "In6.Cu")
		(net "UPI_CPU0_CPU1_P2P2_DN<13>")
	)
	(arc
		(start 347.19006 -278.82596)
		(mid 347.002862 -278.775817)
		(end 346.815664 -278.82596)
		(width 0.0889)
		(layer "In6.Cu")
		(net "UPI_CPU0_CPU1_P2P2_DN<13>")
	)
	(arc
		(start 344.457528 -284.52826)
		(mid 344.326614 -284.66462)
		(end 344.278966 -284.847538)
		(width 0.0889)
		(layer "In6.Cu")
		(net "UPI_CPU0_CPU1_P2P2_DN<13>")
	)
	(arc
		(start 342.583516 -289.446462)
		(mid 342.47412 -289.530559)
		(end 342.399112 -289.64636)
		(width 0.0889)
		(layer "In6.Cu")
		(net "UPI_CPU0_CPU1_P2P2_DN<13>")
	)
	(arc
		(start 98.789236 -285.166816)
		(mid 98.92015 -285.030456)
		(end 98.967798 -284.847538)
		(width 0.0889)
		(layer "In6.Cu")
		(net "UPI_CPU0_CPU1_P2P2_DN<13>")
	)
	(arc
		(start 99.249992 -282.081478)
		(mid 99.047169 -281.881247)
		(end 98.967798 -281.607514)
		(width 0.0889)
		(layer "In6.Cu")
		(net "UPI_CPU0_CPU1_P2P2_DN<13>")
	)
	(arc
		(start 344.927174 -283.714444)
		(mid 344.79626 -283.850804)
		(end 344.748612 -284.033722)
		(width 0.0889)
		(layer "In6.Cu")
		(net "UPI_CPU0_CPU1_P2P2_DN<13>")
	)
	(arc
		(start 100.37699 -282.395676)
		(mid 100.326975 -282.218545)
		(end 100.198682 -282.086558)
		(width 0.0889)
		(layer "In6.Cu")
		(net "UPI_CPU0_CPU1_P2P2_DN<13>")
	)
	(arc
		(start 98.319082 -287.608518)
		(mid 98.449996 -287.472158)
		(end 98.497644 -287.28924)
		(width 0.0889)
		(layer "In6.Cu")
		(net "UPI_CPU0_CPU1_P2P2_DN<13>")
	)
	(arc
		(start 100.198682 -279.469596)
		(mid 100.329596 -279.333236)
		(end 100.377244 -279.150318)
		(width 0.0889)
		(layer "In6.Cu")
		(net "UPI_CPU0_CPU1_P2P2_DN<13>")
	)
	(segment
		(start 103.762048 -273.730974)
		(end 103.761794 -273.731228)
		(width 0.13208)
		(layer "F.Cu")
		(net "UPI_CPU0_CPU1_P2P2_DN<12>")
	)
	(segment
		(start 103.761794 -273.731228)
		(end 103.761794 -274.266914)
		(width 0.13208)
		(layer "F.Cu")
		(net "UPI_CPU0_CPU1_P2P2_DN<12>")
	)
	(segment
		(start 349.822516 -279.150064)
		(end 349.822262 -279.150318)
		(width 0.13208)
		(layer "F.Cu")
		(net "UPI_CPU0_CPU1_P2P2_DN<12>")
	)
	(segment
		(start 349.822516 -278.614378)
		(end 349.822516 -279.150064)
		(width 0.13208)
		(layer "F.Cu")
		(net "UPI_CPU0_CPU1_P2P2_DN<12>")
	)
	(segment
		(start 99.72167 -278.660098)
		(end 99.729036 -278.65578)
		(width 0.0889)
		(layer "In6.Cu")
		(net "UPI_CPU0_CPU1_P2P2_DN<12>")
	)
	(segment
		(start 70.824852 -364.827566)
		(end 66.435478 -354.230178)
		(width 0.14732)
		(layer "In6.Cu")
		(net "UPI_CPU0_CPU1_P2P2_DN<12>")
	)
	(segment
		(start 99.720146 -278.66086)
		(end 99.72167 -278.660098)
		(width 0.0889)
		(layer "In6.Cu")
		(net "UPI_CPU0_CPU1_P2P2_DN<12>")
	)
	(segment
		(start 97.840546 -285.171896)
		(end 97.849436 -285.166816)
		(width 0.0889)
		(layer "In6.Cu")
		(net "UPI_CPU0_CPU1_P2P2_DN<12>")
	)
	(segment
		(start 103.897176 -274.61591)
		(end 103.918258 -274.537932)
		(width 0.0889)
		(layer "In6.Cu")
		(net "UPI_CPU0_CPU1_P2P2_DN<12>")
	)
	(segment
		(start 343.996518 -288.592768)
		(end 343.987628 -288.597848)
		(width 0.0889)
		(layer "In6.Cu")
		(net "UPI_CPU0_CPU1_P2P2_DN<12>")
	)
	(segment
		(start 162.014916 -382.699768)
		(end 125.485652 -382.699768)
		(width 0.14732)
		(layer "In6.Cu")
		(net "UPI_CPU0_CPU1_P2P2_DN<12>")
	)
	(segment
		(start 66.435478 -354.230178)
		(end 66.435478 -334.783176)
		(width 0.14732)
		(layer "In6.Cu")
		(net "UPI_CPU0_CPU1_P2P2_DN<12>")
	)
	(segment
		(start 78.090268 -313.013598)
		(end 93.440758 -300.416722)
		(width 0.14732)
		(layer "In6.Cu")
		(net "UPI_CPU0_CPU1_P2P2_DN<12>")
	)
	(segment
		(start 346.345002 -281.91587)
		(end 346.346018 -281.916378)
		(width 0.0889)
		(layer "In6.Cu")
		(net "UPI_CPU0_CPU1_P2P2_DN<12>")
	)
	(segment
		(start 349.635064 -280.453846)
		(end 349.620332 -280.462482)
		(width 0.0889)
		(layer "In6.Cu")
		(net "UPI_CPU0_CPU1_P2P2_DN<12>")
	)
	(segment
		(start 346.628212 -282.390342)
		(end 346.628212 -282.424378)
		(width 0.0889)
		(layer "In6.Cu")
		(net "UPI_CPU0_CPU1_P2P2_DN<12>")
	)
	(segment
		(start 125.485652 -382.699768)
		(end 97.045272 -378.481082)
		(width 0.14732)
		(layer "In6.Cu")
		(net "UPI_CPU0_CPU1_P2P2_DN<12>")
	)
	(segment
		(start 336.992214 -302.034194)
		(end 315.11875 -323.907658)
		(width 0.14732)
		(layer "In6.Cu")
		(net "UPI_CPU0_CPU1_P2P2_DN<12>")
	)
	(segment
		(start 99.71405 -277.03653)
		(end 99.735386 -277.024338)
		(width 0.0889)
		(layer "In6.Cu")
		(net "UPI_CPU0_CPU1_P2P2_DN<12>")
	)
	(segment
		(start 344.748612 -287.28924)
		(end 344.748612 -287.304734)
		(width 0.0889)
		(layer "In6.Cu")
		(net "UPI_CPU0_CPU1_P2P2_DN<12>")
	)
	(segment
		(start 98.027998 -284.847538)
		(end 98.027998 -284.832044)
		(width 0.0889)
		(layer "In6.Cu")
		(net "UPI_CPU0_CPU1_P2P2_DN<12>")
	)
	(segment
		(start 350.560132 -279.46604)
		(end 350.574864 -279.474676)
		(width 0.0889)
		(layer "In6.Cu")
		(net "UPI_CPU0_CPU1_P2P2_DN<12>")
	)
	(segment
		(start 344.948256 -286.95777)
		(end 344.936064 -286.964882)
		(width 0.0889)
		(layer "In6.Cu")
		(net "UPI_CPU0_CPU1_P2P2_DN<12>")
	)
	(segment
		(start 101.317044 -275.903436)
		(end 101.317044 -275.880576)
		(width 0.0889)
		(layer "In6.Cu")
		(net "UPI_CPU0_CPU1_P2P2_DN<12>")
	)
	(segment
		(start 345.406218 -284.52318)
		(end 345.397328 -284.52826)
		(width 0.0889)
		(layer "In6.Cu")
		(net "UPI_CPU0_CPU1_P2P2_DN<12>")
	)
	(segment
		(start 98.780346 -280.288492)
		(end 98.789236 -280.283412)
		(width 0.0889)
		(layer "In6.Cu")
		(net "UPI_CPU0_CPU1_P2P2_DN<12>")
	)
	(segment
		(start 97.088198 -288.103056)
		(end 97.088198 -288.087562)
		(width 0.0889)
		(layer "In6.Cu")
		(net "UPI_CPU0_CPU1_P2P2_DN<12>")
	)
	(segment
		(start 345.875864 -283.709364)
		(end 345.866974 -283.714444)
		(width 0.0889)
		(layer "In6.Cu")
		(net "UPI_CPU0_CPU1_P2P2_DN<12>")
	)
	(segment
		(start 102.620064 -274.582636)
		(end 102.62108 -274.583398)
		(width 0.0889)
		(layer "In6.Cu")
		(net "UPI_CPU0_CPU1_P2P2_DN<12>")
	)
	(segment
		(start 99.437444 -277.536656)
		(end 99.437444 -277.522432)
		(width 0.0889)
		(layer "In6.Cu")
		(net "UPI_CPU0_CPU1_P2P2_DN<12>")
	)
	(segment
		(start 344.94216 -285.33344)
		(end 344.936064 -285.336996)
		(width 0.0889)
		(layer "In6.Cu")
		(net "UPI_CPU0_CPU1_P2P2_DN<12>")
	)
	(segment
		(start 75.593194 -369.595908)
		(end 70.824852 -364.827566)
		(width 0.14732)
		(layer "In6.Cu")
		(net "UPI_CPU0_CPU1_P2P2_DN<12>")
	)
	(segment
		(start 96.867726 -290.30422)
		(end 96.926654 -290.30422)
		(width 0.0889)
		(layer "In6.Cu")
		(net "UPI_CPU0_CPU1_P2P2_DN<12>")
	)
	(segment
		(start 98.310192 -281.102562)
		(end 98.319082 -281.097482)
		(width 0.0889)
		(layer "In6.Cu")
		(net "UPI_CPU0_CPU1_P2P2_DN<12>")
	)
	(segment
		(start 350.574864 -279.474676)
		(end 350.58096 -279.478232)
		(width 0.0889)
		(layer "In6.Cu")
		(net "UPI_CPU0_CPU1_P2P2_DN<12>")
	)
	(segment
		(start 98.497644 -284.033722)
		(end 98.497644 -284.023816)
		(width 0.0889)
		(layer "In6.Cu")
		(net "UPI_CPU0_CPU1_P2P2_DN<12>")
	)
	(segment
		(start 346.628212 -280.778204)
		(end 346.628212 -280.793698)
		(width 0.0889)
		(layer "In6.Cu")
		(net "UPI_CPU0_CPU1_P2P2_DN<12>")
	)
	(segment
		(start 100.659946 -277.032974)
		(end 100.66147 -277.032212)
		(width 0.0889)
		(layer "In6.Cu")
		(net "UPI_CPU0_CPU1_P2P2_DN<12>")
	)
	(segment
		(start 314.089034 -326.392794)
		(end 307.101748 -333.38008)
		(width 0.14732)
		(layer "In6.Cu")
		(net "UPI_CPU0_CPU1_P2P2_DN<12>")
	)
	(segment
		(start 346.815664 -280.453846)
		(end 346.806774 -280.458926)
		(width 0.0889)
		(layer "In6.Cu")
		(net "UPI_CPU0_CPU1_P2P2_DN<12>")
	)
	(segment
		(start 345.688412 -284.033722)
		(end 345.688412 -284.049216)
		(width 0.0889)
		(layer "In6.Cu")
		(net "UPI_CPU0_CPU1_P2P2_DN<12>")
	)
	(segment
		(start 342.659208 -291.615114)
		(end 342.659208 -294.423084)
		(width 0.0889)
		(layer "In6.Cu")
		(net "UPI_CPU0_CPU1_P2P2_DN<12>")
	)
	(segment
		(start 342.659208 -294.423084)
		(end 342.701372 -294.465248)
		(width 0.0889)
		(layer "In6.Cu")
		(net "UPI_CPU0_CPU1_P2P2_DN<12>")
	)
	(segment
		(start 93.952822 -299.72635)
		(end 95.031052 -297.123104)
		(width 0.14732)
		(layer "In6.Cu")
		(net "UPI_CPU0_CPU1_P2P2_DN<12>")
	)
	(segment
		(start 100.66147 -277.032212)
		(end 100.668836 -277.027894)
		(width 0.0889)
		(layer "In6.Cu")
		(net "UPI_CPU0_CPU1_P2P2_DN<12>")
	)
	(segment
		(start 99.735386 -277.024338)
		(end 99.734878 -277.024338)
		(width 0.0889)
		(layer "In6.Cu")
		(net "UPI_CPU0_CPU1_P2P2_DN<12>")
	)
	(segment
		(start 264.76325 -373.948706)
		(end 162.014916 -382.699768)
		(width 0.14732)
		(layer "In6.Cu")
		(net "UPI_CPU0_CPU1_P2P2_DN<12>")
	)
	(segment
		(start 341.774018 -299.259752)
		(end 340.417658 -300.616112)
		(width 0.14732)
		(layer "In6.Cu")
		(net "UPI_CPU0_CPU1_P2P2_DN<12>")
	)
	(segment
		(start 67.095116 -328.083418)
		(end 68.01739 -324.751954)
		(width 0.14732)
		(layer "In6.Cu")
		(net "UPI_CPU0_CPU1_P2P2_DN<12>")
	)
	(segment
		(start 342.701372 -297.020234)
		(end 341.774018 -299.259752)
		(width 0.14732)
		(layer "In6.Cu")
		(net "UPI_CPU0_CPU1_P2P2_DN<12>")
	)
	(segment
		(start 97.839784 -286.80029)
		(end 97.840546 -286.799782)
		(width 0.0889)
		(layer "In6.Cu")
		(net "UPI_CPU0_CPU1_P2P2_DN<12>")
	)
	(segment
		(start 68.01739 -324.751954)
		(end 69.510656 -321.593464)
		(width 0.14732)
		(layer "In6.Cu")
		(net "UPI_CPU0_CPU1_P2P2_DN<12>")
	)
	(segment
		(start 93.440758 -300.416722)
		(end 93.952822 -299.72635)
		(width 0.14732)
		(layer "In6.Cu")
		(net "UPI_CPU0_CPU1_P2P2_DN<12>")
	)
	(segment
		(start 315.11875 -323.907658)
		(end 314.089034 -326.392794)
		(width 0.14732)
		(layer "In6.Cu")
		(net "UPI_CPU0_CPU1_P2P2_DN<12>")
	)
	(segment
		(start 345.218766 -286.467804)
		(end 345.218766 -286.475424)
		(width 0.0889)
		(layer "In6.Cu")
		(net "UPI_CPU0_CPU1_P2P2_DN<12>")
	)
	(segment
		(start 344.936064 -286.964882)
		(end 344.927174 -286.969962)
		(width 0.0889)
		(layer "In6.Cu")
		(net "UPI_CPU0_CPU1_P2P2_DN<12>")
	)
	(segment
		(start 270.451072 -344.82278)
		(end 270.451072 -368.260884)
		(width 0.14732)
		(layer "In6.Cu")
		(net "UPI_CPU0_CPU1_P2P2_DN<12>")
	)
	(segment
		(start 98.967798 -279.964134)
		(end 98.967798 -279.94864)
		(width 0.0889)
		(layer "In6.Cu")
		(net "UPI_CPU0_CPU1_P2P2_DN<12>")
	)
	(segment
		(start 98.783394 -283.542232)
		(end 98.788982 -283.539184)
		(width 0.0889)
		(layer "In6.Cu")
		(net "UPI_CPU0_CPU1_P2P2_DN<12>")
	)
	(segment
		(start 346.345764 -282.895548)
		(end 346.336874 -282.900628)
		(width 0.0889)
		(layer "In6.Cu")
		(net "UPI_CPU0_CPU1_P2P2_DN<12>")
	)
	(segment
		(start 344.466418 -287.778698)
		(end 344.457528 -287.783778)
		(width 0.0889)
		(layer "In6.Cu")
		(net "UPI_CPU0_CPU1_P2P2_DN<12>")
	)
	(segment
		(start 343.809066 -288.917126)
		(end 343.809066 -289.078416)
		(width 0.0889)
		(layer "In6.Cu")
		(net "UPI_CPU0_CPU1_P2P2_DN<12>")
	)
	(segment
		(start 101.787198 -275.08073)
		(end 101.787198 -275.065236)
		(width 0.0889)
		(layer "In6.Cu")
		(net "UPI_CPU0_CPU1_P2P2_DN<12>")
	)
	(segment
		(start 99.249992 -279.474676)
		(end 99.258882 -279.469596)
		(width 0.0889)
		(layer "In6.Cu")
		(net "UPI_CPU0_CPU1_P2P2_DN<12>")
	)
	(segment
		(start 96.618552 -288.898076)
		(end 96.618298 -288.898584)
		(width 0.0889)
		(layer "In6.Cu")
		(net "UPI_CPU0_CPU1_P2P2_DN<12>")
	)
	(segment
		(start 69.510656 -321.593464)
		(end 78.090268 -313.013598)
		(width 0.14732)
		(layer "In6.Cu")
		(net "UPI_CPU0_CPU1_P2P2_DN<12>")
	)
	(segment
		(start 344.278966 -288.103056)
		(end 344.278966 -288.121598)
		(width 0.0889)
		(layer "In6.Cu")
		(net "UPI_CPU0_CPU1_P2P2_DN<12>")
	)
	(segment
		(start 96.852232 -290.319714)
		(end 96.867726 -290.30422)
		(width 0.0889)
		(layer "In6.Cu")
		(net "UPI_CPU0_CPU1_P2P2_DN<12>")
	)
	(segment
		(start 342.701372 -294.465248)
		(end 342.701372 -294.487346)
		(width 0.0889)
		(layer "In6.Cu")
		(net "UPI_CPU0_CPU1_P2P2_DN<12>")
	)
	(segment
		(start 95.031052 -292.140894)
		(end 96.852232 -290.319714)
		(width 0.14732)
		(layer "In6.Cu")
		(net "UPI_CPU0_CPU1_P2P2_DN<12>")
	)
	(segment
		(start 98.027998 -281.607514)
		(end 98.027998 -281.576526)
		(width 0.0889)
		(layer "In6.Cu")
		(net "UPI_CPU0_CPU1_P2P2_DN<12>")
	)
	(segment
		(start 98.780092 -283.544264)
		(end 98.780854 -283.543756)
		(width 0.0889)
		(layer "In6.Cu")
		(net "UPI_CPU0_CPU1_P2P2_DN<12>")
	)
	(segment
		(start 344.927174 -285.980632)
		(end 344.935302 -285.985204)
		(width 0.0889)
		(layer "In6.Cu")
		(net "UPI_CPU0_CPU1_P2P2_DN<12>")
	)
	(segment
		(start 98.310192 -284.35808)
		(end 98.319082 -284.353)
		(width 0.0889)
		(layer "In6.Cu")
		(net "UPI_CPU0_CPU1_P2P2_DN<12>")
	)
	(segment
		(start 344.936064 -285.336996)
		(end 344.927174 -285.342076)
		(width 0.0889)
		(layer "In6.Cu")
		(net "UPI_CPU0_CPU1_P2P2_DN<12>")
	)
	(segment
		(start 100.847398 -276.708616)
		(end 100.847398 -276.69871)
		(width 0.0889)
		(layer "In6.Cu")
		(net "UPI_CPU0_CPU1_P2P2_DN<12>")
	)
	(segment
		(start 97.83445 -285.175452)
		(end 97.840546 -285.171896)
		(width 0.0889)
		(layer "In6.Cu")
		(net "UPI_CPU0_CPU1_P2P2_DN<12>")
	)
	(segment
		(start 307.101748 -333.38008)
		(end 285.177738 -333.38008)
		(width 0.14732)
		(layer "In6.Cu")
		(net "UPI_CPU0_CPU1_P2P2_DN<12>")
	)
	(segment
		(start 344.278712 -289.60953)
		(end 344.278712 -289.817048)
		(width 0.0889)
		(layer "In6.Cu")
		(net "UPI_CPU0_CPU1_P2P2_DN<12>")
	)
	(segment
		(start 97.83445 -286.803338)
		(end 97.839784 -286.80029)
		(width 0.0889)
		(layer "In6.Cu")
		(net "UPI_CPU0_CPU1_P2P2_DN<12>")
	)
	(segment
		(start 97.045272 -378.481082)
		(end 75.593194 -369.595908)
		(width 0.14732)
		(layer "In6.Cu")
		(net "UPI_CPU0_CPU1_P2P2_DN<12>")
	)
	(segment
		(start 270.451072 -368.260884)
		(end 264.76325 -373.948706)
		(width 0.14732)
		(layer "In6.Cu")
		(net "UPI_CPU0_CPU1_P2P2_DN<12>")
	)
	(segment
		(start 344.935302 -285.985204)
		(end 344.936064 -285.985712)
		(width 0.0889)
		(layer "In6.Cu")
		(net "UPI_CPU0_CPU1_P2P2_DN<12>")
	)
	(segment
		(start 99.719384 -278.661368)
		(end 99.720146 -278.66086)
		(width 0.0889)
		(layer "In6.Cu")
		(net "UPI_CPU0_CPU1_P2P2_DN<12>")
	)
	(segment
		(start 348.695264 -280.453846)
		(end 348.680532 -280.462482)
		(width 0.0889)
		(layer "In6.Cu")
		(net "UPI_CPU0_CPU1_P2P2_DN<12>")
	)
	(segment
		(start 98.780854 -283.543756)
		(end 98.783394 -283.542232)
		(width 0.0889)
		(layer "In6.Cu")
		(net "UPI_CPU0_CPU1_P2P2_DN<12>")
	)
	(segment
		(start 97.370392 -287.613598)
		(end 97.379282 -287.608518)
		(width 0.0889)
		(layer "In6.Cu")
		(net "UPI_CPU0_CPU1_P2P2_DN<12>")
	)
	(segment
		(start 99.729036 -278.017224)
		(end 99.720146 -278.012144)
		(width 0.0889)
		(layer "In6.Cu")
		(net "UPI_CPU0_CPU1_P2P2_DN<12>")
	)
	(segment
		(start 95.031052 -297.123104)
		(end 95.031052 -292.140894)
		(width 0.14732)
		(layer "In6.Cu")
		(net "UPI_CPU0_CPU1_P2P2_DN<12>")
	)
	(segment
		(start 97.087436 -289.734498)
		(end 97.087182 -289.734498)
		(width 0.0889)
		(layer "In6.Cu")
		(net "UPI_CPU0_CPU1_P2P2_DN<12>")
	)
	(segment
		(start 97.08896 -290.141914)
		(end 97.08896 -289.914584)
		(width 0.0889)
		(layer "In6.Cu")
		(net "UPI_CPU0_CPU1_P2P2_DN<12>")
	)
	(segment
		(start 346.158312 -283.219906)
		(end 346.158312 -283.229812)
		(width 0.0889)
		(layer "In6.Cu")
		(net "UPI_CPU0_CPU1_P2P2_DN<12>")
	)
	(segment
		(start 342.701372 -294.487346)
		(end 342.701372 -297.020234)
		(width 0.14732)
		(layer "In6.Cu")
		(net "UPI_CPU0_CPU1_P2P2_DN<12>")
	)
	(segment
		(start 98.319082 -282.086558)
		(end 98.310192 -282.081478)
		(width 0.0889)
		(layer "In6.Cu")
		(net "UPI_CPU0_CPU1_P2P2_DN<12>")
	)
	(segment
		(start 96.926654 -290.30422)
		(end 97.08896 -290.141914)
		(width 0.0889)
		(layer "In6.Cu")
		(net "UPI_CPU0_CPU1_P2P2_DN<12>")
	)
	(segment
		(start 346.346018 -281.267662)
		(end 346.337128 -281.272742)
		(width 0.0889)
		(layer "In6.Cu")
		(net "UPI_CPU0_CPU1_P2P2_DN<12>")
	)
	(segment
		(start 97.557844 -285.675578)
		(end 97.557844 -285.661354)
		(width 0.0889)
		(layer "In6.Cu")
		(net "UPI_CPU0_CPU1_P2P2_DN<12>")
	)
	(segment
		(start 279.571704 -335.702148)
		(end 270.451072 -344.82278)
		(width 0.14732)
		(layer "In6.Cu")
		(net "UPI_CPU0_CPU1_P2P2_DN<12>")
	)
	(segment
		(start 285.177738 -333.38008)
		(end 279.571704 -335.702148)
		(width 0.14732)
		(layer "In6.Cu")
		(net "UPI_CPU0_CPU1_P2P2_DN<12>")
	)
	(segment
		(start 102.62108 -274.583398)
		(end 102.634796 -274.591272)
		(width 0.0889)
		(layer "In6.Cu")
		(net "UPI_CPU0_CPU1_P2P2_DN<12>")
	)
	(segment
		(start 343.91854 -290.355782)
		(end 342.659208 -291.615114)
		(width 0.0889)
		(layer "In6.Cu")
		(net "UPI_CPU0_CPU1_P2P2_DN<12>")
	)
	(segment
		(start 350.857566 -279.964134)
		(end 350.857566 -279.982676)
		(width 0.0889)
		(layer "In6.Cu")
		(net "UPI_CPU0_CPU1_P2P2_DN<12>")
	)
	(segment
		(start 103.918258 -274.537932)
		(end 103.761794 -274.266914)
		(width 0.0889)
		(layer "In6.Cu")
		(net "UPI_CPU0_CPU1_P2P2_DN<12>")
	)
	(segment
		(start 347.755464 -280.453846)
		(end 347.740732 -280.462482)
		(width 0.0889)
		(layer "In6.Cu")
		(net "UPI_CPU0_CPU1_P2P2_DN<12>")
	)
	(segment
		(start 98.497644 -280.778204)
		(end 98.497644 -280.76398)
		(width 0.0889)
		(layer "In6.Cu")
		(net "UPI_CPU0_CPU1_P2P2_DN<12>")
	)
	(segment
		(start 98.497644 -282.424378)
		(end 98.497644 -282.405836)
		(width 0.0889)
		(layer "In6.Cu")
		(net "UPI_CPU0_CPU1_P2P2_DN<12>")
	)
	(segment
		(start 98.788982 -282.900628)
		(end 98.780092 -282.895548)
		(width 0.0889)
		(layer "In6.Cu")
		(net "UPI_CPU0_CPU1_P2P2_DN<12>")
	)
	(segment
		(start 99.71405 -278.664416)
		(end 99.719384 -278.661368)
		(width 0.0889)
		(layer "In6.Cu")
		(net "UPI_CPU0_CPU1_P2P2_DN<12>")
	)
	(segment
		(start 97.08896 -289.914584)
		(end 97.087436 -289.734498)
		(width 0.0889)
		(layer "In6.Cu")
		(net "UPI_CPU0_CPU1_P2P2_DN<12>")
	)
	(segment
		(start 96.618552 -289.113976)
		(end 96.618552 -288.898076)
		(width 0.0889)
		(layer "In6.Cu")
		(net "UPI_CPU0_CPU1_P2P2_DN<12>")
	)
	(segment
		(start 101.599746 -275.405088)
		(end 101.608636 -275.400008)
		(width 0.0889)
		(layer "In6.Cu")
		(net "UPI_CPU0_CPU1_P2P2_DN<12>")
	)
	(segment
		(start 96.900746 -288.427414)
		(end 96.909636 -288.422334)
		(width 0.0889)
		(layer "In6.Cu")
		(net "UPI_CPU0_CPU1_P2P2_DN<12>")
	)
	(segment
		(start 346.337128 -281.911298)
		(end 346.345002 -281.91587)
		(width 0.0889)
		(layer "In6.Cu")
		(net "UPI_CPU0_CPU1_P2P2_DN<12>")
	)
	(segment
		(start 66.435478 -334.783176)
		(end 67.095116 -328.083418)
		(width 0.14732)
		(layer "In6.Cu")
		(net "UPI_CPU0_CPU1_P2P2_DN<12>")
	)
	(segment
		(start 98.027744 -286.48406)
		(end 98.027744 -286.466788)
		(width 0.0889)
		(layer "In6.Cu")
		(net "UPI_CPU0_CPU1_P2P2_DN<12>")
	)
	(segment
		(start 350.575118 -280.453846)
		(end 350.564704 -280.459942)
		(width 0.0889)
		(layer "In6.Cu")
		(net "UPI_CPU0_CPU1_P2P2_DN<12>")
	)
	(segment
		(start 349.822262 -279.150318)
		(end 349.978726 -279.421336)
		(width 0.0889)
		(layer "In6.Cu")
		(net "UPI_CPU0_CPU1_P2P2_DN<12>")
	)
	(segment
		(start 340.417658 -300.616112)
		(end 336.992214 -302.034194)
		(width 0.14732)
		(layer "In6.Cu")
		(net "UPI_CPU0_CPU1_P2P2_DN<12>")
	)
	(segment
		(start 103.573072 -274.591018)
		(end 103.639874 -274.629372)
		(width 0.0889)
		(layer "In6.Cu")
		(net "UPI_CPU0_CPU1_P2P2_DN<12>")
	)
	(segment
		(start 349.978726 -279.421336)
		(end 350.06788 -279.445212)
		(width 0.0889)
		(layer "In6.Cu")
		(net "UPI_CPU0_CPU1_P2P2_DN<12>")
	)
	(segment
		(start 103.825802 -274.643596)
		(end 103.897176 -274.61591)
		(width 0.0889)
		(layer "In6.Cu")
		(net "UPI_CPU0_CPU1_P2P2_DN<12>")
	)
	(arc
		(start 347.740732 -280.462482)
		(mid 347.464291 -280.529648)
		(end 347.19006 -280.453846)
		(width 0.0889)
		(layer "In6.Cu")
		(net "UPI_CPU0_CPU1_P2P2_DN<12>")
	)
	(arc
		(start 349.620332 -280.462482)
		(mid 349.343891 -280.529648)
		(end 349.06966 -280.453846)
		(width 0.0889)
		(layer "In6.Cu")
		(net "UPI_CPU0_CPU1_P2P2_DN<12>")
	)
	(arc
		(start 98.027998 -284.832044)
		(mid 98.107368 -284.55831)
		(end 98.310192 -284.35808)
		(width 0.0889)
		(layer "In6.Cu")
		(net "UPI_CPU0_CPU1_P2P2_DN<12>")
	)
	(arc
		(start 350.58096 -279.478232)
		(mid 350.783547 -279.684583)
		(end 350.857566 -279.964134)
		(width 0.0889)
		(layer "In6.Cu")
		(net "UPI_CPU0_CPU1_P2P2_DN<12>")
	)
	(arc
		(start 97.087182 -289.734498)
		(mid 97.057257 -289.60197)
		(end 96.975168 -289.493706)
		(width 0.0889)
		(layer "In6.Cu")
		(net "UPI_CPU0_CPU1_P2P2_DN<12>")
	)
	(arc
		(start 343.996264 -290.2966)
		(mid 343.955454 -290.323634)
		(end 343.91854 -290.355782)
		(width 0.0889)
		(layer "In6.Cu")
		(net "UPI_CPU0_CPU1_P2P2_DN<12>")
	)
	(arc
		(start 102.069392 -274.591272)
		(mid 102.343591 -274.515437)
		(end 102.620064 -274.582636)
		(width 0.0889)
		(layer "In6.Cu")
		(net "UPI_CPU0_CPU1_P2P2_DN<12>")
	)
	(arc
		(start 346.336874 -282.900628)
		(mid 346.20596 -283.036988)
		(end 346.158312 -283.219906)
		(width 0.0889)
		(layer "In6.Cu")
		(net "UPI_CPU0_CPU1_P2P2_DN<12>")
	)
	(arc
		(start 101.608636 -275.400008)
		(mid 101.73955 -275.263648)
		(end 101.787198 -275.08073)
		(width 0.0889)
		(layer "In6.Cu")
		(net "UPI_CPU0_CPU1_P2P2_DN<12>")
	)
	(arc
		(start 99.437444 -279.150318)
		(mid 99.511435 -278.870752)
		(end 99.71405 -278.664416)
		(width 0.0889)
		(layer "In6.Cu")
		(net "UPI_CPU0_CPU1_P2P2_DN<12>")
	)
	(arc
		(start 98.319082 -284.353)
		(mid 98.449996 -284.21664)
		(end 98.497644 -284.033722)
		(width 0.0889)
		(layer "In6.Cu")
		(net "UPI_CPU0_CPU1_P2P2_DN<12>")
	)
	(arc
		(start 97.557844 -285.661354)
		(mid 97.631835 -285.381788)
		(end 97.83445 -285.175452)
		(width 0.0889)
		(layer "In6.Cu")
		(net "UPI_CPU0_CPU1_P2P2_DN<12>")
	)
	(arc
		(start 343.993216 -289.277806)
		(mid 344.167348 -289.416653)
		(end 344.278712 -289.60953)
		(width 0.0889)
		(layer "In6.Cu")
		(net "UPI_CPU0_CPU1_P2P2_DN<12>")
	)
	(arc
		(start 98.967798 -279.94864)
		(mid 99.047168 -279.674906)
		(end 99.249992 -279.474676)
		(width 0.0889)
		(layer "In6.Cu")
		(net "UPI_CPU0_CPU1_P2P2_DN<12>")
	)
	(arc
		(start 97.557844 -287.28924)
		(mid 97.631835 -287.009674)
		(end 97.83445 -286.803338)
		(width 0.0889)
		(layer "In6.Cu")
		(net "UPI_CPU0_CPU1_P2P2_DN<12>")
	)
	(arc
		(start 96.618298 -288.898584)
		(mid 96.69846 -288.626395)
		(end 96.900746 -288.427414)
		(width 0.0889)
		(layer "In6.Cu")
		(net "UPI_CPU0_CPU1_P2P2_DN<12>")
	)
	(arc
		(start 345.218766 -284.847538)
		(mid 345.144775 -285.127104)
		(end 344.94216 -285.33344)
		(width 0.0889)
		(layer "In6.Cu")
		(net "UPI_CPU0_CPU1_P2P2_DN<12>")
	)
	(arc
		(start 97.840546 -286.799782)
		(mid 97.975479 -286.666428)
		(end 98.027744 -286.48406)
		(width 0.0889)
		(layer "In6.Cu")
		(net "UPI_CPU0_CPU1_P2P2_DN<12>")
	)
	(arc
		(start 343.987628 -288.597848)
		(mid 343.856714 -288.734208)
		(end 343.809066 -288.917126)
		(width 0.0889)
		(layer "In6.Cu")
		(net "UPI_CPU0_CPU1_P2P2_DN<12>")
	)
	(arc
		(start 346.337128 -281.272742)
		(mid 346.158652 -281.59202)
		(end 346.337128 -281.911298)
		(width 0.0889)
		(layer "In6.Cu")
		(net "UPI_CPU0_CPU1_P2P2_DN<12>")
	)
	(arc
		(start 102.634796 -274.591272)
		(mid 102.821994 -274.641415)
		(end 103.009192 -274.591272)
		(width 0.0889)
		(layer "In6.Cu")
		(net "UPI_CPU0_CPU1_P2P2_DN<12>")
	)
	(arc
		(start 100.28555 -277.032974)
		(mid 100.472748 -277.083117)
		(end 100.659946 -277.032974)
		(width 0.0889)
		(layer "In6.Cu")
		(net "UPI_CPU0_CPU1_P2P2_DN<12>")
	)
	(arc
		(start 100.847398 -276.69871)
		(mid 100.925509 -276.421761)
		(end 101.129846 -276.219158)
		(width 0.0889)
		(layer "In6.Cu")
		(net "UPI_CPU0_CPU1_P2P2_DN<12>")
	)
	(arc
		(start 98.027744 -286.466788)
		(mid 97.975474 -286.284423)
		(end 97.840546 -286.151066)
		(width 0.0889)
		(layer "In6.Cu")
		(net "UPI_CPU0_CPU1_P2P2_DN<12>")
	)
	(arc
		(start 98.497644 -280.76398)
		(mid 98.576863 -280.489295)
		(end 98.780346 -280.288492)
		(width 0.0889)
		(layer "In6.Cu")
		(net "UPI_CPU0_CPU1_P2P2_DN<12>")
	)
	(arc
		(start 97.849436 -285.166816)
		(mid 97.98035 -285.030456)
		(end 98.027998 -284.847538)
		(width 0.0889)
		(layer "In6.Cu")
		(net "UPI_CPU0_CPU1_P2P2_DN<12>")
	)
	(arc
		(start 101.317044 -275.880576)
		(mid 101.396263 -275.605891)
		(end 101.599746 -275.405088)
		(width 0.0889)
		(layer "In6.Cu")
		(net "UPI_CPU0_CPU1_P2P2_DN<12>")
	)
	(arc
		(start 100.668836 -277.027894)
		(mid 100.79975 -276.891534)
		(end 100.847398 -276.708616)
		(width 0.0889)
		(layer "In6.Cu")
		(net "UPI_CPU0_CPU1_P2P2_DN<12>")
	)
	(arc
		(start 347.19006 -280.453846)
		(mid 347.002862 -280.403703)
		(end 346.815664 -280.453846)
		(width 0.0889)
		(layer "In6.Cu")
		(net "UPI_CPU0_CPU1_P2P2_DN<12>")
	)
	(arc
		(start 98.497644 -284.023816)
		(mid 98.575755 -283.746867)
		(end 98.780092 -283.544264)
		(width 0.0889)
		(layer "In6.Cu")
		(net "UPI_CPU0_CPU1_P2P2_DN<12>")
	)
	(arc
		(start 97.840546 -286.151066)
		(mid 97.637065 -285.950262)
		(end 97.557844 -285.675578)
		(width 0.0889)
		(layer "In6.Cu")
		(net "UPI_CPU0_CPU1_P2P2_DN<12>")
	)
	(arc
		(start 346.346018 -281.916378)
		(mid 346.548841 -282.116609)
		(end 346.628212 -282.390342)
		(width 0.0889)
		(layer "In6.Cu")
		(net "UPI_CPU0_CPU1_P2P2_DN<12>")
	)
	(arc
		(start 99.437444 -277.522432)
		(mid 99.511435 -277.242866)
		(end 99.71405 -277.03653)
		(width 0.0889)
		(layer "In6.Cu")
		(net "UPI_CPU0_CPU1_P2P2_DN<12>")
	)
	(arc
		(start 96.975168 -289.493706)
		(mid 96.940988 -289.468087)
		(end 96.904302 -289.446208)
		(width 0.0889)
		(layer "In6.Cu")
		(net "UPI_CPU0_CPU1_P2P2_DN<12>")
	)
	(arc
		(start 98.319082 -281.097482)
		(mid 98.449996 -280.961122)
		(end 98.497644 -280.778204)
		(width 0.0889)
		(layer "In6.Cu")
		(net "UPI_CPU0_CPU1_P2P2_DN<12>")
	)
	(arc
		(start 345.218766 -286.475424)
		(mid 345.146531 -286.751948)
		(end 344.948256 -286.95777)
		(width 0.0889)
		(layer "In6.Cu")
		(net "UPI_CPU0_CPU1_P2P2_DN<12>")
	)
	(arc
		(start 350.00946 -280.453846)
		(mid 349.822262 -280.403703)
		(end 349.635064 -280.453846)
		(width 0.0889)
		(layer "In6.Cu")
		(net "UPI_CPU0_CPU1_P2P2_DN<12>")
	)
	(arc
		(start 344.748612 -287.304734)
		(mid 344.669242 -287.578468)
		(end 344.466418 -287.778698)
		(width 0.0889)
		(layer "In6.Cu")
		(net "UPI_CPU0_CPU1_P2P2_DN<12>")
	)
	(arc
		(start 343.809066 -289.078416)
		(mid 343.884071 -289.193875)
		(end 343.993216 -289.277806)
		(width 0.0889)
		(layer "In6.Cu")
		(net "UPI_CPU0_CPU1_P2P2_DN<12>")
	)
	(arc
		(start 98.310192 -282.081478)
		(mid 98.107369 -281.881247)
		(end 98.027998 -281.607514)
		(width 0.0889)
		(layer "In6.Cu")
		(net "UPI_CPU0_CPU1_P2P2_DN<12>")
	)
	(arc
		(start 345.866974 -283.714444)
		(mid 345.73606 -283.850804)
		(end 345.688412 -284.033722)
		(width 0.0889)
		(layer "In6.Cu")
		(net "UPI_CPU0_CPU1_P2P2_DN<12>")
	)
	(arc
		(start 348.680532 -280.462482)
		(mid 348.404091 -280.529648)
		(end 348.12986 -280.453846)
		(width 0.0889)
		(layer "In6.Cu")
		(net "UPI_CPU0_CPU1_P2P2_DN<12>")
	)
	(arc
		(start 350.06788 -279.445212)
		(mid 350.077874 -279.441053)
		(end 350.087946 -279.437084)
		(width 0.0889)
		(layer "In6.Cu")
		(net "UPI_CPU0_CPU1_P2P2_DN<12>")
	)
	(arc
		(start 344.457528 -287.783778)
		(mid 344.326614 -287.920138)
		(end 344.278966 -288.103056)
		(width 0.0889)
		(layer "In6.Cu")
		(net "UPI_CPU0_CPU1_P2P2_DN<12>")
	)
	(arc
		(start 345.397328 -284.52826)
		(mid 345.266414 -284.66462)
		(end 345.218766 -284.847538)
		(width 0.0889)
		(layer "In6.Cu")
		(net "UPI_CPU0_CPU1_P2P2_DN<12>")
	)
	(arc
		(start 344.278966 -288.121598)
		(mid 344.198804 -288.393787)
		(end 343.996518 -288.592768)
		(width 0.0889)
		(layer "In6.Cu")
		(net "UPI_CPU0_CPU1_P2P2_DN<12>")
	)
	(arc
		(start 98.497644 -282.405836)
		(mid 98.449965 -282.222936)
		(end 98.319082 -282.086558)
		(width 0.0889)
		(layer "In6.Cu")
		(net "UPI_CPU0_CPU1_P2P2_DN<12>")
	)
	(arc
		(start 98.788982 -283.539184)
		(mid 98.967579 -283.219906)
		(end 98.788982 -282.900628)
		(width 0.0889)
		(layer "In6.Cu")
		(net "UPI_CPU0_CPU1_P2P2_DN<12>")
	)
	(arc
		(start 101.129846 -276.219158)
		(mid 101.264779 -276.085804)
		(end 101.317044 -275.903436)
		(width 0.0889)
		(layer "In6.Cu")
		(net "UPI_CPU0_CPU1_P2P2_DN<12>")
	)
	(arc
		(start 99.729036 -278.65578)
		(mid 99.907633 -278.336502)
		(end 99.729036 -278.017224)
		(width 0.0889)
		(layer "In6.Cu")
		(net "UPI_CPU0_CPU1_P2P2_DN<12>")
	)
	(arc
		(start 97.379282 -287.608518)
		(mid 97.510196 -287.472158)
		(end 97.557844 -287.28924)
		(width 0.0889)
		(layer "In6.Cu")
		(net "UPI_CPU0_CPU1_P2P2_DN<12>")
	)
	(arc
		(start 344.927174 -285.342076)
		(mid 344.748577 -285.661354)
		(end 344.927174 -285.980632)
		(width 0.0889)
		(layer "In6.Cu")
		(net "UPI_CPU0_CPU1_P2P2_DN<12>")
	)
	(arc
		(start 344.278712 -289.817048)
		(mid 344.200601 -290.093997)
		(end 343.996264 -290.2966)
		(width 0.0889)
		(layer "In6.Cu")
		(net "UPI_CPU0_CPU1_P2P2_DN<12>")
	)
	(arc
		(start 346.628212 -280.793698)
		(mid 346.548842 -281.067432)
		(end 346.346018 -281.267662)
		(width 0.0889)
		(layer "In6.Cu")
		(net "UPI_CPU0_CPU1_P2P2_DN<12>")
	)
	(arc
		(start 349.06966 -280.453846)
		(mid 348.882462 -280.403703)
		(end 348.695264 -280.453846)
		(width 0.0889)
		(layer "In6.Cu")
		(net "UPI_CPU0_CPU1_P2P2_DN<12>")
	)
	(arc
		(start 99.720146 -278.012144)
		(mid 99.516665 -277.81134)
		(end 99.437444 -277.536656)
		(width 0.0889)
		(layer "In6.Cu")
		(net "UPI_CPU0_CPU1_P2P2_DN<12>")
	)
	(arc
		(start 96.904302 -289.446208)
		(mid 96.729913 -289.307198)
		(end 96.618552 -289.113976)
		(width 0.0889)
		(layer "In6.Cu")
		(net "UPI_CPU0_CPU1_P2P2_DN<12>")
	)
	(arc
		(start 99.258882 -279.469596)
		(mid 99.389796 -279.333236)
		(end 99.437444 -279.150318)
		(width 0.0889)
		(layer "In6.Cu")
		(net "UPI_CPU0_CPU1_P2P2_DN<12>")
	)
	(arc
		(start 98.789236 -280.283412)
		(mid 98.92015 -280.147052)
		(end 98.967798 -279.964134)
		(width 0.0889)
		(layer "In6.Cu")
		(net "UPI_CPU0_CPU1_P2P2_DN<12>")
	)
	(arc
		(start 346.628212 -282.424378)
		(mid 346.54805 -282.696567)
		(end 346.345764 -282.895548)
		(width 0.0889)
		(layer "In6.Cu")
		(net "UPI_CPU0_CPU1_P2P2_DN<12>")
	)
	(arc
		(start 348.12986 -280.453846)
		(mid 347.942662 -280.403703)
		(end 347.755464 -280.453846)
		(width 0.0889)
		(layer "In6.Cu")
		(net "UPI_CPU0_CPU1_P2P2_DN<12>")
	)
	(arc
		(start 350.564704 -280.459942)
		(mid 350.286272 -280.529756)
		(end 350.00946 -280.453846)
		(width 0.0889)
		(layer "In6.Cu")
		(net "UPI_CPU0_CPU1_P2P2_DN<12>")
	)
	(arc
		(start 350.857566 -279.982676)
		(mid 350.777404 -280.254865)
		(end 350.575118 -280.453846)
		(width 0.0889)
		(layer "In6.Cu")
		(net "UPI_CPU0_CPU1_P2P2_DN<12>")
	)
	(arc
		(start 96.909636 -288.422334)
		(mid 97.04055 -288.285974)
		(end 97.088198 -288.103056)
		(width 0.0889)
		(layer "In6.Cu")
		(net "UPI_CPU0_CPU1_P2P2_DN<12>")
	)
	(arc
		(start 344.927174 -286.969962)
		(mid 344.79626 -287.106322)
		(end 344.748612 -287.28924)
		(width 0.0889)
		(layer "In6.Cu")
		(net "UPI_CPU0_CPU1_P2P2_DN<12>")
	)
	(arc
		(start 98.780092 -282.895548)
		(mid 98.577806 -282.696567)
		(end 98.497644 -282.424378)
		(width 0.0889)
		(layer "In6.Cu")
		(net "UPI_CPU0_CPU1_P2P2_DN<12>")
	)
	(arc
		(start 99.734878 -277.024338)
		(mid 100.011353 -276.957018)
		(end 100.28555 -277.032974)
		(width 0.0889)
		(layer "In6.Cu")
		(net "UPI_CPU0_CPU1_P2P2_DN<12>")
	)
	(arc
		(start 346.806774 -280.458926)
		(mid 346.67586 -280.595286)
		(end 346.628212 -280.778204)
		(width 0.0889)
		(layer "In6.Cu")
		(net "UPI_CPU0_CPU1_P2P2_DN<12>")
	)
	(arc
		(start 350.087946 -279.437084)
		(mid 350.327221 -279.399776)
		(end 350.560132 -279.46604)
		(width 0.0889)
		(layer "In6.Cu")
		(net "UPI_CPU0_CPU1_P2P2_DN<12>")
	)
	(arc
		(start 98.027998 -281.576526)
		(mid 98.107368 -281.302792)
		(end 98.310192 -281.102562)
		(width 0.0889)
		(layer "In6.Cu")
		(net "UPI_CPU0_CPU1_P2P2_DN<12>")
	)
	(arc
		(start 346.158312 -283.229812)
		(mid 346.080201 -283.506761)
		(end 345.875864 -283.709364)
		(width 0.0889)
		(layer "In6.Cu")
		(net "UPI_CPU0_CPU1_P2P2_DN<12>")
	)
	(arc
		(start 101.787198 -275.065236)
		(mid 101.866568 -274.791502)
		(end 102.069392 -274.591272)
		(width 0.0889)
		(layer "In6.Cu")
		(net "UPI_CPU0_CPU1_P2P2_DN<12>")
	)
	(arc
		(start 345.688412 -284.049216)
		(mid 345.609042 -284.32295)
		(end 345.406218 -284.52318)
		(width 0.0889)
		(layer "In6.Cu")
		(net "UPI_CPU0_CPU1_P2P2_DN<12>")
	)
	(arc
		(start 103.009192 -274.591272)
		(mid 103.291103 -274.515546)
		(end 103.573072 -274.591018)
		(width 0.0889)
		(layer "In6.Cu")
		(net "UPI_CPU0_CPU1_P2P2_DN<12>")
	)
	(arc
		(start 103.639874 -274.629372)
		(mid 103.731233 -274.657596)
		(end 103.825802 -274.643596)
		(width 0.0889)
		(layer "In6.Cu")
		(net "UPI_CPU0_CPU1_P2P2_DN<12>")
	)
	(arc
		(start 344.936064 -285.985712)
		(mid 345.141136 -286.189391)
		(end 345.218766 -286.467804)
		(width 0.0889)
		(layer "In6.Cu")
		(net "UPI_CPU0_CPU1_P2P2_DN<12>")
	)
	(arc
		(start 97.088198 -288.087562)
		(mid 97.167568 -287.813828)
		(end 97.370392 -287.613598)
		(width 0.0889)
		(layer "In6.Cu")
		(net "UPI_CPU0_CPU1_P2P2_DN<12>")
	)
	(segment
		(start 347.472762 -281.591766)
		(end 347.473016 -281.59202)
		(width 0.13208)
		(layer "F.Cu")
		(net "UPI_CPU0_CPU1_P2P2_DN<11>")
	)
	(segment
		(start 97.183448 -282.405582)
		(end 97.183194 -282.405836)
		(width 0.13208)
		(layer "F.Cu")
		(net "UPI_CPU0_CPU1_P2P2_DN<11>")
	)
	(segment
		(start 97.183448 -281.869896)
		(end 97.183448 -282.405582)
		(width 0.13208)
		(layer "F.Cu")
		(net "UPI_CPU0_CPU1_P2P2_DN<11>")
	)
	(segment
		(start 347.472762 -281.05608)
		(end 347.472762 -281.591766)
		(width 0.13208)
		(layer "F.Cu")
		(net "UPI_CPU0_CPU1_P2P2_DN<11>")
	)
	(segment
		(start 345.875864 -285.336996)
		(end 345.87434 -285.337758)
		(width 0.0889)
		(layer "In6.Cu")
		(net "UPI_CPU0_CPU1_P2P2_DN<11>")
	)
	(segment
		(start 343.536778 -295.292526)
		(end 343.536778 -295.572434)
		(width 0.14732)
		(layer "In6.Cu")
		(net "UPI_CPU0_CPU1_P2P2_DN<11>")
	)
	(segment
		(start 271.365472 -345.079574)
		(end 271.365472 -368.54765)
		(width 0.14732)
		(layer "In6.Cu")
		(net "UPI_CPU0_CPU1_P2P2_DN<11>")
	)
	(segment
		(start 343.591134 -293.935658)
		(end 343.591134 -294.189658)
		(width 0.0889)
		(layer "In6.Cu")
		(net "UPI_CPU0_CPU1_P2P2_DN<11>")
	)
	(segment
		(start 96.148144 -289.978084)
		(end 96.148144 -289.645852)
		(width 0.0889)
		(layer "In6.Cu")
		(net "UPI_CPU0_CPU1_P2P2_DN<11>")
	)
	(segment
		(start 96.618044 -285.679896)
		(end 96.618044 -285.661354)
		(width 0.0889)
		(layer "In6.Cu")
		(net "UPI_CPU0_CPU1_P2P2_DN<11>")
	)
	(segment
		(start 96.148398 -288.103056)
		(end 96.148398 -288.087562)
		(width 0.0889)
		(layer "In6.Cu")
		(net "UPI_CPU0_CPU1_P2P2_DN<11>")
	)
	(segment
		(start 343.494614 -293.839138)
		(end 343.591134 -293.935658)
		(width 0.0889)
		(layer "In6.Cu")
		(net "UPI_CPU0_CPU1_P2P2_DN<11>")
	)
	(segment
		(start 96.900492 -286.799782)
		(end 96.901254 -286.799274)
		(width 0.0889)
		(layer "In6.Cu")
		(net "UPI_CPU0_CPU1_P2P2_DN<11>")
	)
	(segment
		(start 347.78569 -281.59202)
		(end 347.843094 -281.534616)
		(width 0.0889)
		(layer "In6.Cu")
		(net "UPI_CPU0_CPU1_P2P2_DN<11>")
	)
	(segment
		(start 96.430592 -287.613598)
		(end 96.439482 -287.608518)
		(width 0.0889)
		(layer "In6.Cu")
		(net "UPI_CPU0_CPU1_P2P2_DN<11>")
	)
	(segment
		(start 343.494614 -291.767514)
		(end 343.494614 -293.839138)
		(width 0.0889)
		(layer "In6.Cu")
		(net "UPI_CPU0_CPU1_P2P2_DN<11>")
	)
	(segment
		(start 347.284802 -281.91587)
		(end 347.285818 -281.916378)
		(width 0.0889)
		(layer "In6.Cu")
		(net "UPI_CPU0_CPU1_P2P2_DN<11>")
	)
	(segment
		(start 280.040588 -336.404458)
		(end 271.365472 -345.079574)
		(width 0.14732)
		(layer "In6.Cu")
		(net "UPI_CPU0_CPU1_P2P2_DN<11>")
	)
	(segment
		(start 314.719716 -327.060052)
		(end 307.571648 -334.20812)
		(width 0.14732)
		(layer "In6.Cu")
		(net "UPI_CPU0_CPU1_P2P2_DN<11>")
	)
	(segment
		(start 97.370392 -284.35808)
		(end 97.379282 -284.353)
		(width 0.0889)
		(layer "In6.Cu")
		(net "UPI_CPU0_CPU1_P2P2_DN<11>")
	)
	(segment
		(start 162.734244 -383.528824)
		(end 161.28238 -383.528824)
		(width 0.14732)
		(layer "In6.Cu")
		(net "UPI_CPU0_CPU1_P2P2_DN<11>")
	)
	(segment
		(start 340.892892 -301.315882)
		(end 337.465162 -302.735742)
		(width 0.14732)
		(layer "In6.Cu")
		(net "UPI_CPU0_CPU1_P2P2_DN<11>")
	)
	(segment
		(start 161.281364 -383.52984)
		(end 125.435868 -383.52984)
		(width 0.14732)
		(layer "In6.Cu")
		(net "UPI_CPU0_CPU1_P2P2_DN<11>")
	)
	(segment
		(start 346.815664 -283.709364)
		(end 346.806774 -283.714444)
		(width 0.0889)
		(layer "In6.Cu")
		(net "UPI_CPU0_CPU1_P2P2_DN<11>")
	)
	(segment
		(start 337.465162 -302.735742)
		(end 315.836046 -324.364858)
		(width 0.14732)
		(layer "In6.Cu")
		(net "UPI_CPU0_CPU1_P2P2_DN<11>")
	)
	(segment
		(start 343.536524 -297.527726)
		(end 342.72855 -299.480224)
		(width 0.14732)
		(layer "In6.Cu")
		(net "UPI_CPU0_CPU1_P2P2_DN<11>")
	)
	(segment
		(start 95.678498 -289.114738)
		(end 95.678498 -288.898584)
		(width 0.0889)
		(layer "In6.Cu")
		(net "UPI_CPU0_CPU1_P2P2_DN<11>")
	)
	(segment
		(start 97.561146 -282.471114)
		(end 97.495868 -282.405836)
		(width 0.0889)
		(layer "In6.Cu")
		(net "UPI_CPU0_CPU1_P2P2_DN<11>")
	)
	(segment
		(start 346.158566 -286.4612)
		(end 346.158566 -286.475424)
		(width 0.0889)
		(layer "In6.Cu")
		(net "UPI_CPU0_CPU1_P2P2_DN<11>")
	)
	(segment
		(start 345.87434 -285.337758)
		(end 345.866974 -285.342076)
		(width 0.0889)
		(layer "In6.Cu")
		(net "UPI_CPU0_CPU1_P2P2_DN<11>")
	)
	(segment
		(start 347.285818 -281.267662)
		(end 347.276928 -281.272742)
		(width 0.0889)
		(layer "In6.Cu")
		(net "UPI_CPU0_CPU1_P2P2_DN<11>")
	)
	(segment
		(start 345.872816 -286.966914)
		(end 345.870276 -286.968184)
		(width 0.0889)
		(layer "In6.Cu")
		(net "UPI_CPU0_CPU1_P2P2_DN<11>")
	)
	(segment
		(start 163.202874 -383.4511)
		(end 162.742626 -383.527808)
		(width 0.14732)
		(layer "In6.Cu")
		(net "UPI_CPU0_CPU1_P2P2_DN<11>")
	)
	(segment
		(start 344.748866 -288.917126)
		(end 344.748866 -289.078416)
		(width 0.0889)
		(layer "In6.Cu")
		(net "UPI_CPU0_CPU1_P2P2_DN<11>")
	)
	(segment
		(start 345.406218 -287.778698)
		(end 345.397328 -287.783778)
		(width 0.0889)
		(layer "In6.Cu")
		(net "UPI_CPU0_CPU1_P2P2_DN<11>")
	)
	(segment
		(start 345.094814 -290.167314)
		(end 345.094814 -290.307776)
		(width 0.0889)
		(layer "In6.Cu")
		(net "UPI_CPU0_CPU1_P2P2_DN<11>")
	)
	(segment
		(start 347.473016 -281.59202)
		(end 347.78569 -281.59202)
		(width 0.0889)
		(layer "In6.Cu")
		(net "UPI_CPU0_CPU1_P2P2_DN<11>")
	)
	(segment
		(start 345.218512 -290.043616)
		(end 345.094814 -290.167314)
		(width 0.0889)
		(layer "In6.Cu")
		(net "UPI_CPU0_CPU1_P2P2_DN<11>")
	)
	(segment
		(start 94.241112 -292.337998)
		(end 94.241112 -291.885116)
		(width 0.0889)
		(layer "In6.Cu")
		(net "UPI_CPU0_CPU1_P2P2_DN<11>")
	)
	(segment
		(start 347.276928 -281.911298)
		(end 347.284802 -281.91587)
		(width 0.0889)
		(layer "In6.Cu")
		(net "UPI_CPU0_CPU1_P2P2_DN<11>")
	)
	(segment
		(start 265.091926 -374.821196)
		(end 163.202874 -383.4511)
		(width 0.14732)
		(layer "In6.Cu")
		(net "UPI_CPU0_CPU1_P2P2_DN<11>")
	)
	(segment
		(start 66.266314 -327.966324)
		(end 67.23888 -324.453758)
		(width 0.14732)
		(layer "In6.Cu")
		(net "UPI_CPU0_CPU1_P2P2_DN<11>")
	)
	(segment
		(start 345.874848 -286.965644)
		(end 345.872816 -286.966914)
		(width 0.0889)
		(layer "In6.Cu")
		(net "UPI_CPU0_CPU1_P2P2_DN<11>")
	)
	(segment
		(start 340.9315 -301.277528)
		(end 340.892892 -301.315882)
		(width 0.14732)
		(layer "In6.Cu")
		(net "UPI_CPU0_CPU1_P2P2_DN<11>")
	)
	(segment
		(start 95.961708 -288.426906)
		(end 95.969836 -288.422334)
		(width 0.0889)
		(layer "In6.Cu")
		(net "UPI_CPU0_CPU1_P2P2_DN<11>")
	)
	(segment
		(start 75.085194 -370.294408)
		(end 70.145656 -365.35487)
		(width 0.14732)
		(layer "In6.Cu")
		(net "UPI_CPU0_CPU1_P2P2_DN<11>")
	)
	(segment
		(start 343.591134 -294.189658)
		(end 343.494614 -294.286178)
		(width 0.0889)
		(layer "In6.Cu")
		(net "UPI_CPU0_CPU1_P2P2_DN<11>")
	)
	(segment
		(start 347.669104 -281.272742)
		(end 347.661738 -281.268424)
		(width 0.0889)
		(layer "In6.Cu")
		(net "UPI_CPU0_CPU1_P2P2_DN<11>")
	)
	(segment
		(start 346.346018 -284.52318)
		(end 346.337128 -284.52826)
		(width 0.0889)
		(layer "In6.Cu")
		(net "UPI_CPU0_CPU1_P2P2_DN<11>")
	)
	(segment
		(start 96.901254 -286.799274)
		(end 96.903794 -286.79775)
		(width 0.0889)
		(layer "In6.Cu")
		(net "UPI_CPU0_CPU1_P2P2_DN<11>")
	)
	(segment
		(start 78.498192 -311.430416)
		(end 90.910156 -301.244254)
		(width 0.14732)
		(layer "In6.Cu")
		(net "UPI_CPU0_CPU1_P2P2_DN<11>")
	)
	(segment
		(start 345.870276 -286.968184)
		(end 345.866974 -286.970216)
		(width 0.0889)
		(layer "In6.Cu")
		(net "UPI_CPU0_CPU1_P2P2_DN<11>")
	)
	(segment
		(start 65.602358 -354.385372)
		(end 65.602358 -334.711294)
		(width 0.14732)
		(layer "In6.Cu")
		(net "UPI_CPU0_CPU1_P2P2_DN<11>")
	)
	(segment
		(start 345.88196 -285.33344)
		(end 345.876626 -285.336488)
		(width 0.0889)
		(layer "In6.Cu")
		(net "UPI_CPU0_CPU1_P2P2_DN<11>")
	)
	(segment
		(start 347.661738 -281.268424)
		(end 347.660214 -281.267662)
		(width 0.0889)
		(layer "In6.Cu")
		(net "UPI_CPU0_CPU1_P2P2_DN<11>")
	)
	(segment
		(start 67.23888 -324.453758)
		(end 68.821046 -321.107562)
		(width 0.14732)
		(layer "In6.Cu")
		(net "UPI_CPU0_CPU1_P2P2_DN<11>")
	)
	(segment
		(start 343.536778 -295.270428)
		(end 343.536778 -295.292526)
		(width 0.0889)
		(layer "In6.Cu")
		(net "UPI_CPU0_CPU1_P2P2_DN<11>")
	)
	(segment
		(start 96.774762 -379.278388)
		(end 75.085194 -370.294408)
		(width 0.14732)
		(layer "In6.Cu")
		(net "UPI_CPU0_CPU1_P2P2_DN<11>")
	)
	(segment
		(start 96.618044 -287.28924)
		(end 96.618044 -287.279334)
		(width 0.0889)
		(layer "In6.Cu")
		(net "UPI_CPU0_CPU1_P2P2_DN<11>")
	)
	(segment
		(start 345.866974 -285.980632)
		(end 345.875864 -285.985712)
		(width 0.0889)
		(layer "In6.Cu")
		(net "UPI_CPU0_CPU1_P2P2_DN<11>")
	)
	(segment
		(start 347.568012 -282.390342)
		(end 347.568012 -282.406598)
		(width 0.0889)
		(layer "In6.Cu")
		(net "UPI_CPU0_CPU1_P2P2_DN<11>")
	)
	(segment
		(start 95.960946 -288.427414)
		(end 95.961708 -288.426906)
		(width 0.0889)
		(layer "In6.Cu")
		(net "UPI_CPU0_CPU1_P2P2_DN<11>")
	)
	(segment
		(start 344.933016 -289.277806)
		(end 344.933524 -289.27806)
		(width 0.0889)
		(layer "In6.Cu")
		(net "UPI_CPU0_CPU1_P2P2_DN<11>")
	)
	(segment
		(start 342.72855 -299.480224)
		(end 340.9315 -301.277274)
		(width 0.14732)
		(layer "In6.Cu")
		(net "UPI_CPU0_CPU1_P2P2_DN<11>")
	)
	(segment
		(start 94.199202 -292.379908)
		(end 94.241112 -292.337998)
		(width 0.0889)
		(layer "In6.Cu")
		(net "UPI_CPU0_CPU1_P2P2_DN<11>")
	)
	(segment
		(start 345.88196 -286.961326)
		(end 345.877134 -286.96412)
		(width 0.0889)
		(layer "In6.Cu")
		(net "UPI_CPU0_CPU1_P2P2_DN<11>")
	)
	(segment
		(start 68.821046 -321.107562)
		(end 78.498192 -311.430416)
		(width 0.14732)
		(layer "In6.Cu")
		(net "UPI_CPU0_CPU1_P2P2_DN<11>")
	)
	(segment
		(start 96.899984 -285.172404)
		(end 96.900746 -285.171896)
		(width 0.0889)
		(layer "In6.Cu")
		(net "UPI_CPU0_CPU1_P2P2_DN<11>")
	)
	(segment
		(start 97.840292 -283.544264)
		(end 97.849182 -283.539184)
		(width 0.0889)
		(layer "In6.Cu")
		(net "UPI_CPU0_CPU1_P2P2_DN<11>")
	)
	(segment
		(start 344.970862 -290.431728)
		(end 344.8304 -290.431728)
		(width 0.0889)
		(layer "In6.Cu")
		(net "UPI_CPU0_CPU1_P2P2_DN<11>")
	)
	(segment
		(start 345.866974 -286.970216)
		(end 345.866974 -286.969962)
		(width 0.0889)
		(layer "In6.Cu")
		(net "UPI_CPU0_CPU1_P2P2_DN<11>")
	)
	(segment
		(start 345.094814 -290.307776)
		(end 344.970862 -290.431728)
		(width 0.0889)
		(layer "In6.Cu")
		(net "UPI_CPU0_CPU1_P2P2_DN<11>")
	)
	(segment
		(start 65.602358 -334.711294)
		(end 66.266314 -327.966324)
		(width 0.14732)
		(layer "In6.Cu")
		(net "UPI_CPU0_CPU1_P2P2_DN<11>")
	)
	(segment
		(start 96.89465 -285.175452)
		(end 96.899984 -285.172404)
		(width 0.0889)
		(layer "In6.Cu")
		(net "UPI_CPU0_CPU1_P2P2_DN<11>")
	)
	(segment
		(start 97.495868 -282.405836)
		(end 97.183194 -282.405836)
		(width 0.0889)
		(layer "In6.Cu")
		(net "UPI_CPU0_CPU1_P2P2_DN<11>")
	)
	(segment
		(start 91.251024 -301.140876)
		(end 92.7989 -299.870622)
		(width 0.14732)
		(layer "In6.Cu")
		(net "UPI_CPU0_CPU1_P2P2_DN<11>")
	)
	(segment
		(start 340.9315 -301.277274)
		(end 340.9315 -301.277528)
		(width 0.14732)
		(layer "In6.Cu")
		(net "UPI_CPU0_CPU1_P2P2_DN<11>")
	)
	(segment
		(start 97.088198 -284.847538)
		(end 97.088198 -284.832044)
		(width 0.0889)
		(layer "In6.Cu")
		(net "UPI_CPU0_CPU1_P2P2_DN<11>")
	)
	(segment
		(start 90.910156 -301.244254)
		(end 91.251024 -301.140876)
		(width 0.14732)
		(layer "In6.Cu")
		(net "UPI_CPU0_CPU1_P2P2_DN<11>")
	)
	(segment
		(start 162.742626 -383.527808)
		(end 162.734244 -383.528824)
		(width 0.14732)
		(layer "In6.Cu")
		(net "UPI_CPU0_CPU1_P2P2_DN<11>")
	)
	(segment
		(start 70.145656 -365.35487)
		(end 65.602358 -354.385372)
		(width 0.14732)
		(layer "In6.Cu")
		(net "UPI_CPU0_CPU1_P2P2_DN<11>")
	)
	(segment
		(start 343.494614 -295.228264)
		(end 343.536778 -295.270428)
		(width 0.0889)
		(layer "In6.Cu")
		(net "UPI_CPU0_CPU1_P2P2_DN<11>")
	)
	(segment
		(start 94.198948 -292.557708)
		(end 94.199202 -292.557454)
		(width 0.14732)
		(layer "In6.Cu")
		(net "UPI_CPU0_CPU1_P2P2_DN<11>")
	)
	(segment
		(start 93.236034 -299.280834)
		(end 94.198948 -296.955972)
		(width 0.14732)
		(layer "In6.Cu")
		(net "UPI_CPU0_CPU1_P2P2_DN<11>")
	)
	(segment
		(start 97.557844 -284.033722)
		(end 97.557844 -284.023816)
		(width 0.0889)
		(layer "In6.Cu")
		(net "UPI_CPU0_CPU1_P2P2_DN<11>")
	)
	(segment
		(start 344.8304 -290.431728)
		(end 343.494614 -291.767514)
		(width 0.0889)
		(layer "In6.Cu")
		(net "UPI_CPU0_CPU1_P2P2_DN<11>")
	)
	(segment
		(start 94.199202 -292.402006)
		(end 94.199202 -292.379908)
		(width 0.0889)
		(layer "In6.Cu")
		(net "UPI_CPU0_CPU1_P2P2_DN<11>")
	)
	(segment
		(start 345.218512 -289.60953)
		(end 345.218512 -290.043616)
		(width 0.0889)
		(layer "In6.Cu")
		(net "UPI_CPU0_CPU1_P2P2_DN<11>")
	)
	(segment
		(start 96.900746 -285.171896)
		(end 96.90227 -285.171134)
		(width 0.0889)
		(layer "In6.Cu")
		(net "UPI_CPU0_CPU1_P2P2_DN<11>")
	)
	(segment
		(start 343.536524 -295.572688)
		(end 343.536524 -297.527726)
		(width 0.14732)
		(layer "In6.Cu")
		(net "UPI_CPU0_CPU1_P2P2_DN<11>")
	)
	(segment
		(start 96.90227 -285.171134)
		(end 96.909636 -285.166816)
		(width 0.0889)
		(layer "In6.Cu")
		(net "UPI_CPU0_CPU1_P2P2_DN<11>")
	)
	(segment
		(start 96.909382 -286.156146)
		(end 96.900492 -286.151066)
		(width 0.0889)
		(layer "In6.Cu")
		(net "UPI_CPU0_CPU1_P2P2_DN<11>")
	)
	(segment
		(start 346.827856 -283.702252)
		(end 346.815664 -283.709364)
		(width 0.0889)
		(layer "In6.Cu")
		(net "UPI_CPU0_CPU1_P2P2_DN<11>")
	)
	(segment
		(start 345.218766 -288.103056)
		(end 345.218766 -288.121598)
		(width 0.0889)
		(layer "In6.Cu")
		(net "UPI_CPU0_CPU1_P2P2_DN<11>")
	)
	(segment
		(start 344.936318 -288.592768)
		(end 344.927428 -288.597848)
		(width 0.0889)
		(layer "In6.Cu")
		(net "UPI_CPU0_CPU1_P2P2_DN<11>")
	)
	(segment
		(start 347.285818 -282.895548)
		(end 347.276928 -282.900628)
		(width 0.0889)
		(layer "In6.Cu")
		(net "UPI_CPU0_CPU1_P2P2_DN<11>")
	)
	(segment
		(start 343.536778 -295.572434)
		(end 343.536524 -295.572688)
		(width 0.14732)
		(layer "In6.Cu")
		(net "UPI_CPU0_CPU1_P2P2_DN<11>")
	)
	(segment
		(start 161.28238 -383.528824)
		(end 161.281364 -383.52984)
		(width 0.14732)
		(layer "In6.Cu")
		(net "UPI_CPU0_CPU1_P2P2_DN<11>")
	)
	(segment
		(start 94.198948 -296.955972)
		(end 94.198948 -292.557708)
		(width 0.14732)
		(layer "In6.Cu")
		(net "UPI_CPU0_CPU1_P2P2_DN<11>")
	)
	(segment
		(start 285.343092 -334.20812)
		(end 280.040588 -336.404458)
		(width 0.14732)
		(layer "In6.Cu")
		(net "UPI_CPU0_CPU1_P2P2_DN<11>")
	)
	(segment
		(start 345.877134 -286.96412)
		(end 345.874848 -286.965644)
		(width 0.0889)
		(layer "In6.Cu")
		(net "UPI_CPU0_CPU1_P2P2_DN<11>")
	)
	(segment
		(start 94.241112 -291.885116)
		(end 96.148144 -289.978084)
		(width 0.0889)
		(layer "In6.Cu")
		(net "UPI_CPU0_CPU1_P2P2_DN<11>")
	)
	(segment
		(start 346.628212 -284.033722)
		(end 346.628212 -284.049216)
		(width 0.0889)
		(layer "In6.Cu")
		(net "UPI_CPU0_CPU1_P2P2_DN<11>")
	)
	(segment
		(start 307.571648 -334.20812)
		(end 285.343092 -334.20812)
		(width 0.14732)
		(layer "In6.Cu")
		(net "UPI_CPU0_CPU1_P2P2_DN<11>")
	)
	(segment
		(start 345.876626 -285.336488)
		(end 345.875864 -285.336996)
		(width 0.0889)
		(layer "In6.Cu")
		(net "UPI_CPU0_CPU1_P2P2_DN<11>")
	)
	(segment
		(start 125.435868 -383.52984)
		(end 96.774762 -379.278388)
		(width 0.14732)
		(layer "In6.Cu")
		(net "UPI_CPU0_CPU1_P2P2_DN<11>")
	)
	(segment
		(start 97.849182 -282.900628)
		(end 97.840292 -282.895548)
		(width 0.0889)
		(layer "In6.Cu")
		(net "UPI_CPU0_CPU1_P2P2_DN<11>")
	)
	(segment
		(start 92.7989 -299.870622)
		(end 93.236034 -299.280834)
		(width 0.14732)
		(layer "In6.Cu")
		(net "UPI_CPU0_CPU1_P2P2_DN<11>")
	)
	(segment
		(start 345.688412 -287.28924)
		(end 345.688412 -287.304734)
		(width 0.0889)
		(layer "In6.Cu")
		(net "UPI_CPU0_CPU1_P2P2_DN<11>")
	)
	(segment
		(start 94.199202 -292.557454)
		(end 94.199202 -292.402006)
		(width 0.14732)
		(layer "In6.Cu")
		(net "UPI_CPU0_CPU1_P2P2_DN<11>")
	)
	(segment
		(start 315.836046 -324.364858)
		(end 314.719716 -327.060052)
		(width 0.14732)
		(layer "In6.Cu")
		(net "UPI_CPU0_CPU1_P2P2_DN<11>")
	)
	(segment
		(start 271.365472 -368.54765)
		(end 265.091926 -374.821196)
		(width 0.14732)
		(layer "In6.Cu")
		(net "UPI_CPU0_CPU1_P2P2_DN<11>")
	)
	(segment
		(start 343.494614 -294.286178)
		(end 343.494614 -295.228264)
		(width 0.0889)
		(layer "In6.Cu")
		(net "UPI_CPU0_CPU1_P2P2_DN<11>")
	)
	(segment
		(start 96.903794 -286.79775)
		(end 96.909382 -286.794702)
		(width 0.0889)
		(layer "In6.Cu")
		(net "UPI_CPU0_CPU1_P2P2_DN<11>")
	)
	(arc
		(start 98.02749 -283.207714)
		(mid 97.977019 -283.031706)
		(end 97.849182 -282.900628)
		(width 0.0889)
		(layer "In6.Cu")
		(net "UPI_CPU0_CPU1_P2P2_DN<11>")
	)
	(arc
		(start 97.557844 -284.023816)
		(mid 97.635955 -283.746867)
		(end 97.840292 -283.544264)
		(width 0.0889)
		(layer "In6.Cu")
		(net "UPI_CPU0_CPU1_P2P2_DN<11>")
	)
	(arc
		(start 345.866974 -286.969962)
		(mid 345.73606 -287.106322)
		(end 345.688412 -287.28924)
		(width 0.0889)
		(layer "In6.Cu")
		(net "UPI_CPU0_CPU1_P2P2_DN<11>")
	)
	(arc
		(start 95.969836 -288.422334)
		(mid 96.10075 -288.285974)
		(end 96.148398 -288.103056)
		(width 0.0889)
		(layer "In6.Cu")
		(net "UPI_CPU0_CPU1_P2P2_DN<11>")
	)
	(arc
		(start 97.840292 -282.895548)
		(mid 97.656378 -282.725503)
		(end 97.56394 -282.492704)
		(width 0.0889)
		(layer "In6.Cu")
		(net "UPI_CPU0_CPU1_P2P2_DN<11>")
	)
	(arc
		(start 97.379282 -284.353)
		(mid 97.510196 -284.21664)
		(end 97.557844 -284.033722)
		(width 0.0889)
		(layer "In6.Cu")
		(net "UPI_CPU0_CPU1_P2P2_DN<11>")
	)
	(arc
		(start 98.027744 -283.22651)
		(mid 98.027734 -283.21711)
		(end 98.02749 -283.207714)
		(width 0.0889)
		(layer "In6.Cu")
		(net "UPI_CPU0_CPU1_P2P2_DN<11>")
	)
	(arc
		(start 95.963994 -289.446462)
		(mid 95.789862 -289.307615)
		(end 95.678498 -289.114738)
		(width 0.0889)
		(layer "In6.Cu")
		(net "UPI_CPU0_CPU1_P2P2_DN<11>")
	)
	(arc
		(start 96.618044 -285.661354)
		(mid 96.692035 -285.381788)
		(end 96.89465 -285.175452)
		(width 0.0889)
		(layer "In6.Cu")
		(net "UPI_CPU0_CPU1_P2P2_DN<11>")
	)
	(arc
		(start 345.397328 -287.783778)
		(mid 345.266414 -287.920138)
		(end 345.218766 -288.103056)
		(width 0.0889)
		(layer "In6.Cu")
		(net "UPI_CPU0_CPU1_P2P2_DN<11>")
	)
	(arc
		(start 346.806774 -283.714444)
		(mid 346.67586 -283.850804)
		(end 346.628212 -284.033722)
		(width 0.0889)
		(layer "In6.Cu")
		(net "UPI_CPU0_CPU1_P2P2_DN<11>")
	)
	(arc
		(start 345.218766 -288.121598)
		(mid 345.138604 -288.393787)
		(end 344.936318 -288.592768)
		(width 0.0889)
		(layer "In6.Cu")
		(net "UPI_CPU0_CPU1_P2P2_DN<11>")
	)
	(arc
		(start 347.276928 -282.900628)
		(mid 347.146014 -283.036988)
		(end 347.098366 -283.219906)
		(width 0.0889)
		(layer "In6.Cu")
		(net "UPI_CPU0_CPU1_P2P2_DN<11>")
	)
	(arc
		(start 346.337128 -284.52826)
		(mid 346.206214 -284.66462)
		(end 346.158566 -284.847538)
		(width 0.0889)
		(layer "In6.Cu")
		(net "UPI_CPU0_CPU1_P2P2_DN<11>")
	)
	(arc
		(start 347.660214 -281.267662)
		(mid 347.473016 -281.217519)
		(end 347.285818 -281.267662)
		(width 0.0889)
		(layer "In6.Cu")
		(net "UPI_CPU0_CPU1_P2P2_DN<11>")
	)
	(arc
		(start 347.098366 -283.219906)
		(mid 347.026131 -283.49643)
		(end 346.827856 -283.702252)
		(width 0.0889)
		(layer "In6.Cu")
		(net "UPI_CPU0_CPU1_P2P2_DN<11>")
	)
	(arc
		(start 96.618044 -287.279334)
		(mid 96.696155 -287.002385)
		(end 96.900492 -286.799782)
		(width 0.0889)
		(layer "In6.Cu")
		(net "UPI_CPU0_CPU1_P2P2_DN<11>")
	)
	(arc
		(start 97.849182 -283.539184)
		(mid 97.978471 -283.405698)
		(end 98.027744 -283.22651)
		(width 0.0889)
		(layer "In6.Cu")
		(net "UPI_CPU0_CPU1_P2P2_DN<11>")
	)
	(arc
		(start 347.843094 -281.534616)
		(mid 347.784938 -281.384503)
		(end 347.669104 -281.272742)
		(width 0.0889)
		(layer "In6.Cu")
		(net "UPI_CPU0_CPU1_P2P2_DN<11>")
	)
	(arc
		(start 96.148144 -289.645852)
		(mid 96.073139 -289.530393)
		(end 95.963994 -289.446462)
		(width 0.0889)
		(layer "In6.Cu")
		(net "UPI_CPU0_CPU1_P2P2_DN<11>")
	)
	(arc
		(start 347.285818 -281.916378)
		(mid 347.488641 -282.116609)
		(end 347.568012 -282.390342)
		(width 0.0889)
		(layer "In6.Cu")
		(net "UPI_CPU0_CPU1_P2P2_DN<11>")
	)
	(arc
		(start 347.276928 -281.272742)
		(mid 347.098452 -281.59202)
		(end 347.276928 -281.911298)
		(width 0.0889)
		(layer "In6.Cu")
		(net "UPI_CPU0_CPU1_P2P2_DN<11>")
	)
	(arc
		(start 97.56394 -282.492704)
		(mid 97.56244 -282.481922)
		(end 97.561146 -282.471114)
		(width 0.0889)
		(layer "In6.Cu")
		(net "UPI_CPU0_CPU1_P2P2_DN<11>")
	)
	(arc
		(start 345.866974 -285.342076)
		(mid 345.688377 -285.661354)
		(end 345.866974 -285.980632)
		(width 0.0889)
		(layer "In6.Cu")
		(net "UPI_CPU0_CPU1_P2P2_DN<11>")
	)
	(arc
		(start 346.158566 -286.475424)
		(mid 346.084575 -286.75499)
		(end 345.88196 -286.961326)
		(width 0.0889)
		(layer "In6.Cu")
		(net "UPI_CPU0_CPU1_P2P2_DN<11>")
	)
	(arc
		(start 344.933524 -289.27806)
		(mid 344.935813 -289.279325)
		(end 344.938096 -289.2806)
		(width 0.0889)
		(layer "In6.Cu")
		(net "UPI_CPU0_CPU1_P2P2_DN<11>")
	)
	(arc
		(start 346.158566 -284.847538)
		(mid 346.084575 -285.127104)
		(end 345.88196 -285.33344)
		(width 0.0889)
		(layer "In6.Cu")
		(net "UPI_CPU0_CPU1_P2P2_DN<11>")
	)
	(arc
		(start 96.439482 -287.608518)
		(mid 96.570396 -287.472158)
		(end 96.618044 -287.28924)
		(width 0.0889)
		(layer "In6.Cu")
		(net "UPI_CPU0_CPU1_P2P2_DN<11>")
	)
	(arc
		(start 344.938096 -289.2806)
		(mid 345.10898 -289.4189)
		(end 345.218512 -289.60953)
		(width 0.0889)
		(layer "In6.Cu")
		(net "UPI_CPU0_CPU1_P2P2_DN<11>")
	)
	(arc
		(start 344.748866 -289.078416)
		(mid 344.823871 -289.193875)
		(end 344.933016 -289.277806)
		(width 0.0889)
		(layer "In6.Cu")
		(net "UPI_CPU0_CPU1_P2P2_DN<11>")
	)
	(arc
		(start 96.909382 -286.794702)
		(mid 97.087979 -286.475424)
		(end 96.909382 -286.156146)
		(width 0.0889)
		(layer "In6.Cu")
		(net "UPI_CPU0_CPU1_P2P2_DN<11>")
	)
	(arc
		(start 346.628212 -284.049216)
		(mid 346.548842 -284.32295)
		(end 346.346018 -284.52318)
		(width 0.0889)
		(layer "In6.Cu")
		(net "UPI_CPU0_CPU1_P2P2_DN<11>")
	)
	(arc
		(start 96.909636 -285.166816)
		(mid 97.04055 -285.030456)
		(end 97.088198 -284.847538)
		(width 0.0889)
		(layer "In6.Cu")
		(net "UPI_CPU0_CPU1_P2P2_DN<11>")
	)
	(arc
		(start 345.688412 -287.304734)
		(mid 345.609042 -287.578468)
		(end 345.406218 -287.778698)
		(width 0.0889)
		(layer "In6.Cu")
		(net "UPI_CPU0_CPU1_P2P2_DN<11>")
	)
	(arc
		(start 96.900492 -286.151066)
		(mid 96.698206 -285.952085)
		(end 96.618044 -285.679896)
		(width 0.0889)
		(layer "In6.Cu")
		(net "UPI_CPU0_CPU1_P2P2_DN<11>")
	)
	(arc
		(start 95.678498 -288.898584)
		(mid 95.75866 -288.626395)
		(end 95.960946 -288.427414)
		(width 0.0889)
		(layer "In6.Cu")
		(net "UPI_CPU0_CPU1_P2P2_DN<11>")
	)
	(arc
		(start 97.088198 -284.832044)
		(mid 97.167568 -284.55831)
		(end 97.370392 -284.35808)
		(width 0.0889)
		(layer "In6.Cu")
		(net "UPI_CPU0_CPU1_P2P2_DN<11>")
	)
	(arc
		(start 347.568012 -282.406598)
		(mid 347.492397 -282.688862)
		(end 347.285818 -282.895548)
		(width 0.0889)
		(layer "In6.Cu")
		(net "UPI_CPU0_CPU1_P2P2_DN<11>")
	)
	(arc
		(start 344.927428 -288.597848)
		(mid 344.796514 -288.734208)
		(end 344.748866 -288.917126)
		(width 0.0889)
		(layer "In6.Cu")
		(net "UPI_CPU0_CPU1_P2P2_DN<11>")
	)
	(arc
		(start 345.875864 -285.985712)
		(mid 346.079345 -286.186516)
		(end 346.158566 -286.4612)
		(width 0.0889)
		(layer "In6.Cu")
		(net "UPI_CPU0_CPU1_P2P2_DN<11>")
	)
	(arc
		(start 96.148398 -288.087562)
		(mid 96.227768 -287.813828)
		(end 96.430592 -287.613598)
		(width 0.0889)
		(layer "In6.Cu")
		(net "UPI_CPU0_CPU1_P2P2_DN<11>")
	)
	(segment
		(start 347.942916 -282.405582)
		(end 347.942662 -282.405836)
		(width 0.13208)
		(layer "F.Cu")
		(net "UPI_CPU0_CPU1_P2P2_DN<10>")
	)
	(segment
		(start 98.123248 -280.77795)
		(end 98.122994 -280.778204)
		(width 0.13208)
		(layer "F.Cu")
		(net "UPI_CPU0_CPU1_P2P2_DN<10>")
	)
	(segment
		(start 98.123248 -280.242264)
		(end 98.123248 -280.77795)
		(width 0.13208)
		(layer "F.Cu")
		(net "UPI_CPU0_CPU1_P2P2_DN<10>")
	)
	(segment
		(start 347.942916 -281.869896)
		(end 347.942916 -282.405582)
		(width 0.13208)
		(layer "F.Cu")
		(net "UPI_CPU0_CPU1_P2P2_DN<10>")
	)
	(segment
		(start 346.806774 -285.980632)
		(end 346.814902 -285.985204)
		(width 0.0889)
		(layer "In6.Cu")
		(net "UPI_CPU0_CPU1_P2P2_DN<10>")
	)
	(segment
		(start 64.766698 -354.542344)
		(end 64.766698 -332.39456)
		(width 0.14732)
		(layer "In6.Cu")
		(net "UPI_CPU0_CPU1_P2P2_DN<10>")
	)
	(segment
		(start 95.208598 -288.103056)
		(end 95.208598 -288.087562)
		(width 0.0889)
		(layer "In6.Cu")
		(net "UPI_CPU0_CPU1_P2P2_DN<10>")
	)
	(segment
		(start 346.158566 -288.103056)
		(end 346.158566 -288.121598)
		(width 0.0889)
		(layer "In6.Cu")
		(net "UPI_CPU0_CPU1_P2P2_DN<10>")
	)
	(segment
		(start 347.285818 -284.52318)
		(end 347.276928 -284.52826)
		(width 0.0889)
		(layer "In6.Cu")
		(net "UPI_CPU0_CPU1_P2P2_DN<10>")
	)
	(segment
		(start 344.367358 -294.810688)
		(end 344.367358 -297.85945)
		(width 0.14732)
		(layer "In6.Cu")
		(net "UPI_CPU0_CPU1_P2P2_DN<10>")
	)
	(segment
		(start 316.595506 -324.780402)
		(end 315.480192 -327.473056)
		(width 0.14732)
		(layer "In6.Cu")
		(net "UPI_CPU0_CPU1_P2P2_DN<10>")
	)
	(segment
		(start 96.900746 -281.916378)
		(end 96.90227 -281.915616)
		(width 0.0889)
		(layer "In6.Cu")
		(net "UPI_CPU0_CPU1_P2P2_DN<10>")
	)
	(segment
		(start 347.942662 -282.405836)
		(end 347.786198 -282.676854)
		(width 0.0889)
		(layer "In6.Cu")
		(net "UPI_CPU0_CPU1_P2P2_DN<10>")
	)
	(segment
		(start 92.523564 -298.831254)
		(end 93.210888 -297.171618)
		(width 0.14732)
		(layer "In6.Cu")
		(net "UPI_CPU0_CPU1_P2P2_DN<10>")
	)
	(segment
		(start 93.700346 -291.198554)
		(end 93.759274 -291.198554)
		(width 0.0889)
		(layer "In6.Cu")
		(net "UPI_CPU0_CPU1_P2P2_DN<10>")
	)
	(segment
		(start 97.96653 -281.049222)
		(end 98.122994 -280.778204)
		(width 0.0889)
		(layer "In6.Cu")
		(net "UPI_CPU0_CPU1_P2P2_DN<10>")
	)
	(segment
		(start 341.21979 -302.162464)
		(end 337.793584 -303.582324)
		(width 0.14732)
		(layer "In6.Cu")
		(net "UPI_CPU0_CPU1_P2P2_DN<10>")
	)
	(segment
		(start 347.749876 -283.712666)
		(end 347.746574 -283.714698)
		(width 0.0889)
		(layer "In6.Cu")
		(net "UPI_CPU0_CPU1_P2P2_DN<10>")
	)
	(segment
		(start 95.96247 -285.171134)
		(end 95.969836 -285.166816)
		(width 0.0889)
		(layer "In6.Cu")
		(net "UPI_CPU0_CPU1_P2P2_DN<10>")
	)
	(segment
		(start 346.814902 -285.985204)
		(end 346.815664 -285.985712)
		(width 0.0889)
		(layer "In6.Cu")
		(net "UPI_CPU0_CPU1_P2P2_DN<10>")
	)
	(segment
		(start 345.876118 -288.592768)
		(end 345.867228 -288.597848)
		(width 0.0889)
		(layer "In6.Cu")
		(net "UPI_CPU0_CPU1_P2P2_DN<10>")
	)
	(segment
		(start 344.367612 -294.614346)
		(end 344.367612 -294.810434)
		(width 0.14732)
		(layer "In6.Cu")
		(net "UPI_CPU0_CPU1_P2P2_DN<10>")
	)
	(segment
		(start 346.816426 -285.336488)
		(end 346.815664 -285.336996)
		(width 0.0889)
		(layer "In6.Cu")
		(net "UPI_CPU0_CPU1_P2P2_DN<10>")
	)
	(segment
		(start 97.088198 -281.59202)
		(end 97.088198 -281.576526)
		(width 0.0889)
		(layer "In6.Cu")
		(net "UPI_CPU0_CPU1_P2P2_DN<10>")
	)
	(segment
		(start 162.764216 -384.363722)
		(end 161.168842 -384.37185)
		(width 0.14732)
		(layer "In6.Cu")
		(net "UPI_CPU0_CPU1_P2P2_DN<10>")
	)
	(segment
		(start 346.346018 -287.778698)
		(end 346.337128 -287.783778)
		(width 0.0889)
		(layer "In6.Cu")
		(net "UPI_CPU0_CPU1_P2P2_DN<10>")
	)
	(segment
		(start 95.960946 -285.171896)
		(end 95.96247 -285.171134)
		(width 0.0889)
		(layer "In6.Cu")
		(net "UPI_CPU0_CPU1_P2P2_DN<10>")
	)
	(segment
		(start 344.367612 -294.592248)
		(end 344.367612 -294.614346)
		(width 0.0889)
		(layer "In6.Cu")
		(net "UPI_CPU0_CPU1_P2P2_DN<10>")
	)
	(segment
		(start 344.042492 -298.507404)
		(end 343.453974 -299.92828)
		(width 0.14732)
		(layer "In6.Cu")
		(net "UPI_CPU0_CPU1_P2P2_DN<10>")
	)
	(segment
		(start 315.480192 -327.473056)
		(end 307.917088 -335.03616)
		(width 0.14732)
		(layer "In6.Cu")
		(net "UPI_CPU0_CPU1_P2P2_DN<10>")
	)
	(segment
		(start 95.678244 -285.675578)
		(end 95.678244 -285.661354)
		(width 0.0889)
		(layer "In6.Cu")
		(net "UPI_CPU0_CPU1_P2P2_DN<10>")
	)
	(segment
		(start 95.021146 -288.427414)
		(end 95.021908 -288.426906)
		(width 0.0889)
		(layer "In6.Cu")
		(net "UPI_CPU0_CPU1_P2P2_DN<10>")
	)
	(segment
		(start 96.430592 -284.35808)
		(end 96.439482 -284.353)
		(width 0.0889)
		(layer "In6.Cu")
		(net "UPI_CPU0_CPU1_P2P2_DN<10>")
	)
	(segment
		(start 74.302874 -370.883688)
		(end 69.57822 -366.159034)
		(width 0.14732)
		(layer "In6.Cu")
		(net "UPI_CPU0_CPU1_P2P2_DN<10>")
	)
	(segment
		(start 96.90227 -281.915616)
		(end 96.909636 -281.911298)
		(width 0.0889)
		(layer "In6.Cu")
		(net "UPI_CPU0_CPU1_P2P2_DN<10>")
	)
	(segment
		(start 95.95485 -285.175452)
		(end 95.960184 -285.172404)
		(width 0.0889)
		(layer "In6.Cu")
		(net "UPI_CPU0_CPU1_P2P2_DN<10>")
	)
	(segment
		(start 92.165932 -299.3136)
		(end 92.523564 -298.831254)
		(width 0.14732)
		(layer "In6.Cu")
		(net "UPI_CPU0_CPU1_P2P2_DN<10>")
	)
	(segment
		(start 64.77762 -332.383384)
		(end 65.105534 -329.053698)
		(width 0.14732)
		(layer "In6.Cu")
		(net "UPI_CPU0_CPU1_P2P2_DN<10>")
	)
	(segment
		(start 64.766698 -332.39456)
		(end 64.77762 -332.383384)
		(width 0.14732)
		(layer "In6.Cu")
		(net "UPI_CPU0_CPU1_P2P2_DN<10>")
	)
	(segment
		(start 285.542736 -335.03616)
		(end 280.485088 -337.131152)
		(width 0.14732)
		(layer "In6.Cu")
		(net "UPI_CPU0_CPU1_P2P2_DN<10>")
	)
	(segment
		(start 68.135246 -320.615818)
		(end 78.811628 -309.939436)
		(width 0.14732)
		(layer "In6.Cu")
		(net "UPI_CPU0_CPU1_P2P2_DN<10>")
	)
	(segment
		(start 96.89465 -281.919934)
		(end 96.899984 -281.916886)
		(width 0.0889)
		(layer "In6.Cu")
		(net "UPI_CPU0_CPU1_P2P2_DN<10>")
	)
	(segment
		(start 96.518984 -380.0856)
		(end 74.302874 -370.883688)
		(width 0.14732)
		(layer "In6.Cu")
		(net "UPI_CPU0_CPU1_P2P2_DN<10>")
	)
	(segment
		(start 346.815664 -286.964882)
		(end 346.806774 -286.969962)
		(width 0.0889)
		(layer "In6.Cu")
		(net "UPI_CPU0_CPU1_P2P2_DN<10>")
	)
	(segment
		(start 347.76156 -283.705808)
		(end 347.756734 -283.708602)
		(width 0.0889)
		(layer "In6.Cu")
		(net "UPI_CPU0_CPU1_P2P2_DN<10>")
	)
	(segment
		(start 161.168842 -384.37185)
		(end 125.414532 -384.37185)
		(width 0.14732)
		(layer "In6.Cu")
		(net "UPI_CPU0_CPU1_P2P2_DN<10>")
	)
	(segment
		(start 91.594686 -299.78223)
		(end 91.59494 -299.78223)
		(width 0.14732)
		(layer "In6.Cu")
		(net "UPI_CPU0_CPU1_P2P2_DN<10>")
	)
	(segment
		(start 347.098366 -286.467804)
		(end 347.098366 -286.475424)
		(width 0.0889)
		(layer "In6.Cu")
		(net "UPI_CPU0_CPU1_P2P2_DN<10>")
	)
	(segment
		(start 347.756734 -283.708602)
		(end 347.754448 -283.710126)
		(width 0.0889)
		(layer "In6.Cu")
		(net "UPI_CPU0_CPU1_P2P2_DN<10>")
	)
	(segment
		(start 346.827856 -286.95777)
		(end 346.815664 -286.964882)
		(width 0.0889)
		(layer "In6.Cu")
		(net "UPI_CPU0_CPU1_P2P2_DN<10>")
	)
	(segment
		(start 346.158312 -289.60953)
		(end 346.158312 -290.148264)
		(width 0.0889)
		(layer "In6.Cu")
		(net "UPI_CPU0_CPU1_P2P2_DN<10>")
	)
	(segment
		(start 343.453974 -299.92828)
		(end 341.21979 -302.162464)
		(width 0.14732)
		(layer "In6.Cu")
		(net "UPI_CPU0_CPU1_P2P2_DN<10>")
	)
	(segment
		(start 280.485088 -337.131152)
		(end 272.193512 -345.422728)
		(width 0.14732)
		(layer "In6.Cu")
		(net "UPI_CPU0_CPU1_P2P2_DN<10>")
	)
	(segment
		(start 96.148398 -284.847538)
		(end 96.148398 -284.832044)
		(width 0.0889)
		(layer "In6.Cu")
		(net "UPI_CPU0_CPU1_P2P2_DN<10>")
	)
	(segment
		(start 344.325448 -291.981128)
		(end 344.325448 -294.550084)
		(width 0.0889)
		(layer "In6.Cu")
		(net "UPI_CPU0_CPU1_P2P2_DN<10>")
	)
	(segment
		(start 65.105534 -329.053698)
		(end 66.459354 -324.160388)
		(width 0.14732)
		(layer "In6.Cu")
		(net "UPI_CPU0_CPU1_P2P2_DN<10>")
	)
	(segment
		(start 346.815664 -285.336996)
		(end 346.808806 -285.340806)
		(width 0.0889)
		(layer "In6.Cu")
		(net "UPI_CPU0_CPU1_P2P2_DN<10>")
	)
	(segment
		(start 345.83624 -289.255962)
		(end 345.851226 -289.255962)
		(width 0.0889)
		(layer "In6.Cu")
		(net "UPI_CPU0_CPU1_P2P2_DN<10>")
	)
	(segment
		(start 272.193512 -345.422728)
		(end 272.193512 -369.040156)
		(width 0.14732)
		(layer "In6.Cu")
		(net "UPI_CPU0_CPU1_P2P2_DN<10>")
	)
	(segment
		(start 95.490792 -287.613598)
		(end 95.499682 -287.608518)
		(width 0.0889)
		(layer "In6.Cu")
		(net "UPI_CPU0_CPU1_P2P2_DN<10>")
	)
	(segment
		(start 344.367612 -294.810434)
		(end 344.367358 -294.810688)
		(width 0.14732)
		(layer "In6.Cu")
		(net "UPI_CPU0_CPU1_P2P2_DN<10>")
	)
	(segment
		(start 344.325448 -294.550084)
		(end 344.367612 -294.592248)
		(width 0.0889)
		(layer "In6.Cu")
		(net "UPI_CPU0_CPU1_P2P2_DN<10>")
	)
	(segment
		(start 97.087944 -283.228542)
		(end 97.087944 -283.21127)
		(width 0.0889)
		(layer "In6.Cu")
		(net "UPI_CPU0_CPU1_P2P2_DN<10>")
	)
	(segment
		(start 95.960184 -285.172404)
		(end 95.960946 -285.171896)
		(width 0.0889)
		(layer "In6.Cu")
		(net "UPI_CPU0_CPU1_P2P2_DN<10>")
	)
	(segment
		(start 93.759274 -291.198554)
		(end 94.268544 -290.689284)
		(width 0.0889)
		(layer "In6.Cu")
		(net "UPI_CPU0_CPU1_P2P2_DN<10>")
	)
	(segment
		(start 69.57822 -366.159034)
		(end 64.766698 -354.542344)
		(width 0.14732)
		(layer "In6.Cu")
		(net "UPI_CPU0_CPU1_P2P2_DN<10>")
	)
	(segment
		(start 265.595862 -375.637806)
		(end 162.764216 -384.363722)
		(width 0.14732)
		(layer "In6.Cu")
		(net "UPI_CPU0_CPU1_P2P2_DN<10>")
	)
	(segment
		(start 95.021908 -288.426906)
		(end 95.030036 -288.422334)
		(width 0.0889)
		(layer "In6.Cu")
		(net "UPI_CPU0_CPU1_P2P2_DN<10>")
	)
	(segment
		(start 78.811628 -309.939436)
		(end 90.380058 -300.446186)
		(width 0.14732)
		(layer "In6.Cu")
		(net "UPI_CPU0_CPU1_P2P2_DN<10>")
	)
	(segment
		(start 91.59494 -299.78223)
		(end 92.165932 -299.3136)
		(width 0.14732)
		(layer "In6.Cu")
		(net "UPI_CPU0_CPU1_P2P2_DN<10>")
	)
	(segment
		(start 96.89465 -283.54782)
		(end 96.899984 -283.544772)
		(width 0.0889)
		(layer "In6.Cu")
		(net "UPI_CPU0_CPU1_P2P2_DN<10>")
	)
	(segment
		(start 272.193512 -369.040156)
		(end 265.595862 -375.637806)
		(width 0.14732)
		(layer "In6.Cu")
		(net "UPI_CPU0_CPU1_P2P2_DN<10>")
	)
	(segment
		(start 347.754448 -283.710126)
		(end 347.752416 -283.711396)
		(width 0.0889)
		(layer "In6.Cu")
		(net "UPI_CPU0_CPU1_P2P2_DN<10>")
	)
	(segment
		(start 125.414532 -384.37185)
		(end 96.518984 -380.0856)
		(width 0.14732)
		(layer "In6.Cu")
		(net "UPI_CPU0_CPU1_P2P2_DN<10>")
	)
	(segment
		(start 94.268544 -290.689284)
		(end 94.268544 -289.609784)
		(width 0.0889)
		(layer "In6.Cu")
		(net "UPI_CPU0_CPU1_P2P2_DN<10>")
	)
	(segment
		(start 347.752416 -283.711396)
		(end 347.749876 -283.712666)
		(width 0.0889)
		(layer "In6.Cu")
		(net "UPI_CPU0_CPU1_P2P2_DN<10>")
	)
	(segment
		(start 347.568012 -284.033722)
		(end 347.568012 -284.049216)
		(width 0.0889)
		(layer "In6.Cu")
		(net "UPI_CPU0_CPU1_P2P2_DN<10>")
	)
	(segment
		(start 66.459354 -324.160388)
		(end 68.135246 -320.615818)
		(width 0.14732)
		(layer "In6.Cu")
		(net "UPI_CPU0_CPU1_P2P2_DN<10>")
	)
	(segment
		(start 93.210888 -297.171618)
		(end 93.210888 -291.688012)
		(width 0.14732)
		(layer "In6.Cu")
		(net "UPI_CPU0_CPU1_P2P2_DN<10>")
	)
	(segment
		(start 346.808806 -285.340806)
		(end 346.806774 -285.342076)
		(width 0.0889)
		(layer "In6.Cu")
		(net "UPI_CPU0_CPU1_P2P2_DN<10>")
	)
	(segment
		(start 307.917088 -335.03616)
		(end 285.542736 -335.03616)
		(width 0.14732)
		(layer "In6.Cu")
		(net "UPI_CPU0_CPU1_P2P2_DN<10>")
	)
	(segment
		(start 93.684852 -291.214048)
		(end 93.700346 -291.198554)
		(width 0.0889)
		(layer "In6.Cu")
		(net "UPI_CPU0_CPU1_P2P2_DN<10>")
	)
	(segment
		(start 344.367358 -297.85945)
		(end 344.042492 -298.507404)
		(width 0.14732)
		(layer "In6.Cu")
		(net "UPI_CPU0_CPU1_P2P2_DN<10>")
	)
	(segment
		(start 97.87763 -281.072844)
		(end 97.96653 -281.049222)
		(width 0.0889)
		(layer "In6.Cu")
		(net "UPI_CPU0_CPU1_P2P2_DN<10>")
	)
	(segment
		(start 347.786198 -282.676854)
		(end 347.810328 -282.766008)
		(width 0.0889)
		(layer "In6.Cu")
		(net "UPI_CPU0_CPU1_P2P2_DN<10>")
	)
	(segment
		(start 345.851226 -289.255962)
		(end 345.873324 -289.27806)
		(width 0.0889)
		(layer "In6.Cu")
		(net "UPI_CPU0_CPU1_P2P2_DN<10>")
	)
	(segment
		(start 90.380058 -300.446186)
		(end 91.02344 -300.25086)
		(width 0.14732)
		(layer "In6.Cu")
		(net "UPI_CPU0_CPU1_P2P2_DN<10>")
	)
	(segment
		(start 346.158312 -290.148264)
		(end 344.325448 -291.981128)
		(width 0.0889)
		(layer "In6.Cu")
		(net "UPI_CPU0_CPU1_P2P2_DN<10>")
	)
	(segment
		(start 346.628212 -287.28924)
		(end 346.628212 -287.304734)
		(width 0.0889)
		(layer "In6.Cu")
		(net "UPI_CPU0_CPU1_P2P2_DN<10>")
	)
	(segment
		(start 95.95485 -286.803338)
		(end 95.960184 -286.80029)
		(width 0.0889)
		(layer "In6.Cu")
		(net "UPI_CPU0_CPU1_P2P2_DN<10>")
	)
	(segment
		(start 93.210888 -291.688012)
		(end 93.684852 -291.214048)
		(width 0.14732)
		(layer "In6.Cu")
		(net "UPI_CPU0_CPU1_P2P2_DN<10>")
	)
	(segment
		(start 337.793584 -303.582324)
		(end 316.595506 -324.780402)
		(width 0.14732)
		(layer "In6.Cu")
		(net "UPI_CPU0_CPU1_P2P2_DN<10>")
	)
	(segment
		(start 346.82176 -285.33344)
		(end 346.816426 -285.336488)
		(width 0.0889)
		(layer "In6.Cu")
		(net "UPI_CPU0_CPU1_P2P2_DN<10>")
	)
	(segment
		(start 96.899984 -281.916886)
		(end 96.900746 -281.916378)
		(width 0.0889)
		(layer "In6.Cu")
		(net "UPI_CPU0_CPU1_P2P2_DN<10>")
	)
	(segment
		(start 91.02344 -300.25086)
		(end 91.594686 -299.78223)
		(width 0.14732)
		(layer "In6.Cu")
		(net "UPI_CPU0_CPU1_P2P2_DN<10>")
	)
	(segment
		(start 96.148144 -286.48406)
		(end 96.148144 -286.466788)
		(width 0.0889)
		(layer "In6.Cu")
		(net "UPI_CPU0_CPU1_P2P2_DN<10>")
	)
	(segment
		(start 95.960184 -286.80029)
		(end 95.960946 -286.799782)
		(width 0.0889)
		(layer "In6.Cu")
		(net "UPI_CPU0_CPU1_P2P2_DN<10>")
	)
	(segment
		(start 345.688666 -288.917126)
		(end 345.688666 -289.078416)
		(width 0.0889)
		(layer "In6.Cu")
		(net "UPI_CPU0_CPU1_P2P2_DN<10>")
	)
	(segment
		(start 94.738698 -289.077908)
		(end 94.738698 -288.898584)
		(width 0.0889)
		(layer "In6.Cu")
		(net "UPI_CPU0_CPU1_P2P2_DN<10>")
	)
	(segment
		(start 96.618044 -282.42006)
		(end 96.618044 -282.405836)
		(width 0.0889)
		(layer "In6.Cu")
		(net "UPI_CPU0_CPU1_P2P2_DN<10>")
	)
	(segment
		(start 347.746574 -283.714698)
		(end 347.746574 -283.714444)
		(width 0.0889)
		(layer "In6.Cu")
		(net "UPI_CPU0_CPU1_P2P2_DN<10>")
	)
	(segment
		(start 96.899984 -283.544772)
		(end 96.900746 -283.544264)
		(width 0.0889)
		(layer "In6.Cu")
		(net "UPI_CPU0_CPU1_P2P2_DN<10>")
	)
	(segment
		(start 348.038166 -283.205682)
		(end 348.038166 -283.219906)
		(width 0.0889)
		(layer "In6.Cu")
		(net "UPI_CPU0_CPU1_P2P2_DN<10>")
	)
	(arc
		(start 94.554294 -289.277806)
		(mid 94.66369 -289.193709)
		(end 94.738698 -289.077908)
		(width 0.0889)
		(layer "In6.Cu")
		(net "UPI_CPU0_CPU1_P2P2_DN<10>")
	)
	(arc
		(start 97.087944 -283.21127)
		(mid 97.035674 -283.028905)
		(end 96.900746 -282.895548)
		(width 0.0889)
		(layer "In6.Cu")
		(net "UPI_CPU0_CPU1_P2P2_DN<10>")
	)
	(arc
		(start 347.810328 -282.766008)
		(mid 347.818899 -282.772404)
		(end 347.827346 -282.778962)
		(width 0.0889)
		(layer "In6.Cu")
		(net "UPI_CPU0_CPU1_P2P2_DN<10>")
	)
	(arc
		(start 347.098366 -286.475424)
		(mid 347.026131 -286.751948)
		(end 346.827856 -286.95777)
		(width 0.0889)
		(layer "In6.Cu")
		(net "UPI_CPU0_CPU1_P2P2_DN<10>")
	)
	(arc
		(start 348.038166 -283.219906)
		(mid 347.964175 -283.499472)
		(end 347.76156 -283.705808)
		(width 0.0889)
		(layer "In6.Cu")
		(net "UPI_CPU0_CPU1_P2P2_DN<10>")
	)
	(arc
		(start 345.873324 -289.27806)
		(mid 346.047143 -289.41686)
		(end 346.158312 -289.60953)
		(width 0.0889)
		(layer "In6.Cu")
		(net "UPI_CPU0_CPU1_P2P2_DN<10>")
	)
	(arc
		(start 96.439482 -284.353)
		(mid 96.570396 -284.21664)
		(end 96.618044 -284.033722)
		(width 0.0889)
		(layer "In6.Cu")
		(net "UPI_CPU0_CPU1_P2P2_DN<10>")
	)
	(arc
		(start 94.268544 -289.609784)
		(mid 94.2757 -289.590223)
		(end 94.28353 -289.570922)
		(width 0.0889)
		(layer "In6.Cu")
		(net "UPI_CPU0_CPU1_P2P2_DN<10>")
	)
	(arc
		(start 347.098366 -284.847538)
		(mid 347.024375 -285.127104)
		(end 346.82176 -285.33344)
		(width 0.0889)
		(layer "In6.Cu")
		(net "UPI_CPU0_CPU1_P2P2_DN<10>")
	)
	(arc
		(start 95.678244 -285.661354)
		(mid 95.752235 -285.381788)
		(end 95.95485 -285.175452)
		(width 0.0889)
		(layer "In6.Cu")
		(net "UPI_CPU0_CPU1_P2P2_DN<10>")
	)
	(arc
		(start 347.568012 -284.049216)
		(mid 347.488642 -284.32295)
		(end 347.285818 -284.52318)
		(width 0.0889)
		(layer "In6.Cu")
		(net "UPI_CPU0_CPU1_P2P2_DN<10>")
	)
	(arc
		(start 346.806774 -285.342076)
		(mid 346.628177 -285.661354)
		(end 346.806774 -285.980632)
		(width 0.0889)
		(layer "In6.Cu")
		(net "UPI_CPU0_CPU1_P2P2_DN<10>")
	)
	(arc
		(start 95.960946 -286.799782)
		(mid 96.095879 -286.666428)
		(end 96.148144 -286.48406)
		(width 0.0889)
		(layer "In6.Cu")
		(net "UPI_CPU0_CPU1_P2P2_DN<10>")
	)
	(arc
		(start 97.088198 -281.576526)
		(mid 97.167568 -281.302792)
		(end 97.370392 -281.102562)
		(width 0.0889)
		(layer "In6.Cu")
		(net "UPI_CPU0_CPU1_P2P2_DN<10>")
	)
	(arc
		(start 96.148144 -286.466788)
		(mid 96.095874 -286.284423)
		(end 95.960946 -286.151066)
		(width 0.0889)
		(layer "In6.Cu")
		(net "UPI_CPU0_CPU1_P2P2_DN<10>")
	)
	(arc
		(start 96.618044 -284.033722)
		(mid 96.692035 -283.754156)
		(end 96.89465 -283.54782)
		(width 0.0889)
		(layer "In6.Cu")
		(net "UPI_CPU0_CPU1_P2P2_DN<10>")
	)
	(arc
		(start 95.960946 -286.151066)
		(mid 95.757465 -285.950262)
		(end 95.678244 -285.675578)
		(width 0.0889)
		(layer "In6.Cu")
		(net "UPI_CPU0_CPU1_P2P2_DN<10>")
	)
	(arc
		(start 96.900746 -283.544264)
		(mid 97.035679 -283.41091)
		(end 97.087944 -283.228542)
		(width 0.0889)
		(layer "In6.Cu")
		(net "UPI_CPU0_CPU1_P2P2_DN<10>")
	)
	(arc
		(start 347.827346 -282.778962)
		(mid 347.979833 -282.969058)
		(end 348.038166 -283.205682)
		(width 0.0889)
		(layer "In6.Cu")
		(net "UPI_CPU0_CPU1_P2P2_DN<10>")
	)
	(arc
		(start 97.370392 -281.102562)
		(mid 97.609923 -281.028188)
		(end 97.858072 -281.064716)
		(width 0.0889)
		(layer "In6.Cu")
		(net "UPI_CPU0_CPU1_P2P2_DN<10>")
	)
	(arc
		(start 346.158566 -288.121598)
		(mid 346.078404 -288.393787)
		(end 345.876118 -288.592768)
		(width 0.0889)
		(layer "In6.Cu")
		(net "UPI_CPU0_CPU1_P2P2_DN<10>")
	)
	(arc
		(start 95.678244 -287.28924)
		(mid 95.752235 -287.009674)
		(end 95.95485 -286.803338)
		(width 0.0889)
		(layer "In6.Cu")
		(net "UPI_CPU0_CPU1_P2P2_DN<10>")
	)
	(arc
		(start 347.746574 -283.714444)
		(mid 347.61566 -283.850804)
		(end 347.568012 -284.033722)
		(width 0.0889)
		(layer "In6.Cu")
		(net "UPI_CPU0_CPU1_P2P2_DN<10>")
	)
	(arc
		(start 95.030036 -288.422334)
		(mid 95.16095 -288.285974)
		(end 95.208598 -288.103056)
		(width 0.0889)
		(layer "In6.Cu")
		(net "UPI_CPU0_CPU1_P2P2_DN<10>")
	)
	(arc
		(start 345.867228 -288.597848)
		(mid 345.736314 -288.734208)
		(end 345.688666 -288.917126)
		(width 0.0889)
		(layer "In6.Cu")
		(net "UPI_CPU0_CPU1_P2P2_DN<10>")
	)
	(arc
		(start 96.909636 -281.911298)
		(mid 97.04055 -281.774938)
		(end 97.088198 -281.59202)
		(width 0.0889)
		(layer "In6.Cu")
		(net "UPI_CPU0_CPU1_P2P2_DN<10>")
	)
	(arc
		(start 94.738698 -288.898584)
		(mid 94.81886 -288.626395)
		(end 95.021146 -288.427414)
		(width 0.0889)
		(layer "In6.Cu")
		(net "UPI_CPU0_CPU1_P2P2_DN<10>")
	)
	(arc
		(start 347.276928 -284.52826)
		(mid 347.146014 -284.66462)
		(end 347.098366 -284.847538)
		(width 0.0889)
		(layer "In6.Cu")
		(net "UPI_CPU0_CPU1_P2P2_DN<10>")
	)
	(arc
		(start 346.337128 -287.783778)
		(mid 346.206214 -287.920138)
		(end 346.158566 -288.103056)
		(width 0.0889)
		(layer "In6.Cu")
		(net "UPI_CPU0_CPU1_P2P2_DN<10>")
	)
	(arc
		(start 346.806774 -286.969962)
		(mid 346.67586 -287.106322)
		(end 346.628212 -287.28924)
		(width 0.0889)
		(layer "In6.Cu")
		(net "UPI_CPU0_CPU1_P2P2_DN<10>")
	)
	(arc
		(start 346.815664 -285.985712)
		(mid 347.020736 -286.189391)
		(end 347.098366 -286.467804)
		(width 0.0889)
		(layer "In6.Cu")
		(net "UPI_CPU0_CPU1_P2P2_DN<10>")
	)
	(arc
		(start 95.208598 -288.087562)
		(mid 95.287968 -287.813828)
		(end 95.490792 -287.613598)
		(width 0.0889)
		(layer "In6.Cu")
		(net "UPI_CPU0_CPU1_P2P2_DN<10>")
	)
	(arc
		(start 96.618044 -282.405836)
		(mid 96.692035 -282.12627)
		(end 96.89465 -281.919934)
		(width 0.0889)
		(layer "In6.Cu")
		(net "UPI_CPU0_CPU1_P2P2_DN<10>")
	)
	(arc
		(start 346.628212 -287.304734)
		(mid 346.548842 -287.578468)
		(end 346.346018 -287.778698)
		(width 0.0889)
		(layer "In6.Cu")
		(net "UPI_CPU0_CPU1_P2P2_DN<10>")
	)
	(arc
		(start 94.28353 -289.570922)
		(mid 94.393787 -289.401162)
		(end 94.554294 -289.277806)
		(width 0.0889)
		(layer "In6.Cu")
		(net "UPI_CPU0_CPU1_P2P2_DN<10>")
	)
	(arc
		(start 95.499682 -287.608518)
		(mid 95.630596 -287.472158)
		(end 95.678244 -287.28924)
		(width 0.0889)
		(layer "In6.Cu")
		(net "UPI_CPU0_CPU1_P2P2_DN<10>")
	)
	(arc
		(start 96.900746 -282.895548)
		(mid 96.697265 -282.694744)
		(end 96.618044 -282.42006)
		(width 0.0889)
		(layer "In6.Cu")
		(net "UPI_CPU0_CPU1_P2P2_DN<10>")
	)
	(arc
		(start 95.969836 -285.166816)
		(mid 96.10075 -285.030456)
		(end 96.148398 -284.847538)
		(width 0.0889)
		(layer "In6.Cu")
		(net "UPI_CPU0_CPU1_P2P2_DN<10>")
	)
	(arc
		(start 96.148398 -284.832044)
		(mid 96.227768 -284.55831)
		(end 96.430592 -284.35808)
		(width 0.0889)
		(layer "In6.Cu")
		(net "UPI_CPU0_CPU1_P2P2_DN<10>")
	)
	(arc
		(start 345.688666 -289.078416)
		(mid 345.749628 -289.17785)
		(end 345.83624 -289.255962)
		(width 0.0889)
		(layer "In6.Cu")
		(net "UPI_CPU0_CPU1_P2P2_DN<10>")
	)
	(arc
		(start 97.858072 -281.064716)
		(mid 97.867888 -281.06869)
		(end 97.87763 -281.072844)
		(width 0.0889)
		(layer "In6.Cu")
		(net "UPI_CPU0_CPU1_P2P2_DN<10>")
	)
	(segment
		(start 86.845648 -280.242264)
		(end 86.845648 -280.77795)
		(width 0.13208)
		(layer "F.Cu")
		(net "UPI_CPU0_CPU1_P2P2_DN<0>")
	)
	(segment
		(start 86.845648 -280.77795)
		(end 86.845394 -280.778204)
		(width 0.13208)
		(layer "F.Cu")
		(net "UPI_CPU0_CPU1_P2P2_DN<0>")
	)
	(segment
		(start 356.870762 -272.917158)
		(end 356.870762 -273.453098)
		(width 0.13208)
		(layer "F.Cu")
		(net "UPI_CPU0_CPU1_P2P2_DN<0>")
	)
	(segment
		(start 356.683564 -286.799782)
		(end 356.68966 -286.803338)
		(width 0.0889)
		(layer "In6.Cu")
		(net "UPI_CPU0_CPU1_P2P2_DN<0>")
	)
	(segment
		(start 85.622892 -283.544264)
		(end 85.631782 -283.539184)
		(width 0.0889)
		(layer "In6.Cu")
		(net "UPI_CPU0_CPU1_P2P2_DN<0>")
	)
	(segment
		(start 52.797964 -316.53353)
		(end 53.153056 -315.676026)
		(width 0.14732)
		(layer "In6.Cu")
		(net "UPI_CPU0_CPU1_P2P2_DN<0>")
	)
	(segment
		(start 357.905812 -277.512526)
		(end 357.905812 -277.540974)
		(width 0.0889)
		(layer "In6.Cu")
		(net "UPI_CPU0_CPU1_P2P2_DN<0>")
	)
	(segment
		(start 56.440578 -356.629716)
		(end 56.440578 -336.857086)
		(width 0.14732)
		(layer "In6.Cu")
		(net "UPI_CPU0_CPU1_P2P2_DN<0>")
	)
	(segment
		(start 86.562692 -281.916378)
		(end 86.571582 -281.911298)
		(width 0.0889)
		(layer "In6.Cu")
		(net "UPI_CPU0_CPU1_P2P2_DN<0>")
	)
	(segment
		(start 81.474056 -291.990526)
		(end 83.510374 -289.954208)
		(width 0.14732)
		(layer "In6.Cu")
		(net "UPI_CPU0_CPU1_P2P2_DN<0>")
	)
	(segment
		(start 356.966266 -280.769568)
		(end 356.966266 -280.78684)
		(width 0.0889)
		(layer "In6.Cu")
		(net "UPI_CPU0_CPU1_P2P2_DN<0>")
	)
	(segment
		(start 280.722832 -349.080836)
		(end 280.722832 -372.758716)
		(width 0.14732)
		(layer "In6.Cu")
		(net "UPI_CPU0_CPU1_P2P2_DN<0>")
	)
	(segment
		(start 84.54136 -284.672532)
		(end 84.855812 -284.35808)
		(width 0.0889)
		(layer "In6.Cu")
		(net "UPI_CPU0_CPU1_P2P2_DN<0>")
	)
	(segment
		(start 54.119272 -333.478378)
		(end 50.739294 -330.0984)
		(width 0.14732)
		(layer "In6.Cu")
		(net "UPI_CPU0_CPU1_P2P2_DN<0>")
	)
	(segment
		(start 85.810344 -283.219906)
		(end 85.810344 -283.201364)
		(width 0.0889)
		(layer "In6.Cu")
		(net "UPI_CPU0_CPU1_P2P2_DN<0>")
	)
	(segment
		(start 280.722832 -372.758716)
		(end 269.594076 -383.889504)
		(width 0.14732)
		(layer "In6.Cu")
		(net "UPI_CPU0_CPU1_P2P2_DN<0>")
	)
	(segment
		(start 356.496366 -288.09442)
		(end 356.496366 -288.195258)
		(width 0.0889)
		(layer "In6.Cu")
		(net "UPI_CPU0_CPU1_P2P2_DN<0>")
	)
	(segment
		(start 87.158068 -280.778204)
		(end 86.845394 -280.778204)
		(width 0.0889)
		(layer "In6.Cu")
		(net "UPI_CPU0_CPU1_P2P2_DN<0>")
	)
	(segment
		(start 356.68966 -287.775142)
		(end 356.683564 -287.778698)
		(width 0.0889)
		(layer "In6.Cu")
		(net "UPI_CPU0_CPU1_P2P2_DN<0>")
	)
	(segment
		(start 69.772276 -305.494944)
		(end 80.198976 -295.068752)
		(width 0.14732)
		(layer "In6.Cu")
		(net "UPI_CPU0_CPU1_P2P2_DN<0>")
	)
	(segment
		(start 53.986176 -314.842652)
		(end 55.778908 -313.88431)
		(width 0.14732)
		(layer "In6.Cu")
		(net "UPI_CPU0_CPU1_P2P2_DN<0>")
	)
	(segment
		(start 84.855812 -284.35808)
		(end 85.152992 -284.35808)
		(width 0.0889)
		(layer "In6.Cu")
		(net "UPI_CPU0_CPU1_P2P2_DN<0>")
	)
	(segment
		(start 53.153056 -315.676026)
		(end 53.986176 -314.842652)
		(width 0.14732)
		(layer "In6.Cu")
		(net "UPI_CPU0_CPU1_P2P2_DN<0>")
	)
	(segment
		(start 357.614474 -277.027894)
		(end 357.622602 -277.032466)
		(width 0.0889)
		(layer "In6.Cu")
		(net "UPI_CPU0_CPU1_P2P2_DN<0>")
	)
	(segment
		(start 52.662074 -317.510668)
		(end 52.73294 -317.42253)
		(width 0.14732)
		(layer "In6.Cu")
		(net "UPI_CPU0_CPU1_P2P2_DN<0>")
	)
	(segment
		(start 357.153464 -278.82596)
		(end 357.144574 -278.83104)
		(width 0.0889)
		(layer "In6.Cu")
		(net "UPI_CPU0_CPU1_P2P2_DN<0>")
	)
	(segment
		(start 357.623364 -274.756372)
		(end 357.614474 -274.761452)
		(width 0.0889)
		(layer "In6.Cu")
		(net "UPI_CPU0_CPU1_P2P2_DN<0>")
	)
	(segment
		(start 50.740056 -318.653922)
		(end 51.950366 -317.806578)
		(width 0.14732)
		(layer "In6.Cu")
		(net "UPI_CPU0_CPU1_P2P2_DN<0>")
	)
	(segment
		(start 341.531194 -311.594754)
		(end 323.838062 -329.287886)
		(width 0.14732)
		(layer "In6.Cu")
		(net "UPI_CPU0_CPU1_P2P2_DN<0>")
	)
	(segment
		(start 58.247026 -312.235088)
		(end 58.82386 -311.996328)
		(width 0.14732)
		(layer "In6.Cu")
		(net "UPI_CPU0_CPU1_P2P2_DN<0>")
	)
	(segment
		(start 66.34734 -307.783992)
		(end 69.772276 -305.494944)
		(width 0.14732)
		(layer "In6.Cu")
		(net "UPI_CPU0_CPU1_P2P2_DN<0>")
	)
	(segment
		(start 357.614474 -275.400008)
		(end 357.623364 -275.405088)
		(width 0.0889)
		(layer "In6.Cu")
		(net "UPI_CPU0_CPU1_P2P2_DN<0>")
	)
	(segment
		(start 50.282348 -319.30594)
		(end 50.740056 -318.653922)
		(width 0.14732)
		(layer "In6.Cu")
		(net "UPI_CPU0_CPU1_P2P2_DN<0>")
	)
	(segment
		(start 356.496112 -292.137592)
		(end 356.495858 -292.137846)
		(width 0.0889)
		(layer "In6.Cu")
		(net "UPI_CPU0_CPU1_P2P2_DN<0>")
	)
	(segment
		(start 87.032592 -281.102562)
		(end 87.041482 -281.097482)
		(width 0.0889)
		(layer "In6.Cu")
		(net "UPI_CPU0_CPU1_P2P2_DN<0>")
	)
	(segment
		(start 87.215472 -280.835608)
		(end 87.158068 -280.778204)
		(width 0.0889)
		(layer "In6.Cu")
		(net "UPI_CPU0_CPU1_P2P2_DN<0>")
	)
	(segment
		(start 58.82386 -311.996328)
		(end 59.68111 -311.825386)
		(width 0.14732)
		(layer "In6.Cu")
		(net "UPI_CPU0_CPU1_P2P2_DN<0>")
	)
	(segment
		(start 51.950366 -317.806578)
		(end 52.25161 -317.753492)
		(width 0.14732)
		(layer "In6.Cu")
		(net "UPI_CPU0_CPU1_P2P2_DN<0>")
	)
	(segment
		(start 86.556596 -281.919934)
		(end 86.562692 -281.916378)
		(width 0.0889)
		(layer "In6.Cu")
		(net "UPI_CPU0_CPU1_P2P2_DN<0>")
	)
	(segment
		(start 65.683638 -308.059074)
		(end 66.34734 -307.783992)
		(width 0.14732)
		(layer "In6.Cu")
		(net "UPI_CPU0_CPU1_P2P2_DN<0>")
	)
	(segment
		(start 50.090832 -324.724522)
		(end 50.091086 -320.390774)
		(width 0.14732)
		(layer "In6.Cu")
		(net "UPI_CPU0_CPU1_P2P2_DN<0>")
	)
	(segment
		(start 357.622602 -277.032466)
		(end 357.623364 -277.032974)
		(width 0.0889)
		(layer "In6.Cu")
		(net "UPI_CPU0_CPU1_P2P2_DN<0>")
	)
	(segment
		(start 52.73294 -317.42253)
		(end 52.797964 -317.265558)
		(width 0.14732)
		(layer "In6.Cu")
		(net "UPI_CPU0_CPU1_P2P2_DN<0>")
	)
	(segment
		(start 69.64426 -378.510546)
		(end 62.575694 -371.44198)
		(width 0.14732)
		(layer "In6.Cu")
		(net "UPI_CPU0_CPU1_P2P2_DN<0>")
	)
	(segment
		(start 356.537768 -299.11548)
		(end 345.845638 -309.80761)
		(width 0.14732)
		(layer "In6.Cu")
		(net "UPI_CPU0_CPU1_P2P2_DN<0>")
	)
	(segment
		(start 84.14766 -289.376866)
		(end 84.14766 -285.623)
		(width 0.0889)
		(layer "In6.Cu")
		(net "UPI_CPU0_CPU1_P2P2_DN<0>")
	)
	(segment
		(start 52.25161 -317.753492)
		(end 52.662074 -317.510668)
		(width 0.14732)
		(layer "In6.Cu")
		(net "UPI_CPU0_CPU1_P2P2_DN<0>")
	)
	(segment
		(start 356.972108 -288.863278)
		(end 356.966012 -288.97326)
		(width 0.0889)
		(layer "In6.Cu")
		(net "UPI_CPU0_CPU1_P2P2_DN<0>")
	)
	(segment
		(start 356.496366 -286.466788)
		(end 356.496366 -286.48406)
		(width 0.0889)
		(layer "In6.Cu")
		(net "UPI_CPU0_CPU1_P2P2_DN<0>")
	)
	(segment
		(start 311.308496 -343.537032)
		(end 286.98063 -343.537032)
		(width 0.14732)
		(layer "In6.Cu")
		(net "UPI_CPU0_CPU1_P2P2_DN<0>")
	)
	(segment
		(start 356.538022 -293.136574)
		(end 356.537768 -293.136828)
		(width 0.14732)
		(layer "In6.Cu")
		(net "UPI_CPU0_CPU1_P2P2_DN<0>")
	)
	(segment
		(start 323.838062 -329.287886)
		(end 322.622164 -332.223364)
		(width 0.14732)
		(layer "In6.Cu")
		(net "UPI_CPU0_CPU1_P2P2_DN<0>")
	)
	(segment
		(start 356.538022 -292.829488)
		(end 356.538022 -292.851586)
		(width 0.0889)
		(layer "In6.Cu")
		(net "UPI_CPU0_CPU1_P2P2_DN<0>")
	)
	(segment
		(start 357.623364 -276.384258)
		(end 357.614474 -276.389338)
		(width 0.0889)
		(layer "In6.Cu")
		(net "UPI_CPU0_CPU1_P2P2_DN<0>")
	)
	(segment
		(start 83.810348 -289.65525)
		(end 83.869276 -289.65525)
		(width 0.0889)
		(layer "In6.Cu")
		(net "UPI_CPU0_CPU1_P2P2_DN<0>")
	)
	(segment
		(start 126.864364 -392.998452)
		(end 92.213684 -387.858254)
		(width 0.14732)
		(layer "In6.Cu")
		(net "UPI_CPU0_CPU1_P2P2_DN<0>")
	)
	(segment
		(start 356.496366 -284.838902)
		(end 356.496366 -284.856174)
		(width 0.0889)
		(layer "In6.Cu")
		(net "UPI_CPU0_CPU1_P2P2_DN<0>")
	)
	(segment
		(start 50.739294 -330.0984)
		(end 50.090832 -328.532744)
		(width 0.14732)
		(layer "In6.Cu")
		(net "UPI_CPU0_CPU1_P2P2_DN<0>")
	)
	(segment
		(start 80.198976 -295.068752)
		(end 81.474056 -291.990526)
		(width 0.14732)
		(layer "In6.Cu")
		(net "UPI_CPU0_CPU1_P2P2_DN<0>")
	)
	(segment
		(start 92.213684 -387.858254)
		(end 69.64426 -378.510546)
		(width 0.14732)
		(layer "In6.Cu")
		(net "UPI_CPU0_CPU1_P2P2_DN<0>")
	)
	(segment
		(start 286.98063 -343.537032)
		(end 285.761684 -344.041984)
		(width 0.14732)
		(layer "In6.Cu")
		(net "UPI_CPU0_CPU1_P2P2_DN<0>")
	)
	(segment
		(start 357.905812 -275.880576)
		(end 357.905812 -275.8948)
		(width 0.0889)
		(layer "In6.Cu")
		(net "UPI_CPU0_CPU1_P2P2_DN<0>")
	)
	(segment
		(start 356.495858 -292.137846)
		(end 356.495858 -292.787324)
		(width 0.0889)
		(layer "In6.Cu")
		(net "UPI_CPU0_CPU1_P2P2_DN<0>")
	)
	(segment
		(start 83.51139 -289.954208)
		(end 83.794854 -289.670744)
		(width 0.14732)
		(layer "In6.Cu")
		(net "UPI_CPU0_CPU1_P2P2_DN<0>")
	)
	(segment
		(start 83.510374 -289.954208)
		(end 83.51139 -289.954208)
		(width 0.14732)
		(layer "In6.Cu")
		(net "UPI_CPU0_CPU1_P2P2_DN<0>")
	)
	(segment
		(start 345.845638 -309.80761)
		(end 341.531194 -311.594754)
		(width 0.14732)
		(layer "In6.Cu")
		(net "UPI_CPU0_CPU1_P2P2_DN<0>")
	)
	(segment
		(start 56.440578 -336.857086)
		(end 55.862474 -335.46923)
		(width 0.14732)
		(layer "In6.Cu")
		(net "UPI_CPU0_CPU1_P2P2_DN<0>")
	)
	(segment
		(start 85.152992 -284.35808)
		(end 85.161882 -284.353)
		(width 0.0889)
		(layer "In6.Cu")
		(net "UPI_CPU0_CPU1_P2P2_DN<0>")
	)
	(segment
		(start 55.862474 -335.46923)
		(end 54.119272 -333.478378)
		(width 0.14732)
		(layer "In6.Cu")
		(net "UPI_CPU0_CPU1_P2P2_DN<0>")
	)
	(segment
		(start 50.090832 -328.532744)
		(end 50.090832 -324.724522)
		(width 0.14732)
		(layer "In6.Cu")
		(net "UPI_CPU0_CPU1_P2P2_DN<0>")
	)
	(segment
		(start 356.68966 -284.519624)
		(end 356.683564 -284.52318)
		(width 0.0889)
		(layer "In6.Cu")
		(net "UPI_CPU0_CPU1_P2P2_DN<0>")
	)
	(segment
		(start 357.435912 -281.582114)
		(end 357.435912 -281.601926)
		(width 0.0889)
		(layer "In6.Cu")
		(net "UPI_CPU0_CPU1_P2P2_DN<0>")
	)
	(segment
		(start 356.966266 -284.025086)
		(end 356.966266 -284.033722)
		(width 0.0889)
		(layer "In6.Cu")
		(net "UPI_CPU0_CPU1_P2P2_DN<0>")
	)
	(segment
		(start 52.797964 -317.265558)
		(end 52.797964 -316.53353)
		(width 0.14732)
		(layer "In6.Cu")
		(net "UPI_CPU0_CPU1_P2P2_DN<0>")
	)
	(segment
		(start 356.495858 -292.787324)
		(end 356.538022 -292.829488)
		(width 0.0889)
		(layer "In6.Cu")
		(net "UPI_CPU0_CPU1_P2P2_DN<0>")
	)
	(segment
		(start 83.794854 -289.670744)
		(end 83.810348 -289.65525)
		(width 0.0889)
		(layer "In6.Cu")
		(net "UPI_CPU0_CPU1_P2P2_DN<0>")
	)
	(segment
		(start 84.14766 -285.623)
		(end 84.54136 -284.672532)
		(width 0.0889)
		(layer "In6.Cu")
		(net "UPI_CPU0_CPU1_P2P2_DN<0>")
	)
	(segment
		(start 50.091086 -320.390774)
		(end 50.282348 -319.30594)
		(width 0.14732)
		(layer "In6.Cu")
		(net "UPI_CPU0_CPU1_P2P2_DN<0>")
	)
	(segment
		(start 356.538022 -292.851586)
		(end 356.538022 -293.136574)
		(width 0.14732)
		(layer "In6.Cu")
		(net "UPI_CPU0_CPU1_P2P2_DN<0>")
	)
	(segment
		(start 55.778908 -313.88431)
		(end 58.247026 -312.235088)
		(width 0.14732)
		(layer "In6.Cu")
		(net "UPI_CPU0_CPU1_P2P2_DN<0>")
	)
	(segment
		(start 357.027226 -273.724116)
		(end 357.11638 -273.747992)
		(width 0.0889)
		(layer "In6.Cu")
		(net "UPI_CPU0_CPU1_P2P2_DN<0>")
	)
	(segment
		(start 59.68111 -311.825386)
		(end 61.445648 -310.646318)
		(width 0.14732)
		(layer "In6.Cu")
		(net "UPI_CPU0_CPU1_P2P2_DN<0>")
	)
	(segment
		(start 357.623364 -278.012144)
		(end 357.614474 -278.017224)
		(width 0.0889)
		(layer "In6.Cu")
		(net "UPI_CPU0_CPU1_P2P2_DN<0>")
	)
	(segment
		(start 356.966012 -288.97326)
		(end 356.957376 -289.131248)
		(width 0.0889)
		(layer "In6.Cu")
		(net "UPI_CPU0_CPU1_P2P2_DN<0>")
	)
	(segment
		(start 285.761684 -344.041984)
		(end 280.722832 -349.080836)
		(width 0.14732)
		(layer "In6.Cu")
		(net "UPI_CPU0_CPU1_P2P2_DN<0>")
	)
	(segment
		(start 356.870762 -273.453098)
		(end 357.027226 -273.724116)
		(width 0.0889)
		(layer "In6.Cu")
		(net "UPI_CPU0_CPU1_P2P2_DN<0>")
	)
	(segment
		(start 62.412372 -310.24576)
		(end 65.683638 -308.059074)
		(width 0.14732)
		(layer "In6.Cu")
		(net "UPI_CPU0_CPU1_P2P2_DN<0>")
	)
	(segment
		(start 357.905812 -274.257008)
		(end 357.905812 -274.27682)
		(width 0.0889)
		(layer "In6.Cu")
		(net "UPI_CPU0_CPU1_P2P2_DN<0>")
	)
	(segment
		(start 357.435912 -283.201364)
		(end 357.435912 -283.229812)
		(width 0.0889)
		(layer "In6.Cu")
		(net "UPI_CPU0_CPU1_P2P2_DN<0>")
	)
	(segment
		(start 61.445648 -310.646318)
		(end 62.412372 -310.24576)
		(width 0.14732)
		(layer "In6.Cu")
		(net "UPI_CPU0_CPU1_P2P2_DN<0>")
	)
	(segment
		(start 62.575694 -371.44198)
		(end 56.440578 -356.629716)
		(width 0.14732)
		(layer "In6.Cu")
		(net "UPI_CPU0_CPU1_P2P2_DN<0>")
	)
	(segment
		(start 356.537768 -293.136828)
		(end 356.537768 -299.11548)
		(width 0.14732)
		(layer "In6.Cu")
		(net "UPI_CPU0_CPU1_P2P2_DN<0>")
	)
	(segment
		(start 161.732722 -392.998452)
		(end 126.864364 -392.998452)
		(width 0.14732)
		(layer "In6.Cu")
		(net "UPI_CPU0_CPU1_P2P2_DN<0>")
	)
	(segment
		(start 356.683564 -285.171896)
		(end 356.68966 -285.175452)
		(width 0.0889)
		(layer "In6.Cu")
		(net "UPI_CPU0_CPU1_P2P2_DN<0>")
	)
	(segment
		(start 356.966266 -285.661354)
		(end 356.966266 -285.675578)
		(width 0.0889)
		(layer "In6.Cu")
		(net "UPI_CPU0_CPU1_P2P2_DN<0>")
	)
	(segment
		(start 357.435912 -279.954228)
		(end 357.435912 -279.982676)
		(width 0.0889)
		(layer "In6.Cu")
		(net "UPI_CPU0_CPU1_P2P2_DN<0>")
	)
	(segment
		(start 85.340444 -284.033722)
		(end 85.340444 -284.023816)
		(width 0.0889)
		(layer "In6.Cu")
		(net "UPI_CPU0_CPU1_P2P2_DN<0>")
	)
	(segment
		(start 356.496112 -289.677348)
		(end 356.496112 -292.137592)
		(width 0.0889)
		(layer "In6.Cu")
		(net "UPI_CPU0_CPU1_P2P2_DN<0>")
	)
	(segment
		(start 357.62946 -276.380702)
		(end 357.623364 -276.384258)
		(width 0.0889)
		(layer "In6.Cu")
		(net "UPI_CPU0_CPU1_P2P2_DN<0>")
	)
	(segment
		(start 357.435912 -278.336502)
		(end 357.435912 -278.346408)
		(width 0.0889)
		(layer "In6.Cu")
		(net "UPI_CPU0_CPU1_P2P2_DN<0>")
	)
	(segment
		(start 357.144574 -279.469596)
		(end 357.153464 -279.474676)
		(width 0.0889)
		(layer "In6.Cu")
		(net "UPI_CPU0_CPU1_P2P2_DN<0>")
	)
	(segment
		(start 269.594076 -383.889504)
		(end 161.732722 -392.998452)
		(width 0.14732)
		(layer "In6.Cu")
		(net "UPI_CPU0_CPU1_P2P2_DN<0>")
	)
	(segment
		(start 356.966266 -282.3972)
		(end 356.966266 -282.414472)
		(width 0.0889)
		(layer "In6.Cu")
		(net "UPI_CPU0_CPU1_P2P2_DN<0>")
	)
	(segment
		(start 86.092792 -282.730194)
		(end 86.101682 -282.725114)
		(width 0.0889)
		(layer "In6.Cu")
		(net "UPI_CPU0_CPU1_P2P2_DN<0>")
	)
	(segment
		(start 322.622164 -332.223364)
		(end 311.308496 -343.537032)
		(width 0.14732)
		(layer "In6.Cu")
		(net "UPI_CPU0_CPU1_P2P2_DN<0>")
	)
	(segment
		(start 83.869276 -289.65525)
		(end 84.14766 -289.376866)
		(width 0.0889)
		(layer "In6.Cu")
		(net "UPI_CPU0_CPU1_P2P2_DN<0>")
	)
	(segment
		(start 87.026496 -281.106118)
		(end 87.032592 -281.102562)
		(width 0.0889)
		(layer "In6.Cu")
		(net "UPI_CPU0_CPU1_P2P2_DN<0>")
	)
	(arc
		(start 357.435912 -283.229812)
		(mid 357.357801 -283.506761)
		(end 357.153464 -283.709364)
		(width 0.0889)
		(layer "In6.Cu")
		(net "UPI_CPU0_CPU1_P2P2_DN<0>")
	)
	(arc
		(start 357.435912 -275.08073)
		(mid 357.435964 -275.088097)
		(end 357.436166 -275.095462)
		(width 0.0889)
		(layer "In6.Cu")
		(net "UPI_CPU0_CPU1_P2P2_DN<0>")
	)
	(arc
		(start 357.436166 -276.698456)
		(mid 357.436072 -276.706838)
		(end 357.436166 -276.71522)
		(width 0.0889)
		(layer "In6.Cu")
		(net "UPI_CPU0_CPU1_P2P2_DN<0>")
	)
	(arc
		(start 357.435912 -278.346408)
		(mid 357.357801 -278.623357)
		(end 357.153464 -278.82596)
		(width 0.0889)
		(layer "In6.Cu")
		(net "UPI_CPU0_CPU1_P2P2_DN<0>")
	)
	(arc
		(start 356.68966 -286.803338)
		(mid 356.96611 -287.28924)
		(end 356.68966 -287.775142)
		(width 0.0889)
		(layer "In6.Cu")
		(net "UPI_CPU0_CPU1_P2P2_DN<0>")
	)
	(arc
		(start 357.614474 -274.761452)
		(mid 357.48356 -274.897812)
		(end 357.435912 -275.08073)
		(width 0.0889)
		(layer "In6.Cu")
		(net "UPI_CPU0_CPU1_P2P2_DN<0>")
	)
	(arc
		(start 86.571582 -281.911298)
		(mid 86.702496 -281.774938)
		(end 86.750144 -281.59202)
		(width 0.0889)
		(layer "In6.Cu")
		(net "UPI_CPU0_CPU1_P2P2_DN<0>")
	)
	(arc
		(start 356.683564 -287.778698)
		(mid 356.548631 -287.912052)
		(end 356.496366 -288.09442)
		(width 0.0889)
		(layer "In6.Cu")
		(net "UPI_CPU0_CPU1_P2P2_DN<0>")
	)
	(arc
		(start 357.153464 -281.102562)
		(mid 357.357799 -281.305167)
		(end 357.435912 -281.582114)
		(width 0.0889)
		(layer "In6.Cu")
		(net "UPI_CPU0_CPU1_P2P2_DN<0>")
	)
	(arc
		(start 357.905812 -277.540974)
		(mid 357.82565 -277.813163)
		(end 357.623364 -278.012144)
		(width 0.0889)
		(layer "In6.Cu")
		(net "UPI_CPU0_CPU1_P2P2_DN<0>")
	)
	(arc
		(start 356.68966 -285.175452)
		(mid 356.892247 -285.381803)
		(end 356.966266 -285.661354)
		(width 0.0889)
		(layer "In6.Cu")
		(net "UPI_CPU0_CPU1_P2P2_DN<0>")
	)
	(arc
		(start 357.153464 -280.453846)
		(mid 357.018531 -280.5872)
		(end 356.966266 -280.769568)
		(width 0.0889)
		(layer "In6.Cu")
		(net "UPI_CPU0_CPU1_P2P2_DN<0>")
	)
	(arc
		(start 357.153464 -282.081478)
		(mid 357.018531 -282.214832)
		(end 356.966266 -282.3972)
		(width 0.0889)
		(layer "In6.Cu")
		(net "UPI_CPU0_CPU1_P2P2_DN<0>")
	)
	(arc
		(start 356.683564 -286.151066)
		(mid 356.548631 -286.28442)
		(end 356.496366 -286.466788)
		(width 0.0889)
		(layer "In6.Cu")
		(net "UPI_CPU0_CPU1_P2P2_DN<0>")
	)
	(arc
		(start 356.957376 -289.131248)
		(mid 356.85035 -289.320983)
		(end 356.681532 -289.458654)
		(width 0.0889)
		(layer "In6.Cu")
		(net "UPI_CPU0_CPU1_P2P2_DN<0>")
	)
	(arc
		(start 86.101682 -282.725114)
		(mid 86.232596 -282.588754)
		(end 86.280244 -282.405836)
		(width 0.0889)
		(layer "In6.Cu")
		(net "UPI_CPU0_CPU1_P2P2_DN<0>")
	)
	(arc
		(start 85.161882 -284.353)
		(mid 85.292796 -284.21664)
		(end 85.340444 -284.033722)
		(width 0.0889)
		(layer "In6.Cu")
		(net "UPI_CPU0_CPU1_P2P2_DN<0>")
	)
	(arc
		(start 356.966266 -285.675578)
		(mid 356.887047 -285.950263)
		(end 356.683564 -286.151066)
		(width 0.0889)
		(layer "In6.Cu")
		(net "UPI_CPU0_CPU1_P2P2_DN<0>")
	)
	(arc
		(start 357.153464 -279.474676)
		(mid 357.357799 -279.677281)
		(end 357.435912 -279.954228)
		(width 0.0889)
		(layer "In6.Cu")
		(net "UPI_CPU0_CPU1_P2P2_DN<0>")
	)
	(arc
		(start 357.905812 -275.8948)
		(mid 357.831896 -276.174302)
		(end 357.62946 -276.380702)
		(width 0.0889)
		(layer "In6.Cu")
		(net "UPI_CPU0_CPU1_P2P2_DN<0>")
	)
	(arc
		(start 357.144574 -278.83104)
		(mid 356.965977 -279.150318)
		(end 357.144574 -279.469596)
		(width 0.0889)
		(layer "In6.Cu")
		(net "UPI_CPU0_CPU1_P2P2_DN<0>")
	)
	(arc
		(start 356.681532 -289.458654)
		(mid 356.568339 -289.550641)
		(end 356.496112 -289.677348)
		(width 0.0889)
		(layer "In6.Cu")
		(net "UPI_CPU0_CPU1_P2P2_DN<0>")
	)
	(arc
		(start 357.153464 -282.730194)
		(mid 357.35575 -282.929175)
		(end 357.435912 -283.201364)
		(width 0.0889)
		(layer "In6.Cu")
		(net "UPI_CPU0_CPU1_P2P2_DN<0>")
	)
	(arc
		(start 85.810344 -283.201364)
		(mid 85.890506 -282.929175)
		(end 86.092792 -282.730194)
		(width 0.0889)
		(layer "In6.Cu")
		(net "UPI_CPU0_CPU1_P2P2_DN<0>")
	)
	(arc
		(start 357.623364 -277.032974)
		(mid 357.827699 -277.235579)
		(end 357.905812 -277.512526)
		(width 0.0889)
		(layer "In6.Cu")
		(net "UPI_CPU0_CPU1_P2P2_DN<0>")
	)
	(arc
		(start 86.750144 -281.59202)
		(mid 86.82406 -281.312518)
		(end 87.026496 -281.106118)
		(width 0.0889)
		(layer "In6.Cu")
		(net "UPI_CPU0_CPU1_P2P2_DN<0>")
	)
	(arc
		(start 356.966266 -284.033722)
		(mid 356.892275 -284.313288)
		(end 356.68966 -284.519624)
		(width 0.0889)
		(layer "In6.Cu")
		(net "UPI_CPU0_CPU1_P2P2_DN<0>")
	)
	(arc
		(start 357.623364 -273.777456)
		(mid 357.827699 -273.980061)
		(end 357.905812 -274.257008)
		(width 0.0889)
		(layer "In6.Cu")
		(net "UPI_CPU0_CPU1_P2P2_DN<0>")
	)
	(arc
		(start 356.496366 -284.856174)
		(mid 356.548636 -285.038539)
		(end 356.683564 -285.171896)
		(width 0.0889)
		(layer "In6.Cu")
		(net "UPI_CPU0_CPU1_P2P2_DN<0>")
	)
	(arc
		(start 356.496366 -286.48406)
		(mid 356.548636 -286.666425)
		(end 356.683564 -286.799782)
		(width 0.0889)
		(layer "In6.Cu")
		(net "UPI_CPU0_CPU1_P2P2_DN<0>")
	)
	(arc
		(start 357.614474 -278.017224)
		(mid 357.48356 -278.153584)
		(end 357.435912 -278.336502)
		(width 0.0889)
		(layer "In6.Cu")
		(net "UPI_CPU0_CPU1_P2P2_DN<0>")
	)
	(arc
		(start 357.435912 -279.982676)
		(mid 357.35575 -280.254865)
		(end 357.153464 -280.453846)
		(width 0.0889)
		(layer "In6.Cu")
		(net "UPI_CPU0_CPU1_P2P2_DN<0>")
	)
	(arc
		(start 357.153464 -283.709364)
		(mid 357.018531 -283.842718)
		(end 356.966266 -284.025086)
		(width 0.0889)
		(layer "In6.Cu")
		(net "UPI_CPU0_CPU1_P2P2_DN<0>")
	)
	(arc
		(start 356.683564 -284.52318)
		(mid 356.548631 -284.656534)
		(end 356.496366 -284.838902)
		(width 0.0889)
		(layer "In6.Cu")
		(net "UPI_CPU0_CPU1_P2P2_DN<0>")
	)
	(arc
		(start 86.280244 -282.405836)
		(mid 86.35416 -282.126334)
		(end 86.556596 -281.919934)
		(width 0.0889)
		(layer "In6.Cu")
		(net "UPI_CPU0_CPU1_P2P2_DN<0>")
	)
	(arc
		(start 85.340444 -284.023816)
		(mid 85.418555 -283.746867)
		(end 85.622892 -283.544264)
		(width 0.0889)
		(layer "In6.Cu")
		(net "UPI_CPU0_CPU1_P2P2_DN<0>")
	)
	(arc
		(start 356.682548 -288.439606)
		(mid 356.877082 -288.617442)
		(end 356.972108 -288.863278)
		(width 0.0889)
		(layer "In6.Cu")
		(net "UPI_CPU0_CPU1_P2P2_DN<0>")
	)
	(arc
		(start 357.905812 -274.27682)
		(mid 357.827701 -274.553769)
		(end 357.623364 -274.756372)
		(width 0.0889)
		(layer "In6.Cu")
		(net "UPI_CPU0_CPU1_P2P2_DN<0>")
	)
	(arc
		(start 356.966266 -280.78684)
		(mid 357.018536 -280.969205)
		(end 357.153464 -281.102562)
		(width 0.0889)
		(layer "In6.Cu")
		(net "UPI_CPU0_CPU1_P2P2_DN<0>")
	)
	(arc
		(start 357.436166 -275.095462)
		(mid 357.48722 -275.270042)
		(end 357.614474 -275.400008)
		(width 0.0889)
		(layer "In6.Cu")
		(net "UPI_CPU0_CPU1_P2P2_DN<0>")
	)
	(arc
		(start 87.041482 -281.097482)
		(mid 87.157221 -280.985658)
		(end 87.215472 -280.835608)
		(width 0.0889)
		(layer "In6.Cu")
		(net "UPI_CPU0_CPU1_P2P2_DN<0>")
	)
	(arc
		(start 357.11638 -273.747992)
		(mid 357.373378 -273.702504)
		(end 357.623364 -273.777456)
		(width 0.0889)
		(layer "In6.Cu")
		(net "UPI_CPU0_CPU1_P2P2_DN<0>")
	)
	(arc
		(start 356.966266 -282.414472)
		(mid 357.018536 -282.596837)
		(end 357.153464 -282.730194)
		(width 0.0889)
		(layer "In6.Cu")
		(net "UPI_CPU0_CPU1_P2P2_DN<0>")
	)
	(arc
		(start 356.496366 -288.195258)
		(mid 356.56408 -288.336765)
		(end 356.682548 -288.439606)
		(width 0.0889)
		(layer "In6.Cu")
		(net "UPI_CPU0_CPU1_P2P2_DN<0>")
	)
	(arc
		(start 357.614474 -276.389338)
		(mid 357.486155 -276.52131)
		(end 357.436166 -276.698456)
		(width 0.0889)
		(layer "In6.Cu")
		(net "UPI_CPU0_CPU1_P2P2_DN<0>")
	)
	(arc
		(start 85.631782 -283.539184)
		(mid 85.762696 -283.402824)
		(end 85.810344 -283.219906)
		(width 0.0889)
		(layer "In6.Cu")
		(net "UPI_CPU0_CPU1_P2P2_DN<0>")
	)
	(arc
		(start 357.623364 -275.405088)
		(mid 357.826669 -275.605954)
		(end 357.905812 -275.880576)
		(width 0.0889)
		(layer "In6.Cu")
		(net "UPI_CPU0_CPU1_P2P2_DN<0>")
	)
	(arc
		(start 357.436166 -276.71522)
		(mid 357.485273 -276.894409)
		(end 357.614474 -277.027894)
		(width 0.0889)
		(layer "In6.Cu")
		(net "UPI_CPU0_CPU1_P2P2_DN<0>")
	)
	(arc
		(start 357.435912 -281.601926)
		(mid 357.357801 -281.878875)
		(end 357.153464 -282.081478)
		(width 0.0889)
		(layer "In6.Cu")
		(net "UPI_CPU0_CPU1_P2P2_DN<0>")
	)
	(segment
		(start 373.207534 -219.228162)
		(end 373.207534 -218.692476)
		(width 0.13208)
		(layer "F.Cu")
		(net "UPI_CPU0_CPU1_P1P0_DP<9>")
	)
	(segment
		(start 373.207534 -218.692476)
		(end 373.20728 -218.692222)
		(width 0.13208)
		(layer "F.Cu")
		(net "UPI_CPU0_CPU1_P1P0_DP<9>")
	)
	(segment
		(start 98.013266 -217.600276)
		(end 98.013266 -217.06459)
		(width 0.13208)
		(layer "F.Cu")
		(net "UPI_CPU0_CPU1_P1P0_DP<9>")
	)
	(segment
		(start 98.013266 -217.06459)
		(end 98.013012 -217.064336)
		(width 0.13208)
		(layer "F.Cu")
		(net "UPI_CPU0_CPU1_P1P0_DP<9>")
	)
	(segment
		(start 364.49381 -180.628036)
		(end 364.333282 -180.29682)
		(width 0.14732)
		(layer "In4.Cu")
		(net "UPI_CPU0_CPU1_P1P0_DP<9>")
	)
	(segment
		(start 364.426754 -180.821584)
		(end 364.49381 -180.628036)
		(width 0.14732)
		(layer "In4.Cu")
		(net "UPI_CPU0_CPU1_P1P0_DP<9>")
	)
	(segment
		(start 328.614786 -148.476462)
		(end 317.82131 -145.832068)
		(width 0.14732)
		(layer "In4.Cu")
		(net "UPI_CPU0_CPU1_P1P0_DP<9>")
	)
	(segment
		(start 97.826576 -216.73947)
		(end 97.825814 -216.739978)
		(width 0.0889)
		(layer "In4.Cu")
		(net "UPI_CPU0_CPU1_P1P0_DP<9>")
	)
	(segment
		(start 363.849412 -179.298854)
		(end 363.655864 -179.231544)
		(width 0.14732)
		(layer "In4.Cu")
		(net "UPI_CPU0_CPU1_P1P0_DP<9>")
	)
	(segment
		(start 373.540528 -211.480654)
		(end 373.540274 -211.4804)
		(width 0.14732)
		(layer "In4.Cu")
		(net "UPI_CPU0_CPU1_P1P0_DP<9>")
	)
	(segment
		(start 373.582184 -213.93023)
		(end 373.582184 -211.824824)
		(width 0.0889)
		(layer "In4.Cu")
		(net "UPI_CPU0_CPU1_P1P0_DP<9>")
	)
	(segment
		(start 105.576624 -189.97041)
		(end 97.680272 -211.354162)
		(width 0.14732)
		(layer "In4.Cu")
		(net "UPI_CPU0_CPU1_P1P0_DP<9>")
	)
	(segment
		(start 97.680526 -211.552282)
		(end 97.680526 -211.91093)
		(width 0.14732)
		(layer "In4.Cu")
		(net "UPI_CPU0_CPU1_P1P0_DP<9>")
	)
	(segment
		(start 373.58193 -215.43645)
		(end 373.582184 -215.422226)
		(width 0.0889)
		(layer "In4.Cu")
		(net "UPI_CPU0_CPU1_P1P0_DP<9>")
	)
	(segment
		(start 364.587536 -181.153054)
		(end 364.426754 -180.821584)
		(width 0.14732)
		(layer "In4.Cu")
		(net "UPI_CPU0_CPU1_P1P0_DP<9>")
	)
	(segment
		(start 364.046008 -179.704492)
		(end 363.849412 -179.298854)
		(width 0.14732)
		(layer "In4.Cu")
		(net "UPI_CPU0_CPU1_P1P0_DP<9>")
	)
	(segment
		(start 106.545888 -188.75502)
		(end 106.2736 -189.096396)
		(width 0.14732)
		(layer "In4.Cu")
		(net "UPI_CPU0_CPU1_P1P0_DP<9>")
	)
	(segment
		(start 97.77857 -217.356182)
		(end 97.856548 -217.335354)
		(width 0.0889)
		(layer "In4.Cu")
		(net "UPI_CPU0_CPU1_P1P0_DP<9>")
	)
	(segment
		(start 374.052084 -214.622634)
		(end 374.052084 -214.461852)
		(width 0.0889)
		(layer "In4.Cu")
		(net "UPI_CPU0_CPU1_P1P0_DP<9>")
	)
	(segment
		(start 362.304076 -176.11217)
		(end 359.122726 -169.551096)
		(width 0.14732)
		(layer "In4.Cu")
		(net "UPI_CPU0_CPU1_P1P0_DP<9>")
	)
	(segment
		(start 317.82131 -145.832068)
		(end 314.824618 -145.832068)
		(width 0.14732)
		(layer "In4.Cu")
		(net "UPI_CPU0_CPU1_P1P0_DP<9>")
	)
	(segment
		(start 97.638362 -212.3313)
		(end 97.737422 -212.43036)
		(width 0.0889)
		(layer "In4.Cu")
		(net "UPI_CPU0_CPU1_P1P0_DP<9>")
	)
	(segment
		(start 105.848912 -189.629034)
		(end 105.576624 -189.97041)
		(width 0.14732)
		(layer "In4.Cu")
		(net "UPI_CPU0_CPU1_P1P0_DP<9>")
	)
	(segment
		(start 106.292904 -189.267846)
		(end 106.020108 -189.60973)
		(width 0.14732)
		(layer "In4.Cu")
		(net "UPI_CPU0_CPU1_P1P0_DP<9>")
	)
	(segment
		(start 97.737422 -212.60562)
		(end 97.638362 -212.70468)
		(width 0.0889)
		(layer "In4.Cu")
		(net "UPI_CPU0_CPU1_P1P0_DP<9>")
	)
	(segment
		(start 97.824798 -215.112854)
		(end 97.816924 -215.117426)
		(width 0.0889)
		(layer "In4.Cu")
		(net "UPI_CPU0_CPU1_P1P0_DP<9>")
	)
	(segment
		(start 364.333282 -180.29682)
		(end 364.139734 -180.229764)
		(width 0.14732)
		(layer "In4.Cu")
		(net "UPI_CPU0_CPU1_P1P0_DP<9>")
	)
	(segment
		(start 107.686856 -187.519818)
		(end 107.41406 -187.861702)
		(width 0.14732)
		(layer "In4.Cu")
		(net "UPI_CPU0_CPU1_P1P0_DP<9>")
	)
	(segment
		(start 373.20728 -218.692222)
		(end 373.363744 -218.421204)
		(width 0.0889)
		(layer "In4.Cu")
		(net "UPI_CPU0_CPU1_P1P0_DP<9>")
	)
	(segment
		(start 108.60024 -186.178698)
		(end 107.667552 -187.348368)
		(width 0.14732)
		(layer "In4.Cu")
		(net "UPI_CPU0_CPU1_P1P0_DP<9>")
	)
	(segment
		(start 97.680272 -211.354162)
		(end 97.680272 -211.552028)
		(width 0.14732)
		(layer "In4.Cu")
		(net "UPI_CPU0_CPU1_P1P0_DP<9>")
	)
	(segment
		(start 356.429818 -166.337996)
		(end 328.614786 -148.476462)
		(width 0.14732)
		(layer "In4.Cu")
		(net "UPI_CPU0_CPU1_P1P0_DP<9>")
	)
	(segment
		(start 373.58193 -215.445086)
		(end 373.58193 -215.43645)
		(width 0.0889)
		(layer "In4.Cu")
		(net "UPI_CPU0_CPU1_P1P0_DP<9>")
	)
	(segment
		(start 257.290316 -144.657572)
		(end 257.29057 -144.657572)
		(width 0.14732)
		(layer "In4.Cu")
		(net "UPI_CPU0_CPU1_P1P0_DP<9>")
	)
	(segment
		(start 363.562138 -178.706526)
		(end 363.40161 -178.37531)
		(width 0.14732)
		(layer "In4.Cu")
		(net "UPI_CPU0_CPU1_P1P0_DP<9>")
	)
	(segment
		(start 97.680272 -211.552028)
		(end 97.680526 -211.552282)
		(width 0.14732)
		(layer "In4.Cu")
		(net "UPI_CPU0_CPU1_P1P0_DP<9>")
	)
	(segment
		(start 97.638362 -212.89518)
		(end 97.737422 -212.99424)
		(width 0.0889)
		(layer "In4.Cu")
		(net "UPI_CPU0_CPU1_P1P0_DP<9>")
	)
	(segment
		(start 365.035338 -182.076598)
		(end 364.874556 -181.745128)
		(width 0.14732)
		(layer "In4.Cu")
		(net "UPI_CPU0_CPU1_P1P0_DP<9>")
	)
	(segment
		(start 97.638362 -212.70468)
		(end 97.638362 -212.89518)
		(width 0.0889)
		(layer "In4.Cu")
		(net "UPI_CPU0_CPU1_P1P0_DP<9>")
	)
	(segment
		(start 363.978952 -179.89804)
		(end 364.046008 -179.704492)
		(width 0.14732)
		(layer "In4.Cu")
		(net "UPI_CPU0_CPU1_P1P0_DP<9>")
	)
	(segment
		(start 364.139734 -180.229764)
		(end 363.978952 -179.89804)
		(width 0.14732)
		(layer "In4.Cu")
		(net "UPI_CPU0_CPU1_P1P0_DP<9>")
	)
	(segment
		(start 107.242864 -187.881006)
		(end 106.970576 -188.222382)
		(width 0.14732)
		(layer "In4.Cu")
		(net "UPI_CPU0_CPU1_P1P0_DP<9>")
	)
	(segment
		(start 364.941612 -181.55158)
		(end 364.781084 -181.220364)
		(width 0.14732)
		(layer "In4.Cu")
		(net "UPI_CPU0_CPU1_P1P0_DP<9>")
	)
	(segment
		(start 238.595916 -144.994122)
		(end 169.752518 -143.880332)
		(width 0.14732)
		(layer "In4.Cu")
		(net "UPI_CPU0_CPU1_P1P0_DP<9>")
	)
	(segment
		(start 106.020108 -189.60973)
		(end 105.848912 -189.629034)
		(width 0.14732)
		(layer "In4.Cu")
		(net "UPI_CPU0_CPU1_P1P0_DP<9>")
	)
	(segment
		(start 373.582184 -211.824824)
		(end 373.540528 -211.783168)
		(width 0.0889)
		(layer "In4.Cu")
		(net "UPI_CPU0_CPU1_P1P0_DP<9>")
	)
	(segment
		(start 365.66348 -184.361836)
		(end 365.66348 -183.102758)
		(width 0.14732)
		(layer "In4.Cu")
		(net "UPI_CPU0_CPU1_P1P0_DP<9>")
	)
	(segment
		(start 97.816924 -215.755982)
		(end 97.818956 -215.757252)
		(width 0.0889)
		(layer "In4.Cu")
		(net "UPI_CPU0_CPU1_P1P0_DP<9>")
	)
	(segment
		(start 275.985478 -144.321022)
		(end 257.290316 -144.657572)
		(width 0.14732)
		(layer "In4.Cu")
		(net "UPI_CPU0_CPU1_P1P0_DP<9>")
	)
	(segment
		(start 97.825814 -215.112346)
		(end 97.824798 -215.112854)
		(width 0.0889)
		(layer "In4.Cu")
		(net "UPI_CPU0_CPU1_P1P0_DP<9>")
	)
	(segment
		(start 257.29057 -144.657572)
		(end 238.595916 -144.994122)
		(width 0.14732)
		(layer "In4.Cu")
		(net "UPI_CPU0_CPU1_P1P0_DP<9>")
	)
	(segment
		(start 365.66348 -183.102758)
		(end 365.48568 -182.673244)
		(width 0.14732)
		(layer "In4.Cu")
		(net "UPI_CPU0_CPU1_P1P0_DP<9>")
	)
	(segment
		(start 363.40161 -178.37531)
		(end 363.208062 -178.308254)
		(width 0.14732)
		(layer "In4.Cu")
		(net "UPI_CPU0_CPU1_P1P0_DP<9>")
	)
	(segment
		(start 373.864632 -214.946992)
		(end 373.873522 -214.941912)
		(width 0.0889)
		(layer "In4.Cu")
		(net "UPI_CPU0_CPU1_P1P0_DP<9>")
	)
	(segment
		(start 98.108008 -214.424768)
		(end 98.108008 -214.644732)
		(width 0.0889)
		(layer "In4.Cu")
		(net "UPI_CPU0_CPU1_P1P0_DP<9>")
	)
	(segment
		(start 97.737422 -213.1695)
		(end 97.638362 -213.26856)
		(width 0.0889)
		(layer "In4.Cu")
		(net "UPI_CPU0_CPU1_P1P0_DP<9>")
	)
	(segment
		(start 373.112284 -217.8939)
		(end 373.112284 -217.859864)
		(width 0.0889)
		(layer "In4.Cu")
		(net "UPI_CPU0_CPU1_P1P0_DP<9>")
	)
	(segment
		(start 97.638616 -217.0557)
		(end 97.638616 -217.072972)
		(width 0.0889)
		(layer "In4.Cu")
		(net "UPI_CPU0_CPU1_P1P0_DP<9>")
	)
	(segment
		(start 106.98988 -188.393832)
		(end 106.717084 -188.735716)
		(width 0.14732)
		(layer "In4.Cu")
		(net "UPI_CPU0_CPU1_P1P0_DP<9>")
	)
	(segment
		(start 97.856548 -217.335354)
		(end 98.013012 -217.064336)
		(width 0.0889)
		(layer "In4.Cu")
		(net "UPI_CPU0_CPU1_P1P0_DP<9>")
	)
	(segment
		(start 97.680526 -211.933028)
		(end 97.638362 -211.975192)
		(width 0.0889)
		(layer "In4.Cu")
		(net "UPI_CPU0_CPU1_P1P0_DP<9>")
	)
	(segment
		(start 373.540274 -211.4804)
		(end 373.540274 -206.112872)
		(width 0.14732)
		(layer "In4.Cu")
		(net "UPI_CPU0_CPU1_P1P0_DP<9>")
	)
	(segment
		(start 362.304076 -176.111916)
		(end 362.304076 -176.11217)
		(width 0.14732)
		(layer "In4.Cu")
		(net "UPI_CPU0_CPU1_P1P0_DP<9>")
	)
	(segment
		(start 97.737422 -212.43036)
		(end 97.737422 -212.60562)
		(width 0.0889)
		(layer "In4.Cu")
		(net "UPI_CPU0_CPU1_P1P0_DP<9>")
	)
	(segment
		(start 97.638362 -213.26856)
		(end 97.638362 -213.8934)
		(width 0.0889)
		(layer "In4.Cu")
		(net "UPI_CPU0_CPU1_P1P0_DP<9>")
	)
	(segment
		(start 106.2736 -189.096396)
		(end 106.292904 -189.267846)
		(width 0.14732)
		(layer "In4.Cu")
		(net "UPI_CPU0_CPU1_P1P0_DP<9>")
	)
	(segment
		(start 373.363744 -218.421204)
		(end 373.339614 -218.33205)
		(width 0.0889)
		(layer "In4.Cu")
		(net "UPI_CPU0_CPU1_P1P0_DP<9>")
	)
	(segment
		(start 364.781084 -181.220364)
		(end 364.587536 -181.153054)
		(width 0.14732)
		(layer "In4.Cu")
		(net "UPI_CPU0_CPU1_P1P0_DP<9>")
	)
	(segment
		(start 364.874556 -181.745128)
		(end 364.941612 -181.55158)
		(width 0.14732)
		(layer "In4.Cu")
		(net "UPI_CPU0_CPU1_P1P0_DP<9>")
	)
	(segment
		(start 169.752518 -143.880332)
		(end 162.658552 -146.331178)
		(width 0.14732)
		(layer "In4.Cu")
		(net "UPI_CPU0_CPU1_P1P0_DP<9>")
	)
	(segment
		(start 162.658552 -146.331178)
		(end 128.80213 -167.162734)
		(width 0.14732)
		(layer "In4.Cu")
		(net "UPI_CPU0_CPU1_P1P0_DP<9>")
	)
	(segment
		(start 107.667552 -187.348368)
		(end 107.686856 -187.519818)
		(width 0.14732)
		(layer "In4.Cu")
		(net "UPI_CPU0_CPU1_P1P0_DP<9>")
	)
	(segment
		(start 363.114336 -177.782982)
		(end 362.304076 -176.111916)
		(width 0.14732)
		(layer "In4.Cu")
		(net "UPI_CPU0_CPU1_P1P0_DP<9>")
	)
	(segment
		(start 365.48568 -182.673244)
		(end 365.228886 -182.143908)
		(width 0.14732)
		(layer "In4.Cu")
		(net "UPI_CPU0_CPU1_P1P0_DP<9>")
	)
	(segment
		(start 373.540274 -206.112872)
		(end 366.710214 -189.6237)
		(width 0.14732)
		(layer "In4.Cu")
		(net "UPI_CPU0_CPU1_P1P0_DP<9>")
	)
	(segment
		(start 107.41406 -187.861702)
		(end 107.242864 -187.881006)
		(width 0.14732)
		(layer "In4.Cu")
		(net "UPI_CPU0_CPU1_P1P0_DP<9>")
	)
	(segment
		(start 363.495082 -178.900074)
		(end 363.562138 -178.706526)
		(width 0.14732)
		(layer "In4.Cu")
		(net "UPI_CPU0_CPU1_P1P0_DP<9>")
	)
	(segment
		(start 363.655864 -179.231544)
		(end 363.495082 -178.900074)
		(width 0.14732)
		(layer "In4.Cu")
		(net "UPI_CPU0_CPU1_P1P0_DP<9>")
	)
	(segment
		(start 366.710214 -189.6237)
		(end 365.66348 -184.361836)
		(width 0.14732)
		(layer "In4.Cu")
		(net "UPI_CPU0_CPU1_P1P0_DP<9>")
	)
	(segment
		(start 97.83191 -216.736422)
		(end 97.826576 -216.73947)
		(width 0.0889)
		(layer "In4.Cu")
		(net "UPI_CPU0_CPU1_P1P0_DP<9>")
	)
	(segment
		(start 97.818956 -215.757252)
		(end 97.825814 -215.761062)
		(width 0.0889)
		(layer "In4.Cu")
		(net "UPI_CPU0_CPU1_P1P0_DP<9>")
	)
	(segment
		(start 106.717084 -188.735716)
		(end 106.545888 -188.75502)
		(width 0.14732)
		(layer "In4.Cu")
		(net "UPI_CPU0_CPU1_P1P0_DP<9>")
	)
	(segment
		(start 128.80213 -167.162734)
		(end 108.60024 -186.178698)
		(width 0.14732)
		(layer "In4.Cu")
		(net "UPI_CPU0_CPU1_P1P0_DP<9>")
	)
	(segment
		(start 97.638362 -213.8934)
		(end 97.638616 -213.893908)
		(width 0.0889)
		(layer "In4.Cu")
		(net "UPI_CPU0_CPU1_P1P0_DP<9>")
	)
	(segment
		(start 363.208062 -178.308254)
		(end 363.04728 -177.97653)
		(width 0.14732)
		(layer "In4.Cu")
		(net "UPI_CPU0_CPU1_P1P0_DP<9>")
	)
	(segment
		(start 97.825814 -215.761062)
		(end 97.828354 -215.762586)
		(width 0.0889)
		(layer "In4.Cu")
		(net "UPI_CPU0_CPU1_P1P0_DP<9>")
	)
	(segment
		(start 97.638362 -211.975192)
		(end 97.638362 -212.3313)
		(width 0.0889)
		(layer "In4.Cu")
		(net "UPI_CPU0_CPU1_P1P0_DP<9>")
	)
	(segment
		(start 363.04728 -177.97653)
		(end 363.114336 -177.782982)
		(width 0.14732)
		(layer "In4.Cu")
		(net "UPI_CPU0_CPU1_P1P0_DP<9>")
	)
	(segment
		(start 373.58193 -217.072972)
		(end 373.58193 -217.0557)
		(width 0.0889)
		(layer "In4.Cu")
		(net "UPI_CPU0_CPU1_P1P0_DP<9>")
	)
	(segment
		(start 106.970576 -188.222382)
		(end 106.98988 -188.393832)
		(width 0.14732)
		(layer "In4.Cu")
		(net "UPI_CPU0_CPU1_P1P0_DP<9>")
	)
	(segment
		(start 314.824618 -145.832068)
		(end 275.985478 -144.321022)
		(width 0.14732)
		(layer "In4.Cu")
		(net "UPI_CPU0_CPU1_P1P0_DP<9>")
	)
	(segment
		(start 97.737422 -212.99424)
		(end 97.737422 -213.1695)
		(width 0.0889)
		(layer "In4.Cu")
		(net "UPI_CPU0_CPU1_P1P0_DP<9>")
	)
	(segment
		(start 373.540528 -211.76107)
		(end 373.540528 -211.480654)
		(width 0.14732)
		(layer "In4.Cu")
		(net "UPI_CPU0_CPU1_P1P0_DP<9>")
	)
	(segment
		(start 373.540528 -211.783168)
		(end 373.540528 -211.76107)
		(width 0.0889)
		(layer "In4.Cu")
		(net "UPI_CPU0_CPU1_P1P0_DP<9>")
	)
	(segment
		(start 373.112284 -216.260426)
		(end 373.112284 -216.231978)
		(width 0.0889)
		(layer "In4.Cu")
		(net "UPI_CPU0_CPU1_P1P0_DP<9>")
	)
	(segment
		(start 97.828354 -215.762586)
		(end 97.83191 -215.764618)
		(width 0.0889)
		(layer "In4.Cu")
		(net "UPI_CPU0_CPU1_P1P0_DP<9>")
	)
	(segment
		(start 365.228886 -182.143908)
		(end 365.035338 -182.076598)
		(width 0.14732)
		(layer "In4.Cu")
		(net "UPI_CPU0_CPU1_P1P0_DP<9>")
	)
	(segment
		(start 359.122726 -169.551096)
		(end 356.429818 -166.337996)
		(width 0.14732)
		(layer "In4.Cu")
		(net "UPI_CPU0_CPU1_P1P0_DP<9>")
	)
	(segment
		(start 97.680526 -211.91093)
		(end 97.680526 -211.933028)
		(width 0.0889)
		(layer "In4.Cu")
		(net "UPI_CPU0_CPU1_P1P0_DP<9>")
	)
	(arc
		(start 97.638362 -215.436704)
		(mid 97.686041 -215.619604)
		(end 97.816924 -215.755982)
		(width 0.0889)
		(layer "In4.Cu")
		(net "UPI_CPU0_CPU1_P1P0_DP<9>")
	)
	(arc
		(start 97.638616 -213.893908)
		(mid 97.713621 -214.009367)
		(end 97.822766 -214.093298)
		(width 0.0889)
		(layer "In4.Cu")
		(net "UPI_CPU0_CPU1_P1P0_DP<9>")
	)
	(arc
		(start 97.825814 -216.739978)
		(mid 97.690881 -216.873332)
		(end 97.638616 -217.0557)
		(width 0.0889)
		(layer "In4.Cu")
		(net "UPI_CPU0_CPU1_P1P0_DP<9>")
	)
	(arc
		(start 373.394732 -217.388694)
		(mid 373.529665 -217.25534)
		(end 373.58193 -217.072972)
		(width 0.0889)
		(layer "In4.Cu")
		(net "UPI_CPU0_CPU1_P1P0_DP<9>")
	)
	(arc
		(start 373.112284 -216.231978)
		(mid 373.192446 -215.959789)
		(end 373.394732 -215.760808)
		(width 0.0889)
		(layer "In4.Cu")
		(net "UPI_CPU0_CPU1_P1P0_DP<9>")
	)
	(arc
		(start 97.816924 -215.117426)
		(mid 97.68967 -215.247392)
		(end 97.638616 -215.421972)
		(width 0.0889)
		(layer "In4.Cu")
		(net "UPI_CPU0_CPU1_P1P0_DP<9>")
	)
	(arc
		(start 373.32285 -218.319096)
		(mid 373.170768 -218.129664)
		(end 373.112284 -217.8939)
		(width 0.0889)
		(layer "In4.Cu")
		(net "UPI_CPU0_CPU1_P1P0_DP<9>")
	)
	(arc
		(start 373.394732 -216.739978)
		(mid 373.190397 -216.537373)
		(end 373.112284 -216.260426)
		(width 0.0889)
		(layer "In4.Cu")
		(net "UPI_CPU0_CPU1_P1P0_DP<9>")
	)
	(arc
		(start 373.59717 -213.968838)
		(mid 373.589348 -213.949662)
		(end 373.582184 -213.93023)
		(width 0.0889)
		(layer "In4.Cu")
		(net "UPI_CPU0_CPU1_P1P0_DP<9>")
	)
	(arc
		(start 373.86768 -214.261954)
		(mid 373.707325 -214.138568)
		(end 373.59717 -213.968838)
		(width 0.0889)
		(layer "In4.Cu")
		(net "UPI_CPU0_CPU1_P1P0_DP<9>")
	)
	(arc
		(start 373.112284 -217.859864)
		(mid 373.192446 -217.587675)
		(end 373.394732 -217.388694)
		(width 0.0889)
		(layer "In4.Cu")
		(net "UPI_CPU0_CPU1_P1P0_DP<9>")
	)
	(arc
		(start 373.873522 -214.941912)
		(mid 374.004436 -214.805552)
		(end 374.052084 -214.622634)
		(width 0.0889)
		(layer "In4.Cu")
		(net "UPI_CPU0_CPU1_P1P0_DP<9>")
	)
	(arc
		(start 373.582184 -215.422226)
		(mid 373.661315 -215.14769)
		(end 373.864632 -214.946992)
		(width 0.0889)
		(layer "In4.Cu")
		(net "UPI_CPU0_CPU1_P1P0_DP<9>")
	)
	(arc
		(start 373.339614 -218.33205)
		(mid 373.331173 -218.32565)
		(end 373.32285 -218.319096)
		(width 0.0889)
		(layer "In4.Cu")
		(net "UPI_CPU0_CPU1_P1P0_DP<9>")
	)
	(arc
		(start 374.052084 -214.461852)
		(mid 373.977013 -214.34611)
		(end 373.86768 -214.261954)
		(width 0.0889)
		(layer "In4.Cu")
		(net "UPI_CPU0_CPU1_P1P0_DP<9>")
	)
	(arc
		(start 98.108008 -214.644732)
		(mid 98.027097 -214.91486)
		(end 97.825814 -215.112346)
		(width 0.0889)
		(layer "In4.Cu")
		(net "UPI_CPU0_CPU1_P1P0_DP<9>")
	)
	(arc
		(start 373.58193 -217.0557)
		(mid 373.52966 -216.873335)
		(end 373.394732 -216.739978)
		(width 0.0889)
		(layer "In4.Cu")
		(net "UPI_CPU0_CPU1_P1P0_DP<9>")
	)
	(arc
		(start 97.822766 -214.093298)
		(mid 97.996729 -214.232062)
		(end 98.108008 -214.424768)
		(width 0.0889)
		(layer "In4.Cu")
		(net "UPI_CPU0_CPU1_P1P0_DP<9>")
	)
	(arc
		(start 97.83191 -215.764618)
		(mid 98.108484 -216.25052)
		(end 97.83191 -216.736422)
		(width 0.0889)
		(layer "In4.Cu")
		(net "UPI_CPU0_CPU1_P1P0_DP<9>")
	)
	(arc
		(start 373.394732 -215.760808)
		(mid 373.529665 -215.627454)
		(end 373.58193 -215.445086)
		(width 0.0889)
		(layer "In4.Cu")
		(net "UPI_CPU0_CPU1_P1P0_DP<9>")
	)
	(arc
		(start 97.638616 -215.421972)
		(mid 97.638419 -215.429337)
		(end 97.638362 -215.436704)
		(width 0.0889)
		(layer "In4.Cu")
		(net "UPI_CPU0_CPU1_P1P0_DP<9>")
	)
	(arc
		(start 97.638616 -217.072972)
		(mid 97.67729 -217.23004)
		(end 97.77857 -217.356182)
		(width 0.0889)
		(layer "In4.Cu")
		(net "UPI_CPU0_CPU1_P1P0_DP<9>")
	)
	(segment
		(start 374.147334 -217.06459)
		(end 374.14708 -217.064336)
		(width 0.13208)
		(layer "F.Cu")
		(net "UPI_CPU0_CPU1_P1P0_DP<8>")
	)
	(segment
		(start 97.073466 -219.228162)
		(end 97.073466 -218.692476)
		(width 0.13208)
		(layer "F.Cu")
		(net "UPI_CPU0_CPU1_P1P0_DP<8>")
	)
	(segment
		(start 374.147334 -217.600276)
		(end 374.147334 -217.06459)
		(width 0.13208)
		(layer "F.Cu")
		(net "UPI_CPU0_CPU1_P1P0_DP<8>")
	)
	(segment
		(start 97.073466 -218.692476)
		(end 97.073212 -218.692222)
		(width 0.13208)
		(layer "F.Cu")
		(net "UPI_CPU0_CPU1_P1P0_DP<8>")
	)
	(segment
		(start 374.052084 -216.266014)
		(end 374.052084 -216.235026)
		(width 0.0889)
		(layer "In4.Cu")
		(net "UPI_CPU0_CPU1_P1P0_DP<8>")
	)
	(segment
		(start 96.886268 -216.739978)
		(end 96.885506 -216.740486)
		(width 0.0889)
		(layer "In4.Cu")
		(net "UPI_CPU0_CPU1_P1P0_DP<8>")
	)
	(segment
		(start 96.882458 -215.75903)
		(end 96.88449 -215.7603)
		(width 0.0889)
		(layer "In4.Cu")
		(net "UPI_CPU0_CPU1_P1P0_DP<8>")
	)
	(segment
		(start 374.522238 -212.6869)
		(end 374.423178 -212.58784)
		(width 0.0889)
		(layer "In4.Cu")
		(net "UPI_CPU0_CPU1_P1P0_DP<8>")
	)
	(segment
		(start 96.741234 -211.539582)
		(end 96.741234 -211.93633)
		(width 0.14732)
		(layer "In4.Cu")
		(net "UPI_CPU0_CPU1_P1P0_DP<8>")
	)
	(segment
		(start 105.46207 -188.523118)
		(end 105.485184 -188.726572)
		(width 0.14732)
		(layer "In4.Cu")
		(net "UPI_CPU0_CPU1_P1P0_DP<8>")
	)
	(segment
		(start 97.168716 -216.25052)
		(end 97.168716 -216.260426)
		(width 0.0889)
		(layer "In4.Cu")
		(net "UPI_CPU0_CPU1_P1P0_DP<8>")
	)
	(segment
		(start 374.334278 -215.761062)
		(end 374.343168 -215.755982)
		(width 0.0889)
		(layer "In4.Cu")
		(net "UPI_CPU0_CPU1_P1P0_DP<8>")
	)
	(segment
		(start 106.75874 -186.89701)
		(end 106.7816 -187.100464)
		(width 0.14732)
		(layer "In4.Cu")
		(net "UPI_CPU0_CPU1_P1P0_DP<8>")
	)
	(segment
		(start 104.304084 -190.52286)
		(end 104.30383 -190.523622)
		(width 0.14732)
		(layer "In4.Cu")
		(net "UPI_CPU0_CPU1_P1P0_DP<8>")
	)
	(segment
		(start 276.08657 -143.483838)
		(end 238.593376 -144.158208)
		(width 0.14732)
		(layer "In4.Cu")
		(net "UPI_CPU0_CPU1_P1P0_DP<8>")
	)
	(segment
		(start 127.233934 -167.27551)
		(end 127.227584 -167.47998)
		(width 0.14732)
		(layer "In4.Cu")
		(net "UPI_CPU0_CPU1_P1P0_DP<8>")
	)
	(segment
		(start 96.888808 -215.76284)
		(end 96.89211 -215.764618)
		(width 0.0889)
		(layer "In4.Cu")
		(net "UPI_CPU0_CPU1_P1P0_DP<8>")
	)
	(segment
		(start 97.168716 -217.859864)
		(end 97.168716 -217.878406)
		(width 0.0889)
		(layer "In4.Cu")
		(net "UPI_CPU0_CPU1_P1P0_DP<8>")
	)
	(segment
		(start 97.537778 -209.266028)
		(end 97.41027 -209.611722)
		(width 0.14732)
		(layer "In4.Cu")
		(net "UPI_CPU0_CPU1_P1P0_DP<8>")
	)
	(segment
		(start 96.868488 -210.65998)
		(end 96.74098 -211.00542)
		(width 0.14732)
		(layer "In4.Cu")
		(net "UPI_CPU0_CPU1_P1P0_DP<8>")
	)
	(segment
		(start 374.423178 -212.58784)
		(end 374.423178 -212.41258)
		(width 0.0889)
		(layer "In4.Cu")
		(net "UPI_CPU0_CPU1_P1P0_DP<8>")
	)
	(segment
		(start 96.74098 -211.00542)
		(end 96.74098 -211.539328)
		(width 0.14732)
		(layer "In4.Cu")
		(net "UPI_CPU0_CPU1_P1P0_DP<8>")
	)
	(segment
		(start 97.935288 -207.772)
		(end 97.80778 -208.11744)
		(width 0.14732)
		(layer "In4.Cu")
		(net "UPI_CPU0_CPU1_P1P0_DP<8>")
	)
	(segment
		(start 374.423178 -212.41258)
		(end 374.522238 -212.31352)
		(width 0.0889)
		(layer "In4.Cu")
		(net "UPI_CPU0_CPU1_P1P0_DP<8>")
	)
	(segment
		(start 126.754636 -167.726614)
		(end 107.87507 -185.496454)
		(width 0.14732)
		(layer "In4.Cu")
		(net "UPI_CPU0_CPU1_P1P0_DP<8>")
	)
	(segment
		(start 96.882966 -216.74201)
		(end 96.877378 -216.745058)
		(width 0.0889)
		(layer "In4.Cu")
		(net "UPI_CPU0_CPU1_P1P0_DP<8>")
	)
	(segment
		(start 374.14708 -217.064336)
		(end 374.303544 -217.335354)
		(width 0.0889)
		(layer "In4.Cu")
		(net "UPI_CPU0_CPU1_P1P0_DP<8>")
	)
	(segment
		(start 359.850182 -169.074338)
		(end 356.989634 -165.703504)
		(width 0.14732)
		(layer "In4.Cu")
		(net "UPI_CPU0_CPU1_P1P0_DP<8>")
	)
	(segment
		(start 374.335294 -216.740486)
		(end 374.334278 -216.739978)
		(width 0.0889)
		(layer "In4.Cu")
		(net "UPI_CPU0_CPU1_P1P0_DP<8>")
	)
	(segment
		(start 105.255314 -189.014862)
		(end 105.05186 -189.037722)
		(width 0.14732)
		(layer "In4.Cu")
		(net "UPI_CPU0_CPU1_P1P0_DP<8>")
	)
	(segment
		(start 96.843088 -214.072216)
		(end 96.882966 -214.093298)
		(width 0.0889)
		(layer "In4.Cu")
		(net "UPI_CPU0_CPU1_P1P0_DP<8>")
	)
	(segment
		(start 127.626618 -166.905686)
		(end 127.233934 -167.27551)
		(width 0.14732)
		(layer "In4.Cu")
		(net "UPI_CPU0_CPU1_P1P0_DP<8>")
	)
	(segment
		(start 374.803924 -214.947246)
		(end 374.812814 -214.942166)
		(width 0.0889)
		(layer "In4.Cu")
		(net "UPI_CPU0_CPU1_P1P0_DP<8>")
	)
	(segment
		(start 98.12147 -207.686402)
		(end 97.935288 -207.772)
		(width 0.14732)
		(layer "In4.Cu")
		(net "UPI_CPU0_CPU1_P1P0_DP<8>")
	)
	(segment
		(start 104.532176 -189.906148)
		(end 104.531668 -189.906402)
		(width 0.14732)
		(layer "In4.Cu")
		(net "UPI_CPU0_CPU1_P1P0_DP<8>")
	)
	(segment
		(start 97.453196 -209.077052)
		(end 97.45218 -209.0801)
		(width 0.14732)
		(layer "In4.Cu")
		(net "UPI_CPU0_CPU1_P1P0_DP<8>")
	)
	(segment
		(start 106.348276 -187.411614)
		(end 106.101896 -187.720732)
		(width 0.14732)
		(layer "In4.Cu")
		(net "UPI_CPU0_CPU1_P1P0_DP<8>")
	)
	(segment
		(start 374.681242 -214.195406)
		(end 374.522238 -213.9315)
		(width 0.0889)
		(layer "In4.Cu")
		(net "UPI_CPU0_CPU1_P1P0_DP<8>")
	)
	(segment
		(start 97.76587 -208.649062)
		(end 97.579688 -208.73466)
		(width 0.14732)
		(layer "In4.Cu")
		(net "UPI_CPU0_CPU1_P1P0_DP<8>")
	)
	(segment
		(start 366.522 -184.272174)
		(end 366.522 -182.870348)
		(width 0.14732)
		(layer "In4.Cu")
		(net "UPI_CPU0_CPU1_P1P0_DP<8>")
	)
	(segment
		(start 366.377474 -182.52186)
		(end 363.113574 -175.797972)
		(width 0.14732)
		(layer "In4.Cu")
		(net "UPI_CPU0_CPU1_P1P0_DP<8>")
	)
	(segment
		(start 104.531668 -189.906402)
		(end 104.304084 -190.52286)
		(width 0.14732)
		(layer "In4.Cu")
		(net "UPI_CPU0_CPU1_P1P0_DP<8>")
	)
	(segment
		(start 238.593376 -144.158208)
		(end 169.563034 -143.041624)
		(width 0.14732)
		(layer "In4.Cu")
		(net "UPI_CPU0_CPU1_P1P0_DP<8>")
	)
	(segment
		(start 106.124756 -187.924186)
		(end 105.894886 -188.212222)
		(width 0.14732)
		(layer "In4.Cu")
		(net "UPI_CPU0_CPU1_P1P0_DP<8>")
	)
	(segment
		(start 374.522238 -212.31352)
		(end 374.522238 -211.825078)
		(width 0.0889)
		(layer "In4.Cu")
		(net "UPI_CPU0_CPU1_P1P0_DP<8>")
	)
	(segment
		(start 374.480074 -206.140812)
		(end 367.538254 -189.381384)
		(width 0.14732)
		(layer "In4.Cu")
		(net "UPI_CPU0_CPU1_P1P0_DP<8>")
	)
	(segment
		(start 96.887538 -215.762078)
		(end 96.888808 -215.76284)
		(width 0.0889)
		(layer "In4.Cu")
		(net "UPI_CPU0_CPU1_P1P0_DP<8>")
	)
	(segment
		(start 96.88449 -215.7603)
		(end 96.886014 -215.761062)
		(width 0.0889)
		(layer "In4.Cu")
		(net "UPI_CPU0_CPU1_P1P0_DP<8>")
	)
	(segment
		(start 96.877378 -217.383614)
		(end 96.885506 -217.388186)
		(width 0.0889)
		(layer "In4.Cu")
		(net "UPI_CPU0_CPU1_P1P0_DP<8>")
	)
	(segment
		(start 105.485184 -188.726572)
		(end 105.255314 -189.014862)
		(width 0.14732)
		(layer "In4.Cu")
		(net "UPI_CPU0_CPU1_P1P0_DP<8>")
	)
	(segment
		(start 96.886014 -215.112346)
		(end 96.884998 -215.112854)
		(width 0.0889)
		(layer "In4.Cu")
		(net "UPI_CPU0_CPU1_P1P0_DP<8>")
	)
	(segment
		(start 374.480074 -211.572348)
		(end 374.480074 -206.140812)
		(width 0.14732)
		(layer "In4.Cu")
		(net "UPI_CPU0_CPU1_P1P0_DP<8>")
	)
	(segment
		(start 97.893378 -208.303368)
		(end 97.76587 -208.649062)
		(width 0.14732)
		(layer "In4.Cu")
		(net "UPI_CPU0_CPU1_P1P0_DP<8>")
	)
	(segment
		(start 104.30383 -190.523622)
		(end 98.16338 -207.15478)
		(width 0.14732)
		(layer "In4.Cu")
		(net "UPI_CPU0_CPU1_P1P0_DP<8>")
	)
	(segment
		(start 374.343168 -216.745058)
		(end 374.335294 -216.740486)
		(width 0.0889)
		(layer "In4.Cu")
		(net "UPI_CPU0_CPU1_P1P0_DP<8>")
	)
	(segment
		(start 105.894886 -188.212222)
		(end 105.691432 -188.235336)
		(width 0.14732)
		(layer "In4.Cu")
		(net "UPI_CPU0_CPU1_P1P0_DP<8>")
	)
	(segment
		(start 374.522238 -213.2838)
		(end 374.423178 -213.18474)
		(width 0.0889)
		(layer "In4.Cu")
		(net "UPI_CPU0_CPU1_P1P0_DP<8>")
	)
	(segment
		(start 96.741234 -211.93633)
		(end 96.741234 -211.958428)
		(width 0.0889)
		(layer "In4.Cu")
		(net "UPI_CPU0_CPU1_P1P0_DP<8>")
	)
	(segment
		(start 97.579688 -208.73466)
		(end 97.453196 -209.077052)
		(width 0.14732)
		(layer "In4.Cu")
		(net "UPI_CPU0_CPU1_P1P0_DP<8>")
	)
	(segment
		(start 104.680766 -189.503304)
		(end 104.569768 -189.804294)
		(width 0.14732)
		(layer "In4.Cu")
		(net "UPI_CPU0_CPU1_P1P0_DP<8>")
	)
	(segment
		(start 96.885506 -217.388186)
		(end 96.886268 -217.388694)
		(width 0.0889)
		(layer "In4.Cu")
		(net "UPI_CPU0_CPU1_P1P0_DP<8>")
	)
	(segment
		(start 363.113828 -175.797972)
		(end 359.850182 -169.074338)
		(width 0.14732)
		(layer "In4.Cu")
		(net "UPI_CPU0_CPU1_P1P0_DP<8>")
	)
	(segment
		(start 366.522 -182.870348)
		(end 366.377474 -182.52186)
		(width 0.14732)
		(layer "In4.Cu")
		(net "UPI_CPU0_CPU1_P1P0_DP<8>")
	)
	(segment
		(start 96.885506 -216.740486)
		(end 96.882966 -216.74201)
		(width 0.0889)
		(layer "In4.Cu")
		(net "UPI_CPU0_CPU1_P1P0_DP<8>")
	)
	(segment
		(start 374.480328 -211.572602)
		(end 374.480074 -211.572348)
		(width 0.14732)
		(layer "In4.Cu")
		(net "UPI_CPU0_CPU1_P1P0_DP<8>")
	)
	(segment
		(start 374.807226 -214.262208)
		(end 374.681242 -214.195406)
		(width 0.0889)
		(layer "In4.Cu")
		(net "UPI_CPU0_CPU1_P1P0_DP<8>")
	)
	(segment
		(start 96.879156 -215.757252)
		(end 96.882458 -215.75903)
		(width 0.0889)
		(layer "In4.Cu")
		(net "UPI_CPU0_CPU1_P1P0_DP<8>")
	)
	(segment
		(start 106.55173 -187.3885)
		(end 106.348276 -187.411614)
		(width 0.14732)
		(layer "In4.Cu")
		(net "UPI_CPU0_CPU1_P1P0_DP<8>")
	)
	(segment
		(start 374.423178 -213.00948)
		(end 374.522238 -212.91042)
		(width 0.0889)
		(layer "In4.Cu")
		(net "UPI_CPU0_CPU1_P1P0_DP<8>")
	)
	(segment
		(start 97.41027 -209.611722)
		(end 97.224088 -209.69732)
		(width 0.14732)
		(layer "In4.Cu")
		(net "UPI_CPU0_CPU1_P1P0_DP<8>")
	)
	(segment
		(start 363.113574 -175.797972)
		(end 363.113828 -175.797972)
		(width 0.14732)
		(layer "In4.Cu")
		(net "UPI_CPU0_CPU1_P1P0_DP<8>")
	)
	(segment
		(start 105.691432 -188.235336)
		(end 105.46207 -188.523118)
		(width 0.14732)
		(layer "In4.Cu")
		(net "UPI_CPU0_CPU1_P1P0_DP<8>")
	)
	(segment
		(start 96.940878 -218.33205)
		(end 96.916748 -218.421204)
		(width 0.0889)
		(layer "In4.Cu")
		(net "UPI_CPU0_CPU1_P1P0_DP<8>")
	)
	(segment
		(start 374.52173 -215.436704)
		(end 374.52173 -215.42121)
		(width 0.0889)
		(layer "In4.Cu")
		(net "UPI_CPU0_CPU1_P1P0_DP<8>")
	)
	(segment
		(start 97.168208 -214.424768)
		(end 97.168208 -214.644732)
		(width 0.0889)
		(layer "In4.Cu")
		(net "UPI_CPU0_CPU1_P1P0_DP<8>")
	)
	(segment
		(start 374.522238 -211.825078)
		(end 374.480328 -211.783168)
		(width 0.0889)
		(layer "In4.Cu")
		(net "UPI_CPU0_CPU1_P1P0_DP<8>")
	)
	(segment
		(start 356.989634 -165.703504)
		(end 328.94905 -147.697698)
		(width 0.14732)
		(layer "In4.Cu")
		(net "UPI_CPU0_CPU1_P1P0_DP<8>")
	)
	(segment
		(start 97.05467 -210.574382)
		(end 96.868488 -210.65998)
		(width 0.14732)
		(layer "In4.Cu")
		(net "UPI_CPU0_CPU1_P1P0_DP<8>")
	)
	(segment
		(start 328.94905 -147.697698)
		(end 317.922402 -144.996408)
		(width 0.14732)
		(layer "In4.Cu")
		(net "UPI_CPU0_CPU1_P1P0_DP<8>")
	)
	(segment
		(start 96.69907 -212.000592)
		(end 96.69907 -213.832694)
		(width 0.0889)
		(layer "In4.Cu")
		(net "UPI_CPU0_CPU1_P1P0_DP<8>")
	)
	(segment
		(start 96.886014 -215.761062)
		(end 96.887538 -215.762078)
		(width 0.0889)
		(layer "In4.Cu")
		(net "UPI_CPU0_CPU1_P1P0_DP<8>")
	)
	(segment
		(start 105.05186 -189.037722)
		(end 104.680766 -189.503304)
		(width 0.14732)
		(layer "In4.Cu")
		(net "UPI_CPU0_CPU1_P1P0_DP<8>")
	)
	(segment
		(start 374.480328 -211.783168)
		(end 374.480328 -211.76107)
		(width 0.0889)
		(layer "In4.Cu")
		(net "UPI_CPU0_CPU1_P1P0_DP<8>")
	)
	(segment
		(start 106.101896 -187.720732)
		(end 106.124756 -187.924186)
		(width 0.14732)
		(layer "In4.Cu")
		(net "UPI_CPU0_CPU1_P1P0_DP<8>")
	)
	(segment
		(start 314.97016 -144.996408)
		(end 276.08657 -143.483838)
		(width 0.14732)
		(layer "In4.Cu")
		(net "UPI_CPU0_CPU1_P1P0_DP<8>")
	)
	(segment
		(start 96.877124 -215.755982)
		(end 96.879156 -215.757252)
		(width 0.0889)
		(layer "In4.Cu")
		(net "UPI_CPU0_CPU1_P1P0_DP<8>")
	)
	(segment
		(start 374.522238 -213.9315)
		(end 374.522238 -213.2838)
		(width 0.0889)
		(layer "In4.Cu")
		(net "UPI_CPU0_CPU1_P1P0_DP<8>")
	)
	(segment
		(start 374.423178 -213.18474)
		(end 374.423178 -213.00948)
		(width 0.0889)
		(layer "In4.Cu")
		(net "UPI_CPU0_CPU1_P1P0_DP<8>")
	)
	(segment
		(start 106.7816 -187.100464)
		(end 106.55173 -187.3885)
		(width 0.14732)
		(layer "In4.Cu")
		(net "UPI_CPU0_CPU1_P1P0_DP<8>")
	)
	(segment
		(start 98.248978 -207.340708)
		(end 98.12147 -207.686402)
		(width 0.14732)
		(layer "In4.Cu")
		(net "UPI_CPU0_CPU1_P1P0_DP<8>")
	)
	(segment
		(start 374.303544 -217.335354)
		(end 374.381776 -217.356182)
		(width 0.0889)
		(layer "In4.Cu")
		(net "UPI_CPU0_CPU1_P1P0_DP<8>")
	)
	(segment
		(start 97.224088 -209.69732)
		(end 97.09658 -210.04276)
		(width 0.14732)
		(layer "In4.Cu")
		(net "UPI_CPU0_CPU1_P1P0_DP<8>")
	)
	(segment
		(start 162.37839 -145.522696)
		(end 127.626618 -166.905686)
		(width 0.14732)
		(layer "In4.Cu")
		(net "UPI_CPU0_CPU1_P1P0_DP<8>")
	)
	(segment
		(start 104.569514 -189.805056)
		(end 104.532176 -189.906148)
		(width 0.14732)
		(layer "In4.Cu")
		(net "UPI_CPU0_CPU1_P1P0_DP<8>")
	)
	(segment
		(start 96.741234 -211.958428)
		(end 96.69907 -212.000592)
		(width 0.0889)
		(layer "In4.Cu")
		(net "UPI_CPU0_CPU1_P1P0_DP<8>")
	)
	(segment
		(start 97.182178 -210.228688)
		(end 97.05467 -210.574382)
		(width 0.14732)
		(layer "In4.Cu")
		(net "UPI_CPU0_CPU1_P1P0_DP<8>")
	)
	(segment
		(start 374.991376 -214.622888)
		(end 374.991376 -214.461598)
		(width 0.0889)
		(layer "In4.Cu")
		(net "UPI_CPU0_CPU1_P1P0_DP<8>")
	)
	(segment
		(start 97.45218 -209.0801)
		(end 97.537778 -209.266028)
		(width 0.14732)
		(layer "In4.Cu")
		(net "UPI_CPU0_CPU1_P1P0_DP<8>")
	)
	(segment
		(start 374.522238 -212.91042)
		(end 374.522238 -212.6869)
		(width 0.0889)
		(layer "In4.Cu")
		(net "UPI_CPU0_CPU1_P1P0_DP<8>")
	)
	(segment
		(start 104.569768 -189.804294)
		(end 104.569514 -189.805056)
		(width 0.14732)
		(layer "In4.Cu")
		(net "UPI_CPU0_CPU1_P1P0_DP<8>")
	)
	(segment
		(start 367.538254 -189.381384)
		(end 366.522 -184.272174)
		(width 0.14732)
		(layer "In4.Cu")
		(net "UPI_CPU0_CPU1_P1P0_DP<8>")
	)
	(segment
		(start 317.922402 -144.996408)
		(end 314.97016 -144.996408)
		(width 0.14732)
		(layer "In4.Cu")
		(net "UPI_CPU0_CPU1_P1P0_DP<8>")
	)
	(segment
		(start 96.74098 -211.539328)
		(end 96.741234 -211.539582)
		(width 0.14732)
		(layer "In4.Cu")
		(net "UPI_CPU0_CPU1_P1P0_DP<8>")
	)
	(segment
		(start 126.95936 -167.73271)
		(end 126.754636 -167.726614)
		(width 0.14732)
		(layer "In4.Cu")
		(net "UPI_CPU0_CPU1_P1P0_DP<8>")
	)
	(segment
		(start 96.916748 -218.421204)
		(end 97.073212 -218.692222)
		(width 0.0889)
		(layer "In4.Cu")
		(net "UPI_CPU0_CPU1_P1P0_DP<8>")
	)
	(segment
		(start 98.16338 -207.15478)
		(end 98.248978 -207.340708)
		(width 0.14732)
		(layer "In4.Cu")
		(net "UPI_CPU0_CPU1_P1P0_DP<8>")
	)
	(segment
		(start 96.884998 -215.112854)
		(end 96.877124 -215.117426)
		(width 0.0889)
		(layer "In4.Cu")
		(net "UPI_CPU0_CPU1_P1P0_DP<8>")
	)
	(segment
		(start 169.563034 -143.041624)
		(end 162.37839 -145.522696)
		(width 0.14732)
		(layer "In4.Cu")
		(net "UPI_CPU0_CPU1_P1P0_DP<8>")
	)
	(segment
		(start 374.480328 -211.76107)
		(end 374.480328 -211.572602)
		(width 0.14732)
		(layer "In4.Cu")
		(net "UPI_CPU0_CPU1_P1P0_DP<8>")
	)
	(segment
		(start 97.80778 -208.11744)
		(end 97.893378 -208.303368)
		(width 0.14732)
		(layer "In4.Cu")
		(net "UPI_CPU0_CPU1_P1P0_DP<8>")
	)
	(segment
		(start 127.227584 -167.47998)
		(end 126.95936 -167.73271)
		(width 0.14732)
		(layer "In4.Cu")
		(net "UPI_CPU0_CPU1_P1P0_DP<8>")
	)
	(segment
		(start 107.87507 -185.496454)
		(end 106.75874 -186.89701)
		(width 0.14732)
		(layer "In4.Cu")
		(net "UPI_CPU0_CPU1_P1P0_DP<8>")
	)
	(segment
		(start 97.09658 -210.04276)
		(end 97.182178 -210.228688)
		(width 0.14732)
		(layer "In4.Cu")
		(net "UPI_CPU0_CPU1_P1P0_DP<8>")
	)
	(arc
		(start 97.168208 -214.644732)
		(mid 97.087297 -214.91486)
		(end 96.886014 -215.112346)
		(width 0.0889)
		(layer "In4.Cu")
		(net "UPI_CPU0_CPU1_P1P0_DP<8>")
	)
	(arc
		(start 374.52173 -217.064336)
		(mid 374.474051 -216.881436)
		(end 374.343168 -216.745058)
		(width 0.0889)
		(layer "In4.Cu")
		(net "UPI_CPU0_CPU1_P1P0_DP<8>")
	)
	(arc
		(start 374.812814 -214.942166)
		(mid 374.943728 -214.805806)
		(end 374.991376 -214.622888)
		(width 0.0889)
		(layer "In4.Cu")
		(net "UPI_CPU0_CPU1_P1P0_DP<8>")
	)
	(arc
		(start 97.168716 -216.260426)
		(mid 97.090605 -216.537375)
		(end 96.886268 -216.739978)
		(width 0.0889)
		(layer "In4.Cu")
		(net "UPI_CPU0_CPU1_P1P0_DP<8>")
	)
	(arc
		(start 374.991376 -214.461598)
		(mid 374.916371 -214.346139)
		(end 374.807226 -214.262208)
		(width 0.0889)
		(layer "In4.Cu")
		(net "UPI_CPU0_CPU1_P1P0_DP<8>")
	)
	(arc
		(start 374.052084 -216.235026)
		(mid 374.131454 -215.961292)
		(end 374.334278 -215.761062)
		(width 0.0889)
		(layer "In4.Cu")
		(net "UPI_CPU0_CPU1_P1P0_DP<8>")
	)
	(arc
		(start 374.52173 -215.42121)
		(mid 374.6011 -215.147476)
		(end 374.803924 -214.947246)
		(width 0.0889)
		(layer "In4.Cu")
		(net "UPI_CPU0_CPU1_P1P0_DP<8>")
	)
	(arc
		(start 96.698816 -215.421972)
		(mid 96.698619 -215.429337)
		(end 96.698562 -215.436704)
		(width 0.0889)
		(layer "In4.Cu")
		(net "UPI_CPU0_CPU1_P1P0_DP<8>")
	)
	(arc
		(start 96.698562 -215.436704)
		(mid 96.746241 -215.619604)
		(end 96.877124 -215.755982)
		(width 0.0889)
		(layer "In4.Cu")
		(net "UPI_CPU0_CPU1_P1P0_DP<8>")
	)
	(arc
		(start 374.343168 -215.755982)
		(mid 374.474082 -215.619622)
		(end 374.52173 -215.436704)
		(width 0.0889)
		(layer "In4.Cu")
		(net "UPI_CPU0_CPU1_P1P0_DP<8>")
	)
	(arc
		(start 96.69907 -213.832694)
		(mid 96.73784 -213.972448)
		(end 96.843088 -214.072216)
		(width 0.0889)
		(layer "In4.Cu")
		(net "UPI_CPU0_CPU1_P1P0_DP<8>")
	)
	(arc
		(start 97.168716 -217.878406)
		(mid 97.113361 -218.122593)
		(end 96.957896 -218.318842)
		(width 0.0889)
		(layer "In4.Cu")
		(net "UPI_CPU0_CPU1_P1P0_DP<8>")
	)
	(arc
		(start 96.882966 -214.093298)
		(mid 97.056929 -214.232062)
		(end 97.168208 -214.424768)
		(width 0.0889)
		(layer "In4.Cu")
		(net "UPI_CPU0_CPU1_P1P0_DP<8>")
	)
	(arc
		(start 96.877124 -215.117426)
		(mid 96.74987 -215.247392)
		(end 96.698816 -215.421972)
		(width 0.0889)
		(layer "In4.Cu")
		(net "UPI_CPU0_CPU1_P1P0_DP<8>")
	)
	(arc
		(start 96.89211 -215.764618)
		(mid 97.094697 -215.970969)
		(end 97.168716 -216.25052)
		(width 0.0889)
		(layer "In4.Cu")
		(net "UPI_CPU0_CPU1_P1P0_DP<8>")
	)
	(arc
		(start 374.334278 -216.739978)
		(mid 374.131455 -216.539747)
		(end 374.052084 -216.266014)
		(width 0.0889)
		(layer "In4.Cu")
		(net "UPI_CPU0_CPU1_P1P0_DP<8>")
	)
	(arc
		(start 96.957896 -218.318842)
		(mid 96.94945 -218.325527)
		(end 96.940878 -218.33205)
		(width 0.0889)
		(layer "In4.Cu")
		(net "UPI_CPU0_CPU1_P1P0_DP<8>")
	)
	(arc
		(start 96.886268 -217.388694)
		(mid 97.088554 -217.587675)
		(end 97.168716 -217.859864)
		(width 0.0889)
		(layer "In4.Cu")
		(net "UPI_CPU0_CPU1_P1P0_DP<8>")
	)
	(arc
		(start 96.877378 -216.745058)
		(mid 96.698781 -217.064336)
		(end 96.877378 -217.383614)
		(width 0.0889)
		(layer "In4.Cu")
		(net "UPI_CPU0_CPU1_P1P0_DP<8>")
	)
	(arc
		(start 374.381776 -217.356182)
		(mid 374.484921 -217.226157)
		(end 374.52173 -217.064336)
		(width 0.0889)
		(layer "In4.Cu")
		(net "UPI_CPU0_CPU1_P1P0_DP<8>")
	)
	(segment
		(start 375.55678 -218.414346)
		(end 375.55678 -217.87866)
		(width 0.13208)
		(layer "F.Cu")
		(net "UPI_CPU0_CPU1_P1P0_DP<7>")
	)
	(segment
		(start 95.663512 -217.87866)
		(end 95.663766 -217.878406)
		(width 0.13208)
		(layer "F.Cu")
		(net "UPI_CPU0_CPU1_P1P0_DP<7>")
	)
	(segment
		(start 375.55678 -217.87866)
		(end 375.557034 -217.878406)
		(width 0.13208)
		(layer "F.Cu")
		(net "UPI_CPU0_CPU1_P1P0_DP<7>")
	)
	(segment
		(start 95.663512 -218.414346)
		(end 95.663512 -217.87866)
		(width 0.13208)
		(layer "F.Cu")
		(net "UPI_CPU0_CPU1_P1P0_DP<7>")
	)
	(segment
		(start 375.360946 -217.559128)
		(end 375.369836 -217.554048)
		(width 0.0889)
		(layer "In4.Cu")
		(net "UPI_CPU0_CPU1_P1P0_DP<7>")
	)
	(segment
		(start 95.82023 -217.607388)
		(end 95.663766 -217.878406)
		(width 0.0889)
		(layer "In4.Cu")
		(net "UPI_CPU0_CPU1_P1P0_DP<7>")
	)
	(segment
		(start 367.63198 -182.619396)
		(end 367.438432 -182.152036)
		(width 0.14732)
		(layer "In4.Cu")
		(net "UPI_CPU0_CPU1_P1P0_DP<7>")
	)
	(segment
		(start 103.84917 -188.561472)
		(end 95.527114 -211.101432)
		(width 0.14732)
		(layer "In4.Cu")
		(net "UPI_CPU0_CPU1_P1P0_DP<7>")
	)
	(segment
		(start 95.527368 -211.836508)
		(end 95.569278 -211.878418)
		(width 0.0889)
		(layer "In4.Cu")
		(net "UPI_CPU0_CPU1_P1P0_DP<7>")
	)
	(segment
		(start 369.453922 -190.678308)
		(end 369.17249 -190.396876)
		(width 0.14732)
		(layer "In4.Cu")
		(net "UPI_CPU0_CPU1_P1P0_DP<7>")
	)
	(segment
		(start 318.057276 -143.883888)
		(end 314.803028 -143.883888)
		(width 0.14732)
		(layer "In4.Cu")
		(net "UPI_CPU0_CPU1_P1P0_DP<7>")
	)
	(segment
		(start 375.65203 -215.455246)
		(end 375.652284 -215.436704)
		(width 0.0889)
		(layer "In4.Cu")
		(net "UPI_CPU0_CPU1_P1P0_DP<7>")
	)
	(segment
		(start 375.40057 -218.149424)
		(end 375.322338 -218.170252)
		(width 0.0889)
		(layer "In4.Cu")
		(net "UPI_CPU0_CPU1_P1P0_DP<7>")
	)
	(segment
		(start 95.844868 -215.922606)
		(end 95.84817 -215.924384)
		(width 0.0889)
		(layer "In4.Cu")
		(net "UPI_CPU0_CPU1_P1P0_DP<7>")
	)
	(segment
		(start 314.803028 -143.883888)
		(end 275.907246 -142.370556)
		(width 0.14732)
		(layer "In4.Cu")
		(net "UPI_CPU0_CPU1_P1P0_DP<7>")
	)
	(segment
		(start 375.652284 -217.082878)
		(end 375.652284 -217.05443)
		(width 0.0889)
		(layer "In4.Cu")
		(net "UPI_CPU0_CPU1_P1P0_DP<7>")
	)
	(segment
		(start 106.516678 -185.2168)
		(end 103.84917 -188.561472)
		(width 0.14732)
		(layer "In4.Cu")
		(net "UPI_CPU0_CPU1_P1P0_DP<7>")
	)
	(segment
		(start 95.527368 -211.539582)
		(end 95.527368 -211.81441)
		(width 0.14732)
		(layer "In4.Cu")
		(net "UPI_CPU0_CPU1_P1P0_DP<7>")
	)
	(segment
		(start 95.844614 -216.578688)
		(end 95.844868 -216.578434)
		(width 0.0889)
		(layer "In4.Cu")
		(net "UPI_CPU0_CPU1_P1P0_DP<7>")
	)
	(segment
		(start 375.751344 -212.56752)
		(end 375.751344 -212.39226)
		(width 0.0889)
		(layer "In4.Cu")
		(net "UPI_CPU0_CPU1_P1P0_DP<7>")
	)
	(segment
		(start 368.616484 -189.053978)
		(end 367.63198 -184.106312)
		(width 0.14732)
		(layer "In4.Cu")
		(net "UPI_CPU0_CPU1_P1P0_DP<7>")
	)
	(segment
		(start 95.859854 -216.569798)
		(end 95.844614 -216.578688)
		(width 0.0889)
		(layer "In4.Cu")
		(net "UPI_CPU0_CPU1_P1P0_DP<7>")
	)
	(segment
		(start 275.907246 -142.370556)
		(end 238.590836 -143.041624)
		(width 0.14732)
		(layer "In4.Cu")
		(net "UPI_CPU0_CPU1_P1P0_DP<7>")
	)
	(segment
		(start 343.556082 -155.754578)
		(end 329.394058 -146.660616)
		(width 0.14732)
		(layer "In4.Cu")
		(net "UPI_CPU0_CPU1_P1P0_DP<7>")
	)
	(segment
		(start 375.694194 -211.572348)
		(end 375.694194 -205.743556)
		(width 0.14732)
		(layer "In4.Cu")
		(net "UPI_CPU0_CPU1_P1P0_DP<7>")
	)
	(segment
		(start 375.751344 -213.11616)
		(end 375.751344 -212.9409)
		(width 0.0889)
		(layer "In4.Cu")
		(net "UPI_CPU0_CPU1_P1P0_DP<7>")
	)
	(segment
		(start 126.854966 -166.073582)
		(end 106.516678 -185.2168)
		(width 0.14732)
		(layer "In4.Cu")
		(net "UPI_CPU0_CPU1_P1P0_DP<7>")
	)
	(segment
		(start 329.394058 -146.660616)
		(end 318.08928 -143.891762)
		(width 0.14732)
		(layer "In4.Cu")
		(net "UPI_CPU0_CPU1_P1P0_DP<7>")
	)
	(segment
		(start 95.859854 -215.931496)
		(end 95.859854 -215.931242)
		(width 0.0889)
		(layer "In4.Cu")
		(net "UPI_CPU0_CPU1_P1P0_DP<7>")
	)
	(segment
		(start 95.527114 -211.101432)
		(end 95.527114 -211.539328)
		(width 0.14732)
		(layer "In4.Cu")
		(net "UPI_CPU0_CPU1_P1P0_DP<7>")
	)
	(segment
		(start 95.7961 -217.518234)
		(end 95.82023 -217.607388)
		(width 0.0889)
		(layer "In4.Cu")
		(net "UPI_CPU0_CPU1_P1P0_DP<7>")
	)
	(segment
		(start 343.556336 -155.754832)
		(end 343.556082 -155.754578)
		(width 0.14732)
		(layer "In4.Cu")
		(net "UPI_CPU0_CPU1_P1P0_DP<7>")
	)
	(segment
		(start 95.82785 -214.283036)
		(end 95.969836 -214.357458)
		(width 0.0889)
		(layer "In4.Cu")
		(net "UPI_CPU0_CPU1_P1P0_DP<7>")
	)
	(segment
		(start 360.78033 -168.460674)
		(end 357.714296 -164.846508)
		(width 0.14732)
		(layer "In4.Cu")
		(net "UPI_CPU0_CPU1_P1P0_DP<7>")
	)
	(segment
		(start 375.652284 -212.66658)
		(end 375.751344 -212.56752)
		(width 0.0889)
		(layer "In4.Cu")
		(net "UPI_CPU0_CPU1_P1P0_DP<7>")
	)
	(segment
		(start 375.751344 -212.39226)
		(end 375.652284 -212.2932)
		(width 0.0889)
		(layer "In4.Cu")
		(net "UPI_CPU0_CPU1_P1P0_DP<7>")
	)
	(segment
		(start 95.527114 -211.539328)
		(end 95.527368 -211.539582)
		(width 0.14732)
		(layer "In4.Cu")
		(net "UPI_CPU0_CPU1_P1P0_DP<7>")
	)
	(segment
		(start 376.122184 -214.636858)
		(end 376.122184 -214.425022)
		(width 0.0889)
		(layer "In4.Cu")
		(net "UPI_CPU0_CPU1_P1P0_DP<7>")
	)
	(segment
		(start 357.714296 -164.846508)
		(end 343.556336 -155.754832)
		(width 0.14732)
		(layer "In4.Cu")
		(net "UPI_CPU0_CPU1_P1P0_DP<7>")
	)
	(segment
		(start 375.751344 -212.9409)
		(end 375.652284 -212.84184)
		(width 0.0889)
		(layer "In4.Cu")
		(net "UPI_CPU0_CPU1_P1P0_DP<7>")
	)
	(segment
		(start 375.694448 -211.869528)
		(end 375.694448 -211.84743)
		(width 0.0889)
		(layer "In4.Cu")
		(net "UPI_CPU0_CPU1_P1P0_DP<7>")
	)
	(segment
		(start 318.08928 -143.891508)
		(end 318.057276 -143.883888)
		(width 0.14732)
		(layer "In4.Cu")
		(net "UPI_CPU0_CPU1_P1P0_DP<7>")
	)
	(segment
		(start 95.851726 -215.92667)
		(end 95.859854 -215.931496)
		(width 0.0889)
		(layer "In4.Cu")
		(net "UPI_CPU0_CPU1_P1P0_DP<7>")
	)
	(segment
		(start 95.568262 -215.414606)
		(end 95.568262 -215.436704)
		(width 0.0889)
		(layer "In4.Cu")
		(net "UPI_CPU0_CPU1_P1P0_DP<7>")
	)
	(segment
		(start 375.652284 -213.21522)
		(end 375.751344 -213.11616)
		(width 0.0889)
		(layer "In4.Cu")
		(net "UPI_CPU0_CPU1_P1P0_DP<7>")
	)
	(segment
		(start 95.569278 -211.878418)
		(end 95.569278 -214.024464)
		(width 0.0889)
		(layer "In4.Cu")
		(net "UPI_CPU0_CPU1_P1P0_DP<7>")
	)
	(segment
		(start 95.850202 -215.925654)
		(end 95.851726 -215.92667)
		(width 0.0889)
		(layer "In4.Cu")
		(net "UPI_CPU0_CPU1_P1P0_DP<7>")
	)
	(segment
		(start 375.694448 -211.572602)
		(end 375.694194 -211.572348)
		(width 0.14732)
		(layer "In4.Cu")
		(net "UPI_CPU0_CPU1_P1P0_DP<7>")
	)
	(segment
		(start 375.694194 -205.743556)
		(end 369.453922 -190.678308)
		(width 0.14732)
		(layer "In4.Cu")
		(net "UPI_CPU0_CPU1_P1P0_DP<7>")
	)
	(segment
		(start 375.652284 -212.2932)
		(end 375.652284 -211.911692)
		(width 0.0889)
		(layer "In4.Cu")
		(net "UPI_CPU0_CPU1_P1P0_DP<7>")
	)
	(segment
		(start 95.859346 -214.941912)
		(end 95.850456 -214.946992)
		(width 0.0889)
		(layer "In4.Cu")
		(net "UPI_CPU0_CPU1_P1P0_DP<7>")
	)
	(segment
		(start 95.527368 -211.81441)
		(end 95.527368 -211.836508)
		(width 0.0889)
		(layer "In4.Cu")
		(net "UPI_CPU0_CPU1_P1P0_DP<7>")
	)
	(segment
		(start 367.63198 -184.106312)
		(end 367.63198 -182.619396)
		(width 0.14732)
		(layer "In4.Cu")
		(net "UPI_CPU0_CPU1_P1P0_DP<7>")
	)
	(segment
		(start 375.369836 -216.574878)
		(end 375.360946 -216.569798)
		(width 0.0889)
		(layer "In4.Cu")
		(net "UPI_CPU0_CPU1_P1P0_DP<7>")
	)
	(segment
		(start 367.438432 -182.152036)
		(end 360.78033 -168.460674)
		(width 0.14732)
		(layer "In4.Cu")
		(net "UPI_CPU0_CPU1_P1P0_DP<7>")
	)
	(segment
		(start 375.652284 -213.8934)
		(end 375.652284 -213.21522)
		(width 0.0889)
		(layer "In4.Cu")
		(net "UPI_CPU0_CPU1_P1P0_DP<7>")
	)
	(segment
		(start 96.037908 -214.461344)
		(end 96.037908 -214.622634)
		(width 0.0889)
		(layer "In4.Cu")
		(net "UPI_CPU0_CPU1_P1P0_DP<7>")
	)
	(segment
		(start 369.17249 -190.396876)
		(end 368.616484 -189.053978)
		(width 0.14732)
		(layer "In4.Cu")
		(net "UPI_CPU0_CPU1_P1P0_DP<7>")
	)
	(segment
		(start 162.005772 -144.445482)
		(end 126.854966 -166.073582)
		(width 0.14732)
		(layer "In4.Cu")
		(net "UPI_CPU0_CPU1_P1P0_DP<7>")
	)
	(segment
		(start 375.557034 -217.878406)
		(end 375.40057 -218.149424)
		(width 0.0889)
		(layer "In4.Cu")
		(net "UPI_CPU0_CPU1_P1P0_DP<7>")
	)
	(segment
		(start 375.652284 -211.911692)
		(end 375.694448 -211.869528)
		(width 0.0889)
		(layer "In4.Cu")
		(net "UPI_CPU0_CPU1_P1P0_DP<7>")
	)
	(segment
		(start 318.08928 -143.891762)
		(end 318.08928 -143.891508)
		(width 0.14732)
		(layer "In4.Cu")
		(net "UPI_CPU0_CPU1_P1P0_DP<7>")
	)
	(segment
		(start 95.569278 -214.024464)
		(end 95.82785 -214.283036)
		(width 0.0889)
		(layer "In4.Cu")
		(net "UPI_CPU0_CPU1_P1P0_DP<7>")
	)
	(segment
		(start 375.694448 -211.84743)
		(end 375.694448 -211.572602)
		(width 0.14732)
		(layer "In4.Cu")
		(net "UPI_CPU0_CPU1_P1P0_DP<7>")
	)
	(segment
		(start 238.590836 -143.041624)
		(end 169.313352 -141.921484)
		(width 0.14732)
		(layer "In4.Cu")
		(net "UPI_CPU0_CPU1_P1P0_DP<7>")
	)
	(segment
		(start 95.568262 -217.064336)
		(end 95.568262 -217.07856)
		(width 0.0889)
		(layer "In4.Cu")
		(net "UPI_CPU0_CPU1_P1P0_DP<7>")
	)
	(segment
		(start 95.84817 -215.924384)
		(end 95.850202 -215.925654)
		(width 0.0889)
		(layer "In4.Cu")
		(net "UPI_CPU0_CPU1_P1P0_DP<7>")
	)
	(segment
		(start 375.360946 -215.931242)
		(end 375.369836 -215.926162)
		(width 0.0889)
		(layer "In4.Cu")
		(net "UPI_CPU0_CPU1_P1P0_DP<7>")
	)
	(segment
		(start 375.652284 -212.84184)
		(end 375.652284 -212.66658)
		(width 0.0889)
		(layer "In4.Cu")
		(net "UPI_CPU0_CPU1_P1P0_DP<7>")
	)
	(segment
		(start 375.652284 -215.436704)
		(end 375.652284 -215.428068)
		(width 0.0889)
		(layer "In4.Cu")
		(net "UPI_CPU0_CPU1_P1P0_DP<7>")
	)
	(segment
		(start 169.313352 -141.921484)
		(end 162.005772 -144.445482)
		(width 0.14732)
		(layer "In4.Cu")
		(net "UPI_CPU0_CPU1_P1P0_DP<7>")
	)
	(arc
		(start 375.652284 -215.428068)
		(mid 375.704554 -215.245703)
		(end 375.839482 -215.112346)
		(width 0.0889)
		(layer "In4.Cu")
		(net "UPI_CPU0_CPU1_P1P0_DP<7>")
	)
	(arc
		(start 95.568262 -215.436704)
		(mid 95.642253 -215.71627)
		(end 95.844868 -215.922606)
		(width 0.0889)
		(layer "In4.Cu")
		(net "UPI_CPU0_CPU1_P1P0_DP<7>")
	)
	(arc
		(start 96.037908 -214.622634)
		(mid 95.990229 -214.805534)
		(end 95.859346 -214.941912)
		(width 0.0889)
		(layer "In4.Cu")
		(net "UPI_CPU0_CPU1_P1P0_DP<7>")
	)
	(arc
		(start 375.182638 -216.238328)
		(mid 375.233131 -216.06235)
		(end 375.360946 -215.931242)
		(width 0.0889)
		(layer "In4.Cu")
		(net "UPI_CPU0_CPU1_P1P0_DP<7>")
	)
	(arc
		(start 375.839482 -215.112346)
		(mid 376.042963 -214.911542)
		(end 376.122184 -214.636858)
		(width 0.0889)
		(layer "In4.Cu")
		(net "UPI_CPU0_CPU1_P1P0_DP<7>")
	)
	(arc
		(start 95.969836 -214.357458)
		(mid 96.008417 -214.406424)
		(end 96.037908 -214.461344)
		(width 0.0889)
		(layer "In4.Cu")
		(net "UPI_CPU0_CPU1_P1P0_DP<7>")
	)
	(arc
		(start 375.182384 -217.878406)
		(mid 375.230063 -217.695506)
		(end 375.360946 -217.559128)
		(width 0.0889)
		(layer "In4.Cu")
		(net "UPI_CPU0_CPU1_P1P0_DP<7>")
	)
	(arc
		(start 375.369836 -215.926162)
		(mid 375.571878 -215.727239)
		(end 375.65203 -215.455246)
		(width 0.0889)
		(layer "In4.Cu")
		(net "UPI_CPU0_CPU1_P1P0_DP<7>")
	)
	(arc
		(start 375.360946 -216.569798)
		(mid 375.231657 -216.436312)
		(end 375.182384 -216.257124)
		(width 0.0889)
		(layer "In4.Cu")
		(net "UPI_CPU0_CPU1_P1P0_DP<7>")
	)
	(arc
		(start 95.850456 -214.946992)
		(mid 95.649174 -215.144479)
		(end 95.568262 -215.414606)
		(width 0.0889)
		(layer "In4.Cu")
		(net "UPI_CPU0_CPU1_P1P0_DP<7>")
	)
	(arc
		(start 95.859854 -215.931242)
		(mid 96.038451 -216.25052)
		(end 95.859854 -216.569798)
		(width 0.0889)
		(layer "In4.Cu")
		(net "UPI_CPU0_CPU1_P1P0_DP<7>")
	)
	(arc
		(start 375.369836 -217.554048)
		(mid 375.572122 -217.355067)
		(end 375.652284 -217.082878)
		(width 0.0889)
		(layer "In4.Cu")
		(net "UPI_CPU0_CPU1_P1P0_DP<7>")
	)
	(arc
		(start 375.322338 -218.170252)
		(mid 375.219193 -218.040227)
		(end 375.182384 -217.878406)
		(width 0.0889)
		(layer "In4.Cu")
		(net "UPI_CPU0_CPU1_P1P0_DP<7>")
	)
	(arc
		(start 375.652284 -217.05443)
		(mid 375.574173 -216.777481)
		(end 375.369836 -216.574878)
		(width 0.0889)
		(layer "In4.Cu")
		(net "UPI_CPU0_CPU1_P1P0_DP<7>")
	)
	(arc
		(start 375.182384 -216.257124)
		(mid 375.182394 -216.247724)
		(end 375.182638 -216.238328)
		(width 0.0889)
		(layer "In4.Cu")
		(net "UPI_CPU0_CPU1_P1P0_DP<7>")
	)
	(arc
		(start 95.844868 -216.578434)
		(mid 95.642281 -216.784785)
		(end 95.568262 -217.064336)
		(width 0.0889)
		(layer "In4.Cu")
		(net "UPI_CPU0_CPU1_P1P0_DP<7>")
	)
	(arc
		(start 95.779082 -217.50528)
		(mid 95.78753 -217.511837)
		(end 95.7961 -217.518234)
		(width 0.0889)
		(layer "In4.Cu")
		(net "UPI_CPU0_CPU1_P1P0_DP<7>")
	)
	(arc
		(start 375.836688 -214.093298)
		(mid 375.727292 -214.009201)
		(end 375.652284 -213.8934)
		(width 0.0889)
		(layer "In4.Cu")
		(net "UPI_CPU0_CPU1_P1P0_DP<7>")
	)
	(arc
		(start 95.568262 -217.07856)
		(mid 95.626556 -217.315203)
		(end 95.779082 -217.50528)
		(width 0.0889)
		(layer "In4.Cu")
		(net "UPI_CPU0_CPU1_P1P0_DP<7>")
	)
	(arc
		(start 376.122184 -214.425022)
		(mid 376.010846 -214.232122)
		(end 375.836688 -214.093298)
		(width 0.0889)
		(layer "In4.Cu")
		(net "UPI_CPU0_CPU1_P1P0_DP<7>")
	)
	(segment
		(start 95.193866 -219.228162)
		(end 95.193866 -218.692476)
		(width 0.13208)
		(layer "F.Cu")
		(net "UPI_CPU0_CPU1_P1P0_DP<6>")
	)
	(segment
		(start 376.026934 -217.600276)
		(end 376.026934 -217.06459)
		(width 0.13208)
		(layer "F.Cu")
		(net "UPI_CPU0_CPU1_P1P0_DP<6>")
	)
	(segment
		(start 376.026934 -217.06459)
		(end 376.02668 -217.064336)
		(width 0.13208)
		(layer "F.Cu")
		(net "UPI_CPU0_CPU1_P1P0_DP<6>")
	)
	(segment
		(start 95.193866 -218.692476)
		(end 95.193612 -218.692222)
		(width 0.13208)
		(layer "F.Cu")
		(net "UPI_CPU0_CPU1_P1P0_DP<6>")
	)
	(segment
		(start 95.003366 -216.74201)
		(end 94.997778 -216.745058)
		(width 0.0889)
		(layer "In4.Cu")
		(net "UPI_CPU0_CPU1_P1P0_DP<6>")
	)
	(segment
		(start 376.67184 -214.954104)
		(end 376.684032 -214.946992)
		(width 0.0889)
		(layer "In4.Cu")
		(net "UPI_CPU0_CPU1_P1P0_DP<6>")
	)
	(segment
		(start 95.037148 -218.421204)
		(end 95.193612 -218.692222)
		(width 0.0889)
		(layer "In4.Cu")
		(net "UPI_CPU0_CPU1_P1P0_DP<6>")
	)
	(segment
		(start 368.63782 -186.126628)
		(end 368.63782 -185.689748)
		(width 0.14732)
		(layer "In4.Cu")
		(net "UPI_CPU0_CPU1_P1P0_DP<6>")
	)
	(segment
		(start 94.997778 -217.383614)
		(end 95.005906 -217.388186)
		(width 0.0889)
		(layer "In4.Cu")
		(net "UPI_CPU0_CPU1_P1P0_DP<6>")
	)
	(segment
		(start 370.98732 -192.886838)
		(end 370.98732 -192.412112)
		(width 0.14732)
		(layer "In4.Cu")
		(net "UPI_CPU0_CPU1_P1P0_DP<6>")
	)
	(segment
		(start 95.006414 -215.112346)
		(end 95.005398 -215.112854)
		(width 0.0889)
		(layer "In4.Cu")
		(net "UPI_CPU0_CPU1_P1P0_DP<6>")
	)
	(segment
		(start 370.222018 -190.564516)
		(end 370.032788 -190.486284)
		(width 0.14732)
		(layer "In4.Cu")
		(net "UPI_CPU0_CPU1_P1P0_DP<6>")
	)
	(segment
		(start 104.17556 -187.248038)
		(end 103.94569 -187.536328)
		(width 0.14732)
		(layer "In4.Cu")
		(net "UPI_CPU0_CPU1_P1P0_DP<6>")
	)
	(segment
		(start 376.359674 -205.85684)
		(end 370.98732 -192.886838)
		(width 0.14732)
		(layer "In4.Cu")
		(net "UPI_CPU0_CPU1_P1P0_DP<6>")
	)
	(segment
		(start 94.999556 -215.757252)
		(end 95.002858 -215.75903)
		(width 0.0889)
		(layer "In4.Cu")
		(net "UPI_CPU0_CPU1_P1P0_DP<6>")
	)
	(segment
		(start 361.244642 -168.08196)
		(end 358.146096 -164.428932)
		(width 0.14732)
		(layer "In4.Cu")
		(net "UPI_CPU0_CPU1_P1P0_DP<6>")
	)
	(segment
		(start 368.75974 -183.557926)
		(end 368.559588 -183.145684)
		(width 0.14732)
		(layer "In4.Cu")
		(net "UPI_CPU0_CPU1_P1P0_DP<6>")
	)
	(segment
		(start 370.425726 -191.43472)
		(end 370.284756 -191.094106)
		(width 0.14732)
		(layer "In4.Cu")
		(net "UPI_CPU0_CPU1_P1P0_DP<6>")
	)
	(segment
		(start 94.997524 -215.755982)
		(end 94.999556 -215.757252)
		(width 0.0889)
		(layer "In4.Cu")
		(net "UPI_CPU0_CPU1_P1P0_DP<6>")
	)
	(segment
		(start 94.861126 -211.504022)
		(end 94.861126 -211.72805)
		(width 0.14732)
		(layer "In4.Cu")
		(net "UPI_CPU0_CPU1_P1P0_DP<6>")
	)
	(segment
		(start 95.006414 -215.761062)
		(end 95.007938 -215.762078)
		(width 0.0889)
		(layer "In4.Cu")
		(net "UPI_CPU0_CPU1_P1P0_DP<6>")
	)
	(segment
		(start 369.829334 -189.616588)
		(end 369.288314 -189.075568)
		(width 0.14732)
		(layer "In4.Cu")
		(net "UPI_CPU0_CPU1_P1P0_DP<6>")
	)
	(segment
		(start 105.83291 -184.937146)
		(end 105.432098 -185.439812)
		(width 0.14732)
		(layer "In4.Cu")
		(net "UPI_CPU0_CPU1_P1P0_DP<6>")
	)
	(segment
		(start 95.061278 -218.33205)
		(end 95.037148 -218.421204)
		(width 0.0889)
		(layer "In4.Cu")
		(net "UPI_CPU0_CPU1_P1P0_DP<6>")
	)
	(segment
		(start 94.860872 -211.278724)
		(end 94.860872 -211.503768)
		(width 0.14732)
		(layer "In4.Cu")
		(net "UPI_CPU0_CPU1_P1P0_DP<6>")
	)
	(segment
		(start 95.00489 -215.7603)
		(end 95.006414 -215.761062)
		(width 0.0889)
		(layer "In4.Cu")
		(net "UPI_CPU0_CPU1_P1P0_DP<6>")
	)
	(segment
		(start 95.005906 -217.388186)
		(end 95.006668 -217.388694)
		(width 0.0889)
		(layer "In4.Cu")
		(net "UPI_CPU0_CPU1_P1P0_DP<6>")
	)
	(segment
		(start 376.401838 -211.911438)
		(end 376.359928 -211.869528)
		(width 0.0889)
		(layer "In4.Cu")
		(net "UPI_CPU0_CPU1_P1P0_DP<6>")
	)
	(segment
		(start 376.214894 -215.760554)
		(end 376.222768 -215.755982)
		(width 0.0889)
		(layer "In4.Cu")
		(net "UPI_CPU0_CPU1_P1P0_DP<6>")
	)
	(segment
		(start 376.183144 -217.335354)
		(end 376.261376 -217.356182)
		(width 0.0889)
		(layer "In4.Cu")
		(net "UPI_CPU0_CPU1_P1P0_DP<6>")
	)
	(segment
		(start 368.75974 -185.130948)
		(end 368.63782 -185.009028)
		(width 0.14732)
		(layer "In4.Cu")
		(net "UPI_CPU0_CPU1_P1P0_DP<6>")
	)
	(segment
		(start 368.63782 -185.689748)
		(end 368.75974 -185.567828)
		(width 0.14732)
		(layer "In4.Cu")
		(net "UPI_CPU0_CPU1_P1P0_DP<6>")
	)
	(segment
		(start 376.401838 -212.27796)
		(end 376.401838 -211.911438)
		(width 0.0889)
		(layer "In4.Cu")
		(net "UPI_CPU0_CPU1_P1P0_DP<6>")
	)
	(segment
		(start 169.377868 -141.25702)
		(end 161.906204 -143.836644)
		(width 0.14732)
		(layer "In4.Cu")
		(net "UPI_CPU0_CPU1_P1P0_DP<6>")
	)
	(segment
		(start 104.815386 -186.445652)
		(end 104.585516 -186.733942)
		(width 0.14732)
		(layer "In4.Cu")
		(net "UPI_CPU0_CPU1_P1P0_DP<6>")
	)
	(segment
		(start 95.288608 -214.424768)
		(end 95.288608 -214.644732)
		(width 0.0889)
		(layer "In4.Cu")
		(net "UPI_CPU0_CPU1_P1P0_DP<6>")
	)
	(segment
		(start 368.365786 -183.078628)
		(end 368.205004 -182.747158)
		(width 0.14732)
		(layer "In4.Cu")
		(net "UPI_CPU0_CPU1_P1P0_DP<6>")
	)
	(segment
		(start 376.401584 -213.199726)
		(end 376.302778 -213.10092)
		(width 0.0889)
		(layer "In4.Cu")
		(net "UPI_CPU0_CPU1_P1P0_DP<6>")
	)
	(segment
		(start 276.295104 -141.697964)
		(end 238.590328 -142.376144)
		(width 0.14732)
		(layer "In4.Cu")
		(net "UPI_CPU0_CPU1_P1P0_DP<6>")
	)
	(segment
		(start 368.63782 -185.009028)
		(end 368.63782 -184.572148)
		(width 0.14732)
		(layer "In4.Cu")
		(net "UPI_CPU0_CPU1_P1P0_DP<6>")
	)
	(segment
		(start 104.585516 -186.733942)
		(end 104.382062 -186.756802)
		(width 0.14732)
		(layer "In4.Cu")
		(net "UPI_CPU0_CPU1_P1P0_DP<6>")
	)
	(segment
		(start 376.359674 -211.68614)
		(end 376.359674 -205.85684)
		(width 0.14732)
		(layer "In4.Cu")
		(net "UPI_CPU0_CPU1_P1P0_DP<6>")
	)
	(segment
		(start 94.818962 -213.8934)
		(end 94.819216 -213.893908)
		(width 0.0889)
		(layer "In4.Cu")
		(net "UPI_CPU0_CPU1_P1P0_DP<6>")
	)
	(segment
		(start 370.284756 -191.094106)
		(end 370.362988 -190.904876)
		(width 0.14732)
		(layer "In4.Cu")
		(net "UPI_CPU0_CPU1_P1P0_DP<6>")
	)
	(segment
		(start 370.98732 -192.412112)
		(end 370.614702 -191.512952)
		(width 0.14732)
		(layer "In4.Cu")
		(net "UPI_CPU0_CPU1_P1P0_DP<6>")
	)
	(segment
		(start 105.83291 -184.936892)
		(end 105.83291 -184.937146)
		(width 0.14732)
		(layer "In4.Cu")
		(net "UPI_CPU0_CPU1_P1P0_DP<6>")
	)
	(segment
		(start 103.94569 -187.536328)
		(end 103.742236 -187.559188)
		(width 0.14732)
		(layer "In4.Cu")
		(net "UPI_CPU0_CPU1_P1P0_DP<6>")
	)
	(segment
		(start 376.401584 -213.93023)
		(end 376.401584 -213.199726)
		(width 0.0889)
		(layer "In4.Cu")
		(net "UPI_CPU0_CPU1_P1P0_DP<6>")
	)
	(segment
		(start 368.205004 -182.747158)
		(end 368.27206 -182.55361)
		(width 0.14732)
		(layer "In4.Cu")
		(net "UPI_CPU0_CPU1_P1P0_DP<6>")
	)
	(segment
		(start 376.359928 -211.686394)
		(end 376.359674 -211.68614)
		(width 0.14732)
		(layer "In4.Cu")
		(net "UPI_CPU0_CPU1_P1P0_DP<6>")
	)
	(segment
		(start 368.559588 -183.145684)
		(end 368.365786 -183.078628)
		(width 0.14732)
		(layer "In4.Cu")
		(net "UPI_CPU0_CPU1_P1P0_DP<6>")
	)
	(segment
		(start 94.861126 -211.72805)
		(end 94.861126 -211.750148)
		(width 0.0889)
		(layer "In4.Cu")
		(net "UPI_CPU0_CPU1_P1P0_DP<6>")
	)
	(segment
		(start 104.152446 -187.044584)
		(end 104.17556 -187.248038)
		(width 0.14732)
		(layer "In4.Cu")
		(net "UPI_CPU0_CPU1_P1P0_DP<6>")
	)
	(segment
		(start 376.359928 -211.84743)
		(end 376.359928 -211.686394)
		(width 0.14732)
		(layer "In4.Cu")
		(net "UPI_CPU0_CPU1_P1P0_DP<6>")
	)
	(segment
		(start 376.401838 -212.65134)
		(end 376.302778 -212.55228)
		(width 0.0889)
		(layer "In4.Cu")
		(net "UPI_CPU0_CPU1_P1P0_DP<6>")
	)
	(segment
		(start 375.931684 -216.266014)
		(end 375.931684 -216.235026)
		(width 0.0889)
		(layer "In4.Cu")
		(net "UPI_CPU0_CPU1_P1P0_DP<6>")
	)
	(segment
		(start 95.007938 -215.762078)
		(end 95.01251 -215.764618)
		(width 0.0889)
		(layer "In4.Cu")
		(net "UPI_CPU0_CPU1_P1P0_DP<6>")
	)
	(segment
		(start 376.302778 -213.10092)
		(end 376.302778 -212.92566)
		(width 0.0889)
		(layer "In4.Cu")
		(net "UPI_CPU0_CPU1_P1P0_DP<6>")
	)
	(segment
		(start 376.401838 -212.8266)
		(end 376.401838 -212.65134)
		(width 0.0889)
		(layer "In4.Cu")
		(net "UPI_CPU0_CPU1_P1P0_DP<6>")
	)
	(segment
		(start 368.75974 -186.807094)
		(end 368.75974 -186.248548)
		(width 0.14732)
		(layer "In4.Cu")
		(net "UPI_CPU0_CPU1_P1P0_DP<6>")
	)
	(segment
		(start 329.627738 -146.116294)
		(end 318.127888 -143.299688)
		(width 0.14732)
		(layer "In4.Cu")
		(net "UPI_CPU0_CPU1_P1P0_DP<6>")
	)
	(segment
		(start 95.005398 -215.112854)
		(end 94.997524 -215.117426)
		(width 0.0889)
		(layer "In4.Cu")
		(net "UPI_CPU0_CPU1_P1P0_DP<6>")
	)
	(segment
		(start 376.684032 -214.946992)
		(end 376.692922 -214.941912)
		(width 0.0889)
		(layer "In4.Cu")
		(net "UPI_CPU0_CPU1_P1P0_DP<6>")
	)
	(segment
		(start 368.75974 -186.248548)
		(end 368.63782 -186.126628)
		(width 0.14732)
		(layer "In4.Cu")
		(net "UPI_CPU0_CPU1_P1P0_DP<6>")
	)
	(segment
		(start 376.302778 -212.92566)
		(end 376.401838 -212.8266)
		(width 0.0889)
		(layer "In4.Cu")
		(net "UPI_CPU0_CPU1_P1P0_DP<6>")
	)
	(segment
		(start 358.146096 -164.428932)
		(end 329.627738 -146.116294)
		(width 0.14732)
		(layer "In4.Cu")
		(net "UPI_CPU0_CPU1_P1P0_DP<6>")
	)
	(segment
		(start 105.432098 -185.439812)
		(end 105.455212 -185.643266)
		(width 0.14732)
		(layer "In4.Cu")
		(net "UPI_CPU0_CPU1_P1P0_DP<6>")
	)
	(segment
		(start 314.740798 -143.299688)
		(end 276.295104 -141.697964)
		(width 0.14732)
		(layer "In4.Cu")
		(net "UPI_CPU0_CPU1_P1P0_DP<6>")
	)
	(segment
		(start 104.382062 -186.756802)
		(end 104.152446 -187.044584)
		(width 0.14732)
		(layer "In4.Cu")
		(net "UPI_CPU0_CPU1_P1P0_DP<6>")
	)
	(segment
		(start 368.27206 -182.55361)
		(end 361.244642 -168.08196)
		(width 0.14732)
		(layer "In4.Cu")
		(net "UPI_CPU0_CPU1_P1P0_DP<6>")
	)
	(segment
		(start 95.002858 -215.75903)
		(end 95.00489 -215.7603)
		(width 0.0889)
		(layer "In4.Cu")
		(net "UPI_CPU0_CPU1_P1P0_DP<6>")
	)
	(segment
		(start 368.75974 -185.567828)
		(end 368.75974 -185.130948)
		(width 0.14732)
		(layer "In4.Cu")
		(net "UPI_CPU0_CPU1_P1P0_DP<6>")
	)
	(segment
		(start 369.891818 -190.145924)
		(end 369.97005 -189.956694)
		(width 0.14732)
		(layer "In4.Cu")
		(net "UPI_CPU0_CPU1_P1P0_DP<6>")
	)
	(segment
		(start 376.359928 -211.869528)
		(end 376.359928 -211.84743)
		(width 0.0889)
		(layer "In4.Cu")
		(net "UPI_CPU0_CPU1_P1P0_DP<6>")
	)
	(segment
		(start 376.214894 -216.740486)
		(end 376.213878 -216.739978)
		(width 0.0889)
		(layer "In4.Cu")
		(net "UPI_CPU0_CPU1_P1P0_DP<6>")
	)
	(segment
		(start 368.63782 -184.572148)
		(end 368.75974 -184.450228)
		(width 0.14732)
		(layer "In4.Cu")
		(net "UPI_CPU0_CPU1_P1P0_DP<6>")
	)
	(segment
		(start 103.742236 -187.559188)
		(end 103.51262 -187.84697)
		(width 0.14732)
		(layer "In4.Cu")
		(net "UPI_CPU0_CPU1_P1P0_DP<6>")
	)
	(segment
		(start 369.97005 -189.956694)
		(end 369.829334 -189.616588)
		(width 0.14732)
		(layer "In4.Cu")
		(net "UPI_CPU0_CPU1_P1P0_DP<6>")
	)
	(segment
		(start 376.302778 -212.37702)
		(end 376.401838 -212.27796)
		(width 0.0889)
		(layer "In4.Cu")
		(net "UPI_CPU0_CPU1_P1P0_DP<6>")
	)
	(segment
		(start 94.860872 -211.503768)
		(end 94.861126 -211.504022)
		(width 0.14732)
		(layer "In4.Cu")
		(net "UPI_CPU0_CPU1_P1P0_DP<6>")
	)
	(segment
		(start 370.032788 -190.486284)
		(end 369.891818 -190.145924)
		(width 0.14732)
		(layer "In4.Cu")
		(net "UPI_CPU0_CPU1_P1P0_DP<6>")
	)
	(segment
		(start 370.362988 -190.904876)
		(end 370.222018 -190.564516)
		(width 0.14732)
		(layer "In4.Cu")
		(net "UPI_CPU0_CPU1_P1P0_DP<6>")
	)
	(segment
		(start 95.005906 -216.740486)
		(end 95.003366 -216.74201)
		(width 0.0889)
		(layer "In4.Cu")
		(net "UPI_CPU0_CPU1_P1P0_DP<6>")
	)
	(segment
		(start 126.074678 -165.883844)
		(end 105.83291 -184.936892)
		(width 0.14732)
		(layer "In4.Cu")
		(net "UPI_CPU0_CPU1_P1P0_DP<6>")
	)
	(segment
		(start 105.225342 -185.931556)
		(end 105.021888 -185.954416)
		(width 0.14732)
		(layer "In4.Cu")
		(net "UPI_CPU0_CPU1_P1P0_DP<6>")
	)
	(segment
		(start 376.02668 -217.064336)
		(end 376.183144 -217.335354)
		(width 0.0889)
		(layer "In4.Cu")
		(net "UPI_CPU0_CPU1_P1P0_DP<6>")
	)
	(segment
		(start 376.302778 -212.55228)
		(end 376.302778 -212.37702)
		(width 0.0889)
		(layer "In4.Cu")
		(net "UPI_CPU0_CPU1_P1P0_DP<6>")
	)
	(segment
		(start 370.614702 -191.512952)
		(end 370.425726 -191.43472)
		(width 0.14732)
		(layer "In4.Cu")
		(net "UPI_CPU0_CPU1_P1P0_DP<6>")
	)
	(segment
		(start 104.792272 -186.242198)
		(end 104.815386 -186.445652)
		(width 0.14732)
		(layer "In4.Cu")
		(net "UPI_CPU0_CPU1_P1P0_DP<6>")
	)
	(segment
		(start 161.906204 -143.836644)
		(end 126.074678 -165.883844)
		(width 0.14732)
		(layer "In4.Cu")
		(net "UPI_CPU0_CPU1_P1P0_DP<6>")
	)
	(segment
		(start 376.213878 -215.761062)
		(end 376.214894 -215.760554)
		(width 0.0889)
		(layer "In4.Cu")
		(net "UPI_CPU0_CPU1_P1P0_DP<6>")
	)
	(segment
		(start 369.288314 -189.075568)
		(end 369.13947 -188.716158)
		(width 0.14732)
		(layer "In4.Cu")
		(net "UPI_CPU0_CPU1_P1P0_DP<6>")
	)
	(segment
		(start 376.222768 -216.745058)
		(end 376.214894 -216.740486)
		(width 0.0889)
		(layer "In4.Cu")
		(net "UPI_CPU0_CPU1_P1P0_DP<6>")
	)
	(segment
		(start 368.75974 -184.450228)
		(end 368.75974 -183.557926)
		(width 0.14732)
		(layer "In4.Cu")
		(net "UPI_CPU0_CPU1_P1P0_DP<6>")
	)
	(segment
		(start 103.51262 -187.84697)
		(end 94.860872 -211.278724)
		(width 0.14732)
		(layer "In4.Cu")
		(net "UPI_CPU0_CPU1_P1P0_DP<6>")
	)
	(segment
		(start 376.871484 -214.622634)
		(end 376.871484 -214.461852)
		(width 0.0889)
		(layer "In4.Cu")
		(net "UPI_CPU0_CPU1_P1P0_DP<6>")
	)
	(segment
		(start 238.590328 -142.376144)
		(end 169.377868 -141.25702)
		(width 0.14732)
		(layer "In4.Cu")
		(net "UPI_CPU0_CPU1_P1P0_DP<6>")
	)
	(segment
		(start 369.13947 -188.716158)
		(end 368.75974 -186.807094)
		(width 0.14732)
		(layer "In4.Cu")
		(net "UPI_CPU0_CPU1_P1P0_DP<6>")
	)
	(segment
		(start 95.006668 -216.739978)
		(end 95.005906 -216.740486)
		(width 0.0889)
		(layer "In4.Cu")
		(net "UPI_CPU0_CPU1_P1P0_DP<6>")
	)
	(segment
		(start 94.818962 -211.792312)
		(end 94.818962 -213.8934)
		(width 0.0889)
		(layer "In4.Cu")
		(net "UPI_CPU0_CPU1_P1P0_DP<6>")
	)
	(segment
		(start 94.861126 -211.750148)
		(end 94.818962 -211.792312)
		(width 0.0889)
		(layer "In4.Cu")
		(net "UPI_CPU0_CPU1_P1P0_DP<6>")
	)
	(segment
		(start 318.127888 -143.299688)
		(end 314.740798 -143.299688)
		(width 0.14732)
		(layer "In4.Cu")
		(net "UPI_CPU0_CPU1_P1P0_DP<6>")
	)
	(segment
		(start 105.455212 -185.643266)
		(end 105.225342 -185.931556)
		(width 0.14732)
		(layer "In4.Cu")
		(net "UPI_CPU0_CPU1_P1P0_DP<6>")
	)
	(segment
		(start 105.021888 -185.954416)
		(end 104.792272 -186.242198)
		(width 0.14732)
		(layer "In4.Cu")
		(net "UPI_CPU0_CPU1_P1P0_DP<6>")
	)
	(arc
		(start 376.222768 -215.755982)
		(mid 376.353682 -215.619622)
		(end 376.40133 -215.436704)
		(width 0.0889)
		(layer "In4.Cu")
		(net "UPI_CPU0_CPU1_P1P0_DP<6>")
	)
	(arc
		(start 376.871484 -214.461852)
		(mid 376.796413 -214.34611)
		(end 376.68708 -214.261954)
		(width 0.0889)
		(layer "In4.Cu")
		(net "UPI_CPU0_CPU1_P1P0_DP<6>")
	)
	(arc
		(start 95.006668 -217.388694)
		(mid 95.287746 -217.834929)
		(end 95.078296 -218.318842)
		(width 0.0889)
		(layer "In4.Cu")
		(net "UPI_CPU0_CPU1_P1P0_DP<6>")
	)
	(arc
		(start 376.41657 -213.968838)
		(mid 376.408748 -213.949662)
		(end 376.401584 -213.93023)
		(width 0.0889)
		(layer "In4.Cu")
		(net "UPI_CPU0_CPU1_P1P0_DP<6>")
	)
	(arc
		(start 376.261376 -217.356182)
		(mid 376.400439 -217.040661)
		(end 376.222768 -216.745058)
		(width 0.0889)
		(layer "In4.Cu")
		(net "UPI_CPU0_CPU1_P1P0_DP<6>")
	)
	(arc
		(start 95.288608 -214.644732)
		(mid 95.207697 -214.91486)
		(end 95.006414 -215.112346)
		(width 0.0889)
		(layer "In4.Cu")
		(net "UPI_CPU0_CPU1_P1P0_DP<6>")
	)
	(arc
		(start 375.931684 -216.235026)
		(mid 376.011054 -215.961292)
		(end 376.213878 -215.761062)
		(width 0.0889)
		(layer "In4.Cu")
		(net "UPI_CPU0_CPU1_P1P0_DP<6>")
	)
	(arc
		(start 376.692922 -214.941912)
		(mid 376.823836 -214.805552)
		(end 376.871484 -214.622634)
		(width 0.0889)
		(layer "In4.Cu")
		(net "UPI_CPU0_CPU1_P1P0_DP<6>")
	)
	(arc
		(start 94.997524 -215.117426)
		(mid 94.818927 -215.436704)
		(end 94.997524 -215.755982)
		(width 0.0889)
		(layer "In4.Cu")
		(net "UPI_CPU0_CPU1_P1P0_DP<6>")
	)
	(arc
		(start 94.997778 -216.745058)
		(mid 94.819181 -217.064336)
		(end 94.997778 -217.383614)
		(width 0.0889)
		(layer "In4.Cu")
		(net "UPI_CPU0_CPU1_P1P0_DP<6>")
	)
	(arc
		(start 95.01251 -215.764618)
		(mid 95.289074 -216.253939)
		(end 95.006668 -216.739978)
		(width 0.0889)
		(layer "In4.Cu")
		(net "UPI_CPU0_CPU1_P1P0_DP<6>")
	)
	(arc
		(start 376.68708 -214.261954)
		(mid 376.526725 -214.138568)
		(end 376.41657 -213.968838)
		(width 0.0889)
		(layer "In4.Cu")
		(net "UPI_CPU0_CPU1_P1P0_DP<6>")
	)
	(arc
		(start 95.078296 -218.318842)
		(mid 95.06985 -218.325527)
		(end 95.061278 -218.33205)
		(width 0.0889)
		(layer "In4.Cu")
		(net "UPI_CPU0_CPU1_P1P0_DP<6>")
	)
	(arc
		(start 376.40133 -215.436704)
		(mid 376.473503 -215.160036)
		(end 376.67184 -214.954104)
		(width 0.0889)
		(layer "In4.Cu")
		(net "UPI_CPU0_CPU1_P1P0_DP<6>")
	)
	(arc
		(start 95.003366 -214.093298)
		(mid 95.177329 -214.232062)
		(end 95.288608 -214.424768)
		(width 0.0889)
		(layer "In4.Cu")
		(net "UPI_CPU0_CPU1_P1P0_DP<6>")
	)
	(arc
		(start 94.819216 -213.893908)
		(mid 94.894221 -214.009367)
		(end 95.003366 -214.093298)
		(width 0.0889)
		(layer "In4.Cu")
		(net "UPI_CPU0_CPU1_P1P0_DP<6>")
	)
	(arc
		(start 376.213878 -216.739978)
		(mid 376.011055 -216.539747)
		(end 375.931684 -216.266014)
		(width 0.0889)
		(layer "In4.Cu")
		(net "UPI_CPU0_CPU1_P1P0_DP<6>")
	)
	(segment
		(start 377.43638 -217.87866)
		(end 377.436634 -217.878406)
		(width 0.13208)
		(layer "F.Cu")
		(net "UPI_CPU0_CPU1_P1P0_DP<5>")
	)
	(segment
		(start 93.783912 -218.414346)
		(end 93.783912 -217.87866)
		(width 0.13208)
		(layer "F.Cu")
		(net "UPI_CPU0_CPU1_P1P0_DP<5>")
	)
	(segment
		(start 93.783912 -217.87866)
		(end 93.784166 -217.878406)
		(width 0.13208)
		(layer "F.Cu")
		(net "UPI_CPU0_CPU1_P1P0_DP<5>")
	)
	(segment
		(start 377.43638 -218.414346)
		(end 377.43638 -217.87866)
		(width 0.13208)
		(layer "F.Cu")
		(net "UPI_CPU0_CPU1_P1P0_DP<5>")
	)
	(segment
		(start 318.262762 -142.187168)
		(end 315.29147 -142.187168)
		(width 0.14732)
		(layer "In4.Cu")
		(net "UPI_CPU0_CPU1_P1P0_DP<5>")
	)
	(segment
		(start 358.8639 -163.567364)
		(end 330.072746 -145.079212)
		(width 0.14732)
		(layer "In4.Cu")
		(net "UPI_CPU0_CPU1_P1P0_DP<5>")
	)
	(segment
		(start 93.972126 -215.92667)
		(end 93.976952 -215.929464)
		(width 0.0889)
		(layer "In4.Cu")
		(net "UPI_CPU0_CPU1_P1P0_DP<5>")
	)
	(segment
		(start 377.28017 -218.149424)
		(end 377.201938 -218.170252)
		(width 0.0889)
		(layer "In4.Cu")
		(net "UPI_CPU0_CPU1_P1P0_DP<5>")
	)
	(segment
		(start 94.158308 -214.461344)
		(end 94.158308 -214.622634)
		(width 0.0889)
		(layer "In4.Cu")
		(net "UPI_CPU0_CPU1_P1P0_DP<5>")
	)
	(segment
		(start 256.768854 -140.82903)
		(end 238.589312 -141.155674)
		(width 0.14732)
		(layer "In4.Cu")
		(net "UPI_CPU0_CPU1_P1P0_DP<5>")
	)
	(segment
		(start 372.349776 -180.759354)
		(end 371.968522 -180.458618)
		(width 0.14732)
		(layer "In4.Cu")
		(net "UPI_CPU0_CPU1_P1P0_DP<5>")
	)
	(segment
		(start 369.356132 -179.926996)
		(end 369.010184 -179.730146)
		(width 0.14732)
		(layer "In4.Cu")
		(net "UPI_CPU0_CPU1_P1P0_DP<5>")
	)
	(segment
		(start 315.29147 -142.187168)
		(end 274.877022 -140.503402)
		(width 0.14732)
		(layer "In4.Cu")
		(net "UPI_CPU0_CPU1_P1P0_DP<5>")
	)
	(segment
		(start 377.574048 -211.572602)
		(end 377.573794 -211.572348)
		(width 0.14732)
		(layer "In4.Cu")
		(net "UPI_CPU0_CPU1_P1P0_DP<5>")
	)
	(segment
		(start 377.574048 -211.869528)
		(end 377.574048 -211.84743)
		(width 0.0889)
		(layer "In4.Cu")
		(net "UPI_CPU0_CPU1_P1P0_DP<5>")
	)
	(segment
		(start 377.630944 -212.29828)
		(end 377.531884 -212.19922)
		(width 0.0889)
		(layer "In4.Cu")
		(net "UPI_CPU0_CPU1_P1P0_DP<5>")
	)
	(segment
		(start 93.647006 -211.973668)
		(end 93.688916 -212.015578)
		(width 0.0889)
		(layer "In4.Cu")
		(net "UPI_CPU0_CPU1_P1P0_DP<5>")
	)
	(segment
		(start 377.574048 -211.84743)
		(end 377.574048 -211.572602)
		(width 0.14732)
		(layer "In4.Cu")
		(net "UPI_CPU0_CPU1_P1P0_DP<5>")
	)
	(segment
		(start 377.531884 -215.436704)
		(end 377.531884 -215.428068)
		(width 0.0889)
		(layer "In4.Cu")
		(net "UPI_CPU0_CPU1_P1P0_DP<5>")
	)
	(segment
		(start 93.9165 -217.518234)
		(end 93.94063 -217.607388)
		(width 0.0889)
		(layer "In4.Cu")
		(net "UPI_CPU0_CPU1_P1P0_DP<5>")
	)
	(segment
		(start 256.771394 -140.82903)
		(end 256.768854 -140.82903)
		(width 0.14732)
		(layer "In4.Cu")
		(net "UPI_CPU0_CPU1_P1P0_DP<5>")
	)
	(segment
		(start 93.980254 -216.569798)
		(end 93.965014 -216.578688)
		(width 0.0889)
		(layer "In4.Cu")
		(net "UPI_CPU0_CPU1_P1P0_DP<5>")
	)
	(segment
		(start 377.531884 -213.8934)
		(end 377.531884 -213.22538)
		(width 0.0889)
		(layer "In4.Cu")
		(net "UPI_CPU0_CPU1_P1P0_DP<5>")
	)
	(segment
		(start 94.375478 -208.919826)
		(end 94.374716 -208.922112)
		(width 0.14732)
		(layer "In4.Cu")
		(net "UPI_CPU0_CPU1_P1P0_DP<5>")
	)
	(segment
		(start 377.531884 -212.19922)
		(end 377.531884 -211.911692)
		(width 0.0889)
		(layer "In4.Cu")
		(net "UPI_CPU0_CPU1_P1P0_DP<5>")
	)
	(segment
		(start 93.976952 -215.929464)
		(end 93.978984 -215.93048)
		(width 0.0889)
		(layer "In4.Cu")
		(net "UPI_CPU0_CPU1_P1P0_DP<5>")
	)
	(segment
		(start 274.877022 -140.503402)
		(end 256.771394 -140.82903)
		(width 0.14732)
		(layer "In4.Cu")
		(net "UPI_CPU0_CPU1_P1P0_DP<5>")
	)
	(segment
		(start 93.979746 -214.941912)
		(end 93.970856 -214.946992)
		(width 0.0889)
		(layer "In4.Cu")
		(net "UPI_CPU0_CPU1_P1P0_DP<5>")
	)
	(segment
		(start 377.53163 -215.455246)
		(end 377.531884 -215.436704)
		(width 0.0889)
		(layer "In4.Cu")
		(net "UPI_CPU0_CPU1_P1P0_DP<5>")
	)
	(segment
		(start 93.965014 -216.578688)
		(end 93.965268 -216.578434)
		(width 0.0889)
		(layer "In4.Cu")
		(net "UPI_CPU0_CPU1_P1P0_DP<5>")
	)
	(segment
		(start 377.630944 -212.95106)
		(end 377.531884 -212.852)
		(width 0.0889)
		(layer "In4.Cu")
		(net "UPI_CPU0_CPU1_P1P0_DP<5>")
	)
	(segment
		(start 377.249436 -216.574878)
		(end 377.240546 -216.569798)
		(width 0.0889)
		(layer "In4.Cu")
		(net "UPI_CPU0_CPU1_P1P0_DP<5>")
	)
	(segment
		(start 93.647006 -211.709762)
		(end 93.647006 -211.95157)
		(width 0.14732)
		(layer "In4.Cu")
		(net "UPI_CPU0_CPU1_P1P0_DP<5>")
	)
	(segment
		(start 377.573794 -211.572348)
		(end 377.573794 -206.041498)
		(width 0.14732)
		(layer "In4.Cu")
		(net "UPI_CPU0_CPU1_P1P0_DP<5>")
	)
	(segment
		(start 377.531884 -217.082878)
		(end 377.531884 -217.05443)
		(width 0.0889)
		(layer "In4.Cu")
		(net "UPI_CPU0_CPU1_P1P0_DP<5>")
	)
	(segment
		(start 94.374716 -208.922112)
		(end 93.646752 -210.89366)
		(width 0.14732)
		(layer "In4.Cu")
		(net "UPI_CPU0_CPU1_P1P0_DP<5>")
	)
	(segment
		(start 93.688662 -215.414606)
		(end 93.688662 -215.436704)
		(width 0.0889)
		(layer "In4.Cu")
		(net "UPI_CPU0_CPU1_P1P0_DP<5>")
	)
	(segment
		(start 93.978984 -215.93048)
		(end 93.980254 -215.931242)
		(width 0.0889)
		(layer "In4.Cu")
		(net "UPI_CPU0_CPU1_P1P0_DP<5>")
	)
	(segment
		(start 371.9195 -183.869584)
		(end 372.66372 -182.072788)
		(width 0.14732)
		(layer "In4.Cu")
		(net "UPI_CPU0_CPU1_P1P0_DP<5>")
	)
	(segment
		(start 377.531884 -211.911692)
		(end 377.574048 -211.869528)
		(width 0.0889)
		(layer "In4.Cu")
		(net "UPI_CPU0_CPU1_P1P0_DP<5>")
	)
	(segment
		(start 377.436634 -217.878406)
		(end 377.28017 -218.149424)
		(width 0.0889)
		(layer "In4.Cu")
		(net "UPI_CPU0_CPU1_P1P0_DP<5>")
	)
	(segment
		(start 372.66372 -182.072788)
		(end 372.66372 -181.284372)
		(width 0.14732)
		(layer "In4.Cu")
		(net "UPI_CPU0_CPU1_P1P0_DP<5>")
	)
	(segment
		(start 93.646752 -211.709508)
		(end 93.647006 -211.709762)
		(width 0.14732)
		(layer "In4.Cu")
		(net "UPI_CPU0_CPU1_P1P0_DP<5>")
	)
	(segment
		(start 93.965268 -215.922606)
		(end 93.96857 -215.924384)
		(width 0.0889)
		(layer "In4.Cu")
		(net "UPI_CPU0_CPU1_P1P0_DP<5>")
	)
	(segment
		(start 377.630944 -212.47354)
		(end 377.630944 -212.29828)
		(width 0.0889)
		(layer "In4.Cu")
		(net "UPI_CPU0_CPU1_P1P0_DP<5>")
	)
	(segment
		(start 377.531884 -212.5726)
		(end 377.630944 -212.47354)
		(width 0.0889)
		(layer "In4.Cu")
		(net "UPI_CPU0_CPU1_P1P0_DP<5>")
	)
	(segment
		(start 362.219748 -167.512238)
		(end 358.8639 -163.567364)
		(width 0.14732)
		(layer "In4.Cu")
		(net "UPI_CPU0_CPU1_P1P0_DP<5>")
	)
	(segment
		(start 104.943148 -184.223406)
		(end 102.243636 -187.60821)
		(width 0.14732)
		(layer "In4.Cu")
		(net "UPI_CPU0_CPU1_P1P0_DP<5>")
	)
	(segment
		(start 125.336808 -165.028118)
		(end 104.943148 -184.223406)
		(width 0.14732)
		(layer "In4.Cu")
		(net "UPI_CPU0_CPU1_P1P0_DP<5>")
	)
	(segment
		(start 93.688916 -212.015578)
		(end 93.688916 -213.930484)
		(width 0.0889)
		(layer "In4.Cu")
		(net "UPI_CPU0_CPU1_P1P0_DP<5>")
	)
	(segment
		(start 377.531884 -212.852)
		(end 377.531884 -212.5726)
		(width 0.0889)
		(layer "In4.Cu")
		(net "UPI_CPU0_CPU1_P1P0_DP<5>")
	)
	(segment
		(start 378.001784 -214.636858)
		(end 378.001784 -214.425022)
		(width 0.0889)
		(layer "In4.Cu")
		(net "UPI_CPU0_CPU1_P1P0_DP<5>")
	)
	(segment
		(start 93.646752 -210.89366)
		(end 93.646752 -211.709508)
		(width 0.14732)
		(layer "In4.Cu")
		(net "UPI_CPU0_CPU1_P1P0_DP<5>")
	)
	(segment
		(start 93.970602 -215.925654)
		(end 93.972126 -215.92667)
		(width 0.0889)
		(layer "In4.Cu")
		(net "UPI_CPU0_CPU1_P1P0_DP<5>")
	)
	(segment
		(start 93.688662 -217.064336)
		(end 93.688662 -217.07856)
		(width 0.0889)
		(layer "In4.Cu")
		(net "UPI_CPU0_CPU1_P1P0_DP<5>")
	)
	(segment
		(start 371.9195 -185.151776)
		(end 371.9195 -183.869584)
		(width 0.14732)
		(layer "In4.Cu")
		(net "UPI_CPU0_CPU1_P1P0_DP<5>")
	)
	(segment
		(start 238.589312 -141.155674)
		(end 169.463212 -140.038074)
		(width 0.14732)
		(layer "In4.Cu")
		(net "UPI_CPU0_CPU1_P1P0_DP<5>")
	)
	(segment
		(start 377.240546 -215.931242)
		(end 377.249436 -215.926162)
		(width 0.0889)
		(layer "In4.Cu")
		(net "UPI_CPU0_CPU1_P1P0_DP<5>")
	)
	(segment
		(start 93.647006 -211.95157)
		(end 93.647006 -211.973668)
		(width 0.0889)
		(layer "In4.Cu")
		(net "UPI_CPU0_CPU1_P1P0_DP<5>")
	)
	(segment
		(start 93.94063 -217.607388)
		(end 93.784166 -217.878406)
		(width 0.0889)
		(layer "In4.Cu")
		(net "UPI_CPU0_CPU1_P1P0_DP<5>")
	)
	(segment
		(start 369.010184 -179.730146)
		(end 367.16843 -177.700432)
		(width 0.14732)
		(layer "In4.Cu")
		(net "UPI_CPU0_CPU1_P1P0_DP<5>")
	)
	(segment
		(start 372.66372 -181.284372)
		(end 372.349776 -180.759354)
		(width 0.14732)
		(layer "In4.Cu")
		(net "UPI_CPU0_CPU1_P1P0_DP<5>")
	)
	(segment
		(start 93.96857 -215.924384)
		(end 93.970602 -215.925654)
		(width 0.0889)
		(layer "In4.Cu")
		(net "UPI_CPU0_CPU1_P1P0_DP<5>")
	)
	(segment
		(start 102.243636 -187.60821)
		(end 94.375478 -208.919826)
		(width 0.14732)
		(layer "In4.Cu")
		(net "UPI_CPU0_CPU1_P1P0_DP<5>")
	)
	(segment
		(start 367.16843 -177.700432)
		(end 362.219748 -167.512238)
		(width 0.14732)
		(layer "In4.Cu")
		(net "UPI_CPU0_CPU1_P1P0_DP<5>")
	)
	(segment
		(start 330.072746 -145.079212)
		(end 318.262762 -142.187168)
		(width 0.14732)
		(layer "In4.Cu")
		(net "UPI_CPU0_CPU1_P1P0_DP<5>")
	)
	(segment
		(start 371.968522 -180.458618)
		(end 369.356132 -179.926996)
		(width 0.14732)
		(layer "In4.Cu")
		(net "UPI_CPU0_CPU1_P1P0_DP<5>")
	)
	(segment
		(start 169.463212 -140.038074)
		(end 161.459164 -142.80134)
		(width 0.14732)
		(layer "In4.Cu")
		(net "UPI_CPU0_CPU1_P1P0_DP<5>")
	)
	(segment
		(start 377.630944 -213.12632)
		(end 377.630944 -212.95106)
		(width 0.0889)
		(layer "In4.Cu")
		(net "UPI_CPU0_CPU1_P1P0_DP<5>")
	)
	(segment
		(start 377.531884 -213.22538)
		(end 377.630944 -213.12632)
		(width 0.0889)
		(layer "In4.Cu")
		(net "UPI_CPU0_CPU1_P1P0_DP<5>")
	)
	(segment
		(start 161.459164 -142.80134)
		(end 125.336808 -165.028118)
		(width 0.14732)
		(layer "In4.Cu")
		(net "UPI_CPU0_CPU1_P1P0_DP<5>")
	)
	(segment
		(start 373.281448 -187.603638)
		(end 371.9195 -185.151776)
		(width 0.14732)
		(layer "In4.Cu")
		(net "UPI_CPU0_CPU1_P1P0_DP<5>")
	)
	(segment
		(start 377.240546 -217.559128)
		(end 377.249436 -217.554048)
		(width 0.0889)
		(layer "In4.Cu")
		(net "UPI_CPU0_CPU1_P1P0_DP<5>")
	)
	(segment
		(start 377.573794 -206.041498)
		(end 373.281448 -187.603638)
		(width 0.14732)
		(layer "In4.Cu")
		(net "UPI_CPU0_CPU1_P1P0_DP<5>")
	)
	(arc
		(start 377.061984 -217.878406)
		(mid 377.109663 -217.695506)
		(end 377.240546 -217.559128)
		(width 0.0889)
		(layer "In4.Cu")
		(net "UPI_CPU0_CPU1_P1P0_DP<5>")
	)
	(arc
		(start 377.061984 -216.257124)
		(mid 377.061994 -216.247724)
		(end 377.062238 -216.238328)
		(width 0.0889)
		(layer "In4.Cu")
		(net "UPI_CPU0_CPU1_P1P0_DP<5>")
	)
	(arc
		(start 93.704156 -213.969346)
		(mid 93.81415 -214.138715)
		(end 93.974158 -214.261954)
		(width 0.0889)
		(layer "In4.Cu")
		(net "UPI_CPU0_CPU1_P1P0_DP<5>")
	)
	(arc
		(start 93.970856 -214.946992)
		(mid 93.769574 -215.144479)
		(end 93.688662 -215.414606)
		(width 0.0889)
		(layer "In4.Cu")
		(net "UPI_CPU0_CPU1_P1P0_DP<5>")
	)
	(arc
		(start 377.719082 -215.112346)
		(mid 377.922563 -214.911542)
		(end 378.001784 -214.636858)
		(width 0.0889)
		(layer "In4.Cu")
		(net "UPI_CPU0_CPU1_P1P0_DP<5>")
	)
	(arc
		(start 93.688662 -215.436704)
		(mid 93.762653 -215.71627)
		(end 93.965268 -215.922606)
		(width 0.0889)
		(layer "In4.Cu")
		(net "UPI_CPU0_CPU1_P1P0_DP<5>")
	)
	(arc
		(start 377.062238 -216.238328)
		(mid 377.112731 -216.06235)
		(end 377.240546 -215.931242)
		(width 0.0889)
		(layer "In4.Cu")
		(net "UPI_CPU0_CPU1_P1P0_DP<5>")
	)
	(arc
		(start 93.899482 -217.50528)
		(mid 93.90793 -217.511837)
		(end 93.9165 -217.518234)
		(width 0.0889)
		(layer "In4.Cu")
		(net "UPI_CPU0_CPU1_P1P0_DP<5>")
	)
	(arc
		(start 93.980254 -215.931242)
		(mid 94.158851 -216.25052)
		(end 93.980254 -216.569798)
		(width 0.0889)
		(layer "In4.Cu")
		(net "UPI_CPU0_CPU1_P1P0_DP<5>")
	)
	(arc
		(start 93.974158 -214.261954)
		(mid 94.083305 -214.345882)
		(end 94.158308 -214.461344)
		(width 0.0889)
		(layer "In4.Cu")
		(net "UPI_CPU0_CPU1_P1P0_DP<5>")
	)
	(arc
		(start 93.965268 -216.578434)
		(mid 93.762681 -216.784785)
		(end 93.688662 -217.064336)
		(width 0.0889)
		(layer "In4.Cu")
		(net "UPI_CPU0_CPU1_P1P0_DP<5>")
	)
	(arc
		(start 377.240546 -216.569798)
		(mid 377.111257 -216.436312)
		(end 377.061984 -216.257124)
		(width 0.0889)
		(layer "In4.Cu")
		(net "UPI_CPU0_CPU1_P1P0_DP<5>")
	)
	(arc
		(start 377.716288 -214.093298)
		(mid 377.606892 -214.009201)
		(end 377.531884 -213.8934)
		(width 0.0889)
		(layer "In4.Cu")
		(net "UPI_CPU0_CPU1_P1P0_DP<5>")
	)
	(arc
		(start 377.531884 -215.428068)
		(mid 377.584154 -215.245703)
		(end 377.719082 -215.112346)
		(width 0.0889)
		(layer "In4.Cu")
		(net "UPI_CPU0_CPU1_P1P0_DP<5>")
	)
	(arc
		(start 93.688662 -217.07856)
		(mid 93.746956 -217.315203)
		(end 93.899482 -217.50528)
		(width 0.0889)
		(layer "In4.Cu")
		(net "UPI_CPU0_CPU1_P1P0_DP<5>")
	)
	(arc
		(start 377.201938 -218.170252)
		(mid 377.098793 -218.040227)
		(end 377.061984 -217.878406)
		(width 0.0889)
		(layer "In4.Cu")
		(net "UPI_CPU0_CPU1_P1P0_DP<5>")
	)
	(arc
		(start 93.688916 -213.930484)
		(mid 93.696201 -213.950046)
		(end 93.704156 -213.969346)
		(width 0.0889)
		(layer "In4.Cu")
		(net "UPI_CPU0_CPU1_P1P0_DP<5>")
	)
	(arc
		(start 94.158308 -214.622634)
		(mid 94.110629 -214.805534)
		(end 93.979746 -214.941912)
		(width 0.0889)
		(layer "In4.Cu")
		(net "UPI_CPU0_CPU1_P1P0_DP<5>")
	)
	(arc
		(start 377.249436 -217.554048)
		(mid 377.451722 -217.355067)
		(end 377.531884 -217.082878)
		(width 0.0889)
		(layer "In4.Cu")
		(net "UPI_CPU0_CPU1_P1P0_DP<5>")
	)
	(arc
		(start 377.249436 -215.926162)
		(mid 377.451478 -215.727239)
		(end 377.53163 -215.455246)
		(width 0.0889)
		(layer "In4.Cu")
		(net "UPI_CPU0_CPU1_P1P0_DP<5>")
	)
	(arc
		(start 377.531884 -217.05443)
		(mid 377.453773 -216.777481)
		(end 377.249436 -216.574878)
		(width 0.0889)
		(layer "In4.Cu")
		(net "UPI_CPU0_CPU1_P1P0_DP<5>")
	)
	(arc
		(start 378.001784 -214.425022)
		(mid 377.890446 -214.232122)
		(end 377.716288 -214.093298)
		(width 0.0889)
		(layer "In4.Cu")
		(net "UPI_CPU0_CPU1_P1P0_DP<5>")
	)
	(segment
		(start 377.906534 -217.06459)
		(end 377.90628 -217.064336)
		(width 0.13208)
		(layer "F.Cu")
		(net "UPI_CPU0_CPU1_P1P0_DP<4>")
	)
	(segment
		(start 377.906534 -217.600276)
		(end 377.906534 -217.06459)
		(width 0.13208)
		(layer "F.Cu")
		(net "UPI_CPU0_CPU1_P1P0_DP<4>")
	)
	(segment
		(start 93.314266 -219.228162)
		(end 93.314266 -218.692476)
		(width 0.13208)
		(layer "F.Cu")
		(net "UPI_CPU0_CPU1_P1P0_DP<4>")
	)
	(segment
		(start 93.314266 -218.692476)
		(end 93.314012 -218.692222)
		(width 0.13208)
		(layer "F.Cu")
		(net "UPI_CPU0_CPU1_P1P0_DP<4>")
	)
	(segment
		(start 378.239528 -211.869528)
		(end 378.239528 -211.84743)
		(width 0.0889)
		(layer "In4.Cu")
		(net "UPI_CPU0_CPU1_P1P0_DP<4>")
	)
	(segment
		(start 93.12529 -215.7603)
		(end 93.126814 -215.761062)
		(width 0.0889)
		(layer "In4.Cu")
		(net "UPI_CPU0_CPU1_P1P0_DP<4>")
	)
	(segment
		(start 93.183456 -210.16468)
		(end 93.183202 -210.164934)
		(width 0.14732)
		(layer "In4.Cu")
		(net "UPI_CPU0_CPU1_P1P0_DP<4>")
	)
	(segment
		(start 362.687108 -167.206676)
		(end 359.232454 -163.145724)
		(width 0.14732)
		(layer "In4.Cu")
		(net "UPI_CPU0_CPU1_P1P0_DP<4>")
	)
	(segment
		(start 101.512624 -187.603892)
		(end 94.19336 -207.428846)
		(width 0.14732)
		(layer "In4.Cu")
		(net "UPI_CPU0_CPU1_P1P0_DP<4>")
	)
	(segment
		(start 378.55144 -214.954104)
		(end 378.563632 -214.946992)
		(width 0.0889)
		(layer "In4.Cu")
		(net "UPI_CPU0_CPU1_P1P0_DP<4>")
	)
	(segment
		(start 372.944136 -178.738276)
		(end 372.740174 -178.721004)
		(width 0.14732)
		(layer "In4.Cu")
		(net "UPI_CPU0_CPU1_P1P0_DP<4>")
	)
	(segment
		(start 373.844566 -179.805838)
		(end 373.605806 -179.522882)
		(width 0.14732)
		(layer "In4.Cu")
		(net "UPI_CPU0_CPU1_P1P0_DP<4>")
	)
	(segment
		(start 378.238766 -206.086202)
		(end 376.258074 -185.348372)
		(width 0.14732)
		(layer "In4.Cu")
		(net "UPI_CPU0_CPU1_P1P0_DP<4>")
	)
	(segment
		(start 378.281438 -212.6615)
		(end 378.182378 -212.56244)
		(width 0.0889)
		(layer "In4.Cu")
		(net "UPI_CPU0_CPU1_P1P0_DP<4>")
	)
	(segment
		(start 376.074432 -183.425338)
		(end 375.978674 -182.420514)
		(width 0.14732)
		(layer "In4.Cu")
		(net "UPI_CPU0_CPU1_P1P0_DP<4>")
	)
	(segment
		(start 93.126306 -217.388186)
		(end 93.127068 -217.388694)
		(width 0.0889)
		(layer "In4.Cu")
		(net "UPI_CPU0_CPU1_P1P0_DP<4>")
	)
	(segment
		(start 378.281438 -212.28812)
		(end 378.281438 -211.911438)
		(width 0.0889)
		(layer "In4.Cu")
		(net "UPI_CPU0_CPU1_P1P0_DP<4>")
	)
	(segment
		(start 92.939616 -213.789006)
		(end 92.93987 -213.788752)
		(width 0.0889)
		(layer "In4.Cu")
		(net "UPI_CPU0_CPU1_P1P0_DP<4>")
	)
	(segment
		(start 318.329818 -141.633448)
		(end 315.368432 -141.633448)
		(width 0.14732)
		(layer "In4.Cu")
		(net "UPI_CPU0_CPU1_P1P0_DP<4>")
	)
	(segment
		(start 378.182378 -212.98408)
		(end 378.281438 -212.88502)
		(width 0.0889)
		(layer "In4.Cu")
		(net "UPI_CPU0_CPU1_P1P0_DP<4>")
	)
	(segment
		(start 124.980446 -164.574474)
		(end 104.521254 -183.83123)
		(width 0.14732)
		(layer "In4.Cu")
		(net "UPI_CPU0_CPU1_P1P0_DP<4>")
	)
	(segment
		(start 93.806264 -208.477358)
		(end 93.8784 -208.633822)
		(width 0.14732)
		(layer "In4.Cu")
		(net "UPI_CPU0_CPU1_P1P0_DP<4>")
	)
	(segment
		(start 93.12656 -215.1126)
		(end 93.117924 -215.117426)
		(width 0.0889)
		(layer "In4.Cu")
		(net "UPI_CPU0_CPU1_P1P0_DP<4>")
	)
	(segment
		(start 372.519702 -178.235356)
		(end 372.143528 -177.789332)
		(width 0.14732)
		(layer "In4.Cu")
		(net "UPI_CPU0_CPU1_P1P0_DP<4>")
	)
	(segment
		(start 93.409516 -217.859864)
		(end 93.409516 -217.878406)
		(width 0.0889)
		(layer "In4.Cu")
		(net "UPI_CPU0_CPU1_P1P0_DP<4>")
	)
	(segment
		(start 376.065542 -184.85104)
		(end 376.195844 -184.693306)
		(width 0.14732)
		(layer "In4.Cu")
		(net "UPI_CPU0_CPU1_P1P0_DP<4>")
	)
	(segment
		(start 378.182378 -212.56244)
		(end 378.182378 -212.38718)
		(width 0.0889)
		(layer "In4.Cu")
		(net "UPI_CPU0_CPU1_P1P0_DP<4>")
	)
	(segment
		(start 376.195336 -184.693306)
		(end 376.136916 -184.080404)
		(width 0.14732)
		(layer "In4.Cu")
		(net "UPI_CPU0_CPU1_P1P0_DP<4>")
	)
	(segment
		(start 93.126814 -215.112346)
		(end 93.12656 -215.1126)
		(width 0.0889)
		(layer "In4.Cu")
		(net "UPI_CPU0_CPU1_P1P0_DP<4>")
	)
	(segment
		(start 375.613676 -181.902862)
		(end 374.269 -180.309012)
		(width 0.14732)
		(layer "In4.Cu")
		(net "UPI_CPU0_CPU1_P1P0_DP<4>")
	)
	(segment
		(start 93.491304 -209.682588)
		(end 93.33992 -210.092544)
		(width 0.14732)
		(layer "In4.Cu")
		(net "UPI_CPU0_CPU1_P1P0_DP<4>")
	)
	(segment
		(start 371.558312 -177.544222)
		(end 368.98961 -177.062384)
		(width 0.14732)
		(layer "In4.Cu")
		(net "UPI_CPU0_CPU1_P1P0_DP<4>")
	)
	(segment
		(start 376.258582 -185.348372)
		(end 376.100594 -185.21807)
		(width 0.14732)
		(layer "In4.Cu")
		(net "UPI_CPU0_CPU1_P1P0_DP<4>")
	)
	(segment
		(start 92.98178 -211.89315)
		(end 92.98178 -211.915248)
		(width 0.0889)
		(layer "In4.Cu")
		(net "UPI_CPU0_CPU1_P1P0_DP<4>")
	)
	(segment
		(start 375.94413 -183.583072)
		(end 376.074432 -183.425338)
		(width 0.14732)
		(layer "In4.Cu")
		(net "UPI_CPU0_CPU1_P1P0_DP<4>")
	)
	(segment
		(start 93.123258 -215.75903)
		(end 93.12529 -215.7603)
		(width 0.0889)
		(layer "In4.Cu")
		(net "UPI_CPU0_CPU1_P1P0_DP<4>")
	)
	(segment
		(start 161.15157 -142.317978)
		(end 124.980446 -164.574474)
		(width 0.14732)
		(layer "In4.Cu")
		(net "UPI_CPU0_CPU1_P1P0_DP<4>")
	)
	(segment
		(start 94.19336 -207.428846)
		(end 94.265496 -207.58531)
		(width 0.14732)
		(layer "In4.Cu")
		(net "UPI_CPU0_CPU1_P1P0_DP<4>")
	)
	(segment
		(start 373.401844 -179.505356)
		(end 373.1641 -179.22367)
		(width 0.14732)
		(layer "In4.Cu")
		(net "UPI_CPU0_CPU1_P1P0_DP<4>")
	)
	(segment
		(start 378.182378 -213.15934)
		(end 378.182378 -212.98408)
		(width 0.0889)
		(layer "In4.Cu")
		(net "UPI_CPU0_CPU1_P1P0_DP<4>")
	)
	(segment
		(start 330.294234 -144.563338)
		(end 318.329818 -141.633448)
		(width 0.14732)
		(layer "In4.Cu")
		(net "UPI_CPU0_CPU1_P1P0_DP<4>")
	)
	(segment
		(start 378.239528 -211.84743)
		(end 378.239528 -211.686394)
		(width 0.14732)
		(layer "In4.Cu")
		(net "UPI_CPU0_CPU1_P1P0_DP<4>")
	)
	(segment
		(start 378.239274 -211.68614)
		(end 378.239274 -206.08671)
		(width 0.14732)
		(layer "In4.Cu")
		(net "UPI_CPU0_CPU1_P1P0_DP<4>")
	)
	(segment
		(start 92.981526 -211.590128)
		(end 92.98178 -211.590382)
		(width 0.14732)
		(layer "In4.Cu")
		(net "UPI_CPU0_CPU1_P1P0_DP<4>")
	)
	(segment
		(start 104.521254 -183.83123)
		(end 101.512624 -187.603892)
		(width 0.14732)
		(layer "In4.Cu")
		(net "UPI_CPU0_CPU1_P1P0_DP<4>")
	)
	(segment
		(start 373.1641 -179.22367)
		(end 373.181372 -179.019708)
		(width 0.14732)
		(layer "In4.Cu")
		(net "UPI_CPU0_CPU1_P1P0_DP<4>")
	)
	(segment
		(start 93.409008 -214.424768)
		(end 93.409008 -214.644732)
		(width 0.0889)
		(layer "In4.Cu")
		(net "UPI_CPU0_CPU1_P1P0_DP<4>")
	)
	(segment
		(start 92.98178 -211.590382)
		(end 92.98178 -211.89315)
		(width 0.14732)
		(layer "In4.Cu")
		(net "UPI_CPU0_CPU1_P1P0_DP<4>")
	)
	(segment
		(start 378.751084 -214.622634)
		(end 378.751084 -214.461852)
		(width 0.0889)
		(layer "In4.Cu")
		(net "UPI_CPU0_CPU1_P1P0_DP<4>")
	)
	(segment
		(start 378.094494 -215.760554)
		(end 378.102368 -215.755982)
		(width 0.0889)
		(layer "In4.Cu")
		(net "UPI_CPU0_CPU1_P1P0_DP<4>")
	)
	(segment
		(start 372.143528 -177.789332)
		(end 371.558312 -177.544222)
		(width 0.14732)
		(layer "In4.Cu")
		(net "UPI_CPU0_CPU1_P1P0_DP<4>")
	)
	(segment
		(start 378.102368 -216.745058)
		(end 378.094494 -216.740486)
		(width 0.0889)
		(layer "In4.Cu")
		(net "UPI_CPU0_CPU1_P1P0_DP<4>")
	)
	(segment
		(start 375.979182 -183.950102)
		(end 375.94413 -183.583072)
		(width 0.14732)
		(layer "In4.Cu")
		(net "UPI_CPU0_CPU1_P1P0_DP<4>")
	)
	(segment
		(start 273.148552 -139.874498)
		(end 238.593376 -140.495528)
		(width 0.14732)
		(layer "In4.Cu")
		(net "UPI_CPU0_CPU1_P1P0_DP<4>")
	)
	(segment
		(start 94.114366 -207.99552)
		(end 93.957394 -208.067656)
		(width 0.14732)
		(layer "In4.Cu")
		(net "UPI_CPU0_CPU1_P1P0_DP<4>")
	)
	(segment
		(start 93.181678 -218.33205)
		(end 93.157548 -218.421204)
		(width 0.0889)
		(layer "In4.Cu")
		(net "UPI_CPU0_CPU1_P1P0_DP<4>")
	)
	(segment
		(start 93.123766 -216.74201)
		(end 93.118178 -216.745058)
		(width 0.0889)
		(layer "In4.Cu")
		(net "UPI_CPU0_CPU1_P1P0_DP<4>")
	)
	(segment
		(start 93.119956 -215.757252)
		(end 93.123258 -215.75903)
		(width 0.0889)
		(layer "In4.Cu")
		(net "UPI_CPU0_CPU1_P1P0_DP<4>")
	)
	(segment
		(start 368.98961 -177.062384)
		(end 366.36071 -174.769272)
		(width 0.14732)
		(layer "In4.Cu")
		(net "UPI_CPU0_CPU1_P1P0_DP<4>")
	)
	(segment
		(start 378.281438 -212.88502)
		(end 378.281438 -212.6615)
		(width 0.0889)
		(layer "In4.Cu")
		(net "UPI_CPU0_CPU1_P1P0_DP<4>")
	)
	(segment
		(start 93.128338 -215.762078)
		(end 93.13291 -215.764618)
		(width 0.0889)
		(layer "In4.Cu")
		(net "UPI_CPU0_CPU1_P1P0_DP<4>")
	)
	(segment
		(start 93.33992 -210.092544)
		(end 93.182948 -210.16468)
		(width 0.14732)
		(layer "In4.Cu")
		(net "UPI_CPU0_CPU1_P1P0_DP<4>")
	)
	(segment
		(start 366.36071 -174.769272)
		(end 362.687108 -167.206676)
		(width 0.14732)
		(layer "In4.Cu")
		(net "UPI_CPU0_CPU1_P1P0_DP<4>")
	)
	(segment
		(start 93.126814 -215.761062)
		(end 93.128338 -215.762078)
		(width 0.0889)
		(layer "In4.Cu")
		(net "UPI_CPU0_CPU1_P1P0_DP<4>")
	)
	(segment
		(start 377.90628 -217.064336)
		(end 378.062744 -217.335354)
		(width 0.0889)
		(layer "In4.Cu")
		(net "UPI_CPU0_CPU1_P1P0_DP<4>")
	)
	(segment
		(start 93.123512 -214.093806)
		(end 93.123766 -214.093298)
		(width 0.0889)
		(layer "In4.Cu")
		(net "UPI_CPU0_CPU1_P1P0_DP<4>")
	)
	(segment
		(start 359.232454 -163.145724)
		(end 330.294234 -144.563338)
		(width 0.14732)
		(layer "In4.Cu")
		(net "UPI_CPU0_CPU1_P1P0_DP<4>")
	)
	(segment
		(start 93.72727 -209.044032)
		(end 93.570298 -209.116168)
		(width 0.14732)
		(layer "In4.Cu")
		(net "UPI_CPU0_CPU1_P1P0_DP<4>")
	)
	(segment
		(start 92.98178 -211.915248)
		(end 92.939616 -211.957412)
		(width 0.0889)
		(layer "In4.Cu")
		(net "UPI_CPU0_CPU1_P1P0_DP<4>")
	)
	(segment
		(start 92.981526 -210.71078)
		(end 92.981526 -211.590128)
		(width 0.14732)
		(layer "In4.Cu")
		(net "UPI_CPU0_CPU1_P1P0_DP<4>")
	)
	(segment
		(start 93.117924 -215.755982)
		(end 93.119956 -215.757252)
		(width 0.0889)
		(layer "In4.Cu")
		(net "UPI_CPU0_CPU1_P1P0_DP<4>")
	)
	(segment
		(start 373.181372 -179.019708)
		(end 372.944136 -178.738276)
		(width 0.14732)
		(layer "In4.Cu")
		(net "UPI_CPU0_CPU1_P1P0_DP<4>")
	)
	(segment
		(start 378.182378 -212.38718)
		(end 378.281438 -212.28812)
		(width 0.0889)
		(layer "In4.Cu")
		(net "UPI_CPU0_CPU1_P1P0_DP<4>")
	)
	(segment
		(start 93.127068 -216.739978)
		(end 93.126306 -216.740486)
		(width 0.0889)
		(layer "In4.Cu")
		(net "UPI_CPU0_CPU1_P1P0_DP<4>")
	)
	(segment
		(start 373.605806 -179.522882)
		(end 373.401844 -179.505356)
		(width 0.14732)
		(layer "In4.Cu")
		(net "UPI_CPU0_CPU1_P1P0_DP<4>")
	)
	(segment
		(start 374.269 -180.309012)
		(end 374.065038 -180.29174)
		(width 0.14732)
		(layer "In4.Cu")
		(net "UPI_CPU0_CPU1_P1P0_DP<4>")
	)
	(segment
		(start 93.419168 -209.52587)
		(end 93.491304 -209.682588)
		(width 0.14732)
		(layer "In4.Cu")
		(net "UPI_CPU0_CPU1_P1P0_DP<4>")
	)
	(segment
		(start 238.593376 -140.495528)
		(end 238.584232 -140.495528)
		(width 0.14732)
		(layer "In4.Cu")
		(net "UPI_CPU0_CPU1_P1P0_DP<4>")
	)
	(segment
		(start 374.065038 -180.29174)
		(end 373.827294 -180.010054)
		(width 0.14732)
		(layer "In4.Cu")
		(net "UPI_CPU0_CPU1_P1P0_DP<4>")
	)
	(segment
		(start 94.265496 -207.58531)
		(end 94.114366 -207.99552)
		(width 0.14732)
		(layer "In4.Cu")
		(net "UPI_CPU0_CPU1_P1P0_DP<4>")
	)
	(segment
		(start 378.093478 -215.761062)
		(end 378.094494 -215.760554)
		(width 0.0889)
		(layer "In4.Cu")
		(net "UPI_CPU0_CPU1_P1P0_DP<4>")
	)
	(segment
		(start 378.094494 -216.740486)
		(end 378.093478 -216.739978)
		(width 0.0889)
		(layer "In4.Cu")
		(net "UPI_CPU0_CPU1_P1P0_DP<4>")
	)
	(segment
		(start 378.062744 -217.335354)
		(end 378.140976 -217.356182)
		(width 0.0889)
		(layer "In4.Cu")
		(net "UPI_CPU0_CPU1_P1P0_DP<4>")
	)
	(segment
		(start 375.978674 -182.420514)
		(end 375.613676 -181.902862)
		(width 0.14732)
		(layer "In4.Cu")
		(net "UPI_CPU0_CPU1_P1P0_DP<4>")
	)
	(segment
		(start 238.584232 -140.495528)
		(end 169.657268 -139.380976)
		(width 0.14732)
		(layer "In4.Cu")
		(net "UPI_CPU0_CPU1_P1P0_DP<4>")
	)
	(segment
		(start 93.8784 -208.633822)
		(end 93.72727 -209.044032)
		(width 0.14732)
		(layer "In4.Cu")
		(net "UPI_CPU0_CPU1_P1P0_DP<4>")
	)
	(segment
		(start 378.239274 -206.08671)
		(end 378.238766 -206.086202)
		(width 0.14732)
		(layer "In4.Cu")
		(net "UPI_CPU0_CPU1_P1P0_DP<4>")
	)
	(segment
		(start 93.157548 -218.421204)
		(end 93.314012 -218.692222)
		(width 0.0889)
		(layer "In4.Cu")
		(net "UPI_CPU0_CPU1_P1P0_DP<4>")
	)
	(segment
		(start 93.118178 -217.383614)
		(end 93.126306 -217.388186)
		(width 0.0889)
		(layer "In4.Cu")
		(net "UPI_CPU0_CPU1_P1P0_DP<4>")
	)
	(segment
		(start 372.50243 -178.439318)
		(end 372.519702 -178.235356)
		(width 0.14732)
		(layer "In4.Cu")
		(net "UPI_CPU0_CPU1_P1P0_DP<4>")
	)
	(segment
		(start 93.957394 -208.067656)
		(end 93.806264 -208.477358)
		(width 0.14732)
		(layer "In4.Cu")
		(net "UPI_CPU0_CPU1_P1P0_DP<4>")
	)
	(segment
		(start 373.827294 -180.010054)
		(end 373.844566 -179.805838)
		(width 0.14732)
		(layer "In4.Cu")
		(net "UPI_CPU0_CPU1_P1P0_DP<4>")
	)
	(segment
		(start 378.281184 -213.93023)
		(end 378.281184 -213.258146)
		(width 0.0889)
		(layer "In4.Cu")
		(net "UPI_CPU0_CPU1_P1P0_DP<4>")
	)
	(segment
		(start 315.368432 -141.633448)
		(end 273.148552 -139.874498)
		(width 0.14732)
		(layer "In4.Cu")
		(net "UPI_CPU0_CPU1_P1P0_DP<4>")
	)
	(segment
		(start 376.258074 -185.348372)
		(end 376.258582 -185.348372)
		(width 0.14732)
		(layer "In4.Cu")
		(net "UPI_CPU0_CPU1_P1P0_DP<4>")
	)
	(segment
		(start 378.281438 -211.911438)
		(end 378.239528 -211.869528)
		(width 0.0889)
		(layer "In4.Cu")
		(net "UPI_CPU0_CPU1_P1P0_DP<4>")
	)
	(segment
		(start 93.570298 -209.116168)
		(end 93.419168 -209.52587)
		(width 0.14732)
		(layer "In4.Cu")
		(net "UPI_CPU0_CPU1_P1P0_DP<4>")
	)
	(segment
		(start 372.740174 -178.721004)
		(end 372.50243 -178.439318)
		(width 0.14732)
		(layer "In4.Cu")
		(net "UPI_CPU0_CPU1_P1P0_DP<4>")
	)
	(segment
		(start 169.657268 -139.380976)
		(end 161.15157 -142.317978)
		(width 0.14732)
		(layer "In4.Cu")
		(net "UPI_CPU0_CPU1_P1P0_DP<4>")
	)
	(segment
		(start 93.182948 -210.16468)
		(end 93.183456 -210.16468)
		(width 0.14732)
		(layer "In4.Cu")
		(net "UPI_CPU0_CPU1_P1P0_DP<4>")
	)
	(segment
		(start 93.183202 -210.164934)
		(end 92.981526 -210.71078)
		(width 0.14732)
		(layer "In4.Cu")
		(net "UPI_CPU0_CPU1_P1P0_DP<4>")
	)
	(segment
		(start 376.100594 -185.21807)
		(end 376.065542 -184.85104)
		(width 0.14732)
		(layer "In4.Cu")
		(net "UPI_CPU0_CPU1_P1P0_DP<4>")
	)
	(segment
		(start 93.409516 -216.25052)
		(end 93.409516 -216.260426)
		(width 0.0889)
		(layer "In4.Cu")
		(net "UPI_CPU0_CPU1_P1P0_DP<4>")
	)
	(segment
		(start 376.195844 -184.693306)
		(end 376.195336 -184.693306)
		(width 0.14732)
		(layer "In4.Cu")
		(net "UPI_CPU0_CPU1_P1P0_DP<4>")
	)
	(segment
		(start 376.137424 -184.080404)
		(end 375.979182 -183.950102)
		(width 0.14732)
		(layer "In4.Cu")
		(net "UPI_CPU0_CPU1_P1P0_DP<4>")
	)
	(segment
		(start 378.563632 -214.946992)
		(end 378.572522 -214.941912)
		(width 0.0889)
		(layer "In4.Cu")
		(net "UPI_CPU0_CPU1_P1P0_DP<4>")
	)
	(segment
		(start 93.126306 -216.740486)
		(end 93.123766 -216.74201)
		(width 0.0889)
		(layer "In4.Cu")
		(net "UPI_CPU0_CPU1_P1P0_DP<4>")
	)
	(segment
		(start 92.939616 -211.957412)
		(end 92.939616 -213.789006)
		(width 0.0889)
		(layer "In4.Cu")
		(net "UPI_CPU0_CPU1_P1P0_DP<4>")
	)
	(segment
		(start 378.239528 -211.686394)
		(end 378.239274 -211.68614)
		(width 0.14732)
		(layer "In4.Cu")
		(net "UPI_CPU0_CPU1_P1P0_DP<4>")
	)
	(segment
		(start 377.811284 -216.266014)
		(end 377.811284 -216.235026)
		(width 0.0889)
		(layer "In4.Cu")
		(net "UPI_CPU0_CPU1_P1P0_DP<4>")
	)
	(segment
		(start 378.281184 -213.258146)
		(end 378.182378 -213.15934)
		(width 0.0889)
		(layer "In4.Cu")
		(net "UPI_CPU0_CPU1_P1P0_DP<4>")
	)
	(segment
		(start 376.136916 -184.080404)
		(end 376.137424 -184.080404)
		(width 0.14732)
		(layer "In4.Cu")
		(net "UPI_CPU0_CPU1_P1P0_DP<4>")
	)
	(arc
		(start 92.939616 -215.421972)
		(mid 92.939419 -215.429337)
		(end 92.939362 -215.436704)
		(width 0.0889)
		(layer "In4.Cu")
		(net "UPI_CPU0_CPU1_P1P0_DP<4>")
	)
	(arc
		(start 377.811284 -216.235026)
		(mid 377.890654 -215.961292)
		(end 378.093478 -215.761062)
		(width 0.0889)
		(layer "In4.Cu")
		(net "UPI_CPU0_CPU1_P1P0_DP<4>")
	)
	(arc
		(start 378.140976 -217.356182)
		(mid 378.244121 -217.226157)
		(end 378.28093 -217.064336)
		(width 0.0889)
		(layer "In4.Cu")
		(net "UPI_CPU0_CPU1_P1P0_DP<4>")
	)
	(arc
		(start 93.123766 -214.093298)
		(mid 93.297729 -214.232062)
		(end 93.409008 -214.424768)
		(width 0.0889)
		(layer "In4.Cu")
		(net "UPI_CPU0_CPU1_P1P0_DP<4>")
	)
	(arc
		(start 378.28093 -215.436704)
		(mid 378.353103 -215.160036)
		(end 378.55144 -214.954104)
		(width 0.0889)
		(layer "In4.Cu")
		(net "UPI_CPU0_CPU1_P1P0_DP<4>")
	)
	(arc
		(start 378.28093 -217.064336)
		(mid 378.233251 -216.881436)
		(end 378.102368 -216.745058)
		(width 0.0889)
		(layer "In4.Cu")
		(net "UPI_CPU0_CPU1_P1P0_DP<4>")
	)
	(arc
		(start 93.198696 -218.318842)
		(mid 93.19025 -218.325527)
		(end 93.181678 -218.33205)
		(width 0.0889)
		(layer "In4.Cu")
		(net "UPI_CPU0_CPU1_P1P0_DP<4>")
	)
	(arc
		(start 378.751084 -214.461852)
		(mid 378.676013 -214.34611)
		(end 378.56668 -214.261954)
		(width 0.0889)
		(layer "In4.Cu")
		(net "UPI_CPU0_CPU1_P1P0_DP<4>")
	)
	(arc
		(start 93.127068 -217.388694)
		(mid 93.329354 -217.587675)
		(end 93.409516 -217.859864)
		(width 0.0889)
		(layer "In4.Cu")
		(net "UPI_CPU0_CPU1_P1P0_DP<4>")
	)
	(arc
		(start 378.102368 -215.755982)
		(mid 378.233282 -215.619622)
		(end 378.28093 -215.436704)
		(width 0.0889)
		(layer "In4.Cu")
		(net "UPI_CPU0_CPU1_P1P0_DP<4>")
	)
	(arc
		(start 378.093478 -216.739978)
		(mid 377.890655 -216.539747)
		(end 377.811284 -216.266014)
		(width 0.0889)
		(layer "In4.Cu")
		(net "UPI_CPU0_CPU1_P1P0_DP<4>")
	)
	(arc
		(start 93.117924 -215.117426)
		(mid 92.99067 -215.247392)
		(end 92.939616 -215.421972)
		(width 0.0889)
		(layer "In4.Cu")
		(net "UPI_CPU0_CPU1_P1P0_DP<4>")
	)
	(arc
		(start 93.409516 -216.260426)
		(mid 93.331405 -216.537375)
		(end 93.127068 -216.739978)
		(width 0.0889)
		(layer "In4.Cu")
		(net "UPI_CPU0_CPU1_P1P0_DP<4>")
	)
	(arc
		(start 92.939362 -215.436704)
		(mid 92.987041 -215.619604)
		(end 93.117924 -215.755982)
		(width 0.0889)
		(layer "In4.Cu")
		(net "UPI_CPU0_CPU1_P1P0_DP<4>")
	)
	(arc
		(start 378.29617 -213.968838)
		(mid 378.288348 -213.949662)
		(end 378.281184 -213.93023)
		(width 0.0889)
		(layer "In4.Cu")
		(net "UPI_CPU0_CPU1_P1P0_DP<4>")
	)
	(arc
		(start 378.572522 -214.941912)
		(mid 378.703436 -214.805552)
		(end 378.751084 -214.622634)
		(width 0.0889)
		(layer "In4.Cu")
		(net "UPI_CPU0_CPU1_P1P0_DP<4>")
	)
	(arc
		(start 92.93987 -213.788752)
		(mid 92.98927 -213.966809)
		(end 93.123512 -214.093806)
		(width 0.0889)
		(layer "In4.Cu")
		(net "UPI_CPU0_CPU1_P1P0_DP<4>")
	)
	(arc
		(start 378.56668 -214.261954)
		(mid 378.406325 -214.138568)
		(end 378.29617 -213.968838)
		(width 0.0889)
		(layer "In4.Cu")
		(net "UPI_CPU0_CPU1_P1P0_DP<4>")
	)
	(arc
		(start 93.409008 -214.644732)
		(mid 93.328097 -214.91486)
		(end 93.126814 -215.112346)
		(width 0.0889)
		(layer "In4.Cu")
		(net "UPI_CPU0_CPU1_P1P0_DP<4>")
	)
	(arc
		(start 93.13291 -215.764618)
		(mid 93.335497 -215.970969)
		(end 93.409516 -216.25052)
		(width 0.0889)
		(layer "In4.Cu")
		(net "UPI_CPU0_CPU1_P1P0_DP<4>")
	)
	(arc
		(start 93.118178 -216.745058)
		(mid 92.939581 -217.064336)
		(end 93.118178 -217.383614)
		(width 0.0889)
		(layer "In4.Cu")
		(net "UPI_CPU0_CPU1_P1P0_DP<4>")
	)
	(arc
		(start 93.409516 -217.878406)
		(mid 93.354161 -218.122593)
		(end 93.198696 -218.318842)
		(width 0.0889)
		(layer "In4.Cu")
		(net "UPI_CPU0_CPU1_P1P0_DP<4>")
	)
	(segment
		(start 379.31598 -217.87866)
		(end 379.316234 -217.878406)
		(width 0.13208)
		(layer "F.Cu")
		(net "UPI_CPU0_CPU1_P1P0_DP<3>")
	)
	(segment
		(start 91.904312 -218.414346)
		(end 91.904312 -217.87866)
		(width 0.13208)
		(layer "F.Cu")
		(net "UPI_CPU0_CPU1_P1P0_DP<3>")
	)
	(segment
		(start 91.904312 -217.87866)
		(end 91.904566 -217.878406)
		(width 0.13208)
		(layer "F.Cu")
		(net "UPI_CPU0_CPU1_P1P0_DP<3>")
	)
	(segment
		(start 379.31598 -218.414346)
		(end 379.31598 -217.87866)
		(width 0.13208)
		(layer "F.Cu")
		(net "UPI_CPU0_CPU1_P1P0_DP<3>")
	)
	(segment
		(start 376.826272 -181.14137)
		(end 376.26671 -178.68265)
		(width 0.14732)
		(layer "In4.Cu")
		(net "UPI_CPU0_CPU1_P1P0_DP<3>")
	)
	(segment
		(start 91.767406 -211.78139)
		(end 91.767406 -211.803488)
		(width 0.0889)
		(layer "In4.Cu")
		(net "UPI_CPU0_CPU1_P1P0_DP<3>")
	)
	(segment
		(start 124.270008 -163.708842)
		(end 103.710232 -183.060594)
		(width 0.14732)
		(layer "In4.Cu")
		(net "UPI_CPU0_CPU1_P1P0_DP<3>")
	)
	(segment
		(start 379.316234 -217.878406)
		(end 379.15977 -218.149424)
		(width 0.0889)
		(layer "In4.Cu")
		(net "UPI_CPU0_CPU1_P1P0_DP<3>")
	)
	(segment
		(start 92.100146 -214.941912)
		(end 92.091256 -214.946992)
		(width 0.0889)
		(layer "In4.Cu")
		(net "UPI_CPU0_CPU1_P1P0_DP<3>")
	)
	(segment
		(start 379.411484 -215.436704)
		(end 379.411484 -215.428068)
		(width 0.0889)
		(layer "In4.Cu")
		(net "UPI_CPU0_CPU1_P1P0_DP<3>")
	)
	(segment
		(start 92.085668 -215.922606)
		(end 92.08897 -215.924384)
		(width 0.0889)
		(layer "In4.Cu")
		(net "UPI_CPU0_CPU1_P1P0_DP<3>")
	)
	(segment
		(start 359.979722 -162.315144)
		(end 330.735178 -143.535908)
		(width 0.14732)
		(layer "In4.Cu")
		(net "UPI_CPU0_CPU1_P1P0_DP<3>")
	)
	(segment
		(start 92.278708 -214.461344)
		(end 92.278708 -214.622634)
		(width 0.0889)
		(layer "In4.Cu")
		(net "UPI_CPU0_CPU1_P1P0_DP<3>")
	)
	(segment
		(start 103.710232 -183.060594)
		(end 100.279454 -187.362084)
		(width 0.14732)
		(layer "In4.Cu")
		(net "UPI_CPU0_CPU1_P1P0_DP<3>")
	)
	(segment
		(start 379.453648 -211.572602)
		(end 379.453394 -211.572348)
		(width 0.14732)
		(layer "In4.Cu")
		(net "UPI_CPU0_CPU1_P1P0_DP<3>")
	)
	(segment
		(start 374.307862 -176.552606)
		(end 374.307862 -176.55286)
		(width 0.14732)
		(layer "In4.Cu")
		(net "UPI_CPU0_CPU1_P1P0_DP<3>")
	)
	(segment
		(start 92.091002 -215.925654)
		(end 92.092526 -215.92667)
		(width 0.0889)
		(layer "In4.Cu")
		(net "UPI_CPU0_CPU1_P1P0_DP<3>")
	)
	(segment
		(start 379.411484 -213.31682)
		(end 379.510544 -213.21776)
		(width 0.0889)
		(layer "In4.Cu")
		(net "UPI_CPU0_CPU1_P1P0_DP<3>")
	)
	(segment
		(start 379.120146 -217.559128)
		(end 379.129036 -217.554048)
		(width 0.0889)
		(layer "In4.Cu")
		(net "UPI_CPU0_CPU1_P1P0_DP<3>")
	)
	(segment
		(start 238.585756 -139.280646)
		(end 169.737786 -138.167618)
		(width 0.14732)
		(layer "In4.Cu")
		(net "UPI_CPU0_CPU1_P1P0_DP<3>")
	)
	(segment
		(start 330.735178 -143.535908)
		(end 318.463422 -140.531088)
		(width 0.14732)
		(layer "In4.Cu")
		(net "UPI_CPU0_CPU1_P1P0_DP<3>")
	)
	(segment
		(start 379.411484 -211.911692)
		(end 379.453648 -211.869528)
		(width 0.0889)
		(layer "In4.Cu")
		(net "UPI_CPU0_CPU1_P1P0_DP<3>")
	)
	(segment
		(start 379.453648 -211.84743)
		(end 379.453648 -211.572602)
		(width 0.14732)
		(layer "In4.Cu")
		(net "UPI_CPU0_CPU1_P1P0_DP<3>")
	)
	(segment
		(start 379.129036 -216.574878)
		(end 379.120146 -216.569798)
		(width 0.0889)
		(layer "In4.Cu")
		(net "UPI_CPU0_CPU1_P1P0_DP<3>")
	)
	(segment
		(start 315.524134 -140.531088)
		(end 271.375886 -138.691112)
		(width 0.14732)
		(layer "In4.Cu")
		(net "UPI_CPU0_CPU1_P1P0_DP<3>")
	)
	(segment
		(start 91.767152 -211.630768)
		(end 91.767406 -211.631022)
		(width 0.14732)
		(layer "In4.Cu")
		(net "UPI_CPU0_CPU1_P1P0_DP<3>")
	)
	(segment
		(start 379.510544 -213.0425)
		(end 379.411484 -212.94344)
		(width 0.0889)
		(layer "In4.Cu")
		(net "UPI_CPU0_CPU1_P1P0_DP<3>")
	)
	(segment
		(start 318.463422 -140.531088)
		(end 315.524134 -140.531088)
		(width 0.14732)
		(layer "In4.Cu")
		(net "UPI_CPU0_CPU1_P1P0_DP<3>")
	)
	(segment
		(start 92.099384 -215.93048)
		(end 92.100654 -215.931242)
		(width 0.0889)
		(layer "In4.Cu")
		(net "UPI_CPU0_CPU1_P1P0_DP<3>")
	)
	(segment
		(start 91.809316 -211.845398)
		(end 91.809316 -213.930484)
		(width 0.0889)
		(layer "In4.Cu")
		(net "UPI_CPU0_CPU1_P1P0_DP<3>")
	)
	(segment
		(start 379.120146 -215.931242)
		(end 379.129036 -215.926162)
		(width 0.0889)
		(layer "In4.Cu")
		(net "UPI_CPU0_CPU1_P1P0_DP<3>")
	)
	(segment
		(start 379.510544 -212.49386)
		(end 379.411484 -212.3948)
		(width 0.0889)
		(layer "In4.Cu")
		(net "UPI_CPU0_CPU1_P1P0_DP<3>")
	)
	(segment
		(start 379.411484 -217.082878)
		(end 379.411484 -217.05443)
		(width 0.0889)
		(layer "In4.Cu")
		(net "UPI_CPU0_CPU1_P1P0_DP<3>")
	)
	(segment
		(start 379.510544 -212.66912)
		(end 379.510544 -212.49386)
		(width 0.0889)
		(layer "In4.Cu")
		(net "UPI_CPU0_CPU1_P1P0_DP<3>")
	)
	(segment
		(start 92.08897 -215.924384)
		(end 92.091002 -215.925654)
		(width 0.0889)
		(layer "In4.Cu")
		(net "UPI_CPU0_CPU1_P1P0_DP<3>")
	)
	(segment
		(start 169.737786 -138.167618)
		(end 160.719262 -141.28115)
		(width 0.14732)
		(layer "In4.Cu")
		(net "UPI_CPU0_CPU1_P1P0_DP<3>")
	)
	(segment
		(start 379.411484 -212.3948)
		(end 379.411484 -211.911692)
		(width 0.0889)
		(layer "In4.Cu")
		(net "UPI_CPU0_CPU1_P1P0_DP<3>")
	)
	(segment
		(start 92.100654 -216.569798)
		(end 92.093288 -216.574116)
		(width 0.0889)
		(layer "In4.Cu")
		(net "UPI_CPU0_CPU1_P1P0_DP<3>")
	)
	(segment
		(start 160.719262 -141.28115)
		(end 124.270008 -163.708842)
		(width 0.14732)
		(layer "In4.Cu")
		(net "UPI_CPU0_CPU1_P1P0_DP<3>")
	)
	(segment
		(start 91.767406 -211.803488)
		(end 91.809316 -211.845398)
		(width 0.0889)
		(layer "In4.Cu")
		(net "UPI_CPU0_CPU1_P1P0_DP<3>")
	)
	(segment
		(start 91.767406 -211.631022)
		(end 91.767406 -211.78139)
		(width 0.14732)
		(layer "In4.Cu")
		(net "UPI_CPU0_CPU1_P1P0_DP<3>")
	)
	(segment
		(start 379.881384 -214.636858)
		(end 379.881384 -214.425022)
		(width 0.0889)
		(layer "In4.Cu")
		(net "UPI_CPU0_CPU1_P1P0_DP<3>")
	)
	(segment
		(start 379.15977 -218.149424)
		(end 379.081538 -218.170252)
		(width 0.0889)
		(layer "In4.Cu")
		(net "UPI_CPU0_CPU1_P1P0_DP<3>")
	)
	(segment
		(start 376.26671 -178.68265)
		(end 376.00763 -178.219354)
		(width 0.14732)
		(layer "In4.Cu")
		(net "UPI_CPU0_CPU1_P1P0_DP<3>")
	)
	(segment
		(start 379.411484 -213.8934)
		(end 379.411484 -213.31682)
		(width 0.0889)
		(layer "In4.Cu")
		(net "UPI_CPU0_CPU1_P1P0_DP<3>")
	)
	(segment
		(start 377.085352 -182.279798)
		(end 376.826526 -181.142386)
		(width 0.14732)
		(layer "In4.Cu")
		(net "UPI_CPU0_CPU1_P1P0_DP<3>")
	)
	(segment
		(start 376.826526 -181.142386)
		(end 376.826272 -181.14137)
		(width 0.14732)
		(layer "In4.Cu")
		(net "UPI_CPU0_CPU1_P1P0_DP<3>")
	)
	(segment
		(start 379.453394 -211.572348)
		(end 379.453394 -205.520798)
		(width 0.14732)
		(layer "In4.Cu")
		(net "UPI_CPU0_CPU1_P1P0_DP<3>")
	)
	(segment
		(start 376.00763 -178.219354)
		(end 374.307862 -176.552606)
		(width 0.14732)
		(layer "In4.Cu")
		(net "UPI_CPU0_CPU1_P1P0_DP<3>")
	)
	(segment
		(start 92.06103 -217.607388)
		(end 91.904566 -217.878406)
		(width 0.0889)
		(layer "In4.Cu")
		(net "UPI_CPU0_CPU1_P1P0_DP<3>")
	)
	(segment
		(start 372.211092 -174.496984)
		(end 371.902228 -174.342552)
		(width 0.14732)
		(layer "In4.Cu")
		(net "UPI_CPU0_CPU1_P1P0_DP<3>")
	)
	(segment
		(start 379.41123 -215.455246)
		(end 379.411484 -215.436704)
		(width 0.0889)
		(layer "In4.Cu")
		(net "UPI_CPU0_CPU1_P1P0_DP<3>")
	)
	(segment
		(start 91.767152 -210.421474)
		(end 91.767152 -211.630768)
		(width 0.14732)
		(layer "In4.Cu")
		(net "UPI_CPU0_CPU1_P1P0_DP<3>")
	)
	(segment
		(start 379.453648 -211.869528)
		(end 379.453648 -211.84743)
		(width 0.0889)
		(layer "In4.Cu")
		(net "UPI_CPU0_CPU1_P1P0_DP<3>")
	)
	(segment
		(start 363.887258 -166.90848)
		(end 359.979722 -162.315144)
		(width 0.14732)
		(layer "In4.Cu")
		(net "UPI_CPU0_CPU1_P1P0_DP<3>")
	)
	(segment
		(start 379.411484 -212.94344)
		(end 379.411484 -212.76818)
		(width 0.0889)
		(layer "In4.Cu")
		(net "UPI_CPU0_CPU1_P1P0_DP<3>")
	)
	(segment
		(start 369.352068 -173.952662)
		(end 368.780822 -173.55185)
		(width 0.14732)
		(layer "In4.Cu")
		(net "UPI_CPU0_CPU1_P1P0_DP<3>")
	)
	(segment
		(start 92.092526 -215.92667)
		(end 92.097352 -215.929464)
		(width 0.0889)
		(layer "In4.Cu")
		(net "UPI_CPU0_CPU1_P1P0_DP<3>")
	)
	(segment
		(start 92.093288 -216.574116)
		(end 92.085668 -216.578434)
		(width 0.0889)
		(layer "In4.Cu")
		(net "UPI_CPU0_CPU1_P1P0_DP<3>")
	)
	(segment
		(start 368.780822 -173.55185)
		(end 363.887258 -166.90848)
		(width 0.14732)
		(layer "In4.Cu")
		(net "UPI_CPU0_CPU1_P1P0_DP<3>")
	)
	(segment
		(start 100.279454 -187.362084)
		(end 91.767152 -210.421474)
		(width 0.14732)
		(layer "In4.Cu")
		(net "UPI_CPU0_CPU1_P1P0_DP<3>")
	)
	(segment
		(start 254.978916 -138.986006)
		(end 238.590074 -139.280646)
		(width 0.14732)
		(layer "In4.Cu")
		(net "UPI_CPU0_CPU1_P1P0_DP<3>")
	)
	(segment
		(start 91.809062 -217.064336)
		(end 91.809062 -217.07856)
		(width 0.0889)
		(layer "In4.Cu")
		(net "UPI_CPU0_CPU1_P1P0_DP<3>")
	)
	(segment
		(start 271.375886 -138.691112)
		(end 254.978916 -138.986006)
		(width 0.14732)
		(layer "In4.Cu")
		(net "UPI_CPU0_CPU1_P1P0_DP<3>")
	)
	(segment
		(start 374.307862 -176.55286)
		(end 372.211092 -174.496984)
		(width 0.14732)
		(layer "In4.Cu")
		(net "UPI_CPU0_CPU1_P1P0_DP<3>")
	)
	(segment
		(start 371.902228 -174.342552)
		(end 369.352068 -173.952662)
		(width 0.14732)
		(layer "In4.Cu")
		(net "UPI_CPU0_CPU1_P1P0_DP<3>")
	)
	(segment
		(start 92.097352 -215.929464)
		(end 92.099384 -215.93048)
		(width 0.0889)
		(layer "In4.Cu")
		(net "UPI_CPU0_CPU1_P1P0_DP<3>")
	)
	(segment
		(start 92.0369 -217.518234)
		(end 92.06103 -217.607388)
		(width 0.0889)
		(layer "In4.Cu")
		(net "UPI_CPU0_CPU1_P1P0_DP<3>")
	)
	(segment
		(start 379.411484 -212.76818)
		(end 379.510544 -212.66912)
		(width 0.0889)
		(layer "In4.Cu")
		(net "UPI_CPU0_CPU1_P1P0_DP<3>")
	)
	(segment
		(start 379.453394 -205.520798)
		(end 377.085352 -182.279798)
		(width 0.14732)
		(layer "In4.Cu")
		(net "UPI_CPU0_CPU1_P1P0_DP<3>")
	)
	(segment
		(start 379.510544 -213.21776)
		(end 379.510544 -213.0425)
		(width 0.0889)
		(layer "In4.Cu")
		(net "UPI_CPU0_CPU1_P1P0_DP<3>")
	)
	(segment
		(start 238.590074 -139.280646)
		(end 238.585756 -139.280646)
		(width 0.14732)
		(layer "In4.Cu")
		(net "UPI_CPU0_CPU1_P1P0_DP<3>")
	)
	(arc
		(start 379.120146 -216.569798)
		(mid 378.990857 -216.436312)
		(end 378.941584 -216.257124)
		(width 0.0889)
		(layer "In4.Cu")
		(net "UPI_CPU0_CPU1_P1P0_DP<3>")
	)
	(arc
		(start 379.129036 -217.554048)
		(mid 379.331322 -217.355067)
		(end 379.411484 -217.082878)
		(width 0.0889)
		(layer "In4.Cu")
		(net "UPI_CPU0_CPU1_P1P0_DP<3>")
	)
	(arc
		(start 379.411484 -217.05443)
		(mid 379.333373 -216.777481)
		(end 379.129036 -216.574878)
		(width 0.0889)
		(layer "In4.Cu")
		(net "UPI_CPU0_CPU1_P1P0_DP<3>")
	)
	(arc
		(start 379.081538 -218.170252)
		(mid 378.978393 -218.040227)
		(end 378.941584 -217.878406)
		(width 0.0889)
		(layer "In4.Cu")
		(net "UPI_CPU0_CPU1_P1P0_DP<3>")
	)
	(arc
		(start 92.019882 -217.50528)
		(mid 92.02833 -217.511837)
		(end 92.0369 -217.518234)
		(width 0.0889)
		(layer "In4.Cu")
		(net "UPI_CPU0_CPU1_P1P0_DP<3>")
	)
	(arc
		(start 92.091256 -214.946992)
		(mid 91.808733 -215.433205)
		(end 92.085668 -215.922606)
		(width 0.0889)
		(layer "In4.Cu")
		(net "UPI_CPU0_CPU1_P1P0_DP<3>")
	)
	(arc
		(start 92.100654 -215.931242)
		(mid 92.279251 -216.25052)
		(end 92.100654 -216.569798)
		(width 0.0889)
		(layer "In4.Cu")
		(net "UPI_CPU0_CPU1_P1P0_DP<3>")
	)
	(arc
		(start 379.129036 -215.926162)
		(mid 379.331078 -215.727239)
		(end 379.41123 -215.455246)
		(width 0.0889)
		(layer "In4.Cu")
		(net "UPI_CPU0_CPU1_P1P0_DP<3>")
	)
	(arc
		(start 92.094558 -214.261954)
		(mid 92.203705 -214.345882)
		(end 92.278708 -214.461344)
		(width 0.0889)
		(layer "In4.Cu")
		(net "UPI_CPU0_CPU1_P1P0_DP<3>")
	)
	(arc
		(start 379.598682 -215.112346)
		(mid 379.802163 -214.911542)
		(end 379.881384 -214.636858)
		(width 0.0889)
		(layer "In4.Cu")
		(net "UPI_CPU0_CPU1_P1P0_DP<3>")
	)
	(arc
		(start 378.941584 -217.878406)
		(mid 378.989263 -217.695506)
		(end 379.120146 -217.559128)
		(width 0.0889)
		(layer "In4.Cu")
		(net "UPI_CPU0_CPU1_P1P0_DP<3>")
	)
	(arc
		(start 379.595888 -214.093298)
		(mid 379.486492 -214.009201)
		(end 379.411484 -213.8934)
		(width 0.0889)
		(layer "In4.Cu")
		(net "UPI_CPU0_CPU1_P1P0_DP<3>")
	)
	(arc
		(start 92.085668 -216.578434)
		(mid 91.883081 -216.784785)
		(end 91.809062 -217.064336)
		(width 0.0889)
		(layer "In4.Cu")
		(net "UPI_CPU0_CPU1_P1P0_DP<3>")
	)
	(arc
		(start 378.941838 -216.238328)
		(mid 378.992331 -216.06235)
		(end 379.120146 -215.931242)
		(width 0.0889)
		(layer "In4.Cu")
		(net "UPI_CPU0_CPU1_P1P0_DP<3>")
	)
	(arc
		(start 378.941584 -216.257124)
		(mid 378.941594 -216.247724)
		(end 378.941838 -216.238328)
		(width 0.0889)
		(layer "In4.Cu")
		(net "UPI_CPU0_CPU1_P1P0_DP<3>")
	)
	(arc
		(start 91.809062 -217.07856)
		(mid 91.867356 -217.315203)
		(end 92.019882 -217.50528)
		(width 0.0889)
		(layer "In4.Cu")
		(net "UPI_CPU0_CPU1_P1P0_DP<3>")
	)
	(arc
		(start 91.824556 -213.969346)
		(mid 91.93455 -214.138715)
		(end 92.094558 -214.261954)
		(width 0.0889)
		(layer "In4.Cu")
		(net "UPI_CPU0_CPU1_P1P0_DP<3>")
	)
	(arc
		(start 92.278708 -214.622634)
		(mid 92.231029 -214.805534)
		(end 92.100146 -214.941912)
		(width 0.0889)
		(layer "In4.Cu")
		(net "UPI_CPU0_CPU1_P1P0_DP<3>")
	)
	(arc
		(start 379.881384 -214.425022)
		(mid 379.770046 -214.232122)
		(end 379.595888 -214.093298)
		(width 0.0889)
		(layer "In4.Cu")
		(net "UPI_CPU0_CPU1_P1P0_DP<3>")
	)
	(arc
		(start 91.809316 -213.930484)
		(mid 91.816601 -213.950046)
		(end 91.824556 -213.969346)
		(width 0.0889)
		(layer "In4.Cu")
		(net "UPI_CPU0_CPU1_P1P0_DP<3>")
	)
	(arc
		(start 379.411484 -215.428068)
		(mid 379.463754 -215.245703)
		(end 379.598682 -215.112346)
		(width 0.0889)
		(layer "In4.Cu")
		(net "UPI_CPU0_CPU1_P1P0_DP<3>")
	)
	(segment
		(start 91.434666 -219.228162)
		(end 91.434666 -218.692476)
		(width 0.13208)
		(layer "F.Cu")
		(net "UPI_CPU0_CPU1_P1P0_DP<2>")
	)
	(segment
		(start 379.786134 -217.600276)
		(end 379.786134 -217.06459)
		(width 0.13208)
		(layer "F.Cu")
		(net "UPI_CPU0_CPU1_P1P0_DP<2>")
	)
	(segment
		(start 91.434666 -218.692476)
		(end 91.434412 -218.692222)
		(width 0.13208)
		(layer "F.Cu")
		(net "UPI_CPU0_CPU1_P1P0_DP<2>")
	)
	(segment
		(start 379.786134 -217.06459)
		(end 379.78588 -217.064336)
		(width 0.13208)
		(layer "F.Cu")
		(net "UPI_CPU0_CPU1_P1P0_DP<2>")
	)
	(segment
		(start 331.003402 -143.031464)
		(end 318.530478 -139.977368)
		(width 0.14732)
		(layer "In4.Cu")
		(net "UPI_CPU0_CPU1_P1P0_DP<2>")
	)
	(segment
		(start 238.6076 -138.698478)
		(end 169.709084 -137.57783)
		(width 0.14732)
		(layer "In4.Cu")
		(net "UPI_CPU0_CPU1_P1P0_DP<2>")
	)
	(segment
		(start 169.709084 -137.57783)
		(end 160.221676 -140.861796)
		(width 0.14732)
		(layer "In4.Cu")
		(net "UPI_CPU0_CPU1_P1P0_DP<2>")
	)
	(segment
		(start 91.277948 -218.421204)
		(end 91.434412 -218.692222)
		(width 0.0889)
		(layer "In4.Cu")
		(net "UPI_CPU0_CPU1_P1P0_DP<2>")
	)
	(segment
		(start 381.100838 -211.967318)
		(end 381.058928 -211.925408)
		(width 0.0889)
		(layer "In4.Cu")
		(net "UPI_CPU0_CPU1_P1P0_DP<2>")
	)
	(segment
		(start 365.724186 -167.588438)
		(end 365.519716 -167.582088)
		(width 0.14732)
		(layer "In4.Cu")
		(net "UPI_CPU0_CPU1_P1P0_DP<2>")
	)
	(segment
		(start 316.01537 -139.977368)
		(end 271.480534 -138.110976)
		(width 0.14732)
		(layer "In4.Cu")
		(net "UPI_CPU0_CPU1_P1P0_DP<2>")
	)
	(segment
		(start 366.550448 -168.468548)
		(end 366.345724 -168.462198)
		(width 0.14732)
		(layer "In4.Cu")
		(net "UPI_CPU0_CPU1_P1P0_DP<2>")
	)
	(segment
		(start 380.06274 -208.005426)
		(end 380.06274 -205.534768)
		(width 0.14732)
		(layer "In4.Cu")
		(net "UPI_CPU0_CPU1_P1P0_DP<2>")
	)
	(segment
		(start 271.480534 -138.110976)
		(end 238.619792 -138.698478)
		(width 0.14732)
		(layer "In4.Cu")
		(net "UPI_CPU0_CPU1_P1P0_DP<2>")
	)
	(segment
		(start 92.133166 -207.816196)
		(end 91.94673 -207.901794)
		(width 0.14732)
		(layer "In4.Cu")
		(net "UPI_CPU0_CPU1_P1P0_DP<2>")
	)
	(segment
		(start 91.24696 -215.1126)
		(end 91.238324 -215.117426)
		(width 0.0889)
		(layer "In4.Cu")
		(net "UPI_CPU0_CPU1_P1P0_DP<2>")
	)
	(segment
		(start 238.619792 -138.698478)
		(end 238.6076 -138.698478)
		(width 0.14732)
		(layer "In4.Cu")
		(net "UPI_CPU0_CPU1_P1P0_DP<2>")
	)
	(segment
		(start 363.845094 -165.797992)
		(end 363.592618 -165.52926)
		(width 0.14732)
		(layer "In4.Cu")
		(net "UPI_CPU0_CPU1_P1P0_DP<2>")
	)
	(segment
		(start 91.529408 -214.424768)
		(end 91.529408 -214.644732)
		(width 0.0889)
		(layer "In4.Cu")
		(net "UPI_CPU0_CPU1_P1P0_DP<2>")
	)
	(segment
		(start 380.43104 -214.954104)
		(end 380.443232 -214.946992)
		(width 0.0889)
		(layer "In4.Cu")
		(net "UPI_CPU0_CPU1_P1P0_DP<2>")
	)
	(segment
		(start 91.247214 -215.112346)
		(end 91.24696 -215.1126)
		(width 0.0889)
		(layer "In4.Cu")
		(net "UPI_CPU0_CPU1_P1P0_DP<2>")
	)
	(segment
		(start 367.154206 -169.323258)
		(end 367.160556 -169.118534)
		(width 0.14732)
		(layer "In4.Cu")
		(net "UPI_CPU0_CPU1_P1P0_DP<2>")
	)
	(segment
		(start 367.160556 -169.118534)
		(end 366.550448 -168.468548)
		(width 0.14732)
		(layer "In4.Cu")
		(net "UPI_CPU0_CPU1_P1P0_DP<2>")
	)
	(segment
		(start 379.974094 -215.760554)
		(end 379.981968 -215.755982)
		(width 0.0889)
		(layer "In4.Cu")
		(net "UPI_CPU0_CPU1_P1P0_DP<2>")
	)
	(segment
		(start 381.058674 -211.6074)
		(end 381.058674 -210.410044)
		(width 0.14732)
		(layer "In4.Cu")
		(net "UPI_CPU0_CPU1_P1P0_DP<2>")
	)
	(segment
		(start 366.345724 -168.462198)
		(end 366.093502 -168.193466)
		(width 0.14732)
		(layer "In4.Cu")
		(net "UPI_CPU0_CPU1_P1P0_DP<2>")
	)
	(segment
		(start 91.246706 -217.388186)
		(end 91.247468 -217.388694)
		(width 0.0889)
		(layer "In4.Cu")
		(net "UPI_CPU0_CPU1_P1P0_DP<2>")
	)
	(segment
		(start 372.20017 -171.656248)
		(end 369.62842 -171.107608)
		(width 0.14732)
		(layer "In4.Cu")
		(net "UPI_CPU0_CPU1_P1P0_DP<2>")
	)
	(segment
		(start 379.973078 -215.761062)
		(end 379.974094 -215.760554)
		(width 0.0889)
		(layer "In4.Cu")
		(net "UPI_CPU0_CPU1_P1P0_DP<2>")
	)
	(segment
		(start 92.175584 -207.284574)
		(end 92.261182 -207.470756)
		(width 0.14732)
		(layer "In4.Cu")
		(net "UPI_CPU0_CPU1_P1P0_DP<2>")
	)
	(segment
		(start 91.247468 -216.739978)
		(end 91.246706 -216.740486)
		(width 0.0889)
		(layer "In4.Cu")
		(net "UPI_CPU0_CPU1_P1P0_DP<2>")
	)
	(segment
		(start 368.847116 -170.91533)
		(end 367.611152 -169.598594)
		(width 0.14732)
		(layer "In4.Cu")
		(net "UPI_CPU0_CPU1_P1P0_DP<2>")
	)
	(segment
		(start 95.97644 -197.030594)
		(end 95.975678 -197.03288)
		(width 0.14732)
		(layer "In4.Cu")
		(net "UPI_CPU0_CPU1_P1P0_DP<2>")
	)
	(segment
		(start 360.380788 -161.896044)
		(end 331.003402 -143.031464)
		(width 0.14732)
		(layer "In4.Cu")
		(net "UPI_CPU0_CPU1_P1P0_DP<2>")
	)
	(segment
		(start 91.543886 -209.404966)
		(end 91.41587 -209.75066)
		(width 0.14732)
		(layer "In4.Cu")
		(net "UPI_CPU0_CPU1_P1P0_DP<2>")
	)
	(segment
		(start 103.414322 -182.534052)
		(end 99.574858 -187.32246)
		(width 0.14732)
		(layer "In4.Cu")
		(net "UPI_CPU0_CPU1_P1P0_DP<2>")
	)
	(segment
		(start 91.238578 -217.383614)
		(end 91.246706 -217.388186)
		(width 0.0889)
		(layer "In4.Cu")
		(net "UPI_CPU0_CPU1_P1P0_DP<2>")
	)
	(segment
		(start 365.519716 -167.582088)
		(end 365.26724 -167.313102)
		(width 0.14732)
		(layer "In4.Cu")
		(net "UPI_CPU0_CPU1_P1P0_DP<2>")
	)
	(segment
		(start 378.84989 -193.825368)
		(end 377.63704 -182.115968)
		(width 0.14732)
		(layer "In4.Cu")
		(net "UPI_CPU0_CPU1_P1P0_DP<2>")
	)
	(segment
		(start 91.240356 -215.757252)
		(end 91.243658 -215.75903)
		(width 0.0889)
		(layer "In4.Cu")
		(net "UPI_CPU0_CPU1_P1P0_DP<2>")
	)
	(segment
		(start 364.571534 -166.360348)
		(end 364.049818 -165.804596)
		(width 0.14732)
		(layer "In4.Cu")
		(net "UPI_CPU0_CPU1_P1P0_DP<2>")
	)
	(segment
		(start 91.815412 -208.256378)
		(end 91.900756 -208.44256)
		(width 0.14732)
		(layer "In4.Cu")
		(net "UPI_CPU0_CPU1_P1P0_DP<2>")
	)
	(segment
		(start 366.099852 -167.988742)
		(end 365.724186 -167.588438)
		(width 0.14732)
		(layer "In4.Cu")
		(net "UPI_CPU0_CPU1_P1P0_DP<2>")
	)
	(segment
		(start 91.41587 -209.75066)
		(end 91.229688 -209.83575)
		(width 0.14732)
		(layer "In4.Cu")
		(net "UPI_CPU0_CPU1_P1P0_DP<2>")
	)
	(segment
		(start 367.406428 -169.59199)
		(end 367.154206 -169.323258)
		(width 0.14732)
		(layer "In4.Cu")
		(net "UPI_CPU0_CPU1_P1P0_DP<2>")
	)
	(segment
		(start 364.817406 -166.833804)
		(end 364.56493 -166.565072)
		(width 0.14732)
		(layer "In4.Cu")
		(net "UPI_CPU0_CPU1_P1P0_DP<2>")
	)
	(segment
		(start 92.261182 -207.470756)
		(end 92.133166 -207.816196)
		(width 0.14732)
		(layer "In4.Cu")
		(net "UPI_CPU0_CPU1_P1P0_DP<2>")
	)
	(segment
		(start 379.78588 -217.064336)
		(end 379.942344 -217.335354)
		(width 0.0889)
		(layer "In4.Cu")
		(net "UPI_CPU0_CPU1_P1P0_DP<2>")
	)
	(segment
		(start 363.592618 -165.52926)
		(end 363.599222 -165.32479)
		(width 0.14732)
		(layer "In4.Cu")
		(net "UPI_CPU0_CPU1_P1P0_DP<2>")
	)
	(segment
		(start 364.049818 -165.804596)
		(end 363.845094 -165.797992)
		(width 0.14732)
		(layer "In4.Cu")
		(net "UPI_CPU0_CPU1_P1P0_DP<2>")
	)
	(segment
		(start 380.06274 -205.534768)
		(end 378.849636 -193.825368)
		(width 0.14732)
		(layer "In4.Cu")
		(net "UPI_CPU0_CPU1_P1P0_DP<2>")
	)
	(segment
		(start 377.63704 -182.115968)
		(end 376.154442 -175.089566)
		(width 0.14732)
		(layer "In4.Cu")
		(net "UPI_CPU0_CPU1_P1P0_DP<2>")
	)
	(segment
		(start 378.849636 -193.825368)
		(end 378.84989 -193.825368)
		(width 0.14732)
		(layer "In4.Cu")
		(net "UPI_CPU0_CPU1_P1P0_DP<2>")
	)
	(segment
		(start 381.100838 -213.3346)
		(end 381.001778 -213.23554)
		(width 0.0889)
		(layer "In4.Cu")
		(net "UPI_CPU0_CPU1_P1P0_DP<2>")
	)
	(segment
		(start 91.101926 -211.631022)
		(end 91.101926 -211.88299)
		(width 0.14732)
		(layer "In4.Cu")
		(net "UPI_CPU0_CPU1_P1P0_DP<2>")
	)
	(segment
		(start 91.101672 -211.630768)
		(end 91.101926 -211.631022)
		(width 0.14732)
		(layer "In4.Cu")
		(net "UPI_CPU0_CPU1_P1P0_DP<2>")
	)
	(segment
		(start 91.244166 -216.74201)
		(end 91.238578 -216.745058)
		(width 0.0889)
		(layer "In4.Cu")
		(net "UPI_CPU0_CPU1_P1P0_DP<2>")
	)
	(segment
		(start 381.100838 -212.96122)
		(end 381.100838 -212.69198)
		(width 0.0889)
		(layer "In4.Cu")
		(net "UPI_CPU0_CPU1_P1P0_DP<2>")
	)
	(segment
		(start 375.928636 -174.71771)
		(end 372.20017 -171.656248)
		(width 0.14732)
		(layer "In4.Cu")
		(net "UPI_CPU0_CPU1_P1P0_DP<2>")
	)
	(segment
		(start 91.246706 -216.740486)
		(end 91.244166 -216.74201)
		(width 0.0889)
		(layer "In4.Cu")
		(net "UPI_CPU0_CPU1_P1P0_DP<2>")
	)
	(segment
		(start 91.248738 -215.762078)
		(end 91.25331 -215.764618)
		(width 0.0889)
		(layer "In4.Cu")
		(net "UPI_CPU0_CPU1_P1P0_DP<2>")
	)
	(segment
		(start 381.001778 -212.41766)
		(end 381.100838 -212.3186)
		(width 0.0889)
		(layer "In4.Cu")
		(net "UPI_CPU0_CPU1_P1P0_DP<2>")
	)
	(segment
		(start 365.021876 -166.840154)
		(end 364.817406 -166.833804)
		(width 0.14732)
		(layer "In4.Cu")
		(net "UPI_CPU0_CPU1_P1P0_DP<2>")
	)
	(segment
		(start 381.001778 -213.06028)
		(end 381.100838 -212.96122)
		(width 0.0889)
		(layer "In4.Cu")
		(net "UPI_CPU0_CPU1_P1P0_DP<2>")
	)
	(segment
		(start 91.458542 -209.218784)
		(end 91.543886 -209.404966)
		(width 0.14732)
		(layer "In4.Cu")
		(net "UPI_CPU0_CPU1_P1P0_DP<2>")
	)
	(segment
		(start 381.058928 -211.925408)
		(end 381.058928 -211.90331)
		(width 0.0889)
		(layer "In4.Cu")
		(net "UPI_CPU0_CPU1_P1P0_DP<2>")
	)
	(segment
		(start 379.690884 -216.266014)
		(end 379.690884 -216.235026)
		(width 0.0889)
		(layer "In4.Cu")
		(net "UPI_CPU0_CPU1_P1P0_DP<2>")
	)
	(segment
		(start 91.238324 -215.755982)
		(end 91.240356 -215.757252)
		(width 0.0889)
		(layer "In4.Cu")
		(net "UPI_CPU0_CPU1_P1P0_DP<2>")
	)
	(segment
		(start 91.101926 -211.905088)
		(end 91.059762 -211.947252)
		(width 0.0889)
		(layer "In4.Cu")
		(net "UPI_CPU0_CPU1_P1P0_DP<2>")
	)
	(segment
		(start 124.054108 -163.117276)
		(end 103.414322 -182.534052)
		(width 0.14732)
		(layer "In4.Cu")
		(net "UPI_CPU0_CPU1_P1P0_DP<2>")
	)
	(segment
		(start 363.599222 -165.32479)
		(end 360.380788 -161.896044)
		(width 0.14732)
		(layer "In4.Cu")
		(net "UPI_CPU0_CPU1_P1P0_DP<2>")
	)
	(segment
		(start 365.26724 -167.313102)
		(end 365.273844 -167.108632)
		(width 0.14732)
		(layer "In4.Cu")
		(net "UPI_CPU0_CPU1_P1P0_DP<2>")
	)
	(segment
		(start 91.229688 -209.83575)
		(end 91.101672 -210.18119)
		(width 0.14732)
		(layer "In4.Cu")
		(net "UPI_CPU0_CPU1_P1P0_DP<2>")
	)
	(segment
		(start 91.302078 -218.33205)
		(end 91.277948 -218.421204)
		(width 0.0889)
		(layer "In4.Cu")
		(net "UPI_CPU0_CPU1_P1P0_DP<2>")
	)
	(segment
		(start 381.001778 -212.59292)
		(end 381.001778 -212.41766)
		(width 0.0889)
		(layer "In4.Cu")
		(net "UPI_CPU0_CPU1_P1P0_DP<2>")
	)
	(segment
		(start 379.942344 -217.335354)
		(end 380.020576 -217.356182)
		(width 0.0889)
		(layer "In4.Cu")
		(net "UPI_CPU0_CPU1_P1P0_DP<2>")
	)
	(segment
		(start 160.221676 -140.861796)
		(end 124.054108 -163.117276)
		(width 0.14732)
		(layer "In4.Cu")
		(net "UPI_CPU0_CPU1_P1P0_DP<2>")
	)
	(segment
		(start 91.243658 -215.75903)
		(end 91.24569 -215.7603)
		(width 0.0889)
		(layer "In4.Cu")
		(net "UPI_CPU0_CPU1_P1P0_DP<2>")
	)
	(segment
		(start 380.630684 -214.622634)
		(end 380.630684 -214.425022)
		(width 0.0889)
		(layer "In4.Cu")
		(net "UPI_CPU0_CPU1_P1P0_DP<2>")
	)
	(segment
		(start 367.611152 -169.598594)
		(end 367.406428 -169.59199)
		(width 0.14732)
		(layer "In4.Cu")
		(net "UPI_CPU0_CPU1_P1P0_DP<2>")
	)
	(segment
		(start 91.059762 -213.893654)
		(end 91.060016 -213.893908)
		(width 0.0889)
		(layer "In4.Cu")
		(net "UPI_CPU0_CPU1_P1P0_DP<2>")
	)
	(segment
		(start 381.001778 -213.23554)
		(end 381.001778 -213.06028)
		(width 0.0889)
		(layer "In4.Cu")
		(net "UPI_CPU0_CPU1_P1P0_DP<2>")
	)
	(segment
		(start 366.093502 -168.193466)
		(end 366.099852 -167.988742)
		(width 0.14732)
		(layer "In4.Cu")
		(net "UPI_CPU0_CPU1_P1P0_DP<2>")
	)
	(segment
		(start 381.058674 -210.410044)
		(end 380.06274 -208.005426)
		(width 0.14732)
		(layer "In4.Cu")
		(net "UPI_CPU0_CPU1_P1P0_DP<2>")
	)
	(segment
		(start 381.058928 -211.90331)
		(end 381.058928 -211.607654)
		(width 0.14732)
		(layer "In4.Cu")
		(net "UPI_CPU0_CPU1_P1P0_DP<2>")
	)
	(segment
		(start 381.058928 -211.607654)
		(end 381.058674 -211.6074)
		(width 0.14732)
		(layer "In4.Cu")
		(net "UPI_CPU0_CPU1_P1P0_DP<2>")
	)
	(segment
		(start 318.530478 -139.977368)
		(end 316.01537 -139.977368)
		(width 0.14732)
		(layer "In4.Cu")
		(net "UPI_CPU0_CPU1_P1P0_DP<2>")
	)
	(segment
		(start 91.247214 -215.761062)
		(end 91.248738 -215.762078)
		(width 0.0889)
		(layer "In4.Cu")
		(net "UPI_CPU0_CPU1_P1P0_DP<2>")
	)
	(segment
		(start 376.154442 -175.089566)
		(end 375.928636 -174.71771)
		(width 0.14732)
		(layer "In4.Cu")
		(net "UPI_CPU0_CPU1_P1P0_DP<2>")
	)
	(segment
		(start 95.97644 -197.03034)
		(end 95.97644 -197.030594)
		(width 0.14732)
		(layer "In4.Cu")
		(net "UPI_CPU0_CPU1_P1P0_DP<2>")
	)
	(segment
		(start 365.273844 -167.108632)
		(end 365.021876 -166.840154)
		(width 0.14732)
		(layer "In4.Cu")
		(net "UPI_CPU0_CPU1_P1P0_DP<2>")
	)
	(segment
		(start 99.574858 -187.32246)
		(end 95.97644 -197.03034)
		(width 0.14732)
		(layer "In4.Cu")
		(net "UPI_CPU0_CPU1_P1P0_DP<2>")
	)
	(segment
		(start 364.56493 -166.565072)
		(end 364.571534 -166.360348)
		(width 0.14732)
		(layer "In4.Cu")
		(net "UPI_CPU0_CPU1_P1P0_DP<2>")
	)
	(segment
		(start 91.059762 -211.947252)
		(end 91.059762 -213.893654)
		(width 0.0889)
		(layer "In4.Cu")
		(net "UPI_CPU0_CPU1_P1P0_DP<2>")
	)
	(segment
		(start 381.100838 -213.892892)
		(end 381.100838 -213.3346)
		(width 0.0889)
		(layer "In4.Cu")
		(net "UPI_CPU0_CPU1_P1P0_DP<2>")
	)
	(segment
		(start 91.900756 -208.44256)
		(end 91.77274 -208.788254)
		(width 0.14732)
		(layer "In4.Cu")
		(net "UPI_CPU0_CPU1_P1P0_DP<2>")
	)
	(segment
		(start 379.981968 -216.745058)
		(end 379.975618 -216.741248)
		(width 0.0889)
		(layer "In4.Cu")
		(net "UPI_CPU0_CPU1_P1P0_DP<2>")
	)
	(segment
		(start 379.975618 -216.741248)
		(end 379.973078 -216.739978)
		(width 0.0889)
		(layer "In4.Cu")
		(net "UPI_CPU0_CPU1_P1P0_DP<2>")
	)
	(segment
		(start 91.24569 -215.7603)
		(end 91.247214 -215.761062)
		(width 0.0889)
		(layer "In4.Cu")
		(net "UPI_CPU0_CPU1_P1P0_DP<2>")
	)
	(segment
		(start 381.10033 -213.894162)
		(end 381.100838 -213.892892)
		(width 0.0889)
		(layer "In4.Cu")
		(net "UPI_CPU0_CPU1_P1P0_DP<2>")
	)
	(segment
		(start 369.62842 -171.107608)
		(end 368.847116 -170.91533)
		(width 0.14732)
		(layer "In4.Cu")
		(net "UPI_CPU0_CPU1_P1P0_DP<2>")
	)
	(segment
		(start 95.975678 -197.03288)
		(end 92.175584 -207.284574)
		(width 0.14732)
		(layer "In4.Cu")
		(net "UPI_CPU0_CPU1_P1P0_DP<2>")
	)
	(segment
		(start 91.77274 -208.788254)
		(end 91.586304 -208.873598)
		(width 0.14732)
		(layer "In4.Cu")
		(net "UPI_CPU0_CPU1_P1P0_DP<2>")
	)
	(segment
		(start 380.443232 -214.946992)
		(end 380.452122 -214.941912)
		(width 0.0889)
		(layer "In4.Cu")
		(net "UPI_CPU0_CPU1_P1P0_DP<2>")
	)
	(segment
		(start 381.100838 -212.69198)
		(end 381.001778 -212.59292)
		(width 0.0889)
		(layer "In4.Cu")
		(net "UPI_CPU0_CPU1_P1P0_DP<2>")
	)
	(segment
		(start 91.586304 -208.873598)
		(end 91.458542 -209.218784)
		(width 0.14732)
		(layer "In4.Cu")
		(net "UPI_CPU0_CPU1_P1P0_DP<2>")
	)
	(segment
		(start 381.100838 -212.3186)
		(end 381.100838 -211.967318)
		(width 0.0889)
		(layer "In4.Cu")
		(net "UPI_CPU0_CPU1_P1P0_DP<2>")
	)
	(segment
		(start 91.101672 -210.18119)
		(end 91.101672 -211.630768)
		(width 0.14732)
		(layer "In4.Cu")
		(net "UPI_CPU0_CPU1_P1P0_DP<2>")
	)
	(segment
		(start 91.94673 -207.901794)
		(end 91.815412 -208.256378)
		(width 0.14732)
		(layer "In4.Cu")
		(net "UPI_CPU0_CPU1_P1P0_DP<2>")
	)
	(segment
		(start 91.101926 -211.88299)
		(end 91.101926 -211.905088)
		(width 0.0889)
		(layer "In4.Cu")
		(net "UPI_CPU0_CPU1_P1P0_DP<2>")
	)
	(arc
		(start 91.319096 -218.318842)
		(mid 91.31065 -218.325527)
		(end 91.302078 -218.33205)
		(width 0.0889)
		(layer "In4.Cu")
		(net "UPI_CPU0_CPU1_P1P0_DP<2>")
	)
	(arc
		(start 380.630684 -214.425022)
		(mid 380.742022 -214.232122)
		(end 380.91618 -214.093298)
		(width 0.0889)
		(layer "In4.Cu")
		(net "UPI_CPU0_CPU1_P1P0_DP<2>")
	)
	(arc
		(start 380.452122 -214.941912)
		(mid 380.583036 -214.805552)
		(end 380.630684 -214.622634)
		(width 0.0889)
		(layer "In4.Cu")
		(net "UPI_CPU0_CPU1_P1P0_DP<2>")
	)
	(arc
		(start 91.247468 -217.388694)
		(mid 91.528546 -217.834929)
		(end 91.319096 -218.318842)
		(width 0.0889)
		(layer "In4.Cu")
		(net "UPI_CPU0_CPU1_P1P0_DP<2>")
	)
	(arc
		(start 91.060016 -213.893908)
		(mid 91.135021 -214.009367)
		(end 91.244166 -214.093298)
		(width 0.0889)
		(layer "In4.Cu")
		(net "UPI_CPU0_CPU1_P1P0_DP<2>")
	)
	(arc
		(start 91.238578 -216.745058)
		(mid 91.059981 -217.064336)
		(end 91.238578 -217.383614)
		(width 0.0889)
		(layer "In4.Cu")
		(net "UPI_CPU0_CPU1_P1P0_DP<2>")
	)
	(arc
		(start 379.690884 -216.235026)
		(mid 379.770254 -215.961292)
		(end 379.973078 -215.761062)
		(width 0.0889)
		(layer "In4.Cu")
		(net "UPI_CPU0_CPU1_P1P0_DP<2>")
	)
	(arc
		(start 380.020576 -217.356182)
		(mid 380.159639 -217.040661)
		(end 379.981968 -216.745058)
		(width 0.0889)
		(layer "In4.Cu")
		(net "UPI_CPU0_CPU1_P1P0_DP<2>")
	)
	(arc
		(start 379.973078 -216.739978)
		(mid 379.770255 -216.539747)
		(end 379.690884 -216.266014)
		(width 0.0889)
		(layer "In4.Cu")
		(net "UPI_CPU0_CPU1_P1P0_DP<2>")
	)
	(arc
		(start 91.25331 -215.764618)
		(mid 91.529874 -216.253939)
		(end 91.247468 -216.739978)
		(width 0.0889)
		(layer "In4.Cu")
		(net "UPI_CPU0_CPU1_P1P0_DP<2>")
	)
	(arc
		(start 91.238324 -215.117426)
		(mid 91.11107 -215.247392)
		(end 91.060016 -215.421972)
		(width 0.0889)
		(layer "In4.Cu")
		(net "UPI_CPU0_CPU1_P1P0_DP<2>")
	)
	(arc
		(start 91.244166 -214.093298)
		(mid 91.418129 -214.232062)
		(end 91.529408 -214.424768)
		(width 0.0889)
		(layer "In4.Cu")
		(net "UPI_CPU0_CPU1_P1P0_DP<2>")
	)
	(arc
		(start 379.981968 -215.755982)
		(mid 380.112882 -215.619622)
		(end 380.16053 -215.436704)
		(width 0.0889)
		(layer "In4.Cu")
		(net "UPI_CPU0_CPU1_P1P0_DP<2>")
	)
	(arc
		(start 91.529408 -214.644732)
		(mid 91.448497 -214.91486)
		(end 91.247214 -215.112346)
		(width 0.0889)
		(layer "In4.Cu")
		(net "UPI_CPU0_CPU1_P1P0_DP<2>")
	)
	(arc
		(start 380.16053 -215.436704)
		(mid 380.232703 -215.160036)
		(end 380.43104 -214.954104)
		(width 0.0889)
		(layer "In4.Cu")
		(net "UPI_CPU0_CPU1_P1P0_DP<2>")
	)
	(arc
		(start 380.91618 -214.093298)
		(mid 381.025305 -214.009495)
		(end 381.10033 -213.894162)
		(width 0.0889)
		(layer "In4.Cu")
		(net "UPI_CPU0_CPU1_P1P0_DP<2>")
	)
	(arc
		(start 91.060016 -215.421972)
		(mid 91.103876 -215.613157)
		(end 91.238324 -215.755982)
		(width 0.0889)
		(layer "In4.Cu")
		(net "UPI_CPU0_CPU1_P1P0_DP<2>")
	)
	(segment
		(start 110.700566 -217.878406)
		(end 110.700566 -218.414346)
		(width 0.13208)
		(layer "F.Cu")
		(net "UPI_CPU0_CPU1_P1P0_DP<23>")
	)
	(segment
		(start 360.51998 -218.414346)
		(end 360.51998 -217.87866)
		(width 0.13208)
		(layer "F.Cu")
		(net "UPI_CPU0_CPU1_P1P0_DP<23>")
	)
	(segment
		(start 360.51998 -217.87866)
		(end 360.520234 -217.878406)
		(width 0.13208)
		(layer "F.Cu")
		(net "UPI_CPU0_CPU1_P1P0_DP<23>")
	)
	(segment
		(start 219.079572 -165.042596)
		(end 218.901264 -164.93617)
		(width 0.14732)
		(layer "In4.Cu")
		(net "UPI_CPU0_CPU1_P1P0_DP<23>")
	)
	(segment
		(start 228.637592 -162.61715)
		(end 228.065076 -162.762692)
		(width 0.14732)
		(layer "In4.Cu")
		(net "UPI_CPU0_CPU1_P1P0_DP<23>")
	)
	(segment
		(start 217.941652 -162.406584)
		(end 217.14968 -162.608006)
		(width 0.14732)
		(layer "In4.Cu")
		(net "UPI_CPU0_CPU1_P1P0_DP<23>")
	)
	(segment
		(start 221.642432 -161.468054)
		(end 221.419166 -161.841942)
		(width 0.14732)
		(layer "In4.Cu")
		(net "UPI_CPU0_CPU1_P1P0_DP<23>")
	)
	(segment
		(start 111.033306 -212.042248)
		(end 111.075216 -212.084158)
		(width 0.0889)
		(layer "In4.Cu")
		(net "UPI_CPU0_CPU1_P1P0_DP<23>")
	)
	(segment
		(start 111.859314 -209.131916)
		(end 111.85906 -209.132678)
		(width 0.14732)
		(layer "In4.Cu")
		(net "UPI_CPU0_CPU1_P1P0_DP<23>")
	)
	(segment
		(start 218.901264 -164.93617)
		(end 218.31554 -162.62985)
		(width 0.14732)
		(layer "In4.Cu")
		(net "UPI_CPU0_CPU1_P1P0_DP<23>")
	)
	(segment
		(start 225.8187 -163.332668)
		(end 225.640392 -163.226242)
		(width 0.14732)
		(layer "In4.Cu")
		(net "UPI_CPU0_CPU1_P1P0_DP<23>")
	)
	(segment
		(start 223.665542 -161.271966)
		(end 224.251266 -163.578794)
		(width 0.14732)
		(layer "In4.Cu")
		(net "UPI_CPU0_CPU1_P1P0_DP<23>")
	)
	(segment
		(start 213.448646 -163.54679)
		(end 198.00697 -167.527478)
		(width 0.14732)
		(layer "In4.Cu")
		(net "UPI_CPU0_CPU1_P1P0_DP<23>")
	)
	(segment
		(start 111.85906 -209.132678)
		(end 111.033052 -211.468208)
		(width 0.14732)
		(layer "In4.Cu")
		(net "UPI_CPU0_CPU1_P1P0_DP<23>")
	)
	(segment
		(start 130.200654 -181.728618)
		(end 130.188462 -182.164228)
		(width 0.14732)
		(layer "In4.Cu")
		(net "UPI_CPU0_CPU1_P1P0_DP<23>")
	)
	(segment
		(start 225.640392 -163.226242)
		(end 225.054668 -160.919922)
		(width 0.14732)
		(layer "In4.Cu")
		(net "UPI_CPU0_CPU1_P1P0_DP<23>")
	)
	(segment
		(start 111.544862 -215.286336)
		(end 111.544862 -215.436704)
		(width 0.0889)
		(layer "In4.Cu")
		(net "UPI_CPU0_CPU1_P1P0_DP<23>")
	)
	(segment
		(start 222.808292 -161.489898)
		(end 222.434404 -161.266632)
		(width 0.14732)
		(layer "In4.Cu")
		(net "UPI_CPU0_CPU1_P1P0_DP<23>")
	)
	(segment
		(start 110.605316 -217.05443)
		(end 110.605316 -217.082878)
		(width 0.0889)
		(layer "In4.Cu")
		(net "UPI_CPU0_CPU1_P1P0_DP<23>")
	)
	(segment
		(start 194.928744 -167.914828)
		(end 189.34938 -167.914828)
		(width 0.14732)
		(layer "In4.Cu")
		(net "UPI_CPU0_CPU1_P1P0_DP<23>")
	)
	(segment
		(start 111.075216 -214.642446)
		(end 111.07547 -214.643208)
		(width 0.0889)
		(layer "In4.Cu")
		(net "UPI_CPU0_CPU1_P1P0_DP<23>")
	)
	(segment
		(start 224.68078 -160.696656)
		(end 223.888808 -160.898078)
		(width 0.14732)
		(layer "In4.Cu")
		(net "UPI_CPU0_CPU1_P1P0_DP<23>")
	)
	(segment
		(start 360.615484 -217.086434)
		(end 360.615484 -217.064336)
		(width 0.0889)
		(layer "In4.Cu")
		(net "UPI_CPU0_CPU1_P1P0_DP<23>")
	)
	(segment
		(start 126.965202 -185.71591)
		(end 126.535688 -186.121548)
		(width 0.14732)
		(layer "In4.Cu")
		(net "UPI_CPU0_CPU1_P1P0_DP<23>")
	)
	(segment
		(start 221.898464 -164.327078)
		(end 221.325948 -164.47262)
		(width 0.14732)
		(layer "In4.Cu")
		(net "UPI_CPU0_CPU1_P1P0_DP<23>")
	)
	(segment
		(start 314.35675 -167.78351)
		(end 302.489108 -167.541194)
		(width 0.14732)
		(layer "In4.Cu")
		(net "UPI_CPU0_CPU1_P1P0_DP<23>")
	)
	(segment
		(start 111.075216 -216.235026)
		(end 111.075216 -216.25052)
		(width 0.0889)
		(layer "In4.Cu")
		(net "UPI_CPU0_CPU1_P1P0_DP<23>")
	)
	(segment
		(start 213.822788 -163.769294)
		(end 213.448646 -163.54679)
		(width 0.14732)
		(layer "In4.Cu")
		(net "UPI_CPU0_CPU1_P1P0_DP<23>")
	)
	(segment
		(start 234.82935 -158.034228)
		(end 229.656386 -159.367728)
		(width 0.14732)
		(layer "In4.Cu")
		(net "UPI_CPU0_CPU1_P1P0_DP<23>")
	)
	(segment
		(start 130.335782 -182.534306)
		(end 129.906268 -182.939944)
		(width 0.14732)
		(layer "In4.Cu")
		(net "UPI_CPU0_CPU1_P1P0_DP<23>")
	)
	(segment
		(start 319.795398 -169.31767)
		(end 314.35675 -167.78351)
		(width 0.14732)
		(layer "In4.Cu")
		(net "UPI_CPU0_CPU1_P1P0_DP<23>")
	)
	(segment
		(start 360.36377 -218.149424)
		(end 360.285538 -218.170252)
		(width 0.0889)
		(layer "In4.Cu")
		(net "UPI_CPU0_CPU1_P1P0_DP<23>")
	)
	(segment
		(start 219.758514 -164.718746)
		(end 219.652088 -164.897054)
		(width 0.14732)
		(layer "In4.Cu")
		(net "UPI_CPU0_CPU1_P1P0_DP<23>")
	)
	(segment
		(start 225.054668 -160.919922)
		(end 224.68078 -160.696656)
		(width 0.14732)
		(layer "In4.Cu")
		(net "UPI_CPU0_CPU1_P1P0_DP<23>")
	)
	(segment
		(start 226.135184 -160.328356)
		(end 225.911664 -160.701736)
		(width 0.14732)
		(layer "In4.Cu")
		(net "UPI_CPU0_CPU1_P1P0_DP<23>")
	)
	(segment
		(start 228.744018 -162.438588)
		(end 228.637592 -162.61715)
		(width 0.14732)
		(layer "In4.Cu")
		(net "UPI_CPU0_CPU1_P1P0_DP<23>")
	)
	(segment
		(start 131.885944 -180.13807)
		(end 131.873752 -180.573426)
		(width 0.14732)
		(layer "In4.Cu")
		(net "UPI_CPU0_CPU1_P1P0_DP<23>")
	)
	(segment
		(start 130.795268 -181.16804)
		(end 130.200654 -181.728618)
		(width 0.14732)
		(layer "In4.Cu")
		(net "UPI_CPU0_CPU1_P1P0_DP<23>")
	)
	(segment
		(start 215.265762 -165.858698)
		(end 215.159336 -166.037006)
		(width 0.14732)
		(layer "In4.Cu")
		(net "UPI_CPU0_CPU1_P1P0_DP<23>")
	)
	(segment
		(start 360.338878 -216.578434)
		(end 360.336592 -216.577164)
		(width 0.0889)
		(layer "In4.Cu")
		(net "UPI_CPU0_CPU1_P1P0_DP<23>")
	)
	(segment
		(start 110.85703 -217.607388)
		(end 110.700566 -217.878406)
		(width 0.0889)
		(layer "In4.Cu")
		(net "UPI_CPU0_CPU1_P1P0_DP<23>")
	)
	(segment
		(start 128.01346 -184.52465)
		(end 127.85979 -184.361836)
		(width 0.14732)
		(layer "In4.Cu")
		(net "UPI_CPU0_CPU1_P1P0_DP<23>")
	)
	(segment
		(start 360.61523 -215.44661)
		(end 360.61523 -215.23833)
		(width 0.0889)
		(layer "In4.Cu")
		(net "UPI_CPU0_CPU1_P1P0_DP<23>")
	)
	(segment
		(start 360.480102 -211.681568)
		(end 360.480102 -204.473302)
		(width 0.14732)
		(layer "In4.Cu")
		(net "UPI_CPU0_CPU1_P1P0_DP<23>")
	)
	(segment
		(start 280.281888 -167.9194)
		(end 275.890228 -167.9194)
		(width 0.14732)
		(layer "In4.Cu")
		(net "UPI_CPU0_CPU1_P1P0_DP<23>")
	)
	(segment
		(start 228.377496 -159.76473)
		(end 228.158294 -160.132014)
		(width 0.14732)
		(layer "In4.Cu")
		(net "UPI_CPU0_CPU1_P1P0_DP<23>")
	)
	(segment
		(start 126.817882 -185.345832)
		(end 126.971298 -185.508138)
		(width 0.14732)
		(layer "In4.Cu")
		(net "UPI_CPU0_CPU1_P1P0_DP<23>")
	)
	(segment
		(start 228.743764 -162.438588)
		(end 228.744018 -162.438588)
		(width 0.14732)
		(layer "In4.Cu")
		(net "UPI_CPU0_CPU1_P1P0_DP<23>")
	)
	(segment
		(start 224.251266 -163.578794)
		(end 224.14484 -163.757102)
		(width 0.14732)
		(layer "In4.Cu")
		(net "UPI_CPU0_CPU1_P1P0_DP<23>")
	)
	(segment
		(start 131.23037 -181.180232)
		(end 130.795268 -181.16804)
		(width 0.14732)
		(layer "In4.Cu")
		(net "UPI_CPU0_CPU1_P1P0_DP<23>")
	)
	(segment
		(start 111.033306 -212.02015)
		(end 111.033306 -212.042248)
		(width 0.0889)
		(layer "In4.Cu")
		(net "UPI_CPU0_CPU1_P1P0_DP<23>")
	)
	(segment
		(start 111.166148 -214.874856)
		(end 111.26724 -214.984076)
		(width 0.0889)
		(layer "In4.Cu")
		(net "UPI_CPU0_CPU1_P1P0_DP<23>")
	)
	(segment
		(start 227.886768 -162.656266)
		(end 227.301044 -160.349946)
		(width 0.14732)
		(layer "In4.Cu")
		(net "UPI_CPU0_CPU1_P1P0_DP<23>")
	)
	(segment
		(start 134.127494 -178.02352)
		(end 131.885944 -180.13807)
		(width 0.14732)
		(layer "In4.Cu")
		(net "UPI_CPU0_CPU1_P1P0_DP<23>")
	)
	(segment
		(start 223.888808 -160.898078)
		(end 223.665542 -161.271966)
		(width 0.14732)
		(layer "In4.Cu")
		(net "UPI_CPU0_CPU1_P1P0_DP<23>")
	)
	(segment
		(start 340.171532 -177.132742)
		(end 332.606904 -173.846744)
		(width 0.14732)
		(layer "In4.Cu")
		(net "UPI_CPU0_CPU1_P1P0_DP<23>")
	)
	(segment
		(start 111.3663 -215.755982)
		(end 111.35741 -215.761062)
		(width 0.0889)
		(layer "In4.Cu")
		(net "UPI_CPU0_CPU1_P1P0_DP<23>")
	)
	(segment
		(start 127.424688 -184.349644)
		(end 126.830074 -184.910222)
		(width 0.14732)
		(layer "In4.Cu")
		(net "UPI_CPU0_CPU1_P1P0_DP<23>")
	)
	(segment
		(start 114.527584 -201.587862)
		(end 111.859314 -209.131916)
		(width 0.14732)
		(layer "In4.Cu")
		(net "UPI_CPU0_CPU1_P1P0_DP<23>")
	)
	(segment
		(start 128.650492 -184.125108)
		(end 128.220978 -184.530746)
		(width 0.14732)
		(layer "In4.Cu")
		(net "UPI_CPU0_CPU1_P1P0_DP<23>")
	)
	(segment
		(start 216.833196 -165.612572)
		(end 216.654888 -165.506146)
		(width 0.14732)
		(layer "In4.Cu")
		(net "UPI_CPU0_CPU1_P1P0_DP<23>")
	)
	(segment
		(start 219.652088 -164.897054)
		(end 219.079572 -165.042596)
		(width 0.14732)
		(layer "In4.Cu")
		(net "UPI_CPU0_CPU1_P1P0_DP<23>")
	)
	(segment
		(start 155.774898 -168.665144)
		(end 149.20976 -170.321478)
		(width 0.14732)
		(layer "In4.Cu")
		(net "UPI_CPU0_CPU1_P1P0_DP<23>")
	)
	(segment
		(start 130.188462 -182.164228)
		(end 130.341878 -182.326534)
		(width 0.14732)
		(layer "In4.Cu")
		(net "UPI_CPU0_CPU1_P1P0_DP<23>")
	)
	(segment
		(start 126.830074 -184.910222)
		(end 126.817882 -185.345832)
		(width 0.14732)
		(layer "In4.Cu")
		(net "UPI_CPU0_CPU1_P1P0_DP<23>")
	)
	(segment
		(start 132.021072 -180.943504)
		(end 131.591558 -181.349142)
		(width 0.14732)
		(layer "In4.Cu")
		(net "UPI_CPU0_CPU1_P1P0_DP<23>")
	)
	(segment
		(start 220.561916 -162.059874)
		(end 220.188028 -161.836608)
		(width 0.14732)
		(layer "In4.Cu")
		(net "UPI_CPU0_CPU1_P1P0_DP<23>")
	)
	(segment
		(start 111.033052 -211.767928)
		(end 111.033306 -211.768182)
		(width 0.14732)
		(layer "In4.Cu")
		(net "UPI_CPU0_CPU1_P1P0_DP<23>")
	)
	(segment
		(start 228.065076 -162.762692)
		(end 227.886768 -162.656266)
		(width 0.14732)
		(layer "In4.Cu")
		(net "UPI_CPU0_CPU1_P1P0_DP<23>")
	)
	(segment
		(start 360.145584 -214.707978)
		(end 360.145584 -214.537798)
		(width 0.0889)
		(layer "In4.Cu")
		(net "UPI_CPU0_CPU1_P1P0_DP<23>")
	)
	(segment
		(start 228.158294 -160.132014)
		(end 228.743764 -162.438588)
		(width 0.14732)
		(layer "In4.Cu")
		(net "UPI_CPU0_CPU1_P1P0_DP<23>")
	)
	(segment
		(start 126.971298 -185.508138)
		(end 126.965202 -185.71591)
		(width 0.14732)
		(layer "In4.Cu")
		(net "UPI_CPU0_CPU1_P1P0_DP<23>")
	)
	(segment
		(start 221.419166 -161.841942)
		(end 222.00489 -164.14877)
		(width 0.14732)
		(layer "In4.Cu")
		(net "UPI_CPU0_CPU1_P1P0_DP<23>")
	)
	(segment
		(start 221.325948 -164.47262)
		(end 221.14764 -164.366194)
		(width 0.14732)
		(layer "In4.Cu")
		(net "UPI_CPU0_CPU1_P1P0_DP<23>")
	)
	(segment
		(start 129.54508 -182.771034)
		(end 129.109978 -182.758842)
		(width 0.14732)
		(layer "In4.Cu")
		(net "UPI_CPU0_CPU1_P1P0_DP<23>")
	)
	(segment
		(start 129.109978 -182.758842)
		(end 128.515364 -183.31942)
		(width 0.14732)
		(layer "In4.Cu")
		(net "UPI_CPU0_CPU1_P1P0_DP<23>")
	)
	(segment
		(start 360.438192 -213.786974)
		(end 360.438192 -213.37778)
		(width 0.0889)
		(layer "In4.Cu")
		(net "UPI_CPU0_CPU1_P1P0_DP<23>")
	)
	(segment
		(start 126.32817 -186.115452)
		(end 126.1745 -185.952638)
		(width 0.14732)
		(layer "In4.Cu")
		(net "UPI_CPU0_CPU1_P1P0_DP<23>")
	)
	(segment
		(start 360.438192 -213.0044)
		(end 360.438192 -212.76056)
		(width 0.0889)
		(layer "In4.Cu")
		(net "UPI_CPU0_CPU1_P1P0_DP<23>")
	)
	(segment
		(start 217.405966 -165.46703)
		(end 216.833196 -165.612572)
		(width 0.14732)
		(layer "In4.Cu")
		(net "UPI_CPU0_CPU1_P1P0_DP<23>")
	)
	(segment
		(start 342.461596 -178.718464)
		(end 340.171532 -177.132742)
		(width 0.14732)
		(layer "In4.Cu")
		(net "UPI_CPU0_CPU1_P1P0_DP<23>")
	)
	(segment
		(start 360.438192 -213.37778)
		(end 360.537252 -213.27872)
		(width 0.0889)
		(layer "In4.Cu")
		(net "UPI_CPU0_CPU1_P1P0_DP<23>")
	)
	(segment
		(start 131.591558 -181.349142)
		(end 131.38404 -181.343046)
		(width 0.14732)
		(layer "In4.Cu")
		(net "UPI_CPU0_CPU1_P1P0_DP<23>")
	)
	(segment
		(start 226.39147 -163.187126)
		(end 225.8187 -163.332668)
		(width 0.14732)
		(layer "In4.Cu")
		(net "UPI_CPU0_CPU1_P1P0_DP<23>")
	)
	(segment
		(start 215.159336 -166.037006)
		(end 214.58682 -166.182548)
		(width 0.14732)
		(layer "In4.Cu")
		(net "UPI_CPU0_CPU1_P1P0_DP<23>")
	)
	(segment
		(start 214.408512 -166.076122)
		(end 213.822788 -163.769294)
		(width 0.14732)
		(layer "In4.Cu")
		(net "UPI_CPU0_CPU1_P1P0_DP<23>")
	)
	(segment
		(start 360.336592 -216.577164)
		(end 360.335576 -216.576656)
		(width 0.0889)
		(layer "In4.Cu")
		(net "UPI_CPU0_CPU1_P1P0_DP<23>")
	)
	(segment
		(start 123.62307 -187.938156)
		(end 116.016024 -197.379336)
		(width 0.14732)
		(layer "In4.Cu")
		(net "UPI_CPU0_CPU1_P1P0_DP<23>")
	)
	(segment
		(start 223.394016 -163.796218)
		(end 222.808292 -161.489898)
		(width 0.14732)
		(layer "In4.Cu")
		(net "UPI_CPU0_CPU1_P1P0_DP<23>")
	)
	(segment
		(start 219.396056 -162.03803)
		(end 219.17279 -162.411918)
		(width 0.14732)
		(layer "In4.Cu")
		(net "UPI_CPU0_CPU1_P1P0_DP<23>")
	)
	(segment
		(start 114.529108 -201.58329)
		(end 114.527584 -201.587862)
		(width 0.14732)
		(layer "In4.Cu")
		(net "UPI_CPU0_CPU1_P1P0_DP<23>")
	)
	(segment
		(start 360.438192 -211.965032)
		(end 360.480356 -211.922868)
		(width 0.0889)
		(layer "In4.Cu")
		(net "UPI_CPU0_CPU1_P1P0_DP<23>")
	)
	(segment
		(start 218.31554 -162.62985)
		(end 217.941652 -162.406584)
		(width 0.14732)
		(layer "In4.Cu")
		(net "UPI_CPU0_CPU1_P1P0_DP<23>")
	)
	(segment
		(start 217.14968 -162.608006)
		(end 216.926414 -162.981894)
		(width 0.14732)
		(layer "In4.Cu")
		(net "UPI_CPU0_CPU1_P1P0_DP<23>")
	)
	(segment
		(start 347.096842 -183.378348)
		(end 342.461596 -178.718464)
		(width 0.14732)
		(layer "In4.Cu")
		(net "UPI_CPU0_CPU1_P1P0_DP<23>")
	)
	(segment
		(start 130.341878 -182.326534)
		(end 130.335782 -182.534306)
		(width 0.14732)
		(layer "In4.Cu")
		(net "UPI_CPU0_CPU1_P1P0_DP<23>")
	)
	(segment
		(start 302.489108 -167.541194)
		(end 280.281888 -167.9194)
		(width 0.14732)
		(layer "In4.Cu")
		(net "UPI_CPU0_CPU1_P1P0_DP<23>")
	)
	(segment
		(start 360.480356 -211.922868)
		(end 360.480356 -211.90077)
		(width 0.0889)
		(layer "In4.Cu")
		(net "UPI_CPU0_CPU1_P1P0_DP<23>")
	)
	(segment
		(start 360.145584 -216.259156)
		(end 360.145584 -216.241884)
		(width 0.0889)
		(layer "In4.Cu")
		(net "UPI_CPU0_CPU1_P1P0_DP<23>")
	)
	(segment
		(start 214.58682 -166.182548)
		(end 214.408512 -166.076122)
		(width 0.14732)
		(layer "In4.Cu")
		(net "UPI_CPU0_CPU1_P1P0_DP<23>")
	)
	(segment
		(start 220.188028 -161.836608)
		(end 219.396056 -162.03803)
		(width 0.14732)
		(layer "In4.Cu")
		(net "UPI_CPU0_CPU1_P1P0_DP<23>")
	)
	(segment
		(start 111.033306 -211.768182)
		(end 111.033306 -212.02015)
		(width 0.14732)
		(layer "In4.Cu")
		(net "UPI_CPU0_CPU1_P1P0_DP<23>")
	)
	(segment
		(start 116.016024 -197.379336)
		(end 114.529108 -201.58329)
		(width 0.14732)
		(layer "In4.Cu")
		(net "UPI_CPU0_CPU1_P1P0_DP<23>")
	)
	(segment
		(start 360.520234 -217.878406)
		(end 360.36377 -218.149424)
		(width 0.0889)
		(layer "In4.Cu")
		(net "UPI_CPU0_CPU1_P1P0_DP<23>")
	)
	(segment
		(start 128.220978 -184.530746)
		(end 128.01346 -184.52465)
		(width 0.14732)
		(layer "In4.Cu")
		(net "UPI_CPU0_CPU1_P1P0_DP<23>")
	)
	(segment
		(start 360.537252 -212.48624)
		(end 360.438192 -212.38718)
		(width 0.0889)
		(layer "In4.Cu")
		(net "UPI_CPU0_CPU1_P1P0_DP<23>")
	)
	(segment
		(start 360.438192 -212.76056)
		(end 360.537252 -212.6615)
		(width 0.0889)
		(layer "In4.Cu")
		(net "UPI_CPU0_CPU1_P1P0_DP<23>")
	)
	(segment
		(start 111.033052 -211.468208)
		(end 111.033052 -211.767928)
		(width 0.14732)
		(layer "In4.Cu")
		(net "UPI_CPU0_CPU1_P1P0_DP<23>")
	)
	(segment
		(start 198.00697 -167.527478)
		(end 194.928744 -167.914828)
		(width 0.14732)
		(layer "In4.Cu")
		(net "UPI_CPU0_CPU1_P1P0_DP<23>")
	)
	(segment
		(start 360.537252 -213.27872)
		(end 360.537252 -213.10346)
		(width 0.0889)
		(layer "In4.Cu")
		(net "UPI_CPU0_CPU1_P1P0_DP<23>")
	)
	(segment
		(start 131.873752 -180.573426)
		(end 132.027168 -180.735732)
		(width 0.14732)
		(layer "In4.Cu")
		(net "UPI_CPU0_CPU1_P1P0_DP<23>")
	)
	(segment
		(start 349.31096 -186.631834)
		(end 347.096842 -183.378348)
		(width 0.14732)
		(layer "In4.Cu")
		(net "UPI_CPU0_CPU1_P1P0_DP<23>")
	)
	(segment
		(start 360.537252 -212.6615)
		(end 360.537252 -212.48624)
		(width 0.0889)
		(layer "In4.Cu")
		(net "UPI_CPU0_CPU1_P1P0_DP<23>")
	)
	(segment
		(start 128.503172 -183.75503)
		(end 128.656588 -183.917336)
		(width 0.14732)
		(layer "In4.Cu")
		(net "UPI_CPU0_CPU1_P1P0_DP<23>")
	)
	(segment
		(start 131.38404 -181.343046)
		(end 131.23037 -181.180232)
		(width 0.14732)
		(layer "In4.Cu")
		(net "UPI_CPU0_CPU1_P1P0_DP<23>")
	)
	(segment
		(start 227.301044 -160.349946)
		(end 226.926902 -160.12668)
		(width 0.14732)
		(layer "In4.Cu")
		(net "UPI_CPU0_CPU1_P1P0_DP<23>")
	)
	(segment
		(start 149.20976 -170.321478)
		(end 134.127494 -178.02352)
		(width 0.14732)
		(layer "In4.Cu")
		(net "UPI_CPU0_CPU1_P1P0_DP<23>")
	)
	(segment
		(start 226.926902 -160.12668)
		(end 226.135184 -160.328356)
		(width 0.14732)
		(layer "In4.Cu")
		(net "UPI_CPU0_CPU1_P1P0_DP<23>")
	)
	(segment
		(start 216.926414 -162.981894)
		(end 217.512138 -165.288976)
		(width 0.14732)
		(layer "In4.Cu")
		(net "UPI_CPU0_CPU1_P1P0_DP<23>")
	)
	(segment
		(start 219.17279 -162.411918)
		(end 219.758514 -164.718746)
		(width 0.14732)
		(layer "In4.Cu")
		(net "UPI_CPU0_CPU1_P1P0_DP<23>")
	)
	(segment
		(start 126.535688 -186.121548)
		(end 126.32817 -186.115452)
		(width 0.14732)
		(layer "In4.Cu")
		(net "UPI_CPU0_CPU1_P1P0_DP<23>")
	)
	(segment
		(start 360.480102 -204.473302)
		(end 355.866446 -193.33464)
		(width 0.14732)
		(layer "In4.Cu")
		(net "UPI_CPU0_CPU1_P1P0_DP<23>")
	)
	(segment
		(start 360.335576 -216.576656)
		(end 360.332782 -216.574878)
		(width 0.0889)
		(layer "In4.Cu")
		(net "UPI_CPU0_CPU1_P1P0_DP<23>")
	)
	(segment
		(start 216.069164 -163.199826)
		(end 215.695276 -162.97656)
		(width 0.14732)
		(layer "In4.Cu")
		(net "UPI_CPU0_CPU1_P1P0_DP<23>")
	)
	(segment
		(start 226.497642 -163.009072)
		(end 226.391216 -163.187126)
		(width 0.14732)
		(layer "In4.Cu")
		(net "UPI_CPU0_CPU1_P1P0_DP<23>")
	)
	(segment
		(start 360.145584 -214.537798)
		(end 360.14533 -214.537798)
		(width 0.0889)
		(layer "In4.Cu")
		(net "UPI_CPU0_CPU1_P1P0_DP<23>")
	)
	(segment
		(start 132.027168 -180.735732)
		(end 132.021072 -180.943504)
		(width 0.14732)
		(layer "In4.Cu")
		(net "UPI_CPU0_CPU1_P1P0_DP<23>")
	)
	(segment
		(start 214.680038 -163.55187)
		(end 215.265762 -165.858698)
		(width 0.14732)
		(layer "In4.Cu")
		(net "UPI_CPU0_CPU1_P1P0_DP<23>")
	)
	(segment
		(start 215.695276 -162.97656)
		(end 214.903304 -163.177982)
		(width 0.14732)
		(layer "In4.Cu")
		(net "UPI_CPU0_CPU1_P1P0_DP<23>")
	)
	(segment
		(start 217.405712 -165.46703)
		(end 217.405966 -165.46703)
		(width 0.14732)
		(layer "In4.Cu")
		(net "UPI_CPU0_CPU1_P1P0_DP<23>")
	)
	(segment
		(start 128.515364 -183.31942)
		(end 128.503172 -183.75503)
		(width 0.14732)
		(layer "In4.Cu")
		(net "UPI_CPU0_CPU1_P1P0_DP<23>")
	)
	(segment
		(start 128.656588 -183.917336)
		(end 128.650492 -184.125108)
		(width 0.14732)
		(layer "In4.Cu")
		(net "UPI_CPU0_CPU1_P1P0_DP<23>")
	)
	(segment
		(start 129.906268 -182.939944)
		(end 129.69875 -182.933848)
		(width 0.14732)
		(layer "In4.Cu")
		(net "UPI_CPU0_CPU1_P1P0_DP<23>")
	)
	(segment
		(start 360.537252 -213.10346)
		(end 360.438192 -213.0044)
		(width 0.0889)
		(layer "In4.Cu")
		(net "UPI_CPU0_CPU1_P1P0_DP<23>")
	)
	(segment
		(start 360.480356 -211.90077)
		(end 360.480356 -211.681822)
		(width 0.14732)
		(layer "In4.Cu")
		(net "UPI_CPU0_CPU1_P1P0_DP<23>")
	)
	(segment
		(start 111.075216 -212.084158)
		(end 111.075216 -214.642446)
		(width 0.0889)
		(layer "In4.Cu")
		(net "UPI_CPU0_CPU1_P1P0_DP<23>")
	)
	(segment
		(start 355.866446 -193.33464)
		(end 349.31096 -186.631834)
		(width 0.14732)
		(layer "In4.Cu")
		(net "UPI_CPU0_CPU1_P1P0_DP<23>")
	)
	(segment
		(start 225.911664 -160.701736)
		(end 226.497642 -163.009072)
		(width 0.14732)
		(layer "In4.Cu")
		(net "UPI_CPU0_CPU1_P1P0_DP<23>")
	)
	(segment
		(start 189.34938 -167.914828)
		(end 155.774898 -168.665144)
		(width 0.14732)
		(layer "In4.Cu")
		(net "UPI_CPU0_CPU1_P1P0_DP<23>")
	)
	(segment
		(start 226.391216 -163.187126)
		(end 226.39147 -163.187126)
		(width 0.14732)
		(layer "In4.Cu")
		(net "UPI_CPU0_CPU1_P1P0_DP<23>")
	)
	(segment
		(start 127.85979 -184.361836)
		(end 127.424688 -184.349644)
		(width 0.14732)
		(layer "In4.Cu")
		(net "UPI_CPU0_CPU1_P1P0_DP<23>")
	)
	(segment
		(start 125.739144 -185.940446)
		(end 123.62307 -187.938156)
		(width 0.14732)
		(layer "In4.Cu")
		(net "UPI_CPU0_CPU1_P1P0_DP<23>")
	)
	(segment
		(start 222.00489 -164.14877)
		(end 221.898464 -164.327078)
		(width 0.14732)
		(layer "In4.Cu")
		(net "UPI_CPU0_CPU1_P1P0_DP<23>")
	)
	(segment
		(start 360.324146 -217.559128)
		(end 360.333036 -217.554048)
		(width 0.0889)
		(layer "In4.Cu")
		(net "UPI_CPU0_CPU1_P1P0_DP<23>")
	)
	(segment
		(start 275.890228 -167.9194)
		(end 237.404402 -158.034228)
		(width 0.14732)
		(layer "In4.Cu")
		(net "UPI_CPU0_CPU1_P1P0_DP<23>")
	)
	(segment
		(start 221.14764 -164.366194)
		(end 220.561916 -162.059874)
		(width 0.14732)
		(layer "In4.Cu")
		(net "UPI_CPU0_CPU1_P1P0_DP<23>")
	)
	(segment
		(start 110.896654 -216.569798)
		(end 110.887764 -216.574878)
		(width 0.0889)
		(layer "In4.Cu")
		(net "UPI_CPU0_CPU1_P1P0_DP<23>")
	)
	(segment
		(start 237.404402 -158.034228)
		(end 234.82935 -158.034228)
		(width 0.14732)
		(layer "In4.Cu")
		(net "UPI_CPU0_CPU1_P1P0_DP<23>")
	)
	(segment
		(start 110.8329 -217.518234)
		(end 110.85703 -217.607388)
		(width 0.0889)
		(layer "In4.Cu")
		(net "UPI_CPU0_CPU1_P1P0_DP<23>")
	)
	(segment
		(start 216.654888 -165.506146)
		(end 216.069164 -163.199826)
		(width 0.14732)
		(layer "In4.Cu")
		(net "UPI_CPU0_CPU1_P1P0_DP<23>")
	)
	(segment
		(start 224.14484 -163.757102)
		(end 223.572324 -163.902644)
		(width 0.14732)
		(layer "In4.Cu")
		(net "UPI_CPU0_CPU1_P1P0_DP<23>")
	)
	(segment
		(start 126.1745 -185.952638)
		(end 125.739144 -185.940446)
		(width 0.14732)
		(layer "In4.Cu")
		(net "UPI_CPU0_CPU1_P1P0_DP<23>")
	)
	(segment
		(start 217.512138 -165.288976)
		(end 217.405712 -165.46703)
		(width 0.14732)
		(layer "In4.Cu")
		(net "UPI_CPU0_CPU1_P1P0_DP<23>")
	)
	(segment
		(start 332.606904 -173.846744)
		(end 319.795398 -169.31767)
		(width 0.14732)
		(layer "In4.Cu")
		(net "UPI_CPU0_CPU1_P1P0_DP<23>")
	)
	(segment
		(start 214.903304 -163.177982)
		(end 214.680038 -163.55187)
		(width 0.14732)
		(layer "In4.Cu")
		(net "UPI_CPU0_CPU1_P1P0_DP<23>")
	)
	(segment
		(start 229.656386 -159.367728)
		(end 228.377496 -159.76473)
		(width 0.14732)
		(layer "In4.Cu")
		(net "UPI_CPU0_CPU1_P1P0_DP<23>")
	)
	(segment
		(start 360.438192 -212.38718)
		(end 360.438192 -211.965032)
		(width 0.0889)
		(layer "In4.Cu")
		(net "UPI_CPU0_CPU1_P1P0_DP<23>")
	)
	(segment
		(start 222.434404 -161.266632)
		(end 221.642432 -161.468054)
		(width 0.14732)
		(layer "In4.Cu")
		(net "UPI_CPU0_CPU1_P1P0_DP<23>")
	)
	(segment
		(start 223.572324 -163.902644)
		(end 223.394016 -163.796218)
		(width 0.14732)
		(layer "In4.Cu")
		(net "UPI_CPU0_CPU1_P1P0_DP<23>")
	)
	(segment
		(start 129.69875 -182.933848)
		(end 129.54508 -182.771034)
		(width 0.14732)
		(layer "In4.Cu")
		(net "UPI_CPU0_CPU1_P1P0_DP<23>")
	)
	(segment
		(start 360.480356 -211.681822)
		(end 360.480102 -211.681568)
		(width 0.14732)
		(layer "In4.Cu")
		(net "UPI_CPU0_CPU1_P1P0_DP<23>")
	)
	(arc
		(start 110.605316 -217.082878)
		(mid 110.664466 -217.316965)
		(end 110.815882 -217.505026)
		(width 0.0889)
		(layer "In4.Cu")
		(net "UPI_CPU0_CPU1_P1P0_DP<23>")
	)
	(arc
		(start 360.615484 -217.064336)
		(mid 360.541493 -216.78477)
		(end 360.338878 -216.578434)
		(width 0.0889)
		(layer "In4.Cu")
		(net "UPI_CPU0_CPU1_P1P0_DP<23>")
	)
	(arc
		(start 360.333036 -217.554048)
		(mid 360.534492 -217.356623)
		(end 360.615484 -217.086434)
		(width 0.0889)
		(layer "In4.Cu")
		(net "UPI_CPU0_CPU1_P1P0_DP<23>")
	)
	(arc
		(start 111.07547 -214.643208)
		(mid 111.098953 -214.767585)
		(end 111.166148 -214.874856)
		(width 0.0889)
		(layer "In4.Cu")
		(net "UPI_CPU0_CPU1_P1P0_DP<23>")
	)
	(arc
		(start 360.242104 -214.294212)
		(mid 360.387379 -214.058851)
		(end 360.438192 -213.786974)
		(width 0.0889)
		(layer "In4.Cu")
		(net "UPI_CPU0_CPU1_P1P0_DP<23>")
	)
	(arc
		(start 111.35741 -215.761062)
		(mid 111.154587 -215.961293)
		(end 111.075216 -216.235026)
		(width 0.0889)
		(layer "In4.Cu")
		(net "UPI_CPU0_CPU1_P1P0_DP<23>")
	)
	(arc
		(start 360.329734 -214.907114)
		(mid 360.220609 -214.823311)
		(end 360.145584 -214.707978)
		(width 0.0889)
		(layer "In4.Cu")
		(net "UPI_CPU0_CPU1_P1P0_DP<23>")
	)
	(arc
		(start 360.145584 -216.241884)
		(mid 360.197854 -216.059519)
		(end 360.332782 -215.926162)
		(width 0.0889)
		(layer "In4.Cu")
		(net "UPI_CPU0_CPU1_P1P0_DP<23>")
	)
	(arc
		(start 360.285538 -218.170252)
		(mid 360.182393 -218.040227)
		(end 360.145584 -217.878406)
		(width 0.0889)
		(layer "In4.Cu")
		(net "UPI_CPU0_CPU1_P1P0_DP<23>")
	)
	(arc
		(start 111.26724 -214.984076)
		(mid 111.331047 -215.045631)
		(end 111.401352 -215.099646)
		(width 0.0889)
		(layer "In4.Cu")
		(net "UPI_CPU0_CPU1_P1P0_DP<23>")
	)
	(arc
		(start 111.544862 -215.436704)
		(mid 111.497183 -215.619604)
		(end 111.3663 -215.755982)
		(width 0.0889)
		(layer "In4.Cu")
		(net "UPI_CPU0_CPU1_P1P0_DP<23>")
	)
	(arc
		(start 111.401352 -215.099646)
		(mid 111.481149 -215.171533)
		(end 111.539528 -215.261698)
		(width 0.0889)
		(layer "In4.Cu")
		(net "UPI_CPU0_CPU1_P1P0_DP<23>")
	)
	(arc
		(start 360.14533 -214.537798)
		(mid 360.171725 -214.407264)
		(end 360.242104 -214.294212)
		(width 0.0889)
		(layer "In4.Cu")
		(net "UPI_CPU0_CPU1_P1P0_DP<23>")
	)
	(arc
		(start 110.887764 -216.574878)
		(mid 110.683429 -216.777483)
		(end 110.605316 -217.05443)
		(width 0.0889)
		(layer "In4.Cu")
		(net "UPI_CPU0_CPU1_P1P0_DP<23>")
	)
	(arc
		(start 110.815882 -217.505026)
		(mid 110.824328 -217.511711)
		(end 110.8329 -217.518234)
		(width 0.0889)
		(layer "In4.Cu")
		(net "UPI_CPU0_CPU1_P1P0_DP<23>")
	)
	(arc
		(start 360.332782 -216.574878)
		(mid 360.197849 -216.441524)
		(end 360.145584 -216.259156)
		(width 0.0889)
		(layer "In4.Cu")
		(net "UPI_CPU0_CPU1_P1P0_DP<23>")
	)
	(arc
		(start 111.075216 -216.25052)
		(mid 111.027537 -216.43342)
		(end 110.896654 -216.569798)
		(width 0.0889)
		(layer "In4.Cu")
		(net "UPI_CPU0_CPU1_P1P0_DP<23>")
	)
	(arc
		(start 360.145584 -217.878406)
		(mid 360.193263 -217.695506)
		(end 360.324146 -217.559128)
		(width 0.0889)
		(layer "In4.Cu")
		(net "UPI_CPU0_CPU1_P1P0_DP<23>")
	)
	(arc
		(start 360.61523 -215.23833)
		(mid 360.50381 -215.045711)
		(end 360.329734 -214.907114)
		(width 0.0889)
		(layer "In4.Cu")
		(net "UPI_CPU0_CPU1_P1P0_DP<23>")
	)
	(arc
		(start 360.332782 -215.926162)
		(mid 360.537117 -215.723557)
		(end 360.61523 -215.44661)
		(width 0.0889)
		(layer "In4.Cu")
		(net "UPI_CPU0_CPU1_P1P0_DP<23>")
	)
	(arc
		(start 111.539528 -215.261698)
		(mid 111.543592 -215.273716)
		(end 111.544862 -215.286336)
		(width 0.0889)
		(layer "In4.Cu")
		(net "UPI_CPU0_CPU1_P1P0_DP<23>")
	)
	(segment
		(start 361.45978 -217.87866)
		(end 361.460034 -217.878406)
		(width 0.13208)
		(layer "F.Cu")
		(net "UPI_CPU0_CPU1_P1P0_DP<22>")
	)
	(segment
		(start 109.760512 -218.414346)
		(end 109.760512 -217.87866)
		(width 0.13208)
		(layer "F.Cu")
		(net "UPI_CPU0_CPU1_P1P0_DP<22>")
	)
	(segment
		(start 361.45978 -218.414346)
		(end 361.45978 -217.87866)
		(width 0.13208)
		(layer "F.Cu")
		(net "UPI_CPU0_CPU1_P1P0_DP<22>")
	)
	(segment
		(start 109.760512 -217.87866)
		(end 109.760766 -217.878406)
		(width 0.13208)
		(layer "F.Cu")
		(net "UPI_CPU0_CPU1_P1P0_DP<22>")
	)
	(segment
		(start 137.644886 -175.29175)
		(end 137.44702 -175.227488)
		(width 0.14732)
		(layer "In4.Cu")
		(net "UPI_CPU0_CPU1_P1P0_DP<22>")
	)
	(segment
		(start 162.289744 -166.340028)
		(end 162.318192 -167.529256)
		(width 0.14732)
		(layer "In4.Cu")
		(net "UPI_CPU0_CPU1_P1P0_DP<22>")
	)
	(segment
		(start 163.408106 -166.00551)
		(end 162.590226 -166.025322)
		(width 0.14732)
		(layer "In4.Cu")
		(net "UPI_CPU0_CPU1_P1P0_DP<22>")
	)
	(segment
		(start 110.423198 -215.75776)
		(end 110.41761 -215.761062)
		(width 0.0889)
		(layer "In4.Cu")
		(net "UPI_CPU0_CPU1_P1P0_DP<22>")
	)
	(segment
		(start 347.968062 -183.172862)
		(end 347.64726 -182.701946)
		(width 0.14732)
		(layer "In4.Cu")
		(net "UPI_CPU0_CPU1_P1P0_DP<22>")
	)
	(segment
		(start 174.755556 -167.234362)
		(end 174.73422 -166.356284)
		(width 0.14732)
		(layer "In4.Cu")
		(net "UPI_CPU0_CPU1_P1P0_DP<22>")
	)
	(segment
		(start 110.135416 -214.694008)
		(end 110.13567 -214.694008)
		(width 0.0889)
		(layer "In4.Cu")
		(net "UPI_CPU0_CPU1_P1P0_DP<22>")
	)
	(segment
		(start 172.03547 -167.446198)
		(end 171.885102 -167.302434)
		(width 0.14732)
		(layer "In4.Cu")
		(net "UPI_CPU0_CPU1_P1P0_DP<22>")
	)
	(segment
		(start 332.949804 -173.074584)
		(end 320.058288 -168.520618)
		(width 0.14732)
		(layer "In4.Cu")
		(net "UPI_CPU0_CPU1_P1P0_DP<22>")
	)
	(segment
		(start 162.590226 -166.025322)
		(end 162.289744 -166.340028)
		(width 0.14732)
		(layer "In4.Cu")
		(net "UPI_CPU0_CPU1_P1P0_DP<22>")
	)
	(segment
		(start 159.539686 -165.141148)
		(end 159.598106 -167.593772)
		(width 0.14732)
		(layer "In4.Cu")
		(net "UPI_CPU0_CPU1_P1P0_DP<22>")
	)
	(segment
		(start 160.658048 -164.80663)
		(end 159.840168 -164.826442)
		(width 0.14732)
		(layer "In4.Cu")
		(net "UPI_CPU0_CPU1_P1P0_DP<22>")
	)
	(segment
		(start 361.272582 -216.574878)
		(end 361.263692 -216.569798)
		(width 0.0889)
		(layer "In4.Cu")
		(net "UPI_CPU0_CPU1_P1P0_DP<22>")
	)
	(segment
		(start 166.71163 -167.425116)
		(end 166.706296 -167.21074)
		(width 0.14732)
		(layer "In4.Cu")
		(net "UPI_CPU0_CPU1_P1P0_DP<22>")
	)
	(segment
		(start 171.862496 -166.362888)
		(end 171.547536 -166.062406)
		(width 0.14732)
		(layer "In4.Cu")
		(net "UPI_CPU0_CPU1_P1P0_DP<22>")
	)
	(segment
		(start 109.91723 -218.149424)
		(end 109.760766 -217.878406)
		(width 0.0889)
		(layer "In4.Cu")
		(net "UPI_CPU0_CPU1_P1P0_DP<22>")
	)
	(segment
		(start 163.75126 -167.49522)
		(end 163.722812 -166.305992)
		(width 0.14732)
		(layer "In4.Cu")
		(net "UPI_CPU0_CPU1_P1P0_DP<22>")
	)
	(segment
		(start 112.358678 -204.845666)
		(end 111.378746 -207.616044)
		(width 0.14732)
		(layer "In4.Cu")
		(net "UPI_CPU0_CPU1_P1P0_DP<22>")
	)
	(segment
		(start 349.16491 -184.536588)
		(end 349.089726 -184.422542)
		(width 0.14732)
		(layer "In4.Cu")
		(net "UPI_CPU0_CPU1_P1P0_DP<22>")
	)
	(segment
		(start 177.051208 -166.301166)
		(end 176.736502 -166.000684)
		(width 0.14732)
		(layer "In4.Cu")
		(net "UPI_CPU0_CPU1_P1P0_DP<22>")
	)
	(segment
		(start 356.552246 -192.81394)
		(end 350.661478 -186.809888)
		(width 0.14732)
		(layer "In4.Cu")
		(net "UPI_CPU0_CPU1_P1P0_DP<22>")
	)
	(segment
		(start 110.03661 -213.106)
		(end 110.13567 -213.20506)
		(width 0.0889)
		(layer "In4.Cu")
		(net "UPI_CPU0_CPU1_P1P0_DP<22>")
	)
	(segment
		(start 110.627668 -209.739738)
		(end 110.627414 -209.7405)
		(width 0.14732)
		(layer "In4.Cu")
		(net "UPI_CPU0_CPU1_P1P0_DP<22>")
	)
	(segment
		(start 361.741974 -214.064088)
		(end 361.73791 -214.061802)
		(width 0.0889)
		(layer "In4.Cu")
		(net "UPI_CPU0_CPU1_P1P0_DP<22>")
	)
	(segment
		(start 162.318192 -167.529256)
		(end 162.174428 -167.679624)
		(width 0.14732)
		(layer "In4.Cu")
		(net "UPI_CPU0_CPU1_P1P0_DP<22>")
	)
	(segment
		(start 361.73791 -214.061802)
		(end 361.729274 -214.056722)
		(width 0.0889)
		(layer "In4.Cu")
		(net "UPI_CPU0_CPU1_P1P0_DP<22>")
	)
	(segment
		(start 361.583986 -204.96149)
		(end 356.552246 -192.81394)
		(width 0.14732)
		(layer "In4.Cu")
		(net "UPI_CPU0_CPU1_P1P0_DP<22>")
	)
	(segment
		(start 177.222912 -167.323008)
		(end 177.072544 -167.179244)
		(width 0.14732)
		(layer "In4.Cu")
		(net "UPI_CPU0_CPU1_P1P0_DP<22>")
	)
	(segment
		(start 146.713702 -170.495722)
		(end 146.64944 -170.693588)
		(width 0.14732)
		(layer "In4.Cu")
		(net "UPI_CPU0_CPU1_P1P0_DP<22>")
	)
	(segment
		(start 340.64702 -176.424844)
		(end 340.624414 -176.409096)
		(width 0.14732)
		(layer "In4.Cu")
		(net "UPI_CPU0_CPU1_P1P0_DP<22>")
	)
	(segment
		(start 148.188172 -169.907966)
		(end 147.990306 -169.843704)
		(width 0.14732)
		(layer "In4.Cu")
		(net "UPI_CPU0_CPU1_P1P0_DP<22>")
	)
	(segment
		(start 158.655766 -165.16223)
		(end 158.34106 -164.861748)
		(width 0.14732)
		(layer "In4.Cu")
		(net "UPI_CPU0_CPU1_P1P0_DP<22>")
	)
	(segment
		(start 110.09376 -211.628482)
		(end 110.09376 -212.03285)
		(width 0.14732)
		(layer "In4.Cu")
		(net "UPI_CPU0_CPU1_P1P0_DP<22>")
	)
	(segment
		(start 361.263692 -215.931242)
		(end 361.272582 -215.926162)
		(width 0.0889)
		(layer "In4.Cu")
		(net "UPI_CPU0_CPU1_P1P0_DP<22>")
	)
	(segment
		(start 189.316106 -167.035734)
		(end 177.222912 -167.323008)
		(width 0.14732)
		(layer "In4.Cu")
		(net "UPI_CPU0_CPU1_P1P0_DP<22>")
	)
	(segment
		(start 166.861998 -167.56888)
		(end 166.71163 -167.425116)
		(width 0.14732)
		(layer "In4.Cu")
		(net "UPI_CPU0_CPU1_P1P0_DP<22>")
	)
	(segment
		(start 348.49435 -183.815228)
		(end 347.968062 -183.172862)
		(width 0.14732)
		(layer "In4.Cu")
		(net "UPI_CPU0_CPU1_P1P0_DP<22>")
	)
	(segment
		(start 151.756872 -168.80967)
		(end 151.57831 -168.702736)
		(width 0.14732)
		(layer "In4.Cu")
		(net "UPI_CPU0_CPU1_P1P0_DP<22>")
	)
	(segment
		(start 112.360202 -204.841094)
		(end 112.358678 -204.845666)
		(width 0.14732)
		(layer "In4.Cu")
		(net "UPI_CPU0_CPU1_P1P0_DP<22>")
	)
	(segment
		(start 362.012484 -214.752682)
		(end 362.012484 -214.546434)
		(width 0.0889)
		(layer "In4.Cu")
		(net "UPI_CPU0_CPU1_P1P0_DP<22>")
	)
	(segment
		(start 152.01519 -165.562788)
		(end 151.791924 -165.936422)
		(width 0.14732)
		(layer "In4.Cu")
		(net "UPI_CPU0_CPU1_P1P0_DP<22>")
	)
	(segment
		(start 137.44702 -175.227488)
		(end 137.376662 -175.08982)
		(width 0.14732)
		(layer "In4.Cu")
		(net "UPI_CPU0_CPU1_P1P0_DP<22>")
	)
	(segment
		(start 171.885102 -167.302434)
		(end 171.862496 -166.362888)
		(width 0.14732)
		(layer "In4.Cu")
		(net "UPI_CPU0_CPU1_P1P0_DP<22>")
	)
	(segment
		(start 314.326524 -166.902892)
		(end 302.490632 -166.661592)
		(width 0.14732)
		(layer "In4.Cu")
		(net "UPI_CPU0_CPU1_P1P0_DP<22>")
	)
	(segment
		(start 361.555284 -217.07856)
		(end 361.555284 -217.064336)
		(width 0.0889)
		(layer "In4.Cu")
		(net "UPI_CPU0_CPU1_P1P0_DP<22>")
	)
	(segment
		(start 174.73422 -166.356284)
		(end 174.419514 -166.055802)
		(width 0.14732)
		(layer "In4.Cu")
		(net "UPI_CPU0_CPU1_P1P0_DP<22>")
	)
	(segment
		(start 170.42892 -166.397178)
		(end 170.452034 -167.33647)
		(width 0.14732)
		(layer "In4.Cu")
		(net "UPI_CPU0_CPU1_P1P0_DP<22>")
	)
	(segment
		(start 110.605062 -215.31834)
		(end 110.605062 -215.436704)
		(width 0.0889)
		(layer "In4.Cu")
		(net "UPI_CPU0_CPU1_P1P0_DP<22>")
	)
	(segment
		(start 152.808432 -165.362382)
		(end 152.01519 -165.562788)
		(width 0.14732)
		(layer "In4.Cu")
		(net "UPI_CPU0_CPU1_P1P0_DP<22>")
	)
	(segment
		(start 237.49381 -157.155134)
		(end 234.718098 -157.155134)
		(width 0.14732)
		(layer "In4.Cu")
		(net "UPI_CPU0_CPU1_P1P0_DP<22>")
	)
	(segment
		(start 165.134798 -167.60952)
		(end 163.901628 -167.638984)
		(width 0.14732)
		(layer "In4.Cu")
		(net "UPI_CPU0_CPU1_P1P0_DP<22>")
	)
	(segment
		(start 340.64702 -176.425098)
		(end 340.64702 -176.424844)
		(width 0.14732)
		(layer "In4.Cu")
		(net "UPI_CPU0_CPU1_P1P0_DP<22>")
	)
	(segment
		(start 159.840168 -164.826442)
		(end 159.539686 -165.141148)
		(width 0.14732)
		(layer "In4.Cu")
		(net "UPI_CPU0_CPU1_P1P0_DP<22>")
	)
	(segment
		(start 175.918622 -166.020496)
		(end 175.618394 -166.335202)
		(width 0.14732)
		(layer "In4.Cu")
		(net "UPI_CPU0_CPU1_P1P0_DP<22>")
	)
	(segment
		(start 110.135416 -216.235026)
		(end 110.135416 -216.25052)
		(width 0.0889)
		(layer "In4.Cu")
		(net "UPI_CPU0_CPU1_P1P0_DP<22>")
	)
	(segment
		(start 194.873372 -167.035734)
		(end 189.316106 -167.035734)
		(width 0.14732)
		(layer "In4.Cu")
		(net "UPI_CPU0_CPU1_P1P0_DP<22>")
	)
	(segment
		(start 110.09376 -212.03285)
		(end 110.09376 -212.054948)
		(width 0.0889)
		(layer "In4.Cu")
		(net "UPI_CPU0_CPU1_P1P0_DP<22>")
	)
	(segment
		(start 197.841616 -166.6621)
		(end 194.873372 -167.035734)
		(width 0.14732)
		(layer "In4.Cu")
		(net "UPI_CPU0_CPU1_P1P0_DP<22>")
	)
	(segment
		(start 110.03661 -212.93074)
		(end 110.03661 -213.106)
		(width 0.0889)
		(layer "In4.Cu")
		(net "UPI_CPU0_CPU1_P1P0_DP<22>")
	)
	(segment
		(start 110.03661 -213.6394)
		(end 110.03661 -213.81466)
		(width 0.0889)
		(layer "In4.Cu")
		(net "UPI_CPU0_CPU1_P1P0_DP<22>")
	)
	(segment
		(start 170.452034 -167.33647)
		(end 170.30827 -167.486838)
		(width 0.14732)
		(layer "In4.Cu")
		(net "UPI_CPU0_CPU1_P1P0_DP<22>")
	)
	(segment
		(start 154.00401 -168.242488)
		(end 153.825448 -168.135554)
		(width 0.14732)
		(layer "In4.Cu")
		(net "UPI_CPU0_CPU1_P1P0_DP<22>")
	)
	(segment
		(start 361.284774 -216.58199)
		(end 361.272582 -216.574878)
		(width 0.0889)
		(layer "In4.Cu")
		(net "UPI_CPU0_CPU1_P1P0_DP<22>")
	)
	(segment
		(start 160.972754 -165.107112)
		(end 160.658048 -164.80663)
		(width 0.14732)
		(layer "In4.Cu")
		(net "UPI_CPU0_CPU1_P1P0_DP<22>")
	)
	(segment
		(start 340.624414 -176.409096)
		(end 332.95844 -173.078394)
		(width 0.14732)
		(layer "In4.Cu")
		(net "UPI_CPU0_CPU1_P1P0_DP<22>")
	)
	(segment
		(start 149.973538 -166.94404)
		(end 149.750272 -167.317674)
		(width 0.14732)
		(layer "In4.Cu")
		(net "UPI_CPU0_CPU1_P1P0_DP<22>")
	)
	(segment
		(start 149.750272 -167.317674)
		(end 150.188422 -169.05351)
		(width 0.14732)
		(layer "In4.Cu")
		(net "UPI_CPU0_CPU1_P1P0_DP<22>")
	)
	(segment
		(start 110.09376 -212.054948)
		(end 110.13567 -212.096858)
		(width 0.0889)
		(layer "In4.Cu")
		(net "UPI_CPU0_CPU1_P1P0_DP<22>")
	)
	(segment
		(start 109.947964 -216.574878)
		(end 109.935772 -216.58199)
		(width 0.0889)
		(layer "In4.Cu")
		(net "UPI_CPU0_CPU1_P1P0_DP<22>")
	)
	(segment
		(start 150.76678 -166.743634)
		(end 149.973538 -166.94404)
		(width 0.14732)
		(layer "In4.Cu")
		(net "UPI_CPU0_CPU1_P1P0_DP<22>")
	)
	(segment
		(start 110.13567 -213.20506)
		(end 110.13567 -213.54034)
		(width 0.0889)
		(layer "In4.Cu")
		(net "UPI_CPU0_CPU1_P1P0_DP<22>")
	)
	(segment
		(start 280.180288 -167.045894)
		(end 276.00148 -167.045894)
		(width 0.14732)
		(layer "In4.Cu")
		(net "UPI_CPU0_CPU1_P1P0_DP<22>")
	)
	(segment
		(start 151.14016 -166.9669)
		(end 150.76678 -166.743634)
		(width 0.14732)
		(layer "In4.Cu")
		(net "UPI_CPU0_CPU1_P1P0_DP<22>")
	)
	(segment
		(start 343.0016 -178.074828)
		(end 340.64702 -176.425098)
		(width 0.14732)
		(layer "In4.Cu")
		(net "UPI_CPU0_CPU1_P1P0_DP<22>")
	)
	(segment
		(start 123.082812 -187.285884)
		(end 115.037616 -197.271132)
		(width 0.14732)
		(layer "In4.Cu")
		(net "UPI_CPU0_CPU1_P1P0_DP<22>")
	)
	(segment
		(start 111.378492 -207.616806)
		(end 111.234728 -208.023206)
		(width 0.14732)
		(layer "In4.Cu")
		(net "UPI_CPU0_CPU1_P1P0_DP<22>")
	)
	(segment
		(start 110.15853 -214.799926)
		(end 110.157768 -214.80018)
		(width 0.0889)
		(layer "In4.Cu")
		(net "UPI_CPU0_CPU1_P1P0_DP<22>")
	)
	(segment
		(start 152.43556 -168.486328)
		(end 152.328626 -168.665144)
		(width 0.14732)
		(layer "In4.Cu")
		(net "UPI_CPU0_CPU1_P1P0_DP<22>")
	)
	(segment
		(start 173.322488 -167.268398)
		(end 173.178724 -167.418766)
		(width 0.14732)
		(layer "In4.Cu")
		(net "UPI_CPU0_CPU1_P1P0_DP<22>")
	)
	(segment
		(start 147.53844 -168.95953)
		(end 147.12442 -168.825418)
		(width 0.14732)
		(layer "In4.Cu")
		(net "UPI_CPU0_CPU1_P1P0_DP<22>")
	)
	(segment
		(start 110.13567 -212.096858)
		(end 110.13567 -212.83168)
		(width 0.0889)
		(layer "In4.Cu")
		(net "UPI_CPU0_CPU1_P1P0_DP<22>")
	)
	(segment
		(start 136.170416 -175.879506)
		(end 136.106154 -176.077372)
		(width 0.14732)
		(layer "In4.Cu")
		(net "UPI_CPU0_CPU1_P1P0_DP<22>")
	)
	(segment
		(start 361.55503 -215.44661)
		(end 361.55503 -215.268048)
		(width 0.0889)
		(layer "In4.Cu")
		(net "UPI_CPU0_CPU1_P1P0_DP<22>")
	)
	(segment
		(start 350.661478 -186.809888)
		(end 349.165164 -184.536842)
		(width 0.14732)
		(layer "In4.Cu")
		(net "UPI_CPU0_CPU1_P1P0_DP<22>")
	)
	(segment
		(start 361.58424 -211.214462)
		(end 361.583986 -211.214208)
		(width 0.14732)
		(layer "In4.Cu")
		(net "UPI_CPU0_CPU1_P1P0_DP<22>")
	)
	(segment
		(start 162.174428 -167.679624)
		(end 161.181542 -167.7035)
		(width 0.14732)
		(layer "In4.Cu")
		(net "UPI_CPU0_CPU1_P1P0_DP<22>")
	)
	(segment
		(start 150.188422 -169.05351)
		(end 150.081488 -169.232072)
		(width 0.14732)
		(layer "In4.Cu")
		(net "UPI_CPU0_CPU1_P1P0_DP<22>")
	)
	(segment
		(start 110.13567 -214.693754)
		(end 110.135416 -214.694008)
		(width 0.0889)
		(layer "In4.Cu")
		(net "UPI_CPU0_CPU1_P1P0_DP<22>")
	)
	(segment
		(start 110.13567 -213.91372)
		(end 110.13567 -214.693754)
		(width 0.0889)
		(layer "In4.Cu")
		(net "UPI_CPU0_CPU1_P1P0_DP<22>")
	)
	(segment
		(start 115.037616 -197.271132)
		(end 112.360202 -204.841094)
		(width 0.14732)
		(layer "In4.Cu")
		(net "UPI_CPU0_CPU1_P1P0_DP<22>")
	)
	(segment
		(start 165.278562 -167.459152)
		(end 165.134798 -167.60952)
		(width 0.14732)
		(layer "In4.Cu")
		(net "UPI_CPU0_CPU1_P1P0_DP<22>")
	)
	(segment
		(start 111.23295 -208.02854)
		(end 110.627668 -209.739738)
		(width 0.14732)
		(layer "In4.Cu")
		(net "UPI_CPU0_CPU1_P1P0_DP<22>")
	)
	(segment
		(start 165.57371 -166.93007)
		(end 165.273228 -167.244776)
		(width 0.14732)
		(layer "In4.Cu")
		(net "UPI_CPU0_CPU1_P1P0_DP<22>")
	)
	(segment
		(start 153.181812 -165.585648)
		(end 152.808432 -165.362382)
		(width 0.14732)
		(layer "In4.Cu")
		(net "UPI_CPU0_CPU1_P1P0_DP<22>")
	)
	(segment
		(start 109.995462 -218.170252)
		(end 109.91723 -218.149424)
		(width 0.0889)
		(layer "In4.Cu")
		(net "UPI_CPU0_CPU1_P1P0_DP<22>")
	)
	(segment
		(start 159.454342 -167.74414)
		(end 158.864554 -167.758618)
		(width 0.14732)
		(layer "In4.Cu")
		(net "UPI_CPU0_CPU1_P1P0_DP<22>")
	)
	(segment
		(start 110.13567 -212.83168)
		(end 110.03661 -212.93074)
		(width 0.0889)
		(layer "In4.Cu")
		(net "UPI_CPU0_CPU1_P1P0_DP<22>")
	)
	(segment
		(start 161.181542 -167.7035)
		(end 161.031174 -167.559736)
		(width 0.14732)
		(layer "In4.Cu")
		(net "UPI_CPU0_CPU1_P1P0_DP<22>")
	)
	(segment
		(start 177.072544 -167.179244)
		(end 177.051208 -166.301166)
		(width 0.14732)
		(layer "In4.Cu")
		(net "UPI_CPU0_CPU1_P1P0_DP<22>")
	)
	(segment
		(start 159.598106 -167.593772)
		(end 159.454342 -167.74414)
		(width 0.14732)
		(layer "In4.Cu")
		(net "UPI_CPU0_CPU1_P1P0_DP<22>")
	)
	(segment
		(start 136.106154 -176.077372)
		(end 133.602984 -177.355754)
		(width 0.14732)
		(layer "In4.Cu")
		(net "UPI_CPU0_CPU1_P1P0_DP<22>")
	)
	(segment
		(start 158.714186 -167.614854)
		(end 158.655766 -165.16223)
		(width 0.14732)
		(layer "In4.Cu")
		(net "UPI_CPU0_CPU1_P1P0_DP<22>")
	)
	(segment
		(start 133.602984 -177.355754)
		(end 123.082812 -187.285884)
		(width 0.14732)
		(layer "In4.Cu")
		(net "UPI_CPU0_CPU1_P1P0_DP<22>")
	)
	(segment
		(start 158.864554 -167.758618)
		(end 158.714186 -167.614854)
		(width 0.14732)
		(layer "In4.Cu")
		(net "UPI_CPU0_CPU1_P1P0_DP<22>")
	)
	(segment
		(start 109.947964 -217.554048)
		(end 109.956854 -217.559128)
		(width 0.0889)
		(layer "In4.Cu")
		(net "UPI_CPU0_CPU1_P1P0_DP<22>")
	)
	(segment
		(start 176.736502 -166.000684)
		(end 175.918622 -166.020496)
		(width 0.14732)
		(layer "In4.Cu")
		(net "UPI_CPU0_CPU1_P1P0_DP<22>")
	)
	(segment
		(start 234.718098 -157.155134)
		(end 197.841616 -166.662354)
		(width 0.14732)
		(layer "In4.Cu")
		(net "UPI_CPU0_CPU1_P1P0_DP<22>")
	)
	(segment
		(start 111.234728 -208.023206)
		(end 111.23295 -208.02854)
		(width 0.14732)
		(layer "In4.Cu")
		(net "UPI_CPU0_CPU1_P1P0_DP<22>")
	)
	(segment
		(start 146.395948 -169.197528)
		(end 146.261836 -169.611548)
		(width 0.14732)
		(layer "In4.Cu")
		(net "UPI_CPU0_CPU1_P1P0_DP<22>")
	)
	(segment
		(start 157.222698 -165.196266)
		(end 157.281118 -167.64889)
		(width 0.14732)
		(layer "In4.Cu")
		(net "UPI_CPU0_CPU1_P1P0_DP<22>")
	)
	(segment
		(start 165.273228 -167.244776)
		(end 165.278562 -167.459152)
		(width 0.14732)
		(layer "In4.Cu")
		(net "UPI_CPU0_CPU1_P1P0_DP<22>")
	)
	(segment
		(start 173.301406 -166.39032)
		(end 173.322488 -167.268398)
		(width 0.14732)
		(layer "In4.Cu")
		(net "UPI_CPU0_CPU1_P1P0_DP<22>")
	)
	(segment
		(start 147.990306 -169.843704)
		(end 147.53844 -168.95953)
		(width 0.14732)
		(layer "In4.Cu")
		(net "UPI_CPU0_CPU1_P1P0_DP<22>")
	)
	(segment
		(start 174.419514 -166.055802)
		(end 173.601634 -166.075614)
		(width 0.14732)
		(layer "In4.Cu")
		(net "UPI_CPU0_CPU1_P1P0_DP<22>")
	)
	(segment
		(start 349.089726 -184.422542)
		(end 348.49435 -183.815228)
		(width 0.14732)
		(layer "In4.Cu")
		(net "UPI_CPU0_CPU1_P1P0_DP<22>")
	)
	(segment
		(start 146.64944 -170.693588)
		(end 137.644886 -175.29175)
		(width 0.14732)
		(layer "In4.Cu")
		(net "UPI_CPU0_CPU1_P1P0_DP<22>")
	)
	(segment
		(start 361.58424 -211.69249)
		(end 361.58424 -211.214462)
		(width 0.14732)
		(layer "In4.Cu")
		(net "UPI_CPU0_CPU1_P1P0_DP<22>")
	)
	(segment
		(start 361.542076 -211.756752)
		(end 361.58424 -211.714588)
		(width 0.0889)
		(layer "In4.Cu")
		(net "UPI_CPU0_CPU1_P1P0_DP<22>")
	)
	(segment
		(start 197.841616 -166.662354)
		(end 197.841616 -166.6621)
		(width 0.14732)
		(layer "In4.Cu")
		(net "UPI_CPU0_CPU1_P1P0_DP<22>")
	)
	(segment
		(start 173.601634 -166.075614)
		(end 173.301406 -166.39032)
		(width 0.14732)
		(layer "In4.Cu")
		(net "UPI_CPU0_CPU1_P1P0_DP<22>")
	)
	(segment
		(start 136.100058 -175.741838)
		(end 136.170416 -175.879506)
		(width 0.14732)
		(layer "In4.Cu")
		(net "UPI_CPU0_CPU1_P1P0_DP<22>")
	)
	(segment
		(start 173.178724 -167.418766)
		(end 172.03547 -167.446198)
		(width 0.14732)
		(layer "In4.Cu")
		(net "UPI_CPU0_CPU1_P1P0_DP<22>")
	)
	(segment
		(start 157.137354 -167.799258)
		(end 155.617926 -167.83558)
		(width 0.14732)
		(layer "In4.Cu")
		(net "UPI_CPU0_CPU1_P1P0_DP<22>")
	)
	(segment
		(start 361.542076 -213.738968)
		(end 361.542076 -211.756752)
		(width 0.0889)
		(layer "In4.Cu")
		(net "UPI_CPU0_CPU1_P1P0_DP<22>")
	)
	(segment
		(start 302.490632 -166.661592)
		(end 280.180288 -167.045894)
		(width 0.14732)
		(layer "In4.Cu")
		(net "UPI_CPU0_CPU1_P1P0_DP<22>")
	)
	(segment
		(start 332.95844 -173.07814)
		(end 332.949804 -173.074584)
		(width 0.14732)
		(layer "In4.Cu")
		(net "UPI_CPU0_CPU1_P1P0_DP<22>")
	)
	(segment
		(start 147.12442 -168.825418)
		(end 146.395948 -169.197528)
		(width 0.14732)
		(layer "In4.Cu")
		(net "UPI_CPU0_CPU1_P1P0_DP<22>")
	)
	(segment
		(start 166.39159 -166.910258)
		(end 165.57371 -166.93007)
		(width 0.14732)
		(layer "In4.Cu")
		(net "UPI_CPU0_CPU1_P1P0_DP<22>")
	)
	(segment
		(start 157.281118 -167.64889)
		(end 157.137354 -167.799258)
		(width 0.14732)
		(layer "In4.Cu")
		(net "UPI_CPU0_CPU1_P1P0_DP<22>")
	)
	(segment
		(start 170.729656 -166.082218)
		(end 170.42892 -166.397178)
		(width 0.14732)
		(layer "In4.Cu")
		(net "UPI_CPU0_CPU1_P1P0_DP<22>")
	)
	(segment
		(start 170.30827 -167.486838)
		(end 166.861998 -167.56888)
		(width 0.14732)
		(layer "In4.Cu")
		(net "UPI_CPU0_CPU1_P1P0_DP<22>")
	)
	(segment
		(start 174.905924 -167.378126)
		(end 174.755556 -167.234362)
		(width 0.14732)
		(layer "In4.Cu")
		(net "UPI_CPU0_CPU1_P1P0_DP<22>")
	)
	(segment
		(start 171.547536 -166.062406)
		(end 170.729656 -166.082218)
		(width 0.14732)
		(layer "In4.Cu")
		(net "UPI_CPU0_CPU1_P1P0_DP<22>")
	)
	(segment
		(start 110.093506 -211.628228)
		(end 110.09376 -211.628482)
		(width 0.14732)
		(layer "In4.Cu")
		(net "UPI_CPU0_CPU1_P1P0_DP<22>")
	)
	(segment
		(start 150.081488 -169.232072)
		(end 148.953728 -169.516806)
		(width 0.14732)
		(layer "In4.Cu")
		(net "UPI_CPU0_CPU1_P1P0_DP<22>")
	)
	(segment
		(start 155.617926 -167.83558)
		(end 154.00401 -168.242488)
		(width 0.14732)
		(layer "In4.Cu")
		(net "UPI_CPU0_CPU1_P1P0_DP<22>")
	)
	(segment
		(start 151.57831 -168.702736)
		(end 151.14016 -166.9669)
		(width 0.14732)
		(layer "In4.Cu")
		(net "UPI_CPU0_CPU1_P1P0_DP<22>")
	)
	(segment
		(start 175.618394 -166.335202)
		(end 175.639476 -167.21328)
		(width 0.14732)
		(layer "In4.Cu")
		(net "UPI_CPU0_CPU1_P1P0_DP<22>")
	)
	(segment
		(start 146.261836 -169.611548)
		(end 146.713702 -170.495722)
		(width 0.14732)
		(layer "In4.Cu")
		(net "UPI_CPU0_CPU1_P1P0_DP<22>")
	)
	(segment
		(start 361.460034 -217.878406)
		(end 361.444286 -217.851228)
		(width 0.0889)
		(layer "In4.Cu")
		(net "UPI_CPU0_CPU1_P1P0_DP<22>")
	)
	(segment
		(start 361.444286 -217.851228)
		(end 361.30357 -217.607388)
		(width 0.0889)
		(layer "In4.Cu")
		(net "UPI_CPU0_CPU1_P1P0_DP<22>")
	)
	(segment
		(start 153.825448 -168.135554)
		(end 153.181812 -165.585648)
		(width 0.14732)
		(layer "In4.Cu")
		(net "UPI_CPU0_CPU1_P1P0_DP<22>")
	)
	(segment
		(start 349.165164 -184.536842)
		(end 349.16491 -184.536588)
		(width 0.14732)
		(layer "In4.Cu")
		(net "UPI_CPU0_CPU1_P1P0_DP<22>")
	)
	(segment
		(start 152.328626 -168.665144)
		(end 151.756872 -168.80967)
		(width 0.14732)
		(layer "In4.Cu")
		(net "UPI_CPU0_CPU1_P1P0_DP<22>")
	)
	(segment
		(start 276.00148 -167.045894)
		(end 237.49381 -157.155134)
		(width 0.14732)
		(layer "In4.Cu")
		(net "UPI_CPU0_CPU1_P1P0_DP<22>")
	)
	(segment
		(start 136.23417 -175.327818)
		(end 136.100058 -175.741838)
		(width 0.14732)
		(layer "In4.Cu")
		(net "UPI_CPU0_CPU1_P1P0_DP<22>")
	)
	(segment
		(start 361.58424 -211.714588)
		(end 361.58424 -211.69249)
		(width 0.0889)
		(layer "In4.Cu")
		(net "UPI_CPU0_CPU1_P1P0_DP<22>")
	)
	(segment
		(start 137.376662 -175.08982)
		(end 136.962642 -174.955708)
		(width 0.14732)
		(layer "In4.Cu")
		(net "UPI_CPU0_CPU1_P1P0_DP<22>")
	)
	(segment
		(start 166.706296 -167.21074)
		(end 166.39159 -166.910258)
		(width 0.14732)
		(layer "In4.Cu")
		(net "UPI_CPU0_CPU1_P1P0_DP<22>")
	)
	(segment
		(start 332.95844 -173.078394)
		(end 332.95844 -173.07814)
		(width 0.14732)
		(layer "In4.Cu")
		(net "UPI_CPU0_CPU1_P1P0_DP<22>")
	)
	(segment
		(start 110.627414 -209.7405)
		(end 110.093506 -211.250022)
		(width 0.14732)
		(layer "In4.Cu")
		(net "UPI_CPU0_CPU1_P1P0_DP<22>")
	)
	(segment
		(start 110.13567 -213.54034)
		(end 110.03661 -213.6394)
		(width 0.0889)
		(layer "In4.Cu")
		(net "UPI_CPU0_CPU1_P1P0_DP<22>")
	)
	(segment
		(start 136.962642 -174.955708)
		(end 136.23417 -175.327818)
		(width 0.14732)
		(layer "In4.Cu")
		(net "UPI_CPU0_CPU1_P1P0_DP<22>")
	)
	(segment
		(start 109.665262 -217.064336)
		(end 109.665262 -217.071956)
		(width 0.0889)
		(layer "In4.Cu")
		(net "UPI_CPU0_CPU1_P1P0_DP<22>")
	)
	(segment
		(start 361.54233 -213.738968)
		(end 361.542076 -213.738968)
		(width 0.0889)
		(layer "In4.Cu")
		(net "UPI_CPU0_CPU1_P1P0_DP<22>")
	)
	(segment
		(start 161.031174 -167.559736)
		(end 160.972754 -165.107112)
		(width 0.14732)
		(layer "In4.Cu")
		(net "UPI_CPU0_CPU1_P1P0_DP<22>")
	)
	(segment
		(start 110.4265 -215.755982)
		(end 110.423198 -215.75776)
		(width 0.0889)
		(layer "In4.Cu")
		(net "UPI_CPU0_CPU1_P1P0_DP<22>")
	)
	(segment
		(start 175.495712 -167.363648)
		(end 174.905924 -167.378126)
		(width 0.14732)
		(layer "In4.Cu")
		(net "UPI_CPU0_CPU1_P1P0_DP<22>")
	)
	(segment
		(start 148.953728 -169.516806)
		(end 148.188172 -169.907966)
		(width 0.14732)
		(layer "In4.Cu")
		(net "UPI_CPU0_CPU1_P1P0_DP<22>")
	)
	(segment
		(start 163.722812 -166.305992)
		(end 163.408106 -166.00551)
		(width 0.14732)
		(layer "In4.Cu")
		(net "UPI_CPU0_CPU1_P1P0_DP<22>")
	)
	(segment
		(start 361.30357 -217.607388)
		(end 361.3277 -217.518234)
		(width 0.0889)
		(layer "In4.Cu")
		(net "UPI_CPU0_CPU1_P1P0_DP<22>")
	)
	(segment
		(start 157.52318 -164.88156)
		(end 157.222698 -165.196266)
		(width 0.14732)
		(layer "In4.Cu")
		(net "UPI_CPU0_CPU1_P1P0_DP<22>")
	)
	(segment
		(start 109.956854 -216.569798)
		(end 109.947964 -216.574878)
		(width 0.0889)
		(layer "In4.Cu")
		(net "UPI_CPU0_CPU1_P1P0_DP<22>")
	)
	(segment
		(start 361.583986 -211.214208)
		(end 361.583986 -204.96149)
		(width 0.14732)
		(layer "In4.Cu")
		(net "UPI_CPU0_CPU1_P1P0_DP<22>")
	)
	(segment
		(start 175.639476 -167.21328)
		(end 175.495712 -167.363648)
		(width 0.14732)
		(layer "In4.Cu")
		(net "UPI_CPU0_CPU1_P1P0_DP<22>")
	)
	(segment
		(start 163.901628 -167.638984)
		(end 163.75126 -167.49522)
		(width 0.14732)
		(layer "In4.Cu")
		(net "UPI_CPU0_CPU1_P1P0_DP<22>")
	)
	(segment
		(start 320.058288 -168.520618)
		(end 314.326524 -166.902892)
		(width 0.14732)
		(layer "In4.Cu")
		(net "UPI_CPU0_CPU1_P1P0_DP<22>")
	)
	(segment
		(start 151.791924 -165.936422)
		(end 152.43556 -168.486328)
		(width 0.14732)
		(layer "In4.Cu")
		(net "UPI_CPU0_CPU1_P1P0_DP<22>")
	)
	(segment
		(start 110.093506 -211.250022)
		(end 110.093506 -211.628228)
		(width 0.14732)
		(layer "In4.Cu")
		(net "UPI_CPU0_CPU1_P1P0_DP<22>")
	)
	(segment
		(start 111.378746 -207.616044)
		(end 111.378492 -207.616806)
		(width 0.14732)
		(layer "In4.Cu")
		(net "UPI_CPU0_CPU1_P1P0_DP<22>")
	)
	(segment
		(start 158.34106 -164.861748)
		(end 157.52318 -164.88156)
		(width 0.14732)
		(layer "In4.Cu")
		(net "UPI_CPU0_CPU1_P1P0_DP<22>")
	)
	(segment
		(start 110.03661 -213.81466)
		(end 110.13567 -213.91372)
		(width 0.0889)
		(layer "In4.Cu")
		(net "UPI_CPU0_CPU1_P1P0_DP<22>")
	)
	(segment
		(start 347.64726 -182.701946)
		(end 343.0016 -178.074828)
		(width 0.14732)
		(layer "In4.Cu")
		(net "UPI_CPU0_CPU1_P1P0_DP<22>")
	)
	(arc
		(start 361.55503 -215.268048)
		(mid 361.628632 -215.157102)
		(end 361.733846 -215.075516)
		(width 0.0889)
		(layer "In4.Cu")
		(net "UPI_CPU0_CPU1_P1P0_DP<22>")
	)
	(arc
		(start 361.555284 -217.064336)
		(mid 361.483049 -216.787812)
		(end 361.284774 -216.58199)
		(width 0.0889)
		(layer "In4.Cu")
		(net "UPI_CPU0_CPU1_P1P0_DP<22>")
	)
	(arc
		(start 110.590076 -215.270334)
		(mid 110.6013 -215.293176)
		(end 110.605062 -215.31834)
		(width 0.0889)
		(layer "In4.Cu")
		(net "UPI_CPU0_CPU1_P1P0_DP<22>")
	)
	(arc
		(start 361.263692 -216.569798)
		(mid 361.085095 -216.25052)
		(end 361.263692 -215.931242)
		(width 0.0889)
		(layer "In4.Cu")
		(net "UPI_CPU0_CPU1_P1P0_DP<22>")
	)
	(arc
		(start 110.157768 -214.80018)
		(mid 110.252778 -214.94465)
		(end 110.385098 -215.055958)
		(width 0.0889)
		(layer "In4.Cu")
		(net "UPI_CPU0_CPU1_P1P0_DP<22>")
	)
	(arc
		(start 110.13567 -214.694008)
		(mid 110.141267 -214.748224)
		(end 110.15853 -214.799926)
		(width 0.0889)
		(layer "In4.Cu")
		(net "UPI_CPU0_CPU1_P1P0_DP<22>")
	)
	(arc
		(start 361.3277 -217.518234)
		(mid 361.336143 -217.511836)
		(end 361.344464 -217.50528)
		(width 0.0889)
		(layer "In4.Cu")
		(net "UPI_CPU0_CPU1_P1P0_DP<22>")
	)
	(arc
		(start 110.605062 -215.436704)
		(mid 110.557383 -215.619604)
		(end 110.4265 -215.755982)
		(width 0.0889)
		(layer "In4.Cu")
		(net "UPI_CPU0_CPU1_P1P0_DP<22>")
	)
	(arc
		(start 361.344464 -217.50528)
		(mid 361.496971 -217.315182)
		(end 361.555284 -217.07856)
		(width 0.0889)
		(layer "In4.Cu")
		(net "UPI_CPU0_CPU1_P1P0_DP<22>")
	)
	(arc
		(start 362.012484 -214.546434)
		(mid 361.940249 -214.26991)
		(end 361.741974 -214.064088)
		(width 0.0889)
		(layer "In4.Cu")
		(net "UPI_CPU0_CPU1_P1P0_DP<22>")
	)
	(arc
		(start 361.733846 -215.075516)
		(mid 361.902698 -214.939594)
		(end 362.012484 -214.752682)
		(width 0.0889)
		(layer "In4.Cu")
		(net "UPI_CPU0_CPU1_P1P0_DP<22>")
	)
	(arc
		(start 109.665262 -217.071956)
		(mid 109.742891 -217.350369)
		(end 109.947964 -217.554048)
		(width 0.0889)
		(layer "In4.Cu")
		(net "UPI_CPU0_CPU1_P1P0_DP<22>")
	)
	(arc
		(start 110.385098 -215.055958)
		(mid 110.407551 -215.071097)
		(end 110.428532 -215.088216)
		(width 0.0889)
		(layer "In4.Cu")
		(net "UPI_CPU0_CPU1_P1P0_DP<22>")
	)
	(arc
		(start 361.272582 -215.926162)
		(mid 361.476917 -215.723557)
		(end 361.55503 -215.44661)
		(width 0.0889)
		(layer "In4.Cu")
		(net "UPI_CPU0_CPU1_P1P0_DP<22>")
	)
	(arc
		(start 110.135416 -216.25052)
		(mid 110.087737 -216.43342)
		(end 109.956854 -216.569798)
		(width 0.0889)
		(layer "In4.Cu")
		(net "UPI_CPU0_CPU1_P1P0_DP<22>")
	)
	(arc
		(start 110.135416 -217.878406)
		(mid 110.098556 -218.040203)
		(end 109.995462 -218.170252)
		(width 0.0889)
		(layer "In4.Cu")
		(net "UPI_CPU0_CPU1_P1P0_DP<22>")
	)
	(arc
		(start 109.935772 -216.58199)
		(mid 109.737544 -216.787838)
		(end 109.665262 -217.064336)
		(width 0.0889)
		(layer "In4.Cu")
		(net "UPI_CPU0_CPU1_P1P0_DP<22>")
	)
	(arc
		(start 110.41761 -215.761062)
		(mid 110.214787 -215.961293)
		(end 110.135416 -216.235026)
		(width 0.0889)
		(layer "In4.Cu")
		(net "UPI_CPU0_CPU1_P1P0_DP<22>")
	)
	(arc
		(start 110.428532 -215.088216)
		(mid 110.514374 -215.174777)
		(end 110.590076 -215.270334)
		(width 0.0889)
		(layer "In4.Cu")
		(net "UPI_CPU0_CPU1_P1P0_DP<22>")
	)
	(arc
		(start 109.956854 -217.559128)
		(mid 110.087768 -217.695488)
		(end 110.135416 -217.878406)
		(width 0.0889)
		(layer "In4.Cu")
		(net "UPI_CPU0_CPU1_P1P0_DP<22>")
	)
	(arc
		(start 361.729274 -214.056722)
		(mid 361.594 -213.922431)
		(end 361.54233 -213.738968)
		(width 0.0889)
		(layer "In4.Cu")
		(net "UPI_CPU0_CPU1_P1P0_DP<22>")
	)
	(segment
		(start 108.820712 -218.414346)
		(end 108.820712 -217.87866)
		(width 0.13208)
		(layer "F.Cu")
		(net "UPI_CPU0_CPU1_P1P0_DP<21>")
	)
	(segment
		(start 108.820712 -217.87866)
		(end 108.820966 -217.878406)
		(width 0.13208)
		(layer "F.Cu")
		(net "UPI_CPU0_CPU1_P1P0_DP<21>")
	)
	(segment
		(start 362.399834 -217.878406)
		(end 362.399834 -218.414346)
		(width 0.13208)
		(layer "F.Cu")
		(net "UPI_CPU0_CPU1_P1P0_DP<21>")
	)
	(segment
		(start 139.51204 -172.235876)
		(end 139.410694 -172.659548)
		(width 0.14732)
		(layer "In4.Cu")
		(net "UPI_CPU0_CPU1_P1P0_DP<21>")
	)
	(segment
		(start 180.10886 -164.968428)
		(end 179.291996 -164.989256)
		(width 0.14732)
		(layer "In4.Cu")
		(net "UPI_CPU0_CPU1_P1P0_DP<21>")
	)
	(segment
		(start 161.046668 -163.984686)
		(end 161.046668 -163.984432)
		(width 0.14732)
		(layer "In4.Cu")
		(net "UPI_CPU0_CPU1_P1P0_DP<21>")
	)
	(segment
		(start 351.20707 -181.214776)
		(end 350.681544 -181.139846)
		(width 0.14732)
		(layer "In4.Cu")
		(net "UPI_CPU0_CPU1_P1P0_DP<21>")
	)
	(segment
		(start 362.49483 -211.830412)
		(end 362.536994 -211.788248)
		(width 0.0889)
		(layer "In4.Cu")
		(net "UPI_CPU0_CPU1_P1P0_DP<21>")
	)
	(segment
		(start 354.608892 -187.373514)
		(end 352.838004 -184.71007)
		(width 0.14732)
		(layer "In4.Cu")
		(net "UPI_CPU0_CPU1_P1P0_DP<21>")
	)
	(segment
		(start 165.408102 -165.640004)
		(end 161.046668 -163.984686)
		(width 0.14732)
		(layer "In4.Cu")
		(net "UPI_CPU0_CPU1_P1P0_DP<21>")
	)
	(segment
		(start 182.916068 -166.352982)
		(end 182.7657 -166.209726)
		(width 0.14732)
		(layer "In4.Cu")
		(net "UPI_CPU0_CPU1_P1P0_DP<21>")
	)
	(segment
		(start 182.7657 -166.209726)
		(end 182.740808 -165.211252)
		(width 0.14732)
		(layer "In4.Cu")
		(net "UPI_CPU0_CPU1_P1P0_DP<21>")
	)
	(segment
		(start 108.89742 -211.882482)
		(end 108.89742 -212.02015)
		(width 0.14732)
		(layer "In4.Cu")
		(net "UPI_CPU0_CPU1_P1P0_DP<21>")
	)
	(segment
		(start 142.606776 -170.696382)
		(end 142.183104 -170.595036)
		(width 0.14732)
		(layer "In4.Cu")
		(net "UPI_CPU0_CPU1_P1P0_DP<21>")
	)
	(segment
		(start 140.208254 -171.80814)
		(end 139.51204 -172.235876)
		(width 0.14732)
		(layer "In4.Cu")
		(net "UPI_CPU0_CPU1_P1P0_DP<21>")
	)
	(segment
		(start 108.725462 -217.064336)
		(end 108.725462 -217.07856)
		(width 0.0889)
		(layer "In4.Cu")
		(net "UPI_CPU0_CPU1_P1P0_DP<21>")
	)
	(segment
		(start 178.87315 -166.453566)
		(end 178.2826 -166.468298)
		(width 0.14732)
		(layer "In4.Cu")
		(net "UPI_CPU0_CPU1_P1P0_DP<21>")
	)
	(segment
		(start 183.650128 -166.187628)
		(end 183.506618 -166.33825)
		(width 0.14732)
		(layer "In4.Cu")
		(net "UPI_CPU0_CPU1_P1P0_DP<21>")
	)
	(segment
		(start 178.132232 -166.325042)
		(end 178.10734 -165.326568)
		(width 0.14732)
		(layer "In4.Cu")
		(net "UPI_CPU0_CPU1_P1P0_DP<21>")
	)
	(segment
		(start 197.57898 -165.857936)
		(end 194.856608 -166.200582)
		(width 0.14732)
		(layer "In4.Cu")
		(net "UPI_CPU0_CPU1_P1P0_DP<21>")
	)
	(segment
		(start 183.506618 -166.33825)
		(end 182.916068 -166.352982)
		(width 0.14732)
		(layer "In4.Cu")
		(net "UPI_CPU0_CPU1_P1P0_DP<21>")
	)
	(segment
		(start 350.681544 -181.139846)
		(end 348.532196 -181.467506)
		(width 0.14732)
		(layer "In4.Cu")
		(net "UPI_CPU0_CPU1_P1P0_DP<21>")
	)
	(segment
		(start 351.786952 -183.12892)
		(end 351.786952 -181.794658)
		(width 0.14732)
		(layer "In4.Cu")
		(net "UPI_CPU0_CPU1_P1P0_DP<21>")
	)
	(segment
		(start 108.97743 -217.607388)
		(end 108.820966 -217.878406)
		(width 0.0889)
		(layer "In4.Cu")
		(net "UPI_CPU0_CPU1_P1P0_DP<21>")
	)
	(segment
		(start 174.139606 -162.4076)
		(end 173.321726 -162.42792)
		(width 0.14732)
		(layer "In4.Cu")
		(net "UPI_CPU0_CPU1_P1P0_DP<21>")
	)
	(segment
		(start 175.338486 -162.685476)
		(end 175.394366 -164.937948)
		(width 0.14732)
		(layer "In4.Cu")
		(net "UPI_CPU0_CPU1_P1P0_DP<21>")
	)
	(segment
		(start 182.740808 -165.211252)
		(end 182.425594 -164.91077)
		(width 0.14732)
		(layer "In4.Cu")
		(net "UPI_CPU0_CPU1_P1P0_DP<21>")
	)
	(segment
		(start 110.328456 -207.727804)
		(end 110.328202 -207.728566)
		(width 0.14732)
		(layer "In4.Cu")
		(net "UPI_CPU0_CPU1_P1P0_DP<21>")
	)
	(segment
		(start 180.424074 -165.26891)
		(end 180.10886 -164.968428)
		(width 0.14732)
		(layer "In4.Cu")
		(net "UPI_CPU0_CPU1_P1P0_DP<21>")
	)
	(segment
		(start 169.112184 -165.819328)
		(end 168.291002 -166.03472)
		(width 0.14732)
		(layer "In4.Cu")
		(net "UPI_CPU0_CPU1_P1P0_DP<21>")
	)
	(segment
		(start 362.203746 -217.559128)
		(end 362.212636 -217.554048)
		(width 0.0889)
		(layer "In4.Cu")
		(net "UPI_CPU0_CPU1_P1P0_DP<21>")
	)
	(segment
		(start 347.737938 -181.31409)
		(end 343.576656 -177.437542)
		(width 0.14732)
		(layer "In4.Cu")
		(net "UPI_CPU0_CPU1_P1P0_DP<21>")
	)
	(segment
		(start 343.576656 -177.437542)
		(end 341.173816 -175.731424)
		(width 0.14732)
		(layer "In4.Cu")
		(net "UPI_CPU0_CPU1_P1P0_DP<21>")
	)
	(segment
		(start 189.215776 -166.200582)
		(end 186.54903 -164.810186)
		(width 0.14732)
		(layer "In4.Cu")
		(net "UPI_CPU0_CPU1_P1P0_DP<21>")
	)
	(segment
		(start 362.536994 -211.788248)
		(end 362.536994 -211.76615)
		(width 0.0889)
		(layer "In4.Cu")
		(net "UPI_CPU0_CPU1_P1P0_DP<21>")
	)
	(segment
		(start 351.219008 -185.443876)
		(end 351.04705 -185.409332)
		(width 0.14732)
		(layer "In4.Cu")
		(net "UPI_CPU0_CPU1_P1P0_DP<21>")
	)
	(segment
		(start 160.997392 -163.96589)
		(end 156.026358 -164.04844)
		(width 0.14732)
		(layer "In4.Cu")
		(net "UPI_CPU0_CPU1_P1P0_DP<21>")
	)
	(segment
		(start 362.49483 -212.68436)
		(end 362.59389 -212.5853)
		(width 0.0889)
		(layer "In4.Cu")
		(net "UPI_CPU0_CPU1_P1P0_DP<21>")
	)
	(segment
		(start 320.362834 -167.733726)
		(end 314.431934 -166.060374)
		(width 0.14732)
		(layer "In4.Cu")
		(net "UPI_CPU0_CPU1_P1P0_DP<21>")
	)
	(segment
		(start 362.49483 -212.85962)
		(end 362.49483 -212.68436)
		(width 0.0889)
		(layer "In4.Cu")
		(net "UPI_CPU0_CPU1_P1P0_DP<21>")
	)
	(segment
		(start 139.60602 -173.258226)
		(end 139.102592 -173.567598)
		(width 0.14732)
		(layer "In4.Cu")
		(net "UPI_CPU0_CPU1_P1P0_DP<21>")
	)
	(segment
		(start 143.60398 -170.630088)
		(end 143.55572 -170.832018)
		(width 0.14732)
		(layer "In4.Cu")
		(net "UPI_CPU0_CPU1_P1P0_DP<21>")
	)
	(segment
		(start 356.200456 -191.266826)
		(end 354.608892 -187.373514)
		(width 0.14732)
		(layer "In4.Cu")
		(net "UPI_CPU0_CPU1_P1P0_DP<21>")
	)
	(segment
		(start 108.89742 -212.02015)
		(end 108.89742 -212.042248)
		(width 0.0889)
		(layer "In4.Cu")
		(net "UPI_CPU0_CPU1_P1P0_DP<21>")
	)
	(segment
		(start 173.321726 -162.42792)
		(end 173.021752 -162.743134)
		(width 0.14732)
		(layer "In4.Cu")
		(net "UPI_CPU0_CPU1_P1P0_DP<21>")
	)
	(segment
		(start 178.2826 -166.468298)
		(end 178.132232 -166.325042)
		(width 0.14732)
		(layer "In4.Cu")
		(net "UPI_CPU0_CPU1_P1P0_DP<21>")
	)
	(segment
		(start 175.394366 -164.937948)
		(end 175.250856 -165.08857)
		(width 0.14732)
		(layer "In4.Cu")
		(net "UPI_CPU0_CPU1_P1P0_DP<21>")
	)
	(segment
		(start 362.495084 -215.436704)
		(end 362.495084 -215.428068)
		(width 0.0889)
		(layer "In4.Cu")
		(net "UPI_CPU0_CPU1_P1P0_DP<21>")
	)
	(segment
		(start 333.313024 -172.315124)
		(end 320.362834 -167.733726)
		(width 0.14732)
		(layer "In4.Cu")
		(net "UPI_CPU0_CPU1_P1P0_DP<21>")
	)
	(segment
		(start 141.48689 -171.022772)
		(end 141.385544 -171.446444)
		(width 0.14732)
		(layer "In4.Cu")
		(net "UPI_CPU0_CPU1_P1P0_DP<21>")
	)
	(segment
		(start 179.01666 -166.302944)
		(end 178.87315 -166.453566)
		(width 0.14732)
		(layer "In4.Cu")
		(net "UPI_CPU0_CPU1_P1P0_DP<21>")
	)
	(segment
		(start 110.328202 -207.728566)
		(end 108.897166 -211.77504)
		(width 0.14732)
		(layer "In4.Cu")
		(net "UPI_CPU0_CPU1_P1P0_DP<21>")
	)
	(segment
		(start 362.59389 -212.41004)
		(end 362.49483 -212.31098)
		(width 0.0889)
		(layer "In4.Cu")
		(net "UPI_CPU0_CPU1_P1P0_DP<21>")
	)
	(segment
		(start 181.189884 -166.395908)
		(end 180.599334 -166.41064)
		(width 0.14732)
		(layer "In4.Cu")
		(net "UPI_CPU0_CPU1_P1P0_DP<21>")
	)
	(segment
		(start 108.9533 -217.518234)
		(end 108.97743 -217.607388)
		(width 0.0889)
		(layer "In4.Cu")
		(net "UPI_CPU0_CPU1_P1P0_DP<21>")
	)
	(segment
		(start 154.999944 -165.205156)
		(end 154.850592 -165.06063)
		(width 0.14732)
		(layer "In4.Cu")
		(net "UPI_CPU0_CPU1_P1P0_DP<21>")
	)
	(segment
		(start 362.24337 -218.149424)
		(end 362.165138 -218.170252)
		(width 0.0889)
		(layer "In4.Cu")
		(net "UPI_CPU0_CPU1_P1P0_DP<21>")
	)
	(segment
		(start 302.492156 -165.816788)
		(end 280.172668 -166.201598)
		(width 0.14732)
		(layer "In4.Cu")
		(net "UPI_CPU0_CPU1_P1P0_DP<21>")
	)
	(segment
		(start 350.728026 -184.705244)
		(end 351.951544 -183.891682)
		(width 0.14732)
		(layer "In4.Cu")
		(net "UPI_CPU0_CPU1_P1P0_DP<21>")
	)
	(segment
		(start 154.838908 -164.376354)
		(end 154.526234 -164.073332)
		(width 0.14732)
		(layer "In4.Cu")
		(net "UPI_CPU0_CPU1_P1P0_DP<21>")
	)
	(segment
		(start 156.026358 -164.04844)
		(end 155.723336 -164.361114)
		(width 0.14732)
		(layer "In4.Cu")
		(net "UPI_CPU0_CPU1_P1P0_DP<21>")
	)
	(segment
		(start 186.54903 -164.810186)
		(end 183.925464 -164.873686)
		(width 0.14732)
		(layer "In4.Cu")
		(net "UPI_CPU0_CPU1_P1P0_DP<21>")
	)
	(segment
		(start 109.002068 -215.922606)
		(end 109.017054 -215.931242)
		(width 0.0889)
		(layer "In4.Cu")
		(net "UPI_CPU0_CPU1_P1P0_DP<21>")
	)
	(segment
		(start 183.925464 -164.873686)
		(end 183.625236 -165.189154)
		(width 0.14732)
		(layer "In4.Cu")
		(net "UPI_CPU0_CPU1_P1P0_DP<21>")
	)
	(segment
		(start 357.263446 -192.349882)
		(end 356.200456 -191.266826)
		(width 0.14732)
		(layer "In4.Cu")
		(net "UPI_CPU0_CPU1_P1P0_DP<21>")
	)
	(segment
		(start 138.233404 -173.021244)
		(end 134.629906 -175.234092)
		(width 0.14732)
		(layer "In4.Cu")
		(net "UPI_CPU0_CPU1_P1P0_DP<21>")
	)
	(segment
		(start 142.850362 -171.09313)
		(end 142.606776 -170.696382)
		(width 0.14732)
		(layer "In4.Cu")
		(net "UPI_CPU0_CPU1_P1P0_DP<21>")
	)
	(segment
		(start 362.212636 -216.574878)
		(end 362.203746 -216.569798)
		(width 0.0889)
		(layer "In4.Cu")
		(net "UPI_CPU0_CPU1_P1P0_DP<21>")
	)
	(segment
		(start 176.97831 -165.046152)
		(end 176.827434 -164.902134)
		(width 0.14732)
		(layer "In4.Cu")
		(net "UPI_CPU0_CPU1_P1P0_DP<21>")
	)
	(segment
		(start 174.45482 -162.707574)
		(end 174.139606 -162.4076)
		(width 0.14732)
		(layer "In4.Cu")
		(net "UPI_CPU0_CPU1_P1P0_DP<21>")
	)
	(segment
		(start 182.425594 -164.91077)
		(end 181.60873 -164.931598)
		(width 0.14732)
		(layer "In4.Cu")
		(net "UPI_CPU0_CPU1_P1P0_DP<21>")
	)
	(segment
		(start 362.399834 -217.878406)
		(end 362.24337 -218.149424)
		(width 0.0889)
		(layer "In4.Cu")
		(net "UPI_CPU0_CPU1_P1P0_DP<21>")
	)
	(segment
		(start 237.600744 -156.310838)
		(end 234.61091 -156.310838)
		(width 0.14732)
		(layer "In4.Cu")
		(net "UPI_CPU0_CPU1_P1P0_DP<21>")
	)
	(segment
		(start 173.021752 -162.743134)
		(end 173.077632 -164.995606)
		(width 0.14732)
		(layer "In4.Cu")
		(net "UPI_CPU0_CPU1_P1P0_DP<21>")
	)
	(segment
		(start 362.495084 -217.082878)
		(end 362.495084 -217.05443)
		(width 0.0889)
		(layer "In4.Cu")
		(net "UPI_CPU0_CPU1_P1P0_DP<21>")
	)
	(segment
		(start 178.10734 -165.326568)
		(end 177.792126 -165.02634)
		(width 0.14732)
		(layer "In4.Cu")
		(net "UPI_CPU0_CPU1_P1P0_DP<21>")
	)
	(segment
		(start 109.009688 -216.574116)
		(end 109.002068 -216.578434)
		(width 0.0889)
		(layer "In4.Cu")
		(net "UPI_CPU0_CPU1_P1P0_DP<21>")
	)
	(segment
		(start 362.49483 -213.233)
		(end 362.59389 -213.13394)
		(width 0.0889)
		(layer "In4.Cu")
		(net "UPI_CPU0_CPU1_P1P0_DP<21>")
	)
	(segment
		(start 175.250856 -165.08857)
		(end 174.661322 -165.103556)
		(width 0.14732)
		(layer "In4.Cu")
		(net "UPI_CPU0_CPU1_P1P0_DP<21>")
	)
	(segment
		(start 362.536994 -211.76615)
		(end 362.536994 -211.214462)
		(width 0.14732)
		(layer "In4.Cu")
		(net "UPI_CPU0_CPU1_P1P0_DP<21>")
	)
	(segment
		(start 351.04705 -185.409332)
		(end 350.693482 -184.877202)
		(width 0.14732)
		(layer "In4.Cu")
		(net "UPI_CPU0_CPU1_P1P0_DP<21>")
	)
	(segment
		(start 280.172668 -166.201598)
		(end 276.108414 -166.201598)
		(width 0.14732)
		(layer "In4.Cu")
		(net "UPI_CPU0_CPU1_P1P0_DP<21>")
	)
	(segment
		(start 154.850592 -165.06063)
		(end 154.838908 -164.376354)
		(width 0.14732)
		(layer "In4.Cu")
		(net "UPI_CPU0_CPU1_P1P0_DP<21>")
	)
	(segment
		(start 183.625236 -165.189154)
		(end 183.650128 -166.187628)
		(width 0.14732)
		(layer "In4.Cu")
		(net "UPI_CPU0_CPU1_P1P0_DP<21>")
	)
	(segment
		(start 167.161972 -165.997382)
		(end 165.408102 -165.640004)
		(width 0.14732)
		(layer "In4.Cu")
		(net "UPI_CPU0_CPU1_P1P0_DP<21>")
	)
	(segment
		(start 108.93933 -214.07247)
		(end 109.195362 -214.328502)
		(width 0.0889)
		(layer "In4.Cu")
		(net "UPI_CPU0_CPU1_P1P0_DP<21>")
	)
	(segment
		(start 143.55572 -170.832018)
		(end 143.052292 -171.14139)
		(width 0.14732)
		(layer "In4.Cu")
		(net "UPI_CPU0_CPU1_P1P0_DP<21>")
	)
	(segment
		(start 154.526234 -164.073332)
		(end 153.516584 -164.090604)
		(width 0.14732)
		(layer "In4.Cu")
		(net "UPI_CPU0_CPU1_P1P0_DP<21>")
	)
	(segment
		(start 352.44278 -184.630314)
		(end 351.219008 -185.443876)
		(width 0.14732)
		(layer "In4.Cu")
		(net "UPI_CPU0_CPU1_P1P0_DP<21>")
	)
	(segment
		(start 143.46174 -169.809668)
		(end 143.360394 -170.23334)
		(width 0.14732)
		(layer "In4.Cu")
		(net "UPI_CPU0_CPU1_P1P0_DP<21>")
	)
	(segment
		(start 140.631926 -171.909486)
		(end 140.208254 -171.80814)
		(width 0.14732)
		(layer "In4.Cu")
		(net "UPI_CPU0_CPU1_P1P0_DP<21>")
	)
	(segment
		(start 176.771554 -162.649916)
		(end 176.45634 -162.349942)
		(width 0.14732)
		(layer "In4.Cu")
		(net "UPI_CPU0_CPU1_P1P0_DP<21>")
	)
	(segment
		(start 194.856608 -166.200582)
		(end 189.215776 -166.200582)
		(width 0.14732)
		(layer "In4.Cu")
		(net "UPI_CPU0_CPU1_P1P0_DP<21>")
	)
	(segment
		(start 177.792126 -165.02634)
		(end 176.97831 -165.046152)
		(width 0.14732)
		(layer "In4.Cu")
		(net "UPI_CPU0_CPU1_P1P0_DP<21>")
	)
	(segment
		(start 181.60873 -164.931598)
		(end 181.308502 -165.246812)
		(width 0.14732)
		(layer "In4.Cu")
		(net "UPI_CPU0_CPU1_P1P0_DP<21>")
	)
	(segment
		(start 109.02315 -214.938864)
		(end 109.007656 -214.946992)
		(width 0.0889)
		(layer "In4.Cu")
		(net "UPI_CPU0_CPU1_P1P0_DP<21>")
	)
	(segment
		(start 140.875512 -172.306234)
		(end 140.631926 -171.909486)
		(width 0.14732)
		(layer "In4.Cu")
		(net "UPI_CPU0_CPU1_P1P0_DP<21>")
	)
	(segment
		(start 362.536994 -211.214462)
		(end 362.53674 -211.214208)
		(width 0.14732)
		(layer "In4.Cu")
		(net "UPI_CPU0_CPU1_P1P0_DP<21>")
	)
	(segment
		(start 234.61091 -156.310838)
		(end 197.57898 -165.857936)
		(width 0.14732)
		(layer "In4.Cu")
		(net "UPI_CPU0_CPU1_P1P0_DP<21>")
	)
	(segment
		(start 109.195362 -214.328502)
		(end 109.195362 -214.584534)
		(width 0.0889)
		(layer "In4.Cu")
		(net "UPI_CPU0_CPU1_P1P0_DP<21>")
	)
	(segment
		(start 109.036866 -214.93099)
		(end 109.02315 -214.938864)
		(width 0.0889)
		(layer "In4.Cu")
		(net "UPI_CPU0_CPU1_P1P0_DP<21>")
	)
	(segment
		(start 143.360394 -170.23334)
		(end 143.60398 -170.630088)
		(width 0.14732)
		(layer "In4.Cu")
		(net "UPI_CPU0_CPU1_P1P0_DP<21>")
	)
	(segment
		(start 122.506994 -186.677808)
		(end 114.068606 -197.15226)
		(width 0.14732)
		(layer "In4.Cu")
		(net "UPI_CPU0_CPU1_P1P0_DP<21>")
	)
	(segment
		(start 155.723336 -164.361114)
		(end 155.73502 -165.045644)
		(width 0.14732)
		(layer "In4.Cu")
		(net "UPI_CPU0_CPU1_P1P0_DP<21>")
	)
	(segment
		(start 141.62913 -171.843192)
		(end 141.58087 -172.045122)
		(width 0.14732)
		(layer "In4.Cu")
		(net "UPI_CPU0_CPU1_P1P0_DP<21>")
	)
	(segment
		(start 114.068606 -197.15226)
		(end 110.328456 -207.727804)
		(width 0.14732)
		(layer "In4.Cu")
		(net "UPI_CPU0_CPU1_P1P0_DP<21>")
	)
	(segment
		(start 362.59389 -212.5853)
		(end 362.59389 -212.41004)
		(width 0.0889)
		(layer "In4.Cu")
		(net "UPI_CPU0_CPU1_P1P0_DP<21>")
	)
	(segment
		(start 109.017054 -216.569798)
		(end 109.009688 -216.574116)
		(width 0.0889)
		(layer "In4.Cu")
		(net "UPI_CPU0_CPU1_P1P0_DP<21>")
	)
	(segment
		(start 142.183104 -170.595036)
		(end 141.48689 -171.022772)
		(width 0.14732)
		(layer "In4.Cu")
		(net "UPI_CPU0_CPU1_P1P0_DP<21>")
	)
	(segment
		(start 109.195362 -214.584534)
		(end 109.19587 -214.592154)
		(width 0.0889)
		(layer "In4.Cu")
		(net "UPI_CPU0_CPU1_P1P0_DP<21>")
	)
	(segment
		(start 108.897166 -211.882228)
		(end 108.89742 -211.882482)
		(width 0.14732)
		(layer "In4.Cu")
		(net "UPI_CPU0_CPU1_P1P0_DP<21>")
	)
	(segment
		(start 174.661322 -165.103556)
		(end 174.5107 -164.960046)
		(width 0.14732)
		(layer "In4.Cu")
		(net "UPI_CPU0_CPU1_P1P0_DP<21>")
	)
	(segment
		(start 314.431934 -166.060374)
		(end 302.492156 -165.816788)
		(width 0.14732)
		(layer "In4.Cu")
		(net "UPI_CPU0_CPU1_P1P0_DP<21>")
	)
	(segment
		(start 108.897166 -211.77504)
		(end 108.897166 -211.882228)
		(width 0.14732)
		(layer "In4.Cu")
		(net "UPI_CPU0_CPU1_P1P0_DP<21>")
	)
	(segment
		(start 108.89742 -212.042248)
		(end 108.93933 -212.084158)
		(width 0.0889)
		(layer "In4.Cu")
		(net "UPI_CPU0_CPU1_P1P0_DP<21>")
	)
	(segment
		(start 176.45634 -162.349942)
		(end 175.63846 -162.370262)
		(width 0.14732)
		(layer "In4.Cu")
		(net "UPI_CPU0_CPU1_P1P0_DP<21>")
	)
	(segment
		(start 179.291996 -164.989256)
		(end 178.991768 -165.30447)
		(width 0.14732)
		(layer "In4.Cu")
		(net "UPI_CPU0_CPU1_P1P0_DP<21>")
	)
	(segment
		(start 276.108414 -166.201598)
		(end 237.600744 -156.310838)
		(width 0.14732)
		(layer "In4.Cu")
		(net "UPI_CPU0_CPU1_P1P0_DP<21>")
	)
	(segment
		(start 172.934122 -165.146228)
		(end 170.710098 -165.2016)
		(width 0.14732)
		(layer "In4.Cu")
		(net "UPI_CPU0_CPU1_P1P0_DP<21>")
	)
	(segment
		(start 362.203746 -215.931242)
		(end 362.212636 -215.926162)
		(width 0.0889)
		(layer "In4.Cu")
		(net "UPI_CPU0_CPU1_P1P0_DP<21>")
	)
	(segment
		(start 362.53674 -205.081124)
		(end 357.263446 -192.349882)
		(width 0.14732)
		(layer "In4.Cu")
		(net "UPI_CPU0_CPU1_P1P0_DP<21>")
	)
	(segment
		(start 352.838004 -184.71007)
		(end 352.44278 -184.630314)
		(width 0.14732)
		(layer "In4.Cu")
		(net "UPI_CPU0_CPU1_P1P0_DP<21>")
	)
	(segment
		(start 362.495338 -213.8172)
		(end 362.49483 -213.795102)
		(width 0.0889)
		(layer "In4.Cu")
		(net "UPI_CPU0_CPU1_P1P0_DP<21>")
	)
	(segment
		(start 362.53674 -211.214208)
		(end 362.53674 -205.081124)
		(width 0.14732)
		(layer "In4.Cu")
		(net "UPI_CPU0_CPU1_P1P0_DP<21>")
	)
	(segment
		(start 141.58087 -172.045122)
		(end 141.077442 -172.354494)
		(width 0.14732)
		(layer "In4.Cu")
		(net "UPI_CPU0_CPU1_P1P0_DP<21>")
	)
	(segment
		(start 155.590494 -165.194996)
		(end 154.999944 -165.205156)
		(width 0.14732)
		(layer "In4.Cu")
		(net "UPI_CPU0_CPU1_P1P0_DP<21>")
	)
	(segment
		(start 108.93933 -212.084158)
		(end 108.93933 -214.07247)
		(width 0.0889)
		(layer "In4.Cu")
		(net "UPI_CPU0_CPU1_P1P0_DP<21>")
	)
	(segment
		(start 180.448966 -166.267384)
		(end 180.424074 -165.26891)
		(width 0.14732)
		(layer "In4.Cu")
		(net "UPI_CPU0_CPU1_P1P0_DP<21>")
	)
	(segment
		(start 138.657076 -173.12259)
		(end 138.233404 -173.021244)
		(width 0.14732)
		(layer "In4.Cu")
		(net "UPI_CPU0_CPU1_P1P0_DP<21>")
	)
	(segment
		(start 108.725462 -215.414606)
		(end 108.725462 -215.436704)
		(width 0.0889)
		(layer "In4.Cu")
		(net "UPI_CPU0_CPU1_P1P0_DP<21>")
	)
	(segment
		(start 143.052292 -171.14139)
		(end 142.850362 -171.09313)
		(width 0.14732)
		(layer "In4.Cu")
		(net "UPI_CPU0_CPU1_P1P0_DP<21>")
	)
	(segment
		(start 139.410694 -172.659548)
		(end 139.65428 -173.056296)
		(width 0.14732)
		(layer "In4.Cu")
		(net "UPI_CPU0_CPU1_P1P0_DP<21>")
	)
	(segment
		(start 362.49483 -213.795102)
		(end 362.49483 -213.233)
		(width 0.0889)
		(layer "In4.Cu")
		(net "UPI_CPU0_CPU1_P1P0_DP<21>")
	)
	(segment
		(start 181.308502 -165.246812)
		(end 181.333394 -166.245286)
		(width 0.14732)
		(layer "In4.Cu")
		(net "UPI_CPU0_CPU1_P1P0_DP<21>")
	)
	(segment
		(start 152.107646 -164.500814)
		(end 143.46174 -169.809668)
		(width 0.14732)
		(layer "In4.Cu")
		(net "UPI_CPU0_CPU1_P1P0_DP<21>")
	)
	(segment
		(start 141.385544 -171.446444)
		(end 141.62913 -171.843192)
		(width 0.14732)
		(layer "In4.Cu")
		(net "UPI_CPU0_CPU1_P1P0_DP<21>")
	)
	(segment
		(start 362.49483 -215.455246)
		(end 362.495084 -215.436704)
		(width 0.0889)
		(layer "In4.Cu")
		(net "UPI_CPU0_CPU1_P1P0_DP<21>")
	)
	(segment
		(start 352.0313 -183.496458)
		(end 351.786952 -183.12892)
		(width 0.14732)
		(layer "In4.Cu")
		(net "UPI_CPU0_CPU1_P1P0_DP<21>")
	)
	(segment
		(start 176.827434 -164.902134)
		(end 176.771554 -162.649916)
		(width 0.14732)
		(layer "In4.Cu")
		(net "UPI_CPU0_CPU1_P1P0_DP<21>")
	)
	(segment
		(start 362.49483 -212.31098)
		(end 362.49483 -211.830412)
		(width 0.0889)
		(layer "In4.Cu")
		(net "UPI_CPU0_CPU1_P1P0_DP<21>")
	)
	(segment
		(start 348.532196 -181.467506)
		(end 347.737938 -181.31409)
		(width 0.14732)
		(layer "In4.Cu")
		(net "UPI_CPU0_CPU1_P1P0_DP<21>")
	)
	(segment
		(start 139.102592 -173.567598)
		(end 138.900662 -173.519338)
		(width 0.14732)
		(layer "In4.Cu")
		(net "UPI_CPU0_CPU1_P1P0_DP<21>")
	)
	(segment
		(start 134.629906 -175.234092)
		(end 122.506994 -186.677808)
		(width 0.14732)
		(layer "In4.Cu")
		(net "UPI_CPU0_CPU1_P1P0_DP<21>")
	)
	(segment
		(start 155.73502 -165.045644)
		(end 155.590494 -165.194996)
		(width 0.14732)
		(layer "In4.Cu")
		(net "UPI_CPU0_CPU1_P1P0_DP<21>")
	)
	(segment
		(start 168.291002 -166.03472)
		(end 167.161972 -165.997382)
		(width 0.14732)
		(layer "In4.Cu")
		(net "UPI_CPU0_CPU1_P1P0_DP<21>")
	)
	(segment
		(start 138.900662 -173.519338)
		(end 138.657076 -173.12259)
		(width 0.14732)
		(layer "In4.Cu")
		(net "UPI_CPU0_CPU1_P1P0_DP<21>")
	)
	(segment
		(start 362.59389 -213.13394)
		(end 362.59389 -212.95868)
		(width 0.0889)
		(layer "In4.Cu")
		(net "UPI_CPU0_CPU1_P1P0_DP<21>")
	)
	(segment
		(start 175.63846 -162.370262)
		(end 175.338486 -162.685476)
		(width 0.14732)
		(layer "In4.Cu")
		(net "UPI_CPU0_CPU1_P1P0_DP<21>")
	)
	(segment
		(start 141.077442 -172.354494)
		(end 140.875512 -172.306234)
		(width 0.14732)
		(layer "In4.Cu")
		(net "UPI_CPU0_CPU1_P1P0_DP<21>")
	)
	(segment
		(start 362.59389 -212.95868)
		(end 362.49483 -212.85962)
		(width 0.0889)
		(layer "In4.Cu")
		(net "UPI_CPU0_CPU1_P1P0_DP<21>")
	)
	(segment
		(start 351.786952 -181.794658)
		(end 351.20707 -181.214776)
		(width 0.14732)
		(layer "In4.Cu")
		(net "UPI_CPU0_CPU1_P1P0_DP<21>")
	)
	(segment
		(start 139.65428 -173.056296)
		(end 139.60602 -173.258226)
		(width 0.14732)
		(layer "In4.Cu")
		(net "UPI_CPU0_CPU1_P1P0_DP<21>")
	)
	(segment
		(start 350.693482 -184.877202)
		(end 350.728026 -184.705244)
		(width 0.14732)
		(layer "In4.Cu")
		(net "UPI_CPU0_CPU1_P1P0_DP<21>")
	)
	(segment
		(start 362.964984 -214.636858)
		(end 362.964984 -214.604092)
		(width 0.0889)
		(layer "In4.Cu")
		(net "UPI_CPU0_CPU1_P1P0_DP<21>")
	)
	(segment
		(start 180.599334 -166.41064)
		(end 180.448966 -166.267384)
		(width 0.14732)
		(layer "In4.Cu")
		(net "UPI_CPU0_CPU1_P1P0_DP<21>")
	)
	(segment
		(start 174.5107 -164.960046)
		(end 174.45482 -162.707574)
		(width 0.14732)
		(layer "In4.Cu")
		(net "UPI_CPU0_CPU1_P1P0_DP<21>")
	)
	(segment
		(start 341.173816 -175.731424)
		(end 333.313024 -172.315124)
		(width 0.14732)
		(layer "In4.Cu")
		(net "UPI_CPU0_CPU1_P1P0_DP<21>")
	)
	(segment
		(start 173.077632 -164.995606)
		(end 172.934122 -165.146228)
		(width 0.14732)
		(layer "In4.Cu")
		(net "UPI_CPU0_CPU1_P1P0_DP<21>")
	)
	(segment
		(start 181.333394 -166.245286)
		(end 181.189884 -166.395908)
		(width 0.14732)
		(layer "In4.Cu")
		(net "UPI_CPU0_CPU1_P1P0_DP<21>")
	)
	(segment
		(start 351.951544 -183.891682)
		(end 352.0313 -183.496458)
		(width 0.14732)
		(layer "In4.Cu")
		(net "UPI_CPU0_CPU1_P1P0_DP<21>")
	)
	(segment
		(start 153.516584 -164.090604)
		(end 152.107646 -164.500814)
		(width 0.14732)
		(layer "In4.Cu")
		(net "UPI_CPU0_CPU1_P1P0_DP<21>")
	)
	(segment
		(start 170.710098 -165.2016)
		(end 169.112184 -165.819328)
		(width 0.14732)
		(layer "In4.Cu")
		(net "UPI_CPU0_CPU1_P1P0_DP<21>")
	)
	(segment
		(start 178.991768 -165.30447)
		(end 179.01666 -166.302944)
		(width 0.14732)
		(layer "In4.Cu")
		(net "UPI_CPU0_CPU1_P1P0_DP<21>")
	)
	(segment
		(start 161.046668 -163.984432)
		(end 160.997392 -163.96589)
		(width 0.14732)
		(layer "In4.Cu")
		(net "UPI_CPU0_CPU1_P1P0_DP<21>")
	)
	(arc
		(start 362.682282 -215.112346)
		(mid 362.885763 -214.911542)
		(end 362.964984 -214.636858)
		(width 0.0889)
		(layer "In4.Cu")
		(net "UPI_CPU0_CPU1_P1P0_DP<21>")
	)
	(arc
		(start 108.725462 -215.436704)
		(mid 108.799453 -215.71627)
		(end 109.002068 -215.922606)
		(width 0.0889)
		(layer "In4.Cu")
		(net "UPI_CPU0_CPU1_P1P0_DP<21>")
	)
	(arc
		(start 362.212636 -217.554048)
		(mid 362.414922 -217.355067)
		(end 362.495084 -217.082878)
		(width 0.0889)
		(layer "In4.Cu")
		(net "UPI_CPU0_CPU1_P1P0_DP<21>")
	)
	(arc
		(start 362.495084 -215.428068)
		(mid 362.547354 -215.245703)
		(end 362.682282 -215.112346)
		(width 0.0889)
		(layer "In4.Cu")
		(net "UPI_CPU0_CPU1_P1P0_DP<21>")
	)
	(arc
		(start 362.682536 -214.132922)
		(mid 362.547603 -213.999568)
		(end 362.495338 -213.8172)
		(width 0.0889)
		(layer "In4.Cu")
		(net "UPI_CPU0_CPU1_P1P0_DP<21>")
	)
	(arc
		(start 109.19587 -214.592154)
		(mid 109.161403 -214.782695)
		(end 109.036866 -214.93099)
		(width 0.0889)
		(layer "In4.Cu")
		(net "UPI_CPU0_CPU1_P1P0_DP<21>")
	)
	(arc
		(start 362.203746 -216.569798)
		(mid 362.025149 -216.25052)
		(end 362.203746 -215.931242)
		(width 0.0889)
		(layer "In4.Cu")
		(net "UPI_CPU0_CPU1_P1P0_DP<21>")
	)
	(arc
		(start 108.936282 -217.50528)
		(mid 108.94473 -217.511837)
		(end 108.9533 -217.518234)
		(width 0.0889)
		(layer "In4.Cu")
		(net "UPI_CPU0_CPU1_P1P0_DP<21>")
	)
	(arc
		(start 108.725462 -217.07856)
		(mid 108.783756 -217.315203)
		(end 108.936282 -217.50528)
		(width 0.0889)
		(layer "In4.Cu")
		(net "UPI_CPU0_CPU1_P1P0_DP<21>")
	)
	(arc
		(start 109.002068 -216.578434)
		(mid 108.799481 -216.784785)
		(end 108.725462 -217.064336)
		(width 0.0889)
		(layer "In4.Cu")
		(net "UPI_CPU0_CPU1_P1P0_DP<21>")
	)
	(arc
		(start 109.017054 -215.931242)
		(mid 109.195651 -216.25052)
		(end 109.017054 -216.569798)
		(width 0.0889)
		(layer "In4.Cu")
		(net "UPI_CPU0_CPU1_P1P0_DP<21>")
	)
	(arc
		(start 362.025184 -217.878406)
		(mid 362.072863 -217.695506)
		(end 362.203746 -217.559128)
		(width 0.0889)
		(layer "In4.Cu")
		(net "UPI_CPU0_CPU1_P1P0_DP<21>")
	)
	(arc
		(start 362.165138 -218.170252)
		(mid 362.061993 -218.040227)
		(end 362.025184 -217.878406)
		(width 0.0889)
		(layer "In4.Cu")
		(net "UPI_CPU0_CPU1_P1P0_DP<21>")
	)
	(arc
		(start 109.007656 -214.946992)
		(mid 108.806374 -215.144479)
		(end 108.725462 -215.414606)
		(width 0.0889)
		(layer "In4.Cu")
		(net "UPI_CPU0_CPU1_P1P0_DP<21>")
	)
	(arc
		(start 362.964984 -214.604092)
		(mid 362.884822 -214.331903)
		(end 362.682536 -214.132922)
		(width 0.0889)
		(layer "In4.Cu")
		(net "UPI_CPU0_CPU1_P1P0_DP<21>")
	)
	(arc
		(start 362.212636 -215.926162)
		(mid 362.414678 -215.727239)
		(end 362.49483 -215.455246)
		(width 0.0889)
		(layer "In4.Cu")
		(net "UPI_CPU0_CPU1_P1P0_DP<21>")
	)
	(arc
		(start 362.495084 -217.05443)
		(mid 362.416973 -216.777481)
		(end 362.212636 -216.574878)
		(width 0.0889)
		(layer "In4.Cu")
		(net "UPI_CPU0_CPU1_P1P0_DP<21>")
	)
	(segment
		(start 362.869734 -217.600276)
		(end 362.869734 -217.06459)
		(width 0.13208)
		(layer "F.Cu")
		(net "UPI_CPU0_CPU1_P1P0_DP<20>")
	)
	(segment
		(start 108.351066 -218.692476)
		(end 108.350812 -218.692222)
		(width 0.13208)
		(layer "F.Cu")
		(net "UPI_CPU0_CPU1_P1P0_DP<20>")
	)
	(segment
		(start 362.869734 -217.06459)
		(end 362.86948 -217.064336)
		(width 0.13208)
		(layer "F.Cu")
		(net "UPI_CPU0_CPU1_P1P0_DP<20>")
	)
	(segment
		(start 108.351066 -219.228162)
		(end 108.351066 -218.692476)
		(width 0.13208)
		(layer "F.Cu")
		(net "UPI_CPU0_CPU1_P1P0_DP<20>")
	)
	(segment
		(start 173.975014 -158.84652)
		(end 174.435516 -157.966664)
		(width 0.14732)
		(layer "In4.Cu")
		(net "UPI_CPU0_CPU1_P1P0_DP<20>")
	)
	(segment
		(start 154.551888 -162.301936)
		(end 134.091934 -174.91075)
		(width 0.14732)
		(layer "In4.Cu")
		(net "UPI_CPU0_CPU1_P1P0_DP<20>")
	)
	(segment
		(start 155.2067 -163.083748)
		(end 154.754326 -162.349942)
		(width 0.14732)
		(layer "In4.Cu")
		(net "UPI_CPU0_CPU1_P1P0_DP<20>")
	)
	(segment
		(start 363.025944 -217.335354)
		(end 363.104176 -217.356182)
		(width 0.0889)
		(layer "In4.Cu")
		(net "UPI_CPU0_CPU1_P1P0_DP<20>")
	)
	(segment
		(start 350.678496 -180.575458)
		(end 348.543372 -180.900832)
		(width 0.14732)
		(layer "In4.Cu")
		(net "UPI_CPU0_CPU1_P1P0_DP<20>")
	)
	(segment
		(start 333.5401 -171.798488)
		(end 320.51244 -167.19296)
		(width 0.14732)
		(layer "In4.Cu")
		(net "UPI_CPU0_CPU1_P1P0_DP<20>")
	)
	(segment
		(start 108.160566 -216.74201)
		(end 108.154978 -216.745058)
		(width 0.0889)
		(layer "In4.Cu")
		(net "UPI_CPU0_CPU1_P1P0_DP<20>")
	)
	(segment
		(start 158.961328 -162.786822)
		(end 158.538164 -162.686238)
		(width 0.14732)
		(layer "In4.Cu")
		(net "UPI_CPU0_CPU1_P1P0_DP<20>")
	)
	(segment
		(start 363.145324 -212.40496)
		(end 363.244384 -212.3059)
		(width 0.0889)
		(layer "In4.Cu")
		(net "UPI_CPU0_CPU1_P1P0_DP<20>")
	)
	(segment
		(start 363.056678 -215.761062)
		(end 363.065568 -215.755982)
		(width 0.0889)
		(layer "In4.Cu")
		(net "UPI_CPU0_CPU1_P1P0_DP<20>")
	)
	(segment
		(start 178.937412 -161.789872)
		(end 178.212242 -161.410396)
		(width 0.14732)
		(layer "In4.Cu")
		(net "UPI_CPU0_CPU1_P1P0_DP<20>")
	)
	(segment
		(start 108.68152 -210.058)
		(end 108.495592 -210.14436)
		(width 0.14732)
		(layer "In4.Cu")
		(net "UPI_CPU0_CPU1_P1P0_DP<20>")
	)
	(segment
		(start 178.082194 -160.99536)
		(end 178.542696 -160.115504)
		(width 0.14732)
		(layer "In4.Cu")
		(net "UPI_CPU0_CPU1_P1P0_DP<20>")
	)
	(segment
		(start 160.511236 -161.47034)
		(end 159.319722 -159.536638)
		(width 0.14732)
		(layer "In4.Cu")
		(net "UPI_CPU0_CPU1_P1P0_DP<20>")
	)
	(segment
		(start 110.438184 -205.23708)
		(end 110.252256 -205.32344)
		(width 0.14732)
		(layer "In4.Cu")
		(net "UPI_CPU0_CPU1_P1P0_DP<20>")
	)
	(segment
		(start 109.032802 -209.093816)
		(end 108.846874 -209.180176)
		(width 0.14732)
		(layer "In4.Cu")
		(net "UPI_CPU0_CPU1_P1P0_DP<20>")
	)
	(segment
		(start 110.477554 -204.705204)
		(end 110.564168 -204.890624)
		(width 0.14732)
		(layer "In4.Cu")
		(net "UPI_CPU0_CPU1_P1P0_DP<20>")
	)
	(segment
		(start 176.883822 -160.715452)
		(end 176.158652 -160.335976)
		(width 0.14732)
		(layer "In4.Cu")
		(net "UPI_CPU0_CPU1_P1P0_DP<20>")
	)
	(segment
		(start 174.105062 -159.261556)
		(end 173.975014 -158.84652)
		(width 0.14732)
		(layer "In4.Cu")
		(net "UPI_CPU0_CPU1_P1P0_DP<20>")
	)
	(segment
		(start 348.543372 -180.900832)
		(end 348.001336 -180.796184)
		(width 0.14732)
		(layer "In4.Cu")
		(net "UPI_CPU0_CPU1_P1P0_DP<20>")
	)
	(segment
		(start 108.72089 -209.526124)
		(end 108.807504 -209.711544)
		(width 0.14732)
		(layer "In4.Cu")
		(net "UPI_CPU0_CPU1_P1P0_DP<20>")
	)
	(segment
		(start 362.77423 -216.260426)
		(end 362.77423 -216.240614)
		(width 0.0889)
		(layer "In4.Cu")
		(net "UPI_CPU0_CPU1_P1P0_DP<20>")
	)
	(segment
		(start 178.542696 -160.115504)
		(end 178.480466 -159.916876)
		(width 0.14732)
		(layer "In4.Cu")
		(net "UPI_CPU0_CPU1_P1P0_DP<20>")
	)
	(segment
		(start 362.86948 -217.064336)
		(end 363.025944 -217.335354)
		(width 0.0889)
		(layer "In4.Cu")
		(net "UPI_CPU0_CPU1_P1P0_DP<20>")
	)
	(segment
		(start 108.018072 -211.882228)
		(end 108.018326 -211.882482)
		(width 0.14732)
		(layer "In4.Cu")
		(net "UPI_CPU0_CPU1_P1P0_DP<20>")
	)
	(segment
		(start 176.426876 -158.842456)
		(end 175.904144 -158.568898)
		(width 0.14732)
		(layer "In4.Cu")
		(net "UPI_CPU0_CPU1_P1P0_DP<20>")
	)
	(segment
		(start 108.018326 -212.042248)
		(end 107.976162 -212.084412)
		(width 0.0889)
		(layer "In4.Cu")
		(net "UPI_CPU0_CPU1_P1P0_DP<20>")
	)
	(segment
		(start 363.520482 -214.950548)
		(end 363.526578 -214.946992)
		(width 0.0889)
		(layer "In4.Cu")
		(net "UPI_CPU0_CPU1_P1P0_DP<20>")
	)
	(segment
		(start 109.735366 -207.165448)
		(end 109.549438 -207.251808)
		(width 0.14732)
		(layer "In4.Cu")
		(net "UPI_CPU0_CPU1_P1P0_DP<20>")
	)
	(segment
		(start 276.179026 -165.644068)
		(end 237.671356 -155.753308)
		(width 0.14732)
		(layer "In4.Cu")
		(net "UPI_CPU0_CPU1_P1P0_DP<20>")
	)
	(segment
		(start 171.76496 -156.403548)
		(end 169.1894 -155.128468)
		(width 0.14732)
		(layer "In4.Cu")
		(net "UPI_CPU0_CPU1_P1P0_DP<20>")
	)
	(segment
		(start 355.22408 -185.899298)
		(end 355.0793 -185.754518)
		(width 0.14732)
		(layer "In4.Cu")
		(net "UPI_CPU0_CPU1_P1P0_DP<20>")
	)
	(segment
		(start 355.277166 -187.149486)
		(end 355.22408 -186.882786)
		(width 0.14732)
		(layer "In4.Cu")
		(net "UPI_CPU0_CPU1_P1P0_DP<20>")
	)
	(segment
		(start 109.198156 -208.215992)
		(end 109.072172 -208.56194)
		(width 0.14732)
		(layer "In4.Cu")
		(net "UPI_CPU0_CPU1_P1P0_DP<20>")
	)
	(segment
		(start 108.194348 -218.421204)
		(end 108.350812 -218.692222)
		(width 0.0889)
		(layer "In4.Cu")
		(net "UPI_CPU0_CPU1_P1P0_DP<20>")
	)
	(segment
		(start 108.154978 -217.383614)
		(end 108.163106 -217.388186)
		(width 0.0889)
		(layer "In4.Cu")
		(net "UPI_CPU0_CPU1_P1P0_DP<20>")
	)
	(segment
		(start 175.245268 -159.510984)
		(end 174.830232 -159.641032)
		(width 0.14732)
		(layer "In4.Cu")
		(net "UPI_CPU0_CPU1_P1P0_DP<20>")
	)
	(segment
		(start 108.163106 -216.740486)
		(end 108.160566 -216.74201)
		(width 0.0889)
		(layer "In4.Cu")
		(net "UPI_CPU0_CPU1_P1P0_DP<20>")
	)
	(segment
		(start 363.244384 -213.778592)
		(end 363.244384 -213.22792)
		(width 0.0889)
		(layer "In4.Cu")
		(net "UPI_CPU0_CPU1_P1P0_DP<20>")
	)
	(segment
		(start 159.758634 -161.934144)
		(end 159.65805 -162.357308)
		(width 0.14732)
		(layer "In4.Cu")
		(net "UPI_CPU0_CPU1_P1P0_DP<20>")
	)
	(segment
		(start 161.731706 -160.718246)
		(end 161.631122 -161.14141)
		(width 0.14732)
		(layer "In4.Cu")
		(net "UPI_CPU0_CPU1_P1P0_DP<20>")
	)
	(segment
		(start 174.373286 -157.76829)
		(end 171.76496 -156.403548)
		(width 0.14732)
		(layer "In4.Cu")
		(net "UPI_CPU0_CPU1_P1P0_DP<20>")
	)
	(segment
		(start 237.671356 -155.753308)
		(end 234.540044 -155.753308)
		(width 0.14732)
		(layer "In4.Cu")
		(net "UPI_CPU0_CPU1_P1P0_DP<20>")
	)
	(segment
		(start 363.202474 -211.74329)
		(end 363.202474 -211.328254)
		(width 0.14732)
		(layer "In4.Cu")
		(net "UPI_CPU0_CPU1_P1P0_DP<20>")
	)
	(segment
		(start 356.961948 -191.217296)
		(end 355.277166 -187.149486)
		(width 0.14732)
		(layer "In4.Cu")
		(net "UPI_CPU0_CPU1_P1P0_DP<20>")
	)
	(segment
		(start 189.4078 -165.633908)
		(end 180.011324 -160.717738)
		(width 0.14732)
		(layer "In4.Cu")
		(net "UPI_CPU0_CPU1_P1P0_DP<20>")
	)
	(segment
		(start 160.9344 -161.570924)
		(end 160.511236 -161.47034)
		(width 0.14732)
		(layer "In4.Cu")
		(net "UPI_CPU0_CPU1_P1P0_DP<20>")
	)
	(segment
		(start 109.549438 -207.251808)
		(end 109.423454 -207.597756)
		(width 0.14732)
		(layer "In4.Cu")
		(net "UPI_CPU0_CPU1_P1P0_DP<20>")
	)
	(segment
		(start 280.167842 -165.644068)
		(end 276.179026 -165.644068)
		(width 0.14732)
		(layer "In4.Cu")
		(net "UPI_CPU0_CPU1_P1P0_DP<20>")
	)
	(segment
		(start 108.455968 -210.675728)
		(end 108.329984 -211.022184)
		(width 0.14732)
		(layer "In4.Cu")
		(net "UPI_CPU0_CPU1_P1P0_DP<20>")
	)
	(segment
		(start 108.163868 -216.739978)
		(end 108.163106 -216.740486)
		(width 0.0889)
		(layer "In4.Cu")
		(net "UPI_CPU0_CPU1_P1P0_DP<20>")
	)
	(segment
		(start 110.564168 -204.890624)
		(end 110.438184 -205.23708)
		(width 0.14732)
		(layer "In4.Cu")
		(net "UPI_CPU0_CPU1_P1P0_DP<20>")
	)
	(segment
		(start 167.0939 -155.072588)
		(end 165.22446 -155.725368)
		(width 0.14732)
		(layer "In4.Cu")
		(net "UPI_CPU0_CPU1_P1P0_DP<20>")
	)
	(segment
		(start 234.540044 -155.753308)
		(end 197.577964 -165.282372)
		(width 0.14732)
		(layer "In4.Cu")
		(net "UPI_CPU0_CPU1_P1P0_DP<20>")
	)
	(segment
		(start 178.212242 -161.410396)
		(end 178.082194 -160.99536)
		(width 0.14732)
		(layer "In4.Cu")
		(net "UPI_CPU0_CPU1_P1P0_DP<20>")
	)
	(segment
		(start 113.123472 -197.442328)
		(end 110.477554 -204.705204)
		(width 0.14732)
		(layer "In4.Cu")
		(net "UPI_CPU0_CPU1_P1P0_DP<20>")
	)
	(segment
		(start 155.974796 -161.597848)
		(end 156.42717 -162.331654)
		(width 0.14732)
		(layer "In4.Cu")
		(net "UPI_CPU0_CPU1_P1P0_DP<20>")
	)
	(segment
		(start 176.489106 -159.041084)
		(end 176.426876 -158.842456)
		(width 0.14732)
		(layer "In4.Cu")
		(net "UPI_CPU0_CPU1_P1P0_DP<20>")
	)
	(segment
		(start 159.117284 -159.488632)
		(end 158.615126 -159.798004)
		(width 0.14732)
		(layer "In4.Cu")
		(net "UPI_CPU0_CPU1_P1P0_DP<20>")
	)
	(segment
		(start 156.42717 -162.331654)
		(end 156.326586 -162.754818)
		(width 0.14732)
		(layer "In4.Cu")
		(net "UPI_CPU0_CPU1_P1P0_DP<20>")
	)
	(segment
		(start 109.384084 -208.129632)
		(end 109.198156 -208.215992)
		(width 0.14732)
		(layer "In4.Cu")
		(net "UPI_CPU0_CPU1_P1P0_DP<20>")
	)
	(segment
		(start 108.329984 -211.022184)
		(end 108.144056 -211.108544)
		(width 0.14732)
		(layer "In4.Cu")
		(net "UPI_CPU0_CPU1_P1P0_DP<20>")
	)
	(segment
		(start 108.018072 -211.454492)
		(end 108.018072 -211.882228)
		(width 0.14732)
		(layer "In4.Cu")
		(net "UPI_CPU0_CPU1_P1P0_DP<20>")
	)
	(segment
		(start 108.445808 -214.424768)
		(end 108.445808 -214.644732)
		(width 0.0889)
		(layer "In4.Cu")
		(net "UPI_CPU0_CPU1_P1P0_DP<20>")
	)
	(segment
		(start 109.072172 -208.56194)
		(end 109.158786 -208.74736)
		(width 0.14732)
		(layer "In4.Cu")
		(net "UPI_CPU0_CPU1_P1P0_DP<20>")
	)
	(segment
		(start 355.0793 -185.386218)
		(end 355.22408 -185.241438)
		(width 0.14732)
		(layer "In4.Cu")
		(net "UPI_CPU0_CPU1_P1P0_DP<20>")
	)
	(segment
		(start 194.785234 -165.633908)
		(end 189.4078 -165.633908)
		(width 0.14732)
		(layer "In4.Cu")
		(net "UPI_CPU0_CPU1_P1P0_DP<20>")
	)
	(segment
		(start 341.49538 -175.265588)
		(end 333.5401 -171.798488)
		(width 0.14732)
		(layer "In4.Cu")
		(net "UPI_CPU0_CPU1_P1P0_DP<20>")
	)
	(segment
		(start 363.244384 -212.3059)
		(end 363.244384 -211.807298)
		(width 0.0889)
		(layer "In4.Cu")
		(net "UPI_CPU0_CPU1_P1P0_DP<20>")
	)
	(segment
		(start 108.162598 -215.112854)
		(end 108.161836 -215.113362)
		(width 0.0889)
		(layer "In4.Cu")
		(net "UPI_CPU0_CPU1_P1P0_DP<20>")
	)
	(segment
		(start 109.90072 -206.287624)
		(end 109.774736 -206.633572)
		(width 0.14732)
		(layer "In4.Cu")
		(net "UPI_CPU0_CPU1_P1P0_DP<20>")
	)
	(segment
		(start 107.976162 -212.084412)
		(end 107.976162 -212.45576)
		(width 0.0889)
		(layer "In4.Cu")
		(net "UPI_CPU0_CPU1_P1P0_DP<20>")
	)
	(segment
		(start 121.954036 -186.326272)
		(end 113.123472 -197.442328)
		(width 0.14732)
		(layer "In4.Cu")
		(net "UPI_CPU0_CPU1_P1P0_DP<20>")
	)
	(segment
		(start 363.20222 -205.218284)
		(end 357.725218 -191.995298)
		(width 0.14732)
		(layer "In4.Cu")
		(net "UPI_CPU0_CPU1_P1P0_DP<20>")
	)
	(segment
		(start 107.976416 -213.01202)
		(end 107.976162 -213.01202)
		(width 0.0889)
		(layer "In4.Cu")
		(net "UPI_CPU0_CPU1_P1P0_DP<20>")
	)
	(segment
		(start 154.754326 -162.349942)
		(end 154.551888 -162.301936)
		(width 0.14732)
		(layer "In4.Cu")
		(net "UPI_CPU0_CPU1_P1P0_DP<20>")
	)
	(segment
		(start 159.319722 -159.536638)
		(end 159.117284 -159.488632)
		(width 0.14732)
		(layer "In4.Cu")
		(net "UPI_CPU0_CPU1_P1P0_DP<20>")
	)
	(segment
		(start 179.352448 -161.659824)
		(end 178.937412 -161.789872)
		(width 0.14732)
		(layer "In4.Cu")
		(net "UPI_CPU0_CPU1_P1P0_DP<20>")
	)
	(segment
		(start 357.725218 -191.995298)
		(end 356.961948 -191.217296)
		(width 0.14732)
		(layer "In4.Cu")
		(net "UPI_CPU0_CPU1_P1P0_DP<20>")
	)
	(segment
		(start 157.34665 -160.752536)
		(end 157.144212 -160.70453)
		(width 0.14732)
		(layer "In4.Cu")
		(net "UPI_CPU0_CPU1_P1P0_DP<20>")
	)
	(segment
		(start 179.81295 -160.779968)
		(end 179.352448 -161.659824)
		(width 0.14732)
		(layer "In4.Cu")
		(net "UPI_CPU0_CPU1_P1P0_DP<20>")
	)
	(segment
		(start 107.976162 -213.01202)
		(end 107.976162 -213.8934)
		(width 0.0889)
		(layer "In4.Cu")
		(net "UPI_CPU0_CPU1_P1P0_DP<20>")
	)
	(segment
		(start 107.976416 -212.456014)
		(end 107.976416 -213.01202)
		(width 0.0889)
		(layer "In4.Cu")
		(net "UPI_CPU0_CPU1_P1P0_DP<20>")
	)
	(segment
		(start 108.846874 -209.180176)
		(end 108.72089 -209.526124)
		(width 0.14732)
		(layer "In4.Cu")
		(net "UPI_CPU0_CPU1_P1P0_DP<20>")
	)
	(segment
		(start 363.145324 -213.12886)
		(end 363.145324 -212.9536)
		(width 0.0889)
		(layer "In4.Cu")
		(net "UPI_CPU0_CPU1_P1P0_DP<20>")
	)
	(segment
		(start 363.526578 -214.946992)
		(end 363.535468 -214.941912)
		(width 0.0889)
		(layer "In4.Cu")
		(net "UPI_CPU0_CPU1_P1P0_DP<20>")
	)
	(segment
		(start 176.158652 -160.335976)
		(end 176.028604 -159.92094)
		(width 0.14732)
		(layer "In4.Cu")
		(net "UPI_CPU0_CPU1_P1P0_DP<20>")
	)
	(segment
		(start 107.976162 -212.45576)
		(end 107.976416 -212.456014)
		(width 0.0889)
		(layer "In4.Cu")
		(net "UPI_CPU0_CPU1_P1P0_DP<20>")
	)
	(segment
		(start 110.086648 -206.201264)
		(end 109.90072 -206.287624)
		(width 0.14732)
		(layer "In4.Cu")
		(net "UPI_CPU0_CPU1_P1P0_DP<20>")
	)
	(segment
		(start 109.423454 -207.597756)
		(end 109.510068 -207.783176)
		(width 0.14732)
		(layer "In4.Cu")
		(net "UPI_CPU0_CPU1_P1P0_DP<20>")
	)
	(segment
		(start 176.028604 -159.92094)
		(end 176.489106 -159.041084)
		(width 0.14732)
		(layer "In4.Cu")
		(net "UPI_CPU0_CPU1_P1P0_DP<20>")
	)
	(segment
		(start 363.202474 -211.765388)
		(end 363.202474 -211.74329)
		(width 0.0889)
		(layer "In4.Cu")
		(net "UPI_CPU0_CPU1_P1P0_DP<20>")
	)
	(segment
		(start 343.930224 -177.00371)
		(end 341.49538 -175.265588)
		(width 0.14732)
		(layer "In4.Cu")
		(net "UPI_CPU0_CPU1_P1P0_DP<20>")
	)
	(segment
		(start 108.161836 -215.113362)
		(end 108.157772 -215.115648)
		(width 0.0889)
		(layer "In4.Cu")
		(net "UPI_CPU0_CPU1_P1P0_DP<20>")
	)
	(segment
		(start 174.435516 -157.966664)
		(end 174.373286 -157.76829)
		(width 0.14732)
		(layer "In4.Cu")
		(net "UPI_CPU0_CPU1_P1P0_DP<20>")
	)
	(segment
		(start 177.75936 -159.705548)
		(end 177.298858 -160.585404)
		(width 0.14732)
		(layer "In4.Cu")
		(net "UPI_CPU0_CPU1_P1P0_DP<20>")
	)
	(segment
		(start 363.145324 -212.9536)
		(end 363.244384 -212.85454)
		(width 0.0889)
		(layer "In4.Cu")
		(net "UPI_CPU0_CPU1_P1P0_DP<20>")
	)
	(segment
		(start 110.126526 -205.668626)
		(end 110.126272 -205.669388)
		(width 0.14732)
		(layer "In4.Cu")
		(net "UPI_CPU0_CPU1_P1P0_DP<20>")
	)
	(segment
		(start 108.165138 -215.762078)
		(end 108.166408 -215.76284)
		(width 0.0889)
		(layer "In4.Cu")
		(net "UPI_CPU0_CPU1_P1P0_DP<20>")
	)
	(segment
		(start 158.538164 -162.686238)
		(end 157.34665 -160.752536)
		(width 0.14732)
		(layer "In4.Cu")
		(net "UPI_CPU0_CPU1_P1P0_DP<20>")
	)
	(segment
		(start 110.126272 -205.669388)
		(end 110.212632 -205.854808)
		(width 0.14732)
		(layer "In4.Cu")
		(net "UPI_CPU0_CPU1_P1P0_DP<20>")
	)
	(segment
		(start 108.446316 -216.25052)
		(end 108.446316 -216.260426)
		(width 0.0889)
		(layer "In4.Cu")
		(net "UPI_CPU0_CPU1_P1P0_DP<20>")
	)
	(segment
		(start 197.577964 -165.282372)
		(end 194.785234 -165.633908)
		(width 0.14732)
		(layer "In4.Cu")
		(net "UPI_CPU0_CPU1_P1P0_DP<20>")
	)
	(segment
		(start 355.22408 -185.241438)
		(end 355.22408 -184.362598)
		(width 0.14732)
		(layer "In4.Cu")
		(net "UPI_CPU0_CPU1_P1P0_DP<20>")
	)
	(segment
		(start 109.510068 -207.783176)
		(end 109.384084 -208.129632)
		(width 0.14732)
		(layer "In4.Cu")
		(net "UPI_CPU0_CPU1_P1P0_DP<20>")
	)
	(segment
		(start 108.166408 -215.76284)
		(end 108.16971 -215.764618)
		(width 0.0889)
		(layer "In4.Cu")
		(net "UPI_CPU0_CPU1_P1P0_DP<20>")
	)
	(segment
		(start 355.22408 -186.882786)
		(end 355.22408 -185.899298)
		(width 0.14732)
		(layer "In4.Cu")
		(net "UPI_CPU0_CPU1_P1P0_DP<20>")
	)
	(segment
		(start 175.70577 -158.631128)
		(end 175.245268 -159.510984)
		(width 0.14732)
		(layer "In4.Cu")
		(net "UPI_CPU0_CPU1_P1P0_DP<20>")
	)
	(segment
		(start 108.144056 -211.108544)
		(end 108.018072 -211.454492)
		(width 0.14732)
		(layer "In4.Cu")
		(net "UPI_CPU0_CPU1_P1P0_DP<20>")
	)
	(segment
		(start 109.774736 -206.633572)
		(end 109.86135 -206.818992)
		(width 0.14732)
		(layer "In4.Cu")
		(net "UPI_CPU0_CPU1_P1P0_DP<20>")
	)
	(segment
		(start 161.631122 -161.14141)
		(end 160.9344 -161.570924)
		(width 0.14732)
		(layer "In4.Cu")
		(net "UPI_CPU0_CPU1_P1P0_DP<20>")
	)
	(segment
		(start 363.244384 -211.807298)
		(end 363.202474 -211.765388)
		(width 0.0889)
		(layer "In4.Cu")
		(net "UPI_CPU0_CPU1_P1P0_DP<20>")
	)
	(segment
		(start 165.22446 -155.725368)
		(end 160.588198 -158.582106)
		(width 0.14732)
		(layer "In4.Cu")
		(net "UPI_CPU0_CPU1_P1P0_DP<20>")
	)
	(segment
		(start 363.244384 -212.67928)
		(end 363.145324 -212.58022)
		(width 0.0889)
		(layer "In4.Cu")
		(net "UPI_CPU0_CPU1_P1P0_DP<20>")
	)
	(segment
		(start 108.495592 -210.14436)
		(end 108.369608 -210.490308)
		(width 0.14732)
		(layer "In4.Cu")
		(net "UPI_CPU0_CPU1_P1P0_DP<20>")
	)
	(segment
		(start 320.51244 -167.19296)
		(end 314.528454 -165.504622)
		(width 0.14732)
		(layer "In4.Cu")
		(net "UPI_CPU0_CPU1_P1P0_DP<20>")
	)
	(segment
		(start 108.218478 -218.33205)
		(end 108.194348 -218.421204)
		(width 0.0889)
		(layer "In4.Cu")
		(net "UPI_CPU0_CPU1_P1P0_DP<20>")
	)
	(segment
		(start 108.163614 -215.761062)
		(end 108.165138 -215.762078)
		(width 0.0889)
		(layer "In4.Cu")
		(net "UPI_CPU0_CPU1_P1P0_DP<20>")
	)
	(segment
		(start 108.154724 -215.755982)
		(end 108.156756 -215.757252)
		(width 0.0889)
		(layer "In4.Cu")
		(net "UPI_CPU0_CPU1_P1P0_DP<20>")
	)
	(segment
		(start 363.244384 -213.22792)
		(end 363.145324 -213.12886)
		(width 0.0889)
		(layer "In4.Cu")
		(net "UPI_CPU0_CPU1_P1P0_DP<20>")
	)
	(segment
		(start 110.212632 -205.854808)
		(end 110.086648 -206.201264)
		(width 0.14732)
		(layer "In4.Cu")
		(net "UPI_CPU0_CPU1_P1P0_DP<20>")
	)
	(segment
		(start 110.252256 -205.32344)
		(end 110.126526 -205.668626)
		(width 0.14732)
		(layer "In4.Cu")
		(net "UPI_CPU0_CPU1_P1P0_DP<20>")
	)
	(segment
		(start 108.369608 -210.490308)
		(end 108.455968 -210.675728)
		(width 0.14732)
		(layer "In4.Cu")
		(net "UPI_CPU0_CPU1_P1P0_DP<20>")
	)
	(segment
		(start 177.957734 -159.643318)
		(end 177.75936 -159.705548)
		(width 0.14732)
		(layer "In4.Cu")
		(net "UPI_CPU0_CPU1_P1P0_DP<20>")
	)
	(segment
		(start 159.65805 -162.357308)
		(end 158.961328 -162.786822)
		(width 0.14732)
		(layer "In4.Cu")
		(net "UPI_CPU0_CPU1_P1P0_DP<20>")
	)
	(segment
		(start 363.065568 -216.745058)
		(end 363.056678 -216.739978)
		(width 0.0889)
		(layer "In4.Cu")
		(net "UPI_CPU0_CPU1_P1P0_DP<20>")
	)
	(segment
		(start 174.830232 -159.641032)
		(end 174.105062 -159.261556)
		(width 0.14732)
		(layer "In4.Cu")
		(net "UPI_CPU0_CPU1_P1P0_DP<20>")
	)
	(segment
		(start 363.244384 -212.85454)
		(end 363.244384 -212.67928)
		(width 0.0889)
		(layer "In4.Cu")
		(net "UPI_CPU0_CPU1_P1P0_DP<20>")
	)
	(segment
		(start 160.588198 -158.582106)
		(end 160.540192 -158.784544)
		(width 0.14732)
		(layer "In4.Cu")
		(net "UPI_CPU0_CPU1_P1P0_DP<20>")
	)
	(segment
		(start 363.202474 -211.328254)
		(end 363.20222 -211.328)
		(width 0.14732)
		(layer "In4.Cu")
		(net "UPI_CPU0_CPU1_P1P0_DP<20>")
	)
	(segment
		(start 108.157772 -215.115648)
		(end 108.154724 -215.117426)
		(width 0.0889)
		(layer "In4.Cu")
		(net "UPI_CPU0_CPU1_P1P0_DP<20>")
	)
	(segment
		(start 156.326586 -162.754818)
		(end 155.629864 -163.184332)
		(width 0.14732)
		(layer "In4.Cu")
		(net "UPI_CPU0_CPU1_P1P0_DP<20>")
	)
	(segment
		(start 355.0793 -185.754518)
		(end 355.0793 -185.386218)
		(width 0.14732)
		(layer "In4.Cu")
		(net "UPI_CPU0_CPU1_P1P0_DP<20>")
	)
	(segment
		(start 175.904144 -158.568898)
		(end 175.70577 -158.631128)
		(width 0.14732)
		(layer "In4.Cu")
		(net "UPI_CPU0_CPU1_P1P0_DP<20>")
	)
	(segment
		(start 158.56712 -160.000442)
		(end 159.758634 -161.934144)
		(width 0.14732)
		(layer "In4.Cu")
		(net "UPI_CPU0_CPU1_P1P0_DP<20>")
	)
	(segment
		(start 108.163614 -215.112346)
		(end 108.162598 -215.112854)
		(width 0.0889)
		(layer "In4.Cu")
		(net "UPI_CPU0_CPU1_P1P0_DP<20>")
	)
	(segment
		(start 314.528454 -165.504622)
		(end 302.493172 -165.259004)
		(width 0.14732)
		(layer "In4.Cu")
		(net "UPI_CPU0_CPU1_P1P0_DP<20>")
	)
	(segment
		(start 363.145324 -212.58022)
		(end 363.145324 -212.40496)
		(width 0.0889)
		(layer "In4.Cu")
		(net "UPI_CPU0_CPU1_P1P0_DP<20>")
	)
	(segment
		(start 363.260132 -213.970108)
		(end 363.244384 -213.778592)
		(width 0.0889)
		(layer "In4.Cu")
		(net "UPI_CPU0_CPU1_P1P0_DP<20>")
	)
	(segment
		(start 108.446316 -217.859864)
		(end 108.446316 -217.878406)
		(width 0.0889)
		(layer "In4.Cu")
		(net "UPI_CPU0_CPU1_P1P0_DP<20>")
	)
	(segment
		(start 169.1894 -155.128468)
		(end 167.0939 -155.072588)
		(width 0.14732)
		(layer "In4.Cu")
		(net "UPI_CPU0_CPU1_P1P0_DP<20>")
	)
	(segment
		(start 107.976162 -213.8934)
		(end 107.976416 -213.893908)
		(width 0.0889)
		(layer "In4.Cu")
		(net "UPI_CPU0_CPU1_P1P0_DP<20>")
	)
	(segment
		(start 177.298858 -160.585404)
		(end 176.883822 -160.715452)
		(width 0.14732)
		(layer "In4.Cu")
		(net "UPI_CPU0_CPU1_P1P0_DP<20>")
	)
	(segment
		(start 108.018326 -211.882482)
		(end 108.018326 -212.02015)
		(width 0.14732)
		(layer "In4.Cu")
		(net "UPI_CPU0_CPU1_P1P0_DP<20>")
	)
	(segment
		(start 355.22408 -184.362598)
		(end 354.793804 -183.423306)
		(width 0.14732)
		(layer "In4.Cu")
		(net "UPI_CPU0_CPU1_P1P0_DP<20>")
	)
	(segment
		(start 363.71403 -214.622634)
		(end 363.71403 -214.461344)
		(width 0.0889)
		(layer "In4.Cu")
		(net "UPI_CPU0_CPU1_P1P0_DP<20>")
	)
	(segment
		(start 156.022802 -161.39541)
		(end 155.974796 -161.597848)
		(width 0.14732)
		(layer "In4.Cu")
		(net "UPI_CPU0_CPU1_P1P0_DP<20>")
	)
	(segment
		(start 158.615126 -159.798004)
		(end 158.56712 -160.000442)
		(width 0.14732)
		(layer "In4.Cu")
		(net "UPI_CPU0_CPU1_P1P0_DP<20>")
	)
	(segment
		(start 348.001336 -180.796184)
		(end 343.930224 -177.00371)
		(width 0.14732)
		(layer "In4.Cu")
		(net "UPI_CPU0_CPU1_P1P0_DP<20>")
	)
	(segment
		(start 108.807504 -209.711544)
		(end 108.68152 -210.058)
		(width 0.14732)
		(layer "In4.Cu")
		(net "UPI_CPU0_CPU1_P1P0_DP<20>")
	)
	(segment
		(start 351.651316 -180.713126)
		(end 350.678496 -180.575458)
		(width 0.14732)
		(layer "In4.Cu")
		(net "UPI_CPU0_CPU1_P1P0_DP<20>")
	)
	(segment
		(start 178.480466 -159.916876)
		(end 177.957734 -159.643318)
		(width 0.14732)
		(layer "In4.Cu")
		(net "UPI_CPU0_CPU1_P1P0_DP<20>")
	)
	(segment
		(start 109.158786 -208.74736)
		(end 109.032802 -209.093816)
		(width 0.14732)
		(layer "In4.Cu")
		(net "UPI_CPU0_CPU1_P1P0_DP<20>")
	)
	(segment
		(start 302.493172 -165.259004)
		(end 280.167842 -165.644068)
		(width 0.14732)
		(layer "In4.Cu")
		(net "UPI_CPU0_CPU1_P1P0_DP<20>")
	)
	(segment
		(start 160.540192 -158.784544)
		(end 161.731706 -160.718246)
		(width 0.14732)
		(layer "In4.Cu")
		(net "UPI_CPU0_CPU1_P1P0_DP<20>")
	)
	(segment
		(start 108.163106 -217.388186)
		(end 108.163868 -217.388694)
		(width 0.0889)
		(layer "In4.Cu")
		(net "UPI_CPU0_CPU1_P1P0_DP<20>")
	)
	(segment
		(start 354.793804 -183.423306)
		(end 351.651316 -180.713126)
		(width 0.14732)
		(layer "In4.Cu")
		(net "UPI_CPU0_CPU1_P1P0_DP<20>")
	)
	(segment
		(start 109.86135 -206.818992)
		(end 109.735366 -207.165448)
		(width 0.14732)
		(layer "In4.Cu")
		(net "UPI_CPU0_CPU1_P1P0_DP<20>")
	)
	(segment
		(start 108.018326 -212.02015)
		(end 108.018326 -212.042248)
		(width 0.0889)
		(layer "In4.Cu")
		(net "UPI_CPU0_CPU1_P1P0_DP<20>")
	)
	(segment
		(start 157.144212 -160.70453)
		(end 156.022802 -161.39541)
		(width 0.14732)
		(layer "In4.Cu")
		(net "UPI_CPU0_CPU1_P1P0_DP<20>")
	)
	(segment
		(start 134.091934 -174.91075)
		(end 121.954036 -186.326272)
		(width 0.14732)
		(layer "In4.Cu")
		(net "UPI_CPU0_CPU1_P1P0_DP<20>")
	)
	(segment
		(start 108.156756 -215.757252)
		(end 108.163614 -215.761062)
		(width 0.0889)
		(layer "In4.Cu")
		(net "UPI_CPU0_CPU1_P1P0_DP<20>")
	)
	(segment
		(start 363.20222 -211.328)
		(end 363.20222 -205.218284)
		(width 0.14732)
		(layer "In4.Cu")
		(net "UPI_CPU0_CPU1_P1P0_DP<20>")
	)
	(segment
		(start 180.011324 -160.717738)
		(end 179.81295 -160.779968)
		(width 0.14732)
		(layer "In4.Cu")
		(net "UPI_CPU0_CPU1_P1P0_DP<20>")
	)
	(segment
		(start 155.629864 -163.184332)
		(end 155.2067 -163.083748)
		(width 0.14732)
		(layer "In4.Cu")
		(net "UPI_CPU0_CPU1_P1P0_DP<20>")
	)
	(arc
		(start 363.71403 -214.461344)
		(mid 363.639025 -214.345885)
		(end 363.52988 -214.261954)
		(width 0.0889)
		(layer "In4.Cu")
		(net "UPI_CPU0_CPU1_P1P0_DP<20>")
	)
	(arc
		(start 363.056678 -216.739978)
		(mid 362.852343 -216.537373)
		(end 362.77423 -216.260426)
		(width 0.0889)
		(layer "In4.Cu")
		(net "UPI_CPU0_CPU1_P1P0_DP<20>")
	)
	(arc
		(start 363.24413 -215.436704)
		(mid 363.317983 -215.157058)
		(end 363.520482 -214.950548)
		(width 0.0889)
		(layer "In4.Cu")
		(net "UPI_CPU0_CPU1_P1P0_DP<20>")
	)
	(arc
		(start 107.976416 -215.421972)
		(mid 107.976219 -215.429337)
		(end 107.976162 -215.436704)
		(width 0.0889)
		(layer "In4.Cu")
		(net "UPI_CPU0_CPU1_P1P0_DP<20>")
	)
	(arc
		(start 363.065568 -215.755982)
		(mid 363.196482 -215.619622)
		(end 363.24413 -215.436704)
		(width 0.0889)
		(layer "In4.Cu")
		(net "UPI_CPU0_CPU1_P1P0_DP<20>")
	)
	(arc
		(start 363.535468 -214.941912)
		(mid 363.666382 -214.805552)
		(end 363.71403 -214.622634)
		(width 0.0889)
		(layer "In4.Cu")
		(net "UPI_CPU0_CPU1_P1P0_DP<20>")
	)
	(arc
		(start 108.445808 -214.644732)
		(mid 108.364897 -214.91486)
		(end 108.163614 -215.112346)
		(width 0.0889)
		(layer "In4.Cu")
		(net "UPI_CPU0_CPU1_P1P0_DP<20>")
	)
	(arc
		(start 108.160566 -214.093298)
		(mid 108.334529 -214.232062)
		(end 108.445808 -214.424768)
		(width 0.0889)
		(layer "In4.Cu")
		(net "UPI_CPU0_CPU1_P1P0_DP<20>")
	)
	(arc
		(start 108.446316 -217.878406)
		(mid 108.390961 -218.122593)
		(end 108.235496 -218.318842)
		(width 0.0889)
		(layer "In4.Cu")
		(net "UPI_CPU0_CPU1_P1P0_DP<20>")
	)
	(arc
		(start 108.235496 -218.318842)
		(mid 108.22705 -218.325527)
		(end 108.218478 -218.33205)
		(width 0.0889)
		(layer "In4.Cu")
		(net "UPI_CPU0_CPU1_P1P0_DP<20>")
	)
	(arc
		(start 108.16971 -215.764618)
		(mid 108.372297 -215.970969)
		(end 108.446316 -216.25052)
		(width 0.0889)
		(layer "In4.Cu")
		(net "UPI_CPU0_CPU1_P1P0_DP<20>")
	)
	(arc
		(start 363.24413 -217.064336)
		(mid 363.196451 -216.881436)
		(end 363.065568 -216.745058)
		(width 0.0889)
		(layer "In4.Cu")
		(net "UPI_CPU0_CPU1_P1P0_DP<20>")
	)
	(arc
		(start 107.976416 -213.893908)
		(mid 108.051421 -214.009367)
		(end 108.160566 -214.093298)
		(width 0.0889)
		(layer "In4.Cu")
		(net "UPI_CPU0_CPU1_P1P0_DP<20>")
	)
	(arc
		(start 108.154724 -215.117426)
		(mid 108.02747 -215.247392)
		(end 107.976416 -215.421972)
		(width 0.0889)
		(layer "In4.Cu")
		(net "UPI_CPU0_CPU1_P1P0_DP<20>")
	)
	(arc
		(start 362.77423 -216.240614)
		(mid 362.852341 -215.963665)
		(end 363.056678 -215.761062)
		(width 0.0889)
		(layer "In4.Cu")
		(net "UPI_CPU0_CPU1_P1P0_DP<20>")
	)
	(arc
		(start 363.52988 -214.261954)
		(mid 363.370125 -214.13904)
		(end 363.260132 -213.970108)
		(width 0.0889)
		(layer "In4.Cu")
		(net "UPI_CPU0_CPU1_P1P0_DP<20>")
	)
	(arc
		(start 107.976162 -215.436704)
		(mid 108.023841 -215.619604)
		(end 108.154724 -215.755982)
		(width 0.0889)
		(layer "In4.Cu")
		(net "UPI_CPU0_CPU1_P1P0_DP<20>")
	)
	(arc
		(start 363.104176 -217.356182)
		(mid 363.207321 -217.226157)
		(end 363.24413 -217.064336)
		(width 0.0889)
		(layer "In4.Cu")
		(net "UPI_CPU0_CPU1_P1P0_DP<20>")
	)
	(arc
		(start 108.163868 -217.388694)
		(mid 108.366154 -217.587675)
		(end 108.446316 -217.859864)
		(width 0.0889)
		(layer "In4.Cu")
		(net "UPI_CPU0_CPU1_P1P0_DP<20>")
	)
	(arc
		(start 108.446316 -216.260426)
		(mid 108.368205 -216.537375)
		(end 108.163868 -216.739978)
		(width 0.0889)
		(layer "In4.Cu")
		(net "UPI_CPU0_CPU1_P1P0_DP<20>")
	)
	(arc
		(start 108.154978 -216.745058)
		(mid 107.976381 -217.064336)
		(end 108.154978 -217.383614)
		(width 0.0889)
		(layer "In4.Cu")
		(net "UPI_CPU0_CPU1_P1P0_DP<20>")
	)
	(segment
		(start 90.024712 -218.414346)
		(end 90.024712 -217.87866)
		(width 0.13208)
		(layer "F.Cu")
		(net "UPI_CPU0_CPU1_P1P0_DP<1>")
	)
	(segment
		(start 90.024712 -217.87866)
		(end 90.024966 -217.878406)
		(width 0.13208)
		(layer "F.Cu")
		(net "UPI_CPU0_CPU1_P1P0_DP<1>")
	)
	(segment
		(start 381.19558 -218.414346)
		(end 381.19558 -217.87866)
		(width 0.13208)
		(layer "F.Cu")
		(net "UPI_CPU0_CPU1_P1P0_DP<1>")
	)
	(segment
		(start 381.19558 -217.87866)
		(end 381.195834 -217.878406)
		(width 0.13208)
		(layer "F.Cu")
		(net "UPI_CPU0_CPU1_P1P0_DP<1>")
	)
	(segment
		(start 331.445362 -142.001494)
		(end 318.664336 -138.872468)
		(width 0.14732)
		(layer "In4.Cu")
		(net "UPI_CPU0_CPU1_P1P0_DP<1>")
	)
	(segment
		(start 86.275672 -204.705204)
		(end 86.046564 -205.969108)
		(width 0.14732)
		(layer "In4.Cu")
		(net "UPI_CPU0_CPU1_P1P0_DP<1>")
	)
	(segment
		(start 90.205814 -216.578688)
		(end 90.206068 -216.578434)
		(width 0.0889)
		(layer "In4.Cu")
		(net "UPI_CPU0_CPU1_P1P0_DP<1>")
	)
	(segment
		(start 383.368042 -202.175364)
		(end 376.470926 -171.214288)
		(width 0.14732)
		(layer "In4.Cu")
		(net "UPI_CPU0_CPU1_P1P0_DP<1>")
	)
	(segment
		(start 382.234186 -213.761574)
		(end 382.234186 -213.26094)
		(width 0.0889)
		(layer "In4.Cu")
		(net "UPI_CPU0_CPU1_P1P0_DP<1>")
	)
	(segment
		(start 90.399108 -214.461344)
		(end 90.399108 -214.622634)
		(width 0.0889)
		(layer "In4.Cu")
		(net "UPI_CPU0_CPU1_P1P0_DP<1>")
	)
	(segment
		(start 381.195834 -217.878406)
		(end 381.03937 -218.149424)
		(width 0.0889)
		(layer "In4.Cu")
		(net "UPI_CPU0_CPU1_P1P0_DP<1>")
	)
	(segment
		(start 380.999746 -217.559128)
		(end 381.008636 -217.554048)
		(width 0.0889)
		(layer "In4.Cu")
		(net "UPI_CPU0_CPU1_P1P0_DP<1>")
	)
	(segment
		(start 381.03937 -218.149424)
		(end 380.961138 -218.170252)
		(width 0.0889)
		(layer "In4.Cu")
		(net "UPI_CPU0_CPU1_P1P0_DP<1>")
	)
	(segment
		(start 372.047008 -168.111678)
		(end 369.560094 -167.918384)
		(width 0.14732)
		(layer "In4.Cu")
		(net "UPI_CPU0_CPU1_P1P0_DP<1>")
	)
	(segment
		(start 376.083576 -170.633644)
		(end 372.86819 -168.369234)
		(width 0.14732)
		(layer "In4.Cu")
		(net "UPI_CPU0_CPU1_P1P0_DP<1>")
	)
	(segment
		(start 382.276096 -210.528408)
		(end 385.154678 -207.649826)
		(width 0.14732)
		(layer "In4.Cu")
		(net "UPI_CPU0_CPU1_P1P0_DP<1>")
	)
	(segment
		(start 86.075266 -206.86776)
		(end 86.405974 -207.579214)
		(width 0.14732)
		(layer "In4.Cu")
		(net "UPI_CPU0_CPU1_P1P0_DP<1>")
	)
	(segment
		(start 318.664336 -138.872468)
		(end 316.048644 -138.872468)
		(width 0.14732)
		(layer "In4.Cu")
		(net "UPI_CPU0_CPU1_P1P0_DP<1>")
	)
	(segment
		(start 89.929462 -217.064336)
		(end 89.929462 -217.07856)
		(width 0.0889)
		(layer "In4.Cu")
		(net "UPI_CPU0_CPU1_P1P0_DP<1>")
	)
	(segment
		(start 380.999746 -215.931242)
		(end 381.008636 -215.926162)
		(width 0.0889)
		(layer "In4.Cu")
		(net "UPI_CPU0_CPU1_P1P0_DP<1>")
	)
	(segment
		(start 123.391676 -162.20694)
		(end 102.343458 -181.999128)
		(width 0.14732)
		(layer "In4.Cu")
		(net "UPI_CPU0_CPU1_P1P0_DP<1>")
	)
	(segment
		(start 89.88806 -211.631022)
		(end 89.88806 -211.78139)
		(width 0.14732)
		(layer "In4.Cu")
		(net "UPI_CPU0_CPU1_P1P0_DP<1>")
	)
	(segment
		(start 361.137454 -161.068766)
		(end 331.445362 -142.001494)
		(width 0.14732)
		(layer "In4.Cu")
		(net "UPI_CPU0_CPU1_P1P0_DP<1>")
	)
	(segment
		(start 372.86819 -168.369234)
		(end 372.047008 -168.111678)
		(width 0.14732)
		(layer "In4.Cu")
		(net "UPI_CPU0_CPU1_P1P0_DP<1>")
	)
	(segment
		(start 382.234186 -211.967572)
		(end 382.27635 -211.925408)
		(width 0.0889)
		(layer "In4.Cu")
		(net "UPI_CPU0_CPU1_P1P0_DP<1>")
	)
	(segment
		(start 382.234186 -212.33892)
		(end 382.234186 -211.967572)
		(width 0.0889)
		(layer "In4.Cu")
		(net "UPI_CPU0_CPU1_P1P0_DP<1>")
	)
	(segment
		(start 381.478282 -215.112092)
		(end 381.515874 -215.090248)
		(width 0.0889)
		(layer "In4.Cu")
		(net "UPI_CPU0_CPU1_P1P0_DP<1>")
	)
	(segment
		(start 382.333246 -212.43798)
		(end 382.234186 -212.33892)
		(width 0.0889)
		(layer "In4.Cu")
		(net "UPI_CPU0_CPU1_P1P0_DP<1>")
	)
	(segment
		(start 90.212926 -215.92667)
		(end 90.215466 -215.92794)
		(width 0.0889)
		(layer "In4.Cu")
		(net "UPI_CPU0_CPU1_P1P0_DP<1>")
	)
	(segment
		(start 369.560094 -167.918384)
		(end 369.174014 -167.728646)
		(width 0.14732)
		(layer "In4.Cu")
		(net "UPI_CPU0_CPU1_P1P0_DP<1>")
	)
	(segment
		(start 376.470926 -171.214288)
		(end 376.083576 -170.633644)
		(width 0.14732)
		(layer "In4.Cu")
		(net "UPI_CPU0_CPU1_P1P0_DP<1>")
	)
	(segment
		(start 382.27635 -211.493862)
		(end 382.276096 -211.493608)
		(width 0.14732)
		(layer "In4.Cu")
		(net "UPI_CPU0_CPU1_P1P0_DP<1>")
	)
	(segment
		(start 90.18143 -217.607388)
		(end 90.024966 -217.878406)
		(width 0.0889)
		(layer "In4.Cu")
		(net "UPI_CPU0_CPU1_P1P0_DP<1>")
	)
	(segment
		(start 86.405974 -207.579214)
		(end 89.887806 -211.061046)
		(width 0.14732)
		(layer "In4.Cu")
		(net "UPI_CPU0_CPU1_P1P0_DP<1>")
	)
	(segment
		(start 90.221054 -216.569798)
		(end 90.205814 -216.578688)
		(width 0.0889)
		(layer "In4.Cu")
		(net "UPI_CPU0_CPU1_P1P0_DP<1>")
	)
	(segment
		(start 238.602266 -137.591038)
		(end 169.527982 -136.456674)
		(width 0.14732)
		(layer "In4.Cu")
		(net "UPI_CPU0_CPU1_P1P0_DP<1>")
	)
	(segment
		(start 316.048644 -138.872468)
		(end 271.347438 -136.993376)
		(width 0.14732)
		(layer "In4.Cu")
		(net "UPI_CPU0_CPU1_P1P0_DP<1>")
	)
	(segment
		(start 102.343458 -181.999128)
		(end 98.616516 -186.637168)
		(width 0.14732)
		(layer "In4.Cu")
		(net "UPI_CPU0_CPU1_P1P0_DP<1>")
	)
	(segment
		(start 369.174014 -167.728646)
		(end 361.137454 -161.068766)
		(width 0.14732)
		(layer "In4.Cu")
		(net "UPI_CPU0_CPU1_P1P0_DP<1>")
	)
	(segment
		(start 89.92997 -213.930484)
		(end 89.929716 -213.930484)
		(width 0.0889)
		(layer "In4.Cu")
		(net "UPI_CPU0_CPU1_P1P0_DP<1>")
	)
	(segment
		(start 169.527982 -136.456674)
		(end 159.894016 -139.75461)
		(width 0.14732)
		(layer "In4.Cu")
		(net "UPI_CPU0_CPU1_P1P0_DP<1>")
	)
	(segment
		(start 382.234186 -213.26094)
		(end 382.333246 -213.16188)
		(width 0.0889)
		(layer "In4.Cu")
		(net "UPI_CPU0_CPU1_P1P0_DP<1>")
	)
	(segment
		(start 90.215466 -215.92794)
		(end 90.221054 -215.931242)
		(width 0.0889)
		(layer "In4.Cu")
		(net "UPI_CPU0_CPU1_P1P0_DP<1>")
	)
	(segment
		(start 382.234186 -212.88756)
		(end 382.234186 -212.7123)
		(width 0.0889)
		(layer "In4.Cu")
		(net "UPI_CPU0_CPU1_P1P0_DP<1>")
	)
	(segment
		(start 98.616516 -186.637168)
		(end 96.303592 -192.788286)
		(width 0.14732)
		(layer "In4.Cu")
		(net "UPI_CPU0_CPU1_P1P0_DP<1>")
	)
	(segment
		(start 382.333246 -212.61324)
		(end 382.333246 -212.43798)
		(width 0.0889)
		(layer "In4.Cu")
		(net "UPI_CPU0_CPU1_P1P0_DP<1>")
	)
	(segment
		(start 89.88806 -211.803488)
		(end 89.92997 -211.845398)
		(width 0.0889)
		(layer "In4.Cu")
		(net "UPI_CPU0_CPU1_P1P0_DP<1>")
	)
	(segment
		(start 89.92997 -211.845398)
		(end 89.92997 -213.930484)
		(width 0.0889)
		(layer "In4.Cu")
		(net "UPI_CPU0_CPU1_P1P0_DP<1>")
	)
	(segment
		(start 90.220546 -214.941912)
		(end 90.211656 -214.946992)
		(width 0.0889)
		(layer "In4.Cu")
		(net "UPI_CPU0_CPU1_P1P0_DP<1>")
	)
	(segment
		(start 90.1573 -217.518234)
		(end 90.18143 -217.607388)
		(width 0.0889)
		(layer "In4.Cu")
		(net "UPI_CPU0_CPU1_P1P0_DP<1>")
	)
	(segment
		(start 382.09347 -214.102188)
		(end 382.234186 -213.761574)
		(width 0.0889)
		(layer "In4.Cu")
		(net "UPI_CPU0_CPU1_P1P0_DP<1>")
	)
	(segment
		(start 381.918464 -214.239348)
		(end 381.921766 -214.237062)
		(width 0.0889)
		(layer "In4.Cu")
		(net "UPI_CPU0_CPU1_P1P0_DP<1>")
	)
	(segment
		(start 89.887806 -211.630768)
		(end 89.88806 -211.631022)
		(width 0.14732)
		(layer "In4.Cu")
		(net "UPI_CPU0_CPU1_P1P0_DP<1>")
	)
	(segment
		(start 381.291084 -217.082878)
		(end 381.291084 -217.05443)
		(width 0.0889)
		(layer "In4.Cu")
		(net "UPI_CPU0_CPU1_P1P0_DP<1>")
	)
	(segment
		(start 385.604258 -205.111858)
		(end 383.368042 -202.175364)
		(width 0.14732)
		(layer "In4.Cu")
		(net "UPI_CPU0_CPU1_P1P0_DP<1>")
	)
	(segment
		(start 382.27635 -211.925408)
		(end 382.27635 -211.90331)
		(width 0.0889)
		(layer "In4.Cu")
		(net "UPI_CPU0_CPU1_P1P0_DP<1>")
	)
	(segment
		(start 382.333246 -213.16188)
		(end 382.333246 -212.98662)
		(width 0.0889)
		(layer "In4.Cu")
		(net "UPI_CPU0_CPU1_P1P0_DP<1>")
	)
	(segment
		(start 89.887806 -211.061046)
		(end 89.887806 -211.630768)
		(width 0.14732)
		(layer "In4.Cu")
		(net "UPI_CPU0_CPU1_P1P0_DP<1>")
	)
	(segment
		(start 90.20937 -215.924384)
		(end 90.211402 -215.925654)
		(width 0.0889)
		(layer "In4.Cu")
		(net "UPI_CPU0_CPU1_P1P0_DP<1>")
	)
	(segment
		(start 96.303592 -192.788286)
		(end 86.275672 -204.705204)
		(width 0.14732)
		(layer "In4.Cu")
		(net "UPI_CPU0_CPU1_P1P0_DP<1>")
	)
	(segment
		(start 382.276096 -211.493608)
		(end 382.276096 -210.528408)
		(width 0.14732)
		(layer "In4.Cu")
		(net "UPI_CPU0_CPU1_P1P0_DP<1>")
	)
	(segment
		(start 89.88806 -211.78139)
		(end 89.88806 -211.803488)
		(width 0.0889)
		(layer "In4.Cu")
		(net "UPI_CPU0_CPU1_P1P0_DP<1>")
	)
	(segment
		(start 86.046564 -205.969108)
		(end 86.075266 -206.86776)
		(width 0.14732)
		(layer "In4.Cu")
		(net "UPI_CPU0_CPU1_P1P0_DP<1>")
	)
	(segment
		(start 382.234186 -212.7123)
		(end 382.333246 -212.61324)
		(width 0.0889)
		(layer "In4.Cu")
		(net "UPI_CPU0_CPU1_P1P0_DP<1>")
	)
	(segment
		(start 381.008636 -216.574878)
		(end 380.999746 -216.569798)
		(width 0.0889)
		(layer "In4.Cu")
		(net "UPI_CPU0_CPU1_P1P0_DP<1>")
	)
	(segment
		(start 271.347438 -136.993376)
		(end 238.602266 -137.591038)
		(width 0.14732)
		(layer "In4.Cu")
		(net "UPI_CPU0_CPU1_P1P0_DP<1>")
	)
	(segment
		(start 385.604258 -206.564484)
		(end 385.604258 -205.111858)
		(width 0.14732)
		(layer "In4.Cu")
		(net "UPI_CPU0_CPU1_P1P0_DP<1>")
	)
	(segment
		(start 381.92329 -214.236046)
		(end 381.947674 -214.221822)
		(width 0.0889)
		(layer "In4.Cu")
		(net "UPI_CPU0_CPU1_P1P0_DP<1>")
	)
	(segment
		(start 381.291084 -215.454992)
		(end 381.291084 -215.427814)
		(width 0.0889)
		(layer "In4.Cu")
		(net "UPI_CPU0_CPU1_P1P0_DP<1>")
	)
	(segment
		(start 385.154678 -207.649826)
		(end 385.604258 -206.564484)
		(width 0.14732)
		(layer "In4.Cu")
		(net "UPI_CPU0_CPU1_P1P0_DP<1>")
	)
	(segment
		(start 382.333246 -212.98662)
		(end 382.234186 -212.88756)
		(width 0.0889)
		(layer "In4.Cu")
		(net "UPI_CPU0_CPU1_P1P0_DP<1>")
	)
	(segment
		(start 90.211402 -215.925654)
		(end 90.212926 -215.92667)
		(width 0.0889)
		(layer "In4.Cu")
		(net "UPI_CPU0_CPU1_P1P0_DP<1>")
	)
	(segment
		(start 90.206068 -215.922606)
		(end 90.20937 -215.924384)
		(width 0.0889)
		(layer "In4.Cu")
		(net "UPI_CPU0_CPU1_P1P0_DP<1>")
	)
	(segment
		(start 381.921766 -214.237062)
		(end 381.92329 -214.236046)
		(width 0.0889)
		(layer "In4.Cu")
		(net "UPI_CPU0_CPU1_P1P0_DP<1>")
	)
	(segment
		(start 159.894016 -139.75461)
		(end 123.391676 -162.20694)
		(width 0.14732)
		(layer "In4.Cu")
		(net "UPI_CPU0_CPU1_P1P0_DP<1>")
	)
	(segment
		(start 382.27635 -211.90331)
		(end 382.27635 -211.493862)
		(width 0.14732)
		(layer "In4.Cu")
		(net "UPI_CPU0_CPU1_P1P0_DP<1>")
	)
	(arc
		(start 381.515874 -215.090248)
		(mid 381.707368 -214.866399)
		(end 381.76073 -214.57666)
		(width 0.0889)
		(layer "In4.Cu")
		(net "UPI_CPU0_CPU1_P1P0_DP<1>")
	)
	(arc
		(start 90.211656 -214.946992)
		(mid 89.92926 -215.433205)
		(end 90.206068 -215.922606)
		(width 0.0889)
		(layer "In4.Cu")
		(net "UPI_CPU0_CPU1_P1P0_DP<1>")
	)
	(arc
		(start 90.399108 -214.622634)
		(mid 90.351429 -214.805534)
		(end 90.220546 -214.941912)
		(width 0.0889)
		(layer "In4.Cu")
		(net "UPI_CPU0_CPU1_P1P0_DP<1>")
	)
	(arc
		(start 89.944956 -213.969346)
		(mid 90.05495 -214.138715)
		(end 90.214958 -214.261954)
		(width 0.0889)
		(layer "In4.Cu")
		(net "UPI_CPU0_CPU1_P1P0_DP<1>")
	)
	(arc
		(start 381.008636 -217.554048)
		(mid 381.210922 -217.355067)
		(end 381.291084 -217.082878)
		(width 0.0889)
		(layer "In4.Cu")
		(net "UPI_CPU0_CPU1_P1P0_DP<1>")
	)
	(arc
		(start 380.999746 -216.569798)
		(mid 380.870457 -216.436312)
		(end 380.821184 -216.257124)
		(width 0.0889)
		(layer "In4.Cu")
		(net "UPI_CPU0_CPU1_P1P0_DP<1>")
	)
	(arc
		(start 381.291084 -215.427814)
		(mid 381.343354 -215.245449)
		(end 381.478282 -215.112092)
		(width 0.0889)
		(layer "In4.Cu")
		(net "UPI_CPU0_CPU1_P1P0_DP<1>")
	)
	(arc
		(start 381.291084 -217.05443)
		(mid 381.212973 -216.777481)
		(end 381.008636 -216.574878)
		(width 0.0889)
		(layer "In4.Cu")
		(net "UPI_CPU0_CPU1_P1P0_DP<1>")
	)
	(arc
		(start 381.947674 -214.221822)
		(mid 382.025605 -214.168138)
		(end 382.09347 -214.102188)
		(width 0.0889)
		(layer "In4.Cu")
		(net "UPI_CPU0_CPU1_P1P0_DP<1>")
	)
	(arc
		(start 380.961138 -218.170252)
		(mid 380.857993 -218.040227)
		(end 380.821184 -217.878406)
		(width 0.0889)
		(layer "In4.Cu")
		(net "UPI_CPU0_CPU1_P1P0_DP<1>")
	)
	(arc
		(start 380.821184 -216.257124)
		(mid 380.821194 -216.247724)
		(end 380.821438 -216.238328)
		(width 0.0889)
		(layer "In4.Cu")
		(net "UPI_CPU0_CPU1_P1P0_DP<1>")
	)
	(arc
		(start 89.929716 -213.930484)
		(mid 89.937001 -213.950046)
		(end 89.944956 -213.969346)
		(width 0.0889)
		(layer "In4.Cu")
		(net "UPI_CPU0_CPU1_P1P0_DP<1>")
	)
	(arc
		(start 380.821438 -216.238328)
		(mid 380.871931 -216.06235)
		(end 380.999746 -215.931242)
		(width 0.0889)
		(layer "In4.Cu")
		(net "UPI_CPU0_CPU1_P1P0_DP<1>")
	)
	(arc
		(start 90.140282 -217.50528)
		(mid 90.14873 -217.511837)
		(end 90.1573 -217.518234)
		(width 0.0889)
		(layer "In4.Cu")
		(net "UPI_CPU0_CPU1_P1P0_DP<1>")
	)
	(arc
		(start 90.206068 -216.578434)
		(mid 90.003481 -216.784785)
		(end 89.929462 -217.064336)
		(width 0.0889)
		(layer "In4.Cu")
		(net "UPI_CPU0_CPU1_P1P0_DP<1>")
	)
	(arc
		(start 90.214958 -214.261954)
		(mid 90.324105 -214.345882)
		(end 90.399108 -214.461344)
		(width 0.0889)
		(layer "In4.Cu")
		(net "UPI_CPU0_CPU1_P1P0_DP<1>")
	)
	(arc
		(start 380.821184 -217.878406)
		(mid 380.868863 -217.695506)
		(end 380.999746 -217.559128)
		(width 0.0889)
		(layer "In4.Cu")
		(net "UPI_CPU0_CPU1_P1P0_DP<1>")
	)
	(arc
		(start 89.929462 -217.07856)
		(mid 89.987756 -217.315203)
		(end 90.140282 -217.50528)
		(width 0.0889)
		(layer "In4.Cu")
		(net "UPI_CPU0_CPU1_P1P0_DP<1>")
	)
	(arc
		(start 381.008636 -215.926162)
		(mid 381.210922 -215.727181)
		(end 381.291084 -215.454992)
		(width 0.0889)
		(layer "In4.Cu")
		(net "UPI_CPU0_CPU1_P1P0_DP<1>")
	)
	(arc
		(start 381.76073 -214.57666)
		(mid 381.794924 -214.387113)
		(end 381.918464 -214.239348)
		(width 0.0889)
		(layer "In4.Cu")
		(net "UPI_CPU0_CPU1_P1P0_DP<1>")
	)
	(arc
		(start 90.221054 -215.931242)
		(mid 90.399651 -216.25052)
		(end 90.221054 -216.569798)
		(width 0.0889)
		(layer "In4.Cu")
		(net "UPI_CPU0_CPU1_P1P0_DP<1>")
	)
	(segment
		(start 364.27918 -218.414346)
		(end 364.27918 -217.87866)
		(width 0.13208)
		(layer "F.Cu")
		(net "UPI_CPU0_CPU1_P1P0_DP<19>")
	)
	(segment
		(start 106.941112 -218.414346)
		(end 106.941112 -217.87866)
		(width 0.13208)
		(layer "F.Cu")
		(net "UPI_CPU0_CPU1_P1P0_DP<19>")
	)
	(segment
		(start 364.27918 -217.87866)
		(end 364.279434 -217.878406)
		(width 0.13208)
		(layer "F.Cu")
		(net "UPI_CPU0_CPU1_P1P0_DP<19>")
	)
	(segment
		(start 106.941112 -217.87866)
		(end 106.941366 -217.878406)
		(width 0.13208)
		(layer "F.Cu")
		(net "UPI_CPU0_CPU1_P1P0_DP<19>")
	)
	(segment
		(start 107.137454 -216.569798)
		(end 107.130088 -216.574116)
		(width 0.0889)
		(layer "In4.Cu")
		(net "UPI_CPU0_CPU1_P1P0_DP<19>")
	)
	(segment
		(start 311.754012 -161.954972)
		(end 311.440322 -162.25647)
		(width 0.14732)
		(layer "In4.Cu")
		(net "UPI_CPU0_CPU1_P1P0_DP<19>")
	)
	(segment
		(start 364.12297 -218.149424)
		(end 364.044738 -218.170252)
		(width 0.0889)
		(layer "In4.Cu")
		(net "UPI_CPU0_CPU1_P1P0_DP<19>")
	)
	(segment
		(start 310.516778 -164.171122)
		(end 310.556402 -162.23869)
		(width 0.14732)
		(layer "In4.Cu")
		(net "UPI_CPU0_CPU1_P1P0_DP<19>")
	)
	(segment
		(start 308.93385 -164.28593)
		(end 308.344062 -164.273484)
		(width 0.14732)
		(layer "In4.Cu")
		(net "UPI_CPU0_CPU1_P1P0_DP<19>")
	)
	(segment
		(start 106.804206 -212.042248)
		(end 106.846116 -212.084158)
		(width 0.0889)
		(layer "In4.Cu")
		(net "UPI_CPU0_CPU1_P1P0_DP<19>")
	)
	(segment
		(start 280.569924 -164.529008)
		(end 276.290024 -164.529008)
		(width 0.14732)
		(layer "In4.Cu")
		(net "UPI_CPU0_CPU1_P1P0_DP<19>")
	)
	(segment
		(start 106.803952 -211.582508)
		(end 106.804206 -211.582762)
		(width 0.14732)
		(layer "In4.Cu")
		(net "UPI_CPU0_CPU1_P1P0_DP<19>")
	)
	(segment
		(start 111.865156 -197.223888)
		(end 106.803952 -211.117942)
		(width 0.14732)
		(layer "In4.Cu")
		(net "UPI_CPU0_CPU1_P1P0_DP<19>")
	)
	(segment
		(start 364.083346 -215.931242)
		(end 364.092236 -215.926162)
		(width 0.0889)
		(layer "In4.Cu")
		(net "UPI_CPU0_CPU1_P1P0_DP<19>")
	)
	(segment
		(start 364.844584 -214.636858)
		(end 364.844584 -214.425022)
		(width 0.0889)
		(layer "In4.Cu")
		(net "UPI_CPU0_CPU1_P1P0_DP<19>")
	)
	(segment
		(start 234.399328 -154.645868)
		(end 197.369684 -164.192204)
		(width 0.14732)
		(layer "In4.Cu")
		(net "UPI_CPU0_CPU1_P1P0_DP<19>")
	)
	(segment
		(start 364.416594 -205.238604)
		(end 358.659176 -191.3382)
		(width 0.14732)
		(layer "In4.Cu")
		(net "UPI_CPU0_CPU1_P1P0_DP<19>")
	)
	(segment
		(start 276.290024 -164.529008)
		(end 237.845346 -154.654504)
		(width 0.14732)
		(layer "In4.Cu")
		(net "UPI_CPU0_CPU1_P1P0_DP<19>")
	)
	(segment
		(start 302.122586 -164.14623)
		(end 280.569924 -164.519356)
		(width 0.14732)
		(layer "In4.Cu")
		(net "UPI_CPU0_CPU1_P1P0_DP<19>")
	)
	(segment
		(start 347.366844 -178.140106)
		(end 342.154256 -174.340774)
		(width 0.14732)
		(layer "In4.Cu")
		(net "UPI_CPU0_CPU1_P1P0_DP<19>")
	)
	(segment
		(start 172.315886 -155.321)
		(end 169.48912 -153.921206)
		(width 0.14732)
		(layer "In4.Cu")
		(net "UPI_CPU0_CPU1_P1P0_DP<19>")
	)
	(segment
		(start 312.833766 -164.21862)
		(end 312.87339 -162.286188)
		(width 0.14732)
		(layer "In4.Cu")
		(net "UPI_CPU0_CPU1_P1P0_DP<19>")
	)
	(segment
		(start 107.315508 -214.461344)
		(end 107.315508 -214.622634)
		(width 0.0889)
		(layer "In4.Cu")
		(net "UPI_CPU0_CPU1_P1P0_DP<19>")
	)
	(segment
		(start 356.339394 -186.720226)
		(end 356.339394 -184.10174)
		(width 0.14732)
		(layer "In4.Cu")
		(net "UPI_CPU0_CPU1_P1P0_DP<19>")
	)
	(segment
		(start 237.845346 -154.654504)
		(end 237.845346 -154.65425)
		(width 0.14732)
		(layer "In4.Cu")
		(net "UPI_CPU0_CPU1_P1P0_DP<19>")
	)
	(segment
		(start 356.339394 -184.10174)
		(end 355.657658 -182.592472)
		(width 0.14732)
		(layer "In4.Cu")
		(net "UPI_CPU0_CPU1_P1P0_DP<19>")
	)
	(segment
		(start 307.937662 -161.876994)
		(end 307.120036 -161.859976)
		(width 0.14732)
		(layer "In4.Cu")
		(net "UPI_CPU0_CPU1_P1P0_DP<19>")
	)
	(segment
		(start 364.374684 -211.769452)
		(end 364.416848 -211.727288)
		(width 0.0889)
		(layer "In4.Cu")
		(net "UPI_CPU0_CPU1_P1P0_DP<19>")
	)
	(segment
		(start 311.400698 -164.189156)
		(end 311.250838 -164.333428)
		(width 0.14732)
		(layer "In4.Cu")
		(net "UPI_CPU0_CPU1_P1P0_DP<19>")
	)
	(segment
		(start 306.806346 -162.161474)
		(end 306.766722 -164.09416)
		(width 0.14732)
		(layer "In4.Cu")
		(net "UPI_CPU0_CPU1_P1P0_DP<19>")
	)
	(segment
		(start 107.131866 -215.928194)
		(end 107.132882 -215.928702)
		(width 0.0889)
		(layer "In4.Cu")
		(net "UPI_CPU0_CPU1_P1P0_DP<19>")
	)
	(segment
		(start 107.122468 -215.922606)
		(end 107.12577 -215.924384)
		(width 0.0889)
		(layer "In4.Cu")
		(net "UPI_CPU0_CPU1_P1P0_DP<19>")
	)
	(segment
		(start 309.437024 -161.907474)
		(end 309.123334 -162.208972)
		(width 0.14732)
		(layer "In4.Cu")
		(net "UPI_CPU0_CPU1_P1P0_DP<19>")
	)
	(segment
		(start 350.584516 -178.034696)
		(end 349.158814 -178.3207)
		(width 0.14732)
		(layer "In4.Cu")
		(net "UPI_CPU0_CPU1_P1P0_DP<19>")
	)
	(segment
		(start 314.848494 -164.406072)
		(end 312.978038 -164.36848)
		(width 0.14732)
		(layer "In4.Cu")
		(net "UPI_CPU0_CPU1_P1P0_DP<19>")
	)
	(segment
		(start 133.467602 -173.979078)
		(end 121.068846 -185.639202)
		(width 0.14732)
		(layer "In4.Cu")
		(net "UPI_CPU0_CPU1_P1P0_DP<19>")
	)
	(segment
		(start 312.87339 -162.286188)
		(end 312.571638 -161.97199)
		(width 0.14732)
		(layer "In4.Cu")
		(net "UPI_CPU0_CPU1_P1P0_DP<19>")
	)
	(segment
		(start 309.08371 -164.141658)
		(end 308.93385 -164.28593)
		(width 0.14732)
		(layer "In4.Cu")
		(net "UPI_CPU0_CPU1_P1P0_DP<19>")
	)
	(segment
		(start 194.715638 -164.526468)
		(end 189.911228 -164.526468)
		(width 0.14732)
		(layer "In4.Cu")
		(net "UPI_CPU0_CPU1_P1P0_DP<19>")
	)
	(segment
		(start 106.804206 -211.582762)
		(end 106.804206 -212.02015)
		(width 0.14732)
		(layer "In4.Cu")
		(net "UPI_CPU0_CPU1_P1P0_DP<19>")
	)
	(segment
		(start 107.136946 -214.941912)
		(end 107.128056 -214.946992)
		(width 0.0889)
		(layer "In4.Cu")
		(net "UPI_CPU0_CPU1_P1P0_DP<19>")
	)
	(segment
		(start 305.620674 -161.829496)
		(end 304.803048 -161.812478)
		(width 0.14732)
		(layer "In4.Cu")
		(net "UPI_CPU0_CPU1_P1P0_DP<19>")
	)
	(segment
		(start 304.299874 -164.190934)
		(end 302.122586 -164.14623)
		(width 0.14732)
		(layer "In4.Cu")
		(net "UPI_CPU0_CPU1_P1P0_DP<19>")
	)
	(segment
		(start 312.978038 -164.36848)
		(end 312.833766 -164.21862)
		(width 0.14732)
		(layer "In4.Cu")
		(net "UPI_CPU0_CPU1_P1P0_DP<19>")
	)
	(segment
		(start 357.955596 -190.621158)
		(end 356.339394 -186.720226)
		(width 0.14732)
		(layer "In4.Cu")
		(net "UPI_CPU0_CPU1_P1P0_DP<19>")
	)
	(segment
		(start 304.803048 -161.812478)
		(end 304.489358 -162.113976)
		(width 0.14732)
		(layer "In4.Cu")
		(net "UPI_CPU0_CPU1_P1P0_DP<19>")
	)
	(segment
		(start 364.37443 -215.455246)
		(end 364.374684 -215.436704)
		(width 0.0889)
		(layer "In4.Cu")
		(net "UPI_CPU0_CPU1_P1P0_DP<19>")
	)
	(segment
		(start 308.344062 -164.273484)
		(end 308.19979 -164.123624)
		(width 0.14732)
		(layer "In4.Cu")
		(net "UPI_CPU0_CPU1_P1P0_DP<19>")
	)
	(segment
		(start 310.66105 -164.320982)
		(end 310.516778 -164.171122)
		(width 0.14732)
		(layer "In4.Cu")
		(net "UPI_CPU0_CPU1_P1P0_DP<19>")
	)
	(segment
		(start 237.845346 -154.65425)
		(end 237.811818 -154.645868)
		(width 0.14732)
		(layer "In4.Cu")
		(net "UPI_CPU0_CPU1_P1P0_DP<19>")
	)
	(segment
		(start 304.449734 -164.046662)
		(end 304.299874 -164.190934)
		(width 0.14732)
		(layer "In4.Cu")
		(net "UPI_CPU0_CPU1_P1P0_DP<19>")
	)
	(segment
		(start 307.120036 -161.859976)
		(end 306.806346 -162.161474)
		(width 0.14732)
		(layer "In4.Cu")
		(net "UPI_CPU0_CPU1_P1P0_DP<19>")
	)
	(segment
		(start 348.450408 -178.420776)
		(end 347.366844 -178.140106)
		(width 0.14732)
		(layer "In4.Cu")
		(net "UPI_CPU0_CPU1_P1P0_DP<19>")
	)
	(segment
		(start 306.766722 -164.09416)
		(end 306.616862 -164.238432)
		(width 0.14732)
		(layer "In4.Cu")
		(net "UPI_CPU0_CPU1_P1P0_DP<19>")
	)
	(segment
		(start 107.12577 -215.924384)
		(end 107.131866 -215.928194)
		(width 0.0889)
		(layer "In4.Cu")
		(net "UPI_CPU0_CPU1_P1P0_DP<19>")
	)
	(segment
		(start 165.112192 -154.477974)
		(end 133.467602 -173.979078)
		(width 0.14732)
		(layer "In4.Cu")
		(net "UPI_CPU0_CPU1_P1P0_DP<19>")
	)
	(segment
		(start 166.903654 -153.852372)
		(end 165.112192 -154.477974)
		(width 0.14732)
		(layer "In4.Cu")
		(net "UPI_CPU0_CPU1_P1P0_DP<19>")
	)
	(segment
		(start 106.803952 -211.117942)
		(end 106.803952 -211.582508)
		(width 0.14732)
		(layer "In4.Cu")
		(net "UPI_CPU0_CPU1_P1P0_DP<19>")
	)
	(segment
		(start 351.061782 -178.106832)
		(end 350.584516 -178.034696)
		(width 0.14732)
		(layer "In4.Cu")
		(net "UPI_CPU0_CPU1_P1P0_DP<19>")
	)
	(segment
		(start 312.571638 -161.97199)
		(end 311.754012 -161.954972)
		(width 0.14732)
		(layer "In4.Cu")
		(net "UPI_CPU0_CPU1_P1P0_DP<19>")
	)
	(segment
		(start 311.440322 -162.25647)
		(end 311.400698 -164.189156)
		(width 0.14732)
		(layer "In4.Cu")
		(net "UPI_CPU0_CPU1_P1P0_DP<19>")
	)
	(segment
		(start 364.374684 -213.1949)
		(end 364.473744 -213.09584)
		(width 0.0889)
		(layer "In4.Cu")
		(net "UPI_CPU0_CPU1_P1P0_DP<19>")
	)
	(segment
		(start 107.09783 -217.607388)
		(end 106.941366 -217.878406)
		(width 0.0889)
		(layer "In4.Cu")
		(net "UPI_CPU0_CPU1_P1P0_DP<19>")
	)
	(segment
		(start 305.882802 -164.076126)
		(end 305.922426 -162.143694)
		(width 0.14732)
		(layer "In4.Cu")
		(net "UPI_CPU0_CPU1_P1P0_DP<19>")
	)
	(segment
		(start 364.092236 -216.574878)
		(end 364.083346 -216.569798)
		(width 0.0889)
		(layer "In4.Cu")
		(net "UPI_CPU0_CPU1_P1P0_DP<19>")
	)
	(segment
		(start 364.083346 -217.559128)
		(end 364.092236 -217.554048)
		(width 0.0889)
		(layer "In4.Cu")
		(net "UPI_CPU0_CPU1_P1P0_DP<19>")
	)
	(segment
		(start 364.416848 -211.727288)
		(end 364.416848 -211.70519)
		(width 0.0889)
		(layer "In4.Cu")
		(net "UPI_CPU0_CPU1_P1P0_DP<19>")
	)
	(segment
		(start 364.473744 -212.52434)
		(end 364.473744 -212.34908)
		(width 0.0889)
		(layer "In4.Cu")
		(net "UPI_CPU0_CPU1_P1P0_DP<19>")
	)
	(segment
		(start 305.922426 -162.143694)
		(end 305.620674 -161.829496)
		(width 0.14732)
		(layer "In4.Cu")
		(net "UPI_CPU0_CPU1_P1P0_DP<19>")
	)
	(segment
		(start 107.0737 -217.518234)
		(end 107.09783 -217.607388)
		(width 0.0889)
		(layer "In4.Cu")
		(net "UPI_CPU0_CPU1_P1P0_DP<19>")
	)
	(segment
		(start 237.811818 -154.645868)
		(end 234.399328 -154.645868)
		(width 0.14732)
		(layer "In4.Cu")
		(net "UPI_CPU0_CPU1_P1P0_DP<19>")
	)
	(segment
		(start 355.657658 -182.592472)
		(end 351.957386 -179.331366)
		(width 0.14732)
		(layer "In4.Cu")
		(net "UPI_CPU0_CPU1_P1P0_DP<19>")
	)
	(segment
		(start 106.846116 -212.084158)
		(end 106.846116 -213.930484)
		(width 0.0889)
		(layer "In4.Cu")
		(net "UPI_CPU0_CPU1_P1P0_DP<19>")
	)
	(segment
		(start 364.374684 -212.6234)
		(end 364.473744 -212.52434)
		(width 0.0889)
		(layer "In4.Cu")
		(net "UPI_CPU0_CPU1_P1P0_DP<19>")
	)
	(segment
		(start 364.473744 -212.92058)
		(end 364.374684 -212.82152)
		(width 0.0889)
		(layer "In4.Cu")
		(net "UPI_CPU0_CPU1_P1P0_DP<19>")
	)
	(segment
		(start 332.3717 -170.05935)
		(end 323.851524 -166.924228)
		(width 0.14732)
		(layer "In4.Cu")
		(net "UPI_CPU0_CPU1_P1P0_DP<19>")
	)
	(segment
		(start 364.374684 -213.8934)
		(end 364.374684 -213.1949)
		(width 0.0889)
		(layer "In4.Cu")
		(net "UPI_CPU0_CPU1_P1P0_DP<19>")
	)
	(segment
		(start 351.957386 -179.331366)
		(end 351.554796 -178.628802)
		(width 0.14732)
		(layer "In4.Cu")
		(net "UPI_CPU0_CPU1_P1P0_DP<19>")
	)
	(segment
		(start 364.473744 -213.09584)
		(end 364.473744 -212.92058)
		(width 0.0889)
		(layer "In4.Cu")
		(net "UPI_CPU0_CPU1_P1P0_DP<19>")
	)
	(segment
		(start 280.569924 -164.519356)
		(end 280.569924 -164.529008)
		(width 0.14732)
		(layer "In4.Cu")
		(net "UPI_CPU0_CPU1_P1P0_DP<19>")
	)
	(segment
		(start 106.845862 -217.064336)
		(end 106.845862 -217.07856)
		(width 0.0889)
		(layer "In4.Cu")
		(net "UPI_CPU0_CPU1_P1P0_DP<19>")
	)
	(segment
		(start 310.25465 -161.924492)
		(end 309.437024 -161.907474)
		(width 0.14732)
		(layer "In4.Cu")
		(net "UPI_CPU0_CPU1_P1P0_DP<19>")
	)
	(segment
		(start 107.132882 -215.928702)
		(end 107.137454 -215.931496)
		(width 0.0889)
		(layer "In4.Cu")
		(net "UPI_CPU0_CPU1_P1P0_DP<19>")
	)
	(segment
		(start 310.556402 -162.23869)
		(end 310.25465 -161.924492)
		(width 0.14732)
		(layer "In4.Cu")
		(net "UPI_CPU0_CPU1_P1P0_DP<19>")
	)
	(segment
		(start 351.554796 -178.628802)
		(end 351.061782 -178.106832)
		(width 0.14732)
		(layer "In4.Cu")
		(net "UPI_CPU0_CPU1_P1P0_DP<19>")
	)
	(segment
		(start 308.239414 -162.191192)
		(end 307.937662 -161.876994)
		(width 0.14732)
		(layer "In4.Cu")
		(net "UPI_CPU0_CPU1_P1P0_DP<19>")
	)
	(segment
		(start 364.416848 -211.70519)
		(end 364.416848 -211.214462)
		(width 0.14732)
		(layer "In4.Cu")
		(net "UPI_CPU0_CPU1_P1P0_DP<19>")
	)
	(segment
		(start 364.374684 -217.082878)
		(end 364.374684 -217.05443)
		(width 0.0889)
		(layer "In4.Cu")
		(net "UPI_CPU0_CPU1_P1P0_DP<19>")
	)
	(segment
		(start 364.416594 -211.214208)
		(end 364.416594 -205.238604)
		(width 0.14732)
		(layer "In4.Cu")
		(net "UPI_CPU0_CPU1_P1P0_DP<19>")
	)
	(segment
		(start 358.659176 -191.3382)
		(end 357.955596 -190.621158)
		(width 0.14732)
		(layer "In4.Cu")
		(net "UPI_CPU0_CPU1_P1P0_DP<19>")
	)
	(segment
		(start 349.158814 -178.3207)
		(end 348.450408 -178.420776)
		(width 0.14732)
		(layer "In4.Cu")
		(net "UPI_CPU0_CPU1_P1P0_DP<19>")
	)
	(segment
		(start 106.804206 -212.02015)
		(end 106.804206 -212.042248)
		(width 0.0889)
		(layer "In4.Cu")
		(net "UPI_CPU0_CPU1_P1P0_DP<19>")
	)
	(segment
		(start 364.473744 -212.34908)
		(end 364.374684 -212.25002)
		(width 0.0889)
		(layer "In4.Cu")
		(net "UPI_CPU0_CPU1_P1P0_DP<19>")
	)
	(segment
		(start 364.374684 -215.436704)
		(end 364.374684 -215.428068)
		(width 0.0889)
		(layer "In4.Cu")
		(net "UPI_CPU0_CPU1_P1P0_DP<19>")
	)
	(segment
		(start 197.369684 -164.192204)
		(end 194.715638 -164.526468)
		(width 0.14732)
		(layer "In4.Cu")
		(net "UPI_CPU0_CPU1_P1P0_DP<19>")
	)
	(segment
		(start 364.279434 -217.878406)
		(end 364.12297 -218.149424)
		(width 0.0889)
		(layer "In4.Cu")
		(net "UPI_CPU0_CPU1_P1P0_DP<19>")
	)
	(segment
		(start 169.48912 -153.921206)
		(end 166.903654 -153.852372)
		(width 0.14732)
		(layer "In4.Cu")
		(net "UPI_CPU0_CPU1_P1P0_DP<19>")
	)
	(segment
		(start 304.489358 -162.113976)
		(end 304.449734 -164.046662)
		(width 0.14732)
		(layer "In4.Cu")
		(net "UPI_CPU0_CPU1_P1P0_DP<19>")
	)
	(segment
		(start 107.130088 -216.574116)
		(end 107.122468 -216.578434)
		(width 0.0889)
		(layer "In4.Cu")
		(net "UPI_CPU0_CPU1_P1P0_DP<19>")
	)
	(segment
		(start 309.123334 -162.208972)
		(end 309.08371 -164.141658)
		(width 0.14732)
		(layer "In4.Cu")
		(net "UPI_CPU0_CPU1_P1P0_DP<19>")
	)
	(segment
		(start 364.416848 -211.214462)
		(end 364.416594 -211.214208)
		(width 0.14732)
		(layer "In4.Cu")
		(net "UPI_CPU0_CPU1_P1P0_DP<19>")
	)
	(segment
		(start 306.616862 -164.238432)
		(end 306.027074 -164.225986)
		(width 0.14732)
		(layer "In4.Cu")
		(net "UPI_CPU0_CPU1_P1P0_DP<19>")
	)
	(segment
		(start 342.154256 -174.340774)
		(end 332.3717 -170.05935)
		(width 0.14732)
		(layer "In4.Cu")
		(net "UPI_CPU0_CPU1_P1P0_DP<19>")
	)
	(segment
		(start 306.027074 -164.225986)
		(end 305.882802 -164.076126)
		(width 0.14732)
		(layer "In4.Cu")
		(net "UPI_CPU0_CPU1_P1P0_DP<19>")
	)
	(segment
		(start 323.851524 -166.924228)
		(end 314.848494 -164.406072)
		(width 0.14732)
		(layer "In4.Cu")
		(net "UPI_CPU0_CPU1_P1P0_DP<19>")
	)
	(segment
		(start 364.374684 -212.82152)
		(end 364.374684 -212.6234)
		(width 0.0889)
		(layer "In4.Cu")
		(net "UPI_CPU0_CPU1_P1P0_DP<19>")
	)
	(segment
		(start 189.911228 -164.526468)
		(end 172.315886 -155.321)
		(width 0.14732)
		(layer "In4.Cu")
		(net "UPI_CPU0_CPU1_P1P0_DP<19>")
	)
	(segment
		(start 364.374684 -212.25002)
		(end 364.374684 -211.769452)
		(width 0.0889)
		(layer "In4.Cu")
		(net "UPI_CPU0_CPU1_P1P0_DP<19>")
	)
	(segment
		(start 107.137454 -215.931496)
		(end 107.137454 -215.931242)
		(width 0.0889)
		(layer "In4.Cu")
		(net "UPI_CPU0_CPU1_P1P0_DP<19>")
	)
	(segment
		(start 121.068846 -185.639202)
		(end 111.865156 -197.223888)
		(width 0.14732)
		(layer "In4.Cu")
		(net "UPI_CPU0_CPU1_P1P0_DP<19>")
	)
	(segment
		(start 308.19979 -164.123624)
		(end 308.239414 -162.191192)
		(width 0.14732)
		(layer "In4.Cu")
		(net "UPI_CPU0_CPU1_P1P0_DP<19>")
	)
	(segment
		(start 311.250838 -164.333428)
		(end 310.66105 -164.320982)
		(width 0.14732)
		(layer "In4.Cu")
		(net "UPI_CPU0_CPU1_P1P0_DP<19>")
	)
	(arc
		(start 107.122468 -216.578434)
		(mid 106.919881 -216.784785)
		(end 106.845862 -217.064336)
		(width 0.0889)
		(layer "In4.Cu")
		(net "UPI_CPU0_CPU1_P1P0_DP<19>")
	)
	(arc
		(start 107.131358 -214.261954)
		(mid 107.240505 -214.345882)
		(end 107.315508 -214.461344)
		(width 0.0889)
		(layer "In4.Cu")
		(net "UPI_CPU0_CPU1_P1P0_DP<19>")
	)
	(arc
		(start 107.315508 -214.622634)
		(mid 107.267829 -214.805534)
		(end 107.136946 -214.941912)
		(width 0.0889)
		(layer "In4.Cu")
		(net "UPI_CPU0_CPU1_P1P0_DP<19>")
	)
	(arc
		(start 364.083346 -216.569798)
		(mid 363.904749 -216.25052)
		(end 364.083346 -215.931242)
		(width 0.0889)
		(layer "In4.Cu")
		(net "UPI_CPU0_CPU1_P1P0_DP<19>")
	)
	(arc
		(start 364.092236 -215.926162)
		(mid 364.294278 -215.727239)
		(end 364.37443 -215.455246)
		(width 0.0889)
		(layer "In4.Cu")
		(net "UPI_CPU0_CPU1_P1P0_DP<19>")
	)
	(arc
		(start 364.044738 -218.170252)
		(mid 363.941593 -218.040227)
		(end 363.904784 -217.878406)
		(width 0.0889)
		(layer "In4.Cu")
		(net "UPI_CPU0_CPU1_P1P0_DP<19>")
	)
	(arc
		(start 363.904784 -217.878406)
		(mid 363.952463 -217.695506)
		(end 364.083346 -217.559128)
		(width 0.0889)
		(layer "In4.Cu")
		(net "UPI_CPU0_CPU1_P1P0_DP<19>")
	)
	(arc
		(start 107.128056 -214.946992)
		(mid 106.845533 -215.433205)
		(end 107.122468 -215.922606)
		(width 0.0889)
		(layer "In4.Cu")
		(net "UPI_CPU0_CPU1_P1P0_DP<19>")
	)
	(arc
		(start 364.374684 -217.05443)
		(mid 364.296573 -216.777481)
		(end 364.092236 -216.574878)
		(width 0.0889)
		(layer "In4.Cu")
		(net "UPI_CPU0_CPU1_P1P0_DP<19>")
	)
	(arc
		(start 364.374684 -215.428068)
		(mid 364.426954 -215.245703)
		(end 364.561882 -215.112346)
		(width 0.0889)
		(layer "In4.Cu")
		(net "UPI_CPU0_CPU1_P1P0_DP<19>")
	)
	(arc
		(start 364.559088 -214.093298)
		(mid 364.449692 -214.009201)
		(end 364.374684 -213.8934)
		(width 0.0889)
		(layer "In4.Cu")
		(net "UPI_CPU0_CPU1_P1P0_DP<19>")
	)
	(arc
		(start 364.092236 -217.554048)
		(mid 364.294522 -217.355067)
		(end 364.374684 -217.082878)
		(width 0.0889)
		(layer "In4.Cu")
		(net "UPI_CPU0_CPU1_P1P0_DP<19>")
	)
	(arc
		(start 364.844584 -214.425022)
		(mid 364.733246 -214.232122)
		(end 364.559088 -214.093298)
		(width 0.0889)
		(layer "In4.Cu")
		(net "UPI_CPU0_CPU1_P1P0_DP<19>")
	)
	(arc
		(start 106.846116 -213.930484)
		(mid 106.853401 -213.950046)
		(end 106.861356 -213.969346)
		(width 0.0889)
		(layer "In4.Cu")
		(net "UPI_CPU0_CPU1_P1P0_DP<19>")
	)
	(arc
		(start 106.845862 -217.07856)
		(mid 106.904156 -217.315203)
		(end 107.056682 -217.50528)
		(width 0.0889)
		(layer "In4.Cu")
		(net "UPI_CPU0_CPU1_P1P0_DP<19>")
	)
	(arc
		(start 364.561882 -215.112346)
		(mid 364.765363 -214.911542)
		(end 364.844584 -214.636858)
		(width 0.0889)
		(layer "In4.Cu")
		(net "UPI_CPU0_CPU1_P1P0_DP<19>")
	)
	(arc
		(start 107.137454 -215.931242)
		(mid 107.316051 -216.25052)
		(end 107.137454 -216.569798)
		(width 0.0889)
		(layer "In4.Cu")
		(net "UPI_CPU0_CPU1_P1P0_DP<19>")
	)
	(arc
		(start 106.861356 -213.969346)
		(mid 106.97135 -214.138715)
		(end 107.131358 -214.261954)
		(width 0.0889)
		(layer "In4.Cu")
		(net "UPI_CPU0_CPU1_P1P0_DP<19>")
	)
	(arc
		(start 107.056682 -217.50528)
		(mid 107.06513 -217.511837)
		(end 107.0737 -217.518234)
		(width 0.0889)
		(layer "In4.Cu")
		(net "UPI_CPU0_CPU1_P1P0_DP<19>")
	)
	(segment
		(start 106.471466 -219.228162)
		(end 106.471466 -218.692476)
		(width 0.13208)
		(layer "F.Cu")
		(net "UPI_CPU0_CPU1_P1P0_DP<18>")
	)
	(segment
		(start 106.471466 -218.692476)
		(end 106.471212 -218.692222)
		(width 0.13208)
		(layer "F.Cu")
		(net "UPI_CPU0_CPU1_P1P0_DP<18>")
	)
	(segment
		(start 364.749334 -217.06459)
		(end 364.74908 -217.064336)
		(width 0.13208)
		(layer "F.Cu")
		(net "UPI_CPU0_CPU1_P1P0_DP<18>")
	)
	(segment
		(start 364.749334 -217.600276)
		(end 364.749334 -217.06459)
		(width 0.13208)
		(layer "F.Cu")
		(net "UPI_CPU0_CPU1_P1P0_DP<18>")
	)
	(segment
		(start 347.041724 -176.508156)
		(end 347.010228 -176.302416)
		(width 0.14732)
		(layer "In4.Cu")
		(net "UPI_CPU0_CPU1_P1P0_DP<18>")
	)
	(segment
		(start 358.466898 -190.33617)
		(end 356.956614 -186.689492)
		(width 0.14732)
		(layer "In4.Cu")
		(net "UPI_CPU0_CPU1_P1P0_DP<18>")
	)
	(segment
		(start 312.736738 -157.94355)
		(end 312.372502 -157.705298)
		(width 0.14732)
		(layer "In4.Cu")
		(net "UPI_CPU0_CPU1_P1P0_DP<18>")
	)
	(segment
		(start 113.31829 -194.497452)
		(end 113.14684 -194.517264)
		(width 0.14732)
		(layer "In4.Cu")
		(net "UPI_CPU0_CPU1_P1P0_DP<18>")
	)
	(segment
		(start 347.610176 -177.627788)
		(end 346.954856 -177.146966)
		(width 0.14732)
		(layer "In4.Cu")
		(net "UPI_CPU0_CPU1_P1P0_DP<18>")
	)
	(segment
		(start 113.842038 -193.64198)
		(end 113.570512 -193.983864)
		(width 0.14732)
		(layer "In4.Cu")
		(net "UPI_CPU0_CPU1_P1P0_DP<18>")
	)
	(segment
		(start 314.640976 -157.22981)
		(end 314.557156 -156.830522)
		(width 0.14732)
		(layer "In4.Cu")
		(net "UPI_CPU0_CPU1_P1P0_DP<18>")
	)
	(segment
		(start 115.253008 -191.865758)
		(end 115.253262 -191.865758)
		(width 0.14732)
		(layer "In4.Cu")
		(net "UPI_CPU0_CPU1_P1P0_DP<18>")
	)
	(segment
		(start 169.653204 -153.260044)
		(end 166.799514 -153.184098)
		(width 0.14732)
		(layer "In4.Cu")
		(net "UPI_CPU0_CPU1_P1P0_DP<18>")
	)
	(segment
		(start 115.253008 -191.866012)
		(end 114.971576 -192.220342)
		(width 0.14732)
		(layer "In4.Cu")
		(net "UPI_CPU0_CPU1_P1P0_DP<18>")
	)
	(segment
		(start 364.905544 -217.335354)
		(end 364.983776 -217.356182)
		(width 0.0889)
		(layer "In4.Cu")
		(net "UPI_CPU0_CPU1_P1P0_DP<18>")
	)
	(segment
		(start 111.927894 -196.24802)
		(end 111.756444 -196.267832)
		(width 0.14732)
		(layer "In4.Cu")
		(net "UPI_CPU0_CPU1_P1P0_DP<18>")
	)
	(segment
		(start 365.593884 -214.622634)
		(end 365.593884 -214.461852)
		(width 0.0889)
		(layer "In4.Cu")
		(net "UPI_CPU0_CPU1_P1P0_DP<18>")
	)
	(segment
		(start 313.536584 -157.775656)
		(end 312.736738 -157.94355)
		(width 0.14732)
		(layer "In4.Cu")
		(net "UPI_CPU0_CPU1_P1P0_DP<18>")
	)
	(segment
		(start 365.082074 -205.388718)
		(end 359.124504 -191.006222)
		(width 0.14732)
		(layer "In4.Cu")
		(net "UPI_CPU0_CPU1_P1P0_DP<18>")
	)
	(segment
		(start 314.557156 -156.830522)
		(end 314.383166 -156.71673)
		(width 0.14732)
		(layer "In4.Cu")
		(net "UPI_CPU0_CPU1_P1P0_DP<18>")
	)
	(segment
		(start 116.39169 -190.628778)
		(end 116.119656 -190.97117)
		(width 0.14732)
		(layer "In4.Cu")
		(net "UPI_CPU0_CPU1_P1P0_DP<18>")
	)
	(segment
		(start 364.937294 -216.740486)
		(end 364.936278 -216.739978)
		(width 0.0889)
		(layer "In4.Cu")
		(net "UPI_CPU0_CPU1_P1P0_DP<18>")
	)
	(segment
		(start 112.623092 -195.372736)
		(end 112.451642 -195.392548)
		(width 0.14732)
		(layer "In4.Cu")
		(net "UPI_CPU0_CPU1_P1P0_DP<18>")
	)
	(segment
		(start 310.020208 -157.781498)
		(end 309.846218 -157.667706)
		(width 0.14732)
		(layer "In4.Cu")
		(net "UPI_CPU0_CPU1_P1P0_DP<18>")
	)
	(segment
		(start 365.082074 -211.4042)
		(end 365.082074 -205.388718)
		(width 0.14732)
		(layer "In4.Cu")
		(net "UPI_CPU0_CPU1_P1P0_DP<18>")
	)
	(segment
		(start 347.010228 -176.302416)
		(end 346.716858 -176.087278)
		(width 0.14732)
		(layer "In4.Cu")
		(net "UPI_CPU0_CPU1_P1P0_DP<18>")
	)
	(segment
		(start 115.696238 -191.503808)
		(end 115.424204 -191.8462)
		(width 0.14732)
		(layer "In4.Cu")
		(net "UPI_CPU0_CPU1_P1P0_DP<18>")
	)
	(segment
		(start 365.082328 -211.404454)
		(end 365.082074 -211.4042)
		(width 0.14732)
		(layer "In4.Cu")
		(net "UPI_CPU0_CPU1_P1P0_DP<18>")
	)
	(segment
		(start 365.124238 -212.79612)
		(end 365.124238 -212.59038)
		(width 0.0889)
		(layer "In4.Cu")
		(net "UPI_CPU0_CPU1_P1P0_DP<18>")
	)
	(segment
		(start 365.123984 -213.169246)
		(end 365.025178 -213.07044)
		(width 0.0889)
		(layer "In4.Cu")
		(net "UPI_CPU0_CPU1_P1P0_DP<18>")
	)
	(segment
		(start 309.238396 -158.362396)
		(end 308.999636 -158.726632)
		(width 0.14732)
		(layer "In4.Cu")
		(net "UPI_CPU0_CPU1_P1P0_DP<18>")
	)
	(segment
		(start 106.096816 -212.405214)
		(end 106.096816 -213.893908)
		(width 0.0889)
		(layer "In4.Cu")
		(net "UPI_CPU0_CPU1_P1P0_DP<18>")
	)
	(segment
		(start 113.590324 -194.155314)
		(end 113.31829 -194.497452)
		(width 0.14732)
		(layer "In4.Cu")
		(net "UPI_CPU0_CPU1_P1P0_DP<18>")
	)
	(segment
		(start 116.371878 -190.457328)
		(end 116.39169 -190.628778)
		(width 0.14732)
		(layer "In4.Cu")
		(net "UPI_CPU0_CPU1_P1P0_DP<18>")
	)
	(segment
		(start 114.971576 -192.220342)
		(end 114.991388 -192.391284)
		(width 0.14732)
		(layer "In4.Cu")
		(net "UPI_CPU0_CPU1_P1P0_DP<18>")
	)
	(segment
		(start 165.26891 -153.718768)
		(end 133.13664 -173.519846)
		(width 0.14732)
		(layer "In4.Cu")
		(net "UPI_CPU0_CPU1_P1P0_DP<18>")
	)
	(segment
		(start 120.051576 -185.825638)
		(end 116.372132 -190.457582)
		(width 0.14732)
		(layer "In4.Cu")
		(net "UPI_CPU0_CPU1_P1P0_DP<18>")
	)
	(segment
		(start 106.566716 -216.25052)
		(end 106.566716 -216.260426)
		(width 0.0889)
		(layer "In4.Cu")
		(net "UPI_CPU0_CPU1_P1P0_DP<18>")
	)
	(segment
		(start 365.025178 -212.89518)
		(end 365.124238 -212.79612)
		(width 0.0889)
		(layer "In4.Cu")
		(net "UPI_CPU0_CPU1_P1P0_DP<18>")
	)
	(segment
		(start 308.19979 -158.894526)
		(end 307.835554 -158.656274)
		(width 0.14732)
		(layer "In4.Cu")
		(net "UPI_CPU0_CPU1_P1P0_DP<18>")
	)
	(segment
		(start 106.281728 -216.741502)
		(end 106.280966 -216.74201)
		(width 0.0889)
		(layer "In4.Cu")
		(net "UPI_CPU0_CPU1_P1P0_DP<18>")
	)
	(segment
		(start 312.114692 -157.192218)
		(end 311.536842 -157.31363)
		(width 0.14732)
		(layer "In4.Cu")
		(net "UPI_CPU0_CPU1_P1P0_DP<18>")
	)
	(segment
		(start 365.123984 -213.93023)
		(end 365.123984 -213.169246)
		(width 0.0889)
		(layer "In4.Cu")
		(net "UPI_CPU0_CPU1_P1P0_DP<18>")
	)
	(segment
		(start 322.350384 -155.047188)
		(end 316.07379 -156.362654)
		(width 0.14732)
		(layer "In4.Cu")
		(net "UPI_CPU0_CPU1_P1P0_DP<18>")
	)
	(segment
		(start 345.927934 -176.393602)
		(end 342.4936 -173.873668)
		(width 0.14732)
		(layer "In4.Cu")
		(net "UPI_CPU0_CPU1_P1P0_DP<18>")
	)
	(segment
		(start 115.253262 -191.865758)
		(end 115.253008 -191.866012)
		(width 0.14732)
		(layer "In4.Cu")
		(net "UPI_CPU0_CPU1_P1P0_DP<18>")
	)
	(segment
		(start 106.566716 -217.859864)
		(end 106.566716 -217.878406)
		(width 0.0889)
		(layer "In4.Cu")
		(net "UPI_CPU0_CPU1_P1P0_DP<18>")
	)
	(segment
		(start 106.138472 -211.582508)
		(end 106.138726 -211.582762)
		(width 0.14732)
		(layer "In4.Cu")
		(net "UPI_CPU0_CPU1_P1P0_DP<18>")
	)
	(segment
		(start 307.751734 -158.256986)
		(end 307.577744 -158.14294)
		(width 0.14732)
		(layer "In4.Cu")
		(net "UPI_CPU0_CPU1_P1P0_DP<18>")
	)
	(segment
		(start 115.67668 -191.332612)
		(end 115.696238 -191.503808)
		(width 0.14732)
		(layer "In4.Cu")
		(net "UPI_CPU0_CPU1_P1P0_DP<18>")
	)
	(segment
		(start 106.284014 -215.112346)
		(end 106.282998 -215.112854)
		(width 0.0889)
		(layer "In4.Cu")
		(net "UPI_CPU0_CPU1_P1P0_DP<18>")
	)
	(segment
		(start 106.220514 -215.722454)
		(end 106.284014 -215.761062)
		(width 0.0889)
		(layer "In4.Cu")
		(net "UPI_CPU0_CPU1_P1P0_DP<18>")
	)
	(segment
		(start 115.948206 -190.990728)
		(end 115.67668 -191.332612)
		(width 0.14732)
		(layer "In4.Cu")
		(net "UPI_CPU0_CPU1_P1P0_DP<18>")
	)
	(segment
		(start 349.065088 -177.771552)
		(end 348.482412 -177.853848)
		(width 0.14732)
		(layer "In4.Cu")
		(net "UPI_CPU0_CPU1_P1P0_DP<18>")
	)
	(segment
		(start 325.32574 -155.555188)
		(end 323.30898 -155.047188)
		(width 0.14732)
		(layer "In4.Cu")
		(net "UPI_CPU0_CPU1_P1P0_DP<18>")
	)
	(segment
		(start 106.284014 -215.761062)
		(end 106.29011 -215.764618)
		(width 0.0889)
		(layer "In4.Cu")
		(net "UPI_CPU0_CPU1_P1P0_DP<18>")
	)
	(segment
		(start 172.617892 -154.72791)
		(end 169.653204 -153.260044)
		(width 0.14732)
		(layer "In4.Cu")
		(net "UPI_CPU0_CPU1_P1P0_DP<18>")
	)
	(segment
		(start 314.383166 -156.71673)
		(end 313.805316 -156.838142)
		(width 0.14732)
		(layer "In4.Cu")
		(net "UPI_CPU0_CPU1_P1P0_DP<18>")
	)
	(segment
		(start 359.124504 -191.006222)
		(end 358.466898 -190.33617)
		(width 0.14732)
		(layer "In4.Cu")
		(net "UPI_CPU0_CPU1_P1P0_DP<18>")
	)
	(segment
		(start 364.654084 -216.266014)
		(end 364.654084 -216.235026)
		(width 0.0889)
		(layer "In4.Cu")
		(net "UPI_CPU0_CPU1_P1P0_DP<18>")
	)
	(segment
		(start 315.005212 -157.468062)
		(end 314.640976 -157.22981)
		(width 0.14732)
		(layer "In4.Cu")
		(net "UPI_CPU0_CPU1_P1P0_DP<18>")
	)
	(segment
		(start 315.959998 -156.536644)
		(end 316.043818 -156.935932)
		(width 0.14732)
		(layer "In4.Cu")
		(net "UPI_CPU0_CPU1_P1P0_DP<18>")
	)
	(segment
		(start 112.875314 -194.859148)
		(end 112.895126 -195.030598)
		(width 0.14732)
		(layer "In4.Cu")
		(net "UPI_CPU0_CPU1_P1P0_DP<18>")
	)
	(segment
		(start 312.288682 -157.30601)
		(end 312.114692 -157.192218)
		(width 0.14732)
		(layer "In4.Cu")
		(net "UPI_CPU0_CPU1_P1P0_DP<18>")
	)
	(segment
		(start 116.119656 -190.97117)
		(end 115.948206 -190.990728)
		(width 0.14732)
		(layer "In4.Cu")
		(net "UPI_CPU0_CPU1_P1P0_DP<18>")
	)
	(segment
		(start 365.025178 -212.31606)
		(end 365.124238 -212.217)
		(width 0.0889)
		(layer "In4.Cu")
		(net "UPI_CPU0_CPU1_P1P0_DP<18>")
	)
	(segment
		(start 112.451642 -195.392548)
		(end 112.180116 -195.734432)
		(width 0.14732)
		(layer "In4.Cu")
		(net "UPI_CPU0_CPU1_P1P0_DP<18>")
	)
	(segment
		(start 279.734264 -163.975288)
		(end 276.390608 -163.975288)
		(width 0.14732)
		(layer "In4.Cu")
		(net "UPI_CPU0_CPU1_P1P0_DP<18>")
	)
	(segment
		(start 365.39424 -214.954104)
		(end 365.406432 -214.946992)
		(width 0.0889)
		(layer "In4.Cu")
		(net "UPI_CPU0_CPU1_P1P0_DP<18>")
	)
	(segment
		(start 312.372502 -157.705298)
		(end 312.288682 -157.30601)
		(width 0.14732)
		(layer "In4.Cu")
		(net "UPI_CPU0_CPU1_P1P0_DP<18>")
	)
	(segment
		(start 106.283506 -217.388186)
		(end 106.284268 -217.388694)
		(width 0.0889)
		(layer "In4.Cu")
		(net "UPI_CPU0_CPU1_P1P0_DP<18>")
	)
	(segment
		(start 133.13664 -173.519846)
		(end 120.052846 -185.824368)
		(width 0.14732)
		(layer "In4.Cu")
		(net "UPI_CPU0_CPU1_P1P0_DP<18>")
	)
	(segment
		(start 310.468264 -158.419038)
		(end 310.104028 -158.180786)
		(width 0.14732)
		(layer "In4.Cu")
		(net "UPI_CPU0_CPU1_P1P0_DP<18>")
	)
	(segment
		(start 311.50687 -157.886908)
		(end 311.26811 -158.251144)
		(width 0.14732)
		(layer "In4.Cu")
		(net "UPI_CPU0_CPU1_P1P0_DP<18>")
	)
	(segment
		(start 365.025178 -212.49132)
		(end 365.025178 -212.31606)
		(width 0.0889)
		(layer "In4.Cu")
		(net "UPI_CPU0_CPU1_P1P0_DP<18>")
	)
	(segment
		(start 311.26811 -158.251144)
		(end 310.468264 -158.419038)
		(width 0.14732)
		(layer "In4.Cu")
		(net "UPI_CPU0_CPU1_P1P0_DP<18>")
	)
	(segment
		(start 111.484918 -196.609716)
		(end 106.138472 -211.285328)
		(width 0.14732)
		(layer "In4.Cu")
		(net "UPI_CPU0_CPU1_P1P0_DP<18>")
	)
	(segment
		(start 114.991388 -192.391284)
		(end 114.719354 -192.733676)
		(width 0.14732)
		(layer "In4.Cu")
		(net "UPI_CPU0_CPU1_P1P0_DP<18>")
	)
	(segment
		(start 114.013488 -193.622168)
		(end 113.842038 -193.64198)
		(width 0.14732)
		(layer "In4.Cu")
		(net "UPI_CPU0_CPU1_P1P0_DP<18>")
	)
	(segment
		(start 106.283506 -216.740486)
		(end 106.281728 -216.741502)
		(width 0.0889)
		(layer "In4.Cu")
		(net "UPI_CPU0_CPU1_P1P0_DP<18>")
	)
	(segment
		(start 355.8921 -181.51475)
		(end 355.659182 -181.05247)
		(width 0.14732)
		(layer "In4.Cu")
		(net "UPI_CPU0_CPU1_P1P0_DP<18>")
	)
	(segment
		(start 355.09962 -179.941728)
		(end 351.26422 -177.523648)
		(width 0.14732)
		(layer "In4.Cu")
		(net "UPI_CPU0_CPU1_P1P0_DP<18>")
	)
	(segment
		(start 112.199928 -195.905882)
		(end 111.927894 -196.24802)
		(width 0.14732)
		(layer "In4.Cu")
		(net "UPI_CPU0_CPU1_P1P0_DP<18>")
	)
	(segment
		(start 365.406432 -214.946992)
		(end 365.415322 -214.941912)
		(width 0.0889)
		(layer "In4.Cu")
		(net "UPI_CPU0_CPU1_P1P0_DP<18>")
	)
	(segment
		(start 106.275378 -217.383614)
		(end 106.283506 -217.388186)
		(width 0.0889)
		(layer "In4.Cu")
		(net "UPI_CPU0_CPU1_P1P0_DP<18>")
	)
	(segment
		(start 356.956614 -186.689492)
		(end 356.956614 -184.08523)
		(width 0.14732)
		(layer "In4.Cu")
		(net "UPI_CPU0_CPU1_P1P0_DP<18>")
	)
	(segment
		(start 309.846218 -157.667706)
		(end 309.268368 -157.789118)
		(width 0.14732)
		(layer "In4.Cu")
		(net "UPI_CPU0_CPU1_P1P0_DP<18>")
	)
	(segment
		(start 106.138726 -212.042248)
		(end 106.096562 -212.084412)
		(width 0.0889)
		(layer "In4.Cu")
		(net "UPI_CPU0_CPU1_P1P0_DP<18>")
	)
	(segment
		(start 234.327954 -154.084528)
		(end 197.26402 -163.6395)
		(width 0.14732)
		(layer "In4.Cu")
		(net "UPI_CPU0_CPU1_P1P0_DP<18>")
	)
	(segment
		(start 346.888562 -176.71669)
		(end 347.041724 -176.508156)
		(width 0.14732)
		(layer "In4.Cu")
		(net "UPI_CPU0_CPU1_P1P0_DP<18>")
	)
	(segment
		(start 237.882938 -154.084528)
		(end 234.327954 -154.084528)
		(width 0.14732)
		(layer "In4.Cu")
		(net "UPI_CPU0_CPU1_P1P0_DP<18>")
	)
	(segment
		(start 106.282998 -215.112854)
		(end 106.275124 -215.117426)
		(width 0.0889)
		(layer "In4.Cu")
		(net "UPI_CPU0_CPU1_P1P0_DP<18>")
	)
	(segment
		(start 327.26884 -157.091888)
		(end 325.32574 -155.555188)
		(width 0.14732)
		(layer "In4.Cu")
		(net "UPI_CPU0_CPU1_P1P0_DP<18>")
	)
	(segment
		(start 276.390608 -163.975288)
		(end 237.882938 -154.084528)
		(width 0.14732)
		(layer "In4.Cu")
		(net "UPI_CPU0_CPU1_P1P0_DP<18>")
	)
	(segment
		(start 351.26422 -177.523648)
		(end 350.656906 -177.452528)
		(width 0.14732)
		(layer "In4.Cu")
		(net "UPI_CPU0_CPU1_P1P0_DP<18>")
	)
	(segment
		(start 315.805058 -157.300168)
		(end 315.005212 -157.468062)
		(width 0.14732)
		(layer "In4.Cu")
		(net "UPI_CPU0_CPU1_P1P0_DP<18>")
	)
	(segment
		(start 364.937294 -215.760554)
		(end 364.945168 -215.755982)
		(width 0.0889)
		(layer "In4.Cu")
		(net "UPI_CPU0_CPU1_P1P0_DP<18>")
	)
	(segment
		(start 114.547904 -192.753234)
		(end 114.548158 -192.753234)
		(width 0.14732)
		(layer "In4.Cu")
		(net "UPI_CPU0_CPU1_P1P0_DP<18>")
	)
	(segment
		(start 365.082328 -211.73567)
		(end 365.082328 -211.404454)
		(width 0.14732)
		(layer "In4.Cu")
		(net "UPI_CPU0_CPU1_P1P0_DP<18>")
	)
	(segment
		(start 348.482412 -177.853848)
		(end 347.610176 -177.627788)
		(width 0.14732)
		(layer "In4.Cu")
		(net "UPI_CPU0_CPU1_P1P0_DP<18>")
	)
	(segment
		(start 113.14684 -194.517264)
		(end 112.875314 -194.859148)
		(width 0.14732)
		(layer "In4.Cu")
		(net "UPI_CPU0_CPU1_P1P0_DP<18>")
	)
	(segment
		(start 346.511118 -176.118774)
		(end 346.35821 -176.327308)
		(width 0.14732)
		(layer "In4.Cu")
		(net "UPI_CPU0_CPU1_P1P0_DP<18>")
	)
	(segment
		(start 365.124238 -212.217)
		(end 365.124238 -211.799678)
		(width 0.0889)
		(layer "In4.Cu")
		(net "UPI_CPU0_CPU1_P1P0_DP<18>")
	)
	(segment
		(start 190.273432 -163.965128)
		(end 172.617892 -154.72791)
		(width 0.14732)
		(layer "In4.Cu")
		(net "UPI_CPU0_CPU1_P1P0_DP<18>")
	)
	(segment
		(start 365.025178 -213.07044)
		(end 365.025178 -212.89518)
		(width 0.0889)
		(layer "In4.Cu")
		(net "UPI_CPU0_CPU1_P1P0_DP<18>")
	)
	(segment
		(start 316.043818 -156.935932)
		(end 315.805058 -157.300168)
		(width 0.14732)
		(layer "In4.Cu")
		(net "UPI_CPU0_CPU1_P1P0_DP<18>")
	)
	(segment
		(start 114.285522 -193.28003)
		(end 114.013488 -193.622168)
		(width 0.14732)
		(layer "In4.Cu")
		(net "UPI_CPU0_CPU1_P1P0_DP<18>")
	)
	(segment
		(start 120.052846 -185.824368)
		(end 120.051576 -185.825638)
		(width 0.14732)
		(layer "In4.Cu")
		(net "UPI_CPU0_CPU1_P1P0_DP<18>")
	)
	(segment
		(start 106.314748 -218.421204)
		(end 106.471212 -218.692222)
		(width 0.0889)
		(layer "In4.Cu")
		(net "UPI_CPU0_CPU1_P1P0_DP<18>")
	)
	(segment
		(start 313.691524 -157.012132)
		(end 313.775344 -157.41142)
		(width 0.14732)
		(layer "In4.Cu")
		(net "UPI_CPU0_CPU1_P1P0_DP<18>")
	)
	(segment
		(start 106.138726 -211.582762)
		(end 106.138726 -212.02015)
		(width 0.14732)
		(layer "In4.Cu")
		(net "UPI_CPU0_CPU1_P1P0_DP<18>")
	)
	(segment
		(start 106.138472 -211.285328)
		(end 106.138472 -211.582508)
		(width 0.14732)
		(layer "In4.Cu")
		(net "UPI_CPU0_CPU1_P1P0_DP<18>")
	)
	(segment
		(start 307.835554 -158.656274)
		(end 307.751734 -158.256986)
		(width 0.14732)
		(layer "In4.Cu")
		(net "UPI_CPU0_CPU1_P1P0_DP<18>")
	)
	(segment
		(start 313.805316 -156.838142)
		(end 313.691524 -157.012132)
		(width 0.14732)
		(layer "In4.Cu")
		(net "UPI_CPU0_CPU1_P1P0_DP<18>")
	)
	(segment
		(start 346.716858 -176.087278)
		(end 346.511118 -176.118774)
		(width 0.14732)
		(layer "In4.Cu")
		(net "UPI_CPU0_CPU1_P1P0_DP<18>")
	)
	(segment
		(start 112.180116 -195.734432)
		(end 112.199928 -195.905882)
		(width 0.14732)
		(layer "In4.Cu")
		(net "UPI_CPU0_CPU1_P1P0_DP<18>")
	)
	(segment
		(start 346.35821 -176.327308)
		(end 345.927934 -176.393602)
		(width 0.14732)
		(layer "In4.Cu")
		(net "UPI_CPU0_CPU1_P1P0_DP<18>")
	)
	(segment
		(start 311.42305 -157.48762)
		(end 311.50687 -157.886908)
		(width 0.14732)
		(layer "In4.Cu")
		(net "UPI_CPU0_CPU1_P1P0_DP<18>")
	)
	(segment
		(start 365.124238 -211.799678)
		(end 365.082328 -211.757768)
		(width 0.0889)
		(layer "In4.Cu")
		(net "UPI_CPU0_CPU1_P1P0_DP<18>")
	)
	(segment
		(start 114.719354 -192.733676)
		(end 114.547904 -192.753234)
		(width 0.14732)
		(layer "In4.Cu")
		(net "UPI_CPU0_CPU1_P1P0_DP<18>")
	)
	(segment
		(start 308.999636 -158.726632)
		(end 308.19979 -158.894526)
		(width 0.14732)
		(layer "In4.Cu")
		(net "UPI_CPU0_CPU1_P1P0_DP<18>")
	)
	(segment
		(start 115.424204 -191.8462)
		(end 115.253008 -191.865758)
		(width 0.14732)
		(layer "In4.Cu")
		(net "UPI_CPU0_CPU1_P1P0_DP<18>")
	)
	(segment
		(start 106.284268 -216.739978)
		(end 106.283506 -216.740486)
		(width 0.0889)
		(layer "In4.Cu")
		(net "UPI_CPU0_CPU1_P1P0_DP<18>")
	)
	(segment
		(start 114.548158 -192.753234)
		(end 114.26571 -193.108834)
		(width 0.14732)
		(layer "In4.Cu")
		(net "UPI_CPU0_CPU1_P1P0_DP<18>")
	)
	(segment
		(start 355.363018 -180.464714)
		(end 355.09962 -179.941728)
		(width 0.14732)
		(layer "In4.Cu")
		(net "UPI_CPU0_CPU1_P1P0_DP<18>")
	)
	(segment
		(start 114.26571 -193.108834)
		(end 114.285522 -193.28003)
		(width 0.14732)
		(layer "In4.Cu")
		(net "UPI_CPU0_CPU1_P1P0_DP<18>")
	)
	(segment
		(start 365.082328 -211.757768)
		(end 365.082328 -211.73567)
		(width 0.0889)
		(layer "In4.Cu")
		(net "UPI_CPU0_CPU1_P1P0_DP<18>")
	)
	(segment
		(start 316.07379 -156.362654)
		(end 315.959998 -156.536644)
		(width 0.14732)
		(layer "In4.Cu")
		(net "UPI_CPU0_CPU1_P1P0_DP<18>")
	)
	(segment
		(start 364.936278 -215.761062)
		(end 364.937294 -215.760554)
		(width 0.0889)
		(layer "In4.Cu")
		(net "UPI_CPU0_CPU1_P1P0_DP<18>")
	)
	(segment
		(start 194.680332 -163.965128)
		(end 190.273432 -163.965128)
		(width 0.14732)
		(layer "In4.Cu")
		(net "UPI_CPU0_CPU1_P1P0_DP<18>")
	)
	(segment
		(start 106.138726 -212.02015)
		(end 106.138726 -212.042248)
		(width 0.0889)
		(layer "In4.Cu")
		(net "UPI_CPU0_CPU1_P1P0_DP<18>")
	)
	(segment
		(start 106.338878 -218.33205)
		(end 106.314748 -218.421204)
		(width 0.0889)
		(layer "In4.Cu")
		(net "UPI_CPU0_CPU1_P1P0_DP<18>")
	)
	(segment
		(start 355.464618 -180.988208)
		(end 355.298756 -180.659024)
		(width 0.14732)
		(layer "In4.Cu")
		(net "UPI_CPU0_CPU1_P1P0_DP<18>")
	)
	(segment
		(start 113.570512 -193.983864)
		(end 113.590324 -194.155314)
		(width 0.14732)
		(layer "In4.Cu")
		(net "UPI_CPU0_CPU1_P1P0_DP<18>")
	)
	(segment
		(start 364.945168 -216.745058)
		(end 364.937294 -216.740486)
		(width 0.0889)
		(layer "In4.Cu")
		(net "UPI_CPU0_CPU1_P1P0_DP<18>")
	)
	(segment
		(start 106.096562 -215.436704)
		(end 106.096562 -215.500712)
		(width 0.0889)
		(layer "In4.Cu")
		(net "UPI_CPU0_CPU1_P1P0_DP<18>")
	)
	(segment
		(start 106.280966 -216.74201)
		(end 106.275378 -216.745058)
		(width 0.0889)
		(layer "In4.Cu")
		(net "UPI_CPU0_CPU1_P1P0_DP<18>")
	)
	(segment
		(start 355.298756 -180.659024)
		(end 355.363018 -180.464714)
		(width 0.14732)
		(layer "In4.Cu")
		(net "UPI_CPU0_CPU1_P1P0_DP<18>")
	)
	(segment
		(start 356.956614 -184.08523)
		(end 355.8921 -181.51475)
		(width 0.14732)
		(layer "In4.Cu")
		(net "UPI_CPU0_CPU1_P1P0_DP<18>")
	)
	(segment
		(start 116.372132 -190.457582)
		(end 116.371878 -190.457328)
		(width 0.14732)
		(layer "In4.Cu")
		(net "UPI_CPU0_CPU1_P1P0_DP<18>")
	)
	(segment
		(start 313.775344 -157.41142)
		(end 313.536584 -157.775656)
		(width 0.14732)
		(layer "In4.Cu")
		(net "UPI_CPU0_CPU1_P1P0_DP<18>")
	)
	(segment
		(start 309.154576 -157.963108)
		(end 309.238396 -158.362396)
		(width 0.14732)
		(layer "In4.Cu")
		(net "UPI_CPU0_CPU1_P1P0_DP<18>")
	)
	(segment
		(start 106.096562 -212.084412)
		(end 106.096562 -212.40496)
		(width 0.0889)
		(layer "In4.Cu")
		(net "UPI_CPU0_CPU1_P1P0_DP<18>")
	)
	(segment
		(start 112.895126 -195.030598)
		(end 112.623092 -195.372736)
		(width 0.14732)
		(layer "In4.Cu")
		(net "UPI_CPU0_CPU1_P1P0_DP<18>")
	)
	(segment
		(start 309.268368 -157.789118)
		(end 309.154576 -157.963108)
		(width 0.14732)
		(layer "In4.Cu")
		(net "UPI_CPU0_CPU1_P1P0_DP<18>")
	)
	(segment
		(start 106.566208 -214.424768)
		(end 106.566208 -214.644732)
		(width 0.0889)
		(layer "In4.Cu")
		(net "UPI_CPU0_CPU1_P1P0_DP<18>")
	)
	(segment
		(start 307.577744 -158.14294)
		(end 279.734264 -163.975288)
		(width 0.14732)
		(layer "In4.Cu")
		(net "UPI_CPU0_CPU1_P1P0_DP<18>")
	)
	(segment
		(start 311.536842 -157.31363)
		(end 311.42305 -157.48762)
		(width 0.14732)
		(layer "In4.Cu")
		(net "UPI_CPU0_CPU1_P1P0_DP<18>")
	)
	(segment
		(start 346.954856 -177.146966)
		(end 346.888562 -176.71669)
		(width 0.14732)
		(layer "In4.Cu")
		(net "UPI_CPU0_CPU1_P1P0_DP<18>")
	)
	(segment
		(start 310.104028 -158.180786)
		(end 310.020208 -157.781498)
		(width 0.14732)
		(layer "In4.Cu")
		(net "UPI_CPU0_CPU1_P1P0_DP<18>")
	)
	(segment
		(start 106.096562 -212.40496)
		(end 106.096816 -212.405214)
		(width 0.0889)
		(layer "In4.Cu")
		(net "UPI_CPU0_CPU1_P1P0_DP<18>")
	)
	(segment
		(start 365.124238 -212.59038)
		(end 365.025178 -212.49132)
		(width 0.0889)
		(layer "In4.Cu")
		(net "UPI_CPU0_CPU1_P1P0_DP<18>")
	)
	(segment
		(start 111.756444 -196.267832)
		(end 111.484918 -196.609716)
		(width 0.14732)
		(layer "In4.Cu")
		(net "UPI_CPU0_CPU1_P1P0_DP<18>")
	)
	(segment
		(start 166.799514 -153.184098)
		(end 165.26891 -153.718768)
		(width 0.14732)
		(layer "In4.Cu")
		(net "UPI_CPU0_CPU1_P1P0_DP<18>")
	)
	(segment
		(start 355.659182 -181.05247)
		(end 355.464618 -180.988208)
		(width 0.14732)
		(layer "In4.Cu")
		(net "UPI_CPU0_CPU1_P1P0_DP<18>")
	)
	(segment
		(start 364.74908 -217.064336)
		(end 364.905544 -217.335354)
		(width 0.0889)
		(layer "In4.Cu")
		(net "UPI_CPU0_CPU1_P1P0_DP<18>")
	)
	(segment
		(start 350.656906 -177.452528)
		(end 349.065088 -177.771552)
		(width 0.14732)
		(layer "In4.Cu")
		(net "UPI_CPU0_CPU1_P1P0_DP<18>")
	)
	(segment
		(start 342.4936 -173.873668)
		(end 327.26884 -157.091888)
		(width 0.14732)
		(layer "In4.Cu")
		(net "UPI_CPU0_CPU1_P1P0_DP<18>")
	)
	(segment
		(start 323.30898 -155.047188)
		(end 322.350384 -155.047188)
		(width 0.14732)
		(layer "In4.Cu")
		(net "UPI_CPU0_CPU1_P1P0_DP<18>")
	)
	(segment
		(start 197.26402 -163.6395)
		(end 194.680332 -163.965128)
		(width 0.14732)
		(layer "In4.Cu")
		(net "UPI_CPU0_CPU1_P1P0_DP<18>")
	)
	(arc
		(start 365.593884 -214.461852)
		(mid 365.518813 -214.34611)
		(end 365.40948 -214.261954)
		(width 0.0889)
		(layer "In4.Cu")
		(net "UPI_CPU0_CPU1_P1P0_DP<18>")
	)
	(arc
		(start 106.096562 -215.500712)
		(mid 106.129671 -215.627704)
		(end 106.220514 -215.722454)
		(width 0.0889)
		(layer "In4.Cu")
		(net "UPI_CPU0_CPU1_P1P0_DP<18>")
	)
	(arc
		(start 365.40948 -214.261954)
		(mid 365.249125 -214.138568)
		(end 365.13897 -213.968838)
		(width 0.0889)
		(layer "In4.Cu")
		(net "UPI_CPU0_CPU1_P1P0_DP<18>")
	)
	(arc
		(start 365.13897 -213.968838)
		(mid 365.131148 -213.949662)
		(end 365.123984 -213.93023)
		(width 0.0889)
		(layer "In4.Cu")
		(net "UPI_CPU0_CPU1_P1P0_DP<18>")
	)
	(arc
		(start 106.566716 -217.878406)
		(mid 106.511361 -218.122593)
		(end 106.355896 -218.318842)
		(width 0.0889)
		(layer "In4.Cu")
		(net "UPI_CPU0_CPU1_P1P0_DP<18>")
	)
	(arc
		(start 364.945168 -215.755982)
		(mid 365.076082 -215.619622)
		(end 365.12373 -215.436704)
		(width 0.0889)
		(layer "In4.Cu")
		(net "UPI_CPU0_CPU1_P1P0_DP<18>")
	)
	(arc
		(start 364.654084 -216.235026)
		(mid 364.733454 -215.961292)
		(end 364.936278 -215.761062)
		(width 0.0889)
		(layer "In4.Cu")
		(net "UPI_CPU0_CPU1_P1P0_DP<18>")
	)
	(arc
		(start 106.355896 -218.318842)
		(mid 106.34745 -218.325527)
		(end 106.338878 -218.33205)
		(width 0.0889)
		(layer "In4.Cu")
		(net "UPI_CPU0_CPU1_P1P0_DP<18>")
	)
	(arc
		(start 106.280966 -214.093298)
		(mid 106.454929 -214.232062)
		(end 106.566208 -214.424768)
		(width 0.0889)
		(layer "In4.Cu")
		(net "UPI_CPU0_CPU1_P1P0_DP<18>")
	)
	(arc
		(start 365.12373 -215.436704)
		(mid 365.195903 -215.160036)
		(end 365.39424 -214.954104)
		(width 0.0889)
		(layer "In4.Cu")
		(net "UPI_CPU0_CPU1_P1P0_DP<18>")
	)
	(arc
		(start 365.415322 -214.941912)
		(mid 365.546236 -214.805552)
		(end 365.593884 -214.622634)
		(width 0.0889)
		(layer "In4.Cu")
		(net "UPI_CPU0_CPU1_P1P0_DP<18>")
	)
	(arc
		(start 106.29011 -215.764618)
		(mid 106.49269 -215.970959)
		(end 106.566716 -216.25052)
		(width 0.0889)
		(layer "In4.Cu")
		(net "UPI_CPU0_CPU1_P1P0_DP<18>")
	)
	(arc
		(start 365.12373 -217.064336)
		(mid 365.076051 -216.881436)
		(end 364.945168 -216.745058)
		(width 0.0889)
		(layer "In4.Cu")
		(net "UPI_CPU0_CPU1_P1P0_DP<18>")
	)
	(arc
		(start 106.566716 -216.260426)
		(mid 106.488605 -216.537375)
		(end 106.284268 -216.739978)
		(width 0.0889)
		(layer "In4.Cu")
		(net "UPI_CPU0_CPU1_P1P0_DP<18>")
	)
	(arc
		(start 106.275124 -215.117426)
		(mid 106.14787 -215.247392)
		(end 106.096816 -215.421972)
		(width 0.0889)
		(layer "In4.Cu")
		(net "UPI_CPU0_CPU1_P1P0_DP<18>")
	)
	(arc
		(start 106.566208 -214.644732)
		(mid 106.485297 -214.91486)
		(end 106.284014 -215.112346)
		(width 0.0889)
		(layer "In4.Cu")
		(net "UPI_CPU0_CPU1_P1P0_DP<18>")
	)
	(arc
		(start 106.275378 -216.745058)
		(mid 106.096781 -217.064336)
		(end 106.275378 -217.383614)
		(width 0.0889)
		(layer "In4.Cu")
		(net "UPI_CPU0_CPU1_P1P0_DP<18>")
	)
	(arc
		(start 364.983776 -217.356182)
		(mid 365.086921 -217.226157)
		(end 365.12373 -217.064336)
		(width 0.0889)
		(layer "In4.Cu")
		(net "UPI_CPU0_CPU1_P1P0_DP<18>")
	)
	(arc
		(start 106.284268 -217.388694)
		(mid 106.486554 -217.587675)
		(end 106.566716 -217.859864)
		(width 0.0889)
		(layer "In4.Cu")
		(net "UPI_CPU0_CPU1_P1P0_DP<18>")
	)
	(arc
		(start 364.936278 -216.739978)
		(mid 364.733455 -216.539747)
		(end 364.654084 -216.266014)
		(width 0.0889)
		(layer "In4.Cu")
		(net "UPI_CPU0_CPU1_P1P0_DP<18>")
	)
	(arc
		(start 106.096816 -215.421972)
		(mid 106.096619 -215.429337)
		(end 106.096562 -215.436704)
		(width 0.0889)
		(layer "In4.Cu")
		(net "UPI_CPU0_CPU1_P1P0_DP<18>")
	)
	(arc
		(start 106.096816 -213.893908)
		(mid 106.171821 -214.009367)
		(end 106.280966 -214.093298)
		(width 0.0889)
		(layer "In4.Cu")
		(net "UPI_CPU0_CPU1_P1P0_DP<18>")
	)
	(segment
		(start 366.15878 -217.87866)
		(end 366.159034 -217.878406)
		(width 0.13208)
		(layer "F.Cu")
		(net "UPI_CPU0_CPU1_P1P0_DP<17>")
	)
	(segment
		(start 105.061512 -218.414346)
		(end 105.061512 -217.87866)
		(width 0.13208)
		(layer "F.Cu")
		(net "UPI_CPU0_CPU1_P1P0_DP<17>")
	)
	(segment
		(start 105.061512 -217.87866)
		(end 105.061766 -217.878406)
		(width 0.13208)
		(layer "F.Cu")
		(net "UPI_CPU0_CPU1_P1P0_DP<17>")
	)
	(segment
		(start 366.15878 -218.414346)
		(end 366.15878 -217.87866)
		(width 0.13208)
		(layer "F.Cu")
		(net "UPI_CPU0_CPU1_P1P0_DP<17>")
	)
	(segment
		(start 366.253776 -215.438228)
		(end 366.254284 -215.426544)
		(width 0.0889)
		(layer "In4.Cu")
		(net "UPI_CPU0_CPU1_P1P0_DP<17>")
	)
	(segment
		(start 366.00257 -218.149424)
		(end 365.924338 -218.170252)
		(width 0.0889)
		(layer "In4.Cu")
		(net "UPI_CPU0_CPU1_P1P0_DP<17>")
	)
	(segment
		(start 325.82739 -154.520392)
		(end 323.426836 -153.916888)
		(width 0.14732)
		(layer "In4.Cu")
		(net "UPI_CPU0_CPU1_P1P0_DP<17>")
	)
	(segment
		(start 342.352122 -172.074332)
		(end 342.362282 -171.86656)
		(width 0.14732)
		(layer "In4.Cu")
		(net "UPI_CPU0_CPU1_P1P0_DP<17>")
	)
	(segment
		(start 351.254822 -175.085502)
		(end 350.452182 -175.041306)
		(width 0.14732)
		(layer "In4.Cu")
		(net "UPI_CPU0_CPU1_P1P0_DP<17>")
	)
	(segment
		(start 341.399622 -170.804332)
		(end 341.19185 -170.794172)
		(width 0.14732)
		(layer "In4.Cu")
		(net "UPI_CPU0_CPU1_P1P0_DP<17>")
	)
	(segment
		(start 104.966516 -215.436958)
		(end 104.966516 -215.483948)
		(width 0.0889)
		(layer "In4.Cu")
		(net "UPI_CPU0_CPU1_P1P0_DP<17>")
	)
	(segment
		(start 366.296194 -211.290408)
		(end 366.296194 -205.432152)
		(width 0.14732)
		(layer "In4.Cu")
		(net "UPI_CPU0_CPU1_P1P0_DP<17>")
	)
	(segment
		(start 360.057954 -190.37173)
		(end 359.411524 -189.712854)
		(width 0.14732)
		(layer "In4.Cu")
		(net "UPI_CPU0_CPU1_P1P0_DP<17>")
	)
	(segment
		(start 341.13216 -169.438066)
		(end 340.582504 -168.831768)
		(width 0.14732)
		(layer "In4.Cu")
		(net "UPI_CPU0_CPU1_P1P0_DP<17>")
	)
	(segment
		(start 343.196418 -173.00575)
		(end 342.352122 -172.074332)
		(width 0.14732)
		(layer "In4.Cu")
		(net "UPI_CPU0_CPU1_P1P0_DP<17>")
	)
	(segment
		(start 344.062812 -173.64075)
		(end 343.196418 -173.00575)
		(width 0.14732)
		(layer "In4.Cu")
		(net "UPI_CPU0_CPU1_P1P0_DP<17>")
	)
	(segment
		(start 341.704676 -170.52798)
		(end 341.399622 -170.804332)
		(width 0.14732)
		(layer "In4.Cu")
		(net "UPI_CPU0_CPU1_P1P0_DP<17>")
	)
	(segment
		(start 366.296448 -211.74583)
		(end 366.296448 -211.290662)
		(width 0.14732)
		(layer "In4.Cu")
		(net "UPI_CPU0_CPU1_P1P0_DP<17>")
	)
	(segment
		(start 366.353344 -212.60562)
		(end 366.353344 -212.43036)
		(width 0.0889)
		(layer "In4.Cu")
		(net "UPI_CPU0_CPU1_P1P0_DP<17>")
	)
	(segment
		(start 366.296448 -211.290662)
		(end 366.296194 -211.290408)
		(width 0.14732)
		(layer "In4.Cu")
		(net "UPI_CPU0_CPU1_P1P0_DP<17>")
	)
	(segment
		(start 342.362282 -171.86656)
		(end 342.667082 -171.590208)
		(width 0.14732)
		(layer "In4.Cu")
		(net "UPI_CPU0_CPU1_P1P0_DP<17>")
	)
	(segment
		(start 365.924338 -218.170252)
		(end 365.92383 -218.17076)
		(width 0.0889)
		(layer "In4.Cu")
		(net "UPI_CPU0_CPU1_P1P0_DP<17>")
	)
	(segment
		(start 322.233036 -153.916888)
		(end 279.616916 -162.844988)
		(width 0.14732)
		(layer "In4.Cu")
		(net "UPI_CPU0_CPU1_P1P0_DP<17>")
	)
	(segment
		(start 366.296448 -211.767928)
		(end 366.296448 -211.74583)
		(width 0.0889)
		(layer "In4.Cu")
		(net "UPI_CPU0_CPU1_P1P0_DP<17>")
	)
	(segment
		(start 339.84311 -169.087038)
		(end 339.635338 -169.076878)
		(width 0.14732)
		(layer "In4.Cu")
		(net "UPI_CPU0_CPU1_P1P0_DP<17>")
	)
	(segment
		(start 340.148164 -168.810686)
		(end 339.84311 -169.087038)
		(width 0.14732)
		(layer "In4.Cu")
		(net "UPI_CPU0_CPU1_P1P0_DP<17>")
	)
	(segment
		(start 366.253776 -215.447118)
		(end 366.253776 -215.438228)
		(width 0.0889)
		(layer "In4.Cu")
		(net "UPI_CPU0_CPU1_P1P0_DP<17>")
	)
	(segment
		(start 105.242614 -216.578688)
		(end 105.242868 -216.578434)
		(width 0.0889)
		(layer "In4.Cu")
		(net "UPI_CPU0_CPU1_P1P0_DP<17>")
	)
	(segment
		(start 166.609268 -151.964136)
		(end 165.128448 -152.48128)
		(width 0.14732)
		(layer "In4.Cu")
		(net "UPI_CPU0_CPU1_P1P0_DP<17>")
	)
	(segment
		(start 104.966262 -217.064336)
		(end 104.966262 -217.07856)
		(width 0.0889)
		(layer "In4.Cu")
		(net "UPI_CPU0_CPU1_P1P0_DP<17>")
	)
	(segment
		(start 105.195624 -215.893396)
		(end 105.253536 -215.928702)
		(width 0.0889)
		(layer "In4.Cu")
		(net "UPI_CPU0_CPU1_P1P0_DP<17>")
	)
	(segment
		(start 105.435908 -214.461344)
		(end 105.435908 -214.622634)
		(width 0.0889)
		(layer "In4.Cu")
		(net "UPI_CPU0_CPU1_P1P0_DP<17>")
	)
	(segment
		(start 132.503926 -172.585888)
		(end 118.39067 -185.857134)
		(width 0.14732)
		(layer "In4.Cu")
		(net "UPI_CPU0_CPU1_P1P0_DP<17>")
	)
	(segment
		(start 104.924606 -212.047328)
		(end 104.966516 -212.089238)
		(width 0.0889)
		(layer "In4.Cu")
		(net "UPI_CPU0_CPU1_P1P0_DP<17>")
	)
	(segment
		(start 366.254284 -212.87994)
		(end 366.254284 -212.70468)
		(width 0.0889)
		(layer "In4.Cu")
		(net "UPI_CPU0_CPU1_P1P0_DP<17>")
	)
	(segment
		(start 105.21823 -217.607388)
		(end 105.061766 -217.878406)
		(width 0.0889)
		(layer "In4.Cu")
		(net "UPI_CPU0_CPU1_P1P0_DP<17>")
	)
	(segment
		(start 118.39067 -185.857134)
		(end 110.69574 -195.54444)
		(width 0.14732)
		(layer "In4.Cu")
		(net "UPI_CPU0_CPU1_P1P0_DP<17>")
	)
	(segment
		(start 348.595696 -175.474884)
		(end 348.11208 -175.443388)
		(width 0.14732)
		(layer "In4.Cu")
		(net "UPI_CPU0_CPU1_P1P0_DP<17>")
	)
	(segment
		(start 342.688672 -171.15536)
		(end 342.139016 -170.549062)
		(width 0.14732)
		(layer "In4.Cu")
		(net "UPI_CPU0_CPU1_P1P0_DP<17>")
	)
	(segment
		(start 366.254284 -211.810092)
		(end 366.296448 -211.767928)
		(width 0.0889)
		(layer "In4.Cu")
		(net "UPI_CPU0_CPU1_P1P0_DP<17>")
	)
	(segment
		(start 279.616916 -162.844988)
		(end 276.533864 -162.844988)
		(width 0.14732)
		(layer "In4.Cu")
		(net "UPI_CPU0_CPU1_P1P0_DP<17>")
	)
	(segment
		(start 104.924352 -211.790788)
		(end 104.924606 -211.791042)
		(width 0.14732)
		(layer "In4.Cu")
		(net "UPI_CPU0_CPU1_P1P0_DP<17>")
	)
	(segment
		(start 234.174538 -152.956768)
		(end 197.051422 -162.52698)
		(width 0.14732)
		(layer "In4.Cu")
		(net "UPI_CPU0_CPU1_P1P0_DP<17>")
	)
	(segment
		(start 340.80577 -170.149266)
		(end 341.11057 -169.872914)
		(width 0.14732)
		(layer "In4.Cu")
		(net "UPI_CPU0_CPU1_P1P0_DP<17>")
	)
	(segment
		(start 341.11057 -169.872914)
		(end 341.13216 -169.438066)
		(width 0.14732)
		(layer "In4.Cu")
		(net "UPI_CPU0_CPU1_P1P0_DP<17>")
	)
	(segment
		(start 359.411524 -189.712854)
		(end 358.17048 -186.71667)
		(width 0.14732)
		(layer "In4.Cu")
		(net "UPI_CPU0_CPU1_P1P0_DP<17>")
	)
	(segment
		(start 340.79561 -170.357038)
		(end 340.80577 -170.149266)
		(width 0.14732)
		(layer "In4.Cu")
		(net "UPI_CPU0_CPU1_P1P0_DP<17>")
	)
	(segment
		(start 197.051422 -162.52698)
		(end 194.609212 -162.834828)
		(width 0.14732)
		(layer "In4.Cu")
		(net "UPI_CPU0_CPU1_P1P0_DP<17>")
	)
	(segment
		(start 342.139016 -170.549062)
		(end 341.704676 -170.52798)
		(width 0.14732)
		(layer "In4.Cu")
		(net "UPI_CPU0_CPU1_P1P0_DP<17>")
	)
	(segment
		(start 173.168818 -153.645362)
		(end 169.952924 -152.052782)
		(width 0.14732)
		(layer "In4.Cu")
		(net "UPI_CPU0_CPU1_P1P0_DP<17>")
	)
	(segment
		(start 365.78413 -216.258394)
		(end 365.78413 -216.235534)
		(width 0.0889)
		(layer "In4.Cu")
		(net "UPI_CPU0_CPU1_P1P0_DP<17>")
	)
	(segment
		(start 356.850442 -180.94579)
		(end 355.975412 -179.205382)
		(width 0.14732)
		(layer "In4.Cu")
		(net "UPI_CPU0_CPU1_P1P0_DP<17>")
	)
	(segment
		(start 276.533864 -162.844988)
		(end 238.0361 -152.956768)
		(width 0.14732)
		(layer "In4.Cu")
		(net "UPI_CPU0_CPU1_P1P0_DP<17>")
	)
	(segment
		(start 358.17048 -184.132982)
		(end 356.850442 -180.94579)
		(width 0.14732)
		(layer "In4.Cu")
		(net "UPI_CPU0_CPU1_P1P0_DP<17>")
	)
	(segment
		(start 169.952924 -152.052782)
		(end 166.609268 -151.964136)
		(width 0.14732)
		(layer "In4.Cu")
		(net "UPI_CPU0_CPU1_P1P0_DP<17>")
	)
	(segment
		(start 351.564448 -175.297592)
		(end 351.254822 -175.085502)
		(width 0.14732)
		(layer "In4.Cu")
		(net "UPI_CPU0_CPU1_P1P0_DP<17>")
	)
	(segment
		(start 366.159034 -217.878406)
		(end 366.00257 -218.149424)
		(width 0.0889)
		(layer "In4.Cu")
		(net "UPI_CPU0_CPU1_P1P0_DP<17>")
	)
	(segment
		(start 366.353344 -213.15426)
		(end 366.353344 -212.979)
		(width 0.0889)
		(layer "In4.Cu")
		(net "UPI_CPU0_CPU1_P1P0_DP<17>")
	)
	(segment
		(start 366.296194 -205.432152)
		(end 360.057954 -190.37173)
		(width 0.14732)
		(layer "In4.Cu")
		(net "UPI_CPU0_CPU1_P1P0_DP<17>")
	)
	(segment
		(start 105.257854 -216.569798)
		(end 105.242614 -216.578688)
		(width 0.0889)
		(layer "In4.Cu")
		(net "UPI_CPU0_CPU1_P1P0_DP<17>")
	)
	(segment
		(start 190.733172 -162.834828)
		(end 173.168818 -153.645362)
		(width 0.14732)
		(layer "In4.Cu")
		(net "UPI_CPU0_CPU1_P1P0_DP<17>")
	)
	(segment
		(start 104.924352 -211.388452)
		(end 104.924352 -211.790788)
		(width 0.14732)
		(layer "In4.Cu")
		(net "UPI_CPU0_CPU1_P1P0_DP<17>")
	)
	(segment
		(start 110.69574 -195.54444)
		(end 104.924352 -211.388452)
		(width 0.14732)
		(layer "In4.Cu")
		(net "UPI_CPU0_CPU1_P1P0_DP<17>")
	)
	(segment
		(start 350.452182 -175.041306)
		(end 348.595696 -175.474884)
		(width 0.14732)
		(layer "In4.Cu")
		(net "UPI_CPU0_CPU1_P1P0_DP<17>")
	)
	(segment
		(start 366.353344 -212.979)
		(end 366.254284 -212.87994)
		(width 0.0889)
		(layer "In4.Cu")
		(net "UPI_CPU0_CPU1_P1P0_DP<17>")
	)
	(segment
		(start 194.609212 -162.834828)
		(end 190.733172 -162.834828)
		(width 0.14732)
		(layer "In4.Cu")
		(net "UPI_CPU0_CPU1_P1P0_DP<17>")
	)
	(segment
		(start 366.441228 -215.112092)
		(end 366.451896 -215.105742)
		(width 0.0889)
		(layer "In4.Cu")
		(net "UPI_CPU0_CPU1_P1P0_DP<17>")
	)
	(segment
		(start 328.059288 -156.304488)
		(end 325.82739 -154.520392)
		(width 0.14732)
		(layer "In4.Cu")
		(net "UPI_CPU0_CPU1_P1P0_DP<17>")
	)
	(segment
		(start 104.924606 -212.02523)
		(end 104.924606 -212.047328)
		(width 0.0889)
		(layer "In4.Cu")
		(net "UPI_CPU0_CPU1_P1P0_DP<17>")
	)
	(segment
		(start 105.257346 -214.941912)
		(end 105.248456 -214.946992)
		(width 0.0889)
		(layer "In4.Cu")
		(net "UPI_CPU0_CPU1_P1P0_DP<17>")
	)
	(segment
		(start 358.17048 -186.71667)
		(end 358.17048 -184.132982)
		(width 0.14732)
		(layer "In4.Cu")
		(net "UPI_CPU0_CPU1_P1P0_DP<17>")
	)
	(segment
		(start 238.0361 -152.956768)
		(end 234.174538 -152.956768)
		(width 0.14732)
		(layer "In4.Cu")
		(net "UPI_CPU0_CPU1_P1P0_DP<17>")
	)
	(segment
		(start 323.426836 -153.916888)
		(end 322.233036 -153.916888)
		(width 0.14732)
		(layer "In4.Cu")
		(net "UPI_CPU0_CPU1_P1P0_DP<17>")
	)
	(segment
		(start 365.78413 -217.890852)
		(end 365.78413 -217.86342)
		(width 0.0889)
		(layer "In4.Cu")
		(net "UPI_CPU0_CPU1_P1P0_DP<17>")
	)
	(segment
		(start 355.975412 -179.205382)
		(end 351.564448 -175.297592)
		(width 0.14732)
		(layer "In4.Cu")
		(net "UPI_CPU0_CPU1_P1P0_DP<17>")
	)
	(segment
		(start 165.128448 -152.48128)
		(end 132.503926 -172.585888)
		(width 0.14732)
		(layer "In4.Cu")
		(net "UPI_CPU0_CPU1_P1P0_DP<17>")
	)
	(segment
		(start 348.11208 -175.443388)
		(end 344.062812 -173.64075)
		(width 0.14732)
		(layer "In4.Cu")
		(net "UPI_CPU0_CPU1_P1P0_DP<17>")
	)
	(segment
		(start 340.582504 -168.831768)
		(end 340.148164 -168.810686)
		(width 0.14732)
		(layer "In4.Cu")
		(net "UPI_CPU0_CPU1_P1P0_DP<17>")
	)
	(segment
		(start 104.924606 -211.791042)
		(end 104.924606 -212.02523)
		(width 0.14732)
		(layer "In4.Cu")
		(net "UPI_CPU0_CPU1_P1P0_DP<17>")
	)
	(segment
		(start 341.19185 -170.794172)
		(end 340.79561 -170.357038)
		(width 0.14732)
		(layer "In4.Cu")
		(net "UPI_CPU0_CPU1_P1P0_DP<17>")
	)
	(segment
		(start 342.667082 -171.590208)
		(end 342.688672 -171.15536)
		(width 0.14732)
		(layer "In4.Cu")
		(net "UPI_CPU0_CPU1_P1P0_DP<17>")
	)
	(segment
		(start 339.635338 -169.076878)
		(end 328.059288 -156.304488)
		(width 0.14732)
		(layer "In4.Cu")
		(net "UPI_CPU0_CPU1_P1P0_DP<17>")
	)
	(segment
		(start 366.254284 -213.895178)
		(end 366.254284 -213.25332)
		(width 0.0889)
		(layer "In4.Cu")
		(net "UPI_CPU0_CPU1_P1P0_DP<17>")
	)
	(segment
		(start 366.254284 -212.3313)
		(end 366.254284 -211.810092)
		(width 0.0889)
		(layer "In4.Cu")
		(net "UPI_CPU0_CPU1_P1P0_DP<17>")
	)
	(segment
		(start 104.966516 -212.089238)
		(end 104.966516 -213.930484)
		(width 0.0889)
		(layer "In4.Cu")
		(net "UPI_CPU0_CPU1_P1P0_DP<17>")
	)
	(segment
		(start 366.254284 -213.25332)
		(end 366.353344 -213.15426)
		(width 0.0889)
		(layer "In4.Cu")
		(net "UPI_CPU0_CPU1_P1P0_DP<17>")
	)
	(segment
		(start 366.254284 -212.70468)
		(end 366.353344 -212.60562)
		(width 0.0889)
		(layer "In4.Cu")
		(net "UPI_CPU0_CPU1_P1P0_DP<17>")
	)
	(segment
		(start 366.353344 -212.43036)
		(end 366.254284 -212.3313)
		(width 0.0889)
		(layer "In4.Cu")
		(net "UPI_CPU0_CPU1_P1P0_DP<17>")
	)
	(segment
		(start 105.1941 -217.518234)
		(end 105.21823 -217.607388)
		(width 0.0889)
		(layer "In4.Cu")
		(net "UPI_CPU0_CPU1_P1P0_DP<17>")
	)
	(segment
		(start 366.72393 -214.622634)
		(end 366.72393 -214.426546)
		(width 0.0889)
		(layer "In4.Cu")
		(net "UPI_CPU0_CPU1_P1P0_DP<17>")
	)
	(segment
		(start 366.253776 -217.075004)
		(end 366.253776 -217.053668)
		(width 0.0889)
		(layer "In4.Cu")
		(net "UPI_CPU0_CPU1_P1P0_DP<17>")
	)
	(arc
		(start 366.72393 -214.426546)
		(mid 366.6127 -214.232891)
		(end 366.43818 -214.093552)
		(width 0.0889)
		(layer "In4.Cu")
		(net "UPI_CPU0_CPU1_P1P0_DP<17>")
	)
	(arc
		(start 365.78413 -217.86342)
		(mid 365.838025 -217.684397)
		(end 365.971582 -217.55354)
		(width 0.0889)
		(layer "In4.Cu")
		(net "UPI_CPU0_CPU1_P1P0_DP<17>")
	)
	(arc
		(start 366.451896 -215.105742)
		(mid 366.65128 -214.899862)
		(end 366.72393 -214.622634)
		(width 0.0889)
		(layer "In4.Cu")
		(net "UPI_CPU0_CPU1_P1P0_DP<17>")
	)
	(arc
		(start 105.253536 -215.928702)
		(mid 105.436257 -216.248016)
		(end 105.257854 -216.569798)
		(width 0.0889)
		(layer "In4.Cu")
		(net "UPI_CPU0_CPU1_P1P0_DP<17>")
	)
	(arc
		(start 105.248456 -214.946992)
		(mid 105.241951 -214.951139)
		(end 105.235502 -214.955374)
		(width 0.0889)
		(layer "In4.Cu")
		(net "UPI_CPU0_CPU1_P1P0_DP<17>")
	)
	(arc
		(start 105.435908 -214.622634)
		(mid 105.388229 -214.805534)
		(end 105.257346 -214.941912)
		(width 0.0889)
		(layer "In4.Cu")
		(net "UPI_CPU0_CPU1_P1P0_DP<17>")
	)
	(arc
		(start 365.971582 -215.925654)
		(mid 366.17556 -215.723478)
		(end 366.253776 -215.447118)
		(width 0.0889)
		(layer "In4.Cu")
		(net "UPI_CPU0_CPU1_P1P0_DP<17>")
	)
	(arc
		(start 104.966516 -213.930484)
		(mid 104.973801 -213.950046)
		(end 104.981756 -213.969346)
		(width 0.0889)
		(layer "In4.Cu")
		(net "UPI_CPU0_CPU1_P1P0_DP<17>")
	)
	(arc
		(start 104.966262 -217.07856)
		(mid 105.024556 -217.315203)
		(end 105.177082 -217.50528)
		(width 0.0889)
		(layer "In4.Cu")
		(net "UPI_CPU0_CPU1_P1P0_DP<17>")
	)
	(arc
		(start 365.92383 -218.17076)
		(mid 365.823442 -218.046057)
		(end 365.78413 -217.890852)
		(width 0.0889)
		(layer "In4.Cu")
		(net "UPI_CPU0_CPU1_P1P0_DP<17>")
	)
	(arc
		(start 104.96677 -215.414606)
		(mid 104.966534 -215.425781)
		(end 104.966516 -215.436958)
		(width 0.0889)
		(layer "In4.Cu")
		(net "UPI_CPU0_CPU1_P1P0_DP<17>")
	)
	(arc
		(start 105.242868 -216.578434)
		(mid 105.040281 -216.784785)
		(end 104.966262 -217.064336)
		(width 0.0889)
		(layer "In4.Cu")
		(net "UPI_CPU0_CPU1_P1P0_DP<17>")
	)
	(arc
		(start 104.966516 -215.483948)
		(mid 105.027696 -215.71853)
		(end 105.195624 -215.893396)
		(width 0.0889)
		(layer "In4.Cu")
		(net "UPI_CPU0_CPU1_P1P0_DP<17>")
	)
	(arc
		(start 104.981756 -213.969346)
		(mid 105.09175 -214.138715)
		(end 105.251758 -214.261954)
		(width 0.0889)
		(layer "In4.Cu")
		(net "UPI_CPU0_CPU1_P1P0_DP<17>")
	)
	(arc
		(start 366.253776 -217.053668)
		(mid 366.175621 -216.777272)
		(end 365.971582 -216.575132)
		(width 0.0889)
		(layer "In4.Cu")
		(net "UPI_CPU0_CPU1_P1P0_DP<17>")
	)
	(arc
		(start 105.177082 -217.50528)
		(mid 105.18553 -217.511837)
		(end 105.1941 -217.518234)
		(width 0.0889)
		(layer "In4.Cu")
		(net "UPI_CPU0_CPU1_P1P0_DP<17>")
	)
	(arc
		(start 366.43818 -214.093552)
		(mid 366.329293 -214.010059)
		(end 366.254284 -213.895178)
		(width 0.0889)
		(layer "In4.Cu")
		(net "UPI_CPU0_CPU1_P1P0_DP<17>")
	)
	(arc
		(start 365.971582 -217.55354)
		(mid 366.17556 -217.351364)
		(end 366.253776 -217.075004)
		(width 0.0889)
		(layer "In4.Cu")
		(net "UPI_CPU0_CPU1_P1P0_DP<17>")
	)
	(arc
		(start 105.251758 -214.261954)
		(mid 105.360905 -214.345882)
		(end 105.435908 -214.461344)
		(width 0.0889)
		(layer "In4.Cu")
		(net "UPI_CPU0_CPU1_P1P0_DP<17>")
	)
	(arc
		(start 366.254284 -215.426544)
		(mid 366.306772 -215.244949)
		(end 366.441228 -215.112092)
		(width 0.0889)
		(layer "In4.Cu")
		(net "UPI_CPU0_CPU1_P1P0_DP<17>")
	)
	(arc
		(start 365.78413 -216.235534)
		(mid 365.838025 -216.056511)
		(end 365.971582 -215.925654)
		(width 0.0889)
		(layer "In4.Cu")
		(net "UPI_CPU0_CPU1_P1P0_DP<17>")
	)
	(arc
		(start 105.235502 -214.955374)
		(mid 105.043728 -215.151387)
		(end 104.96677 -215.414606)
		(width 0.0889)
		(layer "In4.Cu")
		(net "UPI_CPU0_CPU1_P1P0_DP<17>")
	)
	(arc
		(start 365.971582 -216.575132)
		(mid 365.836291 -216.44135)
		(end 365.78413 -216.258394)
		(width 0.0889)
		(layer "In4.Cu")
		(net "UPI_CPU0_CPU1_P1P0_DP<17>")
	)
	(segment
		(start 104.591866 -219.228162)
		(end 104.591866 -218.692476)
		(width 0.13208)
		(layer "F.Cu")
		(net "UPI_CPU0_CPU1_P1P0_DP<16>")
	)
	(segment
		(start 104.591866 -218.692476)
		(end 104.591612 -218.692222)
		(width 0.13208)
		(layer "F.Cu")
		(net "UPI_CPU0_CPU1_P1P0_DP<16>")
	)
	(segment
		(start 366.628934 -217.600276)
		(end 366.628934 -217.06459)
		(width 0.13208)
		(layer "F.Cu")
		(net "UPI_CPU0_CPU1_P1P0_DP<16>")
	)
	(segment
		(start 366.628934 -217.06459)
		(end 366.62868 -217.064336)
		(width 0.13208)
		(layer "F.Cu")
		(net "UPI_CPU0_CPU1_P1P0_DP<16>")
	)
	(segment
		(start 328.5109 -155.938728)
		(end 326.030844 -153.956258)
		(width 0.14732)
		(layer "In4.Cu")
		(net "UPI_CPU0_CPU1_P1P0_DP<16>")
	)
	(segment
		(start 104.259126 -211.790788)
		(end 104.25938 -211.791042)
		(width 0.14732)
		(layer "In4.Cu")
		(net "UPI_CPU0_CPU1_P1P0_DP<16>")
	)
	(segment
		(start 111.994188 -192.804288)
		(end 111.722662 -193.146172)
		(width 0.14732)
		(layer "In4.Cu")
		(net "UPI_CPU0_CPU1_P1P0_DP<16>")
	)
	(segment
		(start 366.904524 -212.835744)
		(end 367.003584 -212.736684)
		(width 0.0889)
		(layer "In4.Cu")
		(net "UPI_CPU0_CPU1_P1P0_DP<16>")
	)
	(segment
		(start 104.402128 -216.741502)
		(end 104.401366 -216.74201)
		(width 0.0889)
		(layer "In4.Cu")
		(net "UPI_CPU0_CPU1_P1P0_DP<16>")
	)
	(segment
		(start 104.687116 -216.25052)
		(end 104.687116 -216.260426)
		(width 0.0889)
		(layer "In4.Cu")
		(net "UPI_CPU0_CPU1_P1P0_DP<16>")
	)
	(segment
		(start 104.687116 -217.859864)
		(end 104.687116 -217.878406)
		(width 0.0889)
		(layer "In4.Cu")
		(net "UPI_CPU0_CPU1_P1P0_DP<16>")
	)
	(segment
		(start 234.10926 -152.364948)
		(end 196.940424 -161.946844)
		(width 0.14732)
		(layer "In4.Cu")
		(net "UPI_CPU0_CPU1_P1P0_DP<16>")
	)
	(segment
		(start 366.904524 -212.287104)
		(end 367.003584 -212.188044)
		(width 0.0889)
		(layer "In4.Cu")
		(net "UPI_CPU0_CPU1_P1P0_DP<16>")
	)
	(segment
		(start 104.404668 -216.739978)
		(end 104.403906 -216.740486)
		(width 0.0889)
		(layer "In4.Cu")
		(net "UPI_CPU0_CPU1_P1P0_DP<16>")
	)
	(segment
		(start 345.323668 -171.816014)
		(end 345.316556 -171.61129)
		(width 0.14732)
		(layer "In4.Cu")
		(net "UPI_CPU0_CPU1_P1P0_DP<16>")
	)
	(segment
		(start 366.824768 -216.745058)
		(end 366.816894 -216.740486)
		(width 0.0889)
		(layer "In4.Cu")
		(net "UPI_CPU0_CPU1_P1P0_DP<16>")
	)
	(segment
		(start 190.923926 -162.245548)
		(end 173.446186 -153.101294)
		(width 0.14732)
		(layer "In4.Cu")
		(net "UPI_CPU0_CPU1_P1P0_DP<16>")
	)
	(segment
		(start 196.940424 -161.946844)
		(end 194.572128 -162.245548)
		(width 0.14732)
		(layer "In4.Cu")
		(net "UPI_CPU0_CPU1_P1P0_DP<16>")
	)
	(segment
		(start 356.805738 -179.564792)
		(end 356.31374 -178.570636)
		(width 0.14732)
		(layer "In4.Cu")
		(net "UPI_CPU0_CPU1_P1P0_DP<16>")
	)
	(segment
		(start 104.25938 -212.027008)
		(end 104.217216 -212.069172)
		(width 0.0889)
		(layer "In4.Cu")
		(net "UPI_CPU0_CPU1_P1P0_DP<16>")
	)
	(segment
		(start 114.79149 -189.282578)
		(end 114.519964 -189.624462)
		(width 0.14732)
		(layer "In4.Cu")
		(net "UPI_CPU0_CPU1_P1P0_DP<16>")
	)
	(segment
		(start 348.623128 -174.89678)
		(end 348.464124 -174.889668)
		(width 0.14732)
		(layer "In4.Cu")
		(net "UPI_CPU0_CPU1_P1P0_DP<16>")
	)
	(segment
		(start 166.504874 -151.295608)
		(end 165.247828 -151.73452)
		(width 0.14732)
		(layer "In4.Cu")
		(net "UPI_CPU0_CPU1_P1P0_DP<16>")
	)
	(segment
		(start 366.62868 -217.064336)
		(end 366.785144 -217.335354)
		(width 0.0889)
		(layer "In4.Cu")
		(net "UPI_CPU0_CPU1_P1P0_DP<16>")
	)
	(segment
		(start 111.47044 -193.65976)
		(end 111.29899 -193.679572)
		(width 0.14732)
		(layer "In4.Cu")
		(net "UPI_CPU0_CPU1_P1P0_DP<16>")
	)
	(segment
		(start 112.689386 -191.929004)
		(end 112.41786 -192.270888)
		(width 0.14732)
		(layer "In4.Cu")
		(net "UPI_CPU0_CPU1_P1P0_DP<16>")
	)
	(segment
		(start 104.404414 -215.761062)
		(end 104.406954 -215.762586)
		(width 0.0889)
		(layer "In4.Cu")
		(net "UPI_CPU0_CPU1_P1P0_DP<16>")
	)
	(segment
		(start 132.21462 -172.09135)
		(end 117.33149 -186.08548)
		(width 0.14732)
		(layer "In4.Cu")
		(net "UPI_CPU0_CPU1_P1P0_DP<16>")
	)
	(segment
		(start 104.686608 -214.59317)
		(end 104.686608 -214.644732)
		(width 0.0889)
		(layer "In4.Cu")
		(net "UPI_CPU0_CPU1_P1P0_DP<16>")
	)
	(segment
		(start 367.003584 -212.561424)
		(end 366.904524 -212.462364)
		(width 0.0889)
		(layer "In4.Cu")
		(net "UPI_CPU0_CPU1_P1P0_DP<16>")
	)
	(segment
		(start 350.637856 -174.417482)
		(end 348.623128 -174.89678)
		(width 0.14732)
		(layer "In4.Cu")
		(net "UPI_CPU0_CPU1_P1P0_DP<16>")
	)
	(segment
		(start 111.29899 -193.679572)
		(end 111.027464 -194.021456)
		(width 0.14732)
		(layer "In4.Cu")
		(net "UPI_CPU0_CPU1_P1P0_DP<16>")
	)
	(segment
		(start 279.555702 -162.255708)
		(end 276.60854 -162.255708)
		(width 0.14732)
		(layer "In4.Cu")
		(net "UPI_CPU0_CPU1_P1P0_DP<16>")
	)
	(segment
		(start 114.539776 -189.795912)
		(end 114.267742 -190.13805)
		(width 0.14732)
		(layer "In4.Cu")
		(net "UPI_CPU0_CPU1_P1P0_DP<16>")
	)
	(segment
		(start 104.217216 -212.069172)
		(end 104.217216 -213.770718)
		(width 0.0889)
		(layer "In4.Cu")
		(net "UPI_CPU0_CPU1_P1P0_DP<16>")
	)
	(segment
		(start 169.98696 -151.38781)
		(end 166.504874 -151.295608)
		(width 0.14732)
		(layer "In4.Cu")
		(net "UPI_CPU0_CPU1_P1P0_DP<16>")
	)
	(segment
		(start 104.401366 -216.74201)
		(end 104.395778 -216.745058)
		(width 0.0889)
		(layer "In4.Cu")
		(net "UPI_CPU0_CPU1_P1P0_DP<16>")
	)
	(segment
		(start 113.57229 -191.013334)
		(end 113.401094 -191.032892)
		(width 0.14732)
		(layer "In4.Cu")
		(net "UPI_CPU0_CPU1_P1P0_DP<16>")
	)
	(segment
		(start 110.222538 -195.034662)
		(end 104.259126 -211.406232)
		(width 0.14732)
		(layer "In4.Cu")
		(net "UPI_CPU0_CPU1_P1P0_DP<16>")
	)
	(segment
		(start 113.113058 -191.395604)
		(end 113.13287 -191.567054)
		(width 0.14732)
		(layer "In4.Cu")
		(net "UPI_CPU0_CPU1_P1P0_DP<16>")
	)
	(segment
		(start 367.003584 -213.110064)
		(end 366.904524 -213.011004)
		(width 0.0889)
		(layer "In4.Cu")
		(net "UPI_CPU0_CPU1_P1P0_DP<16>")
	)
	(segment
		(start 345.797886 -172.060362)
		(end 345.593162 -172.067474)
		(width 0.14732)
		(layer "In4.Cu")
		(net "UPI_CPU0_CPU1_P1P0_DP<16>")
	)
	(segment
		(start 115.234974 -188.920628)
		(end 114.96294 -189.26302)
		(width 0.14732)
		(layer "In4.Cu")
		(net "UPI_CPU0_CPU1_P1P0_DP<16>")
	)
	(segment
		(start 112.860836 -191.909192)
		(end 112.689386 -191.929004)
		(width 0.14732)
		(layer "In4.Cu")
		(net "UPI_CPU0_CPU1_P1P0_DP<16>")
	)
	(segment
		(start 111.742474 -193.317622)
		(end 111.47044 -193.65976)
		(width 0.14732)
		(layer "In4.Cu")
		(net "UPI_CPU0_CPU1_P1P0_DP<16>")
	)
	(segment
		(start 104.259126 -211.406232)
		(end 104.259126 -211.790788)
		(width 0.14732)
		(layer "In4.Cu")
		(net "UPI_CPU0_CPU1_P1P0_DP<16>")
	)
	(segment
		(start 104.395778 -217.383614)
		(end 104.403906 -217.388186)
		(width 0.0889)
		(layer "In4.Cu")
		(net "UPI_CPU0_CPU1_P1P0_DP<16>")
	)
	(segment
		(start 366.961674 -211.72297)
		(end 366.961674 -211.404454)
		(width 0.14732)
		(layer "In4.Cu")
		(net "UPI_CPU0_CPU1_P1P0_DP<16>")
	)
	(segment
		(start 367.27384 -214.954104)
		(end 367.286032 -214.946992)
		(width 0.0889)
		(layer "In4.Cu")
		(net "UPI_CPU0_CPU1_P1P0_DP<16>")
	)
	(segment
		(start 111.047022 -194.192652)
		(end 110.774988 -194.535044)
		(width 0.14732)
		(layer "In4.Cu")
		(net "UPI_CPU0_CPU1_P1P0_DP<16>")
	)
	(segment
		(start 111.722662 -193.146172)
		(end 111.742474 -193.317622)
		(width 0.14732)
		(layer "In4.Cu")
		(net "UPI_CPU0_CPU1_P1P0_DP<16>")
	)
	(segment
		(start 114.96294 -189.26302)
		(end 114.79149 -189.282578)
		(width 0.14732)
		(layer "In4.Cu")
		(net "UPI_CPU0_CPU1_P1P0_DP<16>")
	)
	(segment
		(start 367.003584 -213.93023)
		(end 367.003584 -213.110064)
		(width 0.0889)
		(layer "In4.Cu")
		(net "UPI_CPU0_CPU1_P1P0_DP<16>")
	)
	(segment
		(start 366.961674 -211.745068)
		(end 366.961674 -211.72297)
		(width 0.0889)
		(layer "In4.Cu")
		(net "UPI_CPU0_CPU1_P1P0_DP<16>")
	)
	(segment
		(start 104.435148 -218.421204)
		(end 104.591612 -218.692222)
		(width 0.0889)
		(layer "In4.Cu")
		(net "UPI_CPU0_CPU1_P1P0_DP<16>")
	)
	(segment
		(start 345.593162 -172.067474)
		(end 345.323668 -171.816014)
		(width 0.14732)
		(layer "In4.Cu")
		(net "UPI_CPU0_CPU1_P1P0_DP<16>")
	)
	(segment
		(start 104.403906 -216.740486)
		(end 104.402128 -216.741502)
		(width 0.0889)
		(layer "In4.Cu")
		(net "UPI_CPU0_CPU1_P1P0_DP<16>")
	)
	(segment
		(start 113.824766 -190.499746)
		(end 113.844324 -190.670942)
		(width 0.14732)
		(layer "In4.Cu")
		(net "UPI_CPU0_CPU1_P1P0_DP<16>")
	)
	(segment
		(start 112.41786 -192.270888)
		(end 112.437672 -192.442338)
		(width 0.14732)
		(layer "In4.Cu")
		(net "UPI_CPU0_CPU1_P1P0_DP<16>")
	)
	(segment
		(start 346.25534 -172.486828)
		(end 345.797886 -172.060362)
		(width 0.14732)
		(layer "In4.Cu")
		(net "UPI_CPU0_CPU1_P1P0_DP<16>")
	)
	(segment
		(start 366.96142 -211.4042)
		(end 366.96142 -205.559152)
		(width 0.14732)
		(layer "In4.Cu")
		(net "UPI_CPU0_CPU1_P1P0_DP<16>")
	)
	(segment
		(start 114.519964 -189.624462)
		(end 114.539776 -189.795912)
		(width 0.14732)
		(layer "In4.Cu")
		(net "UPI_CPU0_CPU1_P1P0_DP<16>")
	)
	(segment
		(start 104.25938 -212.00491)
		(end 104.25938 -212.027008)
		(width 0.0889)
		(layer "In4.Cu")
		(net "UPI_CPU0_CPU1_P1P0_DP<16>")
	)
	(segment
		(start 114.096292 -190.157862)
		(end 113.824766 -190.499746)
		(width 0.14732)
		(layer "In4.Cu")
		(net "UPI_CPU0_CPU1_P1P0_DP<16>")
	)
	(segment
		(start 276.60854 -162.255708)
		(end 238.10087 -152.364948)
		(width 0.14732)
		(layer "In4.Cu")
		(net "UPI_CPU0_CPU1_P1P0_DP<16>")
	)
	(segment
		(start 104.459278 -218.33205)
		(end 104.435148 -218.421204)
		(width 0.0889)
		(layer "In4.Cu")
		(net "UPI_CPU0_CPU1_P1P0_DP<16>")
	)
	(segment
		(start 348.254574 -174.880524)
		(end 347.8657 -174.570644)
		(width 0.14732)
		(layer "In4.Cu")
		(net "UPI_CPU0_CPU1_P1P0_DP<16>")
	)
	(segment
		(start 358.73436 -186.552332)
		(end 358.73436 -184.027318)
		(width 0.14732)
		(layer "In4.Cu")
		(net "UPI_CPU0_CPU1_P1P0_DP<16>")
	)
	(segment
		(start 323.52996 -153.327608)
		(end 322.171822 -153.327608)
		(width 0.14732)
		(layer "In4.Cu")
		(net "UPI_CPU0_CPU1_P1P0_DP<16>")
	)
	(segment
		(start 115.215162 -188.749178)
		(end 115.234974 -188.920628)
		(width 0.14732)
		(layer "In4.Cu")
		(net "UPI_CPU0_CPU1_P1P0_DP<16>")
	)
	(segment
		(start 366.904524 -212.462364)
		(end 366.904524 -212.287104)
		(width 0.0889)
		(layer "In4.Cu")
		(net "UPI_CPU0_CPU1_P1P0_DP<16>")
	)
	(segment
		(start 366.816894 -216.740486)
		(end 366.815878 -216.739978)
		(width 0.0889)
		(layer "In4.Cu")
		(net "UPI_CPU0_CPU1_P1P0_DP<16>")
	)
	(segment
		(start 104.404414 -215.112346)
		(end 104.395524 -215.117426)
		(width 0.0889)
		(layer "In4.Cu")
		(net "UPI_CPU0_CPU1_P1P0_DP<16>")
	)
	(segment
		(start 114.267742 -190.13805)
		(end 114.096292 -190.157862)
		(width 0.14732)
		(layer "In4.Cu")
		(net "UPI_CPU0_CPU1_P1P0_DP<16>")
	)
	(segment
		(start 355.329744 -176.582578)
		(end 354.848414 -176.050956)
		(width 0.14732)
		(layer "In4.Cu")
		(net "UPI_CPU0_CPU1_P1P0_DP<16>")
	)
	(segment
		(start 366.785144 -217.335354)
		(end 366.863376 -217.356182)
		(width 0.0889)
		(layer "In4.Cu")
		(net "UPI_CPU0_CPU1_P1P0_DP<16>")
	)
	(segment
		(start 110.603792 -194.554602)
		(end 110.222538 -195.034662)
		(width 0.14732)
		(layer "In4.Cu")
		(net "UPI_CPU0_CPU1_P1P0_DP<16>")
	)
	(segment
		(start 359.924096 -189.425326)
		(end 358.73436 -186.552332)
		(width 0.14732)
		(layer "In4.Cu")
		(net "UPI_CPU0_CPU1_P1P0_DP<16>")
	)
	(segment
		(start 113.13287 -191.567054)
		(end 112.860836 -191.909192)
		(width 0.14732)
		(layer "In4.Cu")
		(net "UPI_CPU0_CPU1_P1P0_DP<16>")
	)
	(segment
		(start 326.030844 -153.956258)
		(end 323.52996 -153.327608)
		(width 0.14732)
		(layer "In4.Cu")
		(net "UPI_CPU0_CPU1_P1P0_DP<16>")
	)
	(segment
		(start 322.171822 -153.327608)
		(end 279.555702 -162.255708)
		(width 0.14732)
		(layer "In4.Cu")
		(net "UPI_CPU0_CPU1_P1P0_DP<16>")
	)
	(segment
		(start 366.815878 -215.761062)
		(end 366.816894 -215.760554)
		(width 0.0889)
		(layer "In4.Cu")
		(net "UPI_CPU0_CPU1_P1P0_DP<16>")
	)
	(segment
		(start 173.446186 -153.101294)
		(end 169.98696 -151.38781)
		(width 0.14732)
		(layer "In4.Cu")
		(net "UPI_CPU0_CPU1_P1P0_DP<16>")
	)
	(segment
		(start 360.537252 -190.050674)
		(end 359.924096 -189.425326)
		(width 0.14732)
		(layer "In4.Cu")
		(net "UPI_CPU0_CPU1_P1P0_DP<16>")
	)
	(segment
		(start 165.247828 -151.73452)
		(end 132.21462 -172.09135)
		(width 0.14732)
		(layer "In4.Cu")
		(net "UPI_CPU0_CPU1_P1P0_DP<16>")
	)
	(segment
		(start 113.844324 -190.670942)
		(end 113.57229 -191.013334)
		(width 0.14732)
		(layer "In4.Cu")
		(net "UPI_CPU0_CPU1_P1P0_DP<16>")
	)
	(segment
		(start 357.29799 -180.559202)
		(end 356.805738 -179.564792)
		(width 0.14732)
		(layer "In4.Cu")
		(net "UPI_CPU0_CPU1_P1P0_DP<16>")
	)
	(segment
		(start 366.816894 -215.760554)
		(end 366.824768 -215.755982)
		(width 0.0889)
		(layer "In4.Cu")
		(net "UPI_CPU0_CPU1_P1P0_DP<16>")
	)
	(segment
		(start 104.40289 -215.7603)
		(end 104.404414 -215.761062)
		(width 0.0889)
		(layer "In4.Cu")
		(net "UPI_CPU0_CPU1_P1P0_DP<16>")
	)
	(segment
		(start 113.401094 -191.032892)
		(end 113.113058 -191.395604)
		(width 0.14732)
		(layer "In4.Cu")
		(net "UPI_CPU0_CPU1_P1P0_DP<16>")
	)
	(segment
		(start 367.473484 -214.622634)
		(end 367.473484 -214.461852)
		(width 0.0889)
		(layer "In4.Cu")
		(net "UPI_CPU0_CPU1_P1P0_DP<16>")
	)
	(segment
		(start 354.848414 -176.050956)
		(end 352.514916 -174.582582)
		(width 0.14732)
		(layer "In4.Cu")
		(net "UPI_CPU0_CPU1_P1P0_DP<16>")
	)
	(segment
		(start 104.395524 -215.755982)
		(end 104.397556 -215.757252)
		(width 0.0889)
		(layer "In4.Cu")
		(net "UPI_CPU0_CPU1_P1P0_DP<16>")
	)
	(segment
		(start 367.003584 -212.188044)
		(end 367.003584 -211.786978)
		(width 0.0889)
		(layer "In4.Cu")
		(net "UPI_CPU0_CPU1_P1P0_DP<16>")
	)
	(segment
		(start 345.316556 -171.61129)
		(end 328.5109 -155.938728)
		(width 0.14732)
		(layer "In4.Cu")
		(net "UPI_CPU0_CPU1_P1P0_DP<16>")
	)
	(segment
		(start 358.73436 -184.027318)
		(end 357.29799 -180.559202)
		(width 0.14732)
		(layer "In4.Cu")
		(net "UPI_CPU0_CPU1_P1P0_DP<16>")
	)
	(segment
		(start 194.572128 -162.245548)
		(end 190.923926 -162.245548)
		(width 0.14732)
		(layer "In4.Cu")
		(net "UPI_CPU0_CPU1_P1P0_DP<16>")
	)
	(segment
		(start 112.437672 -192.442338)
		(end 112.165638 -192.784476)
		(width 0.14732)
		(layer "In4.Cu")
		(net "UPI_CPU0_CPU1_P1P0_DP<16>")
	)
	(segment
		(start 366.961674 -211.404454)
		(end 366.96142 -211.4042)
		(width 0.14732)
		(layer "In4.Cu")
		(net "UPI_CPU0_CPU1_P1P0_DP<16>")
	)
	(segment
		(start 111.027464 -194.021456)
		(end 111.047022 -194.192652)
		(width 0.14732)
		(layer "In4.Cu")
		(net "UPI_CPU0_CPU1_P1P0_DP<16>")
	)
	(segment
		(start 117.33149 -186.08548)
		(end 115.215162 -188.749178)
		(width 0.14732)
		(layer "In4.Cu")
		(net "UPI_CPU0_CPU1_P1P0_DP<16>")
	)
	(segment
		(start 356.313486 -178.570636)
		(end 355.329744 -176.582578)
		(width 0.14732)
		(layer "In4.Cu")
		(net "UPI_CPU0_CPU1_P1P0_DP<16>")
	)
	(segment
		(start 238.10087 -152.364948)
		(end 234.10926 -152.364948)
		(width 0.14732)
		(layer "In4.Cu")
		(net "UPI_CPU0_CPU1_P1P0_DP<16>")
	)
	(segment
		(start 347.8657 -174.570644)
		(end 346.25534 -172.486828)
		(width 0.14732)
		(layer "In4.Cu")
		(net "UPI_CPU0_CPU1_P1P0_DP<16>")
	)
	(segment
		(start 348.464124 -174.889668)
		(end 348.254574 -174.880524)
		(width 0.14732)
		(layer "In4.Cu")
		(net "UPI_CPU0_CPU1_P1P0_DP<16>")
	)
	(segment
		(start 366.904524 -213.011004)
		(end 366.904524 -212.835744)
		(width 0.0889)
		(layer "In4.Cu")
		(net "UPI_CPU0_CPU1_P1P0_DP<16>")
	)
	(segment
		(start 104.25938 -211.791042)
		(end 104.25938 -212.00491)
		(width 0.14732)
		(layer "In4.Cu")
		(net "UPI_CPU0_CPU1_P1P0_DP<16>")
	)
	(segment
		(start 356.31374 -178.570636)
		(end 356.313486 -178.570636)
		(width 0.14732)
		(layer "In4.Cu")
		(net "UPI_CPU0_CPU1_P1P0_DP<16>")
	)
	(segment
		(start 367.003584 -211.786978)
		(end 366.961674 -211.745068)
		(width 0.0889)
		(layer "In4.Cu")
		(net "UPI_CPU0_CPU1_P1P0_DP<16>")
	)
	(segment
		(start 367.003584 -212.736684)
		(end 367.003584 -212.561424)
		(width 0.0889)
		(layer "In4.Cu")
		(net "UPI_CPU0_CPU1_P1P0_DP<16>")
	)
	(segment
		(start 366.96142 -205.559152)
		(end 360.537252 -190.050674)
		(width 0.14732)
		(layer "In4.Cu")
		(net "UPI_CPU0_CPU1_P1P0_DP<16>")
	)
	(segment
		(start 104.406954 -215.762586)
		(end 104.41051 -215.764618)
		(width 0.0889)
		(layer "In4.Cu")
		(net "UPI_CPU0_CPU1_P1P0_DP<16>")
	)
	(segment
		(start 110.774988 -194.535044)
		(end 110.603792 -194.554602)
		(width 0.14732)
		(layer "In4.Cu")
		(net "UPI_CPU0_CPU1_P1P0_DP<16>")
	)
	(segment
		(start 352.514916 -174.582582)
		(end 350.637856 -174.417482)
		(width 0.14732)
		(layer "In4.Cu")
		(net "UPI_CPU0_CPU1_P1P0_DP<16>")
	)
	(segment
		(start 104.400858 -215.75903)
		(end 104.40289 -215.7603)
		(width 0.0889)
		(layer "In4.Cu")
		(net "UPI_CPU0_CPU1_P1P0_DP<16>")
	)
	(segment
		(start 367.286032 -214.946992)
		(end 367.294922 -214.941912)
		(width 0.0889)
		(layer "In4.Cu")
		(net "UPI_CPU0_CPU1_P1P0_DP<16>")
	)
	(segment
		(start 104.397556 -215.757252)
		(end 104.400858 -215.75903)
		(width 0.0889)
		(layer "In4.Cu")
		(net "UPI_CPU0_CPU1_P1P0_DP<16>")
	)
	(segment
		(start 366.533684 -216.266014)
		(end 366.533684 -216.235026)
		(width 0.0889)
		(layer "In4.Cu")
		(net "UPI_CPU0_CPU1_P1P0_DP<16>")
	)
	(segment
		(start 112.165638 -192.784476)
		(end 111.994188 -192.804288)
		(width 0.14732)
		(layer "In4.Cu")
		(net "UPI_CPU0_CPU1_P1P0_DP<16>")
	)
	(segment
		(start 104.403906 -217.388186)
		(end 104.404668 -217.388694)
		(width 0.0889)
		(layer "In4.Cu")
		(net "UPI_CPU0_CPU1_P1P0_DP<16>")
	)
	(arc
		(start 367.01857 -213.968838)
		(mid 367.010748 -213.949662)
		(end 367.003584 -213.93023)
		(width 0.0889)
		(layer "In4.Cu")
		(net "UPI_CPU0_CPU1_P1P0_DP<16>")
	)
	(arc
		(start 104.686608 -214.644732)
		(mid 104.605697 -214.91486)
		(end 104.404414 -215.112346)
		(width 0.0889)
		(layer "In4.Cu")
		(net "UPI_CPU0_CPU1_P1P0_DP<16>")
	)
	(arc
		(start 104.687116 -217.878406)
		(mid 104.631761 -218.122593)
		(end 104.476296 -218.318842)
		(width 0.0889)
		(layer "In4.Cu")
		(net "UPI_CPU0_CPU1_P1P0_DP<16>")
	)
	(arc
		(start 104.395778 -216.745058)
		(mid 104.217181 -217.064336)
		(end 104.395778 -217.383614)
		(width 0.0889)
		(layer "In4.Cu")
		(net "UPI_CPU0_CPU1_P1P0_DP<16>")
	)
	(arc
		(start 367.00333 -215.436704)
		(mid 367.075503 -215.160036)
		(end 367.27384 -214.954104)
		(width 0.0889)
		(layer "In4.Cu")
		(net "UPI_CPU0_CPU1_P1P0_DP<16>")
	)
	(arc
		(start 104.217216 -215.421972)
		(mid 104.217019 -215.429337)
		(end 104.216962 -215.436704)
		(width 0.0889)
		(layer "In4.Cu")
		(net "UPI_CPU0_CPU1_P1P0_DP<16>")
	)
	(arc
		(start 104.401366 -214.093552)
		(mid 104.61021 -214.305551)
		(end 104.686608 -214.59317)
		(width 0.0889)
		(layer "In4.Cu")
		(net "UPI_CPU0_CPU1_P1P0_DP<16>")
	)
	(arc
		(start 104.41051 -215.764618)
		(mid 104.613097 -215.970969)
		(end 104.687116 -216.25052)
		(width 0.0889)
		(layer "In4.Cu")
		(net "UPI_CPU0_CPU1_P1P0_DP<16>")
	)
	(arc
		(start 104.687116 -216.260426)
		(mid 104.609005 -216.537375)
		(end 104.404668 -216.739978)
		(width 0.0889)
		(layer "In4.Cu")
		(net "UPI_CPU0_CPU1_P1P0_DP<16>")
	)
	(arc
		(start 367.294922 -214.941912)
		(mid 367.425836 -214.805552)
		(end 367.473484 -214.622634)
		(width 0.0889)
		(layer "In4.Cu")
		(net "UPI_CPU0_CPU1_P1P0_DP<16>")
	)
	(arc
		(start 366.824768 -215.755982)
		(mid 366.955682 -215.619622)
		(end 367.00333 -215.436704)
		(width 0.0889)
		(layer "In4.Cu")
		(net "UPI_CPU0_CPU1_P1P0_DP<16>")
	)
	(arc
		(start 367.28908 -214.261954)
		(mid 367.128725 -214.138568)
		(end 367.01857 -213.968838)
		(width 0.0889)
		(layer "In4.Cu")
		(net "UPI_CPU0_CPU1_P1P0_DP<16>")
	)
	(arc
		(start 366.533684 -216.235026)
		(mid 366.613054 -215.961292)
		(end 366.815878 -215.761062)
		(width 0.0889)
		(layer "In4.Cu")
		(net "UPI_CPU0_CPU1_P1P0_DP<16>")
	)
	(arc
		(start 104.395524 -215.117426)
		(mid 104.26827 -215.247392)
		(end 104.217216 -215.421972)
		(width 0.0889)
		(layer "In4.Cu")
		(net "UPI_CPU0_CPU1_P1P0_DP<16>")
	)
	(arc
		(start 104.216962 -215.436704)
		(mid 104.264641 -215.619604)
		(end 104.395524 -215.755982)
		(width 0.0889)
		(layer "In4.Cu")
		(net "UPI_CPU0_CPU1_P1P0_DP<16>")
	)
	(arc
		(start 367.473484 -214.461852)
		(mid 367.398413 -214.34611)
		(end 367.28908 -214.261954)
		(width 0.0889)
		(layer "In4.Cu")
		(net "UPI_CPU0_CPU1_P1P0_DP<16>")
	)
	(arc
		(start 367.00333 -217.064336)
		(mid 366.955651 -216.881436)
		(end 366.824768 -216.745058)
		(width 0.0889)
		(layer "In4.Cu")
		(net "UPI_CPU0_CPU1_P1P0_DP<16>")
	)
	(arc
		(start 366.815878 -216.739978)
		(mid 366.613055 -216.539747)
		(end 366.533684 -216.266014)
		(width 0.0889)
		(layer "In4.Cu")
		(net "UPI_CPU0_CPU1_P1P0_DP<16>")
	)
	(arc
		(start 104.217216 -213.770718)
		(mid 104.266503 -213.956531)
		(end 104.401366 -214.093552)
		(width 0.0889)
		(layer "In4.Cu")
		(net "UPI_CPU0_CPU1_P1P0_DP<16>")
	)
	(arc
		(start 104.404668 -217.388694)
		(mid 104.606954 -217.587675)
		(end 104.687116 -217.859864)
		(width 0.0889)
		(layer "In4.Cu")
		(net "UPI_CPU0_CPU1_P1P0_DP<16>")
	)
	(arc
		(start 366.863376 -217.356182)
		(mid 366.966521 -217.226157)
		(end 367.00333 -217.064336)
		(width 0.0889)
		(layer "In4.Cu")
		(net "UPI_CPU0_CPU1_P1P0_DP<16>")
	)
	(arc
		(start 104.476296 -218.318842)
		(mid 104.46785 -218.325527)
		(end 104.459278 -218.33205)
		(width 0.0889)
		(layer "In4.Cu")
		(net "UPI_CPU0_CPU1_P1P0_DP<16>")
	)
	(segment
		(start 368.03838 -217.87866)
		(end 368.038634 -217.878406)
		(width 0.13208)
		(layer "F.Cu")
		(net "UPI_CPU0_CPU1_P1P0_DP<15>")
	)
	(segment
		(start 368.03838 -218.414346)
		(end 368.03838 -217.87866)
		(width 0.13208)
		(layer "F.Cu")
		(net "UPI_CPU0_CPU1_P1P0_DP<15>")
	)
	(segment
		(start 103.181912 -217.87866)
		(end 103.182166 -217.878406)
		(width 0.13208)
		(layer "F.Cu")
		(net "UPI_CPU0_CPU1_P1P0_DP<15>")
	)
	(segment
		(start 103.181912 -218.414346)
		(end 103.181912 -217.87866)
		(width 0.13208)
		(layer "F.Cu")
		(net "UPI_CPU0_CPU1_P1P0_DP<15>")
	)
	(segment
		(start 103.377746 -214.941912)
		(end 103.368856 -214.946992)
		(width 0.0889)
		(layer "In4.Cu")
		(net "UPI_CPU0_CPU1_P1P0_DP<15>")
	)
	(segment
		(start 368.13363 -215.455246)
		(end 368.133884 -215.436704)
		(width 0.0889)
		(layer "In4.Cu")
		(net "UPI_CPU0_CPU1_P1P0_DP<15>")
	)
	(segment
		(start 233.967528 -151.254968)
		(end 196.731636 -160.854136)
		(width 0.14732)
		(layer "In4.Cu")
		(net "UPI_CPU0_CPU1_P1P0_DP<15>")
	)
	(segment
		(start 368.156998 -213.825836)
		(end 368.156998 -213.22538)
		(width 0.0889)
		(layer "In4.Cu")
		(net "UPI_CPU0_CPU1_P1P0_DP<15>")
	)
	(segment
		(start 356.672388 -176.15789)
		(end 355.914706 -175.400208)
		(width 0.14732)
		(layer "In4.Cu")
		(net "UPI_CPU0_CPU1_P1P0_DP<15>")
	)
	(segment
		(start 368.198908 -211.353908)
		(end 368.198908 -205.663292)
		(width 0.14732)
		(layer "In4.Cu")
		(net "UPI_CPU0_CPU1_P1P0_DP<15>")
	)
	(segment
		(start 276.749256 -161.145728)
		(end 238.241586 -151.254968)
		(width 0.14732)
		(layer "In4.Cu")
		(net "UPI_CPU0_CPU1_P1P0_DP<15>")
	)
	(segment
		(start 164.765482 -150.72106)
		(end 131.531614 -171.20108)
		(width 0.14732)
		(layer "In4.Cu")
		(net "UPI_CPU0_CPU1_P1P0_DP<15>")
	)
	(segment
		(start 109.25048 -194.270376)
		(end 103.044752 -211.30768)
		(width 0.14732)
		(layer "In4.Cu")
		(net "UPI_CPU0_CPU1_P1P0_DP<15>")
	)
	(segment
		(start 367.851436 -216.574878)
		(end 367.842546 -216.569798)
		(width 0.0889)
		(layer "In4.Cu")
		(net "UPI_CPU0_CPU1_P1P0_DP<15>")
	)
	(segment
		(start 347.305884 -171.898564)
		(end 329.249532 -155.117292)
		(width 0.14732)
		(layer "In4.Cu")
		(net "UPI_CPU0_CPU1_P1P0_DP<15>")
	)
	(segment
		(start 103.368602 -215.925654)
		(end 103.370126 -215.92667)
		(width 0.0889)
		(layer "In4.Cu")
		(net "UPI_CPU0_CPU1_P1P0_DP<15>")
	)
	(segment
		(start 103.36657 -215.924384)
		(end 103.368602 -215.925654)
		(width 0.0889)
		(layer "In4.Cu")
		(net "UPI_CPU0_CPU1_P1P0_DP<15>")
	)
	(segment
		(start 103.086916 -212.096858)
		(end 103.086916 -213.930484)
		(width 0.0889)
		(layer "In4.Cu")
		(net "UPI_CPU0_CPU1_P1P0_DP<15>")
	)
	(segment
		(start 103.33863 -217.607388)
		(end 103.182166 -217.878406)
		(width 0.0889)
		(layer "In4.Cu")
		(net "UPI_CPU0_CPU1_P1P0_DP<15>")
	)
	(segment
		(start 368.199162 -211.354162)
		(end 368.198908 -211.353908)
		(width 0.14732)
		(layer "In4.Cu")
		(net "UPI_CPU0_CPU1_P1P0_DP<15>")
	)
	(segment
		(start 355.914706 -175.400208)
		(end 355.91496 -175.400208)
		(width 0.14732)
		(layer "In4.Cu")
		(net "UPI_CPU0_CPU1_P1P0_DP<15>")
	)
	(segment
		(start 359.87228 -183.8833)
		(end 356.672388 -176.15789)
		(width 0.14732)
		(layer "In4.Cu")
		(net "UPI_CPU0_CPU1_P1P0_DP<15>")
	)
	(segment
		(start 368.256058 -213.12632)
		(end 368.256058 -212.95106)
		(width 0.0889)
		(layer "In4.Cu")
		(net "UPI_CPU0_CPU1_P1P0_DP<15>")
	)
	(segment
		(start 103.086662 -215.414606)
		(end 103.086662 -215.436704)
		(width 0.0889)
		(layer "In4.Cu")
		(net "UPI_CPU0_CPU1_P1P0_DP<15>")
	)
	(segment
		(start 368.256058 -212.34908)
		(end 368.156998 -212.25002)
		(width 0.0889)
		(layer "In4.Cu")
		(net "UPI_CPU0_CPU1_P1P0_DP<15>")
	)
	(segment
		(start 368.156998 -212.25002)
		(end 368.156998 -211.782152)
		(width 0.0889)
		(layer "In4.Cu")
		(net "UPI_CPU0_CPU1_P1P0_DP<15>")
	)
	(segment
		(start 368.198908 -205.663292)
		(end 361.469432 -189.416944)
		(width 0.14732)
		(layer "In4.Cu")
		(net "UPI_CPU0_CPU1_P1P0_DP<15>")
	)
	(segment
		(start 103.378254 -216.569798)
		(end 103.363014 -216.578688)
		(width 0.0889)
		(layer "In4.Cu")
		(net "UPI_CPU0_CPU1_P1P0_DP<15>")
	)
	(segment
		(start 368.156998 -213.22538)
		(end 368.256058 -213.12632)
		(width 0.0889)
		(layer "In4.Cu")
		(net "UPI_CPU0_CPU1_P1P0_DP<15>")
	)
	(segment
		(start 355.899466 -175.384714)
		(end 351.513902 -172.200062)
		(width 0.14732)
		(layer "In4.Cu")
		(net "UPI_CPU0_CPU1_P1P0_DP<15>")
	)
	(segment
		(start 191.539876 -161.135568)
		(end 174.022004 -151.969978)
		(width 0.14732)
		(layer "In4.Cu")
		(net "UPI_CPU0_CPU1_P1P0_DP<15>")
	)
	(segment
		(start 103.3145 -217.518234)
		(end 103.33863 -217.607388)
		(width 0.0889)
		(layer "In4.Cu")
		(net "UPI_CPU0_CPU1_P1P0_DP<15>")
	)
	(segment
		(start 367.842546 -215.931242)
		(end 367.851436 -215.926162)
		(width 0.0889)
		(layer "In4.Cu")
		(net "UPI_CPU0_CPU1_P1P0_DP<15>")
	)
	(segment
		(start 350.901 -171.994068)
		(end 348.96044 -172.242988)
		(width 0.14732)
		(layer "In4.Cu")
		(net "UPI_CPU0_CPU1_P1P0_DP<15>")
	)
	(segment
		(start 103.086662 -217.064336)
		(end 103.086662 -217.07856)
		(width 0.0889)
		(layer "In4.Cu")
		(net "UPI_CPU0_CPU1_P1P0_DP<15>")
	)
	(segment
		(start 103.372666 -215.92794)
		(end 103.378254 -215.931242)
		(width 0.0889)
		(layer "In4.Cu")
		(net "UPI_CPU0_CPU1_P1P0_DP<15>")
	)
	(segment
		(start 368.038634 -217.878406)
		(end 367.88217 -218.149424)
		(width 0.0889)
		(layer "In4.Cu")
		(net "UPI_CPU0_CPU1_P1P0_DP<15>")
	)
	(segment
		(start 348.21622 -172.248068)
		(end 347.305884 -171.898564)
		(width 0.14732)
		(layer "In4.Cu")
		(net "UPI_CPU0_CPU1_P1P0_DP<15>")
	)
	(segment
		(start 368.156998 -211.782152)
		(end 368.199162 -211.739988)
		(width 0.0889)
		(layer "In4.Cu")
		(net "UPI_CPU0_CPU1_P1P0_DP<15>")
	)
	(segment
		(start 355.91496 -175.400208)
		(end 355.899466 -175.384714)
		(width 0.14732)
		(layer "In4.Cu")
		(net "UPI_CPU0_CPU1_P1P0_DP<15>")
	)
	(segment
		(start 368.603784 -214.636858)
		(end 368.603784 -214.425022)
		(width 0.0889)
		(layer "In4.Cu")
		(net "UPI_CPU0_CPU1_P1P0_DP<15>")
	)
	(segment
		(start 103.370126 -215.92667)
		(end 103.372666 -215.92794)
		(width 0.0889)
		(layer "In4.Cu")
		(net "UPI_CPU0_CPU1_P1P0_DP<15>")
	)
	(segment
		(start 103.044752 -211.653628)
		(end 103.045006 -211.653882)
		(width 0.14732)
		(layer "In4.Cu")
		(net "UPI_CPU0_CPU1_P1P0_DP<15>")
	)
	(segment
		(start 196.731636 -160.854136)
		(end 194.502278 -161.135568)
		(width 0.14732)
		(layer "In4.Cu")
		(net "UPI_CPU0_CPU1_P1P0_DP<15>")
	)
	(segment
		(start 329.249532 -155.117292)
		(end 326.516492 -152.92197)
		(width 0.14732)
		(layer "In4.Cu")
		(net "UPI_CPU0_CPU1_P1P0_DP<15>")
	)
	(segment
		(start 368.156998 -212.6234)
		(end 368.256058 -212.52434)
		(width 0.0889)
		(layer "In4.Cu")
		(net "UPI_CPU0_CPU1_P1P0_DP<15>")
	)
	(segment
		(start 103.363268 -215.922606)
		(end 103.36657 -215.924384)
		(width 0.0889)
		(layer "In4.Cu")
		(net "UPI_CPU0_CPU1_P1P0_DP<15>")
	)
	(segment
		(start 103.044752 -211.30768)
		(end 103.044752 -211.653628)
		(width 0.14732)
		(layer "In4.Cu")
		(net "UPI_CPU0_CPU1_P1P0_DP<15>")
	)
	(segment
		(start 194.502278 -161.135568)
		(end 191.539876 -161.135568)
		(width 0.14732)
		(layer "In4.Cu")
		(net "UPI_CPU0_CPU1_P1P0_DP<15>")
	)
	(segment
		(start 103.363014 -216.578688)
		(end 103.363268 -216.578434)
		(width 0.0889)
		(layer "In4.Cu")
		(net "UPI_CPU0_CPU1_P1P0_DP<15>")
	)
	(segment
		(start 368.256058 -212.52434)
		(end 368.256058 -212.34908)
		(width 0.0889)
		(layer "In4.Cu")
		(net "UPI_CPU0_CPU1_P1P0_DP<15>")
	)
	(segment
		(start 368.133884 -217.082878)
		(end 368.133884 -217.05443)
		(width 0.0889)
		(layer "In4.Cu")
		(net "UPI_CPU0_CPU1_P1P0_DP<15>")
	)
	(segment
		(start 368.199162 -211.739988)
		(end 368.199162 -211.71789)
		(width 0.0889)
		(layer "In4.Cu")
		(net "UPI_CPU0_CPU1_P1P0_DP<15>")
	)
	(segment
		(start 360.872024 -188.808106)
		(end 359.87228 -186.393582)
		(width 0.14732)
		(layer "In4.Cu")
		(net "UPI_CPU0_CPU1_P1P0_DP<15>")
	)
	(segment
		(start 103.045006 -212.054948)
		(end 103.086916 -212.096858)
		(width 0.0889)
		(layer "In4.Cu")
		(net "UPI_CPU0_CPU1_P1P0_DP<15>")
	)
	(segment
		(start 351.513902 -172.200062)
		(end 350.901 -171.994068)
		(width 0.14732)
		(layer "In4.Cu")
		(net "UPI_CPU0_CPU1_P1P0_DP<15>")
	)
	(segment
		(start 174.022004 -151.969978)
		(end 172.245274 -151.090122)
		(width 0.14732)
		(layer "In4.Cu")
		(net "UPI_CPU0_CPU1_P1P0_DP<15>")
	)
	(segment
		(start 322.056506 -152.217628)
		(end 279.440386 -161.145728)
		(width 0.14732)
		(layer "In4.Cu")
		(net "UPI_CPU0_CPU1_P1P0_DP<15>")
	)
	(segment
		(start 368.156998 -212.852)
		(end 368.156998 -212.6234)
		(width 0.0889)
		(layer "In4.Cu")
		(net "UPI_CPU0_CPU1_P1P0_DP<15>")
	)
	(segment
		(start 115.903248 -185.895996)
		(end 109.25048 -194.270376)
		(width 0.14732)
		(layer "In4.Cu")
		(net "UPI_CPU0_CPU1_P1P0_DP<15>")
	)
	(segment
		(start 103.045006 -212.03285)
		(end 103.045006 -212.054948)
		(width 0.0889)
		(layer "In4.Cu")
		(net "UPI_CPU0_CPU1_P1P0_DP<15>")
	)
	(segment
		(start 368.256058 -212.95106)
		(end 368.156998 -212.852)
		(width 0.0889)
		(layer "In4.Cu")
		(net "UPI_CPU0_CPU1_P1P0_DP<15>")
	)
	(segment
		(start 172.245274 -151.090122)
		(end 172.245274 -151.089868)
		(width 0.14732)
		(layer "In4.Cu")
		(net "UPI_CPU0_CPU1_P1P0_DP<15>")
	)
	(segment
		(start 172.245274 -151.089868)
		(end 170.416982 -150.184358)
		(width 0.14732)
		(layer "In4.Cu")
		(net "UPI_CPU0_CPU1_P1P0_DP<15>")
	)
	(segment
		(start 359.87228 -186.393582)
		(end 359.87228 -183.8833)
		(width 0.14732)
		(layer "In4.Cu")
		(net "UPI_CPU0_CPU1_P1P0_DP<15>")
	)
	(segment
		(start 279.440386 -161.145728)
		(end 276.749256 -161.145728)
		(width 0.14732)
		(layer "In4.Cu")
		(net "UPI_CPU0_CPU1_P1P0_DP<15>")
	)
	(segment
		(start 367.88217 -218.149424)
		(end 367.803938 -218.170252)
		(width 0.0889)
		(layer "In4.Cu")
		(net "UPI_CPU0_CPU1_P1P0_DP<15>")
	)
	(segment
		(start 348.96044 -172.242988)
		(end 348.21622 -172.248068)
		(width 0.14732)
		(layer "In4.Cu")
		(net "UPI_CPU0_CPU1_P1P0_DP<15>")
	)
	(segment
		(start 326.516492 -152.92197)
		(end 323.712586 -152.217628)
		(width 0.14732)
		(layer "In4.Cu")
		(net "UPI_CPU0_CPU1_P1P0_DP<15>")
	)
	(segment
		(start 367.842546 -217.559128)
		(end 367.851436 -217.554048)
		(width 0.0889)
		(layer "In4.Cu")
		(net "UPI_CPU0_CPU1_P1P0_DP<15>")
	)
	(segment
		(start 368.133884 -215.436704)
		(end 368.133884 -215.428068)
		(width 0.0889)
		(layer "In4.Cu")
		(net "UPI_CPU0_CPU1_P1P0_DP<15>")
	)
	(segment
		(start 131.531614 -171.20108)
		(end 115.903248 -185.895996)
		(width 0.14732)
		(layer "In4.Cu")
		(net "UPI_CPU0_CPU1_P1P0_DP<15>")
	)
	(segment
		(start 238.241586 -151.254968)
		(end 233.967528 -151.254968)
		(width 0.14732)
		(layer "In4.Cu")
		(net "UPI_CPU0_CPU1_P1P0_DP<15>")
	)
	(segment
		(start 368.199162 -211.71789)
		(end 368.199162 -211.354162)
		(width 0.14732)
		(layer "In4.Cu")
		(net "UPI_CPU0_CPU1_P1P0_DP<15>")
	)
	(segment
		(start 103.556308 -214.461344)
		(end 103.556308 -214.622634)
		(width 0.0889)
		(layer "In4.Cu")
		(net "UPI_CPU0_CPU1_P1P0_DP<15>")
	)
	(segment
		(start 103.045006 -211.653882)
		(end 103.045006 -212.03285)
		(width 0.14732)
		(layer "In4.Cu")
		(net "UPI_CPU0_CPU1_P1P0_DP<15>")
	)
	(segment
		(start 323.712586 -152.217628)
		(end 322.056506 -152.217628)
		(width 0.14732)
		(layer "In4.Cu")
		(net "UPI_CPU0_CPU1_P1P0_DP<15>")
	)
	(segment
		(start 166.591488 -150.083266)
		(end 164.765482 -150.72106)
		(width 0.14732)
		(layer "In4.Cu")
		(net "UPI_CPU0_CPU1_P1P0_DP<15>")
	)
	(segment
		(start 361.469432 -189.416944)
		(end 360.872024 -188.808106)
		(width 0.14732)
		(layer "In4.Cu")
		(net "UPI_CPU0_CPU1_P1P0_DP<15>")
	)
	(segment
		(start 170.416982 -150.184358)
		(end 166.591488 -150.083266)
		(width 0.14732)
		(layer "In4.Cu")
		(net "UPI_CPU0_CPU1_P1P0_DP<15>")
	)
	(arc
		(start 367.664238 -216.238328)
		(mid 367.714731 -216.06235)
		(end 367.842546 -215.931242)
		(width 0.0889)
		(layer "In4.Cu")
		(net "UPI_CPU0_CPU1_P1P0_DP<15>")
	)
	(arc
		(start 367.851436 -217.554048)
		(mid 368.053722 -217.355067)
		(end 368.133884 -217.082878)
		(width 0.0889)
		(layer "In4.Cu")
		(net "UPI_CPU0_CPU1_P1P0_DP<15>")
	)
	(arc
		(start 103.363268 -216.578434)
		(mid 103.160681 -216.784785)
		(end 103.086662 -217.064336)
		(width 0.0889)
		(layer "In4.Cu")
		(net "UPI_CPU0_CPU1_P1P0_DP<15>")
	)
	(arc
		(start 103.556308 -214.622634)
		(mid 103.508629 -214.805534)
		(end 103.377746 -214.941912)
		(width 0.0889)
		(layer "In4.Cu")
		(net "UPI_CPU0_CPU1_P1P0_DP<15>")
	)
	(arc
		(start 103.086662 -215.436704)
		(mid 103.160653 -215.71627)
		(end 103.363268 -215.922606)
		(width 0.0889)
		(layer "In4.Cu")
		(net "UPI_CPU0_CPU1_P1P0_DP<15>")
	)
	(arc
		(start 103.378254 -215.931242)
		(mid 103.556851 -216.25052)
		(end 103.378254 -216.569798)
		(width 0.0889)
		(layer "In4.Cu")
		(net "UPI_CPU0_CPU1_P1P0_DP<15>")
	)
	(arc
		(start 367.842546 -216.569798)
		(mid 367.713257 -216.436312)
		(end 367.663984 -216.257124)
		(width 0.0889)
		(layer "In4.Cu")
		(net "UPI_CPU0_CPU1_P1P0_DP<15>")
	)
	(arc
		(start 103.372158 -214.261954)
		(mid 103.481305 -214.345882)
		(end 103.556308 -214.461344)
		(width 0.0889)
		(layer "In4.Cu")
		(net "UPI_CPU0_CPU1_P1P0_DP<15>")
	)
	(arc
		(start 368.133884 -215.428068)
		(mid 368.186154 -215.245703)
		(end 368.321082 -215.112346)
		(width 0.0889)
		(layer "In4.Cu")
		(net "UPI_CPU0_CPU1_P1P0_DP<15>")
	)
	(arc
		(start 103.086916 -213.930484)
		(mid 103.094201 -213.950046)
		(end 103.102156 -213.969346)
		(width 0.0889)
		(layer "In4.Cu")
		(net "UPI_CPU0_CPU1_P1P0_DP<15>")
	)
	(arc
		(start 103.368856 -214.946992)
		(mid 103.167574 -215.144479)
		(end 103.086662 -215.414606)
		(width 0.0889)
		(layer "In4.Cu")
		(net "UPI_CPU0_CPU1_P1P0_DP<15>")
	)
	(arc
		(start 368.603784 -214.425022)
		(mid 368.492446 -214.232122)
		(end 368.318288 -214.093298)
		(width 0.0889)
		(layer "In4.Cu")
		(net "UPI_CPU0_CPU1_P1P0_DP<15>")
	)
	(arc
		(start 103.086662 -217.07856)
		(mid 103.144956 -217.315203)
		(end 103.297482 -217.50528)
		(width 0.0889)
		(layer "In4.Cu")
		(net "UPI_CPU0_CPU1_P1P0_DP<15>")
	)
	(arc
		(start 367.851436 -215.926162)
		(mid 368.053478 -215.727239)
		(end 368.13363 -215.455246)
		(width 0.0889)
		(layer "In4.Cu")
		(net "UPI_CPU0_CPU1_P1P0_DP<15>")
	)
	(arc
		(start 368.318288 -214.093298)
		(mid 368.200481 -213.981987)
		(end 368.156998 -213.825836)
		(width 0.0889)
		(layer "In4.Cu")
		(net "UPI_CPU0_CPU1_P1P0_DP<15>")
	)
	(arc
		(start 368.133884 -217.05443)
		(mid 368.055773 -216.777481)
		(end 367.851436 -216.574878)
		(width 0.0889)
		(layer "In4.Cu")
		(net "UPI_CPU0_CPU1_P1P0_DP<15>")
	)
	(arc
		(start 368.321082 -215.112346)
		(mid 368.524563 -214.911542)
		(end 368.603784 -214.636858)
		(width 0.0889)
		(layer "In4.Cu")
		(net "UPI_CPU0_CPU1_P1P0_DP<15>")
	)
	(arc
		(start 367.663984 -216.257124)
		(mid 367.663994 -216.247724)
		(end 367.664238 -216.238328)
		(width 0.0889)
		(layer "In4.Cu")
		(net "UPI_CPU0_CPU1_P1P0_DP<15>")
	)
	(arc
		(start 367.803938 -218.170252)
		(mid 367.700793 -218.040227)
		(end 367.663984 -217.878406)
		(width 0.0889)
		(layer "In4.Cu")
		(net "UPI_CPU0_CPU1_P1P0_DP<15>")
	)
	(arc
		(start 103.297482 -217.50528)
		(mid 103.30593 -217.511837)
		(end 103.3145 -217.518234)
		(width 0.0889)
		(layer "In4.Cu")
		(net "UPI_CPU0_CPU1_P1P0_DP<15>")
	)
	(arc
		(start 367.663984 -217.878406)
		(mid 367.711663 -217.695506)
		(end 367.842546 -217.559128)
		(width 0.0889)
		(layer "In4.Cu")
		(net "UPI_CPU0_CPU1_P1P0_DP<15>")
	)
	(arc
		(start 103.102156 -213.969346)
		(mid 103.21215 -214.138715)
		(end 103.372158 -214.261954)
		(width 0.0889)
		(layer "In4.Cu")
		(net "UPI_CPU0_CPU1_P1P0_DP<15>")
	)
	(segment
		(start 102.712266 -219.228162)
		(end 102.712266 -218.692476)
		(width 0.13208)
		(layer "F.Cu")
		(net "UPI_CPU0_CPU1_P1P0_DP<14>")
	)
	(segment
		(start 368.508534 -217.06459)
		(end 368.50828 -217.064336)
		(width 0.13208)
		(layer "F.Cu")
		(net "UPI_CPU0_CPU1_P1P0_DP<14>")
	)
	(segment
		(start 368.508534 -217.600276)
		(end 368.508534 -217.06459)
		(width 0.13208)
		(layer "F.Cu")
		(net "UPI_CPU0_CPU1_P1P0_DP<14>")
	)
	(segment
		(start 102.712266 -218.692476)
		(end 102.712012 -218.692222)
		(width 0.13208)
		(layer "F.Cu")
		(net "UPI_CPU0_CPU1_P1P0_DP<14>")
	)
	(segment
		(start 109.970062 -192.453768)
		(end 109.798866 -192.47358)
		(width 0.14732)
		(layer "In4.Cu")
		(net "UPI_CPU0_CPU1_P1P0_DP<14>")
	)
	(segment
		(start 356.441248 -174.504604)
		(end 356.300278 -174.16399)
		(width 0.14732)
		(layer "In4.Cu")
		(net "UPI_CPU0_CPU1_P1P0_DP<14>")
	)
	(segment
		(start 174.32401 -151.376888)
		(end 170.581066 -149.523196)
		(width 0.14732)
		(layer "In4.Cu")
		(net "UPI_CPU0_CPU1_P1P0_DP<14>")
	)
	(segment
		(start 112.580166 -188.972444)
		(end 112.30864 -189.314328)
		(width 0.14732)
		(layer "In4.Cu")
		(net "UPI_CPU0_CPU1_P1P0_DP<14>")
	)
	(segment
		(start 368.883184 -213.331806)
		(end 368.784378 -213.233)
		(width 0.0889)
		(layer "In4.Cu")
		(net "UPI_CPU0_CPU1_P1P0_DP<14>")
	)
	(segment
		(start 368.695478 -215.761062)
		(end 368.696494 -215.760554)
		(width 0.0889)
		(layer "In4.Cu")
		(net "UPI_CPU0_CPU1_P1P0_DP<14>")
	)
	(segment
		(start 102.379526 -211.653628)
		(end 102.37978 -211.653882)
		(width 0.14732)
		(layer "In4.Cu")
		(net "UPI_CPU0_CPU1_P1P0_DP<14>")
	)
	(segment
		(start 368.664744 -217.335354)
		(end 368.742976 -217.356182)
		(width 0.0889)
		(layer "In4.Cu")
		(net "UPI_CPU0_CPU1_P1P0_DP<14>")
	)
	(segment
		(start 102.524814 -215.112346)
		(end 102.52456 -215.1126)
		(width 0.0889)
		(layer "In4.Cu")
		(net "UPI_CPU0_CPU1_P1P0_DP<14>")
	)
	(segment
		(start 109.259624 -193.34861)
		(end 109.088174 -193.368168)
		(width 0.14732)
		(layer "In4.Cu")
		(net "UPI_CPU0_CPU1_P1P0_DP<14>")
	)
	(segment
		(start 102.52329 -215.7603)
		(end 102.524814 -215.761062)
		(width 0.0889)
		(layer "In4.Cu")
		(net "UPI_CPU0_CPU1_P1P0_DP<14>")
	)
	(segment
		(start 166.69258 -149.420326)
		(end 164.610796 -150.147528)
		(width 0.14732)
		(layer "In4.Cu")
		(net "UPI_CPU0_CPU1_P1P0_DP<14>")
	)
	(segment
		(start 350.481392 -171.341796)
		(end 350.481392 -171.34205)
		(width 0.14732)
		(layer "In4.Cu")
		(net "UPI_CPU0_CPU1_P1P0_DP<14>")
	)
	(segment
		(start 368.841274 -205.765146)
		(end 361.879388 -188.956188)
		(width 0.14732)
		(layer "In4.Cu")
		(net "UPI_CPU0_CPU1_P1P0_DP<14>")
	)
	(segment
		(start 112.751616 -188.952886)
		(end 112.580166 -188.972444)
		(width 0.14732)
		(layer "In4.Cu")
		(net "UPI_CPU0_CPU1_P1P0_DP<14>")
	)
	(segment
		(start 102.52456 -215.1126)
		(end 102.515924 -215.117426)
		(width 0.0889)
		(layer "In4.Cu")
		(net "UPI_CPU0_CPU1_P1P0_DP<14>")
	)
	(segment
		(start 355.46284 -172.818806)
		(end 354.61321 -171.968922)
		(width 0.14732)
		(layer "In4.Cu")
		(net "UPI_CPU0_CPU1_P1P0_DP<14>")
	)
	(segment
		(start 368.413284 -216.266014)
		(end 368.413284 -216.235026)
		(width 0.0889)
		(layer "In4.Cu")
		(net "UPI_CPU0_CPU1_P1P0_DP<14>")
	)
	(segment
		(start 368.883438 -212.2043)
		(end 368.883438 -211.728558)
		(width 0.0889)
		(layer "In4.Cu")
		(net "UPI_CPU0_CPU1_P1P0_DP<14>")
	)
	(segment
		(start 102.521766 -216.74201)
		(end 102.516178 -216.745058)
		(width 0.0889)
		(layer "In4.Cu")
		(net "UPI_CPU0_CPU1_P1P0_DP<14>")
	)
	(segment
		(start 110.937548 -191.236346)
		(end 110.665514 -191.578738)
		(width 0.14732)
		(layer "In4.Cu")
		(net "UPI_CPU0_CPU1_P1P0_DP<14>")
	)
	(segment
		(start 279.2095 -160.592008)
		(end 276.962362 -160.592008)
		(width 0.14732)
		(layer "In4.Cu")
		(net "UPI_CPU0_CPU1_P1P0_DP<14>")
	)
	(segment
		(start 102.524814 -215.761062)
		(end 102.526338 -215.762078)
		(width 0.0889)
		(layer "In4.Cu")
		(net "UPI_CPU0_CPU1_P1P0_DP<14>")
	)
	(segment
		(start 348.86646 -171.67352)
		(end 348.30766 -171.684188)
		(width 0.14732)
		(layer "In4.Cu")
		(net "UPI_CPU0_CPU1_P1P0_DP<14>")
	)
	(segment
		(start 102.515924 -215.755982)
		(end 102.517956 -215.757252)
		(width 0.0889)
		(layer "In4.Cu")
		(net "UPI_CPU0_CPU1_P1P0_DP<14>")
	)
	(segment
		(start 110.494064 -191.598296)
		(end 110.222538 -191.94018)
		(width 0.14732)
		(layer "In4.Cu")
		(net "UPI_CPU0_CPU1_P1P0_DP<14>")
	)
	(segment
		(start 112.056164 -189.82817)
		(end 111.884714 -189.847728)
		(width 0.14732)
		(layer "In4.Cu")
		(net "UPI_CPU0_CPU1_P1P0_DP<14>")
	)
	(segment
		(start 108.816648 -193.710052)
		(end 102.379526 -211.382864)
		(width 0.14732)
		(layer "In4.Cu")
		(net "UPI_CPU0_CPU1_P1P0_DP<14>")
	)
	(segment
		(start 112.30864 -189.314328)
		(end 112.328198 -189.485778)
		(width 0.14732)
		(layer "In4.Cu")
		(net "UPI_CPU0_CPU1_P1P0_DP<14>")
	)
	(segment
		(start 170.581066 -149.523196)
		(end 166.69258 -149.420326)
		(width 0.14732)
		(layer "In4.Cu")
		(net "UPI_CPU0_CPU1_P1P0_DP<14>")
	)
	(segment
		(start 368.883184 -213.93023)
		(end 368.883184 -213.331806)
		(width 0.0889)
		(layer "In4.Cu")
		(net "UPI_CPU0_CPU1_P1P0_DP<14>")
	)
	(segment
		(start 114.836956 -186.131962)
		(end 113.004092 -188.439044)
		(width 0.14732)
		(layer "In4.Cu")
		(net "UPI_CPU0_CPU1_P1P0_DP<14>")
	)
	(segment
		(start 369.15344 -214.954104)
		(end 369.165632 -214.946992)
		(width 0.0889)
		(layer "In4.Cu")
		(net "UPI_CPU0_CPU1_P1P0_DP<14>")
	)
	(segment
		(start 233.891074 -150.665688)
		(end 196.402706 -160.330134)
		(width 0.14732)
		(layer "In4.Cu")
		(net "UPI_CPU0_CPU1_P1P0_DP<14>")
	)
	(segment
		(start 113.004092 -188.439044)
		(end 113.02365 -188.610494)
		(width 0.14732)
		(layer "In4.Cu")
		(net "UPI_CPU0_CPU1_P1P0_DP<14>")
	)
	(segment
		(start 354.612702 -171.968668)
		(end 353.042474 -171.049442)
		(width 0.14732)
		(layer "In4.Cu")
		(net "UPI_CPU0_CPU1_P1P0_DP<14>")
	)
	(segment
		(start 102.525068 -216.739978)
		(end 102.524306 -216.740486)
		(width 0.0889)
		(layer "In4.Cu")
		(net "UPI_CPU0_CPU1_P1P0_DP<14>")
	)
	(segment
		(start 191.916304 -160.581848)
		(end 174.32401 -151.376888)
		(width 0.14732)
		(layer "In4.Cu")
		(net "UPI_CPU0_CPU1_P1P0_DP<14>")
	)
	(segment
		(start 102.555548 -218.421204)
		(end 102.712012 -218.692222)
		(width 0.0889)
		(layer "In4.Cu")
		(net "UPI_CPU0_CPU1_P1P0_DP<14>")
	)
	(segment
		(start 110.222538 -191.94018)
		(end 110.242096 -192.11163)
		(width 0.14732)
		(layer "In4.Cu")
		(net "UPI_CPU0_CPU1_P1P0_DP<14>")
	)
	(segment
		(start 368.841274 -211.50326)
		(end 368.841274 -205.765146)
		(width 0.14732)
		(layer "In4.Cu")
		(net "UPI_CPU0_CPU1_P1P0_DP<14>")
	)
	(segment
		(start 368.883438 -212.95868)
		(end 368.883438 -212.57768)
		(width 0.0889)
		(layer "In4.Cu")
		(net "UPI_CPU0_CPU1_P1P0_DP<14>")
	)
	(segment
		(start 354.61321 -171.968922)
		(end 354.612702 -171.968668)
		(width 0.14732)
		(layer "In4.Cu")
		(net "UPI_CPU0_CPU1_P1P0_DP<14>")
	)
	(segment
		(start 110.665514 -191.578738)
		(end 110.494064 -191.598296)
		(width 0.14732)
		(layer "In4.Cu")
		(net "UPI_CPU0_CPU1_P1P0_DP<14>")
	)
	(segment
		(start 356.630478 -174.582836)
		(end 356.441248 -174.504604)
		(width 0.14732)
		(layer "In4.Cu")
		(net "UPI_CPU0_CPU1_P1P0_DP<14>")
	)
	(segment
		(start 368.883438 -212.57768)
		(end 368.784378 -212.47862)
		(width 0.0889)
		(layer "In4.Cu")
		(net "UPI_CPU0_CPU1_P1P0_DP<14>")
	)
	(segment
		(start 276.962362 -160.592008)
		(end 238.316262 -150.665688)
		(width 0.14732)
		(layer "In4.Cu")
		(net "UPI_CPU0_CPU1_P1P0_DP<14>")
	)
	(segment
		(start 102.37978 -211.955888)
		(end 102.337616 -211.998052)
		(width 0.0889)
		(layer "In4.Cu")
		(net "UPI_CPU0_CPU1_P1P0_DP<14>")
	)
	(segment
		(start 348.30766 -171.684188)
		(end 347.61424 -171.412408)
		(width 0.14732)
		(layer "In4.Cu")
		(net "UPI_CPU0_CPU1_P1P0_DP<14>")
	)
	(segment
		(start 368.841528 -211.686648)
		(end 368.841528 -211.66455)
		(width 0.0889)
		(layer "In4.Cu")
		(net "UPI_CPU0_CPU1_P1P0_DP<14>")
	)
	(segment
		(start 110.242096 -192.11163)
		(end 109.970062 -192.453768)
		(width 0.14732)
		(layer "In4.Cu")
		(net "UPI_CPU0_CPU1_P1P0_DP<14>")
	)
	(segment
		(start 368.784378 -212.30336)
		(end 368.883438 -212.2043)
		(width 0.0889)
		(layer "In4.Cu")
		(net "UPI_CPU0_CPU1_P1P0_DP<14>")
	)
	(segment
		(start 194.41033 -160.581848)
		(end 191.916304 -160.581848)
		(width 0.14732)
		(layer "In4.Cu")
		(net "UPI_CPU0_CPU1_P1P0_DP<14>")
	)
	(segment
		(start 368.784378 -213.233)
		(end 368.784378 -213.05774)
		(width 0.0889)
		(layer "In4.Cu")
		(net "UPI_CPU0_CPU1_P1P0_DP<14>")
	)
	(segment
		(start 323.72935 -151.628348)
		(end 321.995292 -151.628348)
		(width 0.14732)
		(layer "In4.Cu")
		(net "UPI_CPU0_CPU1_P1P0_DP<14>")
	)
	(segment
		(start 102.521258 -215.75903)
		(end 102.52329 -215.7603)
		(width 0.0889)
		(layer "In4.Cu")
		(net "UPI_CPU0_CPU1_P1P0_DP<14>")
	)
	(segment
		(start 368.784378 -213.05774)
		(end 368.883438 -212.95868)
		(width 0.0889)
		(layer "In4.Cu")
		(net "UPI_CPU0_CPU1_P1P0_DP<14>")
	)
	(segment
		(start 102.379526 -211.382864)
		(end 102.379526 -211.653628)
		(width 0.14732)
		(layer "In4.Cu")
		(net "UPI_CPU0_CPU1_P1P0_DP<14>")
	)
	(segment
		(start 368.50828 -217.064336)
		(end 368.664744 -217.335354)
		(width 0.0889)
		(layer "In4.Cu")
		(net "UPI_CPU0_CPU1_P1P0_DP<14>")
	)
	(segment
		(start 109.088174 -193.368168)
		(end 108.816648 -193.710052)
		(width 0.14732)
		(layer "In4.Cu")
		(net "UPI_CPU0_CPU1_P1P0_DP<14>")
	)
	(segment
		(start 111.360966 -190.703454)
		(end 111.189516 -190.723012)
		(width 0.14732)
		(layer "In4.Cu")
		(net "UPI_CPU0_CPU1_P1P0_DP<14>")
	)
	(segment
		(start 102.516178 -217.383614)
		(end 102.524306 -217.388186)
		(width 0.0889)
		(layer "In4.Cu")
		(net "UPI_CPU0_CPU1_P1P0_DP<14>")
	)
	(segment
		(start 369.353084 -214.622634)
		(end 369.353084 -214.461852)
		(width 0.0889)
		(layer "In4.Cu")
		(net "UPI_CPU0_CPU1_P1P0_DP<14>")
	)
	(segment
		(start 113.02365 -188.610494)
		(end 112.751616 -188.952886)
		(width 0.14732)
		(layer "In4.Cu")
		(net "UPI_CPU0_CPU1_P1P0_DP<14>")
	)
	(segment
		(start 102.37978 -211.93379)
		(end 102.37978 -211.955888)
		(width 0.0889)
		(layer "In4.Cu")
		(net "UPI_CPU0_CPU1_P1P0_DP<14>")
	)
	(segment
		(start 321.995292 -151.628348)
		(end 279.2095 -160.592008)
		(width 0.14732)
		(layer "In4.Cu")
		(net "UPI_CPU0_CPU1_P1P0_DP<14>")
	)
	(segment
		(start 111.613188 -190.189612)
		(end 111.633 -190.361062)
		(width 0.14732)
		(layer "In4.Cu")
		(net "UPI_CPU0_CPU1_P1P0_DP<14>")
	)
	(segment
		(start 102.517956 -215.757252)
		(end 102.521258 -215.75903)
		(width 0.0889)
		(layer "In4.Cu")
		(net "UPI_CPU0_CPU1_P1P0_DP<14>")
	)
	(segment
		(start 102.524306 -216.740486)
		(end 102.521766 -216.74201)
		(width 0.0889)
		(layer "In4.Cu")
		(net "UPI_CPU0_CPU1_P1P0_DP<14>")
	)
	(segment
		(start 102.526338 -215.762078)
		(end 102.527608 -215.76284)
		(width 0.0889)
		(layer "In4.Cu")
		(net "UPI_CPU0_CPU1_P1P0_DP<14>")
	)
	(segment
		(start 361.304078 -188.37148)
		(end 360.43616 -186.251596)
		(width 0.14732)
		(layer "In4.Cu")
		(net "UPI_CPU0_CPU1_P1P0_DP<14>")
	)
	(segment
		(start 355.723444 -173.284388)
		(end 355.46284 -173.02353)
		(width 0.14732)
		(layer "In4.Cu")
		(net "UPI_CPU0_CPU1_P1P0_DP<14>")
	)
	(segment
		(start 347.61424 -171.412408)
		(end 329.72756 -154.788108)
		(width 0.14732)
		(layer "In4.Cu")
		(net "UPI_CPU0_CPU1_P1P0_DP<14>")
	)
	(segment
		(start 131.229608 -170.71848)
		(end 114.836956 -186.131962)
		(width 0.14732)
		(layer "In4.Cu")
		(net "UPI_CPU0_CPU1_P1P0_DP<14>")
	)
	(segment
		(start 353.042474 -171.049442)
		(end 352.096578 -171.009818)
		(width 0.14732)
		(layer "In4.Cu")
		(net "UPI_CPU0_CPU1_P1P0_DP<14>")
	)
	(segment
		(start 111.633 -190.361062)
		(end 111.360966 -190.703454)
		(width 0.14732)
		(layer "In4.Cu")
		(net "UPI_CPU0_CPU1_P1P0_DP<14>")
	)
	(segment
		(start 368.883438 -211.728558)
		(end 368.841528 -211.686648)
		(width 0.0889)
		(layer "In4.Cu")
		(net "UPI_CPU0_CPU1_P1P0_DP<14>")
	)
	(segment
		(start 102.527608 -215.76284)
		(end 102.53091 -215.764618)
		(width 0.0889)
		(layer "In4.Cu")
		(net "UPI_CPU0_CPU1_P1P0_DP<14>")
	)
	(segment
		(start 368.841528 -211.503514)
		(end 368.841274 -211.50326)
		(width 0.14732)
		(layer "In4.Cu")
		(net "UPI_CPU0_CPU1_P1P0_DP<14>")
	)
	(segment
		(start 356.300278 -174.16399)
		(end 356.37851 -173.97476)
		(width 0.14732)
		(layer "In4.Cu")
		(net "UPI_CPU0_CPU1_P1P0_DP<14>")
	)
	(segment
		(start 350.481392 -171.34205)
		(end 348.86646 -171.67352)
		(width 0.14732)
		(layer "In4.Cu")
		(net "UPI_CPU0_CPU1_P1P0_DP<14>")
	)
	(segment
		(start 102.807008 -214.424768)
		(end 102.807008 -214.644732)
		(width 0.0889)
		(layer "In4.Cu")
		(net "UPI_CPU0_CPU1_P1P0_DP<14>")
	)
	(segment
		(start 109.531658 -193.006218)
		(end 109.259624 -193.34861)
		(width 0.14732)
		(layer "In4.Cu")
		(net "UPI_CPU0_CPU1_P1P0_DP<14>")
	)
	(segment
		(start 355.928168 -173.284388)
		(end 355.723444 -173.284388)
		(width 0.14732)
		(layer "In4.Cu")
		(net "UPI_CPU0_CPU1_P1P0_DP<14>")
	)
	(segment
		(start 329.72756 -154.788108)
		(end 326.756522 -152.38857)
		(width 0.14732)
		(layer "In4.Cu")
		(net "UPI_CPU0_CPU1_P1P0_DP<14>")
	)
	(segment
		(start 369.165632 -214.946992)
		(end 369.174522 -214.941912)
		(width 0.0889)
		(layer "In4.Cu")
		(net "UPI_CPU0_CPU1_P1P0_DP<14>")
	)
	(segment
		(start 361.879388 -188.956188)
		(end 361.304078 -188.37148)
		(width 0.14732)
		(layer "In4.Cu")
		(net "UPI_CPU0_CPU1_P1P0_DP<14>")
	)
	(segment
		(start 368.841528 -211.66455)
		(end 368.841528 -211.503514)
		(width 0.14732)
		(layer "In4.Cu")
		(net "UPI_CPU0_CPU1_P1P0_DP<14>")
	)
	(segment
		(start 368.696494 -216.740486)
		(end 368.695478 -216.739978)
		(width 0.0889)
		(layer "In4.Cu")
		(net "UPI_CPU0_CPU1_P1P0_DP<14>")
	)
	(segment
		(start 238.316262 -150.665688)
		(end 233.891074 -150.665688)
		(width 0.14732)
		(layer "In4.Cu")
		(net "UPI_CPU0_CPU1_P1P0_DP<14>")
	)
	(segment
		(start 356.209092 -173.565312)
		(end 355.928168 -173.284388)
		(width 0.14732)
		(layer "In4.Cu")
		(net "UPI_CPU0_CPU1_P1P0_DP<14>")
	)
	(segment
		(start 111.189516 -190.723012)
		(end 110.91799 -191.064896)
		(width 0.14732)
		(layer "In4.Cu")
		(net "UPI_CPU0_CPU1_P1P0_DP<14>")
	)
	(segment
		(start 110.91799 -191.064896)
		(end 110.937548 -191.236346)
		(width 0.14732)
		(layer "In4.Cu")
		(net "UPI_CPU0_CPU1_P1P0_DP<14>")
	)
	(segment
		(start 360.43616 -183.770778)
		(end 356.630478 -174.582836)
		(width 0.14732)
		(layer "In4.Cu")
		(net "UPI_CPU0_CPU1_P1P0_DP<14>")
	)
	(segment
		(start 102.807516 -217.859864)
		(end 102.807516 -217.878406)
		(width 0.0889)
		(layer "In4.Cu")
		(net "UPI_CPU0_CPU1_P1P0_DP<14>")
	)
	(segment
		(start 355.46284 -173.02353)
		(end 355.46284 -172.818806)
		(width 0.14732)
		(layer "In4.Cu")
		(net "UPI_CPU0_CPU1_P1P0_DP<14>")
	)
	(segment
		(start 111.884714 -189.847728)
		(end 111.613188 -190.189612)
		(width 0.14732)
		(layer "In4.Cu")
		(net "UPI_CPU0_CPU1_P1P0_DP<14>")
	)
	(segment
		(start 196.402706 -160.330134)
		(end 194.41033 -160.581848)
		(width 0.14732)
		(layer "In4.Cu")
		(net "UPI_CPU0_CPU1_P1P0_DP<14>")
	)
	(segment
		(start 368.784378 -212.47862)
		(end 368.784378 -212.30336)
		(width 0.0889)
		(layer "In4.Cu")
		(net "UPI_CPU0_CPU1_P1P0_DP<14>")
	)
	(segment
		(start 102.579678 -218.33205)
		(end 102.555548 -218.421204)
		(width 0.0889)
		(layer "In4.Cu")
		(net "UPI_CPU0_CPU1_P1P0_DP<14>")
	)
	(segment
		(start 102.524306 -217.388186)
		(end 102.525068 -217.388694)
		(width 0.0889)
		(layer "In4.Cu")
		(net "UPI_CPU0_CPU1_P1P0_DP<14>")
	)
	(segment
		(start 109.511846 -192.834768)
		(end 109.531658 -193.006218)
		(width 0.14732)
		(layer "In4.Cu")
		(net "UPI_CPU0_CPU1_P1P0_DP<14>")
	)
	(segment
		(start 102.37978 -211.653882)
		(end 102.37978 -211.93379)
		(width 0.14732)
		(layer "In4.Cu")
		(net "UPI_CPU0_CPU1_P1P0_DP<14>")
	)
	(segment
		(start 102.807516 -216.25052)
		(end 102.807516 -216.260426)
		(width 0.0889)
		(layer "In4.Cu")
		(net "UPI_CPU0_CPU1_P1P0_DP<14>")
	)
	(segment
		(start 112.328198 -189.485778)
		(end 112.056164 -189.82817)
		(width 0.14732)
		(layer "In4.Cu")
		(net "UPI_CPU0_CPU1_P1P0_DP<14>")
	)
	(segment
		(start 164.610796 -150.147528)
		(end 131.229608 -170.71848)
		(width 0.14732)
		(layer "In4.Cu")
		(net "UPI_CPU0_CPU1_P1P0_DP<14>")
	)
	(segment
		(start 368.704368 -216.745058)
		(end 368.696494 -216.740486)
		(width 0.0889)
		(layer "In4.Cu")
		(net "UPI_CPU0_CPU1_P1P0_DP<14>")
	)
	(segment
		(start 109.798866 -192.47358)
		(end 109.511846 -192.834768)
		(width 0.14732)
		(layer "In4.Cu")
		(net "UPI_CPU0_CPU1_P1P0_DP<14>")
	)
	(segment
		(start 368.696494 -215.760554)
		(end 368.704368 -215.755982)
		(width 0.0889)
		(layer "In4.Cu")
		(net "UPI_CPU0_CPU1_P1P0_DP<14>")
	)
	(segment
		(start 352.096578 -171.009818)
		(end 350.481392 -171.341796)
		(width 0.14732)
		(layer "In4.Cu")
		(net "UPI_CPU0_CPU1_P1P0_DP<14>")
	)
	(segment
		(start 356.37851 -173.97476)
		(end 356.209092 -173.565312)
		(width 0.14732)
		(layer "In4.Cu")
		(net "UPI_CPU0_CPU1_P1P0_DP<14>")
	)
	(segment
		(start 360.43616 -186.251596)
		(end 360.43616 -183.770778)
		(width 0.14732)
		(layer "In4.Cu")
		(net "UPI_CPU0_CPU1_P1P0_DP<14>")
	)
	(segment
		(start 102.337616 -211.998052)
		(end 102.337616 -213.893908)
		(width 0.0889)
		(layer "In4.Cu")
		(net "UPI_CPU0_CPU1_P1P0_DP<14>")
	)
	(segment
		(start 326.756522 -152.38857)
		(end 323.72935 -151.628348)
		(width 0.14732)
		(layer "In4.Cu")
		(net "UPI_CPU0_CPU1_P1P0_DP<14>")
	)
	(arc
		(start 368.88293 -215.436704)
		(mid 368.955103 -215.160036)
		(end 369.15344 -214.954104)
		(width 0.0889)
		(layer "In4.Cu")
		(net "UPI_CPU0_CPU1_P1P0_DP<14>")
	)
	(arc
		(start 102.53091 -215.764618)
		(mid 102.733497 -215.970969)
		(end 102.807516 -216.25052)
		(width 0.0889)
		(layer "In4.Cu")
		(net "UPI_CPU0_CPU1_P1P0_DP<14>")
	)
	(arc
		(start 368.88293 -217.064336)
		(mid 368.835251 -216.881436)
		(end 368.704368 -216.745058)
		(width 0.0889)
		(layer "In4.Cu")
		(net "UPI_CPU0_CPU1_P1P0_DP<14>")
	)
	(arc
		(start 369.353084 -214.461852)
		(mid 369.278013 -214.34611)
		(end 369.16868 -214.261954)
		(width 0.0889)
		(layer "In4.Cu")
		(net "UPI_CPU0_CPU1_P1P0_DP<14>")
	)
	(arc
		(start 102.521766 -214.093298)
		(mid 102.695729 -214.232062)
		(end 102.807008 -214.424768)
		(width 0.0889)
		(layer "In4.Cu")
		(net "UPI_CPU0_CPU1_P1P0_DP<14>")
	)
	(arc
		(start 102.515924 -215.117426)
		(mid 102.38867 -215.247392)
		(end 102.337616 -215.421972)
		(width 0.0889)
		(layer "In4.Cu")
		(net "UPI_CPU0_CPU1_P1P0_DP<14>")
	)
	(arc
		(start 102.525068 -217.388694)
		(mid 102.727354 -217.587675)
		(end 102.807516 -217.859864)
		(width 0.0889)
		(layer "In4.Cu")
		(net "UPI_CPU0_CPU1_P1P0_DP<14>")
	)
	(arc
		(start 102.337616 -215.421972)
		(mid 102.337419 -215.429337)
		(end 102.337362 -215.436704)
		(width 0.0889)
		(layer "In4.Cu")
		(net "UPI_CPU0_CPU1_P1P0_DP<14>")
	)
	(arc
		(start 102.807516 -216.260426)
		(mid 102.729405 -216.537375)
		(end 102.525068 -216.739978)
		(width 0.0889)
		(layer "In4.Cu")
		(net "UPI_CPU0_CPU1_P1P0_DP<14>")
	)
	(arc
		(start 369.174522 -214.941912)
		(mid 369.305436 -214.805552)
		(end 369.353084 -214.622634)
		(width 0.0889)
		(layer "In4.Cu")
		(net "UPI_CPU0_CPU1_P1P0_DP<14>")
	)
	(arc
		(start 102.337616 -213.893908)
		(mid 102.412621 -214.009367)
		(end 102.521766 -214.093298)
		(width 0.0889)
		(layer "In4.Cu")
		(net "UPI_CPU0_CPU1_P1P0_DP<14>")
	)
	(arc
		(start 102.596696 -218.318842)
		(mid 102.58825 -218.325527)
		(end 102.579678 -218.33205)
		(width 0.0889)
		(layer "In4.Cu")
		(net "UPI_CPU0_CPU1_P1P0_DP<14>")
	)
	(arc
		(start 368.704368 -215.755982)
		(mid 368.835282 -215.619622)
		(end 368.88293 -215.436704)
		(width 0.0889)
		(layer "In4.Cu")
		(net "UPI_CPU0_CPU1_P1P0_DP<14>")
	)
	(arc
		(start 368.413284 -216.235026)
		(mid 368.492654 -215.961292)
		(end 368.695478 -215.761062)
		(width 0.0889)
		(layer "In4.Cu")
		(net "UPI_CPU0_CPU1_P1P0_DP<14>")
	)
	(arc
		(start 102.337362 -215.436704)
		(mid 102.385041 -215.619604)
		(end 102.515924 -215.755982)
		(width 0.0889)
		(layer "In4.Cu")
		(net "UPI_CPU0_CPU1_P1P0_DP<14>")
	)
	(arc
		(start 369.16868 -214.261954)
		(mid 369.008325 -214.138568)
		(end 368.89817 -213.968838)
		(width 0.0889)
		(layer "In4.Cu")
		(net "UPI_CPU0_CPU1_P1P0_DP<14>")
	)
	(arc
		(start 102.807516 -217.878406)
		(mid 102.752161 -218.122593)
		(end 102.596696 -218.318842)
		(width 0.0889)
		(layer "In4.Cu")
		(net "UPI_CPU0_CPU1_P1P0_DP<14>")
	)
	(arc
		(start 102.807008 -214.644732)
		(mid 102.726097 -214.91486)
		(end 102.524814 -215.112346)
		(width 0.0889)
		(layer "In4.Cu")
		(net "UPI_CPU0_CPU1_P1P0_DP<14>")
	)
	(arc
		(start 368.742976 -217.356182)
		(mid 368.846121 -217.226157)
		(end 368.88293 -217.064336)
		(width 0.0889)
		(layer "In4.Cu")
		(net "UPI_CPU0_CPU1_P1P0_DP<14>")
	)
	(arc
		(start 368.89817 -213.968838)
		(mid 368.890348 -213.949662)
		(end 368.883184 -213.93023)
		(width 0.0889)
		(layer "In4.Cu")
		(net "UPI_CPU0_CPU1_P1P0_DP<14>")
	)
	(arc
		(start 368.695478 -216.739978)
		(mid 368.492655 -216.539747)
		(end 368.413284 -216.266014)
		(width 0.0889)
		(layer "In4.Cu")
		(net "UPI_CPU0_CPU1_P1P0_DP<14>")
	)
	(arc
		(start 102.516178 -216.745058)
		(mid 102.337581 -217.064336)
		(end 102.516178 -217.383614)
		(width 0.0889)
		(layer "In4.Cu")
		(net "UPI_CPU0_CPU1_P1P0_DP<14>")
	)
	(segment
		(start 101.302312 -217.87866)
		(end 101.302566 -217.878406)
		(width 0.13208)
		(layer "F.Cu")
		(net "UPI_CPU0_CPU1_P1P0_DP<13>")
	)
	(segment
		(start 369.91798 -217.87866)
		(end 369.918234 -217.878406)
		(width 0.13208)
		(layer "F.Cu")
		(net "UPI_CPU0_CPU1_P1P0_DP<13>")
	)
	(segment
		(start 369.91798 -218.414346)
		(end 369.91798 -217.87866)
		(width 0.13208)
		(layer "F.Cu")
		(net "UPI_CPU0_CPU1_P1P0_DP<13>")
	)
	(segment
		(start 101.302312 -218.414346)
		(end 101.302312 -217.87866)
		(width 0.13208)
		(layer "F.Cu")
		(net "UPI_CPU0_CPU1_P1P0_DP<13>")
	)
	(segment
		(start 164.16782 -149.109938)
		(end 130.565144 -169.817542)
		(width 0.14732)
		(layer "In4.Cu")
		(net "UPI_CPU0_CPU1_P1P0_DP<13>")
	)
	(segment
		(start 361.54868 -183.540654)
		(end 357.156258 -172.936154)
		(width 0.14732)
		(layer "In4.Cu")
		(net "UPI_CPU0_CPU1_P1P0_DP<13>")
	)
	(segment
		(start 327.282048 -151.324818)
		(end 323.822568 -150.457408)
		(width 0.14732)
		(layer "In4.Cu")
		(net "UPI_CPU0_CPU1_P1P0_DP<13>")
	)
	(segment
		(start 370.013484 -212.75294)
		(end 370.013484 -212.5726)
		(width 0.0889)
		(layer "In4.Cu")
		(net "UPI_CPU0_CPU1_P1P0_DP<13>")
	)
	(segment
		(start 361.54868 -186.02071)
		(end 361.54868 -183.540654)
		(width 0.14732)
		(layer "In4.Cu")
		(net "UPI_CPU0_CPU1_P1P0_DP<13>")
	)
	(segment
		(start 362.831126 -188.343286)
		(end 362.260388 -187.761626)
		(width 0.14732)
		(layer "In4.Cu")
		(net "UPI_CPU0_CPU1_P1P0_DP<13>")
	)
	(segment
		(start 370.112544 -212.852)
		(end 370.013484 -212.75294)
		(width 0.0889)
		(layer "In4.Cu")
		(net "UPI_CPU0_CPU1_P1P0_DP<13>")
	)
	(segment
		(start 101.207062 -217.064336)
		(end 101.207062 -217.07856)
		(width 0.0889)
		(layer "In4.Cu")
		(net "UPI_CPU0_CPU1_P1P0_DP<13>")
	)
	(segment
		(start 101.45903 -217.607388)
		(end 101.302566 -217.878406)
		(width 0.0889)
		(layer "In4.Cu")
		(net "UPI_CPU0_CPU1_P1P0_DP<13>")
	)
	(segment
		(start 106.624374 -196.073014)
		(end 101.165152 -211.060792)
		(width 0.14732)
		(layer "In4.Cu")
		(net "UPI_CPU0_CPU1_P1P0_DP<13>")
	)
	(segment
		(start 195.657978 -159.312864)
		(end 194.33921 -159.479488)
		(width 0.14732)
		(layer "In4.Cu")
		(net "UPI_CPU0_CPU1_P1P0_DP<13>")
	)
	(segment
		(start 370.112544 -212.29828)
		(end 370.013484 -212.19922)
		(width 0.0889)
		(layer "In4.Cu")
		(net "UPI_CPU0_CPU1_P1P0_DP<13>")
	)
	(segment
		(start 101.483414 -216.578688)
		(end 101.483668 -216.578434)
		(width 0.0889)
		(layer "In4.Cu")
		(net "UPI_CPU0_CPU1_P1P0_DP<13>")
	)
	(segment
		(start 370.013484 -213.12632)
		(end 370.112544 -213.02726)
		(width 0.0889)
		(layer "In4.Cu")
		(net "UPI_CPU0_CPU1_P1P0_DP<13>")
	)
	(segment
		(start 170.880278 -148.316188)
		(end 166.752778 -148.207222)
		(width 0.14732)
		(layer "In4.Cu")
		(net "UPI_CPU0_CPU1_P1P0_DP<13>")
	)
	(segment
		(start 101.165406 -211.950808)
		(end 101.207316 -211.992718)
		(width 0.0889)
		(layer "In4.Cu")
		(net "UPI_CPU0_CPU1_P1P0_DP<13>")
	)
	(segment
		(start 348.373192 -169.385742)
		(end 346.167202 -168.559226)
		(width 0.14732)
		(layer "In4.Cu")
		(net "UPI_CPU0_CPU1_P1P0_DP<13>")
	)
	(segment
		(start 362.260388 -187.761626)
		(end 361.54868 -186.02071)
		(width 0.14732)
		(layer "In4.Cu")
		(net "UPI_CPU0_CPU1_P1P0_DP<13>")
	)
	(segment
		(start 370.013484 -213.8934)
		(end 370.013484 -213.12632)
		(width 0.0889)
		(layer "In4.Cu")
		(net "UPI_CPU0_CPU1_P1P0_DP<13>")
	)
	(segment
		(start 370.013484 -211.774532)
		(end 370.055648 -211.732368)
		(width 0.0889)
		(layer "In4.Cu")
		(net "UPI_CPU0_CPU1_P1P0_DP<13>")
	)
	(segment
		(start 101.165406 -211.653882)
		(end 101.165406 -211.92871)
		(width 0.14732)
		(layer "In4.Cu")
		(net "UPI_CPU0_CPU1_P1P0_DP<13>")
	)
	(segment
		(start 352.045778 -169.130218)
		(end 350.88322 -168.966388)
		(width 0.14732)
		(layer "In4.Cu")
		(net "UPI_CPU0_CPU1_P1P0_DP<13>")
	)
	(segment
		(start 370.055648 -211.732368)
		(end 370.055648 -211.71027)
		(width 0.0889)
		(layer "In4.Cu")
		(net "UPI_CPU0_CPU1_P1P0_DP<13>")
	)
	(segment
		(start 346.167202 -168.559226)
		(end 330.553568 -154.022806)
		(width 0.14732)
		(layer "In4.Cu")
		(net "UPI_CPU0_CPU1_P1P0_DP<13>")
	)
	(segment
		(start 257.679444 -154.50058)
		(end 257.679444 -154.500834)
		(width 0.14732)
		(layer "In4.Cu")
		(net "UPI_CPU0_CPU1_P1P0_DP<13>")
	)
	(segment
		(start 130.565144 -169.817542)
		(end 113.375948 -185.9788)
		(width 0.14732)
		(layer "In4.Cu")
		(net "UPI_CPU0_CPU1_P1P0_DP<13>")
	)
	(segment
		(start 101.4349 -217.518234)
		(end 101.45903 -217.607388)
		(width 0.0889)
		(layer "In4.Cu")
		(net "UPI_CPU0_CPU1_P1P0_DP<13>")
	)
	(segment
		(start 370.013484 -217.082878)
		(end 370.013484 -217.05443)
		(width 0.0889)
		(layer "In4.Cu")
		(net "UPI_CPU0_CPU1_P1P0_DP<13>")
	)
	(segment
		(start 370.013484 -215.436704)
		(end 370.013484 -215.428068)
		(width 0.0889)
		(layer "In4.Cu")
		(net "UPI_CPU0_CPU1_P1P0_DP<13>")
	)
	(segment
		(start 101.165152 -211.653628)
		(end 101.165406 -211.653882)
		(width 0.14732)
		(layer "In4.Cu")
		(net "UPI_CPU0_CPU1_P1P0_DP<13>")
	)
	(segment
		(start 370.055648 -211.71027)
		(end 370.055648 -211.298282)
		(width 0.14732)
		(layer "In4.Cu")
		(net "UPI_CPU0_CPU1_P1P0_DP<13>")
	)
	(segment
		(start 101.489002 -215.925654)
		(end 101.490526 -215.92667)
		(width 0.0889)
		(layer "In4.Cu")
		(net "UPI_CPU0_CPU1_P1P0_DP<13>")
	)
	(segment
		(start 101.165406 -211.92871)
		(end 101.165406 -211.950808)
		(width 0.0889)
		(layer "In4.Cu")
		(net "UPI_CPU0_CPU1_P1P0_DP<13>")
	)
	(segment
		(start 101.490526 -215.92667)
		(end 101.498654 -215.931496)
		(width 0.0889)
		(layer "In4.Cu")
		(net "UPI_CPU0_CPU1_P1P0_DP<13>")
	)
	(segment
		(start 257.679444 -154.500834)
		(end 238.189516 -149.494748)
		(width 0.14732)
		(layer "In4.Cu")
		(net "UPI_CPU0_CPU1_P1P0_DP<13>")
	)
	(segment
		(start 321.87388 -150.457408)
		(end 278.760682 -159.489648)
		(width 0.14732)
		(layer "In4.Cu")
		(net "UPI_CPU0_CPU1_P1P0_DP<13>")
	)
	(segment
		(start 370.013484 -212.5726)
		(end 370.112544 -212.47354)
		(width 0.0889)
		(layer "In4.Cu")
		(net "UPI_CPU0_CPU1_P1P0_DP<13>")
	)
	(segment
		(start 101.48697 -215.924384)
		(end 101.489002 -215.925654)
		(width 0.0889)
		(layer "In4.Cu")
		(net "UPI_CPU0_CPU1_P1P0_DP<13>")
	)
	(segment
		(start 370.483384 -214.636858)
		(end 370.483384 -214.425022)
		(width 0.0889)
		(layer "In4.Cu")
		(net "UPI_CPU0_CPU1_P1P0_DP<13>")
	)
	(segment
		(start 101.498654 -215.931496)
		(end 101.498654 -215.931242)
		(width 0.0889)
		(layer "In4.Cu")
		(net "UPI_CPU0_CPU1_P1P0_DP<13>")
	)
	(segment
		(start 323.822568 -150.457408)
		(end 321.87388 -150.457408)
		(width 0.14732)
		(layer "In4.Cu")
		(net "UPI_CPU0_CPU1_P1P0_DP<13>")
	)
	(segment
		(start 370.055394 -211.298028)
		(end 370.055394 -205.784704)
		(width 0.14732)
		(layer "In4.Cu")
		(net "UPI_CPU0_CPU1_P1P0_DP<13>")
	)
	(segment
		(start 370.01323 -215.455246)
		(end 370.013484 -215.436704)
		(width 0.0889)
		(layer "In4.Cu")
		(net "UPI_CPU0_CPU1_P1P0_DP<13>")
	)
	(segment
		(start 101.676708 -214.461344)
		(end 101.676708 -214.622634)
		(width 0.0889)
		(layer "In4.Cu")
		(net "UPI_CPU0_CPU1_P1P0_DP<13>")
	)
	(segment
		(start 369.722146 -215.931242)
		(end 369.731036 -215.926162)
		(width 0.0889)
		(layer "In4.Cu")
		(net "UPI_CPU0_CPU1_P1P0_DP<13>")
	)
	(segment
		(start 166.752778 -148.207222)
		(end 164.16782 -149.109938)
		(width 0.14732)
		(layer "In4.Cu")
		(net "UPI_CPU0_CPU1_P1P0_DP<13>")
	)
	(segment
		(start 107.698032 -193.125852)
		(end 106.624628 -196.072252)
		(width 0.14732)
		(layer "In4.Cu")
		(net "UPI_CPU0_CPU1_P1P0_DP<13>")
	)
	(segment
		(start 233.740706 -149.494748)
		(end 195.657978 -159.312864)
		(width 0.14732)
		(layer "In4.Cu")
		(net "UPI_CPU0_CPU1_P1P0_DP<13>")
	)
	(segment
		(start 369.76177 -218.149424)
		(end 369.683538 -218.170252)
		(width 0.0889)
		(layer "In4.Cu")
		(net "UPI_CPU0_CPU1_P1P0_DP<13>")
	)
	(segment
		(start 370.055648 -211.298282)
		(end 370.055394 -211.298028)
		(width 0.14732)
		(layer "In4.Cu")
		(net "UPI_CPU0_CPU1_P1P0_DP<13>")
	)
	(segment
		(start 101.207062 -215.414606)
		(end 101.207062 -215.436704)
		(width 0.0889)
		(layer "In4.Cu")
		(net "UPI_CPU0_CPU1_P1P0_DP<13>")
	)
	(segment
		(start 113.375948 -185.9788)
		(end 107.698032 -193.125852)
		(width 0.14732)
		(layer "In4.Cu")
		(net "UPI_CPU0_CPU1_P1P0_DP<13>")
	)
	(segment
		(start 101.498654 -216.569798)
		(end 101.483414 -216.578688)
		(width 0.0889)
		(layer "In4.Cu")
		(net "UPI_CPU0_CPU1_P1P0_DP<13>")
	)
	(segment
		(start 101.498146 -214.941912)
		(end 101.489256 -214.946992)
		(width 0.0889)
		(layer "In4.Cu")
		(net "UPI_CPU0_CPU1_P1P0_DP<13>")
	)
	(segment
		(start 106.624628 -196.072252)
		(end 106.624374 -196.073014)
		(width 0.14732)
		(layer "In4.Cu")
		(net "UPI_CPU0_CPU1_P1P0_DP<13>")
	)
	(segment
		(start 192.428876 -159.479488)
		(end 174.875444 -150.294594)
		(width 0.14732)
		(layer "In4.Cu")
		(net "UPI_CPU0_CPU1_P1P0_DP<13>")
	)
	(segment
		(start 101.483668 -215.922606)
		(end 101.48697 -215.924384)
		(width 0.0889)
		(layer "In4.Cu")
		(net "UPI_CPU0_CPU1_P1P0_DP<13>")
	)
	(segment
		(start 101.165152 -211.060792)
		(end 101.165152 -211.653628)
		(width 0.14732)
		(layer "In4.Cu")
		(net "UPI_CPU0_CPU1_P1P0_DP<13>")
	)
	(segment
		(start 357.156258 -172.936154)
		(end 355.27742 -171.057316)
		(width 0.14732)
		(layer "In4.Cu")
		(net "UPI_CPU0_CPU1_P1P0_DP<13>")
	)
	(segment
		(start 369.731036 -216.574878)
		(end 369.722146 -216.569798)
		(width 0.0889)
		(layer "In4.Cu")
		(net "UPI_CPU0_CPU1_P1P0_DP<13>")
	)
	(segment
		(start 278.760682 -159.489648)
		(end 277.10257 -159.489648)
		(width 0.14732)
		(layer "In4.Cu")
		(net "UPI_CPU0_CPU1_P1P0_DP<13>")
	)
	(segment
		(start 370.112544 -212.47354)
		(end 370.112544 -212.29828)
		(width 0.0889)
		(layer "In4.Cu")
		(net "UPI_CPU0_CPU1_P1P0_DP<13>")
	)
	(segment
		(start 370.055394 -205.784704)
		(end 362.831126 -188.343286)
		(width 0.14732)
		(layer "In4.Cu")
		(net "UPI_CPU0_CPU1_P1P0_DP<13>")
	)
	(segment
		(start 355.27742 -171.057316)
		(end 352.045778 -169.130218)
		(width 0.14732)
		(layer "In4.Cu")
		(net "UPI_CPU0_CPU1_P1P0_DP<13>")
	)
	(segment
		(start 194.33921 -159.479488)
		(end 192.428876 -159.479488)
		(width 0.14732)
		(layer "In4.Cu")
		(net "UPI_CPU0_CPU1_P1P0_DP<13>")
	)
	(segment
		(start 174.875444 -150.294594)
		(end 170.880278 -148.316188)
		(width 0.14732)
		(layer "In4.Cu")
		(net "UPI_CPU0_CPU1_P1P0_DP<13>")
	)
	(segment
		(start 330.553568 -154.022806)
		(end 327.282048 -151.324818)
		(width 0.14732)
		(layer "In4.Cu")
		(net "UPI_CPU0_CPU1_P1P0_DP<13>")
	)
	(segment
		(start 370.112544 -213.02726)
		(end 370.112544 -212.852)
		(width 0.0889)
		(layer "In4.Cu")
		(net "UPI_CPU0_CPU1_P1P0_DP<13>")
	)
	(segment
		(start 277.10257 -159.489648)
		(end 257.679444 -154.50058)
		(width 0.14732)
		(layer "In4.Cu")
		(net "UPI_CPU0_CPU1_P1P0_DP<13>")
	)
	(segment
		(start 370.013484 -212.19922)
		(end 370.013484 -211.774532)
		(width 0.0889)
		(layer "In4.Cu")
		(net "UPI_CPU0_CPU1_P1P0_DP<13>")
	)
	(segment
		(start 369.918234 -217.878406)
		(end 369.76177 -218.149424)
		(width 0.0889)
		(layer "In4.Cu")
		(net "UPI_CPU0_CPU1_P1P0_DP<13>")
	)
	(segment
		(start 349.10268 -169.327068)
		(end 348.373192 -169.385742)
		(width 0.14732)
		(layer "In4.Cu")
		(net "UPI_CPU0_CPU1_P1P0_DP<13>")
	)
	(segment
		(start 350.88322 -168.966388)
		(end 349.10268 -169.327068)
		(width 0.14732)
		(layer "In4.Cu")
		(net "UPI_CPU0_CPU1_P1P0_DP<13>")
	)
	(segment
		(start 238.189516 -149.494748)
		(end 233.740706 -149.494748)
		(width 0.14732)
		(layer "In4.Cu")
		(net "UPI_CPU0_CPU1_P1P0_DP<13>")
	)
	(segment
		(start 369.722146 -217.559128)
		(end 369.731036 -217.554048)
		(width 0.0889)
		(layer "In4.Cu")
		(net "UPI_CPU0_CPU1_P1P0_DP<13>")
	)
	(segment
		(start 101.207316 -211.992718)
		(end 101.207316 -213.930484)
		(width 0.0889)
		(layer "In4.Cu")
		(net "UPI_CPU0_CPU1_P1P0_DP<13>")
	)
	(arc
		(start 101.483668 -216.578434)
		(mid 101.281081 -216.784785)
		(end 101.207062 -217.064336)
		(width 0.0889)
		(layer "In4.Cu")
		(net "UPI_CPU0_CPU1_P1P0_DP<13>")
	)
	(arc
		(start 101.207062 -217.07856)
		(mid 101.265356 -217.315203)
		(end 101.417882 -217.50528)
		(width 0.0889)
		(layer "In4.Cu")
		(net "UPI_CPU0_CPU1_P1P0_DP<13>")
	)
	(arc
		(start 370.013484 -217.05443)
		(mid 369.935373 -216.777481)
		(end 369.731036 -216.574878)
		(width 0.0889)
		(layer "In4.Cu")
		(net "UPI_CPU0_CPU1_P1P0_DP<13>")
	)
	(arc
		(start 370.483384 -214.425022)
		(mid 370.372046 -214.232122)
		(end 370.197888 -214.093298)
		(width 0.0889)
		(layer "In4.Cu")
		(net "UPI_CPU0_CPU1_P1P0_DP<13>")
	)
	(arc
		(start 101.676708 -214.622634)
		(mid 101.629029 -214.805534)
		(end 101.498146 -214.941912)
		(width 0.0889)
		(layer "In4.Cu")
		(net "UPI_CPU0_CPU1_P1P0_DP<13>")
	)
	(arc
		(start 101.207062 -215.436704)
		(mid 101.281053 -215.71627)
		(end 101.483668 -215.922606)
		(width 0.0889)
		(layer "In4.Cu")
		(net "UPI_CPU0_CPU1_P1P0_DP<13>")
	)
	(arc
		(start 369.543584 -217.878406)
		(mid 369.591263 -217.695506)
		(end 369.722146 -217.559128)
		(width 0.0889)
		(layer "In4.Cu")
		(net "UPI_CPU0_CPU1_P1P0_DP<13>")
	)
	(arc
		(start 101.492558 -214.261954)
		(mid 101.601705 -214.345882)
		(end 101.676708 -214.461344)
		(width 0.0889)
		(layer "In4.Cu")
		(net "UPI_CPU0_CPU1_P1P0_DP<13>")
	)
	(arc
		(start 101.207316 -213.930484)
		(mid 101.214601 -213.950046)
		(end 101.222556 -213.969346)
		(width 0.0889)
		(layer "In4.Cu")
		(net "UPI_CPU0_CPU1_P1P0_DP<13>")
	)
	(arc
		(start 101.222556 -213.969346)
		(mid 101.33255 -214.138715)
		(end 101.492558 -214.261954)
		(width 0.0889)
		(layer "In4.Cu")
		(net "UPI_CPU0_CPU1_P1P0_DP<13>")
	)
	(arc
		(start 370.013484 -215.428068)
		(mid 370.065754 -215.245703)
		(end 370.200682 -215.112346)
		(width 0.0889)
		(layer "In4.Cu")
		(net "UPI_CPU0_CPU1_P1P0_DP<13>")
	)
	(arc
		(start 369.722146 -216.569798)
		(mid 369.592857 -216.436312)
		(end 369.543584 -216.257124)
		(width 0.0889)
		(layer "In4.Cu")
		(net "UPI_CPU0_CPU1_P1P0_DP<13>")
	)
	(arc
		(start 101.498654 -215.931242)
		(mid 101.677251 -216.25052)
		(end 101.498654 -216.569798)
		(width 0.0889)
		(layer "In4.Cu")
		(net "UPI_CPU0_CPU1_P1P0_DP<13>")
	)
	(arc
		(start 370.197888 -214.093298)
		(mid 370.088492 -214.009201)
		(end 370.013484 -213.8934)
		(width 0.0889)
		(layer "In4.Cu")
		(net "UPI_CPU0_CPU1_P1P0_DP<13>")
	)
	(arc
		(start 101.489256 -214.946992)
		(mid 101.287974 -215.144479)
		(end 101.207062 -215.414606)
		(width 0.0889)
		(layer "In4.Cu")
		(net "UPI_CPU0_CPU1_P1P0_DP<13>")
	)
	(arc
		(start 369.683538 -218.170252)
		(mid 369.580393 -218.040227)
		(end 369.543584 -217.878406)
		(width 0.0889)
		(layer "In4.Cu")
		(net "UPI_CPU0_CPU1_P1P0_DP<13>")
	)
	(arc
		(start 101.417882 -217.50528)
		(mid 101.42633 -217.511837)
		(end 101.4349 -217.518234)
		(width 0.0889)
		(layer "In4.Cu")
		(net "UPI_CPU0_CPU1_P1P0_DP<13>")
	)
	(arc
		(start 369.543838 -216.238328)
		(mid 369.594331 -216.06235)
		(end 369.722146 -215.931242)
		(width 0.0889)
		(layer "In4.Cu")
		(net "UPI_CPU0_CPU1_P1P0_DP<13>")
	)
	(arc
		(start 369.543584 -216.257124)
		(mid 369.543594 -216.247724)
		(end 369.543838 -216.238328)
		(width 0.0889)
		(layer "In4.Cu")
		(net "UPI_CPU0_CPU1_P1P0_DP<13>")
	)
	(arc
		(start 369.731036 -217.554048)
		(mid 369.933322 -217.355067)
		(end 370.013484 -217.082878)
		(width 0.0889)
		(layer "In4.Cu")
		(net "UPI_CPU0_CPU1_P1P0_DP<13>")
	)
	(arc
		(start 369.731036 -215.926162)
		(mid 369.933078 -215.727239)
		(end 370.01323 -215.455246)
		(width 0.0889)
		(layer "In4.Cu")
		(net "UPI_CPU0_CPU1_P1P0_DP<13>")
	)
	(arc
		(start 370.200682 -215.112346)
		(mid 370.404163 -214.911542)
		(end 370.483384 -214.636858)
		(width 0.0889)
		(layer "In4.Cu")
		(net "UPI_CPU0_CPU1_P1P0_DP<13>")
	)
	(segment
		(start 100.832666 -219.228162)
		(end 100.832666 -218.692476)
		(width 0.13208)
		(layer "F.Cu")
		(net "UPI_CPU0_CPU1_P1P0_DP<12>")
	)
	(segment
		(start 370.388134 -217.600276)
		(end 370.388134 -217.06459)
		(width 0.13208)
		(layer "F.Cu")
		(net "UPI_CPU0_CPU1_P1P0_DP<12>")
	)
	(segment
		(start 100.832666 -218.692476)
		(end 100.832412 -218.692222)
		(width 0.13208)
		(layer "F.Cu")
		(net "UPI_CPU0_CPU1_P1P0_DP<12>")
	)
	(segment
		(start 370.388134 -217.06459)
		(end 370.38788 -217.064336)
		(width 0.13208)
		(layer "F.Cu")
		(net "UPI_CPU0_CPU1_P1P0_DP<12>")
	)
	(segment
		(start 107.980734 -191.834262)
		(end 107.77728 -191.857122)
		(width 0.14732)
		(layer "In4.Cu")
		(net "UPI_CPU0_CPU1_P1P0_DP<12>")
	)
	(segment
		(start 109.490256 -189.9412)
		(end 109.260386 -190.229236)
		(width 0.14732)
		(layer "In4.Cu")
		(net "UPI_CPU0_CPU1_P1P0_DP<12>")
	)
	(segment
		(start 100.641658 -215.75903)
		(end 100.64369 -215.7603)
		(width 0.0889)
		(layer "In4.Cu")
		(net "UPI_CPU0_CPU1_P1P0_DP<12>")
	)
	(segment
		(start 109.696504 -189.449964)
		(end 109.467142 -189.737746)
		(width 0.14732)
		(layer "In4.Cu")
		(net "UPI_CPU0_CPU1_P1P0_DP<12>")
	)
	(segment
		(start 108.85043 -190.743586)
		(end 108.62056 -191.031622)
		(width 0.14732)
		(layer "In4.Cu")
		(net "UPI_CPU0_CPU1_P1P0_DP<12>")
	)
	(segment
		(start 100.645214 -215.112346)
		(end 100.64496 -215.1126)
		(width 0.0889)
		(layer "In4.Cu")
		(net "UPI_CPU0_CPU1_P1P0_DP<12>")
	)
	(segment
		(start 111.40948 -187.534042)
		(end 111.17961 -187.822078)
		(width 0.14732)
		(layer "In4.Cu")
		(net "UPI_CPU0_CPU1_P1P0_DP<12>")
	)
	(segment
		(start 370.292884 -216.266014)
		(end 370.292884 -216.235026)
		(width 0.0889)
		(layer "In4.Cu")
		(net "UPI_CPU0_CPU1_P1P0_DP<12>")
	)
	(segment
		(start 370.720874 -205.924912)
		(end 363.297216 -188.002418)
		(width 0.14732)
		(layer "In4.Cu")
		(net "UPI_CPU0_CPU1_P1P0_DP<12>")
	)
	(segment
		(start 100.499926 -210.988402)
		(end 100.499926 -211.480908)
		(width 0.14732)
		(layer "In4.Cu")
		(net "UPI_CPU0_CPU1_P1P0_DP<12>")
	)
	(segment
		(start 100.644706 -216.740486)
		(end 100.642166 -216.74201)
		(width 0.0889)
		(layer "In4.Cu")
		(net "UPI_CPU0_CPU1_P1P0_DP<12>")
	)
	(segment
		(start 170.28414 -146.403314)
		(end 163.760404 -148.6535)
		(width 0.14732)
		(layer "In4.Cu")
		(net "UPI_CPU0_CPU1_P1P0_DP<12>")
	)
	(segment
		(start 110.33633 -188.647578)
		(end 110.106968 -188.93536)
		(width 0.14732)
		(layer "In4.Cu")
		(net "UPI_CPU0_CPU1_P1P0_DP<12>")
	)
	(segment
		(start 110.106968 -188.93536)
		(end 110.129828 -189.138814)
		(width 0.14732)
		(layer "In4.Cu")
		(net "UPI_CPU0_CPU1_P1P0_DP<12>")
	)
	(segment
		(start 370.576094 -215.760554)
		(end 370.583968 -215.755982)
		(width 0.0889)
		(layer "In4.Cu")
		(net "UPI_CPU0_CPU1_P1P0_DP<12>")
	)
	(segment
		(start 370.762784 -213.176866)
		(end 370.663978 -213.07806)
		(width 0.0889)
		(layer "In4.Cu")
		(net "UPI_CPU0_CPU1_P1P0_DP<12>")
	)
	(segment
		(start 100.50018 -211.991448)
		(end 100.458016 -212.033612)
		(width 0.0889)
		(layer "In4.Cu")
		(net "UPI_CPU0_CPU1_P1P0_DP<12>")
	)
	(segment
		(start 100.499926 -211.480908)
		(end 100.50018 -211.481162)
		(width 0.14732)
		(layer "In4.Cu")
		(net "UPI_CPU0_CPU1_P1P0_DP<12>")
	)
	(segment
		(start 370.663978 -212.41766)
		(end 370.663978 -212.2424)
		(width 0.0889)
		(layer "In4.Cu")
		(net "UPI_CPU0_CPU1_P1P0_DP<12>")
	)
	(segment
		(start 108.18749 -191.342518)
		(end 108.210604 -191.545972)
		(width 0.14732)
		(layer "In4.Cu")
		(net "UPI_CPU0_CPU1_P1P0_DP<12>")
	)
	(segment
		(start 370.763038 -212.14334)
		(end 370.763038 -211.705698)
		(width 0.0889)
		(layer "In4.Cu")
		(net "UPI_CPU0_CPU1_P1P0_DP<12>")
	)
	(segment
		(start 370.663978 -213.07806)
		(end 370.663978 -212.9028)
		(width 0.0889)
		(layer "In4.Cu")
		(net "UPI_CPU0_CPU1_P1P0_DP<12>")
	)
	(segment
		(start 110.976156 -187.845192)
		(end 110.746794 -188.132974)
		(width 0.14732)
		(layer "In4.Cu")
		(net "UPI_CPU0_CPU1_P1P0_DP<12>")
	)
	(segment
		(start 100.927916 -217.859864)
		(end 100.927916 -217.878406)
		(width 0.0889)
		(layer "In4.Cu")
		(net "UPI_CPU0_CPU1_P1P0_DP<12>")
	)
	(segment
		(start 370.583968 -216.745058)
		(end 370.576094 -216.740486)
		(width 0.0889)
		(layer "In4.Cu")
		(net "UPI_CPU0_CPU1_P1P0_DP<12>")
	)
	(segment
		(start 314.89396 -148.339048)
		(end 314.893706 -148.338794)
		(width 0.14732)
		(layer "In4.Cu")
		(net "UPI_CPU0_CPU1_P1P0_DP<12>")
	)
	(segment
		(start 370.721128 -211.412074)
		(end 370.720874 -211.41182)
		(width 0.14732)
		(layer "In4.Cu")
		(net "UPI_CPU0_CPU1_P1P0_DP<12>")
	)
	(segment
		(start 110.746794 -188.132974)
		(end 110.769654 -188.336428)
		(width 0.14732)
		(layer "In4.Cu")
		(net "UPI_CPU0_CPU1_P1P0_DP<12>")
	)
	(segment
		(start 238.603282 -147.499324)
		(end 170.28414 -146.403314)
		(width 0.14732)
		(layer "In4.Cu")
		(net "UPI_CPU0_CPU1_P1P0_DP<12>")
	)
	(segment
		(start 370.663978 -212.9028)
		(end 370.763038 -212.80374)
		(width 0.0889)
		(layer "In4.Cu")
		(net "UPI_CPU0_CPU1_P1P0_DP<12>")
	)
	(segment
		(start 370.721128 -211.64169)
		(end 370.721128 -211.412074)
		(width 0.14732)
		(layer "In4.Cu")
		(net "UPI_CPU0_CPU1_P1P0_DP<12>")
	)
	(segment
		(start 356.395274 -170.234102)
		(end 356.191312 -170.215814)
		(width 0.14732)
		(layer "In4.Cu")
		(net "UPI_CPU0_CPU1_P1P0_DP<12>")
	)
	(segment
		(start 100.636324 -215.755982)
		(end 100.638356 -215.757252)
		(width 0.0889)
		(layer "In4.Cu")
		(net "UPI_CPU0_CPU1_P1P0_DP<12>")
	)
	(segment
		(start 111.17961 -187.822078)
		(end 110.976156 -187.845192)
		(width 0.14732)
		(layer "In4.Cu")
		(net "UPI_CPU0_CPU1_P1P0_DP<12>")
	)
	(segment
		(start 357.050086 -171.600876)
		(end 357.128572 -171.411646)
		(width 0.14732)
		(layer "In4.Cu")
		(net "UPI_CPU0_CPU1_P1P0_DP<12>")
	)
	(segment
		(start 356.881684 -170.815762)
		(end 356.395274 -170.234102)
		(width 0.14732)
		(layer "In4.Cu")
		(net "UPI_CPU0_CPU1_P1P0_DP<12>")
	)
	(segment
		(start 108.210604 -191.545972)
		(end 107.980734 -191.834262)
		(width 0.14732)
		(layer "In4.Cu")
		(net "UPI_CPU0_CPU1_P1P0_DP<12>")
	)
	(segment
		(start 314.893706 -148.338794)
		(end 275.789898 -146.82978)
		(width 0.14732)
		(layer "In4.Cu")
		(net "UPI_CPU0_CPU1_P1P0_DP<12>")
	)
	(segment
		(start 362.11256 -183.44261)
		(end 357.38054 -172.019722)
		(width 0.14732)
		(layer "In4.Cu")
		(net "UPI_CPU0_CPU1_P1P0_DP<12>")
	)
	(segment
		(start 356.191312 -170.215814)
		(end 355.954838 -169.933112)
		(width 0.14732)
		(layer "In4.Cu")
		(net "UPI_CPU0_CPU1_P1P0_DP<12>")
	)
	(segment
		(start 371.045232 -214.946992)
		(end 371.054122 -214.941912)
		(width 0.0889)
		(layer "In4.Cu")
		(net "UPI_CPU0_CPU1_P1P0_DP<12>")
	)
	(segment
		(start 100.64369 -215.7603)
		(end 100.645214 -215.761062)
		(width 0.0889)
		(layer "In4.Cu")
		(net "UPI_CPU0_CPU1_P1P0_DP<12>")
	)
	(segment
		(start 112.265714 -186.227974)
		(end 111.38662 -187.330588)
		(width 0.14732)
		(layer "In4.Cu")
		(net "UPI_CPU0_CPU1_P1P0_DP<12>")
	)
	(segment
		(start 100.638356 -215.757252)
		(end 100.641658 -215.75903)
		(width 0.0889)
		(layer "In4.Cu")
		(net "UPI_CPU0_CPU1_P1P0_DP<12>")
	)
	(segment
		(start 370.720874 -211.41182)
		(end 370.720874 -205.924912)
		(width 0.14732)
		(layer "In4.Cu")
		(net "UPI_CPU0_CPU1_P1P0_DP<12>")
	)
	(segment
		(start 370.763038 -212.51672)
		(end 370.663978 -212.41766)
		(width 0.0889)
		(layer "In4.Cu")
		(net "UPI_CPU0_CPU1_P1P0_DP<12>")
	)
	(segment
		(start 370.575078 -215.761062)
		(end 370.576094 -215.760554)
		(width 0.0889)
		(layer "In4.Cu")
		(net "UPI_CPU0_CPU1_P1P0_DP<12>")
	)
	(segment
		(start 370.663978 -212.2424)
		(end 370.763038 -212.14334)
		(width 0.0889)
		(layer "In4.Cu")
		(net "UPI_CPU0_CPU1_P1P0_DP<12>")
	)
	(segment
		(start 108.62056 -191.031622)
		(end 108.416852 -191.054736)
		(width 0.14732)
		(layer "In4.Cu")
		(net "UPI_CPU0_CPU1_P1P0_DP<12>")
	)
	(segment
		(start 100.675948 -218.421204)
		(end 100.832412 -218.692222)
		(width 0.0889)
		(layer "In4.Cu")
		(net "UPI_CPU0_CPU1_P1P0_DP<12>")
	)
	(segment
		(start 363.297216 -188.002418)
		(end 362.77042 -187.465716)
		(width 0.14732)
		(layer "In4.Cu")
		(net "UPI_CPU0_CPU1_P1P0_DP<12>")
	)
	(segment
		(start 100.645468 -216.739978)
		(end 100.644706 -216.740486)
		(width 0.0889)
		(layer "In4.Cu")
		(net "UPI_CPU0_CPU1_P1P0_DP<12>")
	)
	(segment
		(start 327.61174 -150.813008)
		(end 317.51778 -148.339048)
		(width 0.14732)
		(layer "In4.Cu")
		(net "UPI_CPU0_CPU1_P1P0_DP<12>")
	)
	(segment
		(start 370.762784 -213.93023)
		(end 370.762784 -213.176866)
		(width 0.0889)
		(layer "In4.Cu")
		(net "UPI_CPU0_CPU1_P1P0_DP<12>")
	)
	(segment
		(start 109.467142 -189.737746)
		(end 109.490256 -189.9412)
		(width 0.14732)
		(layer "In4.Cu")
		(net "UPI_CPU0_CPU1_P1P0_DP<12>")
	)
	(segment
		(start 109.260386 -190.229236)
		(end 109.056678 -190.25235)
		(width 0.14732)
		(layer "In4.Cu")
		(net "UPI_CPU0_CPU1_P1P0_DP<12>")
	)
	(segment
		(start 371.03304 -214.954104)
		(end 371.045232 -214.946992)
		(width 0.0889)
		(layer "In4.Cu")
		(net "UPI_CPU0_CPU1_P1P0_DP<12>")
	)
	(segment
		(start 108.416852 -191.054736)
		(end 108.18749 -191.342518)
		(width 0.14732)
		(layer "In4.Cu")
		(net "UPI_CPU0_CPU1_P1P0_DP<12>")
	)
	(segment
		(start 275.789898 -146.82978)
		(end 238.603282 -147.499324)
		(width 0.14732)
		(layer "In4.Cu")
		(net "UPI_CPU0_CPU1_P1P0_DP<12>")
	)
	(segment
		(start 100.645214 -215.761062)
		(end 100.646738 -215.762078)
		(width 0.0889)
		(layer "In4.Cu")
		(net "UPI_CPU0_CPU1_P1P0_DP<12>")
	)
	(segment
		(start 100.636578 -217.383614)
		(end 100.644706 -217.388186)
		(width 0.0889)
		(layer "In4.Cu")
		(net "UPI_CPU0_CPU1_P1P0_DP<12>")
	)
	(segment
		(start 100.458016 -212.033612)
		(end 100.458016 -213.893908)
		(width 0.0889)
		(layer "In4.Cu")
		(net "UPI_CPU0_CPU1_P1P0_DP<12>")
	)
	(segment
		(start 100.927916 -216.25052)
		(end 100.927916 -216.260426)
		(width 0.0889)
		(layer "In4.Cu")
		(net "UPI_CPU0_CPU1_P1P0_DP<12>")
	)
	(segment
		(start 370.763038 -211.705698)
		(end 370.721128 -211.663788)
		(width 0.0889)
		(layer "In4.Cu")
		(net "UPI_CPU0_CPU1_P1P0_DP<12>")
	)
	(segment
		(start 100.648008 -215.76284)
		(end 100.65131 -215.764618)
		(width 0.0889)
		(layer "In4.Cu")
		(net "UPI_CPU0_CPU1_P1P0_DP<12>")
	)
	(segment
		(start 109.056678 -190.25235)
		(end 108.827316 -190.540132)
		(width 0.14732)
		(layer "In4.Cu")
		(net "UPI_CPU0_CPU1_P1P0_DP<12>")
	)
	(segment
		(start 130.328162 -169.225468)
		(end 112.265714 -186.227974)
		(width 0.14732)
		(layer "In4.Cu")
		(net "UPI_CPU0_CPU1_P1P0_DP<12>")
	)
	(segment
		(start 100.927408 -214.424768)
		(end 100.927408 -214.644732)
		(width 0.0889)
		(layer "In4.Cu")
		(net "UPI_CPU0_CPU1_P1P0_DP<12>")
	)
	(segment
		(start 163.760404 -148.6535)
		(end 130.328162 -169.225468)
		(width 0.14732)
		(layer "In4.Cu")
		(net "UPI_CPU0_CPU1_P1P0_DP<12>")
	)
	(segment
		(start 362.11256 -185.856118)
		(end 362.11256 -183.44261)
		(width 0.14732)
		(layer "In4.Cu")
		(net "UPI_CPU0_CPU1_P1P0_DP<12>")
	)
	(segment
		(start 362.77042 -187.465716)
		(end 362.11256 -185.856118)
		(width 0.14732)
		(layer "In4.Cu")
		(net "UPI_CPU0_CPU1_P1P0_DP<12>")
	)
	(segment
		(start 110.769654 -188.336428)
		(end 110.540038 -188.624464)
		(width 0.14732)
		(layer "In4.Cu")
		(net "UPI_CPU0_CPU1_P1P0_DP<12>")
	)
	(segment
		(start 100.50018 -211.481162)
		(end 100.50018 -211.96935)
		(width 0.14732)
		(layer "In4.Cu")
		(net "UPI_CPU0_CPU1_P1P0_DP<12>")
	)
	(segment
		(start 370.763038 -212.80374)
		(end 370.763038 -212.51672)
		(width 0.0889)
		(layer "In4.Cu")
		(net "UPI_CPU0_CPU1_P1P0_DP<12>")
	)
	(segment
		(start 317.51778 -148.339048)
		(end 314.89396 -148.339048)
		(width 0.14732)
		(layer "In4.Cu")
		(net "UPI_CPU0_CPU1_P1P0_DP<12>")
	)
	(segment
		(start 100.644706 -217.388186)
		(end 100.645468 -217.388694)
		(width 0.0889)
		(layer "In4.Cu")
		(net "UPI_CPU0_CPU1_P1P0_DP<12>")
	)
	(segment
		(start 111.38662 -187.330588)
		(end 111.40948 -187.534042)
		(width 0.14732)
		(layer "In4.Cu")
		(net "UPI_CPU0_CPU1_P1P0_DP<12>")
	)
	(segment
		(start 108.827316 -190.540132)
		(end 108.85043 -190.743586)
		(width 0.14732)
		(layer "In4.Cu")
		(net "UPI_CPU0_CPU1_P1P0_DP<12>")
	)
	(segment
		(start 370.38788 -217.064336)
		(end 370.544344 -217.335354)
		(width 0.0889)
		(layer "In4.Cu")
		(net "UPI_CPU0_CPU1_P1P0_DP<12>")
	)
	(segment
		(start 370.544344 -217.335354)
		(end 370.622576 -217.356182)
		(width 0.0889)
		(layer "In4.Cu")
		(net "UPI_CPU0_CPU1_P1P0_DP<12>")
	)
	(segment
		(start 370.721128 -211.663788)
		(end 370.721128 -211.64169)
		(width 0.0889)
		(layer "In4.Cu")
		(net "UPI_CPU0_CPU1_P1P0_DP<12>")
	)
	(segment
		(start 100.64496 -215.1126)
		(end 100.636324 -215.117426)
		(width 0.0889)
		(layer "In4.Cu")
		(net "UPI_CPU0_CPU1_P1P0_DP<12>")
	)
	(segment
		(start 109.900212 -189.42685)
		(end 109.696504 -189.449964)
		(width 0.14732)
		(layer "In4.Cu")
		(net "UPI_CPU0_CPU1_P1P0_DP<12>")
	)
	(segment
		(start 100.50018 -211.96935)
		(end 100.50018 -211.991448)
		(width 0.0889)
		(layer "In4.Cu")
		(net "UPI_CPU0_CPU1_P1P0_DP<12>")
	)
	(segment
		(start 107.77728 -191.857122)
		(end 107.382818 -192.35166)
		(width 0.14732)
		(layer "In4.Cu")
		(net "UPI_CPU0_CPU1_P1P0_DP<12>")
	)
	(segment
		(start 357.191056 -171.941236)
		(end 357.050086 -171.600876)
		(width 0.14732)
		(layer "In4.Cu")
		(net "UPI_CPU0_CPU1_P1P0_DP<12>")
	)
	(segment
		(start 357.128572 -171.411646)
		(end 356.881684 -170.815762)
		(width 0.14732)
		(layer "In4.Cu")
		(net "UPI_CPU0_CPU1_P1P0_DP<12>")
	)
	(segment
		(start 357.38054 -172.019722)
		(end 357.191056 -171.941236)
		(width 0.14732)
		(layer "In4.Cu")
		(net "UPI_CPU0_CPU1_P1P0_DP<12>")
	)
	(segment
		(start 371.232684 -214.622634)
		(end 371.232684 -214.461852)
		(width 0.0889)
		(layer "In4.Cu")
		(net "UPI_CPU0_CPU1_P1P0_DP<12>")
	)
	(segment
		(start 355.973126 -169.72915)
		(end 354.70084 -168.207182)
		(width 0.14732)
		(layer "In4.Cu")
		(net "UPI_CPU0_CPU1_P1P0_DP<12>")
	)
	(segment
		(start 100.700078 -218.33205)
		(end 100.675948 -218.421204)
		(width 0.0889)
		(layer "In4.Cu")
		(net "UPI_CPU0_CPU1_P1P0_DP<12>")
	)
	(segment
		(start 354.70084 -168.207182)
		(end 327.61174 -150.813008)
		(width 0.14732)
		(layer "In4.Cu")
		(net "UPI_CPU0_CPU1_P1P0_DP<12>")
	)
	(segment
		(start 100.646738 -215.762078)
		(end 100.648008 -215.76284)
		(width 0.0889)
		(layer "In4.Cu")
		(net "UPI_CPU0_CPU1_P1P0_DP<12>")
	)
	(segment
		(start 355.954838 -169.933112)
		(end 355.973126 -169.72915)
		(width 0.14732)
		(layer "In4.Cu")
		(net "UPI_CPU0_CPU1_P1P0_DP<12>")
	)
	(segment
		(start 110.540038 -188.624464)
		(end 110.33633 -188.647578)
		(width 0.14732)
		(layer "In4.Cu")
		(net "UPI_CPU0_CPU1_P1P0_DP<12>")
	)
	(segment
		(start 100.642166 -216.74201)
		(end 100.636578 -216.745058)
		(width 0.0889)
		(layer "In4.Cu")
		(net "UPI_CPU0_CPU1_P1P0_DP<12>")
	)
	(segment
		(start 110.129828 -189.138814)
		(end 109.900212 -189.42685)
		(width 0.14732)
		(layer "In4.Cu")
		(net "UPI_CPU0_CPU1_P1P0_DP<12>")
	)
	(segment
		(start 107.382564 -192.35166)
		(end 100.499926 -210.988402)
		(width 0.14732)
		(layer "In4.Cu")
		(net "UPI_CPU0_CPU1_P1P0_DP<12>")
	)
	(segment
		(start 107.382818 -192.35166)
		(end 107.382564 -192.35166)
		(width 0.14732)
		(layer "In4.Cu")
		(net "UPI_CPU0_CPU1_P1P0_DP<12>")
	)
	(segment
		(start 370.576094 -216.740486)
		(end 370.575078 -216.739978)
		(width 0.0889)
		(layer "In4.Cu")
		(net "UPI_CPU0_CPU1_P1P0_DP<12>")
	)
	(arc
		(start 370.76253 -217.064336)
		(mid 370.714851 -216.881436)
		(end 370.583968 -216.745058)
		(width 0.0889)
		(layer "In4.Cu")
		(net "UPI_CPU0_CPU1_P1P0_DP<12>")
	)
	(arc
		(start 371.232684 -214.461852)
		(mid 371.157613 -214.34611)
		(end 371.04828 -214.261954)
		(width 0.0889)
		(layer "In4.Cu")
		(net "UPI_CPU0_CPU1_P1P0_DP<12>")
	)
	(arc
		(start 370.292884 -216.235026)
		(mid 370.372254 -215.961292)
		(end 370.575078 -215.761062)
		(width 0.0889)
		(layer "In4.Cu")
		(net "UPI_CPU0_CPU1_P1P0_DP<12>")
	)
	(arc
		(start 100.636324 -215.117426)
		(mid 100.50907 -215.247392)
		(end 100.458016 -215.421972)
		(width 0.0889)
		(layer "In4.Cu")
		(net "UPI_CPU0_CPU1_P1P0_DP<12>")
	)
	(arc
		(start 100.458016 -215.421972)
		(mid 100.457819 -215.429337)
		(end 100.457762 -215.436704)
		(width 0.0889)
		(layer "In4.Cu")
		(net "UPI_CPU0_CPU1_P1P0_DP<12>")
	)
	(arc
		(start 100.636578 -216.745058)
		(mid 100.457981 -217.064336)
		(end 100.636578 -217.383614)
		(width 0.0889)
		(layer "In4.Cu")
		(net "UPI_CPU0_CPU1_P1P0_DP<12>")
	)
	(arc
		(start 371.04828 -214.261954)
		(mid 370.887925 -214.138568)
		(end 370.77777 -213.968838)
		(width 0.0889)
		(layer "In4.Cu")
		(net "UPI_CPU0_CPU1_P1P0_DP<12>")
	)
	(arc
		(start 100.645468 -217.388694)
		(mid 100.847754 -217.587675)
		(end 100.927916 -217.859864)
		(width 0.0889)
		(layer "In4.Cu")
		(net "UPI_CPU0_CPU1_P1P0_DP<12>")
	)
	(arc
		(start 100.65131 -215.764618)
		(mid 100.853897 -215.970969)
		(end 100.927916 -216.25052)
		(width 0.0889)
		(layer "In4.Cu")
		(net "UPI_CPU0_CPU1_P1P0_DP<12>")
	)
	(arc
		(start 370.76253 -215.436704)
		(mid 370.834703 -215.160036)
		(end 371.03304 -214.954104)
		(width 0.0889)
		(layer "In4.Cu")
		(net "UPI_CPU0_CPU1_P1P0_DP<12>")
	)
	(arc
		(start 371.054122 -214.941912)
		(mid 371.185036 -214.805552)
		(end 371.232684 -214.622634)
		(width 0.0889)
		(layer "In4.Cu")
		(net "UPI_CPU0_CPU1_P1P0_DP<12>")
	)
	(arc
		(start 100.642166 -214.093298)
		(mid 100.816129 -214.232062)
		(end 100.927408 -214.424768)
		(width 0.0889)
		(layer "In4.Cu")
		(net "UPI_CPU0_CPU1_P1P0_DP<12>")
	)
	(arc
		(start 100.458016 -213.893908)
		(mid 100.533021 -214.009367)
		(end 100.642166 -214.093298)
		(width 0.0889)
		(layer "In4.Cu")
		(net "UPI_CPU0_CPU1_P1P0_DP<12>")
	)
	(arc
		(start 370.583968 -215.755982)
		(mid 370.714882 -215.619622)
		(end 370.76253 -215.436704)
		(width 0.0889)
		(layer "In4.Cu")
		(net "UPI_CPU0_CPU1_P1P0_DP<12>")
	)
	(arc
		(start 370.575078 -216.739978)
		(mid 370.372255 -216.539747)
		(end 370.292884 -216.266014)
		(width 0.0889)
		(layer "In4.Cu")
		(net "UPI_CPU0_CPU1_P1P0_DP<12>")
	)
	(arc
		(start 100.457762 -215.436704)
		(mid 100.505441 -215.619604)
		(end 100.636324 -215.755982)
		(width 0.0889)
		(layer "In4.Cu")
		(net "UPI_CPU0_CPU1_P1P0_DP<12>")
	)
	(arc
		(start 370.77777 -213.968838)
		(mid 370.769948 -213.949662)
		(end 370.762784 -213.93023)
		(width 0.0889)
		(layer "In4.Cu")
		(net "UPI_CPU0_CPU1_P1P0_DP<12>")
	)
	(arc
		(start 370.622576 -217.356182)
		(mid 370.725721 -217.226157)
		(end 370.76253 -217.064336)
		(width 0.0889)
		(layer "In4.Cu")
		(net "UPI_CPU0_CPU1_P1P0_DP<12>")
	)
	(arc
		(start 100.717096 -218.318842)
		(mid 100.70865 -218.325527)
		(end 100.700078 -218.33205)
		(width 0.0889)
		(layer "In4.Cu")
		(net "UPI_CPU0_CPU1_P1P0_DP<12>")
	)
	(arc
		(start 100.927408 -214.644732)
		(mid 100.846497 -214.91486)
		(end 100.645214 -215.112346)
		(width 0.0889)
		(layer "In4.Cu")
		(net "UPI_CPU0_CPU1_P1P0_DP<12>")
	)
	(arc
		(start 100.927916 -217.878406)
		(mid 100.872561 -218.122593)
		(end 100.717096 -218.318842)
		(width 0.0889)
		(layer "In4.Cu")
		(net "UPI_CPU0_CPU1_P1P0_DP<12>")
	)
	(arc
		(start 100.927916 -216.260426)
		(mid 100.849805 -216.537375)
		(end 100.645468 -216.739978)
		(width 0.0889)
		(layer "In4.Cu")
		(net "UPI_CPU0_CPU1_P1P0_DP<12>")
	)
	(segment
		(start 99.422712 -218.414346)
		(end 99.422712 -217.87866)
		(width 0.13208)
		(layer "F.Cu")
		(net "UPI_CPU0_CPU1_P1P0_DP<11>")
	)
	(segment
		(start 99.422712 -217.87866)
		(end 99.422966 -217.878406)
		(width 0.13208)
		(layer "F.Cu")
		(net "UPI_CPU0_CPU1_P1P0_DP<11>")
	)
	(segment
		(start 371.79758 -218.414346)
		(end 371.79758 -217.87866)
		(width 0.13208)
		(layer "F.Cu")
		(net "UPI_CPU0_CPU1_P1P0_DP<11>")
	)
	(segment
		(start 371.79758 -217.87866)
		(end 371.797834 -217.878406)
		(width 0.13208)
		(layer "F.Cu")
		(net "UPI_CPU0_CPU1_P1P0_DP<11>")
	)
	(segment
		(start 364.017052 -186.250326)
		(end 364.017306 -186.250326)
		(width 0.14732)
		(layer "In4.Cu")
		(net "UPI_CPU0_CPU1_P1P0_DP<11>")
	)
	(segment
		(start 129.600452 -168.362884)
		(end 110.82401 -186.03722)
		(width 0.14732)
		(layer "In4.Cu")
		(net "UPI_CPU0_CPU1_P1P0_DP<11>")
	)
	(segment
		(start 371.601746 -217.559128)
		(end 371.610636 -217.554048)
		(width 0.0889)
		(layer "In4.Cu")
		(net "UPI_CPU0_CPU1_P1P0_DP<11>")
	)
	(segment
		(start 317.652146 -147.229576)
		(end 314.936886 -147.229576)
		(width 0.14732)
		(layer "In4.Cu")
		(net "UPI_CPU0_CPU1_P1P0_DP<11>")
	)
	(segment
		(start 99.613466 -215.92794)
		(end 99.619054 -215.931242)
		(width 0.0889)
		(layer "In4.Cu")
		(net "UPI_CPU0_CPU1_P1P0_DP<11>")
	)
	(segment
		(start 371.992144 -212.1662)
		(end 371.893084 -212.06714)
		(width 0.0889)
		(layer "In4.Cu")
		(net "UPI_CPU0_CPU1_P1P0_DP<11>")
	)
	(segment
		(start 99.285552 -211.480908)
		(end 99.285806 -211.481162)
		(width 0.14732)
		(layer "In4.Cu")
		(net "UPI_CPU0_CPU1_P1P0_DP<11>")
	)
	(segment
		(start 371.893084 -213.11362)
		(end 371.992144 -213.01456)
		(width 0.0889)
		(layer "In4.Cu")
		(net "UPI_CPU0_CPU1_P1P0_DP<11>")
	)
	(segment
		(start 360.439716 -176.435258)
		(end 360.439716 -176.435004)
		(width 0.14732)
		(layer "In4.Cu")
		(net "UPI_CPU0_CPU1_P1P0_DP<11>")
	)
	(segment
		(start 371.935248 -211.298282)
		(end 371.934994 -211.298028)
		(width 0.14732)
		(layer "In4.Cu")
		(net "UPI_CPU0_CPU1_P1P0_DP<11>")
	)
	(segment
		(start 170.028616 -145.283428)
		(end 163.374832 -147.581112)
		(width 0.14732)
		(layer "In4.Cu")
		(net "UPI_CPU0_CPU1_P1P0_DP<11>")
	)
	(segment
		(start 371.893084 -217.082878)
		(end 371.893084 -217.05443)
		(width 0.0889)
		(layer "In4.Cu")
		(net "UPI_CPU0_CPU1_P1P0_DP<11>")
	)
	(segment
		(start 371.893084 -212.44052)
		(end 371.992144 -212.34146)
		(width 0.0889)
		(layer "In4.Cu")
		(net "UPI_CPU0_CPU1_P1P0_DP<11>")
	)
	(segment
		(start 371.64137 -218.149424)
		(end 371.563138 -218.170252)
		(width 0.0889)
		(layer "In4.Cu")
		(net "UPI_CPU0_CPU1_P1P0_DP<11>")
	)
	(segment
		(start 371.601746 -215.931242)
		(end 371.610636 -215.926162)
		(width 0.0889)
		(layer "In4.Cu")
		(net "UPI_CPU0_CPU1_P1P0_DP<11>")
	)
	(segment
		(start 110.82401 -186.03722)
		(end 106.566208 -191.376554)
		(width 0.14732)
		(layer "In4.Cu")
		(net "UPI_CPU0_CPU1_P1P0_DP<11>")
	)
	(segment
		(start 363.3597 -185.292238)
		(end 363.3597 -183.484774)
		(width 0.14732)
		(layer "In4.Cu")
		(net "UPI_CPU0_CPU1_P1P0_DP<11>")
	)
	(segment
		(start 371.893084 -211.779612)
		(end 371.935248 -211.737448)
		(width 0.0889)
		(layer "In4.Cu")
		(net "UPI_CPU0_CPU1_P1P0_DP<11>")
	)
	(segment
		(start 363.3597 -183.484774)
		(end 360.439716 -176.435258)
		(width 0.14732)
		(layer "In4.Cu")
		(net "UPI_CPU0_CPU1_P1P0_DP<11>")
	)
	(segment
		(start 365.306102 -189.950852)
		(end 365.081058 -188.819536)
		(width 0.14732)
		(layer "In4.Cu")
		(net "UPI_CPU0_CPU1_P1P0_DP<11>")
	)
	(segment
		(start 99.619054 -216.569798)
		(end 99.603814 -216.578688)
		(width 0.0889)
		(layer "In4.Cu")
		(net "UPI_CPU0_CPU1_P1P0_DP<11>")
	)
	(segment
		(start 99.285552 -211.091526)
		(end 99.285552 -211.480908)
		(width 0.14732)
		(layer "In4.Cu")
		(net "UPI_CPU0_CPU1_P1P0_DP<11>")
	)
	(segment
		(start 99.327716 -212.033358)
		(end 99.327716 -213.930484)
		(width 0.0889)
		(layer "In4.Cu")
		(net "UPI_CPU0_CPU1_P1P0_DP<11>")
	)
	(segment
		(start 314.936886 -147.229576)
		(end 314.936886 -147.229322)
		(width 0.14732)
		(layer "In4.Cu")
		(net "UPI_CPU0_CPU1_P1P0_DP<11>")
	)
	(segment
		(start 238.600488 -146.3929)
		(end 170.028616 -145.283428)
		(width 0.14732)
		(layer "In4.Cu")
		(net "UPI_CPU0_CPU1_P1P0_DP<11>")
	)
	(segment
		(start 276.078696 -145.718276)
		(end 238.600488 -146.3929)
		(width 0.14732)
		(layer "In4.Cu")
		(net "UPI_CPU0_CPU1_P1P0_DP<11>")
	)
	(segment
		(start 99.285806 -211.96935)
		(end 99.285806 -211.991448)
		(width 0.0889)
		(layer "In4.Cu")
		(net "UPI_CPU0_CPU1_P1P0_DP<11>")
	)
	(segment
		(start 99.327462 -215.414606)
		(end 99.327462 -215.436704)
		(width 0.0889)
		(layer "In4.Cu")
		(net "UPI_CPU0_CPU1_P1P0_DP<11>")
	)
	(segment
		(start 371.992144 -213.01456)
		(end 371.992144 -212.8393)
		(width 0.0889)
		(layer "In4.Cu")
		(net "UPI_CPU0_CPU1_P1P0_DP<11>")
	)
	(segment
		(start 360.439716 -176.435004)
		(end 357.89616 -170.294554)
		(width 0.14732)
		(layer "In4.Cu")
		(net "UPI_CPU0_CPU1_P1P0_DP<11>")
	)
	(segment
		(start 99.797108 -214.461344)
		(end 99.797108 -214.622634)
		(width 0.0889)
		(layer "In4.Cu")
		(net "UPI_CPU0_CPU1_P1P0_DP<11>")
	)
	(segment
		(start 328.055732 -149.77872)
		(end 317.652146 -147.229576)
		(width 0.14732)
		(layer "In4.Cu")
		(net "UPI_CPU0_CPU1_P1P0_DP<11>")
	)
	(segment
		(start 371.893084 -212.06714)
		(end 371.893084 -211.779612)
		(width 0.0889)
		(layer "In4.Cu")
		(net "UPI_CPU0_CPU1_P1P0_DP<11>")
	)
	(segment
		(start 371.89283 -215.455246)
		(end 371.893084 -215.436704)
		(width 0.0889)
		(layer "In4.Cu")
		(net "UPI_CPU0_CPU1_P1P0_DP<11>")
	)
	(segment
		(start 99.327462 -217.064336)
		(end 99.327462 -217.07856)
		(width 0.0889)
		(layer "In4.Cu")
		(net "UPI_CPU0_CPU1_P1P0_DP<11>")
	)
	(segment
		(start 371.893084 -212.74024)
		(end 371.893084 -212.44052)
		(width 0.0889)
		(layer "In4.Cu")
		(net "UPI_CPU0_CPU1_P1P0_DP<11>")
	)
	(segment
		(start 99.285806 -211.481162)
		(end 99.285806 -211.96935)
		(width 0.14732)
		(layer "In4.Cu")
		(net "UPI_CPU0_CPU1_P1P0_DP<11>")
	)
	(segment
		(start 99.609402 -215.925654)
		(end 99.610926 -215.92667)
		(width 0.0889)
		(layer "In4.Cu")
		(net "UPI_CPU0_CPU1_P1P0_DP<11>")
	)
	(segment
		(start 99.60737 -215.924384)
		(end 99.609402 -215.925654)
		(width 0.0889)
		(layer "In4.Cu")
		(net "UPI_CPU0_CPU1_P1P0_DP<11>")
	)
	(segment
		(start 372.362984 -214.636858)
		(end 372.362984 -214.425022)
		(width 0.0889)
		(layer "In4.Cu")
		(net "UPI_CPU0_CPU1_P1P0_DP<11>")
	)
	(segment
		(start 371.797834 -217.878406)
		(end 371.64137 -218.149424)
		(width 0.0889)
		(layer "In4.Cu")
		(net "UPI_CPU0_CPU1_P1P0_DP<11>")
	)
	(segment
		(start 106.566208 -191.376554)
		(end 99.285552 -211.091526)
		(width 0.14732)
		(layer "In4.Cu")
		(net "UPI_CPU0_CPU1_P1P0_DP<11>")
	)
	(segment
		(start 99.603814 -216.578688)
		(end 99.604068 -216.578434)
		(width 0.0889)
		(layer "In4.Cu")
		(net "UPI_CPU0_CPU1_P1P0_DP<11>")
	)
	(segment
		(start 371.935248 -211.737448)
		(end 371.935248 -211.71535)
		(width 0.0889)
		(layer "In4.Cu")
		(net "UPI_CPU0_CPU1_P1P0_DP<11>")
	)
	(segment
		(start 371.893084 -215.436704)
		(end 371.893084 -215.428068)
		(width 0.0889)
		(layer "In4.Cu")
		(net "UPI_CPU0_CPU1_P1P0_DP<11>")
	)
	(segment
		(start 371.992144 -212.8393)
		(end 371.893084 -212.74024)
		(width 0.0889)
		(layer "In4.Cu")
		(net "UPI_CPU0_CPU1_P1P0_DP<11>")
	)
	(segment
		(start 355.450394 -167.369236)
		(end 328.055732 -149.77872)
		(width 0.14732)
		(layer "In4.Cu")
		(net "UPI_CPU0_CPU1_P1P0_DP<11>")
	)
	(segment
		(start 99.604068 -215.922606)
		(end 99.60737 -215.924384)
		(width 0.0889)
		(layer "In4.Cu")
		(net "UPI_CPU0_CPU1_P1P0_DP<11>")
	)
	(segment
		(start 99.5553 -217.518234)
		(end 99.57943 -217.607388)
		(width 0.0889)
		(layer "In4.Cu")
		(net "UPI_CPU0_CPU1_P1P0_DP<11>")
	)
	(segment
		(start 371.934994 -211.298028)
		(end 371.934994 -205.955392)
		(width 0.14732)
		(layer "In4.Cu")
		(net "UPI_CPU0_CPU1_P1P0_DP<11>")
	)
	(segment
		(start 363.561884 -185.786014)
		(end 363.3597 -185.292238)
		(width 0.14732)
		(layer "In4.Cu")
		(net "UPI_CPU0_CPU1_P1P0_DP<11>")
	)
	(segment
		(start 364.017306 -186.250326)
		(end 363.561884 -185.786014)
		(width 0.14732)
		(layer "In4.Cu")
		(net "UPI_CPU0_CPU1_P1P0_DP<11>")
	)
	(segment
		(start 365.081058 -188.819536)
		(end 364.017052 -186.250326)
		(width 0.14732)
		(layer "In4.Cu")
		(net "UPI_CPU0_CPU1_P1P0_DP<11>")
	)
	(segment
		(start 163.374832 -147.581112)
		(end 129.600452 -168.362884)
		(width 0.14732)
		(layer "In4.Cu")
		(net "UPI_CPU0_CPU1_P1P0_DP<11>")
	)
	(segment
		(start 371.610636 -216.574878)
		(end 371.601746 -216.569798)
		(width 0.0889)
		(layer "In4.Cu")
		(net "UPI_CPU0_CPU1_P1P0_DP<11>")
	)
	(segment
		(start 99.57943 -217.607388)
		(end 99.422966 -217.878406)
		(width 0.0889)
		(layer "In4.Cu")
		(net "UPI_CPU0_CPU1_P1P0_DP<11>")
	)
	(segment
		(start 371.893084 -213.8934)
		(end 371.893084 -213.11362)
		(width 0.0889)
		(layer "In4.Cu")
		(net "UPI_CPU0_CPU1_P1P0_DP<11>")
	)
	(segment
		(start 99.285806 -211.991448)
		(end 99.327716 -212.033358)
		(width 0.0889)
		(layer "In4.Cu")
		(net "UPI_CPU0_CPU1_P1P0_DP<11>")
	)
	(segment
		(start 371.935248 -211.71535)
		(end 371.935248 -211.298282)
		(width 0.14732)
		(layer "In4.Cu")
		(net "UPI_CPU0_CPU1_P1P0_DP<11>")
	)
	(segment
		(start 99.610926 -215.92667)
		(end 99.613466 -215.92794)
		(width 0.0889)
		(layer "In4.Cu")
		(net "UPI_CPU0_CPU1_P1P0_DP<11>")
	)
	(segment
		(start 314.936886 -147.229322)
		(end 276.078696 -145.718276)
		(width 0.14732)
		(layer "In4.Cu")
		(net "UPI_CPU0_CPU1_P1P0_DP<11>")
	)
	(segment
		(start 99.618546 -214.941912)
		(end 99.609656 -214.946992)
		(width 0.0889)
		(layer "In4.Cu")
		(net "UPI_CPU0_CPU1_P1P0_DP<11>")
	)
	(segment
		(start 371.992144 -212.34146)
		(end 371.992144 -212.1662)
		(width 0.0889)
		(layer "In4.Cu")
		(net "UPI_CPU0_CPU1_P1P0_DP<11>")
	)
	(segment
		(start 371.934994 -205.955392)
		(end 365.306102 -189.950852)
		(width 0.14732)
		(layer "In4.Cu")
		(net "UPI_CPU0_CPU1_P1P0_DP<11>")
	)
	(segment
		(start 357.89616 -170.294554)
		(end 355.450394 -167.369236)
		(width 0.14732)
		(layer "In4.Cu")
		(net "UPI_CPU0_CPU1_P1P0_DP<11>")
	)
	(arc
		(start 99.327716 -213.930484)
		(mid 99.335001 -213.950046)
		(end 99.342956 -213.969346)
		(width 0.0889)
		(layer "In4.Cu")
		(net "UPI_CPU0_CPU1_P1P0_DP<11>")
	)
	(arc
		(start 371.423438 -216.238328)
		(mid 371.473931 -216.06235)
		(end 371.601746 -215.931242)
		(width 0.0889)
		(layer "In4.Cu")
		(net "UPI_CPU0_CPU1_P1P0_DP<11>")
	)
	(arc
		(start 99.797108 -214.622634)
		(mid 99.749429 -214.805534)
		(end 99.618546 -214.941912)
		(width 0.0889)
		(layer "In4.Cu")
		(net "UPI_CPU0_CPU1_P1P0_DP<11>")
	)
	(arc
		(start 372.077488 -214.093298)
		(mid 371.968092 -214.009201)
		(end 371.893084 -213.8934)
		(width 0.0889)
		(layer "In4.Cu")
		(net "UPI_CPU0_CPU1_P1P0_DP<11>")
	)
	(arc
		(start 99.538282 -217.50528)
		(mid 99.54673 -217.511837)
		(end 99.5553 -217.518234)
		(width 0.0889)
		(layer "In4.Cu")
		(net "UPI_CPU0_CPU1_P1P0_DP<11>")
	)
	(arc
		(start 372.080282 -215.112346)
		(mid 372.283763 -214.911542)
		(end 372.362984 -214.636858)
		(width 0.0889)
		(layer "In4.Cu")
		(net "UPI_CPU0_CPU1_P1P0_DP<11>")
	)
	(arc
		(start 371.610636 -215.926162)
		(mid 371.812678 -215.727239)
		(end 371.89283 -215.455246)
		(width 0.0889)
		(layer "In4.Cu")
		(net "UPI_CPU0_CPU1_P1P0_DP<11>")
	)
	(arc
		(start 371.423184 -216.257124)
		(mid 371.423194 -216.247724)
		(end 371.423438 -216.238328)
		(width 0.0889)
		(layer "In4.Cu")
		(net "UPI_CPU0_CPU1_P1P0_DP<11>")
	)
	(arc
		(start 99.327462 -217.07856)
		(mid 99.385756 -217.315203)
		(end 99.538282 -217.50528)
		(width 0.0889)
		(layer "In4.Cu")
		(net "UPI_CPU0_CPU1_P1P0_DP<11>")
	)
	(arc
		(start 99.619054 -215.931242)
		(mid 99.797651 -216.25052)
		(end 99.619054 -216.569798)
		(width 0.0889)
		(layer "In4.Cu")
		(net "UPI_CPU0_CPU1_P1P0_DP<11>")
	)
	(arc
		(start 371.563138 -218.170252)
		(mid 371.459993 -218.040227)
		(end 371.423184 -217.878406)
		(width 0.0889)
		(layer "In4.Cu")
		(net "UPI_CPU0_CPU1_P1P0_DP<11>")
	)
	(arc
		(start 99.612958 -214.261954)
		(mid 99.722105 -214.345882)
		(end 99.797108 -214.461344)
		(width 0.0889)
		(layer "In4.Cu")
		(net "UPI_CPU0_CPU1_P1P0_DP<11>")
	)
	(arc
		(start 99.342956 -213.969346)
		(mid 99.45295 -214.138715)
		(end 99.612958 -214.261954)
		(width 0.0889)
		(layer "In4.Cu")
		(net "UPI_CPU0_CPU1_P1P0_DP<11>")
	)
	(arc
		(start 99.604068 -216.578434)
		(mid 99.401481 -216.784785)
		(end 99.327462 -217.064336)
		(width 0.0889)
		(layer "In4.Cu")
		(net "UPI_CPU0_CPU1_P1P0_DP<11>")
	)
	(arc
		(start 371.423184 -217.878406)
		(mid 371.470863 -217.695506)
		(end 371.601746 -217.559128)
		(width 0.0889)
		(layer "In4.Cu")
		(net "UPI_CPU0_CPU1_P1P0_DP<11>")
	)
	(arc
		(start 99.327462 -215.436704)
		(mid 99.401453 -215.71627)
		(end 99.604068 -215.922606)
		(width 0.0889)
		(layer "In4.Cu")
		(net "UPI_CPU0_CPU1_P1P0_DP<11>")
	)
	(arc
		(start 372.362984 -214.425022)
		(mid 372.251646 -214.232122)
		(end 372.077488 -214.093298)
		(width 0.0889)
		(layer "In4.Cu")
		(net "UPI_CPU0_CPU1_P1P0_DP<11>")
	)
	(arc
		(start 99.609656 -214.946992)
		(mid 99.408374 -215.144479)
		(end 99.327462 -215.414606)
		(width 0.0889)
		(layer "In4.Cu")
		(net "UPI_CPU0_CPU1_P1P0_DP<11>")
	)
	(arc
		(start 371.893084 -215.428068)
		(mid 371.945354 -215.245703)
		(end 372.080282 -215.112346)
		(width 0.0889)
		(layer "In4.Cu")
		(net "UPI_CPU0_CPU1_P1P0_DP<11>")
	)
	(arc
		(start 371.893084 -217.05443)
		(mid 371.814973 -216.777481)
		(end 371.610636 -216.574878)
		(width 0.0889)
		(layer "In4.Cu")
		(net "UPI_CPU0_CPU1_P1P0_DP<11>")
	)
	(arc
		(start 371.601746 -216.569798)
		(mid 371.472457 -216.436312)
		(end 371.423184 -216.257124)
		(width 0.0889)
		(layer "In4.Cu")
		(net "UPI_CPU0_CPU1_P1P0_DP<11>")
	)
	(arc
		(start 371.610636 -217.554048)
		(mid 371.812922 -217.355067)
		(end 371.893084 -217.082878)
		(width 0.0889)
		(layer "In4.Cu")
		(net "UPI_CPU0_CPU1_P1P0_DP<11>")
	)
	(segment
		(start 98.953066 -219.228162)
		(end 98.953066 -218.692476)
		(width 0.13208)
		(layer "F.Cu")
		(net "UPI_CPU0_CPU1_P1P0_DP<10>")
	)
	(segment
		(start 372.267734 -217.600276)
		(end 372.267734 -217.06459)
		(width 0.13208)
		(layer "F.Cu")
		(net "UPI_CPU0_CPU1_P1P0_DP<10>")
	)
	(segment
		(start 98.953066 -218.692476)
		(end 98.952812 -218.692222)
		(width 0.13208)
		(layer "F.Cu")
		(net "UPI_CPU0_CPU1_P1P0_DP<10>")
	)
	(segment
		(start 372.267734 -217.06459)
		(end 372.26748 -217.064336)
		(width 0.13208)
		(layer "F.Cu")
		(net "UPI_CPU0_CPU1_P1P0_DP<10>")
	)
	(segment
		(start 372.91264 -214.954104)
		(end 372.924832 -214.946992)
		(width 0.0889)
		(layer "In4.Cu")
		(net "UPI_CPU0_CPU1_P1P0_DP<10>")
	)
	(segment
		(start 317.720218 -146.667728)
		(end 314.867798 -146.667728)
		(width 0.14732)
		(layer "In4.Cu")
		(net "UPI_CPU0_CPU1_P1P0_DP<10>")
	)
	(segment
		(start 372.600474 -211.69249)
		(end 372.600474 -206.062326)
		(width 0.14732)
		(layer "In4.Cu")
		(net "UPI_CPU0_CPU1_P1P0_DP<10>")
	)
	(segment
		(start 107.607354 -188.98235)
		(end 107.626658 -189.1538)
		(width 0.14732)
		(layer "In4.Cu")
		(net "UPI_CPU0_CPU1_P1P0_DP<10>")
	)
	(segment
		(start 372.543324 -212.408008)
		(end 372.642384 -212.308948)
		(width 0.0889)
		(layer "In4.Cu")
		(net "UPI_CPU0_CPU1_P1P0_DP<10>")
	)
	(segment
		(start 372.423944 -217.335354)
		(end 372.502176 -217.356182)
		(width 0.0889)
		(layer "In4.Cu")
		(net "UPI_CPU0_CPU1_P1P0_DP<10>")
	)
	(segment
		(start 98.62058 -211.96935)
		(end 98.62058 -211.991448)
		(width 0.0889)
		(layer "In4.Cu")
		(net "UPI_CPU0_CPU1_P1P0_DP<10>")
	)
	(segment
		(start 99.048316 -217.859864)
		(end 99.048316 -217.878406)
		(width 0.0889)
		(layer "In4.Cu")
		(net "UPI_CPU0_CPU1_P1P0_DP<10>")
	)
	(segment
		(start 99.047808 -214.424768)
		(end 99.047808 -214.644732)
		(width 0.0889)
		(layer "In4.Cu")
		(net "UPI_CPU0_CPU1_P1P0_DP<10>")
	)
	(segment
		(start 372.172484 -216.266014)
		(end 372.172484 -216.235026)
		(width 0.0889)
		(layer "In4.Cu")
		(net "UPI_CPU0_CPU1_P1P0_DP<10>")
	)
	(segment
		(start 372.642384 -213.93023)
		(end 372.642384 -213.330028)
		(width 0.0889)
		(layer "In4.Cu")
		(net "UPI_CPU0_CPU1_P1P0_DP<10>")
	)
	(segment
		(start 98.767138 -215.762078)
		(end 98.768408 -215.76284)
		(width 0.0889)
		(layer "In4.Cu")
		(net "UPI_CPU0_CPU1_P1P0_DP<10>")
	)
	(segment
		(start 99.048316 -216.25052)
		(end 99.048316 -216.260426)
		(width 0.0889)
		(layer "In4.Cu")
		(net "UPI_CPU0_CPU1_P1P0_DP<10>")
	)
	(segment
		(start 363.104938 -180.563266)
		(end 362.524802 -179.98313)
		(width 0.14732)
		(layer "In4.Cu")
		(net "UPI_CPU0_CPU1_P1P0_DP<10>")
	)
	(segment
		(start 358.40543 -170.038014)
		(end 355.807518 -166.930578)
		(width 0.14732)
		(layer "In4.Cu")
		(net "UPI_CPU0_CPU1_P1P0_DP<10>")
	)
	(segment
		(start 98.765106 -216.740486)
		(end 98.762566 -216.74201)
		(width 0.0889)
		(layer "In4.Cu")
		(net "UPI_CPU0_CPU1_P1P0_DP<10>")
	)
	(segment
		(start 109.001306 -187.234322)
		(end 109.02061 -187.405772)
		(width 0.14732)
		(layer "In4.Cu")
		(net "UPI_CPU0_CPU1_P1P0_DP<10>")
	)
	(segment
		(start 276.121368 -145.161)
		(end 257.359404 -145.498566)
		(width 0.14732)
		(layer "In4.Cu")
		(net "UPI_CPU0_CPU1_P1P0_DP<10>")
	)
	(segment
		(start 238.598202 -145.836386)
		(end 169.913808 -144.724882)
		(width 0.14732)
		(layer "In4.Cu")
		(net "UPI_CPU0_CPU1_P1P0_DP<10>")
	)
	(segment
		(start 363.366812 -181.574186)
		(end 363.225842 -181.233572)
		(width 0.14732)
		(layer "In4.Cu")
		(net "UPI_CPU0_CPU1_P1P0_DP<10>")
	)
	(segment
		(start 363.225842 -181.233572)
		(end 363.304328 -181.044342)
		(width 0.14732)
		(layer "In4.Cu")
		(net "UPI_CPU0_CPU1_P1P0_DP<10>")
	)
	(segment
		(start 129.264156 -167.88003)
		(end 109.899704 -186.107578)
		(width 0.14732)
		(layer "In4.Cu")
		(net "UPI_CPU0_CPU1_P1P0_DP<10>")
	)
	(segment
		(start 107.626658 -189.1538)
		(end 107.353862 -189.495684)
		(width 0.14732)
		(layer "In4.Cu")
		(net "UPI_CPU0_CPU1_P1P0_DP<10>")
	)
	(segment
		(start 98.765614 -215.112346)
		(end 98.764598 -215.112854)
		(width 0.0889)
		(layer "In4.Cu")
		(net "UPI_CPU0_CPU1_P1P0_DP<10>")
	)
	(segment
		(start 98.756978 -217.383614)
		(end 98.765106 -217.388186)
		(width 0.0889)
		(layer "In4.Cu")
		(net "UPI_CPU0_CPU1_P1P0_DP<10>")
	)
	(segment
		(start 373.112284 -214.622634)
		(end 373.112284 -214.461852)
		(width 0.0889)
		(layer "In4.Cu")
		(net "UPI_CPU0_CPU1_P1P0_DP<10>")
	)
	(segment
		(start 372.26748 -217.064336)
		(end 372.423944 -217.335354)
		(width 0.0889)
		(layer "In4.Cu")
		(net "UPI_CPU0_CPU1_P1P0_DP<10>")
	)
	(segment
		(start 365.3028 -187.0329)
		(end 365.132112 -186.919108)
		(width 0.14732)
		(layer "In4.Cu")
		(net "UPI_CPU0_CPU1_P1P0_DP<10>")
	)
	(segment
		(start 169.913808 -144.724882)
		(end 163.037266 -147.099274)
		(width 0.14732)
		(layer "In4.Cu")
		(net "UPI_CPU0_CPU1_P1P0_DP<10>")
	)
	(segment
		(start 365.102394 -186.026298)
		(end 364.93196 -185.912506)
		(width 0.14732)
		(layer "In4.Cu")
		(net "UPI_CPU0_CPU1_P1P0_DP<10>")
	)
	(segment
		(start 363.304328 -181.044342)
		(end 363.104938 -180.563266)
		(width 0.14732)
		(layer "In4.Cu")
		(net "UPI_CPU0_CPU1_P1P0_DP<10>")
	)
	(segment
		(start 98.764598 -215.112854)
		(end 98.756724 -215.117426)
		(width 0.0889)
		(layer "In4.Cu")
		(net "UPI_CPU0_CPU1_P1P0_DP<10>")
	)
	(segment
		(start 109.02061 -187.405772)
		(end 108.747814 -187.747656)
		(width 0.14732)
		(layer "In4.Cu")
		(net "UPI_CPU0_CPU1_P1P0_DP<10>")
	)
	(segment
		(start 108.30433 -188.108336)
		(end 108.323634 -188.279786)
		(width 0.14732)
		(layer "In4.Cu")
		(net "UPI_CPU0_CPU1_P1P0_DP<10>")
	)
	(segment
		(start 108.323634 -188.279786)
		(end 108.050838 -188.62167)
		(width 0.14732)
		(layer "In4.Cu")
		(net "UPI_CPU0_CPU1_P1P0_DP<10>")
	)
	(segment
		(start 363.807756 -182.259732)
		(end 363.556042 -181.652418)
		(width 0.14732)
		(layer "In4.Cu")
		(net "UPI_CPU0_CPU1_P1P0_DP<10>")
	)
	(segment
		(start 163.037266 -147.099274)
		(end 129.264156 -167.88003)
		(width 0.14732)
		(layer "In4.Cu")
		(net "UPI_CPU0_CPU1_P1P0_DP<10>")
	)
	(segment
		(start 98.620326 -211.278978)
		(end 98.620326 -211.813648)
		(width 0.14732)
		(layer "In4.Cu")
		(net "UPI_CPU0_CPU1_P1P0_DP<10>")
	)
	(segment
		(start 98.578416 -212.033612)
		(end 98.578416 -213.893908)
		(width 0.0889)
		(layer "In4.Cu")
		(net "UPI_CPU0_CPU1_P1P0_DP<10>")
	)
	(segment
		(start 363.807756 -183.080152)
		(end 363.807756 -182.259732)
		(width 0.14732)
		(layer "In4.Cu")
		(net "UPI_CPU0_CPU1_P1P0_DP<10>")
	)
	(segment
		(start 98.762566 -216.74201)
		(end 98.756978 -216.745058)
		(width 0.0889)
		(layer "In4.Cu")
		(net "UPI_CPU0_CPU1_P1P0_DP<10>")
	)
	(segment
		(start 355.807518 -166.930578)
		(end 328.280522 -149.255226)
		(width 0.14732)
		(layer "In4.Cu")
		(net "UPI_CPU0_CPU1_P1P0_DP<10>")
	)
	(segment
		(start 98.820478 -218.33205)
		(end 98.796348 -218.421204)
		(width 0.0889)
		(layer "In4.Cu")
		(net "UPI_CPU0_CPU1_P1P0_DP<10>")
	)
	(segment
		(start 365.842804 -189.74816)
		(end 365.3028 -187.0329)
		(width 0.14732)
		(layer "In4.Cu")
		(net "UPI_CPU0_CPU1_P1P0_DP<10>")
	)
	(segment
		(start 98.765868 -216.739978)
		(end 98.765106 -216.740486)
		(width 0.0889)
		(layer "In4.Cu")
		(net "UPI_CPU0_CPU1_P1P0_DP<10>")
	)
	(segment
		(start 106.910378 -189.856364)
		(end 106.929682 -190.02756)
		(width 0.14732)
		(layer "In4.Cu")
		(net "UPI_CPU0_CPU1_P1P0_DP<10>")
	)
	(segment
		(start 364.895638 -184.987946)
		(end 364.387384 -184.479692)
		(width 0.14732)
		(layer "In4.Cu")
		(net "UPI_CPU0_CPU1_P1P0_DP<10>")
	)
	(segment
		(start 98.796348 -218.421204)
		(end 98.952812 -218.692222)
		(width 0.0889)
		(layer "In4.Cu")
		(net "UPI_CPU0_CPU1_P1P0_DP<10>")
	)
	(segment
		(start 372.455694 -215.760554)
		(end 372.463568 -215.755982)
		(width 0.0889)
		(layer "In4.Cu")
		(net "UPI_CPU0_CPU1_P1P0_DP<10>")
	)
	(segment
		(start 372.642384 -212.308948)
		(end 372.642384 -211.7344)
		(width 0.0889)
		(layer "In4.Cu")
		(net "UPI_CPU0_CPU1_P1P0_DP<10>")
	)
	(segment
		(start 106.48569 -190.388748)
		(end 106.204766 -190.741046)
		(width 0.14732)
		(layer "In4.Cu")
		(net "UPI_CPU0_CPU1_P1P0_DP<10>")
	)
	(segment
		(start 106.929682 -190.02756)
		(end 106.65714 -190.369444)
		(width 0.14732)
		(layer "In4.Cu")
		(net "UPI_CPU0_CPU1_P1P0_DP<10>")
	)
	(segment
		(start 98.62058 -211.813902)
		(end 98.62058 -211.96935)
		(width 0.14732)
		(layer "In4.Cu")
		(net "UPI_CPU0_CPU1_P1P0_DP<10>")
	)
	(segment
		(start 106.65714 -190.369444)
		(end 106.48569 -190.388748)
		(width 0.14732)
		(layer "In4.Cu")
		(net "UPI_CPU0_CPU1_P1P0_DP<10>")
	)
	(segment
		(start 372.642384 -213.330028)
		(end 372.543324 -213.230968)
		(width 0.0889)
		(layer "In4.Cu")
		(net "UPI_CPU0_CPU1_P1P0_DP<10>")
	)
	(segment
		(start 107.182666 -189.514988)
		(end 106.910378 -189.856364)
		(width 0.14732)
		(layer "In4.Cu")
		(net "UPI_CPU0_CPU1_P1P0_DP<10>")
	)
	(segment
		(start 365.060484 -186.557666)
		(end 365.174022 -186.387486)
		(width 0.14732)
		(layer "In4.Cu")
		(net "UPI_CPU0_CPU1_P1P0_DP<10>")
	)
	(segment
		(start 98.62058 -211.991448)
		(end 98.578416 -212.033612)
		(width 0.0889)
		(layer "In4.Cu")
		(net "UPI_CPU0_CPU1_P1P0_DP<10>")
	)
	(segment
		(start 372.543324 -213.055708)
		(end 372.642384 -212.956648)
		(width 0.0889)
		(layer "In4.Cu")
		(net "UPI_CPU0_CPU1_P1P0_DP<10>")
	)
	(segment
		(start 109.899704 -186.107578)
		(end 109.001306 -187.234322)
		(width 0.14732)
		(layer "In4.Cu")
		(net "UPI_CPU0_CPU1_P1P0_DP<10>")
	)
	(segment
		(start 108.747814 -187.747656)
		(end 108.576618 -187.76696)
		(width 0.14732)
		(layer "In4.Cu")
		(net "UPI_CPU0_CPU1_P1P0_DP<10>")
	)
	(segment
		(start 364.387384 -184.479692)
		(end 363.807756 -183.080152)
		(width 0.14732)
		(layer "In4.Cu")
		(net "UPI_CPU0_CPU1_P1P0_DP<10>")
	)
	(segment
		(start 98.765106 -217.388186)
		(end 98.765868 -217.388694)
		(width 0.0889)
		(layer "In4.Cu")
		(net "UPI_CPU0_CPU1_P1P0_DP<10>")
	)
	(segment
		(start 108.050838 -188.62167)
		(end 107.879642 -188.640974)
		(width 0.14732)
		(layer "In4.Cu")
		(net "UPI_CPU0_CPU1_P1P0_DP<10>")
	)
	(segment
		(start 372.543324 -213.230968)
		(end 372.543324 -213.055708)
		(width 0.0889)
		(layer "In4.Cu")
		(net "UPI_CPU0_CPU1_P1P0_DP<10>")
	)
	(segment
		(start 106.204766 -190.741046)
		(end 98.620326 -211.278978)
		(width 0.14732)
		(layer "In4.Cu")
		(net "UPI_CPU0_CPU1_P1P0_DP<10>")
	)
	(segment
		(start 372.454678 -215.761062)
		(end 372.455694 -215.760554)
		(width 0.0889)
		(layer "In4.Cu")
		(net "UPI_CPU0_CPU1_P1P0_DP<10>")
	)
	(segment
		(start 364.973616 -185.380884)
		(end 364.895638 -184.987946)
		(width 0.14732)
		(layer "In4.Cu")
		(net "UPI_CPU0_CPU1_P1P0_DP<10>")
	)
	(segment
		(start 362.524802 -179.98313)
		(end 358.40543 -170.038014)
		(width 0.14732)
		(layer "In4.Cu")
		(net "UPI_CPU0_CPU1_P1P0_DP<10>")
	)
	(segment
		(start 372.543324 -212.583268)
		(end 372.543324 -212.408008)
		(width 0.0889)
		(layer "In4.Cu")
		(net "UPI_CPU0_CPU1_P1P0_DP<10>")
	)
	(segment
		(start 107.879642 -188.640974)
		(end 107.607354 -188.98235)
		(width 0.14732)
		(layer "In4.Cu")
		(net "UPI_CPU0_CPU1_P1P0_DP<10>")
	)
	(segment
		(start 257.359404 -145.498566)
		(end 257.359658 -145.49882)
		(width 0.14732)
		(layer "In4.Cu")
		(net "UPI_CPU0_CPU1_P1P0_DP<10>")
	)
	(segment
		(start 372.924832 -214.946992)
		(end 372.933722 -214.941912)
		(width 0.0889)
		(layer "In4.Cu")
		(net "UPI_CPU0_CPU1_P1P0_DP<10>")
	)
	(segment
		(start 365.174022 -186.387486)
		(end 365.102394 -186.026298)
		(width 0.14732)
		(layer "In4.Cu")
		(net "UPI_CPU0_CPU1_P1P0_DP<10>")
	)
	(segment
		(start 372.600474 -206.062326)
		(end 365.842804 -189.74816)
		(width 0.14732)
		(layer "In4.Cu")
		(net "UPI_CPU0_CPU1_P1P0_DP<10>")
	)
	(segment
		(start 365.132112 -186.919108)
		(end 365.060484 -186.557666)
		(width 0.14732)
		(layer "In4.Cu")
		(net "UPI_CPU0_CPU1_P1P0_DP<10>")
	)
	(segment
		(start 372.642384 -211.7344)
		(end 372.600474 -211.69249)
		(width 0.0889)
		(layer "In4.Cu")
		(net "UPI_CPU0_CPU1_P1P0_DP<10>")
	)
	(segment
		(start 98.756724 -215.755982)
		(end 98.758756 -215.757252)
		(width 0.0889)
		(layer "In4.Cu")
		(net "UPI_CPU0_CPU1_P1P0_DP<10>")
	)
	(segment
		(start 107.353862 -189.495684)
		(end 107.182666 -189.514988)
		(width 0.14732)
		(layer "In4.Cu")
		(net "UPI_CPU0_CPU1_P1P0_DP<10>")
	)
	(segment
		(start 364.860078 -185.551064)
		(end 364.973616 -185.380884)
		(width 0.14732)
		(layer "In4.Cu")
		(net "UPI_CPU0_CPU1_P1P0_DP<10>")
	)
	(segment
		(start 372.455694 -216.740486)
		(end 372.454678 -216.739978)
		(width 0.0889)
		(layer "In4.Cu")
		(net "UPI_CPU0_CPU1_P1P0_DP<10>")
	)
	(segment
		(start 98.758756 -215.757252)
		(end 98.765614 -215.761062)
		(width 0.0889)
		(layer "In4.Cu")
		(net "UPI_CPU0_CPU1_P1P0_DP<10>")
	)
	(segment
		(start 372.642384 -212.956648)
		(end 372.642384 -212.682328)
		(width 0.0889)
		(layer "In4.Cu")
		(net "UPI_CPU0_CPU1_P1P0_DP<10>")
	)
	(segment
		(start 257.359658 -145.49882)
		(end 238.598202 -145.836386)
		(width 0.14732)
		(layer "In4.Cu")
		(net "UPI_CPU0_CPU1_P1P0_DP<10>")
	)
	(segment
		(start 372.642384 -212.682328)
		(end 372.543324 -212.583268)
		(width 0.0889)
		(layer "In4.Cu")
		(net "UPI_CPU0_CPU1_P1P0_DP<10>")
	)
	(segment
		(start 98.768408 -215.76284)
		(end 98.77171 -215.764618)
		(width 0.0889)
		(layer "In4.Cu")
		(net "UPI_CPU0_CPU1_P1P0_DP<10>")
	)
	(segment
		(start 98.620326 -211.813648)
		(end 98.62058 -211.813902)
		(width 0.14732)
		(layer "In4.Cu")
		(net "UPI_CPU0_CPU1_P1P0_DP<10>")
	)
	(segment
		(start 363.556042 -181.652418)
		(end 363.366812 -181.574186)
		(width 0.14732)
		(layer "In4.Cu")
		(net "UPI_CPU0_CPU1_P1P0_DP<10>")
	)
	(segment
		(start 364.93196 -185.912506)
		(end 364.860078 -185.551064)
		(width 0.14732)
		(layer "In4.Cu")
		(net "UPI_CPU0_CPU1_P1P0_DP<10>")
	)
	(segment
		(start 328.280522 -149.255226)
		(end 317.720218 -146.667728)
		(width 0.14732)
		(layer "In4.Cu")
		(net "UPI_CPU0_CPU1_P1P0_DP<10>")
	)
	(segment
		(start 314.867798 -146.667728)
		(end 276.121368 -145.161)
		(width 0.14732)
		(layer "In4.Cu")
		(net "UPI_CPU0_CPU1_P1P0_DP<10>")
	)
	(segment
		(start 108.576618 -187.76696)
		(end 108.30433 -188.108336)
		(width 0.14732)
		(layer "In4.Cu")
		(net "UPI_CPU0_CPU1_P1P0_DP<10>")
	)
	(segment
		(start 372.463568 -216.745058)
		(end 372.455694 -216.740486)
		(width 0.0889)
		(layer "In4.Cu")
		(net "UPI_CPU0_CPU1_P1P0_DP<10>")
	)
	(segment
		(start 98.765614 -215.761062)
		(end 98.767138 -215.762078)
		(width 0.0889)
		(layer "In4.Cu")
		(net "UPI_CPU0_CPU1_P1P0_DP<10>")
	)
	(arc
		(start 373.112284 -214.461852)
		(mid 373.037213 -214.34611)
		(end 372.92788 -214.261954)
		(width 0.0889)
		(layer "In4.Cu")
		(net "UPI_CPU0_CPU1_P1P0_DP<10>")
	)
	(arc
		(start 98.578416 -213.893908)
		(mid 98.653421 -214.009367)
		(end 98.762566 -214.093298)
		(width 0.0889)
		(layer "In4.Cu")
		(net "UPI_CPU0_CPU1_P1P0_DP<10>")
	)
	(arc
		(start 98.756978 -216.745058)
		(mid 98.578381 -217.064336)
		(end 98.756978 -217.383614)
		(width 0.0889)
		(layer "In4.Cu")
		(net "UPI_CPU0_CPU1_P1P0_DP<10>")
	)
	(arc
		(start 98.756724 -215.117426)
		(mid 98.62947 -215.247392)
		(end 98.578416 -215.421972)
		(width 0.0889)
		(layer "In4.Cu")
		(net "UPI_CPU0_CPU1_P1P0_DP<10>")
	)
	(arc
		(start 372.502176 -217.356182)
		(mid 372.605321 -217.226157)
		(end 372.64213 -217.064336)
		(width 0.0889)
		(layer "In4.Cu")
		(net "UPI_CPU0_CPU1_P1P0_DP<10>")
	)
	(arc
		(start 98.77171 -215.764618)
		(mid 98.974297 -215.970969)
		(end 99.048316 -216.25052)
		(width 0.0889)
		(layer "In4.Cu")
		(net "UPI_CPU0_CPU1_P1P0_DP<10>")
	)
	(arc
		(start 98.765868 -217.388694)
		(mid 98.968154 -217.587675)
		(end 99.048316 -217.859864)
		(width 0.0889)
		(layer "In4.Cu")
		(net "UPI_CPU0_CPU1_P1P0_DP<10>")
	)
	(arc
		(start 372.172484 -216.235026)
		(mid 372.251854 -215.961292)
		(end 372.454678 -215.761062)
		(width 0.0889)
		(layer "In4.Cu")
		(net "UPI_CPU0_CPU1_P1P0_DP<10>")
	)
	(arc
		(start 99.048316 -217.878406)
		(mid 98.992961 -218.122593)
		(end 98.837496 -218.318842)
		(width 0.0889)
		(layer "In4.Cu")
		(net "UPI_CPU0_CPU1_P1P0_DP<10>")
	)
	(arc
		(start 98.578416 -215.421972)
		(mid 98.578219 -215.429337)
		(end 98.578162 -215.436704)
		(width 0.0889)
		(layer "In4.Cu")
		(net "UPI_CPU0_CPU1_P1P0_DP<10>")
	)
	(arc
		(start 372.64213 -217.064336)
		(mid 372.594451 -216.881436)
		(end 372.463568 -216.745058)
		(width 0.0889)
		(layer "In4.Cu")
		(net "UPI_CPU0_CPU1_P1P0_DP<10>")
	)
	(arc
		(start 372.454678 -216.739978)
		(mid 372.251855 -216.539747)
		(end 372.172484 -216.266014)
		(width 0.0889)
		(layer "In4.Cu")
		(net "UPI_CPU0_CPU1_P1P0_DP<10>")
	)
	(arc
		(start 372.92788 -214.261954)
		(mid 372.767525 -214.138568)
		(end 372.65737 -213.968838)
		(width 0.0889)
		(layer "In4.Cu")
		(net "UPI_CPU0_CPU1_P1P0_DP<10>")
	)
	(arc
		(start 98.837496 -218.318842)
		(mid 98.82905 -218.325527)
		(end 98.820478 -218.33205)
		(width 0.0889)
		(layer "In4.Cu")
		(net "UPI_CPU0_CPU1_P1P0_DP<10>")
	)
	(arc
		(start 372.65737 -213.968838)
		(mid 372.649548 -213.949662)
		(end 372.642384 -213.93023)
		(width 0.0889)
		(layer "In4.Cu")
		(net "UPI_CPU0_CPU1_P1P0_DP<10>")
	)
	(arc
		(start 99.047808 -214.644732)
		(mid 98.966897 -214.91486)
		(end 98.765614 -215.112346)
		(width 0.0889)
		(layer "In4.Cu")
		(net "UPI_CPU0_CPU1_P1P0_DP<10>")
	)
	(arc
		(start 372.463568 -215.755982)
		(mid 372.594482 -215.619622)
		(end 372.64213 -215.436704)
		(width 0.0889)
		(layer "In4.Cu")
		(net "UPI_CPU0_CPU1_P1P0_DP<10>")
	)
	(arc
		(start 98.762566 -214.093298)
		(mid 98.936529 -214.232062)
		(end 99.047808 -214.424768)
		(width 0.0889)
		(layer "In4.Cu")
		(net "UPI_CPU0_CPU1_P1P0_DP<10>")
	)
	(arc
		(start 372.64213 -215.436704)
		(mid 372.714303 -215.160036)
		(end 372.91264 -214.954104)
		(width 0.0889)
		(layer "In4.Cu")
		(net "UPI_CPU0_CPU1_P1P0_DP<10>")
	)
	(arc
		(start 99.048316 -216.260426)
		(mid 98.970205 -216.537375)
		(end 98.765868 -216.739978)
		(width 0.0889)
		(layer "In4.Cu")
		(net "UPI_CPU0_CPU1_P1P0_DP<10>")
	)
	(arc
		(start 372.933722 -214.941912)
		(mid 373.064636 -214.805552)
		(end 373.112284 -214.622634)
		(width 0.0889)
		(layer "In4.Cu")
		(net "UPI_CPU0_CPU1_P1P0_DP<10>")
	)
	(arc
		(start 98.578162 -215.436704)
		(mid 98.625841 -215.619604)
		(end 98.756724 -215.755982)
		(width 0.0889)
		(layer "In4.Cu")
		(net "UPI_CPU0_CPU1_P1P0_DP<10>")
	)
	(segment
		(start 381.665734 -217.06459)
		(end 381.66548 -217.064336)
		(width 0.13208)
		(layer "F.Cu")
		(net "UPI_CPU0_CPU1_P1P0_DP<0>")
	)
	(segment
		(start 381.665734 -217.600276)
		(end 381.665734 -217.06459)
		(width 0.13208)
		(layer "F.Cu")
		(net "UPI_CPU0_CPU1_P1P0_DP<0>")
	)
	(segment
		(start 89.555066 -218.692476)
		(end 89.554812 -218.692222)
		(width 0.13208)
		(layer "F.Cu")
		(net "UPI_CPU0_CPU1_P1P0_DP<0>")
	)
	(segment
		(start 89.555066 -219.228162)
		(end 89.555066 -218.692476)
		(width 0.13208)
		(layer "F.Cu")
		(net "UPI_CPU0_CPU1_P1P0_DP<0>")
	)
	(segment
		(start 370.812822 -164.953696)
		(end 372.084854 -165.543738)
		(width 0.14732)
		(layer "In4.Cu")
		(net "UPI_CPU0_CPU1_P1P0_DP<0>")
	)
	(segment
		(start 89.142316 -213.840568)
		(end 89.142316 -211.845652)
		(width 0.0889)
		(layer "In4.Cu")
		(net "UPI_CPU0_CPU1_P1P0_DP<0>")
	)
	(segment
		(start 86.949026 -208.939638)
		(end 86.744302 -208.939638)
		(width 0.14732)
		(layer "In4.Cu")
		(net "UPI_CPU0_CPU1_P1P0_DP<0>")
	)
	(segment
		(start 89.650316 -217.878406)
		(end 89.650316 -217.859864)
		(width 0.0889)
		(layer "In4.Cu")
		(net "UPI_CPU0_CPU1_P1P0_DP<0>")
	)
	(segment
		(start 89.367614 -215.761062)
		(end 89.358724 -215.755982)
		(width 0.0889)
		(layer "In4.Cu")
		(net "UPI_CPU0_CPU1_P1P0_DP<0>")
	)
	(segment
		(start 89.649808 -214.644732)
		(end 89.649808 -214.34806)
		(width 0.0889)
		(layer "In4.Cu")
		(net "UPI_CPU0_CPU1_P1P0_DP<0>")
	)
	(segment
		(start 372.084854 -165.543738)
		(end 372.41988 -165.989508)
		(width 0.14732)
		(layer "In4.Cu")
		(net "UPI_CPU0_CPU1_P1P0_DP<0>")
	)
	(segment
		(start 95.908622 -192.226438)
		(end 98.102674 -186.392058)
		(width 0.14732)
		(layer "In4.Cu")
		(net "UPI_CPU0_CPU1_P1P0_DP<0>")
	)
	(segment
		(start 383.008632 -211.93125)
		(end 383.008632 -211.953348)
		(width 0.0889)
		(layer "In4.Cu")
		(net "UPI_CPU0_CPU1_P1P0_DP<0>")
	)
	(segment
		(start 382.801368 -215.755982)
		(end 382.792478 -215.761062)
		(width 0.0889)
		(layer "In4.Cu")
		(net "UPI_CPU0_CPU1_P1P0_DP<0>")
	)
	(segment
		(start 376.555508 -170.256708)
		(end 377.010422 -170.97121)
		(width 0.14732)
		(layer "In4.Cu")
		(net "UPI_CPU0_CPU1_P1P0_DP<0>")
	)
	(segment
		(start 382.418082 -215.761062)
		(end 382.40335 -215.752426)
		(width 0.0889)
		(layer "In4.Cu")
		(net "UPI_CPU0_CPU1_P1P0_DP<0>")
	)
	(segment
		(start 88.198452 -210.393788)
		(end 87.935308 -210.130644)
		(width 0.14732)
		(layer "In4.Cu")
		(net "UPI_CPU0_CPU1_P1P0_DP<0>")
	)
	(segment
		(start 85.415882 -207.024478)
		(end 85.380576 -205.919832)
		(width 0.14732)
		(layer "In4.Cu")
		(net "UPI_CPU0_CPU1_P1P0_DP<0>")
	)
	(segment
		(start 85.65388 -204.41285)
		(end 95.908622 -192.226438)
		(width 0.14732)
		(layer "In4.Cu")
		(net "UPI_CPU0_CPU1_P1P0_DP<0>")
	)
	(segment
		(start 382.510538 -214.123778)
		(end 382.510538 -214.743284)
		(width 0.0889)
		(layer "In4.Cu")
		(net "UPI_CPU0_CPU1_P1P0_DP<0>")
	)
	(segment
		(start 88.66378 -210.859116)
		(end 88.66378 -210.654392)
		(width 0.14732)
		(layer "In4.Cu")
		(net "UPI_CPU0_CPU1_P1P0_DP<0>")
	)
	(segment
		(start 365.443008 -162.621976)
		(end 365.777272 -162.776916)
		(width 0.14732)
		(layer "In4.Cu")
		(net "UPI_CPU0_CPU1_P1P0_DP<0>")
	)
	(segment
		(start 381.821944 -217.335354)
		(end 381.66548 -217.064336)
		(width 0.0889)
		(layer "In4.Cu")
		(net "UPI_CPU0_CPU1_P1P0_DP<0>")
	)
	(segment
		(start 98.102674 -186.392058)
		(end 102.05085 -181.478174)
		(width 0.14732)
		(layer "In4.Cu")
		(net "UPI_CPU0_CPU1_P1P0_DP<0>")
	)
	(segment
		(start 366.373918 -163.05403)
		(end 366.708182 -163.20897)
		(width 0.14732)
		(layer "In4.Cu")
		(net "UPI_CPU0_CPU1_P1P0_DP<0>")
	)
	(segment
		(start 386.359654 -202.321922)
		(end 386.359654 -206.48295)
		(width 0.14732)
		(layer "In4.Cu")
		(net "UPI_CPU0_CPU1_P1P0_DP<0>")
	)
	(segment
		(start 102.05085 -181.478174)
		(end 122.98299 -161.795206)
		(width 0.14732)
		(layer "In4.Cu")
		(net "UPI_CPU0_CPU1_P1P0_DP<0>")
	)
	(segment
		(start 89.184226 -211.630768)
		(end 89.184226 -211.379562)
		(width 0.14732)
		(layer "In4.Cu")
		(net "UPI_CPU0_CPU1_P1P0_DP<0>")
	)
	(segment
		(start 383.058416 -189.821566)
		(end 383.550414 -192.38722)
		(width 0.14732)
		(layer "In4.Cu")
		(net "UPI_CPU0_CPU1_P1P0_DP<0>")
	)
	(segment
		(start 89.358724 -215.117426)
		(end 89.366598 -215.112854)
		(width 0.0889)
		(layer "In4.Cu")
		(net "UPI_CPU0_CPU1_P1P0_DP<0>")
	)
	(segment
		(start 368.42446 -164.005514)
		(end 368.758978 -164.160454)
		(width 0.14732)
		(layer "In4.Cu")
		(net "UPI_CPU0_CPU1_P1P0_DP<0>")
	)
	(segment
		(start 383.050542 -213.583774)
		(end 382.510538 -214.123778)
		(width 0.0889)
		(layer "In4.Cu")
		(net "UPI_CPU0_CPU1_P1P0_DP<0>")
	)
	(segment
		(start 89.180162 -215.446864)
		(end 89.180162 -215.422226)
		(width 0.0889)
		(layer "In4.Cu")
		(net "UPI_CPU0_CPU1_P1P0_DP<0>")
	)
	(segment
		(start 381.570484 -216.235026)
		(end 381.570484 -216.266014)
		(width 0.0889)
		(layer "In4.Cu")
		(net "UPI_CPU0_CPU1_P1P0_DP<0>")
	)
	(segment
		(start 87.46998 -209.665316)
		(end 87.20963 -209.404966)
		(width 0.14732)
		(layer "In4.Cu")
		(net "UPI_CPU0_CPU1_P1P0_DP<0>")
	)
	(segment
		(start 385.653788 -208.186528)
		(end 383.008378 -210.831938)
		(width 0.14732)
		(layer "In4.Cu")
		(net "UPI_CPU0_CPU1_P1P0_DP<0>")
	)
	(segment
		(start 370.620544 -165.024308)
		(end 370.812822 -164.953696)
		(width 0.14732)
		(layer "In4.Cu")
		(net "UPI_CPU0_CPU1_P1P0_DP<0>")
	)
	(segment
		(start 369.285012 -164.245036)
		(end 369.35537 -164.437568)
		(width 0.14732)
		(layer "In4.Cu")
		(net "UPI_CPU0_CPU1_P1P0_DP<0>")
	)
	(segment
		(start 383.050542 -211.995258)
		(end 383.050542 -213.583774)
		(width 0.0889)
		(layer "In4.Cu")
		(net "UPI_CPU0_CPU1_P1P0_DP<0>")
	)
	(segment
		(start 368.758978 -164.160454)
		(end 368.951002 -164.090096)
		(width 0.14732)
		(layer "In4.Cu")
		(net "UPI_CPU0_CPU1_P1P0_DP<0>")
	)
	(segment
		(start 382.26492 -188.769752)
		(end 383.058416 -189.821566)
		(width 0.14732)
		(layer "In4.Cu")
		(net "UPI_CPU0_CPU1_P1P0_DP<0>")
	)
	(segment
		(start 361.812586 -160.777936)
		(end 365.372396 -162.429444)
		(width 0.14732)
		(layer "In4.Cu")
		(net "UPI_CPU0_CPU1_P1P0_DP<0>")
	)
	(segment
		(start 169.739818 -135.795766)
		(end 238.601758 -136.926828)
		(width 0.14732)
		(layer "In4.Cu")
		(net "UPI_CPU0_CPU1_P1P0_DP<0>")
	)
	(segment
		(start 383.008632 -211.694522)
		(end 383.008632 -211.93125)
		(width 0.14732)
		(layer "In4.Cu")
		(net "UPI_CPU0_CPU1_P1P0_DP<0>")
	)
	(segment
		(start 87.20963 -209.404966)
		(end 87.20963 -209.200242)
		(width 0.14732)
		(layer "In4.Cu")
		(net "UPI_CPU0_CPU1_P1P0_DP<0>")
	)
	(segment
		(start 89.18448 -211.78139)
		(end 89.18448 -211.631022)
		(width 0.14732)
		(layer "In4.Cu")
		(net "UPI_CPU0_CPU1_P1P0_DP<0>")
	)
	(segment
		(start 270.593058 -136.342628)
		(end 316.267084 -138.262868)
		(width 0.14732)
		(layer "In4.Cu")
		(net "UPI_CPU0_CPU1_P1P0_DP<0>")
	)
	(segment
		(start 85.925406 -208.120742)
		(end 85.415882 -207.024478)
		(width 0.14732)
		(layer "In4.Cu")
		(net "UPI_CPU0_CPU1_P1P0_DP<0>")
	)
	(segment
		(start 89.18448 -211.631022)
		(end 89.184226 -211.630768)
		(width 0.14732)
		(layer "In4.Cu")
		(net "UPI_CPU0_CPU1_P1P0_DP<0>")
	)
	(segment
		(start 89.367614 -216.739978)
		(end 89.37371 -216.736422)
		(width 0.0889)
		(layer "In4.Cu")
		(net "UPI_CPU0_CPU1_P1P0_DP<0>")
	)
	(segment
		(start 85.380576 -205.919832)
		(end 85.65388 -204.41285)
		(width 0.14732)
		(layer "In4.Cu")
		(net "UPI_CPU0_CPU1_P1P0_DP<0>")
	)
	(segment
		(start 159.618426 -139.261088)
		(end 169.739818 -135.795766)
		(width 0.14732)
		(layer "In4.Cu")
		(net "UPI_CPU0_CPU1_P1P0_DP<0>")
	)
	(segment
		(start 377.010422 -170.97121)
		(end 382.26492 -188.769752)
		(width 0.14732)
		(layer "In4.Cu")
		(net "UPI_CPU0_CPU1_P1P0_DP<0>")
	)
	(segment
		(start 89.364312 -216.741756)
		(end 89.367614 -216.739978)
		(width 0.0889)
		(layer "In4.Cu")
		(net "UPI_CPU0_CPU1_P1P0_DP<0>")
	)
	(segment
		(start 369.35537 -164.437568)
		(end 369.689634 -164.592508)
		(width 0.14732)
		(layer "In4.Cu")
		(net "UPI_CPU0_CPU1_P1P0_DP<0>")
	)
	(segment
		(start 372.41988 -165.989508)
		(end 372.51894 -166.815008)
		(width 0.14732)
		(layer "In4.Cu")
		(net "UPI_CPU0_CPU1_P1P0_DP<0>")
	)
	(segment
		(start 89.142316 -211.845652)
		(end 89.18448 -211.803488)
		(width 0.0889)
		(layer "In4.Cu")
		(net "UPI_CPU0_CPU1_P1P0_DP<0>")
	)
	(segment
		(start 382.510538 -214.743284)
		(end 382.510284 -214.743538)
		(width 0.0889)
		(layer "In4.Cu")
		(net "UPI_CPU0_CPU1_P1P0_DP<0>")
	)
	(segment
		(start 386.359654 -206.48295)
		(end 385.653788 -208.186528)
		(width 0.14732)
		(layer "In4.Cu")
		(net "UPI_CPU0_CPU1_P1P0_DP<0>")
	)
	(segment
		(start 88.66378 -210.654392)
		(end 88.403176 -210.393788)
		(width 0.14732)
		(layer "In4.Cu")
		(net "UPI_CPU0_CPU1_P1P0_DP<0>")
	)
	(segment
		(start 367.639092 -163.641024)
		(end 367.83137 -163.570666)
		(width 0.14732)
		(layer "In4.Cu")
		(net "UPI_CPU0_CPU1_P1P0_DP<0>")
	)
	(segment
		(start 366.30356 -162.861498)
		(end 366.373918 -163.05403)
		(width 0.14732)
		(layer "In4.Cu")
		(net "UPI_CPU0_CPU1_P1P0_DP<0>")
	)
	(segment
		(start 122.98299 -161.795206)
		(end 159.618426 -139.261088)
		(width 0.14732)
		(layer "In4.Cu")
		(net "UPI_CPU0_CPU1_P1P0_DP<0>")
	)
	(segment
		(start 86.744302 -208.939638)
		(end 85.925406 -208.120742)
		(width 0.14732)
		(layer "In4.Cu")
		(net "UPI_CPU0_CPU1_P1P0_DP<0>")
	)
	(segment
		(start 89.37371 -215.764618)
		(end 89.367614 -215.761062)
		(width 0.0889)
		(layer "In4.Cu")
		(net "UPI_CPU0_CPU1_P1P0_DP<0>")
	)
	(segment
		(start 367.304828 -163.486084)
		(end 367.639092 -163.641024)
		(width 0.14732)
		(layer "In4.Cu")
		(net "UPI_CPU0_CPU1_P1P0_DP<0>")
	)
	(segment
		(start 316.267084 -138.262868)
		(end 318.737996 -138.262868)
		(width 0.14732)
		(layer "In4.Cu")
		(net "UPI_CPU0_CPU1_P1P0_DP<0>")
	)
	(segment
		(start 368.951002 -164.090096)
		(end 369.285012 -164.245036)
		(width 0.14732)
		(layer "In4.Cu")
		(net "UPI_CPU0_CPU1_P1P0_DP<0>")
	)
	(segment
		(start 383.008632 -211.953348)
		(end 383.050542 -211.995258)
		(width 0.0889)
		(layer "In4.Cu")
		(net "UPI_CPU0_CPU1_P1P0_DP<0>")
	)
	(segment
		(start 87.935308 -210.130644)
		(end 87.935308 -209.92592)
		(width 0.14732)
		(layer "In4.Cu")
		(net "UPI_CPU0_CPU1_P1P0_DP<0>")
	)
	(segment
		(start 367.23447 -163.293552)
		(end 367.304828 -163.486084)
		(width 0.14732)
		(layer "In4.Cu")
		(net "UPI_CPU0_CPU1_P1P0_DP<0>")
	)
	(segment
		(start 382.97993 -215.275922)
		(end 382.97993 -215.436704)
		(width 0.0889)
		(layer "In4.Cu")
		(net "UPI_CPU0_CPU1_P1P0_DP<0>")
	)
	(segment
		(start 367.83137 -163.570666)
		(end 368.354102 -163.812982)
		(width 0.14732)
		(layer "In4.Cu")
		(net "UPI_CPU0_CPU1_P1P0_DP<0>")
	)
	(segment
		(start 365.96955 -162.706558)
		(end 366.30356 -162.861498)
		(width 0.14732)
		(layer "In4.Cu")
		(net "UPI_CPU0_CPU1_P1P0_DP<0>")
	)
	(segment
		(start 89.18448 -211.803488)
		(end 89.18448 -211.78139)
		(width 0.0889)
		(layer "In4.Cu")
		(net "UPI_CPU0_CPU1_P1P0_DP<0>")
	)
	(segment
		(start 370.28628 -164.869368)
		(end 370.620544 -165.024308)
		(width 0.14732)
		(layer "In4.Cu")
		(net "UPI_CPU0_CPU1_P1P0_DP<0>")
	)
	(segment
		(start 381.853694 -216.740486)
		(end 381.861568 -216.745058)
		(width 0.0889)
		(layer "In4.Cu")
		(net "UPI_CPU0_CPU1_P1P0_DP<0>")
	)
	(segment
		(start 383.550414 -192.38722)
		(end 386.359654 -202.321922)
		(width 0.14732)
		(layer "In4.Cu")
		(net "UPI_CPU0_CPU1_P1P0_DP<0>")
	)
	(segment
		(start 365.777272 -162.776916)
		(end 365.96955 -162.706558)
		(width 0.14732)
		(layer "In4.Cu")
		(net "UPI_CPU0_CPU1_P1P0_DP<0>")
	)
	(segment
		(start 318.737996 -138.262868)
		(end 331.689202 -141.43355)
		(width 0.14732)
		(layer "In4.Cu")
		(net "UPI_CPU0_CPU1_P1P0_DP<0>")
	)
	(segment
		(start 369.689634 -164.592508)
		(end 369.881912 -164.521896)
		(width 0.14732)
		(layer "In4.Cu")
		(net "UPI_CPU0_CPU1_P1P0_DP<0>")
	)
	(segment
		(start 87.674704 -209.665316)
		(end 87.46998 -209.665316)
		(width 0.14732)
		(layer "In4.Cu")
		(net "UPI_CPU0_CPU1_P1P0_DP<0>")
	)
	(segment
		(start 372.51894 -166.815008)
		(end 373.08282 -167.782748)
		(width 0.14732)
		(layer "In4.Cu")
		(net "UPI_CPU0_CPU1_P1P0_DP<0>")
	)
	(segment
		(start 382.79578 -215.075516)
		(end 382.795526 -215.076024)
		(width 0.0889)
		(layer "In4.Cu")
		(net "UPI_CPU0_CPU1_P1P0_DP<0>")
	)
	(segment
		(start 88.403176 -210.393788)
		(end 88.198452 -210.393788)
		(width 0.14732)
		(layer "In4.Cu")
		(net "UPI_CPU0_CPU1_P1P0_DP<0>")
	)
	(segment
		(start 366.708182 -163.20897)
		(end 366.90046 -163.138612)
		(width 0.14732)
		(layer "In4.Cu")
		(net "UPI_CPU0_CPU1_P1P0_DP<0>")
	)
	(segment
		(start 89.649808 -214.34806)
		(end 89.142316 -213.840568)
		(width 0.0889)
		(layer "In4.Cu")
		(net "UPI_CPU0_CPU1_P1P0_DP<0>")
	)
	(segment
		(start 381.852678 -216.739978)
		(end 381.853694 -216.740486)
		(width 0.0889)
		(layer "In4.Cu")
		(net "UPI_CPU0_CPU1_P1P0_DP<0>")
	)
	(segment
		(start 383.008378 -211.694268)
		(end 383.008632 -211.694522)
		(width 0.14732)
		(layer "In4.Cu")
		(net "UPI_CPU0_CPU1_P1P0_DP<0>")
	)
	(segment
		(start 87.20963 -209.200242)
		(end 86.949026 -208.939638)
		(width 0.14732)
		(layer "In4.Cu")
		(net "UPI_CPU0_CPU1_P1P0_DP<0>")
	)
	(segment
		(start 238.601758 -136.926828)
		(end 270.593058 -136.342628)
		(width 0.14732)
		(layer "In4.Cu")
		(net "UPI_CPU0_CPU1_P1P0_DP<0>")
	)
	(segment
		(start 369.881912 -164.521896)
		(end 370.215922 -164.676836)
		(width 0.14732)
		(layer "In4.Cu")
		(net "UPI_CPU0_CPU1_P1P0_DP<0>")
	)
	(segment
		(start 89.184226 -211.379562)
		(end 88.66378 -210.859116)
		(width 0.14732)
		(layer "In4.Cu")
		(net "UPI_CPU0_CPU1_P1P0_DP<0>")
	)
	(segment
		(start 365.372396 -162.429444)
		(end 365.443008 -162.621976)
		(width 0.14732)
		(layer "In4.Cu")
		(net "UPI_CPU0_CPU1_P1P0_DP<0>")
	)
	(segment
		(start 89.367868 -217.388694)
		(end 89.358978 -217.383614)
		(width 0.0889)
		(layer "In4.Cu")
		(net "UPI_CPU0_CPU1_P1P0_DP<0>")
	)
	(segment
		(start 87.935308 -209.92592)
		(end 87.674704 -209.665316)
		(width 0.14732)
		(layer "In4.Cu")
		(net "UPI_CPU0_CPU1_P1P0_DP<0>")
	)
	(segment
		(start 331.689202 -141.43355)
		(end 361.812586 -160.777936)
		(width 0.14732)
		(layer "In4.Cu")
		(net "UPI_CPU0_CPU1_P1P0_DP<0>")
	)
	(segment
		(start 368.354102 -163.812982)
		(end 368.42446 -164.005514)
		(width 0.14732)
		(layer "In4.Cu")
		(net "UPI_CPU0_CPU1_P1P0_DP<0>")
	)
	(segment
		(start 381.900176 -217.356182)
		(end 381.821944 -217.335354)
		(width 0.0889)
		(layer "In4.Cu")
		(net "UPI_CPU0_CPU1_P1P0_DP<0>")
	)
	(segment
		(start 366.90046 -163.138612)
		(end 367.23447 -163.293552)
		(width 0.14732)
		(layer "In4.Cu")
		(net "UPI_CPU0_CPU1_P1P0_DP<0>")
	)
	(segment
		(start 89.554812 -218.692222)
		(end 89.398348 -218.421204)
		(width 0.0889)
		(layer "In4.Cu")
		(net "UPI_CPU0_CPU1_P1P0_DP<0>")
	)
	(segment
		(start 89.398348 -218.421204)
		(end 89.422478 -218.33205)
		(width 0.0889)
		(layer "In4.Cu")
		(net "UPI_CPU0_CPU1_P1P0_DP<0>")
	)
	(segment
		(start 370.215922 -164.676836)
		(end 370.28628 -164.869368)
		(width 0.14732)
		(layer "In4.Cu")
		(net "UPI_CPU0_CPU1_P1P0_DP<0>")
	)
	(segment
		(start 89.180162 -215.422226)
		(end 89.180416 -215.421972)
		(width 0.0889)
		(layer "In4.Cu")
		(net "UPI_CPU0_CPU1_P1P0_DP<0>")
	)
	(segment
		(start 383.008378 -210.831938)
		(end 383.008378 -211.694268)
		(width 0.14732)
		(layer "In4.Cu")
		(net "UPI_CPU0_CPU1_P1P0_DP<0>")
	)
	(segment
		(start 373.08282 -167.782748)
		(end 376.555508 -170.256708)
		(width 0.14732)
		(layer "In4.Cu")
		(net "UPI_CPU0_CPU1_P1P0_DP<0>")
	)
	(segment
		(start 89.366598 -215.112854)
		(end 89.367614 -215.112346)
		(width 0.0889)
		(layer "In4.Cu")
		(net "UPI_CPU0_CPU1_P1P0_DP<0>")
	)
	(arc
		(start 89.180416 -217.064336)
		(mid 89.229617 -216.878674)
		(end 89.364312 -216.741756)
		(width 0.0889)
		(layer "In4.Cu")
		(net "UPI_CPU0_CPU1_P1P0_DP<0>")
	)
	(arc
		(start 89.358978 -217.383614)
		(mid 89.228064 -217.247254)
		(end 89.180416 -217.064336)
		(width 0.0889)
		(layer "In4.Cu")
		(net "UPI_CPU0_CPU1_P1P0_DP<0>")
	)
	(arc
		(start 382.04013 -217.064336)
		(mid 382.00327 -217.226133)
		(end 381.900176 -217.356182)
		(width 0.0889)
		(layer "In4.Cu")
		(net "UPI_CPU0_CPU1_P1P0_DP<0>")
	)
	(arc
		(start 381.570484 -216.266014)
		(mid 381.649854 -216.539748)
		(end 381.852678 -216.739978)
		(width 0.0889)
		(layer "In4.Cu")
		(net "UPI_CPU0_CPU1_P1P0_DP<0>")
	)
	(arc
		(start 89.650316 -217.859864)
		(mid 89.570154 -217.587675)
		(end 89.367868 -217.388694)
		(width 0.0889)
		(layer "In4.Cu")
		(net "UPI_CPU0_CPU1_P1P0_DP<0>")
	)
	(arc
		(start 382.525778 -214.783416)
		(mid 382.635792 -214.952564)
		(end 382.79578 -215.075516)
		(width 0.0889)
		(layer "In4.Cu")
		(net "UPI_CPU0_CPU1_P1P0_DP<0>")
	)
	(arc
		(start 89.180416 -215.421972)
		(mid 89.23147 -215.247392)
		(end 89.358724 -215.117426)
		(width 0.0889)
		(layer "In4.Cu")
		(net "UPI_CPU0_CPU1_P1P0_DP<0>")
	)
	(arc
		(start 382.510284 -214.743538)
		(mid 382.517673 -214.763616)
		(end 382.525778 -214.783416)
		(width 0.0889)
		(layer "In4.Cu")
		(net "UPI_CPU0_CPU1_P1P0_DP<0>")
	)
	(arc
		(start 382.795526 -215.076024)
		(mid 382.904922 -215.160121)
		(end 382.97993 -215.275922)
		(width 0.0889)
		(layer "In4.Cu")
		(net "UPI_CPU0_CPU1_P1P0_DP<0>")
	)
	(arc
		(start 89.37371 -216.736422)
		(mid 89.650036 -216.25052)
		(end 89.37371 -215.764618)
		(width 0.0889)
		(layer "In4.Cu")
		(net "UPI_CPU0_CPU1_P1P0_DP<0>")
	)
	(arc
		(start 89.367614 -215.112346)
		(mid 89.568896 -214.914859)
		(end 89.649808 -214.644732)
		(width 0.0889)
		(layer "In4.Cu")
		(net "UPI_CPU0_CPU1_P1P0_DP<0>")
	)
	(arc
		(start 382.40335 -215.752426)
		(mid 382.126875 -215.685106)
		(end 381.852678 -215.761062)
		(width 0.0889)
		(layer "In4.Cu")
		(net "UPI_CPU0_CPU1_P1P0_DP<0>")
	)
	(arc
		(start 89.422478 -218.33205)
		(mid 89.43105 -218.325528)
		(end 89.439496 -218.318842)
		(width 0.0889)
		(layer "In4.Cu")
		(net "UPI_CPU0_CPU1_P1P0_DP<0>")
	)
	(arc
		(start 89.439496 -218.318842)
		(mid 89.594894 -218.122561)
		(end 89.650316 -217.878406)
		(width 0.0889)
		(layer "In4.Cu")
		(net "UPI_CPU0_CPU1_P1P0_DP<0>")
	)
	(arc
		(start 381.861568 -216.745058)
		(mid 381.992482 -216.881418)
		(end 382.04013 -217.064336)
		(width 0.0889)
		(layer "In4.Cu")
		(net "UPI_CPU0_CPU1_P1P0_DP<0>")
	)
	(arc
		(start 382.792478 -215.761062)
		(mid 382.60528 -215.811205)
		(end 382.418082 -215.761062)
		(width 0.0889)
		(layer "In4.Cu")
		(net "UPI_CPU0_CPU1_P1P0_DP<0>")
	)
	(arc
		(start 382.97993 -215.436704)
		(mid 382.932251 -215.619604)
		(end 382.801368 -215.755982)
		(width 0.0889)
		(layer "In4.Cu")
		(net "UPI_CPU0_CPU1_P1P0_DP<0>")
	)
	(arc
		(start 381.852678 -215.761062)
		(mid 381.649855 -215.961293)
		(end 381.570484 -216.235026)
		(width 0.0889)
		(layer "In4.Cu")
		(net "UPI_CPU0_CPU1_P1P0_DP<0>")
	)
	(arc
		(start 89.358724 -215.755982)
		(mid 89.23032 -215.624037)
		(end 89.180162 -215.446864)
		(width 0.0889)
		(layer "In4.Cu")
		(net "UPI_CPU0_CPU1_P1P0_DP<0>")
	)
	(segment
		(start 373.67718 -218.414346)
		(end 373.67718 -217.87866)
		(width 0.13208)
		(layer "F.Cu")
		(net "UPI_CPU0_CPU1_P1P0_DN<9>")
	)
	(segment
		(start 97.543112 -217.87866)
		(end 97.543366 -217.878406)
		(width 0.13208)
		(layer "F.Cu")
		(net "UPI_CPU0_CPU1_P1P0_DN<9>")
	)
	(segment
		(start 373.67718 -217.87866)
		(end 373.677434 -217.878406)
		(width 0.13208)
		(layer "F.Cu")
		(net "UPI_CPU0_CPU1_P1P0_DN<9>")
	)
	(segment
		(start 97.543112 -218.414346)
		(end 97.543112 -217.87866)
		(width 0.13208)
		(layer "F.Cu")
		(net "UPI_CPU0_CPU1_P1P0_DN<9>")
	)
	(segment
		(start 373.871744 -212.64372)
		(end 373.871744 -212.46846)
		(width 0.0889)
		(layer "In4.Cu")
		(net "UPI_CPU0_CPU1_P1P0_DN<9>")
	)
	(segment
		(start 97.406206 -211.933028)
		(end 97.448116 -211.974938)
		(width 0.0889)
		(layer "In4.Cu")
		(net "UPI_CPU0_CPU1_P1P0_DN<9>")
	)
	(segment
		(start 97.405952 -211.552028)
		(end 97.406206 -211.552282)
		(width 0.14732)
		(layer "In4.Cu")
		(net "UPI_CPU0_CPU1_P1P0_DN<9>")
	)
	(segment
		(start 97.406206 -211.91093)
		(end 97.406206 -211.933028)
		(width 0.0889)
		(layer "In4.Cu")
		(net "UPI_CPU0_CPU1_P1P0_DN<9>")
	)
	(segment
		(start 373.871744 -212.46846)
		(end 373.772684 -212.3694)
		(width 0.0889)
		(layer "In4.Cu")
		(net "UPI_CPU0_CPU1_P1P0_DN<9>")
	)
	(segment
		(start 373.772684 -212.74278)
		(end 373.871744 -212.64372)
		(width 0.0889)
		(layer "In4.Cu")
		(net "UPI_CPU0_CPU1_P1P0_DN<9>")
	)
	(segment
		(start 373.677434 -217.878406)
		(end 373.52097 -218.149424)
		(width 0.0889)
		(layer "In4.Cu")
		(net "UPI_CPU0_CPU1_P1P0_DN<9>")
	)
	(segment
		(start 373.814848 -211.783168)
		(end 373.814848 -211.76107)
		(width 0.0889)
		(layer "In4.Cu")
		(net "UPI_CPU0_CPU1_P1P0_DN<9>")
	)
	(segment
		(start 365.736124 -182.560976)
		(end 365.736378 -182.560976)
		(width 0.14732)
		(layer "In4.Cu")
		(net "UPI_CPU0_CPU1_P1P0_DN<9>")
	)
	(segment
		(start 373.772684 -211.825332)
		(end 373.814848 -211.783168)
		(width 0.0889)
		(layer "In4.Cu")
		(net "UPI_CPU0_CPU1_P1P0_DN<9>")
	)
	(segment
		(start 365.736378 -182.560976)
		(end 365.736124 -182.560722)
		(width 0.14732)
		(layer "In4.Cu")
		(net "UPI_CPU0_CPU1_P1P0_DN<9>")
	)
	(segment
		(start 373.772684 -212.91804)
		(end 373.772684 -212.74278)
		(width 0.0889)
		(layer "In4.Cu")
		(net "UPI_CPU0_CPU1_P1P0_DN<9>")
	)
	(segment
		(start 328.724514 -148.220684)
		(end 317.886588 -145.565622)
		(width 0.14732)
		(layer "In4.Cu")
		(net "UPI_CPU0_CPU1_P1P0_DN<9>")
	)
	(segment
		(start 162.540442 -146.08175)
		(end 128.63449 -166.943786)
		(width 0.14732)
		(layer "In4.Cu")
		(net "UPI_CPU0_CPU1_P1P0_DN<9>")
	)
	(segment
		(start 97.917508 -214.461344)
		(end 97.917508 -214.622634)
		(width 0.0889)
		(layer "In4.Cu")
		(net "UPI_CPU0_CPU1_P1P0_DN<9>")
	)
	(segment
		(start 373.814594 -206.028798)
		(end 373.793766 -206.00797)
		(width 0.14732)
		(layer "In4.Cu")
		(net "UPI_CPU0_CPU1_P1P0_DN<9>")
	)
	(segment
		(start 97.738946 -214.941912)
		(end 97.730056 -214.946992)
		(width 0.0889)
		(layer "In4.Cu")
		(net "UPI_CPU0_CPU1_P1P0_DN<9>")
	)
	(segment
		(start 97.733866 -215.92794)
		(end 97.739454 -215.931242)
		(width 0.0889)
		(layer "In4.Cu")
		(net "UPI_CPU0_CPU1_P1P0_DN<9>")
	)
	(segment
		(start 275.988272 -144.046448)
		(end 238.595662 -144.719548)
		(width 0.14732)
		(layer "In4.Cu")
		(net "UPI_CPU0_CPU1_P1P0_DN<9>")
	)
	(segment
		(start 97.69983 -217.607388)
		(end 97.543366 -217.878406)
		(width 0.0889)
		(layer "In4.Cu")
		(net "UPI_CPU0_CPU1_P1P0_DN<9>")
	)
	(segment
		(start 373.772684 -217.082878)
		(end 373.772684 -217.05443)
		(width 0.0889)
		(layer "In4.Cu")
		(net "UPI_CPU0_CPU1_P1P0_DN<9>")
	)
	(segment
		(start 97.406206 -211.552282)
		(end 97.406206 -211.91093)
		(width 0.14732)
		(layer "In4.Cu")
		(net "UPI_CPU0_CPU1_P1P0_DN<9>")
	)
	(segment
		(start 362.550964 -175.992282)
		(end 359.354882 -169.400982)
		(width 0.14732)
		(layer "In4.Cu")
		(net "UPI_CPU0_CPU1_P1P0_DN<9>")
	)
	(segment
		(start 97.724214 -216.578688)
		(end 97.724468 -216.578434)
		(width 0.0889)
		(layer "In4.Cu")
		(net "UPI_CPU0_CPU1_P1P0_DN<9>")
	)
	(segment
		(start 365.9378 -184.334658)
		(end 365.9378 -183.048148)
		(width 0.14732)
		(layer "In4.Cu")
		(net "UPI_CPU0_CPU1_P1P0_DN<9>")
	)
	(segment
		(start 373.772684 -213.29142)
		(end 373.871744 -213.19236)
		(width 0.0889)
		(layer "In4.Cu")
		(net "UPI_CPU0_CPU1_P1P0_DN<9>")
	)
	(segment
		(start 317.854584 -145.557748)
		(end 314.830206 -145.557748)
		(width 0.14732)
		(layer "In4.Cu")
		(net "UPI_CPU0_CPU1_P1P0_DN<9>")
	)
	(segment
		(start 97.724468 -215.922606)
		(end 97.72777 -215.924384)
		(width 0.0889)
		(layer "In4.Cu")
		(net "UPI_CPU0_CPU1_P1P0_DN<9>")
	)
	(segment
		(start 97.448116 -211.974938)
		(end 97.448116 -213.930484)
		(width 0.0889)
		(layer "In4.Cu")
		(net "UPI_CPU0_CPU1_P1P0_DN<9>")
	)
	(segment
		(start 97.729802 -215.925654)
		(end 97.731326 -215.92667)
		(width 0.0889)
		(layer "In4.Cu")
		(net "UPI_CPU0_CPU1_P1P0_DN<9>")
	)
	(segment
		(start 105.334308 -189.833758)
		(end 97.405952 -211.304886)
		(width 0.14732)
		(layer "In4.Cu")
		(net "UPI_CPU0_CPU1_P1P0_DN<9>")
	)
	(segment
		(start 374.242584 -214.636858)
		(end 374.242584 -214.425022)
		(width 0.0889)
		(layer "In4.Cu")
		(net "UPI_CPU0_CPU1_P1P0_DN<9>")
	)
	(segment
		(start 97.731326 -215.92667)
		(end 97.733866 -215.92794)
		(width 0.0889)
		(layer "In4.Cu")
		(net "UPI_CPU0_CPU1_P1P0_DN<9>")
	)
	(segment
		(start 373.52097 -218.149424)
		(end 373.442738 -218.170252)
		(width 0.0889)
		(layer "In4.Cu")
		(net "UPI_CPU0_CPU1_P1P0_DN<9>")
	)
	(segment
		(start 317.886588 -145.565368)
		(end 317.854584 -145.557748)
		(width 0.14732)
		(layer "In4.Cu")
		(net "UPI_CPU0_CPU1_P1P0_DN<9>")
	)
	(segment
		(start 373.793766 -206.00797)
		(end 366.97412 -189.54369)
		(width 0.14732)
		(layer "In4.Cu")
		(net "UPI_CPU0_CPU1_P1P0_DN<9>")
	)
	(segment
		(start 108.397802 -185.992262)
		(end 105.334308 -189.833758)
		(width 0.14732)
		(layer "In4.Cu")
		(net "UPI_CPU0_CPU1_P1P0_DN<9>")
	)
	(segment
		(start 97.739454 -216.569798)
		(end 97.724214 -216.578688)
		(width 0.0889)
		(layer "In4.Cu")
		(net "UPI_CPU0_CPU1_P1P0_DN<9>")
	)
	(segment
		(start 373.481346 -215.931242)
		(end 373.490236 -215.926162)
		(width 0.0889)
		(layer "In4.Cu")
		(net "UPI_CPU0_CPU1_P1P0_DN<9>")
	)
	(segment
		(start 238.595662 -144.719548)
		(end 169.708576 -143.60525)
		(width 0.14732)
		(layer "In4.Cu")
		(net "UPI_CPU0_CPU1_P1P0_DN<9>")
	)
	(segment
		(start 373.871744 -213.19236)
		(end 373.871744 -213.0171)
		(width 0.0889)
		(layer "In4.Cu")
		(net "UPI_CPU0_CPU1_P1P0_DN<9>")
	)
	(segment
		(start 317.886588 -145.565622)
		(end 317.886588 -145.565368)
		(width 0.14732)
		(layer "In4.Cu")
		(net "UPI_CPU0_CPU1_P1P0_DN<9>")
	)
	(segment
		(start 373.481346 -217.559128)
		(end 373.490236 -217.554048)
		(width 0.0889)
		(layer "In4.Cu")
		(net "UPI_CPU0_CPU1_P1P0_DN<9>")
	)
	(segment
		(start 366.97412 -189.54369)
		(end 365.9378 -184.334658)
		(width 0.14732)
		(layer "In4.Cu")
		(net "UPI_CPU0_CPU1_P1P0_DN<9>")
	)
	(segment
		(start 97.6757 -217.518234)
		(end 97.69983 -217.607388)
		(width 0.0889)
		(layer "In4.Cu")
		(net "UPI_CPU0_CPU1_P1P0_DN<9>")
	)
	(segment
		(start 97.405952 -211.304886)
		(end 97.405952 -211.552028)
		(width 0.14732)
		(layer "In4.Cu")
		(net "UPI_CPU0_CPU1_P1P0_DN<9>")
	)
	(segment
		(start 314.830206 -145.557748)
		(end 275.988272 -144.046448)
		(width 0.14732)
		(layer "In4.Cu")
		(net "UPI_CPU0_CPU1_P1P0_DN<9>")
	)
	(segment
		(start 373.772684 -215.436704)
		(end 373.772684 -215.428068)
		(width 0.0889)
		(layer "In4.Cu")
		(net "UPI_CPU0_CPU1_P1P0_DN<9>")
	)
	(segment
		(start 97.72777 -215.924384)
		(end 97.729802 -215.925654)
		(width 0.0889)
		(layer "In4.Cu")
		(net "UPI_CPU0_CPU1_P1P0_DN<9>")
	)
	(segment
		(start 373.77243 -215.455246)
		(end 373.772684 -215.436704)
		(width 0.0889)
		(layer "In4.Cu")
		(net "UPI_CPU0_CPU1_P1P0_DN<9>")
	)
	(segment
		(start 373.772684 -212.3694)
		(end 373.772684 -211.825332)
		(width 0.0889)
		(layer "In4.Cu")
		(net "UPI_CPU0_CPU1_P1P0_DN<9>")
	)
	(segment
		(start 97.447862 -215.414606)
		(end 97.447862 -215.436704)
		(width 0.0889)
		(layer "In4.Cu")
		(net "UPI_CPU0_CPU1_P1P0_DN<9>")
	)
	(segment
		(start 373.772684 -213.8934)
		(end 373.772684 -213.29142)
		(width 0.0889)
		(layer "In4.Cu")
		(net "UPI_CPU0_CPU1_P1P0_DN<9>")
	)
	(segment
		(start 356.613206 -166.129716)
		(end 328.724514 -148.220684)
		(width 0.14732)
		(layer "In4.Cu")
		(net "UPI_CPU0_CPU1_P1P0_DN<9>")
	)
	(segment
		(start 128.63449 -166.943786)
		(end 108.397802 -185.992262)
		(width 0.14732)
		(layer "In4.Cu")
		(net "UPI_CPU0_CPU1_P1P0_DN<9>")
	)
	(segment
		(start 365.736124 -182.560722)
		(end 362.550964 -175.992282)
		(width 0.14732)
		(layer "In4.Cu")
		(net "UPI_CPU0_CPU1_P1P0_DN<9>")
	)
	(segment
		(start 359.354882 -169.400982)
		(end 356.613206 -166.129716)
		(width 0.14732)
		(layer "In4.Cu")
		(net "UPI_CPU0_CPU1_P1P0_DN<9>")
	)
	(segment
		(start 169.708576 -143.60525)
		(end 162.540442 -146.08175)
		(width 0.14732)
		(layer "In4.Cu")
		(net "UPI_CPU0_CPU1_P1P0_DN<9>")
	)
	(segment
		(start 373.871744 -213.0171)
		(end 373.772684 -212.91804)
		(width 0.0889)
		(layer "In4.Cu")
		(net "UPI_CPU0_CPU1_P1P0_DN<9>")
	)
	(segment
		(start 373.814848 -211.76107)
		(end 373.814848 -211.366862)
		(width 0.14732)
		(layer "In4.Cu")
		(net "UPI_CPU0_CPU1_P1P0_DN<9>")
	)
	(segment
		(start 373.490236 -216.574878)
		(end 373.481346 -216.569798)
		(width 0.0889)
		(layer "In4.Cu")
		(net "UPI_CPU0_CPU1_P1P0_DN<9>")
	)
	(segment
		(start 373.814848 -211.366862)
		(end 373.814594 -211.366608)
		(width 0.14732)
		(layer "In4.Cu")
		(net "UPI_CPU0_CPU1_P1P0_DN<9>")
	)
	(segment
		(start 373.814594 -211.366608)
		(end 373.814594 -206.028798)
		(width 0.14732)
		(layer "In4.Cu")
		(net "UPI_CPU0_CPU1_P1P0_DN<9>")
	)
	(segment
		(start 97.447862 -217.064336)
		(end 97.447862 -217.07856)
		(width 0.0889)
		(layer "In4.Cu")
		(net "UPI_CPU0_CPU1_P1P0_DN<9>")
	)
	(segment
		(start 365.9378 -183.048148)
		(end 365.736124 -182.560976)
		(width 0.14732)
		(layer "In4.Cu")
		(net "UPI_CPU0_CPU1_P1P0_DN<9>")
	)
	(arc
		(start 97.724468 -216.578434)
		(mid 97.521881 -216.784785)
		(end 97.447862 -217.064336)
		(width 0.0889)
		(layer "In4.Cu")
		(net "UPI_CPU0_CPU1_P1P0_DN<9>")
	)
	(arc
		(start 373.303038 -216.238328)
		(mid 373.353531 -216.06235)
		(end 373.481346 -215.931242)
		(width 0.0889)
		(layer "In4.Cu")
		(net "UPI_CPU0_CPU1_P1P0_DN<9>")
	)
	(arc
		(start 373.490236 -217.554048)
		(mid 373.692522 -217.355067)
		(end 373.772684 -217.082878)
		(width 0.0889)
		(layer "In4.Cu")
		(net "UPI_CPU0_CPU1_P1P0_DN<9>")
	)
	(arc
		(start 97.730056 -214.946992)
		(mid 97.528774 -215.144479)
		(end 97.447862 -215.414606)
		(width 0.0889)
		(layer "In4.Cu")
		(net "UPI_CPU0_CPU1_P1P0_DN<9>")
	)
	(arc
		(start 97.658682 -217.50528)
		(mid 97.66713 -217.511837)
		(end 97.6757 -217.518234)
		(width 0.0889)
		(layer "In4.Cu")
		(net "UPI_CPU0_CPU1_P1P0_DN<9>")
	)
	(arc
		(start 97.448116 -213.930484)
		(mid 97.455401 -213.950046)
		(end 97.463356 -213.969346)
		(width 0.0889)
		(layer "In4.Cu")
		(net "UPI_CPU0_CPU1_P1P0_DN<9>")
	)
	(arc
		(start 373.481346 -216.569798)
		(mid 373.352057 -216.436312)
		(end 373.302784 -216.257124)
		(width 0.0889)
		(layer "In4.Cu")
		(net "UPI_CPU0_CPU1_P1P0_DN<9>")
	)
	(arc
		(start 97.917508 -214.622634)
		(mid 97.869829 -214.805534)
		(end 97.738946 -214.941912)
		(width 0.0889)
		(layer "In4.Cu")
		(net "UPI_CPU0_CPU1_P1P0_DN<9>")
	)
	(arc
		(start 374.242584 -214.425022)
		(mid 374.131246 -214.232122)
		(end 373.957088 -214.093298)
		(width 0.0889)
		(layer "In4.Cu")
		(net "UPI_CPU0_CPU1_P1P0_DN<9>")
	)
	(arc
		(start 373.772684 -215.428068)
		(mid 373.824954 -215.245703)
		(end 373.959882 -215.112346)
		(width 0.0889)
		(layer "In4.Cu")
		(net "UPI_CPU0_CPU1_P1P0_DN<9>")
	)
	(arc
		(start 97.463356 -213.969346)
		(mid 97.57335 -214.138715)
		(end 97.733358 -214.261954)
		(width 0.0889)
		(layer "In4.Cu")
		(net "UPI_CPU0_CPU1_P1P0_DN<9>")
	)
	(arc
		(start 373.772684 -217.05443)
		(mid 373.694573 -216.777481)
		(end 373.490236 -216.574878)
		(width 0.0889)
		(layer "In4.Cu")
		(net "UPI_CPU0_CPU1_P1P0_DN<9>")
	)
	(arc
		(start 373.302784 -216.257124)
		(mid 373.302794 -216.247724)
		(end 373.303038 -216.238328)
		(width 0.0889)
		(layer "In4.Cu")
		(net "UPI_CPU0_CPU1_P1P0_DN<9>")
	)
	(arc
		(start 373.302784 -217.878406)
		(mid 373.350463 -217.695506)
		(end 373.481346 -217.559128)
		(width 0.0889)
		(layer "In4.Cu")
		(net "UPI_CPU0_CPU1_P1P0_DN<9>")
	)
	(arc
		(start 97.733358 -214.261954)
		(mid 97.842505 -214.345882)
		(end 97.917508 -214.461344)
		(width 0.0889)
		(layer "In4.Cu")
		(net "UPI_CPU0_CPU1_P1P0_DN<9>")
	)
	(arc
		(start 97.447862 -215.436704)
		(mid 97.521853 -215.71627)
		(end 97.724468 -215.922606)
		(width 0.0889)
		(layer "In4.Cu")
		(net "UPI_CPU0_CPU1_P1P0_DN<9>")
	)
	(arc
		(start 97.447862 -217.07856)
		(mid 97.506156 -217.315203)
		(end 97.658682 -217.50528)
		(width 0.0889)
		(layer "In4.Cu")
		(net "UPI_CPU0_CPU1_P1P0_DN<9>")
	)
	(arc
		(start 97.739454 -215.931242)
		(mid 97.918051 -216.25052)
		(end 97.739454 -216.569798)
		(width 0.0889)
		(layer "In4.Cu")
		(net "UPI_CPU0_CPU1_P1P0_DN<9>")
	)
	(arc
		(start 373.957088 -214.093298)
		(mid 373.847692 -214.009201)
		(end 373.772684 -213.8934)
		(width 0.0889)
		(layer "In4.Cu")
		(net "UPI_CPU0_CPU1_P1P0_DN<9>")
	)
	(arc
		(start 373.959882 -215.112346)
		(mid 374.163363 -214.911542)
		(end 374.242584 -214.636858)
		(width 0.0889)
		(layer "In4.Cu")
		(net "UPI_CPU0_CPU1_P1P0_DN<9>")
	)
	(arc
		(start 373.442738 -218.170252)
		(mid 373.339593 -218.040227)
		(end 373.302784 -217.878406)
		(width 0.0889)
		(layer "In4.Cu")
		(net "UPI_CPU0_CPU1_P1P0_DN<9>")
	)
	(arc
		(start 373.490236 -215.926162)
		(mid 373.692278 -215.727239)
		(end 373.77243 -215.455246)
		(width 0.0889)
		(layer "In4.Cu")
		(net "UPI_CPU0_CPU1_P1P0_DN<9>")
	)
	(segment
		(start 96.603312 -217.87866)
		(end 96.603566 -217.878406)
		(width 0.13208)
		(layer "F.Cu")
		(net "UPI_CPU0_CPU1_P1P0_DN<8>")
	)
	(segment
		(start 374.61698 -218.414346)
		(end 374.61698 -217.87866)
		(width 0.13208)
		(layer "F.Cu")
		(net "UPI_CPU0_CPU1_P1P0_DN<8>")
	)
	(segment
		(start 96.603312 -218.414346)
		(end 96.603312 -217.87866)
		(width 0.13208)
		(layer "F.Cu")
		(net "UPI_CPU0_CPU1_P1P0_DN<8>")
	)
	(segment
		(start 374.61698 -217.87866)
		(end 374.617234 -217.878406)
		(width 0.13208)
		(layer "F.Cu")
		(net "UPI_CPU0_CPU1_P1P0_DN<8>")
	)
	(segment
		(start 375.181876 -214.426292)
		(end 375.181622 -214.426038)
		(width 0.0889)
		(layer "In4.Cu")
		(net "UPI_CPU0_CPU1_P1P0_DN<8>")
	)
	(segment
		(start 126.649226 -167.448992)
		(end 107.672632 -185.310018)
		(width 0.14732)
		(layer "In4.Cu")
		(net "UPI_CPU0_CPU1_P1P0_DN<8>")
	)
	(segment
		(start 374.617234 -217.878406)
		(end 374.46077 -217.607388)
		(width 0.0889)
		(layer "In4.Cu")
		(net "UPI_CPU0_CPU1_P1P0_DN<8>")
	)
	(segment
		(start 96.76003 -218.149424)
		(end 96.603566 -217.878406)
		(width 0.0889)
		(layer "In4.Cu")
		(net "UPI_CPU0_CPU1_P1P0_DN<8>")
	)
	(segment
		(start 162.26028 -145.273014)
		(end 127.458978 -166.686738)
		(width 0.14732)
		(layer "In4.Cu")
		(net "UPI_CPU0_CPU1_P1P0_DN<8>")
	)
	(segment
		(start 366.79632 -182.815738)
		(end 366.627918 -182.409338)
		(width 0.14732)
		(layer "In4.Cu")
		(net "UPI_CPU0_CPU1_P1P0_DN<8>")
	)
	(segment
		(start 104.312212 -189.709298)
		(end 104.311704 -189.709552)
		(width 0.14732)
		(layer "In4.Cu")
		(net "UPI_CPU0_CPU1_P1P0_DN<8>")
	)
	(segment
		(start 96.466914 -211.958428)
		(end 96.508824 -212.000338)
		(width 0.0889)
		(layer "In4.Cu")
		(net "UPI_CPU0_CPU1_P1P0_DN<8>")
	)
	(segment
		(start 374.754648 -211.572602)
		(end 374.754394 -211.572348)
		(width 0.14732)
		(layer "In4.Cu")
		(net "UPI_CPU0_CPU1_P1P0_DN<8>")
	)
	(segment
		(start 96.799146 -214.941912)
		(end 96.790256 -214.946992)
		(width 0.0889)
		(layer "In4.Cu")
		(net "UPI_CPU0_CPU1_P1P0_DN<8>")
	)
	(segment
		(start 96.508824 -212.000338)
		(end 96.508824 -212.4329)
		(width 0.0889)
		(layer "In4.Cu")
		(net "UPI_CPU0_CPU1_P1P0_DN<8>")
	)
	(segment
		(start 96.799654 -216.569798)
		(end 96.790764 -216.574878)
		(width 0.0889)
		(layer "In4.Cu")
		(net "UPI_CPU0_CPU1_P1P0_DN<8>")
	)
	(segment
		(start 96.769682 -214.248746)
		(end 96.770952 -214.249508)
		(width 0.0889)
		(layer "In4.Cu")
		(net "UPI_CPU0_CPU1_P1P0_DN<8>")
	)
	(segment
		(start 96.771968 -214.250016)
		(end 96.773238 -214.250778)
		(width 0.0889)
		(layer "In4.Cu")
		(net "UPI_CPU0_CPU1_P1P0_DN<8>")
	)
	(segment
		(start 96.790764 -216.574878)
		(end 96.786954 -216.577164)
		(width 0.0889)
		(layer "In4.Cu")
		(net "UPI_CPU0_CPU1_P1P0_DN<8>")
	)
	(segment
		(start 374.421146 -215.931242)
		(end 374.430036 -215.926162)
		(width 0.0889)
		(layer "In4.Cu")
		(net "UPI_CPU0_CPU1_P1P0_DN<8>")
	)
	(segment
		(start 96.78797 -215.924384)
		(end 96.790002 -215.925654)
		(width 0.0889)
		(layer "In4.Cu")
		(net "UPI_CPU0_CPU1_P1P0_DN<8>")
	)
	(segment
		(start 363.360716 -175.678338)
		(end 363.36097 -175.678338)
		(width 0.14732)
		(layer "In4.Cu")
		(net "UPI_CPU0_CPU1_P1P0_DN<8>")
	)
	(segment
		(start 374.754648 -211.783168)
		(end 374.754648 -211.76107)
		(width 0.0889)
		(layer "In4.Cu")
		(net "UPI_CPU0_CPU1_P1P0_DN<8>")
	)
	(segment
		(start 126.648972 -167.448992)
		(end 126.649226 -167.448992)
		(width 0.14732)
		(layer "In4.Cu")
		(net "UPI_CPU0_CPU1_P1P0_DN<8>")
	)
	(segment
		(start 314.975494 -144.722088)
		(end 276.089364 -143.209264)
		(width 0.14732)
		(layer "In4.Cu")
		(net "UPI_CPU0_CPU1_P1P0_DN<8>")
	)
	(segment
		(start 96.838262 -218.170252)
		(end 96.76003 -218.149424)
		(width 0.0889)
		(layer "In4.Cu")
		(net "UPI_CPU0_CPU1_P1P0_DN<8>")
	)
	(segment
		(start 96.508824 -213.35492)
		(end 96.508824 -213.832694)
		(width 0.0889)
		(layer "In4.Cu")
		(net "UPI_CPU0_CPU1_P1P0_DN<8>")
	)
	(segment
		(start 104.837484 -188.866526)
		(end 104.43845 -189.366652)
		(width 0.14732)
		(layer "In4.Cu")
		(net "UPI_CPU0_CPU1_P1P0_DN<8>")
	)
	(segment
		(start 276.089364 -143.209264)
		(end 238.593122 -143.883634)
		(width 0.14732)
		(layer "In4.Cu")
		(net "UPI_CPU0_CPU1_P1P0_DN<8>")
	)
	(segment
		(start 374.754648 -211.76107)
		(end 374.754648 -211.572602)
		(width 0.14732)
		(layer "In4.Cu")
		(net "UPI_CPU0_CPU1_P1P0_DN<8>")
	)
	(segment
		(start 96.46666 -210.956144)
		(end 96.46666 -211.539328)
		(width 0.14732)
		(layer "In4.Cu")
		(net "UPI_CPU0_CPU1_P1P0_DN<8>")
	)
	(segment
		(start 96.409764 -213.25586)
		(end 96.508824 -213.35492)
		(width 0.0889)
		(layer "In4.Cu")
		(net "UPI_CPU0_CPU1_P1P0_DN<8>")
	)
	(segment
		(start 374.712484 -217.07856)
		(end 374.712484 -217.064336)
		(width 0.0889)
		(layer "In4.Cu")
		(net "UPI_CPU0_CPU1_P1P0_DN<8>")
	)
	(segment
		(start 96.409764 -212.70722)
		(end 96.508824 -212.80628)
		(width 0.0889)
		(layer "In4.Cu")
		(net "UPI_CPU0_CPU1_P1P0_DN<8>")
	)
	(segment
		(start 104.274112 -189.811406)
		(end 104.046528 -190.428118)
		(width 0.14732)
		(layer "In4.Cu")
		(net "UPI_CPU0_CPU1_P1P0_DN<8>")
	)
	(segment
		(start 96.790764 -217.554048)
		(end 96.799654 -217.559128)
		(width 0.0889)
		(layer "In4.Cu")
		(net "UPI_CPU0_CPU1_P1P0_DN<8>")
	)
	(segment
		(start 104.274366 -189.810644)
		(end 104.274112 -189.811406)
		(width 0.14732)
		(layer "In4.Cu")
		(net "UPI_CPU0_CPU1_P1P0_DN<8>")
	)
	(segment
		(start 374.754394 -211.572348)
		(end 374.754394 -206.086202)
		(width 0.14732)
		(layer "In4.Cu")
		(net "UPI_CPU0_CPU1_P1P0_DN<8>")
	)
	(segment
		(start 96.784668 -215.922606)
		(end 96.78797 -215.924384)
		(width 0.0889)
		(layer "In4.Cu")
		(net "UPI_CPU0_CPU1_P1P0_DN<8>")
	)
	(segment
		(start 96.508824 -212.80628)
		(end 96.508824 -212.98154)
		(width 0.0889)
		(layer "In4.Cu")
		(net "UPI_CPU0_CPU1_P1P0_DN<8>")
	)
	(segment
		(start 374.817132 -214.051896)
		(end 374.712484 -213.878414)
		(width 0.0889)
		(layer "In4.Cu")
		(net "UPI_CPU0_CPU1_P1P0_DN<8>")
	)
	(segment
		(start 97.322132 -208.639156)
		(end 97.321624 -208.64068)
		(width 0.14732)
		(layer "In4.Cu")
		(net "UPI_CPU0_CPU1_P1P0_DN<8>")
	)
	(segment
		(start 374.754394 -206.086202)
		(end 367.80216 -189.301374)
		(width 0.14732)
		(layer "In4.Cu")
		(net "UPI_CPU0_CPU1_P1P0_DN<8>")
	)
	(segment
		(start 107.672632 -185.310018)
		(end 104.83723 -188.866526)
		(width 0.14732)
		(layer "In4.Cu")
		(net "UPI_CPU0_CPU1_P1P0_DN<8>")
	)
	(segment
		(start 360.08183 -168.923208)
		(end 357.17226 -165.494716)
		(width 0.14732)
		(layer "In4.Cu")
		(net "UPI_CPU0_CPU1_P1P0_DN<8>")
	)
	(segment
		(start 97.195386 -208.98231)
		(end 97.19437 -208.985358)
		(width 0.14732)
		(layer "In4.Cu")
		(net "UPI_CPU0_CPU1_P1P0_DN<8>")
	)
	(segment
		(start 374.436132 -216.578434)
		(end 374.430036 -216.574878)
		(width 0.0889)
		(layer "In4.Cu")
		(net "UPI_CPU0_CPU1_P1P0_DN<8>")
	)
	(segment
		(start 96.786954 -216.577164)
		(end 96.778572 -216.58199)
		(width 0.0889)
		(layer "In4.Cu")
		(net "UPI_CPU0_CPU1_P1P0_DN<8>")
	)
	(segment
		(start 169.519092 -142.766542)
		(end 162.26028 -145.273014)
		(width 0.14732)
		(layer "In4.Cu")
		(net "UPI_CPU0_CPU1_P1P0_DN<8>")
	)
	(segment
		(start 96.790002 -215.925654)
		(end 96.791526 -215.92667)
		(width 0.0889)
		(layer "In4.Cu")
		(net "UPI_CPU0_CPU1_P1P0_DN<8>")
	)
	(segment
		(start 96.466914 -211.539582)
		(end 96.466914 -211.93633)
		(width 0.14732)
		(layer "In4.Cu")
		(net "UPI_CPU0_CPU1_P1P0_DN<8>")
	)
	(segment
		(start 317.955676 -144.722088)
		(end 314.975494 -144.722088)
		(width 0.14732)
		(layer "In4.Cu")
		(net "UPI_CPU0_CPU1_P1P0_DN<8>")
	)
	(segment
		(start 104.43845 -189.366652)
		(end 104.312212 -189.709298)
		(width 0.14732)
		(layer "In4.Cu")
		(net "UPI_CPU0_CPU1_P1P0_DN<8>")
	)
	(segment
		(start 363.36097 -175.678338)
		(end 360.08183 -168.923208)
		(width 0.14732)
		(layer "In4.Cu")
		(net "UPI_CPU0_CPU1_P1P0_DN<8>")
	)
	(segment
		(start 357.17226 -165.494716)
		(end 329.058778 -147.44192)
		(width 0.14732)
		(layer "In4.Cu")
		(net "UPI_CPU0_CPU1_P1P0_DN<8>")
	)
	(segment
		(start 96.409764 -213.0806)
		(end 96.409764 -213.25586)
		(width 0.0889)
		(layer "In4.Cu")
		(net "UPI_CPU0_CPU1_P1P0_DN<8>")
	)
	(segment
		(start 375.181876 -214.638382)
		(end 375.181876 -214.426292)
		(width 0.0889)
		(layer "In4.Cu")
		(net "UPI_CPU0_CPU1_P1P0_DN<8>")
	)
	(segment
		(start 96.508824 -212.4329)
		(end 96.409764 -212.53196)
		(width 0.0889)
		(layer "In4.Cu")
		(net "UPI_CPU0_CPU1_P1P0_DN<8>")
	)
	(segment
		(start 374.890792 -215.117426)
		(end 374.899682 -215.112346)
		(width 0.0889)
		(layer "In4.Cu")
		(net "UPI_CPU0_CPU1_P1P0_DN<8>")
	)
	(segment
		(start 127.458978 -166.686738)
		(end 126.648972 -167.448992)
		(width 0.14732)
		(layer "In4.Cu")
		(net "UPI_CPU0_CPU1_P1P0_DN<8>")
	)
	(segment
		(start 97.321624 -208.64068)
		(end 97.195386 -208.98231)
		(width 0.14732)
		(layer "In4.Cu")
		(net "UPI_CPU0_CPU1_P1P0_DN<8>")
	)
	(segment
		(start 104.311704 -189.709552)
		(end 104.274366 -189.810644)
		(width 0.14732)
		(layer "In4.Cu")
		(net "UPI_CPU0_CPU1_P1P0_DN<8>")
	)
	(segment
		(start 96.508824 -212.98154)
		(end 96.409764 -213.0806)
		(width 0.0889)
		(layer "In4.Cu")
		(net "UPI_CPU0_CPU1_P1P0_DN<8>")
	)
	(segment
		(start 329.058778 -147.44192)
		(end 317.955676 -144.722088)
		(width 0.14732)
		(layer "In4.Cu")
		(net "UPI_CPU0_CPU1_P1P0_DN<8>")
	)
	(segment
		(start 96.753934 -214.240364)
		(end 96.769682 -214.248746)
		(width 0.0889)
		(layer "In4.Cu")
		(net "UPI_CPU0_CPU1_P1P0_DN<8>")
	)
	(segment
		(start 96.409764 -212.53196)
		(end 96.409764 -212.70722)
		(width 0.0889)
		(layer "In4.Cu")
		(net "UPI_CPU0_CPU1_P1P0_DN<8>")
	)
	(segment
		(start 96.466914 -211.93633)
		(end 96.466914 -211.958428)
		(width 0.0889)
		(layer "In4.Cu")
		(net "UPI_CPU0_CPU1_P1P0_DN<8>")
	)
	(segment
		(start 374.712484 -213.878414)
		(end 374.712484 -211.825332)
		(width 0.0889)
		(layer "In4.Cu")
		(net "UPI_CPU0_CPU1_P1P0_DN<8>")
	)
	(segment
		(start 366.79632 -184.244996)
		(end 366.79632 -182.815738)
		(width 0.14732)
		(layer "In4.Cu")
		(net "UPI_CPU0_CPU1_P1P0_DN<8>")
	)
	(segment
		(start 374.46077 -217.607388)
		(end 374.4849 -217.518234)
		(width 0.0889)
		(layer "In4.Cu")
		(net "UPI_CPU0_CPU1_P1P0_DN<8>")
	)
	(segment
		(start 96.46666 -211.539328)
		(end 96.466914 -211.539582)
		(width 0.14732)
		(layer "In4.Cu")
		(net "UPI_CPU0_CPU1_P1P0_DN<8>")
	)
	(segment
		(start 104.83723 -188.866526)
		(end 104.837484 -188.866526)
		(width 0.14732)
		(layer "In4.Cu")
		(net "UPI_CPU0_CPU1_P1P0_DN<8>")
	)
	(segment
		(start 374.89638 -214.093806)
		(end 374.817132 -214.051896)
		(width 0.0889)
		(layer "In4.Cu")
		(net "UPI_CPU0_CPU1_P1P0_DN<8>")
	)
	(segment
		(start 96.791526 -215.92667)
		(end 96.799654 -215.931496)
		(width 0.0889)
		(layer "In4.Cu")
		(net "UPI_CPU0_CPU1_P1P0_DN<8>")
	)
	(segment
		(start 96.770952 -214.249508)
		(end 96.771968 -214.250016)
		(width 0.0889)
		(layer "In4.Cu")
		(net "UPI_CPU0_CPU1_P1P0_DN<8>")
	)
	(segment
		(start 374.712484 -211.825332)
		(end 374.754648 -211.783168)
		(width 0.0889)
		(layer "In4.Cu")
		(net "UPI_CPU0_CPU1_P1P0_DN<8>")
	)
	(segment
		(start 96.977708 -214.461344)
		(end 96.977708 -214.622634)
		(width 0.0889)
		(layer "In4.Cu")
		(net "UPI_CPU0_CPU1_P1P0_DN<8>")
	)
	(segment
		(start 374.430036 -216.574878)
		(end 374.421146 -216.569798)
		(width 0.0889)
		(layer "In4.Cu")
		(net "UPI_CPU0_CPU1_P1P0_DN<8>")
	)
	(segment
		(start 366.627918 -182.409338)
		(end 363.360716 -175.678338)
		(width 0.14732)
		(layer "In4.Cu")
		(net "UPI_CPU0_CPU1_P1P0_DN<8>")
	)
	(segment
		(start 104.04602 -190.429642)
		(end 97.322132 -208.639156)
		(width 0.14732)
		(layer "In4.Cu")
		(net "UPI_CPU0_CPU1_P1P0_DN<8>")
	)
	(segment
		(start 367.80216 -189.301374)
		(end 366.79632 -184.244996)
		(width 0.14732)
		(layer "In4.Cu")
		(net "UPI_CPU0_CPU1_P1P0_DN<8>")
	)
	(segment
		(start 96.508062 -217.064336)
		(end 96.508062 -217.071956)
		(width 0.0889)
		(layer "In4.Cu")
		(net "UPI_CPU0_CPU1_P1P0_DN<8>")
	)
	(segment
		(start 97.19437 -208.985358)
		(end 96.46666 -210.956144)
		(width 0.14732)
		(layer "In4.Cu")
		(net "UPI_CPU0_CPU1_P1P0_DN<8>")
	)
	(segment
		(start 104.046528 -190.428118)
		(end 104.04602 -190.429642)
		(width 0.14732)
		(layer "In4.Cu")
		(net "UPI_CPU0_CPU1_P1P0_DN<8>")
	)
	(segment
		(start 96.799654 -215.931496)
		(end 96.799654 -215.931242)
		(width 0.0889)
		(layer "In4.Cu")
		(net "UPI_CPU0_CPU1_P1P0_DN<8>")
	)
	(segment
		(start 238.593122 -143.883634)
		(end 169.519092 -142.766542)
		(width 0.14732)
		(layer "In4.Cu")
		(net "UPI_CPU0_CPU1_P1P0_DN<8>")
	)
	(segment
		(start 374.71223 -215.452198)
		(end 374.71223 -215.436704)
		(width 0.0889)
		(layer "In4.Cu")
		(net "UPI_CPU0_CPU1_P1P0_DN<8>")
	)
	(segment
		(start 96.508062 -215.414606)
		(end 96.508062 -215.436704)
		(width 0.0889)
		(layer "In4.Cu")
		(net "UPI_CPU0_CPU1_P1P0_DN<8>")
	)
	(arc
		(start 96.773238 -214.250778)
		(mid 96.783343 -214.256465)
		(end 96.793558 -214.261954)
		(width 0.0889)
		(layer "In4.Cu")
		(net "UPI_CPU0_CPU1_P1P0_DN<8>")
	)
	(arc
		(start 96.778572 -216.58199)
		(mid 96.580344 -216.787838)
		(end 96.508062 -217.064336)
		(width 0.0889)
		(layer "In4.Cu")
		(net "UPI_CPU0_CPU1_P1P0_DN<8>")
	)
	(arc
		(start 374.421146 -216.569798)
		(mid 374.24267 -216.25052)
		(end 374.421146 -215.931242)
		(width 0.0889)
		(layer "In4.Cu")
		(net "UPI_CPU0_CPU1_P1P0_DN<8>")
	)
	(arc
		(start 375.181622 -214.426038)
		(mid 375.070494 -214.232879)
		(end 374.89638 -214.093806)
		(width 0.0889)
		(layer "In4.Cu")
		(net "UPI_CPU0_CPU1_P1P0_DN<8>")
	)
	(arc
		(start 374.501664 -217.50528)
		(mid 374.654171 -217.315182)
		(end 374.712484 -217.07856)
		(width 0.0889)
		(layer "In4.Cu")
		(net "UPI_CPU0_CPU1_P1P0_DN<8>")
	)
	(arc
		(start 96.977708 -214.622634)
		(mid 96.930029 -214.805534)
		(end 96.799146 -214.941912)
		(width 0.0889)
		(layer "In4.Cu")
		(net "UPI_CPU0_CPU1_P1P0_DN<8>")
	)
	(arc
		(start 96.790256 -214.946992)
		(mid 96.588974 -215.144479)
		(end 96.508062 -215.414606)
		(width 0.0889)
		(layer "In4.Cu")
		(net "UPI_CPU0_CPU1_P1P0_DN<8>")
	)
	(arc
		(start 96.508824 -213.832694)
		(mid 96.574824 -214.070527)
		(end 96.753934 -214.240364)
		(width 0.0889)
		(layer "In4.Cu")
		(net "UPI_CPU0_CPU1_P1P0_DN<8>")
	)
	(arc
		(start 374.899682 -215.112346)
		(mid 375.102505 -214.912115)
		(end 375.181876 -214.638382)
		(width 0.0889)
		(layer "In4.Cu")
		(net "UPI_CPU0_CPU1_P1P0_DN<8>")
	)
	(arc
		(start 374.4849 -217.518234)
		(mid 374.493343 -217.511836)
		(end 374.501664 -217.50528)
		(width 0.0889)
		(layer "In4.Cu")
		(net "UPI_CPU0_CPU1_P1P0_DN<8>")
	)
	(arc
		(start 96.793558 -214.261954)
		(mid 96.902705 -214.345882)
		(end 96.977708 -214.461344)
		(width 0.0889)
		(layer "In4.Cu")
		(net "UPI_CPU0_CPU1_P1P0_DN<8>")
	)
	(arc
		(start 96.508062 -215.436704)
		(mid 96.582053 -215.71627)
		(end 96.784668 -215.922606)
		(width 0.0889)
		(layer "In4.Cu")
		(net "UPI_CPU0_CPU1_P1P0_DN<8>")
	)
	(arc
		(start 374.430036 -215.926162)
		(mid 374.632859 -215.725931)
		(end 374.71223 -215.452198)
		(width 0.0889)
		(layer "In4.Cu")
		(net "UPI_CPU0_CPU1_P1P0_DN<8>")
	)
	(arc
		(start 96.508062 -217.071956)
		(mid 96.585691 -217.350369)
		(end 96.790764 -217.554048)
		(width 0.0889)
		(layer "In4.Cu")
		(net "UPI_CPU0_CPU1_P1P0_DN<8>")
	)
	(arc
		(start 96.799654 -215.931242)
		(mid 96.978251 -216.25052)
		(end 96.799654 -216.569798)
		(width 0.0889)
		(layer "In4.Cu")
		(net "UPI_CPU0_CPU1_P1P0_DN<8>")
	)
	(arc
		(start 96.978216 -217.878406)
		(mid 96.941356 -218.040203)
		(end 96.838262 -218.170252)
		(width 0.0889)
		(layer "In4.Cu")
		(net "UPI_CPU0_CPU1_P1P0_DN<8>")
	)
	(arc
		(start 374.71223 -215.436704)
		(mid 374.759909 -215.253804)
		(end 374.890792 -215.117426)
		(width 0.0889)
		(layer "In4.Cu")
		(net "UPI_CPU0_CPU1_P1P0_DN<8>")
	)
	(arc
		(start 96.799654 -217.559128)
		(mid 96.930568 -217.695488)
		(end 96.978216 -217.878406)
		(width 0.0889)
		(layer "In4.Cu")
		(net "UPI_CPU0_CPU1_P1P0_DN<8>")
	)
	(arc
		(start 374.712484 -217.064336)
		(mid 374.638568 -216.784834)
		(end 374.436132 -216.578434)
		(width 0.0889)
		(layer "In4.Cu")
		(net "UPI_CPU0_CPU1_P1P0_DN<8>")
	)
	(segment
		(start 96.133666 -217.06459)
		(end 96.133412 -217.064336)
		(width 0.13208)
		(layer "F.Cu")
		(net "UPI_CPU0_CPU1_P1P0_DN<7>")
	)
	(segment
		(start 96.133666 -217.600276)
		(end 96.133666 -217.06459)
		(width 0.13208)
		(layer "F.Cu")
		(net "UPI_CPU0_CPU1_P1P0_DN<7>")
	)
	(segment
		(start 375.087134 -218.692476)
		(end 375.08688 -218.692222)
		(width 0.13208)
		(layer "F.Cu")
		(net "UPI_CPU0_CPU1_P1P0_DN<7>")
	)
	(segment
		(start 375.087134 -219.228162)
		(end 375.087134 -218.692476)
		(width 0.13208)
		(layer "F.Cu")
		(net "UPI_CPU0_CPU1_P1P0_DN<7>")
	)
	(segment
		(start 95.759016 -217.0557)
		(end 95.759016 -217.072972)
		(width 0.0889)
		(layer "In4.Cu")
		(net "UPI_CPU0_CPU1_P1P0_DN<7>")
	)
	(segment
		(start 373.075962 -200.518014)
		(end 373.154194 -200.328784)
		(width 0.14732)
		(layer "In4.Cu")
		(net "UPI_CPU0_CPU1_P1P0_DN<7>")
	)
	(segment
		(start 373.4689 -201.466196)
		(end 373.547132 -201.276966)
		(width 0.14732)
		(layer "In4.Cu")
		(net "UPI_CPU0_CPU1_P1P0_DN<7>")
	)
	(segment
		(start 106.355388 -185.859166)
		(end 106.374692 -186.030616)
		(width 0.14732)
		(layer "In4.Cu")
		(net "UPI_CPU0_CPU1_P1P0_DN<7>")
	)
	(segment
		(start 104.896158 -187.688982)
		(end 104.915462 -187.860432)
		(width 0.14732)
		(layer "In4.Cu")
		(net "UPI_CPU0_CPU1_P1P0_DN<7>")
	)
	(segment
		(start 375.744232 -214.946992)
		(end 375.753122 -214.941912)
		(width 0.0889)
		(layer "In4.Cu")
		(net "UPI_CPU0_CPU1_P1P0_DN<7>")
	)
	(segment
		(start 375.461784 -213.93023)
		(end 375.461784 -211.911184)
		(width 0.0889)
		(layer "In4.Cu")
		(net "UPI_CPU0_CPU1_P1P0_DN<7>")
	)
	(segment
		(start 375.420128 -211.869528)
		(end 375.420128 -211.84743)
		(width 0.0889)
		(layer "In4.Cu")
		(net "UPI_CPU0_CPU1_P1P0_DN<7>")
	)
	(segment
		(start 104.47147 -188.22162)
		(end 104.091486 -188.698124)
		(width 0.14732)
		(layer "In4.Cu")
		(net "UPI_CPU0_CPU1_P1P0_DN<7>")
	)
	(segment
		(start 105.593134 -186.815222)
		(end 105.612438 -186.986418)
		(width 0.14732)
		(layer "In4.Cu")
		(net "UPI_CPU0_CPU1_P1P0_DN<7>")
	)
	(segment
		(start 375.243344 -218.421204)
		(end 375.219214 -218.33205)
		(width 0.0889)
		(layer "In4.Cu")
		(net "UPI_CPU0_CPU1_P1P0_DN<7>")
	)
	(segment
		(start 95.759524 -212.69198)
		(end 95.759524 -212.86724)
		(width 0.0889)
		(layer "In4.Cu")
		(net "UPI_CPU0_CPU1_P1P0_DN<7>")
	)
	(segment
		(start 374.991884 -216.260426)
		(end 374.991884 -216.231978)
		(width 0.0889)
		(layer "In4.Cu")
		(net "UPI_CPU0_CPU1_P1P0_DN<7>")
	)
	(segment
		(start 373.939816 -202.225148)
		(end 373.7991 -201.885042)
		(width 0.14732)
		(layer "In4.Cu")
		(net "UPI_CPU0_CPU1_P1P0_DN<7>")
	)
	(segment
		(start 373.7991 -201.885042)
		(end 373.60987 -201.80681)
		(width 0.14732)
		(layer "In4.Cu")
		(net "UPI_CPU0_CPU1_P1P0_DN<7>")
	)
	(segment
		(start 374.991884 -217.8939)
		(end 374.991884 -217.859864)
		(width 0.0889)
		(layer "In4.Cu")
		(net "UPI_CPU0_CPU1_P1P0_DN<7>")
	)
	(segment
		(start 374.002554 -202.754992)
		(end 373.861584 -202.414378)
		(width 0.14732)
		(layer "In4.Cu")
		(net "UPI_CPU0_CPU1_P1P0_DN<7>")
	)
	(segment
		(start 375.419874 -211.68614)
		(end 375.419874 -205.798166)
		(width 0.14732)
		(layer "In4.Cu")
		(net "UPI_CPU0_CPU1_P1P0_DN<7>")
	)
	(segment
		(start 374.191784 -202.833224)
		(end 374.002554 -202.754992)
		(width 0.14732)
		(layer "In4.Cu")
		(net "UPI_CPU0_CPU1_P1P0_DN<7>")
	)
	(segment
		(start 162.123882 -144.69491)
		(end 127.022606 -166.29253)
		(width 0.14732)
		(layer "In4.Cu")
		(net "UPI_CPU0_CPU1_P1P0_DN<7>")
	)
	(segment
		(start 169.357294 -142.196566)
		(end 162.123882 -144.69491)
		(width 0.14732)
		(layer "In4.Cu")
		(net "UPI_CPU0_CPU1_P1P0_DN<7>")
	)
	(segment
		(start 105.168446 -187.347606)
		(end 104.896158 -187.688982)
		(width 0.14732)
		(layer "In4.Cu")
		(net "UPI_CPU0_CPU1_P1P0_DN<7>")
	)
	(segment
		(start 105.612438 -186.986418)
		(end 105.339896 -187.328302)
		(width 0.14732)
		(layer "In4.Cu")
		(net "UPI_CPU0_CPU1_P1P0_DN<7>")
	)
	(segment
		(start 95.959168 -215.103964)
		(end 95.959676 -215.104472)
		(width 0.0889)
		(layer "In4.Cu")
		(net "UPI_CPU0_CPU1_P1P0_DN<7>")
	)
	(segment
		(start 95.801434 -211.150708)
		(end 95.801434 -211.539328)
		(width 0.14732)
		(layer "In4.Cu")
		(net "UPI_CPU0_CPU1_P1P0_DN<7>")
	)
	(segment
		(start 373.406416 -200.93686)
		(end 373.216932 -200.858628)
		(width 0.14732)
		(layer "In4.Cu")
		(net "UPI_CPU0_CPU1_P1P0_DN<7>")
	)
	(segment
		(start 95.759524 -212.3186)
		(end 95.858584 -212.41766)
		(width 0.0889)
		(layer "In4.Cu")
		(net "UPI_CPU0_CPU1_P1P0_DN<7>")
	)
	(segment
		(start 127.022606 -166.29253)
		(end 106.719116 -185.403236)
		(width 0.14732)
		(layer "In4.Cu")
		(net "UPI_CPU0_CPU1_P1P0_DN<7>")
	)
	(segment
		(start 95.946214 -215.761062)
		(end 95.947738 -215.762078)
		(width 0.0889)
		(layer "In4.Cu")
		(net "UPI_CPU0_CPU1_P1P0_DN<7>")
	)
	(segment
		(start 375.420128 -211.84743)
		(end 375.420128 -211.686394)
		(width 0.14732)
		(layer "In4.Cu")
		(net "UPI_CPU0_CPU1_P1P0_DN<7>")
	)
	(segment
		(start 375.931684 -214.622634)
		(end 375.931684 -214.461852)
		(width 0.0889)
		(layer "In4.Cu")
		(net "UPI_CPU0_CPU1_P1P0_DN<7>")
	)
	(segment
		(start 95.801434 -211.539328)
		(end 95.801688 -211.539582)
		(width 0.14732)
		(layer "In4.Cu")
		(net "UPI_CPU0_CPU1_P1P0_DN<7>")
	)
	(segment
		(start 95.759524 -213.24062)
		(end 95.759524 -213.94547)
		(width 0.0889)
		(layer "In4.Cu")
		(net "UPI_CPU0_CPU1_P1P0_DN<7>")
	)
	(segment
		(start 375.08688 -218.692222)
		(end 375.243344 -218.421204)
		(width 0.0889)
		(layer "In4.Cu")
		(net "UPI_CPU0_CPU1_P1P0_DN<7>")
	)
	(segment
		(start 95.946214 -215.112346)
		(end 95.945198 -215.112854)
		(width 0.0889)
		(layer "In4.Cu")
		(net "UPI_CPU0_CPU1_P1P0_DN<7>")
	)
	(segment
		(start 95.949008 -215.76284)
		(end 95.95231 -215.764618)
		(width 0.0889)
		(layer "In4.Cu")
		(net "UPI_CPU0_CPU1_P1P0_DN<7>")
	)
	(segment
		(start 369.221258 -190.833756)
		(end 368.939826 -190.552324)
		(width 0.14732)
		(layer "In4.Cu")
		(net "UPI_CPU0_CPU1_P1P0_DN<7>")
	)
	(segment
		(start 95.942658 -215.75903)
		(end 95.94469 -215.7603)
		(width 0.0889)
		(layer "In4.Cu")
		(net "UPI_CPU0_CPU1_P1P0_DN<7>")
	)
	(segment
		(start 95.976948 -217.335354)
		(end 96.133412 -217.064336)
		(width 0.0889)
		(layer "In4.Cu")
		(net "UPI_CPU0_CPU1_P1P0_DN<7>")
	)
	(segment
		(start 95.759524 -213.94547)
		(end 95.941896 -214.127842)
		(width 0.0889)
		(layer "In4.Cu")
		(net "UPI_CPU0_CPU1_P1P0_DN<7>")
	)
	(segment
		(start 95.858584 -213.14156)
		(end 95.759524 -213.24062)
		(width 0.0889)
		(layer "In4.Cu")
		(net "UPI_CPU0_CPU1_P1P0_DN<7>")
	)
	(segment
		(start 375.46153 -215.445086)
		(end 375.46153 -215.43645)
		(width 0.0889)
		(layer "In4.Cu")
		(net "UPI_CPU0_CPU1_P1P0_DN<7>")
	)
	(segment
		(start 374.3325 -203.17333)
		(end 374.191784 -202.833224)
		(width 0.14732)
		(layer "In4.Cu")
		(net "UPI_CPU0_CPU1_P1P0_DN<7>")
	)
	(segment
		(start 95.94469 -215.7603)
		(end 95.946214 -215.761062)
		(width 0.0889)
		(layer "In4.Cu")
		(net "UPI_CPU0_CPU1_P1P0_DN<7>")
	)
	(segment
		(start 104.64292 -188.202316)
		(end 104.47147 -188.22162)
		(width 0.14732)
		(layer "In4.Cu")
		(net "UPI_CPU0_CPU1_P1P0_DN<7>")
	)
	(segment
		(start 374.645174 -204.315822)
		(end 374.725438 -204.121766)
		(width 0.14732)
		(layer "In4.Cu")
		(net "UPI_CPU0_CPU1_P1P0_DN<7>")
	)
	(segment
		(start 95.858584 -212.9663)
		(end 95.858584 -213.14156)
		(width 0.0889)
		(layer "In4.Cu")
		(net "UPI_CPU0_CPU1_P1P0_DN<7>")
	)
	(segment
		(start 238.59109 -143.316198)
		(end 169.357294 -142.196566)
		(width 0.14732)
		(layer "In4.Cu")
		(net "UPI_CPU0_CPU1_P1P0_DN<7>")
	)
	(segment
		(start 375.46153 -217.072972)
		(end 375.46153 -217.0557)
		(width 0.0889)
		(layer "In4.Cu")
		(net "UPI_CPU0_CPU1_P1P0_DN<7>")
	)
	(segment
		(start 105.339896 -187.328302)
		(end 105.168446 -187.347606)
		(width 0.14732)
		(layer "In4.Cu")
		(net "UPI_CPU0_CPU1_P1P0_DN<7>")
	)
	(segment
		(start 275.904452 -142.64513)
		(end 238.59109 -143.316198)
		(width 0.14732)
		(layer "In4.Cu")
		(net "UPI_CPU0_CPU1_P1P0_DN<7>")
	)
	(segment
		(start 95.946976 -216.73947)
		(end 95.946214 -216.739978)
		(width 0.0889)
		(layer "In4.Cu")
		(net "UPI_CPU0_CPU1_P1P0_DN<7>")
	)
	(segment
		(start 95.858584 -212.41766)
		(end 95.858584 -212.59292)
		(width 0.0889)
		(layer "In4.Cu")
		(net "UPI_CPU0_CPU1_P1P0_DN<7>")
	)
	(segment
		(start 367.35766 -182.674006)
		(end 367.187988 -182.264812)
		(width 0.14732)
		(layer "In4.Cu")
		(net "UPI_CPU0_CPU1_P1P0_DN<7>")
	)
	(segment
		(start 95.759524 -212.86724)
		(end 95.858584 -212.9663)
		(width 0.0889)
		(layer "In4.Cu")
		(net "UPI_CPU0_CPU1_P1P0_DN<7>")
	)
	(segment
		(start 104.091486 -188.698124)
		(end 95.801434 -211.150708)
		(width 0.14732)
		(layer "In4.Cu")
		(net "UPI_CPU0_CPU1_P1P0_DN<7>")
	)
	(segment
		(start 104.915462 -187.860432)
		(end 104.64292 -188.202316)
		(width 0.14732)
		(layer "In4.Cu")
		(net "UPI_CPU0_CPU1_P1P0_DN<7>")
	)
	(segment
		(start 95.95231 -216.736422)
		(end 95.946976 -216.73947)
		(width 0.0889)
		(layer "In4.Cu")
		(net "UPI_CPU0_CPU1_P1P0_DN<7>")
	)
	(segment
		(start 374.584468 -203.78166)
		(end 374.584722 -203.781406)
		(width 0.14732)
		(layer "In4.Cu")
		(net "UPI_CPU0_CPU1_P1P0_DN<7>")
	)
	(segment
		(start 373.861584 -202.414378)
		(end 373.939816 -202.225148)
		(width 0.14732)
		(layer "In4.Cu")
		(net "UPI_CPU0_CPU1_P1P0_DN<7>")
	)
	(segment
		(start 374.254268 -203.36256)
		(end 374.3325 -203.17333)
		(width 0.14732)
		(layer "In4.Cu")
		(net "UPI_CPU0_CPU1_P1P0_DN<7>")
	)
	(segment
		(start 357.53167 -165.055296)
		(end 329.28433 -146.916394)
		(width 0.14732)
		(layer "In4.Cu")
		(net "UPI_CPU0_CPU1_P1P0_DN<7>")
	)
	(segment
		(start 368.352578 -189.133988)
		(end 367.35766 -184.13349)
		(width 0.14732)
		(layer "In4.Cu")
		(net "UPI_CPU0_CPU1_P1P0_DN<7>")
	)
	(segment
		(start 95.801688 -211.81441)
		(end 95.801688 -211.836508)
		(width 0.0889)
		(layer "In4.Cu")
		(net "UPI_CPU0_CPU1_P1P0_DN<7>")
	)
	(segment
		(start 95.801688 -211.539582)
		(end 95.801688 -211.81441)
		(width 0.14732)
		(layer "In4.Cu")
		(net "UPI_CPU0_CPU1_P1P0_DN<7>")
	)
	(segment
		(start 374.782842 -204.649324)
		(end 374.645174 -204.315822)
		(width 0.14732)
		(layer "In4.Cu")
		(net "UPI_CPU0_CPU1_P1P0_DN<7>")
	)
	(segment
		(start 95.89897 -217.356182)
		(end 95.976948 -217.335354)
		(width 0.0889)
		(layer "In4.Cu")
		(net "UPI_CPU0_CPU1_P1P0_DN<7>")
	)
	(segment
		(start 106.374692 -186.030616)
		(end 106.10215 -186.3725)
		(width 0.14732)
		(layer "In4.Cu")
		(net "UPI_CPU0_CPU1_P1P0_DN<7>")
	)
	(segment
		(start 95.945198 -215.112854)
		(end 95.937324 -215.117426)
		(width 0.0889)
		(layer "In4.Cu")
		(net "UPI_CPU0_CPU1_P1P0_DN<7>")
	)
	(segment
		(start 373.60987 -201.80681)
		(end 373.4689 -201.466196)
		(width 0.14732)
		(layer "In4.Cu")
		(net "UPI_CPU0_CPU1_P1P0_DN<7>")
	)
	(segment
		(start 374.725438 -204.121766)
		(end 374.584468 -203.78166)
		(width 0.14732)
		(layer "In4.Cu")
		(net "UPI_CPU0_CPU1_P1P0_DN<7>")
	)
	(segment
		(start 314.79744 -144.158208)
		(end 275.904452 -142.64513)
		(width 0.14732)
		(layer "In4.Cu")
		(net "UPI_CPU0_CPU1_P1P0_DN<7>")
	)
	(segment
		(start 374.395238 -203.70292)
		(end 374.254268 -203.36256)
		(width 0.14732)
		(layer "In4.Cu")
		(net "UPI_CPU0_CPU1_P1P0_DN<7>")
	)
	(segment
		(start 373.216932 -200.858628)
		(end 373.075962 -200.518014)
		(width 0.14732)
		(layer "In4.Cu")
		(net "UPI_CPU0_CPU1_P1P0_DN<7>")
	)
	(segment
		(start 95.801688 -211.836508)
		(end 95.759524 -211.878672)
		(width 0.0889)
		(layer "In4.Cu")
		(net "UPI_CPU0_CPU1_P1P0_DN<7>")
	)
	(segment
		(start 374.977152 -204.729588)
		(end 374.782842 -204.649324)
		(width 0.14732)
		(layer "In4.Cu")
		(net "UPI_CPU0_CPU1_P1P0_DN<7>")
	)
	(segment
		(start 105.930954 -186.391804)
		(end 105.593134 -186.815222)
		(width 0.14732)
		(layer "In4.Cu")
		(net "UPI_CPU0_CPU1_P1P0_DN<7>")
	)
	(segment
		(start 95.937324 -215.755982)
		(end 95.939356 -215.757252)
		(width 0.0889)
		(layer "In4.Cu")
		(net "UPI_CPU0_CPU1_P1P0_DN<7>")
	)
	(segment
		(start 106.719116 -185.403236)
		(end 106.355388 -185.859166)
		(width 0.14732)
		(layer "In4.Cu")
		(net "UPI_CPU0_CPU1_P1P0_DN<7>")
	)
	(segment
		(start 373.547132 -201.276966)
		(end 373.406416 -200.93686)
		(width 0.14732)
		(layer "In4.Cu")
		(net "UPI_CPU0_CPU1_P1P0_DN<7>")
	)
	(segment
		(start 106.10215 -186.3725)
		(end 105.930954 -186.391804)
		(width 0.14732)
		(layer "In4.Cu")
		(net "UPI_CPU0_CPU1_P1P0_DN<7>")
	)
	(segment
		(start 95.941896 -214.127842)
		(end 96.083628 -214.20201)
		(width 0.0889)
		(layer "In4.Cu")
		(net "UPI_CPU0_CPU1_P1P0_DN<7>")
	)
	(segment
		(start 367.35766 -184.13349)
		(end 367.35766 -182.674006)
		(width 0.14732)
		(layer "In4.Cu")
		(net "UPI_CPU0_CPU1_P1P0_DN<7>")
	)
	(segment
		(start 318.024002 -144.158208)
		(end 314.79744 -144.158208)
		(width 0.14732)
		(layer "In4.Cu")
		(net "UPI_CPU0_CPU1_P1P0_DN<7>")
	)
	(segment
		(start 360.548682 -168.611804)
		(end 357.53167 -165.055296)
		(width 0.14732)
		(layer "In4.Cu")
		(net "UPI_CPU0_CPU1_P1P0_DN<7>")
	)
	(segment
		(start 367.187988 -182.264812)
		(end 360.548682 -168.611804)
		(width 0.14732)
		(layer "In4.Cu")
		(net "UPI_CPU0_CPU1_P1P0_DN<7>")
	)
	(segment
		(start 375.419874 -205.798166)
		(end 374.977152 -204.729588)
		(width 0.14732)
		(layer "In4.Cu")
		(net "UPI_CPU0_CPU1_P1P0_DN<7>")
	)
	(segment
		(start 96.228154 -214.426292)
		(end 96.228154 -214.622634)
		(width 0.0889)
		(layer "In4.Cu")
		(net "UPI_CPU0_CPU1_P1P0_DN<7>")
	)
	(segment
		(start 95.939356 -215.757252)
		(end 95.942658 -215.75903)
		(width 0.0889)
		(layer "In4.Cu")
		(net "UPI_CPU0_CPU1_P1P0_DN<7>")
	)
	(segment
		(start 95.947738 -215.762078)
		(end 95.949008 -215.76284)
		(width 0.0889)
		(layer "In4.Cu")
		(net "UPI_CPU0_CPU1_P1P0_DN<7>")
	)
	(segment
		(start 329.28433 -146.916394)
		(end 318.024002 -144.158208)
		(width 0.14732)
		(layer "In4.Cu")
		(net "UPI_CPU0_CPU1_P1P0_DN<7>")
	)
	(segment
		(start 374.584722 -203.781406)
		(end 374.395238 -203.70292)
		(width 0.14732)
		(layer "In4.Cu")
		(net "UPI_CPU0_CPU1_P1P0_DN<7>")
	)
	(segment
		(start 95.759524 -211.878672)
		(end 95.759524 -212.3186)
		(width 0.0889)
		(layer "In4.Cu")
		(net "UPI_CPU0_CPU1_P1P0_DN<7>")
	)
	(segment
		(start 375.461784 -211.911184)
		(end 375.420128 -211.869528)
		(width 0.0889)
		(layer "In4.Cu")
		(net "UPI_CPU0_CPU1_P1P0_DN<7>")
	)
	(segment
		(start 368.939826 -190.552324)
		(end 368.352578 -189.133988)
		(width 0.14732)
		(layer "In4.Cu")
		(net "UPI_CPU0_CPU1_P1P0_DN<7>")
	)
	(segment
		(start 373.154194 -200.328784)
		(end 369.221258 -190.833756)
		(width 0.14732)
		(layer "In4.Cu")
		(net "UPI_CPU0_CPU1_P1P0_DN<7>")
	)
	(segment
		(start 375.46153 -215.43645)
		(end 375.461784 -215.422226)
		(width 0.0889)
		(layer "In4.Cu")
		(net "UPI_CPU0_CPU1_P1P0_DN<7>")
	)
	(segment
		(start 375.420128 -211.686394)
		(end 375.419874 -211.68614)
		(width 0.14732)
		(layer "In4.Cu")
		(net "UPI_CPU0_CPU1_P1P0_DN<7>")
	)
	(segment
		(start 95.858584 -212.59292)
		(end 95.759524 -212.69198)
		(width 0.0889)
		(layer "In4.Cu")
		(net "UPI_CPU0_CPU1_P1P0_DN<7>")
	)
	(arc
		(start 95.937324 -215.117426)
		(mid 95.81007 -215.247392)
		(end 95.759016 -215.421972)
		(width 0.0889)
		(layer "In4.Cu")
		(net "UPI_CPU0_CPU1_P1P0_DN<7>")
	)
	(arc
		(start 375.219214 -218.33205)
		(mid 375.210773 -218.32565)
		(end 375.20245 -218.319096)
		(width 0.0889)
		(layer "In4.Cu")
		(net "UPI_CPU0_CPU1_P1P0_DN<7>")
	)
	(arc
		(start 96.228154 -214.622634)
		(mid 96.156325 -214.898301)
		(end 95.959168 -215.103964)
		(width 0.0889)
		(layer "In4.Cu")
		(net "UPI_CPU0_CPU1_P1P0_DN<7>")
	)
	(arc
		(start 95.946214 -216.739978)
		(mid 95.811281 -216.873332)
		(end 95.759016 -217.0557)
		(width 0.0889)
		(layer "In4.Cu")
		(net "UPI_CPU0_CPU1_P1P0_DN<7>")
	)
	(arc
		(start 375.274332 -215.760808)
		(mid 375.409265 -215.627454)
		(end 375.46153 -215.445086)
		(width 0.0889)
		(layer "In4.Cu")
		(net "UPI_CPU0_CPU1_P1P0_DN<7>")
	)
	(arc
		(start 375.46153 -217.0557)
		(mid 375.40926 -216.873335)
		(end 375.274332 -216.739978)
		(width 0.0889)
		(layer "In4.Cu")
		(net "UPI_CPU0_CPU1_P1P0_DN<7>")
	)
	(arc
		(start 95.759016 -215.421972)
		(mid 95.758819 -215.429337)
		(end 95.758762 -215.436704)
		(width 0.0889)
		(layer "In4.Cu")
		(net "UPI_CPU0_CPU1_P1P0_DN<7>")
	)
	(arc
		(start 95.759016 -217.072972)
		(mid 95.79769 -217.23004)
		(end 95.89897 -217.356182)
		(width 0.0889)
		(layer "In4.Cu")
		(net "UPI_CPU0_CPU1_P1P0_DN<7>")
	)
	(arc
		(start 375.47677 -213.968838)
		(mid 375.468948 -213.949662)
		(end 375.461784 -213.93023)
		(width 0.0889)
		(layer "In4.Cu")
		(net "UPI_CPU0_CPU1_P1P0_DN<7>")
	)
	(arc
		(start 375.461784 -215.422226)
		(mid 375.540915 -215.14769)
		(end 375.744232 -214.946992)
		(width 0.0889)
		(layer "In4.Cu")
		(net "UPI_CPU0_CPU1_P1P0_DN<7>")
	)
	(arc
		(start 375.274332 -217.388694)
		(mid 375.409265 -217.25534)
		(end 375.46153 -217.072972)
		(width 0.0889)
		(layer "In4.Cu")
		(net "UPI_CPU0_CPU1_P1P0_DN<7>")
	)
	(arc
		(start 95.758762 -215.436704)
		(mid 95.806441 -215.619604)
		(end 95.937324 -215.755982)
		(width 0.0889)
		(layer "In4.Cu")
		(net "UPI_CPU0_CPU1_P1P0_DN<7>")
	)
	(arc
		(start 95.959676 -215.104472)
		(mid 95.952972 -215.108455)
		(end 95.946214 -215.112346)
		(width 0.0889)
		(layer "In4.Cu")
		(net "UPI_CPU0_CPU1_P1P0_DN<7>")
	)
	(arc
		(start 375.74728 -214.261954)
		(mid 375.586925 -214.138568)
		(end 375.47677 -213.968838)
		(width 0.0889)
		(layer "In4.Cu")
		(net "UPI_CPU0_CPU1_P1P0_DN<7>")
	)
	(arc
		(start 375.274332 -216.739978)
		(mid 375.069997 -216.537373)
		(end 374.991884 -216.260426)
		(width 0.0889)
		(layer "In4.Cu")
		(net "UPI_CPU0_CPU1_P1P0_DN<7>")
	)
	(arc
		(start 375.753122 -214.941912)
		(mid 375.884036 -214.805552)
		(end 375.931684 -214.622634)
		(width 0.0889)
		(layer "In4.Cu")
		(net "UPI_CPU0_CPU1_P1P0_DN<7>")
	)
	(arc
		(start 375.931684 -214.461852)
		(mid 375.856613 -214.34611)
		(end 375.74728 -214.261954)
		(width 0.0889)
		(layer "In4.Cu")
		(net "UPI_CPU0_CPU1_P1P0_DN<7>")
	)
	(arc
		(start 375.20245 -218.319096)
		(mid 375.050368 -218.129664)
		(end 374.991884 -217.8939)
		(width 0.0889)
		(layer "In4.Cu")
		(net "UPI_CPU0_CPU1_P1P0_DN<7>")
	)
	(arc
		(start 374.991884 -216.231978)
		(mid 375.072046 -215.959789)
		(end 375.274332 -215.760808)
		(width 0.0889)
		(layer "In4.Cu")
		(net "UPI_CPU0_CPU1_P1P0_DN<7>")
	)
	(arc
		(start 374.991884 -217.859864)
		(mid 375.072046 -217.587675)
		(end 375.274332 -217.388694)
		(width 0.0889)
		(layer "In4.Cu")
		(net "UPI_CPU0_CPU1_P1P0_DN<7>")
	)
	(arc
		(start 96.083628 -214.20201)
		(mid 96.169712 -214.305243)
		(end 96.228154 -214.426292)
		(width 0.0889)
		(layer "In4.Cu")
		(net "UPI_CPU0_CPU1_P1P0_DN<7>")
	)
	(arc
		(start 95.95231 -215.764618)
		(mid 96.228884 -216.25052)
		(end 95.95231 -216.736422)
		(width 0.0889)
		(layer "In4.Cu")
		(net "UPI_CPU0_CPU1_P1P0_DN<7>")
	)
	(segment
		(start 94.723712 -218.414346)
		(end 94.723712 -217.87866)
		(width 0.13208)
		(layer "F.Cu")
		(net "UPI_CPU0_CPU1_P1P0_DN<6>")
	)
	(segment
		(start 376.49658 -217.87866)
		(end 376.496834 -217.878406)
		(width 0.13208)
		(layer "F.Cu")
		(net "UPI_CPU0_CPU1_P1P0_DN<6>")
	)
	(segment
		(start 94.723712 -217.87866)
		(end 94.723966 -217.878406)
		(width 0.13208)
		(layer "F.Cu")
		(net "UPI_CPU0_CPU1_P1P0_DN<6>")
	)
	(segment
		(start 376.49658 -218.414346)
		(end 376.49658 -217.87866)
		(width 0.13208)
		(layer "F.Cu")
		(net "UPI_CPU0_CPU1_P1P0_DN<6>")
	)
	(segment
		(start 376.592084 -213.8934)
		(end 376.592084 -211.911692)
		(width 0.0889)
		(layer "In4.Cu")
		(net "UPI_CPU0_CPU1_P1P0_DN<6>")
	)
	(segment
		(start 376.496834 -217.878406)
		(end 376.34037 -217.607388)
		(width 0.0889)
		(layer "In4.Cu")
		(net "UPI_CPU0_CPU1_P1P0_DN<6>")
	)
	(segment
		(start 376.309636 -216.574878)
		(end 376.300746 -216.569798)
		(width 0.0889)
		(layer "In4.Cu")
		(net "UPI_CPU0_CPU1_P1P0_DN<6>")
	)
	(segment
		(start 94.529656 -212.54974)
		(end 94.628716 -212.6488)
		(width 0.0889)
		(layer "In4.Cu")
		(net "UPI_CPU0_CPU1_P1P0_DN<6>")
	)
	(segment
		(start 94.586806 -211.504022)
		(end 94.586806 -211.72805)
		(width 0.14732)
		(layer "In4.Cu")
		(net "UPI_CPU0_CPU1_P1P0_DN<6>")
	)
	(segment
		(start 94.910402 -215.925654)
		(end 94.911926 -215.92667)
		(width 0.0889)
		(layer "In4.Cu")
		(net "UPI_CPU0_CPU1_P1P0_DN<6>")
	)
	(segment
		(start 95.098108 -214.461344)
		(end 95.098108 -214.622634)
		(width 0.0889)
		(layer "In4.Cu")
		(net "UPI_CPU0_CPU1_P1P0_DN<6>")
	)
	(segment
		(start 238.590074 -142.10157)
		(end 169.333926 -140.981938)
		(width 0.14732)
		(layer "In4.Cu")
		(net "UPI_CPU0_CPU1_P1P0_DN<6>")
	)
	(segment
		(start 276.298406 -141.42339)
		(end 238.590074 -142.10157)
		(width 0.14732)
		(layer "In4.Cu")
		(net "UPI_CPU0_CPU1_P1P0_DN<6>")
	)
	(segment
		(start 103.270304 -187.710318)
		(end 94.586552 -211.229448)
		(width 0.14732)
		(layer "In4.Cu")
		(net "UPI_CPU0_CPU1_P1P0_DN<6>")
	)
	(segment
		(start 376.634248 -211.572602)
		(end 376.633994 -211.572348)
		(width 0.14732)
		(layer "In4.Cu")
		(net "UPI_CPU0_CPU1_P1P0_DN<6>")
	)
	(segment
		(start 377.061984 -214.63254)
		(end 377.061984 -214.425022)
		(width 0.0889)
		(layer "In4.Cu")
		(net "UPI_CPU0_CPU1_P1P0_DN<6>")
	)
	(segment
		(start 94.529656 -212.37448)
		(end 94.529656 -212.54974)
		(width 0.0889)
		(layer "In4.Cu")
		(net "UPI_CPU0_CPU1_P1P0_DN<6>")
	)
	(segment
		(start 94.628716 -211.792058)
		(end 94.628716 -212.27542)
		(width 0.0889)
		(layer "In4.Cu")
		(net "UPI_CPU0_CPU1_P1P0_DN<6>")
	)
	(segment
		(start 94.628716 -212.27542)
		(end 94.529656 -212.37448)
		(width 0.0889)
		(layer "In4.Cu")
		(net "UPI_CPU0_CPU1_P1P0_DN<6>")
	)
	(segment
		(start 161.788094 -143.586962)
		(end 125.907038 -165.664896)
		(width 0.14732)
		(layer "In4.Cu")
		(net "UPI_CPU0_CPU1_P1P0_DN<6>")
	)
	(segment
		(start 376.592084 -211.911692)
		(end 376.634248 -211.869528)
		(width 0.0889)
		(layer "In4.Cu")
		(net "UPI_CPU0_CPU1_P1P0_DN<6>")
	)
	(segment
		(start 370.061998 -189.46114)
		(end 369.520978 -188.92012)
		(width 0.14732)
		(layer "In4.Cu")
		(net "UPI_CPU0_CPU1_P1P0_DN<6>")
	)
	(segment
		(start 165.552374 -142.287498)
		(end 161.788094 -143.586962)
		(width 0.14732)
		(layer "In4.Cu")
		(net "UPI_CPU0_CPU1_P1P0_DN<6>")
	)
	(segment
		(start 369.006628 -183.438292)
		(end 361.47629 -167.93083)
		(width 0.14732)
		(layer "In4.Cu")
		(net "UPI_CPU0_CPU1_P1P0_DN<6>")
	)
	(segment
		(start 169.333926 -140.981938)
		(end 165.552374 -142.287498)
		(width 0.14732)
		(layer "In4.Cu")
		(net "UPI_CPU0_CPU1_P1P0_DN<6>")
	)
	(segment
		(start 94.920054 -216.569798)
		(end 94.898972 -216.58199)
		(width 0.0889)
		(layer "In4.Cu")
		(net "UPI_CPU0_CPU1_P1P0_DN<6>")
	)
	(segment
		(start 376.770646 -215.117172)
		(end 376.778774 -215.1126)
		(width 0.0889)
		(layer "In4.Cu")
		(net "UPI_CPU0_CPU1_P1P0_DN<6>")
	)
	(segment
		(start 94.958662 -218.170252)
		(end 94.88043 -218.149424)
		(width 0.0889)
		(layer "In4.Cu")
		(net "UPI_CPU0_CPU1_P1P0_DN<6>")
	)
	(segment
		(start 376.34037 -217.607388)
		(end 376.3645 -217.518234)
		(width 0.0889)
		(layer "In4.Cu")
		(net "UPI_CPU0_CPU1_P1P0_DN<6>")
	)
	(segment
		(start 369.520978 -188.92012)
		(end 369.403376 -188.636148)
		(width 0.14732)
		(layer "In4.Cu")
		(net "UPI_CPU0_CPU1_P1P0_DN<6>")
	)
	(segment
		(start 376.300746 -215.931242)
		(end 376.310144 -215.925908)
		(width 0.0889)
		(layer "In4.Cu")
		(net "UPI_CPU0_CPU1_P1P0_DN<6>")
	)
	(segment
		(start 125.907038 -165.664896)
		(end 105.630726 -184.750456)
		(width 0.14732)
		(layer "In4.Cu")
		(net "UPI_CPU0_CPU1_P1P0_DN<6>")
	)
	(segment
		(start 369.03406 -186.779916)
		(end 369.03406 -183.465724)
		(width 0.14732)
		(layer "In4.Cu")
		(net "UPI_CPU0_CPU1_P1P0_DN<6>")
	)
	(segment
		(start 376.310144 -215.925908)
		(end 376.311922 -215.924892)
		(width 0.0889)
		(layer "In4.Cu")
		(net "UPI_CPU0_CPU1_P1P0_DN<6>")
	)
	(segment
		(start 94.90837 -215.924384)
		(end 94.910402 -215.925654)
		(width 0.0889)
		(layer "In4.Cu")
		(net "UPI_CPU0_CPU1_P1P0_DN<6>")
	)
	(segment
		(start 94.529656 -213.1314)
		(end 94.628716 -213.23046)
		(width 0.0889)
		(layer "In4.Cu")
		(net "UPI_CPU0_CPU1_P1P0_DN<6>")
	)
	(segment
		(start 318.193166 -143.033242)
		(end 318.193166 -143.032988)
		(width 0.14732)
		(layer "In4.Cu")
		(net "UPI_CPU0_CPU1_P1P0_DN<6>")
	)
	(segment
		(start 376.633994 -205.80223)
		(end 371.26164 -192.832228)
		(width 0.14732)
		(layer "In4.Cu")
		(net "UPI_CPU0_CPU1_P1P0_DN<6>")
	)
	(segment
		(start 94.905068 -215.922606)
		(end 94.90837 -215.924384)
		(width 0.0889)
		(layer "In4.Cu")
		(net "UPI_CPU0_CPU1_P1P0_DN<6>")
	)
	(segment
		(start 105.630726 -184.750456)
		(end 103.270304 -187.710318)
		(width 0.14732)
		(layer "In4.Cu")
		(net "UPI_CPU0_CPU1_P1P0_DN<6>")
	)
	(segment
		(start 94.586552 -211.503768)
		(end 94.586806 -211.504022)
		(width 0.14732)
		(layer "In4.Cu")
		(net "UPI_CPU0_CPU1_P1P0_DN<6>")
	)
	(segment
		(start 94.911926 -215.92667)
		(end 94.916752 -215.929464)
		(width 0.0889)
		(layer "In4.Cu")
		(net "UPI_CPU0_CPU1_P1P0_DN<6>")
	)
	(segment
		(start 94.586806 -211.72805)
		(end 94.586806 -211.750148)
		(width 0.0889)
		(layer "In4.Cu")
		(net "UPI_CPU0_CPU1_P1P0_DN<6>")
	)
	(segment
		(start 94.628716 -213.23046)
		(end 94.628716 -213.930484)
		(width 0.0889)
		(layer "In4.Cu")
		(net "UPI_CPU0_CPU1_P1P0_DN<6>")
	)
	(segment
		(start 94.88043 -218.149424)
		(end 94.723966 -217.878406)
		(width 0.0889)
		(layer "In4.Cu")
		(net "UPI_CPU0_CPU1_P1P0_DN<6>")
	)
	(segment
		(start 94.586806 -211.750148)
		(end 94.628716 -211.792058)
		(width 0.0889)
		(layer "In4.Cu")
		(net "UPI_CPU0_CPU1_P1P0_DN<6>")
	)
	(segment
		(start 94.586552 -211.229448)
		(end 94.586552 -211.503768)
		(width 0.14732)
		(layer "In4.Cu")
		(net "UPI_CPU0_CPU1_P1P0_DN<6>")
	)
	(segment
		(start 371.26164 -192.832228)
		(end 371.26164 -192.357502)
		(width 0.14732)
		(layer "In4.Cu")
		(net "UPI_CPU0_CPU1_P1P0_DN<6>")
	)
	(segment
		(start 371.26164 -192.357502)
		(end 370.061998 -189.46114)
		(width 0.14732)
		(layer "In4.Cu")
		(net "UPI_CPU0_CPU1_P1P0_DN<6>")
	)
	(segment
		(start 329.737466 -145.860516)
		(end 318.193166 -143.033242)
		(width 0.14732)
		(layer "In4.Cu")
		(net "UPI_CPU0_CPU1_P1P0_DN<6>")
	)
	(segment
		(start 376.778774 -215.1126)
		(end 376.779536 -215.112092)
		(width 0.0889)
		(layer "In4.Cu")
		(net "UPI_CPU0_CPU1_P1P0_DN<6>")
	)
	(segment
		(start 94.628716 -212.85708)
		(end 94.529656 -212.95614)
		(width 0.0889)
		(layer "In4.Cu")
		(net "UPI_CPU0_CPU1_P1P0_DN<6>")
	)
	(segment
		(start 314.74664 -143.025368)
		(end 276.298406 -141.42339)
		(width 0.14732)
		(layer "In4.Cu")
		(net "UPI_CPU0_CPU1_P1P0_DN<6>")
	)
	(segment
		(start 94.918784 -215.93048)
		(end 94.920054 -215.931242)
		(width 0.0889)
		(layer "In4.Cu")
		(net "UPI_CPU0_CPU1_P1P0_DN<6>")
	)
	(segment
		(start 376.633994 -211.572348)
		(end 376.633994 -205.80223)
		(width 0.14732)
		(layer "In4.Cu")
		(net "UPI_CPU0_CPU1_P1P0_DN<6>")
	)
	(segment
		(start 376.315732 -216.578434)
		(end 376.309636 -216.574878)
		(width 0.0889)
		(layer "In4.Cu")
		(net "UPI_CPU0_CPU1_P1P0_DN<6>")
	)
	(segment
		(start 318.193166 -143.032988)
		(end 318.161162 -143.025368)
		(width 0.14732)
		(layer "In4.Cu")
		(net "UPI_CPU0_CPU1_P1P0_DN<6>")
	)
	(segment
		(start 376.634248 -211.84743)
		(end 376.634248 -211.572602)
		(width 0.14732)
		(layer "In4.Cu")
		(net "UPI_CPU0_CPU1_P1P0_DN<6>")
	)
	(segment
		(start 94.911164 -217.554048)
		(end 94.920054 -217.559128)
		(width 0.0889)
		(layer "In4.Cu")
		(net "UPI_CPU0_CPU1_P1P0_DN<6>")
	)
	(segment
		(start 369.03406 -183.465724)
		(end 369.006628 -183.438292)
		(width 0.14732)
		(layer "In4.Cu")
		(net "UPI_CPU0_CPU1_P1P0_DN<6>")
	)
	(segment
		(start 94.916752 -215.929464)
		(end 94.918784 -215.93048)
		(width 0.0889)
		(layer "In4.Cu")
		(net "UPI_CPU0_CPU1_P1P0_DN<6>")
	)
	(segment
		(start 361.47629 -167.93083)
		(end 358.328722 -164.220144)
		(width 0.14732)
		(layer "In4.Cu")
		(net "UPI_CPU0_CPU1_P1P0_DN<6>")
	)
	(segment
		(start 376.634248 -211.869528)
		(end 376.634248 -211.84743)
		(width 0.0889)
		(layer "In4.Cu")
		(net "UPI_CPU0_CPU1_P1P0_DN<6>")
	)
	(segment
		(start 94.628716 -212.6488)
		(end 94.628716 -212.85708)
		(width 0.0889)
		(layer "In4.Cu")
		(net "UPI_CPU0_CPU1_P1P0_DN<6>")
	)
	(segment
		(start 358.328722 -164.220144)
		(end 329.737466 -145.860516)
		(width 0.14732)
		(layer "In4.Cu")
		(net "UPI_CPU0_CPU1_P1P0_DN<6>")
	)
	(segment
		(start 94.919546 -214.941912)
		(end 94.910656 -214.946992)
		(width 0.0889)
		(layer "In4.Cu")
		(net "UPI_CPU0_CPU1_P1P0_DN<6>")
	)
	(segment
		(start 376.311922 -215.924892)
		(end 376.315732 -215.922606)
		(width 0.0889)
		(layer "In4.Cu")
		(net "UPI_CPU0_CPU1_P1P0_DN<6>")
	)
	(segment
		(start 318.161162 -143.025368)
		(end 314.74664 -143.025368)
		(width 0.14732)
		(layer "In4.Cu")
		(net "UPI_CPU0_CPU1_P1P0_DN<6>")
	)
	(segment
		(start 94.529656 -212.95614)
		(end 94.529656 -213.1314)
		(width 0.0889)
		(layer "In4.Cu")
		(net "UPI_CPU0_CPU1_P1P0_DN<6>")
	)
	(segment
		(start 369.403376 -188.636148)
		(end 369.03406 -186.779916)
		(width 0.14732)
		(layer "In4.Cu")
		(net "UPI_CPU0_CPU1_P1P0_DN<6>")
	)
	(arc
		(start 377.061984 -214.425022)
		(mid 376.950646 -214.232122)
		(end 376.776488 -214.093298)
		(width 0.0889)
		(layer "In4.Cu")
		(net "UPI_CPU0_CPU1_P1P0_DN<6>")
	)
	(arc
		(start 95.098108 -214.622634)
		(mid 95.050429 -214.805534)
		(end 94.919546 -214.941912)
		(width 0.0889)
		(layer "In4.Cu")
		(net "UPI_CPU0_CPU1_P1P0_DN<6>")
	)
	(arc
		(start 376.592084 -215.43645)
		(mid 376.639763 -215.25355)
		(end 376.770646 -215.117172)
		(width 0.0889)
		(layer "In4.Cu")
		(net "UPI_CPU0_CPU1_P1P0_DN<6>")
	)
	(arc
		(start 94.628716 -213.930484)
		(mid 94.636001 -213.950046)
		(end 94.643956 -213.969346)
		(width 0.0889)
		(layer "In4.Cu")
		(net "UPI_CPU0_CPU1_P1P0_DN<6>")
	)
	(arc
		(start 376.300746 -216.569798)
		(mid 376.12227 -216.25052)
		(end 376.300746 -215.931242)
		(width 0.0889)
		(layer "In4.Cu")
		(net "UPI_CPU0_CPU1_P1P0_DN<6>")
	)
	(arc
		(start 94.898972 -216.58199)
		(mid 94.628561 -217.071457)
		(end 94.911164 -217.554048)
		(width 0.0889)
		(layer "In4.Cu")
		(net "UPI_CPU0_CPU1_P1P0_DN<6>")
	)
	(arc
		(start 376.315732 -215.922606)
		(mid 376.518208 -215.716083)
		(end 376.592084 -215.43645)
		(width 0.0889)
		(layer "In4.Cu")
		(net "UPI_CPU0_CPU1_P1P0_DN<6>")
	)
	(arc
		(start 94.910656 -214.946992)
		(mid 94.628133 -215.433205)
		(end 94.905068 -215.922606)
		(width 0.0889)
		(layer "In4.Cu")
		(net "UPI_CPU0_CPU1_P1P0_DN<6>")
	)
	(arc
		(start 94.913958 -214.261954)
		(mid 95.023105 -214.345882)
		(end 95.098108 -214.461344)
		(width 0.0889)
		(layer "In4.Cu")
		(net "UPI_CPU0_CPU1_P1P0_DN<6>")
	)
	(arc
		(start 376.779536 -215.112092)
		(mid 376.983871 -214.909487)
		(end 377.061984 -214.63254)
		(width 0.0889)
		(layer "In4.Cu")
		(net "UPI_CPU0_CPU1_P1P0_DN<6>")
	)
	(arc
		(start 94.643956 -213.969346)
		(mid 94.75395 -214.138715)
		(end 94.913958 -214.261954)
		(width 0.0889)
		(layer "In4.Cu")
		(net "UPI_CPU0_CPU1_P1P0_DN<6>")
	)
	(arc
		(start 376.776488 -214.093298)
		(mid 376.667092 -214.009201)
		(end 376.592084 -213.8934)
		(width 0.0889)
		(layer "In4.Cu")
		(net "UPI_CPU0_CPU1_P1P0_DN<6>")
	)
	(arc
		(start 94.920054 -215.931242)
		(mid 95.098651 -216.25052)
		(end 94.920054 -216.569798)
		(width 0.0889)
		(layer "In4.Cu")
		(net "UPI_CPU0_CPU1_P1P0_DN<6>")
	)
	(arc
		(start 376.3645 -217.518234)
		(mid 376.372943 -217.511836)
		(end 376.381264 -217.50528)
		(width 0.0889)
		(layer "In4.Cu")
		(net "UPI_CPU0_CPU1_P1P0_DN<6>")
	)
	(arc
		(start 94.920054 -217.559128)
		(mid 95.097902 -217.85472)
		(end 94.958662 -218.170252)
		(width 0.0889)
		(layer "In4.Cu")
		(net "UPI_CPU0_CPU1_P1P0_DN<6>")
	)
	(arc
		(start 376.381264 -217.50528)
		(mid 376.590902 -217.024709)
		(end 376.315732 -216.578434)
		(width 0.0889)
		(layer "In4.Cu")
		(net "UPI_CPU0_CPU1_P1P0_DN<6>")
	)
	(segment
		(start 376.966734 -219.228162)
		(end 376.966734 -218.692476)
		(width 0.13208)
		(layer "F.Cu")
		(net "UPI_CPU0_CPU1_P1P0_DN<5>")
	)
	(segment
		(start 376.966734 -218.692476)
		(end 376.96648 -218.692222)
		(width 0.13208)
		(layer "F.Cu")
		(net "UPI_CPU0_CPU1_P1P0_DN<5>")
	)
	(segment
		(start 94.254066 -217.600276)
		(end 94.254066 -217.06459)
		(width 0.13208)
		(layer "F.Cu")
		(net "UPI_CPU0_CPU1_P1P0_DN<5>")
	)
	(segment
		(start 94.254066 -217.06459)
		(end 94.253812 -217.064336)
		(width 0.13208)
		(layer "F.Cu")
		(net "UPI_CPU0_CPU1_P1P0_DN<5>")
	)
	(segment
		(start 105.145586 -184.409842)
		(end 102.485952 -187.744862)
		(width 0.14732)
		(layer "In4.Cu")
		(net "UPI_CPU0_CPU1_P1P0_DN<5>")
	)
	(segment
		(start 93.879416 -217.0557)
		(end 93.879416 -217.072972)
		(width 0.0889)
		(layer "In4.Cu")
		(net "UPI_CPU0_CPU1_P1P0_DN<5>")
	)
	(segment
		(start 377.623832 -214.946992)
		(end 377.632722 -214.941912)
		(width 0.0889)
		(layer "In4.Cu")
		(net "UPI_CPU0_CPU1_P1P0_DN<5>")
	)
	(segment
		(start 94.067376 -216.73947)
		(end 94.066614 -216.739978)
		(width 0.0889)
		(layer "In4.Cu")
		(net "UPI_CPU0_CPU1_P1P0_DN<5>")
	)
	(segment
		(start 377.299728 -211.869528)
		(end 377.299728 -211.84743)
		(width 0.0889)
		(layer "In4.Cu")
		(net "UPI_CPU0_CPU1_P1P0_DN<5>")
	)
	(segment
		(start 94.75978 -208.672176)
		(end 94.633034 -209.01533)
		(width 0.14732)
		(layer "In4.Cu")
		(net "UPI_CPU0_CPU1_P1P0_DN<5>")
	)
	(segment
		(start 94.059756 -215.757252)
		(end 94.063058 -215.75903)
		(width 0.0889)
		(layer "In4.Cu")
		(net "UPI_CPU0_CPU1_P1P0_DN<5>")
	)
	(segment
		(start 94.40418 -209.634836)
		(end 94.276672 -209.980276)
		(width 0.14732)
		(layer "In4.Cu")
		(net "UPI_CPU0_CPU1_P1P0_DN<5>")
	)
	(segment
		(start 371.888004 -183.228234)
		(end 371.809772 -183.039004)
		(width 0.14732)
		(layer "In4.Cu")
		(net "UPI_CPU0_CPU1_P1P0_DN<5>")
	)
	(segment
		(start 372.3894 -181.360318)
		(end 372.140226 -180.943504)
		(width 0.14732)
		(layer "In4.Cu")
		(net "UPI_CPU0_CPU1_P1P0_DN<5>")
	)
	(segment
		(start 358.681274 -163.776152)
		(end 329.963018 -145.33499)
		(width 0.14732)
		(layer "In4.Cu")
		(net "UPI_CPU0_CPU1_P1P0_DN<5>")
	)
	(segment
		(start 93.879162 -213.2457)
		(end 93.879162 -213.8934)
		(width 0.0889)
		(layer "In4.Cu")
		(net "UPI_CPU0_CPU1_P1P0_DN<5>")
	)
	(segment
		(start 94.068138 -215.762078)
		(end 94.07271 -215.764618)
		(width 0.0889)
		(layer "In4.Cu")
		(net "UPI_CPU0_CPU1_P1P0_DN<5>")
	)
	(segment
		(start 93.879162 -212.015832)
		(end 93.879162 -212.32368)
		(width 0.0889)
		(layer "In4.Cu")
		(net "UPI_CPU0_CPU1_P1P0_DN<5>")
	)
	(segment
		(start 377.122944 -218.421204)
		(end 377.098814 -218.33205)
		(width 0.0889)
		(layer "In4.Cu")
		(net "UPI_CPU0_CPU1_P1P0_DN<5>")
	)
	(segment
		(start 373.398288 -189.95517)
		(end 373.314722 -189.596268)
		(width 0.14732)
		(layer "In4.Cu")
		(net "UPI_CPU0_CPU1_P1P0_DN<5>")
	)
	(segment
		(start 376.96648 -218.692222)
		(end 377.122944 -218.421204)
		(width 0.0889)
		(layer "In4.Cu")
		(net "UPI_CPU0_CPU1_P1P0_DN<5>")
	)
	(segment
		(start 94.057724 -215.755982)
		(end 94.059756 -215.757252)
		(width 0.0889)
		(layer "In4.Cu")
		(net "UPI_CPU0_CPU1_P1P0_DN<5>")
	)
	(segment
		(start 93.879162 -213.8934)
		(end 93.879416 -213.893908)
		(width 0.0889)
		(layer "In4.Cu")
		(net "UPI_CPU0_CPU1_P1P0_DN<5>")
	)
	(segment
		(start 256.77368 -141.10335)
		(end 238.589566 -141.430248)
		(width 0.14732)
		(layer "In4.Cu")
		(net "UPI_CPU0_CPU1_P1P0_DN<5>")
	)
	(segment
		(start 256.77622 -141.10335)
		(end 256.77368 -141.10335)
		(width 0.14732)
		(layer "In4.Cu")
		(net "UPI_CPU0_CPU1_P1P0_DN<5>")
	)
	(segment
		(start 94.07271 -216.736422)
		(end 94.067376 -216.73947)
		(width 0.0889)
		(layer "In4.Cu")
		(net "UPI_CPU0_CPU1_P1P0_DN<5>")
	)
	(segment
		(start 373.630952 -190.954914)
		(end 373.54764 -190.596012)
		(width 0.14732)
		(layer "In4.Cu")
		(net "UPI_CPU0_CPU1_P1P0_DN<5>")
	)
	(segment
		(start 102.485952 -187.744862)
		(end 94.987872 -208.054956)
		(width 0.14732)
		(layer "In4.Cu")
		(net "UPI_CPU0_CPU1_P1P0_DN<5>")
	)
	(segment
		(start 94.063058 -215.75903)
		(end 94.06509 -215.7603)
		(width 0.0889)
		(layer "In4.Cu")
		(net "UPI_CPU0_CPU1_P1P0_DN<5>")
	)
	(segment
		(start 368.836194 -179.947062)
		(end 366.938814 -177.855626)
		(width 0.14732)
		(layer "In4.Cu")
		(net "UPI_CPU0_CPU1_P1P0_DN<5>")
	)
	(segment
		(start 371.64518 -185.222896)
		(end 371.64518 -183.814974)
		(width 0.14732)
		(layer "In4.Cu")
		(net "UPI_CPU0_CPU1_P1P0_DN<5>")
	)
	(segment
		(start 93.921072 -211.709508)
		(end 93.921326 -211.709762)
		(width 0.14732)
		(layer "In4.Cu")
		(net "UPI_CPU0_CPU1_P1P0_DN<5>")
	)
	(segment
		(start 161.577274 -143.051022)
		(end 125.504448 -165.247066)
		(width 0.14732)
		(layer "In4.Cu")
		(net "UPI_CPU0_CPU1_P1P0_DN<5>")
	)
	(segment
		(start 94.632272 -209.017616)
		(end 94.71787 -209.203544)
		(width 0.14732)
		(layer "In4.Cu")
		(net "UPI_CPU0_CPU1_P1P0_DN<5>")
	)
	(segment
		(start 94.36227 -210.166204)
		(end 94.234762 -210.511898)
		(width 0.14732)
		(layer "In4.Cu")
		(net "UPI_CPU0_CPU1_P1P0_DN<5>")
	)
	(segment
		(start 361.9881 -167.663368)
		(end 358.681274 -163.776152)
		(width 0.14732)
		(layer "In4.Cu")
		(net "UPI_CPU0_CPU1_P1P0_DN<5>")
	)
	(segment
		(start 377.299728 -211.84743)
		(end 377.299728 -211.686394)
		(width 0.14732)
		(layer "In4.Cu")
		(net "UPI_CPU0_CPU1_P1P0_DN<5>")
	)
	(segment
		(start 373.422926 -189.422532)
		(end 373.022876 -187.703206)
		(width 0.14732)
		(layer "In4.Cu")
		(net "UPI_CPU0_CPU1_P1P0_DN<5>")
	)
	(segment
		(start 377.811284 -214.622634)
		(end 377.811284 -214.461852)
		(width 0.0889)
		(layer "In4.Cu")
		(net "UPI_CPU0_CPU1_P1P0_DN<5>")
	)
	(segment
		(start 94.065598 -215.112854)
		(end 94.057724 -215.117426)
		(width 0.0889)
		(layer "In4.Cu")
		(net "UPI_CPU0_CPU1_P1P0_DN<5>")
	)
	(segment
		(start 377.34113 -217.072972)
		(end 377.34113 -217.0557)
		(width 0.0889)
		(layer "In4.Cu")
		(net "UPI_CPU0_CPU1_P1P0_DN<5>")
	)
	(segment
		(start 93.879162 -212.32368)
		(end 93.978222 -212.42274)
		(width 0.0889)
		(layer "In4.Cu")
		(net "UPI_CPU0_CPU1_P1P0_DN<5>")
	)
	(segment
		(start 371.950488 -182.69839)
		(end 372.139972 -182.620158)
		(width 0.14732)
		(layer "In4.Cu")
		(net "UPI_CPU0_CPU1_P1P0_DN<5>")
	)
	(segment
		(start 373.804942 -191.062864)
		(end 373.630952 -190.954914)
		(width 0.14732)
		(layer "In4.Cu")
		(net "UPI_CPU0_CPU1_P1P0_DN<5>")
	)
	(segment
		(start 94.590362 -209.549238)
		(end 94.40418 -209.634836)
		(width 0.14732)
		(layer "In4.Cu")
		(net "UPI_CPU0_CPU1_P1P0_DN<5>")
	)
	(segment
		(start 315.285628 -142.461488)
		(end 274.87372 -140.777976)
		(width 0.14732)
		(layer "In4.Cu")
		(net "UPI_CPU0_CPU1_P1P0_DN<5>")
	)
	(segment
		(start 94.234762 -210.511898)
		(end 94.04858 -210.597496)
		(width 0.14732)
		(layer "In4.Cu")
		(net "UPI_CPU0_CPU1_P1P0_DN<5>")
	)
	(segment
		(start 93.921326 -211.95157)
		(end 93.921326 -211.973668)
		(width 0.0889)
		(layer "In4.Cu")
		(net "UPI_CPU0_CPU1_P1P0_DN<5>")
	)
	(segment
		(start 94.945962 -208.586578)
		(end 94.75978 -208.672176)
		(width 0.14732)
		(layer "In4.Cu")
		(net "UPI_CPU0_CPU1_P1P0_DN<5>")
	)
	(segment
		(start 93.978222 -212.598)
		(end 93.879162 -212.69706)
		(width 0.0889)
		(layer "In4.Cu")
		(net "UPI_CPU0_CPU1_P1P0_DN<5>")
	)
	(segment
		(start 94.06509 -215.7603)
		(end 94.066614 -215.761062)
		(width 0.0889)
		(layer "In4.Cu")
		(net "UPI_CPU0_CPU1_P1P0_DN<5>")
	)
	(segment
		(start 93.921072 -210.942936)
		(end 93.921072 -211.709508)
		(width 0.14732)
		(layer "In4.Cu")
		(net "UPI_CPU0_CPU1_P1P0_DN<5>")
	)
	(segment
		(start 369.258342 -180.187346)
		(end 368.836194 -179.947062)
		(width 0.14732)
		(layer "In4.Cu")
		(net "UPI_CPU0_CPU1_P1P0_DN<5>")
	)
	(segment
		(start 373.572278 -190.06312)
		(end 373.398288 -189.95517)
		(width 0.14732)
		(layer "In4.Cu")
		(net "UPI_CPU0_CPU1_P1P0_DN<5>")
	)
	(segment
		(start 376.871484 -216.260426)
		(end 376.871484 -216.231978)
		(width 0.0889)
		(layer "In4.Cu")
		(net "UPI_CPU0_CPU1_P1P0_DN<5>")
	)
	(segment
		(start 94.097348 -217.335354)
		(end 94.253812 -217.064336)
		(width 0.0889)
		(layer "In4.Cu")
		(net "UPI_CPU0_CPU1_P1P0_DN<5>")
	)
	(segment
		(start 370.072666 -180.352954)
		(end 369.258342 -180.187346)
		(width 0.14732)
		(layer "In4.Cu")
		(net "UPI_CPU0_CPU1_P1P0_DN<5>")
	)
	(segment
		(start 372.139972 -182.620158)
		(end 372.389146 -182.018178)
		(width 0.14732)
		(layer "In4.Cu")
		(net "UPI_CPU0_CPU1_P1P0_DN<5>")
	)
	(segment
		(start 95.07347 -208.240884)
		(end 94.945962 -208.586578)
		(width 0.14732)
		(layer "In4.Cu")
		(net "UPI_CPU0_CPU1_P1P0_DN<5>")
	)
	(segment
		(start 370.546884 -180.597302)
		(end 370.185696 -180.523896)
		(width 0.14732)
		(layer "In4.Cu")
		(net "UPI_CPU0_CPU1_P1P0_DN<5>")
	)
	(segment
		(start 94.633034 -209.01533)
		(end 94.632272 -209.017616)
		(width 0.14732)
		(layer "In4.Cu")
		(net "UPI_CPU0_CPU1_P1P0_DN<5>")
	)
	(segment
		(start 93.978222 -213.14664)
		(end 93.879162 -213.2457)
		(width 0.0889)
		(layer "In4.Cu")
		(net "UPI_CPU0_CPU1_P1P0_DN<5>")
	)
	(segment
		(start 94.066614 -215.761062)
		(end 94.068138 -215.762078)
		(width 0.0889)
		(layer "In4.Cu")
		(net "UPI_CPU0_CPU1_P1P0_DN<5>")
	)
	(segment
		(start 373.54764 -190.596012)
		(end 373.655844 -190.422022)
		(width 0.14732)
		(layer "In4.Cu")
		(net "UPI_CPU0_CPU1_P1P0_DN<5>")
	)
	(segment
		(start 377.299474 -211.68614)
		(end 377.299474 -206.073248)
		(width 0.14732)
		(layer "In4.Cu")
		(net "UPI_CPU0_CPU1_P1P0_DN<5>")
	)
	(segment
		(start 377.341384 -213.93023)
		(end 377.341384 -211.911184)
		(width 0.0889)
		(layer "In4.Cu")
		(net "UPI_CPU0_CPU1_P1P0_DN<5>")
	)
	(segment
		(start 372.3894 -182.017924)
		(end 372.3894 -181.360318)
		(width 0.14732)
		(layer "In4.Cu")
		(net "UPI_CPU0_CPU1_P1P0_DN<5>")
	)
	(segment
		(start 377.299728 -211.686394)
		(end 377.299474 -211.68614)
		(width 0.14732)
		(layer "In4.Cu")
		(net "UPI_CPU0_CPU1_P1P0_DN<5>")
	)
	(segment
		(start 373.314722 -189.596268)
		(end 373.422926 -189.422532)
		(width 0.14732)
		(layer "In4.Cu")
		(net "UPI_CPU0_CPU1_P1P0_DN<5>")
	)
	(segment
		(start 376.871484 -217.8939)
		(end 376.871484 -217.859864)
		(width 0.0889)
		(layer "In4.Cu")
		(net "UPI_CPU0_CPU1_P1P0_DN<5>")
	)
	(segment
		(start 373.022876 -187.703206)
		(end 371.64518 -185.222896)
		(width 0.14732)
		(layer "In4.Cu")
		(net "UPI_CPU0_CPU1_P1P0_DN<5>")
	)
	(segment
		(start 93.978222 -212.42274)
		(end 93.978222 -212.598)
		(width 0.0889)
		(layer "In4.Cu")
		(net "UPI_CPU0_CPU1_P1P0_DN<5>")
	)
	(segment
		(start 94.01937 -217.356182)
		(end 94.097348 -217.335354)
		(width 0.0889)
		(layer "In4.Cu")
		(net "UPI_CPU0_CPU1_P1P0_DN<5>")
	)
	(segment
		(start 94.987872 -208.054956)
		(end 95.07347 -208.240884)
		(width 0.14732)
		(layer "In4.Cu")
		(net "UPI_CPU0_CPU1_P1P0_DN<5>")
	)
	(segment
		(start 93.921326 -211.709762)
		(end 93.921326 -211.95157)
		(width 0.14732)
		(layer "In4.Cu")
		(net "UPI_CPU0_CPU1_P1P0_DN<5>")
	)
	(segment
		(start 169.507154 -140.313156)
		(end 161.577274 -143.051022)
		(width 0.14732)
		(layer "In4.Cu")
		(net "UPI_CPU0_CPU1_P1P0_DN<5>")
	)
	(segment
		(start 318.229488 -142.461488)
		(end 315.285628 -142.461488)
		(width 0.14732)
		(layer "In4.Cu")
		(net "UPI_CPU0_CPU1_P1P0_DN<5>")
	)
	(segment
		(start 377.341384 -211.911184)
		(end 377.299728 -211.869528)
		(width 0.0889)
		(layer "In4.Cu")
		(net "UPI_CPU0_CPU1_P1P0_DN<5>")
	)
	(segment
		(start 93.879162 -212.87232)
		(end 93.978222 -212.97138)
		(width 0.0889)
		(layer "In4.Cu")
		(net "UPI_CPU0_CPU1_P1P0_DN<5>")
	)
	(segment
		(start 238.589566 -141.430248)
		(end 169.507154 -140.313156)
		(width 0.14732)
		(layer "In4.Cu")
		(net "UPI_CPU0_CPU1_P1P0_DN<5>")
	)
	(segment
		(start 372.389146 -182.018178)
		(end 372.3894 -182.017924)
		(width 0.14732)
		(layer "In4.Cu")
		(net "UPI_CPU0_CPU1_P1P0_DN<5>")
	)
	(segment
		(start 371.809772 -183.039004)
		(end 371.950488 -182.69839)
		(width 0.14732)
		(layer "In4.Cu")
		(net "UPI_CPU0_CPU1_P1P0_DN<5>")
	)
	(segment
		(start 371.64518 -183.814974)
		(end 371.888004 -183.228234)
		(width 0.14732)
		(layer "In4.Cu")
		(net "UPI_CPU0_CPU1_P1P0_DN<5>")
	)
	(segment
		(start 94.04858 -210.597496)
		(end 93.921072 -210.942936)
		(width 0.14732)
		(layer "In4.Cu")
		(net "UPI_CPU0_CPU1_P1P0_DN<5>")
	)
	(segment
		(start 372.140226 -180.943504)
		(end 371.849904 -180.71465)
		(width 0.14732)
		(layer "In4.Cu")
		(net "UPI_CPU0_CPU1_P1P0_DN<5>")
	)
	(segment
		(start 94.71787 -209.203544)
		(end 94.590362 -209.549238)
		(width 0.14732)
		(layer "In4.Cu")
		(net "UPI_CPU0_CPU1_P1P0_DN<5>")
	)
	(segment
		(start 125.504448 -165.247066)
		(end 105.145586 -184.409842)
		(width 0.14732)
		(layer "In4.Cu")
		(net "UPI_CPU0_CPU1_P1P0_DN<5>")
	)
	(segment
		(start 377.299474 -206.073248)
		(end 373.804942 -191.062864)
		(width 0.14732)
		(layer "In4.Cu")
		(net "UPI_CPU0_CPU1_P1P0_DN<5>")
	)
	(segment
		(start 373.655844 -190.422022)
		(end 373.572278 -190.06312)
		(width 0.14732)
		(layer "In4.Cu")
		(net "UPI_CPU0_CPU1_P1P0_DN<5>")
	)
	(segment
		(start 94.066614 -215.112346)
		(end 94.065598 -215.112854)
		(width 0.0889)
		(layer "In4.Cu")
		(net "UPI_CPU0_CPU1_P1P0_DN<5>")
	)
	(segment
		(start 93.978222 -212.97138)
		(end 93.978222 -213.14664)
		(width 0.0889)
		(layer "In4.Cu")
		(net "UPI_CPU0_CPU1_P1P0_DN<5>")
	)
	(segment
		(start 93.921326 -211.973668)
		(end 93.879162 -212.015832)
		(width 0.0889)
		(layer "In4.Cu")
		(net "UPI_CPU0_CPU1_P1P0_DN<5>")
	)
	(segment
		(start 366.938814 -177.855626)
		(end 361.9881 -167.663368)
		(width 0.14732)
		(layer "In4.Cu")
		(net "UPI_CPU0_CPU1_P1P0_DN<5>")
	)
	(segment
		(start 94.276672 -209.980276)
		(end 94.36227 -210.166204)
		(width 0.14732)
		(layer "In4.Cu")
		(net "UPI_CPU0_CPU1_P1P0_DN<5>")
	)
	(segment
		(start 274.87372 -140.777976)
		(end 256.77622 -141.10335)
		(width 0.14732)
		(layer "In4.Cu")
		(net "UPI_CPU0_CPU1_P1P0_DN<5>")
	)
	(segment
		(start 329.963018 -145.33499)
		(end 318.229488 -142.461488)
		(width 0.14732)
		(layer "In4.Cu")
		(net "UPI_CPU0_CPU1_P1P0_DN<5>")
	)
	(segment
		(start 370.185696 -180.523896)
		(end 370.072666 -180.352954)
		(width 0.14732)
		(layer "In4.Cu")
		(net "UPI_CPU0_CPU1_P1P0_DN<5>")
	)
	(segment
		(start 94.348808 -214.424768)
		(end 94.348808 -214.644732)
		(width 0.0889)
		(layer "In4.Cu")
		(net "UPI_CPU0_CPU1_P1P0_DN<5>")
	)
	(segment
		(start 377.34113 -215.445086)
		(end 377.34113 -215.43645)
		(width 0.0889)
		(layer "In4.Cu")
		(net "UPI_CPU0_CPU1_P1P0_DN<5>")
	)
	(segment
		(start 93.879162 -212.69706)
		(end 93.879162 -212.87232)
		(width 0.0889)
		(layer "In4.Cu")
		(net "UPI_CPU0_CPU1_P1P0_DN<5>")
	)
	(segment
		(start 377.34113 -215.43645)
		(end 377.341384 -215.422226)
		(width 0.0889)
		(layer "In4.Cu")
		(net "UPI_CPU0_CPU1_P1P0_DN<5>")
	)
	(segment
		(start 371.849904 -180.71465)
		(end 370.717572 -180.484272)
		(width 0.14732)
		(layer "In4.Cu")
		(net "UPI_CPU0_CPU1_P1P0_DN<5>")
	)
	(segment
		(start 370.717572 -180.484272)
		(end 370.546884 -180.597302)
		(width 0.14732)
		(layer "In4.Cu")
		(net "UPI_CPU0_CPU1_P1P0_DN<5>")
	)
	(arc
		(start 94.07271 -215.764618)
		(mid 94.349284 -216.25052)
		(end 94.07271 -216.736422)
		(width 0.0889)
		(layer "In4.Cu")
		(net "UPI_CPU0_CPU1_P1P0_DN<5>")
	)
	(arc
		(start 376.871484 -216.231978)
		(mid 376.951646 -215.959789)
		(end 377.153932 -215.760808)
		(width 0.0889)
		(layer "In4.Cu")
		(net "UPI_CPU0_CPU1_P1P0_DN<5>")
	)
	(arc
		(start 377.62688 -214.261954)
		(mid 377.466525 -214.138568)
		(end 377.35637 -213.968838)
		(width 0.0889)
		(layer "In4.Cu")
		(net "UPI_CPU0_CPU1_P1P0_DN<5>")
	)
	(arc
		(start 377.153932 -217.388694)
		(mid 377.288865 -217.25534)
		(end 377.34113 -217.072972)
		(width 0.0889)
		(layer "In4.Cu")
		(net "UPI_CPU0_CPU1_P1P0_DN<5>")
	)
	(arc
		(start 377.153932 -216.739978)
		(mid 376.949597 -216.537373)
		(end 376.871484 -216.260426)
		(width 0.0889)
		(layer "In4.Cu")
		(net "UPI_CPU0_CPU1_P1P0_DN<5>")
	)
	(arc
		(start 94.057724 -215.117426)
		(mid 93.93047 -215.247392)
		(end 93.879416 -215.421972)
		(width 0.0889)
		(layer "In4.Cu")
		(net "UPI_CPU0_CPU1_P1P0_DN<5>")
	)
	(arc
		(start 377.153932 -215.760808)
		(mid 377.288865 -215.627454)
		(end 377.34113 -215.445086)
		(width 0.0889)
		(layer "In4.Cu")
		(net "UPI_CPU0_CPU1_P1P0_DN<5>")
	)
	(arc
		(start 93.879416 -217.072972)
		(mid 93.91809 -217.23004)
		(end 94.01937 -217.356182)
		(width 0.0889)
		(layer "In4.Cu")
		(net "UPI_CPU0_CPU1_P1P0_DN<5>")
	)
	(arc
		(start 377.098814 -218.33205)
		(mid 377.090373 -218.32565)
		(end 377.08205 -218.319096)
		(width 0.0889)
		(layer "In4.Cu")
		(net "UPI_CPU0_CPU1_P1P0_DN<5>")
	)
	(arc
		(start 94.063566 -214.093298)
		(mid 94.237529 -214.232062)
		(end 94.348808 -214.424768)
		(width 0.0889)
		(layer "In4.Cu")
		(net "UPI_CPU0_CPU1_P1P0_DN<5>")
	)
	(arc
		(start 93.879416 -213.893908)
		(mid 93.954421 -214.009367)
		(end 94.063566 -214.093298)
		(width 0.0889)
		(layer "In4.Cu")
		(net "UPI_CPU0_CPU1_P1P0_DN<5>")
	)
	(arc
		(start 377.34113 -217.0557)
		(mid 377.28886 -216.873335)
		(end 377.153932 -216.739978)
		(width 0.0889)
		(layer "In4.Cu")
		(net "UPI_CPU0_CPU1_P1P0_DN<5>")
	)
	(arc
		(start 94.348808 -214.644732)
		(mid 94.267897 -214.91486)
		(end 94.066614 -215.112346)
		(width 0.0889)
		(layer "In4.Cu")
		(net "UPI_CPU0_CPU1_P1P0_DN<5>")
	)
	(arc
		(start 377.632722 -214.941912)
		(mid 377.763636 -214.805552)
		(end 377.811284 -214.622634)
		(width 0.0889)
		(layer "In4.Cu")
		(net "UPI_CPU0_CPU1_P1P0_DN<5>")
	)
	(arc
		(start 377.35637 -213.968838)
		(mid 377.348548 -213.949662)
		(end 377.341384 -213.93023)
		(width 0.0889)
		(layer "In4.Cu")
		(net "UPI_CPU0_CPU1_P1P0_DN<5>")
	)
	(arc
		(start 376.871484 -217.859864)
		(mid 376.951646 -217.587675)
		(end 377.153932 -217.388694)
		(width 0.0889)
		(layer "In4.Cu")
		(net "UPI_CPU0_CPU1_P1P0_DN<5>")
	)
	(arc
		(start 94.066614 -216.739978)
		(mid 93.931681 -216.873332)
		(end 93.879416 -217.0557)
		(width 0.0889)
		(layer "In4.Cu")
		(net "UPI_CPU0_CPU1_P1P0_DN<5>")
	)
	(arc
		(start 93.879162 -215.436704)
		(mid 93.926841 -215.619604)
		(end 94.057724 -215.755982)
		(width 0.0889)
		(layer "In4.Cu")
		(net "UPI_CPU0_CPU1_P1P0_DN<5>")
	)
	(arc
		(start 377.08205 -218.319096)
		(mid 376.929968 -218.129664)
		(end 376.871484 -217.8939)
		(width 0.0889)
		(layer "In4.Cu")
		(net "UPI_CPU0_CPU1_P1P0_DN<5>")
	)
	(arc
		(start 93.879416 -215.421972)
		(mid 93.879219 -215.429337)
		(end 93.879162 -215.436704)
		(width 0.0889)
		(layer "In4.Cu")
		(net "UPI_CPU0_CPU1_P1P0_DN<5>")
	)
	(arc
		(start 377.341384 -215.422226)
		(mid 377.420515 -215.14769)
		(end 377.623832 -214.946992)
		(width 0.0889)
		(layer "In4.Cu")
		(net "UPI_CPU0_CPU1_P1P0_DN<5>")
	)
	(arc
		(start 377.811284 -214.461852)
		(mid 377.736213 -214.34611)
		(end 377.62688 -214.261954)
		(width 0.0889)
		(layer "In4.Cu")
		(net "UPI_CPU0_CPU1_P1P0_DN<5>")
	)
	(segment
		(start 92.844112 -217.87866)
		(end 92.844366 -217.878406)
		(width 0.13208)
		(layer "F.Cu")
		(net "UPI_CPU0_CPU1_P1P0_DN<4>")
	)
	(segment
		(start 378.37618 -218.414346)
		(end 378.37618 -217.87866)
		(width 0.13208)
		(layer "F.Cu")
		(net "UPI_CPU0_CPU1_P1P0_DN<4>")
	)
	(segment
		(start 92.844112 -218.414346)
		(end 92.844112 -217.87866)
		(width 0.13208)
		(layer "F.Cu")
		(net "UPI_CPU0_CPU1_P1P0_DN<4>")
	)
	(segment
		(start 378.37618 -217.87866)
		(end 378.376434 -217.878406)
		(width 0.13208)
		(layer "F.Cu")
		(net "UPI_CPU0_CPU1_P1P0_DN<4>")
	)
	(segment
		(start 92.70746 -211.590382)
		(end 92.70746 -211.89315)
		(width 0.14732)
		(layer "In4.Cu")
		(net "UPI_CPU0_CPU1_P1P0_DN<4>")
	)
	(segment
		(start 378.471684 -217.07856)
		(end 378.471684 -217.064336)
		(width 0.0889)
		(layer "In4.Cu")
		(net "UPI_CPU0_CPU1_P1P0_DN<4>")
	)
	(segment
		(start 378.376434 -217.878406)
		(end 378.360686 -217.851228)
		(width 0.0889)
		(layer "In4.Cu")
		(net "UPI_CPU0_CPU1_P1P0_DN<4>")
	)
	(segment
		(start 378.471684 -213.8934)
		(end 378.471684 -211.911692)
		(width 0.0889)
		(layer "In4.Cu")
		(net "UPI_CPU0_CPU1_P1P0_DN<4>")
	)
	(segment
		(start 378.650246 -215.117172)
		(end 378.658374 -215.1126)
		(width 0.0889)
		(layer "In4.Cu")
		(net "UPI_CPU0_CPU1_P1P0_DN<4>")
	)
	(segment
		(start 318.363092 -141.359128)
		(end 315.374274 -141.359128)
		(width 0.14732)
		(layer "In4.Cu")
		(net "UPI_CPU0_CPU1_P1P0_DN<4>")
	)
	(segment
		(start 376.24512 -182.321708)
		(end 375.8311 -181.734968)
		(width 0.14732)
		(layer "In4.Cu")
		(net "UPI_CPU0_CPU1_P1P0_DN<4>")
	)
	(segment
		(start 92.707206 -211.590128)
		(end 92.70746 -211.590382)
		(width 0.14732)
		(layer "In4.Cu")
		(net "UPI_CPU0_CPU1_P1P0_DN<4>")
	)
	(segment
		(start 93.031564 -217.554048)
		(end 93.040454 -217.559128)
		(width 0.0889)
		(layer "In4.Cu")
		(net "UPI_CPU0_CPU1_P1P0_DN<4>")
	)
	(segment
		(start 378.513848 -211.572602)
		(end 378.513594 -211.572348)
		(width 0.14732)
		(layer "In4.Cu")
		(net "UPI_CPU0_CPU1_P1P0_DN<4>")
	)
	(segment
		(start 93.02877 -215.924384)
		(end 93.030802 -215.925654)
		(width 0.0889)
		(layer "In4.Cu")
		(net "UPI_CPU0_CPU1_P1P0_DN<4>")
	)
	(segment
		(start 378.189236 -216.574878)
		(end 378.180346 -216.569798)
		(width 0.0889)
		(layer "In4.Cu")
		(net "UPI_CPU0_CPU1_P1P0_DN<4>")
	)
	(segment
		(start 369.113816 -176.806352)
		(end 366.583214 -174.599092)
		(width 0.14732)
		(layer "In4.Cu")
		(net "UPI_CPU0_CPU1_P1P0_DN<4>")
	)
	(segment
		(start 378.195332 -216.578434)
		(end 378.189236 -216.574878)
		(width 0.0889)
		(layer "In4.Cu")
		(net "UPI_CPU0_CPU1_P1P0_DN<4>")
	)
	(segment
		(start 378.513848 -211.84743)
		(end 378.513848 -211.572602)
		(width 0.14732)
		(layer "In4.Cu")
		(net "UPI_CPU0_CPU1_P1P0_DN<4>")
	)
	(segment
		(start 378.658374 -215.1126)
		(end 378.659136 -215.112092)
		(width 0.0889)
		(layer "In4.Cu")
		(net "UPI_CPU0_CPU1_P1P0_DN<4>")
	)
	(segment
		(start 93.031818 -214.946484)
		(end 93.031056 -214.946992)
		(width 0.0889)
		(layer "In4.Cu")
		(net "UPI_CPU0_CPU1_P1P0_DN<4>")
	)
	(segment
		(start 92.74937 -213.07044)
		(end 92.65031 -213.1695)
		(width 0.0889)
		(layer "In4.Cu")
		(net "UPI_CPU0_CPU1_P1P0_DN<4>")
	)
	(segment
		(start 92.65031 -212.57006)
		(end 92.65031 -212.74532)
		(width 0.0889)
		(layer "In4.Cu")
		(net "UPI_CPU0_CPU1_P1P0_DN<4>")
	)
	(segment
		(start 93.218508 -214.461344)
		(end 93.218508 -214.622634)
		(width 0.0889)
		(layer "In4.Cu")
		(net "UPI_CPU0_CPU1_P1P0_DN<4>")
	)
	(segment
		(start 92.707206 -210.661758)
		(end 92.707206 -211.590128)
		(width 0.14732)
		(layer "In4.Cu")
		(net "UPI_CPU0_CPU1_P1P0_DN<4>")
	)
	(segment
		(start 92.65031 -213.34476)
		(end 92.74937 -213.44382)
		(width 0.0889)
		(layer "In4.Cu")
		(net "UPI_CPU0_CPU1_P1P0_DN<4>")
	)
	(segment
		(start 378.941584 -214.63254)
		(end 378.941584 -214.425022)
		(width 0.0889)
		(layer "In4.Cu")
		(net "UPI_CPU0_CPU1_P1P0_DN<4>")
	)
	(segment
		(start 238.586518 -140.221208)
		(end 169.613326 -139.105894)
		(width 0.14732)
		(layer "In4.Cu")
		(net "UPI_CPU0_CPU1_P1P0_DN<4>")
	)
	(segment
		(start 93.027754 -216.577164)
		(end 93.019372 -216.58199)
		(width 0.0889)
		(layer "In4.Cu")
		(net "UPI_CPU0_CPU1_P1P0_DN<4>")
	)
	(segment
		(start 104.318816 -183.644794)
		(end 101.270308 -187.46724)
		(width 0.14732)
		(layer "In4.Cu")
		(net "UPI_CPU0_CPU1_P1P0_DN<4>")
	)
	(segment
		(start 101.270308 -187.46724)
		(end 92.707206 -210.661758)
		(width 0.14732)
		(layer "In4.Cu")
		(net "UPI_CPU0_CPU1_P1P0_DN<4>")
	)
	(segment
		(start 93.079062 -218.170252)
		(end 93.00083 -218.149424)
		(width 0.0889)
		(layer "In4.Cu")
		(net "UPI_CPU0_CPU1_P1P0_DN<4>")
	)
	(segment
		(start 378.189236 -215.926162)
		(end 378.195332 -215.922606)
		(width 0.0889)
		(layer "In4.Cu")
		(net "UPI_CPU0_CPU1_P1P0_DN<4>")
	)
	(segment
		(start 93.00083 -218.149424)
		(end 92.844366 -217.878406)
		(width 0.0889)
		(layer "In4.Cu")
		(net "UPI_CPU0_CPU1_P1P0_DN<4>")
	)
	(segment
		(start 238.590836 -140.221208)
		(end 238.586518 -140.221208)
		(width 0.14732)
		(layer "In4.Cu")
		(net "UPI_CPU0_CPU1_P1P0_DN<4>")
	)
	(segment
		(start 378.471684 -211.911692)
		(end 378.513848 -211.869528)
		(width 0.0889)
		(layer "In4.Cu")
		(net "UPI_CPU0_CPU1_P1P0_DN<4>")
	)
	(segment
		(start 93.039946 -214.941912)
		(end 93.032834 -214.945976)
		(width 0.0889)
		(layer "In4.Cu")
		(net "UPI_CPU0_CPU1_P1P0_DN<4>")
	)
	(segment
		(start 124.812806 -164.355526)
		(end 104.318816 -183.644794)
		(width 0.14732)
		(layer "In4.Cu")
		(net "UPI_CPU0_CPU1_P1P0_DN<4>")
	)
	(segment
		(start 378.512324 -206.060548)
		(end 376.244866 -182.321962)
		(width 0.14732)
		(layer "In4.Cu")
		(net "UPI_CPU0_CPU1_P1P0_DN<4>")
	)
	(segment
		(start 92.70746 -211.915248)
		(end 92.74937 -211.957158)
		(width 0.0889)
		(layer "In4.Cu")
		(net "UPI_CPU0_CPU1_P1P0_DN<4>")
	)
	(segment
		(start 161.03346 -142.068296)
		(end 124.812806 -164.355526)
		(width 0.14732)
		(layer "In4.Cu")
		(net "UPI_CPU0_CPU1_P1P0_DN<4>")
	)
	(segment
		(start 378.180346 -215.931242)
		(end 378.189236 -215.926162)
		(width 0.0889)
		(layer "In4.Cu")
		(net "UPI_CPU0_CPU1_P1P0_DN<4>")
	)
	(segment
		(start 273.151854 -139.599924)
		(end 238.590836 -140.221208)
		(width 0.14732)
		(layer "In4.Cu")
		(net "UPI_CPU0_CPU1_P1P0_DN<4>")
	)
	(segment
		(start 93.030802 -215.925654)
		(end 93.032326 -215.92667)
		(width 0.0889)
		(layer "In4.Cu")
		(net "UPI_CPU0_CPU1_P1P0_DN<4>")
	)
	(segment
		(start 330.403962 -144.30756)
		(end 318.363092 -141.359128)
		(width 0.14732)
		(layer "In4.Cu")
		(net "UPI_CPU0_CPU1_P1P0_DN<4>")
	)
	(segment
		(start 92.74937 -212.84438)
		(end 92.74937 -213.07044)
		(width 0.0889)
		(layer "In4.Cu")
		(net "UPI_CPU0_CPU1_P1P0_DN<4>")
	)
	(segment
		(start 92.74937 -212.471)
		(end 92.65031 -212.57006)
		(width 0.0889)
		(layer "In4.Cu")
		(net "UPI_CPU0_CPU1_P1P0_DN<4>")
	)
	(segment
		(start 376.244866 -182.321962)
		(end 376.24512 -182.321708)
		(width 0.14732)
		(layer "In4.Cu")
		(net "UPI_CPU0_CPU1_P1P0_DN<4>")
	)
	(segment
		(start 378.513594 -211.572348)
		(end 378.513594 -206.061818)
		(width 0.14732)
		(layer "In4.Cu")
		(net "UPI_CPU0_CPU1_P1P0_DN<4>")
	)
	(segment
		(start 93.039184 -215.93048)
		(end 93.040454 -215.931242)
		(width 0.0889)
		(layer "In4.Cu")
		(net "UPI_CPU0_CPU1_P1P0_DN<4>")
	)
	(segment
		(start 92.65031 -213.1695)
		(end 92.65031 -213.34476)
		(width 0.0889)
		(layer "In4.Cu")
		(net "UPI_CPU0_CPU1_P1P0_DN<4>")
	)
	(segment
		(start 366.583214 -174.599092)
		(end 362.918756 -167.055292)
		(width 0.14732)
		(layer "In4.Cu")
		(net "UPI_CPU0_CPU1_P1P0_DN<4>")
	)
	(segment
		(start 378.360686 -217.851228)
		(end 378.21997 -217.607388)
		(width 0.0889)
		(layer "In4.Cu")
		(net "UPI_CPU0_CPU1_P1P0_DN<4>")
	)
	(segment
		(start 93.032834 -214.945976)
		(end 93.031818 -214.946484)
		(width 0.0889)
		(layer "In4.Cu")
		(net "UPI_CPU0_CPU1_P1P0_DN<4>")
	)
	(segment
		(start 375.8311 -181.734968)
		(end 372.31066 -177.561748)
		(width 0.14732)
		(layer "In4.Cu")
		(net "UPI_CPU0_CPU1_P1P0_DN<4>")
	)
	(segment
		(start 92.65031 -212.74532)
		(end 92.74937 -212.84438)
		(width 0.0889)
		(layer "In4.Cu")
		(net "UPI_CPU0_CPU1_P1P0_DN<4>")
	)
	(segment
		(start 93.025468 -215.922606)
		(end 93.02877 -215.924384)
		(width 0.0889)
		(layer "In4.Cu")
		(net "UPI_CPU0_CPU1_P1P0_DN<4>")
	)
	(segment
		(start 93.032326 -215.92667)
		(end 93.037152 -215.929464)
		(width 0.0889)
		(layer "In4.Cu")
		(net "UPI_CPU0_CPU1_P1P0_DN<4>")
	)
	(segment
		(start 372.31066 -177.561748)
		(end 371.63756 -177.279808)
		(width 0.14732)
		(layer "In4.Cu")
		(net "UPI_CPU0_CPU1_P1P0_DN<4>")
	)
	(segment
		(start 92.74937 -213.44382)
		(end 92.74937 -213.788752)
		(width 0.0889)
		(layer "In4.Cu")
		(net "UPI_CPU0_CPU1_P1P0_DN<4>")
	)
	(segment
		(start 378.513848 -211.869528)
		(end 378.513848 -211.84743)
		(width 0.0889)
		(layer "In4.Cu")
		(net "UPI_CPU0_CPU1_P1P0_DN<4>")
	)
	(segment
		(start 92.748862 -217.064336)
		(end 92.748862 -217.071956)
		(width 0.0889)
		(layer "In4.Cu")
		(net "UPI_CPU0_CPU1_P1P0_DN<4>")
	)
	(segment
		(start 92.74937 -211.957158)
		(end 92.74937 -212.471)
		(width 0.0889)
		(layer "In4.Cu")
		(net "UPI_CPU0_CPU1_P1P0_DN<4>")
	)
	(segment
		(start 92.70746 -211.89315)
		(end 92.70746 -211.915248)
		(width 0.0889)
		(layer "In4.Cu")
		(net "UPI_CPU0_CPU1_P1P0_DN<4>")
	)
	(segment
		(start 93.037152 -215.929464)
		(end 93.039184 -215.93048)
		(width 0.0889)
		(layer "In4.Cu")
		(net "UPI_CPU0_CPU1_P1P0_DN<4>")
	)
	(segment
		(start 93.031564 -216.574878)
		(end 93.027754 -216.577164)
		(width 0.0889)
		(layer "In4.Cu")
		(net "UPI_CPU0_CPU1_P1P0_DN<4>")
	)
	(segment
		(start 93.040454 -216.569798)
		(end 93.031564 -216.574878)
		(width 0.0889)
		(layer "In4.Cu")
		(net "UPI_CPU0_CPU1_P1P0_DN<4>")
	)
	(segment
		(start 378.21997 -217.607388)
		(end 378.2441 -217.518234)
		(width 0.0889)
		(layer "In4.Cu")
		(net "UPI_CPU0_CPU1_P1P0_DN<4>")
	)
	(segment
		(start 359.41508 -162.936936)
		(end 330.403962 -144.30756)
		(width 0.14732)
		(layer "In4.Cu")
		(net "UPI_CPU0_CPU1_P1P0_DN<4>")
	)
	(segment
		(start 378.513594 -206.061818)
		(end 378.512324 -206.060548)
		(width 0.14732)
		(layer "In4.Cu")
		(net "UPI_CPU0_CPU1_P1P0_DN<4>")
	)
	(segment
		(start 362.918756 -167.055292)
		(end 359.41508 -162.936936)
		(width 0.14732)
		(layer "In4.Cu")
		(net "UPI_CPU0_CPU1_P1P0_DN<4>")
	)
	(segment
		(start 169.613326 -139.105894)
		(end 161.03346 -142.068296)
		(width 0.14732)
		(layer "In4.Cu")
		(net "UPI_CPU0_CPU1_P1P0_DN<4>")
	)
	(segment
		(start 371.63756 -177.279808)
		(end 369.113816 -176.806352)
		(width 0.14732)
		(layer "In4.Cu")
		(net "UPI_CPU0_CPU1_P1P0_DN<4>")
	)
	(segment
		(start 315.374274 -141.359128)
		(end 273.151854 -139.599924)
		(width 0.14732)
		(layer "In4.Cu")
		(net "UPI_CPU0_CPU1_P1P0_DN<4>")
	)
	(arc
		(start 378.195332 -215.922606)
		(mid 378.397808 -215.716083)
		(end 378.471684 -215.43645)
		(width 0.0889)
		(layer "In4.Cu")
		(net "UPI_CPU0_CPU1_P1P0_DN<4>")
	)
	(arc
		(start 93.040454 -217.559128)
		(mid 93.171368 -217.695488)
		(end 93.219016 -217.878406)
		(width 0.0889)
		(layer "In4.Cu")
		(net "UPI_CPU0_CPU1_P1P0_DN<4>")
	)
	(arc
		(start 93.031056 -214.946992)
		(mid 92.74866 -215.433205)
		(end 93.025468 -215.922606)
		(width 0.0889)
		(layer "In4.Cu")
		(net "UPI_CPU0_CPU1_P1P0_DN<4>")
	)
	(arc
		(start 93.219016 -217.878406)
		(mid 93.182156 -218.040203)
		(end 93.079062 -218.170252)
		(width 0.0889)
		(layer "In4.Cu")
		(net "UPI_CPU0_CPU1_P1P0_DN<4>")
	)
	(arc
		(start 378.656088 -214.093298)
		(mid 378.546692 -214.009201)
		(end 378.471684 -213.8934)
		(width 0.0889)
		(layer "In4.Cu")
		(net "UPI_CPU0_CPU1_P1P0_DN<4>")
	)
	(arc
		(start 92.748862 -217.071956)
		(mid 92.826491 -217.350369)
		(end 93.031564 -217.554048)
		(width 0.0889)
		(layer "In4.Cu")
		(net "UPI_CPU0_CPU1_P1P0_DN<4>")
	)
	(arc
		(start 93.218508 -214.622634)
		(mid 93.170829 -214.805534)
		(end 93.039946 -214.941912)
		(width 0.0889)
		(layer "In4.Cu")
		(net "UPI_CPU0_CPU1_P1P0_DN<4>")
	)
	(arc
		(start 378.471684 -215.43645)
		(mid 378.519363 -215.25355)
		(end 378.650246 -215.117172)
		(width 0.0889)
		(layer "In4.Cu")
		(net "UPI_CPU0_CPU1_P1P0_DN<4>")
	)
	(arc
		(start 378.471684 -217.064336)
		(mid 378.397768 -216.784834)
		(end 378.195332 -216.578434)
		(width 0.0889)
		(layer "In4.Cu")
		(net "UPI_CPU0_CPU1_P1P0_DN<4>")
	)
	(arc
		(start 93.019372 -216.58199)
		(mid 92.821144 -216.787838)
		(end 92.748862 -217.064336)
		(width 0.0889)
		(layer "In4.Cu")
		(net "UPI_CPU0_CPU1_P1P0_DN<4>")
	)
	(arc
		(start 93.040454 -215.931242)
		(mid 93.219051 -216.25052)
		(end 93.040454 -216.569798)
		(width 0.0889)
		(layer "In4.Cu")
		(net "UPI_CPU0_CPU1_P1P0_DN<4>")
	)
	(arc
		(start 378.180346 -216.569798)
		(mid 378.00187 -216.25052)
		(end 378.180346 -215.931242)
		(width 0.0889)
		(layer "In4.Cu")
		(net "UPI_CPU0_CPU1_P1P0_DN<4>")
	)
	(arc
		(start 92.74937 -213.788752)
		(mid 92.826133 -214.064925)
		(end 93.034358 -214.261954)
		(width 0.0889)
		(layer "In4.Cu")
		(net "UPI_CPU0_CPU1_P1P0_DN<4>")
	)
	(arc
		(start 378.941584 -214.425022)
		(mid 378.830246 -214.232122)
		(end 378.656088 -214.093298)
		(width 0.0889)
		(layer "In4.Cu")
		(net "UPI_CPU0_CPU1_P1P0_DN<4>")
	)
	(arc
		(start 93.034358 -214.261954)
		(mid 93.143505 -214.345882)
		(end 93.218508 -214.461344)
		(width 0.0889)
		(layer "In4.Cu")
		(net "UPI_CPU0_CPU1_P1P0_DN<4>")
	)
	(arc
		(start 378.659136 -215.112092)
		(mid 378.863471 -214.909487)
		(end 378.941584 -214.63254)
		(width 0.0889)
		(layer "In4.Cu")
		(net "UPI_CPU0_CPU1_P1P0_DN<4>")
	)
	(arc
		(start 378.260864 -217.50528)
		(mid 378.413371 -217.315182)
		(end 378.471684 -217.07856)
		(width 0.0889)
		(layer "In4.Cu")
		(net "UPI_CPU0_CPU1_P1P0_DN<4>")
	)
	(arc
		(start 378.2441 -217.518234)
		(mid 378.252543 -217.511836)
		(end 378.260864 -217.50528)
		(width 0.0889)
		(layer "In4.Cu")
		(net "UPI_CPU0_CPU1_P1P0_DN<4>")
	)
	(segment
		(start 378.846334 -218.692476)
		(end 378.84608 -218.692222)
		(width 0.13208)
		(layer "F.Cu")
		(net "UPI_CPU0_CPU1_P1P0_DN<3>")
	)
	(segment
		(start 378.846334 -219.228162)
		(end 378.846334 -218.692476)
		(width 0.13208)
		(layer "F.Cu")
		(net "UPI_CPU0_CPU1_P1P0_DN<3>")
	)
	(segment
		(start 92.374466 -217.600276)
		(end 92.374466 -217.06459)
		(width 0.13208)
		(layer "F.Cu")
		(net "UPI_CPU0_CPU1_P1P0_DN<3>")
	)
	(segment
		(start 92.374466 -217.06459)
		(end 92.374212 -217.064336)
		(width 0.13208)
		(layer "F.Cu")
		(net "UPI_CPU0_CPU1_P1P0_DN<3>")
	)
	(segment
		(start 238.58347 -139.554966)
		(end 169.781728 -138.4427)
		(width 0.14732)
		(layer "In4.Cu")
		(net "UPI_CPU0_CPU1_P1P0_DN<3>")
	)
	(segment
		(start 372.87454 -175.734218)
		(end 372.872508 -175.529494)
		(width 0.14732)
		(layer "In4.Cu")
		(net "UPI_CPU0_CPU1_P1P0_DN<3>")
	)
	(segment
		(start 92.041726 -211.78139)
		(end 92.041726 -211.803488)
		(width 0.0889)
		(layer "In4.Cu")
		(net "UPI_CPU0_CPU1_P1P0_DN<3>")
	)
	(segment
		(start 92.041726 -211.803488)
		(end 91.999562 -211.845652)
		(width 0.0889)
		(layer "In4.Cu")
		(net "UPI_CPU0_CPU1_P1P0_DN<3>")
	)
	(segment
		(start 160.837372 -141.530832)
		(end 124.437648 -163.92779)
		(width 0.14732)
		(layer "In4.Cu")
		(net "UPI_CPU0_CPU1_P1P0_DN<3>")
	)
	(segment
		(start 124.437648 -163.92779)
		(end 103.91267 -183.24703)
		(width 0.14732)
		(layer "In4.Cu")
		(net "UPI_CPU0_CPU1_P1P0_DN<3>")
	)
	(segment
		(start 92.183458 -215.75903)
		(end 92.18549 -215.7603)
		(width 0.0889)
		(layer "In4.Cu")
		(net "UPI_CPU0_CPU1_P1P0_DN<3>")
	)
	(segment
		(start 373.137684 -175.992536)
		(end 372.87454 -175.734218)
		(width 0.14732)
		(layer "In4.Cu")
		(net "UPI_CPU0_CPU1_P1P0_DN<3>")
	)
	(segment
		(start 92.098622 -212.63102)
		(end 91.999562 -212.73008)
		(width 0.0889)
		(layer "In4.Cu")
		(net "UPI_CPU0_CPU1_P1P0_DN<3>")
	)
	(segment
		(start 376.169428 -179.492148)
		(end 376.007884 -178.781964)
		(width 0.14732)
		(layer "In4.Cu")
		(net "UPI_CPU0_CPU1_P1P0_DN<3>")
	)
	(segment
		(start 92.524326 -209.514948)
		(end 92.372942 -209.924904)
		(width 0.14732)
		(layer "In4.Cu")
		(net "UPI_CPU0_CPU1_P1P0_DN<3>")
	)
	(segment
		(start 315.518292 -140.805408)
		(end 271.372584 -138.965686)
		(width 0.14732)
		(layer "In4.Cu")
		(net "UPI_CPU0_CPU1_P1P0_DN<3>")
	)
	(segment
		(start 93.147388 -207.82788)
		(end 92.990416 -207.900016)
		(width 0.14732)
		(layer "In4.Cu")
		(net "UPI_CPU0_CPU1_P1P0_DN<3>")
	)
	(segment
		(start 366.74171 -171.49064)
		(end 366.52327 -171.193968)
		(width 0.14732)
		(layer "In4.Cu")
		(net "UPI_CPU0_CPU1_P1P0_DN<3>")
	)
	(segment
		(start 379.22073 -215.445086)
		(end 379.22073 -215.43645)
		(width 0.0889)
		(layer "In4.Cu")
		(net "UPI_CPU0_CPU1_P1P0_DN<3>")
	)
	(segment
		(start 91.999562 -212.73008)
		(end 91.999562 -212.90534)
		(width 0.0889)
		(layer "In4.Cu")
		(net "UPI_CPU0_CPU1_P1P0_DN<3>")
	)
	(segment
		(start 379.002544 -218.421204)
		(end 378.978414 -218.33205)
		(width 0.0889)
		(layer "In4.Cu")
		(net "UPI_CPU0_CPU1_P1P0_DN<3>")
	)
	(segment
		(start 379.179328 -211.686394)
		(end 379.179074 -211.68614)
		(width 0.14732)
		(layer "In4.Cu")
		(net "UPI_CPU0_CPU1_P1P0_DN<3>")
	)
	(segment
		(start 92.18549 -215.7603)
		(end 92.187014 -215.761062)
		(width 0.0889)
		(layer "In4.Cu")
		(net "UPI_CPU0_CPU1_P1P0_DN<3>")
	)
	(segment
		(start 92.990416 -207.900016)
		(end 92.839286 -208.309718)
		(width 0.14732)
		(layer "In4.Cu")
		(net "UPI_CPU0_CPU1_P1P0_DN<3>")
	)
	(segment
		(start 92.180156 -215.757252)
		(end 92.183458 -215.75903)
		(width 0.0889)
		(layer "In4.Cu")
		(net "UPI_CPU0_CPU1_P1P0_DN<3>")
	)
	(segment
		(start 93.226382 -207.261206)
		(end 93.298518 -207.41767)
		(width 0.14732)
		(layer "In4.Cu")
		(net "UPI_CPU0_CPU1_P1P0_DN<3>")
	)
	(segment
		(start 366.55375 -170.99153)
		(end 363.671866 -167.079168)
		(width 0.14732)
		(layer "In4.Cu")
		(net "UPI_CPU0_CPU1_P1P0_DN<3>")
	)
	(segment
		(start 271.372584 -138.965686)
		(end 238.592614 -139.554966)
		(width 0.14732)
		(layer "In4.Cu")
		(net "UPI_CPU0_CPU1_P1P0_DN<3>")
	)
	(segment
		(start 378.84608 -218.692222)
		(end 379.002544 -218.421204)
		(width 0.0889)
		(layer "In4.Cu")
		(net "UPI_CPU0_CPU1_P1P0_DN<3>")
	)
	(segment
		(start 92.372942 -209.924904)
		(end 92.216224 -209.99704)
		(width 0.14732)
		(layer "In4.Cu")
		(net "UPI_CPU0_CPU1_P1P0_DN<3>")
	)
	(segment
		(start 367.616994 -172.679106)
		(end 367.398808 -172.38218)
		(width 0.14732)
		(layer "In4.Cu")
		(net "UPI_CPU0_CPU1_P1P0_DN<3>")
	)
	(segment
		(start 379.179074 -205.534768)
		(end 376.81408 -182.324248)
		(width 0.14732)
		(layer "In4.Cu")
		(net "UPI_CPU0_CPU1_P1P0_DN<3>")
	)
	(segment
		(start 376.141996 -180.024786)
		(end 376.060462 -179.665376)
		(width 0.14732)
		(layer "In4.Cu")
		(net "UPI_CPU0_CPU1_P1P0_DN<3>")
	)
	(segment
		(start 379.220984 -213.93023)
		(end 379.220984 -211.911184)
		(width 0.0889)
		(layer "In4.Cu")
		(net "UPI_CPU0_CPU1_P1P0_DN<3>")
	)
	(segment
		(start 169.781728 -138.4427)
		(end 160.837372 -141.530832)
		(width 0.14732)
		(layer "In4.Cu")
		(net "UPI_CPU0_CPU1_P1P0_DN<3>")
	)
	(segment
		(start 318.430148 -140.805408)
		(end 315.518292 -140.805408)
		(width 0.14732)
		(layer "In4.Cu")
		(net "UPI_CPU0_CPU1_P1P0_DN<3>")
	)
	(segment
		(start 367.398808 -172.38218)
		(end 367.429288 -172.179742)
		(width 0.14732)
		(layer "In4.Cu")
		(net "UPI_CPU0_CPU1_P1P0_DN<3>")
	)
	(segment
		(start 92.187776 -216.73947)
		(end 92.187014 -216.739978)
		(width 0.0889)
		(layer "In4.Cu")
		(net "UPI_CPU0_CPU1_P1P0_DN<3>")
	)
	(segment
		(start 376.303794 -180.733954)
		(end 376.41276 -180.560726)
		(width 0.14732)
		(layer "In4.Cu")
		(net "UPI_CPU0_CPU1_P1P0_DN<3>")
	)
	(segment
		(start 93.298518 -207.41767)
		(end 93.147388 -207.82788)
		(width 0.14732)
		(layer "In4.Cu")
		(net "UPI_CPU0_CPU1_P1P0_DN<3>")
	)
	(segment
		(start 91.999562 -213.27872)
		(end 91.999562 -213.8934)
		(width 0.0889)
		(layer "In4.Cu")
		(net "UPI_CPU0_CPU1_P1P0_DN<3>")
	)
	(segment
		(start 368.586512 -173.750732)
		(end 367.819686 -172.70984)
		(width 0.14732)
		(layer "In4.Cu")
		(net "UPI_CPU0_CPU1_P1P0_DN<3>")
	)
	(segment
		(start 371.818154 -174.60722)
		(end 369.246912 -174.214282)
		(width 0.14732)
		(layer "In4.Cu")
		(net "UPI_CPU0_CPU1_P1P0_DN<3>")
	)
	(segment
		(start 92.760292 -208.876392)
		(end 92.60332 -208.948528)
		(width 0.14732)
		(layer "In4.Cu")
		(net "UPI_CPU0_CPU1_P1P0_DN<3>")
	)
	(segment
		(start 375.787412 -178.387756)
		(end 373.342408 -175.990504)
		(width 0.14732)
		(layer "In4.Cu")
		(net "UPI_CPU0_CPU1_P1P0_DN<3>")
	)
	(segment
		(start 92.839286 -208.309718)
		(end 92.911422 -208.466182)
		(width 0.14732)
		(layer "In4.Cu")
		(net "UPI_CPU0_CPU1_P1P0_DN<3>")
	)
	(segment
		(start 376.385328 -181.093364)
		(end 376.303794 -180.733954)
		(width 0.14732)
		(layer "In4.Cu")
		(net "UPI_CPU0_CPU1_P1P0_DN<3>")
	)
	(segment
		(start 379.22073 -215.43645)
		(end 379.220984 -215.422226)
		(width 0.0889)
		(layer "In4.Cu")
		(net "UPI_CPU0_CPU1_P1P0_DN<3>")
	)
	(segment
		(start 92.45219 -209.35823)
		(end 92.524326 -209.514948)
		(width 0.14732)
		(layer "In4.Cu")
		(net "UPI_CPU0_CPU1_P1P0_DN<3>")
	)
	(segment
		(start 92.60332 -208.948528)
		(end 92.45219 -209.35823)
		(width 0.14732)
		(layer "In4.Cu")
		(net "UPI_CPU0_CPU1_P1P0_DN<3>")
	)
	(segment
		(start 372.872508 -175.529494)
		(end 372.872254 -175.529748)
		(width 0.14732)
		(layer "In4.Cu")
		(net "UPI_CPU0_CPU1_P1P0_DN<3>")
	)
	(segment
		(start 379.179328 -211.84743)
		(end 379.179328 -211.686394)
		(width 0.14732)
		(layer "In4.Cu")
		(net "UPI_CPU0_CPU1_P1P0_DN<3>")
	)
	(segment
		(start 378.751084 -216.260426)
		(end 378.751084 -216.231978)
		(width 0.0889)
		(layer "In4.Cu")
		(net "UPI_CPU0_CPU1_P1P0_DN<3>")
	)
	(segment
		(start 372.049802 -174.723044)
		(end 371.818154 -174.60722)
		(width 0.14732)
		(layer "In4.Cu")
		(net "UPI_CPU0_CPU1_P1P0_DN<3>")
	)
	(segment
		(start 92.469208 -214.424768)
		(end 92.469208 -214.644732)
		(width 0.0889)
		(layer "In4.Cu")
		(net "UPI_CPU0_CPU1_P1P0_DN<3>")
	)
	(segment
		(start 103.91267 -183.24703)
		(end 100.52177 -187.498736)
		(width 0.14732)
		(layer "In4.Cu")
		(net "UPI_CPU0_CPU1_P1P0_DN<3>")
	)
	(segment
		(start 379.690884 -214.622634)
		(end 379.690884 -214.461852)
		(width 0.0889)
		(layer "In4.Cu")
		(net "UPI_CPU0_CPU1_P1P0_DN<3>")
	)
	(segment
		(start 379.220984 -211.911184)
		(end 379.179328 -211.869528)
		(width 0.0889)
		(layer "In4.Cu")
		(net "UPI_CPU0_CPU1_P1P0_DN<3>")
	)
	(segment
		(start 367.429288 -172.179742)
		(end 366.944402 -171.521374)
		(width 0.14732)
		(layer "In4.Cu")
		(net "UPI_CPU0_CPU1_P1P0_DN<3>")
	)
	(segment
		(start 92.178124 -215.755982)
		(end 92.180156 -215.757252)
		(width 0.0889)
		(layer "In4.Cu")
		(net "UPI_CPU0_CPU1_P1P0_DN<3>")
	)
	(segment
		(start 92.217748 -217.335354)
		(end 92.374212 -217.064336)
		(width 0.0889)
		(layer "In4.Cu")
		(net "UPI_CPU0_CPU1_P1P0_DN<3>")
	)
	(segment
		(start 92.041472 -211.630768)
		(end 92.041726 -211.631022)
		(width 0.14732)
		(layer "In4.Cu")
		(net "UPI_CPU0_CPU1_P1P0_DN<3>")
	)
	(segment
		(start 92.188538 -215.762078)
		(end 92.19311 -215.764618)
		(width 0.0889)
		(layer "In4.Cu")
		(net "UPI_CPU0_CPU1_P1P0_DN<3>")
	)
	(segment
		(start 367.819686 -172.70984)
		(end 367.616994 -172.679106)
		(width 0.14732)
		(layer "In4.Cu")
		(net "UPI_CPU0_CPU1_P1P0_DN<3>")
	)
	(segment
		(start 92.185998 -215.112854)
		(end 92.178124 -215.117426)
		(width 0.0889)
		(layer "In4.Cu")
		(net "UPI_CPU0_CPU1_P1P0_DN<3>")
	)
	(segment
		(start 100.52177 -187.498736)
		(end 93.226382 -207.261206)
		(width 0.14732)
		(layer "In4.Cu")
		(net "UPI_CPU0_CPU1_P1P0_DN<3>")
	)
	(segment
		(start 92.098622 -213.0044)
		(end 92.098622 -213.17966)
		(width 0.0889)
		(layer "In4.Cu")
		(net "UPI_CPU0_CPU1_P1P0_DN<3>")
	)
	(segment
		(start 378.751084 -217.8939)
		(end 378.751084 -217.859864)
		(width 0.0889)
		(layer "In4.Cu")
		(net "UPI_CPU0_CPU1_P1P0_DN<3>")
	)
	(segment
		(start 376.559064 -181.202584)
		(end 376.385328 -181.093364)
		(width 0.14732)
		(layer "In4.Cu")
		(net "UPI_CPU0_CPU1_P1P0_DN<3>")
	)
	(segment
		(start 91.999562 -212.90534)
		(end 92.098622 -213.0044)
		(width 0.0889)
		(layer "In4.Cu")
		(net "UPI_CPU0_CPU1_P1P0_DN<3>")
	)
	(segment
		(start 92.187014 -215.112346)
		(end 92.185998 -215.112854)
		(width 0.0889)
		(layer "In4.Cu")
		(net "UPI_CPU0_CPU1_P1P0_DN<3>")
	)
	(segment
		(start 92.187014 -215.761062)
		(end 92.188538 -215.762078)
		(width 0.0889)
		(layer "In4.Cu")
		(net "UPI_CPU0_CPU1_P1P0_DN<3>")
	)
	(segment
		(start 376.55881 -181.202838)
		(end 376.559064 -181.202584)
		(width 0.14732)
		(layer "In4.Cu")
		(net "UPI_CPU0_CPU1_P1P0_DN<3>")
	)
	(segment
		(start 92.098622 -212.45576)
		(end 92.098622 -212.63102)
		(width 0.0889)
		(layer "In4.Cu")
		(net "UPI_CPU0_CPU1_P1P0_DN<3>")
	)
	(segment
		(start 379.179074 -211.68614)
		(end 379.179074 -205.534768)
		(width 0.14732)
		(layer "In4.Cu")
		(net "UPI_CPU0_CPU1_P1P0_DN<3>")
	)
	(segment
		(start 379.503432 -214.946992)
		(end 379.512322 -214.941912)
		(width 0.0889)
		(layer "In4.Cu")
		(net "UPI_CPU0_CPU1_P1P0_DN<3>")
	)
	(segment
		(start 379.22073 -217.072972)
		(end 379.22073 -217.0557)
		(width 0.0889)
		(layer "In4.Cu")
		(net "UPI_CPU0_CPU1_P1P0_DN<3>")
	)
	(segment
		(start 92.098622 -213.17966)
		(end 91.999562 -213.27872)
		(width 0.0889)
		(layer "In4.Cu")
		(net "UPI_CPU0_CPU1_P1P0_DN<3>")
	)
	(segment
		(start 91.999562 -212.3567)
		(end 92.098622 -212.45576)
		(width 0.0889)
		(layer "In4.Cu")
		(net "UPI_CPU0_CPU1_P1P0_DN<3>")
	)
	(segment
		(start 376.41276 -180.560726)
		(end 376.315732 -180.133752)
		(width 0.14732)
		(layer "In4.Cu")
		(net "UPI_CPU0_CPU1_P1P0_DN<3>")
	)
	(segment
		(start 91.999562 -211.845652)
		(end 91.999562 -212.3567)
		(width 0.0889)
		(layer "In4.Cu")
		(net "UPI_CPU0_CPU1_P1P0_DN<3>")
	)
	(segment
		(start 92.041472 -210.470496)
		(end 92.041472 -211.630768)
		(width 0.14732)
		(layer "In4.Cu")
		(net "UPI_CPU0_CPU1_P1P0_DN<3>")
	)
	(segment
		(start 376.315732 -180.133752)
		(end 376.141996 -180.024786)
		(width 0.14732)
		(layer "In4.Cu")
		(net "UPI_CPU0_CPU1_P1P0_DN<3>")
	)
	(segment
		(start 376.007884 -178.781964)
		(end 375.787412 -178.387756)
		(width 0.14732)
		(layer "In4.Cu")
		(net "UPI_CPU0_CPU1_P1P0_DN<3>")
	)
	(segment
		(start 92.19311 -216.736422)
		(end 92.187776 -216.73947)
		(width 0.0889)
		(layer "In4.Cu")
		(net "UPI_CPU0_CPU1_P1P0_DN<3>")
	)
	(segment
		(start 379.179328 -211.869528)
		(end 379.179328 -211.84743)
		(width 0.0889)
		(layer "In4.Cu")
		(net "UPI_CPU0_CPU1_P1P0_DN<3>")
	)
	(segment
		(start 372.872254 -175.529748)
		(end 372.049802 -174.723044)
		(width 0.14732)
		(layer "In4.Cu")
		(net "UPI_CPU0_CPU1_P1P0_DN<3>")
	)
	(segment
		(start 359.797096 -162.523932)
		(end 330.62545 -143.791686)
		(width 0.14732)
		(layer "In4.Cu")
		(net "UPI_CPU0_CPU1_P1P0_DN<3>")
	)
	(segment
		(start 366.52327 -171.193968)
		(end 366.55375 -170.99153)
		(width 0.14732)
		(layer "In4.Cu")
		(net "UPI_CPU0_CPU1_P1P0_DN<3>")
	)
	(segment
		(start 366.944402 -171.521374)
		(end 366.74171 -171.49064)
		(width 0.14732)
		(layer "In4.Cu")
		(net "UPI_CPU0_CPU1_P1P0_DN<3>")
	)
	(segment
		(start 238.592614 -139.554966)
		(end 238.58347 -139.554966)
		(width 0.14732)
		(layer "In4.Cu")
		(net "UPI_CPU0_CPU1_P1P0_DN<3>")
	)
	(segment
		(start 369.246912 -174.214282)
		(end 368.586512 -173.750732)
		(width 0.14732)
		(layer "In4.Cu")
		(net "UPI_CPU0_CPU1_P1P0_DN<3>")
	)
	(segment
		(start 91.999562 -213.8934)
		(end 91.999816 -213.893908)
		(width 0.0889)
		(layer "In4.Cu")
		(net "UPI_CPU0_CPU1_P1P0_DN<3>")
	)
	(segment
		(start 373.342408 -175.990504)
		(end 373.137684 -175.992536)
		(width 0.14732)
		(layer "In4.Cu")
		(net "UPI_CPU0_CPU1_P1P0_DN<3>")
	)
	(segment
		(start 92.216224 -209.99704)
		(end 92.041472 -210.470496)
		(width 0.14732)
		(layer "In4.Cu")
		(net "UPI_CPU0_CPU1_P1P0_DN<3>")
	)
	(segment
		(start 376.060462 -179.665376)
		(end 376.169428 -179.492148)
		(width 0.14732)
		(layer "In4.Cu")
		(net "UPI_CPU0_CPU1_P1P0_DN<3>")
	)
	(segment
		(start 376.81408 -182.324248)
		(end 376.55881 -181.202838)
		(width 0.14732)
		(layer "In4.Cu")
		(net "UPI_CPU0_CPU1_P1P0_DN<3>")
	)
	(segment
		(start 92.13977 -217.356182)
		(end 92.217748 -217.335354)
		(width 0.0889)
		(layer "In4.Cu")
		(net "UPI_CPU0_CPU1_P1P0_DN<3>")
	)
	(segment
		(start 363.671866 -167.079168)
		(end 359.797096 -162.523932)
		(width 0.14732)
		(layer "In4.Cu")
		(net "UPI_CPU0_CPU1_P1P0_DN<3>")
	)
	(segment
		(start 92.041726 -211.631022)
		(end 92.041726 -211.78139)
		(width 0.14732)
		(layer "In4.Cu")
		(net "UPI_CPU0_CPU1_P1P0_DN<3>")
	)
	(segment
		(start 330.62545 -143.791686)
		(end 318.430148 -140.805408)
		(width 0.14732)
		(layer "In4.Cu")
		(net "UPI_CPU0_CPU1_P1P0_DN<3>")
	)
	(segment
		(start 92.911422 -208.466182)
		(end 92.760292 -208.876392)
		(width 0.14732)
		(layer "In4.Cu")
		(net "UPI_CPU0_CPU1_P1P0_DN<3>")
	)
	(arc
		(start 378.96165 -218.319096)
		(mid 378.809568 -218.129664)
		(end 378.751084 -217.8939)
		(width 0.0889)
		(layer "In4.Cu")
		(net "UPI_CPU0_CPU1_P1P0_DN<3>")
	)
	(arc
		(start 92.187014 -216.739978)
		(mid 92.000811 -217.035655)
		(end 92.13977 -217.356182)
		(width 0.0889)
		(layer "In4.Cu")
		(net "UPI_CPU0_CPU1_P1P0_DN<3>")
	)
	(arc
		(start 92.19311 -215.764618)
		(mid 92.469684 -216.25052)
		(end 92.19311 -216.736422)
		(width 0.0889)
		(layer "In4.Cu")
		(net "UPI_CPU0_CPU1_P1P0_DN<3>")
	)
	(arc
		(start 379.512322 -214.941912)
		(mid 379.643236 -214.805552)
		(end 379.690884 -214.622634)
		(width 0.0889)
		(layer "In4.Cu")
		(net "UPI_CPU0_CPU1_P1P0_DN<3>")
	)
	(arc
		(start 92.469208 -214.644732)
		(mid 92.388297 -214.91486)
		(end 92.187014 -215.112346)
		(width 0.0889)
		(layer "In4.Cu")
		(net "UPI_CPU0_CPU1_P1P0_DN<3>")
	)
	(arc
		(start 379.50648 -214.261954)
		(mid 379.346125 -214.138568)
		(end 379.23597 -213.968838)
		(width 0.0889)
		(layer "In4.Cu")
		(net "UPI_CPU0_CPU1_P1P0_DN<3>")
	)
	(arc
		(start 379.220984 -215.422226)
		(mid 379.300115 -215.14769)
		(end 379.503432 -214.946992)
		(width 0.0889)
		(layer "In4.Cu")
		(net "UPI_CPU0_CPU1_P1P0_DN<3>")
	)
	(arc
		(start 379.22073 -217.0557)
		(mid 379.16846 -216.873335)
		(end 379.033532 -216.739978)
		(width 0.0889)
		(layer "In4.Cu")
		(net "UPI_CPU0_CPU1_P1P0_DN<3>")
	)
	(arc
		(start 379.033532 -217.388694)
		(mid 379.168465 -217.25534)
		(end 379.22073 -217.072972)
		(width 0.0889)
		(layer "In4.Cu")
		(net "UPI_CPU0_CPU1_P1P0_DN<3>")
	)
	(arc
		(start 378.978414 -218.33205)
		(mid 378.969973 -218.32565)
		(end 378.96165 -218.319096)
		(width 0.0889)
		(layer "In4.Cu")
		(net "UPI_CPU0_CPU1_P1P0_DN<3>")
	)
	(arc
		(start 92.183966 -214.093298)
		(mid 92.357929 -214.232062)
		(end 92.469208 -214.424768)
		(width 0.0889)
		(layer "In4.Cu")
		(net "UPI_CPU0_CPU1_P1P0_DN<3>")
	)
	(arc
		(start 379.033532 -216.739978)
		(mid 378.829197 -216.537373)
		(end 378.751084 -216.260426)
		(width 0.0889)
		(layer "In4.Cu")
		(net "UPI_CPU0_CPU1_P1P0_DN<3>")
	)
	(arc
		(start 379.033532 -215.760808)
		(mid 379.168465 -215.627454)
		(end 379.22073 -215.445086)
		(width 0.0889)
		(layer "In4.Cu")
		(net "UPI_CPU0_CPU1_P1P0_DN<3>")
	)
	(arc
		(start 379.690884 -214.461852)
		(mid 379.615813 -214.34611)
		(end 379.50648 -214.261954)
		(width 0.0889)
		(layer "In4.Cu")
		(net "UPI_CPU0_CPU1_P1P0_DN<3>")
	)
	(arc
		(start 91.999816 -213.893908)
		(mid 92.074821 -214.009367)
		(end 92.183966 -214.093298)
		(width 0.0889)
		(layer "In4.Cu")
		(net "UPI_CPU0_CPU1_P1P0_DN<3>")
	)
	(arc
		(start 379.23597 -213.968838)
		(mid 379.228148 -213.949662)
		(end 379.220984 -213.93023)
		(width 0.0889)
		(layer "In4.Cu")
		(net "UPI_CPU0_CPU1_P1P0_DN<3>")
	)
	(arc
		(start 378.751084 -216.231978)
		(mid 378.831246 -215.959789)
		(end 379.033532 -215.760808)
		(width 0.0889)
		(layer "In4.Cu")
		(net "UPI_CPU0_CPU1_P1P0_DN<3>")
	)
	(arc
		(start 92.178124 -215.117426)
		(mid 91.999527 -215.436704)
		(end 92.178124 -215.755982)
		(width 0.0889)
		(layer "In4.Cu")
		(net "UPI_CPU0_CPU1_P1P0_DN<3>")
	)
	(arc
		(start 378.751084 -217.859864)
		(mid 378.831246 -217.587675)
		(end 379.033532 -217.388694)
		(width 0.0889)
		(layer "In4.Cu")
		(net "UPI_CPU0_CPU1_P1P0_DN<3>")
	)
	(segment
		(start 380.25578 -218.414346)
		(end 380.25578 -217.87866)
		(width 0.13208)
		(layer "F.Cu")
		(net "UPI_CPU0_CPU1_P1P0_DN<2>")
	)
	(segment
		(start 90.964512 -217.87866)
		(end 90.964766 -217.878406)
		(width 0.13208)
		(layer "F.Cu")
		(net "UPI_CPU0_CPU1_P1P0_DN<2>")
	)
	(segment
		(start 380.25578 -217.87866)
		(end 380.256034 -217.878406)
		(width 0.13208)
		(layer "F.Cu")
		(net "UPI_CPU0_CPU1_P1P0_DN<2>")
	)
	(segment
		(start 90.964512 -218.414346)
		(end 90.964512 -217.87866)
		(width 0.13208)
		(layer "F.Cu")
		(net "UPI_CPU0_CPU1_P1P0_DN<2>")
	)
	(segment
		(start 369.689888 -170.840146)
		(end 368.991642 -170.668188)
		(width 0.14732)
		(layer "In4.Cu")
		(net "UPI_CPU0_CPU1_P1P0_DN<2>")
	)
	(segment
		(start 91.145868 -215.922606)
		(end 91.14917 -215.924384)
		(width 0.0889)
		(layer "In4.Cu")
		(net "UPI_CPU0_CPU1_P1P0_DN<2>")
	)
	(segment
		(start 380.240286 -217.851228)
		(end 380.09957 -217.607388)
		(width 0.0889)
		(layer "In4.Cu")
		(net "UPI_CPU0_CPU1_P1P0_DN<2>")
	)
	(segment
		(start 372.322852 -171.40174)
		(end 369.689888 -170.840146)
		(width 0.14732)
		(layer "In4.Cu")
		(net "UPI_CPU0_CPU1_P1P0_DN<2>")
	)
	(segment
		(start 91.160854 -216.569798)
		(end 91.139772 -216.58199)
		(width 0.0889)
		(layer "In4.Cu")
		(net "UPI_CPU0_CPU1_P1P0_DN<2>")
	)
	(segment
		(start 123.886468 -162.898328)
		(end 103.212392 -182.347362)
		(width 0.14732)
		(layer "In4.Cu")
		(net "UPI_CPU0_CPU1_P1P0_DN<2>")
	)
	(segment
		(start 380.068836 -216.574878)
		(end 380.059946 -216.569798)
		(width 0.0889)
		(layer "In4.Cu")
		(net "UPI_CPU0_CPU1_P1P0_DN<2>")
	)
	(segment
		(start 90.770456 -213.3346)
		(end 90.869516 -213.43366)
		(width 0.0889)
		(layer "In4.Cu")
		(net "UPI_CPU0_CPU1_P1P0_DN<2>")
	)
	(segment
		(start 90.827352 -211.630768)
		(end 90.827606 -211.631022)
		(width 0.14732)
		(layer "In4.Cu")
		(net "UPI_CPU0_CPU1_P1P0_DN<2>")
	)
	(segment
		(start 380.256034 -217.878406)
		(end 380.240286 -217.851228)
		(width 0.0889)
		(layer "In4.Cu")
		(net "UPI_CPU0_CPU1_P1P0_DN<2>")
	)
	(segment
		(start 360.557572 -161.683446)
		(end 331.11313 -142.775686)
		(width 0.14732)
		(layer "In4.Cu")
		(net "UPI_CPU0_CPU1_P1P0_DN<2>")
	)
	(segment
		(start 160.103566 -140.612368)
		(end 123.886468 -162.898328)
		(width 0.14732)
		(layer "In4.Cu")
		(net "UPI_CPU0_CPU1_P1P0_DN<2>")
	)
	(segment
		(start 91.338908 -214.461344)
		(end 91.338908 -214.622634)
		(width 0.0889)
		(layer "In4.Cu")
		(net "UPI_CPU0_CPU1_P1P0_DN<2>")
	)
	(segment
		(start 91.157552 -215.929464)
		(end 91.159584 -215.93048)
		(width 0.0889)
		(layer "In4.Cu")
		(net "UPI_CPU0_CPU1_P1P0_DN<2>")
	)
	(segment
		(start 99.332796 -187.1853)
		(end 95.719138 -196.934836)
		(width 0.14732)
		(layer "In4.Cu")
		(net "UPI_CPU0_CPU1_P1P0_DN<2>")
	)
	(segment
		(start 381.332994 -211.493608)
		(end 381.332994 -210.355434)
		(width 0.14732)
		(layer "In4.Cu")
		(net "UPI_CPU0_CPU1_P1P0_DN<2>")
	)
	(segment
		(start 377.908566 -182.073296)
		(end 376.413268 -174.987204)
		(width 0.14732)
		(layer "In4.Cu")
		(net "UPI_CPU0_CPU1_P1P0_DN<2>")
	)
	(segment
		(start 380.821184 -214.63254)
		(end 380.821184 -214.461852)
		(width 0.0889)
		(layer "In4.Cu")
		(net "UPI_CPU0_CPU1_P1P0_DN<2>")
	)
	(segment
		(start 376.413268 -174.987204)
		(end 376.138948 -174.535338)
		(width 0.14732)
		(layer "In4.Cu")
		(net "UPI_CPU0_CPU1_P1P0_DN<2>")
	)
	(segment
		(start 318.563752 -139.703048)
		(end 316.021212 -139.703048)
		(width 0.14732)
		(layer "In4.Cu")
		(net "UPI_CPU0_CPU1_P1P0_DN<2>")
	)
	(segment
		(start 380.074932 -216.578434)
		(end 380.072138 -216.57691)
		(width 0.0889)
		(layer "In4.Cu")
		(net "UPI_CPU0_CPU1_P1P0_DN<2>")
	)
	(segment
		(start 368.991642 -170.668188)
		(end 360.557572 -161.683446)
		(width 0.14732)
		(layer "In4.Cu")
		(net "UPI_CPU0_CPU1_P1P0_DN<2>")
	)
	(segment
		(start 316.021212 -139.703048)
		(end 271.483836 -137.836402)
		(width 0.14732)
		(layer "In4.Cu")
		(net "UPI_CPU0_CPU1_P1P0_DN<2>")
	)
	(segment
		(start 90.770456 -213.15934)
		(end 90.770456 -213.3346)
		(width 0.0889)
		(layer "In4.Cu")
		(net "UPI_CPU0_CPU1_P1P0_DN<2>")
	)
	(segment
		(start 380.537974 -215.1126)
		(end 380.538736 -215.112092)
		(width 0.0889)
		(layer "In4.Cu")
		(net "UPI_CPU0_CPU1_P1P0_DN<2>")
	)
	(segment
		(start 90.869516 -211.946998)
		(end 90.869516 -212.51164)
		(width 0.0889)
		(layer "In4.Cu")
		(net "UPI_CPU0_CPU1_P1P0_DN<2>")
	)
	(segment
		(start 380.068836 -215.926162)
		(end 380.074932 -215.922606)
		(width 0.0889)
		(layer "In4.Cu")
		(net "UPI_CPU0_CPU1_P1P0_DN<2>")
	)
	(segment
		(start 91.153234 -214.945976)
		(end 91.152218 -214.946484)
		(width 0.0889)
		(layer "In4.Cu")
		(net "UPI_CPU0_CPU1_P1P0_DN<2>")
	)
	(segment
		(start 380.072138 -216.57691)
		(end 380.068836 -216.574878)
		(width 0.0889)
		(layer "In4.Cu")
		(net "UPI_CPU0_CPU1_P1P0_DN<2>")
	)
	(segment
		(start 91.12123 -218.149424)
		(end 90.964766 -217.878406)
		(width 0.0889)
		(layer "In4.Cu")
		(net "UPI_CPU0_CPU1_P1P0_DN<2>")
	)
	(segment
		(start 380.059946 -215.931242)
		(end 380.068836 -215.926162)
		(width 0.0889)
		(layer "In4.Cu")
		(net "UPI_CPU0_CPU1_P1P0_DN<2>")
	)
	(segment
		(start 271.483836 -137.836402)
		(end 238.617252 -138.424158)
		(width 0.14732)
		(layer "In4.Cu")
		(net "UPI_CPU0_CPU1_P1P0_DN<2>")
	)
	(segment
		(start 380.33706 -207.950816)
		(end 380.33706 -205.520544)
		(width 0.14732)
		(layer "In4.Cu")
		(net "UPI_CPU0_CPU1_P1P0_DN<2>")
	)
	(segment
		(start 380.529846 -215.117172)
		(end 380.537974 -215.1126)
		(width 0.0889)
		(layer "In4.Cu")
		(net "UPI_CPU0_CPU1_P1P0_DN<2>")
	)
	(segment
		(start 381.291084 -213.93023)
		(end 381.291084 -211.967572)
		(width 0.0889)
		(layer "In4.Cu")
		(net "UPI_CPU0_CPU1_P1P0_DN<2>")
	)
	(segment
		(start 90.770456 -212.6107)
		(end 90.770456 -212.78596)
		(width 0.0889)
		(layer "In4.Cu")
		(net "UPI_CPU0_CPU1_P1P0_DN<2>")
	)
	(segment
		(start 91.160346 -214.941912)
		(end 91.153234 -214.945976)
		(width 0.0889)
		(layer "In4.Cu")
		(net "UPI_CPU0_CPU1_P1P0_DN<2>")
	)
	(segment
		(start 381.291084 -211.967572)
		(end 381.333248 -211.925408)
		(width 0.0889)
		(layer "In4.Cu")
		(net "UPI_CPU0_CPU1_P1P0_DN<2>")
	)
	(segment
		(start 380.09957 -217.607388)
		(end 380.1237 -217.518234)
		(width 0.0889)
		(layer "In4.Cu")
		(net "UPI_CPU0_CPU1_P1P0_DN<2>")
	)
	(segment
		(start 91.151964 -217.554048)
		(end 91.160854 -217.559128)
		(width 0.0889)
		(layer "In4.Cu")
		(net "UPI_CPU0_CPU1_P1P0_DN<2>")
	)
	(segment
		(start 380.351284 -217.07856)
		(end 380.351284 -217.064336)
		(width 0.0889)
		(layer "In4.Cu")
		(net "UPI_CPU0_CPU1_P1P0_DN<2>")
	)
	(segment
		(start 238.609886 -138.424158)
		(end 169.665142 -137.302748)
		(width 0.14732)
		(layer "In4.Cu")
		(net "UPI_CPU0_CPU1_P1P0_DN<2>")
	)
	(segment
		(start 380.33706 -205.520544)
		(end 377.908566 -182.073296)
		(width 0.14732)
		(layer "In4.Cu")
		(net "UPI_CPU0_CPU1_P1P0_DN<2>")
	)
	(segment
		(start 376.138948 -174.535338)
		(end 372.322852 -171.40174)
		(width 0.14732)
		(layer "In4.Cu")
		(net "UPI_CPU0_CPU1_P1P0_DN<2>")
	)
	(segment
		(start 331.11313 -142.775686)
		(end 318.563752 -139.703048)
		(width 0.14732)
		(layer "In4.Cu")
		(net "UPI_CPU0_CPU1_P1P0_DN<2>")
	)
	(segment
		(start 91.918282 -207.188816)
		(end 91.918028 -207.189578)
		(width 0.14732)
		(layer "In4.Cu")
		(net "UPI_CPU0_CPU1_P1P0_DN<2>")
	)
	(segment
		(start 91.152218 -214.946484)
		(end 91.151456 -214.946992)
		(width 0.0889)
		(layer "In4.Cu")
		(net "UPI_CPU0_CPU1_P1P0_DN<2>")
	)
	(segment
		(start 91.199462 -218.170252)
		(end 91.12123 -218.149424)
		(width 0.0889)
		(layer "In4.Cu")
		(net "UPI_CPU0_CPU1_P1P0_DN<2>")
	)
	(segment
		(start 381.333248 -211.925408)
		(end 381.333248 -211.90331)
		(width 0.0889)
		(layer "In4.Cu")
		(net "UPI_CPU0_CPU1_P1P0_DN<2>")
	)
	(segment
		(start 91.151202 -215.925654)
		(end 91.152726 -215.92667)
		(width 0.0889)
		(layer "In4.Cu")
		(net "UPI_CPU0_CPU1_P1P0_DN<2>")
	)
	(segment
		(start 90.869516 -212.88502)
		(end 90.869516 -213.06028)
		(width 0.0889)
		(layer "In4.Cu")
		(net "UPI_CPU0_CPU1_P1P0_DN<2>")
	)
	(segment
		(start 91.918028 -207.189578)
		(end 90.827352 -210.131914)
		(width 0.14732)
		(layer "In4.Cu")
		(net "UPI_CPU0_CPU1_P1P0_DN<2>")
	)
	(segment
		(start 90.827606 -211.88299)
		(end 90.827606 -211.905088)
		(width 0.0889)
		(layer "In4.Cu")
		(net "UPI_CPU0_CPU1_P1P0_DN<2>")
	)
	(segment
		(start 90.869516 -213.06028)
		(end 90.770456 -213.15934)
		(width 0.0889)
		(layer "In4.Cu")
		(net "UPI_CPU0_CPU1_P1P0_DN<2>")
	)
	(segment
		(start 91.152726 -215.92667)
		(end 91.157552 -215.929464)
		(width 0.0889)
		(layer "In4.Cu")
		(net "UPI_CPU0_CPU1_P1P0_DN<2>")
	)
	(segment
		(start 103.212392 -182.347362)
		(end 99.332796 -187.1853)
		(width 0.14732)
		(layer "In4.Cu")
		(net "UPI_CPU0_CPU1_P1P0_DN<2>")
	)
	(segment
		(start 381.333248 -211.90331)
		(end 381.333248 -211.493862)
		(width 0.14732)
		(layer "In4.Cu")
		(net "UPI_CPU0_CPU1_P1P0_DN<2>")
	)
	(segment
		(start 381.333248 -211.493862)
		(end 381.332994 -211.493608)
		(width 0.14732)
		(layer "In4.Cu")
		(net "UPI_CPU0_CPU1_P1P0_DN<2>")
	)
	(segment
		(start 238.617252 -138.424158)
		(end 238.609886 -138.424158)
		(width 0.14732)
		(layer "In4.Cu")
		(net "UPI_CPU0_CPU1_P1P0_DN<2>")
	)
	(segment
		(start 381.332994 -210.355434)
		(end 380.33706 -207.950816)
		(width 0.14732)
		(layer "In4.Cu")
		(net "UPI_CPU0_CPU1_P1P0_DN<2>")
	)
	(segment
		(start 169.665142 -137.302748)
		(end 160.103566 -140.612368)
		(width 0.14732)
		(layer "In4.Cu")
		(net "UPI_CPU0_CPU1_P1P0_DN<2>")
	)
	(segment
		(start 90.827606 -211.631022)
		(end 90.827606 -211.88299)
		(width 0.14732)
		(layer "In4.Cu")
		(net "UPI_CPU0_CPU1_P1P0_DN<2>")
	)
	(segment
		(start 90.869516 -213.43366)
		(end 90.869516 -213.895686)
		(width 0.0889)
		(layer "In4.Cu")
		(net "UPI_CPU0_CPU1_P1P0_DN<2>")
	)
	(segment
		(start 90.827606 -211.905088)
		(end 90.869516 -211.946998)
		(width 0.0889)
		(layer "In4.Cu")
		(net "UPI_CPU0_CPU1_P1P0_DN<2>")
	)
	(segment
		(start 91.159584 -215.93048)
		(end 91.160854 -215.931242)
		(width 0.0889)
		(layer "In4.Cu")
		(net "UPI_CPU0_CPU1_P1P0_DN<2>")
	)
	(segment
		(start 90.827352 -210.131914)
		(end 90.827352 -211.630768)
		(width 0.14732)
		(layer "In4.Cu")
		(net "UPI_CPU0_CPU1_P1P0_DN<2>")
	)
	(segment
		(start 90.770456 -212.78596)
		(end 90.869516 -212.88502)
		(width 0.0889)
		(layer "In4.Cu")
		(net "UPI_CPU0_CPU1_P1P0_DN<2>")
	)
	(segment
		(start 91.14917 -215.924384)
		(end 91.151202 -215.925654)
		(width 0.0889)
		(layer "In4.Cu")
		(net "UPI_CPU0_CPU1_P1P0_DN<2>")
	)
	(segment
		(start 95.719138 -196.934836)
		(end 91.918282 -207.188816)
		(width 0.14732)
		(layer "In4.Cu")
		(net "UPI_CPU0_CPU1_P1P0_DN<2>")
	)
	(segment
		(start 90.869516 -212.51164)
		(end 90.770456 -212.6107)
		(width 0.0889)
		(layer "In4.Cu")
		(net "UPI_CPU0_CPU1_P1P0_DN<2>")
	)
	(arc
		(start 91.154758 -214.261954)
		(mid 91.263905 -214.345882)
		(end 91.338908 -214.461344)
		(width 0.0889)
		(layer "In4.Cu")
		(net "UPI_CPU0_CPU1_P1P0_DN<2>")
	)
	(arc
		(start 91.151456 -214.946992)
		(mid 90.86906 -215.433205)
		(end 91.145868 -215.922606)
		(width 0.0889)
		(layer "In4.Cu")
		(net "UPI_CPU0_CPU1_P1P0_DN<2>")
	)
	(arc
		(start 380.351284 -215.43645)
		(mid 380.398963 -215.25355)
		(end 380.529846 -215.117172)
		(width 0.0889)
		(layer "In4.Cu")
		(net "UPI_CPU0_CPU1_P1P0_DN<2>")
	)
	(arc
		(start 90.884756 -213.969346)
		(mid 90.99475 -214.138715)
		(end 91.154758 -214.261954)
		(width 0.0889)
		(layer "In4.Cu")
		(net "UPI_CPU0_CPU1_P1P0_DN<2>")
	)
	(arc
		(start 91.139772 -216.58199)
		(mid 90.869361 -217.071457)
		(end 91.151964 -217.554048)
		(width 0.0889)
		(layer "In4.Cu")
		(net "UPI_CPU0_CPU1_P1P0_DN<2>")
	)
	(arc
		(start 380.140464 -217.50528)
		(mid 380.292971 -217.315182)
		(end 380.351284 -217.07856)
		(width 0.0889)
		(layer "In4.Cu")
		(net "UPI_CPU0_CPU1_P1P0_DN<2>")
	)
	(arc
		(start 380.059946 -216.569798)
		(mid 379.88147 -216.25052)
		(end 380.059946 -215.931242)
		(width 0.0889)
		(layer "In4.Cu")
		(net "UPI_CPU0_CPU1_P1P0_DN<2>")
	)
	(arc
		(start 381.005588 -214.261954)
		(mid 381.165558 -214.138984)
		(end 381.27559 -213.969854)
		(width 0.0889)
		(layer "In4.Cu")
		(net "UPI_CPU0_CPU1_P1P0_DN<2>")
	)
	(arc
		(start 380.538736 -215.112092)
		(mid 380.743071 -214.909487)
		(end 380.821184 -214.63254)
		(width 0.0889)
		(layer "In4.Cu")
		(net "UPI_CPU0_CPU1_P1P0_DN<2>")
	)
	(arc
		(start 380.351284 -217.064336)
		(mid 380.277368 -216.784834)
		(end 380.074932 -216.578434)
		(width 0.0889)
		(layer "In4.Cu")
		(net "UPI_CPU0_CPU1_P1P0_DN<2>")
	)
	(arc
		(start 381.27559 -213.969854)
		(mid 381.283691 -213.950181)
		(end 381.291084 -213.93023)
		(width 0.0889)
		(layer "In4.Cu")
		(net "UPI_CPU0_CPU1_P1P0_DN<2>")
	)
	(arc
		(start 91.160854 -217.559128)
		(mid 91.338702 -217.85472)
		(end 91.199462 -218.170252)
		(width 0.0889)
		(layer "In4.Cu")
		(net "UPI_CPU0_CPU1_P1P0_DN<2>")
	)
	(arc
		(start 91.338908 -214.622634)
		(mid 91.291229 -214.805534)
		(end 91.160346 -214.941912)
		(width 0.0889)
		(layer "In4.Cu")
		(net "UPI_CPU0_CPU1_P1P0_DN<2>")
	)
	(arc
		(start 90.869516 -213.895686)
		(mid 90.873375 -213.933292)
		(end 90.884756 -213.969346)
		(width 0.0889)
		(layer "In4.Cu")
		(net "UPI_CPU0_CPU1_P1P0_DN<2>")
	)
	(arc
		(start 380.821184 -214.461852)
		(mid 380.896255 -214.34611)
		(end 381.005588 -214.261954)
		(width 0.0889)
		(layer "In4.Cu")
		(net "UPI_CPU0_CPU1_P1P0_DN<2>")
	)
	(arc
		(start 380.074932 -215.922606)
		(mid 380.277408 -215.716083)
		(end 380.351284 -215.43645)
		(width 0.0889)
		(layer "In4.Cu")
		(net "UPI_CPU0_CPU1_P1P0_DN<2>")
	)
	(arc
		(start 380.1237 -217.518234)
		(mid 380.132143 -217.511836)
		(end 380.140464 -217.50528)
		(width 0.0889)
		(layer "In4.Cu")
		(net "UPI_CPU0_CPU1_P1P0_DN<2>")
	)
	(arc
		(start 91.160854 -215.931242)
		(mid 91.339451 -216.25052)
		(end 91.160854 -216.569798)
		(width 0.0889)
		(layer "In4.Cu")
		(net "UPI_CPU0_CPU1_P1P0_DN<2>")
	)
	(segment
		(start 111.170466 -217.600276)
		(end 111.170466 -217.064336)
		(width 0.13208)
		(layer "F.Cu")
		(net "UPI_CPU0_CPU1_P1P0_DN<23>")
	)
	(segment
		(start 360.050334 -219.228162)
		(end 360.050334 -218.692476)
		(width 0.13208)
		(layer "F.Cu")
		(net "UPI_CPU0_CPU1_P1P0_DN<23>")
	)
	(segment
		(start 360.050334 -218.692476)
		(end 360.05008 -218.692222)
		(width 0.13208)
		(layer "F.Cu")
		(net "UPI_CPU0_CPU1_P1P0_DN<23>")
	)
	(segment
		(start 111.014002 -217.335354)
		(end 111.170466 -217.064336)
		(width 0.0889)
		(layer "In4.Cu")
		(net "UPI_CPU0_CPU1_P1P0_DN<23>")
	)
	(segment
		(start 111.265462 -212.084412)
		(end 111.265462 -213.03488)
		(width 0.0889)
		(layer "In4.Cu")
		(net "UPI_CPU0_CPU1_P1P0_DN<23>")
	)
	(segment
		(start 111.775748 -210.19135)
		(end 111.653066 -210.538568)
		(width 0.14732)
		(layer "In4.Cu")
		(net "UPI_CPU0_CPU1_P1P0_DN<23>")
	)
	(segment
		(start 129.577084 -183.204866)
		(end 129.423668 -183.042306)
		(width 0.14732)
		(layer "In4.Cu")
		(net "UPI_CPU0_CPU1_P1P0_DN<23>")
	)
	(segment
		(start 217.220546 -163.02482)
		(end 217.80627 -165.331902)
		(width 0.14732)
		(layer "In4.Cu")
		(net "UPI_CPU0_CPU1_P1P0_DN<23>")
	)
	(segment
		(start 111.265462 -213.60384)
		(end 111.364522 -213.7029)
		(width 0.0889)
		(layer "In4.Cu")
		(net "UPI_CPU0_CPU1_P1P0_DN<23>")
	)
	(segment
		(start 217.583512 -165.705028)
		(end 216.79027 -165.906704)
		(width 0.14732)
		(layer "In4.Cu")
		(net "UPI_CPU0_CPU1_P1P0_DN<23>")
	)
	(segment
		(start 112.425988 -208.788254)
		(end 112.303052 -209.135726)
		(width 0.14732)
		(layer "In4.Cu")
		(net "UPI_CPU0_CPU1_P1P0_DN<23>")
	)
	(segment
		(start 302.4886 -167.815768)
		(end 280.284428 -168.19372)
		(width 0.14732)
		(layer "In4.Cu")
		(net "UPI_CPU0_CPU1_P1P0_DN<23>")
	)
	(segment
		(start 111.305848 -214.74557)
		(end 111.40694 -214.85479)
		(width 0.0889)
		(layer "In4.Cu")
		(net "UPI_CPU0_CPU1_P1P0_DN<23>")
	)
	(segment
		(start 111.96066 -210.103212)
		(end 111.775748 -210.19135)
		(width 0.14732)
		(layer "In4.Cu")
		(net "UPI_CPU0_CPU1_P1P0_DN<23>")
	)
	(segment
		(start 217.327226 -162.846004)
		(end 217.220546 -163.02482)
		(width 0.14732)
		(layer "In4.Cu")
		(net "UPI_CPU0_CPU1_P1P0_DN<23>")
	)
	(segment
		(start 213.406482 -163.841176)
		(end 198.058532 -167.797734)
		(width 0.14732)
		(layer "In4.Cu")
		(net "UPI_CPU0_CPU1_P1P0_DN<23>")
	)
	(segment
		(start 115.304824 -200.213468)
		(end 115.159282 -200.625202)
		(width 0.14732)
		(layer "In4.Cu")
		(net "UPI_CPU0_CPU1_P1P0_DN<23>")
	)
	(segment
		(start 223.959674 -161.314892)
		(end 224.545398 -163.62172)
		(width 0.14732)
		(layer "In4.Cu")
		(net "UPI_CPU0_CPU1_P1P0_DN<23>")
	)
	(segment
		(start 115.460526 -200.139046)
		(end 115.304824 -200.213468)
		(width 0.14732)
		(layer "In4.Cu")
		(net "UPI_CPU0_CPU1_P1P0_DN<23>")
	)
	(segment
		(start 226.312476 -160.566354)
		(end 226.205796 -160.744662)
		(width 0.14732)
		(layer "In4.Cu")
		(net "UPI_CPU0_CPU1_P1P0_DN<23>")
	)
	(segment
		(start 127.738378 -184.633108)
		(end 127.530352 -184.627266)
		(width 0.14732)
		(layer "In4.Cu")
		(net "UPI_CPU0_CPU1_P1P0_DN<23>")
	)
	(segment
		(start 332.50632 -174.102268)
		(end 319.71234 -169.57929)
		(width 0.14732)
		(layer "In4.Cu")
		(net "UPI_CPU0_CPU1_P1P0_DN<23>")
	)
	(segment
		(start 112.689894 -207.6069)
		(end 112.689894 -207.607154)
		(width 0.14732)
		(layer "In4.Cu")
		(net "UPI_CPU0_CPU1_P1P0_DN<23>")
	)
	(segment
		(start 228.452426 -160.17494)
		(end 229.037896 -162.481514)
		(width 0.14732)
		(layer "In4.Cu")
		(net "UPI_CPU0_CPU1_P1P0_DN<23>")
	)
	(segment
		(start 359.95483 -216.25052)
		(end 359.95483 -216.240614)
		(width 0.0889)
		(layer "In4.Cu")
		(net "UPI_CPU0_CPU1_P1P0_DN<23>")
	)
	(segment
		(start 221.283022 -164.766752)
		(end 221.096332 -164.655246)
		(width 0.14732)
		(layer "In4.Cu")
		(net "UPI_CPU0_CPU1_P1P0_DN<23>")
	)
	(segment
		(start 219.466922 -162.454844)
		(end 220.052646 -164.761672)
		(width 0.14732)
		(layer "In4.Cu")
		(net "UPI_CPU0_CPU1_P1P0_DN<23>")
	)
	(segment
		(start 115.159282 -200.625202)
		(end 115.233704 -200.780904)
		(width 0.14732)
		(layer "In4.Cu")
		(net "UPI_CPU0_CPU1_P1P0_DN<23>")
	)
	(segment
		(start 360.42473 -217.064336)
		(end 360.42473 -217.0557)
		(width 0.0889)
		(layer "In4.Cu")
		(net "UPI_CPU0_CPU1_P1P0_DN<23>")
	)
	(segment
		(start 127.101346 -185.031888)
		(end 127.095504 -185.239914)
		(width 0.14732)
		(layer "In4.Cu")
		(net "UPI_CPU0_CPU1_P1P0_DN<23>")
	)
	(segment
		(start 111.43361 -211.158582)
		(end 111.307372 -211.515452)
		(width 0.14732)
		(layer "In4.Cu")
		(net "UPI_CPU0_CPU1_P1P0_DN<23>")
	)
	(segment
		(start 112.083596 -209.75574)
		(end 111.96066 -210.103212)
		(width 0.14732)
		(layer "In4.Cu")
		(net "UPI_CPU0_CPU1_P1P0_DN<23>")
	)
	(segment
		(start 114.186716 -203.374752)
		(end 112.689894 -207.6069)
		(width 0.14732)
		(layer "In4.Cu")
		(net "UPI_CPU0_CPU1_P1P0_DN<23>")
	)
	(segment
		(start 220.052646 -164.761672)
		(end 219.829634 -165.135052)
		(width 0.14732)
		(layer "In4.Cu")
		(net "UPI_CPU0_CPU1_P1P0_DN<23>")
	)
	(segment
		(start 280.284428 -168.19372)
		(end 275.85543 -168.19372)
		(width 0.14732)
		(layer "In4.Cu")
		(net "UPI_CPU0_CPU1_P1P0_DN<23>")
	)
	(segment
		(start 130.471926 -181.850284)
		(end 130.466084 -182.05831)
		(width 0.14732)
		(layer "In4.Cu")
		(net "UPI_CPU0_CPU1_P1P0_DN<23>")
	)
	(segment
		(start 227.648516 -162.834066)
		(end 227.063046 -160.527492)
		(width 0.14732)
		(layer "In4.Cu")
		(net "UPI_CPU0_CPU1_P1P0_DN<23>")
	)
	(segment
		(start 360.42473 -215.436704)
		(end 360.42473 -215.275922)
		(width 0.0889)
		(layer "In4.Cu")
		(net "UPI_CPU0_CPU1_P1P0_DN<23>")
	)
	(segment
		(start 359.955084 -217.8939)
		(end 359.955084 -217.864182)
		(width 0.0889)
		(layer "In4.Cu")
		(net "UPI_CPU0_CPU1_P1P0_DN<23>")
	)
	(segment
		(start 360.206036 -211.681822)
		(end 360.205782 -211.681568)
		(width 0.14732)
		(layer "In4.Cu")
		(net "UPI_CPU0_CPU1_P1P0_DN<23>")
	)
	(segment
		(start 114.559334 -202.32116)
		(end 114.413792 -202.732894)
		(width 0.14732)
		(layer "In4.Cu")
		(net "UPI_CPU0_CPU1_P1P0_DN<23>")
	)
	(segment
		(start 115.233704 -200.780904)
		(end 115.087908 -201.192892)
		(width 0.14732)
		(layer "In4.Cu")
		(net "UPI_CPU0_CPU1_P1P0_DN<23>")
	)
	(segment
		(start 112.33785 -208.603596)
		(end 112.425988 -208.788254)
		(width 0.14732)
		(layer "In4.Cu")
		(net "UPI_CPU0_CPU1_P1P0_DN<23>")
	)
	(segment
		(start 360.206036 -211.922868)
		(end 360.206036 -211.90077)
		(width 0.0889)
		(layer "In4.Cu")
		(net "UPI_CPU0_CPU1_P1P0_DN<23>")
	)
	(segment
		(start 114.71529 -202.246738)
		(end 114.559334 -202.32116)
		(width 0.14732)
		(layer "In4.Cu")
		(net "UPI_CPU0_CPU1_P1P0_DN<23>")
	)
	(segment
		(start 228.55936 -159.99587)
		(end 228.452426 -160.17494)
		(width 0.14732)
		(layer "In4.Cu")
		(net "UPI_CPU0_CPU1_P1P0_DN<23>")
	)
	(segment
		(start 226.88423 -160.420812)
		(end 226.312476 -160.566354)
		(width 0.14732)
		(layer "In4.Cu")
		(net "UPI_CPU0_CPU1_P1P0_DN<23>")
	)
	(segment
		(start 221.096332 -164.655246)
		(end 220.909388 -164.543994)
		(width 0.14732)
		(layer "In4.Cu")
		(net "UPI_CPU0_CPU1_P1P0_DN<23>")
	)
	(segment
		(start 355.633274 -193.488564)
		(end 349.097854 -186.806332)
		(width 0.14732)
		(layer "In4.Cu")
		(net "UPI_CPU0_CPU1_P1P0_DN<23>")
	)
	(segment
		(start 112.11814 -209.223864)
		(end 111.995458 -209.571082)
		(width 0.14732)
		(layer "In4.Cu")
		(net "UPI_CPU0_CPU1_P1P0_DN<23>")
	)
	(segment
		(start 115.606322 -199.727058)
		(end 115.460526 -200.139046)
		(width 0.14732)
		(layer "In4.Cu")
		(net "UPI_CPU0_CPU1_P1P0_DN<23>")
	)
	(segment
		(start 129.423668 -183.042306)
		(end 129.215642 -183.036464)
		(width 0.14732)
		(layer "In4.Cu")
		(net "UPI_CPU0_CPU1_P1P0_DN<23>")
	)
	(segment
		(start 215.559894 -165.901624)
		(end 215.336882 -166.275004)
		(width 0.14732)
		(layer "In4.Cu")
		(net "UPI_CPU0_CPU1_P1P0_DN<23>")
	)
	(segment
		(start 226.569016 -163.425124)
		(end 225.775774 -163.6268)
		(width 0.14732)
		(layer "In4.Cu")
		(net "UPI_CPU0_CPU1_P1P0_DN<23>")
	)
	(segment
		(start 114.488214 -202.888342)
		(end 114.342418 -203.300584)
		(width 0.14732)
		(layer "In4.Cu")
		(net "UPI_CPU0_CPU1_P1P0_DN<23>")
	)
	(segment
		(start 222.07601 -164.565076)
		(end 221.283022 -164.766752)
		(width 0.14732)
		(layer "In4.Cu")
		(net "UPI_CPU0_CPU1_P1P0_DN<23>")
	)
	(segment
		(start 234.864148 -158.308548)
		(end 229.731316 -159.631888)
		(width 0.14732)
		(layer "In4.Cu")
		(net "UPI_CPU0_CPU1_P1P0_DN<23>")
	)
	(segment
		(start 360.206544 -218.421204)
		(end 360.182414 -218.33205)
		(width 0.0889)
		(layer "In4.Cu")
		(net "UPI_CPU0_CPU1_P1P0_DN<23>")
	)
	(segment
		(start 131.108958 -181.451504)
		(end 130.900932 -181.445662)
		(width 0.14732)
		(layer "In4.Cu")
		(net "UPI_CPU0_CPU1_P1P0_DN<23>")
	)
	(segment
		(start 126.053088 -186.22391)
		(end 125.845062 -186.218068)
		(width 0.14732)
		(layer "In4.Cu")
		(net "UPI_CPU0_CPU1_P1P0_DN<23>")
	)
	(segment
		(start 360.247946 -213.78672)
		(end 360.247946 -211.964778)
		(width 0.0889)
		(layer "In4.Cu")
		(net "UPI_CPU0_CPU1_P1P0_DN<23>")
	)
	(segment
		(start 131.697222 -181.626764)
		(end 131.262374 -181.614064)
		(width 0.14732)
		(layer "In4.Cu")
		(net "UPI_CPU0_CPU1_P1P0_DN<23>")
	)
	(segment
		(start 224.637854 -160.990788)
		(end 224.066354 -161.136076)
		(width 0.14732)
		(layer "In4.Cu")
		(net "UPI_CPU0_CPU1_P1P0_DN<23>")
	)
	(segment
		(start 360.05008 -218.692222)
		(end 360.206544 -218.421204)
		(width 0.0889)
		(layer "In4.Cu")
		(net "UPI_CPU0_CPU1_P1P0_DN<23>")
	)
	(segment
		(start 224.545398 -163.62172)
		(end 224.322386 -163.9951)
		(width 0.14732)
		(layer "In4.Cu")
		(net "UPI_CPU0_CPU1_P1P0_DN<23>")
	)
	(segment
		(start 342.284812 -178.929792)
		(end 340.03742 -177.373788)
		(width 0.14732)
		(layer "In4.Cu")
		(net "UPI_CPU0_CPU1_P1P0_DN<23>")
	)
	(segment
		(start 132.30479 -180.630068)
		(end 132.29209 -181.06517)
		(width 0.14732)
		(layer "In4.Cu")
		(net "UPI_CPU0_CPU1_P1P0_DN<23>")
	)
	(segment
		(start 216.79027 -165.906704)
		(end 216.60358 -165.795198)
		(width 0.14732)
		(layer "In4.Cu")
		(net "UPI_CPU0_CPU1_P1P0_DN<23>")
	)
	(segment
		(start 116.259102 -197.514972)
		(end 115.5319 -199.571356)
		(width 0.14732)
		(layer "In4.Cu")
		(net "UPI_CPU0_CPU1_P1P0_DN<23>")
	)
	(segment
		(start 130.6195 -182.22087)
		(end 130.6068 -182.655972)
		(width 0.14732)
		(layer "In4.Cu")
		(net "UPI_CPU0_CPU1_P1P0_DN<23>")
	)
	(segment
		(start 275.85543 -168.19372)
		(end 237.369604 -158.308548)
		(width 0.14732)
		(layer "In4.Cu")
		(net "UPI_CPU0_CPU1_P1P0_DN<23>")
	)
	(segment
		(start 130.011932 -183.217566)
		(end 129.577084 -183.204866)
		(width 0.14732)
		(layer "In4.Cu")
		(net "UPI_CPU0_CPU1_P1P0_DN<23>")
	)
	(segment
		(start 112.689894 -207.607154)
		(end 112.690148 -207.607916)
		(width 0.14732)
		(layer "In4.Cu")
		(net "UPI_CPU0_CPU1_P1P0_DN<23>")
	)
	(segment
		(start 126.206504 -186.38647)
		(end 126.053088 -186.22391)
		(width 0.14732)
		(layer "In4.Cu")
		(net "UPI_CPU0_CPU1_P1P0_DN<23>")
	)
	(segment
		(start 225.40214 -163.404042)
		(end 224.81667 -161.097468)
		(width 0.14732)
		(layer "In4.Cu")
		(net "UPI_CPU0_CPU1_P1P0_DN<23>")
	)
	(segment
		(start 127.24892 -185.402474)
		(end 127.23622 -185.837576)
		(width 0.14732)
		(layer "In4.Cu")
		(net "UPI_CPU0_CPU1_P1P0_DN<23>")
	)
	(segment
		(start 111.453168 -215.926162)
		(end 111.444278 -215.931242)
		(width 0.0889)
		(layer "In4.Cu")
		(net "UPI_CPU0_CPU1_P1P0_DN<23>")
	)
	(segment
		(start 128.93421 -183.811672)
		(end 128.92151 -184.246774)
		(width 0.14732)
		(layer "In4.Cu")
		(net "UPI_CPU0_CPU1_P1P0_DN<23>")
	)
	(segment
		(start 218.849956 -165.225222)
		(end 218.663012 -165.11397)
		(width 0.14732)
		(layer "In4.Cu")
		(net "UPI_CPU0_CPU1_P1P0_DN<23>")
	)
	(segment
		(start 111.307372 -211.515452)
		(end 111.307372 -211.767928)
		(width 0.14732)
		(layer "In4.Cu")
		(net "UPI_CPU0_CPU1_P1P0_DN<23>")
	)
	(segment
		(start 219.829634 -165.135052)
		(end 219.036646 -165.336728)
		(width 0.14732)
		(layer "In4.Cu")
		(net "UPI_CPU0_CPU1_P1P0_DN<23>")
	)
	(segment
		(start 214.17026 -166.253922)
		(end 213.58479 -163.947094)
		(width 0.14732)
		(layer "In4.Cu")
		(net "UPI_CPU0_CPU1_P1P0_DN<23>")
	)
	(segment
		(start 349.097854 -186.806332)
		(end 346.884244 -183.553862)
		(width 0.14732)
		(layer "In4.Cu")
		(net "UPI_CPU0_CPU1_P1P0_DN<23>")
	)
	(segment
		(start 128.780794 -183.649112)
		(end 128.93421 -183.811672)
		(width 0.14732)
		(layer "In4.Cu")
		(net "UPI_CPU0_CPU1_P1P0_DN<23>")
	)
	(segment
		(start 111.265462 -213.03488)
		(end 111.364522 -213.13394)
		(width 0.0889)
		(layer "In4.Cu")
		(net "UPI_CPU0_CPU1_P1P0_DN<23>")
	)
	(segment
		(start 228.815392 -162.855402)
		(end 228.022404 -163.05657)
		(width 0.14732)
		(layer "In4.Cu")
		(net "UPI_CPU0_CPU1_P1P0_DN<23>")
	)
	(segment
		(start 360.247946 -211.964778)
		(end 360.206036 -211.922868)
		(width 0.0889)
		(layer "In4.Cu")
		(net "UPI_CPU0_CPU1_P1P0_DN<23>")
	)
	(segment
		(start 114.186462 -203.374752)
		(end 114.186716 -203.374752)
		(width 0.14732)
		(layer "In4.Cu")
		(net "UPI_CPU0_CPU1_P1P0_DN<23>")
	)
	(segment
		(start 128.786636 -183.441086)
		(end 128.780794 -183.649112)
		(width 0.14732)
		(layer "In4.Cu")
		(net "UPI_CPU0_CPU1_P1P0_DN<23>")
	)
	(segment
		(start 128.92151 -184.246774)
		(end 128.326642 -184.808368)
		(width 0.14732)
		(layer "In4.Cu")
		(net "UPI_CPU0_CPU1_P1P0_DN<23>")
	)
	(segment
		(start 149.307042 -170.58005)
		(end 134.28726 -178.250088)
		(width 0.14732)
		(layer "In4.Cu")
		(net "UPI_CPU0_CPU1_P1P0_DN<23>")
	)
	(segment
		(start 228.022404 -163.05657)
		(end 227.648516 -162.834066)
		(width 0.14732)
		(layer "In4.Cu")
		(net "UPI_CPU0_CPU1_P1P0_DN<23>")
	)
	(segment
		(start 227.063046 -160.527492)
		(end 226.88423 -160.420812)
		(width 0.14732)
		(layer "In4.Cu")
		(net "UPI_CPU0_CPU1_P1P0_DN<23>")
	)
	(segment
		(start 110.93577 -217.356182)
		(end 111.014002 -217.335354)
		(width 0.0889)
		(layer "In4.Cu")
		(net "UPI_CPU0_CPU1_P1P0_DN<23>")
	)
	(segment
		(start 216.416636 -165.683946)
		(end 215.831166 -163.377372)
		(width 0.14732)
		(layer "In4.Cu")
		(net "UPI_CPU0_CPU1_P1P0_DN<23>")
	)
	(segment
		(start 111.618522 -211.070698)
		(end 111.43361 -211.158582)
		(width 0.14732)
		(layer "In4.Cu")
		(net "UPI_CPU0_CPU1_P1P0_DN<23>")
	)
	(segment
		(start 221.713298 -161.884868)
		(end 222.299022 -164.191696)
		(width 0.14732)
		(layer "In4.Cu")
		(net "UPI_CPU0_CPU1_P1P0_DN<23>")
	)
	(segment
		(start 223.155764 -163.974018)
		(end 222.570294 -161.667444)
		(width 0.14732)
		(layer "In4.Cu")
		(net "UPI_CPU0_CPU1_P1P0_DN<23>")
	)
	(segment
		(start 132.29209 -181.06517)
		(end 131.697222 -181.626764)
		(width 0.14732)
		(layer "In4.Cu")
		(net "UPI_CPU0_CPU1_P1P0_DN<23>")
	)
	(segment
		(start 127.23622 -185.837576)
		(end 126.641352 -186.39917)
		(width 0.14732)
		(layer "In4.Cu")
		(net "UPI_CPU0_CPU1_P1P0_DN<23>")
	)
	(segment
		(start 319.71234 -169.57929)
		(end 314.31611 -168.057322)
		(width 0.14732)
		(layer "In4.Cu")
		(net "UPI_CPU0_CPU1_P1P0_DN<23>")
	)
	(segment
		(start 215.08085 -163.41598)
		(end 214.97417 -163.594796)
		(width 0.14732)
		(layer "In4.Cu")
		(net "UPI_CPU0_CPU1_P1P0_DN<23>")
	)
	(segment
		(start 360.205782 -211.681568)
		(end 360.205782 -204.527912)
		(width 0.14732)
		(layer "In4.Cu")
		(net "UPI_CPU0_CPU1_P1P0_DN<23>")
	)
	(segment
		(start 189.352682 -168.189148)
		(end 155.811982 -168.938956)
		(width 0.14732)
		(layer "In4.Cu")
		(net "UPI_CPU0_CPU1_P1P0_DN<23>")
	)
	(segment
		(start 214.97417 -163.594796)
		(end 215.559894 -165.901624)
		(width 0.14732)
		(layer "In4.Cu")
		(net "UPI_CPU0_CPU1_P1P0_DN<23>")
	)
	(segment
		(start 111.364522 -213.3092)
		(end 111.265462 -213.40826)
		(width 0.0889)
		(layer "In4.Cu")
		(net "UPI_CPU0_CPU1_P1P0_DN<23>")
	)
	(segment
		(start 125.845062 -186.218068)
		(end 123.825 -188.124846)
		(width 0.14732)
		(layer "In4.Cu")
		(net "UPI_CPU0_CPU1_P1P0_DN<23>")
	)
	(segment
		(start 114.860832 -201.83475)
		(end 114.71529 -202.246738)
		(width 0.14732)
		(layer "In4.Cu")
		(net "UPI_CPU0_CPU1_P1P0_DN<23>")
	)
	(segment
		(start 115.087908 -201.192892)
		(end 114.932206 -201.267314)
		(width 0.14732)
		(layer "In4.Cu")
		(net "UPI_CPU0_CPU1_P1P0_DN<23>")
	)
	(segment
		(start 111.364522 -213.87816)
		(end 111.265462 -213.97722)
		(width 0.0889)
		(layer "In4.Cu")
		(net "UPI_CPU0_CPU1_P1P0_DN<23>")
	)
	(segment
		(start 223.529398 -164.196776)
		(end 223.342708 -164.08527)
		(width 0.14732)
		(layer "In4.Cu")
		(net "UPI_CPU0_CPU1_P1P0_DN<23>")
	)
	(segment
		(start 222.391478 -161.560764)
		(end 221.819978 -161.706052)
		(width 0.14732)
		(layer "In4.Cu")
		(net "UPI_CPU0_CPU1_P1P0_DN<23>")
	)
	(segment
		(start 225.589084 -163.515294)
		(end 225.40214 -163.404042)
		(width 0.14732)
		(layer "In4.Cu")
		(net "UPI_CPU0_CPU1_P1P0_DN<23>")
	)
	(segment
		(start 114.342418 -203.300584)
		(end 114.186462 -203.374752)
		(width 0.14732)
		(layer "In4.Cu")
		(net "UPI_CPU0_CPU1_P1P0_DN<23>")
	)
	(segment
		(start 132.151374 -180.467508)
		(end 132.30479 -180.630068)
		(width 0.14732)
		(layer "In4.Cu")
		(net "UPI_CPU0_CPU1_P1P0_DN<23>")
	)
	(segment
		(start 213.58479 -163.947094)
		(end 213.406482 -163.841176)
		(width 0.14732)
		(layer "In4.Cu")
		(net "UPI_CPU0_CPU1_P1P0_DN<23>")
	)
	(segment
		(start 111.307372 -211.767928)
		(end 111.307626 -211.768182)
		(width 0.14732)
		(layer "In4.Cu")
		(net "UPI_CPU0_CPU1_P1P0_DN<23>")
	)
	(segment
		(start 127.095504 -185.239914)
		(end 127.24892 -185.402474)
		(width 0.14732)
		(layer "In4.Cu")
		(net "UPI_CPU0_CPU1_P1P0_DN<23>")
	)
	(segment
		(start 111.364522 -213.7029)
		(end 111.364522 -213.87816)
		(width 0.0889)
		(layer "In4.Cu")
		(net "UPI_CPU0_CPU1_P1P0_DN<23>")
	)
	(segment
		(start 237.369604 -158.308548)
		(end 234.864148 -158.308548)
		(width 0.14732)
		(layer "In4.Cu")
		(net "UPI_CPU0_CPU1_P1P0_DN<23>")
	)
	(segment
		(start 225.775774 -163.6268)
		(end 225.589084 -163.515294)
		(width 0.14732)
		(layer "In4.Cu")
		(net "UPI_CPU0_CPU1_P1P0_DN<23>")
	)
	(segment
		(start 112.303052 -209.135726)
		(end 112.11814 -209.223864)
		(width 0.14732)
		(layer "In4.Cu")
		(net "UPI_CPU0_CPU1_P1P0_DN<23>")
	)
	(segment
		(start 314.31611 -168.057322)
		(end 302.4886 -167.815768)
		(width 0.14732)
		(layer "In4.Cu")
		(net "UPI_CPU0_CPU1_P1P0_DN<23>")
	)
	(segment
		(start 222.570294 -161.667444)
		(end 222.391478 -161.560764)
		(width 0.14732)
		(layer "In4.Cu")
		(net "UPI_CPU0_CPU1_P1P0_DN<23>")
	)
	(segment
		(start 224.066354 -161.136076)
		(end 223.959674 -161.314892)
		(width 0.14732)
		(layer "In4.Cu")
		(net "UPI_CPU0_CPU1_P1P0_DN<23>")
	)
	(segment
		(start 216.60358 -165.795198)
		(end 216.416636 -165.683946)
		(width 0.14732)
		(layer "In4.Cu")
		(net "UPI_CPU0_CPU1_P1P0_DN<23>")
	)
	(segment
		(start 346.884244 -183.553862)
		(end 342.284812 -178.929792)
		(width 0.14732)
		(layer "In4.Cu")
		(net "UPI_CPU0_CPU1_P1P0_DN<23>")
	)
	(segment
		(start 360.206036 -211.90077)
		(end 360.206036 -211.681822)
		(width 0.14732)
		(layer "In4.Cu")
		(net "UPI_CPU0_CPU1_P1P0_DN<23>")
	)
	(segment
		(start 111.735362 -215.285574)
		(end 111.735362 -215.452198)
		(width 0.0889)
		(layer "In4.Cu")
		(net "UPI_CPU0_CPU1_P1P0_DN<23>")
	)
	(segment
		(start 222.299022 -164.191696)
		(end 222.07601 -164.565076)
		(width 0.14732)
		(layer "In4.Cu")
		(net "UPI_CPU0_CPU1_P1P0_DN<23>")
	)
	(segment
		(start 112.690148 -207.607916)
		(end 112.778286 -207.792574)
		(width 0.14732)
		(layer "In4.Cu")
		(net "UPI_CPU0_CPU1_P1P0_DN<23>")
	)
	(segment
		(start 115.5319 -199.571356)
		(end 115.606322 -199.727058)
		(width 0.14732)
		(layer "In4.Cu")
		(net "UPI_CPU0_CPU1_P1P0_DN<23>")
	)
	(segment
		(start 129.215642 -183.036464)
		(end 128.786636 -183.441086)
		(width 0.14732)
		(layer "In4.Cu")
		(net "UPI_CPU0_CPU1_P1P0_DN<23>")
	)
	(segment
		(start 111.741204 -210.723226)
		(end 111.618522 -211.070698)
		(width 0.14732)
		(layer "In4.Cu")
		(net "UPI_CPU0_CPU1_P1P0_DN<23>")
	)
	(segment
		(start 155.811982 -168.938956)
		(end 149.307042 -170.58005)
		(width 0.14732)
		(layer "In4.Cu")
		(net "UPI_CPU0_CPU1_P1P0_DN<23>")
	)
	(segment
		(start 229.731316 -159.631888)
		(end 228.55936 -159.99587)
		(width 0.14732)
		(layer "In4.Cu")
		(net "UPI_CPU0_CPU1_P1P0_DN<23>")
	)
	(segment
		(start 218.077542 -162.807396)
		(end 217.898726 -162.700716)
		(width 0.14732)
		(layer "In4.Cu")
		(net "UPI_CPU0_CPU1_P1P0_DN<23>")
	)
	(segment
		(start 215.831166 -163.377372)
		(end 215.65235 -163.270692)
		(width 0.14732)
		(layer "In4.Cu")
		(net "UPI_CPU0_CPU1_P1P0_DN<23>")
	)
	(segment
		(start 198.058532 -167.797734)
		(end 194.946016 -168.189148)
		(width 0.14732)
		(layer "In4.Cu")
		(net "UPI_CPU0_CPU1_P1P0_DN<23>")
	)
	(segment
		(start 217.898726 -162.700716)
		(end 217.327226 -162.846004)
		(width 0.14732)
		(layer "In4.Cu")
		(net "UPI_CPU0_CPU1_P1P0_DN<23>")
	)
	(segment
		(start 114.788188 -201.674476)
		(end 114.786664 -201.679048)
		(width 0.14732)
		(layer "In4.Cu")
		(net "UPI_CPU0_CPU1_P1P0_DN<23>")
	)
	(segment
		(start 215.65235 -163.270692)
		(end 215.08085 -163.41598)
		(width 0.14732)
		(layer "In4.Cu")
		(net "UPI_CPU0_CPU1_P1P0_DN<23>")
	)
	(segment
		(start 226.791774 -163.051998)
		(end 226.569016 -163.425124)
		(width 0.14732)
		(layer "In4.Cu")
		(net "UPI_CPU0_CPU1_P1P0_DN<23>")
	)
	(segment
		(start 215.336882 -166.275004)
		(end 214.543894 -166.47668)
		(width 0.14732)
		(layer "In4.Cu")
		(net "UPI_CPU0_CPU1_P1P0_DN<23>")
	)
	(segment
		(start 217.80627 -165.331902)
		(end 217.583512 -165.705028)
		(width 0.14732)
		(layer "In4.Cu")
		(net "UPI_CPU0_CPU1_P1P0_DN<23>")
	)
	(segment
		(start 360.424984 -217.072972)
		(end 360.42473 -217.064336)
		(width 0.0889)
		(layer "In4.Cu")
		(net "UPI_CPU0_CPU1_P1P0_DN<23>")
	)
	(segment
		(start 134.28726 -178.250088)
		(end 132.157216 -180.259736)
		(width 0.14732)
		(layer "In4.Cu")
		(net "UPI_CPU0_CPU1_P1P0_DN<23>")
	)
	(segment
		(start 111.364522 -213.13394)
		(end 111.364522 -213.3092)
		(width 0.0889)
		(layer "In4.Cu")
		(net "UPI_CPU0_CPU1_P1P0_DN<23>")
	)
	(segment
		(start 218.663012 -165.11397)
		(end 218.077542 -162.807396)
		(width 0.14732)
		(layer "In4.Cu")
		(net "UPI_CPU0_CPU1_P1P0_DN<23>")
	)
	(segment
		(start 111.653066 -210.538568)
		(end 111.741204 -210.723226)
		(width 0.14732)
		(layer "In4.Cu")
		(net "UPI_CPU0_CPU1_P1P0_DN<23>")
	)
	(segment
		(start 219.036646 -165.336728)
		(end 218.849956 -165.225222)
		(width 0.14732)
		(layer "In4.Cu")
		(net "UPI_CPU0_CPU1_P1P0_DN<23>")
	)
	(segment
		(start 220.323918 -162.23742)
		(end 220.145102 -162.13074)
		(width 0.14732)
		(layer "In4.Cu")
		(net "UPI_CPU0_CPU1_P1P0_DN<23>")
	)
	(segment
		(start 111.307626 -212.042248)
		(end 111.265462 -212.084412)
		(width 0.0889)
		(layer "In4.Cu")
		(net "UPI_CPU0_CPU1_P1P0_DN<23>")
	)
	(segment
		(start 128.326642 -184.808368)
		(end 127.891794 -184.795668)
		(width 0.14732)
		(layer "In4.Cu")
		(net "UPI_CPU0_CPU1_P1P0_DN<23>")
	)
	(segment
		(start 130.6068 -182.655972)
		(end 130.011932 -183.217566)
		(width 0.14732)
		(layer "In4.Cu")
		(net "UPI_CPU0_CPU1_P1P0_DN<23>")
	)
	(segment
		(start 111.265716 -216.25052)
		(end 111.265716 -216.260426)
		(width 0.0889)
		(layer "In4.Cu")
		(net "UPI_CPU0_CPU1_P1P0_DN<23>")
	)
	(segment
		(start 112.778286 -207.792574)
		(end 112.655604 -208.140046)
		(width 0.14732)
		(layer "In4.Cu")
		(net "UPI_CPU0_CPU1_P1P0_DN<23>")
	)
	(segment
		(start 127.530352 -184.627266)
		(end 127.101346 -185.031888)
		(width 0.14732)
		(layer "In4.Cu")
		(net "UPI_CPU0_CPU1_P1P0_DN<23>")
	)
	(segment
		(start 127.891794 -184.795668)
		(end 127.738378 -184.633108)
		(width 0.14732)
		(layer "In4.Cu")
		(net "UPI_CPU0_CPU1_P1P0_DN<23>")
	)
	(segment
		(start 229.037896 -162.481514)
		(end 228.815392 -162.855402)
		(width 0.14732)
		(layer "In4.Cu")
		(net "UPI_CPU0_CPU1_P1P0_DN<23>")
	)
	(segment
		(start 223.342708 -164.08527)
		(end 223.155764 -163.974018)
		(width 0.14732)
		(layer "In4.Cu")
		(net "UPI_CPU0_CPU1_P1P0_DN<23>")
	)
	(segment
		(start 131.262374 -181.614064)
		(end 131.108958 -181.451504)
		(width 0.14732)
		(layer "In4.Cu")
		(net "UPI_CPU0_CPU1_P1P0_DN<23>")
	)
	(segment
		(start 111.307626 -211.768182)
		(end 111.307626 -212.02015)
		(width 0.14732)
		(layer "In4.Cu")
		(net "UPI_CPU0_CPU1_P1P0_DN<23>")
	)
	(segment
		(start 112.655604 -208.140046)
		(end 112.470438 -208.228438)
		(width 0.14732)
		(layer "In4.Cu")
		(net "UPI_CPU0_CPU1_P1P0_DN<23>")
	)
	(segment
		(start 126.641352 -186.39917)
		(end 126.206504 -186.38647)
		(width 0.14732)
		(layer "In4.Cu")
		(net "UPI_CPU0_CPU1_P1P0_DN<23>")
	)
	(segment
		(start 112.470438 -208.228438)
		(end 112.33785 -208.603596)
		(width 0.14732)
		(layer "In4.Cu")
		(net "UPI_CPU0_CPU1_P1P0_DN<23>")
	)
	(segment
		(start 359.95483 -214.744808)
		(end 359.95483 -214.536528)
		(width 0.0889)
		(layer "In4.Cu")
		(net "UPI_CPU0_CPU1_P1P0_DN<23>")
	)
	(segment
		(start 360.237532 -216.739978)
		(end 360.231436 -216.736422)
		(width 0.0889)
		(layer "In4.Cu")
		(net "UPI_CPU0_CPU1_P1P0_DN<23>")
	)
	(segment
		(start 111.265462 -213.40826)
		(end 111.265462 -213.60384)
		(width 0.0889)
		(layer "In4.Cu")
		(net "UPI_CPU0_CPU1_P1P0_DN<23>")
	)
	(segment
		(start 360.237278 -215.761062)
		(end 360.246168 -215.755982)
		(width 0.0889)
		(layer "In4.Cu")
		(net "UPI_CPU0_CPU1_P1P0_DN<23>")
	)
	(segment
		(start 220.909388 -164.543994)
		(end 220.323918 -162.23742)
		(width 0.14732)
		(layer "In4.Cu")
		(net "UPI_CPU0_CPU1_P1P0_DN<23>")
	)
	(segment
		(start 110.983268 -216.739978)
		(end 110.974378 -216.745058)
		(width 0.0889)
		(layer "In4.Cu")
		(net "UPI_CPU0_CPU1_P1P0_DN<23>")
	)
	(segment
		(start 340.03742 -177.373788)
		(end 332.50632 -174.102268)
		(width 0.14732)
		(layer "In4.Cu")
		(net "UPI_CPU0_CPU1_P1P0_DN<23>")
	)
	(segment
		(start 219.573602 -162.276028)
		(end 219.466922 -162.454844)
		(width 0.14732)
		(layer "In4.Cu")
		(net "UPI_CPU0_CPU1_P1P0_DN<23>")
	)
	(segment
		(start 132.157216 -180.259736)
		(end 132.151374 -180.467508)
		(width 0.14732)
		(layer "In4.Cu")
		(net "UPI_CPU0_CPU1_P1P0_DN<23>")
	)
	(segment
		(start 111.307626 -212.02015)
		(end 111.307626 -212.042248)
		(width 0.0889)
		(layer "In4.Cu")
		(net "UPI_CPU0_CPU1_P1P0_DN<23>")
	)
	(segment
		(start 221.819978 -161.706052)
		(end 221.713298 -161.884868)
		(width 0.14732)
		(layer "In4.Cu")
		(net "UPI_CPU0_CPU1_P1P0_DN<23>")
	)
	(segment
		(start 214.543894 -166.47668)
		(end 214.17026 -166.253922)
		(width 0.14732)
		(layer "In4.Cu")
		(net "UPI_CPU0_CPU1_P1P0_DN<23>")
	)
	(segment
		(start 130.466084 -182.05831)
		(end 130.6195 -182.22087)
		(width 0.14732)
		(layer "In4.Cu")
		(net "UPI_CPU0_CPU1_P1P0_DN<23>")
	)
	(segment
		(start 194.946016 -168.189148)
		(end 189.352682 -168.189148)
		(width 0.14732)
		(layer "In4.Cu")
		(net "UPI_CPU0_CPU1_P1P0_DN<23>")
	)
	(segment
		(start 226.205796 -160.744662)
		(end 226.791774 -163.051998)
		(width 0.14732)
		(layer "In4.Cu")
		(net "UPI_CPU0_CPU1_P1P0_DN<23>")
	)
	(segment
		(start 114.786664 -201.679048)
		(end 114.860832 -201.83475)
		(width 0.14732)
		(layer "In4.Cu")
		(net "UPI_CPU0_CPU1_P1P0_DN<23>")
	)
	(segment
		(start 111.265462 -214.642446)
		(end 111.265716 -214.643208)
		(width 0.0889)
		(layer "In4.Cu")
		(net "UPI_CPU0_CPU1_P1P0_DN<23>")
	)
	(segment
		(start 111.265462 -213.97722)
		(end 111.265462 -214.642446)
		(width 0.0889)
		(layer "In4.Cu")
		(net "UPI_CPU0_CPU1_P1P0_DN<23>")
	)
	(segment
		(start 123.825 -188.124846)
		(end 116.259102 -197.514972)
		(width 0.14732)
		(layer "In4.Cu")
		(net "UPI_CPU0_CPU1_P1P0_DN<23>")
	)
	(segment
		(start 111.995458 -209.571082)
		(end 112.083596 -209.75574)
		(width 0.14732)
		(layer "In4.Cu")
		(net "UPI_CPU0_CPU1_P1P0_DN<23>")
	)
	(segment
		(start 114.413792 -202.732894)
		(end 114.488214 -202.888342)
		(width 0.14732)
		(layer "In4.Cu")
		(net "UPI_CPU0_CPU1_P1P0_DN<23>")
	)
	(segment
		(start 114.932206 -201.267314)
		(end 114.788188 -201.674476)
		(width 0.14732)
		(layer "In4.Cu")
		(net "UPI_CPU0_CPU1_P1P0_DN<23>")
	)
	(segment
		(start 224.322386 -163.9951)
		(end 223.529398 -164.196776)
		(width 0.14732)
		(layer "In4.Cu")
		(net "UPI_CPU0_CPU1_P1P0_DN<23>")
	)
	(segment
		(start 224.81667 -161.097468)
		(end 224.637854 -160.990788)
		(width 0.14732)
		(layer "In4.Cu")
		(net "UPI_CPU0_CPU1_P1P0_DN<23>")
	)
	(segment
		(start 360.205782 -204.527912)
		(end 355.633274 -193.488564)
		(width 0.14732)
		(layer "In4.Cu")
		(net "UPI_CPU0_CPU1_P1P0_DN<23>")
	)
	(segment
		(start 220.145102 -162.13074)
		(end 219.573602 -162.276028)
		(width 0.14732)
		(layer "In4.Cu")
		(net "UPI_CPU0_CPU1_P1P0_DN<23>")
	)
	(segment
		(start 130.900932 -181.445662)
		(end 130.471926 -181.850284)
		(width 0.14732)
		(layer "In4.Cu")
		(net "UPI_CPU0_CPU1_P1P0_DN<23>")
	)
	(arc
		(start 360.231436 -216.736422)
		(mid 360.028849 -216.530071)
		(end 359.95483 -216.25052)
		(width 0.0889)
		(layer "In4.Cu")
		(net "UPI_CPU0_CPU1_P1P0_DN<23>")
	)
	(arc
		(start 111.444278 -215.931242)
		(mid 111.313364 -216.067602)
		(end 111.265716 -216.25052)
		(width 0.0889)
		(layer "In4.Cu")
		(net "UPI_CPU0_CPU1_P1P0_DN<23>")
	)
	(arc
		(start 359.95483 -214.536528)
		(mid 359.994316 -214.338176)
		(end 360.101134 -214.16645)
		(width 0.0889)
		(layer "In4.Cu")
		(net "UPI_CPU0_CPU1_P1P0_DN<23>")
	)
	(arc
		(start 111.265716 -216.260426)
		(mid 111.187605 -216.537375)
		(end 110.983268 -216.739978)
		(width 0.0889)
		(layer "In4.Cu")
		(net "UPI_CPU0_CPU1_P1P0_DN<23>")
	)
	(arc
		(start 360.237786 -217.388694)
		(mid 360.372719 -217.25534)
		(end 360.424984 -217.072972)
		(width 0.0889)
		(layer "In4.Cu")
		(net "UPI_CPU0_CPU1_P1P0_DN<23>")
	)
	(arc
		(start 110.974378 -216.745058)
		(mid 110.843464 -216.881418)
		(end 110.795816 -217.064336)
		(width 0.0889)
		(layer "In4.Cu")
		(net "UPI_CPU0_CPU1_P1P0_DN<23>")
	)
	(arc
		(start 360.16565 -218.319096)
		(mid 360.013568 -218.129664)
		(end 359.955084 -217.8939)
		(width 0.0889)
		(layer "In4.Cu")
		(net "UPI_CPU0_CPU1_P1P0_DN<23>")
	)
	(arc
		(start 360.240326 -215.076024)
		(mid 360.066297 -214.937387)
		(end 359.95483 -214.744808)
		(width 0.0889)
		(layer "In4.Cu")
		(net "UPI_CPU0_CPU1_P1P0_DN<23>")
	)
	(arc
		(start 111.735362 -215.452198)
		(mid 111.655992 -215.725932)
		(end 111.453168 -215.926162)
		(width 0.0889)
		(layer "In4.Cu")
		(net "UPI_CPU0_CPU1_P1P0_DN<23>")
	)
	(arc
		(start 360.246168 -215.755982)
		(mid 360.377082 -215.619622)
		(end 360.42473 -215.436704)
		(width 0.0889)
		(layer "In4.Cu")
		(net "UPI_CPU0_CPU1_P1P0_DN<23>")
	)
	(arc
		(start 360.42473 -217.0557)
		(mid 360.37246 -216.873335)
		(end 360.237532 -216.739978)
		(width 0.0889)
		(layer "In4.Cu")
		(net "UPI_CPU0_CPU1_P1P0_DN<23>")
	)
	(arc
		(start 360.182414 -218.33205)
		(mid 360.173973 -218.32565)
		(end 360.16565 -218.319096)
		(width 0.0889)
		(layer "In4.Cu")
		(net "UPI_CPU0_CPU1_P1P0_DN<23>")
	)
	(arc
		(start 111.508794 -214.94242)
		(mid 111.626299 -215.048265)
		(end 111.711994 -215.18118)
		(width 0.0889)
		(layer "In4.Cu")
		(net "UPI_CPU0_CPU1_P1P0_DN<23>")
	)
	(arc
		(start 360.101134 -214.16645)
		(mid 360.209921 -213.990264)
		(end 360.247946 -213.78672)
		(width 0.0889)
		(layer "In4.Cu")
		(net "UPI_CPU0_CPU1_P1P0_DN<23>")
	)
	(arc
		(start 111.265716 -214.643208)
		(mid 111.276093 -214.698195)
		(end 111.305848 -214.74557)
		(width 0.0889)
		(layer "In4.Cu")
		(net "UPI_CPU0_CPU1_P1P0_DN<23>")
	)
	(arc
		(start 359.955084 -217.864182)
		(mid 360.034303 -217.589497)
		(end 360.237786 -217.388694)
		(width 0.0889)
		(layer "In4.Cu")
		(net "UPI_CPU0_CPU1_P1P0_DN<23>")
	)
	(arc
		(start 359.95483 -216.240614)
		(mid 360.032941 -215.963665)
		(end 360.237278 -215.761062)
		(width 0.0889)
		(layer "In4.Cu")
		(net "UPI_CPU0_CPU1_P1P0_DN<23>")
	)
	(arc
		(start 111.711994 -215.18118)
		(mid 111.729376 -215.2321)
		(end 111.735362 -215.285574)
		(width 0.0889)
		(layer "In4.Cu")
		(net "UPI_CPU0_CPU1_P1P0_DN<23>")
	)
	(arc
		(start 110.795816 -217.064336)
		(mid 110.832676 -217.226133)
		(end 110.93577 -217.356182)
		(width 0.0889)
		(layer "In4.Cu")
		(net "UPI_CPU0_CPU1_P1P0_DN<23>")
	)
	(arc
		(start 111.40694 -214.85479)
		(mid 111.455402 -214.901471)
		(end 111.508794 -214.94242)
		(width 0.0889)
		(layer "In4.Cu")
		(net "UPI_CPU0_CPU1_P1P0_DN<23>")
	)
	(arc
		(start 360.42473 -215.275922)
		(mid 360.349659 -215.16018)
		(end 360.240326 -215.076024)
		(width 0.0889)
		(layer "In4.Cu")
		(net "UPI_CPU0_CPU1_P1P0_DN<23>")
	)
	(segment
		(start 110.230666 -219.228162)
		(end 110.230666 -218.692222)
		(width 0.13208)
		(layer "F.Cu")
		(net "UPI_CPU0_CPU1_P1P0_DN<22>")
	)
	(segment
		(start 360.990134 -217.600276)
		(end 360.990134 -217.06459)
		(width 0.13208)
		(layer "F.Cu")
		(net "UPI_CPU0_CPU1_P1P0_DN<22>")
	)
	(segment
		(start 360.990134 -217.06459)
		(end 360.98988 -217.064336)
		(width 0.13208)
		(layer "F.Cu")
		(net "UPI_CPU0_CPU1_P1P0_DN<22>")
	)
	(segment
		(start 340.48954 -176.649888)
		(end 332.84922 -173.330108)
		(width 0.14732)
		(layer "In4.Cu")
		(net "UPI_CPU0_CPU1_P1P0_DN<22>")
	)
	(segment
		(start 173.298866 -167.690546)
		(end 171.928028 -167.723312)
		(width 0.14732)
		(layer "In4.Cu")
		(net "UPI_CPU0_CPU1_P1P0_DN<22>")
	)
	(segment
		(start 349.661226 -186.052968)
		(end 349.458788 -185.74512)
		(width 0.14732)
		(layer "In4.Cu")
		(net "UPI_CPU0_CPU1_P1P0_DN<22>")
	)
	(segment
		(start 349.86214 -186.09437)
		(end 349.661226 -186.052968)
		(width 0.14732)
		(layer "In4.Cu")
		(net "UPI_CPU0_CPU1_P1P0_DN<22>")
	)
	(segment
		(start 150.15083 -167.182292)
		(end 150.04415 -167.360854)
		(width 0.14732)
		(layer "In4.Cu")
		(net "UPI_CPU0_CPU1_P1P0_DN<22>")
	)
	(segment
		(start 110.36808 -211.628482)
		(end 110.36808 -212.03285)
		(width 0.14732)
		(layer "In4.Cu")
		(net "UPI_CPU0_CPU1_P1P0_DN<22>")
	)
	(segment
		(start 111.93907 -207.221582)
		(end 111.793528 -207.63357)
		(width 0.14732)
		(layer "In4.Cu")
		(net "UPI_CPU0_CPU1_P1P0_DN<22>")
	)
	(segment
		(start 110.795562 -215.317578)
		(end 110.795562 -215.452198)
		(width 0.0889)
		(layer "In4.Cu")
		(net "UPI_CPU0_CPU1_P1P0_DN<22>")
	)
	(segment
		(start 159.8168 -165.248336)
		(end 159.87522 -167.701214)
		(width 0.14732)
		(layer "In4.Cu")
		(net "UPI_CPU0_CPU1_P1P0_DN<22>")
	)
	(segment
		(start 147.79752 -170.069764)
		(end 147.345654 -169.18559)
		(width 0.14732)
		(layer "In4.Cu")
		(net "UPI_CPU0_CPU1_P1P0_DN<22>")
	)
	(segment
		(start 110.367826 -211.297266)
		(end 110.367826 -211.628228)
		(width 0.14732)
		(layer "In4.Cu")
		(net "UPI_CPU0_CPU1_P1P0_DN<22>")
	)
	(segment
		(start 111.566198 -208.275428)
		(end 111.420656 -208.687416)
		(width 0.14732)
		(layer "In4.Cu")
		(net "UPI_CPU0_CPU1_P1P0_DN<22>")
	)
	(segment
		(start 361.36453 -215.436704)
		(end 361.36453 -215.229694)
		(width 0.0889)
		(layer "In4.Cu")
		(net "UPI_CPU0_CPU1_P1P0_DN<22>")
	)
	(segment
		(start 146.622008 -169.390314)
		(end 146.558 -169.587926)
		(width 0.14732)
		(layer "In4.Cu")
		(net "UPI_CPU0_CPU1_P1P0_DN<22>")
	)
	(segment
		(start 136.46658 -175.855884)
		(end 136.332214 -176.270158)
		(width 0.14732)
		(layer "In4.Cu")
		(net "UPI_CPU0_CPU1_P1P0_DN<22>")
	)
	(segment
		(start 153.960576 -168.53662)
		(end 153.586942 -168.312846)
		(width 0.14732)
		(layer "In4.Cu")
		(net "UPI_CPU0_CPU1_P1P0_DN<22>")
	)
	(segment
		(start 234.752896 -157.429454)
		(end 197.893178 -166.932356)
		(width 0.14732)
		(layer "In4.Cu")
		(net "UPI_CPU0_CPU1_P1P0_DN<22>")
	)
	(segment
		(start 110.034578 -217.383614)
		(end 110.042706 -217.388186)
		(width 0.0889)
		(layer "In4.Cu")
		(net "UPI_CPU0_CPU1_P1P0_DN<22>")
	)
	(segment
		(start 361.177078 -215.761062)
		(end 361.185968 -215.755982)
		(width 0.0889)
		(layer "In4.Cu")
		(net "UPI_CPU0_CPU1_P1P0_DN<22>")
	)
	(segment
		(start 158.233872 -165.138862)
		(end 157.643322 -165.153086)
		(width 0.14732)
		(layer "In4.Cu")
		(net "UPI_CPU0_CPU1_P1P0_DN<22>")
	)
	(segment
		(start 162.566858 -166.447216)
		(end 162.595306 -167.636698)
		(width 0.14732)
		(layer "In4.Cu")
		(net "UPI_CPU0_CPU1_P1P0_DN<22>")
	)
	(segment
		(start 165.550596 -167.351964)
		(end 165.555676 -167.56634)
		(width 0.14732)
		(layer "In4.Cu")
		(net "UPI_CPU0_CPU1_P1P0_DN<22>")
	)
	(segment
		(start 111.793528 -207.63357)
		(end 111.637572 -207.707992)
		(width 0.14732)
		(layer "In4.Cu")
		(net "UPI_CPU0_CPU1_P1P0_DN<22>")
	)
	(segment
		(start 171.613322 -167.422576)
		(end 171.59097 -166.48303)
		(width 0.14732)
		(layer "In4.Cu")
		(net "UPI_CPU0_CPU1_P1P0_DN<22>")
	)
	(segment
		(start 110.814866 -210.399122)
		(end 110.669324 -210.81111)
		(width 0.14732)
		(layer "In4.Cu")
		(net "UPI_CPU0_CPU1_P1P0_DN<22>")
	)
	(segment
		(start 152.505918 -168.903396)
		(end 151.713692 -169.103802)
		(width 0.14732)
		(layer "In4.Cu")
		(net "UPI_CPU0_CPU1_P1P0_DN<22>")
	)
	(segment
		(start 174.462694 -166.476426)
		(end 174.312326 -166.332916)
		(width 0.14732)
		(layer "In4.Cu")
		(net "UPI_CPU0_CPU1_P1P0_DN<22>")
	)
	(segment
		(start 110.740698 -210.24342)
		(end 110.814866 -210.399122)
		(width 0.14732)
		(layer "In4.Cu")
		(net "UPI_CPU0_CPU1_P1P0_DN<22>")
	)
	(segment
		(start 152.765252 -165.65626)
		(end 152.192482 -165.80104)
		(width 0.14732)
		(layer "In4.Cu")
		(net "UPI_CPU0_CPU1_P1P0_DN<22>")
	)
	(segment
		(start 146.558 -169.587926)
		(end 147.009866 -170.4721)
		(width 0.14732)
		(layer "In4.Cu")
		(net "UPI_CPU0_CPU1_P1P0_DN<22>")
	)
	(segment
		(start 152.94356 -165.76294)
		(end 152.765252 -165.65626)
		(width 0.14732)
		(layer "In4.Cu")
		(net "UPI_CPU0_CPU1_P1P0_DN<22>")
	)
	(segment
		(start 110.325916 -217.859864)
		(end 110.325916 -217.888312)
		(width 0.0889)
		(layer "In4.Cu")
		(net "UPI_CPU0_CPU1_P1P0_DN<22>")
	)
	(segment
		(start 361.309666 -205.0161)
		(end 356.319074 -192.968118)
		(width 0.14732)
		(layer "In4.Cu")
		(net "UPI_CPU0_CPU1_P1P0_DN<22>")
	)
	(segment
		(start 150.901908 -167.144192)
		(end 150.7236 -167.037512)
		(width 0.14732)
		(layer "In4.Cu")
		(net "UPI_CPU0_CPU1_P1P0_DN<22>")
	)
	(segment
		(start 112.69218 -205.092554)
		(end 112.546638 -205.504542)
		(width 0.14732)
		(layer "In4.Cu")
		(net "UPI_CPU0_CPU1_P1P0_DN<22>")
	)
	(segment
		(start 314.285884 -167.176704)
		(end 302.490124 -166.936166)
		(width 0.14732)
		(layer "In4.Cu")
		(net "UPI_CPU0_CPU1_P1P0_DN<22>")
	)
	(segment
		(start 137.183876 -175.31588)
		(end 136.986264 -175.251872)
		(width 0.14732)
		(layer "In4.Cu")
		(net "UPI_CPU0_CPU1_P1P0_DN<22>")
	)
	(segment
		(start 361.35183 -211.756498)
		(end 361.30992 -211.714588)
		(width 0.0889)
		(layer "In4.Cu")
		(net "UPI_CPU0_CPU1_P1P0_DN<22>")
	)
	(segment
		(start 110.074202 -218.421204)
		(end 110.189264 -218.620594)
		(width 0.0889)
		(layer "In4.Cu")
		(net "UPI_CPU0_CPU1_P1P0_DN<22>")
	)
	(segment
		(start 349.50019 -185.544714)
		(end 349.297752 -185.23712)
		(width 0.14732)
		(layer "In4.Cu")
		(net "UPI_CPU0_CPU1_P1P0_DN<22>")
	)
	(segment
		(start 176.779682 -166.421308)
		(end 176.629314 -166.277798)
		(width 0.14732)
		(layer "In4.Cu")
		(net "UPI_CPU0_CPU1_P1P0_DN<22>")
	)
	(segment
		(start 111.637572 -207.707992)
		(end 111.637318 -207.708754)
		(width 0.14732)
		(layer "In4.Cu")
		(net "UPI_CPU0_CPU1_P1P0_DN<22>")
	)
	(segment
		(start 176.800764 -167.299386)
		(end 176.779682 -166.421308)
		(width 0.14732)
		(layer "In4.Cu")
		(net "UPI_CPU0_CPU1_P1P0_DN<22>")
	)
	(segment
		(start 171.928028 -167.723312)
		(end 171.613322 -167.422576)
		(width 0.14732)
		(layer "In4.Cu")
		(net "UPI_CPU0_CPU1_P1P0_DN<22>")
	)
	(segment
		(start 110.36808 -212.054948)
		(end 110.325916 -212.097112)
		(width 0.0889)
		(layer "In4.Cu")
		(net "UPI_CPU0_CPU1_P1P0_DN<22>")
	)
	(segment
		(start 163.451286 -166.426134)
		(end 163.300918 -166.282624)
		(width 0.14732)
		(layer "In4.Cu")
		(net "UPI_CPU0_CPU1_P1P0_DN<22>")
	)
	(segment
		(start 112.546638 -205.504542)
		(end 112.390682 -205.578964)
		(width 0.14732)
		(layer "In4.Cu")
		(net "UPI_CPU0_CPU1_P1P0_DN<22>")
	)
	(segment
		(start 157.499812 -165.303454)
		(end 157.558232 -167.756332)
		(width 0.14732)
		(layer "In4.Cu")
		(net "UPI_CPU0_CPU1_P1P0_DN<22>")
	)
	(segment
		(start 147.345654 -169.18559)
		(end 147.148042 -169.121582)
		(width 0.14732)
		(layer "In4.Cu")
		(net "UPI_CPU0_CPU1_P1P0_DN<22>")
	)
	(segment
		(start 152.729692 -168.529762)
		(end 152.505918 -168.903396)
		(width 0.14732)
		(layer "In4.Cu")
		(net "UPI_CPU0_CPU1_P1P0_DN<22>")
	)
	(segment
		(start 361.25277 -212.87486)
		(end 361.35183 -212.7758)
		(width 0.0889)
		(layer "In4.Cu")
		(net "UPI_CPU0_CPU1_P1P0_DN<22>")
	)
	(segment
		(start 110.513368 -215.926162)
		(end 110.504478 -215.931242)
		(width 0.0889)
		(layer "In4.Cu")
		(net "UPI_CPU0_CPU1_P1P0_DN<22>")
	)
	(segment
		(start 150.04415 -167.360854)
		(end 150.482554 -169.09669)
		(width 0.14732)
		(layer "In4.Cu")
		(net "UPI_CPU0_CPU1_P1P0_DN<22>")
	)
	(segment
		(start 166.440104 -167.545258)
		(end 166.43477 -167.330882)
		(width 0.14732)
		(layer "In4.Cu")
		(net "UPI_CPU0_CPU1_P1P0_DN<22>")
	)
	(segment
		(start 175.895508 -166.44239)
		(end 175.91659 -167.320722)
		(width 0.14732)
		(layer "In4.Cu")
		(net "UPI_CPU0_CPU1_P1P0_DN<22>")
	)
	(segment
		(start 280.182828 -167.320214)
		(end 275.966682 -167.320214)
		(width 0.14732)
		(layer "In4.Cu")
		(net "UPI_CPU0_CPU1_P1P0_DN<22>")
	)
	(segment
		(start 347.747844 -183.337454)
		(end 347.43517 -182.877968)
		(width 0.14732)
		(layer "In4.Cu")
		(net "UPI_CPU0_CPU1_P1P0_DN<22>")
	)
	(segment
		(start 112.24514 -205.990698)
		(end 112.319562 -206.146146)
		(width 0.14732)
		(layer "In4.Cu")
		(net "UPI_CPU0_CPU1_P1P0_DN<22>")
	)
	(segment
		(start 342.824562 -178.286156)
		(end 340.48954 -176.649888)
		(width 0.14732)
		(layer "In4.Cu")
		(net "UPI_CPU0_CPU1_P1P0_DN<22>")
	)
	(segment
		(start 147.148042 -169.121582)
		(end 146.622008 -169.390314)
		(width 0.14732)
		(layer "In4.Cu")
		(net "UPI_CPU0_CPU1_P1P0_DN<22>")
	)
	(segment
		(start 110.098332 -218.33205)
		(end 110.074202 -218.421204)
		(width 0.0889)
		(layer "In4.Cu")
		(net "UPI_CPU0_CPU1_P1P0_DN<22>")
	)
	(segment
		(start 158.442406 -167.734742)
		(end 158.383986 -165.282372)
		(width 0.14732)
		(layer "In4.Cu")
		(net "UPI_CPU0_CPU1_P1P0_DN<22>")
	)
	(segment
		(start 110.367826 -211.628228)
		(end 110.36808 -211.628482)
		(width 0.14732)
		(layer "In4.Cu")
		(net "UPI_CPU0_CPU1_P1P0_DN<22>")
	)
	(segment
		(start 146.8755 -170.886374)
		(end 137.668254 -175.587914)
		(width 0.14732)
		(layer "In4.Cu")
		(net "UPI_CPU0_CPU1_P1P0_DN<22>")
	)
	(segment
		(start 150.25878 -169.470578)
		(end 149.05101 -169.775378)
		(width 0.14732)
		(layer "In4.Cu")
		(net "UPI_CPU0_CPU1_P1P0_DN<22>")
	)
	(segment
		(start 170.428158 -167.758618)
		(end 166.754556 -167.845994)
		(width 0.14732)
		(layer "In4.Cu")
		(net "UPI_CPU0_CPU1_P1P0_DN<22>")
	)
	(segment
		(start 112.018064 -206.632556)
		(end 111.864902 -207.06588)
		(width 0.14732)
		(layer "In4.Cu")
		(net "UPI_CPU0_CPU1_P1P0_DN<22>")
	)
	(segment
		(start 361.25277 -212.43544)
		(end 361.25277 -212.26018)
		(width 0.0889)
		(layer "In4.Cu")
		(net "UPI_CPU0_CPU1_P1P0_DN<22>")
	)
	(segment
		(start 159.96031 -165.097968)
		(end 159.8168 -165.248336)
		(width 0.14732)
		(layer "In4.Cu")
		(net "UPI_CPU0_CPU1_P1P0_DN<22>")
	)
	(segment
		(start 137.254234 -175.453548)
		(end 137.183876 -175.31588)
		(width 0.14732)
		(layer "In4.Cu")
		(net "UPI_CPU0_CPU1_P1P0_DN<22>")
	)
	(segment
		(start 136.396222 -175.718216)
		(end 136.46658 -175.855884)
		(width 0.14732)
		(layer "In4.Cu")
		(net "UPI_CPU0_CPU1_P1P0_DN<22>")
	)
	(segment
		(start 174.798736 -167.65524)
		(end 174.483776 -167.354504)
		(width 0.14732)
		(layer "In4.Cu")
		(net "UPI_CPU0_CPU1_P1P0_DN<22>")
	)
	(segment
		(start 112.173766 -206.558388)
		(end 112.018064 -206.632556)
		(width 0.14732)
		(layer "In4.Cu")
		(net "UPI_CPU0_CPU1_P1P0_DN<22>")
	)
	(segment
		(start 110.513368 -210.885532)
		(end 110.513622 -210.885532)
		(width 0.14732)
		(layer "In4.Cu")
		(net "UPI_CPU0_CPU1_P1P0_DN<22>")
	)
	(segment
		(start 356.319074 -192.968118)
		(end 350.446848 -186.983116)
		(width 0.14732)
		(layer "In4.Cu")
		(net "UPI_CPU0_CPU1_P1P0_DN<22>")
	)
	(segment
		(start 170.706034 -166.504366)
		(end 170.729148 -167.443658)
		(width 0.14732)
		(layer "In4.Cu")
		(net "UPI_CPU0_CPU1_P1P0_DN<22>")
	)
	(segment
		(start 155.655264 -168.109138)
		(end 153.960576 -168.53662)
		(width 0.14732)
		(layer "In4.Cu")
		(net "UPI_CPU0_CPU1_P1P0_DN<22>")
	)
	(segment
		(start 157.643322 -165.153086)
		(end 157.499812 -165.303454)
		(width 0.14732)
		(layer "In4.Cu")
		(net "UPI_CPU0_CPU1_P1P0_DN<22>")
	)
	(segment
		(start 166.754556 -167.845994)
		(end 166.440104 -167.545258)
		(width 0.14732)
		(layer "In4.Cu")
		(net "UPI_CPU0_CPU1_P1P0_DN<22>")
	)
	(segment
		(start 173.721776 -166.34714)
		(end 173.57852 -166.497508)
		(width 0.14732)
		(layer "In4.Cu")
		(net "UPI_CPU0_CPU1_P1P0_DN<22>")
	)
	(segment
		(start 111.49203 -208.119726)
		(end 111.566198 -208.275428)
		(width 0.14732)
		(layer "In4.Cu")
		(net "UPI_CPU0_CPU1_P1P0_DN<22>")
	)
	(segment
		(start 110.325916 -212.097112)
		(end 110.325916 -214.695278)
		(width 0.0889)
		(layer "In4.Cu")
		(net "UPI_CPU0_CPU1_P1P0_DN<22>")
	)
	(segment
		(start 170.50639 -167.67683)
		(end 170.428158 -167.758618)
		(width 0.14732)
		(layer "In4.Cu")
		(net "UPI_CPU0_CPU1_P1P0_DN<22>")
	)
	(segment
		(start 170.50639 -167.676576)
		(end 170.50639 -167.67683)
		(width 0.14732)
		(layer "In4.Cu")
		(net "UPI_CPU0_CPU1_P1P0_DN<22>")
	)
	(segment
		(start 158.757366 -168.035732)
		(end 158.442406 -167.734742)
		(width 0.14732)
		(layer "In4.Cu")
		(net "UPI_CPU0_CPU1_P1P0_DN<22>")
	)
	(segment
		(start 152.085802 -165.979602)
		(end 152.729692 -168.529762)
		(width 0.14732)
		(layer "In4.Cu")
		(net "UPI_CPU0_CPU1_P1P0_DN<22>")
	)
	(segment
		(start 111.187738 -209.345276)
		(end 111.042196 -209.757264)
		(width 0.14732)
		(layer "In4.Cu")
		(net "UPI_CPU0_CPU1_P1P0_DN<22>")
	)
	(segment
		(start 348.87535 -184.59577)
		(end 348.28988 -183.998616)
		(width 0.14732)
		(layer "In4.Cu")
		(net "UPI_CPU0_CPU1_P1P0_DN<22>")
	)
	(segment
		(start 174.312326 -166.332916)
		(end 173.721776 -166.34714)
		(width 0.14732)
		(layer "In4.Cu")
		(net "UPI_CPU0_CPU1_P1P0_DN<22>")
	)
	(segment
		(start 157.558232 -167.756332)
		(end 157.257496 -168.071038)
		(width 0.14732)
		(layer "In4.Cu")
		(net "UPI_CPU0_CPU1_P1P0_DN<22>")
	)
	(segment
		(start 162.710368 -166.296848)
		(end 162.566858 -166.447216)
		(width 0.14732)
		(layer "In4.Cu")
		(net "UPI_CPU0_CPU1_P1P0_DN<22>")
	)
	(segment
		(start 162.29457 -167.951404)
		(end 161.0741 -167.980614)
		(width 0.14732)
		(layer "In4.Cu")
		(net "UPI_CPU0_CPU1_P1P0_DN<22>")
	)
	(segment
		(start 149.05101 -169.775378)
		(end 148.21154 -170.20413)
		(width 0.14732)
		(layer "In4.Cu")
		(net "UPI_CPU0_CPU1_P1P0_DN<22>")
	)
	(segment
		(start 237.459012 -157.429454)
		(end 234.752896 -157.429454)
		(width 0.14732)
		(layer "In4.Cu")
		(net "UPI_CPU0_CPU1_P1P0_DN<22>")
	)
	(segment
		(start 111.420656 -208.687416)
		(end 111.2647 -208.761838)
		(width 0.14732)
		(layer "In4.Cu")
		(net "UPI_CPU0_CPU1_P1P0_DN<22>")
	)
	(segment
		(start 171.440348 -166.33952)
		(end 170.849798 -166.353744)
		(width 0.14732)
		(layer "In4.Cu")
		(net "UPI_CPU0_CPU1_P1P0_DN<22>")
	)
	(segment
		(start 361.35183 -212.16112)
		(end 361.35183 -211.756498)
		(width 0.0889)
		(layer "In4.Cu")
		(net "UPI_CPU0_CPU1_P1P0_DN<22>")
	)
	(segment
		(start 361.309666 -211.328)
		(end 361.309666 -205.0161)
		(width 0.14732)
		(layer "In4.Cu")
		(net "UPI_CPU0_CPU1_P1P0_DN<22>")
	)
	(segment
		(start 361.35183 -213.14918)
		(end 361.25277 -213.05012)
		(width 0.0889)
		(layer "In4.Cu")
		(net "UPI_CPU0_CPU1_P1P0_DN<22>")
	)
	(segment
		(start 173.57852 -166.497508)
		(end 173.599602 -167.37584)
		(width 0.14732)
		(layer "In4.Cu")
		(net "UPI_CPU0_CPU1_P1P0_DN<22>")
	)
	(segment
		(start 151.339804 -168.880028)
		(end 150.901908 -167.144192)
		(width 0.14732)
		(layer "In4.Cu")
		(net "UPI_CPU0_CPU1_P1P0_DN<22>")
	)
	(segment
		(start 350.446848 -186.983116)
		(end 349.861886 -186.094624)
		(width 0.14732)
		(layer "In4.Cu")
		(net "UPI_CPU0_CPU1_P1P0_DN<22>")
	)
	(segment
		(start 110.513622 -210.885532)
		(end 110.367826 -211.297266)
		(width 0.14732)
		(layer "In4.Cu")
		(net "UPI_CPU0_CPU1_P1P0_DN<22>")
	)
	(segment
		(start 151.713692 -169.103802)
		(end 151.339804 -168.880028)
		(width 0.14732)
		(layer "In4.Cu")
		(net "UPI_CPU0_CPU1_P1P0_DN<22>")
	)
	(segment
		(start 173.599602 -167.37584)
		(end 173.298866 -167.690546)
		(width 0.14732)
		(layer "In4.Cu")
		(net "UPI_CPU0_CPU1_P1P0_DN<22>")
	)
	(segment
		(start 136.986264 -175.251872)
		(end 136.46023 -175.520604)
		(width 0.14732)
		(layer "In4.Cu")
		(net "UPI_CPU0_CPU1_P1P0_DN<22>")
	)
	(segment
		(start 112.619028 -204.933042)
		(end 112.617758 -204.936852)
		(width 0.14732)
		(layer "In4.Cu")
		(net "UPI_CPU0_CPU1_P1P0_DN<22>")
	)
	(segment
		(start 360.89463 -216.260426)
		(end 360.89463 -216.240614)
		(width 0.0889)
		(layer "In4.Cu")
		(net "UPI_CPU0_CPU1_P1P0_DN<22>")
	)
	(segment
		(start 110.36808 -212.03285)
		(end 110.36808 -212.054948)
		(width 0.0889)
		(layer "In4.Cu")
		(net "UPI_CPU0_CPU1_P1P0_DN<22>")
	)
	(segment
		(start 361.30992 -211.714588)
		(end 361.30992 -211.69249)
		(width 0.0889)
		(layer "In4.Cu")
		(net "UPI_CPU0_CPU1_P1P0_DN<22>")
	)
	(segment
		(start 361.82173 -214.71509)
		(end 361.82173 -214.546434)
		(width 0.0889)
		(layer "In4.Cu")
		(net "UPI_CPU0_CPU1_P1P0_DN<22>")
	)
	(segment
		(start 349.861886 -186.094624)
		(end 349.86214 -186.09437)
		(width 0.14732)
		(layer "In4.Cu")
		(net "UPI_CPU0_CPU1_P1P0_DN<22>")
	)
	(segment
		(start 111.493554 -208.115154)
		(end 111.49203 -208.119726)
		(width 0.14732)
		(layer "In4.Cu")
		(net "UPI_CPU0_CPU1_P1P0_DN<22>")
	)
	(segment
		(start 137.668254 -175.587914)
		(end 137.254234 -175.453548)
		(width 0.14732)
		(layer "In4.Cu")
		(net "UPI_CPU0_CPU1_P1P0_DN<22>")
	)
	(segment
		(start 361.25277 -212.26018)
		(end 361.35183 -212.16112)
		(width 0.0889)
		(layer "In4.Cu")
		(net "UPI_CPU0_CPU1_P1P0_DN<22>")
	)
	(segment
		(start 349.458788 -185.74512)
		(end 349.50019 -185.544714)
		(width 0.14732)
		(layer "In4.Cu")
		(net "UPI_CPU0_CPU1_P1P0_DN<22>")
	)
	(segment
		(start 175.91659 -167.320722)
		(end 175.615854 -167.635428)
		(width 0.14732)
		(layer "In4.Cu")
		(net "UPI_CPU0_CPU1_P1P0_DN<22>")
	)
	(segment
		(start 150.7236 -167.037512)
		(end 150.15083 -167.182292)
		(width 0.14732)
		(layer "In4.Cu")
		(net "UPI_CPU0_CPU1_P1P0_DN<22>")
	)
	(segment
		(start 110.189264 -218.620594)
		(end 110.230666 -218.692222)
		(width 0.0889)
		(layer "In4.Cu")
		(net "UPI_CPU0_CPU1_P1P0_DN<22>")
	)
	(segment
		(start 111.2647 -208.761838)
		(end 111.11357 -209.189574)
		(width 0.14732)
		(layer "In4.Cu")
		(net "UPI_CPU0_CPU1_P1P0_DN<22>")
	)
	(segment
		(start 162.595306 -167.636698)
		(end 162.29457 -167.951404)
		(width 0.14732)
		(layer "In4.Cu")
		(net "UPI_CPU0_CPU1_P1P0_DN<22>")
	)
	(segment
		(start 349.096838 -185.195718)
		(end 348.8944 -184.88787)
		(width 0.14732)
		(layer "In4.Cu")
		(net "UPI_CPU0_CPU1_P1P0_DN<22>")
	)
	(segment
		(start 170.729148 -167.443658)
		(end 170.50639 -167.676576)
		(width 0.14732)
		(layer "In4.Cu")
		(net "UPI_CPU0_CPU1_P1P0_DN<22>")
	)
	(segment
		(start 361.146344 -217.335354)
		(end 361.224576 -217.356182)
		(width 0.0889)
		(layer "In4.Cu")
		(net "UPI_CPU0_CPU1_P1P0_DN<22>")
	)
	(segment
		(start 332.84922 -173.330108)
		(end 319.97523 -168.782238)
		(width 0.14732)
		(layer "In4.Cu")
		(net "UPI_CPU0_CPU1_P1P0_DN<22>")
	)
	(segment
		(start 361.643168 -214.227156)
		(end 361.634278 -214.222076)
		(width 0.0889)
		(layer "In4.Cu")
		(net "UPI_CPU0_CPU1_P1P0_DN<22>")
	)
	(segment
		(start 175.615854 -167.635428)
		(end 174.798736 -167.65524)
		(width 0.14732)
		(layer "In4.Cu")
		(net "UPI_CPU0_CPU1_P1P0_DN<22>")
	)
	(segment
		(start 319.97523 -168.782238)
		(end 314.285884 -167.176704)
		(width 0.14732)
		(layer "In4.Cu")
		(net "UPI_CPU0_CPU1_P1P0_DN<22>")
	)
	(segment
		(start 158.383986 -165.282372)
		(end 158.233872 -165.138862)
		(width 0.14732)
		(layer "In4.Cu")
		(net "UPI_CPU0_CPU1_P1P0_DN<22>")
	)
	(segment
		(start 110.042706 -217.388186)
		(end 110.043468 -217.388694)
		(width 0.0889)
		(layer "In4.Cu")
		(net "UPI_CPU0_CPU1_P1P0_DN<22>")
	)
	(segment
		(start 361.35183 -212.5345)
		(end 361.25277 -212.43544)
		(width 0.0889)
		(layer "In4.Cu")
		(net "UPI_CPU0_CPU1_P1P0_DN<22>")
	)
	(segment
		(start 361.30992 -211.328254)
		(end 361.309666 -211.328)
		(width 0.14732)
		(layer "In4.Cu")
		(net "UPI_CPU0_CPU1_P1P0_DN<22>")
	)
	(segment
		(start 111.11357 -209.189574)
		(end 111.187738 -209.345276)
		(width 0.14732)
		(layer "In4.Cu")
		(net "UPI_CPU0_CPU1_P1P0_DN<22>")
	)
	(segment
		(start 361.30992 -211.69249)
		(end 361.30992 -211.328254)
		(width 0.14732)
		(layer "In4.Cu")
		(net "UPI_CPU0_CPU1_P1P0_DN<22>")
	)
	(segment
		(start 123.284742 -187.472574)
		(end 115.280694 -197.406768)
		(width 0.14732)
		(layer "In4.Cu")
		(net "UPI_CPU0_CPU1_P1P0_DN<22>")
	)
	(segment
		(start 133.76275 -177.582322)
		(end 123.284742 -187.472574)
		(width 0.14732)
		(layer "In4.Cu")
		(net "UPI_CPU0_CPU1_P1P0_DN<22>")
	)
	(segment
		(start 361.25277 -213.05012)
		(end 361.25277 -212.87486)
		(width 0.0889)
		(layer "In4.Cu")
		(net "UPI_CPU0_CPU1_P1P0_DN<22>")
	)
	(segment
		(start 148.21154 -170.20413)
		(end 147.79752 -170.069764)
		(width 0.14732)
		(layer "In4.Cu")
		(net "UPI_CPU0_CPU1_P1P0_DN<22>")
	)
	(segment
		(start 165.25494 -167.8813)
		(end 163.794186 -167.916098)
		(width 0.14732)
		(layer "In4.Cu")
		(net "UPI_CPU0_CPU1_P1P0_DN<22>")
	)
	(segment
		(start 136.332214 -176.270158)
		(end 133.76275 -177.582322)
		(width 0.14732)
		(layer "In4.Cu")
		(net "UPI_CPU0_CPU1_P1P0_DN<22>")
	)
	(segment
		(start 110.88624 -209.831686)
		(end 110.740698 -210.24342)
		(width 0.14732)
		(layer "In4.Cu")
		(net "UPI_CPU0_CPU1_P1P0_DN<22>")
	)
	(segment
		(start 160.55086 -165.083744)
		(end 159.96031 -165.097968)
		(width 0.14732)
		(layer "In4.Cu")
		(net "UPI_CPU0_CPU1_P1P0_DN<22>")
	)
	(segment
		(start 347.43517 -182.877968)
		(end 342.824562 -178.286156)
		(width 0.14732)
		(layer "In4.Cu")
		(net "UPI_CPU0_CPU1_P1P0_DN<22>")
	)
	(segment
		(start 159.87522 -167.701214)
		(end 159.574484 -168.01592)
		(width 0.14732)
		(layer "In4.Cu")
		(net "UPI_CPU0_CPU1_P1P0_DN<22>")
	)
	(segment
		(start 115.280694 -197.406768)
		(end 112.619028 -204.933042)
		(width 0.14732)
		(layer "In4.Cu")
		(net "UPI_CPU0_CPU1_P1P0_DN<22>")
	)
	(segment
		(start 112.390682 -205.578964)
		(end 112.24514 -205.990698)
		(width 0.14732)
		(layer "In4.Cu")
		(net "UPI_CPU0_CPU1_P1P0_DN<22>")
	)
	(segment
		(start 157.257496 -168.071038)
		(end 155.655264 -168.109138)
		(width 0.14732)
		(layer "In4.Cu")
		(net "UPI_CPU0_CPU1_P1P0_DN<22>")
	)
	(segment
		(start 110.669324 -210.81111)
		(end 110.513368 -210.885532)
		(width 0.14732)
		(layer "In4.Cu")
		(net "UPI_CPU0_CPU1_P1P0_DN<22>")
	)
	(segment
		(start 361.17784 -216.740486)
		(end 361.177078 -216.739978)
		(width 0.0889)
		(layer "In4.Cu")
		(net "UPI_CPU0_CPU1_P1P0_DN<22>")
	)
	(segment
		(start 153.586942 -168.312846)
		(end 152.94356 -165.76294)
		(width 0.14732)
		(layer "In4.Cu")
		(net "UPI_CPU0_CPU1_P1P0_DN<22>")
	)
	(segment
		(start 361.35183 -212.7758)
		(end 361.35183 -212.5345)
		(width 0.0889)
		(layer "In4.Cu")
		(net "UPI_CPU0_CPU1_P1P0_DN<22>")
	)
	(segment
		(start 197.893178 -166.932356)
		(end 194.890644 -167.310054)
		(width 0.14732)
		(layer "In4.Cu")
		(net "UPI_CPU0_CPU1_P1P0_DN<22>")
	)
	(segment
		(start 152.192482 -165.80104)
		(end 152.085802 -165.979602)
		(width 0.14732)
		(layer "In4.Cu")
		(net "UPI_CPU0_CPU1_P1P0_DN<22>")
	)
	(segment
		(start 160.700974 -165.227254)
		(end 160.55086 -165.083744)
		(width 0.14732)
		(layer "In4.Cu")
		(net "UPI_CPU0_CPU1_P1P0_DN<22>")
	)
	(segment
		(start 165.555676 -167.56634)
		(end 165.25494 -167.8813)
		(width 0.14732)
		(layer "In4.Cu")
		(net "UPI_CPU0_CPU1_P1P0_DN<22>")
	)
	(segment
		(start 361.185968 -216.745058)
		(end 361.17784 -216.740486)
		(width 0.0889)
		(layer "In4.Cu")
		(net "UPI_CPU0_CPU1_P1P0_DN<22>")
	)
	(segment
		(start 110.325916 -216.25052)
		(end 110.325916 -216.260426)
		(width 0.0889)
		(layer "In4.Cu")
		(net "UPI_CPU0_CPU1_P1P0_DN<22>")
	)
	(segment
		(start 163.47948 -167.615362)
		(end 163.451286 -166.426134)
		(width 0.14732)
		(layer "In4.Cu")
		(net "UPI_CPU0_CPU1_P1P0_DN<22>")
	)
	(segment
		(start 111.637318 -207.708754)
		(end 111.493554 -208.115154)
		(width 0.14732)
		(layer "In4.Cu")
		(net "UPI_CPU0_CPU1_P1P0_DN<22>")
	)
	(segment
		(start 110.040166 -216.74201)
		(end 110.034578 -216.745058)
		(width 0.0889)
		(layer "In4.Cu")
		(net "UPI_CPU0_CPU1_P1P0_DN<22>")
	)
	(segment
		(start 174.483776 -167.354504)
		(end 174.462694 -166.476426)
		(width 0.14732)
		(layer "In4.Cu")
		(net "UPI_CPU0_CPU1_P1P0_DN<22>")
	)
	(segment
		(start 166.284402 -167.187372)
		(end 165.693852 -167.201596)
		(width 0.14732)
		(layer "In4.Cu")
		(net "UPI_CPU0_CPU1_P1P0_DN<22>")
	)
	(segment
		(start 160.759394 -167.679624)
		(end 160.700974 -165.227254)
		(width 0.14732)
		(layer "In4.Cu")
		(net "UPI_CPU0_CPU1_P1P0_DN<22>")
	)
	(segment
		(start 176.629314 -166.277798)
		(end 176.038764 -166.292022)
		(width 0.14732)
		(layer "In4.Cu")
		(net "UPI_CPU0_CPU1_P1P0_DN<22>")
	)
	(segment
		(start 111.042196 -209.757264)
		(end 110.88624 -209.831686)
		(width 0.14732)
		(layer "In4.Cu")
		(net "UPI_CPU0_CPU1_P1P0_DN<22>")
	)
	(segment
		(start 136.46023 -175.520604)
		(end 136.396222 -175.718216)
		(width 0.14732)
		(layer "In4.Cu")
		(net "UPI_CPU0_CPU1_P1P0_DN<22>")
	)
	(segment
		(start 165.693852 -167.201596)
		(end 165.550596 -167.351964)
		(width 0.14732)
		(layer "In4.Cu")
		(net "UPI_CPU0_CPU1_P1P0_DN<22>")
	)
	(segment
		(start 161.0741 -167.980614)
		(end 160.759394 -167.679624)
		(width 0.14732)
		(layer "In4.Cu")
		(net "UPI_CPU0_CPU1_P1P0_DN<22>")
	)
	(segment
		(start 302.490124 -166.936166)
		(end 280.182828 -167.320214)
		(width 0.14732)
		(layer "In4.Cu")
		(net "UPI_CPU0_CPU1_P1P0_DN<22>")
	)
	(segment
		(start 176.038764 -166.292022)
		(end 175.895508 -166.44239)
		(width 0.14732)
		(layer "In4.Cu")
		(net "UPI_CPU0_CPU1_P1P0_DN<22>")
	)
	(segment
		(start 159.574484 -168.01592)
		(end 158.757366 -168.035732)
		(width 0.14732)
		(layer "In4.Cu")
		(net "UPI_CPU0_CPU1_P1P0_DN<22>")
	)
	(segment
		(start 110.040928 -216.741502)
		(end 110.040166 -216.74201)
		(width 0.0889)
		(layer "In4.Cu")
		(net "UPI_CPU0_CPU1_P1P0_DN<22>")
	)
	(segment
		(start 348.28988 -183.998616)
		(end 347.747844 -183.337454)
		(width 0.14732)
		(layer "In4.Cu")
		(net "UPI_CPU0_CPU1_P1P0_DN<22>")
	)
	(segment
		(start 170.849798 -166.353744)
		(end 170.706034 -166.504366)
		(width 0.14732)
		(layer "In4.Cu")
		(net "UPI_CPU0_CPU1_P1P0_DN<22>")
	)
	(segment
		(start 110.042706 -216.740486)
		(end 110.040928 -216.741502)
		(width 0.0889)
		(layer "In4.Cu")
		(net "UPI_CPU0_CPU1_P1P0_DN<22>")
	)
	(segment
		(start 194.890644 -167.310054)
		(end 189.319408 -167.310054)
		(width 0.14732)
		(layer "In4.Cu")
		(net "UPI_CPU0_CPU1_P1P0_DN<22>")
	)
	(segment
		(start 361.35183 -213.742524)
		(end 361.35183 -213.14918)
		(width 0.0889)
		(layer "In4.Cu")
		(net "UPI_CPU0_CPU1_P1P0_DN<22>")
	)
	(segment
		(start 150.482554 -169.09669)
		(end 150.25878 -169.470578)
		(width 0.14732)
		(layer "In4.Cu")
		(net "UPI_CPU0_CPU1_P1P0_DN<22>")
	)
	(segment
		(start 147.009866 -170.4721)
		(end 146.8755 -170.886374)
		(width 0.14732)
		(layer "In4.Cu")
		(net "UPI_CPU0_CPU1_P1P0_DN<22>")
	)
	(segment
		(start 112.617758 -204.936852)
		(end 112.69218 -205.092554)
		(width 0.14732)
		(layer "In4.Cu")
		(net "UPI_CPU0_CPU1_P1P0_DN<22>")
	)
	(segment
		(start 348.935802 -184.687464)
		(end 348.87535 -184.59577)
		(width 0.14732)
		(layer "In4.Cu")
		(net "UPI_CPU0_CPU1_P1P0_DN<22>")
	)
	(segment
		(start 275.966682 -167.320214)
		(end 237.459012 -157.429454)
		(width 0.14732)
		(layer "In4.Cu")
		(net "UPI_CPU0_CPU1_P1P0_DN<22>")
	)
	(segment
		(start 349.297752 -185.23712)
		(end 349.096838 -185.195718)
		(width 0.14732)
		(layer "In4.Cu")
		(net "UPI_CPU0_CPU1_P1P0_DN<22>")
	)
	(segment
		(start 360.98988 -217.064336)
		(end 361.146344 -217.335354)
		(width 0.0889)
		(layer "In4.Cu")
		(net "UPI_CPU0_CPU1_P1P0_DN<22>")
	)
	(segment
		(start 348.8944 -184.88787)
		(end 348.935802 -184.687464)
		(width 0.14732)
		(layer "In4.Cu")
		(net "UPI_CPU0_CPU1_P1P0_DN<22>")
	)
	(segment
		(start 189.319408 -167.310054)
		(end 177.11547 -167.600122)
		(width 0.14732)
		(layer "In4.Cu")
		(net "UPI_CPU0_CPU1_P1P0_DN<22>")
	)
	(segment
		(start 163.300918 -166.282624)
		(end 162.710368 -166.296848)
		(width 0.14732)
		(layer "In4.Cu")
		(net "UPI_CPU0_CPU1_P1P0_DN<22>")
	)
	(segment
		(start 171.59097 -166.48303)
		(end 171.440348 -166.33952)
		(width 0.14732)
		(layer "In4.Cu")
		(net "UPI_CPU0_CPU1_P1P0_DN<22>")
	)
	(segment
		(start 111.864902 -207.06588)
		(end 111.93907 -207.221582)
		(width 0.14732)
		(layer "In4.Cu")
		(net "UPI_CPU0_CPU1_P1P0_DN<22>")
	)
	(segment
		(start 166.43477 -167.330882)
		(end 166.284402 -167.187372)
		(width 0.14732)
		(layer "In4.Cu")
		(net "UPI_CPU0_CPU1_P1P0_DN<22>")
	)
	(segment
		(start 112.319562 -206.146146)
		(end 112.173766 -206.558388)
		(width 0.14732)
		(layer "In4.Cu")
		(net "UPI_CPU0_CPU1_P1P0_DN<22>")
	)
	(segment
		(start 110.043468 -216.739978)
		(end 110.042706 -216.740486)
		(width 0.0889)
		(layer "In4.Cu")
		(net "UPI_CPU0_CPU1_P1P0_DN<22>")
	)
	(segment
		(start 163.794186 -167.916098)
		(end 163.47948 -167.615362)
		(width 0.14732)
		(layer "In4.Cu")
		(net "UPI_CPU0_CPU1_P1P0_DN<22>")
	)
	(segment
		(start 177.11547 -167.600122)
		(end 176.800764 -167.299386)
		(width 0.14732)
		(layer "In4.Cu")
		(net "UPI_CPU0_CPU1_P1P0_DN<22>")
	)
	(arc
		(start 110.746032 -215.16086)
		(mid 110.782807 -215.235419)
		(end 110.795562 -215.317578)
		(width 0.0889)
		(layer "In4.Cu")
		(net "UPI_CPU0_CPU1_P1P0_DN<22>")
	)
	(arc
		(start 361.36453 -217.064336)
		(mid 361.316851 -216.881436)
		(end 361.185968 -216.745058)
		(width 0.0889)
		(layer "In4.Cu")
		(net "UPI_CPU0_CPU1_P1P0_DN<22>")
	)
	(arc
		(start 110.115096 -218.319096)
		(mid 110.106774 -218.32565)
		(end 110.098332 -218.33205)
		(width 0.0889)
		(layer "In4.Cu")
		(net "UPI_CPU0_CPU1_P1P0_DN<22>")
	)
	(arc
		(start 110.325916 -216.260426)
		(mid 110.247805 -216.537375)
		(end 110.043468 -216.739978)
		(width 0.0889)
		(layer "In4.Cu")
		(net "UPI_CPU0_CPU1_P1P0_DN<22>")
	)
	(arc
		(start 110.043468 -217.388694)
		(mid 110.245754 -217.587675)
		(end 110.325916 -217.859864)
		(width 0.0889)
		(layer "In4.Cu")
		(net "UPI_CPU0_CPU1_P1P0_DN<22>")
	)
	(arc
		(start 110.325916 -214.695278)
		(mid 110.3272 -214.707899)
		(end 110.33125 -214.719916)
		(width 0.0889)
		(layer "In4.Cu")
		(net "UPI_CPU0_CPU1_P1P0_DN<22>")
	)
	(arc
		(start 110.504478 -215.931242)
		(mid 110.373564 -216.067602)
		(end 110.325916 -216.25052)
		(width 0.0889)
		(layer "In4.Cu")
		(net "UPI_CPU0_CPU1_P1P0_DN<22>")
	)
	(arc
		(start 361.82173 -214.546434)
		(mid 361.774051 -214.363534)
		(end 361.643168 -214.227156)
		(width 0.0889)
		(layer "In4.Cu")
		(net "UPI_CPU0_CPU1_P1P0_DN<22>")
	)
	(arc
		(start 361.642914 -214.907622)
		(mid 361.748129 -214.826036)
		(end 361.82173 -214.71509)
		(width 0.0889)
		(layer "In4.Cu")
		(net "UPI_CPU0_CPU1_P1P0_DN<22>")
	)
	(arc
		(start 361.36453 -215.229694)
		(mid 361.474271 -215.043194)
		(end 361.642914 -214.907622)
		(width 0.0889)
		(layer "In4.Cu")
		(net "UPI_CPU0_CPU1_P1P0_DN<22>")
	)
	(arc
		(start 110.034578 -216.745058)
		(mid 109.855981 -217.064336)
		(end 110.034578 -217.383614)
		(width 0.0889)
		(layer "In4.Cu")
		(net "UPI_CPU0_CPU1_P1P0_DN<22>")
	)
	(arc
		(start 361.634278 -214.222076)
		(mid 361.429943 -214.019471)
		(end 361.35183 -213.742524)
		(width 0.0889)
		(layer "In4.Cu")
		(net "UPI_CPU0_CPU1_P1P0_DN<22>")
	)
	(arc
		(start 110.33125 -214.719916)
		(mid 110.395274 -214.817849)
		(end 110.484412 -214.893652)
		(width 0.0889)
		(layer "In4.Cu")
		(net "UPI_CPU0_CPU1_P1P0_DN<22>")
	)
	(arc
		(start 361.177078 -216.739978)
		(mid 360.972743 -216.537373)
		(end 360.89463 -216.260426)
		(width 0.0889)
		(layer "In4.Cu")
		(net "UPI_CPU0_CPU1_P1P0_DN<22>")
	)
	(arc
		(start 361.224576 -217.356182)
		(mid 361.327721 -217.226157)
		(end 361.36453 -217.064336)
		(width 0.0889)
		(layer "In4.Cu")
		(net "UPI_CPU0_CPU1_P1P0_DN<22>")
	)
	(arc
		(start 110.325916 -217.888312)
		(mid 110.268443 -218.127159)
		(end 110.115096 -218.319096)
		(width 0.0889)
		(layer "In4.Cu")
		(net "UPI_CPU0_CPU1_P1P0_DN<22>")
	)
	(arc
		(start 360.89463 -216.240614)
		(mid 360.972741 -215.963665)
		(end 361.177078 -215.761062)
		(width 0.0889)
		(layer "In4.Cu")
		(net "UPI_CPU0_CPU1_P1P0_DN<22>")
	)
	(arc
		(start 110.795562 -215.452198)
		(mid 110.716192 -215.725932)
		(end 110.513368 -215.926162)
		(width 0.0889)
		(layer "In4.Cu")
		(net "UPI_CPU0_CPU1_P1P0_DN<22>")
	)
	(arc
		(start 361.185968 -215.755982)
		(mid 361.316882 -215.619622)
		(end 361.36453 -215.436704)
		(width 0.0889)
		(layer "In4.Cu")
		(net "UPI_CPU0_CPU1_P1P0_DN<22>")
	)
	(arc
		(start 110.555786 -214.946484)
		(mid 110.656901 -215.048354)
		(end 110.746032 -215.16086)
		(width 0.0889)
		(layer "In4.Cu")
		(net "UPI_CPU0_CPU1_P1P0_DN<22>")
	)
	(arc
		(start 110.484412 -214.893652)
		(mid 110.521295 -214.918452)
		(end 110.555786 -214.946484)
		(width 0.0889)
		(layer "In4.Cu")
		(net "UPI_CPU0_CPU1_P1P0_DN<22>")
	)
	(segment
		(start 109.290866 -217.600276)
		(end 109.290866 -217.06459)
		(width 0.13208)
		(layer "F.Cu")
		(net "UPI_CPU0_CPU1_P1P0_DN<21>")
	)
	(segment
		(start 361.929934 -219.228162)
		(end 361.929934 -218.692222)
		(width 0.13208)
		(layer "F.Cu")
		(net "UPI_CPU0_CPU1_P1P0_DN<21>")
	)
	(segment
		(start 109.290866 -217.06459)
		(end 109.290612 -217.064336)
		(width 0.13208)
		(layer "F.Cu")
		(net "UPI_CPU0_CPU1_P1P0_DN<21>")
	)
	(segment
		(start 183.627014 -166.609776)
		(end 182.809134 -166.630096)
		(width 0.14732)
		(layer "In4.Cu")
		(net "UPI_CPU0_CPU1_P1P0_DN<21>")
	)
	(segment
		(start 175.371252 -165.360096)
		(end 174.554388 -165.380924)
		(width 0.14732)
		(layer "In4.Cu")
		(net "UPI_CPU0_CPU1_P1P0_DN<21>")
	)
	(segment
		(start 137.11936 -174.197518)
		(end 136.805416 -174.390304)
		(width 0.14732)
		(layer "In4.Cu")
		(net "UPI_CPU0_CPU1_P1P0_DN<21>")
	)
	(segment
		(start 173.054518 -165.417754)
		(end 170.764708 -165.474904)
		(width 0.14732)
		(layer "In4.Cu")
		(net "UPI_CPU0_CPU1_P1P0_DN<21>")
	)
	(segment
		(start 109.17174 -212.02015)
		(end 109.17174 -212.042248)
		(width 0.0889)
		(layer "In4.Cu")
		(net "UPI_CPU0_CPU1_P1P0_DN<21>")
	)
	(segment
		(start 110.959646 -206.766668)
		(end 111.034068 -206.92237)
		(width 0.14732)
		(layer "In4.Cu")
		(net "UPI_CPU0_CPU1_P1P0_DN<21>")
	)
	(segment
		(start 139.704064 -172.612812)
		(end 139.94765 -173.00956)
		(width 0.14732)
		(layer "In4.Cu")
		(net "UPI_CPU0_CPU1_P1P0_DN<21>")
	)
	(segment
		(start 177.685192 -165.303454)
		(end 176.871122 -165.323266)
		(width 0.14732)
		(layer "In4.Cu")
		(net "UPI_CPU0_CPU1_P1P0_DN<21>")
	)
	(segment
		(start 110.143036 -209.44205)
		(end 109.98708 -209.516472)
		(width 0.14732)
		(layer "In4.Cu")
		(net "UPI_CPU0_CPU1_P1P0_DN<21>")
	)
	(segment
		(start 180.17744 -166.38778)
		(end 180.152548 -165.389306)
		(width 0.14732)
		(layer "In4.Cu")
		(net "UPI_CPU0_CPU1_P1P0_DN<21>")
	)
	(segment
		(start 362.262674 -211.788248)
		(end 362.262674 -211.76615)
		(width 0.0889)
		(layer "In4.Cu")
		(net "UPI_CPU0_CPU1_P1P0_DN<21>")
	)
	(segment
		(start 110.587028 -207.820514)
		(end 110.66145 -207.976216)
		(width 0.14732)
		(layer "In4.Cu")
		(net "UPI_CPU0_CPU1_P1P0_DN<21>")
	)
	(segment
		(start 109.094524 -215.755982)
		(end 109.10951 -215.764618)
		(width 0.0889)
		(layer "In4.Cu")
		(net "UPI_CPU0_CPU1_P1P0_DN<21>")
	)
	(segment
		(start 181.585616 -165.353746)
		(end 181.610508 -166.35222)
		(width 0.14732)
		(layer "In4.Cu")
		(net "UPI_CPU0_CPU1_P1P0_DN<21>")
	)
	(segment
		(start 113.654332 -199.146922)
		(end 113.464086 -199.685402)
		(width 0.14732)
		(layer "In4.Cu")
		(net "UPI_CPU0_CPU1_P1P0_DN<21>")
	)
	(segment
		(start 176.555908 -165.022276)
		(end 176.500028 -162.770312)
		(width 0.14732)
		(layer "In4.Cu")
		(net "UPI_CPU0_CPU1_P1P0_DN<21>")
	)
	(segment
		(start 109.129576 -212.58784)
		(end 109.228636 -212.6869)
		(width 0.0889)
		(layer "In4.Cu")
		(net "UPI_CPU0_CPU1_P1P0_DN<21>")
	)
	(segment
		(start 362.117132 -216.739978)
		(end 362.10494 -216.732866)
		(width 0.0889)
		(layer "In4.Cu")
		(net "UPI_CPU0_CPU1_P1P0_DN<21>")
	)
	(segment
		(start 139.149328 -173.860968)
		(end 138.726164 -173.759876)
		(width 0.14732)
		(layer "In4.Cu")
		(net "UPI_CPU0_CPU1_P1P0_DN<21>")
	)
	(segment
		(start 175.615854 -162.79241)
		(end 175.67148 -165.044882)
		(width 0.14732)
		(layer "In4.Cu")
		(net "UPI_CPU0_CPU1_P1P0_DN<21>")
	)
	(segment
		(start 173.29912 -162.850068)
		(end 173.354746 -165.10254)
		(width 0.14732)
		(layer "In4.Cu")
		(net "UPI_CPU0_CPU1_P1P0_DN<21>")
	)
	(segment
		(start 165.331648 -165.904418)
		(end 160.949386 -164.241226)
		(width 0.14732)
		(layer "In4.Cu")
		(net "UPI_CPU0_CPU1_P1P0_DN<21>")
	)
	(segment
		(start 194.87388 -166.474902)
		(end 189.148466 -166.474902)
		(width 0.14732)
		(layer "In4.Cu")
		(net "UPI_CPU0_CPU1_P1P0_DN<21>")
	)
	(segment
		(start 362.77423 -214.63127)
		(end 362.77423 -214.613998)
		(width 0.0889)
		(layer "In4.Cu")
		(net "UPI_CPU0_CPU1_P1P0_DN<21>")
	)
	(segment
		(start 139.94765 -173.00956)
		(end 139.846558 -173.432724)
		(width 0.14732)
		(layer "In4.Cu")
		(net "UPI_CPU0_CPU1_P1P0_DN<21>")
	)
	(segment
		(start 109.171486 -211.882228)
		(end 109.17174 -211.882482)
		(width 0.14732)
		(layer "In4.Cu")
		(net "UPI_CPU0_CPU1_P1P0_DN<21>")
	)
	(segment
		(start 134.169912 -176.045876)
		(end 134.16407 -176.2506)
		(width 0.14732)
		(layer "In4.Cu")
		(net "UPI_CPU0_CPU1_P1P0_DN<21>")
	)
	(segment
		(start 362.086398 -218.421204)
		(end 362.062268 -218.33205)
		(width 0.0889)
		(layer "In4.Cu")
		(net "UPI_CPU0_CPU1_P1P0_DN<21>")
	)
	(segment
		(start 113.392712 -200.253092)
		(end 113.236756 -200.327514)
		(width 0.14732)
		(layer "In4.Cu")
		(net "UPI_CPU0_CPU1_P1P0_DN<21>")
	)
	(segment
		(start 142.432278 -170.93692)
		(end 142.22984 -170.888406)
		(width 0.14732)
		(layer "In4.Cu")
		(net "UPI_CPU0_CPU1_P1P0_DN<21>")
	)
	(segment
		(start 140.701014 -172.546772)
		(end 140.457428 -172.150024)
		(width 0.14732)
		(layer "In4.Cu")
		(net "UPI_CPU0_CPU1_P1P0_DN<21>")
	)
	(segment
		(start 111.034068 -206.92237)
		(end 110.888526 -207.334358)
		(width 0.14732)
		(layer "In4.Cu")
		(net "UPI_CPU0_CPU1_P1P0_DN<21>")
	)
	(segment
		(start 276.073616 -166.475918)
		(end 256.786126 -161.521902)
		(width 0.14732)
		(layer "In4.Cu")
		(net "UPI_CPU0_CPU1_P1P0_DN<21>")
	)
	(segment
		(start 138.726164 -173.759876)
		(end 138.482578 -173.363128)
		(width 0.14732)
		(layer "In4.Cu")
		(net "UPI_CPU0_CPU1_P1P0_DN<21>")
	)
	(segment
		(start 113.810034 -199.0725)
		(end 113.654332 -199.146922)
		(width 0.14732)
		(layer "In4.Cu")
		(net "UPI_CPU0_CPU1_P1P0_DN<21>")
	)
	(segment
		(start 141.124178 -172.647864)
		(end 140.701014 -172.546772)
		(width 0.14732)
		(layer "In4.Cu")
		(net "UPI_CPU0_CPU1_P1P0_DN<21>")
	)
	(segment
		(start 114.311684 -197.287896)
		(end 113.881408 -198.50481)
		(width 0.14732)
		(layer "In4.Cu")
		(net "UPI_CPU0_CPU1_P1P0_DN<21>")
	)
	(segment
		(start 143.796258 -171.006516)
		(end 143.099028 -171.43476)
		(width 0.14732)
		(layer "In4.Cu")
		(net "UPI_CPU0_CPU1_P1P0_DN<21>")
	)
	(segment
		(start 110.888526 -207.334358)
		(end 110.73257 -207.40878)
		(width 0.14732)
		(layer "In4.Cu")
		(net "UPI_CPU0_CPU1_P1P0_DN<21>")
	)
	(segment
		(start 110.359952 -208.462626)
		(end 110.21441 -208.87436)
		(width 0.14732)
		(layer "In4.Cu")
		(net "UPI_CPU0_CPU1_P1P0_DN<21>")
	)
	(segment
		(start 170.764708 -165.474904)
		(end 169.196766 -166.080948)
		(width 0.14732)
		(layer "In4.Cu")
		(net "UPI_CPU0_CPU1_P1P0_DN<21>")
	)
	(segment
		(start 351.077784 -181.473602)
		(end 350.682814 -181.417468)
		(width 0.14732)
		(layer "In4.Cu")
		(net "UPI_CPU0_CPU1_P1P0_DN<21>")
	)
	(segment
		(start 362.26242 -205.135734)
		(end 357.030274 -192.50406)
		(width 0.14732)
		(layer "In4.Cu")
		(net "UPI_CPU0_CPU1_P1P0_DN<21>")
	)
	(segment
		(start 109.385608 -214.249508)
		(end 109.385608 -214.57666)
		(width 0.0889)
		(layer "In4.Cu")
		(net "UPI_CPU0_CPU1_P1P0_DN<21>")
	)
	(segment
		(start 176.871122 -165.323266)
		(end 176.555908 -165.022276)
		(width 0.14732)
		(layer "In4.Cu")
		(net "UPI_CPU0_CPU1_P1P0_DN<21>")
	)
	(segment
		(start 155.999688 -164.470334)
		(end 156.011372 -165.154864)
		(width 0.14732)
		(layer "In4.Cu")
		(net "UPI_CPU0_CPU1_P1P0_DN<21>")
	)
	(segment
		(start 177.835814 -165.446964)
		(end 177.685192 -165.303454)
		(width 0.14732)
		(layer "In4.Cu")
		(net "UPI_CPU0_CPU1_P1P0_DN<21>")
	)
	(segment
		(start 109.171486 -211.822284)
		(end 109.171486 -211.882228)
		(width 0.14732)
		(layer "In4.Cu")
		(net "UPI_CPU0_CPU1_P1P0_DN<21>")
	)
	(segment
		(start 354.365052 -187.5028)
		(end 352.672396 -184.956704)
		(width 0.14732)
		(layer "In4.Cu")
		(net "UPI_CPU0_CPU1_P1P0_DN<21>")
	)
	(segment
		(start 183.90235 -165.296088)
		(end 183.927242 -166.294562)
		(width 0.14732)
		(layer "In4.Cu")
		(net "UPI_CPU0_CPU1_P1P0_DN<21>")
	)
	(segment
		(start 156.144468 -164.320982)
		(end 155.999688 -164.470334)
		(width 0.14732)
		(layer "In4.Cu")
		(net "UPI_CPU0_CPU1_P1P0_DN<21>")
	)
	(segment
		(start 182.494174 -166.330122)
		(end 182.469282 -165.331648)
		(width 0.14732)
		(layer "In4.Cu")
		(net "UPI_CPU0_CPU1_P1P0_DN<21>")
	)
	(segment
		(start 143.099028 -171.43476)
		(end 142.675864 -171.333668)
		(width 0.14732)
		(layer "In4.Cu")
		(net "UPI_CPU0_CPU1_P1P0_DN<21>")
	)
	(segment
		(start 110.515908 -208.388204)
		(end 110.359952 -208.462626)
		(width 0.14732)
		(layer "In4.Cu")
		(net "UPI_CPU0_CPU1_P1P0_DN<21>")
	)
	(segment
		(start 320.279776 -167.995346)
		(end 314.391294 -166.334186)
		(width 0.14732)
		(layer "In4.Cu")
		(net "UPI_CPU0_CPU1_P1P0_DN<21>")
	)
	(segment
		(start 136.60628 -174.342806)
		(end 134.7978 -175.453294)
		(width 0.14732)
		(layer "In4.Cu")
		(net "UPI_CPU0_CPU1_P1P0_DN<21>")
	)
	(segment
		(start 181.729126 -165.203124)
		(end 181.585616 -165.353746)
		(width 0.14732)
		(layer "In4.Cu")
		(net "UPI_CPU0_CPU1_P1P0_DN<21>")
	)
	(segment
		(start 181.31028 -166.667434)
		(end 180.4924 -166.687754)
		(width 0.14732)
		(layer "In4.Cu")
		(net "UPI_CPU0_CPU1_P1P0_DN<21>")
	)
	(segment
		(start 362.304584 -211.830158)
		(end 362.262674 -211.788248)
		(width 0.0889)
		(layer "In4.Cu")
		(net "UPI_CPU0_CPU1_P1P0_DN<21>")
	)
	(segment
		(start 141.678914 -171.399708)
		(end 141.9225 -171.796456)
		(width 0.14732)
		(layer "In4.Cu")
		(net "UPI_CPU0_CPU1_P1P0_DN<21>")
	)
	(segment
		(start 351.739708 -183.553608)
		(end 351.512632 -183.211978)
		(width 0.14732)
		(layer "In4.Cu")
		(net "UPI_CPU0_CPU1_P1P0_DN<21>")
	)
	(segment
		(start 139.846558 -173.432724)
		(end 139.149328 -173.860968)
		(width 0.14732)
		(layer "In4.Cu")
		(net "UPI_CPU0_CPU1_P1P0_DN<21>")
	)
	(segment
		(start 142.22984 -170.888406)
		(end 141.727428 -171.19727)
		(width 0.14732)
		(layer "In4.Cu")
		(net "UPI_CPU0_CPU1_P1P0_DN<21>")
	)
	(segment
		(start 350.481392 -184.539636)
		(end 351.70491 -183.726074)
		(width 0.14732)
		(layer "In4.Cu")
		(net "UPI_CPU0_CPU1_P1P0_DN<21>")
	)
	(segment
		(start 133.895846 -176.503838)
		(end 133.691122 -176.497742)
		(width 0.14732)
		(layer "In4.Cu")
		(net "UPI_CPU0_CPU1_P1P0_DN<21>")
	)
	(segment
		(start 351.512632 -183.211978)
		(end 351.512632 -181.90845)
		(width 0.14732)
		(layer "In4.Cu")
		(net "UPI_CPU0_CPU1_P1P0_DN<21>")
	)
	(segment
		(start 113.464086 -199.685402)
		(end 113.538254 -199.841104)
		(width 0.14732)
		(layer "In4.Cu")
		(net "UPI_CPU0_CPU1_P1P0_DN<21>")
	)
	(segment
		(start 362.26242 -211.328)
		(end 362.26242 -205.135734)
		(width 0.14732)
		(layer "In4.Cu")
		(net "UPI_CPU0_CPU1_P1P0_DN<21>")
	)
	(segment
		(start 347.608652 -181.568598)
		(end 343.40292 -177.650648)
		(width 0.14732)
		(layer "In4.Cu")
		(net "UPI_CPU0_CPU1_P1P0_DN<21>")
	)
	(segment
		(start 109.129576 -213.993476)
		(end 109.385608 -214.249508)
		(width 0.0889)
		(layer "In4.Cu")
		(net "UPI_CPU0_CPU1_P1P0_DN<21>")
	)
	(segment
		(start 109.915706 -210.083908)
		(end 109.770164 -210.495896)
		(width 0.14732)
		(layer "In4.Cu")
		(net "UPI_CPU0_CPU1_P1P0_DN<21>")
	)
	(segment
		(start 180.152548 -165.389306)
		(end 180.001926 -165.245796)
		(width 0.14732)
		(layer "In4.Cu")
		(net "UPI_CPU0_CPU1_P1P0_DN<21>")
	)
	(segment
		(start 182.809134 -166.630096)
		(end 182.494174 -166.330122)
		(width 0.14732)
		(layer "In4.Cu")
		(net "UPI_CPU0_CPU1_P1P0_DN<21>")
	)
	(segment
		(start 109.104176 -216.73947)
		(end 109.103414 -216.739978)
		(width 0.0889)
		(layer "In4.Cu")
		(net "UPI_CPU0_CPU1_P1P0_DN<21>")
	)
	(segment
		(start 361.83443 -216.25052)
		(end 361.83443 -216.2429)
		(width 0.0889)
		(layer "In4.Cu")
		(net "UPI_CPU0_CPU1_P1P0_DN<21>")
	)
	(segment
		(start 133.691122 -176.497742)
		(end 122.708924 -186.864498)
		(width 0.14732)
		(layer "In4.Cu")
		(net "UPI_CPU0_CPU1_P1P0_DN<21>")
	)
	(segment
		(start 154.566366 -164.494464)
		(end 154.417014 -164.349684)
		(width 0.14732)
		(layer "In4.Cu")
		(net "UPI_CPU0_CPU1_P1P0_DN<21>")
	)
	(segment
		(start 109.228636 -213.43874)
		(end 109.129576 -213.5378)
		(width 0.0889)
		(layer "In4.Cu")
		(net "UPI_CPU0_CPU1_P1P0_DN<21>")
	)
	(segment
		(start 178.993546 -166.725092)
		(end 178.175666 -166.745412)
		(width 0.14732)
		(layer "In4.Cu")
		(net "UPI_CPU0_CPU1_P1P0_DN<21>")
	)
	(segment
		(start 153.557986 -164.364416)
		(end 152.219914 -164.754052)
		(width 0.14732)
		(layer "In4.Cu")
		(net "UPI_CPU0_CPU1_P1P0_DN<21>")
	)
	(segment
		(start 154.57805 -165.178994)
		(end 154.566366 -164.494464)
		(width 0.14732)
		(layer "In4.Cu")
		(net "UPI_CPU0_CPU1_P1P0_DN<21>")
	)
	(segment
		(start 174.032672 -162.684968)
		(end 173.442122 -162.699446)
		(width 0.14732)
		(layer "In4.Cu")
		(net "UPI_CPU0_CPU1_P1P0_DN<21>")
	)
	(segment
		(start 113.881408 -198.50481)
		(end 113.95583 -198.660512)
		(width 0.14732)
		(layer "In4.Cu")
		(net "UPI_CPU0_CPU1_P1P0_DN<21>")
	)
	(segment
		(start 110.587282 -207.819752)
		(end 110.587028 -207.820514)
		(width 0.14732)
		(layer "In4.Cu")
		(net "UPI_CPU0_CPU1_P1P0_DN<21>")
	)
	(segment
		(start 362.30433 -215.445086)
		(end 362.30433 -215.43645)
		(width 0.0889)
		(layer "In4.Cu")
		(net "UPI_CPU0_CPU1_P1P0_DN<21>")
	)
	(segment
		(start 352.672396 -184.956704)
		(end 352.49993 -184.921906)
		(width 0.14732)
		(layer "In4.Cu")
		(net "UPI_CPU0_CPU1_P1P0_DN<21>")
	)
	(segment
		(start 143.702278 -169.984166)
		(end 143.653764 -170.186604)
		(width 0.14732)
		(layer "In4.Cu")
		(net "UPI_CPU0_CPU1_P1P0_DN<21>")
	)
	(segment
		(start 237.565946 -156.585158)
		(end 234.645708 -156.585158)
		(width 0.14732)
		(layer "In4.Cu")
		(net "UPI_CPU0_CPU1_P1P0_DN<21>")
	)
	(segment
		(start 302.491648 -166.091362)
		(end 280.175208 -166.475918)
		(width 0.14732)
		(layer "In4.Cu")
		(net "UPI_CPU0_CPU1_P1P0_DN<21>")
	)
	(segment
		(start 139.752578 -172.410374)
		(end 139.704064 -172.612812)
		(width 0.14732)
		(layer "In4.Cu")
		(net "UPI_CPU0_CPU1_P1P0_DN<21>")
	)
	(segment
		(start 152.219914 -164.754052)
		(end 143.702278 -169.984166)
		(width 0.14732)
		(layer "In4.Cu")
		(net "UPI_CPU0_CPU1_P1P0_DN<21>")
	)
	(segment
		(start 109.614208 -210.570318)
		(end 109.171486 -211.822284)
		(width 0.14732)
		(layer "In4.Cu")
		(net "UPI_CPU0_CPU1_P1P0_DN<21>")
	)
	(segment
		(start 109.98708 -209.516472)
		(end 109.841538 -209.928206)
		(width 0.14732)
		(layer "In4.Cu")
		(net "UPI_CPU0_CPU1_P1P0_DN<21>")
	)
	(segment
		(start 168.32199 -166.31031)
		(end 167.129714 -166.27094)
		(width 0.14732)
		(layer "In4.Cu")
		(net "UPI_CPU0_CPU1_P1P0_DN<21>")
	)
	(segment
		(start 167.129714 -166.27094)
		(end 165.331648 -165.904418)
		(width 0.14732)
		(layer "In4.Cu")
		(net "UPI_CPU0_CPU1_P1P0_DN<21>")
	)
	(segment
		(start 175.758856 -162.641788)
		(end 175.615854 -162.79241)
		(width 0.14732)
		(layer "In4.Cu")
		(net "UPI_CPU0_CPU1_P1P0_DN<21>")
	)
	(segment
		(start 109.10951 -216.736422)
		(end 109.104176 -216.73947)
		(width 0.0889)
		(layer "In4.Cu")
		(net "UPI_CPU0_CPU1_P1P0_DN<21>")
	)
	(segment
		(start 109.129576 -213.16442)
		(end 109.228636 -213.26348)
		(width 0.0889)
		(layer "In4.Cu")
		(net "UPI_CPU0_CPU1_P1P0_DN<21>")
	)
	(segment
		(start 352.49993 -184.921906)
		(end 351.276412 -185.735468)
		(width 0.14732)
		(layer "In4.Cu")
		(net "UPI_CPU0_CPU1_P1P0_DN<21>")
	)
	(segment
		(start 109.129576 -213.5378)
		(end 109.129576 -213.993476)
		(width 0.0889)
		(layer "In4.Cu")
		(net "UPI_CPU0_CPU1_P1P0_DN<21>")
	)
	(segment
		(start 280.175208 -166.475918)
		(end 276.073616 -166.475918)
		(width 0.14732)
		(layer "In4.Cu")
		(net "UPI_CPU0_CPU1_P1P0_DN<21>")
	)
	(segment
		(start 142.675864 -171.333668)
		(end 142.432278 -170.93692)
		(width 0.14732)
		(layer "In4.Cu")
		(net "UPI_CPU0_CPU1_P1P0_DN<21>")
	)
	(segment
		(start 343.40292 -177.650648)
		(end 341.03818 -175.971708)
		(width 0.14732)
		(layer "In4.Cu")
		(net "UPI_CPU0_CPU1_P1P0_DN<21>")
	)
	(segment
		(start 197.630542 -166.127938)
		(end 194.87388 -166.474902)
		(width 0.14732)
		(layer "In4.Cu")
		(net "UPI_CPU0_CPU1_P1P0_DN<21>")
	)
	(segment
		(start 362.30433 -215.43645)
		(end 362.304584 -215.422226)
		(width 0.0889)
		(layer "In4.Cu")
		(net "UPI_CPU0_CPU1_P1P0_DN<21>")
	)
	(segment
		(start 154.890724 -165.481508)
		(end 154.57805 -165.178994)
		(width 0.14732)
		(layer "In4.Cu")
		(net "UPI_CPU0_CPU1_P1P0_DN<21>")
	)
	(segment
		(start 178.175666 -166.745412)
		(end 177.860706 -166.445438)
		(width 0.14732)
		(layer "In4.Cu")
		(net "UPI_CPU0_CPU1_P1P0_DN<21>")
	)
	(segment
		(start 355.966776 -191.42075)
		(end 354.365052 -187.5028)
		(width 0.14732)
		(layer "In4.Cu")
		(net "UPI_CPU0_CPU1_P1P0_DN<21>")
	)
	(segment
		(start 174.239174 -165.080442)
		(end 174.183294 -162.82797)
		(width 0.14732)
		(layer "In4.Cu")
		(net "UPI_CPU0_CPU1_P1P0_DN<21>")
	)
	(segment
		(start 109.05617 -217.356182)
		(end 109.134148 -217.335354)
		(width 0.0889)
		(layer "In4.Cu")
		(net "UPI_CPU0_CPU1_P1P0_DN<21>")
	)
	(segment
		(start 155.708858 -165.467538)
		(end 154.890724 -165.481508)
		(width 0.14732)
		(layer "In4.Cu")
		(net "UPI_CPU0_CPU1_P1P0_DN<21>")
	)
	(segment
		(start 182.469282 -165.331648)
		(end 182.31866 -165.188138)
		(width 0.14732)
		(layer "In4.Cu")
		(net "UPI_CPU0_CPU1_P1P0_DN<21>")
	)
	(segment
		(start 314.391294 -166.334186)
		(end 302.491648 -166.091362)
		(width 0.14732)
		(layer "In4.Cu")
		(net "UPI_CPU0_CPU1_P1P0_DN<21>")
	)
	(segment
		(start 122.708924 -186.864498)
		(end 114.311684 -197.287896)
		(width 0.14732)
		(layer "In4.Cu")
		(net "UPI_CPU0_CPU1_P1P0_DN<21>")
	)
	(segment
		(start 143.653764 -170.186604)
		(end 143.89735 -170.583352)
		(width 0.14732)
		(layer "In4.Cu")
		(net "UPI_CPU0_CPU1_P1P0_DN<21>")
	)
	(segment
		(start 141.821408 -172.21962)
		(end 141.124178 -172.647864)
		(width 0.14732)
		(layer "In4.Cu")
		(net "UPI_CPU0_CPU1_P1P0_DN<21>")
	)
	(segment
		(start 138.482578 -173.363128)
		(end 138.28014 -173.314614)
		(width 0.14732)
		(layer "In4.Cu")
		(net "UPI_CPU0_CPU1_P1P0_DN<21>")
	)
	(segment
		(start 113.95583 -198.660512)
		(end 113.810034 -199.0725)
		(width 0.14732)
		(layer "In4.Cu")
		(net "UPI_CPU0_CPU1_P1P0_DN<21>")
	)
	(segment
		(start 109.841538 -209.928206)
		(end 109.915706 -210.083908)
		(width 0.14732)
		(layer "In4.Cu")
		(net "UPI_CPU0_CPU1_P1P0_DN<21>")
	)
	(segment
		(start 109.134148 -217.335354)
		(end 109.290612 -217.064336)
		(width 0.0889)
		(layer "In4.Cu")
		(net "UPI_CPU0_CPU1_P1P0_DN<21>")
	)
	(segment
		(start 109.17174 -212.042248)
		(end 109.129576 -212.084412)
		(width 0.0889)
		(layer "In4.Cu")
		(net "UPI_CPU0_CPU1_P1P0_DN<21>")
	)
	(segment
		(start 181.610508 -166.35222)
		(end 181.31028 -166.667434)
		(width 0.14732)
		(layer "In4.Cu")
		(net "UPI_CPU0_CPU1_P1P0_DN<21>")
	)
	(segment
		(start 109.129576 -212.084412)
		(end 109.129576 -212.58784)
		(width 0.0889)
		(layer "In4.Cu")
		(net "UPI_CPU0_CPU1_P1P0_DN<21>")
	)
	(segment
		(start 362.30433 -217.072972)
		(end 362.30433 -217.0557)
		(width 0.0889)
		(layer "In4.Cu")
		(net "UPI_CPU0_CPU1_P1P0_DN<21>")
	)
	(segment
		(start 184.04586 -165.145466)
		(end 183.90235 -165.296088)
		(width 0.14732)
		(layer "In4.Cu")
		(net "UPI_CPU0_CPU1_P1P0_DN<21>")
	)
	(segment
		(start 177.860706 -166.445438)
		(end 177.835814 -165.446964)
		(width 0.14732)
		(layer "In4.Cu")
		(net "UPI_CPU0_CPU1_P1P0_DN<21>")
	)
	(segment
		(start 350.881442 -185.655966)
		(end 350.40189 -184.934606)
		(width 0.14732)
		(layer "In4.Cu")
		(net "UPI_CPU0_CPU1_P1P0_DN<21>")
	)
	(segment
		(start 109.138466 -215.092026)
		(end 109.094524 -215.117426)
		(width 0.0889)
		(layer "In4.Cu")
		(net "UPI_CPU0_CPU1_P1P0_DN<21>")
	)
	(segment
		(start 136.805416 -174.390304)
		(end 136.60628 -174.342806)
		(width 0.14732)
		(layer "In4.Cu")
		(net "UPI_CPU0_CPU1_P1P0_DN<21>")
	)
	(segment
		(start 351.70491 -183.726074)
		(end 351.739708 -183.553608)
		(width 0.14732)
		(layer "In4.Cu")
		(net "UPI_CPU0_CPU1_P1P0_DN<21>")
	)
	(segment
		(start 361.834684 -217.888312)
		(end 361.834684 -217.859864)
		(width 0.0889)
		(layer "In4.Cu")
		(net "UPI_CPU0_CPU1_P1P0_DN<21>")
	)
	(segment
		(start 351.512632 -181.90845)
		(end 351.077784 -181.473602)
		(width 0.14732)
		(layer "In4.Cu")
		(net "UPI_CPU0_CPU1_P1P0_DN<21>")
	)
	(segment
		(start 351.276412 -185.735468)
		(end 350.881442 -185.655966)
		(width 0.14732)
		(layer "In4.Cu")
		(net "UPI_CPU0_CPU1_P1P0_DN<21>")
	)
	(segment
		(start 175.67148 -165.044882)
		(end 175.371252 -165.360096)
		(width 0.14732)
		(layer "In4.Cu")
		(net "UPI_CPU0_CPU1_P1P0_DN<21>")
	)
	(segment
		(start 362.304584 -213.827106)
		(end 362.304584 -211.830158)
		(width 0.0889)
		(layer "In4.Cu")
		(net "UPI_CPU0_CPU1_P1P0_DN<21>")
	)
	(segment
		(start 234.645708 -156.585158)
		(end 197.630542 -166.127938)
		(width 0.14732)
		(layer "In4.Cu")
		(net "UPI_CPU0_CPU1_P1P0_DN<21>")
	)
	(segment
		(start 183.927242 -166.294562)
		(end 183.627014 -166.609776)
		(width 0.14732)
		(layer "In4.Cu")
		(net "UPI_CPU0_CPU1_P1P0_DN<21>")
	)
	(segment
		(start 109.17174 -211.882482)
		(end 109.17174 -212.02015)
		(width 0.14732)
		(layer "In4.Cu")
		(net "UPI_CPU0_CPU1_P1P0_DN<21>")
	)
	(segment
		(start 140.457428 -172.150024)
		(end 140.25499 -172.10151)
		(width 0.14732)
		(layer "In4.Cu")
		(net "UPI_CPU0_CPU1_P1P0_DN<21>")
	)
	(segment
		(start 138.28014 -173.314614)
		(end 137.167112 -173.998128)
		(width 0.14732)
		(layer "In4.Cu")
		(net "UPI_CPU0_CPU1_P1P0_DN<21>")
	)
	(segment
		(start 110.288578 -209.030062)
		(end 110.143036 -209.44205)
		(width 0.14732)
		(layer "In4.Cu")
		(net "UPI_CPU0_CPU1_P1P0_DN<21>")
	)
	(segment
		(start 333.21244 -172.570648)
		(end 320.279776 -167.995346)
		(width 0.14732)
		(layer "In4.Cu")
		(net "UPI_CPU0_CPU1_P1P0_DN<21>")
	)
	(segment
		(start 256.786126 -161.521902)
		(end 237.565946 -156.585158)
		(width 0.14732)
		(layer "In4.Cu")
		(net "UPI_CPU0_CPU1_P1P0_DN<21>")
	)
	(segment
		(start 154.417014 -164.349684)
		(end 153.557986 -164.364416)
		(width 0.14732)
		(layer "In4.Cu")
		(net "UPI_CPU0_CPU1_P1P0_DN<21>")
	)
	(segment
		(start 348.526608 -181.74589)
		(end 347.608652 -181.568598)
		(width 0.14732)
		(layer "In4.Cu")
		(net "UPI_CPU0_CPU1_P1P0_DN<21>")
	)
	(segment
		(start 110.73257 -207.40878)
		(end 110.587282 -207.819752)
		(width 0.14732)
		(layer "In4.Cu")
		(net "UPI_CPU0_CPU1_P1P0_DN<21>")
	)
	(segment
		(start 137.167112 -173.998128)
		(end 137.11936 -174.197518)
		(width 0.14732)
		(layer "In4.Cu")
		(net "UPI_CPU0_CPU1_P1P0_DN<21>")
	)
	(segment
		(start 110.66145 -207.976216)
		(end 110.515908 -208.388204)
		(width 0.14732)
		(layer "In4.Cu")
		(net "UPI_CPU0_CPU1_P1P0_DN<21>")
	)
	(segment
		(start 186.485022 -165.086284)
		(end 184.04586 -165.145466)
		(width 0.14732)
		(layer "In4.Cu")
		(net "UPI_CPU0_CPU1_P1P0_DN<21>")
	)
	(segment
		(start 350.682814 -181.417468)
		(end 348.526608 -181.74589)
		(width 0.14732)
		(layer "In4.Cu")
		(net "UPI_CPU0_CPU1_P1P0_DN<21>")
	)
	(segment
		(start 174.554388 -165.380924)
		(end 174.239174 -165.080442)
		(width 0.14732)
		(layer "In4.Cu")
		(net "UPI_CPU0_CPU1_P1P0_DN<21>")
	)
	(segment
		(start 179.293774 -166.409878)
		(end 178.993546 -166.725092)
		(width 0.14732)
		(layer "In4.Cu")
		(net "UPI_CPU0_CPU1_P1P0_DN<21>")
	)
	(segment
		(start 189.148466 -166.474902)
		(end 186.485022 -165.086284)
		(width 0.14732)
		(layer "In4.Cu")
		(net "UPI_CPU0_CPU1_P1P0_DN<21>")
	)
	(segment
		(start 176.500028 -162.770312)
		(end 176.349406 -162.62731)
		(width 0.14732)
		(layer "In4.Cu")
		(net "UPI_CPU0_CPU1_P1P0_DN<21>")
	)
	(segment
		(start 341.03818 -175.971708)
		(end 333.21244 -172.570648)
		(width 0.14732)
		(layer "In4.Cu")
		(net "UPI_CPU0_CPU1_P1P0_DN<21>")
	)
	(segment
		(start 141.9225 -171.796456)
		(end 141.821408 -172.21962)
		(width 0.14732)
		(layer "In4.Cu")
		(net "UPI_CPU0_CPU1_P1P0_DN<21>")
	)
	(segment
		(start 109.228636 -213.26348)
		(end 109.228636 -213.43874)
		(width 0.0889)
		(layer "In4.Cu")
		(net "UPI_CPU0_CPU1_P1P0_DN<21>")
	)
	(segment
		(start 357.030274 -192.50406)
		(end 355.966776 -191.42075)
		(width 0.14732)
		(layer "In4.Cu")
		(net "UPI_CPU0_CPU1_P1P0_DN<21>")
	)
	(segment
		(start 160.949386 -164.241226)
		(end 156.144468 -164.320982)
		(width 0.14732)
		(layer "In4.Cu")
		(net "UPI_CPU0_CPU1_P1P0_DN<21>")
	)
	(segment
		(start 109.129576 -212.96122)
		(end 109.129576 -213.16442)
		(width 0.0889)
		(layer "In4.Cu")
		(net "UPI_CPU0_CPU1_P1P0_DN<21>")
	)
	(segment
		(start 362.262674 -211.76615)
		(end 362.262674 -211.328254)
		(width 0.14732)
		(layer "In4.Cu")
		(net "UPI_CPU0_CPU1_P1P0_DN<21>")
	)
	(segment
		(start 109.228636 -212.86216)
		(end 109.129576 -212.96122)
		(width 0.0889)
		(layer "In4.Cu")
		(net "UPI_CPU0_CPU1_P1P0_DN<21>")
	)
	(segment
		(start 140.25499 -172.10151)
		(end 139.752578 -172.410374)
		(width 0.14732)
		(layer "In4.Cu")
		(net "UPI_CPU0_CPU1_P1P0_DN<21>")
	)
	(segment
		(start 361.929934 -218.692222)
		(end 362.086398 -218.421204)
		(width 0.0889)
		(layer "In4.Cu")
		(net "UPI_CPU0_CPU1_P1P0_DN<21>")
	)
	(segment
		(start 173.354746 -165.10254)
		(end 173.054518 -165.417754)
		(width 0.14732)
		(layer "In4.Cu")
		(net "UPI_CPU0_CPU1_P1P0_DN<21>")
	)
	(segment
		(start 134.7978 -175.453294)
		(end 134.169912 -176.045876)
		(width 0.14732)
		(layer "In4.Cu")
		(net "UPI_CPU0_CPU1_P1P0_DN<21>")
	)
	(segment
		(start 109.770164 -210.495896)
		(end 109.614208 -210.570318)
		(width 0.14732)
		(layer "In4.Cu")
		(net "UPI_CPU0_CPU1_P1P0_DN<21>")
	)
	(segment
		(start 179.412392 -165.260782)
		(end 179.268882 -165.411404)
		(width 0.14732)
		(layer "In4.Cu")
		(net "UPI_CPU0_CPU1_P1P0_DN<21>")
	)
	(segment
		(start 156.011372 -165.154864)
		(end 155.708858 -165.467538)
		(width 0.14732)
		(layer "In4.Cu")
		(net "UPI_CPU0_CPU1_P1P0_DN<21>")
	)
	(segment
		(start 110.21441 -208.87436)
		(end 110.288578 -209.030062)
		(width 0.14732)
		(layer "In4.Cu")
		(net "UPI_CPU0_CPU1_P1P0_DN<21>")
	)
	(segment
		(start 180.4924 -166.687754)
		(end 180.17744 -166.38778)
		(width 0.14732)
		(layer "In4.Cu")
		(net "UPI_CPU0_CPU1_P1P0_DN<21>")
	)
	(segment
		(start 182.31866 -165.188138)
		(end 181.729126 -165.203124)
		(width 0.14732)
		(layer "In4.Cu")
		(net "UPI_CPU0_CPU1_P1P0_DN<21>")
	)
	(segment
		(start 180.001926 -165.245796)
		(end 179.412392 -165.260782)
		(width 0.14732)
		(layer "In4.Cu")
		(net "UPI_CPU0_CPU1_P1P0_DN<21>")
	)
	(segment
		(start 134.16407 -176.2506)
		(end 133.895846 -176.503838)
		(width 0.14732)
		(layer "In4.Cu")
		(net "UPI_CPU0_CPU1_P1P0_DN<21>")
	)
	(segment
		(start 143.89735 -170.583352)
		(end 143.796258 -171.006516)
		(width 0.14732)
		(layer "In4.Cu")
		(net "UPI_CPU0_CPU1_P1P0_DN<21>")
	)
	(segment
		(start 113.236756 -200.327514)
		(end 110.959646 -206.766668)
		(width 0.14732)
		(layer "In4.Cu")
		(net "UPI_CPU0_CPU1_P1P0_DN<21>")
	)
	(segment
		(start 176.349406 -162.62731)
		(end 175.758856 -162.641788)
		(width 0.14732)
		(layer "In4.Cu")
		(net "UPI_CPU0_CPU1_P1P0_DN<21>")
	)
	(segment
		(start 113.538254 -199.841104)
		(end 113.392712 -200.253092)
		(width 0.14732)
		(layer "In4.Cu")
		(net "UPI_CPU0_CPU1_P1P0_DN<21>")
	)
	(segment
		(start 179.268882 -165.411404)
		(end 179.293774 -166.409878)
		(width 0.14732)
		(layer "In4.Cu")
		(net "UPI_CPU0_CPU1_P1P0_DN<21>")
	)
	(segment
		(start 169.196766 -166.080948)
		(end 168.32199 -166.31031)
		(width 0.14732)
		(layer "In4.Cu")
		(net "UPI_CPU0_CPU1_P1P0_DN<21>")
	)
	(segment
		(start 109.228636 -212.6869)
		(end 109.228636 -212.86216)
		(width 0.0889)
		(layer "In4.Cu")
		(net "UPI_CPU0_CPU1_P1P0_DN<21>")
	)
	(segment
		(start 362.262674 -211.328254)
		(end 362.26242 -211.328)
		(width 0.14732)
		(layer "In4.Cu")
		(net "UPI_CPU0_CPU1_P1P0_DN<21>")
	)
	(segment
		(start 173.442122 -162.699446)
		(end 173.29912 -162.850068)
		(width 0.14732)
		(layer "In4.Cu")
		(net "UPI_CPU0_CPU1_P1P0_DN<21>")
	)
	(segment
		(start 141.727428 -171.19727)
		(end 141.678914 -171.399708)
		(width 0.14732)
		(layer "In4.Cu")
		(net "UPI_CPU0_CPU1_P1P0_DN<21>")
	)
	(segment
		(start 174.183294 -162.82797)
		(end 174.032672 -162.684968)
		(width 0.14732)
		(layer "In4.Cu")
		(net "UPI_CPU0_CPU1_P1P0_DN<21>")
	)
	(segment
		(start 350.40189 -184.934606)
		(end 350.481392 -184.539636)
		(width 0.14732)
		(layer "In4.Cu")
		(net "UPI_CPU0_CPU1_P1P0_DN<21>")
	)
	(arc
		(start 362.587032 -214.946992)
		(mid 362.721965 -214.813638)
		(end 362.77423 -214.63127)
		(width 0.0889)
		(layer "In4.Cu")
		(net "UPI_CPU0_CPU1_P1P0_DN<21>")
	)
	(arc
		(start 362.30433 -217.0557)
		(mid 362.25206 -216.873335)
		(end 362.117132 -216.739978)
		(width 0.0889)
		(layer "In4.Cu")
		(net "UPI_CPU0_CPU1_P1P0_DN<21>")
	)
	(arc
		(start 108.915962 -215.436704)
		(mid 108.963641 -215.619604)
		(end 109.094524 -215.755982)
		(width 0.0889)
		(layer "In4.Cu")
		(net "UPI_CPU0_CPU1_P1P0_DN<21>")
	)
	(arc
		(start 362.062268 -218.33205)
		(mid 362.053824 -218.325653)
		(end 362.045504 -218.319096)
		(width 0.0889)
		(layer "In4.Cu")
		(net "UPI_CPU0_CPU1_P1P0_DN<21>")
	)
	(arc
		(start 109.094524 -215.117426)
		(mid 108.96727 -215.247392)
		(end 108.916216 -215.421972)
		(width 0.0889)
		(layer "In4.Cu")
		(net "UPI_CPU0_CPU1_P1P0_DN<21>")
	)
	(arc
		(start 362.117132 -215.760808)
		(mid 362.252065 -215.627454)
		(end 362.30433 -215.445086)
		(width 0.0889)
		(layer "In4.Cu")
		(net "UPI_CPU0_CPU1_P1P0_DN<21>")
	)
	(arc
		(start 361.834684 -217.859864)
		(mid 361.914846 -217.587675)
		(end 362.117132 -217.388694)
		(width 0.0889)
		(layer "In4.Cu")
		(net "UPI_CPU0_CPU1_P1P0_DN<21>")
	)
	(arc
		(start 109.10951 -215.764618)
		(mid 109.386084 -216.25052)
		(end 109.10951 -216.736422)
		(width 0.0889)
		(layer "In4.Cu")
		(net "UPI_CPU0_CPU1_P1P0_DN<21>")
	)
	(arc
		(start 109.385608 -214.57666)
		(mid 109.331744 -214.867777)
		(end 109.138466 -215.092026)
		(width 0.0889)
		(layer "In4.Cu")
		(net "UPI_CPU0_CPU1_P1P0_DN<21>")
	)
	(arc
		(start 362.117132 -217.388694)
		(mid 362.252065 -217.25534)
		(end 362.30433 -217.072972)
		(width 0.0889)
		(layer "In4.Cu")
		(net "UPI_CPU0_CPU1_P1P0_DN<21>")
	)
	(arc
		(start 362.587032 -214.298276)
		(mid 362.384746 -214.099295)
		(end 362.304584 -213.827106)
		(width 0.0889)
		(layer "In4.Cu")
		(net "UPI_CPU0_CPU1_P1P0_DN<21>")
	)
	(arc
		(start 362.77423 -214.613998)
		(mid 362.72196 -214.431633)
		(end 362.587032 -214.298276)
		(width 0.0889)
		(layer "In4.Cu")
		(net "UPI_CPU0_CPU1_P1P0_DN<21>")
	)
	(arc
		(start 362.304584 -215.422226)
		(mid 362.383715 -215.14769)
		(end 362.587032 -214.946992)
		(width 0.0889)
		(layer "In4.Cu")
		(net "UPI_CPU0_CPU1_P1P0_DN<21>")
	)
	(arc
		(start 362.10494 -216.732866)
		(mid 361.906712 -216.527018)
		(end 361.83443 -216.25052)
		(width 0.0889)
		(layer "In4.Cu")
		(net "UPI_CPU0_CPU1_P1P0_DN<21>")
	)
	(arc
		(start 109.103414 -216.739978)
		(mid 108.917211 -217.035655)
		(end 109.05617 -217.356182)
		(width 0.0889)
		(layer "In4.Cu")
		(net "UPI_CPU0_CPU1_P1P0_DN<21>")
	)
	(arc
		(start 108.916216 -215.421972)
		(mid 108.916019 -215.429337)
		(end 108.915962 -215.436704)
		(width 0.0889)
		(layer "In4.Cu")
		(net "UPI_CPU0_CPU1_P1P0_DN<21>")
	)
	(arc
		(start 362.045504 -218.319096)
		(mid 361.89212 -218.127177)
		(end 361.834684 -217.888312)
		(width 0.0889)
		(layer "In4.Cu")
		(net "UPI_CPU0_CPU1_P1P0_DN<21>")
	)
	(arc
		(start 361.83443 -216.2429)
		(mid 361.912059 -215.964487)
		(end 362.117132 -215.760808)
		(width 0.0889)
		(layer "In4.Cu")
		(net "UPI_CPU0_CPU1_P1P0_DN<21>")
	)
	(segment
		(start 363.33938 -217.87866)
		(end 363.339634 -217.878406)
		(width 0.13208)
		(layer "F.Cu")
		(net "UPI_CPU0_CPU1_P1P0_DN<20>")
	)
	(segment
		(start 363.33938 -218.414346)
		(end 363.33938 -217.87866)
		(width 0.13208)
		(layer "F.Cu")
		(net "UPI_CPU0_CPU1_P1P0_DN<20>")
	)
	(segment
		(start 107.880912 -218.414346)
		(end 107.880912 -217.87866)
		(width 0.13208)
		(layer "F.Cu")
		(net "UPI_CPU0_CPU1_P1P0_DN<20>")
	)
	(segment
		(start 107.880912 -217.87866)
		(end 107.881166 -217.878406)
		(width 0.13208)
		(layer "F.Cu")
		(net "UPI_CPU0_CPU1_P1P0_DN<20>")
	)
	(segment
		(start 348.130622 -180.541676)
		(end 344.104214 -176.790858)
		(width 0.14732)
		(layer "In4.Cu")
		(net "UPI_CPU0_CPU1_P1P0_DN<20>")
	)
	(segment
		(start 363.339634 -217.878406)
		(end 363.323886 -217.851228)
		(width 0.0889)
		(layer "In4.Cu")
		(net "UPI_CPU0_CPU1_P1P0_DN<20>")
	)
	(segment
		(start 178.44008 -161.219896)
		(end 178.378104 -161.021776)
		(width 0.14732)
		(layer "In4.Cu")
		(net "UPI_CPU0_CPU1_P1P0_DN<20>")
	)
	(segment
		(start 107.686856 -212.73008)
		(end 107.785916 -212.82914)
		(width 0.0889)
		(layer "In4.Cu")
		(net "UPI_CPU0_CPU1_P1P0_DN<20>")
	)
	(segment
		(start 121.751344 -186.139836)
		(end 112.880648 -197.306438)
		(width 0.14732)
		(layer "In4.Cu")
		(net "UPI_CPU0_CPU1_P1P0_DN<20>")
	)
	(segment
		(start 112.880648 -197.306438)
		(end 109.868462 -205.574138)
		(width 0.14732)
		(layer "In4.Cu")
		(net "UPI_CPU0_CPU1_P1P0_DN<20>")
	)
	(segment
		(start 155.38069 -162.842956)
		(end 154.928316 -162.10915)
		(width 0.14732)
		(layer "In4.Cu")
		(net "UPI_CPU0_CPU1_P1P0_DN<20>")
	)
	(segment
		(start 171.88942 -156.158946)
		(end 169.257218 -154.855672)
		(width 0.14732)
		(layer "In4.Cu")
		(net "UPI_CPU0_CPU1_P1P0_DN<20>")
	)
	(segment
		(start 108.076746 -214.941912)
		(end 108.067856 -214.946992)
		(width 0.0889)
		(layer "In4.Cu")
		(net "UPI_CPU0_CPU1_P1P0_DN<20>")
	)
	(segment
		(start 344.104214 -176.790858)
		(end 341.631524 -175.025304)
		(width 0.14732)
		(layer "In4.Cu")
		(net "UPI_CPU0_CPU1_P1P0_DN<20>")
	)
	(segment
		(start 167.050974 -154.796998)
		(end 165.105842 -155.476194)
		(width 0.14732)
		(layer "In4.Cu")
		(net "UPI_CPU0_CPU1_P1P0_DN<20>")
	)
	(segment
		(start 177.56886 -159.47771)
		(end 177.108358 -160.357566)
		(width 0.14732)
		(layer "In4.Cu")
		(net "UPI_CPU0_CPU1_P1P0_DN<20>")
	)
	(segment
		(start 160.347406 -158.408116)
		(end 160.246822 -158.831788)
		(width 0.14732)
		(layer "In4.Cu")
		(net "UPI_CPU0_CPU1_P1P0_DN<20>")
	)
	(segment
		(start 348.54896 -180.622448)
		(end 348.130622 -180.541676)
		(width 0.14732)
		(layer "In4.Cu")
		(net "UPI_CPU0_CPU1_P1P0_DN<20>")
	)
	(segment
		(start 363.904784 -214.622634)
		(end 363.904784 -214.425784)
		(width 0.0889)
		(layer "In4.Cu")
		(net "UPI_CPU0_CPU1_P1P0_DN<20>")
	)
	(segment
		(start 109.868462 -205.574138)
		(end 107.743752 -211.405978)
		(width 0.14732)
		(layer "In4.Cu")
		(net "UPI_CPU0_CPU1_P1P0_DN<20>")
	)
	(segment
		(start 234.505246 -155.478988)
		(end 197.526402 -165.01237)
		(width 0.14732)
		(layer "In4.Cu")
		(net "UPI_CPU0_CPU1_P1P0_DN<20>")
	)
	(segment
		(start 363.476794 -211.214462)
		(end 363.47654 -211.214208)
		(width 0.14732)
		(layer "In4.Cu")
		(net "UPI_CPU0_CPU1_P1P0_DN<20>")
	)
	(segment
		(start 363.476794 -211.74329)
		(end 363.476794 -211.214462)
		(width 0.14732)
		(layer "In4.Cu")
		(net "UPI_CPU0_CPU1_P1P0_DN<20>")
	)
	(segment
		(start 177.98415 -159.347408)
		(end 177.56886 -159.47771)
		(width 0.14732)
		(layer "In4.Cu")
		(net "UPI_CPU0_CPU1_P1P0_DN<20>")
	)
	(segment
		(start 107.785916 -212.084158)
		(end 107.785916 -212.45576)
		(width 0.0889)
		(layer "In4.Cu")
		(net "UPI_CPU0_CPU1_P1P0_DN<20>")
	)
	(segment
		(start 180.03774 -160.421828)
		(end 179.62245 -160.55213)
		(width 0.14732)
		(layer "In4.Cu")
		(net "UPI_CPU0_CPU1_P1P0_DN<20>")
	)
	(segment
		(start 237.706154 -155.478988)
		(end 234.505246 -155.478988)
		(width 0.14732)
		(layer "In4.Cu")
		(net "UPI_CPU0_CPU1_P1P0_DN<20>")
	)
	(segment
		(start 108.06557 -215.924384)
		(end 108.067602 -215.925654)
		(width 0.0889)
		(layer "In4.Cu")
		(net "UPI_CPU0_CPU1_P1P0_DN<20>")
	)
	(segment
		(start 107.785916 -212.82914)
		(end 107.785916 -213.0044)
		(width 0.0889)
		(layer "In4.Cu")
		(net "UPI_CPU0_CPU1_P1P0_DN<20>")
	)
	(segment
		(start 363.447076 -213.92007)
		(end 363.43463 -213.762844)
		(width 0.0889)
		(layer "In4.Cu")
		(net "UPI_CPU0_CPU1_P1P0_DN<20>")
	)
	(segment
		(start 355.4984 -186.855608)
		(end 355.4984 -184.302654)
		(width 0.14732)
		(layer "In4.Cu")
		(net "UPI_CPU0_CPU1_P1P0_DN<20>")
	)
	(segment
		(start 156.085794 -162.580828)
		(end 155.58262 -162.890962)
		(width 0.14732)
		(layer "In4.Cu")
		(net "UPI_CPU0_CPU1_P1P0_DN<20>")
	)
	(segment
		(start 158.374334 -159.624014)
		(end 158.27375 -160.047686)
		(width 0.14732)
		(layer "In4.Cu")
		(net "UPI_CPU0_CPU1_P1P0_DN<20>")
	)
	(segment
		(start 159.493712 -159.295846)
		(end 159.07004 -159.195262)
		(width 0.14732)
		(layer "In4.Cu")
		(net "UPI_CPU0_CPU1_P1P0_DN<20>")
	)
	(segment
		(start 108.077254 -216.569798)
		(end 108.068364 -216.574878)
		(width 0.0889)
		(layer "In4.Cu")
		(net "UPI_CPU0_CPU1_P1P0_DN<20>")
	)
	(segment
		(start 355.541072 -187.069476)
		(end 355.4984 -186.855608)
		(width 0.14732)
		(layer "In4.Cu")
		(net "UPI_CPU0_CPU1_P1P0_DN<20>")
	)
	(segment
		(start 175.054768 -159.283146)
		(end 174.856648 -159.345122)
		(width 0.14732)
		(layer "In4.Cu")
		(net "UPI_CPU0_CPU1_P1P0_DN<20>")
	)
	(segment
		(start 363.323886 -217.851228)
		(end 363.18317 -217.607388)
		(width 0.0889)
		(layer "In4.Cu")
		(net "UPI_CPU0_CPU1_P1P0_DN<20>")
	)
	(segment
		(start 357.19512 -191.063118)
		(end 355.541072 -187.069476)
		(width 0.14732)
		(layer "In4.Cu")
		(net "UPI_CPU0_CPU1_P1P0_DN<20>")
	)
	(segment
		(start 363.622336 -215.112092)
		(end 363.628432 -215.108536)
		(width 0.0889)
		(layer "In4.Cu")
		(net "UPI_CPU0_CPU1_P1P0_DN<20>")
	)
	(segment
		(start 156.1338 -162.378898)
		(end 156.085794 -162.580828)
		(width 0.14732)
		(layer "In4.Cu")
		(net "UPI_CPU0_CPU1_P1P0_DN<20>")
	)
	(segment
		(start 179.161948 -161.431986)
		(end 178.963828 -161.493962)
		(width 0.14732)
		(layer "In4.Cu")
		(net "UPI_CPU0_CPU1_P1P0_DN<20>")
	)
	(segment
		(start 178.963828 -161.493962)
		(end 178.44008 -161.219896)
		(width 0.14732)
		(layer "In4.Cu")
		(net "UPI_CPU0_CPU1_P1P0_DN<20>")
	)
	(segment
		(start 174.270924 -158.872936)
		(end 174.731426 -157.99308)
		(width 0.14732)
		(layer "In4.Cu")
		(net "UPI_CPU0_CPU1_P1P0_DN<20>")
	)
	(segment
		(start 169.257218 -154.855672)
		(end 167.050974 -154.796998)
		(width 0.14732)
		(layer "In4.Cu")
		(net "UPI_CPU0_CPU1_P1P0_DN<20>")
	)
	(segment
		(start 350.676972 -180.29809)
		(end 349.612966 -180.460142)
		(width 0.14732)
		(layer "In4.Cu")
		(net "UPI_CPU0_CPU1_P1P0_DN<20>")
	)
	(segment
		(start 276.213824 -165.369748)
		(end 237.706154 -155.478988)
		(width 0.14732)
		(layer "In4.Cu")
		(net "UPI_CPU0_CPU1_P1P0_DN<20>")
	)
	(segment
		(start 159.07004 -159.195262)
		(end 158.374334 -159.624014)
		(width 0.14732)
		(layer "In4.Cu")
		(net "UPI_CPU0_CPU1_P1P0_DN<20>")
	)
	(segment
		(start 155.78201 -161.22142)
		(end 155.681426 -161.645092)
		(width 0.14732)
		(layer "In4.Cu")
		(net "UPI_CPU0_CPU1_P1P0_DN<20>")
	)
	(segment
		(start 179.62245 -160.55213)
		(end 179.161948 -161.431986)
		(width 0.14732)
		(layer "In4.Cu")
		(net "UPI_CPU0_CPU1_P1P0_DN<20>")
	)
	(segment
		(start 302.49368 -164.98443)
		(end 280.165302 -165.369748)
		(width 0.14732)
		(layer "In4.Cu")
		(net "UPI_CPU0_CPU1_P1P0_DN<20>")
	)
	(segment
		(start 363.47654 -205.163674)
		(end 357.95839 -191.84112)
		(width 0.14732)
		(layer "In4.Cu")
		(net "UPI_CPU0_CPU1_P1P0_DN<20>")
	)
	(segment
		(start 155.681426 -161.645092)
		(end 156.1338 -162.378898)
		(width 0.14732)
		(layer "In4.Cu")
		(net "UPI_CPU0_CPU1_P1P0_DN<20>")
	)
	(segment
		(start 175.51527 -158.40329)
		(end 175.054768 -159.283146)
		(width 0.14732)
		(layer "In4.Cu")
		(net "UPI_CPU0_CPU1_P1P0_DN<20>")
	)
	(segment
		(start 175.93056 -158.272988)
		(end 175.51527 -158.40329)
		(width 0.14732)
		(layer "In4.Cu")
		(net "UPI_CPU0_CPU1_P1P0_DN<20>")
	)
	(segment
		(start 108.064554 -216.577164)
		(end 108.056172 -216.58199)
		(width 0.0889)
		(layer "In4.Cu")
		(net "UPI_CPU0_CPU1_P1P0_DN<20>")
	)
	(segment
		(start 107.785916 -212.45576)
		(end 107.686856 -212.55482)
		(width 0.0889)
		(layer "In4.Cu")
		(net "UPI_CPU0_CPU1_P1P0_DN<20>")
	)
	(segment
		(start 154.928316 -162.10915)
		(end 154.504644 -162.008566)
		(width 0.14732)
		(layer "In4.Cu")
		(net "UPI_CPU0_CPU1_P1P0_DN<20>")
	)
	(segment
		(start 107.743752 -211.882228)
		(end 107.744006 -211.882482)
		(width 0.14732)
		(layer "In4.Cu")
		(net "UPI_CPU0_CPU1_P1P0_DN<20>")
	)
	(segment
		(start 154.504644 -162.008566)
		(end 133.924294 -174.691802)
		(width 0.14732)
		(layer "In4.Cu")
		(net "UPI_CPU0_CPU1_P1P0_DN<20>")
	)
	(segment
		(start 174.601124 -157.57779)
		(end 171.88942 -156.158946)
		(width 0.14732)
		(layer "In4.Cu")
		(net "UPI_CPU0_CPU1_P1P0_DN<20>")
	)
	(segment
		(start 107.686856 -212.55482)
		(end 107.686856 -212.73008)
		(width 0.0889)
		(layer "In4.Cu")
		(net "UPI_CPU0_CPU1_P1P0_DN<20>")
	)
	(segment
		(start 363.18317 -217.607388)
		(end 363.2073 -217.518234)
		(width 0.0889)
		(layer "In4.Cu")
		(net "UPI_CPU0_CPU1_P1P0_DN<20>")
	)
	(segment
		(start 197.526402 -165.01237)
		(end 194.767962 -165.359588)
		(width 0.14732)
		(layer "In4.Cu")
		(net "UPI_CPU0_CPU1_P1P0_DN<20>")
	)
	(segment
		(start 157.096968 -160.41116)
		(end 155.78201 -161.22142)
		(width 0.14732)
		(layer "In4.Cu")
		(net "UPI_CPU0_CPU1_P1P0_DN<20>")
	)
	(segment
		(start 108.077254 -215.931496)
		(end 108.077254 -215.931242)
		(width 0.0889)
		(layer "In4.Cu")
		(net "UPI_CPU0_CPU1_P1P0_DN<20>")
	)
	(segment
		(start 355.4984 -184.302654)
		(end 355.01834 -183.25465)
		(width 0.14732)
		(layer "In4.Cu")
		(net "UPI_CPU0_CPU1_P1P0_DN<20>")
	)
	(segment
		(start 189.475364 -165.359588)
		(end 180.03774 -160.421828)
		(width 0.14732)
		(layer "In4.Cu")
		(net "UPI_CPU0_CPU1_P1P0_DN<20>")
	)
	(segment
		(start 108.03763 -218.149424)
		(end 107.881166 -217.878406)
		(width 0.0889)
		(layer "In4.Cu")
		(net "UPI_CPU0_CPU1_P1P0_DN<20>")
	)
	(segment
		(start 178.378104 -161.021776)
		(end 178.838606 -160.14192)
		(width 0.14732)
		(layer "In4.Cu")
		(net "UPI_CPU0_CPU1_P1P0_DN<20>")
	)
	(segment
		(start 158.27375 -160.047686)
		(end 159.465264 -161.981388)
		(width 0.14732)
		(layer "In4.Cu")
		(net "UPI_CPU0_CPU1_P1P0_DN<20>")
	)
	(segment
		(start 108.067602 -215.925654)
		(end 108.069126 -215.92667)
		(width 0.0889)
		(layer "In4.Cu")
		(net "UPI_CPU0_CPU1_P1P0_DN<20>")
	)
	(segment
		(start 108.068364 -217.554048)
		(end 108.077254 -217.559128)
		(width 0.0889)
		(layer "In4.Cu")
		(net "UPI_CPU0_CPU1_P1P0_DN<20>")
	)
	(segment
		(start 108.068364 -216.574878)
		(end 108.064554 -216.577164)
		(width 0.0889)
		(layer "In4.Cu")
		(net "UPI_CPU0_CPU1_P1P0_DN<20>")
	)
	(segment
		(start 357.95839 -191.84112)
		(end 357.19512 -191.063118)
		(width 0.14732)
		(layer "In4.Cu")
		(net "UPI_CPU0_CPU1_P1P0_DN<20>")
	)
	(segment
		(start 158.712154 -162.445446)
		(end 157.52064 -160.511744)
		(width 0.14732)
		(layer "In4.Cu")
		(net "UPI_CPU0_CPU1_P1P0_DN<20>")
	)
	(segment
		(start 107.785916 -213.37778)
		(end 107.785916 -213.930484)
		(width 0.0889)
		(layer "In4.Cu")
		(net "UPI_CPU0_CPU1_P1P0_DN<20>")
	)
	(segment
		(start 107.744006 -212.02015)
		(end 107.744006 -212.042248)
		(width 0.0889)
		(layer "In4.Cu")
		(net "UPI_CPU0_CPU1_P1P0_DN<20>")
	)
	(segment
		(start 363.152182 -215.926162)
		(end 363.164374 -215.91905)
		(width 0.0889)
		(layer "In4.Cu")
		(net "UPI_CPU0_CPU1_P1P0_DN<20>")
	)
	(segment
		(start 363.164374 -216.58199)
		(end 363.152182 -216.574878)
		(width 0.0889)
		(layer "In4.Cu")
		(net "UPI_CPU0_CPU1_P1P0_DN<20>")
	)
	(segment
		(start 333.640938 -171.542964)
		(end 320.595498 -166.93134)
		(width 0.14732)
		(layer "In4.Cu")
		(net "UPI_CPU0_CPU1_P1P0_DN<20>")
	)
	(segment
		(start 174.3329 -159.071056)
		(end 174.270924 -158.872936)
		(width 0.14732)
		(layer "In4.Cu")
		(net "UPI_CPU0_CPU1_P1P0_DN<20>")
	)
	(segment
		(start 176.654714 -158.651956)
		(end 175.93056 -158.272988)
		(width 0.14732)
		(layer "In4.Cu")
		(net "UPI_CPU0_CPU1_P1P0_DN<20>")
	)
	(segment
		(start 351.76968 -180.452522)
		(end 350.676972 -180.29809)
		(width 0.14732)
		(layer "In4.Cu")
		(net "UPI_CPU0_CPU1_P1P0_DN<20>")
	)
	(segment
		(start 161.39033 -160.96742)
		(end 160.887156 -161.277554)
		(width 0.14732)
		(layer "In4.Cu")
		(net "UPI_CPU0_CPU1_P1P0_DN<20>")
	)
	(segment
		(start 176.785016 -159.0675)
		(end 176.654714 -158.651956)
		(width 0.14732)
		(layer "In4.Cu")
		(net "UPI_CPU0_CPU1_P1P0_DN<20>")
	)
	(segment
		(start 107.686856 -213.27872)
		(end 107.785916 -213.37778)
		(width 0.0889)
		(layer "In4.Cu")
		(net "UPI_CPU0_CPU1_P1P0_DN<20>")
	)
	(segment
		(start 363.43463 -213.762844)
		(end 363.43463 -211.807552)
		(width 0.0889)
		(layer "In4.Cu")
		(net "UPI_CPU0_CPU1_P1P0_DN<20>")
	)
	(segment
		(start 320.595498 -166.93134)
		(end 314.569094 -165.23081)
		(width 0.14732)
		(layer "In4.Cu")
		(net "UPI_CPU0_CPU1_P1P0_DN<20>")
	)
	(segment
		(start 314.569094 -165.23081)
		(end 302.49368 -164.98443)
		(width 0.14732)
		(layer "In4.Cu")
		(net "UPI_CPU0_CPU1_P1P0_DN<20>")
	)
	(segment
		(start 363.47654 -211.214208)
		(end 363.47654 -205.163674)
		(width 0.14732)
		(layer "In4.Cu")
		(net "UPI_CPU0_CPU1_P1P0_DN<20>")
	)
	(segment
		(start 176.910238 -160.419542)
		(end 176.38649 -160.145476)
		(width 0.14732)
		(layer "In4.Cu")
		(net "UPI_CPU0_CPU1_P1P0_DN<20>")
	)
	(segment
		(start 159.417258 -162.183318)
		(end 158.914084 -162.493452)
		(width 0.14732)
		(layer "In4.Cu")
		(net "UPI_CPU0_CPU1_P1P0_DN<20>")
	)
	(segment
		(start 107.785662 -217.064336)
		(end 107.785662 -217.071956)
		(width 0.0889)
		(layer "In4.Cu")
		(net "UPI_CPU0_CPU1_P1P0_DN<20>")
	)
	(segment
		(start 178.838606 -160.14192)
		(end 178.708304 -159.726376)
		(width 0.14732)
		(layer "In4.Cu")
		(net "UPI_CPU0_CPU1_P1P0_DN<20>")
	)
	(segment
		(start 174.856648 -159.345122)
		(end 174.3329 -159.071056)
		(width 0.14732)
		(layer "In4.Cu")
		(net "UPI_CPU0_CPU1_P1P0_DN<20>")
	)
	(segment
		(start 160.246822 -158.831788)
		(end 161.438336 -160.76549)
		(width 0.14732)
		(layer "In4.Cu")
		(net "UPI_CPU0_CPU1_P1P0_DN<20>")
	)
	(segment
		(start 341.631524 -175.025304)
		(end 333.640938 -171.542964)
		(width 0.14732)
		(layer "In4.Cu")
		(net "UPI_CPU0_CPU1_P1P0_DN<20>")
	)
	(segment
		(start 107.686856 -213.10346)
		(end 107.686856 -213.27872)
		(width 0.0889)
		(layer "In4.Cu")
		(net "UPI_CPU0_CPU1_P1P0_DN<20>")
	)
	(segment
		(start 176.324514 -159.947356)
		(end 176.785016 -159.0675)
		(width 0.14732)
		(layer "In4.Cu")
		(net "UPI_CPU0_CPU1_P1P0_DN<20>")
	)
	(segment
		(start 107.744006 -212.042248)
		(end 107.785916 -212.084158)
		(width 0.0889)
		(layer "In4.Cu")
		(net "UPI_CPU0_CPU1_P1P0_DN<20>")
	)
	(segment
		(start 158.914084 -162.493452)
		(end 158.712154 -162.445446)
		(width 0.14732)
		(layer "In4.Cu")
		(net "UPI_CPU0_CPU1_P1P0_DN<20>")
	)
	(segment
		(start 108.062268 -215.922606)
		(end 108.06557 -215.924384)
		(width 0.0889)
		(layer "In4.Cu")
		(net "UPI_CPU0_CPU1_P1P0_DN<20>")
	)
	(segment
		(start 108.255308 -214.461344)
		(end 108.255308 -214.622634)
		(width 0.0889)
		(layer "In4.Cu")
		(net "UPI_CPU0_CPU1_P1P0_DN<20>")
	)
	(segment
		(start 107.785916 -213.0044)
		(end 107.686856 -213.10346)
		(width 0.0889)
		(layer "In4.Cu")
		(net "UPI_CPU0_CPU1_P1P0_DN<20>")
	)
	(segment
		(start 194.767962 -165.359588)
		(end 189.475364 -165.359588)
		(width 0.14732)
		(layer "In4.Cu")
		(net "UPI_CPU0_CPU1_P1P0_DN<20>")
	)
	(segment
		(start 157.52064 -160.511744)
		(end 157.096968 -160.41116)
		(width 0.14732)
		(layer "In4.Cu")
		(net "UPI_CPU0_CPU1_P1P0_DN<20>")
	)
	(segment
		(start 362.964984 -216.259156)
		(end 362.964984 -216.241884)
		(width 0.0889)
		(layer "In4.Cu")
		(net "UPI_CPU0_CPU1_P1P0_DN<20>")
	)
	(segment
		(start 107.744006 -211.882482)
		(end 107.744006 -212.02015)
		(width 0.14732)
		(layer "In4.Cu")
		(net "UPI_CPU0_CPU1_P1P0_DN<20>")
	)
	(segment
		(start 108.069126 -215.92667)
		(end 108.077254 -215.931496)
		(width 0.0889)
		(layer "In4.Cu")
		(net "UPI_CPU0_CPU1_P1P0_DN<20>")
	)
	(segment
		(start 160.887156 -161.277554)
		(end 160.685226 -161.229548)
		(width 0.14732)
		(layer "In4.Cu")
		(net "UPI_CPU0_CPU1_P1P0_DN<20>")
	)
	(segment
		(start 165.105842 -155.476194)
		(end 160.347406 -158.408116)
		(width 0.14732)
		(layer "In4.Cu")
		(net "UPI_CPU0_CPU1_P1P0_DN<20>")
	)
	(segment
		(start 178.708304 -159.726376)
		(end 177.98415 -159.347408)
		(width 0.14732)
		(layer "In4.Cu")
		(net "UPI_CPU0_CPU1_P1P0_DN<20>")
	)
	(segment
		(start 363.476794 -211.765388)
		(end 363.476794 -211.74329)
		(width 0.0889)
		(layer "In4.Cu")
		(net "UPI_CPU0_CPU1_P1P0_DN<20>")
	)
	(segment
		(start 363.434884 -217.07856)
		(end 363.434884 -217.064336)
		(width 0.0889)
		(layer "In4.Cu")
		(net "UPI_CPU0_CPU1_P1P0_DN<20>")
	)
	(segment
		(start 355.01834 -183.25465)
		(end 351.76968 -180.452522)
		(width 0.14732)
		(layer "In4.Cu")
		(net "UPI_CPU0_CPU1_P1P0_DN<20>")
	)
	(segment
		(start 363.43463 -211.807552)
		(end 363.476794 -211.765388)
		(width 0.0889)
		(layer "In4.Cu")
		(net "UPI_CPU0_CPU1_P1P0_DN<20>")
	)
	(segment
		(start 108.115862 -218.170252)
		(end 108.03763 -218.149424)
		(width 0.0889)
		(layer "In4.Cu")
		(net "UPI_CPU0_CPU1_P1P0_DN<20>")
	)
	(segment
		(start 160.685226 -161.229548)
		(end 159.493712 -159.295846)
		(width 0.14732)
		(layer "In4.Cu")
		(net "UPI_CPU0_CPU1_P1P0_DN<20>")
	)
	(segment
		(start 107.743752 -211.405978)
		(end 107.743752 -211.882228)
		(width 0.14732)
		(layer "In4.Cu")
		(net "UPI_CPU0_CPU1_P1P0_DN<20>")
	)
	(segment
		(start 161.438336 -160.76549)
		(end 161.39033 -160.96742)
		(width 0.14732)
		(layer "In4.Cu")
		(net "UPI_CPU0_CPU1_P1P0_DN<20>")
	)
	(segment
		(start 177.108358 -160.357566)
		(end 176.910238 -160.419542)
		(width 0.14732)
		(layer "In4.Cu")
		(net "UPI_CPU0_CPU1_P1P0_DN<20>")
	)
	(segment
		(start 159.465264 -161.981388)
		(end 159.417258 -162.183318)
		(width 0.14732)
		(layer "In4.Cu")
		(net "UPI_CPU0_CPU1_P1P0_DN<20>")
	)
	(segment
		(start 155.58262 -162.890962)
		(end 155.38069 -162.842956)
		(width 0.14732)
		(layer "In4.Cu")
		(net "UPI_CPU0_CPU1_P1P0_DN<20>")
	)
	(segment
		(start 363.613446 -215.117172)
		(end 363.622336 -215.112092)
		(width 0.0889)
		(layer "In4.Cu")
		(net "UPI_CPU0_CPU1_P1P0_DN<20>")
	)
	(segment
		(start 176.38649 -160.145476)
		(end 176.324514 -159.947356)
		(width 0.14732)
		(layer "In4.Cu")
		(net "UPI_CPU0_CPU1_P1P0_DN<20>")
	)
	(segment
		(start 280.165302 -165.369748)
		(end 276.213824 -165.369748)
		(width 0.14732)
		(layer "In4.Cu")
		(net "UPI_CPU0_CPU1_P1P0_DN<20>")
	)
	(segment
		(start 133.924294 -174.691802)
		(end 121.751344 -186.139836)
		(width 0.14732)
		(layer "In4.Cu")
		(net "UPI_CPU0_CPU1_P1P0_DN<20>")
	)
	(segment
		(start 174.731426 -157.99308)
		(end 174.601124 -157.57779)
		(width 0.14732)
		(layer "In4.Cu")
		(net "UPI_CPU0_CPU1_P1P0_DN<20>")
	)
	(segment
		(start 349.612966 -180.460142)
		(end 348.54896 -180.622448)
		(width 0.14732)
		(layer "In4.Cu")
		(net "UPI_CPU0_CPU1_P1P0_DN<20>")
	)
	(arc
		(start 363.434884 -217.064336)
		(mid 363.362649 -216.787812)
		(end 363.164374 -216.58199)
		(width 0.0889)
		(layer "In4.Cu")
		(net "UPI_CPU0_CPU1_P1P0_DN<20>")
	)
	(arc
		(start 363.434884 -215.43645)
		(mid 363.482563 -215.25355)
		(end 363.613446 -215.117172)
		(width 0.0889)
		(layer "In4.Cu")
		(net "UPI_CPU0_CPU1_P1P0_DN<20>")
	)
	(arc
		(start 363.904784 -214.425784)
		(mid 363.793446 -214.232434)
		(end 363.619034 -214.093298)
		(width 0.0889)
		(layer "In4.Cu")
		(net "UPI_CPU0_CPU1_P1P0_DN<20>")
	)
	(arc
		(start 108.067856 -214.946992)
		(mid 107.78546 -215.433205)
		(end 108.062268 -215.922606)
		(width 0.0889)
		(layer "In4.Cu")
		(net "UPI_CPU0_CPU1_P1P0_DN<20>")
	)
	(arc
		(start 108.077254 -217.559128)
		(mid 108.208168 -217.695488)
		(end 108.255816 -217.878406)
		(width 0.0889)
		(layer "In4.Cu")
		(net "UPI_CPU0_CPU1_P1P0_DN<20>")
	)
	(arc
		(start 363.2073 -217.518234)
		(mid 363.215743 -217.511836)
		(end 363.224064 -217.50528)
		(width 0.0889)
		(layer "In4.Cu")
		(net "UPI_CPU0_CPU1_P1P0_DN<20>")
	)
	(arc
		(start 107.801156 -213.969346)
		(mid 107.91115 -214.138715)
		(end 108.071158 -214.261954)
		(width 0.0889)
		(layer "In4.Cu")
		(net "UPI_CPU0_CPU1_P1P0_DN<20>")
	)
	(arc
		(start 107.785916 -213.930484)
		(mid 107.793201 -213.950046)
		(end 107.801156 -213.969346)
		(width 0.0889)
		(layer "In4.Cu")
		(net "UPI_CPU0_CPU1_P1P0_DN<20>")
	)
	(arc
		(start 108.255308 -214.622634)
		(mid 108.207629 -214.805534)
		(end 108.076746 -214.941912)
		(width 0.0889)
		(layer "In4.Cu")
		(net "UPI_CPU0_CPU1_P1P0_DN<20>")
	)
	(arc
		(start 108.255816 -217.878406)
		(mid 108.218956 -218.040203)
		(end 108.115862 -218.170252)
		(width 0.0889)
		(layer "In4.Cu")
		(net "UPI_CPU0_CPU1_P1P0_DN<20>")
	)
	(arc
		(start 363.164374 -215.91905)
		(mid 363.362664 -215.713091)
		(end 363.434884 -215.43645)
		(width 0.0889)
		(layer "In4.Cu")
		(net "UPI_CPU0_CPU1_P1P0_DN<20>")
	)
	(arc
		(start 107.785662 -217.071956)
		(mid 107.863291 -217.350369)
		(end 108.068364 -217.554048)
		(width 0.0889)
		(layer "In4.Cu")
		(net "UPI_CPU0_CPU1_P1P0_DN<20>")
	)
	(arc
		(start 363.152182 -216.574878)
		(mid 363.017249 -216.441524)
		(end 362.964984 -216.259156)
		(width 0.0889)
		(layer "In4.Cu")
		(net "UPI_CPU0_CPU1_P1P0_DN<20>")
	)
	(arc
		(start 363.628432 -215.108536)
		(mid 363.830845 -214.902123)
		(end 363.904784 -214.622634)
		(width 0.0889)
		(layer "In4.Cu")
		(net "UPI_CPU0_CPU1_P1P0_DN<20>")
	)
	(arc
		(start 363.619034 -214.093298)
		(mid 363.519776 -214.01986)
		(end 363.447076 -213.92007)
		(width 0.0889)
		(layer "In4.Cu")
		(net "UPI_CPU0_CPU1_P1P0_DN<20>")
	)
	(arc
		(start 363.224064 -217.50528)
		(mid 363.376571 -217.315182)
		(end 363.434884 -217.07856)
		(width 0.0889)
		(layer "In4.Cu")
		(net "UPI_CPU0_CPU1_P1P0_DN<20>")
	)
	(arc
		(start 108.077254 -215.931242)
		(mid 108.255851 -216.25052)
		(end 108.077254 -216.569798)
		(width 0.0889)
		(layer "In4.Cu")
		(net "UPI_CPU0_CPU1_P1P0_DN<20>")
	)
	(arc
		(start 108.071158 -214.261954)
		(mid 108.180305 -214.345882)
		(end 108.255308 -214.461344)
		(width 0.0889)
		(layer "In4.Cu")
		(net "UPI_CPU0_CPU1_P1P0_DN<20>")
	)
	(arc
		(start 362.964984 -216.241884)
		(mid 363.017254 -216.059519)
		(end 363.152182 -215.926162)
		(width 0.0889)
		(layer "In4.Cu")
		(net "UPI_CPU0_CPU1_P1P0_DN<20>")
	)
	(arc
		(start 108.056172 -216.58199)
		(mid 107.857944 -216.787838)
		(end 107.785662 -217.064336)
		(width 0.0889)
		(layer "In4.Cu")
		(net "UPI_CPU0_CPU1_P1P0_DN<20>")
	)
	(segment
		(start 380.725934 -219.228162)
		(end 380.725934 -218.692476)
		(width 0.13208)
		(layer "F.Cu")
		(net "UPI_CPU0_CPU1_P1P0_DN<1>")
	)
	(segment
		(start 90.494866 -217.600276)
		(end 90.494866 -217.06459)
		(width 0.13208)
		(layer "F.Cu")
		(net "UPI_CPU0_CPU1_P1P0_DN<1>")
	)
	(segment
		(start 90.494866 -217.06459)
		(end 90.494612 -217.064336)
		(width 0.13208)
		(layer "F.Cu")
		(net "UPI_CPU0_CPU1_P1P0_DN<1>")
	)
	(segment
		(start 380.725934 -218.692476)
		(end 380.72568 -218.692222)
		(width 0.13208)
		(layer "F.Cu")
		(net "UPI_CPU0_CPU1_P1P0_DN<1>")
	)
	(segment
		(start 123.559316 -162.425888)
		(end 102.545388 -182.185818)
		(width 0.14732)
		(layer "In4.Cu")
		(net "UPI_CPU0_CPU1_P1P0_DN<1>")
	)
	(segment
		(start 385.329938 -206.509874)
		(end 385.329938 -205.204568)
		(width 0.14732)
		(layer "In4.Cu")
		(net "UPI_CPU0_CPU1_P1P0_DN<1>")
	)
	(segment
		(start 88.211406 -208.996534)
		(end 88.41613 -208.996534)
		(width 0.14732)
		(layer "In4.Cu")
		(net "UPI_CPU0_CPU1_P1P0_DN<1>")
	)
	(segment
		(start 90.308176 -216.73947)
		(end 90.307414 -216.739978)
		(width 0.0889)
		(layer "In4.Cu")
		(net "UPI_CPU0_CPU1_P1P0_DN<1>")
	)
	(segment
		(start 90.120216 -212.985604)
		(end 90.21953 -213.084918)
		(width 0.0889)
		(layer "In4.Cu")
		(net "UPI_CPU0_CPU1_P1P0_DN<1>")
	)
	(segment
		(start 88.41613 -208.996534)
		(end 88.676734 -209.257138)
		(width 0.14732)
		(layer "In4.Cu")
		(net "UPI_CPU0_CPU1_P1P0_DN<1>")
	)
	(segment
		(start 366.462818 -166.026338)
		(end 366.178846 -165.791134)
		(width 0.14732)
		(layer "In4.Cu")
		(net "UPI_CPU0_CPU1_P1P0_DN<1>")
	)
	(segment
		(start 86.63432 -207.419448)
		(end 87.354156 -208.139284)
		(width 0.14732)
		(layer "In4.Cu")
		(net "UPI_CPU0_CPU1_P1P0_DN<1>")
	)
	(segment
		(start 87.819484 -208.604612)
		(end 88.211406 -208.996534)
		(width 0.14732)
		(layer "In4.Cu")
		(net "UPI_CPU0_CPU1_P1P0_DN<1>")
	)
	(segment
		(start 383.11328 -202.293728)
		(end 376.214132 -171.324016)
		(width 0.14732)
		(layer "In4.Cu")
		(net "UPI_CPU0_CPU1_P1P0_DN<1>")
	)
	(segment
		(start 366.666526 -166.007288)
		(end 366.462818 -166.026338)
		(width 0.14732)
		(layer "In4.Cu")
		(net "UPI_CPU0_CPU1_P1P0_DN<1>")
	)
	(segment
		(start 382.04394 -213.723728)
		(end 382.04394 -211.967318)
		(width 0.0889)
		(layer "In4.Cu")
		(net "UPI_CPU0_CPU1_P1P0_DN<1>")
	)
	(segment
		(start 360.975148 -161.290762)
		(end 331.335634 -142.257272)
		(width 0.14732)
		(layer "In4.Cu")
		(net "UPI_CPU0_CPU1_P1P0_DN<1>")
	)
	(segment
		(start 369.486434 -168.187878)
		(end 369.0239 -167.960548)
		(width 0.14732)
		(layer "In4.Cu")
		(net "UPI_CPU0_CPU1_P1P0_DN<1>")
	)
	(segment
		(start 90.21953 -212.35289)
		(end 90.21953 -212.61959)
		(width 0.0889)
		(layer "In4.Cu")
		(net "UPI_CPU0_CPU1_P1P0_DN<1>")
	)
	(segment
		(start 382.00203 -211.925408)
		(end 382.00203 -211.90331)
		(width 0.0889)
		(layer "In4.Cu")
		(net "UPI_CPU0_CPU1_P1P0_DN<1>")
	)
	(segment
		(start 90.26017 -217.356182)
		(end 90.338148 -217.335354)
		(width 0.0889)
		(layer "In4.Cu")
		(net "UPI_CPU0_CPU1_P1P0_DN<1>")
	)
	(segment
		(start 90.16238 -211.78139)
		(end 90.16238 -211.803488)
		(width 0.0889)
		(layer "In4.Cu")
		(net "UPI_CPU0_CPU1_P1P0_DN<1>")
	)
	(segment
		(start 380.630684 -217.8939)
		(end 380.630684 -217.859864)
		(width 0.0889)
		(layer "In4.Cu")
		(net "UPI_CPU0_CPU1_P1P0_DN<1>")
	)
	(segment
		(start 372.745254 -168.618408)
		(end 371.994684 -168.38295)
		(width 0.14732)
		(layer "In4.Cu")
		(net "UPI_CPU0_CPU1_P1P0_DN<1>")
	)
	(segment
		(start 381.383032 -214.946992)
		(end 381.413004 -214.92972)
		(width 0.0889)
		(layer "In4.Cu")
		(net "UPI_CPU0_CPU1_P1P0_DN<1>")
	)
	(segment
		(start 365.5695 -165.285928)
		(end 365.285528 -165.050724)
		(width 0.14732)
		(layer "In4.Cu")
		(net "UPI_CPU0_CPU1_P1P0_DN<1>")
	)
	(segment
		(start 160.011872 -140.004546)
		(end 123.559316 -162.425888)
		(width 0.14732)
		(layer "In4.Cu")
		(net "UPI_CPU0_CPU1_P1P0_DN<1>")
	)
	(segment
		(start 89.37244 -209.952844)
		(end 89.633044 -210.213448)
		(width 0.14732)
		(layer "In4.Cu")
		(net "UPI_CPU0_CPU1_P1P0_DN<1>")
	)
	(segment
		(start 364.983014 -164.612066)
		(end 364.779052 -164.631116)
		(width 0.14732)
		(layer "In4.Cu")
		(net "UPI_CPU0_CPU1_P1P0_DN<1>")
	)
	(segment
		(start 316.042802 -139.146788)
		(end 271.344136 -137.26795)
		(width 0.14732)
		(layer "In4.Cu")
		(net "UPI_CPU0_CPU1_P1P0_DN<1>")
	)
	(segment
		(start 90.120216 -212.253576)
		(end 90.21953 -212.35289)
		(width 0.0889)
		(layer "In4.Cu")
		(net "UPI_CPU0_CPU1_P1P0_DN<1>")
	)
	(segment
		(start 86.347808 -206.80299)
		(end 86.63432 -207.419448)
		(width 0.14732)
		(layer "In4.Cu")
		(net "UPI_CPU0_CPU1_P1P0_DN<1>")
	)
	(segment
		(start 375.883678 -170.828462)
		(end 372.745254 -168.618408)
		(width 0.14732)
		(layer "In4.Cu")
		(net "UPI_CPU0_CPU1_P1P0_DN<1>")
	)
	(segment
		(start 366.967516 -166.256716)
		(end 366.666526 -166.007288)
		(width 0.14732)
		(layer "In4.Cu")
		(net "UPI_CPU0_CPU1_P1P0_DN<1>")
	)
	(segment
		(start 367.4745 -166.676578)
		(end 367.270538 -166.695882)
		(width 0.14732)
		(layer "In4.Cu")
		(net "UPI_CPU0_CPU1_P1P0_DN<1>")
	)
	(segment
		(start 365.266478 -164.847016)
		(end 364.983014 -164.612066)
		(width 0.14732)
		(layer "In4.Cu")
		(net "UPI_CPU0_CPU1_P1P0_DN<1>")
	)
	(segment
		(start 382.001776 -211.6074)
		(end 382.001776 -210.414616)
		(width 0.14732)
		(layer "In4.Cu")
		(net "UPI_CPU0_CPU1_P1P0_DN<1>")
	)
	(segment
		(start 366.178846 -165.791134)
		(end 366.159796 -165.587172)
		(width 0.14732)
		(layer "In4.Cu")
		(net "UPI_CPU0_CPU1_P1P0_DN<1>")
	)
	(segment
		(start 381.10033 -215.445086)
		(end 381.10033 -215.43645)
		(width 0.0889)
		(layer "In4.Cu")
		(net "UPI_CPU0_CPU1_P1P0_DN<1>")
	)
	(segment
		(start 90.298524 -215.755982)
		(end 90.300556 -215.757252)
		(width 0.0889)
		(layer "In4.Cu")
		(net "UPI_CPU0_CPU1_P1P0_DN<1>")
	)
	(segment
		(start 89.633044 -210.418172)
		(end 90.162126 -210.947254)
		(width 0.14732)
		(layer "In4.Cu")
		(net "UPI_CPU0_CPU1_P1P0_DN<1>")
	)
	(segment
		(start 90.306652 -215.111838)
		(end 90.306398 -215.112854)
		(width 0.0889)
		(layer "In4.Cu")
		(net "UPI_CPU0_CPU1_P1P0_DN<1>")
	)
	(segment
		(start 90.120216 -213.450932)
		(end 90.120216 -213.893908)
		(width 0.0889)
		(layer "In4.Cu")
		(net "UPI_CPU0_CPU1_P1P0_DN<1>")
	)
	(segment
		(start 90.309954 -215.762586)
		(end 90.31351 -215.764618)
		(width 0.0889)
		(layer "In4.Cu")
		(net "UPI_CPU0_CPU1_P1P0_DN<1>")
	)
	(segment
		(start 365.773208 -165.266878)
		(end 365.5695 -165.285928)
		(width 0.14732)
		(layer "In4.Cu")
		(net "UPI_CPU0_CPU1_P1P0_DN<1>")
	)
	(segment
		(start 365.285528 -165.050724)
		(end 365.266478 -164.847016)
		(width 0.14732)
		(layer "In4.Cu")
		(net "UPI_CPU0_CPU1_P1P0_DN<1>")
	)
	(segment
		(start 90.162126 -211.630768)
		(end 90.16238 -211.631022)
		(width 0.14732)
		(layer "In4.Cu")
		(net "UPI_CPU0_CPU1_P1P0_DN<1>")
	)
	(segment
		(start 90.21953 -212.61959)
		(end 90.120216 -212.718904)
		(width 0.0889)
		(layer "In4.Cu")
		(net "UPI_CPU0_CPU1_P1P0_DN<1>")
	)
	(segment
		(start 87.55888 -208.139284)
		(end 87.819484 -208.399888)
		(width 0.14732)
		(layer "In4.Cu")
		(net "UPI_CPU0_CPU1_P1P0_DN<1>")
	)
	(segment
		(start 382.00203 -211.607654)
		(end 382.001776 -211.6074)
		(width 0.14732)
		(layer "In4.Cu")
		(net "UPI_CPU0_CPU1_P1P0_DN<1>")
	)
	(segment
		(start 364.476284 -164.19195)
		(end 360.975148 -161.290762)
		(width 0.14732)
		(layer "In4.Cu")
		(net "UPI_CPU0_CPU1_P1P0_DN<1>")
	)
	(segment
		(start 169.571416 -136.731756)
		(end 160.011872 -140.004546)
		(width 0.14732)
		(layer "In4.Cu")
		(net "UPI_CPU0_CPU1_P1P0_DN<1>")
	)
	(segment
		(start 381.10033 -217.072972)
		(end 381.10033 -217.0557)
		(width 0.0889)
		(layer "In4.Cu")
		(net "UPI_CPU0_CPU1_P1P0_DN<1>")
	)
	(segment
		(start 380.882144 -218.421204)
		(end 380.858014 -218.33205)
		(width 0.0889)
		(layer "In4.Cu")
		(net "UPI_CPU0_CPU1_P1P0_DN<1>")
	)
	(segment
		(start 368.5159 -167.53967)
		(end 368.312192 -167.55872)
		(width 0.14732)
		(layer "In4.Cu")
		(net "UPI_CPU0_CPU1_P1P0_DN<1>")
	)
	(segment
		(start 86.3219 -205.989428)
		(end 86.347808 -206.80299)
		(width 0.14732)
		(layer "In4.Cu")
		(net "UPI_CPU0_CPU1_P1P0_DN<1>")
	)
	(segment
		(start 90.120216 -217.0557)
		(end 90.120216 -217.072972)
		(width 0.0889)
		(layer "In4.Cu")
		(net "UPI_CPU0_CPU1_P1P0_DN<1>")
	)
	(segment
		(start 89.167716 -209.952844)
		(end 89.37244 -209.952844)
		(width 0.14732)
		(layer "In4.Cu")
		(net "UPI_CPU0_CPU1_P1P0_DN<1>")
	)
	(segment
		(start 90.306398 -215.112854)
		(end 90.298524 -215.117426)
		(width 0.0889)
		(layer "In4.Cu")
		(net "UPI_CPU0_CPU1_P1P0_DN<1>")
	)
	(segment
		(start 376.214132 -171.324016)
		(end 375.883678 -170.828462)
		(width 0.14732)
		(layer "In4.Cu")
		(net "UPI_CPU0_CPU1_P1P0_DN<1>")
	)
	(segment
		(start 90.307414 -215.761062)
		(end 90.309954 -215.762586)
		(width 0.0889)
		(layer "In4.Cu")
		(net "UPI_CPU0_CPU1_P1P0_DN<1>")
	)
	(segment
		(start 382.04394 -211.967318)
		(end 382.00203 -211.925408)
		(width 0.0889)
		(layer "In4.Cu")
		(net "UPI_CPU0_CPU1_P1P0_DN<1>")
	)
	(segment
		(start 90.162126 -210.947254)
		(end 90.162126 -211.630768)
		(width 0.14732)
		(layer "In4.Cu")
		(net "UPI_CPU0_CPU1_P1P0_DN<1>")
	)
	(segment
		(start 364.779052 -164.631116)
		(end 364.495334 -164.395912)
		(width 0.14732)
		(layer "In4.Cu")
		(net "UPI_CPU0_CPU1_P1P0_DN<1>")
	)
	(segment
		(start 90.16238 -211.803488)
		(end 90.120216 -211.845652)
		(width 0.0889)
		(layer "In4.Cu")
		(net "UPI_CPU0_CPU1_P1P0_DN<1>")
	)
	(segment
		(start 364.495334 -164.395912)
		(end 364.476284 -164.19195)
		(width 0.14732)
		(layer "In4.Cu")
		(net "UPI_CPU0_CPU1_P1P0_DN<1>")
	)
	(segment
		(start 89.633044 -210.213448)
		(end 89.633044 -210.418172)
		(width 0.14732)
		(layer "In4.Cu")
		(net "UPI_CPU0_CPU1_P1P0_DN<1>")
	)
	(segment
		(start 238.60252 -137.865612)
		(end 169.571416 -136.731756)
		(width 0.14732)
		(layer "In4.Cu")
		(net "UPI_CPU0_CPU1_P1P0_DN<1>")
	)
	(segment
		(start 368.00917 -167.119808)
		(end 367.4745 -166.676578)
		(width 0.14732)
		(layer "In4.Cu")
		(net "UPI_CPU0_CPU1_P1P0_DN<1>")
	)
	(segment
		(start 90.16238 -211.631022)
		(end 90.16238 -211.78139)
		(width 0.14732)
		(layer "In4.Cu")
		(net "UPI_CPU0_CPU1_P1P0_DN<1>")
	)
	(segment
		(start 88.676734 -209.257138)
		(end 88.676734 -209.461862)
		(width 0.14732)
		(layer "In4.Cu")
		(net "UPI_CPU0_CPU1_P1P0_DN<1>")
	)
	(segment
		(start 368.312192 -167.55872)
		(end 368.028474 -167.323516)
		(width 0.14732)
		(layer "In4.Cu")
		(net "UPI_CPU0_CPU1_P1P0_DN<1>")
	)
	(segment
		(start 385.329938 -205.204568)
		(end 383.11328 -202.293728)
		(width 0.14732)
		(layer "In4.Cu")
		(net "UPI_CPU0_CPU1_P1P0_DN<1>")
	)
	(segment
		(start 381.376936 -214.950548)
		(end 381.383032 -214.946992)
		(width 0.0889)
		(layer "In4.Cu")
		(net "UPI_CPU0_CPU1_P1P0_DN<1>")
	)
	(segment
		(start 271.344136 -137.26795)
		(end 238.60252 -137.865612)
		(width 0.14732)
		(layer "In4.Cu")
		(net "UPI_CPU0_CPU1_P1P0_DN<1>")
	)
	(segment
		(start 102.545388 -182.185818)
		(end 98.85807 -186.774836)
		(width 0.14732)
		(layer "In4.Cu")
		(net "UPI_CPU0_CPU1_P1P0_DN<1>")
	)
	(segment
		(start 381.818134 -214.077042)
		(end 381.852678 -214.056976)
		(width 0.0889)
		(layer "In4.Cu")
		(net "UPI_CPU0_CPU1_P1P0_DN<1>")
	)
	(segment
		(start 90.21953 -213.084918)
		(end 90.21953 -213.351618)
		(width 0.0889)
		(layer "In4.Cu")
		(net "UPI_CPU0_CPU1_P1P0_DN<1>")
	)
	(segment
		(start 98.85807 -186.774836)
		(end 96.543876 -192.929002)
		(width 0.14732)
		(layer "In4.Cu")
		(net "UPI_CPU0_CPU1_P1P0_DN<1>")
	)
	(segment
		(start 380.630684 -216.260426)
		(end 380.630684 -216.231978)
		(width 0.0889)
		(layer "In4.Cu")
		(net "UPI_CPU0_CPU1_P1P0_DN<1>")
	)
	(segment
		(start 86.53272 -204.826108)
		(end 86.3219 -205.989428)
		(width 0.14732)
		(layer "In4.Cu")
		(net "UPI_CPU0_CPU1_P1P0_DN<1>")
	)
	(segment
		(start 380.72568 -218.692222)
		(end 380.882144 -218.421204)
		(width 0.0889)
		(layer "In4.Cu")
		(net "UPI_CPU0_CPU1_P1P0_DN<1>")
	)
	(segment
		(start 90.31351 -216.736422)
		(end 90.308176 -216.73947)
		(width 0.0889)
		(layer "In4.Cu")
		(net "UPI_CPU0_CPU1_P1P0_DN<1>")
	)
	(segment
		(start 381.930656 -213.997794)
		(end 382.04394 -213.723728)
		(width 0.0889)
		(layer "In4.Cu")
		(net "UPI_CPU0_CPU1_P1P0_DN<1>")
	)
	(segment
		(start 331.335634 -142.257272)
		(end 318.631062 -139.146788)
		(width 0.14732)
		(layer "In4.Cu")
		(net "UPI_CPU0_CPU1_P1P0_DN<1>")
	)
	(segment
		(start 371.994684 -168.38295)
		(end 369.486434 -168.187878)
		(width 0.14732)
		(layer "In4.Cu")
		(net "UPI_CPU0_CPU1_P1P0_DN<1>")
	)
	(segment
		(start 382.00203 -211.90331)
		(end 382.00203 -211.607654)
		(width 0.14732)
		(layer "In4.Cu")
		(net "UPI_CPU0_CPU1_P1P0_DN<1>")
	)
	(segment
		(start 88.676734 -209.461862)
		(end 89.167716 -209.952844)
		(width 0.14732)
		(layer "In4.Cu")
		(net "UPI_CPU0_CPU1_P1P0_DN<1>")
	)
	(segment
		(start 90.307414 -215.112346)
		(end 90.306652 -215.111838)
		(width 0.0889)
		(layer "In4.Cu")
		(net "UPI_CPU0_CPU1_P1P0_DN<1>")
	)
	(segment
		(start 87.819484 -208.399888)
		(end 87.819484 -208.604612)
		(width 0.14732)
		(layer "In4.Cu")
		(net "UPI_CPU0_CPU1_P1P0_DN<1>")
	)
	(segment
		(start 96.543876 -192.929002)
		(end 86.53272 -204.826108)
		(width 0.14732)
		(layer "In4.Cu")
		(net "UPI_CPU0_CPU1_P1P0_DN<1>")
	)
	(segment
		(start 87.354156 -208.139284)
		(end 87.55888 -208.139284)
		(width 0.14732)
		(layer "In4.Cu")
		(net "UPI_CPU0_CPU1_P1P0_DN<1>")
	)
	(segment
		(start 368.028474 -167.323516)
		(end 368.00917 -167.119808)
		(width 0.14732)
		(layer "In4.Cu")
		(net "UPI_CPU0_CPU1_P1P0_DN<1>")
	)
	(segment
		(start 90.120216 -211.845652)
		(end 90.120216 -212.253576)
		(width 0.0889)
		(layer "In4.Cu")
		(net "UPI_CPU0_CPU1_P1P0_DN<1>")
	)
	(segment
		(start 366.986566 -166.460678)
		(end 366.967516 -166.256716)
		(width 0.14732)
		(layer "In4.Cu")
		(net "UPI_CPU0_CPU1_P1P0_DN<1>")
	)
	(segment
		(start 369.0239 -167.960548)
		(end 368.5159 -167.53967)
		(width 0.14732)
		(layer "In4.Cu")
		(net "UPI_CPU0_CPU1_P1P0_DN<1>")
	)
	(segment
		(start 90.589608 -214.424768)
		(end 90.589608 -214.644732)
		(width 0.0889)
		(layer "In4.Cu")
		(net "UPI_CPU0_CPU1_P1P0_DN<1>")
	)
	(segment
		(start 384.922014 -207.494378)
		(end 385.329938 -206.509874)
		(width 0.14732)
		(layer "In4.Cu")
		(net "UPI_CPU0_CPU1_P1P0_DN<1>")
	)
	(segment
		(start 318.631062 -139.146788)
		(end 316.042802 -139.146788)
		(width 0.14732)
		(layer "In4.Cu")
		(net "UPI_CPU0_CPU1_P1P0_DN<1>")
	)
	(segment
		(start 382.001776 -210.414616)
		(end 384.922014 -207.494378)
		(width 0.14732)
		(layer "In4.Cu")
		(net "UPI_CPU0_CPU1_P1P0_DN<1>")
	)
	(segment
		(start 90.338148 -217.335354)
		(end 90.494612 -217.064336)
		(width 0.0889)
		(layer "In4.Cu")
		(net "UPI_CPU0_CPU1_P1P0_DN<1>")
	)
	(segment
		(start 90.300556 -215.757252)
		(end 90.307414 -215.761062)
		(width 0.0889)
		(layer "In4.Cu")
		(net "UPI_CPU0_CPU1_P1P0_DN<1>")
	)
	(segment
		(start 367.270538 -166.695882)
		(end 366.986566 -166.460678)
		(width 0.14732)
		(layer "In4.Cu")
		(net "UPI_CPU0_CPU1_P1P0_DN<1>")
	)
	(segment
		(start 366.159796 -165.587172)
		(end 365.773208 -165.266878)
		(width 0.14732)
		(layer "In4.Cu")
		(net "UPI_CPU0_CPU1_P1P0_DN<1>")
	)
	(segment
		(start 90.120216 -212.718904)
		(end 90.120216 -212.985604)
		(width 0.0889)
		(layer "In4.Cu")
		(net "UPI_CPU0_CPU1_P1P0_DN<1>")
	)
	(segment
		(start 90.21953 -213.351618)
		(end 90.120216 -213.450932)
		(width 0.0889)
		(layer "In4.Cu")
		(net "UPI_CPU0_CPU1_P1P0_DN<1>")
	)
	(arc
		(start 381.852678 -214.056976)
		(mid 381.893608 -214.029943)
		(end 381.930656 -213.997794)
		(width 0.0889)
		(layer "In4.Cu")
		(net "UPI_CPU0_CPU1_P1P0_DN<1>")
	)
	(arc
		(start 90.31351 -215.764618)
		(mid 90.590084 -216.25052)
		(end 90.31351 -216.736422)
		(width 0.0889)
		(layer "In4.Cu")
		(net "UPI_CPU0_CPU1_P1P0_DN<1>")
	)
	(arc
		(start 380.913132 -216.739978)
		(mid 380.708797 -216.537373)
		(end 380.630684 -216.260426)
		(width 0.0889)
		(layer "In4.Cu")
		(net "UPI_CPU0_CPU1_P1P0_DN<1>")
	)
	(arc
		(start 380.913132 -217.388694)
		(mid 381.048065 -217.25534)
		(end 381.10033 -217.072972)
		(width 0.0889)
		(layer "In4.Cu")
		(net "UPI_CPU0_CPU1_P1P0_DN<1>")
	)
	(arc
		(start 90.120216 -217.072972)
		(mid 90.15889 -217.23004)
		(end 90.26017 -217.356182)
		(width 0.0889)
		(layer "In4.Cu")
		(net "UPI_CPU0_CPU1_P1P0_DN<1>")
	)
	(arc
		(start 381.10033 -215.43645)
		(mid 381.174321 -215.156884)
		(end 381.376936 -214.950548)
		(width 0.0889)
		(layer "In4.Cu")
		(net "UPI_CPU0_CPU1_P1P0_DN<1>")
	)
	(arc
		(start 90.298524 -215.117426)
		(mid 90.17127 -215.247392)
		(end 90.120216 -215.421972)
		(width 0.0889)
		(layer "In4.Cu")
		(net "UPI_CPU0_CPU1_P1P0_DN<1>")
	)
	(arc
		(start 90.119962 -215.436704)
		(mid 90.167641 -215.619604)
		(end 90.298524 -215.755982)
		(width 0.0889)
		(layer "In4.Cu")
		(net "UPI_CPU0_CPU1_P1P0_DN<1>")
	)
	(arc
		(start 90.120216 -213.893908)
		(mid 90.195221 -214.009367)
		(end 90.304366 -214.093298)
		(width 0.0889)
		(layer "In4.Cu")
		(net "UPI_CPU0_CPU1_P1P0_DN<1>")
	)
	(arc
		(start 380.913132 -215.760808)
		(mid 381.048065 -215.627454)
		(end 381.10033 -215.445086)
		(width 0.0889)
		(layer "In4.Cu")
		(net "UPI_CPU0_CPU1_P1P0_DN<1>")
	)
	(arc
		(start 380.630684 -217.859864)
		(mid 380.710846 -217.587675)
		(end 380.913132 -217.388694)
		(width 0.0889)
		(layer "In4.Cu")
		(net "UPI_CPU0_CPU1_P1P0_DN<1>")
	)
	(arc
		(start 381.413004 -214.92972)
		(mid 381.536542 -214.781953)
		(end 381.570738 -214.592408)
		(width 0.0889)
		(layer "In4.Cu")
		(net "UPI_CPU0_CPU1_P1P0_DN<1>")
	)
	(arc
		(start 380.84125 -218.319096)
		(mid 380.689168 -218.129664)
		(end 380.630684 -217.8939)
		(width 0.0889)
		(layer "In4.Cu")
		(net "UPI_CPU0_CPU1_P1P0_DN<1>")
	)
	(arc
		(start 381.570738 -214.592408)
		(mid 381.624663 -214.30122)
		(end 381.818134 -214.077042)
		(width 0.0889)
		(layer "In4.Cu")
		(net "UPI_CPU0_CPU1_P1P0_DN<1>")
	)
	(arc
		(start 380.630684 -216.231978)
		(mid 380.710846 -215.959789)
		(end 380.913132 -215.760808)
		(width 0.0889)
		(layer "In4.Cu")
		(net "UPI_CPU0_CPU1_P1P0_DN<1>")
	)
	(arc
		(start 90.120216 -215.421972)
		(mid 90.120019 -215.429337)
		(end 90.119962 -215.436704)
		(width 0.0889)
		(layer "In4.Cu")
		(net "UPI_CPU0_CPU1_P1P0_DN<1>")
	)
	(arc
		(start 381.10033 -217.0557)
		(mid 381.04806 -216.873335)
		(end 380.913132 -216.739978)
		(width 0.0889)
		(layer "In4.Cu")
		(net "UPI_CPU0_CPU1_P1P0_DN<1>")
	)
	(arc
		(start 90.307414 -216.739978)
		(mid 90.172481 -216.873332)
		(end 90.120216 -217.0557)
		(width 0.0889)
		(layer "In4.Cu")
		(net "UPI_CPU0_CPU1_P1P0_DN<1>")
	)
	(arc
		(start 90.589608 -214.644732)
		(mid 90.508697 -214.91486)
		(end 90.307414 -215.112346)
		(width 0.0889)
		(layer "In4.Cu")
		(net "UPI_CPU0_CPU1_P1P0_DN<1>")
	)
	(arc
		(start 90.304366 -214.093298)
		(mid 90.478329 -214.232062)
		(end 90.589608 -214.424768)
		(width 0.0889)
		(layer "In4.Cu")
		(net "UPI_CPU0_CPU1_P1P0_DN<1>")
	)
	(arc
		(start 380.858014 -218.33205)
		(mid 380.849573 -218.32565)
		(end 380.84125 -218.319096)
		(width 0.0889)
		(layer "In4.Cu")
		(net "UPI_CPU0_CPU1_P1P0_DN<1>")
	)
	(segment
		(start 363.809534 -218.692476)
		(end 363.80928 -218.692222)
		(width 0.13208)
		(layer "F.Cu")
		(net "UPI_CPU0_CPU1_P1P0_DN<19>")
	)
	(segment
		(start 107.411266 -217.600276)
		(end 107.411266 -217.06459)
		(width 0.13208)
		(layer "F.Cu")
		(net "UPI_CPU0_CPU1_P1P0_DN<19>")
	)
	(segment
		(start 107.411266 -217.06459)
		(end 107.411012 -217.064336)
		(width 0.13208)
		(layer "F.Cu")
		(net "UPI_CPU0_CPU1_P1P0_DN<19>")
	)
	(segment
		(start 363.809534 -219.228162)
		(end 363.809534 -218.692476)
		(width 0.13208)
		(layer "F.Cu")
		(net "UPI_CPU0_CPU1_P1P0_DN<19>")
	)
	(segment
		(start 166.94658 -154.127962)
		(end 165.23081 -154.727148)
		(width 0.14732)
		(layer "In4.Cu")
		(net "UPI_CPU0_CPU1_P1P0_DN<19>")
	)
	(segment
		(start 107.224576 -216.73947)
		(end 107.223814 -216.739978)
		(width 0.0889)
		(layer "In4.Cu")
		(net "UPI_CPU0_CPU1_P1P0_DN<19>")
	)
	(segment
		(start 310.541924 -164.593016)
		(end 310.239918 -164.279326)
		(width 0.14732)
		(layer "In4.Cu")
		(net "UPI_CPU0_CPU1_P1P0_DN<19>")
	)
	(segment
		(start 309.042054 -164.56279)
		(end 308.224936 -164.545518)
		(width 0.14732)
		(layer "In4.Cu")
		(net "UPI_CPU0_CPU1_P1P0_DN<19>")
	)
	(segment
		(start 311.359042 -164.610288)
		(end 310.541924 -164.593016)
		(width 0.14732)
		(layer "In4.Cu")
		(net "UPI_CPU0_CPU1_P1P0_DN<19>")
	)
	(segment
		(start 311.712356 -162.375596)
		(end 311.672986 -164.308282)
		(width 0.14732)
		(layer "In4.Cu")
		(net "UPI_CPU0_CPU1_P1P0_DN<19>")
	)
	(segment
		(start 310.279542 -162.346894)
		(end 310.13527 -162.196526)
		(width 0.14732)
		(layer "In4.Cu")
		(net "UPI_CPU0_CPU1_P1P0_DN<19>")
	)
	(segment
		(start 107.222798 -215.112854)
		(end 107.214924 -215.117426)
		(width 0.0889)
		(layer "In4.Cu")
		(net "UPI_CPU0_CPU1_P1P0_DN<19>")
	)
	(segment
		(start 304.722022 -164.165788)
		(end 304.408078 -164.467794)
		(width 0.14732)
		(layer "In4.Cu")
		(net "UPI_CPU0_CPU1_P1P0_DN<19>")
	)
	(segment
		(start 108.921296 -206.530956)
		(end 108.795058 -206.877412)
		(width 0.14732)
		(layer "In4.Cu")
		(net "UPI_CPU0_CPU1_P1P0_DN<19>")
	)
	(segment
		(start 309.545228 -162.184334)
		(end 309.395368 -162.328098)
		(width 0.14732)
		(layer "In4.Cu")
		(net "UPI_CPU0_CPU1_P1P0_DN<19>")
	)
	(segment
		(start 304.911252 -162.089338)
		(end 304.761392 -162.233102)
		(width 0.14732)
		(layer "In4.Cu")
		(net "UPI_CPU0_CPU1_P1P0_DN<19>")
	)
	(segment
		(start 107.226608 -215.76284)
		(end 107.22991 -215.764618)
		(width 0.0889)
		(layer "In4.Cu")
		(net "UPI_CPU0_CPU1_P1P0_DN<19>")
	)
	(segment
		(start 108.443776 -207.841596)
		(end 108.258102 -207.927956)
		(width 0.14732)
		(layer "In4.Cu")
		(net "UPI_CPU0_CPU1_P1P0_DN<19>")
	)
	(segment
		(start 109.14634 -205.913228)
		(end 108.960666 -205.999588)
		(width 0.14732)
		(layer "In4.Cu")
		(net "UPI_CPU0_CPU1_P1P0_DN<19>")
	)
	(segment
		(start 305.907948 -164.49802)
		(end 305.605942 -164.18433)
		(width 0.14732)
		(layer "In4.Cu")
		(net "UPI_CPU0_CPU1_P1P0_DN<19>")
	)
	(segment
		(start 172.191426 -155.565602)
		(end 169.421302 -154.194002)
		(width 0.14732)
		(layer "In4.Cu")
		(net "UPI_CPU0_CPU1_P1P0_DN<19>")
	)
	(segment
		(start 169.421302 -154.194002)
		(end 166.94658 -154.127962)
		(width 0.14732)
		(layer "In4.Cu")
		(net "UPI_CPU0_CPU1_P1P0_DN<19>")
	)
	(segment
		(start 364.142528 -211.328254)
		(end 364.142274 -211.328)
		(width 0.14732)
		(layer "In4.Cu")
		(net "UPI_CPU0_CPU1_P1P0_DN<19>")
	)
	(segment
		(start 194.73291 -164.800788)
		(end 189.843664 -164.800788)
		(width 0.14732)
		(layer "In4.Cu")
		(net "UPI_CPU0_CPU1_P1P0_DN<19>")
	)
	(segment
		(start 107.036362 -212.81644)
		(end 107.036362 -213.0171)
		(width 0.0889)
		(layer "In4.Cu")
		(net "UPI_CPU0_CPU1_P1P0_DN<19>")
	)
	(segment
		(start 312.858912 -164.640768)
		(end 312.556906 -164.326824)
		(width 0.14732)
		(layer "In4.Cu")
		(net "UPI_CPU0_CPU1_P1P0_DN<19>")
	)
	(segment
		(start 108.4834 -207.30972)
		(end 108.570014 -207.49514)
		(width 0.14732)
		(layer "In4.Cu")
		(net "UPI_CPU0_CPU1_P1P0_DN<19>")
	)
	(segment
		(start 107.214924 -215.755982)
		(end 107.216956 -215.757252)
		(width 0.0889)
		(layer "In4.Cu")
		(net "UPI_CPU0_CPU1_P1P0_DN<19>")
	)
	(segment
		(start 107.135422 -212.71738)
		(end 107.036362 -212.81644)
		(width 0.0889)
		(layer "In4.Cu")
		(net "UPI_CPU0_CPU1_P1P0_DN<19>")
	)
	(segment
		(start 108.570014 -207.49514)
		(end 108.443776 -207.841596)
		(width 0.14732)
		(layer "In4.Cu")
		(net "UPI_CPU0_CPU1_P1P0_DN<19>")
	)
	(segment
		(start 234.434126 -154.920188)
		(end 197.421246 -164.462206)
		(width 0.14732)
		(layer "In4.Cu")
		(net "UPI_CPU0_CPU1_P1P0_DN<19>")
	)
	(segment
		(start 311.672986 -164.308282)
		(end 311.359042 -164.610288)
		(width 0.14732)
		(layer "In4.Cu")
		(net "UPI_CPU0_CPU1_P1P0_DN<19>")
	)
	(segment
		(start 312.556906 -164.326824)
		(end 312.59653 -162.394392)
		(width 0.14732)
		(layer "In4.Cu")
		(net "UPI_CPU0_CPU1_P1P0_DN<19>")
	)
	(segment
		(start 307.03901 -164.213286)
		(end 306.725066 -164.515292)
		(width 0.14732)
		(layer "In4.Cu")
		(net "UPI_CPU0_CPU1_P1P0_DN<19>")
	)
	(segment
		(start 309.395368 -162.328098)
		(end 309.355998 -164.260784)
		(width 0.14732)
		(layer "In4.Cu")
		(net "UPI_CPU0_CPU1_P1P0_DN<19>")
	)
	(segment
		(start 305.605942 -164.18433)
		(end 305.645566 -162.251898)
		(width 0.14732)
		(layer "In4.Cu")
		(net "UPI_CPU0_CPU1_P1P0_DN<19>")
	)
	(segment
		(start 280.844244 -164.789104)
		(end 280.844244 -164.803328)
		(width 0.14732)
		(layer "In4.Cu")
		(net "UPI_CPU0_CPU1_P1P0_DN<19>")
	)
	(segment
		(start 314.808108 -164.679884)
		(end 312.858912 -164.640768)
		(width 0.14732)
		(layer "In4.Cu")
		(net "UPI_CPU0_CPU1_P1P0_DN<19>")
	)
	(segment
		(start 276.255226 -164.803328)
		(end 237.77702 -154.920188)
		(width 0.14732)
		(layer "In4.Cu")
		(net "UPI_CPU0_CPU1_P1P0_DN<19>")
	)
	(segment
		(start 349.205042 -178.591464)
		(end 348.43466 -178.700176)
		(width 0.14732)
		(layer "In4.Cu")
		(net "UPI_CPU0_CPU1_P1P0_DN<19>")
	)
	(segment
		(start 311.862216 -162.231832)
		(end 311.712356 -162.375596)
		(width 0.14732)
		(layer "In4.Cu")
		(net "UPI_CPU0_CPU1_P1P0_DN<19>")
	)
	(segment
		(start 364.18393 -215.43645)
		(end 364.184184 -215.422226)
		(width 0.0889)
		(layer "In4.Cu")
		(net "UPI_CPU0_CPU1_P1P0_DN<19>")
	)
	(segment
		(start 364.142274 -205.293214)
		(end 358.426004 -191.492378)
		(width 0.14732)
		(layer "In4.Cu")
		(net "UPI_CPU0_CPU1_P1P0_DN<19>")
	)
	(segment
		(start 304.761392 -162.233102)
		(end 304.722022 -164.165788)
		(width 0.14732)
		(layer "In4.Cu")
		(net "UPI_CPU0_CPU1_P1P0_DN<19>")
	)
	(segment
		(start 107.135422 -212.54212)
		(end 107.135422 -212.71738)
		(width 0.0889)
		(layer "In4.Cu")
		(net "UPI_CPU0_CPU1_P1P0_DN<19>")
	)
	(segment
		(start 363.996732 -216.739978)
		(end 363.98454 -216.732866)
		(width 0.0889)
		(layer "In4.Cu")
		(net "UPI_CPU0_CPU1_P1P0_DN<19>")
	)
	(segment
		(start 108.258102 -207.927956)
		(end 108.132118 -208.273904)
		(width 0.14732)
		(layer "In4.Cu")
		(net "UPI_CPU0_CPU1_P1P0_DN<19>")
	)
	(segment
		(start 109.497622 -204.949044)
		(end 109.311948 -205.035404)
		(width 0.14732)
		(layer "In4.Cu")
		(net "UPI_CPU0_CPU1_P1P0_DN<19>")
	)
	(segment
		(start 345.971368 -177.642012)
		(end 345.939618 -177.43932)
		(width 0.14732)
		(layer "In4.Cu")
		(net "UPI_CPU0_CPU1_P1P0_DN<19>")
	)
	(segment
		(start 107.506008 -214.424768)
		(end 107.506008 -214.644732)
		(width 0.0889)
		(layer "In4.Cu")
		(net "UPI_CPU0_CPU1_P1P0_DN<19>")
	)
	(segment
		(start 107.078272 -211.582508)
		(end 107.078526 -211.582762)
		(width 0.14732)
		(layer "In4.Cu")
		(net "UPI_CPU0_CPU1_P1P0_DN<19>")
	)
	(segment
		(start 107.036362 -212.44306)
		(end 107.135422 -212.54212)
		(width 0.0889)
		(layer "In4.Cu")
		(net "UPI_CPU0_CPU1_P1P0_DN<19>")
	)
	(segment
		(start 347.247464 -178.392582)
		(end 346.471494 -177.827178)
		(width 0.14732)
		(layer "In4.Cu")
		(net "UPI_CPU0_CPU1_P1P0_DN<19>")
	)
	(segment
		(start 107.036362 -213.893654)
		(end 107.036616 -213.893908)
		(width 0.0889)
		(layer "In4.Cu")
		(net "UPI_CPU0_CPU1_P1P0_DN<19>")
	)
	(segment
		(start 358.426004 -191.492378)
		(end 357.722424 -190.775336)
		(width 0.14732)
		(layer "In4.Cu")
		(net "UPI_CPU0_CPU1_P1P0_DN<19>")
	)
	(segment
		(start 121.271538 -185.825638)
		(end 112.10798 -197.359778)
		(width 0.14732)
		(layer "In4.Cu")
		(net "UPI_CPU0_CPU1_P1P0_DN<19>")
	)
	(segment
		(start 364.142528 -211.70519)
		(end 364.142528 -211.328254)
		(width 0.14732)
		(layer "In4.Cu")
		(net "UPI_CPU0_CPU1_P1P0_DN<19>")
	)
	(segment
		(start 107.86745 -209.423508)
		(end 107.741212 -209.769964)
		(width 0.14732)
		(layer "In4.Cu")
		(net "UPI_CPU0_CPU1_P1P0_DN<19>")
	)
	(segment
		(start 109.185964 -205.381352)
		(end 109.272578 -205.566772)
		(width 0.14732)
		(layer "In4.Cu")
		(net "UPI_CPU0_CPU1_P1P0_DN<19>")
	)
	(segment
		(start 107.38993 -210.734148)
		(end 107.204256 -210.820508)
		(width 0.14732)
		(layer "In4.Cu")
		(net "UPI_CPU0_CPU1_P1P0_DN<19>")
	)
	(segment
		(start 107.216956 -215.757252)
		(end 107.223814 -215.761062)
		(width 0.0889)
		(layer "In4.Cu")
		(net "UPI_CPU0_CPU1_P1P0_DN<19>")
	)
	(segment
		(start 133.635242 -174.198026)
		(end 121.271538 -185.825638)
		(width 0.14732)
		(layer "In4.Cu")
		(net "UPI_CPU0_CPU1_P1P0_DN<19>")
	)
	(segment
		(start 363.71403 -216.25052)
		(end 363.71403 -216.2429)
		(width 0.0889)
		(layer "In4.Cu")
		(net "UPI_CPU0_CPU1_P1P0_DN<19>")
	)
	(segment
		(start 364.184184 -211.768944)
		(end 364.142528 -211.727288)
		(width 0.0889)
		(layer "In4.Cu")
		(net "UPI_CPU0_CPU1_P1P0_DN<19>")
	)
	(segment
		(start 107.135422 -213.11616)
		(end 107.135422 -213.29142)
		(width 0.0889)
		(layer "In4.Cu")
		(net "UPI_CPU0_CPU1_P1P0_DN<19>")
	)
	(segment
		(start 107.036362 -213.0171)
		(end 107.135422 -213.11616)
		(width 0.0889)
		(layer "In4.Cu")
		(net "UPI_CPU0_CPU1_P1P0_DN<19>")
	)
	(segment
		(start 355.431852 -182.75935)
		(end 351.74174 -179.507388)
		(width 0.14732)
		(layer "In4.Cu")
		(net "UPI_CPU0_CPU1_P1P0_DN<19>")
	)
	(segment
		(start 109.537246 -204.417168)
		(end 109.62386 -204.602588)
		(width 0.14732)
		(layer "In4.Cu")
		(net "UPI_CPU0_CPU1_P1P0_DN<19>")
	)
	(segment
		(start 107.223814 -215.761062)
		(end 107.225338 -215.762078)
		(width 0.0889)
		(layer "In4.Cu")
		(net "UPI_CPU0_CPU1_P1P0_DN<19>")
	)
	(segment
		(start 305.501294 -162.10153)
		(end 304.911252 -162.089338)
		(width 0.14732)
		(layer "In4.Cu")
		(net "UPI_CPU0_CPU1_P1P0_DN<19>")
	)
	(segment
		(start 107.429554 -210.202272)
		(end 107.516168 -210.387692)
		(width 0.14732)
		(layer "In4.Cu")
		(net "UPI_CPU0_CPU1_P1P0_DN<19>")
	)
	(segment
		(start 108.218732 -208.459324)
		(end 108.092494 -208.80578)
		(width 0.14732)
		(layer "In4.Cu")
		(net "UPI_CPU0_CPU1_P1P0_DN<19>")
	)
	(segment
		(start 107.254548 -217.335354)
		(end 107.411012 -217.064336)
		(width 0.0889)
		(layer "In4.Cu")
		(net "UPI_CPU0_CPU1_P1P0_DN<19>")
	)
	(segment
		(start 107.036362 -213.39048)
		(end 107.036362 -213.893654)
		(width 0.0889)
		(layer "In4.Cu")
		(net "UPI_CPU0_CPU1_P1P0_DN<19>")
	)
	(segment
		(start 107.036362 -212.084412)
		(end 107.036362 -212.44306)
		(width 0.0889)
		(layer "In4.Cu")
		(net "UPI_CPU0_CPU1_P1P0_DN<19>")
	)
	(segment
		(start 308.224936 -164.545518)
		(end 307.92293 -164.231828)
		(width 0.14732)
		(layer "In4.Cu")
		(net "UPI_CPU0_CPU1_P1P0_DN<19>")
	)
	(segment
		(start 332.269084 -170.314112)
		(end 323.766942 -167.185594)
		(width 0.14732)
		(layer "In4.Cu")
		(net "UPI_CPU0_CPU1_P1P0_DN<19>")
	)
	(segment
		(start 108.092494 -208.80578)
		(end 107.90682 -208.89214)
		(width 0.14732)
		(layer "In4.Cu")
		(net "UPI_CPU0_CPU1_P1P0_DN<19>")
	)
	(segment
		(start 307.07838 -162.2806)
		(end 307.03901 -164.213286)
		(width 0.14732)
		(layer "In4.Cu")
		(net "UPI_CPU0_CPU1_P1P0_DN<19>")
	)
	(segment
		(start 363.965744 -218.421204)
		(end 363.941614 -218.33205)
		(width 0.0889)
		(layer "In4.Cu")
		(net "UPI_CPU0_CPU1_P1P0_DN<19>")
	)
	(segment
		(start 108.960666 -205.999588)
		(end 108.834682 -206.345536)
		(width 0.14732)
		(layer "In4.Cu")
		(net "UPI_CPU0_CPU1_P1P0_DN<19>")
	)
	(segment
		(start 189.843664 -164.800788)
		(end 172.191426 -155.565602)
		(width 0.14732)
		(layer "In4.Cu")
		(net "UPI_CPU0_CPU1_P1P0_DN<19>")
	)
	(segment
		(start 108.795058 -206.877412)
		(end 108.609384 -206.963772)
		(width 0.14732)
		(layer "In4.Cu")
		(net "UPI_CPU0_CPU1_P1P0_DN<19>")
	)
	(segment
		(start 364.654084 -214.622634)
		(end 364.654084 -214.461852)
		(width 0.0889)
		(layer "In4.Cu")
		(net "UPI_CPU0_CPU1_P1P0_DN<19>")
	)
	(segment
		(start 107.078526 -212.02015)
		(end 107.078526 -212.042248)
		(width 0.0889)
		(layer "In4.Cu")
		(net "UPI_CPU0_CPU1_P1P0_DN<19>")
	)
	(segment
		(start 364.184184 -213.93023)
		(end 364.184184 -211.768944)
		(width 0.0889)
		(layer "In4.Cu")
		(net "UPI_CPU0_CPU1_P1P0_DN<19>")
	)
	(segment
		(start 107.555538 -209.856324)
		(end 107.429554 -210.202272)
		(width 0.14732)
		(layer "In4.Cu")
		(net "UPI_CPU0_CPU1_P1P0_DN<19>")
	)
	(segment
		(start 307.22824 -162.136836)
		(end 307.07838 -162.2806)
		(width 0.14732)
		(layer "In4.Cu")
		(net "UPI_CPU0_CPU1_P1P0_DN<19>")
	)
	(segment
		(start 307.962554 -162.299396)
		(end 307.818282 -162.149028)
		(width 0.14732)
		(layer "In4.Cu")
		(net "UPI_CPU0_CPU1_P1P0_DN<19>")
	)
	(segment
		(start 363.714284 -217.8939)
		(end 363.714284 -217.859864)
		(width 0.0889)
		(layer "In4.Cu")
		(net "UPI_CPU0_CPU1_P1P0_DN<19>")
	)
	(segment
		(start 107.17657 -217.356182)
		(end 107.254548 -217.335354)
		(width 0.0889)
		(layer "In4.Cu")
		(net "UPI_CPU0_CPU1_P1P0_DN<19>")
	)
	(segment
		(start 312.452258 -162.244024)
		(end 311.862216 -162.231832)
		(width 0.14732)
		(layer "In4.Cu")
		(net "UPI_CPU0_CPU1_P1P0_DN<19>")
	)
	(segment
		(start 323.766942 -167.185594)
		(end 314.808108 -164.67963)
		(width 0.14732)
		(layer "In4.Cu")
		(net "UPI_CPU0_CPU1_P1P0_DN<19>")
	)
	(segment
		(start 109.62386 -204.602588)
		(end 109.497622 -204.949044)
		(width 0.14732)
		(layer "In4.Cu")
		(net "UPI_CPU0_CPU1_P1P0_DN<19>")
	)
	(segment
		(start 237.77702 -154.920188)
		(end 234.434126 -154.920188)
		(width 0.14732)
		(layer "In4.Cu")
		(net "UPI_CPU0_CPU1_P1P0_DN<19>")
	)
	(segment
		(start 357.722424 -190.775336)
		(end 356.065074 -186.774836)
		(width 0.14732)
		(layer "In4.Cu")
		(net "UPI_CPU0_CPU1_P1P0_DN<19>")
	)
	(segment
		(start 350.927162 -178.364134)
		(end 350.59112 -178.313334)
		(width 0.14732)
		(layer "In4.Cu")
		(net "UPI_CPU0_CPU1_P1P0_DN<19>")
	)
	(segment
		(start 307.818282 -162.149028)
		(end 307.22824 -162.136836)
		(width 0.14732)
		(layer "In4.Cu")
		(net "UPI_CPU0_CPU1_P1P0_DN<19>")
	)
	(segment
		(start 165.23081 -154.727148)
		(end 133.635242 -174.198026)
		(width 0.14732)
		(layer "In4.Cu")
		(net "UPI_CPU0_CPU1_P1P0_DN<19>")
	)
	(segment
		(start 109.272578 -205.566772)
		(end 109.14634 -205.913228)
		(width 0.14732)
		(layer "In4.Cu")
		(net "UPI_CPU0_CPU1_P1P0_DN<19>")
	)
	(segment
		(start 109.311948 -205.035404)
		(end 109.185964 -205.381352)
		(width 0.14732)
		(layer "In4.Cu")
		(net "UPI_CPU0_CPU1_P1P0_DN<19>")
	)
	(segment
		(start 310.239918 -164.279326)
		(end 310.279542 -162.346894)
		(width 0.14732)
		(layer "In4.Cu")
		(net "UPI_CPU0_CPU1_P1P0_DN<19>")
	)
	(segment
		(start 306.725066 -164.515292)
		(end 305.907948 -164.49802)
		(width 0.14732)
		(layer "In4.Cu")
		(net "UPI_CPU0_CPU1_P1P0_DN<19>")
	)
	(segment
		(start 309.355998 -164.260784)
		(end 309.042054 -164.56279)
		(width 0.14732)
		(layer "In4.Cu")
		(net "UPI_CPU0_CPU1_P1P0_DN<19>")
	)
	(segment
		(start 107.135422 -213.29142)
		(end 107.036362 -213.39048)
		(width 0.0889)
		(layer "In4.Cu")
		(net "UPI_CPU0_CPU1_P1P0_DN<19>")
	)
	(segment
		(start 305.645566 -162.251898)
		(end 305.501294 -162.10153)
		(width 0.14732)
		(layer "In4.Cu")
		(net "UPI_CPU0_CPU1_P1P0_DN<19>")
	)
	(segment
		(start 364.142274 -211.328)
		(end 364.142274 -205.293214)
		(width 0.14732)
		(layer "In4.Cu")
		(net "UPI_CPU0_CPU1_P1P0_DN<19>")
	)
	(segment
		(start 346.471494 -177.827178)
		(end 346.26931 -177.858928)
		(width 0.14732)
		(layer "In4.Cu")
		(net "UPI_CPU0_CPU1_P1P0_DN<19>")
	)
	(segment
		(start 107.225338 -215.762078)
		(end 107.226608 -215.76284)
		(width 0.0889)
		(layer "In4.Cu")
		(net "UPI_CPU0_CPU1_P1P0_DN<19>")
	)
	(segment
		(start 280.844244 -164.803328)
		(end 276.255226 -164.803328)
		(width 0.14732)
		(layer "In4.Cu")
		(net "UPI_CPU0_CPU1_P1P0_DN<19>")
	)
	(segment
		(start 364.18393 -217.072972)
		(end 364.18393 -217.0557)
		(width 0.0889)
		(layer "In4.Cu")
		(net "UPI_CPU0_CPU1_P1P0_DN<19>")
	)
	(segment
		(start 350.59112 -178.313334)
		(end 349.205042 -178.591464)
		(width 0.14732)
		(layer "In4.Cu")
		(net "UPI_CPU0_CPU1_P1P0_DN<19>")
	)
	(segment
		(start 364.142528 -211.727288)
		(end 364.142528 -211.70519)
		(width 0.0889)
		(layer "In4.Cu")
		(net "UPI_CPU0_CPU1_P1P0_DN<19>")
	)
	(segment
		(start 351.3328 -178.793648)
		(end 350.927162 -178.364134)
		(width 0.14732)
		(layer "In4.Cu")
		(net "UPI_CPU0_CPU1_P1P0_DN<19>")
	)
	(segment
		(start 363.80928 -218.692222)
		(end 363.965744 -218.421204)
		(width 0.0889)
		(layer "In4.Cu")
		(net "UPI_CPU0_CPU1_P1P0_DN<19>")
	)
	(segment
		(start 107.780836 -209.238088)
		(end 107.86745 -209.423508)
		(width 0.14732)
		(layer "In4.Cu")
		(net "UPI_CPU0_CPU1_P1P0_DN<19>")
	)
	(segment
		(start 345.939618 -177.43932)
		(end 342.016842 -174.580296)
		(width 0.14732)
		(layer "In4.Cu")
		(net "UPI_CPU0_CPU1_P1P0_DN<19>")
	)
	(segment
		(start 364.466632 -214.946992)
		(end 364.475522 -214.941912)
		(width 0.0889)
		(layer "In4.Cu")
		(net "UPI_CPU0_CPU1_P1P0_DN<19>")
	)
	(segment
		(start 108.609384 -206.963772)
		(end 108.4834 -207.30972)
		(width 0.14732)
		(layer "In4.Cu")
		(net "UPI_CPU0_CPU1_P1P0_DN<19>")
	)
	(segment
		(start 348.43466 -178.700176)
		(end 347.247464 -178.392582)
		(width 0.14732)
		(layer "In4.Cu")
		(net "UPI_CPU0_CPU1_P1P0_DN<19>")
	)
	(segment
		(start 107.078526 -211.582762)
		(end 107.078526 -212.02015)
		(width 0.14732)
		(layer "In4.Cu")
		(net "UPI_CPU0_CPU1_P1P0_DN<19>")
	)
	(segment
		(start 107.22991 -216.736422)
		(end 107.224576 -216.73947)
		(width 0.0889)
		(layer "In4.Cu")
		(net "UPI_CPU0_CPU1_P1P0_DN<19>")
	)
	(segment
		(start 310.13527 -162.196526)
		(end 309.545228 -162.184334)
		(width 0.14732)
		(layer "In4.Cu")
		(net "UPI_CPU0_CPU1_P1P0_DN<19>")
	)
	(segment
		(start 304.408078 -164.467794)
		(end 302.122078 -164.420804)
		(width 0.14732)
		(layer "In4.Cu")
		(net "UPI_CPU0_CPU1_P1P0_DN<19>")
	)
	(segment
		(start 342.016842 -174.580296)
		(end 332.269084 -170.314112)
		(width 0.14732)
		(layer "In4.Cu")
		(net "UPI_CPU0_CPU1_P1P0_DN<19>")
	)
	(segment
		(start 112.10798 -197.359778)
		(end 109.537246 -204.417168)
		(width 0.14732)
		(layer "In4.Cu")
		(net "UPI_CPU0_CPU1_P1P0_DN<19>")
	)
	(segment
		(start 312.59653 -162.394392)
		(end 312.452258 -162.244024)
		(width 0.14732)
		(layer "In4.Cu")
		(net "UPI_CPU0_CPU1_P1P0_DN<19>")
	)
	(segment
		(start 107.741212 -209.769964)
		(end 107.555538 -209.856324)
		(width 0.14732)
		(layer "In4.Cu")
		(net "UPI_CPU0_CPU1_P1P0_DN<19>")
	)
	(segment
		(start 356.065074 -184.160922)
		(end 355.431852 -182.75935)
		(width 0.14732)
		(layer "In4.Cu")
		(net "UPI_CPU0_CPU1_P1P0_DN<19>")
	)
	(segment
		(start 314.808108 -164.67963)
		(end 314.808108 -164.679884)
		(width 0.14732)
		(layer "In4.Cu")
		(net "UPI_CPU0_CPU1_P1P0_DN<19>")
	)
	(segment
		(start 107.516168 -210.387692)
		(end 107.38993 -210.734148)
		(width 0.14732)
		(layer "In4.Cu")
		(net "UPI_CPU0_CPU1_P1P0_DN<19>")
	)
	(segment
		(start 364.18393 -215.445086)
		(end 364.18393 -215.43645)
		(width 0.0889)
		(layer "In4.Cu")
		(net "UPI_CPU0_CPU1_P1P0_DN<19>")
	)
	(segment
		(start 107.204256 -210.820508)
		(end 107.078272 -211.166456)
		(width 0.14732)
		(layer "In4.Cu")
		(net "UPI_CPU0_CPU1_P1P0_DN<19>")
	)
	(segment
		(start 107.078526 -212.042248)
		(end 107.036362 -212.084412)
		(width 0.0889)
		(layer "In4.Cu")
		(net "UPI_CPU0_CPU1_P1P0_DN<19>")
	)
	(segment
		(start 356.065074 -186.774836)
		(end 356.065074 -184.160922)
		(width 0.14732)
		(layer "In4.Cu")
		(net "UPI_CPU0_CPU1_P1P0_DN<19>")
	)
	(segment
		(start 346.26931 -177.858928)
		(end 345.971368 -177.642012)
		(width 0.14732)
		(layer "In4.Cu")
		(net "UPI_CPU0_CPU1_P1P0_DN<19>")
	)
	(segment
		(start 108.132118 -208.273904)
		(end 108.218732 -208.459324)
		(width 0.14732)
		(layer "In4.Cu")
		(net "UPI_CPU0_CPU1_P1P0_DN<19>")
	)
	(segment
		(start 107.078272 -211.166456)
		(end 107.078272 -211.582508)
		(width 0.14732)
		(layer "In4.Cu")
		(net "UPI_CPU0_CPU1_P1P0_DN<19>")
	)
	(segment
		(start 107.223814 -215.112346)
		(end 107.222798 -215.112854)
		(width 0.0889)
		(layer "In4.Cu")
		(net "UPI_CPU0_CPU1_P1P0_DN<19>")
	)
	(segment
		(start 302.122078 -164.420804)
		(end 280.844244 -164.789104)
		(width 0.14732)
		(layer "In4.Cu")
		(net "UPI_CPU0_CPU1_P1P0_DN<19>")
	)
	(segment
		(start 351.74174 -179.507388)
		(end 351.3328 -178.793648)
		(width 0.14732)
		(layer "In4.Cu")
		(net "UPI_CPU0_CPU1_P1P0_DN<19>")
	)
	(segment
		(start 108.834682 -206.345536)
		(end 108.921296 -206.530956)
		(width 0.14732)
		(layer "In4.Cu")
		(net "UPI_CPU0_CPU1_P1P0_DN<19>")
	)
	(segment
		(start 107.90682 -208.89214)
		(end 107.780836 -209.238088)
		(width 0.14732)
		(layer "In4.Cu")
		(net "UPI_CPU0_CPU1_P1P0_DN<19>")
	)
	(segment
		(start 307.92293 -164.231828)
		(end 307.962554 -162.299396)
		(width 0.14732)
		(layer "In4.Cu")
		(net "UPI_CPU0_CPU1_P1P0_DN<19>")
	)
	(segment
		(start 197.421246 -164.462206)
		(end 194.73291 -164.800788)
		(width 0.14732)
		(layer "In4.Cu")
		(net "UPI_CPU0_CPU1_P1P0_DN<19>")
	)
	(arc
		(start 364.475522 -214.941912)
		(mid 364.606436 -214.805552)
		(end 364.654084 -214.622634)
		(width 0.0889)
		(layer "In4.Cu")
		(net "UPI_CPU0_CPU1_P1P0_DN<19>")
	)
	(arc
		(start 363.92485 -218.319096)
		(mid 363.772768 -218.129664)
		(end 363.714284 -217.8939)
		(width 0.0889)
		(layer "In4.Cu")
		(net "UPI_CPU0_CPU1_P1P0_DN<19>")
	)
	(arc
		(start 363.941614 -218.33205)
		(mid 363.933173 -218.32565)
		(end 363.92485 -218.319096)
		(width 0.0889)
		(layer "In4.Cu")
		(net "UPI_CPU0_CPU1_P1P0_DN<19>")
	)
	(arc
		(start 107.220766 -214.093298)
		(mid 107.394729 -214.232062)
		(end 107.506008 -214.424768)
		(width 0.0889)
		(layer "In4.Cu")
		(net "UPI_CPU0_CPU1_P1P0_DN<19>")
	)
	(arc
		(start 364.18393 -217.0557)
		(mid 364.13166 -216.873335)
		(end 363.996732 -216.739978)
		(width 0.0889)
		(layer "In4.Cu")
		(net "UPI_CPU0_CPU1_P1P0_DN<19>")
	)
	(arc
		(start 364.184184 -215.422226)
		(mid 364.263315 -215.14769)
		(end 364.466632 -214.946992)
		(width 0.0889)
		(layer "In4.Cu")
		(net "UPI_CPU0_CPU1_P1P0_DN<19>")
	)
	(arc
		(start 363.98454 -216.732866)
		(mid 363.786312 -216.527018)
		(end 363.71403 -216.25052)
		(width 0.0889)
		(layer "In4.Cu")
		(net "UPI_CPU0_CPU1_P1P0_DN<19>")
	)
	(arc
		(start 107.506008 -214.644732)
		(mid 107.425097 -214.91486)
		(end 107.223814 -215.112346)
		(width 0.0889)
		(layer "In4.Cu")
		(net "UPI_CPU0_CPU1_P1P0_DN<19>")
	)
	(arc
		(start 107.223814 -216.739978)
		(mid 107.037611 -217.035655)
		(end 107.17657 -217.356182)
		(width 0.0889)
		(layer "In4.Cu")
		(net "UPI_CPU0_CPU1_P1P0_DN<19>")
	)
	(arc
		(start 107.036616 -213.893908)
		(mid 107.111621 -214.009367)
		(end 107.220766 -214.093298)
		(width 0.0889)
		(layer "In4.Cu")
		(net "UPI_CPU0_CPU1_P1P0_DN<19>")
	)
	(arc
		(start 363.996732 -215.760808)
		(mid 364.131665 -215.627454)
		(end 364.18393 -215.445086)
		(width 0.0889)
		(layer "In4.Cu")
		(net "UPI_CPU0_CPU1_P1P0_DN<19>")
	)
	(arc
		(start 364.19917 -213.968838)
		(mid 364.191348 -213.949662)
		(end 364.184184 -213.93023)
		(width 0.0889)
		(layer "In4.Cu")
		(net "UPI_CPU0_CPU1_P1P0_DN<19>")
	)
	(arc
		(start 363.996732 -217.388694)
		(mid 364.131665 -217.25534)
		(end 364.18393 -217.072972)
		(width 0.0889)
		(layer "In4.Cu")
		(net "UPI_CPU0_CPU1_P1P0_DN<19>")
	)
	(arc
		(start 107.22991 -215.764618)
		(mid 107.506484 -216.25052)
		(end 107.22991 -216.736422)
		(width 0.0889)
		(layer "In4.Cu")
		(net "UPI_CPU0_CPU1_P1P0_DN<19>")
	)
	(arc
		(start 363.71403 -216.2429)
		(mid 363.791659 -215.964487)
		(end 363.996732 -215.760808)
		(width 0.0889)
		(layer "In4.Cu")
		(net "UPI_CPU0_CPU1_P1P0_DN<19>")
	)
	(arc
		(start 364.46968 -214.261954)
		(mid 364.309325 -214.138568)
		(end 364.19917 -213.968838)
		(width 0.0889)
		(layer "In4.Cu")
		(net "UPI_CPU0_CPU1_P1P0_DN<19>")
	)
	(arc
		(start 107.214924 -215.117426)
		(mid 107.036327 -215.436704)
		(end 107.214924 -215.755982)
		(width 0.0889)
		(layer "In4.Cu")
		(net "UPI_CPU0_CPU1_P1P0_DN<19>")
	)
	(arc
		(start 364.654084 -214.461852)
		(mid 364.579013 -214.34611)
		(end 364.46968 -214.261954)
		(width 0.0889)
		(layer "In4.Cu")
		(net "UPI_CPU0_CPU1_P1P0_DN<19>")
	)
	(arc
		(start 363.714284 -217.859864)
		(mid 363.794446 -217.587675)
		(end 363.996732 -217.388694)
		(width 0.0889)
		(layer "In4.Cu")
		(net "UPI_CPU0_CPU1_P1P0_DN<19>")
	)
	(segment
		(start 365.21898 -217.87866)
		(end 365.219234 -217.878406)
		(width 0.13208)
		(layer "F.Cu")
		(net "UPI_CPU0_CPU1_P1P0_DN<18>")
	)
	(segment
		(start 106.001312 -217.87866)
		(end 106.001566 -217.878406)
		(width 0.13208)
		(layer "F.Cu")
		(net "UPI_CPU0_CPU1_P1P0_DN<18>")
	)
	(segment
		(start 106.001312 -218.414346)
		(end 106.001312 -217.87866)
		(width 0.13208)
		(layer "F.Cu")
		(net "UPI_CPU0_CPU1_P1P0_DN<18>")
	)
	(segment
		(start 365.21898 -218.414346)
		(end 365.21898 -217.87866)
		(width 0.13208)
		(layer "F.Cu")
		(net "UPI_CPU0_CPU1_P1P0_DN<18>")
	)
	(segment
		(start 276.425406 -163.700968)
		(end 237.917736 -153.810208)
		(width 0.14732)
		(layer "In4.Cu")
		(net "UPI_CPU0_CPU1_P1P0_DN<18>")
	)
	(segment
		(start 347.330268 -176.579022)
		(end 347.264228 -176.148492)
		(width 0.14732)
		(layer "In4.Cu")
		(net "UPI_CPU0_CPU1_P1P0_DN<18>")
	)
	(segment
		(start 106.188764 -216.574878)
		(end 106.176572 -216.58199)
		(width 0.0889)
		(layer "In4.Cu")
		(net "UPI_CPU0_CPU1_P1P0_DN<18>")
	)
	(segment
		(start 105.864406 -212.02015)
		(end 105.864406 -212.042248)
		(width 0.0889)
		(layer "In4.Cu")
		(net "UPI_CPU0_CPU1_P1P0_DN<18>")
	)
	(segment
		(start 347.177106 -176.787302)
		(end 347.330268 -176.579022)
		(width 0.14732)
		(layer "In4.Cu")
		(net "UPI_CPU0_CPU1_P1P0_DN<18>")
	)
	(segment
		(start 106.197146 -214.941912)
		(end 106.188256 -214.946992)
		(width 0.0889)
		(layer "In4.Cu")
		(net "UPI_CPU0_CPU1_P1P0_DN<18>")
	)
	(segment
		(start 365.203486 -217.851228)
		(end 365.06277 -217.607388)
		(width 0.0889)
		(layer "In4.Cu")
		(net "UPI_CPU0_CPU1_P1P0_DN<18>")
	)
	(segment
		(start 234.293156 -153.810208)
		(end 197.212458 -163.369498)
		(width 0.14732)
		(layer "In4.Cu")
		(net "UPI_CPU0_CPU1_P1P0_DN<18>")
	)
	(segment
		(start 106.15803 -218.149424)
		(end 106.001566 -217.878406)
		(width 0.0889)
		(layer "In4.Cu")
		(net "UPI_CPU0_CPU1_P1P0_DN<18>")
	)
	(segment
		(start 356.139496 -181.395878)
		(end 355.31044 -179.750212)
		(width 0.14732)
		(layer "In4.Cu")
		(net "UPI_CPU0_CPU1_P1P0_DN<18>")
	)
	(segment
		(start 322.321936 -154.772868)
		(end 315.90615 -156.11729)
		(width 0.14732)
		(layer "In4.Cu")
		(net "UPI_CPU0_CPU1_P1P0_DN<18>")
	)
	(segment
		(start 346.357194 -175.864774)
		(end 346.204032 -176.073308)
		(width 0.14732)
		(layer "In4.Cu")
		(net "UPI_CPU0_CPU1_P1P0_DN<18>")
	)
	(segment
		(start 365.023146 -215.931242)
		(end 365.032036 -215.926162)
		(width 0.0889)
		(layer "In4.Cu")
		(net "UPI_CPU0_CPU1_P1P0_DN<18>")
	)
	(segment
		(start 314.88634 -157.06217)
		(end 314.80252 -156.662882)
		(width 0.14732)
		(layer "In4.Cu")
		(net "UPI_CPU0_CPU1_P1P0_DN<18>")
	)
	(segment
		(start 345.998546 -176.105058)
		(end 342.678258 -173.66869)
		(width 0.14732)
		(layer "In4.Cu")
		(net "UPI_CPU0_CPU1_P1P0_DN<18>")
	)
	(segment
		(start 197.212458 -163.369498)
		(end 194.66306 -163.690808)
		(width 0.14732)
		(layer "In4.Cu")
		(net "UPI_CPU0_CPU1_P1P0_DN<18>")
	)
	(segment
		(start 105.864152 -211.236814)
		(end 105.864152 -211.582508)
		(width 0.14732)
		(layer "In4.Cu")
		(net "UPI_CPU0_CPU1_P1P0_DN<18>")
	)
	(segment
		(start 132.969 -173.300898)
		(end 119.850154 -185.637932)
		(width 0.14732)
		(layer "In4.Cu")
		(net "UPI_CPU0_CPU1_P1P0_DN<18>")
	)
	(segment
		(start 307.632862 -157.851094)
		(end 279.705816 -163.700968)
		(width 0.14732)
		(layer "In4.Cu")
		(net "UPI_CPU0_CPU1_P1P0_DN<18>")
	)
	(segment
		(start 347.208856 -176.992788)
		(end 347.177106 -176.787302)
		(width 0.14732)
		(layer "In4.Cu")
		(net "UPI_CPU0_CPU1_P1P0_DN<18>")
	)
	(segment
		(start 111.242094 -196.473826)
		(end 105.864152 -211.236814)
		(width 0.14732)
		(layer "In4.Cu")
		(net "UPI_CPU0_CPU1_P1P0_DN<18>")
	)
	(segment
		(start 359.357676 -190.852044)
		(end 358.70007 -190.181992)
		(width 0.14732)
		(layer "In4.Cu")
		(net "UPI_CPU0_CPU1_P1P0_DN<18>")
	)
	(segment
		(start 308.946296 -158.307278)
		(end 308.83225 -158.481268)
		(width 0.14732)
		(layer "In4.Cu")
		(net "UPI_CPU0_CPU1_P1P0_DN<18>")
	)
	(segment
		(start 357.230934 -186.634882)
		(end 357.230934 -184.03062)
		(width 0.14732)
		(layer "In4.Cu")
		(net "UPI_CPU0_CPU1_P1P0_DN<18>")
	)
	(segment
		(start 325.449692 -155.303474)
		(end 323.343016 -154.772868)
		(width 0.14732)
		(layer "In4.Cu")
		(net "UPI_CPU0_CPU1_P1P0_DN<18>")
	)
	(segment
		(start 311.21477 -157.83179)
		(end 311.100724 -158.00578)
		(width 0.14732)
		(layer "In4.Cu")
		(net "UPI_CPU0_CPU1_P1P0_DN<18>")
	)
	(segment
		(start 347.730064 -177.375312)
		(end 347.208856 -176.992788)
		(width 0.14732)
		(layer "In4.Cu")
		(net "UPI_CPU0_CPU1_P1P0_DN<18>")
	)
	(segment
		(start 237.917736 -153.810208)
		(end 234.293156 -153.810208)
		(width 0.14732)
		(layer "In4.Cu")
		(net "UPI_CPU0_CPU1_P1P0_DN<18>")
	)
	(segment
		(start 312.16981 -156.900118)
		(end 311.369202 -157.068266)
		(width 0.14732)
		(layer "In4.Cu")
		(net "UPI_CPU0_CPU1_P1P0_DN<18>")
	)
	(segment
		(start 365.314484 -217.07856)
		(end 365.314484 -217.064336)
		(width 0.0889)
		(layer "In4.Cu")
		(net "UPI_CPU0_CPU1_P1P0_DN<18>")
	)
	(segment
		(start 365.038132 -216.578434)
		(end 365.032036 -216.574878)
		(width 0.0889)
		(layer "In4.Cu")
		(net "UPI_CPU0_CPU1_P1P0_DN<18>")
	)
	(segment
		(start 365.314484 -213.8934)
		(end 365.314484 -211.799932)
		(width 0.0889)
		(layer "In4.Cu")
		(net "UPI_CPU0_CPU1_P1P0_DN<18>")
	)
	(segment
		(start 313.637676 -156.592778)
		(end 313.399424 -156.957014)
		(width 0.14732)
		(layer "In4.Cu")
		(net "UPI_CPU0_CPU1_P1P0_DN<18>")
	)
	(segment
		(start 190.340996 -163.690808)
		(end 172.742352 -154.483308)
		(width 0.14732)
		(layer "In4.Cu")
		(net "UPI_CPU0_CPU1_P1P0_DN<18>")
	)
	(segment
		(start 365.784384 -214.63254)
		(end 365.784384 -214.425022)
		(width 0.0889)
		(layer "In4.Cu")
		(net "UPI_CPU0_CPU1_P1P0_DN<18>")
	)
	(segment
		(start 365.501174 -215.1126)
		(end 365.501936 -215.112092)
		(width 0.0889)
		(layer "In4.Cu")
		(net "UPI_CPU0_CPU1_P1P0_DN<18>")
	)
	(segment
		(start 315.751718 -156.880814)
		(end 315.637672 -157.054804)
		(width 0.14732)
		(layer "In4.Cu")
		(net "UPI_CPU0_CPU1_P1P0_DN<18>")
	)
	(segment
		(start 194.66306 -163.690808)
		(end 190.340996 -163.690808)
		(width 0.14732)
		(layer "In4.Cu")
		(net "UPI_CPU0_CPU1_P1P0_DN<18>")
	)
	(segment
		(start 106.188764 -217.554048)
		(end 106.197654 -217.559128)
		(width 0.0889)
		(layer "In4.Cu")
		(net "UPI_CPU0_CPU1_P1P0_DN<18>")
	)
	(segment
		(start 165.150292 -153.469594)
		(end 132.969 -173.300898)
		(width 0.14732)
		(layer "In4.Cu")
		(net "UPI_CPU0_CPU1_P1P0_DN<18>")
	)
	(segment
		(start 350.64573 -177.174906)
		(end 349.01886 -177.500788)
		(width 0.14732)
		(layer "In4.Cu")
		(net "UPI_CPU0_CPU1_P1P0_DN<18>")
	)
	(segment
		(start 313.483244 -157.356302)
		(end 313.369198 -157.530292)
		(width 0.14732)
		(layer "In4.Cu")
		(net "UPI_CPU0_CPU1_P1P0_DN<18>")
	)
	(segment
		(start 315.06033 -157.175962)
		(end 314.88634 -157.06217)
		(width 0.14732)
		(layer "In4.Cu")
		(net "UPI_CPU0_CPU1_P1P0_DN<18>")
	)
	(segment
		(start 310.349392 -158.013146)
		(end 310.265572 -157.613858)
		(width 0.14732)
		(layer "In4.Cu")
		(net "UPI_CPU0_CPU1_P1P0_DN<18>")
	)
	(segment
		(start 349.01886 -177.500788)
		(end 348.49816 -177.574448)
		(width 0.14732)
		(layer "In4.Cu")
		(net "UPI_CPU0_CPU1_P1P0_DN<18>")
	)
	(segment
		(start 342.67775 -173.668182)
		(end 327.4568 -156.89072)
		(width 0.14732)
		(layer "In4.Cu")
		(net "UPI_CPU0_CPU1_P1P0_DN<18>")
	)
	(segment
		(start 308.83225 -158.481268)
		(end 308.254908 -158.602426)
		(width 0.14732)
		(layer "In4.Cu")
		(net "UPI_CPU0_CPU1_P1P0_DN<18>")
	)
	(segment
		(start 351.357946 -177.258218)
		(end 350.64573 -177.174906)
		(width 0.14732)
		(layer "In4.Cu")
		(net "UPI_CPU0_CPU1_P1P0_DN<18>")
	)
	(segment
		(start 308.080918 -158.488634)
		(end 307.997098 -158.089346)
		(width 0.14732)
		(layer "In4.Cu")
		(net "UPI_CPU0_CPU1_P1P0_DN<18>")
	)
	(segment
		(start 105.864406 -212.042248)
		(end 105.906316 -212.084158)
		(width 0.0889)
		(layer "In4.Cu")
		(net "UPI_CPU0_CPU1_P1P0_DN<18>")
	)
	(segment
		(start 309.901336 -157.375606)
		(end 309.100728 -157.543754)
		(width 0.14732)
		(layer "In4.Cu")
		(net "UPI_CPU0_CPU1_P1P0_DN<18>")
	)
	(segment
		(start 348.49816 -177.574448)
		(end 347.730064 -177.375312)
		(width 0.14732)
		(layer "In4.Cu")
		(net "UPI_CPU0_CPU1_P1P0_DN<18>")
	)
	(segment
		(start 279.705816 -163.700968)
		(end 276.425406 -163.700968)
		(width 0.14732)
		(layer "In4.Cu")
		(net "UPI_CPU0_CPU1_P1P0_DN<18>")
	)
	(segment
		(start 365.032036 -215.926162)
		(end 365.038132 -215.922606)
		(width 0.0889)
		(layer "In4.Cu")
		(net "UPI_CPU0_CPU1_P1P0_DN<18>")
	)
	(segment
		(start 314.438284 -156.42463)
		(end 313.637676 -156.592778)
		(width 0.14732)
		(layer "In4.Cu")
		(net "UPI_CPU0_CPU1_P1P0_DN<18>")
	)
	(segment
		(start 105.807256 -213.05266)
		(end 105.807256 -213.22792)
		(width 0.0889)
		(layer "In4.Cu")
		(net "UPI_CPU0_CPU1_P1P0_DN<18>")
	)
	(segment
		(start 105.906316 -212.40496)
		(end 105.807256 -212.50402)
		(width 0.0889)
		(layer "In4.Cu")
		(net "UPI_CPU0_CPU1_P1P0_DN<18>")
	)
	(segment
		(start 308.254908 -158.602426)
		(end 308.080918 -158.488634)
		(width 0.14732)
		(layer "In4.Cu")
		(net "UPI_CPU0_CPU1_P1P0_DN<18>")
	)
	(segment
		(start 313.369198 -157.530292)
		(end 312.791856 -157.65145)
		(width 0.14732)
		(layer "In4.Cu")
		(net "UPI_CPU0_CPU1_P1P0_DN<18>")
	)
	(segment
		(start 347.264228 -176.148492)
		(end 346.787724 -175.798734)
		(width 0.14732)
		(layer "In4.Cu")
		(net "UPI_CPU0_CPU1_P1P0_DN<18>")
	)
	(segment
		(start 105.906316 -212.9536)
		(end 105.807256 -213.05266)
		(width 0.0889)
		(layer "In4.Cu")
		(net "UPI_CPU0_CPU1_P1P0_DN<18>")
	)
	(segment
		(start 346.204032 -176.073308)
		(end 345.998546 -176.105058)
		(width 0.14732)
		(layer "In4.Cu")
		(net "UPI_CPU0_CPU1_P1P0_DN<18>")
	)
	(segment
		(start 365.356394 -211.290408)
		(end 365.356394 -205.334108)
		(width 0.14732)
		(layer "In4.Cu")
		(net "UPI_CPU0_CPU1_P1P0_DN<18>")
	)
	(segment
		(start 308.862476 -157.90799)
		(end 308.946296 -158.307278)
		(width 0.14732)
		(layer "In4.Cu")
		(net "UPI_CPU0_CPU1_P1P0_DN<18>")
	)
	(segment
		(start 342.678258 -173.66869)
		(end 342.678004 -173.668182)
		(width 0.14732)
		(layer "In4.Cu")
		(net "UPI_CPU0_CPU1_P1P0_DN<18>")
	)
	(segment
		(start 365.493046 -215.117172)
		(end 365.501174 -215.1126)
		(width 0.0889)
		(layer "In4.Cu")
		(net "UPI_CPU0_CPU1_P1P0_DN<18>")
	)
	(segment
		(start 346.787724 -175.798734)
		(end 346.357194 -175.864774)
		(width 0.14732)
		(layer "In4.Cu")
		(net "UPI_CPU0_CPU1_P1P0_DN<18>")
	)
	(segment
		(start 105.906316 -215.436958)
		(end 105.906316 -215.500712)
		(width 0.0889)
		(layer "In4.Cu")
		(net "UPI_CPU0_CPU1_P1P0_DN<18>")
	)
	(segment
		(start 105.807256 -213.22792)
		(end 105.906316 -213.32698)
		(width 0.0889)
		(layer "In4.Cu")
		(net "UPI_CPU0_CPU1_P1P0_DN<18>")
	)
	(segment
		(start 312.617866 -157.537658)
		(end 312.534046 -157.13837)
		(width 0.14732)
		(layer "In4.Cu")
		(net "UPI_CPU0_CPU1_P1P0_DN<18>")
	)
	(segment
		(start 323.343016 -154.772868)
		(end 322.321936 -154.772868)
		(width 0.14732)
		(layer "In4.Cu")
		(net "UPI_CPU0_CPU1_P1P0_DN<18>")
	)
	(segment
		(start 311.369202 -157.068266)
		(end 311.13095 -157.432502)
		(width 0.14732)
		(layer "In4.Cu")
		(net "UPI_CPU0_CPU1_P1P0_DN<18>")
	)
	(segment
		(start 172.742352 -154.483308)
		(end 169.720768 -152.987248)
		(width 0.14732)
		(layer "In4.Cu")
		(net "UPI_CPU0_CPU1_P1P0_DN<18>")
	)
	(segment
		(start 105.906062 -217.064336)
		(end 105.906062 -217.071956)
		(width 0.0889)
		(layer "In4.Cu")
		(net "UPI_CPU0_CPU1_P1P0_DN<18>")
	)
	(segment
		(start 166.756588 -152.908508)
		(end 165.150292 -153.469594)
		(width 0.14732)
		(layer "In4.Cu")
		(net "UPI_CPU0_CPU1_P1P0_DN<18>")
	)
	(segment
		(start 365.356648 -211.757768)
		(end 365.356648 -211.73567)
		(width 0.0889)
		(layer "In4.Cu")
		(net "UPI_CPU0_CPU1_P1P0_DN<18>")
	)
	(segment
		(start 119.850154 -185.637932)
		(end 111.242094 -196.473826)
		(width 0.14732)
		(layer "In4.Cu")
		(net "UPI_CPU0_CPU1_P1P0_DN<18>")
	)
	(segment
		(start 106.375708 -214.461344)
		(end 106.375708 -214.622634)
		(width 0.0889)
		(layer "In4.Cu")
		(net "UPI_CPU0_CPU1_P1P0_DN<18>")
	)
	(segment
		(start 365.032036 -216.574878)
		(end 365.023146 -216.569798)
		(width 0.0889)
		(layer "In4.Cu")
		(net "UPI_CPU0_CPU1_P1P0_DN<18>")
	)
	(segment
		(start 365.314484 -211.799932)
		(end 365.356648 -211.757768)
		(width 0.0889)
		(layer "In4.Cu")
		(net "UPI_CPU0_CPU1_P1P0_DN<18>")
	)
	(segment
		(start 105.864406 -211.582762)
		(end 105.864406 -212.02015)
		(width 0.14732)
		(layer "In4.Cu")
		(net "UPI_CPU0_CPU1_P1P0_DN<18>")
	)
	(segment
		(start 327.4568 -156.89072)
		(end 325.449692 -155.303474)
		(width 0.14732)
		(layer "In4.Cu")
		(net "UPI_CPU0_CPU1_P1P0_DN<18>")
	)
	(segment
		(start 106.197654 -216.569798)
		(end 106.188764 -216.574878)
		(width 0.0889)
		(layer "In4.Cu")
		(net "UPI_CPU0_CPU1_P1P0_DN<18>")
	)
	(segment
		(start 309.100728 -157.543754)
		(end 308.862476 -157.90799)
		(width 0.14732)
		(layer "In4.Cu")
		(net "UPI_CPU0_CPU1_P1P0_DN<18>")
	)
	(segment
		(start 342.678004 -173.668182)
		(end 342.67775 -173.668182)
		(width 0.14732)
		(layer "In4.Cu")
		(net "UPI_CPU0_CPU1_P1P0_DN<18>")
	)
	(segment
		(start 365.356648 -211.73567)
		(end 365.356648 -211.290662)
		(width 0.14732)
		(layer "In4.Cu")
		(net "UPI_CPU0_CPU1_P1P0_DN<18>")
	)
	(segment
		(start 357.230934 -184.03062)
		(end 356.140004 -181.396132)
		(width 0.14732)
		(layer "In4.Cu")
		(net "UPI_CPU0_CPU1_P1P0_DN<18>")
	)
	(segment
		(start 105.807256 -212.50402)
		(end 105.807256 -212.67928)
		(width 0.0889)
		(layer "In4.Cu")
		(net "UPI_CPU0_CPU1_P1P0_DN<18>")
	)
	(segment
		(start 105.906316 -212.084158)
		(end 105.906316 -212.40496)
		(width 0.0889)
		(layer "In4.Cu")
		(net "UPI_CPU0_CPU1_P1P0_DN<18>")
	)
	(segment
		(start 169.720768 -152.987248)
		(end 166.756588 -152.908508)
		(width 0.14732)
		(layer "In4.Cu")
		(net "UPI_CPU0_CPU1_P1P0_DN<18>")
	)
	(segment
		(start 315.637672 -157.054804)
		(end 315.06033 -157.175962)
		(width 0.14732)
		(layer "In4.Cu")
		(net "UPI_CPU0_CPU1_P1P0_DN<18>")
	)
	(segment
		(start 312.534046 -157.13837)
		(end 312.16981 -156.900118)
		(width 0.14732)
		(layer "In4.Cu")
		(net "UPI_CPU0_CPU1_P1P0_DN<18>")
	)
	(segment
		(start 105.906316 -213.32698)
		(end 105.906316 -213.930484)
		(width 0.0889)
		(layer "In4.Cu")
		(net "UPI_CPU0_CPU1_P1P0_DN<18>")
	)
	(segment
		(start 106.188256 -214.946992)
		(end 106.175302 -214.955374)
		(width 0.0889)
		(layer "In4.Cu")
		(net "UPI_CPU0_CPU1_P1P0_DN<18>")
	)
	(segment
		(start 106.1212 -215.885014)
		(end 106.193336 -215.928702)
		(width 0.0889)
		(layer "In4.Cu")
		(net "UPI_CPU0_CPU1_P1P0_DN<18>")
	)
	(segment
		(start 312.791856 -157.65145)
		(end 312.617866 -157.537658)
		(width 0.14732)
		(layer "In4.Cu")
		(net "UPI_CPU0_CPU1_P1P0_DN<18>")
	)
	(segment
		(start 315.90615 -156.11729)
		(end 315.667898 -156.481526)
		(width 0.14732)
		(layer "In4.Cu")
		(net "UPI_CPU0_CPU1_P1P0_DN<18>")
	)
	(segment
		(start 105.906316 -212.77834)
		(end 105.906316 -212.9536)
		(width 0.0889)
		(layer "In4.Cu")
		(net "UPI_CPU0_CPU1_P1P0_DN<18>")
	)
	(segment
		(start 355.31044 -179.750212)
		(end 351.357946 -177.258218)
		(width 0.14732)
		(layer "In4.Cu")
		(net "UPI_CPU0_CPU1_P1P0_DN<18>")
	)
	(segment
		(start 358.70007 -190.181992)
		(end 357.230934 -186.634882)
		(width 0.14732)
		(layer "In4.Cu")
		(net "UPI_CPU0_CPU1_P1P0_DN<18>")
	)
	(segment
		(start 315.667898 -156.481526)
		(end 315.751718 -156.880814)
		(width 0.14732)
		(layer "In4.Cu")
		(net "UPI_CPU0_CPU1_P1P0_DN<18>")
	)
	(segment
		(start 310.265572 -157.613858)
		(end 309.901336 -157.375606)
		(width 0.14732)
		(layer "In4.Cu")
		(net "UPI_CPU0_CPU1_P1P0_DN<18>")
	)
	(segment
		(start 105.807256 -212.67928)
		(end 105.906316 -212.77834)
		(width 0.0889)
		(layer "In4.Cu")
		(net "UPI_CPU0_CPU1_P1P0_DN<18>")
	)
	(segment
		(start 356.140004 -181.396132)
		(end 356.139496 -181.395878)
		(width 0.14732)
		(layer "In4.Cu")
		(net "UPI_CPU0_CPU1_P1P0_DN<18>")
	)
	(segment
		(start 310.523382 -158.126938)
		(end 310.349392 -158.013146)
		(width 0.14732)
		(layer "In4.Cu")
		(net "UPI_CPU0_CPU1_P1P0_DN<18>")
	)
	(segment
		(start 106.236262 -218.170252)
		(end 106.15803 -218.149424)
		(width 0.0889)
		(layer "In4.Cu")
		(net "UPI_CPU0_CPU1_P1P0_DN<18>")
	)
	(segment
		(start 365.356394 -205.334108)
		(end 359.357676 -190.852044)
		(width 0.14732)
		(layer "In4.Cu")
		(net "UPI_CPU0_CPU1_P1P0_DN<18>")
	)
	(segment
		(start 307.997098 -158.089346)
		(end 307.632862 -157.851094)
		(width 0.14732)
		(layer "In4.Cu")
		(net "UPI_CPU0_CPU1_P1P0_DN<18>")
	)
	(segment
		(start 365.356648 -211.290662)
		(end 365.356394 -211.290408)
		(width 0.14732)
		(layer "In4.Cu")
		(net "UPI_CPU0_CPU1_P1P0_DN<18>")
	)
	(segment
		(start 313.399424 -156.957014)
		(end 313.483244 -157.356302)
		(width 0.14732)
		(layer "In4.Cu")
		(net "UPI_CPU0_CPU1_P1P0_DN<18>")
	)
	(segment
		(start 314.80252 -156.662882)
		(end 314.438284 -156.42463)
		(width 0.14732)
		(layer "In4.Cu")
		(net "UPI_CPU0_CPU1_P1P0_DN<18>")
	)
	(segment
		(start 311.100724 -158.00578)
		(end 310.523382 -158.126938)
		(width 0.14732)
		(layer "In4.Cu")
		(net "UPI_CPU0_CPU1_P1P0_DN<18>")
	)
	(segment
		(start 365.06277 -217.607388)
		(end 365.0869 -217.518234)
		(width 0.0889)
		(layer "In4.Cu")
		(net "UPI_CPU0_CPU1_P1P0_DN<18>")
	)
	(segment
		(start 311.13095 -157.432502)
		(end 311.21477 -157.83179)
		(width 0.14732)
		(layer "In4.Cu")
		(net "UPI_CPU0_CPU1_P1P0_DN<18>")
	)
	(segment
		(start 365.219234 -217.878406)
		(end 365.203486 -217.851228)
		(width 0.0889)
		(layer "In4.Cu")
		(net "UPI_CPU0_CPU1_P1P0_DN<18>")
	)
	(segment
		(start 105.864152 -211.582508)
		(end 105.864406 -211.582762)
		(width 0.14732)
		(layer "In4.Cu")
		(net "UPI_CPU0_CPU1_P1P0_DN<18>")
	)
	(arc
		(start 106.197654 -217.559128)
		(mid 106.328568 -217.695488)
		(end 106.376216 -217.878406)
		(width 0.0889)
		(layer "In4.Cu")
		(net "UPI_CPU0_CPU1_P1P0_DN<18>")
	)
	(arc
		(start 106.375708 -214.622634)
		(mid 106.328029 -214.805534)
		(end 106.197146 -214.941912)
		(width 0.0889)
		(layer "In4.Cu")
		(net "UPI_CPU0_CPU1_P1P0_DN<18>")
	)
	(arc
		(start 105.921556 -213.969346)
		(mid 106.03155 -214.138715)
		(end 106.191558 -214.261954)
		(width 0.0889)
		(layer "In4.Cu")
		(net "UPI_CPU0_CPU1_P1P0_DN<18>")
	)
	(arc
		(start 365.498888 -214.093298)
		(mid 365.389492 -214.009201)
		(end 365.314484 -213.8934)
		(width 0.0889)
		(layer "In4.Cu")
		(net "UPI_CPU0_CPU1_P1P0_DN<18>")
	)
	(arc
		(start 106.191558 -214.261954)
		(mid 106.300705 -214.345882)
		(end 106.375708 -214.461344)
		(width 0.0889)
		(layer "In4.Cu")
		(net "UPI_CPU0_CPU1_P1P0_DN<18>")
	)
	(arc
		(start 105.906316 -213.930484)
		(mid 105.913601 -213.950046)
		(end 105.921556 -213.969346)
		(width 0.0889)
		(layer "In4.Cu")
		(net "UPI_CPU0_CPU1_P1P0_DN<18>")
	)
	(arc
		(start 365.023146 -216.569798)
		(mid 364.84467 -216.25052)
		(end 365.023146 -215.931242)
		(width 0.0889)
		(layer "In4.Cu")
		(net "UPI_CPU0_CPU1_P1P0_DN<18>")
	)
	(arc
		(start 105.90657 -215.414606)
		(mid 105.906334 -215.425781)
		(end 105.906316 -215.436958)
		(width 0.0889)
		(layer "In4.Cu")
		(net "UPI_CPU0_CPU1_P1P0_DN<18>")
	)
	(arc
		(start 365.314484 -215.43645)
		(mid 365.362163 -215.25355)
		(end 365.493046 -215.117172)
		(width 0.0889)
		(layer "In4.Cu")
		(net "UPI_CPU0_CPU1_P1P0_DN<18>")
	)
	(arc
		(start 365.103664 -217.50528)
		(mid 365.256171 -217.315182)
		(end 365.314484 -217.07856)
		(width 0.0889)
		(layer "In4.Cu")
		(net "UPI_CPU0_CPU1_P1P0_DN<18>")
	)
	(arc
		(start 365.784384 -214.425022)
		(mid 365.673046 -214.232122)
		(end 365.498888 -214.093298)
		(width 0.0889)
		(layer "In4.Cu")
		(net "UPI_CPU0_CPU1_P1P0_DN<18>")
	)
	(arc
		(start 106.248708 -215.969088)
		(mid 106.37476 -216.28229)
		(end 106.197654 -216.569798)
		(width 0.0889)
		(layer "In4.Cu")
		(net "UPI_CPU0_CPU1_P1P0_DN<18>")
	)
	(arc
		(start 106.193336 -215.928702)
		(mid 106.22194 -215.947635)
		(end 106.248708 -215.969088)
		(width 0.0889)
		(layer "In4.Cu")
		(net "UPI_CPU0_CPU1_P1P0_DN<18>")
	)
	(arc
		(start 106.176572 -216.58199)
		(mid 105.978344 -216.787838)
		(end 105.906062 -217.064336)
		(width 0.0889)
		(layer "In4.Cu")
		(net "UPI_CPU0_CPU1_P1P0_DN<18>")
	)
	(arc
		(start 365.0869 -217.518234)
		(mid 365.095343 -217.511836)
		(end 365.103664 -217.50528)
		(width 0.0889)
		(layer "In4.Cu")
		(net "UPI_CPU0_CPU1_P1P0_DN<18>")
	)
	(arc
		(start 106.376216 -217.878406)
		(mid 106.339356 -218.040203)
		(end 106.236262 -218.170252)
		(width 0.0889)
		(layer "In4.Cu")
		(net "UPI_CPU0_CPU1_P1P0_DN<18>")
	)
	(arc
		(start 365.501936 -215.112092)
		(mid 365.706271 -214.909487)
		(end 365.784384 -214.63254)
		(width 0.0889)
		(layer "In4.Cu")
		(net "UPI_CPU0_CPU1_P1P0_DN<18>")
	)
	(arc
		(start 105.906316 -215.500712)
		(mid 105.96363 -215.720889)
		(end 106.1212 -215.885014)
		(width 0.0889)
		(layer "In4.Cu")
		(net "UPI_CPU0_CPU1_P1P0_DN<18>")
	)
	(arc
		(start 105.906062 -217.071956)
		(mid 105.983691 -217.350369)
		(end 106.188764 -217.554048)
		(width 0.0889)
		(layer "In4.Cu")
		(net "UPI_CPU0_CPU1_P1P0_DN<18>")
	)
	(arc
		(start 106.175302 -214.955374)
		(mid 105.983528 -215.151387)
		(end 105.90657 -215.414606)
		(width 0.0889)
		(layer "In4.Cu")
		(net "UPI_CPU0_CPU1_P1P0_DN<18>")
	)
	(arc
		(start 365.314484 -217.064336)
		(mid 365.240568 -216.784834)
		(end 365.038132 -216.578434)
		(width 0.0889)
		(layer "In4.Cu")
		(net "UPI_CPU0_CPU1_P1P0_DN<18>")
	)
	(arc
		(start 365.038132 -215.922606)
		(mid 365.240608 -215.716083)
		(end 365.314484 -215.43645)
		(width 0.0889)
		(layer "In4.Cu")
		(net "UPI_CPU0_CPU1_P1P0_DN<18>")
	)
	(segment
		(start 365.689134 -218.692476)
		(end 365.68888 -218.692222)
		(width 0.13208)
		(layer "F.Cu")
		(net "UPI_CPU0_CPU1_P1P0_DN<17>")
	)
	(segment
		(start 365.689134 -219.228162)
		(end 365.689134 -218.692476)
		(width 0.13208)
		(layer "F.Cu")
		(net "UPI_CPU0_CPU1_P1P0_DN<17>")
	)
	(segment
		(start 105.531666 -217.06459)
		(end 105.531412 -217.064336)
		(width 0.13208)
		(layer "F.Cu")
		(net "UPI_CPU0_CPU1_P1P0_DN<17>")
	)
	(segment
		(start 105.531666 -217.600276)
		(end 105.531666 -217.06459)
		(width 0.13208)
		(layer "F.Cu")
		(net "UPI_CPU0_CPU1_P1P0_DN<17>")
	)
	(segment
		(start 342.398604 -171.463208)
		(end 342.409018 -171.255436)
		(width 0.14732)
		(layer "In4.Cu")
		(net "UPI_CPU0_CPU1_P1P0_DN<17>")
	)
	(segment
		(start 354.383086 -178.354736)
		(end 354.107242 -178.110388)
		(width 0.14732)
		(layer "In4.Cu")
		(net "UPI_CPU0_CPU1_P1P0_DN<17>")
	)
	(segment
		(start 113.346484 -192.88125)
		(end 113.14303 -192.904618)
		(width 0.14732)
		(layer "In4.Cu")
		(net "UPI_CPU0_CPU1_P1P0_DN<17>")
	)
	(segment
		(start 365.593884 -216.260426)
		(end 365.593884 -216.231978)
		(width 0.0889)
		(layer "In4.Cu")
		(net "UPI_CPU0_CPU1_P1P0_DN<17>")
	)
	(segment
		(start 351.395284 -175.514254)
		(end 351.163128 -175.35525)
		(width 0.14732)
		(layer "In4.Cu")
		(net "UPI_CPU0_CPU1_P1P0_DN<17>")
	)
	(segment
		(start 366.021874 -211.4042)
		(end 366.021874 -205.486762)
		(width 0.14732)
		(layer "In4.Cu")
		(net "UPI_CPU0_CPU1_P1P0_DN<17>")
	)
	(segment
		(start 111.637572 -194.80022)
		(end 111.66094 -195.003674)
		(width 0.14732)
		(layer "In4.Cu")
		(net "UPI_CPU0_CPU1_P1P0_DN<17>")
	)
	(segment
		(start 366.06353 -215.445086)
		(end 366.06353 -215.43645)
		(width 0.0889)
		(layer "In4.Cu")
		(net "UPI_CPU0_CPU1_P1P0_DN<17>")
	)
	(segment
		(start 105.156762 -215.436704)
		(end 105.156762 -215.483948)
		(width 0.0889)
		(layer "In4.Cu")
		(net "UPI_CPU0_CPU1_P1P0_DN<17>")
	)
	(segment
		(start 276.499066 -163.119308)
		(end 238.001302 -153.231088)
		(width 0.14732)
		(layer "In4.Cu")
		(net "UPI_CPU0_CPU1_P1P0_DN<17>")
	)
	(segment
		(start 343.951306 -173.891448)
		(end 343.951052 -173.891448)
		(width 0.14732)
		(layer "In4.Cu")
		(net "UPI_CPU0_CPU1_P1P0_DN<17>")
	)
	(segment
		(start 105.29697 -217.356182)
		(end 105.374948 -217.335354)
		(width 0.0889)
		(layer "In4.Cu")
		(net "UPI_CPU0_CPU1_P1P0_DN<17>")
	)
	(segment
		(start 234.209336 -153.231088)
		(end 197.102984 -162.796982)
		(width 0.14732)
		(layer "In4.Cu")
		(net "UPI_CPU0_CPU1_P1P0_DN<17>")
	)
	(segment
		(start 322.261484 -154.191208)
		(end 279.645364 -163.119308)
		(width 0.14732)
		(layer "In4.Cu")
		(net "UPI_CPU0_CPU1_P1P0_DN<17>")
	)
	(segment
		(start 340.852506 -169.538142)
		(end 340.455504 -169.1005)
		(width 0.14732)
		(layer "In4.Cu")
		(net "UPI_CPU0_CPU1_P1P0_DN<17>")
	)
	(segment
		(start 359.178352 -189.867032)
		(end 357.89616 -186.77128)
		(width 0.14732)
		(layer "In4.Cu")
		(net "UPI_CPU0_CPU1_P1P0_DN<17>")
	)
	(segment
		(start 323.3928 -154.191208)
		(end 322.261484 -154.191208)
		(width 0.14732)
		(layer "In4.Cu")
		(net "UPI_CPU0_CPU1_P1P0_DN<17>")
	)
	(segment
		(start 366.06353 -215.43645)
		(end 366.063784 -215.422226)
		(width 0.0889)
		(layer "In4.Cu")
		(net "UPI_CPU0_CPU1_P1P0_DN<17>")
	)
	(segment
		(start 342.093804 -171.73956)
		(end 342.398604 -171.463208)
		(width 0.14732)
		(layer "In4.Cu")
		(net "UPI_CPU0_CPU1_P1P0_DN<17>")
	)
	(segment
		(start 112.708182 -193.684906)
		(end 112.504728 -193.708274)
		(width 0.14732)
		(layer "In4.Cu")
		(net "UPI_CPU0_CPU1_P1P0_DN<17>")
	)
	(segment
		(start 341.06485 -171.06265)
		(end 340.515956 -170.457114)
		(width 0.14732)
		(layer "In4.Cu")
		(net "UPI_CPU0_CPU1_P1P0_DN<17>")
	)
	(segment
		(start 112.275874 -193.996564)
		(end 112.299242 -194.200018)
		(width 0.14732)
		(layer "In4.Cu")
		(net "UPI_CPU0_CPU1_P1P0_DN<17>")
	)
	(segment
		(start 173.044358 -153.889964)
		(end 169.885106 -152.325578)
		(width 0.14732)
		(layer "In4.Cu")
		(net "UPI_CPU0_CPU1_P1P0_DN<17>")
	)
	(segment
		(start 353.339146 -177.429922)
		(end 353.3267 -177.225452)
		(width 0.14732)
		(layer "In4.Cu")
		(net "UPI_CPU0_CPU1_P1P0_DN<17>")
	)
	(segment
		(start 105.374948 -217.335354)
		(end 105.531412 -217.064336)
		(width 0.0889)
		(layer "In4.Cu")
		(net "UPI_CPU0_CPU1_P1P0_DN<17>")
	)
	(segment
		(start 352.57105 -176.749456)
		(end 352.558604 -176.544986)
		(width 0.14732)
		(layer "In4.Cu")
		(net "UPI_CPU0_CPU1_P1P0_DN<17>")
	)
	(segment
		(start 112.06988 -194.488562)
		(end 111.866426 -194.51193)
		(width 0.14732)
		(layer "In4.Cu")
		(net "UPI_CPU0_CPU1_P1P0_DN<17>")
	)
	(segment
		(start 351.802954 -176.068736)
		(end 351.790508 -175.864266)
		(width 0.14732)
		(layer "In4.Cu")
		(net "UPI_CPU0_CPU1_P1P0_DN<17>")
	)
	(segment
		(start 105.35031 -216.736422)
		(end 105.344976 -216.73947)
		(width 0.0889)
		(layer "In4.Cu")
		(net "UPI_CPU0_CPU1_P1P0_DN<17>")
	)
	(segment
		(start 366.063784 -211.809584)
		(end 366.022128 -211.767928)
		(width 0.0889)
		(layer "In4.Cu")
		(net "UPI_CPU0_CPU1_P1P0_DN<17>")
	)
	(segment
		(start 355.753924 -179.375816)
		(end 354.587302 -178.34229)
		(width 0.14732)
		(layer "In4.Cu")
		(net "UPI_CPU0_CPU1_P1P0_DN<17>")
	)
	(segment
		(start 343.924382 -173.87951)
		(end 343.01176 -173.210728)
		(width 0.14732)
		(layer "In4.Cu")
		(net "UPI_CPU0_CPU1_P1P0_DN<17>")
	)
	(segment
		(start 353.05111 -176.981358)
		(end 352.846894 -176.993804)
		(width 0.14732)
		(layer "In4.Cu")
		(net "UPI_CPU0_CPU1_P1P0_DN<17>")
	)
	(segment
		(start 342.409018 -171.255436)
		(end 342.012016 -170.817794)
		(width 0.14732)
		(layer "In4.Cu")
		(net "UPI_CPU0_CPU1_P1P0_DN<17>")
	)
	(segment
		(start 340.455504 -169.1005)
		(end 340.24824 -169.09034)
		(width 0.14732)
		(layer "In4.Cu")
		(net "UPI_CPU0_CPU1_P1P0_DN<17>")
	)
	(segment
		(start 327.870566 -156.505148)
		(end 327.87082 -156.505148)
		(width 0.14732)
		(layer "In4.Cu")
		(net "UPI_CPU0_CPU1_P1P0_DN<17>")
	)
	(segment
		(start 197.102984 -162.796982)
		(end 194.626484 -163.109148)
		(width 0.14732)
		(layer "In4.Cu")
		(net "UPI_CPU0_CPU1_P1P0_DN<17>")
	)
	(segment
		(start 169.885106 -152.325578)
		(end 166.652194 -152.239726)
		(width 0.14732)
		(layer "In4.Cu")
		(net "UPI_CPU0_CPU1_P1P0_DN<17>")
	)
	(segment
		(start 325.702676 -154.772106)
		(end 323.3928 -154.191208)
		(width 0.14732)
		(layer "In4.Cu")
		(net "UPI_CPU0_CPU1_P1P0_DN<17>")
	)
	(segment
		(start 112.299242 -194.200018)
		(end 112.06988 -194.488562)
		(width 0.14732)
		(layer "In4.Cu")
		(net "UPI_CPU0_CPU1_P1P0_DN<17>")
	)
	(segment
		(start 365.845344 -218.421204)
		(end 365.821214 -218.33205)
		(width 0.0889)
		(layer "In4.Cu")
		(net "UPI_CPU0_CPU1_P1P0_DN<17>")
	)
	(segment
		(start 105.626408 -214.424768)
		(end 105.626408 -214.644732)
		(width 0.0889)
		(layer "In4.Cu")
		(net "UPI_CPU0_CPU1_P1P0_DN<17>")
	)
	(segment
		(start 105.156762 -212.74024)
		(end 105.156762 -212.9155)
		(width 0.0889)
		(layer "In4.Cu")
		(net "UPI_CPU0_CPU1_P1P0_DN<17>")
	)
	(segment
		(start 105.255822 -213.01456)
		(end 105.255822 -213.18982)
		(width 0.0889)
		(layer "In4.Cu")
		(net "UPI_CPU0_CPU1_P1P0_DN<17>")
	)
	(segment
		(start 105.198926 -212.047328)
		(end 105.156762 -212.089492)
		(width 0.0889)
		(layer "In4.Cu")
		(net "UPI_CPU0_CPU1_P1P0_DN<17>")
	)
	(segment
		(start 105.198926 -211.791042)
		(end 105.198926 -212.02523)
		(width 0.14732)
		(layer "In4.Cu")
		(net "UPI_CPU0_CPU1_P1P0_DN<17>")
	)
	(segment
		(start 341.499698 -171.083986)
		(end 341.06485 -171.06265)
		(width 0.14732)
		(layer "In4.Cu")
		(net "UPI_CPU0_CPU1_P1P0_DN<17>")
	)
	(segment
		(start 165.247066 -152.730454)
		(end 132.671566 -172.804836)
		(width 0.14732)
		(layer "In4.Cu")
		(net "UPI_CPU0_CPU1_P1P0_DN<17>")
	)
	(segment
		(start 353.819206 -177.661824)
		(end 353.61499 -177.67427)
		(width 0.14732)
		(layer "In4.Cu")
		(net "UPI_CPU0_CPU1_P1P0_DN<17>")
	)
	(segment
		(start 111.66094 -195.003674)
		(end 111.431578 -195.292218)
		(width 0.14732)
		(layer "In4.Cu")
		(net "UPI_CPU0_CPU1_P1P0_DN<17>")
	)
	(segment
		(start 343.951052 -173.891448)
		(end 343.924382 -173.87951)
		(width 0.14732)
		(layer "In4.Cu")
		(net "UPI_CPU0_CPU1_P1P0_DN<17>")
	)
	(segment
		(start 342.072468 -172.174408)
		(end 342.093804 -171.73956)
		(width 0.14732)
		(layer "In4.Cu")
		(net "UPI_CPU0_CPU1_P1P0_DN<17>")
	)
	(segment
		(start 366.022128 -211.404454)
		(end 366.021874 -211.4042)
		(width 0.14732)
		(layer "In4.Cu")
		(net "UPI_CPU0_CPU1_P1P0_DN<17>")
	)
	(segment
		(start 113.14303 -192.904618)
		(end 112.914176 -193.192908)
		(width 0.14732)
		(layer "In4.Cu")
		(net "UPI_CPU0_CPU1_P1P0_DN<17>")
	)
	(segment
		(start 340.537292 -170.022266)
		(end 340.842092 -169.745914)
		(width 0.14732)
		(layer "In4.Cu")
		(net "UPI_CPU0_CPU1_P1P0_DN<17>")
	)
	(segment
		(start 352.078798 -176.313338)
		(end 351.802954 -176.068736)
		(width 0.14732)
		(layer "In4.Cu")
		(net "UPI_CPU0_CPU1_P1P0_DN<17>")
	)
	(segment
		(start 111.431578 -195.292218)
		(end 111.228378 -195.315586)
		(width 0.14732)
		(layer "In4.Cu")
		(net "UPI_CPU0_CPU1_P1P0_DN<17>")
	)
	(segment
		(start 366.533684 -214.622634)
		(end 366.533684 -214.461852)
		(width 0.0889)
		(layer "In4.Cu")
		(net "UPI_CPU0_CPU1_P1P0_DN<17>")
	)
	(segment
		(start 105.157016 -217.0557)
		(end 105.157016 -217.072972)
		(width 0.0889)
		(layer "In4.Cu")
		(net "UPI_CPU0_CPU1_P1P0_DN<17>")
	)
	(segment
		(start 118.593362 -186.04357)
		(end 113.552478 -192.389252)
		(width 0.14732)
		(layer "In4.Cu")
		(net "UPI_CPU0_CPU1_P1P0_DN<17>")
	)
	(segment
		(start 105.198926 -212.02523)
		(end 105.198926 -212.047328)
		(width 0.0889)
		(layer "In4.Cu")
		(net "UPI_CPU0_CPU1_P1P0_DN<17>")
	)
	(segment
		(start 340.842092 -169.745914)
		(end 340.852506 -169.538142)
		(width 0.14732)
		(layer "In4.Cu")
		(net "UPI_CPU0_CPU1_P1P0_DN<17>")
	)
	(segment
		(start 105.294938 -215.73109)
		(end 105.344214 -215.761062)
		(width 0.0889)
		(layer "In4.Cu")
		(net "UPI_CPU0_CPU1_P1P0_DN<17>")
	)
	(segment
		(start 132.671566 -172.804836)
		(end 118.593362 -186.04357)
		(width 0.14732)
		(layer "In4.Cu")
		(net "UPI_CPU0_CPU1_P1P0_DN<17>")
	)
	(segment
		(start 352.846894 -176.993804)
		(end 352.57105 -176.749456)
		(width 0.14732)
		(layer "In4.Cu")
		(net "UPI_CPU0_CPU1_P1P0_DN<17>")
	)
	(segment
		(start 105.156762 -213.8934)
		(end 105.157016 -213.893908)
		(width 0.0889)
		(layer "In4.Cu")
		(net "UPI_CPU0_CPU1_P1P0_DN<17>")
	)
	(segment
		(start 105.255822 -213.18982)
		(end 105.156762 -213.28888)
		(width 0.0889)
		(layer "In4.Cu")
		(net "UPI_CPU0_CPU1_P1P0_DN<17>")
	)
	(segment
		(start 105.156762 -212.9155)
		(end 105.255822 -213.01456)
		(width 0.0889)
		(layer "In4.Cu")
		(net "UPI_CPU0_CPU1_P1P0_DN<17>")
	)
	(segment
		(start 353.3267 -177.225452)
		(end 353.05111 -176.981358)
		(width 0.14732)
		(layer "In4.Cu")
		(net "UPI_CPU0_CPU1_P1P0_DN<17>")
	)
	(segment
		(start 112.914176 -193.192908)
		(end 112.937544 -193.396362)
		(width 0.14732)
		(layer "In4.Cu")
		(net "UPI_CPU0_CPU1_P1P0_DN<17>")
	)
	(segment
		(start 339.943186 -169.366692)
		(end 339.508338 -169.345356)
		(width 0.14732)
		(layer "In4.Cu")
		(net "UPI_CPU0_CPU1_P1P0_DN<17>")
	)
	(segment
		(start 105.344214 -215.112346)
		(end 105.343198 -215.112854)
		(width 0.0889)
		(layer "In4.Cu")
		(net "UPI_CPU0_CPU1_P1P0_DN<17>")
	)
	(segment
		(start 105.344976 -216.73947)
		(end 105.344214 -216.739978)
		(width 0.0889)
		(layer "In4.Cu")
		(net "UPI_CPU0_CPU1_P1P0_DN<17>")
	)
	(segment
		(start 359.824782 -190.525908)
		(end 359.178352 -189.867032)
		(width 0.14732)
		(layer "In4.Cu")
		(net "UPI_CPU0_CPU1_P1P0_DN<17>")
	)
	(segment
		(start 238.001302 -153.231088)
		(end 234.209336 -153.231088)
		(width 0.14732)
		(layer "In4.Cu")
		(net "UPI_CPU0_CPU1_P1P0_DN<17>")
	)
	(segment
		(start 354.094796 -177.905918)
		(end 353.819206 -177.661824)
		(width 0.14732)
		(layer "In4.Cu")
		(net "UPI_CPU0_CPU1_P1P0_DN<17>")
	)
	(segment
		(start 105.344214 -215.761062)
		(end 105.35031 -215.764618)
		(width 0.0889)
		(layer "In4.Cu")
		(net "UPI_CPU0_CPU1_P1P0_DN<17>")
	)
	(segment
		(start 105.156762 -213.28888)
		(end 105.156762 -213.8934)
		(width 0.0889)
		(layer "In4.Cu")
		(net "UPI_CPU0_CPU1_P1P0_DN<17>")
	)
	(segment
		(start 105.198672 -211.436966)
		(end 105.198672 -211.790788)
		(width 0.14732)
		(layer "In4.Cu")
		(net "UPI_CPU0_CPU1_P1P0_DN<17>")
	)
	(segment
		(start 112.504728 -193.708274)
		(end 112.275874 -193.996564)
		(width 0.14732)
		(layer "In4.Cu")
		(net "UPI_CPU0_CPU1_P1P0_DN<17>")
	)
	(segment
		(start 166.652194 -152.239726)
		(end 165.247066 -152.730454)
		(width 0.14732)
		(layer "In4.Cu")
		(net "UPI_CPU0_CPU1_P1P0_DN<17>")
	)
	(segment
		(start 112.937544 -193.396362)
		(end 112.708182 -193.684906)
		(width 0.14732)
		(layer "In4.Cu")
		(net "UPI_CPU0_CPU1_P1P0_DN<17>")
	)
	(segment
		(start 105.156762 -212.36686)
		(end 105.255822 -212.46592)
		(width 0.0889)
		(layer "In4.Cu")
		(net "UPI_CPU0_CPU1_P1P0_DN<17>")
	)
	(segment
		(start 348.045278 -175.714152)
		(end 343.951306 -173.891448)
		(width 0.14732)
		(layer "In4.Cu")
		(net "UPI_CPU0_CPU1_P1P0_DN<17>")
	)
	(segment
		(start 353.61499 -177.67427)
		(end 353.339146 -177.429922)
		(width 0.14732)
		(layer "In4.Cu")
		(net "UPI_CPU0_CPU1_P1P0_DN<17>")
	)
	(segment
		(start 111.866426 -194.51193)
		(end 111.637572 -194.80022)
		(width 0.14732)
		(layer "In4.Cu")
		(net "UPI_CPU0_CPU1_P1P0_DN<17>")
	)
	(segment
		(start 354.587302 -178.34229)
		(end 354.383086 -178.354736)
		(width 0.14732)
		(layer "In4.Cu")
		(net "UPI_CPU0_CPU1_P1P0_DN<17>")
	)
	(segment
		(start 356.60076 -181.06009)
		(end 355.753924 -179.375816)
		(width 0.14732)
		(layer "In4.Cu")
		(net "UPI_CPU0_CPU1_P1P0_DN<17>")
	)
	(segment
		(start 327.87082 -156.505148)
		(end 325.702676 -154.772106)
		(width 0.14732)
		(layer "In4.Cu")
		(net "UPI_CPU0_CPU1_P1P0_DN<17>")
	)
	(segment
		(start 366.022128 -211.74583)
		(end 366.022128 -211.404454)
		(width 0.14732)
		(layer "In4.Cu")
		(net "UPI_CPU0_CPU1_P1P0_DN<17>")
	)
	(segment
		(start 190.665608 -163.109148)
		(end 173.044358 -153.889964)
		(width 0.14732)
		(layer "In4.Cu")
		(net "UPI_CPU0_CPU1_P1P0_DN<17>")
	)
	(segment
		(start 366.06353 -217.072972)
		(end 366.06353 -217.0557)
		(width 0.0889)
		(layer "In4.Cu")
		(net "UPI_CPU0_CPU1_P1P0_DN<17>")
	)
	(segment
		(start 111.228378 -195.315586)
		(end 110.938564 -195.68033)
		(width 0.14732)
		(layer "In4.Cu")
		(net "UPI_CPU0_CPU1_P1P0_DN<17>")
	)
	(segment
		(start 366.063784 -213.93023)
		(end 366.063784 -211.809584)
		(width 0.0889)
		(layer "In4.Cu")
		(net "UPI_CPU0_CPU1_P1P0_DN<17>")
	)
	(segment
		(start 357.89616 -184.187592)
		(end 356.60076 -181.06009)
		(width 0.14732)
		(layer "In4.Cu")
		(net "UPI_CPU0_CPU1_P1P0_DN<17>")
	)
	(segment
		(start 105.198672 -211.790788)
		(end 105.198926 -211.791042)
		(width 0.14732)
		(layer "In4.Cu")
		(net "UPI_CPU0_CPU1_P1P0_DN<17>")
	)
	(segment
		(start 351.163128 -175.35525)
		(end 350.476312 -175.317404)
		(width 0.14732)
		(layer "In4.Cu")
		(net "UPI_CPU0_CPU1_P1P0_DN<17>")
	)
	(segment
		(start 352.558604 -176.544986)
		(end 352.283014 -176.300892)
		(width 0.14732)
		(layer "In4.Cu")
		(net "UPI_CPU0_CPU1_P1P0_DN<17>")
	)
	(segment
		(start 340.24824 -169.09034)
		(end 339.943186 -169.366692)
		(width 0.14732)
		(layer "In4.Cu")
		(net "UPI_CPU0_CPU1_P1P0_DN<17>")
	)
	(segment
		(start 341.804752 -170.807634)
		(end 341.499698 -171.083986)
		(width 0.14732)
		(layer "In4.Cu")
		(net "UPI_CPU0_CPU1_P1P0_DN<17>")
	)
	(segment
		(start 105.255822 -212.46592)
		(end 105.255822 -212.64118)
		(width 0.0889)
		(layer "In4.Cu")
		(net "UPI_CPU0_CPU1_P1P0_DN<17>")
	)
	(segment
		(start 352.283014 -176.300892)
		(end 352.078798 -176.313338)
		(width 0.14732)
		(layer "In4.Cu")
		(net "UPI_CPU0_CPU1_P1P0_DN<17>")
	)
	(segment
		(start 113.575846 -192.592706)
		(end 113.346484 -192.88125)
		(width 0.14732)
		(layer "In4.Cu")
		(net "UPI_CPU0_CPU1_P1P0_DN<17>")
	)
	(segment
		(start 365.68888 -218.692222)
		(end 365.845344 -218.421204)
		(width 0.0889)
		(layer "In4.Cu")
		(net "UPI_CPU0_CPU1_P1P0_DN<17>")
	)
	(segment
		(start 366.346232 -214.946992)
		(end 366.355122 -214.941912)
		(width 0.0889)
		(layer "In4.Cu")
		(net "UPI_CPU0_CPU1_P1P0_DN<17>")
	)
	(segment
		(start 113.552478 -192.389252)
		(end 113.575846 -192.592706)
		(width 0.14732)
		(layer "In4.Cu")
		(net "UPI_CPU0_CPU1_P1P0_DN<17>")
	)
	(segment
		(start 110.938564 -195.68033)
		(end 105.198672 -211.436966)
		(width 0.14732)
		(layer "In4.Cu")
		(net "UPI_CPU0_CPU1_P1P0_DN<17>")
	)
	(segment
		(start 339.508338 -169.345356)
		(end 327.870566 -156.505148)
		(width 0.14732)
		(layer "In4.Cu")
		(net "UPI_CPU0_CPU1_P1P0_DN<17>")
	)
	(segment
		(start 348.618556 -175.75149)
		(end 348.045278 -175.714152)
		(width 0.14732)
		(layer "In4.Cu")
		(net "UPI_CPU0_CPU1_P1P0_DN<17>")
	)
	(segment
		(start 340.515956 -170.457114)
		(end 340.537292 -170.022266)
		(width 0.14732)
		(layer "In4.Cu")
		(net "UPI_CPU0_CPU1_P1P0_DN<17>")
	)
	(segment
		(start 279.645364 -163.119308)
		(end 276.499066 -163.119308)
		(width 0.14732)
		(layer "In4.Cu")
		(net "UPI_CPU0_CPU1_P1P0_DN<17>")
	)
	(segment
		(start 105.343198 -215.112854)
		(end 105.335324 -215.117426)
		(width 0.0889)
		(layer "In4.Cu")
		(net "UPI_CPU0_CPU1_P1P0_DN<17>")
	)
	(segment
		(start 365.593884 -217.8939)
		(end 365.593884 -217.859864)
		(width 0.0889)
		(layer "In4.Cu")
		(net "UPI_CPU0_CPU1_P1P0_DN<17>")
	)
	(segment
		(start 351.790508 -175.864266)
		(end 351.395284 -175.514254)
		(width 0.14732)
		(layer "In4.Cu")
		(net "UPI_CPU0_CPU1_P1P0_DN<17>")
	)
	(segment
		(start 342.012016 -170.817794)
		(end 341.804752 -170.807634)
		(width 0.14732)
		(layer "In4.Cu")
		(net "UPI_CPU0_CPU1_P1P0_DN<17>")
	)
	(segment
		(start 366.022128 -211.767928)
		(end 366.022128 -211.74583)
		(width 0.0889)
		(layer "In4.Cu")
		(net "UPI_CPU0_CPU1_P1P0_DN<17>")
	)
	(segment
		(start 354.107242 -178.110388)
		(end 354.094796 -177.905918)
		(width 0.14732)
		(layer "In4.Cu")
		(net "UPI_CPU0_CPU1_P1P0_DN<17>")
	)
	(segment
		(start 105.255822 -212.64118)
		(end 105.156762 -212.74024)
		(width 0.0889)
		(layer "In4.Cu")
		(net "UPI_CPU0_CPU1_P1P0_DN<17>")
	)
	(segment
		(start 350.476312 -175.317404)
		(end 348.618556 -175.75149)
		(width 0.14732)
		(layer "In4.Cu")
		(net "UPI_CPU0_CPU1_P1P0_DN<17>")
	)
	(segment
		(start 105.156762 -212.089492)
		(end 105.156762 -212.36686)
		(width 0.0889)
		(layer "In4.Cu")
		(net "UPI_CPU0_CPU1_P1P0_DN<17>")
	)
	(segment
		(start 194.626484 -163.109148)
		(end 190.665608 -163.109148)
		(width 0.14732)
		(layer "In4.Cu")
		(net "UPI_CPU0_CPU1_P1P0_DN<17>")
	)
	(segment
		(start 366.021874 -205.486762)
		(end 359.824782 -190.525908)
		(width 0.14732)
		(layer "In4.Cu")
		(net "UPI_CPU0_CPU1_P1P0_DN<17>")
	)
	(segment
		(start 343.01176 -173.210728)
		(end 342.072468 -172.174408)
		(width 0.14732)
		(layer "In4.Cu")
		(net "UPI_CPU0_CPU1_P1P0_DN<17>")
	)
	(segment
		(start 357.89616 -186.77128)
		(end 357.89616 -184.187592)
		(width 0.14732)
		(layer "In4.Cu")
		(net "UPI_CPU0_CPU1_P1P0_DN<17>")
	)
	(arc
		(start 365.876332 -217.388694)
		(mid 366.011265 -217.25534)
		(end 366.06353 -217.072972)
		(width 0.0889)
		(layer "In4.Cu")
		(net "UPI_CPU0_CPU1_P1P0_DN<17>")
	)
	(arc
		(start 365.821214 -218.33205)
		(mid 365.812773 -218.32565)
		(end 365.80445 -218.319096)
		(width 0.0889)
		(layer "In4.Cu")
		(net "UPI_CPU0_CPU1_P1P0_DN<17>")
	)
	(arc
		(start 366.355122 -214.941912)
		(mid 366.486036 -214.805552)
		(end 366.533684 -214.622634)
		(width 0.0889)
		(layer "In4.Cu")
		(net "UPI_CPU0_CPU1_P1P0_DN<17>")
	)
	(arc
		(start 365.876332 -215.760808)
		(mid 366.011265 -215.627454)
		(end 366.06353 -215.445086)
		(width 0.0889)
		(layer "In4.Cu")
		(net "UPI_CPU0_CPU1_P1P0_DN<17>")
	)
	(arc
		(start 365.80445 -218.319096)
		(mid 365.652368 -218.129664)
		(end 365.593884 -217.8939)
		(width 0.0889)
		(layer "In4.Cu")
		(net "UPI_CPU0_CPU1_P1P0_DN<17>")
	)
	(arc
		(start 365.593884 -217.859864)
		(mid 365.674046 -217.587675)
		(end 365.876332 -217.388694)
		(width 0.0889)
		(layer "In4.Cu")
		(net "UPI_CPU0_CPU1_P1P0_DN<17>")
	)
	(arc
		(start 105.35031 -215.764618)
		(mid 105.626884 -216.25052)
		(end 105.35031 -216.736422)
		(width 0.0889)
		(layer "In4.Cu")
		(net "UPI_CPU0_CPU1_P1P0_DN<17>")
	)
	(arc
		(start 366.06353 -217.0557)
		(mid 366.01126 -216.873335)
		(end 365.876332 -216.739978)
		(width 0.0889)
		(layer "In4.Cu")
		(net "UPI_CPU0_CPU1_P1P0_DN<17>")
	)
	(arc
		(start 366.07877 -213.968838)
		(mid 366.070948 -213.949662)
		(end 366.063784 -213.93023)
		(width 0.0889)
		(layer "In4.Cu")
		(net "UPI_CPU0_CPU1_P1P0_DN<17>")
	)
	(arc
		(start 105.335324 -215.117426)
		(mid 105.20807 -215.247392)
		(end 105.157016 -215.421972)
		(width 0.0889)
		(layer "In4.Cu")
		(net "UPI_CPU0_CPU1_P1P0_DN<17>")
	)
	(arc
		(start 366.063784 -215.422226)
		(mid 366.142915 -215.14769)
		(end 366.346232 -214.946992)
		(width 0.0889)
		(layer "In4.Cu")
		(net "UPI_CPU0_CPU1_P1P0_DN<17>")
	)
	(arc
		(start 105.344214 -216.739978)
		(mid 105.209281 -216.873332)
		(end 105.157016 -217.0557)
		(width 0.0889)
		(layer "In4.Cu")
		(net "UPI_CPU0_CPU1_P1P0_DN<17>")
	)
	(arc
		(start 105.341166 -214.093298)
		(mid 105.515129 -214.232062)
		(end 105.626408 -214.424768)
		(width 0.0889)
		(layer "In4.Cu")
		(net "UPI_CPU0_CPU1_P1P0_DN<17>")
	)
	(arc
		(start 105.626408 -214.644732)
		(mid 105.545497 -214.91486)
		(end 105.344214 -215.112346)
		(width 0.0889)
		(layer "In4.Cu")
		(net "UPI_CPU0_CPU1_P1P0_DN<17>")
	)
	(arc
		(start 105.157016 -217.072972)
		(mid 105.19569 -217.23004)
		(end 105.29697 -217.356182)
		(width 0.0889)
		(layer "In4.Cu")
		(net "UPI_CPU0_CPU1_P1P0_DN<17>")
	)
	(arc
		(start 366.34928 -214.261954)
		(mid 366.188925 -214.138568)
		(end 366.07877 -213.968838)
		(width 0.0889)
		(layer "In4.Cu")
		(net "UPI_CPU0_CPU1_P1P0_DN<17>")
	)
	(arc
		(start 365.876332 -216.739978)
		(mid 365.671997 -216.537373)
		(end 365.593884 -216.260426)
		(width 0.0889)
		(layer "In4.Cu")
		(net "UPI_CPU0_CPU1_P1P0_DN<17>")
	)
	(arc
		(start 105.157016 -213.893908)
		(mid 105.232021 -214.009367)
		(end 105.341166 -214.093298)
		(width 0.0889)
		(layer "In4.Cu")
		(net "UPI_CPU0_CPU1_P1P0_DN<17>")
	)
	(arc
		(start 105.157016 -215.421972)
		(mid 105.156819 -215.429337)
		(end 105.156762 -215.436704)
		(width 0.0889)
		(layer "In4.Cu")
		(net "UPI_CPU0_CPU1_P1P0_DN<17>")
	)
	(arc
		(start 366.533684 -214.461852)
		(mid 366.458613 -214.34611)
		(end 366.34928 -214.261954)
		(width 0.0889)
		(layer "In4.Cu")
		(net "UPI_CPU0_CPU1_P1P0_DN<17>")
	)
	(arc
		(start 365.593884 -216.231978)
		(mid 365.674046 -215.959789)
		(end 365.876332 -215.760808)
		(width 0.0889)
		(layer "In4.Cu")
		(net "UPI_CPU0_CPU1_P1P0_DN<17>")
	)
	(arc
		(start 105.156762 -215.483948)
		(mid 105.193655 -215.625517)
		(end 105.294938 -215.73109)
		(width 0.0889)
		(layer "In4.Cu")
		(net "UPI_CPU0_CPU1_P1P0_DN<17>")
	)
	(segment
		(start 104.121712 -218.414346)
		(end 104.121712 -217.87866)
		(width 0.13208)
		(layer "F.Cu")
		(net "UPI_CPU0_CPU1_P1P0_DN<16>")
	)
	(segment
		(start 367.09858 -217.87866)
		(end 367.098834 -217.878406)
		(width 0.13208)
		(layer "F.Cu")
		(net "UPI_CPU0_CPU1_P1P0_DN<16>")
	)
	(segment
		(start 367.09858 -218.414346)
		(end 367.09858 -217.87866)
		(width 0.13208)
		(layer "F.Cu")
		(net "UPI_CPU0_CPU1_P1P0_DN<16>")
	)
	(segment
		(start 104.121712 -217.87866)
		(end 104.121966 -217.878406)
		(width 0.13208)
		(layer "F.Cu")
		(net "UPI_CPU0_CPU1_P1P0_DN<16>")
	)
	(segment
		(start 196.888862 -161.676588)
		(end 194.554856 -161.971228)
		(width 0.14732)
		(layer "In4.Cu")
		(net "UPI_CPU0_CPU1_P1P0_DN<16>")
	)
	(segment
		(start 367.663984 -214.63254)
		(end 367.663984 -214.4268)
		(width 0.0889)
		(layer "In4.Cu")
		(net "UPI_CPU0_CPU1_P1P0_DN<16>")
	)
	(segment
		(start 367.098834 -217.878406)
		(end 367.083086 -217.851228)
		(width 0.0889)
		(layer "In4.Cu")
		(net "UPI_CPU0_CPU1_P1P0_DN<16>")
	)
	(segment
		(start 103.92791 -213.3727)
		(end 104.02697 -213.47176)
		(width 0.0889)
		(layer "In4.Cu")
		(net "UPI_CPU0_CPU1_P1P0_DN<16>")
	)
	(segment
		(start 348.06255 -174.376588)
		(end 346.458794 -172.301408)
		(width 0.14732)
		(layer "In4.Cu")
		(net "UPI_CPU0_CPU1_P1P0_DN<16>")
	)
	(segment
		(start 367.194084 -217.07856)
		(end 367.194084 -217.064336)
		(width 0.0889)
		(layer "In4.Cu")
		(net "UPI_CPU0_CPU1_P1P0_DN<16>")
	)
	(segment
		(start 132.04698 -171.872402)
		(end 117.128798 -185.899044)
		(width 0.14732)
		(layer "In4.Cu")
		(net "UPI_CPU0_CPU1_P1P0_DN<16>")
	)
	(segment
		(start 117.128798 -185.899044)
		(end 109.979714 -194.898772)
		(width 0.14732)
		(layer "In4.Cu")
		(net "UPI_CPU0_CPU1_P1P0_DN<16>")
	)
	(segment
		(start 352.605086 -174.31512)
		(end 350.617536 -174.140114)
		(width 0.14732)
		(layer "In4.Cu")
		(net "UPI_CPU0_CPU1_P1P0_DN<16>")
	)
	(segment
		(start 104.309926 -215.92667)
		(end 104.312466 -215.92794)
		(width 0.0889)
		(layer "In4.Cu")
		(net "UPI_CPU0_CPU1_P1P0_DN<16>")
	)
	(segment
		(start 359.00868 -183.972708)
		(end 357.547926 -180.445664)
		(width 0.14732)
		(layer "In4.Cu")
		(net "UPI_CPU0_CPU1_P1P0_DN<16>")
	)
	(segment
		(start 359.00868 -186.497722)
		(end 359.00868 -183.972708)
		(width 0.14732)
		(layer "In4.Cu")
		(net "UPI_CPU0_CPU1_P1P0_DN<16>")
	)
	(segment
		(start 104.026462 -217.064336)
		(end 104.026462 -217.071956)
		(width 0.0889)
		(layer "In4.Cu")
		(net "UPI_CPU0_CPU1_P1P0_DN<16>")
	)
	(segment
		(start 103.984806 -211.790788)
		(end 103.98506 -211.791042)
		(width 0.14732)
		(layer "In4.Cu")
		(net "UPI_CPU0_CPU1_P1P0_DN<16>")
	)
	(segment
		(start 166.461948 -151.020018)
		(end 165.12921 -151.485346)
		(width 0.14732)
		(layer "In4.Cu")
		(net "UPI_CPU0_CPU1_P1P0_DN<16>")
	)
	(segment
		(start 103.98506 -211.791042)
		(end 103.98506 -212.00491)
		(width 0.14732)
		(layer "In4.Cu")
		(net "UPI_CPU0_CPU1_P1P0_DN<16>")
	)
	(segment
		(start 279.527254 -161.981388)
		(end 276.643338 -161.981388)
		(width 0.14732)
		(layer "In4.Cu")
		(net "UPI_CPU0_CPU1_P1P0_DN<16>")
	)
	(segment
		(start 326.155558 -153.704544)
		(end 323.563996 -153.053288)
		(width 0.14732)
		(layer "In4.Cu")
		(net "UPI_CPU0_CPU1_P1P0_DN<16>")
	)
	(segment
		(start 367.663984 -214.4268)
		(end 367.66373 -214.426546)
		(width 0.0889)
		(layer "In4.Cu")
		(net "UPI_CPU0_CPU1_P1P0_DN<16>")
	)
	(segment
		(start 367.380774 -215.1126)
		(end 367.381536 -215.112092)
		(width 0.0889)
		(layer "In4.Cu")
		(net "UPI_CPU0_CPU1_P1P0_DN<16>")
	)
	(segment
		(start 355.026468 -175.838866)
		(end 352.605086 -174.31512)
		(width 0.14732)
		(layer "In4.Cu")
		(net "UPI_CPU0_CPU1_P1P0_DN<16>")
	)
	(segment
		(start 103.92791 -213.19744)
		(end 103.92791 -213.3727)
		(width 0.0889)
		(layer "In4.Cu")
		(net "UPI_CPU0_CPU1_P1P0_DN<16>")
	)
	(segment
		(start 366.917732 -216.578434)
		(end 366.911636 -216.574878)
		(width 0.0889)
		(layer "In4.Cu")
		(net "UPI_CPU0_CPU1_P1P0_DN<16>")
	)
	(segment
		(start 366.911636 -215.926162)
		(end 366.917732 -215.922606)
		(width 0.0889)
		(layer "In4.Cu")
		(net "UPI_CPU0_CPU1_P1P0_DN<16>")
	)
	(segment
		(start 367.23574 -205.504542)
		(end 360.770424 -189.896496)
		(width 0.14732)
		(layer "In4.Cu")
		(net "UPI_CPU0_CPU1_P1P0_DN<16>")
	)
	(segment
		(start 234.074462 -152.090628)
		(end 196.888862 -161.676842)
		(width 0.14732)
		(layer "In4.Cu")
		(net "UPI_CPU0_CPU1_P1P0_DN<16>")
	)
	(segment
		(start 360.157268 -189.271148)
		(end 359.00868 -186.497722)
		(width 0.14732)
		(layer "In4.Cu")
		(net "UPI_CPU0_CPU1_P1P0_DN<16>")
	)
	(segment
		(start 103.98506 -212.027008)
		(end 104.02697 -212.068918)
		(width 0.0889)
		(layer "In4.Cu")
		(net "UPI_CPU0_CPU1_P1P0_DN<16>")
	)
	(segment
		(start 104.026462 -215.414606)
		(end 104.026462 -215.436704)
		(width 0.0889)
		(layer "In4.Cu")
		(net "UPI_CPU0_CPU1_P1P0_DN<16>")
	)
	(segment
		(start 165.12921 -151.485346)
		(end 132.04698 -171.872402)
		(width 0.14732)
		(layer "In4.Cu")
		(net "UPI_CPU0_CPU1_P1P0_DN<16>")
	)
	(segment
		(start 104.02697 -212.068918)
		(end 104.02697 -212.51672)
		(width 0.0889)
		(layer "In4.Cu")
		(net "UPI_CPU0_CPU1_P1P0_DN<16>")
	)
	(segment
		(start 103.98506 -212.00491)
		(end 103.98506 -212.027008)
		(width 0.0889)
		(layer "In4.Cu")
		(net "UPI_CPU0_CPU1_P1P0_DN<16>")
	)
	(segment
		(start 366.94237 -217.607388)
		(end 366.9665 -217.518234)
		(width 0.0889)
		(layer "In4.Cu")
		(net "UPI_CPU0_CPU1_P1P0_DN<16>")
	)
	(segment
		(start 367.235994 -211.72297)
		(end 367.235994 -211.290662)
		(width 0.14732)
		(layer "In4.Cu")
		(net "UPI_CPU0_CPU1_P1P0_DN<16>")
	)
	(segment
		(start 170.054778 -151.115014)
		(end 166.461948 -151.020018)
		(width 0.14732)
		(layer "In4.Cu")
		(net "UPI_CPU0_CPU1_P1P0_DN<16>")
	)
	(segment
		(start 104.312466 -215.92794)
		(end 104.318054 -215.931242)
		(width 0.0889)
		(layer "In4.Cu")
		(net "UPI_CPU0_CPU1_P1P0_DN<16>")
	)
	(segment
		(start 104.308402 -215.925654)
		(end 104.309926 -215.92667)
		(width 0.0889)
		(layer "In4.Cu")
		(net "UPI_CPU0_CPU1_P1P0_DN<16>")
	)
	(segment
		(start 103.92791 -212.79104)
		(end 104.02697 -212.8901)
		(width 0.0889)
		(layer "In4.Cu")
		(net "UPI_CPU0_CPU1_P1P0_DN<16>")
	)
	(segment
		(start 367.19383 -211.787232)
		(end 367.235994 -211.745068)
		(width 0.0889)
		(layer "In4.Cu")
		(net "UPI_CPU0_CPU1_P1P0_DN<16>")
	)
	(segment
		(start 367.23574 -211.290408)
		(end 367.23574 -205.504542)
		(width 0.14732)
		(layer "In4.Cu")
		(net "UPI_CPU0_CPU1_P1P0_DN<16>")
	)
	(segment
		(start 367.372646 -215.117172)
		(end 367.380774 -215.1126)
		(width 0.0889)
		(layer "In4.Cu")
		(net "UPI_CPU0_CPU1_P1P0_DN<16>")
	)
	(segment
		(start 355.558852 -176.426622)
		(end 355.026468 -175.838866)
		(width 0.14732)
		(layer "In4.Cu")
		(net "UPI_CPU0_CPU1_P1P0_DN<16>")
	)
	(segment
		(start 104.02697 -212.51672)
		(end 103.92791 -212.61578)
		(width 0.0889)
		(layer "In4.Cu")
		(net "UPI_CPU0_CPU1_P1P0_DN<16>")
	)
	(segment
		(start 367.19383 -213.894416)
		(end 367.19383 -211.787232)
		(width 0.0889)
		(layer "In4.Cu")
		(net "UPI_CPU0_CPU1_P1P0_DN<16>")
	)
	(segment
		(start 238.135668 -152.090628)
		(end 234.074462 -152.090628)
		(width 0.14732)
		(layer "In4.Cu")
		(net "UPI_CPU0_CPU1_P1P0_DN<16>")
	)
	(segment
		(start 328.690478 -155.730702)
		(end 326.155558 -153.704544)
		(width 0.14732)
		(layer "In4.Cu")
		(net "UPI_CPU0_CPU1_P1P0_DN<16>")
	)
	(segment
		(start 276.643338 -161.981388)
		(end 238.135668 -152.090628)
		(width 0.14732)
		(layer "In4.Cu")
		(net "UPI_CPU0_CPU1_P1P0_DN<16>")
	)
	(segment
		(start 367.235994 -211.290662)
		(end 367.23574 -211.290408)
		(width 0.14732)
		(layer "In4.Cu")
		(net "UPI_CPU0_CPU1_P1P0_DN<16>")
	)
	(segment
		(start 366.902746 -215.931242)
		(end 366.911636 -215.926162)
		(width 0.0889)
		(layer "In4.Cu")
		(net "UPI_CPU0_CPU1_P1P0_DN<16>")
	)
	(segment
		(start 367.235994 -211.745068)
		(end 367.235994 -211.72297)
		(width 0.0889)
		(layer "In4.Cu")
		(net "UPI_CPU0_CPU1_P1P0_DN<16>")
	)
	(segment
		(start 194.554856 -161.971228)
		(end 190.99149 -161.971228)
		(width 0.14732)
		(layer "In4.Cu")
		(net "UPI_CPU0_CPU1_P1P0_DN<16>")
	)
	(segment
		(start 104.309164 -216.574878)
		(end 104.296972 -216.58199)
		(width 0.0889)
		(layer "In4.Cu")
		(net "UPI_CPU0_CPU1_P1P0_DN<16>")
	)
	(segment
		(start 104.496108 -214.593424)
		(end 104.496108 -214.622634)
		(width 0.0889)
		(layer "In4.Cu")
		(net "UPI_CPU0_CPU1_P1P0_DN<16>")
	)
	(segment
		(start 104.318054 -216.569798)
		(end 104.309164 -216.574878)
		(width 0.0889)
		(layer "In4.Cu")
		(net "UPI_CPU0_CPU1_P1P0_DN<16>")
	)
	(segment
		(start 103.984806 -211.357718)
		(end 103.984806 -211.790788)
		(width 0.14732)
		(layer "In4.Cu")
		(net "UPI_CPU0_CPU1_P1P0_DN<16>")
	)
	(segment
		(start 104.02697 -212.8901)
		(end 104.02697 -213.09838)
		(width 0.0889)
		(layer "In4.Cu")
		(net "UPI_CPU0_CPU1_P1P0_DN<16>")
	)
	(segment
		(start 367.083086 -217.851228)
		(end 366.94237 -217.607388)
		(width 0.0889)
		(layer "In4.Cu")
		(net "UPI_CPU0_CPU1_P1P0_DN<16>")
	)
	(segment
		(start 104.309164 -217.554048)
		(end 104.318054 -217.559128)
		(width 0.0889)
		(layer "In4.Cu")
		(net "UPI_CPU0_CPU1_P1P0_DN<16>")
	)
	(segment
		(start 357.547926 -180.445664)
		(end 355.558852 -176.426622)
		(width 0.14732)
		(layer "In4.Cu")
		(net "UPI_CPU0_CPU1_P1P0_DN<16>")
	)
	(segment
		(start 346.458794 -172.301408)
		(end 328.690478 -155.730702)
		(width 0.14732)
		(layer "In4.Cu")
		(net "UPI_CPU0_CPU1_P1P0_DN<16>")
	)
	(segment
		(start 104.303068 -215.922606)
		(end 104.308402 -215.925654)
		(width 0.0889)
		(layer "In4.Cu")
		(net "UPI_CPU0_CPU1_P1P0_DN<16>")
	)
	(segment
		(start 196.888862 -161.676842)
		(end 196.888862 -161.676588)
		(width 0.14732)
		(layer "In4.Cu")
		(net "UPI_CPU0_CPU1_P1P0_DN<16>")
	)
	(segment
		(start 104.317546 -214.941912)
		(end 104.308656 -214.946992)
		(width 0.0889)
		(layer "In4.Cu")
		(net "UPI_CPU0_CPU1_P1P0_DN<16>")
	)
	(segment
		(start 366.911636 -216.574878)
		(end 366.902746 -216.569798)
		(width 0.0889)
		(layer "In4.Cu")
		(net "UPI_CPU0_CPU1_P1P0_DN<16>")
	)
	(segment
		(start 360.770424 -189.896496)
		(end 360.157268 -189.271148)
		(width 0.14732)
		(layer "In4.Cu")
		(net "UPI_CPU0_CPU1_P1P0_DN<16>")
	)
	(segment
		(start 348.35592 -174.610268)
		(end 348.06255 -174.376588)
		(width 0.14732)
		(layer "In4.Cu")
		(net "UPI_CPU0_CPU1_P1P0_DN<16>")
	)
	(segment
		(start 104.02697 -213.09838)
		(end 103.92791 -213.19744)
		(width 0.0889)
		(layer "In4.Cu")
		(net "UPI_CPU0_CPU1_P1P0_DN<16>")
	)
	(segment
		(start 104.02697 -213.47176)
		(end 104.02697 -213.770718)
		(width 0.0889)
		(layer "In4.Cu")
		(net "UPI_CPU0_CPU1_P1P0_DN<16>")
	)
	(segment
		(start 109.979714 -194.898772)
		(end 103.984806 -211.357718)
		(width 0.14732)
		(layer "In4.Cu")
		(net "UPI_CPU0_CPU1_P1P0_DN<16>")
	)
	(segment
		(start 348.596966 -174.620936)
		(end 348.35592 -174.610268)
		(width 0.14732)
		(layer "In4.Cu")
		(net "UPI_CPU0_CPU1_P1P0_DN<16>")
	)
	(segment
		(start 323.563996 -153.053288)
		(end 322.143374 -153.053288)
		(width 0.14732)
		(layer "In4.Cu")
		(net "UPI_CPU0_CPU1_P1P0_DN<16>")
	)
	(segment
		(start 322.143374 -153.053288)
		(end 279.527254 -161.981388)
		(width 0.14732)
		(layer "In4.Cu")
		(net "UPI_CPU0_CPU1_P1P0_DN<16>")
	)
	(segment
		(start 350.617536 -174.140114)
		(end 348.596966 -174.620936)
		(width 0.14732)
		(layer "In4.Cu")
		(net "UPI_CPU0_CPU1_P1P0_DN<16>")
	)
	(segment
		(start 104.27843 -218.149424)
		(end 104.121966 -217.878406)
		(width 0.0889)
		(layer "In4.Cu")
		(net "UPI_CPU0_CPU1_P1P0_DN<16>")
	)
	(segment
		(start 104.356662 -218.170252)
		(end 104.27843 -218.149424)
		(width 0.0889)
		(layer "In4.Cu")
		(net "UPI_CPU0_CPU1_P1P0_DN<16>")
	)
	(segment
		(start 173.5709 -152.856692)
		(end 170.054778 -151.115014)
		(width 0.14732)
		(layer "In4.Cu")
		(net "UPI_CPU0_CPU1_P1P0_DN<16>")
	)
	(segment
		(start 103.92791 -212.61578)
		(end 103.92791 -212.79104)
		(width 0.0889)
		(layer "In4.Cu")
		(net "UPI_CPU0_CPU1_P1P0_DN<16>")
	)
	(segment
		(start 190.99149 -161.971228)
		(end 173.5709 -152.856692)
		(width 0.14732)
		(layer "In4.Cu")
		(net "UPI_CPU0_CPU1_P1P0_DN<16>")
	)
	(arc
		(start 367.194084 -215.43645)
		(mid 367.241763 -215.25355)
		(end 367.372646 -215.117172)
		(width 0.0889)
		(layer "In4.Cu")
		(net "UPI_CPU0_CPU1_P1P0_DN<16>")
	)
	(arc
		(start 367.194084 -217.064336)
		(mid 367.120168 -216.784834)
		(end 366.917732 -216.578434)
		(width 0.0889)
		(layer "In4.Cu")
		(net "UPI_CPU0_CPU1_P1P0_DN<16>")
	)
	(arc
		(start 367.381536 -215.112092)
		(mid 367.585871 -214.909487)
		(end 367.663984 -214.63254)
		(width 0.0889)
		(layer "In4.Cu")
		(net "UPI_CPU0_CPU1_P1P0_DN<16>")
	)
	(arc
		(start 104.026462 -215.436704)
		(mid 104.100453 -215.71627)
		(end 104.303068 -215.922606)
		(width 0.0889)
		(layer "In4.Cu")
		(net "UPI_CPU0_CPU1_P1P0_DN<16>")
	)
	(arc
		(start 104.496616 -217.878406)
		(mid 104.459756 -218.040203)
		(end 104.356662 -218.170252)
		(width 0.0889)
		(layer "In4.Cu")
		(net "UPI_CPU0_CPU1_P1P0_DN<16>")
	)
	(arc
		(start 104.318054 -215.931242)
		(mid 104.496651 -216.25052)
		(end 104.318054 -216.569798)
		(width 0.0889)
		(layer "In4.Cu")
		(net "UPI_CPU0_CPU1_P1P0_DN<16>")
	)
	(arc
		(start 366.983264 -217.50528)
		(mid 367.135771 -217.315182)
		(end 367.194084 -217.07856)
		(width 0.0889)
		(layer "In4.Cu")
		(net "UPI_CPU0_CPU1_P1P0_DN<16>")
	)
	(arc
		(start 367.37798 -214.093552)
		(mid 367.268877 -214.009726)
		(end 367.19383 -213.894416)
		(width 0.0889)
		(layer "In4.Cu")
		(net "UPI_CPU0_CPU1_P1P0_DN<16>")
	)
	(arc
		(start 366.902746 -216.569798)
		(mid 366.72427 -216.25052)
		(end 366.902746 -215.931242)
		(width 0.0889)
		(layer "In4.Cu")
		(net "UPI_CPU0_CPU1_P1P0_DN<16>")
	)
	(arc
		(start 104.02697 -213.770718)
		(mid 104.101274 -214.050833)
		(end 104.304592 -214.257382)
		(width 0.0889)
		(layer "In4.Cu")
		(net "UPI_CPU0_CPU1_P1P0_DN<16>")
	)
	(arc
		(start 367.64849 -214.386922)
		(mid 367.538424 -214.217013)
		(end 367.37798 -214.093552)
		(width 0.0889)
		(layer "In4.Cu")
		(net "UPI_CPU0_CPU1_P1P0_DN<16>")
	)
	(arc
		(start 104.304592 -214.257382)
		(mid 104.444834 -214.400031)
		(end 104.496108 -214.593424)
		(width 0.0889)
		(layer "In4.Cu")
		(net "UPI_CPU0_CPU1_P1P0_DN<16>")
	)
	(arc
		(start 104.496108 -214.622634)
		(mid 104.448429 -214.805534)
		(end 104.317546 -214.941912)
		(width 0.0889)
		(layer "In4.Cu")
		(net "UPI_CPU0_CPU1_P1P0_DN<16>")
	)
	(arc
		(start 104.296972 -216.58199)
		(mid 104.098744 -216.787838)
		(end 104.026462 -217.064336)
		(width 0.0889)
		(layer "In4.Cu")
		(net "UPI_CPU0_CPU1_P1P0_DN<16>")
	)
	(arc
		(start 104.318054 -217.559128)
		(mid 104.448968 -217.695488)
		(end 104.496616 -217.878406)
		(width 0.0889)
		(layer "In4.Cu")
		(net "UPI_CPU0_CPU1_P1P0_DN<16>")
	)
	(arc
		(start 366.9665 -217.518234)
		(mid 366.974943 -217.511836)
		(end 366.983264 -217.50528)
		(width 0.0889)
		(layer "In4.Cu")
		(net "UPI_CPU0_CPU1_P1P0_DN<16>")
	)
	(arc
		(start 104.308656 -214.946992)
		(mid 104.107374 -215.144479)
		(end 104.026462 -215.414606)
		(width 0.0889)
		(layer "In4.Cu")
		(net "UPI_CPU0_CPU1_P1P0_DN<16>")
	)
	(arc
		(start 366.917732 -215.922606)
		(mid 367.120208 -215.716083)
		(end 367.194084 -215.43645)
		(width 0.0889)
		(layer "In4.Cu")
		(net "UPI_CPU0_CPU1_P1P0_DN<16>")
	)
	(arc
		(start 104.026462 -217.071956)
		(mid 104.104091 -217.350369)
		(end 104.309164 -217.554048)
		(width 0.0889)
		(layer "In4.Cu")
		(net "UPI_CPU0_CPU1_P1P0_DN<16>")
	)
	(arc
		(start 367.66373 -214.426546)
		(mid 367.656459 -214.4066)
		(end 367.64849 -214.386922)
		(width 0.0889)
		(layer "In4.Cu")
		(net "UPI_CPU0_CPU1_P1P0_DN<16>")
	)
	(segment
		(start 367.568734 -219.228162)
		(end 367.568734 -218.692476)
		(width 0.13208)
		(layer "F.Cu")
		(net "UPI_CPU0_CPU1_P1P0_DN<15>")
	)
	(segment
		(start 103.652066 -217.06459)
		(end 103.651812 -217.064336)
		(width 0.13208)
		(layer "F.Cu")
		(net "UPI_CPU0_CPU1_P1P0_DN<15>")
	)
	(segment
		(start 103.652066 -217.600276)
		(end 103.652066 -217.06459)
		(width 0.13208)
		(layer "F.Cu")
		(net "UPI_CPU0_CPU1_P1P0_DN<15>")
	)
	(segment
		(start 367.568734 -218.692476)
		(end 367.56848 -218.692222)
		(width 0.13208)
		(layer "F.Cu")
		(net "UPI_CPU0_CPU1_P1P0_DN<15>")
	)
	(segment
		(start 110.714028 -193.065654)
		(end 110.542578 -193.085466)
		(width 0.14732)
		(layer "In4.Cu")
		(net "UPI_CPU0_CPU1_P1P0_DN<15>")
	)
	(segment
		(start 367.924842 -211.739988)
		(end 367.924842 -211.71789)
		(width 0.0889)
		(layer "In4.Cu")
		(net "UPI_CPU0_CPU1_P1P0_DN<15>")
	)
	(segment
		(start 360.638852 -188.962284)
		(end 359.59796 -186.448192)
		(width 0.14732)
		(layer "In4.Cu")
		(net "UPI_CPU0_CPU1_P1P0_DN<15>")
	)
	(segment
		(start 103.464614 -215.761062)
		(end 103.467154 -215.762586)
		(width 0.0889)
		(layer "In4.Cu")
		(net "UPI_CPU0_CPU1_P1P0_DN<15>")
	)
	(segment
		(start 367.473484 -216.260426)
		(end 367.473484 -216.231978)
		(width 0.0889)
		(layer "In4.Cu")
		(net "UPI_CPU0_CPU1_P1P0_DN<15>")
	)
	(segment
		(start 110.542578 -193.085466)
		(end 110.271052 -193.42735)
		(width 0.14732)
		(layer "In4.Cu")
		(net "UPI_CPU0_CPU1_P1P0_DN<15>")
	)
	(segment
		(start 166.634414 -150.358856)
		(end 164.8841 -150.970234)
		(width 0.14732)
		(layer "In4.Cu")
		(net "UPI_CPU0_CPU1_P1P0_DN<15>")
	)
	(segment
		(start 164.8841 -150.970234)
		(end 131.699254 -171.420028)
		(width 0.14732)
		(layer "In4.Cu")
		(net "UPI_CPU0_CPU1_P1P0_DN<15>")
	)
	(segment
		(start 368.225832 -214.946992)
		(end 368.234722 -214.941912)
		(width 0.0889)
		(layer "In4.Cu")
		(net "UPI_CPU0_CPU1_P1P0_DN<15>")
	)
	(segment
		(start 354.204778 -174.64405)
		(end 353.85121 -174.387256)
		(width 0.14732)
		(layer "In4.Cu")
		(net "UPI_CPU0_CPU1_P1P0_DN<15>")
	)
	(segment
		(start 368.413284 -214.622634)
		(end 368.413538 -214.62238)
		(width 0.0889)
		(layer "In4.Cu")
		(net "UPI_CPU0_CPU1_P1P0_DN<15>")
	)
	(segment
		(start 348.166182 -172.522896)
		(end 347.157802 -172.1358)
		(width 0.14732)
		(layer "In4.Cu")
		(net "UPI_CPU0_CPU1_P1P0_DN<15>")
	)
	(segment
		(start 110.018576 -193.941192)
		(end 109.847126 -193.96075)
		(width 0.14732)
		(layer "In4.Cu")
		(net "UPI_CPU0_CPU1_P1P0_DN<15>")
	)
	(segment
		(start 367.966752 -211.781898)
		(end 367.924842 -211.739988)
		(width 0.0889)
		(layer "In4.Cu")
		(net "UPI_CPU0_CPU1_P1P0_DN<15>")
	)
	(segment
		(start 110.29061 -193.5988)
		(end 110.018576 -193.941192)
		(width 0.14732)
		(layer "In4.Cu")
		(net "UPI_CPU0_CPU1_P1P0_DN<15>")
	)
	(segment
		(start 276.714458 -161.420048)
		(end 238.206788 -151.529288)
		(width 0.14732)
		(layer "In4.Cu")
		(net "UPI_CPU0_CPU1_P1P0_DN<15>")
	)
	(segment
		(start 131.699254 -171.420028)
		(end 116.10594 -186.082432)
		(width 0.14732)
		(layer "In4.Cu")
		(net "UPI_CPU0_CPU1_P1P0_DN<15>")
	)
	(segment
		(start 103.47071 -216.736422)
		(end 103.465376 -216.73947)
		(width 0.0889)
		(layer "In4.Cu")
		(net "UPI_CPU0_CPU1_P1P0_DN<15>")
	)
	(segment
		(start 103.277416 -217.0557)
		(end 103.277416 -217.072972)
		(width 0.0889)
		(layer "In4.Cu")
		(net "UPI_CPU0_CPU1_P1P0_DN<15>")
	)
	(segment
		(start 103.277162 -212.54466)
		(end 103.376222 -212.64372)
		(width 0.0889)
		(layer "In4.Cu")
		(net "UPI_CPU0_CPU1_P1P0_DN<15>")
	)
	(segment
		(start 103.277162 -212.91804)
		(end 103.277162 -213.0933)
		(width 0.0889)
		(layer "In4.Cu")
		(net "UPI_CPU0_CPU1_P1P0_DN<15>")
	)
	(segment
		(start 347.157802 -172.1358)
		(end 329.069954 -155.325064)
		(width 0.14732)
		(layer "In4.Cu")
		(net "UPI_CPU0_CPU1_P1P0_DN<15>")
	)
	(segment
		(start 103.277162 -213.46668)
		(end 103.277162 -213.8934)
		(width 0.0889)
		(layer "In4.Cu")
		(net "UPI_CPU0_CPU1_P1P0_DN<15>")
	)
	(segment
		(start 353.824032 -174.216822)
		(end 353.470718 -173.960282)
		(width 0.14732)
		(layer "In4.Cu")
		(net "UPI_CPU0_CPU1_P1P0_DN<15>")
	)
	(segment
		(start 367.473484 -217.8939)
		(end 367.473484 -217.859864)
		(width 0.0889)
		(layer "In4.Cu")
		(net "UPI_CPU0_CPU1_P1P0_DN<15>")
	)
	(segment
		(start 103.455724 -215.755982)
		(end 103.457756 -215.757252)
		(width 0.0889)
		(layer "In4.Cu")
		(net "UPI_CPU0_CPU1_P1P0_DN<15>")
	)
	(segment
		(start 103.746808 -214.424768)
		(end 103.746808 -214.644732)
		(width 0.0889)
		(layer "In4.Cu")
		(net "UPI_CPU0_CPU1_P1P0_DN<15>")
	)
	(segment
		(start 111.932974 -191.334898)
		(end 111.661448 -191.676782)
		(width 0.14732)
		(layer "In4.Cu")
		(net "UPI_CPU0_CPU1_P1P0_DN<15>")
	)
	(segment
		(start 116.10594 -186.082432)
		(end 113.052098 -189.926214)
		(width 0.14732)
		(layer "In4.Cu")
		(net "UPI_CPU0_CPU1_P1P0_DN<15>")
	)
	(segment
		(start 367.966752 -213.82609)
		(end 367.966752 -211.781898)
		(width 0.0889)
		(layer "In4.Cu")
		(net "UPI_CPU0_CPU1_P1P0_DN<15>")
	)
	(segment
		(start 103.463598 -215.112854)
		(end 103.455724 -215.117426)
		(width 0.0889)
		(layer "In4.Cu")
		(net "UPI_CPU0_CPU1_P1P0_DN<15>")
	)
	(segment
		(start 103.457756 -215.757252)
		(end 103.464614 -215.761062)
		(width 0.0889)
		(layer "In4.Cu")
		(net "UPI_CPU0_CPU1_P1P0_DN<15>")
	)
	(segment
		(start 103.376222 -213.19236)
		(end 103.376222 -213.36762)
		(width 0.0889)
		(layer "In4.Cu")
		(net "UPI_CPU0_CPU1_P1P0_DN<15>")
	)
	(segment
		(start 103.319326 -211.653882)
		(end 103.319326 -212.03285)
		(width 0.14732)
		(layer "In4.Cu")
		(net "UPI_CPU0_CPU1_P1P0_DN<15>")
	)
	(segment
		(start 111.409226 -192.19037)
		(end 111.237776 -192.210182)
		(width 0.14732)
		(layer "In4.Cu")
		(net "UPI_CPU0_CPU1_P1P0_DN<15>")
	)
	(segment
		(start 354.375212 -174.617126)
		(end 354.204778 -174.64405)
		(width 0.14732)
		(layer "In4.Cu")
		(net "UPI_CPU0_CPU1_P1P0_DN<15>")
	)
	(segment
		(start 112.799876 -190.440056)
		(end 112.628426 -190.459614)
		(width 0.14732)
		(layer "In4.Cu")
		(net "UPI_CPU0_CPU1_P1P0_DN<15>")
	)
	(segment
		(start 109.847126 -193.96075)
		(end 109.493304 -194.406266)
		(width 0.14732)
		(layer "In4.Cu")
		(net "UPI_CPU0_CPU1_P1P0_DN<15>")
	)
	(segment
		(start 368.413538 -214.62238)
		(end 368.413538 -214.460582)
		(width 0.0889)
		(layer "In4.Cu")
		(net "UPI_CPU0_CPU1_P1P0_DN<15>")
	)
	(segment
		(start 353.85121 -174.387256)
		(end 353.824032 -174.216822)
		(width 0.14732)
		(layer "In4.Cu")
		(net "UPI_CPU0_CPU1_P1P0_DN<15>")
	)
	(segment
		(start 350.873314 -172.27423)
		(end 348.978982 -172.517308)
		(width 0.14732)
		(layer "In4.Cu")
		(net "UPI_CPU0_CPU1_P1P0_DN<15>")
	)
	(segment
		(start 326.39127 -153.173684)
		(end 323.67855 -152.491948)
		(width 0.14732)
		(layer "In4.Cu")
		(net "UPI_CPU0_CPU1_P1P0_DN<15>")
	)
	(segment
		(start 367.924842 -211.71789)
		(end 367.924842 -211.467954)
		(width 0.14732)
		(layer "In4.Cu")
		(net "UPI_CPU0_CPU1_P1P0_DN<15>")
	)
	(segment
		(start 367.94313 -215.445086)
		(end 367.94313 -215.43645)
		(width 0.0889)
		(layer "In4.Cu")
		(net "UPI_CPU0_CPU1_P1P0_DN<15>")
	)
	(segment
		(start 112.3569 -190.801498)
		(end 112.376458 -190.972948)
		(width 0.14732)
		(layer "In4.Cu")
		(net "UPI_CPU0_CPU1_P1P0_DN<15>")
	)
	(segment
		(start 353.470718 -173.960282)
		(end 353.300284 -173.987206)
		(width 0.14732)
		(layer "In4.Cu")
		(net "UPI_CPU0_CPU1_P1P0_DN<15>")
	)
	(segment
		(start 279.468834 -161.420048)
		(end 276.714458 -161.420048)
		(width 0.14732)
		(layer "In4.Cu")
		(net "UPI_CPU0_CPU1_P1P0_DN<15>")
	)
	(segment
		(start 173.89729 -152.21458)
		(end 170.349164 -150.457154)
		(width 0.14732)
		(layer "In4.Cu")
		(net "UPI_CPU0_CPU1_P1P0_DN<15>")
	)
	(segment
		(start 359.59796 -186.448192)
		(end 359.59796 -183.93791)
		(width 0.14732)
		(layer "In4.Cu")
		(net "UPI_CPU0_CPU1_P1P0_DN<15>")
	)
	(segment
		(start 103.319326 -212.03285)
		(end 103.319326 -212.054948)
		(width 0.0889)
		(layer "In4.Cu")
		(net "UPI_CPU0_CPU1_P1P0_DN<15>")
	)
	(segment
		(start 367.924588 -205.717902)
		(end 361.23626 -189.571122)
		(width 0.14732)
		(layer "In4.Cu")
		(net "UPI_CPU0_CPU1_P1P0_DN<15>")
	)
	(segment
		(start 103.465376 -216.73947)
		(end 103.464614 -216.739978)
		(width 0.0889)
		(layer "In4.Cu")
		(net "UPI_CPU0_CPU1_P1P0_DN<15>")
	)
	(segment
		(start 103.464614 -215.112346)
		(end 103.463598 -215.112854)
		(width 0.0889)
		(layer "In4.Cu")
		(net "UPI_CPU0_CPU1_P1P0_DN<15>")
	)
	(segment
		(start 110.986062 -192.723516)
		(end 110.714028 -193.065654)
		(width 0.14732)
		(layer "In4.Cu")
		(net "UPI_CPU0_CPU1_P1P0_DN<15>")
	)
	(segment
		(start 367.94313 -217.072972)
		(end 367.94313 -217.0557)
		(width 0.0889)
		(layer "In4.Cu")
		(net "UPI_CPU0_CPU1_P1P0_DN<15>")
	)
	(segment
		(start 113.07191 -190.097664)
		(end 112.799876 -190.440056)
		(width 0.14732)
		(layer "In4.Cu")
		(net "UPI_CPU0_CPU1_P1P0_DN<15>")
	)
	(segment
		(start 112.376458 -190.972948)
		(end 112.104424 -191.31534)
		(width 0.14732)
		(layer "In4.Cu")
		(net "UPI_CPU0_CPU1_P1P0_DN<15>")
	)
	(segment
		(start 356.439724 -176.313338)
		(end 355.72065 -175.594264)
		(width 0.14732)
		(layer "In4.Cu")
		(net "UPI_CPU0_CPU1_P1P0_DN<15>")
	)
	(segment
		(start 103.467154 -215.762586)
		(end 103.47071 -215.764618)
		(width 0.0889)
		(layer "In4.Cu")
		(net "UPI_CPU0_CPU1_P1P0_DN<15>")
	)
	(segment
		(start 367.924588 -211.4677)
		(end 367.924588 -205.717902)
		(width 0.14732)
		(layer "In4.Cu")
		(net "UPI_CPU0_CPU1_P1P0_DN<15>")
	)
	(segment
		(start 110.96625 -192.552066)
		(end 110.986062 -192.723516)
		(width 0.14732)
		(layer "In4.Cu")
		(net "UPI_CPU0_CPU1_P1P0_DN<15>")
	)
	(segment
		(start 323.67855 -152.491948)
		(end 322.084954 -152.491948)
		(width 0.14732)
		(layer "In4.Cu")
		(net "UPI_CPU0_CPU1_P1P0_DN<15>")
	)
	(segment
		(start 352.015298 -172.903134)
		(end 352.015044 -172.903134)
		(width 0.14732)
		(layer "In4.Cu")
		(net "UPI_CPU0_CPU1_P1P0_DN<15>")
	)
	(segment
		(start 367.56848 -218.692222)
		(end 367.724944 -218.421204)
		(width 0.0889)
		(layer "In4.Cu")
		(net "UPI_CPU0_CPU1_P1P0_DN<15>")
	)
	(segment
		(start 329.069954 -155.325064)
		(end 326.39127 -153.173684)
		(width 0.14732)
		(layer "In4.Cu")
		(net "UPI_CPU0_CPU1_P1P0_DN<15>")
	)
	(segment
		(start 103.277162 -213.0933)
		(end 103.376222 -213.19236)
		(width 0.0889)
		(layer "In4.Cu")
		(net "UPI_CPU0_CPU1_P1P0_DN<15>")
	)
	(segment
		(start 103.277162 -213.8934)
		(end 103.277416 -213.893908)
		(width 0.0889)
		(layer "In4.Cu")
		(net "UPI_CPU0_CPU1_P1P0_DN<15>")
	)
	(segment
		(start 359.59796 -183.93791)
		(end 356.439724 -176.313338)
		(width 0.14732)
		(layer "In4.Cu")
		(net "UPI_CPU0_CPU1_P1P0_DN<15>")
	)
	(segment
		(start 103.376222 -212.64372)
		(end 103.376222 -212.81898)
		(width 0.0889)
		(layer "In4.Cu")
		(net "UPI_CPU0_CPU1_P1P0_DN<15>")
	)
	(segment
		(start 353.300284 -173.987206)
		(end 352.946716 -173.730412)
		(width 0.14732)
		(layer "In4.Cu")
		(net "UPI_CPU0_CPU1_P1P0_DN<15>")
	)
	(segment
		(start 238.206788 -151.529288)
		(end 234.002326 -151.529288)
		(width 0.14732)
		(layer "In4.Cu")
		(net "UPI_CPU0_CPU1_P1P0_DN<15>")
	)
	(segment
		(start 361.23626 -189.571122)
		(end 360.638852 -188.962284)
		(width 0.14732)
		(layer "In4.Cu")
		(net "UPI_CPU0_CPU1_P1P0_DN<15>")
	)
	(segment
		(start 352.946716 -173.730412)
		(end 352.919538 -173.559978)
		(width 0.14732)
		(layer "In4.Cu")
		(net "UPI_CPU0_CPU1_P1P0_DN<15>")
	)
	(segment
		(start 352.042222 -173.073314)
		(end 352.015298 -172.903134)
		(width 0.14732)
		(layer "In4.Cu")
		(net "UPI_CPU0_CPU1_P1P0_DN<15>")
	)
	(segment
		(start 113.052098 -189.926214)
		(end 113.07191 -190.097664)
		(width 0.14732)
		(layer "In4.Cu")
		(net "UPI_CPU0_CPU1_P1P0_DN<15>")
	)
	(segment
		(start 351.386648 -172.446696)
		(end 351.385886 -172.446442)
		(width 0.14732)
		(layer "In4.Cu")
		(net "UPI_CPU0_CPU1_P1P0_DN<15>")
	)
	(segment
		(start 111.661448 -191.676782)
		(end 111.68126 -191.848232)
		(width 0.14732)
		(layer "In4.Cu")
		(net "UPI_CPU0_CPU1_P1P0_DN<15>")
	)
	(segment
		(start 170.349164 -150.457154)
		(end 166.634414 -150.358856)
		(width 0.14732)
		(layer "In4.Cu")
		(net "UPI_CPU0_CPU1_P1P0_DN<15>")
	)
	(segment
		(start 110.271052 -193.42735)
		(end 110.29061 -193.5988)
		(width 0.14732)
		(layer "In4.Cu")
		(net "UPI_CPU0_CPU1_P1P0_DN<15>")
	)
	(segment
		(start 103.376222 -213.36762)
		(end 103.277162 -213.46668)
		(width 0.0889)
		(layer "In4.Cu")
		(net "UPI_CPU0_CPU1_P1P0_DN<15>")
	)
	(segment
		(start 352.015044 -172.903134)
		(end 351.386648 -172.446696)
		(width 0.14732)
		(layer "In4.Cu")
		(net "UPI_CPU0_CPU1_P1P0_DN<15>")
	)
	(segment
		(start 111.68126 -191.848232)
		(end 111.409226 -192.19037)
		(width 0.14732)
		(layer "In4.Cu")
		(net "UPI_CPU0_CPU1_P1P0_DN<15>")
	)
	(segment
		(start 367.924842 -211.467954)
		(end 367.924588 -211.4677)
		(width 0.14732)
		(layer "In4.Cu")
		(net "UPI_CPU0_CPU1_P1P0_DN<15>")
	)
	(segment
		(start 352.566224 -173.303438)
		(end 352.396044 -173.330362)
		(width 0.14732)
		(layer "In4.Cu")
		(net "UPI_CPU0_CPU1_P1P0_DN<15>")
	)
	(segment
		(start 355.72065 -175.594264)
		(end 354.375212 -174.617126)
		(width 0.14732)
		(layer "In4.Cu")
		(net "UPI_CPU0_CPU1_P1P0_DN<15>")
	)
	(segment
		(start 367.94313 -215.43645)
		(end 367.943384 -215.422226)
		(width 0.0889)
		(layer "In4.Cu")
		(net "UPI_CPU0_CPU1_P1P0_DN<15>")
	)
	(segment
		(start 103.319072 -211.653628)
		(end 103.319326 -211.653882)
		(width 0.14732)
		(layer "In4.Cu")
		(net "UPI_CPU0_CPU1_P1P0_DN<15>")
	)
	(segment
		(start 103.319326 -212.054948)
		(end 103.277162 -212.097112)
		(width 0.0889)
		(layer "In4.Cu")
		(net "UPI_CPU0_CPU1_P1P0_DN<15>")
	)
	(segment
		(start 112.104424 -191.31534)
		(end 111.932974 -191.334898)
		(width 0.14732)
		(layer "In4.Cu")
		(net "UPI_CPU0_CPU1_P1P0_DN<15>")
	)
	(segment
		(start 351.385886 -172.446442)
		(end 350.873314 -172.27423)
		(width 0.14732)
		(layer "In4.Cu")
		(net "UPI_CPU0_CPU1_P1P0_DN<15>")
	)
	(segment
		(start 191.472312 -161.409888)
		(end 173.89729 -152.21458)
		(width 0.14732)
		(layer "In4.Cu")
		(net "UPI_CPU0_CPU1_P1P0_DN<15>")
	)
	(segment
		(start 103.319072 -211.356194)
		(end 103.319072 -211.653628)
		(width 0.14732)
		(layer "In4.Cu")
		(net "UPI_CPU0_CPU1_P1P0_DN<15>")
	)
	(segment
		(start 103.41737 -217.356182)
		(end 103.495348 -217.335354)
		(width 0.0889)
		(layer "In4.Cu")
		(net "UPI_CPU0_CPU1_P1P0_DN<15>")
	)
	(segment
		(start 112.628426 -190.459614)
		(end 112.3569 -190.801498)
		(width 0.14732)
		(layer "In4.Cu")
		(net "UPI_CPU0_CPU1_P1P0_DN<15>")
	)
	(segment
		(start 234.002326 -151.529288)
		(end 196.783198 -161.124138)
		(width 0.14732)
		(layer "In4.Cu")
		(net "UPI_CPU0_CPU1_P1P0_DN<15>")
	)
	(segment
		(start 348.978982 -172.517308)
		(end 348.166182 -172.522896)
		(width 0.14732)
		(layer "In4.Cu")
		(net "UPI_CPU0_CPU1_P1P0_DN<15>")
	)
	(segment
		(start 322.084954 -152.491948)
		(end 279.468834 -161.420048)
		(width 0.14732)
		(layer "In4.Cu")
		(net "UPI_CPU0_CPU1_P1P0_DN<15>")
	)
	(segment
		(start 196.783198 -161.124138)
		(end 194.51955 -161.409888)
		(width 0.14732)
		(layer "In4.Cu")
		(net "UPI_CPU0_CPU1_P1P0_DN<15>")
	)
	(segment
		(start 103.495348 -217.335354)
		(end 103.651812 -217.064336)
		(width 0.0889)
		(layer "In4.Cu")
		(net "UPI_CPU0_CPU1_P1P0_DN<15>")
	)
	(segment
		(start 103.376222 -212.81898)
		(end 103.277162 -212.91804)
		(width 0.0889)
		(layer "In4.Cu")
		(net "UPI_CPU0_CPU1_P1P0_DN<15>")
	)
	(segment
		(start 367.724944 -218.421204)
		(end 367.700814 -218.33205)
		(width 0.0889)
		(layer "In4.Cu")
		(net "UPI_CPU0_CPU1_P1P0_DN<15>")
	)
	(segment
		(start 194.51955 -161.409888)
		(end 191.472312 -161.409888)
		(width 0.14732)
		(layer "In4.Cu")
		(net "UPI_CPU0_CPU1_P1P0_DN<15>")
	)
	(segment
		(start 109.493304 -194.406266)
		(end 103.319072 -211.356194)
		(width 0.14732)
		(layer "In4.Cu")
		(net "UPI_CPU0_CPU1_P1P0_DN<15>")
	)
	(segment
		(start 352.919538 -173.559978)
		(end 352.566224 -173.303438)
		(width 0.14732)
		(layer "In4.Cu")
		(net "UPI_CPU0_CPU1_P1P0_DN<15>")
	)
	(segment
		(start 111.237776 -192.210182)
		(end 110.96625 -192.552066)
		(width 0.14732)
		(layer "In4.Cu")
		(net "UPI_CPU0_CPU1_P1P0_DN<15>")
	)
	(segment
		(start 352.396044 -173.330362)
		(end 352.042222 -173.073314)
		(width 0.14732)
		(layer "In4.Cu")
		(net "UPI_CPU0_CPU1_P1P0_DN<15>")
	)
	(segment
		(start 103.277162 -212.097112)
		(end 103.277162 -212.54466)
		(width 0.0889)
		(layer "In4.Cu")
		(net "UPI_CPU0_CPU1_P1P0_DN<15>")
	)
	(arc
		(start 103.277416 -217.072972)
		(mid 103.31609 -217.23004)
		(end 103.41737 -217.356182)
		(width 0.0889)
		(layer "In4.Cu")
		(net "UPI_CPU0_CPU1_P1P0_DN<15>")
	)
	(arc
		(start 367.755932 -216.739978)
		(mid 367.551597 -216.537373)
		(end 367.473484 -216.260426)
		(width 0.0889)
		(layer "In4.Cu")
		(net "UPI_CPU0_CPU1_P1P0_DN<15>")
	)
	(arc
		(start 103.461566 -214.093298)
		(mid 103.635529 -214.232062)
		(end 103.746808 -214.424768)
		(width 0.0889)
		(layer "In4.Cu")
		(net "UPI_CPU0_CPU1_P1P0_DN<15>")
	)
	(arc
		(start 103.464614 -216.739978)
		(mid 103.329681 -216.873332)
		(end 103.277416 -217.0557)
		(width 0.0889)
		(layer "In4.Cu")
		(net "UPI_CPU0_CPU1_P1P0_DN<15>")
	)
	(arc
		(start 368.234722 -214.941912)
		(mid 368.365636 -214.805552)
		(end 368.413284 -214.622634)
		(width 0.0889)
		(layer "In4.Cu")
		(net "UPI_CPU0_CPU1_P1P0_DN<15>")
	)
	(arc
		(start 368.229388 -214.2617)
		(mid 368.037465 -214.080415)
		(end 367.966752 -213.82609)
		(width 0.0889)
		(layer "In4.Cu")
		(net "UPI_CPU0_CPU1_P1P0_DN<15>")
	)
	(arc
		(start 368.413538 -214.460582)
		(mid 368.338431 -214.345436)
		(end 368.229388 -214.2617)
		(width 0.0889)
		(layer "In4.Cu")
		(net "UPI_CPU0_CPU1_P1P0_DN<15>")
	)
	(arc
		(start 367.473484 -216.231978)
		(mid 367.553646 -215.959789)
		(end 367.755932 -215.760808)
		(width 0.0889)
		(layer "In4.Cu")
		(net "UPI_CPU0_CPU1_P1P0_DN<15>")
	)
	(arc
		(start 367.700814 -218.33205)
		(mid 367.692373 -218.32565)
		(end 367.68405 -218.319096)
		(width 0.0889)
		(layer "In4.Cu")
		(net "UPI_CPU0_CPU1_P1P0_DN<15>")
	)
	(arc
		(start 103.277416 -213.893908)
		(mid 103.352421 -214.009367)
		(end 103.461566 -214.093298)
		(width 0.0889)
		(layer "In4.Cu")
		(net "UPI_CPU0_CPU1_P1P0_DN<15>")
	)
	(arc
		(start 103.277416 -215.421972)
		(mid 103.277219 -215.429337)
		(end 103.277162 -215.436704)
		(width 0.0889)
		(layer "In4.Cu")
		(net "UPI_CPU0_CPU1_P1P0_DN<15>")
	)
	(arc
		(start 103.455724 -215.117426)
		(mid 103.32847 -215.247392)
		(end 103.277416 -215.421972)
		(width 0.0889)
		(layer "In4.Cu")
		(net "UPI_CPU0_CPU1_P1P0_DN<15>")
	)
	(arc
		(start 367.755932 -217.388694)
		(mid 367.890865 -217.25534)
		(end 367.94313 -217.072972)
		(width 0.0889)
		(layer "In4.Cu")
		(net "UPI_CPU0_CPU1_P1P0_DN<15>")
	)
	(arc
		(start 367.943384 -215.422226)
		(mid 368.022515 -215.14769)
		(end 368.225832 -214.946992)
		(width 0.0889)
		(layer "In4.Cu")
		(net "UPI_CPU0_CPU1_P1P0_DN<15>")
	)
	(arc
		(start 103.47071 -215.764618)
		(mid 103.747284 -216.25052)
		(end 103.47071 -216.736422)
		(width 0.0889)
		(layer "In4.Cu")
		(net "UPI_CPU0_CPU1_P1P0_DN<15>")
	)
	(arc
		(start 367.94313 -217.0557)
		(mid 367.89086 -216.873335)
		(end 367.755932 -216.739978)
		(width 0.0889)
		(layer "In4.Cu")
		(net "UPI_CPU0_CPU1_P1P0_DN<15>")
	)
	(arc
		(start 367.68405 -218.319096)
		(mid 367.531968 -218.129664)
		(end 367.473484 -217.8939)
		(width 0.0889)
		(layer "In4.Cu")
		(net "UPI_CPU0_CPU1_P1P0_DN<15>")
	)
	(arc
		(start 103.746808 -214.644732)
		(mid 103.665897 -214.91486)
		(end 103.464614 -215.112346)
		(width 0.0889)
		(layer "In4.Cu")
		(net "UPI_CPU0_CPU1_P1P0_DN<15>")
	)
	(arc
		(start 367.473484 -217.859864)
		(mid 367.553646 -217.587675)
		(end 367.755932 -217.388694)
		(width 0.0889)
		(layer "In4.Cu")
		(net "UPI_CPU0_CPU1_P1P0_DN<15>")
	)
	(arc
		(start 367.755932 -215.760808)
		(mid 367.890865 -215.627454)
		(end 367.94313 -215.445086)
		(width 0.0889)
		(layer "In4.Cu")
		(net "UPI_CPU0_CPU1_P1P0_DN<15>")
	)
	(arc
		(start 103.277162 -215.436704)
		(mid 103.324841 -215.619604)
		(end 103.455724 -215.755982)
		(width 0.0889)
		(layer "In4.Cu")
		(net "UPI_CPU0_CPU1_P1P0_DN<15>")
	)
	(segment
		(start 102.242112 -217.87866)
		(end 102.242366 -217.878406)
		(width 0.13208)
		(layer "F.Cu")
		(net "UPI_CPU0_CPU1_P1P0_DN<14>")
	)
	(segment
		(start 368.97818 -217.87866)
		(end 368.978434 -217.878406)
		(width 0.13208)
		(layer "F.Cu")
		(net "UPI_CPU0_CPU1_P1P0_DN<14>")
	)
	(segment
		(start 102.242112 -218.414346)
		(end 102.242112 -217.87866)
		(width 0.13208)
		(layer "F.Cu")
		(net "UPI_CPU0_CPU1_P1P0_DN<14>")
	)
	(segment
		(start 368.97818 -218.414346)
		(end 368.97818 -217.87866)
		(width 0.13208)
		(layer "F.Cu")
		(net "UPI_CPU0_CPU1_P1P0_DN<14>")
	)
	(segment
		(start 102.04831 -213.2584)
		(end 102.14737 -213.35746)
		(width 0.0889)
		(layer "In4.Cu")
		(net "UPI_CPU0_CPU1_P1P0_DN<14>")
	)
	(segment
		(start 102.438454 -215.931496)
		(end 102.438454 -215.931242)
		(width 0.0889)
		(layer "In4.Cu")
		(net "UPI_CPU0_CPU1_P1P0_DN<14>")
	)
	(segment
		(start 369.260374 -215.1126)
		(end 369.261136 -215.112092)
		(width 0.0889)
		(layer "In4.Cu")
		(net "UPI_CPU0_CPU1_P1P0_DN<14>")
	)
	(segment
		(start 368.782346 -215.931242)
		(end 368.791236 -215.926162)
		(width 0.0889)
		(layer "In4.Cu")
		(net "UPI_CPU0_CPU1_P1P0_DN<14>")
	)
	(segment
		(start 360.71048 -183.716168)
		(end 356.462584 -173.46041)
		(width 0.14732)
		(layer "In4.Cu")
		(net "UPI_CPU0_CPU1_P1P0_DN<14>")
	)
	(segment
		(start 102.42677 -215.924384)
		(end 102.428802 -215.925654)
		(width 0.0889)
		(layer "In4.Cu")
		(net "UPI_CPU0_CPU1_P1P0_DN<14>")
	)
	(segment
		(start 102.04831 -212.67674)
		(end 102.14737 -212.7758)
		(width 0.0889)
		(layer "In4.Cu")
		(net "UPI_CPU0_CPU1_P1P0_DN<14>")
	)
	(segment
		(start 174.448724 -151.132286)
		(end 170.64863 -149.2504)
		(width 0.14732)
		(layer "In4.Cu")
		(net "UPI_CPU0_CPU1_P1P0_DN<14>")
	)
	(segment
		(start 369.115848 -211.389722)
		(end 369.115594 -211.389468)
		(width 0.14732)
		(layer "In4.Cu")
		(net "UPI_CPU0_CPU1_P1P0_DN<14>")
	)
	(segment
		(start 369.115594 -205.710536)
		(end 362.11256 -188.801756)
		(width 0.14732)
		(layer "In4.Cu")
		(net "UPI_CPU0_CPU1_P1P0_DN<14>")
	)
	(segment
		(start 102.429564 -217.554048)
		(end 102.438454 -217.559128)
		(width 0.0889)
		(layer "In4.Cu")
		(net "UPI_CPU0_CPU1_P1P0_DN<14>")
	)
	(segment
		(start 233.856276 -150.391368)
		(end 196.351144 -160.060132)
		(width 0.14732)
		(layer "In4.Cu")
		(net "UPI_CPU0_CPU1_P1P0_DN<14>")
	)
	(segment
		(start 102.14737 -212.98408)
		(end 102.04831 -213.08314)
		(width 0.0889)
		(layer "In4.Cu")
		(net "UPI_CPU0_CPU1_P1P0_DN<14>")
	)
	(segment
		(start 131.061968 -170.499532)
		(end 114.634264 -185.945526)
		(width 0.14732)
		(layer "In4.Cu")
		(net "UPI_CPU0_CPU1_P1P0_DN<14>")
	)
	(segment
		(start 194.393058 -160.307528)
		(end 191.983868 -160.307528)
		(width 0.14732)
		(layer "In4.Cu")
		(net "UPI_CPU0_CPU1_P1P0_DN<14>")
	)
	(segment
		(start 353.12223 -170.77817)
		(end 352.07448 -170.734228)
		(width 0.14732)
		(layer "In4.Cu")
		(net "UPI_CPU0_CPU1_P1P0_DN<14>")
	)
	(segment
		(start 369.115594 -211.389468)
		(end 369.115594 -205.710536)
		(width 0.14732)
		(layer "In4.Cu")
		(net "UPI_CPU0_CPU1_P1P0_DN<14>")
	)
	(segment
		(start 369.073684 -217.07856)
		(end 369.073684 -217.064336)
		(width 0.0889)
		(layer "In4.Cu")
		(net "UPI_CPU0_CPU1_P1P0_DN<14>")
	)
	(segment
		(start 102.428802 -215.925654)
		(end 102.430326 -215.92667)
		(width 0.0889)
		(layer "In4.Cu")
		(net "UPI_CPU0_CPU1_P1P0_DN<14>")
	)
	(segment
		(start 196.351144 -160.060132)
		(end 194.393058 -160.307528)
		(width 0.14732)
		(layer "In4.Cu")
		(net "UPI_CPU0_CPU1_P1P0_DN<14>")
	)
	(segment
		(start 102.429564 -216.574878)
		(end 102.425754 -216.577164)
		(width 0.0889)
		(layer "In4.Cu")
		(net "UPI_CPU0_CPU1_P1P0_DN<14>")
	)
	(segment
		(start 114.634264 -185.945526)
		(end 108.573824 -193.574162)
		(width 0.14732)
		(layer "In4.Cu")
		(net "UPI_CPU0_CPU1_P1P0_DN<14>")
	)
	(segment
		(start 368.978434 -217.878406)
		(end 368.962686 -217.851228)
		(width 0.0889)
		(layer "In4.Cu")
		(net "UPI_CPU0_CPU1_P1P0_DN<14>")
	)
	(segment
		(start 323.763386 -151.354028)
		(end 321.966844 -151.354028)
		(width 0.14732)
		(layer "In4.Cu")
		(net "UPI_CPU0_CPU1_P1P0_DN<14>")
	)
	(segment
		(start 102.616508 -214.461344)
		(end 102.616508 -214.622634)
		(width 0.0889)
		(layer "In4.Cu")
		(net "UPI_CPU0_CPU1_P1P0_DN<14>")
	)
	(segment
		(start 164.492178 -149.898354)
		(end 131.061968 -170.499532)
		(width 0.14732)
		(layer "In4.Cu")
		(net "UPI_CPU0_CPU1_P1P0_DN<14>")
	)
	(segment
		(start 102.10546 -211.955888)
		(end 102.14737 -211.997798)
		(width 0.0889)
		(layer "In4.Cu")
		(net "UPI_CPU0_CPU1_P1P0_DN<14>")
	)
	(segment
		(start 102.10546 -211.653882)
		(end 102.10546 -211.93379)
		(width 0.14732)
		(layer "In4.Cu")
		(net "UPI_CPU0_CPU1_P1P0_DN<14>")
	)
	(segment
		(start 166.649654 -149.144736)
		(end 164.492178 -149.898354)
		(width 0.14732)
		(layer "In4.Cu")
		(net "UPI_CPU0_CPU1_P1P0_DN<14>")
	)
	(segment
		(start 102.105206 -211.33435)
		(end 102.105206 -211.653628)
		(width 0.14732)
		(layer "In4.Cu")
		(net "UPI_CPU0_CPU1_P1P0_DN<14>")
	)
	(segment
		(start 368.791236 -216.574878)
		(end 368.782346 -216.569798)
		(width 0.0889)
		(layer "In4.Cu")
		(net "UPI_CPU0_CPU1_P1P0_DN<14>")
	)
	(segment
		(start 102.425754 -216.577164)
		(end 102.417372 -216.58199)
		(width 0.0889)
		(layer "In4.Cu")
		(net "UPI_CPU0_CPU1_P1P0_DN<14>")
	)
	(segment
		(start 102.430834 -214.945976)
		(end 102.429818 -214.946484)
		(width 0.0889)
		(layer "In4.Cu")
		(net "UPI_CPU0_CPU1_P1P0_DN<14>")
	)
	(segment
		(start 102.477062 -218.170252)
		(end 102.39883 -218.149424)
		(width 0.0889)
		(layer "In4.Cu")
		(net "UPI_CPU0_CPU1_P1P0_DN<14>")
	)
	(segment
		(start 348.83598 -171.399708)
		(end 348.356936 -171.408852)
		(width 0.14732)
		(layer "In4.Cu")
		(net "UPI_CPU0_CPU1_P1P0_DN<14>")
	)
	(segment
		(start 102.14737 -213.35746)
		(end 102.14737 -213.931246)
		(width 0.0889)
		(layer "In4.Cu")
		(net "UPI_CPU0_CPU1_P1P0_DN<14>")
	)
	(segment
		(start 102.429818 -214.946484)
		(end 102.429056 -214.946992)
		(width 0.0889)
		(layer "In4.Cu")
		(net "UPI_CPU0_CPU1_P1P0_DN<14>")
	)
	(segment
		(start 102.04831 -212.50148)
		(end 102.04831 -212.67674)
		(width 0.0889)
		(layer "In4.Cu")
		(net "UPI_CPU0_CPU1_P1P0_DN<14>")
	)
	(segment
		(start 102.423468 -215.922606)
		(end 102.42677 -215.924384)
		(width 0.0889)
		(layer "In4.Cu")
		(net "UPI_CPU0_CPU1_P1P0_DN<14>")
	)
	(segment
		(start 362.11256 -188.801756)
		(end 361.537504 -188.217556)
		(width 0.14732)
		(layer "In4.Cu")
		(net "UPI_CPU0_CPU1_P1P0_DN<14>")
	)
	(segment
		(start 102.14737 -213.931246)
		(end 102.147116 -213.930484)
		(width 0.0889)
		(layer "In4.Cu")
		(net "UPI_CPU0_CPU1_P1P0_DN<14>")
	)
	(segment
		(start 369.115848 -211.686648)
		(end 369.115848 -211.66455)
		(width 0.0889)
		(layer "In4.Cu")
		(net "UPI_CPU0_CPU1_P1P0_DN<14>")
	)
	(segment
		(start 102.105206 -211.653628)
		(end 102.10546 -211.653882)
		(width 0.14732)
		(layer "In4.Cu")
		(net "UPI_CPU0_CPU1_P1P0_DN<14>")
	)
	(segment
		(start 352.07448 -170.734228)
		(end 350.426274 -171.073064)
		(width 0.14732)
		(layer "In4.Cu")
		(net "UPI_CPU0_CPU1_P1P0_DN<14>")
	)
	(segment
		(start 368.791236 -215.926162)
		(end 368.797332 -215.922606)
		(width 0.0889)
		(layer "In4.Cu")
		(net "UPI_CPU0_CPU1_P1P0_DN<14>")
	)
	(segment
		(start 369.073684 -213.8934)
		(end 369.073684 -211.728812)
		(width 0.0889)
		(layer "In4.Cu")
		(net "UPI_CPU0_CPU1_P1P0_DN<14>")
	)
	(segment
		(start 347.76283 -171.175934)
		(end 329.907392 -154.58059)
		(width 0.14732)
		(layer "In4.Cu")
		(net "UPI_CPU0_CPU1_P1P0_DN<14>")
	)
	(segment
		(start 356.462584 -173.430692)
		(end 354.781866 -171.749466)
		(width 0.14732)
		(layer "In4.Cu")
		(net "UPI_CPU0_CPU1_P1P0_DN<14>")
	)
	(segment
		(start 356.462584 -173.46041)
		(end 356.462584 -173.430692)
		(width 0.14732)
		(layer "In4.Cu")
		(net "UPI_CPU0_CPU1_P1P0_DN<14>")
	)
	(segment
		(start 102.14737 -212.40242)
		(end 102.04831 -212.50148)
		(width 0.0889)
		(layer "In4.Cu")
		(net "UPI_CPU0_CPU1_P1P0_DN<14>")
	)
	(segment
		(start 102.04831 -213.08314)
		(end 102.04831 -213.2584)
		(width 0.0889)
		(layer "In4.Cu")
		(net "UPI_CPU0_CPU1_P1P0_DN<14>")
	)
	(segment
		(start 369.252246 -215.117172)
		(end 369.260374 -215.1126)
		(width 0.0889)
		(layer "In4.Cu")
		(net "UPI_CPU0_CPU1_P1P0_DN<14>")
	)
	(segment
		(start 368.797332 -216.578434)
		(end 368.791236 -216.574878)
		(width 0.0889)
		(layer "In4.Cu")
		(net "UPI_CPU0_CPU1_P1P0_DN<14>")
	)
	(segment
		(start 321.966844 -151.354028)
		(end 279.181052 -160.317688)
		(width 0.14732)
		(layer "In4.Cu")
		(net "UPI_CPU0_CPU1_P1P0_DN<14>")
	)
	(segment
		(start 350.426274 -171.073064)
		(end 348.83598 -171.399708)
		(width 0.14732)
		(layer "In4.Cu")
		(net "UPI_CPU0_CPU1_P1P0_DN<14>")
	)
	(segment
		(start 369.073684 -211.728812)
		(end 369.115848 -211.686648)
		(width 0.0889)
		(layer "In4.Cu")
		(net "UPI_CPU0_CPU1_P1P0_DN<14>")
	)
	(segment
		(start 329.907392 -154.58059)
		(end 326.881998 -152.13711)
		(width 0.14732)
		(layer "In4.Cu")
		(net "UPI_CPU0_CPU1_P1P0_DN<14>")
	)
	(segment
		(start 276.99716 -160.317688)
		(end 238.35106 -150.391368)
		(width 0.14732)
		(layer "In4.Cu")
		(net "UPI_CPU0_CPU1_P1P0_DN<14>")
	)
	(segment
		(start 369.115848 -211.66455)
		(end 369.115848 -211.389722)
		(width 0.14732)
		(layer "In4.Cu")
		(net "UPI_CPU0_CPU1_P1P0_DN<14>")
	)
	(segment
		(start 191.983868 -160.307528)
		(end 174.448724 -151.132286)
		(width 0.14732)
		(layer "In4.Cu")
		(net "UPI_CPU0_CPU1_P1P0_DN<14>")
	)
	(segment
		(start 108.573824 -193.574162)
		(end 102.105206 -211.33435)
		(width 0.14732)
		(layer "In4.Cu")
		(net "UPI_CPU0_CPU1_P1P0_DN<14>")
	)
	(segment
		(start 354.781866 -171.749466)
		(end 353.12223 -170.77817)
		(width 0.14732)
		(layer "In4.Cu")
		(net "UPI_CPU0_CPU1_P1P0_DN<14>")
	)
	(segment
		(start 360.71048 -186.197494)
		(end 360.71048 -183.716168)
		(width 0.14732)
		(layer "In4.Cu")
		(net "UPI_CPU0_CPU1_P1P0_DN<14>")
	)
	(segment
		(start 102.14737 -211.997798)
		(end 102.14737 -212.40242)
		(width 0.0889)
		(layer "In4.Cu")
		(net "UPI_CPU0_CPU1_P1P0_DN<14>")
	)
	(segment
		(start 102.39883 -218.149424)
		(end 102.242366 -217.878406)
		(width 0.0889)
		(layer "In4.Cu")
		(net "UPI_CPU0_CPU1_P1P0_DN<14>")
	)
	(segment
		(start 369.543584 -214.63254)
		(end 369.543584 -214.425022)
		(width 0.0889)
		(layer "In4.Cu")
		(net "UPI_CPU0_CPU1_P1P0_DN<14>")
	)
	(segment
		(start 326.881998 -152.13711)
		(end 323.763386 -151.354028)
		(width 0.14732)
		(layer "In4.Cu")
		(net "UPI_CPU0_CPU1_P1P0_DN<14>")
	)
	(segment
		(start 102.10546 -211.93379)
		(end 102.10546 -211.955888)
		(width 0.0889)
		(layer "In4.Cu")
		(net "UPI_CPU0_CPU1_P1P0_DN<14>")
	)
	(segment
		(start 238.35106 -150.391368)
		(end 233.856276 -150.391368)
		(width 0.14732)
		(layer "In4.Cu")
		(net "UPI_CPU0_CPU1_P1P0_DN<14>")
	)
	(segment
		(start 102.146862 -217.064336)
		(end 102.146862 -217.071956)
		(width 0.0889)
		(layer "In4.Cu")
		(net "UPI_CPU0_CPU1_P1P0_DN<14>")
	)
	(segment
		(start 279.181052 -160.317688)
		(end 276.99716 -160.317688)
		(width 0.14732)
		(layer "In4.Cu")
		(net "UPI_CPU0_CPU1_P1P0_DN<14>")
	)
	(segment
		(start 348.356936 -171.408852)
		(end 347.76283 -171.175934)
		(width 0.14732)
		(layer "In4.Cu")
		(net "UPI_CPU0_CPU1_P1P0_DN<14>")
	)
	(segment
		(start 102.14737 -212.7758)
		(end 102.14737 -212.98408)
		(width 0.0889)
		(layer "In4.Cu")
		(net "UPI_CPU0_CPU1_P1P0_DN<14>")
	)
	(segment
		(start 102.438454 -216.569798)
		(end 102.429564 -216.574878)
		(width 0.0889)
		(layer "In4.Cu")
		(net "UPI_CPU0_CPU1_P1P0_DN<14>")
	)
	(segment
		(start 102.437946 -214.941912)
		(end 102.430834 -214.945976)
		(width 0.0889)
		(layer "In4.Cu")
		(net "UPI_CPU0_CPU1_P1P0_DN<14>")
	)
	(segment
		(start 368.82197 -217.607388)
		(end 368.8461 -217.518234)
		(width 0.0889)
		(layer "In4.Cu")
		(net "UPI_CPU0_CPU1_P1P0_DN<14>")
	)
	(segment
		(start 368.962686 -217.851228)
		(end 368.82197 -217.607388)
		(width 0.0889)
		(layer "In4.Cu")
		(net "UPI_CPU0_CPU1_P1P0_DN<14>")
	)
	(segment
		(start 102.430326 -215.92667)
		(end 102.438454 -215.931496)
		(width 0.0889)
		(layer "In4.Cu")
		(net "UPI_CPU0_CPU1_P1P0_DN<14>")
	)
	(segment
		(start 361.537504 -188.217556)
		(end 360.71048 -186.197494)
		(width 0.14732)
		(layer "In4.Cu")
		(net "UPI_CPU0_CPU1_P1P0_DN<14>")
	)
	(segment
		(start 170.64863 -149.2504)
		(end 166.649654 -149.144736)
		(width 0.14732)
		(layer "In4.Cu")
		(net "UPI_CPU0_CPU1_P1P0_DN<14>")
	)
	(arc
		(start 102.438454 -215.931242)
		(mid 102.617051 -216.25052)
		(end 102.438454 -216.569798)
		(width 0.0889)
		(layer "In4.Cu")
		(net "UPI_CPU0_CPU1_P1P0_DN<14>")
	)
	(arc
		(start 102.147116 -213.930484)
		(mid 102.154401 -213.950046)
		(end 102.162356 -213.969346)
		(width 0.0889)
		(layer "In4.Cu")
		(net "UPI_CPU0_CPU1_P1P0_DN<14>")
	)
	(arc
		(start 102.417372 -216.58199)
		(mid 102.219144 -216.787838)
		(end 102.146862 -217.064336)
		(width 0.0889)
		(layer "In4.Cu")
		(net "UPI_CPU0_CPU1_P1P0_DN<14>")
	)
	(arc
		(start 368.8461 -217.518234)
		(mid 368.854543 -217.511836)
		(end 368.862864 -217.50528)
		(width 0.0889)
		(layer "In4.Cu")
		(net "UPI_CPU0_CPU1_P1P0_DN<14>")
	)
	(arc
		(start 102.616508 -214.622634)
		(mid 102.568829 -214.805534)
		(end 102.437946 -214.941912)
		(width 0.0889)
		(layer "In4.Cu")
		(net "UPI_CPU0_CPU1_P1P0_DN<14>")
	)
	(arc
		(start 368.862864 -217.50528)
		(mid 369.015371 -217.315182)
		(end 369.073684 -217.07856)
		(width 0.0889)
		(layer "In4.Cu")
		(net "UPI_CPU0_CPU1_P1P0_DN<14>")
	)
	(arc
		(start 369.258088 -214.093298)
		(mid 369.148692 -214.009201)
		(end 369.073684 -213.8934)
		(width 0.0889)
		(layer "In4.Cu")
		(net "UPI_CPU0_CPU1_P1P0_DN<14>")
	)
	(arc
		(start 102.432358 -214.261954)
		(mid 102.541505 -214.345882)
		(end 102.616508 -214.461344)
		(width 0.0889)
		(layer "In4.Cu")
		(net "UPI_CPU0_CPU1_P1P0_DN<14>")
	)
	(arc
		(start 102.162356 -213.969346)
		(mid 102.27235 -214.138715)
		(end 102.432358 -214.261954)
		(width 0.0889)
		(layer "In4.Cu")
		(net "UPI_CPU0_CPU1_P1P0_DN<14>")
	)
	(arc
		(start 369.543584 -214.425022)
		(mid 369.432246 -214.232122)
		(end 369.258088 -214.093298)
		(width 0.0889)
		(layer "In4.Cu")
		(net "UPI_CPU0_CPU1_P1P0_DN<14>")
	)
	(arc
		(start 102.146862 -217.071956)
		(mid 102.224491 -217.350369)
		(end 102.429564 -217.554048)
		(width 0.0889)
		(layer "In4.Cu")
		(net "UPI_CPU0_CPU1_P1P0_DN<14>")
	)
	(arc
		(start 369.073684 -215.43645)
		(mid 369.121363 -215.25355)
		(end 369.252246 -215.117172)
		(width 0.0889)
		(layer "In4.Cu")
		(net "UPI_CPU0_CPU1_P1P0_DN<14>")
	)
	(arc
		(start 102.617016 -217.878406)
		(mid 102.580156 -218.040203)
		(end 102.477062 -218.170252)
		(width 0.0889)
		(layer "In4.Cu")
		(net "UPI_CPU0_CPU1_P1P0_DN<14>")
	)
	(arc
		(start 369.261136 -215.112092)
		(mid 369.465471 -214.909487)
		(end 369.543584 -214.63254)
		(width 0.0889)
		(layer "In4.Cu")
		(net "UPI_CPU0_CPU1_P1P0_DN<14>")
	)
	(arc
		(start 368.797332 -215.922606)
		(mid 368.999808 -215.716083)
		(end 369.073684 -215.43645)
		(width 0.0889)
		(layer "In4.Cu")
		(net "UPI_CPU0_CPU1_P1P0_DN<14>")
	)
	(arc
		(start 102.438454 -217.559128)
		(mid 102.569368 -217.695488)
		(end 102.617016 -217.878406)
		(width 0.0889)
		(layer "In4.Cu")
		(net "UPI_CPU0_CPU1_P1P0_DN<14>")
	)
	(arc
		(start 368.782346 -216.569798)
		(mid 368.60387 -216.25052)
		(end 368.782346 -215.931242)
		(width 0.0889)
		(layer "In4.Cu")
		(net "UPI_CPU0_CPU1_P1P0_DN<14>")
	)
	(arc
		(start 369.073684 -217.064336)
		(mid 368.999768 -216.784834)
		(end 368.797332 -216.578434)
		(width 0.0889)
		(layer "In4.Cu")
		(net "UPI_CPU0_CPU1_P1P0_DN<14>")
	)
	(arc
		(start 102.429056 -214.946992)
		(mid 102.14666 -215.433205)
		(end 102.423468 -215.922606)
		(width 0.0889)
		(layer "In4.Cu")
		(net "UPI_CPU0_CPU1_P1P0_DN<14>")
	)
	(segment
		(start 369.448334 -218.692476)
		(end 369.44808 -218.692222)
		(width 0.13208)
		(layer "F.Cu")
		(net "UPI_CPU0_CPU1_P1P0_DN<13>")
	)
	(segment
		(start 101.772466 -217.06459)
		(end 101.772212 -217.064336)
		(width 0.13208)
		(layer "F.Cu")
		(net "UPI_CPU0_CPU1_P1P0_DN<13>")
	)
	(segment
		(start 369.448334 -219.228162)
		(end 369.448334 -218.692476)
		(width 0.13208)
		(layer "F.Cu")
		(net "UPI_CPU0_CPU1_P1P0_DN<13>")
	)
	(segment
		(start 101.772466 -217.600276)
		(end 101.772466 -217.06459)
		(width 0.13208)
		(layer "F.Cu")
		(net "UPI_CPU0_CPU1_P1P0_DN<13>")
	)
	(segment
		(start 107.008422 -195.821554)
		(end 106.882946 -196.165978)
		(width 0.14732)
		(layer "In4.Cu")
		(net "UPI_CPU0_CPU1_P1P0_DN<13>")
	)
	(segment
		(start 355.107494 -171.275502)
		(end 354.41763 -170.864022)
		(width 0.14732)
		(layer "In4.Cu")
		(net "UPI_CPU0_CPU1_P1P0_DN<13>")
	)
	(segment
		(start 107.194096 -195.735194)
		(end 107.008422 -195.821554)
		(width 0.14732)
		(layer "In4.Cu")
		(net "UPI_CPU0_CPU1_P1P0_DN<13>")
	)
	(segment
		(start 369.822984 -213.93023)
		(end 369.822984 -211.774024)
		(width 0.0889)
		(layer "In4.Cu")
		(net "UPI_CPU0_CPU1_P1P0_DN<13>")
	)
	(segment
		(start 101.586538 -215.762078)
		(end 101.587808 -215.76284)
		(width 0.0889)
		(layer "In4.Cu")
		(net "UPI_CPU0_CPU1_P1P0_DN<13>")
	)
	(segment
		(start 361.27436 -183.595264)
		(end 356.923594 -173.091602)
		(width 0.14732)
		(layer "In4.Cu")
		(net "UPI_CPU0_CPU1_P1P0_DN<13>")
	)
	(segment
		(start 349.141034 -169.599356)
		(end 348.33433 -169.664126)
		(width 0.14732)
		(layer "In4.Cu")
		(net "UPI_CPU0_CPU1_P1P0_DN<13>")
	)
	(segment
		(start 166.795704 -148.482812)
		(end 164.286438 -149.359112)
		(width 0.14732)
		(layer "In4.Cu")
		(net "UPI_CPU0_CPU1_P1P0_DN<13>")
	)
	(segment
		(start 102.22865 -209.366358)
		(end 102.102412 -209.712814)
		(width 0.14732)
		(layer "In4.Cu")
		(net "UPI_CPU0_CPU1_P1P0_DN<13>")
	)
	(segment
		(start 106.0323 -198.501)
		(end 106.11866 -198.686674)
		(width 0.14732)
		(layer "In4.Cu")
		(net "UPI_CPU0_CPU1_P1P0_DN<13>")
	)
	(segment
		(start 101.59111 -216.736422)
		(end 101.585776 -216.73947)
		(width 0.0889)
		(layer "In4.Cu")
		(net "UPI_CPU0_CPU1_P1P0_DN<13>")
	)
	(segment
		(start 101.439472 -211.653628)
		(end 101.439726 -211.653882)
		(width 0.14732)
		(layer "In4.Cu")
		(net "UPI_CPU0_CPU1_P1P0_DN<13>")
	)
	(segment
		(start 369.353084 -216.260426)
		(end 369.353084 -216.231978)
		(width 0.0889)
		(layer "In4.Cu")
		(net "UPI_CPU0_CPU1_P1P0_DN<13>")
	)
	(segment
		(start 370.292884 -214.622634)
		(end 370.292884 -214.461852)
		(width 0.0889)
		(layer "In4.Cu")
		(net "UPI_CPU0_CPU1_P1P0_DN<13>")
	)
	(segment
		(start 170.812714 -148.588984)
		(end 166.795704 -148.482812)
		(width 0.14732)
		(layer "In4.Cu")
		(net "UPI_CPU0_CPU1_P1P0_DN<13>")
	)
	(segment
		(start 106.969052 -196.353176)
		(end 106.842814 -196.699632)
		(width 0.14732)
		(layer "In4.Cu")
		(net "UPI_CPU0_CPU1_P1P0_DN<13>")
	)
	(segment
		(start 101.496622 -212.69706)
		(end 101.397562 -212.79612)
		(width 0.0889)
		(layer "In4.Cu")
		(net "UPI_CPU0_CPU1_P1P0_DN<13>")
	)
	(segment
		(start 101.585776 -216.73947)
		(end 101.585014 -216.739978)
		(width 0.0889)
		(layer "In4.Cu")
		(net "UPI_CPU0_CPU1_P1P0_DN<13>")
	)
	(segment
		(start 101.916738 -209.799174)
		(end 101.790754 -210.145122)
		(width 0.14732)
		(layer "In4.Cu")
		(net "UPI_CPU0_CPU1_P1P0_DN<13>")
	)
	(segment
		(start 101.581458 -215.75903)
		(end 101.58349 -215.7603)
		(width 0.0889)
		(layer "In4.Cu")
		(net "UPI_CPU0_CPU1_P1P0_DN<13>")
	)
	(segment
		(start 101.615748 -217.335354)
		(end 101.772212 -217.064336)
		(width 0.0889)
		(layer "In4.Cu")
		(net "UPI_CPU0_CPU1_P1P0_DN<13>")
	)
	(segment
		(start 101.496622 -213.2457)
		(end 101.397562 -213.34476)
		(width 0.0889)
		(layer "In4.Cu")
		(net "UPI_CPU0_CPU1_P1P0_DN<13>")
	)
	(segment
		(start 369.82273 -217.072972)
		(end 369.82273 -217.0557)
		(width 0.0889)
		(layer "In4.Cu")
		(net "UPI_CPU0_CPU1_P1P0_DN<13>")
	)
	(segment
		(start 101.53777 -217.356182)
		(end 101.615748 -217.335354)
		(width 0.0889)
		(layer "In4.Cu")
		(net "UPI_CPU0_CPU1_P1P0_DN<13>")
	)
	(segment
		(start 101.397562 -212.97138)
		(end 101.496622 -213.07044)
		(width 0.0889)
		(layer "In4.Cu")
		(net "UPI_CPU0_CPU1_P1P0_DN<13>")
	)
	(segment
		(start 101.397562 -212.42274)
		(end 101.496622 -212.5218)
		(width 0.0889)
		(layer "In4.Cu")
		(net "UPI_CPU0_CPU1_P1P0_DN<13>")
	)
	(segment
		(start 362.026708 -187.91555)
		(end 361.27436 -186.074812)
		(width 0.14732)
		(layer "In4.Cu")
		(net "UPI_CPU0_CPU1_P1P0_DN<13>")
	)
	(segment
		(start 107.23372 -195.203064)
		(end 107.320334 -195.388738)
		(width 0.14732)
		(layer "In4.Cu")
		(net "UPI_CPU0_CPU1_P1P0_DN<13>")
	)
	(segment
		(start 106.491532 -197.663816)
		(end 106.305604 -197.75043)
		(width 0.14732)
		(layer "In4.Cu")
		(net "UPI_CPU0_CPU1_P1P0_DN<13>")
	)
	(segment
		(start 101.439472 -211.10956)
		(end 101.439472 -211.653628)
		(width 0.14732)
		(layer "In4.Cu")
		(net "UPI_CPU0_CPU1_P1P0_DN<13>")
	)
	(segment
		(start 101.439726 -211.950808)
		(end 101.397562 -211.992972)
		(width 0.0889)
		(layer "In4.Cu")
		(net "UPI_CPU0_CPU1_P1P0_DN<13>")
	)
	(segment
		(start 102.579932 -208.40192)
		(end 102.453694 -208.748376)
		(width 0.14732)
		(layer "In4.Cu")
		(net "UPI_CPU0_CPU1_P1P0_DN<13>")
	)
	(segment
		(start 102.142036 -209.180684)
		(end 102.22865 -209.366358)
		(width 0.14732)
		(layer "In4.Cu")
		(net "UPI_CPU0_CPU1_P1P0_DN<13>")
	)
	(segment
		(start 346.019882 -168.797224)
		(end 330.37272 -154.229308)
		(width 0.14732)
		(layer "In4.Cu")
		(net "UPI_CPU0_CPU1_P1P0_DN<13>")
	)
	(segment
		(start 130.732784 -170.03649)
		(end 113.57864 -186.165236)
		(width 0.14732)
		(layer "In4.Cu")
		(net "UPI_CPU0_CPU1_P1P0_DN<13>")
	)
	(segment
		(start 106.882946 -196.165978)
		(end 106.882438 -196.167502)
		(width 0.14732)
		(layer "In4.Cu")
		(net "UPI_CPU0_CPU1_P1P0_DN<13>")
	)
	(segment
		(start 354.417376 -170.864022)
		(end 351.952814 -169.394378)
		(width 0.14732)
		(layer "In4.Cu")
		(net "UPI_CPU0_CPU1_P1P0_DN<13>")
	)
	(segment
		(start 106.882438 -196.167502)
		(end 106.969052 -196.353176)
		(width 0.14732)
		(layer "In4.Cu")
		(net "UPI_CPU0_CPU1_P1P0_DN<13>")
	)
	(segment
		(start 101.397816 -217.0557)
		(end 101.397816 -217.072972)
		(width 0.0889)
		(layer "In4.Cu")
		(net "UPI_CPU0_CPU1_P1P0_DN<13>")
	)
	(segment
		(start 105.806748 -199.11949)
		(end 102.493318 -208.216246)
		(width 0.14732)
		(layer "In4.Cu")
		(net "UPI_CPU0_CPU1_P1P0_DN<13>")
	)
	(segment
		(start 102.493318 -208.216246)
		(end 102.579932 -208.40192)
		(width 0.14732)
		(layer "In4.Cu")
		(net "UPI_CPU0_CPU1_P1P0_DN<13>")
	)
	(segment
		(start 164.286438 -149.359112)
		(end 130.732784 -170.03649)
		(width 0.14732)
		(layer "In4.Cu")
		(net "UPI_CPU0_CPU1_P1P0_DN<13>")
	)
	(segment
		(start 351.952814 -169.394378)
		(end 350.891602 -169.244772)
		(width 0.14732)
		(layer "In4.Cu")
		(net "UPI_CPU0_CPU1_P1P0_DN<13>")
	)
	(segment
		(start 107.585002 -194.238626)
		(end 107.671616 -194.4243)
		(width 0.14732)
		(layer "In4.Cu")
		(net "UPI_CPU0_CPU1_P1P0_DN<13>")
	)
	(segment
		(start 101.439726 -211.653882)
		(end 101.439726 -211.92871)
		(width 0.14732)
		(layer "In4.Cu")
		(net "UPI_CPU0_CPU1_P1P0_DN<13>")
	)
	(segment
		(start 113.57864 -186.165236)
		(end 107.940856 -193.261742)
		(width 0.14732)
		(layer "In4.Cu")
		(net "UPI_CPU0_CPU1_P1P0_DN<13>")
	)
	(segment
		(start 369.781328 -211.732368)
		(end 369.781328 -211.71027)
		(width 0.0889)
		(layer "In4.Cu")
		(net "UPI_CPU0_CPU1_P1P0_DN<13>")
	)
	(segment
		(start 105.992676 -199.032876)
		(end 105.806748 -199.11949)
		(width 0.14732)
		(layer "In4.Cu")
		(net "UPI_CPU0_CPU1_P1P0_DN<13>")
	)
	(segment
		(start 101.565456 -210.763612)
		(end 101.439472 -211.10956)
		(width 0.14732)
		(layer "In4.Cu")
		(net "UPI_CPU0_CPU1_P1P0_DN<13>")
	)
	(segment
		(start 107.671616 -194.4243)
		(end 107.545378 -194.770756)
		(width 0.14732)
		(layer "In4.Cu")
		(net "UPI_CPU0_CPU1_P1P0_DN<13>")
	)
	(segment
		(start 101.58349 -215.7603)
		(end 101.585014 -215.761062)
		(width 0.0889)
		(layer "In4.Cu")
		(net "UPI_CPU0_CPU1_P1P0_DN<13>")
	)
	(segment
		(start 323.788532 -150.731728)
		(end 321.902328 -150.731728)
		(width 0.14732)
		(layer "In4.Cu")
		(net "UPI_CPU0_CPU1_P1P0_DN<13>")
	)
	(segment
		(start 233.775504 -149.769068)
		(end 195.70954 -159.582866)
		(width 0.14732)
		(layer "In4.Cu")
		(net "UPI_CPU0_CPU1_P1P0_DN<13>")
	)
	(segment
		(start 362.597954 -188.497464)
		(end 362.026708 -187.91555)
		(width 0.14732)
		(layer "In4.Cu")
		(net "UPI_CPU0_CPU1_P1P0_DN<13>")
	)
	(segment
		(start 277.067772 -159.763968)
		(end 238.154718 -149.769068)
		(width 0.14732)
		(layer "In4.Cu")
		(net "UPI_CPU0_CPU1_P1P0_DN<13>")
	)
	(segment
		(start 174.75073 -150.539196)
		(end 170.812714 -148.588984)
		(width 0.14732)
		(layer "In4.Cu")
		(net "UPI_CPU0_CPU1_P1P0_DN<13>")
	)
	(segment
		(start 369.781328 -211.412074)
		(end 369.781074 -211.41182)
		(width 0.14732)
		(layer "In4.Cu")
		(net "UPI_CPU0_CPU1_P1P0_DN<13>")
	)
	(segment
		(start 101.397562 -212.79612)
		(end 101.397562 -212.97138)
		(width 0.0889)
		(layer "In4.Cu")
		(net "UPI_CPU0_CPU1_P1P0_DN<13>")
	)
	(segment
		(start 106.617516 -197.317614)
		(end 106.491532 -197.663816)
		(width 0.14732)
		(layer "In4.Cu")
		(net "UPI_CPU0_CPU1_P1P0_DN<13>")
	)
	(segment
		(start 369.781328 -211.71027)
		(end 369.781328 -211.412074)
		(width 0.14732)
		(layer "In4.Cu")
		(net "UPI_CPU0_CPU1_P1P0_DN<13>")
	)
	(segment
		(start 107.320334 -195.388738)
		(end 107.194096 -195.735194)
		(width 0.14732)
		(layer "In4.Cu")
		(net "UPI_CPU0_CPU1_P1P0_DN<13>")
	)
	(segment
		(start 106.531156 -197.13194)
		(end 106.617516 -197.317614)
		(width 0.14732)
		(layer "In4.Cu")
		(net "UPI_CPU0_CPU1_P1P0_DN<13>")
	)
	(segment
		(start 354.41763 -170.864022)
		(end 354.417376 -170.864022)
		(width 0.14732)
		(layer "In4.Cu")
		(net "UPI_CPU0_CPU1_P1P0_DN<13>")
	)
	(segment
		(start 350.891602 -169.244772)
		(end 349.141034 -169.599356)
		(width 0.14732)
		(layer "In4.Cu")
		(net "UPI_CPU0_CPU1_P1P0_DN<13>")
	)
	(segment
		(start 194.356482 -159.753808)
		(end 192.361312 -159.753808)
		(width 0.14732)
		(layer "In4.Cu")
		(net "UPI_CPU0_CPU1_P1P0_DN<13>")
	)
	(segment
		(start 192.361312 -159.753808)
		(end 174.75073 -150.539196)
		(width 0.14732)
		(layer "In4.Cu")
		(net "UPI_CPU0_CPU1_P1P0_DN<13>")
	)
	(segment
		(start 101.583998 -215.112854)
		(end 101.576124 -215.117426)
		(width 0.0889)
		(layer "In4.Cu")
		(net "UPI_CPU0_CPU1_P1P0_DN<13>")
	)
	(segment
		(start 361.27436 -186.074812)
		(end 361.27436 -183.595264)
		(width 0.14732)
		(layer "In4.Cu")
		(net "UPI_CPU0_CPU1_P1P0_DN<13>")
	)
	(segment
		(start 356.923594 -173.091602)
		(end 355.107494 -171.275502)
		(width 0.14732)
		(layer "In4.Cu")
		(net "UPI_CPU0_CPU1_P1P0_DN<13>")
	)
	(segment
		(start 106.65714 -196.785992)
		(end 106.531156 -197.13194)
		(width 0.14732)
		(layer "In4.Cu")
		(net "UPI_CPU0_CPU1_P1P0_DN<13>")
	)
	(segment
		(start 107.359704 -194.857116)
		(end 107.23372 -195.203064)
		(width 0.14732)
		(layer "In4.Cu")
		(net "UPI_CPU0_CPU1_P1P0_DN<13>")
	)
	(segment
		(start 369.822984 -211.774024)
		(end 369.781328 -211.732368)
		(width 0.0889)
		(layer "In4.Cu")
		(net "UPI_CPU0_CPU1_P1P0_DN<13>")
	)
	(segment
		(start 106.842814 -196.699632)
		(end 106.65714 -196.785992)
		(width 0.14732)
		(layer "In4.Cu")
		(net "UPI_CPU0_CPU1_P1P0_DN<13>")
	)
	(segment
		(start 102.453694 -208.748376)
		(end 102.26802 -208.834736)
		(width 0.14732)
		(layer "In4.Cu")
		(net "UPI_CPU0_CPU1_P1P0_DN<13>")
	)
	(segment
		(start 369.604544 -218.421204)
		(end 369.580414 -218.33205)
		(width 0.0889)
		(layer "In4.Cu")
		(net "UPI_CPU0_CPU1_P1P0_DN<13>")
	)
	(segment
		(start 101.75113 -210.677252)
		(end 101.565456 -210.763612)
		(width 0.14732)
		(layer "In4.Cu")
		(net "UPI_CPU0_CPU1_P1P0_DN<13>")
	)
	(segment
		(start 101.790754 -210.145122)
		(end 101.877368 -210.330796)
		(width 0.14732)
		(layer "In4.Cu")
		(net "UPI_CPU0_CPU1_P1P0_DN<13>")
	)
	(segment
		(start 101.578156 -215.757252)
		(end 101.581458 -215.75903)
		(width 0.0889)
		(layer "In4.Cu")
		(net "UPI_CPU0_CPU1_P1P0_DN<13>")
	)
	(segment
		(start 102.102412 -209.712814)
		(end 101.916738 -209.799174)
		(width 0.14732)
		(layer "In4.Cu")
		(net "UPI_CPU0_CPU1_P1P0_DN<13>")
	)
	(segment
		(start 106.11866 -198.686674)
		(end 105.992676 -199.032876)
		(width 0.14732)
		(layer "In4.Cu")
		(net "UPI_CPU0_CPU1_P1P0_DN<13>")
	)
	(segment
		(start 101.867208 -214.424768)
		(end 101.867208 -214.644732)
		(width 0.0889)
		(layer "In4.Cu")
		(net "UPI_CPU0_CPU1_P1P0_DN<13>")
	)
	(segment
		(start 101.496622 -212.5218)
		(end 101.496622 -212.69706)
		(width 0.0889)
		(layer "In4.Cu")
		(net "UPI_CPU0_CPU1_P1P0_DN<13>")
	)
	(segment
		(start 101.439726 -211.92871)
		(end 101.439726 -211.950808)
		(width 0.0889)
		(layer "In4.Cu")
		(net "UPI_CPU0_CPU1_P1P0_DN<13>")
	)
	(segment
		(start 101.397562 -213.34476)
		(end 101.397562 -213.8934)
		(width 0.0889)
		(layer "In4.Cu")
		(net "UPI_CPU0_CPU1_P1P0_DN<13>")
	)
	(segment
		(start 101.576124 -215.755982)
		(end 101.578156 -215.757252)
		(width 0.0889)
		(layer "In4.Cu")
		(net "UPI_CPU0_CPU1_P1P0_DN<13>")
	)
	(segment
		(start 101.397562 -213.8934)
		(end 101.397816 -213.893908)
		(width 0.0889)
		(layer "In4.Cu")
		(net "UPI_CPU0_CPU1_P1P0_DN<13>")
	)
	(segment
		(start 101.877368 -210.330796)
		(end 101.75113 -210.677252)
		(width 0.14732)
		(layer "In4.Cu")
		(net "UPI_CPU0_CPU1_P1P0_DN<13>")
	)
	(segment
		(start 102.26802 -208.834736)
		(end 102.142036 -209.180684)
		(width 0.14732)
		(layer "In4.Cu")
		(net "UPI_CPU0_CPU1_P1P0_DN<13>")
	)
	(segment
		(start 369.353084 -217.8939)
		(end 369.353084 -217.859864)
		(width 0.0889)
		(layer "In4.Cu")
		(net "UPI_CPU0_CPU1_P1P0_DN<13>")
	)
	(segment
		(start 195.70954 -159.582866)
		(end 194.356482 -159.753808)
		(width 0.14732)
		(layer "In4.Cu")
		(net "UPI_CPU0_CPU1_P1P0_DN<13>")
	)
	(segment
		(start 101.397562 -211.992972)
		(end 101.397562 -212.42274)
		(width 0.0889)
		(layer "In4.Cu")
		(net "UPI_CPU0_CPU1_P1P0_DN<13>")
	)
	(segment
		(start 321.902328 -150.731728)
		(end 278.78913 -159.763968)
		(width 0.14732)
		(layer "In4.Cu")
		(net "UPI_CPU0_CPU1_P1P0_DN<13>")
	)
	(segment
		(start 278.78913 -159.763968)
		(end 277.067772 -159.763968)
		(width 0.14732)
		(layer "In4.Cu")
		(net "UPI_CPU0_CPU1_P1P0_DN<13>")
	)
	(segment
		(start 369.44808 -218.692222)
		(end 369.604544 -218.421204)
		(width 0.0889)
		(layer "In4.Cu")
		(net "UPI_CPU0_CPU1_P1P0_DN<13>")
	)
	(segment
		(start 330.37272 -154.229308)
		(end 327.155048 -151.576024)
		(width 0.14732)
		(layer "In4.Cu")
		(net "UPI_CPU0_CPU1_P1P0_DN<13>")
	)
	(segment
		(start 369.82273 -215.445086)
		(end 369.82273 -215.43645)
		(width 0.0889)
		(layer "In4.Cu")
		(net "UPI_CPU0_CPU1_P1P0_DN<13>")
	)
	(segment
		(start 106.305604 -197.75043)
		(end 106.0323 -198.501)
		(width 0.14732)
		(layer "In4.Cu")
		(net "UPI_CPU0_CPU1_P1P0_DN<13>")
	)
	(segment
		(start 369.781074 -205.839314)
		(end 362.597954 -188.497464)
		(width 0.14732)
		(layer "In4.Cu")
		(net "UPI_CPU0_CPU1_P1P0_DN<13>")
	)
	(segment
		(start 327.155048 -151.576024)
		(end 323.788532 -150.731728)
		(width 0.14732)
		(layer "In4.Cu")
		(net "UPI_CPU0_CPU1_P1P0_DN<13>")
	)
	(segment
		(start 101.585014 -215.112346)
		(end 101.583998 -215.112854)
		(width 0.0889)
		(layer "In4.Cu")
		(net "UPI_CPU0_CPU1_P1P0_DN<13>")
	)
	(segment
		(start 348.33433 -169.664126)
		(end 346.019882 -168.797224)
		(width 0.14732)
		(layer "In4.Cu")
		(net "UPI_CPU0_CPU1_P1P0_DN<13>")
	)
	(segment
		(start 107.545378 -194.770756)
		(end 107.359704 -194.857116)
		(width 0.14732)
		(layer "In4.Cu")
		(net "UPI_CPU0_CPU1_P1P0_DN<13>")
	)
	(segment
		(start 370.105432 -214.946992)
		(end 370.114322 -214.941912)
		(width 0.0889)
		(layer "In4.Cu")
		(net "UPI_CPU0_CPU1_P1P0_DN<13>")
	)
	(segment
		(start 101.496622 -213.07044)
		(end 101.496622 -213.2457)
		(width 0.0889)
		(layer "In4.Cu")
		(net "UPI_CPU0_CPU1_P1P0_DN<13>")
	)
	(segment
		(start 101.587808 -215.76284)
		(end 101.59111 -215.764618)
		(width 0.0889)
		(layer "In4.Cu")
		(net "UPI_CPU0_CPU1_P1P0_DN<13>")
	)
	(segment
		(start 369.82273 -215.43645)
		(end 369.822984 -215.422226)
		(width 0.0889)
		(layer "In4.Cu")
		(net "UPI_CPU0_CPU1_P1P0_DN<13>")
	)
	(segment
		(start 101.585014 -215.761062)
		(end 101.586538 -215.762078)
		(width 0.0889)
		(layer "In4.Cu")
		(net "UPI_CPU0_CPU1_P1P0_DN<13>")
	)
	(segment
		(start 238.154718 -149.769068)
		(end 233.775504 -149.769068)
		(width 0.14732)
		(layer "In4.Cu")
		(net "UPI_CPU0_CPU1_P1P0_DN<13>")
	)
	(segment
		(start 107.940856 -193.261742)
		(end 107.585002 -194.238626)
		(width 0.14732)
		(layer "In4.Cu")
		(net "UPI_CPU0_CPU1_P1P0_DN<13>")
	)
	(segment
		(start 369.781074 -211.41182)
		(end 369.781074 -205.839314)
		(width 0.14732)
		(layer "In4.Cu")
		(net "UPI_CPU0_CPU1_P1P0_DN<13>")
	)
	(arc
		(start 101.867208 -214.644732)
		(mid 101.786297 -214.91486)
		(end 101.585014 -215.112346)
		(width 0.0889)
		(layer "In4.Cu")
		(net "UPI_CPU0_CPU1_P1P0_DN<13>")
	)
	(arc
		(start 101.59111 -215.764618)
		(mid 101.867684 -216.25052)
		(end 101.59111 -216.736422)
		(width 0.0889)
		(layer "In4.Cu")
		(net "UPI_CPU0_CPU1_P1P0_DN<13>")
	)
	(arc
		(start 370.114322 -214.941912)
		(mid 370.245236 -214.805552)
		(end 370.292884 -214.622634)
		(width 0.0889)
		(layer "In4.Cu")
		(net "UPI_CPU0_CPU1_P1P0_DN<13>")
	)
	(arc
		(start 369.353084 -216.231978)
		(mid 369.433246 -215.959789)
		(end 369.635532 -215.760808)
		(width 0.0889)
		(layer "In4.Cu")
		(net "UPI_CPU0_CPU1_P1P0_DN<13>")
	)
	(arc
		(start 369.353084 -217.859864)
		(mid 369.433246 -217.587675)
		(end 369.635532 -217.388694)
		(width 0.0889)
		(layer "In4.Cu")
		(net "UPI_CPU0_CPU1_P1P0_DN<13>")
	)
	(arc
		(start 370.292884 -214.461852)
		(mid 370.217813 -214.34611)
		(end 370.10848 -214.261954)
		(width 0.0889)
		(layer "In4.Cu")
		(net "UPI_CPU0_CPU1_P1P0_DN<13>")
	)
	(arc
		(start 369.635532 -216.739978)
		(mid 369.431197 -216.537373)
		(end 369.353084 -216.260426)
		(width 0.0889)
		(layer "In4.Cu")
		(net "UPI_CPU0_CPU1_P1P0_DN<13>")
	)
	(arc
		(start 101.397562 -215.436704)
		(mid 101.445241 -215.619604)
		(end 101.576124 -215.755982)
		(width 0.0889)
		(layer "In4.Cu")
		(net "UPI_CPU0_CPU1_P1P0_DN<13>")
	)
	(arc
		(start 369.56365 -218.319096)
		(mid 369.411568 -218.129664)
		(end 369.353084 -217.8939)
		(width 0.0889)
		(layer "In4.Cu")
		(net "UPI_CPU0_CPU1_P1P0_DN<13>")
	)
	(arc
		(start 101.585014 -216.739978)
		(mid 101.450081 -216.873332)
		(end 101.397816 -217.0557)
		(width 0.0889)
		(layer "In4.Cu")
		(net "UPI_CPU0_CPU1_P1P0_DN<13>")
	)
	(arc
		(start 101.397816 -213.893908)
		(mid 101.472821 -214.009367)
		(end 101.581966 -214.093298)
		(width 0.0889)
		(layer "In4.Cu")
		(net "UPI_CPU0_CPU1_P1P0_DN<13>")
	)
	(arc
		(start 101.397816 -217.072972)
		(mid 101.43649 -217.23004)
		(end 101.53777 -217.356182)
		(width 0.0889)
		(layer "In4.Cu")
		(net "UPI_CPU0_CPU1_P1P0_DN<13>")
	)
	(arc
		(start 369.635532 -217.388694)
		(mid 369.770465 -217.25534)
		(end 369.82273 -217.072972)
		(width 0.0889)
		(layer "In4.Cu")
		(net "UPI_CPU0_CPU1_P1P0_DN<13>")
	)
	(arc
		(start 369.822984 -215.422226)
		(mid 369.902115 -215.14769)
		(end 370.105432 -214.946992)
		(width 0.0889)
		(layer "In4.Cu")
		(net "UPI_CPU0_CPU1_P1P0_DN<13>")
	)
	(arc
		(start 369.580414 -218.33205)
		(mid 369.571973 -218.32565)
		(end 369.56365 -218.319096)
		(width 0.0889)
		(layer "In4.Cu")
		(net "UPI_CPU0_CPU1_P1P0_DN<13>")
	)
	(arc
		(start 369.82273 -217.0557)
		(mid 369.77046 -216.873335)
		(end 369.635532 -216.739978)
		(width 0.0889)
		(layer "In4.Cu")
		(net "UPI_CPU0_CPU1_P1P0_DN<13>")
	)
	(arc
		(start 369.83797 -213.968838)
		(mid 369.830148 -213.949662)
		(end 369.822984 -213.93023)
		(width 0.0889)
		(layer "In4.Cu")
		(net "UPI_CPU0_CPU1_P1P0_DN<13>")
	)
	(arc
		(start 101.576124 -215.117426)
		(mid 101.44887 -215.247392)
		(end 101.397816 -215.421972)
		(width 0.0889)
		(layer "In4.Cu")
		(net "UPI_CPU0_CPU1_P1P0_DN<13>")
	)
	(arc
		(start 370.10848 -214.261954)
		(mid 369.948125 -214.138568)
		(end 369.83797 -213.968838)
		(width 0.0889)
		(layer "In4.Cu")
		(net "UPI_CPU0_CPU1_P1P0_DN<13>")
	)
	(arc
		(start 369.635532 -215.760808)
		(mid 369.770465 -215.627454)
		(end 369.82273 -215.445086)
		(width 0.0889)
		(layer "In4.Cu")
		(net "UPI_CPU0_CPU1_P1P0_DN<13>")
	)
	(arc
		(start 101.581966 -214.093298)
		(mid 101.755929 -214.232062)
		(end 101.867208 -214.424768)
		(width 0.0889)
		(layer "In4.Cu")
		(net "UPI_CPU0_CPU1_P1P0_DN<13>")
	)
	(arc
		(start 101.397816 -215.421972)
		(mid 101.397619 -215.429337)
		(end 101.397562 -215.436704)
		(width 0.0889)
		(layer "In4.Cu")
		(net "UPI_CPU0_CPU1_P1P0_DN<13>")
	)
	(segment
		(start 100.362512 -218.414346)
		(end 100.362512 -217.87866)
		(width 0.13208)
		(layer "F.Cu")
		(net "UPI_CPU0_CPU1_P1P0_DN<12>")
	)
	(segment
		(start 370.85778 -218.414346)
		(end 370.85778 -217.87866)
		(width 0.13208)
		(layer "F.Cu")
		(net "UPI_CPU0_CPU1_P1P0_DN<12>")
	)
	(segment
		(start 100.362512 -217.87866)
		(end 100.362766 -217.878406)
		(width 0.13208)
		(layer "F.Cu")
		(net "UPI_CPU0_CPU1_P1P0_DN<12>")
	)
	(segment
		(start 370.85778 -217.87866)
		(end 370.858034 -217.878406)
		(width 0.13208)
		(layer "F.Cu")
		(net "UPI_CPU0_CPU1_P1P0_DN<12>")
	)
	(segment
		(start 107.125008 -192.256918)
		(end 100.225606 -210.939126)
		(width 0.14732)
		(layer "In4.Cu")
		(net "UPI_CPU0_CPU1_P1P0_DN<12>")
	)
	(segment
		(start 363.530388 -187.84824)
		(end 363.0041 -187.311792)
		(width 0.14732)
		(layer "In4.Cu")
		(net "UPI_CPU0_CPU1_P1P0_DN<12>")
	)
	(segment
		(start 370.953284 -211.705952)
		(end 370.995448 -211.663788)
		(width 0.0889)
		(layer "In4.Cu")
		(net "UPI_CPU0_CPU1_P1P0_DN<12>")
	)
	(segment
		(start 314.904374 -148.064728)
		(end 314.904374 -148.06422)
		(width 0.14732)
		(layer "In4.Cu")
		(net "UPI_CPU0_CPU1_P1P0_DN<12>")
	)
	(segment
		(start 100.543868 -215.922606)
		(end 100.54717 -215.924384)
		(width 0.0889)
		(layer "In4.Cu")
		(net "UPI_CPU0_CPU1_P1P0_DN<12>")
	)
	(segment
		(start 100.549964 -216.574878)
		(end 100.546154 -216.577164)
		(width 0.0889)
		(layer "In4.Cu")
		(net "UPI_CPU0_CPU1_P1P0_DN<12>")
	)
	(segment
		(start 100.551234 -214.945976)
		(end 100.550218 -214.946484)
		(width 0.0889)
		(layer "In4.Cu")
		(net "UPI_CPU0_CPU1_P1P0_DN<12>")
	)
	(segment
		(start 371.423184 -214.63254)
		(end 371.423184 -214.425022)
		(width 0.0889)
		(layer "In4.Cu")
		(net "UPI_CPU0_CPU1_P1P0_DN<12>")
	)
	(segment
		(start 130.160522 -169.00652)
		(end 112.063276 -186.041538)
		(width 0.14732)
		(layer "In4.Cu")
		(net "UPI_CPU0_CPU1_P1P0_DN<12>")
	)
	(segment
		(start 100.16871 -212.51418)
		(end 100.16871 -212.68944)
		(width 0.0889)
		(layer "In4.Cu")
		(net "UPI_CPU0_CPU1_P1P0_DN<12>")
	)
	(segment
		(start 370.670836 -215.926162)
		(end 370.676932 -215.922606)
		(width 0.0889)
		(layer "In4.Cu")
		(net "UPI_CPU0_CPU1_P1P0_DN<12>")
	)
	(segment
		(start 100.225606 -211.480908)
		(end 100.22586 -211.481162)
		(width 0.14732)
		(layer "In4.Cu")
		(net "UPI_CPU0_CPU1_P1P0_DN<12>")
	)
	(segment
		(start 327.721468 -150.55723)
		(end 317.551054 -148.064728)
		(width 0.14732)
		(layer "In4.Cu")
		(net "UPI_CPU0_CPU1_P1P0_DN<12>")
	)
	(segment
		(start 112.063276 -186.041538)
		(end 107.140502 -192.215008)
		(width 0.14732)
		(layer "In4.Cu")
		(net "UPI_CPU0_CPU1_P1P0_DN<12>")
	)
	(segment
		(start 100.22586 -211.991448)
		(end 100.26777 -212.033358)
		(width 0.0889)
		(layer "In4.Cu")
		(net "UPI_CPU0_CPU1_P1P0_DN<12>")
	)
	(segment
		(start 371.131846 -215.117172)
		(end 371.139974 -215.1126)
		(width 0.0889)
		(layer "In4.Cu")
		(net "UPI_CPU0_CPU1_P1P0_DN<12>")
	)
	(segment
		(start 370.995448 -211.663788)
		(end 370.995448 -211.64169)
		(width 0.0889)
		(layer "In4.Cu")
		(net "UPI_CPU0_CPU1_P1P0_DN<12>")
	)
	(segment
		(start 371.139974 -215.1126)
		(end 371.140736 -215.112092)
		(width 0.0889)
		(layer "In4.Cu")
		(net "UPI_CPU0_CPU1_P1P0_DN<12>")
	)
	(segment
		(start 370.70157 -217.607388)
		(end 370.7257 -217.518234)
		(width 0.0889)
		(layer "In4.Cu")
		(net "UPI_CPU0_CPU1_P1P0_DN<12>")
	)
	(segment
		(start 100.225606 -210.939126)
		(end 100.225606 -211.480908)
		(width 0.14732)
		(layer "In4.Cu")
		(net "UPI_CPU0_CPU1_P1P0_DN<12>")
	)
	(segment
		(start 370.661946 -215.931242)
		(end 370.670836 -215.926162)
		(width 0.0889)
		(layer "In4.Cu")
		(net "UPI_CPU0_CPU1_P1P0_DN<12>")
	)
	(segment
		(start 370.995194 -205.870302)
		(end 363.530388 -187.84824)
		(width 0.14732)
		(layer "In4.Cu")
		(net "UPI_CPU0_CPU1_P1P0_DN<12>")
	)
	(segment
		(start 100.26777 -212.96376)
		(end 100.16871 -213.06282)
		(width 0.0889)
		(layer "In4.Cu")
		(net "UPI_CPU0_CPU1_P1P0_DN<12>")
	)
	(segment
		(start 370.995448 -211.298282)
		(end 370.995194 -211.298028)
		(width 0.14732)
		(layer "In4.Cu")
		(net "UPI_CPU0_CPU1_P1P0_DN<12>")
	)
	(segment
		(start 362.38688 -185.802016)
		(end 362.38688 -183.388)
		(width 0.14732)
		(layer "In4.Cu")
		(net "UPI_CPU0_CPU1_P1P0_DN<12>")
	)
	(segment
		(start 100.51923 -218.149424)
		(end 100.362766 -217.878406)
		(width 0.0889)
		(layer "In4.Cu")
		(net "UPI_CPU0_CPU1_P1P0_DN<12>")
	)
	(segment
		(start 100.736908 -214.461344)
		(end 100.736908 -214.622634)
		(width 0.0889)
		(layer "In4.Cu")
		(net "UPI_CPU0_CPU1_P1P0_DN<12>")
	)
	(segment
		(start 370.676932 -216.578434)
		(end 370.670836 -216.574878)
		(width 0.0889)
		(layer "In4.Cu")
		(net "UPI_CPU0_CPU1_P1P0_DN<12>")
	)
	(segment
		(start 107.140502 -192.215008)
		(end 107.125262 -192.256156)
		(width 0.14732)
		(layer "In4.Cu")
		(net "UPI_CPU0_CPU1_P1P0_DN<12>")
	)
	(segment
		(start 100.558854 -216.569798)
		(end 100.549964 -216.574878)
		(width 0.0889)
		(layer "In4.Cu")
		(net "UPI_CPU0_CPU1_P1P0_DN<12>")
	)
	(segment
		(start 370.995194 -211.298028)
		(end 370.995194 -205.870302)
		(width 0.14732)
		(layer "In4.Cu")
		(net "UPI_CPU0_CPU1_P1P0_DN<12>")
	)
	(segment
		(start 100.54717 -215.924384)
		(end 100.549202 -215.925654)
		(width 0.0889)
		(layer "In4.Cu")
		(net "UPI_CPU0_CPU1_P1P0_DN<12>")
	)
	(segment
		(start 100.546154 -216.577164)
		(end 100.537772 -216.58199)
		(width 0.0889)
		(layer "In4.Cu")
		(net "UPI_CPU0_CPU1_P1P0_DN<12>")
	)
	(segment
		(start 100.16871 -213.06282)
		(end 100.16871 -213.23808)
		(width 0.0889)
		(layer "In4.Cu")
		(net "UPI_CPU0_CPU1_P1P0_DN<12>")
	)
	(segment
		(start 362.38688 -183.388)
		(end 357.119174 -170.671998)
		(width 0.14732)
		(layer "In4.Cu")
		(net "UPI_CPU0_CPU1_P1P0_DN<12>")
	)
	(segment
		(start 238.603028 -147.22475)
		(end 170.240198 -146.128232)
		(width 0.14732)
		(layer "In4.Cu")
		(net "UPI_CPU0_CPU1_P1P0_DN<12>")
	)
	(segment
		(start 100.549964 -217.554048)
		(end 100.558854 -217.559128)
		(width 0.0889)
		(layer "In4.Cu")
		(net "UPI_CPU0_CPU1_P1P0_DN<12>")
	)
	(segment
		(start 100.26777 -212.41512)
		(end 100.16871 -212.51418)
		(width 0.0889)
		(layer "In4.Cu")
		(net "UPI_CPU0_CPU1_P1P0_DN<12>")
	)
	(segment
		(start 100.16871 -213.23808)
		(end 100.26777 -213.33714)
		(width 0.0889)
		(layer "In4.Cu")
		(net "UPI_CPU0_CPU1_P1P0_DN<12>")
	)
	(segment
		(start 370.953284 -213.8934)
		(end 370.953284 -211.705952)
		(width 0.0889)
		(layer "In4.Cu")
		(net "UPI_CPU0_CPU1_P1P0_DN<12>")
	)
	(segment
		(start 100.597462 -218.170252)
		(end 100.51923 -218.149424)
		(width 0.0889)
		(layer "In4.Cu")
		(net "UPI_CPU0_CPU1_P1P0_DN<12>")
	)
	(segment
		(start 370.995448 -211.64169)
		(end 370.995448 -211.298282)
		(width 0.14732)
		(layer "In4.Cu")
		(net "UPI_CPU0_CPU1_P1P0_DN<12>")
	)
	(segment
		(start 354.884482 -167.998902)
		(end 327.721468 -150.55723)
		(width 0.14732)
		(layer "In4.Cu")
		(net "UPI_CPU0_CPU1_P1P0_DN<12>")
	)
	(segment
		(start 100.26777 -212.033358)
		(end 100.26777 -212.41512)
		(width 0.0889)
		(layer "In4.Cu")
		(net "UPI_CPU0_CPU1_P1P0_DN<12>")
	)
	(segment
		(start 100.22586 -211.481162)
		(end 100.22586 -211.96935)
		(width 0.14732)
		(layer "In4.Cu")
		(net "UPI_CPU0_CPU1_P1P0_DN<12>")
	)
	(segment
		(start 357.119174 -170.671998)
		(end 354.884482 -167.998902)
		(width 0.14732)
		(layer "In4.Cu")
		(net "UPI_CPU0_CPU1_P1P0_DN<12>")
	)
	(segment
		(start 370.670836 -216.574878)
		(end 370.661946 -216.569798)
		(width 0.0889)
		(layer "In4.Cu")
		(net "UPI_CPU0_CPU1_P1P0_DN<12>")
	)
	(segment
		(start 100.549202 -215.925654)
		(end 100.550726 -215.92667)
		(width 0.0889)
		(layer "In4.Cu")
		(net "UPI_CPU0_CPU1_P1P0_DN<12>")
	)
	(segment
		(start 275.792692 -146.555206)
		(end 238.603028 -147.22475)
		(width 0.14732)
		(layer "In4.Cu")
		(net "UPI_CPU0_CPU1_P1P0_DN<12>")
	)
	(segment
		(start 170.240198 -146.128232)
		(end 163.642294 -148.403818)
		(width 0.14732)
		(layer "In4.Cu")
		(net "UPI_CPU0_CPU1_P1P0_DN<12>")
	)
	(segment
		(start 370.842286 -217.851228)
		(end 370.70157 -217.607388)
		(width 0.0889)
		(layer "In4.Cu")
		(net "UPI_CPU0_CPU1_P1P0_DN<12>")
	)
	(segment
		(start 100.26777 -213.33714)
		(end 100.26777 -213.931246)
		(width 0.0889)
		(layer "In4.Cu")
		(net "UPI_CPU0_CPU1_P1P0_DN<12>")
	)
	(segment
		(start 163.642294 -148.403818)
		(end 130.160522 -169.00652)
		(width 0.14732)
		(layer "In4.Cu")
		(net "UPI_CPU0_CPU1_P1P0_DN<12>")
	)
	(segment
		(start 314.904374 -148.06422)
		(end 275.792692 -146.555206)
		(width 0.14732)
		(layer "In4.Cu")
		(net "UPI_CPU0_CPU1_P1P0_DN<12>")
	)
	(segment
		(start 317.551054 -148.064728)
		(end 314.904374 -148.064728)
		(width 0.14732)
		(layer "In4.Cu")
		(net "UPI_CPU0_CPU1_P1P0_DN<12>")
	)
	(segment
		(start 100.22586 -211.96935)
		(end 100.22586 -211.991448)
		(width 0.0889)
		(layer "In4.Cu")
		(net "UPI_CPU0_CPU1_P1P0_DN<12>")
	)
	(segment
		(start 100.558346 -214.941912)
		(end 100.551234 -214.945976)
		(width 0.0889)
		(layer "In4.Cu")
		(net "UPI_CPU0_CPU1_P1P0_DN<12>")
	)
	(segment
		(start 100.550218 -214.946484)
		(end 100.549456 -214.946992)
		(width 0.0889)
		(layer "In4.Cu")
		(net "UPI_CPU0_CPU1_P1P0_DN<12>")
	)
	(segment
		(start 370.953284 -217.07856)
		(end 370.953284 -217.064336)
		(width 0.0889)
		(layer "In4.Cu")
		(net "UPI_CPU0_CPU1_P1P0_DN<12>")
	)
	(segment
		(start 100.267262 -217.064336)
		(end 100.267262 -217.071956)
		(width 0.0889)
		(layer "In4.Cu")
		(net "UPI_CPU0_CPU1_P1P0_DN<12>")
	)
	(segment
		(start 100.558854 -215.931496)
		(end 100.558854 -215.931242)
		(width 0.0889)
		(layer "In4.Cu")
		(net "UPI_CPU0_CPU1_P1P0_DN<12>")
	)
	(segment
		(start 107.125262 -192.256156)
		(end 107.125008 -192.256918)
		(width 0.14732)
		(layer "In4.Cu")
		(net "UPI_CPU0_CPU1_P1P0_DN<12>")
	)
	(segment
		(start 370.858034 -217.878406)
		(end 370.842286 -217.851228)
		(width 0.0889)
		(layer "In4.Cu")
		(net "UPI_CPU0_CPU1_P1P0_DN<12>")
	)
	(segment
		(start 100.26777 -213.931246)
		(end 100.267516 -213.930484)
		(width 0.0889)
		(layer "In4.Cu")
		(net "UPI_CPU0_CPU1_P1P0_DN<12>")
	)
	(segment
		(start 363.0041 -187.311792)
		(end 362.38688 -185.802016)
		(width 0.14732)
		(layer "In4.Cu")
		(net "UPI_CPU0_CPU1_P1P0_DN<12>")
	)
	(segment
		(start 100.550726 -215.92667)
		(end 100.558854 -215.931496)
		(width 0.0889)
		(layer "In4.Cu")
		(net "UPI_CPU0_CPU1_P1P0_DN<12>")
	)
	(segment
		(start 100.16871 -212.68944)
		(end 100.26777 -212.7885)
		(width 0.0889)
		(layer "In4.Cu")
		(net "UPI_CPU0_CPU1_P1P0_DN<12>")
	)
	(segment
		(start 100.26777 -212.7885)
		(end 100.26777 -212.96376)
		(width 0.0889)
		(layer "In4.Cu")
		(net "UPI_CPU0_CPU1_P1P0_DN<12>")
	)
	(arc
		(start 100.558854 -215.931242)
		(mid 100.737451 -216.25052)
		(end 100.558854 -216.569798)
		(width 0.0889)
		(layer "In4.Cu")
		(net "UPI_CPU0_CPU1_P1P0_DN<12>")
	)
	(arc
		(start 100.267516 -213.930484)
		(mid 100.274801 -213.950046)
		(end 100.282756 -213.969346)
		(width 0.0889)
		(layer "In4.Cu")
		(net "UPI_CPU0_CPU1_P1P0_DN<12>")
	)
	(arc
		(start 370.676932 -215.922606)
		(mid 370.879408 -215.716083)
		(end 370.953284 -215.43645)
		(width 0.0889)
		(layer "In4.Cu")
		(net "UPI_CPU0_CPU1_P1P0_DN<12>")
	)
	(arc
		(start 100.552758 -214.261954)
		(mid 100.661905 -214.345882)
		(end 100.736908 -214.461344)
		(width 0.0889)
		(layer "In4.Cu")
		(net "UPI_CPU0_CPU1_P1P0_DN<12>")
	)
	(arc
		(start 370.953284 -215.43645)
		(mid 371.000963 -215.25355)
		(end 371.131846 -215.117172)
		(width 0.0889)
		(layer "In4.Cu")
		(net "UPI_CPU0_CPU1_P1P0_DN<12>")
	)
	(arc
		(start 100.558854 -217.559128)
		(mid 100.689768 -217.695488)
		(end 100.737416 -217.878406)
		(width 0.0889)
		(layer "In4.Cu")
		(net "UPI_CPU0_CPU1_P1P0_DN<12>")
	)
	(arc
		(start 370.953284 -217.064336)
		(mid 370.879368 -216.784834)
		(end 370.676932 -216.578434)
		(width 0.0889)
		(layer "In4.Cu")
		(net "UPI_CPU0_CPU1_P1P0_DN<12>")
	)
	(arc
		(start 371.423184 -214.425022)
		(mid 371.311846 -214.232122)
		(end 371.137688 -214.093298)
		(width 0.0889)
		(layer "In4.Cu")
		(net "UPI_CPU0_CPU1_P1P0_DN<12>")
	)
	(arc
		(start 100.282756 -213.969346)
		(mid 100.39275 -214.138715)
		(end 100.552758 -214.261954)
		(width 0.0889)
		(layer "In4.Cu")
		(net "UPI_CPU0_CPU1_P1P0_DN<12>")
	)
	(arc
		(start 370.661946 -216.569798)
		(mid 370.48347 -216.25052)
		(end 370.661946 -215.931242)
		(width 0.0889)
		(layer "In4.Cu")
		(net "UPI_CPU0_CPU1_P1P0_DN<12>")
	)
	(arc
		(start 371.137688 -214.093298)
		(mid 371.028292 -214.009201)
		(end 370.953284 -213.8934)
		(width 0.0889)
		(layer "In4.Cu")
		(net "UPI_CPU0_CPU1_P1P0_DN<12>")
	)
	(arc
		(start 371.140736 -215.112092)
		(mid 371.345071 -214.909487)
		(end 371.423184 -214.63254)
		(width 0.0889)
		(layer "In4.Cu")
		(net "UPI_CPU0_CPU1_P1P0_DN<12>")
	)
	(arc
		(start 100.736908 -214.622634)
		(mid 100.689229 -214.805534)
		(end 100.558346 -214.941912)
		(width 0.0889)
		(layer "In4.Cu")
		(net "UPI_CPU0_CPU1_P1P0_DN<12>")
	)
	(arc
		(start 100.549456 -214.946992)
		(mid 100.26706 -215.433205)
		(end 100.543868 -215.922606)
		(width 0.0889)
		(layer "In4.Cu")
		(net "UPI_CPU0_CPU1_P1P0_DN<12>")
	)
	(arc
		(start 370.742464 -217.50528)
		(mid 370.894971 -217.315182)
		(end 370.953284 -217.07856)
		(width 0.0889)
		(layer "In4.Cu")
		(net "UPI_CPU0_CPU1_P1P0_DN<12>")
	)
	(arc
		(start 100.267262 -217.071956)
		(mid 100.344891 -217.350369)
		(end 100.549964 -217.554048)
		(width 0.0889)
		(layer "In4.Cu")
		(net "UPI_CPU0_CPU1_P1P0_DN<12>")
	)
	(arc
		(start 100.737416 -217.878406)
		(mid 100.700556 -218.040203)
		(end 100.597462 -218.170252)
		(width 0.0889)
		(layer "In4.Cu")
		(net "UPI_CPU0_CPU1_P1P0_DN<12>")
	)
	(arc
		(start 370.7257 -217.518234)
		(mid 370.734143 -217.511836)
		(end 370.742464 -217.50528)
		(width 0.0889)
		(layer "In4.Cu")
		(net "UPI_CPU0_CPU1_P1P0_DN<12>")
	)
	(arc
		(start 100.537772 -216.58199)
		(mid 100.339544 -216.787838)
		(end 100.267262 -217.064336)
		(width 0.0889)
		(layer "In4.Cu")
		(net "UPI_CPU0_CPU1_P1P0_DN<12>")
	)
	(segment
		(start 371.327934 -218.692476)
		(end 371.32768 -218.692222)
		(width 0.13208)
		(layer "F.Cu")
		(net "UPI_CPU0_CPU1_P1P0_DN<11>")
	)
	(segment
		(start 99.892866 -217.600276)
		(end 99.892866 -217.06459)
		(width 0.13208)
		(layer "F.Cu")
		(net "UPI_CPU0_CPU1_P1P0_DN<11>")
	)
	(segment
		(start 99.892866 -217.06459)
		(end 99.892612 -217.064336)
		(width 0.13208)
		(layer "F.Cu")
		(net "UPI_CPU0_CPU1_P1P0_DN<11>")
	)
	(segment
		(start 371.327934 -219.228162)
		(end 371.327934 -218.692476)
		(width 0.13208)
		(layer "F.Cu")
		(net "UPI_CPU0_CPU1_P1P0_DN<11>")
	)
	(segment
		(start 111.026448 -186.223656)
		(end 110.375192 -187.04052)
		(width 0.14732)
		(layer "In4.Cu")
		(net "UPI_CPU0_CPU1_P1P0_DN<11>")
	)
	(segment
		(start 276.075902 -145.99285)
		(end 238.600742 -146.667474)
		(width 0.14732)
		(layer "In4.Cu")
		(net "UPI_CPU0_CPU1_P1P0_DN<11>")
	)
	(segment
		(start 99.560126 -211.96935)
		(end 99.560126 -211.991448)
		(width 0.0889)
		(layer "In4.Cu")
		(net "UPI_CPU0_CPU1_P1P0_DN<11>")
	)
	(segment
		(start 363.78388 -186.404504)
		(end 363.328204 -185.939684)
		(width 0.14732)
		(layer "In4.Cu")
		(net "UPI_CPU0_CPU1_P1P0_DN<11>")
	)
	(segment
		(start 363.987334 -187.274454)
		(end 363.846364 -186.93384)
		(width 0.14732)
		(layer "In4.Cu")
		(net "UPI_CPU0_CPU1_P1P0_DN<11>")
	)
	(segment
		(start 107.097068 -191.151256)
		(end 106.808524 -191.513206)
		(width 0.14732)
		(layer "In4.Cu")
		(net "UPI_CPU0_CPU1_P1P0_DN<11>")
	)
	(segment
		(start 364.380018 -188.222636)
		(end 364.239048 -187.882022)
		(width 0.14732)
		(layer "In4.Cu")
		(net "UPI_CPU0_CPU1_P1P0_DN<11>")
	)
	(segment
		(start 109.000544 -188.959998)
		(end 108.727748 -189.301882)
		(width 0.14732)
		(layer "In4.Cu")
		(net "UPI_CPU0_CPU1_P1P0_DN<11>")
	)
	(segment
		(start 371.660674 -206.010002)
		(end 365.042196 -190.030862)
		(width 0.14732)
		(layer "In4.Cu")
		(net "UPI_CPU0_CPU1_P1P0_DN<11>")
	)
	(segment
		(start 360.256328 -176.709578)
		(end 360.256074 -176.709578)
		(width 0.14732)
		(layer "In4.Cu")
		(net "UPI_CPU0_CPU1_P1P0_DN<11>")
	)
	(segment
		(start 108.303568 -189.833758)
		(end 108.031026 -190.175642)
		(width 0.14732)
		(layer "In4.Cu")
		(net "UPI_CPU0_CPU1_P1P0_DN<11>")
	)
	(segment
		(start 357.65867 -170.438318)
		(end 355.266752 -167.577516)
		(width 0.14732)
		(layer "In4.Cu")
		(net "UPI_CPU0_CPU1_P1P0_DN<11>")
	)
	(segment
		(start 99.559872 -211.140802)
		(end 99.559872 -211.480908)
		(width 0.14732)
		(layer "In4.Cu")
		(net "UPI_CPU0_CPU1_P1P0_DN<11>")
	)
	(segment
		(start 371.660674 -211.41182)
		(end 371.660674 -206.010002)
		(width 0.14732)
		(layer "In4.Cu")
		(net "UPI_CPU0_CPU1_P1P0_DN<11>")
	)
	(segment
		(start 363.846364 -186.93384)
		(end 363.924596 -186.74461)
		(width 0.14732)
		(layer "In4.Cu")
		(net "UPI_CPU0_CPU1_P1P0_DN<11>")
	)
	(segment
		(start 99.71151 -216.736422)
		(end 99.706176 -216.73947)
		(width 0.0889)
		(layer "In4.Cu")
		(net "UPI_CPU0_CPU1_P1P0_DN<11>")
	)
	(segment
		(start 99.517962 -212.49894)
		(end 99.617022 -212.598)
		(width 0.0889)
		(layer "In4.Cu")
		(net "UPI_CPU0_CPU1_P1P0_DN<11>")
	)
	(segment
		(start 99.517962 -212.033612)
		(end 99.517962 -212.49894)
		(width 0.0889)
		(layer "In4.Cu")
		(net "UPI_CPU0_CPU1_P1P0_DN<11>")
	)
	(segment
		(start 99.705414 -215.112346)
		(end 99.704398 -215.112854)
		(width 0.0889)
		(layer "In4.Cu")
		(net "UPI_CPU0_CPU1_P1P0_DN<11>")
	)
	(segment
		(start 107.859576 -190.194946)
		(end 107.521756 -190.618618)
		(width 0.14732)
		(layer "In4.Cu")
		(net "UPI_CPU0_CPU1_P1P0_DN<11>")
	)
	(segment
		(start 163.492942 -147.830794)
		(end 129.768092 -168.581832)
		(width 0.14732)
		(layer "In4.Cu")
		(net "UPI_CPU0_CPU1_P1P0_DN<11>")
	)
	(segment
		(start 99.705414 -215.761062)
		(end 99.707954 -215.762586)
		(width 0.0889)
		(layer "In4.Cu")
		(net "UPI_CPU0_CPU1_P1P0_DN<11>")
	)
	(segment
		(start 110.1217 -187.553854)
		(end 109.950504 -187.573158)
		(width 0.14732)
		(layer "In4.Cu")
		(net "UPI_CPU0_CPU1_P1P0_DN<11>")
	)
	(segment
		(start 371.32768 -218.692222)
		(end 371.484144 -218.421204)
		(width 0.0889)
		(layer "In4.Cu")
		(net "UPI_CPU0_CPU1_P1P0_DN<11>")
	)
	(segment
		(start 99.706176 -216.73947)
		(end 99.705414 -216.739978)
		(width 0.0889)
		(layer "In4.Cu")
		(net "UPI_CPU0_CPU1_P1P0_DN<11>")
	)
	(segment
		(start 99.517962 -213.44128)
		(end 99.517962 -213.8934)
		(width 0.0889)
		(layer "In4.Cu")
		(net "UPI_CPU0_CPU1_P1P0_DN<11>")
	)
	(segment
		(start 371.985032 -214.946992)
		(end 371.993922 -214.941912)
		(width 0.0889)
		(layer "In4.Cu")
		(net "UPI_CPU0_CPU1_P1P0_DN<11>")
	)
	(segment
		(start 364.817152 -188.899546)
		(end 364.569248 -188.300868)
		(width 0.14732)
		(layer "In4.Cu")
		(net "UPI_CPU0_CPU1_P1P0_DN<11>")
	)
	(segment
		(start 110.394496 -187.21197)
		(end 110.1217 -187.553854)
		(width 0.14732)
		(layer "In4.Cu")
		(net "UPI_CPU0_CPU1_P1P0_DN<11>")
	)
	(segment
		(start 363.08538 -185.34634)
		(end 363.08538 -184.804558)
		(width 0.14732)
		(layer "In4.Cu")
		(net "UPI_CPU0_CPU1_P1P0_DN<11>")
	)
	(segment
		(start 99.617022 -212.598)
		(end 99.617022 -212.77326)
		(width 0.0889)
		(layer "In4.Cu")
		(net "UPI_CPU0_CPU1_P1P0_DN<11>")
	)
	(segment
		(start 365.042196 -190.030862)
		(end 364.817152 -188.899546)
		(width 0.14732)
		(layer "In4.Cu")
		(net "UPI_CPU0_CPU1_P1P0_DN<11>")
	)
	(segment
		(start 109.678216 -187.914534)
		(end 109.69752 -188.085984)
		(width 0.14732)
		(layer "In4.Cu")
		(net "UPI_CPU0_CPU1_P1P0_DN<11>")
	)
	(segment
		(start 99.65817 -217.356182)
		(end 99.736148 -217.335354)
		(width 0.0889)
		(layer "In4.Cu")
		(net "UPI_CPU0_CPU1_P1P0_DN<11>")
	)
	(segment
		(start 99.517962 -213.0679)
		(end 99.617022 -213.16696)
		(width 0.0889)
		(layer "In4.Cu")
		(net "UPI_CPU0_CPU1_P1P0_DN<11>")
	)
	(segment
		(start 371.660928 -211.737448)
		(end 371.660928 -211.71535)
		(width 0.0889)
		(layer "In4.Cu")
		(net "UPI_CPU0_CPU1_P1P0_DN<11>")
	)
	(segment
		(start 99.517962 -213.8934)
		(end 99.518216 -213.893908)
		(width 0.0889)
		(layer "In4.Cu")
		(net "UPI_CPU0_CPU1_P1P0_DN<11>")
	)
	(segment
		(start 362.9406 -184.291478)
		(end 363.08538 -184.146698)
		(width 0.14732)
		(layer "In4.Cu")
		(net "UPI_CPU0_CPU1_P1P0_DN<11>")
	)
	(segment
		(start 107.268518 -191.131952)
		(end 107.097068 -191.151256)
		(width 0.14732)
		(layer "In4.Cu")
		(net "UPI_CPU0_CPU1_P1P0_DN<11>")
	)
	(segment
		(start 99.704398 -215.112854)
		(end 99.696524 -215.117426)
		(width 0.0889)
		(layer "In4.Cu")
		(net "UPI_CPU0_CPU1_P1P0_DN<11>")
	)
	(segment
		(start 364.31728 -187.692792)
		(end 364.176564 -187.352686)
		(width 0.14732)
		(layer "In4.Cu")
		(net "UPI_CPU0_CPU1_P1P0_DN<11>")
	)
	(segment
		(start 109.69752 -188.085984)
		(end 109.424724 -188.427868)
		(width 0.14732)
		(layer "In4.Cu")
		(net "UPI_CPU0_CPU1_P1P0_DN<11>")
	)
	(segment
		(start 99.698556 -215.757252)
		(end 99.705414 -215.761062)
		(width 0.0889)
		(layer "In4.Cu")
		(net "UPI_CPU0_CPU1_P1P0_DN<11>")
	)
	(segment
		(start 317.618872 -147.503896)
		(end 314.926472 -147.503896)
		(width 0.14732)
		(layer "In4.Cu")
		(net "UPI_CPU0_CPU1_P1P0_DN<11>")
	)
	(segment
		(start 238.600742 -146.667474)
		(end 170.072558 -145.55851)
		(width 0.14732)
		(layer "In4.Cu")
		(net "UPI_CPU0_CPU1_P1P0_DN<11>")
	)
	(segment
		(start 99.559872 -211.480908)
		(end 99.560126 -211.481162)
		(width 0.14732)
		(layer "In4.Cu")
		(net "UPI_CPU0_CPU1_P1P0_DN<11>")
	)
	(segment
		(start 371.232684 -217.8939)
		(end 371.232684 -217.859864)
		(width 0.0889)
		(layer "In4.Cu")
		(net "UPI_CPU0_CPU1_P1P0_DN<11>")
	)
	(segment
		(start 99.617022 -213.16696)
		(end 99.617022 -213.34222)
		(width 0.0889)
		(layer "In4.Cu")
		(net "UPI_CPU0_CPU1_P1P0_DN<11>")
	)
	(segment
		(start 109.950504 -187.573158)
		(end 109.678216 -187.914534)
		(width 0.14732)
		(layer "In4.Cu")
		(net "UPI_CPU0_CPU1_P1P0_DN<11>")
	)
	(segment
		(start 99.987608 -214.424768)
		(end 99.987608 -214.644732)
		(width 0.0889)
		(layer "In4.Cu")
		(net "UPI_CPU0_CPU1_P1P0_DN<11>")
	)
	(segment
		(start 108.727748 -189.301882)
		(end 108.556552 -189.321186)
		(width 0.14732)
		(layer "In4.Cu")
		(net "UPI_CPU0_CPU1_P1P0_DN<11>")
	)
	(segment
		(start 371.70233 -217.072972)
		(end 371.70233 -217.0557)
		(width 0.0889)
		(layer "In4.Cu")
		(net "UPI_CPU0_CPU1_P1P0_DN<11>")
	)
	(segment
		(start 99.617022 -213.34222)
		(end 99.517962 -213.44128)
		(width 0.0889)
		(layer "In4.Cu")
		(net "UPI_CPU0_CPU1_P1P0_DN<11>")
	)
	(segment
		(start 107.54106 -190.790068)
		(end 107.268518 -191.131952)
		(width 0.14732)
		(layer "In4.Cu")
		(net "UPI_CPU0_CPU1_P1P0_DN<11>")
	)
	(segment
		(start 372.172484 -214.622634)
		(end 372.172484 -214.461852)
		(width 0.0889)
		(layer "In4.Cu")
		(net "UPI_CPU0_CPU1_P1P0_DN<11>")
	)
	(segment
		(start 314.926472 -147.503896)
		(end 314.926218 -147.503642)
		(width 0.14732)
		(layer "In4.Cu")
		(net "UPI_CPU0_CPU1_P1P0_DN<11>")
	)
	(segment
		(start 109.253528 -188.447172)
		(end 108.98124 -188.788548)
		(width 0.14732)
		(layer "In4.Cu")
		(net "UPI_CPU0_CPU1_P1P0_DN<11>")
	)
	(segment
		(start 99.736148 -217.335354)
		(end 99.892612 -217.064336)
		(width 0.0889)
		(layer "In4.Cu")
		(net "UPI_CPU0_CPU1_P1P0_DN<11>")
	)
	(segment
		(start 314.926218 -147.503642)
		(end 276.075902 -145.99285)
		(width 0.14732)
		(layer "In4.Cu")
		(net "UPI_CPU0_CPU1_P1P0_DN<11>")
	)
	(segment
		(start 99.518216 -217.0557)
		(end 99.518216 -217.072972)
		(width 0.0889)
		(layer "In4.Cu")
		(net "UPI_CPU0_CPU1_P1P0_DN<11>")
	)
	(segment
		(start 363.328204 -185.939684)
		(end 363.08538 -185.34634)
		(width 0.14732)
		(layer "In4.Cu")
		(net "UPI_CPU0_CPU1_P1P0_DN<11>")
	)
	(segment
		(start 371.70233 -215.445086)
		(end 371.70233 -215.43645)
		(width 0.0889)
		(layer "In4.Cu")
		(net "UPI_CPU0_CPU1_P1P0_DN<11>")
	)
	(segment
		(start 360.256074 -176.709578)
		(end 357.65867 -170.438318)
		(width 0.14732)
		(layer "In4.Cu")
		(net "UPI_CPU0_CPU1_P1P0_DN<11>")
	)
	(segment
		(start 371.702584 -213.93023)
		(end 371.702584 -211.779104)
		(width 0.0889)
		(layer "In4.Cu")
		(net "UPI_CPU0_CPU1_P1P0_DN<11>")
	)
	(segment
		(start 371.660928 -211.71535)
		(end 371.660928 -211.412074)
		(width 0.14732)
		(layer "In4.Cu")
		(net "UPI_CPU0_CPU1_P1P0_DN<11>")
	)
	(segment
		(start 129.768092 -168.581832)
		(end 111.026448 -186.223656)
		(width 0.14732)
		(layer "In4.Cu")
		(net "UPI_CPU0_CPU1_P1P0_DN<11>")
	)
	(segment
		(start 107.521756 -190.618618)
		(end 107.54106 -190.790068)
		(width 0.14732)
		(layer "In4.Cu")
		(net "UPI_CPU0_CPU1_P1P0_DN<11>")
	)
	(segment
		(start 355.266752 -167.577516)
		(end 327.946004 -150.034498)
		(width 0.14732)
		(layer "In4.Cu")
		(net "UPI_CPU0_CPU1_P1P0_DN<11>")
	)
	(segment
		(start 99.560126 -211.481162)
		(end 99.560126 -211.96935)
		(width 0.14732)
		(layer "In4.Cu")
		(net "UPI_CPU0_CPU1_P1P0_DN<11>")
	)
	(segment
		(start 371.232684 -216.260426)
		(end 371.232684 -216.231978)
		(width 0.0889)
		(layer "In4.Cu")
		(net "UPI_CPU0_CPU1_P1P0_DN<11>")
	)
	(segment
		(start 363.08538 -183.539384)
		(end 360.256328 -176.709578)
		(width 0.14732)
		(layer "In4.Cu")
		(net "UPI_CPU0_CPU1_P1P0_DN<11>")
	)
	(segment
		(start 363.08538 -184.146698)
		(end 363.08538 -183.539384)
		(width 0.14732)
		(layer "In4.Cu")
		(net "UPI_CPU0_CPU1_P1P0_DN<11>")
	)
	(segment
		(start 362.9406 -184.659778)
		(end 362.9406 -184.291478)
		(width 0.14732)
		(layer "In4.Cu")
		(net "UPI_CPU0_CPU1_P1P0_DN<11>")
	)
	(segment
		(start 363.924596 -186.74461)
		(end 363.78388 -186.404504)
		(width 0.14732)
		(layer "In4.Cu")
		(net "UPI_CPU0_CPU1_P1P0_DN<11>")
	)
	(segment
		(start 99.517962 -212.87232)
		(end 99.517962 -213.0679)
		(width 0.0889)
		(layer "In4.Cu")
		(net "UPI_CPU0_CPU1_P1P0_DN<11>")
	)
	(segment
		(start 364.239048 -187.882022)
		(end 364.31728 -187.692792)
		(width 0.14732)
		(layer "In4.Cu")
		(net "UPI_CPU0_CPU1_P1P0_DN<11>")
	)
	(segment
		(start 364.569248 -188.300868)
		(end 364.380018 -188.222636)
		(width 0.14732)
		(layer "In4.Cu")
		(net "UPI_CPU0_CPU1_P1P0_DN<11>")
	)
	(segment
		(start 108.98124 -188.788548)
		(end 109.000544 -188.959998)
		(width 0.14732)
		(layer "In4.Cu")
		(net "UPI_CPU0_CPU1_P1P0_DN<11>")
	)
	(segment
		(start 99.696524 -215.755982)
		(end 99.698556 -215.757252)
		(width 0.0889)
		(layer "In4.Cu")
		(net "UPI_CPU0_CPU1_P1P0_DN<11>")
	)
	(segment
		(start 108.031026 -190.175642)
		(end 107.859576 -190.194946)
		(width 0.14732)
		(layer "In4.Cu")
		(net "UPI_CPU0_CPU1_P1P0_DN<11>")
	)
	(segment
		(start 110.375192 -187.04052)
		(end 110.394496 -187.21197)
		(width 0.14732)
		(layer "In4.Cu")
		(net "UPI_CPU0_CPU1_P1P0_DN<11>")
	)
	(segment
		(start 371.702584 -211.779104)
		(end 371.660928 -211.737448)
		(width 0.0889)
		(layer "In4.Cu")
		(net "UPI_CPU0_CPU1_P1P0_DN<11>")
	)
	(segment
		(start 170.072558 -145.55851)
		(end 163.492942 -147.830794)
		(width 0.14732)
		(layer "In4.Cu")
		(net "UPI_CPU0_CPU1_P1P0_DN<11>")
	)
	(segment
		(start 363.08538 -184.804558)
		(end 362.9406 -184.659778)
		(width 0.14732)
		(layer "In4.Cu")
		(net "UPI_CPU0_CPU1_P1P0_DN<11>")
	)
	(segment
		(start 99.707954 -215.762586)
		(end 99.71151 -215.764618)
		(width 0.0889)
		(layer "In4.Cu")
		(net "UPI_CPU0_CPU1_P1P0_DN<11>")
	)
	(segment
		(start 109.424724 -188.427868)
		(end 109.253528 -188.447172)
		(width 0.14732)
		(layer "In4.Cu")
		(net "UPI_CPU0_CPU1_P1P0_DN<11>")
	)
	(segment
		(start 327.946004 -150.034498)
		(end 317.618872 -147.503896)
		(width 0.14732)
		(layer "In4.Cu")
		(net "UPI_CPU0_CPU1_P1P0_DN<11>")
	)
	(segment
		(start 108.284264 -189.662562)
		(end 108.303568 -189.833758)
		(width 0.14732)
		(layer "In4.Cu")
		(net "UPI_CPU0_CPU1_P1P0_DN<11>")
	)
	(segment
		(start 364.176564 -187.352686)
		(end 363.987334 -187.274454)
		(width 0.14732)
		(layer "In4.Cu")
		(net "UPI_CPU0_CPU1_P1P0_DN<11>")
	)
	(segment
		(start 99.560126 -211.991448)
		(end 99.517962 -212.033612)
		(width 0.0889)
		(layer "In4.Cu")
		(net "UPI_CPU0_CPU1_P1P0_DN<11>")
	)
	(segment
		(start 371.484144 -218.421204)
		(end 371.460014 -218.33205)
		(width 0.0889)
		(layer "In4.Cu")
		(net "UPI_CPU0_CPU1_P1P0_DN<11>")
	)
	(segment
		(start 106.808524 -191.513206)
		(end 99.559872 -211.140802)
		(width 0.14732)
		(layer "In4.Cu")
		(net "UPI_CPU0_CPU1_P1P0_DN<11>")
	)
	(segment
		(start 371.70233 -215.43645)
		(end 371.702584 -215.422226)
		(width 0.0889)
		(layer "In4.Cu")
		(net "UPI_CPU0_CPU1_P1P0_DN<11>")
	)
	(segment
		(start 371.660928 -211.412074)
		(end 371.660674 -211.41182)
		(width 0.14732)
		(layer "In4.Cu")
		(net "UPI_CPU0_CPU1_P1P0_DN<11>")
	)
	(segment
		(start 99.617022 -212.77326)
		(end 99.517962 -212.87232)
		(width 0.0889)
		(layer "In4.Cu")
		(net "UPI_CPU0_CPU1_P1P0_DN<11>")
	)
	(segment
		(start 108.556552 -189.321186)
		(end 108.284264 -189.662562)
		(width 0.14732)
		(layer "In4.Cu")
		(net "UPI_CPU0_CPU1_P1P0_DN<11>")
	)
	(arc
		(start 99.705414 -216.739978)
		(mid 99.570481 -216.873332)
		(end 99.518216 -217.0557)
		(width 0.0889)
		(layer "In4.Cu")
		(net "UPI_CPU0_CPU1_P1P0_DN<11>")
	)
	(arc
		(start 99.696524 -215.117426)
		(mid 99.56927 -215.247392)
		(end 99.518216 -215.421972)
		(width 0.0889)
		(layer "In4.Cu")
		(net "UPI_CPU0_CPU1_P1P0_DN<11>")
	)
	(arc
		(start 99.987608 -214.644732)
		(mid 99.906697 -214.91486)
		(end 99.705414 -215.112346)
		(width 0.0889)
		(layer "In4.Cu")
		(net "UPI_CPU0_CPU1_P1P0_DN<11>")
	)
	(arc
		(start 371.993922 -214.941912)
		(mid 372.124836 -214.805552)
		(end 372.172484 -214.622634)
		(width 0.0889)
		(layer "In4.Cu")
		(net "UPI_CPU0_CPU1_P1P0_DN<11>")
	)
	(arc
		(start 371.71757 -213.968838)
		(mid 371.709748 -213.949662)
		(end 371.702584 -213.93023)
		(width 0.0889)
		(layer "In4.Cu")
		(net "UPI_CPU0_CPU1_P1P0_DN<11>")
	)
	(arc
		(start 371.515132 -217.388694)
		(mid 371.650065 -217.25534)
		(end 371.70233 -217.072972)
		(width 0.0889)
		(layer "In4.Cu")
		(net "UPI_CPU0_CPU1_P1P0_DN<11>")
	)
	(arc
		(start 99.702366 -214.093298)
		(mid 99.876329 -214.232062)
		(end 99.987608 -214.424768)
		(width 0.0889)
		(layer "In4.Cu")
		(net "UPI_CPU0_CPU1_P1P0_DN<11>")
	)
	(arc
		(start 99.517962 -215.436704)
		(mid 99.565641 -215.619604)
		(end 99.696524 -215.755982)
		(width 0.0889)
		(layer "In4.Cu")
		(net "UPI_CPU0_CPU1_P1P0_DN<11>")
	)
	(arc
		(start 371.515132 -215.760808)
		(mid 371.650065 -215.627454)
		(end 371.70233 -215.445086)
		(width 0.0889)
		(layer "In4.Cu")
		(net "UPI_CPU0_CPU1_P1P0_DN<11>")
	)
	(arc
		(start 371.460014 -218.33205)
		(mid 371.451573 -218.32565)
		(end 371.44325 -218.319096)
		(width 0.0889)
		(layer "In4.Cu")
		(net "UPI_CPU0_CPU1_P1P0_DN<11>")
	)
	(arc
		(start 371.232684 -217.859864)
		(mid 371.312846 -217.587675)
		(end 371.515132 -217.388694)
		(width 0.0889)
		(layer "In4.Cu")
		(net "UPI_CPU0_CPU1_P1P0_DN<11>")
	)
	(arc
		(start 372.172484 -214.461852)
		(mid 372.097413 -214.34611)
		(end 371.98808 -214.261954)
		(width 0.0889)
		(layer "In4.Cu")
		(net "UPI_CPU0_CPU1_P1P0_DN<11>")
	)
	(arc
		(start 371.70233 -217.0557)
		(mid 371.65006 -216.873335)
		(end 371.515132 -216.739978)
		(width 0.0889)
		(layer "In4.Cu")
		(net "UPI_CPU0_CPU1_P1P0_DN<11>")
	)
	(arc
		(start 99.518216 -217.072972)
		(mid 99.55689 -217.23004)
		(end 99.65817 -217.356182)
		(width 0.0889)
		(layer "In4.Cu")
		(net "UPI_CPU0_CPU1_P1P0_DN<11>")
	)
	(arc
		(start 371.702584 -215.422226)
		(mid 371.781715 -215.14769)
		(end 371.985032 -214.946992)
		(width 0.0889)
		(layer "In4.Cu")
		(net "UPI_CPU0_CPU1_P1P0_DN<11>")
	)
	(arc
		(start 99.518216 -213.893908)
		(mid 99.593221 -214.009367)
		(end 99.702366 -214.093298)
		(width 0.0889)
		(layer "In4.Cu")
		(net "UPI_CPU0_CPU1_P1P0_DN<11>")
	)
	(arc
		(start 371.98808 -214.261954)
		(mid 371.827725 -214.138568)
		(end 371.71757 -213.968838)
		(width 0.0889)
		(layer "In4.Cu")
		(net "UPI_CPU0_CPU1_P1P0_DN<11>")
	)
	(arc
		(start 99.71151 -215.764618)
		(mid 99.988084 -216.25052)
		(end 99.71151 -216.736422)
		(width 0.0889)
		(layer "In4.Cu")
		(net "UPI_CPU0_CPU1_P1P0_DN<11>")
	)
	(arc
		(start 371.232684 -216.231978)
		(mid 371.312846 -215.959789)
		(end 371.515132 -215.760808)
		(width 0.0889)
		(layer "In4.Cu")
		(net "UPI_CPU0_CPU1_P1P0_DN<11>")
	)
	(arc
		(start 99.518216 -215.421972)
		(mid 99.518019 -215.429337)
		(end 99.517962 -215.436704)
		(width 0.0889)
		(layer "In4.Cu")
		(net "UPI_CPU0_CPU1_P1P0_DN<11>")
	)
	(arc
		(start 371.44325 -218.319096)
		(mid 371.291168 -218.129664)
		(end 371.232684 -217.8939)
		(width 0.0889)
		(layer "In4.Cu")
		(net "UPI_CPU0_CPU1_P1P0_DN<11>")
	)
	(arc
		(start 371.515132 -216.739978)
		(mid 371.310797 -216.537373)
		(end 371.232684 -216.260426)
		(width 0.0889)
		(layer "In4.Cu")
		(net "UPI_CPU0_CPU1_P1P0_DN<11>")
	)
	(segment
		(start 372.73738 -218.414346)
		(end 372.73738 -217.87866)
		(width 0.13208)
		(layer "F.Cu")
		(net "UPI_CPU0_CPU1_P1P0_DN<10>")
	)
	(segment
		(start 98.482912 -218.414346)
		(end 98.482912 -217.87866)
		(width 0.13208)
		(layer "F.Cu")
		(net "UPI_CPU0_CPU1_P1P0_DN<10>")
	)
	(segment
		(start 372.73738 -217.87866)
		(end 372.737634 -217.878406)
		(width 0.13208)
		(layer "F.Cu")
		(net "UPI_CPU0_CPU1_P1P0_DN<10>")
	)
	(segment
		(start 98.482912 -217.87866)
		(end 98.483166 -217.878406)
		(width 0.13208)
		(layer "F.Cu")
		(net "UPI_CPU0_CPU1_P1P0_DN<10>")
	)
	(segment
		(start 373.017796 -215.113616)
		(end 373.019574 -215.1126)
		(width 0.0889)
		(layer "In4.Cu")
		(net "UPI_CPU0_CPU1_P1P0_DN<10>")
	)
	(segment
		(start 314.873132 -146.393408)
		(end 276.124162 -144.886426)
		(width 0.14732)
		(layer "In4.Cu")
		(net "UPI_CPU0_CPU1_P1P0_DN<10>")
	)
	(segment
		(start 98.28911 -213.11108)
		(end 98.28911 -213.28634)
		(width 0.0889)
		(layer "In4.Cu")
		(net "UPI_CPU0_CPU1_P1P0_DN<10>")
	)
	(segment
		(start 169.869866 -144.4498)
		(end 162.919156 -146.849592)
		(width 0.14732)
		(layer "In4.Cu")
		(net "UPI_CPU0_CPU1_P1P0_DN<10>")
	)
	(segment
		(start 372.550436 -215.926162)
		(end 372.556532 -215.922606)
		(width 0.0889)
		(layer "In4.Cu")
		(net "UPI_CPU0_CPU1_P1P0_DN<10>")
	)
	(segment
		(start 98.28911 -212.56244)
		(end 98.28911 -212.7377)
		(width 0.0889)
		(layer "In4.Cu")
		(net "UPI_CPU0_CPU1_P1P0_DN<10>")
	)
	(segment
		(start 98.346006 -211.813648)
		(end 98.34626 -211.813902)
		(width 0.14732)
		(layer "In4.Cu")
		(net "UPI_CPU0_CPU1_P1P0_DN<10>")
	)
	(segment
		(start 98.38817 -213.3854)
		(end 98.38817 -213.929468)
		(width 0.0889)
		(layer "In4.Cu")
		(net "UPI_CPU0_CPU1_P1P0_DN<10>")
	)
	(segment
		(start 98.674936 -215.928956)
		(end 98.677984 -215.93048)
		(width 0.0889)
		(layer "In4.Cu")
		(net "UPI_CPU0_CPU1_P1P0_DN<10>")
	)
	(segment
		(start 98.34626 -211.813902)
		(end 98.34626 -211.96935)
		(width 0.14732)
		(layer "In4.Cu")
		(net "UPI_CPU0_CPU1_P1P0_DN<10>")
	)
	(segment
		(start 364.082076 -182.205122)
		(end 363.337602 -180.407818)
		(width 0.14732)
		(layer "In4.Cu")
		(net "UPI_CPU0_CPU1_P1P0_DN<10>")
	)
	(segment
		(start 372.550436 -216.574878)
		(end 372.541546 -216.569798)
		(width 0.0889)
		(layer "In4.Cu")
		(net "UPI_CPU0_CPU1_P1P0_DN<10>")
	)
	(segment
		(start 238.597948 -145.561812)
		(end 169.869866 -144.4498)
		(width 0.14732)
		(layer "In4.Cu")
		(net "UPI_CPU0_CPU1_P1P0_DN<10>")
	)
	(segment
		(start 98.34626 -211.991448)
		(end 98.38817 -212.033358)
		(width 0.0889)
		(layer "In4.Cu")
		(net "UPI_CPU0_CPU1_P1P0_DN<10>")
	)
	(segment
		(start 328.39025 -148.999448)
		(end 317.753492 -146.393408)
		(width 0.14732)
		(layer "In4.Cu")
		(net "UPI_CPU0_CPU1_P1P0_DN<10>")
	)
	(segment
		(start 98.38817 -212.83676)
		(end 98.38817 -213.01202)
		(width 0.0889)
		(layer "In4.Cu")
		(net "UPI_CPU0_CPU1_P1P0_DN<10>")
	)
	(segment
		(start 372.83263 -213.894416)
		(end 372.83263 -211.74583)
		(width 0.0889)
		(layer "In4.Cu")
		(net "UPI_CPU0_CPU1_P1P0_DN<10>")
	)
	(segment
		(start 98.678746 -214.941912)
		(end 98.678238 -214.942166)
		(width 0.0889)
		(layer "In4.Cu")
		(net "UPI_CPU0_CPU1_P1P0_DN<10>")
	)
	(segment
		(start 98.670364 -216.574878)
		(end 98.666554 -216.577164)
		(width 0.0889)
		(layer "In4.Cu")
		(net "UPI_CPU0_CPU1_P1P0_DN<10>")
	)
	(segment
		(start 363.337602 -180.407818)
		(end 362.757466 -179.827682)
		(width 0.14732)
		(layer "In4.Cu")
		(net "UPI_CPU0_CPU1_P1P0_DN<10>")
	)
	(segment
		(start 98.38817 -212.033358)
		(end 98.38817 -212.46338)
		(width 0.0889)
		(layer "In4.Cu")
		(net "UPI_CPU0_CPU1_P1P0_DN<10>")
	)
	(segment
		(start 98.28911 -212.7377)
		(end 98.38817 -212.83676)
		(width 0.0889)
		(layer "In4.Cu")
		(net "UPI_CPU0_CPU1_P1P0_DN<10>")
	)
	(segment
		(start 98.717862 -218.170252)
		(end 98.678238 -218.159584)
		(width 0.0889)
		(layer "In4.Cu")
		(net "UPI_CPU0_CPU1_P1P0_DN<10>")
	)
	(segment
		(start 98.677984 -215.93048)
		(end 98.678238 -215.930734)
		(width 0.0889)
		(layer "In4.Cu")
		(net "UPI_CPU0_CPU1_P1P0_DN<10>")
	)
	(segment
		(start 365.148876 -184.853072)
		(end 364.620048 -184.324244)
		(width 0.14732)
		(layer "In4.Cu")
		(net "UPI_CPU0_CPU1_P1P0_DN<10>")
	)
	(segment
		(start 98.28911 -213.28634)
		(end 98.38817 -213.3854)
		(width 0.0889)
		(layer "In4.Cu")
		(net "UPI_CPU0_CPU1_P1P0_DN<10>")
	)
	(segment
		(start 98.857308 -214.461344)
		(end 98.857308 -214.622634)
		(width 0.0889)
		(layer "In4.Cu")
		(net "UPI_CPU0_CPU1_P1P0_DN<10>")
	)
	(segment
		(start 373.302784 -214.63254)
		(end 373.302784 -214.4268)
		(width 0.0889)
		(layer "In4.Cu")
		(net "UPI_CPU0_CPU1_P1P0_DN<10>")
	)
	(segment
		(start 98.679254 -216.569798)
		(end 98.678238 -216.570306)
		(width 0.0889)
		(layer "In4.Cu")
		(net "UPI_CPU0_CPU1_P1P0_DN<10>")
	)
	(segment
		(start 355.99116 -166.722298)
		(end 328.39025 -148.999448)
		(width 0.14732)
		(layer "In4.Cu")
		(net "UPI_CPU0_CPU1_P1P0_DN<10>")
	)
	(segment
		(start 98.63963 -218.149424)
		(end 98.483166 -217.878406)
		(width 0.0889)
		(layer "In4.Cu")
		(net "UPI_CPU0_CPU1_P1P0_DN<10>")
	)
	(segment
		(start 372.58117 -217.607388)
		(end 372.6053 -217.518234)
		(width 0.0889)
		(layer "In4.Cu")
		(net "UPI_CPU0_CPU1_P1P0_DN<10>")
	)
	(segment
		(start 98.678238 -215.930734)
		(end 98.679254 -215.931242)
		(width 0.0889)
		(layer "In4.Cu")
		(net "UPI_CPU0_CPU1_P1P0_DN<10>")
	)
	(segment
		(start 372.721886 -217.851228)
		(end 372.58117 -217.607388)
		(width 0.0889)
		(layer "In4.Cu")
		(net "UPI_CPU0_CPU1_P1P0_DN<10>")
	)
	(segment
		(start 98.388424 -213.93023)
		(end 98.387916 -213.930484)
		(width 0.0889)
		(layer "In4.Cu")
		(net "UPI_CPU0_CPU1_P1P0_DN<10>")
	)
	(segment
		(start 317.753492 -146.393408)
		(end 314.873132 -146.393408)
		(width 0.14732)
		(layer "In4.Cu")
		(net "UPI_CPU0_CPU1_P1P0_DN<10>")
	)
	(segment
		(start 98.664268 -215.922606)
		(end 98.66757 -215.924384)
		(width 0.0889)
		(layer "In4.Cu")
		(net "UPI_CPU0_CPU1_P1P0_DN<10>")
	)
	(segment
		(start 98.38817 -213.01202)
		(end 98.28911 -213.11108)
		(width 0.0889)
		(layer "In4.Cu")
		(net "UPI_CPU0_CPU1_P1P0_DN<10>")
	)
	(segment
		(start 98.346006 -211.229702)
		(end 98.346006 -211.813648)
		(width 0.14732)
		(layer "In4.Cu")
		(net "UPI_CPU0_CPU1_P1P0_DN<10>")
	)
	(segment
		(start 373.017034 -215.114124)
		(end 373.017796 -215.113616)
		(width 0.0889)
		(layer "In4.Cu")
		(net "UPI_CPU0_CPU1_P1P0_DN<10>")
	)
	(segment
		(start 372.874794 -206.007716)
		(end 366.10671 -189.66815)
		(width 0.14732)
		(layer "In4.Cu")
		(net "UPI_CPU0_CPU1_P1P0_DN<10>")
	)
	(segment
		(start 362.757466 -179.827682)
		(end 358.64292 -169.89425)
		(width 0.14732)
		(layer "In4.Cu")
		(net "UPI_CPU0_CPU1_P1P0_DN<10>")
	)
	(segment
		(start 98.669602 -215.925654)
		(end 98.671126 -215.92667)
		(width 0.0889)
		(layer "In4.Cu")
		(net "UPI_CPU0_CPU1_P1P0_DN<10>")
	)
	(segment
		(start 372.541546 -215.931242)
		(end 372.550436 -215.926162)
		(width 0.0889)
		(layer "In4.Cu")
		(net "UPI_CPU0_CPU1_P1P0_DN<10>")
	)
	(segment
		(start 105.96245 -190.604394)
		(end 98.346006 -211.229702)
		(width 0.14732)
		(layer "In4.Cu")
		(net "UPI_CPU0_CPU1_P1P0_DN<10>")
	)
	(segment
		(start 373.019574 -215.1126)
		(end 373.020336 -215.112092)
		(width 0.0889)
		(layer "In4.Cu")
		(net "UPI_CPU0_CPU1_P1P0_DN<10>")
	)
	(segment
		(start 358.64292 -169.89425)
		(end 355.99116 -166.722298)
		(width 0.14732)
		(layer "In4.Cu")
		(net "UPI_CPU0_CPU1_P1P0_DN<10>")
	)
	(segment
		(start 373.011446 -215.117172)
		(end 373.012208 -215.116664)
		(width 0.0889)
		(layer "In4.Cu")
		(net "UPI_CPU0_CPU1_P1P0_DN<10>")
	)
	(segment
		(start 373.302784 -214.4268)
		(end 373.30253 -214.426546)
		(width 0.0889)
		(layer "In4.Cu")
		(net "UPI_CPU0_CPU1_P1P0_DN<10>")
	)
	(segment
		(start 98.678238 -218.159584)
		(end 98.63963 -218.149424)
		(width 0.0889)
		(layer "In4.Cu")
		(net "UPI_CPU0_CPU1_P1P0_DN<10>")
	)
	(segment
		(start 373.012208 -215.116664)
		(end 373.017034 -215.114124)
		(width 0.0889)
		(layer "In4.Cu")
		(net "UPI_CPU0_CPU1_P1P0_DN<10>")
	)
	(segment
		(start 98.671126 -215.92667)
		(end 98.674936 -215.928956)
		(width 0.0889)
		(layer "In4.Cu")
		(net "UPI_CPU0_CPU1_P1P0_DN<10>")
	)
	(segment
		(start 98.670364 -217.554048)
		(end 98.678238 -217.55862)
		(width 0.0889)
		(layer "In4.Cu")
		(net "UPI_CPU0_CPU1_P1P0_DN<10>")
	)
	(segment
		(start 364.620048 -184.324244)
		(end 364.082076 -183.025542)
		(width 0.14732)
		(layer "In4.Cu")
		(net "UPI_CPU0_CPU1_P1P0_DN<10>")
	)
	(segment
		(start 98.666554 -216.577164)
		(end 98.658172 -216.58199)
		(width 0.0889)
		(layer "In4.Cu")
		(net "UPI_CPU0_CPU1_P1P0_DN<10>")
	)
	(segment
		(start 372.874794 -211.69249)
		(end 372.874794 -206.007716)
		(width 0.14732)
		(layer "In4.Cu")
		(net "UPI_CPU0_CPU1_P1P0_DN<10>")
	)
	(segment
		(start 98.678238 -216.570306)
		(end 98.670364 -216.574878)
		(width 0.0889)
		(layer "In4.Cu")
		(net "UPI_CPU0_CPU1_P1P0_DN<10>")
	)
	(segment
		(start 276.124162 -144.886426)
		(end 238.597948 -145.561812)
		(width 0.14732)
		(layer "In4.Cu")
		(net "UPI_CPU0_CPU1_P1P0_DN<10>")
	)
	(segment
		(start 98.387662 -217.064336)
		(end 98.387662 -217.071956)
		(width 0.0889)
		(layer "In4.Cu")
		(net "UPI_CPU0_CPU1_P1P0_DN<10>")
	)
	(segment
		(start 98.678238 -214.942166)
		(end 98.669856 -214.946992)
		(width 0.0889)
		(layer "In4.Cu")
		(net "UPI_CPU0_CPU1_P1P0_DN<10>")
	)
	(segment
		(start 98.66757 -215.924384)
		(end 98.669602 -215.925654)
		(width 0.0889)
		(layer "In4.Cu")
		(net "UPI_CPU0_CPU1_P1P0_DN<10>")
	)
	(segment
		(start 372.737634 -217.878406)
		(end 372.721886 -217.851228)
		(width 0.0889)
		(layer "In4.Cu")
		(net "UPI_CPU0_CPU1_P1P0_DN<10>")
	)
	(segment
		(start 372.83263 -211.74583)
		(end 372.874794 -211.703666)
		(width 0.0889)
		(layer "In4.Cu")
		(net "UPI_CPU0_CPU1_P1P0_DN<10>")
	)
	(segment
		(start 98.38817 -212.46338)
		(end 98.28911 -212.56244)
		(width 0.0889)
		(layer "In4.Cu")
		(net "UPI_CPU0_CPU1_P1P0_DN<10>")
	)
	(segment
		(start 98.678238 -217.55862)
		(end 98.679254 -217.559128)
		(width 0.0889)
		(layer "In4.Cu")
		(net "UPI_CPU0_CPU1_P1P0_DN<10>")
	)
	(segment
		(start 364.082076 -183.025542)
		(end 364.082076 -182.205122)
		(width 0.14732)
		(layer "In4.Cu")
		(net "UPI_CPU0_CPU1_P1P0_DN<10>")
	)
	(segment
		(start 109.697266 -185.921142)
		(end 105.96245 -190.604394)
		(width 0.14732)
		(layer "In4.Cu")
		(net "UPI_CPU0_CPU1_P1P0_DN<10>")
	)
	(segment
		(start 372.832884 -217.07856)
		(end 372.832884 -217.064336)
		(width 0.0889)
		(layer "In4.Cu")
		(net "UPI_CPU0_CPU1_P1P0_DN<10>")
	)
	(segment
		(start 98.387662 -215.414606)
		(end 98.387662 -215.436704)
		(width 0.0889)
		(layer "In4.Cu")
		(net "UPI_CPU0_CPU1_P1P0_DN<10>")
	)
	(segment
		(start 372.556532 -216.578434)
		(end 372.550436 -216.574878)
		(width 0.0889)
		(layer "In4.Cu")
		(net "UPI_CPU0_CPU1_P1P0_DN<10>")
	)
	(segment
		(start 98.34626 -211.96935)
		(end 98.34626 -211.991448)
		(width 0.0889)
		(layer "In4.Cu")
		(net "UPI_CPU0_CPU1_P1P0_DN<10>")
	)
	(segment
		(start 129.096516 -167.661082)
		(end 109.697266 -185.921142)
		(width 0.14732)
		(layer "In4.Cu")
		(net "UPI_CPU0_CPU1_P1P0_DN<10>")
	)
	(segment
		(start 366.10671 -189.66815)
		(end 365.148876 -184.853072)
		(width 0.14732)
		(layer "In4.Cu")
		(net "UPI_CPU0_CPU1_P1P0_DN<10>")
	)
	(segment
		(start 372.874794 -211.703666)
		(end 372.874794 -211.69249)
		(width 0.0889)
		(layer "In4.Cu")
		(net "UPI_CPU0_CPU1_P1P0_DN<10>")
	)
	(segment
		(start 162.919156 -146.849592)
		(end 129.096516 -167.661082)
		(width 0.14732)
		(layer "In4.Cu")
		(net "UPI_CPU0_CPU1_P1P0_DN<10>")
	)
	(arc
		(start 373.30253 -214.426546)
		(mid 373.295259 -214.4066)
		(end 373.28729 -214.386922)
		(width 0.0889)
		(layer "In4.Cu")
		(net "UPI_CPU0_CPU1_P1P0_DN<10>")
	)
	(arc
		(start 373.28729 -214.386922)
		(mid 373.177224 -214.217013)
		(end 373.01678 -214.093552)
		(width 0.0889)
		(layer "In4.Cu")
		(net "UPI_CPU0_CPU1_P1P0_DN<10>")
	)
	(arc
		(start 98.38817 -213.929468)
		(mid 98.388297 -213.929849)
		(end 98.388424 -213.93023)
		(width 0.0889)
		(layer "In4.Cu")
		(net "UPI_CPU0_CPU1_P1P0_DN<10>")
	)
	(arc
		(start 372.556532 -215.922606)
		(mid 372.759008 -215.716083)
		(end 372.832884 -215.43645)
		(width 0.0889)
		(layer "In4.Cu")
		(net "UPI_CPU0_CPU1_P1P0_DN<10>")
	)
	(arc
		(start 98.658172 -216.58199)
		(mid 98.459944 -216.787838)
		(end 98.387662 -217.064336)
		(width 0.0889)
		(layer "In4.Cu")
		(net "UPI_CPU0_CPU1_P1P0_DN<10>")
	)
	(arc
		(start 373.020336 -215.112092)
		(mid 373.224671 -214.909487)
		(end 373.302784 -214.63254)
		(width 0.0889)
		(layer "In4.Cu")
		(net "UPI_CPU0_CPU1_P1P0_DN<10>")
	)
	(arc
		(start 98.857308 -214.622634)
		(mid 98.809629 -214.805534)
		(end 98.678746 -214.941912)
		(width 0.0889)
		(layer "In4.Cu")
		(net "UPI_CPU0_CPU1_P1P0_DN<10>")
	)
	(arc
		(start 372.6053 -217.518234)
		(mid 372.613743 -217.511836)
		(end 372.622064 -217.50528)
		(width 0.0889)
		(layer "In4.Cu")
		(net "UPI_CPU0_CPU1_P1P0_DN<10>")
	)
	(arc
		(start 98.387662 -217.071956)
		(mid 98.465291 -217.350369)
		(end 98.670364 -217.554048)
		(width 0.0889)
		(layer "In4.Cu")
		(net "UPI_CPU0_CPU1_P1P0_DN<10>")
	)
	(arc
		(start 98.387662 -215.436704)
		(mid 98.461653 -215.71627)
		(end 98.664268 -215.922606)
		(width 0.0889)
		(layer "In4.Cu")
		(net "UPI_CPU0_CPU1_P1P0_DN<10>")
	)
	(arc
		(start 98.387916 -213.930484)
		(mid 98.395201 -213.950046)
		(end 98.403156 -213.969346)
		(width 0.0889)
		(layer "In4.Cu")
		(net "UPI_CPU0_CPU1_P1P0_DN<10>")
	)
	(arc
		(start 372.541546 -216.569798)
		(mid 372.36307 -216.25052)
		(end 372.541546 -215.931242)
		(width 0.0889)
		(layer "In4.Cu")
		(net "UPI_CPU0_CPU1_P1P0_DN<10>")
	)
	(arc
		(start 98.679254 -217.559128)
		(mid 98.810168 -217.695488)
		(end 98.857816 -217.878406)
		(width 0.0889)
		(layer "In4.Cu")
		(net "UPI_CPU0_CPU1_P1P0_DN<10>")
	)
	(arc
		(start 372.832884 -215.43645)
		(mid 372.880563 -215.25355)
		(end 373.011446 -215.117172)
		(width 0.0889)
		(layer "In4.Cu")
		(net "UPI_CPU0_CPU1_P1P0_DN<10>")
	)
	(arc
		(start 372.832884 -217.064336)
		(mid 372.758968 -216.784834)
		(end 372.556532 -216.578434)
		(width 0.0889)
		(layer "In4.Cu")
		(net "UPI_CPU0_CPU1_P1P0_DN<10>")
	)
	(arc
		(start 373.01678 -214.093552)
		(mid 372.907677 -214.009726)
		(end 372.83263 -213.894416)
		(width 0.0889)
		(layer "In4.Cu")
		(net "UPI_CPU0_CPU1_P1P0_DN<10>")
	)
	(arc
		(start 98.669856 -214.946992)
		(mid 98.468574 -215.144479)
		(end 98.387662 -215.414606)
		(width 0.0889)
		(layer "In4.Cu")
		(net "UPI_CPU0_CPU1_P1P0_DN<10>")
	)
	(arc
		(start 98.403156 -213.969346)
		(mid 98.51315 -214.138715)
		(end 98.673158 -214.261954)
		(width 0.0889)
		(layer "In4.Cu")
		(net "UPI_CPU0_CPU1_P1P0_DN<10>")
	)
	(arc
		(start 98.673158 -214.261954)
		(mid 98.782305 -214.345882)
		(end 98.857308 -214.461344)
		(width 0.0889)
		(layer "In4.Cu")
		(net "UPI_CPU0_CPU1_P1P0_DN<10>")
	)
	(arc
		(start 98.857816 -217.878406)
		(mid 98.820956 -218.040203)
		(end 98.717862 -218.170252)
		(width 0.0889)
		(layer "In4.Cu")
		(net "UPI_CPU0_CPU1_P1P0_DN<10>")
	)
	(arc
		(start 372.622064 -217.50528)
		(mid 372.774571 -217.315182)
		(end 372.832884 -217.07856)
		(width 0.0889)
		(layer "In4.Cu")
		(net "UPI_CPU0_CPU1_P1P0_DN<10>")
	)
	(arc
		(start 98.679254 -215.931242)
		(mid 98.857851 -216.25052)
		(end 98.679254 -216.569798)
		(width 0.0889)
		(layer "In4.Cu")
		(net "UPI_CPU0_CPU1_P1P0_DN<10>")
	)
	(segment
		(start 89.084912 -218.414346)
		(end 89.084912 -217.87866)
		(width 0.13208)
		(layer "F.Cu")
		(net "UPI_CPU0_CPU1_P1P0_DN<0>")
	)
	(segment
		(start 382.135634 -218.414346)
		(end 382.135634 -217.878406)
		(width 0.13208)
		(layer "F.Cu")
		(net "UPI_CPU0_CPU1_P1P0_DN<0>")
	)
	(segment
		(start 89.084912 -217.87866)
		(end 89.085166 -217.878406)
		(width 0.13208)
		(layer "F.Cu")
		(net "UPI_CPU0_CPU1_P1P0_DN<0>")
	)
	(segment
		(start 89.272872 -216.57437)
		(end 89.27211 -216.574878)
		(width 0.0889)
		(layer "In4.Cu")
		(net "UPI_CPU0_CPU1_P1P0_DN<0>")
	)
	(segment
		(start 383.282952 -211.694522)
		(end 383.282698 -211.694268)
		(width 0.14732)
		(layer "In4.Cu")
		(net "UPI_CPU0_CPU1_P1P0_DN<0>")
	)
	(segment
		(start 383.282952 -211.93125)
		(end 383.282952 -211.694522)
		(width 0.14732)
		(layer "In4.Cu")
		(net "UPI_CPU0_CPU1_P1P0_DN<0>")
	)
	(segment
		(start 88.989662 -215.414606)
		(end 88.989662 -215.452198)
		(width 0.0889)
		(layer "In4.Cu")
		(net "UPI_CPU0_CPU1_P1P0_DN<0>")
	)
	(segment
		(start 88.909906 -211.630768)
		(end 88.91016 -211.631022)
		(width 0.14732)
		(layer "In4.Cu")
		(net "UPI_CPU0_CPU1_P1P0_DN<0>")
	)
	(segment
		(start 381.948436 -216.574878)
		(end 381.939546 -216.569798)
		(width 0.0889)
		(layer "In4.Cu")
		(net "UPI_CPU0_CPU1_P1P0_DN<0>")
	)
	(segment
		(start 88.989662 -217.064336)
		(end 88.989662 -217.071956)
		(width 0.0889)
		(layer "In4.Cu")
		(net "UPI_CPU0_CPU1_P1P0_DN<0>")
	)
	(segment
		(start 382.119886 -217.851228)
		(end 381.97917 -217.607388)
		(width 0.0889)
		(layer "In4.Cu")
		(net "UPI_CPU0_CPU1_P1P0_DN<0>")
	)
	(segment
		(start 89.274904 -216.5731)
		(end 89.272872 -216.57437)
		(width 0.0889)
		(layer "In4.Cu")
		(net "UPI_CPU0_CPU1_P1P0_DN<0>")
	)
	(segment
		(start 159.50057 -139.011152)
		(end 122.81535 -161.576258)
		(width 0.14732)
		(layer "In4.Cu")
		(net "UPI_CPU0_CPU1_P1P0_DN<0>")
	)
	(segment
		(start 88.91016 -211.78139)
		(end 88.91016 -211.803488)
		(width 0.0889)
		(layer "In4.Cu")
		(net "UPI_CPU0_CPU1_P1P0_DN<0>")
	)
	(segment
		(start 381.954532 -216.578434)
		(end 381.948436 -216.574878)
		(width 0.0889)
		(layer "In4.Cu")
		(net "UPI_CPU0_CPU1_P1P0_DN<0>")
	)
	(segment
		(start 383.817622 -192.323974)
		(end 383.315972 -189.707266)
		(width 0.14732)
		(layer "In4.Cu")
		(net "UPI_CPU0_CPU1_P1P0_DN<0>")
	)
	(segment
		(start 88.85301 -213.38286)
		(end 88.85301 -213.55812)
		(width 0.0889)
		(layer "In4.Cu")
		(net "UPI_CPU0_CPU1_P1P0_DN<0>")
	)
	(segment
		(start 270.59636 -136.068054)
		(end 238.601504 -136.652254)
		(width 0.14732)
		(layer "In4.Cu")
		(net "UPI_CPU0_CPU1_P1P0_DN<0>")
	)
	(segment
		(start 88.95207 -211.845398)
		(end 88.95207 -212.60816)
		(width 0.0889)
		(layer "In4.Cu")
		(net "UPI_CPU0_CPU1_P1P0_DN<0>")
	)
	(segment
		(start 89.280746 -214.941912)
		(end 89.271856 -214.946992)
		(width 0.0889)
		(layer "In4.Cu")
		(net "UPI_CPU0_CPU1_P1P0_DN<0>")
	)
	(segment
		(start 89.271856 -215.926162)
		(end 89.286842 -215.934798)
		(width 0.0889)
		(layer "In4.Cu")
		(net "UPI_CPU0_CPU1_P1P0_DN<0>")
	)
	(segment
		(start 101.84892 -181.291484)
		(end 97.86112 -186.25439)
		(width 0.14732)
		(layer "In4.Cu")
		(net "UPI_CPU0_CPU1_P1P0_DN<0>")
	)
	(segment
		(start 95.668338 -192.085722)
		(end 85.396832 -204.291946)
		(width 0.14732)
		(layer "In4.Cu")
		(net "UPI_CPU0_CPU1_P1P0_DN<0>")
	)
	(segment
		(start 88.95207 -213.2838)
		(end 88.85301 -213.38286)
		(width 0.0889)
		(layer "In4.Cu")
		(net "UPI_CPU0_CPU1_P1P0_DN<0>")
	)
	(segment
		(start 85.396832 -204.291946)
		(end 85.10524 -205.899512)
		(width 0.14732)
		(layer "In4.Cu")
		(net "UPI_CPU0_CPU1_P1P0_DN<0>")
	)
	(segment
		(start 373.290084 -167.593518)
		(end 372.784624 -166.725854)
		(width 0.14732)
		(layer "In4.Cu")
		(net "UPI_CPU0_CPU1_P1P0_DN<0>")
	)
	(segment
		(start 88.95207 -212.60816)
		(end 88.85301 -212.70722)
		(width 0.0889)
		(layer "In4.Cu")
		(net "UPI_CPU0_CPU1_P1P0_DN<0>")
	)
	(segment
		(start 88.95207 -212.98154)
		(end 88.95207 -213.2838)
		(width 0.0889)
		(layer "In4.Cu")
		(net "UPI_CPU0_CPU1_P1P0_DN<0>")
	)
	(segment
		(start 88.85301 -213.55812)
		(end 88.95207 -213.65718)
		(width 0.0889)
		(layer "In4.Cu")
		(net "UPI_CPU0_CPU1_P1P0_DN<0>")
	)
	(segment
		(start 88.95207 -213.65718)
		(end 88.95207 -213.919562)
		(width 0.0889)
		(layer "In4.Cu")
		(net "UPI_CPU0_CPU1_P1P0_DN<0>")
	)
	(segment
		(start 89.27211 -216.574878)
		(end 89.266014 -216.578434)
		(width 0.0889)
		(layer "In4.Cu")
		(net "UPI_CPU0_CPU1_P1P0_DN<0>")
	)
	(segment
		(start 89.272364 -217.554048)
		(end 89.281254 -217.559128)
		(width 0.0889)
		(layer "In4.Cu")
		(net "UPI_CPU0_CPU1_P1P0_DN<0>")
	)
	(segment
		(start 382.135634 -217.878406)
		(end 382.119886 -217.851228)
		(width 0.0889)
		(layer "In4.Cu")
		(net "UPI_CPU0_CPU1_P1P0_DN<0>")
	)
	(segment
		(start 386.633974 -202.283822)
		(end 383.817622 -192.323974)
		(width 0.14732)
		(layer "In4.Cu")
		(net "UPI_CPU0_CPU1_P1P0_DN<0>")
	)
	(segment
		(start 361.94492 -160.53689)
		(end 331.79893 -141.177772)
		(width 0.14732)
		(layer "In4.Cu")
		(net "UPI_CPU0_CPU1_P1P0_DN<0>")
	)
	(segment
		(start 88.85301 -212.88248)
		(end 88.95207 -212.98154)
		(width 0.0889)
		(layer "In4.Cu")
		(net "UPI_CPU0_CPU1_P1P0_DN<0>")
	)
	(segment
		(start 88.85301 -212.70722)
		(end 88.85301 -212.88248)
		(width 0.0889)
		(layer "In4.Cu")
		(net "UPI_CPU0_CPU1_P1P0_DN<0>")
	)
	(segment
		(start 88.909906 -211.493354)
		(end 88.909906 -211.630768)
		(width 0.14732)
		(layer "In4.Cu")
		(net "UPI_CPU0_CPU1_P1P0_DN<0>")
	)
	(segment
		(start 169.696384 -135.520684)
		(end 159.50057 -139.011152)
		(width 0.14732)
		(layer "In4.Cu")
		(net "UPI_CPU0_CPU1_P1P0_DN<0>")
	)
	(segment
		(start 377.262644 -170.856402)
		(end 376.7582 -170.064176)
		(width 0.14732)
		(layer "In4.Cu")
		(net "UPI_CPU0_CPU1_P1P0_DN<0>")
	)
	(segment
		(start 316.272926 -137.988548)
		(end 270.59636 -136.068054)
		(width 0.14732)
		(layer "In4.Cu")
		(net "UPI_CPU0_CPU1_P1P0_DN<0>")
	)
	(segment
		(start 372.683532 -165.88359)
		(end 372.262908 -165.323774)
		(width 0.14732)
		(layer "In4.Cu")
		(net "UPI_CPU0_CPU1_P1P0_DN<0>")
	)
	(segment
		(start 382.322832 -215.926162)
		(end 382.337564 -215.934798)
		(width 0.0889)
		(layer "In4.Cu")
		(net "UPI_CPU0_CPU1_P1P0_DN<0>")
	)
	(segment
		(start 88.95207 -213.919562)
		(end 89.459562 -214.427054)
		(width 0.0889)
		(layer "In4.Cu")
		(net "UPI_CPU0_CPU1_P1P0_DN<0>")
	)
	(segment
		(start 85.14334 -207.089248)
		(end 85.696806 -208.280508)
		(width 0.14732)
		(layer "In4.Cu")
		(net "UPI_CPU0_CPU1_P1P0_DN<0>")
	)
	(segment
		(start 372.784624 -166.725854)
		(end 372.683532 -165.88359)
		(width 0.14732)
		(layer "In4.Cu")
		(net "UPI_CPU0_CPU1_P1P0_DN<0>")
	)
	(segment
		(start 382.700784 -214.202772)
		(end 383.240788 -213.662768)
		(width 0.0889)
		(layer "In4.Cu")
		(net "UPI_CPU0_CPU1_P1P0_DN<0>")
	)
	(segment
		(start 382.230884 -217.07856)
		(end 382.230884 -217.064336)
		(width 0.0889)
		(layer "In4.Cu")
		(net "UPI_CPU0_CPU1_P1P0_DN<0>")
	)
	(segment
		(start 376.7582 -170.064176)
		(end 373.290084 -167.593518)
		(width 0.14732)
		(layer "In4.Cu")
		(net "UPI_CPU0_CPU1_P1P0_DN<0>")
	)
	(segment
		(start 89.24163 -218.149424)
		(end 89.085166 -217.878406)
		(width 0.0889)
		(layer "In4.Cu")
		(net "UPI_CPU0_CPU1_P1P0_DN<0>")
	)
	(segment
		(start 383.240788 -211.995512)
		(end 383.282952 -211.953348)
		(width 0.0889)
		(layer "In4.Cu")
		(net "UPI_CPU0_CPU1_P1P0_DN<0>")
	)
	(segment
		(start 383.282698 -210.94573)
		(end 385.886452 -208.341976)
		(width 0.14732)
		(layer "In4.Cu")
		(net "UPI_CPU0_CPU1_P1P0_DN<0>")
	)
	(segment
		(start 318.77127 -137.988548)
		(end 316.272926 -137.988548)
		(width 0.14732)
		(layer "In4.Cu")
		(net "UPI_CPU0_CPU1_P1P0_DN<0>")
	)
	(segment
		(start 85.10524 -205.899512)
		(end 85.14334 -207.089248)
		(width 0.14732)
		(layer "In4.Cu")
		(net "UPI_CPU0_CPU1_P1P0_DN<0>")
	)
	(segment
		(start 89.284556 -216.567766)
		(end 89.274904 -216.5731)
		(width 0.0889)
		(layer "In4.Cu")
		(net "UPI_CPU0_CPU1_P1P0_DN<0>")
	)
	(segment
		(start 85.696806 -208.280508)
		(end 88.909906 -211.493354)
		(width 0.14732)
		(layer "In4.Cu")
		(net "UPI_CPU0_CPU1_P1P0_DN<0>")
	)
	(segment
		(start 97.86112 -186.25439)
		(end 95.668338 -192.085722)
		(width 0.14732)
		(layer "In4.Cu")
		(net "UPI_CPU0_CPU1_P1P0_DN<0>")
	)
	(segment
		(start 381.939546 -215.931242)
		(end 381.948436 -215.926162)
		(width 0.0889)
		(layer "In4.Cu")
		(net "UPI_CPU0_CPU1_P1P0_DN<0>")
	)
	(segment
		(start 386.633974 -206.53756)
		(end 386.633974 -202.283822)
		(width 0.14732)
		(layer "In4.Cu")
		(net "UPI_CPU0_CPU1_P1P0_DN<0>")
	)
	(segment
		(start 372.262908 -165.323774)
		(end 361.94492 -160.53689)
		(width 0.14732)
		(layer "In4.Cu")
		(net "UPI_CPU0_CPU1_P1P0_DN<0>")
	)
	(segment
		(start 383.282952 -211.953348)
		(end 383.282952 -211.93125)
		(width 0.0889)
		(layer "In4.Cu")
		(net "UPI_CPU0_CPU1_P1P0_DN<0>")
	)
	(segment
		(start 381.97917 -217.607388)
		(end 382.0033 -217.518234)
		(width 0.0889)
		(layer "In4.Cu")
		(net "UPI_CPU0_CPU1_P1P0_DN<0>")
	)
	(segment
		(start 383.240788 -213.662768)
		(end 383.240788 -211.995512)
		(width 0.0889)
		(layer "In4.Cu")
		(net "UPI_CPU0_CPU1_P1P0_DN<0>")
	)
	(segment
		(start 383.17043 -215.452198)
		(end 383.17043 -215.23833)
		(width 0.0889)
		(layer "In4.Cu")
		(net "UPI_CPU0_CPU1_P1P0_DN<0>")
	)
	(segment
		(start 122.81535 -161.576258)
		(end 101.84892 -181.291484)
		(width 0.14732)
		(layer "In4.Cu")
		(net "UPI_CPU0_CPU1_P1P0_DN<0>")
	)
	(segment
		(start 331.79893 -141.177772)
		(end 318.77127 -137.988548)
		(width 0.14732)
		(layer "In4.Cu")
		(net "UPI_CPU0_CPU1_P1P0_DN<0>")
	)
	(segment
		(start 88.91016 -211.631022)
		(end 88.91016 -211.78139)
		(width 0.14732)
		(layer "In4.Cu")
		(net "UPI_CPU0_CPU1_P1P0_DN<0>")
	)
	(segment
		(start 88.91016 -211.803488)
		(end 88.95207 -211.845398)
		(width 0.0889)
		(layer "In4.Cu")
		(net "UPI_CPU0_CPU1_P1P0_DN<0>")
	)
	(segment
		(start 89.319862 -218.170252)
		(end 89.24163 -218.149424)
		(width 0.0889)
		(layer "In4.Cu")
		(net "UPI_CPU0_CPU1_P1P0_DN<0>")
	)
	(segment
		(start 385.886452 -208.341976)
		(end 386.633974 -206.53756)
		(width 0.14732)
		(layer "In4.Cu")
		(net "UPI_CPU0_CPU1_P1P0_DN<0>")
	)
	(segment
		(start 382.700784 -214.707978)
		(end 382.700784 -214.202772)
		(width 0.0889)
		(layer "In4.Cu")
		(net "UPI_CPU0_CPU1_P1P0_DN<0>")
	)
	(segment
		(start 383.282698 -211.694268)
		(end 383.282698 -210.94573)
		(width 0.14732)
		(layer "In4.Cu")
		(net "UPI_CPU0_CPU1_P1P0_DN<0>")
	)
	(segment
		(start 383.315972 -189.707266)
		(end 382.514094 -188.644276)
		(width 0.14732)
		(layer "In4.Cu")
		(net "UPI_CPU0_CPU1_P1P0_DN<0>")
	)
	(segment
		(start 89.459562 -214.427054)
		(end 89.459562 -214.640414)
		(width 0.0889)
		(layer "In4.Cu")
		(net "UPI_CPU0_CPU1_P1P0_DN<0>")
	)
	(segment
		(start 89.281 -214.94242)
		(end 89.280746 -214.941912)
		(width 0.0889)
		(layer "In4.Cu")
		(net "UPI_CPU0_CPU1_P1P0_DN<0>")
	)
	(segment
		(start 238.601504 -136.652254)
		(end 169.696384 -135.520684)
		(width 0.14732)
		(layer "In4.Cu")
		(net "UPI_CPU0_CPU1_P1P0_DN<0>")
	)
	(segment
		(start 382.514094 -188.644276)
		(end 377.262644 -170.856402)
		(width 0.14732)
		(layer "In4.Cu")
		(net "UPI_CPU0_CPU1_P1P0_DN<0>")
	)
	(arc
		(start 89.286842 -215.934798)
		(mid 89.413565 -216.070579)
		(end 89.459562 -216.25052)
		(width 0.0889)
		(layer "In4.Cu")
		(net "UPI_CPU0_CPU1_P1P0_DN<0>")
	)
	(arc
		(start 382.230884 -217.064336)
		(mid 382.156968 -216.784834)
		(end 381.954532 -216.578434)
		(width 0.0889)
		(layer "In4.Cu")
		(net "UPI_CPU0_CPU1_P1P0_DN<0>")
	)
	(arc
		(start 383.17043 -215.23833)
		(mid 383.05901 -215.045711)
		(end 382.884934 -214.907114)
		(width 0.0889)
		(layer "In4.Cu")
		(net "UPI_CPU0_CPU1_P1P0_DN<0>")
	)
	(arc
		(start 89.266014 -216.578434)
		(mid 89.063601 -216.784847)
		(end 88.989662 -217.064336)
		(width 0.0889)
		(layer "In4.Cu")
		(net "UPI_CPU0_CPU1_P1P0_DN<0>")
	)
	(arc
		(start 382.337564 -215.934798)
		(mid 382.614039 -216.002118)
		(end 382.888236 -215.926162)
		(width 0.0889)
		(layer "In4.Cu")
		(net "UPI_CPU0_CPU1_P1P0_DN<0>")
	)
	(arc
		(start 89.271856 -214.946992)
		(mid 89.070574 -215.144479)
		(end 88.989662 -215.414606)
		(width 0.0889)
		(layer "In4.Cu")
		(net "UPI_CPU0_CPU1_P1P0_DN<0>")
	)
	(arc
		(start 381.948436 -215.926162)
		(mid 382.135634 -215.876019)
		(end 382.322832 -215.926162)
		(width 0.0889)
		(layer "In4.Cu")
		(net "UPI_CPU0_CPU1_P1P0_DN<0>")
	)
	(arc
		(start 381.939546 -216.569798)
		(mid 381.76107 -216.25052)
		(end 381.939546 -215.931242)
		(width 0.0889)
		(layer "In4.Cu")
		(net "UPI_CPU0_CPU1_P1P0_DN<0>")
	)
	(arc
		(start 89.459562 -216.25052)
		(mid 89.412917 -216.43169)
		(end 89.284556 -216.567766)
		(width 0.0889)
		(layer "In4.Cu")
		(net "UPI_CPU0_CPU1_P1P0_DN<0>")
	)
	(arc
		(start 88.989662 -217.071956)
		(mid 89.067291 -217.350369)
		(end 89.272364 -217.554048)
		(width 0.0889)
		(layer "In4.Cu")
		(net "UPI_CPU0_CPU1_P1P0_DN<0>")
	)
	(arc
		(start 382.888236 -215.926162)
		(mid 383.091059 -215.725931)
		(end 383.17043 -215.452198)
		(width 0.0889)
		(layer "In4.Cu")
		(net "UPI_CPU0_CPU1_P1P0_DN<0>")
	)
	(arc
		(start 89.459816 -217.878406)
		(mid 89.422956 -218.040203)
		(end 89.319862 -218.170252)
		(width 0.0889)
		(layer "In4.Cu")
		(net "UPI_CPU0_CPU1_P1P0_DN<0>")
	)
	(arc
		(start 88.989662 -215.452198)
		(mid 89.069032 -215.725932)
		(end 89.271856 -215.926162)
		(width 0.0889)
		(layer "In4.Cu")
		(net "UPI_CPU0_CPU1_P1P0_DN<0>")
	)
	(arc
		(start 89.459562 -214.640414)
		(mid 89.407773 -214.813595)
		(end 89.281 -214.94242)
		(width 0.0889)
		(layer "In4.Cu")
		(net "UPI_CPU0_CPU1_P1P0_DN<0>")
	)
	(arc
		(start 382.020064 -217.50528)
		(mid 382.172571 -217.315182)
		(end 382.230884 -217.07856)
		(width 0.0889)
		(layer "In4.Cu")
		(net "UPI_CPU0_CPU1_P1P0_DN<0>")
	)
	(arc
		(start 382.0033 -217.518234)
		(mid 382.011743 -217.511836)
		(end 382.020064 -217.50528)
		(width 0.0889)
		(layer "In4.Cu")
		(net "UPI_CPU0_CPU1_P1P0_DN<0>")
	)
	(arc
		(start 382.884934 -214.907114)
		(mid 382.775809 -214.823311)
		(end 382.700784 -214.707978)
		(width 0.0889)
		(layer "In4.Cu")
		(net "UPI_CPU0_CPU1_P1P0_DN<0>")
	)
	(arc
		(start 89.281254 -217.559128)
		(mid 89.412168 -217.695488)
		(end 89.459816 -217.878406)
		(width 0.0889)
		(layer "In4.Cu")
		(net "UPI_CPU0_CPU1_P1P0_DN<0>")
	)
	(segment
		(start 126.676912 -215.158574)
		(end 126.676912 -214.622888)
		(width 0.13208)
		(layer "F.Cu")
		(net "UPI_CPU0_CPU1_P0P1_DP<9>")
	)
	(segment
		(start 345.013534 -215.436958)
		(end 345.01328 -215.436704)
		(width 0.13208)
		(layer "F.Cu")
		(net "UPI_CPU0_CPU1_P0P1_DP<9>")
	)
	(segment
		(start 345.013534 -215.972644)
		(end 345.013534 -215.436958)
		(width 0.13208)
		(layer "F.Cu")
		(net "UPI_CPU0_CPU1_P0P1_DP<9>")
	)
	(segment
		(start 126.676912 -214.622888)
		(end 126.676658 -214.622634)
		(width 0.13208)
		(layer "F.Cu")
		(net "UPI_CPU0_CPU1_P0P1_DP<9>")
	)
	(segment
		(start 345.169744 -215.165686)
		(end 345.145614 -215.076532)
		(width 0.0889)
		(layer "In6.Cu")
		(net "UPI_CPU0_CPU1_P0P1_DP<9>")
	)
	(segment
		(start 131.41198 -200.744328)
		(end 131.136644 -201.083164)
		(width 0.14732)
		(layer "In6.Cu")
		(net "UPI_CPU0_CPU1_P0P1_DP<9>")
	)
	(segment
		(start 302.425354 -180.895752)
		(end 273.202908 -181.604158)
		(width 0.14732)
		(layer "In6.Cu")
		(net "UPI_CPU0_CPU1_P0P1_DP<9>")
	)
	(segment
		(start 344.52052 -202.838304)
		(end 343.714578 -201.845672)
		(width 0.14732)
		(layer "In6.Cu")
		(net "UPI_CPU0_CPU1_P0P1_DP<9>")
	)
	(segment
		(start 129.995676 -202.486768)
		(end 129.584958 -202.992228)
		(width 0.14732)
		(layer "In6.Cu")
		(net "UPI_CPU0_CPU1_P0P1_DP<9>")
	)
	(segment
		(start 144.576038 -187.590938)
		(end 140.244068 -193.405506)
		(width 0.14732)
		(layer "In6.Cu")
		(net "UPI_CPU0_CPU1_P0P1_DP<9>")
	)
	(segment
		(start 345.346528 -211.66201)
		(end 345.346528 -211.537296)
		(width 0.14732)
		(layer "In6.Cu")
		(net "UPI_CPU0_CPU1_P0P1_DP<9>")
	)
	(segment
		(start 140.244068 -193.405506)
		(end 134.007606 -197.550786)
		(width 0.14732)
		(layer "In6.Cu")
		(net "UPI_CPU0_CPU1_P0P1_DP<9>")
	)
	(segment
		(start 131.86283 -200.38695)
		(end 131.58724 -200.726294)
		(width 0.14732)
		(layer "In6.Cu")
		(net "UPI_CPU0_CPU1_P0P1_DP<9>")
	)
	(segment
		(start 343.714578 -201.845672)
		(end 343.714578 -201.845926)
		(width 0.14732)
		(layer "In6.Cu")
		(net "UPI_CPU0_CPU1_P0P1_DP<9>")
	)
	(segment
		(start 326.458072 -190.954914)
		(end 319.945766 -184.73928)
		(width 0.14732)
		(layer "In6.Cu")
		(net "UPI_CPU0_CPU1_P0P1_DP<9>")
	)
	(segment
		(start 273.202908 -181.604158)
		(end 238.627666 -181.769004)
		(width 0.14732)
		(layer "In6.Cu")
		(net "UPI_CPU0_CPU1_P0P1_DP<9>")
	)
	(segment
		(start 133.2611 -198.46925)
		(end 133.279388 -198.644256)
		(width 0.14732)
		(layer "In6.Cu")
		(net "UPI_CPU0_CPU1_P0P1_DP<9>")
	)
	(segment
		(start 345.346528 -211.537296)
		(end 345.346274 -211.53755)
		(width 0.14732)
		(layer "In6.Cu")
		(net "UPI_CPU0_CPU1_P0P1_DP<9>")
	)
	(segment
		(start 345.388438 -211.726018)
		(end 345.346528 -211.684108)
		(width 0.0889)
		(layer "In6.Cu")
		(net "UPI_CPU0_CPU1_P0P1_DP<9>")
	)
	(segment
		(start 152.296368 -183.638698)
		(end 144.576038 -187.590938)
		(width 0.14732)
		(layer "In6.Cu")
		(net "UPI_CPU0_CPU1_P0P1_DP<9>")
	)
	(segment
		(start 126.81458 -211.66963)
		(end 126.81458 -211.691728)
		(width 0.0889)
		(layer "In6.Cu")
		(net "UPI_CPU0_CPU1_P0P1_DP<9>")
	)
	(segment
		(start 132.295392 -199.855074)
		(end 132.120132 -199.873108)
		(width 0.14732)
		(layer "In6.Cu")
		(net "UPI_CPU0_CPU1_P0P1_DP<9>")
	)
	(segment
		(start 132.570982 -199.51573)
		(end 132.295392 -199.855074)
		(width 0.14732)
		(layer "In6.Cu")
		(net "UPI_CPU0_CPU1_P0P1_DP<9>")
	)
	(segment
		(start 134.007606 -197.550786)
		(end 133.2611 -198.46925)
		(width 0.14732)
		(layer "In6.Cu")
		(net "UPI_CPU0_CPU1_P0P1_DP<9>")
	)
	(segment
		(start 130.170682 -202.468734)
		(end 129.995676 -202.486768)
		(width 0.14732)
		(layer "In6.Cu")
		(net "UPI_CPU0_CPU1_P0P1_DP<9>")
	)
	(segment
		(start 318.889126 -184.250584)
		(end 318.842898 -184.05094)
		(width 0.14732)
		(layer "In6.Cu")
		(net "UPI_CPU0_CPU1_P0P1_DP<9>")
	)
	(segment
		(start 132.552948 -199.34047)
		(end 132.570982 -199.51573)
		(width 0.14732)
		(layer "In6.Cu")
		(net "UPI_CPU0_CPU1_P0P1_DP<9>")
	)
	(segment
		(start 155.610306 -182.790338)
		(end 152.296368 -183.638698)
		(width 0.14732)
		(layer "In6.Cu")
		(net "UPI_CPU0_CPU1_P0P1_DP<9>")
	)
	(segment
		(start 345.388438 -213.892892)
		(end 345.388438 -211.726018)
		(width 0.0889)
		(layer "In6.Cu")
		(net "UPI_CPU0_CPU1_P0P1_DP<9>")
	)
	(segment
		(start 158.92526 -181.941724)
		(end 155.610814 -182.790338)
		(width 0.14732)
		(layer "In6.Cu")
		(net "UPI_CPU0_CPU1_P0P1_DP<9>")
	)
	(segment
		(start 318.842898 -184.05094)
		(end 315.453522 -181.935882)
		(width 0.14732)
		(layer "In6.Cu")
		(net "UPI_CPU0_CPU1_P0P1_DP<9>")
	)
	(segment
		(start 126.548134 -214.224616)
		(end 126.517908 -214.321644)
		(width 0.0889)
		(layer "In6.Cu")
		(net "UPI_CPU0_CPU1_P0P1_DP<9>")
	)
	(segment
		(start 126.81458 -211.46643)
		(end 126.81458 -211.66963)
		(width 0.14732)
		(layer "In6.Cu")
		(net "UPI_CPU0_CPU1_P0P1_DP<9>")
	)
	(segment
		(start 130.879088 -201.597514)
		(end 130.703828 -201.615548)
		(width 0.14732)
		(layer "In6.Cu")
		(net "UPI_CPU0_CPU1_P0P1_DP<9>")
	)
	(segment
		(start 155.610814 -182.790338)
		(end 155.610306 -182.790338)
		(width 0.14732)
		(layer "In6.Cu")
		(net "UPI_CPU0_CPU1_P0P1_DP<9>")
	)
	(segment
		(start 130.428492 -201.954384)
		(end 130.446526 -202.129644)
		(width 0.14732)
		(layer "In6.Cu")
		(net "UPI_CPU0_CPU1_P0P1_DP<9>")
	)
	(segment
		(start 345.388184 -213.8934)
		(end 345.388438 -213.892892)
		(width 0.0889)
		(layer "In6.Cu")
		(net "UPI_CPU0_CPU1_P0P1_DP<9>")
	)
	(segment
		(start 319.40119 -184.399428)
		(end 319.2018 -184.445656)
		(width 0.14732)
		(layer "In6.Cu")
		(net "UPI_CPU0_CPU1_P0P1_DP<9>")
	)
	(segment
		(start 132.828284 -199.001634)
		(end 132.552948 -199.34047)
		(width 0.14732)
		(layer "In6.Cu")
		(net "UPI_CPU0_CPU1_P0P1_DP<9>")
	)
	(segment
		(start 133.279388 -198.644256)
		(end 133.003544 -198.9836)
		(width 0.14732)
		(layer "In6.Cu")
		(net "UPI_CPU0_CPU1_P0P1_DP<9>")
	)
	(segment
		(start 212.418168 -181.769004)
		(end 200.604374 -181.250082)
		(width 0.14732)
		(layer "In6.Cu")
		(net "UPI_CPU0_CPU1_P0P1_DP<9>")
	)
	(segment
		(start 132.120132 -199.873108)
		(end 131.844796 -200.211944)
		(width 0.14732)
		(layer "In6.Cu")
		(net "UPI_CPU0_CPU1_P0P1_DP<9>")
	)
	(segment
		(start 326.98436 -191.278764)
		(end 326.458072 -190.954914)
		(width 0.14732)
		(layer "In6.Cu")
		(net "UPI_CPU0_CPU1_P0P1_DP<9>")
	)
	(segment
		(start 131.154678 -201.25817)
		(end 130.879088 -201.597514)
		(width 0.14732)
		(layer "In6.Cu")
		(net "UPI_CPU0_CPU1_P0P1_DP<9>")
	)
	(segment
		(start 129.584958 -202.992228)
		(end 126.813818 -210.90763)
		(width 0.14732)
		(layer "In6.Cu")
		(net "UPI_CPU0_CPU1_P0P1_DP<9>")
	)
	(segment
		(start 126.81458 -211.691728)
		(end 126.772416 -211.733892)
		(width 0.0889)
		(layer "In6.Cu")
		(net "UPI_CPU0_CPU1_P0P1_DP<9>")
	)
	(segment
		(start 312.429144 -181.079648)
		(end 302.425354 -180.895752)
		(width 0.14732)
		(layer "In6.Cu")
		(net "UPI_CPU0_CPU1_P0P1_DP<9>")
	)
	(segment
		(start 343.714578 -201.845926)
		(end 333.024734 -193.43624)
		(width 0.14732)
		(layer "In6.Cu")
		(net "UPI_CPU0_CPU1_P0P1_DP<9>")
	)
	(segment
		(start 344.917776 -214.636858)
		(end 344.917776 -214.425784)
		(width 0.0889)
		(layer "In6.Cu")
		(net "UPI_CPU0_CPU1_P0P1_DP<9>")
	)
	(segment
		(start 133.003544 -198.9836)
		(end 132.828284 -199.001634)
		(width 0.14732)
		(layer "In6.Cu")
		(net "UPI_CPU0_CPU1_P0P1_DP<9>")
	)
	(segment
		(start 131.844796 -200.211944)
		(end 131.86283 -200.38695)
		(width 0.14732)
		(layer "In6.Cu")
		(net "UPI_CPU0_CPU1_P0P1_DP<9>")
	)
	(segment
		(start 345.346528 -211.684108)
		(end 345.346528 -211.66201)
		(width 0.0889)
		(layer "In6.Cu")
		(net "UPI_CPU0_CPU1_P0P1_DP<9>")
	)
	(segment
		(start 319.945766 -184.73928)
		(end 319.40119 -184.399428)
		(width 0.14732)
		(layer "In6.Cu")
		(net "UPI_CPU0_CPU1_P0P1_DP<9>")
	)
	(segment
		(start 345.346274 -211.53755)
		(end 345.346274 -210.643724)
		(width 0.14732)
		(layer "In6.Cu")
		(net "UPI_CPU0_CPU1_P0P1_DP<9>")
	)
	(segment
		(start 126.813818 -211.465668)
		(end 126.81458 -211.46643)
		(width 0.14732)
		(layer "In6.Cu")
		(net "UPI_CPU0_CPU1_P0P1_DP<9>")
	)
	(segment
		(start 345.346274 -210.643724)
		(end 344.52052 -202.838304)
		(width 0.14732)
		(layer "In6.Cu")
		(net "UPI_CPU0_CPU1_P0P1_DP<9>")
	)
	(segment
		(start 345.01328 -215.436704)
		(end 345.169744 -215.165686)
		(width 0.0889)
		(layer "In6.Cu")
		(net "UPI_CPU0_CPU1_P0P1_DP<9>")
	)
	(segment
		(start 315.453522 -181.935882)
		(end 312.429144 -181.079648)
		(width 0.14732)
		(layer "In6.Cu")
		(net "UPI_CPU0_CPU1_P0P1_DP<9>")
	)
	(segment
		(start 333.024734 -193.43624)
		(end 326.98436 -191.278764)
		(width 0.14732)
		(layer "In6.Cu")
		(net "UPI_CPU0_CPU1_P0P1_DP<9>")
	)
	(segment
		(start 238.627666 -181.769004)
		(end 212.418168 -181.769004)
		(width 0.14732)
		(layer "In6.Cu")
		(net "UPI_CPU0_CPU1_P0P1_DP<9>")
	)
	(segment
		(start 131.58724 -200.726294)
		(end 131.41198 -200.744328)
		(width 0.14732)
		(layer "In6.Cu")
		(net "UPI_CPU0_CPU1_P0P1_DP<9>")
	)
	(segment
		(start 200.604374 -181.250082)
		(end 158.92526 -181.941724)
		(width 0.14732)
		(layer "In6.Cu")
		(net "UPI_CPU0_CPU1_P0P1_DP<9>")
	)
	(segment
		(start 126.517908 -214.321644)
		(end 126.676658 -214.622634)
		(width 0.0889)
		(layer "In6.Cu")
		(net "UPI_CPU0_CPU1_P0P1_DP<9>")
	)
	(segment
		(start 130.446526 -202.129644)
		(end 130.170682 -202.468734)
		(width 0.14732)
		(layer "In6.Cu")
		(net "UPI_CPU0_CPU1_P0P1_DP<9>")
	)
	(segment
		(start 131.136644 -201.083164)
		(end 131.154678 -201.25817)
		(width 0.14732)
		(layer "In6.Cu")
		(net "UPI_CPU0_CPU1_P0P1_DP<9>")
	)
	(segment
		(start 130.703828 -201.615548)
		(end 130.428492 -201.954384)
		(width 0.14732)
		(layer "In6.Cu")
		(net "UPI_CPU0_CPU1_P0P1_DP<9>")
	)
	(segment
		(start 126.813818 -210.90763)
		(end 126.813818 -211.465668)
		(width 0.14732)
		(layer "In6.Cu")
		(net "UPI_CPU0_CPU1_P0P1_DP<9>")
	)
	(segment
		(start 319.2018 -184.445656)
		(end 318.889126 -184.250584)
		(width 0.14732)
		(layer "In6.Cu")
		(net "UPI_CPU0_CPU1_P0P1_DP<9>")
	)
	(segment
		(start 126.772416 -211.733892)
		(end 126.772416 -213.929214)
		(width 0.0889)
		(layer "In6.Cu")
		(net "UPI_CPU0_CPU1_P0P1_DP<9>")
	)
	(arc
		(start 345.128596 -215.063324)
		(mid 344.976165 -214.873342)
		(end 344.917776 -214.636858)
		(width 0.0889)
		(layer "In6.Cu")
		(net "UPI_CPU0_CPU1_P0P1_DP<9>")
	)
	(arc
		(start 344.917776 -214.425784)
		(mid 345.029216 -214.232389)
		(end 345.20378 -214.093298)
		(width 0.0889)
		(layer "In6.Cu")
		(net "UPI_CPU0_CPU1_P0P1_DP<9>")
	)
	(arc
		(start 126.772416 -213.929214)
		(mid 126.683726 -214.094715)
		(end 126.548134 -214.224616)
		(width 0.0889)
		(layer "In6.Cu")
		(net "UPI_CPU0_CPU1_P0P1_DP<9>")
	)
	(arc
		(start 345.145614 -215.076532)
		(mid 345.137042 -215.070009)
		(end 345.128596 -215.063324)
		(width 0.0889)
		(layer "In6.Cu")
		(net "UPI_CPU0_CPU1_P0P1_DP<9>")
	)
	(arc
		(start 345.20378 -214.093298)
		(mid 345.313176 -214.009201)
		(end 345.388184 -213.8934)
		(width 0.0889)
		(layer "In6.Cu")
		(net "UPI_CPU0_CPU1_P0P1_DP<9>")
	)
	(segment
		(start 344.073734 -214.344758)
		(end 344.073734 -213.732618)
		(width 0.13208)
		(layer "F.Cu")
		(net "UPI_CPU0_CPU1_P0P1_DP<8>")
	)
	(segment
		(start 127.616712 -215.158574)
		(end 127.616712 -214.622888)
		(width 0.13208)
		(layer "F.Cu")
		(net "UPI_CPU0_CPU1_P0P1_DP<8>")
	)
	(segment
		(start 127.616712 -214.622888)
		(end 127.616458 -214.622634)
		(width 0.13208)
		(layer "F.Cu")
		(net "UPI_CPU0_CPU1_P0P1_DP<8>")
	)
	(segment
		(start 302.504094 -181.729126)
		(end 273.215354 -182.438802)
		(width 0.14732)
		(layer "In6.Cu")
		(net "UPI_CPU0_CPU1_P0P1_DP<8>")
	)
	(segment
		(start 238.630206 -182.603648)
		(end 212.292438 -182.603648)
		(width 0.14732)
		(layer "In6.Cu")
		(net "UPI_CPU0_CPU1_P0P1_DP<8>")
	)
	(segment
		(start 344.232484 -214.033608)
		(end 344.317066 -214.05977)
		(width 0.0889)
		(layer "In6.Cu")
		(net "UPI_CPU0_CPU1_P0P1_DP<8>")
	)
	(segment
		(start 127.459994 -214.893652)
		(end 127.616458 -214.622634)
		(width 0.0889)
		(layer "In6.Cu")
		(net "UPI_CPU0_CPU1_P0P1_DP<8>")
	)
	(segment
		(start 312.271664 -181.90972)
		(end 302.504094 -181.729126)
		(width 0.14732)
		(layer "In6.Cu")
		(net "UPI_CPU0_CPU1_P0P1_DP<8>")
	)
	(segment
		(start 127.381762 -214.91448)
		(end 127.459994 -214.893652)
		(width 0.0889)
		(layer "In6.Cu")
		(net "UPI_CPU0_CPU1_P0P1_DP<8>")
	)
	(segment
		(start 132.720842 -200.863962)
		(end 132.444998 -201.203306)
		(width 0.14732)
		(layer "In6.Cu")
		(net "UPI_CPU0_CPU1_P0P1_DP<8>")
	)
	(segment
		(start 145.149824 -188.233812)
		(end 140.82395 -194.040506)
		(width 0.14732)
		(layer "In6.Cu")
		(net "UPI_CPU0_CPU1_P0P1_DP<8>")
	)
	(segment
		(start 127.754126 -211.465668)
		(end 127.75438 -211.465922)
		(width 0.14732)
		(layer "In6.Cu")
		(net "UPI_CPU0_CPU1_P0P1_DP<8>")
	)
	(segment
		(start 132.012436 -201.735182)
		(end 131.736592 -202.074526)
		(width 0.14732)
		(layer "In6.Cu")
		(net "UPI_CPU0_CPU1_P0P1_DP<8>")
	)
	(segment
		(start 131.028186 -202.945492)
		(end 130.85318 -202.96378)
		(width 0.14732)
		(layer "In6.Cu")
		(net "UPI_CPU0_CPU1_P0P1_DP<8>")
	)
	(segment
		(start 343.615264 -203.214224)
		(end 342.76411 -202.165458)
		(width 0.14732)
		(layer "In6.Cu")
		(net "UPI_CPU0_CPU1_P0P1_DP<8>")
	)
	(segment
		(start 344.448384 -212.756496)
		(end 344.34907 -212.657182)
		(width 0.0889)
		(layer "In6.Cu")
		(net "UPI_CPU0_CPU1_P0P1_DP<8>")
	)
	(segment
		(start 344.406474 -211.537296)
		(end 344.40622 -211.53755)
		(width 0.14732)
		(layer "In6.Cu")
		(net "UPI_CPU0_CPU1_P0P1_DP<8>")
	)
	(segment
		(start 344.34907 -213.12251)
		(end 344.448384 -213.023196)
		(width 0.0889)
		(layer "In6.Cu")
		(net "UPI_CPU0_CPU1_P0P1_DP<8>")
	)
	(segment
		(start 131.30403 -202.606402)
		(end 131.028186 -202.945492)
		(width 0.14732)
		(layer "In6.Cu")
		(net "UPI_CPU0_CPU1_P0P1_DP<8>")
	)
	(segment
		(start 152.474168 -184.48401)
		(end 145.149824 -188.233812)
		(width 0.14732)
		(layer "In6.Cu")
		(net "UPI_CPU0_CPU1_P0P1_DP<8>")
	)
	(segment
		(start 344.448384 -211.726018)
		(end 344.406474 -211.684108)
		(width 0.0889)
		(layer "In6.Cu")
		(net "UPI_CPU0_CPU1_P0P1_DP<8>")
	)
	(segment
		(start 131.736592 -202.074526)
		(end 131.561586 -202.09256)
		(width 0.14732)
		(layer "In6.Cu")
		(net "UPI_CPU0_CPU1_P0P1_DP<8>")
	)
	(segment
		(start 127.712216 -212.296248)
		(end 127.81153 -212.395562)
		(width 0.0889)
		(layer "In6.Cu")
		(net "UPI_CPU0_CPU1_P0P1_DP<8>")
	)
	(segment
		(start 344.34907 -212.657182)
		(end 344.34907 -212.390482)
		(width 0.0889)
		(layer "In6.Cu")
		(net "UPI_CPU0_CPU1_P0P1_DP<8>")
	)
	(segment
		(start 133.429248 -199.992742)
		(end 133.153404 -200.332086)
		(width 0.14732)
		(layer "In6.Cu")
		(net "UPI_CPU0_CPU1_P0P1_DP<8>")
	)
	(segment
		(start 322.295266 -188.257434)
		(end 321.2338 -187.237878)
		(width 0.14732)
		(layer "In6.Cu")
		(net "UPI_CPU0_CPU1_P0P1_DP<8>")
	)
	(segment
		(start 323.305424 -189.428374)
		(end 323.03974 -189.173104)
		(width 0.14732)
		(layer "In6.Cu")
		(net "UPI_CPU0_CPU1_P0P1_DP<8>")
	)
	(segment
		(start 130.85318 -202.96378)
		(end 130.386328 -203.53782)
		(width 0.14732)
		(layer "In6.Cu")
		(net "UPI_CPU0_CPU1_P0P1_DP<8>")
	)
	(segment
		(start 132.978398 -200.35012)
		(end 132.702808 -200.688956)
		(width 0.14732)
		(layer "In6.Cu")
		(net "UPI_CPU0_CPU1_P0P1_DP<8>")
	)
	(segment
		(start 127.712216 -213.511892)
		(end 127.712216 -213.929468)
		(width 0.0889)
		(layer "In6.Cu")
		(net "UPI_CPU0_CPU1_P0P1_DP<8>")
	)
	(segment
		(start 131.561586 -202.09256)
		(end 131.285996 -202.431396)
		(width 0.14732)
		(layer "In6.Cu")
		(net "UPI_CPU0_CPU1_P0P1_DP<8>")
	)
	(segment
		(start 133.153404 -200.332086)
		(end 132.978398 -200.35012)
		(width 0.14732)
		(layer "In6.Cu")
		(net "UPI_CPU0_CPU1_P0P1_DP<8>")
	)
	(segment
		(start 344.34907 -212.390482)
		(end 344.448384 -212.291168)
		(width 0.0889)
		(layer "In6.Cu")
		(net "UPI_CPU0_CPU1_P0P1_DP<8>")
	)
	(segment
		(start 323.03974 -189.173104)
		(end 323.035422 -188.96838)
		(width 0.14732)
		(layer "In6.Cu")
		(net "UPI_CPU0_CPU1_P0P1_DP<8>")
	)
	(segment
		(start 323.987922 -189.883034)
		(end 323.510148 -189.42431)
		(width 0.14732)
		(layer "In6.Cu")
		(net "UPI_CPU0_CPU1_P0P1_DP<8>")
	)
	(segment
		(start 130.386328 -203.53782)
		(end 127.754126 -211.055458)
		(width 0.14732)
		(layer "In6.Cu")
		(net "UPI_CPU0_CPU1_P0P1_DP<8>")
	)
	(segment
		(start 323.991986 -190.087758)
		(end 323.987922 -189.883034)
		(width 0.14732)
		(layer "In6.Cu")
		(net "UPI_CPU0_CPU1_P0P1_DP<8>")
	)
	(segment
		(start 342.76411 -202.165458)
		(end 332.759304 -194.295014)
		(width 0.14732)
		(layer "In6.Cu")
		(net "UPI_CPU0_CPU1_P0P1_DP<8>")
	)
	(segment
		(start 131.285996 -202.431396)
		(end 131.30403 -202.606402)
		(width 0.14732)
		(layer "In6.Cu")
		(net "UPI_CPU0_CPU1_P0P1_DP<8>")
	)
	(segment
		(start 134.914386 -197.96887)
		(end 133.411214 -199.817736)
		(width 0.14732)
		(layer "In6.Cu")
		(net "UPI_CPU0_CPU1_P0P1_DP<8>")
	)
	(segment
		(start 344.34907 -213.38921)
		(end 344.34907 -213.12251)
		(width 0.0889)
		(layer "In6.Cu")
		(net "UPI_CPU0_CPU1_P0P1_DP<8>")
	)
	(segment
		(start 133.411214 -199.817736)
		(end 133.429248 -199.992742)
		(width 0.14732)
		(layer "In6.Cu")
		(net "UPI_CPU0_CPU1_P0P1_DP<8>")
	)
	(segment
		(start 344.073734 -213.732618)
		(end 344.232484 -214.033608)
		(width 0.0889)
		(layer "In6.Cu")
		(net "UPI_CPU0_CPU1_P0P1_DP<8>")
	)
	(segment
		(start 127.712216 -211.845652)
		(end 127.712216 -212.296248)
		(width 0.0889)
		(layer "In6.Cu")
		(net "UPI_CPU0_CPU1_P0P1_DP<8>")
	)
	(segment
		(start 132.269992 -201.22134)
		(end 131.994402 -201.560176)
		(width 0.14732)
		(layer "In6.Cu")
		(net "UPI_CPU0_CPU1_P0P1_DP<8>")
	)
	(segment
		(start 322.769992 -188.713364)
		(end 322.565268 -188.717428)
		(width 0.14732)
		(layer "In6.Cu")
		(net "UPI_CPU0_CPU1_P0P1_DP<8>")
	)
	(segment
		(start 344.448384 -213.488524)
		(end 344.34907 -213.38921)
		(width 0.0889)
		(layer "In6.Cu")
		(net "UPI_CPU0_CPU1_P0P1_DP<8>")
	)
	(segment
		(start 273.215354 -182.438802)
		(end 238.630206 -182.603648)
		(width 0.14732)
		(layer "In6.Cu")
		(net "UPI_CPU0_CPU1_P0P1_DP<8>")
	)
	(segment
		(start 321.2338 -187.237878)
		(end 320.525394 -186.699652)
		(width 0.14732)
		(layer "In6.Cu")
		(net "UPI_CPU0_CPU1_P0P1_DP<8>")
	)
	(segment
		(start 323.035422 -188.96838)
		(end 322.769992 -188.713364)
		(width 0.14732)
		(layer "In6.Cu")
		(net "UPI_CPU0_CPU1_P0P1_DP<8>")
	)
	(segment
		(start 344.448384 -212.291168)
		(end 344.448384 -211.726018)
		(width 0.0889)
		(layer "In6.Cu")
		(net "UPI_CPU0_CPU1_P0P1_DP<8>")
	)
	(segment
		(start 325.535544 -191.369442)
		(end 324.462648 -190.338964)
		(width 0.14732)
		(layer "In6.Cu")
		(net "UPI_CPU0_CPU1_P0P1_DP<8>")
	)
	(segment
		(start 127.712216 -213.046564)
		(end 127.81153 -213.145878)
		(width 0.0889)
		(layer "In6.Cu")
		(net "UPI_CPU0_CPU1_P0P1_DP<8>")
	)
	(segment
		(start 212.292438 -182.603648)
		(end 200.5838 -182.089044)
		(width 0.14732)
		(layer "In6.Cu")
		(net "UPI_CPU0_CPU1_P0P1_DP<8>")
	)
	(segment
		(start 127.81153 -213.145878)
		(end 127.81153 -213.412578)
		(width 0.0889)
		(layer "In6.Cu")
		(net "UPI_CPU0_CPU1_P0P1_DP<8>")
	)
	(segment
		(start 344.40622 -211.53755)
		(end 344.40622 -210.68919)
		(width 0.14732)
		(layer "In6.Cu")
		(net "UPI_CPU0_CPU1_P0P1_DP<8>")
	)
	(segment
		(start 132.444998 -201.203306)
		(end 132.269992 -201.22134)
		(width 0.14732)
		(layer "In6.Cu")
		(net "UPI_CPU0_CPU1_P0P1_DP<8>")
	)
	(segment
		(start 320.525394 -186.699652)
		(end 320.322448 -186.727338)
		(width 0.14732)
		(layer "In6.Cu")
		(net "UPI_CPU0_CPU1_P0P1_DP<8>")
	)
	(segment
		(start 324.462648 -190.338964)
		(end 324.257924 -190.343028)
		(width 0.14732)
		(layer "In6.Cu")
		(net "UPI_CPU0_CPU1_P0P1_DP<8>")
	)
	(segment
		(start 320.028824 -186.50458)
		(end 320.001138 -186.301634)
		(width 0.14732)
		(layer "In6.Cu")
		(net "UPI_CPU0_CPU1_P0P1_DP<8>")
	)
	(segment
		(start 159.141668 -182.77713)
		(end 152.474168 -184.48401)
		(width 0.14732)
		(layer "In6.Cu")
		(net "UPI_CPU0_CPU1_P0P1_DP<8>")
	)
	(segment
		(start 127.241808 -214.461852)
		(end 127.241808 -214.622634)
		(width 0.0889)
		(layer "In6.Cu")
		(net "UPI_CPU0_CPU1_P0P1_DP<8>")
	)
	(segment
		(start 344.448384 -213.023196)
		(end 344.448384 -212.756496)
		(width 0.0889)
		(layer "In6.Cu")
		(net "UPI_CPU0_CPU1_P0P1_DP<8>")
	)
	(segment
		(start 127.712216 -212.761576)
		(end 127.712216 -213.046564)
		(width 0.0889)
		(layer "In6.Cu")
		(net "UPI_CPU0_CPU1_P0P1_DP<8>")
	)
	(segment
		(start 317.397384 -184.323736)
		(end 315.20003 -182.836312)
		(width 0.14732)
		(layer "In6.Cu")
		(net "UPI_CPU0_CPU1_P0P1_DP<8>")
	)
	(segment
		(start 127.754126 -211.055458)
		(end 127.754126 -211.465668)
		(width 0.14732)
		(layer "In6.Cu")
		(net "UPI_CPU0_CPU1_P0P1_DP<8>")
	)
	(segment
		(start 127.75438 -211.803488)
		(end 127.712216 -211.845652)
		(width 0.0889)
		(layer "In6.Cu")
		(net "UPI_CPU0_CPU1_P0P1_DP<8>")
	)
	(segment
		(start 127.81153 -212.395562)
		(end 127.81153 -212.662262)
		(width 0.0889)
		(layer "In6.Cu")
		(net "UPI_CPU0_CPU1_P0P1_DP<8>")
	)
	(segment
		(start 127.81153 -213.412578)
		(end 127.712216 -213.511892)
		(width 0.0889)
		(layer "In6.Cu")
		(net "UPI_CPU0_CPU1_P0P1_DP<8>")
	)
	(segment
		(start 323.510148 -189.42431)
		(end 323.305424 -189.428374)
		(width 0.14732)
		(layer "In6.Cu")
		(net "UPI_CPU0_CPU1_P0P1_DP<8>")
	)
	(segment
		(start 322.565268 -188.717428)
		(end 322.29933 -188.461904)
		(width 0.14732)
		(layer "In6.Cu")
		(net "UPI_CPU0_CPU1_P0P1_DP<8>")
	)
	(segment
		(start 132.702808 -200.688956)
		(end 132.720842 -200.863962)
		(width 0.14732)
		(layer "In6.Cu")
		(net "UPI_CPU0_CPU1_P0P1_DP<8>")
	)
	(segment
		(start 344.40622 -210.68919)
		(end 343.615264 -203.214224)
		(width 0.14732)
		(layer "In6.Cu")
		(net "UPI_CPU0_CPU1_P0P1_DP<8>")
	)
	(segment
		(start 315.20003 -182.836312)
		(end 312.271664 -181.90972)
		(width 0.14732)
		(layer "In6.Cu")
		(net "UPI_CPU0_CPU1_P0P1_DP<8>")
	)
	(segment
		(start 127.81153 -212.662262)
		(end 127.712216 -212.761576)
		(width 0.0889)
		(layer "In6.Cu")
		(net "UPI_CPU0_CPU1_P0P1_DP<8>")
	)
	(segment
		(start 127.75438 -211.465922)
		(end 127.75438 -211.78139)
		(width 0.14732)
		(layer "In6.Cu")
		(net "UPI_CPU0_CPU1_P0P1_DP<8>")
	)
	(segment
		(start 200.5838 -182.089044)
		(end 159.141668 -182.77713)
		(width 0.14732)
		(layer "In6.Cu")
		(net "UPI_CPU0_CPU1_P0P1_DP<8>")
	)
	(segment
		(start 140.82395 -194.040506)
		(end 134.914386 -197.96887)
		(width 0.14732)
		(layer "In6.Cu")
		(net "UPI_CPU0_CPU1_P0P1_DP<8>")
	)
	(segment
		(start 320.001138 -186.301634)
		(end 317.397384 -184.323736)
		(width 0.14732)
		(layer "In6.Cu")
		(net "UPI_CPU0_CPU1_P0P1_DP<8>")
	)
	(segment
		(start 326.717914 -192.105026)
		(end 325.535544 -191.369442)
		(width 0.14732)
		(layer "In6.Cu")
		(net "UPI_CPU0_CPU1_P0P1_DP<8>")
	)
	(segment
		(start 324.257924 -190.343028)
		(end 323.991986 -190.087758)
		(width 0.14732)
		(layer "In6.Cu")
		(net "UPI_CPU0_CPU1_P0P1_DP<8>")
	)
	(segment
		(start 320.322448 -186.727338)
		(end 320.028824 -186.50458)
		(width 0.14732)
		(layer "In6.Cu")
		(net "UPI_CPU0_CPU1_P0P1_DP<8>")
	)
	(segment
		(start 322.29933 -188.461904)
		(end 322.295266 -188.257434)
		(width 0.14732)
		(layer "In6.Cu")
		(net "UPI_CPU0_CPU1_P0P1_DP<8>")
	)
	(segment
		(start 131.994402 -201.560176)
		(end 132.012436 -201.735182)
		(width 0.14732)
		(layer "In6.Cu")
		(net "UPI_CPU0_CPU1_P0P1_DP<8>")
	)
	(segment
		(start 127.75438 -211.78139)
		(end 127.75438 -211.803488)
		(width 0.0889)
		(layer "In6.Cu")
		(net "UPI_CPU0_CPU1_P0P1_DP<8>")
	)
	(segment
		(start 332.759304 -194.295014)
		(end 326.717914 -192.105026)
		(width 0.14732)
		(layer "In6.Cu")
		(net "UPI_CPU0_CPU1_P0P1_DP<8>")
	)
	(segment
		(start 344.406474 -211.66201)
		(end 344.406474 -211.537296)
		(width 0.14732)
		(layer "In6.Cu")
		(net "UPI_CPU0_CPU1_P0P1_DP<8>")
	)
	(segment
		(start 344.406474 -211.684108)
		(end 344.406474 -211.66201)
		(width 0.0889)
		(layer "In6.Cu")
		(net "UPI_CPU0_CPU1_P0P1_DP<8>")
	)
	(segment
		(start 344.448384 -213.8934)
		(end 344.448384 -213.488524)
		(width 0.0889)
		(layer "In6.Cu")
		(net "UPI_CPU0_CPU1_P0P1_DP<8>")
	)
	(arc
		(start 127.426212 -214.261954)
		(mid 127.316816 -214.346051)
		(end 127.241808 -214.461852)
		(width 0.0889)
		(layer "In6.Cu")
		(net "UPI_CPU0_CPU1_P0P1_DP<8>")
	)
	(arc
		(start 344.317066 -214.05977)
		(mid 344.393739 -213.985276)
		(end 344.448384 -213.8934)
		(width 0.0889)
		(layer "In6.Cu")
		(net "UPI_CPU0_CPU1_P0P1_DP<8>")
	)
	(arc
		(start 127.696976 -213.968584)
		(mid 127.58677 -214.138501)
		(end 127.426212 -214.261954)
		(width 0.0889)
		(layer "In6.Cu")
		(net "UPI_CPU0_CPU1_P0P1_DP<8>")
	)
	(arc
		(start 127.712216 -213.929468)
		(mid 127.704938 -213.949159)
		(end 127.696976 -213.968584)
		(width 0.0889)
		(layer "In6.Cu")
		(net "UPI_CPU0_CPU1_P0P1_DP<8>")
	)
	(arc
		(start 127.241808 -214.622634)
		(mid 127.278668 -214.784431)
		(end 127.381762 -214.91448)
		(width 0.0889)
		(layer "In6.Cu")
		(net "UPI_CPU0_CPU1_P0P1_DP<8>")
	)
	(segment
		(start 128.556512 -215.158574)
		(end 128.556512 -214.622888)
		(width 0.13208)
		(layer "F.Cu")
		(net "UPI_CPU0_CPU1_P0P1_DP<7>")
	)
	(segment
		(start 343.133934 -215.972644)
		(end 343.133934 -215.436958)
		(width 0.13208)
		(layer "F.Cu")
		(net "UPI_CPU0_CPU1_P0P1_DP<7>")
	)
	(segment
		(start 343.133934 -215.436958)
		(end 343.13368 -215.436704)
		(width 0.13208)
		(layer "F.Cu")
		(net "UPI_CPU0_CPU1_P0P1_DP<7>")
	)
	(segment
		(start 128.556512 -214.622888)
		(end 128.556258 -214.622634)
		(width 0.13208)
		(layer "F.Cu")
		(net "UPI_CPU0_CPU1_P0P1_DP<7>")
	)
	(segment
		(start 128.651762 -213.93023)
		(end 128.652016 -213.929468)
		(width 0.0889)
		(layer "In6.Cu")
		(net "UPI_CPU0_CPU1_P0P1_DP<7>")
	)
	(segment
		(start 316.998096 -185.169302)
		(end 314.505086 -183.500014)
		(width 0.14732)
		(layer "In6.Cu")
		(net "UPI_CPU0_CPU1_P0P1_DP<7>")
	)
	(segment
		(start 343.508838 -211.657438)
		(end 343.466928 -211.615528)
		(width 0.0889)
		(layer "In6.Cu")
		(net "UPI_CPU0_CPU1_P0P1_DP<7>")
	)
	(segment
		(start 128.693926 -211.77123)
		(end 128.693926 -211.793328)
		(width 0.0889)
		(layer "In6.Cu")
		(net "UPI_CPU0_CPU1_P0P1_DP<7>")
	)
	(segment
		(start 133.982206 -200.86701)
		(end 133.749542 -201.153014)
		(width 0.14732)
		(layer "In6.Cu")
		(net "UPI_CPU0_CPU1_P0P1_DP<7>")
	)
	(segment
		(start 341.791036 -202.458828)
		(end 341.791036 -202.458574)
		(width 0.14732)
		(layer "In6.Cu")
		(net "UPI_CPU0_CPU1_P0P1_DP<7>")
	)
	(segment
		(start 302.506634 -182.592726)
		(end 273.228054 -183.301894)
		(width 0.14732)
		(layer "In6.Cu")
		(net "UPI_CPU0_CPU1_P0P1_DP<7>")
	)
	(segment
		(start 343.290144 -215.165686)
		(end 343.266014 -215.076532)
		(width 0.0889)
		(layer "In6.Cu")
		(net "UPI_CPU0_CPU1_P0P1_DP<7>")
	)
	(segment
		(start 134.615428 -199.85863)
		(end 134.636256 -200.062338)
		(width 0.14732)
		(layer "In6.Cu")
		(net "UPI_CPU0_CPU1_P0P1_DP<7>")
	)
	(segment
		(start 322.43522 -190.029084)
		(end 320.197988 -188.662056)
		(width 0.14732)
		(layer "In6.Cu")
		(net "UPI_CPU0_CPU1_P0P1_DP<7>")
	)
	(segment
		(start 332.39583 -195.067936)
		(end 325.317612 -192.478152)
		(width 0.14732)
		(layer "In6.Cu")
		(net "UPI_CPU0_CPU1_P0P1_DP<7>")
	)
	(segment
		(start 312.182764 -182.771034)
		(end 302.506634 -182.592726)
		(width 0.14732)
		(layer "In6.Cu")
		(net "UPI_CPU0_CPU1_P0P1_DP<7>")
	)
	(segment
		(start 343.466928 -211.468716)
		(end 343.466674 -211.46897)
		(width 0.14732)
		(layer "In6.Cu")
		(net "UPI_CPU0_CPU1_P0P1_DP<7>")
	)
	(segment
		(start 200.230486 -182.930292)
		(end 179.813712 -183.269128)
		(width 0.14732)
		(layer "In6.Cu")
		(net "UPI_CPU0_CPU1_P0P1_DP<7>")
	)
	(segment
		(start 128.693926 -211.793328)
		(end 128.651762 -211.835492)
		(width 0.0889)
		(layer "In6.Cu")
		(net "UPI_CPU0_CPU1_P0P1_DP<7>")
	)
	(segment
		(start 342.7095 -203.590398)
		(end 341.791036 -202.458828)
		(width 0.14732)
		(layer "In6.Cu")
		(net "UPI_CPU0_CPU1_P0P1_DP<7>")
	)
	(segment
		(start 343.13368 -215.436704)
		(end 343.290144 -215.165686)
		(width 0.0889)
		(layer "In6.Cu")
		(net "UPI_CPU0_CPU1_P0P1_DP<7>")
	)
	(segment
		(start 238.632492 -183.46674)
		(end 212.438488 -183.46674)
		(width 0.14732)
		(layer "In6.Cu")
		(net "UPI_CPU0_CPU1_P0P1_DP<7>")
	)
	(segment
		(start 179.813458 -183.269128)
		(end 159.397192 -183.607964)
		(width 0.14732)
		(layer "In6.Cu")
		(net "UPI_CPU0_CPU1_P0P1_DP<7>")
	)
	(segment
		(start 133.102096 -201.949304)
		(end 132.898642 -201.970132)
		(width 0.14732)
		(layer "In6.Cu")
		(net "UPI_CPU0_CPU1_P0P1_DP<7>")
	)
	(segment
		(start 152.61971 -185.343546)
		(end 147.922234 -187.747656)
		(width 0.14732)
		(layer "In6.Cu")
		(net "UPI_CPU0_CPU1_P0P1_DP<7>")
	)
	(segment
		(start 137.17397 -197.659752)
		(end 136.97331 -197.619366)
		(width 0.14732)
		(layer "In6.Cu")
		(net "UPI_CPU0_CPU1_P0P1_DP<7>")
	)
	(segment
		(start 320.197988 -188.662056)
		(end 316.998096 -185.169302)
		(width 0.14732)
		(layer "In6.Cu")
		(net "UPI_CPU0_CPU1_P0P1_DP<7>")
	)
	(segment
		(start 343.466674 -210.7438)
		(end 342.7095 -203.590398)
		(width 0.14732)
		(layer "In6.Cu")
		(net "UPI_CPU0_CPU1_P0P1_DP<7>")
	)
	(segment
		(start 136.97331 -197.619366)
		(end 135.80364 -198.39686)
		(width 0.14732)
		(layer "In6.Cu")
		(net "UPI_CPU0_CPU1_P0P1_DP<7>")
	)
	(segment
		(start 131.167124 -204.099668)
		(end 128.693672 -211.1629)
		(width 0.14732)
		(layer "In6.Cu")
		(net "UPI_CPU0_CPU1_P0P1_DP<7>")
	)
	(segment
		(start 146.239484 -188.60897)
		(end 145.743676 -188.862716)
		(width 0.14732)
		(layer "In6.Cu")
		(net "UPI_CPU0_CPU1_P0P1_DP<7>")
	)
	(segment
		(start 325.317612 -192.478152)
		(end 322.43522 -190.029084)
		(width 0.14732)
		(layer "In6.Cu")
		(net "UPI_CPU0_CPU1_P0P1_DP<7>")
	)
	(segment
		(start 146.825208 -188.30925)
		(end 146.76247 -188.504068)
		(width 0.14732)
		(layer "In6.Cu")
		(net "UPI_CPU0_CPU1_P0P1_DP<7>")
	)
	(segment
		(start 147.922234 -187.747656)
		(end 147.859242 -187.942728)
		(width 0.14732)
		(layer "In6.Cu")
		(net "UPI_CPU0_CPU1_P0P1_DP<7>")
	)
	(segment
		(start 133.33476 -201.6633)
		(end 133.102096 -201.949304)
		(width 0.14732)
		(layer "In6.Cu")
		(net "UPI_CPU0_CPU1_P0P1_DP<7>")
	)
	(segment
		(start 133.961124 -200.663302)
		(end 133.982206 -200.86701)
		(width 0.14732)
		(layer "In6.Cu")
		(net "UPI_CPU0_CPU1_P0P1_DP<7>")
	)
	(segment
		(start 134.636256 -200.062338)
		(end 134.403846 -200.348342)
		(width 0.14732)
		(layer "In6.Cu")
		(net "UPI_CPU0_CPU1_P0P1_DP<7>")
	)
	(segment
		(start 343.466928 -211.615528)
		(end 343.466928 -211.59343)
		(width 0.0889)
		(layer "In6.Cu")
		(net "UPI_CPU0_CPU1_P0P1_DP<7>")
	)
	(segment
		(start 132.898642 -201.970132)
		(end 131.167124 -204.099668)
		(width 0.14732)
		(layer "In6.Cu")
		(net "UPI_CPU0_CPU1_P0P1_DP<7>")
	)
	(segment
		(start 147.859242 -187.942728)
		(end 147.531074 -188.110368)
		(width 0.14732)
		(layer "In6.Cu")
		(net "UPI_CPU0_CPU1_P0P1_DP<7>")
	)
	(segment
		(start 273.228054 -183.301894)
		(end 238.632492 -183.46674)
		(width 0.14732)
		(layer "In6.Cu")
		(net "UPI_CPU0_CPU1_P0P1_DP<7>")
	)
	(segment
		(start 343.466928 -211.59343)
		(end 343.466928 -211.468716)
		(width 0.14732)
		(layer "In6.Cu")
		(net "UPI_CPU0_CPU1_P0P1_DP<7>")
	)
	(segment
		(start 147.531074 -188.110368)
		(end 147.33651 -188.04763)
		(width 0.14732)
		(layer "In6.Cu")
		(net "UPI_CPU0_CPU1_P0P1_DP<7>")
	)
	(segment
		(start 314.505086 -183.500014)
		(end 312.182764 -182.771034)
		(width 0.14732)
		(layer "In6.Cu")
		(net "UPI_CPU0_CPU1_P0P1_DP<7>")
	)
	(segment
		(start 179.813712 -183.269128)
		(end 179.813458 -183.269128)
		(width 0.14732)
		(layer "In6.Cu")
		(net "UPI_CPU0_CPU1_P0P1_DP<7>")
	)
	(segment
		(start 128.651762 -211.835492)
		(end 128.651762 -213.93023)
		(width 0.0889)
		(layer "In6.Cu")
		(net "UPI_CPU0_CPU1_P0P1_DP<7>")
	)
	(segment
		(start 341.791036 -202.458574)
		(end 332.39583 -195.067936)
		(width 0.14732)
		(layer "In6.Cu")
		(net "UPI_CPU0_CPU1_P0P1_DP<7>")
	)
	(segment
		(start 133.545834 -201.173842)
		(end 133.313678 -201.459592)
		(width 0.14732)
		(layer "In6.Cu")
		(net "UPI_CPU0_CPU1_P0P1_DP<7>")
	)
	(segment
		(start 128.427734 -214.22487)
		(end 128.397508 -214.321644)
		(width 0.0889)
		(layer "In6.Cu")
		(net "UPI_CPU0_CPU1_P0P1_DP<7>")
	)
	(segment
		(start 134.403846 -200.348342)
		(end 134.200138 -200.369424)
		(width 0.14732)
		(layer "In6.Cu")
		(net "UPI_CPU0_CPU1_P0P1_DP<7>")
	)
	(segment
		(start 128.693672 -211.1629)
		(end 128.693672 -211.546948)
		(width 0.14732)
		(layer "In6.Cu")
		(net "UPI_CPU0_CPU1_P0P1_DP<7>")
	)
	(segment
		(start 128.693672 -211.546948)
		(end 128.693926 -211.547202)
		(width 0.14732)
		(layer "In6.Cu")
		(net "UPI_CPU0_CPU1_P0P1_DP<7>")
	)
	(segment
		(start 343.038176 -214.636858)
		(end 343.038176 -214.425784)
		(width 0.0889)
		(layer "In6.Cu")
		(net "UPI_CPU0_CPU1_P0P1_DP<7>")
	)
	(segment
		(start 159.397192 -183.607964)
		(end 152.61971 -185.343546)
		(width 0.14732)
		(layer "In6.Cu")
		(net "UPI_CPU0_CPU1_P0P1_DP<7>")
	)
	(segment
		(start 145.743676 -188.862716)
		(end 141.425168 -194.659504)
		(width 0.14732)
		(layer "In6.Cu")
		(net "UPI_CPU0_CPU1_P0P1_DP<7>")
	)
	(segment
		(start 133.313678 -201.459592)
		(end 133.33476 -201.6633)
		(width 0.14732)
		(layer "In6.Cu")
		(net "UPI_CPU0_CPU1_P0P1_DP<7>")
	)
	(segment
		(start 134.200138 -200.369424)
		(end 133.961124 -200.663302)
		(width 0.14732)
		(layer "In6.Cu")
		(net "UPI_CPU0_CPU1_P0P1_DP<7>")
	)
	(segment
		(start 133.749542 -201.153014)
		(end 133.545834 -201.173842)
		(width 0.14732)
		(layer "In6.Cu")
		(net "UPI_CPU0_CPU1_P0P1_DP<7>")
	)
	(segment
		(start 343.466674 -211.46897)
		(end 343.466674 -210.7438)
		(width 0.14732)
		(layer "In6.Cu")
		(net "UPI_CPU0_CPU1_P0P1_DP<7>")
	)
	(segment
		(start 147.33651 -188.04763)
		(end 146.825208 -188.30925)
		(width 0.14732)
		(layer "In6.Cu")
		(net "UPI_CPU0_CPU1_P0P1_DP<7>")
	)
	(segment
		(start 137.521188 -197.254876)
		(end 137.480802 -197.45579)
		(width 0.14732)
		(layer "In6.Cu")
		(net "UPI_CPU0_CPU1_P0P1_DP<7>")
	)
	(segment
		(start 135.80364 -198.39686)
		(end 134.615428 -199.85863)
		(width 0.14732)
		(layer "In6.Cu")
		(net "UPI_CPU0_CPU1_P0P1_DP<7>")
	)
	(segment
		(start 141.425168 -194.659504)
		(end 137.521188 -197.254876)
		(width 0.14732)
		(layer "In6.Cu")
		(net "UPI_CPU0_CPU1_P0P1_DP<7>")
	)
	(segment
		(start 137.480802 -197.45579)
		(end 137.17397 -197.659752)
		(width 0.14732)
		(layer "In6.Cu")
		(net "UPI_CPU0_CPU1_P0P1_DP<7>")
	)
	(segment
		(start 212.438488 -183.46674)
		(end 200.230486 -182.930292)
		(width 0.14732)
		(layer "In6.Cu")
		(net "UPI_CPU0_CPU1_P0P1_DP<7>")
	)
	(segment
		(start 146.76247 -188.504068)
		(end 146.434302 -188.671962)
		(width 0.14732)
		(layer "In6.Cu")
		(net "UPI_CPU0_CPU1_P0P1_DP<7>")
	)
	(segment
		(start 343.508838 -213.892892)
		(end 343.508838 -211.657438)
		(width 0.0889)
		(layer "In6.Cu")
		(net "UPI_CPU0_CPU1_P0P1_DP<7>")
	)
	(segment
		(start 146.434302 -188.671962)
		(end 146.239484 -188.60897)
		(width 0.14732)
		(layer "In6.Cu")
		(net "UPI_CPU0_CPU1_P0P1_DP<7>")
	)
	(segment
		(start 343.508584 -213.8934)
		(end 343.508838 -213.892892)
		(width 0.0889)
		(layer "In6.Cu")
		(net "UPI_CPU0_CPU1_P0P1_DP<7>")
	)
	(segment
		(start 128.693926 -211.547202)
		(end 128.693926 -211.77123)
		(width 0.14732)
		(layer "In6.Cu")
		(net "UPI_CPU0_CPU1_P0P1_DP<7>")
	)
	(segment
		(start 128.397508 -214.321644)
		(end 128.556258 -214.622634)
		(width 0.0889)
		(layer "In6.Cu")
		(net "UPI_CPU0_CPU1_P0P1_DP<7>")
	)
	(arc
		(start 128.63703 -213.96833)
		(mid 128.550479 -214.111364)
		(end 128.427734 -214.22487)
		(width 0.0889)
		(layer "In6.Cu")
		(net "UPI_CPU0_CPU1_P0P1_DP<7>")
	)
	(arc
		(start 128.652016 -213.929468)
		(mid 128.644858 -213.949028)
		(end 128.63703 -213.96833)
		(width 0.0889)
		(layer "In6.Cu")
		(net "UPI_CPU0_CPU1_P0P1_DP<7>")
	)
	(arc
		(start 343.038176 -214.425784)
		(mid 343.149616 -214.232389)
		(end 343.32418 -214.093298)
		(width 0.0889)
		(layer "In6.Cu")
		(net "UPI_CPU0_CPU1_P0P1_DP<7>")
	)
	(arc
		(start 343.32418 -214.093298)
		(mid 343.433576 -214.009201)
		(end 343.508584 -213.8934)
		(width 0.0889)
		(layer "In6.Cu")
		(net "UPI_CPU0_CPU1_P0P1_DP<7>")
	)
	(arc
		(start 343.266014 -215.076532)
		(mid 343.257442 -215.070009)
		(end 343.248996 -215.063324)
		(width 0.0889)
		(layer "In6.Cu")
		(net "UPI_CPU0_CPU1_P0P1_DP<7>")
	)
	(arc
		(start 343.248996 -215.063324)
		(mid 343.096565 -214.873342)
		(end 343.038176 -214.636858)
		(width 0.0889)
		(layer "In6.Cu")
		(net "UPI_CPU0_CPU1_P0P1_DP<7>")
	)
	(segment
		(start 342.66378 -214.622888)
		(end 342.663526 -214.622634)
		(width 0.13208)
		(layer "F.Cu")
		(net "UPI_CPU0_CPU1_P0P1_DP<6>")
	)
	(segment
		(start 342.66378 -215.158574)
		(end 342.66378 -214.622888)
		(width 0.13208)
		(layer "F.Cu")
		(net "UPI_CPU0_CPU1_P0P1_DP<6>")
	)
	(segment
		(start 129.026666 -215.972644)
		(end 129.026666 -215.436958)
		(width 0.13208)
		(layer "F.Cu")
		(net "UPI_CPU0_CPU1_P0P1_DP<6>")
	)
	(segment
		(start 129.026666 -215.436958)
		(end 129.026412 -215.436704)
		(width 0.13208)
		(layer "F.Cu")
		(net "UPI_CPU0_CPU1_P0P1_DP<6>")
	)
	(segment
		(start 342.801194 -211.66201)
		(end 342.801194 -210.874864)
		(width 0.14732)
		(layer "In6.Cu")
		(net "UPI_CPU0_CPU1_P0P1_DP<6>")
	)
	(segment
		(start 129.35966 -211.547202)
		(end 129.35966 -211.77123)
		(width 0.14732)
		(layer "In6.Cu")
		(net "UPI_CPU0_CPU1_P0P1_DP<6>")
	)
	(segment
		(start 342.504776 -214.321644)
		(end 342.535002 -214.22487)
		(width 0.0889)
		(layer "In6.Cu")
		(net "UPI_CPU0_CPU1_P0P1_DP<6>")
	)
	(segment
		(start 129.40157 -213.892892)
		(end 129.401316 -213.8934)
		(width 0.0889)
		(layer "In6.Cu")
		(net "UPI_CPU0_CPU1_P0P1_DP<6>")
	)
	(segment
		(start 314.25261 -184.022746)
		(end 312.394346 -183.439054)
		(width 0.14732)
		(layer "In6.Cu")
		(net "UPI_CPU0_CPU1_P0P1_DP<6>")
	)
	(segment
		(start 129.40157 -211.835238)
		(end 129.40157 -213.892892)
		(width 0.0889)
		(layer "In6.Cu")
		(net "UPI_CPU0_CPU1_P0P1_DP<6>")
	)
	(segment
		(start 131.727702 -204.315822)
		(end 129.359406 -211.078572)
		(width 0.14732)
		(layer "In6.Cu")
		(net "UPI_CPU0_CPU1_P0P1_DP<6>")
	)
	(segment
		(start 129.35966 -211.793328)
		(end 129.40157 -211.835238)
		(width 0.0889)
		(layer "In6.Cu")
		(net "UPI_CPU0_CPU1_P0P1_DP<6>")
	)
	(segment
		(start 342.759284 -213.929468)
		(end 342.759284 -211.726018)
		(width 0.0889)
		(layer "In6.Cu")
		(net "UPI_CPU0_CPU1_P0P1_DP<6>")
	)
	(segment
		(start 316.3062 -185.397902)
		(end 314.25261 -184.022746)
		(width 0.14732)
		(layer "In6.Cu")
		(net "UPI_CPU0_CPU1_P0P1_DP<6>")
	)
	(segment
		(start 132.91947 -202.850242)
		(end 131.727702 -204.315822)
		(width 0.14732)
		(layer "In6.Cu")
		(net "UPI_CPU0_CPU1_P0P1_DP<6>")
	)
	(segment
		(start 129.35966 -211.77123)
		(end 129.35966 -211.793328)
		(width 0.0889)
		(layer "In6.Cu")
		(net "UPI_CPU0_CPU1_P0P1_DP<6>")
	)
	(segment
		(start 322.287392 -190.63462)
		(end 319.60058 -188.993018)
		(width 0.14732)
		(layer "In6.Cu")
		(net "UPI_CPU0_CPU1_P0P1_DP<6>")
	)
	(segment
		(start 342.663526 -214.622634)
		(end 342.504776 -214.321644)
		(width 0.0889)
		(layer "In6.Cu")
		(net "UPI_CPU0_CPU1_P0P1_DP<6>")
	)
	(segment
		(start 336.883756 -199.317864)
		(end 332.360524 -195.759324)
		(width 0.14732)
		(layer "In6.Cu")
		(net "UPI_CPU0_CPU1_P0P1_DP<6>")
	)
	(segment
		(start 341.397844 -202.869292)
		(end 336.88401 -199.318118)
		(width 0.14732)
		(layer "In6.Cu")
		(net "UPI_CPU0_CPU1_P0P1_DP<6>")
	)
	(segment
		(start 159.463994 -184.164986)
		(end 152.850342 -185.857896)
		(width 0.14732)
		(layer "In6.Cu")
		(net "UPI_CPU0_CPU1_P0P1_DP<6>")
	)
	(segment
		(start 317.7032 -186.922664)
		(end 317.060834 -186.221624)
		(width 0.14732)
		(layer "In6.Cu")
		(net "UPI_CPU0_CPU1_P0P1_DP<6>")
	)
	(segment
		(start 342.801194 -210.874864)
		(end 342.80094 -210.875118)
		(width 0.14732)
		(layer "In6.Cu")
		(net "UPI_CPU0_CPU1_P0P1_DP<6>")
	)
	(segment
		(start 148.995384 -187.831476)
		(end 147.776438 -188.987176)
		(width 0.14732)
		(layer "In6.Cu")
		(net "UPI_CPU0_CPU1_P0P1_DP<6>")
	)
	(segment
		(start 342.80094 -210.875118)
		(end 342.80094 -210.774534)
		(width 0.14732)
		(layer "In6.Cu")
		(net "UPI_CPU0_CPU1_P0P1_DP<6>")
	)
	(segment
		(start 332.360524 -195.759324)
		(end 325.218552 -193.124582)
		(width 0.14732)
		(layer "In6.Cu")
		(net "UPI_CPU0_CPU1_P0P1_DP<6>")
	)
	(segment
		(start 319.60058 -188.993018)
		(end 317.703454 -186.922664)
		(width 0.14732)
		(layer "In6.Cu")
		(net "UPI_CPU0_CPU1_P0P1_DP<6>")
	)
	(segment
		(start 128.930908 -214.425784)
		(end 128.930908 -214.636858)
		(width 0.0889)
		(layer "In6.Cu")
		(net "UPI_CPU0_CPU1_P0P1_DP<6>")
	)
	(segment
		(start 273.237706 -183.96585)
		(end 238.63427 -184.130696)
		(width 0.14732)
		(layer "In6.Cu")
		(net "UPI_CPU0_CPU1_P0P1_DP<6>")
	)
	(segment
		(start 238.63427 -184.130696)
		(end 214.752936 -184.130696)
		(width 0.14732)
		(layer "In6.Cu")
		(net "UPI_CPU0_CPU1_P0P1_DP<6>")
	)
	(segment
		(start 129.158746 -215.076532)
		(end 129.182876 -215.165686)
		(width 0.0889)
		(layer "In6.Cu")
		(net "UPI_CPU0_CPU1_P0P1_DP<6>")
	)
	(segment
		(start 141.910054 -196.860922)
		(end 132.91947 -202.850242)
		(width 0.14732)
		(layer "In6.Cu")
		(net "UPI_CPU0_CPU1_P0P1_DP<6>")
	)
	(segment
		(start 342.801194 -211.684108)
		(end 342.801194 -211.66201)
		(width 0.0889)
		(layer "In6.Cu")
		(net "UPI_CPU0_CPU1_P0P1_DP<6>")
	)
	(segment
		(start 317.060834 -186.221116)
		(end 316.3062 -185.397902)
		(width 0.14732)
		(layer "In6.Cu")
		(net "UPI_CPU0_CPU1_P0P1_DP<6>")
	)
	(segment
		(start 302.508666 -183.256936)
		(end 273.237706 -183.96585)
		(width 0.14732)
		(layer "In6.Cu")
		(net "UPI_CPU0_CPU1_P0P1_DP<6>")
	)
	(segment
		(start 129.359406 -211.078572)
		(end 129.359406 -211.546948)
		(width 0.14732)
		(layer "In6.Cu")
		(net "UPI_CPU0_CPU1_P0P1_DP<6>")
	)
	(segment
		(start 342.759284 -211.726018)
		(end 342.801194 -211.684108)
		(width 0.0889)
		(layer "In6.Cu")
		(net "UPI_CPU0_CPU1_P0P1_DP<6>")
	)
	(segment
		(start 147.776438 -188.987176)
		(end 141.910054 -196.860922)
		(width 0.14732)
		(layer "In6.Cu")
		(net "UPI_CPU0_CPU1_P0P1_DP<6>")
	)
	(segment
		(start 324.882256 -192.839086)
		(end 322.287392 -190.63462)
		(width 0.14732)
		(layer "In6.Cu")
		(net "UPI_CPU0_CPU1_P0P1_DP<6>")
	)
	(segment
		(start 317.060834 -186.221624)
		(end 317.060834 -186.221116)
		(width 0.14732)
		(layer "In6.Cu")
		(net "UPI_CPU0_CPU1_P0P1_DP<6>")
	)
	(segment
		(start 317.703454 -186.922664)
		(end 317.7032 -186.922664)
		(width 0.14732)
		(layer "In6.Cu")
		(net "UPI_CPU0_CPU1_P0P1_DP<6>")
	)
	(segment
		(start 152.850342 -185.857896)
		(end 148.995384 -187.831476)
		(width 0.14732)
		(layer "In6.Cu")
		(net "UPI_CPU0_CPU1_P0P1_DP<6>")
	)
	(segment
		(start 200.156318 -183.489092)
		(end 159.463994 -184.164986)
		(width 0.14732)
		(layer "In6.Cu")
		(net "UPI_CPU0_CPU1_P0P1_DP<6>")
	)
	(segment
		(start 336.88401 -199.318118)
		(end 336.883756 -199.317864)
		(width 0.14732)
		(layer "In6.Cu")
		(net "UPI_CPU0_CPU1_P0P1_DP<6>")
	)
	(segment
		(start 325.218552 -193.124582)
		(end 324.882256 -192.839086)
		(width 0.14732)
		(layer "In6.Cu")
		(net "UPI_CPU0_CPU1_P0P1_DP<6>")
	)
	(segment
		(start 129.359406 -211.546948)
		(end 129.35966 -211.547202)
		(width 0.14732)
		(layer "In6.Cu")
		(net "UPI_CPU0_CPU1_P0P1_DP<6>")
	)
	(segment
		(start 129.182876 -215.165686)
		(end 129.026412 -215.436704)
		(width 0.0889)
		(layer "In6.Cu")
		(net "UPI_CPU0_CPU1_P0P1_DP<6>")
	)
	(segment
		(start 214.752936 -184.130696)
		(end 200.156318 -183.489092)
		(width 0.14732)
		(layer "In6.Cu")
		(net "UPI_CPU0_CPU1_P0P1_DP<6>")
	)
	(segment
		(start 342.80094 -210.774534)
		(end 342.0491 -203.671424)
		(width 0.14732)
		(layer "In6.Cu")
		(net "UPI_CPU0_CPU1_P0P1_DP<6>")
	)
	(segment
		(start 342.0491 -203.671424)
		(end 341.397844 -202.869292)
		(width 0.14732)
		(layer "In6.Cu")
		(net "UPI_CPU0_CPU1_P0P1_DP<6>")
	)
	(segment
		(start 312.394346 -183.439054)
		(end 302.508666 -183.256936)
		(width 0.14732)
		(layer "In6.Cu")
		(net "UPI_CPU0_CPU1_P0P1_DP<6>")
	)
	(arc
		(start 342.535002 -214.22487)
		(mid 342.657748 -214.111365)
		(end 342.744298 -213.96833)
		(width 0.0889)
		(layer "In6.Cu")
		(net "UPI_CPU0_CPU1_P0P1_DP<6>")
	)
	(arc
		(start 128.930908 -214.636858)
		(mid 128.989253 -214.873363)
		(end 129.141728 -215.063324)
		(width 0.0889)
		(layer "In6.Cu")
		(net "UPI_CPU0_CPU1_P0P1_DP<6>")
	)
	(arc
		(start 129.401316 -213.8934)
		(mid 129.326245 -214.009142)
		(end 129.216912 -214.093298)
		(width 0.0889)
		(layer "In6.Cu")
		(net "UPI_CPU0_CPU1_P0P1_DP<6>")
	)
	(arc
		(start 129.216912 -214.093298)
		(mid 129.042364 -214.232402)
		(end 128.930908 -214.425784)
		(width 0.0889)
		(layer "In6.Cu")
		(net "UPI_CPU0_CPU1_P0P1_DP<6>")
	)
	(arc
		(start 342.744298 -213.96833)
		(mid 342.752133 -213.949031)
		(end 342.759284 -213.929468)
		(width 0.0889)
		(layer "In6.Cu")
		(net "UPI_CPU0_CPU1_P0P1_DP<6>")
	)
	(arc
		(start 129.141728 -215.063324)
		(mid 129.150174 -215.070009)
		(end 129.158746 -215.076532)
		(width 0.0889)
		(layer "In6.Cu")
		(net "UPI_CPU0_CPU1_P0P1_DP<6>")
	)
	(segment
		(start 130.436112 -215.158574)
		(end 130.436112 -214.622888)
		(width 0.13208)
		(layer "F.Cu")
		(net "UPI_CPU0_CPU1_P0P1_DP<5>")
	)
	(segment
		(start 130.436112 -214.622888)
		(end 130.435858 -214.622634)
		(width 0.13208)
		(layer "F.Cu")
		(net "UPI_CPU0_CPU1_P0P1_DP<5>")
	)
	(segment
		(start 341.254334 -215.436958)
		(end 341.25408 -215.436704)
		(width 0.13208)
		(layer "F.Cu")
		(net "UPI_CPU0_CPU1_P0P1_DP<5>")
	)
	(segment
		(start 341.254334 -215.972644)
		(end 341.254334 -215.436958)
		(width 0.13208)
		(layer "F.Cu")
		(net "UPI_CPU0_CPU1_P0P1_DP<5>")
	)
	(segment
		(start 340.541356 -203.6064)
		(end 332.199234 -197.043548)
		(width 0.14732)
		(layer "In6.Cu")
		(net "UPI_CPU0_CPU1_P0P1_DP<5>")
	)
	(segment
		(start 341.587328 -211.684108)
		(end 341.587328 -211.66201)
		(width 0.0889)
		(layer "In6.Cu")
		(net "UPI_CPU0_CPU1_P0P1_DP<5>")
	)
	(segment
		(start 340.936072 -204.093064)
		(end 340.541356 -203.606654)
		(width 0.14732)
		(layer "In6.Cu")
		(net "UPI_CPU0_CPU1_P0P1_DP<5>")
	)
	(segment
		(start 130.531362 -213.93023)
		(end 130.531616 -213.929468)
		(width 0.0889)
		(layer "In6.Cu")
		(net "UPI_CPU0_CPU1_P0P1_DP<5>")
	)
	(segment
		(start 312.224166 -184.571132)
		(end 302.511968 -184.39257)
		(width 0.14732)
		(layer "In6.Cu")
		(net "UPI_CPU0_CPU1_P0P1_DP<5>")
	)
	(segment
		(start 131.034282 -209.698844)
		(end 130.912616 -210.046316)
		(width 0.14732)
		(layer "In6.Cu")
		(net "UPI_CPU0_CPU1_P0P1_DP<5>")
	)
	(segment
		(start 143.94434 -196.237606)
		(end 143.741648 -196.267324)
		(width 0.14732)
		(layer "In6.Cu")
		(net "UPI_CPU0_CPU1_P0P1_DP<5>")
	)
	(segment
		(start 132.741416 -204.824838)
		(end 131.930648 -207.14081)
		(width 0.14732)
		(layer "In6.Cu")
		(net "UPI_CPU0_CPU1_P0P1_DP<5>")
	)
	(segment
		(start 143.343884 -196.801232)
		(end 143.373602 -197.003924)
		(width 0.14732)
		(layer "In6.Cu")
		(net "UPI_CPU0_CPU1_P0P1_DP<5>")
	)
	(segment
		(start 341.629238 -211.726018)
		(end 341.587328 -211.684108)
		(width 0.0889)
		(layer "In6.Cu")
		(net "UPI_CPU0_CPU1_P0P1_DP<5>")
	)
	(segment
		(start 130.573526 -211.64931)
		(end 130.573526 -211.671408)
		(width 0.0889)
		(layer "In6.Cu")
		(net "UPI_CPU0_CPU1_P0P1_DP<5>")
	)
	(segment
		(start 131.930648 -207.14081)
		(end 132.019294 -207.325214)
		(width 0.14732)
		(layer "In6.Cu")
		(net "UPI_CPU0_CPU1_P0P1_DP<5>")
	)
	(segment
		(start 148.624544 -189.712854)
		(end 144.13484 -195.739512)
		(width 0.14732)
		(layer "In6.Cu")
		(net "UPI_CPU0_CPU1_P0P1_DP<5>")
	)
	(segment
		(start 131.591304 -208.109312)
		(end 131.67995 -208.293716)
		(width 0.14732)
		(layer "In6.Cu")
		(net "UPI_CPU0_CPU1_P0P1_DP<5>")
	)
	(segment
		(start 131.340606 -209.262218)
		(end 131.21894 -209.609944)
		(width 0.14732)
		(layer "In6.Cu")
		(net "UPI_CPU0_CPU1_P0P1_DP<5>")
	)
	(segment
		(start 130.277108 -214.321644)
		(end 130.435858 -214.622634)
		(width 0.0889)
		(layer "In6.Cu")
		(net "UPI_CPU0_CPU1_P0P1_DP<5>")
	)
	(segment
		(start 131.558284 -208.641442)
		(end 131.373626 -208.730342)
		(width 0.14732)
		(layer "In6.Cu")
		(net "UPI_CPU0_CPU1_P0P1_DP<5>")
	)
	(segment
		(start 332.199234 -197.043548)
		(end 326.513952 -194.97294)
		(width 0.14732)
		(layer "In6.Cu")
		(net "UPI_CPU0_CPU1_P0P1_DP<5>")
	)
	(segment
		(start 318.348868 -190.844678)
		(end 315.498734 -186.185048)
		(width 0.14732)
		(layer "In6.Cu")
		(net "UPI_CPU0_CPU1_P0P1_DP<5>")
	)
	(segment
		(start 130.307334 -214.22487)
		(end 130.277108 -214.321644)
		(width 0.0889)
		(layer "In6.Cu")
		(net "UPI_CPU0_CPU1_P0P1_DP<5>")
	)
	(segment
		(start 131.67995 -208.293716)
		(end 131.558284 -208.641442)
		(width 0.14732)
		(layer "In6.Cu")
		(net "UPI_CPU0_CPU1_P0P1_DP<5>")
	)
	(segment
		(start 131.71297 -207.76184)
		(end 131.591304 -208.109312)
		(width 0.14732)
		(layer "In6.Cu")
		(net "UPI_CPU0_CPU1_P0P1_DP<5>")
	)
	(segment
		(start 130.573272 -211.014818)
		(end 130.573272 -211.191348)
		(width 0.14732)
		(layer "In6.Cu")
		(net "UPI_CPU0_CPU1_P0P1_DP<5>")
	)
	(segment
		(start 132.019294 -207.325214)
		(end 131.897628 -207.67294)
		(width 0.14732)
		(layer "In6.Cu")
		(net "UPI_CPU0_CPU1_P0P1_DP<5>")
	)
	(segment
		(start 200.35647 -184.606692)
		(end 159.56026 -185.283856)
		(width 0.14732)
		(layer "In6.Cu")
		(net "UPI_CPU0_CPU1_P0P1_DP<5>")
	)
	(segment
		(start 130.694938 -210.667346)
		(end 130.573272 -211.014818)
		(width 0.14732)
		(layer "In6.Cu")
		(net "UPI_CPU0_CPU1_P0P1_DP<5>")
	)
	(segment
		(start 131.373626 -208.730342)
		(end 131.25196 -209.077814)
		(width 0.14732)
		(layer "In6.Cu")
		(net "UPI_CPU0_CPU1_P0P1_DP<5>")
	)
	(segment
		(start 341.587074 -211.53755)
		(end 341.587074 -210.23834)
		(width 0.14732)
		(layer "In6.Cu")
		(net "UPI_CPU0_CPU1_P0P1_DP<5>")
	)
	(segment
		(start 319.5955 -191.802004)
		(end 318.348868 -190.844678)
		(width 0.14732)
		(layer "In6.Cu")
		(net "UPI_CPU0_CPU1_P0P1_DP<5>")
	)
	(segment
		(start 341.629238 -213.892892)
		(end 341.629238 -211.726018)
		(width 0.0889)
		(layer "In6.Cu")
		(net "UPI_CPU0_CPU1_P0P1_DP<5>")
	)
	(segment
		(start 326.513952 -194.97294)
		(end 319.5955 -191.802004)
		(width 0.14732)
		(layer "In6.Cu")
		(net "UPI_CPU0_CPU1_P0P1_DP<5>")
	)
	(segment
		(start 144.13484 -195.739512)
		(end 144.164558 -195.942204)
		(width 0.14732)
		(layer "In6.Cu")
		(net "UPI_CPU0_CPU1_P0P1_DP<5>")
	)
	(segment
		(start 131.21894 -209.609944)
		(end 131.034282 -209.698844)
		(width 0.14732)
		(layer "In6.Cu")
		(net "UPI_CPU0_CPU1_P0P1_DP<5>")
	)
	(segment
		(start 341.158576 -214.636858)
		(end 341.158576 -214.425784)
		(width 0.0889)
		(layer "In6.Cu")
		(net "UPI_CPU0_CPU1_P0P1_DP<5>")
	)
	(segment
		(start 130.879596 -210.578446)
		(end 130.694938 -210.667346)
		(width 0.14732)
		(layer "In6.Cu")
		(net "UPI_CPU0_CPU1_P0P1_DP<5>")
	)
	(segment
		(start 144.164558 -195.942204)
		(end 143.94434 -196.237606)
		(width 0.14732)
		(layer "In6.Cu")
		(net "UPI_CPU0_CPU1_P0P1_DP<5>")
	)
	(segment
		(start 341.587074 -210.23834)
		(end 340.936072 -204.093064)
		(width 0.14732)
		(layer "In6.Cu")
		(net "UPI_CPU0_CPU1_P0P1_DP<5>")
	)
	(segment
		(start 130.573272 -211.191348)
		(end 130.573526 -211.191602)
		(width 0.14732)
		(layer "In6.Cu")
		(net "UPI_CPU0_CPU1_P0P1_DP<5>")
	)
	(segment
		(start 133.666992 -203.686664)
		(end 132.741416 -204.824838)
		(width 0.14732)
		(layer "In6.Cu")
		(net "UPI_CPU0_CPU1_P0P1_DP<5>")
	)
	(segment
		(start 130.531362 -211.713572)
		(end 130.531362 -213.93023)
		(width 0.0889)
		(layer "In6.Cu")
		(net "UPI_CPU0_CPU1_P0P1_DP<5>")
	)
	(segment
		(start 143.741648 -196.267324)
		(end 143.343884 -196.801232)
		(width 0.14732)
		(layer "In6.Cu")
		(net "UPI_CPU0_CPU1_P0P1_DP<5>")
	)
	(segment
		(start 149.649942 -188.741304)
		(end 148.624544 -189.712854)
		(width 0.14732)
		(layer "In6.Cu")
		(net "UPI_CPU0_CPU1_P0P1_DP<5>")
	)
	(segment
		(start 313.842654 -185.07837)
		(end 312.224166 -184.571132)
		(width 0.14732)
		(layer "In6.Cu")
		(net "UPI_CPU0_CPU1_P0P1_DP<5>")
	)
	(segment
		(start 143.153384 -197.29958)
		(end 142.950692 -197.329044)
		(width 0.14732)
		(layer "In6.Cu")
		(net "UPI_CPU0_CPU1_P0P1_DP<5>")
	)
	(segment
		(start 315.498734 -186.185048)
		(end 313.842654 -185.07837)
		(width 0.14732)
		(layer "In6.Cu")
		(net "UPI_CPU0_CPU1_P0P1_DP<5>")
	)
	(segment
		(start 131.001516 -210.23072)
		(end 130.879596 -210.578446)
		(width 0.14732)
		(layer "In6.Cu")
		(net "UPI_CPU0_CPU1_P0P1_DP<5>")
	)
	(segment
		(start 142.950692 -197.329044)
		(end 142.676118 -197.697598)
		(width 0.14732)
		(layer "In6.Cu")
		(net "UPI_CPU0_CPU1_P0P1_DP<5>")
	)
	(segment
		(start 341.628984 -213.8934)
		(end 341.629238 -213.892892)
		(width 0.0889)
		(layer "In6.Cu")
		(net "UPI_CPU0_CPU1_P0P1_DP<5>")
	)
	(segment
		(start 130.573526 -211.191602)
		(end 130.573526 -211.64931)
		(width 0.14732)
		(layer "In6.Cu")
		(net "UPI_CPU0_CPU1_P0P1_DP<5>")
	)
	(segment
		(start 130.573526 -211.671408)
		(end 130.531362 -211.713572)
		(width 0.0889)
		(layer "In6.Cu")
		(net "UPI_CPU0_CPU1_P0P1_DP<5>")
	)
	(segment
		(start 238.637318 -185.265568)
		(end 215.349582 -185.265568)
		(width 0.14732)
		(layer "In6.Cu")
		(net "UPI_CPU0_CPU1_P0P1_DP<5>")
	)
	(segment
		(start 131.25196 -209.077814)
		(end 131.340606 -209.262218)
		(width 0.14732)
		(layer "In6.Cu")
		(net "UPI_CPU0_CPU1_P0P1_DP<5>")
	)
	(segment
		(start 341.25408 -215.436704)
		(end 341.410544 -215.165686)
		(width 0.0889)
		(layer "In6.Cu")
		(net "UPI_CPU0_CPU1_P0P1_DP<5>")
	)
	(segment
		(start 341.410544 -215.165686)
		(end 341.386414 -215.076532)
		(width 0.0889)
		(layer "In6.Cu")
		(net "UPI_CPU0_CPU1_P0P1_DP<5>")
	)
	(segment
		(start 341.587328 -211.537296)
		(end 341.587074 -211.53755)
		(width 0.14732)
		(layer "In6.Cu")
		(net "UPI_CPU0_CPU1_P0P1_DP<5>")
	)
	(segment
		(start 302.511968 -184.39257)
		(end 273.254216 -185.100722)
		(width 0.14732)
		(layer "In6.Cu")
		(net "UPI_CPU0_CPU1_P0P1_DP<5>")
	)
	(segment
		(start 273.254216 -185.100722)
		(end 238.637318 -185.265568)
		(width 0.14732)
		(layer "In6.Cu")
		(net "UPI_CPU0_CPU1_P0P1_DP<5>")
	)
	(segment
		(start 341.587328 -211.66201)
		(end 341.587328 -211.537296)
		(width 0.14732)
		(layer "In6.Cu")
		(net "UPI_CPU0_CPU1_P0P1_DP<5>")
	)
	(segment
		(start 215.349582 -185.265568)
		(end 200.35647 -184.606692)
		(width 0.14732)
		(layer "In6.Cu")
		(net "UPI_CPU0_CPU1_P0P1_DP<5>")
	)
	(segment
		(start 159.56026 -185.283856)
		(end 153.246074 -186.90082)
		(width 0.14732)
		(layer "In6.Cu")
		(net "UPI_CPU0_CPU1_P0P1_DP<5>")
	)
	(segment
		(start 340.541356 -203.606654)
		(end 340.541356 -203.6064)
		(width 0.14732)
		(layer "In6.Cu")
		(net "UPI_CPU0_CPU1_P0P1_DP<5>")
	)
	(segment
		(start 143.373602 -197.003924)
		(end 143.153384 -197.29958)
		(width 0.14732)
		(layer "In6.Cu")
		(net "UPI_CPU0_CPU1_P0P1_DP<5>")
	)
	(segment
		(start 131.897628 -207.67294)
		(end 131.71297 -207.76184)
		(width 0.14732)
		(layer "In6.Cu")
		(net "UPI_CPU0_CPU1_P0P1_DP<5>")
	)
	(segment
		(start 142.676118 -197.697598)
		(end 133.666992 -203.686664)
		(width 0.14732)
		(layer "In6.Cu")
		(net "UPI_CPU0_CPU1_P0P1_DP<5>")
	)
	(segment
		(start 130.912616 -210.046316)
		(end 131.001516 -210.23072)
		(width 0.14732)
		(layer "In6.Cu")
		(net "UPI_CPU0_CPU1_P0P1_DP<5>")
	)
	(segment
		(start 153.246074 -186.90082)
		(end 149.649942 -188.741304)
		(width 0.14732)
		(layer "In6.Cu")
		(net "UPI_CPU0_CPU1_P0P1_DP<5>")
	)
	(arc
		(start 130.531616 -213.929468)
		(mid 130.524458 -213.949028)
		(end 130.51663 -213.96833)
		(width 0.0889)
		(layer "In6.Cu")
		(net "UPI_CPU0_CPU1_P0P1_DP<5>")
	)
	(arc
		(start 341.158576 -214.425784)
		(mid 341.270016 -214.232389)
		(end 341.44458 -214.093298)
		(width 0.0889)
		(layer "In6.Cu")
		(net "UPI_CPU0_CPU1_P0P1_DP<5>")
	)
	(arc
		(start 341.386414 -215.076532)
		(mid 341.377842 -215.070009)
		(end 341.369396 -215.063324)
		(width 0.0889)
		(layer "In6.Cu")
		(net "UPI_CPU0_CPU1_P0P1_DP<5>")
	)
	(arc
		(start 341.44458 -214.093298)
		(mid 341.553976 -214.009201)
		(end 341.628984 -213.8934)
		(width 0.0889)
		(layer "In6.Cu")
		(net "UPI_CPU0_CPU1_P0P1_DP<5>")
	)
	(arc
		(start 341.369396 -215.063324)
		(mid 341.216965 -214.873342)
		(end 341.158576 -214.636858)
		(width 0.0889)
		(layer "In6.Cu")
		(net "UPI_CPU0_CPU1_P0P1_DP<5>")
	)
	(arc
		(start 130.51663 -213.96833)
		(mid 130.430079 -214.111364)
		(end 130.307334 -214.22487)
		(width 0.0889)
		(layer "In6.Cu")
		(net "UPI_CPU0_CPU1_P0P1_DP<5>")
	)
	(segment
		(start 130.906266 -215.972644)
		(end 130.906266 -215.436958)
		(width 0.13208)
		(layer "F.Cu")
		(net "UPI_CPU0_CPU1_P0P1_DP<4>")
	)
	(segment
		(start 340.78418 -215.158574)
		(end 340.78418 -214.622888)
		(width 0.13208)
		(layer "F.Cu")
		(net "UPI_CPU0_CPU1_P0P1_DP<4>")
	)
	(segment
		(start 340.78418 -214.622888)
		(end 340.783926 -214.622634)
		(width 0.13208)
		(layer "F.Cu")
		(net "UPI_CPU0_CPU1_P0P1_DP<4>")
	)
	(segment
		(start 130.906266 -215.436958)
		(end 130.906012 -215.436704)
		(width 0.13208)
		(layer "F.Cu")
		(net "UPI_CPU0_CPU1_P0P1_DP<4>")
	)
	(segment
		(start 255.011682 -185.809636)
		(end 215.533732 -185.898536)
		(width 0.14732)
		(layer "In6.Cu")
		(net "UPI_CPU0_CPU1_P0P1_DP<4>")
	)
	(segment
		(start 339.936328 -203.849478)
		(end 339.936328 -203.849224)
		(width 0.14732)
		(layer "In6.Cu")
		(net "UPI_CPU0_CPU1_P0P1_DP<4>")
	)
	(segment
		(start 131.038346 -215.076532)
		(end 131.062476 -215.165686)
		(width 0.0889)
		(layer "In6.Cu")
		(net "UPI_CPU0_CPU1_P0P1_DP<4>")
	)
	(segment
		(start 148.962618 -191.572642)
		(end 148.352764 -192.11798)
		(width 0.14732)
		(layer "In6.Cu")
		(net "UPI_CPU0_CPU1_P0P1_DP<4>")
	)
	(segment
		(start 142.92199 -198.938642)
		(end 136.79932 -207.642968)
		(width 0.14732)
		(layer "In6.Cu")
		(net "UPI_CPU0_CPU1_P0P1_DP<4>")
	)
	(segment
		(start 153.524458 -189.495684)
		(end 152.044654 -190.819024)
		(width 0.14732)
		(layer "In6.Cu")
		(net "UPI_CPU0_CPU1_P0P1_DP<4>")
	)
	(segment
		(start 331.953108 -197.560438)
		(end 326.281542 -195.485766)
		(width 0.14732)
		(layer "In6.Cu")
		(net "UPI_CPU0_CPU1_P0P1_DP<4>")
	)
	(segment
		(start 131.062476 -215.165686)
		(end 130.906012 -215.436704)
		(width 0.0889)
		(layer "In6.Cu")
		(net "UPI_CPU0_CPU1_P0P1_DP<4>")
	)
	(segment
		(start 340.783926 -214.622634)
		(end 340.625176 -214.321644)
		(width 0.0889)
		(layer "In6.Cu")
		(net "UPI_CPU0_CPU1_P0P1_DP<4>")
	)
	(segment
		(start 215.533732 -185.898536)
		(end 200.608184 -185.174382)
		(width 0.14732)
		(layer "In6.Cu")
		(net "UPI_CPU0_CPU1_P0P1_DP<4>")
	)
	(segment
		(start 302.24984 -184.96788)
		(end 273.21129 -185.768742)
		(width 0.14732)
		(layer "In6.Cu")
		(net "UPI_CPU0_CPU1_P0P1_DP<4>")
	)
	(segment
		(start 155.14193 -187.318142)
		(end 155.14193 -187.317888)
		(width 0.14732)
		(layer "In6.Cu")
		(net "UPI_CPU0_CPU1_P0P1_DP<4>")
	)
	(segment
		(start 149.396958 -191.597026)
		(end 148.962618 -191.572642)
		(width 0.14732)
		(layer "In6.Cu")
		(net "UPI_CPU0_CPU1_P0P1_DP<4>")
	)
	(segment
		(start 147.23491 -193.11747)
		(end 146.625056 -193.662808)
		(width 0.14732)
		(layer "In6.Cu")
		(net "UPI_CPU0_CPU1_P0P1_DP<4>")
	)
	(segment
		(start 340.921594 -211.783168)
		(end 340.921594 -211.76107)
		(width 0.0889)
		(layer "In6.Cu")
		(net "UPI_CPU0_CPU1_P0P1_DP<4>")
	)
	(segment
		(start 340.879684 -213.929468)
		(end 340.879684 -211.825078)
		(width 0.0889)
		(layer "In6.Cu")
		(net "UPI_CPU0_CPU1_P0P1_DP<4>")
	)
	(segment
		(start 340.625176 -214.321644)
		(end 340.655402 -214.22487)
		(width 0.0889)
		(layer "In6.Cu")
		(net "UPI_CPU0_CPU1_P0P1_DP<4>")
	)
	(segment
		(start 312.11393 -185.153554)
		(end 302.478186 -184.96788)
		(width 0.14732)
		(layer "In6.Cu")
		(net "UPI_CPU0_CPU1_P0P1_DP<4>")
	)
	(segment
		(start 148.989796 -193.513202)
		(end 148.550122 -193.906394)
		(width 0.14732)
		(layer "In6.Cu")
		(net "UPI_CPU0_CPU1_P0P1_DP<4>")
	)
	(segment
		(start 131.28117 -213.221062)
		(end 131.28117 -213.892892)
		(width 0.0889)
		(layer "In6.Cu")
		(net "UPI_CPU0_CPU1_P0P1_DP<4>")
	)
	(segment
		(start 150.27783 -192.361566)
		(end 150.070058 -192.349882)
		(width 0.14732)
		(layer "In6.Cu")
		(net "UPI_CPU0_CPU1_P0P1_DP<4>")
	)
	(segment
		(start 200.608184 -185.174382)
		(end 159.592772 -185.862468)
		(width 0.14732)
		(layer "In6.Cu")
		(net "UPI_CPU0_CPU1_P0P1_DP<4>")
	)
	(segment
		(start 151.124666 -190.052198)
		(end 150.690326 -190.027814)
		(width 0.14732)
		(layer "In6.Cu")
		(net "UPI_CPU0_CPU1_P0P1_DP<4>")
	)
	(segment
		(start 159.592772 -185.862468)
		(end 155.14193 -187.318142)
		(width 0.14732)
		(layer "In6.Cu")
		(net "UPI_CPU0_CPU1_P0P1_DP<4>")
	)
	(segment
		(start 148.352764 -192.11798)
		(end 148.32838 -192.552574)
		(width 0.14732)
		(layer "In6.Cu")
		(net "UPI_CPU0_CPU1_P0P1_DP<4>")
	)
	(segment
		(start 150.070058 -192.349882)
		(end 149.396958 -191.597026)
		(width 0.14732)
		(layer "In6.Cu")
		(net "UPI_CPU0_CPU1_P0P1_DP<4>")
	)
	(segment
		(start 339.917024 -203.825602)
		(end 331.953108 -197.560438)
		(width 0.14732)
		(layer "In6.Cu")
		(net "UPI_CPU0_CPU1_P0P1_DP<4>")
	)
	(segment
		(start 147.66925 -193.141854)
		(end 147.23491 -193.11747)
		(width 0.14732)
		(layer "In6.Cu")
		(net "UPI_CPU0_CPU1_P0P1_DP<4>")
	)
	(segment
		(start 339.936328 -203.849224)
		(end 339.917024 -203.825602)
		(width 0.14732)
		(layer "In6.Cu")
		(net "UPI_CPU0_CPU1_P0P1_DP<4>")
	)
	(segment
		(start 315.043566 -186.563254)
		(end 313.569096 -185.601356)
		(width 0.14732)
		(layer "In6.Cu")
		(net "UPI_CPU0_CPU1_P0P1_DP<4>")
	)
	(segment
		(start 317.977266 -191.341248)
		(end 316.540642 -189.001908)
		(width 0.14732)
		(layer "In6.Cu")
		(net "UPI_CPU0_CPU1_P0P1_DP<4>")
	)
	(segment
		(start 340.921594 -211.76107)
		(end 340.921594 -209.759296)
		(width 0.14732)
		(layer "In6.Cu")
		(net "UPI_CPU0_CPU1_P0P1_DP<4>")
	)
	(segment
		(start 148.34235 -193.89471)
		(end 147.66925 -193.141854)
		(width 0.14732)
		(layer "In6.Cu")
		(net "UPI_CPU0_CPU1_P0P1_DP<4>")
	)
	(segment
		(start 255.013206 -185.809636)
		(end 255.011682 -185.809636)
		(width 0.14732)
		(layer "In6.Cu")
		(net "UPI_CPU0_CPU1_P0P1_DP<4>")
	)
	(segment
		(start 155.14193 -187.317888)
		(end 153.848562 -188.489844)
		(width 0.14732)
		(layer "In6.Cu")
		(net "UPI_CPU0_CPU1_P0P1_DP<4>")
	)
	(segment
		(start 147.262088 -195.05803)
		(end 142.92199 -198.938642)
		(width 0.14732)
		(layer "In6.Cu")
		(net "UPI_CPU0_CPU1_P0P1_DP<4>")
	)
	(segment
		(start 147.273772 -194.850258)
		(end 147.262088 -195.05803)
		(width 0.14732)
		(layer "In6.Cu")
		(net "UPI_CPU0_CPU1_P0P1_DP<4>")
	)
	(segment
		(start 316.540642 -189.001908)
		(end 316.540896 -189.001908)
		(width 0.14732)
		(layer "In6.Cu")
		(net "UPI_CPU0_CPU1_P0P1_DP<4>")
	)
	(segment
		(start 313.569096 -185.601356)
		(end 312.11393 -185.153554)
		(width 0.14732)
		(layer "In6.Cu")
		(net "UPI_CPU0_CPU1_P0P1_DP<4>")
	)
	(segment
		(start 133.696202 -210.747102)
		(end 133.680708 -210.762596)
		(width 0.0889)
		(layer "In6.Cu")
		(net "UPI_CPU0_CPU1_P0P1_DP<4>")
	)
	(segment
		(start 131.28117 -213.892892)
		(end 131.280916 -213.8934)
		(width 0.0889)
		(layer "In6.Cu")
		(net "UPI_CPU0_CPU1_P0P1_DP<4>")
	)
	(segment
		(start 150.056088 -191.007746)
		(end 150.729188 -191.760602)
		(width 0.14732)
		(layer "In6.Cu")
		(net "UPI_CPU0_CPU1_P0P1_DP<4>")
	)
	(segment
		(start 152.044654 -190.819024)
		(end 151.797766 -190.805054)
		(width 0.14732)
		(layer "In6.Cu")
		(net "UPI_CPU0_CPU1_P0P1_DP<4>")
	)
	(segment
		(start 130.810508 -214.425784)
		(end 130.810508 -214.636858)
		(width 0.0889)
		(layer "In6.Cu")
		(net "UPI_CPU0_CPU1_P0P1_DP<4>")
	)
	(segment
		(start 273.21129 -185.768742)
		(end 255.013206 -185.809636)
		(width 0.14732)
		(layer "In6.Cu")
		(net "UPI_CPU0_CPU1_P0P1_DP<4>")
	)
	(segment
		(start 340.879684 -211.825078)
		(end 340.921594 -211.783168)
		(width 0.0889)
		(layer "In6.Cu")
		(net "UPI_CPU0_CPU1_P0P1_DP<4>")
	)
	(segment
		(start 146.625056 -193.662808)
		(end 146.600672 -194.097402)
		(width 0.14732)
		(layer "In6.Cu")
		(net "UPI_CPU0_CPU1_P0P1_DP<4>")
	)
	(segment
		(start 148.550122 -193.906394)
		(end 148.34235 -193.89471)
		(width 0.14732)
		(layer "In6.Cu")
		(net "UPI_CPU0_CPU1_P0P1_DP<4>")
	)
	(segment
		(start 150.690326 -190.027814)
		(end 150.080472 -190.573152)
		(width 0.14732)
		(layer "In6.Cu")
		(net "UPI_CPU0_CPU1_P0P1_DP<4>")
	)
	(segment
		(start 148.32838 -192.552574)
		(end 149.00148 -193.30543)
		(width 0.14732)
		(layer "In6.Cu")
		(net "UPI_CPU0_CPU1_P0P1_DP<4>")
	)
	(segment
		(start 149.00148 -193.30543)
		(end 148.989796 -193.513202)
		(width 0.14732)
		(layer "In6.Cu")
		(net "UPI_CPU0_CPU1_P0P1_DP<4>")
	)
	(segment
		(start 134.609078 -209.83321)
		(end 134.609078 -209.834226)
		(width 0.14732)
		(layer "In6.Cu")
		(net "UPI_CPU0_CPU1_P0P1_DP<4>")
	)
	(segment
		(start 134.609078 -209.834226)
		(end 133.696202 -210.747102)
		(width 0.14732)
		(layer "In6.Cu")
		(net "UPI_CPU0_CPU1_P0P1_DP<4>")
	)
	(segment
		(start 136.79932 -207.642968)
		(end 134.609078 -209.83321)
		(width 0.14732)
		(layer "In6.Cu")
		(net "UPI_CPU0_CPU1_P0P1_DP<4>")
	)
	(segment
		(start 150.080472 -190.573152)
		(end 150.056088 -191.007746)
		(width 0.14732)
		(layer "In6.Cu")
		(net "UPI_CPU0_CPU1_P0P1_DP<4>")
	)
	(segment
		(start 153.848562 -188.489844)
		(end 153.524458 -189.495684)
		(width 0.14732)
		(layer "In6.Cu")
		(net "UPI_CPU0_CPU1_P0P1_DP<4>")
	)
	(segment
		(start 340.921594 -209.759296)
		(end 340.349586 -204.35824)
		(width 0.14732)
		(layer "In6.Cu")
		(net "UPI_CPU0_CPU1_P0P1_DP<4>")
	)
	(segment
		(start 150.717504 -191.968374)
		(end 150.27783 -192.361566)
		(width 0.14732)
		(layer "In6.Cu")
		(net "UPI_CPU0_CPU1_P0P1_DP<4>")
	)
	(segment
		(start 319.26784 -192.26784)
		(end 317.977266 -191.341248)
		(width 0.14732)
		(layer "In6.Cu")
		(net "UPI_CPU0_CPU1_P0P1_DP<4>")
	)
	(segment
		(start 150.729188 -191.760602)
		(end 150.717504 -191.968374)
		(width 0.14732)
		(layer "In6.Cu")
		(net "UPI_CPU0_CPU1_P0P1_DP<4>")
	)
	(segment
		(start 326.281542 -195.485766)
		(end 319.26784 -192.26784)
		(width 0.14732)
		(layer "In6.Cu")
		(net "UPI_CPU0_CPU1_P0P1_DP<4>")
	)
	(segment
		(start 340.349586 -204.35824)
		(end 339.936328 -203.849478)
		(width 0.14732)
		(layer "In6.Cu")
		(net "UPI_CPU0_CPU1_P0P1_DP<4>")
	)
	(segment
		(start 146.600672 -194.097402)
		(end 147.273772 -194.850258)
		(width 0.14732)
		(layer "In6.Cu")
		(net "UPI_CPU0_CPU1_P0P1_DP<4>")
	)
	(segment
		(start 151.797766 -190.805054)
		(end 151.124666 -190.052198)
		(width 0.14732)
		(layer "In6.Cu")
		(net "UPI_CPU0_CPU1_P0P1_DP<4>")
	)
	(segment
		(start 316.540896 -189.001908)
		(end 315.043566 -186.563254)
		(width 0.14732)
		(layer "In6.Cu")
		(net "UPI_CPU0_CPU1_P0P1_DP<4>")
	)
	(segment
		(start 133.680708 -210.821524)
		(end 131.28117 -213.221062)
		(width 0.0889)
		(layer "In6.Cu")
		(net "UPI_CPU0_CPU1_P0P1_DP<4>")
	)
	(segment
		(start 302.478186 -184.96788)
		(end 302.24984 -184.96788)
		(width 0.14732)
		(layer "In6.Cu")
		(net "UPI_CPU0_CPU1_P0P1_DP<4>")
	)
	(segment
		(start 133.680708 -210.762596)
		(end 133.680708 -210.821524)
		(width 0.0889)
		(layer "In6.Cu")
		(net "UPI_CPU0_CPU1_P0P1_DP<4>")
	)
	(arc
		(start 131.021328 -215.063324)
		(mid 131.029774 -215.070009)
		(end 131.038346 -215.076532)
		(width 0.0889)
		(layer "In6.Cu")
		(net "UPI_CPU0_CPU1_P0P1_DP<4>")
	)
	(arc
		(start 130.810508 -214.636858)
		(mid 130.868853 -214.873363)
		(end 131.021328 -215.063324)
		(width 0.0889)
		(layer "In6.Cu")
		(net "UPI_CPU0_CPU1_P0P1_DP<4>")
	)
	(arc
		(start 340.864698 -213.96833)
		(mid 340.872533 -213.949031)
		(end 340.879684 -213.929468)
		(width 0.0889)
		(layer "In6.Cu")
		(net "UPI_CPU0_CPU1_P0P1_DP<4>")
	)
	(arc
		(start 340.655402 -214.22487)
		(mid 340.778148 -214.111365)
		(end 340.864698 -213.96833)
		(width 0.0889)
		(layer "In6.Cu")
		(net "UPI_CPU0_CPU1_P0P1_DP<4>")
	)
	(arc
		(start 131.096512 -214.093298)
		(mid 130.921964 -214.232402)
		(end 130.810508 -214.425784)
		(width 0.0889)
		(layer "In6.Cu")
		(net "UPI_CPU0_CPU1_P0P1_DP<4>")
	)
	(arc
		(start 131.280916 -213.8934)
		(mid 131.205845 -214.009142)
		(end 131.096512 -214.093298)
		(width 0.0889)
		(layer "In6.Cu")
		(net "UPI_CPU0_CPU1_P0P1_DP<4>")
	)
	(segment
		(start 339.374734 -215.972644)
		(end 339.374734 -215.436958)
		(width 0.13208)
		(layer "F.Cu")
		(net "UPI_CPU0_CPU1_P0P1_DP<3>")
	)
	(segment
		(start 132.315712 -214.622888)
		(end 132.315458 -214.622634)
		(width 0.13208)
		(layer "F.Cu")
		(net "UPI_CPU0_CPU1_P0P1_DP<3>")
	)
	(segment
		(start 339.374734 -215.436958)
		(end 339.37448 -215.436704)
		(width 0.13208)
		(layer "F.Cu")
		(net "UPI_CPU0_CPU1_P0P1_DP<3>")
	)
	(segment
		(start 132.315712 -215.158574)
		(end 132.315712 -214.622888)
		(width 0.13208)
		(layer "F.Cu")
		(net "UPI_CPU0_CPU1_P0P1_DP<3>")
	)
	(segment
		(start 133.892036 -212.177884)
		(end 133.892036 -212.318346)
		(width 0.0889)
		(layer "In6.Cu")
		(net "UPI_CPU0_CPU1_P0P1_DP<3>")
	)
	(segment
		(start 320.243962 -193.974466)
		(end 318.803528 -193.320162)
		(width 0.14732)
		(layer "In6.Cu")
		(net "UPI_CPU0_CPU1_P0P1_DP<3>")
	)
	(segment
		(start 238.504984 -198.004938)
		(end 237.249716 -198.162164)
		(width 0.14732)
		(layer "In6.Cu")
		(net "UPI_CPU0_CPU1_P0P1_DP<3>")
	)
	(segment
		(start 328.055478 -197.521576)
		(end 326.037194 -196.605906)
		(width 0.14732)
		(layer "In6.Cu")
		(net "UPI_CPU0_CPU1_P0P1_DP<3>")
	)
	(segment
		(start 339.707728 -211.66201)
		(end 339.707728 -211.537296)
		(width 0.14732)
		(layer "In6.Cu")
		(net "UPI_CPU0_CPU1_P0P1_DP<3>")
	)
	(segment
		(start 317.159386 -192.157604)
		(end 314.21832 -187.353956)
		(width 0.14732)
		(layer "In6.Cu")
		(net "UPI_CPU0_CPU1_P0P1_DP<3>")
	)
	(segment
		(start 313.060842 -186.600846)
		(end 311.98185 -186.269884)
		(width 0.14732)
		(layer "In6.Cu")
		(net "UPI_CPU0_CPU1_P0P1_DP<3>")
	)
	(segment
		(start 200.422764 -186.302904)
		(end 200.420478 -186.302904)
		(width 0.14732)
		(layer "In6.Cu")
		(net "UPI_CPU0_CPU1_P0P1_DP<3>")
	)
	(segment
		(start 151.50084 -193.117978)
		(end 151.500586 -193.117724)
		(width 0.14732)
		(layer "In6.Cu")
		(net "UPI_CPU0_CPU1_P0P1_DP<3>")
	)
	(segment
		(start 149.166072 -194.948048)
		(end 148.285454 -195.63842)
		(width 0.14732)
		(layer "In6.Cu")
		(net "UPI_CPU0_CPU1_P0P1_DP<3>")
	)
	(segment
		(start 135.243316 -210.885278)
		(end 135.243316 -210.886548)
		(width 0.14732)
		(layer "In6.Cu")
		(net "UPI_CPU0_CPU1_P0P1_DP<3>")
	)
	(segment
		(start 339.37448 -215.436704)
		(end 339.530944 -215.165686)
		(width 0.0889)
		(layer "In6.Cu")
		(net "UPI_CPU0_CPU1_P0P1_DP<3>")
	)
	(segment
		(start 149.369272 -194.972686)
		(end 149.166072 -194.948048)
		(width 0.14732)
		(layer "In6.Cu")
		(net "UPI_CPU0_CPU1_P0P1_DP<3>")
	)
	(segment
		(start 151.7904 -192.890648)
		(end 151.790654 -192.890902)
		(width 0.14732)
		(layer "In6.Cu")
		(net "UPI_CPU0_CPU1_P0P1_DP<3>")
	)
	(segment
		(start 151.18588 -193.548508)
		(end 150.982934 -193.52387)
		(width 0.14732)
		(layer "In6.Cu")
		(net "UPI_CPU0_CPU1_P0P1_DP<3>")
	)
	(segment
		(start 339.749384 -213.8934)
		(end 339.749638 -213.892892)
		(width 0.0889)
		(layer "In6.Cu")
		(net "UPI_CPU0_CPU1_P0P1_DP<3>")
	)
	(segment
		(start 339.749638 -211.726018)
		(end 339.707728 -211.684108)
		(width 0.0889)
		(layer "In6.Cu")
		(net "UPI_CPU0_CPU1_P0P1_DP<3>")
	)
	(segment
		(start 314.21832 -187.353956)
		(end 314.218574 -187.353956)
		(width 0.14732)
		(layer "In6.Cu")
		(net "UPI_CPU0_CPU1_P0P1_DP<3>")
	)
	(segment
		(start 321.02044 -195.343018)
		(end 320.275712 -195.00469)
		(width 0.14732)
		(layer "In6.Cu")
		(net "UPI_CPU0_CPU1_P0P1_DP<3>")
	)
	(segment
		(start 151.500586 -193.117724)
		(end 151.475948 -193.321178)
		(width 0.14732)
		(layer "In6.Cu")
		(net "UPI_CPU0_CPU1_P0P1_DP<3>")
	)
	(segment
		(start 260.926326 -190.005462)
		(end 249.482356 -192.982342)
		(width 0.14732)
		(layer "In6.Cu")
		(net "UPI_CPU0_CPU1_P0P1_DP<3>")
	)
	(segment
		(start 133.562852 -212.507068)
		(end 133.374384 -212.695536)
		(width 0.0889)
		(layer "In6.Cu")
		(net "UPI_CPU0_CPU1_P0P1_DP<3>")
	)
	(segment
		(start 151.9936 -192.915286)
		(end 151.7904 -192.890648)
		(width 0.14732)
		(layer "In6.Cu")
		(net "UPI_CPU0_CPU1_P0P1_DP<3>")
	)
	(segment
		(start 223.257364 -190.798704)
		(end 215.205056 -186.993784)
		(width 0.14732)
		(layer "In6.Cu")
		(net "UPI_CPU0_CPU1_P0P1_DP<3>")
	)
	(segment
		(start 233.540554 -197.459092)
		(end 223.257364 -190.798704)
		(width 0.14732)
		(layer "In6.Cu")
		(net "UPI_CPU0_CPU1_P0P1_DP<3>")
	)
	(segment
		(start 339.530944 -215.165686)
		(end 339.506814 -215.076532)
		(width 0.0889)
		(layer "In6.Cu")
		(net "UPI_CPU0_CPU1_P0P1_DP<3>")
	)
	(segment
		(start 264.673334 -187.931298)
		(end 260.926326 -190.005462)
		(width 0.14732)
		(layer "In6.Cu")
		(net "UPI_CPU0_CPU1_P0P1_DP<3>")
	)
	(segment
		(start 148.285454 -195.63842)
		(end 143.720312 -199.736202)
		(width 0.14732)
		(layer "In6.Cu")
		(net "UPI_CPU0_CPU1_P0P1_DP<3>")
	)
	(segment
		(start 325.842376 -196.679312)
		(end 325.647812 -197.107302)
		(width 0.14732)
		(layer "In6.Cu")
		(net "UPI_CPU0_CPU1_P0P1_DP<3>")
	)
	(segment
		(start 150.17496 -194.157346)
		(end 149.684232 -194.542156)
		(width 0.14732)
		(layer "In6.Cu")
		(net "UPI_CPU0_CPU1_P0P1_DP<3>")
	)
	(segment
		(start 324.495668 -196.921882)
		(end 324.34276 -196.514466)
		(width 0.14732)
		(layer "In6.Cu")
		(net "UPI_CPU0_CPU1_P0P1_DP<3>")
	)
	(segment
		(start 151.475948 -193.321178)
		(end 151.18588 -193.548508)
		(width 0.14732)
		(layer "In6.Cu")
		(net "UPI_CPU0_CPU1_P0P1_DP<3>")
	)
	(segment
		(start 302.46828 -186.093354)
		(end 273.031712 -186.9059)
		(width 0.14732)
		(layer "In6.Cu")
		(net "UPI_CPU0_CPU1_P0P1_DP<3>")
	)
	(segment
		(start 151.790654 -192.890902)
		(end 151.50084 -193.117978)
		(width 0.14732)
		(layer "In6.Cu")
		(net "UPI_CPU0_CPU1_P0P1_DP<3>")
	)
	(segment
		(start 132.410962 -213.562438)
		(end 132.410962 -213.93023)
		(width 0.0889)
		(layer "In6.Cu")
		(net "UPI_CPU0_CPU1_P0P1_DP<3>")
	)
	(segment
		(start 133.185662 -213.02472)
		(end 133.0452 -213.02472)
		(width 0.0889)
		(layer "In6.Cu")
		(net "UPI_CPU0_CPU1_P0P1_DP<3>")
	)
	(segment
		(start 150.174706 -194.157092)
		(end 150.17496 -194.157346)
		(width 0.14732)
		(layer "In6.Cu")
		(net "UPI_CPU0_CPU1_P0P1_DP<3>")
	)
	(segment
		(start 323.537834 -196.148706)
		(end 323.130418 -196.301614)
		(width 0.14732)
		(layer "In6.Cu")
		(net "UPI_CPU0_CPU1_P0P1_DP<3>")
	)
	(segment
		(start 132.760212 -213.213188)
		(end 132.410962 -213.562438)
		(width 0.0889)
		(layer "In6.Cu")
		(net "UPI_CPU0_CPU1_P0P1_DP<3>")
	)
	(segment
		(start 143.720312 -199.736202)
		(end 137.423398 -208.705196)
		(width 0.14732)
		(layer "In6.Cu")
		(net "UPI_CPU0_CPU1_P0P1_DP<3>")
	)
	(segment
		(start 324.463918 -195.891404)
		(end 323.926962 -195.64731)
		(width 0.14732)
		(layer "In6.Cu")
		(net "UPI_CPU0_CPU1_P0P1_DP<3>")
	)
	(segment
		(start 133.892036 -212.318346)
		(end 133.703314 -212.507068)
		(width 0.0889)
		(layer "In6.Cu")
		(net "UPI_CPU0_CPU1_P0P1_DP<3>")
	)
	(segment
		(start 322.38569 -195.963286)
		(end 322.232782 -195.55587)
		(width 0.14732)
		(layer "In6.Cu")
		(net "UPI_CPU0_CPU1_P0P1_DP<3>")
	)
	(segment
		(start 322.232782 -195.55587)
		(end 322.427346 -195.12788)
		(width 0.14732)
		(layer "In6.Cu")
		(net "UPI_CPU0_CPU1_P0P1_DP<3>")
	)
	(segment
		(start 325.647812 -197.107302)
		(end 325.240396 -197.26021)
		(width 0.14732)
		(layer "In6.Cu")
		(net "UPI_CPU0_CPU1_P0P1_DP<3>")
	)
	(segment
		(start 339.707474 -208.96199)
		(end 339.2805 -204.931772)
		(width 0.14732)
		(layer "In6.Cu")
		(net "UPI_CPU0_CPU1_P0P1_DP<3>")
	)
	(segment
		(start 132.410962 -213.93023)
		(end 132.411216 -213.929468)
		(width 0.0889)
		(layer "In6.Cu")
		(net "UPI_CPU0_CPU1_P0P1_DP<3>")
	)
	(segment
		(start 133.0452 -213.02472)
		(end 132.856732 -213.213188)
		(width 0.0889)
		(layer "In6.Cu")
		(net "UPI_CPU0_CPU1_P0P1_DP<3>")
	)
	(segment
		(start 134.638288 -211.491576)
		(end 134.578344 -211.491576)
		(width 0.0889)
		(layer "In6.Cu")
		(net "UPI_CPU0_CPU1_P0P1_DP<3>")
	)
	(segment
		(start 159.801306 -186.971686)
		(end 158.004256 -188.019436)
		(width 0.14732)
		(layer "In6.Cu")
		(net "UPI_CPU0_CPU1_P0P1_DP<3>")
	)
	(segment
		(start 133.703314 -212.507068)
		(end 133.562852 -212.507068)
		(width 0.0889)
		(layer "In6.Cu")
		(net "UPI_CPU0_CPU1_P0P1_DP<3>")
	)
	(segment
		(start 152.283668 -192.687956)
		(end 151.9936 -192.915286)
		(width 0.14732)
		(layer "In6.Cu")
		(net "UPI_CPU0_CPU1_P0P1_DP<3>")
	)
	(segment
		(start 338.82457 -204.370432)
		(end 331.979778 -198.985124)
		(width 0.14732)
		(layer "In6.Cu")
		(net "UPI_CPU0_CPU1_P0P1_DP<3>")
	)
	(segment
		(start 321.427856 -195.19011)
		(end 321.02044 -195.343018)
		(width 0.14732)
		(layer "In6.Cu")
		(net "UPI_CPU0_CPU1_P0P1_DP<3>")
	)
	(segment
		(start 150.692866 -193.750946)
		(end 150.668228 -193.954654)
		(width 0.14732)
		(layer "In6.Cu")
		(net "UPI_CPU0_CPU1_P0P1_DP<3>")
	)
	(segment
		(start 158.004256 -188.019436)
		(end 152.308306 -192.484756)
		(width 0.14732)
		(layer "In6.Cu")
		(net "UPI_CPU0_CPU1_P0P1_DP<3>")
	)
	(segment
		(start 200.420478 -186.302904)
		(end 159.801306 -186.971686)
		(width 0.14732)
		(layer "In6.Cu")
		(net "UPI_CPU0_CPU1_P0P1_DP<3>")
	)
	(segment
		(start 273.031712 -186.9059)
		(end 264.673334 -187.931298)
		(width 0.14732)
		(layer "In6.Cu")
		(net "UPI_CPU0_CPU1_P0P1_DP<3>")
	)
	(segment
		(start 215.205056 -186.993784)
		(end 200.422764 -186.302904)
		(width 0.14732)
		(layer "In6.Cu")
		(net "UPI_CPU0_CPU1_P0P1_DP<3>")
	)
	(segment
		(start 323.130418 -196.301614)
		(end 322.38569 -195.963286)
		(width 0.14732)
		(layer "In6.Cu")
		(net "UPI_CPU0_CPU1_P0P1_DP<3>")
	)
	(segment
		(start 339.749638 -213.892892)
		(end 339.749638 -211.726018)
		(width 0.0889)
		(layer "In6.Cu")
		(net "UPI_CPU0_CPU1_P0P1_DP<3>")
	)
	(segment
		(start 235.919772 -198.162164)
		(end 234.730036 -197.810628)
		(width 0.14732)
		(layer "In6.Cu")
		(net "UPI_CPU0_CPU1_P0P1_DP<3>")
	)
	(segment
		(start 324.34276 -196.514466)
		(end 324.537324 -196.086476)
		(width 0.14732)
		(layer "In6.Cu")
		(net "UPI_CPU0_CPU1_P0P1_DP<3>")
	)
	(segment
		(start 135.243316 -210.886548)
		(end 134.653782 -211.476082)
		(width 0.14732)
		(layer "In6.Cu")
		(net "UPI_CPU0_CPU1_P0P1_DP<3>")
	)
	(segment
		(start 133.374384 -212.835998)
		(end 133.185662 -213.02472)
		(width 0.0889)
		(layer "In6.Cu")
		(net "UPI_CPU0_CPU1_P0P1_DP<3>")
	)
	(segment
		(start 339.707728 -211.684108)
		(end 339.707728 -211.66201)
		(width 0.0889)
		(layer "In6.Cu")
		(net "UPI_CPU0_CPU1_P0P1_DP<3>")
	)
	(segment
		(start 150.668228 -193.954654)
		(end 150.37816 -194.18173)
		(width 0.14732)
		(layer "In6.Cu")
		(net "UPI_CPU0_CPU1_P0P1_DP<3>")
	)
	(segment
		(start 326.037194 -196.605906)
		(end 325.842376 -196.679312)
		(width 0.14732)
		(layer "In6.Cu")
		(net "UPI_CPU0_CPU1_P0P1_DP<3>")
	)
	(segment
		(start 320.317368 -194.169284)
		(end 320.243962 -193.974466)
		(width 0.14732)
		(layer "In6.Cu")
		(net "UPI_CPU0_CPU1_P0P1_DP<3>")
	)
	(segment
		(start 150.982934 -193.52387)
		(end 150.69312 -193.7512)
		(width 0.14732)
		(layer "In6.Cu")
		(net "UPI_CPU0_CPU1_P0P1_DP<3>")
	)
	(segment
		(start 339.2805 -204.931772)
		(end 338.82457 -204.370432)
		(width 0.14732)
		(layer "In6.Cu")
		(net "UPI_CPU0_CPU1_P0P1_DP<3>")
	)
	(segment
		(start 321.816984 -194.688714)
		(end 321.62242 -194.76212)
		(width 0.14732)
		(layer "In6.Cu")
		(net "UPI_CPU0_CPU1_P0P1_DP<3>")
	)
	(segment
		(start 321.62242 -194.76212)
		(end 321.427856 -195.19011)
		(width 0.14732)
		(layer "In6.Cu")
		(net "UPI_CPU0_CPU1_P0P1_DP<3>")
	)
	(segment
		(start 320.275712 -195.00469)
		(end 320.122804 -194.597274)
		(width 0.14732)
		(layer "In6.Cu")
		(net "UPI_CPU0_CPU1_P0P1_DP<3>")
	)
	(segment
		(start 322.427346 -195.12788)
		(end 322.35394 -194.932808)
		(width 0.14732)
		(layer "In6.Cu")
		(net "UPI_CPU0_CPU1_P0P1_DP<3>")
	)
	(segment
		(start 149.659594 -194.745356)
		(end 149.369272 -194.972686)
		(width 0.14732)
		(layer "In6.Cu")
		(net "UPI_CPU0_CPU1_P0P1_DP<3>")
	)
	(segment
		(start 311.98185 -186.269884)
		(end 302.46828 -186.093354)
		(width 0.14732)
		(layer "In6.Cu")
		(net "UPI_CPU0_CPU1_P0P1_DP<3>")
	)
	(segment
		(start 132.856732 -213.213188)
		(end 132.760212 -213.213188)
		(width 0.0889)
		(layer "In6.Cu")
		(net "UPI_CPU0_CPU1_P0P1_DP<3>")
	)
	(segment
		(start 320.122804 -194.597274)
		(end 320.317368 -194.169284)
		(width 0.14732)
		(layer "In6.Cu")
		(net "UPI_CPU0_CPU1_P0P1_DP<3>")
	)
	(segment
		(start 132.186934 -214.22487)
		(end 132.156708 -214.321644)
		(width 0.0889)
		(layer "In6.Cu")
		(net "UPI_CPU0_CPU1_P0P1_DP<3>")
	)
	(segment
		(start 331.979778 -198.985124)
		(end 328.055478 -197.521576)
		(width 0.14732)
		(layer "In6.Cu")
		(net "UPI_CPU0_CPU1_P0P1_DP<3>")
	)
	(segment
		(start 149.683978 -194.541902)
		(end 149.659594 -194.745356)
		(width 0.14732)
		(layer "In6.Cu")
		(net "UPI_CPU0_CPU1_P0P1_DP<3>")
	)
	(segment
		(start 149.684232 -194.542156)
		(end 149.683978 -194.541902)
		(width 0.14732)
		(layer "In6.Cu")
		(net "UPI_CPU0_CPU1_P0P1_DP<3>")
	)
	(segment
		(start 133.374384 -212.695536)
		(end 133.374384 -212.835998)
		(width 0.0889)
		(layer "In6.Cu")
		(net "UPI_CPU0_CPU1_P0P1_DP<3>")
	)
	(segment
		(start 322.35394 -194.932808)
		(end 321.816984 -194.688714)
		(width 0.14732)
		(layer "In6.Cu")
		(net "UPI_CPU0_CPU1_P0P1_DP<3>")
	)
	(segment
		(start 323.732398 -195.720716)
		(end 323.537834 -196.148706)
		(width 0.14732)
		(layer "In6.Cu")
		(net "UPI_CPU0_CPU1_P0P1_DP<3>")
	)
	(segment
		(start 339.278976 -214.636858)
		(end 339.278976 -214.425784)
		(width 0.0889)
		(layer "In6.Cu")
		(net "UPI_CPU0_CPU1_P0P1_DP<3>")
	)
	(segment
		(start 137.423398 -208.705196)
		(end 135.243316 -210.885278)
		(width 0.14732)
		(layer "In6.Cu")
		(net "UPI_CPU0_CPU1_P0P1_DP<3>")
	)
	(segment
		(start 134.653782 -211.476082)
		(end 134.638288 -211.491576)
		(width 0.0889)
		(layer "In6.Cu")
		(net "UPI_CPU0_CPU1_P0P1_DP<3>")
	)
	(segment
		(start 318.803528 -193.320162)
		(end 317.159386 -192.157604)
		(width 0.14732)
		(layer "In6.Cu")
		(net "UPI_CPU0_CPU1_P0P1_DP<3>")
	)
	(segment
		(start 339.707728 -211.537296)
		(end 339.707474 -211.53755)
		(width 0.14732)
		(layer "In6.Cu")
		(net "UPI_CPU0_CPU1_P0P1_DP<3>")
	)
	(segment
		(start 134.578344 -211.491576)
		(end 133.892036 -212.177884)
		(width 0.0889)
		(layer "In6.Cu")
		(net "UPI_CPU0_CPU1_P0P1_DP<3>")
	)
	(segment
		(start 132.156708 -214.321644)
		(end 132.315458 -214.622634)
		(width 0.0889)
		(layer "In6.Cu")
		(net "UPI_CPU0_CPU1_P0P1_DP<3>")
	)
	(segment
		(start 150.69312 -193.7512)
		(end 150.692866 -193.750946)
		(width 0.14732)
		(layer "In6.Cu")
		(net "UPI_CPU0_CPU1_P0P1_DP<3>")
	)
	(segment
		(start 339.707474 -211.53755)
		(end 339.707474 -208.96199)
		(width 0.14732)
		(layer "In6.Cu")
		(net "UPI_CPU0_CPU1_P0P1_DP<3>")
	)
	(segment
		(start 324.537324 -196.086476)
		(end 324.463918 -195.891404)
		(width 0.14732)
		(layer "In6.Cu")
		(net "UPI_CPU0_CPU1_P0P1_DP<3>")
	)
	(segment
		(start 314.218574 -187.353956)
		(end 313.060842 -186.600846)
		(width 0.14732)
		(layer "In6.Cu")
		(net "UPI_CPU0_CPU1_P0P1_DP<3>")
	)
	(segment
		(start 234.730036 -197.810628)
		(end 233.540554 -197.459092)
		(width 0.14732)
		(layer "In6.Cu")
		(net "UPI_CPU0_CPU1_P0P1_DP<3>")
	)
	(segment
		(start 237.249716 -198.162164)
		(end 235.919772 -198.162164)
		(width 0.14732)
		(layer "In6.Cu")
		(net "UPI_CPU0_CPU1_P0P1_DP<3>")
	)
	(segment
		(start 150.37816 -194.18173)
		(end 150.174706 -194.157092)
		(width 0.14732)
		(layer "In6.Cu")
		(net "UPI_CPU0_CPU1_P0P1_DP<3>")
	)
	(segment
		(start 249.482356 -192.982342)
		(end 238.504984 -198.004938)
		(width 0.14732)
		(layer "In6.Cu")
		(net "UPI_CPU0_CPU1_P0P1_DP<3>")
	)
	(segment
		(start 325.240396 -197.26021)
		(end 324.495668 -196.921882)
		(width 0.14732)
		(layer "In6.Cu")
		(net "UPI_CPU0_CPU1_P0P1_DP<3>")
	)
	(segment
		(start 323.926962 -195.64731)
		(end 323.732398 -195.720716)
		(width 0.14732)
		(layer "In6.Cu")
		(net "UPI_CPU0_CPU1_P0P1_DP<3>")
	)
	(segment
		(start 152.308306 -192.484756)
		(end 152.283668 -192.687956)
		(width 0.14732)
		(layer "In6.Cu")
		(net "UPI_CPU0_CPU1_P0P1_DP<3>")
	)
	(arc
		(start 339.489796 -215.063324)
		(mid 339.337365 -214.873342)
		(end 339.278976 -214.636858)
		(width 0.0889)
		(layer "In6.Cu")
		(net "UPI_CPU0_CPU1_P0P1_DP<3>")
	)
	(arc
		(start 132.39623 -213.96833)
		(mid 132.309679 -214.111364)
		(end 132.186934 -214.22487)
		(width 0.0889)
		(layer "In6.Cu")
		(net "UPI_CPU0_CPU1_P0P1_DP<3>")
	)
	(arc
		(start 339.278976 -214.425784)
		(mid 339.390416 -214.232389)
		(end 339.56498 -214.093298)
		(width 0.0889)
		(layer "In6.Cu")
		(net "UPI_CPU0_CPU1_P0P1_DP<3>")
	)
	(arc
		(start 339.506814 -215.076532)
		(mid 339.498242 -215.070009)
		(end 339.489796 -215.063324)
		(width 0.0889)
		(layer "In6.Cu")
		(net "UPI_CPU0_CPU1_P0P1_DP<3>")
	)
	(arc
		(start 132.411216 -213.929468)
		(mid 132.404058 -213.949028)
		(end 132.39623 -213.96833)
		(width 0.0889)
		(layer "In6.Cu")
		(net "UPI_CPU0_CPU1_P0P1_DP<3>")
	)
	(arc
		(start 339.56498 -214.093298)
		(mid 339.674376 -214.009201)
		(end 339.749384 -213.8934)
		(width 0.0889)
		(layer "In6.Cu")
		(net "UPI_CPU0_CPU1_P0P1_DP<3>")
	)
	(segment
		(start 132.785866 -215.972644)
		(end 132.785866 -215.436958)
		(width 0.13208)
		(layer "F.Cu")
		(net "UPI_CPU0_CPU1_P0P1_DP<2>")
	)
	(segment
		(start 132.785866 -215.436958)
		(end 132.785612 -215.436704)
		(width 0.13208)
		(layer "F.Cu")
		(net "UPI_CPU0_CPU1_P0P1_DP<2>")
	)
	(segment
		(start 338.90458 -215.158574)
		(end 338.90458 -214.622888)
		(width 0.13208)
		(layer "F.Cu")
		(net "UPI_CPU0_CPU1_P0P1_DP<2>")
	)
	(segment
		(start 338.90458 -214.622888)
		(end 338.904326 -214.622634)
		(width 0.13208)
		(layer "F.Cu")
		(net "UPI_CPU0_CPU1_P0P1_DP<2>")
	)
	(segment
		(start 331.347318 -204.681582)
		(end 328.052684 -201.96175)
		(width 0.14732)
		(layer "In6.Cu")
		(net "UPI_CPU0_CPU1_P0P1_DP<2>")
	)
	(segment
		(start 336.101944 -208.606644)
		(end 332.679802 -205.781656)
		(width 0.14732)
		(layer "In6.Cu")
		(net "UPI_CPU0_CPU1_P0P1_DP<2>")
	)
	(segment
		(start 237.291626 -198.832724)
		(end 236.11459 -198.832724)
		(width 0.14732)
		(layer "In6.Cu")
		(net "UPI_CPU0_CPU1_P0P1_DP<2>")
	)
	(segment
		(start 236.11459 -198.832724)
		(end 233.23042 -197.980046)
		(width 0.14732)
		(layer "In6.Cu")
		(net "UPI_CPU0_CPU1_P0P1_DP<2>")
	)
	(segment
		(start 317.4238 -193.663316)
		(end 313.760866 -187.736226)
		(width 0.14732)
		(layer "In6.Cu")
		(net "UPI_CPU0_CPU1_P0P1_DP<2>")
	)
	(segment
		(start 268.900656 -190.029846)
		(end 268.5542 -190.156846)
		(width 0.14732)
		(layer "In6.Cu")
		(net "UPI_CPU0_CPU1_P0P1_DP<2>")
	)
	(segment
		(start 339.041994 -210.874864)
		(end 339.04174 -210.875118)
		(width 0.14732)
		(layer "In6.Cu")
		(net "UPI_CPU0_CPU1_P0P1_DP<2>")
	)
	(segment
		(start 339.04174 -210.440524)
		(end 337.990434 -209.389218)
		(width 0.14732)
		(layer "In6.Cu")
		(net "UPI_CPU0_CPU1_P0P1_DP<2>")
	)
	(segment
		(start 249.803412 -193.564256)
		(end 238.665766 -198.660766)
		(width 0.14732)
		(layer "In6.Cu")
		(net "UPI_CPU0_CPU1_P0P1_DP<2>")
	)
	(segment
		(start 312.747406 -187.09767)
		(end 311.90438 -186.845702)
		(width 0.14732)
		(layer "In6.Cu")
		(net "UPI_CPU0_CPU1_P0P1_DP<2>")
	)
	(segment
		(start 137.705084 -209.292444)
		(end 136.150858 -210.846924)
		(width 0.14732)
		(layer "In6.Cu")
		(net "UPI_CPU0_CPU1_P0P1_DP<2>")
	)
	(segment
		(start 331.554582 -204.66177)
		(end 331.347318 -204.681582)
		(width 0.14732)
		(layer "In6.Cu")
		(net "UPI_CPU0_CPU1_P0P1_DP<2>")
	)
	(segment
		(start 132.779008 -214.278718)
		(end 132.779008 -214.278972)
		(width 0.0889)
		(layer "In6.Cu")
		(net "UPI_CPU0_CPU1_P0P1_DP<2>")
	)
	(segment
		(start 332.65999 -205.574392)
		(end 334.551782 -203.282804)
		(width 0.14732)
		(layer "In6.Cu")
		(net "UPI_CPU0_CPU1_P0P1_DP<2>")
	)
	(segment
		(start 238.665766 -198.660766)
		(end 237.291626 -198.832724)
		(width 0.14732)
		(layer "In6.Cu")
		(net "UPI_CPU0_CPU1_P0P1_DP<2>")
	)
	(segment
		(start 136.150858 -210.846924)
		(end 135.234934 -211.762848)
		(width 0.14732)
		(layer "In6.Cu")
		(net "UPI_CPU0_CPU1_P0P1_DP<2>")
	)
	(segment
		(start 337.990434 -209.389218)
		(end 336.101944 -208.606644)
		(width 0.14732)
		(layer "In6.Cu")
		(net "UPI_CPU0_CPU1_P0P1_DP<2>")
	)
	(segment
		(start 339.041994 -211.66201)
		(end 339.041994 -210.874864)
		(width 0.14732)
		(layer "In6.Cu")
		(net "UPI_CPU0_CPU1_P0P1_DP<2>")
	)
	(segment
		(start 271.73682 -187.815982)
		(end 268.900656 -190.029846)
		(width 0.14732)
		(layer "In6.Cu")
		(net "UPI_CPU0_CPU1_P0P1_DP<2>")
	)
	(segment
		(start 339.000084 -211.726018)
		(end 339.041994 -211.684108)
		(width 0.0889)
		(layer "In6.Cu")
		(net "UPI_CPU0_CPU1_P0P1_DP<2>")
	)
	(segment
		(start 207.791304 -187.67171)
		(end 200.17867 -186.881008)
		(width 0.14732)
		(layer "In6.Cu")
		(net "UPI_CPU0_CPU1_P0P1_DP<2>")
	)
	(segment
		(start 233.23042 -197.980046)
		(end 223.372172 -191.594994)
		(width 0.14732)
		(layer "In6.Cu")
		(net "UPI_CPU0_CPU1_P0P1_DP<2>")
	)
	(segment
		(start 326.341486 -200.439274)
		(end 326.7075 -199.970898)
		(width 0.14732)
		(layer "In6.Cu")
		(net "UPI_CPU0_CPU1_P0P1_DP<2>")
	)
	(segment
		(start 211.219288 -187.437268)
		(end 207.791304 -187.67171)
		(width 0.14732)
		(layer "In6.Cu")
		(net "UPI_CPU0_CPU1_P0P1_DP<2>")
	)
	(segment
		(start 334.551782 -203.282804)
		(end 334.51038 -202.849734)
		(width 0.14732)
		(layer "In6.Cu")
		(net "UPI_CPU0_CPU1_P0P1_DP<2>")
	)
	(segment
		(start 339.000084 -213.929468)
		(end 339.000084 -211.726018)
		(width 0.0889)
		(layer "In6.Cu")
		(net "UPI_CPU0_CPU1_P0P1_DP<2>")
	)
	(segment
		(start 152.56764 -194.429888)
		(end 148.61667 -196.089016)
		(width 0.14732)
		(layer "In6.Cu")
		(net "UPI_CPU0_CPU1_P0P1_DP<2>")
	)
	(segment
		(start 132.942076 -215.165686)
		(end 132.785612 -215.436704)
		(width 0.0889)
		(layer "In6.Cu")
		(net "UPI_CPU0_CPU1_P0P1_DP<2>")
	)
	(segment
		(start 311.90438 -186.845702)
		(end 302.458374 -186.672728)
		(width 0.14732)
		(layer "In6.Cu")
		(net "UPI_CPU0_CPU1_P0P1_DP<2>")
	)
	(segment
		(start 273.00555 -187.489846)
		(end 271.73682 -187.815982)
		(width 0.14732)
		(layer "In6.Cu")
		(net "UPI_CPU0_CPU1_P0P1_DP<2>")
	)
	(segment
		(start 326.36714 -200.645776)
		(end 326.341486 -200.439274)
		(width 0.14732)
		(layer "In6.Cu")
		(net "UPI_CPU0_CPU1_P0P1_DP<2>")
	)
	(segment
		(start 143.980408 -200.380092)
		(end 137.705084 -209.292444)
		(width 0.14732)
		(layer "In6.Cu")
		(net "UPI_CPU0_CPU1_P0P1_DP<2>")
	)
	(segment
		(start 132.690108 -214.49411)
		(end 132.690108 -214.636858)
		(width 0.0889)
		(layer "In6.Cu")
		(net "UPI_CPU0_CPU1_P0P1_DP<2>")
	)
	(segment
		(start 267.4493 -190.322454)
		(end 260.992112 -190.592202)
		(width 0.14732)
		(layer "In6.Cu")
		(net "UPI_CPU0_CPU1_P0P1_DP<2>")
	)
	(segment
		(start 132.917946 -215.076532)
		(end 132.942076 -215.165686)
		(width 0.0889)
		(layer "In6.Cu")
		(net "UPI_CPU0_CPU1_P0P1_DP<2>")
	)
	(segment
		(start 135.21944 -211.838286)
		(end 132.779008 -214.278718)
		(width 0.0889)
		(layer "In6.Cu")
		(net "UPI_CPU0_CPU1_P0P1_DP<2>")
	)
	(segment
		(start 325.577708 -199.088756)
		(end 325.211948 -199.557132)
		(width 0.14732)
		(layer "In6.Cu")
		(net "UPI_CPU0_CPU1_P0P1_DP<2>")
	)
	(segment
		(start 325.005192 -199.582786)
		(end 317.4238 -193.663316)
		(width 0.14732)
		(layer "In6.Cu")
		(net "UPI_CPU0_CPU1_P0P1_DP<2>")
	)
	(segment
		(start 339.041994 -211.684108)
		(end 339.041994 -211.66201)
		(width 0.0889)
		(layer "In6.Cu")
		(net "UPI_CPU0_CPU1_P0P1_DP<2>")
	)
	(segment
		(start 268.5542 -190.156846)
		(end 267.4493 -190.322454)
		(width 0.14732)
		(layer "In6.Cu")
		(net "UPI_CPU0_CPU1_P0P1_DP<2>")
	)
	(segment
		(start 158.706312 -188.29147)
		(end 152.56764 -194.429888)
		(width 0.14732)
		(layer "In6.Cu")
		(net "UPI_CPU0_CPU1_P0P1_DP<2>")
	)
	(segment
		(start 302.452024 -186.672728)
		(end 273.00555 -187.489846)
		(width 0.14732)
		(layer "In6.Cu")
		(net "UPI_CPU0_CPU1_P0P1_DP<2>")
	)
	(segment
		(start 313.760866 -187.736226)
		(end 312.747406 -187.09767)
		(width 0.14732)
		(layer "In6.Cu")
		(net "UPI_CPU0_CPU1_P0P1_DP<2>")
	)
	(segment
		(start 223.372172 -191.594994)
		(end 215.0745 -187.673742)
		(width 0.14732)
		(layer "In6.Cu")
		(net "UPI_CPU0_CPU1_P0P1_DP<2>")
	)
	(segment
		(start 326.009508 -199.035416)
		(end 325.577708 -199.088756)
		(width 0.14732)
		(layer "In6.Cu")
		(net "UPI_CPU0_CPU1_P0P1_DP<2>")
	)
	(segment
		(start 200.17867 -186.881008)
		(end 159.91078 -187.572396)
		(width 0.14732)
		(layer "In6.Cu")
		(net "UPI_CPU0_CPU1_P0P1_DP<2>")
	)
	(segment
		(start 148.61667 -196.089016)
		(end 143.980408 -200.380092)
		(width 0.14732)
		(layer "In6.Cu")
		(net "UPI_CPU0_CPU1_P0P1_DP<2>")
	)
	(segment
		(start 159.91078 -187.572396)
		(end 158.706312 -188.29147)
		(width 0.14732)
		(layer "In6.Cu")
		(net "UPI_CPU0_CPU1_P0P1_DP<2>")
	)
	(segment
		(start 339.04174 -210.875118)
		(end 339.04174 -210.440524)
		(width 0.14732)
		(layer "In6.Cu")
		(net "UPI_CPU0_CPU1_P0P1_DP<2>")
	)
	(segment
		(start 328.052684 -201.96175)
		(end 326.36714 -200.645776)
		(width 0.14732)
		(layer "In6.Cu")
		(net "UPI_CPU0_CPU1_P0P1_DP<2>")
	)
	(segment
		(start 338.904326 -214.622634)
		(end 338.745576 -214.321644)
		(width 0.0889)
		(layer "In6.Cu")
		(net "UPI_CPU0_CPU1_P0P1_DP<2>")
	)
	(segment
		(start 302.458374 -186.672728)
		(end 302.452024 -186.672728)
		(width 0.14732)
		(layer "In6.Cu")
		(net "UPI_CPU0_CPU1_P0P1_DP<2>")
	)
	(segment
		(start 326.7075 -199.970898)
		(end 326.65416 -199.539098)
		(width 0.14732)
		(layer "In6.Cu")
		(net "UPI_CPU0_CPU1_P0P1_DP<2>")
	)
	(segment
		(start 135.21944 -211.778342)
		(end 135.21944 -211.838286)
		(width 0.0889)
		(layer "In6.Cu")
		(net "UPI_CPU0_CPU1_P0P1_DP<2>")
	)
	(segment
		(start 333.879444 -202.32878)
		(end 333.446374 -202.370182)
		(width 0.14732)
		(layer "In6.Cu")
		(net "UPI_CPU0_CPU1_P0P1_DP<2>")
	)
	(segment
		(start 135.234934 -211.762848)
		(end 135.21944 -211.778342)
		(width 0.0889)
		(layer "In6.Cu")
		(net "UPI_CPU0_CPU1_P0P1_DP<2>")
	)
	(segment
		(start 334.51038 -202.849734)
		(end 333.879444 -202.32878)
		(width 0.14732)
		(layer "In6.Cu")
		(net "UPI_CPU0_CPU1_P0P1_DP<2>")
	)
	(segment
		(start 338.745576 -214.321644)
		(end 338.775802 -214.22487)
		(width 0.0889)
		(layer "In6.Cu")
		(net "UPI_CPU0_CPU1_P0P1_DP<2>")
	)
	(segment
		(start 326.65416 -199.539098)
		(end 326.009508 -199.035416)
		(width 0.14732)
		(layer "In6.Cu")
		(net "UPI_CPU0_CPU1_P0P1_DP<2>")
	)
	(segment
		(start 215.0745 -187.673742)
		(end 211.219288 -187.437268)
		(width 0.14732)
		(layer "In6.Cu")
		(net "UPI_CPU0_CPU1_P0P1_DP<2>")
	)
	(segment
		(start 332.679802 -205.781656)
		(end 332.65999 -205.574392)
		(width 0.14732)
		(layer "In6.Cu")
		(net "UPI_CPU0_CPU1_P0P1_DP<2>")
	)
	(segment
		(start 325.211948 -199.557132)
		(end 325.005192 -199.582786)
		(width 0.14732)
		(layer "In6.Cu")
		(net "UPI_CPU0_CPU1_P0P1_DP<2>")
	)
	(segment
		(start 260.992112 -190.592202)
		(end 249.803412 -193.564256)
		(width 0.14732)
		(layer "In6.Cu")
		(net "UPI_CPU0_CPU1_P0P1_DP<2>")
	)
	(segment
		(start 333.446374 -202.370182)
		(end 331.554582 -204.66177)
		(width 0.14732)
		(layer "In6.Cu")
		(net "UPI_CPU0_CPU1_P0P1_DP<2>")
	)
	(arc
		(start 132.690108 -214.636858)
		(mid 132.748453 -214.873363)
		(end 132.900928 -215.063324)
		(width 0.0889)
		(layer "In6.Cu")
		(net "UPI_CPU0_CPU1_P0P1_DP<2>")
	)
	(arc
		(start 338.985098 -213.96833)
		(mid 338.992933 -213.949031)
		(end 339.000084 -213.929468)
		(width 0.0889)
		(layer "In6.Cu")
		(net "UPI_CPU0_CPU1_P0P1_DP<2>")
	)
	(arc
		(start 132.900928 -215.063324)
		(mid 132.909374 -215.070009)
		(end 132.917946 -215.076532)
		(width 0.0889)
		(layer "In6.Cu")
		(net "UPI_CPU0_CPU1_P0P1_DP<2>")
	)
	(arc
		(start 338.775802 -214.22487)
		(mid 338.898548 -214.111365)
		(end 338.985098 -213.96833)
		(width 0.0889)
		(layer "In6.Cu")
		(net "UPI_CPU0_CPU1_P0P1_DP<2>")
	)
	(arc
		(start 132.779008 -214.278972)
		(mid 132.713113 -214.37768)
		(end 132.690108 -214.49411)
		(width 0.0889)
		(layer "In6.Cu")
		(net "UPI_CPU0_CPU1_P0P1_DP<2>")
	)
	(segment
		(start 112.579912 -214.622888)
		(end 112.579658 -214.622634)
		(width 0.13208)
		(layer "F.Cu")
		(net "UPI_CPU0_CPU1_P0P1_DP<23>")
	)
	(segment
		(start 359.110534 -215.436958)
		(end 359.11028 -215.436704)
		(width 0.13208)
		(layer "F.Cu")
		(net "UPI_CPU0_CPU1_P0P1_DP<23>")
	)
	(segment
		(start 112.579912 -215.158574)
		(end 112.579912 -214.622888)
		(width 0.13208)
		(layer "F.Cu")
		(net "UPI_CPU0_CPU1_P0P1_DP<23>")
	)
	(segment
		(start 359.110534 -215.972644)
		(end 359.110534 -215.436958)
		(width 0.13208)
		(layer "F.Cu")
		(net "UPI_CPU0_CPU1_P0P1_DP<23>")
	)
	(segment
		(start 112.579658 -214.622634)
		(end 112.579658 -214.546434)
		(width 0.13208)
		(layer "F.Cu")
		(net "UPI_CPU0_CPU1_P0P1_DP<23>")
	)
	(segment
		(start 359.205276 -214.644732)
		(end 359.205276 -214.159084)
		(width 0.0889)
		(layer "In6.Cu")
		(net "UPI_CPU0_CPU1_P0P1_DP<23>")
	)
	(segment
		(start 155.57754 -169.884344)
		(end 149.601428 -171.413678)
		(width 0.14732)
		(layer "In6.Cu")
		(net "UPI_CPU0_CPU1_P0P1_DP<23>")
	)
	(segment
		(start 353.429824 -193.769996)
		(end 342.221566 -182.926482)
		(width 0.14732)
		(layer "In6.Cu")
		(net "UPI_CPU0_CPU1_P0P1_DP<23>")
	)
	(segment
		(start 314.109608 -168.928796)
		(end 302.47336 -168.712134)
		(width 0.14732)
		(layer "In6.Cu")
		(net "UPI_CPU0_CPU1_P0P1_DP<23>")
	)
	(segment
		(start 113.295684 -212.674962)
		(end 113.295684 -213.470744)
		(width 0.0889)
		(layer "In6.Cu")
		(net "UPI_CPU0_CPU1_P0P1_DP<23>")
	)
	(segment
		(start 112.954308 -213.81212)
		(end 112.954308 -214.40648)
		(width 0.0889)
		(layer "In6.Cu")
		(net "UPI_CPU0_CPU1_P0P1_DP<23>")
	)
	(segment
		(start 113.253774 -209.884264)
		(end 113.253774 -212.610954)
		(width 0.14732)
		(layer "In6.Cu")
		(net "UPI_CPU0_CPU1_P0P1_DP<23>")
	)
	(segment
		(start 149.601428 -171.413678)
		(end 136.542018 -178.099974)
		(width 0.14732)
		(layer "In6.Cu")
		(net "UPI_CPU0_CPU1_P0P1_DP<23>")
	)
	(segment
		(start 358.73563 -213.689438)
		(end 358.73563 -211.794852)
		(width 0.0889)
		(layer "In6.Cu")
		(net "UPI_CPU0_CPU1_P0P1_DP<23>")
	)
	(segment
		(start 358.777794 -211.752688)
		(end 358.777794 -211.73059)
		(width 0.0889)
		(layer "In6.Cu")
		(net "UPI_CPU0_CPU1_P0P1_DP<23>")
	)
	(segment
		(start 136.542018 -178.099974)
		(end 132.247132 -183.863996)
		(width 0.14732)
		(layer "In6.Cu")
		(net "UPI_CPU0_CPU1_P0P1_DP<23>")
	)
	(segment
		(start 320.780918 -170.851068)
		(end 320.780918 -170.851322)
		(width 0.14732)
		(layer "In6.Cu")
		(net "UPI_CPU0_CPU1_P0P1_DP<23>")
	)
	(segment
		(start 132.247132 -183.863996)
		(end 124.026168 -189.32779)
		(width 0.14732)
		(layer "In6.Cu")
		(net "UPI_CPU0_CPU1_P0P1_DP<23>")
	)
	(segment
		(start 112.954308 -214.40648)
		(end 112.814354 -214.546434)
		(width 0.0889)
		(layer "In6.Cu")
		(net "UPI_CPU0_CPU1_P0P1_DP<23>")
	)
	(segment
		(start 112.814354 -214.546434)
		(end 112.579658 -214.546434)
		(width 0.0889)
		(layer "In6.Cu")
		(net "UPI_CPU0_CPU1_P0P1_DP<23>")
	)
	(segment
		(start 358.77754 -209.929476)
		(end 357.617522 -198.931784)
		(width 0.14732)
		(layer "In6.Cu")
		(net "UPI_CPU0_CPU1_P0P1_DP<23>")
	)
	(segment
		(start 302.47336 -168.712134)
		(end 302.473106 -168.71188)
		(width 0.14732)
		(layer "In6.Cu")
		(net "UPI_CPU0_CPU1_P0P1_DP<23>")
	)
	(segment
		(start 113.253774 -212.610954)
		(end 113.253774 -212.633052)
		(width 0.0889)
		(layer "In6.Cu")
		(net "UPI_CPU0_CPU1_P0P1_DP<23>")
	)
	(segment
		(start 302.467518 -168.71188)
		(end 302.461676 -168.712134)
		(width 0.14732)
		(layer "In6.Cu")
		(net "UPI_CPU0_CPU1_P0P1_DP<23>")
	)
	(segment
		(start 342.221566 -182.926482)
		(end 337.995006 -179.850796)
		(width 0.14732)
		(layer "In6.Cu")
		(net "UPI_CPU0_CPU1_P0P1_DP<23>")
	)
	(segment
		(start 337.995006 -179.850796)
		(end 320.780918 -170.851068)
		(width 0.14732)
		(layer "In6.Cu")
		(net "UPI_CPU0_CPU1_P0P1_DP<23>")
	)
	(segment
		(start 358.73563 -211.794852)
		(end 358.777794 -211.752688)
		(width 0.0889)
		(layer "In6.Cu")
		(net "UPI_CPU0_CPU1_P0P1_DP<23>")
	)
	(segment
		(start 238.595154 -169.594276)
		(end 210.78698 -169.594276)
		(width 0.14732)
		(layer "In6.Cu")
		(net "UPI_CPU0_CPU1_P0P1_DP<23>")
	)
	(segment
		(start 302.473106 -168.71188)
		(end 302.467518 -168.71188)
		(width 0.14732)
		(layer "In6.Cu")
		(net "UPI_CPU0_CPU1_P0P1_DP<23>")
	)
	(segment
		(start 320.59118 -170.740832)
		(end 314.109608 -168.928796)
		(width 0.14732)
		(layer "In6.Cu")
		(net "UPI_CPU0_CPU1_P0P1_DP<23>")
	)
	(segment
		(start 113.253774 -212.633052)
		(end 113.295684 -212.674962)
		(width 0.0889)
		(layer "In6.Cu")
		(net "UPI_CPU0_CPU1_P0P1_DP<23>")
	)
	(segment
		(start 359.205276 -214.159084)
		(end 358.73563 -213.689438)
		(width 0.0889)
		(layer "In6.Cu")
		(net "UPI_CPU0_CPU1_P0P1_DP<23>")
	)
	(segment
		(start 358.777794 -210.815936)
		(end 358.77754 -210.81619)
		(width 0.14732)
		(layer "In6.Cu")
		(net "UPI_CPU0_CPU1_P0P1_DP<23>")
	)
	(segment
		(start 273.025362 -169.42943)
		(end 238.595154 -169.594276)
		(width 0.14732)
		(layer "In6.Cu")
		(net "UPI_CPU0_CPU1_P0P1_DP<23>")
	)
	(segment
		(start 113.295684 -213.470744)
		(end 112.954308 -213.81212)
		(width 0.0889)
		(layer "In6.Cu")
		(net "UPI_CPU0_CPU1_P0P1_DP<23>")
	)
	(segment
		(start 358.777794 -211.73059)
		(end 358.777794 -210.815936)
		(width 0.14732)
		(layer "In6.Cu")
		(net "UPI_CPU0_CPU1_P0P1_DP<23>")
	)
	(segment
		(start 117.74424 -197.056502)
		(end 113.253774 -209.884264)
		(width 0.14732)
		(layer "In6.Cu")
		(net "UPI_CPU0_CPU1_P0P1_DP<23>")
	)
	(segment
		(start 200.412096 -169.138854)
		(end 155.57754 -169.884344)
		(width 0.14732)
		(layer "In6.Cu")
		(net "UPI_CPU0_CPU1_P0P1_DP<23>")
	)
	(segment
		(start 320.780918 -170.851322)
		(end 320.59118 -170.740832)
		(width 0.14732)
		(layer "In6.Cu")
		(net "UPI_CPU0_CPU1_P0P1_DP<23>")
	)
	(segment
		(start 210.78698 -169.594276)
		(end 200.412096 -169.138854)
		(width 0.14732)
		(layer "In6.Cu")
		(net "UPI_CPU0_CPU1_P0P1_DP<23>")
	)
	(segment
		(start 359.11028 -215.436704)
		(end 358.953816 -215.165686)
		(width 0.0889)
		(layer "In6.Cu")
		(net "UPI_CPU0_CPU1_P0P1_DP<23>")
	)
	(segment
		(start 302.461676 -168.712134)
		(end 273.025362 -169.42943)
		(width 0.14732)
		(layer "In6.Cu")
		(net "UPI_CPU0_CPU1_P0P1_DP<23>")
	)
	(segment
		(start 357.617522 -198.931784)
		(end 353.429824 -193.769996)
		(width 0.14732)
		(layer "In6.Cu")
		(net "UPI_CPU0_CPU1_P0P1_DP<23>")
	)
	(segment
		(start 124.026168 -189.32779)
		(end 117.74424 -197.056502)
		(width 0.14732)
		(layer "In6.Cu")
		(net "UPI_CPU0_CPU1_P0P1_DP<23>")
	)
	(segment
		(start 358.953816 -215.165686)
		(end 358.977946 -215.076532)
		(width 0.0889)
		(layer "In6.Cu")
		(net "UPI_CPU0_CPU1_P0P1_DP<23>")
	)
	(segment
		(start 358.77754 -210.81619)
		(end 358.77754 -209.929476)
		(width 0.14732)
		(layer "In6.Cu")
		(net "UPI_CPU0_CPU1_P0P1_DP<23>")
	)
	(arc
		(start 358.977946 -215.076532)
		(mid 358.986389 -215.070134)
		(end 358.99471 -215.063578)
		(width 0.0889)
		(layer "In6.Cu")
		(net "UPI_CPU0_CPU1_P0P1_DP<23>")
	)
	(arc
		(start 358.99471 -215.063578)
		(mid 359.145459 -214.877005)
		(end 359.205276 -214.644732)
		(width 0.0889)
		(layer "In6.Cu")
		(net "UPI_CPU0_CPU1_P0P1_DP<23>")
	)
	(segment
		(start 113.989866 -215.436958)
		(end 113.989612 -215.436704)
		(width 0.13208)
		(layer "F.Cu")
		(net "UPI_CPU0_CPU1_P0P1_DP<22>")
	)
	(segment
		(start 358.170734 -215.436958)
		(end 358.17048 -215.436704)
		(width 0.13208)
		(layer "F.Cu")
		(net "UPI_CPU0_CPU1_P0P1_DP<22>")
	)
	(segment
		(start 113.989866 -215.972644)
		(end 113.989866 -215.436958)
		(width 0.13208)
		(layer "F.Cu")
		(net "UPI_CPU0_CPU1_P0P1_DP<22>")
	)
	(segment
		(start 358.170734 -215.972644)
		(end 358.170734 -215.436958)
		(width 0.13208)
		(layer "F.Cu")
		(net "UPI_CPU0_CPU1_P0P1_DP<22>")
	)
	(segment
		(start 114.323114 -211.76361)
		(end 114.323114 -211.785708)
		(width 0.0889)
		(layer "In6.Cu")
		(net "UPI_CPU0_CPU1_P0P1_DP<22>")
	)
	(segment
		(start 114.122708 -215.079072)
		(end 114.146076 -215.165686)
		(width 0.0889)
		(layer "In6.Cu")
		(net "UPI_CPU0_CPU1_P0P1_DP<22>")
	)
	(segment
		(start 238.59744 -170.450764)
		(end 211.275168 -170.450764)
		(width 0.14732)
		(layer "In6.Cu")
		(net "UPI_CPU0_CPU1_P0P1_DP<22>")
	)
	(segment
		(start 357.837486 -209.97926)
		(end 356.722426 -199.413368)
		(width 0.14732)
		(layer "In6.Cu")
		(net "UPI_CPU0_CPU1_P0P1_DP<22>")
	)
	(segment
		(start 357.982266 -215.112854)
		(end 357.983282 -215.112346)
		(width 0.0889)
		(layer "In6.Cu")
		(net "UPI_CPU0_CPU1_P0P1_DP<22>")
	)
	(segment
		(start 351.936812 -193.480944)
		(end 341.754968 -183.6293)
		(width 0.14732)
		(layer "In6.Cu")
		(net "UPI_CPU0_CPU1_P0P1_DP<22>")
	)
	(segment
		(start 118.42496 -197.755002)
		(end 114.323114 -209.47126)
		(width 0.14732)
		(layer "In6.Cu")
		(net "UPI_CPU0_CPU1_P0P1_DP<22>")
	)
	(segment
		(start 320.292984 -171.560236)
		(end 313.93384 -169.78249)
		(width 0.14732)
		(layer "In6.Cu")
		(net "UPI_CPU0_CPU1_P0P1_DP<22>")
	)
	(segment
		(start 358.17048 -215.436704)
		(end 357.857806 -215.436704)
		(width 0.0889)
		(layer "In6.Cu")
		(net "UPI_CPU0_CPU1_P0P1_DP<22>")
	)
	(segment
		(start 302.469804 -169.568876)
		(end 302.463962 -169.56913)
		(width 0.14732)
		(layer "In6.Cu")
		(net "UPI_CPU0_CPU1_P0P1_DP<22>")
	)
	(segment
		(start 357.837486 -211.651088)
		(end 357.837486 -211.62899)
		(width 0.0889)
		(layer "In6.Cu")
		(net "UPI_CPU0_CPU1_P0P1_DP<22>")
	)
	(segment
		(start 211.275168 -170.450764)
		(end 201.036936 -170.001438)
		(width 0.14732)
		(layer "In6.Cu")
		(net "UPI_CPU0_CPU1_P0P1_DP<22>")
	)
	(segment
		(start 273.037808 -170.285918)
		(end 238.59744 -170.450764)
		(width 0.14732)
		(layer "In6.Cu")
		(net "UPI_CPU0_CPU1_P0P1_DP<22>")
	)
	(segment
		(start 337.616292 -180.617114)
		(end 320.292984 -171.560236)
		(width 0.14732)
		(layer "In6.Cu")
		(net "UPI_CPU0_CPU1_P0P1_DP<22>")
	)
	(segment
		(start 341.754968 -183.6293)
		(end 337.616292 -180.617114)
		(width 0.14732)
		(layer "In6.Cu")
		(net "UPI_CPU0_CPU1_P0P1_DP<22>")
	)
	(segment
		(start 124.884434 -189.806834)
		(end 118.42496 -197.755002)
		(width 0.14732)
		(layer "In6.Cu")
		(net "UPI_CPU0_CPU1_P0P1_DP<22>")
	)
	(segment
		(start 357.974392 -215.117426)
		(end 357.982266 -215.112854)
		(width 0.0889)
		(layer "In6.Cu")
		(net "UPI_CPU0_CPU1_P0P1_DP<22>")
	)
	(segment
		(start 149.829774 -172.238924)
		(end 137.07618 -178.770026)
		(width 0.14732)
		(layer "In6.Cu")
		(net "UPI_CPU0_CPU1_P0P1_DP<22>")
	)
	(segment
		(start 357.795576 -213.839044)
		(end 357.795576 -211.692998)
		(width 0.0889)
		(layer "In6.Cu")
		(net "UPI_CPU0_CPU1_P0P1_DP<22>")
	)
	(segment
		(start 302.475646 -169.56913)
		(end 302.475392 -169.568876)
		(width 0.14732)
		(layer "In6.Cu")
		(net "UPI_CPU0_CPU1_P0P1_DP<22>")
	)
	(segment
		(start 114.323114 -211.785708)
		(end 114.365024 -211.827618)
		(width 0.0889)
		(layer "In6.Cu")
		(net "UPI_CPU0_CPU1_P0P1_DP<22>")
	)
	(segment
		(start 113.894362 -214.322406)
		(end 113.894362 -214.57666)
		(width 0.0889)
		(layer "In6.Cu")
		(net "UPI_CPU0_CPU1_P0P1_DP<22>")
	)
	(segment
		(start 357.795576 -211.692998)
		(end 357.837486 -211.651088)
		(width 0.0889)
		(layer "In6.Cu")
		(net "UPI_CPU0_CPU1_P0P1_DP<22>")
	)
	(segment
		(start 357.857806 -215.436704)
		(end 357.800402 -215.3793)
		(width 0.0889)
		(layer "In6.Cu")
		(net "UPI_CPU0_CPU1_P0P1_DP<22>")
	)
	(segment
		(start 114.323114 -209.47126)
		(end 114.323114 -211.76361)
		(width 0.14732)
		(layer "In6.Cu")
		(net "UPI_CPU0_CPU1_P0P1_DP<22>")
	)
	(segment
		(start 114.365024 -211.827618)
		(end 114.365024 -213.851744)
		(width 0.0889)
		(layer "In6.Cu")
		(net "UPI_CPU0_CPU1_P0P1_DP<22>")
	)
	(segment
		(start 114.365024 -213.851744)
		(end 113.894362 -214.322406)
		(width 0.0889)
		(layer "In6.Cu")
		(net "UPI_CPU0_CPU1_P0P1_DP<22>")
	)
	(segment
		(start 357.837486 -211.62899)
		(end 357.837486 -209.97926)
		(width 0.14732)
		(layer "In6.Cu")
		(net "UPI_CPU0_CPU1_P0P1_DP<22>")
	)
	(segment
		(start 114.146076 -215.165686)
		(end 113.989612 -215.436704)
		(width 0.0889)
		(layer "In6.Cu")
		(net "UPI_CPU0_CPU1_P0P1_DP<22>")
	)
	(segment
		(start 356.722426 -199.413368)
		(end 351.936812 -193.480944)
		(width 0.14732)
		(layer "In6.Cu")
		(net "UPI_CPU0_CPU1_P0P1_DP<22>")
	)
	(segment
		(start 155.630118 -170.754802)
		(end 149.829774 -172.238924)
		(width 0.14732)
		(layer "In6.Cu")
		(net "UPI_CPU0_CPU1_P0P1_DP<22>")
	)
	(segment
		(start 137.07618 -178.770026)
		(end 132.747004 -184.581038)
		(width 0.14732)
		(layer "In6.Cu")
		(net "UPI_CPU0_CPU1_P0P1_DP<22>")
	)
	(segment
		(start 302.475392 -169.568876)
		(end 302.469804 -169.568876)
		(width 0.14732)
		(layer "In6.Cu")
		(net "UPI_CPU0_CPU1_P0P1_DP<22>")
	)
	(segment
		(start 313.93384 -169.78249)
		(end 302.475646 -169.56913)
		(width 0.14732)
		(layer "In6.Cu")
		(net "UPI_CPU0_CPU1_P0P1_DP<22>")
	)
	(segment
		(start 201.036936 -170.001438)
		(end 155.630118 -170.754802)
		(width 0.14732)
		(layer "In6.Cu")
		(net "UPI_CPU0_CPU1_P0P1_DP<22>")
	)
	(segment
		(start 358.265476 -214.308944)
		(end 357.795576 -213.839044)
		(width 0.0889)
		(layer "In6.Cu")
		(net "UPI_CPU0_CPU1_P0P1_DP<22>")
	)
	(segment
		(start 132.747004 -184.581038)
		(end 124.884434 -189.806834)
		(width 0.14732)
		(layer "In6.Cu")
		(net "UPI_CPU0_CPU1_P0P1_DP<22>")
	)
	(segment
		(start 358.265476 -214.644732)
		(end 358.265476 -214.308944)
		(width 0.0889)
		(layer "In6.Cu")
		(net "UPI_CPU0_CPU1_P0P1_DP<22>")
	)
	(segment
		(start 302.463962 -169.56913)
		(end 273.037808 -170.285918)
		(width 0.14732)
		(layer "In6.Cu")
		(net "UPI_CPU0_CPU1_P0P1_DP<22>")
	)
	(arc
		(start 114.102642 -215.063578)
		(mid 114.112587 -215.071439)
		(end 114.122708 -215.079072)
		(width 0.0889)
		(layer "In6.Cu")
		(net "UPI_CPU0_CPU1_P0P1_DP<22>")
	)
	(arc
		(start 113.894362 -214.57666)
		(mid 113.938178 -214.845919)
		(end 114.102642 -215.063578)
		(width 0.0889)
		(layer "In6.Cu")
		(net "UPI_CPU0_CPU1_P0P1_DP<22>")
	)
	(arc
		(start 357.800402 -215.3793)
		(mid 357.858558 -215.229187)
		(end 357.974392 -215.117426)
		(width 0.0889)
		(layer "In6.Cu")
		(net "UPI_CPU0_CPU1_P0P1_DP<22>")
	)
	(arc
		(start 357.983282 -215.112346)
		(mid 358.184564 -214.914859)
		(end 358.265476 -214.644732)
		(width 0.0889)
		(layer "In6.Cu")
		(net "UPI_CPU0_CPU1_P0P1_DP<22>")
	)
	(segment
		(start 114.929666 -214.344758)
		(end 114.929666 -213.732618)
		(width 0.13208)
		(layer "F.Cu")
		(net "UPI_CPU0_CPU1_P0P1_DP<21>")
	)
	(segment
		(start 356.76078 -215.158574)
		(end 356.76078 -214.622888)
		(width 0.13208)
		(layer "F.Cu")
		(net "UPI_CPU0_CPU1_P0P1_DP<21>")
	)
	(segment
		(start 356.76078 -214.622888)
		(end 356.760526 -214.622634)
		(width 0.13208)
		(layer "F.Cu")
		(net "UPI_CPU0_CPU1_P0P1_DP<21>")
	)
	(segment
		(start 302.472344 -170.432984)
		(end 302.466502 -170.433238)
		(width 0.14732)
		(layer "In6.Cu")
		(net "UPI_CPU0_CPU1_P0P1_DP<21>")
	)
	(segment
		(start 356.89794 -211.66201)
		(end 356.89794 -210.029044)
		(width 0.14732)
		(layer "In6.Cu")
		(net "UPI_CPU0_CPU1_P0P1_DP<21>")
	)
	(segment
		(start 302.477932 -170.432984)
		(end 302.472344 -170.432984)
		(width 0.14732)
		(layer "In6.Cu")
		(net "UPI_CPU0_CPU1_P0P1_DP<21>")
	)
	(segment
		(start 356.89794 -210.029044)
		(end 355.798374 -199.611488)
		(width 0.14732)
		(layer "In6.Cu")
		(net "UPI_CPU0_CPU1_P0P1_DP<21>")
	)
	(segment
		(start 356.385876 -214.622634)
		(end 356.385876 -214.461852)
		(width 0.0889)
		(layer "In6.Cu")
		(net "UPI_CPU0_CPU1_P0P1_DP<21>")
	)
	(segment
		(start 356.57028 -214.261954)
		(end 356.85603 -213.976204)
		(width 0.0889)
		(layer "In6.Cu")
		(net "UPI_CPU0_CPU1_P0P1_DP<21>")
	)
	(segment
		(start 356.85603 -213.516972)
		(end 356.955344 -213.417658)
		(width 0.0889)
		(layer "In6.Cu")
		(net "UPI_CPU0_CPU1_P0P1_DP<21>")
	)
	(segment
		(start 115.262406 -211.780628)
		(end 115.304316 -211.822538)
		(width 0.0889)
		(layer "In6.Cu")
		(net "UPI_CPU0_CPU1_P0P1_DP<21>")
	)
	(segment
		(start 356.85603 -213.976204)
		(end 356.85603 -213.516972)
		(width 0.0889)
		(layer "In6.Cu")
		(net "UPI_CPU0_CPU1_P0P1_DP<21>")
	)
	(segment
		(start 115.088416 -214.033608)
		(end 114.929666 -213.732618)
		(width 0.0889)
		(layer "In6.Cu")
		(net "UPI_CPU0_CPU1_P0P1_DP<21>")
	)
	(segment
		(start 355.798374 -199.611488)
		(end 351.2185 -193.941446)
		(width 0.14732)
		(layer "In6.Cu")
		(net "UPI_CPU0_CPU1_P0P1_DP<21>")
	)
	(segment
		(start 320.00571 -172.386498)
		(end 313.769502 -170.643296)
		(width 0.14732)
		(layer "In6.Cu")
		(net "UPI_CPU0_CPU1_P0P1_DP<21>")
	)
	(segment
		(start 200.736454 -170.842178)
		(end 155.980384 -171.585128)
		(width 0.14732)
		(layer "In6.Cu")
		(net "UPI_CPU0_CPU1_P0P1_DP<21>")
	)
	(segment
		(start 302.478186 -170.433238)
		(end 302.477932 -170.432984)
		(width 0.14732)
		(layer "In6.Cu")
		(net "UPI_CPU0_CPU1_P0P1_DP<21>")
	)
	(segment
		(start 356.955344 -212.41893)
		(end 356.85603 -212.319616)
		(width 0.0889)
		(layer "In6.Cu")
		(net "UPI_CPU0_CPU1_P0P1_DP<21>")
	)
	(segment
		(start 356.955344 -213.417658)
		(end 356.955344 -213.150958)
		(width 0.0889)
		(layer "In6.Cu")
		(net "UPI_CPU0_CPU1_P0P1_DP<21>")
	)
	(segment
		(start 337.326986 -181.441344)
		(end 320.00571 -172.386498)
		(width 0.14732)
		(layer "In6.Cu")
		(net "UPI_CPU0_CPU1_P0P1_DP<21>")
	)
	(segment
		(start 115.262406 -211.75853)
		(end 115.262406 -211.780628)
		(width 0.0889)
		(layer "In6.Cu")
		(net "UPI_CPU0_CPU1_P0P1_DP<21>")
	)
	(segment
		(start 356.955344 -212.68563)
		(end 356.955344 -212.41893)
		(width 0.0889)
		(layer "In6.Cu")
		(net "UPI_CPU0_CPU1_P0P1_DP<21>")
	)
	(segment
		(start 356.85603 -213.051644)
		(end 356.85603 -212.784944)
		(width 0.0889)
		(layer "In6.Cu")
		(net "UPI_CPU0_CPU1_P0P1_DP<21>")
	)
	(segment
		(start 149.912832 -173.137576)
		(end 137.61339 -179.43576)
		(width 0.14732)
		(layer "In6.Cu")
		(net "UPI_CPU0_CPU1_P0P1_DP<21>")
	)
	(segment
		(start 115.172998 -214.05977)
		(end 115.088416 -214.033608)
		(width 0.0889)
		(layer "In6.Cu")
		(net "UPI_CPU0_CPU1_P0P1_DP<21>")
	)
	(segment
		(start 356.955344 -213.150958)
		(end 356.85603 -213.051644)
		(width 0.0889)
		(layer "In6.Cu")
		(net "UPI_CPU0_CPU1_P0P1_DP<21>")
	)
	(segment
		(start 273.050508 -171.149518)
		(end 238.599218 -171.314364)
		(width 0.14732)
		(layer "In6.Cu")
		(net "UPI_CPU0_CPU1_P0P1_DP<21>")
	)
	(segment
		(start 211.49564 -171.314364)
		(end 200.736454 -170.842178)
		(width 0.14732)
		(layer "In6.Cu")
		(net "UPI_CPU0_CPU1_P0P1_DP<21>")
	)
	(segment
		(start 238.599218 -171.314364)
		(end 211.49564 -171.314364)
		(width 0.14732)
		(layer "In6.Cu")
		(net "UPI_CPU0_CPU1_P0P1_DP<21>")
	)
	(segment
		(start 119.080534 -198.480426)
		(end 115.262406 -209.386932)
		(width 0.14732)
		(layer "In6.Cu")
		(net "UPI_CPU0_CPU1_P0P1_DP<21>")
	)
	(segment
		(start 356.85603 -211.726018)
		(end 356.89794 -211.684108)
		(width 0.0889)
		(layer "In6.Cu")
		(net "UPI_CPU0_CPU1_P0P1_DP<21>")
	)
	(segment
		(start 313.769502 -170.643296)
		(end 302.478186 -170.433238)
		(width 0.14732)
		(layer "In6.Cu")
		(net "UPI_CPU0_CPU1_P0P1_DP<21>")
	)
	(segment
		(start 137.61339 -179.43576)
		(end 133.304534 -185.219594)
		(width 0.14732)
		(layer "In6.Cu")
		(net "UPI_CPU0_CPU1_P0P1_DP<21>")
	)
	(segment
		(start 356.85603 -212.319616)
		(end 356.85603 -211.726018)
		(width 0.0889)
		(layer "In6.Cu")
		(net "UPI_CPU0_CPU1_P0P1_DP<21>")
	)
	(segment
		(start 356.604062 -214.893652)
		(end 356.52583 -214.91448)
		(width 0.0889)
		(layer "In6.Cu")
		(net "UPI_CPU0_CPU1_P0P1_DP<21>")
	)
	(segment
		(start 125.811026 -190.200026)
		(end 119.080534 -198.480426)
		(width 0.14732)
		(layer "In6.Cu")
		(net "UPI_CPU0_CPU1_P0P1_DP<21>")
	)
	(segment
		(start 302.466502 -170.433238)
		(end 273.050508 -171.149518)
		(width 0.14732)
		(layer "In6.Cu")
		(net "UPI_CPU0_CPU1_P0P1_DP<21>")
	)
	(segment
		(start 115.304316 -211.822538)
		(end 115.304316 -213.8934)
		(width 0.0889)
		(layer "In6.Cu")
		(net "UPI_CPU0_CPU1_P0P1_DP<21>")
	)
	(segment
		(start 356.760526 -214.622634)
		(end 356.604062 -214.893652)
		(width 0.0889)
		(layer "In6.Cu")
		(net "UPI_CPU0_CPU1_P0P1_DP<21>")
	)
	(segment
		(start 356.85603 -212.784944)
		(end 356.955344 -212.68563)
		(width 0.0889)
		(layer "In6.Cu")
		(net "UPI_CPU0_CPU1_P0P1_DP<21>")
	)
	(segment
		(start 115.262406 -209.386932)
		(end 115.262406 -211.75853)
		(width 0.14732)
		(layer "In6.Cu")
		(net "UPI_CPU0_CPU1_P0P1_DP<21>")
	)
	(segment
		(start 133.304534 -185.219594)
		(end 125.811026 -190.200026)
		(width 0.14732)
		(layer "In6.Cu")
		(net "UPI_CPU0_CPU1_P0P1_DP<21>")
	)
	(segment
		(start 351.2185 -193.941446)
		(end 341.252556 -184.299098)
		(width 0.14732)
		(layer "In6.Cu")
		(net "UPI_CPU0_CPU1_P0P1_DP<21>")
	)
	(segment
		(start 341.252556 -184.299098)
		(end 337.326986 -181.441344)
		(width 0.14732)
		(layer "In6.Cu")
		(net "UPI_CPU0_CPU1_P0P1_DP<21>")
	)
	(segment
		(start 356.89794 -211.684108)
		(end 356.89794 -211.66201)
		(width 0.0889)
		(layer "In6.Cu")
		(net "UPI_CPU0_CPU1_P0P1_DP<21>")
	)
	(segment
		(start 155.980384 -171.585128)
		(end 149.912832 -173.137576)
		(width 0.14732)
		(layer "In6.Cu")
		(net "UPI_CPU0_CPU1_P0P1_DP<21>")
	)
	(arc
		(start 115.304316 -213.8934)
		(mid 115.249646 -213.985256)
		(end 115.172998 -214.05977)
		(width 0.0889)
		(layer "In6.Cu")
		(net "UPI_CPU0_CPU1_P0P1_DP<21>")
	)
	(arc
		(start 356.52583 -214.91448)
		(mid 356.422685 -214.784455)
		(end 356.385876 -214.622634)
		(width 0.0889)
		(layer "In6.Cu")
		(net "UPI_CPU0_CPU1_P0P1_DP<21>")
	)
	(arc
		(start 356.385876 -214.461852)
		(mid 356.460947 -214.34611)
		(end 356.57028 -214.261954)
		(width 0.0889)
		(layer "In6.Cu")
		(net "UPI_CPU0_CPU1_P0P1_DP<21>")
	)
	(segment
		(start 115.869466 -215.436958)
		(end 115.869212 -215.436704)
		(width 0.13208)
		(layer "F.Cu")
		(net "UPI_CPU0_CPU1_P0P1_DP<20>")
	)
	(segment
		(start 115.869466 -215.972644)
		(end 115.869466 -215.436958)
		(width 0.13208)
		(layer "F.Cu")
		(net "UPI_CPU0_CPU1_P0P1_DP<20>")
	)
	(segment
		(start 355.82098 -215.158574)
		(end 355.82098 -214.622888)
		(width 0.13208)
		(layer "F.Cu")
		(net "UPI_CPU0_CPU1_P0P1_DP<20>")
	)
	(segment
		(start 355.82098 -214.622888)
		(end 355.820726 -214.622634)
		(width 0.13208)
		(layer "F.Cu")
		(net "UPI_CPU0_CPU1_P0P1_DP<20>")
	)
	(segment
		(start 126.683008 -190.640716)
		(end 125.31725 -192.320926)
		(width 0.14732)
		(layer "In6.Cu")
		(net "UPI_CPU0_CPU1_P0P1_DP<20>")
	)
	(segment
		(start 116.20246 -211.706968)
		(end 116.24437 -211.748878)
		(width 0.0889)
		(layer "In6.Cu")
		(net "UPI_CPU0_CPU1_P0P1_DP<20>")
	)
	(segment
		(start 116.025676 -215.165686)
		(end 115.869212 -215.436704)
		(width 0.0889)
		(layer "In6.Cu")
		(net "UPI_CPU0_CPU1_P0P1_DP<20>")
	)
	(segment
		(start 355.958394 -210.078828)
		(end 354.875338 -199.81926)
		(width 0.14732)
		(layer "In6.Cu")
		(net "UPI_CPU0_CPU1_P0P1_DP<20>")
	)
	(segment
		(start 116.202206 -209.23885)
		(end 116.202206 -211.706714)
		(width 0.14732)
		(layer "In6.Cu")
		(net "UPI_CPU0_CPU1_P0P1_DP<20>")
	)
	(segment
		(start 238.601504 -172.156882)
		(end 211.643976 -172.156882)
		(width 0.14732)
		(layer "In6.Cu")
		(net "UPI_CPU0_CPU1_P0P1_DP<20>")
	)
	(segment
		(start 355.958394 -211.68995)
		(end 355.958394 -210.078828)
		(width 0.14732)
		(layer "In6.Cu")
		(net "UPI_CPU0_CPU1_P0P1_DP<20>")
	)
	(segment
		(start 133.857746 -185.87212)
		(end 126.683008 -190.640716)
		(width 0.14732)
		(layer "In6.Cu")
		(net "UPI_CPU0_CPU1_P0P1_DP<20>")
	)
	(segment
		(start 138.148822 -180.111908)
		(end 135.969756 -183.036718)
		(width 0.14732)
		(layer "In6.Cu")
		(net "UPI_CPU0_CPU1_P0P1_DP<20>")
	)
	(segment
		(start 340.74481 -184.973722)
		(end 336.91703 -182.186834)
		(width 0.14732)
		(layer "In6.Cu")
		(net "UPI_CPU0_CPU1_P0P1_DP<20>")
	)
	(segment
		(start 302.480472 -171.276264)
		(end 302.480218 -171.27601)
		(width 0.14732)
		(layer "In6.Cu")
		(net "UPI_CPU0_CPU1_P0P1_DP<20>")
	)
	(segment
		(start 350.523302 -194.434206)
		(end 340.74481 -184.973722)
		(width 0.14732)
		(layer "In6.Cu")
		(net "UPI_CPU0_CPU1_P0P1_DP<20>")
	)
	(segment
		(start 115.773708 -214.425784)
		(end 115.773708 -214.636858)
		(width 0.0889)
		(layer "In6.Cu")
		(net "UPI_CPU0_CPU1_P0P1_DP<20>")
	)
	(segment
		(start 116.24437 -211.748878)
		(end 116.24437 -213.892892)
		(width 0.0889)
		(layer "In6.Cu")
		(net "UPI_CPU0_CPU1_P0P1_DP<20>")
	)
	(segment
		(start 313.65698 -171.484036)
		(end 302.480472 -171.276264)
		(width 0.14732)
		(layer "In6.Cu")
		(net "UPI_CPU0_CPU1_P0P1_DP<20>")
	)
	(segment
		(start 135.97001 -183.036718)
		(end 133.857746 -185.87212)
		(width 0.14732)
		(layer "In6.Cu")
		(net "UPI_CPU0_CPU1_P0P1_DP<20>")
	)
	(segment
		(start 119.709184 -199.221344)
		(end 116.202206 -209.23885)
		(width 0.14732)
		(layer "In6.Cu")
		(net "UPI_CPU0_CPU1_P0P1_DP<20>")
	)
	(segment
		(start 355.820726 -214.622634)
		(end 355.661976 -214.321644)
		(width 0.0889)
		(layer "In6.Cu")
		(net "UPI_CPU0_CPU1_P0P1_DP<20>")
	)
	(segment
		(start 355.958394 -211.712048)
		(end 355.958394 -211.68995)
		(width 0.0889)
		(layer "In6.Cu")
		(net "UPI_CPU0_CPU1_P0P1_DP<20>")
	)
	(segment
		(start 355.661976 -214.321644)
		(end 355.692202 -214.22487)
		(width 0.0889)
		(layer "In6.Cu")
		(net "UPI_CPU0_CPU1_P0P1_DP<20>")
	)
	(segment
		(start 336.91703 -182.186834)
		(end 319.64757 -173.158658)
		(width 0.14732)
		(layer "In6.Cu")
		(net "UPI_CPU0_CPU1_P0P1_DP<20>")
	)
	(segment
		(start 156.453078 -172.422058)
		(end 149.880828 -174.103538)
		(width 0.14732)
		(layer "In6.Cu")
		(net "UPI_CPU0_CPU1_P0P1_DP<20>")
	)
	(segment
		(start 116.202206 -211.706714)
		(end 116.20246 -211.706968)
		(width 0.14732)
		(layer "In6.Cu")
		(net "UPI_CPU0_CPU1_P0P1_DP<20>")
	)
	(segment
		(start 125.31725 -192.32118)
		(end 119.709184 -199.221344)
		(width 0.14732)
		(layer "In6.Cu")
		(net "UPI_CPU0_CPU1_P0P1_DP<20>")
	)
	(segment
		(start 273.062954 -171.992036)
		(end 238.601504 -172.156882)
		(width 0.14732)
		(layer "In6.Cu")
		(net "UPI_CPU0_CPU1_P0P1_DP<20>")
	)
	(segment
		(start 302.47463 -171.27601)
		(end 302.468788 -171.276264)
		(width 0.14732)
		(layer "In6.Cu")
		(net "UPI_CPU0_CPU1_P0P1_DP<20>")
	)
	(segment
		(start 302.468788 -171.276264)
		(end 273.062954 -171.992036)
		(width 0.14732)
		(layer "In6.Cu")
		(net "UPI_CPU0_CPU1_P0P1_DP<20>")
	)
	(segment
		(start 211.643976 -172.156882)
		(end 200.881488 -171.684442)
		(width 0.14732)
		(layer "In6.Cu")
		(net "UPI_CPU0_CPU1_P0P1_DP<20>")
	)
	(segment
		(start 116.24437 -213.892892)
		(end 116.244116 -213.8934)
		(width 0.0889)
		(layer "In6.Cu")
		(net "UPI_CPU0_CPU1_P0P1_DP<20>")
	)
	(segment
		(start 125.31725 -192.320926)
		(end 125.31725 -192.32118)
		(width 0.14732)
		(layer "In6.Cu")
		(net "UPI_CPU0_CPU1_P0P1_DP<20>")
	)
	(segment
		(start 116.001546 -215.076532)
		(end 116.025676 -215.165686)
		(width 0.0889)
		(layer "In6.Cu")
		(net "UPI_CPU0_CPU1_P0P1_DP<20>")
	)
	(segment
		(start 149.880828 -174.103538)
		(end 138.148822 -180.111908)
		(width 0.14732)
		(layer "In6.Cu")
		(net "UPI_CPU0_CPU1_P0P1_DP<20>")
	)
	(segment
		(start 355.916484 -213.929468)
		(end 355.916484 -211.753958)
		(width 0.0889)
		(layer "In6.Cu")
		(net "UPI_CPU0_CPU1_P0P1_DP<20>")
	)
	(segment
		(start 354.875338 -199.81926)
		(end 350.523302 -194.434206)
		(width 0.14732)
		(layer "In6.Cu")
		(net "UPI_CPU0_CPU1_P0P1_DP<20>")
	)
	(segment
		(start 319.64757 -173.158658)
		(end 313.65698 -171.484036)
		(width 0.14732)
		(layer "In6.Cu")
		(net "UPI_CPU0_CPU1_P0P1_DP<20>")
	)
	(segment
		(start 135.969756 -183.036718)
		(end 135.97001 -183.036718)
		(width 0.14732)
		(layer "In6.Cu")
		(net "UPI_CPU0_CPU1_P0P1_DP<20>")
	)
	(segment
		(start 302.480218 -171.27601)
		(end 302.47463 -171.27601)
		(width 0.14732)
		(layer "In6.Cu")
		(net "UPI_CPU0_CPU1_P0P1_DP<20>")
	)
	(segment
		(start 355.916484 -211.753958)
		(end 355.958394 -211.712048)
		(width 0.0889)
		(layer "In6.Cu")
		(net "UPI_CPU0_CPU1_P0P1_DP<20>")
	)
	(segment
		(start 200.881488 -171.684442)
		(end 156.453078 -172.422058)
		(width 0.14732)
		(layer "In6.Cu")
		(net "UPI_CPU0_CPU1_P0P1_DP<20>")
	)
	(arc
		(start 116.244116 -213.8934)
		(mid 116.169045 -214.009142)
		(end 116.059712 -214.093298)
		(width 0.0889)
		(layer "In6.Cu")
		(net "UPI_CPU0_CPU1_P0P1_DP<20>")
	)
	(arc
		(start 355.692202 -214.22487)
		(mid 355.814948 -214.111365)
		(end 355.901498 -213.96833)
		(width 0.0889)
		(layer "In6.Cu")
		(net "UPI_CPU0_CPU1_P0P1_DP<20>")
	)
	(arc
		(start 115.773708 -214.636858)
		(mid 115.832053 -214.873363)
		(end 115.984528 -215.063324)
		(width 0.0889)
		(layer "In6.Cu")
		(net "UPI_CPU0_CPU1_P0P1_DP<20>")
	)
	(arc
		(start 115.984528 -215.063324)
		(mid 115.992974 -215.070009)
		(end 116.001546 -215.076532)
		(width 0.0889)
		(layer "In6.Cu")
		(net "UPI_CPU0_CPU1_P0P1_DP<20>")
	)
	(arc
		(start 116.059712 -214.093298)
		(mid 115.885164 -214.232402)
		(end 115.773708 -214.425784)
		(width 0.0889)
		(layer "In6.Cu")
		(net "UPI_CPU0_CPU1_P0P1_DP<20>")
	)
	(arc
		(start 355.901498 -213.96833)
		(mid 355.909333 -213.949031)
		(end 355.916484 -213.929468)
		(width 0.0889)
		(layer "In6.Cu")
		(net "UPI_CPU0_CPU1_P0P1_DP<20>")
	)
	(segment
		(start 134.665466 -215.972644)
		(end 134.665466 -215.436958)
		(width 0.13208)
		(layer "F.Cu")
		(net "UPI_CPU0_CPU1_P0P1_DP<1>")
	)
	(segment
		(start 337.495134 -215.436958)
		(end 337.49488 -215.436704)
		(width 0.13208)
		(layer "F.Cu")
		(net "UPI_CPU0_CPU1_P0P1_DP<1>")
	)
	(segment
		(start 134.665466 -215.436958)
		(end 134.665212 -215.436704)
		(width 0.13208)
		(layer "F.Cu")
		(net "UPI_CPU0_CPU1_P0P1_DP<1>")
	)
	(segment
		(start 337.495134 -215.972644)
		(end 337.495134 -215.436958)
		(width 0.13208)
		(layer "F.Cu")
		(net "UPI_CPU0_CPU1_P0P1_DP<1>")
	)
	(segment
		(start 337.399376 -213.862158)
		(end 337.76031 -213.501224)
		(width 0.0889)
		(layer "In6.Cu")
		(net "UPI_CPU0_CPU1_P0P1_DP<1>")
	)
	(segment
		(start 147.424648 -199.73163)
		(end 147.42668 -200.166986)
		(width 0.14732)
		(layer "In6.Cu")
		(net "UPI_CPU0_CPU1_P0P1_DP<1>")
	)
	(segment
		(start 144.319752 -202.142852)
		(end 143.903954 -202.56246)
		(width 0.14732)
		(layer "In6.Cu")
		(net "UPI_CPU0_CPU1_P0P1_DP<1>")
	)
	(segment
		(start 239.036352 -199.73417)
		(end 237.361222 -199.943466)
		(width 0.14732)
		(layer "In6.Cu")
		(net "UPI_CPU0_CPU1_P0P1_DP<1>")
	)
	(segment
		(start 148.965412 -197.616064)
		(end 149.246336 -197.89394)
		(width 0.14732)
		(layer "In6.Cu")
		(net "UPI_CPU0_CPU1_P0P1_DP<1>")
	)
	(segment
		(start 134.290562 -215.275922)
		(end 134.290562 -215.374728)
		(width 0.0889)
		(layer "In6.Cu")
		(net "UPI_CPU0_CPU1_P0P1_DP<1>")
	)
	(segment
		(start 313.51855 -190.026036)
		(end 312.946542 -188.543184)
		(width 0.14732)
		(layer "In6.Cu")
		(net "UPI_CPU0_CPU1_P0P1_DP<1>")
	)
	(segment
		(start 134.760716 -213.927944)
		(end 134.760716 -214.7443)
		(width 0.0889)
		(layer "In6.Cu")
		(net "UPI_CPU0_CPU1_P0P1_DP<1>")
	)
	(segment
		(start 134.352538 -215.436704)
		(end 134.665212 -215.436704)
		(width 0.0889)
		(layer "In6.Cu")
		(net "UPI_CPU0_CPU1_P0P1_DP<1>")
	)
	(segment
		(start 142.51305 -205.299818)
		(end 142.205202 -205.61046)
		(width 0.14732)
		(layer "In6.Cu")
		(net "UPI_CPU0_CPU1_P0P1_DP<1>")
	)
	(segment
		(start 165.628066 -188.828172)
		(end 165.479222 -188.972952)
		(width 0.14732)
		(layer "In6.Cu")
		(net "UPI_CPU0_CPU1_P0P1_DP<1>")
	)
	(segment
		(start 149.58822 -196.987922)
		(end 149.380448 -196.988938)
		(width 0.14732)
		(layer "In6.Cu")
		(net "UPI_CPU0_CPU1_P0P1_DP<1>")
	)
	(segment
		(start 163.16198 -188.94171)
		(end 163.139882 -190.592964)
		(width 0.14732)
		(layer "In6.Cu")
		(net "UPI_CPU0_CPU1_P0P1_DP<1>")
	)
	(segment
		(start 142.032736 -205.611222)
		(end 141.725396 -205.921356)
		(width 0.14732)
		(layer "In6.Cu")
		(net "UPI_CPU0_CPU1_P0P1_DP<1>")
	)
	(segment
		(start 141.41831 -206.404464)
		(end 141.245844 -206.405226)
		(width 0.14732)
		(layer "In6.Cu")
		(net "UPI_CPU0_CPU1_P0P1_DP<1>")
	)
	(segment
		(start 165.479222 -188.972952)
		(end 165.457124 -190.624206)
		(width 0.14732)
		(layer "In6.Cu")
		(net "UPI_CPU0_CPU1_P0P1_DP<1>")
	)
	(segment
		(start 163.139882 -190.592964)
		(end 162.828478 -190.897002)
		(width 0.14732)
		(layer "In6.Cu")
		(net "UPI_CPU0_CPU1_P0P1_DP<1>")
	)
	(segment
		(start 142.205202 -205.61046)
		(end 142.032736 -205.611222)
		(width 0.14732)
		(layer "In6.Cu")
		(net "UPI_CPU0_CPU1_P0P1_DP<1>")
	)
	(segment
		(start 163.901374 -188.804804)
		(end 163.310824 -188.79693)
		(width 0.14732)
		(layer "In6.Cu")
		(net "UPI_CPU0_CPU1_P0P1_DP<1>")
	)
	(segment
		(start 139.339066 -209.119216)
		(end 139.379198 -209.319876)
		(width 0.14732)
		(layer "In6.Cu")
		(net "UPI_CPU0_CPU1_P0P1_DP<1>")
	)
	(segment
		(start 298.43476 -190.580518)
		(end 297.719496 -190.744856)
		(width 0.14732)
		(layer "In6.Cu")
		(net "UPI_CPU0_CPU1_P0P1_DP<1>")
	)
	(segment
		(start 145.535142 -200.915778)
		(end 145.536158 -201.12355)
		(width 0.14732)
		(layer "In6.Cu")
		(net "UPI_CPU0_CPU1_P0P1_DP<1>")
	)
	(segment
		(start 149.380448 -196.988938)
		(end 148.964396 -197.408292)
		(width 0.14732)
		(layer "In6.Cu")
		(net "UPI_CPU0_CPU1_P0P1_DP<1>")
	)
	(segment
		(start 250.227338 -194.613022)
		(end 239.036352 -199.73417)
		(width 0.14732)
		(layer "In6.Cu")
		(net "UPI_CPU0_CPU1_P0P1_DP<1>")
	)
	(segment
		(start 335.706466 -209.710528)
		(end 315.081666 -193.562478)
		(width 0.14732)
		(layer "In6.Cu")
		(net "UPI_CPU0_CPU1_P0P1_DP<1>")
	)
	(segment
		(start 311.791858 -187.970922)
		(end 302.473106 -187.788804)
		(width 0.14732)
		(layer "In6.Cu")
		(net "UPI_CPU0_CPU1_P0P1_DP<1>")
	)
	(segment
		(start 144.164304 -203.460604)
		(end 142.512288 -205.127352)
		(width 0.14732)
		(layer "In6.Cu")
		(net "UPI_CPU0_CPU1_P0P1_DP<1>")
	)
	(segment
		(start 138.762994 -209.984594)
		(end 135.943086 -212.804502)
		(width 0.14732)
		(layer "In6.Cu")
		(net "UPI_CPU0_CPU1_P0P1_DP<1>")
	)
	(segment
		(start 141.245844 -206.405226)
		(end 140.938504 -206.71536)
		(width 0.14732)
		(layer "In6.Cu")
		(net "UPI_CPU0_CPU1_P0P1_DP<1>")
	)
	(segment
		(start 134.290562 -215.374728)
		(end 134.352538 -215.436704)
		(width 0.0889)
		(layer "In6.Cu")
		(net "UPI_CPU0_CPU1_P0P1_DP<1>")
	)
	(segment
		(start 313.435492 -190.213234)
		(end 313.51855 -190.026036)
		(width 0.14732)
		(layer "In6.Cu")
		(net "UPI_CPU0_CPU1_P0P1_DP<1>")
	)
	(segment
		(start 163.310824 -188.79693)
		(end 163.16198 -188.94171)
		(width 0.14732)
		(layer "In6.Cu")
		(net "UPI_CPU0_CPU1_P0P1_DP<1>")
	)
	(segment
		(start 135.927592 -212.819996)
		(end 135.868664 -212.819996)
		(width 0.0889)
		(layer "In6.Cu")
		(net "UPI_CPU0_CPU1_P0P1_DP<1>")
	)
	(segment
		(start 232.848404 -199.168004)
		(end 220.23832 -192.476882)
		(width 0.14732)
		(layer "In6.Cu")
		(net "UPI_CPU0_CPU1_P0P1_DP<1>")
	)
	(segment
		(start 143.903954 -202.56246)
		(end 143.90497 -202.770232)
		(width 0.14732)
		(layer "In6.Cu")
		(net "UPI_CPU0_CPU1_P0P1_DP<1>")
	)
	(segment
		(start 141.726158 -206.093822)
		(end 141.41831 -206.404464)
		(width 0.14732)
		(layer "In6.Cu")
		(net "UPI_CPU0_CPU1_P0P1_DP<1>")
	)
	(segment
		(start 235.964476 -199.943466)
		(end 232.848404 -199.168004)
		(width 0.14732)
		(layer "In6.Cu")
		(net "UPI_CPU0_CPU1_P0P1_DP<1>")
	)
	(segment
		(start 140.388848 -207.803496)
		(end 140.18768 -207.843882)
		(width 0.14732)
		(layer "In6.Cu")
		(net "UPI_CPU0_CPU1_P0P1_DP<1>")
	)
	(segment
		(start 190.81369 -191.271398)
		(end 166.645844 -190.948056)
		(width 0.14732)
		(layer "In6.Cu")
		(net "UPI_CPU0_CPU1_P0P1_DP<1>")
	)
	(segment
		(start 159.862012 -190.857124)
		(end 157.525974 -191.702944)
		(width 0.14732)
		(layer "In6.Cu")
		(net "UPI_CPU0_CPU1_P0P1_DP<1>")
	)
	(segment
		(start 149.869144 -197.266052)
		(end 149.58822 -196.987922)
		(width 0.14732)
		(layer "In6.Cu")
		(net "UPI_CPU0_CPU1_P0P1_DP<1>")
	)
	(segment
		(start 301.009558 -188.520832)
		(end 298.43476 -190.580518)
		(width 0.14732)
		(layer "In6.Cu")
		(net "UPI_CPU0_CPU1_P0P1_DP<1>")
	)
	(segment
		(start 165.457124 -190.624206)
		(end 165.14572 -190.928498)
		(width 0.14732)
		(layer "In6.Cu")
		(net "UPI_CPU0_CPU1_P0P1_DP<1>")
	)
	(segment
		(start 149.24786 -198.32955)
		(end 148.482558 -199.101456)
		(width 0.14732)
		(layer "In6.Cu")
		(net "UPI_CPU0_CPU1_P0P1_DP<1>")
	)
	(segment
		(start 337.651344 -215.165686)
		(end 337.627214 -215.076532)
		(width 0.0889)
		(layer "In6.Cu")
		(net "UPI_CPU0_CPU1_P0P1_DP<1>")
	)
	(segment
		(start 164.024564 -190.605156)
		(end 164.046662 -188.953902)
		(width 0.14732)
		(layer "In6.Cu")
		(net "UPI_CPU0_CPU1_P0P1_DP<1>")
	)
	(segment
		(start 337.718146 -210.989164)
		(end 336.957924 -210.228942)
		(width 0.14732)
		(layer "In6.Cu")
		(net "UPI_CPU0_CPU1_P0P1_DP<1>")
	)
	(segment
		(start 314.046616 -191.395096)
		(end 313.755532 -190.640208)
		(width 0.14732)
		(layer "In6.Cu")
		(net "UPI_CPU0_CPU1_P0P1_DP<1>")
	)
	(segment
		(start 147.16633 -199.269096)
		(end 147.167346 -199.476868)
		(width 0.14732)
		(layer "In6.Cu")
		(net "UPI_CPU0_CPU1_P0P1_DP<1>")
	)
	(segment
		(start 139.379198 -209.319876)
		(end 139.175236 -209.626708)
		(width 0.14732)
		(layer "In6.Cu")
		(net "UPI_CPU0_CPU1_P0P1_DP<1>")
	)
	(segment
		(start 141.725396 -205.921356)
		(end 141.726158 -206.093822)
		(width 0.14732)
		(layer "In6.Cu")
		(net "UPI_CPU0_CPU1_P0P1_DP<1>")
	)
	(segment
		(start 140.552424 -207.296004)
		(end 140.59281 -207.496664)
		(width 0.14732)
		(layer "In6.Cu")
		(net "UPI_CPU0_CPU1_P0P1_DP<1>")
	)
	(segment
		(start 312.946542 -188.543184)
		(end 312.237882 -188.103002)
		(width 0.14732)
		(layer "In6.Cu")
		(net "UPI_CPU0_CPU1_P0P1_DP<1>")
	)
	(segment
		(start 146.158966 -200.495154)
		(end 145.95094 -200.49617)
		(width 0.14732)
		(layer "In6.Cu")
		(net "UPI_CPU0_CPU1_P0P1_DP<1>")
	)
	(segment
		(start 261.11835 -191.708024)
		(end 250.227338 -194.613022)
		(width 0.14732)
		(layer "In6.Cu")
		(net "UPI_CPU0_CPU1_P0P1_DP<1>")
	)
	(segment
		(start 138.974322 -209.667094)
		(end 138.762994 -209.984594)
		(width 0.14732)
		(layer "In6.Cu")
		(net "UPI_CPU0_CPU1_P0P1_DP<1>")
	)
	(segment
		(start 139.743942 -208.772506)
		(end 139.543028 -208.812638)
		(width 0.14732)
		(layer "In6.Cu")
		(net "UPI_CPU0_CPU1_P0P1_DP<1>")
	)
	(segment
		(start 165.14572 -190.928498)
		(end 164.328856 -190.916814)
		(width 0.14732)
		(layer "In6.Cu")
		(net "UPI_CPU0_CPU1_P0P1_DP<1>")
	)
	(segment
		(start 337.7184 -211.537296)
		(end 337.718146 -211.53755)
		(width 0.14732)
		(layer "In6.Cu")
		(net "UPI_CPU0_CPU1_P0P1_DP<1>")
	)
	(segment
		(start 144.78508 -202.396598)
		(end 144.527778 -202.141836)
		(width 0.14732)
		(layer "In6.Cu")
		(net "UPI_CPU0_CPU1_P0P1_DP<1>")
	)
	(segment
		(start 145.220436 -202.394312)
		(end 144.78508 -202.396598)
		(width 0.14732)
		(layer "In6.Cu")
		(net "UPI_CPU0_CPU1_P0P1_DP<1>")
	)
	(segment
		(start 153.226008 -195.366894)
		(end 151.445214 -196.114416)
		(width 0.14732)
		(layer "In6.Cu")
		(net "UPI_CPU0_CPU1_P0P1_DP<1>")
	)
	(segment
		(start 315.081666 -193.562478)
		(end 314.724796 -193.152522)
		(width 0.14732)
		(layer "In6.Cu")
		(net "UPI_CPU0_CPU1_P0P1_DP<1>")
	)
	(segment
		(start 144.527778 -202.141836)
		(end 144.319752 -202.142852)
		(width 0.14732)
		(layer "In6.Cu")
		(net "UPI_CPU0_CPU1_P0P1_DP<1>")
	)
	(segment
		(start 302.473106 -187.788804)
		(end 301.009558 -188.520832)
		(width 0.14732)
		(layer "In6.Cu")
		(net "UPI_CPU0_CPU1_P0P1_DP<1>")
	)
	(segment
		(start 166.218616 -188.836046)
		(end 165.628066 -188.828172)
		(width 0.14732)
		(layer "In6.Cu")
		(net "UPI_CPU0_CPU1_P0P1_DP<1>")
	)
	(segment
		(start 145.536158 -201.12355)
		(end 145.79346 -201.378312)
		(width 0.14732)
		(layer "In6.Cu")
		(net "UPI_CPU0_CPU1_P0P1_DP<1>")
	)
	(segment
		(start 164.328856 -190.916814)
		(end 164.024564 -190.605156)
		(width 0.14732)
		(layer "In6.Cu")
		(net "UPI_CPU0_CPU1_P0P1_DP<1>")
	)
	(segment
		(start 166.341806 -190.636652)
		(end 166.363904 -188.985144)
		(width 0.14732)
		(layer "In6.Cu")
		(net "UPI_CPU0_CPU1_P0P1_DP<1>")
	)
	(segment
		(start 146.416268 -200.749916)
		(end 146.158966 -200.495154)
		(width 0.14732)
		(layer "In6.Cu")
		(net "UPI_CPU0_CPU1_P0P1_DP<1>")
	)
	(segment
		(start 162.828478 -190.897002)
		(end 159.862012 -190.857124)
		(width 0.14732)
		(layer "In6.Cu")
		(net "UPI_CPU0_CPU1_P0P1_DP<1>")
	)
	(segment
		(start 312.237882 -188.103002)
		(end 311.791858 -187.970922)
		(width 0.14732)
		(layer "In6.Cu")
		(net "UPI_CPU0_CPU1_P0P1_DP<1>")
	)
	(segment
		(start 237.361222 -199.943466)
		(end 235.964476 -199.943466)
		(width 0.14732)
		(layer "In6.Cu")
		(net "UPI_CPU0_CPU1_P0P1_DP<1>")
	)
	(segment
		(start 139.543028 -208.812638)
		(end 139.339066 -209.119216)
		(width 0.14732)
		(layer "In6.Cu")
		(net "UPI_CPU0_CPU1_P0P1_DP<1>")
	)
	(segment
		(start 139.947904 -208.46542)
		(end 139.743942 -208.772506)
		(width 0.14732)
		(layer "In6.Cu")
		(net "UPI_CPU0_CPU1_P0P1_DP<1>")
	)
	(segment
		(start 337.718146 -211.53755)
		(end 337.718146 -210.989164)
		(width 0.14732)
		(layer "In6.Cu")
		(net "UPI_CPU0_CPU1_P0P1_DP<1>")
	)
	(segment
		(start 139.175236 -209.626708)
		(end 138.974322 -209.667094)
		(width 0.14732)
		(layer "In6.Cu")
		(net "UPI_CPU0_CPU1_P0P1_DP<1>")
	)
	(segment
		(start 337.7184 -211.684108)
		(end 337.7184 -211.66201)
		(width 0.0889)
		(layer "In6.Cu")
		(net "UPI_CPU0_CPU1_P0P1_DP<1>")
	)
	(segment
		(start 313.56808 -190.55715)
		(end 313.435492 -190.213234)
		(width 0.14732)
		(layer "In6.Cu")
		(net "UPI_CPU0_CPU1_P0P1_DP<1>")
	)
	(segment
		(start 148.482558 -199.101456)
		(end 148.046948 -199.10298)
		(width 0.14732)
		(layer "In6.Cu")
		(net "UPI_CPU0_CPU1_P0P1_DP<1>")
	)
	(segment
		(start 337.76031 -213.501224)
		(end 337.76031 -211.726018)
		(width 0.0889)
		(layer "In6.Cu")
		(net "UPI_CPU0_CPU1_P0P1_DP<1>")
	)
	(segment
		(start 135.943086 -212.804502)
		(end 135.927592 -212.819996)
		(width 0.0889)
		(layer "In6.Cu")
		(net "UPI_CPU0_CPU1_P0P1_DP<1>")
	)
	(segment
		(start 147.42668 -200.166986)
		(end 146.851624 -200.74763)
		(width 0.14732)
		(layer "In6.Cu")
		(net "UPI_CPU0_CPU1_P0P1_DP<1>")
	)
	(segment
		(start 145.95094 -200.49617)
		(end 145.535142 -200.915778)
		(width 0.14732)
		(layer "In6.Cu")
		(net "UPI_CPU0_CPU1_P0P1_DP<1>")
	)
	(segment
		(start 140.59281 -207.496664)
		(end 140.388848 -207.803496)
		(width 0.14732)
		(layer "In6.Cu")
		(net "UPI_CPU0_CPU1_P0P1_DP<1>")
	)
	(segment
		(start 149.246336 -197.89394)
		(end 149.24786 -198.32955)
		(width 0.14732)
		(layer "In6.Cu")
		(net "UPI_CPU0_CPU1_P0P1_DP<1>")
	)
	(segment
		(start 313.755532 -190.640208)
		(end 313.56808 -190.55715)
		(width 0.14732)
		(layer "In6.Cu")
		(net "UPI_CPU0_CPU1_P0P1_DP<1>")
	)
	(segment
		(start 146.851624 -200.74763)
		(end 146.416268 -200.749916)
		(width 0.14732)
		(layer "In6.Cu")
		(net "UPI_CPU0_CPU1_P0P1_DP<1>")
	)
	(segment
		(start 164.046662 -188.953902)
		(end 163.901374 -188.804804)
		(width 0.14732)
		(layer "In6.Cu")
		(net "UPI_CPU0_CPU1_P0P1_DP<1>")
	)
	(segment
		(start 314.096146 -191.925956)
		(end 313.963812 -191.582294)
		(width 0.14732)
		(layer "In6.Cu")
		(net "UPI_CPU0_CPU1_P0P1_DP<1>")
	)
	(segment
		(start 337.7184 -211.66201)
		(end 337.7184 -211.537296)
		(width 0.14732)
		(layer "In6.Cu")
		(net "UPI_CPU0_CPU1_P0P1_DP<1>")
	)
	(segment
		(start 150.3045 -197.264528)
		(end 149.869144 -197.266052)
		(width 0.14732)
		(layer "In6.Cu")
		(net "UPI_CPU0_CPU1_P0P1_DP<1>")
	)
	(segment
		(start 147.582128 -198.849488)
		(end 147.16633 -199.269096)
		(width 0.14732)
		(layer "In6.Cu")
		(net "UPI_CPU0_CPU1_P0P1_DP<1>")
	)
	(segment
		(start 208.36382 -190.561722)
		(end 190.81369 -191.271398)
		(width 0.14732)
		(layer "In6.Cu")
		(net "UPI_CPU0_CPU1_P0P1_DP<1>")
	)
	(segment
		(start 140.938504 -206.715614)
		(end 140.552424 -207.296004)
		(width 0.14732)
		(layer "In6.Cu")
		(net "UPI_CPU0_CPU1_P0P1_DP<1>")
	)
	(segment
		(start 166.645844 -190.948056)
		(end 166.341806 -190.636652)
		(width 0.14732)
		(layer "In6.Cu")
		(net "UPI_CPU0_CPU1_P0P1_DP<1>")
	)
	(segment
		(start 156.17952 -192.386966)
		(end 153.226008 -195.366894)
		(width 0.14732)
		(layer "In6.Cu")
		(net "UPI_CPU0_CPU1_P0P1_DP<1>")
	)
	(segment
		(start 337.49488 -215.436704)
		(end 337.651344 -215.165686)
		(width 0.0889)
		(layer "In6.Cu")
		(net "UPI_CPU0_CPU1_P0P1_DP<1>")
	)
	(segment
		(start 148.964396 -197.408292)
		(end 148.965412 -197.616064)
		(width 0.14732)
		(layer "In6.Cu")
		(net "UPI_CPU0_CPU1_P0P1_DP<1>")
	)
	(segment
		(start 145.79346 -201.378312)
		(end 145.795492 -201.813668)
		(width 0.14732)
		(layer "In6.Cu")
		(net "UPI_CPU0_CPU1_P0P1_DP<1>")
	)
	(segment
		(start 139.907772 -208.26476)
		(end 139.947904 -208.46542)
		(width 0.14732)
		(layer "In6.Cu")
		(net "UPI_CPU0_CPU1_P0P1_DP<1>")
	)
	(segment
		(start 337.76031 -211.726018)
		(end 337.7184 -211.684108)
		(width 0.0889)
		(layer "In6.Cu")
		(net "UPI_CPU0_CPU1_P0P1_DP<1>")
	)
	(segment
		(start 313.963812 -191.582294)
		(end 314.046616 -191.395096)
		(width 0.14732)
		(layer "In6.Cu")
		(net "UPI_CPU0_CPU1_P0P1_DP<1>")
	)
	(segment
		(start 148.046948 -199.10298)
		(end 147.7899 -198.848472)
		(width 0.14732)
		(layer "In6.Cu")
		(net "UPI_CPU0_CPU1_P0P1_DP<1>")
	)
	(segment
		(start 147.7899 -198.848472)
		(end 147.582128 -198.849488)
		(width 0.14732)
		(layer "In6.Cu")
		(net "UPI_CPU0_CPU1_P0P1_DP<1>")
	)
	(segment
		(start 140.938504 -206.71536)
		(end 140.938504 -206.715614)
		(width 0.14732)
		(layer "In6.Cu")
		(net "UPI_CPU0_CPU1_P0P1_DP<1>")
	)
	(segment
		(start 220.23832 -192.476882)
		(end 208.36382 -190.561722)
		(width 0.14732)
		(layer "In6.Cu")
		(net "UPI_CPU0_CPU1_P0P1_DP<1>")
	)
	(segment
		(start 337.399376 -214.636858)
		(end 337.399376 -213.862158)
		(width 0.0889)
		(layer "In6.Cu")
		(net "UPI_CPU0_CPU1_P0P1_DP<1>")
	)
	(segment
		(start 151.445214 -196.114416)
		(end 150.3045 -197.264528)
		(width 0.14732)
		(layer "In6.Cu")
		(net "UPI_CPU0_CPU1_P0P1_DP<1>")
	)
	(segment
		(start 135.868664 -212.819996)
		(end 134.760716 -213.927944)
		(width 0.0889)
		(layer "In6.Cu")
		(net "UPI_CPU0_CPU1_P0P1_DP<1>")
	)
	(segment
		(start 286.488886 -190.696088)
		(end 261.11835 -191.708024)
		(width 0.14732)
		(layer "In6.Cu")
		(net "UPI_CPU0_CPU1_P0P1_DP<1>")
	)
	(segment
		(start 147.167346 -199.476868)
		(end 147.424648 -199.73163)
		(width 0.14732)
		(layer "In6.Cu")
		(net "UPI_CPU0_CPU1_P0P1_DP<1>")
	)
	(segment
		(start 157.525974 -191.702944)
		(end 156.17952 -192.386966)
		(width 0.14732)
		(layer "In6.Cu")
		(net "UPI_CPU0_CPU1_P0P1_DP<1>")
	)
	(segment
		(start 297.719496 -190.744856)
		(end 286.488886 -190.696088)
		(width 0.14732)
		(layer "In6.Cu")
		(net "UPI_CPU0_CPU1_P0P1_DP<1>")
	)
	(segment
		(start 143.90497 -202.770232)
		(end 144.162272 -203.024994)
		(width 0.14732)
		(layer "In6.Cu")
		(net "UPI_CPU0_CPU1_P0P1_DP<1>")
	)
	(segment
		(start 145.795492 -201.813668)
		(end 145.220436 -202.394312)
		(width 0.14732)
		(layer "In6.Cu")
		(net "UPI_CPU0_CPU1_P0P1_DP<1>")
	)
	(segment
		(start 166.363904 -188.985144)
		(end 166.218616 -188.836046)
		(width 0.14732)
		(layer "In6.Cu")
		(net "UPI_CPU0_CPU1_P0P1_DP<1>")
	)
	(segment
		(start 140.18768 -207.843882)
		(end 139.907772 -208.26476)
		(width 0.14732)
		(layer "In6.Cu")
		(net "UPI_CPU0_CPU1_P0P1_DP<1>")
	)
	(segment
		(start 314.283598 -192.009014)
		(end 314.096146 -191.925956)
		(width 0.14732)
		(layer "In6.Cu")
		(net "UPI_CPU0_CPU1_P0P1_DP<1>")
	)
	(segment
		(start 144.162272 -203.024994)
		(end 144.164304 -203.460604)
		(width 0.14732)
		(layer "In6.Cu")
		(net "UPI_CPU0_CPU1_P0P1_DP<1>")
	)
	(segment
		(start 336.957924 -210.228942)
		(end 335.706466 -209.710528)
		(width 0.14732)
		(layer "In6.Cu")
		(net "UPI_CPU0_CPU1_P0P1_DP<1>")
	)
	(segment
		(start 314.724796 -193.152522)
		(end 314.283598 -192.009014)
		(width 0.14732)
		(layer "In6.Cu")
		(net "UPI_CPU0_CPU1_P0P1_DP<1>")
	)
	(segment
		(start 142.512288 -205.127352)
		(end 142.51305 -205.299818)
		(width 0.14732)
		(layer "In6.Cu")
		(net "UPI_CPU0_CPU1_P0P1_DP<1>")
	)
	(arc
		(start 134.745476 -214.78367)
		(mid 134.635251 -214.953008)
		(end 134.474966 -215.076024)
		(width 0.0889)
		(layer "In6.Cu")
		(net "UPI_CPU0_CPU1_P0P1_DP<1>")
	)
	(arc
		(start 134.474966 -215.076024)
		(mid 134.36557 -215.160121)
		(end 134.290562 -215.275922)
		(width 0.0889)
		(layer "In6.Cu")
		(net "UPI_CPU0_CPU1_P0P1_DP<1>")
	)
	(arc
		(start 337.610196 -215.063324)
		(mid 337.457765 -214.873342)
		(end 337.399376 -214.636858)
		(width 0.0889)
		(layer "In6.Cu")
		(net "UPI_CPU0_CPU1_P0P1_DP<1>")
	)
	(arc
		(start 134.760716 -214.7443)
		(mid 134.753443 -214.764119)
		(end 134.745476 -214.78367)
		(width 0.0889)
		(layer "In6.Cu")
		(net "UPI_CPU0_CPU1_P0P1_DP<1>")
	)
	(arc
		(start 337.627214 -215.076532)
		(mid 337.618642 -215.070009)
		(end 337.610196 -215.063324)
		(width 0.0889)
		(layer "In6.Cu")
		(net "UPI_CPU0_CPU1_P0P1_DP<1>")
	)
	(segment
		(start 354.411534 -215.972644)
		(end 354.411534 -215.436958)
		(width 0.13208)
		(layer "F.Cu")
		(net "UPI_CPU0_CPU1_P0P1_DP<19>")
	)
	(segment
		(start 117.278912 -214.622888)
		(end 117.278658 -214.622634)
		(width 0.13208)
		(layer "F.Cu")
		(net "UPI_CPU0_CPU1_P0P1_DP<19>")
	)
	(segment
		(start 354.411534 -215.436958)
		(end 354.41128 -215.436704)
		(width 0.13208)
		(layer "F.Cu")
		(net "UPI_CPU0_CPU1_P0P1_DP<19>")
	)
	(segment
		(start 117.278912 -215.158574)
		(end 117.278912 -214.622888)
		(width 0.13208)
		(layer "F.Cu")
		(net "UPI_CPU0_CPU1_P0P1_DP<19>")
	)
	(segment
		(start 123.447302 -196.622416)
		(end 123.464828 -196.793866)
		(width 0.14732)
		(layer "In6.Cu")
		(net "UPI_CPU0_CPU1_P0P1_DP<19>")
	)
	(segment
		(start 117.416072 -209.440018)
		(end 117.416072 -211.719414)
		(width 0.14732)
		(layer "In6.Cu")
		(net "UPI_CPU0_CPU1_P0P1_DP<19>")
	)
	(segment
		(start 125.304296 -194.53098)
		(end 125.132592 -194.54876)
		(width 0.14732)
		(layer "In6.Cu")
		(net "UPI_CPU0_CPU1_P0P1_DP<19>")
	)
	(segment
		(start 125.132592 -194.54876)
		(end 124.857256 -194.887596)
		(width 0.14732)
		(layer "In6.Cu")
		(net "UPI_CPU0_CPU1_P0P1_DP<19>")
	)
	(segment
		(start 121.60758 -198.88581)
		(end 120.735852 -199.958198)
		(width 0.14732)
		(layer "In6.Cu")
		(net "UPI_CPU0_CPU1_P0P1_DP<19>")
	)
	(segment
		(start 150.141178 -175.218598)
		(end 138.895582 -180.976524)
		(width 0.14732)
		(layer "In6.Cu")
		(net "UPI_CPU0_CPU1_P0P1_DP<19>")
	)
	(segment
		(start 123.464828 -196.793866)
		(end 123.189238 -197.13321)
		(width 0.14732)
		(layer "In6.Cu")
		(net "UPI_CPU0_CPU1_P0P1_DP<19>")
	)
	(segment
		(start 120.735852 -199.958198)
		(end 117.416072 -209.440018)
		(width 0.14732)
		(layer "In6.Cu")
		(net "UPI_CPU0_CPU1_P0P1_DP<19>")
	)
	(segment
		(start 354.567744 -215.165686)
		(end 354.543614 -215.076532)
		(width 0.0889)
		(layer "In6.Cu")
		(net "UPI_CPU0_CPU1_P0P1_DP<19>")
	)
	(segment
		(start 354.744528 -211.559648)
		(end 354.744274 -211.559902)
		(width 0.14732)
		(layer "In6.Cu")
		(net "UPI_CPU0_CPU1_P0P1_DP<19>")
	)
	(segment
		(start 354.786184 -213.8934)
		(end 354.786438 -213.892892)
		(width 0.0889)
		(layer "In6.Cu")
		(net "UPI_CPU0_CPU1_P0P1_DP<19>")
	)
	(segment
		(start 122.31243 -198.0184)
		(end 122.037094 -198.357236)
		(width 0.14732)
		(layer "In6.Cu")
		(net "UPI_CPU0_CPU1_P0P1_DP<19>")
	)
	(segment
		(start 124.875036 -195.059046)
		(end 124.599192 -195.39839)
		(width 0.14732)
		(layer "In6.Cu")
		(net "UPI_CPU0_CPU1_P0P1_DP<19>")
	)
	(segment
		(start 319.221866 -174.193454)
		(end 313.49061 -172.591222)
		(width 0.14732)
		(layer "In6.Cu")
		(net "UPI_CPU0_CPU1_P0P1_DP<19>")
	)
	(segment
		(start 238.38408 -173.266608)
		(end 211.435442 -173.266608)
		(width 0.14732)
		(layer "In6.Cu")
		(net "UPI_CPU0_CPU1_P0P1_DP<19>")
	)
	(segment
		(start 117.416326 -211.77123)
		(end 117.416326 -211.793328)
		(width 0.0889)
		(layer "In6.Cu")
		(net "UPI_CPU0_CPU1_P0P1_DP<19>")
	)
	(segment
		(start 354.315776 -214.636858)
		(end 354.315776 -214.425784)
		(width 0.0889)
		(layer "In6.Cu")
		(net "UPI_CPU0_CPU1_P0P1_DP<19>")
	)
	(segment
		(start 349.723456 -195.21043)
		(end 340.051898 -185.852816)
		(width 0.14732)
		(layer "In6.Cu")
		(net "UPI_CPU0_CPU1_P0P1_DP<19>")
	)
	(segment
		(start 354.744528 -211.77123)
		(end 354.744528 -211.559648)
		(width 0.14732)
		(layer "In6.Cu")
		(net "UPI_CPU0_CPU1_P0P1_DP<19>")
	)
	(segment
		(start 124.599192 -195.39839)
		(end 124.427742 -195.41617)
		(width 0.14732)
		(layer "In6.Cu")
		(net "UPI_CPU0_CPU1_P0P1_DP<19>")
	)
	(segment
		(start 124.857256 -194.887596)
		(end 124.875036 -195.059046)
		(width 0.14732)
		(layer "In6.Cu")
		(net "UPI_CPU0_CPU1_P0P1_DP<19>")
	)
	(segment
		(start 354.41128 -215.436704)
		(end 354.567744 -215.165686)
		(width 0.0889)
		(layer "In6.Cu")
		(net "UPI_CPU0_CPU1_P0P1_DP<19>")
	)
	(segment
		(start 124.169932 -195.926456)
		(end 123.894342 -196.2658)
		(width 0.14732)
		(layer "In6.Cu")
		(net "UPI_CPU0_CPU1_P0P1_DP<19>")
	)
	(segment
		(start 336.300064 -183.121554)
		(end 319.221866 -174.193454)
		(width 0.14732)
		(layer "In6.Cu")
		(net "UPI_CPU0_CPU1_P0P1_DP<19>")
	)
	(segment
		(start 127.855218 -191.198754)
		(end 125.56236 -194.020186)
		(width 0.14732)
		(layer "In6.Cu")
		(net "UPI_CPU0_CPU1_P0P1_DP<19>")
	)
	(segment
		(start 122.037094 -198.357236)
		(end 122.054874 -198.528686)
		(width 0.14732)
		(layer "In6.Cu")
		(net "UPI_CPU0_CPU1_P0P1_DP<19>")
	)
	(segment
		(start 117.150134 -214.22487)
		(end 117.119908 -214.321644)
		(width 0.0889)
		(layer "In6.Cu")
		(net "UPI_CPU0_CPU1_P0P1_DP<19>")
	)
	(segment
		(start 313.49061 -172.591222)
		(end 302.477678 -172.386498)
		(width 0.14732)
		(layer "In6.Cu")
		(net "UPI_CPU0_CPU1_P0P1_DP<19>")
	)
	(segment
		(start 123.189238 -197.13321)
		(end 123.017534 -197.15099)
		(width 0.14732)
		(layer "In6.Cu")
		(net "UPI_CPU0_CPU1_P0P1_DP<19>")
	)
	(segment
		(start 340.051898 -185.852816)
		(end 336.300064 -183.121554)
		(width 0.14732)
		(layer "In6.Cu")
		(net "UPI_CPU0_CPU1_P0P1_DP<19>")
	)
	(segment
		(start 122.742198 -197.489826)
		(end 122.759724 -197.661276)
		(width 0.14732)
		(layer "In6.Cu")
		(net "UPI_CPU0_CPU1_P0P1_DP<19>")
	)
	(segment
		(start 117.119908 -214.321644)
		(end 117.278658 -214.622634)
		(width 0.0889)
		(layer "In6.Cu")
		(net "UPI_CPU0_CPU1_P0P1_DP<19>")
	)
	(segment
		(start 117.374162 -213.93023)
		(end 117.374416 -213.929468)
		(width 0.0889)
		(layer "In6.Cu")
		(net "UPI_CPU0_CPU1_P0P1_DP<19>")
	)
	(segment
		(start 200.79589 -172.799756)
		(end 156.73578 -173.531022)
		(width 0.14732)
		(layer "In6.Cu")
		(net "UPI_CPU0_CPU1_P0P1_DP<19>")
	)
	(segment
		(start 121.60758 -198.885556)
		(end 121.60758 -198.88581)
		(width 0.14732)
		(layer "In6.Cu")
		(net "UPI_CPU0_CPU1_P0P1_DP<19>")
	)
	(segment
		(start 125.579886 -194.191636)
		(end 125.304296 -194.53098)
		(width 0.14732)
		(layer "In6.Cu")
		(net "UPI_CPU0_CPU1_P0P1_DP<19>")
	)
	(segment
		(start 122.759724 -197.661276)
		(end 122.484134 -198.00062)
		(width 0.14732)
		(layer "In6.Cu")
		(net "UPI_CPU0_CPU1_P0P1_DP<19>")
	)
	(segment
		(start 273.07921 -173.101762)
		(end 238.38408 -173.266608)
		(width 0.14732)
		(layer "In6.Cu")
		(net "UPI_CPU0_CPU1_P0P1_DP<19>")
	)
	(segment
		(start 354.786438 -213.892892)
		(end 354.786438 -211.835238)
		(width 0.0889)
		(layer "In6.Cu")
		(net "UPI_CPU0_CPU1_P0P1_DP<19>")
	)
	(segment
		(start 138.895582 -180.976524)
		(end 134.64032 -186.688984)
		(width 0.14732)
		(layer "In6.Cu")
		(net "UPI_CPU0_CPU1_P0P1_DP<19>")
	)
	(segment
		(start 124.427742 -195.41617)
		(end 124.152406 -195.755006)
		(width 0.14732)
		(layer "In6.Cu")
		(net "UPI_CPU0_CPU1_P0P1_DP<19>")
	)
	(segment
		(start 354.786438 -211.835238)
		(end 354.744528 -211.793328)
		(width 0.0889)
		(layer "In6.Cu")
		(net "UPI_CPU0_CPU1_P0P1_DP<19>")
	)
	(segment
		(start 117.374162 -211.835492)
		(end 117.374162 -213.93023)
		(width 0.0889)
		(layer "In6.Cu")
		(net "UPI_CPU0_CPU1_P0P1_DP<19>")
	)
	(segment
		(start 354.744274 -210.145376)
		(end 353.684586 -200.112884)
		(width 0.14732)
		(layer "In6.Cu")
		(net "UPI_CPU0_CPU1_P0P1_DP<19>")
	)
	(segment
		(start 117.416326 -211.719668)
		(end 117.416326 -211.77123)
		(width 0.14732)
		(layer "In6.Cu")
		(net "UPI_CPU0_CPU1_P0P1_DP<19>")
	)
	(segment
		(start 134.64032 -186.688984)
		(end 127.855218 -191.198754)
		(width 0.14732)
		(layer "In6.Cu")
		(net "UPI_CPU0_CPU1_P0P1_DP<19>")
	)
	(segment
		(start 156.73578 -173.531022)
		(end 150.141178 -175.218598)
		(width 0.14732)
		(layer "In6.Cu")
		(net "UPI_CPU0_CPU1_P0P1_DP<19>")
	)
	(segment
		(start 211.435442 -173.266608)
		(end 200.79589 -172.799756)
		(width 0.14732)
		(layer "In6.Cu")
		(net "UPI_CPU0_CPU1_P0P1_DP<19>")
	)
	(segment
		(start 125.56236 -194.020186)
		(end 125.579886 -194.191636)
		(width 0.14732)
		(layer "In6.Cu")
		(net "UPI_CPU0_CPU1_P0P1_DP<19>")
	)
	(segment
		(start 124.152406 -195.755006)
		(end 124.169932 -195.926456)
		(width 0.14732)
		(layer "In6.Cu")
		(net "UPI_CPU0_CPU1_P0P1_DP<19>")
	)
	(segment
		(start 354.744274 -211.559902)
		(end 354.744274 -210.145376)
		(width 0.14732)
		(layer "In6.Cu")
		(net "UPI_CPU0_CPU1_P0P1_DP<19>")
	)
	(segment
		(start 354.744528 -211.793328)
		(end 354.744528 -211.77123)
		(width 0.0889)
		(layer "In6.Cu")
		(net "UPI_CPU0_CPU1_P0P1_DP<19>")
	)
	(segment
		(start 353.684586 -200.112884)
		(end 349.723456 -195.21043)
		(width 0.14732)
		(layer "In6.Cu")
		(net "UPI_CPU0_CPU1_P0P1_DP<19>")
	)
	(segment
		(start 121.77903 -198.86803)
		(end 121.60758 -198.885556)
		(width 0.14732)
		(layer "In6.Cu")
		(net "UPI_CPU0_CPU1_P0P1_DP<19>")
	)
	(segment
		(start 123.722638 -196.28358)
		(end 123.447302 -196.622416)
		(width 0.14732)
		(layer "In6.Cu")
		(net "UPI_CPU0_CPU1_P0P1_DP<19>")
	)
	(segment
		(start 122.484134 -198.00062)
		(end 122.31243 -198.0184)
		(width 0.14732)
		(layer "In6.Cu")
		(net "UPI_CPU0_CPU1_P0P1_DP<19>")
	)
	(segment
		(start 122.054874 -198.528686)
		(end 121.77903 -198.86803)
		(width 0.14732)
		(layer "In6.Cu")
		(net "UPI_CPU0_CPU1_P0P1_DP<19>")
	)
	(segment
		(start 117.416326 -211.793328)
		(end 117.374162 -211.835492)
		(width 0.0889)
		(layer "In6.Cu")
		(net "UPI_CPU0_CPU1_P0P1_DP<19>")
	)
	(segment
		(start 117.416072 -211.719414)
		(end 117.416326 -211.719668)
		(width 0.14732)
		(layer "In6.Cu")
		(net "UPI_CPU0_CPU1_P0P1_DP<19>")
	)
	(segment
		(start 302.477678 -172.386498)
		(end 273.07921 -173.101762)
		(width 0.14732)
		(layer "In6.Cu")
		(net "UPI_CPU0_CPU1_P0P1_DP<19>")
	)
	(segment
		(start 123.017534 -197.15099)
		(end 122.742198 -197.489826)
		(width 0.14732)
		(layer "In6.Cu")
		(net "UPI_CPU0_CPU1_P0P1_DP<19>")
	)
	(segment
		(start 123.894342 -196.2658)
		(end 123.722638 -196.28358)
		(width 0.14732)
		(layer "In6.Cu")
		(net "UPI_CPU0_CPU1_P0P1_DP<19>")
	)
	(arc
		(start 354.543614 -215.076532)
		(mid 354.535042 -215.070009)
		(end 354.526596 -215.063324)
		(width 0.0889)
		(layer "In6.Cu")
		(net "UPI_CPU0_CPU1_P0P1_DP<19>")
	)
	(arc
		(start 117.35943 -213.96833)
		(mid 117.272879 -214.111364)
		(end 117.150134 -214.22487)
		(width 0.0889)
		(layer "In6.Cu")
		(net "UPI_CPU0_CPU1_P0P1_DP<19>")
	)
	(arc
		(start 354.315776 -214.425784)
		(mid 354.427216 -214.232389)
		(end 354.60178 -214.093298)
		(width 0.0889)
		(layer "In6.Cu")
		(net "UPI_CPU0_CPU1_P0P1_DP<19>")
	)
	(arc
		(start 117.374416 -213.929468)
		(mid 117.367258 -213.949028)
		(end 117.35943 -213.96833)
		(width 0.0889)
		(layer "In6.Cu")
		(net "UPI_CPU0_CPU1_P0P1_DP<19>")
	)
	(arc
		(start 354.526596 -215.063324)
		(mid 354.374165 -214.873342)
		(end 354.315776 -214.636858)
		(width 0.0889)
		(layer "In6.Cu")
		(net "UPI_CPU0_CPU1_P0P1_DP<19>")
	)
	(arc
		(start 354.60178 -214.093298)
		(mid 354.711176 -214.009201)
		(end 354.786184 -213.8934)
		(width 0.0889)
		(layer "In6.Cu")
		(net "UPI_CPU0_CPU1_P0P1_DP<19>")
	)
	(segment
		(start 118.218712 -215.158574)
		(end 118.218712 -214.622888)
		(width 0.13208)
		(layer "F.Cu")
		(net "UPI_CPU0_CPU1_P0P1_DP<18>")
	)
	(segment
		(start 353.471734 -214.344758)
		(end 353.471734 -213.732618)
		(width 0.13208)
		(layer "F.Cu")
		(net "UPI_CPU0_CPU1_P0P1_DP<18>")
	)
	(segment
		(start 118.218712 -214.622888)
		(end 118.218458 -214.622634)
		(width 0.13208)
		(layer "F.Cu")
		(net "UPI_CPU0_CPU1_P0P1_DP<18>")
	)
	(segment
		(start 339.499956 -186.477402)
		(end 335.91246 -183.865012)
		(width 0.14732)
		(layer "In6.Cu")
		(net "UPI_CPU0_CPU1_P0P1_DP<18>")
	)
	(segment
		(start 335.91246 -183.865012)
		(end 318.877188 -174.959264)
		(width 0.14732)
		(layer "In6.Cu")
		(net "UPI_CPU0_CPU1_P0P1_DP<18>")
	)
	(segment
		(start 124.578872 -196.756782)
		(end 124.303536 -197.095618)
		(width 0.14732)
		(layer "In6.Cu")
		(net "UPI_CPU0_CPU1_P0P1_DP<18>")
	)
	(segment
		(start 124.303536 -197.095618)
		(end 124.321062 -197.267068)
		(width 0.14732)
		(layer "In6.Cu")
		(net "UPI_CPU0_CPU1_P0P1_DP<18>")
	)
	(segment
		(start 349.127064 -195.79209)
		(end 339.499956 -186.477402)
		(width 0.14732)
		(layer "In6.Cu")
		(net "UPI_CPU0_CPU1_P0P1_DP<18>")
	)
	(segment
		(start 125.28423 -195.889118)
		(end 125.283976 -195.889372)
		(width 0.14732)
		(layer "In6.Cu")
		(net "UPI_CPU0_CPU1_P0P1_DP<18>")
	)
	(segment
		(start 313.388502 -173.425104)
		(end 302.479964 -173.222158)
		(width 0.14732)
		(layer "In6.Cu")
		(net "UPI_CPU0_CPU1_P0P1_DP<18>")
	)
	(segment
		(start 353.80422 -211.53755)
		(end 353.80422 -210.190588)
		(width 0.14732)
		(layer "In6.Cu")
		(net "UPI_CPU0_CPU1_P0P1_DP<18>")
	)
	(segment
		(start 353.804474 -211.537296)
		(end 353.80422 -211.53755)
		(width 0.14732)
		(layer "In6.Cu")
		(net "UPI_CPU0_CPU1_P0P1_DP<18>")
	)
	(segment
		(start 125.731016 -195.53174)
		(end 125.455426 -195.871084)
		(width 0.14732)
		(layer "In6.Cu")
		(net "UPI_CPU0_CPU1_P0P1_DP<18>")
	)
	(segment
		(start 118.356126 -211.579968)
		(end 118.35638 -211.580222)
		(width 0.14732)
		(layer "In6.Cu")
		(net "UPI_CPU0_CPU1_P0P1_DP<18>")
	)
	(segment
		(start 125.71349 -195.36029)
		(end 125.731016 -195.53174)
		(width 0.14732)
		(layer "In6.Cu")
		(net "UPI_CPU0_CPU1_P0P1_DP<18>")
	)
	(segment
		(start 121.413778 -200.650602)
		(end 118.356126 -209.384138)
		(width 0.14732)
		(layer "In6.Cu")
		(net "UPI_CPU0_CPU1_P0P1_DP<18>")
	)
	(segment
		(start 117.983762 -214.91448)
		(end 118.061994 -214.893652)
		(width 0.0889)
		(layer "In6.Cu")
		(net "UPI_CPU0_CPU1_P0P1_DP<18>")
	)
	(segment
		(start 124.321062 -197.267068)
		(end 124.045218 -197.606412)
		(width 0.14732)
		(layer "In6.Cu")
		(net "UPI_CPU0_CPU1_P0P1_DP<18>")
	)
	(segment
		(start 135.176768 -187.357004)
		(end 128.742694 -191.633602)
		(width 0.14732)
		(layer "In6.Cu")
		(net "UPI_CPU0_CPU1_P0P1_DP<18>")
	)
	(segment
		(start 353.846384 -213.488524)
		(end 353.74707 -213.38921)
		(width 0.0889)
		(layer "In6.Cu")
		(net "UPI_CPU0_CPU1_P0P1_DP<18>")
	)
	(segment
		(start 118.314216 -212.761576)
		(end 118.314216 -213.046564)
		(width 0.0889)
		(layer "In6.Cu")
		(net "UPI_CPU0_CPU1_P0P1_DP<18>")
	)
	(segment
		(start 139.409424 -181.67604)
		(end 135.176768 -187.357004)
		(width 0.14732)
		(layer "In6.Cu")
		(net "UPI_CPU0_CPU1_P0P1_DP<18>")
	)
	(segment
		(start 123.115324 -198.557388)
		(end 122.839988 -198.896224)
		(width 0.14732)
		(layer "In6.Cu")
		(net "UPI_CPU0_CPU1_P0P1_DP<18>")
	)
	(segment
		(start 118.061994 -214.893652)
		(end 118.218458 -214.622634)
		(width 0.0889)
		(layer "In6.Cu")
		(net "UPI_CPU0_CPU1_P0P1_DP<18>")
	)
	(segment
		(start 124.045218 -197.606412)
		(end 123.873768 -197.624192)
		(width 0.14732)
		(layer "In6.Cu")
		(net "UPI_CPU0_CPU1_P0P1_DP<18>")
	)
	(segment
		(start 128.742694 -191.633602)
		(end 127.837438 -192.747138)
		(width 0.14732)
		(layer "In6.Cu")
		(net "UPI_CPU0_CPU1_P0P1_DP<18>")
	)
	(segment
		(start 127.407924 -193.275712)
		(end 127.132588 -193.614548)
		(width 0.14732)
		(layer "In6.Cu")
		(net "UPI_CPU0_CPU1_P0P1_DP<18>")
	)
	(segment
		(start 353.846384 -213.8934)
		(end 353.846384 -213.488524)
		(width 0.0889)
		(layer "In6.Cu")
		(net "UPI_CPU0_CPU1_P0P1_DP<18>")
	)
	(segment
		(start 126.70282 -194.143122)
		(end 126.427484 -194.481958)
		(width 0.14732)
		(layer "In6.Cu")
		(net "UPI_CPU0_CPU1_P0P1_DP<18>")
	)
	(segment
		(start 122.58167 -199.407018)
		(end 122.41022 -199.424798)
		(width 0.14732)
		(layer "In6.Cu")
		(net "UPI_CPU0_CPU1_P0P1_DP<18>")
	)
	(segment
		(start 122.41022 -199.424798)
		(end 121.413778 -200.650602)
		(width 0.14732)
		(layer "In6.Cu")
		(net "UPI_CPU0_CPU1_P0P1_DP<18>")
	)
	(segment
		(start 118.41353 -213.145878)
		(end 118.41353 -213.412578)
		(width 0.0889)
		(layer "In6.Cu")
		(net "UPI_CPU0_CPU1_P0P1_DP<18>")
	)
	(segment
		(start 123.286774 -198.539608)
		(end 123.115324 -198.557388)
		(width 0.14732)
		(layer "In6.Cu")
		(net "UPI_CPU0_CPU1_P0P1_DP<18>")
	)
	(segment
		(start 126.16942 -194.992752)
		(end 125.997716 -195.010532)
		(width 0.14732)
		(layer "In6.Cu")
		(net "UPI_CPU0_CPU1_P0P1_DP<18>")
	)
	(segment
		(start 200.782682 -173.644814)
		(end 156.826966 -174.374302)
		(width 0.14732)
		(layer "In6.Cu")
		(net "UPI_CPU0_CPU1_P0P1_DP<18>")
	)
	(segment
		(start 125.283722 -195.888864)
		(end 125.28423 -195.889118)
		(width 0.14732)
		(layer "In6.Cu")
		(net "UPI_CPU0_CPU1_P0P1_DP<18>")
	)
	(segment
		(start 118.314216 -213.046564)
		(end 118.41353 -213.145878)
		(width 0.0889)
		(layer "In6.Cu")
		(net "UPI_CPU0_CPU1_P0P1_DP<18>")
	)
	(segment
		(start 318.877188 -174.959264)
		(end 313.388502 -173.425104)
		(width 0.14732)
		(layer "In6.Cu")
		(net "UPI_CPU0_CPU1_P0P1_DP<18>")
	)
	(segment
		(start 126.427484 -194.481958)
		(end 126.44501 -194.653408)
		(width 0.14732)
		(layer "In6.Cu")
		(net "UPI_CPU0_CPU1_P0P1_DP<18>")
	)
	(segment
		(start 126.874524 -194.125342)
		(end 126.70282 -194.143122)
		(width 0.14732)
		(layer "In6.Cu")
		(net "UPI_CPU0_CPU1_P0P1_DP<18>")
	)
	(segment
		(start 353.74707 -212.657182)
		(end 353.74707 -212.390482)
		(width 0.0889)
		(layer "In6.Cu")
		(net "UPI_CPU0_CPU1_P0P1_DP<18>")
	)
	(segment
		(start 125.00864 -196.228208)
		(end 125.026166 -196.399658)
		(width 0.14732)
		(layer "In6.Cu")
		(net "UPI_CPU0_CPU1_P0P1_DP<18>")
	)
	(segment
		(start 273.091402 -173.936914)
		(end 238.277146 -174.10176)
		(width 0.14732)
		(layer "In6.Cu")
		(net "UPI_CPU0_CPU1_P0P1_DP<18>")
	)
	(segment
		(start 353.80422 -210.190588)
		(end 352.757994 -200.286366)
		(width 0.14732)
		(layer "In6.Cu")
		(net "UPI_CPU0_CPU1_P0P1_DP<18>")
	)
	(segment
		(start 118.35638 -211.73821)
		(end 118.35638 -211.760308)
		(width 0.0889)
		(layer "In6.Cu")
		(net "UPI_CPU0_CPU1_P0P1_DP<18>")
	)
	(segment
		(start 124.750322 -196.739002)
		(end 124.578872 -196.756782)
		(width 0.14732)
		(layer "In6.Cu")
		(net "UPI_CPU0_CPU1_P0P1_DP<18>")
	)
	(segment
		(start 353.471734 -213.732618)
		(end 353.630484 -214.033608)
		(width 0.0889)
		(layer "In6.Cu")
		(net "UPI_CPU0_CPU1_P0P1_DP<18>")
	)
	(segment
		(start 125.455426 -195.871084)
		(end 125.283722 -195.888864)
		(width 0.14732)
		(layer "In6.Cu")
		(net "UPI_CPU0_CPU1_P0P1_DP<18>")
	)
	(segment
		(start 353.74707 -213.38921)
		(end 353.74707 -213.12251)
		(width 0.0889)
		(layer "In6.Cu")
		(net "UPI_CPU0_CPU1_P0P1_DP<18>")
	)
	(segment
		(start 118.41353 -212.662262)
		(end 118.314216 -212.761576)
		(width 0.0889)
		(layer "In6.Cu")
		(net "UPI_CPU0_CPU1_P0P1_DP<18>")
	)
	(segment
		(start 353.74707 -212.390482)
		(end 353.846384 -212.291168)
		(width 0.0889)
		(layer "In6.Cu")
		(net "UPI_CPU0_CPU1_P0P1_DP<18>")
	)
	(segment
		(start 122.839988 -198.896224)
		(end 122.857514 -199.067674)
		(width 0.14732)
		(layer "In6.Cu")
		(net "UPI_CPU0_CPU1_P0P1_DP<18>")
	)
	(segment
		(start 211.194396 -174.10176)
		(end 200.782682 -173.644814)
		(width 0.14732)
		(layer "In6.Cu")
		(net "UPI_CPU0_CPU1_P0P1_DP<18>")
	)
	(segment
		(start 125.997716 -195.010532)
		(end 125.71349 -195.36029)
		(width 0.14732)
		(layer "In6.Cu")
		(net "UPI_CPU0_CPU1_P0P1_DP<18>")
	)
	(segment
		(start 118.35638 -211.580222)
		(end 118.35638 -211.73821)
		(width 0.14732)
		(layer "In6.Cu")
		(net "UPI_CPU0_CPU1_P0P1_DP<18>")
	)
	(segment
		(start 118.41353 -212.395562)
		(end 118.41353 -212.662262)
		(width 0.0889)
		(layer "In6.Cu")
		(net "UPI_CPU0_CPU1_P0P1_DP<18>")
	)
	(segment
		(start 127.837438 -192.747138)
		(end 127.855218 -192.918842)
		(width 0.14732)
		(layer "In6.Cu")
		(net "UPI_CPU0_CPU1_P0P1_DP<18>")
	)
	(segment
		(start 127.579374 -193.257932)
		(end 127.407924 -193.275712)
		(width 0.14732)
		(layer "In6.Cu")
		(net "UPI_CPU0_CPU1_P0P1_DP<18>")
	)
	(segment
		(start 118.35638 -211.760308)
		(end 118.314216 -211.802472)
		(width 0.0889)
		(layer "In6.Cu")
		(net "UPI_CPU0_CPU1_P0P1_DP<18>")
	)
	(segment
		(start 353.804474 -211.684108)
		(end 353.804474 -211.66201)
		(width 0.0889)
		(layer "In6.Cu")
		(net "UPI_CPU0_CPU1_P0P1_DP<18>")
	)
	(segment
		(start 118.314216 -212.296248)
		(end 118.41353 -212.395562)
		(width 0.0889)
		(layer "In6.Cu")
		(net "UPI_CPU0_CPU1_P0P1_DP<18>")
	)
	(segment
		(start 353.804474 -211.66201)
		(end 353.804474 -211.537296)
		(width 0.14732)
		(layer "In6.Cu")
		(net "UPI_CPU0_CPU1_P0P1_DP<18>")
	)
	(segment
		(start 127.132588 -193.614548)
		(end 127.150114 -193.785998)
		(width 0.14732)
		(layer "In6.Cu")
		(net "UPI_CPU0_CPU1_P0P1_DP<18>")
	)
	(segment
		(start 353.846384 -212.756496)
		(end 353.74707 -212.657182)
		(width 0.0889)
		(layer "In6.Cu")
		(net "UPI_CPU0_CPU1_P0P1_DP<18>")
	)
	(segment
		(start 118.314216 -213.511892)
		(end 118.314216 -213.929468)
		(width 0.0889)
		(layer "In6.Cu")
		(net "UPI_CPU0_CPU1_P0P1_DP<18>")
	)
	(segment
		(start 302.479964 -173.222158)
		(end 273.091402 -173.936914)
		(width 0.14732)
		(layer "In6.Cu")
		(net "UPI_CPU0_CPU1_P0P1_DP<18>")
	)
	(segment
		(start 353.630484 -214.033608)
		(end 353.715066 -214.05977)
		(width 0.0889)
		(layer "In6.Cu")
		(net "UPI_CPU0_CPU1_P0P1_DP<18>")
	)
	(segment
		(start 123.873768 -197.624192)
		(end 123.544838 -198.028814)
		(width 0.14732)
		(layer "In6.Cu")
		(net "UPI_CPU0_CPU1_P0P1_DP<18>")
	)
	(segment
		(start 125.283976 -195.889372)
		(end 125.00864 -196.228208)
		(width 0.14732)
		(layer "In6.Cu")
		(net "UPI_CPU0_CPU1_P0P1_DP<18>")
	)
	(segment
		(start 117.843808 -214.461852)
		(end 117.843808 -214.622634)
		(width 0.0889)
		(layer "In6.Cu")
		(net "UPI_CPU0_CPU1_P0P1_DP<18>")
	)
	(segment
		(start 125.026166 -196.399658)
		(end 124.750322 -196.739002)
		(width 0.14732)
		(layer "In6.Cu")
		(net "UPI_CPU0_CPU1_P0P1_DP<18>")
	)
	(segment
		(start 353.846384 -213.023196)
		(end 353.846384 -212.756496)
		(width 0.0889)
		(layer "In6.Cu")
		(net "UPI_CPU0_CPU1_P0P1_DP<18>")
	)
	(segment
		(start 118.356126 -209.384138)
		(end 118.356126 -211.579968)
		(width 0.14732)
		(layer "In6.Cu")
		(net "UPI_CPU0_CPU1_P0P1_DP<18>")
	)
	(segment
		(start 353.846384 -212.291168)
		(end 353.846384 -211.726018)
		(width 0.0889)
		(layer "In6.Cu")
		(net "UPI_CPU0_CPU1_P0P1_DP<18>")
	)
	(segment
		(start 352.757994 -200.286366)
		(end 349.127064 -195.79209)
		(width 0.14732)
		(layer "In6.Cu")
		(net "UPI_CPU0_CPU1_P0P1_DP<18>")
	)
	(segment
		(start 156.826966 -174.374302)
		(end 150.516082 -175.989234)
		(width 0.14732)
		(layer "In6.Cu")
		(net "UPI_CPU0_CPU1_P0P1_DP<18>")
	)
	(segment
		(start 127.150114 -193.785998)
		(end 126.874524 -194.125342)
		(width 0.14732)
		(layer "In6.Cu")
		(net "UPI_CPU0_CPU1_P0P1_DP<18>")
	)
	(segment
		(start 353.74707 -213.12251)
		(end 353.846384 -213.023196)
		(width 0.0889)
		(layer "In6.Cu")
		(net "UPI_CPU0_CPU1_P0P1_DP<18>")
	)
	(segment
		(start 127.855218 -192.918842)
		(end 127.579374 -193.257932)
		(width 0.14732)
		(layer "In6.Cu")
		(net "UPI_CPU0_CPU1_P0P1_DP<18>")
	)
	(segment
		(start 126.44501 -194.653408)
		(end 126.16942 -194.992752)
		(width 0.14732)
		(layer "In6.Cu")
		(net "UPI_CPU0_CPU1_P0P1_DP<18>")
	)
	(segment
		(start 353.846384 -211.726018)
		(end 353.804474 -211.684108)
		(width 0.0889)
		(layer "In6.Cu")
		(net "UPI_CPU0_CPU1_P0P1_DP<18>")
	)
	(segment
		(start 123.562618 -198.200518)
		(end 123.286774 -198.539608)
		(width 0.14732)
		(layer "In6.Cu")
		(net "UPI_CPU0_CPU1_P0P1_DP<18>")
	)
	(segment
		(start 122.857514 -199.067674)
		(end 122.58167 -199.407018)
		(width 0.14732)
		(layer "In6.Cu")
		(net "UPI_CPU0_CPU1_P0P1_DP<18>")
	)
	(segment
		(start 238.277146 -174.10176)
		(end 211.194396 -174.10176)
		(width 0.14732)
		(layer "In6.Cu")
		(net "UPI_CPU0_CPU1_P0P1_DP<18>")
	)
	(segment
		(start 123.544838 -198.028814)
		(end 123.562618 -198.200518)
		(width 0.14732)
		(layer "In6.Cu")
		(net "UPI_CPU0_CPU1_P0P1_DP<18>")
	)
	(segment
		(start 118.41353 -213.412578)
		(end 118.314216 -213.511892)
		(width 0.0889)
		(layer "In6.Cu")
		(net "UPI_CPU0_CPU1_P0P1_DP<18>")
	)
	(segment
		(start 118.314216 -211.802472)
		(end 118.314216 -212.296248)
		(width 0.0889)
		(layer "In6.Cu")
		(net "UPI_CPU0_CPU1_P0P1_DP<18>")
	)
	(segment
		(start 150.516082 -175.989234)
		(end 139.409424 -181.67604)
		(width 0.14732)
		(layer "In6.Cu")
		(net "UPI_CPU0_CPU1_P0P1_DP<18>")
	)
	(arc
		(start 117.843808 -214.622634)
		(mid 117.880668 -214.784431)
		(end 117.983762 -214.91448)
		(width 0.0889)
		(layer "In6.Cu")
		(net "UPI_CPU0_CPU1_P0P1_DP<18>")
	)
	(arc
		(start 118.314216 -213.929468)
		(mid 118.306938 -213.949159)
		(end 118.298976 -213.968584)
		(width 0.0889)
		(layer "In6.Cu")
		(net "UPI_CPU0_CPU1_P0P1_DP<18>")
	)
	(arc
		(start 353.715066 -214.05977)
		(mid 353.791739 -213.985276)
		(end 353.846384 -213.8934)
		(width 0.0889)
		(layer "In6.Cu")
		(net "UPI_CPU0_CPU1_P0P1_DP<18>")
	)
	(arc
		(start 118.298976 -213.968584)
		(mid 118.18877 -214.138501)
		(end 118.028212 -214.261954)
		(width 0.0889)
		(layer "In6.Cu")
		(net "UPI_CPU0_CPU1_P0P1_DP<18>")
	)
	(arc
		(start 118.028212 -214.261954)
		(mid 117.918816 -214.346051)
		(end 117.843808 -214.461852)
		(width 0.0889)
		(layer "In6.Cu")
		(net "UPI_CPU0_CPU1_P0P1_DP<18>")
	)
	(segment
		(start 352.531934 -215.972644)
		(end 352.531934 -215.436958)
		(width 0.13208)
		(layer "F.Cu")
		(net "UPI_CPU0_CPU1_P0P1_DP<17>")
	)
	(segment
		(start 352.531934 -215.436958)
		(end 352.53168 -215.436704)
		(width 0.13208)
		(layer "F.Cu")
		(net "UPI_CPU0_CPU1_P0P1_DP<17>")
	)
	(segment
		(start 119.158512 -215.158574)
		(end 119.158512 -214.622888)
		(width 0.13208)
		(layer "F.Cu")
		(net "UPI_CPU0_CPU1_P0P1_DP<17>")
	)
	(segment
		(start 119.158512 -214.622888)
		(end 119.158258 -214.622634)
		(width 0.13208)
		(layer "F.Cu")
		(net "UPI_CPU0_CPU1_P0P1_DP<17>")
	)
	(segment
		(start 352.53168 -215.436704)
		(end 352.688144 -215.165686)
		(width 0.0889)
		(layer "In6.Cu")
		(net "UPI_CPU0_CPU1_P0P1_DP<17>")
	)
	(segment
		(start 352.864674 -210.244944)
		(end 351.83318 -200.48474)
		(width 0.14732)
		(layer "In6.Cu")
		(net "UPI_CPU0_CPU1_P0P1_DP<17>")
	)
	(segment
		(start 352.906584 -213.8934)
		(end 352.906838 -213.892892)
		(width 0.0889)
		(layer "In6.Cu")
		(net "UPI_CPU0_CPU1_P0P1_DP<17>")
	)
	(segment
		(start 153.897076 -176.090834)
		(end 153.896822 -176.091088)
		(width 0.14732)
		(layer "In6.Cu")
		(net "UPI_CPU0_CPU1_P0P1_DP<17>")
	)
	(segment
		(start 352.864928 -211.684108)
		(end 352.864928 -211.66201)
		(width 0.0889)
		(layer "In6.Cu")
		(net "UPI_CPU0_CPU1_P0P1_DP<17>")
	)
	(segment
		(start 200.606152 -174.489364)
		(end 157.34919 -175.207422)
		(width 0.14732)
		(layer "In6.Cu")
		(net "UPI_CPU0_CPU1_P0P1_DP<17>")
	)
	(segment
		(start 119.295672 -211.173568)
		(end 119.295926 -211.173822)
		(width 0.14732)
		(layer "In6.Cu")
		(net "UPI_CPU0_CPU1_P0P1_DP<17>")
	)
	(segment
		(start 135.689848 -188.080396)
		(end 129.564384 -192.150492)
		(width 0.14732)
		(layer "In6.Cu")
		(net "UPI_CPU0_CPU1_P0P1_DP<17>")
	)
	(segment
		(start 119.295672 -209.330036)
		(end 119.295672 -211.173568)
		(width 0.14732)
		(layer "In6.Cu")
		(net "UPI_CPU0_CPU1_P0P1_DP<17>")
	)
	(segment
		(start 119.886984 -208.07172)
		(end 119.76608 -208.419954)
		(width 0.14732)
		(layer "In6.Cu")
		(net "UPI_CPU0_CPU1_P0P1_DP<17>")
	)
	(segment
		(start 120.22455 -207.10271)
		(end 120.103392 -207.45069)
		(width 0.14732)
		(layer "In6.Cu")
		(net "UPI_CPU0_CPU1_P0P1_DP<17>")
	)
	(segment
		(start 119.029734 -214.22487)
		(end 118.999508 -214.321644)
		(width 0.0889)
		(layer "In6.Cu")
		(net "UPI_CPU0_CPU1_P0P1_DP<17>")
	)
	(segment
		(start 119.918734 -207.539844)
		(end 119.79783 -207.88757)
		(width 0.14732)
		(layer "In6.Cu")
		(net "UPI_CPU0_CPU1_P0P1_DP<17>")
	)
	(segment
		(start 121.581418 -203.204826)
		(end 121.46026 -203.55306)
		(width 0.14732)
		(layer "In6.Cu")
		(net "UPI_CPU0_CPU1_P0P1_DP<17>")
	)
	(segment
		(start 318.517016 -175.724566)
		(end 313.30011 -174.266352)
		(width 0.14732)
		(layer "In6.Cu")
		(net "UPI_CPU0_CPU1_P0P1_DP<17>")
	)
	(segment
		(start 339.501226 -187.838334)
		(end 339.497924 -187.63361)
		(width 0.14732)
		(layer "In6.Cu")
		(net "UPI_CPU0_CPU1_P0P1_DP<17>")
	)
	(segment
		(start 120.135396 -206.918306)
		(end 120.22455 -207.10271)
		(width 0.14732)
		(layer "In6.Cu")
		(net "UPI_CPU0_CPU1_P0P1_DP<17>")
	)
	(segment
		(start 121.275602 -203.642214)
		(end 120.135396 -206.918306)
		(width 0.14732)
		(layer "In6.Cu")
		(net "UPI_CPU0_CPU1_P0P1_DP<17>")
	)
	(segment
		(start 348.443296 -196.288914)
		(end 340.730332 -188.82614)
		(width 0.14732)
		(layer "In6.Cu")
		(net "UPI_CPU0_CPU1_P0P1_DP<17>")
	)
	(segment
		(start 119.581422 -208.509108)
		(end 119.295672 -209.330036)
		(width 0.14732)
		(layer "In6.Cu")
		(net "UPI_CPU0_CPU1_P0P1_DP<17>")
	)
	(segment
		(start 339.766148 -188.09462)
		(end 339.501226 -187.838334)
		(width 0.14732)
		(layer "In6.Cu")
		(net "UPI_CPU0_CPU1_P0P1_DP<17>")
	)
	(segment
		(start 119.79783 -207.88757)
		(end 119.886984 -208.07172)
		(width 0.14732)
		(layer "In6.Cu")
		(net "UPI_CPU0_CPU1_P0P1_DP<17>")
	)
	(segment
		(start 335.481676 -184.593484)
		(end 318.517016 -175.724566)
		(width 0.14732)
		(layer "In6.Cu")
		(net "UPI_CPU0_CPU1_P0P1_DP<17>")
	)
	(segment
		(start 119.295926 -211.173822)
		(end 119.295926 -211.61629)
		(width 0.14732)
		(layer "In6.Cu")
		(net "UPI_CPU0_CPU1_P0P1_DP<17>")
	)
	(segment
		(start 339.970872 -188.091318)
		(end 339.766148 -188.09462)
		(width 0.14732)
		(layer "In6.Cu")
		(net "UPI_CPU0_CPU1_P0P1_DP<17>")
	)
	(segment
		(start 352.688144 -215.165686)
		(end 352.664014 -215.076532)
		(width 0.0889)
		(layer "In6.Cu")
		(net "UPI_CPU0_CPU1_P0P1_DP<17>")
	)
	(segment
		(start 313.30011 -174.266352)
		(end 302.48225 -174.065184)
		(width 0.14732)
		(layer "In6.Cu")
		(net "UPI_CPU0_CPU1_P0P1_DP<17>")
	)
	(segment
		(start 352.906838 -211.726018)
		(end 352.864928 -211.684108)
		(width 0.0889)
		(layer "In6.Cu")
		(net "UPI_CPU0_CPU1_P0P1_DP<17>")
	)
	(segment
		(start 238.609632 -174.944278)
		(end 210.970114 -174.944278)
		(width 0.14732)
		(layer "In6.Cu")
		(net "UPI_CPU0_CPU1_P0P1_DP<17>")
	)
	(segment
		(start 121.878344 -201.911204)
		(end 121.967498 -202.095354)
		(width 0.14732)
		(layer "In6.Cu")
		(net "UPI_CPU0_CPU1_P0P1_DP<17>")
	)
	(segment
		(start 210.970114 -174.944278)
		(end 200.606152 -174.489364)
		(width 0.14732)
		(layer "In6.Cu")
		(net "UPI_CPU0_CPU1_P0P1_DP<17>")
	)
	(segment
		(start 157.34919 -175.207422)
		(end 153.897076 -176.090834)
		(width 0.14732)
		(layer "In6.Cu")
		(net "UPI_CPU0_CPU1_P0P1_DP<17>")
	)
	(segment
		(start 352.436176 -214.636858)
		(end 352.436176 -214.425784)
		(width 0.0889)
		(layer "In6.Cu")
		(net "UPI_CPU0_CPU1_P0P1_DP<17>")
	)
	(segment
		(start 340.525608 -188.829442)
		(end 340.260686 -188.573156)
		(width 0.14732)
		(layer "In6.Cu")
		(net "UPI_CPU0_CPU1_P0P1_DP<17>")
	)
	(segment
		(start 119.295926 -211.61629)
		(end 119.295926 -211.638388)
		(width 0.0889)
		(layer "In6.Cu")
		(net "UPI_CPU0_CPU1_P0P1_DP<17>")
	)
	(segment
		(start 119.253762 -211.680552)
		(end 119.253762 -213.93023)
		(width 0.0889)
		(layer "In6.Cu")
		(net "UPI_CPU0_CPU1_P0P1_DP<17>")
	)
	(segment
		(start 119.253762 -213.93023)
		(end 119.254016 -213.929468)
		(width 0.0889)
		(layer "In6.Cu")
		(net "UPI_CPU0_CPU1_P0P1_DP<17>")
	)
	(segment
		(start 119.76608 -208.419954)
		(end 119.581422 -208.509108)
		(width 0.14732)
		(layer "In6.Cu")
		(net "UPI_CPU0_CPU1_P0P1_DP<17>")
	)
	(segment
		(start 352.864674 -211.53755)
		(end 352.864674 -210.244944)
		(width 0.14732)
		(layer "In6.Cu")
		(net "UPI_CPU0_CPU1_P0P1_DP<17>")
	)
	(segment
		(start 351.83318 -200.48474)
		(end 348.443296 -196.288914)
		(width 0.14732)
		(layer "In6.Cu")
		(net "UPI_CPU0_CPU1_P0P1_DP<17>")
	)
	(segment
		(start 139.965684 -182.339996)
		(end 135.689848 -188.080396)
		(width 0.14732)
		(layer "In6.Cu")
		(net "UPI_CPU0_CPU1_P0P1_DP<17>")
	)
	(segment
		(start 129.564384 -192.150492)
		(end 122.063256 -201.379582)
		(width 0.14732)
		(layer "In6.Cu")
		(net "UPI_CPU0_CPU1_P0P1_DP<17>")
	)
	(segment
		(start 150.445216 -176.974246)
		(end 139.965684 -182.339996)
		(width 0.14732)
		(layer "In6.Cu")
		(net "UPI_CPU0_CPU1_P0P1_DP<17>")
	)
	(segment
		(start 302.48225 -174.065184)
		(end 273.103848 -174.779432)
		(width 0.14732)
		(layer "In6.Cu")
		(net "UPI_CPU0_CPU1_P0P1_DP<17>")
	)
	(segment
		(start 119.295926 -211.638388)
		(end 119.253762 -211.680552)
		(width 0.0889)
		(layer "In6.Cu")
		(net "UPI_CPU0_CPU1_P0P1_DP<17>")
	)
	(segment
		(start 273.103848 -174.779432)
		(end 238.609632 -174.944278)
		(width 0.14732)
		(layer "In6.Cu")
		(net "UPI_CPU0_CPU1_P0P1_DP<17>")
	)
	(segment
		(start 121.661936 -202.532742)
		(end 121.492264 -203.020422)
		(width 0.14732)
		(layer "In6.Cu")
		(net "UPI_CPU0_CPU1_P0P1_DP<17>")
	)
	(segment
		(start 153.896822 -176.091088)
		(end 150.445216 -176.974246)
		(width 0.14732)
		(layer "In6.Cu")
		(net "UPI_CPU0_CPU1_P0P1_DP<17>")
	)
	(segment
		(start 340.730332 -188.82614)
		(end 340.525608 -188.829442)
		(width 0.14732)
		(layer "In6.Cu")
		(net "UPI_CPU0_CPU1_P0P1_DP<17>")
	)
	(segment
		(start 339.497924 -187.63361)
		(end 339.012784 -187.164218)
		(width 0.14732)
		(layer "In6.Cu")
		(net "UPI_CPU0_CPU1_P0P1_DP<17>")
	)
	(segment
		(start 339.012784 -187.164218)
		(end 335.481676 -184.593484)
		(width 0.14732)
		(layer "In6.Cu")
		(net "UPI_CPU0_CPU1_P0P1_DP<17>")
	)
	(segment
		(start 340.257384 -188.368432)
		(end 339.970872 -188.091318)
		(width 0.14732)
		(layer "In6.Cu")
		(net "UPI_CPU0_CPU1_P0P1_DP<17>")
	)
	(segment
		(start 340.260686 -188.573156)
		(end 340.257384 -188.368432)
		(width 0.14732)
		(layer "In6.Cu")
		(net "UPI_CPU0_CPU1_P0P1_DP<17>")
	)
	(segment
		(start 122.063256 -201.379582)
		(end 121.878344 -201.911204)
		(width 0.14732)
		(layer "In6.Cu")
		(net "UPI_CPU0_CPU1_P0P1_DP<17>")
	)
	(segment
		(start 121.46026 -203.55306)
		(end 121.275602 -203.642214)
		(width 0.14732)
		(layer "In6.Cu")
		(net "UPI_CPU0_CPU1_P0P1_DP<17>")
	)
	(segment
		(start 121.846594 -202.443588)
		(end 121.661936 -202.532742)
		(width 0.14732)
		(layer "In6.Cu")
		(net "UPI_CPU0_CPU1_P0P1_DP<17>")
	)
	(segment
		(start 352.906838 -213.892892)
		(end 352.906838 -211.726018)
		(width 0.0889)
		(layer "In6.Cu")
		(net "UPI_CPU0_CPU1_P0P1_DP<17>")
	)
	(segment
		(start 352.864928 -211.537296)
		(end 352.864674 -211.53755)
		(width 0.14732)
		(layer "In6.Cu")
		(net "UPI_CPU0_CPU1_P0P1_DP<17>")
	)
	(segment
		(start 121.492264 -203.020422)
		(end 121.581418 -203.204826)
		(width 0.14732)
		(layer "In6.Cu")
		(net "UPI_CPU0_CPU1_P0P1_DP<17>")
	)
	(segment
		(start 118.999508 -214.321644)
		(end 119.158258 -214.622634)
		(width 0.0889)
		(layer "In6.Cu")
		(net "UPI_CPU0_CPU1_P0P1_DP<17>")
	)
	(segment
		(start 120.103392 -207.45069)
		(end 119.918734 -207.539844)
		(width 0.14732)
		(layer "In6.Cu")
		(net "UPI_CPU0_CPU1_P0P1_DP<17>")
	)
	(segment
		(start 121.967498 -202.095354)
		(end 121.846594 -202.443588)
		(width 0.14732)
		(layer "In6.Cu")
		(net "UPI_CPU0_CPU1_P0P1_DP<17>")
	)
	(segment
		(start 352.864928 -211.66201)
		(end 352.864928 -211.537296)
		(width 0.14732)
		(layer "In6.Cu")
		(net "UPI_CPU0_CPU1_P0P1_DP<17>")
	)
	(arc
		(start 352.646996 -215.063324)
		(mid 352.494565 -214.873342)
		(end 352.436176 -214.636858)
		(width 0.0889)
		(layer "In6.Cu")
		(net "UPI_CPU0_CPU1_P0P1_DP<17>")
	)
	(arc
		(start 352.664014 -215.076532)
		(mid 352.655442 -215.070009)
		(end 352.646996 -215.063324)
		(width 0.0889)
		(layer "In6.Cu")
		(net "UPI_CPU0_CPU1_P0P1_DP<17>")
	)
	(arc
		(start 119.254016 -213.929468)
		(mid 119.246858 -213.949028)
		(end 119.23903 -213.96833)
		(width 0.0889)
		(layer "In6.Cu")
		(net "UPI_CPU0_CPU1_P0P1_DP<17>")
	)
	(arc
		(start 352.436176 -214.425784)
		(mid 352.547616 -214.232389)
		(end 352.72218 -214.093298)
		(width 0.0889)
		(layer "In6.Cu")
		(net "UPI_CPU0_CPU1_P0P1_DP<17>")
	)
	(arc
		(start 352.72218 -214.093298)
		(mid 352.831576 -214.009201)
		(end 352.906584 -213.8934)
		(width 0.0889)
		(layer "In6.Cu")
		(net "UPI_CPU0_CPU1_P0P1_DP<17>")
	)
	(arc
		(start 119.23903 -213.96833)
		(mid 119.152479 -214.111364)
		(end 119.029734 -214.22487)
		(width 0.0889)
		(layer "In6.Cu")
		(net "UPI_CPU0_CPU1_P0P1_DP<17>")
	)
	(segment
		(start 351.592134 -214.344758)
		(end 351.592134 -213.732618)
		(width 0.13208)
		(layer "F.Cu")
		(net "UPI_CPU0_CPU1_P0P1_DP<16>")
	)
	(segment
		(start 120.098312 -214.622888)
		(end 120.098058 -214.622634)
		(width 0.13208)
		(layer "F.Cu")
		(net "UPI_CPU0_CPU1_P0P1_DP<16>")
	)
	(segment
		(start 120.098312 -215.158574)
		(end 120.098312 -214.622888)
		(width 0.13208)
		(layer "F.Cu")
		(net "UPI_CPU0_CPU1_P0P1_DP<16>")
	)
	(segment
		(start 136.241282 -188.750194)
		(end 130.071622 -192.85077)
		(width 0.14732)
		(layer "In6.Cu")
		(net "UPI_CPU0_CPU1_P0P1_DP<16>")
	)
	(segment
		(start 339.840824 -189.325504)
		(end 339.47608 -188.972698)
		(width 0.14732)
		(layer "In6.Cu")
		(net "UPI_CPU0_CPU1_P0P1_DP<16>")
	)
	(segment
		(start 339.271356 -188.976)
		(end 339.006434 -188.719714)
		(width 0.14732)
		(layer "In6.Cu")
		(net "UPI_CPU0_CPU1_P0P1_DP<16>")
	)
	(segment
		(start 123.183142 -201.325734)
		(end 123.183396 -201.325734)
		(width 0.14732)
		(layer "In6.Cu")
		(net "UPI_CPU0_CPU1_P0P1_DP<16>")
	)
	(segment
		(start 273.116294 -175.635666)
		(end 238.611918 -175.800512)
		(width 0.14732)
		(layer "In6.Cu")
		(net "UPI_CPU0_CPU1_P0P1_DP<16>")
	)
	(segment
		(start 120.379998 -209.331814)
		(end 120.235726 -209.744056)
		(width 0.14732)
		(layer "In6.Cu")
		(net "UPI_CPU0_CPU1_P0P1_DP<16>")
	)
	(segment
		(start 120.193816 -213.511892)
		(end 120.193816 -213.929468)
		(width 0.0889)
		(layer "In6.Cu")
		(net "UPI_CPU0_CPU1_P0P1_DP<16>")
	)
	(segment
		(start 351.86747 -213.12251)
		(end 351.966784 -213.023196)
		(width 0.0889)
		(layer "In6.Cu")
		(net "UPI_CPU0_CPU1_P0P1_DP<16>")
	)
	(segment
		(start 341.316056 -190.752984)
		(end 341.051388 -190.496952)
		(width 0.14732)
		(layer "In6.Cu")
		(net "UPI_CPU0_CPU1_P0P1_DP<16>")
	)
	(segment
		(start 120.974612 -207.634332)
		(end 121.049542 -207.789526)
		(width 0.14732)
		(layer "In6.Cu")
		(net "UPI_CPU0_CPU1_P0P1_DP<16>")
	)
	(segment
		(start 351.966784 -211.726018)
		(end 351.924874 -211.684108)
		(width 0.0889)
		(layer "In6.Cu")
		(net "UPI_CPU0_CPU1_P0P1_DP<16>")
	)
	(segment
		(start 122.599958 -203.360782)
		(end 122.444256 -203.435458)
		(width 0.14732)
		(layer "In6.Cu")
		(net "UPI_CPU0_CPU1_P0P1_DP<16>")
	)
	(segment
		(start 122.669554 -202.792838)
		(end 122.74423 -202.948286)
		(width 0.14732)
		(layer "In6.Cu")
		(net "UPI_CPU0_CPU1_P0P1_DP<16>")
	)
	(segment
		(start 351.966784 -212.756496)
		(end 351.86747 -212.657182)
		(width 0.0889)
		(layer "In6.Cu")
		(net "UPI_CPU0_CPU1_P0P1_DP<16>")
	)
	(segment
		(start 302.48479 -174.921926)
		(end 273.116294 -175.635666)
		(width 0.14732)
		(layer "In6.Cu")
		(net "UPI_CPU0_CPU1_P0P1_DP<16>")
	)
	(segment
		(start 200.182226 -175.33366)
		(end 157.558486 -176.040796)
		(width 0.14732)
		(layer "In6.Cu")
		(net "UPI_CPU0_CPU1_P0P1_DP<16>")
	)
	(segment
		(start 120.193816 -212.296248)
		(end 120.29313 -212.395562)
		(width 0.0889)
		(layer "In6.Cu")
		(net "UPI_CPU0_CPU1_P0P1_DP<16>")
	)
	(segment
		(start 351.86747 -212.657182)
		(end 351.86747 -212.390482)
		(width 0.0889)
		(layer "In6.Cu")
		(net "UPI_CPU0_CPU1_P0P1_DP<16>")
	)
	(segment
		(start 351.966784 -213.488524)
		(end 351.86747 -213.38921)
		(width 0.0889)
		(layer "In6.Cu")
		(net "UPI_CPU0_CPU1_P0P1_DP<16>")
	)
	(segment
		(start 120.29313 -213.412578)
		(end 120.193816 -213.511892)
		(width 0.0889)
		(layer "In6.Cu")
		(net "UPI_CPU0_CPU1_P0P1_DP<16>")
	)
	(segment
		(start 150.644098 -177.810414)
		(end 140.535406 -182.985918)
		(width 0.14732)
		(layer "In6.Cu")
		(net "UPI_CPU0_CPU1_P0P1_DP<16>")
	)
	(segment
		(start 120.23598 -211.78139)
		(end 120.23598 -211.803488)
		(width 0.0889)
		(layer "In6.Cu")
		(net "UPI_CPU0_CPU1_P0P1_DP<16>")
	)
	(segment
		(start 140.535406 -182.985918)
		(end 136.241282 -188.750194)
		(width 0.14732)
		(layer "In6.Cu")
		(net "UPI_CPU0_CPU1_P0P1_DP<16>")
	)
	(segment
		(start 341.051388 -190.496952)
		(end 340.846664 -190.500254)
		(width 0.14732)
		(layer "In6.Cu")
		(net "UPI_CPU0_CPU1_P0P1_DP<16>")
	)
	(segment
		(start 119.941594 -214.893652)
		(end 120.098058 -214.622634)
		(width 0.0889)
		(layer "In6.Cu")
		(net "UPI_CPU0_CPU1_P0P1_DP<16>")
	)
	(segment
		(start 351.92462 -211.53755)
		(end 351.92462 -210.290156)
		(width 0.14732)
		(layer "In6.Cu")
		(net "UPI_CPU0_CPU1_P0P1_DP<16>")
	)
	(segment
		(start 157.558486 -176.040796)
		(end 154.101292 -176.925732)
		(width 0.14732)
		(layer "In6.Cu")
		(net "UPI_CPU0_CPU1_P0P1_DP<16>")
	)
	(segment
		(start 351.924874 -211.684108)
		(end 351.924874 -211.66201)
		(width 0.0889)
		(layer "In6.Cu")
		(net "UPI_CPU0_CPU1_P0P1_DP<16>")
	)
	(segment
		(start 120.679972 -208.844388)
		(end 120.5357 -209.257138)
		(width 0.14732)
		(layer "In6.Cu")
		(net "UPI_CPU0_CPU1_P0P1_DP<16>")
	)
	(segment
		(start 122.813826 -202.380596)
		(end 122.669554 -202.792838)
		(width 0.14732)
		(layer "In6.Cu")
		(net "UPI_CPU0_CPU1_P0P1_DP<16>")
	)
	(segment
		(start 122.74423 -202.948286)
		(end 122.599958 -203.360782)
		(width 0.14732)
		(layer "In6.Cu")
		(net "UPI_CPU0_CPU1_P0P1_DP<16>")
	)
	(segment
		(start 351.966784 -212.291168)
		(end 351.966784 -211.726018)
		(width 0.0889)
		(layer "In6.Cu")
		(net "UPI_CPU0_CPU1_P0P1_DP<16>")
	)
	(segment
		(start 340.846664 -190.500254)
		(end 340.581742 -190.243968)
		(width 0.14732)
		(layer "In6.Cu")
		(net "UPI_CPU0_CPU1_P0P1_DP<16>")
	)
	(segment
		(start 120.29313 -213.145878)
		(end 120.29313 -213.412578)
		(width 0.0889)
		(layer "In6.Cu")
		(net "UPI_CPU0_CPU1_P0P1_DP<16>")
	)
	(segment
		(start 351.86747 -212.390482)
		(end 351.966784 -212.291168)
		(width 0.0889)
		(layer "In6.Cu")
		(net "UPI_CPU0_CPU1_P0P1_DP<16>")
	)
	(segment
		(start 341.789004 -191.210692)
		(end 341.58428 -191.213994)
		(width 0.14732)
		(layer "In6.Cu")
		(net "UPI_CPU0_CPU1_P0P1_DP<16>")
	)
	(segment
		(start 120.193816 -212.761576)
		(end 120.193816 -213.046564)
		(width 0.0889)
		(layer "In6.Cu")
		(net "UPI_CPU0_CPU1_P0P1_DP<16>")
	)
	(segment
		(start 122.969528 -202.30592)
		(end 122.813826 -202.380596)
		(width 0.14732)
		(layer "In6.Cu")
		(net "UPI_CPU0_CPU1_P0P1_DP<16>")
	)
	(segment
		(start 154.100784 -176.925732)
		(end 150.644098 -177.810414)
		(width 0.14732)
		(layer "In6.Cu")
		(net "UPI_CPU0_CPU1_P0P1_DP<16>")
	)
	(segment
		(start 120.905016 -208.202276)
		(end 120.749568 -208.276952)
		(width 0.14732)
		(layer "In6.Cu")
		(net "UPI_CPU0_CPU1_P0P1_DP<16>")
	)
	(segment
		(start 351.750884 -214.033608)
		(end 351.835466 -214.05977)
		(width 0.0889)
		(layer "In6.Cu")
		(net "UPI_CPU0_CPU1_P0P1_DP<16>")
	)
	(segment
		(start 123.039124 -201.737976)
		(end 123.1138 -201.893424)
		(width 0.14732)
		(layer "In6.Cu")
		(net "UPI_CPU0_CPU1_P0P1_DP<16>")
	)
	(segment
		(start 340.581742 -190.243968)
		(end 340.57844 -190.039244)
		(width 0.14732)
		(layer "In6.Cu")
		(net "UPI_CPU0_CPU1_P0P1_DP<16>")
	)
	(segment
		(start 120.29313 -212.395562)
		(end 120.29313 -212.662262)
		(width 0.0889)
		(layer "In6.Cu")
		(net "UPI_CPU0_CPU1_P0P1_DP<16>")
	)
	(segment
		(start 351.966784 -213.8934)
		(end 351.966784 -213.488524)
		(width 0.0889)
		(layer "In6.Cu")
		(net "UPI_CPU0_CPU1_P0P1_DP<16>")
	)
	(segment
		(start 351.966784 -213.023196)
		(end 351.966784 -212.756496)
		(width 0.0889)
		(layer "In6.Cu")
		(net "UPI_CPU0_CPU1_P0P1_DP<16>")
	)
	(segment
		(start 341.319358 -190.957708)
		(end 341.316056 -190.752984)
		(width 0.14732)
		(layer "In6.Cu")
		(net "UPI_CPU0_CPU1_P0P1_DP<16>")
	)
	(segment
		(start 122.444256 -203.435458)
		(end 122.44451 -203.435712)
		(width 0.14732)
		(layer "In6.Cu")
		(net "UPI_CPU0_CPU1_P0P1_DP<16>")
	)
	(segment
		(start 120.749568 -208.276952)
		(end 120.605296 -208.689194)
		(width 0.14732)
		(layer "In6.Cu")
		(net "UPI_CPU0_CPU1_P0P1_DP<16>")
	)
	(segment
		(start 120.605296 -208.689194)
		(end 120.679972 -208.844388)
		(width 0.14732)
		(layer "In6.Cu")
		(net "UPI_CPU0_CPU1_P0P1_DP<16>")
	)
	(segment
		(start 121.049542 -207.789526)
		(end 120.905016 -208.202276)
		(width 0.14732)
		(layer "In6.Cu")
		(net "UPI_CPU0_CPU1_P0P1_DP<16>")
	)
	(segment
		(start 120.29313 -212.662262)
		(end 120.193816 -212.761576)
		(width 0.0889)
		(layer "In6.Cu")
		(net "UPI_CPU0_CPU1_P0P1_DP<16>")
	)
	(segment
		(start 340.57844 -190.039244)
		(end 340.313772 -189.783212)
		(width 0.14732)
		(layer "In6.Cu")
		(net "UPI_CPU0_CPU1_P0P1_DP<16>")
	)
	(segment
		(start 120.235726 -209.744056)
		(end 120.235726 -211.473288)
		(width 0.14732)
		(layer "In6.Cu")
		(net "UPI_CPU0_CPU1_P0P1_DP<16>")
	)
	(segment
		(start 340.313772 -189.783212)
		(end 340.109048 -189.786514)
		(width 0.14732)
		(layer "In6.Cu")
		(net "UPI_CPU0_CPU1_P0P1_DP<16>")
	)
	(segment
		(start 119.723408 -214.461852)
		(end 119.723408 -214.622634)
		(width 0.0889)
		(layer "In6.Cu")
		(net "UPI_CPU0_CPU1_P0P1_DP<16>")
	)
	(segment
		(start 122.44451 -203.435712)
		(end 120.974612 -207.634332)
		(width 0.14732)
		(layer "In6.Cu")
		(net "UPI_CPU0_CPU1_P0P1_DP<16>")
	)
	(segment
		(start 120.193816 -211.845652)
		(end 120.193816 -212.296248)
		(width 0.0889)
		(layer "In6.Cu")
		(net "UPI_CPU0_CPU1_P0P1_DP<16>")
	)
	(segment
		(start 130.071622 -192.85077)
		(end 123.183142 -201.325734)
		(width 0.14732)
		(layer "In6.Cu")
		(net "UPI_CPU0_CPU1_P0P1_DP<16>")
	)
	(segment
		(start 318.162686 -176.509172)
		(end 313.196478 -175.121062)
		(width 0.14732)
		(layer "In6.Cu")
		(net "UPI_CPU0_CPU1_P0P1_DP<16>")
	)
	(segment
		(start 351.592134 -213.732618)
		(end 351.750884 -214.033608)
		(width 0.0889)
		(layer "In6.Cu")
		(net "UPI_CPU0_CPU1_P0P1_DP<16>")
	)
	(segment
		(start 351.92462 -210.290156)
		(end 350.90989 -200.69175)
		(width 0.14732)
		(layer "In6.Cu")
		(net "UPI_CPU0_CPU1_P0P1_DP<16>")
	)
	(segment
		(start 120.235726 -211.473288)
		(end 120.23598 -211.473542)
		(width 0.14732)
		(layer "In6.Cu")
		(net "UPI_CPU0_CPU1_P0P1_DP<16>")
	)
	(segment
		(start 351.924874 -211.537296)
		(end 351.92462 -211.53755)
		(width 0.14732)
		(layer "In6.Cu")
		(net "UPI_CPU0_CPU1_P0P1_DP<16>")
	)
	(segment
		(start 120.5357 -209.257138)
		(end 120.379998 -209.331814)
		(width 0.14732)
		(layer "In6.Cu")
		(net "UPI_CPU0_CPU1_P0P1_DP<16>")
	)
	(segment
		(start 351.86747 -213.38921)
		(end 351.86747 -213.12251)
		(width 0.0889)
		(layer "In6.Cu")
		(net "UPI_CPU0_CPU1_P0P1_DP<16>")
	)
	(segment
		(start 337.779106 -187.330588)
		(end 335.02473 -185.324496)
		(width 0.14732)
		(layer "In6.Cu")
		(net "UPI_CPU0_CPU1_P0P1_DP<16>")
	)
	(segment
		(start 339.47608 -188.972698)
		(end 339.271356 -188.976)
		(width 0.14732)
		(layer "In6.Cu")
		(net "UPI_CPU0_CPU1_P0P1_DP<16>")
	)
	(segment
		(start 119.863362 -214.91448)
		(end 119.941594 -214.893652)
		(width 0.0889)
		(layer "In6.Cu")
		(net "UPI_CPU0_CPU1_P0P1_DP<16>")
	)
	(segment
		(start 123.1138 -201.893424)
		(end 122.969528 -202.30592)
		(width 0.14732)
		(layer "In6.Cu")
		(net "UPI_CPU0_CPU1_P0P1_DP<16>")
	)
	(segment
		(start 238.611918 -175.800512)
		(end 210.814666 -175.800512)
		(width 0.14732)
		(layer "In6.Cu")
		(net "UPI_CPU0_CPU1_P0P1_DP<16>")
	)
	(segment
		(start 154.101292 -176.925732)
		(end 154.100784 -176.925732)
		(width 0.14732)
		(layer "In6.Cu")
		(net "UPI_CPU0_CPU1_P0P1_DP<16>")
	)
	(segment
		(start 313.196478 -175.121062)
		(end 302.48479 -174.921926)
		(width 0.14732)
		(layer "In6.Cu")
		(net "UPI_CPU0_CPU1_P0P1_DP<16>")
	)
	(segment
		(start 348.477586 -197.682866)
		(end 341.789004 -191.210692)
		(width 0.14732)
		(layer "In6.Cu")
		(net "UPI_CPU0_CPU1_P0P1_DP<16>")
	)
	(segment
		(start 339.006434 -188.719714)
		(end 339.002878 -188.51499)
		(width 0.14732)
		(layer "In6.Cu")
		(net "UPI_CPU0_CPU1_P0P1_DP<16>")
	)
	(segment
		(start 120.23598 -211.473542)
		(end 120.23598 -211.78139)
		(width 0.14732)
		(layer "In6.Cu")
		(net "UPI_CPU0_CPU1_P0P1_DP<16>")
	)
	(segment
		(start 120.23598 -211.803488)
		(end 120.193816 -211.845652)
		(width 0.0889)
		(layer "In6.Cu")
		(net "UPI_CPU0_CPU1_P0P1_DP<16>")
	)
	(segment
		(start 335.02473 -185.324496)
		(end 318.162686 -176.509172)
		(width 0.14732)
		(layer "In6.Cu")
		(net "UPI_CPU0_CPU1_P0P1_DP<16>")
	)
	(segment
		(start 210.814666 -175.800512)
		(end 200.182226 -175.33366)
		(width 0.14732)
		(layer "In6.Cu")
		(net "UPI_CPU0_CPU1_P0P1_DP<16>")
	)
	(segment
		(start 350.90989 -200.69175)
		(end 348.477586 -197.682866)
		(width 0.14732)
		(layer "In6.Cu")
		(net "UPI_CPU0_CPU1_P0P1_DP<16>")
	)
	(segment
		(start 341.58428 -191.213994)
		(end 341.319358 -190.957708)
		(width 0.14732)
		(layer "In6.Cu")
		(net "UPI_CPU0_CPU1_P0P1_DP<16>")
	)
	(segment
		(start 120.193816 -213.046564)
		(end 120.29313 -213.145878)
		(width 0.0889)
		(layer "In6.Cu")
		(net "UPI_CPU0_CPU1_P0P1_DP<16>")
	)
	(segment
		(start 351.924874 -211.66201)
		(end 351.924874 -211.537296)
		(width 0.14732)
		(layer "In6.Cu")
		(net "UPI_CPU0_CPU1_P0P1_DP<16>")
	)
	(segment
		(start 340.109048 -189.786514)
		(end 339.844126 -189.530228)
		(width 0.14732)
		(layer "In6.Cu")
		(net "UPI_CPU0_CPU1_P0P1_DP<16>")
	)
	(segment
		(start 339.002878 -188.51499)
		(end 337.779106 -187.330588)
		(width 0.14732)
		(layer "In6.Cu")
		(net "UPI_CPU0_CPU1_P0P1_DP<16>")
	)
	(segment
		(start 123.183396 -201.325734)
		(end 123.039124 -201.737976)
		(width 0.14732)
		(layer "In6.Cu")
		(net "UPI_CPU0_CPU1_P0P1_DP<16>")
	)
	(segment
		(start 339.844126 -189.530228)
		(end 339.840824 -189.325504)
		(width 0.14732)
		(layer "In6.Cu")
		(net "UPI_CPU0_CPU1_P0P1_DP<16>")
	)
	(arc
		(start 351.835466 -214.05977)
		(mid 351.912139 -213.985276)
		(end 351.966784 -213.8934)
		(width 0.0889)
		(layer "In6.Cu")
		(net "UPI_CPU0_CPU1_P0P1_DP<16>")
	)
	(arc
		(start 119.907812 -214.261954)
		(mid 119.798416 -214.346051)
		(end 119.723408 -214.461852)
		(width 0.0889)
		(layer "In6.Cu")
		(net "UPI_CPU0_CPU1_P0P1_DP<16>")
	)
	(arc
		(start 120.193816 -213.929468)
		(mid 120.186538 -213.949159)
		(end 120.178576 -213.968584)
		(width 0.0889)
		(layer "In6.Cu")
		(net "UPI_CPU0_CPU1_P0P1_DP<16>")
	)
	(arc
		(start 120.178576 -213.968584)
		(mid 120.06837 -214.138501)
		(end 119.907812 -214.261954)
		(width 0.0889)
		(layer "In6.Cu")
		(net "UPI_CPU0_CPU1_P0P1_DP<16>")
	)
	(arc
		(start 119.723408 -214.622634)
		(mid 119.760268 -214.784431)
		(end 119.863362 -214.91448)
		(width 0.0889)
		(layer "In6.Cu")
		(net "UPI_CPU0_CPU1_P0P1_DP<16>")
	)
	(segment
		(start 351.12198 -215.158574)
		(end 351.12198 -214.622888)
		(width 0.13208)
		(layer "F.Cu")
		(net "UPI_CPU0_CPU1_P0P1_DP<15>")
	)
	(segment
		(start 351.12198 -214.622888)
		(end 351.121726 -214.622634)
		(width 0.13208)
		(layer "F.Cu")
		(net "UPI_CPU0_CPU1_P0P1_DP<15>")
	)
	(segment
		(start 120.568466 -214.344758)
		(end 120.568466 -213.732618)
		(width 0.13208)
		(layer "F.Cu")
		(net "UPI_CPU0_CPU1_P0P1_DP<15>")
	)
	(segment
		(start 120.727216 -214.033608)
		(end 120.568466 -213.732618)
		(width 0.0889)
		(layer "In6.Cu")
		(net "UPI_CPU0_CPU1_P0P1_DP<15>")
	)
	(segment
		(start 350.25584 -200.83907)
		(end 348.562676 -198.743824)
		(width 0.14732)
		(layer "In6.Cu")
		(net "UPI_CPU0_CPU1_P0P1_DP<15>")
	)
	(segment
		(start 351.259394 -210.330034)
		(end 350.25584 -200.83907)
		(width 0.14732)
		(layer "In6.Cu")
		(net "UPI_CPU0_CPU1_P0P1_DP<15>")
	)
	(segment
		(start 351.259648 -211.66201)
		(end 351.259648 -210.874864)
		(width 0.14732)
		(layer "In6.Cu")
		(net "UPI_CPU0_CPU1_P0P1_DP<15>")
	)
	(segment
		(start 302.486568 -175.504602)
		(end 302.480726 -175.504856)
		(width 0.14732)
		(layer "In6.Cu")
		(net "UPI_CPU0_CPU1_P0P1_DP<15>")
	)
	(segment
		(start 348.562676 -198.743824)
		(end 336.586068 -187.154312)
		(width 0.14732)
		(layer "In6.Cu")
		(net "UPI_CPU0_CPU1_P0P1_DP<15>")
	)
	(segment
		(start 351.217484 -211.726272)
		(end 351.259648 -211.684108)
		(width 0.0889)
		(layer "In6.Cu")
		(net "UPI_CPU0_CPU1_P0P1_DP<15>")
	)
	(segment
		(start 120.943116 -211.825078)
		(end 120.943116 -213.8934)
		(width 0.0889)
		(layer "In6.Cu")
		(net "UPI_CPU0_CPU1_P0P1_DP<15>")
	)
	(segment
		(start 351.316798 -212.652102)
		(end 351.316798 -212.385402)
		(width 0.0889)
		(layer "In6.Cu")
		(net "UPI_CPU0_CPU1_P0P1_DP<15>")
	)
	(segment
		(start 336.586068 -187.154312)
		(end 334.846168 -185.887106)
		(width 0.14732)
		(layer "In6.Cu")
		(net "UPI_CPU0_CPU1_P0P1_DP<15>")
	)
	(segment
		(start 351.259648 -210.874864)
		(end 351.259394 -210.875118)
		(width 0.14732)
		(layer "In6.Cu")
		(net "UPI_CPU0_CPU1_P0P1_DP<15>")
	)
	(segment
		(start 351.259648 -211.684108)
		(end 351.259648 -211.66201)
		(width 0.0889)
		(layer "In6.Cu")
		(net "UPI_CPU0_CPU1_P0P1_DP<15>")
	)
	(segment
		(start 302.480726 -175.504856)
		(end 273.124676 -176.218088)
		(width 0.14732)
		(layer "In6.Cu")
		(net "UPI_CPU0_CPU1_P0P1_DP<15>")
	)
	(segment
		(start 302.49241 -175.504856)
		(end 302.492156 -175.504602)
		(width 0.14732)
		(layer "In6.Cu")
		(net "UPI_CPU0_CPU1_P0P1_DP<15>")
	)
	(segment
		(start 334.846168 -185.887106)
		(end 317.835788 -176.99482)
		(width 0.14732)
		(layer "In6.Cu")
		(net "UPI_CPU0_CPU1_P0P1_DP<15>")
	)
	(segment
		(start 150.792688 -178.388264)
		(end 140.893038 -183.456326)
		(width 0.14732)
		(layer "In6.Cu")
		(net "UPI_CPU0_CPU1_P0P1_DP<15>")
	)
	(segment
		(start 120.901206 -211.783168)
		(end 120.943116 -211.825078)
		(width 0.0889)
		(layer "In6.Cu")
		(net "UPI_CPU0_CPU1_P0P1_DP<15>")
	)
	(segment
		(start 351.217484 -213.018116)
		(end 351.217484 -212.751416)
		(width 0.0889)
		(layer "In6.Cu")
		(net "UPI_CPU0_CPU1_P0P1_DP<15>")
	)
	(segment
		(start 120.811798 -214.05977)
		(end 120.727216 -214.033608)
		(width 0.0889)
		(layer "In6.Cu")
		(net "UPI_CPU0_CPU1_P0P1_DP<15>")
	)
	(segment
		(start 120.900952 -209.90179)
		(end 120.900952 -211.399628)
		(width 0.14732)
		(layer "In6.Cu")
		(net "UPI_CPU0_CPU1_P0P1_DP<15>")
	)
	(segment
		(start 130.289554 -193.467736)
		(end 123.90501 -201.32294)
		(width 0.14732)
		(layer "In6.Cu")
		(net "UPI_CPU0_CPU1_P0P1_DP<15>")
	)
	(segment
		(start 302.492156 -175.504602)
		(end 302.486568 -175.504602)
		(width 0.14732)
		(layer "In6.Cu")
		(net "UPI_CPU0_CPU1_P0P1_DP<15>")
	)
	(segment
		(start 351.316798 -212.385402)
		(end 351.217484 -212.286088)
		(width 0.0889)
		(layer "In6.Cu")
		(net "UPI_CPU0_CPU1_P0P1_DP<15>")
	)
	(segment
		(start 120.901206 -211.76107)
		(end 120.901206 -211.783168)
		(width 0.0889)
		(layer "In6.Cu")
		(net "UPI_CPU0_CPU1_P0P1_DP<15>")
	)
	(segment
		(start 351.121726 -214.622634)
		(end 350.965262 -214.893652)
		(width 0.0889)
		(layer "In6.Cu")
		(net "UPI_CPU0_CPU1_P0P1_DP<15>")
	)
	(segment
		(start 351.217484 -213.483444)
		(end 351.316798 -213.38413)
		(width 0.0889)
		(layer "In6.Cu")
		(net "UPI_CPU0_CPU1_P0P1_DP<15>")
	)
	(segment
		(start 157.691074 -176.62271)
		(end 150.792688 -178.388264)
		(width 0.14732)
		(layer "In6.Cu")
		(net "UPI_CPU0_CPU1_P0P1_DP<15>")
	)
	(segment
		(start 350.965262 -214.893652)
		(end 350.88703 -214.91448)
		(width 0.0889)
		(layer "In6.Cu")
		(net "UPI_CPU0_CPU1_P0P1_DP<15>")
	)
	(segment
		(start 313.218322 -175.703992)
		(end 302.49241 -175.504856)
		(width 0.14732)
		(layer "In6.Cu")
		(net "UPI_CPU0_CPU1_P0P1_DP<15>")
	)
	(segment
		(start 351.217484 -212.286088)
		(end 351.217484 -211.726272)
		(width 0.0889)
		(layer "In6.Cu")
		(net "UPI_CPU0_CPU1_P0P1_DP<15>")
	)
	(segment
		(start 120.901206 -211.399882)
		(end 120.901206 -211.76107)
		(width 0.14732)
		(layer "In6.Cu")
		(net "UPI_CPU0_CPU1_P0P1_DP<15>")
	)
	(segment
		(start 123.90501 -201.32294)
		(end 120.900952 -209.90179)
		(width 0.14732)
		(layer "In6.Cu")
		(net "UPI_CPU0_CPU1_P0P1_DP<15>")
	)
	(segment
		(start 210.943952 -176.382934)
		(end 200.302876 -175.915574)
		(width 0.14732)
		(layer "In6.Cu")
		(net "UPI_CPU0_CPU1_P0P1_DP<15>")
	)
	(segment
		(start 351.217484 -213.929468)
		(end 351.217484 -213.483444)
		(width 0.0889)
		(layer "In6.Cu")
		(net "UPI_CPU0_CPU1_P0P1_DP<15>")
	)
	(segment
		(start 120.900952 -211.399628)
		(end 120.901206 -211.399882)
		(width 0.14732)
		(layer "In6.Cu")
		(net "UPI_CPU0_CPU1_P0P1_DP<15>")
	)
	(segment
		(start 273.124676 -176.218088)
		(end 238.613442 -176.382934)
		(width 0.14732)
		(layer "In6.Cu")
		(net "UPI_CPU0_CPU1_P0P1_DP<15>")
	)
	(segment
		(start 200.302876 -175.915574)
		(end 157.691074 -176.62271)
		(width 0.14732)
		(layer "In6.Cu")
		(net "UPI_CPU0_CPU1_P0P1_DP<15>")
	)
	(segment
		(start 351.217484 -212.751416)
		(end 351.316798 -212.652102)
		(width 0.0889)
		(layer "In6.Cu")
		(net "UPI_CPU0_CPU1_P0P1_DP<15>")
	)
	(segment
		(start 140.893038 -183.456326)
		(end 136.520428 -189.325504)
		(width 0.14732)
		(layer "In6.Cu")
		(net "UPI_CPU0_CPU1_P0P1_DP<15>")
	)
	(segment
		(start 350.747076 -214.622634)
		(end 350.747076 -214.461852)
		(width 0.0889)
		(layer "In6.Cu")
		(net "UPI_CPU0_CPU1_P0P1_DP<15>")
	)
	(segment
		(start 136.520428 -189.325504)
		(end 130.289554 -193.467736)
		(width 0.14732)
		(layer "In6.Cu")
		(net "UPI_CPU0_CPU1_P0P1_DP<15>")
	)
	(segment
		(start 351.259394 -210.875118)
		(end 351.259394 -210.330034)
		(width 0.14732)
		(layer "In6.Cu")
		(net "UPI_CPU0_CPU1_P0P1_DP<15>")
	)
	(segment
		(start 351.316798 -213.11743)
		(end 351.217484 -213.018116)
		(width 0.0889)
		(layer "In6.Cu")
		(net "UPI_CPU0_CPU1_P0P1_DP<15>")
	)
	(segment
		(start 238.613442 -176.382934)
		(end 210.943952 -176.382934)
		(width 0.14732)
		(layer "In6.Cu")
		(net "UPI_CPU0_CPU1_P0P1_DP<15>")
	)
	(segment
		(start 317.835788 -176.99482)
		(end 313.218322 -175.703992)
		(width 0.14732)
		(layer "In6.Cu")
		(net "UPI_CPU0_CPU1_P0P1_DP<15>")
	)
	(segment
		(start 351.316798 -213.38413)
		(end 351.316798 -213.11743)
		(width 0.0889)
		(layer "In6.Cu")
		(net "UPI_CPU0_CPU1_P0P1_DP<15>")
	)
	(arc
		(start 120.943116 -213.8934)
		(mid 120.888446 -213.985256)
		(end 120.811798 -214.05977)
		(width 0.0889)
		(layer "In6.Cu")
		(net "UPI_CPU0_CPU1_P0P1_DP<15>")
	)
	(arc
		(start 350.93148 -214.261954)
		(mid 351.092061 -214.138523)
		(end 351.202244 -213.968584)
		(width 0.0889)
		(layer "In6.Cu")
		(net "UPI_CPU0_CPU1_P0P1_DP<15>")
	)
	(arc
		(start 351.202244 -213.968584)
		(mid 351.210209 -213.94916)
		(end 351.217484 -213.929468)
		(width 0.0889)
		(layer "In6.Cu")
		(net "UPI_CPU0_CPU1_P0P1_DP<15>")
	)
	(arc
		(start 350.747076 -214.461852)
		(mid 350.822147 -214.34611)
		(end 350.93148 -214.261954)
		(width 0.0889)
		(layer "In6.Cu")
		(net "UPI_CPU0_CPU1_P0P1_DP<15>")
	)
	(arc
		(start 350.88703 -214.91448)
		(mid 350.783885 -214.784455)
		(end 350.747076 -214.622634)
		(width 0.0889)
		(layer "In6.Cu")
		(net "UPI_CPU0_CPU1_P0P1_DP<15>")
	)
	(segment
		(start 121.508266 -215.436958)
		(end 121.508012 -215.436704)
		(width 0.13208)
		(layer "F.Cu")
		(net "UPI_CPU0_CPU1_P0P1_DP<14>")
	)
	(segment
		(start 350.18218 -214.622888)
		(end 350.181926 -214.622634)
		(width 0.13208)
		(layer "F.Cu")
		(net "UPI_CPU0_CPU1_P0P1_DP<14>")
	)
	(segment
		(start 121.508266 -215.972644)
		(end 121.508266 -215.436958)
		(width 0.13208)
		(layer "F.Cu")
		(net "UPI_CPU0_CPU1_P0P1_DP<14>")
	)
	(segment
		(start 350.18218 -215.158574)
		(end 350.18218 -214.622888)
		(width 0.13208)
		(layer "F.Cu")
		(net "UPI_CPU0_CPU1_P0P1_DP<14>")
	)
	(segment
		(start 335.382616 -188.23813)
		(end 335.154016 -187.493656)
		(width 0.14732)
		(layer "In6.Cu")
		(net "UPI_CPU0_CPU1_P0P1_DP<14>")
	)
	(segment
		(start 350.31934 -210.375246)
		(end 349.329248 -201.014076)
		(width 0.14732)
		(layer "In6.Cu")
		(net "UPI_CPU0_CPU1_P0P1_DP<14>")
	)
	(segment
		(start 121.882662 -211.726018)
		(end 121.882662 -213.894162)
		(width 0.0889)
		(layer "In6.Cu")
		(net "UPI_CPU0_CPU1_P0P1_DP<14>")
	)
	(segment
		(start 350.277684 -213.929468)
		(end 350.277684 -211.726018)
		(width 0.0889)
		(layer "In6.Cu")
		(net "UPI_CPU0_CPU1_P0P1_DP<14>")
	)
	(segment
		(start 335.963514 -189.441328)
		(end 335.382616 -188.23813)
		(width 0.14732)
		(layer "In6.Cu")
		(net "UPI_CPU0_CPU1_P0P1_DP<14>")
	)
	(segment
		(start 141.442694 -184.142126)
		(end 137.106914 -189.96279)
		(width 0.14732)
		(layer "In6.Cu")
		(net "UPI_CPU0_CPU1_P0P1_DP<14>")
	)
	(segment
		(start 347.946472 -199.30237)
		(end 336.631026 -190.41364)
		(width 0.14732)
		(layer "In6.Cu")
		(net "UPI_CPU0_CPU1_P0P1_DP<14>")
	)
	(segment
		(start 121.664476 -215.165686)
		(end 121.508012 -215.436704)
		(width 0.0889)
		(layer "In6.Cu")
		(net "UPI_CPU0_CPU1_P0P1_DP<14>")
	)
	(segment
		(start 313.136534 -176.552098)
		(end 302.494696 -176.35474)
		(width 0.14732)
		(layer "In6.Cu")
		(net "UPI_CPU0_CPU1_P0P1_DP<14>")
	)
	(segment
		(start 331.173328 -184.928256)
		(end 317.465964 -177.762408)
		(width 0.14732)
		(layer "In6.Cu")
		(net "UPI_CPU0_CPU1_P0P1_DP<14>")
	)
	(segment
		(start 350.31934 -210.875118)
		(end 350.31934 -210.375246)
		(width 0.14732)
		(layer "In6.Cu")
		(net "UPI_CPU0_CPU1_P0P1_DP<14>")
	)
	(segment
		(start 157.875732 -177.465482)
		(end 151.094694 -179.20081)
		(width 0.14732)
		(layer "In6.Cu")
		(net "UPI_CPU0_CPU1_P0P1_DP<14>")
	)
	(segment
		(start 302.483012 -176.35474)
		(end 273.137122 -177.067464)
		(width 0.14732)
		(layer "In6.Cu")
		(net "UPI_CPU0_CPU1_P0P1_DP<14>")
	)
	(segment
		(start 273.137122 -177.067464)
		(end 238.615728 -177.23231)
		(width 0.14732)
		(layer "In6.Cu")
		(net "UPI_CPU0_CPU1_P0P1_DP<14>")
	)
	(segment
		(start 350.277684 -211.726018)
		(end 350.319594 -211.684108)
		(width 0.0889)
		(layer "In6.Cu")
		(net "UPI_CPU0_CPU1_P0P1_DP<14>")
	)
	(segment
		(start 331.173836 -184.928256)
		(end 331.173328 -184.928256)
		(width 0.14732)
		(layer "In6.Cu")
		(net "UPI_CPU0_CPU1_P0P1_DP<14>")
	)
	(segment
		(start 336.631026 -190.41364)
		(end 335.963514 -189.441328)
		(width 0.14732)
		(layer "In6.Cu")
		(net "UPI_CPU0_CPU1_P0P1_DP<14>")
	)
	(segment
		(start 302.488854 -176.354486)
		(end 302.483012 -176.35474)
		(width 0.14732)
		(layer "In6.Cu")
		(net "UPI_CPU0_CPU1_P0P1_DP<14>")
	)
	(segment
		(start 350.319594 -211.66201)
		(end 350.319594 -210.874864)
		(width 0.14732)
		(layer "In6.Cu")
		(net "UPI_CPU0_CPU1_P0P1_DP<14>")
	)
	(segment
		(start 121.840752 -211.684108)
		(end 121.882662 -211.726018)
		(width 0.0889)
		(layer "In6.Cu")
		(net "UPI_CPU0_CPU1_P0P1_DP<14>")
	)
	(segment
		(start 302.494696 -176.35474)
		(end 302.494442 -176.354486)
		(width 0.14732)
		(layer "In6.Cu")
		(net "UPI_CPU0_CPU1_P0P1_DP<14>")
	)
	(segment
		(start 335.154016 -187.493656)
		(end 334.442308 -186.636914)
		(width 0.14732)
		(layer "In6.Cu")
		(net "UPI_CPU0_CPU1_P0P1_DP<14>")
	)
	(segment
		(start 350.023176 -214.321644)
		(end 350.053402 -214.22487)
		(width 0.0889)
		(layer "In6.Cu")
		(net "UPI_CPU0_CPU1_P0P1_DP<14>")
	)
	(segment
		(start 302.494442 -176.354486)
		(end 302.488854 -176.354486)
		(width 0.14732)
		(layer "In6.Cu")
		(net "UPI_CPU0_CPU1_P0P1_DP<14>")
	)
	(segment
		(start 130.816604 -194.14363)
		(end 124.906024 -201.415396)
		(width 0.14732)
		(layer "In6.Cu")
		(net "UPI_CPU0_CPU1_P0P1_DP<14>")
	)
	(segment
		(start 350.319594 -211.684108)
		(end 350.319594 -211.66201)
		(width 0.0889)
		(layer "In6.Cu")
		(net "UPI_CPU0_CPU1_P0P1_DP<14>")
	)
	(segment
		(start 211.345526 -177.23231)
		(end 200.53173 -176.75733)
		(width 0.14732)
		(layer "In6.Cu")
		(net "UPI_CPU0_CPU1_P0P1_DP<14>")
	)
	(segment
		(start 151.094694 -179.20081)
		(end 141.442694 -184.142126)
		(width 0.14732)
		(layer "In6.Cu")
		(net "UPI_CPU0_CPU1_P0P1_DP<14>")
	)
	(segment
		(start 121.840752 -210.170522)
		(end 121.840752 -211.66201)
		(width 0.14732)
		(layer "In6.Cu")
		(net "UPI_CPU0_CPU1_P0P1_DP<14>")
	)
	(segment
		(start 350.319594 -210.874864)
		(end 350.31934 -210.875118)
		(width 0.14732)
		(layer "In6.Cu")
		(net "UPI_CPU0_CPU1_P0P1_DP<14>")
	)
	(segment
		(start 238.615728 -177.23231)
		(end 211.345526 -177.23231)
		(width 0.14732)
		(layer "In6.Cu")
		(net "UPI_CPU0_CPU1_P0P1_DP<14>")
	)
	(segment
		(start 137.106914 -189.96279)
		(end 130.816604 -194.14363)
		(width 0.14732)
		(layer "In6.Cu")
		(net "UPI_CPU0_CPU1_P0P1_DP<14>")
	)
	(segment
		(start 350.181926 -214.622634)
		(end 350.023176 -214.321644)
		(width 0.0889)
		(layer "In6.Cu")
		(net "UPI_CPU0_CPU1_P0P1_DP<14>")
	)
	(segment
		(start 349.329248 -201.014076)
		(end 347.946472 -199.30237)
		(width 0.14732)
		(layer "In6.Cu")
		(net "UPI_CPU0_CPU1_P0P1_DP<14>")
	)
	(segment
		(start 124.906024 -201.415396)
		(end 121.840752 -210.170522)
		(width 0.14732)
		(layer "In6.Cu")
		(net "UPI_CPU0_CPU1_P0P1_DP<14>")
	)
	(segment
		(start 334.442308 -186.636914)
		(end 331.173836 -184.928256)
		(width 0.14732)
		(layer "In6.Cu")
		(net "UPI_CPU0_CPU1_P0P1_DP<14>")
	)
	(segment
		(start 121.640346 -215.076532)
		(end 121.664476 -215.165686)
		(width 0.0889)
		(layer "In6.Cu")
		(net "UPI_CPU0_CPU1_P0P1_DP<14>")
	)
	(segment
		(start 317.465964 -177.762408)
		(end 313.136534 -176.552098)
		(width 0.14732)
		(layer "In6.Cu")
		(net "UPI_CPU0_CPU1_P0P1_DP<14>")
	)
	(segment
		(start 200.53173 -176.75733)
		(end 157.875732 -177.465482)
		(width 0.14732)
		(layer "In6.Cu")
		(net "UPI_CPU0_CPU1_P0P1_DP<14>")
	)
	(segment
		(start 121.412508 -214.425784)
		(end 121.412508 -214.636858)
		(width 0.0889)
		(layer "In6.Cu")
		(net "UPI_CPU0_CPU1_P0P1_DP<14>")
	)
	(segment
		(start 121.840752 -211.66201)
		(end 121.840752 -211.684108)
		(width 0.0889)
		(layer "In6.Cu")
		(net "UPI_CPU0_CPU1_P0P1_DP<14>")
	)
	(arc
		(start 121.698512 -214.093298)
		(mid 121.523964 -214.232402)
		(end 121.412508 -214.425784)
		(width 0.0889)
		(layer "In6.Cu")
		(net "UPI_CPU0_CPU1_P0P1_DP<14>")
	)
	(arc
		(start 121.882662 -213.894162)
		(mid 121.807624 -214.009482)
		(end 121.698512 -214.093298)
		(width 0.0889)
		(layer "In6.Cu")
		(net "UPI_CPU0_CPU1_P0P1_DP<14>")
	)
	(arc
		(start 121.623328 -215.063324)
		(mid 121.631774 -215.070009)
		(end 121.640346 -215.076532)
		(width 0.0889)
		(layer "In6.Cu")
		(net "UPI_CPU0_CPU1_P0P1_DP<14>")
	)
	(arc
		(start 350.262698 -213.96833)
		(mid 350.270533 -213.949031)
		(end 350.277684 -213.929468)
		(width 0.0889)
		(layer "In6.Cu")
		(net "UPI_CPU0_CPU1_P0P1_DP<14>")
	)
	(arc
		(start 121.412508 -214.636858)
		(mid 121.470853 -214.873363)
		(end 121.623328 -215.063324)
		(width 0.0889)
		(layer "In6.Cu")
		(net "UPI_CPU0_CPU1_P0P1_DP<14>")
	)
	(arc
		(start 350.053402 -214.22487)
		(mid 350.176148 -214.111365)
		(end 350.262698 -213.96833)
		(width 0.0889)
		(layer "In6.Cu")
		(net "UPI_CPU0_CPU1_P0P1_DP<14>")
	)
	(segment
		(start 349.24238 -215.158574)
		(end 349.24238 -214.622888)
		(width 0.13208)
		(layer "F.Cu")
		(net "UPI_CPU0_CPU1_P0P1_DP<13>")
	)
	(segment
		(start 122.448066 -214.344758)
		(end 122.448066 -213.732618)
		(width 0.13208)
		(layer "F.Cu")
		(net "UPI_CPU0_CPU1_P0P1_DP<13>")
	)
	(segment
		(start 349.24238 -214.622888)
		(end 349.242126 -214.622634)
		(width 0.13208)
		(layer "F.Cu")
		(net "UPI_CPU0_CPU1_P0P1_DP<13>")
	)
	(segment
		(start 137.765536 -190.531242)
		(end 131.360418 -194.788028)
		(width 0.14732)
		(layer "In6.Cu")
		(net "UPI_CPU0_CPU1_P0P1_DP<13>")
	)
	(segment
		(start 122.780806 -211.542122)
		(end 122.780806 -211.67471)
		(width 0.14732)
		(layer "In6.Cu")
		(net "UPI_CPU0_CPU1_P0P1_DP<13>")
	)
	(segment
		(start 349.337884 -213.483444)
		(end 349.437198 -213.38413)
		(width 0.0889)
		(layer "In6.Cu")
		(net "UPI_CPU0_CPU1_P0P1_DP<13>")
	)
	(segment
		(start 349.085662 -214.893652)
		(end 349.00743 -214.91448)
		(width 0.0889)
		(layer "In6.Cu")
		(net "UPI_CPU0_CPU1_P0P1_DP<13>")
	)
	(segment
		(start 348.406974 -201.224388)
		(end 347.328998 -199.895968)
		(width 0.14732)
		(layer "In6.Cu")
		(net "UPI_CPU0_CPU1_P0P1_DP<13>")
	)
	(segment
		(start 302.491394 -177.211736)
		(end 273.149568 -177.924206)
		(width 0.14732)
		(layer "In6.Cu")
		(net "UPI_CPU0_CPU1_P0P1_DP<13>")
	)
	(segment
		(start 347.328998 -199.895968)
		(end 332.062074 -187.887864)
		(width 0.14732)
		(layer "In6.Cu")
		(net "UPI_CPU0_CPU1_P0P1_DP<13>")
	)
	(segment
		(start 122.822716 -211.738718)
		(end 122.822716 -213.8934)
		(width 0.0889)
		(layer "In6.Cu")
		(net "UPI_CPU0_CPU1_P0P1_DP<13>")
	)
	(segment
		(start 349.437198 -213.38413)
		(end 349.437198 -213.11743)
		(width 0.0889)
		(layer "In6.Cu")
		(net "UPI_CPU0_CPU1_P0P1_DP<13>")
	)
	(segment
		(start 122.780552 -210.431888)
		(end 122.780552 -211.541868)
		(width 0.14732)
		(layer "In6.Cu")
		(net "UPI_CPU0_CPU1_P0P1_DP<13>")
	)
	(segment
		(start 313.111134 -177.40884)
		(end 302.491394 -177.211736)
		(width 0.14732)
		(layer "In6.Cu")
		(net "UPI_CPU0_CPU1_P0P1_DP<13>")
	)
	(segment
		(start 349.379794 -210.875118)
		(end 349.379794 -210.429602)
		(width 0.14732)
		(layer "In6.Cu")
		(net "UPI_CPU0_CPU1_P0P1_DP<13>")
	)
	(segment
		(start 349.337884 -211.726272)
		(end 349.380048 -211.684108)
		(width 0.0889)
		(layer "In6.Cu")
		(net "UPI_CPU0_CPU1_P0P1_DP<13>")
	)
	(segment
		(start 348.867476 -214.622634)
		(end 348.867476 -214.461852)
		(width 0.0889)
		(layer "In6.Cu")
		(net "UPI_CPU0_CPU1_P0P1_DP<13>")
	)
	(segment
		(start 349.337884 -212.286088)
		(end 349.337884 -211.726272)
		(width 0.0889)
		(layer "In6.Cu")
		(net "UPI_CPU0_CPU1_P0P1_DP<13>")
	)
	(segment
		(start 238.618014 -178.089052)
		(end 211.885276 -178.089052)
		(width 0.14732)
		(layer "In6.Cu")
		(net "UPI_CPU0_CPU1_P0P1_DP<13>")
	)
	(segment
		(start 131.360418 -194.788028)
		(end 125.909832 -201.493882)
		(width 0.14732)
		(layer "In6.Cu")
		(net "UPI_CPU0_CPU1_P0P1_DP<13>")
	)
	(segment
		(start 151.363426 -180.00599)
		(end 142.056358 -184.770776)
		(width 0.14732)
		(layer "In6.Cu")
		(net "UPI_CPU0_CPU1_P0P1_DP<13>")
	)
	(segment
		(start 349.379794 -210.429602)
		(end 348.406974 -201.224388)
		(width 0.14732)
		(layer "In6.Cu")
		(net "UPI_CPU0_CPU1_P0P1_DP<13>")
	)
	(segment
		(start 273.149568 -177.924206)
		(end 238.618014 -178.089052)
		(width 0.14732)
		(layer "In6.Cu")
		(net "UPI_CPU0_CPU1_P0P1_DP<13>")
	)
	(segment
		(start 125.909832 -201.493882)
		(end 122.780552 -210.431888)
		(width 0.14732)
		(layer "In6.Cu")
		(net "UPI_CPU0_CPU1_P0P1_DP<13>")
	)
	(segment
		(start 349.380048 -211.66201)
		(end 349.380048 -210.874864)
		(width 0.14732)
		(layer "In6.Cu")
		(net "UPI_CPU0_CPU1_P0P1_DP<13>")
	)
	(segment
		(start 349.437198 -212.652102)
		(end 349.437198 -212.385402)
		(width 0.0889)
		(layer "In6.Cu")
		(net "UPI_CPU0_CPU1_P0P1_DP<13>")
	)
	(segment
		(start 122.606816 -214.033608)
		(end 122.448066 -213.732618)
		(width 0.0889)
		(layer "In6.Cu")
		(net "UPI_CPU0_CPU1_P0P1_DP<13>")
	)
	(segment
		(start 332.062074 -187.887864)
		(end 326.009254 -183.709818)
		(width 0.14732)
		(layer "In6.Cu")
		(net "UPI_CPU0_CPU1_P0P1_DP<13>")
	)
	(segment
		(start 122.780806 -211.696808)
		(end 122.822716 -211.738718)
		(width 0.0889)
		(layer "In6.Cu")
		(net "UPI_CPU0_CPU1_P0P1_DP<13>")
	)
	(segment
		(start 211.885276 -178.089052)
		(end 200.864978 -177.604928)
		(width 0.14732)
		(layer "In6.Cu")
		(net "UPI_CPU0_CPU1_P0P1_DP<13>")
	)
	(segment
		(start 349.337884 -212.751416)
		(end 349.437198 -212.652102)
		(width 0.0889)
		(layer "In6.Cu")
		(net "UPI_CPU0_CPU1_P0P1_DP<13>")
	)
	(segment
		(start 142.056358 -184.770776)
		(end 137.765536 -190.531242)
		(width 0.14732)
		(layer "In6.Cu")
		(net "UPI_CPU0_CPU1_P0P1_DP<13>")
	)
	(segment
		(start 122.780552 -211.541868)
		(end 122.780806 -211.542122)
		(width 0.14732)
		(layer "In6.Cu")
		(net "UPI_CPU0_CPU1_P0P1_DP<13>")
	)
	(segment
		(start 349.337884 -213.018116)
		(end 349.337884 -212.751416)
		(width 0.0889)
		(layer "In6.Cu")
		(net "UPI_CPU0_CPU1_P0P1_DP<13>")
	)
	(segment
		(start 122.780806 -211.67471)
		(end 122.780806 -211.696808)
		(width 0.0889)
		(layer "In6.Cu")
		(net "UPI_CPU0_CPU1_P0P1_DP<13>")
	)
	(segment
		(start 349.380048 -211.684108)
		(end 349.380048 -211.66201)
		(width 0.0889)
		(layer "In6.Cu")
		(net "UPI_CPU0_CPU1_P0P1_DP<13>")
	)
	(segment
		(start 349.242126 -214.622634)
		(end 349.085662 -214.893652)
		(width 0.0889)
		(layer "In6.Cu")
		(net "UPI_CPU0_CPU1_P0P1_DP<13>")
	)
	(segment
		(start 349.380048 -210.874864)
		(end 349.379794 -210.875118)
		(width 0.14732)
		(layer "In6.Cu")
		(net "UPI_CPU0_CPU1_P0P1_DP<13>")
	)
	(segment
		(start 200.864978 -177.604928)
		(end 157.963616 -178.31689)
		(width 0.14732)
		(layer "In6.Cu")
		(net "UPI_CPU0_CPU1_P0P1_DP<13>")
	)
	(segment
		(start 122.691398 -214.05977)
		(end 122.606816 -214.033608)
		(width 0.0889)
		(layer "In6.Cu")
		(net "UPI_CPU0_CPU1_P0P1_DP<13>")
	)
	(segment
		(start 326.009254 -183.709818)
		(end 317.103252 -178.525932)
		(width 0.14732)
		(layer "In6.Cu")
		(net "UPI_CPU0_CPU1_P0P1_DP<13>")
	)
	(segment
		(start 317.103252 -178.525932)
		(end 313.111134 -177.40884)
		(width 0.14732)
		(layer "In6.Cu")
		(net "UPI_CPU0_CPU1_P0P1_DP<13>")
	)
	(segment
		(start 157.963616 -178.31689)
		(end 151.363426 -180.00599)
		(width 0.14732)
		(layer "In6.Cu")
		(net "UPI_CPU0_CPU1_P0P1_DP<13>")
	)
	(segment
		(start 349.437198 -213.11743)
		(end 349.337884 -213.018116)
		(width 0.0889)
		(layer "In6.Cu")
		(net "UPI_CPU0_CPU1_P0P1_DP<13>")
	)
	(segment
		(start 349.437198 -212.385402)
		(end 349.337884 -212.286088)
		(width 0.0889)
		(layer "In6.Cu")
		(net "UPI_CPU0_CPU1_P0P1_DP<13>")
	)
	(segment
		(start 349.337884 -213.929468)
		(end 349.337884 -213.483444)
		(width 0.0889)
		(layer "In6.Cu")
		(net "UPI_CPU0_CPU1_P0P1_DP<13>")
	)
	(arc
		(start 349.00743 -214.91448)
		(mid 348.904285 -214.784455)
		(end 348.867476 -214.622634)
		(width 0.0889)
		(layer "In6.Cu")
		(net "UPI_CPU0_CPU1_P0P1_DP<13>")
	)
	(arc
		(start 122.822716 -213.8934)
		(mid 122.768046 -213.985256)
		(end 122.691398 -214.05977)
		(width 0.0889)
		(layer "In6.Cu")
		(net "UPI_CPU0_CPU1_P0P1_DP<13>")
	)
	(arc
		(start 349.05188 -214.261954)
		(mid 349.212461 -214.138523)
		(end 349.322644 -213.968584)
		(width 0.0889)
		(layer "In6.Cu")
		(net "UPI_CPU0_CPU1_P0P1_DP<13>")
	)
	(arc
		(start 349.322644 -213.968584)
		(mid 349.330609 -213.94916)
		(end 349.337884 -213.929468)
		(width 0.0889)
		(layer "In6.Cu")
		(net "UPI_CPU0_CPU1_P0P1_DP<13>")
	)
	(arc
		(start 348.867476 -214.461852)
		(mid 348.942547 -214.34611)
		(end 349.05188 -214.261954)
		(width 0.0889)
		(layer "In6.Cu")
		(net "UPI_CPU0_CPU1_P0P1_DP<13>")
	)
	(segment
		(start 123.387866 -215.436958)
		(end 123.387612 -215.436704)
		(width 0.13208)
		(layer "F.Cu")
		(net "UPI_CPU0_CPU1_P0P1_DP<12>")
	)
	(segment
		(start 123.387866 -215.972644)
		(end 123.387866 -215.436958)
		(width 0.13208)
		(layer "F.Cu")
		(net "UPI_CPU0_CPU1_P0P1_DP<12>")
	)
	(segment
		(start 348.30258 -214.622888)
		(end 348.302326 -214.622634)
		(width 0.13208)
		(layer "F.Cu")
		(net "UPI_CPU0_CPU1_P0P1_DP<12>")
	)
	(segment
		(start 348.30258 -215.158574)
		(end 348.30258 -214.622888)
		(width 0.13208)
		(layer "F.Cu")
		(net "UPI_CPU0_CPU1_P0P1_DP<12>")
	)
	(segment
		(start 138.404854 -191.14516)
		(end 131.865624 -195.49237)
		(width 0.14732)
		(layer "In6.Cu")
		(net "UPI_CPU0_CPU1_P0P1_DP<12>")
	)
	(segment
		(start 329.308206 -188.125862)
		(end 327.180956 -186.61761)
		(width 0.14732)
		(layer "In6.Cu")
		(net "UPI_CPU0_CPU1_P0P1_DP<12>")
	)
	(segment
		(start 273.162014 -178.780694)
		(end 238.6203 -178.94554)
		(width 0.14732)
		(layer "In6.Cu")
		(net "UPI_CPU0_CPU1_P0P1_DP<12>")
	)
	(segment
		(start 123.292108 -214.425784)
		(end 123.292108 -214.636858)
		(width 0.0889)
		(layer "In6.Cu")
		(net "UPI_CPU0_CPU1_P0P1_DP<12>")
	)
	(segment
		(start 212.338412 -178.94554)
		(end 200.811384 -178.439064)
		(width 0.14732)
		(layer "In6.Cu")
		(net "UPI_CPU0_CPU1_P0P1_DP<12>")
	)
	(segment
		(start 123.720352 -210.63966)
		(end 123.720352 -211.63407)
		(width 0.14732)
		(layer "In6.Cu")
		(net "UPI_CPU0_CPU1_P0P1_DP<12>")
	)
	(segment
		(start 327.180956 -186.61761)
		(end 325.881492 -185.065924)
		(width 0.14732)
		(layer "In6.Cu")
		(net "UPI_CPU0_CPU1_P0P1_DP<12>")
	)
	(segment
		(start 325.581518 -184.606438)
		(end 325.094854 -184.144412)
		(width 0.14732)
		(layer "In6.Cu")
		(net "UPI_CPU0_CPU1_P0P1_DP<12>")
	)
	(segment
		(start 302.499522 -178.068732)
		(end 302.493934 -178.068732)
		(width 0.14732)
		(layer "In6.Cu")
		(net "UPI_CPU0_CPU1_P0P1_DP<12>")
	)
	(segment
		(start 348.439994 -211.684108)
		(end 348.439994 -211.66201)
		(width 0.0889)
		(layer "In6.Cu")
		(net "UPI_CPU0_CPU1_P0P1_DP<12>")
	)
	(segment
		(start 126.875032 -201.631804)
		(end 123.720352 -210.63966)
		(width 0.14732)
		(layer "In6.Cu")
		(net "UPI_CPU0_CPU1_P0P1_DP<12>")
	)
	(segment
		(start 332.766924 -189.589156)
		(end 331.635608 -189.11062)
		(width 0.14732)
		(layer "In6.Cu")
		(net "UPI_CPU0_CPU1_P0P1_DP<12>")
	)
	(segment
		(start 325.094854 -184.144412)
		(end 316.82055 -179.335176)
		(width 0.14732)
		(layer "In6.Cu")
		(net "UPI_CPU0_CPU1_P0P1_DP<12>")
	)
	(segment
		(start 331.635608 -189.11062)
		(end 331.635354 -189.11062)
		(width 0.14732)
		(layer "In6.Cu")
		(net "UPI_CPU0_CPU1_P0P1_DP<12>")
	)
	(segment
		(start 200.811384 -178.439064)
		(end 158.105856 -179.147724)
		(width 0.14732)
		(layer "In6.Cu")
		(net "UPI_CPU0_CPU1_P0P1_DP<12>")
	)
	(segment
		(start 123.720352 -211.63407)
		(end 123.720352 -211.656168)
		(width 0.0889)
		(layer "In6.Cu")
		(net "UPI_CPU0_CPU1_P0P1_DP<12>")
	)
	(segment
		(start 151.716994 -180.78323)
		(end 142.677134 -185.410348)
		(width 0.14732)
		(layer "In6.Cu")
		(net "UPI_CPU0_CPU1_P0P1_DP<12>")
	)
	(segment
		(start 158.105856 -179.147724)
		(end 151.716994 -180.78323)
		(width 0.14732)
		(layer "In6.Cu")
		(net "UPI_CPU0_CPU1_P0P1_DP<12>")
	)
	(segment
		(start 123.519946 -215.076532)
		(end 123.544076 -215.165686)
		(width 0.0889)
		(layer "In6.Cu")
		(net "UPI_CPU0_CPU1_P0P1_DP<12>")
	)
	(segment
		(start 123.720352 -211.656168)
		(end 123.762262 -211.698078)
		(width 0.0889)
		(layer "In6.Cu")
		(net "UPI_CPU0_CPU1_P0P1_DP<12>")
	)
	(segment
		(start 312.986928 -178.26355)
		(end 302.499776 -178.068986)
		(width 0.14732)
		(layer "In6.Cu")
		(net "UPI_CPU0_CPU1_P0P1_DP<12>")
	)
	(segment
		(start 348.398084 -213.929468)
		(end 348.398084 -211.726018)
		(width 0.0889)
		(layer "In6.Cu")
		(net "UPI_CPU0_CPU1_P0P1_DP<12>")
	)
	(segment
		(start 142.677134 -185.410348)
		(end 138.404854 -191.14516)
		(width 0.14732)
		(layer "In6.Cu")
		(net "UPI_CPU0_CPU1_P0P1_DP<12>")
	)
	(segment
		(start 238.6203 -178.94554)
		(end 212.338412 -178.94554)
		(width 0.14732)
		(layer "In6.Cu")
		(net "UPI_CPU0_CPU1_P0P1_DP<12>")
	)
	(segment
		(start 302.488092 -178.068986)
		(end 273.162014 -178.780694)
		(width 0.14732)
		(layer "In6.Cu")
		(net "UPI_CPU0_CPU1_P0P1_DP<12>")
	)
	(segment
		(start 302.499776 -178.068986)
		(end 302.499522 -178.068732)
		(width 0.14732)
		(layer "In6.Cu")
		(net "UPI_CPU0_CPU1_P0P1_DP<12>")
	)
	(segment
		(start 316.82055 -179.335176)
		(end 312.986928 -178.26355)
		(width 0.14732)
		(layer "In6.Cu")
		(net "UPI_CPU0_CPU1_P0P1_DP<12>")
	)
	(segment
		(start 348.398084 -211.726018)
		(end 348.439994 -211.684108)
		(width 0.0889)
		(layer "In6.Cu")
		(net "UPI_CPU0_CPU1_P0P1_DP<12>")
	)
	(segment
		(start 348.143576 -214.321644)
		(end 348.173802 -214.22487)
		(width 0.0889)
		(layer "In6.Cu")
		(net "UPI_CPU0_CPU1_P0P1_DP<12>")
	)
	(segment
		(start 348.43974 -210.474814)
		(end 347.501718 -201.600308)
		(width 0.14732)
		(layer "In6.Cu")
		(net "UPI_CPU0_CPU1_P0P1_DP<12>")
	)
	(segment
		(start 331.635354 -189.11062)
		(end 329.308206 -188.125862)
		(width 0.14732)
		(layer "In6.Cu")
		(net "UPI_CPU0_CPU1_P0P1_DP<12>")
	)
	(segment
		(start 347.501718 -201.600308)
		(end 346.555822 -200.434956)
		(width 0.14732)
		(layer "In6.Cu")
		(net "UPI_CPU0_CPU1_P0P1_DP<12>")
	)
	(segment
		(start 348.43974 -210.875118)
		(end 348.43974 -210.474814)
		(width 0.14732)
		(layer "In6.Cu")
		(net "UPI_CPU0_CPU1_P0P1_DP<12>")
	)
	(segment
		(start 348.439994 -210.874864)
		(end 348.43974 -210.875118)
		(width 0.14732)
		(layer "In6.Cu")
		(net "UPI_CPU0_CPU1_P0P1_DP<12>")
	)
	(segment
		(start 348.439994 -211.66201)
		(end 348.439994 -210.874864)
		(width 0.14732)
		(layer "In6.Cu")
		(net "UPI_CPU0_CPU1_P0P1_DP<12>")
	)
	(segment
		(start 123.544076 -215.165686)
		(end 123.387612 -215.436704)
		(width 0.0889)
		(layer "In6.Cu")
		(net "UPI_CPU0_CPU1_P0P1_DP<12>")
	)
	(segment
		(start 131.865624 -195.49237)
		(end 126.875032 -201.631804)
		(width 0.14732)
		(layer "In6.Cu")
		(net "UPI_CPU0_CPU1_P0P1_DP<12>")
	)
	(segment
		(start 348.302326 -214.622634)
		(end 348.143576 -214.321644)
		(width 0.0889)
		(layer "In6.Cu")
		(net "UPI_CPU0_CPU1_P0P1_DP<12>")
	)
	(segment
		(start 346.555822 -200.434956)
		(end 332.766924 -189.589156)
		(width 0.14732)
		(layer "In6.Cu")
		(net "UPI_CPU0_CPU1_P0P1_DP<12>")
	)
	(segment
		(start 325.881492 -185.065924)
		(end 325.581518 -184.606438)
		(width 0.14732)
		(layer "In6.Cu")
		(net "UPI_CPU0_CPU1_P0P1_DP<12>")
	)
	(segment
		(start 302.493934 -178.068732)
		(end 302.488092 -178.068986)
		(width 0.14732)
		(layer "In6.Cu")
		(net "UPI_CPU0_CPU1_P0P1_DP<12>")
	)
	(segment
		(start 123.762262 -211.698078)
		(end 123.762262 -213.894162)
		(width 0.0889)
		(layer "In6.Cu")
		(net "UPI_CPU0_CPU1_P0P1_DP<12>")
	)
	(arc
		(start 123.578112 -214.093298)
		(mid 123.403564 -214.232402)
		(end 123.292108 -214.425784)
		(width 0.0889)
		(layer "In6.Cu")
		(net "UPI_CPU0_CPU1_P0P1_DP<12>")
	)
	(arc
		(start 348.383098 -213.96833)
		(mid 348.390933 -213.949031)
		(end 348.398084 -213.929468)
		(width 0.0889)
		(layer "In6.Cu")
		(net "UPI_CPU0_CPU1_P0P1_DP<12>")
	)
	(arc
		(start 123.292108 -214.636858)
		(mid 123.350453 -214.873363)
		(end 123.502928 -215.063324)
		(width 0.0889)
		(layer "In6.Cu")
		(net "UPI_CPU0_CPU1_P0P1_DP<12>")
	)
	(arc
		(start 123.762262 -213.894162)
		(mid 123.687224 -214.009482)
		(end 123.578112 -214.093298)
		(width 0.0889)
		(layer "In6.Cu")
		(net "UPI_CPU0_CPU1_P0P1_DP<12>")
	)
	(arc
		(start 348.173802 -214.22487)
		(mid 348.296548 -214.111365)
		(end 348.383098 -213.96833)
		(width 0.0889)
		(layer "In6.Cu")
		(net "UPI_CPU0_CPU1_P0P1_DP<12>")
	)
	(arc
		(start 123.502928 -215.063324)
		(mid 123.511374 -215.070009)
		(end 123.519946 -215.076532)
		(width 0.0889)
		(layer "In6.Cu")
		(net "UPI_CPU0_CPU1_P0P1_DP<12>")
	)
	(segment
		(start 124.797312 -215.158574)
		(end 124.797312 -214.622888)
		(width 0.13208)
		(layer "F.Cu")
		(net "UPI_CPU0_CPU1_P0P1_DP<11>")
	)
	(segment
		(start 346.893134 -215.436958)
		(end 346.89288 -215.436704)
		(width 0.13208)
		(layer "F.Cu")
		(net "UPI_CPU0_CPU1_P0P1_DP<11>")
	)
	(segment
		(start 124.797312 -214.622888)
		(end 124.797058 -214.622634)
		(width 0.13208)
		(layer "F.Cu")
		(net "UPI_CPU0_CPU1_P0P1_DP<11>")
	)
	(segment
		(start 346.893134 -215.972644)
		(end 346.893134 -215.436958)
		(width 0.13208)
		(layer "F.Cu")
		(net "UPI_CPU0_CPU1_P0P1_DP<11>")
	)
	(segment
		(start 125.267974 -210.008216)
		(end 125.083062 -210.096862)
		(width 0.14732)
		(layer "In6.Cu")
		(net "UPI_CPU0_CPU1_P0P1_DP<11>")
	)
	(segment
		(start 331.465428 -190.735458)
		(end 331.41158 -190.537592)
		(width 0.14732)
		(layer "In6.Cu")
		(net "UPI_CPU0_CPU1_P0P1_DP<11>")
	)
	(segment
		(start 125.607064 -209.03946)
		(end 125.422406 -209.12836)
		(width 0.14732)
		(layer "In6.Cu")
		(net "UPI_CPU0_CPU1_P0P1_DP<11>")
	)
	(segment
		(start 347.268038 -213.892892)
		(end 347.268038 -211.726018)
		(width 0.0889)
		(layer "In6.Cu")
		(net "UPI_CPU0_CPU1_P0P1_DP<11>")
	)
	(segment
		(start 127.302006 -204.198728)
		(end 127.18034 -204.546708)
		(width 0.14732)
		(layer "In6.Cu")
		(net "UPI_CPU0_CPU1_P0P1_DP<11>")
	)
	(segment
		(start 312.719466 -179.375816)
		(end 302.496982 -179.186332)
		(width 0.14732)
		(layer "In6.Cu")
		(net "UPI_CPU0_CPU1_P0P1_DP<11>")
	)
	(segment
		(start 125.083316 -210.097116)
		(end 124.934218 -210.522566)
		(width 0.14732)
		(layer "In6.Cu")
		(net "UPI_CPU0_CPU1_P0P1_DP<11>")
	)
	(segment
		(start 125.08357 -210.096862)
		(end 125.083316 -210.097116)
		(width 0.14732)
		(layer "In6.Cu")
		(net "UPI_CPU0_CPU1_P0P1_DP<11>")
	)
	(segment
		(start 347.226128 -211.537296)
		(end 347.225874 -211.53755)
		(width 0.14732)
		(layer "In6.Cu")
		(net "UPI_CPU0_CPU1_P0P1_DP<11>")
	)
	(segment
		(start 347.267784 -213.8934)
		(end 347.268038 -213.892892)
		(width 0.0889)
		(layer "In6.Cu")
		(net "UPI_CPU0_CPU1_P0P1_DP<11>")
	)
	(segment
		(start 158.295848 -180.26761)
		(end 155.198572 -181.060598)
		(width 0.14732)
		(layer "In6.Cu")
		(net "UPI_CPU0_CPU1_P0P1_DP<11>")
	)
	(segment
		(start 127.552958 -203.044552)
		(end 127.55245 -203.044806)
		(width 0.14732)
		(layer "In6.Cu")
		(net "UPI_CPU0_CPU1_P0P1_DP<11>")
	)
	(segment
		(start 324.317868 -184.974484)
		(end 316.506352 -180.434234)
		(width 0.14732)
		(layer "In6.Cu")
		(net "UPI_CPU0_CPU1_P0P1_DP<11>")
	)
	(segment
		(start 124.934472 -211.65185)
		(end 124.934472 -211.673948)
		(width 0.0889)
		(layer "In6.Cu")
		(net "UPI_CPU0_CPU1_P0P1_DP<11>")
	)
	(segment
		(start 125.640084 -208.507076)
		(end 125.72873 -208.691734)
		(width 0.14732)
		(layer "In6.Cu")
		(net "UPI_CPU0_CPU1_P0P1_DP<11>")
	)
	(segment
		(start 125.30074 -209.475832)
		(end 125.38964 -209.660236)
		(width 0.14732)
		(layer "In6.Cu")
		(net "UPI_CPU0_CPU1_P0P1_DP<11>")
	)
	(segment
		(start 127.857758 -202.173078)
		(end 127.552958 -203.044552)
		(width 0.14732)
		(layer "In6.Cu")
		(net "UPI_CPU0_CPU1_P0P1_DP<11>")
	)
	(segment
		(start 328.77633 -189.10935)
		(end 326.484488 -187.506356)
		(width 0.14732)
		(layer "In6.Cu")
		(net "UPI_CPU0_CPU1_P0P1_DP<11>")
	)
	(segment
		(start 127.21336 -204.014324)
		(end 127.302006 -204.198728)
		(width 0.14732)
		(layer "In6.Cu")
		(net "UPI_CPU0_CPU1_P0P1_DP<11>")
	)
	(segment
		(start 124.934218 -211.483448)
		(end 124.934472 -211.483702)
		(width 0.14732)
		(layer "In6.Cu")
		(net "UPI_CPU0_CPU1_P0P1_DP<11>")
	)
	(segment
		(start 125.72873 -208.691734)
		(end 125.607064 -209.03946)
		(width 0.14732)
		(layer "In6.Cu")
		(net "UPI_CPU0_CPU1_P0P1_DP<11>")
	)
	(segment
		(start 126.995682 -204.635608)
		(end 126.696724 -205.489556)
		(width 0.14732)
		(layer "In6.Cu")
		(net "UPI_CPU0_CPU1_P0P1_DP<11>")
	)
	(segment
		(start 126.01829 -207.865218)
		(end 125.833632 -207.954118)
		(width 0.14732)
		(layer "In6.Cu")
		(net "UPI_CPU0_CPU1_P0P1_DP<11>")
	)
	(segment
		(start 346.797376 -214.636858)
		(end 346.797376 -214.425784)
		(width 0.0889)
		(layer "In6.Cu")
		(net "UPI_CPU0_CPU1_P0P1_DP<11>")
	)
	(segment
		(start 316.506352 -180.434234)
		(end 312.719466 -179.375816)
		(width 0.14732)
		(layer "In6.Cu")
		(net "UPI_CPU0_CPU1_P0P1_DP<11>")
	)
	(segment
		(start 346.89288 -215.436704)
		(end 347.049344 -215.165686)
		(width 0.0889)
		(layer "In6.Cu")
		(net "UPI_CPU0_CPU1_P0P1_DP<11>")
	)
	(segment
		(start 238.623348 -180.062378)
		(end 212.02142 -180.062378)
		(width 0.14732)
		(layer "In6.Cu")
		(net "UPI_CPU0_CPU1_P0P1_DP<11>")
	)
	(segment
		(start 127.55245 -203.044806)
		(end 127.21336 -204.014324)
		(width 0.14732)
		(layer "In6.Cu")
		(net "UPI_CPU0_CPU1_P0P1_DP<11>")
	)
	(segment
		(start 124.934218 -210.522566)
		(end 124.934218 -211.483448)
		(width 0.14732)
		(layer "In6.Cu")
		(net "UPI_CPU0_CPU1_P0P1_DP<11>")
	)
	(segment
		(start 124.892308 -211.716112)
		(end 124.892308 -213.929976)
		(width 0.0889)
		(layer "In6.Cu")
		(net "UPI_CPU0_CPU1_P0P1_DP<11>")
	)
	(segment
		(start 124.934472 -211.483702)
		(end 124.934472 -211.65185)
		(width 0.14732)
		(layer "In6.Cu")
		(net "UPI_CPU0_CPU1_P0P1_DP<11>")
	)
	(segment
		(start 331.785214 -190.918338)
		(end 331.465428 -190.735458)
		(width 0.14732)
		(layer "In6.Cu")
		(net "UPI_CPU0_CPU1_P0P1_DP<11>")
	)
	(segment
		(start 155.198064 -181.060598)
		(end 152.10155 -181.853332)
		(width 0.14732)
		(layer "In6.Cu")
		(net "UPI_CPU0_CPU1_P0P1_DP<11>")
	)
	(segment
		(start 273.17827 -179.897532)
		(end 238.623348 -180.062378)
		(width 0.14732)
		(layer "In6.Cu")
		(net "UPI_CPU0_CPU1_P0P1_DP<11>")
	)
	(segment
		(start 346.33154 -202.08621)
		(end 345.455494 -201.007218)
		(width 0.14732)
		(layer "In6.Cu")
		(net "UPI_CPU0_CPU1_P0P1_DP<11>")
	)
	(segment
		(start 347.225874 -211.53755)
		(end 347.225874 -210.543902)
		(width 0.14732)
		(layer "In6.Cu")
		(net "UPI_CPU0_CPU1_P0P1_DP<11>")
	)
	(segment
		(start 331.982826 -190.86449)
		(end 331.785214 -190.918338)
		(width 0.14732)
		(layer "In6.Cu")
		(net "UPI_CPU0_CPU1_P0P1_DP<11>")
	)
	(segment
		(start 125.833632 -207.954118)
		(end 125.640084 -208.507076)
		(width 0.14732)
		(layer "In6.Cu")
		(net "UPI_CPU0_CPU1_P0P1_DP<11>")
	)
	(segment
		(start 126.785624 -205.674214)
		(end 126.663704 -206.02194)
		(width 0.14732)
		(layer "In6.Cu")
		(net "UPI_CPU0_CPU1_P0P1_DP<11>")
	)
	(segment
		(start 347.049344 -215.165686)
		(end 347.025214 -215.076532)
		(width 0.0889)
		(layer "In6.Cu")
		(net "UPI_CPU0_CPU1_P0P1_DP<11>")
	)
	(segment
		(start 345.455494 -201.007218)
		(end 334.103726 -192.077594)
		(width 0.14732)
		(layer "In6.Cu")
		(net "UPI_CPU0_CPU1_P0P1_DP<11>")
	)
	(segment
		(start 126.696724 -205.489556)
		(end 126.785624 -205.674214)
		(width 0.14732)
		(layer "In6.Cu")
		(net "UPI_CPU0_CPU1_P0P1_DP<11>")
	)
	(segment
		(start 124.934472 -211.673948)
		(end 124.892308 -211.716112)
		(width 0.0889)
		(layer "In6.Cu")
		(net "UPI_CPU0_CPU1_P0P1_DP<11>")
	)
	(segment
		(start 155.198572 -181.060598)
		(end 155.198064 -181.060598)
		(width 0.14732)
		(layer "In6.Cu")
		(net "UPI_CPU0_CPU1_P0P1_DP<11>")
	)
	(segment
		(start 124.638308 -214.321644)
		(end 124.797058 -214.622634)
		(width 0.0889)
		(layer "In6.Cu")
		(net "UPI_CPU0_CPU1_P0P1_DP<11>")
	)
	(segment
		(start 347.225874 -210.543902)
		(end 346.33154 -202.08621)
		(width 0.14732)
		(layer "In6.Cu")
		(net "UPI_CPU0_CPU1_P0P1_DP<11>")
	)
	(segment
		(start 139.030202 -192.20688)
		(end 132.350764 -196.6468)
		(width 0.14732)
		(layer "In6.Cu")
		(net "UPI_CPU0_CPU1_P0P1_DP<11>")
	)
	(segment
		(start 125.422406 -209.12836)
		(end 125.30074 -209.475832)
		(width 0.14732)
		(layer "In6.Cu")
		(net "UPI_CPU0_CPU1_P0P1_DP<11>")
	)
	(segment
		(start 347.226128 -211.684108)
		(end 347.226128 -211.66201)
		(width 0.0889)
		(layer "In6.Cu")
		(net "UPI_CPU0_CPU1_P0P1_DP<11>")
	)
	(segment
		(start 124.668534 -214.224616)
		(end 124.638308 -214.321644)
		(width 0.0889)
		(layer "In6.Cu")
		(net "UPI_CPU0_CPU1_P0P1_DP<11>")
	)
	(segment
		(start 127.18034 -204.546708)
		(end 126.995682 -204.635608)
		(width 0.14732)
		(layer "In6.Cu")
		(net "UPI_CPU0_CPU1_P0P1_DP<11>")
	)
	(segment
		(start 125.38964 -209.660236)
		(end 125.267974 -210.008216)
		(width 0.14732)
		(layer "In6.Cu")
		(net "UPI_CPU0_CPU1_P0P1_DP<11>")
	)
	(segment
		(start 212.02142 -180.062378)
		(end 200.684638 -179.564538)
		(width 0.14732)
		(layer "In6.Cu")
		(net "UPI_CPU0_CPU1_P0P1_DP<11>")
	)
	(segment
		(start 329.471528 -189.42812)
		(end 328.77633 -189.10935)
		(width 0.14732)
		(layer "In6.Cu")
		(net "UPI_CPU0_CPU1_P0P1_DP<11>")
	)
	(segment
		(start 126.663704 -206.02194)
		(end 126.479046 -206.11084)
		(width 0.14732)
		(layer "In6.Cu")
		(net "UPI_CPU0_CPU1_P0P1_DP<11>")
	)
	(segment
		(start 324.700646 -185.322972)
		(end 324.317868 -184.974484)
		(width 0.14732)
		(layer "In6.Cu")
		(net "UPI_CPU0_CPU1_P0P1_DP<11>")
	)
	(segment
		(start 124.892308 -213.929976)
		(end 124.892816 -213.929214)
		(width 0.0889)
		(layer "In6.Cu")
		(net "UPI_CPU0_CPU1_P0P1_DP<11>")
	)
	(segment
		(start 126.479046 -206.11084)
		(end 126.05131 -207.332834)
		(width 0.14732)
		(layer "In6.Cu")
		(net "UPI_CPU0_CPU1_P0P1_DP<11>")
	)
	(segment
		(start 326.484488 -187.506356)
		(end 325.066152 -185.834274)
		(width 0.14732)
		(layer "In6.Cu")
		(net "UPI_CPU0_CPU1_P0P1_DP<11>")
	)
	(segment
		(start 200.684638 -179.564538)
		(end 158.295848 -180.26761)
		(width 0.14732)
		(layer "In6.Cu")
		(net "UPI_CPU0_CPU1_P0P1_DP<11>")
	)
	(segment
		(start 152.10155 -181.853332)
		(end 143.439642 -186.28741)
		(width 0.14732)
		(layer "In6.Cu")
		(net "UPI_CPU0_CPU1_P0P1_DP<11>")
	)
	(segment
		(start 334.103726 -192.077594)
		(end 331.982826 -190.86449)
		(width 0.14732)
		(layer "In6.Cu")
		(net "UPI_CPU0_CPU1_P0P1_DP<11>")
	)
	(segment
		(start 325.066152 -185.834274)
		(end 324.700646 -185.322972)
		(width 0.14732)
		(layer "In6.Cu")
		(net "UPI_CPU0_CPU1_P0P1_DP<11>")
	)
	(segment
		(start 347.226128 -211.66201)
		(end 347.226128 -211.537296)
		(width 0.14732)
		(layer "In6.Cu")
		(net "UPI_CPU0_CPU1_P0P1_DP<11>")
	)
	(segment
		(start 302.496982 -179.186332)
		(end 273.17827 -179.897532)
		(width 0.14732)
		(layer "In6.Cu")
		(net "UPI_CPU0_CPU1_P0P1_DP<11>")
	)
	(segment
		(start 126.05131 -207.332834)
		(end 126.14021 -207.517238)
		(width 0.14732)
		(layer "In6.Cu")
		(net "UPI_CPU0_CPU1_P0P1_DP<11>")
	)
	(segment
		(start 143.439642 -186.28741)
		(end 139.030202 -192.20688)
		(width 0.14732)
		(layer "In6.Cu")
		(net "UPI_CPU0_CPU1_P0P1_DP<11>")
	)
	(segment
		(start 132.350764 -196.6468)
		(end 127.857758 -202.173078)
		(width 0.14732)
		(layer "In6.Cu")
		(net "UPI_CPU0_CPU1_P0P1_DP<11>")
	)
	(segment
		(start 125.083062 -210.096862)
		(end 125.08357 -210.096862)
		(width 0.14732)
		(layer "In6.Cu")
		(net "UPI_CPU0_CPU1_P0P1_DP<11>")
	)
	(segment
		(start 331.41158 -190.537592)
		(end 329.471528 -189.42812)
		(width 0.14732)
		(layer "In6.Cu")
		(net "UPI_CPU0_CPU1_P0P1_DP<11>")
	)
	(segment
		(start 347.268038 -211.726018)
		(end 347.226128 -211.684108)
		(width 0.0889)
		(layer "In6.Cu")
		(net "UPI_CPU0_CPU1_P0P1_DP<11>")
	)
	(segment
		(start 126.14021 -207.517238)
		(end 126.01829 -207.865218)
		(width 0.14732)
		(layer "In6.Cu")
		(net "UPI_CPU0_CPU1_P0P1_DP<11>")
	)
	(arc
		(start 124.892816 -213.929214)
		(mid 124.804126 -214.094715)
		(end 124.668534 -214.224616)
		(width 0.0889)
		(layer "In6.Cu")
		(net "UPI_CPU0_CPU1_P0P1_DP<11>")
	)
	(arc
		(start 347.08338 -214.093298)
		(mid 347.192776 -214.009201)
		(end 347.267784 -213.8934)
		(width 0.0889)
		(layer "In6.Cu")
		(net "UPI_CPU0_CPU1_P0P1_DP<11>")
	)
	(arc
		(start 346.797376 -214.425784)
		(mid 346.908816 -214.232389)
		(end 347.08338 -214.093298)
		(width 0.0889)
		(layer "In6.Cu")
		(net "UPI_CPU0_CPU1_P0P1_DP<11>")
	)
	(arc
		(start 347.008196 -215.063324)
		(mid 346.855765 -214.873342)
		(end 346.797376 -214.636858)
		(width 0.0889)
		(layer "In6.Cu")
		(net "UPI_CPU0_CPU1_P0P1_DP<11>")
	)
	(arc
		(start 347.025214 -215.076532)
		(mid 347.016642 -215.070009)
		(end 347.008196 -215.063324)
		(width 0.0889)
		(layer "In6.Cu")
		(net "UPI_CPU0_CPU1_P0P1_DP<11>")
	)
	(segment
		(start 345.953334 -214.344758)
		(end 345.953334 -213.732618)
		(width 0.13208)
		(layer "F.Cu")
		(net "UPI_CPU0_CPU1_P0P1_DP<10>")
	)
	(segment
		(start 125.737112 -215.158574)
		(end 125.737112 -214.622888)
		(width 0.13208)
		(layer "F.Cu")
		(net "UPI_CPU0_CPU1_P0P1_DP<10>")
	)
	(segment
		(start 125.737112 -214.622888)
		(end 125.736858 -214.622634)
		(width 0.13208)
		(layer "F.Cu")
		(net "UPI_CPU0_CPU1_P0P1_DP<10>")
	)
	(segment
		(start 130.269996 -200.630282)
		(end 130.28803 -200.805542)
		(width 0.14732)
		(layer "In6.Cu")
		(net "UPI_CPU0_CPU1_P0P1_DP<10>")
	)
	(segment
		(start 273.190462 -180.74005)
		(end 238.625634 -180.904896)
		(width 0.14732)
		(layer "In6.Cu")
		(net "UPI_CPU0_CPU1_P0P1_DP<10>")
	)
	(segment
		(start 133.087364 -197.165722)
		(end 132.395214 -198.016622)
		(width 0.14732)
		(layer "In6.Cu")
		(net "UPI_CPU0_CPU1_P0P1_DP<10>")
	)
	(segment
		(start 130.545586 -200.291446)
		(end 130.269996 -200.630282)
		(width 0.14732)
		(layer "In6.Cu")
		(net "UPI_CPU0_CPU1_P0P1_DP<10>")
	)
	(segment
		(start 130.720592 -200.273412)
		(end 130.545586 -200.291446)
		(width 0.14732)
		(layer "In6.Cu")
		(net "UPI_CPU0_CPU1_P0P1_DP<10>")
	)
	(segment
		(start 344.655902 -201.51344)
		(end 333.444088 -192.693036)
		(width 0.14732)
		(layer "In6.Cu")
		(net "UPI_CPU0_CPU1_P0P1_DP<10>")
	)
	(segment
		(start 125.832108 -211.667852)
		(end 125.832108 -212.164676)
		(width 0.0889)
		(layer "In6.Cu")
		(net "UPI_CPU0_CPU1_P0P1_DP<10>")
	)
	(segment
		(start 131.962398 -198.549006)
		(end 131.686808 -198.887842)
		(width 0.14732)
		(layer "In6.Cu")
		(net "UPI_CPU0_CPU1_P0P1_DP<10>")
	)
	(segment
		(start 327.346818 -190.52667)
		(end 327.055988 -190.3476)
		(width 0.14732)
		(layer "In6.Cu")
		(net "UPI_CPU0_CPU1_P0P1_DP<10>")
	)
	(segment
		(start 129.30378 -202.015852)
		(end 129.12852 -202.033886)
		(width 0.14732)
		(layer "In6.Cu")
		(net "UPI_CPU0_CPU1_P0P1_DP<10>")
	)
	(segment
		(start 346.327984 -212.756496)
		(end 346.22867 -212.657182)
		(width 0.0889)
		(layer "In6.Cu")
		(net "UPI_CPU0_CPU1_P0P1_DP<10>")
	)
	(segment
		(start 131.428998 -199.402192)
		(end 131.253992 -199.420226)
		(width 0.14732)
		(layer "In6.Cu")
		(net "UPI_CPU0_CPU1_P0P1_DP<10>")
	)
	(segment
		(start 125.931422 -212.26399)
		(end 125.931422 -212.53069)
		(width 0.0889)
		(layer "In6.Cu")
		(net "UPI_CPU0_CPU1_P0P1_DP<10>")
	)
	(segment
		(start 346.22867 -212.390482)
		(end 346.327984 -212.291168)
		(width 0.0889)
		(layer "In6.Cu")
		(net "UPI_CPU0_CPU1_P0P1_DP<10>")
	)
	(segment
		(start 346.327984 -213.488524)
		(end 346.22867 -213.38921)
		(width 0.0889)
		(layer "In6.Cu")
		(net "UPI_CPU0_CPU1_P0P1_DP<10>")
	)
	(segment
		(start 333.444088 -192.693036)
		(end 327.346818 -190.52667)
		(width 0.14732)
		(layer "In6.Cu")
		(net "UPI_CPU0_CPU1_P0P1_DP<10>")
	)
	(segment
		(start 346.327984 -213.023196)
		(end 346.327984 -212.756496)
		(width 0.0889)
		(layer "In6.Cu")
		(net "UPI_CPU0_CPU1_P0P1_DP<10>")
	)
	(segment
		(start 346.327984 -212.291168)
		(end 346.327984 -211.726018)
		(width 0.0889)
		(layer "In6.Cu")
		(net "UPI_CPU0_CPU1_P0P1_DP<10>")
	)
	(segment
		(start 125.931422 -213.262718)
		(end 125.832108 -213.362032)
		(width 0.0889)
		(layer "In6.Cu")
		(net "UPI_CPU0_CPU1_P0P1_DP<10>")
	)
	(segment
		(start 128.821434 -202.411584)
		(end 125.874272 -210.82889)
		(width 0.14732)
		(layer "In6.Cu")
		(net "UPI_CPU0_CPU1_P0P1_DP<10>")
	)
	(segment
		(start 139.629388 -192.816226)
		(end 133.087364 -197.165722)
		(width 0.14732)
		(layer "In6.Cu")
		(net "UPI_CPU0_CPU1_P0P1_DP<10>")
	)
	(segment
		(start 132.413248 -198.191882)
		(end 132.137404 -198.530972)
		(width 0.14732)
		(layer "In6.Cu")
		(net "UPI_CPU0_CPU1_P0P1_DP<10>")
	)
	(segment
		(start 322.236338 -185.406284)
		(end 321.707764 -184.674002)
		(width 0.14732)
		(layer "In6.Cu")
		(net "UPI_CPU0_CPU1_P0P1_DP<10>")
	)
	(segment
		(start 131.686808 -198.887842)
		(end 131.704842 -199.063102)
		(width 0.14732)
		(layer "In6.Cu")
		(net "UPI_CPU0_CPU1_P0P1_DP<10>")
	)
	(segment
		(start 125.362208 -214.461852)
		(end 125.362208 -214.622634)
		(width 0.0889)
		(layer "In6.Cu")
		(net "UPI_CPU0_CPU1_P0P1_DP<10>")
	)
	(segment
		(start 125.832108 -212.630004)
		(end 125.832108 -212.896704)
		(width 0.0889)
		(layer "In6.Cu")
		(net "UPI_CPU0_CPU1_P0P1_DP<10>")
	)
	(segment
		(start 130.978402 -199.759062)
		(end 130.996436 -199.934322)
		(width 0.14732)
		(layer "In6.Cu")
		(net "UPI_CPU0_CPU1_P0P1_DP<10>")
	)
	(segment
		(start 131.253992 -199.420226)
		(end 130.978402 -199.759062)
		(width 0.14732)
		(layer "In6.Cu")
		(net "UPI_CPU0_CPU1_P0P1_DP<10>")
	)
	(segment
		(start 320.500502 -184.08904)
		(end 320.454528 -183.889142)
		(width 0.14732)
		(layer "In6.Cu")
		(net "UPI_CPU0_CPU1_P0P1_DP<10>")
	)
	(segment
		(start 132.137404 -198.530972)
		(end 131.962398 -198.549006)
		(width 0.14732)
		(layer "In6.Cu")
		(net "UPI_CPU0_CPU1_P0P1_DP<10>")
	)
	(segment
		(start 125.502162 -214.91448)
		(end 125.580394 -214.893652)
		(width 0.0889)
		(layer "In6.Cu")
		(net "UPI_CPU0_CPU1_P0P1_DP<10>")
	)
	(segment
		(start 322.203572 -185.608468)
		(end 322.236338 -185.406284)
		(width 0.14732)
		(layer "In6.Cu")
		(net "UPI_CPU0_CPU1_P0P1_DP<10>")
	)
	(segment
		(start 346.286074 -211.537296)
		(end 346.28582 -211.53755)
		(width 0.14732)
		(layer "In6.Cu")
		(net "UPI_CPU0_CPU1_P0P1_DP<10>")
	)
	(segment
		(start 152.09393 -182.809642)
		(end 143.995902 -186.955176)
		(width 0.14732)
		(layer "In6.Cu")
		(net "UPI_CPU0_CPU1_P0P1_DP<10>")
	)
	(segment
		(start 346.286074 -211.684108)
		(end 346.286074 -211.66201)
		(width 0.0889)
		(layer "In6.Cu")
		(net "UPI_CPU0_CPU1_P0P1_DP<10>")
	)
	(segment
		(start 319.943226 -183.739536)
		(end 319.630806 -183.54421)
		(width 0.14732)
		(layer "In6.Cu")
		(net "UPI_CPU0_CPU1_P0P1_DP<10>")
	)
	(segment
		(start 125.832108 -213.362032)
		(end 125.832108 -213.929722)
		(width 0.0889)
		(layer "In6.Cu")
		(net "UPI_CPU0_CPU1_P0P1_DP<10>")
	)
	(segment
		(start 125.832108 -212.896704)
		(end 125.931422 -212.996018)
		(width 0.0889)
		(layer "In6.Cu")
		(net "UPI_CPU0_CPU1_P0P1_DP<10>")
	)
	(segment
		(start 132.395214 -198.016622)
		(end 132.413248 -198.191882)
		(width 0.14732)
		(layer "In6.Cu")
		(net "UPI_CPU0_CPU1_P0P1_DP<10>")
	)
	(segment
		(start 346.22867 -213.38921)
		(end 346.22867 -213.12251)
		(width 0.0889)
		(layer "In6.Cu")
		(net "UPI_CPU0_CPU1_P0P1_DP<10>")
	)
	(segment
		(start 129.12852 -202.033886)
		(end 128.821434 -202.411584)
		(width 0.14732)
		(layer "In6.Cu")
		(net "UPI_CPU0_CPU1_P0P1_DP<10>")
	)
	(segment
		(start 321.707764 -184.674002)
		(end 321.012312 -184.238646)
		(width 0.14732)
		(layer "In6.Cu")
		(net "UPI_CPU0_CPU1_P0P1_DP<10>")
	)
	(segment
		(start 320.812922 -184.284366)
		(end 320.500502 -184.08904)
		(width 0.14732)
		(layer "In6.Cu")
		(net "UPI_CPU0_CPU1_P0P1_DP<10>")
	)
	(segment
		(start 179.73167 -180.762656)
		(end 179.731416 -180.762656)
		(width 0.14732)
		(layer "In6.Cu")
		(net "UPI_CPU0_CPU1_P0P1_DP<10>")
	)
	(segment
		(start 125.874272 -210.82889)
		(end 125.874272 -211.60359)
		(width 0.14732)
		(layer "In6.Cu")
		(net "UPI_CPU0_CPU1_P0P1_DP<10>")
	)
	(segment
		(start 129.83718 -201.162666)
		(end 129.56159 -201.501502)
		(width 0.14732)
		(layer "In6.Cu")
		(net "UPI_CPU0_CPU1_P0P1_DP<10>")
	)
	(segment
		(start 346.28582 -211.53755)
		(end 346.28582 -210.589368)
		(width 0.14732)
		(layer "In6.Cu")
		(net "UPI_CPU0_CPU1_P0P1_DP<10>")
	)
	(segment
		(start 323.030342 -186.506612)
		(end 322.621402 -185.939938)
		(width 0.14732)
		(layer "In6.Cu")
		(net "UPI_CPU0_CPU1_P0P1_DP<10>")
	)
	(segment
		(start 322.621402 -185.939938)
		(end 322.419218 -185.907426)
		(width 0.14732)
		(layer "In6.Cu")
		(net "UPI_CPU0_CPU1_P0P1_DP<10>")
	)
	(segment
		(start 131.704842 -199.063102)
		(end 131.428998 -199.402192)
		(width 0.14732)
		(layer "In6.Cu")
		(net "UPI_CPU0_CPU1_P0P1_DP<10>")
	)
	(segment
		(start 158.728664 -181.111144)
		(end 152.09393 -182.809642)
		(width 0.14732)
		(layer "In6.Cu")
		(net "UPI_CPU0_CPU1_P0P1_DP<10>")
	)
	(segment
		(start 125.931422 -212.996018)
		(end 125.931422 -213.262718)
		(width 0.0889)
		(layer "In6.Cu")
		(net "UPI_CPU0_CPU1_P0P1_DP<10>")
	)
	(segment
		(start 129.579624 -201.676508)
		(end 129.30378 -202.015852)
		(width 0.14732)
		(layer "In6.Cu")
		(net "UPI_CPU0_CPU1_P0P1_DP<10>")
	)
	(segment
		(start 125.931422 -212.53069)
		(end 125.832108 -212.630004)
		(width 0.0889)
		(layer "In6.Cu")
		(net "UPI_CPU0_CPU1_P0P1_DP<10>")
	)
	(segment
		(start 319.584832 -183.344312)
		(end 316.364112 -181.327044)
		(width 0.14732)
		(layer "In6.Cu")
		(net "UPI_CPU0_CPU1_P0P1_DP<10>")
	)
	(segment
		(start 130.996436 -199.934322)
		(end 130.720592 -200.273412)
		(width 0.14732)
		(layer "In6.Cu")
		(net "UPI_CPU0_CPU1_P0P1_DP<10>")
	)
	(segment
		(start 130.012186 -201.144632)
		(end 129.83718 -201.162666)
		(width 0.14732)
		(layer "In6.Cu")
		(net "UPI_CPU0_CPU1_P0P1_DP<10>")
	)
	(segment
		(start 125.832108 -212.164676)
		(end 125.931422 -212.26399)
		(width 0.0889)
		(layer "In6.Cu")
		(net "UPI_CPU0_CPU1_P0P1_DP<10>")
	)
	(segment
		(start 312.530744 -180.240178)
		(end 301.879508 -180.044344)
		(width 0.14732)
		(layer "In6.Cu")
		(net "UPI_CPU0_CPU1_P0P1_DP<10>")
	)
	(segment
		(start 238.625634 -180.904896)
		(end 211.913216 -180.904896)
		(width 0.14732)
		(layer "In6.Cu")
		(net "UPI_CPU0_CPU1_P0P1_DP<10>")
	)
	(segment
		(start 179.731416 -180.762656)
		(end 158.728664 -181.111144)
		(width 0.14732)
		(layer "In6.Cu")
		(net "UPI_CPU0_CPU1_P0P1_DP<10>")
	)
	(segment
		(start 346.286074 -211.66201)
		(end 346.286074 -211.537296)
		(width 0.14732)
		(layer "In6.Cu")
		(net "UPI_CPU0_CPU1_P0P1_DP<10>")
	)
	(segment
		(start 129.56159 -201.501502)
		(end 129.579624 -201.676508)
		(width 0.14732)
		(layer "In6.Cu")
		(net "UPI_CPU0_CPU1_P0P1_DP<10>")
	)
	(segment
		(start 125.874272 -211.625688)
		(end 125.832108 -211.667852)
		(width 0.0889)
		(layer "In6.Cu")
		(net "UPI_CPU0_CPU1_P0P1_DP<10>")
	)
	(segment
		(start 211.913216 -180.904896)
		(end 200.734676 -180.413914)
		(width 0.14732)
		(layer "In6.Cu")
		(net "UPI_CPU0_CPU1_P0P1_DP<10>")
	)
	(segment
		(start 316.364112 -181.327044)
		(end 312.530744 -180.240178)
		(width 0.14732)
		(layer "In6.Cu")
		(net "UPI_CPU0_CPU1_P0P1_DP<10>")
	)
	(segment
		(start 346.22867 -213.12251)
		(end 346.327984 -213.023196)
		(width 0.0889)
		(layer "In6.Cu")
		(net "UPI_CPU0_CPU1_P0P1_DP<10>")
	)
	(segment
		(start 125.546358 -214.2617)
		(end 125.546612 -214.261954)
		(width 0.0889)
		(layer "In6.Cu")
		(net "UPI_CPU0_CPU1_P0P1_DP<10>")
	)
	(segment
		(start 320.454528 -183.889142)
		(end 320.142616 -183.693816)
		(width 0.14732)
		(layer "In6.Cu")
		(net "UPI_CPU0_CPU1_P0P1_DP<10>")
	)
	(segment
		(start 345.953334 -213.732618)
		(end 346.112084 -214.033608)
		(width 0.0889)
		(layer "In6.Cu")
		(net "UPI_CPU0_CPU1_P0P1_DP<10>")
	)
	(segment
		(start 130.28803 -200.805542)
		(end 130.012186 -201.144632)
		(width 0.14732)
		(layer "In6.Cu")
		(net "UPI_CPU0_CPU1_P0P1_DP<10>")
	)
	(segment
		(start 320.142616 -183.693816)
		(end 319.943226 -183.739536)
		(width 0.14732)
		(layer "In6.Cu")
		(net "UPI_CPU0_CPU1_P0P1_DP<10>")
	)
	(segment
		(start 301.879508 -180.044344)
		(end 273.190462 -180.74005)
		(width 0.14732)
		(layer "In6.Cu")
		(net "UPI_CPU0_CPU1_P0P1_DP<10>")
	)
	(segment
		(start 143.995902 -186.955176)
		(end 139.629388 -192.816226)
		(width 0.14732)
		(layer "In6.Cu")
		(net "UPI_CPU0_CPU1_P0P1_DP<10>")
	)
	(segment
		(start 346.22867 -212.657182)
		(end 346.22867 -212.390482)
		(width 0.0889)
		(layer "In6.Cu")
		(net "UPI_CPU0_CPU1_P0P1_DP<10>")
	)
	(segment
		(start 346.112084 -214.033608)
		(end 346.196666 -214.05977)
		(width 0.0889)
		(layer "In6.Cu")
		(net "UPI_CPU0_CPU1_P0P1_DP<10>")
	)
	(segment
		(start 346.28582 -210.589368)
		(end 345.426284 -202.46213)
		(width 0.14732)
		(layer "In6.Cu")
		(net "UPI_CPU0_CPU1_P0P1_DP<10>")
	)
	(segment
		(start 200.734676 -180.413914)
		(end 179.73167 -180.762656)
		(width 0.14732)
		(layer "In6.Cu")
		(net "UPI_CPU0_CPU1_P0P1_DP<10>")
	)
	(segment
		(start 327.055988 -190.3476)
		(end 323.030342 -186.506612)
		(width 0.14732)
		(layer "In6.Cu")
		(net "UPI_CPU0_CPU1_P0P1_DP<10>")
	)
	(segment
		(start 322.419218 -185.907426)
		(end 322.203572 -185.608468)
		(width 0.14732)
		(layer "In6.Cu")
		(net "UPI_CPU0_CPU1_P0P1_DP<10>")
	)
	(segment
		(start 346.327984 -213.8934)
		(end 346.327984 -213.488524)
		(width 0.0889)
		(layer "In6.Cu")
		(net "UPI_CPU0_CPU1_P0P1_DP<10>")
	)
	(segment
		(start 346.327984 -211.726018)
		(end 346.286074 -211.684108)
		(width 0.0889)
		(layer "In6.Cu")
		(net "UPI_CPU0_CPU1_P0P1_DP<10>")
	)
	(segment
		(start 125.874272 -211.60359)
		(end 125.874272 -211.625688)
		(width 0.0889)
		(layer "In6.Cu")
		(net "UPI_CPU0_CPU1_P0P1_DP<10>")
	)
	(segment
		(start 125.580394 -214.893652)
		(end 125.736858 -214.622634)
		(width 0.0889)
		(layer "In6.Cu")
		(net "UPI_CPU0_CPU1_P0P1_DP<10>")
	)
	(segment
		(start 319.630806 -183.54421)
		(end 319.584832 -183.344312)
		(width 0.14732)
		(layer "In6.Cu")
		(net "UPI_CPU0_CPU1_P0P1_DP<10>")
	)
	(segment
		(start 321.012312 -184.238646)
		(end 320.812922 -184.284366)
		(width 0.14732)
		(layer "In6.Cu")
		(net "UPI_CPU0_CPU1_P0P1_DP<10>")
	)
	(segment
		(start 345.426284 -202.46213)
		(end 344.655902 -201.51344)
		(width 0.14732)
		(layer "In6.Cu")
		(net "UPI_CPU0_CPU1_P0P1_DP<10>")
	)
	(arc
		(start 125.546612 -214.261954)
		(mid 125.437216 -214.346051)
		(end 125.362208 -214.461852)
		(width 0.0889)
		(layer "In6.Cu")
		(net "UPI_CPU0_CPU1_P0P1_DP<10>")
	)
	(arc
		(start 125.832108 -213.929722)
		(mid 125.720709 -214.1228)
		(end 125.546358 -214.2617)
		(width 0.0889)
		(layer "In6.Cu")
		(net "UPI_CPU0_CPU1_P0P1_DP<10>")
	)
	(arc
		(start 346.196666 -214.05977)
		(mid 346.273339 -213.985276)
		(end 346.327984 -213.8934)
		(width 0.0889)
		(layer "In6.Cu")
		(net "UPI_CPU0_CPU1_P0P1_DP<10>")
	)
	(arc
		(start 125.362208 -214.622634)
		(mid 125.399068 -214.784431)
		(end 125.502162 -214.91448)
		(width 0.0889)
		(layer "In6.Cu")
		(net "UPI_CPU0_CPU1_P0P1_DP<10>")
	)
	(segment
		(start 336.555334 -215.972644)
		(end 336.555334 -215.436958)
		(width 0.13208)
		(layer "F.Cu")
		(net "UPI_CPU0_CPU1_P0P1_DP<0>")
	)
	(segment
		(start 336.555334 -215.436958)
		(end 336.55508 -215.436704)
		(width 0.13208)
		(layer "F.Cu")
		(net "UPI_CPU0_CPU1_P0P1_DP<0>")
	)
	(segment
		(start 135.605266 -215.972644)
		(end 135.605266 -215.436958)
		(width 0.13208)
		(layer "F.Cu")
		(net "UPI_CPU0_CPU1_P0P1_DP<0>")
	)
	(segment
		(start 135.605266 -215.436958)
		(end 135.605012 -215.436704)
		(width 0.13208)
		(layer "F.Cu")
		(net "UPI_CPU0_CPU1_P0P1_DP<0>")
	)
	(segment
		(start 139.37742 -210.827874)
		(end 139.117578 -211.089494)
		(width 0.14732)
		(layer "In6.Cu")
		(net "UPI_CPU0_CPU1_P0P1_DP<0>")
	)
	(segment
		(start 151.744426 -198.732394)
		(end 151.169116 -199.313038)
		(width 0.14732)
		(layer "In6.Cu")
		(net "UPI_CPU0_CPU1_P0P1_DP<0>")
	)
	(segment
		(start 148.021548 -201.134726)
		(end 148.479002 -201.58837)
		(width 0.14732)
		(layer "In6.Cu")
		(net "UPI_CPU0_CPU1_P0P1_DP<0>")
	)
	(segment
		(start 137.926318 -212.289136)
		(end 137.666476 -212.550756)
		(width 0.14732)
		(layer "In6.Cu")
		(net "UPI_CPU0_CPU1_P0P1_DP<0>")
	)
	(segment
		(start 330.740766 -207.120998)
		(end 330.29398 -207.69072)
		(width 0.14732)
		(layer "In6.Cu")
		(net "UPI_CPU0_CPU1_P0P1_DP<0>")
	)
	(segment
		(start 298.014644 -191.608456)
		(end 286.504126 -191.558926)
		(width 0.14732)
		(layer "In6.Cu")
		(net "UPI_CPU0_CPU1_P0P1_DP<0>")
	)
	(segment
		(start 286.504126 -191.55918)
		(end 261.248398 -192.566036)
		(width 0.14732)
		(layer "In6.Cu")
		(net "UPI_CPU0_CPU1_P0P1_DP<0>")
	)
	(segment
		(start 308.565804 -191.019684)
		(end 305.184048 -190.913258)
		(width 0.14732)
		(layer "In6.Cu")
		(net "UPI_CPU0_CPU1_P0P1_DP<0>")
	)
	(segment
		(start 336.826098 -212.79866)
		(end 336.826098 -212.53196)
		(width 0.0889)
		(layer "In6.Cu")
		(net "UPI_CPU0_CPU1_P0P1_DP<0>")
	)
	(segment
		(start 250.71705 -195.37553)
		(end 239.388904 -200.55967)
		(width 0.14732)
		(layer "In6.Cu")
		(net "UPI_CPU0_CPU1_P0P1_DP<0>")
	)
	(segment
		(start 332.56474 -208.550764)
		(end 332.117954 -209.120486)
		(width 0.14732)
		(layer "In6.Cu")
		(net "UPI_CPU0_CPU1_P0P1_DP<0>")
	)
	(segment
		(start 143.58493 -206.960724)
		(end 142.811246 -207.740758)
		(width 0.14732)
		(layer "In6.Cu")
		(net "UPI_CPU0_CPU1_P0P1_DP<0>")
	)
	(segment
		(start 148.644356 -200.506584)
		(end 148.436584 -200.5076)
		(width 0.14732)
		(layer "In6.Cu")
		(net "UPI_CPU0_CPU1_P0P1_DP<0>")
	)
	(segment
		(start 334.595216 -209.955384)
		(end 334.388714 -209.98053)
		(width 0.14732)
		(layer "In6.Cu")
		(net "UPI_CPU0_CPU1_P0P1_DP<0>")
	)
	(segment
		(start 332.865984 -210.097624)
		(end 332.81366 -209.665824)
		(width 0.14732)
		(layer "In6.Cu")
		(net "UPI_CPU0_CPU1_P0P1_DP<0>")
	)
	(segment
		(start 135.448802 -215.089486)
		(end 135.605012 -215.436704)
		(width 0.0889)
		(layer "In6.Cu")
		(net "UPI_CPU0_CPU1_P0P1_DP<0>")
	)
	(segment
		(start 150.276306 -198.860918)
		(end 150.068534 -198.861934)
		(width 0.14732)
		(layer "In6.Cu")
		(net "UPI_CPU0_CPU1_P0P1_DP<0>")
	)
	(segment
		(start 336.459576 -213.89721)
		(end 336.826098 -213.530688)
		(width 0.0889)
		(layer "In6.Cu")
		(net "UPI_CPU0_CPU1_P0P1_DP<0>")
	)
	(segment
		(start 336.726784 -212.897974)
		(end 336.826098 -212.79866)
		(width 0.0889)
		(layer "In6.Cu")
		(net "UPI_CPU0_CPU1_P0P1_DP<0>")
	)
	(segment
		(start 156.716984 -193.123566)
		(end 155.070302 -194.784726)
		(width 0.14732)
		(layer "In6.Cu")
		(net "UPI_CPU0_CPU1_P0P1_DP<0>")
	)
	(segment
		(start 151.700484 -197.216268)
		(end 151.284432 -197.635622)
		(width 0.14732)
		(layer "In6.Cu")
		(net "UPI_CPU0_CPU1_P0P1_DP<0>")
	)
	(segment
		(start 336.826098 -213.530688)
		(end 336.826098 -213.263988)
		(width 0.0889)
		(layer "In6.Cu")
		(net "UPI_CPU0_CPU1_P0P1_DP<0>")
	)
	(segment
		(start 147.46986 -202.605894)
		(end 147.012406 -202.15225)
		(width 0.14732)
		(layer "In6.Cu")
		(net "UPI_CPU0_CPU1_P0P1_DP<0>")
	)
	(segment
		(start 137.20318 -213.017354)
		(end 136.943338 -213.278974)
		(width 0.14732)
		(layer "In6.Cu")
		(net "UPI_CPU0_CPU1_P0P1_DP<0>")
	)
	(segment
		(start 138.65352 -211.351368)
		(end 138.654282 -211.556092)
		(width 0.14732)
		(layer "In6.Cu")
		(net "UPI_CPU0_CPU1_P0P1_DP<0>")
	)
	(segment
		(start 136.47928 -213.540848)
		(end 136.463786 -213.556342)
		(width 0.0889)
		(layer "In6.Cu")
		(net "UPI_CPU0_CPU1_P0P1_DP<0>")
	)
	(segment
		(start 148.020532 -200.926954)
		(end 148.021548 -201.134726)
		(width 0.14732)
		(layer "In6.Cu")
		(net "UPI_CPU0_CPU1_P0P1_DP<0>")
	)
	(segment
		(start 312.421524 -191.912494)
		(end 308.565804 -191.019684)
		(width 0.14732)
		(layer "In6.Cu")
		(net "UPI_CPU0_CPU1_P0P1_DP<0>")
	)
	(segment
		(start 135.472932 -215.000332)
		(end 135.448802 -215.089486)
		(width 0.0889)
		(layer "In6.Cu")
		(net "UPI_CPU0_CPU1_P0P1_DP<0>")
	)
	(segment
		(start 329.612498 -206.23657)
		(end 329.587352 -206.030068)
		(width 0.14732)
		(layer "In6.Cu")
		(net "UPI_CPU0_CPU1_P0P1_DP<0>")
	)
	(segment
		(start 331.04201 -208.667858)
		(end 330.989686 -208.236058)
		(width 0.14732)
		(layer "In6.Cu")
		(net "UPI_CPU0_CPU1_P0P1_DP<0>")
	)
	(segment
		(start 141.831314 -208.152238)
		(end 140.100558 -209.894932)
		(width 0.14732)
		(layer "In6.Cu")
		(net "UPI_CPU0_CPU1_P0P1_DP<0>")
	)
	(segment
		(start 336.711544 -215.707722)
		(end 336.789776 -215.72855)
		(width 0.0889)
		(layer "In6.Cu")
		(net "UPI_CPU0_CPU1_P0P1_DP<0>")
	)
	(segment
		(start 145.380456 -203.797916)
		(end 145.172684 -203.798932)
		(width 0.14732)
		(layer "In6.Cu")
		(net "UPI_CPU0_CPU1_P0P1_DP<0>")
	)
	(segment
		(start 141.831314 -208.151984)
		(end 141.831314 -208.152238)
		(width 0.14732)
		(layer "In6.Cu")
		(net "UPI_CPU0_CPU1_P0P1_DP<0>")
	)
	(segment
		(start 301.521876 -190.958724)
		(end 301.452026 -190.24219)
		(width 0.14732)
		(layer "In6.Cu")
		(net "UPI_CPU0_CPU1_P0P1_DP<0>")
	)
	(segment
		(start 137.925556 -212.084412)
		(end 137.926318 -212.289136)
		(width 0.14732)
		(layer "In6.Cu")
		(net "UPI_CPU0_CPU1_P0P1_DP<0>")
	)
	(segment
		(start 239.388904 -200.55967)
		(end 237.415324 -200.805796)
		(width 0.14732)
		(layer "In6.Cu")
		(net "UPI_CPU0_CPU1_P0P1_DP<0>")
	)
	(segment
		(start 146.389598 -202.780392)
		(end 146.847052 -203.234036)
		(width 0.14732)
		(layer "In6.Cu")
		(net "UPI_CPU0_CPU1_P0P1_DP<0>")
	)
	(segment
		(start 330.29398 -207.69072)
		(end 329.86218 -207.743044)
		(width 0.14732)
		(layer "In6.Cu")
		(net "UPI_CPU0_CPU1_P0P1_DP<0>")
	)
	(segment
		(start 145.216626 -205.315058)
		(end 144.641316 -205.895702)
		(width 0.14732)
		(layer "In6.Cu")
		(net "UPI_CPU0_CPU1_P0P1_DP<0>")
	)
	(segment
		(start 336.826098 -211.726018)
		(end 336.784188 -211.684108)
		(width 0.0889)
		(layer "In6.Cu")
		(net "UPI_CPU0_CPU1_P0P1_DP<0>")
	)
	(segment
		(start 336.826098 -212.53196)
		(end 336.726784 -212.432646)
		(width 0.0889)
		(layer "In6.Cu")
		(net "UPI_CPU0_CPU1_P0P1_DP<0>")
	)
	(segment
		(start 136.463786 -213.556342)
		(end 136.404858 -213.556342)
		(width 0.0889)
		(layer "In6.Cu")
		(net "UPI_CPU0_CPU1_P0P1_DP<0>")
	)
	(segment
		(start 137.92581 -212.084412)
		(end 137.925556 -212.084412)
		(width 0.14732)
		(layer "In6.Cu")
		(net "UPI_CPU0_CPU1_P0P1_DP<0>")
	)
	(segment
		(start 147.905216 -202.60437)
		(end 147.46986 -202.605894)
		(width 0.14732)
		(layer "In6.Cu")
		(net "UPI_CPU0_CPU1_P0P1_DP<0>")
	)
	(segment
		(start 336.726784 -213.164674)
		(end 336.726784 -212.897974)
		(width 0.0889)
		(layer "In6.Cu")
		(net "UPI_CPU0_CPU1_P0P1_DP<0>")
	)
	(segment
		(start 139.636246 -210.362038)
		(end 139.376912 -210.62315)
		(width 0.14732)
		(layer "In6.Cu")
		(net "UPI_CPU0_CPU1_P0P1_DP<0>")
	)
	(segment
		(start 329.587352 -206.030068)
		(end 314.560712 -194.252088)
		(width 0.14732)
		(layer "In6.Cu")
		(net "UPI_CPU0_CPU1_P0P1_DP<0>")
	)
	(segment
		(start 151.742902 -198.297038)
		(end 151.744426 -198.732394)
		(width 0.14732)
		(layer "In6.Cu")
		(net "UPI_CPU0_CPU1_P0P1_DP<0>")
	)
	(segment
		(start 138.913108 -211.09051)
		(end 138.653774 -211.351368)
		(width 0.14732)
		(layer "In6.Cu")
		(net "UPI_CPU0_CPU1_P0P1_DP<0>")
	)
	(segment
		(start 286.504126 -191.558926)
		(end 286.504126 -191.55918)
		(width 0.14732)
		(layer "In6.Cu")
		(net "UPI_CPU0_CPU1_P0P1_DP<0>")
	)
	(segment
		(start 139.376912 -210.62315)
		(end 139.37742 -210.827874)
		(width 0.14732)
		(layer "In6.Cu")
		(net "UPI_CPU0_CPU1_P0P1_DP<0>")
	)
	(segment
		(start 312.421778 -191.912494)
		(end 312.421778 -191.912748)
		(width 0.14732)
		(layer "In6.Cu")
		(net "UPI_CPU0_CPU1_P0P1_DP<0>")
	)
	(segment
		(start 329.86218 -207.743044)
		(end 329.218036 -207.238092)
		(width 0.14732)
		(layer "In6.Cu")
		(net "UPI_CPU0_CPU1_P0P1_DP<0>")
	)
	(segment
		(start 330.947268 -207.095852)
		(end 330.740766 -207.120998)
		(width 0.14732)
		(layer "In6.Cu")
		(net "UPI_CPU0_CPU1_P0P1_DP<0>")
	)
	(segment
		(start 143.583152 -206.525368)
		(end 143.58493 -206.960724)
		(width 0.14732)
		(layer "In6.Cu")
		(net "UPI_CPU0_CPU1_P0P1_DP<0>")
	)
	(segment
		(start 145.215102 -204.879702)
		(end 145.216626 -205.315058)
		(width 0.14732)
		(layer "In6.Cu")
		(net "UPI_CPU0_CPU1_P0P1_DP<0>")
	)
	(segment
		(start 138.912854 -211.090256)
		(end 138.913108 -211.09051)
		(width 0.14732)
		(layer "In6.Cu")
		(net "UPI_CPU0_CPU1_P0P1_DP<0>")
	)
	(segment
		(start 143.124682 -205.863952)
		(end 143.125698 -206.071724)
		(width 0.14732)
		(layer "In6.Cu")
		(net "UPI_CPU0_CPU1_P0P1_DP<0>")
	)
	(segment
		(start 335.271872 -210.485736)
		(end 334.595216 -209.955384)
		(width 0.14732)
		(layer "In6.Cu")
		(net "UPI_CPU0_CPU1_P0P1_DP<0>")
	)
	(segment
		(start 333.941928 -210.550252)
		(end 333.510128 -210.602576)
		(width 0.14732)
		(layer "In6.Cu")
		(net "UPI_CPU0_CPU1_P0P1_DP<0>")
	)
	(segment
		(start 305.184048 -190.913258)
		(end 301.857918 -191.236092)
		(width 0.14732)
		(layer "In6.Cu")
		(net "UPI_CPU0_CPU1_P0P1_DP<0>")
	)
	(segment
		(start 139.117578 -211.089494)
		(end 138.912854 -211.090256)
		(width 0.14732)
		(layer "In6.Cu")
		(net "UPI_CPU0_CPU1_P0P1_DP<0>")
	)
	(segment
		(start 219.986352 -193.295778)
		(end 208.431384 -191.430148)
		(width 0.14732)
		(layer "In6.Cu")
		(net "UPI_CPU0_CPU1_P0P1_DP<0>")
	)
	(segment
		(start 300.641766 -191.044576)
		(end 300.364398 -191.380618)
		(width 0.14732)
		(layer "In6.Cu")
		(net "UPI_CPU0_CPU1_P0P1_DP<0>")
	)
	(segment
		(start 333.2353 -208.8896)
		(end 332.771242 -208.525618)
		(width 0.14732)
		(layer "In6.Cu")
		(net "UPI_CPU0_CPU1_P0P1_DP<0>")
	)
	(segment
		(start 336.726784 -212.165946)
		(end 336.826098 -212.066632)
		(width 0.0889)
		(layer "In6.Cu")
		(net "UPI_CPU0_CPU1_P0P1_DP<0>")
	)
	(segment
		(start 329.165712 -206.806292)
		(end 329.612498 -206.23657)
		(width 0.14732)
		(layer "In6.Cu")
		(net "UPI_CPU0_CPU1_P0P1_DP<0>")
	)
	(segment
		(start 312.58256 -192.006728)
		(end 312.421778 -191.912494)
		(width 0.14732)
		(layer "In6.Cu")
		(net "UPI_CPU0_CPU1_P0P1_DP<0>")
	)
	(segment
		(start 332.81366 -209.665824)
		(end 333.260446 -209.096102)
		(width 0.14732)
		(layer "In6.Cu")
		(net "UPI_CPU0_CPU1_P0P1_DP<0>")
	)
	(segment
		(start 336.784188 -211.684108)
		(end 336.784188 -211.66201)
		(width 0.0889)
		(layer "In6.Cu")
		(net "UPI_CPU0_CPU1_P0P1_DP<0>")
	)
	(segment
		(start 331.436472 -207.666336)
		(end 331.411326 -207.459834)
		(width 0.14732)
		(layer "In6.Cu")
		(net "UPI_CPU0_CPU1_P0P1_DP<0>")
	)
	(segment
		(start 151.169116 -199.313038)
		(end 150.73376 -199.314562)
		(width 0.14732)
		(layer "In6.Cu")
		(net "UPI_CPU0_CPU1_P0P1_DP<0>")
	)
	(segment
		(start 336.784188 -211.66201)
		(end 336.784188 -211.537296)
		(width 0.14732)
		(layer "In6.Cu")
		(net "UPI_CPU0_CPU1_P0P1_DP<0>")
	)
	(segment
		(start 336.726784 -212.432646)
		(end 336.726784 -212.165946)
		(width 0.0889)
		(layer "In6.Cu")
		(net "UPI_CPU0_CPU1_P0P1_DP<0>")
	)
	(segment
		(start 146.273266 -204.250036)
		(end 145.83791 -204.25156)
		(width 0.14732)
		(layer "In6.Cu")
		(net "UPI_CPU0_CPU1_P0P1_DP<0>")
	)
	(segment
		(start 336.783934 -211.53755)
		(end 336.783934 -211.376514)
		(width 0.14732)
		(layer "In6.Cu")
		(net "UPI_CPU0_CPU1_P0P1_DP<0>")
	)
	(segment
		(start 143.125698 -206.071724)
		(end 143.583152 -206.525368)
		(width 0.14732)
		(layer "In6.Cu")
		(net "UPI_CPU0_CPU1_P0P1_DP<0>")
	)
	(segment
		(start 149.653498 -199.48906)
		(end 150.110952 -199.942704)
		(width 0.14732)
		(layer "In6.Cu")
		(net "UPI_CPU0_CPU1_P0P1_DP<0>")
	)
	(segment
		(start 208.431384 -191.430148)
		(end 190.284862 -192.164462)
		(width 0.14732)
		(layer "In6.Cu")
		(net "UPI_CPU0_CPU1_P0P1_DP<0>")
	)
	(segment
		(start 261.248398 -192.566036)
		(end 250.71705 -195.37553)
		(width 0.14732)
		(layer "In6.Cu")
		(net "UPI_CPU0_CPU1_P0P1_DP<0>")
	)
	(segment
		(start 336.55508 -215.436704)
		(end 336.711544 -215.707722)
		(width 0.0889)
		(layer "In6.Cu")
		(net "UPI_CPU0_CPU1_P0P1_DP<0>")
	)
	(segment
		(start 150.112476 -200.37806)
		(end 149.537166 -200.958704)
		(width 0.14732)
		(layer "In6.Cu")
		(net "UPI_CPU0_CPU1_P0P1_DP<0>")
	)
	(segment
		(start 300.57217 -190.327534)
		(end 300.641766 -191.044576)
		(width 0.14732)
		(layer "In6.Cu")
		(net "UPI_CPU0_CPU1_P0P1_DP<0>")
	)
	(segment
		(start 151.285448 -197.843394)
		(end 151.742902 -198.297038)
		(width 0.14732)
		(layer "In6.Cu")
		(net "UPI_CPU0_CPU1_P0P1_DP<0>")
	)
	(segment
		(start 232.564178 -199.969628)
		(end 219.986352 -193.295778)
		(width 0.14732)
		(layer "In6.Cu")
		(net "UPI_CPU0_CPU1_P0P1_DP<0>")
	)
	(segment
		(start 336.783934 -211.376514)
		(end 336.332576 -210.925156)
		(width 0.14732)
		(layer "In6.Cu")
		(net "UPI_CPU0_CPU1_P0P1_DP<0>")
	)
	(segment
		(start 151.908256 -197.215252)
		(end 151.700484 -197.216268)
		(width 0.14732)
		(layer "In6.Cu")
		(net "UPI_CPU0_CPU1_P0P1_DP<0>")
	)
	(segment
		(start 312.421778 -191.912748)
		(end 312.421524 -191.912494)
		(width 0.14732)
		(layer "In6.Cu")
		(net "UPI_CPU0_CPU1_P0P1_DP<0>")
	)
	(segment
		(start 146.388582 -202.57262)
		(end 146.389598 -202.780392)
		(width 0.14732)
		(layer "In6.Cu")
		(net "UPI_CPU0_CPU1_P0P1_DP<0>")
	)
	(segment
		(start 150.068534 -198.861934)
		(end 149.652482 -199.281288)
		(width 0.14732)
		(layer "In6.Cu")
		(net "UPI_CPU0_CPU1_P0P1_DP<0>")
	)
	(segment
		(start 140.100812 -210.099656)
		(end 139.84097 -210.361276)
		(width 0.14732)
		(layer "In6.Cu")
		(net "UPI_CPU0_CPU1_P0P1_DP<0>")
	)
	(segment
		(start 157.884368 -192.530222)
		(end 156.716984 -193.123566)
		(width 0.14732)
		(layer "In6.Cu")
		(net "UPI_CPU0_CPU1_P0P1_DP<0>")
	)
	(segment
		(start 151.284432 -197.635622)
		(end 151.285448 -197.843394)
		(width 0.14732)
		(layer "In6.Cu")
		(net "UPI_CPU0_CPU1_P0P1_DP<0>")
	)
	(segment
		(start 138.18997 -211.818728)
		(end 137.92581 -212.084412)
		(width 0.14732)
		(layer "In6.Cu")
		(net "UPI_CPU0_CPU1_P0P1_DP<0>")
	)
	(segment
		(start 152.36571 -197.668896)
		(end 151.908256 -197.215252)
		(width 0.14732)
		(layer "In6.Cu")
		(net "UPI_CPU0_CPU1_P0P1_DP<0>")
	)
	(segment
		(start 336.459576 -214.636858)
		(end 336.459576 -213.89721)
		(width 0.0889)
		(layer "In6.Cu")
		(net "UPI_CPU0_CPU1_P0P1_DP<0>")
	)
	(segment
		(start 144.20596 -205.897226)
		(end 143.748506 -205.443582)
		(width 0.14732)
		(layer "In6.Cu")
		(net "UPI_CPU0_CPU1_P0P1_DP<0>")
	)
	(segment
		(start 336.826098 -213.263988)
		(end 336.726784 -213.164674)
		(width 0.0889)
		(layer "In6.Cu")
		(net "UPI_CPU0_CPU1_P0P1_DP<0>")
	)
	(segment
		(start 149.652482 -199.281288)
		(end 149.653498 -199.48906)
		(width 0.14732)
		(layer "In6.Cu")
		(net "UPI_CPU0_CPU1_P0P1_DP<0>")
	)
	(segment
		(start 329.218036 -207.238092)
		(end 329.165712 -206.806292)
		(width 0.14732)
		(layer "In6.Cu")
		(net "UPI_CPU0_CPU1_P0P1_DP<0>")
	)
	(segment
		(start 333.510128 -210.602576)
		(end 332.865984 -210.097624)
		(width 0.14732)
		(layer "In6.Cu")
		(net "UPI_CPU0_CPU1_P0P1_DP<0>")
	)
	(segment
		(start 136.404858 -213.556342)
		(end 135.700008 -214.261192)
		(width 0.0889)
		(layer "In6.Cu")
		(net "UPI_CPU0_CPU1_P0P1_DP<0>")
	)
	(segment
		(start 142.811246 -207.740758)
		(end 141.831314 -208.151984)
		(width 0.14732)
		(layer "In6.Cu")
		(net "UPI_CPU0_CPU1_P0P1_DP<0>")
	)
	(segment
		(start 146.804634 -202.153266)
		(end 146.388582 -202.57262)
		(width 0.14732)
		(layer "In6.Cu")
		(net "UPI_CPU0_CPU1_P0P1_DP<0>")
	)
	(segment
		(start 301.292006 -190.11011)
		(end 300.70425 -190.167006)
		(width 0.14732)
		(layer "In6.Cu")
		(net "UPI_CPU0_CPU1_P0P1_DP<0>")
	)
	(segment
		(start 150.110952 -199.942704)
		(end 150.112476 -200.37806)
		(width 0.14732)
		(layer "In6.Cu")
		(net "UPI_CPU0_CPU1_P0P1_DP<0>")
	)
	(segment
		(start 149.10181 -200.960228)
		(end 148.644356 -200.506584)
		(width 0.14732)
		(layer "In6.Cu")
		(net "UPI_CPU0_CPU1_P0P1_DP<0>")
	)
	(segment
		(start 144.757648 -204.426058)
		(end 145.215102 -204.879702)
		(width 0.14732)
		(layer "In6.Cu")
		(net "UPI_CPU0_CPU1_P0P1_DP<0>")
	)
	(segment
		(start 160.013904 -191.759078)
		(end 157.884368 -192.530222)
		(width 0.14732)
		(layer "In6.Cu")
		(net "UPI_CPU0_CPU1_P0P1_DP<0>")
	)
	(segment
		(start 336.332576 -210.925156)
		(end 335.271872 -210.485736)
		(width 0.14732)
		(layer "In6.Cu")
		(net "UPI_CPU0_CPU1_P0P1_DP<0>")
	)
	(segment
		(start 136.943338 -213.278974)
		(end 136.738614 -213.279736)
		(width 0.14732)
		(layer "In6.Cu")
		(net "UPI_CPU0_CPU1_P0P1_DP<0>")
	)
	(segment
		(start 138.653774 -211.351368)
		(end 138.65352 -211.351368)
		(width 0.14732)
		(layer "In6.Cu")
		(net "UPI_CPU0_CPU1_P0P1_DP<0>")
	)
	(segment
		(start 143.540734 -205.444598)
		(end 143.124682 -205.863952)
		(width 0.14732)
		(layer "In6.Cu")
		(net "UPI_CPU0_CPU1_P0P1_DP<0>")
	)
	(segment
		(start 148.436584 -200.5076)
		(end 148.020532 -200.926954)
		(width 0.14732)
		(layer "In6.Cu")
		(net "UPI_CPU0_CPU1_P0P1_DP<0>")
	)
	(segment
		(start 300.70425 -190.167006)
		(end 300.57217 -190.327534)
		(width 0.14732)
		(layer "In6.Cu")
		(net "UPI_CPU0_CPU1_P0P1_DP<0>")
	)
	(segment
		(start 301.452026 -190.24219)
		(end 301.292006 -190.11011)
		(width 0.14732)
		(layer "In6.Cu")
		(net "UPI_CPU0_CPU1_P0P1_DP<0>")
	)
	(segment
		(start 331.686154 -209.17281)
		(end 331.04201 -208.667858)
		(width 0.14732)
		(layer "In6.Cu")
		(net "UPI_CPU0_CPU1_P0P1_DP<0>")
	)
	(segment
		(start 331.411326 -207.459834)
		(end 330.947268 -207.095852)
		(width 0.14732)
		(layer "In6.Cu")
		(net "UPI_CPU0_CPU1_P0P1_DP<0>")
	)
	(segment
		(start 146.847052 -203.234036)
		(end 146.848576 -203.669392)
		(width 0.14732)
		(layer "In6.Cu")
		(net "UPI_CPU0_CPU1_P0P1_DP<0>")
	)
	(segment
		(start 138.39444 -211.817712)
		(end 138.189716 -211.818474)
		(width 0.14732)
		(layer "In6.Cu")
		(net "UPI_CPU0_CPU1_P0P1_DP<0>")
	)
	(segment
		(start 137.202418 -212.81263)
		(end 137.20318 -213.017354)
		(width 0.14732)
		(layer "In6.Cu")
		(net "UPI_CPU0_CPU1_P0P1_DP<0>")
	)
	(segment
		(start 144.756632 -204.218286)
		(end 144.757648 -204.426058)
		(width 0.14732)
		(layer "In6.Cu")
		(net "UPI_CPU0_CPU1_P0P1_DP<0>")
	)
	(segment
		(start 136.738614 -213.279736)
		(end 136.47928 -213.540848)
		(width 0.14732)
		(layer "In6.Cu")
		(net "UPI_CPU0_CPU1_P0P1_DP<0>")
	)
	(segment
		(start 150.73376 -199.314562)
		(end 150.276306 -198.860918)
		(width 0.14732)
		(layer "In6.Cu")
		(net "UPI_CPU0_CPU1_P0P1_DP<0>")
	)
	(segment
		(start 152.80132 -197.667372)
		(end 152.36571 -197.668896)
		(width 0.14732)
		(layer "In6.Cu")
		(net "UPI_CPU0_CPU1_P0P1_DP<0>")
	)
	(segment
		(start 336.784188 -211.537296)
		(end 336.783934 -211.53755)
		(width 0.14732)
		(layer "In6.Cu")
		(net "UPI_CPU0_CPU1_P0P1_DP<0>")
	)
	(segment
		(start 190.284862 -192.164462)
		(end 160.013904 -191.759078)
		(width 0.14732)
		(layer "In6.Cu")
		(net "UPI_CPU0_CPU1_P0P1_DP<0>")
	)
	(segment
		(start 155.070302 -194.784726)
		(end 154.65679 -195.795392)
		(width 0.14732)
		(layer "In6.Cu")
		(net "UPI_CPU0_CPU1_P0P1_DP<0>")
	)
	(segment
		(start 135.488934 -214.986616)
		(end 135.489696 -214.987378)
		(width 0.0889)
		(layer "In6.Cu")
		(net "UPI_CPU0_CPU1_P0P1_DP<0>")
	)
	(segment
		(start 314.560712 -194.252088)
		(end 312.58256 -192.006728)
		(width 0.14732)
		(layer "In6.Cu")
		(net "UPI_CPU0_CPU1_P0P1_DP<0>")
	)
	(segment
		(start 301.857918 -191.236092)
		(end 301.521876 -190.958724)
		(width 0.14732)
		(layer "In6.Cu")
		(net "UPI_CPU0_CPU1_P0P1_DP<0>")
	)
	(segment
		(start 149.537166 -200.958704)
		(end 149.10181 -200.960228)
		(width 0.14732)
		(layer "In6.Cu")
		(net "UPI_CPU0_CPU1_P0P1_DP<0>")
	)
	(segment
		(start 144.641316 -205.895702)
		(end 144.20596 -205.897226)
		(width 0.14732)
		(layer "In6.Cu")
		(net "UPI_CPU0_CPU1_P0P1_DP<0>")
	)
	(segment
		(start 235.923328 -200.805796)
		(end 232.564178 -199.969628)
		(width 0.14732)
		(layer "In6.Cu")
		(net "UPI_CPU0_CPU1_P0P1_DP<0>")
	)
	(segment
		(start 138.189716 -211.818474)
		(end 138.18997 -211.818728)
		(width 0.14732)
		(layer "In6.Cu")
		(net "UPI_CPU0_CPU1_P0P1_DP<0>")
	)
	(segment
		(start 137.461752 -212.551518)
		(end 137.202418 -212.81263)
		(width 0.14732)
		(layer "In6.Cu")
		(net "UPI_CPU0_CPU1_P0P1_DP<0>")
	)
	(segment
		(start 140.100558 -209.894932)
		(end 140.10005 -209.894932)
		(width 0.14732)
		(layer "In6.Cu")
		(net "UPI_CPU0_CPU1_P0P1_DP<0>")
	)
	(segment
		(start 334.388714 -209.98053)
		(end 333.941928 -210.550252)
		(width 0.14732)
		(layer "In6.Cu")
		(net "UPI_CPU0_CPU1_P0P1_DP<0>")
	)
	(segment
		(start 146.848576 -203.669392)
		(end 146.273266 -204.250036)
		(width 0.14732)
		(layer "In6.Cu")
		(net "UPI_CPU0_CPU1_P0P1_DP<0>")
	)
	(segment
		(start 147.012406 -202.15225)
		(end 146.804634 -202.153266)
		(width 0.14732)
		(layer "In6.Cu")
		(net "UPI_CPU0_CPU1_P0P1_DP<0>")
	)
	(segment
		(start 300.364398 -191.380618)
		(end 298.014644 -191.608456)
		(width 0.14732)
		(layer "In6.Cu")
		(net "UPI_CPU0_CPU1_P0P1_DP<0>")
	)
	(segment
		(start 336.751168 -215.117426)
		(end 336.742278 -215.112346)
		(width 0.0889)
		(layer "In6.Cu")
		(net "UPI_CPU0_CPU1_P0P1_DP<0>")
	)
	(segment
		(start 154.65679 -195.795392)
		(end 152.80132 -197.667372)
		(width 0.14732)
		(layer "In6.Cu")
		(net "UPI_CPU0_CPU1_P0P1_DP<0>")
	)
	(segment
		(start 148.479002 -201.58837)
		(end 148.480526 -202.023726)
		(width 0.14732)
		(layer "In6.Cu")
		(net "UPI_CPU0_CPU1_P0P1_DP<0>")
	)
	(segment
		(start 135.700008 -214.261192)
		(end 135.700008 -214.546688)
		(width 0.0889)
		(layer "In6.Cu")
		(net "UPI_CPU0_CPU1_P0P1_DP<0>")
	)
	(segment
		(start 336.826098 -212.066632)
		(end 336.826098 -211.726018)
		(width 0.0889)
		(layer "In6.Cu")
		(net "UPI_CPU0_CPU1_P0P1_DP<0>")
	)
	(segment
		(start 145.83791 -204.25156)
		(end 145.380456 -203.797916)
		(width 0.14732)
		(layer "In6.Cu")
		(net "UPI_CPU0_CPU1_P0P1_DP<0>")
	)
	(segment
		(start 332.117954 -209.120486)
		(end 331.686154 -209.17281)
		(width 0.14732)
		(layer "In6.Cu")
		(net "UPI_CPU0_CPU1_P0P1_DP<0>")
	)
	(segment
		(start 137.666476 -212.550756)
		(end 137.461752 -212.551518)
		(width 0.14732)
		(layer "In6.Cu")
		(net "UPI_CPU0_CPU1_P0P1_DP<0>")
	)
	(segment
		(start 140.10005 -209.894932)
		(end 140.100812 -210.099656)
		(width 0.14732)
		(layer "In6.Cu")
		(net "UPI_CPU0_CPU1_P0P1_DP<0>")
	)
	(segment
		(start 138.654282 -211.556092)
		(end 138.39444 -211.817712)
		(width 0.14732)
		(layer "In6.Cu")
		(net "UPI_CPU0_CPU1_P0P1_DP<0>")
	)
	(segment
		(start 148.480526 -202.023726)
		(end 147.905216 -202.60437)
		(width 0.14732)
		(layer "In6.Cu")
		(net "UPI_CPU0_CPU1_P0P1_DP<0>")
	)
	(segment
		(start 333.260446 -209.096102)
		(end 333.2353 -208.8896)
		(width 0.14732)
		(layer "In6.Cu")
		(net "UPI_CPU0_CPU1_P0P1_DP<0>")
	)
	(segment
		(start 145.172684 -203.798932)
		(end 144.756632 -204.218286)
		(width 0.14732)
		(layer "In6.Cu")
		(net "UPI_CPU0_CPU1_P0P1_DP<0>")
	)
	(segment
		(start 139.84097 -210.361276)
		(end 139.636246 -210.362038)
		(width 0.14732)
		(layer "In6.Cu")
		(net "UPI_CPU0_CPU1_P0P1_DP<0>")
	)
	(segment
		(start 332.771242 -208.525618)
		(end 332.56474 -208.550764)
		(width 0.14732)
		(layer "In6.Cu")
		(net "UPI_CPU0_CPU1_P0P1_DP<0>")
	)
	(segment
		(start 237.415324 -200.805796)
		(end 235.923328 -200.805796)
		(width 0.14732)
		(layer "In6.Cu")
		(net "UPI_CPU0_CPU1_P0P1_DP<0>")
	)
	(segment
		(start 143.748506 -205.443582)
		(end 143.540734 -205.444598)
		(width 0.14732)
		(layer "In6.Cu")
		(net "UPI_CPU0_CPU1_P0P1_DP<0>")
	)
	(segment
		(start 330.989686 -208.236058)
		(end 331.436472 -207.666336)
		(width 0.14732)
		(layer "In6.Cu")
		(net "UPI_CPU0_CPU1_P0P1_DP<0>")
	)
	(arc
		(start 135.489696 -214.987378)
		(mid 135.481374 -214.993933)
		(end 135.472932 -215.000332)
		(width 0.0889)
		(layer "In6.Cu")
		(net "UPI_CPU0_CPU1_P0P1_DP<0>")
	)
	(arc
		(start 336.742278 -215.112346)
		(mid 336.538797 -214.911542)
		(end 336.459576 -214.636858)
		(width 0.0889)
		(layer "In6.Cu")
		(net "UPI_CPU0_CPU1_P0P1_DP<0>")
	)
	(arc
		(start 336.92973 -215.436704)
		(mid 336.882051 -215.253804)
		(end 336.751168 -215.117426)
		(width 0.0889)
		(layer "In6.Cu")
		(net "UPI_CPU0_CPU1_P0P1_DP<0>")
	)
	(arc
		(start 336.789776 -215.72855)
		(mid 336.892921 -215.598525)
		(end 336.92973 -215.436704)
		(width 0.0889)
		(layer "In6.Cu")
		(net "UPI_CPU0_CPU1_P0P1_DP<0>")
	)
	(arc
		(start 135.700008 -214.546688)
		(mid 135.644394 -214.790597)
		(end 135.488934 -214.986616)
		(width 0.0889)
		(layer "In6.Cu")
		(net "UPI_CPU0_CPU1_P0P1_DP<0>")
	)
	(segment
		(start 126.207012 -213.808818)
		(end 126.207012 -213.732618)
		(width 0.13208)
		(layer "F.Cu")
		(net "UPI_CPU0_CPU1_P0P1_DN<9>")
	)
	(segment
		(start 126.207266 -214.344758)
		(end 126.207266 -213.809072)
		(width 0.13208)
		(layer "F.Cu")
		(net "UPI_CPU0_CPU1_P0P1_DN<9>")
	)
	(segment
		(start 345.48318 -215.158574)
		(end 345.48318 -214.622888)
		(width 0.13208)
		(layer "F.Cu")
		(net "UPI_CPU0_CPU1_P0P1_DN<9>")
	)
	(segment
		(start 345.48318 -214.622888)
		(end 345.482926 -214.622634)
		(width 0.13208)
		(layer "F.Cu")
		(net "UPI_CPU0_CPU1_P0P1_DN<9>")
	)
	(segment
		(start 126.207266 -213.809072)
		(end 126.207012 -213.808818)
		(width 0.13208)
		(layer "F.Cu")
		(net "UPI_CPU0_CPU1_P0P1_DN<9>")
	)
	(segment
		(start 345.677998 -212.385402)
		(end 345.578684 -212.286088)
		(width 0.0889)
		(layer "In6.Cu")
		(net "UPI_CPU0_CPU1_P0P1_DN<9>")
	)
	(segment
		(start 344.784934 -202.728322)
		(end 343.90838 -201.649076)
		(width 0.14732)
		(layer "In6.Cu")
		(net "UPI_CPU0_CPU1_P0P1_DN<9>")
	)
	(segment
		(start 126.539498 -211.465668)
		(end 126.54026 -211.46643)
		(width 0.14732)
		(layer "In6.Cu")
		(net "UPI_CPU0_CPU1_P0P1_DN<9>")
	)
	(segment
		(start 126.58217 -211.733638)
		(end 126.58217 -213.89213)
		(width 0.0889)
		(layer "In6.Cu")
		(net "UPI_CPU0_CPU1_P0P1_DN<9>")
	)
	(segment
		(start 345.482926 -214.622634)
		(end 345.326462 -214.893652)
		(width 0.0889)
		(layer "In6.Cu")
		(net "UPI_CPU0_CPU1_P0P1_DN<9>")
	)
	(segment
		(start 345.620848 -211.684108)
		(end 345.620848 -211.66201)
		(width 0.0889)
		(layer "In6.Cu")
		(net "UPI_CPU0_CPU1_P0P1_DN<9>")
	)
	(segment
		(start 126.54026 -211.66963)
		(end 126.54026 -211.691728)
		(width 0.0889)
		(layer "In6.Cu")
		(net "UPI_CPU0_CPU1_P0P1_DN<9>")
	)
	(segment
		(start 345.620594 -210.875118)
		(end 345.620594 -210.629246)
		(width 0.14732)
		(layer "In6.Cu")
		(net "UPI_CPU0_CPU1_P0P1_DN<9>")
	)
	(segment
		(start 345.578684 -212.286088)
		(end 345.578684 -211.726272)
		(width 0.0889)
		(layer "In6.Cu")
		(net "UPI_CPU0_CPU1_P0P1_DN<9>")
	)
	(segment
		(start 312.469784 -180.805836)
		(end 302.423068 -180.621178)
		(width 0.14732)
		(layer "In6.Cu")
		(net "UPI_CPU0_CPU1_P0P1_DN<9>")
	)
	(segment
		(start 345.677998 -212.652102)
		(end 345.677998 -212.385402)
		(width 0.0889)
		(layer "In6.Cu")
		(net "UPI_CPU0_CPU1_P0P1_DN<9>")
	)
	(segment
		(start 126.450344 -214.05977)
		(end 126.365762 -214.033608)
		(width 0.0889)
		(layer "In6.Cu")
		(net "UPI_CPU0_CPU1_P0P1_DN<9>")
	)
	(segment
		(start 212.424264 -181.494684)
		(end 200.608184 -180.975508)
		(width 0.14732)
		(layer "In6.Cu")
		(net "UPI_CPU0_CPU1_P0P1_DN<9>")
	)
	(segment
		(start 345.620848 -211.66201)
		(end 345.620848 -210.874864)
		(width 0.14732)
		(layer "In6.Cu")
		(net "UPI_CPU0_CPU1_P0P1_DN<9>")
	)
	(segment
		(start 152.198578 -183.38038)
		(end 144.394174 -187.3758)
		(width 0.14732)
		(layer "In6.Cu")
		(net "UPI_CPU0_CPU1_P0P1_DN<9>")
	)
	(segment
		(start 333.1591 -193.192908)
		(end 327.10374 -191.030098)
		(width 0.14732)
		(layer "In6.Cu")
		(net "UPI_CPU0_CPU1_P0P1_DN<9>")
	)
	(segment
		(start 133.820916 -197.3453)
		(end 129.34188 -202.856338)
		(width 0.14732)
		(layer "In6.Cu")
		(net "UPI_CPU0_CPU1_P0P1_DN<9>")
	)
	(segment
		(start 343.90838 -201.649076)
		(end 333.1591 -193.192908)
		(width 0.14732)
		(layer "In6.Cu")
		(net "UPI_CPU0_CPU1_P0P1_DN<9>")
	)
	(segment
		(start 140.052552 -193.203322)
		(end 133.820916 -197.3453)
		(width 0.14732)
		(layer "In6.Cu")
		(net "UPI_CPU0_CPU1_P0P1_DN<9>")
	)
	(segment
		(start 144.394174 -187.3758)
		(end 140.052552 -193.203322)
		(width 0.14732)
		(layer "In6.Cu")
		(net "UPI_CPU0_CPU1_P0P1_DN<9>")
	)
	(segment
		(start 345.620848 -210.874864)
		(end 345.620594 -210.875118)
		(width 0.14732)
		(layer "In6.Cu")
		(net "UPI_CPU0_CPU1_P0P1_DN<9>")
	)
	(segment
		(start 345.677998 -213.38413)
		(end 345.677998 -213.11743)
		(width 0.0889)
		(layer "In6.Cu")
		(net "UPI_CPU0_CPU1_P0P1_DN<9>")
	)
	(segment
		(start 326.626728 -190.73622)
		(end 320.11493 -184.521348)
		(width 0.14732)
		(layer "In6.Cu")
		(net "UPI_CPU0_CPU1_P0P1_DN<9>")
	)
	(segment
		(start 345.326462 -214.893652)
		(end 345.24823 -214.91448)
		(width 0.0889)
		(layer "In6.Cu")
		(net "UPI_CPU0_CPU1_P0P1_DN<9>")
	)
	(segment
		(start 315.56579 -181.68239)
		(end 312.469784 -180.805836)
		(width 0.14732)
		(layer "In6.Cu")
		(net "UPI_CPU0_CPU1_P0P1_DN<9>")
	)
	(segment
		(start 200.608184 -180.975508)
		(end 158.88843 -181.667912)
		(width 0.14732)
		(layer "In6.Cu")
		(net "UPI_CPU0_CPU1_P0P1_DN<9>")
	)
	(segment
		(start 345.620594 -210.629246)
		(end 344.784934 -202.728322)
		(width 0.14732)
		(layer "In6.Cu")
		(net "UPI_CPU0_CPU1_P0P1_DN<9>")
	)
	(segment
		(start 158.88843 -181.667912)
		(end 152.198578 -183.38038)
		(width 0.14732)
		(layer "In6.Cu")
		(net "UPI_CPU0_CPU1_P0P1_DN<9>")
	)
	(segment
		(start 320.11493 -184.521348)
		(end 315.56579 -181.68239)
		(width 0.14732)
		(layer "In6.Cu")
		(net "UPI_CPU0_CPU1_P0P1_DN<9>")
	)
	(segment
		(start 345.578684 -212.751416)
		(end 345.677998 -212.652102)
		(width 0.0889)
		(layer "In6.Cu")
		(net "UPI_CPU0_CPU1_P0P1_DN<9>")
	)
	(segment
		(start 273.198844 -181.329838)
		(end 238.626904 -181.494684)
		(width 0.14732)
		(layer "In6.Cu")
		(net "UPI_CPU0_CPU1_P0P1_DN<9>")
	)
	(segment
		(start 126.539498 -210.860894)
		(end 126.539498 -211.465668)
		(width 0.14732)
		(layer "In6.Cu")
		(net "UPI_CPU0_CPU1_P0P1_DN<9>")
	)
	(segment
		(start 327.10374 -191.030098)
		(end 326.626728 -190.73622)
		(width 0.14732)
		(layer "In6.Cu")
		(net "UPI_CPU0_CPU1_P0P1_DN<9>")
	)
	(segment
		(start 126.54026 -211.691728)
		(end 126.58217 -211.733638)
		(width 0.0889)
		(layer "In6.Cu")
		(net "UPI_CPU0_CPU1_P0P1_DN<9>")
	)
	(segment
		(start 345.578684 -213.929468)
		(end 345.578684 -213.483444)
		(width 0.0889)
		(layer "In6.Cu")
		(net "UPI_CPU0_CPU1_P0P1_DN<9>")
	)
	(segment
		(start 238.626904 -181.494684)
		(end 212.424264 -181.494684)
		(width 0.14732)
		(layer "In6.Cu")
		(net "UPI_CPU0_CPU1_P0P1_DN<9>")
	)
	(segment
		(start 126.365762 -214.033608)
		(end 126.207012 -213.732618)
		(width 0.0889)
		(layer "In6.Cu")
		(net "UPI_CPU0_CPU1_P0P1_DN<9>")
	)
	(segment
		(start 345.677998 -213.11743)
		(end 345.578684 -213.018116)
		(width 0.0889)
		(layer "In6.Cu")
		(net "UPI_CPU0_CPU1_P0P1_DN<9>")
	)
	(segment
		(start 302.423068 -180.621178)
		(end 273.198844 -181.329838)
		(width 0.14732)
		(layer "In6.Cu")
		(net "UPI_CPU0_CPU1_P0P1_DN<9>")
	)
	(segment
		(start 345.578684 -211.726272)
		(end 345.620848 -211.684108)
		(width 0.0889)
		(layer "In6.Cu")
		(net "UPI_CPU0_CPU1_P0P1_DN<9>")
	)
	(segment
		(start 345.108276 -214.622634)
		(end 345.108276 -214.461852)
		(width 0.0889)
		(layer "In6.Cu")
		(net "UPI_CPU0_CPU1_P0P1_DN<9>")
	)
	(segment
		(start 345.578684 -213.483444)
		(end 345.677998 -213.38413)
		(width 0.0889)
		(layer "In6.Cu")
		(net "UPI_CPU0_CPU1_P0P1_DN<9>")
	)
	(segment
		(start 345.578684 -213.018116)
		(end 345.578684 -212.751416)
		(width 0.0889)
		(layer "In6.Cu")
		(net "UPI_CPU0_CPU1_P0P1_DN<9>")
	)
	(segment
		(start 129.34188 -202.856338)
		(end 126.539498 -210.860894)
		(width 0.14732)
		(layer "In6.Cu")
		(net "UPI_CPU0_CPU1_P0P1_DN<9>")
	)
	(segment
		(start 126.54026 -211.46643)
		(end 126.54026 -211.66963)
		(width 0.14732)
		(layer "In6.Cu")
		(net "UPI_CPU0_CPU1_P0P1_DN<9>")
	)
	(segment
		(start 126.58217 -213.89213)
		(end 126.581662 -213.8934)
		(width 0.0889)
		(layer "In6.Cu")
		(net "UPI_CPU0_CPU1_P0P1_DN<9>")
	)
	(arc
		(start 345.29268 -214.261954)
		(mid 345.453261 -214.138523)
		(end 345.563444 -213.968584)
		(width 0.0889)
		(layer "In6.Cu")
		(net "UPI_CPU0_CPU1_P0P1_DN<9>")
	)
	(arc
		(start 345.108276 -214.461852)
		(mid 345.183347 -214.34611)
		(end 345.29268 -214.261954)
		(width 0.0889)
		(layer "In6.Cu")
		(net "UPI_CPU0_CPU1_P0P1_DN<9>")
	)
	(arc
		(start 345.563444 -213.968584)
		(mid 345.571409 -213.94916)
		(end 345.578684 -213.929468)
		(width 0.0889)
		(layer "In6.Cu")
		(net "UPI_CPU0_CPU1_P0P1_DN<9>")
	)
	(arc
		(start 345.24823 -214.91448)
		(mid 345.145085 -214.784455)
		(end 345.108276 -214.622634)
		(width 0.0889)
		(layer "In6.Cu")
		(net "UPI_CPU0_CPU1_P0P1_DN<9>")
	)
	(arc
		(start 126.581662 -213.8934)
		(mid 126.526992 -213.985256)
		(end 126.450344 -214.05977)
		(width 0.0889)
		(layer "In6.Cu")
		(net "UPI_CPU0_CPU1_P0P1_DN<9>")
	)
	(segment
		(start 127.147066 -215.436958)
		(end 127.146812 -215.436704)
		(width 0.13208)
		(layer "F.Cu")
		(net "UPI_CPU0_CPU1_P0P1_DN<8>")
	)
	(segment
		(start 344.54338 -215.158574)
		(end 344.54338 -214.622888)
		(width 0.13208)
		(layer "F.Cu")
		(net "UPI_CPU0_CPU1_P0P1_DN<8>")
	)
	(segment
		(start 127.147066 -215.972644)
		(end 127.147066 -215.436958)
		(width 0.13208)
		(layer "F.Cu")
		(net "UPI_CPU0_CPU1_P0P1_DN<8>")
	)
	(segment
		(start 344.54338 -214.622888)
		(end 344.543126 -214.622634)
		(width 0.13208)
		(layer "F.Cu")
		(net "UPI_CPU0_CPU1_P0P1_DN<8>")
	)
	(segment
		(start 344.543126 -214.622634)
		(end 344.384376 -214.321644)
		(width 0.0889)
		(layer "In6.Cu")
		(net "UPI_CPU0_CPU1_P0P1_DN<8>")
	)
	(segment
		(start 200.58761 -181.81447)
		(end 159.104838 -182.503318)
		(width 0.14732)
		(layer "In6.Cu")
		(net "UPI_CPU0_CPU1_P0P1_DN<8>")
	)
	(segment
		(start 159.104838 -182.503318)
		(end 152.376378 -184.225692)
		(width 0.14732)
		(layer "In6.Cu")
		(net "UPI_CPU0_CPU1_P0P1_DN<8>")
	)
	(segment
		(start 127.48006 -211.465922)
		(end 127.48006 -211.78139)
		(width 0.14732)
		(layer "In6.Cu")
		(net "UPI_CPU0_CPU1_P0P1_DN<8>")
	)
	(segment
		(start 142.766796 -190.973202)
		(end 140.632434 -193.838322)
		(width 0.14732)
		(layer "In6.Cu")
		(net "UPI_CPU0_CPU1_P0P1_DN<8>")
	)
	(segment
		(start 321.412616 -187.028836)
		(end 317.557404 -184.100724)
		(width 0.14732)
		(layer "In6.Cu")
		(net "UPI_CPU0_CPU1_P0P1_DN<8>")
	)
	(segment
		(start 342.957912 -201.968862)
		(end 332.894432 -194.051936)
		(width 0.14732)
		(layer "In6.Cu")
		(net "UPI_CPU0_CPU1_P0P1_DN<8>")
	)
	(segment
		(start 127.52197 -213.892892)
		(end 127.521716 -213.8934)
		(width 0.0889)
		(layer "In6.Cu")
		(net "UPI_CPU0_CPU1_P0P1_DN<8>")
	)
	(segment
		(start 273.21129 -182.164482)
		(end 238.629444 -182.329328)
		(width 0.14732)
		(layer "In6.Cu")
		(net "UPI_CPU0_CPU1_P0P1_DN<8>")
	)
	(segment
		(start 332.894432 -194.051936)
		(end 326.838564 -191.856614)
		(width 0.14732)
		(layer "In6.Cu")
		(net "UPI_CPU0_CPU1_P0P1_DN<8>")
	)
	(segment
		(start 127.479806 -211.008722)
		(end 127.479806 -211.465668)
		(width 0.14732)
		(layer "In6.Cu")
		(net "UPI_CPU0_CPU1_P0P1_DN<8>")
	)
	(segment
		(start 325.704962 -191.151764)
		(end 324.903338 -190.381382)
		(width 0.14732)
		(layer "In6.Cu")
		(net "UPI_CPU0_CPU1_P0P1_DN<8>")
	)
	(segment
		(start 212.298534 -182.329328)
		(end 200.58761 -181.81447)
		(width 0.14732)
		(layer "In6.Cu")
		(net "UPI_CPU0_CPU1_P0P1_DN<8>")
	)
	(segment
		(start 127.52197 -211.845398)
		(end 127.52197 -213.892892)
		(width 0.0889)
		(layer "In6.Cu")
		(net "UPI_CPU0_CPU1_P0P1_DN<8>")
	)
	(segment
		(start 127.303276 -215.165686)
		(end 127.146812 -215.436704)
		(width 0.0889)
		(layer "In6.Cu")
		(net "UPI_CPU0_CPU1_P0P1_DN<8>")
	)
	(segment
		(start 238.629444 -182.329328)
		(end 212.298534 -182.329328)
		(width 0.14732)
		(layer "In6.Cu")
		(net "UPI_CPU0_CPU1_P0P1_DN<8>")
	)
	(segment
		(start 302.503332 -181.454552)
		(end 273.21129 -182.164482)
		(width 0.14732)
		(layer "In6.Cu")
		(net "UPI_CPU0_CPU1_P0P1_DN<8>")
	)
	(segment
		(start 127.051308 -214.425784)
		(end 127.051308 -214.636858)
		(width 0.0889)
		(layer "In6.Cu")
		(net "UPI_CPU0_CPU1_P0P1_DN<8>")
	)
	(segment
		(start 127.48006 -211.803488)
		(end 127.52197 -211.845398)
		(width 0.0889)
		(layer "In6.Cu")
		(net "UPI_CPU0_CPU1_P0P1_DN<8>")
	)
	(segment
		(start 344.680794 -210.874864)
		(end 344.68054 -210.875118)
		(width 0.14732)
		(layer "In6.Cu")
		(net "UPI_CPU0_CPU1_P0P1_DN<8>")
	)
	(segment
		(start 344.384376 -214.321644)
		(end 344.414602 -214.22487)
		(width 0.0889)
		(layer "In6.Cu")
		(net "UPI_CPU0_CPU1_P0P1_DN<8>")
	)
	(segment
		(start 343.879678 -203.104496)
		(end 342.957912 -201.968862)
		(width 0.14732)
		(layer "In6.Cu")
		(net "UPI_CPU0_CPU1_P0P1_DN<8>")
	)
	(segment
		(start 152.376378 -184.225692)
		(end 144.96796 -188.018674)
		(width 0.14732)
		(layer "In6.Cu")
		(net "UPI_CPU0_CPU1_P0P1_DN<8>")
	)
	(segment
		(start 144.96796 -188.018674)
		(end 142.766542 -190.973202)
		(width 0.14732)
		(layer "In6.Cu")
		(net "UPI_CPU0_CPU1_P0P1_DN<8>")
	)
	(segment
		(start 140.632434 -193.838322)
		(end 134.727696 -197.763384)
		(width 0.14732)
		(layer "In6.Cu")
		(net "UPI_CPU0_CPU1_P0P1_DN<8>")
	)
	(segment
		(start 344.68054 -210.875118)
		(end 344.68054 -210.674712)
		(width 0.14732)
		(layer "In6.Cu")
		(net "UPI_CPU0_CPU1_P0P1_DN<8>")
	)
	(segment
		(start 142.766542 -190.973202)
		(end 142.766796 -190.973202)
		(width 0.14732)
		(layer "In6.Cu")
		(net "UPI_CPU0_CPU1_P0P1_DN<8>")
	)
	(segment
		(start 344.680794 -211.66201)
		(end 344.680794 -210.874864)
		(width 0.14732)
		(layer "In6.Cu")
		(net "UPI_CPU0_CPU1_P0P1_DN<8>")
	)
	(segment
		(start 315.320934 -182.58663)
		(end 312.316622 -181.636162)
		(width 0.14732)
		(layer "In6.Cu")
		(net "UPI_CPU0_CPU1_P0P1_DN<8>")
	)
	(segment
		(start 324.903338 -190.381382)
		(end 321.412616 -187.028836)
		(width 0.14732)
		(layer "In6.Cu")
		(net "UPI_CPU0_CPU1_P0P1_DN<8>")
	)
	(segment
		(start 130.14325 -203.40193)
		(end 127.479806 -211.008722)
		(width 0.14732)
		(layer "In6.Cu")
		(net "UPI_CPU0_CPU1_P0P1_DN<8>")
	)
	(segment
		(start 344.638884 -211.726018)
		(end 344.680794 -211.684108)
		(width 0.0889)
		(layer "In6.Cu")
		(net "UPI_CPU0_CPU1_P0P1_DN<8>")
	)
	(segment
		(start 344.68054 -210.674712)
		(end 343.879678 -203.104496)
		(width 0.14732)
		(layer "In6.Cu")
		(net "UPI_CPU0_CPU1_P0P1_DN<8>")
	)
	(segment
		(start 312.316622 -181.636162)
		(end 302.503332 -181.454552)
		(width 0.14732)
		(layer "In6.Cu")
		(net "UPI_CPU0_CPU1_P0P1_DN<8>")
	)
	(segment
		(start 127.48006 -211.78139)
		(end 127.48006 -211.803488)
		(width 0.0889)
		(layer "In6.Cu")
		(net "UPI_CPU0_CPU1_P0P1_DN<8>")
	)
	(segment
		(start 317.557404 -184.100724)
		(end 315.320934 -182.58663)
		(width 0.14732)
		(layer "In6.Cu")
		(net "UPI_CPU0_CPU1_P0P1_DN<8>")
	)
	(segment
		(start 326.838564 -191.856614)
		(end 325.704962 -191.151764)
		(width 0.14732)
		(layer "In6.Cu")
		(net "UPI_CPU0_CPU1_P0P1_DN<8>")
	)
	(segment
		(start 127.279146 -215.076532)
		(end 127.303276 -215.165686)
		(width 0.0889)
		(layer "In6.Cu")
		(net "UPI_CPU0_CPU1_P0P1_DN<8>")
	)
	(segment
		(start 134.727696 -197.763384)
		(end 130.14325 -203.40193)
		(width 0.14732)
		(layer "In6.Cu")
		(net "UPI_CPU0_CPU1_P0P1_DN<8>")
	)
	(segment
		(start 344.638884 -213.929468)
		(end 344.638884 -211.726018)
		(width 0.0889)
		(layer "In6.Cu")
		(net "UPI_CPU0_CPU1_P0P1_DN<8>")
	)
	(segment
		(start 344.680794 -211.684108)
		(end 344.680794 -211.66201)
		(width 0.0889)
		(layer "In6.Cu")
		(net "UPI_CPU0_CPU1_P0P1_DN<8>")
	)
	(segment
		(start 127.479806 -211.465668)
		(end 127.48006 -211.465922)
		(width 0.14732)
		(layer "In6.Cu")
		(net "UPI_CPU0_CPU1_P0P1_DN<8>")
	)
	(arc
		(start 344.623898 -213.96833)
		(mid 344.631733 -213.949031)
		(end 344.638884 -213.929468)
		(width 0.0889)
		(layer "In6.Cu")
		(net "UPI_CPU0_CPU1_P0P1_DN<8>")
	)
	(arc
		(start 127.051308 -214.636858)
		(mid 127.109653 -214.873363)
		(end 127.262128 -215.063324)
		(width 0.0889)
		(layer "In6.Cu")
		(net "UPI_CPU0_CPU1_P0P1_DN<8>")
	)
	(arc
		(start 127.262128 -215.063324)
		(mid 127.270574 -215.070009)
		(end 127.279146 -215.076532)
		(width 0.0889)
		(layer "In6.Cu")
		(net "UPI_CPU0_CPU1_P0P1_DN<8>")
	)
	(arc
		(start 127.521716 -213.8934)
		(mid 127.446645 -214.009142)
		(end 127.337312 -214.093298)
		(width 0.0889)
		(layer "In6.Cu")
		(net "UPI_CPU0_CPU1_P0P1_DN<8>")
	)
	(arc
		(start 344.414602 -214.22487)
		(mid 344.537348 -214.111365)
		(end 344.623898 -213.96833)
		(width 0.0889)
		(layer "In6.Cu")
		(net "UPI_CPU0_CPU1_P0P1_DN<8>")
	)
	(arc
		(start 127.337312 -214.093298)
		(mid 127.162764 -214.232402)
		(end 127.051308 -214.425784)
		(width 0.0889)
		(layer "In6.Cu")
		(net "UPI_CPU0_CPU1_P0P1_DN<8>")
	)
	(segment
		(start 343.60358 -215.158574)
		(end 343.60358 -214.622888)
		(width 0.13208)
		(layer "F.Cu")
		(net "UPI_CPU0_CPU1_P0P1_DN<7>")
	)
	(segment
		(start 128.086866 -214.344758)
		(end 128.086866 -213.732618)
		(width 0.13208)
		(layer "F.Cu")
		(net "UPI_CPU0_CPU1_P0P1_DN<7>")
	)
	(segment
		(start 343.60358 -214.622888)
		(end 343.603326 -214.622634)
		(width 0.13208)
		(layer "F.Cu")
		(net "UPI_CPU0_CPU1_P0P1_DN<7>")
	)
	(segment
		(start 130.924046 -203.963778)
		(end 128.419352 -211.116164)
		(width 0.14732)
		(layer "In6.Cu")
		(net "UPI_CPU0_CPU1_P0P1_DN<7>")
	)
	(segment
		(start 343.798398 -212.385402)
		(end 343.699084 -212.286088)
		(width 0.0889)
		(layer "In6.Cu")
		(net "UPI_CPU0_CPU1_P0P1_DN<7>")
	)
	(segment
		(start 343.740994 -210.806538)
		(end 343.740994 -210.729322)
		(width 0.14732)
		(layer "In6.Cu")
		(net "UPI_CPU0_CPU1_P0P1_DN<7>")
	)
	(segment
		(start 200.234296 -182.655718)
		(end 159.360362 -183.334152)
		(width 0.14732)
		(layer "In6.Cu")
		(net "UPI_CPU0_CPU1_P0P1_DN<7>")
	)
	(segment
		(start 312.227214 -182.497222)
		(end 302.505872 -182.318152)
		(width 0.14732)
		(layer "In6.Cu")
		(net "UPI_CPU0_CPU1_P0P1_DN<7>")
	)
	(segment
		(start 343.603326 -214.622634)
		(end 343.446862 -214.893652)
		(width 0.0889)
		(layer "In6.Cu")
		(net "UPI_CPU0_CPU1_P0P1_DN<7>")
	)
	(segment
		(start 152.52192 -185.085228)
		(end 145.561812 -188.647578)
		(width 0.14732)
		(layer "In6.Cu")
		(net "UPI_CPU0_CPU1_P0P1_DN<7>")
	)
	(segment
		(start 343.798398 -213.38413)
		(end 343.798398 -213.11743)
		(width 0.0889)
		(layer "In6.Cu")
		(net "UPI_CPU0_CPU1_P0P1_DN<7>")
	)
	(segment
		(start 343.699084 -211.657692)
		(end 343.741248 -211.615528)
		(width 0.0889)
		(layer "In6.Cu")
		(net "UPI_CPU0_CPU1_P0P1_DN<7>")
	)
	(segment
		(start 128.419606 -211.547202)
		(end 128.419606 -211.77123)
		(width 0.14732)
		(layer "In6.Cu")
		(net "UPI_CPU0_CPU1_P0P1_DN<7>")
	)
	(segment
		(start 145.561812 -188.647578)
		(end 141.233652 -194.45732)
		(width 0.14732)
		(layer "In6.Cu")
		(net "UPI_CPU0_CPU1_P0P1_DN<7>")
	)
	(segment
		(start 341.984838 -202.261978)
		(end 332.531212 -194.825112)
		(width 0.14732)
		(layer "In6.Cu")
		(net "UPI_CPU0_CPU1_P0P1_DN<7>")
	)
	(segment
		(start 343.798398 -213.11743)
		(end 343.699084 -213.018116)
		(width 0.0889)
		(layer "In6.Cu")
		(net "UPI_CPU0_CPU1_P0P1_DN<7>")
	)
	(segment
		(start 332.531212 -194.825112)
		(end 325.458074 -192.237106)
		(width 0.14732)
		(layer "In6.Cu")
		(net "UPI_CPU0_CPU1_P0P1_DN<7>")
	)
	(segment
		(start 343.699084 -213.018116)
		(end 343.699084 -212.751416)
		(width 0.0889)
		(layer "In6.Cu")
		(net "UPI_CPU0_CPU1_P0P1_DN<7>")
	)
	(segment
		(start 322.59651 -189.806072)
		(end 320.374264 -188.447934)
		(width 0.14732)
		(layer "In6.Cu")
		(net "UPI_CPU0_CPU1_P0P1_DN<7>")
	)
	(segment
		(start 302.505872 -182.318152)
		(end 273.22399 -183.027574)
		(width 0.14732)
		(layer "In6.Cu")
		(net "UPI_CPU0_CPU1_P0P1_DN<7>")
	)
	(segment
		(start 343.699084 -212.751416)
		(end 343.798398 -212.652102)
		(width 0.0889)
		(layer "In6.Cu")
		(net "UPI_CPU0_CPU1_P0P1_DN<7>")
	)
	(segment
		(start 342.973914 -203.48067)
		(end 341.984838 -202.261978)
		(width 0.14732)
		(layer "In6.Cu")
		(net "UPI_CPU0_CPU1_P0P1_DN<7>")
	)
	(segment
		(start 135.61695 -198.191374)
		(end 130.924046 -203.963778)
		(width 0.14732)
		(layer "In6.Cu")
		(net "UPI_CPU0_CPU1_P0P1_DN<7>")
	)
	(segment
		(start 343.740994 -210.729322)
		(end 342.973914 -203.48067)
		(width 0.14732)
		(layer "In6.Cu")
		(net "UPI_CPU0_CPU1_P0P1_DN<7>")
	)
	(segment
		(start 343.446862 -214.893652)
		(end 343.36863 -214.91448)
		(width 0.0889)
		(layer "In6.Cu")
		(net "UPI_CPU0_CPU1_P0P1_DN<7>")
	)
	(segment
		(start 343.228676 -214.622634)
		(end 343.228676 -214.461852)
		(width 0.0889)
		(layer "In6.Cu")
		(net "UPI_CPU0_CPU1_P0P1_DN<7>")
	)
	(segment
		(start 212.444584 -183.19242)
		(end 200.234296 -182.655718)
		(width 0.14732)
		(layer "In6.Cu")
		(net "UPI_CPU0_CPU1_P0P1_DN<7>")
	)
	(segment
		(start 343.741248 -210.806284)
		(end 343.740994 -210.806538)
		(width 0.14732)
		(layer "In6.Cu")
		(net "UPI_CPU0_CPU1_P0P1_DN<7>")
	)
	(segment
		(start 343.699084 -213.929468)
		(end 343.699084 -213.483444)
		(width 0.0889)
		(layer "In6.Cu")
		(net "UPI_CPU0_CPU1_P0P1_DN<7>")
	)
	(segment
		(start 314.624974 -183.250078)
		(end 312.227214 -182.497222)
		(width 0.14732)
		(layer "In6.Cu")
		(net "UPI_CPU0_CPU1_P0P1_DN<7>")
	)
	(segment
		(start 320.374264 -188.447934)
		(end 317.178182 -184.959498)
		(width 0.14732)
		(layer "In6.Cu")
		(net "UPI_CPU0_CPU1_P0P1_DN<7>")
	)
	(segment
		(start 343.741248 -211.615528)
		(end 343.741248 -211.59343)
		(width 0.0889)
		(layer "In6.Cu")
		(net "UPI_CPU0_CPU1_P0P1_DN<7>")
	)
	(segment
		(start 128.419352 -211.546948)
		(end 128.419606 -211.547202)
		(width 0.14732)
		(layer "In6.Cu")
		(net "UPI_CPU0_CPU1_P0P1_DN<7>")
	)
	(segment
		(start 325.458074 -192.237106)
		(end 322.59651 -189.806072)
		(width 0.14732)
		(layer "In6.Cu")
		(net "UPI_CPU0_CPU1_P0P1_DN<7>")
	)
	(segment
		(start 128.419606 -211.793328)
		(end 128.461516 -211.835238)
		(width 0.0889)
		(layer "In6.Cu")
		(net "UPI_CPU0_CPU1_P0P1_DN<7>")
	)
	(segment
		(start 159.360362 -183.334152)
		(end 152.52192 -185.085228)
		(width 0.14732)
		(layer "In6.Cu")
		(net "UPI_CPU0_CPU1_P0P1_DN<7>")
	)
	(segment
		(start 343.699084 -212.286088)
		(end 343.699084 -211.657692)
		(width 0.0889)
		(layer "In6.Cu")
		(net "UPI_CPU0_CPU1_P0P1_DN<7>")
	)
	(segment
		(start 128.330198 -214.05977)
		(end 128.245616 -214.033608)
		(width 0.0889)
		(layer "In6.Cu")
		(net "UPI_CPU0_CPU1_P0P1_DN<7>")
	)
	(segment
		(start 317.178182 -184.959498)
		(end 314.624974 -183.250078)
		(width 0.14732)
		(layer "In6.Cu")
		(net "UPI_CPU0_CPU1_P0P1_DN<7>")
	)
	(segment
		(start 273.22399 -183.027574)
		(end 238.63173 -183.19242)
		(width 0.14732)
		(layer "In6.Cu")
		(net "UPI_CPU0_CPU1_P0P1_DN<7>")
	)
	(segment
		(start 343.699084 -213.483444)
		(end 343.798398 -213.38413)
		(width 0.0889)
		(layer "In6.Cu")
		(net "UPI_CPU0_CPU1_P0P1_DN<7>")
	)
	(segment
		(start 343.798398 -212.652102)
		(end 343.798398 -212.385402)
		(width 0.0889)
		(layer "In6.Cu")
		(net "UPI_CPU0_CPU1_P0P1_DN<7>")
	)
	(segment
		(start 238.63173 -183.19242)
		(end 212.444584 -183.19242)
		(width 0.14732)
		(layer "In6.Cu")
		(net "UPI_CPU0_CPU1_P0P1_DN<7>")
	)
	(segment
		(start 128.419352 -211.116164)
		(end 128.419352 -211.546948)
		(width 0.14732)
		(layer "In6.Cu")
		(net "UPI_CPU0_CPU1_P0P1_DN<7>")
	)
	(segment
		(start 128.461516 -211.835238)
		(end 128.461516 -213.8934)
		(width 0.0889)
		(layer "In6.Cu")
		(net "UPI_CPU0_CPU1_P0P1_DN<7>")
	)
	(segment
		(start 128.245616 -214.033608)
		(end 128.086866 -213.732618)
		(width 0.0889)
		(layer "In6.Cu")
		(net "UPI_CPU0_CPU1_P0P1_DN<7>")
	)
	(segment
		(start 141.233652 -194.45732)
		(end 135.61695 -198.191374)
		(width 0.14732)
		(layer "In6.Cu")
		(net "UPI_CPU0_CPU1_P0P1_DN<7>")
	)
	(segment
		(start 128.419606 -211.77123)
		(end 128.419606 -211.793328)
		(width 0.0889)
		(layer "In6.Cu")
		(net "UPI_CPU0_CPU1_P0P1_DN<7>")
	)
	(segment
		(start 343.741248 -211.59343)
		(end 343.741248 -210.806284)
		(width 0.14732)
		(layer "In6.Cu")
		(net "UPI_CPU0_CPU1_P0P1_DN<7>")
	)
	(arc
		(start 128.461516 -213.8934)
		(mid 128.406846 -213.985256)
		(end 128.330198 -214.05977)
		(width 0.0889)
		(layer "In6.Cu")
		(net "UPI_CPU0_CPU1_P0P1_DN<7>")
	)
	(arc
		(start 343.228676 -214.461852)
		(mid 343.303747 -214.34611)
		(end 343.41308 -214.261954)
		(width 0.0889)
		(layer "In6.Cu")
		(net "UPI_CPU0_CPU1_P0P1_DN<7>")
	)
	(arc
		(start 343.41308 -214.261954)
		(mid 343.573661 -214.138523)
		(end 343.683844 -213.968584)
		(width 0.0889)
		(layer "In6.Cu")
		(net "UPI_CPU0_CPU1_P0P1_DN<7>")
	)
	(arc
		(start 343.36863 -214.91448)
		(mid 343.265485 -214.784455)
		(end 343.228676 -214.622634)
		(width 0.0889)
		(layer "In6.Cu")
		(net "UPI_CPU0_CPU1_P0P1_DN<7>")
	)
	(arc
		(start 343.683844 -213.968584)
		(mid 343.691809 -213.94916)
		(end 343.699084 -213.929468)
		(width 0.0889)
		(layer "In6.Cu")
		(net "UPI_CPU0_CPU1_P0P1_DN<7>")
	)
	(segment
		(start 129.496312 -214.622888)
		(end 129.496058 -214.622634)
		(width 0.13208)
		(layer "F.Cu")
		(net "UPI_CPU0_CPU1_P0P1_DN<6>")
	)
	(segment
		(start 342.194134 -214.344758)
		(end 342.194134 -213.732618)
		(width 0.13208)
		(layer "F.Cu")
		(net "UPI_CPU0_CPU1_P0P1_DN<6>")
	)
	(segment
		(start 129.496312 -215.158574)
		(end 129.496312 -214.622888)
		(width 0.13208)
		(layer "F.Cu")
		(net "UPI_CPU0_CPU1_P0P1_DN<6>")
	)
	(segment
		(start 342.526874 -211.66201)
		(end 342.526874 -211.537296)
		(width 0.14732)
		(layer "In6.Cu")
		(net "UPI_CPU0_CPU1_P0P1_DN<6>")
	)
	(segment
		(start 342.568784 -211.726018)
		(end 342.526874 -211.684108)
		(width 0.0889)
		(layer "In6.Cu")
		(net "UPI_CPU0_CPU1_P0P1_DN<6>")
	)
	(segment
		(start 312.349896 -183.712866)
		(end 302.509428 -183.53151)
		(width 0.14732)
		(layer "In6.Cu")
		(net "UPI_CPU0_CPU1_P0P1_DN<6>")
	)
	(segment
		(start 322.126102 -190.857632)
		(end 321.408806 -190.419482)
		(width 0.14732)
		(layer "In6.Cu")
		(net "UPI_CPU0_CPU1_P0P1_DN<6>")
	)
	(segment
		(start 342.194134 -213.732618)
		(end 342.352884 -214.033608)
		(width 0.0889)
		(layer "In6.Cu")
		(net "UPI_CPU0_CPU1_P0P1_DN<6>")
	)
	(segment
		(start 323.79666 -192.276984)
		(end 323.592698 -192.293494)
		(width 0.14732)
		(layer "In6.Cu")
		(net "UPI_CPU0_CPU1_P0P1_DN<6>")
	)
	(segment
		(start 129.63398 -211.547202)
		(end 129.63398 -211.77123)
		(width 0.14732)
		(layer "In6.Cu")
		(net "UPI_CPU0_CPU1_P0P1_DN<6>")
	)
	(segment
		(start 131.97078 -204.451712)
		(end 129.633726 -211.125308)
		(width 0.14732)
		(layer "In6.Cu")
		(net "UPI_CPU0_CPU1_P0P1_DN<6>")
	)
	(segment
		(start 238.635032 -184.405016)
		(end 214.74684 -184.405016)
		(width 0.14732)
		(layer "In6.Cu")
		(net "UPI_CPU0_CPU1_P0P1_DN<6>")
	)
	(segment
		(start 323.295264 -191.850772)
		(end 322.99402 -191.594994)
		(width 0.14732)
		(layer "In6.Cu")
		(net "UPI_CPU0_CPU1_P0P1_DN<6>")
	)
	(segment
		(start 328.574146 -194.655186)
		(end 328.388218 -194.741038)
		(width 0.14732)
		(layer "In6.Cu")
		(net "UPI_CPU0_CPU1_P0P1_DN<6>")
	)
	(segment
		(start 320.533014 -189.884558)
		(end 320.334132 -189.932564)
		(width 0.14732)
		(layer "In6.Cu")
		(net "UPI_CPU0_CPU1_P0P1_DN<6>")
	)
	(segment
		(start 342.568784 -213.8934)
		(end 342.568784 -213.488524)
		(width 0.0889)
		(layer "In6.Cu")
		(net "UPI_CPU0_CPU1_P0P1_DN<6>")
	)
	(segment
		(start 324.374764 -192.958212)
		(end 324.09384 -192.719452)
		(width 0.14732)
		(layer "In6.Cu")
		(net "UPI_CPU0_CPU1_P0P1_DN<6>")
	)
	(segment
		(start 142.10157 -197.06336)
		(end 133.10616 -203.055728)
		(width 0.14732)
		(layer "In6.Cu")
		(net "UPI_CPU0_CPU1_P0P1_DN<6>")
	)
	(segment
		(start 342.46947 -212.390482)
		(end 342.568784 -212.291168)
		(width 0.0889)
		(layer "In6.Cu")
		(net "UPI_CPU0_CPU1_P0P1_DN<6>")
	)
	(segment
		(start 320.895218 -190.275718)
		(end 320.847212 -190.076328)
		(width 0.14732)
		(layer "In6.Cu")
		(net "UPI_CPU0_CPU1_P0P1_DN<6>")
	)
	(segment
		(start 324.09384 -192.719452)
		(end 324.07733 -192.515236)
		(width 0.14732)
		(layer "In6.Cu")
		(net "UPI_CPU0_CPU1_P0P1_DN<6>")
	)
	(segment
		(start 328.388218 -194.741038)
		(end 328.042524 -194.61353)
		(width 0.14732)
		(layer "In6.Cu")
		(net "UPI_CPU0_CPU1_P0P1_DN<6>")
	)
	(segment
		(start 342.52662 -211.53755)
		(end 342.52662 -210.789266)
		(width 0.14732)
		(layer "In6.Cu")
		(net "UPI_CPU0_CPU1_P0P1_DN<6>")
	)
	(segment
		(start 316.786514 -186.328558)
		(end 316.786514 -186.32805)
		(width 0.14732)
		(layer "In6.Cu")
		(net "UPI_CPU0_CPU1_P0P1_DN<6>")
	)
	(segment
		(start 320.019426 -189.74054)
		(end 319.97142 -189.541404)
		(width 0.14732)
		(layer "In6.Cu")
		(net "UPI_CPU0_CPU1_P0P1_DN<6>")
	)
	(segment
		(start 129.591816 -213.046564)
		(end 129.69113 -213.145878)
		(width 0.0889)
		(layer "In6.Cu")
		(net "UPI_CPU0_CPU1_P0P1_DN<6>")
	)
	(segment
		(start 319.97142 -189.541404)
		(end 319.424304 -189.20714)
		(width 0.14732)
		(layer "In6.Cu")
		(net "UPI_CPU0_CPU1_P0P1_DN<6>")
	)
	(segment
		(start 318.185546 -188.069474)
		(end 318.194436 -187.865004)
		(width 0.14732)
		(layer "In6.Cu")
		(net "UPI_CPU0_CPU1_P0P1_DN<6>")
	)
	(segment
		(start 129.591816 -212.296248)
		(end 129.69113 -212.395562)
		(width 0.0889)
		(layer "In6.Cu")
		(net "UPI_CPU0_CPU1_P0P1_DN<6>")
	)
	(segment
		(start 320.847212 -190.076328)
		(end 320.533014 -189.884558)
		(width 0.14732)
		(layer "In6.Cu")
		(net "UPI_CPU0_CPU1_P0P1_DN<6>")
	)
	(segment
		(start 322.99402 -191.594994)
		(end 322.789804 -191.611504)
		(width 0.14732)
		(layer "In6.Cu")
		(net "UPI_CPU0_CPU1_P0P1_DN<6>")
	)
	(segment
		(start 302.509428 -183.53151)
		(end 273.24177 -184.24017)
		(width 0.14732)
		(layer "In6.Cu")
		(net "UPI_CPU0_CPU1_P0P1_DN<6>")
	)
	(segment
		(start 324.578726 -192.941448)
		(end 324.374764 -192.958212)
		(width 0.14732)
		(layer "In6.Cu")
		(net "UPI_CPU0_CPU1_P0P1_DN<6>")
	)
	(segment
		(start 323.311774 -192.054988)
		(end 323.295264 -191.850772)
		(width 0.14732)
		(layer "In6.Cu")
		(net "UPI_CPU0_CPU1_P0P1_DN<6>")
	)
	(segment
		(start 129.69113 -212.395562)
		(end 129.69113 -212.662262)
		(width 0.0889)
		(layer "In6.Cu")
		(net "UPI_CPU0_CPU1_P0P1_DN<6>")
	)
	(segment
		(start 133.10616 -203.055728)
		(end 131.97078 -204.451712)
		(width 0.14732)
		(layer "In6.Cu")
		(net "UPI_CPU0_CPU1_P0P1_DN<6>")
	)
	(segment
		(start 324.07733 -192.515236)
		(end 323.79666 -192.276984)
		(width 0.14732)
		(layer "In6.Cu")
		(net "UPI_CPU0_CPU1_P0P1_DN<6>")
	)
	(segment
		(start 129.121408 -214.461852)
		(end 129.121408 -214.622634)
		(width 0.0889)
		(layer "In6.Cu")
		(net "UPI_CPU0_CPU1_P0P1_DN<6>")
	)
	(segment
		(start 129.591816 -211.835492)
		(end 129.591816 -212.296248)
		(width 0.0889)
		(layer "In6.Cu")
		(net "UPI_CPU0_CPU1_P0P1_DN<6>")
	)
	(segment
		(start 323.592698 -192.293494)
		(end 323.311774 -192.054988)
		(width 0.14732)
		(layer "In6.Cu")
		(net "UPI_CPU0_CPU1_P0P1_DN<6>")
	)
	(segment
		(start 318.434466 -188.341254)
		(end 318.185546 -188.069474)
		(width 0.14732)
		(layer "In6.Cu")
		(net "UPI_CPU0_CPU1_P0P1_DN<6>")
	)
	(segment
		(start 320.334132 -189.932564)
		(end 320.019426 -189.74054)
		(width 0.14732)
		(layer "In6.Cu")
		(net "UPI_CPU0_CPU1_P0P1_DN<6>")
	)
	(segment
		(start 316.786514 -186.32805)
		(end 316.126114 -185.607452)
		(width 0.14732)
		(layer "In6.Cu")
		(net "UPI_CPU0_CPU1_P0P1_DN<6>")
	)
	(segment
		(start 129.69113 -213.145878)
		(end 129.69113 -213.412578)
		(width 0.0889)
		(layer "In6.Cu")
		(net "UPI_CPU0_CPU1_P0P1_DN<6>")
	)
	(segment
		(start 129.339594 -214.893652)
		(end 129.496058 -214.622634)
		(width 0.0889)
		(layer "In6.Cu")
		(net "UPI_CPU0_CPU1_P0P1_DN<6>")
	)
	(segment
		(start 129.63398 -211.793328)
		(end 129.591816 -211.835492)
		(width 0.0889)
		(layer "In6.Cu")
		(net "UPI_CPU0_CPU1_P0P1_DN<6>")
	)
	(segment
		(start 129.591816 -213.511892)
		(end 129.591816 -213.929468)
		(width 0.0889)
		(layer "In6.Cu")
		(net "UPI_CPU0_CPU1_P0P1_DN<6>")
	)
	(segment
		(start 342.568784 -213.023196)
		(end 342.568784 -212.756496)
		(width 0.0889)
		(layer "In6.Cu")
		(net "UPI_CPU0_CPU1_P0P1_DN<6>")
	)
	(segment
		(start 342.568784 -212.756496)
		(end 342.46947 -212.657182)
		(width 0.0889)
		(layer "In6.Cu")
		(net "UPI_CPU0_CPU1_P0P1_DN<6>")
	)
	(segment
		(start 129.633726 -211.546948)
		(end 129.63398 -211.547202)
		(width 0.14732)
		(layer "In6.Cu")
		(net "UPI_CPU0_CPU1_P0P1_DN<6>")
	)
	(segment
		(start 342.46947 -212.657182)
		(end 342.46947 -212.390482)
		(width 0.0889)
		(layer "In6.Cu")
		(net "UPI_CPU0_CPU1_P0P1_DN<6>")
	)
	(segment
		(start 129.63398 -211.77123)
		(end 129.63398 -211.793328)
		(width 0.0889)
		(layer "In6.Cu")
		(net "UPI_CPU0_CPU1_P0P1_DN<6>")
	)
	(segment
		(start 325.077836 -193.365374)
		(end 324.578726 -192.941448)
		(width 0.14732)
		(layer "In6.Cu")
		(net "UPI_CPU0_CPU1_P0P1_DN<6>")
	)
	(segment
		(start 321.408806 -190.419482)
		(end 321.209924 -190.467742)
		(width 0.14732)
		(layer "In6.Cu")
		(net "UPI_CPU0_CPU1_P0P1_DN<6>")
	)
	(segment
		(start 327.956672 -194.427348)
		(end 325.077836 -193.365374)
		(width 0.14732)
		(layer "In6.Cu")
		(net "UPI_CPU0_CPU1_P0P1_DN<6>")
	)
	(segment
		(start 328.042524 -194.61353)
		(end 327.956672 -194.427348)
		(width 0.14732)
		(layer "In6.Cu")
		(net "UPI_CPU0_CPU1_P0P1_DN<6>")
	)
	(segment
		(start 318.194436 -187.865004)
		(end 317.94577 -187.593478)
		(width 0.14732)
		(layer "In6.Cu")
		(net "UPI_CPU0_CPU1_P0P1_DN<6>")
	)
	(segment
		(start 142.10157 -197.063106)
		(end 142.10157 -197.06336)
		(width 0.14732)
		(layer "In6.Cu")
		(net "UPI_CPU0_CPU1_P0P1_DN<6>")
	)
	(segment
		(start 129.69113 -213.412578)
		(end 129.591816 -213.511892)
		(width 0.0889)
		(layer "In6.Cu")
		(net "UPI_CPU0_CPU1_P0P1_DN<6>")
	)
	(segment
		(start 129.591816 -212.761576)
		(end 129.591816 -213.046564)
		(width 0.0889)
		(layer "In6.Cu")
		(net "UPI_CPU0_CPU1_P0P1_DN<6>")
	)
	(segment
		(start 342.568784 -212.291168)
		(end 342.568784 -211.726018)
		(width 0.0889)
		(layer "In6.Cu")
		(net "UPI_CPU0_CPU1_P0P1_DN<6>")
	)
	(segment
		(start 159.500824 -184.438798)
		(end 152.948132 -186.116214)
		(width 0.14732)
		(layer "In6.Cu")
		(net "UPI_CPU0_CPU1_P0P1_DN<6>")
	)
	(segment
		(start 321.209924 -190.467742)
		(end 320.895218 -190.275718)
		(width 0.14732)
		(layer "In6.Cu")
		(net "UPI_CPU0_CPU1_P0P1_DN<6>")
	)
	(segment
		(start 341.204042 -203.065888)
		(end 332.224888 -196.001894)
		(width 0.14732)
		(layer "In6.Cu")
		(net "UPI_CPU0_CPU1_P0P1_DN<6>")
	)
	(segment
		(start 314.132722 -184.272682)
		(end 312.349896 -183.712866)
		(width 0.14732)
		(layer "In6.Cu")
		(net "UPI_CPU0_CPU1_P0P1_DN<6>")
	)
	(segment
		(start 342.352884 -214.033608)
		(end 342.437466 -214.05977)
		(width 0.0889)
		(layer "In6.Cu")
		(net "UPI_CPU0_CPU1_P0P1_DN<6>")
	)
	(segment
		(start 273.24177 -184.24017)
		(end 238.635032 -184.405016)
		(width 0.14732)
		(layer "In6.Cu")
		(net "UPI_CPU0_CPU1_P0P1_DN<6>")
	)
	(segment
		(start 152.948132 -186.116214)
		(end 149.155404 -188.05779)
		(width 0.14732)
		(layer "In6.Cu")
		(net "UPI_CPU0_CPU1_P0P1_DN<6>")
	)
	(segment
		(start 147.982432 -189.170056)
		(end 142.10157 -197.063106)
		(width 0.14732)
		(layer "In6.Cu")
		(net "UPI_CPU0_CPU1_P0P1_DN<6>")
	)
	(segment
		(start 129.261362 -214.91448)
		(end 129.339594 -214.893652)
		(width 0.0889)
		(layer "In6.Cu")
		(net "UPI_CPU0_CPU1_P0P1_DN<6>")
	)
	(segment
		(start 149.155404 -188.05779)
		(end 147.982432 -189.170056)
		(width 0.14732)
		(layer "In6.Cu")
		(net "UPI_CPU0_CPU1_P0P1_DN<6>")
	)
	(segment
		(start 318.63919 -188.350144)
		(end 318.434466 -188.341254)
		(width 0.14732)
		(layer "In6.Cu")
		(net "UPI_CPU0_CPU1_P0P1_DN<6>")
	)
	(segment
		(start 322.50888 -191.372744)
		(end 322.49237 -191.168782)
		(width 0.14732)
		(layer "In6.Cu")
		(net "UPI_CPU0_CPU1_P0P1_DN<6>")
	)
	(segment
		(start 317.7413 -187.584588)
		(end 317.492126 -187.312808)
		(width 0.14732)
		(layer "In6.Cu")
		(net "UPI_CPU0_CPU1_P0P1_DN<6>")
	)
	(segment
		(start 342.46947 -213.38921)
		(end 342.46947 -213.12251)
		(width 0.0889)
		(layer "In6.Cu")
		(net "UPI_CPU0_CPU1_P0P1_DN<6>")
	)
	(segment
		(start 322.789804 -191.611504)
		(end 322.50888 -191.372744)
		(width 0.14732)
		(layer "In6.Cu")
		(net "UPI_CPU0_CPU1_P0P1_DN<6>")
	)
	(segment
		(start 342.568784 -213.488524)
		(end 342.46947 -213.38921)
		(width 0.0889)
		(layer "In6.Cu")
		(net "UPI_CPU0_CPU1_P0P1_DN<6>")
	)
	(segment
		(start 332.224888 -196.001894)
		(end 328.574146 -194.655186)
		(width 0.14732)
		(layer "In6.Cu")
		(net "UPI_CPU0_CPU1_P0P1_DN<6>")
	)
	(segment
		(start 200.152508 -183.763666)
		(end 159.500824 -184.438798)
		(width 0.14732)
		(layer "In6.Cu")
		(net "UPI_CPU0_CPU1_P0P1_DN<6>")
	)
	(segment
		(start 214.74684 -184.405016)
		(end 200.152508 -183.763666)
		(width 0.14732)
		(layer "In6.Cu")
		(net "UPI_CPU0_CPU1_P0P1_DN<6>")
	)
	(segment
		(start 319.424304 -189.20714)
		(end 318.63919 -188.350144)
		(width 0.14732)
		(layer "In6.Cu")
		(net "UPI_CPU0_CPU1_P0P1_DN<6>")
	)
	(segment
		(start 129.633726 -211.125308)
		(end 129.633726 -211.546948)
		(width 0.14732)
		(layer "In6.Cu")
		(net "UPI_CPU0_CPU1_P0P1_DN<6>")
	)
	(segment
		(start 316.126114 -185.607452)
		(end 314.132722 -184.272682)
		(width 0.14732)
		(layer "In6.Cu")
		(net "UPI_CPU0_CPU1_P0P1_DN<6>")
	)
	(segment
		(start 342.526874 -211.684108)
		(end 342.526874 -211.66201)
		(width 0.0889)
		(layer "In6.Cu")
		(net "UPI_CPU0_CPU1_P0P1_DN<6>")
	)
	(segment
		(start 342.46947 -213.12251)
		(end 342.568784 -213.023196)
		(width 0.0889)
		(layer "In6.Cu")
		(net "UPI_CPU0_CPU1_P0P1_DN<6>")
	)
	(segment
		(start 317.94577 -187.593478)
		(end 317.7413 -187.584588)
		(width 0.14732)
		(layer "In6.Cu")
		(net "UPI_CPU0_CPU1_P0P1_DN<6>")
	)
	(segment
		(start 342.526874 -211.537296)
		(end 342.52662 -211.53755)
		(width 0.14732)
		(layer "In6.Cu")
		(net "UPI_CPU0_CPU1_P0P1_DN<6>")
	)
	(segment
		(start 341.784686 -203.781152)
		(end 341.204042 -203.065888)
		(width 0.14732)
		(layer "In6.Cu")
		(net "UPI_CPU0_CPU1_P0P1_DN<6>")
	)
	(segment
		(start 342.52662 -210.789266)
		(end 341.784686 -203.781152)
		(width 0.14732)
		(layer "In6.Cu")
		(net "UPI_CPU0_CPU1_P0P1_DN<6>")
	)
	(segment
		(start 129.69113 -212.662262)
		(end 129.591816 -212.761576)
		(width 0.0889)
		(layer "In6.Cu")
		(net "UPI_CPU0_CPU1_P0P1_DN<6>")
	)
	(segment
		(start 322.49237 -191.168782)
		(end 322.126102 -190.857632)
		(width 0.14732)
		(layer "In6.Cu")
		(net "UPI_CPU0_CPU1_P0P1_DN<6>")
	)
	(segment
		(start 317.501016 -187.108084)
		(end 316.786514 -186.328558)
		(width 0.14732)
		(layer "In6.Cu")
		(net "UPI_CPU0_CPU1_P0P1_DN<6>")
	)
	(segment
		(start 317.492126 -187.312808)
		(end 317.501016 -187.108084)
		(width 0.14732)
		(layer "In6.Cu")
		(net "UPI_CPU0_CPU1_P0P1_DN<6>")
	)
	(arc
		(start 129.591816 -213.929468)
		(mid 129.584538 -213.949159)
		(end 129.576576 -213.968584)
		(width 0.0889)
		(layer "In6.Cu")
		(net "UPI_CPU0_CPU1_P0P1_DN<6>")
	)
	(arc
		(start 129.305812 -214.261954)
		(mid 129.196416 -214.346051)
		(end 129.121408 -214.461852)
		(width 0.0889)
		(layer "In6.Cu")
		(net "UPI_CPU0_CPU1_P0P1_DN<6>")
	)
	(arc
		(start 129.576576 -213.968584)
		(mid 129.46637 -214.138501)
		(end 129.305812 -214.261954)
		(width 0.0889)
		(layer "In6.Cu")
		(net "UPI_CPU0_CPU1_P0P1_DN<6>")
	)
	(arc
		(start 342.437466 -214.05977)
		(mid 342.514139 -213.985276)
		(end 342.568784 -213.8934)
		(width 0.0889)
		(layer "In6.Cu")
		(net "UPI_CPU0_CPU1_P0P1_DN<6>")
	)
	(arc
		(start 129.121408 -214.622634)
		(mid 129.158268 -214.784431)
		(end 129.261362 -214.91448)
		(width 0.0889)
		(layer "In6.Cu")
		(net "UPI_CPU0_CPU1_P0P1_DN<6>")
	)
	(segment
		(start 341.72398 -214.622888)
		(end 341.723726 -214.622634)
		(width 0.13208)
		(layer "F.Cu")
		(net "UPI_CPU0_CPU1_P0P1_DN<5>")
	)
	(segment
		(start 129.966466 -214.344758)
		(end 129.966466 -213.732618)
		(width 0.13208)
		(layer "F.Cu")
		(net "UPI_CPU0_CPU1_P0P1_DN<5>")
	)
	(segment
		(start 341.72398 -215.158574)
		(end 341.72398 -214.622888)
		(width 0.13208)
		(layer "F.Cu")
		(net "UPI_CPU0_CPU1_P0P1_DN<5>")
	)
	(segment
		(start 149.489922 -188.51499)
		(end 148.41855 -189.52972)
		(width 0.14732)
		(layer "In6.Cu")
		(net "UPI_CPU0_CPU1_P0P1_DN<5>")
	)
	(segment
		(start 340.735158 -203.409804)
		(end 332.334362 -196.800724)
		(width 0.14732)
		(layer "In6.Cu")
		(net "UPI_CPU0_CPU1_P0P1_DN<5>")
	)
	(segment
		(start 341.861648 -211.684108)
		(end 341.861648 -211.66201)
		(width 0.0889)
		(layer "In6.Cu")
		(net "UPI_CPU0_CPU1_P0P1_DN<5>")
	)
	(segment
		(start 159.52343 -185.010044)
		(end 153.148284 -186.642502)
		(width 0.14732)
		(layer "In6.Cu")
		(net "UPI_CPU0_CPU1_P0P1_DN<5>")
	)
	(segment
		(start 130.341116 -211.713318)
		(end 130.341116 -213.8934)
		(width 0.0889)
		(layer "In6.Cu")
		(net "UPI_CPU0_CPU1_P0P1_DN<5>")
	)
	(segment
		(start 130.298952 -211.191348)
		(end 130.299206 -211.191602)
		(width 0.14732)
		(layer "In6.Cu")
		(net "UPI_CPU0_CPU1_P0P1_DN<5>")
	)
	(segment
		(start 130.125216 -214.033608)
		(end 129.966466 -213.732618)
		(width 0.0889)
		(layer "In6.Cu")
		(net "UPI_CPU0_CPU1_P0P1_DN<5>")
	)
	(segment
		(start 341.200486 -203.983336)
		(end 340.735158 -203.409804)
		(width 0.14732)
		(layer "In6.Cu")
		(net "UPI_CPU0_CPU1_P0P1_DN<5>")
	)
	(segment
		(start 332.334362 -196.800724)
		(end 329.450446 -195.750434)
		(width 0.14732)
		(layer "In6.Cu")
		(net "UPI_CPU0_CPU1_P0P1_DN<5>")
	)
	(segment
		(start 326.618346 -194.718686)
		(end 319.737994 -191.56553)
		(width 0.14732)
		(layer "In6.Cu")
		(net "UPI_CPU0_CPU1_P0P1_DN<5>")
	)
	(segment
		(start 200.36028 -184.332118)
		(end 159.52343 -185.010044)
		(width 0.14732)
		(layer "In6.Cu")
		(net "UPI_CPU0_CPU1_P0P1_DN<5>")
	)
	(segment
		(start 341.819484 -213.018116)
		(end 341.819484 -212.751416)
		(width 0.0889)
		(layer "In6.Cu")
		(net "UPI_CPU0_CPU1_P0P1_DN<5>")
	)
	(segment
		(start 130.299206 -211.64931)
		(end 130.299206 -211.671408)
		(width 0.0889)
		(layer "In6.Cu")
		(net "UPI_CPU0_CPU1_P0P1_DN<5>")
	)
	(segment
		(start 142.484602 -197.495414)
		(end 133.480302 -203.481178)
		(width 0.14732)
		(layer "In6.Cu")
		(net "UPI_CPU0_CPU1_P0P1_DN<5>")
	)
	(segment
		(start 313.962288 -184.82818)
		(end 312.268616 -184.297574)
		(width 0.14732)
		(layer "In6.Cu")
		(net "UPI_CPU0_CPU1_P0P1_DN<5>")
	)
	(segment
		(start 302.511206 -184.117996)
		(end 273.250152 -184.826402)
		(width 0.14732)
		(layer "In6.Cu")
		(net "UPI_CPU0_CPU1_P0P1_DN<5>")
	)
	(segment
		(start 312.268616 -184.297574)
		(end 302.511206 -184.117996)
		(width 0.14732)
		(layer "In6.Cu")
		(net "UPI_CPU0_CPU1_P0P1_DN<5>")
	)
	(segment
		(start 130.299206 -211.671408)
		(end 130.341116 -211.713318)
		(width 0.0889)
		(layer "In6.Cu")
		(net "UPI_CPU0_CPU1_P0P1_DN<5>")
	)
	(segment
		(start 215.355678 -184.991248)
		(end 200.36028 -184.332118)
		(width 0.14732)
		(layer "In6.Cu")
		(net "UPI_CPU0_CPU1_P0P1_DN<5>")
	)
	(segment
		(start 341.918798 -213.11743)
		(end 341.819484 -213.018116)
		(width 0.0889)
		(layer "In6.Cu")
		(net "UPI_CPU0_CPU1_P0P1_DN<5>")
	)
	(segment
		(start 341.819484 -211.726272)
		(end 341.861648 -211.684108)
		(width 0.0889)
		(layer "In6.Cu")
		(net "UPI_CPU0_CPU1_P0P1_DN<5>")
	)
	(segment
		(start 341.918798 -212.652102)
		(end 341.918798 -212.385402)
		(width 0.0889)
		(layer "In6.Cu")
		(net "UPI_CPU0_CPU1_P0P1_DN<5>")
	)
	(segment
		(start 273.250152 -184.826402)
		(end 238.636556 -184.991248)
		(width 0.14732)
		(layer "In6.Cu")
		(net "UPI_CPU0_CPU1_P0P1_DN<5>")
	)
	(segment
		(start 341.819484 -213.483444)
		(end 341.918798 -213.38413)
		(width 0.0889)
		(layer "In6.Cu")
		(net "UPI_CPU0_CPU1_P0P1_DN<5>")
	)
	(segment
		(start 341.861394 -210.875118)
		(end 341.861394 -210.223608)
		(width 0.14732)
		(layer "In6.Cu")
		(net "UPI_CPU0_CPU1_P0P1_DN<5>")
	)
	(segment
		(start 315.701426 -185.99023)
		(end 313.962288 -184.82818)
		(width 0.14732)
		(layer "In6.Cu")
		(net "UPI_CPU0_CPU1_P0P1_DN<5>")
	)
	(segment
		(start 130.298952 -210.968082)
		(end 130.298952 -211.191348)
		(width 0.14732)
		(layer "In6.Cu")
		(net "UPI_CPU0_CPU1_P0P1_DN<5>")
	)
	(segment
		(start 341.723726 -214.622634)
		(end 341.567262 -214.893652)
		(width 0.0889)
		(layer "In6.Cu")
		(net "UPI_CPU0_CPU1_P0P1_DN<5>")
	)
	(segment
		(start 341.918798 -212.385402)
		(end 341.819484 -212.286088)
		(width 0.0889)
		(layer "In6.Cu")
		(net "UPI_CPU0_CPU1_P0P1_DN<5>")
	)
	(segment
		(start 341.861648 -210.874864)
		(end 341.861394 -210.875118)
		(width 0.14732)
		(layer "In6.Cu")
		(net "UPI_CPU0_CPU1_P0P1_DN<5>")
	)
	(segment
		(start 341.861394 -210.223608)
		(end 341.200486 -203.983336)
		(width 0.14732)
		(layer "In6.Cu")
		(net "UPI_CPU0_CPU1_P0P1_DN<5>")
	)
	(segment
		(start 341.918798 -213.38413)
		(end 341.918798 -213.11743)
		(width 0.0889)
		(layer "In6.Cu")
		(net "UPI_CPU0_CPU1_P0P1_DN<5>")
	)
	(segment
		(start 148.41855 -189.52972)
		(end 142.484602 -197.495414)
		(width 0.14732)
		(layer "In6.Cu")
		(net "UPI_CPU0_CPU1_P0P1_DN<5>")
	)
	(segment
		(start 341.861648 -211.66201)
		(end 341.861648 -210.874864)
		(width 0.14732)
		(layer "In6.Cu")
		(net "UPI_CPU0_CPU1_P0P1_DN<5>")
	)
	(segment
		(start 341.819484 -212.751416)
		(end 341.918798 -212.652102)
		(width 0.0889)
		(layer "In6.Cu")
		(net "UPI_CPU0_CPU1_P0P1_DN<5>")
	)
	(segment
		(start 238.636556 -184.991248)
		(end 215.355678 -184.991248)
		(width 0.14732)
		(layer "In6.Cu")
		(net "UPI_CPU0_CPU1_P0P1_DN<5>")
	)
	(segment
		(start 341.349076 -214.622634)
		(end 341.349076 -214.461852)
		(width 0.0889)
		(layer "In6.Cu")
		(net "UPI_CPU0_CPU1_P0P1_DN<5>")
	)
	(segment
		(start 329.450192 -195.75018)
		(end 326.618346 -194.718686)
		(width 0.14732)
		(layer "In6.Cu")
		(net "UPI_CPU0_CPU1_P0P1_DN<5>")
	)
	(segment
		(start 319.737994 -191.56553)
		(end 318.55664 -190.657988)
		(width 0.14732)
		(layer "In6.Cu")
		(net "UPI_CPU0_CPU1_P0P1_DN<5>")
	)
	(segment
		(start 341.819484 -212.286088)
		(end 341.819484 -211.726272)
		(width 0.0889)
		(layer "In6.Cu")
		(net "UPI_CPU0_CPU1_P0P1_DN<5>")
	)
	(segment
		(start 318.55664 -190.657988)
		(end 315.701426 -185.99023)
		(width 0.14732)
		(layer "In6.Cu")
		(net "UPI_CPU0_CPU1_P0P1_DN<5>")
	)
	(segment
		(start 329.450446 -195.750434)
		(end 329.450192 -195.75018)
		(width 0.14732)
		(layer "In6.Cu")
		(net "UPI_CPU0_CPU1_P0P1_DN<5>")
	)
	(segment
		(start 133.480302 -203.481178)
		(end 132.498338 -204.688948)
		(width 0.14732)
		(layer "In6.Cu")
		(net "UPI_CPU0_CPU1_P0P1_DN<5>")
	)
	(segment
		(start 130.209798 -214.05977)
		(end 130.125216 -214.033608)
		(width 0.0889)
		(layer "In6.Cu")
		(net "UPI_CPU0_CPU1_P0P1_DN<5>")
	)
	(segment
		(start 341.567262 -214.893652)
		(end 341.48903 -214.91448)
		(width 0.0889)
		(layer "In6.Cu")
		(net "UPI_CPU0_CPU1_P0P1_DN<5>")
	)
	(segment
		(start 132.498338 -204.688948)
		(end 130.298952 -210.968082)
		(width 0.14732)
		(layer "In6.Cu")
		(net "UPI_CPU0_CPU1_P0P1_DN<5>")
	)
	(segment
		(start 341.819484 -213.929468)
		(end 341.819484 -213.483444)
		(width 0.0889)
		(layer "In6.Cu")
		(net "UPI_CPU0_CPU1_P0P1_DN<5>")
	)
	(segment
		(start 153.148284 -186.642502)
		(end 149.489922 -188.51499)
		(width 0.14732)
		(layer "In6.Cu")
		(net "UPI_CPU0_CPU1_P0P1_DN<5>")
	)
	(segment
		(start 130.299206 -211.191602)
		(end 130.299206 -211.64931)
		(width 0.14732)
		(layer "In6.Cu")
		(net "UPI_CPU0_CPU1_P0P1_DN<5>")
	)
	(arc
		(start 341.804244 -213.968584)
		(mid 341.812209 -213.94916)
		(end 341.819484 -213.929468)
		(width 0.0889)
		(layer "In6.Cu")
		(net "UPI_CPU0_CPU1_P0P1_DN<5>")
	)
	(arc
		(start 341.53348 -214.261954)
		(mid 341.694061 -214.138523)
		(end 341.804244 -213.968584)
		(width 0.0889)
		(layer "In6.Cu")
		(net "UPI_CPU0_CPU1_P0P1_DN<5>")
	)
	(arc
		(start 341.48903 -214.91448)
		(mid 341.385885 -214.784455)
		(end 341.349076 -214.622634)
		(width 0.0889)
		(layer "In6.Cu")
		(net "UPI_CPU0_CPU1_P0P1_DN<5>")
	)
	(arc
		(start 341.349076 -214.461852)
		(mid 341.424147 -214.34611)
		(end 341.53348 -214.261954)
		(width 0.0889)
		(layer "In6.Cu")
		(net "UPI_CPU0_CPU1_P0P1_DN<5>")
	)
	(arc
		(start 130.341116 -213.8934)
		(mid 130.286446 -213.985256)
		(end 130.209798 -214.05977)
		(width 0.0889)
		(layer "In6.Cu")
		(net "UPI_CPU0_CPU1_P0P1_DN<5>")
	)
	(segment
		(start 131.375912 -215.158574)
		(end 131.375912 -214.622888)
		(width 0.13208)
		(layer "F.Cu")
		(net "UPI_CPU0_CPU1_P0P1_DN<4>")
	)
	(segment
		(start 131.375912 -214.622888)
		(end 131.375658 -214.622634)
		(width 0.13208)
		(layer "F.Cu")
		(net "UPI_CPU0_CPU1_P0P1_DN<4>")
	)
	(segment
		(start 340.314534 -214.344758)
		(end 340.314534 -213.732618)
		(width 0.13208)
		(layer "F.Cu")
		(net "UPI_CPU0_CPU1_P0P1_DN<4>")
	)
	(segment
		(start 273.215354 -186.043062)
		(end 255.013714 -186.08421)
		(width 0.14732)
		(layer "In6.Cu")
		(net "UPI_CPU0_CPU1_P0P1_DN<4>")
	)
	(segment
		(start 255.013714 -186.08421)
		(end 255.01346 -186.083956)
		(width 0.14732)
		(layer "In6.Cu")
		(net "UPI_CPU0_CPU1_P0P1_DN<4>")
	)
	(segment
		(start 330.402692 -197.285864)
		(end 330.217018 -197.37197)
		(width 0.14732)
		(layer "In6.Cu")
		(net "UPI_CPU0_CPU1_P0P1_DN<4>")
	)
	(segment
		(start 132.136896 -212.634576)
		(end 132.136896 -212.774784)
		(width 0.0889)
		(layer "In6.Cu")
		(net "UPI_CPU0_CPU1_P0P1_DN<4>")
	)
	(segment
		(start 133.874764 -210.956652)
		(end 133.81482 -210.956652)
		(width 0.0889)
		(layer "In6.Cu")
		(net "UPI_CPU0_CPU1_P0P1_DN<4>")
	)
	(segment
		(start 313.451494 -185.852308)
		(end 312.069988 -185.427112)
		(width 0.14732)
		(layer "In6.Cu")
		(net "UPI_CPU0_CPU1_P0P1_DN<4>")
	)
	(segment
		(start 157.812994 -186.88558)
		(end 157.630368 -186.793124)
		(width 0.14732)
		(layer "In6.Cu")
		(net "UPI_CPU0_CPU1_P0P1_DN<4>")
	)
	(segment
		(start 137.01014 -207.82026)
		(end 134.883398 -209.947002)
		(width 0.14732)
		(layer "In6.Cu")
		(net "UPI_CPU0_CPU1_P0P1_DN<4>")
	)
	(segment
		(start 147.540472 -193.40957)
		(end 147.333208 -193.397886)
		(width 0.14732)
		(layer "In6.Cu")
		(net "UPI_CPU0_CPU1_P0P1_DN<4>")
	)
	(segment
		(start 131.001008 -214.461852)
		(end 131.001008 -214.622634)
		(width 0.0889)
		(layer "In6.Cu")
		(net "UPI_CPU0_CPU1_P0P1_DN<4>")
	)
	(segment
		(start 329.78471 -197.05955)
		(end 329.395582 -196.91731)
		(width 0.14732)
		(layer "In6.Cu")
		(net "UPI_CPU0_CPU1_P0P1_DN<4>")
	)
	(segment
		(start 131.948174 -212.963506)
		(end 131.807966 -212.963506)
		(width 0.0889)
		(layer "In6.Cu")
		(net "UPI_CPU0_CPU1_P0P1_DN<4>")
	)
	(segment
		(start 319.129156 -192.506346)
		(end 317.772288 -191.532002)
		(width 0.14732)
		(layer "In6.Cu")
		(net "UPI_CPU0_CPU1_P0P1_DN<4>")
	)
	(segment
		(start 132.654294 -212.117178)
		(end 132.654294 -212.257386)
		(width 0.0889)
		(layer "In6.Cu")
		(net "UPI_CPU0_CPU1_P0P1_DN<4>")
	)
	(segment
		(start 328.863706 -196.876924)
		(end 328.777346 -196.690996)
		(width 0.14732)
		(layer "In6.Cu")
		(net "UPI_CPU0_CPU1_P0P1_DN<4>")
	)
	(segment
		(start 159.638746 -186.13628)
		(end 158.255716 -186.5884)
		(width 0.14732)
		(layer "In6.Cu")
		(net "UPI_CPU0_CPU1_P0P1_DN<4>")
	)
	(segment
		(start 327.813416 -196.338444)
		(end 326.177148 -195.739766)
		(width 0.14732)
		(layer "In6.Cu")
		(net "UPI_CPU0_CPU1_P0P1_DN<4>")
	)
	(segment
		(start 340.689184 -212.756496)
		(end 340.58987 -212.657182)
		(width 0.0889)
		(layer "In6.Cu")
		(net "UPI_CPU0_CPU1_P0P1_DN<4>")
	)
	(segment
		(start 331.817726 -197.803262)
		(end 330.402692 -197.285864)
		(width 0.14732)
		(layer "In6.Cu")
		(net "UPI_CPU0_CPU1_P0P1_DN<4>")
	)
	(segment
		(start 327.899776 -196.524372)
		(end 327.813416 -196.338444)
		(width 0.14732)
		(layer "In6.Cu")
		(net "UPI_CPU0_CPU1_P0P1_DN<4>")
	)
	(segment
		(start 146.881088 -193.999104)
		(end 147.554188 -194.75196)
		(width 0.14732)
		(layer "In6.Cu")
		(net "UPI_CPU0_CPU1_P0P1_DN<4>")
	)
	(segment
		(start 156.83738 -187.204858)
		(end 156.654754 -187.112148)
		(width 0.14732)
		(layer "In6.Cu")
		(net "UPI_CPU0_CPU1_P0P1_DN<4>")
	)
	(segment
		(start 154.360118 -188.39688)
		(end 154.087322 -188.644022)
		(width 0.14732)
		(layer "In6.Cu")
		(net "UPI_CPU0_CPU1_P0P1_DN<4>")
	)
	(segment
		(start 134.883398 -209.948018)
		(end 133.890258 -210.941158)
		(width 0.14732)
		(layer "In6.Cu")
		(net "UPI_CPU0_CPU1_P0P1_DN<4>")
	)
	(segment
		(start 148.608796 -192.454276)
		(end 149.281896 -193.207132)
		(width 0.14732)
		(layer "In6.Cu")
		(net "UPI_CPU0_CPU1_P0P1_DN<4>")
	)
	(segment
		(start 146.892772 -193.791586)
		(end 146.881088 -193.999104)
		(width 0.14732)
		(layer "In6.Cu")
		(net "UPI_CPU0_CPU1_P0P1_DN<4>")
	)
	(segment
		(start 340.689184 -213.023196)
		(end 340.689184 -212.756496)
		(width 0.0889)
		(layer "In6.Cu")
		(net "UPI_CPU0_CPU1_P0P1_DN<4>")
	)
	(segment
		(start 143.128238 -199.122284)
		(end 137.01014 -207.82026)
		(width 0.14732)
		(layer "In6.Cu")
		(net "UPI_CPU0_CPU1_P0P1_DN<4>")
	)
	(segment
		(start 340.58987 -212.657182)
		(end 340.58987 -212.390482)
		(width 0.0889)
		(layer "In6.Cu")
		(net "UPI_CPU0_CPU1_P0P1_DN<4>")
	)
	(segment
		(start 131.807966 -212.963506)
		(end 131.471416 -213.300056)
		(width 0.0889)
		(layer "In6.Cu")
		(net "UPI_CPU0_CPU1_P0P1_DN<4>")
	)
	(segment
		(start 147.333208 -193.397886)
		(end 146.892772 -193.791586)
		(width 0.14732)
		(layer "In6.Cu")
		(net "UPI_CPU0_CPU1_P0P1_DN<4>")
	)
	(segment
		(start 133.171692 -211.739988)
		(end 132.98297 -211.92871)
		(width 0.0889)
		(layer "In6.Cu")
		(net "UPI_CPU0_CPU1_P0P1_DN<4>")
	)
	(segment
		(start 149.281896 -193.207132)
		(end 149.257512 -193.64198)
		(width 0.14732)
		(layer "In6.Cu")
		(net "UPI_CPU0_CPU1_P0P1_DN<4>")
	)
	(segment
		(start 133.81482 -210.956652)
		(end 133.171692 -211.59978)
		(width 0.0889)
		(layer "In6.Cu")
		(net "UPI_CPU0_CPU1_P0P1_DN<4>")
	)
	(segment
		(start 132.654294 -212.257386)
		(end 132.465572 -212.446108)
		(width 0.0889)
		(layer "In6.Cu")
		(net "UPI_CPU0_CPU1_P0P1_DN<4>")
	)
	(segment
		(start 329.87107 -197.245478)
		(end 329.78471 -197.05955)
		(width 0.14732)
		(layer "In6.Cu")
		(net "UPI_CPU0_CPU1_P0P1_DN<4>")
	)
	(segment
		(start 133.171692 -211.59978)
		(end 133.171692 -211.739988)
		(width 0.0889)
		(layer "In6.Cu")
		(net "UPI_CPU0_CPU1_P0P1_DN<4>")
	)
	(segment
		(start 340.085172 -204.468222)
		(end 339.723222 -204.022452)
		(width 0.14732)
		(layer "In6.Cu")
		(net "UPI_CPU0_CPU1_P0P1_DN<4>")
	)
	(segment
		(start 150.348188 -190.70193)
		(end 150.336504 -190.909448)
		(width 0.14732)
		(layer "In6.Cu")
		(net "UPI_CPU0_CPU1_P0P1_DN<4>")
	)
	(segment
		(start 154.564588 -188.40704)
		(end 154.360118 -188.39688)
		(width 0.14732)
		(layer "In6.Cu")
		(net "UPI_CPU0_CPU1_P0P1_DN<4>")
	)
	(segment
		(start 340.689184 -213.488524)
		(end 340.58987 -213.38921)
		(width 0.0889)
		(layer "In6.Cu")
		(net "UPI_CPU0_CPU1_P0P1_DN<4>")
	)
	(segment
		(start 151.009604 -191.662304)
		(end 150.98522 -192.097152)
		(width 0.14732)
		(layer "In6.Cu")
		(net "UPI_CPU0_CPU1_P0P1_DN<4>")
	)
	(segment
		(start 151.668734 -191.07277)
		(end 150.995888 -190.319914)
		(width 0.14732)
		(layer "In6.Cu")
		(net "UPI_CPU0_CPU1_P0P1_DN<4>")
	)
	(segment
		(start 147.529804 -195.187062)
		(end 143.128238 -199.122284)
		(width 0.14732)
		(layer "In6.Cu")
		(net "UPI_CPU0_CPU1_P0P1_DN<4>")
	)
	(segment
		(start 131.471416 -213.300056)
		(end 131.471416 -213.928706)
		(width 0.0889)
		(layer "In6.Cu")
		(net "UPI_CPU0_CPU1_P0P1_DN<4>")
	)
	(segment
		(start 340.689184 -213.8934)
		(end 340.689184 -213.488524)
		(width 0.0889)
		(layer "In6.Cu")
		(net "UPI_CPU0_CPU1_P0P1_DN<4>")
	)
	(segment
		(start 156.654754 -187.112148)
		(end 155.2829 -187.560712)
		(width 0.14732)
		(layer "In6.Cu")
		(net "UPI_CPU0_CPU1_P0P1_DN<4>")
	)
	(segment
		(start 330.217018 -197.37197)
		(end 329.87107 -197.245478)
		(width 0.14732)
		(layer "In6.Cu")
		(net "UPI_CPU0_CPU1_P0P1_DN<4>")
	)
	(segment
		(start 200.603866 -185.448956)
		(end 159.638746 -186.13628)
		(width 0.14732)
		(layer "In6.Cu")
		(net "UPI_CPU0_CPU1_P0P1_DN<4>")
	)
	(segment
		(start 157.630368 -186.793124)
		(end 157.280356 -186.907424)
		(width 0.14732)
		(layer "In6.Cu")
		(net "UPI_CPU0_CPU1_P0P1_DN<4>")
	)
	(segment
		(start 328.431652 -196.564504)
		(end 328.245978 -196.650864)
		(width 0.14732)
		(layer "In6.Cu")
		(net "UPI_CPU0_CPU1_P0P1_DN<4>")
	)
	(segment
		(start 328.245978 -196.650864)
		(end 327.899776 -196.524372)
		(width 0.14732)
		(layer "In6.Cu")
		(net "UPI_CPU0_CPU1_P0P1_DN<4>")
	)
	(segment
		(start 133.890258 -210.941158)
		(end 133.874764 -210.956652)
		(width 0.0889)
		(layer "In6.Cu")
		(net "UPI_CPU0_CPU1_P0P1_DN<4>")
	)
	(segment
		(start 314.84189 -186.759596)
		(end 313.451494 -185.852308)
		(width 0.14732)
		(layer "In6.Cu")
		(net "UPI_CPU0_CPU1_P0P1_DN<4>")
	)
	(segment
		(start 131.219194 -214.893652)
		(end 131.375658 -214.622634)
		(width 0.0889)
		(layer "In6.Cu")
		(net "UPI_CPU0_CPU1_P0P1_DN<4>")
	)
	(segment
		(start 340.647274 -209.774028)
		(end 340.085172 -204.468222)
		(width 0.14732)
		(layer "In6.Cu")
		(net "UPI_CPU0_CPU1_P0P1_DN<4>")
	)
	(segment
		(start 148.213318 -194.162426)
		(end 147.540472 -193.40957)
		(width 0.14732)
		(layer "In6.Cu")
		(net "UPI_CPU0_CPU1_P0P1_DN<4>")
	)
	(segment
		(start 317.772288 -191.532002)
		(end 314.84189 -186.759596)
		(width 0.14732)
		(layer "In6.Cu")
		(net "UPI_CPU0_CPU1_P0P1_DN<4>")
	)
	(segment
		(start 152.142698 -191.09944)
		(end 151.668734 -191.07277)
		(width 0.14732)
		(layer "In6.Cu")
		(net "UPI_CPU0_CPU1_P0P1_DN<4>")
	)
	(segment
		(start 340.314534 -213.732618)
		(end 340.473284 -214.033608)
		(width 0.0889)
		(layer "In6.Cu")
		(net "UPI_CPU0_CPU1_P0P1_DN<4>")
	)
	(segment
		(start 340.58987 -213.12251)
		(end 340.689184 -213.023196)
		(width 0.0889)
		(layer "In6.Cu")
		(net "UPI_CPU0_CPU1_P0P1_DN<4>")
	)
	(segment
		(start 340.58987 -213.38921)
		(end 340.58987 -213.12251)
		(width 0.0889)
		(layer "In6.Cu")
		(net "UPI_CPU0_CPU1_P0P1_DN<4>")
	)
	(segment
		(start 132.325364 -212.446108)
		(end 132.136896 -212.634576)
		(width 0.0889)
		(layer "In6.Cu")
		(net "UPI_CPU0_CPU1_P0P1_DN<4>")
	)
	(segment
		(start 157.1879 -187.090304)
		(end 156.83738 -187.204858)
		(width 0.14732)
		(layer "In6.Cu")
		(net "UPI_CPU0_CPU1_P0P1_DN<4>")
	)
	(segment
		(start 149.26818 -191.864742)
		(end 149.060916 -191.853058)
		(width 0.14732)
		(layer "In6.Cu")
		(net "UPI_CPU0_CPU1_P0P1_DN<4>")
	)
	(segment
		(start 340.647274 -211.783168)
		(end 340.647274 -211.76107)
		(width 0.0889)
		(layer "In6.Cu")
		(net "UPI_CPU0_CPU1_P0P1_DN<4>")
	)
	(segment
		(start 150.98522 -192.097152)
		(end 150.376128 -192.641982)
		(width 0.14732)
		(layer "In6.Cu")
		(net "UPI_CPU0_CPU1_P0P1_DN<4>")
	)
	(segment
		(start 302.25365 -185.2422)
		(end 273.215354 -186.043062)
		(width 0.14732)
		(layer "In6.Cu")
		(net "UPI_CPU0_CPU1_P0P1_DN<4>")
	)
	(segment
		(start 254.354076 -186.085734)
		(end 215.527382 -186.17311)
		(width 0.14732)
		(layer "In6.Cu")
		(net "UPI_CPU0_CPU1_P0P1_DN<4>")
	)
	(segment
		(start 340.689184 -211.825078)
		(end 340.647274 -211.783168)
		(width 0.0889)
		(layer "In6.Cu")
		(net "UPI_CPU0_CPU1_P0P1_DN<4>")
	)
	(segment
		(start 157.280356 -186.907424)
		(end 157.1879 -187.090304)
		(width 0.14732)
		(layer "In6.Cu")
		(net "UPI_CPU0_CPU1_P0P1_DN<4>")
	)
	(segment
		(start 329.395582 -196.91731)
		(end 329.209654 -197.003416)
		(width 0.14732)
		(layer "In6.Cu")
		(net "UPI_CPU0_CPU1_P0P1_DN<4>")
	)
	(segment
		(start 132.98297 -211.92871)
		(end 132.842762 -211.92871)
		(width 0.0889)
		(layer "In6.Cu")
		(net "UPI_CPU0_CPU1_P0P1_DN<4>")
	)
	(segment
		(start 131.140962 -214.91448)
		(end 131.219194 -214.893652)
		(width 0.0889)
		(layer "In6.Cu")
		(net "UPI_CPU0_CPU1_P0P1_DN<4>")
	)
	(segment
		(start 148.64842 -194.18681)
		(end 148.213318 -194.162426)
		(width 0.14732)
		(layer "In6.Cu")
		(net "UPI_CPU0_CPU1_P0P1_DN<4>")
	)
	(segment
		(start 132.465572 -212.446108)
		(end 132.325364 -212.446108)
		(width 0.0889)
		(layer "In6.Cu")
		(net "UPI_CPU0_CPU1_P0P1_DN<4>")
	)
	(segment
		(start 158.16326 -186.77128)
		(end 157.812994 -186.88558)
		(width 0.14732)
		(layer "In6.Cu")
		(net "UPI_CPU0_CPU1_P0P1_DN<4>")
	)
	(segment
		(start 326.177148 -195.739766)
		(end 319.129156 -192.506346)
		(width 0.14732)
		(layer "In6.Cu")
		(net "UPI_CPU0_CPU1_P0P1_DN<4>")
	)
	(segment
		(start 134.883398 -209.947002)
		(end 134.883398 -209.948018)
		(width 0.14732)
		(layer "In6.Cu")
		(net "UPI_CPU0_CPU1_P0P1_DN<4>")
	)
	(segment
		(start 154.837892 -188.15939)
		(end 154.564588 -188.40704)
		(width 0.14732)
		(layer "In6.Cu")
		(net "UPI_CPU0_CPU1_P0P1_DN<4>")
	)
	(segment
		(start 158.255716 -186.5884)
		(end 158.16326 -186.77128)
		(width 0.14732)
		(layer "In6.Cu")
		(net "UPI_CPU0_CPU1_P0P1_DN<4>")
	)
	(segment
		(start 329.209654 -197.003416)
		(end 328.863706 -196.876924)
		(width 0.14732)
		(layer "In6.Cu")
		(net "UPI_CPU0_CPU1_P0P1_DN<4>")
	)
	(segment
		(start 255.01219 -186.083956)
		(end 254.867664 -186.229244)
		(width 0.14732)
		(layer "In6.Cu")
		(net "UPI_CPU0_CPU1_P0P1_DN<4>")
	)
	(segment
		(start 150.336504 -190.909448)
		(end 151.009604 -191.662304)
		(width 0.14732)
		(layer "In6.Cu")
		(net "UPI_CPU0_CPU1_P0P1_DN<4>")
	)
	(segment
		(start 340.58987 -212.390482)
		(end 340.689184 -212.291168)
		(width 0.0889)
		(layer "In6.Cu")
		(net "UPI_CPU0_CPU1_P0P1_DN<4>")
	)
	(segment
		(start 132.136896 -212.774784)
		(end 131.948174 -212.963506)
		(width 0.0889)
		(layer "In6.Cu")
		(net "UPI_CPU0_CPU1_P0P1_DN<4>")
	)
	(segment
		(start 215.527382 -186.17311)
		(end 200.603866 -185.448956)
		(width 0.14732)
		(layer "In6.Cu")
		(net "UPI_CPU0_CPU1_P0P1_DN<4>")
	)
	(segment
		(start 155.2829 -187.560712)
		(end 154.847798 -187.95492)
		(width 0.14732)
		(layer "In6.Cu")
		(net "UPI_CPU0_CPU1_P0P1_DN<4>")
	)
	(segment
		(start 132.842762 -211.92871)
		(end 132.654294 -212.117178)
		(width 0.0889)
		(layer "In6.Cu")
		(net "UPI_CPU0_CPU1_P0P1_DN<4>")
	)
	(segment
		(start 302.475392 -185.2422)
		(end 302.25365 -185.2422)
		(width 0.14732)
		(layer "In6.Cu")
		(net "UPI_CPU0_CPU1_P0P1_DN<4>")
	)
	(segment
		(start 147.554188 -194.75196)
		(end 147.529804 -195.187062)
		(width 0.14732)
		(layer "In6.Cu")
		(net "UPI_CPU0_CPU1_P0P1_DN<4>")
	)
	(segment
		(start 254.867664 -186.229244)
		(end 254.49911 -186.23026)
		(width 0.14732)
		(layer "In6.Cu")
		(net "UPI_CPU0_CPU1_P0P1_DN<4>")
	)
	(segment
		(start 328.777346 -196.690996)
		(end 328.431652 -196.564504)
		(width 0.14732)
		(layer "In6.Cu")
		(net "UPI_CPU0_CPU1_P0P1_DN<4>")
	)
	(segment
		(start 153.762964 -189.650624)
		(end 152.142698 -191.09944)
		(width 0.14732)
		(layer "In6.Cu")
		(net "UPI_CPU0_CPU1_P0P1_DN<4>")
	)
	(segment
		(start 340.647274 -211.76107)
		(end 340.647274 -209.774028)
		(width 0.14732)
		(layer "In6.Cu")
		(net "UPI_CPU0_CPU1_P0P1_DN<4>")
	)
	(segment
		(start 254.49911 -186.23026)
		(end 254.354076 -186.085734)
		(width 0.14732)
		(layer "In6.Cu")
		(net "UPI_CPU0_CPU1_P0P1_DN<4>")
	)
	(segment
		(start 340.689184 -212.291168)
		(end 340.689184 -211.825078)
		(width 0.0889)
		(layer "In6.Cu")
		(net "UPI_CPU0_CPU1_P0P1_DN<4>")
	)
	(segment
		(start 149.060916 -191.853058)
		(end 148.62048 -192.246758)
		(width 0.14732)
		(layer "In6.Cu")
		(net "UPI_CPU0_CPU1_P0P1_DN<4>")
	)
	(segment
		(start 150.376128 -192.641982)
		(end 149.941026 -192.617598)
		(width 0.14732)
		(layer "In6.Cu")
		(net "UPI_CPU0_CPU1_P0P1_DN<4>")
	)
	(segment
		(start 312.069988 -185.427112)
		(end 302.475392 -185.2422)
		(width 0.14732)
		(layer "In6.Cu")
		(net "UPI_CPU0_CPU1_P0P1_DN<4>")
	)
	(segment
		(start 255.01346 -186.083956)
		(end 255.01219 -186.083956)
		(width 0.14732)
		(layer "In6.Cu")
		(net "UPI_CPU0_CPU1_P0P1_DN<4>")
	)
	(segment
		(start 149.257512 -193.64198)
		(end 148.64842 -194.18681)
		(width 0.14732)
		(layer "In6.Cu")
		(net "UPI_CPU0_CPU1_P0P1_DN<4>")
	)
	(segment
		(start 149.941026 -192.617598)
		(end 149.26818 -191.864742)
		(width 0.14732)
		(layer "In6.Cu")
		(net "UPI_CPU0_CPU1_P0P1_DN<4>")
	)
	(segment
		(start 150.995888 -190.319914)
		(end 150.788624 -190.30823)
		(width 0.14732)
		(layer "In6.Cu")
		(net "UPI_CPU0_CPU1_P0P1_DN<4>")
	)
	(segment
		(start 148.62048 -192.246758)
		(end 148.608796 -192.454276)
		(width 0.14732)
		(layer "In6.Cu")
		(net "UPI_CPU0_CPU1_P0P1_DN<4>")
	)
	(segment
		(start 340.473284 -214.033608)
		(end 340.557866 -214.05977)
		(width 0.0889)
		(layer "In6.Cu")
		(net "UPI_CPU0_CPU1_P0P1_DN<4>")
	)
	(segment
		(start 339.723222 -204.022452)
		(end 331.817726 -197.803262)
		(width 0.14732)
		(layer "In6.Cu")
		(net "UPI_CPU0_CPU1_P0P1_DN<4>")
	)
	(segment
		(start 154.087322 -188.644022)
		(end 153.762964 -189.650624)
		(width 0.14732)
		(layer "In6.Cu")
		(net "UPI_CPU0_CPU1_P0P1_DN<4>")
	)
	(segment
		(start 154.847798 -187.95492)
		(end 154.837892 -188.15939)
		(width 0.14732)
		(layer "In6.Cu")
		(net "UPI_CPU0_CPU1_P0P1_DN<4>")
	)
	(segment
		(start 150.788624 -190.30823)
		(end 150.348188 -190.70193)
		(width 0.14732)
		(layer "In6.Cu")
		(net "UPI_CPU0_CPU1_P0P1_DN<4>")
	)
	(arc
		(start 131.471416 -213.928706)
		(mid 131.464148 -213.948653)
		(end 131.456176 -213.96833)
		(width 0.0889)
		(layer "In6.Cu")
		(net "UPI_CPU0_CPU1_P0P1_DN<4>")
	)
	(arc
		(start 131.456176 -213.96833)
		(mid 131.346125 -214.138361)
		(end 131.185666 -214.261954)
		(width 0.0889)
		(layer "In6.Cu")
		(net "UPI_CPU0_CPU1_P0P1_DN<4>")
	)
	(arc
		(start 340.557866 -214.05977)
		(mid 340.634539 -213.985276)
		(end 340.689184 -213.8934)
		(width 0.0889)
		(layer "In6.Cu")
		(net "UPI_CPU0_CPU1_P0P1_DN<4>")
	)
	(arc
		(start 131.001008 -214.622634)
		(mid 131.037868 -214.784431)
		(end 131.140962 -214.91448)
		(width 0.0889)
		(layer "In6.Cu")
		(net "UPI_CPU0_CPU1_P0P1_DN<4>")
	)
	(arc
		(start 131.185666 -214.261954)
		(mid 131.076179 -214.346049)
		(end 131.001008 -214.461852)
		(width 0.0889)
		(layer "In6.Cu")
		(net "UPI_CPU0_CPU1_P0P1_DN<4>")
	)
	(segment
		(start 131.846066 -214.344758)
		(end 131.846066 -213.732618)
		(width 0.13208)
		(layer "F.Cu")
		(net "UPI_CPU0_CPU1_P0P1_DN<3>")
	)
	(segment
		(start 339.84438 -215.158574)
		(end 339.84438 -214.622888)
		(width 0.13208)
		(layer "F.Cu")
		(net "UPI_CPU0_CPU1_P0P1_DN<3>")
	)
	(segment
		(start 339.84438 -214.622888)
		(end 339.844126 -214.622634)
		(width 0.13208)
		(layer "F.Cu")
		(net "UPI_CPU0_CPU1_P0P1_DN<3>")
	)
	(segment
		(start 132.004816 -214.033608)
		(end 131.846066 -213.732618)
		(width 0.0889)
		(layer "In6.Cu")
		(net "UPI_CPU0_CPU1_P0P1_DN<3>")
	)
	(segment
		(start 324.639686 -196.524626)
		(end 324.83425 -196.096382)
		(width 0.14732)
		(layer "In6.Cu")
		(net "UPI_CPU0_CPU1_P0P1_DN<3>")
	)
	(segment
		(start 339.544914 -204.82179)
		(end 339.018372 -204.173582)
		(width 0.14732)
		(layer "In6.Cu")
		(net "UPI_CPU0_CPU1_P0P1_DN<3>")
	)
	(segment
		(start 324.680834 -195.688458)
		(end 323.936868 -195.35013)
		(width 0.14732)
		(layer "In6.Cu")
		(net "UPI_CPU0_CPU1_P0P1_DN<3>")
	)
	(segment
		(start 325.250302 -196.963284)
		(end 324.712838 -196.718936)
		(width 0.14732)
		(layer "In6.Cu")
		(net "UPI_CPU0_CPU1_P0P1_DN<3>")
	)
	(segment
		(start 314.42025 -187.157868)
		(end 313.17819 -186.349894)
		(width 0.14732)
		(layer "In6.Cu")
		(net "UPI_CPU0_CPU1_P0P1_DN<3>")
	)
	(segment
		(start 317.36411 -191.966088)
		(end 314.42025 -187.157868)
		(width 0.14732)
		(layer "In6.Cu")
		(net "UPI_CPU0_CPU1_P0P1_DN<3>")
	)
	(segment
		(start 157.849824 -187.791852)
		(end 148.108924 -195.428108)
		(width 0.14732)
		(layer "In6.Cu")
		(net "UPI_CPU0_CPU1_P0P1_DN<3>")
	)
	(segment
		(start 339.982048 -211.66201)
		(end 339.982048 -210.874864)
		(width 0.14732)
		(layer "In6.Cu")
		(net "UPI_CPU0_CPU1_P0P1_DN<3>")
	)
	(segment
		(start 320.460878 -193.77152)
		(end 318.940688 -193.081148)
		(width 0.14732)
		(layer "In6.Cu")
		(net "UPI_CPU0_CPU1_P0P1_DN<3>")
	)
	(segment
		(start 249.3899 -192.722754)
		(end 238.429038 -197.737984)
		(width 0.14732)
		(layer "In6.Cu")
		(net "UPI_CPU0_CPU1_P0P1_DN<3>")
	)
	(segment
		(start 339.981794 -208.947258)
		(end 339.544914 -204.82179)
		(width 0.14732)
		(layer "In6.Cu")
		(net "UPI_CPU0_CPU1_P0P1_DN<3>")
	)
	(segment
		(start 235.95965 -197.887844)
		(end 233.656378 -197.207124)
		(width 0.14732)
		(layer "In6.Cu")
		(net "UPI_CPU0_CPU1_P0P1_DN<3>")
	)
	(segment
		(start 159.725106 -186.698382)
		(end 157.849824 -187.791852)
		(width 0.14732)
		(layer "In6.Cu")
		(net "UPI_CPU0_CPU1_P0P1_DN<3>")
	)
	(segment
		(start 340.039198 -213.11743)
		(end 339.939884 -213.018116)
		(width 0.0889)
		(layer "In6.Cu")
		(net "UPI_CPU0_CPU1_P0P1_DN<3>")
	)
	(segment
		(start 340.039198 -212.385402)
		(end 339.939884 -212.286088)
		(width 0.0889)
		(layer "In6.Cu")
		(net "UPI_CPU0_CPU1_P0P1_DN<3>")
	)
	(segment
		(start 325.444866 -196.890132)
		(end 325.250302 -196.963284)
		(width 0.14732)
		(layer "In6.Cu")
		(net "UPI_CPU0_CPU1_P0P1_DN<3>")
	)
	(segment
		(start 320.492882 -194.801744)
		(end 320.41973 -194.607434)
		(width 0.14732)
		(layer "In6.Cu")
		(net "UPI_CPU0_CPU1_P0P1_DN<3>")
	)
	(segment
		(start 260.82371 -189.748668)
		(end 249.3899 -192.722754)
		(width 0.14732)
		(layer "In6.Cu")
		(net "UPI_CPU0_CPU1_P0P1_DN<3>")
	)
	(segment
		(start 313.17819 -186.349894)
		(end 312.025538 -185.996326)
		(width 0.14732)
		(layer "In6.Cu")
		(net "UPI_CPU0_CPU1_P0P1_DN<3>")
	)
	(segment
		(start 237.232444 -197.887844)
		(end 235.95965 -197.887844)
		(width 0.14732)
		(layer "In6.Cu")
		(net "UPI_CPU0_CPU1_P0P1_DN<3>")
	)
	(segment
		(start 339.939884 -212.286088)
		(end 339.939884 -211.726272)
		(width 0.0889)
		(layer "In6.Cu")
		(net "UPI_CPU0_CPU1_P0P1_DN<3>")
	)
	(segment
		(start 318.940688 -193.081148)
		(end 317.36411 -191.966088)
		(width 0.14732)
		(layer "In6.Cu")
		(net "UPI_CPU0_CPU1_P0P1_DN<3>")
	)
	(segment
		(start 273.011138 -186.631834)
		(end 264.586974 -187.66536)
		(width 0.14732)
		(layer "In6.Cu")
		(net "UPI_CPU0_CPU1_P0P1_DN<3>")
	)
	(segment
		(start 339.687662 -214.893652)
		(end 339.60943 -214.91448)
		(width 0.0889)
		(layer "In6.Cu")
		(net "UPI_CPU0_CPU1_P0P1_DN<3>")
	)
	(segment
		(start 321.419474 -194.545458)
		(end 321.22491 -194.97294)
		(width 0.14732)
		(layer "In6.Cu")
		(net "UPI_CPU0_CPU1_P0P1_DN<3>")
	)
	(segment
		(start 339.469476 -214.622634)
		(end 339.469476 -214.461852)
		(width 0.0889)
		(layer "In6.Cu")
		(net "UPI_CPU0_CPU1_P0P1_DN<3>")
	)
	(segment
		(start 132.681218 -213.022942)
		(end 132.220716 -213.483444)
		(width 0.0889)
		(layer "In6.Cu")
		(net "UPI_CPU0_CPU1_P0P1_DN<3>")
	)
	(segment
		(start 223.391222 -190.55842)
		(end 215.27262 -186.722258)
		(width 0.14732)
		(layer "In6.Cu")
		(net "UPI_CPU0_CPU1_P0P1_DN<3>")
	)
	(segment
		(start 320.614294 -194.17919)
		(end 320.460878 -193.77152)
		(width 0.14732)
		(layer "In6.Cu")
		(net "UPI_CPU0_CPU1_P0P1_DN<3>")
	)
	(segment
		(start 320.41973 -194.607434)
		(end 320.614294 -194.17919)
		(width 0.14732)
		(layer "In6.Cu")
		(net "UPI_CPU0_CPU1_P0P1_DN<3>")
	)
	(segment
		(start 132.777738 -213.022942)
		(end 132.681218 -213.022942)
		(width 0.0889)
		(layer "In6.Cu")
		(net "UPI_CPU0_CPU1_P0P1_DN<3>")
	)
	(segment
		(start 322.60286 -195.76034)
		(end 322.529708 -195.56603)
		(width 0.14732)
		(layer "In6.Cu")
		(net "UPI_CPU0_CPU1_P0P1_DN<3>")
	)
	(segment
		(start 134.855204 -210.885278)
		(end 134.855204 -210.886548)
		(width 0.14732)
		(layer "In6.Cu")
		(net "UPI_CPU0_CPU1_P0P1_DN<3>")
	)
	(segment
		(start 339.982048 -211.684108)
		(end 339.982048 -211.66201)
		(width 0.0889)
		(layer "In6.Cu")
		(net "UPI_CPU0_CPU1_P0P1_DN<3>")
	)
	(segment
		(start 332.115922 -198.742808)
		(end 328.16038 -197.267576)
		(width 0.14732)
		(layer "In6.Cu")
		(net "UPI_CPU0_CPU1_P0P1_DN<3>")
	)
	(segment
		(start 339.982048 -210.874864)
		(end 339.981794 -210.875118)
		(width 0.14732)
		(layer "In6.Cu")
		(net "UPI_CPU0_CPU1_P0P1_DN<3>")
	)
	(segment
		(start 137.212324 -208.527904)
		(end 134.855204 -210.885278)
		(width 0.14732)
		(layer "In6.Cu")
		(net "UPI_CPU0_CPU1_P0P1_DN<3>")
	)
	(segment
		(start 132.220716 -213.483444)
		(end 132.220716 -213.8934)
		(width 0.0889)
		(layer "In6.Cu")
		(net "UPI_CPU0_CPU1_P0P1_DN<3>")
	)
	(segment
		(start 321.22491 -194.97294)
		(end 321.030346 -195.046092)
		(width 0.14732)
		(layer "In6.Cu")
		(net "UPI_CPU0_CPU1_P0P1_DN<3>")
	)
	(segment
		(start 322.570856 -194.729862)
		(end 321.82689 -194.391534)
		(width 0.14732)
		(layer "In6.Cu")
		(net "UPI_CPU0_CPU1_P0P1_DN<3>")
	)
	(segment
		(start 215.27262 -186.722258)
		(end 200.424542 -186.02833)
		(width 0.14732)
		(layer "In6.Cu")
		(net "UPI_CPU0_CPU1_P0P1_DN<3>")
	)
	(segment
		(start 148.108924 -195.428108)
		(end 143.513556 -199.552814)
		(width 0.14732)
		(layer "In6.Cu")
		(net "UPI_CPU0_CPU1_P0P1_DN<3>")
	)
	(segment
		(start 325.63943 -196.462396)
		(end 325.444866 -196.890132)
		(width 0.14732)
		(layer "In6.Cu")
		(net "UPI_CPU0_CPU1_P0P1_DN<3>")
	)
	(segment
		(start 132.089398 -214.05977)
		(end 132.004816 -214.033608)
		(width 0.0889)
		(layer "In6.Cu")
		(net "UPI_CPU0_CPU1_P0P1_DN<3>")
	)
	(segment
		(start 324.712838 -196.718936)
		(end 324.639686 -196.524626)
		(width 0.14732)
		(layer "In6.Cu")
		(net "UPI_CPU0_CPU1_P0P1_DN<3>")
	)
	(segment
		(start 340.039198 -213.38413)
		(end 340.039198 -213.11743)
		(width 0.0889)
		(layer "In6.Cu")
		(net "UPI_CPU0_CPU1_P0P1_DN<3>")
	)
	(segment
		(start 324.83425 -196.096382)
		(end 324.680834 -195.688458)
		(width 0.14732)
		(layer "In6.Cu")
		(net "UPI_CPU0_CPU1_P0P1_DN<3>")
	)
	(segment
		(start 233.656378 -197.207124)
		(end 223.391222 -190.55842)
		(width 0.14732)
		(layer "In6.Cu")
		(net "UPI_CPU0_CPU1_P0P1_DN<3>")
	)
	(segment
		(start 339.939884 -211.726272)
		(end 339.982048 -211.684108)
		(width 0.0889)
		(layer "In6.Cu")
		(net "UPI_CPU0_CPU1_P0P1_DN<3>")
	)
	(segment
		(start 339.939884 -212.751416)
		(end 340.039198 -212.652102)
		(width 0.0889)
		(layer "In6.Cu")
		(net "UPI_CPU0_CPU1_P0P1_DN<3>")
	)
	(segment
		(start 134.459726 -211.282026)
		(end 134.444232 -211.29752)
		(width 0.0889)
		(layer "In6.Cu")
		(net "UPI_CPU0_CPU1_P0P1_DN<3>")
	)
	(segment
		(start 134.444232 -211.356448)
		(end 132.777738 -213.022942)
		(width 0.0889)
		(layer "In6.Cu")
		(net "UPI_CPU0_CPU1_P0P1_DN<3>")
	)
	(segment
		(start 339.939884 -213.929468)
		(end 339.939884 -213.483444)
		(width 0.0889)
		(layer "In6.Cu")
		(net "UPI_CPU0_CPU1_P0P1_DN<3>")
	)
	(segment
		(start 134.444232 -211.29752)
		(end 134.444232 -211.356448)
		(width 0.0889)
		(layer "In6.Cu")
		(net "UPI_CPU0_CPU1_P0P1_DN<3>")
	)
	(segment
		(start 323.529452 -195.504054)
		(end 323.334888 -195.931536)
		(width 0.14732)
		(layer "In6.Cu")
		(net "UPI_CPU0_CPU1_P0P1_DN<3>")
	)
	(segment
		(start 264.586974 -187.66536)
		(end 260.82371 -189.748668)
		(width 0.14732)
		(layer "In6.Cu")
		(net "UPI_CPU0_CPU1_P0P1_DN<3>")
	)
	(segment
		(start 143.513556 -199.552814)
		(end 137.212324 -208.527904)
		(width 0.14732)
		(layer "In6.Cu")
		(net "UPI_CPU0_CPU1_P0P1_DN<3>")
	)
	(segment
		(start 321.030346 -195.046092)
		(end 320.492882 -194.801744)
		(width 0.14732)
		(layer "In6.Cu")
		(net "UPI_CPU0_CPU1_P0P1_DN<3>")
	)
	(segment
		(start 200.424542 -186.02833)
		(end 159.725106 -186.698382)
		(width 0.14732)
		(layer "In6.Cu")
		(net "UPI_CPU0_CPU1_P0P1_DN<3>")
	)
	(segment
		(start 340.039198 -212.652102)
		(end 340.039198 -212.385402)
		(width 0.0889)
		(layer "In6.Cu")
		(net "UPI_CPU0_CPU1_P0P1_DN<3>")
	)
	(segment
		(start 323.140324 -196.004688)
		(end 322.60286 -195.76034)
		(width 0.14732)
		(layer "In6.Cu")
		(net "UPI_CPU0_CPU1_P0P1_DN<3>")
	)
	(segment
		(start 339.939884 -213.483444)
		(end 340.039198 -213.38413)
		(width 0.0889)
		(layer "In6.Cu")
		(net "UPI_CPU0_CPU1_P0P1_DN<3>")
	)
	(segment
		(start 238.429038 -197.737984)
		(end 237.232444 -197.887844)
		(width 0.14732)
		(layer "In6.Cu")
		(net "UPI_CPU0_CPU1_P0P1_DN<3>")
	)
	(segment
		(start 321.82689 -194.391534)
		(end 321.419474 -194.545458)
		(width 0.14732)
		(layer "In6.Cu")
		(net "UPI_CPU0_CPU1_P0P1_DN<3>")
	)
	(segment
		(start 312.025538 -185.996326)
		(end 302.46701 -185.81878)
		(width 0.14732)
		(layer "In6.Cu")
		(net "UPI_CPU0_CPU1_P0P1_DN<3>")
	)
	(segment
		(start 322.724272 -195.137786)
		(end 322.570856 -194.729862)
		(width 0.14732)
		(layer "In6.Cu")
		(net "UPI_CPU0_CPU1_P0P1_DN<3>")
	)
	(segment
		(start 339.018372 -204.173582)
		(end 332.115922 -198.742808)
		(width 0.14732)
		(layer "In6.Cu")
		(net "UPI_CPU0_CPU1_P0P1_DN<3>")
	)
	(segment
		(start 339.981794 -210.875118)
		(end 339.981794 -208.947258)
		(width 0.14732)
		(layer "In6.Cu")
		(net "UPI_CPU0_CPU1_P0P1_DN<3>")
	)
	(segment
		(start 326.046846 -196.30898)
		(end 325.63943 -196.462396)
		(width 0.14732)
		(layer "In6.Cu")
		(net "UPI_CPU0_CPU1_P0P1_DN<3>")
	)
	(segment
		(start 322.529708 -195.56603)
		(end 322.724272 -195.137786)
		(width 0.14732)
		(layer "In6.Cu")
		(net "UPI_CPU0_CPU1_P0P1_DN<3>")
	)
	(segment
		(start 323.936868 -195.35013)
		(end 323.529452 -195.504054)
		(width 0.14732)
		(layer "In6.Cu")
		(net "UPI_CPU0_CPU1_P0P1_DN<3>")
	)
	(segment
		(start 134.855204 -210.886548)
		(end 134.459726 -211.282026)
		(width 0.14732)
		(layer "In6.Cu")
		(net "UPI_CPU0_CPU1_P0P1_DN<3>")
	)
	(segment
		(start 323.334888 -195.931536)
		(end 323.140324 -196.004688)
		(width 0.14732)
		(layer "In6.Cu")
		(net "UPI_CPU0_CPU1_P0P1_DN<3>")
	)
	(segment
		(start 339.939884 -213.018116)
		(end 339.939884 -212.751416)
		(width 0.0889)
		(layer "In6.Cu")
		(net "UPI_CPU0_CPU1_P0P1_DN<3>")
	)
	(segment
		(start 328.16038 -197.267576)
		(end 326.046846 -196.30898)
		(width 0.14732)
		(layer "In6.Cu")
		(net "UPI_CPU0_CPU1_P0P1_DN<3>")
	)
	(segment
		(start 339.844126 -214.622634)
		(end 339.687662 -214.893652)
		(width 0.0889)
		(layer "In6.Cu")
		(net "UPI_CPU0_CPU1_P0P1_DN<3>")
	)
	(segment
		(start 302.46701 -185.81878)
		(end 273.011138 -186.631834)
		(width 0.14732)
		(layer "In6.Cu")
		(net "UPI_CPU0_CPU1_P0P1_DN<3>")
	)
	(arc
		(start 339.60943 -214.91448)
		(mid 339.506285 -214.784455)
		(end 339.469476 -214.622634)
		(width 0.0889)
		(layer "In6.Cu")
		(net "UPI_CPU0_CPU1_P0P1_DN<3>")
	)
	(arc
		(start 339.469476 -214.461852)
		(mid 339.544547 -214.34611)
		(end 339.65388 -214.261954)
		(width 0.0889)
		(layer "In6.Cu")
		(net "UPI_CPU0_CPU1_P0P1_DN<3>")
	)
	(arc
		(start 339.924644 -213.968584)
		(mid 339.932609 -213.94916)
		(end 339.939884 -213.929468)
		(width 0.0889)
		(layer "In6.Cu")
		(net "UPI_CPU0_CPU1_P0P1_DN<3>")
	)
	(arc
		(start 132.220716 -213.8934)
		(mid 132.166046 -213.985256)
		(end 132.089398 -214.05977)
		(width 0.0889)
		(layer "In6.Cu")
		(net "UPI_CPU0_CPU1_P0P1_DN<3>")
	)
	(arc
		(start 339.65388 -214.261954)
		(mid 339.814461 -214.138523)
		(end 339.924644 -213.968584)
		(width 0.0889)
		(layer "In6.Cu")
		(net "UPI_CPU0_CPU1_P0P1_DN<3>")
	)
	(segment
		(start 133.255512 -215.158574)
		(end 133.255512 -214.622888)
		(width 0.13208)
		(layer "F.Cu")
		(net "UPI_CPU0_CPU1_P0P1_DN<2>")
	)
	(segment
		(start 133.255512 -214.622888)
		(end 133.255258 -214.622634)
		(width 0.13208)
		(layer "F.Cu")
		(net "UPI_CPU0_CPU1_P0P1_DN<2>")
	)
	(segment
		(start 338.434934 -214.344758)
		(end 338.434934 -213.732618)
		(width 0.13208)
		(layer "F.Cu")
		(net "UPI_CPU0_CPU1_P0P1_DN<2>")
	)
	(segment
		(start 137.915904 -209.469736)
		(end 137.915396 -209.470498)
		(width 0.14732)
		(layer "In6.Cu")
		(net "UPI_CPU0_CPU1_P0P1_DN<2>")
	)
	(segment
		(start 133.847078 -213.480142)
		(end 133.847078 -213.620604)
		(width 0.0889)
		(layer "In6.Cu")
		(net "UPI_CPU0_CPU1_P0P1_DN<2>")
	)
	(segment
		(start 334.247998 -202.988926)
		(end 333.792322 -202.612752)
		(width 0.14732)
		(layer "In6.Cu")
		(net "UPI_CPU0_CPU1_P0P1_DN<2>")
	)
	(segment
		(start 159.988758 -187.8457)
		(end 158.876238 -188.509656)
		(width 0.14732)
		(layer "In6.Cu")
		(net "UPI_CPU0_CPU1_P0P1_DN<2>")
	)
	(segment
		(start 132.880354 -214.493856)
		(end 132.880354 -214.62238)
		(width 0.0889)
		(layer "In6.Cu")
		(net "UPI_CPU0_CPU1_P0P1_DN<2>")
	)
	(segment
		(start 137.915396 -209.470498)
		(end 135.42899 -211.956904)
		(width 0.14732)
		(layer "In6.Cu")
		(net "UPI_CPU0_CPU1_P0P1_DN<2>")
	)
	(segment
		(start 135.354568 -211.972398)
		(end 134.882382 -212.444584)
		(width 0.0889)
		(layer "In6.Cu")
		(net "UPI_CPU0_CPU1_P0P1_DN<2>")
	)
	(segment
		(start 338.809584 -213.488524)
		(end 338.71027 -213.38921)
		(width 0.0889)
		(layer "In6.Cu")
		(net "UPI_CPU0_CPU1_P0P1_DN<2>")
	)
	(segment
		(start 249.896376 -193.82359)
		(end 238.741712 -198.927974)
		(width 0.14732)
		(layer "In6.Cu")
		(net "UPI_CPU0_CPU1_P0P1_DN<2>")
	)
	(segment
		(start 338.767674 -211.66201)
		(end 338.767674 -211.537296)
		(width 0.14732)
		(layer "In6.Cu")
		(net "UPI_CPU0_CPU1_P0P1_DN<2>")
	)
	(segment
		(start 141.842744 -203.892912)
		(end 141.877796 -204.094588)
		(width 0.14732)
		(layer "In6.Cu")
		(net "UPI_CPU0_CPU1_P0P1_DN<2>")
	)
	(segment
		(start 140.872972 -205.270354)
		(end 137.915904 -209.469736)
		(width 0.14732)
		(layer "In6.Cu")
		(net "UPI_CPU0_CPU1_P0P1_DN<2>")
	)
	(segment
		(start 326.108568 -200.792334)
		(end 326.054974 -200.360026)
		(width 0.14732)
		(layer "In6.Cu")
		(net "UPI_CPU0_CPU1_P0P1_DN<2>")
	)
	(segment
		(start 314.67425 -190.012066)
		(end 314.72124 -189.812676)
		(width 0.14732)
		(layer "In6.Cu")
		(net "UPI_CPU0_CPU1_P0P1_DN<2>")
	)
	(segment
		(start 314.867798 -190.325502)
		(end 314.67425 -190.012066)
		(width 0.14732)
		(layer "In6.Cu")
		(net "UPI_CPU0_CPU1_P0P1_DN<2>")
	)
	(segment
		(start 315.505592 -191.357504)
		(end 315.312044 -191.044068)
		(width 0.14732)
		(layer "In6.Cu")
		(net "UPI_CPU0_CPU1_P0P1_DN<2>")
	)
	(segment
		(start 338.71027 -213.38921)
		(end 338.71027 -213.12251)
		(width 0.0889)
		(layer "In6.Cu")
		(net "UPI_CPU0_CPU1_P0P1_DN<2>")
	)
	(segment
		(start 133.847078 -213.620604)
		(end 133.658356 -213.809326)
		(width 0.0889)
		(layer "In6.Cu")
		(net "UPI_CPU0_CPU1_P0P1_DN<2>")
	)
	(segment
		(start 236.074712 -199.107044)
		(end 233.114596 -198.232014)
		(width 0.14732)
		(layer "In6.Cu")
		(net "UPI_CPU0_CPU1_P0P1_DN<2>")
	)
	(segment
		(start 142.4686 -203.255372)
		(end 142.256764 -203.55687)
		(width 0.14732)
		(layer "In6.Cu")
		(net "UPI_CPU0_CPU1_P0P1_DN<2>")
	)
	(segment
		(start 134.69366 -212.773768)
		(end 134.553198 -212.773768)
		(width 0.0889)
		(layer "In6.Cu")
		(net "UPI_CPU0_CPU1_P0P1_DN<2>")
	)
	(segment
		(start 134.36473 -212.962236)
		(end 134.36473 -213.102698)
		(width 0.0889)
		(layer "In6.Cu")
		(net "UPI_CPU0_CPU1_P0P1_DN<2>")
	)
	(segment
		(start 315.067442 -190.372746)
		(end 314.867798 -190.325502)
		(width 0.14732)
		(layer "In6.Cu")
		(net "UPI_CPU0_CPU1_P0P1_DN<2>")
	)
	(segment
		(start 331.260196 -204.965554)
		(end 327.880726 -202.175872)
		(width 0.14732)
		(layer "In6.Cu")
		(net "UPI_CPU0_CPU1_P0P1_DN<2>")
	)
	(segment
		(start 338.71027 -212.657182)
		(end 338.71027 -212.390482)
		(width 0.0889)
		(layer "In6.Cu")
		(net "UPI_CPU0_CPU1_P0P1_DN<2>")
	)
	(segment
		(start 338.809584 -213.023196)
		(end 338.809584 -212.756496)
		(width 0.0889)
		(layer "In6.Cu")
		(net "UPI_CPU0_CPU1_P0P1_DN<2>")
	)
	(segment
		(start 134.882382 -212.585046)
		(end 134.69366 -212.773768)
		(width 0.0889)
		(layer "In6.Cu")
		(net "UPI_CPU0_CPU1_P0P1_DN<2>")
	)
	(segment
		(start 141.286992 -204.933804)
		(end 141.074902 -205.235302)
		(width 0.14732)
		(layer "In6.Cu")
		(net "UPI_CPU0_CPU1_P0P1_DN<2>")
	)
	(segment
		(start 134.882382 -212.444584)
		(end 134.882382 -212.585046)
		(width 0.0889)
		(layer "In6.Cu")
		(net "UPI_CPU0_CPU1_P0P1_DN<2>")
	)
	(segment
		(start 268.622526 -190.424054)
		(end 267.475462 -190.596012)
		(width 0.14732)
		(layer "In6.Cu")
		(net "UPI_CPU0_CPU1_P0P1_DN<2>")
	)
	(segment
		(start 133.658356 -213.809326)
		(end 133.517894 -213.809326)
		(width 0.0889)
		(layer "In6.Cu")
		(net "UPI_CPU0_CPU1_P0P1_DN<2>")
	)
	(segment
		(start 298.247816 -187.208922)
		(end 298.098972 -187.068206)
		(width 0.14732)
		(layer "In6.Cu")
		(net "UPI_CPU0_CPU1_P0P1_DN<2>")
	)
	(segment
		(start 133.020562 -214.91448)
		(end 133.098794 -214.893652)
		(width 0.0889)
		(layer "In6.Cu")
		(net "UPI_CPU0_CPU1_P0P1_DN<2>")
	)
	(segment
		(start 326.054974 -200.360026)
		(end 326.421242 -199.89165)
		(width 0.14732)
		(layer "In6.Cu")
		(net "UPI_CPU0_CPU1_P0P1_DN<2>")
	)
	(segment
		(start 132.880354 -214.62238)
		(end 132.880608 -214.622634)
		(width 0.0889)
		(layer "In6.Cu")
		(net "UPI_CPU0_CPU1_P0P1_DN<2>")
	)
	(segment
		(start 317.216028 -193.849498)
		(end 315.705236 -191.404494)
		(width 0.14732)
		(layer "In6.Cu")
		(net "UPI_CPU0_CPU1_P0P1_DN<2>")
	)
	(segment
		(start 135.413496 -211.972398)
		(end 135.354568 -211.972398)
		(width 0.0889)
		(layer "In6.Cu")
		(net "UPI_CPU0_CPU1_P0P1_DN<2>")
	)
	(segment
		(start 302.45304 -186.947302)
		(end 298.756832 -187.049664)
		(width 0.14732)
		(layer "In6.Cu")
		(net "UPI_CPU0_CPU1_P0P1_DN<2>")
	)
	(segment
		(start 133.517894 -213.809326)
		(end 132.913628 -214.413592)
		(width 0.0889)
		(layer "In6.Cu")
		(net "UPI_CPU0_CPU1_P0P1_DN<2>")
	)
	(segment
		(start 326.421242 -199.89165)
		(end 326.395588 -199.685402)
		(width 0.14732)
		(layer "In6.Cu")
		(net "UPI_CPU0_CPU1_P0P1_DN<2>")
	)
	(segment
		(start 332.376018 -205.48727)
		(end 334.26781 -203.195682)
		(width 0.14732)
		(layer "In6.Cu")
		(net "UPI_CPU0_CPU1_P0P1_DN<2>")
	)
	(segment
		(start 313.560714 -187.9346)
		(end 312.632852 -187.349892)
		(width 0.14732)
		(layer "In6.Cu")
		(net "UPI_CPU0_CPU1_P0P1_DN<2>")
	)
	(segment
		(start 207.786478 -187.947046)
		(end 200.166732 -187.155582)
		(width 0.14732)
		(layer "In6.Cu")
		(net "UPI_CPU0_CPU1_P0P1_DN<2>")
	)
	(segment
		(start 338.71027 -212.390482)
		(end 338.809584 -212.291168)
		(width 0.0889)
		(layer "In6.Cu")
		(net "UPI_CPU0_CPU1_P0P1_DN<2>")
	)
	(segment
		(start 271.860518 -188.067442)
		(end 269.03553 -190.27267)
		(width 0.14732)
		(layer "In6.Cu")
		(net "UPI_CPU0_CPU1_P0P1_DN<2>")
	)
	(segment
		(start 333.792322 -202.612752)
		(end 333.585566 -202.632564)
		(width 0.14732)
		(layer "In6.Cu")
		(net "UPI_CPU0_CPU1_P0P1_DN<2>")
	)
	(segment
		(start 150.127208 -195.752212)
		(end 150.049738 -195.94195)
		(width 0.14732)
		(layer "In6.Cu")
		(net "UPI_CPU0_CPU1_P0P1_DN<2>")
	)
	(segment
		(start 141.463776 -204.431138)
		(end 141.25194 -204.732128)
		(width 0.14732)
		(layer "In6.Cu")
		(net "UPI_CPU0_CPU1_P0P1_DN<2>")
	)
	(segment
		(start 333.585566 -202.632564)
		(end 331.693774 -204.924152)
		(width 0.14732)
		(layer "In6.Cu")
		(net "UPI_CPU0_CPU1_P0P1_DN<2>")
	)
	(segment
		(start 332.41742 -205.920848)
		(end 332.376018 -205.48727)
		(width 0.14732)
		(layer "In6.Cu")
		(net "UPI_CPU0_CPU1_P0P1_DN<2>")
	)
	(segment
		(start 325.358506 -199.815704)
		(end 324.925944 -199.869044)
		(width 0.14732)
		(layer "In6.Cu")
		(net "UPI_CPU0_CPU1_P0P1_DN<2>")
	)
	(segment
		(start 334.26781 -203.195682)
		(end 334.247998 -202.988926)
		(width 0.14732)
		(layer "In6.Cu")
		(net "UPI_CPU0_CPU1_P0P1_DN<2>")
	)
	(segment
		(start 269.03553 -190.27267)
		(end 268.622526 -190.424054)
		(width 0.14732)
		(layer "In6.Cu")
		(net "UPI_CPU0_CPU1_P0P1_DN<2>")
	)
	(segment
		(start 315.359034 -190.844678)
		(end 315.067442 -190.372746)
		(width 0.14732)
		(layer "In6.Cu")
		(net "UPI_CPU0_CPU1_P0P1_DN<2>")
	)
	(segment
		(start 273.043904 -187.763404)
		(end 271.860518 -188.067442)
		(width 0.14732)
		(layer "In6.Cu")
		(net "UPI_CPU0_CPU1_P0P1_DN<2>")
	)
	(segment
		(start 338.76742 -210.554316)
		(end 337.834986 -209.621882)
		(width 0.14732)
		(layer "In6.Cu")
		(net "UPI_CPU0_CPU1_P0P1_DN<2>")
	)
	(segment
		(start 338.809584 -211.726018)
		(end 338.767674 -211.684108)
		(width 0.0889)
		(layer "In6.Cu")
		(net "UPI_CPU0_CPU1_P0P1_DN<2>")
	)
	(segment
		(start 237.308898 -199.107044)
		(end 236.074712 -199.107044)
		(width 0.14732)
		(layer "In6.Cu")
		(net "UPI_CPU0_CPU1_P0P1_DN<2>")
	)
	(segment
		(start 134.553198 -212.773768)
		(end 134.36473 -212.962236)
		(width 0.0889)
		(layer "In6.Cu")
		(net "UPI_CPU0_CPU1_P0P1_DN<2>")
	)
	(segment
		(start 142.433548 -203.053696)
		(end 142.4686 -203.255372)
		(width 0.14732)
		(layer "In6.Cu")
		(net "UPI_CPU0_CPU1_P0P1_DN<2>")
	)
	(segment
		(start 150.049738 -195.94195)
		(end 149.709886 -196.084444)
		(width 0.14732)
		(layer "In6.Cu")
		(net "UPI_CPU0_CPU1_P0P1_DN<2>")
	)
	(segment
		(start 338.809584 -213.8934)
		(end 338.809584 -213.488524)
		(width 0.0889)
		(layer "In6.Cu")
		(net "UPI_CPU0_CPU1_P0P1_DN<2>")
	)
	(segment
		(start 158.876238 -188.509656)
		(end 152.723596 -194.662044)
		(width 0.14732)
		(layer "In6.Cu")
		(net "UPI_CPU0_CPU1_P0P1_DN<2>")
	)
	(segment
		(start 135.42899 -211.956904)
		(end 135.413496 -211.972398)
		(width 0.0889)
		(layer "In6.Cu")
		(net "UPI_CPU0_CPU1_P0P1_DN<2>")
	)
	(segment
		(start 144.18818 -200.561956)
		(end 142.433548 -203.053696)
		(width 0.14732)
		(layer "In6.Cu")
		(net "UPI_CPU0_CPU1_P0P1_DN<2>")
	)
	(segment
		(start 141.25194 -204.732128)
		(end 141.286992 -204.933804)
		(width 0.14732)
		(layer "In6.Cu")
		(net "UPI_CPU0_CPU1_P0P1_DN<2>")
	)
	(segment
		(start 338.71027 -213.12251)
		(end 338.809584 -213.023196)
		(width 0.0889)
		(layer "In6.Cu")
		(net "UPI_CPU0_CPU1_P0P1_DN<2>")
	)
	(segment
		(start 315.312044 -191.044068)
		(end 315.359034 -190.844678)
		(width 0.14732)
		(layer "In6.Cu")
		(net "UPI_CPU0_CPU1_P0P1_DN<2>")
	)
	(segment
		(start 211.220304 -187.71235)
		(end 207.786478 -187.947046)
		(width 0.14732)
		(layer "In6.Cu")
		(net "UPI_CPU0_CPU1_P0P1_DN<2>")
	)
	(segment
		(start 312.632852 -187.349892)
		(end 311.861708 -187.119514)
		(width 0.14732)
		(layer "In6.Cu")
		(net "UPI_CPU0_CPU1_P0P1_DN<2>")
	)
	(segment
		(start 325.724266 -199.347328)
		(end 325.358506 -199.815704)
		(width 0.14732)
		(layer "In6.Cu")
		(net "UPI_CPU0_CPU1_P0P1_DN<2>")
	)
	(segment
		(start 326.395588 -199.685402)
		(end 325.93026 -199.321674)
		(width 0.14732)
		(layer "In6.Cu")
		(net "UPI_CPU0_CPU1_P0P1_DN<2>")
	)
	(segment
		(start 223.238314 -191.835278)
		(end 215.004904 -187.944506)
		(width 0.14732)
		(layer "In6.Cu")
		(net "UPI_CPU0_CPU1_P0P1_DN<2>")
	)
	(segment
		(start 337.834986 -209.621882)
		(end 335.958942 -208.844388)
		(width 0.14732)
		(layer "In6.Cu")
		(net "UPI_CPU0_CPU1_P0P1_DN<2>")
	)
	(segment
		(start 338.809584 -212.756496)
		(end 338.71027 -212.657182)
		(width 0.0889)
		(layer "In6.Cu")
		(net "UPI_CPU0_CPU1_P0P1_DN<2>")
	)
	(segment
		(start 314.72124 -189.812676)
		(end 313.560714 -187.9346)
		(width 0.14732)
		(layer "In6.Cu")
		(net "UPI_CPU0_CPU1_P0P1_DN<2>")
	)
	(segment
		(start 200.166732 -187.155582)
		(end 159.988758 -187.8457)
		(width 0.14732)
		(layer "In6.Cu")
		(net "UPI_CPU0_CPU1_P0P1_DN<2>")
	)
	(segment
		(start 141.877796 -204.094588)
		(end 141.66596 -204.396086)
		(width 0.14732)
		(layer "In6.Cu")
		(net "UPI_CPU0_CPU1_P0P1_DN<2>")
	)
	(segment
		(start 338.434934 -213.732618)
		(end 338.593684 -214.033608)
		(width 0.0889)
		(layer "In6.Cu")
		(net "UPI_CPU0_CPU1_P0P1_DN<2>")
	)
	(segment
		(start 335.958942 -208.844388)
		(end 332.41742 -205.920848)
		(width 0.14732)
		(layer "In6.Cu")
		(net "UPI_CPU0_CPU1_P0P1_DN<2>")
	)
	(segment
		(start 141.074902 -205.235302)
		(end 140.872972 -205.270354)
		(width 0.14732)
		(layer "In6.Cu")
		(net "UPI_CPU0_CPU1_P0P1_DN<2>")
	)
	(segment
		(start 327.880726 -202.175872)
		(end 326.108568 -200.792334)
		(width 0.14732)
		(layer "In6.Cu")
		(net "UPI_CPU0_CPU1_P0P1_DN<2>")
	)
	(segment
		(start 233.114596 -198.232014)
		(end 223.238314 -191.835278)
		(width 0.14732)
		(layer "In6.Cu")
		(net "UPI_CPU0_CPU1_P0P1_DN<2>")
	)
	(segment
		(start 149.709886 -196.084444)
		(end 149.520402 -196.007228)
		(width 0.14732)
		(layer "In6.Cu")
		(net "UPI_CPU0_CPU1_P0P1_DN<2>")
	)
	(segment
		(start 324.925944 -199.869044)
		(end 317.216028 -193.849498)
		(width 0.14732)
		(layer "In6.Cu")
		(net "UPI_CPU0_CPU1_P0P1_DN<2>")
	)
	(segment
		(start 338.809584 -212.291168)
		(end 338.809584 -211.726018)
		(width 0.0889)
		(layer "In6.Cu")
		(net "UPI_CPU0_CPU1_P0P1_DN<2>")
	)
	(segment
		(start 298.756832 -187.049664)
		(end 298.616116 -187.198762)
		(width 0.14732)
		(layer "In6.Cu")
		(net "UPI_CPU0_CPU1_P0P1_DN<2>")
	)
	(segment
		(start 134.035546 -213.291674)
		(end 133.847078 -213.480142)
		(width 0.0889)
		(layer "In6.Cu")
		(net "UPI_CPU0_CPU1_P0P1_DN<2>")
	)
	(segment
		(start 338.767674 -211.537296)
		(end 338.76742 -211.53755)
		(width 0.14732)
		(layer "In6.Cu")
		(net "UPI_CPU0_CPU1_P0P1_DN<2>")
	)
	(segment
		(start 325.93026 -199.321674)
		(end 325.724266 -199.347328)
		(width 0.14732)
		(layer "In6.Cu")
		(net "UPI_CPU0_CPU1_P0P1_DN<2>")
	)
	(segment
		(start 298.616116 -187.198762)
		(end 298.247816 -187.208922)
		(width 0.14732)
		(layer "In6.Cu")
		(net "UPI_CPU0_CPU1_P0P1_DN<2>")
	)
	(segment
		(start 261.033514 -190.865252)
		(end 249.896376 -193.82359)
		(width 0.14732)
		(layer "In6.Cu")
		(net "UPI_CPU0_CPU1_P0P1_DN<2>")
	)
	(segment
		(start 338.593684 -214.033608)
		(end 338.678266 -214.05977)
		(width 0.0889)
		(layer "In6.Cu")
		(net "UPI_CPU0_CPU1_P0P1_DN<2>")
	)
	(segment
		(start 152.723596 -194.662044)
		(end 150.127208 -195.752212)
		(width 0.14732)
		(layer "In6.Cu")
		(net "UPI_CPU0_CPU1_P0P1_DN<2>")
	)
	(segment
		(start 142.256764 -203.55687)
		(end 142.05458 -203.591922)
		(width 0.14732)
		(layer "In6.Cu")
		(net "UPI_CPU0_CPU1_P0P1_DN<2>")
	)
	(segment
		(start 338.76742 -211.53755)
		(end 338.76742 -210.554316)
		(width 0.14732)
		(layer "In6.Cu")
		(net "UPI_CPU0_CPU1_P0P1_DN<2>")
	)
	(segment
		(start 133.098794 -214.893652)
		(end 133.255258 -214.622634)
		(width 0.0889)
		(layer "In6.Cu")
		(net "UPI_CPU0_CPU1_P0P1_DN<2>")
	)
	(segment
		(start 149.520402 -196.007228)
		(end 148.767546 -196.323204)
		(width 0.14732)
		(layer "In6.Cu")
		(net "UPI_CPU0_CPU1_P0P1_DN<2>")
	)
	(segment
		(start 238.741712 -198.927974)
		(end 237.308898 -199.107044)
		(width 0.14732)
		(layer "In6.Cu")
		(net "UPI_CPU0_CPU1_P0P1_DN<2>")
	)
	(segment
		(start 267.475462 -190.596012)
		(end 261.033514 -190.865252)
		(width 0.14732)
		(layer "In6.Cu")
		(net "UPI_CPU0_CPU1_P0P1_DN<2>")
	)
	(segment
		(start 311.861708 -187.119514)
		(end 302.45304 -186.947302)
		(width 0.14732)
		(layer "In6.Cu")
		(net "UPI_CPU0_CPU1_P0P1_DN<2>")
	)
	(segment
		(start 141.66596 -204.396086)
		(end 141.463776 -204.431138)
		(width 0.14732)
		(layer "In6.Cu")
		(net "UPI_CPU0_CPU1_P0P1_DN<2>")
	)
	(segment
		(start 331.693774 -204.924152)
		(end 331.260196 -204.965554)
		(width 0.14732)
		(layer "In6.Cu")
		(net "UPI_CPU0_CPU1_P0P1_DN<2>")
	)
	(segment
		(start 215.004904 -187.944506)
		(end 211.220304 -187.71235)
		(width 0.14732)
		(layer "In6.Cu")
		(net "UPI_CPU0_CPU1_P0P1_DN<2>")
	)
	(segment
		(start 315.705236 -191.404494)
		(end 315.505592 -191.357504)
		(width 0.14732)
		(layer "In6.Cu")
		(net "UPI_CPU0_CPU1_P0P1_DN<2>")
	)
	(segment
		(start 134.176008 -213.291674)
		(end 134.035546 -213.291674)
		(width 0.0889)
		(layer "In6.Cu")
		(net "UPI_CPU0_CPU1_P0P1_DN<2>")
	)
	(segment
		(start 338.767674 -211.684108)
		(end 338.767674 -211.66201)
		(width 0.0889)
		(layer "In6.Cu")
		(net "UPI_CPU0_CPU1_P0P1_DN<2>")
	)
	(segment
		(start 148.767546 -196.323204)
		(end 144.18818 -200.561956)
		(width 0.14732)
		(layer "In6.Cu")
		(net "UPI_CPU0_CPU1_P0P1_DN<2>")
	)
	(segment
		(start 142.05458 -203.591922)
		(end 141.842744 -203.892912)
		(width 0.14732)
		(layer "In6.Cu")
		(net "UPI_CPU0_CPU1_P0P1_DN<2>")
	)
	(segment
		(start 134.36473 -213.102698)
		(end 134.176008 -213.291674)
		(width 0.0889)
		(layer "In6.Cu")
		(net "UPI_CPU0_CPU1_P0P1_DN<2>")
	)
	(segment
		(start 298.098972 -187.068206)
		(end 273.043904 -187.763404)
		(width 0.14732)
		(layer "In6.Cu")
		(net "UPI_CPU0_CPU1_P0P1_DN<2>")
	)
	(arc
		(start 132.880608 -214.622634)
		(mid 132.917468 -214.784431)
		(end 133.020562 -214.91448)
		(width 0.0889)
		(layer "In6.Cu")
		(net "UPI_CPU0_CPU1_P0P1_DN<2>")
	)
	(arc
		(start 132.913628 -214.413592)
		(mid 132.888968 -214.450403)
		(end 132.880354 -214.493856)
		(width 0.0889)
		(layer "In6.Cu")
		(net "UPI_CPU0_CPU1_P0P1_DN<2>")
	)
	(arc
		(start 338.678266 -214.05977)
		(mid 338.754939 -213.985276)
		(end 338.809584 -213.8934)
		(width 0.0889)
		(layer "In6.Cu")
		(net "UPI_CPU0_CPU1_P0P1_DN<2>")
	)
	(segment
		(start 358.640634 -214.623142)
		(end 358.640126 -214.622634)
		(width 0.13208)
		(layer "F.Cu")
		(net "UPI_CPU0_CPU1_P0P1_DN<23>")
	)
	(segment
		(start 113.519712 -215.158574)
		(end 113.519712 -214.622888)
		(width 0.13208)
		(layer "F.Cu")
		(net "UPI_CPU0_CPU1_P0P1_DN<23>")
	)
	(segment
		(start 113.519712 -214.622888)
		(end 113.519458 -214.622634)
		(width 0.13208)
		(layer "F.Cu")
		(net "UPI_CPU0_CPU1_P0P1_DN<23>")
	)
	(segment
		(start 113.519458 -214.622634)
		(end 113.519458 -214.546434)
		(width 0.13208)
		(layer "F.Cu")
		(net "UPI_CPU0_CPU1_P0P1_DN<23>")
	)
	(segment
		(start 358.640634 -215.158574)
		(end 358.640634 -214.623142)
		(width 0.13208)
		(layer "F.Cu")
		(net "UPI_CPU0_CPU1_P0P1_DN<23>")
	)
	(segment
		(start 136.723882 -178.315112)
		(end 132.438648 -184.06618)
		(width 0.14732)
		(layer "In6.Cu")
		(net "UPI_CPU0_CPU1_P0P1_DN<23>")
	)
	(segment
		(start 358.44607 -212.61959)
		(end 358.44607 -212.35289)
		(width 0.0889)
		(layer "In6.Cu")
		(net "UPI_CPU0_CPU1_P0P1_DN<23>")
	)
	(segment
		(start 210.780884 -169.868596)
		(end 200.408286 -169.413428)
		(width 0.14732)
		(layer "In6.Cu")
		(net "UPI_CPU0_CPU1_P0P1_DN<23>")
	)
	(segment
		(start 121.133108 -193.515742)
		(end 120.961404 -193.533522)
		(width 0.14732)
		(layer "In6.Cu")
		(net "UPI_CPU0_CPU1_P0P1_DN<23>")
	)
	(segment
		(start 113.528094 -212.610954)
		(end 113.528094 -212.633052)
		(width 0.0889)
		(layer "In6.Cu")
		(net "UPI_CPU0_CPU1_P0P1_DN<23>")
	)
	(segment
		(start 358.50322 -211.730336)
		(end 358.50322 -209.943954)
		(width 0.14732)
		(layer "In6.Cu")
		(net "UPI_CPU0_CPU1_P0P1_DN<23>")
	)
	(segment
		(start 359.014776 -214.622634)
		(end 359.014776 -214.237824)
		(width 0.0889)
		(layer "In6.Cu")
		(net "UPI_CPU0_CPU1_P0P1_DN<23>")
	)
	(segment
		(start 119.551196 -195.268342)
		(end 119.27586 -195.607178)
		(width 0.14732)
		(layer "In6.Cu")
		(net "UPI_CPU0_CPU1_P0P1_DN<23>")
	)
	(segment
		(start 120.2563 -194.400932)
		(end 119.980964 -194.739768)
		(width 0.14732)
		(layer "In6.Cu")
		(net "UPI_CPU0_CPU1_P0P1_DN<23>")
	)
	(segment
		(start 354.381308 -195.608194)
		(end 354.149152 -195.321936)
		(width 0.14732)
		(layer "In6.Cu")
		(net "UPI_CPU0_CPU1_P0P1_DN<23>")
	)
	(segment
		(start 120.703594 -194.043808)
		(end 120.428004 -194.383152)
		(width 0.14732)
		(layer "In6.Cu")
		(net "UPI_CPU0_CPU1_P0P1_DN<23>")
	)
	(segment
		(start 113.268252 -214.546434)
		(end 113.519458 -214.546434)
		(width 0.0889)
		(layer "In6.Cu")
		(net "UPI_CPU0_CPU1_P0P1_DN<23>")
	)
	(segment
		(start 320.483484 -170.995848)
		(end 314.069476 -169.202608)
		(width 0.14732)
		(layer "In6.Cu")
		(net "UPI_CPU0_CPU1_P0P1_DN<23>")
	)
	(segment
		(start 353.938332 -194.832478)
		(end 353.734878 -194.811396)
		(width 0.14732)
		(layer "In6.Cu")
		(net "UPI_CPU0_CPU1_P0P1_DN<23>")
	)
	(segment
		(start 119.017796 -196.117972)
		(end 118.846346 -196.135498)
		(width 0.14732)
		(layer "In6.Cu")
		(net "UPI_CPU0_CPU1_P0P1_DN<23>")
	)
	(segment
		(start 149.699218 -171.671996)
		(end 136.723882 -178.315112)
		(width 0.14732)
		(layer "In6.Cu")
		(net "UPI_CPU0_CPU1_P0P1_DN<23>")
	)
	(segment
		(start 113.144554 -213.891114)
		(end 113.144554 -214.422736)
		(width 0.0889)
		(layer "In6.Cu")
		(net "UPI_CPU0_CPU1_P0P1_DN<23>")
	)
	(segment
		(start 122.096276 -192.137538)
		(end 122.113802 -192.308988)
		(width 0.14732)
		(layer "In6.Cu")
		(net "UPI_CPU0_CPU1_P0P1_DN<23>")
	)
	(segment
		(start 358.44607 -212.35289)
		(end 358.545384 -212.253576)
		(width 0.0889)
		(layer "In6.Cu")
		(net "UPI_CPU0_CPU1_P0P1_DN<23>")
	)
	(segment
		(start 320.64833 -171.091606)
		(end 320.483484 -170.995848)
		(width 0.14732)
		(layer "In6.Cu")
		(net "UPI_CPU0_CPU1_P0P1_DN<23>")
	)
	(segment
		(start 273.029426 -169.70375)
		(end 238.595916 -169.868596)
		(width 0.14732)
		(layer "In6.Cu")
		(net "UPI_CPU0_CPU1_P0P1_DN<23>")
	)
	(segment
		(start 342.044528 -183.137048)
		(end 337.849718 -180.08473)
		(width 0.14732)
		(layer "In6.Cu")
		(net "UPI_CPU0_CPU1_P0P1_DN<23>")
	)
	(segment
		(start 119.980964 -194.739768)
		(end 119.99849 -194.911218)
		(width 0.14732)
		(layer "In6.Cu")
		(net "UPI_CPU0_CPU1_P0P1_DN<23>")
	)
	(segment
		(start 238.595916 -169.868596)
		(end 210.780884 -169.868596)
		(width 0.14732)
		(layer "In6.Cu")
		(net "UPI_CPU0_CPU1_P0P1_DN<23>")
	)
	(segment
		(start 113.528094 -212.633052)
		(end 113.48593 -212.675216)
		(width 0.0889)
		(layer "In6.Cu")
		(net "UPI_CPU0_CPU1_P0P1_DN<23>")
	)
	(segment
		(start 119.27586 -195.607178)
		(end 119.29364 -195.778628)
		(width 0.14732)
		(layer "In6.Cu")
		(net "UPI_CPU0_CPU1_P0P1_DN<23>")
	)
	(segment
		(start 132.438648 -184.06618)
		(end 124.212858 -189.533276)
		(width 0.14732)
		(layer "In6.Cu")
		(net "UPI_CPU0_CPU1_P0P1_DN<23>")
	)
	(segment
		(start 353.227132 -193.95567)
		(end 342.044528 -183.137048)
		(width 0.14732)
		(layer "In6.Cu")
		(net "UPI_CPU0_CPU1_P0P1_DN<23>")
	)
	(segment
		(start 113.48593 -212.675216)
		(end 113.48593 -213.549738)
		(width 0.0889)
		(layer "In6.Cu")
		(net "UPI_CPU0_CPU1_P0P1_DN<23>")
	)
	(segment
		(start 354.585016 -195.62953)
		(end 354.381308 -195.608194)
		(width 0.14732)
		(layer "In6.Cu")
		(net "UPI_CPU0_CPU1_P0P1_DN<23>")
	)
	(segment
		(start 354.170234 -195.118482)
		(end 353.938332 -194.832478)
		(width 0.14732)
		(layer "In6.Cu")
		(net "UPI_CPU0_CPU1_P0P1_DN<23>")
	)
	(segment
		(start 113.528094 -209.931)
		(end 113.528094 -212.610954)
		(width 0.14732)
		(layer "In6.Cu")
		(net "UPI_CPU0_CPU1_P0P1_DN<23>")
	)
	(segment
		(start 358.545384 -212.253576)
		(end 358.545384 -211.794598)
		(width 0.0889)
		(layer "In6.Cu")
		(net "UPI_CPU0_CPU1_P0P1_DN<23>")
	)
	(segment
		(start 314.069476 -169.202608)
		(end 302.46828 -168.986454)
		(width 0.14732)
		(layer "In6.Cu")
		(net "UPI_CPU0_CPU1_P0P1_DN<23>")
	)
	(segment
		(start 121.408698 -193.176398)
		(end 121.133108 -193.515742)
		(width 0.14732)
		(layer "In6.Cu")
		(net "UPI_CPU0_CPU1_P0P1_DN<23>")
	)
	(segment
		(start 122.583956 -191.73063)
		(end 122.412506 -191.74841)
		(width 0.14732)
		(layer "In6.Cu")
		(net "UPI_CPU0_CPU1_P0P1_DN<23>")
	)
	(segment
		(start 122.113802 -192.308988)
		(end 121.838212 -192.648332)
		(width 0.14732)
		(layer "In6.Cu")
		(net "UPI_CPU0_CPU1_P0P1_DN<23>")
	)
	(segment
		(start 358.545384 -213.450932)
		(end 358.44607 -213.351618)
		(width 0.0889)
		(layer "In6.Cu")
		(net "UPI_CPU0_CPU1_P0P1_DN<23>")
	)
	(segment
		(start 358.640126 -214.622634)
		(end 358.79659 -214.893652)
		(width 0.0889)
		(layer "In6.Cu")
		(net "UPI_CPU0_CPU1_P0P1_DN<23>")
	)
	(segment
		(start 358.79659 -214.893652)
		(end 358.874822 -214.91448)
		(width 0.0889)
		(layer "In6.Cu")
		(net "UPI_CPU0_CPU1_P0P1_DN<23>")
	)
	(segment
		(start 357.353108 -199.041512)
		(end 354.585016 -195.62953)
		(width 0.14732)
		(layer "In6.Cu")
		(net "UPI_CPU0_CPU1_P0P1_DN<23>")
	)
	(segment
		(start 119.7229 -195.250562)
		(end 119.551196 -195.268342)
		(width 0.14732)
		(layer "In6.Cu")
		(net "UPI_CPU0_CPU1_P0P1_DN<23>")
	)
	(segment
		(start 302.46828 -168.986454)
		(end 273.029426 -169.70375)
		(width 0.14732)
		(layer "In6.Cu")
		(net "UPI_CPU0_CPU1_P0P1_DN<23>")
	)
	(segment
		(start 358.503474 -211.73059)
		(end 358.50322 -211.730336)
		(width 0.14732)
		(layer "In6.Cu")
		(net "UPI_CPU0_CPU1_P0P1_DN<23>")
	)
	(segment
		(start 358.545384 -211.794598)
		(end 358.503474 -211.752688)
		(width 0.0889)
		(layer "In6.Cu")
		(net "UPI_CPU0_CPU1_P0P1_DN<23>")
	)
	(segment
		(start 121.838212 -192.648332)
		(end 121.666508 -192.666112)
		(width 0.14732)
		(layer "In6.Cu")
		(net "UPI_CPU0_CPU1_P0P1_DN<23>")
	)
	(segment
		(start 200.408286 -169.413428)
		(end 155.61437 -170.158156)
		(width 0.14732)
		(layer "In6.Cu")
		(net "UPI_CPU0_CPU1_P0P1_DN<23>")
	)
	(segment
		(start 118.846346 -196.135498)
		(end 117.987318 -197.192392)
		(width 0.14732)
		(layer "In6.Cu")
		(net "UPI_CPU0_CPU1_P0P1_DN<23>")
	)
	(segment
		(start 122.84202 -191.219836)
		(end 122.8598 -191.391286)
		(width 0.14732)
		(layer "In6.Cu")
		(net "UPI_CPU0_CPU1_P0P1_DN<23>")
	)
	(segment
		(start 120.686068 -193.872358)
		(end 120.703594 -194.043808)
		(width 0.14732)
		(layer "In6.Cu")
		(net "UPI_CPU0_CPU1_P0P1_DN<23>")
	)
	(segment
		(start 122.412506 -191.74841)
		(end 122.096276 -192.137538)
		(width 0.14732)
		(layer "In6.Cu")
		(net "UPI_CPU0_CPU1_P0P1_DN<23>")
	)
	(segment
		(start 120.961404 -193.533522)
		(end 120.686068 -193.872358)
		(width 0.14732)
		(layer "In6.Cu")
		(net "UPI_CPU0_CPU1_P0P1_DN<23>")
	)
	(segment
		(start 119.99849 -194.911218)
		(end 119.7229 -195.250562)
		(width 0.14732)
		(layer "In6.Cu")
		(net "UPI_CPU0_CPU1_P0P1_DN<23>")
	)
	(segment
		(start 353.502468 -194.525138)
		(end 353.523804 -194.32143)
		(width 0.14732)
		(layer "In6.Cu")
		(net "UPI_CPU0_CPU1_P0P1_DN<23>")
	)
	(segment
		(start 119.29364 -195.778628)
		(end 119.017796 -196.117972)
		(width 0.14732)
		(layer "In6.Cu")
		(net "UPI_CPU0_CPU1_P0P1_DN<23>")
	)
	(segment
		(start 358.545384 -212.985604)
		(end 358.545384 -212.718904)
		(width 0.0889)
		(layer "In6.Cu")
		(net "UPI_CPU0_CPU1_P0P1_DN<23>")
	)
	(segment
		(start 121.666508 -192.666112)
		(end 121.391172 -193.004948)
		(width 0.14732)
		(layer "In6.Cu")
		(net "UPI_CPU0_CPU1_P0P1_DN<23>")
	)
	(segment
		(start 117.987318 -197.192392)
		(end 113.528094 -209.931)
		(width 0.14732)
		(layer "In6.Cu")
		(net "UPI_CPU0_CPU1_P0P1_DN<23>")
	)
	(segment
		(start 359.014776 -214.237824)
		(end 358.545384 -213.768432)
		(width 0.0889)
		(layer "In6.Cu")
		(net "UPI_CPU0_CPU1_P0P1_DN<23>")
	)
	(segment
		(start 358.50322 -209.943954)
		(end 357.353108 -199.041512)
		(width 0.14732)
		(layer "In6.Cu")
		(net "UPI_CPU0_CPU1_P0P1_DN<23>")
	)
	(segment
		(start 358.44607 -213.084918)
		(end 358.545384 -212.985604)
		(width 0.0889)
		(layer "In6.Cu")
		(net "UPI_CPU0_CPU1_P0P1_DN<23>")
	)
	(segment
		(start 353.734878 -194.811396)
		(end 353.502468 -194.525138)
		(width 0.14732)
		(layer "In6.Cu")
		(net "UPI_CPU0_CPU1_P0P1_DN<23>")
	)
	(segment
		(start 358.44607 -213.351618)
		(end 358.44607 -213.084918)
		(width 0.0889)
		(layer "In6.Cu")
		(net "UPI_CPU0_CPU1_P0P1_DN<23>")
	)
	(segment
		(start 354.149152 -195.321936)
		(end 354.170234 -195.118482)
		(width 0.14732)
		(layer "In6.Cu")
		(net "UPI_CPU0_CPU1_P0P1_DN<23>")
	)
	(segment
		(start 122.8598 -191.391286)
		(end 122.583956 -191.73063)
		(width 0.14732)
		(layer "In6.Cu")
		(net "UPI_CPU0_CPU1_P0P1_DN<23>")
	)
	(segment
		(start 120.428004 -194.383152)
		(end 120.2563 -194.400932)
		(width 0.14732)
		(layer "In6.Cu")
		(net "UPI_CPU0_CPU1_P0P1_DN<23>")
	)
	(segment
		(start 337.849718 -180.08473)
		(end 320.64833 -171.091606)
		(width 0.14732)
		(layer "In6.Cu")
		(net "UPI_CPU0_CPU1_P0P1_DN<23>")
	)
	(segment
		(start 113.48593 -213.549738)
		(end 113.144554 -213.891114)
		(width 0.0889)
		(layer "In6.Cu")
		(net "UPI_CPU0_CPU1_P0P1_DN<23>")
	)
	(segment
		(start 353.523804 -194.32143)
		(end 353.227132 -193.95567)
		(width 0.14732)
		(layer "In6.Cu")
		(net "UPI_CPU0_CPU1_P0P1_DN<23>")
	)
	(segment
		(start 121.391172 -193.004948)
		(end 121.408698 -193.176398)
		(width 0.14732)
		(layer "In6.Cu")
		(net "UPI_CPU0_CPU1_P0P1_DN<23>")
	)
	(segment
		(start 358.545384 -213.768432)
		(end 358.545384 -213.450932)
		(width 0.0889)
		(layer "In6.Cu")
		(net "UPI_CPU0_CPU1_P0P1_DN<23>")
	)
	(segment
		(start 155.61437 -170.158156)
		(end 149.699218 -171.671996)
		(width 0.14732)
		(layer "In6.Cu")
		(net "UPI_CPU0_CPU1_P0P1_DN<23>")
	)
	(segment
		(start 124.212858 -189.533276)
		(end 122.84202 -191.219836)
		(width 0.14732)
		(layer "In6.Cu")
		(net "UPI_CPU0_CPU1_P0P1_DN<23>")
	)
	(segment
		(start 358.503474 -211.752688)
		(end 358.503474 -211.73059)
		(width 0.0889)
		(layer "In6.Cu")
		(net "UPI_CPU0_CPU1_P0P1_DN<23>")
	)
	(segment
		(start 113.144554 -214.422736)
		(end 113.268252 -214.546434)
		(width 0.0889)
		(layer "In6.Cu")
		(net "UPI_CPU0_CPU1_P0P1_DN<23>")
	)
	(segment
		(start 358.545384 -212.718904)
		(end 358.44607 -212.61959)
		(width 0.0889)
		(layer "In6.Cu")
		(net "UPI_CPU0_CPU1_P0P1_DN<23>")
	)
	(arc
		(start 359.014522 -214.637112)
		(mid 359.014717 -214.629874)
		(end 359.014776 -214.622634)
		(width 0.0889)
		(layer "In6.Cu")
		(net "UPI_CPU0_CPU1_P0P1_DN<23>")
	)
	(arc
		(start 358.874822 -214.91448)
		(mid 358.974771 -214.790954)
		(end 359.014522 -214.637112)
		(width 0.0889)
		(layer "In6.Cu")
		(net "UPI_CPU0_CPU1_P0P1_DN<23>")
	)
	(segment
		(start 114.459766 -214.622888)
		(end 114.459512 -214.622634)
		(width 0.13208)
		(layer "F.Cu")
		(net "UPI_CPU0_CPU1_P0P1_DN<22>")
	)
	(segment
		(start 114.459766 -215.158574)
		(end 114.459766 -214.622888)
		(width 0.13208)
		(layer "F.Cu")
		(net "UPI_CPU0_CPU1_P0P1_DN<22>")
	)
	(segment
		(start 357.230934 -215.436958)
		(end 357.23068 -215.436704)
		(width 0.13208)
		(layer "F.Cu")
		(net "UPI_CPU0_CPU1_P0P1_DN<22>")
	)
	(segment
		(start 357.230934 -215.972644)
		(end 357.230934 -215.436958)
		(width 0.13208)
		(layer "F.Cu")
		(net "UPI_CPU0_CPU1_P0P1_DN<22>")
	)
	(segment
		(start 114.55527 -213.930738)
		(end 114.084608 -214.4014)
		(width 0.0889)
		(layer "In6.Cu")
		(net "UPI_CPU0_CPU1_P0P1_DN<22>")
	)
	(segment
		(start 123.619006 -191.799464)
		(end 123.34367 -192.1383)
		(width 0.14732)
		(layer "In6.Cu")
		(net "UPI_CPU0_CPU1_P0P1_DN<22>")
	)
	(segment
		(start 357.60533 -212.995764)
		(end 357.60533 -212.729064)
		(width 0.0889)
		(layer "In6.Cu")
		(net "UPI_CPU0_CPU1_P0P1_DN<22>")
	)
	(segment
		(start 119.783098 -196.518784)
		(end 119.800878 -196.690234)
		(width 0.14732)
		(layer "In6.Cu")
		(net "UPI_CPU0_CPU1_P0P1_DN<22>")
	)
	(segment
		(start 121.940066 -194.058286)
		(end 121.664222 -194.39763)
		(width 0.14732)
		(layer "In6.Cu")
		(net "UPI_CPU0_CPU1_P0P1_DN<22>")
	)
	(segment
		(start 341.57793 -183.839866)
		(end 337.471004 -180.851048)
		(width 0.14732)
		(layer "In6.Cu")
		(net "UPI_CPU0_CPU1_P0P1_DN<22>")
	)
	(segment
		(start 357.60533 -211.693252)
		(end 357.563166 -211.651088)
		(width 0.0889)
		(layer "In6.Cu")
		(net "UPI_CPU0_CPU1_P0P1_DN<22>")
	)
	(segment
		(start 149.927564 -172.497242)
		(end 137.258044 -178.985164)
		(width 0.14732)
		(layer "In6.Cu")
		(net "UPI_CPU0_CPU1_P0P1_DN<22>")
	)
	(segment
		(start 119.800878 -196.690234)
		(end 119.525034 -197.029578)
		(width 0.14732)
		(layer "In6.Cu")
		(net "UPI_CPU0_CPU1_P0P1_DN<22>")
	)
	(segment
		(start 273.041872 -170.560238)
		(end 238.598202 -170.725084)
		(width 0.14732)
		(layer "In6.Cu")
		(net "UPI_CPU0_CPU1_P0P1_DN<22>")
	)
	(segment
		(start 357.563166 -211.651088)
		(end 357.563166 -211.62899)
		(width 0.0889)
		(layer "In6.Cu")
		(net "UPI_CPU0_CPU1_P0P1_DN<22>")
	)
	(segment
		(start 124.04852 -191.27089)
		(end 124.0663 -191.44234)
		(width 0.14732)
		(layer "In6.Cu")
		(net "UPI_CPU0_CPU1_P0P1_DN<22>")
	)
	(segment
		(start 125.071124 -190.01232)
		(end 124.04852 -191.27089)
		(width 0.14732)
		(layer "In6.Cu")
		(net "UPI_CPU0_CPU1_P0P1_DN<22>")
	)
	(segment
		(start 114.55527 -213.511892)
		(end 114.55527 -213.930738)
		(width 0.0889)
		(layer "In6.Cu")
		(net "UPI_CPU0_CPU1_P0P1_DN<22>")
	)
	(segment
		(start 320.191384 -171.816776)
		(end 313.893708 -170.056302)
		(width 0.14732)
		(layer "In6.Cu")
		(net "UPI_CPU0_CPU1_P0P1_DN<22>")
	)
	(segment
		(start 114.597434 -209.517996)
		(end 114.597434 -211.76361)
		(width 0.14732)
		(layer "In6.Cu")
		(net "UPI_CPU0_CPU1_P0P1_DN<22>")
	)
	(segment
		(start 120.488202 -195.651374)
		(end 120.505728 -195.822824)
		(width 0.14732)
		(layer "In6.Cu")
		(net "UPI_CPU0_CPU1_P0P1_DN<22>")
	)
	(segment
		(start 358.07523 -214.387938)
		(end 357.60533 -213.918038)
		(width 0.0889)
		(layer "In6.Cu")
		(net "UPI_CPU0_CPU1_P0P1_DN<22>")
	)
	(segment
		(start 119.783352 -196.518784)
		(end 119.783098 -196.518784)
		(width 0.14732)
		(layer "In6.Cu")
		(net "UPI_CPU0_CPU1_P0P1_DN<22>")
	)
	(segment
		(start 121.922286 -193.886836)
		(end 121.940066 -194.058286)
		(width 0.14732)
		(layer "In6.Cu")
		(net "UPI_CPU0_CPU1_P0P1_DN<22>")
	)
	(segment
		(start 114.55527 -212.296248)
		(end 114.654584 -212.395562)
		(width 0.0889)
		(layer "In6.Cu")
		(net "UPI_CPU0_CPU1_P0P1_DN<22>")
	)
	(segment
		(start 114.303048 -214.893652)
		(end 114.459512 -214.622634)
		(width 0.0889)
		(layer "In6.Cu")
		(net "UPI_CPU0_CPU1_P0P1_DN<22>")
	)
	(segment
		(start 114.223038 -214.914988)
		(end 114.303048 -214.893652)
		(width 0.0889)
		(layer "In6.Cu")
		(net "UPI_CPU0_CPU1_P0P1_DN<22>")
	)
	(segment
		(start 114.654584 -212.662262)
		(end 114.55527 -212.761576)
		(width 0.0889)
		(layer "In6.Cu")
		(net "UPI_CPU0_CPU1_P0P1_DN<22>")
	)
	(segment
		(start 122.62739 -193.019426)
		(end 122.644916 -193.190876)
		(width 0.14732)
		(layer "In6.Cu")
		(net "UPI_CPU0_CPU1_P0P1_DN<22>")
	)
	(segment
		(start 358.07523 -214.62365)
		(end 358.07523 -214.387938)
		(width 0.0889)
		(layer "In6.Cu")
		(net "UPI_CPU0_CPU1_P0P1_DN<22>")
	)
	(segment
		(start 358.074976 -214.62365)
		(end 358.07523 -214.62365)
		(width 0.0889)
		(layer "In6.Cu")
		(net "UPI_CPU0_CPU1_P0P1_DN<22>")
	)
	(segment
		(start 238.598202 -170.725084)
		(end 211.269072 -170.725084)
		(width 0.14732)
		(layer "In6.Cu")
		(net "UPI_CPU0_CPU1_P0P1_DN<22>")
	)
	(segment
		(start 122.197622 -193.548)
		(end 121.922286 -193.886836)
		(width 0.14732)
		(layer "In6.Cu")
		(net "UPI_CPU0_CPU1_P0P1_DN<22>")
	)
	(segment
		(start 357.563166 -209.993738)
		(end 356.458012 -199.522588)
		(width 0.14732)
		(layer "In6.Cu")
		(net "UPI_CPU0_CPU1_P0P1_DN<22>")
	)
	(segment
		(start 357.506016 -213.095078)
		(end 357.60533 -212.995764)
		(width 0.0889)
		(layer "In6.Cu")
		(net "UPI_CPU0_CPU1_P0P1_DN<22>")
	)
	(segment
		(start 119.353584 -197.047358)
		(end 118.668038 -197.890892)
		(width 0.14732)
		(layer "In6.Cu")
		(net "UPI_CPU0_CPU1_P0P1_DN<22>")
	)
	(segment
		(start 120.505728 -195.822824)
		(end 120.230138 -196.162168)
		(width 0.14732)
		(layer "In6.Cu")
		(net "UPI_CPU0_CPU1_P0P1_DN<22>")
	)
	(segment
		(start 120.956578 -195.268342)
		(end 120.785128 -195.286122)
		(width 0.14732)
		(layer "In6.Cu")
		(net "UPI_CPU0_CPU1_P0P1_DN<22>")
	)
	(segment
		(start 123.790456 -191.781684)
		(end 123.619006 -191.799464)
		(width 0.14732)
		(layer "In6.Cu")
		(net "UPI_CPU0_CPU1_P0P1_DN<22>")
	)
	(segment
		(start 357.60533 -212.263736)
		(end 357.60533 -211.693252)
		(width 0.0889)
		(layer "In6.Cu")
		(net "UPI_CPU0_CPU1_P0P1_DN<22>")
	)
	(segment
		(start 121.664222 -194.39763)
		(end 121.492772 -194.41541)
		(width 0.14732)
		(layer "In6.Cu")
		(net "UPI_CPU0_CPU1_P0P1_DN<22>")
	)
	(segment
		(start 357.23068 -215.436704)
		(end 357.543354 -215.436704)
		(width 0.0889)
		(layer "In6.Cu")
		(net "UPI_CPU0_CPU1_P0P1_DN<22>")
	)
	(segment
		(start 123.361196 -192.30975)
		(end 123.085606 -192.649094)
		(width 0.14732)
		(layer "In6.Cu")
		(net "UPI_CPU0_CPU1_P0P1_DN<22>")
	)
	(segment
		(start 155.666948 -171.028614)
		(end 149.927564 -172.497242)
		(width 0.14732)
		(layer "In6.Cu")
		(net "UPI_CPU0_CPU1_P0P1_DN<22>")
	)
	(segment
		(start 357.506016 -212.62975)
		(end 357.506016 -212.36305)
		(width 0.0889)
		(layer "In6.Cu")
		(net "UPI_CPU0_CPU1_P0P1_DN<22>")
	)
	(segment
		(start 351.733866 -193.666364)
		(end 341.57793 -183.839866)
		(width 0.14732)
		(layer "In6.Cu")
		(net "UPI_CPU0_CPU1_P0P1_DN<22>")
	)
	(segment
		(start 357.60533 -213.918038)
		(end 357.60533 -213.461092)
		(width 0.0889)
		(layer "In6.Cu")
		(net "UPI_CPU0_CPU1_P0P1_DN<22>")
	)
	(segment
		(start 114.597434 -211.76361)
		(end 114.597434 -211.785708)
		(width 0.0889)
		(layer "In6.Cu")
		(net "UPI_CPU0_CPU1_P0P1_DN<22>")
	)
	(segment
		(start 124.0663 -191.44234)
		(end 123.790456 -191.781684)
		(width 0.14732)
		(layer "In6.Cu")
		(net "UPI_CPU0_CPU1_P0P1_DN<22>")
	)
	(segment
		(start 357.563166 -211.62899)
		(end 357.563166 -209.993738)
		(width 0.14732)
		(layer "In6.Cu")
		(net "UPI_CPU0_CPU1_P0P1_DN<22>")
	)
	(segment
		(start 302.470566 -169.84345)
		(end 273.041872 -170.560238)
		(width 0.14732)
		(layer "In6.Cu")
		(net "UPI_CPU0_CPU1_P0P1_DN<22>")
	)
	(segment
		(start 357.506016 -213.361778)
		(end 357.506016 -213.095078)
		(width 0.0889)
		(layer "In6.Cu")
		(net "UPI_CPU0_CPU1_P0P1_DN<22>")
	)
	(segment
		(start 114.55527 -213.046564)
		(end 114.654584 -213.145878)
		(width 0.0889)
		(layer "In6.Cu")
		(net "UPI_CPU0_CPU1_P0P1_DN<22>")
	)
	(segment
		(start 114.654584 -212.395562)
		(end 114.654584 -212.662262)
		(width 0.0889)
		(layer "In6.Cu")
		(net "UPI_CPU0_CPU1_P0P1_DN<22>")
	)
	(segment
		(start 122.913902 -192.66662)
		(end 122.62739 -193.019426)
		(width 0.14732)
		(layer "In6.Cu")
		(net "UPI_CPU0_CPU1_P0P1_DN<22>")
	)
	(segment
		(start 120.058688 -196.180202)
		(end 119.783352 -196.518784)
		(width 0.14732)
		(layer "In6.Cu")
		(net "UPI_CPU0_CPU1_P0P1_DN<22>")
	)
	(segment
		(start 337.471004 -180.851048)
		(end 320.191384 -171.816776)
		(width 0.14732)
		(layer "In6.Cu")
		(net "UPI_CPU0_CPU1_P0P1_DN<22>")
	)
	(segment
		(start 120.230138 -196.162168)
		(end 120.058434 -196.179948)
		(width 0.14732)
		(layer "In6.Cu")
		(net "UPI_CPU0_CPU1_P0P1_DN<22>")
	)
	(segment
		(start 357.60533 -212.729064)
		(end 357.506016 -212.62975)
		(width 0.0889)
		(layer "In6.Cu")
		(net "UPI_CPU0_CPU1_P0P1_DN<22>")
	)
	(segment
		(start 121.232422 -194.928998)
		(end 120.956578 -195.268342)
		(width 0.14732)
		(layer "In6.Cu")
		(net "UPI_CPU0_CPU1_P0P1_DN<22>")
	)
	(segment
		(start 137.258044 -178.985164)
		(end 132.93852 -184.783222)
		(width 0.14732)
		(layer "In6.Cu")
		(net "UPI_CPU0_CPU1_P0P1_DN<22>")
	)
	(segment
		(start 118.668038 -197.890892)
		(end 114.597434 -209.517996)
		(width 0.14732)
		(layer "In6.Cu")
		(net "UPI_CPU0_CPU1_P0P1_DN<22>")
	)
	(segment
		(start 357.543354 -215.436704)
		(end 357.608632 -215.371426)
		(width 0.0889)
		(layer "In6.Cu")
		(net "UPI_CPU0_CPU1_P0P1_DN<22>")
	)
	(segment
		(start 114.55527 -211.827872)
		(end 114.55527 -212.296248)
		(width 0.0889)
		(layer "In6.Cu")
		(net "UPI_CPU0_CPU1_P0P1_DN<22>")
	)
	(segment
		(start 121.492772 -194.41541)
		(end 121.214642 -194.757548)
		(width 0.14732)
		(layer "In6.Cu")
		(net "UPI_CPU0_CPU1_P0P1_DN<22>")
	)
	(segment
		(start 120.785128 -195.286122)
		(end 120.488202 -195.651374)
		(width 0.14732)
		(layer "In6.Cu")
		(net "UPI_CPU0_CPU1_P0P1_DN<22>")
	)
	(segment
		(start 120.058434 -196.179948)
		(end 120.058688 -196.180202)
		(width 0.14732)
		(layer "In6.Cu")
		(net "UPI_CPU0_CPU1_P0P1_DN<22>")
	)
	(segment
		(start 201.033126 -170.276012)
		(end 155.666948 -171.028614)
		(width 0.14732)
		(layer "In6.Cu")
		(net "UPI_CPU0_CPU1_P0P1_DN<22>")
	)
	(segment
		(start 114.55527 -212.761576)
		(end 114.55527 -213.046564)
		(width 0.0889)
		(layer "In6.Cu")
		(net "UPI_CPU0_CPU1_P0P1_DN<22>")
	)
	(segment
		(start 132.93852 -184.783222)
		(end 125.071124 -190.01232)
		(width 0.14732)
		(layer "In6.Cu")
		(net "UPI_CPU0_CPU1_P0P1_DN<22>")
	)
	(segment
		(start 313.893708 -170.056302)
		(end 302.470566 -169.84345)
		(width 0.14732)
		(layer "In6.Cu")
		(net "UPI_CPU0_CPU1_P0P1_DN<22>")
	)
	(segment
		(start 121.214642 -194.757548)
		(end 121.232422 -194.928998)
		(width 0.14732)
		(layer "In6.Cu")
		(net "UPI_CPU0_CPU1_P0P1_DN<22>")
	)
	(segment
		(start 357.887524 -214.946992)
		(end 357.896414 -214.941912)
		(width 0.0889)
		(layer "In6.Cu")
		(net "UPI_CPU0_CPU1_P0P1_DN<22>")
	)
	(segment
		(start 357.60533 -213.461092)
		(end 357.506016 -213.361778)
		(width 0.0889)
		(layer "In6.Cu")
		(net "UPI_CPU0_CPU1_P0P1_DN<22>")
	)
	(segment
		(start 114.654584 -213.412578)
		(end 114.55527 -213.511892)
		(width 0.0889)
		(layer "In6.Cu")
		(net "UPI_CPU0_CPU1_P0P1_DN<22>")
	)
	(segment
		(start 357.506016 -212.36305)
		(end 357.60533 -212.263736)
		(width 0.0889)
		(layer "In6.Cu")
		(net "UPI_CPU0_CPU1_P0P1_DN<22>")
	)
	(segment
		(start 211.269072 -170.725084)
		(end 201.033126 -170.276012)
		(width 0.14732)
		(layer "In6.Cu")
		(net "UPI_CPU0_CPU1_P0P1_DN<22>")
	)
	(segment
		(start 123.085606 -192.649094)
		(end 122.913902 -192.66662)
		(width 0.14732)
		(layer "In6.Cu")
		(net "UPI_CPU0_CPU1_P0P1_DN<22>")
	)
	(segment
		(start 114.084608 -214.4014)
		(end 114.084608 -214.592408)
		(width 0.0889)
		(layer "In6.Cu")
		(net "UPI_CPU0_CPU1_P0P1_DN<22>")
	)
	(segment
		(start 122.369326 -193.53022)
		(end 122.197622 -193.548)
		(width 0.14732)
		(layer "In6.Cu")
		(net "UPI_CPU0_CPU1_P0P1_DN<22>")
	)
	(segment
		(start 119.525034 -197.029578)
		(end 119.353584 -197.047358)
		(width 0.14732)
		(layer "In6.Cu")
		(net "UPI_CPU0_CPU1_P0P1_DN<22>")
	)
	(segment
		(start 114.654584 -213.145878)
		(end 114.654584 -213.412578)
		(width 0.0889)
		(layer "In6.Cu")
		(net "UPI_CPU0_CPU1_P0P1_DN<22>")
	)
	(segment
		(start 122.644916 -193.190876)
		(end 122.369326 -193.53022)
		(width 0.14732)
		(layer "In6.Cu")
		(net "UPI_CPU0_CPU1_P0P1_DN<22>")
	)
	(segment
		(start 114.597434 -211.785708)
		(end 114.55527 -211.827872)
		(width 0.0889)
		(layer "In6.Cu")
		(net "UPI_CPU0_CPU1_P0P1_DN<22>")
	)
	(segment
		(start 356.458012 -199.522588)
		(end 351.733866 -193.666364)
		(width 0.14732)
		(layer "In6.Cu")
		(net "UPI_CPU0_CPU1_P0P1_DN<22>")
	)
	(segment
		(start 123.34367 -192.1383)
		(end 123.361196 -192.30975)
		(width 0.14732)
		(layer "In6.Cu")
		(net "UPI_CPU0_CPU1_P0P1_DN<22>")
	)
	(arc
		(start 357.611426 -215.35009)
		(mid 357.703685 -215.117175)
		(end 357.887524 -214.946992)
		(width 0.0889)
		(layer "In6.Cu")
		(net "UPI_CPU0_CPU1_P0P1_DN<22>")
	)
	(arc
		(start 357.896414 -214.941912)
		(mid 358.023668 -214.811946)
		(end 358.074722 -214.637366)
		(width 0.0889)
		(layer "In6.Cu")
		(net "UPI_CPU0_CPU1_P0P1_DN<22>")
	)
	(arc
		(start 114.084608 -214.592408)
		(mid 114.113835 -214.770872)
		(end 114.223038 -214.914988)
		(width 0.0889)
		(layer "In6.Cu")
		(net "UPI_CPU0_CPU1_P0P1_DN<22>")
	)
	(arc
		(start 357.608632 -215.371426)
		(mid 357.609927 -215.360745)
		(end 357.611426 -215.35009)
		(width 0.0889)
		(layer "In6.Cu")
		(net "UPI_CPU0_CPU1_P0P1_DN<22>")
	)
	(arc
		(start 358.074722 -214.637366)
		(mid 358.07491 -214.630509)
		(end 358.074976 -214.62365)
		(width 0.0889)
		(layer "In6.Cu")
		(net "UPI_CPU0_CPU1_P0P1_DN<22>")
	)
	(segment
		(start 356.291134 -215.972644)
		(end 356.291134 -215.436958)
		(width 0.13208)
		(layer "F.Cu")
		(net "UPI_CPU0_CPU1_P0P1_DN<21>")
	)
	(segment
		(start 115.399312 -214.622888)
		(end 115.399058 -214.622634)
		(width 0.13208)
		(layer "F.Cu")
		(net "UPI_CPU0_CPU1_P0P1_DN<21>")
	)
	(segment
		(start 115.399312 -215.158574)
		(end 115.399312 -214.622888)
		(width 0.13208)
		(layer "F.Cu")
		(net "UPI_CPU0_CPU1_P0P1_DN<21>")
	)
	(segment
		(start 356.291134 -215.436958)
		(end 356.29088 -215.436704)
		(width 0.13208)
		(layer "F.Cu")
		(net "UPI_CPU0_CPU1_P0P1_DN<21>")
	)
	(segment
		(start 119.323612 -198.616316)
		(end 115.536726 -209.433668)
		(width 0.14732)
		(layer "In6.Cu")
		(net "UPI_CPU0_CPU1_P0P1_DN<21>")
	)
	(segment
		(start 123.284234 -193.937128)
		(end 123.008644 -194.276472)
		(width 0.14732)
		(layer "In6.Cu")
		(net "UPI_CPU0_CPU1_P0P1_DN<21>")
	)
	(segment
		(start 115.494562 -213.93023)
		(end 115.494816 -213.929468)
		(width 0.0889)
		(layer "In6.Cu")
		(net "UPI_CPU0_CPU1_P0P1_DN<21>")
	)
	(segment
		(start 356.29088 -215.436704)
		(end 356.447344 -215.165686)
		(width 0.0889)
		(layer "In6.Cu")
		(net "UPI_CPU0_CPU1_P0P1_DN<21>")
	)
	(segment
		(start 123.266708 -193.765678)
		(end 123.284234 -193.937128)
		(width 0.14732)
		(layer "In6.Cu")
		(net "UPI_CPU0_CPU1_P0P1_DN<21>")
	)
	(segment
		(start 356.62362 -211.66201)
		(end 356.62362 -210.043522)
		(width 0.14732)
		(layer "In6.Cu")
		(net "UPI_CPU0_CPU1_P0P1_DN<21>")
	)
	(segment
		(start 123.542044 -193.426842)
		(end 123.266708 -193.765678)
		(width 0.14732)
		(layer "In6.Cu")
		(net "UPI_CPU0_CPU1_P0P1_DN<21>")
	)
	(segment
		(start 125.997716 -190.405512)
		(end 123.971812 -192.898268)
		(width 0.14732)
		(layer "In6.Cu")
		(net "UPI_CPU0_CPU1_P0P1_DN<21>")
	)
	(segment
		(start 341.075518 -184.509664)
		(end 337.181698 -181.675278)
		(width 0.14732)
		(layer "In6.Cu")
		(net "UPI_CPU0_CPU1_P0P1_DN<21>")
	)
	(segment
		(start 120.419114 -197.268592)
		(end 120.436894 -197.440042)
		(width 0.14732)
		(layer "In6.Cu")
		(net "UPI_CPU0_CPU1_P0P1_DN<21>")
	)
	(segment
		(start 120.436894 -197.440042)
		(end 120.16105 -197.779132)
		(width 0.14732)
		(layer "In6.Cu")
		(net "UPI_CPU0_CPU1_P0P1_DN<21>")
	)
	(segment
		(start 137.795254 -179.650898)
		(end 133.49605 -185.421778)
		(width 0.14732)
		(layer "In6.Cu")
		(net "UPI_CPU0_CPU1_P0P1_DN<21>")
	)
	(segment
		(start 121.124218 -196.401182)
		(end 121.141998 -196.572632)
		(width 0.14732)
		(layer "In6.Cu")
		(net "UPI_CPU0_CPU1_P0P1_DN<21>")
	)
	(segment
		(start 122.131836 -195.161408)
		(end 121.829322 -195.533772)
		(width 0.14732)
		(layer "In6.Cu")
		(net "UPI_CPU0_CPU1_P0P1_DN<21>")
	)
	(segment
		(start 115.270534 -214.22487)
		(end 115.240308 -214.321644)
		(width 0.0889)
		(layer "In6.Cu")
		(net "UPI_CPU0_CPU1_P0P1_DN<21>")
	)
	(segment
		(start 119.9896 -197.797166)
		(end 119.323612 -198.616316)
		(width 0.14732)
		(layer "In6.Cu")
		(net "UPI_CPU0_CPU1_P0P1_DN<21>")
	)
	(segment
		(start 115.536726 -211.780628)
		(end 115.494562 -211.822792)
		(width 0.0889)
		(layer "In6.Cu")
		(net "UPI_CPU0_CPU1_P0P1_DN<21>")
	)
	(segment
		(start 123.713748 -193.409062)
		(end 123.542044 -193.426842)
		(width 0.14732)
		(layer "In6.Cu")
		(net "UPI_CPU0_CPU1_P0P1_DN<21>")
	)
	(segment
		(start 122.57913 -194.804538)
		(end 122.30354 -195.143882)
		(width 0.14732)
		(layer "In6.Cu")
		(net "UPI_CPU0_CPU1_P0P1_DN<21>")
	)
	(segment
		(start 313.72937 -170.917108)
		(end 302.473106 -170.707558)
		(width 0.14732)
		(layer "In6.Cu")
		(net "UPI_CPU0_CPU1_P0P1_DN<21>")
	)
	(segment
		(start 120.694704 -196.93001)
		(end 120.419368 -197.268846)
		(width 0.14732)
		(layer "In6.Cu")
		(net "UPI_CPU0_CPU1_P0P1_DN<21>")
	)
	(segment
		(start 119.9896 -197.796912)
		(end 119.9896 -197.797166)
		(width 0.14732)
		(layer "In6.Cu")
		(net "UPI_CPU0_CPU1_P0P1_DN<21>")
	)
	(segment
		(start 115.536726 -211.75853)
		(end 115.536726 -211.780628)
		(width 0.0889)
		(layer "In6.Cu")
		(net "UPI_CPU0_CPU1_P0P1_DN<21>")
	)
	(segment
		(start 120.866154 -196.911976)
		(end 120.69445 -196.929756)
		(width 0.14732)
		(layer "In6.Cu")
		(net "UPI_CPU0_CPU1_P0P1_DN<21>")
	)
	(segment
		(start 356.665784 -211.726272)
		(end 356.62362 -211.684108)
		(width 0.0889)
		(layer "In6.Cu")
		(net "UPI_CPU0_CPU1_P0P1_DN<21>")
	)
	(segment
		(start 122.561604 -194.633088)
		(end 122.57913 -194.804538)
		(width 0.14732)
		(layer "In6.Cu")
		(net "UPI_CPU0_CPU1_P0P1_DN<21>")
	)
	(segment
		(start 121.829322 -195.533772)
		(end 121.847102 -195.705222)
		(width 0.14732)
		(layer "In6.Cu")
		(net "UPI_CPU0_CPU1_P0P1_DN<21>")
	)
	(segment
		(start 122.30354 -195.143882)
		(end 122.131836 -195.161408)
		(width 0.14732)
		(layer "In6.Cu")
		(net "UPI_CPU0_CPU1_P0P1_DN<21>")
	)
	(segment
		(start 356.447344 -215.165686)
		(end 356.423214 -215.076532)
		(width 0.0889)
		(layer "In6.Cu")
		(net "UPI_CPU0_CPU1_P0P1_DN<21>")
	)
	(segment
		(start 120.69445 -196.929756)
		(end 120.694704 -196.93001)
		(width 0.14732)
		(layer "In6.Cu")
		(net "UPI_CPU0_CPU1_P0P1_DN<21>")
	)
	(segment
		(start 356.62362 -210.043522)
		(end 355.53396 -199.720962)
		(width 0.14732)
		(layer "In6.Cu")
		(net "UPI_CPU0_CPU1_P0P1_DN<21>")
	)
	(segment
		(start 356.195376 -214.636858)
		(end 356.195376 -214.425784)
		(width 0.0889)
		(layer "In6.Cu")
		(net "UPI_CPU0_CPU1_P0P1_DN<21>")
	)
	(segment
		(start 337.181698 -181.675278)
		(end 319.90411 -172.643038)
		(width 0.14732)
		(layer "In6.Cu")
		(net "UPI_CPU0_CPU1_P0P1_DN<21>")
	)
	(segment
		(start 115.536726 -209.433668)
		(end 115.536726 -211.75853)
		(width 0.14732)
		(layer "In6.Cu")
		(net "UPI_CPU0_CPU1_P0P1_DN<21>")
	)
	(segment
		(start 123.989338 -193.069718)
		(end 123.713748 -193.409062)
		(width 0.14732)
		(layer "In6.Cu")
		(net "UPI_CPU0_CPU1_P0P1_DN<21>")
	)
	(segment
		(start 120.16105 -197.779132)
		(end 119.9896 -197.796912)
		(width 0.14732)
		(layer "In6.Cu")
		(net "UPI_CPU0_CPU1_P0P1_DN<21>")
	)
	(segment
		(start 356.665784 -213.89721)
		(end 356.665784 -211.726272)
		(width 0.0889)
		(layer "In6.Cu")
		(net "UPI_CPU0_CPU1_P0P1_DN<21>")
	)
	(segment
		(start 238.600488 -171.588684)
		(end 211.489544 -171.588684)
		(width 0.14732)
		(layer "In6.Cu")
		(net "UPI_CPU0_CPU1_P0P1_DN<21>")
	)
	(segment
		(start 319.90411 -172.643038)
		(end 313.72937 -170.917108)
		(width 0.14732)
		(layer "In6.Cu")
		(net "UPI_CPU0_CPU1_P0P1_DN<21>")
	)
	(segment
		(start 115.240308 -214.321644)
		(end 115.399058 -214.622634)
		(width 0.0889)
		(layer "In6.Cu")
		(net "UPI_CPU0_CPU1_P0P1_DN<21>")
	)
	(segment
		(start 122.83694 -194.294252)
		(end 122.561604 -194.633088)
		(width 0.14732)
		(layer "In6.Cu")
		(net "UPI_CPU0_CPU1_P0P1_DN<21>")
	)
	(segment
		(start 356.62362 -211.684108)
		(end 356.62362 -211.66201)
		(width 0.0889)
		(layer "In6.Cu")
		(net "UPI_CPU0_CPU1_P0P1_DN<21>")
	)
	(segment
		(start 200.732644 -171.116752)
		(end 156.017214 -171.85894)
		(width 0.14732)
		(layer "In6.Cu")
		(net "UPI_CPU0_CPU1_P0P1_DN<21>")
	)
	(segment
		(start 120.419368 -197.268846)
		(end 120.419114 -197.268592)
		(width 0.14732)
		(layer "In6.Cu")
		(net "UPI_CPU0_CPU1_P0P1_DN<21>")
	)
	(segment
		(start 150.010622 -173.395894)
		(end 137.795254 -179.650898)
		(width 0.14732)
		(layer "In6.Cu")
		(net "UPI_CPU0_CPU1_P0P1_DN<21>")
	)
	(segment
		(start 123.971812 -192.898268)
		(end 123.989338 -193.069718)
		(width 0.14732)
		(layer "In6.Cu")
		(net "UPI_CPU0_CPU1_P0P1_DN<21>")
	)
	(segment
		(start 356.454202 -214.108538)
		(end 356.665784 -213.89721)
		(width 0.0889)
		(layer "In6.Cu")
		(net "UPI_CPU0_CPU1_P0P1_DN<21>")
	)
	(segment
		(start 121.571258 -196.044566)
		(end 121.399554 -196.062346)
		(width 0.14732)
		(layer "In6.Cu")
		(net "UPI_CPU0_CPU1_P0P1_DN<21>")
	)
	(segment
		(start 355.53396 -199.720962)
		(end 351.015554 -194.126866)
		(width 0.14732)
		(layer "In6.Cu")
		(net "UPI_CPU0_CPU1_P0P1_DN<21>")
	)
	(segment
		(start 115.494562 -211.822792)
		(end 115.494562 -213.93023)
		(width 0.0889)
		(layer "In6.Cu")
		(net "UPI_CPU0_CPU1_P0P1_DN<21>")
	)
	(segment
		(start 123.008644 -194.276472)
		(end 122.83694 -194.294252)
		(width 0.14732)
		(layer "In6.Cu")
		(net "UPI_CPU0_CPU1_P0P1_DN<21>")
	)
	(segment
		(start 273.054572 -171.423838)
		(end 238.600488 -171.588684)
		(width 0.14732)
		(layer "In6.Cu")
		(net "UPI_CPU0_CPU1_P0P1_DN<21>")
	)
	(segment
		(start 351.015554 -194.126866)
		(end 341.075518 -184.509664)
		(width 0.14732)
		(layer "In6.Cu")
		(net "UPI_CPU0_CPU1_P0P1_DN<21>")
	)
	(segment
		(start 302.473106 -170.707558)
		(end 273.054572 -171.423838)
		(width 0.14732)
		(layer "In6.Cu")
		(net "UPI_CPU0_CPU1_P0P1_DN<21>")
	)
	(segment
		(start 121.399554 -196.062346)
		(end 121.124218 -196.401182)
		(width 0.14732)
		(layer "In6.Cu")
		(net "UPI_CPU0_CPU1_P0P1_DN<21>")
	)
	(segment
		(start 211.489544 -171.588684)
		(end 200.732644 -171.116752)
		(width 0.14732)
		(layer "In6.Cu")
		(net "UPI_CPU0_CPU1_P0P1_DN<21>")
	)
	(segment
		(start 121.847102 -195.705222)
		(end 121.571258 -196.044566)
		(width 0.14732)
		(layer "In6.Cu")
		(net "UPI_CPU0_CPU1_P0P1_DN<21>")
	)
	(segment
		(start 121.141998 -196.572632)
		(end 120.866154 -196.911976)
		(width 0.14732)
		(layer "In6.Cu")
		(net "UPI_CPU0_CPU1_P0P1_DN<21>")
	)
	(segment
		(start 156.017214 -171.85894)
		(end 150.010622 -173.395894)
		(width 0.14732)
		(layer "In6.Cu")
		(net "UPI_CPU0_CPU1_P0P1_DN<21>")
	)
	(segment
		(start 133.49605 -185.421778)
		(end 125.997716 -190.405512)
		(width 0.14732)
		(layer "In6.Cu")
		(net "UPI_CPU0_CPU1_P0P1_DN<21>")
	)
	(arc
		(start 356.423214 -215.076532)
		(mid 356.414642 -215.070009)
		(end 356.406196 -215.063324)
		(width 0.0889)
		(layer "In6.Cu")
		(net "UPI_CPU0_CPU1_P0P1_DN<21>")
	)
	(arc
		(start 115.494816 -213.929468)
		(mid 115.487658 -213.949028)
		(end 115.47983 -213.96833)
		(width 0.0889)
		(layer "In6.Cu")
		(net "UPI_CPU0_CPU1_P0P1_DN<21>")
	)
	(arc
		(start 356.195376 -214.425784)
		(mid 356.29681 -214.244333)
		(end 356.454202 -214.108538)
		(width 0.0889)
		(layer "In6.Cu")
		(net "UPI_CPU0_CPU1_P0P1_DN<21>")
	)
	(arc
		(start 115.47983 -213.96833)
		(mid 115.393279 -214.111364)
		(end 115.270534 -214.22487)
		(width 0.0889)
		(layer "In6.Cu")
		(net "UPI_CPU0_CPU1_P0P1_DN<21>")
	)
	(arc
		(start 356.406196 -215.063324)
		(mid 356.253765 -214.873342)
		(end 356.195376 -214.636858)
		(width 0.0889)
		(layer "In6.Cu")
		(net "UPI_CPU0_CPU1_P0P1_DN<21>")
	)
	(segment
		(start 116.339112 -214.622888)
		(end 116.338858 -214.622634)
		(width 0.13208)
		(layer "F.Cu")
		(net "UPI_CPU0_CPU1_P0P1_DN<20>")
	)
	(segment
		(start 116.339112 -215.158574)
		(end 116.339112 -214.622888)
		(width 0.13208)
		(layer "F.Cu")
		(net "UPI_CPU0_CPU1_P0P1_DN<20>")
	)
	(segment
		(start 355.351334 -213.732618)
		(end 355.351334 -214.344758)
		(width 0.13208)
		(layer "F.Cu")
		(net "UPI_CPU0_CPU1_P0P1_DN<20>")
	)
	(segment
		(start 350.320356 -194.61988)
		(end 340.567772 -185.184288)
		(width 0.14732)
		(layer "In6.Cu")
		(net "UPI_CPU0_CPU1_P0P1_DN<20>")
	)
	(segment
		(start 302.475392 -171.550584)
		(end 273.067018 -172.266356)
		(width 0.14732)
		(layer "In6.Cu")
		(net "UPI_CPU0_CPU1_P0P1_DN<20>")
	)
	(segment
		(start 273.067018 -172.266356)
		(end 238.602774 -172.431202)
		(width 0.14732)
		(layer "In6.Cu")
		(net "UPI_CPU0_CPU1_P0P1_DN<20>")
	)
	(segment
		(start 123.376944 -195.373244)
		(end 123.144534 -195.659248)
		(width 0.14732)
		(layer "In6.Cu")
		(net "UPI_CPU0_CPU1_P0P1_DN<20>")
	)
	(segment
		(start 120.513602 -198.89597)
		(end 120.309894 -198.917052)
		(width 0.14732)
		(layer "In6.Cu")
		(net "UPI_CPU0_CPU1_P0P1_DN<20>")
	)
	(segment
		(start 121.808494 -197.302882)
		(end 121.604786 -197.323964)
		(width 0.14732)
		(layer "In6.Cu")
		(net "UPI_CPU0_CPU1_P0P1_DN<20>")
	)
	(segment
		(start 355.725984 -211.753958)
		(end 355.684074 -211.712048)
		(width 0.0889)
		(layer "In6.Cu")
		(net "UPI_CPU0_CPU1_P0P1_DN<20>")
	)
	(segment
		(start 124.650754 -193.576448)
		(end 124.671582 -193.780156)
		(width 0.14732)
		(layer "In6.Cu")
		(net "UPI_CPU0_CPU1_P0P1_DN<20>")
	)
	(segment
		(start 355.684074 -211.712048)
		(end 355.684074 -211.68995)
		(width 0.0889)
		(layer "In6.Cu")
		(net "UPI_CPU0_CPU1_P0P1_DN<20>")
	)
	(segment
		(start 156.489908 -172.69587)
		(end 149.978618 -174.361856)
		(width 0.14732)
		(layer "In6.Cu")
		(net "UPI_CPU0_CPU1_P0P1_DN<20>")
	)
	(segment
		(start 125.086618 -193.269616)
		(end 124.88291 -193.290698)
		(width 0.14732)
		(layer "In6.Cu")
		(net "UPI_CPU0_CPU1_P0P1_DN<20>")
	)
	(segment
		(start 355.725984 -213.8934)
		(end 355.725984 -213.488524)
		(width 0.0889)
		(layer "In6.Cu")
		(net "UPI_CPU0_CPU1_P0P1_DN<20>")
	)
	(segment
		(start 120.95734 -198.120508)
		(end 120.725184 -198.406258)
		(width 0.14732)
		(layer "In6.Cu")
		(net "UPI_CPU0_CPU1_P0P1_DN<20>")
	)
	(segment
		(start 125.319028 -192.983612)
		(end 125.086618 -193.269616)
		(width 0.14732)
		(layer "In6.Cu")
		(net "UPI_CPU0_CPU1_P0P1_DN<20>")
	)
	(segment
		(start 116.476526 -209.285586)
		(end 116.476526 -211.684616)
		(width 0.14732)
		(layer "In6.Cu")
		(net "UPI_CPU0_CPU1_P0P1_DN<20>")
	)
	(segment
		(start 124.88291 -193.290698)
		(end 124.650754 -193.576448)
		(width 0.14732)
		(layer "In6.Cu")
		(net "UPI_CPU0_CPU1_P0P1_DN<20>")
	)
	(segment
		(start 355.510084 -214.033608)
		(end 355.594666 -214.05977)
		(width 0.0889)
		(layer "In6.Cu")
		(net "UPI_CPU0_CPU1_P0P1_DN<20>")
	)
	(segment
		(start 313.616848 -171.757848)
		(end 302.475392 -171.550584)
		(width 0.14732)
		(layer "In6.Cu")
		(net "UPI_CPU0_CPU1_P0P1_DN<20>")
	)
	(segment
		(start 122.70867 -195.96608)
		(end 122.729752 -196.169534)
		(width 0.14732)
		(layer "In6.Cu")
		(net "UPI_CPU0_CPU1_P0P1_DN<20>")
	)
	(segment
		(start 355.725984 -212.291168)
		(end 355.725984 -211.753958)
		(width 0.0889)
		(layer "In6.Cu")
		(net "UPI_CPU0_CPU1_P0P1_DN<20>")
	)
	(segment
		(start 116.182394 -214.893652)
		(end 116.338858 -214.622634)
		(width 0.0889)
		(layer "In6.Cu")
		(net "UPI_CPU0_CPU1_P0P1_DN<20>")
	)
	(segment
		(start 211.63788 -172.431202)
		(end 200.877678 -171.959016)
		(width 0.14732)
		(layer "In6.Cu")
		(net "UPI_CPU0_CPU1_P0P1_DN<20>")
	)
	(segment
		(start 124.671582 -193.780156)
		(end 124.439172 -194.06616)
		(width 0.14732)
		(layer "In6.Cu")
		(net "UPI_CPU0_CPU1_P0P1_DN<20>")
	)
	(segment
		(start 123.144534 -195.659248)
		(end 122.940826 -195.68033)
		(width 0.14732)
		(layer "In6.Cu")
		(net "UPI_CPU0_CPU1_P0P1_DN<20>")
	)
	(segment
		(start 124.003308 -194.372992)
		(end 124.02439 -194.5767)
		(width 0.14732)
		(layer "In6.Cu")
		(net "UPI_CPU0_CPU1_P0P1_DN<20>")
	)
	(segment
		(start 121.161048 -198.099426)
		(end 120.95734 -198.120508)
		(width 0.14732)
		(layer "In6.Cu")
		(net "UPI_CPU0_CPU1_P0P1_DN<20>")
	)
	(segment
		(start 122.040904 -197.016878)
		(end 121.808494 -197.302882)
		(width 0.14732)
		(layer "In6.Cu")
		(net "UPI_CPU0_CPU1_P0P1_DN<20>")
	)
	(segment
		(start 123.79198 -194.862704)
		(end 123.588272 -194.883786)
		(width 0.14732)
		(layer "In6.Cu")
		(net "UPI_CPU0_CPU1_P0P1_DN<20>")
	)
	(segment
		(start 355.62667 -213.12251)
		(end 355.725984 -213.023196)
		(width 0.0889)
		(layer "In6.Cu")
		(net "UPI_CPU0_CPU1_P0P1_DN<20>")
	)
	(segment
		(start 122.729752 -196.169534)
		(end 122.497088 -196.455792)
		(width 0.14732)
		(layer "In6.Cu")
		(net "UPI_CPU0_CPU1_P0P1_DN<20>")
	)
	(segment
		(start 354.610924 -199.928734)
		(end 350.320356 -194.61988)
		(width 0.14732)
		(layer "In6.Cu")
		(net "UPI_CPU0_CPU1_P0P1_DN<20>")
	)
	(segment
		(start 134.049262 -186.074304)
		(end 126.869698 -190.846202)
		(width 0.14732)
		(layer "In6.Cu")
		(net "UPI_CPU0_CPU1_P0P1_DN<20>")
	)
	(segment
		(start 355.62667 -212.657182)
		(end 355.62667 -212.390482)
		(width 0.0889)
		(layer "In6.Cu")
		(net "UPI_CPU0_CPU1_P0P1_DN<20>")
	)
	(segment
		(start 116.53393 -213.412578)
		(end 116.434616 -213.511892)
		(width 0.0889)
		(layer "In6.Cu")
		(net "UPI_CPU0_CPU1_P0P1_DN<20>")
	)
	(segment
		(start 355.725984 -212.756496)
		(end 355.62667 -212.657182)
		(width 0.0889)
		(layer "In6.Cu")
		(net "UPI_CPU0_CPU1_P0P1_DN<20>")
	)
	(segment
		(start 119.952262 -199.357234)
		(end 116.476526 -209.285586)
		(width 0.14732)
		(layer "In6.Cu")
		(net "UPI_CPU0_CPU1_P0P1_DN<20>")
	)
	(segment
		(start 116.53393 -213.145878)
		(end 116.53393 -213.412578)
		(width 0.0889)
		(layer "In6.Cu")
		(net "UPI_CPU0_CPU1_P0P1_DN<20>")
	)
	(segment
		(start 115.964208 -214.461852)
		(end 115.964208 -214.622634)
		(width 0.0889)
		(layer "In6.Cu")
		(net "UPI_CPU0_CPU1_P0P1_DN<20>")
	)
	(segment
		(start 116.53393 -212.662262)
		(end 116.434616 -212.761576)
		(width 0.0889)
		(layer "In6.Cu")
		(net "UPI_CPU0_CPU1_P0P1_DN<20>")
	)
	(segment
		(start 355.725984 -213.023196)
		(end 355.725984 -212.756496)
		(width 0.0889)
		(layer "In6.Cu")
		(net "UPI_CPU0_CPU1_P0P1_DN<20>")
	)
	(segment
		(start 124.439172 -194.06616)
		(end 124.235464 -194.087242)
		(width 0.14732)
		(layer "In6.Cu")
		(net "UPI_CPU0_CPU1_P0P1_DN<20>")
	)
	(segment
		(start 355.351334 -213.732618)
		(end 355.510084 -214.033608)
		(width 0.0889)
		(layer "In6.Cu")
		(net "UPI_CPU0_CPU1_P0P1_DN<20>")
	)
	(segment
		(start 121.37263 -197.609714)
		(end 121.393458 -197.813422)
		(width 0.14732)
		(layer "In6.Cu")
		(net "UPI_CPU0_CPU1_P0P1_DN<20>")
	)
	(segment
		(start 116.53393 -212.395562)
		(end 116.53393 -212.662262)
		(width 0.0889)
		(layer "In6.Cu")
		(net "UPI_CPU0_CPU1_P0P1_DN<20>")
	)
	(segment
		(start 116.476526 -211.684616)
		(end 116.47678 -211.68487)
		(width 0.14732)
		(layer "In6.Cu")
		(net "UPI_CPU0_CPU1_P0P1_DN<20>")
	)
	(segment
		(start 126.869698 -190.846202)
		(end 125.2982 -192.779904)
		(width 0.14732)
		(layer "In6.Cu")
		(net "UPI_CPU0_CPU1_P0P1_DN<20>")
	)
	(segment
		(start 355.62667 -213.38921)
		(end 355.62667 -213.12251)
		(width 0.0889)
		(layer "In6.Cu")
		(net "UPI_CPU0_CPU1_P0P1_DN<20>")
	)
	(segment
		(start 238.602774 -172.431202)
		(end 211.63788 -172.431202)
		(width 0.14732)
		(layer "In6.Cu")
		(net "UPI_CPU0_CPU1_P0P1_DN<20>")
	)
	(segment
		(start 124.235464 -194.087242)
		(end 124.003308 -194.372992)
		(width 0.14732)
		(layer "In6.Cu")
		(net "UPI_CPU0_CPU1_P0P1_DN<20>")
	)
	(segment
		(start 124.02439 -194.5767)
		(end 123.79198 -194.862704)
		(width 0.14732)
		(layer "In6.Cu")
		(net "UPI_CPU0_CPU1_P0P1_DN<20>")
	)
	(segment
		(start 116.434616 -211.749132)
		(end 116.434616 -212.296248)
		(width 0.0889)
		(layer "In6.Cu")
		(net "UPI_CPU0_CPU1_P0P1_DN<20>")
	)
	(segment
		(start 336.771742 -182.420768)
		(end 319.54597 -173.415198)
		(width 0.14732)
		(layer "In6.Cu")
		(net "UPI_CPU0_CPU1_P0P1_DN<20>")
	)
	(segment
		(start 121.604786 -197.323964)
		(end 121.37263 -197.609714)
		(width 0.14732)
		(layer "In6.Cu")
		(net "UPI_CPU0_CPU1_P0P1_DN<20>")
	)
	(segment
		(start 116.47678 -211.706968)
		(end 116.434616 -211.749132)
		(width 0.0889)
		(layer "In6.Cu")
		(net "UPI_CPU0_CPU1_P0P1_DN<20>")
	)
	(segment
		(start 123.356116 -195.169536)
		(end 123.376944 -195.373244)
		(width 0.14732)
		(layer "In6.Cu")
		(net "UPI_CPU0_CPU1_P0P1_DN<20>")
	)
	(segment
		(start 116.434616 -212.761576)
		(end 116.434616 -213.046564)
		(width 0.0889)
		(layer "In6.Cu")
		(net "UPI_CPU0_CPU1_P0P1_DN<20>")
	)
	(segment
		(start 355.725984 -213.488524)
		(end 355.62667 -213.38921)
		(width 0.0889)
		(layer "In6.Cu")
		(net "UPI_CPU0_CPU1_P0P1_DN<20>")
	)
	(segment
		(start 122.020076 -196.81317)
		(end 122.040904 -197.016878)
		(width 0.14732)
		(layer "In6.Cu")
		(net "UPI_CPU0_CPU1_P0P1_DN<20>")
	)
	(segment
		(start 120.309894 -198.917052)
		(end 119.952262 -199.357234)
		(width 0.14732)
		(layer "In6.Cu")
		(net "UPI_CPU0_CPU1_P0P1_DN<20>")
	)
	(segment
		(start 116.434616 -212.296248)
		(end 116.53393 -212.395562)
		(width 0.0889)
		(layer "In6.Cu")
		(net "UPI_CPU0_CPU1_P0P1_DN<20>")
	)
	(segment
		(start 116.434616 -213.046564)
		(end 116.53393 -213.145878)
		(width 0.0889)
		(layer "In6.Cu")
		(net "UPI_CPU0_CPU1_P0P1_DN<20>")
	)
	(segment
		(start 120.725184 -198.406258)
		(end 120.746012 -198.609966)
		(width 0.14732)
		(layer "In6.Cu")
		(net "UPI_CPU0_CPU1_P0P1_DN<20>")
	)
	(segment
		(start 200.877678 -171.959016)
		(end 156.489908 -172.69587)
		(width 0.14732)
		(layer "In6.Cu")
		(net "UPI_CPU0_CPU1_P0P1_DN<20>")
	)
	(segment
		(start 355.684074 -210.093306)
		(end 354.610924 -199.928734)
		(width 0.14732)
		(layer "In6.Cu")
		(net "UPI_CPU0_CPU1_P0P1_DN<20>")
	)
	(segment
		(start 121.393458 -197.813422)
		(end 121.161048 -198.099426)
		(width 0.14732)
		(layer "In6.Cu")
		(net "UPI_CPU0_CPU1_P0P1_DN<20>")
	)
	(segment
		(start 122.497088 -196.455792)
		(end 122.29338 -196.476874)
		(width 0.14732)
		(layer "In6.Cu")
		(net "UPI_CPU0_CPU1_P0P1_DN<20>")
	)
	(segment
		(start 355.62667 -212.390482)
		(end 355.725984 -212.291168)
		(width 0.0889)
		(layer "In6.Cu")
		(net "UPI_CPU0_CPU1_P0P1_DN<20>")
	)
	(segment
		(start 122.29338 -196.476874)
		(end 122.020076 -196.81317)
		(width 0.14732)
		(layer "In6.Cu")
		(net "UPI_CPU0_CPU1_P0P1_DN<20>")
	)
	(segment
		(start 319.54597 -173.415198)
		(end 313.616848 -171.757848)
		(width 0.14732)
		(layer "In6.Cu")
		(net "UPI_CPU0_CPU1_P0P1_DN<20>")
	)
	(segment
		(start 340.567772 -185.184288)
		(end 336.771742 -182.420768)
		(width 0.14732)
		(layer "In6.Cu")
		(net "UPI_CPU0_CPU1_P0P1_DN<20>")
	)
	(segment
		(start 116.47678 -211.68487)
		(end 116.47678 -211.706968)
		(width 0.0889)
		(layer "In6.Cu")
		(net "UPI_CPU0_CPU1_P0P1_DN<20>")
	)
	(segment
		(start 116.434616 -213.511892)
		(end 116.434616 -213.929468)
		(width 0.0889)
		(layer "In6.Cu")
		(net "UPI_CPU0_CPU1_P0P1_DN<20>")
	)
	(segment
		(start 116.104162 -214.91448)
		(end 116.182394 -214.893652)
		(width 0.0889)
		(layer "In6.Cu")
		(net "UPI_CPU0_CPU1_P0P1_DN<20>")
	)
	(segment
		(start 122.940826 -195.68033)
		(end 122.70867 -195.96608)
		(width 0.14732)
		(layer "In6.Cu")
		(net "UPI_CPU0_CPU1_P0P1_DN<20>")
	)
	(segment
		(start 149.978618 -174.361856)
		(end 138.330686 -180.327046)
		(width 0.14732)
		(layer "In6.Cu")
		(net "UPI_CPU0_CPU1_P0P1_DN<20>")
	)
	(segment
		(start 125.2982 -192.779904)
		(end 125.319028 -192.983612)
		(width 0.14732)
		(layer "In6.Cu")
		(net "UPI_CPU0_CPU1_P0P1_DN<20>")
	)
	(segment
		(start 123.588272 -194.883786)
		(end 123.356116 -195.169536)
		(width 0.14732)
		(layer "In6.Cu")
		(net "UPI_CPU0_CPU1_P0P1_DN<20>")
	)
	(segment
		(start 355.684074 -211.68995)
		(end 355.684074 -210.093306)
		(width 0.14732)
		(layer "In6.Cu")
		(net "UPI_CPU0_CPU1_P0P1_DN<20>")
	)
	(segment
		(start 120.746012 -198.609966)
		(end 120.513602 -198.89597)
		(width 0.14732)
		(layer "In6.Cu")
		(net "UPI_CPU0_CPU1_P0P1_DN<20>")
	)
	(segment
		(start 138.330686 -180.327046)
		(end 134.049262 -186.074304)
		(width 0.14732)
		(layer "In6.Cu")
		(net "UPI_CPU0_CPU1_P0P1_DN<20>")
	)
	(arc
		(start 116.419376 -213.968584)
		(mid 116.30917 -214.138501)
		(end 116.148612 -214.261954)
		(width 0.0889)
		(layer "In6.Cu")
		(net "UPI_CPU0_CPU1_P0P1_DN<20>")
	)
	(arc
		(start 355.594666 -214.05977)
		(mid 355.671339 -213.985276)
		(end 355.725984 -213.8934)
		(width 0.0889)
		(layer "In6.Cu")
		(net "UPI_CPU0_CPU1_P0P1_DN<20>")
	)
	(arc
		(start 115.964208 -214.622634)
		(mid 116.001068 -214.784431)
		(end 116.104162 -214.91448)
		(width 0.0889)
		(layer "In6.Cu")
		(net "UPI_CPU0_CPU1_P0P1_DN<20>")
	)
	(arc
		(start 116.148612 -214.261954)
		(mid 116.039216 -214.346051)
		(end 115.964208 -214.461852)
		(width 0.0889)
		(layer "In6.Cu")
		(net "UPI_CPU0_CPU1_P0P1_DN<20>")
	)
	(arc
		(start 116.434616 -213.929468)
		(mid 116.427338 -213.949159)
		(end 116.419376 -213.968584)
		(width 0.0889)
		(layer "In6.Cu")
		(net "UPI_CPU0_CPU1_P0P1_DN<20>")
	)
	(segment
		(start 133.725666 -215.972644)
		(end 133.725666 -215.436958)
		(width 0.13208)
		(layer "F.Cu")
		(net "UPI_CPU0_CPU1_P0P1_DN<1>")
	)
	(segment
		(start 337.96478 -215.158574)
		(end 337.96478 -214.622888)
		(width 0.13208)
		(layer "F.Cu")
		(net "UPI_CPU0_CPU1_P0P1_DN<1>")
	)
	(segment
		(start 133.725666 -215.436958)
		(end 133.725412 -215.436704)
		(width 0.13208)
		(layer "F.Cu")
		(net "UPI_CPU0_CPU1_P0P1_DN<1>")
	)
	(segment
		(start 337.96478 -214.622888)
		(end 337.964526 -214.622634)
		(width 0.13208)
		(layer "F.Cu")
		(net "UPI_CPU0_CPU1_P0P1_DN<1>")
	)
	(segment
		(start 146.271234 -200.220072)
		(end 145.835878 -200.222358)
		(width 0.14732)
		(layer "In6.Cu")
		(net "UPI_CPU0_CPU1_P0P1_DN<1>")
	)
	(segment
		(start 338.04987 -212.886798)
		(end 337.950556 -212.787484)
		(width 0.0889)
		(layer "In6.Cu")
		(net "UPI_CPU0_CPU1_P0P1_DN<1>")
	)
	(segment
		(start 162.889184 -188.824362)
		(end 162.867086 -190.47587)
		(width 0.14732)
		(layer "In6.Cu")
		(net "UPI_CPU0_CPU1_P0P1_DN<1>")
	)
	(segment
		(start 145.105374 -202.1205)
		(end 144.897348 -202.121516)
		(width 0.14732)
		(layer "In6.Cu")
		(net "UPI_CPU0_CPU1_P0P1_DN<1>")
	)
	(segment
		(start 145.26006 -200.80351)
		(end 145.262346 -201.238612)
		(width 0.14732)
		(layer "In6.Cu")
		(net "UPI_CPU0_CPU1_P0P1_DN<1>")
	)
	(segment
		(start 298.312078 -190.327026)
		(end 297.689016 -190.470282)
		(width 0.14732)
		(layer "In6.Cu")
		(net "UPI_CPU0_CPU1_P0P1_DN<1>")
	)
	(segment
		(start 190.80988 -190.996824)
		(end 166.763192 -190.675006)
		(width 0.14732)
		(layer "In6.Cu")
		(net "UPI_CPU0_CPU1_P0P1_DN<1>")
	)
	(segment
		(start 235.998258 -199.669146)
		(end 232.947464 -198.909686)
		(width 0.14732)
		(layer "In6.Cu")
		(net "UPI_CPU0_CPU1_P0P1_DN<1>")
	)
	(segment
		(start 156.01569 -192.162176)
		(end 153.069544 -195.134992)
		(width 0.14732)
		(layer "In6.Cu")
		(net "UPI_CPU0_CPU1_P0P1_DN<1>")
	)
	(segment
		(start 232.947464 -198.909686)
		(end 220.326712 -192.21323)
		(width 0.14732)
		(layer "In6.Cu")
		(net "UPI_CPU0_CPU1_P0P1_DN<1>")
	)
	(segment
		(start 148.97227 -198.009002)
		(end 148.973032 -198.217028)
		(width 0.14732)
		(layer "In6.Cu")
		(net "UPI_CPU0_CPU1_P0P1_DN<1>")
	)
	(segment
		(start 166.639748 -188.875162)
		(end 166.335964 -188.56325)
		(width 0.14732)
		(layer "In6.Cu")
		(net "UPI_CPU0_CPU1_P0P1_DN<1>")
	)
	(segment
		(start 151.28875 -195.882514)
		(end 150.189692 -196.990462)
		(width 0.14732)
		(layer "In6.Cu")
		(net "UPI_CPU0_CPU1_P0P1_DN<1>")
	)
	(segment
		(start 135.733536 -212.62594)
		(end 135.733536 -212.685884)
		(width 0.0889)
		(layer "In6.Cu")
		(net "UPI_CPU0_CPU1_P0P1_DN<1>")
	)
	(segment
		(start 157.416754 -191.450722)
		(end 156.01569 -192.162176)
		(width 0.14732)
		(layer "In6.Cu")
		(net "UPI_CPU0_CPU1_P0P1_DN<1>")
	)
	(segment
		(start 337.99272 -211.684108)
		(end 337.99272 -211.66201)
		(width 0.0889)
		(layer "In6.Cu")
		(net "UPI_CPU0_CPU1_P0P1_DN<1>")
	)
	(segment
		(start 337.113372 -209.996278)
		(end 335.846166 -209.47126)
		(width 0.14732)
		(layer "In6.Cu")
		(net "UPI_CPU0_CPU1_P0P1_DN<1>")
	)
	(segment
		(start 147.902422 -198.57339)
		(end 147.467066 -198.575676)
		(width 0.14732)
		(layer "In6.Cu")
		(net "UPI_CPU0_CPU1_P0P1_DN<1>")
	)
	(segment
		(start 148.15947 -198.828152)
		(end 147.902422 -198.57339)
		(width 0.14732)
		(layer "In6.Cu")
		(net "UPI_CPU0_CPU1_P0P1_DN<1>")
	)
	(segment
		(start 162.867086 -190.47587)
		(end 162.718242 -190.621158)
		(width 0.14732)
		(layer "In6.Cu")
		(net "UPI_CPU0_CPU1_P0P1_DN<1>")
	)
	(segment
		(start 134.57047 -213.84895)
		(end 134.57047 -214.706708)
		(width 0.0889)
		(layer "In6.Cu")
		(net "UPI_CPU0_CPU1_P0P1_DN<1>")
	)
	(segment
		(start 237.34395 -199.669146)
		(end 235.998258 -199.669146)
		(width 0.14732)
		(layer "In6.Cu")
		(net "UPI_CPU0_CPU1_P0P1_DN<1>")
	)
	(segment
		(start 149.981666 -196.991224)
		(end 149.700488 -196.713094)
		(width 0.14732)
		(layer "In6.Cu")
		(net "UPI_CPU0_CPU1_P0P1_DN<1>")
	)
	(segment
		(start 134.038086 -215.436704)
		(end 133.725412 -215.436704)
		(width 0.0889)
		(layer "In6.Cu")
		(net "UPI_CPU0_CPU1_P0P1_DN<1>")
	)
	(segment
		(start 337.99272 -211.66201)
		(end 337.99272 -211.537296)
		(width 0.14732)
		(layer "In6.Cu")
		(net "UPI_CPU0_CPU1_P0P1_DN<1>")
	)
	(segment
		(start 165.184328 -190.507112)
		(end 165.035484 -190.6524)
		(width 0.14732)
		(layer "In6.Cu")
		(net "UPI_CPU0_CPU1_P0P1_DN<1>")
	)
	(segment
		(start 146.893534 -199.59193)
		(end 147.150582 -199.846692)
		(width 0.14732)
		(layer "In6.Cu")
		(net "UPI_CPU0_CPU1_P0P1_DN<1>")
	)
	(segment
		(start 337.950556 -212.055456)
		(end 337.950556 -211.726272)
		(width 0.0889)
		(layer "In6.Cu")
		(net "UPI_CPU0_CPU1_P0P1_DN<1>")
	)
	(segment
		(start 302.410876 -187.51296)
		(end 300.860714 -188.288168)
		(width 0.14732)
		(layer "In6.Cu")
		(net "UPI_CPU0_CPU1_P0P1_DN<1>")
	)
	(segment
		(start 338.04987 -212.42147)
		(end 338.04987 -212.15477)
		(width 0.0889)
		(layer "In6.Cu")
		(net "UPI_CPU0_CPU1_P0P1_DN<1>")
	)
	(segment
		(start 220.326712 -192.21323)
		(end 208.38033 -190.286386)
		(width 0.14732)
		(layer "In6.Cu")
		(net "UPI_CPU0_CPU1_P0P1_DN<1>")
	)
	(segment
		(start 134.100062 -215.374728)
		(end 134.038086 -215.436704)
		(width 0.0889)
		(layer "In6.Cu")
		(net "UPI_CPU0_CPU1_P0P1_DN<1>")
	)
	(segment
		(start 159.815784 -190.582042)
		(end 157.416754 -191.450722)
		(width 0.14732)
		(layer "In6.Cu")
		(net "UPI_CPU0_CPU1_P0P1_DN<1>")
	)
	(segment
		(start 337.99272 -211.537296)
		(end 337.992466 -211.53755)
		(width 0.14732)
		(layer "In6.Cu")
		(net "UPI_CPU0_CPU1_P0P1_DN<1>")
	)
	(segment
		(start 146.891248 -199.156828)
		(end 146.893534 -199.59193)
		(width 0.14732)
		(layer "In6.Cu")
		(net "UPI_CPU0_CPU1_P0P1_DN<1>")
	)
	(segment
		(start 261.076948 -191.434974)
		(end 250.13412 -194.353688)
		(width 0.14732)
		(layer "In6.Cu")
		(net "UPI_CPU0_CPU1_P0P1_DN<1>")
	)
	(segment
		(start 134.100062 -215.238838)
		(end 134.100062 -215.374728)
		(width 0.0889)
		(layer "In6.Cu")
		(net "UPI_CPU0_CPU1_P0P1_DN<1>")
	)
	(segment
		(start 337.589622 -213.941152)
		(end 337.950556 -213.580218)
		(width 0.0889)
		(layer "In6.Cu")
		(net "UPI_CPU0_CPU1_P0P1_DN<1>")
	)
	(segment
		(start 150.189692 -196.990462)
		(end 149.981666 -196.991224)
		(width 0.14732)
		(layer "In6.Cu")
		(net "UPI_CPU0_CPU1_P0P1_DN<1>")
	)
	(segment
		(start 145.519394 -201.493374)
		(end 145.52041 -201.7014)
		(width 0.14732)
		(layer "In6.Cu")
		(net "UPI_CPU0_CPU1_P0P1_DN<1>")
	)
	(segment
		(start 148.691346 -197.731126)
		(end 148.97227 -198.009002)
		(width 0.14732)
		(layer "In6.Cu")
		(net "UPI_CPU0_CPU1_P0P1_DN<1>")
	)
	(segment
		(start 147.467066 -198.575676)
		(end 146.891248 -199.156828)
		(width 0.14732)
		(layer "In6.Cu")
		(net "UPI_CPU0_CPU1_P0P1_DN<1>")
	)
	(segment
		(start 148.36775 -198.82739)
		(end 148.15947 -198.828152)
		(width 0.14732)
		(layer "In6.Cu")
		(net "UPI_CPU0_CPU1_P0P1_DN<1>")
	)
	(segment
		(start 166.61765 -190.526416)
		(end 166.639748 -188.875162)
		(width 0.14732)
		(layer "In6.Cu")
		(net "UPI_CPU0_CPU1_P0P1_DN<1>")
	)
	(segment
		(start 313.169554 -188.358526)
		(end 312.35142 -187.850272)
		(width 0.14732)
		(layer "In6.Cu")
		(net "UPI_CPU0_CPU1_P0P1_DN<1>")
	)
	(segment
		(start 143.631158 -202.885294)
		(end 143.888206 -203.140056)
		(width 0.14732)
		(layer "In6.Cu")
		(net "UPI_CPU0_CPU1_P0P1_DN<1>")
	)
	(segment
		(start 146.528536 -200.474834)
		(end 146.271234 -200.220072)
		(width 0.14732)
		(layer "In6.Cu")
		(net "UPI_CPU0_CPU1_P0P1_DN<1>")
	)
	(segment
		(start 337.808062 -214.893652)
		(end 337.72983 -214.91448)
		(width 0.0889)
		(layer "In6.Cu")
		(net "UPI_CPU0_CPU1_P0P1_DN<1>")
	)
	(segment
		(start 140.72489 -206.541116)
		(end 138.549634 -209.809842)
		(width 0.14732)
		(layer "In6.Cu")
		(net "UPI_CPU0_CPU1_P0P1_DN<1>")
	)
	(segment
		(start 148.689568 -197.29577)
		(end 148.691346 -197.731126)
		(width 0.14732)
		(layer "In6.Cu")
		(net "UPI_CPU0_CPU1_P0P1_DN<1>")
	)
	(segment
		(start 134.57047 -214.706708)
		(end 134.569962 -214.707978)
		(width 0.0889)
		(layer "In6.Cu")
		(net "UPI_CPU0_CPU1_P0P1_DN<1>")
	)
	(segment
		(start 300.860714 -188.288168)
		(end 299.586396 -189.307724)
		(width 0.14732)
		(layer "In6.Cu")
		(net "UPI_CPU0_CPU1_P0P1_DN<1>")
	)
	(segment
		(start 312.35142 -187.850272)
		(end 311.834276 -187.697364)
		(width 0.14732)
		(layer "In6.Cu")
		(net "UPI_CPU0_CPU1_P0P1_DN<1>")
	)
	(segment
		(start 147.150582 -199.846692)
		(end 147.151598 -200.054718)
		(width 0.14732)
		(layer "In6.Cu")
		(net "UPI_CPU0_CPU1_P0P1_DN<1>")
	)
	(segment
		(start 337.950556 -213.580218)
		(end 337.950556 -213.252812)
		(width 0.0889)
		(layer "In6.Cu")
		(net "UPI_CPU0_CPU1_P0P1_DN<1>")
	)
	(segment
		(start 337.589622 -214.62238)
		(end 337.589622 -213.941152)
		(width 0.0889)
		(layer "In6.Cu")
		(net "UPI_CPU0_CPU1_P0P1_DN<1>")
	)
	(segment
		(start 311.834276 -187.697364)
		(end 302.410876 -187.51296)
		(width 0.14732)
		(layer "In6.Cu")
		(net "UPI_CPU0_CPU1_P0P1_DN<1>")
	)
	(segment
		(start 149.26564 -196.714872)
		(end 148.689568 -197.29577)
		(width 0.14732)
		(layer "In6.Cu")
		(net "UPI_CPU0_CPU1_P0P1_DN<1>")
	)
	(segment
		(start 208.38033 -190.286386)
		(end 190.80988 -190.996824)
		(width 0.14732)
		(layer "In6.Cu")
		(net "UPI_CPU0_CPU1_P0P1_DN<1>")
	)
	(segment
		(start 164.300408 -190.49492)
		(end 164.322506 -188.84392)
		(width 0.14732)
		(layer "In6.Cu")
		(net "UPI_CPU0_CPU1_P0P1_DN<1>")
	)
	(segment
		(start 337.992466 -211.53755)
		(end 337.992466 -210.875372)
		(width 0.14732)
		(layer "In6.Cu")
		(net "UPI_CPU0_CPU1_P0P1_DN<1>")
	)
	(segment
		(start 250.13412 -194.353688)
		(end 238.960406 -199.466962)
		(width 0.14732)
		(layer "In6.Cu")
		(net "UPI_CPU0_CPU1_P0P1_DN<1>")
	)
	(segment
		(start 144.897348 -202.121516)
		(end 144.640046 -201.866754)
		(width 0.14732)
		(layer "In6.Cu")
		(net "UPI_CPU0_CPU1_P0P1_DN<1>")
	)
	(segment
		(start 143.888206 -203.140056)
		(end 143.889222 -203.348082)
		(width 0.14732)
		(layer "In6.Cu")
		(net "UPI_CPU0_CPU1_P0P1_DN<1>")
	)
	(segment
		(start 299.586396 -189.307724)
		(end 298.312078 -190.327026)
		(width 0.14732)
		(layer "In6.Cu")
		(net "UPI_CPU0_CPU1_P0P1_DN<1>")
	)
	(segment
		(start 144.640046 -201.866754)
		(end 144.20469 -201.86904)
		(width 0.14732)
		(layer "In6.Cu")
		(net "UPI_CPU0_CPU1_P0P1_DN<1>")
	)
	(segment
		(start 165.518084 -188.552074)
		(end 165.206426 -188.855604)
		(width 0.14732)
		(layer "In6.Cu")
		(net "UPI_CPU0_CPU1_P0P1_DN<1>")
	)
	(segment
		(start 165.206426 -188.855604)
		(end 165.184328 -190.507112)
		(width 0.14732)
		(layer "In6.Cu")
		(net "UPI_CPU0_CPU1_P0P1_DN<1>")
	)
	(segment
		(start 165.035484 -190.6524)
		(end 164.44595 -190.644018)
		(width 0.14732)
		(layer "In6.Cu")
		(net "UPI_CPU0_CPU1_P0P1_DN<1>")
	)
	(segment
		(start 138.549634 -209.809842)
		(end 135.74903 -212.610446)
		(width 0.14732)
		(layer "In6.Cu")
		(net "UPI_CPU0_CPU1_P0P1_DN<1>")
	)
	(segment
		(start 144.20469 -201.86904)
		(end 143.628872 -202.450192)
		(width 0.14732)
		(layer "In6.Cu")
		(net "UPI_CPU0_CPU1_P0P1_DN<1>")
	)
	(segment
		(start 135.74903 -212.610446)
		(end 135.733536 -212.62594)
		(width 0.0889)
		(layer "In6.Cu")
		(net "UPI_CPU0_CPU1_P0P1_DN<1>")
	)
	(segment
		(start 337.950556 -211.726272)
		(end 337.99272 -211.684108)
		(width 0.0889)
		(layer "In6.Cu")
		(net "UPI_CPU0_CPU1_P0P1_DN<1>")
	)
	(segment
		(start 162.718242 -190.621158)
		(end 159.815784 -190.582042)
		(width 0.14732)
		(layer "In6.Cu")
		(net "UPI_CPU0_CPU1_P0P1_DN<1>")
	)
	(segment
		(start 337.950556 -212.520784)
		(end 338.04987 -212.42147)
		(width 0.0889)
		(layer "In6.Cu")
		(net "UPI_CPU0_CPU1_P0P1_DN<1>")
	)
	(segment
		(start 337.589876 -214.622634)
		(end 337.589622 -214.62238)
		(width 0.0889)
		(layer "In6.Cu")
		(net "UPI_CPU0_CPU1_P0P1_DN<1>")
	)
	(segment
		(start 163.200842 -188.520832)
		(end 162.889184 -188.824362)
		(width 0.14732)
		(layer "In6.Cu")
		(net "UPI_CPU0_CPU1_P0P1_DN<1>")
	)
	(segment
		(start 166.763192 -190.675006)
		(end 166.61765 -190.526416)
		(width 0.14732)
		(layer "In6.Cu")
		(net "UPI_CPU0_CPU1_P0P1_DN<1>")
	)
	(segment
		(start 164.018722 -188.532008)
		(end 163.200842 -188.520832)
		(width 0.14732)
		(layer "In6.Cu")
		(net "UPI_CPU0_CPU1_P0P1_DN<1>")
	)
	(segment
		(start 143.628872 -202.450192)
		(end 143.631158 -202.885294)
		(width 0.14732)
		(layer "In6.Cu")
		(net "UPI_CPU0_CPU1_P0P1_DN<1>")
	)
	(segment
		(start 135.733536 -212.685884)
		(end 134.57047 -213.84895)
		(width 0.0889)
		(layer "In6.Cu")
		(net "UPI_CPU0_CPU1_P0P1_DN<1>")
	)
	(segment
		(start 145.262346 -201.238612)
		(end 145.519394 -201.493374)
		(width 0.14732)
		(layer "In6.Cu")
		(net "UPI_CPU0_CPU1_P0P1_DN<1>")
	)
	(segment
		(start 148.973032 -198.217028)
		(end 148.36775 -198.82739)
		(width 0.14732)
		(layer "In6.Cu")
		(net "UPI_CPU0_CPU1_P0P1_DN<1>")
	)
	(segment
		(start 335.846166 -209.47126)
		(end 315.271404 -193.36258)
		(width 0.14732)
		(layer "In6.Cu")
		(net "UPI_CPU0_CPU1_P0P1_DN<1>")
	)
	(segment
		(start 238.960406 -199.466962)
		(end 237.34395 -199.669146)
		(width 0.14732)
		(layer "In6.Cu")
		(net "UPI_CPU0_CPU1_P0P1_DN<1>")
	)
	(segment
		(start 166.335964 -188.56325)
		(end 165.518084 -188.552074)
		(width 0.14732)
		(layer "In6.Cu")
		(net "UPI_CPU0_CPU1_P0P1_DN<1>")
	)
	(segment
		(start 338.04987 -212.15477)
		(end 337.950556 -212.055456)
		(width 0.0889)
		(layer "In6.Cu")
		(net "UPI_CPU0_CPU1_P0P1_DN<1>")
	)
	(segment
		(start 338.04987 -213.153498)
		(end 338.04987 -212.886798)
		(width 0.0889)
		(layer "In6.Cu")
		(net "UPI_CPU0_CPU1_P0P1_DN<1>")
	)
	(segment
		(start 297.689016 -190.470282)
		(end 286.48406 -190.421514)
		(width 0.14732)
		(layer "In6.Cu")
		(net "UPI_CPU0_CPU1_P0P1_DN<1>")
	)
	(segment
		(start 147.151598 -200.054718)
		(end 146.736562 -200.473818)
		(width 0.14732)
		(layer "In6.Cu")
		(net "UPI_CPU0_CPU1_P0P1_DN<1>")
	)
	(segment
		(start 337.950556 -212.787484)
		(end 337.950556 -212.520784)
		(width 0.0889)
		(layer "In6.Cu")
		(net "UPI_CPU0_CPU1_P0P1_DN<1>")
	)
	(segment
		(start 337.964526 -214.622634)
		(end 337.808062 -214.893652)
		(width 0.0889)
		(layer "In6.Cu")
		(net "UPI_CPU0_CPU1_P0P1_DN<1>")
	)
	(segment
		(start 314.963556 -193.008758)
		(end 313.169554 -188.358526)
		(width 0.14732)
		(layer "In6.Cu")
		(net "UPI_CPU0_CPU1_P0P1_DN<1>")
	)
	(segment
		(start 286.48406 -190.421514)
		(end 261.076948 -191.434974)
		(width 0.14732)
		(layer "In6.Cu")
		(net "UPI_CPU0_CPU1_P0P1_DN<1>")
	)
	(segment
		(start 164.44595 -190.644018)
		(end 164.300408 -190.49492)
		(width 0.14732)
		(layer "In6.Cu")
		(net "UPI_CPU0_CPU1_P0P1_DN<1>")
	)
	(segment
		(start 337.992466 -210.875372)
		(end 337.113372 -209.996278)
		(width 0.14732)
		(layer "In6.Cu")
		(net "UPI_CPU0_CPU1_P0P1_DN<1>")
	)
	(segment
		(start 315.271404 -193.36258)
		(end 314.963556 -193.008758)
		(width 0.14732)
		(layer "In6.Cu")
		(net "UPI_CPU0_CPU1_P0P1_DN<1>")
	)
	(segment
		(start 153.069544 -195.134992)
		(end 151.28875 -195.882514)
		(width 0.14732)
		(layer "In6.Cu")
		(net "UPI_CPU0_CPU1_P0P1_DN<1>")
	)
	(segment
		(start 164.322506 -188.84392)
		(end 164.018722 -188.532008)
		(width 0.14732)
		(layer "In6.Cu")
		(net "UPI_CPU0_CPU1_P0P1_DN<1>")
	)
	(segment
		(start 145.835878 -200.222358)
		(end 145.26006 -200.80351)
		(width 0.14732)
		(layer "In6.Cu")
		(net "UPI_CPU0_CPU1_P0P1_DN<1>")
	)
	(segment
		(start 337.950556 -213.252812)
		(end 338.04987 -213.153498)
		(width 0.0889)
		(layer "In6.Cu")
		(net "UPI_CPU0_CPU1_P0P1_DN<1>")
	)
	(segment
		(start 146.736562 -200.473818)
		(end 146.528536 -200.474834)
		(width 0.14732)
		(layer "In6.Cu")
		(net "UPI_CPU0_CPU1_P0P1_DN<1>")
	)
	(segment
		(start 149.700488 -196.713094)
		(end 149.26564 -196.714872)
		(width 0.14732)
		(layer "In6.Cu")
		(net "UPI_CPU0_CPU1_P0P1_DN<1>")
	)
	(segment
		(start 143.889222 -203.348082)
		(end 140.72489 -206.541116)
		(width 0.14732)
		(layer "In6.Cu")
		(net "UPI_CPU0_CPU1_P0P1_DN<1>")
	)
	(segment
		(start 145.52041 -201.7014)
		(end 145.105374 -202.1205)
		(width 0.14732)
		(layer "In6.Cu")
		(net "UPI_CPU0_CPU1_P0P1_DN<1>")
	)
	(arc
		(start 337.72983 -214.91448)
		(mid 337.626685 -214.784455)
		(end 337.589876 -214.622634)
		(width 0.0889)
		(layer "In6.Cu")
		(net "UPI_CPU0_CPU1_P0P1_DN<1>")
	)
	(arc
		(start 134.385812 -214.907114)
		(mid 134.211536 -215.045925)
		(end 134.100062 -215.238838)
		(width 0.0889)
		(layer "In6.Cu")
		(net "UPI_CPU0_CPU1_P0P1_DN<1>")
	)
	(arc
		(start 134.569962 -214.707978)
		(mid 134.494924 -214.823298)
		(end 134.385812 -214.907114)
		(width 0.0889)
		(layer "In6.Cu")
		(net "UPI_CPU0_CPU1_P0P1_DN<1>")
	)
	(segment
		(start 116.809266 -214.344758)
		(end 116.809266 -213.732618)
		(width 0.13208)
		(layer "F.Cu")
		(net "UPI_CPU0_CPU1_P0P1_DN<19>")
	)
	(segment
		(start 354.88118 -214.622888)
		(end 354.880926 -214.622634)
		(width 0.13208)
		(layer "F.Cu")
		(net "UPI_CPU0_CPU1_P0P1_DN<19>")
	)
	(segment
		(start 354.88118 -215.158574)
		(end 354.88118 -214.622888)
		(width 0.13208)
		(layer "F.Cu")
		(net "UPI_CPU0_CPU1_P0P1_DN<19>")
	)
	(segment
		(start 117.052598 -214.05977)
		(end 116.968016 -214.033608)
		(width 0.0889)
		(layer "In6.Cu")
		(net "UPI_CPU0_CPU1_P0P1_DN<19>")
	)
	(segment
		(start 117.183916 -211.835238)
		(end 117.183916 -213.8934)
		(width 0.0889)
		(layer "In6.Cu")
		(net "UPI_CPU0_CPU1_P0P1_DN<19>")
	)
	(segment
		(start 156.69895 -173.25721)
		(end 150.043388 -174.96028)
		(width 0.14732)
		(layer "In6.Cu")
		(net "UPI_CPU0_CPU1_P0P1_DN<19>")
	)
	(segment
		(start 354.976684 -211.835492)
		(end 355.018848 -211.793328)
		(width 0.0889)
		(layer "In6.Cu")
		(net "UPI_CPU0_CPU1_P0P1_DN<19>")
	)
	(segment
		(start 354.976684 -213.929468)
		(end 354.976684 -213.483444)
		(width 0.0889)
		(layer "In6.Cu")
		(net "UPI_CPU0_CPU1_P0P1_DN<19>")
	)
	(segment
		(start 355.018848 -210.897216)
		(end 355.018594 -210.89747)
		(width 0.14732)
		(layer "In6.Cu")
		(net "UPI_CPU0_CPU1_P0P1_DN<19>")
	)
	(segment
		(start 355.018594 -210.130898)
		(end 353.949 -200.00341)
		(width 0.14732)
		(layer "In6.Cu")
		(net "UPI_CPU0_CPU1_P0P1_DN<19>")
	)
	(segment
		(start 238.383318 -172.992288)
		(end 211.441538 -172.992288)
		(width 0.14732)
		(layer "In6.Cu")
		(net "UPI_CPU0_CPU1_P0P1_DN<19>")
	)
	(segment
		(start 117.142006 -211.793328)
		(end 117.183916 -211.835238)
		(width 0.0889)
		(layer "In6.Cu")
		(net "UPI_CPU0_CPU1_P0P1_DN<19>")
	)
	(segment
		(start 355.018594 -210.89747)
		(end 355.018594 -210.130898)
		(width 0.14732)
		(layer "In6.Cu")
		(net "UPI_CPU0_CPU1_P0P1_DN<19>")
	)
	(segment
		(start 117.142006 -211.719668)
		(end 117.142006 -211.77123)
		(width 0.14732)
		(layer "In6.Cu")
		(net "UPI_CPU0_CPU1_P0P1_DN<19>")
	)
	(segment
		(start 302.471074 -172.112178)
		(end 273.075146 -172.827442)
		(width 0.14732)
		(layer "In6.Cu")
		(net "UPI_CPU0_CPU1_P0P1_DN<19>")
	)
	(segment
		(start 138.713718 -180.761386)
		(end 134.448804 -186.4868)
		(width 0.14732)
		(layer "In6.Cu")
		(net "UPI_CPU0_CPU1_P0P1_DN<19>")
	)
	(segment
		(start 117.142006 -211.77123)
		(end 117.142006 -211.793328)
		(width 0.0889)
		(layer "In6.Cu")
		(net "UPI_CPU0_CPU1_P0P1_DN<19>")
	)
	(segment
		(start 354.506276 -214.622634)
		(end 354.506276 -214.461852)
		(width 0.0889)
		(layer "In6.Cu")
		(net "UPI_CPU0_CPU1_P0P1_DN<19>")
	)
	(segment
		(start 354.976684 -213.018116)
		(end 354.976684 -212.751416)
		(width 0.0889)
		(layer "In6.Cu")
		(net "UPI_CPU0_CPU1_P0P1_DN<19>")
	)
	(segment
		(start 349.926402 -195.024756)
		(end 340.228936 -185.64225)
		(width 0.14732)
		(layer "In6.Cu")
		(net "UPI_CPU0_CPU1_P0P1_DN<19>")
	)
	(segment
		(start 319.34912 -173.950376)
		(end 319.34912 -173.950122)
		(width 0.14732)
		(layer "In6.Cu")
		(net "UPI_CPU0_CPU1_P0P1_DN<19>")
	)
	(segment
		(start 354.976684 -212.286088)
		(end 354.976684 -211.835492)
		(width 0.0889)
		(layer "In6.Cu")
		(net "UPI_CPU0_CPU1_P0P1_DN<19>")
	)
	(segment
		(start 355.075998 -212.385402)
		(end 354.976684 -212.286088)
		(width 0.0889)
		(layer "In6.Cu")
		(net "UPI_CPU0_CPU1_P0P1_DN<19>")
	)
	(segment
		(start 302.482504 -172.111924)
		(end 302.476916 -172.111924)
		(width 0.14732)
		(layer "In6.Cu")
		(net "UPI_CPU0_CPU1_P0P1_DN<19>")
	)
	(segment
		(start 355.075998 -212.652102)
		(end 355.075998 -212.385402)
		(width 0.0889)
		(layer "In6.Cu")
		(net "UPI_CPU0_CPU1_P0P1_DN<19>")
	)
	(segment
		(start 302.476916 -172.111924)
		(end 302.471074 -172.112178)
		(width 0.14732)
		(layer "In6.Cu")
		(net "UPI_CPU0_CPU1_P0P1_DN<19>")
	)
	(segment
		(start 340.228936 -185.64225)
		(end 336.445352 -182.88762)
		(width 0.14732)
		(layer "In6.Cu")
		(net "UPI_CPU0_CPU1_P0P1_DN<19>")
	)
	(segment
		(start 354.880926 -214.622634)
		(end 354.724462 -214.893652)
		(width 0.0889)
		(layer "In6.Cu")
		(net "UPI_CPU0_CPU1_P0P1_DN<19>")
	)
	(segment
		(start 319.34912 -173.950122)
		(end 319.323466 -173.936914)
		(width 0.14732)
		(layer "In6.Cu")
		(net "UPI_CPU0_CPU1_P0P1_DN<19>")
	)
	(segment
		(start 302.482758 -172.112178)
		(end 302.482504 -172.111924)
		(width 0.14732)
		(layer "In6.Cu")
		(net "UPI_CPU0_CPU1_P0P1_DN<19>")
	)
	(segment
		(start 134.448804 -186.4868)
		(end 127.668528 -190.993268)
		(width 0.14732)
		(layer "In6.Cu")
		(net "UPI_CPU0_CPU1_P0P1_DN<19>")
	)
	(segment
		(start 313.56427 -172.326554)
		(end 313.530742 -172.31741)
		(width 0.14732)
		(layer "In6.Cu")
		(net "UPI_CPU0_CPU1_P0P1_DN<19>")
	)
	(segment
		(start 355.018848 -211.77123)
		(end 355.018848 -210.897216)
		(width 0.14732)
		(layer "In6.Cu")
		(net "UPI_CPU0_CPU1_P0P1_DN<19>")
	)
	(segment
		(start 116.968016 -214.033608)
		(end 116.809266 -213.732618)
		(width 0.0889)
		(layer "In6.Cu")
		(net "UPI_CPU0_CPU1_P0P1_DN<19>")
	)
	(segment
		(start 117.141752 -209.393282)
		(end 117.141752 -211.719414)
		(width 0.14732)
		(layer "In6.Cu")
		(net "UPI_CPU0_CPU1_P0P1_DN<19>")
	)
	(segment
		(start 353.949 -200.00341)
		(end 349.926402 -195.024756)
		(width 0.14732)
		(layer "In6.Cu")
		(net "UPI_CPU0_CPU1_P0P1_DN<19>")
	)
	(segment
		(start 355.075998 -213.38413)
		(end 355.075998 -213.11743)
		(width 0.0889)
		(layer "In6.Cu")
		(net "UPI_CPU0_CPU1_P0P1_DN<19>")
	)
	(segment
		(start 127.668528 -190.993268)
		(end 120.492774 -199.822308)
		(width 0.14732)
		(layer "In6.Cu")
		(net "UPI_CPU0_CPU1_P0P1_DN<19>")
	)
	(segment
		(start 273.075146 -172.827442)
		(end 238.383318 -172.992288)
		(width 0.14732)
		(layer "In6.Cu")
		(net "UPI_CPU0_CPU1_P0P1_DN<19>")
	)
	(segment
		(start 354.976684 -213.483444)
		(end 355.075998 -213.38413)
		(width 0.0889)
		(layer "In6.Cu")
		(net "UPI_CPU0_CPU1_P0P1_DN<19>")
	)
	(segment
		(start 120.492774 -199.822308)
		(end 117.141752 -209.393282)
		(width 0.14732)
		(layer "In6.Cu")
		(net "UPI_CPU0_CPU1_P0P1_DN<19>")
	)
	(segment
		(start 354.976684 -212.751416)
		(end 355.075998 -212.652102)
		(width 0.0889)
		(layer "In6.Cu")
		(net "UPI_CPU0_CPU1_P0P1_DN<19>")
	)
	(segment
		(start 200.7997 -172.525182)
		(end 156.69895 -173.25721)
		(width 0.14732)
		(layer "In6.Cu")
		(net "UPI_CPU0_CPU1_P0P1_DN<19>")
	)
	(segment
		(start 336.445352 -182.88762)
		(end 319.34912 -173.950376)
		(width 0.14732)
		(layer "In6.Cu")
		(net "UPI_CPU0_CPU1_P0P1_DN<19>")
	)
	(segment
		(start 150.043388 -174.96028)
		(end 138.713718 -180.761386)
		(width 0.14732)
		(layer "In6.Cu")
		(net "UPI_CPU0_CPU1_P0P1_DN<19>")
	)
	(segment
		(start 319.323466 -173.936914)
		(end 313.56427 -172.326808)
		(width 0.14732)
		(layer "In6.Cu")
		(net "UPI_CPU0_CPU1_P0P1_DN<19>")
	)
	(segment
		(start 117.141752 -211.719414)
		(end 117.142006 -211.719668)
		(width 0.14732)
		(layer "In6.Cu")
		(net "UPI_CPU0_CPU1_P0P1_DN<19>")
	)
	(segment
		(start 313.530742 -172.31741)
		(end 302.482758 -172.112178)
		(width 0.14732)
		(layer "In6.Cu")
		(net "UPI_CPU0_CPU1_P0P1_DN<19>")
	)
	(segment
		(start 313.56427 -172.326808)
		(end 313.56427 -172.326554)
		(width 0.14732)
		(layer "In6.Cu")
		(net "UPI_CPU0_CPU1_P0P1_DN<19>")
	)
	(segment
		(start 355.075998 -213.11743)
		(end 354.976684 -213.018116)
		(width 0.0889)
		(layer "In6.Cu")
		(net "UPI_CPU0_CPU1_P0P1_DN<19>")
	)
	(segment
		(start 355.018848 -211.793328)
		(end 355.018848 -211.77123)
		(width 0.0889)
		(layer "In6.Cu")
		(net "UPI_CPU0_CPU1_P0P1_DN<19>")
	)
	(segment
		(start 354.724462 -214.893652)
		(end 354.64623 -214.91448)
		(width 0.0889)
		(layer "In6.Cu")
		(net "UPI_CPU0_CPU1_P0P1_DN<19>")
	)
	(segment
		(start 211.441538 -172.992288)
		(end 200.7997 -172.525182)
		(width 0.14732)
		(layer "In6.Cu")
		(net "UPI_CPU0_CPU1_P0P1_DN<19>")
	)
	(arc
		(start 354.506276 -214.461852)
		(mid 354.581347 -214.34611)
		(end 354.69068 -214.261954)
		(width 0.0889)
		(layer "In6.Cu")
		(net "UPI_CPU0_CPU1_P0P1_DN<19>")
	)
	(arc
		(start 354.64623 -214.91448)
		(mid 354.543085 -214.784455)
		(end 354.506276 -214.622634)
		(width 0.0889)
		(layer "In6.Cu")
		(net "UPI_CPU0_CPU1_P0P1_DN<19>")
	)
	(arc
		(start 117.183916 -213.8934)
		(mid 117.129246 -213.985256)
		(end 117.052598 -214.05977)
		(width 0.0889)
		(layer "In6.Cu")
		(net "UPI_CPU0_CPU1_P0P1_DN<19>")
	)
	(arc
		(start 354.69068 -214.261954)
		(mid 354.851261 -214.138523)
		(end 354.961444 -213.968584)
		(width 0.0889)
		(layer "In6.Cu")
		(net "UPI_CPU0_CPU1_P0P1_DN<19>")
	)
	(arc
		(start 354.961444 -213.968584)
		(mid 354.969409 -213.94916)
		(end 354.976684 -213.929468)
		(width 0.0889)
		(layer "In6.Cu")
		(net "UPI_CPU0_CPU1_P0P1_DN<19>")
	)
	(segment
		(start 117.749066 -215.972644)
		(end 117.749066 -215.436958)
		(width 0.13208)
		(layer "F.Cu")
		(net "UPI_CPU0_CPU1_P0P1_DN<18>")
	)
	(segment
		(start 353.94138 -215.158574)
		(end 353.94138 -214.622888)
		(width 0.13208)
		(layer "F.Cu")
		(net "UPI_CPU0_CPU1_P0P1_DN<18>")
	)
	(segment
		(start 117.749066 -215.436958)
		(end 117.748812 -215.436704)
		(width 0.13208)
		(layer "F.Cu")
		(net "UPI_CPU0_CPU1_P0P1_DN<18>")
	)
	(segment
		(start 353.94138 -214.622888)
		(end 353.941126 -214.622634)
		(width 0.13208)
		(layer "F.Cu")
		(net "UPI_CPU0_CPU1_P0P1_DN<18>")
	)
	(segment
		(start 354.078794 -211.684108)
		(end 354.078794 -211.66201)
		(width 0.0889)
		(layer "In6.Cu")
		(net "UPI_CPU0_CPU1_P0P1_DN<18>")
	)
	(segment
		(start 117.653308 -214.425784)
		(end 117.653308 -214.636858)
		(width 0.0889)
		(layer "In6.Cu")
		(net "UPI_CPU0_CPU1_P0P1_DN<18>")
	)
	(segment
		(start 318.978788 -174.702724)
		(end 313.428634 -173.151292)
		(width 0.14732)
		(layer "In6.Cu")
		(net "UPI_CPU0_CPU1_P0P1_DN<18>")
	)
	(segment
		(start 353.022408 -200.176892)
		(end 349.33001 -195.60667)
		(width 0.14732)
		(layer "In6.Cu")
		(net "UPI_CPU0_CPU1_P0P1_DN<18>")
	)
	(segment
		(start 336.057748 -183.631078)
		(end 318.978788 -174.702724)
		(width 0.14732)
		(layer "In6.Cu")
		(net "UPI_CPU0_CPU1_P0P1_DN<18>")
	)
	(segment
		(start 134.985252 -187.15482)
		(end 128.556004 -191.428116)
		(width 0.14732)
		(layer "In6.Cu")
		(net "UPI_CPU0_CPU1_P0P1_DN<18>")
	)
	(segment
		(start 302.47336 -172.947838)
		(end 273.087338 -173.662594)
		(width 0.14732)
		(layer "In6.Cu")
		(net "UPI_CPU0_CPU1_P0P1_DN<18>")
	)
	(segment
		(start 354.07854 -210.17611)
		(end 353.022408 -200.176892)
		(width 0.14732)
		(layer "In6.Cu")
		(net "UPI_CPU0_CPU1_P0P1_DN<18>")
	)
	(segment
		(start 211.200492 -173.82744)
		(end 200.786492 -173.37024)
		(width 0.14732)
		(layer "In6.Cu")
		(net "UPI_CPU0_CPU1_P0P1_DN<18>")
	)
	(segment
		(start 354.036884 -213.929468)
		(end 354.036884 -211.726018)
		(width 0.0889)
		(layer "In6.Cu")
		(net "UPI_CPU0_CPU1_P0P1_DN<18>")
	)
	(segment
		(start 354.078794 -211.66201)
		(end 354.078794 -210.874864)
		(width 0.14732)
		(layer "In6.Cu")
		(net "UPI_CPU0_CPU1_P0P1_DN<18>")
	)
	(segment
		(start 128.556004 -191.428116)
		(end 121.1707 -200.514712)
		(width 0.14732)
		(layer "In6.Cu")
		(net "UPI_CPU0_CPU1_P0P1_DN<18>")
	)
	(segment
		(start 353.941126 -214.622634)
		(end 353.782376 -214.321644)
		(width 0.0889)
		(layer "In6.Cu")
		(net "UPI_CPU0_CPU1_P0P1_DN<18>")
	)
	(segment
		(start 121.1707 -200.514712)
		(end 118.081806 -209.337402)
		(width 0.14732)
		(layer "In6.Cu")
		(net "UPI_CPU0_CPU1_P0P1_DN<18>")
	)
	(segment
		(start 313.428634 -173.151292)
		(end 302.485044 -172.947838)
		(width 0.14732)
		(layer "In6.Cu")
		(net "UPI_CPU0_CPU1_P0P1_DN<18>")
	)
	(segment
		(start 118.081806 -209.337402)
		(end 118.081806 -211.579968)
		(width 0.14732)
		(layer "In6.Cu")
		(net "UPI_CPU0_CPU1_P0P1_DN<18>")
	)
	(segment
		(start 118.08206 -211.580222)
		(end 118.08206 -211.73821)
		(width 0.14732)
		(layer "In6.Cu")
		(net "UPI_CPU0_CPU1_P0P1_DN<18>")
	)
	(segment
		(start 302.485044 -172.947838)
		(end 302.48479 -172.947584)
		(width 0.14732)
		(layer "In6.Cu")
		(net "UPI_CPU0_CPU1_P0P1_DN<18>")
	)
	(segment
		(start 339.676994 -186.266836)
		(end 336.057748 -183.631078)
		(width 0.14732)
		(layer "In6.Cu")
		(net "UPI_CPU0_CPU1_P0P1_DN<18>")
	)
	(segment
		(start 150.418292 -175.730916)
		(end 139.22756 -181.460902)
		(width 0.14732)
		(layer "In6.Cu")
		(net "UPI_CPU0_CPU1_P0P1_DN<18>")
	)
	(segment
		(start 353.782376 -214.321644)
		(end 353.812602 -214.22487)
		(width 0.0889)
		(layer "In6.Cu")
		(net "UPI_CPU0_CPU1_P0P1_DN<18>")
	)
	(segment
		(start 118.12397 -211.802218)
		(end 118.12397 -213.892892)
		(width 0.0889)
		(layer "In6.Cu")
		(net "UPI_CPU0_CPU1_P0P1_DN<18>")
	)
	(segment
		(start 200.786492 -173.37024)
		(end 156.790136 -174.10049)
		(width 0.14732)
		(layer "In6.Cu")
		(net "UPI_CPU0_CPU1_P0P1_DN<18>")
	)
	(segment
		(start 354.036884 -211.726018)
		(end 354.078794 -211.684108)
		(width 0.0889)
		(layer "In6.Cu")
		(net "UPI_CPU0_CPU1_P0P1_DN<18>")
	)
	(segment
		(start 118.08206 -211.73821)
		(end 118.08206 -211.760308)
		(width 0.0889)
		(layer "In6.Cu")
		(net "UPI_CPU0_CPU1_P0P1_DN<18>")
	)
	(segment
		(start 118.081806 -211.579968)
		(end 118.08206 -211.580222)
		(width 0.14732)
		(layer "In6.Cu")
		(net "UPI_CPU0_CPU1_P0P1_DN<18>")
	)
	(segment
		(start 302.48479 -172.947584)
		(end 302.479202 -172.947584)
		(width 0.14732)
		(layer "In6.Cu")
		(net "UPI_CPU0_CPU1_P0P1_DN<18>")
	)
	(segment
		(start 354.078794 -210.874864)
		(end 354.07854 -210.875118)
		(width 0.14732)
		(layer "In6.Cu")
		(net "UPI_CPU0_CPU1_P0P1_DN<18>")
	)
	(segment
		(start 139.22756 -181.460902)
		(end 134.985252 -187.15482)
		(width 0.14732)
		(layer "In6.Cu")
		(net "UPI_CPU0_CPU1_P0P1_DN<18>")
	)
	(segment
		(start 273.087338 -173.662594)
		(end 238.276384 -173.82744)
		(width 0.14732)
		(layer "In6.Cu")
		(net "UPI_CPU0_CPU1_P0P1_DN<18>")
	)
	(segment
		(start 349.33001 -195.60667)
		(end 339.676994 -186.266836)
		(width 0.14732)
		(layer "In6.Cu")
		(net "UPI_CPU0_CPU1_P0P1_DN<18>")
	)
	(segment
		(start 117.905276 -215.165686)
		(end 117.748812 -215.436704)
		(width 0.0889)
		(layer "In6.Cu")
		(net "UPI_CPU0_CPU1_P0P1_DN<18>")
	)
	(segment
		(start 118.08206 -211.760308)
		(end 118.12397 -211.802218)
		(width 0.0889)
		(layer "In6.Cu")
		(net "UPI_CPU0_CPU1_P0P1_DN<18>")
	)
	(segment
		(start 354.07854 -210.875118)
		(end 354.07854 -210.17611)
		(width 0.14732)
		(layer "In6.Cu")
		(net "UPI_CPU0_CPU1_P0P1_DN<18>")
	)
	(segment
		(start 118.12397 -213.892892)
		(end 118.123716 -213.8934)
		(width 0.0889)
		(layer "In6.Cu")
		(net "UPI_CPU0_CPU1_P0P1_DN<18>")
	)
	(segment
		(start 117.881146 -215.076532)
		(end 117.905276 -215.165686)
		(width 0.0889)
		(layer "In6.Cu")
		(net "UPI_CPU0_CPU1_P0P1_DN<18>")
	)
	(segment
		(start 302.479202 -172.947584)
		(end 302.47336 -172.947838)
		(width 0.14732)
		(layer "In6.Cu")
		(net "UPI_CPU0_CPU1_P0P1_DN<18>")
	)
	(segment
		(start 156.790136 -174.10049)
		(end 150.418292 -175.730916)
		(width 0.14732)
		(layer "In6.Cu")
		(net "UPI_CPU0_CPU1_P0P1_DN<18>")
	)
	(segment
		(start 238.276384 -173.82744)
		(end 211.200492 -173.82744)
		(width 0.14732)
		(layer "In6.Cu")
		(net "UPI_CPU0_CPU1_P0P1_DN<18>")
	)
	(arc
		(start 117.653308 -214.636858)
		(mid 117.711653 -214.873363)
		(end 117.864128 -215.063324)
		(width 0.0889)
		(layer "In6.Cu")
		(net "UPI_CPU0_CPU1_P0P1_DN<18>")
	)
	(arc
		(start 117.864128 -215.063324)
		(mid 117.872574 -215.070009)
		(end 117.881146 -215.076532)
		(width 0.0889)
		(layer "In6.Cu")
		(net "UPI_CPU0_CPU1_P0P1_DN<18>")
	)
	(arc
		(start 353.812602 -214.22487)
		(mid 353.935348 -214.111365)
		(end 354.021898 -213.96833)
		(width 0.0889)
		(layer "In6.Cu")
		(net "UPI_CPU0_CPU1_P0P1_DN<18>")
	)
	(arc
		(start 118.123716 -213.8934)
		(mid 118.048645 -214.009142)
		(end 117.939312 -214.093298)
		(width 0.0889)
		(layer "In6.Cu")
		(net "UPI_CPU0_CPU1_P0P1_DN<18>")
	)
	(arc
		(start 117.939312 -214.093298)
		(mid 117.764764 -214.232402)
		(end 117.653308 -214.425784)
		(width 0.0889)
		(layer "In6.Cu")
		(net "UPI_CPU0_CPU1_P0P1_DN<18>")
	)
	(arc
		(start 354.021898 -213.96833)
		(mid 354.029733 -213.949031)
		(end 354.036884 -213.929468)
		(width 0.0889)
		(layer "In6.Cu")
		(net "UPI_CPU0_CPU1_P0P1_DN<18>")
	)
	(segment
		(start 353.00158 -214.622888)
		(end 353.001326 -214.622634)
		(width 0.13208)
		(layer "F.Cu")
		(net "UPI_CPU0_CPU1_P0P1_DN<17>")
	)
	(segment
		(start 118.688866 -214.344758)
		(end 118.688866 -213.732618)
		(width 0.13208)
		(layer "F.Cu")
		(net "UPI_CPU0_CPU1_P0P1_DN<17>")
	)
	(segment
		(start 353.00158 -215.158574)
		(end 353.00158 -214.622888)
		(width 0.13208)
		(layer "F.Cu")
		(net "UPI_CPU0_CPU1_P0P1_DN<17>")
	)
	(segment
		(start 210.97621 -174.669958)
		(end 200.609962 -174.21479)
		(width 0.14732)
		(layer "In6.Cu")
		(net "UPI_CPU0_CPU1_P0P1_DN<17>")
	)
	(segment
		(start 335.626964 -184.35955)
		(end 318.618616 -175.468026)
		(width 0.14732)
		(layer "In6.Cu")
		(net "UPI_CPU0_CPU1_P0P1_DN<17>")
	)
	(segment
		(start 135.498332 -187.878212)
		(end 129.377694 -191.945006)
		(width 0.14732)
		(layer "In6.Cu")
		(net "UPI_CPU0_CPU1_P0P1_DN<17>")
	)
	(segment
		(start 353.139248 -211.684108)
		(end 353.139248 -211.66201)
		(width 0.0889)
		(layer "In6.Cu")
		(net "UPI_CPU0_CPU1_P0P1_DN<17>")
	)
	(segment
		(start 339.189822 -186.953652)
		(end 335.626964 -184.35955)
		(width 0.14732)
		(layer "In6.Cu")
		(net "UPI_CPU0_CPU1_P0P1_DN<17>")
	)
	(segment
		(start 353.097084 -213.018116)
		(end 353.097084 -212.751416)
		(width 0.0889)
		(layer "In6.Cu")
		(net "UPI_CPU0_CPU1_P0P1_DN<17>")
	)
	(segment
		(start 150.347426 -176.715928)
		(end 139.78382 -182.124858)
		(width 0.14732)
		(layer "In6.Cu")
		(net "UPI_CPU0_CPU1_P0P1_DN<17>")
	)
	(segment
		(start 137.607548 -185.046112)
		(end 137.607802 -185.046112)
		(width 0.14732)
		(layer "In6.Cu")
		(net "UPI_CPU0_CPU1_P0P1_DN<17>")
	)
	(segment
		(start 353.097084 -213.929468)
		(end 353.097084 -213.483444)
		(width 0.0889)
		(layer "In6.Cu")
		(net "UPI_CPU0_CPU1_P0P1_DN<17>")
	)
	(segment
		(start 119.021606 -211.173822)
		(end 119.021606 -211.61629)
		(width 0.14732)
		(layer "In6.Cu")
		(net "UPI_CPU0_CPU1_P0P1_DN<17>")
	)
	(segment
		(start 302.487076 -173.79061)
		(end 302.481488 -173.79061)
		(width 0.14732)
		(layer "In6.Cu")
		(net "UPI_CPU0_CPU1_P0P1_DN<17>")
	)
	(segment
		(start 353.196398 -213.11743)
		(end 353.097084 -213.018116)
		(width 0.0889)
		(layer "In6.Cu")
		(net "UPI_CPU0_CPU1_P0P1_DN<17>")
	)
	(segment
		(start 353.196398 -213.38413)
		(end 353.196398 -213.11743)
		(width 0.0889)
		(layer "In6.Cu")
		(net "UPI_CPU0_CPU1_P0P1_DN<17>")
	)
	(segment
		(start 353.138994 -210.230466)
		(end 352.097594 -200.375266)
		(width 0.14732)
		(layer "In6.Cu")
		(net "UPI_CPU0_CPU1_P0P1_DN<17>")
	)
	(segment
		(start 118.932198 -214.05977)
		(end 118.847616 -214.033608)
		(width 0.0889)
		(layer "In6.Cu")
		(net "UPI_CPU0_CPU1_P0P1_DN<17>")
	)
	(segment
		(start 302.48733 -173.790864)
		(end 302.487076 -173.79061)
		(width 0.14732)
		(layer "In6.Cu")
		(net "UPI_CPU0_CPU1_P0P1_DN<17>")
	)
	(segment
		(start 353.139248 -210.874864)
		(end 353.138994 -210.875118)
		(width 0.14732)
		(layer "In6.Cu")
		(net "UPI_CPU0_CPU1_P0P1_DN<17>")
	)
	(segment
		(start 119.021606 -211.61629)
		(end 119.021606 -211.638388)
		(width 0.0889)
		(layer "In6.Cu")
		(net "UPI_CPU0_CPU1_P0P1_DN<17>")
	)
	(segment
		(start 137.607802 -185.046112)
		(end 135.498332 -187.878212)
		(width 0.14732)
		(layer "In6.Cu")
		(net "UPI_CPU0_CPU1_P0P1_DN<17>")
	)
	(segment
		(start 353.001326 -214.622634)
		(end 352.844862 -214.893652)
		(width 0.0889)
		(layer "In6.Cu")
		(net "UPI_CPU0_CPU1_P0P1_DN<17>")
	)
	(segment
		(start 352.844862 -214.893652)
		(end 352.76663 -214.91448)
		(width 0.0889)
		(layer "In6.Cu")
		(net "UPI_CPU0_CPU1_P0P1_DN<17>")
	)
	(segment
		(start 353.097084 -213.483444)
		(end 353.196398 -213.38413)
		(width 0.0889)
		(layer "In6.Cu")
		(net "UPI_CPU0_CPU1_P0P1_DN<17>")
	)
	(segment
		(start 353.097084 -212.286088)
		(end 353.097084 -211.726272)
		(width 0.0889)
		(layer "In6.Cu")
		(net "UPI_CPU0_CPU1_P0P1_DN<17>")
	)
	(segment
		(start 353.097084 -212.751416)
		(end 353.196398 -212.652102)
		(width 0.0889)
		(layer "In6.Cu")
		(net "UPI_CPU0_CPU1_P0P1_DN<17>")
	)
	(segment
		(start 119.021352 -209.283554)
		(end 119.021352 -211.173568)
		(width 0.14732)
		(layer "In6.Cu")
		(net "UPI_CPU0_CPU1_P0P1_DN<17>")
	)
	(segment
		(start 348.646242 -196.103494)
		(end 339.189822 -186.953652)
		(width 0.14732)
		(layer "In6.Cu")
		(net "UPI_CPU0_CPU1_P0P1_DN<17>")
	)
	(segment
		(start 273.099784 -174.505112)
		(end 238.60887 -174.669958)
		(width 0.14732)
		(layer "In6.Cu")
		(net "UPI_CPU0_CPU1_P0P1_DN<17>")
	)
	(segment
		(start 200.609962 -174.21479)
		(end 157.31236 -174.93361)
		(width 0.14732)
		(layer "In6.Cu")
		(net "UPI_CPU0_CPU1_P0P1_DN<17>")
	)
	(segment
		(start 302.475646 -173.790864)
		(end 273.099784 -174.505112)
		(width 0.14732)
		(layer "In6.Cu")
		(net "UPI_CPU0_CPU1_P0P1_DN<17>")
	)
	(segment
		(start 238.60887 -174.669958)
		(end 210.97621 -174.669958)
		(width 0.14732)
		(layer "In6.Cu")
		(net "UPI_CPU0_CPU1_P0P1_DN<17>")
	)
	(segment
		(start 302.481488 -173.79061)
		(end 302.475646 -173.790864)
		(width 0.14732)
		(layer "In6.Cu")
		(net "UPI_CPU0_CPU1_P0P1_DN<17>")
	)
	(segment
		(start 318.618616 -175.468026)
		(end 313.340242 -173.99254)
		(width 0.14732)
		(layer "In6.Cu")
		(net "UPI_CPU0_CPU1_P0P1_DN<17>")
	)
	(segment
		(start 129.377694 -191.945006)
		(end 121.819924 -201.243946)
		(width 0.14732)
		(layer "In6.Cu")
		(net "UPI_CPU0_CPU1_P0P1_DN<17>")
	)
	(segment
		(start 119.021606 -211.638388)
		(end 119.063516 -211.680298)
		(width 0.0889)
		(layer "In6.Cu")
		(net "UPI_CPU0_CPU1_P0P1_DN<17>")
	)
	(segment
		(start 157.31236 -174.93361)
		(end 150.347426 -176.715928)
		(width 0.14732)
		(layer "In6.Cu")
		(net "UPI_CPU0_CPU1_P0P1_DN<17>")
	)
	(segment
		(start 139.78382 -182.124858)
		(end 137.607548 -185.046112)
		(width 0.14732)
		(layer "In6.Cu")
		(net "UPI_CPU0_CPU1_P0P1_DN<17>")
	)
	(segment
		(start 352.097594 -200.375266)
		(end 348.646242 -196.103494)
		(width 0.14732)
		(layer "In6.Cu")
		(net "UPI_CPU0_CPU1_P0P1_DN<17>")
	)
	(segment
		(start 119.063516 -211.680298)
		(end 119.063516 -213.8934)
		(width 0.0889)
		(layer "In6.Cu")
		(net "UPI_CPU0_CPU1_P0P1_DN<17>")
	)
	(segment
		(start 119.021352 -211.173568)
		(end 119.021606 -211.173822)
		(width 0.14732)
		(layer "In6.Cu")
		(net "UPI_CPU0_CPU1_P0P1_DN<17>")
	)
	(segment
		(start 353.139248 -211.66201)
		(end 353.139248 -210.874864)
		(width 0.14732)
		(layer "In6.Cu")
		(net "UPI_CPU0_CPU1_P0P1_DN<17>")
	)
	(segment
		(start 121.819924 -201.243946)
		(end 119.021352 -209.283554)
		(width 0.14732)
		(layer "In6.Cu")
		(net "UPI_CPU0_CPU1_P0P1_DN<17>")
	)
	(segment
		(start 352.626676 -214.622634)
		(end 352.626676 -214.461852)
		(width 0.0889)
		(layer "In6.Cu")
		(net "UPI_CPU0_CPU1_P0P1_DN<17>")
	)
	(segment
		(start 313.340242 -173.99254)
		(end 302.48733 -173.790864)
		(width 0.14732)
		(layer "In6.Cu")
		(net "UPI_CPU0_CPU1_P0P1_DN<17>")
	)
	(segment
		(start 353.196398 -212.652102)
		(end 353.196398 -212.385402)
		(width 0.0889)
		(layer "In6.Cu")
		(net "UPI_CPU0_CPU1_P0P1_DN<17>")
	)
	(segment
		(start 353.097084 -211.726272)
		(end 353.139248 -211.684108)
		(width 0.0889)
		(layer "In6.Cu")
		(net "UPI_CPU0_CPU1_P0P1_DN<17>")
	)
	(segment
		(start 353.196398 -212.385402)
		(end 353.097084 -212.286088)
		(width 0.0889)
		(layer "In6.Cu")
		(net "UPI_CPU0_CPU1_P0P1_DN<17>")
	)
	(segment
		(start 118.847616 -214.033608)
		(end 118.688866 -213.732618)
		(width 0.0889)
		(layer "In6.Cu")
		(net "UPI_CPU0_CPU1_P0P1_DN<17>")
	)
	(segment
		(start 353.138994 -210.875118)
		(end 353.138994 -210.230466)
		(width 0.14732)
		(layer "In6.Cu")
		(net "UPI_CPU0_CPU1_P0P1_DN<17>")
	)
	(arc
		(start 352.81108 -214.261954)
		(mid 352.971661 -214.138523)
		(end 353.081844 -213.968584)
		(width 0.0889)
		(layer "In6.Cu")
		(net "UPI_CPU0_CPU1_P0P1_DN<17>")
	)
	(arc
		(start 119.063516 -213.8934)
		(mid 119.008846 -213.985256)
		(end 118.932198 -214.05977)
		(width 0.0889)
		(layer "In6.Cu")
		(net "UPI_CPU0_CPU1_P0P1_DN<17>")
	)
	(arc
		(start 353.081844 -213.968584)
		(mid 353.089809 -213.94916)
		(end 353.097084 -213.929468)
		(width 0.0889)
		(layer "In6.Cu")
		(net "UPI_CPU0_CPU1_P0P1_DN<17>")
	)
	(arc
		(start 352.626676 -214.461852)
		(mid 352.701747 -214.34611)
		(end 352.81108 -214.261954)
		(width 0.0889)
		(layer "In6.Cu")
		(net "UPI_CPU0_CPU1_P0P1_DN<17>")
	)
	(arc
		(start 352.76663 -214.91448)
		(mid 352.663485 -214.784455)
		(end 352.626676 -214.622634)
		(width 0.0889)
		(layer "In6.Cu")
		(net "UPI_CPU0_CPU1_P0P1_DN<17>")
	)
	(segment
		(start 352.06178 -214.622888)
		(end 352.061526 -214.622634)
		(width 0.13208)
		(layer "F.Cu")
		(net "UPI_CPU0_CPU1_P0P1_DN<16>")
	)
	(segment
		(start 119.628666 -215.972644)
		(end 119.628666 -215.436958)
		(width 0.13208)
		(layer "F.Cu")
		(net "UPI_CPU0_CPU1_P0P1_DN<16>")
	)
	(segment
		(start 119.628666 -215.436958)
		(end 119.628412 -215.436704)
		(width 0.13208)
		(layer "F.Cu")
		(net "UPI_CPU0_CPU1_P0P1_DN<16>")
	)
	(segment
		(start 352.06178 -215.158574)
		(end 352.06178 -214.622888)
		(width 0.13208)
		(layer "F.Cu")
		(net "UPI_CPU0_CPU1_P0P1_DN<16>")
	)
	(segment
		(start 210.820762 -175.526192)
		(end 200.186036 -175.059086)
		(width 0.14732)
		(layer "In6.Cu")
		(net "UPI_CPU0_CPU1_P0P1_DN<16>")
	)
	(segment
		(start 140.353542 -182.77078)
		(end 136.049766 -188.54801)
		(width 0.14732)
		(layer "In6.Cu")
		(net "UPI_CPU0_CPU1_P0P1_DN<16>")
	)
	(segment
		(start 119.96166 -211.803488)
		(end 120.00357 -211.845398)
		(width 0.0889)
		(layer "In6.Cu")
		(net "UPI_CPU0_CPU1_P0P1_DN<16>")
	)
	(segment
		(start 119.96166 -211.473542)
		(end 119.96166 -211.78139)
		(width 0.14732)
		(layer "In6.Cu")
		(net "UPI_CPU0_CPU1_P0P1_DN<16>")
	)
	(segment
		(start 238.611156 -175.526192)
		(end 210.820762 -175.526192)
		(width 0.14732)
		(layer "In6.Cu")
		(net "UPI_CPU0_CPU1_P0P1_DN<16>")
	)
	(segment
		(start 200.186036 -175.059086)
		(end 157.521656 -175.766984)
		(width 0.14732)
		(layer "In6.Cu")
		(net "UPI_CPU0_CPU1_P0P1_DN<16>")
	)
	(segment
		(start 348.680532 -197.497192)
		(end 337.956144 -187.120022)
		(width 0.14732)
		(layer "In6.Cu")
		(net "UPI_CPU0_CPU1_P0P1_DN<16>")
	)
	(segment
		(start 313.23661 -174.84725)
		(end 302.48987 -174.647606)
		(width 0.14732)
		(layer "In6.Cu")
		(net "UPI_CPU0_CPU1_P0P1_DN<16>")
	)
	(segment
		(start 302.489616 -174.647352)
		(end 302.484028 -174.647352)
		(width 0.14732)
		(layer "In6.Cu")
		(net "UPI_CPU0_CPU1_P0P1_DN<16>")
	)
	(segment
		(start 352.199194 -211.66201)
		(end 352.199194 -210.874864)
		(width 0.14732)
		(layer "In6.Cu")
		(net "UPI_CPU0_CPU1_P0P1_DN<16>")
	)
	(segment
		(start 129.884932 -192.645284)
		(end 122.940064 -201.189844)
		(width 0.14732)
		(layer "In6.Cu")
		(net "UPI_CPU0_CPU1_P0P1_DN<16>")
	)
	(segment
		(start 335.170018 -185.090562)
		(end 318.264286 -176.252632)
		(width 0.14732)
		(layer "In6.Cu")
		(net "UPI_CPU0_CPU1_P0P1_DN<16>")
	)
	(segment
		(start 119.976646 -209.653632)
		(end 119.961406 -209.668872)
		(width 0.14732)
		(layer "In6.Cu")
		(net "UPI_CPU0_CPU1_P0P1_DN<16>")
	)
	(segment
		(start 120.00357 -211.845398)
		(end 120.00357 -213.892892)
		(width 0.0889)
		(layer "In6.Cu")
		(net "UPI_CPU0_CPU1_P0P1_DN<16>")
	)
	(segment
		(start 157.521656 -175.766984)
		(end 150.546308 -177.552096)
		(width 0.14732)
		(layer "In6.Cu")
		(net "UPI_CPU0_CPU1_P0P1_DN<16>")
	)
	(segment
		(start 119.760746 -215.076532)
		(end 119.784876 -215.165686)
		(width 0.0889)
		(layer "In6.Cu")
		(net "UPI_CPU0_CPU1_P0P1_DN<16>")
	)
	(segment
		(start 119.961406 -209.668872)
		(end 119.961406 -211.473288)
		(width 0.14732)
		(layer "In6.Cu")
		(net "UPI_CPU0_CPU1_P0P1_DN<16>")
	)
	(segment
		(start 318.264286 -176.252632)
		(end 313.23661 -174.84725)
		(width 0.14732)
		(layer "In6.Cu")
		(net "UPI_CPU0_CPU1_P0P1_DN<16>")
	)
	(segment
		(start 122.940064 -201.189844)
		(end 119.976646 -209.653632)
		(width 0.14732)
		(layer "In6.Cu")
		(net "UPI_CPU0_CPU1_P0P1_DN<16>")
	)
	(segment
		(start 351.174304 -200.582276)
		(end 348.680532 -197.497192)
		(width 0.14732)
		(layer "In6.Cu")
		(net "UPI_CPU0_CPU1_P0P1_DN<16>")
	)
	(segment
		(start 352.157284 -211.726018)
		(end 352.199194 -211.684108)
		(width 0.0889)
		(layer "In6.Cu")
		(net "UPI_CPU0_CPU1_P0P1_DN<16>")
	)
	(segment
		(start 352.199194 -210.874864)
		(end 352.19894 -210.875118)
		(width 0.14732)
		(layer "In6.Cu")
		(net "UPI_CPU0_CPU1_P0P1_DN<16>")
	)
	(segment
		(start 352.19894 -210.275678)
		(end 351.174304 -200.582276)
		(width 0.14732)
		(layer "In6.Cu")
		(net "UPI_CPU0_CPU1_P0P1_DN<16>")
	)
	(segment
		(start 352.19894 -210.875118)
		(end 352.19894 -210.275678)
		(width 0.14732)
		(layer "In6.Cu")
		(net "UPI_CPU0_CPU1_P0P1_DN<16>")
	)
	(segment
		(start 119.532908 -214.425784)
		(end 119.532908 -214.636858)
		(width 0.0889)
		(layer "In6.Cu")
		(net "UPI_CPU0_CPU1_P0P1_DN<16>")
	)
	(segment
		(start 352.157284 -213.929468)
		(end 352.157284 -211.726018)
		(width 0.0889)
		(layer "In6.Cu")
		(net "UPI_CPU0_CPU1_P0P1_DN<16>")
	)
	(segment
		(start 337.956144 -187.120022)
		(end 335.170018 -185.090562)
		(width 0.14732)
		(layer "In6.Cu")
		(net "UPI_CPU0_CPU1_P0P1_DN<16>")
	)
	(segment
		(start 351.902776 -214.321644)
		(end 351.933002 -214.22487)
		(width 0.0889)
		(layer "In6.Cu")
		(net "UPI_CPU0_CPU1_P0P1_DN<16>")
	)
	(segment
		(start 120.00357 -213.892892)
		(end 120.003316 -213.8934)
		(width 0.0889)
		(layer "In6.Cu")
		(net "UPI_CPU0_CPU1_P0P1_DN<16>")
	)
	(segment
		(start 136.049766 -188.54801)
		(end 129.884932 -192.645284)
		(width 0.14732)
		(layer "In6.Cu")
		(net "UPI_CPU0_CPU1_P0P1_DN<16>")
	)
	(segment
		(start 352.199194 -211.684108)
		(end 352.199194 -211.66201)
		(width 0.0889)
		(layer "In6.Cu")
		(net "UPI_CPU0_CPU1_P0P1_DN<16>")
	)
	(segment
		(start 150.546308 -177.552096)
		(end 140.353542 -182.77078)
		(width 0.14732)
		(layer "In6.Cu")
		(net "UPI_CPU0_CPU1_P0P1_DN<16>")
	)
	(segment
		(start 119.784876 -215.165686)
		(end 119.628412 -215.436704)
		(width 0.0889)
		(layer "In6.Cu")
		(net "UPI_CPU0_CPU1_P0P1_DN<16>")
	)
	(segment
		(start 302.478186 -174.647606)
		(end 273.11223 -175.361346)
		(width 0.14732)
		(layer "In6.Cu")
		(net "UPI_CPU0_CPU1_P0P1_DN<16>")
	)
	(segment
		(start 119.961406 -211.473288)
		(end 119.96166 -211.473542)
		(width 0.14732)
		(layer "In6.Cu")
		(net "UPI_CPU0_CPU1_P0P1_DN<16>")
	)
	(segment
		(start 273.11223 -175.361346)
		(end 238.611156 -175.526192)
		(width 0.14732)
		(layer "In6.Cu")
		(net "UPI_CPU0_CPU1_P0P1_DN<16>")
	)
	(segment
		(start 352.061526 -214.622634)
		(end 351.902776 -214.321644)
		(width 0.0889)
		(layer "In6.Cu")
		(net "UPI_CPU0_CPU1_P0P1_DN<16>")
	)
	(segment
		(start 119.96166 -211.78139)
		(end 119.96166 -211.803488)
		(width 0.0889)
		(layer "In6.Cu")
		(net "UPI_CPU0_CPU1_P0P1_DN<16>")
	)
	(segment
		(start 302.484028 -174.647352)
		(end 302.478186 -174.647606)
		(width 0.14732)
		(layer "In6.Cu")
		(net "UPI_CPU0_CPU1_P0P1_DN<16>")
	)
	(segment
		(start 302.48987 -174.647606)
		(end 302.489616 -174.647352)
		(width 0.14732)
		(layer "In6.Cu")
		(net "UPI_CPU0_CPU1_P0P1_DN<16>")
	)
	(arc
		(start 351.933002 -214.22487)
		(mid 352.055748 -214.111365)
		(end 352.142298 -213.96833)
		(width 0.0889)
		(layer "In6.Cu")
		(net "UPI_CPU0_CPU1_P0P1_DN<16>")
	)
	(arc
		(start 352.142298 -213.96833)
		(mid 352.150133 -213.949031)
		(end 352.157284 -213.929468)
		(width 0.0889)
		(layer "In6.Cu")
		(net "UPI_CPU0_CPU1_P0P1_DN<16>")
	)
	(arc
		(start 120.003316 -213.8934)
		(mid 119.928245 -214.009142)
		(end 119.818912 -214.093298)
		(width 0.0889)
		(layer "In6.Cu")
		(net "UPI_CPU0_CPU1_P0P1_DN<16>")
	)
	(arc
		(start 119.532908 -214.636858)
		(mid 119.591253 -214.873363)
		(end 119.743728 -215.063324)
		(width 0.0889)
		(layer "In6.Cu")
		(net "UPI_CPU0_CPU1_P0P1_DN<16>")
	)
	(arc
		(start 119.818912 -214.093298)
		(mid 119.644364 -214.232402)
		(end 119.532908 -214.425784)
		(width 0.0889)
		(layer "In6.Cu")
		(net "UPI_CPU0_CPU1_P0P1_DN<16>")
	)
	(arc
		(start 119.743728 -215.063324)
		(mid 119.752174 -215.070009)
		(end 119.760746 -215.076532)
		(width 0.0889)
		(layer "In6.Cu")
		(net "UPI_CPU0_CPU1_P0P1_DN<16>")
	)
	(segment
		(start 121.038112 -215.158574)
		(end 121.038112 -214.622888)
		(width 0.13208)
		(layer "F.Cu")
		(net "UPI_CPU0_CPU1_P0P1_DN<15>")
	)
	(segment
		(start 121.038112 -214.622888)
		(end 121.037858 -214.622634)
		(width 0.13208)
		(layer "F.Cu")
		(net "UPI_CPU0_CPU1_P0P1_DN<15>")
	)
	(segment
		(start 350.652334 -215.436958)
		(end 350.65208 -215.436704)
		(width 0.13208)
		(layer "F.Cu")
		(net "UPI_CPU0_CPU1_P0P1_DN<15>")
	)
	(segment
		(start 350.652334 -215.972644)
		(end 350.652334 -215.436958)
		(width 0.13208)
		(layer "F.Cu")
		(net "UPI_CPU0_CPU1_P0P1_DN<15>")
	)
	(segment
		(start 351.027238 -213.892892)
		(end 351.027238 -211.726018)
		(width 0.0889)
		(layer "In6.Cu")
		(net "UPI_CPU0_CPU1_P0P1_DN<15>")
	)
	(segment
		(start 123.70562 -203.161138)
		(end 123.5837 -203.508864)
		(width 0.14732)
		(layer "In6.Cu")
		(net "UPI_CPU0_CPU1_P0P1_DN<15>")
	)
	(segment
		(start 317.734188 -177.25136)
		(end 313.17819 -175.977804)
		(width 0.14732)
		(layer "In6.Cu")
		(net "UPI_CPU0_CPU1_P0P1_DN<15>")
	)
	(segment
		(start 238.614204 -176.657254)
		(end 210.937856 -176.657254)
		(width 0.14732)
		(layer "In6.Cu")
		(net "UPI_CPU0_CPU1_P0P1_DN<15>")
	)
	(segment
		(start 121.175526 -211.783168)
		(end 121.133362 -211.825332)
		(width 0.0889)
		(layer "In6.Cu")
		(net "UPI_CPU0_CPU1_P0P1_DN<15>")
	)
	(segment
		(start 154.309064 -177.771552)
		(end 154.30881 -177.771806)
		(width 0.14732)
		(layer "In6.Cu")
		(net "UPI_CPU0_CPU1_P0P1_DN<15>")
	)
	(segment
		(start 124.04471 -202.192382)
		(end 123.923044 -202.540108)
		(width 0.14732)
		(layer "In6.Cu")
		(net "UPI_CPU0_CPU1_P0P1_DN<15>")
	)
	(segment
		(start 350.556576 -214.636858)
		(end 350.556576 -214.425784)
		(width 0.0889)
		(layer "In6.Cu")
		(net "UPI_CPU0_CPU1_P0P1_DN<15>")
	)
	(segment
		(start 124.148088 -201.45883)
		(end 123.956064 -202.007724)
		(width 0.14732)
		(layer "In6.Cu")
		(net "UPI_CPU0_CPU1_P0P1_DN<15>")
	)
	(segment
		(start 130.476244 -193.673222)
		(end 124.148088 -201.45883)
		(width 0.14732)
		(layer "In6.Cu")
		(net "UPI_CPU0_CPU1_P0P1_DN<15>")
	)
	(segment
		(start 351.027238 -211.726018)
		(end 350.985328 -211.684108)
		(width 0.0889)
		(layer "In6.Cu")
		(net "UPI_CPU0_CPU1_P0P1_DN<15>")
	)
	(segment
		(start 339.921342 -190.965328)
		(end 339.656674 -190.708788)
		(width 0.14732)
		(layer "In6.Cu")
		(net "UPI_CPU0_CPU1_P0P1_DN<15>")
	)
	(segment
		(start 350.985074 -210.344512)
		(end 349.991426 -200.948544)
		(width 0.14732)
		(layer "In6.Cu")
		(net "UPI_CPU0_CPU1_P0P1_DN<15>")
	)
	(segment
		(start 339.653118 -190.504064)
		(end 339.354414 -190.215012)
		(width 0.14732)
		(layer "In6.Cu")
		(net "UPI_CPU0_CPU1_P0P1_DN<15>")
	)
	(segment
		(start 339.354414 -190.215012)
		(end 339.14969 -190.218314)
		(width 0.14732)
		(layer "In6.Cu")
		(net "UPI_CPU0_CPU1_P0P1_DN<15>")
	)
	(segment
		(start 121.910856 -207.848708)
		(end 121.999502 -208.033112)
		(width 0.14732)
		(layer "In6.Cu")
		(net "UPI_CPU0_CPU1_P0P1_DN<15>")
	)
	(segment
		(start 121.571512 -208.81721)
		(end 121.660412 -209.001614)
		(width 0.14732)
		(layer "In6.Cu")
		(net "UPI_CPU0_CPU1_P0P1_DN<15>")
	)
	(segment
		(start 350.985074 -211.53755)
		(end 350.985074 -210.344512)
		(width 0.14732)
		(layer "In6.Cu")
		(net "UPI_CPU0_CPU1_P0P1_DN<15>")
	)
	(segment
		(start 121.353834 -209.438494)
		(end 121.175272 -209.948526)
		(width 0.14732)
		(layer "In6.Cu")
		(net "UPI_CPU0_CPU1_P0P1_DN<15>")
	)
	(segment
		(start 273.12874 -176.492408)
		(end 238.614204 -176.657254)
		(width 0.14732)
		(layer "In6.Cu")
		(net "UPI_CPU0_CPU1_P0P1_DN<15>")
	)
	(segment
		(start 313.17819 -175.977804)
		(end 302.48733 -175.779176)
		(width 0.14732)
		(layer "In6.Cu")
		(net "UPI_CPU0_CPU1_P0P1_DN<15>")
	)
	(segment
		(start 121.175526 -211.76107)
		(end 121.175526 -211.783168)
		(width 0.0889)
		(layer "In6.Cu")
		(net "UPI_CPU0_CPU1_P0P1_DN<15>")
	)
	(segment
		(start 157.727904 -176.896522)
		(end 154.309064 -177.771552)
		(width 0.14732)
		(layer "In6.Cu")
		(net "UPI_CPU0_CPU1_P0P1_DN<15>")
	)
	(segment
		(start 121.538492 -209.349594)
		(end 121.353834 -209.438494)
		(width 0.14732)
		(layer "In6.Cu")
		(net "UPI_CPU0_CPU1_P0P1_DN<15>")
	)
	(segment
		(start 123.738386 -202.629008)
		(end 123.61672 -202.97648)
		(width 0.14732)
		(layer "In6.Cu")
		(net "UPI_CPU0_CPU1_P0P1_DN<15>")
	)
	(segment
		(start 210.937856 -176.657254)
		(end 200.299066 -176.190148)
		(width 0.14732)
		(layer "In6.Cu")
		(net "UPI_CPU0_CPU1_P0P1_DN<15>")
	)
	(segment
		(start 121.175272 -209.948526)
		(end 121.175272 -211.399628)
		(width 0.14732)
		(layer "In6.Cu")
		(net "UPI_CPU0_CPU1_P0P1_DN<15>")
	)
	(segment
		(start 123.956064 -202.007724)
		(end 124.04471 -202.192382)
		(width 0.14732)
		(layer "In6.Cu")
		(net "UPI_CPU0_CPU1_P0P1_DN<15>")
	)
	(segment
		(start 334.70088 -186.12104)
		(end 317.734188 -177.25136)
		(width 0.14732)
		(layer "In6.Cu")
		(net "UPI_CPU0_CPU1_P0P1_DN<15>")
	)
	(segment
		(start 123.5837 -203.508864)
		(end 123.399296 -203.59751)
		(width 0.14732)
		(layer "In6.Cu")
		(net "UPI_CPU0_CPU1_P0P1_DN<15>")
	)
	(segment
		(start 338.881212 -189.757304)
		(end 336.40903 -187.364878)
		(width 0.14732)
		(layer "In6.Cu")
		(net "UPI_CPU0_CPU1_P0P1_DN<15>")
	)
	(segment
		(start 136.711944 -189.527688)
		(end 130.476244 -193.673222)
		(width 0.14732)
		(layer "In6.Cu")
		(net "UPI_CPU0_CPU1_P0P1_DN<15>")
	)
	(segment
		(start 123.923044 -202.540108)
		(end 123.738386 -202.629008)
		(width 0.14732)
		(layer "In6.Cu")
		(net "UPI_CPU0_CPU1_P0P1_DN<15>")
	)
	(segment
		(start 121.999502 -208.033112)
		(end 121.877836 -208.380838)
		(width 0.14732)
		(layer "In6.Cu")
		(net "UPI_CPU0_CPU1_P0P1_DN<15>")
	)
	(segment
		(start 340.126066 -190.961772)
		(end 339.921342 -190.965328)
		(width 0.14732)
		(layer "In6.Cu")
		(net "UPI_CPU0_CPU1_P0P1_DN<15>")
	)
	(segment
		(start 121.175272 -211.399628)
		(end 121.175526 -211.399882)
		(width 0.14732)
		(layer "In6.Cu")
		(net "UPI_CPU0_CPU1_P0P1_DN<15>")
	)
	(segment
		(start 123.399296 -203.59751)
		(end 121.910856 -207.848708)
		(width 0.14732)
		(layer "In6.Cu")
		(net "UPI_CPU0_CPU1_P0P1_DN<15>")
	)
	(segment
		(start 339.14969 -190.218314)
		(end 338.884768 -189.962028)
		(width 0.14732)
		(layer "In6.Cu")
		(net "UPI_CPU0_CPU1_P0P1_DN<15>")
	)
	(segment
		(start 348.35973 -198.929498)
		(end 340.126066 -190.961772)
		(width 0.14732)
		(layer "In6.Cu")
		(net "UPI_CPU0_CPU1_P0P1_DN<15>")
	)
	(segment
		(start 141.074902 -183.671464)
		(end 136.711944 -189.527688)
		(width 0.14732)
		(layer "In6.Cu")
		(net "UPI_CPU0_CPU1_P0P1_DN<15>")
	)
	(segment
		(start 350.65208 -215.436704)
		(end 350.808544 -215.165686)
		(width 0.0889)
		(layer "In6.Cu")
		(net "UPI_CPU0_CPU1_P0P1_DN<15>")
	)
	(segment
		(start 121.660412 -209.001614)
		(end 121.538492 -209.349594)
		(width 0.14732)
		(layer "In6.Cu")
		(net "UPI_CPU0_CPU1_P0P1_DN<15>")
	)
	(segment
		(start 121.133362 -213.93023)
		(end 121.133616 -213.929468)
		(width 0.0889)
		(layer "In6.Cu")
		(net "UPI_CPU0_CPU1_P0P1_DN<15>")
	)
	(segment
		(start 338.884768 -189.962028)
		(end 338.881212 -189.757304)
		(width 0.14732)
		(layer "In6.Cu")
		(net "UPI_CPU0_CPU1_P0P1_DN<15>")
	)
	(segment
		(start 123.61672 -202.97648)
		(end 123.70562 -203.161138)
		(width 0.14732)
		(layer "In6.Cu")
		(net "UPI_CPU0_CPU1_P0P1_DN<15>")
	)
	(segment
		(start 339.656674 -190.708788)
		(end 339.653118 -190.504064)
		(width 0.14732)
		(layer "In6.Cu")
		(net "UPI_CPU0_CPU1_P0P1_DN<15>")
	)
	(segment
		(start 349.991426 -200.948544)
		(end 348.35973 -198.929498)
		(width 0.14732)
		(layer "In6.Cu")
		(net "UPI_CPU0_CPU1_P0P1_DN<15>")
	)
	(segment
		(start 120.879108 -214.321644)
		(end 121.037858 -214.622634)
		(width 0.0889)
		(layer "In6.Cu")
		(net "UPI_CPU0_CPU1_P0P1_DN<15>")
	)
	(segment
		(start 302.48733 -175.779176)
		(end 273.12874 -176.492408)
		(width 0.14732)
		(layer "In6.Cu")
		(net "UPI_CPU0_CPU1_P0P1_DN<15>")
	)
	(segment
		(start 350.808544 -215.165686)
		(end 350.784414 -215.076532)
		(width 0.0889)
		(layer "In6.Cu")
		(net "UPI_CPU0_CPU1_P0P1_DN<15>")
	)
	(segment
		(start 350.985328 -211.537296)
		(end 350.985074 -211.53755)
		(width 0.14732)
		(layer "In6.Cu")
		(net "UPI_CPU0_CPU1_P0P1_DN<15>")
	)
	(segment
		(start 121.175526 -211.399882)
		(end 121.175526 -211.76107)
		(width 0.14732)
		(layer "In6.Cu")
		(net "UPI_CPU0_CPU1_P0P1_DN<15>")
	)
	(segment
		(start 121.877836 -208.380838)
		(end 121.693178 -208.469738)
		(width 0.14732)
		(layer "In6.Cu")
		(net "UPI_CPU0_CPU1_P0P1_DN<15>")
	)
	(segment
		(start 120.909334 -214.22487)
		(end 120.879108 -214.321644)
		(width 0.0889)
		(layer "In6.Cu")
		(net "UPI_CPU0_CPU1_P0P1_DN<15>")
	)
	(segment
		(start 350.985328 -211.684108)
		(end 350.985328 -211.66201)
		(width 0.0889)
		(layer "In6.Cu")
		(net "UPI_CPU0_CPU1_P0P1_DN<15>")
	)
	(segment
		(start 154.30881 -177.771806)
		(end 150.890478 -178.646582)
		(width 0.14732)
		(layer "In6.Cu")
		(net "UPI_CPU0_CPU1_P0P1_DN<15>")
	)
	(segment
		(start 200.299066 -176.190148)
		(end 157.727904 -176.896522)
		(width 0.14732)
		(layer "In6.Cu")
		(net "UPI_CPU0_CPU1_P0P1_DN<15>")
	)
	(segment
		(start 121.133362 -211.825332)
		(end 121.133362 -213.93023)
		(width 0.0889)
		(layer "In6.Cu")
		(net "UPI_CPU0_CPU1_P0P1_DN<15>")
	)
	(segment
		(start 121.693178 -208.469738)
		(end 121.571512 -208.81721)
		(width 0.14732)
		(layer "In6.Cu")
		(net "UPI_CPU0_CPU1_P0P1_DN<15>")
	)
	(segment
		(start 350.985328 -211.66201)
		(end 350.985328 -211.537296)
		(width 0.14732)
		(layer "In6.Cu")
		(net "UPI_CPU0_CPU1_P0P1_DN<15>")
	)
	(segment
		(start 336.40903 -187.364878)
		(end 334.70088 -186.12104)
		(width 0.14732)
		(layer "In6.Cu")
		(net "UPI_CPU0_CPU1_P0P1_DN<15>")
	)
	(segment
		(start 351.026984 -213.8934)
		(end 351.027238 -213.892892)
		(width 0.0889)
		(layer "In6.Cu")
		(net "UPI_CPU0_CPU1_P0P1_DN<15>")
	)
	(segment
		(start 150.890478 -178.646582)
		(end 141.074902 -183.671464)
		(width 0.14732)
		(layer "In6.Cu")
		(net "UPI_CPU0_CPU1_P0P1_DN<15>")
	)
	(arc
		(start 121.11863 -213.96833)
		(mid 121.032079 -214.111364)
		(end 120.909334 -214.22487)
		(width 0.0889)
		(layer "In6.Cu")
		(net "UPI_CPU0_CPU1_P0P1_DN<15>")
	)
	(arc
		(start 350.784414 -215.076532)
		(mid 350.775842 -215.070009)
		(end 350.767396 -215.063324)
		(width 0.0889)
		(layer "In6.Cu")
		(net "UPI_CPU0_CPU1_P0P1_DN<15>")
	)
	(arc
		(start 350.767396 -215.063324)
		(mid 350.614965 -214.873342)
		(end 350.556576 -214.636858)
		(width 0.0889)
		(layer "In6.Cu")
		(net "UPI_CPU0_CPU1_P0P1_DN<15>")
	)
	(arc
		(start 121.133616 -213.929468)
		(mid 121.126458 -213.949028)
		(end 121.11863 -213.96833)
		(width 0.0889)
		(layer "In6.Cu")
		(net "UPI_CPU0_CPU1_P0P1_DN<15>")
	)
	(arc
		(start 350.556576 -214.425784)
		(mid 350.668016 -214.232389)
		(end 350.84258 -214.093298)
		(width 0.0889)
		(layer "In6.Cu")
		(net "UPI_CPU0_CPU1_P0P1_DN<15>")
	)
	(arc
		(start 350.84258 -214.093298)
		(mid 350.951976 -214.009201)
		(end 351.026984 -213.8934)
		(width 0.0889)
		(layer "In6.Cu")
		(net "UPI_CPU0_CPU1_P0P1_DN<15>")
	)
	(segment
		(start 121.977912 -215.158574)
		(end 121.977912 -214.622888)
		(width 0.13208)
		(layer "F.Cu")
		(net "UPI_CPU0_CPU1_P0P1_DN<14>")
	)
	(segment
		(start 121.977912 -214.622888)
		(end 121.977658 -214.622634)
		(width 0.13208)
		(layer "F.Cu")
		(net "UPI_CPU0_CPU1_P0P1_DN<14>")
	)
	(segment
		(start 349.712534 -214.344758)
		(end 349.712534 -213.732618)
		(width 0.13208)
		(layer "F.Cu")
		(net "UPI_CPU0_CPU1_P0P1_DN<14>")
	)
	(segment
		(start 336.428334 -190.603632)
		(end 335.725516 -189.579504)
		(width 0.14732)
		(layer "In6.Cu")
		(net "UPI_CPU0_CPU1_P0P1_DN<14>")
	)
	(segment
		(start 123.199652 -207.558386)
		(end 123.014994 -207.647286)
		(width 0.14732)
		(layer "In6.Cu")
		(net "UPI_CPU0_CPU1_P0P1_DN<14>")
	)
	(segment
		(start 335.12633 -188.338714)
		(end 334.90789 -187.626752)
		(width 0.14732)
		(layer "In6.Cu")
		(net "UPI_CPU0_CPU1_P0P1_DN<14>")
	)
	(segment
		(start 332.86573 -186.122564)
		(end 332.53934 -185.95213)
		(width 0.14732)
		(layer "In6.Cu")
		(net "UPI_CPU0_CPU1_P0P1_DN<14>")
	)
	(segment
		(start 238.61649 -177.50663)
		(end 211.33943 -177.50663)
		(width 0.14732)
		(layer "In6.Cu")
		(net "UPI_CPU0_CPU1_P0P1_DN<14>")
	)
	(segment
		(start 331.046582 -185.171588)
		(end 317.364364 -178.018948)
		(width 0.14732)
		(layer "In6.Cu")
		(net "UPI_CPU0_CPU1_P0P1_DN<14>")
	)
	(segment
		(start 121.742962 -214.91448)
		(end 121.821194 -214.893652)
		(width 0.0889)
		(layer "In6.Cu")
		(net "UPI_CPU0_CPU1_P0P1_DN<14>")
	)
	(segment
		(start 313.096402 -176.82591)
		(end 302.489616 -176.62906)
		(width 0.14732)
		(layer "In6.Cu")
		(net "UPI_CPU0_CPU1_P0P1_DN<14>")
	)
	(segment
		(start 123.910852 -205.08849)
		(end 123.999752 -205.273148)
		(width 0.14732)
		(layer "In6.Cu")
		(net "UPI_CPU0_CPU1_P0P1_DN<14>")
	)
	(segment
		(start 273.141186 -177.341784)
		(end 238.61649 -177.50663)
		(width 0.14732)
		(layer "In6.Cu")
		(net "UPI_CPU0_CPU1_P0P1_DN<14>")
	)
	(segment
		(start 331.629766 -185.476642)
		(end 331.43444 -185.537856)
		(width 0.14732)
		(layer "In6.Cu")
		(net "UPI_CPU0_CPU1_P0P1_DN<14>")
	)
	(segment
		(start 122.115072 -211.684108)
		(end 122.072908 -211.726272)
		(width 0.0889)
		(layer "In6.Cu")
		(net "UPI_CPU0_CPU1_P0P1_DN<14>")
	)
	(segment
		(start 122.642884 -209.147918)
		(end 122.521218 -209.495898)
		(width 0.14732)
		(layer "In6.Cu")
		(net "UPI_CPU0_CPU1_P0P1_DN<14>")
	)
	(segment
		(start 122.981974 -208.179416)
		(end 122.860308 -208.527142)
		(width 0.14732)
		(layer "In6.Cu")
		(net "UPI_CPU0_CPU1_P0P1_DN<14>")
	)
	(segment
		(start 332.926944 -186.318144)
		(end 332.86573 -186.122564)
		(width 0.14732)
		(layer "In6.Cu")
		(net "UPI_CPU0_CPU1_P0P1_DN<14>")
	)
	(segment
		(start 350.045274 -211.684108)
		(end 350.045274 -211.66201)
		(width 0.0889)
		(layer "In6.Cu")
		(net "UPI_CPU0_CPU1_P0P1_DN<14>")
	)
	(segment
		(start 123.014994 -207.647286)
		(end 122.893328 -207.994758)
		(width 0.14732)
		(layer "In6.Cu")
		(net "UPI_CPU0_CPU1_P0P1_DN<14>")
	)
	(segment
		(start 121.821194 -214.893652)
		(end 121.977658 -214.622634)
		(width 0.0889)
		(layer "In6.Cu")
		(net "UPI_CPU0_CPU1_P0P1_DN<14>")
	)
	(segment
		(start 122.072908 -213.362032)
		(end 122.072908 -213.929722)
		(width 0.0889)
		(layer "In6.Cu")
		(net "UPI_CPU0_CPU1_P0P1_DN<14>")
	)
	(segment
		(start 122.072908 -212.896704)
		(end 122.172222 -212.996018)
		(width 0.0889)
		(layer "In6.Cu")
		(net "UPI_CPU0_CPU1_P0P1_DN<14>")
	)
	(segment
		(start 131.003294 -194.349116)
		(end 125.149102 -201.551286)
		(width 0.14732)
		(layer "In6.Cu")
		(net "UPI_CPU0_CPU1_P0P1_DN<14>")
	)
	(segment
		(start 122.33656 -209.584798)
		(end 122.115072 -210.217258)
		(width 0.14732)
		(layer "In6.Cu")
		(net "UPI_CPU0_CPU1_P0P1_DN<14>")
	)
	(segment
		(start 122.893328 -207.994758)
		(end 122.981974 -208.179416)
		(width 0.14732)
		(layer "In6.Cu")
		(net "UPI_CPU0_CPU1_P0P1_DN<14>")
	)
	(segment
		(start 349.98787 -213.12251)
		(end 350.087184 -213.023196)
		(width 0.0889)
		(layer "In6.Cu")
		(net "UPI_CPU0_CPU1_P0P1_DN<14>")
	)
	(segment
		(start 349.712534 -213.732618)
		(end 349.871284 -214.033608)
		(width 0.0889)
		(layer "In6.Cu")
		(net "UPI_CPU0_CPU1_P0P1_DN<14>")
	)
	(segment
		(start 122.072908 -211.726272)
		(end 122.072908 -212.164676)
		(width 0.0889)
		(layer "In6.Cu")
		(net "UPI_CPU0_CPU1_P0P1_DN<14>")
	)
	(segment
		(start 141.624558 -184.357264)
		(end 137.29843 -190.164974)
		(width 0.14732)
		(layer "In6.Cu")
		(net "UPI_CPU0_CPU1_P0P1_DN<14>")
	)
	(segment
		(start 200.52792 -177.031904)
		(end 157.912562 -177.739294)
		(width 0.14732)
		(layer "In6.Cu")
		(net "UPI_CPU0_CPU1_P0P1_DN<14>")
	)
	(segment
		(start 350.087184 -213.023196)
		(end 350.087184 -212.756496)
		(width 0.0889)
		(layer "In6.Cu")
		(net "UPI_CPU0_CPU1_P0P1_DN<14>")
	)
	(segment
		(start 335.725516 -189.579504)
		(end 335.12633 -188.338714)
		(width 0.14732)
		(layer "In6.Cu")
		(net "UPI_CPU0_CPU1_P0P1_DN<14>")
	)
	(segment
		(start 333.253588 -186.488832)
		(end 332.926944 -186.318144)
		(width 0.14732)
		(layer "In6.Cu")
		(net "UPI_CPU0_CPU1_P0P1_DN<14>")
	)
	(segment
		(start 302.489616 -176.62906)
		(end 273.141186 -177.341784)
		(width 0.14732)
		(layer "In6.Cu")
		(net "UPI_CPU0_CPU1_P0P1_DN<14>")
	)
	(segment
		(start 123.660408 -206.241904)
		(end 123.538742 -206.58963)
		(width 0.14732)
		(layer "In6.Cu")
		(net "UPI_CPU0_CPU1_P0P1_DN<14>")
	)
	(segment
		(start 350.04502 -210.389724)
		(end 349.064834 -201.12355)
		(width 0.14732)
		(layer "In6.Cu")
		(net "UPI_CPU0_CPU1_P0P1_DN<14>")
	)
	(segment
		(start 350.087184 -212.756496)
		(end 349.98787 -212.657182)
		(width 0.0889)
		(layer "In6.Cu")
		(net "UPI_CPU0_CPU1_P0P1_DN<14>")
	)
	(segment
		(start 154.552142 -178.599338)
		(end 151.192484 -179.459128)
		(width 0.14732)
		(layer "In6.Cu")
		(net "UPI_CPU0_CPU1_P0P1_DN<14>")
	)
	(segment
		(start 122.172222 -212.53069)
		(end 122.072908 -212.630004)
		(width 0.0889)
		(layer "In6.Cu")
		(net "UPI_CPU0_CPU1_P0P1_DN<14>")
	)
	(segment
		(start 154.552396 -178.599338)
		(end 154.552142 -178.599338)
		(width 0.14732)
		(layer "In6.Cu")
		(net "UPI_CPU0_CPU1_P0P1_DN<14>")
	)
	(segment
		(start 122.67565 -208.616042)
		(end 122.553984 -208.963514)
		(width 0.14732)
		(layer "In6.Cu")
		(net "UPI_CPU0_CPU1_P0P1_DN<14>")
	)
	(segment
		(start 123.354084 -206.67853)
		(end 123.232418 -207.026002)
		(width 0.14732)
		(layer "In6.Cu")
		(net "UPI_CPU0_CPU1_P0P1_DN<14>")
	)
	(segment
		(start 122.521218 -209.495898)
		(end 122.33656 -209.584798)
		(width 0.14732)
		(layer "In6.Cu")
		(net "UPI_CPU0_CPU1_P0P1_DN<14>")
	)
	(segment
		(start 122.115072 -210.217258)
		(end 122.115072 -211.66201)
		(width 0.14732)
		(layer "In6.Cu")
		(net "UPI_CPU0_CPU1_P0P1_DN<14>")
	)
	(segment
		(start 122.172222 -212.996018)
		(end 122.172222 -213.262718)
		(width 0.0889)
		(layer "In6.Cu")
		(net "UPI_CPU0_CPU1_P0P1_DN<14>")
	)
	(segment
		(start 211.33943 -177.50663)
		(end 200.52792 -177.031904)
		(width 0.14732)
		(layer "In6.Cu")
		(net "UPI_CPU0_CPU1_P0P1_DN<14>")
	)
	(segment
		(start 332.344014 -186.013344)
		(end 332.01737 -185.842656)
		(width 0.14732)
		(layer "In6.Cu")
		(net "UPI_CPU0_CPU1_P0P1_DN<14>")
	)
	(segment
		(start 123.321318 -207.21066)
		(end 123.199652 -207.558386)
		(width 0.14732)
		(layer "In6.Cu")
		(net "UPI_CPU0_CPU1_P0P1_DN<14>")
	)
	(segment
		(start 349.98787 -212.657182)
		(end 349.98787 -212.390482)
		(width 0.0889)
		(layer "In6.Cu")
		(net "UPI_CPU0_CPU1_P0P1_DN<14>")
	)
	(segment
		(start 122.172222 -213.262718)
		(end 122.072908 -213.362032)
		(width 0.0889)
		(layer "In6.Cu")
		(net "UPI_CPU0_CPU1_P0P1_DN<14>")
	)
	(segment
		(start 333.448914 -186.427618)
		(end 333.253588 -186.488832)
		(width 0.14732)
		(layer "In6.Cu")
		(net "UPI_CPU0_CPU1_P0P1_DN<14>")
	)
	(segment
		(start 317.364364 -178.018948)
		(end 313.096402 -176.82591)
		(width 0.14732)
		(layer "In6.Cu")
		(net "UPI_CPU0_CPU1_P0P1_DN<14>")
	)
	(segment
		(start 349.98787 -213.38921)
		(end 349.98787 -213.12251)
		(width 0.0889)
		(layer "In6.Cu")
		(net "UPI_CPU0_CPU1_P0P1_DN<14>")
	)
	(segment
		(start 332.53934 -185.95213)
		(end 332.344014 -186.013344)
		(width 0.14732)
		(layer "In6.Cu")
		(net "UPI_CPU0_CPU1_P0P1_DN<14>")
	)
	(segment
		(start 334.90789 -187.626752)
		(end 334.266286 -186.854846)
		(width 0.14732)
		(layer "In6.Cu")
		(net "UPI_CPU0_CPU1_P0P1_DN<14>")
	)
	(segment
		(start 123.571762 -206.057246)
		(end 123.660408 -206.241904)
		(width 0.14732)
		(layer "In6.Cu")
		(net "UPI_CPU0_CPU1_P0P1_DN<14>")
	)
	(segment
		(start 121.603008 -214.461852)
		(end 121.603008 -214.622634)
		(width 0.0889)
		(layer "In6.Cu")
		(net "UPI_CPU0_CPU1_P0P1_DN<14>")
	)
	(segment
		(start 122.553984 -208.963514)
		(end 122.642884 -209.147918)
		(width 0.14732)
		(layer "In6.Cu")
		(net "UPI_CPU0_CPU1_P0P1_DN<14>")
	)
	(segment
		(start 334.266286 -186.854846)
		(end 333.448914 -186.427618)
		(width 0.14732)
		(layer "In6.Cu")
		(net "UPI_CPU0_CPU1_P0P1_DN<14>")
	)
	(segment
		(start 122.860308 -208.527142)
		(end 122.67565 -208.616042)
		(width 0.14732)
		(layer "In6.Cu")
		(net "UPI_CPU0_CPU1_P0P1_DN<14>")
	)
	(segment
		(start 350.087184 -212.291168)
		(end 350.087184 -211.726018)
		(width 0.0889)
		(layer "In6.Cu")
		(net "UPI_CPU0_CPU1_P0P1_DN<14>")
	)
	(segment
		(start 331.956156 -185.647076)
		(end 331.629766 -185.476642)
		(width 0.14732)
		(layer "In6.Cu")
		(net "UPI_CPU0_CPU1_P0P1_DN<14>")
	)
	(segment
		(start 350.087184 -211.726018)
		(end 350.045274 -211.684108)
		(width 0.0889)
		(layer "In6.Cu")
		(net "UPI_CPU0_CPU1_P0P1_DN<14>")
	)
	(segment
		(start 331.107796 -185.367168)
		(end 331.046582 -185.171588)
		(width 0.14732)
		(layer "In6.Cu")
		(net "UPI_CPU0_CPU1_P0P1_DN<14>")
	)
	(segment
		(start 342.11895 -195.073778)
		(end 336.428334 -190.603632)
		(width 0.14732)
		(layer "In6.Cu")
		(net "UPI_CPU0_CPU1_P0P1_DN<14>")
	)
	(segment
		(start 331.43444 -185.537856)
		(end 331.107796 -185.367168)
		(width 0.14732)
		(layer "In6.Cu")
		(net "UPI_CPU0_CPU1_P0P1_DN<14>")
	)
	(segment
		(start 123.878086 -205.620874)
		(end 123.693428 -205.709774)
		(width 0.14732)
		(layer "In6.Cu")
		(net "UPI_CPU0_CPU1_P0P1_DN<14>")
	)
	(segment
		(start 350.087184 -213.8934)
		(end 350.087184 -213.488524)
		(width 0.0889)
		(layer "In6.Cu")
		(net "UPI_CPU0_CPU1_P0P1_DN<14>")
	)
	(segment
		(start 151.192484 -179.459128)
		(end 141.624558 -184.357264)
		(width 0.14732)
		(layer "In6.Cu")
		(net "UPI_CPU0_CPU1_P0P1_DN<14>")
	)
	(segment
		(start 349.064834 -201.12355)
		(end 347.752416 -199.498966)
		(width 0.14732)
		(layer "In6.Cu")
		(net "UPI_CPU0_CPU1_P0P1_DN<14>")
	)
	(segment
		(start 122.172222 -212.26399)
		(end 122.172222 -212.53069)
		(width 0.0889)
		(layer "In6.Cu")
		(net "UPI_CPU0_CPU1_P0P1_DN<14>")
	)
	(segment
		(start 125.149102 -201.55154)
		(end 123.910852 -205.08849)
		(width 0.14732)
		(layer "In6.Cu")
		(net "UPI_CPU0_CPU1_P0P1_DN<14>")
	)
	(segment
		(start 157.912562 -177.739294)
		(end 154.552396 -178.599338)
		(width 0.14732)
		(layer "In6.Cu")
		(net "UPI_CPU0_CPU1_P0P1_DN<14>")
	)
	(segment
		(start 349.98787 -212.390482)
		(end 350.087184 -212.291168)
		(width 0.0889)
		(layer "In6.Cu")
		(net "UPI_CPU0_CPU1_P0P1_DN<14>")
	)
	(segment
		(start 122.072908 -212.164676)
		(end 122.172222 -212.26399)
		(width 0.0889)
		(layer "In6.Cu")
		(net "UPI_CPU0_CPU1_P0P1_DN<14>")
	)
	(segment
		(start 350.045274 -211.66201)
		(end 350.045274 -211.537296)
		(width 0.14732)
		(layer "In6.Cu")
		(net "UPI_CPU0_CPU1_P0P1_DN<14>")
	)
	(segment
		(start 347.752416 -199.498966)
		(end 342.11895 -195.073524)
		(width 0.14732)
		(layer "In6.Cu")
		(net "UPI_CPU0_CPU1_P0P1_DN<14>")
	)
	(segment
		(start 122.115072 -211.66201)
		(end 122.115072 -211.684108)
		(width 0.0889)
		(layer "In6.Cu")
		(net "UPI_CPU0_CPU1_P0P1_DN<14>")
	)
	(segment
		(start 123.693428 -205.709774)
		(end 123.571762 -206.057246)
		(width 0.14732)
		(layer "In6.Cu")
		(net "UPI_CPU0_CPU1_P0P1_DN<14>")
	)
	(segment
		(start 123.232418 -207.026002)
		(end 123.321318 -207.21066)
		(width 0.14732)
		(layer "In6.Cu")
		(net "UPI_CPU0_CPU1_P0P1_DN<14>")
	)
	(segment
		(start 350.04502 -211.53755)
		(end 350.04502 -210.389724)
		(width 0.14732)
		(layer "In6.Cu")
		(net "UPI_CPU0_CPU1_P0P1_DN<14>")
	)
	(segment
		(start 350.045274 -211.537296)
		(end 350.04502 -211.53755)
		(width 0.14732)
		(layer "In6.Cu")
		(net "UPI_CPU0_CPU1_P0P1_DN<14>")
	)
	(segment
		(start 125.149102 -201.551286)
		(end 125.149102 -201.55154)
		(width 0.14732)
		(layer "In6.Cu")
		(net "UPI_CPU0_CPU1_P0P1_DN<14>")
	)
	(segment
		(start 342.11895 -195.073524)
		(end 342.11895 -195.073778)
		(width 0.14732)
		(layer "In6.Cu")
		(net "UPI_CPU0_CPU1_P0P1_DN<14>")
	)
	(segment
		(start 332.01737 -185.842656)
		(end 331.956156 -185.647076)
		(width 0.14732)
		(layer "In6.Cu")
		(net "UPI_CPU0_CPU1_P0P1_DN<14>")
	)
	(segment
		(start 121.787158 -214.2617)
		(end 121.787412 -214.261954)
		(width 0.0889)
		(layer "In6.Cu")
		(net "UPI_CPU0_CPU1_P0P1_DN<14>")
	)
	(segment
		(start 349.871284 -214.033608)
		(end 349.955866 -214.05977)
		(width 0.0889)
		(layer "In6.Cu")
		(net "UPI_CPU0_CPU1_P0P1_DN<14>")
	)
	(segment
		(start 123.538742 -206.58963)
		(end 123.354084 -206.67853)
		(width 0.14732)
		(layer "In6.Cu")
		(net "UPI_CPU0_CPU1_P0P1_DN<14>")
	)
	(segment
		(start 123.999752 -205.273148)
		(end 123.878086 -205.620874)
		(width 0.14732)
		(layer "In6.Cu")
		(net "UPI_CPU0_CPU1_P0P1_DN<14>")
	)
	(segment
		(start 137.29843 -190.164974)
		(end 131.003294 -194.349116)
		(width 0.14732)
		(layer "In6.Cu")
		(net "UPI_CPU0_CPU1_P0P1_DN<14>")
	)
	(segment
		(start 350.087184 -213.488524)
		(end 349.98787 -213.38921)
		(width 0.0889)
		(layer "In6.Cu")
		(net "UPI_CPU0_CPU1_P0P1_DN<14>")
	)
	(segment
		(start 122.072908 -212.630004)
		(end 122.072908 -212.896704)
		(width 0.0889)
		(layer "In6.Cu")
		(net "UPI_CPU0_CPU1_P0P1_DN<14>")
	)
	(arc
		(start 121.787412 -214.261954)
		(mid 121.678016 -214.346051)
		(end 121.603008 -214.461852)
		(width 0.0889)
		(layer "In6.Cu")
		(net "UPI_CPU0_CPU1_P0P1_DN<14>")
	)
	(arc
		(start 122.072908 -213.929722)
		(mid 121.961509 -214.1228)
		(end 121.787158 -214.2617)
		(width 0.0889)
		(layer "In6.Cu")
		(net "UPI_CPU0_CPU1_P0P1_DN<14>")
	)
	(arc
		(start 121.603008 -214.622634)
		(mid 121.639868 -214.784431)
		(end 121.742962 -214.91448)
		(width 0.0889)
		(layer "In6.Cu")
		(net "UPI_CPU0_CPU1_P0P1_DN<14>")
	)
	(arc
		(start 349.955866 -214.05977)
		(mid 350.032539 -213.985276)
		(end 350.087184 -213.8934)
		(width 0.0889)
		(layer "In6.Cu")
		(net "UPI_CPU0_CPU1_P0P1_DN<14>")
	)
	(segment
		(start 122.917712 -215.158574)
		(end 122.917712 -214.622888)
		(width 0.13208)
		(layer "F.Cu")
		(net "UPI_CPU0_CPU1_P0P1_DN<13>")
	)
	(segment
		(start 122.917712 -214.622888)
		(end 122.917458 -214.622634)
		(width 0.13208)
		(layer "F.Cu")
		(net "UPI_CPU0_CPU1_P0P1_DN<13>")
	)
	(segment
		(start 348.772734 -215.436958)
		(end 348.77248 -215.436704)
		(width 0.13208)
		(layer "F.Cu")
		(net "UPI_CPU0_CPU1_P0P1_DN<13>")
	)
	(segment
		(start 348.772734 -215.972644)
		(end 348.772734 -215.436958)
		(width 0.13208)
		(layer "F.Cu")
		(net "UPI_CPU0_CPU1_P0P1_DN<13>")
	)
	(segment
		(start 330.411582 -187.08243)
		(end 329.39609 -186.381644)
		(width 0.14732)
		(layer "In6.Cu")
		(net "UPI_CPU0_CPU1_P0P1_DN<13>")
	)
	(segment
		(start 330.751942 -187.492894)
		(end 330.448666 -187.283598)
		(width 0.14732)
		(layer "In6.Cu")
		(net "UPI_CPU0_CPU1_P0P1_DN<13>")
	)
	(segment
		(start 123.81865 -208.66735)
		(end 123.662948 -208.742026)
		(width 0.14732)
		(layer "In6.Cu")
		(net "UPI_CPU0_CPU1_P0P1_DN<13>")
	)
	(segment
		(start 123.593606 -209.309462)
		(end 123.44908 -209.722212)
		(width 0.14732)
		(layer "In6.Cu")
		(net "UPI_CPU0_CPU1_P0P1_DN<13>")
	)
	(segment
		(start 349.105474 -211.53755)
		(end 349.105474 -210.44408)
		(width 0.14732)
		(layer "In6.Cu")
		(net "UPI_CPU0_CPU1_P0P1_DN<13>")
	)
	(segment
		(start 126.15291 -201.629772)
		(end 126.153164 -201.629772)
		(width 0.14732)
		(layer "In6.Cu")
		(net "UPI_CPU0_CPU1_P0P1_DN<13>")
	)
	(segment
		(start 123.293378 -209.796888)
		(end 123.054872 -210.478624)
		(width 0.14732)
		(layer "In6.Cu")
		(net "UPI_CPU0_CPU1_P0P1_DN<13>")
	)
	(segment
		(start 154.730704 -179.427632)
		(end 154.73045 -179.427632)
		(width 0.14732)
		(layer "In6.Cu")
		(net "UPI_CPU0_CPU1_P0P1_DN<13>")
	)
	(segment
		(start 302.492156 -177.48631)
		(end 273.153632 -178.198526)
		(width 0.14732)
		(layer "In6.Cu")
		(net "UPI_CPU0_CPU1_P0P1_DN<13>")
	)
	(segment
		(start 131.547108 -194.993514)
		(end 126.15291 -201.629772)
		(width 0.14732)
		(layer "In6.Cu")
		(net "UPI_CPU0_CPU1_P0P1_DN<13>")
	)
	(segment
		(start 123.662948 -208.742026)
		(end 123.518676 -209.154268)
		(width 0.14732)
		(layer "In6.Cu")
		(net "UPI_CPU0_CPU1_P0P1_DN<13>")
	)
	(segment
		(start 328.854562 -186.007248)
		(end 325.861934 -183.94172)
		(width 0.14732)
		(layer "In6.Cu")
		(net "UPI_CPU0_CPU1_P0P1_DN<13>")
	)
	(segment
		(start 123.054872 -211.541868)
		(end 123.055126 -211.542122)
		(width 0.14732)
		(layer "In6.Cu")
		(net "UPI_CPU0_CPU1_P0P1_DN<13>")
	)
	(segment
		(start 316.995556 -178.780694)
		(end 313.071002 -177.682652)
		(width 0.14732)
		(layer "In6.Cu")
		(net "UPI_CPU0_CPU1_P0P1_DN<13>")
	)
	(segment
		(start 122.758708 -214.321644)
		(end 122.917458 -214.622634)
		(width 0.0889)
		(layer "In6.Cu")
		(net "UPI_CPU0_CPU1_P0P1_DN<13>")
	)
	(segment
		(start 125.5141 -203.824078)
		(end 125.358652 -203.899008)
		(width 0.14732)
		(layer "In6.Cu")
		(net "UPI_CPU0_CPU1_P0P1_DN<13>")
	)
	(segment
		(start 329.396344 -186.381136)
		(end 329.194922 -186.41822)
		(width 0.14732)
		(layer "In6.Cu")
		(net "UPI_CPU0_CPU1_P0P1_DN<13>")
	)
	(segment
		(start 330.448666 -187.283598)
		(end 330.411836 -187.081922)
		(width 0.14732)
		(layer "In6.Cu")
		(net "UPI_CPU0_CPU1_P0P1_DN<13>")
	)
	(segment
		(start 125.658626 -203.411582)
		(end 125.5141 -203.824078)
		(width 0.14732)
		(layer "In6.Cu")
		(net "UPI_CPU0_CPU1_P0P1_DN<13>")
	)
	(segment
		(start 126.07036 -202.235816)
		(end 125.925834 -202.648312)
		(width 0.14732)
		(layer "In6.Cu")
		(net "UPI_CPU0_CPU1_P0P1_DN<13>")
	)
	(segment
		(start 125.99543 -202.080368)
		(end 126.07036 -202.235816)
		(width 0.14732)
		(layer "In6.Cu")
		(net "UPI_CPU0_CPU1_P0P1_DN<13>")
	)
	(segment
		(start 328.891392 -186.208924)
		(end 328.854562 -186.007248)
		(width 0.14732)
		(layer "In6.Cu")
		(net "UPI_CPU0_CPU1_P0P1_DN<13>")
	)
	(segment
		(start 123.054872 -210.478624)
		(end 123.054872 -211.541868)
		(width 0.14732)
		(layer "In6.Cu")
		(net "UPI_CPU0_CPU1_P0P1_DN<13>")
	)
	(segment
		(start 123.962922 -208.2546)
		(end 123.81865 -208.66735)
		(width 0.14732)
		(layer "In6.Cu")
		(net "UPI_CPU0_CPU1_P0P1_DN<13>")
	)
	(segment
		(start 123.055126 -211.542122)
		(end 123.055126 -211.67471)
		(width 0.14732)
		(layer "In6.Cu")
		(net "UPI_CPU0_CPU1_P0P1_DN<13>")
	)
	(segment
		(start 151.461216 -180.264308)
		(end 142.238222 -184.985914)
		(width 0.14732)
		(layer "In6.Cu")
		(net "UPI_CPU0_CPU1_P0P1_DN<13>")
	)
	(segment
		(start 125.925834 -202.648312)
		(end 125.770386 -202.722988)
		(width 0.14732)
		(layer "In6.Cu")
		(net "UPI_CPU0_CPU1_P0P1_DN<13>")
	)
	(segment
		(start 123.055126 -211.67471)
		(end 123.055126 -211.696808)
		(width 0.0889)
		(layer "In6.Cu")
		(net "UPI_CPU0_CPU1_P0P1_DN<13>")
	)
	(segment
		(start 349.105474 -210.44408)
		(end 348.14256 -201.334116)
		(width 0.14732)
		(layer "In6.Cu")
		(net "UPI_CPU0_CPU1_P0P1_DN<13>")
	)
	(segment
		(start 329.194922 -186.41822)
		(end 328.891392 -186.208924)
		(width 0.14732)
		(layer "In6.Cu")
		(net "UPI_CPU0_CPU1_P0P1_DN<13>")
	)
	(segment
		(start 348.928944 -215.165686)
		(end 348.904814 -215.076532)
		(width 0.0889)
		(layer "In6.Cu")
		(net "UPI_CPU0_CPU1_P0P1_DN<13>")
	)
	(segment
		(start 348.14256 -201.334116)
		(end 347.135196 -200.092564)
		(width 0.14732)
		(layer "In6.Cu")
		(net "UPI_CPU0_CPU1_P0P1_DN<13>")
	)
	(segment
		(start 349.105728 -211.684108)
		(end 349.105728 -211.66201)
		(width 0.0889)
		(layer "In6.Cu")
		(net "UPI_CPU0_CPU1_P0P1_DN<13>")
	)
	(segment
		(start 122.788934 -214.22487)
		(end 122.758708 -214.321644)
		(width 0.0889)
		(layer "In6.Cu")
		(net "UPI_CPU0_CPU1_P0P1_DN<13>")
	)
	(segment
		(start 348.77248 -215.436704)
		(end 348.928944 -215.165686)
		(width 0.0889)
		(layer "In6.Cu")
		(net "UPI_CPU0_CPU1_P0P1_DN<13>")
	)
	(segment
		(start 123.518676 -209.154268)
		(end 123.593606 -209.309462)
		(width 0.14732)
		(layer "In6.Cu")
		(net "UPI_CPU0_CPU1_P0P1_DN<13>")
	)
	(segment
		(start 349.147384 -213.8934)
		(end 349.147638 -213.892892)
		(width 0.0889)
		(layer "In6.Cu")
		(net "UPI_CPU0_CPU1_P0P1_DN<13>")
	)
	(segment
		(start 123.055126 -211.696808)
		(end 123.012962 -211.738972)
		(width 0.0889)
		(layer "In6.Cu")
		(net "UPI_CPU0_CPU1_P0P1_DN<13>")
	)
	(segment
		(start 125.358652 -203.899008)
		(end 123.887992 -208.099406)
		(width 0.14732)
		(layer "In6.Cu")
		(net "UPI_CPU0_CPU1_P0P1_DN<13>")
	)
	(segment
		(start 154.73045 -179.427632)
		(end 151.461216 -180.264308)
		(width 0.14732)
		(layer "In6.Cu")
		(net "UPI_CPU0_CPU1_P0P1_DN<13>")
	)
	(segment
		(start 137.957052 -190.733426)
		(end 131.547108 -194.993514)
		(width 0.14732)
		(layer "In6.Cu")
		(net "UPI_CPU0_CPU1_P0P1_DN<13>")
	)
	(segment
		(start 273.153632 -178.198526)
		(end 238.618776 -178.363372)
		(width 0.14732)
		(layer "In6.Cu")
		(net "UPI_CPU0_CPU1_P0P1_DN<13>")
	)
	(segment
		(start 200.861168 -177.879502)
		(end 158.000446 -178.590702)
		(width 0.14732)
		(layer "In6.Cu")
		(net "UPI_CPU0_CPU1_P0P1_DN<13>")
	)
	(segment
		(start 123.012962 -211.738972)
		(end 123.012962 -213.93023)
		(width 0.0889)
		(layer "In6.Cu")
		(net "UPI_CPU0_CPU1_P0P1_DN<13>")
	)
	(segment
		(start 126.153164 -201.629772)
		(end 125.99543 -202.080368)
		(width 0.14732)
		(layer "In6.Cu")
		(net "UPI_CPU0_CPU1_P0P1_DN<13>")
	)
	(segment
		(start 330.411836 -187.081922)
		(end 330.411582 -187.08243)
		(width 0.14732)
		(layer "In6.Cu")
		(net "UPI_CPU0_CPU1_P0P1_DN<13>")
	)
	(segment
		(start 349.147638 -213.892892)
		(end 349.147638 -211.726018)
		(width 0.0889)
		(layer "In6.Cu")
		(net "UPI_CPU0_CPU1_P0P1_DN<13>")
	)
	(segment
		(start 123.012962 -213.93023)
		(end 123.013216 -213.929468)
		(width 0.0889)
		(layer "In6.Cu")
		(net "UPI_CPU0_CPU1_P0P1_DN<13>")
	)
	(segment
		(start 142.238222 -184.985914)
		(end 137.957052 -190.733426)
		(width 0.14732)
		(layer "In6.Cu")
		(net "UPI_CPU0_CPU1_P0P1_DN<13>")
	)
	(segment
		(start 123.887992 -208.099406)
		(end 123.962922 -208.2546)
		(width 0.14732)
		(layer "In6.Cu")
		(net "UPI_CPU0_CPU1_P0P1_DN<13>")
	)
	(segment
		(start 158.000446 -178.590702)
		(end 154.730704 -179.427632)
		(width 0.14732)
		(layer "In6.Cu")
		(net "UPI_CPU0_CPU1_P0P1_DN<13>")
	)
	(segment
		(start 125.583696 -203.256134)
		(end 125.658626 -203.411582)
		(width 0.14732)
		(layer "In6.Cu")
		(net "UPI_CPU0_CPU1_P0P1_DN<13>")
	)
	(segment
		(start 349.105728 -211.66201)
		(end 349.105728 -211.537296)
		(width 0.14732)
		(layer "In6.Cu")
		(net "UPI_CPU0_CPU1_P0P1_DN<13>")
	)
	(segment
		(start 325.861934 -183.94172)
		(end 316.995556 -178.780694)
		(width 0.14732)
		(layer "In6.Cu")
		(net "UPI_CPU0_CPU1_P0P1_DN<13>")
	)
	(segment
		(start 329.39609 -186.381644)
		(end 329.396344 -186.381136)
		(width 0.14732)
		(layer "In6.Cu")
		(net "UPI_CPU0_CPU1_P0P1_DN<13>")
	)
	(segment
		(start 330.953364 -187.456064)
		(end 330.751942 -187.492894)
		(width 0.14732)
		(layer "In6.Cu")
		(net "UPI_CPU0_CPU1_P0P1_DN<13>")
	)
	(segment
		(start 313.071002 -177.682652)
		(end 302.492156 -177.48631)
		(width 0.14732)
		(layer "In6.Cu")
		(net "UPI_CPU0_CPU1_P0P1_DN<13>")
	)
	(segment
		(start 348.676976 -214.636858)
		(end 348.676976 -214.425784)
		(width 0.0889)
		(layer "In6.Cu")
		(net "UPI_CPU0_CPU1_P0P1_DN<13>")
	)
	(segment
		(start 347.135196 -200.092564)
		(end 331.89926 -188.108844)
		(width 0.14732)
		(layer "In6.Cu")
		(net "UPI_CPU0_CPU1_P0P1_DN<13>")
	)
	(segment
		(start 349.147638 -211.726018)
		(end 349.105728 -211.684108)
		(width 0.0889)
		(layer "In6.Cu")
		(net "UPI_CPU0_CPU1_P0P1_DN<13>")
	)
	(segment
		(start 123.44908 -209.722212)
		(end 123.293378 -209.796888)
		(width 0.14732)
		(layer "In6.Cu")
		(net "UPI_CPU0_CPU1_P0P1_DN<13>")
	)
	(segment
		(start 238.618776 -178.363372)
		(end 211.87918 -178.363372)
		(width 0.14732)
		(layer "In6.Cu")
		(net "UPI_CPU0_CPU1_P0P1_DN<13>")
	)
	(segment
		(start 125.770386 -202.722988)
		(end 125.583696 -203.256134)
		(width 0.14732)
		(layer "In6.Cu")
		(net "UPI_CPU0_CPU1_P0P1_DN<13>")
	)
	(segment
		(start 211.87918 -178.363372)
		(end 200.861168 -177.879502)
		(width 0.14732)
		(layer "In6.Cu")
		(net "UPI_CPU0_CPU1_P0P1_DN<13>")
	)
	(segment
		(start 349.105728 -211.537296)
		(end 349.105474 -211.53755)
		(width 0.14732)
		(layer "In6.Cu")
		(net "UPI_CPU0_CPU1_P0P1_DN<13>")
	)
	(segment
		(start 331.89926 -188.108844)
		(end 330.953364 -187.456064)
		(width 0.14732)
		(layer "In6.Cu")
		(net "UPI_CPU0_CPU1_P0P1_DN<13>")
	)
	(arc
		(start 123.013216 -213.929468)
		(mid 123.006058 -213.949028)
		(end 122.99823 -213.96833)
		(width 0.0889)
		(layer "In6.Cu")
		(net "UPI_CPU0_CPU1_P0P1_DN<13>")
	)
	(arc
		(start 348.96298 -214.093298)
		(mid 349.072376 -214.009201)
		(end 349.147384 -213.8934)
		(width 0.0889)
		(layer "In6.Cu")
		(net "UPI_CPU0_CPU1_P0P1_DN<13>")
	)
	(arc
		(start 348.904814 -215.076532)
		(mid 348.896242 -215.070009)
		(end 348.887796 -215.063324)
		(width 0.0889)
		(layer "In6.Cu")
		(net "UPI_CPU0_CPU1_P0P1_DN<13>")
	)
	(arc
		(start 122.99823 -213.96833)
		(mid 122.911679 -214.111364)
		(end 122.788934 -214.22487)
		(width 0.0889)
		(layer "In6.Cu")
		(net "UPI_CPU0_CPU1_P0P1_DN<13>")
	)
	(arc
		(start 348.676976 -214.425784)
		(mid 348.788416 -214.232389)
		(end 348.96298 -214.093298)
		(width 0.0889)
		(layer "In6.Cu")
		(net "UPI_CPU0_CPU1_P0P1_DN<13>")
	)
	(arc
		(start 348.887796 -215.063324)
		(mid 348.735365 -214.873342)
		(end 348.676976 -214.636858)
		(width 0.0889)
		(layer "In6.Cu")
		(net "UPI_CPU0_CPU1_P0P1_DN<13>")
	)
	(segment
		(start 347.832934 -214.344758)
		(end 347.832934 -213.732618)
		(width 0.13208)
		(layer "F.Cu")
		(net "UPI_CPU0_CPU1_P0P1_DN<12>")
	)
	(segment
		(start 123.857512 -215.158574)
		(end 123.857512 -214.622888)
		(width 0.13208)
		(layer "F.Cu")
		(net "UPI_CPU0_CPU1_P0P1_DN<12>")
	)
	(segment
		(start 123.857512 -214.622888)
		(end 123.857258 -214.622634)
		(width 0.13208)
		(layer "F.Cu")
		(net "UPI_CPU0_CPU1_P0P1_DN<12>")
	)
	(segment
		(start 302.494696 -178.343306)
		(end 273.166078 -179.055014)
		(width 0.14732)
		(layer "In6.Cu")
		(net "UPI_CPU0_CPU1_P0P1_DN<12>")
	)
	(segment
		(start 123.994672 -210.686396)
		(end 123.994672 -211.63407)
		(width 0.14732)
		(layer "In6.Cu")
		(net "UPI_CPU0_CPU1_P0P1_DN<12>")
	)
	(segment
		(start 333.14894 -190.423292)
		(end 333.12481 -190.219838)
		(width 0.14732)
		(layer "In6.Cu")
		(net "UPI_CPU0_CPU1_P0P1_DN<12>")
	)
	(segment
		(start 339.93709 -195.577968)
		(end 333.641954 -190.626746)
		(width 0.14732)
		(layer "In6.Cu")
		(net "UPI_CPU0_CPU1_P0P1_DN<12>")
	)
	(segment
		(start 124.051822 -212.53069)
		(end 123.952508 -212.630004)
		(width 0.0889)
		(layer "In6.Cu")
		(net "UPI_CPU0_CPU1_P0P1_DN<12>")
	)
	(segment
		(start 312.946796 -178.537362)
		(end 302.494696 -178.343306)
		(width 0.14732)
		(layer "In6.Cu")
		(net "UPI_CPU0_CPU1_P0P1_DN<12>")
	)
	(segment
		(start 332.134718 -189.61989)
		(end 331.94498 -189.696852)
		(width 0.14732)
		(layer "In6.Cu")
		(net "UPI_CPU0_CPU1_P0P1_DN<12>")
	)
	(segment
		(start 134.09041 -194.34302)
		(end 134.056374 -194.51193)
		(width 0.14732)
		(layer "In6.Cu")
		(net "UPI_CPU0_CPU1_P0P1_DN<12>")
	)
	(segment
		(start 333.641954 -190.626746)
		(end 333.438754 -190.65113)
		(width 0.14732)
		(layer "In6.Cu")
		(net "UPI_CPU0_CPU1_P0P1_DN<12>")
	)
	(segment
		(start 348.207584 -212.291168)
		(end 348.207584 -211.726018)
		(width 0.0889)
		(layer "In6.Cu")
		(net "UPI_CPU0_CPU1_P0P1_DN<12>")
	)
	(segment
		(start 325.660512 -185.229754)
		(end 325.369174 -184.783476)
		(width 0.14732)
		(layer "In6.Cu")
		(net "UPI_CPU0_CPU1_P0P1_DN<12>")
	)
	(segment
		(start 329.17384 -188.366908)
		(end 326.99325 -186.821064)
		(width 0.14732)
		(layer "In6.Cu")
		(net "UPI_CPU0_CPU1_P0P1_DN<12>")
	)
	(segment
		(start 151.814784 -181.041548)
		(end 142.858998 -185.625486)
		(width 0.14732)
		(layer "In6.Cu")
		(net "UPI_CPU0_CPU1_P0P1_DN<12>")
	)
	(segment
		(start 331.605636 -189.553342)
		(end 331.528674 -189.36335)
		(width 0.14732)
		(layer "In6.Cu")
		(net "UPI_CPU0_CPU1_P0P1_DN<12>")
	)
	(segment
		(start 325.369174 -184.783476)
		(end 324.928992 -184.365646)
		(width 0.14732)
		(layer "In6.Cu")
		(net "UPI_CPU0_CPU1_P0P1_DN<12>")
	)
	(segment
		(start 123.952508 -212.630004)
		(end 123.952508 -212.896704)
		(width 0.0889)
		(layer "In6.Cu")
		(net "UPI_CPU0_CPU1_P0P1_DN<12>")
	)
	(segment
		(start 348.10827 -213.12251)
		(end 348.207584 -213.023196)
		(width 0.0889)
		(layer "In6.Cu")
		(net "UPI_CPU0_CPU1_P0P1_DN<12>")
	)
	(segment
		(start 158.142686 -179.421536)
		(end 151.814784 -181.041548)
		(width 0.14732)
		(layer "In6.Cu")
		(net "UPI_CPU0_CPU1_P0P1_DN<12>")
	)
	(segment
		(start 347.991684 -214.033608)
		(end 348.076266 -214.05977)
		(width 0.0889)
		(layer "In6.Cu")
		(net "UPI_CPU0_CPU1_P0P1_DN<12>")
	)
	(segment
		(start 134.623048 -194.135248)
		(end 134.454138 -194.101212)
		(width 0.14732)
		(layer "In6.Cu")
		(net "UPI_CPU0_CPU1_P0P1_DN<12>")
	)
	(segment
		(start 132.592572 -195.3387)
		(end 132.052314 -195.697856)
		(width 0.14732)
		(layer "In6.Cu")
		(net "UPI_CPU0_CPU1_P0P1_DN<12>")
	)
	(segment
		(start 138.59637 -191.347344)
		(end 137.81405 -191.867536)
		(width 0.14732)
		(layer "In6.Cu")
		(net "UPI_CPU0_CPU1_P0P1_DN<12>")
	)
	(segment
		(start 127.11811 -201.767694)
		(end 123.994672 -210.686396)
		(width 0.14732)
		(layer "In6.Cu")
		(net "UPI_CPU0_CPU1_P0P1_DN<12>")
	)
	(segment
		(start 348.165674 -211.684108)
		(end 348.165674 -211.66201)
		(width 0.0889)
		(layer "In6.Cu")
		(net "UPI_CPU0_CPU1_P0P1_DN<12>")
	)
	(segment
		(start 124.051822 -212.996018)
		(end 124.051822 -213.262718)
		(width 0.0889)
		(layer "In6.Cu")
		(net "UPI_CPU0_CPU1_P0P1_DN<12>")
	)
	(segment
		(start 135.95223 -193.105278)
		(end 135.918194 -193.274188)
		(width 0.14732)
		(layer "In6.Cu")
		(net "UPI_CPU0_CPU1_P0P1_DN<12>")
	)
	(segment
		(start 133.523228 -194.719956)
		(end 133.1595 -194.961764)
		(width 0.14732)
		(layer "In6.Cu")
		(net "UPI_CPU0_CPU1_P0P1_DN<12>")
	)
	(segment
		(start 142.858998 -185.625486)
		(end 138.59637 -191.347344)
		(width 0.14732)
		(layer "In6.Cu")
		(net "UPI_CPU0_CPU1_P0P1_DN<12>")
	)
	(segment
		(start 348.207584 -211.726018)
		(end 348.165674 -211.684108)
		(width 0.0889)
		(layer "In6.Cu")
		(net "UPI_CPU0_CPU1_P0P1_DN<12>")
	)
	(segment
		(start 133.692138 -194.753992)
		(end 133.523228 -194.719956)
		(width 0.14732)
		(layer "In6.Cu")
		(net "UPI_CPU0_CPU1_P0P1_DN<12>")
	)
	(segment
		(start 333.438754 -190.65113)
		(end 333.14894 -190.423292)
		(width 0.14732)
		(layer "In6.Cu")
		(net "UPI_CPU0_CPU1_P0P1_DN<12>")
	)
	(segment
		(start 348.207584 -212.756496)
		(end 348.10827 -212.657182)
		(width 0.0889)
		(layer "In6.Cu")
		(net "UPI_CPU0_CPU1_P0P1_DN<12>")
	)
	(segment
		(start 123.952508 -212.896704)
		(end 124.051822 -212.996018)
		(width 0.0889)
		(layer "In6.Cu")
		(net "UPI_CPU0_CPU1_P0P1_DN<12>")
	)
	(segment
		(start 134.056374 -194.51193)
		(end 133.692138 -194.753992)
		(width 0.14732)
		(layer "In6.Cu")
		(net "UPI_CPU0_CPU1_P0P1_DN<12>")
	)
	(segment
		(start 238.621062 -179.21986)
		(end 212.332316 -179.21986)
		(width 0.14732)
		(layer "In6.Cu")
		(net "UPI_CPU0_CPU1_P0P1_DN<12>")
	)
	(segment
		(start 132.761482 -195.372736)
		(end 132.592572 -195.3387)
		(width 0.14732)
		(layer "In6.Cu")
		(net "UPI_CPU0_CPU1_P0P1_DN<12>")
	)
	(segment
		(start 123.952508 -211.698332)
		(end 123.952508 -212.164676)
		(width 0.0889)
		(layer "In6.Cu")
		(net "UPI_CPU0_CPU1_P0P1_DN<12>")
	)
	(segment
		(start 348.16542 -211.53755)
		(end 348.16542 -210.489292)
		(width 0.14732)
		(layer "In6.Cu")
		(net "UPI_CPU0_CPU1_P0P1_DN<12>")
	)
	(segment
		(start 124.051822 -212.26399)
		(end 124.051822 -212.53069)
		(width 0.0889)
		(layer "In6.Cu")
		(net "UPI_CPU0_CPU1_P0P1_DN<12>")
	)
	(segment
		(start 332.625954 -189.827662)
		(end 332.134718 -189.61989)
		(width 0.14732)
		(layer "In6.Cu")
		(net "UPI_CPU0_CPU1_P0P1_DN<12>")
	)
	(segment
		(start 331.528674 -189.36335)
		(end 329.17384 -188.366908)
		(width 0.14732)
		(layer "In6.Cu")
		(net "UPI_CPU0_CPU1_P0P1_DN<12>")
	)
	(segment
		(start 346.36202 -200.631552)
		(end 339.93709 -195.577968)
		(width 0.14732)
		(layer "In6.Cu")
		(net "UPI_CPU0_CPU1_P0P1_DN<12>")
	)
	(segment
		(start 324.928992 -184.365646)
		(end 316.712854 -179.589938)
		(width 0.14732)
		(layer "In6.Cu")
		(net "UPI_CPU0_CPU1_P0P1_DN<12>")
	)
	(segment
		(start 331.94498 -189.696852)
		(end 331.605636 -189.553342)
		(width 0.14732)
		(layer "In6.Cu")
		(net "UPI_CPU0_CPU1_P0P1_DN<12>")
	)
	(segment
		(start 134.987284 -193.893186)
		(end 134.623048 -194.135248)
		(width 0.14732)
		(layer "In6.Cu")
		(net "UPI_CPU0_CPU1_P0P1_DN<12>")
	)
	(segment
		(start 135.385048 -193.482214)
		(end 135.02132 -193.724022)
		(width 0.14732)
		(layer "In6.Cu")
		(net "UPI_CPU0_CPU1_P0P1_DN<12>")
	)
	(segment
		(start 123.952508 -213.362032)
		(end 123.952508 -213.929722)
		(width 0.0889)
		(layer "In6.Cu")
		(net "UPI_CPU0_CPU1_P0P1_DN<12>")
	)
	(segment
		(start 136.88314 -192.48628)
		(end 136.849104 -192.655444)
		(width 0.14732)
		(layer "In6.Cu")
		(net "UPI_CPU0_CPU1_P0P1_DN<12>")
	)
	(segment
		(start 133.125464 -195.130674)
		(end 132.761482 -195.372736)
		(width 0.14732)
		(layer "In6.Cu")
		(net "UPI_CPU0_CPU1_P0P1_DN<12>")
	)
	(segment
		(start 137.81405 -191.867536)
		(end 137.780014 -192.036446)
		(width 0.14732)
		(layer "In6.Cu")
		(net "UPI_CPU0_CPU1_P0P1_DN<12>")
	)
	(segment
		(start 135.918194 -193.274188)
		(end 135.553958 -193.51625)
		(width 0.14732)
		(layer "In6.Cu")
		(net "UPI_CPU0_CPU1_P0P1_DN<12>")
	)
	(segment
		(start 200.807574 -178.713638)
		(end 158.142686 -179.421536)
		(width 0.14732)
		(layer "In6.Cu")
		(net "UPI_CPU0_CPU1_P0P1_DN<12>")
	)
	(segment
		(start 348.10827 -212.390482)
		(end 348.207584 -212.291168)
		(width 0.0889)
		(layer "In6.Cu")
		(net "UPI_CPU0_CPU1_P0P1_DN<12>")
	)
	(segment
		(start 348.165674 -211.537296)
		(end 348.16542 -211.53755)
		(width 0.14732)
		(layer "In6.Cu")
		(net "UPI_CPU0_CPU1_P0P1_DN<12>")
	)
	(segment
		(start 123.994672 -211.63407)
		(end 123.994672 -211.656168)
		(width 0.0889)
		(layer "In6.Cu")
		(net "UPI_CPU0_CPU1_P0P1_DN<12>")
	)
	(segment
		(start 212.332316 -179.21986)
		(end 200.807574 -178.713638)
		(width 0.14732)
		(layer "In6.Cu")
		(net "UPI_CPU0_CPU1_P0P1_DN<12>")
	)
	(segment
		(start 333.12481 -190.219838)
		(end 332.625954 -189.827662)
		(width 0.14732)
		(layer "In6.Cu")
		(net "UPI_CPU0_CPU1_P0P1_DN<12>")
	)
	(segment
		(start 135.02132 -193.724022)
		(end 134.987284 -193.893186)
		(width 0.14732)
		(layer "In6.Cu")
		(net "UPI_CPU0_CPU1_P0P1_DN<12>")
	)
	(segment
		(start 136.315958 -192.86347)
		(end 135.95223 -193.105278)
		(width 0.14732)
		(layer "In6.Cu")
		(net "UPI_CPU0_CPU1_P0P1_DN<12>")
	)
	(segment
		(start 133.1595 -194.961764)
		(end 133.125464 -195.130674)
		(width 0.14732)
		(layer "In6.Cu")
		(net "UPI_CPU0_CPU1_P0P1_DN<12>")
	)
	(segment
		(start 137.246868 -192.244472)
		(end 136.88314 -192.48628)
		(width 0.14732)
		(layer "In6.Cu")
		(net "UPI_CPU0_CPU1_P0P1_DN<12>")
	)
	(segment
		(start 134.454138 -194.101212)
		(end 134.09041 -194.34302)
		(width 0.14732)
		(layer "In6.Cu")
		(net "UPI_CPU0_CPU1_P0P1_DN<12>")
	)
	(segment
		(start 123.482608 -214.461852)
		(end 123.482608 -214.622634)
		(width 0.0889)
		(layer "In6.Cu")
		(net "UPI_CPU0_CPU1_P0P1_DN<12>")
	)
	(segment
		(start 348.207584 -213.023196)
		(end 348.207584 -212.756496)
		(width 0.0889)
		(layer "In6.Cu")
		(net "UPI_CPU0_CPU1_P0P1_DN<12>")
	)
	(segment
		(start 136.484868 -192.897506)
		(end 136.315958 -192.86347)
		(width 0.14732)
		(layer "In6.Cu")
		(net "UPI_CPU0_CPU1_P0P1_DN<12>")
	)
	(segment
		(start 348.10827 -212.657182)
		(end 348.10827 -212.390482)
		(width 0.0889)
		(layer "In6.Cu")
		(net "UPI_CPU0_CPU1_P0P1_DN<12>")
	)
	(segment
		(start 348.207584 -213.488524)
		(end 348.10827 -213.38921)
		(width 0.0889)
		(layer "In6.Cu")
		(net "UPI_CPU0_CPU1_P0P1_DN<12>")
	)
	(segment
		(start 123.700794 -214.893652)
		(end 123.857258 -214.622634)
		(width 0.0889)
		(layer "In6.Cu")
		(net "UPI_CPU0_CPU1_P0P1_DN<12>")
	)
	(segment
		(start 348.10827 -213.38921)
		(end 348.10827 -213.12251)
		(width 0.0889)
		(layer "In6.Cu")
		(net "UPI_CPU0_CPU1_P0P1_DN<12>")
	)
	(segment
		(start 348.207584 -213.8934)
		(end 348.207584 -213.488524)
		(width 0.0889)
		(layer "In6.Cu")
		(net "UPI_CPU0_CPU1_P0P1_DN<12>")
	)
	(segment
		(start 316.712854 -179.589938)
		(end 312.946796 -178.537362)
		(width 0.14732)
		(layer "In6.Cu")
		(net "UPI_CPU0_CPU1_P0P1_DN<12>")
	)
	(segment
		(start 123.952508 -212.164676)
		(end 124.051822 -212.26399)
		(width 0.0889)
		(layer "In6.Cu")
		(net "UPI_CPU0_CPU1_P0P1_DN<12>")
	)
	(segment
		(start 136.849104 -192.655444)
		(end 136.484868 -192.897506)
		(width 0.14732)
		(layer "In6.Cu")
		(net "UPI_CPU0_CPU1_P0P1_DN<12>")
	)
	(segment
		(start 137.780014 -192.036446)
		(end 137.415778 -192.278508)
		(width 0.14732)
		(layer "In6.Cu")
		(net "UPI_CPU0_CPU1_P0P1_DN<12>")
	)
	(segment
		(start 123.666758 -214.2617)
		(end 123.667012 -214.261954)
		(width 0.0889)
		(layer "In6.Cu")
		(net "UPI_CPU0_CPU1_P0P1_DN<12>")
	)
	(segment
		(start 348.165674 -211.66201)
		(end 348.165674 -211.537296)
		(width 0.14732)
		(layer "In6.Cu")
		(net "UPI_CPU0_CPU1_P0P1_DN<12>")
	)
	(segment
		(start 347.237304 -201.710036)
		(end 346.36202 -200.631552)
		(width 0.14732)
		(layer "In6.Cu")
		(net "UPI_CPU0_CPU1_P0P1_DN<12>")
	)
	(segment
		(start 123.994672 -211.656168)
		(end 123.952508 -211.698332)
		(width 0.0889)
		(layer "In6.Cu")
		(net "UPI_CPU0_CPU1_P0P1_DN<12>")
	)
	(segment
		(start 132.052314 -195.697856)
		(end 127.11811 -201.767694)
		(width 0.14732)
		(layer "In6.Cu")
		(net "UPI_CPU0_CPU1_P0P1_DN<12>")
	)
	(segment
		(start 137.415778 -192.278508)
		(end 137.246868 -192.244472)
		(width 0.14732)
		(layer "In6.Cu")
		(net "UPI_CPU0_CPU1_P0P1_DN<12>")
	)
	(segment
		(start 135.553958 -193.51625)
		(end 135.385048 -193.482214)
		(width 0.14732)
		(layer "In6.Cu")
		(net "UPI_CPU0_CPU1_P0P1_DN<12>")
	)
	(segment
		(start 326.99325 -186.821064)
		(end 325.660512 -185.229754)
		(width 0.14732)
		(layer "In6.Cu")
		(net "UPI_CPU0_CPU1_P0P1_DN<12>")
	)
	(segment
		(start 124.051822 -213.262718)
		(end 123.952508 -213.362032)
		(width 0.0889)
		(layer "In6.Cu")
		(net "UPI_CPU0_CPU1_P0P1_DN<12>")
	)
	(segment
		(start 348.16542 -210.489292)
		(end 347.237304 -201.710036)
		(width 0.14732)
		(layer "In6.Cu")
		(net "UPI_CPU0_CPU1_P0P1_DN<12>")
	)
	(segment
		(start 347.832934 -213.732618)
		(end 347.991684 -214.033608)
		(width 0.0889)
		(layer "In6.Cu")
		(net "UPI_CPU0_CPU1_P0P1_DN<12>")
	)
	(segment
		(start 123.622562 -214.91448)
		(end 123.700794 -214.893652)
		(width 0.0889)
		(layer "In6.Cu")
		(net "UPI_CPU0_CPU1_P0P1_DN<12>")
	)
	(segment
		(start 273.166078 -179.055014)
		(end 238.621062 -179.21986)
		(width 0.14732)
		(layer "In6.Cu")
		(net "UPI_CPU0_CPU1_P0P1_DN<12>")
	)
	(arc
		(start 123.667012 -214.261954)
		(mid 123.557616 -214.346051)
		(end 123.482608 -214.461852)
		(width 0.0889)
		(layer "In6.Cu")
		(net "UPI_CPU0_CPU1_P0P1_DN<12>")
	)
	(arc
		(start 123.952508 -213.929722)
		(mid 123.841109 -214.1228)
		(end 123.666758 -214.2617)
		(width 0.0889)
		(layer "In6.Cu")
		(net "UPI_CPU0_CPU1_P0P1_DN<12>")
	)
	(arc
		(start 123.482608 -214.622634)
		(mid 123.519468 -214.784431)
		(end 123.622562 -214.91448)
		(width 0.0889)
		(layer "In6.Cu")
		(net "UPI_CPU0_CPU1_P0P1_DN<12>")
	)
	(arc
		(start 348.076266 -214.05977)
		(mid 348.152939 -213.985276)
		(end 348.207584 -213.8934)
		(width 0.0889)
		(layer "In6.Cu")
		(net "UPI_CPU0_CPU1_P0P1_DN<12>")
	)
	(segment
		(start 347.36278 -214.622888)
		(end 347.362526 -214.622634)
		(width 0.13208)
		(layer "F.Cu")
		(net "UPI_CPU0_CPU1_P0P1_DN<11>")
	)
	(segment
		(start 124.327666 -214.344758)
		(end 124.327666 -213.809072)
		(width 0.13208)
		(layer "F.Cu")
		(net "UPI_CPU0_CPU1_P0P1_DN<11>")
	)
	(segment
		(start 124.327412 -213.808818)
		(end 124.327412 -213.732618)
		(width 0.13208)
		(layer "F.Cu")
		(net "UPI_CPU0_CPU1_P0P1_DN<11>")
	)
	(segment
		(start 124.327666 -213.809072)
		(end 124.327412 -213.808818)
		(width 0.13208)
		(layer "F.Cu")
		(net "UPI_CPU0_CPU1_P0P1_DN<11>")
	)
	(segment
		(start 347.36278 -215.158574)
		(end 347.36278 -214.622888)
		(width 0.13208)
		(layer "F.Cu")
		(net "UPI_CPU0_CPU1_P0P1_DN<11>")
	)
	(segment
		(start 345.649296 -200.810622)
		(end 339.949282 -196.32676)
		(width 0.14732)
		(layer "In6.Cu")
		(net "UPI_CPU0_CPU1_P0P1_DN<11>")
	)
	(segment
		(start 124.659898 -211.483448)
		(end 124.660152 -211.483702)
		(width 0.14732)
		(layer "In6.Cu")
		(net "UPI_CPU0_CPU1_P0P1_DN<11>")
	)
	(segment
		(start 329.597004 -189.183772)
		(end 328.913236 -188.870336)
		(width 0.14732)
		(layer "In6.Cu")
		(net "UPI_CPU0_CPU1_P0P1_DN<11>")
	)
	(segment
		(start 346.595954 -201.976228)
		(end 345.649296 -200.810622)
		(width 0.14732)
		(layer "In6.Cu")
		(net "UPI_CPU0_CPU1_P0P1_DN<11>")
	)
	(segment
		(start 347.458284 -213.483444)
		(end 347.557598 -213.38413)
		(width 0.0889)
		(layer "In6.Cu")
		(net "UPI_CPU0_CPU1_P0P1_DN<11>")
	)
	(segment
		(start 347.458284 -211.726272)
		(end 347.500448 -211.684108)
		(width 0.0889)
		(layer "In6.Cu")
		(net "UPI_CPU0_CPU1_P0P1_DN<11>")
	)
	(segment
		(start 316.614048 -180.179218)
		(end 312.759598 -179.102004)
		(width 0.14732)
		(layer "In6.Cu")
		(net "UPI_CPU0_CPU1_P0P1_DN<11>")
	)
	(segment
		(start 347.557598 -213.11743)
		(end 347.458284 -213.018116)
		(width 0.0889)
		(layer "In6.Cu")
		(net "UPI_CPU0_CPU1_P0P1_DN<11>")
	)
	(segment
		(start 324.907148 -185.139584)
		(end 324.48119 -184.751726)
		(width 0.14732)
		(layer "In6.Cu")
		(net "UPI_CPU0_CPU1_P0P1_DN<11>")
	)
	(segment
		(start 326.670924 -187.301632)
		(end 325.282814 -185.665618)
		(width 0.14732)
		(layer "In6.Cu")
		(net "UPI_CPU0_CPU1_P0P1_DN<11>")
	)
	(segment
		(start 347.557598 -212.385402)
		(end 347.458284 -212.286088)
		(width 0.0889)
		(layer "In6.Cu")
		(net "UPI_CPU0_CPU1_P0P1_DN<11>")
	)
	(segment
		(start 124.660152 -211.673948)
		(end 124.702062 -211.715858)
		(width 0.0889)
		(layer "In6.Cu")
		(net "UPI_CPU0_CPU1_P0P1_DN<11>")
	)
	(segment
		(start 124.659898 -210.47583)
		(end 124.659898 -211.483448)
		(width 0.14732)
		(layer "In6.Cu")
		(net "UPI_CPU0_CPU1_P0P1_DN<11>")
	)
	(segment
		(start 312.759598 -179.102004)
		(end 302.49622 -178.911758)
		(width 0.14732)
		(layer "In6.Cu")
		(net "UPI_CPU0_CPU1_P0P1_DN<11>")
	)
	(segment
		(start 124.486162 -214.033608)
		(end 124.327412 -213.732618)
		(width 0.0889)
		(layer "In6.Cu")
		(net "UPI_CPU0_CPU1_P0P1_DN<11>")
	)
	(segment
		(start 324.48119 -184.751726)
		(end 316.614048 -180.179218)
		(width 0.14732)
		(layer "In6.Cu")
		(net "UPI_CPU0_CPU1_P0P1_DN<11>")
	)
	(segment
		(start 347.206062 -214.893652)
		(end 347.12783 -214.91448)
		(width 0.0889)
		(layer "In6.Cu")
		(net "UPI_CPU0_CPU1_P0P1_DN<11>")
	)
	(segment
		(start 347.500448 -211.684108)
		(end 347.500448 -211.66201)
		(width 0.0889)
		(layer "In6.Cu")
		(net "UPI_CPU0_CPU1_P0P1_DN<11>")
	)
	(segment
		(start 127.3302 -202.849226)
		(end 124.659898 -210.47583)
		(width 0.14732)
		(layer "In6.Cu")
		(net "UPI_CPU0_CPU1_P0P1_DN<11>")
	)
	(segment
		(start 347.557598 -212.652102)
		(end 347.557598 -212.385402)
		(width 0.0889)
		(layer "In6.Cu")
		(net "UPI_CPU0_CPU1_P0P1_DN<11>")
	)
	(segment
		(start 238.622586 -179.788058)
		(end 212.027516 -179.788058)
		(width 0.14732)
		(layer "In6.Cu")
		(net "UPI_CPU0_CPU1_P0P1_DN<11>")
	)
	(segment
		(start 124.702062 -211.715858)
		(end 124.702062 -213.8934)
		(width 0.0889)
		(layer "In6.Cu")
		(net "UPI_CPU0_CPU1_P0P1_DN<11>")
	)
	(segment
		(start 347.500448 -210.874864)
		(end 347.500194 -210.875118)
		(width 0.14732)
		(layer "In6.Cu")
		(net "UPI_CPU0_CPU1_P0P1_DN<11>")
	)
	(segment
		(start 124.660152 -211.65185)
		(end 124.660152 -211.673948)
		(width 0.0889)
		(layer "In6.Cu")
		(net "UPI_CPU0_CPU1_P0P1_DN<11>")
	)
	(segment
		(start 325.282814 -185.665618)
		(end 324.907148 -185.139584)
		(width 0.14732)
		(layer "In6.Cu")
		(net "UPI_CPU0_CPU1_P0P1_DN<11>")
	)
	(segment
		(start 347.458284 -213.018116)
		(end 347.458284 -212.751416)
		(width 0.0889)
		(layer "In6.Cu")
		(net "UPI_CPU0_CPU1_P0P1_DN<11>")
	)
	(segment
		(start 328.913236 -188.870336)
		(end 326.670924 -187.301632)
		(width 0.14732)
		(layer "In6.Cu")
		(net "UPI_CPU0_CPU1_P0P1_DN<11>")
	)
	(segment
		(start 212.027516 -179.788058)
		(end 200.688448 -179.289964)
		(width 0.14732)
		(layer "In6.Cu")
		(net "UPI_CPU0_CPU1_P0P1_DN<11>")
	)
	(segment
		(start 347.557598 -213.38413)
		(end 347.557598 -213.11743)
		(width 0.0889)
		(layer "In6.Cu")
		(net "UPI_CPU0_CPU1_P0P1_DN<11>")
	)
	(segment
		(start 334.25765 -191.849248)
		(end 329.597004 -189.183772)
		(width 0.14732)
		(layer "In6.Cu")
		(net "UPI_CPU0_CPU1_P0P1_DN<11>")
	)
	(segment
		(start 347.458284 -212.286088)
		(end 347.458284 -211.726272)
		(width 0.0889)
		(layer "In6.Cu")
		(net "UPI_CPU0_CPU1_P0P1_DN<11>")
	)
	(segment
		(start 346.987876 -214.622634)
		(end 346.987876 -214.461852)
		(width 0.0889)
		(layer "In6.Cu")
		(net "UPI_CPU0_CPU1_P0P1_DN<11>")
	)
	(segment
		(start 127.614426 -202.037188)
		(end 127.330708 -202.848972)
		(width 0.14732)
		(layer "In6.Cu")
		(net "UPI_CPU0_CPU1_P0P1_DN<11>")
	)
	(segment
		(start 127.330708 -202.848972)
		(end 127.3302 -202.849226)
		(width 0.14732)
		(layer "In6.Cu")
		(net "UPI_CPU0_CPU1_P0P1_DN<11>")
	)
	(segment
		(start 302.49622 -178.911758)
		(end 273.174206 -179.623212)
		(width 0.14732)
		(layer "In6.Cu")
		(net "UPI_CPU0_CPU1_P0P1_DN<11>")
	)
	(segment
		(start 138.838686 -192.004696)
		(end 132.164074 -196.441314)
		(width 0.14732)
		(layer "In6.Cu")
		(net "UPI_CPU0_CPU1_P0P1_DN<11>")
	)
	(segment
		(start 347.500194 -210.529424)
		(end 346.595954 -201.976228)
		(width 0.14732)
		(layer "In6.Cu")
		(net "UPI_CPU0_CPU1_P0P1_DN<11>")
	)
	(segment
		(start 347.458284 -213.929468)
		(end 347.458284 -213.483444)
		(width 0.0889)
		(layer "In6.Cu")
		(net "UPI_CPU0_CPU1_P0P1_DN<11>")
	)
	(segment
		(start 347.362526 -214.622634)
		(end 347.206062 -214.893652)
		(width 0.0889)
		(layer "In6.Cu")
		(net "UPI_CPU0_CPU1_P0P1_DN<11>")
	)
	(segment
		(start 124.660152 -211.483702)
		(end 124.660152 -211.65185)
		(width 0.14732)
		(layer "In6.Cu")
		(net "UPI_CPU0_CPU1_P0P1_DN<11>")
	)
	(segment
		(start 339.949282 -196.32676)
		(end 339.949282 -196.326506)
		(width 0.14732)
		(layer "In6.Cu")
		(net "UPI_CPU0_CPU1_P0P1_DN<11>")
	)
	(segment
		(start 347.458284 -212.751416)
		(end 347.557598 -212.652102)
		(width 0.0889)
		(layer "In6.Cu")
		(net "UPI_CPU0_CPU1_P0P1_DN<11>")
	)
	(segment
		(start 152.00376 -181.595014)
		(end 143.257778 -186.072272)
		(width 0.14732)
		(layer "In6.Cu")
		(net "UPI_CPU0_CPU1_P0P1_DN<11>")
	)
	(segment
		(start 124.570744 -214.05977)
		(end 124.486162 -214.033608)
		(width 0.0889)
		(layer "In6.Cu")
		(net "UPI_CPU0_CPU1_P0P1_DN<11>")
	)
	(segment
		(start 143.257778 -186.072272)
		(end 138.838686 -192.004696)
		(width 0.14732)
		(layer "In6.Cu")
		(net "UPI_CPU0_CPU1_P0P1_DN<11>")
	)
	(segment
		(start 132.164074 -196.441314)
		(end 127.614426 -202.037188)
		(width 0.14732)
		(layer "In6.Cu")
		(net "UPI_CPU0_CPU1_P0P1_DN<11>")
	)
	(segment
		(start 273.174206 -179.623212)
		(end 238.622586 -179.788058)
		(width 0.14732)
		(layer "In6.Cu")
		(net "UPI_CPU0_CPU1_P0P1_DN<11>")
	)
	(segment
		(start 339.949282 -196.326506)
		(end 334.25765 -191.849248)
		(width 0.14732)
		(layer "In6.Cu")
		(net "UPI_CPU0_CPU1_P0P1_DN<11>")
	)
	(segment
		(start 347.500194 -210.875118)
		(end 347.500194 -210.529424)
		(width 0.14732)
		(layer "In6.Cu")
		(net "UPI_CPU0_CPU1_P0P1_DN<11>")
	)
	(segment
		(start 158.259018 -179.993798)
		(end 152.00376 -181.595014)
		(width 0.14732)
		(layer "In6.Cu")
		(net "UPI_CPU0_CPU1_P0P1_DN<11>")
	)
	(segment
		(start 200.688448 -179.289964)
		(end 158.259018 -179.993798)
		(width 0.14732)
		(layer "In6.Cu")
		(net "UPI_CPU0_CPU1_P0P1_DN<11>")
	)
	(segment
		(start 347.500448 -211.66201)
		(end 347.500448 -210.874864)
		(width 0.14732)
		(layer "In6.Cu")
		(net "UPI_CPU0_CPU1_P0P1_DN<11>")
	)
	(arc
		(start 347.443044 -213.968584)
		(mid 347.451009 -213.94916)
		(end 347.458284 -213.929468)
		(width 0.0889)
		(layer "In6.Cu")
		(net "UPI_CPU0_CPU1_P0P1_DN<11>")
	)
	(arc
		(start 124.702062 -213.8934)
		(mid 124.647392 -213.985256)
		(end 124.570744 -214.05977)
		(width 0.0889)
		(layer "In6.Cu")
		(net "UPI_CPU0_CPU1_P0P1_DN<11>")
	)
	(arc
		(start 347.12783 -214.91448)
		(mid 347.024685 -214.784455)
		(end 346.987876 -214.622634)
		(width 0.0889)
		(layer "In6.Cu")
		(net "UPI_CPU0_CPU1_P0P1_DN<11>")
	)
	(arc
		(start 346.987876 -214.461852)
		(mid 347.062947 -214.34611)
		(end 347.17228 -214.261954)
		(width 0.0889)
		(layer "In6.Cu")
		(net "UPI_CPU0_CPU1_P0P1_DN<11>")
	)
	(arc
		(start 347.17228 -214.261954)
		(mid 347.332861 -214.138523)
		(end 347.443044 -213.968584)
		(width 0.0889)
		(layer "In6.Cu")
		(net "UPI_CPU0_CPU1_P0P1_DN<11>")
	)
	(segment
		(start 125.267466 -215.972644)
		(end 125.267466 -215.436958)
		(width 0.13208)
		(layer "F.Cu")
		(net "UPI_CPU0_CPU1_P0P1_DN<10>")
	)
	(segment
		(start 346.42298 -214.622888)
		(end 346.422726 -214.622634)
		(width 0.13208)
		(layer "F.Cu")
		(net "UPI_CPU0_CPU1_P0P1_DN<10>")
	)
	(segment
		(start 125.267466 -215.436958)
		(end 125.267212 -215.436704)
		(width 0.13208)
		(layer "F.Cu")
		(net "UPI_CPU0_CPU1_P0P1_DN<10>")
	)
	(segment
		(start 346.42298 -215.158574)
		(end 346.42298 -214.622888)
		(width 0.13208)
		(layer "F.Cu")
		(net "UPI_CPU0_CPU1_P0P1_DN<10>")
	)
	(segment
		(start 128.578356 -202.275694)
		(end 125.599952 -210.782154)
		(width 0.14732)
		(layer "In6.Cu")
		(net "UPI_CPU0_CPU1_P0P1_DN<10>")
	)
	(segment
		(start 312.571384 -179.966366)
		(end 301.878746 -179.76977)
		(width 0.14732)
		(layer "In6.Cu")
		(net "UPI_CPU0_CPU1_P0P1_DN<10>")
	)
	(segment
		(start 141.592554 -189.721744)
		(end 139.437872 -192.614042)
		(width 0.14732)
		(layer "In6.Cu")
		(net "UPI_CPU0_CPU1_P0P1_DN<10>")
	)
	(segment
		(start 346.518484 -211.726018)
		(end 346.560394 -211.684108)
		(width 0.0889)
		(layer "In6.Cu")
		(net "UPI_CPU0_CPU1_P0P1_DN<10>")
	)
	(segment
		(start 323.238114 -186.32551)
		(end 321.899026 -184.469786)
		(width 0.14732)
		(layer "In6.Cu")
		(net "UPI_CPU0_CPU1_P0P1_DN<10>")
	)
	(segment
		(start 333.578454 -192.44945)
		(end 327.466198 -190.27775)
		(width 0.14732)
		(layer "In6.Cu")
		(net "UPI_CPU0_CPU1_P0P1_DN<10>")
	)
	(segment
		(start 273.186398 -180.46573)
		(end 238.624872 -180.630576)
		(width 0.14732)
		(layer "In6.Cu")
		(net "UPI_CPU0_CPU1_P0P1_DN<10>")
	)
	(segment
		(start 327.466198 -190.27775)
		(end 327.224644 -190.128906)
		(width 0.14732)
		(layer "In6.Cu")
		(net "UPI_CPU0_CPU1_P0P1_DN<10>")
	)
	(segment
		(start 346.422726 -214.622634)
		(end 346.263976 -214.321644)
		(width 0.0889)
		(layer "In6.Cu")
		(net "UPI_CPU0_CPU1_P0P1_DN<10>")
	)
	(segment
		(start 200.738486 -180.13934)
		(end 158.691834 -180.837332)
		(width 0.14732)
		(layer "In6.Cu")
		(net "UPI_CPU0_CPU1_P0P1_DN<10>")
	)
	(segment
		(start 301.878746 -179.76977)
		(end 273.186398 -180.46573)
		(width 0.14732)
		(layer "In6.Cu")
		(net "UPI_CPU0_CPU1_P0P1_DN<10>")
	)
	(segment
		(start 238.624872 -180.630576)
		(end 211.919312 -180.630576)
		(width 0.14732)
		(layer "In6.Cu")
		(net "UPI_CPU0_CPU1_P0P1_DN<10>")
	)
	(segment
		(start 346.263976 -214.321644)
		(end 346.294202 -214.22487)
		(width 0.0889)
		(layer "In6.Cu")
		(net "UPI_CPU0_CPU1_P0P1_DN<10>")
	)
	(segment
		(start 321.567556 -184.262014)
		(end 316.476634 -181.073806)
		(width 0.14732)
		(layer "In6.Cu")
		(net "UPI_CPU0_CPU1_P0P1_DN<10>")
	)
	(segment
		(start 132.900674 -196.960236)
		(end 128.578356 -202.275694)
		(width 0.14732)
		(layer "In6.Cu")
		(net "UPI_CPU0_CPU1_P0P1_DN<10>")
	)
	(segment
		(start 321.56781 -184.262522)
		(end 321.567556 -184.262014)
		(width 0.14732)
		(layer "In6.Cu")
		(net "UPI_CPU0_CPU1_P0P1_DN<10>")
	)
	(segment
		(start 346.518484 -213.929468)
		(end 346.518484 -211.726018)
		(width 0.0889)
		(layer "In6.Cu")
		(net "UPI_CPU0_CPU1_P0P1_DN<10>")
	)
	(segment
		(start 125.399546 -215.076532)
		(end 125.423676 -215.165686)
		(width 0.0889)
		(layer "In6.Cu")
		(net "UPI_CPU0_CPU1_P0P1_DN<10>")
	)
	(segment
		(start 143.814038 -186.740038)
		(end 141.5923 -189.721744)
		(width 0.14732)
		(layer "In6.Cu")
		(net "UPI_CPU0_CPU1_P0P1_DN<10>")
	)
	(segment
		(start 327.224644 -190.128906)
		(end 323.238114 -186.32551)
		(width 0.14732)
		(layer "In6.Cu")
		(net "UPI_CPU0_CPU1_P0P1_DN<10>")
	)
	(segment
		(start 316.476634 -181.073806)
		(end 312.571384 -179.966366)
		(width 0.14732)
		(layer "In6.Cu")
		(net "UPI_CPU0_CPU1_P0P1_DN<10>")
	)
	(segment
		(start 346.560394 -211.66201)
		(end 346.560394 -210.874864)
		(width 0.14732)
		(layer "In6.Cu")
		(net "UPI_CPU0_CPU1_P0P1_DN<10>")
	)
	(segment
		(start 125.171708 -214.425784)
		(end 125.171708 -214.636858)
		(width 0.0889)
		(layer "In6.Cu")
		(net "UPI_CPU0_CPU1_P0P1_DN<10>")
	)
	(segment
		(start 151.99614 -182.551324)
		(end 143.814038 -186.740038)
		(width 0.14732)
		(layer "In6.Cu")
		(net "UPI_CPU0_CPU1_P0P1_DN<10>")
	)
	(segment
		(start 346.560394 -211.684108)
		(end 346.560394 -211.66201)
		(width 0.0889)
		(layer "In6.Cu")
		(net "UPI_CPU0_CPU1_P0P1_DN<10>")
	)
	(segment
		(start 125.599952 -210.782154)
		(end 125.599952 -211.60359)
		(width 0.14732)
		(layer "In6.Cu")
		(net "UPI_CPU0_CPU1_P0P1_DN<10>")
	)
	(segment
		(start 125.599952 -211.625688)
		(end 125.641862 -211.667598)
		(width 0.0889)
		(layer "In6.Cu")
		(net "UPI_CPU0_CPU1_P0P1_DN<10>")
	)
	(segment
		(start 346.560394 -210.874864)
		(end 346.56014 -210.875118)
		(width 0.14732)
		(layer "In6.Cu")
		(net "UPI_CPU0_CPU1_P0P1_DN<10>")
	)
	(segment
		(start 345.690698 -202.352148)
		(end 344.849704 -201.31659)
		(width 0.14732)
		(layer "In6.Cu")
		(net "UPI_CPU0_CPU1_P0P1_DN<10>")
	)
	(segment
		(start 125.599952 -211.60359)
		(end 125.599952 -211.625688)
		(width 0.0889)
		(layer "In6.Cu")
		(net "UPI_CPU0_CPU1_P0P1_DN<10>")
	)
	(segment
		(start 211.919312 -180.630576)
		(end 200.738486 -180.13934)
		(width 0.14732)
		(layer "In6.Cu")
		(net "UPI_CPU0_CPU1_P0P1_DN<10>")
	)
	(segment
		(start 125.641862 -211.667598)
		(end 125.641862 -213.894162)
		(width 0.0889)
		(layer "In6.Cu")
		(net "UPI_CPU0_CPU1_P0P1_DN<10>")
	)
	(segment
		(start 141.5923 -189.721744)
		(end 141.592554 -189.721744)
		(width 0.14732)
		(layer "In6.Cu")
		(net "UPI_CPU0_CPU1_P0P1_DN<10>")
	)
	(segment
		(start 125.423676 -215.165686)
		(end 125.267212 -215.436704)
		(width 0.0889)
		(layer "In6.Cu")
		(net "UPI_CPU0_CPU1_P0P1_DN<10>")
	)
	(segment
		(start 321.899026 -184.469786)
		(end 321.56781 -184.262522)
		(width 0.14732)
		(layer "In6.Cu")
		(net "UPI_CPU0_CPU1_P0P1_DN<10>")
	)
	(segment
		(start 346.56014 -210.57489)
		(end 345.690698 -202.352148)
		(width 0.14732)
		(layer "In6.Cu")
		(net "UPI_CPU0_CPU1_P0P1_DN<10>")
	)
	(segment
		(start 344.849704 -201.31659)
		(end 333.578454 -192.44945)
		(width 0.14732)
		(layer "In6.Cu")
		(net "UPI_CPU0_CPU1_P0P1_DN<10>")
	)
	(segment
		(start 346.56014 -210.875118)
		(end 346.56014 -210.57489)
		(width 0.14732)
		(layer "In6.Cu")
		(net "UPI_CPU0_CPU1_P0P1_DN<10>")
	)
	(segment
		(start 139.437872 -192.614042)
		(end 132.900674 -196.960236)
		(width 0.14732)
		(layer "In6.Cu")
		(net "UPI_CPU0_CPU1_P0P1_DN<10>")
	)
	(segment
		(start 158.691834 -180.837332)
		(end 151.99614 -182.551324)
		(width 0.14732)
		(layer "In6.Cu")
		(net "UPI_CPU0_CPU1_P0P1_DN<10>")
	)
	(arc
		(start 346.294202 -214.22487)
		(mid 346.416948 -214.111365)
		(end 346.503498 -213.96833)
		(width 0.0889)
		(layer "In6.Cu")
		(net "UPI_CPU0_CPU1_P0P1_DN<10>")
	)
	(arc
		(start 346.503498 -213.96833)
		(mid 346.511333 -213.949031)
		(end 346.518484 -213.929468)
		(width 0.0889)
		(layer "In6.Cu")
		(net "UPI_CPU0_CPU1_P0P1_DN<10>")
	)
	(arc
		(start 125.382528 -215.063324)
		(mid 125.390974 -215.070009)
		(end 125.399546 -215.076532)
		(width 0.0889)
		(layer "In6.Cu")
		(net "UPI_CPU0_CPU1_P0P1_DN<10>")
	)
	(arc
		(start 125.457712 -214.093298)
		(mid 125.283164 -214.232402)
		(end 125.171708 -214.425784)
		(width 0.0889)
		(layer "In6.Cu")
		(net "UPI_CPU0_CPU1_P0P1_DN<10>")
	)
	(arc
		(start 125.641862 -213.894162)
		(mid 125.566824 -214.009482)
		(end 125.457712 -214.093298)
		(width 0.0889)
		(layer "In6.Cu")
		(net "UPI_CPU0_CPU1_P0P1_DN<10>")
	)
	(arc
		(start 125.171708 -214.636858)
		(mid 125.230053 -214.873363)
		(end 125.382528 -215.063324)
		(width 0.0889)
		(layer "In6.Cu")
		(net "UPI_CPU0_CPU1_P0P1_DN<10>")
	)
	(segment
		(start 135.135112 -215.158574)
		(end 135.135112 -214.546434)
		(width 0.13208)
		(layer "F.Cu")
		(net "UPI_CPU0_CPU1_P0P1_DN<0>")
	)
	(segment
		(start 337.02498 -216.250774)
		(end 337.024726 -216.25052)
		(width 0.13208)
		(layer "F.Cu")
		(net "UPI_CPU0_CPU1_P0P1_DN<0>")
	)
	(segment
		(start 337.02498 -216.78646)
		(end 337.02498 -216.250774)
		(width 0.13208)
		(layer "F.Cu")
		(net "UPI_CPU0_CPU1_P0P1_DN<0>")
	)
	(segment
		(start 208.447894 -191.154812)
		(end 190.281052 -191.889888)
		(width 0.14732)
		(layer "In6.Cu")
		(net "UPI_CPU0_CPU1_P0P1_DN<0>")
	)
	(segment
		(start 331.275944 -208.316068)
		(end 331.72273 -207.746092)
		(width 0.14732)
		(layer "In6.Cu")
		(net "UPI_CPU0_CPU1_P0P1_DN<0>")
	)
	(segment
		(start 336.868262 -215.979502)
		(end 336.892392 -215.890348)
		(width 0.0889)
		(layer "In6.Cu")
		(net "UPI_CPU0_CPU1_P0P1_DN<0>")
	)
	(segment
		(start 145.492978 -203.523088)
		(end 145.057876 -203.524866)
		(width 0.14732)
		(layer "In6.Cu")
		(net "UPI_CPU0_CPU1_P0P1_DN<0>")
	)
	(segment
		(start 239.312958 -200.292462)
		(end 237.398052 -200.531476)
		(width 0.14732)
		(layer "In6.Cu")
		(net "UPI_CPU0_CPU1_P0P1_DN<0>")
	)
	(segment
		(start 136.285224 -213.346792)
		(end 136.26973 -213.362286)
		(width 0.0889)
		(layer "In6.Cu")
		(net "UPI_CPU0_CPU1_P0P1_DN<0>")
	)
	(segment
		(start 331.300836 -208.522062)
		(end 331.275944 -208.316068)
		(width 0.14732)
		(layer "In6.Cu")
		(net "UPI_CPU0_CPU1_P0P1_DN<0>")
	)
	(segment
		(start 144.318482 -205.622398)
		(end 143.861028 -205.168754)
		(width 0.14732)
		(layer "In6.Cu")
		(net "UPI_CPU0_CPU1_P0P1_DN<0>")
	)
	(segment
		(start 312.524394 -191.65443)
		(end 308.601364 -190.746126)
		(width 0.14732)
		(layer "In6.Cu")
		(net "UPI_CPU0_CPU1_P0P1_DN<0>")
	)
	(segment
		(start 154.423364 -195.64096)
		(end 152.686258 -197.393306)
		(width 0.14732)
		(layer "In6.Cu")
		(net "UPI_CPU0_CPU1_P0P1_DN<0>")
	)
	(segment
		(start 141.67485 -207.920082)
		(end 136.285224 -213.346792)
		(width 0.14732)
		(layer "In6.Cu")
		(net "UPI_CPU0_CPU1_P0P1_DN<0>")
	)
	(segment
		(start 337.058254 -211.53755)
		(end 337.058254 -211.262722)
		(width 0.14732)
		(layer "In6.Cu")
		(net "UPI_CPU0_CPU1_P0P1_DN<0>")
	)
	(segment
		(start 142.654782 -207.508856)
		(end 141.67485 -207.920082)
		(width 0.14732)
		(layer "In6.Cu")
		(net "UPI_CPU0_CPU1_P0P1_DN<0>")
	)
	(segment
		(start 336.488024 -210.692492)
		(end 335.411572 -210.246468)
		(width 0.14732)
		(layer "In6.Cu")
		(net "UPI_CPU0_CPU1_P0P1_DN<0>")
	)
	(segment
		(start 151.469598 -198.619872)
		(end 151.054308 -199.038972)
		(width 0.14732)
		(layer "In6.Cu")
		(net "UPI_CPU0_CPU1_P0P1_DN<0>")
	)
	(segment
		(start 329.846178 -205.884018)
		(end 326.787256 -203.486512)
		(width 0.14732)
		(layer "In6.Cu")
		(net "UPI_CPU0_CPU1_P0P1_DN<0>")
	)
	(segment
		(start 152.020778 -196.940424)
		(end 151.585676 -196.942202)
		(width 0.14732)
		(layer "In6.Cu")
		(net "UPI_CPU0_CPU1_P0P1_DN<0>")
	)
	(segment
		(start 337.12023 -215.436704)
		(end 337.12023 -215.42248)
		(width 0.0889)
		(layer "In6.Cu")
		(net "UPI_CPU0_CPU1_P0P1_DN<0>")
	)
	(segment
		(start 337.058254 -211.262722)
		(end 336.488024 -210.692492)
		(width 0.14732)
		(layer "In6.Cu")
		(net "UPI_CPU0_CPU1_P0P1_DN<0>")
	)
	(segment
		(start 146.158458 -203.97597)
		(end 145.950432 -203.976732)
		(width 0.14732)
		(layer "In6.Cu")
		(net "UPI_CPU0_CPU1_P0P1_DN<0>")
	)
	(segment
		(start 190.281052 -191.889888)
		(end 159.967422 -191.483996)
		(width 0.14732)
		(layer "In6.Cu")
		(net "UPI_CPU0_CPU1_P0P1_DN<0>")
	)
	(segment
		(start 326.787256 -203.486512)
		(end 314.749942 -194.051682)
		(width 0.14732)
		(layer "In6.Cu")
		(net "UPI_CPU0_CPU1_P0P1_DN<0>")
	)
	(segment
		(start 335.411572 -210.246468)
		(end 334.674972 -209.669126)
		(width 0.14732)
		(layer "In6.Cu")
		(net "UPI_CPU0_CPU1_P0P1_DN<0>")
	)
	(segment
		(start 314.749942 -194.051682)
		(end 312.759344 -191.792352)
		(width 0.14732)
		(layer "In6.Cu")
		(net "UPI_CPU0_CPU1_P0P1_DN<0>")
	)
	(segment
		(start 332.41869 -208.291938)
		(end 331.972158 -208.86166)
		(width 0.14732)
		(layer "In6.Cu")
		(net "UPI_CPU0_CPU1_P0P1_DN<0>")
	)
	(segment
		(start 331.72273 -207.746092)
		(end 331.670152 -207.313784)
		(width 0.14732)
		(layer "In6.Cu")
		(net "UPI_CPU0_CPU1_P0P1_DN<0>")
	)
	(segment
		(start 143.425926 -205.170532)
		(end 142.849854 -205.75143)
		(width 0.14732)
		(layer "In6.Cu")
		(net "UPI_CPU0_CPU1_P0P1_DN<0>")
	)
	(segment
		(start 147.747482 -201.249534)
		(end 148.204936 -201.703178)
		(width 0.14732)
		(layer "In6.Cu")
		(net "UPI_CPU0_CPU1_P0P1_DN<0>")
	)
	(segment
		(start 151.468836 -198.411846)
		(end 151.469598 -198.619872)
		(width 0.14732)
		(layer "In6.Cu")
		(net "UPI_CPU0_CPU1_P0P1_DN<0>")
	)
	(segment
		(start 142.851632 -206.186532)
		(end 143.309086 -206.640176)
		(width 0.14732)
		(layer "In6.Cu")
		(net "UPI_CPU0_CPU1_P0P1_DN<0>")
	)
	(segment
		(start 144.483582 -204.540866)
		(end 144.941036 -204.99451)
		(width 0.14732)
		(layer "In6.Cu")
		(net "UPI_CPU0_CPU1_P0P1_DN<0>")
	)
	(segment
		(start 306.883308 -190.69177)
		(end 305.175158 -190.63843)
		(width 0.14732)
		(layer "In6.Cu")
		(net "UPI_CPU0_CPU1_P0P1_DN<0>")
	)
	(segment
		(start 144.526508 -205.621636)
		(end 144.318482 -205.622398)
		(width 0.14732)
		(layer "In6.Cu")
		(net "UPI_CPU0_CPU1_P0P1_DN<0>")
	)
	(segment
		(start 334.674972 -209.669126)
		(end 334.242664 -209.721704)
		(width 0.14732)
		(layer "In6.Cu")
		(net "UPI_CPU0_CPU1_P0P1_DN<0>")
	)
	(segment
		(start 157.775148 -192.278)
		(end 156.553154 -192.898776)
		(width 0.14732)
		(layer "In6.Cu")
		(net "UPI_CPU0_CPU1_P0P1_DN<0>")
	)
	(segment
		(start 142.849854 -205.75143)
		(end 142.851632 -206.186532)
		(width 0.14732)
		(layer "In6.Cu")
		(net "UPI_CPU0_CPU1_P0P1_DN<0>")
	)
	(segment
		(start 135.291576 -214.817452)
		(end 135.135112 -214.546434)
		(width 0.0889)
		(layer "In6.Cu")
		(net "UPI_CPU0_CPU1_P0P1_DN<0>")
	)
	(segment
		(start 149.953726 -198.587868)
		(end 149.377654 -199.168766)
		(width 0.14732)
		(layer "In6.Cu")
		(net "UPI_CPU0_CPU1_P0P1_DN<0>")
	)
	(segment
		(start 147.124928 -201.877422)
		(end 146.689826 -201.8792)
		(width 0.14732)
		(layer "In6.Cu")
		(net "UPI_CPU0_CPU1_P0P1_DN<0>")
	)
	(segment
		(start 146.113754 -202.460098)
		(end 146.115532 -202.8952)
		(width 0.14732)
		(layer "In6.Cu")
		(net "UPI_CPU0_CPU1_P0P1_DN<0>")
	)
	(segment
		(start 146.689826 -201.8792)
		(end 146.113754 -202.460098)
		(width 0.14732)
		(layer "In6.Cu")
		(net "UPI_CPU0_CPU1_P0P1_DN<0>")
	)
	(segment
		(start 331.027024 -206.809594)
		(end 330.594716 -206.862172)
		(width 0.14732)
		(layer "In6.Cu")
		(net "UPI_CPU0_CPU1_P0P1_DN<0>")
	)
	(segment
		(start 286.505396 -191.284352)
		(end 286.4993 -191.284352)
		(width 0.14732)
		(layer "In6.Cu")
		(net "UPI_CPU0_CPU1_P0P1_DN<0>")
	)
	(segment
		(start 329.45197 -206.886302)
		(end 329.898756 -206.316326)
		(width 0.14732)
		(layer "In6.Cu")
		(net "UPI_CPU0_CPU1_P0P1_DN<0>")
	)
	(segment
		(start 143.309848 -206.848202)
		(end 142.654782 -207.508856)
		(width 0.14732)
		(layer "In6.Cu")
		(net "UPI_CPU0_CPU1_P0P1_DN<0>")
	)
	(segment
		(start 156.553154 -192.898776)
		(end 154.836876 -194.630294)
		(width 0.14732)
		(layer "In6.Cu")
		(net "UPI_CPU0_CPU1_P0P1_DN<0>")
	)
	(segment
		(start 298.001944 -191.333882)
		(end 286.505396 -191.284352)
		(width 0.14732)
		(layer "In6.Cu")
		(net "UPI_CPU0_CPU1_P0P1_DN<0>")
	)
	(segment
		(start 333.796132 -210.291426)
		(end 333.589884 -210.316318)
		(width 0.14732)
		(layer "In6.Cu")
		(net "UPI_CPU0_CPU1_P0P1_DN<0>")
	)
	(segment
		(start 147.790408 -202.330304)
		(end 147.582382 -202.331066)
		(width 0.14732)
		(layer "In6.Cu")
		(net "UPI_CPU0_CPU1_P0P1_DN<0>")
	)
	(segment
		(start 220.074744 -193.032126)
		(end 208.447894 -191.154812)
		(width 0.14732)
		(layer "In6.Cu")
		(net "UPI_CPU0_CPU1_P0P1_DN<0>")
	)
	(segment
		(start 331.670152 -207.313784)
		(end 331.027024 -206.809594)
		(width 0.14732)
		(layer "In6.Cu")
		(net "UPI_CPU0_CPU1_P0P1_DN<0>")
	)
	(segment
		(start 146.572986 -203.348844)
		(end 146.573748 -203.55687)
		(width 0.14732)
		(layer "In6.Cu")
		(net "UPI_CPU0_CPU1_P0P1_DN<0>")
	)
	(segment
		(start 334.242664 -209.721704)
		(end 333.796132 -210.291426)
		(width 0.14732)
		(layer "In6.Cu")
		(net "UPI_CPU0_CPU1_P0P1_DN<0>")
	)
	(segment
		(start 337.016344 -213.609682)
		(end 337.016344 -211.726272)
		(width 0.0889)
		(layer "In6.Cu")
		(net "UPI_CPU0_CPU1_P0P1_DN<0>")
	)
	(segment
		(start 332.850998 -208.23936)
		(end 332.41869 -208.291938)
		(width 0.14732)
		(layer "In6.Cu")
		(net "UPI_CPU0_CPU1_P0P1_DN<0>")
	)
	(segment
		(start 312.759344 -191.792352)
		(end 312.524394 -191.65443)
		(width 0.14732)
		(layer "In6.Cu")
		(net "UPI_CPU0_CPU1_P0P1_DN<0>")
	)
	(segment
		(start 148.756878 -200.231756)
		(end 148.321776 -200.233534)
		(width 0.14732)
		(layer "In6.Cu")
		(net "UPI_CPU0_CPU1_P0P1_DN<0>")
	)
	(segment
		(start 301.944786 -190.951866)
		(end 301.784004 -190.819278)
		(width 0.14732)
		(layer "In6.Cu")
		(net "UPI_CPU0_CPU1_P0P1_DN<0>")
	)
	(segment
		(start 235.95711 -200.531476)
		(end 232.663238 -199.71131)
		(width 0.14732)
		(layer "In6.Cu")
		(net "UPI_CPU0_CPU1_P0P1_DN<0>")
	)
	(segment
		(start 159.967422 -191.483996)
		(end 157.775148 -192.278)
		(width 0.14732)
		(layer "In6.Cu")
		(net "UPI_CPU0_CPU1_P0P1_DN<0>")
	)
	(segment
		(start 136.26973 -213.42223)
		(end 135.509762 -214.182198)
		(width 0.0889)
		(layer "In6.Cu")
		(net "UPI_CPU0_CPU1_P0P1_DN<0>")
	)
	(segment
		(start 151.009604 -197.5231)
		(end 151.011382 -197.958202)
		(width 0.14732)
		(layer "In6.Cu")
		(net "UPI_CPU0_CPU1_P0P1_DN<0>")
	)
	(segment
		(start 336.65033 -214.63127)
		(end 336.65033 -213.975696)
		(width 0.0889)
		(layer "In6.Cu")
		(net "UPI_CPU0_CPU1_P0P1_DN<0>")
	)
	(segment
		(start 150.846282 -199.039734)
		(end 150.388828 -198.58609)
		(width 0.14732)
		(layer "In6.Cu")
		(net "UPI_CPU0_CPU1_P0P1_DN<0>")
	)
	(segment
		(start 148.204936 -201.703178)
		(end 148.205698 -201.911204)
		(width 0.14732)
		(layer "In6.Cu")
		(net "UPI_CPU0_CPU1_P0P1_DN<0>")
	)
	(segment
		(start 147.582382 -202.331066)
		(end 147.124928 -201.877422)
		(width 0.14732)
		(layer "In6.Cu")
		(net "UPI_CPU0_CPU1_P0P1_DN<0>")
	)
	(segment
		(start 136.26973 -213.362286)
		(end 136.26973 -213.42223)
		(width 0.0889)
		(layer "In6.Cu")
		(net "UPI_CPU0_CPU1_P0P1_DN<0>")
	)
	(segment
		(start 336.65033 -213.975696)
		(end 337.016344 -213.609682)
		(width 0.0889)
		(layer "In6.Cu")
		(net "UPI_CPU0_CPU1_P0P1_DN<0>")
	)
	(segment
		(start 149.837648 -200.265538)
		(end 149.422358 -200.684638)
		(width 0.14732)
		(layer "In6.Cu")
		(net "UPI_CPU0_CPU1_P0P1_DN<0>")
	)
	(segment
		(start 232.663238 -199.71131)
		(end 220.074744 -193.032126)
		(width 0.14732)
		(layer "In6.Cu")
		(net "UPI_CPU0_CPU1_P0P1_DN<0>")
	)
	(segment
		(start 337.058508 -211.684108)
		(end 337.058508 -211.66201)
		(width 0.0889)
		(layer "In6.Cu")
		(net "UPI_CPU0_CPU1_P0P1_DN<0>")
	)
	(segment
		(start 300.56455 -189.904878)
		(end 300.287944 -190.24092)
		(width 0.14732)
		(layer "In6.Cu")
		(net "UPI_CPU0_CPU1_P0P1_DN<0>")
	)
	(segment
		(start 333.546704 -209.175858)
		(end 333.494126 -208.74355)
		(width 0.14732)
		(layer "In6.Cu")
		(net "UPI_CPU0_CPU1_P0P1_DN<0>")
	)
	(segment
		(start 333.099918 -209.745834)
		(end 333.546704 -209.175858)
		(width 0.14732)
		(layer "In6.Cu")
		(net "UPI_CPU0_CPU1_P0P1_DN<0>")
	)
	(segment
		(start 154.836876 -194.630294)
		(end 154.423364 -195.64096)
		(width 0.14732)
		(layer "In6.Cu")
		(net "UPI_CPU0_CPU1_P0P1_DN<0>")
	)
	(segment
		(start 144.481804 -204.105764)
		(end 144.483582 -204.540866)
		(width 0.14732)
		(layer "In6.Cu")
		(net "UPI_CPU0_CPU1_P0P1_DN<0>")
	)
	(segment
		(start 333.12481 -209.951828)
		(end 333.099918 -209.745834)
		(width 0.14732)
		(layer "In6.Cu")
		(net "UPI_CPU0_CPU1_P0P1_DN<0>")
	)
	(segment
		(start 330.148184 -207.431894)
		(end 329.941936 -207.456786)
		(width 0.14732)
		(layer "In6.Cu")
		(net "UPI_CPU0_CPU1_P0P1_DN<0>")
	)
	(segment
		(start 329.898756 -206.316326)
		(end 329.846178 -205.884018)
		(width 0.14732)
		(layer "In6.Cu")
		(net "UPI_CPU0_CPU1_P0P1_DN<0>")
	)
	(segment
		(start 143.309086 -206.640176)
		(end 143.309848 -206.848202)
		(width 0.14732)
		(layer "In6.Cu")
		(net "UPI_CPU0_CPU1_P0P1_DN<0>")
	)
	(segment
		(start 149.422358 -200.684638)
		(end 149.214332 -200.6854)
		(width 0.14732)
		(layer "In6.Cu")
		(net "UPI_CPU0_CPU1_P0P1_DN<0>")
	)
	(segment
		(start 301.37862 -189.825884)
		(end 300.56455 -189.904878)
		(width 0.14732)
		(layer "In6.Cu")
		(net "UPI_CPU0_CPU1_P0P1_DN<0>")
	)
	(segment
		(start 143.861028 -205.168754)
		(end 143.425926 -205.170532)
		(width 0.14732)
		(layer "In6.Cu")
		(net "UPI_CPU0_CPU1_P0P1_DN<0>")
	)
	(segment
		(start 237.398052 -200.531476)
		(end 235.95711 -200.531476)
		(width 0.14732)
		(layer "In6.Cu")
		(net "UPI_CPU0_CPU1_P0P1_DN<0>")
	)
	(segment
		(start 149.214332 -200.6854)
		(end 148.756878 -200.231756)
		(width 0.14732)
		(layer "In6.Cu")
		(net "UPI_CPU0_CPU1_P0P1_DN<0>")
	)
	(segment
		(start 150.388828 -198.58609)
		(end 149.953726 -198.587868)
		(width 0.14732)
		(layer "In6.Cu")
		(net "UPI_CPU0_CPU1_P0P1_DN<0>")
	)
	(segment
		(start 308.601364 -190.746126)
		(end 306.883562 -190.692024)
		(width 0.14732)
		(layer "In6.Cu")
		(net "UPI_CPU0_CPU1_P0P1_DN<0>")
	)
	(segment
		(start 333.494126 -208.74355)
		(end 332.850998 -208.23936)
		(width 0.14732)
		(layer "In6.Cu")
		(net "UPI_CPU0_CPU1_P0P1_DN<0>")
	)
	(segment
		(start 301.784004 -190.819278)
		(end 301.714408 -190.10249)
		(width 0.14732)
		(layer "In6.Cu")
		(net "UPI_CPU0_CPU1_P0P1_DN<0>")
	)
	(segment
		(start 300.287944 -190.24092)
		(end 300.35754 -190.957708)
		(width 0.14732)
		(layer "In6.Cu")
		(net "UPI_CPU0_CPU1_P0P1_DN<0>")
	)
	(segment
		(start 146.115532 -202.8952)
		(end 146.572986 -203.348844)
		(width 0.14732)
		(layer "In6.Cu")
		(net "UPI_CPU0_CPU1_P0P1_DN<0>")
	)
	(segment
		(start 306.883562 -190.692024)
		(end 306.883308 -190.69177)
		(width 0.14732)
		(layer "In6.Cu")
		(net "UPI_CPU0_CPU1_P0P1_DN<0>")
	)
	(segment
		(start 300.224952 -191.118236)
		(end 298.001944 -191.333882)
		(width 0.14732)
		(layer "In6.Cu")
		(net "UPI_CPU0_CPU1_P0P1_DN<0>")
	)
	(segment
		(start 149.379432 -199.603868)
		(end 149.836886 -200.057512)
		(width 0.14732)
		(layer "In6.Cu")
		(net "UPI_CPU0_CPU1_P0P1_DN<0>")
	)
	(segment
		(start 337.058508 -211.537296)
		(end 337.058254 -211.53755)
		(width 0.14732)
		(layer "In6.Cu")
		(net "UPI_CPU0_CPU1_P0P1_DN<0>")
	)
	(segment
		(start 151.011382 -197.958202)
		(end 151.468836 -198.411846)
		(width 0.14732)
		(layer "In6.Cu")
		(net "UPI_CPU0_CPU1_P0P1_DN<0>")
	)
	(segment
		(start 152.478232 -197.394068)
		(end 152.020778 -196.940424)
		(width 0.14732)
		(layer "In6.Cu")
		(net "UPI_CPU0_CPU1_P0P1_DN<0>")
	)
	(segment
		(start 152.686258 -197.393306)
		(end 152.478232 -197.394068)
		(width 0.14732)
		(layer "In6.Cu")
		(net "UPI_CPU0_CPU1_P0P1_DN<0>")
	)
	(segment
		(start 148.205698 -201.911204)
		(end 147.790408 -202.330304)
		(width 0.14732)
		(layer "In6.Cu")
		(net "UPI_CPU0_CPU1_P0P1_DN<0>")
	)
	(segment
		(start 144.941798 -205.202536)
		(end 144.526508 -205.621636)
		(width 0.14732)
		(layer "In6.Cu")
		(net "UPI_CPU0_CPU1_P0P1_DN<0>")
	)
	(segment
		(start 333.589884 -210.316318)
		(end 333.12481 -209.951828)
		(width 0.14732)
		(layer "In6.Cu")
		(net "UPI_CPU0_CPU1_P0P1_DN<0>")
	)
	(segment
		(start 135.369808 -214.83828)
		(end 135.291576 -214.817452)
		(width 0.0889)
		(layer "In6.Cu")
		(net "UPI_CPU0_CPU1_P0P1_DN<0>")
	)
	(segment
		(start 330.594716 -206.862172)
		(end 330.148184 -207.431894)
		(width 0.14732)
		(layer "In6.Cu")
		(net "UPI_CPU0_CPU1_P0P1_DN<0>")
	)
	(segment
		(start 301.714408 -190.10249)
		(end 301.37862 -189.825884)
		(width 0.14732)
		(layer "In6.Cu")
		(net "UPI_CPU0_CPU1_P0P1_DN<0>")
	)
	(segment
		(start 151.585676 -196.942202)
		(end 151.009604 -197.5231)
		(width 0.14732)
		(layer "In6.Cu")
		(net "UPI_CPU0_CPU1_P0P1_DN<0>")
	)
	(segment
		(start 145.057876 -203.524866)
		(end 144.481804 -204.105764)
		(width 0.14732)
		(layer "In6.Cu")
		(net "UPI_CPU0_CPU1_P0P1_DN<0>")
	)
	(segment
		(start 149.377654 -199.168766)
		(end 149.379432 -199.603868)
		(width 0.14732)
		(layer "In6.Cu")
		(net "UPI_CPU0_CPU1_P0P1_DN<0>")
	)
	(segment
		(start 135.509762 -214.182198)
		(end 135.509762 -214.546434)
		(width 0.0889)
		(layer "In6.Cu")
		(net "UPI_CPU0_CPU1_P0P1_DN<0>")
	)
	(segment
		(start 147.745704 -200.814432)
		(end 147.747482 -201.249534)
		(width 0.14732)
		(layer "In6.Cu")
		(net "UPI_CPU0_CPU1_P0P1_DN<0>")
	)
	(segment
		(start 145.950432 -203.976732)
		(end 145.492978 -203.523088)
		(width 0.14732)
		(layer "In6.Cu")
		(net "UPI_CPU0_CPU1_P0P1_DN<0>")
	)
	(segment
		(start 300.35754 -190.957708)
		(end 300.224952 -191.118236)
		(width 0.14732)
		(layer "In6.Cu")
		(net "UPI_CPU0_CPU1_P0P1_DN<0>")
	)
	(segment
		(start 261.206996 -192.292986)
		(end 250.623832 -195.116196)
		(width 0.14732)
		(layer "In6.Cu")
		(net "UPI_CPU0_CPU1_P0P1_DN<0>")
	)
	(segment
		(start 144.941036 -204.99451)
		(end 144.941798 -205.202536)
		(width 0.14732)
		(layer "In6.Cu")
		(net "UPI_CPU0_CPU1_P0P1_DN<0>")
	)
	(segment
		(start 146.573748 -203.55687)
		(end 146.158458 -203.97597)
		(width 0.14732)
		(layer "In6.Cu")
		(net "UPI_CPU0_CPU1_P0P1_DN<0>")
	)
	(segment
		(start 148.321776 -200.233534)
		(end 147.745704 -200.814432)
		(width 0.14732)
		(layer "In6.Cu")
		(net "UPI_CPU0_CPU1_P0P1_DN<0>")
	)
	(segment
		(start 305.175158 -190.63843)
		(end 301.944786 -190.951866)
		(width 0.14732)
		(layer "In6.Cu")
		(net "UPI_CPU0_CPU1_P0P1_DN<0>")
	)
	(segment
		(start 337.024726 -216.25052)
		(end 336.868262 -215.979502)
		(width 0.0889)
		(layer "In6.Cu")
		(net "UPI_CPU0_CPU1_P0P1_DN<0>")
	)
	(segment
		(start 149.836886 -200.057512)
		(end 149.837648 -200.265538)
		(width 0.14732)
		(layer "In6.Cu")
		(net "UPI_CPU0_CPU1_P0P1_DN<0>")
	)
	(segment
		(start 337.016344 -211.726272)
		(end 337.058508 -211.684108)
		(width 0.0889)
		(layer "In6.Cu")
		(net "UPI_CPU0_CPU1_P0P1_DN<0>")
	)
	(segment
		(start 337.058508 -211.66201)
		(end 337.058508 -211.537296)
		(width 0.14732)
		(layer "In6.Cu")
		(net "UPI_CPU0_CPU1_P0P1_DN<0>")
	)
	(segment
		(start 151.054308 -199.038972)
		(end 150.846282 -199.039734)
		(width 0.14732)
		(layer "In6.Cu")
		(net "UPI_CPU0_CPU1_P0P1_DN<0>")
	)
	(segment
		(start 329.941936 -207.456786)
		(end 329.476862 -207.092296)
		(width 0.14732)
		(layer "In6.Cu")
		(net "UPI_CPU0_CPU1_P0P1_DN<0>")
	)
	(segment
		(start 286.4993 -191.284352)
		(end 261.206996 -192.292986)
		(width 0.14732)
		(layer "In6.Cu")
		(net "UPI_CPU0_CPU1_P0P1_DN<0>")
	)
	(segment
		(start 331.76591 -208.886552)
		(end 331.300836 -208.522062)
		(width 0.14732)
		(layer "In6.Cu")
		(net "UPI_CPU0_CPU1_P0P1_DN<0>")
	)
	(segment
		(start 331.972158 -208.86166)
		(end 331.76591 -208.886552)
		(width 0.14732)
		(layer "In6.Cu")
		(net "UPI_CPU0_CPU1_P0P1_DN<0>")
	)
	(segment
		(start 250.623832 -195.116196)
		(end 239.312958 -200.292462)
		(width 0.14732)
		(layer "In6.Cu")
		(net "UPI_CPU0_CPU1_P0P1_DN<0>")
	)
	(segment
		(start 329.476862 -207.092296)
		(end 329.45197 -206.886302)
		(width 0.14732)
		(layer "In6.Cu")
		(net "UPI_CPU0_CPU1_P0P1_DN<0>")
	)
	(arc
		(start 135.509762 -214.546434)
		(mid 135.472902 -214.708231)
		(end 135.369808 -214.83828)
		(width 0.0889)
		(layer "In6.Cu")
		(net "UPI_CPU0_CPU1_P0P1_DN<0>")
	)
	(arc
		(start 337.12023 -215.42248)
		(mid 337.041011 -215.147795)
		(end 336.837528 -214.946992)
		(width 0.0889)
		(layer "In6.Cu")
		(net "UPI_CPU0_CPU1_P0P1_DN<0>")
	)
	(arc
		(start 336.90941 -215.87714)
		(mid 337.064808 -215.680859)
		(end 337.12023 -215.436704)
		(width 0.0889)
		(layer "In6.Cu")
		(net "UPI_CPU0_CPU1_P0P1_DN<0>")
	)
	(arc
		(start 336.837528 -214.946992)
		(mid 336.702595 -214.813638)
		(end 336.65033 -214.63127)
		(width 0.0889)
		(layer "In6.Cu")
		(net "UPI_CPU0_CPU1_P0P1_DN<0>")
	)
	(arc
		(start 336.892392 -215.890348)
		(mid 336.900964 -215.883826)
		(end 336.90941 -215.87714)
		(width 0.0889)
		(layer "In6.Cu")
		(net "UPI_CPU0_CPU1_P0P1_DN<0>")
	)
	(segment
		(start 186.861704 -16.550386)
		(end 186.861704 -17.133824)
		(width 0.13208)
		(layer "F.Cu")
		(net "USB2_7_R_DP")
	)
	(segment
		(start 186.861958 -16.550132)
		(end 186.861704 -16.550386)
		(width 0.13208)
		(layer "F.Cu")
		(net "USB2_7_R_DP")
	)
	(segment
		(start 186.861704 -17.133824)
		(end 186.69127 -17.304258)
		(width 0.13208)
		(layer "F.Cu")
		(net "USB2_7_R_DP")
	)
	(segment
		(start 186.69127 -17.304258)
		(end 186.69127 -17.842992)
		(width 0.13208)
		(layer "F.Cu")
		(net "USB2_7_R_DP")
	)
	(segment
		(start 186.69127 -17.842992)
		(end 186.993022 -18.144744)
		(width 0.13208)
		(layer "F.Cu")
		(net "USB2_7_R_DP")
	)
	(via
		(at 186.993022 -18.144744)
		(size 0.508)
		(drill 0.254)
		(layers "F.Cu" "B.Cu")
		(net "USB2_7_R_DP")
	)
	(segment
		(start 187.074556 -19.017742)
		(end 187.096654 -19.017742)
		(width 0.13208)
		(layer "B.Cu")
		(net "USB2_7_R_DP")
	)
	(segment
		(start 186.690762 -18.447004)
		(end 186.690762 -18.633948)
		(width 0.13208)
		(layer "B.Cu")
		(net "USB2_7_R_DP")
	)
	(segment
		(start 186.690762 -18.633948)
		(end 187.074556 -19.017742)
		(width 0.13208)
		(layer "B.Cu")
		(net "USB2_7_R_DP")
	)
	(segment
		(start 186.993022 -18.144744)
		(end 186.690762 -18.447004)
		(width 0.13208)
		(layer "B.Cu")
		(net "USB2_7_R_DP")
	)
	(segment
		(start 186.43219 -17.841976)
		(end 186.129422 -18.144744)
		(width 0.13208)
		(layer "F.Cu")
		(net "USB2_7_R_DN")
	)
	(segment
		(start 186.43219 -17.311878)
		(end 186.43219 -17.841976)
		(width 0.13208)
		(layer "F.Cu")
		(net "USB2_7_R_DN")
	)
	(segment
		(start 186.26201 -16.550132)
		(end 186.261756 -16.550386)
		(width 0.13208)
		(layer "F.Cu")
		(net "USB2_7_R_DN")
	)
	(segment
		(start 186.261756 -16.550386)
		(end 186.261756 -17.141444)
		(width 0.13208)
		(layer "F.Cu")
		(net "USB2_7_R_DN")
	)
	(segment
		(start 186.261756 -17.141444)
		(end 186.43219 -17.311878)
		(width 0.13208)
		(layer "F.Cu")
		(net "USB2_7_R_DN")
	)
	(via
		(at 186.129422 -18.144744)
		(size 0.508)
		(drill 0.254)
		(layers "F.Cu" "B.Cu")
		(net "USB2_7_R_DN")
	)
	(segment
		(start 186.129422 -18.144744)
		(end 186.431682 -18.447004)
		(width 0.13208)
		(layer "B.Cu")
		(net "USB2_7_R_DN")
	)
	(segment
		(start 186.431682 -18.641314)
		(end 186.055254 -19.017742)
		(width 0.13208)
		(layer "B.Cu")
		(net "USB2_7_R_DN")
	)
	(segment
		(start 186.431682 -18.447004)
		(end 186.431682 -18.641314)
		(width 0.13208)
		(layer "B.Cu")
		(net "USB2_7_R_DN")
	)
	(segment
		(start 347.039692 -47.227744)
		(end 346.919804 -47.124112)
		(width 0.0889)
		(layer "F.Cu")
		(net "TP_USB2_13_DP")
	)
	(segment
		(start 353.200462 -47.125636)
		(end 351.182686 -47.125636)
		(width 0.0889)
		(layer "F.Cu")
		(net "TP_USB2_13_DP")
	)
	(segment
		(start 351.182686 -47.125636)
		(end 348.361254 -47.123604)
		(width 0.0889)
		(layer "F.Cu")
		(net "TP_USB2_13_DP")
	)
	(segment
		(start 348.361254 -47.123604)
		(end 348.32925 -47.0916)
		(width 0.0889)
		(layer "F.Cu")
		(net "TP_USB2_13_DP")
	)
	(segment
		(start 353.57435 -46.751748)
		(end 353.200462 -47.125636)
		(width 0.0889)
		(layer "F.Cu")
		(net "TP_USB2_13_DP")
	)
	(segment
		(start 346.919804 -47.124112)
		(end 346.745306 -46.949614)
		(width 0.0889)
		(layer "F.Cu")
		(net "TP_USB2_13_DP")
	)
	(segment
		(start 347.856556 -47.15383)
		(end 347.563948 -47.15383)
		(width 0.0889)
		(layer "F.Cu")
		(net "TP_USB2_13_DP")
	)
	(segment
		(start 347.490034 -47.227744)
		(end 347.039692 -47.227744)
		(width 0.0889)
		(layer "F.Cu")
		(net "TP_USB2_13_DP")
	)
	(segment
		(start 347.918786 -47.0916)
		(end 347.856556 -47.15383)
		(width 0.0889)
		(layer "F.Cu")
		(net "TP_USB2_13_DP")
	)
	(segment
		(start 347.563948 -47.15383)
		(end 347.490034 -47.227744)
		(width 0.0889)
		(layer "F.Cu")
		(net "TP_USB2_13_DP")
	)
	(segment
		(start 348.32925 -47.0916)
		(end 347.918786 -47.0916)
		(width 0.0889)
		(layer "F.Cu")
		(net "TP_USB2_13_DP")
	)
	(segment
		(start 346.745306 -46.949614)
		(end 346.384626 -46.949614)
		(width 0.0889)
		(layer "F.Cu")
		(net "TP_USB2_13_DP")
	)
	(via
		(at 353.57435 -46.751748)
		(size 0.762)
		(drill 0.381)
		(layers "F.Cu" "B.Cu")
		(net "TP_USB2_13_DP")
	)
	(segment
		(start 354.747576 -46.351444)
		(end 354.168202 -46.351444)
		(width 0.0889)
		(layer "F.Cu")
		(net "TP_USB2_13_DN")
	)
	(segment
		(start 354.168202 -46.351444)
		(end 354.009706 -46.192948)
		(width 0.0889)
		(layer "F.Cu")
		(net "TP_USB2_13_DN")
	)
	(segment
		(start 351.453958 -46.903386)
		(end 348.50705 -46.901354)
		(width 0.0889)
		(layer "F.Cu")
		(net "TP_USB2_13_DN")
	)
	(segment
		(start 347.262958 -46.901354)
		(end 347.214698 -46.949614)
		(width 0.0889)
		(layer "F.Cu")
		(net "TP_USB2_13_DN")
	)
	(segment
		(start 354.009706 -46.192948)
		(end 353.252278 -46.192948)
		(width 0.0889)
		(layer "F.Cu")
		(net "TP_USB2_13_DN")
	)
	(segment
		(start 354.782374 -46.316646)
		(end 354.747576 -46.351444)
		(width 0.0889)
		(layer "F.Cu")
		(net "TP_USB2_13_DN")
	)
	(segment
		(start 352.54184 -46.903386)
		(end 351.453958 -46.903386)
		(width 0.0889)
		(layer "F.Cu")
		(net "TP_USB2_13_DN")
	)
	(segment
		(start 353.252278 -46.192948)
		(end 352.54184 -46.903386)
		(width 0.0889)
		(layer "F.Cu")
		(net "TP_USB2_13_DN")
	)
	(segment
		(start 348.50705 -46.901354)
		(end 347.262958 -46.901354)
		(width 0.0889)
		(layer "F.Cu")
		(net "TP_USB2_13_DN")
	)
	(via
		(at 354.782374 -46.316646)
		(size 0.762)
		(drill 0.381)
		(layers "F.Cu" "B.Cu")
		(net "TP_USB2_13_DN")
	)
	(segment
		(start 347.588078 -40.184832)
		(end 347.47454 -40.29837)
		(width 0.0889)
		(layer "F.Cu")
		(net "TP_USB2_12_DP")
	)
	(segment
		(start 350.52254 -33.282128)
		(end 350.52254 -35.05581)
		(width 0.12954)
		(layer "F.Cu")
		(net "TP_USB2_12_DP")
	)
	(segment
		(start 347.153992 -40.29837)
		(end 347.040454 -40.256968)
		(width 0.0889)
		(layer "F.Cu")
		(net "TP_USB2_12_DP")
	)
	(segment
		(start 348.994222 -36.584128)
		(end 348.994222 -39.428674)
		(width 0.12954)
		(layer "F.Cu")
		(net "TP_USB2_12_DP")
	)
	(segment
		(start 350.52254 -35.05581)
		(end 348.994222 -36.584128)
		(width 0.12954)
		(layer "F.Cu")
		(net "TP_USB2_12_DP")
	)
	(segment
		(start 354.2157 -26.421588)
		(end 352.65106 -27.986228)
		(width 0.12954)
		(layer "F.Cu")
		(net "TP_USB2_12_DP")
	)
	(segment
		(start 347.47454 -40.29837)
		(end 347.153992 -40.29837)
		(width 0.0889)
		(layer "F.Cu")
		(net "TP_USB2_12_DP")
	)
	(segment
		(start 346.353638 -40.446452)
		(end 345.96959 -40.446452)
		(width 0.0889)
		(layer "F.Cu")
		(net "TP_USB2_12_DP")
	)
	(segment
		(start 348.994222 -39.428674)
		(end 348.340172 -40.082724)
		(width 0.12954)
		(layer "F.Cu")
		(net "TP_USB2_12_DP")
	)
	(segment
		(start 348.238064 -40.184832)
		(end 347.588078 -40.184832)
		(width 0.0889)
		(layer "F.Cu")
		(net "TP_USB2_12_DP")
	)
	(segment
		(start 352.65106 -27.986228)
		(end 352.65106 -31.153608)
		(width 0.12954)
		(layer "F.Cu")
		(net "TP_USB2_12_DP")
	)
	(segment
		(start 346.655898 -40.144192)
		(end 346.353638 -40.446452)
		(width 0.0889)
		(layer "F.Cu")
		(net "TP_USB2_12_DP")
	)
	(segment
		(start 347.040454 -40.256968)
		(end 346.93733 -40.1701)
		(width 0.0889)
		(layer "F.Cu")
		(net "TP_USB2_12_DP")
	)
	(segment
		(start 346.911422 -40.144192)
		(end 346.655898 -40.144192)
		(width 0.0889)
		(layer "F.Cu")
		(net "TP_USB2_12_DP")
	)
	(segment
		(start 346.93733 -40.1701)
		(end 346.911422 -40.144192)
		(width 0.0889)
		(layer "F.Cu")
		(net "TP_USB2_12_DP")
	)
	(segment
		(start 352.65106 -31.153608)
		(end 350.52254 -33.282128)
		(width 0.12954)
		(layer "F.Cu")
		(net "TP_USB2_12_DP")
	)
	(segment
		(start 348.340172 -40.082724)
		(end 348.238064 -40.184832)
		(width 0.0889)
		(layer "F.Cu")
		(net "TP_USB2_12_DP")
	)
	(via
		(at 354.2157 -26.421588)
		(size 0.762)
		(drill 0.381)
		(layers "F.Cu" "B.Cu")
		(net "TP_USB2_12_DP")
	)
	(segment
		(start 349.288862 -39.49192)
		(end 349.288862 -36.688776)
		(width 0.12954)
		(layer "F.Cu")
		(net "TP_USB2_12_DN")
	)
	(segment
		(start 348.476062 -40.30472)
		(end 349.288862 -39.49192)
		(width 0.12954)
		(layer "F.Cu")
		(net "TP_USB2_12_DN")
	)
	(segment
		(start 346.799662 -40.446452)
		(end 346.997274 -40.446452)
		(width 0.0889)
		(layer "F.Cu")
		(net "TP_USB2_12_DN")
	)
	(segment
		(start 351.06864 -34.319972)
		(end 353.645724 -31.742888)
		(width 0.12954)
		(layer "F.Cu")
		(net "TP_USB2_12_DN")
	)
	(segment
		(start 349.288862 -36.688776)
		(end 351.06864 -34.908998)
		(width 0.12954)
		(layer "F.Cu")
		(net "TP_USB2_12_DN")
	)
	(segment
		(start 347.08719 -40.536368)
		(end 347.572076 -40.536368)
		(width 0.0889)
		(layer "F.Cu")
		(net "TP_USB2_12_DN")
	)
	(segment
		(start 347.626432 -40.482012)
		(end 348.29877 -40.482012)
		(width 0.0889)
		(layer "F.Cu")
		(net "TP_USB2_12_DN")
	)
	(segment
		(start 346.997274 -40.446452)
		(end 347.08719 -40.536368)
		(width 0.0889)
		(layer "F.Cu")
		(net "TP_USB2_12_DN")
	)
	(segment
		(start 357.666798 -31.742888)
		(end 358.61625 -30.793436)
		(width 0.12954)
		(layer "F.Cu")
		(net "TP_USB2_12_DN")
	)
	(segment
		(start 353.645724 -31.742888)
		(end 357.666798 -31.742888)
		(width 0.12954)
		(layer "F.Cu")
		(net "TP_USB2_12_DN")
	)
	(segment
		(start 347.572076 -40.536368)
		(end 347.626432 -40.482012)
		(width 0.0889)
		(layer "F.Cu")
		(net "TP_USB2_12_DN")
	)
	(segment
		(start 351.06864 -34.908998)
		(end 351.06864 -34.319972)
		(width 0.12954)
		(layer "F.Cu")
		(net "TP_USB2_12_DN")
	)
	(segment
		(start 348.29877 -40.482012)
		(end 348.476062 -40.30472)
		(width 0.0889)
		(layer "F.Cu")
		(net "TP_USB2_12_DN")
	)
	(via
		(at 358.61625 -30.793436)
		(size 0.762)
		(drill 0.381)
		(layers "F.Cu" "B.Cu")
		(net "TP_USB2_12_DN")
	)
	(segment
		(start 346.329254 -46.449234)
		(end 345.96959 -46.449234)
		(width 0.0889)
		(layer "F.Cu")
		(net "TP_USB2_11_DP")
	)
	(segment
		(start 347.041216 -46.65345)
		(end 346.94622 -46.748446)
		(width 0.0889)
		(layer "F.Cu")
		(net "TP_USB2_11_DP")
	)
	(segment
		(start 353.745038 -45.964348)
		(end 353.110292 -45.964348)
		(width 0.0889)
		(layer "F.Cu")
		(net "TP_USB2_11_DP")
	)
	(segment
		(start 346.648024 -46.748446)
		(end 346.503752 -46.623732)
		(width 0.0889)
		(layer "F.Cu")
		(net "TP_USB2_11_DP")
	)
	(segment
		(start 354.526342 -44.962064)
		(end 353.973892 -45.514514)
		(width 0.0889)
		(layer "F.Cu")
		(net "TP_USB2_11_DP")
	)
	(segment
		(start 347.351604 -46.65345)
		(end 347.041216 -46.65345)
		(width 0.0889)
		(layer "F.Cu")
		(net "TP_USB2_11_DP")
	)
	(segment
		(start 353.110292 -45.964348)
		(end 352.363278 -46.711362)
		(width 0.0889)
		(layer "F.Cu")
		(net "TP_USB2_11_DP")
	)
	(segment
		(start 346.503752 -46.623732)
		(end 346.329254 -46.449234)
		(width 0.0889)
		(layer "F.Cu")
		(net "TP_USB2_11_DP")
	)
	(segment
		(start 346.94622 -46.748446)
		(end 346.648024 -46.748446)
		(width 0.0889)
		(layer "F.Cu")
		(net "TP_USB2_11_DP")
	)
	(segment
		(start 353.973892 -45.514514)
		(end 353.973892 -45.735494)
		(width 0.0889)
		(layer "F.Cu")
		(net "TP_USB2_11_DP")
	)
	(segment
		(start 353.973892 -45.735494)
		(end 353.745038 -45.964348)
		(width 0.0889)
		(layer "F.Cu")
		(net "TP_USB2_11_DP")
	)
	(segment
		(start 347.409262 -46.711108)
		(end 347.351604 -46.65345)
		(width 0.0889)
		(layer "F.Cu")
		(net "TP_USB2_11_DP")
	)
	(segment
		(start 352.363278 -46.711362)
		(end 351.757488 -46.711362)
		(width 0.0889)
		(layer "F.Cu")
		(net "TP_USB2_11_DP")
	)
	(segment
		(start 351.757488 -46.711362)
		(end 351.64014 -46.711108)
		(width 0.0889)
		(layer "F.Cu")
		(net "TP_USB2_11_DP")
	)
	(segment
		(start 351.64014 -46.711108)
		(end 347.409262 -46.711108)
		(width 0.0889)
		(layer "F.Cu")
		(net "TP_USB2_11_DP")
	)
	(via
		(at 354.526342 -44.962064)
		(size 0.762)
		(drill 0.381)
		(layers "F.Cu" "B.Cu")
		(net "TP_USB2_11_DP")
	)
	(segment
		(start 347.55836 -46.520862)
		(end 347.400626 -46.455584)
		(width 0.0889)
		(layer "F.Cu")
		(net "TP_USB2_11_DN")
	)
	(segment
		(start 353.323652 -45.433234)
		(end 352.236024 -46.520862)
		(width 0.0889)
		(layer "F.Cu")
		(net "TP_USB2_11_DN")
	)
	(segment
		(start 347.400626 -46.455584)
		(end 346.806012 -46.455584)
		(width 0.0889)
		(layer "F.Cu")
		(net "TP_USB2_11_DN")
	)
	(segment
		(start 346.806012 -46.455584)
		(end 346.799662 -46.449234)
		(width 0.0889)
		(layer "F.Cu")
		(net "TP_USB2_11_DN")
	)
	(segment
		(start 352.236024 -46.520862)
		(end 347.55836 -46.520862)
		(width 0.0889)
		(layer "F.Cu")
		(net "TP_USB2_11_DN")
	)
	(via
		(at 353.323652 -45.433234)
		(size 0.762)
		(drill 0.381)
		(layers "F.Cu" "B.Cu")
		(net "TP_USB2_11_DN")
	)
	(segment
		(start 346.763848 -40.946578)
		(end 346.9767 -41.159684)
		(width 0.0889)
		(layer "F.Cu")
		(net "TP_USB2_10_DP")
	)
	(segment
		(start 346.9767 -41.159684)
		(end 347.044772 -41.227502)
		(width 0.0889)
		(layer "F.Cu")
		(net "TP_USB2_10_DP")
	)
	(segment
		(start 351.716086 -35.410648)
		(end 352.2726 -35.410648)
		(width 0.12954)
		(layer "F.Cu")
		(net "TP_USB2_10_DP")
	)
	(segment
		(start 348.055438 -40.89781)
		(end 348.624906 -40.89781)
		(width 0.0889)
		(layer "F.Cu")
		(net "TP_USB2_10_DP")
	)
	(segment
		(start 347.044772 -41.227502)
		(end 347.419422 -41.227502)
		(width 0.0889)
		(layer "F.Cu")
		(net "TP_USB2_10_DP")
	)
	(segment
		(start 346.384626 -40.946578)
		(end 346.763848 -40.946578)
		(width 0.0889)
		(layer "F.Cu")
		(net "TP_USB2_10_DP")
	)
	(segment
		(start 358.153208 -33.368234)
		(end 358.56799 -33.783016)
		(width 0.12954)
		(layer "F.Cu")
		(net "TP_USB2_10_DP")
	)
	(segment
		(start 354.315014 -33.368234)
		(end 358.153208 -33.368234)
		(width 0.12954)
		(layer "F.Cu")
		(net "TP_USB2_10_DP")
	)
	(segment
		(start 347.486224 -41.1607)
		(end 347.792548 -41.1607)
		(width 0.0889)
		(layer "F.Cu")
		(net "TP_USB2_10_DP")
	)
	(segment
		(start 348.624906 -40.89781)
		(end 348.817692 -40.705024)
		(width 0.0889)
		(layer "F.Cu")
		(net "TP_USB2_10_DP")
	)
	(segment
		(start 349.898462 -37.228272)
		(end 351.716086 -35.410648)
		(width 0.12954)
		(layer "F.Cu")
		(net "TP_USB2_10_DP")
	)
	(segment
		(start 349.898462 -39.624254)
		(end 349.898462 -37.228272)
		(width 0.12954)
		(layer "F.Cu")
		(net "TP_USB2_10_DP")
	)
	(segment
		(start 347.792548 -41.1607)
		(end 348.055438 -40.89781)
		(width 0.0889)
		(layer "F.Cu")
		(net "TP_USB2_10_DP")
	)
	(segment
		(start 348.817692 -40.705024)
		(end 349.898462 -39.624254)
		(width 0.12954)
		(layer "F.Cu")
		(net "TP_USB2_10_DP")
	)
	(segment
		(start 352.2726 -35.410648)
		(end 354.315014 -33.368234)
		(width 0.12954)
		(layer "F.Cu")
		(net "TP_USB2_10_DP")
	)
	(segment
		(start 347.419422 -41.227502)
		(end 347.486224 -41.1607)
		(width 0.0889)
		(layer "F.Cu")
		(net "TP_USB2_10_DP")
	)
	(via
		(at 358.56799 -33.783016)
		(size 0.762)
		(drill 0.381)
		(layers "F.Cu" "B.Cu")
		(net "TP_USB2_10_DP")
	)
	(segment
		(start 347.73743 -40.946324)
		(end 347.976444 -40.70731)
		(width 0.0889)
		(layer "F.Cu")
		(net "TP_USB2_10_DN")
	)
	(segment
		(start 349.601282 -39.56177)
		(end 349.601282 -36.941506)
		(width 0.12954)
		(layer "F.Cu")
		(net "TP_USB2_10_DN")
	)
	(segment
		(start 348.455742 -40.70731)
		(end 348.6404 -40.522652)
		(width 0.0889)
		(layer "F.Cu")
		(net "TP_USB2_10_DN")
	)
	(segment
		(start 347.976444 -40.70731)
		(end 348.455742 -40.70731)
		(width 0.0889)
		(layer "F.Cu")
		(net "TP_USB2_10_DN")
	)
	(segment
		(start 353.94138 -32.601408)
		(end 358.254808 -32.601408)
		(width 0.12954)
		(layer "F.Cu")
		(net "TP_USB2_10_DN")
	)
	(segment
		(start 348.6404 -40.522652)
		(end 349.601282 -39.56177)
		(width 0.12954)
		(layer "F.Cu")
		(net "TP_USB2_10_DN")
	)
	(segment
		(start 349.601282 -36.941506)
		(end 353.94138 -32.601408)
		(width 0.12954)
		(layer "F.Cu")
		(net "TP_USB2_10_DN")
	)
	(segment
		(start 347.214698 -40.946578)
		(end 347.73743 -40.946324)
		(width 0.0889)
		(layer "F.Cu")
		(net "TP_USB2_10_DN")
	)
	(segment
		(start 358.254808 -32.601408)
		(end 358.606598 -32.249618)
		(width 0.12954)
		(layer "F.Cu")
		(net "TP_USB2_10_DN")
	)
	(via
		(at 358.606598 -32.249618)
		(size 0.762)
		(drill 0.381)
		(layers "F.Cu" "B.Cu")
		(net "TP_USB2_10_DN")
	)
	(segment
		(start 110.700566 -235.784136)
		(end 110.70082 -235.783882)
		(width 0.12954)
		(layer "F.Cu")
		(net "TP_TRC_CPU1_PTI<9>")
	)
	(segment
		(start 110.700566 -236.319822)
		(end 110.700566 -235.784136)
		(width 0.12954)
		(layer "F.Cu")
		(net "TP_TRC_CPU1_PTI<9>")
	)
	(via
		(at 110.70082 -235.783882)
		(size 0.4572)
		(drill 0.2032)
		(layers "F.Cu" "B.Cu")
		(net "TP_TRC_CPU1_PTI<9>")
	)
	(segment
		(start 111.170466 -235.506006)
		(end 111.170466 -234.970066)
		(width 0.12954)
		(layer "F.Cu")
		(net "TP_TRC_CPU1_PTI<8>")
	)
	(via
		(at 108.0897 -234.834684)
		(size 0.6604)
		(drill 0.3302)
		(layers "F.Cu" "B.Cu")
		(net "TP_TRC_CPU1_PTI<8>")
	)
	(via
		(at 111.170466 -234.970066)
		(size 0.4572)
		(drill 0.2032)
		(layers "F.Cu" "B.Cu")
		(net "TP_TRC_CPU1_PTI<8>")
	)
	(segment
		(start 108.393738 -234.530646)
		(end 108.0897 -234.834684)
		(width 0.12954)
		(layer "B.Cu")
		(net "TP_TRC_CPU1_PTI<8>")
	)
	(segment
		(start 108.538518 -234.530646)
		(end 108.393738 -234.530646)
		(width 0.12954)
		(layer "B.Cu")
		(net "TP_TRC_CPU1_PTI<8>")
	)
	(segment
		(start 110.513368 -234.480608)
		(end 110.513114 -234.480608)
		(width 0.0889)
		(layer "B.Cu")
		(net "TP_TRC_CPU1_PTI<8>")
	)
	(segment
		(start 110.54207 -234.496864)
		(end 110.513368 -234.480608)
		(width 0.0889)
		(layer "B.Cu")
		(net "TP_TRC_CPU1_PTI<8>")
	)
	(segment
		(start 108.820966 -234.530646)
		(end 108.538518 -234.530646)
		(width 0.0889)
		(layer "B.Cu")
		(net "TP_TRC_CPU1_PTI<8>")
	)
	(segment
		(start 111.170466 -234.970066)
		(end 110.54207 -234.496864)
		(width 0.0889)
		(layer "B.Cu")
		(net "TP_TRC_CPU1_PTI<8>")
	)
	(arc
		(start 109.008164 -234.480608)
		(mid 108.917857 -234.517937)
		(end 108.820966 -234.530646)
		(width 0.0889)
		(layer "B.Cu")
		(net "TP_TRC_CPU1_PTI<8>")
	)
	(arc
		(start 109.947964 -234.480608)
		(mid 109.760766 -234.530751)
		(end 109.573568 -234.480608)
		(width 0.0889)
		(layer "B.Cu")
		(net "TP_TRC_CPU1_PTI<8>")
	)
	(arc
		(start 109.573568 -234.480608)
		(mid 109.290866 -234.404832)
		(end 109.008164 -234.480608)
		(width 0.0889)
		(layer "B.Cu")
		(net "TP_TRC_CPU1_PTI<8>")
	)
	(arc
		(start 110.513114 -234.480608)
		(mid 110.230556 -234.404959)
		(end 109.947964 -234.480608)
		(width 0.0889)
		(layer "B.Cu")
		(net "TP_TRC_CPU1_PTI<8>")
	)
	(segment
		(start 111.640112 -236.319822)
		(end 111.640112 -235.78439)
		(width 0.12954)
		(layer "F.Cu")
		(net "TP_TRC_CPU1_PTI<7>")
	)
	(segment
		(start 111.640112 -235.78439)
		(end 111.64062 -235.783882)
		(width 0.12954)
		(layer "F.Cu")
		(net "TP_TRC_CPU1_PTI<7>")
	)
	(via
		(at 111.64062 -235.783882)
		(size 0.4572)
		(drill 0.2032)
		(layers "F.Cu" "B.Cu")
		(net "TP_TRC_CPU1_PTI<7>")
	)
	(segment
		(start 113.050066 -234.970066)
		(end 113.050066 -235.506006)
		(width 0.12954)
		(layer "F.Cu")
		(net "TP_TRC_CPU1_PTI<6>")
	)
	(via
		(at 113.050066 -234.970066)
		(size 0.4572)
		(drill 0.2032)
		(layers "F.Cu" "B.Cu")
		(net "TP_TRC_CPU1_PTI<6>")
	)
	(segment
		(start 111.640112 -237.412276)
		(end 111.64062 -237.411768)
		(width 0.12954)
		(layer "F.Cu")
		(net "TP_TRC_CPU1_PTI<5>")
	)
	(segment
		(start 111.640112 -237.947454)
		(end 111.640112 -237.412276)
		(width 0.12954)
		(layer "F.Cu")
		(net "TP_TRC_CPU1_PTI<5>")
	)
	(via
		(at 111.64062 -237.411768)
		(size 0.4572)
		(drill 0.2032)
		(layers "F.Cu" "B.Cu")
		(net "TP_TRC_CPU1_PTI<5>")
	)
	(segment
		(start 113.050066 -237.133892)
		(end 113.050066 -236.597698)
		(width 0.12954)
		(layer "F.Cu")
		(net "TP_TRC_CPU1_PTI<4>")
	)
	(via
		(at 113.050066 -236.597698)
		(size 0.4572)
		(drill 0.2032)
		(layers "F.Cu" "B.Cu")
		(net "TP_TRC_CPU1_PTI<4>")
	)
	(segment
		(start 112.579912 -237.412276)
		(end 112.58042 -237.411768)
		(width 0.12954)
		(layer "F.Cu")
		(net "TP_TRC_CPU1_PTI<3>")
	)
	(segment
		(start 112.579912 -237.947454)
		(end 112.579912 -237.412276)
		(width 0.12954)
		(layer "F.Cu")
		(net "TP_TRC_CPU1_PTI<3>")
	)
	(via
		(at 112.58042 -237.411768)
		(size 0.4572)
		(drill 0.2032)
		(layers "F.Cu" "B.Cu")
		(net "TP_TRC_CPU1_PTI<3>")
	)
	(segment
		(start 109.400594 -268.84757)
		(end 109.400594 -269.38351)
		(width 0.12954)
		(layer "F.Cu")
		(net "TP_TRC_CPU1_PTI<31>")
	)
	(via
		(at 109.400594 -269.38351)
		(size 0.4572)
		(drill 0.2032)
		(layers "F.Cu" "B.Cu")
		(net "TP_TRC_CPU1_PTI<31>")
	)
	(segment
		(start 108.930694 -269.66164)
		(end 108.930694 -270.19758)
		(width 0.12954)
		(layer "F.Cu")
		(net "TP_TRC_CPU1_PTI<30>")
	)
	(via
		(at 108.930694 -270.19758)
		(size 0.4572)
		(drill 0.2032)
		(layers "F.Cu" "B.Cu")
		(net "TP_TRC_CPU1_PTI<30>")
	)
	(segment
		(start 113.989866 -235.506006)
		(end 113.99012 -235.505752)
		(width 0.12954)
		(layer "F.Cu")
		(net "TP_TRC_CPU1_PTI<2>")
	)
	(segment
		(start 113.99012 -235.505752)
		(end 113.99012 -234.970066)
		(width 0.12954)
		(layer "F.Cu")
		(net "TP_TRC_CPU1_PTI<2>")
	)
	(via
		(at 115.907058 -235.343954)
		(size 0.6604)
		(drill 0.3302)
		(layers "F.Cu" "B.Cu")
		(net "TP_TRC_CPU1_PTI<2>")
	)
	(via
		(at 113.99012 -234.970066)
		(size 0.4572)
		(drill 0.2032)
		(layers "F.Cu" "B.Cu")
		(net "TP_TRC_CPU1_PTI<2>")
	)
	(segment
		(start 115.907058 -235.343954)
		(end 115.716558 -235.153454)
		(width 0.0889)
		(layer "B.Cu")
		(net "TP_TRC_CPU1_PTI<2>")
	)
	(segment
		(start 114.621818 -234.65917)
		(end 114.301016 -234.65917)
		(width 0.0889)
		(layer "B.Cu")
		(net "TP_TRC_CPU1_PTI<2>")
	)
	(segment
		(start 114.301016 -234.65917)
		(end 113.99012 -234.970066)
		(width 0.0889)
		(layer "B.Cu")
		(net "TP_TRC_CPU1_PTI<2>")
	)
	(segment
		(start 115.116102 -235.153454)
		(end 114.621818 -234.65917)
		(width 0.0889)
		(layer "B.Cu")
		(net "TP_TRC_CPU1_PTI<2>")
	)
	(segment
		(start 115.716558 -235.153454)
		(end 115.116102 -235.153454)
		(width 0.0889)
		(layer "B.Cu")
		(net "TP_TRC_CPU1_PTI<2>")
	)
	(segment
		(start 108.460794 -268.847824)
		(end 108.460794 -269.38351)
		(width 0.12954)
		(layer "F.Cu")
		(net "TP_TRC_CPU1_PTI<29>")
	)
	(segment
		(start 108.461048 -268.84757)
		(end 108.460794 -268.847824)
		(width 0.12954)
		(layer "F.Cu")
		(net "TP_TRC_CPU1_PTI<29>")
	)
	(via
		(at 108.460794 -269.38351)
		(size 0.4572)
		(drill 0.2032)
		(layers "F.Cu" "B.Cu")
		(net "TP_TRC_CPU1_PTI<29>")
	)
	(segment
		(start 107.521248 -269.383256)
		(end 107.520994 -269.38351)
		(width 0.12954)
		(layer "F.Cu")
		(net "TP_TRC_CPU1_PTI<28>")
	)
	(segment
		(start 107.521248 -268.84757)
		(end 107.521248 -269.383256)
		(width 0.12954)
		(layer "F.Cu")
		(net "TP_TRC_CPU1_PTI<28>")
	)
	(via
		(at 107.520994 -269.38351)
		(size 0.4572)
		(drill 0.2032)
		(layers "F.Cu" "B.Cu")
		(net "TP_TRC_CPU1_PTI<28>")
	)
	(segment
		(start 106.581194 -268.847824)
		(end 106.581194 -269.38351)
		(width 0.12954)
		(layer "F.Cu")
		(net "TP_TRC_CPU1_PTI<27>")
	)
	(segment
		(start 106.581448 -268.84757)
		(end 106.581194 -268.847824)
		(width 0.12954)
		(layer "F.Cu")
		(net "TP_TRC_CPU1_PTI<27>")
	)
	(via
		(at 106.581194 -269.38351)
		(size 0.4572)
		(drill 0.2032)
		(layers "F.Cu" "B.Cu")
		(net "TP_TRC_CPU1_PTI<27>")
	)
	(segment
		(start 109.400594 -270.475456)
		(end 109.400594 -271.011396)
		(width 0.12954)
		(layer "F.Cu")
		(net "TP_TRC_CPU1_PTI<26>")
	)
	(via
		(at 109.400594 -271.011396)
		(size 0.4572)
		(drill 0.2032)
		(layers "F.Cu" "B.Cu")
		(net "TP_TRC_CPU1_PTI<26>")
	)
	(segment
		(start 108.930694 -271.289272)
		(end 108.930694 -271.824958)
		(width 0.12954)
		(layer "F.Cu")
		(net "TP_TRC_CPU1_PTI<25>")
	)
	(segment
		(start 108.930694 -271.824958)
		(end 108.930948 -271.825212)
		(width 0.12954)
		(layer "F.Cu")
		(net "TP_TRC_CPU1_PTI<25>")
	)
	(via
		(at 108.930948 -271.825212)
		(size 0.4572)
		(drill 0.2032)
		(layers "F.Cu" "B.Cu")
		(net "TP_TRC_CPU1_PTI<25>")
	)
	(segment
		(start 107.990894 -271.289272)
		(end 107.990894 -271.824958)
		(width 0.12954)
		(layer "F.Cu")
		(net "TP_TRC_CPU1_PTI<24>")
	)
	(segment
		(start 107.990894 -271.824958)
		(end 107.991148 -271.825212)
		(width 0.12954)
		(layer "F.Cu")
		(net "TP_TRC_CPU1_PTI<24>")
	)
	(via
		(at 107.991148 -271.825212)
		(size 0.4572)
		(drill 0.2032)
		(layers "F.Cu" "B.Cu")
		(net "TP_TRC_CPU1_PTI<24>")
	)
	(segment
		(start 105.171748 -269.661894)
		(end 105.171748 -270.19758)
		(width 0.12954)
		(layer "F.Cu")
		(net "TP_TRC_CPU1_PTI<23>")
	)
	(segment
		(start 105.171494 -269.66164)
		(end 105.171748 -269.661894)
		(width 0.12954)
		(layer "F.Cu")
		(net "TP_TRC_CPU1_PTI<23>")
	)
	(via
		(at 105.171748 -270.19758)
		(size 0.4572)
		(drill 0.2032)
		(layers "F.Cu" "B.Cu")
		(net "TP_TRC_CPU1_PTI<23>")
	)
	(segment
		(start 106.581448 -270.475456)
		(end 106.581194 -270.47571)
		(width 0.12954)
		(layer "F.Cu")
		(net "TP_TRC_CPU1_PTI<22>")
	)
	(segment
		(start 106.581194 -270.47571)
		(end 106.581194 -271.011396)
		(width 0.12954)
		(layer "F.Cu")
		(net "TP_TRC_CPU1_PTI<22>")
	)
	(via
		(at 106.581194 -271.011396)
		(size 0.4572)
		(drill 0.2032)
		(layers "F.Cu" "B.Cu")
		(net "TP_TRC_CPU1_PTI<22>")
	)
	(segment
		(start 104.701848 -270.475456)
		(end 104.701594 -270.47571)
		(width 0.12954)
		(layer "F.Cu")
		(net "TP_TRC_CPU1_PTI<21>")
	)
	(segment
		(start 104.701594 -270.47571)
		(end 104.701594 -271.011396)
		(width 0.12954)
		(layer "F.Cu")
		(net "TP_TRC_CPU1_PTI<21>")
	)
	(via
		(at 104.701594 -271.011396)
		(size 0.4572)
		(drill 0.2032)
		(layers "F.Cu" "B.Cu")
		(net "TP_TRC_CPU1_PTI<21>")
	)
	(segment
		(start 107.051348 -271.289526)
		(end 107.051348 -271.825212)
		(width 0.12954)
		(layer "F.Cu")
		(net "TP_TRC_CPU1_PTI<20>")
	)
	(segment
		(start 107.051094 -271.289272)
		(end 107.051348 -271.289526)
		(width 0.12954)
		(layer "F.Cu")
		(net "TP_TRC_CPU1_PTI<20>")
	)
	(via
		(at 82.726022 -276.317456)
		(size 0.6604)
		(drill 0.3302)
		(layers "F.Cu" "B.Cu")
		(net "TP_TRC_CPU1_PTI<20>")
	)
	(via
		(at 107.051348 -271.825212)
		(size 0.4572)
		(drill 0.2032)
		(layers "F.Cu" "B.Cu")
		(net "TP_TRC_CPU1_PTI<20>")
	)
	(segment
		(start 103.494078 -275.396452)
		(end 103.479346 -275.405088)
		(width 0.0889)
		(layer "B.Cu")
		(net "TP_TRC_CPU1_PTI<20>")
	)
	(segment
		(start 107.23245 -273.125184)
		(end 107.235752 -273.127216)
		(width 0.0889)
		(layer "B.Cu")
		(net "TP_TRC_CPU1_PTI<20>")
	)
	(segment
		(start 87.512652 -275.398992)
		(end 87.502238 -275.405088)
		(width 0.0889)
		(layer "B.Cu")
		(net "TP_TRC_CPU1_PTI<20>")
	)
	(segment
		(start 102.554278 -275.396452)
		(end 102.539546 -275.405088)
		(width 0.0889)
		(layer "B.Cu")
		(net "TP_TRC_CPU1_PTI<20>")
	)
	(segment
		(start 107.238546 -273.777456)
		(end 107.23245 -273.781012)
		(width 0.0889)
		(layer "B.Cu")
		(net "TP_TRC_CPU1_PTI<20>")
	)
	(segment
		(start 107.235752 -273.127216)
		(end 107.238546 -273.12874)
		(width 0.0889)
		(layer "B.Cu")
		(net "TP_TRC_CPU1_PTI<20>")
	)
	(segment
		(start 106.777282 -274.586192)
		(end 106.768392 -274.591272)
		(width 0.0889)
		(layer "B.Cu")
		(net "TP_TRC_CPU1_PTI<20>")
	)
	(segment
		(start 104.428036 -275.400008)
		(end 104.419146 -275.405088)
		(width 0.0889)
		(layer "B.Cu")
		(net "TP_TRC_CPU1_PTI<20>")
	)
	(segment
		(start 84.440268 -275.747988)
		(end 84.41817 -275.747988)
		(width 0.0889)
		(layer "B.Cu")
		(net "TP_TRC_CPU1_PTI<20>")
	)
	(segment
		(start 96.915478 -275.396452)
		(end 96.900746 -275.405088)
		(width 0.0889)
		(layer "B.Cu")
		(net "TP_TRC_CPU1_PTI<20>")
	)
	(segment
		(start 92.211906 -275.398992)
		(end 92.201492 -275.405088)
		(width 0.0889)
		(layer "B.Cu")
		(net "TP_TRC_CPU1_PTI<20>")
	)
	(segment
		(start 101.614478 -275.396452)
		(end 101.599746 -275.405088)
		(width 0.0889)
		(layer "B.Cu")
		(net "TP_TRC_CPU1_PTI<20>")
	)
	(segment
		(start 84.728558 -275.768308)
		(end 84.460588 -275.768308)
		(width 0.0889)
		(layer "B.Cu")
		(net "TP_TRC_CPU1_PTI<20>")
	)
	(segment
		(start 83.29549 -275.747988)
		(end 82.726022 -276.317456)
		(width 0.12954)
		(layer "B.Cu")
		(net "TP_TRC_CPU1_PTI<20>")
	)
	(segment
		(start 107.207812 -272.09623)
		(end 107.183682 -272.185384)
		(width 0.0889)
		(layer "B.Cu")
		(net "TP_TRC_CPU1_PTI<20>")
	)
	(segment
		(start 97.85096 -275.398992)
		(end 97.840546 -275.405088)
		(width 0.0889)
		(layer "B.Cu")
		(net "TP_TRC_CPU1_PTI<20>")
	)
	(segment
		(start 107.238546 -273.12874)
		(end 107.247436 -273.13382)
		(width 0.0889)
		(layer "B.Cu")
		(net "TP_TRC_CPU1_PTI<20>")
	)
	(segment
		(start 85.040724 -275.456142)
		(end 84.728558 -275.768308)
		(width 0.0889)
		(layer "B.Cu")
		(net "TP_TRC_CPU1_PTI<20>")
	)
	(segment
		(start 91.27236 -275.398992)
		(end 91.261946 -275.405088)
		(width 0.0889)
		(layer "B.Cu")
		(net "TP_TRC_CPU1_PTI<20>")
	)
	(segment
		(start 90.332306 -275.398992)
		(end 90.321892 -275.405088)
		(width 0.0889)
		(layer "B.Cu")
		(net "TP_TRC_CPU1_PTI<20>")
	)
	(segment
		(start 99.734878 -275.396452)
		(end 99.720146 -275.405088)
		(width 0.0889)
		(layer "B.Cu")
		(net "TP_TRC_CPU1_PTI<20>")
	)
	(segment
		(start 106.955844 -272.625058)
		(end 106.955844 -272.639282)
		(width 0.0889)
		(layer "B.Cu")
		(net "TP_TRC_CPU1_PTI<20>")
	)
	(segment
		(start 95.975678 -275.396452)
		(end 95.960946 -275.405088)
		(width 0.0889)
		(layer "B.Cu")
		(net "TP_TRC_CPU1_PTI<20>")
	)
	(segment
		(start 86.37524 -275.456142)
		(end 85.040724 -275.456142)
		(width 0.0889)
		(layer "B.Cu")
		(net "TP_TRC_CPU1_PTI<20>")
	)
	(segment
		(start 95.035878 -275.396452)
		(end 95.021146 -275.405088)
		(width 0.0889)
		(layer "B.Cu")
		(net "TP_TRC_CPU1_PTI<20>")
	)
	(segment
		(start 84.460588 -275.768308)
		(end 84.440268 -275.747988)
		(width 0.0889)
		(layer "B.Cu")
		(net "TP_TRC_CPU1_PTI<20>")
	)
	(segment
		(start 107.247436 -273.772376)
		(end 107.238546 -273.777456)
		(width 0.0889)
		(layer "B.Cu")
		(net "TP_TRC_CPU1_PTI<20>")
	)
	(segment
		(start 93.156278 -275.396452)
		(end 93.141546 -275.405088)
		(width 0.0889)
		(layer "B.Cu")
		(net "TP_TRC_CPU1_PTI<20>")
	)
	(segment
		(start 105.454196 -274.591272)
		(end 105.439464 -274.582636)
		(width 0.0889)
		(layer "B.Cu")
		(net "TP_TRC_CPU1_PTI<20>")
	)
	(segment
		(start 98.790506 -275.398992)
		(end 98.780092 -275.405088)
		(width 0.0889)
		(layer "B.Cu")
		(net "TP_TRC_CPU1_PTI<20>")
	)
	(segment
		(start 84.41817 -275.747988)
		(end 83.29549 -275.747988)
		(width 0.12954)
		(layer "B.Cu")
		(net "TP_TRC_CPU1_PTI<20>")
	)
	(segment
		(start 87.127842 -275.405088)
		(end 87.11311 -275.396452)
		(width 0.0889)
		(layer "B.Cu")
		(net "TP_TRC_CPU1_PTI<20>")
	)
	(segment
		(start 104.606598 -275.065236)
		(end 104.606598 -275.08073)
		(width 0.0889)
		(layer "B.Cu")
		(net "TP_TRC_CPU1_PTI<20>")
	)
	(segment
		(start 107.051348 -271.825212)
		(end 107.207812 -272.09623)
		(width 0.0889)
		(layer "B.Cu")
		(net "TP_TRC_CPU1_PTI<20>")
	)
	(arc
		(start 96.900746 -275.405088)
		(mid 96.713548 -275.455231)
		(end 96.52635 -275.405088)
		(width 0.0889)
		(layer "B.Cu")
		(net "TP_TRC_CPU1_PTI<20>")
	)
	(arc
		(start 99.720146 -275.405088)
		(mid 99.532948 -275.455231)
		(end 99.34575 -275.405088)
		(width 0.0889)
		(layer "B.Cu")
		(net "TP_TRC_CPU1_PTI<20>")
	)
	(arc
		(start 101.599746 -275.405088)
		(mid 101.412548 -275.455231)
		(end 101.22535 -275.405088)
		(width 0.0889)
		(layer "B.Cu")
		(net "TP_TRC_CPU1_PTI<20>")
	)
	(arc
		(start 90.321892 -275.405088)
		(mid 90.134694 -275.455231)
		(end 89.947496 -275.405088)
		(width 0.0889)
		(layer "B.Cu")
		(net "TP_TRC_CPU1_PTI<20>")
	)
	(arc
		(start 107.183682 -272.185384)
		(mid 107.019067 -272.378948)
		(end 106.955844 -272.625058)
		(width 0.0889)
		(layer "B.Cu")
		(net "TP_TRC_CPU1_PTI<20>")
	)
	(arc
		(start 88.442292 -275.405088)
		(mid 88.255094 -275.455231)
		(end 88.067896 -275.405088)
		(width 0.0889)
		(layer "B.Cu")
		(net "TP_TRC_CPU1_PTI<20>")
	)
	(arc
		(start 106.955844 -274.266914)
		(mid 106.908165 -274.449814)
		(end 106.777282 -274.586192)
		(width 0.0889)
		(layer "B.Cu")
		(net "TP_TRC_CPU1_PTI<20>")
	)
	(arc
		(start 87.502238 -275.405088)
		(mid 87.31504 -275.455231)
		(end 87.127842 -275.405088)
		(width 0.0889)
		(layer "B.Cu")
		(net "TP_TRC_CPU1_PTI<20>")
	)
	(arc
		(start 104.419146 -275.405088)
		(mid 104.231948 -275.455231)
		(end 104.04475 -275.405088)
		(width 0.0889)
		(layer "B.Cu")
		(net "TP_TRC_CPU1_PTI<20>")
	)
	(arc
		(start 106.768392 -274.591272)
		(mid 106.581194 -274.641415)
		(end 106.393996 -274.591272)
		(width 0.0889)
		(layer "B.Cu")
		(net "TP_TRC_CPU1_PTI<20>")
	)
	(arc
		(start 89.007696 -275.405088)
		(mid 88.724994 -275.329346)
		(end 88.442292 -275.405088)
		(width 0.0889)
		(layer "B.Cu")
		(net "TP_TRC_CPU1_PTI<20>")
	)
	(arc
		(start 92.76715 -275.405088)
		(mid 92.490337 -275.329252)
		(end 92.211906 -275.398992)
		(width 0.0889)
		(layer "B.Cu")
		(net "TP_TRC_CPU1_PTI<20>")
	)
	(arc
		(start 107.247436 -273.13382)
		(mid 107.426033 -273.453098)
		(end 107.247436 -273.772376)
		(width 0.0889)
		(layer "B.Cu")
		(net "TP_TRC_CPU1_PTI<20>")
	)
	(arc
		(start 94.081346 -275.405088)
		(mid 93.894148 -275.455231)
		(end 93.70695 -275.405088)
		(width 0.0889)
		(layer "B.Cu")
		(net "TP_TRC_CPU1_PTI<20>")
	)
	(arc
		(start 92.201492 -275.405088)
		(mid 92.014294 -275.455231)
		(end 91.827096 -275.405088)
		(width 0.0889)
		(layer "B.Cu")
		(net "TP_TRC_CPU1_PTI<20>")
	)
	(arc
		(start 102.16515 -275.405088)
		(mid 101.890921 -275.329163)
		(end 101.614478 -275.396452)
		(width 0.0889)
		(layer "B.Cu")
		(net "TP_TRC_CPU1_PTI<20>")
	)
	(arc
		(start 105.828592 -274.591272)
		(mid 105.641394 -274.641415)
		(end 105.454196 -274.591272)
		(width 0.0889)
		(layer "B.Cu")
		(net "TP_TRC_CPU1_PTI<20>")
	)
	(arc
		(start 104.04475 -275.405088)
		(mid 103.770521 -275.329163)
		(end 103.494078 -275.396452)
		(width 0.0889)
		(layer "B.Cu")
		(net "TP_TRC_CPU1_PTI<20>")
	)
	(arc
		(start 93.141546 -275.405088)
		(mid 92.954348 -275.455231)
		(end 92.76715 -275.405088)
		(width 0.0889)
		(layer "B.Cu")
		(net "TP_TRC_CPU1_PTI<20>")
	)
	(arc
		(start 95.021146 -275.405088)
		(mid 94.833948 -275.455231)
		(end 94.64675 -275.405088)
		(width 0.0889)
		(layer "B.Cu")
		(net "TP_TRC_CPU1_PTI<20>")
	)
	(arc
		(start 106.955844 -272.639282)
		(mid 107.029835 -272.918848)
		(end 107.23245 -273.125184)
		(width 0.0889)
		(layer "B.Cu")
		(net "TP_TRC_CPU1_PTI<20>")
	)
	(arc
		(start 89.382092 -275.405088)
		(mid 89.194894 -275.455231)
		(end 89.007696 -275.405088)
		(width 0.0889)
		(layer "B.Cu")
		(net "TP_TRC_CPU1_PTI<20>")
	)
	(arc
		(start 94.64675 -275.405088)
		(mid 94.364048 -275.329346)
		(end 94.081346 -275.405088)
		(width 0.0889)
		(layer "B.Cu")
		(net "TP_TRC_CPU1_PTI<20>")
	)
	(arc
		(start 97.46615 -275.405088)
		(mid 97.191921 -275.329163)
		(end 96.915478 -275.396452)
		(width 0.0889)
		(layer "B.Cu")
		(net "TP_TRC_CPU1_PTI<20>")
	)
	(arc
		(start 87.11311 -275.396452)
		(mid 86.836669 -275.329286)
		(end 86.562438 -275.405088)
		(width 0.0889)
		(layer "B.Cu")
		(net "TP_TRC_CPU1_PTI<20>")
	)
	(arc
		(start 107.23245 -273.781012)
		(mid 107.029863 -273.987363)
		(end 106.955844 -274.266914)
		(width 0.0889)
		(layer "B.Cu")
		(net "TP_TRC_CPU1_PTI<20>")
	)
	(arc
		(start 95.960946 -275.405088)
		(mid 95.773748 -275.455231)
		(end 95.58655 -275.405088)
		(width 0.0889)
		(layer "B.Cu")
		(net "TP_TRC_CPU1_PTI<20>")
	)
	(arc
		(start 95.58655 -275.405088)
		(mid 95.312321 -275.329163)
		(end 95.035878 -275.396452)
		(width 0.0889)
		(layer "B.Cu")
		(net "TP_TRC_CPU1_PTI<20>")
	)
	(arc
		(start 91.261946 -275.405088)
		(mid 91.074748 -275.455231)
		(end 90.88755 -275.405088)
		(width 0.0889)
		(layer "B.Cu")
		(net "TP_TRC_CPU1_PTI<20>")
	)
	(arc
		(start 100.28555 -275.405088)
		(mid 100.011321 -275.329163)
		(end 99.734878 -275.396452)
		(width 0.0889)
		(layer "B.Cu")
		(net "TP_TRC_CPU1_PTI<20>")
	)
	(arc
		(start 97.840546 -275.405088)
		(mid 97.653348 -275.455231)
		(end 97.46615 -275.405088)
		(width 0.0889)
		(layer "B.Cu")
		(net "TP_TRC_CPU1_PTI<20>")
	)
	(arc
		(start 96.52635 -275.405088)
		(mid 96.252121 -275.329163)
		(end 95.975678 -275.396452)
		(width 0.0889)
		(layer "B.Cu")
		(net "TP_TRC_CPU1_PTI<20>")
	)
	(arc
		(start 93.70695 -275.405088)
		(mid 93.432721 -275.329163)
		(end 93.156278 -275.396452)
		(width 0.0889)
		(layer "B.Cu")
		(net "TP_TRC_CPU1_PTI<20>")
	)
	(arc
		(start 90.88755 -275.405088)
		(mid 90.610737 -275.329252)
		(end 90.332306 -275.398992)
		(width 0.0889)
		(layer "B.Cu")
		(net "TP_TRC_CPU1_PTI<20>")
	)
	(arc
		(start 101.22535 -275.405088)
		(mid 100.942648 -275.329346)
		(end 100.659946 -275.405088)
		(width 0.0889)
		(layer "B.Cu")
		(net "TP_TRC_CPU1_PTI<20>")
	)
	(arc
		(start 103.479346 -275.405088)
		(mid 103.292148 -275.455231)
		(end 103.10495 -275.405088)
		(width 0.0889)
		(layer "B.Cu")
		(net "TP_TRC_CPU1_PTI<20>")
	)
	(arc
		(start 86.562438 -275.405088)
		(mid 86.472202 -275.442958)
		(end 86.37524 -275.456142)
		(width 0.0889)
		(layer "B.Cu")
		(net "TP_TRC_CPU1_PTI<20>")
	)
	(arc
		(start 99.34575 -275.405088)
		(mid 99.068937 -275.329252)
		(end 98.790506 -275.398992)
		(width 0.0889)
		(layer "B.Cu")
		(net "TP_TRC_CPU1_PTI<20>")
	)
	(arc
		(start 88.067896 -275.405088)
		(mid 87.791083 -275.329252)
		(end 87.512652 -275.398992)
		(width 0.0889)
		(layer "B.Cu")
		(net "TP_TRC_CPU1_PTI<20>")
	)
	(arc
		(start 98.780092 -275.405088)
		(mid 98.592894 -275.455231)
		(end 98.405696 -275.405088)
		(width 0.0889)
		(layer "B.Cu")
		(net "TP_TRC_CPU1_PTI<20>")
	)
	(arc
		(start 106.393996 -274.591272)
		(mid 106.111294 -274.515496)
		(end 105.828592 -274.591272)
		(width 0.0889)
		(layer "B.Cu")
		(net "TP_TRC_CPU1_PTI<20>")
	)
	(arc
		(start 104.606598 -275.08073)
		(mid 104.558919 -275.26363)
		(end 104.428036 -275.400008)
		(width 0.0889)
		(layer "B.Cu")
		(net "TP_TRC_CPU1_PTI<20>")
	)
	(arc
		(start 89.947496 -275.405088)
		(mid 89.664794 -275.329346)
		(end 89.382092 -275.405088)
		(width 0.0889)
		(layer "B.Cu")
		(net "TP_TRC_CPU1_PTI<20>")
	)
	(arc
		(start 91.827096 -275.405088)
		(mid 91.550537 -275.329379)
		(end 91.27236 -275.398992)
		(width 0.0889)
		(layer "B.Cu")
		(net "TP_TRC_CPU1_PTI<20>")
	)
	(arc
		(start 103.10495 -275.405088)
		(mid 102.830721 -275.329163)
		(end 102.554278 -275.396452)
		(width 0.0889)
		(layer "B.Cu")
		(net "TP_TRC_CPU1_PTI<20>")
	)
	(arc
		(start 98.405696 -275.405088)
		(mid 98.129137 -275.329379)
		(end 97.85096 -275.398992)
		(width 0.0889)
		(layer "B.Cu")
		(net "TP_TRC_CPU1_PTI<20>")
	)
	(arc
		(start 102.539546 -275.405088)
		(mid 102.352348 -275.455231)
		(end 102.16515 -275.405088)
		(width 0.0889)
		(layer "B.Cu")
		(net "TP_TRC_CPU1_PTI<20>")
	)
	(arc
		(start 105.439464 -274.582636)
		(mid 105.162989 -274.515316)
		(end 104.888792 -274.591272)
		(width 0.0889)
		(layer "B.Cu")
		(net "TP_TRC_CPU1_PTI<20>")
	)
	(arc
		(start 104.888792 -274.591272)
		(mid 104.685969 -274.791503)
		(end 104.606598 -275.065236)
		(width 0.0889)
		(layer "B.Cu")
		(net "TP_TRC_CPU1_PTI<20>")
	)
	(arc
		(start 100.659946 -275.405088)
		(mid 100.472748 -275.455231)
		(end 100.28555 -275.405088)
		(width 0.0889)
		(layer "B.Cu")
		(net "TP_TRC_CPU1_PTI<20>")
	)
	(segment
		(start 114.459766 -235.784136)
		(end 114.46002 -235.783882)
		(width 0.12954)
		(layer "F.Cu")
		(net "TP_TRC_CPU1_PTI<1>")
	)
	(segment
		(start 114.459766 -236.319822)
		(end 114.459766 -235.784136)
		(width 0.12954)
		(layer "F.Cu")
		(net "TP_TRC_CPU1_PTI<1>")
	)
	(via
		(at 114.46002 -235.783882)
		(size 0.4572)
		(drill 0.2032)
		(layers "F.Cu" "B.Cu")
		(net "TP_TRC_CPU1_PTI<1>")
	)
	(segment
		(start 106.111294 -271.289272)
		(end 106.111294 -271.824958)
		(width 0.12954)
		(layer "F.Cu")
		(net "TP_TRC_CPU1_PTI<19>")
	)
	(segment
		(start 106.111294 -271.824958)
		(end 106.111548 -271.825212)
		(width 0.12954)
		(layer "F.Cu")
		(net "TP_TRC_CPU1_PTI<19>")
	)
	(via
		(at 106.111548 -271.825212)
		(size 0.4572)
		(drill 0.2032)
		(layers "F.Cu" "B.Cu")
		(net "TP_TRC_CPU1_PTI<19>")
	)
	(segment
		(start 105.171494 -271.289272)
		(end 105.171494 -271.824958)
		(width 0.12954)
		(layer "F.Cu")
		(net "TP_TRC_CPU1_PTI<18>")
	)
	(segment
		(start 105.171494 -271.824958)
		(end 105.171748 -271.825212)
		(width 0.12954)
		(layer "F.Cu")
		(net "TP_TRC_CPU1_PTI<18>")
	)
	(via
		(at 105.171748 -271.825212)
		(size 0.4572)
		(drill 0.2032)
		(layers "F.Cu" "B.Cu")
		(net "TP_TRC_CPU1_PTI<18>")
	)
	(segment
		(start 105.641648 -272.103342)
		(end 105.641394 -272.103596)
		(width 0.12954)
		(layer "F.Cu")
		(net "TP_TRC_CPU1_PTI<17>")
	)
	(segment
		(start 105.641394 -272.103596)
		(end 105.641394 -272.639282)
		(width 0.12954)
		(layer "F.Cu")
		(net "TP_TRC_CPU1_PTI<17>")
	)
	(via
		(at 105.641394 -272.639282)
		(size 0.4572)
		(drill 0.2032)
		(layers "F.Cu" "B.Cu")
		(net "TP_TRC_CPU1_PTI<17>")
	)
	(segment
		(start 104.701594 -272.103596)
		(end 104.701594 -272.639282)
		(width 0.12954)
		(layer "F.Cu")
		(net "TP_TRC_CPU1_PTI<16>")
	)
	(segment
		(start 104.701848 -272.103342)
		(end 104.701594 -272.103596)
		(width 0.12954)
		(layer "F.Cu")
		(net "TP_TRC_CPU1_PTI<16>")
	)
	(via
		(at 104.701594 -272.639282)
		(size 0.4572)
		(drill 0.2032)
		(layers "F.Cu" "B.Cu")
		(net "TP_TRC_CPU1_PTI<16>")
	)
	(segment
		(start 109.760512 -237.947454)
		(end 109.760512 -237.412276)
		(width 0.12954)
		(layer "F.Cu")
		(net "TP_TRC_CPU1_PTI<15>")
	)
	(segment
		(start 109.760512 -237.412276)
		(end 109.76102 -237.411768)
		(width 0.12954)
		(layer "F.Cu")
		(net "TP_TRC_CPU1_PTI<15>")
	)
	(via
		(at 109.76102 -237.411768)
		(size 0.4572)
		(drill 0.2032)
		(layers "F.Cu" "B.Cu")
		(net "TP_TRC_CPU1_PTI<15>")
	)
	(segment
		(start 109.290866 -237.133892)
		(end 109.290866 -236.597698)
		(width 0.12954)
		(layer "F.Cu")
		(net "TP_TRC_CPU1_PTI<14>")
	)
	(via
		(at 109.290866 -236.597698)
		(size 0.4572)
		(drill 0.2032)
		(layers "F.Cu" "B.Cu")
		(net "TP_TRC_CPU1_PTI<14>")
	)
	(segment
		(start 109.760512 -235.78439)
		(end 109.76102 -235.783882)
		(width 0.12954)
		(layer "F.Cu")
		(net "TP_TRC_CPU1_PTI<13>")
	)
	(segment
		(start 109.760512 -236.319822)
		(end 109.760512 -235.78439)
		(width 0.12954)
		(layer "F.Cu")
		(net "TP_TRC_CPU1_PTI<13>")
	)
	(via
		(at 109.76102 -235.783882)
		(size 0.4572)
		(drill 0.2032)
		(layers "F.Cu" "B.Cu")
		(net "TP_TRC_CPU1_PTI<13>")
	)
	(segment
		(start 109.290866 -235.506006)
		(end 109.290866 -234.970066)
		(width 0.12954)
		(layer "F.Cu")
		(net "TP_TRC_CPU1_PTI<12>")
	)
	(via
		(at 109.290866 -234.970066)
		(size 0.4572)
		(drill 0.2032)
		(layers "F.Cu" "B.Cu")
		(net "TP_TRC_CPU1_PTI<12>")
	)
	(segment
		(start 110.700566 -237.947454)
		(end 110.700566 -237.412022)
		(width 0.12954)
		(layer "F.Cu")
		(net "TP_TRC_CPU1_PTI<11>")
	)
	(segment
		(start 110.700566 -237.412022)
		(end 110.70082 -237.411768)
		(width 0.12954)
		(layer "F.Cu")
		(net "TP_TRC_CPU1_PTI<11>")
	)
	(via
		(at 110.70082 -237.411768)
		(size 0.4572)
		(drill 0.2032)
		(layers "F.Cu" "B.Cu")
		(net "TP_TRC_CPU1_PTI<11>")
	)
	(segment
		(start 111.170466 -237.133892)
		(end 111.170466 -236.597698)
		(width 0.12954)
		(layer "F.Cu")
		(net "TP_TRC_CPU1_PTI<10>")
	)
	(via
		(at 111.170466 -236.597698)
		(size 0.4572)
		(drill 0.2032)
		(layers "F.Cu" "B.Cu")
		(net "TP_TRC_CPU1_PTI<10>")
	)
	(segment
		(start 113.989866 -237.133892)
		(end 113.989866 -236.597952)
		(width 0.12954)
		(layer "F.Cu")
		(net "TP_TRC_CPU1_PTI<0>")
	)
	(segment
		(start 113.989866 -236.597952)
		(end 113.99012 -236.597698)
		(width 0.12954)
		(layer "F.Cu")
		(net "TP_TRC_CPU1_PTI<0>")
	)
	(via
		(at 113.99012 -236.597698)
		(size 0.4572)
		(drill 0.2032)
		(layers "F.Cu" "B.Cu")
		(net "TP_TRC_CPU1_PTI<0>")
	)
	(segment
		(start 107.991148 -269.661894)
		(end 107.991148 -270.19758)
		(width 0.12954)
		(layer "F.Cu")
		(net "TP_TRC_CPU1_PTI3_CLK")
	)
	(segment
		(start 107.990894 -269.66164)
		(end 107.991148 -269.661894)
		(width 0.12954)
		(layer "F.Cu")
		(net "TP_TRC_CPU1_PTI3_CLK")
	)
	(via
		(at 107.991148 -270.19758)
		(size 0.4572)
		(drill 0.2032)
		(layers "F.Cu" "B.Cu")
		(net "TP_TRC_CPU1_PTI3_CLK")
	)
	(segment
		(start 106.111294 -269.66164)
		(end 106.111294 -270.197326)
		(width 0.12954)
		(layer "F.Cu")
		(net "TP_TRC_CPU1_PTI2_CLK")
	)
	(segment
		(start 106.111294 -270.197326)
		(end 106.111548 -270.19758)
		(width 0.12954)
		(layer "F.Cu")
		(net "TP_TRC_CPU1_PTI2_CLK")
	)
	(via
		(at 106.111548 -270.19758)
		(size 0.4572)
		(drill 0.2032)
		(layers "F.Cu" "B.Cu")
		(net "TP_TRC_CPU1_PTI2_CLK")
	)
	(segment
		(start 112.579912 -236.319822)
		(end 112.579912 -235.78439)
		(width 0.12954)
		(layer "F.Cu")
		(net "TP_TRC_CPU1_PTI1_CLK")
	)
	(segment
		(start 112.579912 -235.78439)
		(end 112.58042 -235.783882)
		(width 0.12954)
		(layer "F.Cu")
		(net "TP_TRC_CPU1_PTI1_CLK")
	)
	(via
		(at 112.58042 -235.783882)
		(size 0.4572)
		(drill 0.2032)
		(layers "F.Cu" "B.Cu")
		(net "TP_TRC_CPU1_PTI1_CLK")
	)
	(segment
		(start 113.519712 -237.412276)
		(end 113.52022 -237.411768)
		(width 0.12954)
		(layer "F.Cu")
		(net "TP_TRC_CPU1_PTI0_CLK")
	)
	(segment
		(start 113.519712 -237.947454)
		(end 113.519712 -237.412276)
		(width 0.12954)
		(layer "F.Cu")
		(net "TP_TRC_CPU1_PTI0_CLK")
	)
	(via
		(at 113.52022 -237.411768)
		(size 0.4572)
		(drill 0.2032)
		(layers "F.Cu" "B.Cu")
		(net "TP_TRC_CPU1_PTI0_CLK")
	)
	(segment
		(start 362.399834 -236.319822)
		(end 362.399834 -235.783882)
		(width 0.12954)
		(layer "F.Cu")
		(net "TP_TRC_CPU0_PTI_MON<1>")
	)
	(via
		(at 362.399834 -235.783882)
		(size 0.4572)
		(drill 0.2032)
		(layers "F.Cu" "B.Cu")
		(net "TP_TRC_CPU0_PTI_MON<1>")
	)
	(segment
		(start 358.640634 -236.319822)
		(end 358.640634 -235.783882)
		(width 0.12954)
		(layer "F.Cu")
		(net "TP_TRC_CPU0_PTI<9>")
	)
	(via
		(at 358.640634 -235.783882)
		(size 0.4572)
		(drill 0.2032)
		(layers "F.Cu" "B.Cu")
		(net "TP_TRC_CPU0_PTI<9>")
	)
	(segment
		(start 359.110534 -235.506006)
		(end 359.11028 -235.505752)
		(width 0.12954)
		(layer "F.Cu")
		(net "TP_TRC_CPU0_PTI<8>")
	)
	(segment
		(start 359.11028 -235.505752)
		(end 359.11028 -234.970066)
		(width 0.12954)
		(layer "F.Cu")
		(net "TP_TRC_CPU0_PTI<8>")
	)
	(via
		(at 359.11028 -234.970066)
		(size 0.4572)
		(drill 0.2032)
		(layers "F.Cu" "B.Cu")
		(net "TP_TRC_CPU0_PTI<8>")
	)
	(via
		(at 356.100634 -234.782614)
		(size 0.6604)
		(drill 0.3302)
		(layers "F.Cu" "B.Cu")
		(net "TP_TRC_CPU0_PTI<8>")
	)
	(segment
		(start 359.11028 -234.970066)
		(end 358.385872 -234.661964)
		(width 0.0889)
		(layer "B.Cu")
		(net "TP_TRC_CPU0_PTI<8>")
	)
	(segment
		(start 358.385872 -234.661964)
		(end 358.357932 -234.645708)
		(width 0.0889)
		(layer "B.Cu")
		(net "TP_TRC_CPU0_PTI<8>")
	)
	(segment
		(start 357.983536 -234.645708)
		(end 357.973122 -234.651804)
		(width 0.0889)
		(layer "B.Cu")
		(net "TP_TRC_CPU0_PTI<8>")
	)
	(segment
		(start 356.761034 -234.7214)
		(end 356.161848 -234.7214)
		(width 0.12954)
		(layer "B.Cu")
		(net "TP_TRC_CPU0_PTI<8>")
	)
	(segment
		(start 356.161848 -234.7214)
		(end 356.100634 -234.782614)
		(width 0.12954)
		(layer "B.Cu")
		(net "TP_TRC_CPU0_PTI<8>")
	)
	(arc
		(start 358.357932 -234.645708)
		(mid 358.170734 -234.595531)
		(end 357.983536 -234.645708)
		(width 0.0889)
		(layer "B.Cu")
		(net "TP_TRC_CPU0_PTI<8>")
	)
	(arc
		(start 357.043482 -234.645708)
		(mid 356.90724 -234.702142)
		(end 356.761034 -234.7214)
		(width 0.0889)
		(layer "B.Cu")
		(net "TP_TRC_CPU0_PTI<8>")
	)
	(arc
		(start 357.417878 -234.645708)
		(mid 357.23068 -234.595565)
		(end 357.043482 -234.645708)
		(width 0.0889)
		(layer "B.Cu")
		(net "TP_TRC_CPU0_PTI<8>")
	)
	(arc
		(start 357.973122 -234.651804)
		(mid 357.69469 -234.72165)
		(end 357.417878 -234.645708)
		(width 0.0889)
		(layer "B.Cu")
		(net "TP_TRC_CPU0_PTI<8>")
	)
	(segment
		(start 359.58018 -236.319822)
		(end 359.580434 -236.319568)
		(width 0.12954)
		(layer "F.Cu")
		(net "TP_TRC_CPU0_PTI<7>")
	)
	(segment
		(start 359.580434 -236.319568)
		(end 359.580434 -235.783882)
		(width 0.12954)
		(layer "F.Cu")
		(net "TP_TRC_CPU0_PTI<7>")
	)
	(via
		(at 359.580434 -235.783882)
		(size 0.4572)
		(drill 0.2032)
		(layers "F.Cu" "B.Cu")
		(net "TP_TRC_CPU0_PTI<7>")
	)
	(segment
		(start 360.990134 -235.506006)
		(end 360.98988 -235.505752)
		(width 0.12954)
		(layer "F.Cu")
		(net "TP_TRC_CPU0_PTI<6>")
	)
	(segment
		(start 360.98988 -235.505752)
		(end 360.98988 -234.970066)
		(width 0.12954)
		(layer "F.Cu")
		(net "TP_TRC_CPU0_PTI<6>")
	)
	(via
		(at 360.98988 -234.970066)
		(size 0.4572)
		(drill 0.2032)
		(layers "F.Cu" "B.Cu")
		(net "TP_TRC_CPU0_PTI<6>")
	)
	(via
		(at 363.75975 -234.83062)
		(size 0.6604)
		(drill 0.3302)
		(layers "F.Cu" "B.Cu")
		(net "TP_TRC_CPU0_PTI<6>")
	)
	(segment
		(start 361.742736 -234.645708)
		(end 361.714288 -234.662472)
		(width 0.0889)
		(layer "B.Cu")
		(net "TP_TRC_CPU0_PTI<6>")
	)
	(segment
		(start 362.681774 -234.645708)
		(end 362.66374 -234.656122)
		(width 0.0889)
		(layer "B.Cu")
		(net "TP_TRC_CPU0_PTI<6>")
	)
	(segment
		(start 362.698538 -234.636056)
		(end 362.681774 -234.645708)
		(width 0.0889)
		(layer "B.Cu")
		(net "TP_TRC_CPU0_PTI<6>")
	)
	(segment
		(start 363.75975 -234.83062)
		(end 363.241082 -234.83062)
		(width 0.12954)
		(layer "B.Cu")
		(net "TP_TRC_CPU0_PTI<6>")
	)
	(segment
		(start 363.241082 -234.83062)
		(end 363.05617 -234.645708)
		(width 0.12954)
		(layer "B.Cu")
		(net "TP_TRC_CPU0_PTI<6>")
	)
	(segment
		(start 361.714288 -234.662472)
		(end 360.98988 -234.970066)
		(width 0.0889)
		(layer "B.Cu")
		(net "TP_TRC_CPU0_PTI<6>")
	)
	(arc
		(start 362.117132 -234.645708)
		(mid 361.929934 -234.595565)
		(end 361.742736 -234.645708)
		(width 0.0889)
		(layer "B.Cu")
		(net "TP_TRC_CPU0_PTI<6>")
	)
	(arc
		(start 362.66374 -234.656122)
		(mid 362.38909 -234.721407)
		(end 362.117132 -234.645708)
		(width 0.0889)
		(layer "B.Cu")
		(net "TP_TRC_CPU0_PTI<6>")
	)
	(arc
		(start 363.05617 -234.645708)
		(mid 362.87858 -234.595447)
		(end 362.698538 -234.636056)
		(width 0.0889)
		(layer "B.Cu")
		(net "TP_TRC_CPU0_PTI<6>")
	)
	(segment
		(start 359.58018 -237.947454)
		(end 359.580434 -237.9472)
		(width 0.12954)
		(layer "F.Cu")
		(net "TP_TRC_CPU0_PTI<5>")
	)
	(segment
		(start 359.580434 -237.9472)
		(end 359.580434 -237.411514)
		(width 0.12954)
		(layer "F.Cu")
		(net "TP_TRC_CPU0_PTI<5>")
	)
	(via
		(at 359.580434 -237.411514)
		(size 0.4572)
		(drill 0.2032)
		(layers "F.Cu" "B.Cu")
		(net "TP_TRC_CPU0_PTI<5>")
	)
	(segment
		(start 360.990134 -237.133892)
		(end 360.98988 -237.133638)
		(width 0.12954)
		(layer "F.Cu")
		(net "TP_TRC_CPU0_PTI<4>")
	)
	(segment
		(start 360.98988 -237.133638)
		(end 360.98988 -236.597952)
		(width 0.12954)
		(layer "F.Cu")
		(net "TP_TRC_CPU0_PTI<4>")
	)
	(via
		(at 360.98988 -236.597952)
		(size 0.4572)
		(drill 0.2032)
		(layers "F.Cu" "B.Cu")
		(net "TP_TRC_CPU0_PTI<4>")
	)
	(segment
		(start 360.520234 -237.9472)
		(end 360.520234 -237.411514)
		(width 0.12954)
		(layer "F.Cu")
		(net "TP_TRC_CPU0_PTI<3>")
	)
	(segment
		(start 360.51998 -237.947454)
		(end 360.520234 -237.9472)
		(width 0.12954)
		(layer "F.Cu")
		(net "TP_TRC_CPU0_PTI<3>")
	)
	(via
		(at 360.520234 -237.411514)
		(size 0.4572)
		(drill 0.2032)
		(layers "F.Cu" "B.Cu")
		(net "TP_TRC_CPU0_PTI<3>")
	)
	(segment
		(start 357.340662 -268.84757)
		(end 357.340662 -269.38351)
		(width 0.12954)
		(layer "F.Cu")
		(net "TP_TRC_CPU0_PTI<31>")
	)
	(via
		(at 357.340662 -269.38351)
		(size 0.4572)
		(drill 0.2032)
		(layers "F.Cu" "B.Cu")
		(net "TP_TRC_CPU0_PTI<31>")
	)
	(segment
		(start 356.870762 -270.19758)
		(end 356.871016 -270.197326)
		(width 0.12954)
		(layer "F.Cu")
		(net "TP_TRC_CPU0_PTI<30>")
	)
	(segment
		(start 356.871016 -270.197326)
		(end 356.871016 -269.661894)
		(width 0.12954)
		(layer "F.Cu")
		(net "TP_TRC_CPU0_PTI<30>")
	)
	(segment
		(start 356.871016 -269.661894)
		(end 356.870762 -269.66164)
		(width 0.12954)
		(layer "F.Cu")
		(net "TP_TRC_CPU0_PTI<30>")
	)
	(via
		(at 356.870762 -270.19758)
		(size 0.4572)
		(drill 0.2032)
		(layers "F.Cu" "B.Cu")
		(net "TP_TRC_CPU0_PTI<30>")
	)
	(segment
		(start 361.929934 -235.506006)
		(end 361.929934 -234.970066)
		(width 0.12954)
		(layer "F.Cu")
		(net "TP_TRC_CPU0_PTI<2>")
	)
	(via
		(at 361.929934 -234.970066)
		(size 0.4572)
		(drill 0.2032)
		(layers "F.Cu" "B.Cu")
		(net "TP_TRC_CPU0_PTI<2>")
	)
	(segment
		(start 356.401116 -268.84757)
		(end 356.401116 -269.383256)
		(width 0.12954)
		(layer "F.Cu")
		(net "TP_TRC_CPU0_PTI<29>")
	)
	(segment
		(start 356.401116 -269.383256)
		(end 356.400862 -269.38351)
		(width 0.12954)
		(layer "F.Cu")
		(net "TP_TRC_CPU0_PTI<29>")
	)
	(via
		(at 356.400862 -269.38351)
		(size 0.4572)
		(drill 0.2032)
		(layers "F.Cu" "B.Cu")
		(net "TP_TRC_CPU0_PTI<29>")
	)
	(segment
		(start 355.461062 -269.38351)
		(end 355.461316 -269.383256)
		(width 0.12954)
		(layer "F.Cu")
		(net "TP_TRC_CPU0_PTI<28>")
	)
	(segment
		(start 355.461316 -269.383256)
		(end 355.461316 -268.84757)
		(width 0.12954)
		(layer "F.Cu")
		(net "TP_TRC_CPU0_PTI<28>")
	)
	(via
		(at 355.461062 -269.38351)
		(size 0.4572)
		(drill 0.2032)
		(layers "F.Cu" "B.Cu")
		(net "TP_TRC_CPU0_PTI<28>")
	)
	(segment
		(start 354.521516 -269.383256)
		(end 354.521262 -269.38351)
		(width 0.12954)
		(layer "F.Cu")
		(net "TP_TRC_CPU0_PTI<27>")
	)
	(segment
		(start 354.521516 -268.84757)
		(end 354.521516 -269.383256)
		(width 0.12954)
		(layer "F.Cu")
		(net "TP_TRC_CPU0_PTI<27>")
	)
	(via
		(at 354.521262 -269.38351)
		(size 0.4572)
		(drill 0.2032)
		(layers "F.Cu" "B.Cu")
		(net "TP_TRC_CPU0_PTI<27>")
	)
	(segment
		(start 357.340662 -270.475456)
		(end 357.340662 -271.011396)
		(width 0.12954)
		(layer "F.Cu")
		(net "TP_TRC_CPU0_PTI<26>")
	)
	(via
		(at 357.340662 -271.011396)
		(size 0.4572)
		(drill 0.2032)
		(layers "F.Cu" "B.Cu")
		(net "TP_TRC_CPU0_PTI<26>")
	)
	(segment
		(start 356.870762 -271.289272)
		(end 356.871016 -271.825212)
		(width 0.12954)
		(layer "F.Cu")
		(net "TP_TRC_CPU0_PTI<25>")
	)
	(via
		(at 356.871016 -271.825212)
		(size 0.4572)
		(drill 0.2032)
		(layers "F.Cu" "B.Cu")
		(net "TP_TRC_CPU0_PTI<25>")
	)
	(segment
		(start 355.930962 -271.289272)
		(end 355.931216 -271.825212)
		(width 0.12954)
		(layer "F.Cu")
		(net "TP_TRC_CPU0_PTI<24>")
	)
	(via
		(at 355.931216 -271.825212)
		(size 0.4572)
		(drill 0.2032)
		(layers "F.Cu" "B.Cu")
		(net "TP_TRC_CPU0_PTI<24>")
	)
	(via
		(at 323.984112 -279.458674)
		(size 0.6604)
		(drill 0.3302)
		(layers "F.Cu" "B.Cu")
		(net "TP_TRC_CPU0_PTI<24>")
	)
	(segment
		(start 352.737166 -275.08073)
		(end 352.737166 -275.094954)
		(width 0.0889)
		(layer "B.Cu")
		(net "TP_TRC_CPU0_PTI<24>")
	)
	(segment
		(start 352.454464 -275.570442)
		(end 352.439732 -275.579078)
		(width 0.0889)
		(layer "B.Cu")
		(net "TP_TRC_CPU0_PTI<24>")
	)
	(segment
		(start 355.273864 -273.942556)
		(end 355.264974 -273.947636)
		(width 0.0889)
		(layer "B.Cu")
		(net "TP_TRC_CPU0_PTI<24>")
	)
	(segment
		(start 333.861156 -277.227792)
		(end 333.172054 -277.227792)
		(width 0.0889)
		(layer "B.Cu")
		(net "TP_TRC_CPU0_PTI<24>")
	)
	(segment
		(start 350.574864 -275.570442)
		(end 350.560132 -275.579078)
		(width 0.0889)
		(layer "B.Cu")
		(net "TP_TRC_CPU0_PTI<24>")
	)
	(segment
		(start 355.735128 -272.14449)
		(end 355.744018 -272.14957)
		(width 0.0889)
		(layer "B.Cu")
		(net "TP_TRC_CPU0_PTI<24>")
	)
	(segment
		(start 356.026212 -272.617184)
		(end 356.026212 -272.654776)
		(width 0.0889)
		(layer "B.Cu")
		(net "TP_TRC_CPU0_PTI<24>")
	)
	(segment
		(start 352.924618 -274.756372)
		(end 352.915728 -274.761452)
		(width 0.0889)
		(layer "B.Cu")
		(net "TP_TRC_CPU0_PTI<24>")
	)
	(segment
		(start 355.27996 -273.939)
		(end 355.273864 -273.942556)
		(width 0.0889)
		(layer "B.Cu")
		(net "TP_TRC_CPU0_PTI<24>")
	)
	(segment
		(start 345.875864 -275.570442)
		(end 345.861132 -275.579078)
		(width 0.0889)
		(layer "B.Cu")
		(net "TP_TRC_CPU0_PTI<24>")
	)
	(segment
		(start 343.996264 -275.570442)
		(end 343.981532 -275.579078)
		(width 0.0889)
		(layer "B.Cu")
		(net "TP_TRC_CPU0_PTI<24>")
	)
	(segment
		(start 339.297264 -275.570442)
		(end 339.282532 -275.579078)
		(width 0.0889)
		(layer "B.Cu")
		(net "TP_TRC_CPU0_PTI<24>")
	)
	(segment
		(start 355.931216 -271.825212)
		(end 355.618542 -271.825212)
		(width 0.0889)
		(layer "B.Cu")
		(net "TP_TRC_CPU0_PTI<24>")
	)
	(segment
		(start 336.477864 -275.570442)
		(end 336.46745 -275.576538)
		(width 0.0889)
		(layer "B.Cu")
		(net "TP_TRC_CPU0_PTI<24>")
	)
	(segment
		(start 355.086412 -274.266914)
		(end 355.086412 -274.282408)
		(width 0.0889)
		(layer "B.Cu")
		(net "TP_TRC_CPU0_PTI<24>")
	)
	(segment
		(start 342.116918 -275.570442)
		(end 342.106504 -275.576538)
		(width 0.0889)
		(layer "B.Cu")
		(net "TP_TRC_CPU0_PTI<24>")
	)
	(segment
		(start 341.176864 -275.570442)
		(end 341.162132 -275.579078)
		(width 0.0889)
		(layer "B.Cu")
		(net "TP_TRC_CPU0_PTI<24>")
	)
	(segment
		(start 332.73619 -277.663656)
		(end 331.392276 -279.00757)
		(width 0.12954)
		(layer "B.Cu")
		(net "TP_TRC_CPU0_PTI<24>")
	)
	(segment
		(start 348.695518 -275.570442)
		(end 348.685104 -275.576538)
		(width 0.0889)
		(layer "B.Cu")
		(net "TP_TRC_CPU0_PTI<24>")
	)
	(segment
		(start 354.248974 -274.762468)
		(end 354.23856 -274.756372)
		(width 0.0889)
		(layer "B.Cu")
		(net "TP_TRC_CPU0_PTI<24>")
	)
	(segment
		(start 353.309428 -274.762468)
		(end 353.299014 -274.756372)
		(width 0.0889)
		(layer "B.Cu")
		(net "TP_TRC_CPU0_PTI<24>")
	)
	(segment
		(start 349.635064 -275.570442)
		(end 349.62465 -275.576538)
		(width 0.0889)
		(layer "B.Cu")
		(net "TP_TRC_CPU0_PTI<24>")
	)
	(segment
		(start 355.618542 -271.825212)
		(end 355.561138 -271.882616)
		(width 0.0889)
		(layer "B.Cu")
		(net "TP_TRC_CPU0_PTI<24>")
	)
	(segment
		(start 335.459578 -275.62937)
		(end 333.861156 -277.227792)
		(width 0.0889)
		(layer "B.Cu")
		(net "TP_TRC_CPU0_PTI<24>")
	)
	(segment
		(start 333.172054 -277.227792)
		(end 332.73619 -277.663656)
		(width 0.0889)
		(layer "B.Cu")
		(net "TP_TRC_CPU0_PTI<24>")
	)
	(segment
		(start 344.936064 -275.570442)
		(end 344.921332 -275.579078)
		(width 0.0889)
		(layer "B.Cu")
		(net "TP_TRC_CPU0_PTI<24>")
	)
	(segment
		(start 351.514664 -275.570442)
		(end 351.499932 -275.579078)
		(width 0.0889)
		(layer "B.Cu")
		(net "TP_TRC_CPU0_PTI<24>")
	)
	(segment
		(start 331.392276 -279.00757)
		(end 324.435216 -279.00757)
		(width 0.12954)
		(layer "B.Cu")
		(net "TP_TRC_CPU0_PTI<24>")
	)
	(segment
		(start 347.755464 -275.570442)
		(end 347.740732 -275.579078)
		(width 0.0889)
		(layer "B.Cu")
		(net "TP_TRC_CPU0_PTI<24>")
	)
	(segment
		(start 343.056464 -275.570442)
		(end 343.04605 -275.576538)
		(width 0.0889)
		(layer "B.Cu")
		(net "TP_TRC_CPU0_PTI<24>")
	)
	(segment
		(start 324.435216 -279.00757)
		(end 323.984112 -279.458674)
		(width 0.12954)
		(layer "B.Cu")
		(net "TP_TRC_CPU0_PTI<24>")
	)
	(segment
		(start 355.744018 -273.12874)
		(end 355.735128 -273.13382)
		(width 0.0889)
		(layer "B.Cu")
		(net "TP_TRC_CPU0_PTI<24>")
	)
	(arc
		(start 350.94926 -275.570442)
		(mid 350.762062 -275.520299)
		(end 350.574864 -275.570442)
		(width 0.0889)
		(layer "B.Cu")
		(net "TP_TRC_CPU0_PTI<24>")
	)
	(arc
		(start 348.12986 -275.570442)
		(mid 347.942662 -275.520299)
		(end 347.755464 -275.570442)
		(width 0.0889)
		(layer "B.Cu")
		(net "TP_TRC_CPU0_PTI<24>")
	)
	(arc
		(start 342.491314 -275.570442)
		(mid 342.304116 -275.520299)
		(end 342.116918 -275.570442)
		(width 0.0889)
		(layer "B.Cu")
		(net "TP_TRC_CPU0_PTI<24>")
	)
	(arc
		(start 338.73186 -275.570442)
		(mid 338.544662 -275.520299)
		(end 338.357464 -275.570442)
		(width 0.0889)
		(layer "B.Cu")
		(net "TP_TRC_CPU0_PTI<24>")
	)
	(arc
		(start 336.46745 -275.576538)
		(mid 336.189018 -275.646352)
		(end 335.912206 -275.570442)
		(width 0.0889)
		(layer "B.Cu")
		(net "TP_TRC_CPU0_PTI<24>")
	)
	(arc
		(start 354.23856 -274.756372)
		(mid 354.051362 -274.706229)
		(end 353.864164 -274.756372)
		(width 0.0889)
		(layer "B.Cu")
		(net "TP_TRC_CPU0_PTI<24>")
	)
	(arc
		(start 335.912206 -275.570442)
		(mid 335.725008 -275.520299)
		(end 335.53781 -275.570442)
		(width 0.0889)
		(layer "B.Cu")
		(net "TP_TRC_CPU0_PTI<24>")
	)
	(arc
		(start 340.61146 -275.570442)
		(mid 340.424262 -275.520299)
		(end 340.237064 -275.570442)
		(width 0.0889)
		(layer "B.Cu")
		(net "TP_TRC_CPU0_PTI<24>")
	)
	(arc
		(start 344.37066 -275.570442)
		(mid 344.183462 -275.520299)
		(end 343.996264 -275.570442)
		(width 0.0889)
		(layer "B.Cu")
		(net "TP_TRC_CPU0_PTI<24>")
	)
	(arc
		(start 343.981532 -275.579078)
		(mid 343.705091 -275.646244)
		(end 343.43086 -275.570442)
		(width 0.0889)
		(layer "B.Cu")
		(net "TP_TRC_CPU0_PTI<24>")
	)
	(arc
		(start 336.85226 -275.570442)
		(mid 336.665062 -275.520299)
		(end 336.477864 -275.570442)
		(width 0.0889)
		(layer "B.Cu")
		(net "TP_TRC_CPU0_PTI<24>")
	)
	(arc
		(start 352.439732 -275.579078)
		(mid 352.163291 -275.646244)
		(end 351.88906 -275.570442)
		(width 0.0889)
		(layer "B.Cu")
		(net "TP_TRC_CPU0_PTI<24>")
	)
	(arc
		(start 353.299014 -274.756372)
		(mid 353.111816 -274.706229)
		(end 352.924618 -274.756372)
		(width 0.0889)
		(layer "B.Cu")
		(net "TP_TRC_CPU0_PTI<24>")
	)
	(arc
		(start 335.53781 -275.570442)
		(mid 335.496752 -275.597329)
		(end 335.459578 -275.62937)
		(width 0.0889)
		(layer "B.Cu")
		(net "TP_TRC_CPU0_PTI<24>")
	)
	(arc
		(start 351.88906 -275.570442)
		(mid 351.701862 -275.520299)
		(end 351.514664 -275.570442)
		(width 0.0889)
		(layer "B.Cu")
		(net "TP_TRC_CPU0_PTI<24>")
	)
	(arc
		(start 349.62465 -275.576538)
		(mid 349.346472 -275.64623)
		(end 349.069914 -275.570442)
		(width 0.0889)
		(layer "B.Cu")
		(net "TP_TRC_CPU0_PTI<24>")
	)
	(arc
		(start 348.685104 -275.576538)
		(mid 348.406672 -275.646352)
		(end 348.12986 -275.570442)
		(width 0.0889)
		(layer "B.Cu")
		(net "TP_TRC_CPU0_PTI<24>")
	)
	(arc
		(start 355.556566 -273.453098)
		(mid 355.482575 -273.732664)
		(end 355.27996 -273.939)
		(width 0.0889)
		(layer "B.Cu")
		(net "TP_TRC_CPU0_PTI<24>")
	)
	(arc
		(start 343.04605 -275.576538)
		(mid 342.767872 -275.64623)
		(end 342.491314 -275.570442)
		(width 0.0889)
		(layer "B.Cu")
		(net "TP_TRC_CPU0_PTI<24>")
	)
	(arc
		(start 350.560132 -275.579078)
		(mid 350.283691 -275.646244)
		(end 350.00946 -275.570442)
		(width 0.0889)
		(layer "B.Cu")
		(net "TP_TRC_CPU0_PTI<24>")
	)
	(arc
		(start 352.915728 -274.761452)
		(mid 352.784814 -274.897812)
		(end 352.737166 -275.08073)
		(width 0.0889)
		(layer "B.Cu")
		(net "TP_TRC_CPU0_PTI<24>")
	)
	(arc
		(start 337.79206 -275.570442)
		(mid 337.604862 -275.520299)
		(end 337.417664 -275.570442)
		(width 0.0889)
		(layer "B.Cu")
		(net "TP_TRC_CPU0_PTI<24>")
	)
	(arc
		(start 355.744018 -272.14957)
		(mid 355.9453 -272.347057)
		(end 356.026212 -272.617184)
		(width 0.0889)
		(layer "B.Cu")
		(net "TP_TRC_CPU0_PTI<24>")
	)
	(arc
		(start 346.25026 -275.570442)
		(mid 346.063062 -275.520299)
		(end 345.875864 -275.570442)
		(width 0.0889)
		(layer "B.Cu")
		(net "TP_TRC_CPU0_PTI<24>")
	)
	(arc
		(start 340.237064 -275.570442)
		(mid 339.954362 -275.646184)
		(end 339.67166 -275.570442)
		(width 0.0889)
		(layer "B.Cu")
		(net "TP_TRC_CPU0_PTI<24>")
	)
	(arc
		(start 355.264974 -273.947636)
		(mid 355.13406 -274.083996)
		(end 355.086412 -274.266914)
		(width 0.0889)
		(layer "B.Cu")
		(net "TP_TRC_CPU0_PTI<24>")
	)
	(arc
		(start 355.561138 -271.882616)
		(mid 355.619294 -272.032729)
		(end 355.735128 -272.14449)
		(width 0.0889)
		(layer "B.Cu")
		(net "TP_TRC_CPU0_PTI<24>")
	)
	(arc
		(start 338.357464 -275.570442)
		(mid 338.074762 -275.646184)
		(end 337.79206 -275.570442)
		(width 0.0889)
		(layer "B.Cu")
		(net "TP_TRC_CPU0_PTI<24>")
	)
	(arc
		(start 347.19006 -275.570442)
		(mid 347.002862 -275.520299)
		(end 346.815664 -275.570442)
		(width 0.0889)
		(layer "B.Cu")
		(net "TP_TRC_CPU0_PTI<24>")
	)
	(arc
		(start 353.864164 -274.756372)
		(mid 353.587605 -274.832115)
		(end 353.309428 -274.762468)
		(width 0.0889)
		(layer "B.Cu")
		(net "TP_TRC_CPU0_PTI<24>")
	)
	(arc
		(start 341.55126 -275.570442)
		(mid 341.364062 -275.520299)
		(end 341.176864 -275.570442)
		(width 0.0889)
		(layer "B.Cu")
		(net "TP_TRC_CPU0_PTI<24>")
	)
	(arc
		(start 352.737166 -275.094954)
		(mid 352.657947 -275.369639)
		(end 352.454464 -275.570442)
		(width 0.0889)
		(layer "B.Cu")
		(net "TP_TRC_CPU0_PTI<24>")
	)
	(arc
		(start 343.43086 -275.570442)
		(mid 343.243662 -275.520299)
		(end 343.056464 -275.570442)
		(width 0.0889)
		(layer "B.Cu")
		(net "TP_TRC_CPU0_PTI<24>")
	)
	(arc
		(start 356.026212 -272.654776)
		(mid 355.946842 -272.92851)
		(end 355.744018 -273.12874)
		(width 0.0889)
		(layer "B.Cu")
		(net "TP_TRC_CPU0_PTI<24>")
	)
	(arc
		(start 344.921332 -275.579078)
		(mid 344.644891 -275.646244)
		(end 344.37066 -275.570442)
		(width 0.0889)
		(layer "B.Cu")
		(net "TP_TRC_CPU0_PTI<24>")
	)
	(arc
		(start 354.804218 -274.756372)
		(mid 354.527405 -274.832242)
		(end 354.248974 -274.762468)
		(width 0.0889)
		(layer "B.Cu")
		(net "TP_TRC_CPU0_PTI<24>")
	)
	(arc
		(start 341.162132 -275.579078)
		(mid 340.885691 -275.646244)
		(end 340.61146 -275.570442)
		(width 0.0889)
		(layer "B.Cu")
		(net "TP_TRC_CPU0_PTI<24>")
	)
	(arc
		(start 355.086412 -274.282408)
		(mid 355.007042 -274.556142)
		(end 354.804218 -274.756372)
		(width 0.0889)
		(layer "B.Cu")
		(net "TP_TRC_CPU0_PTI<24>")
	)
	(arc
		(start 347.740732 -275.579078)
		(mid 347.464291 -275.646244)
		(end 347.19006 -275.570442)
		(width 0.0889)
		(layer "B.Cu")
		(net "TP_TRC_CPU0_PTI<24>")
	)
	(arc
		(start 346.815664 -275.570442)
		(mid 346.532962 -275.646184)
		(end 346.25026 -275.570442)
		(width 0.0889)
		(layer "B.Cu")
		(net "TP_TRC_CPU0_PTI<24>")
	)
	(arc
		(start 345.861132 -275.579078)
		(mid 345.584691 -275.646244)
		(end 345.31046 -275.570442)
		(width 0.0889)
		(layer "B.Cu")
		(net "TP_TRC_CPU0_PTI<24>")
	)
	(arc
		(start 350.00946 -275.570442)
		(mid 349.822262 -275.520299)
		(end 349.635064 -275.570442)
		(width 0.0889)
		(layer "B.Cu")
		(net "TP_TRC_CPU0_PTI<24>")
	)
	(arc
		(start 339.67166 -275.570442)
		(mid 339.484462 -275.520299)
		(end 339.297264 -275.570442)
		(width 0.0889)
		(layer "B.Cu")
		(net "TP_TRC_CPU0_PTI<24>")
	)
	(arc
		(start 349.069914 -275.570442)
		(mid 348.882716 -275.520299)
		(end 348.695518 -275.570442)
		(width 0.0889)
		(layer "B.Cu")
		(net "TP_TRC_CPU0_PTI<24>")
	)
	(arc
		(start 351.499932 -275.579078)
		(mid 351.223491 -275.646244)
		(end 350.94926 -275.570442)
		(width 0.0889)
		(layer "B.Cu")
		(net "TP_TRC_CPU0_PTI<24>")
	)
	(arc
		(start 337.417664 -275.570442)
		(mid 337.134962 -275.646184)
		(end 336.85226 -275.570442)
		(width 0.0889)
		(layer "B.Cu")
		(net "TP_TRC_CPU0_PTI<24>")
	)
	(arc
		(start 339.282532 -275.579078)
		(mid 339.006091 -275.646244)
		(end 338.73186 -275.570442)
		(width 0.0889)
		(layer "B.Cu")
		(net "TP_TRC_CPU0_PTI<24>")
	)
	(arc
		(start 342.106504 -275.576538)
		(mid 341.828072 -275.646352)
		(end 341.55126 -275.570442)
		(width 0.0889)
		(layer "B.Cu")
		(net "TP_TRC_CPU0_PTI<24>")
	)
	(arc
		(start 345.31046 -275.570442)
		(mid 345.123262 -275.520299)
		(end 344.936064 -275.570442)
		(width 0.0889)
		(layer "B.Cu")
		(net "TP_TRC_CPU0_PTI<24>")
	)
	(arc
		(start 355.735128 -273.13382)
		(mid 355.604214 -273.27018)
		(end 355.556566 -273.453098)
		(width 0.0889)
		(layer "B.Cu")
		(net "TP_TRC_CPU0_PTI<24>")
	)
	(segment
		(start 353.111562 -269.66164)
		(end 353.111562 -270.197326)
		(width 0.12954)
		(layer "F.Cu")
		(net "TP_TRC_CPU0_PTI<23>")
	)
	(segment
		(start 353.111562 -270.197326)
		(end 353.111816 -270.19758)
		(width 0.12954)
		(layer "F.Cu")
		(net "TP_TRC_CPU0_PTI<23>")
	)
	(via
		(at 353.111816 -270.19758)
		(size 0.4572)
		(drill 0.2032)
		(layers "F.Cu" "B.Cu")
		(net "TP_TRC_CPU0_PTI<23>")
	)
	(segment
		(start 354.521516 -270.475456)
		(end 354.521516 -271.011142)
		(width 0.12954)
		(layer "F.Cu")
		(net "TP_TRC_CPU0_PTI<22>")
	)
	(segment
		(start 354.521516 -271.011142)
		(end 354.521262 -271.011396)
		(width 0.12954)
		(layer "F.Cu")
		(net "TP_TRC_CPU0_PTI<22>")
	)
	(via
		(at 354.521262 -271.011396)
		(size 0.4572)
		(drill 0.2032)
		(layers "F.Cu" "B.Cu")
		(net "TP_TRC_CPU0_PTI<22>")
	)
	(segment
		(start 352.641916 -270.475456)
		(end 352.641662 -270.47571)
		(width 0.12954)
		(layer "F.Cu")
		(net "TP_TRC_CPU0_PTI<21>")
	)
	(segment
		(start 352.641662 -270.47571)
		(end 352.641662 -271.011396)
		(width 0.12954)
		(layer "F.Cu")
		(net "TP_TRC_CPU0_PTI<21>")
	)
	(via
		(at 352.641662 -271.011396)
		(size 0.4572)
		(drill 0.2032)
		(layers "F.Cu" "B.Cu")
		(net "TP_TRC_CPU0_PTI<21>")
	)
	(segment
		(start 354.991162 -271.289272)
		(end 354.991162 -271.824958)
		(width 0.12954)
		(layer "F.Cu")
		(net "TP_TRC_CPU0_PTI<20>")
	)
	(segment
		(start 354.991162 -271.824958)
		(end 354.991416 -271.825212)
		(width 0.12954)
		(layer "F.Cu")
		(net "TP_TRC_CPU0_PTI<20>")
	)
	(via
		(at 322.714112 -279.458674)
		(size 0.6604)
		(drill 0.3302)
		(layers "F.Cu" "B.Cu")
		(net "TP_TRC_CPU0_PTI<20>")
	)
	(via
		(at 354.991416 -271.825212)
		(size 0.4572)
		(drill 0.2032)
		(layers "F.Cu" "B.Cu")
		(net "TP_TRC_CPU0_PTI<20>")
	)
	(segment
		(start 331.259434 -278.607774)
		(end 323.565012 -278.607774)
		(width 0.12954)
		(layer "B.Cu")
		(net "TP_TRC_CPU0_PTI<20>")
	)
	(segment
		(start 355.187504 -273.772376)
		(end 355.178614 -273.777456)
		(width 0.0889)
		(layer "B.Cu")
		(net "TP_TRC_CPU0_PTI<20>")
	)
	(segment
		(start 355.178614 -273.777456)
		(end 355.172518 -273.781012)
		(width 0.0889)
		(layer "B.Cu")
		(net "TP_TRC_CPU0_PTI<20>")
	)
	(segment
		(start 340.151974 -275.398992)
		(end 340.14156 -275.405088)
		(width 0.0889)
		(layer "B.Cu")
		(net "TP_TRC_CPU0_PTI<20>")
	)
	(segment
		(start 352.368104 -275.400008)
		(end 352.359214 -275.405088)
		(width 0.0889)
		(layer "B.Cu")
		(net "TP_TRC_CPU0_PTI<20>")
	)
	(segment
		(start 351.434146 -275.396452)
		(end 351.419414 -275.405088)
		(width 0.0889)
		(layer "B.Cu")
		(net "TP_TRC_CPU0_PTI<20>")
	)
	(segment
		(start 342.975946 -275.396452)
		(end 342.961214 -275.405088)
		(width 0.0889)
		(layer "B.Cu")
		(net "TP_TRC_CPU0_PTI<20>")
	)
	(segment
		(start 355.65715 -272.95856)
		(end 355.64826 -272.96364)
		(width 0.0889)
		(layer "B.Cu")
		(net "TP_TRC_CPU0_PTI<20>")
	)
	(segment
		(start 339.212428 -275.398992)
		(end 339.202014 -275.405088)
		(width 0.0889)
		(layer "B.Cu")
		(net "TP_TRC_CPU0_PTI<20>")
	)
	(segment
		(start 355.366066 -273.437604)
		(end 355.366066 -273.453098)
		(width 0.0889)
		(layer "B.Cu")
		(net "TP_TRC_CPU0_PTI<20>")
	)
	(segment
		(start 344.855546 -275.396452)
		(end 344.840814 -275.405088)
		(width 0.0889)
		(layer "B.Cu")
		(net "TP_TRC_CPU0_PTI<20>")
	)
	(segment
		(start 338.272374 -275.398992)
		(end 338.26196 -275.405088)
		(width 0.0889)
		(layer "B.Cu")
		(net "TP_TRC_CPU0_PTI<20>")
	)
	(segment
		(start 355.64826 -272.314924)
		(end 355.65715 -272.320004)
		(width 0.0889)
		(layer "B.Cu")
		(net "TP_TRC_CPU0_PTI<20>")
	)
	(segment
		(start 354.71735 -274.586192)
		(end 354.70846 -274.591272)
		(width 0.0889)
		(layer "B.Cu")
		(net "TP_TRC_CPU0_PTI<20>")
	)
	(segment
		(start 323.565012 -278.607774)
		(end 322.714112 -279.458674)
		(width 0.12954)
		(layer "B.Cu")
		(net "TP_TRC_CPU0_PTI<20>")
	)
	(segment
		(start 350.494346 -275.396452)
		(end 350.479614 -275.405088)
		(width 0.0889)
		(layer "B.Cu")
		(net "TP_TRC_CPU0_PTI<20>")
	)
	(segment
		(start 343.915746 -275.396452)
		(end 343.901014 -275.405088)
		(width 0.0889)
		(layer "B.Cu")
		(net "TP_TRC_CPU0_PTI<20>")
	)
	(segment
		(start 349.554546 -275.396452)
		(end 349.539814 -275.405088)
		(width 0.0889)
		(layer "B.Cu")
		(net "TP_TRC_CPU0_PTI<20>")
	)
	(segment
		(start 353.394264 -274.591272)
		(end 353.379532 -274.582636)
		(width 0.0889)
		(layer "B.Cu")
		(net "TP_TRC_CPU0_PTI<20>")
	)
	(segment
		(start 354.991416 -271.825212)
		(end 355.30409 -271.825212)
		(width 0.0889)
		(layer "B.Cu")
		(net "TP_TRC_CPU0_PTI<20>")
	)
	(segment
		(start 335.324958 -275.49475)
		(end 333.782162 -277.037546)
		(width 0.0889)
		(layer "B.Cu")
		(net "TP_TRC_CPU0_PTI<20>")
	)
	(segment
		(start 341.096346 -275.396452)
		(end 341.081614 -275.405088)
		(width 0.0889)
		(layer "B.Cu")
		(net "TP_TRC_CPU0_PTI<20>")
	)
	(segment
		(start 333.782162 -277.037546)
		(end 332.829662 -277.037546)
		(width 0.0889)
		(layer "B.Cu")
		(net "TP_TRC_CPU0_PTI<20>")
	)
	(segment
		(start 355.30409 -271.825212)
		(end 355.369368 -271.89049)
		(width 0.0889)
		(layer "B.Cu")
		(net "TP_TRC_CPU0_PTI<20>")
	)
	(segment
		(start 345.791028 -275.398992)
		(end 345.780614 -275.405088)
		(width 0.0889)
		(layer "B.Cu")
		(net "TP_TRC_CPU0_PTI<20>")
	)
	(segment
		(start 347.674946 -275.396452)
		(end 347.660214 -275.405088)
		(width 0.0889)
		(layer "B.Cu")
		(net "TP_TRC_CPU0_PTI<20>")
	)
	(segment
		(start 332.829662 -277.037546)
		(end 332.604364 -277.262844)
		(width 0.0889)
		(layer "B.Cu")
		(net "TP_TRC_CPU0_PTI<20>")
	)
	(segment
		(start 332.604364 -277.262844)
		(end 331.259434 -278.607774)
		(width 0.12954)
		(layer "B.Cu")
		(net "TP_TRC_CPU0_PTI<20>")
	)
	(segment
		(start 346.730574 -275.398992)
		(end 346.72016 -275.405088)
		(width 0.0889)
		(layer "B.Cu")
		(net "TP_TRC_CPU0_PTI<20>")
	)
	(segment
		(start 352.546666 -275.065236)
		(end 352.546666 -275.08073)
		(width 0.0889)
		(layer "B.Cu")
		(net "TP_TRC_CPU0_PTI<20>")
	)
	(arc
		(start 353.76866 -274.591272)
		(mid 353.581462 -274.641415)
		(end 353.394264 -274.591272)
		(width 0.0889)
		(layer "B.Cu")
		(net "TP_TRC_CPU0_PTI<20>")
	)
	(arc
		(start 337.887564 -275.405088)
		(mid 337.604862 -275.329346)
		(end 337.32216 -275.405088)
		(width 0.0889)
		(layer "B.Cu")
		(net "TP_TRC_CPU0_PTI<20>")
	)
	(arc
		(start 341.081614 -275.405088)
		(mid 340.894416 -275.455231)
		(end 340.707218 -275.405088)
		(width 0.0889)
		(layer "B.Cu")
		(net "TP_TRC_CPU0_PTI<20>")
	)
	(arc
		(start 352.82886 -274.591272)
		(mid 352.626037 -274.791503)
		(end 352.546666 -275.065236)
		(width 0.0889)
		(layer "B.Cu")
		(net "TP_TRC_CPU0_PTI<20>")
	)
	(arc
		(start 338.26196 -275.405088)
		(mid 338.074762 -275.455231)
		(end 337.887564 -275.405088)
		(width 0.0889)
		(layer "B.Cu")
		(net "TP_TRC_CPU0_PTI<20>")
	)
	(arc
		(start 353.379532 -274.582636)
		(mid 353.103057 -274.515316)
		(end 352.82886 -274.591272)
		(width 0.0889)
		(layer "B.Cu")
		(net "TP_TRC_CPU0_PTI<20>")
	)
	(arc
		(start 355.65715 -272.320004)
		(mid 355.835747 -272.639282)
		(end 355.65715 -272.95856)
		(width 0.0889)
		(layer "B.Cu")
		(net "TP_TRC_CPU0_PTI<20>")
	)
	(arc
		(start 342.586818 -275.405088)
		(mid 342.304116 -275.329346)
		(end 342.021414 -275.405088)
		(width 0.0889)
		(layer "B.Cu")
		(net "TP_TRC_CPU0_PTI<20>")
	)
	(arc
		(start 343.901014 -275.405088)
		(mid 343.713816 -275.455231)
		(end 343.526618 -275.405088)
		(width 0.0889)
		(layer "B.Cu")
		(net "TP_TRC_CPU0_PTI<20>")
	)
	(arc
		(start 355.366066 -273.453098)
		(mid 355.318387 -273.635998)
		(end 355.187504 -273.772376)
		(width 0.0889)
		(layer "B.Cu")
		(net "TP_TRC_CPU0_PTI<20>")
	)
	(arc
		(start 355.172518 -273.781012)
		(mid 354.969931 -273.987363)
		(end 354.895912 -274.266914)
		(width 0.0889)
		(layer "B.Cu")
		(net "TP_TRC_CPU0_PTI<20>")
	)
	(arc
		(start 345.406218 -275.405088)
		(mid 345.131989 -275.329163)
		(end 344.855546 -275.396452)
		(width 0.0889)
		(layer "B.Cu")
		(net "TP_TRC_CPU0_PTI<20>")
	)
	(arc
		(start 345.780614 -275.405088)
		(mid 345.593416 -275.455231)
		(end 345.406218 -275.405088)
		(width 0.0889)
		(layer "B.Cu")
		(net "TP_TRC_CPU0_PTI<20>")
	)
	(arc
		(start 354.895912 -274.266914)
		(mid 354.848233 -274.449814)
		(end 354.71735 -274.586192)
		(width 0.0889)
		(layer "B.Cu")
		(net "TP_TRC_CPU0_PTI<20>")
	)
	(arc
		(start 351.984818 -275.405088)
		(mid 351.710589 -275.329163)
		(end 351.434146 -275.396452)
		(width 0.0889)
		(layer "B.Cu")
		(net "TP_TRC_CPU0_PTI<20>")
	)
	(arc
		(start 350.105218 -275.405088)
		(mid 349.830989 -275.329163)
		(end 349.554546 -275.396452)
		(width 0.0889)
		(layer "B.Cu")
		(net "TP_TRC_CPU0_PTI<20>")
	)
	(arc
		(start 349.539814 -275.405088)
		(mid 349.352616 -275.455231)
		(end 349.165418 -275.405088)
		(width 0.0889)
		(layer "B.Cu")
		(net "TP_TRC_CPU0_PTI<20>")
	)
	(arc
		(start 339.202014 -275.405088)
		(mid 339.014816 -275.455231)
		(end 338.827618 -275.405088)
		(width 0.0889)
		(layer "B.Cu")
		(net "TP_TRC_CPU0_PTI<20>")
	)
	(arc
		(start 341.647018 -275.405088)
		(mid 341.372789 -275.329163)
		(end 341.096346 -275.396452)
		(width 0.0889)
		(layer "B.Cu")
		(net "TP_TRC_CPU0_PTI<20>")
	)
	(arc
		(start 337.32216 -275.405088)
		(mid 337.134962 -275.455231)
		(end 336.947764 -275.405088)
		(width 0.0889)
		(layer "B.Cu")
		(net "TP_TRC_CPU0_PTI<20>")
	)
	(arc
		(start 344.840814 -275.405088)
		(mid 344.653616 -275.455231)
		(end 344.466418 -275.405088)
		(width 0.0889)
		(layer "B.Cu")
		(net "TP_TRC_CPU0_PTI<20>")
	)
	(arc
		(start 338.827618 -275.405088)
		(mid 338.550805 -275.329252)
		(end 338.272374 -275.398992)
		(width 0.0889)
		(layer "B.Cu")
		(net "TP_TRC_CPU0_PTI<20>")
	)
	(arc
		(start 340.14156 -275.405088)
		(mid 339.954362 -275.455231)
		(end 339.767164 -275.405088)
		(width 0.0889)
		(layer "B.Cu")
		(net "TP_TRC_CPU0_PTI<20>")
	)
	(arc
		(start 336.947764 -275.405088)
		(mid 336.665062 -275.329346)
		(end 336.38236 -275.405088)
		(width 0.0889)
		(layer "B.Cu")
		(net "TP_TRC_CPU0_PTI<20>")
	)
	(arc
		(start 352.359214 -275.405088)
		(mid 352.172016 -275.455231)
		(end 351.984818 -275.405088)
		(width 0.0889)
		(layer "B.Cu")
		(net "TP_TRC_CPU0_PTI<20>")
	)
	(arc
		(start 348.600014 -275.405088)
		(mid 348.412816 -275.455231)
		(end 348.225618 -275.405088)
		(width 0.0889)
		(layer "B.Cu")
		(net "TP_TRC_CPU0_PTI<20>")
	)
	(arc
		(start 347.660214 -275.405088)
		(mid 347.473016 -275.455231)
		(end 347.285818 -275.405088)
		(width 0.0889)
		(layer "B.Cu")
		(net "TP_TRC_CPU0_PTI<20>")
	)
	(arc
		(start 340.707218 -275.405088)
		(mid 340.430405 -275.329252)
		(end 340.151974 -275.398992)
		(width 0.0889)
		(layer "B.Cu")
		(net "TP_TRC_CPU0_PTI<20>")
	)
	(arc
		(start 336.007964 -275.405088)
		(mid 335.651207 -275.333893)
		(end 335.324958 -275.49475)
		(width 0.0889)
		(layer "B.Cu")
		(net "TP_TRC_CPU0_PTI<20>")
	)
	(arc
		(start 354.70846 -274.591272)
		(mid 354.521262 -274.641415)
		(end 354.334064 -274.591272)
		(width 0.0889)
		(layer "B.Cu")
		(net "TP_TRC_CPU0_PTI<20>")
	)
	(arc
		(start 343.526618 -275.405088)
		(mid 343.252389 -275.329163)
		(end 342.975946 -275.396452)
		(width 0.0889)
		(layer "B.Cu")
		(net "TP_TRC_CPU0_PTI<20>")
	)
	(arc
		(start 346.72016 -275.405088)
		(mid 346.532962 -275.455231)
		(end 346.345764 -275.405088)
		(width 0.0889)
		(layer "B.Cu")
		(net "TP_TRC_CPU0_PTI<20>")
	)
	(arc
		(start 342.961214 -275.405088)
		(mid 342.774016 -275.455231)
		(end 342.586818 -275.405088)
		(width 0.0889)
		(layer "B.Cu")
		(net "TP_TRC_CPU0_PTI<20>")
	)
	(arc
		(start 349.165418 -275.405088)
		(mid 348.882716 -275.329346)
		(end 348.600014 -275.405088)
		(width 0.0889)
		(layer "B.Cu")
		(net "TP_TRC_CPU0_PTI<20>")
	)
	(arc
		(start 351.045018 -275.405088)
		(mid 350.770789 -275.329163)
		(end 350.494346 -275.396452)
		(width 0.0889)
		(layer "B.Cu")
		(net "TP_TRC_CPU0_PTI<20>")
	)
	(arc
		(start 351.419414 -275.405088)
		(mid 351.232216 -275.455231)
		(end 351.045018 -275.405088)
		(width 0.0889)
		(layer "B.Cu")
		(net "TP_TRC_CPU0_PTI<20>")
	)
	(arc
		(start 336.38236 -275.405088)
		(mid 336.195162 -275.455231)
		(end 336.007964 -275.405088)
		(width 0.0889)
		(layer "B.Cu")
		(net "TP_TRC_CPU0_PTI<20>")
	)
	(arc
		(start 347.285818 -275.405088)
		(mid 347.009005 -275.329252)
		(end 346.730574 -275.398992)
		(width 0.0889)
		(layer "B.Cu")
		(net "TP_TRC_CPU0_PTI<20>")
	)
	(arc
		(start 354.334064 -274.591272)
		(mid 354.051362 -274.515496)
		(end 353.76866 -274.591272)
		(width 0.0889)
		(layer "B.Cu")
		(net "TP_TRC_CPU0_PTI<20>")
	)
	(arc
		(start 355.369368 -271.89049)
		(mid 355.458482 -272.135787)
		(end 355.64826 -272.314924)
		(width 0.0889)
		(layer "B.Cu")
		(net "TP_TRC_CPU0_PTI<20>")
	)
	(arc
		(start 348.225618 -275.405088)
		(mid 347.951389 -275.329163)
		(end 347.674946 -275.396452)
		(width 0.0889)
		(layer "B.Cu")
		(net "TP_TRC_CPU0_PTI<20>")
	)
	(arc
		(start 346.345764 -275.405088)
		(mid 346.069205 -275.329379)
		(end 345.791028 -275.398992)
		(width 0.0889)
		(layer "B.Cu")
		(net "TP_TRC_CPU0_PTI<20>")
	)
	(arc
		(start 344.466418 -275.405088)
		(mid 344.192189 -275.329163)
		(end 343.915746 -275.396452)
		(width 0.0889)
		(layer "B.Cu")
		(net "TP_TRC_CPU0_PTI<20>")
	)
	(arc
		(start 350.479614 -275.405088)
		(mid 350.292416 -275.455231)
		(end 350.105218 -275.405088)
		(width 0.0889)
		(layer "B.Cu")
		(net "TP_TRC_CPU0_PTI<20>")
	)
	(arc
		(start 355.64826 -272.96364)
		(mid 355.445437 -273.163871)
		(end 355.366066 -273.437604)
		(width 0.0889)
		(layer "B.Cu")
		(net "TP_TRC_CPU0_PTI<20>")
	)
	(arc
		(start 342.021414 -275.405088)
		(mid 341.834216 -275.455231)
		(end 341.647018 -275.405088)
		(width 0.0889)
		(layer "B.Cu")
		(net "TP_TRC_CPU0_PTI<20>")
	)
	(arc
		(start 339.767164 -275.405088)
		(mid 339.490605 -275.329379)
		(end 339.212428 -275.398992)
		(width 0.0889)
		(layer "B.Cu")
		(net "TP_TRC_CPU0_PTI<20>")
	)
	(arc
		(start 352.546666 -275.08073)
		(mid 352.498987 -275.26363)
		(end 352.368104 -275.400008)
		(width 0.0889)
		(layer "B.Cu")
		(net "TP_TRC_CPU0_PTI<20>")
	)
	(segment
		(start 354.051362 -271.289272)
		(end 354.051616 -271.289526)
		(width 0.12954)
		(layer "F.Cu")
		(net "TP_TRC_CPU0_PTI<19>")
	)
	(segment
		(start 354.051616 -271.289526)
		(end 354.051616 -271.825212)
		(width 0.12954)
		(layer "F.Cu")
		(net "TP_TRC_CPU0_PTI<19>")
	)
	(via
		(at 354.051616 -271.825212)
		(size 0.4572)
		(drill 0.2032)
		(layers "F.Cu" "B.Cu")
		(net "TP_TRC_CPU0_PTI<19>")
	)
	(segment
		(start 353.111816 -271.289526)
		(end 353.111816 -271.825212)
		(width 0.12954)
		(layer "F.Cu")
		(net "TP_TRC_CPU0_PTI<18>")
	)
	(segment
		(start 353.111562 -271.289272)
		(end 353.111816 -271.289526)
		(width 0.12954)
		(layer "F.Cu")
		(net "TP_TRC_CPU0_PTI<18>")
	)
	(via
		(at 353.111816 -271.825212)
		(size 0.4572)
		(drill 0.2032)
		(layers "F.Cu" "B.Cu")
		(net "TP_TRC_CPU0_PTI<18>")
	)
	(segment
		(start 353.581716 -272.103342)
		(end 353.581716 -272.639028)
		(width 0.12954)
		(layer "F.Cu")
		(net "TP_TRC_CPU0_PTI<17>")
	)
	(segment
		(start 353.581716 -272.639028)
		(end 353.581462 -272.639282)
		(width 0.12954)
		(layer "F.Cu")
		(net "TP_TRC_CPU0_PTI<17>")
	)
	(via
		(at 353.581462 -272.639282)
		(size 0.4572)
		(drill 0.2032)
		(layers "F.Cu" "B.Cu")
		(net "TP_TRC_CPU0_PTI<17>")
	)
	(segment
		(start 352.641916 -272.639028)
		(end 352.641662 -272.639282)
		(width 0.12954)
		(layer "F.Cu")
		(net "TP_TRC_CPU0_PTI<16>")
	)
	(segment
		(start 352.641916 -272.103342)
		(end 352.641916 -272.639028)
		(width 0.12954)
		(layer "F.Cu")
		(net "TP_TRC_CPU0_PTI<16>")
	)
	(via
		(at 352.641662 -272.639282)
		(size 0.4572)
		(drill 0.2032)
		(layers "F.Cu" "B.Cu")
		(net "TP_TRC_CPU0_PTI<16>")
	)
	(segment
		(start 357.70058 -237.947454)
		(end 357.700834 -237.9472)
		(width 0.12954)
		(layer "F.Cu")
		(net "TP_TRC_CPU0_PTI<15>")
	)
	(segment
		(start 357.700834 -237.9472)
		(end 357.700834 -237.411514)
		(width 0.12954)
		(layer "F.Cu")
		(net "TP_TRC_CPU0_PTI<15>")
	)
	(via
		(at 357.700834 -237.411514)
		(size 0.4572)
		(drill 0.2032)
		(layers "F.Cu" "B.Cu")
		(net "TP_TRC_CPU0_PTI<15>")
	)
	(segment
		(start 357.23068 -237.133638)
		(end 357.23068 -236.597952)
		(width 0.12954)
		(layer "F.Cu")
		(net "TP_TRC_CPU0_PTI<14>")
	)
	(segment
		(start 357.230934 -237.133892)
		(end 357.23068 -237.133638)
		(width 0.12954)
		(layer "F.Cu")
		(net "TP_TRC_CPU0_PTI<14>")
	)
	(via
		(at 357.23068 -236.597952)
		(size 0.4572)
		(drill 0.2032)
		(layers "F.Cu" "B.Cu")
		(net "TP_TRC_CPU0_PTI<14>")
	)
	(segment
		(start 357.700834 -236.319568)
		(end 357.700834 -235.783882)
		(width 0.12954)
		(layer "F.Cu")
		(net "TP_TRC_CPU0_PTI<13>")
	)
	(segment
		(start 357.70058 -236.319822)
		(end 357.700834 -236.319568)
		(width 0.12954)
		(layer "F.Cu")
		(net "TP_TRC_CPU0_PTI<13>")
	)
	(via
		(at 357.700834 -235.783882)
		(size 0.4572)
		(drill 0.2032)
		(layers "F.Cu" "B.Cu")
		(net "TP_TRC_CPU0_PTI<13>")
	)
	(segment
		(start 357.23068 -235.505752)
		(end 357.23068 -234.970066)
		(width 0.12954)
		(layer "F.Cu")
		(net "TP_TRC_CPU0_PTI<12>")
	)
	(segment
		(start 357.230934 -235.506006)
		(end 357.23068 -235.505752)
		(width 0.12954)
		(layer "F.Cu")
		(net "TP_TRC_CPU0_PTI<12>")
	)
	(via
		(at 357.23068 -234.970066)
		(size 0.4572)
		(drill 0.2032)
		(layers "F.Cu" "B.Cu")
		(net "TP_TRC_CPU0_PTI<12>")
	)
	(segment
		(start 358.640634 -237.947454)
		(end 358.640634 -237.411514)
		(width 0.12954)
		(layer "F.Cu")
		(net "TP_TRC_CPU0_PTI<11>")
	)
	(via
		(at 358.640634 -237.411514)
		(size 0.4572)
		(drill 0.2032)
		(layers "F.Cu" "B.Cu")
		(net "TP_TRC_CPU0_PTI<11>")
	)
	(segment
		(start 359.11028 -237.133638)
		(end 359.11028 -236.597952)
		(width 0.12954)
		(layer "F.Cu")
		(net "TP_TRC_CPU0_PTI<10>")
	)
	(segment
		(start 359.110534 -237.133892)
		(end 359.11028 -237.133638)
		(width 0.12954)
		(layer "F.Cu")
		(net "TP_TRC_CPU0_PTI<10>")
	)
	(via
		(at 359.11028 -236.597952)
		(size 0.4572)
		(drill 0.2032)
		(layers "F.Cu" "B.Cu")
		(net "TP_TRC_CPU0_PTI<10>")
	)
	(segment
		(start 355.930962 -269.66164)
		(end 355.931216 -270.19758)
		(width 0.12954)
		(layer "F.Cu")
		(net "TP_TRC_CPU0_PTI3_CLK")
	)
	(via
		(at 355.931216 -270.19758)
		(size 0.4572)
		(drill 0.2032)
		(layers "F.Cu" "B.Cu")
		(net "TP_TRC_CPU0_PTI3_CLK")
	)
	(segment
		(start 354.051362 -269.66164)
		(end 354.051616 -269.661894)
		(width 0.12954)
		(layer "F.Cu")
		(net "TP_TRC_CPU0_PTI2_CLK")
	)
	(segment
		(start 354.051616 -269.661894)
		(end 354.051616 -270.19758)
		(width 0.12954)
		(layer "F.Cu")
		(net "TP_TRC_CPU0_PTI2_CLK")
	)
	(via
		(at 354.051616 -270.19758)
		(size 0.4572)
		(drill 0.2032)
		(layers "F.Cu" "B.Cu")
		(net "TP_TRC_CPU0_PTI2_CLK")
	)
	(segment
		(start 360.51998 -236.319822)
		(end 360.520234 -236.319568)
		(width 0.12954)
		(layer "F.Cu")
		(net "TP_TRC_CPU0_PTI1_CLK")
	)
	(segment
		(start 360.520234 -236.319568)
		(end 360.520234 -235.783882)
		(width 0.12954)
		(layer "F.Cu")
		(net "TP_TRC_CPU0_PTI1_CLK")
	)
	(via
		(at 360.520234 -235.783882)
		(size 0.4572)
		(drill 0.2032)
		(layers "F.Cu" "B.Cu")
		(net "TP_TRC_CPU0_PTI1_CLK")
	)
	(segment
		(start 361.460034 -237.9472)
		(end 361.460034 -237.411514)
		(width 0.12954)
		(layer "F.Cu")
		(net "TP_TRC_CPU0_PTI0_CLK")
	)
	(segment
		(start 361.45978 -237.947454)
		(end 361.460034 -237.9472)
		(width 0.12954)
		(layer "F.Cu")
		(net "TP_TRC_CPU0_PTI0_CLK")
	)
	(via
		(at 361.460034 -237.411514)
		(size 0.4572)
		(drill 0.2032)
		(layers "F.Cu" "B.Cu")
		(net "TP_TRC_CPU0_PTI0_CLK")
	)
	(segment
		(start 361.929934 -236.597952)
		(end 361.929934 -237.133892)
		(width 0.12954)
		(layer "F.Cu")
		(net "TP_TP_TRC_CPU0_PTI_MON<0>")
	)
	(via
		(at 361.929934 -236.597952)
		(size 0.4572)
		(drill 0.2032)
		(layers "F.Cu" "B.Cu")
		(net "TP_TP_TRC_CPU0_PTI_MON<0>")
	)
	(segment
		(start 351.702116 -270.475456)
		(end 351.701862 -270.47571)
		(width 0.12954)
		(layer "F.Cu")
		(net "TP_SPI_S3M_CPU0_OE_LVC1_R_N")
	)
	(segment
		(start 351.701862 -270.47571)
		(end 351.701862 -271.011396)
		(width 0.12954)
		(layer "F.Cu")
		(net "TP_SPI_S3M_CPU0_OE_LVC1_R_N")
	)
	(via
		(at 316.749176 -270.56588)
		(size 0.6604)
		(drill 0.3302)
		(layers "F.Cu" "B.Cu")
		(net "TP_SPI_S3M_CPU0_OE_LVC1_R_N")
	)
	(via
		(at 351.701862 -271.011396)
		(size 0.4572)
		(drill 0.2032)
		(layers "F.Cu" "B.Cu")
		(net "TP_SPI_S3M_CPU0_OE_LVC1_R_N")
	)
	(segment
		(start 345.875864 -270.687038)
		(end 345.861132 -270.695674)
		(width 0.0889)
		(layer "B.Cu")
		(net "TP_SPI_S3M_CPU0_OE_LVC1_R_N")
	)
	(segment
		(start 328.433938 -270.565626)
		(end 318.470026 -270.565626)
		(width 0.12954)
		(layer "B.Cu")
		(net "TP_SPI_S3M_CPU0_OE_LVC1_R_N")
	)
	(segment
		(start 339.297264 -270.687038)
		(end 339.282532 -270.695674)
		(width 0.0889)
		(layer "B.Cu")
		(net "TP_SPI_S3M_CPU0_OE_LVC1_R_N")
	)
	(segment
		(start 334.343502 -270.848074)
		(end 333.835248 -270.848074)
		(width 0.0889)
		(layer "B.Cu")
		(net "TP_SPI_S3M_CPU0_OE_LVC1_R_N")
	)
	(segment
		(start 328.716386 -270.848074)
		(end 328.433938 -270.565626)
		(width 0.12954)
		(layer "B.Cu")
		(net "TP_SPI_S3M_CPU0_OE_LVC1_R_N")
	)
	(segment
		(start 318.470026 -270.565626)
		(end 318.470026 -270.56588)
		(width 0.12954)
		(layer "B.Cu")
		(net "TP_SPI_S3M_CPU0_OE_LVC1_R_N")
	)
	(segment
		(start 334.785208 -270.636238)
		(end 334.555338 -270.636238)
		(width 0.0889)
		(layer "B.Cu")
		(net "TP_SPI_S3M_CPU0_OE_LVC1_R_N")
	)
	(segment
		(start 344.936064 -270.687038)
		(end 344.921332 -270.695674)
		(width 0.0889)
		(layer "B.Cu")
		(net "TP_SPI_S3M_CPU0_OE_LVC1_R_N")
	)
	(segment
		(start 350.574864 -270.687038)
		(end 350.56445 -270.693134)
		(width 0.0889)
		(layer "B.Cu")
		(net "TP_SPI_S3M_CPU0_OE_LVC1_R_N")
	)
	(segment
		(start 342.116918 -270.687038)
		(end 342.106504 -270.693134)
		(width 0.0889)
		(layer "B.Cu")
		(net "TP_SPI_S3M_CPU0_OE_LVC1_R_N")
	)
	(segment
		(start 347.755464 -270.687038)
		(end 347.740732 -270.695674)
		(width 0.0889)
		(layer "B.Cu")
		(net "TP_SPI_S3M_CPU0_OE_LVC1_R_N")
	)
	(segment
		(start 343.996264 -270.687038)
		(end 343.981532 -270.695674)
		(width 0.0889)
		(layer "B.Cu")
		(net "TP_SPI_S3M_CPU0_OE_LVC1_R_N")
	)
	(segment
		(start 318.470026 -270.56588)
		(end 316.749176 -270.56588)
		(width 0.12954)
		(layer "B.Cu")
		(net "TP_SPI_S3M_CPU0_OE_LVC1_R_N")
	)
	(segment
		(start 341.176864 -270.687038)
		(end 341.162132 -270.695674)
		(width 0.0889)
		(layer "B.Cu")
		(net "TP_SPI_S3M_CPU0_OE_LVC1_R_N")
	)
	(segment
		(start 351.514664 -270.687038)
		(end 351.499932 -270.695674)
		(width 0.0889)
		(layer "B.Cu")
		(net "TP_SPI_S3M_CPU0_OE_LVC1_R_N")
	)
	(segment
		(start 351.858326 -270.740378)
		(end 351.837244 -270.6624)
		(width 0.0889)
		(layer "B.Cu")
		(net "TP_SPI_S3M_CPU0_OE_LVC1_R_N")
	)
	(segment
		(start 348.695518 -270.687038)
		(end 348.685104 -270.693134)
		(width 0.0889)
		(layer "B.Cu")
		(net "TP_SPI_S3M_CPU0_OE_LVC1_R_N")
	)
	(segment
		(start 343.056464 -270.687038)
		(end 343.04605 -270.693134)
		(width 0.0889)
		(layer "B.Cu")
		(net "TP_SPI_S3M_CPU0_OE_LVC1_R_N")
	)
	(segment
		(start 334.555338 -270.636238)
		(end 334.343502 -270.848074)
		(width 0.0889)
		(layer "B.Cu")
		(net "TP_SPI_S3M_CPU0_OE_LVC1_R_N")
	)
	(segment
		(start 351.701862 -271.011396)
		(end 351.858326 -270.740378)
		(width 0.0889)
		(layer "B.Cu")
		(net "TP_SPI_S3M_CPU0_OE_LVC1_R_N")
	)
	(segment
		(start 333.835248 -270.848074)
		(end 328.716386 -270.848074)
		(width 0.12954)
		(layer "B.Cu")
		(net "TP_SPI_S3M_CPU0_OE_LVC1_R_N")
	)
	(arc
		(start 350.94926 -270.687038)
		(mid 350.762062 -270.636895)
		(end 350.574864 -270.687038)
		(width 0.0889)
		(layer "B.Cu")
		(net "TP_SPI_S3M_CPU0_OE_LVC1_R_N")
	)
	(arc
		(start 340.237064 -270.687038)
		(mid 339.954362 -270.762814)
		(end 339.67166 -270.687038)
		(width 0.0889)
		(layer "B.Cu")
		(net "TP_SPI_S3M_CPU0_OE_LVC1_R_N")
	)
	(arc
		(start 349.069914 -270.687038)
		(mid 348.882716 -270.636895)
		(end 348.695518 -270.687038)
		(width 0.0889)
		(layer "B.Cu")
		(net "TP_SPI_S3M_CPU0_OE_LVC1_R_N")
	)
	(arc
		(start 346.25026 -270.687038)
		(mid 346.063062 -270.636895)
		(end 345.875864 -270.687038)
		(width 0.0889)
		(layer "B.Cu")
		(net "TP_SPI_S3M_CPU0_OE_LVC1_R_N")
	)
	(arc
		(start 351.837244 -270.6624)
		(mid 351.673148 -270.638053)
		(end 351.514664 -270.687038)
		(width 0.0889)
		(layer "B.Cu")
		(net "TP_SPI_S3M_CPU0_OE_LVC1_R_N")
	)
	(arc
		(start 338.73186 -270.687038)
		(mid 338.544662 -270.636895)
		(end 338.357464 -270.687038)
		(width 0.0889)
		(layer "B.Cu")
		(net "TP_SPI_S3M_CPU0_OE_LVC1_R_N")
	)
	(arc
		(start 337.417664 -270.687038)
		(mid 337.134962 -270.762814)
		(end 336.85226 -270.687038)
		(width 0.0889)
		(layer "B.Cu")
		(net "TP_SPI_S3M_CPU0_OE_LVC1_R_N")
	)
	(arc
		(start 338.357464 -270.687038)
		(mid 338.074762 -270.762814)
		(end 337.79206 -270.687038)
		(width 0.0889)
		(layer "B.Cu")
		(net "TP_SPI_S3M_CPU0_OE_LVC1_R_N")
	)
	(arc
		(start 346.815664 -270.687038)
		(mid 346.532962 -270.762814)
		(end 346.25026 -270.687038)
		(width 0.0889)
		(layer "B.Cu")
		(net "TP_SPI_S3M_CPU0_OE_LVC1_R_N")
	)
	(arc
		(start 341.55126 -270.687038)
		(mid 341.364062 -270.636895)
		(end 341.176864 -270.687038)
		(width 0.0889)
		(layer "B.Cu")
		(net "TP_SPI_S3M_CPU0_OE_LVC1_R_N")
	)
	(arc
		(start 340.61146 -270.687038)
		(mid 340.424262 -270.636895)
		(end 340.237064 -270.687038)
		(width 0.0889)
		(layer "B.Cu")
		(net "TP_SPI_S3M_CPU0_OE_LVC1_R_N")
	)
	(arc
		(start 342.106504 -270.693134)
		(mid 341.828072 -270.76298)
		(end 341.55126 -270.687038)
		(width 0.0889)
		(layer "B.Cu")
		(net "TP_SPI_S3M_CPU0_OE_LVC1_R_N")
	)
	(arc
		(start 348.12986 -270.687038)
		(mid 347.942662 -270.636895)
		(end 347.755464 -270.687038)
		(width 0.0889)
		(layer "B.Cu")
		(net "TP_SPI_S3M_CPU0_OE_LVC1_R_N")
	)
	(arc
		(start 341.162132 -270.695674)
		(mid 340.885657 -270.762994)
		(end 340.61146 -270.687038)
		(width 0.0889)
		(layer "B.Cu")
		(net "TP_SPI_S3M_CPU0_OE_LVC1_R_N")
	)
	(arc
		(start 339.67166 -270.687038)
		(mid 339.484462 -270.636895)
		(end 339.297264 -270.687038)
		(width 0.0889)
		(layer "B.Cu")
		(net "TP_SPI_S3M_CPU0_OE_LVC1_R_N")
	)
	(arc
		(start 335.91246 -270.687038)
		(mid 335.725262 -270.636895)
		(end 335.538064 -270.687038)
		(width 0.0889)
		(layer "B.Cu")
		(net "TP_SPI_S3M_CPU0_OE_LVC1_R_N")
	)
	(arc
		(start 334.97266 -270.687038)
		(mid 334.882281 -270.649283)
		(end 334.785208 -270.636238)
		(width 0.0889)
		(layer "B.Cu")
		(net "TP_SPI_S3M_CPU0_OE_LVC1_R_N")
	)
	(arc
		(start 351.499932 -270.695674)
		(mid 351.223457 -270.762994)
		(end 350.94926 -270.687038)
		(width 0.0889)
		(layer "B.Cu")
		(net "TP_SPI_S3M_CPU0_OE_LVC1_R_N")
	)
	(arc
		(start 335.538064 -270.687038)
		(mid 335.255362 -270.762814)
		(end 334.97266 -270.687038)
		(width 0.0889)
		(layer "B.Cu")
		(net "TP_SPI_S3M_CPU0_OE_LVC1_R_N")
	)
	(arc
		(start 343.04605 -270.693134)
		(mid 342.767872 -270.762857)
		(end 342.491314 -270.687038)
		(width 0.0889)
		(layer "B.Cu")
		(net "TP_SPI_S3M_CPU0_OE_LVC1_R_N")
	)
	(arc
		(start 339.282532 -270.695674)
		(mid 339.006057 -270.762994)
		(end 338.73186 -270.687038)
		(width 0.0889)
		(layer "B.Cu")
		(net "TP_SPI_S3M_CPU0_OE_LVC1_R_N")
	)
	(arc
		(start 348.685104 -270.693134)
		(mid 348.406672 -270.76298)
		(end 348.12986 -270.687038)
		(width 0.0889)
		(layer "B.Cu")
		(net "TP_SPI_S3M_CPU0_OE_LVC1_R_N")
	)
	(arc
		(start 337.79206 -270.687038)
		(mid 337.604862 -270.636895)
		(end 337.417664 -270.687038)
		(width 0.0889)
		(layer "B.Cu")
		(net "TP_SPI_S3M_CPU0_OE_LVC1_R_N")
	)
	(arc
		(start 336.85226 -270.687038)
		(mid 336.665062 -270.636895)
		(end 336.477864 -270.687038)
		(width 0.0889)
		(layer "B.Cu")
		(net "TP_SPI_S3M_CPU0_OE_LVC1_R_N")
	)
	(arc
		(start 344.37066 -270.687038)
		(mid 344.183462 -270.636895)
		(end 343.996264 -270.687038)
		(width 0.0889)
		(layer "B.Cu")
		(net "TP_SPI_S3M_CPU0_OE_LVC1_R_N")
	)
	(arc
		(start 343.43086 -270.687038)
		(mid 343.243662 -270.636895)
		(end 343.056464 -270.687038)
		(width 0.0889)
		(layer "B.Cu")
		(net "TP_SPI_S3M_CPU0_OE_LVC1_R_N")
	)
	(arc
		(start 345.861132 -270.695674)
		(mid 345.584657 -270.762994)
		(end 345.31046 -270.687038)
		(width 0.0889)
		(layer "B.Cu")
		(net "TP_SPI_S3M_CPU0_OE_LVC1_R_N")
	)
	(arc
		(start 349.635318 -270.687038)
		(mid 349.352616 -270.762814)
		(end 349.069914 -270.687038)
		(width 0.0889)
		(layer "B.Cu")
		(net "TP_SPI_S3M_CPU0_OE_LVC1_R_N")
	)
	(arc
		(start 350.56445 -270.693134)
		(mid 350.286272 -270.762857)
		(end 350.009714 -270.687038)
		(width 0.0889)
		(layer "B.Cu")
		(net "TP_SPI_S3M_CPU0_OE_LVC1_R_N")
	)
	(arc
		(start 343.981532 -270.695674)
		(mid 343.705057 -270.762994)
		(end 343.43086 -270.687038)
		(width 0.0889)
		(layer "B.Cu")
		(net "TP_SPI_S3M_CPU0_OE_LVC1_R_N")
	)
	(arc
		(start 347.19006 -270.687038)
		(mid 347.002862 -270.636895)
		(end 346.815664 -270.687038)
		(width 0.0889)
		(layer "B.Cu")
		(net "TP_SPI_S3M_CPU0_OE_LVC1_R_N")
	)
	(arc
		(start 344.921332 -270.695674)
		(mid 344.644857 -270.762994)
		(end 344.37066 -270.687038)
		(width 0.0889)
		(layer "B.Cu")
		(net "TP_SPI_S3M_CPU0_OE_LVC1_R_N")
	)
	(arc
		(start 347.740732 -270.695674)
		(mid 347.464257 -270.762994)
		(end 347.19006 -270.687038)
		(width 0.0889)
		(layer "B.Cu")
		(net "TP_SPI_S3M_CPU0_OE_LVC1_R_N")
	)
	(arc
		(start 350.009714 -270.687038)
		(mid 349.822516 -270.636895)
		(end 349.635318 -270.687038)
		(width 0.0889)
		(layer "B.Cu")
		(net "TP_SPI_S3M_CPU0_OE_LVC1_R_N")
	)
	(arc
		(start 342.491314 -270.687038)
		(mid 342.304116 -270.636895)
		(end 342.116918 -270.687038)
		(width 0.0889)
		(layer "B.Cu")
		(net "TP_SPI_S3M_CPU0_OE_LVC1_R_N")
	)
	(arc
		(start 345.31046 -270.687038)
		(mid 345.123262 -270.636895)
		(end 344.936064 -270.687038)
		(width 0.0889)
		(layer "B.Cu")
		(net "TP_SPI_S3M_CPU0_OE_LVC1_R_N")
	)
	(arc
		(start 336.477864 -270.687038)
		(mid 336.195162 -270.762814)
		(end 335.91246 -270.687038)
		(width 0.0889)
		(layer "B.Cu")
		(net "TP_SPI_S3M_CPU0_OE_LVC1_R_N")
	)
	(segment
		(start 353.111562 -265.313922)
		(end 353.111816 -265.314176)
		(width 0.12954)
		(layer "F.Cu")
		(net "TP_SPI_S3M_CPU0_IO3_LVC1_R")
	)
	(segment
		(start 353.111562 -264.778236)
		(end 353.111562 -265.313922)
		(width 0.12954)
		(layer "F.Cu")
		(net "TP_SPI_S3M_CPU0_IO3_LVC1_R")
	)
	(via
		(at 353.111816 -265.314176)
		(size 0.4572)
		(drill 0.2032)
		(layers "F.Cu" "B.Cu")
		(net "TP_SPI_S3M_CPU0_IO3_LVC1_R")
	)
	(via
		(at 324.06082 -268.29385)
		(size 0.6604)
		(drill 0.3302)
		(layers "F.Cu" "B.Cu")
		(net "TP_SPI_S3M_CPU0_IO3_LVC1_R")
	)
	(segment
		(start 342.116664 -264.176002)
		(end 342.101932 -264.184638)
		(width 0.0889)
		(layer "B.Cu")
		(net "TP_SPI_S3M_CPU0_IO3_LVC1_R")
	)
	(segment
		(start 351.419414 -264.989818)
		(end 351.413318 -264.986262)
		(width 0.0889)
		(layer "B.Cu")
		(net "TP_SPI_S3M_CPU0_IO3_LVC1_R")
	)
	(segment
		(start 332.229206 -264.893298)
		(end 330.355448 -266.767056)
		(width 0.12954)
		(layer "B.Cu")
		(net "TP_SPI_S3M_CPU0_IO3_LVC1_R")
	)
	(segment
		(start 351.428304 -264.994898)
		(end 351.419414 -264.989818)
		(width 0.0889)
		(layer "B.Cu")
		(net "TP_SPI_S3M_CPU0_IO3_LVC1_R")
	)
	(segment
		(start 353.111816 -265.314176)
		(end 352.799142 -265.314176)
		(width 0.0889)
		(layer "B.Cu")
		(net "TP_SPI_S3M_CPU0_IO3_LVC1_R")
	)
	(segment
		(start 340.237064 -264.176002)
		(end 340.22665 -264.182098)
		(width 0.0889)
		(layer "B.Cu")
		(net "TP_SPI_S3M_CPU0_IO3_LVC1_R")
	)
	(segment
		(start 332.666594 -264.893298)
		(end 332.229206 -264.893298)
		(width 0.12954)
		(layer "B.Cu")
		(net "TP_SPI_S3M_CPU0_IO3_LVC1_R")
	)
	(segment
		(start 348.695264 -264.176002)
		(end 348.680532 -264.184638)
		(width 0.0889)
		(layer "B.Cu")
		(net "TP_SPI_S3M_CPU0_IO3_LVC1_R")
	)
	(segment
		(start 350.953324 -264.125456)
		(end 350.762062 -264.125456)
		(width 0.0889)
		(layer "B.Cu")
		(net "TP_SPI_S3M_CPU0_IO3_LVC1_R")
	)
	(segment
		(start 335.37144 -264.215372)
		(end 335.232756 -264.354056)
		(width 0.12954)
		(layer "B.Cu")
		(net "TP_SPI_S3M_CPU0_IO3_LVC1_R")
	)
	(segment
		(start 346.815664 -264.176002)
		(end 346.80525 -264.182098)
		(width 0.0889)
		(layer "B.Cu")
		(net "TP_SPI_S3M_CPU0_IO3_LVC1_R")
	)
	(segment
		(start 341.176864 -264.176002)
		(end 341.162132 -264.184638)
		(width 0.0889)
		(layer "B.Cu")
		(net "TP_SPI_S3M_CPU0_IO3_LVC1_R")
	)
	(segment
		(start 325.587614 -266.767056)
		(end 324.06082 -268.29385)
		(width 0.12954)
		(layer "B.Cu")
		(net "TP_SPI_S3M_CPU0_IO3_LVC1_R")
	)
	(segment
		(start 352.454464 -265.803888)
		(end 352.439732 -265.812524)
		(width 0.0889)
		(layer "B.Cu")
		(net "TP_SPI_S3M_CPU0_IO3_LVC1_R")
	)
	(segment
		(start 334.913986 -264.952226)
		(end 332.808834 -264.952226)
		(width 0.12954)
		(layer "B.Cu")
		(net "TP_SPI_S3M_CPU0_IO3_LVC1_R")
	)
	(segment
		(start 352.799142 -265.314176)
		(end 352.73361 -265.379708)
		(width 0.0889)
		(layer "B.Cu")
		(net "TP_SPI_S3M_CPU0_IO3_LVC1_R")
	)
	(segment
		(start 335.725262 -264.125456)
		(end 335.461356 -264.125456)
		(width 0.0889)
		(layer "B.Cu")
		(net "TP_SPI_S3M_CPU0_IO3_LVC1_R")
	)
	(segment
		(start 335.461356 -264.125456)
		(end 335.37144 -264.215372)
		(width 0.0889)
		(layer "B.Cu")
		(net "TP_SPI_S3M_CPU0_IO3_LVC1_R")
	)
	(segment
		(start 351.606866 -265.336274)
		(end 351.606866 -265.314176)
		(width 0.0889)
		(layer "B.Cu")
		(net "TP_SPI_S3M_CPU0_IO3_LVC1_R")
	)
	(segment
		(start 335.232756 -264.633456)
		(end 334.913986 -264.952226)
		(width 0.12954)
		(layer "B.Cu")
		(net "TP_SPI_S3M_CPU0_IO3_LVC1_R")
	)
	(segment
		(start 350.574864 -264.176002)
		(end 350.560132 -264.184638)
		(width 0.0889)
		(layer "B.Cu")
		(net "TP_SPI_S3M_CPU0_IO3_LVC1_R")
	)
	(segment
		(start 344.936064 -264.176002)
		(end 344.921332 -264.184638)
		(width 0.0889)
		(layer "B.Cu")
		(net "TP_SPI_S3M_CPU0_IO3_LVC1_R")
	)
	(segment
		(start 343.996264 -264.176002)
		(end 343.981532 -264.184638)
		(width 0.0889)
		(layer "B.Cu")
		(net "TP_SPI_S3M_CPU0_IO3_LVC1_R")
	)
	(segment
		(start 351.136712 -264.308844)
		(end 350.953324 -264.125456)
		(width 0.0889)
		(layer "B.Cu")
		(net "TP_SPI_S3M_CPU0_IO3_LVC1_R")
	)
	(segment
		(start 351.136712 -264.50036)
		(end 351.136712 -264.308844)
		(width 0.0889)
		(layer "B.Cu")
		(net "TP_SPI_S3M_CPU0_IO3_LVC1_R")
	)
	(segment
		(start 330.355448 -266.767056)
		(end 325.587614 -266.767056)
		(width 0.12954)
		(layer "B.Cu")
		(net "TP_SPI_S3M_CPU0_IO3_LVC1_R")
	)
	(segment
		(start 345.876118 -264.176002)
		(end 345.865704 -264.182098)
		(width 0.0889)
		(layer "B.Cu")
		(net "TP_SPI_S3M_CPU0_IO3_LVC1_R")
	)
	(segment
		(start 335.232756 -264.354056)
		(end 335.232756 -264.633456)
		(width 0.12954)
		(layer "B.Cu")
		(net "TP_SPI_S3M_CPU0_IO3_LVC1_R")
	)
	(segment
		(start 347.755464 -264.176002)
		(end 347.740732 -264.184638)
		(width 0.0889)
		(layer "B.Cu")
		(net "TP_SPI_S3M_CPU0_IO3_LVC1_R")
	)
	(segment
		(start 332.808834 -264.952226)
		(end 332.666594 -264.893298)
		(width 0.12954)
		(layer "B.Cu")
		(net "TP_SPI_S3M_CPU0_IO3_LVC1_R")
	)
	(segment
		(start 339.297518 -264.176002)
		(end 339.287104 -264.182098)
		(width 0.0889)
		(layer "B.Cu")
		(net "TP_SPI_S3M_CPU0_IO3_LVC1_R")
	)
	(arc
		(start 341.55126 -264.176002)
		(mid 341.364062 -264.125859)
		(end 341.176864 -264.176002)
		(width 0.0889)
		(layer "B.Cu")
		(net "TP_SPI_S3M_CPU0_IO3_LVC1_R")
	)
	(arc
		(start 349.635064 -264.176002)
		(mid 349.352362 -264.251778)
		(end 349.06966 -264.176002)
		(width 0.0889)
		(layer "B.Cu")
		(net "TP_SPI_S3M_CPU0_IO3_LVC1_R")
	)
	(arc
		(start 344.921332 -264.184638)
		(mid 344.644857 -264.251958)
		(end 344.37066 -264.176002)
		(width 0.0889)
		(layer "B.Cu")
		(net "TP_SPI_S3M_CPU0_IO3_LVC1_R")
	)
	(arc
		(start 346.250514 -264.176002)
		(mid 346.063316 -264.125859)
		(end 345.876118 -264.176002)
		(width 0.0889)
		(layer "B.Cu")
		(net "TP_SPI_S3M_CPU0_IO3_LVC1_R")
	)
	(arc
		(start 340.22665 -264.182098)
		(mid 339.948472 -264.251821)
		(end 339.671914 -264.176002)
		(width 0.0889)
		(layer "B.Cu")
		(net "TP_SPI_S3M_CPU0_IO3_LVC1_R")
	)
	(arc
		(start 338.73186 -264.176002)
		(mid 338.544662 -264.125859)
		(end 338.357464 -264.176002)
		(width 0.0889)
		(layer "B.Cu")
		(net "TP_SPI_S3M_CPU0_IO3_LVC1_R")
	)
	(arc
		(start 350.00946 -264.176002)
		(mid 349.822262 -264.125859)
		(end 349.635064 -264.176002)
		(width 0.0889)
		(layer "B.Cu")
		(net "TP_SPI_S3M_CPU0_IO3_LVC1_R")
	)
	(arc
		(start 337.79206 -264.176002)
		(mid 337.604862 -264.125859)
		(end 337.417664 -264.176002)
		(width 0.0889)
		(layer "B.Cu")
		(net "TP_SPI_S3M_CPU0_IO3_LVC1_R")
	)
	(arc
		(start 342.49106 -264.176002)
		(mid 342.303862 -264.125859)
		(end 342.116664 -264.176002)
		(width 0.0889)
		(layer "B.Cu")
		(net "TP_SPI_S3M_CPU0_IO3_LVC1_R")
	)
	(arc
		(start 351.413318 -264.986262)
		(mid 351.210731 -264.779911)
		(end 351.136712 -264.50036)
		(width 0.0889)
		(layer "B.Cu")
		(net "TP_SPI_S3M_CPU0_IO3_LVC1_R")
	)
	(arc
		(start 350.762062 -264.125456)
		(mid 350.665139 -264.138414)
		(end 350.574864 -264.176002)
		(width 0.0889)
		(layer "B.Cu")
		(net "TP_SPI_S3M_CPU0_IO3_LVC1_R")
	)
	(arc
		(start 343.981532 -264.184638)
		(mid 343.705057 -264.251958)
		(end 343.43086 -264.176002)
		(width 0.0889)
		(layer "B.Cu")
		(net "TP_SPI_S3M_CPU0_IO3_LVC1_R")
	)
	(arc
		(start 343.43086 -264.176002)
		(mid 343.243662 -264.125859)
		(end 343.056464 -264.176002)
		(width 0.0889)
		(layer "B.Cu")
		(net "TP_SPI_S3M_CPU0_IO3_LVC1_R")
	)
	(arc
		(start 340.61146 -264.176002)
		(mid 340.424262 -264.125859)
		(end 340.237064 -264.176002)
		(width 0.0889)
		(layer "B.Cu")
		(net "TP_SPI_S3M_CPU0_IO3_LVC1_R")
	)
	(arc
		(start 339.287104 -264.182098)
		(mid 339.008672 -264.251944)
		(end 338.73186 -264.176002)
		(width 0.0889)
		(layer "B.Cu")
		(net "TP_SPI_S3M_CPU0_IO3_LVC1_R")
	)
	(arc
		(start 349.06966 -264.176002)
		(mid 348.882462 -264.125859)
		(end 348.695264 -264.176002)
		(width 0.0889)
		(layer "B.Cu")
		(net "TP_SPI_S3M_CPU0_IO3_LVC1_R")
	)
	(arc
		(start 351.88906 -265.803888)
		(mid 351.687778 -265.606401)
		(end 351.606866 -265.336274)
		(width 0.0889)
		(layer "B.Cu")
		(net "TP_SPI_S3M_CPU0_IO3_LVC1_R")
	)
	(arc
		(start 336.85226 -264.176002)
		(mid 336.665062 -264.125859)
		(end 336.477864 -264.176002)
		(width 0.0889)
		(layer "B.Cu")
		(net "TP_SPI_S3M_CPU0_IO3_LVC1_R")
	)
	(arc
		(start 342.101932 -264.184638)
		(mid 341.825457 -264.251958)
		(end 341.55126 -264.176002)
		(width 0.0889)
		(layer "B.Cu")
		(net "TP_SPI_S3M_CPU0_IO3_LVC1_R")
	)
	(arc
		(start 348.12986 -264.176002)
		(mid 347.942662 -264.125859)
		(end 347.755464 -264.176002)
		(width 0.0889)
		(layer "B.Cu")
		(net "TP_SPI_S3M_CPU0_IO3_LVC1_R")
	)
	(arc
		(start 352.73361 -265.379708)
		(mid 352.644366 -265.62493)
		(end 352.454464 -265.803888)
		(width 0.0889)
		(layer "B.Cu")
		(net "TP_SPI_S3M_CPU0_IO3_LVC1_R")
	)
	(arc
		(start 337.417664 -264.176002)
		(mid 337.134962 -264.251778)
		(end 336.85226 -264.176002)
		(width 0.0889)
		(layer "B.Cu")
		(net "TP_SPI_S3M_CPU0_IO3_LVC1_R")
	)
	(arc
		(start 352.439732 -265.812524)
		(mid 352.163291 -265.87969)
		(end 351.88906 -265.803888)
		(width 0.0889)
		(layer "B.Cu")
		(net "TP_SPI_S3M_CPU0_IO3_LVC1_R")
	)
	(arc
		(start 347.19006 -264.176002)
		(mid 347.002862 -264.125859)
		(end 346.815664 -264.176002)
		(width 0.0889)
		(layer "B.Cu")
		(net "TP_SPI_S3M_CPU0_IO3_LVC1_R")
	)
	(arc
		(start 341.162132 -264.184638)
		(mid 340.885657 -264.251958)
		(end 340.61146 -264.176002)
		(width 0.0889)
		(layer "B.Cu")
		(net "TP_SPI_S3M_CPU0_IO3_LVC1_R")
	)
	(arc
		(start 345.31046 -264.176002)
		(mid 345.123262 -264.125859)
		(end 344.936064 -264.176002)
		(width 0.0889)
		(layer "B.Cu")
		(net "TP_SPI_S3M_CPU0_IO3_LVC1_R")
	)
	(arc
		(start 344.37066 -264.176002)
		(mid 344.183462 -264.125859)
		(end 343.996264 -264.176002)
		(width 0.0889)
		(layer "B.Cu")
		(net "TP_SPI_S3M_CPU0_IO3_LVC1_R")
	)
	(arc
		(start 335.91246 -264.176002)
		(mid 335.822188 -264.138403)
		(end 335.725262 -264.125456)
		(width 0.0889)
		(layer "B.Cu")
		(net "TP_SPI_S3M_CPU0_IO3_LVC1_R")
	)
	(arc
		(start 345.865704 -264.182098)
		(mid 345.587272 -264.251944)
		(end 345.31046 -264.176002)
		(width 0.0889)
		(layer "B.Cu")
		(net "TP_SPI_S3M_CPU0_IO3_LVC1_R")
	)
	(arc
		(start 348.680532 -264.184638)
		(mid 348.404057 -264.251958)
		(end 348.12986 -264.176002)
		(width 0.0889)
		(layer "B.Cu")
		(net "TP_SPI_S3M_CPU0_IO3_LVC1_R")
	)
	(arc
		(start 339.671914 -264.176002)
		(mid 339.484716 -264.125859)
		(end 339.297518 -264.176002)
		(width 0.0889)
		(layer "B.Cu")
		(net "TP_SPI_S3M_CPU0_IO3_LVC1_R")
	)
	(arc
		(start 347.740732 -264.184638)
		(mid 347.464257 -264.251958)
		(end 347.19006 -264.176002)
		(width 0.0889)
		(layer "B.Cu")
		(net "TP_SPI_S3M_CPU0_IO3_LVC1_R")
	)
	(arc
		(start 343.056464 -264.176002)
		(mid 342.773762 -264.251778)
		(end 342.49106 -264.176002)
		(width 0.0889)
		(layer "B.Cu")
		(net "TP_SPI_S3M_CPU0_IO3_LVC1_R")
	)
	(arc
		(start 351.606866 -265.314176)
		(mid 351.559187 -265.131276)
		(end 351.428304 -264.994898)
		(width 0.0889)
		(layer "B.Cu")
		(net "TP_SPI_S3M_CPU0_IO3_LVC1_R")
	)
	(arc
		(start 346.80525 -264.182098)
		(mid 346.527072 -264.251821)
		(end 346.250514 -264.176002)
		(width 0.0889)
		(layer "B.Cu")
		(net "TP_SPI_S3M_CPU0_IO3_LVC1_R")
	)
	(arc
		(start 338.357464 -264.176002)
		(mid 338.074762 -264.251778)
		(end 337.79206 -264.176002)
		(width 0.0889)
		(layer "B.Cu")
		(net "TP_SPI_S3M_CPU0_IO3_LVC1_R")
	)
	(arc
		(start 336.477864 -264.176002)
		(mid 336.195162 -264.251778)
		(end 335.91246 -264.176002)
		(width 0.0889)
		(layer "B.Cu")
		(net "TP_SPI_S3M_CPU0_IO3_LVC1_R")
	)
	(arc
		(start 350.560132 -264.184638)
		(mid 350.283657 -264.251958)
		(end 350.00946 -264.176002)
		(width 0.0889)
		(layer "B.Cu")
		(net "TP_SPI_S3M_CPU0_IO3_LVC1_R")
	)
	(segment
		(start 353.111562 -268.033754)
		(end 353.111816 -268.034008)
		(width 0.12954)
		(layer "F.Cu")
		(net "TP_SPI_S3M_CPU0_IO2_LVC1_R")
	)
	(segment
		(start 353.111816 -268.034008)
		(end 353.111816 -268.569694)
		(width 0.12954)
		(layer "F.Cu")
		(net "TP_SPI_S3M_CPU0_IO2_LVC1_R")
	)
	(via
		(at 328.11085 -268.22146)
		(size 0.6604)
		(drill 0.3302)
		(layers "F.Cu" "B.Cu")
		(net "TP_SPI_S3M_CPU0_IO2_LVC1_R")
	)
	(via
		(at 353.111816 -268.569694)
		(size 0.4572)
		(drill 0.2032)
		(layers "F.Cu" "B.Cu")
		(net "TP_SPI_S3M_CPU0_IO2_LVC1_R")
	)
	(segment
		(start 328.770996 -267.561314)
		(end 328.11085 -268.22146)
		(width 0.12954)
		(layer "B.Cu")
		(net "TP_SPI_S3M_CPU0_IO2_LVC1_R")
	)
	(segment
		(start 338.272374 -264.995914)
		(end 338.26196 -264.989818)
		(width 0.0889)
		(layer "B.Cu")
		(net "TP_SPI_S3M_CPU0_IO2_LVC1_R")
	)
	(segment
		(start 351.89795 -267.4366)
		(end 351.88906 -267.43152)
		(width 0.0889)
		(layer "B.Cu")
		(net "TP_SPI_S3M_CPU0_IO2_LVC1_R")
	)
	(segment
		(start 339.767164 -264.989818)
		(end 339.75675 -264.995914)
		(width 0.0889)
		(layer "B.Cu")
		(net "TP_SPI_S3M_CPU0_IO2_LVC1_R")
	)
	(segment
		(start 346.345764 -264.989818)
		(end 346.33535 -264.995914)
		(width 0.0889)
		(layer "B.Cu")
		(net "TP_SPI_S3M_CPU0_IO2_LVC1_R")
	)
	(segment
		(start 341.096346 -264.998454)
		(end 341.081614 -264.989818)
		(width 0.0889)
		(layer "B.Cu")
		(net "TP_SPI_S3M_CPU0_IO2_LVC1_R")
	)
	(segment
		(start 335.102708 -266.032234)
		(end 332.424278 -266.032234)
		(width 0.12954)
		(layer "B.Cu")
		(net "TP_SPI_S3M_CPU0_IO2_LVC1_R")
	)
	(segment
		(start 342.036146 -264.998454)
		(end 342.021414 -264.989818)
		(width 0.0889)
		(layer "B.Cu")
		(net "TP_SPI_S3M_CPU0_IO2_LVC1_R")
	)
	(segment
		(start 352.373946 -268.253972)
		(end 352.359214 -268.245336)
		(width 0.0889)
		(layer "B.Cu")
		(net "TP_SPI_S3M_CPU0_IO2_LVC1_R")
	)
	(segment
		(start 336.007964 -264.989818)
		(end 335.999074 -264.994898)
		(width 0.0889)
		(layer "B.Cu")
		(net "TP_SPI_S3M_CPU0_IO2_LVC1_R")
	)
	(segment
		(start 353.111816 -268.569694)
		(end 352.955352 -268.298676)
		(width 0.0889)
		(layer "B.Cu")
		(net "TP_SPI_S3M_CPU0_IO2_LVC1_R")
	)
	(segment
		(start 349.554546 -264.998454)
		(end 349.539814 -264.989818)
		(width 0.0889)
		(layer "B.Cu")
		(net "TP_SPI_S3M_CPU0_IO2_LVC1_R")
	)
	(segment
		(start 351.606612 -266.96035)
		(end 351.606612 -266.933172)
		(width 0.0889)
		(layer "B.Cu")
		(net "TP_SPI_S3M_CPU0_IO2_LVC1_R")
	)
	(segment
		(start 330.895198 -267.561314)
		(end 328.770996 -267.561314)
		(width 0.12954)
		(layer "B.Cu")
		(net "TP_SPI_S3M_CPU0_IO2_LVC1_R")
	)
	(segment
		(start 350.95815 -265.808714)
		(end 350.94926 -265.803634)
		(width 0.0889)
		(layer "B.Cu")
		(net "TP_SPI_S3M_CPU0_IO2_LVC1_R")
	)
	(segment
		(start 346.730574 -264.995914)
		(end 346.72016 -264.989818)
		(width 0.0889)
		(layer "B.Cu")
		(net "TP_SPI_S3M_CPU0_IO2_LVC1_R")
	)
	(segment
		(start 332.424278 -266.032234)
		(end 330.895198 -267.561314)
		(width 0.12954)
		(layer "B.Cu")
		(net "TP_SPI_S3M_CPU0_IO2_LVC1_R")
	)
	(segment
		(start 350.667066 -265.32967)
		(end 350.667066 -265.314176)
		(width 0.0889)
		(layer "B.Cu")
		(net "TP_SPI_S3M_CPU0_IO2_LVC1_R")
	)
	(segment
		(start 340.151974 -264.995914)
		(end 340.14156 -264.989818)
		(width 0.0889)
		(layer "B.Cu")
		(net "TP_SPI_S3M_CPU0_IO2_LVC1_R")
	)
	(segment
		(start 335.255362 -265.87958)
		(end 335.102708 -266.032234)
		(width 0.0889)
		(layer "B.Cu")
		(net "TP_SPI_S3M_CPU0_IO2_LVC1_R")
	)
	(segment
		(start 352.359214 -268.245336)
		(end 352.353118 -268.24178)
		(width 0.0889)
		(layer "B.Cu")
		(net "TP_SPI_S3M_CPU0_IO2_LVC1_R")
	)
	(segment
		(start 343.915746 -264.998454)
		(end 343.901014 -264.989818)
		(width 0.0889)
		(layer "B.Cu")
		(net "TP_SPI_S3M_CPU0_IO2_LVC1_R")
	)
	(segment
		(start 335.820512 -265.314176)
		(end 335.820512 -265.332718)
		(width 0.0889)
		(layer "B.Cu")
		(net "TP_SPI_S3M_CPU0_IO2_LVC1_R")
	)
	(segment
		(start 352.955352 -268.298676)
		(end 352.866198 -268.2748)
		(width 0.0889)
		(layer "B.Cu")
		(net "TP_SPI_S3M_CPU0_IO2_LVC1_R")
	)
	(segment
		(start 348.614746 -264.998454)
		(end 348.600014 -264.989818)
		(width 0.0889)
		(layer "B.Cu")
		(net "TP_SPI_S3M_CPU0_IO2_LVC1_R")
	)
	(segment
		(start 347.674946 -264.998454)
		(end 347.660214 -264.989818)
		(width 0.0889)
		(layer "B.Cu")
		(net "TP_SPI_S3M_CPU0_IO2_LVC1_R")
	)
	(segment
		(start 351.419414 -266.61745)
		(end 351.413318 -266.613894)
		(width 0.0889)
		(layer "B.Cu")
		(net "TP_SPI_S3M_CPU0_IO2_LVC1_R")
	)
	(segment
		(start 344.855546 -264.998454)
		(end 344.840814 -264.989818)
		(width 0.0889)
		(layer "B.Cu")
		(net "TP_SPI_S3M_CPU0_IO2_LVC1_R")
	)
	(segment
		(start 342.975946 -264.998454)
		(end 342.961214 -264.989818)
		(width 0.0889)
		(layer "B.Cu")
		(net "TP_SPI_S3M_CPU0_IO2_LVC1_R")
	)
	(arc
		(start 350.667066 -265.314176)
		(mid 350.479767 -264.989735)
		(end 350.105218 -264.989818)
		(width 0.0889)
		(layer "B.Cu")
		(net "TP_SPI_S3M_CPU0_IO2_LVC1_R")
	)
	(arc
		(start 345.406218 -264.989818)
		(mid 345.132019 -265.065653)
		(end 344.855546 -264.998454)
		(width 0.0889)
		(layer "B.Cu")
		(net "TP_SPI_S3M_CPU0_IO2_LVC1_R")
	)
	(arc
		(start 351.88906 -267.43152)
		(mid 351.686774 -267.232539)
		(end 351.606612 -266.96035)
		(width 0.0889)
		(layer "B.Cu")
		(net "TP_SPI_S3M_CPU0_IO2_LVC1_R")
	)
	(arc
		(start 352.866198 -268.2748)
		(mid 352.617693 -268.320787)
		(end 352.373946 -268.253972)
		(width 0.0889)
		(layer "B.Cu")
		(net "TP_SPI_S3M_CPU0_IO2_LVC1_R")
	)
	(arc
		(start 338.26196 -264.989818)
		(mid 338.074762 -264.939675)
		(end 337.887564 -264.989818)
		(width 0.0889)
		(layer "B.Cu")
		(net "TP_SPI_S3M_CPU0_IO2_LVC1_R")
	)
	(arc
		(start 351.606612 -266.933172)
		(mid 351.554342 -266.750807)
		(end 351.419414 -266.61745)
		(width 0.0889)
		(layer "B.Cu")
		(net "TP_SPI_S3M_CPU0_IO2_LVC1_R")
	)
	(arc
		(start 342.961214 -264.989818)
		(mid 342.774016 -264.939675)
		(end 342.586818 -264.989818)
		(width 0.0889)
		(layer "B.Cu")
		(net "TP_SPI_S3M_CPU0_IO2_LVC1_R")
	)
	(arc
		(start 339.75675 -264.995914)
		(mid 339.478572 -265.065637)
		(end 339.202014 -264.989818)
		(width 0.0889)
		(layer "B.Cu")
		(net "TP_SPI_S3M_CPU0_IO2_LVC1_R")
	)
	(arc
		(start 339.202014 -264.989818)
		(mid 339.014816 -264.939675)
		(end 338.827618 -264.989818)
		(width 0.0889)
		(layer "B.Cu")
		(net "TP_SPI_S3M_CPU0_IO2_LVC1_R")
	)
	(arc
		(start 348.225618 -264.989818)
		(mid 347.951419 -265.065653)
		(end 347.674946 -264.998454)
		(width 0.0889)
		(layer "B.Cu")
		(net "TP_SPI_S3M_CPU0_IO2_LVC1_R")
	)
	(arc
		(start 346.33535 -264.995914)
		(mid 346.057172 -265.065637)
		(end 345.780614 -264.989818)
		(width 0.0889)
		(layer "B.Cu")
		(net "TP_SPI_S3M_CPU0_IO2_LVC1_R")
	)
	(arc
		(start 343.526618 -264.989818)
		(mid 343.252419 -265.065653)
		(end 342.975946 -264.998454)
		(width 0.0889)
		(layer "B.Cu")
		(net "TP_SPI_S3M_CPU0_IO2_LVC1_R")
	)
	(arc
		(start 351.136712 -266.127992)
		(mid 351.089033 -265.945092)
		(end 350.95815 -265.808714)
		(width 0.0889)
		(layer "B.Cu")
		(net "TP_SPI_S3M_CPU0_IO2_LVC1_R")
	)
	(arc
		(start 341.647018 -264.989818)
		(mid 341.372819 -265.065653)
		(end 341.096346 -264.998454)
		(width 0.0889)
		(layer "B.Cu")
		(net "TP_SPI_S3M_CPU0_IO2_LVC1_R")
	)
	(arc
		(start 344.840814 -264.989818)
		(mid 344.653616 -264.939675)
		(end 344.466418 -264.989818)
		(width 0.0889)
		(layer "B.Cu")
		(net "TP_SPI_S3M_CPU0_IO2_LVC1_R")
	)
	(arc
		(start 344.466418 -264.989818)
		(mid 344.192219 -265.065653)
		(end 343.915746 -264.998454)
		(width 0.0889)
		(layer "B.Cu")
		(net "TP_SPI_S3M_CPU0_IO2_LVC1_R")
	)
	(arc
		(start 352.353118 -268.24178)
		(mid 352.150531 -268.035429)
		(end 352.076512 -267.755878)
		(width 0.0889)
		(layer "B.Cu")
		(net "TP_SPI_S3M_CPU0_IO2_LVC1_R")
	)
	(arc
		(start 342.586818 -264.989818)
		(mid 342.312619 -265.065653)
		(end 342.036146 -264.998454)
		(width 0.0889)
		(layer "B.Cu")
		(net "TP_SPI_S3M_CPU0_IO2_LVC1_R")
	)
	(arc
		(start 347.660214 -264.989818)
		(mid 347.473016 -264.939675)
		(end 347.285818 -264.989818)
		(width 0.0889)
		(layer "B.Cu")
		(net "TP_SPI_S3M_CPU0_IO2_LVC1_R")
	)
	(arc
		(start 335.999074 -264.994898)
		(mid 335.86816 -265.131258)
		(end 335.820512 -265.314176)
		(width 0.0889)
		(layer "B.Cu")
		(net "TP_SPI_S3M_CPU0_IO2_LVC1_R")
	)
	(arc
		(start 348.600014 -264.989818)
		(mid 348.412816 -264.939675)
		(end 348.225618 -264.989818)
		(width 0.0889)
		(layer "B.Cu")
		(net "TP_SPI_S3M_CPU0_IO2_LVC1_R")
	)
	(arc
		(start 347.285818 -264.989818)
		(mid 347.009005 -265.065688)
		(end 346.730574 -264.995914)
		(width 0.0889)
		(layer "B.Cu")
		(net "TP_SPI_S3M_CPU0_IO2_LVC1_R")
	)
	(arc
		(start 351.413318 -266.613894)
		(mid 351.210731 -266.407543)
		(end 351.136712 -266.127992)
		(width 0.0889)
		(layer "B.Cu")
		(net "TP_SPI_S3M_CPU0_IO2_LVC1_R")
	)
	(arc
		(start 346.72016 -264.989818)
		(mid 346.532962 -264.939675)
		(end 346.345764 -264.989818)
		(width 0.0889)
		(layer "B.Cu")
		(net "TP_SPI_S3M_CPU0_IO2_LVC1_R")
	)
	(arc
		(start 350.105218 -264.989818)
		(mid 349.831019 -265.065653)
		(end 349.554546 -264.998454)
		(width 0.0889)
		(layer "B.Cu")
		(net "TP_SPI_S3M_CPU0_IO2_LVC1_R")
	)
	(arc
		(start 349.165418 -264.989818)
		(mid 348.891219 -265.065653)
		(end 348.614746 -264.998454)
		(width 0.0889)
		(layer "B.Cu")
		(net "TP_SPI_S3M_CPU0_IO2_LVC1_R")
	)
	(arc
		(start 335.820512 -265.332718)
		(mid 335.648588 -265.720515)
		(end 335.255362 -265.87958)
		(width 0.0889)
		(layer "B.Cu")
		(net "TP_SPI_S3M_CPU0_IO2_LVC1_R")
	)
	(arc
		(start 337.32216 -264.989818)
		(mid 337.134962 -264.939675)
		(end 336.947764 -264.989818)
		(width 0.0889)
		(layer "B.Cu")
		(net "TP_SPI_S3M_CPU0_IO2_LVC1_R")
	)
	(arc
		(start 345.780614 -264.989818)
		(mid 345.593416 -264.939675)
		(end 345.406218 -264.989818)
		(width 0.0889)
		(layer "B.Cu")
		(net "TP_SPI_S3M_CPU0_IO2_LVC1_R")
	)
	(arc
		(start 336.947764 -264.989818)
		(mid 336.665062 -265.065594)
		(end 336.38236 -264.989818)
		(width 0.0889)
		(layer "B.Cu")
		(net "TP_SPI_S3M_CPU0_IO2_LVC1_R")
	)
	(arc
		(start 337.887564 -264.989818)
		(mid 337.604862 -265.065594)
		(end 337.32216 -264.989818)
		(width 0.0889)
		(layer "B.Cu")
		(net "TP_SPI_S3M_CPU0_IO2_LVC1_R")
	)
	(arc
		(start 350.94926 -265.803634)
		(mid 350.746437 -265.603403)
		(end 350.667066 -265.32967)
		(width 0.0889)
		(layer "B.Cu")
		(net "TP_SPI_S3M_CPU0_IO2_LVC1_R")
	)
	(arc
		(start 341.081614 -264.989818)
		(mid 340.894416 -264.939675)
		(end 340.707218 -264.989818)
		(width 0.0889)
		(layer "B.Cu")
		(net "TP_SPI_S3M_CPU0_IO2_LVC1_R")
	)
	(arc
		(start 349.539814 -264.989818)
		(mid 349.352616 -264.939675)
		(end 349.165418 -264.989818)
		(width 0.0889)
		(layer "B.Cu")
		(net "TP_SPI_S3M_CPU0_IO2_LVC1_R")
	)
	(arc
		(start 340.707218 -264.989818)
		(mid 340.430405 -265.065688)
		(end 340.151974 -264.995914)
		(width 0.0889)
		(layer "B.Cu")
		(net "TP_SPI_S3M_CPU0_IO2_LVC1_R")
	)
	(arc
		(start 343.901014 -264.989818)
		(mid 343.713816 -264.939675)
		(end 343.526618 -264.989818)
		(width 0.0889)
		(layer "B.Cu")
		(net "TP_SPI_S3M_CPU0_IO2_LVC1_R")
	)
	(arc
		(start 340.14156 -264.989818)
		(mid 339.954362 -264.939675)
		(end 339.767164 -264.989818)
		(width 0.0889)
		(layer "B.Cu")
		(net "TP_SPI_S3M_CPU0_IO2_LVC1_R")
	)
	(arc
		(start 342.021414 -264.989818)
		(mid 341.834216 -264.939675)
		(end 341.647018 -264.989818)
		(width 0.0889)
		(layer "B.Cu")
		(net "TP_SPI_S3M_CPU0_IO2_LVC1_R")
	)
	(arc
		(start 352.076512 -267.755878)
		(mid 352.028833 -267.572978)
		(end 351.89795 -267.4366)
		(width 0.0889)
		(layer "B.Cu")
		(net "TP_SPI_S3M_CPU0_IO2_LVC1_R")
	)
	(arc
		(start 336.38236 -264.989818)
		(mid 336.195162 -264.939675)
		(end 336.007964 -264.989818)
		(width 0.0889)
		(layer "B.Cu")
		(net "TP_SPI_S3M_CPU0_IO2_LVC1_R")
	)
	(arc
		(start 338.827618 -264.989818)
		(mid 338.550805 -265.065688)
		(end 338.272374 -264.995914)
		(width 0.0889)
		(layer "B.Cu")
		(net "TP_SPI_S3M_CPU0_IO2_LVC1_R")
	)
	(segment
		(start 350.762316 -267.219938)
		(end 350.762062 -267.220192)
		(width 0.12954)
		(layer "F.Cu")
		(net "TP_SPI_S3M_CPU0_IO1_LVC1_R")
	)
	(segment
		(start 350.762062 -267.220192)
		(end 350.762062 -267.755878)
		(width 0.12954)
		(layer "F.Cu")
		(net "TP_SPI_S3M_CPU0_IO1_LVC1_R")
	)
	(via
		(at 350.762062 -267.755878)
		(size 0.4572)
		(drill 0.2032)
		(layers "F.Cu" "B.Cu")
		(net "TP_SPI_S3M_CPU0_IO1_LVC1_R")
	)
	(segment
		(start 351.701862 -265.592306)
		(end 351.701862 -266.128246)
		(width 0.12954)
		(layer "F.Cu")
		(net "TP_SPI_S3M_CPU0_IO0_LVC1_R")
	)
	(segment
		(start 351.702116 -265.592306)
		(end 351.701862 -265.592306)
		(width 0.12954)
		(layer "F.Cu")
		(net "TP_SPI_S3M_CPU0_IO0_LVC1_R")
	)
	(via
		(at 351.701862 -266.128246)
		(size 0.4572)
		(drill 0.2032)
		(layers "F.Cu" "B.Cu")
		(net "TP_SPI_S3M_CPU0_IO0_LVC1_R")
	)
	(segment
		(start 350.292162 -266.405868)
		(end 350.292162 -266.941554)
		(width 0.12954)
		(layer "F.Cu")
		(net "TP_SPI_S3M_CPU0_CS1_LVC1_R_N")
	)
	(segment
		(start 350.292162 -266.941554)
		(end 350.292416 -266.941808)
		(width 0.12954)
		(layer "F.Cu")
		(net "TP_SPI_S3M_CPU0_CS1_LVC1_R_N")
	)
	(via
		(at 350.292416 -266.941808)
		(size 0.4572)
		(drill 0.2032)
		(layers "F.Cu" "B.Cu")
		(net "TP_SPI_S3M_CPU0_CS1_LVC1_R_N")
	)
	(via
		(at 329.82916 -268.250416)
		(size 0.6604)
		(drill 0.3302)
		(layers "F.Cu" "B.Cu")
		(net "TP_SPI_S3M_CPU0_CS1_LVC1_R_N")
	)
	(segment
		(start 330.00696 -268.072616)
		(end 329.82916 -268.250416)
		(width 0.12954)
		(layer "B.Cu")
		(net "TP_SPI_S3M_CPU0_CS1_LVC1_R_N")
	)
	(segment
		(start 350.292416 -266.941808)
		(end 349.57004 -266.634976)
		(width 0.0889)
		(layer "B.Cu")
		(net "TP_SPI_S3M_CPU0_CS1_LVC1_R_N")
	)
	(segment
		(start 330.99629 -268.072616)
		(end 330.00696 -268.072616)
		(width 0.12954)
		(layer "B.Cu")
		(net "TP_SPI_S3M_CPU0_CS1_LVC1_R_N")
	)
	(segment
		(start 344.851228 -266.6238)
		(end 344.840814 -266.617704)
		(width 0.0889)
		(layer "B.Cu")
		(net "TP_SPI_S3M_CPU0_CS1_LVC1_R_N")
	)
	(segment
		(start 332.62951 -266.439396)
		(end 330.99629 -268.072616)
		(width 0.12954)
		(layer "B.Cu")
		(net "TP_SPI_S3M_CPU0_CS1_LVC1_R_N")
	)
	(segment
		(start 334.596994 -266.439396)
		(end 333.231998 -266.439396)
		(width 0.0889)
		(layer "B.Cu")
		(net "TP_SPI_S3M_CPU0_CS1_LVC1_R_N")
	)
	(segment
		(start 349.57004 -266.634976)
		(end 349.539814 -266.61745)
		(width 0.0889)
		(layer "B.Cu")
		(net "TP_SPI_S3M_CPU0_CS1_LVC1_R_N")
	)
	(segment
		(start 341.096346 -266.62634)
		(end 341.081614 -266.617704)
		(width 0.0889)
		(layer "B.Cu")
		(net "TP_SPI_S3M_CPU0_CS1_LVC1_R_N")
	)
	(segment
		(start 346.735146 -266.62634)
		(end 346.720414 -266.617704)
		(width 0.0889)
		(layer "B.Cu")
		(net "TP_SPI_S3M_CPU0_CS1_LVC1_R_N")
	)
	(segment
		(start 342.975946 -266.62634)
		(end 342.961214 -266.617704)
		(width 0.0889)
		(layer "B.Cu")
		(net "TP_SPI_S3M_CPU0_CS1_LVC1_R_N")
	)
	(segment
		(start 349.539814 -266.61745)
		(end 349.539814 -266.617704)
		(width 0.0889)
		(layer "B.Cu")
		(net "TP_SPI_S3M_CPU0_CS1_LVC1_R_N")
	)
	(segment
		(start 345.790774 -266.6238)
		(end 345.78036 -266.617704)
		(width 0.0889)
		(layer "B.Cu")
		(net "TP_SPI_S3M_CPU0_CS1_LVC1_R_N")
	)
	(segment
		(start 340.156546 -266.62634)
		(end 340.141814 -266.617704)
		(width 0.0889)
		(layer "B.Cu")
		(net "TP_SPI_S3M_CPU0_CS1_LVC1_R_N")
	)
	(segment
		(start 335.068164 -266.617704)
		(end 334.775302 -266.617704)
		(width 0.0889)
		(layer "B.Cu")
		(net "TP_SPI_S3M_CPU0_CS1_LVC1_R_N")
	)
	(segment
		(start 348.600268 -266.617704)
		(end 348.600014 -266.617704)
		(width 0.0889)
		(layer "B.Cu")
		(net "TP_SPI_S3M_CPU0_CS1_LVC1_R_N")
	)
	(segment
		(start 347.674946 -266.62634)
		(end 347.660214 -266.617704)
		(width 0.0889)
		(layer "B.Cu")
		(net "TP_SPI_S3M_CPU0_CS1_LVC1_R_N")
	)
	(segment
		(start 339.212174 -266.6238)
		(end 339.20176 -266.617704)
		(width 0.0889)
		(layer "B.Cu")
		(net "TP_SPI_S3M_CPU0_CS1_LVC1_R_N")
	)
	(segment
		(start 342.036146 -266.62634)
		(end 342.021414 -266.617704)
		(width 0.0889)
		(layer "B.Cu")
		(net "TP_SPI_S3M_CPU0_CS1_LVC1_R_N")
	)
	(segment
		(start 333.231998 -266.439396)
		(end 332.62951 -266.439396)
		(width 0.12954)
		(layer "B.Cu")
		(net "TP_SPI_S3M_CPU0_CS1_LVC1_R_N")
	)
	(segment
		(start 343.915746 -266.62634)
		(end 343.901014 -266.617704)
		(width 0.0889)
		(layer "B.Cu")
		(net "TP_SPI_S3M_CPU0_CS1_LVC1_R_N")
	)
	(segment
		(start 334.775302 -266.617704)
		(end 334.596994 -266.439396)
		(width 0.0889)
		(layer "B.Cu")
		(net "TP_SPI_S3M_CPU0_CS1_LVC1_R_N")
	)
	(arc
		(start 342.021414 -266.617704)
		(mid 341.834216 -266.567527)
		(end 341.647018 -266.617704)
		(width 0.0889)
		(layer "B.Cu")
		(net "TP_SPI_S3M_CPU0_CS1_LVC1_R_N")
	)
	(arc
		(start 346.720414 -266.617704)
		(mid 346.533216 -266.567527)
		(end 346.346018 -266.617704)
		(width 0.0889)
		(layer "B.Cu")
		(net "TP_SPI_S3M_CPU0_CS1_LVC1_R_N")
	)
	(arc
		(start 345.78036 -266.617704)
		(mid 345.593162 -266.567527)
		(end 345.405964 -266.617704)
		(width 0.0889)
		(layer "B.Cu")
		(net "TP_SPI_S3M_CPU0_CS1_LVC1_R_N")
	)
	(arc
		(start 345.405964 -266.617704)
		(mid 345.129405 -266.693447)
		(end 344.851228 -266.6238)
		(width 0.0889)
		(layer "B.Cu")
		(net "TP_SPI_S3M_CPU0_CS1_LVC1_R_N")
	)
	(arc
		(start 347.660214 -266.617704)
		(mid 347.473016 -266.567527)
		(end 347.285818 -266.617704)
		(width 0.0889)
		(layer "B.Cu")
		(net "TP_SPI_S3M_CPU0_CS1_LVC1_R_N")
	)
	(arc
		(start 342.586818 -266.617704)
		(mid 342.312619 -266.693539)
		(end 342.036146 -266.62634)
		(width 0.0889)
		(layer "B.Cu")
		(net "TP_SPI_S3M_CPU0_CS1_LVC1_R_N")
	)
	(arc
		(start 342.961214 -266.617704)
		(mid 342.774016 -266.567527)
		(end 342.586818 -266.617704)
		(width 0.0889)
		(layer "B.Cu")
		(net "TP_SPI_S3M_CPU0_CS1_LVC1_R_N")
	)
	(arc
		(start 347.285818 -266.617704)
		(mid 347.011619 -266.693539)
		(end 346.735146 -266.62634)
		(width 0.0889)
		(layer "B.Cu")
		(net "TP_SPI_S3M_CPU0_CS1_LVC1_R_N")
	)
	(arc
		(start 339.767418 -266.617704)
		(mid 339.490605 -266.693574)
		(end 339.212174 -266.6238)
		(width 0.0889)
		(layer "B.Cu")
		(net "TP_SPI_S3M_CPU0_CS1_LVC1_R_N")
	)
	(arc
		(start 336.947764 -266.617704)
		(mid 336.665062 -266.69348)
		(end 336.38236 -266.617704)
		(width 0.0889)
		(layer "B.Cu")
		(net "TP_SPI_S3M_CPU0_CS1_LVC1_R_N")
	)
	(arc
		(start 349.539814 -266.617704)
		(mid 349.352616 -266.567527)
		(end 349.165418 -266.617704)
		(width 0.0889)
		(layer "B.Cu")
		(net "TP_SPI_S3M_CPU0_CS1_LVC1_R_N")
	)
	(arc
		(start 343.526618 -266.617704)
		(mid 343.252419 -266.693539)
		(end 342.975946 -266.62634)
		(width 0.0889)
		(layer "B.Cu")
		(net "TP_SPI_S3M_CPU0_CS1_LVC1_R_N")
	)
	(arc
		(start 348.225618 -266.617704)
		(mid 347.951419 -266.693539)
		(end 347.674946 -266.62634)
		(width 0.0889)
		(layer "B.Cu")
		(net "TP_SPI_S3M_CPU0_CS1_LVC1_R_N")
	)
	(arc
		(start 344.466418 -266.617704)
		(mid 344.192219 -266.693539)
		(end 343.915746 -266.62634)
		(width 0.0889)
		(layer "B.Cu")
		(net "TP_SPI_S3M_CPU0_CS1_LVC1_R_N")
	)
	(arc
		(start 346.346018 -266.617704)
		(mid 346.069205 -266.693574)
		(end 345.790774 -266.6238)
		(width 0.0889)
		(layer "B.Cu")
		(net "TP_SPI_S3M_CPU0_CS1_LVC1_R_N")
	)
	(arc
		(start 348.600014 -266.617704)
		(mid 348.412816 -266.567527)
		(end 348.225618 -266.617704)
		(width 0.0889)
		(layer "B.Cu")
		(net "TP_SPI_S3M_CPU0_CS1_LVC1_R_N")
	)
	(arc
		(start 343.901014 -266.617704)
		(mid 343.713816 -266.567527)
		(end 343.526618 -266.617704)
		(width 0.0889)
		(layer "B.Cu")
		(net "TP_SPI_S3M_CPU0_CS1_LVC1_R_N")
	)
	(arc
		(start 340.141814 -266.617704)
		(mid 339.954616 -266.567527)
		(end 339.767418 -266.617704)
		(width 0.0889)
		(layer "B.Cu")
		(net "TP_SPI_S3M_CPU0_CS1_LVC1_R_N")
	)
	(arc
		(start 344.840814 -266.617704)
		(mid 344.653616 -266.567527)
		(end 344.466418 -266.617704)
		(width 0.0889)
		(layer "B.Cu")
		(net "TP_SPI_S3M_CPU0_CS1_LVC1_R_N")
	)
	(arc
		(start 336.007964 -266.617704)
		(mid 335.725262 -266.69348)
		(end 335.44256 -266.617704)
		(width 0.0889)
		(layer "B.Cu")
		(net "TP_SPI_S3M_CPU0_CS1_LVC1_R_N")
	)
	(arc
		(start 338.827364 -266.617704)
		(mid 338.544662 -266.69348)
		(end 338.26196 -266.617704)
		(width 0.0889)
		(layer "B.Cu")
		(net "TP_SPI_S3M_CPU0_CS1_LVC1_R_N")
	)
	(arc
		(start 337.32216 -266.617704)
		(mid 337.134962 -266.567527)
		(end 336.947764 -266.617704)
		(width 0.0889)
		(layer "B.Cu")
		(net "TP_SPI_S3M_CPU0_CS1_LVC1_R_N")
	)
	(arc
		(start 349.165418 -266.617704)
		(mid 348.88286 -266.693387)
		(end 348.600268 -266.617704)
		(width 0.0889)
		(layer "B.Cu")
		(net "TP_SPI_S3M_CPU0_CS1_LVC1_R_N")
	)
	(arc
		(start 337.887564 -266.617704)
		(mid 337.604862 -266.69348)
		(end 337.32216 -266.617704)
		(width 0.0889)
		(layer "B.Cu")
		(net "TP_SPI_S3M_CPU0_CS1_LVC1_R_N")
	)
	(arc
		(start 339.20176 -266.617704)
		(mid 339.014562 -266.567527)
		(end 338.827364 -266.617704)
		(width 0.0889)
		(layer "B.Cu")
		(net "TP_SPI_S3M_CPU0_CS1_LVC1_R_N")
	)
	(arc
		(start 338.26196 -266.617704)
		(mid 338.074762 -266.567527)
		(end 337.887564 -266.617704)
		(width 0.0889)
		(layer "B.Cu")
		(net "TP_SPI_S3M_CPU0_CS1_LVC1_R_N")
	)
	(arc
		(start 341.081614 -266.617704)
		(mid 340.894416 -266.567527)
		(end 340.707218 -266.617704)
		(width 0.0889)
		(layer "B.Cu")
		(net "TP_SPI_S3M_CPU0_CS1_LVC1_R_N")
	)
	(arc
		(start 340.707218 -266.617704)
		(mid 340.433019 -266.693539)
		(end 340.156546 -266.62634)
		(width 0.0889)
		(layer "B.Cu")
		(net "TP_SPI_S3M_CPU0_CS1_LVC1_R_N")
	)
	(arc
		(start 336.38236 -266.617704)
		(mid 336.195162 -266.567527)
		(end 336.007964 -266.617704)
		(width 0.0889)
		(layer "B.Cu")
		(net "TP_SPI_S3M_CPU0_CS1_LVC1_R_N")
	)
	(arc
		(start 341.647018 -266.617704)
		(mid 341.372819 -266.693539)
		(end 341.096346 -266.62634)
		(width 0.0889)
		(layer "B.Cu")
		(net "TP_SPI_S3M_CPU0_CS1_LVC1_R_N")
	)
	(arc
		(start 335.44256 -266.617704)
		(mid 335.255362 -266.567527)
		(end 335.068164 -266.617704)
		(width 0.0889)
		(layer "B.Cu")
		(net "TP_SPI_S3M_CPU0_CS1_LVC1_R_N")
	)
	(segment
		(start 352.171762 -264.778236)
		(end 352.171762 -265.313922)
		(width 0.12954)
		(layer "F.Cu")
		(net "TP_SPI_S3M_CPU0_CS0_LVC1_R_N")
	)
	(segment
		(start 352.171762 -265.313922)
		(end 352.172016 -265.314176)
		(width 0.12954)
		(layer "F.Cu")
		(net "TP_SPI_S3M_CPU0_CS0_LVC1_R_N")
	)
	(via
		(at 330.416154 -265.090656)
		(size 0.6604)
		(drill 0.3302)
		(layers "F.Cu" "B.Cu")
		(net "TP_SPI_S3M_CPU0_CS0_LVC1_R_N")
	)
	(via
		(at 352.172016 -265.314176)
		(size 0.4572)
		(drill 0.2032)
		(layers "F.Cu" "B.Cu")
		(net "TP_SPI_S3M_CPU0_CS0_LVC1_R_N")
	)
	(segment
		(start 340.237064 -262.548116)
		(end 340.222332 -262.556752)
		(width 0.0889)
		(layer "B.Cu")
		(net "TP_SPI_S3M_CPU0_CS0_LVC1_R_N")
	)
	(segment
		(start 348.695264 -262.548116)
		(end 348.680532 -262.556752)
		(width 0.0889)
		(layer "B.Cu")
		(net "TP_SPI_S3M_CPU0_CS0_LVC1_R_N")
	)
	(segment
		(start 337.802474 -262.554212)
		(end 337.79206 -262.548116)
		(width 0.0889)
		(layer "B.Cu")
		(net "TP_SPI_S3M_CPU0_CS0_LVC1_R_N")
	)
	(segment
		(start 338.742528 -262.554212)
		(end 338.732114 -262.548116)
		(width 0.0889)
		(layer "B.Cu")
		(net "TP_SPI_S3M_CPU0_CS0_LVC1_R_N")
	)
	(segment
		(start 342.116664 -262.548116)
		(end 342.101932 -262.556752)
		(width 0.0889)
		(layer "B.Cu")
		(net "TP_SPI_S3M_CPU0_CS0_LVC1_R_N")
	)
	(segment
		(start 351.327212 -263.847072)
		(end 350.417892 -262.937752)
		(width 0.0889)
		(layer "B.Cu")
		(net "TP_SPI_S3M_CPU0_CS0_LVC1_R_N")
	)
	(segment
		(start 349.478092 -262.937752)
		(end 349.147638 -262.607298)
		(width 0.0889)
		(layer "B.Cu")
		(net "TP_SPI_S3M_CPU0_CS0_LVC1_R_N")
	)
	(segment
		(start 351.52076 -264.828274)
		(end 351.514664 -264.824718)
		(width 0.0889)
		(layer "B.Cu")
		(net "TP_SPI_S3M_CPU0_CS0_LVC1_R_N")
	)
	(segment
		(start 346.815664 -262.548116)
		(end 346.800932 -262.556752)
		(width 0.0889)
		(layer "B.Cu")
		(net "TP_SPI_S3M_CPU0_CS0_LVC1_R_N")
	)
	(segment
		(start 332.7908 -262.71601)
		(end 330.416154 -265.090656)
		(width 0.12954)
		(layer "B.Cu")
		(net "TP_SPI_S3M_CPU0_CS0_LVC1_R_N")
	)
	(segment
		(start 334.476598 -262.71601)
		(end 332.7908 -262.71601)
		(width 0.12954)
		(layer "B.Cu")
		(net "TP_SPI_S3M_CPU0_CS0_LVC1_R_N")
	)
	(segment
		(start 347.755464 -262.548116)
		(end 347.740732 -262.556752)
		(width 0.0889)
		(layer "B.Cu")
		(net "TP_SPI_S3M_CPU0_CS0_LVC1_R_N")
	)
	(segment
		(start 341.176864 -262.548116)
		(end 341.162132 -262.556752)
		(width 0.0889)
		(layer "B.Cu")
		(net "TP_SPI_S3M_CPU0_CS0_LVC1_R_N")
	)
	(segment
		(start 351.327212 -264.50036)
		(end 351.327212 -263.847072)
		(width 0.0889)
		(layer "B.Cu")
		(net "TP_SPI_S3M_CPU0_CS0_LVC1_R_N")
	)
	(segment
		(start 337.417664 -262.548116)
		(end 337.402932 -262.556752)
		(width 0.0889)
		(layer "B.Cu")
		(net "TP_SPI_S3M_CPU0_CS0_LVC1_R_N")
	)
	(segment
		(start 351.514664 -264.824718)
		(end 351.505774 -264.819638)
		(width 0.0889)
		(layer "B.Cu")
		(net "TP_SPI_S3M_CPU0_CS0_LVC1_R_N")
	)
	(segment
		(start 345.321128 -262.554212)
		(end 345.310714 -262.548116)
		(width 0.0889)
		(layer "B.Cu")
		(net "TP_SPI_S3M_CPU0_CS0_LVC1_R_N")
	)
	(segment
		(start 352.172016 -265.314176)
		(end 351.735136 -265.056112)
		(width 0.0889)
		(layer "B.Cu")
		(net "TP_SPI_S3M_CPU0_CS0_LVC1_R_N")
	)
	(segment
		(start 344.936318 -262.548116)
		(end 344.925904 -262.554212)
		(width 0.0889)
		(layer "B.Cu")
		(net "TP_SPI_S3M_CPU0_CS0_LVC1_R_N")
	)
	(segment
		(start 343.996264 -262.548116)
		(end 343.981532 -262.556752)
		(width 0.0889)
		(layer "B.Cu")
		(net "TP_SPI_S3M_CPU0_CS0_LVC1_R_N")
	)
	(segment
		(start 335.851246 -262.71601)
		(end 334.476598 -262.71601)
		(width 0.0889)
		(layer "B.Cu")
		(net "TP_SPI_S3M_CPU0_CS0_LVC1_R_N")
	)
	(segment
		(start 343.056464 -262.548116)
		(end 343.041732 -262.556752)
		(width 0.0889)
		(layer "B.Cu")
		(net "TP_SPI_S3M_CPU0_CS0_LVC1_R_N")
	)
	(segment
		(start 350.417892 -262.937752)
		(end 349.478092 -262.937752)
		(width 0.0889)
		(layer "B.Cu")
		(net "TP_SPI_S3M_CPU0_CS0_LVC1_R_N")
	)
	(arc
		(start 348.12986 -262.548116)
		(mid 347.942662 -262.497973)
		(end 347.755464 -262.548116)
		(width 0.0889)
		(layer "B.Cu")
		(net "TP_SPI_S3M_CPU0_CS0_LVC1_R_N")
	)
	(arc
		(start 344.37066 -262.548116)
		(mid 344.183462 -262.497973)
		(end 343.996264 -262.548116)
		(width 0.0889)
		(layer "B.Cu")
		(net "TP_SPI_S3M_CPU0_CS0_LVC1_R_N")
	)
	(arc
		(start 343.041732 -262.556752)
		(mid 342.765257 -262.624072)
		(end 342.49106 -262.548116)
		(width 0.0889)
		(layer "B.Cu")
		(net "TP_SPI_S3M_CPU0_CS0_LVC1_R_N")
	)
	(arc
		(start 345.310714 -262.548116)
		(mid 345.123516 -262.497973)
		(end 344.936318 -262.548116)
		(width 0.0889)
		(layer "B.Cu")
		(net "TP_SPI_S3M_CPU0_CS0_LVC1_R_N")
	)
	(arc
		(start 347.740732 -262.556752)
		(mid 347.464257 -262.624072)
		(end 347.19006 -262.548116)
		(width 0.0889)
		(layer "B.Cu")
		(net "TP_SPI_S3M_CPU0_CS0_LVC1_R_N")
	)
	(arc
		(start 346.800932 -262.556752)
		(mid 346.524457 -262.624072)
		(end 346.25026 -262.548116)
		(width 0.0889)
		(layer "B.Cu")
		(net "TP_SPI_S3M_CPU0_CS0_LVC1_R_N")
	)
	(arc
		(start 340.61146 -262.548116)
		(mid 340.424262 -262.497973)
		(end 340.237064 -262.548116)
		(width 0.0889)
		(layer "B.Cu")
		(net "TP_SPI_S3M_CPU0_CS0_LVC1_R_N")
	)
	(arc
		(start 338.357718 -262.548116)
		(mid 338.080905 -262.623986)
		(end 337.802474 -262.554212)
		(width 0.0889)
		(layer "B.Cu")
		(net "TP_SPI_S3M_CPU0_CS0_LVC1_R_N")
	)
	(arc
		(start 345.875864 -262.548116)
		(mid 345.599305 -262.623859)
		(end 345.321128 -262.554212)
		(width 0.0889)
		(layer "B.Cu")
		(net "TP_SPI_S3M_CPU0_CS0_LVC1_R_N")
	)
	(arc
		(start 351.735136 -265.056112)
		(mid 351.64401 -264.927085)
		(end 351.52076 -264.828274)
		(width 0.0889)
		(layer "B.Cu")
		(net "TP_SPI_S3M_CPU0_CS0_LVC1_R_N")
	)
	(arc
		(start 337.79206 -262.548116)
		(mid 337.604862 -262.497973)
		(end 337.417664 -262.548116)
		(width 0.0889)
		(layer "B.Cu")
		(net "TP_SPI_S3M_CPU0_CS0_LVC1_R_N")
	)
	(arc
		(start 343.981532 -262.556752)
		(mid 343.705057 -262.624072)
		(end 343.43086 -262.548116)
		(width 0.0889)
		(layer "B.Cu")
		(net "TP_SPI_S3M_CPU0_CS0_LVC1_R_N")
	)
	(arc
		(start 347.19006 -262.548116)
		(mid 347.002862 -262.497973)
		(end 346.815664 -262.548116)
		(width 0.0889)
		(layer "B.Cu")
		(net "TP_SPI_S3M_CPU0_CS0_LVC1_R_N")
	)
	(arc
		(start 349.147638 -262.607298)
		(mid 348.931506 -262.500975)
		(end 348.695264 -262.548116)
		(width 0.0889)
		(layer "B.Cu")
		(net "TP_SPI_S3M_CPU0_CS0_LVC1_R_N")
	)
	(arc
		(start 351.505774 -264.819638)
		(mid 351.37486 -264.683278)
		(end 351.327212 -264.50036)
		(width 0.0889)
		(layer "B.Cu")
		(net "TP_SPI_S3M_CPU0_CS0_LVC1_R_N")
	)
	(arc
		(start 339.67166 -262.548116)
		(mid 339.484462 -262.497973)
		(end 339.297264 -262.548116)
		(width 0.0889)
		(layer "B.Cu")
		(net "TP_SPI_S3M_CPU0_CS0_LVC1_R_N")
	)
	(arc
		(start 336.85226 -262.548116)
		(mid 336.665062 -262.497973)
		(end 336.477864 -262.548116)
		(width 0.0889)
		(layer "B.Cu")
		(net "TP_SPI_S3M_CPU0_CS0_LVC1_R_N")
	)
	(arc
		(start 342.101932 -262.556752)
		(mid 341.825457 -262.624072)
		(end 341.55126 -262.548116)
		(width 0.0889)
		(layer "B.Cu")
		(net "TP_SPI_S3M_CPU0_CS0_LVC1_R_N")
	)
	(arc
		(start 339.297264 -262.548116)
		(mid 339.020705 -262.623859)
		(end 338.742528 -262.554212)
		(width 0.0889)
		(layer "B.Cu")
		(net "TP_SPI_S3M_CPU0_CS0_LVC1_R_N")
	)
	(arc
		(start 336.477864 -262.548116)
		(mid 336.175598 -262.673264)
		(end 335.851246 -262.71601)
		(width 0.0889)
		(layer "B.Cu")
		(net "TP_SPI_S3M_CPU0_CS0_LVC1_R_N")
	)
	(arc
		(start 340.222332 -262.556752)
		(mid 339.945857 -262.624072)
		(end 339.67166 -262.548116)
		(width 0.0889)
		(layer "B.Cu")
		(net "TP_SPI_S3M_CPU0_CS0_LVC1_R_N")
	)
	(arc
		(start 348.680532 -262.556752)
		(mid 348.404057 -262.624072)
		(end 348.12986 -262.548116)
		(width 0.0889)
		(layer "B.Cu")
		(net "TP_SPI_S3M_CPU0_CS0_LVC1_R_N")
	)
	(arc
		(start 341.162132 -262.556752)
		(mid 340.885657 -262.624072)
		(end 340.61146 -262.548116)
		(width 0.0889)
		(layer "B.Cu")
		(net "TP_SPI_S3M_CPU0_CS0_LVC1_R_N")
	)
	(arc
		(start 343.43086 -262.548116)
		(mid 343.243662 -262.497973)
		(end 343.056464 -262.548116)
		(width 0.0889)
		(layer "B.Cu")
		(net "TP_SPI_S3M_CPU0_CS0_LVC1_R_N")
	)
	(arc
		(start 342.49106 -262.548116)
		(mid 342.303862 -262.497973)
		(end 342.116664 -262.548116)
		(width 0.0889)
		(layer "B.Cu")
		(net "TP_SPI_S3M_CPU0_CS0_LVC1_R_N")
	)
	(arc
		(start 341.55126 -262.548116)
		(mid 341.364062 -262.497973)
		(end 341.176864 -262.548116)
		(width 0.0889)
		(layer "B.Cu")
		(net "TP_SPI_S3M_CPU0_CS0_LVC1_R_N")
	)
	(arc
		(start 337.402932 -262.556752)
		(mid 337.126457 -262.624072)
		(end 336.85226 -262.548116)
		(width 0.0889)
		(layer "B.Cu")
		(net "TP_SPI_S3M_CPU0_CS0_LVC1_R_N")
	)
	(arc
		(start 338.732114 -262.548116)
		(mid 338.544916 -262.497973)
		(end 338.357718 -262.548116)
		(width 0.0889)
		(layer "B.Cu")
		(net "TP_SPI_S3M_CPU0_CS0_LVC1_R_N")
	)
	(arc
		(start 346.25026 -262.548116)
		(mid 346.063062 -262.497973)
		(end 345.875864 -262.548116)
		(width 0.0889)
		(layer "B.Cu")
		(net "TP_SPI_S3M_CPU0_CS0_LVC1_R_N")
	)
	(arc
		(start 344.925904 -262.554212)
		(mid 344.647472 -262.624058)
		(end 344.37066 -262.548116)
		(width 0.0889)
		(layer "B.Cu")
		(net "TP_SPI_S3M_CPU0_CS0_LVC1_R_N")
	)
	(segment
		(start 352.641916 -267.219938)
		(end 352.641916 -267.755624)
		(width 0.12954)
		(layer "F.Cu")
		(net "TP_SPI_S3M_CPU0_CLK_LVC1_R")
	)
	(segment
		(start 352.641916 -267.755624)
		(end 352.641662 -267.755878)
		(width 0.12954)
		(layer "F.Cu")
		(net "TP_SPI_S3M_CPU0_CLK_LVC1_R")
	)
	(via
		(at 326.090788 -268.174216)
		(size 0.6604)
		(drill 0.3302)
		(layers "F.Cu" "B.Cu")
		(net "TP_SPI_S3M_CPU0_CLK_LVC1_R")
	)
	(via
		(at 352.641662 -267.755878)
		(size 0.4572)
		(drill 0.2032)
		(layers "F.Cu" "B.Cu")
		(net "TP_SPI_S3M_CPU0_CLK_LVC1_R")
	)
	(segment
		(start 348.695264 -264.824718)
		(end 348.680532 -264.816082)
		(width 0.0889)
		(layer "B.Cu")
		(net "TP_SPI_S3M_CPU0_CLK_LVC1_R")
	)
	(segment
		(start 344.936064 -264.824718)
		(end 344.921332 -264.816082)
		(width 0.0889)
		(layer "B.Cu")
		(net "TP_SPI_S3M_CPU0_CLK_LVC1_R")
	)
	(segment
		(start 334.936592 -265.689334)
		(end 334.907128 -265.718798)
		(width 0.12954)
		(layer "B.Cu")
		(net "TP_SPI_S3M_CPU0_CLK_LVC1_R")
	)
	(segment
		(start 330.600812 -267.223748)
		(end 327.035922 -267.223748)
		(width 0.12954)
		(layer "B.Cu")
		(net "TP_SPI_S3M_CPU0_CLK_LVC1_R")
	)
	(segment
		(start 352.454464 -268.080236)
		(end 352.445574 -268.075156)
		(width 0.0889)
		(layer "B.Cu")
		(net "TP_SPI_S3M_CPU0_CLK_LVC1_R")
	)
	(segment
		(start 343.996264 -264.824718)
		(end 343.981532 -264.816082)
		(width 0.0889)
		(layer "B.Cu")
		(net "TP_SPI_S3M_CPU0_CLK_LVC1_R")
	)
	(segment
		(start 335.630012 -265.30427)
		(end 335.630012 -265.314176)
		(width 0.0889)
		(layer "B.Cu")
		(net "TP_SPI_S3M_CPU0_CLK_LVC1_R")
	)
	(segment
		(start 339.297518 -264.824718)
		(end 339.287104 -264.818622)
		(width 0.0889)
		(layer "B.Cu")
		(net "TP_SPI_S3M_CPU0_CLK_LVC1_R")
	)
	(segment
		(start 343.056464 -264.824718)
		(end 343.041732 -264.816082)
		(width 0.0889)
		(layer "B.Cu")
		(net "TP_SPI_S3M_CPU0_CLK_LVC1_R")
	)
	(segment
		(start 334.907128 -265.718798)
		(end 332.105762 -265.718798)
		(width 0.12954)
		(layer "B.Cu")
		(net "TP_SPI_S3M_CPU0_CLK_LVC1_R")
	)
	(segment
		(start 346.260928 -264.818622)
		(end 346.250514 -264.824718)
		(width 0.0889)
		(layer "B.Cu")
		(net "TP_SPI_S3M_CPU0_CLK_LVC1_R")
	)
	(segment
		(start 349.635064 -264.824718)
		(end 349.620332 -264.816082)
		(width 0.0889)
		(layer "B.Cu")
		(net "TP_SPI_S3M_CPU0_CLK_LVC1_R")
	)
	(segment
		(start 352.641662 -267.755878)
		(end 352.798126 -268.026896)
		(width 0.0889)
		(layer "B.Cu")
		(net "TP_SPI_S3M_CPU0_CLK_LVC1_R")
	)
	(segment
		(start 347.755464 -264.824718)
		(end 347.740732 -264.816082)
		(width 0.0889)
		(layer "B.Cu")
		(net "TP_SPI_S3M_CPU0_CLK_LVC1_R")
	)
	(segment
		(start 350.574864 -264.824718)
		(end 350.560132 -264.816082)
		(width 0.0889)
		(layer "B.Cu")
		(net "TP_SPI_S3M_CPU0_CLK_LVC1_R")
	)
	(segment
		(start 335.45145 -265.633454)
		(end 335.44256 -265.638534)
		(width 0.0889)
		(layer "B.Cu")
		(net "TP_SPI_S3M_CPU0_CLK_LVC1_R")
	)
	(segment
		(start 351.514664 -266.45235)
		(end 351.505774 -266.44727)
		(width 0.0889)
		(layer "B.Cu")
		(net "TP_SPI_S3M_CPU0_CLK_LVC1_R")
	)
	(segment
		(start 352.267012 -267.755878)
		(end 352.267012 -267.737336)
		(width 0.0889)
		(layer "B.Cu")
		(net "TP_SPI_S3M_CPU0_CLK_LVC1_R")
	)
	(segment
		(start 351.045018 -265.638534)
		(end 351.036128 -265.633454)
		(width 0.0889)
		(layer "B.Cu")
		(net "TP_SPI_S3M_CPU0_CLK_LVC1_R")
	)
	(segment
		(start 351.327212 -266.127992)
		(end 351.327212 -266.112498)
		(width 0.0889)
		(layer "B.Cu")
		(net "TP_SPI_S3M_CPU0_CLK_LVC1_R")
	)
	(segment
		(start 352.798126 -268.026896)
		(end 352.777044 -268.104874)
		(width 0.0889)
		(layer "B.Cu")
		(net "TP_SPI_S3M_CPU0_CLK_LVC1_R")
	)
	(segment
		(start 342.116664 -264.824718)
		(end 342.101932 -264.816082)
		(width 0.0889)
		(layer "B.Cu")
		(net "TP_SPI_S3M_CPU0_CLK_LVC1_R")
	)
	(segment
		(start 350.58096 -264.828274)
		(end 350.574864 -264.824718)
		(width 0.0889)
		(layer "B.Cu")
		(net "TP_SPI_S3M_CPU0_CLK_LVC1_R")
	)
	(segment
		(start 332.105762 -265.718798)
		(end 330.600812 -267.223748)
		(width 0.12954)
		(layer "B.Cu")
		(net "TP_SPI_S3M_CPU0_CLK_LVC1_R")
	)
	(segment
		(start 345.876118 -264.824718)
		(end 345.865704 -264.818622)
		(width 0.0889)
		(layer "B.Cu")
		(net "TP_SPI_S3M_CPU0_CLK_LVC1_R")
	)
	(segment
		(start 351.797366 -266.950444)
		(end 351.797366 -266.941808)
		(width 0.0889)
		(layer "B.Cu")
		(net "TP_SPI_S3M_CPU0_CLK_LVC1_R")
	)
	(segment
		(start 335.255362 -265.689334)
		(end 334.936592 -265.689334)
		(width 0.0889)
		(layer "B.Cu")
		(net "TP_SPI_S3M_CPU0_CLK_LVC1_R")
	)
	(segment
		(start 351.52076 -266.455906)
		(end 351.514664 -266.45235)
		(width 0.0889)
		(layer "B.Cu")
		(net "TP_SPI_S3M_CPU0_CLK_LVC1_R")
	)
	(segment
		(start 341.176864 -264.824718)
		(end 341.162132 -264.816082)
		(width 0.0889)
		(layer "B.Cu")
		(net "TP_SPI_S3M_CPU0_CLK_LVC1_R")
	)
	(segment
		(start 327.035922 -267.223748)
		(end 326.0979 -268.16177)
		(width 0.12954)
		(layer "B.Cu")
		(net "TP_SPI_S3M_CPU0_CLK_LVC1_R")
	)
	(segment
		(start 339.682328 -264.818622)
		(end 339.671914 -264.824718)
		(width 0.0889)
		(layer "B.Cu")
		(net "TP_SPI_S3M_CPU0_CLK_LVC1_R")
	)
	(segment
		(start 326.0979 -268.167104)
		(end 326.090788 -268.174216)
		(width 0.12954)
		(layer "B.Cu")
		(net "TP_SPI_S3M_CPU0_CLK_LVC1_R")
	)
	(segment
		(start 326.0979 -268.16177)
		(end 326.0979 -268.167104)
		(width 0.12954)
		(layer "B.Cu")
		(net "TP_SPI_S3M_CPU0_CLK_LVC1_R")
	)
	(arc
		(start 347.740732 -264.816082)
		(mid 347.464257 -264.748762)
		(end 347.19006 -264.824718)
		(width 0.0889)
		(layer "B.Cu")
		(net "TP_SPI_S3M_CPU0_CLK_LVC1_R")
	)
	(arc
		(start 351.984564 -267.266166)
		(mid 351.849631 -267.132812)
		(end 351.797366 -266.950444)
		(width 0.0889)
		(layer "B.Cu")
		(net "TP_SPI_S3M_CPU0_CLK_LVC1_R")
	)
	(arc
		(start 352.777044 -268.104874)
		(mid 352.612948 -268.129221)
		(end 352.454464 -268.080236)
		(width 0.0889)
		(layer "B.Cu")
		(net "TP_SPI_S3M_CPU0_CLK_LVC1_R")
	)
	(arc
		(start 347.19006 -264.824718)
		(mid 347.002862 -264.874861)
		(end 346.815664 -264.824718)
		(width 0.0889)
		(layer "B.Cu")
		(net "TP_SPI_S3M_CPU0_CLK_LVC1_R")
	)
	(arc
		(start 352.267012 -267.737336)
		(mid 352.18685 -267.465147)
		(end 351.984564 -267.266166)
		(width 0.0889)
		(layer "B.Cu")
		(net "TP_SPI_S3M_CPU0_CLK_LVC1_R")
	)
	(arc
		(start 346.815664 -264.824718)
		(mid 346.539105 -264.748975)
		(end 346.260928 -264.818622)
		(width 0.0889)
		(layer "B.Cu")
		(net "TP_SPI_S3M_CPU0_CLK_LVC1_R")
	)
	(arc
		(start 346.250514 -264.824718)
		(mid 346.063316 -264.874861)
		(end 345.876118 -264.824718)
		(width 0.0889)
		(layer "B.Cu")
		(net "TP_SPI_S3M_CPU0_CLK_LVC1_R")
	)
	(arc
		(start 345.865704 -264.818622)
		(mid 345.587272 -264.748776)
		(end 345.31046 -264.824718)
		(width 0.0889)
		(layer "B.Cu")
		(net "TP_SPI_S3M_CPU0_CLK_LVC1_R")
	)
	(arc
		(start 338.357464 -264.824718)
		(mid 338.074762 -264.748942)
		(end 337.79206 -264.824718)
		(width 0.0889)
		(layer "B.Cu")
		(net "TP_SPI_S3M_CPU0_CLK_LVC1_R")
	)
	(arc
		(start 350.00946 -264.824718)
		(mid 349.822262 -264.874861)
		(end 349.635064 -264.824718)
		(width 0.0889)
		(layer "B.Cu")
		(net "TP_SPI_S3M_CPU0_CLK_LVC1_R")
	)
	(arc
		(start 344.37066 -264.824718)
		(mid 344.183462 -264.874861)
		(end 343.996264 -264.824718)
		(width 0.0889)
		(layer "B.Cu")
		(net "TP_SPI_S3M_CPU0_CLK_LVC1_R")
	)
	(arc
		(start 348.12986 -264.824718)
		(mid 347.942662 -264.874861)
		(end 347.755464 -264.824718)
		(width 0.0889)
		(layer "B.Cu")
		(net "TP_SPI_S3M_CPU0_CLK_LVC1_R")
	)
	(arc
		(start 344.921332 -264.816082)
		(mid 344.644857 -264.748762)
		(end 344.37066 -264.824718)
		(width 0.0889)
		(layer "B.Cu")
		(net "TP_SPI_S3M_CPU0_CLK_LVC1_R")
	)
	(arc
		(start 336.477864 -264.824718)
		(mid 336.195162 -264.748942)
		(end 335.91246 -264.824718)
		(width 0.0889)
		(layer "B.Cu")
		(net "TP_SPI_S3M_CPU0_CLK_LVC1_R")
	)
	(arc
		(start 342.49106 -264.824718)
		(mid 342.303862 -264.874861)
		(end 342.116664 -264.824718)
		(width 0.0889)
		(layer "B.Cu")
		(net "TP_SPI_S3M_CPU0_CLK_LVC1_R")
	)
	(arc
		(start 337.417664 -264.824718)
		(mid 337.134962 -264.748942)
		(end 336.85226 -264.824718)
		(width 0.0889)
		(layer "B.Cu")
		(net "TP_SPI_S3M_CPU0_CLK_LVC1_R")
	)
	(arc
		(start 341.162132 -264.816082)
		(mid 340.885657 -264.748762)
		(end 340.61146 -264.824718)
		(width 0.0889)
		(layer "B.Cu")
		(net "TP_SPI_S3M_CPU0_CLK_LVC1_R")
	)
	(arc
		(start 340.237064 -264.824718)
		(mid 339.960505 -264.748975)
		(end 339.682328 -264.818622)
		(width 0.0889)
		(layer "B.Cu")
		(net "TP_SPI_S3M_CPU0_CLK_LVC1_R")
	)
	(arc
		(start 343.43086 -264.824718)
		(mid 343.243662 -264.874861)
		(end 343.056464 -264.824718)
		(width 0.0889)
		(layer "B.Cu")
		(net "TP_SPI_S3M_CPU0_CLK_LVC1_R")
	)
	(arc
		(start 335.91246 -264.824718)
		(mid 335.708125 -265.027323)
		(end 335.630012 -265.30427)
		(width 0.0889)
		(layer "B.Cu")
		(net "TP_SPI_S3M_CPU0_CLK_LVC1_R")
	)
	(arc
		(start 349.06966 -264.824718)
		(mid 348.882462 -264.874861)
		(end 348.695264 -264.824718)
		(width 0.0889)
		(layer "B.Cu")
		(net "TP_SPI_S3M_CPU0_CLK_LVC1_R")
	)
	(arc
		(start 337.79206 -264.824718)
		(mid 337.604862 -264.874861)
		(end 337.417664 -264.824718)
		(width 0.0889)
		(layer "B.Cu")
		(net "TP_SPI_S3M_CPU0_CLK_LVC1_R")
	)
	(arc
		(start 340.61146 -264.824718)
		(mid 340.424262 -264.874861)
		(end 340.237064 -264.824718)
		(width 0.0889)
		(layer "B.Cu")
		(net "TP_SPI_S3M_CPU0_CLK_LVC1_R")
	)
	(arc
		(start 350.560132 -264.816082)
		(mid 350.283657 -264.748762)
		(end 350.00946 -264.824718)
		(width 0.0889)
		(layer "B.Cu")
		(net "TP_SPI_S3M_CPU0_CLK_LVC1_R")
	)
	(arc
		(start 351.505774 -266.44727)
		(mid 351.37486 -266.31091)
		(end 351.327212 -266.127992)
		(width 0.0889)
		(layer "B.Cu")
		(net "TP_SPI_S3M_CPU0_CLK_LVC1_R")
	)
	(arc
		(start 338.73186 -264.824718)
		(mid 338.544662 -264.874861)
		(end 338.357464 -264.824718)
		(width 0.0889)
		(layer "B.Cu")
		(net "TP_SPI_S3M_CPU0_CLK_LVC1_R")
	)
	(arc
		(start 341.55126 -264.824718)
		(mid 341.364062 -264.874861)
		(end 341.176864 -264.824718)
		(width 0.0889)
		(layer "B.Cu")
		(net "TP_SPI_S3M_CPU0_CLK_LVC1_R")
	)
	(arc
		(start 339.671914 -264.824718)
		(mid 339.484716 -264.874861)
		(end 339.297518 -264.824718)
		(width 0.0889)
		(layer "B.Cu")
		(net "TP_SPI_S3M_CPU0_CLK_LVC1_R")
	)
	(arc
		(start 335.44256 -265.638534)
		(mid 335.352304 -265.676256)
		(end 335.255362 -265.689334)
		(width 0.0889)
		(layer "B.Cu")
		(net "TP_SPI_S3M_CPU0_CLK_LVC1_R")
	)
	(arc
		(start 336.85226 -264.824718)
		(mid 336.665062 -264.874861)
		(end 336.477864 -264.824718)
		(width 0.0889)
		(layer "B.Cu")
		(net "TP_SPI_S3M_CPU0_CLK_LVC1_R")
	)
	(arc
		(start 351.036128 -265.633454)
		(mid 350.905214 -265.497094)
		(end 350.857566 -265.314176)
		(width 0.0889)
		(layer "B.Cu")
		(net "TP_SPI_S3M_CPU0_CLK_LVC1_R")
	)
	(arc
		(start 342.101932 -264.816082)
		(mid 341.825457 -264.748762)
		(end 341.55126 -264.824718)
		(width 0.0889)
		(layer "B.Cu")
		(net "TP_SPI_S3M_CPU0_CLK_LVC1_R")
	)
	(arc
		(start 343.041732 -264.816082)
		(mid 342.765257 -264.748762)
		(end 342.49106 -264.824718)
		(width 0.0889)
		(layer "B.Cu")
		(net "TP_SPI_S3M_CPU0_CLK_LVC1_R")
	)
	(arc
		(start 343.981532 -264.816082)
		(mid 343.705057 -264.748762)
		(end 343.43086 -264.824718)
		(width 0.0889)
		(layer "B.Cu")
		(net "TP_SPI_S3M_CPU0_CLK_LVC1_R")
	)
	(arc
		(start 348.680532 -264.816082)
		(mid 348.404057 -264.748762)
		(end 348.12986 -264.824718)
		(width 0.0889)
		(layer "B.Cu")
		(net "TP_SPI_S3M_CPU0_CLK_LVC1_R")
	)
	(arc
		(start 352.445574 -268.075156)
		(mid 352.31466 -267.938796)
		(end 352.267012 -267.755878)
		(width 0.0889)
		(layer "B.Cu")
		(net "TP_SPI_S3M_CPU0_CLK_LVC1_R")
	)
	(arc
		(start 345.31046 -264.824718)
		(mid 345.123262 -264.874861)
		(end 344.936064 -264.824718)
		(width 0.0889)
		(layer "B.Cu")
		(net "TP_SPI_S3M_CPU0_CLK_LVC1_R")
	)
	(arc
		(start 335.630012 -265.314176)
		(mid 335.582333 -265.497076)
		(end 335.45145 -265.633454)
		(width 0.0889)
		(layer "B.Cu")
		(net "TP_SPI_S3M_CPU0_CLK_LVC1_R")
	)
	(arc
		(start 349.620332 -264.816082)
		(mid 349.343857 -264.748762)
		(end 349.06966 -264.824718)
		(width 0.0889)
		(layer "B.Cu")
		(net "TP_SPI_S3M_CPU0_CLK_LVC1_R")
	)
	(arc
		(start 351.327212 -266.112498)
		(mid 351.247842 -265.838764)
		(end 351.045018 -265.638534)
		(width 0.0889)
		(layer "B.Cu")
		(net "TP_SPI_S3M_CPU0_CLK_LVC1_R")
	)
	(arc
		(start 351.797366 -266.941808)
		(mid 351.723375 -266.662242)
		(end 351.52076 -266.455906)
		(width 0.0889)
		(layer "B.Cu")
		(net "TP_SPI_S3M_CPU0_CLK_LVC1_R")
	)
	(arc
		(start 339.287104 -264.818622)
		(mid 339.008672 -264.748776)
		(end 338.73186 -264.824718)
		(width 0.0889)
		(layer "B.Cu")
		(net "TP_SPI_S3M_CPU0_CLK_LVC1_R")
	)
	(arc
		(start 350.857566 -265.314176)
		(mid 350.783575 -265.03461)
		(end 350.58096 -264.828274)
		(width 0.0889)
		(layer "B.Cu")
		(net "TP_SPI_S3M_CPU0_CLK_LVC1_R")
	)
	(segment
		(start 330.79436 -40.461946)
		(end 330.255118 -40.461946)
		(width 0.12954)
		(layer "F.Cu")
		(net "TP_SPI_PCH_CS1_R_N")
	)
	(via
		(at 330.255118 -40.461946)
		(size 0.4572)
		(drill 0.2032)
		(layers "F.Cu" "B.Cu")
		(net "TP_SPI_PCH_CS1_R_N")
	)
	(via
		(at 330.322174 -38.35908)
		(size 0.6604)
		(drill 0.3302)
		(layers "F.Cu" "B.Cu")
		(net "TP_SPI_PCH_CS1_R_N")
	)
	(segment
		(start 330.255118 -39.866316)
		(end 329.995022 -39.60622)
		(width 0.12954)
		(layer "B.Cu")
		(net "TP_SPI_PCH_CS1_R_N")
	)
	(segment
		(start 329.995022 -38.686232)
		(end 330.322174 -38.35908)
		(width 0.12954)
		(layer "B.Cu")
		(net "TP_SPI_PCH_CS1_R_N")
	)
	(segment
		(start 330.255118 -40.461946)
		(end 330.255118 -39.866316)
		(width 0.12954)
		(layer "B.Cu")
		(net "TP_SPI_PCH_CS1_R_N")
	)
	(segment
		(start 329.995022 -39.60622)
		(end 329.995022 -38.686232)
		(width 0.12954)
		(layer "B.Cu")
		(net "TP_SPI_PCH_CS1_R_N")
	)
	(segment
		(start 352.171762 -269.66164)
		(end 352.172016 -269.661894)
		(width 0.12954)
		(layer "F.Cu")
		(net "TP_SPI_IBL_CPU0_TPM_OE_N")
	)
	(segment
		(start 352.172016 -269.661894)
		(end 352.172016 -270.19758)
		(width 0.12954)
		(layer "F.Cu")
		(net "TP_SPI_IBL_CPU0_TPM_OE_N")
	)
	(via
		(at 352.172016 -270.19758)
		(size 0.4572)
		(drill 0.2032)
		(layers "F.Cu" "B.Cu")
		(net "TP_SPI_IBL_CPU0_TPM_OE_N")
	)
	(via
		(at 329.305412 -270.291306)
		(size 0.6604)
		(drill 0.3302)
		(layers "F.Cu" "B.Cu")
		(net "TP_SPI_IBL_CPU0_TPM_OE_N")
	)
	(segment
		(start 345.791028 -270.515842)
		(end 345.780614 -270.521938)
		(width 0.0889)
		(layer "B.Cu")
		(net "TP_SPI_IBL_CPU0_TPM_OE_N")
	)
	(segment
		(start 343.915746 -270.513302)
		(end 343.901014 -270.521938)
		(width 0.0889)
		(layer "B.Cu")
		(net "TP_SPI_IBL_CPU0_TPM_OE_N")
	)
	(segment
		(start 352.015552 -270.468598)
		(end 351.926398 -270.492474)
		(width 0.0889)
		(layer "B.Cu")
		(net "TP_SPI_IBL_CPU0_TPM_OE_N")
	)
	(segment
		(start 335.068164 -270.521938)
		(end 334.846422 -270.393668)
		(width 0.0889)
		(layer "B.Cu")
		(net "TP_SPI_IBL_CPU0_TPM_OE_N")
	)
	(segment
		(start 334.047084 -270.38173)
		(end 333.9084 -270.520414)
		(width 0.12954)
		(layer "B.Cu")
		(net "TP_SPI_IBL_CPU0_TPM_OE_N")
	)
	(segment
		(start 351.434146 -270.513302)
		(end 351.419414 -270.521938)
		(width 0.0889)
		(layer "B.Cu")
		(net "TP_SPI_IBL_CPU0_TPM_OE_N")
	)
	(segment
		(start 347.674946 -270.513302)
		(end 347.660214 -270.521938)
		(width 0.0889)
		(layer "B.Cu")
		(net "TP_SPI_IBL_CPU0_TPM_OE_N")
	)
	(segment
		(start 342.975946 -270.513302)
		(end 342.961214 -270.521938)
		(width 0.0889)
		(layer "B.Cu")
		(net "TP_SPI_IBL_CPU0_TPM_OE_N")
	)
	(segment
		(start 338.272374 -270.515842)
		(end 338.26196 -270.521938)
		(width 0.0889)
		(layer "B.Cu")
		(net "TP_SPI_IBL_CPU0_TPM_OE_N")
	)
	(segment
		(start 334.801718 -270.38173)
		(end 334.047084 -270.38173)
		(width 0.0889)
		(layer "B.Cu")
		(net "TP_SPI_IBL_CPU0_TPM_OE_N")
	)
	(segment
		(start 341.096346 -270.513302)
		(end 341.081614 -270.521938)
		(width 0.0889)
		(layer "B.Cu")
		(net "TP_SPI_IBL_CPU0_TPM_OE_N")
	)
	(segment
		(start 339.212428 -270.515842)
		(end 339.202014 -270.521938)
		(width 0.0889)
		(layer "B.Cu")
		(net "TP_SPI_IBL_CPU0_TPM_OE_N")
	)
	(segment
		(start 352.172016 -270.19758)
		(end 352.015552 -270.468598)
		(width 0.0889)
		(layer "B.Cu")
		(net "TP_SPI_IBL_CPU0_TPM_OE_N")
	)
	(segment
		(start 340.151974 -270.515842)
		(end 340.14156 -270.521938)
		(width 0.0889)
		(layer "B.Cu")
		(net "TP_SPI_IBL_CPU0_TPM_OE_N")
	)
	(segment
		(start 333.9084 -270.520414)
		(end 329.53452 -270.520414)
		(width 0.12954)
		(layer "B.Cu")
		(net "TP_SPI_IBL_CPU0_TPM_OE_N")
	)
	(segment
		(start 346.730574 -270.515842)
		(end 346.72016 -270.521938)
		(width 0.0889)
		(layer "B.Cu")
		(net "TP_SPI_IBL_CPU0_TPM_OE_N")
	)
	(segment
		(start 329.53452 -270.520414)
		(end 329.305412 -270.291306)
		(width 0.12954)
		(layer "B.Cu")
		(net "TP_SPI_IBL_CPU0_TPM_OE_N")
	)
	(segment
		(start 344.855546 -270.513302)
		(end 344.840814 -270.521938)
		(width 0.0889)
		(layer "B.Cu")
		(net "TP_SPI_IBL_CPU0_TPM_OE_N")
	)
	(segment
		(start 350.494346 -270.513302)
		(end 350.479614 -270.521938)
		(width 0.0889)
		(layer "B.Cu")
		(net "TP_SPI_IBL_CPU0_TPM_OE_N")
	)
	(arc
		(start 337.887564 -270.521938)
		(mid 337.604862 -270.446162)
		(end 337.32216 -270.521938)
		(width 0.0889)
		(layer "B.Cu")
		(net "TP_SPI_IBL_CPU0_TPM_OE_N")
	)
	(arc
		(start 346.72016 -270.521938)
		(mid 346.532962 -270.572081)
		(end 346.345764 -270.521938)
		(width 0.0889)
		(layer "B.Cu")
		(net "TP_SPI_IBL_CPU0_TPM_OE_N")
	)
	(arc
		(start 345.780614 -270.521938)
		(mid 345.593416 -270.572081)
		(end 345.406218 -270.521938)
		(width 0.0889)
		(layer "B.Cu")
		(net "TP_SPI_IBL_CPU0_TPM_OE_N")
	)
	(arc
		(start 340.707218 -270.521938)
		(mid 340.430405 -270.446068)
		(end 340.151974 -270.515842)
		(width 0.0889)
		(layer "B.Cu")
		(net "TP_SPI_IBL_CPU0_TPM_OE_N")
	)
	(arc
		(start 343.901014 -270.521938)
		(mid 343.713816 -270.572081)
		(end 343.526618 -270.521938)
		(width 0.0889)
		(layer "B.Cu")
		(net "TP_SPI_IBL_CPU0_TPM_OE_N")
	)
	(arc
		(start 351.926398 -270.492474)
		(mid 351.677893 -270.446487)
		(end 351.434146 -270.513302)
		(width 0.0889)
		(layer "B.Cu")
		(net "TP_SPI_IBL_CPU0_TPM_OE_N")
	)
	(arc
		(start 342.021414 -270.521938)
		(mid 341.834216 -270.572081)
		(end 341.647018 -270.521938)
		(width 0.0889)
		(layer "B.Cu")
		(net "TP_SPI_IBL_CPU0_TPM_OE_N")
	)
	(arc
		(start 345.406218 -270.521938)
		(mid 345.132019 -270.446103)
		(end 344.855546 -270.513302)
		(width 0.0889)
		(layer "B.Cu")
		(net "TP_SPI_IBL_CPU0_TPM_OE_N")
	)
	(arc
		(start 341.081614 -270.521938)
		(mid 340.894416 -270.572081)
		(end 340.707218 -270.521938)
		(width 0.0889)
		(layer "B.Cu")
		(net "TP_SPI_IBL_CPU0_TPM_OE_N")
	)
	(arc
		(start 335.44256 -270.521938)
		(mid 335.255362 -270.572081)
		(end 335.068164 -270.521938)
		(width 0.0889)
		(layer "B.Cu")
		(net "TP_SPI_IBL_CPU0_TPM_OE_N")
	)
	(arc
		(start 342.586818 -270.521938)
		(mid 342.304116 -270.446162)
		(end 342.021414 -270.521938)
		(width 0.0889)
		(layer "B.Cu")
		(net "TP_SPI_IBL_CPU0_TPM_OE_N")
	)
	(arc
		(start 349.165418 -270.521938)
		(mid 348.882716 -270.446162)
		(end 348.600014 -270.521938)
		(width 0.0889)
		(layer "B.Cu")
		(net "TP_SPI_IBL_CPU0_TPM_OE_N")
	)
	(arc
		(start 344.840814 -270.521938)
		(mid 344.653616 -270.572081)
		(end 344.466418 -270.521938)
		(width 0.0889)
		(layer "B.Cu")
		(net "TP_SPI_IBL_CPU0_TPM_OE_N")
	)
	(arc
		(start 344.466418 -270.521938)
		(mid 344.192219 -270.446103)
		(end 343.915746 -270.513302)
		(width 0.0889)
		(layer "B.Cu")
		(net "TP_SPI_IBL_CPU0_TPM_OE_N")
	)
	(arc
		(start 336.947764 -270.521938)
		(mid 336.665062 -270.446162)
		(end 336.38236 -270.521938)
		(width 0.0889)
		(layer "B.Cu")
		(net "TP_SPI_IBL_CPU0_TPM_OE_N")
	)
	(arc
		(start 334.846422 -270.393668)
		(mid 334.824862 -270.384715)
		(end 334.801718 -270.38173)
		(width 0.0889)
		(layer "B.Cu")
		(net "TP_SPI_IBL_CPU0_TPM_OE_N")
	)
	(arc
		(start 347.285818 -270.521938)
		(mid 347.009005 -270.446068)
		(end 346.730574 -270.515842)
		(width 0.0889)
		(layer "B.Cu")
		(net "TP_SPI_IBL_CPU0_TPM_OE_N")
	)
	(arc
		(start 348.600014 -270.521938)
		(mid 348.412816 -270.572081)
		(end 348.225618 -270.521938)
		(width 0.0889)
		(layer "B.Cu")
		(net "TP_SPI_IBL_CPU0_TPM_OE_N")
	)
	(arc
		(start 351.419414 -270.521938)
		(mid 351.232216 -270.572081)
		(end 351.045018 -270.521938)
		(width 0.0889)
		(layer "B.Cu")
		(net "TP_SPI_IBL_CPU0_TPM_OE_N")
	)
	(arc
		(start 347.660214 -270.521938)
		(mid 347.473016 -270.572081)
		(end 347.285818 -270.521938)
		(width 0.0889)
		(layer "B.Cu")
		(net "TP_SPI_IBL_CPU0_TPM_OE_N")
	)
	(arc
		(start 338.827618 -270.521938)
		(mid 338.550805 -270.446068)
		(end 338.272374 -270.515842)
		(width 0.0889)
		(layer "B.Cu")
		(net "TP_SPI_IBL_CPU0_TPM_OE_N")
	)
	(arc
		(start 342.961214 -270.521938)
		(mid 342.774016 -270.572081)
		(end 342.586818 -270.521938)
		(width 0.0889)
		(layer "B.Cu")
		(net "TP_SPI_IBL_CPU0_TPM_OE_N")
	)
	(arc
		(start 348.225618 -270.521938)
		(mid 347.951419 -270.446103)
		(end 347.674946 -270.513302)
		(width 0.0889)
		(layer "B.Cu")
		(net "TP_SPI_IBL_CPU0_TPM_OE_N")
	)
	(arc
		(start 346.345764 -270.521938)
		(mid 346.069205 -270.446195)
		(end 345.791028 -270.515842)
		(width 0.0889)
		(layer "B.Cu")
		(net "TP_SPI_IBL_CPU0_TPM_OE_N")
	)
	(arc
		(start 339.202014 -270.521938)
		(mid 339.014816 -270.572081)
		(end 338.827618 -270.521938)
		(width 0.0889)
		(layer "B.Cu")
		(net "TP_SPI_IBL_CPU0_TPM_OE_N")
	)
	(arc
		(start 343.526618 -270.521938)
		(mid 343.252419 -270.446103)
		(end 342.975946 -270.513302)
		(width 0.0889)
		(layer "B.Cu")
		(net "TP_SPI_IBL_CPU0_TPM_OE_N")
	)
	(arc
		(start 351.045018 -270.521938)
		(mid 350.770819 -270.446103)
		(end 350.494346 -270.513302)
		(width 0.0889)
		(layer "B.Cu")
		(net "TP_SPI_IBL_CPU0_TPM_OE_N")
	)
	(arc
		(start 338.26196 -270.521938)
		(mid 338.074762 -270.572081)
		(end 337.887564 -270.521938)
		(width 0.0889)
		(layer "B.Cu")
		(net "TP_SPI_IBL_CPU0_TPM_OE_N")
	)
	(arc
		(start 336.007964 -270.521938)
		(mid 335.725262 -270.446162)
		(end 335.44256 -270.521938)
		(width 0.0889)
		(layer "B.Cu")
		(net "TP_SPI_IBL_CPU0_TPM_OE_N")
	)
	(arc
		(start 336.38236 -270.521938)
		(mid 336.195162 -270.572081)
		(end 336.007964 -270.521938)
		(width 0.0889)
		(layer "B.Cu")
		(net "TP_SPI_IBL_CPU0_TPM_OE_N")
	)
	(arc
		(start 340.14156 -270.521938)
		(mid 339.954362 -270.572081)
		(end 339.767164 -270.521938)
		(width 0.0889)
		(layer "B.Cu")
		(net "TP_SPI_IBL_CPU0_TPM_OE_N")
	)
	(arc
		(start 349.539814 -270.521938)
		(mid 349.352616 -270.572081)
		(end 349.165418 -270.521938)
		(width 0.0889)
		(layer "B.Cu")
		(net "TP_SPI_IBL_CPU0_TPM_OE_N")
	)
	(arc
		(start 337.32216 -270.521938)
		(mid 337.134962 -270.572081)
		(end 336.947764 -270.521938)
		(width 0.0889)
		(layer "B.Cu")
		(net "TP_SPI_IBL_CPU0_TPM_OE_N")
	)
	(arc
		(start 341.647018 -270.521938)
		(mid 341.372819 -270.446103)
		(end 341.096346 -270.513302)
		(width 0.0889)
		(layer "B.Cu")
		(net "TP_SPI_IBL_CPU0_TPM_OE_N")
	)
	(arc
		(start 339.767164 -270.521938)
		(mid 339.490605 -270.446195)
		(end 339.212428 -270.515842)
		(width 0.0889)
		(layer "B.Cu")
		(net "TP_SPI_IBL_CPU0_TPM_OE_N")
	)
	(arc
		(start 350.479614 -270.521938)
		(mid 350.292416 -270.572081)
		(end 350.105218 -270.521938)
		(width 0.0889)
		(layer "B.Cu")
		(net "TP_SPI_IBL_CPU0_TPM_OE_N")
	)
	(arc
		(start 350.105218 -270.521938)
		(mid 349.822516 -270.446162)
		(end 349.539814 -270.521938)
		(width 0.0889)
		(layer "B.Cu")
		(net "TP_SPI_IBL_CPU0_TPM_OE_N")
	)
	(segment
		(start 351.231962 -265.313922)
		(end 351.232216 -265.314176)
		(width 0.12954)
		(layer "F.Cu")
		(net "TP_SPI_IBL_CPU0_TPM_IO1")
	)
	(segment
		(start 351.231962 -264.778236)
		(end 351.231962 -265.313922)
		(width 0.12954)
		(layer "F.Cu")
		(net "TP_SPI_IBL_CPU0_TPM_IO1")
	)
	(via
		(at 351.232216 -265.314176)
		(size 0.4572)
		(drill 0.2032)
		(layers "F.Cu" "B.Cu")
		(net "TP_SPI_IBL_CPU0_TPM_IO1")
	)
	(segment
		(start 351.702116 -269.383256)
		(end 351.701862 -269.38351)
		(width 0.12954)
		(layer "F.Cu")
		(net "TP_SPI_IBL_CPU0_TPM_IO0")
	)
	(segment
		(start 351.702116 -268.84757)
		(end 351.702116 -269.383256)
		(width 0.12954)
		(layer "F.Cu")
		(net "TP_SPI_IBL_CPU0_TPM_IO0")
	)
	(via
		(at 351.701862 -269.38351)
		(size 0.4572)
		(drill 0.2032)
		(layers "F.Cu" "B.Cu")
		(net "TP_SPI_IBL_CPU0_TPM_IO0")
	)
	(via
		(at 333.19212 -268.959076)
		(size 0.6604)
		(drill 0.3302)
		(layers "F.Cu" "B.Cu")
		(net "TP_SPI_IBL_CPU0_TPM_IO0")
	)
	(segment
		(start 333.19212 -268.959076)
		(end 334.234028 -268.959076)
		(width 0.12954)
		(layer "B.Cu")
		(net "TP_SPI_IBL_CPU0_TPM_IO0")
	)
	(segment
		(start 350.009714 -269.059152)
		(end 350.009968 -269.059152)
		(width 0.0889)
		(layer "B.Cu")
		(net "TP_SPI_IBL_CPU0_TPM_IO0")
	)
	(segment
		(start 341.162132 -269.067788)
		(end 341.176864 -269.059152)
		(width 0.0889)
		(layer "B.Cu")
		(net "TP_SPI_IBL_CPU0_TPM_IO0")
	)
	(segment
		(start 350.949514 -269.059152)
		(end 350.977962 -269.075662)
		(width 0.0889)
		(layer "B.Cu")
		(net "TP_SPI_IBL_CPU0_TPM_IO0")
	)
	(segment
		(start 339.287104 -269.065248)
		(end 339.297518 -269.059152)
		(width 0.0889)
		(layer "B.Cu")
		(net "TP_SPI_IBL_CPU0_TPM_IO0")
	)
	(segment
		(start 334.844898 -268.959076)
		(end 334.85582 -268.969998)
		(width 0.0889)
		(layer "B.Cu")
		(net "TP_SPI_IBL_CPU0_TPM_IO0")
	)
	(segment
		(start 350.977962 -269.075662)
		(end 351.701862 -269.38351)
		(width 0.0889)
		(layer "B.Cu")
		(net "TP_SPI_IBL_CPU0_TPM_IO0")
	)
	(segment
		(start 349.06966 -269.059152)
		(end 349.080074 -269.065248)
		(width 0.0889)
		(layer "B.Cu")
		(net "TP_SPI_IBL_CPU0_TPM_IO0")
	)
	(segment
		(start 345.865704 -269.065248)
		(end 345.876118 -269.059152)
		(width 0.0889)
		(layer "B.Cu")
		(net "TP_SPI_IBL_CPU0_TPM_IO0")
	)
	(segment
		(start 342.101932 -269.067788)
		(end 342.116664 -269.059152)
		(width 0.0889)
		(layer "B.Cu")
		(net "TP_SPI_IBL_CPU0_TPM_IO0")
	)
	(segment
		(start 346.80525 -269.065248)
		(end 346.815664 -269.059152)
		(width 0.0889)
		(layer "B.Cu")
		(net "TP_SPI_IBL_CPU0_TPM_IO0")
	)
	(segment
		(start 334.234028 -268.959076)
		(end 334.844898 -268.959076)
		(width 0.0889)
		(layer "B.Cu")
		(net "TP_SPI_IBL_CPU0_TPM_IO0")
	)
	(segment
		(start 350.94926 -269.059152)
		(end 350.949514 -269.059152)
		(width 0.0889)
		(layer "B.Cu")
		(net "TP_SPI_IBL_CPU0_TPM_IO0")
	)
	(segment
		(start 347.740732 -269.067788)
		(end 347.755464 -269.059152)
		(width 0.0889)
		(layer "B.Cu")
		(net "TP_SPI_IBL_CPU0_TPM_IO0")
	)
	(segment
		(start 348.680532 -269.067788)
		(end 348.695264 -269.059152)
		(width 0.0889)
		(layer "B.Cu")
		(net "TP_SPI_IBL_CPU0_TPM_IO0")
	)
	(segment
		(start 344.93581 -269.059152)
		(end 344.936064 -269.059152)
		(width 0.0889)
		(layer "B.Cu")
		(net "TP_SPI_IBL_CPU0_TPM_IO0")
	)
	(segment
		(start 343.981532 -269.067788)
		(end 343.996264 -269.059152)
		(width 0.0889)
		(layer "B.Cu")
		(net "TP_SPI_IBL_CPU0_TPM_IO0")
	)
	(segment
		(start 340.22665 -269.065248)
		(end 340.237064 -269.059152)
		(width 0.0889)
		(layer "B.Cu")
		(net "TP_SPI_IBL_CPU0_TPM_IO0")
	)
	(arc
		(start 350.009968 -269.059152)
		(mid 350.292416 -269.134801)
		(end 350.574864 -269.059152)
		(width 0.0889)
		(layer "B.Cu")
		(net "TP_SPI_IBL_CPU0_TPM_IO0")
	)
	(arc
		(start 343.996264 -269.059152)
		(mid 344.183462 -269.009009)
		(end 344.37066 -269.059152)
		(width 0.0889)
		(layer "B.Cu")
		(net "TP_SPI_IBL_CPU0_TPM_IO0")
	)
	(arc
		(start 347.755464 -269.059152)
		(mid 347.942662 -269.009009)
		(end 348.12986 -269.059152)
		(width 0.0889)
		(layer "B.Cu")
		(net "TP_SPI_IBL_CPU0_TPM_IO0")
	)
	(arc
		(start 342.49106 -269.059152)
		(mid 342.773762 -269.134928)
		(end 343.056464 -269.059152)
		(width 0.0889)
		(layer "B.Cu")
		(net "TP_SPI_IBL_CPU0_TPM_IO0")
	)
	(arc
		(start 347.19006 -269.059152)
		(mid 347.464259 -269.134987)
		(end 347.740732 -269.067788)
		(width 0.0889)
		(layer "B.Cu")
		(net "TP_SPI_IBL_CPU0_TPM_IO0")
	)
	(arc
		(start 345.31046 -269.059152)
		(mid 345.587273 -269.135022)
		(end 345.865704 -269.065248)
		(width 0.0889)
		(layer "B.Cu")
		(net "TP_SPI_IBL_CPU0_TPM_IO0")
	)
	(arc
		(start 337.417664 -269.059152)
		(mid 337.604862 -269.009009)
		(end 337.79206 -269.059152)
		(width 0.0889)
		(layer "B.Cu")
		(net "TP_SPI_IBL_CPU0_TPM_IO0")
	)
	(arc
		(start 334.908652 -269.016226)
		(mid 334.939924 -269.038781)
		(end 334.97266 -269.059152)
		(width 0.0889)
		(layer "B.Cu")
		(net "TP_SPI_IBL_CPU0_TPM_IO0")
	)
	(arc
		(start 349.080074 -269.065248)
		(mid 349.358506 -269.135094)
		(end 349.635318 -269.059152)
		(width 0.0889)
		(layer "B.Cu")
		(net "TP_SPI_IBL_CPU0_TPM_IO0")
	)
	(arc
		(start 342.116664 -269.059152)
		(mid 342.303862 -269.009009)
		(end 342.49106 -269.059152)
		(width 0.0889)
		(layer "B.Cu")
		(net "TP_SPI_IBL_CPU0_TPM_IO0")
	)
	(arc
		(start 336.477864 -269.059152)
		(mid 336.665062 -269.009009)
		(end 336.85226 -269.059152)
		(width 0.0889)
		(layer "B.Cu")
		(net "TP_SPI_IBL_CPU0_TPM_IO0")
	)
	(arc
		(start 334.97266 -269.059152)
		(mid 335.255362 -269.134928)
		(end 335.538064 -269.059152)
		(width 0.0889)
		(layer "B.Cu")
		(net "TP_SPI_IBL_CPU0_TPM_IO0")
	)
	(arc
		(start 345.876118 -269.059152)
		(mid 346.063316 -269.009009)
		(end 346.250514 -269.059152)
		(width 0.0889)
		(layer "B.Cu")
		(net "TP_SPI_IBL_CPU0_TPM_IO0")
	)
	(arc
		(start 348.12986 -269.059152)
		(mid 348.404059 -269.134987)
		(end 348.680532 -269.067788)
		(width 0.0889)
		(layer "B.Cu")
		(net "TP_SPI_IBL_CPU0_TPM_IO0")
	)
	(arc
		(start 337.79206 -269.059152)
		(mid 338.074762 -269.134928)
		(end 338.357464 -269.059152)
		(width 0.0889)
		(layer "B.Cu")
		(net "TP_SPI_IBL_CPU0_TPM_IO0")
	)
	(arc
		(start 344.936064 -269.059152)
		(mid 345.123262 -269.009009)
		(end 345.31046 -269.059152)
		(width 0.0889)
		(layer "B.Cu")
		(net "TP_SPI_IBL_CPU0_TPM_IO0")
	)
	(arc
		(start 341.176864 -269.059152)
		(mid 341.364062 -269.009009)
		(end 341.55126 -269.059152)
		(width 0.0889)
		(layer "B.Cu")
		(net "TP_SPI_IBL_CPU0_TPM_IO0")
	)
	(arc
		(start 336.85226 -269.059152)
		(mid 337.134962 -269.134928)
		(end 337.417664 -269.059152)
		(width 0.0889)
		(layer "B.Cu")
		(net "TP_SPI_IBL_CPU0_TPM_IO0")
	)
	(arc
		(start 338.73186 -269.059152)
		(mid 339.008673 -269.135022)
		(end 339.287104 -269.065248)
		(width 0.0889)
		(layer "B.Cu")
		(net "TP_SPI_IBL_CPU0_TPM_IO0")
	)
	(arc
		(start 340.237064 -269.059152)
		(mid 340.424262 -269.009009)
		(end 340.61146 -269.059152)
		(width 0.0889)
		(layer "B.Cu")
		(net "TP_SPI_IBL_CPU0_TPM_IO0")
	)
	(arc
		(start 346.250514 -269.059152)
		(mid 346.527073 -269.134895)
		(end 346.80525 -269.065248)
		(width 0.0889)
		(layer "B.Cu")
		(net "TP_SPI_IBL_CPU0_TPM_IO0")
	)
	(arc
		(start 335.538064 -269.059152)
		(mid 335.725262 -269.009009)
		(end 335.91246 -269.059152)
		(width 0.0889)
		(layer "B.Cu")
		(net "TP_SPI_IBL_CPU0_TPM_IO0")
	)
	(arc
		(start 346.815664 -269.059152)
		(mid 347.002862 -269.009009)
		(end 347.19006 -269.059152)
		(width 0.0889)
		(layer "B.Cu")
		(net "TP_SPI_IBL_CPU0_TPM_IO0")
	)
	(arc
		(start 343.056464 -269.059152)
		(mid 343.243662 -269.009009)
		(end 343.43086 -269.059152)
		(width 0.0889)
		(layer "B.Cu")
		(net "TP_SPI_IBL_CPU0_TPM_IO0")
	)
	(arc
		(start 335.91246 -269.059152)
		(mid 336.195162 -269.134928)
		(end 336.477864 -269.059152)
		(width 0.0889)
		(layer "B.Cu")
		(net "TP_SPI_IBL_CPU0_TPM_IO0")
	)
	(arc
		(start 341.55126 -269.059152)
		(mid 341.825459 -269.134987)
		(end 342.101932 -269.067788)
		(width 0.0889)
		(layer "B.Cu")
		(net "TP_SPI_IBL_CPU0_TPM_IO0")
	)
	(arc
		(start 338.357464 -269.059152)
		(mid 338.544662 -269.009009)
		(end 338.73186 -269.059152)
		(width 0.0889)
		(layer "B.Cu")
		(net "TP_SPI_IBL_CPU0_TPM_IO0")
	)
	(arc
		(start 343.43086 -269.059152)
		(mid 343.705059 -269.134987)
		(end 343.981532 -269.067788)
		(width 0.0889)
		(layer "B.Cu")
		(net "TP_SPI_IBL_CPU0_TPM_IO0")
	)
	(arc
		(start 348.695264 -269.059152)
		(mid 348.882462 -269.009009)
		(end 349.06966 -269.059152)
		(width 0.0889)
		(layer "B.Cu")
		(net "TP_SPI_IBL_CPU0_TPM_IO0")
	)
	(arc
		(start 350.574864 -269.059152)
		(mid 350.762062 -269.009009)
		(end 350.94926 -269.059152)
		(width 0.0889)
		(layer "B.Cu")
		(net "TP_SPI_IBL_CPU0_TPM_IO0")
	)
	(arc
		(start 349.635318 -269.059152)
		(mid 349.822516 -269.008975)
		(end 350.009714 -269.059152)
		(width 0.0889)
		(layer "B.Cu")
		(net "TP_SPI_IBL_CPU0_TPM_IO0")
	)
	(arc
		(start 340.61146 -269.059152)
		(mid 340.885659 -269.134987)
		(end 341.162132 -269.067788)
		(width 0.0889)
		(layer "B.Cu")
		(net "TP_SPI_IBL_CPU0_TPM_IO0")
	)
	(arc
		(start 339.671914 -269.059152)
		(mid 339.948473 -269.134895)
		(end 340.22665 -269.065248)
		(width 0.0889)
		(layer "B.Cu")
		(net "TP_SPI_IBL_CPU0_TPM_IO0")
	)
	(arc
		(start 344.37066 -269.059152)
		(mid 344.653252 -269.134928)
		(end 344.93581 -269.059152)
		(width 0.0889)
		(layer "B.Cu")
		(net "TP_SPI_IBL_CPU0_TPM_IO0")
	)
	(arc
		(start 334.85582 -268.969998)
		(mid 334.881518 -268.993932)
		(end 334.908652 -269.016226)
		(width 0.0889)
		(layer "B.Cu")
		(net "TP_SPI_IBL_CPU0_TPM_IO0")
	)
	(arc
		(start 339.297518 -269.059152)
		(mid 339.484716 -269.009009)
		(end 339.671914 -269.059152)
		(width 0.0889)
		(layer "B.Cu")
		(net "TP_SPI_IBL_CPU0_TPM_IO0")
	)
	(segment
		(start 351.232216 -269.661894)
		(end 351.232216 -270.19758)
		(width 0.12954)
		(layer "F.Cu")
		(net "TP_SPI_IBL_CPU0_TPM_CS0_N")
	)
	(segment
		(start 351.231962 -269.66164)
		(end 351.232216 -269.661894)
		(width 0.12954)
		(layer "F.Cu")
		(net "TP_SPI_IBL_CPU0_TPM_CS0_N")
	)
	(via
		(at 351.232216 -270.19758)
		(size 0.4572)
		(drill 0.2032)
		(layers "F.Cu" "B.Cu")
		(net "TP_SPI_IBL_CPU0_TPM_CS0_N")
	)
	(segment
		(start 349.822516 -265.592306)
		(end 349.822262 -265.592306)
		(width 0.12954)
		(layer "F.Cu")
		(net "TP_SPI_IBL_CPU0_TPM_CLK")
	)
	(segment
		(start 349.822262 -265.592306)
		(end 349.822262 -266.128246)
		(width 0.12954)
		(layer "F.Cu")
		(net "TP_SPI_IBL_CPU0_TPM_CLK")
	)
	(via
		(at 349.822262 -266.128246)
		(size 0.4572)
		(drill 0.2032)
		(layers "F.Cu" "B.Cu")
		(net "TP_SPI_IBL_CPU0_TPM_CLK")
	)
	(segment
		(start 142.947136 -16.550132)
		(end 142.947136 -19.887692)
		(width 0.12954)
		(layer "F.Cu")
		(net "TP_SPI_2_PLD_IO3")
	)
	(segment
		(start 142.947136 -19.887692)
		(end 142.946882 -19.887946)
		(width 0.12954)
		(layer "F.Cu")
		(net "TP_SPI_2_PLD_IO3")
	)
	(via
		(at 142.946882 -19.887946)
		(size 0.762)
		(drill 0.381)
		(layers "F.Cu" "B.Cu")
		(net "TP_SPI_2_PLD_IO3")
	)
	(segment
		(start 143.547084 -16.550132)
		(end 143.547084 -20.811744)
		(width 0.12954)
		(layer "F.Cu")
		(net "TP_SPI_2_PLD_IO2")
	)
	(segment
		(start 143.547084 -20.811744)
		(end 142.95628 -21.402548)
		(width 0.12954)
		(layer "F.Cu")
		(net "TP_SPI_2_PLD_IO2")
	)
	(via
		(at 142.95628 -21.402548)
		(size 0.762)
		(drill 0.381)
		(layers "F.Cu" "B.Cu")
		(net "TP_SPI_2_PLD_IO2")
	)
	(segment
		(start 144.147032 -20.586192)
		(end 144.146778 -20.586446)
		(width 0.12954)
		(layer "F.Cu")
		(net "TP_SPI_2_PLD_IO1")
	)
	(segment
		(start 144.147032 -16.550132)
		(end 144.147032 -20.586192)
		(width 0.12954)
		(layer "F.Cu")
		(net "TP_SPI_2_PLD_IO1")
	)
	(via
		(at 144.146778 -20.586446)
		(size 0.762)
		(drill 0.381)
		(layers "F.Cu" "B.Cu")
		(net "TP_SPI_2_PLD_IO1")
	)
	(segment
		(start 144.74698 -16.550132)
		(end 144.74698 -21.593048)
		(width 0.12954)
		(layer "F.Cu")
		(net "TP_SPI_2_PLD_IO0")
	)
	(segment
		(start 144.74698 -21.593048)
		(end 144.15008 -22.189948)
		(width 0.12954)
		(layer "F.Cu")
		(net "TP_SPI_2_PLD_IO0")
	)
	(via
		(at 144.15008 -22.189948)
		(size 0.762)
		(drill 0.381)
		(layers "F.Cu" "B.Cu")
		(net "TP_SPI_2_PLD_IO0")
	)
	(segment
		(start 145.346928 -19.776694)
		(end 145.346674 -19.776948)
		(width 0.12954)
		(layer "F.Cu")
		(net "TP_SPI_2_PLD_CS_N")
	)
	(segment
		(start 145.346928 -16.550132)
		(end 145.346928 -19.776694)
		(width 0.12954)
		(layer "F.Cu")
		(net "TP_SPI_2_PLD_CS_N")
	)
	(via
		(at 145.346674 -19.776948)
		(size 0.762)
		(drill 0.381)
		(layers "F.Cu" "B.Cu")
		(net "TP_SPI_2_PLD_CS_N")
	)
	(segment
		(start 145.94713 -16.550132)
		(end 145.94713 -21.053298)
		(width 0.12954)
		(layer "F.Cu")
		(net "TP_SPI_2_PLD_CLK")
	)
	(segment
		(start 145.94713 -21.053298)
		(end 145.77568 -21.224748)
		(width 0.12954)
		(layer "F.Cu")
		(net "TP_SPI_2_PLD_CLK")
	)
	(segment
		(start 145.77568 -21.224748)
		(end 145.34388 -21.224748)
		(width 0.12954)
		(layer "F.Cu")
		(net "TP_SPI_2_PLD_CLK")
	)
	(via
		(at 145.34388 -21.224748)
		(size 0.762)
		(drill 0.381)
		(layers "F.Cu" "B.Cu")
		(net "TP_SPI_2_PLD_CLK")
	)
	(segment
		(start 228.00056 -231.283002)
		(end 227.838 -231.120442)
		(width 0.12954)
		(layer "F.Cu")
		(net "TP_SMB_S3M_CPU1_EN")
	)
	(segment
		(start 227.838 -231.120442)
		(end 227.838 -230.571548)
		(width 0.12954)
		(layer "F.Cu")
		(net "TP_SMB_S3M_CPU1_EN")
	)
	(segment
		(start 228.00056 -232.435146)
		(end 228.00056 -231.283002)
		(width 0.12954)
		(layer "F.Cu")
		(net "TP_SMB_S3M_CPU1_EN")
	)
	(via
		(at 228.00056 -232.435146)
		(size 0.762)
		(drill 0.381)
		(layers "F.Cu" "B.Cu")
		(net "TP_SMB_S3M_CPU1_EN")
	)
	(segment
		(start 391.187178 -154.60599)
		(end 391.411206 -154.381962)
		(width 0.12954)
		(layer "F.Cu")
		(net "TP_SMB_S3M_CPU0_EN")
	)
	(segment
		(start 389.891778 -154.60599)
		(end 391.187178 -154.60599)
		(width 0.12954)
		(layer "F.Cu")
		(net "TP_SMB_S3M_CPU0_EN")
	)
	(segment
		(start 391.411206 -154.381962)
		(end 391.411206 -152.714452)
		(width 0.12954)
		(layer "F.Cu")
		(net "TP_SMB_S3M_CPU0_EN")
	)
	(via
		(at 389.891778 -154.60599)
		(size 0.762)
		(drill 0.381)
		(layers "F.Cu" "B.Cu")
		(net "TP_SMB_S3M_CPU0_EN")
	)
	(via
		(at 7.6708 -191.724788)
		(size 0.6604)
		(drill 0.3302)
		(layers "F.Cu" "B.Cu")
		(net "TP_SMB_PEHPCPU1_EN")
	)
	(segment
		(start 7.6708 -191.724788)
		(end 9.581134 -191.724788)
		(width 0.12954)
		(layer "B.Cu")
		(net "TP_SMB_PEHPCPU1_EN")
	)
	(via
		(at 365.368078 -187.34151)
		(size 0.6604)
		(drill 0.3302)
		(layers "F.Cu" "B.Cu")
		(net "TP_SMB_PEHPCPU0_EN")
	)
	(segment
		(start 365.368078 -187.34151)
		(end 366.57788 -186.131708)
		(width 0.12954)
		(layer "B.Cu")
		(net "TP_SMB_PEHPCPU0_EN")
	)
	(segment
		(start 366.57788 -186.131708)
		(end 367.302034 -186.131708)
		(width 0.12954)
		(layer "B.Cu")
		(net "TP_SMB_PEHPCPU0_EN")
	)
	(segment
		(start 329.980036 -45.630846)
		(end 330.251816 -46.100746)
		(width 0.12954)
		(layer "F.Cu")
		(net "TP_SLP_LAN_N")
	)
	(via
		(at 330.251816 -46.100746)
		(size 0.4572)
		(drill 0.2032)
		(layers "F.Cu" "B.Cu")
		(net "TP_SLP_LAN_N")
	)
	(segment
		(start 114.569494 -268.033754)
		(end 114.569748 -268.034008)
		(width 0.12954)
		(layer "F.Cu")
		(net "TP_SGPIO_S3M_CPU1_GSXRST_N")
	)
	(segment
		(start 114.569748 -268.034008)
		(end 114.569748 -268.569694)
		(width 0.12954)
		(layer "F.Cu")
		(net "TP_SGPIO_S3M_CPU1_GSXRST_N")
	)
	(via
		(at 114.569748 -268.569694)
		(size 0.4572)
		(drill 0.2032)
		(layers "F.Cu" "B.Cu")
		(net "TP_SGPIO_S3M_CPU1_GSXRST_N")
	)
	(segment
		(start 115.509548 -268.034008)
		(end 115.509548 -268.569694)
		(width 0.12954)
		(layer "F.Cu")
		(net "TP_SGPIO_S3M_CPU1_GSXDOUT")
	)
	(segment
		(start 115.509294 -268.033754)
		(end 115.509548 -268.034008)
		(width 0.12954)
		(layer "F.Cu")
		(net "TP_SGPIO_S3M_CPU1_GSXDOUT")
	)
	(via
		(at 115.509548 -268.569694)
		(size 0.4572)
		(drill 0.2032)
		(layers "F.Cu" "B.Cu")
		(net "TP_SGPIO_S3M_CPU1_GSXDOUT")
	)
	(segment
		(start 116.918994 -268.847824)
		(end 116.918994 -269.38351)
		(width 0.12954)
		(layer "F.Cu")
		(net "TP_SGPIO_S3M_CPU1_GSXDLOAD")
	)
	(segment
		(start 116.919248 -268.84757)
		(end 116.918994 -268.847824)
		(width 0.12954)
		(layer "F.Cu")
		(net "TP_SGPIO_S3M_CPU1_GSXDLOAD")
	)
	(via
		(at 116.918994 -269.38351)
		(size 0.4572)
		(drill 0.2032)
		(layers "F.Cu" "B.Cu")
		(net "TP_SGPIO_S3M_CPU1_GSXDLOAD")
	)
	(segment
		(start 116.449094 -266.405868)
		(end 116.44884 -266.406122)
		(width 0.12954)
		(layer "F.Cu")
		(net "TP_SGPIO_S3M_CPU1_GSXDIN")
	)
	(segment
		(start 116.44884 -266.406122)
		(end 116.44884 -266.941808)
		(width 0.12954)
		(layer "F.Cu")
		(net "TP_SGPIO_S3M_CPU1_GSXDIN")
	)
	(via
		(at 138.154156 -266.680442)
		(size 0.6604)
		(drill 0.3302)
		(layers "F.Cu" "B.Cu")
		(net "TP_SGPIO_S3M_CPU1_GSXDIN")
	)
	(via
		(at 116.44884 -266.941808)
		(size 0.4572)
		(drill 0.2032)
		(layers "F.Cu" "B.Cu")
		(net "TP_SGPIO_S3M_CPU1_GSXDIN")
	)
	(segment
		(start 134.587996 -266.45235)
		(end 134.598918 -266.4587)
		(width 0.0889)
		(layer "B.Cu")
		(net "TP_SGPIO_S3M_CPU1_GSXDIN")
	)
	(segment
		(start 136.678924 -266.376404)
		(end 136.876282 -266.179046)
		(width 0.0889)
		(layer "B.Cu")
		(net "TP_SGPIO_S3M_CPU1_GSXDIN")
	)
	(segment
		(start 136.876282 -266.179046)
		(end 137.65276 -266.179046)
		(width 0.0889)
		(layer "B.Cu")
		(net "TP_SGPIO_S3M_CPU1_GSXDIN")
	)
	(segment
		(start 134.573264 -266.443714)
		(end 134.587996 -266.45235)
		(width 0.0889)
		(layer "B.Cu")
		(net "TP_SGPIO_S3M_CPU1_GSXDIN")
	)
	(segment
		(start 124.235464 -266.443714)
		(end 124.250196 -266.45235)
		(width 0.0889)
		(layer "B.Cu")
		(net "TP_SGPIO_S3M_CPU1_GSXDIN")
	)
	(segment
		(start 137.65276 -266.179046)
		(end 138.154156 -266.680442)
		(width 0.0889)
		(layer "B.Cu")
		(net "TP_SGPIO_S3M_CPU1_GSXDIN")
	)
	(segment
		(start 136.184894 -266.376404)
		(end 136.678924 -266.376404)
		(width 0.0889)
		(layer "B.Cu")
		(net "TP_SGPIO_S3M_CPU1_GSXDIN")
	)
	(segment
		(start 118.045992 -266.45235)
		(end 118.05158 -266.449048)
		(width 0.0889)
		(layer "B.Cu")
		(net "TP_SGPIO_S3M_CPU1_GSXDIN")
	)
	(segment
		(start 117.666008 -266.449048)
		(end 117.671596 -266.45235)
		(width 0.0889)
		(layer "B.Cu")
		(net "TP_SGPIO_S3M_CPU1_GSXDIN")
	)
	(segment
		(start 130.814064 -266.443714)
		(end 130.828796 -266.45235)
		(width 0.0889)
		(layer "B.Cu")
		(net "TP_SGPIO_S3M_CPU1_GSXDIN")
	)
	(segment
		(start 127.994664 -266.443714)
		(end 128.009396 -266.45235)
		(width 0.0889)
		(layer "B.Cu")
		(net "TP_SGPIO_S3M_CPU1_GSXDIN")
	)
	(segment
		(start 125.175264 -266.443714)
		(end 125.189996 -266.45235)
		(width 0.0889)
		(layer "B.Cu")
		(net "TP_SGPIO_S3M_CPU1_GSXDIN")
	)
	(segment
		(start 135.513064 -266.443968)
		(end 135.527796 -266.452604)
		(width 0.0889)
		(layer "B.Cu")
		(net "TP_SGPIO_S3M_CPU1_GSXDIN")
	)
	(segment
		(start 129.874264 -266.443714)
		(end 129.888996 -266.45235)
		(width 0.0889)
		(layer "B.Cu")
		(net "TP_SGPIO_S3M_CPU1_GSXDIN")
	)
	(segment
		(start 120.476264 -266.443714)
		(end 120.490996 -266.45235)
		(width 0.0889)
		(layer "B.Cu")
		(net "TP_SGPIO_S3M_CPU1_GSXDIN")
	)
	(segment
		(start 118.985792 -266.452604)
		(end 118.999508 -266.444476)
		(width 0.0889)
		(layer "B.Cu")
		(net "TP_SGPIO_S3M_CPU1_GSXDIN")
	)
	(segment
		(start 128.934464 -266.443714)
		(end 128.949196 -266.45235)
		(width 0.0889)
		(layer "B.Cu")
		(net "TP_SGPIO_S3M_CPU1_GSXDIN")
	)
	(segment
		(start 123.295664 -266.443714)
		(end 123.310396 -266.45235)
		(width 0.0889)
		(layer "B.Cu")
		(net "TP_SGPIO_S3M_CPU1_GSXDIN")
	)
	(segment
		(start 116.44884 -266.941808)
		(end 116.954808 -266.501118)
		(width 0.0889)
		(layer "B.Cu")
		(net "TP_SGPIO_S3M_CPU1_GSXDIN")
	)
	(segment
		(start 127.054864 -266.443714)
		(end 127.069596 -266.45235)
		(width 0.0889)
		(layer "B.Cu")
		(net "TP_SGPIO_S3M_CPU1_GSXDIN")
	)
	(segment
		(start 122.355864 -266.443714)
		(end 122.370596 -266.45235)
		(width 0.0889)
		(layer "B.Cu")
		(net "TP_SGPIO_S3M_CPU1_GSXDIN")
	)
	(segment
		(start 131.753864 -266.443714)
		(end 131.768596 -266.45235)
		(width 0.0889)
		(layer "B.Cu")
		(net "TP_SGPIO_S3M_CPU1_GSXDIN")
	)
	(arc
		(start 132.708396 -266.45235)
		(mid 132.895594 -266.502527)
		(end 133.082792 -266.45235)
		(width 0.0889)
		(layer "B.Cu")
		(net "TP_SGPIO_S3M_CPU1_GSXDIN")
	)
	(arc
		(start 126.129796 -266.45235)
		(mid 126.316994 -266.502527)
		(end 126.504192 -266.45235)
		(width 0.0889)
		(layer "B.Cu")
		(net "TP_SGPIO_S3M_CPU1_GSXDIN")
	)
	(arc
		(start 120.490996 -266.45235)
		(mid 120.678194 -266.502527)
		(end 120.865392 -266.45235)
		(width 0.0889)
		(layer "B.Cu")
		(net "TP_SGPIO_S3M_CPU1_GSXDIN")
	)
	(arc
		(start 120.865392 -266.45235)
		(mid 121.148094 -266.376574)
		(end 121.430796 -266.45235)
		(width 0.0889)
		(layer "B.Cu")
		(net "TP_SGPIO_S3M_CPU1_GSXDIN")
	)
	(arc
		(start 125.189996 -266.45235)
		(mid 125.377194 -266.502527)
		(end 125.564392 -266.45235)
		(width 0.0889)
		(layer "B.Cu")
		(net "TP_SGPIO_S3M_CPU1_GSXDIN")
	)
	(arc
		(start 130.263392 -266.45235)
		(mid 130.537591 -266.376515)
		(end 130.814064 -266.443714)
		(width 0.0889)
		(layer "B.Cu")
		(net "TP_SGPIO_S3M_CPU1_GSXDIN")
	)
	(arc
		(start 119.551196 -266.45235)
		(mid 119.738394 -266.502527)
		(end 119.925592 -266.45235)
		(width 0.0889)
		(layer "B.Cu")
		(net "TP_SGPIO_S3M_CPU1_GSXDIN")
	)
	(arc
		(start 128.009396 -266.45235)
		(mid 128.196594 -266.502527)
		(end 128.383792 -266.45235)
		(width 0.0889)
		(layer "B.Cu")
		(net "TP_SGPIO_S3M_CPU1_GSXDIN")
	)
	(arc
		(start 122.370596 -266.45235)
		(mid 122.557794 -266.502527)
		(end 122.744992 -266.45235)
		(width 0.0889)
		(layer "B.Cu")
		(net "TP_SGPIO_S3M_CPU1_GSXDIN")
	)
	(arc
		(start 118.999508 -266.444476)
		(mid 119.276368 -266.376574)
		(end 119.551196 -266.45235)
		(width 0.0889)
		(layer "B.Cu")
		(net "TP_SGPIO_S3M_CPU1_GSXDIN")
	)
	(arc
		(start 128.383792 -266.45235)
		(mid 128.657991 -266.376515)
		(end 128.934464 -266.443714)
		(width 0.0889)
		(layer "B.Cu")
		(net "TP_SGPIO_S3M_CPU1_GSXDIN")
	)
	(arc
		(start 135.527796 -266.452604)
		(mid 135.70874 -266.502695)
		(end 135.89127 -266.4587)
		(width 0.0889)
		(layer "B.Cu")
		(net "TP_SGPIO_S3M_CPU1_GSXDIN")
	)
	(arc
		(start 123.310396 -266.45235)
		(mid 123.497594 -266.502527)
		(end 123.684792 -266.45235)
		(width 0.0889)
		(layer "B.Cu")
		(net "TP_SGPIO_S3M_CPU1_GSXDIN")
	)
	(arc
		(start 117.106192 -266.452604)
		(mid 117.296721 -266.384189)
		(end 117.49913 -266.387326)
		(width 0.0889)
		(layer "B.Cu")
		(net "TP_SGPIO_S3M_CPU1_GSXDIN")
	)
	(arc
		(start 126.504192 -266.45235)
		(mid 126.778391 -266.376515)
		(end 127.054864 -266.443714)
		(width 0.0889)
		(layer "B.Cu")
		(net "TP_SGPIO_S3M_CPU1_GSXDIN")
	)
	(arc
		(start 129.888996 -266.45235)
		(mid 130.076194 -266.502527)
		(end 130.263392 -266.45235)
		(width 0.0889)
		(layer "B.Cu")
		(net "TP_SGPIO_S3M_CPU1_GSXDIN")
	)
	(arc
		(start 116.954808 -266.501118)
		(mid 117.033116 -266.485015)
		(end 117.106192 -266.452604)
		(width 0.0889)
		(layer "B.Cu")
		(net "TP_SGPIO_S3M_CPU1_GSXDIN")
	)
	(arc
		(start 134.598918 -266.4587)
		(mid 134.781448 -266.502724)
		(end 134.962392 -266.452604)
		(width 0.0889)
		(layer "B.Cu")
		(net "TP_SGPIO_S3M_CPU1_GSXDIN")
	)
	(arc
		(start 127.069596 -266.45235)
		(mid 127.256794 -266.502527)
		(end 127.443992 -266.45235)
		(width 0.0889)
		(layer "B.Cu")
		(net "TP_SGPIO_S3M_CPU1_GSXDIN")
	)
	(arc
		(start 131.768596 -266.45235)
		(mid 131.955794 -266.502527)
		(end 132.142992 -266.45235)
		(width 0.0889)
		(layer "B.Cu")
		(net "TP_SGPIO_S3M_CPU1_GSXDIN")
	)
	(arc
		(start 121.805192 -266.45235)
		(mid 122.079391 -266.376515)
		(end 122.355864 -266.443714)
		(width 0.0889)
		(layer "B.Cu")
		(net "TP_SGPIO_S3M_CPU1_GSXDIN")
	)
	(arc
		(start 119.925592 -266.45235)
		(mid 120.199791 -266.376515)
		(end 120.476264 -266.443714)
		(width 0.0889)
		(layer "B.Cu")
		(net "TP_SGPIO_S3M_CPU1_GSXDIN")
	)
	(arc
		(start 117.49913 -266.387326)
		(mid 117.585007 -266.411591)
		(end 117.666008 -266.449048)
		(width 0.0889)
		(layer "B.Cu")
		(net "TP_SGPIO_S3M_CPU1_GSXDIN")
	)
	(arc
		(start 131.203192 -266.45235)
		(mid 131.477391 -266.376515)
		(end 131.753864 -266.443714)
		(width 0.0889)
		(layer "B.Cu")
		(net "TP_SGPIO_S3M_CPU1_GSXDIN")
	)
	(arc
		(start 128.949196 -266.45235)
		(mid 129.136394 -266.502527)
		(end 129.323592 -266.45235)
		(width 0.0889)
		(layer "B.Cu")
		(net "TP_SGPIO_S3M_CPU1_GSXDIN")
	)
	(arc
		(start 118.611396 -266.452604)
		(mid 118.798594 -266.502781)
		(end 118.985792 -266.452604)
		(width 0.0889)
		(layer "B.Cu")
		(net "TP_SGPIO_S3M_CPU1_GSXDIN")
	)
	(arc
		(start 123.684792 -266.45235)
		(mid 123.958991 -266.376515)
		(end 124.235464 -266.443714)
		(width 0.0889)
		(layer "B.Cu")
		(net "TP_SGPIO_S3M_CPU1_GSXDIN")
	)
	(arc
		(start 118.05158 -266.449048)
		(mid 118.331969 -266.376608)
		(end 118.611396 -266.452604)
		(width 0.0889)
		(layer "B.Cu")
		(net "TP_SGPIO_S3M_CPU1_GSXDIN")
	)
	(arc
		(start 133.082792 -266.45235)
		(mid 133.365494 -266.376574)
		(end 133.648196 -266.45235)
		(width 0.0889)
		(layer "B.Cu")
		(net "TP_SGPIO_S3M_CPU1_GSXDIN")
	)
	(arc
		(start 124.250196 -266.45235)
		(mid 124.437394 -266.502527)
		(end 124.624592 -266.45235)
		(width 0.0889)
		(layer "B.Cu")
		(net "TP_SGPIO_S3M_CPU1_GSXDIN")
	)
	(arc
		(start 127.443992 -266.45235)
		(mid 127.718191 -266.376515)
		(end 127.994664 -266.443714)
		(width 0.0889)
		(layer "B.Cu")
		(net "TP_SGPIO_S3M_CPU1_GSXDIN")
	)
	(arc
		(start 130.828796 -266.45235)
		(mid 131.015994 -266.502527)
		(end 131.203192 -266.45235)
		(width 0.0889)
		(layer "B.Cu")
		(net "TP_SGPIO_S3M_CPU1_GSXDIN")
	)
	(arc
		(start 134.022592 -266.45235)
		(mid 134.296791 -266.376515)
		(end 134.573264 -266.443714)
		(width 0.0889)
		(layer "B.Cu")
		(net "TP_SGPIO_S3M_CPU1_GSXDIN")
	)
	(arc
		(start 122.744992 -266.45235)
		(mid 123.019191 -266.376515)
		(end 123.295664 -266.443714)
		(width 0.0889)
		(layer "B.Cu")
		(net "TP_SGPIO_S3M_CPU1_GSXDIN")
	)
	(arc
		(start 121.430796 -266.45235)
		(mid 121.617994 -266.502527)
		(end 121.805192 -266.45235)
		(width 0.0889)
		(layer "B.Cu")
		(net "TP_SGPIO_S3M_CPU1_GSXDIN")
	)
	(arc
		(start 132.142992 -266.45235)
		(mid 132.425694 -266.376574)
		(end 132.708396 -266.45235)
		(width 0.0889)
		(layer "B.Cu")
		(net "TP_SGPIO_S3M_CPU1_GSXDIN")
	)
	(arc
		(start 117.671596 -266.45235)
		(mid 117.858794 -266.502527)
		(end 118.045992 -266.45235)
		(width 0.0889)
		(layer "B.Cu")
		(net "TP_SGPIO_S3M_CPU1_GSXDIN")
	)
	(arc
		(start 129.323592 -266.45235)
		(mid 129.597791 -266.376515)
		(end 129.874264 -266.443714)
		(width 0.0889)
		(layer "B.Cu")
		(net "TP_SGPIO_S3M_CPU1_GSXDIN")
	)
	(arc
		(start 124.624592 -266.45235)
		(mid 124.898791 -266.376515)
		(end 125.175264 -266.443714)
		(width 0.0889)
		(layer "B.Cu")
		(net "TP_SGPIO_S3M_CPU1_GSXDIN")
	)
	(arc
		(start 133.648196 -266.45235)
		(mid 133.835394 -266.502527)
		(end 134.022592 -266.45235)
		(width 0.0889)
		(layer "B.Cu")
		(net "TP_SGPIO_S3M_CPU1_GSXDIN")
	)
	(arc
		(start 125.564392 -266.45235)
		(mid 125.847094 -266.376574)
		(end 126.129796 -266.45235)
		(width 0.0889)
		(layer "B.Cu")
		(net "TP_SGPIO_S3M_CPU1_GSXDIN")
	)
	(arc
		(start 134.962392 -266.452604)
		(mid 135.236591 -266.376769)
		(end 135.513064 -266.443968)
		(width 0.0889)
		(layer "B.Cu")
		(net "TP_SGPIO_S3M_CPU1_GSXDIN")
	)
	(arc
		(start 135.89127 -266.4587)
		(mid 136.032433 -266.397415)
		(end 136.184894 -266.376404)
		(width 0.0889)
		(layer "B.Cu")
		(net "TP_SGPIO_S3M_CPU1_GSXDIN")
	)
	(segment
		(start 115.509294 -266.405868)
		(end 115.509548 -266.406122)
		(width 0.12954)
		(layer "F.Cu")
		(net "TP_SGPIO_S3M_CPU1_GSXCLK")
	)
	(segment
		(start 115.509548 -266.406122)
		(end 115.509548 -266.941808)
		(width 0.12954)
		(layer "F.Cu")
		(net "TP_SGPIO_S3M_CPU1_GSXCLK")
	)
	(via
		(at 115.509548 -266.941808)
		(size 0.4572)
		(drill 0.2032)
		(layers "F.Cu" "B.Cu")
		(net "TP_SGPIO_S3M_CPU1_GSXCLK")
	)
	(segment
		(start 362.509562 -268.033754)
		(end 362.509816 -268.034008)
		(width 0.12954)
		(layer "F.Cu")
		(net "TP_SGPIO_S3M_CPU0_RST_R_N")
	)
	(segment
		(start 362.509816 -268.034008)
		(end 362.509816 -268.569694)
		(width 0.12954)
		(layer "F.Cu")
		(net "TP_SGPIO_S3M_CPU0_RST_R_N")
	)
	(via
		(at 362.509816 -268.569694)
		(size 0.4572)
		(drill 0.2032)
		(layers "F.Cu" "B.Cu")
		(net "TP_SGPIO_S3M_CPU0_RST_R_N")
	)
	(segment
		(start 363.449616 -268.569694)
		(end 363.449616 -268.034008)
		(width 0.12954)
		(layer "F.Cu")
		(net "TP_SGPIO_S3M_CPU0_GSXDOUT_R")
	)
	(segment
		(start 363.449616 -268.034008)
		(end 363.449362 -268.033754)
		(width 0.12954)
		(layer "F.Cu")
		(net "TP_SGPIO_S3M_CPU0_GSXDOUT_R")
	)
	(via
		(at 363.449616 -268.569694)
		(size 0.4572)
		(drill 0.2032)
		(layers "F.Cu" "B.Cu")
		(net "TP_SGPIO_S3M_CPU0_GSXDOUT_R")
	)
	(segment
		(start 364.859062 -269.38351)
		(end 364.859062 -268.847824)
		(width 0.12954)
		(layer "F.Cu")
		(net "TP_SGPIO_S3M_CPU0_GSXDLOAD_R")
	)
	(segment
		(start 364.859062 -268.847824)
		(end 364.859316 -268.84757)
		(width 0.12954)
		(layer "F.Cu")
		(net "TP_SGPIO_S3M_CPU0_GSXDLOAD_R")
	)
	(via
		(at 364.859062 -269.38351)
		(size 0.4572)
		(drill 0.2032)
		(layers "F.Cu" "B.Cu")
		(net "TP_SGPIO_S3M_CPU0_GSXDLOAD_R")
	)
	(segment
		(start 364.389162 -266.941808)
		(end 364.389162 -266.405868)
		(width 0.12954)
		(layer "F.Cu")
		(net "TP_SGPIO_S3M_CPU0_GSXDIN")
	)
	(via
		(at 364.389162 -266.941808)
		(size 0.4572)
		(drill 0.2032)
		(layers "F.Cu" "B.Cu")
		(net "TP_SGPIO_S3M_CPU0_GSXDIN")
	)
	(segment
		(start 363.449362 -266.941808)
		(end 363.449362 -266.405868)
		(width 0.12954)
		(layer "F.Cu")
		(net "TP_SGPIO_S3M_CPU0_GSXCLK_R")
	)
	(via
		(at 363.449362 -266.941808)
		(size 0.4572)
		(drill 0.2032)
		(layers "F.Cu" "B.Cu")
		(net "TP_SGPIO_S3M_CPU0_GSXCLK_R")
	)
	(segment
		(start 354.521516 -267.219938)
		(end 354.521262 -267.220192)
		(width 0.12954)
		(layer "F.Cu")
		(net "TP_RST_ESPI_IBL_CPU0_LVC1_N")
	)
	(segment
		(start 354.521262 -267.220192)
		(end 354.521262 -267.755878)
		(width 0.12954)
		(layer "F.Cu")
		(net "TP_RST_ESPI_IBL_CPU0_LVC1_N")
	)
	(via
		(at 354.521262 -267.755878)
		(size 0.4572)
		(drill 0.2032)
		(layers "F.Cu" "B.Cu")
		(net "TP_RST_ESPI_IBL_CPU0_LVC1_N")
	)
	(segment
		(start 329.437746 -54.089046)
		(end 329.980036 -54.089046)
		(width 0.12954)
		(layer "F.Cu")
		(net "TP_PLTRST_N")
	)
	(via
		(at 328.163682 -52.974748)
		(size 0.6604)
		(drill 0.3302)
		(layers "F.Cu" "B.Cu")
		(net "TP_PLTRST_N")
	)
	(via
		(at 329.437746 -54.089046)
		(size 0.4572)
		(drill 0.2032)
		(layers "F.Cu" "B.Cu")
		(net "TP_PLTRST_N")
	)
	(segment
		(start 329.437746 -53.817012)
		(end 329.437746 -54.089046)
		(width 0.12954)
		(layer "B.Cu")
		(net "TP_PLTRST_N")
	)
	(segment
		(start 328.163682 -52.974748)
		(end 328.595482 -52.974748)
		(width 0.12954)
		(layer "B.Cu")
		(net "TP_PLTRST_N")
	)
	(segment
		(start 328.595482 -52.974748)
		(end 329.437746 -53.817012)
		(width 0.12954)
		(layer "B.Cu")
		(net "TP_PLTRST_N")
	)
	(segment
		(start 332.422246 -46.100746)
		(end 332.693518 -45.630846)
		(width 0.12954)
		(layer "F.Cu")
		(net "TP_PCH_SLP_S5_N")
	)
	(via
		(at 332.498446 -46.44771)
		(size 0.6604)
		(drill 0.3302)
		(layers "F.Cu" "B.Cu")
		(net "TP_PCH_SLP_S5_N")
	)
	(via
		(at 332.693518 -45.630846)
		(size 0.4572)
		(drill 0.2032)
		(layers "F.Cu" "B.Cu")
		(net "TP_PCH_SLP_S5_N")
	)
	(segment
		(start 332.498446 -46.44771)
		(end 332.498446 -45.825918)
		(width 0.12954)
		(layer "B.Cu")
		(net "TP_PCH_SLP_S5_N")
	)
	(segment
		(start 332.498446 -45.825918)
		(end 332.693518 -45.630846)
		(width 0.12954)
		(layer "B.Cu")
		(net "TP_PCH_SLP_S5_N")
	)
	(segment
		(start 331.880718 -45.160946)
		(end 331.73543 -45.160946)
		(width 0.12954)
		(layer "F.Cu")
		(net "TP_PCH_SLP_A_N")
	)
	(segment
		(start 331.73543 -45.160946)
		(end 331.608176 -45.033692)
		(width 0.12954)
		(layer "F.Cu")
		(net "TP_PCH_SLP_A_N")
	)
	(segment
		(start 331.608176 -45.033692)
		(end 331.608176 -44.691046)
		(width 0.12954)
		(layer "F.Cu")
		(net "TP_PCH_SLP_A_N")
	)
	(via
		(at 331.880718 -45.160946)
		(size 0.4572)
		(drill 0.2032)
		(layers "F.Cu" "B.Cu")
		(net "TP_PCH_SLP_A_N")
	)
	(segment
		(start 349.86468 -32.858456)
		(end 349.86468 -35.169602)
		(width 0.12954)
		(layer "F.Cu")
		(net "TP_PCH_RSVD<7>")
	)
	(segment
		(start 351.88652 -27.577288)
		(end 351.88652 -30.836616)
		(width 0.12954)
		(layer "F.Cu")
		(net "TP_PCH_RSVD<7>")
	)
	(segment
		(start 352.63836 -26.825448)
		(end 351.88652 -27.577288)
		(width 0.12954)
		(layer "F.Cu")
		(net "TP_PCH_RSVD<7>")
	)
	(segment
		(start 348.316296 -39.733728)
		(end 348.189296 -39.860728)
		(width 0.0889)
		(layer "F.Cu")
		(net "TP_PCH_RSVD<7>")
	)
	(segment
		(start 348.694502 -36.33978)
		(end 348.694502 -39.355522)
		(width 0.12954)
		(layer "F.Cu")
		(net "TP_PCH_RSVD<7>")
	)
	(segment
		(start 351.88652 -30.836616)
		(end 349.86468 -32.858456)
		(width 0.12954)
		(layer "F.Cu")
		(net "TP_PCH_RSVD<7>")
	)
	(segment
		(start 348.189296 -39.860728)
		(end 347.742002 -39.860728)
		(width 0.0889)
		(layer "F.Cu")
		(net "TP_PCH_RSVD<7>")
	)
	(segment
		(start 347.431868 -39.728902)
		(end 347.214698 -39.946072)
		(width 0.0889)
		(layer "F.Cu")
		(net "TP_PCH_RSVD<7>")
	)
	(segment
		(start 347.61043 -39.729156)
		(end 347.431868 -39.728902)
		(width 0.0889)
		(layer "F.Cu")
		(net "TP_PCH_RSVD<7>")
	)
	(segment
		(start 352.63836 -26.449528)
		(end 352.63836 -26.825448)
		(width 0.12954)
		(layer "F.Cu")
		(net "TP_PCH_RSVD<7>")
	)
	(segment
		(start 349.86468 -35.169602)
		(end 348.694502 -36.33978)
		(width 0.12954)
		(layer "F.Cu")
		(net "TP_PCH_RSVD<7>")
	)
	(segment
		(start 348.694502 -39.355522)
		(end 348.316296 -39.733728)
		(width 0.12954)
		(layer "F.Cu")
		(net "TP_PCH_RSVD<7>")
	)
	(segment
		(start 347.742002 -39.860728)
		(end 347.61043 -39.729156)
		(width 0.0889)
		(layer "F.Cu")
		(net "TP_PCH_RSVD<7>")
	)
	(via
		(at 352.63836 -26.449528)
		(size 0.762)
		(drill 0.381)
		(layers "F.Cu" "B.Cu")
		(net "TP_PCH_RSVD<7>")
	)
	(segment
		(start 334.325468 -53.149246)
		(end 334.864456 -53.149246)
		(width 0.12954)
		(layer "F.Cu")
		(net "TP_PCH_RSVD<6>")
	)
	(via
		(at 334.325468 -53.149246)
		(size 0.4572)
		(drill 0.2032)
		(layers "F.Cu" "B.Cu")
		(net "TP_PCH_RSVD<6>")
	)
	(segment
		(start 321.694302 -67.018662)
		(end 322.504308 -66.208656)
		(width 0.12954)
		(layer "F.Cu")
		(net "TP_PCH_RSVD<2>")
	)
	(segment
		(start 326.713596 -61.006228)
		(end 328.110596 -59.609228)
		(width 0.0889)
		(layer "F.Cu")
		(net "TP_PCH_RSVD<2>")
	)
	(segment
		(start 322.504308 -64.523112)
		(end 323.449696 -63.577724)
		(width 0.12954)
		(layer "F.Cu")
		(net "TP_PCH_RSVD<2>")
	)
	(segment
		(start 321.093084 -71.676514)
		(end 321.694302 -71.075296)
		(width 0.12954)
		(layer "F.Cu")
		(net "TP_PCH_RSVD<2>")
	)
	(segment
		(start 325.532496 -61.117988)
		(end 326.601836 -61.117988)
		(width 0.12954)
		(layer "F.Cu")
		(net "TP_PCH_RSVD<2>")
	)
	(segment
		(start 323.449696 -63.200788)
		(end 325.532496 -61.117988)
		(width 0.12954)
		(layer "F.Cu")
		(net "TP_PCH_RSVD<2>")
	)
	(segment
		(start 328.110596 -59.609228)
		(end 328.110596 -59.48045)
		(width 0.0889)
		(layer "F.Cu")
		(net "TP_PCH_RSVD<2>")
	)
	(segment
		(start 322.504308 -66.208656)
		(end 322.504308 -64.523112)
		(width 0.12954)
		(layer "F.Cu")
		(net "TP_PCH_RSVD<2>")
	)
	(segment
		(start 321.694302 -71.075296)
		(end 321.694302 -67.018662)
		(width 0.12954)
		(layer "F.Cu")
		(net "TP_PCH_RSVD<2>")
	)
	(segment
		(start 328.110596 -59.48045)
		(end 327.895458 -59.265312)
		(width 0.0889)
		(layer "F.Cu")
		(net "TP_PCH_RSVD<2>")
	)
	(segment
		(start 326.601836 -61.117988)
		(end 326.713596 -61.006228)
		(width 0.12954)
		(layer "F.Cu")
		(net "TP_PCH_RSVD<2>")
	)
	(segment
		(start 323.449696 -63.577724)
		(end 323.449696 -63.200788)
		(width 0.12954)
		(layer "F.Cu")
		(net "TP_PCH_RSVD<2>")
	)
	(via
		(at 321.093084 -71.676514)
		(size 0.762)
		(drill 0.381)
		(layers "F.Cu" "B.Cu")
		(net "TP_PCH_RSVD<2>")
	)
	(segment
		(start 325.794116 -57.482486)
		(end 325.954136 -57.322466)
		(width 0.12954)
		(layer "F.Cu")
		(net "TP_PCH_RSVD<1>")
	)
	(segment
		(start 326.216772 -57.322466)
		(end 326.584818 -56.95442)
		(width 0.12954)
		(layer "F.Cu")
		(net "TP_PCH_RSVD<1>")
	)
	(segment
		(start 325.954136 -57.322466)
		(end 326.216772 -57.322466)
		(width 0.12954)
		(layer "F.Cu")
		(net "TP_PCH_RSVD<1>")
	)
	(via
		(at 325.794116 -57.482486)
		(size 0.49022)
		(drill 0.254)
		(layers "F.Cu" "B.Cu")
		(net "TP_PCH_RSVD<1>")
	)
	(segment
		(start 336.767678 -55.498746)
		(end 337.306666 -55.498746)
		(width 0.12954)
		(layer "F.Cu")
		(net "TP_PCH_RSVD<19>")
	)
	(via
		(at 336.767678 -55.498746)
		(size 0.4572)
		(drill 0.2032)
		(layers "F.Cu" "B.Cu")
		(net "TP_PCH_RSVD<19>")
	)
	(segment
		(start 337.581748 -55.968646)
		(end 338.120736 -55.968646)
		(width 0.12954)
		(layer "F.Cu")
		(net "TP_PCH_RSVD<18>")
	)
	(via
		(at 337.581748 -55.968646)
		(size 0.4572)
		(drill 0.2032)
		(layers "F.Cu" "B.Cu")
		(net "TP_PCH_RSVD<18>")
	)
	(via
		(at 337.72348 -57.831228)
		(size 0.6604)
		(drill 0.3302)
		(layers "F.Cu" "B.Cu")
		(net "TP_PCH_RSVD<18>")
	)
	(segment
		(start 337.72348 -57.831228)
		(end 337.83778 -57.716928)
		(width 0.12954)
		(layer "B.Cu")
		(net "TP_PCH_RSVD<18>")
	)
	(segment
		(start 337.96478 -56.175148)
		(end 337.758278 -55.968646)
		(width 0.12954)
		(layer "B.Cu")
		(net "TP_PCH_RSVD<18>")
	)
	(segment
		(start 338.10702 -57.051448)
		(end 338.10702 -56.835548)
		(width 0.12954)
		(layer "B.Cu")
		(net "TP_PCH_RSVD<18>")
	)
	(segment
		(start 338.10702 -56.835548)
		(end 337.96478 -56.693308)
		(width 0.12954)
		(layer "B.Cu")
		(net "TP_PCH_RSVD<18>")
	)
	(segment
		(start 337.83778 -57.320688)
		(end 338.10702 -57.051448)
		(width 0.12954)
		(layer "B.Cu")
		(net "TP_PCH_RSVD<18>")
	)
	(segment
		(start 337.96478 -56.693308)
		(end 337.96478 -56.175148)
		(width 0.12954)
		(layer "B.Cu")
		(net "TP_PCH_RSVD<18>")
	)
	(segment
		(start 337.758278 -55.968646)
		(end 337.581748 -55.968646)
		(width 0.12954)
		(layer "B.Cu")
		(net "TP_PCH_RSVD<18>")
	)
	(segment
		(start 337.83778 -57.716928)
		(end 337.83778 -57.320688)
		(width 0.12954)
		(layer "B.Cu")
		(net "TP_PCH_RSVD<18>")
	)
	(segment
		(start 333.23657 -47.510446)
		(end 333.50835 -47.980346)
		(width 0.12954)
		(layer "F.Cu")
		(net "TP_PCH_RSVD<16>")
	)
	(via
		(at 333.50835 -47.980346)
		(size 0.4572)
		(drill 0.2032)
		(layers "F.Cu" "B.Cu")
		(net "TP_PCH_RSVD<16>")
	)
	(segment
		(start 338.396072 -44.221146)
		(end 338.93506 -44.221146)
		(width 0.12954)
		(layer "F.Cu")
		(net "TP_PCH_RSVD<15>")
	)
	(via
		(at 338.396072 -44.221146)
		(size 0.4572)
		(drill 0.2032)
		(layers "F.Cu" "B.Cu")
		(net "TP_PCH_RSVD<15>")
	)
	(segment
		(start 331.883258 -54.558946)
		(end 332.422246 -54.558946)
		(width 0.12954)
		(layer "F.Cu")
		(net "TP_PCH_RSVD<13>")
	)
	(via
		(at 331.883258 -54.558946)
		(size 0.4572)
		(drill 0.2032)
		(layers "F.Cu" "B.Cu")
		(net "TP_PCH_RSVD<13>")
	)
	(segment
		(start 326.020176 -56.244744)
		(end 326.311006 -55.953914)
		(width 0.0889)
		(layer "F.Cu")
		(net "TP_PCH_RSVD<0>")
	)
	(segment
		(start 326.311006 -55.953914)
		(end 326.584818 -55.953914)
		(width 0.0889)
		(layer "F.Cu")
		(net "TP_PCH_RSVD<0>")
	)
	(segment
		(start 325.672704 -56.244744)
		(end 326.020176 -56.244744)
		(width 0.0889)
		(layer "F.Cu")
		(net "TP_PCH_RSVD<0>")
	)
	(via
		(at 325.672704 -56.244744)
		(size 0.508)
		(drill 0.254)
		(layers "F.Cu" "B.Cu")
		(net "TP_PCH_RSVD<0>")
	)
	(via
		(at 324.44817 -55.080154)
		(size 0.6604)
		(drill 0.3302)
		(layers "F.Cu" "B.Cu")
		(net "TP_PCH_RSVD<0>")
	)
	(segment
		(start 324.44817 -55.080154)
		(end 325.61276 -56.244744)
		(width 0.12954)
		(layer "B.Cu")
		(net "TP_PCH_RSVD<0>")
	)
	(segment
		(start 325.61276 -56.244744)
		(end 325.672704 -56.244744)
		(width 0.12954)
		(layer "B.Cu")
		(net "TP_PCH_RSVD<0>")
	)
	(segment
		(start 324.810882 -56.232044)
		(end 324.810882 -55.878222)
		(width 0.0889)
		(layer "F.Cu")
		(net "TP_PCH_MGPIO_TEST1")
	)
	(segment
		(start 324.810882 -55.878222)
		(end 325.23557 -55.453534)
		(width 0.0889)
		(layer "F.Cu")
		(net "TP_PCH_MGPIO_TEST1")
	)
	(segment
		(start 325.23557 -55.453534)
		(end 326.999854 -55.453534)
		(width 0.0889)
		(layer "F.Cu")
		(net "TP_PCH_MGPIO_TEST1")
	)
	(via
		(at 324.810882 -56.232044)
		(size 0.508)
		(drill 0.254)
		(layers "F.Cu" "B.Cu")
		(net "TP_PCH_MGPIO_TEST1")
	)
	(segment
		(start 329.302364 -45.630846)
		(end 329.165966 -45.767244)
		(width 0.12954)
		(layer "F.Cu")
		(net "TP_PCH_GPP_O_11")
	)
	(segment
		(start 329.437746 -45.630846)
		(end 329.302364 -45.630846)
		(width 0.12954)
		(layer "F.Cu")
		(net "TP_PCH_GPP_O_11")
	)
	(segment
		(start 329.165966 -45.767244)
		(end 329.165966 -46.100746)
		(width 0.12954)
		(layer "F.Cu")
		(net "TP_PCH_GPP_O_11")
	)
	(via
		(at 329.437746 -45.630846)
		(size 0.4572)
		(drill 0.2032)
		(layers "F.Cu" "B.Cu")
		(net "TP_PCH_GPP_O_11")
	)
	(segment
		(start 331.608176 -51.269646)
		(end 331.879956 -51.739546)
		(width 0.12954)
		(layer "F.Cu")
		(net "TP_PCH_GPP_N_4")
	)
	(via
		(at 332.534006 -52.393596)
		(size 0.6604)
		(drill 0.3302)
		(layers "F.Cu" "B.Cu")
		(net "TP_PCH_GPP_N_4")
	)
	(via
		(at 331.879956 -51.739546)
		(size 0.4572)
		(drill 0.2032)
		(layers "F.Cu" "B.Cu")
		(net "TP_PCH_GPP_N_4")
	)
	(segment
		(start 331.879956 -51.739546)
		(end 332.534006 -52.393596)
		(width 0.12954)
		(layer "B.Cu")
		(net "TP_PCH_GPP_N_4")
	)
	(segment
		(start 331.608176 -52.209446)
		(end 331.067664 -52.209446)
		(width 0.12954)
		(layer "F.Cu")
		(net "TP_PCH_GPP_N_1")
	)
	(via
		(at 331.067664 -52.209446)
		(size 0.4572)
		(drill 0.2032)
		(layers "F.Cu" "B.Cu")
		(net "TP_PCH_GPP_N_1")
	)
	(via
		(at 331.77226 -53.467508)
		(size 0.6604)
		(drill 0.3302)
		(layers "F.Cu" "B.Cu")
		(net "TP_PCH_GPP_N_1")
	)
	(segment
		(start 331.77226 -53.467508)
		(end 331.674978 -53.370226)
		(width 0.12954)
		(layer "B.Cu")
		(net "TP_PCH_GPP_N_1")
	)
	(segment
		(start 331.674978 -53.370226)
		(end 331.674978 -52.81676)
		(width 0.12954)
		(layer "B.Cu")
		(net "TP_PCH_GPP_N_1")
	)
	(segment
		(start 331.674978 -52.81676)
		(end 331.067664 -52.209446)
		(width 0.12954)
		(layer "B.Cu")
		(net "TP_PCH_GPP_N_1")
	)
	(segment
		(start 337.037172 -40.934894)
		(end 337.306666 -41.401746)
		(width 0.12954)
		(layer "F.Cu")
		(net "TP_PCH_GPP_E_2")
	)
	(via
		(at 337.037172 -40.934894)
		(size 0.4572)
		(drill 0.2032)
		(layers "F.Cu" "B.Cu")
		(net "TP_PCH_GPP_E_2")
	)
	(segment
		(start 326.711564 -47.230792)
		(end 327.067672 -46.993048)
		(width 0.0889)
		(layer "F.Cu")
		(net "TP_PCH_GPP_D_20")
	)
	(segment
		(start 326.469248 -47.230792)
		(end 326.711564 -47.230792)
		(width 0.0889)
		(layer "F.Cu")
		(net "TP_PCH_GPP_D_20")
	)
	(segment
		(start 324.635622 -46.853348)
		(end 324.977506 -47.195232)
		(width 0.0889)
		(layer "F.Cu")
		(net "TP_PCH_GPP_D_20")
	)
	(segment
		(start 324.977506 -47.195232)
		(end 326.348598 -47.195232)
		(width 0.0889)
		(layer "F.Cu")
		(net "TP_PCH_GPP_D_20")
	)
	(segment
		(start 326.348598 -47.195232)
		(end 326.469248 -47.230792)
		(width 0.0889)
		(layer "F.Cu")
		(net "TP_PCH_GPP_D_20")
	)
	(segment
		(start 327.067672 -46.993048)
		(end 327.132696 -46.949614)
		(width 0.0889)
		(layer "F.Cu")
		(net "TP_PCH_GPP_D_20")
	)
	(segment
		(start 327.132696 -46.949614)
		(end 327.41489 -46.949614)
		(width 0.0889)
		(layer "F.Cu")
		(net "TP_PCH_GPP_D_20")
	)
	(via
		(at 324.635622 -46.853348)
		(size 0.508)
		(drill 0.254)
		(layers "F.Cu" "B.Cu")
		(net "TP_PCH_GPP_D_20")
	)
	(segment
		(start 325.915782 -48.357028)
		(end 326.38492 -48.450246)
		(width 0.0889)
		(layer "F.Cu")
		(net "TP_PCH_GPP_D_2")
	)
	(segment
		(start 323.629782 -48.580548)
		(end 323.853302 -48.357028)
		(width 0.0889)
		(layer "F.Cu")
		(net "TP_PCH_GPP_D_2")
	)
	(segment
		(start 326.38492 -48.450246)
		(end 326.999854 -48.450246)
		(width 0.0889)
		(layer "F.Cu")
		(net "TP_PCH_GPP_D_2")
	)
	(segment
		(start 323.853302 -48.357028)
		(end 325.915782 -48.357028)
		(width 0.0889)
		(layer "F.Cu")
		(net "TP_PCH_GPP_D_2")
	)
	(segment
		(start 323.314822 -48.580548)
		(end 323.629782 -48.580548)
		(width 0.0889)
		(layer "F.Cu")
		(net "TP_PCH_GPP_D_2")
	)
	(via
		(at 323.314822 -48.580548)
		(size 0.508)
		(drill 0.254)
		(layers "F.Cu" "B.Cu")
		(net "TP_PCH_GPP_D_2")
	)
	(segment
		(start 331.608176 -56.908446)
		(end 331.06995 -56.908446)
		(width 0.12954)
		(layer "F.Cu")
		(net "TP_PCH_CPU_MSMI_N")
	)
	(via
		(at 331.06995 -56.908446)
		(size 0.4572)
		(drill 0.2032)
		(layers "F.Cu" "B.Cu")
		(net "TP_PCH_CPU_MSMI_N")
	)
	(via
		(at 330.51369 -57.96534)
		(size 0.6604)
		(drill 0.3302)
		(layers "F.Cu" "B.Cu")
		(net "TP_PCH_CPU_MSMI_N")
	)
	(segment
		(start 331.06995 -56.908446)
		(end 331.06995 -57.40908)
		(width 0.12954)
		(layer "B.Cu")
		(net "TP_PCH_CPU_MSMI_N")
	)
	(segment
		(start 331.06995 -57.40908)
		(end 330.51369 -57.96534)
		(width 0.12954)
		(layer "B.Cu")
		(net "TP_PCH_CPU_MSMI_N")
	)
	(segment
		(start 321.858132 -65.718436)
		(end 321.858132 -64.034416)
		(width 0.12954)
		(layer "F.Cu")
		(net "TP_PCH_CPU_MEMTRIP_N")
	)
	(segment
		(start 327.590658 -58.483246)
		(end 327.590658 -58.306716)
		(width 0.0889)
		(layer "F.Cu")
		(net "TP_PCH_CPU_MEMTRIP_N")
	)
	(segment
		(start 325.433944 -60.719716)
		(end 326.420988 -60.719716)
		(width 0.12954)
		(layer "F.Cu")
		(net "TP_PCH_CPU_MEMTRIP_N")
	)
	(segment
		(start 326.420988 -60.719716)
		(end 327.166986 -59.973718)
		(width 0.12954)
		(layer "F.Cu")
		(net "TP_PCH_CPU_MEMTRIP_N")
	)
	(segment
		(start 327.45426 -59.686444)
		(end 327.542652 -59.472576)
		(width 0.0889)
		(layer "F.Cu")
		(net "TP_PCH_CPU_MEMTRIP_N")
	)
	(segment
		(start 324.379844 -61.512704)
		(end 324.640956 -61.512704)
		(width 0.12954)
		(layer "F.Cu")
		(net "TP_PCH_CPU_MEMTRIP_N")
	)
	(segment
		(start 327.611994 -58.965338)
		(end 327.611994 -58.57875)
		(width 0.0889)
		(layer "F.Cu")
		(net "TP_PCH_CPU_MEMTRIP_N")
	)
	(segment
		(start 327.542652 -59.472576)
		(end 327.542652 -59.03468)
		(width 0.0889)
		(layer "F.Cu")
		(net "TP_PCH_CPU_MEMTRIP_N")
	)
	(segment
		(start 327.542652 -59.03468)
		(end 327.611994 -58.965338)
		(width 0.0889)
		(layer "F.Cu")
		(net "TP_PCH_CPU_MEMTRIP_N")
	)
	(segment
		(start 324.640956 -61.512704)
		(end 325.433944 -60.719716)
		(width 0.12954)
		(layer "F.Cu")
		(net "TP_PCH_CPU_MEMTRIP_N")
	)
	(segment
		(start 321.093084 -66.483484)
		(end 321.858132 -65.718436)
		(width 0.12954)
		(layer "F.Cu")
		(net "TP_PCH_CPU_MEMTRIP_N")
	)
	(segment
		(start 327.166986 -59.973718)
		(end 327.45426 -59.686444)
		(width 0.0889)
		(layer "F.Cu")
		(net "TP_PCH_CPU_MEMTRIP_N")
	)
	(segment
		(start 321.858132 -64.034416)
		(end 324.379844 -61.512704)
		(width 0.12954)
		(layer "F.Cu")
		(net "TP_PCH_CPU_MEMTRIP_N")
	)
	(segment
		(start 321.093084 -70.406514)
		(end 321.093084 -66.483484)
		(width 0.12954)
		(layer "F.Cu")
		(net "TP_PCH_CPU_MEMTRIP_N")
	)
	(segment
		(start 327.590658 -58.306716)
		(end 327.829926 -57.86501)
		(width 0.0889)
		(layer "F.Cu")
		(net "TP_PCH_CPU_MEMTRIP_N")
	)
	(segment
		(start 327.829926 -57.86501)
		(end 327.829926 -57.454546)
		(width 0.0889)
		(layer "F.Cu")
		(net "TP_PCH_CPU_MEMTRIP_N")
	)
	(segment
		(start 327.611994 -58.57875)
		(end 327.590658 -58.483246)
		(width 0.0889)
		(layer "F.Cu")
		(net "TP_PCH_CPU_MEMTRIP_N")
	)
	(via
		(at 321.093084 -70.406514)
		(size 0.762)
		(drill 0.381)
		(layers "F.Cu" "B.Cu")
		(net "TP_PCH_CPU_MEMTRIP_N")
	)
	(segment
		(start 325.627746 -36.937188)
		(end 326.542146 -36.937188)
		(width 0.12954)
		(layer "F.Cu")
		(net "TP_PCH_CGC_DUT_DETECTED")
	)
	(segment
		(start 326.542146 -36.937188)
		(end 327.240138 -37.63518)
		(width 0.12954)
		(layer "F.Cu")
		(net "TP_PCH_CGC_DUT_DETECTED")
	)
	(segment
		(start 325.397622 -36.707064)
		(end 325.627746 -36.937188)
		(width 0.12954)
		(layer "F.Cu")
		(net "TP_PCH_CGC_DUT_DETECTED")
	)
	(via
		(at 325.397622 -36.707064)
		(size 0.508)
		(drill 0.254)
		(layers "F.Cu" "B.Cu")
		(net "TP_PCH_CGC_DUT_DETECTED")
	)
	(segment
		(start 137.808716 -118.286784)
		(end 134.9756 -118.286784)
		(width 0.12954)
		(layer "F.Cu")
		(net "TP_PCA9555_U51_P07")
	)
	(via
		(at 134.9756 -118.286784)
		(size 0.762)
		(drill 0.381)
		(layers "F.Cu" "B.Cu")
		(net "TP_PCA9555_U51_P07")
	)
	(segment
		(start 135.88746 -122.186954)
		(end 137.808716 -122.186954)
		(width 0.12954)
		(layer "F.Cu")
		(net "TP_PCA9555_U51_P01")
	)
	(via
		(at 135.88746 -122.186954)
		(size 0.762)
		(drill 0.381)
		(layers "F.Cu" "B.Cu")
		(net "TP_PCA9555_U51_P01")
	)
	(segment
		(start 134.74446 -122.83694)
		(end 137.808716 -122.83694)
		(width 0.12954)
		(layer "F.Cu")
		(net "TP_PCA9555_U51_P00")
	)
	(via
		(at 134.74446 -122.83694)
		(size 0.762)
		(drill 0.381)
		(layers "F.Cu" "B.Cu")
		(net "TP_PCA9555_U51_P00")
	)
	(segment
		(start 353.515676 -60.475368)
		(end 352.090736 -59.050428)
		(width 0.12954)
		(layer "F.Cu")
		(net "TP_P3E_PCH_15_RX_DP")
	)
	(segment
		(start 346.992702 -56.45404)
		(end 346.799662 -56.45404)
		(width 0.0889)
		(layer "F.Cu")
		(net "TP_P3E_PCH_15_RX_DP")
	)
	(segment
		(start 348.771464 -56.528462)
		(end 348.638368 -56.528462)
		(width 0.12954)
		(layer "F.Cu")
		(net "TP_P3E_PCH_15_RX_DP")
	)
	(segment
		(start 353.515676 -61.834268)
		(end 353.515676 -60.475368)
		(width 0.12954)
		(layer "F.Cu")
		(net "TP_P3E_PCH_15_RX_DP")
	)
	(segment
		(start 359.840276 -64.117728)
		(end 355.799136 -64.117728)
		(width 0.12954)
		(layer "F.Cu")
		(net "TP_P3E_PCH_15_RX_DP")
	)
	(segment
		(start 347.043502 -56.40324)
		(end 346.992702 -56.45404)
		(width 0.0889)
		(layer "F.Cu")
		(net "TP_P3E_PCH_15_RX_DP")
	)
	(segment
		(start 351.29343 -59.050428)
		(end 348.771464 -56.528462)
		(width 0.12954)
		(layer "F.Cu")
		(net "TP_P3E_PCH_15_RX_DP")
	)
	(segment
		(start 348.638368 -56.528462)
		(end 348.513146 -56.40324)
		(width 0.0889)
		(layer "F.Cu")
		(net "TP_P3E_PCH_15_RX_DP")
	)
	(segment
		(start 352.090736 -59.050428)
		(end 351.29343 -59.050428)
		(width 0.12954)
		(layer "F.Cu")
		(net "TP_P3E_PCH_15_RX_DP")
	)
	(segment
		(start 348.513146 -56.40324)
		(end 347.043502 -56.40324)
		(width 0.0889)
		(layer "F.Cu")
		(net "TP_P3E_PCH_15_RX_DP")
	)
	(segment
		(start 355.799136 -64.117728)
		(end 353.515676 -61.834268)
		(width 0.12954)
		(layer "F.Cu")
		(net "TP_P3E_PCH_15_RX_DP")
	)
	(via
		(at 359.840276 -64.117728)
		(size 0.762)
		(drill 0.381)
		(layers "F.Cu" "B.Cu")
		(net "TP_P3E_PCH_15_RX_DP")
	)
	(segment
		(start 346.888054 -56.755284)
		(end 346.76969 -56.778906)
		(width 0.0889)
		(layer "F.Cu")
		(net "TP_P3E_PCH_15_RX_DN")
	)
	(segment
		(start 348.396052 -56.770778)
		(end 348.219014 -56.59374)
		(width 0.0889)
		(layer "F.Cu")
		(net "TP_P3E_PCH_15_RX_DN")
	)
	(segment
		(start 348.487492 -56.770778)
		(end 348.396052 -56.770778)
		(width 0.12954)
		(layer "F.Cu")
		(net "TP_P3E_PCH_15_RX_DN")
	)
	(segment
		(start 348.219014 -56.59374)
		(end 347.173804 -56.59374)
		(width 0.0889)
		(layer "F.Cu")
		(net "TP_P3E_PCH_15_RX_DN")
	)
	(segment
		(start 346.47124 -56.657494)
		(end 346.267786 -56.45404)
		(width 0.0889)
		(layer "F.Cu")
		(net "TP_P3E_PCH_15_RX_DN")
	)
	(segment
		(start 353.165156 -62.164468)
		(end 353.165156 -60.551822)
		(width 0.12954)
		(layer "F.Cu")
		(net "TP_P3E_PCH_15_RX_DN")
	)
	(segment
		(start 346.975176 -56.699658)
		(end 346.888054 -56.755284)
		(width 0.0889)
		(layer "F.Cu")
		(net "TP_P3E_PCH_15_RX_DN")
	)
	(segment
		(start 346.76969 -56.778906)
		(end 346.47124 -56.657494)
		(width 0.0889)
		(layer "F.Cu")
		(net "TP_P3E_PCH_15_RX_DN")
	)
	(segment
		(start 358.417876 -64.851788)
		(end 355.852476 -64.851788)
		(width 0.12954)
		(layer "F.Cu")
		(net "TP_P3E_PCH_15_RX_DN")
	)
	(segment
		(start 351.971102 -59.357768)
		(end 351.074482 -59.357768)
		(width 0.12954)
		(layer "F.Cu")
		(net "TP_P3E_PCH_15_RX_DN")
	)
	(segment
		(start 355.852476 -64.851788)
		(end 353.165156 -62.164468)
		(width 0.12954)
		(layer "F.Cu")
		(net "TP_P3E_PCH_15_RX_DN")
	)
	(segment
		(start 347.03766 -56.644794)
		(end 346.975176 -56.699658)
		(width 0.0889)
		(layer "F.Cu")
		(net "TP_P3E_PCH_15_RX_DN")
	)
	(segment
		(start 346.267786 -56.45404)
		(end 345.96959 -56.45404)
		(width 0.0889)
		(layer "F.Cu")
		(net "TP_P3E_PCH_15_RX_DN")
	)
	(segment
		(start 347.173804 -56.59374)
		(end 347.03766 -56.644794)
		(width 0.0889)
		(layer "F.Cu")
		(net "TP_P3E_PCH_15_RX_DN")
	)
	(segment
		(start 353.165156 -60.551822)
		(end 351.971102 -59.357768)
		(width 0.12954)
		(layer "F.Cu")
		(net "TP_P3E_PCH_15_RX_DN")
	)
	(segment
		(start 351.074482 -59.357768)
		(end 348.487492 -56.770778)
		(width 0.12954)
		(layer "F.Cu")
		(net "TP_P3E_PCH_15_RX_DN")
	)
	(via
		(at 358.417876 -64.851788)
		(size 0.762)
		(drill 0.381)
		(layers "F.Cu" "B.Cu")
		(net "TP_P3E_PCH_15_RX_DN")
	)
	(segment
		(start 353.906836 -61.534802)
		(end 353.906836 -60.427362)
		(width 0.12954)
		(layer "F.Cu")
		(net "TP_P3E_PCH_14_RX_DP")
	)
	(segment
		(start 355.849682 -63.477648)
		(end 353.906836 -61.534802)
		(width 0.12954)
		(layer "F.Cu")
		(net "TP_P3E_PCH_14_RX_DP")
	)
	(segment
		(start 353.906836 -60.427362)
		(end 352.214942 -58.735468)
		(width 0.12954)
		(layer "F.Cu")
		(net "TP_P3E_PCH_14_RX_DP")
	)
	(segment
		(start 352.214942 -58.735468)
		(end 351.38995 -58.735468)
		(width 0.12954)
		(layer "F.Cu")
		(net "TP_P3E_PCH_14_RX_DP")
	)
	(segment
		(start 347.380052 -55.953914)
		(end 347.214698 -55.953914)
		(width 0.0889)
		(layer "F.Cu")
		(net "TP_P3E_PCH_14_RX_DP")
	)
	(segment
		(start 348.85249 -56.198008)
		(end 347.624146 -56.198008)
		(width 0.0889)
		(layer "F.Cu")
		(net "TP_P3E_PCH_14_RX_DP")
	)
	(segment
		(start 351.38995 -58.735468)
		(end 348.85249 -56.198008)
		(width 0.12954)
		(layer "F.Cu")
		(net "TP_P3E_PCH_14_RX_DP")
	)
	(segment
		(start 347.624146 -56.198008)
		(end 347.380052 -55.953914)
		(width 0.0889)
		(layer "F.Cu")
		(net "TP_P3E_PCH_14_RX_DP")
	)
	(segment
		(start 358.351582 -63.477648)
		(end 355.849682 -63.477648)
		(width 0.12954)
		(layer "F.Cu")
		(net "TP_P3E_PCH_14_RX_DP")
	)
	(via
		(at 358.351582 -63.477648)
		(size 0.762)
		(drill 0.381)
		(layers "F.Cu" "B.Cu")
		(net "TP_P3E_PCH_14_RX_DP")
	)
	(segment
		(start 349.06204 -55.956708)
		(end 347.973396 -55.956708)
		(width 0.12954)
		(layer "F.Cu")
		(net "TP_P3E_PCH_14_RX_DN")
	)
	(segment
		(start 355.55428 -62.689232)
		(end 354.198936 -61.333888)
		(width 0.12954)
		(layer "F.Cu")
		(net "TP_P3E_PCH_14_RX_DN")
	)
	(segment
		(start 354.198936 -61.333888)
		(end 354.198936 -60.307728)
		(width 0.12954)
		(layer "F.Cu")
		(net "TP_P3E_PCH_14_RX_DN")
	)
	(segment
		(start 347.666564 -55.956708)
		(end 347.384878 -55.675022)
		(width 0.0889)
		(layer "F.Cu")
		(net "TP_P3E_PCH_14_RX_DN")
	)
	(segment
		(start 360.180636 -62.184788)
		(end 359.676192 -62.689232)
		(width 0.12954)
		(layer "F.Cu")
		(net "TP_P3E_PCH_14_RX_DN")
	)
	(segment
		(start 359.676192 -62.689232)
		(end 355.55428 -62.689232)
		(width 0.12954)
		(layer "F.Cu")
		(net "TP_P3E_PCH_14_RX_DN")
	)
	(segment
		(start 347.384878 -55.675022)
		(end 347.063314 -55.675022)
		(width 0.0889)
		(layer "F.Cu")
		(net "TP_P3E_PCH_14_RX_DN")
	)
	(segment
		(start 351.53854 -58.433208)
		(end 349.06204 -55.956708)
		(width 0.12954)
		(layer "F.Cu")
		(net "TP_P3E_PCH_14_RX_DN")
	)
	(segment
		(start 352.324416 -58.433208)
		(end 351.53854 -58.433208)
		(width 0.12954)
		(layer "F.Cu")
		(net "TP_P3E_PCH_14_RX_DN")
	)
	(segment
		(start 347.973396 -55.956708)
		(end 347.666564 -55.956708)
		(width 0.0889)
		(layer "F.Cu")
		(net "TP_P3E_PCH_14_RX_DN")
	)
	(segment
		(start 346.952316 -55.77078)
		(end 346.769182 -55.953914)
		(width 0.0889)
		(layer "F.Cu")
		(net "TP_P3E_PCH_14_RX_DN")
	)
	(segment
		(start 346.769182 -55.953914)
		(end 346.384626 -55.953914)
		(width 0.0889)
		(layer "F.Cu")
		(net "TP_P3E_PCH_14_RX_DN")
	)
	(segment
		(start 347.063314 -55.675022)
		(end 346.952316 -55.77078)
		(width 0.0889)
		(layer "F.Cu")
		(net "TP_P3E_PCH_14_RX_DN")
	)
	(segment
		(start 354.198936 -60.307728)
		(end 352.324416 -58.433208)
		(width 0.12954)
		(layer "F.Cu")
		(net "TP_P3E_PCH_14_RX_DN")
	)
	(via
		(at 360.180636 -62.184788)
		(size 0.762)
		(drill 0.381)
		(layers "F.Cu" "B.Cu")
		(net "TP_P3E_PCH_14_RX_DN")
	)
	(segment
		(start 388.85114 -16.4846)
		(end 388.7216 -16.35506)
		(width 0.12954)
		(layer "F.Cu")
		(net "TP_OCP_SFF_B69")
	)
	(segment
		(start 391.14984 -12.563348)
		(end 391.846816 -11.866372)
		(width 0.12954)
		(layer "F.Cu")
		(net "TP_OCP_SFF_B69")
	)
	(segment
		(start 388.7216 -16.35506)
		(end 388.7216 -13.978128)
		(width 0.12954)
		(layer "F.Cu")
		(net "TP_OCP_SFF_B69")
	)
	(segment
		(start 391.846816 -11.866372)
		(end 391.846816 -11.26998)
		(width 0.12954)
		(layer "F.Cu")
		(net "TP_OCP_SFF_B69")
	)
	(segment
		(start 390.13638 -12.563348)
		(end 391.14984 -12.563348)
		(width 0.12954)
		(layer "F.Cu")
		(net "TP_OCP_SFF_B69")
	)
	(segment
		(start 388.7216 -13.978128)
		(end 390.13638 -12.563348)
		(width 0.12954)
		(layer "F.Cu")
		(net "TP_OCP_SFF_B69")
	)
	(via
		(at 388.85114 -16.4846)
		(size 0.762)
		(drill 0.381)
		(layers "F.Cu" "B.Cu")
		(net "TP_OCP_SFF_B69")
	)
	(segment
		(start 389.45058 -13.769848)
		(end 389.45058 -14.399768)
		(width 0.12954)
		(layer "F.Cu")
		(net "TP_OCP_SFF_B68")
	)
	(segment
		(start 392.446764 -11.26998)
		(end 392.446764 -11.933936)
		(width 0.12954)
		(layer "F.Cu")
		(net "TP_OCP_SFF_B68")
	)
	(segment
		(start 390.3726 -12.847828)
		(end 389.45058 -13.769848)
		(width 0.12954)
		(layer "F.Cu")
		(net "TP_OCP_SFF_B68")
	)
	(segment
		(start 391.532872 -12.847828)
		(end 390.3726 -12.847828)
		(width 0.12954)
		(layer "F.Cu")
		(net "TP_OCP_SFF_B68")
	)
	(segment
		(start 389.45058 -14.399768)
		(end 389.54202 -14.491208)
		(width 0.12954)
		(layer "F.Cu")
		(net "TP_OCP_SFF_B68")
	)
	(segment
		(start 392.446764 -11.933936)
		(end 391.532872 -12.847828)
		(width 0.12954)
		(layer "F.Cu")
		(net "TP_OCP_SFF_B68")
	)
	(via
		(at 389.54202 -14.491208)
		(size 0.762)
		(drill 0.381)
		(layers "F.Cu" "B.Cu")
		(net "TP_OCP_SFF_B68")
	)
	(segment
		(start 121.038112 -230.900732)
		(end 121.038366 -230.900478)
		(width 0.12954)
		(layer "F.Cu")
		(net "TP_JTAG_CPU1_PLD_TMS")
	)
	(segment
		(start 121.038112 -231.436418)
		(end 121.038112 -230.900732)
		(width 0.12954)
		(layer "F.Cu")
		(net "TP_JTAG_CPU1_PLD_TMS")
	)
	(via
		(at 121.038366 -230.900478)
		(size 0.4572)
		(drill 0.2032)
		(layers "F.Cu" "B.Cu")
		(net "TP_JTAG_CPU1_PLD_TMS")
	)
	(via
		(at 144.946878 -229.44709)
		(size 0.6604)
		(drill 0.3302)
		(layers "F.Cu" "B.Cu")
		(net "TP_JTAG_CPU1_PLD_TMS")
	)
	(segment
		(start 132.043678 -230.404924)
		(end 132.033264 -230.41102)
		(width 0.0889)
		(layer "B.Cu")
		(net "TP_JTAG_CPU1_PLD_TMS")
	)
	(segment
		(start 144.946878 -229.44709)
		(end 144.28216 -230.111808)
		(width 0.12954)
		(layer "B.Cu")
		(net "TP_JTAG_CPU1_PLD_TMS")
	)
	(segment
		(start 133.538468 -230.41102)
		(end 133.528054 -230.404924)
		(width 0.0889)
		(layer "B.Cu")
		(net "TP_JTAG_CPU1_PLD_TMS")
	)
	(segment
		(start 144.28216 -230.111808)
		(end 140.42644 -230.111808)
		(width 0.12954)
		(layer "B.Cu")
		(net "TP_JTAG_CPU1_PLD_TMS")
	)
	(segment
		(start 127.899414 -230.41102)
		(end 127.884682 -230.402384)
		(width 0.0889)
		(layer "B.Cu")
		(net "TP_JTAG_CPU1_PLD_TMS")
	)
	(segment
		(start 130.718814 -230.41102)
		(end 130.704082 -230.402384)
		(width 0.0889)
		(layer "B.Cu")
		(net "TP_JTAG_CPU1_PLD_TMS")
	)
	(segment
		(start 124.140214 -230.41102)
		(end 124.125482 -230.402384)
		(width 0.0889)
		(layer "B.Cu")
		(net "TP_JTAG_CPU1_PLD_TMS")
	)
	(segment
		(start 126.019814 -230.41102)
		(end 126.0094 -230.404924)
		(width 0.0889)
		(layer "B.Cu")
		(net "TP_JTAG_CPU1_PLD_TMS")
	)
	(segment
		(start 131.658868 -230.41102)
		(end 131.648454 -230.404924)
		(width 0.0889)
		(layer "B.Cu")
		(net "TP_JTAG_CPU1_PLD_TMS")
	)
	(segment
		(start 139.918694 -230.111808)
		(end 139.711938 -230.318564)
		(width 0.0889)
		(layer "B.Cu")
		(net "TP_JTAG_CPU1_PLD_TMS")
	)
	(segment
		(start 137.297414 -230.41102)
		(end 137.287 -230.404924)
		(width 0.0889)
		(layer "B.Cu")
		(net "TP_JTAG_CPU1_PLD_TMS")
	)
	(segment
		(start 125.080268 -230.41102)
		(end 125.069854 -230.404924)
		(width 0.0889)
		(layer "B.Cu")
		(net "TP_JTAG_CPU1_PLD_TMS")
	)
	(segment
		(start 139.711938 -230.318564)
		(end 139.551664 -230.41102)
		(width 0.0889)
		(layer "B.Cu")
		(net "TP_JTAG_CPU1_PLD_TMS")
	)
	(segment
		(start 138.622024 -230.404924)
		(end 138.61161 -230.41102)
		(width 0.0889)
		(layer "B.Cu")
		(net "TP_JTAG_CPU1_PLD_TMS")
	)
	(segment
		(start 123.200414 -230.41102)
		(end 123.185682 -230.402384)
		(width 0.0889)
		(layer "B.Cu")
		(net "TP_JTAG_CPU1_PLD_TMS")
	)
	(segment
		(start 121.416318 -230.8352)
		(end 121.35104 -230.900478)
		(width 0.0889)
		(layer "B.Cu")
		(net "TP_JTAG_CPU1_PLD_TMS")
	)
	(segment
		(start 140.42644 -230.111808)
		(end 139.918694 -230.111808)
		(width 0.0889)
		(layer "B.Cu")
		(net "TP_JTAG_CPU1_PLD_TMS")
	)
	(segment
		(start 128.839214 -230.41102)
		(end 128.824482 -230.402384)
		(width 0.0889)
		(layer "B.Cu")
		(net "TP_JTAG_CPU1_PLD_TMS")
	)
	(segment
		(start 129.779014 -230.41102)
		(end 129.764282 -230.402384)
		(width 0.0889)
		(layer "B.Cu")
		(net "TP_JTAG_CPU1_PLD_TMS")
	)
	(segment
		(start 126.959614 -230.41102)
		(end 126.944882 -230.402384)
		(width 0.0889)
		(layer "B.Cu")
		(net "TP_JTAG_CPU1_PLD_TMS")
	)
	(segment
		(start 121.35104 -230.900478)
		(end 121.038366 -230.900478)
		(width 0.0889)
		(layer "B.Cu")
		(net "TP_JTAG_CPU1_PLD_TMS")
	)
	(segment
		(start 138.237214 -230.41102)
		(end 138.222482 -230.402384)
		(width 0.0889)
		(layer "B.Cu")
		(net "TP_JTAG_CPU1_PLD_TMS")
	)
	(arc
		(start 133.912864 -230.41102)
		(mid 133.725666 -230.461163)
		(end 133.538468 -230.41102)
		(width 0.0889)
		(layer "B.Cu")
		(net "TP_JTAG_CPU1_PLD_TMS")
	)
	(arc
		(start 135.418068 -230.41102)
		(mid 135.135366 -230.335244)
		(end 134.852664 -230.41102)
		(width 0.0889)
		(layer "B.Cu")
		(net "TP_JTAG_CPU1_PLD_TMS")
	)
	(arc
		(start 137.287 -230.404924)
		(mid 137.008822 -230.335201)
		(end 136.732264 -230.41102)
		(width 0.0889)
		(layer "B.Cu")
		(net "TP_JTAG_CPU1_PLD_TMS")
	)
	(arc
		(start 139.551664 -230.41102)
		(mid 139.364466 -230.461163)
		(end 139.177268 -230.41102)
		(width 0.0889)
		(layer "B.Cu")
		(net "TP_JTAG_CPU1_PLD_TMS")
	)
	(arc
		(start 127.884682 -230.402384)
		(mid 127.608207 -230.335064)
		(end 127.33401 -230.41102)
		(width 0.0889)
		(layer "B.Cu")
		(net "TP_JTAG_CPU1_PLD_TMS")
	)
	(arc
		(start 133.528054 -230.404924)
		(mid 133.249622 -230.335078)
		(end 132.97281 -230.41102)
		(width 0.0889)
		(layer "B.Cu")
		(net "TP_JTAG_CPU1_PLD_TMS")
	)
	(arc
		(start 135.792464 -230.41102)
		(mid 135.605266 -230.461163)
		(end 135.418068 -230.41102)
		(width 0.0889)
		(layer "B.Cu")
		(net "TP_JTAG_CPU1_PLD_TMS")
	)
	(arc
		(start 131.648454 -230.404924)
		(mid 131.370022 -230.335078)
		(end 131.09321 -230.41102)
		(width 0.0889)
		(layer "B.Cu")
		(net "TP_JTAG_CPU1_PLD_TMS")
	)
	(arc
		(start 125.454664 -230.41102)
		(mid 125.267466 -230.461163)
		(end 125.080268 -230.41102)
		(width 0.0889)
		(layer "B.Cu")
		(net "TP_JTAG_CPU1_PLD_TMS")
	)
	(arc
		(start 134.852664 -230.41102)
		(mid 134.665466 -230.461163)
		(end 134.478268 -230.41102)
		(width 0.0889)
		(layer "B.Cu")
		(net "TP_JTAG_CPU1_PLD_TMS")
	)
	(arc
		(start 129.764282 -230.402384)
		(mid 129.487807 -230.335064)
		(end 129.21361 -230.41102)
		(width 0.0889)
		(layer "B.Cu")
		(net "TP_JTAG_CPU1_PLD_TMS")
	)
	(arc
		(start 127.33401 -230.41102)
		(mid 127.146812 -230.461163)
		(end 126.959614 -230.41102)
		(width 0.0889)
		(layer "B.Cu")
		(net "TP_JTAG_CPU1_PLD_TMS")
	)
	(arc
		(start 130.704082 -230.402384)
		(mid 130.427607 -230.335064)
		(end 130.15341 -230.41102)
		(width 0.0889)
		(layer "B.Cu")
		(net "TP_JTAG_CPU1_PLD_TMS")
	)
	(arc
		(start 123.185682 -230.402384)
		(mid 122.909207 -230.335064)
		(end 122.63501 -230.41102)
		(width 0.0889)
		(layer "B.Cu")
		(net "TP_JTAG_CPU1_PLD_TMS")
	)
	(arc
		(start 122.260614 -230.41102)
		(mid 121.977912 -230.335244)
		(end 121.69521 -230.41102)
		(width 0.0889)
		(layer "B.Cu")
		(net "TP_JTAG_CPU1_PLD_TMS")
	)
	(arc
		(start 126.39421 -230.41102)
		(mid 126.207012 -230.461163)
		(end 126.019814 -230.41102)
		(width 0.0889)
		(layer "B.Cu")
		(net "TP_JTAG_CPU1_PLD_TMS")
	)
	(arc
		(start 124.125482 -230.402384)
		(mid 123.849007 -230.335064)
		(end 123.57481 -230.41102)
		(width 0.0889)
		(layer "B.Cu")
		(net "TP_JTAG_CPU1_PLD_TMS")
	)
	(arc
		(start 131.09321 -230.41102)
		(mid 130.906012 -230.461163)
		(end 130.718814 -230.41102)
		(width 0.0889)
		(layer "B.Cu")
		(net "TP_JTAG_CPU1_PLD_TMS")
	)
	(arc
		(start 123.57481 -230.41102)
		(mid 123.387612 -230.461163)
		(end 123.200414 -230.41102)
		(width 0.0889)
		(layer "B.Cu")
		(net "TP_JTAG_CPU1_PLD_TMS")
	)
	(arc
		(start 138.61161 -230.41102)
		(mid 138.424412 -230.461163)
		(end 138.237214 -230.41102)
		(width 0.0889)
		(layer "B.Cu")
		(net "TP_JTAG_CPU1_PLD_TMS")
	)
	(arc
		(start 132.033264 -230.41102)
		(mid 131.846066 -230.461163)
		(end 131.658868 -230.41102)
		(width 0.0889)
		(layer "B.Cu")
		(net "TP_JTAG_CPU1_PLD_TMS")
	)
	(arc
		(start 126.0094 -230.404924)
		(mid 125.731222 -230.335201)
		(end 125.454664 -230.41102)
		(width 0.0889)
		(layer "B.Cu")
		(net "TP_JTAG_CPU1_PLD_TMS")
	)
	(arc
		(start 124.51461 -230.41102)
		(mid 124.327412 -230.461163)
		(end 124.140214 -230.41102)
		(width 0.0889)
		(layer "B.Cu")
		(net "TP_JTAG_CPU1_PLD_TMS")
	)
	(arc
		(start 125.069854 -230.404924)
		(mid 124.791422 -230.335078)
		(end 124.51461 -230.41102)
		(width 0.0889)
		(layer "B.Cu")
		(net "TP_JTAG_CPU1_PLD_TMS")
	)
	(arc
		(start 139.177268 -230.41102)
		(mid 138.900455 -230.33515)
		(end 138.622024 -230.404924)
		(width 0.0889)
		(layer "B.Cu")
		(net "TP_JTAG_CPU1_PLD_TMS")
	)
	(arc
		(start 128.824482 -230.402384)
		(mid 128.548007 -230.335064)
		(end 128.27381 -230.41102)
		(width 0.0889)
		(layer "B.Cu")
		(net "TP_JTAG_CPU1_PLD_TMS")
	)
	(arc
		(start 126.944882 -230.402384)
		(mid 126.668407 -230.335064)
		(end 126.39421 -230.41102)
		(width 0.0889)
		(layer "B.Cu")
		(net "TP_JTAG_CPU1_PLD_TMS")
	)
	(arc
		(start 137.67181 -230.41102)
		(mid 137.484612 -230.461163)
		(end 137.297414 -230.41102)
		(width 0.0889)
		(layer "B.Cu")
		(net "TP_JTAG_CPU1_PLD_TMS")
	)
	(arc
		(start 130.15341 -230.41102)
		(mid 129.966212 -230.461163)
		(end 129.779014 -230.41102)
		(width 0.0889)
		(layer "B.Cu")
		(net "TP_JTAG_CPU1_PLD_TMS")
	)
	(arc
		(start 128.27381 -230.41102)
		(mid 128.086612 -230.461163)
		(end 127.899414 -230.41102)
		(width 0.0889)
		(layer "B.Cu")
		(net "TP_JTAG_CPU1_PLD_TMS")
	)
	(arc
		(start 132.97281 -230.41102)
		(mid 132.785612 -230.461163)
		(end 132.598414 -230.41102)
		(width 0.0889)
		(layer "B.Cu")
		(net "TP_JTAG_CPU1_PLD_TMS")
	)
	(arc
		(start 132.598414 -230.41102)
		(mid 132.321855 -230.335277)
		(end 132.043678 -230.404924)
		(width 0.0889)
		(layer "B.Cu")
		(net "TP_JTAG_CPU1_PLD_TMS")
	)
	(arc
		(start 134.478268 -230.41102)
		(mid 134.195566 -230.335244)
		(end 133.912864 -230.41102)
		(width 0.0889)
		(layer "B.Cu")
		(net "TP_JTAG_CPU1_PLD_TMS")
	)
	(arc
		(start 138.222482 -230.402384)
		(mid 137.946007 -230.335064)
		(end 137.67181 -230.41102)
		(width 0.0889)
		(layer "B.Cu")
		(net "TP_JTAG_CPU1_PLD_TMS")
	)
	(arc
		(start 122.63501 -230.41102)
		(mid 122.447812 -230.461163)
		(end 122.260614 -230.41102)
		(width 0.0889)
		(layer "B.Cu")
		(net "TP_JTAG_CPU1_PLD_TMS")
	)
	(arc
		(start 121.69521 -230.41102)
		(mid 121.50546 -230.590034)
		(end 121.416318 -230.8352)
		(width 0.0889)
		(layer "B.Cu")
		(net "TP_JTAG_CPU1_PLD_TMS")
	)
	(arc
		(start 129.21361 -230.41102)
		(mid 129.026412 -230.461163)
		(end 128.839214 -230.41102)
		(width 0.0889)
		(layer "B.Cu")
		(net "TP_JTAG_CPU1_PLD_TMS")
	)
	(arc
		(start 136.357868 -230.41102)
		(mid 136.075166 -230.335244)
		(end 135.792464 -230.41102)
		(width 0.0889)
		(layer "B.Cu")
		(net "TP_JTAG_CPU1_PLD_TMS")
	)
	(arc
		(start 136.732264 -230.41102)
		(mid 136.545066 -230.461163)
		(end 136.357868 -230.41102)
		(width 0.0889)
		(layer "B.Cu")
		(net "TP_JTAG_CPU1_PLD_TMS")
	)
	(segment
		(start 119.158512 -230.900732)
		(end 119.158766 -230.900478)
		(width 0.12954)
		(layer "F.Cu")
		(net "TP_JTAG_CPU1_PLD_TDO_R")
	)
	(segment
		(start 119.158512 -231.436418)
		(end 119.158512 -230.900732)
		(width 0.12954)
		(layer "F.Cu")
		(net "TP_JTAG_CPU1_PLD_TDO_R")
	)
	(via
		(at 148.177758 -229.01529)
		(size 0.6604)
		(drill 0.3302)
		(layers "F.Cu" "B.Cu")
		(net "TP_JTAG_CPU1_PLD_TDO_R")
	)
	(via
		(at 119.158766 -230.900478)
		(size 0.4572)
		(drill 0.2032)
		(layers "F.Cu" "B.Cu")
		(net "TP_JTAG_CPU1_PLD_TDO_R")
	)
	(segment
		(start 147.512278 -229.01529)
		(end 145.19656 -231.331008)
		(width 0.12954)
		(layer "B.Cu")
		(net "TP_JTAG_CPU1_PLD_TDO_R")
	)
	(segment
		(start 128.839468 -231.39019)
		(end 128.829054 -231.396286)
		(width 0.0889)
		(layer "B.Cu")
		(net "TP_JTAG_CPU1_PLD_TDO_R")
	)
	(segment
		(start 126.019814 -231.39019)
		(end 126.005082 -231.398826)
		(width 0.0889)
		(layer "B.Cu")
		(net "TP_JTAG_CPU1_PLD_TDO_R")
	)
	(segment
		(start 125.080014 -231.39019)
		(end 125.065282 -231.398826)
		(width 0.0889)
		(layer "B.Cu")
		(net "TP_JTAG_CPU1_PLD_TDO_R")
	)
	(segment
		(start 124.140214 -231.39019)
		(end 124.125482 -231.398826)
		(width 0.0889)
		(layer "B.Cu")
		(net "TP_JTAG_CPU1_PLD_TDO_R")
	)
	(segment
		(start 119.536972 -230.96601)
		(end 119.47144 -230.900478)
		(width 0.0889)
		(layer "B.Cu")
		(net "TP_JTAG_CPU1_PLD_TDO_R")
	)
	(segment
		(start 145.19656 -231.331008)
		(end 140.35532 -231.331008)
		(width 0.12954)
		(layer "B.Cu")
		(net "TP_JTAG_CPU1_PLD_TDO_R")
	)
	(segment
		(start 139.562078 -231.30129)
		(end 138.569446 -231.30129)
		(width 0.0889)
		(layer "B.Cu")
		(net "TP_JTAG_CPU1_PLD_TDO_R")
	)
	(segment
		(start 126.959614 -231.39019)
		(end 126.944882 -231.398826)
		(width 0.0889)
		(layer "B.Cu")
		(net "TP_JTAG_CPU1_PLD_TDO_R")
	)
	(segment
		(start 140.29944 -231.386888)
		(end 139.647676 -231.386888)
		(width 0.0889)
		(layer "B.Cu")
		(net "TP_JTAG_CPU1_PLD_TDO_R")
	)
	(segment
		(start 148.177758 -229.01529)
		(end 147.512278 -229.01529)
		(width 0.12954)
		(layer "B.Cu")
		(net "TP_JTAG_CPU1_PLD_TDO_R")
	)
	(segment
		(start 123.200414 -231.39019)
		(end 123.19 -231.396286)
		(width 0.0889)
		(layer "B.Cu")
		(net "TP_JTAG_CPU1_PLD_TDO_R")
	)
	(segment
		(start 140.35532 -231.331008)
		(end 140.29944 -231.386888)
		(width 0.12954)
		(layer "B.Cu")
		(net "TP_JTAG_CPU1_PLD_TDO_R")
	)
	(segment
		(start 129.779014 -231.39019)
		(end 129.7686 -231.396286)
		(width 0.0889)
		(layer "B.Cu")
		(net "TP_JTAG_CPU1_PLD_TDO_R")
	)
	(segment
		(start 121.710196 -231.398826)
		(end 121.695464 -231.39019)
		(width 0.0889)
		(layer "B.Cu")
		(net "TP_JTAG_CPU1_PLD_TDO_R")
	)
	(segment
		(start 127.899414 -231.39019)
		(end 127.884682 -231.398826)
		(width 0.0889)
		(layer "B.Cu")
		(net "TP_JTAG_CPU1_PLD_TDO_R")
	)
	(segment
		(start 119.47144 -230.900478)
		(end 119.158766 -230.900478)
		(width 0.0889)
		(layer "B.Cu")
		(net "TP_JTAG_CPU1_PLD_TDO_R")
	)
	(segment
		(start 121.695464 -231.39019)
		(end 121.687082 -231.385364)
		(width 0.0889)
		(layer "B.Cu")
		(net "TP_JTAG_CPU1_PLD_TDO_R")
	)
	(segment
		(start 131.658614 -231.39019)
		(end 131.643882 -231.398826)
		(width 0.0889)
		(layer "B.Cu")
		(net "TP_JTAG_CPU1_PLD_TDO_R")
	)
	(segment
		(start 139.647676 -231.386888)
		(end 139.562078 -231.30129)
		(width 0.0889)
		(layer "B.Cu")
		(net "TP_JTAG_CPU1_PLD_TDO_R")
	)
	(segment
		(start 137.292334 -231.390444)
		(end 137.246614 -231.416352)
		(width 0.0889)
		(layer "B.Cu")
		(net "TP_JTAG_CPU1_PLD_TDO_R")
	)
	(segment
		(start 138.231626 -231.390444)
		(end 138.166602 -231.427274)
		(width 0.0889)
		(layer "B.Cu")
		(net "TP_JTAG_CPU1_PLD_TDO_R")
	)
	(segment
		(start 130.718814 -231.39019)
		(end 130.704082 -231.398826)
		(width 0.0889)
		(layer "B.Cu")
		(net "TP_JTAG_CPU1_PLD_TDO_R")
	)
	(segment
		(start 133.538468 -231.39019)
		(end 133.528054 -231.396286)
		(width 0.0889)
		(layer "B.Cu")
		(net "TP_JTAG_CPU1_PLD_TDO_R")
	)
	(segment
		(start 137.343896 -231.361234)
		(end 137.292334 -231.390444)
		(width 0.0889)
		(layer "B.Cu")
		(net "TP_JTAG_CPU1_PLD_TDO_R")
	)
	(arc
		(start 131.643882 -231.398826)
		(mid 131.367441 -231.465992)
		(end 131.09321 -231.39019)
		(width 0.0889)
		(layer "B.Cu")
		(net "TP_JTAG_CPU1_PLD_TDO_R")
	)
	(arc
		(start 121.687082 -231.385364)
		(mid 121.503574 -231.340086)
		(end 121.321322 -231.39019)
		(width 0.0889)
		(layer "B.Cu")
		(net "TP_JTAG_CPU1_PLD_TDO_R")
	)
	(arc
		(start 120.381014 -231.39019)
		(mid 120.098566 -231.465805)
		(end 119.816118 -231.39019)
		(width 0.0889)
		(layer "B.Cu")
		(net "TP_JTAG_CPU1_PLD_TDO_R")
	)
	(arc
		(start 123.57481 -231.39019)
		(mid 123.387612 -231.340047)
		(end 123.200414 -231.39019)
		(width 0.0889)
		(layer "B.Cu")
		(net "TP_JTAG_CPU1_PLD_TDO_R")
	)
	(arc
		(start 129.213864 -231.39019)
		(mid 129.026666 -231.340047)
		(end 128.839468 -231.39019)
		(width 0.0889)
		(layer "B.Cu")
		(net "TP_JTAG_CPU1_PLD_TDO_R")
	)
	(arc
		(start 121.321322 -231.39019)
		(mid 121.038366 -231.466059)
		(end 120.75541 -231.39019)
		(width 0.0889)
		(layer "B.Cu")
		(net "TP_JTAG_CPU1_PLD_TDO_R")
	)
	(arc
		(start 138.569446 -231.30129)
		(mid 138.39475 -231.323948)
		(end 138.231626 -231.390444)
		(width 0.0889)
		(layer "B.Cu")
		(net "TP_JTAG_CPU1_PLD_TDO_R")
	)
	(arc
		(start 130.704082 -231.398826)
		(mid 130.427641 -231.465992)
		(end 130.15341 -231.39019)
		(width 0.0889)
		(layer "B.Cu")
		(net "TP_JTAG_CPU1_PLD_TDO_R")
	)
	(arc
		(start 132.03301 -231.39019)
		(mid 131.845812 -231.340047)
		(end 131.658614 -231.39019)
		(width 0.0889)
		(layer "B.Cu")
		(net "TP_JTAG_CPU1_PLD_TDO_R")
	)
	(arc
		(start 131.09321 -231.39019)
		(mid 130.906012 -231.340047)
		(end 130.718814 -231.39019)
		(width 0.0889)
		(layer "B.Cu")
		(net "TP_JTAG_CPU1_PLD_TDO_R")
	)
	(arc
		(start 127.33401 -231.39019)
		(mid 127.146812 -231.340047)
		(end 126.959614 -231.39019)
		(width 0.0889)
		(layer "B.Cu")
		(net "TP_JTAG_CPU1_PLD_TDO_R")
	)
	(arc
		(start 122.635264 -231.39019)
		(mid 122.448066 -231.340047)
		(end 122.260868 -231.39019)
		(width 0.0889)
		(layer "B.Cu")
		(net "TP_JTAG_CPU1_PLD_TDO_R")
	)
	(arc
		(start 138.166602 -231.427274)
		(mid 137.912279 -231.466679)
		(end 137.66673 -231.389682)
		(width 0.0889)
		(layer "B.Cu")
		(net "TP_JTAG_CPU1_PLD_TDO_R")
	)
	(arc
		(start 137.66673 -231.389682)
		(mid 137.508528 -231.339014)
		(end 137.343896 -231.361234)
		(width 0.0889)
		(layer "B.Cu")
		(net "TP_JTAG_CPU1_PLD_TDO_R")
	)
	(arc
		(start 134.478268 -231.39019)
		(mid 134.195566 -231.465932)
		(end 133.912864 -231.39019)
		(width 0.0889)
		(layer "B.Cu")
		(net "TP_JTAG_CPU1_PLD_TDO_R")
	)
	(arc
		(start 128.829054 -231.396286)
		(mid 128.550622 -231.4661)
		(end 128.27381 -231.39019)
		(width 0.0889)
		(layer "B.Cu")
		(net "TP_JTAG_CPU1_PLD_TDO_R")
	)
	(arc
		(start 122.260868 -231.39019)
		(mid 121.986639 -231.466115)
		(end 121.710196 -231.398826)
		(width 0.0889)
		(layer "B.Cu")
		(net "TP_JTAG_CPU1_PLD_TDO_R")
	)
	(arc
		(start 136.732264 -231.39019)
		(mid 136.545066 -231.340047)
		(end 136.357868 -231.39019)
		(width 0.0889)
		(layer "B.Cu")
		(net "TP_JTAG_CPU1_PLD_TDO_R")
	)
	(arc
		(start 132.97281 -231.39019)
		(mid 132.785612 -231.340047)
		(end 132.598414 -231.39019)
		(width 0.0889)
		(layer "B.Cu")
		(net "TP_JTAG_CPU1_PLD_TDO_R")
	)
	(arc
		(start 120.75541 -231.39019)
		(mid 120.568212 -231.340047)
		(end 120.381014 -231.39019)
		(width 0.0889)
		(layer "B.Cu")
		(net "TP_JTAG_CPU1_PLD_TDO_R")
	)
	(arc
		(start 129.7686 -231.396286)
		(mid 129.490422 -231.465978)
		(end 129.213864 -231.39019)
		(width 0.0889)
		(layer "B.Cu")
		(net "TP_JTAG_CPU1_PLD_TDO_R")
	)
	(arc
		(start 123.19 -231.396286)
		(mid 122.911822 -231.465978)
		(end 122.635264 -231.39019)
		(width 0.0889)
		(layer "B.Cu")
		(net "TP_JTAG_CPU1_PLD_TDO_R")
	)
	(arc
		(start 119.816118 -231.39019)
		(mid 119.626281 -231.211189)
		(end 119.536972 -230.96601)
		(width 0.0889)
		(layer "B.Cu")
		(net "TP_JTAG_CPU1_PLD_TDO_R")
	)
	(arc
		(start 135.792464 -231.39019)
		(mid 135.605266 -231.340047)
		(end 135.418068 -231.39019)
		(width 0.0889)
		(layer "B.Cu")
		(net "TP_JTAG_CPU1_PLD_TDO_R")
	)
	(arc
		(start 133.528054 -231.396286)
		(mid 133.249622 -231.4661)
		(end 132.97281 -231.39019)
		(width 0.0889)
		(layer "B.Cu")
		(net "TP_JTAG_CPU1_PLD_TDO_R")
	)
	(arc
		(start 136.357868 -231.39019)
		(mid 136.075166 -231.465932)
		(end 135.792464 -231.39019)
		(width 0.0889)
		(layer "B.Cu")
		(net "TP_JTAG_CPU1_PLD_TDO_R")
	)
	(arc
		(start 125.065282 -231.398826)
		(mid 124.788841 -231.465992)
		(end 124.51461 -231.39019)
		(width 0.0889)
		(layer "B.Cu")
		(net "TP_JTAG_CPU1_PLD_TDO_R")
	)
	(arc
		(start 133.912864 -231.39019)
		(mid 133.725666 -231.340047)
		(end 133.538468 -231.39019)
		(width 0.0889)
		(layer "B.Cu")
		(net "TP_JTAG_CPU1_PLD_TDO_R")
	)
	(arc
		(start 135.418068 -231.39019)
		(mid 135.135366 -231.465932)
		(end 134.852664 -231.39019)
		(width 0.0889)
		(layer "B.Cu")
		(net "TP_JTAG_CPU1_PLD_TDO_R")
	)
	(arc
		(start 126.944882 -231.398826)
		(mid 126.668441 -231.465992)
		(end 126.39421 -231.39019)
		(width 0.0889)
		(layer "B.Cu")
		(net "TP_JTAG_CPU1_PLD_TDO_R")
	)
	(arc
		(start 130.15341 -231.39019)
		(mid 129.966212 -231.340047)
		(end 129.779014 -231.39019)
		(width 0.0889)
		(layer "B.Cu")
		(net "TP_JTAG_CPU1_PLD_TDO_R")
	)
	(arc
		(start 137.246614 -231.416352)
		(mid 136.986281 -231.465247)
		(end 136.732264 -231.39019)
		(width 0.0889)
		(layer "B.Cu")
		(net "TP_JTAG_CPU1_PLD_TDO_R")
	)
	(arc
		(start 124.125482 -231.398826)
		(mid 123.849041 -231.465992)
		(end 123.57481 -231.39019)
		(width 0.0889)
		(layer "B.Cu")
		(net "TP_JTAG_CPU1_PLD_TDO_R")
	)
	(arc
		(start 132.598414 -231.39019)
		(mid 132.315712 -231.465932)
		(end 132.03301 -231.39019)
		(width 0.0889)
		(layer "B.Cu")
		(net "TP_JTAG_CPU1_PLD_TDO_R")
	)
	(arc
		(start 134.852664 -231.39019)
		(mid 134.665466 -231.340047)
		(end 134.478268 -231.39019)
		(width 0.0889)
		(layer "B.Cu")
		(net "TP_JTAG_CPU1_PLD_TDO_R")
	)
	(arc
		(start 124.51461 -231.39019)
		(mid 124.327412 -231.340047)
		(end 124.140214 -231.39019)
		(width 0.0889)
		(layer "B.Cu")
		(net "TP_JTAG_CPU1_PLD_TDO_R")
	)
	(arc
		(start 125.45441 -231.39019)
		(mid 125.267212 -231.340047)
		(end 125.080014 -231.39019)
		(width 0.0889)
		(layer "B.Cu")
		(net "TP_JTAG_CPU1_PLD_TDO_R")
	)
	(arc
		(start 127.884682 -231.398826)
		(mid 127.608241 -231.465992)
		(end 127.33401 -231.39019)
		(width 0.0889)
		(layer "B.Cu")
		(net "TP_JTAG_CPU1_PLD_TDO_R")
	)
	(arc
		(start 126.39421 -231.39019)
		(mid 126.207012 -231.340047)
		(end 126.019814 -231.39019)
		(width 0.0889)
		(layer "B.Cu")
		(net "TP_JTAG_CPU1_PLD_TDO_R")
	)
	(arc
		(start 126.005082 -231.398826)
		(mid 125.728641 -231.465992)
		(end 125.45441 -231.39019)
		(width 0.0889)
		(layer "B.Cu")
		(net "TP_JTAG_CPU1_PLD_TDO_R")
	)
	(arc
		(start 128.27381 -231.39019)
		(mid 128.086612 -231.340047)
		(end 127.899414 -231.39019)
		(width 0.0889)
		(layer "B.Cu")
		(net "TP_JTAG_CPU1_PLD_TDO_R")
	)
	(segment
		(start 120.098312 -230.900732)
		(end 120.098566 -230.900478)
		(width 0.12954)
		(layer "F.Cu")
		(net "TP_JTAG_CPU1_PLD_TDI")
	)
	(segment
		(start 120.098312 -231.436418)
		(end 120.098312 -230.900732)
		(width 0.12954)
		(layer "F.Cu")
		(net "TP_JTAG_CPU1_PLD_TDI")
	)
	(via
		(at 149.254718 -227.35921)
		(size 0.6604)
		(drill 0.3302)
		(layers "F.Cu" "B.Cu")
		(net "TP_JTAG_CPU1_PLD_TDI")
	)
	(via
		(at 120.098566 -230.900478)
		(size 0.4572)
		(drill 0.2032)
		(layers "F.Cu" "B.Cu")
		(net "TP_JTAG_CPU1_PLD_TDI")
	)
	(segment
		(start 124.059696 -231.2162)
		(end 124.044964 -231.224836)
		(width 0.0889)
		(layer "B.Cu")
		(net "TP_JTAG_CPU1_PLD_TDI")
	)
	(segment
		(start 123.119896 -231.2162)
		(end 123.105164 -231.224836)
		(width 0.0889)
		(layer "B.Cu")
		(net "TP_JTAG_CPU1_PLD_TDI")
	)
	(segment
		(start 148.622258 -227.35921)
		(end 145.03908 -230.942388)
		(width 0.12954)
		(layer "B.Cu")
		(net "TP_JTAG_CPU1_PLD_TDI")
	)
	(segment
		(start 119.911368 -231.224836)
		(end 119.902478 -231.219756)
		(width 0.0889)
		(layer "B.Cu")
		(net "TP_JTAG_CPU1_PLD_TDI")
	)
	(segment
		(start 140.198094 -230.942388)
		(end 139.790932 -231.111044)
		(width 0.0889)
		(layer "B.Cu")
		(net "TP_JTAG_CPU1_PLD_TDI")
	)
	(segment
		(start 125.939296 -231.2162)
		(end 125.924564 -231.224836)
		(width 0.0889)
		(layer "B.Cu")
		(net "TP_JTAG_CPU1_PLD_TDI")
	)
	(segment
		(start 129.698496 -231.2162)
		(end 129.683764 -231.224836)
		(width 0.0889)
		(layer "B.Cu")
		(net "TP_JTAG_CPU1_PLD_TDI")
	)
	(segment
		(start 119.728488 -230.957882)
		(end 119.785892 -230.900478)
		(width 0.0889)
		(layer "B.Cu")
		(net "TP_JTAG_CPU1_PLD_TDI")
	)
	(segment
		(start 132.513324 -231.21874)
		(end 132.50291 -231.224836)
		(width 0.0889)
		(layer "B.Cu")
		(net "TP_JTAG_CPU1_PLD_TDI")
	)
	(segment
		(start 149.254718 -227.35921)
		(end 148.622258 -227.35921)
		(width 0.12954)
		(layer "B.Cu")
		(net "TP_JTAG_CPU1_PLD_TDI")
	)
	(segment
		(start 137.2616 -231.188514)
		(end 137.1981 -231.224582)
		(width 0.0889)
		(layer "B.Cu")
		(net "TP_JTAG_CPU1_PLD_TDI")
	)
	(segment
		(start 120.300496 -231.2162)
		(end 120.285764 -231.224836)
		(width 0.0889)
		(layer "B.Cu")
		(net "TP_JTAG_CPU1_PLD_TDI")
	)
	(segment
		(start 139.790932 -231.111044)
		(end 138.569446 -231.111044)
		(width 0.0889)
		(layer "B.Cu")
		(net "TP_JTAG_CPU1_PLD_TDI")
	)
	(segment
		(start 131.573778 -231.21874)
		(end 131.563364 -231.224836)
		(width 0.0889)
		(layer "B.Cu")
		(net "TP_JTAG_CPU1_PLD_TDI")
	)
	(segment
		(start 121.790968 -231.224836)
		(end 121.776236 -231.2162)
		(width 0.0889)
		(layer "B.Cu")
		(net "TP_JTAG_CPU1_PLD_TDI")
	)
	(segment
		(start 121.79935 -231.229662)
		(end 121.790968 -231.224836)
		(width 0.0889)
		(layer "B.Cu")
		(net "TP_JTAG_CPU1_PLD_TDI")
	)
	(segment
		(start 145.03908 -230.942388)
		(end 140.198094 -230.942388)
		(width 0.12954)
		(layer "B.Cu")
		(net "TP_JTAG_CPU1_PLD_TDI")
	)
	(segment
		(start 119.785892 -230.900478)
		(end 120.098566 -230.900478)
		(width 0.0889)
		(layer "B.Cu")
		(net "TP_JTAG_CPU1_PLD_TDI")
	)
	(segment
		(start 122.730768 -231.224836)
		(end 122.720354 -231.21874)
		(width 0.0889)
		(layer "B.Cu")
		(net "TP_JTAG_CPU1_PLD_TDI")
	)
	(segment
		(start 124.999496 -231.2162)
		(end 124.984764 -231.224836)
		(width 0.0889)
		(layer "B.Cu")
		(net "TP_JTAG_CPU1_PLD_TDI")
	)
	(segment
		(start 130.638296 -231.2162)
		(end 130.623564 -231.224836)
		(width 0.0889)
		(layer "B.Cu")
		(net "TP_JTAG_CPU1_PLD_TDI")
	)
	(segment
		(start 138.1379 -231.224582)
		(end 138.086338 -231.253792)
		(width 0.0889)
		(layer "B.Cu")
		(net "TP_JTAG_CPU1_PLD_TDI")
	)
	(segment
		(start 127.818896 -231.2162)
		(end 127.804164 -231.224836)
		(width 0.0889)
		(layer "B.Cu")
		(net "TP_JTAG_CPU1_PLD_TDI")
	)
	(segment
		(start 137.1981 -231.224582)
		(end 137.16254 -231.244648)
		(width 0.0889)
		(layer "B.Cu")
		(net "TP_JTAG_CPU1_PLD_TDI")
	)
	(segment
		(start 126.879096 -231.2162)
		(end 126.864364 -231.224836)
		(width 0.0889)
		(layer "B.Cu")
		(net "TP_JTAG_CPU1_PLD_TDI")
	)
	(arc
		(start 136.262364 -231.224836)
		(mid 136.075166 -231.274979)
		(end 135.887968 -231.224836)
		(width 0.0889)
		(layer "B.Cu")
		(net "TP_JTAG_CPU1_PLD_TDI")
	)
	(arc
		(start 136.827768 -231.224836)
		(mid 136.545066 -231.149094)
		(end 136.262364 -231.224836)
		(width 0.0889)
		(layer "B.Cu")
		(net "TP_JTAG_CPU1_PLD_TDI")
	)
	(arc
		(start 119.902478 -231.219756)
		(mid 119.786739 -231.107932)
		(end 119.728488 -230.957882)
		(width 0.0889)
		(layer "B.Cu")
		(net "TP_JTAG_CPU1_PLD_TDI")
	)
	(arc
		(start 124.984764 -231.224836)
		(mid 124.797566 -231.274979)
		(end 124.610368 -231.224836)
		(width 0.0889)
		(layer "B.Cu")
		(net "TP_JTAG_CPU1_PLD_TDI")
	)
	(arc
		(start 131.188968 -231.224836)
		(mid 130.914739 -231.148911)
		(end 130.638296 -231.2162)
		(width 0.0889)
		(layer "B.Cu")
		(net "TP_JTAG_CPU1_PLD_TDI")
	)
	(arc
		(start 135.887968 -231.224836)
		(mid 135.605266 -231.149094)
		(end 135.322564 -231.224836)
		(width 0.0889)
		(layer "B.Cu")
		(net "TP_JTAG_CPU1_PLD_TDI")
	)
	(arc
		(start 122.16511 -231.224836)
		(mid 121.982859 -231.274947)
		(end 121.79935 -231.229662)
		(width 0.0889)
		(layer "B.Cu")
		(net "TP_JTAG_CPU1_PLD_TDI")
	)
	(arc
		(start 128.369568 -231.224836)
		(mid 128.095339 -231.148911)
		(end 127.818896 -231.2162)
		(width 0.0889)
		(layer "B.Cu")
		(net "TP_JTAG_CPU1_PLD_TDI")
	)
	(arc
		(start 125.550168 -231.224836)
		(mid 125.275939 -231.148911)
		(end 124.999496 -231.2162)
		(width 0.0889)
		(layer "B.Cu")
		(net "TP_JTAG_CPU1_PLD_TDI")
	)
	(arc
		(start 138.086338 -231.253792)
		(mid 137.921703 -231.276043)
		(end 137.763504 -231.225344)
		(width 0.0889)
		(layer "B.Cu")
		(net "TP_JTAG_CPU1_PLD_TDI")
	)
	(arc
		(start 130.249168 -231.224836)
		(mid 129.974939 -231.148911)
		(end 129.698496 -231.2162)
		(width 0.0889)
		(layer "B.Cu")
		(net "TP_JTAG_CPU1_PLD_TDI")
	)
	(arc
		(start 138.569446 -231.111044)
		(mid 138.346327 -231.139899)
		(end 138.1379 -231.224582)
		(width 0.0889)
		(layer "B.Cu")
		(net "TP_JTAG_CPU1_PLD_TDI")
	)
	(arc
		(start 123.670568 -231.224836)
		(mid 123.396339 -231.148911)
		(end 123.119896 -231.2162)
		(width 0.0889)
		(layer "B.Cu")
		(net "TP_JTAG_CPU1_PLD_TDI")
	)
	(arc
		(start 134.948168 -231.224836)
		(mid 134.665466 -231.149094)
		(end 134.382764 -231.224836)
		(width 0.0889)
		(layer "B.Cu")
		(net "TP_JTAG_CPU1_PLD_TDI")
	)
	(arc
		(start 123.105164 -231.224836)
		(mid 122.917966 -231.274979)
		(end 122.730768 -231.224836)
		(width 0.0889)
		(layer "B.Cu")
		(net "TP_JTAG_CPU1_PLD_TDI")
	)
	(arc
		(start 137.16254 -231.244648)
		(mid 136.992816 -231.274297)
		(end 136.827768 -231.224836)
		(width 0.0889)
		(layer "B.Cu")
		(net "TP_JTAG_CPU1_PLD_TDI")
	)
	(arc
		(start 131.563364 -231.224836)
		(mid 131.376166 -231.274979)
		(end 131.188968 -231.224836)
		(width 0.0889)
		(layer "B.Cu")
		(net "TP_JTAG_CPU1_PLD_TDI")
	)
	(arc
		(start 126.864364 -231.224836)
		(mid 126.677166 -231.274979)
		(end 126.489968 -231.224836)
		(width 0.0889)
		(layer "B.Cu")
		(net "TP_JTAG_CPU1_PLD_TDI")
	)
	(arc
		(start 135.322564 -231.224836)
		(mid 135.135366 -231.274979)
		(end 134.948168 -231.224836)
		(width 0.0889)
		(layer "B.Cu")
		(net "TP_JTAG_CPU1_PLD_TDI")
	)
	(arc
		(start 134.382764 -231.224836)
		(mid 134.195566 -231.274979)
		(end 134.008368 -231.224836)
		(width 0.0889)
		(layer "B.Cu")
		(net "TP_JTAG_CPU1_PLD_TDI")
	)
	(arc
		(start 124.044964 -231.224836)
		(mid 123.857766 -231.274979)
		(end 123.670568 -231.224836)
		(width 0.0889)
		(layer "B.Cu")
		(net "TP_JTAG_CPU1_PLD_TDI")
	)
	(arc
		(start 130.623564 -231.224836)
		(mid 130.436366 -231.274979)
		(end 130.249168 -231.224836)
		(width 0.0889)
		(layer "B.Cu")
		(net "TP_JTAG_CPU1_PLD_TDI")
	)
	(arc
		(start 129.309368 -231.224836)
		(mid 129.026666 -231.149094)
		(end 128.743964 -231.224836)
		(width 0.0889)
		(layer "B.Cu")
		(net "TP_JTAG_CPU1_PLD_TDI")
	)
	(arc
		(start 129.683764 -231.224836)
		(mid 129.496566 -231.274979)
		(end 129.309368 -231.224836)
		(width 0.0889)
		(layer "B.Cu")
		(net "TP_JTAG_CPU1_PLD_TDI")
	)
	(arc
		(start 121.776236 -231.2162)
		(mid 121.499795 -231.149034)
		(end 121.225564 -231.224836)
		(width 0.0889)
		(layer "B.Cu")
		(net "TP_JTAG_CPU1_PLD_TDI")
	)
	(arc
		(start 121.225564 -231.224836)
		(mid 121.038366 -231.274979)
		(end 120.851168 -231.224836)
		(width 0.0889)
		(layer "B.Cu")
		(net "TP_JTAG_CPU1_PLD_TDI")
	)
	(arc
		(start 127.804164 -231.224836)
		(mid 127.616966 -231.274979)
		(end 127.429768 -231.224836)
		(width 0.0889)
		(layer "B.Cu")
		(net "TP_JTAG_CPU1_PLD_TDI")
	)
	(arc
		(start 124.610368 -231.224836)
		(mid 124.336139 -231.148911)
		(end 124.059696 -231.2162)
		(width 0.0889)
		(layer "B.Cu")
		(net "TP_JTAG_CPU1_PLD_TDI")
	)
	(arc
		(start 128.743964 -231.224836)
		(mid 128.556766 -231.274979)
		(end 128.369568 -231.224836)
		(width 0.0889)
		(layer "B.Cu")
		(net "TP_JTAG_CPU1_PLD_TDI")
	)
	(arc
		(start 132.128514 -231.224836)
		(mid 131.851955 -231.149127)
		(end 131.573778 -231.21874)
		(width 0.0889)
		(layer "B.Cu")
		(net "TP_JTAG_CPU1_PLD_TDI")
	)
	(arc
		(start 133.442964 -231.224836)
		(mid 133.255766 -231.274979)
		(end 133.068568 -231.224836)
		(width 0.0889)
		(layer "B.Cu")
		(net "TP_JTAG_CPU1_PLD_TDI")
	)
	(arc
		(start 126.489968 -231.224836)
		(mid 126.215739 -231.148911)
		(end 125.939296 -231.2162)
		(width 0.0889)
		(layer "B.Cu")
		(net "TP_JTAG_CPU1_PLD_TDI")
	)
	(arc
		(start 120.285764 -231.224836)
		(mid 120.098566 -231.274979)
		(end 119.911368 -231.224836)
		(width 0.0889)
		(layer "B.Cu")
		(net "TP_JTAG_CPU1_PLD_TDI")
	)
	(arc
		(start 134.008368 -231.224836)
		(mid 133.725666 -231.149094)
		(end 133.442964 -231.224836)
		(width 0.0889)
		(layer "B.Cu")
		(net "TP_JTAG_CPU1_PLD_TDI")
	)
	(arc
		(start 120.851168 -231.224836)
		(mid 120.576939 -231.148911)
		(end 120.300496 -231.2162)
		(width 0.0889)
		(layer "B.Cu")
		(net "TP_JTAG_CPU1_PLD_TDI")
	)
	(arc
		(start 133.068568 -231.224836)
		(mid 132.791755 -231.149)
		(end 132.513324 -231.21874)
		(width 0.0889)
		(layer "B.Cu")
		(net "TP_JTAG_CPU1_PLD_TDI")
	)
	(arc
		(start 127.429768 -231.224836)
		(mid 127.155539 -231.148911)
		(end 126.879096 -231.2162)
		(width 0.0889)
		(layer "B.Cu")
		(net "TP_JTAG_CPU1_PLD_TDI")
	)
	(arc
		(start 122.720354 -231.21874)
		(mid 122.441922 -231.148926)
		(end 122.16511 -231.224836)
		(width 0.0889)
		(layer "B.Cu")
		(net "TP_JTAG_CPU1_PLD_TDI")
	)
	(arc
		(start 132.50291 -231.224836)
		(mid 132.315712 -231.274979)
		(end 132.128514 -231.224836)
		(width 0.0889)
		(layer "B.Cu")
		(net "TP_JTAG_CPU1_PLD_TDI")
	)
	(arc
		(start 137.763504 -231.225344)
		(mid 137.516849 -231.148246)
		(end 137.2616 -231.188514)
		(width 0.0889)
		(layer "B.Cu")
		(net "TP_JTAG_CPU1_PLD_TDI")
	)
	(arc
		(start 125.924564 -231.224836)
		(mid 125.737366 -231.274979)
		(end 125.550168 -231.224836)
		(width 0.0889)
		(layer "B.Cu")
		(net "TP_JTAG_CPU1_PLD_TDI")
	)
	(segment
		(start 368.97818 -231.436418)
		(end 368.97818 -230.900732)
		(width 0.12954)
		(layer "F.Cu")
		(net "TP_JTAG_CPU0_PLD_TMS")
	)
	(segment
		(start 368.97818 -230.900732)
		(end 368.978434 -230.900478)
		(width 0.12954)
		(layer "F.Cu")
		(net "TP_JTAG_CPU0_PLD_TMS")
	)
	(via
		(at 368.978434 -230.900478)
		(size 0.4572)
		(drill 0.2032)
		(layers "F.Cu" "B.Cu")
		(net "TP_JTAG_CPU0_PLD_TMS")
	)
	(via
		(at 390.047988 -229.91318)
		(size 0.6604)
		(drill 0.3302)
		(layers "F.Cu" "B.Cu")
		(net "TP_JTAG_CPU0_PLD_TMS")
	)
	(segment
		(start 387.120638 -232.19537)
		(end 386.632958 -231.70769)
		(width 0.12954)
		(layer "B.Cu")
		(net "TP_JTAG_CPU0_PLD_TMS")
	)
	(segment
		(start 372.080282 -231.39019)
		(end 372.06555 -231.398826)
		(width 0.0889)
		(layer "B.Cu")
		(net "TP_JTAG_CPU0_PLD_TMS")
	)
	(segment
		(start 379.598682 -231.39019)
		(end 379.58395 -231.398826)
		(width 0.0889)
		(layer "B.Cu")
		(net "TP_JTAG_CPU0_PLD_TMS")
	)
	(segment
		(start 373.959882 -231.39019)
		(end 373.94515 -231.398826)
		(width 0.0889)
		(layer "B.Cu")
		(net "TP_JTAG_CPU0_PLD_TMS")
	)
	(segment
		(start 370.575332 -231.39019)
		(end 370.56695 -231.385364)
		(width 0.0889)
		(layer "B.Cu")
		(net "TP_JTAG_CPU0_PLD_TMS")
	)
	(segment
		(start 386.287518 -231.70769)
		(end 385.759198 -231.70769)
		(width 0.0889)
		(layer "B.Cu")
		(net "TP_JTAG_CPU0_PLD_TMS")
	)
	(segment
		(start 371.140482 -231.39019)
		(end 371.130068 -231.396286)
		(width 0.0889)
		(layer "B.Cu")
		(net "TP_JTAG_CPU0_PLD_TMS")
	)
	(segment
		(start 369.635278 -231.39019)
		(end 368.978434 -230.900478)
		(width 0.0889)
		(layer "B.Cu")
		(net "TP_JTAG_CPU0_PLD_TMS")
	)
	(segment
		(start 376.779536 -231.39019)
		(end 376.769122 -231.396286)
		(width 0.0889)
		(layer "B.Cu")
		(net "TP_JTAG_CPU0_PLD_TMS")
	)
	(segment
		(start 386.632958 -231.70769)
		(end 386.287518 -231.70769)
		(width 0.12954)
		(layer "B.Cu")
		(net "TP_JTAG_CPU0_PLD_TMS")
	)
	(segment
		(start 390.047988 -229.91318)
		(end 387.765798 -232.19537)
		(width 0.12954)
		(layer "B.Cu")
		(net "TP_JTAG_CPU0_PLD_TMS")
	)
	(segment
		(start 385.441698 -231.39019)
		(end 385.237736 -231.39019)
		(width 0.0889)
		(layer "B.Cu")
		(net "TP_JTAG_CPU0_PLD_TMS")
	)
	(segment
		(start 385.759198 -231.70769)
		(end 385.441698 -231.39019)
		(width 0.0889)
		(layer "B.Cu")
		(net "TP_JTAG_CPU0_PLD_TMS")
	)
	(segment
		(start 375.839482 -231.39019)
		(end 375.82475 -231.398826)
		(width 0.0889)
		(layer "B.Cu")
		(net "TP_JTAG_CPU0_PLD_TMS")
	)
	(segment
		(start 378.658882 -231.39019)
		(end 378.64415 -231.398826)
		(width 0.0889)
		(layer "B.Cu")
		(net "TP_JTAG_CPU0_PLD_TMS")
	)
	(segment
		(start 387.765798 -232.19537)
		(end 387.120638 -232.19537)
		(width 0.12954)
		(layer "B.Cu")
		(net "TP_JTAG_CPU0_PLD_TMS")
	)
	(segment
		(start 374.899682 -231.39019)
		(end 374.88495 -231.398826)
		(width 0.0889)
		(layer "B.Cu")
		(net "TP_JTAG_CPU0_PLD_TMS")
	)
	(segment
		(start 369.65001 -231.398826)
		(end 369.635278 -231.39019)
		(width 0.0889)
		(layer "B.Cu")
		(net "TP_JTAG_CPU0_PLD_TMS")
	)
	(segment
		(start 381.478536 -231.39019)
		(end 381.468122 -231.396286)
		(width 0.0889)
		(layer "B.Cu")
		(net "TP_JTAG_CPU0_PLD_TMS")
	)
	(segment
		(start 377.719082 -231.39019)
		(end 377.708668 -231.396286)
		(width 0.0889)
		(layer "B.Cu")
		(net "TP_JTAG_CPU0_PLD_TMS")
	)
	(segment
		(start 373.020082 -231.39019)
		(end 373.00535 -231.398826)
		(width 0.0889)
		(layer "B.Cu")
		(net "TP_JTAG_CPU0_PLD_TMS")
	)
	(arc
		(start 376.769122 -231.396286)
		(mid 376.49069 -231.4661)
		(end 376.213878 -231.39019)
		(width 0.0889)
		(layer "B.Cu")
		(net "TP_JTAG_CPU0_PLD_TMS")
	)
	(arc
		(start 383.732532 -231.39019)
		(mid 383.545334 -231.340047)
		(end 383.358136 -231.39019)
		(width 0.0889)
		(layer "B.Cu")
		(net "TP_JTAG_CPU0_PLD_TMS")
	)
	(arc
		(start 382.792732 -231.39019)
		(mid 382.605534 -231.340047)
		(end 382.418336 -231.39019)
		(width 0.0889)
		(layer "B.Cu")
		(net "TP_JTAG_CPU0_PLD_TMS")
	)
	(arc
		(start 379.58395 -231.398826)
		(mid 379.307509 -231.465992)
		(end 379.033278 -231.39019)
		(width 0.0889)
		(layer "B.Cu")
		(net "TP_JTAG_CPU0_PLD_TMS")
	)
	(arc
		(start 384.672332 -231.39019)
		(mid 384.485134 -231.340047)
		(end 384.297936 -231.39019)
		(width 0.0889)
		(layer "B.Cu")
		(net "TP_JTAG_CPU0_PLD_TMS")
	)
	(arc
		(start 374.88495 -231.398826)
		(mid 374.608509 -231.465992)
		(end 374.334278 -231.39019)
		(width 0.0889)
		(layer "B.Cu")
		(net "TP_JTAG_CPU0_PLD_TMS")
	)
	(arc
		(start 380.912878 -231.39019)
		(mid 380.72568 -231.340047)
		(end 380.538482 -231.39019)
		(width 0.0889)
		(layer "B.Cu")
		(net "TP_JTAG_CPU0_PLD_TMS")
	)
	(arc
		(start 379.033278 -231.39019)
		(mid 378.84608 -231.340047)
		(end 378.658882 -231.39019)
		(width 0.0889)
		(layer "B.Cu")
		(net "TP_JTAG_CPU0_PLD_TMS")
	)
	(arc
		(start 385.237736 -231.39019)
		(mid 384.955034 -231.465932)
		(end 384.672332 -231.39019)
		(width 0.0889)
		(layer "B.Cu")
		(net "TP_JTAG_CPU0_PLD_TMS")
	)
	(arc
		(start 382.418336 -231.39019)
		(mid 382.135634 -231.465932)
		(end 381.852932 -231.39019)
		(width 0.0889)
		(layer "B.Cu")
		(net "TP_JTAG_CPU0_PLD_TMS")
	)
	(arc
		(start 383.358136 -231.39019)
		(mid 383.075434 -231.465932)
		(end 382.792732 -231.39019)
		(width 0.0889)
		(layer "B.Cu")
		(net "TP_JTAG_CPU0_PLD_TMS")
	)
	(arc
		(start 378.64415 -231.398826)
		(mid 378.367709 -231.465992)
		(end 378.093478 -231.39019)
		(width 0.0889)
		(layer "B.Cu")
		(net "TP_JTAG_CPU0_PLD_TMS")
	)
	(arc
		(start 374.334278 -231.39019)
		(mid 374.14708 -231.340047)
		(end 373.959882 -231.39019)
		(width 0.0889)
		(layer "B.Cu")
		(net "TP_JTAG_CPU0_PLD_TMS")
	)
	(arc
		(start 373.394478 -231.39019)
		(mid 373.20728 -231.340047)
		(end 373.020082 -231.39019)
		(width 0.0889)
		(layer "B.Cu")
		(net "TP_JTAG_CPU0_PLD_TMS")
	)
	(arc
		(start 377.708668 -231.396286)
		(mid 377.43049 -231.465978)
		(end 377.153932 -231.39019)
		(width 0.0889)
		(layer "B.Cu")
		(net "TP_JTAG_CPU0_PLD_TMS")
	)
	(arc
		(start 375.274078 -231.39019)
		(mid 375.08688 -231.340047)
		(end 374.899682 -231.39019)
		(width 0.0889)
		(layer "B.Cu")
		(net "TP_JTAG_CPU0_PLD_TMS")
	)
	(arc
		(start 370.56695 -231.385364)
		(mid 370.383188 -231.339964)
		(end 370.200682 -231.39019)
		(width 0.0889)
		(layer "B.Cu")
		(net "TP_JTAG_CPU0_PLD_TMS")
	)
	(arc
		(start 373.00535 -231.398826)
		(mid 372.728909 -231.465992)
		(end 372.454678 -231.39019)
		(width 0.0889)
		(layer "B.Cu")
		(net "TP_JTAG_CPU0_PLD_TMS")
	)
	(arc
		(start 375.82475 -231.398826)
		(mid 375.548309 -231.465992)
		(end 375.274078 -231.39019)
		(width 0.0889)
		(layer "B.Cu")
		(net "TP_JTAG_CPU0_PLD_TMS")
	)
	(arc
		(start 379.973078 -231.39019)
		(mid 379.78588 -231.340047)
		(end 379.598682 -231.39019)
		(width 0.0889)
		(layer "B.Cu")
		(net "TP_JTAG_CPU0_PLD_TMS")
	)
	(arc
		(start 370.200682 -231.39019)
		(mid 369.926453 -231.466115)
		(end 369.65001 -231.398826)
		(width 0.0889)
		(layer "B.Cu")
		(net "TP_JTAG_CPU0_PLD_TMS")
	)
	(arc
		(start 377.153932 -231.39019)
		(mid 376.966734 -231.340047)
		(end 376.779536 -231.39019)
		(width 0.0889)
		(layer "B.Cu")
		(net "TP_JTAG_CPU0_PLD_TMS")
	)
	(arc
		(start 371.514878 -231.39019)
		(mid 371.32768 -231.340047)
		(end 371.140482 -231.39019)
		(width 0.0889)
		(layer "B.Cu")
		(net "TP_JTAG_CPU0_PLD_TMS")
	)
	(arc
		(start 381.468122 -231.396286)
		(mid 381.18969 -231.4661)
		(end 380.912878 -231.39019)
		(width 0.0889)
		(layer "B.Cu")
		(net "TP_JTAG_CPU0_PLD_TMS")
	)
	(arc
		(start 371.130068 -231.396286)
		(mid 370.85189 -231.465978)
		(end 370.575332 -231.39019)
		(width 0.0889)
		(layer "B.Cu")
		(net "TP_JTAG_CPU0_PLD_TMS")
	)
	(arc
		(start 380.538482 -231.39019)
		(mid 380.25578 -231.465932)
		(end 379.973078 -231.39019)
		(width 0.0889)
		(layer "B.Cu")
		(net "TP_JTAG_CPU0_PLD_TMS")
	)
	(arc
		(start 381.852932 -231.39019)
		(mid 381.665734 -231.340047)
		(end 381.478536 -231.39019)
		(width 0.0889)
		(layer "B.Cu")
		(net "TP_JTAG_CPU0_PLD_TMS")
	)
	(arc
		(start 373.94515 -231.398826)
		(mid 373.668709 -231.465992)
		(end 373.394478 -231.39019)
		(width 0.0889)
		(layer "B.Cu")
		(net "TP_JTAG_CPU0_PLD_TMS")
	)
	(arc
		(start 378.093478 -231.39019)
		(mid 377.90628 -231.340047)
		(end 377.719082 -231.39019)
		(width 0.0889)
		(layer "B.Cu")
		(net "TP_JTAG_CPU0_PLD_TMS")
	)
	(arc
		(start 372.06555 -231.398826)
		(mid 371.789109 -231.465992)
		(end 371.514878 -231.39019)
		(width 0.0889)
		(layer "B.Cu")
		(net "TP_JTAG_CPU0_PLD_TMS")
	)
	(arc
		(start 384.297936 -231.39019)
		(mid 384.015234 -231.465932)
		(end 383.732532 -231.39019)
		(width 0.0889)
		(layer "B.Cu")
		(net "TP_JTAG_CPU0_PLD_TMS")
	)
	(arc
		(start 372.454678 -231.39019)
		(mid 372.26748 -231.340047)
		(end 372.080282 -231.39019)
		(width 0.0889)
		(layer "B.Cu")
		(net "TP_JTAG_CPU0_PLD_TMS")
	)
	(arc
		(start 376.213878 -231.39019)
		(mid 376.02668 -231.340047)
		(end 375.839482 -231.39019)
		(width 0.0889)
		(layer "B.Cu")
		(net "TP_JTAG_CPU0_PLD_TMS")
	)
	(segment
		(start 367.09858 -231.436418)
		(end 367.09858 -230.900732)
		(width 0.12954)
		(layer "F.Cu")
		(net "TP_JTAG_CPU0_PLD_TDO")
	)
	(segment
		(start 367.09858 -230.900732)
		(end 367.098834 -230.900478)
		(width 0.12954)
		(layer "F.Cu")
		(net "TP_JTAG_CPU0_PLD_TDO")
	)
	(via
		(at 367.098834 -230.900478)
		(size 0.4572)
		(drill 0.2032)
		(layers "F.Cu" "B.Cu")
		(net "TP_JTAG_CPU0_PLD_TDO")
	)
	(via
		(at 385.576318 -192.39357)
		(size 0.6604)
		(drill 0.3302)
		(layers "F.Cu" "B.Cu")
		(net "TP_JTAG_CPU0_PLD_TDO")
	)
	(segment
		(start 377.719082 -230.41102)
		(end 377.70435 -230.402384)
		(width 0.0889)
		(layer "B.Cu")
		(net "TP_JTAG_CPU0_PLD_TDO")
	)
	(segment
		(start 368.30635 -230.402384)
		(end 367.629694 -230.595678)
		(width 0.0889)
		(layer "B.Cu")
		(net "TP_JTAG_CPU0_PLD_TDO")
	)
	(segment
		(start 381.478536 -230.41102)
		(end 381.468122 -230.404924)
		(width 0.0889)
		(layer "B.Cu")
		(net "TP_JTAG_CPU0_PLD_TDO")
	)
	(segment
		(start 376.779282 -230.41102)
		(end 376.76455 -230.402384)
		(width 0.0889)
		(layer "B.Cu")
		(net "TP_JTAG_CPU0_PLD_TDO")
	)
	(segment
		(start 367.629694 -230.595678)
		(end 367.098834 -230.900478)
		(width 0.0889)
		(layer "B.Cu")
		(net "TP_JTAG_CPU0_PLD_TDO")
	)
	(segment
		(start 368.321082 -230.41102)
		(end 368.30635 -230.402384)
		(width 0.0889)
		(layer "B.Cu")
		(net "TP_JTAG_CPU0_PLD_TDO")
	)
	(segment
		(start 386.978144 -230.523288)
		(end 386.317236 -230.523288)
		(width 0.0889)
		(layer "B.Cu")
		(net "TP_JTAG_CPU0_PLD_TDO")
	)
	(segment
		(start 392.889994 -225.0694)
		(end 387.436106 -230.523288)
		(width 0.12954)
		(layer "B.Cu")
		(net "TP_JTAG_CPU0_PLD_TDO")
	)
	(segment
		(start 373.959882 -230.41102)
		(end 373.949468 -230.404924)
		(width 0.0889)
		(layer "B.Cu")
		(net "TP_JTAG_CPU0_PLD_TDO")
	)
	(segment
		(start 392.889994 -199.707246)
		(end 392.889994 -225.0694)
		(width 0.12954)
		(layer "B.Cu")
		(net "TP_JTAG_CPU0_PLD_TDO")
	)
	(segment
		(start 375.839482 -230.41102)
		(end 375.82475 -230.402384)
		(width 0.0889)
		(layer "B.Cu")
		(net "TP_JTAG_CPU0_PLD_TDO")
	)
	(segment
		(start 373.020336 -230.41102)
		(end 373.009922 -230.404924)
		(width 0.0889)
		(layer "B.Cu")
		(net "TP_JTAG_CPU0_PLD_TDO")
	)
	(segment
		(start 378.658882 -230.41102)
		(end 378.64415 -230.402384)
		(width 0.0889)
		(layer "B.Cu")
		(net "TP_JTAG_CPU0_PLD_TDO")
	)
	(segment
		(start 374.899682 -230.41102)
		(end 374.88495 -230.402384)
		(width 0.0889)
		(layer "B.Cu")
		(net "TP_JTAG_CPU0_PLD_TDO")
	)
	(segment
		(start 387.436106 -230.523288)
		(end 386.978144 -230.523288)
		(width 0.12954)
		(layer "B.Cu")
		(net "TP_JTAG_CPU0_PLD_TDO")
	)
	(segment
		(start 372.080282 -230.41102)
		(end 372.06555 -230.402384)
		(width 0.0889)
		(layer "B.Cu")
		(net "TP_JTAG_CPU0_PLD_TDO")
	)
	(segment
		(start 369.260882 -230.41102)
		(end 369.24615 -230.402384)
		(width 0.0889)
		(layer "B.Cu")
		(net "TP_JTAG_CPU0_PLD_TDO")
	)
	(segment
		(start 371.140482 -230.41102)
		(end 371.12575 -230.402384)
		(width 0.0889)
		(layer "B.Cu")
		(net "TP_JTAG_CPU0_PLD_TDO")
	)
	(segment
		(start 379.598936 -230.41102)
		(end 379.588522 -230.404924)
		(width 0.0889)
		(layer "B.Cu")
		(net "TP_JTAG_CPU0_PLD_TDO")
	)
	(segment
		(start 369.65001 -230.402384)
		(end 369.635278 -230.41102)
		(width 0.0889)
		(layer "B.Cu")
		(net "TP_JTAG_CPU0_PLD_TDO")
	)
	(segment
		(start 386.317236 -230.523288)
		(end 386.294376 -230.500174)
		(width 0.0889)
		(layer "B.Cu")
		(net "TP_JTAG_CPU0_PLD_TDO")
	)
	(segment
		(start 385.576318 -192.39357)
		(end 392.889994 -199.707246)
		(width 0.12954)
		(layer "B.Cu")
		(net "TP_JTAG_CPU0_PLD_TDO")
	)
	(segment
		(start 379.983746 -230.404924)
		(end 379.973332 -230.41102)
		(width 0.0889)
		(layer "B.Cu")
		(net "TP_JTAG_CPU0_PLD_TDO")
	)
	(arc
		(start 374.334278 -230.41102)
		(mid 374.14708 -230.461163)
		(end 373.959882 -230.41102)
		(width 0.0889)
		(layer "B.Cu")
		(net "TP_JTAG_CPU0_PLD_TDO")
	)
	(arc
		(start 376.213878 -230.41102)
		(mid 376.02668 -230.461163)
		(end 375.839482 -230.41102)
		(width 0.0889)
		(layer "B.Cu")
		(net "TP_JTAG_CPU0_PLD_TDO")
	)
	(arc
		(start 373.394732 -230.41102)
		(mid 373.207534 -230.461163)
		(end 373.020336 -230.41102)
		(width 0.0889)
		(layer "B.Cu")
		(net "TP_JTAG_CPU0_PLD_TDO")
	)
	(arc
		(start 382.418336 -230.41102)
		(mid 382.135634 -230.335244)
		(end 381.852932 -230.41102)
		(width 0.0889)
		(layer "B.Cu")
		(net "TP_JTAG_CPU0_PLD_TDO")
	)
	(arc
		(start 377.70435 -230.402384)
		(mid 377.427875 -230.335064)
		(end 377.153678 -230.41102)
		(width 0.0889)
		(layer "B.Cu")
		(net "TP_JTAG_CPU0_PLD_TDO")
	)
	(arc
		(start 383.732532 -230.41102)
		(mid 383.545334 -230.461163)
		(end 383.358136 -230.41102)
		(width 0.0889)
		(layer "B.Cu")
		(net "TP_JTAG_CPU0_PLD_TDO")
	)
	(arc
		(start 378.093478 -230.41102)
		(mid 377.90628 -230.461163)
		(end 377.719082 -230.41102)
		(width 0.0889)
		(layer "B.Cu")
		(net "TP_JTAG_CPU0_PLD_TDO")
	)
	(arc
		(start 379.973332 -230.41102)
		(mid 379.786134 -230.461163)
		(end 379.598936 -230.41102)
		(width 0.0889)
		(layer "B.Cu")
		(net "TP_JTAG_CPU0_PLD_TDO")
	)
	(arc
		(start 369.24615 -230.402384)
		(mid 368.969675 -230.335064)
		(end 368.695478 -230.41102)
		(width 0.0889)
		(layer "B.Cu")
		(net "TP_JTAG_CPU0_PLD_TDO")
	)
	(arc
		(start 385.612132 -230.41102)
		(mid 385.424934 -230.461163)
		(end 385.237736 -230.41102)
		(width 0.0889)
		(layer "B.Cu")
		(net "TP_JTAG_CPU0_PLD_TDO")
	)
	(arc
		(start 369.635278 -230.41102)
		(mid 369.44808 -230.461163)
		(end 369.260882 -230.41102)
		(width 0.0889)
		(layer "B.Cu")
		(net "TP_JTAG_CPU0_PLD_TDO")
	)
	(arc
		(start 372.454678 -230.41102)
		(mid 372.26748 -230.461163)
		(end 372.080282 -230.41102)
		(width 0.0889)
		(layer "B.Cu")
		(net "TP_JTAG_CPU0_PLD_TDO")
	)
	(arc
		(start 374.88495 -230.402384)
		(mid 374.608475 -230.335064)
		(end 374.334278 -230.41102)
		(width 0.0889)
		(layer "B.Cu")
		(net "TP_JTAG_CPU0_PLD_TDO")
	)
	(arc
		(start 370.200682 -230.41102)
		(mid 369.926483 -230.335185)
		(end 369.65001 -230.402384)
		(width 0.0889)
		(layer "B.Cu")
		(net "TP_JTAG_CPU0_PLD_TDO")
	)
	(arc
		(start 378.64415 -230.402384)
		(mid 378.367675 -230.335064)
		(end 378.093478 -230.41102)
		(width 0.0889)
		(layer "B.Cu")
		(net "TP_JTAG_CPU0_PLD_TDO")
	)
	(arc
		(start 384.672332 -230.41102)
		(mid 384.485134 -230.461163)
		(end 384.297936 -230.41102)
		(width 0.0889)
		(layer "B.Cu")
		(net "TP_JTAG_CPU0_PLD_TDO")
	)
	(arc
		(start 385.237736 -230.41102)
		(mid 384.955034 -230.335244)
		(end 384.672332 -230.41102)
		(width 0.0889)
		(layer "B.Cu")
		(net "TP_JTAG_CPU0_PLD_TDO")
	)
	(arc
		(start 371.12575 -230.402384)
		(mid 370.849275 -230.335064)
		(end 370.575078 -230.41102)
		(width 0.0889)
		(layer "B.Cu")
		(net "TP_JTAG_CPU0_PLD_TDO")
	)
	(arc
		(start 376.76455 -230.402384)
		(mid 376.488075 -230.335064)
		(end 376.213878 -230.41102)
		(width 0.0889)
		(layer "B.Cu")
		(net "TP_JTAG_CPU0_PLD_TDO")
	)
	(arc
		(start 386.177536 -230.41102)
		(mid 385.894834 -230.335244)
		(end 385.612132 -230.41102)
		(width 0.0889)
		(layer "B.Cu")
		(net "TP_JTAG_CPU0_PLD_TDO")
	)
	(arc
		(start 373.949468 -230.404924)
		(mid 373.67129 -230.335201)
		(end 373.394732 -230.41102)
		(width 0.0889)
		(layer "B.Cu")
		(net "TP_JTAG_CPU0_PLD_TDO")
	)
	(arc
		(start 371.514878 -230.41102)
		(mid 371.32768 -230.461163)
		(end 371.140482 -230.41102)
		(width 0.0889)
		(layer "B.Cu")
		(net "TP_JTAG_CPU0_PLD_TDO")
	)
	(arc
		(start 379.588522 -230.404924)
		(mid 379.31009 -230.335078)
		(end 379.033278 -230.41102)
		(width 0.0889)
		(layer "B.Cu")
		(net "TP_JTAG_CPU0_PLD_TDO")
	)
	(arc
		(start 377.153678 -230.41102)
		(mid 376.96648 -230.461163)
		(end 376.779282 -230.41102)
		(width 0.0889)
		(layer "B.Cu")
		(net "TP_JTAG_CPU0_PLD_TDO")
	)
	(arc
		(start 386.241544 -230.453946)
		(mid 386.210272 -230.431391)
		(end 386.177536 -230.41102)
		(width 0.0889)
		(layer "B.Cu")
		(net "TP_JTAG_CPU0_PLD_TDO")
	)
	(arc
		(start 382.792732 -230.41102)
		(mid 382.605534 -230.461163)
		(end 382.418336 -230.41102)
		(width 0.0889)
		(layer "B.Cu")
		(net "TP_JTAG_CPU0_PLD_TDO")
	)
	(arc
		(start 383.358136 -230.41102)
		(mid 383.075434 -230.335244)
		(end 382.792732 -230.41102)
		(width 0.0889)
		(layer "B.Cu")
		(net "TP_JTAG_CPU0_PLD_TDO")
	)
	(arc
		(start 381.852932 -230.41102)
		(mid 381.665734 -230.461163)
		(end 381.478536 -230.41102)
		(width 0.0889)
		(layer "B.Cu")
		(net "TP_JTAG_CPU0_PLD_TDO")
	)
	(arc
		(start 381.468122 -230.404924)
		(mid 381.18969 -230.335078)
		(end 380.912878 -230.41102)
		(width 0.0889)
		(layer "B.Cu")
		(net "TP_JTAG_CPU0_PLD_TDO")
	)
	(arc
		(start 386.294376 -230.500174)
		(mid 386.268678 -230.47624)
		(end 386.241544 -230.453946)
		(width 0.0889)
		(layer "B.Cu")
		(net "TP_JTAG_CPU0_PLD_TDO")
	)
	(arc
		(start 370.575078 -230.41102)
		(mid 370.38788 -230.461163)
		(end 370.200682 -230.41102)
		(width 0.0889)
		(layer "B.Cu")
		(net "TP_JTAG_CPU0_PLD_TDO")
	)
	(arc
		(start 380.912878 -230.41102)
		(mid 380.72568 -230.461163)
		(end 380.538482 -230.41102)
		(width 0.0889)
		(layer "B.Cu")
		(net "TP_JTAG_CPU0_PLD_TDO")
	)
	(arc
		(start 380.538482 -230.41102)
		(mid 380.261923 -230.335277)
		(end 379.983746 -230.404924)
		(width 0.0889)
		(layer "B.Cu")
		(net "TP_JTAG_CPU0_PLD_TDO")
	)
	(arc
		(start 372.06555 -230.402384)
		(mid 371.789075 -230.335064)
		(end 371.514878 -230.41102)
		(width 0.0889)
		(layer "B.Cu")
		(net "TP_JTAG_CPU0_PLD_TDO")
	)
	(arc
		(start 375.82475 -230.402384)
		(mid 375.548275 -230.335064)
		(end 375.274078 -230.41102)
		(width 0.0889)
		(layer "B.Cu")
		(net "TP_JTAG_CPU0_PLD_TDO")
	)
	(arc
		(start 368.695478 -230.41102)
		(mid 368.50828 -230.461163)
		(end 368.321082 -230.41102)
		(width 0.0889)
		(layer "B.Cu")
		(net "TP_JTAG_CPU0_PLD_TDO")
	)
	(arc
		(start 384.297936 -230.41102)
		(mid 384.015234 -230.335244)
		(end 383.732532 -230.41102)
		(width 0.0889)
		(layer "B.Cu")
		(net "TP_JTAG_CPU0_PLD_TDO")
	)
	(arc
		(start 379.033278 -230.41102)
		(mid 378.84608 -230.461163)
		(end 378.658882 -230.41102)
		(width 0.0889)
		(layer "B.Cu")
		(net "TP_JTAG_CPU0_PLD_TDO")
	)
	(arc
		(start 375.274078 -230.41102)
		(mid 375.08688 -230.461163)
		(end 374.899682 -230.41102)
		(width 0.0889)
		(layer "B.Cu")
		(net "TP_JTAG_CPU0_PLD_TDO")
	)
	(arc
		(start 373.009922 -230.404924)
		(mid 372.73149 -230.335078)
		(end 372.454678 -230.41102)
		(width 0.0889)
		(layer "B.Cu")
		(net "TP_JTAG_CPU0_PLD_TDO")
	)
	(segment
		(start 368.03838 -231.436418)
		(end 368.03838 -230.900732)
		(width 0.12954)
		(layer "F.Cu")
		(net "TP_JTAG_CPU0_PLD_TDI")
	)
	(segment
		(start 368.03838 -230.900732)
		(end 368.038634 -230.900478)
		(width 0.12954)
		(layer "F.Cu")
		(net "TP_JTAG_CPU0_PLD_TDI")
	)
	(via
		(at 368.038634 -230.900478)
		(size 0.4572)
		(drill 0.2032)
		(layers "F.Cu" "B.Cu")
		(net "TP_JTAG_CPU0_PLD_TDI")
	)
	(via
		(at 386.892038 -192.79743)
		(size 0.6604)
		(drill 0.3302)
		(layers "F.Cu" "B.Cu")
		(net "TP_JTAG_CPU0_PLD_TDI")
	)
	(segment
		(start 368.609118 -230.642922)
		(end 368.038634 -230.900478)
		(width 0.0889)
		(layer "B.Cu")
		(net "TP_JTAG_CPU0_PLD_TDI")
	)
	(segment
		(start 393.171934 -199.557386)
		(end 393.171934 -225.344228)
		(width 0.12954)
		(layer "B.Cu")
		(net "TP_JTAG_CPU0_PLD_TDI")
	)
	(segment
		(start 369.730528 -230.57612)
		(end 369.715796 -230.584756)
		(width 0.0889)
		(layer "B.Cu")
		(net "TP_JTAG_CPU0_PLD_TDI")
	)
	(segment
		(start 369.176046 -230.582216)
		(end 369.165632 -230.57612)
		(width 0.0889)
		(layer "B.Cu")
		(net "TP_JTAG_CPU0_PLD_TDI")
	)
	(segment
		(start 373.879364 -230.584756)
		(end 373.864632 -230.57612)
		(width 0.0889)
		(layer "B.Cu")
		(net "TP_JTAG_CPU0_PLD_TDI")
	)
	(segment
		(start 386.836412 -230.836216)
		(end 386.71373 -230.713534)
		(width 0.0889)
		(layer "B.Cu")
		(net "TP_JTAG_CPU0_PLD_TDI")
	)
	(segment
		(start 380.068582 -230.57612)
		(end 380.058168 -230.582216)
		(width 0.0889)
		(layer "B.Cu")
		(net "TP_JTAG_CPU0_PLD_TDI")
	)
	(segment
		(start 369.715796 -230.584756)
		(end 369.730782 -230.57612)
		(width 0.0889)
		(layer "B.Cu")
		(net "TP_JTAG_CPU0_PLD_TDI")
	)
	(segment
		(start 386.238242 -230.713534)
		(end 386.16001 -230.635302)
		(width 0.0889)
		(layer "B.Cu")
		(net "TP_JTAG_CPU0_PLD_TDI")
	)
	(segment
		(start 393.171934 -225.344228)
		(end 387.679946 -230.836216)
		(width 0.12954)
		(layer "B.Cu")
		(net "TP_JTAG_CPU0_PLD_TDI")
	)
	(segment
		(start 387.056122 -230.836216)
		(end 386.836412 -230.836216)
		(width 0.0889)
		(layer "B.Cu")
		(net "TP_JTAG_CPU0_PLD_TDI")
	)
	(segment
		(start 375.758964 -230.584756)
		(end 375.744232 -230.57612)
		(width 0.0889)
		(layer "B.Cu")
		(net "TP_JTAG_CPU0_PLD_TDI")
	)
	(segment
		(start 386.892038 -192.79743)
		(end 386.892038 -193.27749)
		(width 0.12954)
		(layer "B.Cu")
		(net "TP_JTAG_CPU0_PLD_TDI")
	)
	(segment
		(start 386.71373 -230.713534)
		(end 386.238242 -230.713534)
		(width 0.0889)
		(layer "B.Cu")
		(net "TP_JTAG_CPU0_PLD_TDI")
	)
	(segment
		(start 378.578364 -230.584756)
		(end 378.563632 -230.57612)
		(width 0.0889)
		(layer "B.Cu")
		(net "TP_JTAG_CPU0_PLD_TDI")
	)
	(segment
		(start 380.453392 -230.582216)
		(end 380.442978 -230.57612)
		(width 0.0889)
		(layer "B.Cu")
		(net "TP_JTAG_CPU0_PLD_TDI")
	)
	(segment
		(start 387.679946 -230.836216)
		(end 387.056122 -230.836216)
		(width 0.12954)
		(layer "B.Cu")
		(net "TP_JTAG_CPU0_PLD_TDI")
	)
	(segment
		(start 386.892038 -193.27749)
		(end 393.171934 -199.557386)
		(width 0.12954)
		(layer "B.Cu")
		(net "TP_JTAG_CPU0_PLD_TDI")
	)
	(segment
		(start 371.999764 -230.584756)
		(end 371.985032 -230.57612)
		(width 0.0889)
		(layer "B.Cu")
		(net "TP_JTAG_CPU0_PLD_TDI")
	)
	(segment
		(start 377.638564 -230.584756)
		(end 377.623832 -230.57612)
		(width 0.0889)
		(layer "B.Cu")
		(net "TP_JTAG_CPU0_PLD_TDI")
	)
	(segment
		(start 371.059964 -230.584756)
		(end 371.045232 -230.57612)
		(width 0.0889)
		(layer "B.Cu")
		(net "TP_JTAG_CPU0_PLD_TDI")
	)
	(segment
		(start 374.819164 -230.584756)
		(end 374.804432 -230.57612)
		(width 0.0889)
		(layer "B.Cu")
		(net "TP_JTAG_CPU0_PLD_TDI")
	)
	(segment
		(start 376.698764 -230.584756)
		(end 376.684032 -230.57612)
		(width 0.0889)
		(layer "B.Cu")
		(net "TP_JTAG_CPU0_PLD_TDI")
	)
	(arc
		(start 380.442978 -230.57612)
		(mid 380.25578 -230.525977)
		(end 380.068582 -230.57612)
		(width 0.0889)
		(layer "B.Cu")
		(net "TP_JTAG_CPU0_PLD_TDI")
	)
	(arc
		(start 369.730782 -230.57612)
		(mid 369.454223 -230.651863)
		(end 369.176046 -230.582216)
		(width 0.0889)
		(layer "B.Cu")
		(net "TP_JTAG_CPU0_PLD_TDI")
	)
	(arc
		(start 384.767836 -230.57612)
		(mid 384.485134 -230.651896)
		(end 384.202432 -230.57612)
		(width 0.0889)
		(layer "B.Cu")
		(net "TP_JTAG_CPU0_PLD_TDI")
	)
	(arc
		(start 374.430036 -230.57612)
		(mid 374.155837 -230.651955)
		(end 373.879364 -230.584756)
		(width 0.0889)
		(layer "B.Cu")
		(net "TP_JTAG_CPU0_PLD_TDI")
	)
	(arc
		(start 371.985032 -230.57612)
		(mid 371.797834 -230.525977)
		(end 371.610636 -230.57612)
		(width 0.0889)
		(layer "B.Cu")
		(net "TP_JTAG_CPU0_PLD_TDI")
	)
	(arc
		(start 384.202432 -230.57612)
		(mid 384.015234 -230.525977)
		(end 383.828036 -230.57612)
		(width 0.0889)
		(layer "B.Cu")
		(net "TP_JTAG_CPU0_PLD_TDI")
	)
	(arc
		(start 385.707636 -230.57612)
		(mid 385.424934 -230.651896)
		(end 385.142232 -230.57612)
		(width 0.0889)
		(layer "B.Cu")
		(net "TP_JTAG_CPU0_PLD_TDI")
	)
	(arc
		(start 383.828036 -230.57612)
		(mid 383.545334 -230.651896)
		(end 383.262632 -230.57612)
		(width 0.0889)
		(layer "B.Cu")
		(net "TP_JTAG_CPU0_PLD_TDI")
	)
	(arc
		(start 374.804432 -230.57612)
		(mid 374.617234 -230.525977)
		(end 374.430036 -230.57612)
		(width 0.0889)
		(layer "B.Cu")
		(net "TP_JTAG_CPU0_PLD_TDI")
	)
	(arc
		(start 377.249436 -230.57612)
		(mid 376.975237 -230.651955)
		(end 376.698764 -230.584756)
		(width 0.0889)
		(layer "B.Cu")
		(net "TP_JTAG_CPU0_PLD_TDI")
	)
	(arc
		(start 373.864632 -230.57612)
		(mid 373.677434 -230.525977)
		(end 373.490236 -230.57612)
		(width 0.0889)
		(layer "B.Cu")
		(net "TP_JTAG_CPU0_PLD_TDI")
	)
	(arc
		(start 373.490236 -230.57612)
		(mid 373.207534 -230.651896)
		(end 372.924832 -230.57612)
		(width 0.0889)
		(layer "B.Cu")
		(net "TP_JTAG_CPU0_PLD_TDI")
	)
	(arc
		(start 381.948436 -230.57612)
		(mid 381.665734 -230.651896)
		(end 381.383032 -230.57612)
		(width 0.0889)
		(layer "B.Cu")
		(net "TP_JTAG_CPU0_PLD_TDI")
	)
	(arc
		(start 371.610636 -230.57612)
		(mid 371.336437 -230.651955)
		(end 371.059964 -230.584756)
		(width 0.0889)
		(layer "B.Cu")
		(net "TP_JTAG_CPU0_PLD_TDI")
	)
	(arc
		(start 371.045232 -230.57612)
		(mid 370.858034 -230.525977)
		(end 370.670836 -230.57612)
		(width 0.0889)
		(layer "B.Cu")
		(net "TP_JTAG_CPU0_PLD_TDI")
	)
	(arc
		(start 382.322832 -230.57612)
		(mid 382.135634 -230.525977)
		(end 381.948436 -230.57612)
		(width 0.0889)
		(layer "B.Cu")
		(net "TP_JTAG_CPU0_PLD_TDI")
	)
	(arc
		(start 370.104924 -230.57612)
		(mid 369.917726 -230.525977)
		(end 369.730528 -230.57612)
		(width 0.0889)
		(layer "B.Cu")
		(net "TP_JTAG_CPU0_PLD_TDI")
	)
	(arc
		(start 376.684032 -230.57612)
		(mid 376.496834 -230.525977)
		(end 376.309636 -230.57612)
		(width 0.0889)
		(layer "B.Cu")
		(net "TP_JTAG_CPU0_PLD_TDI")
	)
	(arc
		(start 383.262632 -230.57612)
		(mid 383.075434 -230.525977)
		(end 382.888236 -230.57612)
		(width 0.0889)
		(layer "B.Cu")
		(net "TP_JTAG_CPU0_PLD_TDI")
	)
	(arc
		(start 375.744232 -230.57612)
		(mid 375.557034 -230.525977)
		(end 375.369836 -230.57612)
		(width 0.0889)
		(layer "B.Cu")
		(net "TP_JTAG_CPU0_PLD_TDI")
	)
	(arc
		(start 378.563632 -230.57612)
		(mid 378.376434 -230.525977)
		(end 378.189236 -230.57612)
		(width 0.0889)
		(layer "B.Cu")
		(net "TP_JTAG_CPU0_PLD_TDI")
	)
	(arc
		(start 385.142232 -230.57612)
		(mid 384.955034 -230.525977)
		(end 384.767836 -230.57612)
		(width 0.0889)
		(layer "B.Cu")
		(net "TP_JTAG_CPU0_PLD_TDI")
	)
	(arc
		(start 386.16001 -230.635302)
		(mid 386.12296 -230.603156)
		(end 386.082032 -230.57612)
		(width 0.0889)
		(layer "B.Cu")
		(net "TP_JTAG_CPU0_PLD_TDI")
	)
	(arc
		(start 372.550436 -230.57612)
		(mid 372.276237 -230.651955)
		(end 371.999764 -230.584756)
		(width 0.0889)
		(layer "B.Cu")
		(net "TP_JTAG_CPU0_PLD_TDI")
	)
	(arc
		(start 379.503432 -230.57612)
		(mid 379.316234 -230.525977)
		(end 379.129036 -230.57612)
		(width 0.0889)
		(layer "B.Cu")
		(net "TP_JTAG_CPU0_PLD_TDI")
	)
	(arc
		(start 369.165632 -230.57612)
		(mid 368.978434 -230.525977)
		(end 368.791236 -230.57612)
		(width 0.0889)
		(layer "B.Cu")
		(net "TP_JTAG_CPU0_PLD_TDI")
	)
	(arc
		(start 378.189236 -230.57612)
		(mid 377.915037 -230.651955)
		(end 377.638564 -230.584756)
		(width 0.0889)
		(layer "B.Cu")
		(net "TP_JTAG_CPU0_PLD_TDI")
	)
	(arc
		(start 382.888236 -230.57612)
		(mid 382.605534 -230.651896)
		(end 382.322832 -230.57612)
		(width 0.0889)
		(layer "B.Cu")
		(net "TP_JTAG_CPU0_PLD_TDI")
	)
	(arc
		(start 368.791236 -230.57612)
		(mid 368.703068 -230.617408)
		(end 368.609118 -230.642922)
		(width 0.0889)
		(layer "B.Cu")
		(net "TP_JTAG_CPU0_PLD_TDI")
	)
	(arc
		(start 376.309636 -230.57612)
		(mid 376.035437 -230.651955)
		(end 375.758964 -230.584756)
		(width 0.0889)
		(layer "B.Cu")
		(net "TP_JTAG_CPU0_PLD_TDI")
	)
	(arc
		(start 381.383032 -230.57612)
		(mid 381.195834 -230.525977)
		(end 381.008636 -230.57612)
		(width 0.0889)
		(layer "B.Cu")
		(net "TP_JTAG_CPU0_PLD_TDI")
	)
	(arc
		(start 379.129036 -230.57612)
		(mid 378.854837 -230.651955)
		(end 378.578364 -230.584756)
		(width 0.0889)
		(layer "B.Cu")
		(net "TP_JTAG_CPU0_PLD_TDI")
	)
	(arc
		(start 386.082032 -230.57612)
		(mid 385.894834 -230.525977)
		(end 385.707636 -230.57612)
		(width 0.0889)
		(layer "B.Cu")
		(net "TP_JTAG_CPU0_PLD_TDI")
	)
	(arc
		(start 375.369836 -230.57612)
		(mid 375.095637 -230.651955)
		(end 374.819164 -230.584756)
		(width 0.0889)
		(layer "B.Cu")
		(net "TP_JTAG_CPU0_PLD_TDI")
	)
	(arc
		(start 380.058168 -230.582216)
		(mid 379.77999 -230.651939)
		(end 379.503432 -230.57612)
		(width 0.0889)
		(layer "B.Cu")
		(net "TP_JTAG_CPU0_PLD_TDI")
	)
	(arc
		(start 372.924832 -230.57612)
		(mid 372.737634 -230.525977)
		(end 372.550436 -230.57612)
		(width 0.0889)
		(layer "B.Cu")
		(net "TP_JTAG_CPU0_PLD_TDI")
	)
	(arc
		(start 370.670836 -230.57612)
		(mid 370.38788 -230.652023)
		(end 370.104924 -230.57612)
		(width 0.0889)
		(layer "B.Cu")
		(net "TP_JTAG_CPU0_PLD_TDI")
	)
	(arc
		(start 381.008636 -230.57612)
		(mid 380.731823 -230.65199)
		(end 380.453392 -230.582216)
		(width 0.0889)
		(layer "B.Cu")
		(net "TP_JTAG_CPU0_PLD_TDI")
	)
	(arc
		(start 377.623832 -230.57612)
		(mid 377.436634 -230.525977)
		(end 377.249436 -230.57612)
		(width 0.0889)
		(layer "B.Cu")
		(net "TP_JTAG_CPU0_PLD_TDI")
	)
	(segment
		(start 377.45416 -93.571568)
		(end 377.45416 -94.22003)
		(width 0.12954)
		(layer "F.Cu")
		(net "TP_JTAG_BMC_A2")
	)
	(segment
		(start 377.01855 -94.65564)
		(end 377.01855 -96.212152)
		(width 0.12954)
		(layer "F.Cu")
		(net "TP_JTAG_BMC_A2")
	)
	(segment
		(start 377.45416 -94.22003)
		(end 377.01855 -94.65564)
		(width 0.12954)
		(layer "F.Cu")
		(net "TP_JTAG_BMC_A2")
	)
	(via
		(at 377.45416 -93.571568)
		(size 0.508)
		(drill 0.254)
		(layers "F.Cu" "B.Cu")
		(net "TP_JTAG_BMC_A2")
	)
	(segment
		(start 379.675136 -95.043752)
		(end 379.304296 -95.043752)
		(width 0.12954)
		(layer "F.Cu")
		(net "TP_JTAG_BMC_A0")
	)
	(segment
		(start 378.968508 -95.37954)
		(end 378.968508 -96.212152)
		(width 0.12954)
		(layer "F.Cu")
		(net "TP_JTAG_BMC_A0")
	)
	(segment
		(start 379.304296 -95.043752)
		(end 378.968508 -95.37954)
		(width 0.12954)
		(layer "F.Cu")
		(net "TP_JTAG_BMC_A0")
	)
	(via
		(at 379.675136 -95.043752)
		(size 0.508)
		(drill 0.254)
		(layers "F.Cu" "B.Cu")
		(net "TP_JTAG_BMC_A0")
	)
	(segment
		(start 108.14812 -55.885588)
		(end 107.539536 -55.277004)
		(width 0.12954)
		(layer "F.Cu")
		(net "TP_JTAG_BMC_4B")
	)
	(segment
		(start 107.539536 -55.277004)
		(end 105.76941 -55.277004)
		(width 0.12954)
		(layer "F.Cu")
		(net "TP_JTAG_BMC_4B")
	)
	(via
		(at 108.14812 -55.885588)
		(size 0.762)
		(drill 0.381)
		(layers "F.Cu" "B.Cu")
		(net "TP_JTAG_BMC_4B")
	)
	(segment
		(start 98.18116 -56.728868)
		(end 98.983038 -55.92699)
		(width 0.12954)
		(layer "F.Cu")
		(net "TP_JTAG_BMC_1B")
	)
	(segment
		(start 98.983038 -55.92699)
		(end 99.92741 -55.92699)
		(width 0.12954)
		(layer "F.Cu")
		(net "TP_JTAG_BMC_1B")
	)
	(via
		(at 98.18116 -56.728868)
		(size 0.762)
		(drill 0.381)
		(layers "F.Cu" "B.Cu")
		(net "TP_JTAG_BMC_1B")
	)
	(segment
		(start 369.448334 -230.622602)
		(end 369.44808 -230.622348)
		(width 0.12954)
		(layer "F.Cu")
		(net "TP_IBL_SLPS5_CPU0_R_N")
	)
	(segment
		(start 369.44808 -230.622348)
		(end 369.44808 -230.086662)
		(width 0.12954)
		(layer "F.Cu")
		(net "TP_IBL_SLPS5_CPU0_R_N")
	)
	(via
		(at 369.44808 -230.086662)
		(size 0.4572)
		(drill 0.2032)
		(layers "F.Cu" "B.Cu")
		(net "TP_IBL_SLPS5_CPU0_R_N")
	)
	(segment
		(start 366.628934 -230.622602)
		(end 366.628934 -230.086916)
		(width 0.12954)
		(layer "F.Cu")
		(net "TP_IBL_SLPS4_CPU0_R_N")
	)
	(segment
		(start 366.628934 -230.086916)
		(end 366.62868 -230.086662)
		(width 0.12954)
		(layer "F.Cu")
		(net "TP_IBL_SLPS4_CPU0_R_N")
	)
	(via
		(at 366.62868 -230.086662)
		(size 0.4572)
		(drill 0.2032)
		(layers "F.Cu" "B.Cu")
		(net "TP_IBL_SLPS4_CPU0_R_N")
	)
	(segment
		(start 367.568734 -230.622602)
		(end 367.568734 -230.086916)
		(width 0.12954)
		(layer "F.Cu")
		(net "TP_IBL_SLPS3_CPU0_R_N")
	)
	(segment
		(start 367.568734 -230.086916)
		(end 367.56848 -230.086662)
		(width 0.12954)
		(layer "F.Cu")
		(net "TP_IBL_SLPS3_CPU0_R_N")
	)
	(via
		(at 367.56848 -230.086662)
		(size 0.4572)
		(drill 0.2032)
		(layers "F.Cu" "B.Cu")
		(net "TP_IBL_SLPS3_CPU0_R_N")
	)
	(segment
		(start 365.689134 -230.622602)
		(end 365.689134 -230.086916)
		(width 0.12954)
		(layer "F.Cu")
		(net "TP_IBL_PLT_RST_SYNC_N")
	)
	(segment
		(start 365.689134 -230.086916)
		(end 365.68888 -230.086662)
		(width 0.12954)
		(layer "F.Cu")
		(net "TP_IBL_PLT_RST_SYNC_N")
	)
	(via
		(at 365.68888 -230.086662)
		(size 0.4572)
		(drill 0.2032)
		(layers "F.Cu" "B.Cu")
		(net "TP_IBL_PLT_RST_SYNC_N")
	)
	(segment
		(start 364.749334 -230.086916)
		(end 364.74908 -230.086662)
		(width 0.12954)
		(layer "F.Cu")
		(net "TP_IBL_GRST_WARN_PLD_R_N")
	)
	(segment
		(start 364.749334 -230.622602)
		(end 364.749334 -230.086916)
		(width 0.12954)
		(layer "F.Cu")
		(net "TP_IBL_GRST_WARN_PLD_R_N")
	)
	(via
		(at 364.74908 -230.086662)
		(size 0.4572)
		(drill 0.2032)
		(layers "F.Cu" "B.Cu")
		(net "TP_IBL_GRST_WARN_PLD_R_N")
	)
	(via
		(at 385.817618 -226.31527)
		(size 0.6604)
		(drill 0.3302)
		(layers "F.Cu" "B.Cu")
		(net "TP_IBL_GRST_WARN_PLD_R_N")
	)
	(segment
		(start 374.899936 -226.506786)
		(end 374.889522 -226.512882)
		(width 0.0889)
		(layer "B.Cu")
		(net "TP_IBL_GRST_WARN_PLD_R_N")
	)
	(segment
		(start 366.25403 -228.45903)
		(end 366.25403 -228.474524)
		(width 0.0889)
		(layer "B.Cu")
		(net "TP_IBL_GRST_WARN_PLD_R_N")
	)
	(segment
		(start 385.128008 -226.31527)
		(end 384.516884 -226.31527)
		(width 0.0889)
		(layer "B.Cu")
		(net "TP_IBL_GRST_WARN_PLD_R_N")
	)
	(segment
		(start 369.261136 -226.506786)
		(end 369.250722 -226.512882)
		(width 0.0889)
		(layer "B.Cu")
		(net "TP_IBL_GRST_WARN_PLD_R_N")
	)
	(segment
		(start 373.020082 -226.506786)
		(end 373.009668 -226.512882)
		(width 0.0889)
		(layer "B.Cu")
		(net "TP_IBL_GRST_WARN_PLD_R_N")
	)
	(segment
		(start 365.15167 -230.086662)
		(end 364.74908 -230.086662)
		(width 0.0889)
		(layer "B.Cu")
		(net "TP_IBL_GRST_WARN_PLD_R_N")
	)
	(segment
		(start 385.817618 -226.31527)
		(end 385.128008 -226.31527)
		(width 0.12954)
		(layer "B.Cu")
		(net "TP_IBL_GRST_WARN_PLD_R_N")
	)
	(segment
		(start 382.418082 -226.506786)
		(end 382.407668 -226.512882)
		(width 0.0889)
		(layer "B.Cu")
		(net "TP_IBL_GRST_WARN_PLD_R_N")
	)
	(segment
		(start 366.911636 -227.320602)
		(end 366.902746 -227.325682)
		(width 0.0889)
		(layer "B.Cu")
		(net "TP_IBL_GRST_WARN_PLD_R_N")
	)
	(segment
		(start 365.507778 -229.758748)
		(end 365.501682 -229.762304)
		(width 0.0889)
		(layer "B.Cu")
		(net "TP_IBL_GRST_WARN_PLD_R_N")
	)
	(segment
		(start 373.959882 -226.506786)
		(end 373.94515 -226.515422)
		(width 0.0889)
		(layer "B.Cu")
		(net "TP_IBL_GRST_WARN_PLD_R_N")
	)
	(segment
		(start 366.724184 -227.64496)
		(end 366.724184 -227.659184)
		(width 0.0889)
		(layer "B.Cu")
		(net "TP_IBL_GRST_WARN_PLD_R_N")
	)
	(segment
		(start 372.080536 -226.506786)
		(end 372.070122 -226.512882)
		(width 0.0889)
		(layer "B.Cu")
		(net "TP_IBL_GRST_WARN_PLD_R_N")
	)
	(segment
		(start 371.140482 -226.506786)
		(end 371.12575 -226.515422)
		(width 0.0889)
		(layer "B.Cu")
		(net "TP_IBL_GRST_WARN_PLD_R_N")
	)
	(segment
		(start 380.538482 -226.506786)
		(end 380.52375 -226.515422)
		(width 0.0889)
		(layer "B.Cu")
		(net "TP_IBL_GRST_WARN_PLD_R_N")
	)
	(segment
		(start 378.659136 -226.506786)
		(end 378.648722 -226.512882)
		(width 0.0889)
		(layer "B.Cu")
		(net "TP_IBL_GRST_WARN_PLD_R_N")
	)
	(segment
		(start 379.598682 -226.506786)
		(end 379.588268 -226.512882)
		(width 0.0889)
		(layer "B.Cu")
		(net "TP_IBL_GRST_WARN_PLD_R_N")
	)
	(segment
		(start 383.358136 -226.506786)
		(end 383.347722 -226.512882)
		(width 0.0889)
		(layer "B.Cu")
		(net "TP_IBL_GRST_WARN_PLD_R_N")
	)
	(segment
		(start 370.200682 -226.506786)
		(end 370.190268 -226.512882)
		(width 0.0889)
		(layer "B.Cu")
		(net "TP_IBL_GRST_WARN_PLD_R_N")
	)
	(segment
		(start 365.332518 -229.971854)
		(end 365.264446 -230.039926)
		(width 0.0889)
		(layer "B.Cu")
		(net "TP_IBL_GRST_WARN_PLD_R_N")
	)
	(segment
		(start 377.719082 -226.506786)
		(end 377.70435 -226.515422)
		(width 0.0889)
		(layer "B.Cu")
		(net "TP_IBL_GRST_WARN_PLD_R_N")
	)
	(segment
		(start 365.264446 -230.039926)
		(end 365.15167 -230.086662)
		(width 0.0889)
		(layer "B.Cu")
		(net "TP_IBL_GRST_WARN_PLD_R_N")
	)
	(segment
		(start 376.779282 -226.506786)
		(end 376.768868 -226.512882)
		(width 0.0889)
		(layer "B.Cu")
		(net "TP_IBL_GRST_WARN_PLD_R_N")
	)
	(segment
		(start 381.478536 -226.506786)
		(end 381.468122 -226.512882)
		(width 0.0889)
		(layer "B.Cu")
		(net "TP_IBL_GRST_WARN_PLD_R_N")
	)
	(segment
		(start 365.971836 -228.948488)
		(end 365.962946 -228.953568)
		(width 0.0889)
		(layer "B.Cu")
		(net "TP_IBL_GRST_WARN_PLD_R_N")
	)
	(segment
		(start 366.917732 -227.317046)
		(end 366.911636 -227.320602)
		(width 0.0889)
		(layer "B.Cu")
		(net "TP_IBL_GRST_WARN_PLD_R_N")
	)
	(segment
		(start 384.516884 -226.31527)
		(end 384.41503 -226.417124)
		(width 0.0889)
		(layer "B.Cu")
		(net "TP_IBL_GRST_WARN_PLD_R_N")
	)
	(segment
		(start 367.381536 -226.506786)
		(end 367.372646 -226.511866)
		(width 0.0889)
		(layer "B.Cu")
		(net "TP_IBL_GRST_WARN_PLD_R_N")
	)
	(segment
		(start 366.441482 -228.134672)
		(end 366.432592 -228.139752)
		(width 0.0889)
		(layer "B.Cu")
		(net "TP_IBL_GRST_WARN_PLD_R_N")
	)
	(segment
		(start 368.321082 -226.506786)
		(end 368.310668 -226.512882)
		(width 0.0889)
		(layer "B.Cu")
		(net "TP_IBL_GRST_WARN_PLD_R_N")
	)
	(arc
		(start 382.407668 -226.512882)
		(mid 382.12949 -226.582605)
		(end 381.852932 -226.506786)
		(width 0.0889)
		(layer "B.Cu")
		(net "TP_IBL_GRST_WARN_PLD_R_N")
	)
	(arc
		(start 366.902746 -227.325682)
		(mid 366.771832 -227.462042)
		(end 366.724184 -227.64496)
		(width 0.0889)
		(layer "B.Cu")
		(net "TP_IBL_GRST_WARN_PLD_R_N")
	)
	(arc
		(start 381.852932 -226.506786)
		(mid 381.665734 -226.456643)
		(end 381.478536 -226.506786)
		(width 0.0889)
		(layer "B.Cu")
		(net "TP_IBL_GRST_WARN_PLD_R_N")
	)
	(arc
		(start 377.153678 -226.506786)
		(mid 376.96648 -226.456643)
		(end 376.779282 -226.506786)
		(width 0.0889)
		(layer "B.Cu")
		(net "TP_IBL_GRST_WARN_PLD_R_N")
	)
	(arc
		(start 370.190268 -226.512882)
		(mid 369.91209 -226.582605)
		(end 369.635532 -226.506786)
		(width 0.0889)
		(layer "B.Cu")
		(net "TP_IBL_GRST_WARN_PLD_R_N")
	)
	(arc
		(start 374.334278 -226.506786)
		(mid 374.14708 -226.456643)
		(end 373.959882 -226.506786)
		(width 0.0889)
		(layer "B.Cu")
		(net "TP_IBL_GRST_WARN_PLD_R_N")
	)
	(arc
		(start 367.372646 -226.511866)
		(mid 367.241732 -226.648226)
		(end 367.194084 -226.831144)
		(width 0.0889)
		(layer "B.Cu")
		(net "TP_IBL_GRST_WARN_PLD_R_N")
	)
	(arc
		(start 373.009668 -226.512882)
		(mid 372.73149 -226.582605)
		(end 372.454932 -226.506786)
		(width 0.0889)
		(layer "B.Cu")
		(net "TP_IBL_GRST_WARN_PLD_R_N")
	)
	(arc
		(start 373.394478 -226.506786)
		(mid 373.20728 -226.456643)
		(end 373.020082 -226.506786)
		(width 0.0889)
		(layer "B.Cu")
		(net "TP_IBL_GRST_WARN_PLD_R_N")
	)
	(arc
		(start 367.755932 -226.506786)
		(mid 367.568734 -226.456643)
		(end 367.381536 -226.506786)
		(width 0.0889)
		(layer "B.Cu")
		(net "TP_IBL_GRST_WARN_PLD_R_N")
	)
	(arc
		(start 367.194084 -226.831144)
		(mid 367.120168 -227.110646)
		(end 366.917732 -227.317046)
		(width 0.0889)
		(layer "B.Cu")
		(net "TP_IBL_GRST_WARN_PLD_R_N")
	)
	(arc
		(start 380.52375 -226.515422)
		(mid 380.247275 -226.582742)
		(end 379.973078 -226.506786)
		(width 0.0889)
		(layer "B.Cu")
		(net "TP_IBL_GRST_WARN_PLD_R_N")
	)
	(arc
		(start 368.695478 -226.506786)
		(mid 368.50828 -226.456643)
		(end 368.321082 -226.506786)
		(width 0.0889)
		(layer "B.Cu")
		(net "TP_IBL_GRST_WARN_PLD_R_N")
	)
	(arc
		(start 376.768868 -226.512882)
		(mid 376.49069 -226.582605)
		(end 376.214132 -226.506786)
		(width 0.0889)
		(layer "B.Cu")
		(net "TP_IBL_GRST_WARN_PLD_R_N")
	)
	(arc
		(start 371.12575 -226.515422)
		(mid 370.849275 -226.582742)
		(end 370.575078 -226.506786)
		(width 0.0889)
		(layer "B.Cu")
		(net "TP_IBL_GRST_WARN_PLD_R_N")
	)
	(arc
		(start 384.297936 -226.506786)
		(mid 384.015234 -226.582562)
		(end 383.732532 -226.506786)
		(width 0.0889)
		(layer "B.Cu")
		(net "TP_IBL_GRST_WARN_PLD_R_N")
	)
	(arc
		(start 379.973078 -226.506786)
		(mid 379.78588 -226.456643)
		(end 379.598682 -226.506786)
		(width 0.0889)
		(layer "B.Cu")
		(net "TP_IBL_GRST_WARN_PLD_R_N")
	)
	(arc
		(start 368.310668 -226.512882)
		(mid 368.03249 -226.582605)
		(end 367.755932 -226.506786)
		(width 0.0889)
		(layer "B.Cu")
		(net "TP_IBL_GRST_WARN_PLD_R_N")
	)
	(arc
		(start 374.889522 -226.512882)
		(mid 374.61109 -226.582728)
		(end 374.334278 -226.506786)
		(width 0.0889)
		(layer "B.Cu")
		(net "TP_IBL_GRST_WARN_PLD_R_N")
	)
	(arc
		(start 370.575078 -226.506786)
		(mid 370.38788 -226.456643)
		(end 370.200682 -226.506786)
		(width 0.0889)
		(layer "B.Cu")
		(net "TP_IBL_GRST_WARN_PLD_R_N")
	)
	(arc
		(start 371.514878 -226.506786)
		(mid 371.32768 -226.456643)
		(end 371.140482 -226.506786)
		(width 0.0889)
		(layer "B.Cu")
		(net "TP_IBL_GRST_WARN_PLD_R_N")
	)
	(arc
		(start 373.94515 -226.515422)
		(mid 373.668675 -226.582742)
		(end 373.394478 -226.506786)
		(width 0.0889)
		(layer "B.Cu")
		(net "TP_IBL_GRST_WARN_PLD_R_N")
	)
	(arc
		(start 382.792478 -226.506786)
		(mid 382.60528 -226.456643)
		(end 382.418082 -226.506786)
		(width 0.0889)
		(layer "B.Cu")
		(net "TP_IBL_GRST_WARN_PLD_R_N")
	)
	(arc
		(start 369.635532 -226.506786)
		(mid 369.448334 -226.456643)
		(end 369.261136 -226.506786)
		(width 0.0889)
		(layer "B.Cu")
		(net "TP_IBL_GRST_WARN_PLD_R_N")
	)
	(arc
		(start 366.432592 -228.139752)
		(mid 366.301678 -228.276112)
		(end 366.25403 -228.45903)
		(width 0.0889)
		(layer "B.Cu")
		(net "TP_IBL_GRST_WARN_PLD_R_N")
	)
	(arc
		(start 380.912878 -226.506786)
		(mid 380.72568 -226.456643)
		(end 380.538482 -226.506786)
		(width 0.0889)
		(layer "B.Cu")
		(net "TP_IBL_GRST_WARN_PLD_R_N")
	)
	(arc
		(start 366.25403 -228.474524)
		(mid 366.17466 -228.748258)
		(end 365.971836 -228.948488)
		(width 0.0889)
		(layer "B.Cu")
		(net "TP_IBL_GRST_WARN_PLD_R_N")
	)
	(arc
		(start 372.070122 -226.512882)
		(mid 371.79169 -226.582728)
		(end 371.514878 -226.506786)
		(width 0.0889)
		(layer "B.Cu")
		(net "TP_IBL_GRST_WARN_PLD_R_N")
	)
	(arc
		(start 383.732532 -226.506786)
		(mid 383.545334 -226.456643)
		(end 383.358136 -226.506786)
		(width 0.0889)
		(layer "B.Cu")
		(net "TP_IBL_GRST_WARN_PLD_R_N")
	)
	(arc
		(start 377.70435 -226.515422)
		(mid 377.427875 -226.582742)
		(end 377.153678 -226.506786)
		(width 0.0889)
		(layer "B.Cu")
		(net "TP_IBL_GRST_WARN_PLD_R_N")
	)
	(arc
		(start 375.274332 -226.506786)
		(mid 375.087134 -226.456643)
		(end 374.899936 -226.506786)
		(width 0.0889)
		(layer "B.Cu")
		(net "TP_IBL_GRST_WARN_PLD_R_N")
	)
	(arc
		(start 366.724184 -227.659184)
		(mid 366.644965 -227.933869)
		(end 366.441482 -228.134672)
		(width 0.0889)
		(layer "B.Cu")
		(net "TP_IBL_GRST_WARN_PLD_R_N")
	)
	(arc
		(start 378.093478 -226.506786)
		(mid 377.90628 -226.456643)
		(end 377.719082 -226.506786)
		(width 0.0889)
		(layer "B.Cu")
		(net "TP_IBL_GRST_WARN_PLD_R_N")
	)
	(arc
		(start 381.468122 -226.512882)
		(mid 381.18969 -226.582728)
		(end 380.912878 -226.506786)
		(width 0.0889)
		(layer "B.Cu")
		(net "TP_IBL_GRST_WARN_PLD_R_N")
	)
	(arc
		(start 378.648722 -226.512882)
		(mid 378.37029 -226.582728)
		(end 378.093478 -226.506786)
		(width 0.0889)
		(layer "B.Cu")
		(net "TP_IBL_GRST_WARN_PLD_R_N")
	)
	(arc
		(start 369.250722 -226.512882)
		(mid 368.97229 -226.582728)
		(end 368.695478 -226.506786)
		(width 0.0889)
		(layer "B.Cu")
		(net "TP_IBL_GRST_WARN_PLD_R_N")
	)
	(arc
		(start 376.214132 -226.506786)
		(mid 376.026934 -226.456643)
		(end 375.839736 -226.506786)
		(width 0.0889)
		(layer "B.Cu")
		(net "TP_IBL_GRST_WARN_PLD_R_N")
	)
	(arc
		(start 365.501682 -229.762304)
		(mid 365.397564 -229.85132)
		(end 365.332518 -229.971854)
		(width 0.0889)
		(layer "B.Cu")
		(net "TP_IBL_GRST_WARN_PLD_R_N")
	)
	(arc
		(start 379.033532 -226.506786)
		(mid 378.846334 -226.456643)
		(end 378.659136 -226.506786)
		(width 0.0889)
		(layer "B.Cu")
		(net "TP_IBL_GRST_WARN_PLD_R_N")
	)
	(arc
		(start 365.962946 -228.953568)
		(mid 365.832032 -229.089928)
		(end 365.784384 -229.272846)
		(width 0.0889)
		(layer "B.Cu")
		(net "TP_IBL_GRST_WARN_PLD_R_N")
	)
	(arc
		(start 384.41503 -226.417124)
		(mid 384.359425 -226.465798)
		(end 384.297936 -226.506786)
		(width 0.0889)
		(layer "B.Cu")
		(net "TP_IBL_GRST_WARN_PLD_R_N")
	)
	(arc
		(start 375.839736 -226.506786)
		(mid 375.557034 -226.582562)
		(end 375.274332 -226.506786)
		(width 0.0889)
		(layer "B.Cu")
		(net "TP_IBL_GRST_WARN_PLD_R_N")
	)
	(arc
		(start 379.588268 -226.512882)
		(mid 379.31009 -226.582605)
		(end 379.033532 -226.506786)
		(width 0.0889)
		(layer "B.Cu")
		(net "TP_IBL_GRST_WARN_PLD_R_N")
	)
	(arc
		(start 372.454932 -226.506786)
		(mid 372.267734 -226.456643)
		(end 372.080536 -226.506786)
		(width 0.0889)
		(layer "B.Cu")
		(net "TP_IBL_GRST_WARN_PLD_R_N")
	)
	(arc
		(start 365.784384 -229.272846)
		(mid 365.710393 -229.552412)
		(end 365.507778 -229.758748)
		(width 0.0889)
		(layer "B.Cu")
		(net "TP_IBL_GRST_WARN_PLD_R_N")
	)
	(arc
		(start 383.347722 -226.512882)
		(mid 383.06929 -226.582728)
		(end 382.792478 -226.506786)
		(width 0.0889)
		(layer "B.Cu")
		(net "TP_IBL_GRST_WARN_PLD_R_N")
	)
	(segment
		(start 104.591866 -233.34218)
		(end 104.591866 -233.87812)
		(width 0.12954)
		(layer "F.Cu")
		(net "TP_I3C_MNG3_BMC_SW_SDA")
	)
	(via
		(at 104.591866 -233.34218)
		(size 0.4572)
		(drill 0.2032)
		(layers "F.Cu" "B.Cu")
		(net "TP_I3C_MNG3_BMC_SW_SDA")
	)
	(segment
		(start 105.531666 -233.34218)
		(end 105.531666 -233.87812)
		(width 0.12954)
		(layer "F.Cu")
		(net "TP_I3C_MNG3_BMC_SW_SCL")
	)
	(via
		(at 105.531666 -233.34218)
		(size 0.4572)
		(drill 0.2032)
		(layers "F.Cu" "B.Cu")
		(net "TP_I3C_MNG3_BMC_SW_SCL")
	)
	(segment
		(start 352.531934 -233.34218)
		(end 352.531934 -233.87812)
		(width 0.12954)
		(layer "F.Cu")
		(net "TP_I3C_MNG2_BMC_SW_SDA")
	)
	(via
		(at 352.531934 -233.34218)
		(size 0.4572)
		(drill 0.2032)
		(layers "F.Cu" "B.Cu")
		(net "TP_I3C_MNG2_BMC_SW_SDA")
	)
	(segment
		(start 353.471734 -233.34218)
		(end 353.471734 -233.87812)
		(width 0.12954)
		(layer "F.Cu")
		(net "TP_I3C_MNG2_BMC_SW_SCL")
	)
	(via
		(at 353.471734 -233.34218)
		(size 0.4572)
		(drill 0.2032)
		(layers "F.Cu" "B.Cu")
		(net "TP_I3C_MNG2_BMC_SW_SCL")
	)
	(segment
		(start 116.809012 -232.250234)
		(end 116.809012 -231.714548)
		(width 0.12954)
		(layer "F.Cu")
		(net "TP_I2C_S3M_RTC_CPU1_SDA")
	)
	(segment
		(start 116.809266 -232.250488)
		(end 116.809012 -232.250234)
		(width 0.12954)
		(layer "F.Cu")
		(net "TP_I2C_S3M_RTC_CPU1_SDA")
	)
	(via
		(at 116.809012 -231.714548)
		(size 0.4572)
		(drill 0.2032)
		(layers "F.Cu" "B.Cu")
		(net "TP_I2C_S3M_RTC_CPU1_SDA")
	)
	(via
		(at 145.797778 -231.48417)
		(size 0.6604)
		(drill 0.3302)
		(layers "F.Cu" "B.Cu")
		(net "TP_I2C_S3M_RTC_CPU1_SDA")
	)
	(segment
		(start 126.019814 -232.038906)
		(end 126.005082 -232.03027)
		(width 0.0889)
		(layer "B.Cu")
		(net "TP_I2C_S3M_RTC_CPU1_SDA")
	)
	(segment
		(start 125.080014 -232.038906)
		(end 125.065282 -232.03027)
		(width 0.0889)
		(layer "B.Cu")
		(net "TP_I2C_S3M_RTC_CPU1_SDA")
	)
	(segment
		(start 139.628118 -232.22077)
		(end 138.558778 -232.22077)
		(width 0.12954)
		(layer "B.Cu")
		(net "TP_I2C_S3M_RTC_CPU1_SDA")
	)
	(segment
		(start 127.899414 -232.038906)
		(end 127.884682 -232.03027)
		(width 0.0889)
		(layer "B.Cu")
		(net "TP_I2C_S3M_RTC_CPU1_SDA")
	)
	(segment
		(start 140.08354 -231.765348)
		(end 139.628118 -232.22077)
		(width 0.12954)
		(layer "B.Cu")
		(net "TP_I2C_S3M_RTC_CPU1_SDA")
	)
	(segment
		(start 145.797778 -231.48417)
		(end 145.5166 -231.765348)
		(width 0.12954)
		(layer "B.Cu")
		(net "TP_I2C_S3M_RTC_CPU1_SDA")
	)
	(segment
		(start 128.839468 -232.038906)
		(end 128.829054 -232.03281)
		(width 0.0889)
		(layer "B.Cu")
		(net "TP_I2C_S3M_RTC_CPU1_SDA")
	)
	(segment
		(start 145.5166 -231.765348)
		(end 140.08354 -231.765348)
		(width 0.12954)
		(layer "B.Cu")
		(net "TP_I2C_S3M_RTC_CPU1_SDA")
	)
	(segment
		(start 138.376914 -232.038906)
		(end 137.718038 -232.038906)
		(width 0.12954)
		(layer "B.Cu")
		(net "TP_I2C_S3M_RTC_CPU1_SDA")
	)
	(segment
		(start 117.05463 -232.009442)
		(end 116.965476 -231.985566)
		(width 0.0889)
		(layer "B.Cu")
		(net "TP_I2C_S3M_RTC_CPU1_SDA")
	)
	(segment
		(start 137.718038 -232.038906)
		(end 137.297668 -232.038906)
		(width 0.0889)
		(layer "B.Cu")
		(net "TP_I2C_S3M_RTC_CPU1_SDA")
	)
	(segment
		(start 124.140214 -232.038906)
		(end 124.125482 -232.03027)
		(width 0.0889)
		(layer "B.Cu")
		(net "TP_I2C_S3M_RTC_CPU1_SDA")
	)
	(segment
		(start 123.200414 -232.038906)
		(end 123.19 -232.03281)
		(width 0.0889)
		(layer "B.Cu")
		(net "TP_I2C_S3M_RTC_CPU1_SDA")
	)
	(segment
		(start 119.815864 -232.038906)
		(end 119.807482 -232.043732)
		(width 0.0889)
		(layer "B.Cu")
		(net "TP_I2C_S3M_RTC_CPU1_SDA")
	)
	(segment
		(start 121.706132 -232.03281)
		(end 121.695718 -232.038906)
		(width 0.0889)
		(layer "B.Cu")
		(net "TP_I2C_S3M_RTC_CPU1_SDA")
	)
	(segment
		(start 119.826278 -232.03281)
		(end 119.815864 -232.038906)
		(width 0.0889)
		(layer "B.Cu")
		(net "TP_I2C_S3M_RTC_CPU1_SDA")
	)
	(segment
		(start 117.561614 -232.038906)
		(end 117.546882 -232.03027)
		(width 0.0889)
		(layer "B.Cu")
		(net "TP_I2C_S3M_RTC_CPU1_SDA")
	)
	(segment
		(start 131.658614 -232.038906)
		(end 131.643882 -232.03027)
		(width 0.0889)
		(layer "B.Cu")
		(net "TP_I2C_S3M_RTC_CPU1_SDA")
	)
	(segment
		(start 138.558778 -232.22077)
		(end 138.376914 -232.038906)
		(width 0.12954)
		(layer "B.Cu")
		(net "TP_I2C_S3M_RTC_CPU1_SDA")
	)
	(segment
		(start 116.965476 -231.985566)
		(end 116.809012 -231.714548)
		(width 0.0889)
		(layer "B.Cu")
		(net "TP_I2C_S3M_RTC_CPU1_SDA")
	)
	(segment
		(start 132.598414 -232.038906)
		(end 132.583682 -232.03027)
		(width 0.0889)
		(layer "B.Cu")
		(net "TP_I2C_S3M_RTC_CPU1_SDA")
	)
	(segment
		(start 129.779014 -232.038906)
		(end 129.7686 -232.03281)
		(width 0.0889)
		(layer "B.Cu")
		(net "TP_I2C_S3M_RTC_CPU1_SDA")
	)
	(segment
		(start 130.718814 -232.038906)
		(end 130.704082 -232.03027)
		(width 0.0889)
		(layer "B.Cu")
		(net "TP_I2C_S3M_RTC_CPU1_SDA")
	)
	(segment
		(start 132.983224 -232.03281)
		(end 132.97281 -232.038906)
		(width 0.0889)
		(layer "B.Cu")
		(net "TP_I2C_S3M_RTC_CPU1_SDA")
	)
	(segment
		(start 118.501414 -232.038906)
		(end 118.486682 -232.03027)
		(width 0.0889)
		(layer "B.Cu")
		(net "TP_I2C_S3M_RTC_CPU1_SDA")
	)
	(arc
		(start 125.065282 -232.03027)
		(mid 124.788807 -231.96295)
		(end 124.51461 -232.038906)
		(width 0.0889)
		(layer "B.Cu")
		(net "TP_I2C_S3M_RTC_CPU1_SDA")
	)
	(arc
		(start 127.884682 -232.03027)
		(mid 127.608207 -231.96295)
		(end 127.33401 -232.038906)
		(width 0.0889)
		(layer "B.Cu")
		(net "TP_I2C_S3M_RTC_CPU1_SDA")
	)
	(arc
		(start 118.486682 -232.03027)
		(mid 118.210207 -231.96295)
		(end 117.93601 -232.038906)
		(width 0.0889)
		(layer "B.Cu")
		(net "TP_I2C_S3M_RTC_CPU1_SDA")
	)
	(arc
		(start 137.297668 -232.038906)
		(mid 137.014966 -231.96313)
		(end 136.732264 -232.038906)
		(width 0.0889)
		(layer "B.Cu")
		(net "TP_I2C_S3M_RTC_CPU1_SDA")
	)
	(arc
		(start 130.704082 -232.03027)
		(mid 130.427607 -231.96295)
		(end 130.15341 -232.038906)
		(width 0.0889)
		(layer "B.Cu")
		(net "TP_I2C_S3M_RTC_CPU1_SDA")
	)
	(arc
		(start 130.15341 -232.038906)
		(mid 129.966212 -232.089049)
		(end 129.779014 -232.038906)
		(width 0.0889)
		(layer "B.Cu")
		(net "TP_I2C_S3M_RTC_CPU1_SDA")
	)
	(arc
		(start 128.27381 -232.038906)
		(mid 128.086612 -232.089049)
		(end 127.899414 -232.038906)
		(width 0.0889)
		(layer "B.Cu")
		(net "TP_I2C_S3M_RTC_CPU1_SDA")
	)
	(arc
		(start 118.87581 -232.038906)
		(mid 118.688612 -232.089049)
		(end 118.501414 -232.038906)
		(width 0.0889)
		(layer "B.Cu")
		(net "TP_I2C_S3M_RTC_CPU1_SDA")
	)
	(arc
		(start 122.635264 -232.038906)
		(mid 122.448066 -232.089049)
		(end 122.260868 -232.038906)
		(width 0.0889)
		(layer "B.Cu")
		(net "TP_I2C_S3M_RTC_CPU1_SDA")
	)
	(arc
		(start 123.19 -232.03281)
		(mid 122.911822 -231.963087)
		(end 122.635264 -232.038906)
		(width 0.0889)
		(layer "B.Cu")
		(net "TP_I2C_S3M_RTC_CPU1_SDA")
	)
	(arc
		(start 135.792464 -232.038906)
		(mid 135.605266 -232.089049)
		(end 135.418068 -232.038906)
		(width 0.0889)
		(layer "B.Cu")
		(net "TP_I2C_S3M_RTC_CPU1_SDA")
	)
	(arc
		(start 129.7686 -232.03281)
		(mid 129.490422 -231.963087)
		(end 129.213864 -232.038906)
		(width 0.0889)
		(layer "B.Cu")
		(net "TP_I2C_S3M_RTC_CPU1_SDA")
	)
	(arc
		(start 120.381014 -232.038906)
		(mid 120.104455 -231.963163)
		(end 119.826278 -232.03281)
		(width 0.0889)
		(layer "B.Cu")
		(net "TP_I2C_S3M_RTC_CPU1_SDA")
	)
	(arc
		(start 131.09321 -232.038906)
		(mid 130.906012 -232.089049)
		(end 130.718814 -232.038906)
		(width 0.0889)
		(layer "B.Cu")
		(net "TP_I2C_S3M_RTC_CPU1_SDA")
	)
	(arc
		(start 126.005082 -232.03027)
		(mid 125.728607 -231.96295)
		(end 125.45441 -232.038906)
		(width 0.0889)
		(layer "B.Cu")
		(net "TP_I2C_S3M_RTC_CPU1_SDA")
	)
	(arc
		(start 122.260868 -232.038906)
		(mid 121.984309 -231.963163)
		(end 121.706132 -232.03281)
		(width 0.0889)
		(layer "B.Cu")
		(net "TP_I2C_S3M_RTC_CPU1_SDA")
	)
	(arc
		(start 125.45441 -232.038906)
		(mid 125.267212 -232.089049)
		(end 125.080014 -232.038906)
		(width 0.0889)
		(layer "B.Cu")
		(net "TP_I2C_S3M_RTC_CPU1_SDA")
	)
	(arc
		(start 123.57481 -232.038906)
		(mid 123.387612 -232.089049)
		(end 123.200414 -232.038906)
		(width 0.0889)
		(layer "B.Cu")
		(net "TP_I2C_S3M_RTC_CPU1_SDA")
	)
	(arc
		(start 121.695718 -232.038906)
		(mid 121.50852 -232.089049)
		(end 121.321322 -232.038906)
		(width 0.0889)
		(layer "B.Cu")
		(net "TP_I2C_S3M_RTC_CPU1_SDA")
	)
	(arc
		(start 119.441722 -232.038906)
		(mid 119.158766 -231.963003)
		(end 118.87581 -232.038906)
		(width 0.0889)
		(layer "B.Cu")
		(net "TP_I2C_S3M_RTC_CPU1_SDA")
	)
	(arc
		(start 128.829054 -232.03281)
		(mid 128.550622 -231.962964)
		(end 128.27381 -232.038906)
		(width 0.0889)
		(layer "B.Cu")
		(net "TP_I2C_S3M_RTC_CPU1_SDA")
	)
	(arc
		(start 126.959614 -232.038906)
		(mid 126.676912 -231.96313)
		(end 126.39421 -232.038906)
		(width 0.0889)
		(layer "B.Cu")
		(net "TP_I2C_S3M_RTC_CPU1_SDA")
	)
	(arc
		(start 134.852664 -232.038906)
		(mid 134.665466 -232.089049)
		(end 134.478268 -232.038906)
		(width 0.0889)
		(layer "B.Cu")
		(net "TP_I2C_S3M_RTC_CPU1_SDA")
	)
	(arc
		(start 119.807482 -232.043732)
		(mid 119.623974 -232.08901)
		(end 119.441722 -232.038906)
		(width 0.0889)
		(layer "B.Cu")
		(net "TP_I2C_S3M_RTC_CPU1_SDA")
	)
	(arc
		(start 133.538468 -232.038906)
		(mid 133.261655 -231.963036)
		(end 132.983224 -232.03281)
		(width 0.0889)
		(layer "B.Cu")
		(net "TP_I2C_S3M_RTC_CPU1_SDA")
	)
	(arc
		(start 121.321322 -232.038906)
		(mid 121.038366 -231.963003)
		(end 120.75541 -232.038906)
		(width 0.0889)
		(layer "B.Cu")
		(net "TP_I2C_S3M_RTC_CPU1_SDA")
	)
	(arc
		(start 131.643882 -232.03027)
		(mid 131.367407 -231.96295)
		(end 131.09321 -232.038906)
		(width 0.0889)
		(layer "B.Cu")
		(net "TP_I2C_S3M_RTC_CPU1_SDA")
	)
	(arc
		(start 134.478268 -232.038906)
		(mid 134.195566 -231.96313)
		(end 133.912864 -232.038906)
		(width 0.0889)
		(layer "B.Cu")
		(net "TP_I2C_S3M_RTC_CPU1_SDA")
	)
	(arc
		(start 124.51461 -232.038906)
		(mid 124.327412 -232.089049)
		(end 124.140214 -232.038906)
		(width 0.0889)
		(layer "B.Cu")
		(net "TP_I2C_S3M_RTC_CPU1_SDA")
	)
	(arc
		(start 136.732264 -232.038906)
		(mid 136.545066 -232.089049)
		(end 136.357868 -232.038906)
		(width 0.0889)
		(layer "B.Cu")
		(net "TP_I2C_S3M_RTC_CPU1_SDA")
	)
	(arc
		(start 127.33401 -232.038906)
		(mid 127.146812 -232.089049)
		(end 126.959614 -232.038906)
		(width 0.0889)
		(layer "B.Cu")
		(net "TP_I2C_S3M_RTC_CPU1_SDA")
	)
	(arc
		(start 136.357868 -232.038906)
		(mid 136.075166 -231.96313)
		(end 135.792464 -232.038906)
		(width 0.0889)
		(layer "B.Cu")
		(net "TP_I2C_S3M_RTC_CPU1_SDA")
	)
	(arc
		(start 124.125482 -232.03027)
		(mid 123.849007 -231.96295)
		(end 123.57481 -232.038906)
		(width 0.0889)
		(layer "B.Cu")
		(net "TP_I2C_S3M_RTC_CPU1_SDA")
	)
	(arc
		(start 117.546882 -232.03027)
		(mid 117.303138 -231.963391)
		(end 117.05463 -232.009442)
		(width 0.0889)
		(layer "B.Cu")
		(net "TP_I2C_S3M_RTC_CPU1_SDA")
	)
	(arc
		(start 135.418068 -232.038906)
		(mid 135.135366 -231.96313)
		(end 134.852664 -232.038906)
		(width 0.0889)
		(layer "B.Cu")
		(net "TP_I2C_S3M_RTC_CPU1_SDA")
	)
	(arc
		(start 129.213864 -232.038906)
		(mid 129.026666 -232.089049)
		(end 128.839468 -232.038906)
		(width 0.0889)
		(layer "B.Cu")
		(net "TP_I2C_S3M_RTC_CPU1_SDA")
	)
	(arc
		(start 133.912864 -232.038906)
		(mid 133.725666 -232.089049)
		(end 133.538468 -232.038906)
		(width 0.0889)
		(layer "B.Cu")
		(net "TP_I2C_S3M_RTC_CPU1_SDA")
	)
	(arc
		(start 132.97281 -232.038906)
		(mid 132.785612 -232.089049)
		(end 132.598414 -232.038906)
		(width 0.0889)
		(layer "B.Cu")
		(net "TP_I2C_S3M_RTC_CPU1_SDA")
	)
	(arc
		(start 117.93601 -232.038906)
		(mid 117.748812 -232.089049)
		(end 117.561614 -232.038906)
		(width 0.0889)
		(layer "B.Cu")
		(net "TP_I2C_S3M_RTC_CPU1_SDA")
	)
	(arc
		(start 132.583682 -232.03027)
		(mid 132.307207 -231.96295)
		(end 132.03301 -232.038906)
		(width 0.0889)
		(layer "B.Cu")
		(net "TP_I2C_S3M_RTC_CPU1_SDA")
	)
	(arc
		(start 132.03301 -232.038906)
		(mid 131.845812 -232.089049)
		(end 131.658614 -232.038906)
		(width 0.0889)
		(layer "B.Cu")
		(net "TP_I2C_S3M_RTC_CPU1_SDA")
	)
	(arc
		(start 126.39421 -232.038906)
		(mid 126.207012 -232.089049)
		(end 126.019814 -232.038906)
		(width 0.0889)
		(layer "B.Cu")
		(net "TP_I2C_S3M_RTC_CPU1_SDA")
	)
	(arc
		(start 120.75541 -232.038906)
		(mid 120.568212 -232.089049)
		(end 120.381014 -232.038906)
		(width 0.0889)
		(layer "B.Cu")
		(net "TP_I2C_S3M_RTC_CPU1_SDA")
	)
	(segment
		(start 117.749066 -232.250488)
		(end 117.748812 -232.250234)
		(width 0.12954)
		(layer "F.Cu")
		(net "TP_I2C_S3M_RTC_CPU1_SCL")
	)
	(segment
		(start 117.748812 -232.250234)
		(end 117.748812 -231.714548)
		(width 0.12954)
		(layer "F.Cu")
		(net "TP_I2C_S3M_RTC_CPU1_SCL")
	)
	(via
		(at 117.748812 -231.714548)
		(size 0.4572)
		(drill 0.2032)
		(layers "F.Cu" "B.Cu")
		(net "TP_I2C_S3M_RTC_CPU1_SCL")
	)
	(via
		(at 139.638278 -227.08235)
		(size 0.6604)
		(drill 0.3302)
		(layers "F.Cu" "B.Cu")
		(net "TP_I2C_S3M_RTC_CPU1_SCL")
	)
	(segment
		(start 139.638278 -227.08235)
		(end 138.243818 -227.08235)
		(width 0.12954)
		(layer "B.Cu")
		(net "TP_I2C_S3M_RTC_CPU1_SCL")
	)
	(segment
		(start 130.638296 -227.960682)
		(end 130.623564 -227.969318)
		(width 0.0889)
		(layer "B.Cu")
		(net "TP_I2C_S3M_RTC_CPU1_SCL")
	)
	(segment
		(start 136.666478 -227.76053)
		(end 136.280398 -227.76053)
		(width 0.0889)
		(layer "B.Cu")
		(net "TP_I2C_S3M_RTC_CPU1_SCL")
	)
	(segment
		(start 136.147302 -227.893626)
		(end 135.607298 -227.893626)
		(width 0.0889)
		(layer "B.Cu")
		(net "TP_I2C_S3M_RTC_CPU1_SCL")
	)
	(segment
		(start 129.698496 -227.960682)
		(end 129.683764 -227.969318)
		(width 0.0889)
		(layer "B.Cu")
		(net "TP_I2C_S3M_RTC_CPU1_SCL")
	)
	(segment
		(start 136.280398 -227.76053)
		(end 136.147302 -227.893626)
		(width 0.0889)
		(layer "B.Cu")
		(net "TP_I2C_S3M_RTC_CPU1_SCL")
	)
	(segment
		(start 122.175524 -227.963222)
		(end 122.16511 -227.969318)
		(width 0.0889)
		(layer "B.Cu")
		(net "TP_I2C_S3M_RTC_CPU1_SCL")
	)
	(segment
		(start 137.565638 -227.76053)
		(end 136.666478 -227.76053)
		(width 0.12954)
		(layer "B.Cu")
		(net "TP_I2C_S3M_RTC_CPU1_SCL")
	)
	(segment
		(start 120.300496 -227.960682)
		(end 120.285764 -227.969318)
		(width 0.0889)
		(layer "B.Cu")
		(net "TP_I2C_S3M_RTC_CPU1_SCL")
	)
	(segment
		(start 134.397496 -227.960682)
		(end 134.382764 -227.969318)
		(width 0.0889)
		(layer "B.Cu")
		(net "TP_I2C_S3M_RTC_CPU1_SCL")
	)
	(segment
		(start 117.781578 -230.80599)
		(end 117.748812 -231.714548)
		(width 0.0889)
		(layer "B.Cu")
		(net "TP_I2C_S3M_RTC_CPU1_SCL")
	)
	(segment
		(start 119.360696 -227.960682)
		(end 119.345964 -227.969318)
		(width 0.0889)
		(layer "B.Cu")
		(net "TP_I2C_S3M_RTC_CPU1_SCL")
	)
	(segment
		(start 131.578096 -227.960682)
		(end 131.563364 -227.969318)
		(width 0.0889)
		(layer "B.Cu")
		(net "TP_I2C_S3M_RTC_CPU1_SCL")
	)
	(segment
		(start 118.906798 -228.91115)
		(end 117.781578 -230.80599)
		(width 0.0889)
		(layer "B.Cu")
		(net "TP_I2C_S3M_RTC_CPU1_SCL")
	)
	(segment
		(start 124.059696 -227.960682)
		(end 124.044964 -227.969318)
		(width 0.0889)
		(layer "B.Cu")
		(net "TP_I2C_S3M_RTC_CPU1_SCL")
	)
	(segment
		(start 123.119896 -227.960682)
		(end 123.105164 -227.969318)
		(width 0.0889)
		(layer "B.Cu")
		(net "TP_I2C_S3M_RTC_CPU1_SCL")
	)
	(segment
		(start 124.999496 -227.960682)
		(end 124.984764 -227.969318)
		(width 0.0889)
		(layer "B.Cu")
		(net "TP_I2C_S3M_RTC_CPU1_SCL")
	)
	(segment
		(start 138.243818 -227.08235)
		(end 137.565638 -227.76053)
		(width 0.12954)
		(layer "B.Cu")
		(net "TP_I2C_S3M_RTC_CPU1_SCL")
	)
	(segment
		(start 121.235978 -227.963222)
		(end 121.225564 -227.969318)
		(width 0.0889)
		(layer "B.Cu")
		(net "TP_I2C_S3M_RTC_CPU1_SCL")
	)
	(segment
		(start 119.063262 -228.444806)
		(end 119.063262 -228.45903)
		(width 0.0889)
		(layer "B.Cu")
		(net "TP_I2C_S3M_RTC_CPU1_SCL")
	)
	(segment
		(start 126.874778 -227.963222)
		(end 126.864364 -227.969318)
		(width 0.0889)
		(layer "B.Cu")
		(net "TP_I2C_S3M_RTC_CPU1_SCL")
	)
	(segment
		(start 128.754124 -227.963222)
		(end 128.74371 -227.969318)
		(width 0.0889)
		(layer "B.Cu")
		(net "TP_I2C_S3M_RTC_CPU1_SCL")
	)
	(arc
		(start 128.369314 -227.969318)
		(mid 128.086612 -227.893576)
		(end 127.80391 -227.969318)
		(width 0.0889)
		(layer "B.Cu")
		(net "TP_I2C_S3M_RTC_CPU1_SCL")
	)
	(arc
		(start 125.550168 -227.969318)
		(mid 125.275939 -227.893393)
		(end 124.999496 -227.960682)
		(width 0.0889)
		(layer "B.Cu")
		(net "TP_I2C_S3M_RTC_CPU1_SCL")
	)
	(arc
		(start 131.563364 -227.969318)
		(mid 131.376166 -228.019461)
		(end 131.188968 -227.969318)
		(width 0.0889)
		(layer "B.Cu")
		(net "TP_I2C_S3M_RTC_CPU1_SCL")
	)
	(arc
		(start 121.225564 -227.969318)
		(mid 121.038366 -228.019461)
		(end 120.851168 -227.969318)
		(width 0.0889)
		(layer "B.Cu")
		(net "TP_I2C_S3M_RTC_CPU1_SCL")
	)
	(arc
		(start 119.911368 -227.969318)
		(mid 119.637139 -227.893393)
		(end 119.360696 -227.960682)
		(width 0.0889)
		(layer "B.Cu")
		(net "TP_I2C_S3M_RTC_CPU1_SCL")
	)
	(arc
		(start 123.670568 -227.969318)
		(mid 123.396339 -227.893393)
		(end 123.119896 -227.960682)
		(width 0.0889)
		(layer "B.Cu")
		(net "TP_I2C_S3M_RTC_CPU1_SCL")
	)
	(arc
		(start 127.429514 -227.969318)
		(mid 127.152955 -227.893609)
		(end 126.874778 -227.963222)
		(width 0.0889)
		(layer "B.Cu")
		(net "TP_I2C_S3M_RTC_CPU1_SCL")
	)
	(arc
		(start 135.607298 -227.893626)
		(mid 135.459923 -227.912622)
		(end 135.322564 -227.969318)
		(width 0.0889)
		(layer "B.Cu")
		(net "TP_I2C_S3M_RTC_CPU1_SCL")
	)
	(arc
		(start 129.683764 -227.969318)
		(mid 129.496566 -228.019461)
		(end 129.309368 -227.969318)
		(width 0.0889)
		(layer "B.Cu")
		(net "TP_I2C_S3M_RTC_CPU1_SCL")
	)
	(arc
		(start 128.74371 -227.969318)
		(mid 128.556512 -228.019461)
		(end 128.369314 -227.969318)
		(width 0.0889)
		(layer "B.Cu")
		(net "TP_I2C_S3M_RTC_CPU1_SCL")
	)
	(arc
		(start 132.128768 -227.969318)
		(mid 131.854539 -227.893393)
		(end 131.578096 -227.960682)
		(width 0.0889)
		(layer "B.Cu")
		(net "TP_I2C_S3M_RTC_CPU1_SCL")
	)
	(arc
		(start 131.188968 -227.969318)
		(mid 130.914739 -227.893393)
		(end 130.638296 -227.960682)
		(width 0.0889)
		(layer "B.Cu")
		(net "TP_I2C_S3M_RTC_CPU1_SCL")
	)
	(arc
		(start 124.984764 -227.969318)
		(mid 124.797566 -228.019461)
		(end 124.610368 -227.969318)
		(width 0.0889)
		(layer "B.Cu")
		(net "TP_I2C_S3M_RTC_CPU1_SCL")
	)
	(arc
		(start 123.105164 -227.969318)
		(mid 122.917966 -228.019461)
		(end 122.730768 -227.969318)
		(width 0.0889)
		(layer "B.Cu")
		(net "TP_I2C_S3M_RTC_CPU1_SCL")
	)
	(arc
		(start 129.309368 -227.969318)
		(mid 129.032555 -227.893482)
		(end 128.754124 -227.963222)
		(width 0.0889)
		(layer "B.Cu")
		(net "TP_I2C_S3M_RTC_CPU1_SCL")
	)
	(arc
		(start 133.068568 -227.969318)
		(mid 132.785866 -227.893576)
		(end 132.503164 -227.969318)
		(width 0.0889)
		(layer "B.Cu")
		(net "TP_I2C_S3M_RTC_CPU1_SCL")
	)
	(arc
		(start 119.345964 -227.969318)
		(mid 119.142483 -228.170122)
		(end 119.063262 -228.444806)
		(width 0.0889)
		(layer "B.Cu")
		(net "TP_I2C_S3M_RTC_CPU1_SCL")
	)
	(arc
		(start 134.382764 -227.969318)
		(mid 134.195566 -228.019461)
		(end 134.008368 -227.969318)
		(width 0.0889)
		(layer "B.Cu")
		(net "TP_I2C_S3M_RTC_CPU1_SCL")
	)
	(arc
		(start 130.249168 -227.969318)
		(mid 129.974939 -227.893393)
		(end 129.698496 -227.960682)
		(width 0.0889)
		(layer "B.Cu")
		(net "TP_I2C_S3M_RTC_CPU1_SCL")
	)
	(arc
		(start 122.730768 -227.969318)
		(mid 122.453955 -227.893482)
		(end 122.175524 -227.963222)
		(width 0.0889)
		(layer "B.Cu")
		(net "TP_I2C_S3M_RTC_CPU1_SCL")
	)
	(arc
		(start 121.790714 -227.969318)
		(mid 121.514155 -227.893609)
		(end 121.235978 -227.963222)
		(width 0.0889)
		(layer "B.Cu")
		(net "TP_I2C_S3M_RTC_CPU1_SCL")
	)
	(arc
		(start 120.851168 -227.969318)
		(mid 120.576939 -227.893393)
		(end 120.300496 -227.960682)
		(width 0.0889)
		(layer "B.Cu")
		(net "TP_I2C_S3M_RTC_CPU1_SCL")
	)
	(arc
		(start 135.322564 -227.969318)
		(mid 135.135366 -228.019461)
		(end 134.948168 -227.969318)
		(width 0.0889)
		(layer "B.Cu")
		(net "TP_I2C_S3M_RTC_CPU1_SCL")
	)
	(arc
		(start 127.80391 -227.969318)
		(mid 127.616712 -228.019461)
		(end 127.429514 -227.969318)
		(width 0.0889)
		(layer "B.Cu")
		(net "TP_I2C_S3M_RTC_CPU1_SCL")
	)
	(arc
		(start 133.442964 -227.969318)
		(mid 133.255766 -228.019461)
		(end 133.068568 -227.969318)
		(width 0.0889)
		(layer "B.Cu")
		(net "TP_I2C_S3M_RTC_CPU1_SCL")
	)
	(arc
		(start 132.503164 -227.969318)
		(mid 132.315966 -228.019461)
		(end 132.128768 -227.969318)
		(width 0.0889)
		(layer "B.Cu")
		(net "TP_I2C_S3M_RTC_CPU1_SCL")
	)
	(arc
		(start 126.864364 -227.969318)
		(mid 126.677166 -228.019461)
		(end 126.489968 -227.969318)
		(width 0.0889)
		(layer "B.Cu")
		(net "TP_I2C_S3M_RTC_CPU1_SCL")
	)
	(arc
		(start 130.623564 -227.969318)
		(mid 130.436366 -228.019461)
		(end 130.249168 -227.969318)
		(width 0.0889)
		(layer "B.Cu")
		(net "TP_I2C_S3M_RTC_CPU1_SCL")
	)
	(arc
		(start 119.063262 -228.45903)
		(mid 119.023043 -228.698246)
		(end 118.906798 -228.91115)
		(width 0.0889)
		(layer "B.Cu")
		(net "TP_I2C_S3M_RTC_CPU1_SCL")
	)
	(arc
		(start 120.285764 -227.969318)
		(mid 120.098566 -228.019461)
		(end 119.911368 -227.969318)
		(width 0.0889)
		(layer "B.Cu")
		(net "TP_I2C_S3M_RTC_CPU1_SCL")
	)
	(arc
		(start 134.008368 -227.969318)
		(mid 133.725666 -227.893576)
		(end 133.442964 -227.969318)
		(width 0.0889)
		(layer "B.Cu")
		(net "TP_I2C_S3M_RTC_CPU1_SCL")
	)
	(arc
		(start 126.489968 -227.969318)
		(mid 126.207266 -227.893576)
		(end 125.924564 -227.969318)
		(width 0.0889)
		(layer "B.Cu")
		(net "TP_I2C_S3M_RTC_CPU1_SCL")
	)
	(arc
		(start 124.044964 -227.969318)
		(mid 123.857766 -228.019461)
		(end 123.670568 -227.969318)
		(width 0.0889)
		(layer "B.Cu")
		(net "TP_I2C_S3M_RTC_CPU1_SCL")
	)
	(arc
		(start 122.16511 -227.969318)
		(mid 121.977912 -228.019461)
		(end 121.790714 -227.969318)
		(width 0.0889)
		(layer "B.Cu")
		(net "TP_I2C_S3M_RTC_CPU1_SCL")
	)
	(arc
		(start 125.924564 -227.969318)
		(mid 125.737366 -228.019461)
		(end 125.550168 -227.969318)
		(width 0.0889)
		(layer "B.Cu")
		(net "TP_I2C_S3M_RTC_CPU1_SCL")
	)
	(arc
		(start 124.610368 -227.969318)
		(mid 124.336139 -227.893393)
		(end 124.059696 -227.960682)
		(width 0.0889)
		(layer "B.Cu")
		(net "TP_I2C_S3M_RTC_CPU1_SCL")
	)
	(arc
		(start 134.948168 -227.969318)
		(mid 134.673939 -227.893393)
		(end 134.397496 -227.960682)
		(width 0.0889)
		(layer "B.Cu")
		(net "TP_I2C_S3M_RTC_CPU1_SCL")
	)
	(segment
		(start 116.809266 -233.87812)
		(end 116.809012 -233.877866)
		(width 0.12954)
		(layer "F.Cu")
		(net "TP_I2C_S3M_RTC_CPU1_RST_N")
	)
	(segment
		(start 116.809012 -233.877866)
		(end 116.809012 -233.34218)
		(width 0.12954)
		(layer "F.Cu")
		(net "TP_I2C_S3M_RTC_CPU1_RST_N")
	)
	(via
		(at 116.809012 -233.34218)
		(size 0.4572)
		(drill 0.2032)
		(layers "F.Cu" "B.Cu")
		(net "TP_I2C_S3M_RTC_CPU1_RST_N")
	)
	(segment
		(start 364.749334 -232.250488)
		(end 364.74908 -232.250234)
		(width 0.12954)
		(layer "F.Cu")
		(net "TP_I2C_S3M_RTC_CPU0_SDA")
	)
	(segment
		(start 364.74908 -232.250234)
		(end 364.74908 -231.714548)
		(width 0.12954)
		(layer "F.Cu")
		(net "TP_I2C_S3M_RTC_CPU0_SDA")
	)
	(via
		(at 364.74908 -231.714548)
		(size 0.4572)
		(drill 0.2032)
		(layers "F.Cu" "B.Cu")
		(net "TP_I2C_S3M_RTC_CPU0_SDA")
	)
	(via
		(at 387.923278 -233.08691)
		(size 0.6604)
		(drill 0.3302)
		(layers "F.Cu" "B.Cu")
		(net "TP_I2C_S3M_RTC_CPU0_SDA")
	)
	(segment
		(start 378.578364 -232.212642)
		(end 378.563632 -232.204006)
		(width 0.0889)
		(layer "B.Cu")
		(net "TP_I2C_S3M_RTC_CPU0_SDA")
	)
	(segment
		(start 386.485638 -232.62971)
		(end 385.670298 -232.62971)
		(width 0.12954)
		(layer "B.Cu")
		(net "TP_I2C_S3M_RTC_CPU0_SDA")
	)
	(segment
		(start 373.875046 -232.210102)
		(end 373.864632 -232.204006)
		(width 0.0889)
		(layer "B.Cu")
		(net "TP_I2C_S3M_RTC_CPU0_SDA")
	)
	(segment
		(start 371.999764 -232.212642)
		(end 371.985032 -232.204006)
		(width 0.0889)
		(layer "B.Cu")
		(net "TP_I2C_S3M_RTC_CPU0_SDA")
	)
	(segment
		(start 367.851436 -232.204006)
		(end 367.836704 -232.212642)
		(width 0.0889)
		(layer "B.Cu")
		(net "TP_I2C_S3M_RTC_CPU0_SDA")
	)
	(segment
		(start 379.518164 -232.212642)
		(end 379.503432 -232.204006)
		(width 0.0889)
		(layer "B.Cu")
		(net "TP_I2C_S3M_RTC_CPU0_SDA")
	)
	(segment
		(start 374.814592 -232.210102)
		(end 374.804178 -232.204006)
		(width 0.0889)
		(layer "B.Cu")
		(net "TP_I2C_S3M_RTC_CPU0_SDA")
	)
	(segment
		(start 365.061754 -231.714548)
		(end 364.74908 -231.714548)
		(width 0.0889)
		(layer "B.Cu")
		(net "TP_I2C_S3M_RTC_CPU0_SDA")
	)
	(segment
		(start 377.638564 -232.212642)
		(end 377.623832 -232.204006)
		(width 0.0889)
		(layer "B.Cu")
		(net "TP_I2C_S3M_RTC_CPU0_SDA")
	)
	(segment
		(start 375.758964 -232.212642)
		(end 375.744232 -232.204006)
		(width 0.0889)
		(layer "B.Cu")
		(net "TP_I2C_S3M_RTC_CPU0_SDA")
	)
	(segment
		(start 366.360964 -232.212642)
		(end 366.346232 -232.204006)
		(width 0.0889)
		(layer "B.Cu")
		(net "TP_I2C_S3M_RTC_CPU0_SDA")
	)
	(segment
		(start 372.939564 -232.212642)
		(end 372.924832 -232.204006)
		(width 0.0889)
		(layer "B.Cu")
		(net "TP_I2C_S3M_RTC_CPU0_SDA")
	)
	(segment
		(start 365.406432 -232.204006)
		(end 365.400336 -232.20045)
		(width 0.0889)
		(layer "B.Cu")
		(net "TP_I2C_S3M_RTC_CPU0_SDA")
	)
	(segment
		(start 380.453646 -232.210102)
		(end 380.443232 -232.204006)
		(width 0.0889)
		(layer "B.Cu")
		(net "TP_I2C_S3M_RTC_CPU0_SDA")
	)
	(segment
		(start 386.942838 -233.08691)
		(end 386.485638 -232.62971)
		(width 0.12954)
		(layer "B.Cu")
		(net "TP_I2C_S3M_RTC_CPU0_SDA")
	)
	(segment
		(start 371.059964 -232.212642)
		(end 371.045232 -232.204006)
		(width 0.0889)
		(layer "B.Cu")
		(net "TP_I2C_S3M_RTC_CPU0_SDA")
	)
	(segment
		(start 385.428998 -232.38841)
		(end 385.194048 -232.15346)
		(width 0.0889)
		(layer "B.Cu")
		(net "TP_I2C_S3M_RTC_CPU0_SDA")
	)
	(segment
		(start 385.670298 -232.62971)
		(end 385.428998 -232.38841)
		(width 0.12954)
		(layer "B.Cu")
		(net "TP_I2C_S3M_RTC_CPU0_SDA")
	)
	(segment
		(start 367.859818 -232.19918)
		(end 367.851436 -232.204006)
		(width 0.0889)
		(layer "B.Cu")
		(net "TP_I2C_S3M_RTC_CPU0_SDA")
	)
	(segment
		(start 387.923278 -233.08691)
		(end 386.942838 -233.08691)
		(width 0.12954)
		(layer "B.Cu")
		(net "TP_I2C_S3M_RTC_CPU0_SDA")
	)
	(segment
		(start 368.235992 -232.210102)
		(end 368.225578 -232.204006)
		(width 0.0889)
		(layer "B.Cu")
		(net "TP_I2C_S3M_RTC_CPU0_SDA")
	)
	(segment
		(start 365.12754 -231.780334)
		(end 365.061754 -231.714548)
		(width 0.0889)
		(layer "B.Cu")
		(net "TP_I2C_S3M_RTC_CPU0_SDA")
	)
	(segment
		(start 365.421164 -232.212642)
		(end 365.406432 -232.204006)
		(width 0.0889)
		(layer "B.Cu")
		(net "TP_I2C_S3M_RTC_CPU0_SDA")
	)
	(segment
		(start 385.194048 -232.15346)
		(end 384.955034 -232.15346)
		(width 0.0889)
		(layer "B.Cu")
		(net "TP_I2C_S3M_RTC_CPU0_SDA")
	)
	(segment
		(start 381.948436 -232.204006)
		(end 381.938022 -232.210102)
		(width 0.0889)
		(layer "B.Cu")
		(net "TP_I2C_S3M_RTC_CPU0_SDA")
	)
	(segment
		(start 369.731036 -232.204006)
		(end 369.716304 -232.212642)
		(width 0.0889)
		(layer "B.Cu")
		(net "TP_I2C_S3M_RTC_CPU0_SDA")
	)
	(arc
		(start 377.623832 -232.204006)
		(mid 377.436634 -232.153863)
		(end 377.249436 -232.204006)
		(width 0.0889)
		(layer "B.Cu")
		(net "TP_I2C_S3M_RTC_CPU0_SDA")
	)
	(arc
		(start 378.563632 -232.204006)
		(mid 378.376434 -232.153863)
		(end 378.189236 -232.204006)
		(width 0.0889)
		(layer "B.Cu")
		(net "TP_I2C_S3M_RTC_CPU0_SDA")
	)
	(arc
		(start 365.400336 -232.20045)
		(mid 365.214881 -232.022255)
		(end 365.12754 -231.780334)
		(width 0.0889)
		(layer "B.Cu")
		(net "TP_I2C_S3M_RTC_CPU0_SDA")
	)
	(arc
		(start 376.309636 -232.204006)
		(mid 376.035437 -232.279841)
		(end 375.758964 -232.212642)
		(width 0.0889)
		(layer "B.Cu")
		(net "TP_I2C_S3M_RTC_CPU0_SDA")
	)
	(arc
		(start 375.369836 -232.204006)
		(mid 375.093023 -232.279876)
		(end 374.814592 -232.210102)
		(width 0.0889)
		(layer "B.Cu")
		(net "TP_I2C_S3M_RTC_CPU0_SDA")
	)
	(arc
		(start 381.008382 -232.204006)
		(mid 380.731823 -232.279749)
		(end 380.453646 -232.210102)
		(width 0.0889)
		(layer "B.Cu")
		(net "TP_I2C_S3M_RTC_CPU0_SDA")
	)
	(arc
		(start 377.249436 -232.204006)
		(mid 376.966734 -232.279782)
		(end 376.684032 -232.204006)
		(width 0.0889)
		(layer "B.Cu")
		(net "TP_I2C_S3M_RTC_CPU0_SDA")
	)
	(arc
		(start 384.767836 -232.204006)
		(mid 384.485134 -232.279782)
		(end 384.202432 -232.204006)
		(width 0.0889)
		(layer "B.Cu")
		(net "TP_I2C_S3M_RTC_CPU0_SDA")
	)
	(arc
		(start 368.791236 -232.204006)
		(mid 368.514423 -232.279876)
		(end 368.235992 -232.210102)
		(width 0.0889)
		(layer "B.Cu")
		(net "TP_I2C_S3M_RTC_CPU0_SDA")
	)
	(arc
		(start 380.068836 -232.204006)
		(mid 379.794637 -232.279841)
		(end 379.518164 -232.212642)
		(width 0.0889)
		(layer "B.Cu")
		(net "TP_I2C_S3M_RTC_CPU0_SDA")
	)
	(arc
		(start 382.322832 -232.204006)
		(mid 382.135634 -232.153863)
		(end 381.948436 -232.204006)
		(width 0.0889)
		(layer "B.Cu")
		(net "TP_I2C_S3M_RTC_CPU0_SDA")
	)
	(arc
		(start 366.346232 -232.204006)
		(mid 366.159034 -232.153863)
		(end 365.971836 -232.204006)
		(width 0.0889)
		(layer "B.Cu")
		(net "TP_I2C_S3M_RTC_CPU0_SDA")
	)
	(arc
		(start 383.262632 -232.204006)
		(mid 383.075434 -232.153863)
		(end 382.888236 -232.204006)
		(width 0.0889)
		(layer "B.Cu")
		(net "TP_I2C_S3M_RTC_CPU0_SDA")
	)
	(arc
		(start 370.670836 -232.204006)
		(mid 370.388134 -232.279782)
		(end 370.105432 -232.204006)
		(width 0.0889)
		(layer "B.Cu")
		(net "TP_I2C_S3M_RTC_CPU0_SDA")
	)
	(arc
		(start 380.443232 -232.204006)
		(mid 380.256034 -232.153863)
		(end 380.068836 -232.204006)
		(width 0.0889)
		(layer "B.Cu")
		(net "TP_I2C_S3M_RTC_CPU0_SDA")
	)
	(arc
		(start 374.804178 -232.204006)
		(mid 374.61698 -232.153863)
		(end 374.429782 -232.204006)
		(width 0.0889)
		(layer "B.Cu")
		(net "TP_I2C_S3M_RTC_CPU0_SDA")
	)
	(arc
		(start 379.503432 -232.204006)
		(mid 379.316234 -232.153863)
		(end 379.129036 -232.204006)
		(width 0.0889)
		(layer "B.Cu")
		(net "TP_I2C_S3M_RTC_CPU0_SDA")
	)
	(arc
		(start 379.129036 -232.204006)
		(mid 378.854837 -232.279841)
		(end 378.578364 -232.212642)
		(width 0.0889)
		(layer "B.Cu")
		(net "TP_I2C_S3M_RTC_CPU0_SDA")
	)
	(arc
		(start 371.610636 -232.204006)
		(mid 371.336437 -232.279841)
		(end 371.059964 -232.212642)
		(width 0.0889)
		(layer "B.Cu")
		(net "TP_I2C_S3M_RTC_CPU0_SDA")
	)
	(arc
		(start 370.105432 -232.204006)
		(mid 369.918234 -232.153863)
		(end 369.731036 -232.204006)
		(width 0.0889)
		(layer "B.Cu")
		(net "TP_I2C_S3M_RTC_CPU0_SDA")
	)
	(arc
		(start 368.225578 -232.204006)
		(mid 368.043327 -232.153895)
		(end 367.859818 -232.19918)
		(width 0.0889)
		(layer "B.Cu")
		(net "TP_I2C_S3M_RTC_CPU0_SDA")
	)
	(arc
		(start 383.828036 -232.204006)
		(mid 383.545334 -232.279782)
		(end 383.262632 -232.204006)
		(width 0.0889)
		(layer "B.Cu")
		(net "TP_I2C_S3M_RTC_CPU0_SDA")
	)
	(arc
		(start 378.189236 -232.204006)
		(mid 377.915037 -232.279841)
		(end 377.638564 -232.212642)
		(width 0.0889)
		(layer "B.Cu")
		(net "TP_I2C_S3M_RTC_CPU0_SDA")
	)
	(arc
		(start 372.924832 -232.204006)
		(mid 372.737634 -232.153863)
		(end 372.550436 -232.204006)
		(width 0.0889)
		(layer "B.Cu")
		(net "TP_I2C_S3M_RTC_CPU0_SDA")
	)
	(arc
		(start 384.202432 -232.204006)
		(mid 384.015234 -232.153863)
		(end 383.828036 -232.204006)
		(width 0.0889)
		(layer "B.Cu")
		(net "TP_I2C_S3M_RTC_CPU0_SDA")
	)
	(arc
		(start 374.429782 -232.204006)
		(mid 374.153223 -232.279749)
		(end 373.875046 -232.210102)
		(width 0.0889)
		(layer "B.Cu")
		(net "TP_I2C_S3M_RTC_CPU0_SDA")
	)
	(arc
		(start 384.955034 -232.15346)
		(mid 384.858106 -232.166411)
		(end 384.767836 -232.204006)
		(width 0.0889)
		(layer "B.Cu")
		(net "TP_I2C_S3M_RTC_CPU0_SDA")
	)
	(arc
		(start 366.911636 -232.204006)
		(mid 366.637437 -232.279841)
		(end 366.360964 -232.212642)
		(width 0.0889)
		(layer "B.Cu")
		(net "TP_I2C_S3M_RTC_CPU0_SDA")
	)
	(arc
		(start 382.888236 -232.204006)
		(mid 382.605534 -232.279782)
		(end 382.322832 -232.204006)
		(width 0.0889)
		(layer "B.Cu")
		(net "TP_I2C_S3M_RTC_CPU0_SDA")
	)
	(arc
		(start 369.165632 -232.204006)
		(mid 368.978434 -232.153863)
		(end 368.791236 -232.204006)
		(width 0.0889)
		(layer "B.Cu")
		(net "TP_I2C_S3M_RTC_CPU0_SDA")
	)
	(arc
		(start 373.864632 -232.204006)
		(mid 373.677434 -232.153863)
		(end 373.490236 -232.204006)
		(width 0.0889)
		(layer "B.Cu")
		(net "TP_I2C_S3M_RTC_CPU0_SDA")
	)
	(arc
		(start 381.938022 -232.210102)
		(mid 381.65959 -232.279948)
		(end 381.382778 -232.204006)
		(width 0.0889)
		(layer "B.Cu")
		(net "TP_I2C_S3M_RTC_CPU0_SDA")
	)
	(arc
		(start 371.045232 -232.204006)
		(mid 370.858034 -232.153863)
		(end 370.670836 -232.204006)
		(width 0.0889)
		(layer "B.Cu")
		(net "TP_I2C_S3M_RTC_CPU0_SDA")
	)
	(arc
		(start 372.550436 -232.204006)
		(mid 372.276237 -232.279841)
		(end 371.999764 -232.212642)
		(width 0.0889)
		(layer "B.Cu")
		(net "TP_I2C_S3M_RTC_CPU0_SDA")
	)
	(arc
		(start 367.836704 -232.212642)
		(mid 367.560229 -232.279962)
		(end 367.286032 -232.204006)
		(width 0.0889)
		(layer "B.Cu")
		(net "TP_I2C_S3M_RTC_CPU0_SDA")
	)
	(arc
		(start 371.985032 -232.204006)
		(mid 371.797834 -232.153863)
		(end 371.610636 -232.204006)
		(width 0.0889)
		(layer "B.Cu")
		(net "TP_I2C_S3M_RTC_CPU0_SDA")
	)
	(arc
		(start 381.382778 -232.204006)
		(mid 381.19558 -232.153863)
		(end 381.008382 -232.204006)
		(width 0.0889)
		(layer "B.Cu")
		(net "TP_I2C_S3M_RTC_CPU0_SDA")
	)
	(arc
		(start 365.971836 -232.204006)
		(mid 365.697637 -232.279841)
		(end 365.421164 -232.212642)
		(width 0.0889)
		(layer "B.Cu")
		(net "TP_I2C_S3M_RTC_CPU0_SDA")
	)
	(arc
		(start 375.744232 -232.204006)
		(mid 375.557034 -232.153863)
		(end 375.369836 -232.204006)
		(width 0.0889)
		(layer "B.Cu")
		(net "TP_I2C_S3M_RTC_CPU0_SDA")
	)
	(arc
		(start 373.490236 -232.204006)
		(mid 373.216037 -232.279841)
		(end 372.939564 -232.212642)
		(width 0.0889)
		(layer "B.Cu")
		(net "TP_I2C_S3M_RTC_CPU0_SDA")
	)
	(arc
		(start 369.716304 -232.212642)
		(mid 369.439829 -232.279962)
		(end 369.165632 -232.204006)
		(width 0.0889)
		(layer "B.Cu")
		(net "TP_I2C_S3M_RTC_CPU0_SDA")
	)
	(arc
		(start 376.684032 -232.204006)
		(mid 376.496834 -232.153863)
		(end 376.309636 -232.204006)
		(width 0.0889)
		(layer "B.Cu")
		(net "TP_I2C_S3M_RTC_CPU0_SDA")
	)
	(arc
		(start 367.286032 -232.204006)
		(mid 367.098834 -232.153863)
		(end 366.911636 -232.204006)
		(width 0.0889)
		(layer "B.Cu")
		(net "TP_I2C_S3M_RTC_CPU0_SDA")
	)
	(segment
		(start 365.68888 -232.250234)
		(end 365.68888 -231.714548)
		(width 0.12954)
		(layer "F.Cu")
		(net "TP_I2C_S3M_RTC_CPU0_SCL")
	)
	(segment
		(start 365.689134 -232.250488)
		(end 365.68888 -232.250234)
		(width 0.12954)
		(layer "F.Cu")
		(net "TP_I2C_S3M_RTC_CPU0_SCL")
	)
	(via
		(at 365.68888 -231.714548)
		(size 0.4572)
		(drill 0.2032)
		(layers "F.Cu" "B.Cu")
		(net "TP_I2C_S3M_RTC_CPU0_SCL")
	)
	(via
		(at 389.084058 -232.07091)
		(size 0.6604)
		(drill 0.3302)
		(layers "F.Cu" "B.Cu")
		(net "TP_I2C_S3M_RTC_CPU0_SCL")
	)
	(segment
		(start 373.959882 -232.038906)
		(end 373.94515 -232.03027)
		(width 0.0889)
		(layer "B.Cu")
		(net "TP_I2C_S3M_RTC_CPU0_SCL")
	)
	(segment
		(start 379.598682 -232.038906)
		(end 379.58395 -232.03027)
		(width 0.0889)
		(layer "B.Cu")
		(net "TP_I2C_S3M_RTC_CPU0_SCL")
	)
	(segment
		(start 367.766346 -232.03281)
		(end 367.755932 -232.038906)
		(width 0.0889)
		(layer "B.Cu")
		(net "TP_I2C_S3M_RTC_CPU0_SCL")
	)
	(segment
		(start 375.839482 -232.038906)
		(end 375.82475 -232.03027)
		(width 0.0889)
		(layer "B.Cu")
		(net "TP_I2C_S3M_RTC_CPU0_SCL")
	)
	(segment
		(start 386.881878 -232.53319)
		(end 386.559298 -232.21061)
		(width 0.12954)
		(layer "B.Cu")
		(net "TP_I2C_S3M_RTC_CPU0_SCL")
	)
	(segment
		(start 380.538482 -232.038906)
		(end 380.52375 -232.03027)
		(width 0.0889)
		(layer "B.Cu")
		(net "TP_I2C_S3M_RTC_CPU0_SCL")
	)
	(segment
		(start 372.080282 -232.038906)
		(end 372.06555 -232.03027)
		(width 0.0889)
		(layer "B.Cu")
		(net "TP_I2C_S3M_RTC_CPU0_SCL")
	)
	(segment
		(start 365.501682 -232.038906)
		(end 365.492792 -232.033826)
		(width 0.0889)
		(layer "B.Cu")
		(net "TP_I2C_S3M_RTC_CPU0_SCL")
	)
	(segment
		(start 388.621778 -232.53319)
		(end 386.881878 -232.53319)
		(width 0.12954)
		(layer "B.Cu")
		(net "TP_I2C_S3M_RTC_CPU0_SCL")
	)
	(segment
		(start 373.020082 -232.038906)
		(end 373.00535 -232.03027)
		(width 0.0889)
		(layer "B.Cu")
		(net "TP_I2C_S3M_RTC_CPU0_SCL")
	)
	(segment
		(start 371.140482 -232.038906)
		(end 371.130068 -232.03281)
		(width 0.0889)
		(layer "B.Cu")
		(net "TP_I2C_S3M_RTC_CPU0_SCL")
	)
	(segment
		(start 365.318802 -231.771952)
		(end 365.376206 -231.714548)
		(width 0.0889)
		(layer "B.Cu")
		(net "TP_I2C_S3M_RTC_CPU0_SCL")
	)
	(segment
		(start 376.779536 -232.038906)
		(end 376.769122 -232.03281)
		(width 0.0889)
		(layer "B.Cu")
		(net "TP_I2C_S3M_RTC_CPU0_SCL")
	)
	(segment
		(start 385.662678 -232.21061)
		(end 385.415282 -231.963214)
		(width 0.0889)
		(layer "B.Cu")
		(net "TP_I2C_S3M_RTC_CPU0_SCL")
	)
	(segment
		(start 366.441482 -232.038906)
		(end 366.42675 -232.03027)
		(width 0.0889)
		(layer "B.Cu")
		(net "TP_I2C_S3M_RTC_CPU0_SCL")
	)
	(segment
		(start 365.376206 -231.714548)
		(end 365.68888 -231.714548)
		(width 0.0889)
		(layer "B.Cu")
		(net "TP_I2C_S3M_RTC_CPU0_SCL")
	)
	(segment
		(start 367.755932 -232.038906)
		(end 367.74755 -232.043732)
		(width 0.0889)
		(layer "B.Cu")
		(net "TP_I2C_S3M_RTC_CPU0_SCL")
	)
	(segment
		(start 386.559298 -232.21061)
		(end 385.939538 -232.21061)
		(width 0.12954)
		(layer "B.Cu")
		(net "TP_I2C_S3M_RTC_CPU0_SCL")
	)
	(segment
		(start 377.719082 -232.038906)
		(end 377.708668 -232.03281)
		(width 0.0889)
		(layer "B.Cu")
		(net "TP_I2C_S3M_RTC_CPU0_SCL")
	)
	(segment
		(start 385.939538 -232.21061)
		(end 385.662678 -232.21061)
		(width 0.0889)
		(layer "B.Cu")
		(net "TP_I2C_S3M_RTC_CPU0_SCL")
	)
	(segment
		(start 378.658882 -232.038906)
		(end 378.64415 -232.03027)
		(width 0.0889)
		(layer "B.Cu")
		(net "TP_I2C_S3M_RTC_CPU0_SCL")
	)
	(segment
		(start 389.084058 -232.07091)
		(end 388.621778 -232.53319)
		(width 0.12954)
		(layer "B.Cu")
		(net "TP_I2C_S3M_RTC_CPU0_SCL")
	)
	(segment
		(start 380.923292 -232.03281)
		(end 380.912878 -232.038906)
		(width 0.0889)
		(layer "B.Cu")
		(net "TP_I2C_S3M_RTC_CPU0_SCL")
	)
	(segment
		(start 369.6462 -232.03281)
		(end 369.635786 -232.038906)
		(width 0.0889)
		(layer "B.Cu")
		(net "TP_I2C_S3M_RTC_CPU0_SCL")
	)
	(segment
		(start 385.415282 -231.963214)
		(end 384.955034 -231.963214)
		(width 0.0889)
		(layer "B.Cu")
		(net "TP_I2C_S3M_RTC_CPU0_SCL")
	)
	(arc
		(start 365.492792 -232.033826)
		(mid 365.377053 -231.922002)
		(end 365.318802 -231.771952)
		(width 0.0889)
		(layer "B.Cu")
		(net "TP_I2C_S3M_RTC_CPU0_SCL")
	)
	(arc
		(start 370.575332 -232.038906)
		(mid 370.388134 -232.089049)
		(end 370.200936 -232.038906)
		(width 0.0889)
		(layer "B.Cu")
		(net "TP_I2C_S3M_RTC_CPU0_SCL")
	)
	(arc
		(start 376.769122 -232.03281)
		(mid 376.49069 -231.962964)
		(end 376.213878 -232.038906)
		(width 0.0889)
		(layer "B.Cu")
		(net "TP_I2C_S3M_RTC_CPU0_SCL")
	)
	(arc
		(start 378.093478 -232.038906)
		(mid 377.90628 -232.089049)
		(end 377.719082 -232.038906)
		(width 0.0889)
		(layer "B.Cu")
		(net "TP_I2C_S3M_RTC_CPU0_SCL")
	)
	(arc
		(start 369.26139 -232.038906)
		(mid 368.978434 -231.963003)
		(end 368.695478 -232.038906)
		(width 0.0889)
		(layer "B.Cu")
		(net "TP_I2C_S3M_RTC_CPU0_SCL")
	)
	(arc
		(start 379.973078 -232.038906)
		(mid 379.78588 -232.089049)
		(end 379.598682 -232.038906)
		(width 0.0889)
		(layer "B.Cu")
		(net "TP_I2C_S3M_RTC_CPU0_SCL")
	)
	(arc
		(start 373.394478 -232.038906)
		(mid 373.20728 -232.089049)
		(end 373.020082 -232.038906)
		(width 0.0889)
		(layer "B.Cu")
		(net "TP_I2C_S3M_RTC_CPU0_SCL")
	)
	(arc
		(start 382.418336 -232.038906)
		(mid 382.135634 -231.96313)
		(end 381.852932 -232.038906)
		(width 0.0889)
		(layer "B.Cu")
		(net "TP_I2C_S3M_RTC_CPU0_SCL")
	)
	(arc
		(start 372.454678 -232.038906)
		(mid 372.26748 -232.089049)
		(end 372.080282 -232.038906)
		(width 0.0889)
		(layer "B.Cu")
		(net "TP_I2C_S3M_RTC_CPU0_SCL")
	)
	(arc
		(start 380.52375 -232.03027)
		(mid 380.247275 -231.96295)
		(end 379.973078 -232.038906)
		(width 0.0889)
		(layer "B.Cu")
		(net "TP_I2C_S3M_RTC_CPU0_SCL")
	)
	(arc
		(start 384.672332 -232.038906)
		(mid 384.485134 -232.089049)
		(end 384.297936 -232.038906)
		(width 0.0889)
		(layer "B.Cu")
		(net "TP_I2C_S3M_RTC_CPU0_SCL")
	)
	(arc
		(start 379.58395 -232.03027)
		(mid 379.307475 -231.96295)
		(end 379.033278 -232.038906)
		(width 0.0889)
		(layer "B.Cu")
		(net "TP_I2C_S3M_RTC_CPU0_SCL")
	)
	(arc
		(start 383.732532 -232.038906)
		(mid 383.545334 -232.089049)
		(end 383.358136 -232.038906)
		(width 0.0889)
		(layer "B.Cu")
		(net "TP_I2C_S3M_RTC_CPU0_SCL")
	)
	(arc
		(start 371.130068 -232.03281)
		(mid 370.85189 -231.963087)
		(end 370.575332 -232.038906)
		(width 0.0889)
		(layer "B.Cu")
		(net "TP_I2C_S3M_RTC_CPU0_SCL")
	)
	(arc
		(start 375.82475 -232.03027)
		(mid 375.548275 -231.96295)
		(end 375.274078 -232.038906)
		(width 0.0889)
		(layer "B.Cu")
		(net "TP_I2C_S3M_RTC_CPU0_SCL")
	)
	(arc
		(start 367.74755 -232.043732)
		(mid 367.564042 -232.08901)
		(end 367.38179 -232.038906)
		(width 0.0889)
		(layer "B.Cu")
		(net "TP_I2C_S3M_RTC_CPU0_SCL")
	)
	(arc
		(start 366.42675 -232.03027)
		(mid 366.150275 -231.96295)
		(end 365.876078 -232.038906)
		(width 0.0889)
		(layer "B.Cu")
		(net "TP_I2C_S3M_RTC_CPU0_SCL")
	)
	(arc
		(start 378.64415 -232.03027)
		(mid 378.367675 -231.96295)
		(end 378.093478 -232.038906)
		(width 0.0889)
		(layer "B.Cu")
		(net "TP_I2C_S3M_RTC_CPU0_SCL")
	)
	(arc
		(start 381.478536 -232.038906)
		(mid 381.201723 -231.963036)
		(end 380.923292 -232.03281)
		(width 0.0889)
		(layer "B.Cu")
		(net "TP_I2C_S3M_RTC_CPU0_SCL")
	)
	(arc
		(start 384.955034 -231.963214)
		(mid 384.808711 -231.982476)
		(end 384.672332 -232.038906)
		(width 0.0889)
		(layer "B.Cu")
		(net "TP_I2C_S3M_RTC_CPU0_SCL")
	)
	(arc
		(start 373.94515 -232.03027)
		(mid 373.668675 -231.96295)
		(end 373.394478 -232.038906)
		(width 0.0889)
		(layer "B.Cu")
		(net "TP_I2C_S3M_RTC_CPU0_SCL")
	)
	(arc
		(start 382.792732 -232.038906)
		(mid 382.605534 -232.089049)
		(end 382.418336 -232.038906)
		(width 0.0889)
		(layer "B.Cu")
		(net "TP_I2C_S3M_RTC_CPU0_SCL")
	)
	(arc
		(start 377.708668 -232.03281)
		(mid 377.43049 -231.963087)
		(end 377.153932 -232.038906)
		(width 0.0889)
		(layer "B.Cu")
		(net "TP_I2C_S3M_RTC_CPU0_SCL")
	)
	(arc
		(start 379.033278 -232.038906)
		(mid 378.84608 -232.089049)
		(end 378.658882 -232.038906)
		(width 0.0889)
		(layer "B.Cu")
		(net "TP_I2C_S3M_RTC_CPU0_SCL")
	)
	(arc
		(start 384.297936 -232.038906)
		(mid 384.015234 -231.96313)
		(end 383.732532 -232.038906)
		(width 0.0889)
		(layer "B.Cu")
		(net "TP_I2C_S3M_RTC_CPU0_SCL")
	)
	(arc
		(start 371.514878 -232.038906)
		(mid 371.32768 -232.089049)
		(end 371.140482 -232.038906)
		(width 0.0889)
		(layer "B.Cu")
		(net "TP_I2C_S3M_RTC_CPU0_SCL")
	)
	(arc
		(start 370.200936 -232.038906)
		(mid 369.924377 -231.963163)
		(end 369.6462 -232.03281)
		(width 0.0889)
		(layer "B.Cu")
		(net "TP_I2C_S3M_RTC_CPU0_SCL")
	)
	(arc
		(start 365.876078 -232.038906)
		(mid 365.68888 -232.089049)
		(end 365.501682 -232.038906)
		(width 0.0889)
		(layer "B.Cu")
		(net "TP_I2C_S3M_RTC_CPU0_SCL")
	)
	(arc
		(start 381.852932 -232.038906)
		(mid 381.665734 -232.089049)
		(end 381.478536 -232.038906)
		(width 0.0889)
		(layer "B.Cu")
		(net "TP_I2C_S3M_RTC_CPU0_SCL")
	)
	(arc
		(start 369.635786 -232.038906)
		(mid 369.448588 -232.089049)
		(end 369.26139 -232.038906)
		(width 0.0889)
		(layer "B.Cu")
		(net "TP_I2C_S3M_RTC_CPU0_SCL")
	)
	(arc
		(start 375.274078 -232.038906)
		(mid 375.08688 -232.089049)
		(end 374.899682 -232.038906)
		(width 0.0889)
		(layer "B.Cu")
		(net "TP_I2C_S3M_RTC_CPU0_SCL")
	)
	(arc
		(start 373.00535 -232.03027)
		(mid 372.728875 -231.96295)
		(end 372.454678 -232.038906)
		(width 0.0889)
		(layer "B.Cu")
		(net "TP_I2C_S3M_RTC_CPU0_SCL")
	)
	(arc
		(start 374.899682 -232.038906)
		(mid 374.61698 -231.96313)
		(end 374.334278 -232.038906)
		(width 0.0889)
		(layer "B.Cu")
		(net "TP_I2C_S3M_RTC_CPU0_SCL")
	)
	(arc
		(start 372.06555 -232.03027)
		(mid 371.789075 -231.96295)
		(end 371.514878 -232.038906)
		(width 0.0889)
		(layer "B.Cu")
		(net "TP_I2C_S3M_RTC_CPU0_SCL")
	)
	(arc
		(start 376.213878 -232.038906)
		(mid 376.02668 -232.089049)
		(end 375.839482 -232.038906)
		(width 0.0889)
		(layer "B.Cu")
		(net "TP_I2C_S3M_RTC_CPU0_SCL")
	)
	(arc
		(start 368.321082 -232.038906)
		(mid 368.044523 -231.963163)
		(end 367.766346 -232.03281)
		(width 0.0889)
		(layer "B.Cu")
		(net "TP_I2C_S3M_RTC_CPU0_SCL")
	)
	(arc
		(start 380.912878 -232.038906)
		(mid 380.72568 -232.089049)
		(end 380.538482 -232.038906)
		(width 0.0889)
		(layer "B.Cu")
		(net "TP_I2C_S3M_RTC_CPU0_SCL")
	)
	(arc
		(start 367.38179 -232.038906)
		(mid 367.098834 -231.963003)
		(end 366.815878 -232.038906)
		(width 0.0889)
		(layer "B.Cu")
		(net "TP_I2C_S3M_RTC_CPU0_SCL")
	)
	(arc
		(start 374.334278 -232.038906)
		(mid 374.14708 -232.089049)
		(end 373.959882 -232.038906)
		(width 0.0889)
		(layer "B.Cu")
		(net "TP_I2C_S3M_RTC_CPU0_SCL")
	)
	(arc
		(start 383.358136 -232.038906)
		(mid 383.075434 -231.96313)
		(end 382.792732 -232.038906)
		(width 0.0889)
		(layer "B.Cu")
		(net "TP_I2C_S3M_RTC_CPU0_SCL")
	)
	(arc
		(start 377.153932 -232.038906)
		(mid 376.966734 -232.089049)
		(end 376.779536 -232.038906)
		(width 0.0889)
		(layer "B.Cu")
		(net "TP_I2C_S3M_RTC_CPU0_SCL")
	)
	(arc
		(start 368.695478 -232.038906)
		(mid 368.50828 -232.089049)
		(end 368.321082 -232.038906)
		(width 0.0889)
		(layer "B.Cu")
		(net "TP_I2C_S3M_RTC_CPU0_SCL")
	)
	(arc
		(start 366.815878 -232.038906)
		(mid 366.62868 -232.089049)
		(end 366.441482 -232.038906)
		(width 0.0889)
		(layer "B.Cu")
		(net "TP_I2C_S3M_RTC_CPU0_SCL")
	)
	(segment
		(start 364.749334 -233.87812)
		(end 364.74908 -233.877866)
		(width 0.12954)
		(layer "F.Cu")
		(net "TP_I2C_S3M_RTC_CPU0_ALERT_N")
	)
	(segment
		(start 364.74908 -233.877866)
		(end 364.74908 -233.34218)
		(width 0.12954)
		(layer "F.Cu")
		(net "TP_I2C_S3M_RTC_CPU0_ALERT_N")
	)
	(via
		(at 364.74908 -233.34218)
		(size 0.4572)
		(drill 0.2032)
		(layers "F.Cu" "B.Cu")
		(net "TP_I2C_S3M_RTC_CPU0_ALERT_N")
	)
	(segment
		(start 115.399566 -233.06405)
		(end 115.399566 -232.528364)
		(width 0.12954)
		(layer "F.Cu")
		(net "TP_H_SBLINK7_CPU1_PMSYNC")
	)
	(segment
		(start 115.399312 -233.064304)
		(end 115.399566 -233.06405)
		(width 0.12954)
		(layer "F.Cu")
		(net "TP_H_SBLINK7_CPU1_PMSYNC")
	)
	(via
		(at 115.399566 -232.528364)
		(size 0.4572)
		(drill 0.2032)
		(layers "F.Cu" "B.Cu")
		(net "TP_H_SBLINK7_CPU1_PMSYNC")
	)
	(segment
		(start 113.989866 -233.87812)
		(end 113.989866 -233.34218)
		(width 0.12954)
		(layer "F.Cu")
		(net "TP_H_SBLINK7_CPU1_PMDOWN")
	)
	(via
		(at 113.989866 -233.34218)
		(size 0.4572)
		(drill 0.2032)
		(layers "F.Cu" "B.Cu")
		(net "TP_H_SBLINK7_CPU1_PMDOWN")
	)
	(segment
		(start 363.339634 -233.06405)
		(end 363.339634 -232.528364)
		(width 0.12954)
		(layer "F.Cu")
		(net "TP_H_SBLINK7_CPU0_PMSYNC")
	)
	(segment
		(start 363.33938 -233.064304)
		(end 363.339634 -233.06405)
		(width 0.12954)
		(layer "F.Cu")
		(net "TP_H_SBLINK7_CPU0_PMSYNC")
	)
	(via
		(at 363.339634 -232.528364)
		(size 0.4572)
		(drill 0.2032)
		(layers "F.Cu" "B.Cu")
		(net "TP_H_SBLINK7_CPU0_PMSYNC")
	)
	(segment
		(start 361.929934 -233.87812)
		(end 361.929934 -233.34218)
		(width 0.12954)
		(layer "F.Cu")
		(net "TP_H_SBLINK7_CPU0_PMDOWN")
	)
	(via
		(at 361.929934 -233.34218)
		(size 0.4572)
		(drill 0.2032)
		(layers "F.Cu" "B.Cu")
		(net "TP_H_SBLINK7_CPU0_PMDOWN")
	)
	(segment
		(start 116.339112 -233.064304)
		(end 116.339366 -233.06405)
		(width 0.12954)
		(layer "F.Cu")
		(net "TP_H_SBLINK6_CPU1_PMSYNC")
	)
	(segment
		(start 116.339366 -233.06405)
		(end 116.339366 -232.528364)
		(width 0.12954)
		(layer "F.Cu")
		(net "TP_H_SBLINK6_CPU1_PMSYNC")
	)
	(via
		(at 116.339366 -232.528364)
		(size 0.4572)
		(drill 0.2032)
		(layers "F.Cu" "B.Cu")
		(net "TP_H_SBLINK6_CPU1_PMSYNC")
	)
	(segment
		(start 114.929666 -232.250488)
		(end 114.929412 -232.250234)
		(width 0.12954)
		(layer "F.Cu")
		(net "TP_H_SBLINK6_CPU1_PMDOWN")
	)
	(segment
		(start 114.929412 -232.250234)
		(end 114.929412 -231.714548)
		(width 0.12954)
		(layer "F.Cu")
		(net "TP_H_SBLINK6_CPU1_PMDOWN")
	)
	(via
		(at 114.929412 -231.714548)
		(size 0.4572)
		(drill 0.2032)
		(layers "F.Cu" "B.Cu")
		(net "TP_H_SBLINK6_CPU1_PMDOWN")
	)
	(segment
		(start 364.27918 -233.064304)
		(end 364.279434 -233.06405)
		(width 0.12954)
		(layer "F.Cu")
		(net "TP_H_SBLINK6_CPU0_PMSYNC")
	)
	(segment
		(start 364.279434 -233.06405)
		(end 364.279434 -232.528364)
		(width 0.12954)
		(layer "F.Cu")
		(net "TP_H_SBLINK6_CPU0_PMSYNC")
	)
	(via
		(at 364.279434 -232.528364)
		(size 0.4572)
		(drill 0.2032)
		(layers "F.Cu" "B.Cu")
		(net "TP_H_SBLINK6_CPU0_PMSYNC")
	)
	(segment
		(start 362.86948 -232.250234)
		(end 362.86948 -231.714548)
		(width 0.12954)
		(layer "F.Cu")
		(net "TP_H_SBLINK6_CPU0_PMDOWN")
	)
	(segment
		(start 362.869734 -232.250488)
		(end 362.86948 -232.250234)
		(width 0.12954)
		(layer "F.Cu")
		(net "TP_H_SBLINK6_CPU0_PMDOWN")
	)
	(via
		(at 362.86948 -231.714548)
		(size 0.4572)
		(drill 0.2032)
		(layers "F.Cu" "B.Cu")
		(net "TP_H_SBLINK6_CPU0_PMDOWN")
	)
	(segment
		(start 119.628412 -228.994716)
		(end 119.628412 -228.45903)
		(width 0.12954)
		(layer "F.Cu")
		(net "TP_H_SBLINK5_CPU1_PMSYNC")
	)
	(segment
		(start 119.628666 -228.99497)
		(end 119.628412 -228.994716)
		(width 0.12954)
		(layer "F.Cu")
		(net "TP_H_SBLINK5_CPU1_PMSYNC")
	)
	(via
		(at 119.628412 -228.45903)
		(size 0.4572)
		(drill 0.2032)
		(layers "F.Cu" "B.Cu")
		(net "TP_H_SBLINK5_CPU1_PMSYNC")
	)
	(segment
		(start 121.038112 -228.1809)
		(end 121.038366 -228.180646)
		(width 0.12954)
		(layer "F.Cu")
		(net "TP_H_SBLINK5_CPU1_PMDOWN")
	)
	(segment
		(start 121.038366 -228.180646)
		(end 121.038366 -227.64496)
		(width 0.12954)
		(layer "F.Cu")
		(net "TP_H_SBLINK5_CPU1_PMDOWN")
	)
	(via
		(at 121.038366 -227.64496)
		(size 0.4572)
		(drill 0.2032)
		(layers "F.Cu" "B.Cu")
		(net "TP_H_SBLINK5_CPU1_PMDOWN")
	)
	(segment
		(start 367.56848 -228.994716)
		(end 367.56848 -228.45903)
		(width 0.12954)
		(layer "F.Cu")
		(net "TP_H_SBLINK5_CPU0_PMSYNC")
	)
	(segment
		(start 367.568734 -228.99497)
		(end 367.56848 -228.994716)
		(width 0.12954)
		(layer "F.Cu")
		(net "TP_H_SBLINK5_CPU0_PMSYNC")
	)
	(via
		(at 367.56848 -228.45903)
		(size 0.4572)
		(drill 0.2032)
		(layers "F.Cu" "B.Cu")
		(net "TP_H_SBLINK5_CPU0_PMSYNC")
	)
	(segment
		(start 368.978434 -228.180646)
		(end 368.978434 -227.64496)
		(width 0.12954)
		(layer "F.Cu")
		(net "TP_H_SBLINK5_CPU0_PMDOWN")
	)
	(segment
		(start 368.97818 -228.1809)
		(end 368.978434 -228.180646)
		(width 0.12954)
		(layer "F.Cu")
		(net "TP_H_SBLINK5_CPU0_PMDOWN")
	)
	(via
		(at 368.978434 -227.64496)
		(size 0.4572)
		(drill 0.2032)
		(layers "F.Cu" "B.Cu")
		(net "TP_H_SBLINK5_CPU0_PMDOWN")
	)
	(segment
		(start 114.929412 -233.877866)
		(end 114.929412 -233.34218)
		(width 0.12954)
		(layer "F.Cu")
		(net "TP_H_SBLINK4_CPU1_PMSYNC")
	)
	(segment
		(start 114.929666 -233.87812)
		(end 114.929412 -233.877866)
		(width 0.12954)
		(layer "F.Cu")
		(net "TP_H_SBLINK4_CPU1_PMSYNC")
	)
	(via
		(at 114.929412 -233.34218)
		(size 0.4572)
		(drill 0.2032)
		(layers "F.Cu" "B.Cu")
		(net "TP_H_SBLINK4_CPU1_PMSYNC")
	)
	(segment
		(start 114.46002 -233.06405)
		(end 114.46002 -232.528618)
		(width 0.12954)
		(layer "F.Cu")
		(net "TP_H_SBLINK4_CPU1_PMDOWN")
	)
	(segment
		(start 114.46002 -232.528618)
		(end 114.459766 -232.528364)
		(width 0.12954)
		(layer "F.Cu")
		(net "TP_H_SBLINK4_CPU1_PMDOWN")
	)
	(segment
		(start 114.459766 -233.064304)
		(end 114.46002 -233.06405)
		(width 0.12954)
		(layer "F.Cu")
		(net "TP_H_SBLINK4_CPU1_PMDOWN")
	)
	(via
		(at 114.459766 -232.528364)
		(size 0.4572)
		(drill 0.2032)
		(layers "F.Cu" "B.Cu")
		(net "TP_H_SBLINK4_CPU1_PMDOWN")
	)
	(segment
		(start 362.869734 -233.87812)
		(end 362.86948 -233.877866)
		(width 0.12954)
		(layer "F.Cu")
		(net "TP_H_SBLINK4_CPU0_PMSYNC")
	)
	(segment
		(start 362.86948 -233.877866)
		(end 362.86948 -233.34218)
		(width 0.12954)
		(layer "F.Cu")
		(net "TP_H_SBLINK4_CPU0_PMSYNC")
	)
	(via
		(at 362.86948 -233.34218)
		(size 0.4572)
		(drill 0.2032)
		(layers "F.Cu" "B.Cu")
		(net "TP_H_SBLINK4_CPU0_PMSYNC")
	)
	(segment
		(start 362.400088 -232.528618)
		(end 362.399834 -232.528364)
		(width 0.12954)
		(layer "F.Cu")
		(net "TP_H_SBLINK4_CPU0_PMDOWN")
	)
	(segment
		(start 362.400088 -233.06405)
		(end 362.400088 -232.528618)
		(width 0.12954)
		(layer "F.Cu")
		(net "TP_H_SBLINK4_CPU0_PMDOWN")
	)
	(segment
		(start 362.399834 -233.064304)
		(end 362.400088 -233.06405)
		(width 0.12954)
		(layer "F.Cu")
		(net "TP_H_SBLINK4_CPU0_PMDOWN")
	)
	(via
		(at 362.399834 -232.528364)
		(size 0.4572)
		(drill 0.2032)
		(layers "F.Cu" "B.Cu")
		(net "TP_H_SBLINK4_CPU0_PMDOWN")
	)
	(segment
		(start 116.339366 -234.691936)
		(end 116.339366 -234.15625)
		(width 0.12954)
		(layer "F.Cu")
		(net "TP_H_SBLINK3_CPU1_PMSYNC")
	)
	(segment
		(start 116.339112 -234.69219)
		(end 116.339366 -234.691936)
		(width 0.12954)
		(layer "F.Cu")
		(net "TP_H_SBLINK3_CPU1_PMSYNC")
	)
	(via
		(at 116.339366 -234.15625)
		(size 0.4572)
		(drill 0.2032)
		(layers "F.Cu" "B.Cu")
		(net "TP_H_SBLINK3_CPU1_PMSYNC")
	)
	(segment
		(start 118.218712 -234.69219)
		(end 118.218966 -234.691936)
		(width 0.12954)
		(layer "F.Cu")
		(net "TP_H_SBLINK3_CPU1_PMDOWN")
	)
	(segment
		(start 118.218966 -234.691936)
		(end 118.218966 -234.15625)
		(width 0.12954)
		(layer "F.Cu")
		(net "TP_H_SBLINK3_CPU1_PMDOWN")
	)
	(via
		(at 118.218966 -234.15625)
		(size 0.4572)
		(drill 0.2032)
		(layers "F.Cu" "B.Cu")
		(net "TP_H_SBLINK3_CPU1_PMDOWN")
	)
	(segment
		(start 364.279434 -234.691936)
		(end 364.279434 -234.15625)
		(width 0.12954)
		(layer "F.Cu")
		(net "TP_H_SBLINK3_CPU0_PMSYNC")
	)
	(segment
		(start 364.27918 -234.69219)
		(end 364.279434 -234.691936)
		(width 0.12954)
		(layer "F.Cu")
		(net "TP_H_SBLINK3_CPU0_PMSYNC")
	)
	(via
		(at 364.279434 -234.15625)
		(size 0.4572)
		(drill 0.2032)
		(layers "F.Cu" "B.Cu")
		(net "TP_H_SBLINK3_CPU0_PMSYNC")
	)
	(segment
		(start 366.159034 -234.691936)
		(end 366.159034 -234.15625)
		(width 0.12954)
		(layer "F.Cu")
		(net "TP_H_SBLINK3_CPU0_PMDOWN")
	)
	(segment
		(start 366.15878 -234.69219)
		(end 366.159034 -234.691936)
		(width 0.12954)
		(layer "F.Cu")
		(net "TP_H_SBLINK3_CPU0_PMDOWN")
	)
	(via
		(at 366.159034 -234.15625)
		(size 0.4572)
		(drill 0.2032)
		(layers "F.Cu" "B.Cu")
		(net "TP_H_SBLINK3_CPU0_PMDOWN")
	)
	(segment
		(start 117.749066 -233.87812)
		(end 117.748812 -233.877866)
		(width 0.12954)
		(layer "F.Cu")
		(net "TP_H_SBLINK2_CPU1_PMSYNC")
	)
	(segment
		(start 117.748812 -233.877866)
		(end 117.748812 -233.34218)
		(width 0.12954)
		(layer "F.Cu")
		(net "TP_H_SBLINK2_CPU1_PMSYNC")
	)
	(via
		(at 117.748812 -233.34218)
		(size 0.4572)
		(drill 0.2032)
		(layers "F.Cu" "B.Cu")
		(net "TP_H_SBLINK2_CPU1_PMSYNC")
	)
	(segment
		(start 119.158512 -234.69219)
		(end 119.158766 -234.691936)
		(width 0.12954)
		(layer "F.Cu")
		(net "TP_H_SBLINK2_CPU1_PMDOWN")
	)
	(segment
		(start 119.158766 -234.691936)
		(end 119.158766 -234.15625)
		(width 0.12954)
		(layer "F.Cu")
		(net "TP_H_SBLINK2_CPU1_PMDOWN")
	)
	(via
		(at 119.158766 -234.15625)
		(size 0.4572)
		(drill 0.2032)
		(layers "F.Cu" "B.Cu")
		(net "TP_H_SBLINK2_CPU1_PMDOWN")
	)
	(segment
		(start 365.689134 -233.87812)
		(end 365.68888 -233.877866)
		(width 0.12954)
		(layer "F.Cu")
		(net "TP_H_SBLINK2_CPU0_PMSYNC")
	)
	(segment
		(start 365.68888 -233.877866)
		(end 365.68888 -233.34218)
		(width 0.12954)
		(layer "F.Cu")
		(net "TP_H_SBLINK2_CPU0_PMSYNC")
	)
	(via
		(at 365.68888 -233.34218)
		(size 0.4572)
		(drill 0.2032)
		(layers "F.Cu" "B.Cu")
		(net "TP_H_SBLINK2_CPU0_PMSYNC")
	)
	(segment
		(start 367.09858 -234.69219)
		(end 367.098834 -234.691936)
		(width 0.12954)
		(layer "F.Cu")
		(net "TP_H_SBLINK2_CPU0_PMDOWN")
	)
	(segment
		(start 367.098834 -234.691936)
		(end 367.098834 -234.15625)
		(width 0.12954)
		(layer "F.Cu")
		(net "TP_H_SBLINK2_CPU0_PMDOWN")
	)
	(via
		(at 367.098834 -234.15625)
		(size 0.4572)
		(drill 0.2032)
		(layers "F.Cu" "B.Cu")
		(net "TP_H_SBLINK2_CPU0_PMDOWN")
	)
	(segment
		(start 122.448066 -245.27256)
		(end 122.447558 -244.73662)
		(width 0.12954)
		(layer "F.Cu")
		(net "TP_H_CPU1_PMSYNC_PCH_INTRP_R")
	)
	(segment
		(start 122.447558 -244.73662)
		(end 122.447812 -244.736366)
		(width 0.12954)
		(layer "F.Cu")
		(net "TP_H_CPU1_PMSYNC_PCH_INTRP_R")
	)
	(via
		(at 137.510012 -241.793776)
		(size 0.6604)
		(drill 0.3302)
		(layers "F.Cu" "B.Cu")
		(net "TP_H_CPU1_PMSYNC_PCH_INTRP_R")
	)
	(via
		(at 122.447812 -244.736366)
		(size 0.4572)
		(drill 0.2032)
		(layers "F.Cu" "B.Cu")
		(net "TP_H_CPU1_PMSYNC_PCH_INTRP_R")
	)
	(segment
		(start 135.270494 -244.344444)
		(end 135.06196 -244.552978)
		(width 0.0889)
		(layer "B.Cu")
		(net "TP_H_CPU1_PMSYNC_PCH_INTRP_R")
	)
	(segment
		(start 125.465078 -245.054882)
		(end 125.454664 -245.060978)
		(width 0.0889)
		(layer "B.Cu")
		(net "TP_H_CPU1_PMSYNC_PCH_INTRP_R")
	)
	(segment
		(start 123.200414 -245.060978)
		(end 123.159012 -245.03634)
		(width 0.0889)
		(layer "B.Cu")
		(net "TP_H_CPU1_PMSYNC_PCH_INTRP_R")
	)
	(segment
		(start 126.959868 -245.060978)
		(end 126.949454 -245.054882)
		(width 0.0889)
		(layer "B.Cu")
		(net "TP_H_CPU1_PMSYNC_PCH_INTRP_R")
	)
	(segment
		(start 123.159012 -245.03634)
		(end 122.452892 -244.734334)
		(width 0.0889)
		(layer "B.Cu")
		(net "TP_H_CPU1_PMSYNC_PCH_INTRP_R")
	)
	(segment
		(start 136.941052 -243.692172)
		(end 136.28878 -244.344444)
		(width 0.12954)
		(layer "B.Cu")
		(net "TP_H_CPU1_PMSYNC_PCH_INTRP_R")
	)
	(segment
		(start 128.839214 -245.060978)
		(end 128.824482 -245.052342)
		(width 0.0889)
		(layer "B.Cu")
		(net "TP_H_CPU1_PMSYNC_PCH_INTRP_R")
	)
	(segment
		(start 124.140214 -245.060978)
		(end 124.125482 -245.052342)
		(width 0.0889)
		(layer "B.Cu")
		(net "TP_H_CPU1_PMSYNC_PCH_INTRP_R")
	)
	(segment
		(start 135.06196 -244.912388)
		(end 134.962138 -245.01221)
		(width 0.0889)
		(layer "B.Cu")
		(net "TP_H_CPU1_PMSYNC_PCH_INTRP_R")
	)
	(segment
		(start 130.718814 -245.060978)
		(end 130.704082 -245.052342)
		(width 0.0889)
		(layer "B.Cu")
		(net "TP_H_CPU1_PMSYNC_PCH_INTRP_R")
	)
	(segment
		(start 129.779014 -245.060978)
		(end 129.764282 -245.052342)
		(width 0.0889)
		(layer "B.Cu")
		(net "TP_H_CPU1_PMSYNC_PCH_INTRP_R")
	)
	(segment
		(start 125.080268 -245.060978)
		(end 125.069854 -245.054882)
		(width 0.0889)
		(layer "B.Cu")
		(net "TP_H_CPU1_PMSYNC_PCH_INTRP_R")
	)
	(segment
		(start 132.043678 -245.054882)
		(end 132.033264 -245.060978)
		(width 0.0889)
		(layer "B.Cu")
		(net "TP_H_CPU1_PMSYNC_PCH_INTRP_R")
	)
	(segment
		(start 135.06196 -244.552978)
		(end 135.06196 -244.912388)
		(width 0.0889)
		(layer "B.Cu")
		(net "TP_H_CPU1_PMSYNC_PCH_INTRP_R")
	)
	(segment
		(start 137.510012 -241.793776)
		(end 136.941052 -242.362736)
		(width 0.12954)
		(layer "B.Cu")
		(net "TP_H_CPU1_PMSYNC_PCH_INTRP_R")
	)
	(segment
		(start 136.28878 -244.344444)
		(end 135.270494 -244.344444)
		(width 0.0889)
		(layer "B.Cu")
		(net "TP_H_CPU1_PMSYNC_PCH_INTRP_R")
	)
	(segment
		(start 127.344678 -245.054882)
		(end 127.334264 -245.060978)
		(width 0.0889)
		(layer "B.Cu")
		(net "TP_H_CPU1_PMSYNC_PCH_INTRP_R")
	)
	(segment
		(start 136.941052 -242.362736)
		(end 136.941052 -243.692172)
		(width 0.12954)
		(layer "B.Cu")
		(net "TP_H_CPU1_PMSYNC_PCH_INTRP_R")
	)
	(segment
		(start 134.478014 -245.060978)
		(end 134.4676 -245.054882)
		(width 0.0889)
		(layer "B.Cu")
		(net "TP_H_CPU1_PMSYNC_PCH_INTRP_R")
	)
	(segment
		(start 133.538468 -245.060978)
		(end 133.528054 -245.054882)
		(width 0.0889)
		(layer "B.Cu")
		(net "TP_H_CPU1_PMSYNC_PCH_INTRP_R")
	)
	(segment
		(start 122.452892 -244.734334)
		(end 122.447812 -244.736366)
		(width 0.0889)
		(layer "B.Cu")
		(net "TP_H_CPU1_PMSYNC_PCH_INTRP_R")
	)
	(segment
		(start 131.658868 -245.060978)
		(end 131.648454 -245.054882)
		(width 0.0889)
		(layer "B.Cu")
		(net "TP_H_CPU1_PMSYNC_PCH_INTRP_R")
	)
	(arc
		(start 130.704082 -245.052342)
		(mid 130.427641 -244.985176)
		(end 130.15341 -245.060978)
		(width 0.0889)
		(layer "B.Cu")
		(net "TP_H_CPU1_PMSYNC_PCH_INTRP_R")
	)
	(arc
		(start 124.51461 -245.060978)
		(mid 124.327412 -245.111121)
		(end 124.140214 -245.060978)
		(width 0.0889)
		(layer "B.Cu")
		(net "TP_H_CPU1_PMSYNC_PCH_INTRP_R")
	)
	(arc
		(start 123.57481 -245.060978)
		(mid 123.387612 -245.111121)
		(end 123.200414 -245.060978)
		(width 0.0889)
		(layer "B.Cu")
		(net "TP_H_CPU1_PMSYNC_PCH_INTRP_R")
	)
	(arc
		(start 128.27381 -245.060978)
		(mid 128.086612 -245.111121)
		(end 127.899414 -245.060978)
		(width 0.0889)
		(layer "B.Cu")
		(net "TP_H_CPU1_PMSYNC_PCH_INTRP_R")
	)
	(arc
		(start 126.39421 -245.060978)
		(mid 126.207012 -245.111121)
		(end 126.019814 -245.060978)
		(width 0.0889)
		(layer "B.Cu")
		(net "TP_H_CPU1_PMSYNC_PCH_INTRP_R")
	)
	(arc
		(start 134.4676 -245.054882)
		(mid 134.189422 -244.98519)
		(end 133.912864 -245.060978)
		(width 0.0889)
		(layer "B.Cu")
		(net "TP_H_CPU1_PMSYNC_PCH_INTRP_R")
	)
	(arc
		(start 125.454664 -245.060978)
		(mid 125.267466 -245.111121)
		(end 125.080268 -245.060978)
		(width 0.0889)
		(layer "B.Cu")
		(net "TP_H_CPU1_PMSYNC_PCH_INTRP_R")
	)
	(arc
		(start 128.824482 -245.052342)
		(mid 128.548041 -244.985176)
		(end 128.27381 -245.060978)
		(width 0.0889)
		(layer "B.Cu")
		(net "TP_H_CPU1_PMSYNC_PCH_INTRP_R")
	)
	(arc
		(start 131.09321 -245.060978)
		(mid 130.906012 -245.111121)
		(end 130.718814 -245.060978)
		(width 0.0889)
		(layer "B.Cu")
		(net "TP_H_CPU1_PMSYNC_PCH_INTRP_R")
	)
	(arc
		(start 125.069854 -245.054882)
		(mid 124.791422 -244.985068)
		(end 124.51461 -245.060978)
		(width 0.0889)
		(layer "B.Cu")
		(net "TP_H_CPU1_PMSYNC_PCH_INTRP_R")
	)
	(arc
		(start 131.648454 -245.054882)
		(mid 131.370022 -244.985068)
		(end 131.09321 -245.060978)
		(width 0.0889)
		(layer "B.Cu")
		(net "TP_H_CPU1_PMSYNC_PCH_INTRP_R")
	)
	(arc
		(start 127.334264 -245.060978)
		(mid 127.147066 -245.111121)
		(end 126.959868 -245.060978)
		(width 0.0889)
		(layer "B.Cu")
		(net "TP_H_CPU1_PMSYNC_PCH_INTRP_R")
	)
	(arc
		(start 130.15341 -245.060978)
		(mid 129.966212 -245.111121)
		(end 129.779014 -245.060978)
		(width 0.0889)
		(layer "B.Cu")
		(net "TP_H_CPU1_PMSYNC_PCH_INTRP_R")
	)
	(arc
		(start 129.21361 -245.060978)
		(mid 129.026412 -245.111121)
		(end 128.839214 -245.060978)
		(width 0.0889)
		(layer "B.Cu")
		(net "TP_H_CPU1_PMSYNC_PCH_INTRP_R")
	)
	(arc
		(start 132.598414 -245.060978)
		(mid 132.321855 -244.985269)
		(end 132.043678 -245.054882)
		(width 0.0889)
		(layer "B.Cu")
		(net "TP_H_CPU1_PMSYNC_PCH_INTRP_R")
	)
	(arc
		(start 129.764282 -245.052342)
		(mid 129.487841 -244.985176)
		(end 129.21361 -245.060978)
		(width 0.0889)
		(layer "B.Cu")
		(net "TP_H_CPU1_PMSYNC_PCH_INTRP_R")
	)
	(arc
		(start 126.019814 -245.060978)
		(mid 125.743255 -244.985269)
		(end 125.465078 -245.054882)
		(width 0.0889)
		(layer "B.Cu")
		(net "TP_H_CPU1_PMSYNC_PCH_INTRP_R")
	)
	(arc
		(start 127.899414 -245.060978)
		(mid 127.622855 -244.985269)
		(end 127.344678 -245.054882)
		(width 0.0889)
		(layer "B.Cu")
		(net "TP_H_CPU1_PMSYNC_PCH_INTRP_R")
	)
	(arc
		(start 126.949454 -245.054882)
		(mid 126.671022 -244.985068)
		(end 126.39421 -245.060978)
		(width 0.0889)
		(layer "B.Cu")
		(net "TP_H_CPU1_PMSYNC_PCH_INTRP_R")
	)
	(arc
		(start 133.528054 -245.054882)
		(mid 133.249622 -244.985068)
		(end 132.97281 -245.060978)
		(width 0.0889)
		(layer "B.Cu")
		(net "TP_H_CPU1_PMSYNC_PCH_INTRP_R")
	)
	(arc
		(start 133.912864 -245.060978)
		(mid 133.725666 -245.111121)
		(end 133.538468 -245.060978)
		(width 0.0889)
		(layer "B.Cu")
		(net "TP_H_CPU1_PMSYNC_PCH_INTRP_R")
	)
	(arc
		(start 134.85241 -245.060978)
		(mid 134.665212 -245.111121)
		(end 134.478014 -245.060978)
		(width 0.0889)
		(layer "B.Cu")
		(net "TP_H_CPU1_PMSYNC_PCH_INTRP_R")
	)
	(arc
		(start 134.962138 -245.01221)
		(mid 134.905975 -245.033671)
		(end 134.85241 -245.060978)
		(width 0.0889)
		(layer "B.Cu")
		(net "TP_H_CPU1_PMSYNC_PCH_INTRP_R")
	)
	(arc
		(start 132.97281 -245.060978)
		(mid 132.785612 -245.111121)
		(end 132.598414 -245.060978)
		(width 0.0889)
		(layer "B.Cu")
		(net "TP_H_CPU1_PMSYNC_PCH_INTRP_R")
	)
	(arc
		(start 124.125482 -245.052342)
		(mid 123.849041 -244.985176)
		(end 123.57481 -245.060978)
		(width 0.0889)
		(layer "B.Cu")
		(net "TP_H_CPU1_PMSYNC_PCH_INTRP_R")
	)
	(arc
		(start 132.033264 -245.060978)
		(mid 131.846066 -245.111121)
		(end 131.658868 -245.060978)
		(width 0.0889)
		(layer "B.Cu")
		(net "TP_H_CPU1_PMSYNC_PCH_INTRP_R")
	)
	(segment
		(start 121.978166 -246.086376)
		(end 121.978166 -245.55069)
		(width 0.12954)
		(layer "F.Cu")
		(net "TP_H_CPU1_PMDOWN_PCH_R")
	)
	(segment
		(start 121.977912 -246.08663)
		(end 121.978166 -246.086376)
		(width 0.12954)
		(layer "F.Cu")
		(net "TP_H_CPU1_PMDOWN_PCH_R")
	)
	(via
		(at 138.627612 -240.91773)
		(size 0.6604)
		(drill 0.3302)
		(layers "F.Cu" "B.Cu")
		(net "TP_H_CPU1_PMDOWN_PCH_R")
	)
	(via
		(at 121.978166 -245.55069)
		(size 0.4572)
		(drill 0.2032)
		(layers "F.Cu" "B.Cu")
		(net "TP_H_CPU1_PMDOWN_PCH_R")
	)
	(segment
		(start 135.93572 -245.023386)
		(end 135.732774 -245.226332)
		(width 0.0889)
		(layer "B.Cu")
		(net "TP_H_CPU1_PMDOWN_PCH_R")
	)
	(segment
		(start 125.549914 -245.226332)
		(end 125.5395 -245.232428)
		(width 0.0889)
		(layer "B.Cu")
		(net "TP_H_CPU1_PMDOWN_PCH_R")
	)
	(segment
		(start 127.814324 -245.232428)
		(end 127.80391 -245.226332)
		(width 0.0889)
		(layer "B.Cu")
		(net "TP_H_CPU1_PMDOWN_PCH_R")
	)
	(segment
		(start 123.119896 -245.234968)
		(end 123.105164 -245.226332)
		(width 0.0889)
		(layer "B.Cu")
		(net "TP_H_CPU1_PMDOWN_PCH_R")
	)
	(segment
		(start 122.735594 -245.223284)
		(end 122.730514 -245.226078)
		(width 0.0889)
		(layer "B.Cu")
		(net "TP_H_CPU1_PMDOWN_PCH_R")
	)
	(segment
		(start 136.281922 -245.023386)
		(end 135.93572 -245.023386)
		(width 0.0889)
		(layer "B.Cu")
		(net "TP_H_CPU1_PMDOWN_PCH_R")
	)
	(segment
		(start 123.104402 -245.226078)
		(end 123.099322 -245.223284)
		(width 0.0889)
		(layer "B.Cu")
		(net "TP_H_CPU1_PMDOWN_PCH_R")
	)
	(segment
		(start 123.105164 -245.226332)
		(end 123.104402 -245.226078)
		(width 0.0889)
		(layer "B.Cu")
		(net "TP_H_CPU1_PMDOWN_PCH_R")
	)
	(segment
		(start 136.406636 -245.1481)
		(end 136.281922 -245.023386)
		(width 0.0889)
		(layer "B.Cu")
		(net "TP_H_CPU1_PMDOWN_PCH_R")
	)
	(segment
		(start 138.627612 -240.91773)
		(end 138.627612 -241.47018)
		(width 0.12954)
		(layer "B.Cu")
		(net "TP_H_CPU1_PMDOWN_PCH_R")
	)
	(segment
		(start 134.397496 -245.234968)
		(end 134.382764 -245.226332)
		(width 0.0889)
		(layer "B.Cu")
		(net "TP_H_CPU1_PMDOWN_PCH_R")
	)
	(segment
		(start 129.698496 -245.234968)
		(end 129.683764 -245.226332)
		(width 0.0889)
		(layer "B.Cu")
		(net "TP_H_CPU1_PMDOWN_PCH_R")
	)
	(segment
		(start 137.525252 -242.57254)
		(end 137.525252 -244.348254)
		(width 0.12954)
		(layer "B.Cu")
		(net "TP_H_CPU1_PMDOWN_PCH_R")
	)
	(segment
		(start 137.525252 -244.348254)
		(end 136.725406 -245.1481)
		(width 0.12954)
		(layer "B.Cu")
		(net "TP_H_CPU1_PMDOWN_PCH_R")
	)
	(segment
		(start 138.627612 -241.47018)
		(end 137.525252 -242.57254)
		(width 0.12954)
		(layer "B.Cu")
		(net "TP_H_CPU1_PMDOWN_PCH_R")
	)
	(segment
		(start 132.513324 -245.232428)
		(end 132.50291 -245.226332)
		(width 0.0889)
		(layer "B.Cu")
		(net "TP_H_CPU1_PMDOWN_PCH_R")
	)
	(segment
		(start 128.758696 -245.234968)
		(end 128.743964 -245.226332)
		(width 0.0889)
		(layer "B.Cu")
		(net "TP_H_CPU1_PMDOWN_PCH_R")
	)
	(segment
		(start 127.429514 -245.226332)
		(end 127.4191 -245.232428)
		(width 0.0889)
		(layer "B.Cu")
		(net "TP_H_CPU1_PMDOWN_PCH_R")
	)
	(segment
		(start 122.730514 -245.226078)
		(end 121.980198 -245.545864)
		(width 0.0889)
		(layer "B.Cu")
		(net "TP_H_CPU1_PMDOWN_PCH_R")
	)
	(segment
		(start 121.980198 -245.545864)
		(end 121.978166 -245.55069)
		(width 0.0889)
		(layer "B.Cu")
		(net "TP_H_CPU1_PMDOWN_PCH_R")
	)
	(segment
		(start 130.638296 -245.234968)
		(end 130.623564 -245.226332)
		(width 0.0889)
		(layer "B.Cu")
		(net "TP_H_CPU1_PMDOWN_PCH_R")
	)
	(segment
		(start 135.732774 -245.226332)
		(end 135.322564 -245.226332)
		(width 0.0889)
		(layer "B.Cu")
		(net "TP_H_CPU1_PMDOWN_PCH_R")
	)
	(segment
		(start 124.059696 -245.234968)
		(end 124.044964 -245.226332)
		(width 0.0889)
		(layer "B.Cu")
		(net "TP_H_CPU1_PMDOWN_PCH_R")
	)
	(segment
		(start 125.934724 -245.232428)
		(end 125.92431 -245.226332)
		(width 0.0889)
		(layer "B.Cu")
		(net "TP_H_CPU1_PMDOWN_PCH_R")
	)
	(segment
		(start 136.725406 -245.1481)
		(end 136.406636 -245.1481)
		(width 0.0889)
		(layer "B.Cu")
		(net "TP_H_CPU1_PMDOWN_PCH_R")
	)
	(segment
		(start 132.128514 -245.226332)
		(end 132.1181 -245.232428)
		(width 0.0889)
		(layer "B.Cu")
		(net "TP_H_CPU1_PMDOWN_PCH_R")
	)
	(arc
		(start 127.4191 -245.232428)
		(mid 127.140922 -245.30212)
		(end 126.864364 -245.226332)
		(width 0.0889)
		(layer "B.Cu")
		(net "TP_H_CPU1_PMDOWN_PCH_R")
	)
	(arc
		(start 131.563364 -245.226332)
		(mid 131.376166 -245.176189)
		(end 131.188968 -245.226332)
		(width 0.0889)
		(layer "B.Cu")
		(net "TP_H_CPU1_PMDOWN_PCH_R")
	)
	(arc
		(start 132.50291 -245.226332)
		(mid 132.315712 -245.176189)
		(end 132.128514 -245.226332)
		(width 0.0889)
		(layer "B.Cu")
		(net "TP_H_CPU1_PMDOWN_PCH_R")
	)
	(arc
		(start 124.984764 -245.226332)
		(mid 124.797566 -245.176189)
		(end 124.610368 -245.226332)
		(width 0.0889)
		(layer "B.Cu")
		(net "TP_H_CPU1_PMDOWN_PCH_R")
	)
	(arc
		(start 131.188968 -245.226332)
		(mid 130.914739 -245.302257)
		(end 130.638296 -245.234968)
		(width 0.0889)
		(layer "B.Cu")
		(net "TP_H_CPU1_PMDOWN_PCH_R")
	)
	(arc
		(start 134.008368 -245.226332)
		(mid 133.725666 -245.302074)
		(end 133.442964 -245.226332)
		(width 0.0889)
		(layer "B.Cu")
		(net "TP_H_CPU1_PMDOWN_PCH_R")
	)
	(arc
		(start 124.610368 -245.226332)
		(mid 124.336139 -245.302257)
		(end 124.059696 -245.234968)
		(width 0.0889)
		(layer "B.Cu")
		(net "TP_H_CPU1_PMDOWN_PCH_R")
	)
	(arc
		(start 133.442964 -245.226332)
		(mid 133.255766 -245.176189)
		(end 133.068568 -245.226332)
		(width 0.0889)
		(layer "B.Cu")
		(net "TP_H_CPU1_PMDOWN_PCH_R")
	)
	(arc
		(start 125.5395 -245.232428)
		(mid 125.261322 -245.30212)
		(end 124.984764 -245.226332)
		(width 0.0889)
		(layer "B.Cu")
		(net "TP_H_CPU1_PMDOWN_PCH_R")
	)
	(arc
		(start 124.044964 -245.226332)
		(mid 123.857766 -245.176189)
		(end 123.670568 -245.226332)
		(width 0.0889)
		(layer "B.Cu")
		(net "TP_H_CPU1_PMDOWN_PCH_R")
	)
	(arc
		(start 128.369568 -245.226332)
		(mid 128.092755 -245.302168)
		(end 127.814324 -245.232428)
		(width 0.0889)
		(layer "B.Cu")
		(net "TP_H_CPU1_PMDOWN_PCH_R")
	)
	(arc
		(start 130.249168 -245.226332)
		(mid 129.974939 -245.302257)
		(end 129.698496 -245.234968)
		(width 0.0889)
		(layer "B.Cu")
		(net "TP_H_CPU1_PMDOWN_PCH_R")
	)
	(arc
		(start 129.683764 -245.226332)
		(mid 129.496566 -245.176189)
		(end 129.309368 -245.226332)
		(width 0.0889)
		(layer "B.Cu")
		(net "TP_H_CPU1_PMDOWN_PCH_R")
	)
	(arc
		(start 134.948168 -245.226332)
		(mid 134.673939 -245.302257)
		(end 134.397496 -245.234968)
		(width 0.0889)
		(layer "B.Cu")
		(net "TP_H_CPU1_PMDOWN_PCH_R")
	)
	(arc
		(start 128.743964 -245.226332)
		(mid 128.556766 -245.176189)
		(end 128.369568 -245.226332)
		(width 0.0889)
		(layer "B.Cu")
		(net "TP_H_CPU1_PMDOWN_PCH_R")
	)
	(arc
		(start 132.1181 -245.232428)
		(mid 131.839922 -245.30212)
		(end 131.563364 -245.226332)
		(width 0.0889)
		(layer "B.Cu")
		(net "TP_H_CPU1_PMDOWN_PCH_R")
	)
	(arc
		(start 123.099322 -245.223284)
		(mid 122.917458 -245.174583)
		(end 122.735594 -245.223284)
		(width 0.0889)
		(layer "B.Cu")
		(net "TP_H_CPU1_PMDOWN_PCH_R")
	)
	(arc
		(start 123.670568 -245.226332)
		(mid 123.396339 -245.302257)
		(end 123.119896 -245.234968)
		(width 0.0889)
		(layer "B.Cu")
		(net "TP_H_CPU1_PMDOWN_PCH_R")
	)
	(arc
		(start 127.80391 -245.226332)
		(mid 127.616712 -245.176189)
		(end 127.429514 -245.226332)
		(width 0.0889)
		(layer "B.Cu")
		(net "TP_H_CPU1_PMDOWN_PCH_R")
	)
	(arc
		(start 135.322564 -245.226332)
		(mid 135.135366 -245.176189)
		(end 134.948168 -245.226332)
		(width 0.0889)
		(layer "B.Cu")
		(net "TP_H_CPU1_PMDOWN_PCH_R")
	)
	(arc
		(start 129.309368 -245.226332)
		(mid 129.035139 -245.302257)
		(end 128.758696 -245.234968)
		(width 0.0889)
		(layer "B.Cu")
		(net "TP_H_CPU1_PMDOWN_PCH_R")
	)
	(arc
		(start 134.382764 -245.226332)
		(mid 134.195566 -245.176189)
		(end 134.008368 -245.226332)
		(width 0.0889)
		(layer "B.Cu")
		(net "TP_H_CPU1_PMDOWN_PCH_R")
	)
	(arc
		(start 125.92431 -245.226332)
		(mid 125.737112 -245.176189)
		(end 125.549914 -245.226332)
		(width 0.0889)
		(layer "B.Cu")
		(net "TP_H_CPU1_PMDOWN_PCH_R")
	)
	(arc
		(start 130.623564 -245.226332)
		(mid 130.436366 -245.176189)
		(end 130.249168 -245.226332)
		(width 0.0889)
		(layer "B.Cu")
		(net "TP_H_CPU1_PMDOWN_PCH_R")
	)
	(arc
		(start 126.864364 -245.226332)
		(mid 126.677166 -245.176189)
		(end 126.489968 -245.226332)
		(width 0.0889)
		(layer "B.Cu")
		(net "TP_H_CPU1_PMDOWN_PCH_R")
	)
	(arc
		(start 126.489968 -245.226332)
		(mid 126.213155 -245.302168)
		(end 125.934724 -245.232428)
		(width 0.0889)
		(layer "B.Cu")
		(net "TP_H_CPU1_PMDOWN_PCH_R")
	)
	(arc
		(start 133.068568 -245.226332)
		(mid 132.791755 -245.302168)
		(end 132.513324 -245.232428)
		(width 0.0889)
		(layer "B.Cu")
		(net "TP_H_CPU1_PMDOWN_PCH_R")
	)
	(segment
		(start 329.165966 -51.739546)
		(end 329.437746 -51.269646)
		(width 0.12954)
		(layer "F.Cu")
		(net "TP_GPP_M_12")
	)
	(via
		(at 329.437746 -51.269646)
		(size 0.4572)
		(drill 0.2032)
		(layers "F.Cu" "B.Cu")
		(net "TP_GPP_M_12")
	)
	(segment
		(start 102.712266 -228.99497)
		(end 102.712266 -228.459284)
		(width 0.12954)
		(layer "F.Cu")
		(net "TP_FM_WAKE_CPU1_N")
	)
	(segment
		(start 102.712266 -228.459284)
		(end 102.712012 -228.45903)
		(width 0.12954)
		(layer "F.Cu")
		(net "TP_FM_WAKE_CPU1_N")
	)
	(via
		(at 102.712012 -228.45903)
		(size 0.4572)
		(drill 0.2032)
		(layers "F.Cu" "B.Cu")
		(net "TP_FM_WAKE_CPU1_N")
	)
	(segment
		(start 117.278912 -231.436418)
		(end 117.278912 -230.900732)
		(width 0.12954)
		(layer "F.Cu")
		(net "TP_FM_SYS_RST_CPU1_N")
	)
	(segment
		(start 117.278912 -230.900732)
		(end 117.279166 -230.900478)
		(width 0.12954)
		(layer "F.Cu")
		(net "TP_FM_SYS_RST_CPU1_N")
	)
	(via
		(at 117.279166 -230.900478)
		(size 0.4572)
		(drill 0.2032)
		(layers "F.Cu" "B.Cu")
		(net "TP_FM_SYS_RST_CPU1_N")
	)
	(segment
		(start 350.652334 -228.99497)
		(end 350.652334 -228.459284)
		(width 0.12954)
		(layer "F.Cu")
		(net "TP_FM_IBL_WAKE_CPU0_N")
	)
	(segment
		(start 350.652334 -228.459284)
		(end 350.65208 -228.45903)
		(width 0.12954)
		(layer "F.Cu")
		(net "TP_FM_IBL_WAKE_CPU0_N")
	)
	(via
		(at 350.65208 -228.45903)
		(size 0.4572)
		(drill 0.2032)
		(layers "F.Cu" "B.Cu")
		(net "TP_FM_IBL_WAKE_CPU0_N")
	)
	(segment
		(start 365.21898 -230.900732)
		(end 365.219234 -230.900478)
		(width 0.12954)
		(layer "F.Cu")
		(net "TP_FM_IBL_SYS_RST_CPU0_N")
	)
	(segment
		(start 365.21898 -231.436418)
		(end 365.21898 -230.900732)
		(width 0.12954)
		(layer "F.Cu")
		(net "TP_FM_IBL_SYS_RST_CPU0_N")
	)
	(via
		(at 365.219234 -230.900478)
		(size 0.4572)
		(drill 0.2032)
		(layers "F.Cu" "B.Cu")
		(net "TP_FM_IBL_SYS_RST_CPU0_N")
	)
	(segment
		(start 121.508012 -230.622348)
		(end 121.508012 -230.086662)
		(width 0.12954)
		(layer "F.Cu")
		(net "TP_FM_IBL_SLPS5_CPU1_R_N")
	)
	(segment
		(start 121.508266 -230.622602)
		(end 121.508012 -230.622348)
		(width 0.12954)
		(layer "F.Cu")
		(net "TP_FM_IBL_SLPS5_CPU1_R_N")
	)
	(via
		(at 121.508012 -230.086662)
		(size 0.4572)
		(drill 0.2032)
		(layers "F.Cu" "B.Cu")
		(net "TP_FM_IBL_SLPS5_CPU1_R_N")
	)
	(segment
		(start 118.688866 -230.622602)
		(end 118.688866 -230.086916)
		(width 0.12954)
		(layer "F.Cu")
		(net "TP_FM_IBL_SLPS4_CPU1_R_N")
	)
	(segment
		(start 118.688866 -230.086916)
		(end 118.688612 -230.086662)
		(width 0.12954)
		(layer "F.Cu")
		(net "TP_FM_IBL_SLPS4_CPU1_R_N")
	)
	(via
		(at 118.688612 -230.086662)
		(size 0.4572)
		(drill 0.2032)
		(layers "F.Cu" "B.Cu")
		(net "TP_FM_IBL_SLPS4_CPU1_R_N")
	)
	(segment
		(start 119.628666 -230.086916)
		(end 119.628412 -230.086662)
		(width 0.12954)
		(layer "F.Cu")
		(net "TP_FM_IBL_SLPS3_CPU1_R_N")
	)
	(segment
		(start 119.628666 -230.622602)
		(end 119.628666 -230.086916)
		(width 0.12954)
		(layer "F.Cu")
		(net "TP_FM_IBL_SLPS3_CPU1_R_N")
	)
	(via
		(at 119.628412 -230.086662)
		(size 0.4572)
		(drill 0.2032)
		(layers "F.Cu" "B.Cu")
		(net "TP_FM_IBL_SLPS3_CPU1_R_N")
	)
	(segment
		(start 117.278912 -232.528618)
		(end 117.279166 -232.528364)
		(width 0.12954)
		(layer "F.Cu")
		(net "TP_FM_IBL_PWRBTN_CPU1_N")
	)
	(segment
		(start 117.278912 -233.064304)
		(end 117.278912 -232.528618)
		(width 0.12954)
		(layer "F.Cu")
		(net "TP_FM_IBL_PWRBTN_CPU1_N")
	)
	(via
		(at 117.279166 -232.528364)
		(size 0.4572)
		(drill 0.2032)
		(layers "F.Cu" "B.Cu")
		(net "TP_FM_IBL_PWRBTN_CPU1_N")
	)
	(via
		(at 147.396708 -230.76789)
		(size 0.6604)
		(drill 0.3302)
		(layers "F.Cu" "B.Cu")
		(net "TP_FM_IBL_PWRBTN_CPU1_N")
	)
	(segment
		(start 117.143784 -232.179368)
		(end 117.122702 -232.257346)
		(width 0.0889)
		(layer "B.Cu")
		(net "TP_FM_IBL_PWRBTN_CPU1_N")
	)
	(segment
		(start 130.638296 -232.212642)
		(end 130.623564 -232.204006)
		(width 0.0889)
		(layer "B.Cu")
		(net "TP_FM_IBL_PWRBTN_CPU1_N")
	)
	(segment
		(start 119.911368 -232.204006)
		(end 119.896636 -232.212642)
		(width 0.0889)
		(layer "B.Cu")
		(net "TP_FM_IBL_PWRBTN_CPU1_N")
	)
	(segment
		(start 124.999496 -232.212642)
		(end 124.984764 -232.204006)
		(width 0.0889)
		(layer "B.Cu")
		(net "TP_FM_IBL_PWRBTN_CPU1_N")
	)
	(segment
		(start 125.934978 -232.210102)
		(end 125.924564 -232.204006)
		(width 0.0889)
		(layer "B.Cu")
		(net "TP_FM_IBL_PWRBTN_CPU1_N")
	)
	(segment
		(start 121.790968 -232.204006)
		(end 121.776236 -232.212642)
		(width 0.0889)
		(layer "B.Cu")
		(net "TP_FM_IBL_PWRBTN_CPU1_N")
	)
	(segment
		(start 137.347706 -232.349548)
		(end 137.202164 -232.204006)
		(width 0.0889)
		(layer "B.Cu")
		(net "TP_FM_IBL_PWRBTN_CPU1_N")
	)
	(segment
		(start 140.22324 -232.237788)
		(end 139.844018 -232.61701)
		(width 0.12954)
		(layer "B.Cu")
		(net "TP_FM_IBL_PWRBTN_CPU1_N")
	)
	(segment
		(start 126.874524 -232.210102)
		(end 126.86411 -232.204006)
		(width 0.0889)
		(layer "B.Cu")
		(net "TP_FM_IBL_PWRBTN_CPU1_N")
	)
	(segment
		(start 123.119896 -232.212642)
		(end 123.105164 -232.204006)
		(width 0.0889)
		(layer "B.Cu")
		(net "TP_FM_IBL_PWRBTN_CPU1_N")
	)
	(segment
		(start 129.698496 -232.212642)
		(end 129.683764 -232.204006)
		(width 0.0889)
		(layer "B.Cu")
		(net "TP_FM_IBL_PWRBTN_CPU1_N")
	)
	(segment
		(start 132.513578 -232.210102)
		(end 132.503164 -232.204006)
		(width 0.0889)
		(layer "B.Cu")
		(net "TP_FM_IBL_PWRBTN_CPU1_N")
	)
	(segment
		(start 139.844018 -232.61701)
		(end 138.401298 -232.61701)
		(width 0.12954)
		(layer "B.Cu")
		(net "TP_FM_IBL_PWRBTN_CPU1_N")
	)
	(segment
		(start 124.059696 -232.212642)
		(end 124.044964 -232.204006)
		(width 0.0889)
		(layer "B.Cu")
		(net "TP_FM_IBL_PWRBTN_CPU1_N")
	)
	(segment
		(start 119.91975 -232.19918)
		(end 119.911368 -232.204006)
		(width 0.0889)
		(layer "B.Cu")
		(net "TP_FM_IBL_PWRBTN_CPU1_N")
	)
	(segment
		(start 134.008368 -232.204006)
		(end 133.997954 -232.210102)
		(width 0.0889)
		(layer "B.Cu")
		(net "TP_FM_IBL_PWRBTN_CPU1_N")
	)
	(segment
		(start 127.818896 -232.212642)
		(end 127.804164 -232.204006)
		(width 0.0889)
		(layer "B.Cu")
		(net "TP_FM_IBL_PWRBTN_CPU1_N")
	)
	(segment
		(start 120.295924 -232.210102)
		(end 120.28551 -232.204006)
		(width 0.0889)
		(layer "B.Cu")
		(net "TP_FM_IBL_PWRBTN_CPU1_N")
	)
	(segment
		(start 138.133836 -232.349548)
		(end 137.786618 -232.349548)
		(width 0.12954)
		(layer "B.Cu")
		(net "TP_FM_IBL_PWRBTN_CPU1_N")
	)
	(segment
		(start 137.786618 -232.349548)
		(end 137.347706 -232.349548)
		(width 0.0889)
		(layer "B.Cu")
		(net "TP_FM_IBL_PWRBTN_CPU1_N")
	)
	(segment
		(start 117.122702 -232.257346)
		(end 117.279166 -232.528364)
		(width 0.0889)
		(layer "B.Cu")
		(net "TP_FM_IBL_PWRBTN_CPU1_N")
	)
	(segment
		(start 131.578096 -232.212642)
		(end 131.563364 -232.204006)
		(width 0.0889)
		(layer "B.Cu")
		(net "TP_FM_IBL_PWRBTN_CPU1_N")
	)
	(segment
		(start 138.401298 -232.61701)
		(end 138.133836 -232.349548)
		(width 0.12954)
		(layer "B.Cu")
		(net "TP_FM_IBL_PWRBTN_CPU1_N")
	)
	(segment
		(start 145.92681 -232.237788)
		(end 140.22324 -232.237788)
		(width 0.12954)
		(layer "B.Cu")
		(net "TP_FM_IBL_PWRBTN_CPU1_N")
	)
	(segment
		(start 147.396708 -230.76789)
		(end 145.92681 -232.237788)
		(width 0.12954)
		(layer "B.Cu")
		(net "TP_FM_IBL_PWRBTN_CPU1_N")
	)
	(segment
		(start 117.481096 -232.212642)
		(end 117.466364 -232.204006)
		(width 0.0889)
		(layer "B.Cu")
		(net "TP_FM_IBL_PWRBTN_CPU1_N")
	)
	(segment
		(start 118.420896 -232.212642)
		(end 118.406164 -232.204006)
		(width 0.0889)
		(layer "B.Cu")
		(net "TP_FM_IBL_PWRBTN_CPU1_N")
	)
	(arc
		(start 130.623564 -232.204006)
		(mid 130.436366 -232.153863)
		(end 130.249168 -232.204006)
		(width 0.0889)
		(layer "B.Cu")
		(net "TP_FM_IBL_PWRBTN_CPU1_N")
	)
	(arc
		(start 127.429768 -232.204006)
		(mid 127.152955 -232.279876)
		(end 126.874524 -232.210102)
		(width 0.0889)
		(layer "B.Cu")
		(net "TP_FM_IBL_PWRBTN_CPU1_N")
	)
	(arc
		(start 119.345964 -232.204006)
		(mid 119.158766 -232.153863)
		(end 118.971568 -232.204006)
		(width 0.0889)
		(layer "B.Cu")
		(net "TP_FM_IBL_PWRBTN_CPU1_N")
	)
	(arc
		(start 122.730768 -232.204006)
		(mid 122.448066 -232.279782)
		(end 122.165364 -232.204006)
		(width 0.0889)
		(layer "B.Cu")
		(net "TP_FM_IBL_PWRBTN_CPU1_N")
	)
	(arc
		(start 127.804164 -232.204006)
		(mid 127.616966 -232.153863)
		(end 127.429768 -232.204006)
		(width 0.0889)
		(layer "B.Cu")
		(net "TP_FM_IBL_PWRBTN_CPU1_N")
	)
	(arc
		(start 136.827768 -232.204006)
		(mid 136.545066 -232.279782)
		(end 136.262364 -232.204006)
		(width 0.0889)
		(layer "B.Cu")
		(net "TP_FM_IBL_PWRBTN_CPU1_N")
	)
	(arc
		(start 118.406164 -232.204006)
		(mid 118.218966 -232.153863)
		(end 118.031768 -232.204006)
		(width 0.0889)
		(layer "B.Cu")
		(net "TP_FM_IBL_PWRBTN_CPU1_N")
	)
	(arc
		(start 124.610368 -232.204006)
		(mid 124.336169 -232.279841)
		(end 124.059696 -232.212642)
		(width 0.0889)
		(layer "B.Cu")
		(net "TP_FM_IBL_PWRBTN_CPU1_N")
	)
	(arc
		(start 121.225564 -232.204006)
		(mid 121.038366 -232.153863)
		(end 120.851168 -232.204006)
		(width 0.0889)
		(layer "B.Cu")
		(net "TP_FM_IBL_PWRBTN_CPU1_N")
	)
	(arc
		(start 131.563364 -232.204006)
		(mid 131.376166 -232.153863)
		(end 131.188968 -232.204006)
		(width 0.0889)
		(layer "B.Cu")
		(net "TP_FM_IBL_PWRBTN_CPU1_N")
	)
	(arc
		(start 128.743964 -232.204006)
		(mid 128.556766 -232.153863)
		(end 128.369568 -232.204006)
		(width 0.0889)
		(layer "B.Cu")
		(net "TP_FM_IBL_PWRBTN_CPU1_N")
	)
	(arc
		(start 136.262364 -232.204006)
		(mid 136.075166 -232.153863)
		(end 135.887968 -232.204006)
		(width 0.0889)
		(layer "B.Cu")
		(net "TP_FM_IBL_PWRBTN_CPU1_N")
	)
	(arc
		(start 120.28551 -232.204006)
		(mid 120.103259 -232.153895)
		(end 119.91975 -232.19918)
		(width 0.0889)
		(layer "B.Cu")
		(net "TP_FM_IBL_PWRBTN_CPU1_N")
	)
	(arc
		(start 132.503164 -232.204006)
		(mid 132.315966 -232.153863)
		(end 132.128768 -232.204006)
		(width 0.0889)
		(layer "B.Cu")
		(net "TP_FM_IBL_PWRBTN_CPU1_N")
	)
	(arc
		(start 121.776236 -232.212642)
		(mid 121.499761 -232.279962)
		(end 121.225564 -232.204006)
		(width 0.0889)
		(layer "B.Cu")
		(net "TP_FM_IBL_PWRBTN_CPU1_N")
	)
	(arc
		(start 118.031768 -232.204006)
		(mid 117.757569 -232.279841)
		(end 117.481096 -232.212642)
		(width 0.0889)
		(layer "B.Cu")
		(net "TP_FM_IBL_PWRBTN_CPU1_N")
	)
	(arc
		(start 123.670568 -232.204006)
		(mid 123.396369 -232.279841)
		(end 123.119896 -232.212642)
		(width 0.0889)
		(layer "B.Cu")
		(net "TP_FM_IBL_PWRBTN_CPU1_N")
	)
	(arc
		(start 133.068314 -232.204006)
		(mid 132.791755 -232.279749)
		(end 132.513578 -232.210102)
		(width 0.0889)
		(layer "B.Cu")
		(net "TP_FM_IBL_PWRBTN_CPU1_N")
	)
	(arc
		(start 124.044964 -232.204006)
		(mid 123.857766 -232.153863)
		(end 123.670568 -232.204006)
		(width 0.0889)
		(layer "B.Cu")
		(net "TP_FM_IBL_PWRBTN_CPU1_N")
	)
	(arc
		(start 133.997954 -232.210102)
		(mid 133.719522 -232.279948)
		(end 133.44271 -232.204006)
		(width 0.0889)
		(layer "B.Cu")
		(net "TP_FM_IBL_PWRBTN_CPU1_N")
	)
	(arc
		(start 134.948168 -232.204006)
		(mid 134.665466 -232.279782)
		(end 134.382764 -232.204006)
		(width 0.0889)
		(layer "B.Cu")
		(net "TP_FM_IBL_PWRBTN_CPU1_N")
	)
	(arc
		(start 126.86411 -232.204006)
		(mid 126.676912 -232.153863)
		(end 126.489714 -232.204006)
		(width 0.0889)
		(layer "B.Cu")
		(net "TP_FM_IBL_PWRBTN_CPU1_N")
	)
	(arc
		(start 129.683764 -232.204006)
		(mid 129.496566 -232.153863)
		(end 129.309368 -232.204006)
		(width 0.0889)
		(layer "B.Cu")
		(net "TP_FM_IBL_PWRBTN_CPU1_N")
	)
	(arc
		(start 119.896636 -232.212642)
		(mid 119.620161 -232.279962)
		(end 119.345964 -232.204006)
		(width 0.0889)
		(layer "B.Cu")
		(net "TP_FM_IBL_PWRBTN_CPU1_N")
	)
	(arc
		(start 124.984764 -232.204006)
		(mid 124.797566 -232.153863)
		(end 124.610368 -232.204006)
		(width 0.0889)
		(layer "B.Cu")
		(net "TP_FM_IBL_PWRBTN_CPU1_N")
	)
	(arc
		(start 126.489714 -232.204006)
		(mid 126.213155 -232.279749)
		(end 125.934978 -232.210102)
		(width 0.0889)
		(layer "B.Cu")
		(net "TP_FM_IBL_PWRBTN_CPU1_N")
	)
	(arc
		(start 120.851168 -232.204006)
		(mid 120.574355 -232.279876)
		(end 120.295924 -232.210102)
		(width 0.0889)
		(layer "B.Cu")
		(net "TP_FM_IBL_PWRBTN_CPU1_N")
	)
	(arc
		(start 125.924564 -232.204006)
		(mid 125.737366 -232.153863)
		(end 125.550168 -232.204006)
		(width 0.0889)
		(layer "B.Cu")
		(net "TP_FM_IBL_PWRBTN_CPU1_N")
	)
	(arc
		(start 135.887968 -232.204006)
		(mid 135.605266 -232.279782)
		(end 135.322564 -232.204006)
		(width 0.0889)
		(layer "B.Cu")
		(net "TP_FM_IBL_PWRBTN_CPU1_N")
	)
	(arc
		(start 132.128768 -232.204006)
		(mid 131.854569 -232.279841)
		(end 131.578096 -232.212642)
		(width 0.0889)
		(layer "B.Cu")
		(net "TP_FM_IBL_PWRBTN_CPU1_N")
	)
	(arc
		(start 128.369568 -232.204006)
		(mid 128.095369 -232.279841)
		(end 127.818896 -232.212642)
		(width 0.0889)
		(layer "B.Cu")
		(net "TP_FM_IBL_PWRBTN_CPU1_N")
	)
	(arc
		(start 122.165364 -232.204006)
		(mid 121.978166 -232.153863)
		(end 121.790968 -232.204006)
		(width 0.0889)
		(layer "B.Cu")
		(net "TP_FM_IBL_PWRBTN_CPU1_N")
	)
	(arc
		(start 137.202164 -232.204006)
		(mid 137.014966 -232.153863)
		(end 136.827768 -232.204006)
		(width 0.0889)
		(layer "B.Cu")
		(net "TP_FM_IBL_PWRBTN_CPU1_N")
	)
	(arc
		(start 134.382764 -232.204006)
		(mid 134.195566 -232.153863)
		(end 134.008368 -232.204006)
		(width 0.0889)
		(layer "B.Cu")
		(net "TP_FM_IBL_PWRBTN_CPU1_N")
	)
	(arc
		(start 129.309368 -232.204006)
		(mid 129.026666 -232.279782)
		(end 128.743964 -232.204006)
		(width 0.0889)
		(layer "B.Cu")
		(net "TP_FM_IBL_PWRBTN_CPU1_N")
	)
	(arc
		(start 135.322564 -232.204006)
		(mid 135.135366 -232.153863)
		(end 134.948168 -232.204006)
		(width 0.0889)
		(layer "B.Cu")
		(net "TP_FM_IBL_PWRBTN_CPU1_N")
	)
	(arc
		(start 131.188968 -232.204006)
		(mid 130.914769 -232.279841)
		(end 130.638296 -232.212642)
		(width 0.0889)
		(layer "B.Cu")
		(net "TP_FM_IBL_PWRBTN_CPU1_N")
	)
	(arc
		(start 133.44271 -232.204006)
		(mid 133.255512 -232.153863)
		(end 133.068314 -232.204006)
		(width 0.0889)
		(layer "B.Cu")
		(net "TP_FM_IBL_PWRBTN_CPU1_N")
	)
	(arc
		(start 125.550168 -232.204006)
		(mid 125.275969 -232.279841)
		(end 124.999496 -232.212642)
		(width 0.0889)
		(layer "B.Cu")
		(net "TP_FM_IBL_PWRBTN_CPU1_N")
	)
	(arc
		(start 123.105164 -232.204006)
		(mid 122.917966 -232.153863)
		(end 122.730768 -232.204006)
		(width 0.0889)
		(layer "B.Cu")
		(net "TP_FM_IBL_PWRBTN_CPU1_N")
	)
	(arc
		(start 118.971568 -232.204006)
		(mid 118.697369 -232.279841)
		(end 118.420896 -232.212642)
		(width 0.0889)
		(layer "B.Cu")
		(net "TP_FM_IBL_PWRBTN_CPU1_N")
	)
	(arc
		(start 117.466364 -232.204006)
		(mid 117.307876 -232.155073)
		(end 117.143784 -232.179368)
		(width 0.0889)
		(layer "B.Cu")
		(net "TP_FM_IBL_PWRBTN_CPU1_N")
	)
	(arc
		(start 130.249168 -232.204006)
		(mid 129.974969 -232.279841)
		(end 129.698496 -232.212642)
		(width 0.0889)
		(layer "B.Cu")
		(net "TP_FM_IBL_PWRBTN_CPU1_N")
	)
	(segment
		(start 368.03838 -232.528364)
		(end 368.03838 -233.064304)
		(width 0.12954)
		(layer "F.Cu")
		(net "TP_FM_IBL_ADR_TRIGGER_CPU0_R")
	)
	(via
		(at 368.03838 -232.528364)
		(size 0.4572)
		(drill 0.2032)
		(layers "F.Cu" "B.Cu")
		(net "TP_FM_IBL_ADR_TRIGGER_CPU0_R")
	)
	(segment
		(start 367.09858 -232.528618)
		(end 367.098834 -232.528364)
		(width 0.12954)
		(layer "F.Cu")
		(net "TP_FM_IBL_ADR_COMPLETE_CPU0_R")
	)
	(segment
		(start 367.09858 -233.064304)
		(end 367.09858 -232.528618)
		(width 0.12954)
		(layer "F.Cu")
		(net "TP_FM_IBL_ADR_COMPLETE_CPU0_R")
	)
	(via
		(at 367.098834 -232.528364)
		(size 0.4572)
		(drill 0.2032)
		(layers "F.Cu" "B.Cu")
		(net "TP_FM_IBL_ADR_COMPLETE_CPU0_R")
	)
	(segment
		(start 366.62868 -232.250234)
		(end 366.62868 -231.714548)
		(width 0.12954)
		(layer "F.Cu")
		(net "TP_FM_IBL_ADR_ACK_CPU0")
	)
	(segment
		(start 366.628934 -232.250488)
		(end 366.62868 -232.250234)
		(width 0.12954)
		(layer "F.Cu")
		(net "TP_FM_IBL_ADR_ACK_CPU0")
	)
	(via
		(at 366.62868 -231.714548)
		(size 0.4572)
		(drill 0.2032)
		(layers "F.Cu" "B.Cu")
		(net "TP_FM_IBL_ADR_ACK_CPU0")
	)
	(segment
		(start 102.352094 -263.150604)
		(end 102.352348 -263.150858)
		(width 0.12954)
		(layer "F.Cu")
		(net "TP_EV_CPU1_EXT_BGREF")
	)
	(segment
		(start 102.352348 -263.150858)
		(end 102.352348 -263.686544)
		(width 0.12954)
		(layer "F.Cu")
		(net "TP_EV_CPU1_EXT_BGREF")
	)
	(via
		(at 102.352348 -263.686544)
		(size 0.4572)
		(drill 0.2032)
		(layers "F.Cu" "B.Cu")
		(net "TP_EV_CPU1_EXT_BGREF")
	)
	(via
		(at 82.711798 -264.388346)
		(size 0.6604)
		(drill 0.3302)
		(layers "F.Cu" "B.Cu")
		(net "TP_EV_CPU1_EXT_BGREF")
	)
	(segment
		(start 84.105242 -264.388346)
		(end 82.711798 -264.388346)
		(width 0.12954)
		(layer "B.Cu")
		(net "TP_EV_CPU1_EXT_BGREF")
	)
	(segment
		(start 102.352348 -263.686544)
		(end 101.824536 -263.435084)
		(width 0.0889)
		(layer "B.Cu")
		(net "TP_EV_CPU1_EXT_BGREF")
	)
	(segment
		(start 99.34575 -263.362186)
		(end 99.331018 -263.370822)
		(width 0.0889)
		(layer "B.Cu")
		(net "TP_EV_CPU1_EXT_BGREF")
	)
	(segment
		(start 100.28555 -263.362186)
		(end 100.270818 -263.370822)
		(width 0.0889)
		(layer "B.Cu")
		(net "TP_EV_CPU1_EXT_BGREF")
	)
	(segment
		(start 91.82735 -263.362186)
		(end 91.816936 -263.368282)
		(width 0.0889)
		(layer "B.Cu")
		(net "TP_EV_CPU1_EXT_BGREF")
	)
	(segment
		(start 95.58655 -263.362186)
		(end 95.571818 -263.370822)
		(width 0.0889)
		(layer "B.Cu")
		(net "TP_EV_CPU1_EXT_BGREF")
	)
	(segment
		(start 98.40595 -263.362186)
		(end 98.395536 -263.368282)
		(width 0.0889)
		(layer "B.Cu")
		(net "TP_EV_CPU1_EXT_BGREF")
	)
	(segment
		(start 93.70695 -263.362186)
		(end 93.692218 -263.370822)
		(width 0.0889)
		(layer "B.Cu")
		(net "TP_EV_CPU1_EXT_BGREF")
	)
	(segment
		(start 96.52635 -263.362186)
		(end 96.511618 -263.370822)
		(width 0.0889)
		(layer "B.Cu")
		(net "TP_EV_CPU1_EXT_BGREF")
	)
	(segment
		(start 88.40978 -263.24179)
		(end 87.048086 -263.24179)
		(width 0.0889)
		(layer "B.Cu")
		(net "TP_EV_CPU1_EXT_BGREF")
	)
	(segment
		(start 88.99779 -263.223756)
		(end 88.914986 -263.30656)
		(width 0.0889)
		(layer "B.Cu")
		(net "TP_EV_CPU1_EXT_BGREF")
	)
	(segment
		(start 97.453704 -263.363456)
		(end 97.424494 -263.378188)
		(width 0.0889)
		(layer "B.Cu")
		(net "TP_EV_CPU1_EXT_BGREF")
	)
	(segment
		(start 92.76715 -263.362186)
		(end 92.752418 -263.370822)
		(width 0.0889)
		(layer "B.Cu")
		(net "TP_EV_CPU1_EXT_BGREF")
	)
	(segment
		(start 87.048086 -263.24179)
		(end 85.251798 -263.24179)
		(width 0.12954)
		(layer "B.Cu")
		(net "TP_EV_CPU1_EXT_BGREF")
	)
	(segment
		(start 89.394284 -263.319514)
		(end 89.298526 -263.223756)
		(width 0.0889)
		(layer "B.Cu")
		(net "TP_EV_CPU1_EXT_BGREF")
	)
	(segment
		(start 89.91219 -263.25068)
		(end 89.843102 -263.319514)
		(width 0.0889)
		(layer "B.Cu")
		(net "TP_EV_CPU1_EXT_BGREF")
	)
	(segment
		(start 88.47455 -263.30656)
		(end 88.40978 -263.24179)
		(width 0.0889)
		(layer "B.Cu")
		(net "TP_EV_CPU1_EXT_BGREF")
	)
	(segment
		(start 85.251798 -263.24179)
		(end 84.105242 -264.388346)
		(width 0.12954)
		(layer "B.Cu")
		(net "TP_EV_CPU1_EXT_BGREF")
	)
	(arc
		(start 93.141546 -263.362186)
		(mid 92.954348 -263.312043)
		(end 92.76715 -263.362186)
		(width 0.0889)
		(layer "B.Cu")
		(net "TP_EV_CPU1_EXT_BGREF")
	)
	(arc
		(start 94.064582 -263.352788)
		(mid 93.88457 -263.312006)
		(end 93.70695 -263.362186)
		(width 0.0889)
		(layer "B.Cu")
		(net "TP_EV_CPU1_EXT_BGREF")
	)
	(arc
		(start 99.331018 -263.370822)
		(mid 99.054543 -263.438142)
		(end 98.780346 -263.362186)
		(width 0.0889)
		(layer "B.Cu")
		(net "TP_EV_CPU1_EXT_BGREF")
	)
	(arc
		(start 99.720146 -263.362186)
		(mid 99.532948 -263.312043)
		(end 99.34575 -263.362186)
		(width 0.0889)
		(layer "B.Cu")
		(net "TP_EV_CPU1_EXT_BGREF")
	)
	(arc
		(start 94.663768 -263.352788)
		(mid 94.643159 -263.361927)
		(end 94.621604 -263.368536)
		(width 0.0889)
		(layer "B.Cu")
		(net "TP_EV_CPU1_EXT_BGREF")
	)
	(arc
		(start 91.816936 -263.368282)
		(mid 91.538758 -263.438005)
		(end 91.2622 -263.362186)
		(width 0.0889)
		(layer "B.Cu")
		(net "TP_EV_CPU1_EXT_BGREF")
	)
	(arc
		(start 88.914986 -263.30656)
		(mid 88.694768 -263.397777)
		(end 88.47455 -263.30656)
		(width 0.0889)
		(layer "B.Cu")
		(net "TP_EV_CPU1_EXT_BGREF")
	)
	(arc
		(start 95.960946 -263.362186)
		(mid 95.773748 -263.312043)
		(end 95.58655 -263.362186)
		(width 0.0889)
		(layer "B.Cu")
		(net "TP_EV_CPU1_EXT_BGREF")
	)
	(arc
		(start 94.621604 -263.368536)
		(mid 94.364048 -263.398391)
		(end 94.106492 -263.368536)
		(width 0.0889)
		(layer "B.Cu")
		(net "TP_EV_CPU1_EXT_BGREF")
	)
	(arc
		(start 95.571818 -263.370822)
		(mid 95.295343 -263.438142)
		(end 95.021146 -263.362186)
		(width 0.0889)
		(layer "B.Cu")
		(net "TP_EV_CPU1_EXT_BGREF")
	)
	(arc
		(start 91.2622 -263.362186)
		(mid 91.075002 -263.312043)
		(end 90.887804 -263.362186)
		(width 0.0889)
		(layer "B.Cu")
		(net "TP_EV_CPU1_EXT_BGREF")
	)
	(arc
		(start 89.843102 -263.319514)
		(mid 89.61873 -263.41234)
		(end 89.394284 -263.319514)
		(width 0.0889)
		(layer "B.Cu")
		(net "TP_EV_CPU1_EXT_BGREF")
	)
	(arc
		(start 97.424494 -263.378188)
		(mid 97.160586 -263.436276)
		(end 96.900746 -263.362186)
		(width 0.0889)
		(layer "B.Cu")
		(net "TP_EV_CPU1_EXT_BGREF")
	)
	(arc
		(start 100.270818 -263.370822)
		(mid 99.994343 -263.438142)
		(end 99.720146 -263.362186)
		(width 0.0889)
		(layer "B.Cu")
		(net "TP_EV_CPU1_EXT_BGREF")
	)
	(arc
		(start 96.900746 -263.362186)
		(mid 96.713548 -263.312043)
		(end 96.52635 -263.362186)
		(width 0.0889)
		(layer "B.Cu")
		(net "TP_EV_CPU1_EXT_BGREF")
	)
	(arc
		(start 95.021146 -263.362186)
		(mid 94.843639 -263.312048)
		(end 94.663768 -263.352788)
		(width 0.0889)
		(layer "B.Cu")
		(net "TP_EV_CPU1_EXT_BGREF")
	)
	(arc
		(start 92.201746 -263.362186)
		(mid 92.014548 -263.312043)
		(end 91.82735 -263.362186)
		(width 0.0889)
		(layer "B.Cu")
		(net "TP_EV_CPU1_EXT_BGREF")
	)
	(arc
		(start 101.22535 -263.362186)
		(mid 100.942648 -263.437962)
		(end 100.659946 -263.362186)
		(width 0.0889)
		(layer "B.Cu")
		(net "TP_EV_CPU1_EXT_BGREF")
	)
	(arc
		(start 98.780346 -263.362186)
		(mid 98.593148 -263.312043)
		(end 98.40595 -263.362186)
		(width 0.0889)
		(layer "B.Cu")
		(net "TP_EV_CPU1_EXT_BGREF")
	)
	(arc
		(start 101.599746 -263.362186)
		(mid 101.412548 -263.312043)
		(end 101.22535 -263.362186)
		(width 0.0889)
		(layer "B.Cu")
		(net "TP_EV_CPU1_EXT_BGREF")
	)
	(arc
		(start 90.887804 -263.362186)
		(mid 90.569536 -263.420077)
		(end 90.28684 -263.262872)
		(width 0.0889)
		(layer "B.Cu")
		(net "TP_EV_CPU1_EXT_BGREF")
	)
	(arc
		(start 90.28684 -263.262872)
		(mid 90.102156 -263.175586)
		(end 89.91219 -263.25068)
		(width 0.0889)
		(layer "B.Cu")
		(net "TP_EV_CPU1_EXT_BGREF")
	)
	(arc
		(start 93.692218 -263.370822)
		(mid 93.415743 -263.438142)
		(end 93.141546 -263.362186)
		(width 0.0889)
		(layer "B.Cu")
		(net "TP_EV_CPU1_EXT_BGREF")
	)
	(arc
		(start 101.824536 -263.435084)
		(mid 101.708291 -263.410509)
		(end 101.599746 -263.362186)
		(width 0.0889)
		(layer "B.Cu")
		(net "TP_EV_CPU1_EXT_BGREF")
	)
	(arc
		(start 100.659946 -263.362186)
		(mid 100.472748 -263.312043)
		(end 100.28555 -263.362186)
		(width 0.0889)
		(layer "B.Cu")
		(net "TP_EV_CPU1_EXT_BGREF")
	)
	(arc
		(start 97.8408 -263.362186)
		(mid 97.64707 -263.310603)
		(end 97.453704 -263.363456)
		(width 0.0889)
		(layer "B.Cu")
		(net "TP_EV_CPU1_EXT_BGREF")
	)
	(arc
		(start 89.298526 -263.223756)
		(mid 89.148158 -263.161472)
		(end 88.99779 -263.223756)
		(width 0.0889)
		(layer "B.Cu")
		(net "TP_EV_CPU1_EXT_BGREF")
	)
	(arc
		(start 94.106492 -263.368536)
		(mid 94.085066 -263.361917)
		(end 94.064582 -263.352788)
		(width 0.0889)
		(layer "B.Cu")
		(net "TP_EV_CPU1_EXT_BGREF")
	)
	(arc
		(start 92.752418 -263.370822)
		(mid 92.475943 -263.438142)
		(end 92.201746 -263.362186)
		(width 0.0889)
		(layer "B.Cu")
		(net "TP_EV_CPU1_EXT_BGREF")
	)
	(arc
		(start 96.511618 -263.370822)
		(mid 96.235143 -263.438142)
		(end 95.960946 -263.362186)
		(width 0.0889)
		(layer "B.Cu")
		(net "TP_EV_CPU1_EXT_BGREF")
	)
	(arc
		(start 98.395536 -263.368282)
		(mid 98.117358 -263.438005)
		(end 97.8408 -263.362186)
		(width 0.0889)
		(layer "B.Cu")
		(net "TP_EV_CPU1_EXT_BGREF")
	)
	(segment
		(start 350.292162 -263.68629)
		(end 350.292416 -263.686544)
		(width 0.12954)
		(layer "F.Cu")
		(net "TP_EV_CPU0_EXT_BGREF")
	)
	(segment
		(start 350.292162 -263.150604)
		(end 350.292162 -263.68629)
		(width 0.12954)
		(layer "F.Cu")
		(net "TP_EV_CPU0_EXT_BGREF")
	)
	(via
		(at 318.494664 -267.007086)
		(size 0.6604)
		(drill 0.3302)
		(layers "F.Cu" "B.Cu")
		(net "TP_EV_CPU0_EXT_BGREF")
	)
	(via
		(at 350.292416 -263.686544)
		(size 0.4572)
		(drill 0.2032)
		(layers "F.Cu" "B.Cu")
		(net "TP_EV_CPU0_EXT_BGREF")
	)
	(segment
		(start 325.105014 -266.360656)
		(end 324.458584 -267.007086)
		(width 0.12954)
		(layer "B.Cu")
		(net "TP_EV_CPU0_EXT_BGREF")
	)
	(segment
		(start 336.414618 -263.30656)
		(end 336.3468 -263.238742)
		(width 0.12954)
		(layer "B.Cu")
		(net "TP_EV_CPU0_EXT_BGREF")
	)
	(segment
		(start 335.103724 -263.238488)
		(end 334.826356 -263.515856)
		(width 0.12954)
		(layer "B.Cu")
		(net "TP_EV_CPU0_EXT_BGREF")
	)
	(segment
		(start 348.225618 -263.362186)
		(end 348.210886 -263.370822)
		(width 0.0889)
		(layer "B.Cu")
		(net "TP_EV_CPU0_EXT_BGREF")
	)
	(segment
		(start 345.393772 -263.363456)
		(end 345.364562 -263.378188)
		(width 0.0889)
		(layer "B.Cu")
		(net "TP_EV_CPU0_EXT_BGREF")
	)
	(segment
		(start 336.346292 -263.238488)
		(end 335.103724 -263.238488)
		(width 0.12954)
		(layer "B.Cu")
		(net "TP_EV_CPU0_EXT_BGREF")
	)
	(segment
		(start 341.647018 -263.362186)
		(end 341.632286 -263.370822)
		(width 0.0889)
		(layer "B.Cu")
		(net "TP_EV_CPU0_EXT_BGREF")
	)
	(segment
		(start 336.937858 -263.223756)
		(end 336.855054 -263.30656)
		(width 0.12954)
		(layer "B.Cu")
		(net "TP_EV_CPU0_EXT_BGREF")
	)
	(segment
		(start 344.466418 -263.362186)
		(end 344.451686 -263.370822)
		(width 0.0889)
		(layer "B.Cu")
		(net "TP_EV_CPU0_EXT_BGREF")
	)
	(segment
		(start 340.707218 -263.362186)
		(end 340.692486 -263.370822)
		(width 0.0889)
		(layer "B.Cu")
		(net "TP_EV_CPU0_EXT_BGREF")
	)
	(segment
		(start 329.979528 -266.360656)
		(end 325.105014 -266.360656)
		(width 0.12954)
		(layer "B.Cu")
		(net "TP_EV_CPU0_EXT_BGREF")
	)
	(segment
		(start 346.346018 -263.362186)
		(end 346.335604 -263.368282)
		(width 0.0889)
		(layer "B.Cu")
		(net "TP_EV_CPU0_EXT_BGREF")
	)
	(segment
		(start 332.824328 -263.515856)
		(end 329.979528 -266.360656)
		(width 0.12954)
		(layer "B.Cu")
		(net "TP_EV_CPU0_EXT_BGREF")
	)
	(segment
		(start 339.767418 -263.362186)
		(end 339.757004 -263.368282)
		(width 0.0889)
		(layer "B.Cu")
		(net "TP_EV_CPU0_EXT_BGREF")
	)
	(segment
		(start 334.826356 -263.515856)
		(end 332.824328 -263.515856)
		(width 0.12954)
		(layer "B.Cu")
		(net "TP_EV_CPU0_EXT_BGREF")
	)
	(segment
		(start 324.458584 -267.007086)
		(end 318.494664 -267.007086)
		(width 0.12954)
		(layer "B.Cu")
		(net "TP_EV_CPU0_EXT_BGREF")
	)
	(segment
		(start 337.334352 -263.319514)
		(end 337.238594 -263.223756)
		(width 0.12954)
		(layer "B.Cu")
		(net "TP_EV_CPU0_EXT_BGREF")
	)
	(segment
		(start 337.852258 -263.25068)
		(end 337.78317 -263.319514)
		(width 0.12954)
		(layer "B.Cu")
		(net "TP_EV_CPU0_EXT_BGREF")
	)
	(segment
		(start 343.526618 -263.362186)
		(end 343.511886 -263.370822)
		(width 0.0889)
		(layer "B.Cu")
		(net "TP_EV_CPU0_EXT_BGREF")
	)
	(segment
		(start 350.292416 -263.686544)
		(end 349.764604 -263.435084)
		(width 0.0889)
		(layer "B.Cu")
		(net "TP_EV_CPU0_EXT_BGREF")
	)
	(segment
		(start 347.285818 -263.362186)
		(end 347.271086 -263.370822)
		(width 0.0889)
		(layer "B.Cu")
		(net "TP_EV_CPU0_EXT_BGREF")
	)
	(arc
		(start 347.660214 -263.362186)
		(mid 347.473016 -263.312043)
		(end 347.285818 -263.362186)
		(width 0.0889)
		(layer "B.Cu")
		(net "TP_EV_CPU0_EXT_BGREF")
	)
	(arc
		(start 348.210886 -263.370822)
		(mid 347.934411 -263.438142)
		(end 347.660214 -263.362186)
		(width 0.0889)
		(layer "B.Cu")
		(net "TP_EV_CPU0_EXT_BGREF")
	)
	(arc
		(start 344.451686 -263.370822)
		(mid 344.175211 -263.438142)
		(end 343.901014 -263.362186)
		(width 0.0889)
		(layer "B.Cu")
		(net "TP_EV_CPU0_EXT_BGREF")
	)
	(arc
		(start 349.764604 -263.435084)
		(mid 349.648359 -263.410509)
		(end 349.539814 -263.362186)
		(width 0.0889)
		(layer "B.Cu")
		(net "TP_EV_CPU0_EXT_BGREF")
	)
	(arc
		(start 336.3468 -263.238742)
		(mid 336.346567 -263.238586)
		(end 336.346292 -263.238488)
		(width 0.12954)
		(layer "B.Cu")
		(net "TP_EV_CPU0_EXT_BGREF")
	)
	(arc
		(start 346.720414 -263.362186)
		(mid 346.533216 -263.312043)
		(end 346.346018 -263.362186)
		(width 0.0889)
		(layer "B.Cu")
		(net "TP_EV_CPU0_EXT_BGREF")
	)
	(arc
		(start 339.757004 -263.368282)
		(mid 339.478826 -263.438005)
		(end 339.202268 -263.362186)
		(width 0.0889)
		(layer "B.Cu")
		(net "TP_EV_CPU0_EXT_BGREF")
	)
	(arc
		(start 345.780868 -263.362186)
		(mid 345.587138 -263.310603)
		(end 345.393772 -263.363456)
		(width 0.0889)
		(layer "B.Cu")
		(net "TP_EV_CPU0_EXT_BGREF")
	)
	(arc
		(start 342.561672 -263.368536)
		(mid 342.304116 -263.398391)
		(end 342.04656 -263.368536)
		(width 0.0889)
		(layer "B.Cu")
		(net "TP_EV_CPU0_EXT_BGREF")
	)
	(arc
		(start 344.840814 -263.362186)
		(mid 344.653616 -263.312043)
		(end 344.466418 -263.362186)
		(width 0.0889)
		(layer "B.Cu")
		(net "TP_EV_CPU0_EXT_BGREF")
	)
	(arc
		(start 349.165418 -263.362186)
		(mid 348.882716 -263.437962)
		(end 348.600014 -263.362186)
		(width 0.0889)
		(layer "B.Cu")
		(net "TP_EV_CPU0_EXT_BGREF")
	)
	(arc
		(start 347.271086 -263.370822)
		(mid 346.994611 -263.438142)
		(end 346.720414 -263.362186)
		(width 0.0889)
		(layer "B.Cu")
		(net "TP_EV_CPU0_EXT_BGREF")
	)
	(arc
		(start 341.632286 -263.370822)
		(mid 341.355811 -263.438142)
		(end 341.081614 -263.362186)
		(width 0.0889)
		(layer "B.Cu")
		(net "TP_EV_CPU0_EXT_BGREF")
	)
	(arc
		(start 340.141814 -263.362186)
		(mid 339.954616 -263.312043)
		(end 339.767418 -263.362186)
		(width 0.0889)
		(layer "B.Cu")
		(net "TP_EV_CPU0_EXT_BGREF")
	)
	(arc
		(start 338.827872 -263.362186)
		(mid 338.509604 -263.420077)
		(end 338.226908 -263.262872)
		(width 0.0889)
		(layer "B.Cu")
		(net "TP_EV_CPU0_EXT_BGREF")
	)
	(arc
		(start 341.081614 -263.362186)
		(mid 340.894416 -263.312043)
		(end 340.707218 -263.362186)
		(width 0.0889)
		(layer "B.Cu")
		(net "TP_EV_CPU0_EXT_BGREF")
	)
	(arc
		(start 342.603836 -263.352788)
		(mid 342.583227 -263.361927)
		(end 342.561672 -263.368536)
		(width 0.0889)
		(layer "B.Cu")
		(net "TP_EV_CPU0_EXT_BGREF")
	)
	(arc
		(start 342.961214 -263.362186)
		(mid 342.783707 -263.312048)
		(end 342.603836 -263.352788)
		(width 0.0889)
		(layer "B.Cu")
		(net "TP_EV_CPU0_EXT_BGREF")
	)
	(arc
		(start 349.539814 -263.362186)
		(mid 349.352616 -263.312043)
		(end 349.165418 -263.362186)
		(width 0.0889)
		(layer "B.Cu")
		(net "TP_EV_CPU0_EXT_BGREF")
	)
	(arc
		(start 337.238594 -263.223756)
		(mid 337.088226 -263.161472)
		(end 336.937858 -263.223756)
		(width 0.12954)
		(layer "B.Cu")
		(net "TP_EV_CPU0_EXT_BGREF")
	)
	(arc
		(start 343.511886 -263.370822)
		(mid 343.235411 -263.438142)
		(end 342.961214 -263.362186)
		(width 0.0889)
		(layer "B.Cu")
		(net "TP_EV_CPU0_EXT_BGREF")
	)
	(arc
		(start 337.78317 -263.319514)
		(mid 337.558798 -263.412415)
		(end 337.334352 -263.319514)
		(width 0.12954)
		(layer "B.Cu")
		(net "TP_EV_CPU0_EXT_BGREF")
	)
	(arc
		(start 338.226908 -263.262872)
		(mid 338.042224 -263.175586)
		(end 337.852258 -263.25068)
		(width 0.12954)
		(layer "B.Cu")
		(net "TP_EV_CPU0_EXT_BGREF")
	)
	(arc
		(start 340.692486 -263.370822)
		(mid 340.416011 -263.438142)
		(end 340.141814 -263.362186)
		(width 0.0889)
		(layer "B.Cu")
		(net "TP_EV_CPU0_EXT_BGREF")
	)
	(arc
		(start 339.202268 -263.362186)
		(mid 339.01507 -263.312043)
		(end 338.827872 -263.362186)
		(width 0.0889)
		(layer "B.Cu")
		(net "TP_EV_CPU0_EXT_BGREF")
	)
	(arc
		(start 348.600014 -263.362186)
		(mid 348.412816 -263.312043)
		(end 348.225618 -263.362186)
		(width 0.0889)
		(layer "B.Cu")
		(net "TP_EV_CPU0_EXT_BGREF")
	)
	(arc
		(start 342.04656 -263.368536)
		(mid 342.025134 -263.361917)
		(end 342.00465 -263.352788)
		(width 0.0889)
		(layer "B.Cu")
		(net "TP_EV_CPU0_EXT_BGREF")
	)
	(arc
		(start 346.335604 -263.368282)
		(mid 346.057426 -263.438005)
		(end 345.780868 -263.362186)
		(width 0.0889)
		(layer "B.Cu")
		(net "TP_EV_CPU0_EXT_BGREF")
	)
	(arc
		(start 342.00465 -263.352788)
		(mid 341.824638 -263.312006)
		(end 341.647018 -263.362186)
		(width 0.0889)
		(layer "B.Cu")
		(net "TP_EV_CPU0_EXT_BGREF")
	)
	(arc
		(start 336.855054 -263.30656)
		(mid 336.634836 -263.397777)
		(end 336.414618 -263.30656)
		(width 0.12954)
		(layer "B.Cu")
		(net "TP_EV_CPU0_EXT_BGREF")
	)
	(arc
		(start 343.901014 -263.362186)
		(mid 343.713816 -263.312043)
		(end 343.526618 -263.362186)
		(width 0.0889)
		(layer "B.Cu")
		(net "TP_EV_CPU0_EXT_BGREF")
	)
	(arc
		(start 345.364562 -263.378188)
		(mid 345.100654 -263.436276)
		(end 344.840814 -263.362186)
		(width 0.0889)
		(layer "B.Cu")
		(net "TP_EV_CPU0_EXT_BGREF")
	)
	(segment
		(start 354.991416 -266.406122)
		(end 354.991416 -266.941808)
		(width 0.12954)
		(layer "F.Cu")
		(net "TP_ESPI_IBL_CPU0_OE_LVC1_N")
	)
	(segment
		(start 354.991162 -266.405868)
		(end 354.991416 -266.406122)
		(width 0.12954)
		(layer "F.Cu")
		(net "TP_ESPI_IBL_CPU0_OE_LVC1_N")
	)
	(via
		(at 354.991416 -266.941808)
		(size 0.4572)
		(drill 0.2032)
		(layers "F.Cu" "B.Cu")
		(net "TP_ESPI_IBL_CPU0_OE_LVC1_N")
	)
	(via
		(at 331.986128 -268.949424)
		(size 0.6604)
		(drill 0.3302)
		(layers "F.Cu" "B.Cu")
		(net "TP_ESPI_IBL_CPU0_OE_LVC1_N")
	)
	(segment
		(start 352.866198 -268.864588)
		(end 352.9711 -268.96949)
		(width 0.0889)
		(layer "B.Cu")
		(net "TP_ESPI_IBL_CPU0_OE_LVC1_N")
	)
	(segment
		(start 334.76692 -268.611604)
		(end 334.990186 -268.83487)
		(width 0.0889)
		(layer "B.Cu")
		(net "TP_ESPI_IBL_CPU0_OE_LVC1_N")
	)
	(segment
		(start 333.679292 -268.611604)
		(end 334.26273 -268.611604)
		(width 0.12954)
		(layer "B.Cu")
		(net "TP_ESPI_IBL_CPU0_OE_LVC1_N")
	)
	(segment
		(start 340.141814 -268.894052)
		(end 340.152228 -268.887956)
		(width 0.0889)
		(layer "B.Cu")
		(net "TP_ESPI_IBL_CPU0_OE_LVC1_N")
	)
	(segment
		(start 332.54061 -268.394942)
		(end 333.46263 -268.394942)
		(width 0.12954)
		(layer "B.Cu")
		(net "TP_ESPI_IBL_CPU0_OE_LVC1_N")
	)
	(segment
		(start 351.419414 -268.894052)
		(end 351.434146 -268.885416)
		(width 0.0889)
		(layer "B.Cu")
		(net "TP_ESPI_IBL_CPU0_OE_LVC1_N")
	)
	(segment
		(start 344.840814 -268.894052)
		(end 344.855546 -268.885416)
		(width 0.0889)
		(layer "B.Cu")
		(net "TP_ESPI_IBL_CPU0_OE_LVC1_N")
	)
	(segment
		(start 339.20176 -268.894052)
		(end 339.212174 -268.887956)
		(width 0.0889)
		(layer "B.Cu")
		(net "TP_ESPI_IBL_CPU0_OE_LVC1_N")
	)
	(segment
		(start 346.720414 -268.894052)
		(end 346.730828 -268.887956)
		(width 0.0889)
		(layer "B.Cu")
		(net "TP_ESPI_IBL_CPU0_OE_LVC1_N")
	)
	(segment
		(start 352.359214 -268.894052)
		(end 352.373946 -268.885416)
		(width 0.0889)
		(layer "B.Cu")
		(net "TP_ESPI_IBL_CPU0_OE_LVC1_N")
	)
	(segment
		(start 354.240846 -267.43787)
		(end 354.991416 -266.941808)
		(width 0.0889)
		(layer "B.Cu")
		(net "TP_ESPI_IBL_CPU0_OE_LVC1_N")
	)
	(segment
		(start 343.901014 -268.894052)
		(end 343.915746 -268.885416)
		(width 0.0889)
		(layer "B.Cu")
		(net "TP_ESPI_IBL_CPU0_OE_LVC1_N")
	)
	(segment
		(start 347.65996 -268.894052)
		(end 347.670374 -268.887956)
		(width 0.0889)
		(layer "B.Cu")
		(net "TP_ESPI_IBL_CPU0_OE_LVC1_N")
	)
	(segment
		(start 345.780614 -268.894052)
		(end 345.795346 -268.885416)
		(width 0.0889)
		(layer "B.Cu")
		(net "TP_ESPI_IBL_CPU0_OE_LVC1_N")
	)
	(segment
		(start 341.08136 -268.894052)
		(end 341.091774 -268.887956)
		(width 0.0889)
		(layer "B.Cu")
		(net "TP_ESPI_IBL_CPU0_OE_LVC1_N")
	)
	(segment
		(start 331.986128 -268.949424)
		(end 332.54061 -268.394942)
		(width 0.12954)
		(layer "B.Cu")
		(net "TP_ESPI_IBL_CPU0_OE_LVC1_N")
	)
	(segment
		(start 333.46263 -268.394942)
		(end 333.679292 -268.611604)
		(width 0.12954)
		(layer "B.Cu")
		(net "TP_ESPI_IBL_CPU0_OE_LVC1_N")
	)
	(segment
		(start 348.600014 -268.894052)
		(end 348.614746 -268.885416)
		(width 0.0889)
		(layer "B.Cu")
		(net "TP_ESPI_IBL_CPU0_OE_LVC1_N")
	)
	(segment
		(start 334.26273 -268.611604)
		(end 334.76692 -268.611604)
		(width 0.0889)
		(layer "B.Cu")
		(net "TP_ESPI_IBL_CPU0_OE_LVC1_N")
	)
	(segment
		(start 342.021414 -268.894052)
		(end 342.036146 -268.885416)
		(width 0.0889)
		(layer "B.Cu")
		(net "TP_ESPI_IBL_CPU0_OE_LVC1_N")
	)
	(segment
		(start 353.36607 -268.96949)
		(end 354.240846 -267.43787)
		(width 0.0889)
		(layer "B.Cu")
		(net "TP_ESPI_IBL_CPU0_OE_LVC1_N")
	)
	(segment
		(start 352.9711 -268.96949)
		(end 353.36607 -268.96949)
		(width 0.0889)
		(layer "B.Cu")
		(net "TP_ESPI_IBL_CPU0_OE_LVC1_N")
	)
	(arc
		(start 341.647018 -268.894052)
		(mid 341.834216 -268.944195)
		(end 342.021414 -268.894052)
		(width 0.0889)
		(layer "B.Cu")
		(net "TP_ESPI_IBL_CPU0_OE_LVC1_N")
	)
	(arc
		(start 347.285564 -268.894052)
		(mid 347.472762 -268.944195)
		(end 347.65996 -268.894052)
		(width 0.0889)
		(layer "B.Cu")
		(net "TP_ESPI_IBL_CPU0_OE_LVC1_N")
	)
	(arc
		(start 342.961214 -268.894052)
		(mid 343.243916 -268.818276)
		(end 343.526618 -268.894052)
		(width 0.0889)
		(layer "B.Cu")
		(net "TP_ESPI_IBL_CPU0_OE_LVC1_N")
	)
	(arc
		(start 347.670374 -268.887956)
		(mid 347.948806 -268.81811)
		(end 348.225618 -268.894052)
		(width 0.0889)
		(layer "B.Cu")
		(net "TP_ESPI_IBL_CPU0_OE_LVC1_N")
	)
	(arc
		(start 349.539814 -268.894052)
		(mid 349.822516 -268.818276)
		(end 350.105218 -268.894052)
		(width 0.0889)
		(layer "B.Cu")
		(net "TP_ESPI_IBL_CPU0_OE_LVC1_N")
	)
	(arc
		(start 344.855546 -268.885416)
		(mid 345.132021 -268.818096)
		(end 345.406218 -268.894052)
		(width 0.0889)
		(layer "B.Cu")
		(net "TP_ESPI_IBL_CPU0_OE_LVC1_N")
	)
	(arc
		(start 336.007964 -268.894052)
		(mid 336.195162 -268.944195)
		(end 336.38236 -268.894052)
		(width 0.0889)
		(layer "B.Cu")
		(net "TP_ESPI_IBL_CPU0_OE_LVC1_N")
	)
	(arc
		(start 336.947764 -268.894052)
		(mid 337.134962 -268.944195)
		(end 337.32216 -268.894052)
		(width 0.0889)
		(layer "B.Cu")
		(net "TP_ESPI_IBL_CPU0_OE_LVC1_N")
	)
	(arc
		(start 338.26196 -268.894052)
		(mid 338.544662 -268.818276)
		(end 338.827364 -268.894052)
		(width 0.0889)
		(layer "B.Cu")
		(net "TP_ESPI_IBL_CPU0_OE_LVC1_N")
	)
	(arc
		(start 350.105218 -268.894052)
		(mid 350.292416 -268.944195)
		(end 350.479614 -268.894052)
		(width 0.0889)
		(layer "B.Cu")
		(net "TP_ESPI_IBL_CPU0_OE_LVC1_N")
	)
	(arc
		(start 336.38236 -268.894052)
		(mid 336.665062 -268.818276)
		(end 336.947764 -268.894052)
		(width 0.0889)
		(layer "B.Cu")
		(net "TP_ESPI_IBL_CPU0_OE_LVC1_N")
	)
	(arc
		(start 352.373946 -268.885416)
		(mid 352.61769 -268.818537)
		(end 352.866198 -268.864588)
		(width 0.0889)
		(layer "B.Cu")
		(net "TP_ESPI_IBL_CPU0_OE_LVC1_N")
	)
	(arc
		(start 345.406218 -268.894052)
		(mid 345.593416 -268.944195)
		(end 345.780614 -268.894052)
		(width 0.0889)
		(layer "B.Cu")
		(net "TP_ESPI_IBL_CPU0_OE_LVC1_N")
	)
	(arc
		(start 341.091774 -268.887956)
		(mid 341.370206 -268.81811)
		(end 341.647018 -268.894052)
		(width 0.0889)
		(layer "B.Cu")
		(net "TP_ESPI_IBL_CPU0_OE_LVC1_N")
	)
	(arc
		(start 340.152228 -268.887956)
		(mid 340.430406 -268.818233)
		(end 340.706964 -268.894052)
		(width 0.0889)
		(layer "B.Cu")
		(net "TP_ESPI_IBL_CPU0_OE_LVC1_N")
	)
	(arc
		(start 342.586818 -268.894052)
		(mid 342.774016 -268.944195)
		(end 342.961214 -268.894052)
		(width 0.0889)
		(layer "B.Cu")
		(net "TP_ESPI_IBL_CPU0_OE_LVC1_N")
	)
	(arc
		(start 346.730828 -268.887956)
		(mid 347.009006 -268.818233)
		(end 347.285564 -268.894052)
		(width 0.0889)
		(layer "B.Cu")
		(net "TP_ESPI_IBL_CPU0_OE_LVC1_N")
	)
	(arc
		(start 335.068164 -268.894052)
		(mid 335.255362 -268.944195)
		(end 335.44256 -268.894052)
		(width 0.0889)
		(layer "B.Cu")
		(net "TP_ESPI_IBL_CPU0_OE_LVC1_N")
	)
	(arc
		(start 348.225618 -268.894052)
		(mid 348.412816 -268.944195)
		(end 348.600014 -268.894052)
		(width 0.0889)
		(layer "B.Cu")
		(net "TP_ESPI_IBL_CPU0_OE_LVC1_N")
	)
	(arc
		(start 339.212174 -268.887956)
		(mid 339.490606 -268.81811)
		(end 339.767418 -268.894052)
		(width 0.0889)
		(layer "B.Cu")
		(net "TP_ESPI_IBL_CPU0_OE_LVC1_N")
	)
	(arc
		(start 334.990186 -268.83487)
		(mid 335.027236 -268.867016)
		(end 335.068164 -268.894052)
		(width 0.0889)
		(layer "B.Cu")
		(net "TP_ESPI_IBL_CPU0_OE_LVC1_N")
	)
	(arc
		(start 338.827364 -268.894052)
		(mid 339.014562 -268.944195)
		(end 339.20176 -268.894052)
		(width 0.0889)
		(layer "B.Cu")
		(net "TP_ESPI_IBL_CPU0_OE_LVC1_N")
	)
	(arc
		(start 344.466418 -268.894052)
		(mid 344.653616 -268.944195)
		(end 344.840814 -268.894052)
		(width 0.0889)
		(layer "B.Cu")
		(net "TP_ESPI_IBL_CPU0_OE_LVC1_N")
	)
	(arc
		(start 340.706964 -268.894052)
		(mid 340.894162 -268.944195)
		(end 341.08136 -268.894052)
		(width 0.0889)
		(layer "B.Cu")
		(net "TP_ESPI_IBL_CPU0_OE_LVC1_N")
	)
	(arc
		(start 337.887564 -268.894052)
		(mid 338.074762 -268.944195)
		(end 338.26196 -268.894052)
		(width 0.0889)
		(layer "B.Cu")
		(net "TP_ESPI_IBL_CPU0_OE_LVC1_N")
	)
	(arc
		(start 345.795346 -268.885416)
		(mid 346.071821 -268.818096)
		(end 346.346018 -268.894052)
		(width 0.0889)
		(layer "B.Cu")
		(net "TP_ESPI_IBL_CPU0_OE_LVC1_N")
	)
	(arc
		(start 343.526618 -268.894052)
		(mid 343.713816 -268.944195)
		(end 343.901014 -268.894052)
		(width 0.0889)
		(layer "B.Cu")
		(net "TP_ESPI_IBL_CPU0_OE_LVC1_N")
	)
	(arc
		(start 349.165418 -268.894052)
		(mid 349.352616 -268.944195)
		(end 349.539814 -268.894052)
		(width 0.0889)
		(layer "B.Cu")
		(net "TP_ESPI_IBL_CPU0_OE_LVC1_N")
	)
	(arc
		(start 343.915746 -268.885416)
		(mid 344.192221 -268.818096)
		(end 344.466418 -268.894052)
		(width 0.0889)
		(layer "B.Cu")
		(net "TP_ESPI_IBL_CPU0_OE_LVC1_N")
	)
	(arc
		(start 346.346018 -268.894052)
		(mid 346.533216 -268.944195)
		(end 346.720414 -268.894052)
		(width 0.0889)
		(layer "B.Cu")
		(net "TP_ESPI_IBL_CPU0_OE_LVC1_N")
	)
	(arc
		(start 351.434146 -268.885416)
		(mid 351.710621 -268.818096)
		(end 351.984818 -268.894052)
		(width 0.0889)
		(layer "B.Cu")
		(net "TP_ESPI_IBL_CPU0_OE_LVC1_N")
	)
	(arc
		(start 351.045018 -268.894052)
		(mid 351.232216 -268.944195)
		(end 351.419414 -268.894052)
		(width 0.0889)
		(layer "B.Cu")
		(net "TP_ESPI_IBL_CPU0_OE_LVC1_N")
	)
	(arc
		(start 337.32216 -268.894052)
		(mid 337.604862 -268.818276)
		(end 337.887564 -268.894052)
		(width 0.0889)
		(layer "B.Cu")
		(net "TP_ESPI_IBL_CPU0_OE_LVC1_N")
	)
	(arc
		(start 348.614746 -268.885416)
		(mid 348.891221 -268.818096)
		(end 349.165418 -268.894052)
		(width 0.0889)
		(layer "B.Cu")
		(net "TP_ESPI_IBL_CPU0_OE_LVC1_N")
	)
	(arc
		(start 339.767418 -268.894052)
		(mid 339.954616 -268.944195)
		(end 340.141814 -268.894052)
		(width 0.0889)
		(layer "B.Cu")
		(net "TP_ESPI_IBL_CPU0_OE_LVC1_N")
	)
	(arc
		(start 351.984818 -268.894052)
		(mid 352.172016 -268.944195)
		(end 352.359214 -268.894052)
		(width 0.0889)
		(layer "B.Cu")
		(net "TP_ESPI_IBL_CPU0_OE_LVC1_N")
	)
	(arc
		(start 342.036146 -268.885416)
		(mid 342.312621 -268.818096)
		(end 342.586818 -268.894052)
		(width 0.0889)
		(layer "B.Cu")
		(net "TP_ESPI_IBL_CPU0_OE_LVC1_N")
	)
	(arc
		(start 350.479614 -268.894052)
		(mid 350.762316 -268.818276)
		(end 351.045018 -268.894052)
		(width 0.0889)
		(layer "B.Cu")
		(net "TP_ESPI_IBL_CPU0_OE_LVC1_N")
	)
	(arc
		(start 335.44256 -268.894052)
		(mid 335.725262 -268.818276)
		(end 336.007964 -268.894052)
		(width 0.0889)
		(layer "B.Cu")
		(net "TP_ESPI_IBL_CPU0_OE_LVC1_N")
	)
	(segment
		(start 356.871016 -266.406122)
		(end 356.871016 -266.941808)
		(width 0.12954)
		(layer "F.Cu")
		(net "TP_ESPI_IBL_CPU0_IO3_LVC1")
	)
	(segment
		(start 356.870762 -266.405868)
		(end 356.871016 -266.406122)
		(width 0.12954)
		(layer "F.Cu")
		(net "TP_ESPI_IBL_CPU0_IO3_LVC1")
	)
	(via
		(at 356.871016 -266.941808)
		(size 0.4572)
		(drill 0.2032)
		(layers "F.Cu" "B.Cu")
		(net "TP_ESPI_IBL_CPU0_IO3_LVC1")
	)
	(segment
		(start 349.822516 -267.219938)
		(end 349.822262 -267.220192)
		(width 0.12954)
		(layer "F.Cu")
		(net "TP_ESPI_IBL_CPU0_IO2_LVC1")
	)
	(segment
		(start 349.822262 -267.220192)
		(end 349.822262 -267.755878)
		(width 0.12954)
		(layer "F.Cu")
		(net "TP_ESPI_IBL_CPU0_IO2_LVC1")
	)
	(via
		(at 349.822262 -267.755878)
		(size 0.4572)
		(drill 0.2032)
		(layers "F.Cu" "B.Cu")
		(net "TP_ESPI_IBL_CPU0_IO2_LVC1")
	)
	(segment
		(start 355.461316 -267.219938)
		(end 355.461316 -267.755624)
		(width 0.12954)
		(layer "F.Cu")
		(net "TP_ESPI_IBL_CPU0_IO1_LVC1")
	)
	(segment
		(start 355.461316 -267.755624)
		(end 355.461062 -267.755878)
		(width 0.12954)
		(layer "F.Cu")
		(net "TP_ESPI_IBL_CPU0_IO1_LVC1")
	)
	(via
		(at 355.461062 -267.755878)
		(size 0.4572)
		(drill 0.2032)
		(layers "F.Cu" "B.Cu")
		(net "TP_ESPI_IBL_CPU0_IO1_LVC1")
	)
	(segment
		(start 355.930962 -266.405868)
		(end 355.931216 -266.406122)
		(width 0.12954)
		(layer "F.Cu")
		(net "TP_ESPI_IBL_CPU0_IO0_LVC1")
	)
	(segment
		(start 355.931216 -266.406122)
		(end 355.931216 -266.941808)
		(width 0.12954)
		(layer "F.Cu")
		(net "TP_ESPI_IBL_CPU0_IO0_LVC1")
	)
	(via
		(at 355.931216 -266.941808)
		(size 0.4572)
		(drill 0.2032)
		(layers "F.Cu" "B.Cu")
		(net "TP_ESPI_IBL_CPU0_IO0_LVC1")
	)
	(segment
		(start 354.991162 -268.033754)
		(end 354.991416 -268.034008)
		(width 0.12954)
		(layer "F.Cu")
		(net "TP_ESPI_IBL_CPU0_CS1_N")
	)
	(segment
		(start 354.991416 -268.034008)
		(end 354.991416 -268.569694)
		(width 0.12954)
		(layer "F.Cu")
		(net "TP_ESPI_IBL_CPU0_CS1_N")
	)
	(via
		(at 354.991416 -268.569694)
		(size 0.4572)
		(drill 0.2032)
		(layers "F.Cu" "B.Cu")
		(net "TP_ESPI_IBL_CPU0_CS1_N")
	)
	(segment
		(start 354.051616 -268.034008)
		(end 354.051616 -268.569694)
		(width 0.12954)
		(layer "F.Cu")
		(net "TP_ESPI_IBL_CPU0_CS0_LVC1_N")
	)
	(segment
		(start 354.051362 -268.033754)
		(end 354.051616 -268.034008)
		(width 0.12954)
		(layer "F.Cu")
		(net "TP_ESPI_IBL_CPU0_CS0_LVC1_N")
	)
	(via
		(at 354.051616 -268.569694)
		(size 0.4572)
		(drill 0.2032)
		(layers "F.Cu" "B.Cu")
		(net "TP_ESPI_IBL_CPU0_CS0_LVC1_N")
	)
	(segment
		(start 353.111816 -266.406122)
		(end 353.111816 -266.941808)
		(width 0.12954)
		(layer "F.Cu")
		(net "TP_ESPI_IBL_CPU0_ALERT1_N")
	)
	(segment
		(start 353.111562 -266.405868)
		(end 353.111816 -266.406122)
		(width 0.12954)
		(layer "F.Cu")
		(net "TP_ESPI_IBL_CPU0_ALERT1_N")
	)
	(via
		(at 353.111816 -266.941808)
		(size 0.4572)
		(drill 0.2032)
		(layers "F.Cu" "B.Cu")
		(net "TP_ESPI_IBL_CPU0_ALERT1_N")
	)
	(segment
		(start 353.581716 -266.127992)
		(end 353.581462 -266.128246)
		(width 0.12954)
		(layer "F.Cu")
		(net "TP_ESPI_IBL_CPU0_ALERT0_LVC1_N")
	)
	(segment
		(start 353.581716 -265.592306)
		(end 353.581716 -266.127992)
		(width 0.12954)
		(layer "F.Cu")
		(net "TP_ESPI_IBL_CPU0_ALERT0_LVC1_N")
	)
	(via
		(at 353.581462 -266.128246)
		(size 0.4572)
		(drill 0.2032)
		(layers "F.Cu" "B.Cu")
		(net "TP_ESPI_IBL_CPU0_ALERT0_LVC1_N")
	)
	(segment
		(start 339.748876 -41.871646)
		(end 339.209888 -41.871646)
		(width 0.12954)
		(layer "F.Cu")
		(net "TP_EDSFF1B_TYPE_ID")
	)
	(via
		(at 339.759798 -41.400476)
		(size 0.6604)
		(drill 0.3302)
		(layers "F.Cu" "B.Cu")
		(net "TP_EDSFF1B_TYPE_ID")
	)
	(via
		(at 339.209888 -41.871646)
		(size 0.4572)
		(drill 0.2032)
		(layers "F.Cu" "B.Cu")
		(net "TP_EDSFF1B_TYPE_ID")
	)
	(segment
		(start 339.759798 -41.400476)
		(end 339.288628 -41.871646)
		(width 0.12954)
		(layer "B.Cu")
		(net "TP_EDSFF1B_TYPE_ID")
	)
	(segment
		(start 339.288628 -41.871646)
		(end 339.209888 -41.871646)
		(width 0.12954)
		(layer "B.Cu")
		(net "TP_EDSFF1B_TYPE_ID")
	)
	(segment
		(start 337.581748 -41.871646)
		(end 338.120736 -41.871646)
		(width 0.12954)
		(layer "F.Cu")
		(net "TP_EDSFF1A_TYPE_ID")
	)
	(via
		(at 337.581748 -41.871646)
		(size 0.4572)
		(drill 0.2032)
		(layers "F.Cu" "B.Cu")
		(net "TP_EDSFF1A_TYPE_ID")
	)
	(segment
		(start 118.218712 -228.1809)
		(end 118.218966 -228.180646)
		(width 0.12954)
		(layer "F.Cu")
		(net "TP_DMI_CPU1_PCH_TX_DP<7>")
	)
	(segment
		(start 118.218966 -228.180646)
		(end 118.218966 -227.64496)
		(width 0.12954)
		(layer "F.Cu")
		(net "TP_DMI_CPU1_PCH_TX_DP<7>")
	)
	(via
		(at 118.218966 -227.64496)
		(size 0.4572)
		(drill 0.2032)
		(layers "F.Cu" "B.Cu")
		(net "TP_DMI_CPU1_PCH_TX_DP<7>")
	)
	(segment
		(start 117.748812 -228.994716)
		(end 117.748812 -228.45903)
		(width 0.12954)
		(layer "F.Cu")
		(net "TP_DMI_CPU1_PCH_TX_DP<6>")
	)
	(segment
		(start 117.749066 -228.99497)
		(end 117.748812 -228.994716)
		(width 0.12954)
		(layer "F.Cu")
		(net "TP_DMI_CPU1_PCH_TX_DP<6>")
	)
	(via
		(at 117.748812 -228.45903)
		(size 0.4572)
		(drill 0.2032)
		(layers "F.Cu" "B.Cu")
		(net "TP_DMI_CPU1_PCH_TX_DP<6>")
	)
	(segment
		(start 116.339366 -228.180646)
		(end 116.339366 -227.64496)
		(width 0.12954)
		(layer "F.Cu")
		(net "TP_DMI_CPU1_PCH_TX_DP<5>")
	)
	(segment
		(start 116.339112 -228.1809)
		(end 116.339366 -228.180646)
		(width 0.12954)
		(layer "F.Cu")
		(net "TP_DMI_CPU1_PCH_TX_DP<5>")
	)
	(via
		(at 116.339366 -227.64496)
		(size 0.4572)
		(drill 0.2032)
		(layers "F.Cu" "B.Cu")
		(net "TP_DMI_CPU1_PCH_TX_DP<5>")
	)
	(segment
		(start 115.869466 -228.99497)
		(end 115.869212 -228.994716)
		(width 0.12954)
		(layer "F.Cu")
		(net "TP_DMI_CPU1_PCH_TX_DP<4>")
	)
	(segment
		(start 115.869212 -228.994716)
		(end 115.869212 -228.45903)
		(width 0.12954)
		(layer "F.Cu")
		(net "TP_DMI_CPU1_PCH_TX_DP<4>")
	)
	(via
		(at 115.869212 -228.45903)
		(size 0.4572)
		(drill 0.2032)
		(layers "F.Cu" "B.Cu")
		(net "TP_DMI_CPU1_PCH_TX_DP<4>")
	)
	(segment
		(start 114.46002 -228.180646)
		(end 114.46002 -227.64496)
		(width 0.12954)
		(layer "F.Cu")
		(net "TP_DMI_CPU1_PCH_TX_DP<3>")
	)
	(segment
		(start 114.459766 -228.1809)
		(end 114.46002 -228.180646)
		(width 0.12954)
		(layer "F.Cu")
		(net "TP_DMI_CPU1_PCH_TX_DP<3>")
	)
	(via
		(at 114.46002 -227.64496)
		(size 0.4572)
		(drill 0.2032)
		(layers "F.Cu" "B.Cu")
		(net "TP_DMI_CPU1_PCH_TX_DP<3>")
	)
	(segment
		(start 113.989866 -228.99497)
		(end 113.989612 -228.994716)
		(width 0.12954)
		(layer "F.Cu")
		(net "TP_DMI_CPU1_PCH_TX_DP<2>")
	)
	(segment
		(start 113.989612 -228.994716)
		(end 113.989612 -228.45903)
		(width 0.12954)
		(layer "F.Cu")
		(net "TP_DMI_CPU1_PCH_TX_DP<2>")
	)
	(via
		(at 113.989612 -228.45903)
		(size 0.4572)
		(drill 0.2032)
		(layers "F.Cu" "B.Cu")
		(net "TP_DMI_CPU1_PCH_TX_DP<2>")
	)
	(segment
		(start 112.579912 -228.1809)
		(end 112.580166 -228.180646)
		(width 0.12954)
		(layer "F.Cu")
		(net "TP_DMI_CPU1_PCH_TX_DP<1>")
	)
	(segment
		(start 112.580166 -228.180646)
		(end 112.580166 -227.64496)
		(width 0.12954)
		(layer "F.Cu")
		(net "TP_DMI_CPU1_PCH_TX_DP<1>")
	)
	(via
		(at 112.580166 -227.64496)
		(size 0.4572)
		(drill 0.2032)
		(layers "F.Cu" "B.Cu")
		(net "TP_DMI_CPU1_PCH_TX_DP<1>")
	)
	(segment
		(start 113.050066 -228.99497)
		(end 113.049812 -228.994716)
		(width 0.12954)
		(layer "F.Cu")
		(net "TP_DMI_CPU1_PCH_TX_DP<0>")
	)
	(segment
		(start 113.049812 -228.994716)
		(end 113.049812 -228.45903)
		(width 0.12954)
		(layer "F.Cu")
		(net "TP_DMI_CPU1_PCH_TX_DP<0>")
	)
	(via
		(at 113.049812 -228.45903)
		(size 0.4572)
		(drill 0.2032)
		(layers "F.Cu" "B.Cu")
		(net "TP_DMI_CPU1_PCH_TX_DP<0>")
	)
	(segment
		(start 118.688612 -227.36683)
		(end 118.688612 -226.831144)
		(width 0.12954)
		(layer "F.Cu")
		(net "TP_DMI_CPU1_PCH_TX_DN<7>")
	)
	(segment
		(start 118.688866 -227.367084)
		(end 118.688612 -227.36683)
		(width 0.12954)
		(layer "F.Cu")
		(net "TP_DMI_CPU1_PCH_TX_DN<7>")
	)
	(via
		(at 118.688612 -226.831144)
		(size 0.4572)
		(drill 0.2032)
		(layers "F.Cu" "B.Cu")
		(net "TP_DMI_CPU1_PCH_TX_DN<7>")
	)
	(segment
		(start 117.279166 -228.180646)
		(end 117.279166 -227.64496)
		(width 0.12954)
		(layer "F.Cu")
		(net "TP_DMI_CPU1_PCH_TX_DN<6>")
	)
	(segment
		(start 117.278912 -228.1809)
		(end 117.279166 -228.180646)
		(width 0.12954)
		(layer "F.Cu")
		(net "TP_DMI_CPU1_PCH_TX_DN<6>")
	)
	(via
		(at 117.279166 -227.64496)
		(size 0.4572)
		(drill 0.2032)
		(layers "F.Cu" "B.Cu")
		(net "TP_DMI_CPU1_PCH_TX_DN<6>")
	)
	(segment
		(start 116.809266 -227.367084)
		(end 116.809012 -227.36683)
		(width 0.12954)
		(layer "F.Cu")
		(net "TP_DMI_CPU1_PCH_TX_DN<5>")
	)
	(segment
		(start 116.809012 -227.36683)
		(end 116.809012 -226.831144)
		(width 0.12954)
		(layer "F.Cu")
		(net "TP_DMI_CPU1_PCH_TX_DN<5>")
	)
	(via
		(at 116.809012 -226.831144)
		(size 0.4572)
		(drill 0.2032)
		(layers "F.Cu" "B.Cu")
		(net "TP_DMI_CPU1_PCH_TX_DN<5>")
	)
	(segment
		(start 115.399566 -228.180646)
		(end 115.399566 -227.64496)
		(width 0.12954)
		(layer "F.Cu")
		(net "TP_DMI_CPU1_PCH_TX_DN<4>")
	)
	(segment
		(start 115.399312 -228.1809)
		(end 115.399566 -228.180646)
		(width 0.12954)
		(layer "F.Cu")
		(net "TP_DMI_CPU1_PCH_TX_DN<4>")
	)
	(via
		(at 115.399566 -227.64496)
		(size 0.4572)
		(drill 0.2032)
		(layers "F.Cu" "B.Cu")
		(net "TP_DMI_CPU1_PCH_TX_DN<4>")
	)
	(segment
		(start 114.929666 -227.367084)
		(end 114.929666 -226.831144)
		(width 0.12954)
		(layer "F.Cu")
		(net "TP_DMI_CPU1_PCH_TX_DN<3>")
	)
	(via
		(at 114.929666 -226.831144)
		(size 0.4572)
		(drill 0.2032)
		(layers "F.Cu" "B.Cu")
		(net "TP_DMI_CPU1_PCH_TX_DN<3>")
	)
	(segment
		(start 113.519966 -228.180646)
		(end 113.519966 -227.64496)
		(width 0.12954)
		(layer "F.Cu")
		(net "TP_DMI_CPU1_PCH_TX_DN<2>")
	)
	(segment
		(start 113.519712 -228.1809)
		(end 113.519966 -228.180646)
		(width 0.12954)
		(layer "F.Cu")
		(net "TP_DMI_CPU1_PCH_TX_DN<2>")
	)
	(via
		(at 113.519966 -227.64496)
		(size 0.4572)
		(drill 0.2032)
		(layers "F.Cu" "B.Cu")
		(net "TP_DMI_CPU1_PCH_TX_DN<2>")
	)
	(segment
		(start 113.049812 -227.36683)
		(end 113.049812 -226.831144)
		(width 0.12954)
		(layer "F.Cu")
		(net "TP_DMI_CPU1_PCH_TX_DN<1>")
	)
	(segment
		(start 113.050066 -227.367084)
		(end 113.049812 -227.36683)
		(width 0.12954)
		(layer "F.Cu")
		(net "TP_DMI_CPU1_PCH_TX_DN<1>")
	)
	(via
		(at 113.049812 -226.831144)
		(size 0.4572)
		(drill 0.2032)
		(layers "F.Cu" "B.Cu")
		(net "TP_DMI_CPU1_PCH_TX_DN<1>")
	)
	(segment
		(start 112.110266 -228.99497)
		(end 112.110012 -228.994716)
		(width 0.12954)
		(layer "F.Cu")
		(net "TP_DMI_CPU1_PCH_TX_DN<0>")
	)
	(segment
		(start 112.110012 -228.994716)
		(end 112.110012 -228.45903)
		(width 0.12954)
		(layer "F.Cu")
		(net "TP_DMI_CPU1_PCH_TX_DN<0>")
	)
	(via
		(at 112.110012 -228.45903)
		(size 0.4572)
		(drill 0.2032)
		(layers "F.Cu" "B.Cu")
		(net "TP_DMI_CPU1_PCH_TX_DN<0>")
	)
	(segment
		(start 110.700566 -228.1809)
		(end 110.700566 -227.64496)
		(width 0.12954)
		(layer "F.Cu")
		(net "TP_DMI_CPU1_PCH_RX_C_DP<7>")
	)
	(via
		(at 110.700566 -227.64496)
		(size 0.4572)
		(drill 0.2032)
		(layers "F.Cu" "B.Cu")
		(net "TP_DMI_CPU1_PCH_RX_C_DP<7>")
	)
	(segment
		(start 110.230412 -228.994716)
		(end 110.230412 -228.45903)
		(width 0.12954)
		(layer "F.Cu")
		(net "TP_DMI_CPU1_PCH_RX_C_DP<6>")
	)
	(segment
		(start 110.230666 -228.99497)
		(end 110.230412 -228.994716)
		(width 0.12954)
		(layer "F.Cu")
		(net "TP_DMI_CPU1_PCH_RX_C_DP<6>")
	)
	(via
		(at 110.230412 -228.45903)
		(size 0.4572)
		(drill 0.2032)
		(layers "F.Cu" "B.Cu")
		(net "TP_DMI_CPU1_PCH_RX_C_DP<6>")
	)
	(segment
		(start 108.820712 -228.1809)
		(end 108.820966 -228.180646)
		(width 0.12954)
		(layer "F.Cu")
		(net "TP_DMI_CPU1_PCH_RX_C_DP<5>")
	)
	(segment
		(start 108.820966 -228.180646)
		(end 108.820966 -227.64496)
		(width 0.12954)
		(layer "F.Cu")
		(net "TP_DMI_CPU1_PCH_RX_C_DP<5>")
	)
	(via
		(at 108.820966 -227.64496)
		(size 0.4572)
		(drill 0.2032)
		(layers "F.Cu" "B.Cu")
		(net "TP_DMI_CPU1_PCH_RX_C_DP<5>")
	)
	(segment
		(start 108.351066 -228.99497)
		(end 108.350812 -228.994716)
		(width 0.12954)
		(layer "F.Cu")
		(net "TP_DMI_CPU1_PCH_RX_C_DP<4>")
	)
	(segment
		(start 108.350812 -228.994716)
		(end 108.350812 -228.45903)
		(width 0.12954)
		(layer "F.Cu")
		(net "TP_DMI_CPU1_PCH_RX_C_DP<4>")
	)
	(via
		(at 108.350812 -228.45903)
		(size 0.4572)
		(drill 0.2032)
		(layers "F.Cu" "B.Cu")
		(net "TP_DMI_CPU1_PCH_RX_C_DP<4>")
	)
	(segment
		(start 106.941112 -228.1809)
		(end 106.941366 -228.180646)
		(width 0.12954)
		(layer "F.Cu")
		(net "TP_DMI_CPU1_PCH_RX_C_DP<3>")
	)
	(segment
		(start 106.941366 -228.180646)
		(end 106.941366 -227.64496)
		(width 0.12954)
		(layer "F.Cu")
		(net "TP_DMI_CPU1_PCH_RX_C_DP<3>")
	)
	(via
		(at 106.941366 -227.64496)
		(size 0.4572)
		(drill 0.2032)
		(layers "F.Cu" "B.Cu")
		(net "TP_DMI_CPU1_PCH_RX_C_DP<3>")
	)
	(segment
		(start 106.471466 -228.459284)
		(end 106.471212 -228.45903)
		(width 0.12954)
		(layer "F.Cu")
		(net "TP_DMI_CPU1_PCH_RX_C_DP<2>")
	)
	(segment
		(start 106.471466 -228.99497)
		(end 106.471466 -228.459284)
		(width 0.12954)
		(layer "F.Cu")
		(net "TP_DMI_CPU1_PCH_RX_C_DP<2>")
	)
	(via
		(at 106.471212 -228.45903)
		(size 0.4572)
		(drill 0.2032)
		(layers "F.Cu" "B.Cu")
		(net "TP_DMI_CPU1_PCH_RX_C_DP<2>")
	)
	(segment
		(start 105.061766 -228.180646)
		(end 105.061766 -227.64496)
		(width 0.12954)
		(layer "F.Cu")
		(net "TP_DMI_CPU1_PCH_RX_C_DP<1>")
	)
	(segment
		(start 105.061512 -228.1809)
		(end 105.061766 -228.180646)
		(width 0.12954)
		(layer "F.Cu")
		(net "TP_DMI_CPU1_PCH_RX_C_DP<1>")
	)
	(via
		(at 105.061766 -227.64496)
		(size 0.4572)
		(drill 0.2032)
		(layers "F.Cu" "B.Cu")
		(net "TP_DMI_CPU1_PCH_RX_C_DP<1>")
	)
	(segment
		(start 104.591866 -228.459284)
		(end 104.591612 -228.45903)
		(width 0.12954)
		(layer "F.Cu")
		(net "TP_DMI_CPU1_PCH_RX_C_DP<0>")
	)
	(segment
		(start 104.591866 -228.99497)
		(end 104.591866 -228.459284)
		(width 0.12954)
		(layer "F.Cu")
		(net "TP_DMI_CPU1_PCH_RX_C_DP<0>")
	)
	(via
		(at 104.591612 -228.45903)
		(size 0.4572)
		(drill 0.2032)
		(layers "F.Cu" "B.Cu")
		(net "TP_DMI_CPU1_PCH_RX_C_DP<0>")
	)
	(segment
		(start 111.170466 -226.831398)
		(end 111.170212 -226.831144)
		(width 0.12954)
		(layer "F.Cu")
		(net "TP_DMI_CPU1_PCH_RX_C_DN<7>")
	)
	(segment
		(start 111.170466 -227.367084)
		(end 111.170466 -226.831398)
		(width 0.12954)
		(layer "F.Cu")
		(net "TP_DMI_CPU1_PCH_RX_C_DN<7>")
	)
	(via
		(at 111.170212 -226.831144)
		(size 0.4572)
		(drill 0.2032)
		(layers "F.Cu" "B.Cu")
		(net "TP_DMI_CPU1_PCH_RX_C_DN<7>")
	)
	(segment
		(start 109.760512 -228.1809)
		(end 109.760512 -227.645214)
		(width 0.12954)
		(layer "F.Cu")
		(net "TP_DMI_CPU1_PCH_RX_C_DN<6>")
	)
	(segment
		(start 109.760512 -227.645214)
		(end 109.760766 -227.64496)
		(width 0.12954)
		(layer "F.Cu")
		(net "TP_DMI_CPU1_PCH_RX_C_DN<6>")
	)
	(via
		(at 109.760766 -227.64496)
		(size 0.4572)
		(drill 0.2032)
		(layers "F.Cu" "B.Cu")
		(net "TP_DMI_CPU1_PCH_RX_C_DN<6>")
	)
	(segment
		(start 109.290612 -227.36683)
		(end 109.290612 -226.831144)
		(width 0.12954)
		(layer "F.Cu")
		(net "TP_DMI_CPU1_PCH_RX_C_DN<5>")
	)
	(segment
		(start 109.290866 -227.367084)
		(end 109.290612 -227.36683)
		(width 0.12954)
		(layer "F.Cu")
		(net "TP_DMI_CPU1_PCH_RX_C_DN<5>")
	)
	(via
		(at 109.290612 -226.831144)
		(size 0.4572)
		(drill 0.2032)
		(layers "F.Cu" "B.Cu")
		(net "TP_DMI_CPU1_PCH_RX_C_DN<5>")
	)
	(segment
		(start 107.880912 -228.1809)
		(end 107.880912 -227.645214)
		(width 0.12954)
		(layer "F.Cu")
		(net "TP_DMI_CPU1_PCH_RX_C_DN<4>")
	)
	(segment
		(start 107.880912 -227.645214)
		(end 107.881166 -227.64496)
		(width 0.12954)
		(layer "F.Cu")
		(net "TP_DMI_CPU1_PCH_RX_C_DN<4>")
	)
	(via
		(at 107.881166 -227.64496)
		(size 0.4572)
		(drill 0.2032)
		(layers "F.Cu" "B.Cu")
		(net "TP_DMI_CPU1_PCH_RX_C_DN<4>")
	)
	(segment
		(start 107.411266 -226.831398)
		(end 107.411012 -226.831144)
		(width 0.12954)
		(layer "F.Cu")
		(net "TP_DMI_CPU1_PCH_RX_C_DN<3>")
	)
	(segment
		(start 107.411266 -227.367084)
		(end 107.411266 -226.831398)
		(width 0.12954)
		(layer "F.Cu")
		(net "TP_DMI_CPU1_PCH_RX_C_DN<3>")
	)
	(via
		(at 107.411012 -226.831144)
		(size 0.4572)
		(drill 0.2032)
		(layers "F.Cu" "B.Cu")
		(net "TP_DMI_CPU1_PCH_RX_C_DN<3>")
	)
	(segment
		(start 106.001312 -227.645214)
		(end 106.001566 -227.64496)
		(width 0.12954)
		(layer "F.Cu")
		(net "TP_DMI_CPU1_PCH_RX_C_DN<2>")
	)
	(segment
		(start 106.001312 -228.1809)
		(end 106.001312 -227.645214)
		(width 0.12954)
		(layer "F.Cu")
		(net "TP_DMI_CPU1_PCH_RX_C_DN<2>")
	)
	(via
		(at 106.001566 -227.64496)
		(size 0.4572)
		(drill 0.2032)
		(layers "F.Cu" "B.Cu")
		(net "TP_DMI_CPU1_PCH_RX_C_DN<2>")
	)
	(segment
		(start 105.531666 -226.831398)
		(end 105.531412 -226.831144)
		(width 0.12954)
		(layer "F.Cu")
		(net "TP_DMI_CPU1_PCH_RX_C_DN<1>")
	)
	(segment
		(start 105.531666 -227.367084)
		(end 105.531666 -226.831398)
		(width 0.12954)
		(layer "F.Cu")
		(net "TP_DMI_CPU1_PCH_RX_C_DN<1>")
	)
	(via
		(at 105.531412 -226.831144)
		(size 0.4572)
		(drill 0.2032)
		(layers "F.Cu" "B.Cu")
		(net "TP_DMI_CPU1_PCH_RX_C_DN<1>")
	)
	(segment
		(start 104.121966 -228.180646)
		(end 104.121966 -227.64496)
		(width 0.12954)
		(layer "F.Cu")
		(net "TP_DMI_CPU1_PCH_RX_C_DN<0>")
	)
	(segment
		(start 104.121712 -228.1809)
		(end 104.121966 -228.180646)
		(width 0.12954)
		(layer "F.Cu")
		(net "TP_DMI_CPU1_PCH_RX_C_DN<0>")
	)
	(via
		(at 104.121966 -227.64496)
		(size 0.4572)
		(drill 0.2032)
		(layers "F.Cu" "B.Cu")
		(net "TP_DMI_CPU1_PCH_RX_C_DN<0>")
	)
	(segment
		(start 117.859048 -268.84757)
		(end 117.859048 -269.38351)
		(width 0.12954)
		(layer "F.Cu")
		(net "TP_CPU1_SSC_SYNC")
	)
	(via
		(at 153.6827 -270.730218)
		(size 0.6604)
		(drill 0.3302)
		(layers "F.Cu" "B.Cu")
		(net "TP_CPU1_SSC_SYNC")
	)
	(via
		(at 117.859048 -269.38351)
		(size 0.4572)
		(drill 0.2032)
		(layers "F.Cu" "B.Cu")
		(net "TP_CPU1_SSC_SYNC")
	)
	(segment
		(start 117.723666 -269.034514)
		(end 117.702584 -269.112492)
		(width 0.0889)
		(layer "B.Cu")
		(net "TP_CPU1_SSC_SYNC")
	)
	(segment
		(start 121.43105 -269.059152)
		(end 121.420636 -269.065248)
		(width 0.0889)
		(layer "B.Cu")
		(net "TP_CPU1_SSC_SYNC")
	)
	(segment
		(start 121.81586 -269.065248)
		(end 121.805446 -269.059152)
		(width 0.0889)
		(layer "B.Cu")
		(net "TP_CPU1_SSC_SYNC")
	)
	(segment
		(start 119.93626 -269.065248)
		(end 119.925846 -269.059152)
		(width 0.0889)
		(layer "B.Cu")
		(net "TP_CPU1_SSC_SYNC")
	)
	(segment
		(start 153.6827 -270.730218)
		(end 152.517348 -269.564866)
		(width 0.12954)
		(layer "B.Cu")
		(net "TP_CPU1_SSC_SYNC")
	)
	(segment
		(start 117.702584 -269.112492)
		(end 117.859048 -269.38351)
		(width 0.0889)
		(layer "B.Cu")
		(net "TP_CPU1_SSC_SYNC")
	)
	(segment
		(start 152.517348 -269.564866)
		(end 137.700512 -269.564866)
		(width 0.12954)
		(layer "B.Cu")
		(net "TP_CPU1_SSC_SYNC")
	)
	(segment
		(start 129.888996 -269.059152)
		(end 129.874264 -269.067788)
		(width 0.0889)
		(layer "B.Cu")
		(net "TP_CPU1_SSC_SYNC")
	)
	(segment
		(start 133.648196 -269.059152)
		(end 133.637782 -269.065248)
		(width 0.0889)
		(layer "B.Cu")
		(net "TP_CPU1_SSC_SYNC")
	)
	(segment
		(start 137.32383 -269.188438)
		(end 137.323576 -269.188438)
		(width 0.0889)
		(layer "B.Cu")
		(net "TP_CPU1_SSC_SYNC")
	)
	(segment
		(start 126.129796 -269.059152)
		(end 126.115064 -269.067788)
		(width 0.0889)
		(layer "B.Cu")
		(net "TP_CPU1_SSC_SYNC")
	)
	(segment
		(start 137.700512 -269.564866)
		(end 137.512298 -269.376652)
		(width 0.12954)
		(layer "B.Cu")
		(net "TP_CPU1_SSC_SYNC")
	)
	(segment
		(start 128.009396 -269.059152)
		(end 127.994664 -269.067788)
		(width 0.0889)
		(layer "B.Cu")
		(net "TP_CPU1_SSC_SYNC")
	)
	(segment
		(start 128.949196 -269.059152)
		(end 128.934464 -269.067788)
		(width 0.0889)
		(layer "B.Cu")
		(net "TP_CPU1_SSC_SYNC")
	)
	(segment
		(start 119.000778 -269.067788)
		(end 118.986046 -269.059152)
		(width 0.0889)
		(layer "B.Cu")
		(net "TP_CPU1_SSC_SYNC")
	)
	(segment
		(start 127.069596 -269.059152)
		(end 127.054864 -269.067788)
		(width 0.0889)
		(layer "B.Cu")
		(net "TP_CPU1_SSC_SYNC")
	)
	(segment
		(start 132.70865 -269.059152)
		(end 132.698236 -269.065248)
		(width 0.0889)
		(layer "B.Cu")
		(net "TP_CPU1_SSC_SYNC")
	)
	(segment
		(start 130.828796 -269.059152)
		(end 130.814064 -269.067788)
		(width 0.0889)
		(layer "B.Cu")
		(net "TP_CPU1_SSC_SYNC")
	)
	(segment
		(start 134.587996 -269.059152)
		(end 134.573264 -269.067788)
		(width 0.0889)
		(layer "B.Cu")
		(net "TP_CPU1_SSC_SYNC")
	)
	(segment
		(start 125.189996 -269.059152)
		(end 125.175264 -269.067788)
		(width 0.0889)
		(layer "B.Cu")
		(net "TP_CPU1_SSC_SYNC")
	)
	(segment
		(start 124.250196 -269.059152)
		(end 124.235464 -269.067788)
		(width 0.0889)
		(layer "B.Cu")
		(net "TP_CPU1_SSC_SYNC")
	)
	(segment
		(start 131.768596 -269.059152)
		(end 131.753864 -269.067788)
		(width 0.0889)
		(layer "B.Cu")
		(net "TP_CPU1_SSC_SYNC")
	)
	(segment
		(start 137.512298 -269.376652)
		(end 137.32383 -269.188438)
		(width 0.0889)
		(layer "B.Cu")
		(net "TP_CPU1_SSC_SYNC")
	)
	(segment
		(start 135.527796 -269.059152)
		(end 135.513064 -269.067788)
		(width 0.0889)
		(layer "B.Cu")
		(net "TP_CPU1_SSC_SYNC")
	)
	(arc
		(start 127.994664 -269.067788)
		(mid 127.718189 -269.135108)
		(end 127.443992 -269.059152)
		(width 0.0889)
		(layer "B.Cu")
		(net "TP_CPU1_SSC_SYNC")
	)
	(arc
		(start 120.865392 -269.059152)
		(mid 120.678194 -269.009009)
		(end 120.490996 -269.059152)
		(width 0.0889)
		(layer "B.Cu")
		(net "TP_CPU1_SSC_SYNC")
	)
	(arc
		(start 136.467596 -269.059152)
		(mid 136.184894 -269.134928)
		(end 135.902192 -269.059152)
		(width 0.0889)
		(layer "B.Cu")
		(net "TP_CPU1_SSC_SYNC")
	)
	(arc
		(start 128.934464 -269.067788)
		(mid 128.657989 -269.135108)
		(end 128.383792 -269.059152)
		(width 0.0889)
		(layer "B.Cu")
		(net "TP_CPU1_SSC_SYNC")
	)
	(arc
		(start 118.046246 -269.059152)
		(mid 117.887758 -269.010219)
		(end 117.723666 -269.034514)
		(width 0.0889)
		(layer "B.Cu")
		(net "TP_CPU1_SSC_SYNC")
	)
	(arc
		(start 132.142992 -269.059152)
		(mid 131.955794 -269.009009)
		(end 131.768596 -269.059152)
		(width 0.0889)
		(layer "B.Cu")
		(net "TP_CPU1_SSC_SYNC")
	)
	(arc
		(start 122.370596 -269.059152)
		(mid 122.094037 -269.134895)
		(end 121.81586 -269.065248)
		(width 0.0889)
		(layer "B.Cu")
		(net "TP_CPU1_SSC_SYNC")
	)
	(arc
		(start 127.443992 -269.059152)
		(mid 127.256794 -269.009009)
		(end 127.069596 -269.059152)
		(width 0.0889)
		(layer "B.Cu")
		(net "TP_CPU1_SSC_SYNC")
	)
	(arc
		(start 131.753864 -269.067788)
		(mid 131.477389 -269.135108)
		(end 131.203192 -269.059152)
		(width 0.0889)
		(layer "B.Cu")
		(net "TP_CPU1_SSC_SYNC")
	)
	(arc
		(start 123.684792 -269.059152)
		(mid 123.497594 -269.009009)
		(end 123.310396 -269.059152)
		(width 0.0889)
		(layer "B.Cu")
		(net "TP_CPU1_SSC_SYNC")
	)
	(arc
		(start 127.054864 -269.067788)
		(mid 126.778389 -269.135108)
		(end 126.504192 -269.059152)
		(width 0.0889)
		(layer "B.Cu")
		(net "TP_CPU1_SSC_SYNC")
	)
	(arc
		(start 126.115064 -269.067788)
		(mid 125.838589 -269.135108)
		(end 125.564392 -269.059152)
		(width 0.0889)
		(layer "B.Cu")
		(net "TP_CPU1_SSC_SYNC")
	)
	(arc
		(start 134.573264 -269.067788)
		(mid 134.296789 -269.135108)
		(end 134.022592 -269.059152)
		(width 0.0889)
		(layer "B.Cu")
		(net "TP_CPU1_SSC_SYNC")
	)
	(arc
		(start 125.175264 -269.067788)
		(mid 124.898789 -269.135108)
		(end 124.624592 -269.059152)
		(width 0.0889)
		(layer "B.Cu")
		(net "TP_CPU1_SSC_SYNC")
	)
	(arc
		(start 125.564392 -269.059152)
		(mid 125.377194 -269.009009)
		(end 125.189996 -269.059152)
		(width 0.0889)
		(layer "B.Cu")
		(net "TP_CPU1_SSC_SYNC")
	)
	(arc
		(start 130.263392 -269.059152)
		(mid 130.076194 -269.009009)
		(end 129.888996 -269.059152)
		(width 0.0889)
		(layer "B.Cu")
		(net "TP_CPU1_SSC_SYNC")
	)
	(arc
		(start 123.310396 -269.059152)
		(mid 123.027694 -269.134928)
		(end 122.744992 -269.059152)
		(width 0.0889)
		(layer "B.Cu")
		(net "TP_CPU1_SSC_SYNC")
	)
	(arc
		(start 137.323576 -269.188438)
		(mid 137.074252 -269.155564)
		(end 136.841992 -269.059152)
		(width 0.0889)
		(layer "B.Cu")
		(net "TP_CPU1_SSC_SYNC")
	)
	(arc
		(start 134.962392 -269.059152)
		(mid 134.775194 -269.009009)
		(end 134.587996 -269.059152)
		(width 0.0889)
		(layer "B.Cu")
		(net "TP_CPU1_SSC_SYNC")
	)
	(arc
		(start 130.814064 -269.067788)
		(mid 130.537589 -269.135108)
		(end 130.263392 -269.059152)
		(width 0.0889)
		(layer "B.Cu")
		(net "TP_CPU1_SSC_SYNC")
	)
	(arc
		(start 118.61165 -269.059152)
		(mid 118.328948 -269.134928)
		(end 118.046246 -269.059152)
		(width 0.0889)
		(layer "B.Cu")
		(net "TP_CPU1_SSC_SYNC")
	)
	(arc
		(start 128.383792 -269.059152)
		(mid 128.196594 -269.009009)
		(end 128.009396 -269.059152)
		(width 0.0889)
		(layer "B.Cu")
		(net "TP_CPU1_SSC_SYNC")
	)
	(arc
		(start 133.083046 -269.059152)
		(mid 132.895848 -269.009009)
		(end 132.70865 -269.059152)
		(width 0.0889)
		(layer "B.Cu")
		(net "TP_CPU1_SSC_SYNC")
	)
	(arc
		(start 124.624592 -269.059152)
		(mid 124.437394 -269.009009)
		(end 124.250196 -269.059152)
		(width 0.0889)
		(layer "B.Cu")
		(net "TP_CPU1_SSC_SYNC")
	)
	(arc
		(start 124.235464 -269.067788)
		(mid 123.958989 -269.135108)
		(end 123.684792 -269.059152)
		(width 0.0889)
		(layer "B.Cu")
		(net "TP_CPU1_SSC_SYNC")
	)
	(arc
		(start 131.203192 -269.059152)
		(mid 131.015994 -269.009009)
		(end 130.828796 -269.059152)
		(width 0.0889)
		(layer "B.Cu")
		(net "TP_CPU1_SSC_SYNC")
	)
	(arc
		(start 129.874264 -269.067788)
		(mid 129.597789 -269.135108)
		(end 129.323592 -269.059152)
		(width 0.0889)
		(layer "B.Cu")
		(net "TP_CPU1_SSC_SYNC")
	)
	(arc
		(start 135.902192 -269.059152)
		(mid 135.714994 -269.009009)
		(end 135.527796 -269.059152)
		(width 0.0889)
		(layer "B.Cu")
		(net "TP_CPU1_SSC_SYNC")
	)
	(arc
		(start 133.637782 -269.065248)
		(mid 133.359604 -269.134971)
		(end 133.083046 -269.059152)
		(width 0.0889)
		(layer "B.Cu")
		(net "TP_CPU1_SSC_SYNC")
	)
	(arc
		(start 121.805446 -269.059152)
		(mid 121.618248 -269.009009)
		(end 121.43105 -269.059152)
		(width 0.0889)
		(layer "B.Cu")
		(net "TP_CPU1_SSC_SYNC")
	)
	(arc
		(start 129.323592 -269.059152)
		(mid 129.136394 -269.009009)
		(end 128.949196 -269.059152)
		(width 0.0889)
		(layer "B.Cu")
		(net "TP_CPU1_SSC_SYNC")
	)
	(arc
		(start 132.698236 -269.065248)
		(mid 132.419804 -269.135094)
		(end 132.142992 -269.059152)
		(width 0.0889)
		(layer "B.Cu")
		(net "TP_CPU1_SSC_SYNC")
	)
	(arc
		(start 120.490996 -269.059152)
		(mid 120.214437 -269.134895)
		(end 119.93626 -269.065248)
		(width 0.0889)
		(layer "B.Cu")
		(net "TP_CPU1_SSC_SYNC")
	)
	(arc
		(start 118.986046 -269.059152)
		(mid 118.798848 -269.009009)
		(end 118.61165 -269.059152)
		(width 0.0889)
		(layer "B.Cu")
		(net "TP_CPU1_SSC_SYNC")
	)
	(arc
		(start 121.420636 -269.065248)
		(mid 121.142204 -269.135094)
		(end 120.865392 -269.059152)
		(width 0.0889)
		(layer "B.Cu")
		(net "TP_CPU1_SSC_SYNC")
	)
	(arc
		(start 134.022592 -269.059152)
		(mid 133.835394 -269.009009)
		(end 133.648196 -269.059152)
		(width 0.0889)
		(layer "B.Cu")
		(net "TP_CPU1_SSC_SYNC")
	)
	(arc
		(start 136.841992 -269.059152)
		(mid 136.654794 -269.009009)
		(end 136.467596 -269.059152)
		(width 0.0889)
		(layer "B.Cu")
		(net "TP_CPU1_SSC_SYNC")
	)
	(arc
		(start 119.925846 -269.059152)
		(mid 119.738648 -269.009009)
		(end 119.55145 -269.059152)
		(width 0.0889)
		(layer "B.Cu")
		(net "TP_CPU1_SSC_SYNC")
	)
	(arc
		(start 135.513064 -269.067788)
		(mid 135.236589 -269.135108)
		(end 134.962392 -269.059152)
		(width 0.0889)
		(layer "B.Cu")
		(net "TP_CPU1_SSC_SYNC")
	)
	(arc
		(start 122.744992 -269.059152)
		(mid 122.557794 -269.009009)
		(end 122.370596 -269.059152)
		(width 0.0889)
		(layer "B.Cu")
		(net "TP_CPU1_SSC_SYNC")
	)
	(arc
		(start 126.504192 -269.059152)
		(mid 126.316994 -269.009009)
		(end 126.129796 -269.059152)
		(width 0.0889)
		(layer "B.Cu")
		(net "TP_CPU1_SSC_SYNC")
	)
	(arc
		(start 119.55145 -269.059152)
		(mid 119.277251 -269.134987)
		(end 119.000778 -269.067788)
		(width 0.0889)
		(layer "B.Cu")
		(net "TP_CPU1_SSC_SYNC")
	)
	(segment
		(start 116.449094 -264.778236)
		(end 116.449348 -264.77849)
		(width 0.12954)
		(layer "F.Cu")
		(net "TP_CPU1_SPARE9")
	)
	(segment
		(start 116.449348 -264.77849)
		(end 116.449348 -265.314176)
		(width 0.12954)
		(layer "F.Cu")
		(net "TP_CPU1_SPARE9")
	)
	(via
		(at 116.449348 -265.314176)
		(size 0.4572)
		(drill 0.2032)
		(layers "F.Cu" "B.Cu")
		(net "TP_CPU1_SPARE9")
	)
	(segment
		(start 117.388894 -264.778236)
		(end 117.389148 -264.77849)
		(width 0.12954)
		(layer "F.Cu")
		(net "TP_CPU1_SPARE8")
	)
	(segment
		(start 117.389148 -264.77849)
		(end 117.389148 -265.314176)
		(width 0.12954)
		(layer "F.Cu")
		(net "TP_CPU1_SPARE8")
	)
	(via
		(at 117.389148 -265.314176)
		(size 0.4572)
		(drill 0.2032)
		(layers "F.Cu" "B.Cu")
		(net "TP_CPU1_SPARE8")
	)
	(segment
		(start 117.858794 -263.964674)
		(end 117.858794 -264.50036)
		(width 0.12954)
		(layer "F.Cu")
		(net "TP_CPU1_SPARE7")
	)
	(segment
		(start 117.859048 -263.96442)
		(end 117.858794 -263.964674)
		(width 0.12954)
		(layer "F.Cu")
		(net "TP_CPU1_SPARE7")
	)
	(via
		(at 117.858794 -264.50036)
		(size 0.4572)
		(drill 0.2032)
		(layers "F.Cu" "B.Cu")
		(net "TP_CPU1_SPARE7")
	)
	(segment
		(start 121.508266 -248.528078)
		(end 121.508266 -247.992392)
		(width 0.12954)
		(layer "F.Cu")
		(net "TP_CPU1_SPARE6")
	)
	(segment
		(start 121.508266 -247.992392)
		(end 121.508012 -247.992138)
		(width 0.12954)
		(layer "F.Cu")
		(net "TP_CPU1_SPARE6")
	)
	(via
		(at 137.535158 -248.14276)
		(size 0.6604)
		(drill 0.3302)
		(layers "F.Cu" "B.Cu")
		(net "TP_CPU1_SPARE6")
	)
	(via
		(at 121.508012 -247.992138)
		(size 0.4572)
		(drill 0.2032)
		(layers "F.Cu" "B.Cu")
		(net "TP_CPU1_SPARE6")
	)
	(segment
		(start 136.054084 -248.148856)
		(end 135.749284 -248.453656)
		(width 0.12954)
		(layer "B.Cu")
		(net "TP_CPU1_SPARE6")
	)
	(segment
		(start 128.839214 -247.66778)
		(end 128.824482 -247.676416)
		(width 0.0889)
		(layer "B.Cu")
		(net "TP_CPU1_SPARE6")
	)
	(segment
		(start 124.140214 -247.66778)
		(end 124.125482 -247.676416)
		(width 0.0889)
		(layer "B.Cu")
		(net "TP_CPU1_SPARE6")
	)
	(segment
		(start 134.910068 -248.453656)
		(end 134.199884 -247.743472)
		(width 0.12954)
		(layer "B.Cu")
		(net "TP_CPU1_SPARE6")
	)
	(segment
		(start 122.017028 -247.742456)
		(end 121.508012 -247.992138)
		(width 0.0889)
		(layer "B.Cu")
		(net "TP_CPU1_SPARE6")
	)
	(segment
		(start 135.749284 -248.453656)
		(end 134.910068 -248.453656)
		(width 0.12954)
		(layer "B.Cu")
		(net "TP_CPU1_SPARE6")
	)
	(segment
		(start 137.535158 -248.14276)
		(end 137.529062 -248.148856)
		(width 0.12954)
		(layer "B.Cu")
		(net "TP_CPU1_SPARE6")
	)
	(segment
		(start 122.260614 -247.66778)
		(end 122.245882 -247.676416)
		(width 0.0889)
		(layer "B.Cu")
		(net "TP_CPU1_SPARE6")
	)
	(segment
		(start 126.020068 -247.66778)
		(end 126.009654 -247.673876)
		(width 0.0889)
		(layer "B.Cu")
		(net "TP_CPU1_SPARE6")
	)
	(segment
		(start 137.529062 -248.148856)
		(end 136.054084 -248.148856)
		(width 0.12954)
		(layer "B.Cu")
		(net "TP_CPU1_SPARE6")
	)
	(segment
		(start 129.779014 -247.66778)
		(end 129.764282 -247.676416)
		(width 0.0889)
		(layer "B.Cu")
		(net "TP_CPU1_SPARE6")
	)
	(segment
		(start 127.899414 -247.66778)
		(end 127.884682 -247.676416)
		(width 0.0889)
		(layer "B.Cu")
		(net "TP_CPU1_SPARE6")
	)
	(segment
		(start 134.199884 -247.743472)
		(end 133.255512 -247.743472)
		(width 0.0889)
		(layer "B.Cu")
		(net "TP_CPU1_SPARE6")
	)
	(segment
		(start 131.103878 -247.673876)
		(end 131.093464 -247.66778)
		(width 0.0889)
		(layer "B.Cu")
		(net "TP_CPU1_SPARE6")
	)
	(segment
		(start 126.404878 -247.673876)
		(end 126.394464 -247.66778)
		(width 0.0889)
		(layer "B.Cu")
		(net "TP_CPU1_SPARE6")
	)
	(segment
		(start 125.080014 -247.66778)
		(end 125.065282 -247.676416)
		(width 0.0889)
		(layer "B.Cu")
		(net "TP_CPU1_SPARE6")
	)
	(segment
		(start 132.598668 -247.66778)
		(end 132.588254 -247.673876)
		(width 0.0889)
		(layer "B.Cu")
		(net "TP_CPU1_SPARE6")
	)
	(segment
		(start 123.200414 -247.66778)
		(end 123.185682 -247.676416)
		(width 0.0889)
		(layer "B.Cu")
		(net "TP_CPU1_SPARE6")
	)
	(segment
		(start 130.719068 -247.66778)
		(end 130.708654 -247.673876)
		(width 0.0889)
		(layer "B.Cu")
		(net "TP_CPU1_SPARE6")
	)
	(arc
		(start 129.21361 -247.66778)
		(mid 129.026412 -247.617637)
		(end 128.839214 -247.66778)
		(width 0.0889)
		(layer "B.Cu")
		(net "TP_CPU1_SPARE6")
	)
	(arc
		(start 124.51461 -247.66778)
		(mid 124.327412 -247.617637)
		(end 124.140214 -247.66778)
		(width 0.0889)
		(layer "B.Cu")
		(net "TP_CPU1_SPARE6")
	)
	(arc
		(start 127.33401 -247.66778)
		(mid 127.146812 -247.617637)
		(end 126.959614 -247.66778)
		(width 0.0889)
		(layer "B.Cu")
		(net "TP_CPU1_SPARE6")
	)
	(arc
		(start 125.45441 -247.66778)
		(mid 125.267212 -247.617637)
		(end 125.080014 -247.66778)
		(width 0.0889)
		(layer "B.Cu")
		(net "TP_CPU1_SPARE6")
	)
	(arc
		(start 129.764282 -247.676416)
		(mid 129.487807 -247.743736)
		(end 129.21361 -247.66778)
		(width 0.0889)
		(layer "B.Cu")
		(net "TP_CPU1_SPARE6")
	)
	(arc
		(start 124.125482 -247.676416)
		(mid 123.849007 -247.743736)
		(end 123.57481 -247.66778)
		(width 0.0889)
		(layer "B.Cu")
		(net "TP_CPU1_SPARE6")
	)
	(arc
		(start 126.009654 -247.673876)
		(mid 125.731222 -247.743722)
		(end 125.45441 -247.66778)
		(width 0.0889)
		(layer "B.Cu")
		(net "TP_CPU1_SPARE6")
	)
	(arc
		(start 131.093464 -247.66778)
		(mid 130.906266 -247.617637)
		(end 130.719068 -247.66778)
		(width 0.0889)
		(layer "B.Cu")
		(net "TP_CPU1_SPARE6")
	)
	(arc
		(start 132.03301 -247.66778)
		(mid 131.845812 -247.617637)
		(end 131.658614 -247.66778)
		(width 0.0889)
		(layer "B.Cu")
		(net "TP_CPU1_SPARE6")
	)
	(arc
		(start 128.27381 -247.66778)
		(mid 128.086612 -247.617637)
		(end 127.899414 -247.66778)
		(width 0.0889)
		(layer "B.Cu")
		(net "TP_CPU1_SPARE6")
	)
	(arc
		(start 132.588254 -247.673876)
		(mid 132.309822 -247.743722)
		(end 132.03301 -247.66778)
		(width 0.0889)
		(layer "B.Cu")
		(net "TP_CPU1_SPARE6")
	)
	(arc
		(start 123.57481 -247.66778)
		(mid 123.387612 -247.617637)
		(end 123.200414 -247.66778)
		(width 0.0889)
		(layer "B.Cu")
		(net "TP_CPU1_SPARE6")
	)
	(arc
		(start 130.15341 -247.66778)
		(mid 129.966212 -247.617637)
		(end 129.779014 -247.66778)
		(width 0.0889)
		(layer "B.Cu")
		(net "TP_CPU1_SPARE6")
	)
	(arc
		(start 122.245882 -247.676416)
		(mid 122.134973 -247.721628)
		(end 122.017028 -247.742456)
		(width 0.0889)
		(layer "B.Cu")
		(net "TP_CPU1_SPARE6")
	)
	(arc
		(start 123.185682 -247.676416)
		(mid 122.909207 -247.743736)
		(end 122.63501 -247.66778)
		(width 0.0889)
		(layer "B.Cu")
		(net "TP_CPU1_SPARE6")
	)
	(arc
		(start 132.973064 -247.66778)
		(mid 132.785866 -247.617637)
		(end 132.598668 -247.66778)
		(width 0.0889)
		(layer "B.Cu")
		(net "TP_CPU1_SPARE6")
	)
	(arc
		(start 122.63501 -247.66778)
		(mid 122.447812 -247.617637)
		(end 122.260614 -247.66778)
		(width 0.0889)
		(layer "B.Cu")
		(net "TP_CPU1_SPARE6")
	)
	(arc
		(start 126.394464 -247.66778)
		(mid 126.207266 -247.617637)
		(end 126.020068 -247.66778)
		(width 0.0889)
		(layer "B.Cu")
		(net "TP_CPU1_SPARE6")
	)
	(arc
		(start 127.884682 -247.676416)
		(mid 127.608207 -247.743736)
		(end 127.33401 -247.66778)
		(width 0.0889)
		(layer "B.Cu")
		(net "TP_CPU1_SPARE6")
	)
	(arc
		(start 131.658614 -247.66778)
		(mid 131.382055 -247.743523)
		(end 131.103878 -247.673876)
		(width 0.0889)
		(layer "B.Cu")
		(net "TP_CPU1_SPARE6")
	)
	(arc
		(start 125.065282 -247.676416)
		(mid 124.788807 -247.743736)
		(end 124.51461 -247.66778)
		(width 0.0889)
		(layer "B.Cu")
		(net "TP_CPU1_SPARE6")
	)
	(arc
		(start 126.959614 -247.66778)
		(mid 126.683055 -247.743523)
		(end 126.404878 -247.673876)
		(width 0.0889)
		(layer "B.Cu")
		(net "TP_CPU1_SPARE6")
	)
	(arc
		(start 128.824482 -247.676416)
		(mid 128.548007 -247.743736)
		(end 128.27381 -247.66778)
		(width 0.0889)
		(layer "B.Cu")
		(net "TP_CPU1_SPARE6")
	)
	(arc
		(start 133.255512 -247.743472)
		(mid 133.109304 -247.724223)
		(end 132.973064 -247.66778)
		(width 0.0889)
		(layer "B.Cu")
		(net "TP_CPU1_SPARE6")
	)
	(arc
		(start 130.708654 -247.673876)
		(mid 130.430222 -247.743722)
		(end 130.15341 -247.66778)
		(width 0.0889)
		(layer "B.Cu")
		(net "TP_CPU1_SPARE6")
	)
	(segment
		(start 101.882194 -257.453384)
		(end 101.882194 -257.98907)
		(width 0.12954)
		(layer "F.Cu")
		(net "TP_CPU1_SPARE5")
	)
	(segment
		(start 101.882448 -257.45313)
		(end 101.882194 -257.453384)
		(width 0.12954)
		(layer "F.Cu")
		(net "TP_CPU1_SPARE5")
	)
	(via
		(at 83.214718 -258.32689)
		(size 0.6604)
		(drill 0.3302)
		(layers "F.Cu" "B.Cu")
		(net "TP_CPU1_SPARE5")
	)
	(via
		(at 101.882194 -257.98907)
		(size 0.4572)
		(drill 0.2032)
		(layers "F.Cu" "B.Cu")
		(net "TP_CPU1_SPARE5")
	)
	(segment
		(start 100.755196 -257.664712)
		(end 100.740464 -257.673348)
		(width 0.0889)
		(layer "B.Cu")
		(net "TP_CPU1_SPARE5")
	)
	(segment
		(start 98.87585 -257.664712)
		(end 98.865436 -257.670808)
		(width 0.0889)
		(layer "B.Cu")
		(net "TP_CPU1_SPARE5")
	)
	(segment
		(start 96.056196 -257.664712)
		(end 96.041464 -257.673348)
		(width 0.0889)
		(layer "B.Cu")
		(net "TP_CPU1_SPARE5")
	)
	(segment
		(start 84.260182 -257.281426)
		(end 83.214718 -258.32689)
		(width 0.12954)
		(layer "B.Cu")
		(net "TP_CPU1_SPARE5")
	)
	(segment
		(start 95.116396 -257.664712)
		(end 95.101664 -257.673348)
		(width 0.0889)
		(layer "B.Cu")
		(net "TP_CPU1_SPARE5")
	)
	(segment
		(start 92.29725 -257.664712)
		(end 92.286836 -257.670808)
		(width 0.0889)
		(layer "B.Cu")
		(net "TP_CPU1_SPARE5")
	)
	(segment
		(start 89.776808 -257.589528)
		(end 87.38235 -257.589528)
		(width 0.0889)
		(layer "B.Cu")
		(net "TP_CPU1_SPARE5")
	)
	(segment
		(start 99.26066 -257.670808)
		(end 99.250246 -257.664712)
		(width 0.0889)
		(layer "B.Cu")
		(net "TP_CPU1_SPARE5")
	)
	(segment
		(start 92.68206 -257.670808)
		(end 92.671646 -257.664712)
		(width 0.0889)
		(layer "B.Cu")
		(net "TP_CPU1_SPARE5")
	)
	(segment
		(start 89.851992 -257.664712)
		(end 89.776808 -257.589528)
		(width 0.0889)
		(layer "B.Cu")
		(net "TP_CPU1_SPARE5")
	)
	(segment
		(start 101.526594 -257.89382)
		(end 101.129592 -257.664712)
		(width 0.0889)
		(layer "B.Cu")
		(net "TP_CPU1_SPARE5")
	)
	(segment
		(start 96.99625 -257.664712)
		(end 96.985836 -257.670808)
		(width 0.0889)
		(layer "B.Cu")
		(net "TP_CPU1_SPARE5")
	)
	(segment
		(start 87.38235 -257.589528)
		(end 87.074248 -257.281426)
		(width 0.12954)
		(layer "B.Cu")
		(net "TP_CPU1_SPARE5")
	)
	(segment
		(start 97.38106 -257.670808)
		(end 97.370646 -257.664712)
		(width 0.0889)
		(layer "B.Cu")
		(net "TP_CPU1_SPARE5")
	)
	(segment
		(start 87.074248 -257.281426)
		(end 84.260182 -257.281426)
		(width 0.12954)
		(layer "B.Cu")
		(net "TP_CPU1_SPARE5")
	)
	(segment
		(start 89.862406 -257.670808)
		(end 89.851992 -257.664712)
		(width 0.0889)
		(layer "B.Cu")
		(net "TP_CPU1_SPARE5")
	)
	(segment
		(start 90.80246 -257.670808)
		(end 90.792046 -257.664712)
		(width 0.0889)
		(layer "B.Cu")
		(net "TP_CPU1_SPARE5")
	)
	(segment
		(start 94.176596 -257.664712)
		(end 94.161864 -257.673348)
		(width 0.0889)
		(layer "B.Cu")
		(net "TP_CPU1_SPARE5")
	)
	(arc
		(start 96.430592 -257.664712)
		(mid 96.243394 -257.614569)
		(end 96.056196 -257.664712)
		(width 0.0889)
		(layer "B.Cu")
		(net "TP_CPU1_SPARE5")
	)
	(arc
		(start 94.550992 -257.664712)
		(mid 94.363794 -257.614569)
		(end 94.176596 -257.664712)
		(width 0.0889)
		(layer "B.Cu")
		(net "TP_CPU1_SPARE5")
	)
	(arc
		(start 96.041464 -257.673348)
		(mid 95.764989 -257.740668)
		(end 95.490792 -257.664712)
		(width 0.0889)
		(layer "B.Cu")
		(net "TP_CPU1_SPARE5")
	)
	(arc
		(start 100.740464 -257.673348)
		(mid 100.463989 -257.740668)
		(end 100.189792 -257.664712)
		(width 0.0889)
		(layer "B.Cu")
		(net "TP_CPU1_SPARE5")
	)
	(arc
		(start 93.611192 -257.664712)
		(mid 93.423994 -257.614569)
		(end 93.236796 -257.664712)
		(width 0.0889)
		(layer "B.Cu")
		(net "TP_CPU1_SPARE5")
	)
	(arc
		(start 90.792046 -257.664712)
		(mid 90.604848 -257.614569)
		(end 90.41765 -257.664712)
		(width 0.0889)
		(layer "B.Cu")
		(net "TP_CPU1_SPARE5")
	)
	(arc
		(start 98.865436 -257.670808)
		(mid 98.587004 -257.740654)
		(end 98.310192 -257.664712)
		(width 0.0889)
		(layer "B.Cu")
		(net "TP_CPU1_SPARE5")
	)
	(arc
		(start 97.935796 -257.664712)
		(mid 97.659237 -257.740455)
		(end 97.38106 -257.670808)
		(width 0.0889)
		(layer "B.Cu")
		(net "TP_CPU1_SPARE5")
	)
	(arc
		(start 99.250246 -257.664712)
		(mid 99.063048 -257.614569)
		(end 98.87585 -257.664712)
		(width 0.0889)
		(layer "B.Cu")
		(net "TP_CPU1_SPARE5")
	)
	(arc
		(start 94.161864 -257.673348)
		(mid 93.885389 -257.740668)
		(end 93.611192 -257.664712)
		(width 0.0889)
		(layer "B.Cu")
		(net "TP_CPU1_SPARE5")
	)
	(arc
		(start 92.286836 -257.670808)
		(mid 92.008404 -257.740654)
		(end 91.731592 -257.664712)
		(width 0.0889)
		(layer "B.Cu")
		(net "TP_CPU1_SPARE5")
	)
	(arc
		(start 97.370646 -257.664712)
		(mid 97.183448 -257.614569)
		(end 96.99625 -257.664712)
		(width 0.0889)
		(layer "B.Cu")
		(net "TP_CPU1_SPARE5")
	)
	(arc
		(start 95.101664 -257.673348)
		(mid 94.825189 -257.740668)
		(end 94.550992 -257.664712)
		(width 0.0889)
		(layer "B.Cu")
		(net "TP_CPU1_SPARE5")
	)
	(arc
		(start 91.731592 -257.664712)
		(mid 91.544394 -257.614569)
		(end 91.357196 -257.664712)
		(width 0.0889)
		(layer "B.Cu")
		(net "TP_CPU1_SPARE5")
	)
	(arc
		(start 101.129592 -257.664712)
		(mid 100.942394 -257.614569)
		(end 100.755196 -257.664712)
		(width 0.0889)
		(layer "B.Cu")
		(net "TP_CPU1_SPARE5")
	)
	(arc
		(start 93.236796 -257.664712)
		(mid 92.960237 -257.740455)
		(end 92.68206 -257.670808)
		(width 0.0889)
		(layer "B.Cu")
		(net "TP_CPU1_SPARE5")
	)
	(arc
		(start 90.41765 -257.664712)
		(mid 90.140837 -257.740582)
		(end 89.862406 -257.670808)
		(width 0.0889)
		(layer "B.Cu")
		(net "TP_CPU1_SPARE5")
	)
	(arc
		(start 98.310192 -257.664712)
		(mid 98.122994 -257.614569)
		(end 97.935796 -257.664712)
		(width 0.0889)
		(layer "B.Cu")
		(net "TP_CPU1_SPARE5")
	)
	(arc
		(start 96.985836 -257.670808)
		(mid 96.707404 -257.740654)
		(end 96.430592 -257.664712)
		(width 0.0889)
		(layer "B.Cu")
		(net "TP_CPU1_SPARE5")
	)
	(arc
		(start 91.357196 -257.664712)
		(mid 91.080637 -257.740455)
		(end 90.80246 -257.670808)
		(width 0.0889)
		(layer "B.Cu")
		(net "TP_CPU1_SPARE5")
	)
	(arc
		(start 101.882194 -257.98907)
		(mid 101.698125 -257.964846)
		(end 101.526594 -257.89382)
		(width 0.0889)
		(layer "B.Cu")
		(net "TP_CPU1_SPARE5")
	)
	(arc
		(start 100.189792 -257.664712)
		(mid 100.002594 -257.614569)
		(end 99.815396 -257.664712)
		(width 0.0889)
		(layer "B.Cu")
		(net "TP_CPU1_SPARE5")
	)
	(arc
		(start 95.490792 -257.664712)
		(mid 95.303594 -257.614569)
		(end 95.116396 -257.664712)
		(width 0.0889)
		(layer "B.Cu")
		(net "TP_CPU1_SPARE5")
	)
	(arc
		(start 99.815396 -257.664712)
		(mid 99.538837 -257.740455)
		(end 99.26066 -257.670808)
		(width 0.0889)
		(layer "B.Cu")
		(net "TP_CPU1_SPARE5")
	)
	(arc
		(start 92.671646 -257.664712)
		(mid 92.484448 -257.614569)
		(end 92.29725 -257.664712)
		(width 0.0889)
		(layer "B.Cu")
		(net "TP_CPU1_SPARE5")
	)
	(segment
		(start 122.558048 -272.103342)
		(end 122.557794 -272.639282)
		(width 0.12954)
		(layer "F.Cu")
		(net "TP_CPU1_SPARE4")
	)
	(via
		(at 122.557794 -272.639282)
		(size 0.4572)
		(drill 0.2032)
		(layers "F.Cu" "B.Cu")
		(net "TP_CPU1_SPARE4")
	)
	(segment
		(start 105.171494 -278.336502)
		(end 105.171494 -277.800562)
		(width 0.12954)
		(layer "F.Cu")
		(net "TP_CPU1_SPARE13")
	)
	(via
		(at 105.171494 -278.336502)
		(size 0.4572)
		(drill 0.2032)
		(layers "F.Cu" "B.Cu")
		(net "TP_CPU1_SPARE13")
	)
	(segment
		(start 117.859048 -272.103342)
		(end 117.858794 -272.639282)
		(width 0.12954)
		(layer "F.Cu")
		(net "TP_CPU1_SPARE12")
	)
	(via
		(at 117.858794 -272.639282)
		(size 0.4572)
		(drill 0.2032)
		(layers "F.Cu" "B.Cu")
		(net "TP_CPU1_SPARE12")
	)
	(segment
		(start 114.569494 -271.289272)
		(end 114.569748 -271.825212)
		(width 0.12954)
		(layer "F.Cu")
		(net "TP_CPU1_SPARE11")
	)
	(via
		(at 114.569748 -271.825212)
		(size 0.4572)
		(drill 0.2032)
		(layers "F.Cu" "B.Cu")
		(net "TP_CPU1_SPARE11")
	)
	(segment
		(start 115.979448 -263.96442)
		(end 115.979194 -263.964674)
		(width 0.12954)
		(layer "F.Cu")
		(net "TP_CPU1_SPARE10")
	)
	(segment
		(start 115.979194 -263.964674)
		(end 115.979194 -264.50036)
		(width 0.12954)
		(layer "F.Cu")
		(net "TP_CPU1_SPARE10")
	)
	(via
		(at 115.979194 -264.50036)
		(size 0.4572)
		(drill 0.2032)
		(layers "F.Cu" "B.Cu")
		(net "TP_CPU1_SPARE10")
	)
	(segment
		(start 88.615012 -224.111312)
		(end 88.615012 -223.575626)
		(width 0.12954)
		(layer "F.Cu")
		(net "TP_CPU1_PPD")
	)
	(segment
		(start 88.615266 -224.111566)
		(end 88.615012 -224.111312)
		(width 0.12954)
		(layer "F.Cu")
		(net "TP_CPU1_PPD")
	)
	(via
		(at 88.615012 -223.575626)
		(size 0.4572)
		(drill 0.2032)
		(layers "F.Cu" "B.Cu")
		(net "TP_CPU1_PPD")
	)
	(segment
		(start 106.001312 -233.064304)
		(end 106.001566 -233.06405)
		(width 0.12954)
		(layer "F.Cu")
		(net "TP_CPU1_IFST_TRIG_LVC1_R")
	)
	(segment
		(start 106.001566 -233.06405)
		(end 106.001566 -232.528364)
		(width 0.12954)
		(layer "F.Cu")
		(net "TP_CPU1_IFST_TRIG_LVC1_R")
	)
	(via
		(at 106.001566 -232.528364)
		(size 0.4572)
		(drill 0.2032)
		(layers "F.Cu" "B.Cu")
		(net "TP_CPU1_IFST_TRIG_LVC1_R")
	)
	(via
		(at 82.874358 -233.61015)
		(size 0.6604)
		(drill 0.3302)
		(layers "F.Cu" "B.Cu")
		(net "TP_CPU1_IFST_TRIG_LVC1_R")
	)
	(segment
		(start 93.986096 -232.844086)
		(end 93.971364 -232.852722)
		(width 0.0889)
		(layer "B.Cu")
		(net "TP_CPU1_IFST_TRIG_LVC1_R")
	)
	(segment
		(start 87.205566 -232.903268)
		(end 85.444076 -232.903268)
		(width 0.0889)
		(layer "B.Cu")
		(net "TP_CPU1_IFST_TRIG_LVC1_R")
	)
	(segment
		(start 104.323896 -232.844086)
		(end 104.309164 -232.852722)
		(width 0.0889)
		(layer "B.Cu")
		(net "TP_CPU1_IFST_TRIG_LVC1_R")
	)
	(segment
		(start 95.865696 -232.844086)
		(end 95.850964 -232.852722)
		(width 0.0889)
		(layer "B.Cu")
		(net "TP_CPU1_IFST_TRIG_LVC1_R")
	)
	(segment
		(start 102.444296 -232.844086)
		(end 102.429564 -232.852722)
		(width 0.0889)
		(layer "B.Cu")
		(net "TP_CPU1_IFST_TRIG_LVC1_R")
	)
	(segment
		(start 83.186778 -233.29773)
		(end 82.874358 -233.61015)
		(width 0.12954)
		(layer "B.Cu")
		(net "TP_CPU1_IFST_TRIG_LVC1_R")
	)
	(segment
		(start 106.31424 -232.528364)
		(end 106.371644 -232.585768)
		(width 0.0889)
		(layer "B.Cu")
		(net "TP_CPU1_IFST_TRIG_LVC1_R")
	)
	(segment
		(start 93.046296 -232.844086)
		(end 93.031564 -232.852722)
		(width 0.0889)
		(layer "B.Cu")
		(net "TP_CPU1_IFST_TRIG_LVC1_R")
	)
	(segment
		(start 92.101924 -232.846626)
		(end 92.09151 -232.852722)
		(width 0.0889)
		(layer "B.Cu")
		(net "TP_CPU1_IFST_TRIG_LVC1_R")
	)
	(segment
		(start 85.049614 -233.29773)
		(end 83.186778 -233.29773)
		(width 0.12954)
		(layer "B.Cu")
		(net "TP_CPU1_IFST_TRIG_LVC1_R")
	)
	(segment
		(start 106.001566 -232.528364)
		(end 106.31424 -232.528364)
		(width 0.0889)
		(layer "B.Cu")
		(net "TP_CPU1_IFST_TRIG_LVC1_R")
	)
	(segment
		(start 105.263696 -232.844086)
		(end 105.248964 -232.852722)
		(width 0.0889)
		(layer "B.Cu")
		(net "TP_CPU1_IFST_TRIG_LVC1_R")
	)
	(segment
		(start 98.680524 -232.846626)
		(end 98.678238 -232.847896)
		(width 0.0889)
		(layer "B.Cu")
		(net "TP_CPU1_IFST_TRIG_LVC1_R")
	)
	(segment
		(start 94.925896 -232.844086)
		(end 94.911164 -232.852722)
		(width 0.0889)
		(layer "B.Cu")
		(net "TP_CPU1_IFST_TRIG_LVC1_R")
	)
	(segment
		(start 100.564696 -232.844086)
		(end 100.549964 -232.852722)
		(width 0.0889)
		(layer "B.Cu")
		(net "TP_CPU1_IFST_TRIG_LVC1_R")
	)
	(segment
		(start 85.444076 -232.903268)
		(end 85.049614 -233.29773)
		(width 0.0889)
		(layer "B.Cu")
		(net "TP_CPU1_IFST_TRIG_LVC1_R")
	)
	(segment
		(start 101.504496 -232.844086)
		(end 101.489764 -232.852722)
		(width 0.0889)
		(layer "B.Cu")
		(net "TP_CPU1_IFST_TRIG_LVC1_R")
	)
	(segment
		(start 96.805496 -232.844086)
		(end 96.790764 -232.852722)
		(width 0.0889)
		(layer "B.Cu")
		(net "TP_CPU1_IFST_TRIG_LVC1_R")
	)
	(segment
		(start 91.717114 -232.852722)
		(end 91.7067 -232.846626)
		(width 0.0889)
		(layer "B.Cu")
		(net "TP_CPU1_IFST_TRIG_LVC1_R")
	)
	(segment
		(start 88.347296 -232.844086)
		(end 88.332564 -232.852722)
		(width 0.0889)
		(layer "B.Cu")
		(net "TP_CPU1_IFST_TRIG_LVC1_R")
	)
	(segment
		(start 90.226896 -232.844086)
		(end 90.212164 -232.852722)
		(width 0.0889)
		(layer "B.Cu")
		(net "TP_CPU1_IFST_TRIG_LVC1_R")
	)
	(segment
		(start 98.678238 -232.847896)
		(end 98.67011 -232.852722)
		(width 0.0889)
		(layer "B.Cu")
		(net "TP_CPU1_IFST_TRIG_LVC1_R")
	)
	(segment
		(start 103.384096 -232.844086)
		(end 103.369364 -232.852722)
		(width 0.0889)
		(layer "B.Cu")
		(net "TP_CPU1_IFST_TRIG_LVC1_R")
	)
	(segment
		(start 98.295714 -232.852722)
		(end 98.2853 -232.846626)
		(width 0.0889)
		(layer "B.Cu")
		(net "TP_CPU1_IFST_TRIG_LVC1_R")
	)
	(segment
		(start 89.287096 -232.844086)
		(end 89.272364 -232.852722)
		(width 0.0889)
		(layer "B.Cu")
		(net "TP_CPU1_IFST_TRIG_LVC1_R")
	)
	(segment
		(start 99.624896 -232.844086)
		(end 99.610164 -232.852722)
		(width 0.0889)
		(layer "B.Cu")
		(net "TP_CPU1_IFST_TRIG_LVC1_R")
	)
	(segment
		(start 106.197654 -232.847642)
		(end 106.188764 -232.852722)
		(width 0.0889)
		(layer "B.Cu")
		(net "TP_CPU1_IFST_TRIG_LVC1_R")
	)
	(arc
		(start 97.730564 -232.852722)
		(mid 97.543366 -232.902865)
		(end 97.356168 -232.852722)
		(width 0.0889)
		(layer "B.Cu")
		(net "TP_CPU1_IFST_TRIG_LVC1_R")
	)
	(arc
		(start 88.897968 -232.852722)
		(mid 88.623769 -232.776887)
		(end 88.347296 -232.844086)
		(width 0.0889)
		(layer "B.Cu")
		(net "TP_CPU1_IFST_TRIG_LVC1_R")
	)
	(arc
		(start 100.175568 -232.852722)
		(mid 99.901369 -232.776887)
		(end 99.624896 -232.844086)
		(width 0.0889)
		(layer "B.Cu")
		(net "TP_CPU1_IFST_TRIG_LVC1_R")
	)
	(arc
		(start 101.115368 -232.852722)
		(mid 100.841169 -232.776887)
		(end 100.564696 -232.844086)
		(width 0.0889)
		(layer "B.Cu")
		(net "TP_CPU1_IFST_TRIG_LVC1_R")
	)
	(arc
		(start 104.874568 -232.852722)
		(mid 104.600369 -232.776887)
		(end 104.323896 -232.844086)
		(width 0.0889)
		(layer "B.Cu")
		(net "TP_CPU1_IFST_TRIG_LVC1_R")
	)
	(arc
		(start 91.7067 -232.846626)
		(mid 91.428522 -232.776903)
		(end 91.151964 -232.852722)
		(width 0.0889)
		(layer "B.Cu")
		(net "TP_CPU1_IFST_TRIG_LVC1_R")
	)
	(arc
		(start 91.151964 -232.852722)
		(mid 90.964766 -232.902865)
		(end 90.777568 -232.852722)
		(width 0.0889)
		(layer "B.Cu")
		(net "TP_CPU1_IFST_TRIG_LVC1_R")
	)
	(arc
		(start 99.235768 -232.852722)
		(mid 98.958955 -232.776852)
		(end 98.680524 -232.846626)
		(width 0.0889)
		(layer "B.Cu")
		(net "TP_CPU1_IFST_TRIG_LVC1_R")
	)
	(arc
		(start 106.188764 -232.852722)
		(mid 106.001566 -232.902865)
		(end 105.814368 -232.852722)
		(width 0.0889)
		(layer "B.Cu")
		(net "TP_CPU1_IFST_TRIG_LVC1_R")
	)
	(arc
		(start 90.212164 -232.852722)
		(mid 90.024966 -232.902865)
		(end 89.837768 -232.852722)
		(width 0.0889)
		(layer "B.Cu")
		(net "TP_CPU1_IFST_TRIG_LVC1_R")
	)
	(arc
		(start 106.371644 -232.585768)
		(mid 106.313488 -232.735881)
		(end 106.197654 -232.847642)
		(width 0.0889)
		(layer "B.Cu")
		(net "TP_CPU1_IFST_TRIG_LVC1_R")
	)
	(arc
		(start 101.489764 -232.852722)
		(mid 101.302566 -232.902865)
		(end 101.115368 -232.852722)
		(width 0.0889)
		(layer "B.Cu")
		(net "TP_CPU1_IFST_TRIG_LVC1_R")
	)
	(arc
		(start 87.392764 -232.852722)
		(mid 87.302492 -232.890321)
		(end 87.205566 -232.903268)
		(width 0.0889)
		(layer "B.Cu")
		(net "TP_CPU1_IFST_TRIG_LVC1_R")
	)
	(arc
		(start 102.429564 -232.852722)
		(mid 102.242366 -232.902865)
		(end 102.055168 -232.852722)
		(width 0.0889)
		(layer "B.Cu")
		(net "TP_CPU1_IFST_TRIG_LVC1_R")
	)
	(arc
		(start 88.332564 -232.852722)
		(mid 88.145366 -232.902865)
		(end 87.958168 -232.852722)
		(width 0.0889)
		(layer "B.Cu")
		(net "TP_CPU1_IFST_TRIG_LVC1_R")
	)
	(arc
		(start 97.356168 -232.852722)
		(mid 97.081969 -232.776887)
		(end 96.805496 -232.844086)
		(width 0.0889)
		(layer "B.Cu")
		(net "TP_CPU1_IFST_TRIG_LVC1_R")
	)
	(arc
		(start 93.971364 -232.852722)
		(mid 93.784166 -232.902865)
		(end 93.596968 -232.852722)
		(width 0.0889)
		(layer "B.Cu")
		(net "TP_CPU1_IFST_TRIG_LVC1_R")
	)
	(arc
		(start 90.777568 -232.852722)
		(mid 90.503369 -232.776887)
		(end 90.226896 -232.844086)
		(width 0.0889)
		(layer "B.Cu")
		(net "TP_CPU1_IFST_TRIG_LVC1_R")
	)
	(arc
		(start 99.610164 -232.852722)
		(mid 99.422966 -232.902865)
		(end 99.235768 -232.852722)
		(width 0.0889)
		(layer "B.Cu")
		(net "TP_CPU1_IFST_TRIG_LVC1_R")
	)
	(arc
		(start 89.837768 -232.852722)
		(mid 89.563569 -232.776887)
		(end 89.287096 -232.844086)
		(width 0.0889)
		(layer "B.Cu")
		(net "TP_CPU1_IFST_TRIG_LVC1_R")
	)
	(arc
		(start 87.958168 -232.852722)
		(mid 87.675466 -232.776946)
		(end 87.392764 -232.852722)
		(width 0.0889)
		(layer "B.Cu")
		(net "TP_CPU1_IFST_TRIG_LVC1_R")
	)
	(arc
		(start 102.055168 -232.852722)
		(mid 101.780969 -232.776887)
		(end 101.504496 -232.844086)
		(width 0.0889)
		(layer "B.Cu")
		(net "TP_CPU1_IFST_TRIG_LVC1_R")
	)
	(arc
		(start 103.369364 -232.852722)
		(mid 103.182166 -232.902865)
		(end 102.994968 -232.852722)
		(width 0.0889)
		(layer "B.Cu")
		(net "TP_CPU1_IFST_TRIG_LVC1_R")
	)
	(arc
		(start 95.476568 -232.852722)
		(mid 95.202369 -232.776887)
		(end 94.925896 -232.844086)
		(width 0.0889)
		(layer "B.Cu")
		(net "TP_CPU1_IFST_TRIG_LVC1_R")
	)
	(arc
		(start 100.549964 -232.852722)
		(mid 100.362766 -232.902865)
		(end 100.175568 -232.852722)
		(width 0.0889)
		(layer "B.Cu")
		(net "TP_CPU1_IFST_TRIG_LVC1_R")
	)
	(arc
		(start 93.031564 -232.852722)
		(mid 92.844366 -232.902865)
		(end 92.657168 -232.852722)
		(width 0.0889)
		(layer "B.Cu")
		(net "TP_CPU1_IFST_TRIG_LVC1_R")
	)
	(arc
		(start 92.09151 -232.852722)
		(mid 91.904312 -232.902865)
		(end 91.717114 -232.852722)
		(width 0.0889)
		(layer "B.Cu")
		(net "TP_CPU1_IFST_TRIG_LVC1_R")
	)
	(arc
		(start 93.596968 -232.852722)
		(mid 93.322769 -232.776887)
		(end 93.046296 -232.844086)
		(width 0.0889)
		(layer "B.Cu")
		(net "TP_CPU1_IFST_TRIG_LVC1_R")
	)
	(arc
		(start 98.67011 -232.852722)
		(mid 98.482912 -232.902865)
		(end 98.295714 -232.852722)
		(width 0.0889)
		(layer "B.Cu")
		(net "TP_CPU1_IFST_TRIG_LVC1_R")
	)
	(arc
		(start 105.814368 -232.852722)
		(mid 105.540169 -232.776887)
		(end 105.263696 -232.844086)
		(width 0.0889)
		(layer "B.Cu")
		(net "TP_CPU1_IFST_TRIG_LVC1_R")
	)
	(arc
		(start 94.911164 -232.852722)
		(mid 94.723966 -232.902865)
		(end 94.536768 -232.852722)
		(width 0.0889)
		(layer "B.Cu")
		(net "TP_CPU1_IFST_TRIG_LVC1_R")
	)
	(arc
		(start 96.416368 -232.852722)
		(mid 96.142169 -232.776887)
		(end 95.865696 -232.844086)
		(width 0.0889)
		(layer "B.Cu")
		(net "TP_CPU1_IFST_TRIG_LVC1_R")
	)
	(arc
		(start 105.248964 -232.852722)
		(mid 105.061766 -232.902865)
		(end 104.874568 -232.852722)
		(width 0.0889)
		(layer "B.Cu")
		(net "TP_CPU1_IFST_TRIG_LVC1_R")
	)
	(arc
		(start 95.850964 -232.852722)
		(mid 95.663766 -232.902865)
		(end 95.476568 -232.852722)
		(width 0.0889)
		(layer "B.Cu")
		(net "TP_CPU1_IFST_TRIG_LVC1_R")
	)
	(arc
		(start 104.309164 -232.852722)
		(mid 104.121966 -232.902865)
		(end 103.934768 -232.852722)
		(width 0.0889)
		(layer "B.Cu")
		(net "TP_CPU1_IFST_TRIG_LVC1_R")
	)
	(arc
		(start 103.934768 -232.852722)
		(mid 103.660569 -232.776887)
		(end 103.384096 -232.844086)
		(width 0.0889)
		(layer "B.Cu")
		(net "TP_CPU1_IFST_TRIG_LVC1_R")
	)
	(arc
		(start 102.994968 -232.852722)
		(mid 102.720769 -232.776887)
		(end 102.444296 -232.844086)
		(width 0.0889)
		(layer "B.Cu")
		(net "TP_CPU1_IFST_TRIG_LVC1_R")
	)
	(arc
		(start 92.657168 -232.852722)
		(mid 92.380355 -232.776852)
		(end 92.101924 -232.846626)
		(width 0.0889)
		(layer "B.Cu")
		(net "TP_CPU1_IFST_TRIG_LVC1_R")
	)
	(arc
		(start 98.2853 -232.846626)
		(mid 98.007122 -232.776903)
		(end 97.730564 -232.852722)
		(width 0.0889)
		(layer "B.Cu")
		(net "TP_CPU1_IFST_TRIG_LVC1_R")
	)
	(arc
		(start 89.272364 -232.852722)
		(mid 89.085166 -232.902865)
		(end 88.897968 -232.852722)
		(width 0.0889)
		(layer "B.Cu")
		(net "TP_CPU1_IFST_TRIG_LVC1_R")
	)
	(arc
		(start 94.536768 -232.852722)
		(mid 94.262569 -232.776887)
		(end 93.986096 -232.844086)
		(width 0.0889)
		(layer "B.Cu")
		(net "TP_CPU1_IFST_TRIG_LVC1_R")
	)
	(arc
		(start 96.790764 -232.852722)
		(mid 96.603566 -232.902865)
		(end 96.416368 -232.852722)
		(width 0.0889)
		(layer "B.Cu")
		(net "TP_CPU1_IFST_TRIG_LVC1_R")
	)
	(segment
		(start 105.531412 -232.250234)
		(end 105.531412 -231.714548)
		(width 0.12954)
		(layer "F.Cu")
		(net "TP_CPU1_IFST_KOT_LVC1_R")
	)
	(segment
		(start 105.531666 -232.250488)
		(end 105.531412 -232.250234)
		(width 0.12954)
		(layer "F.Cu")
		(net "TP_CPU1_IFST_KOT_LVC1_R")
	)
	(via
		(at 105.531412 -231.714548)
		(size 0.4572)
		(drill 0.2032)
		(layers "F.Cu" "B.Cu")
		(net "TP_CPU1_IFST_KOT_LVC1_R")
	)
	(via
		(at 78.373478 -201.66203)
		(size 0.6604)
		(drill 0.3302)
		(layers "F.Cu" "B.Cu")
		(net "TP_CPU1_IFST_KOT_LVC1_R")
	)
	(segment
		(start 93.046296 -228.957124)
		(end 93.031564 -228.948488)
		(width 0.0889)
		(layer "B.Cu")
		(net "TP_CPU1_IFST_KOT_LVC1_R")
	)
	(segment
		(start 103.369364 -230.57612)
		(end 103.363268 -230.572564)
		(width 0.0889)
		(layer "B.Cu")
		(net "TP_CPU1_IFST_KOT_LVC1_R")
	)
	(segment
		(start 86.612222 -228.794056)
		(end 84.144612 -228.794056)
		(width 0.0889)
		(layer "B.Cu")
		(net "TP_CPU1_IFST_KOT_LVC1_R")
	)
	(segment
		(start 92.106496 -228.957124)
		(end 92.091764 -228.948488)
		(width 0.0889)
		(layer "B.Cu")
		(net "TP_CPU1_IFST_KOT_LVC1_R")
	)
	(segment
		(start 93.981778 -228.954584)
		(end 93.971364 -228.948488)
		(width 0.0889)
		(layer "B.Cu")
		(net "TP_CPU1_IFST_KOT_LVC1_R")
	)
	(segment
		(start 98.678238 -228.95306)
		(end 98.670364 -228.948488)
		(width 0.0889)
		(layer "B.Cu")
		(net "TP_CPU1_IFST_KOT_LVC1_R")
	)
	(segment
		(start 95.865696 -228.957124)
		(end 95.850964 -228.948488)
		(width 0.0889)
		(layer "B.Cu")
		(net "TP_CPU1_IFST_KOT_LVC1_R")
	)
	(segment
		(start 89.287096 -228.957124)
		(end 89.272364 -228.948488)
		(width 0.0889)
		(layer "B.Cu")
		(net "TP_CPU1_IFST_KOT_LVC1_R")
	)
	(segment
		(start 83.938618 -229.00005)
		(end 81.709006 -229.00005)
		(width 0.12954)
		(layer "B.Cu")
		(net "TP_CPU1_IFST_KOT_LVC1_R")
	)
	(segment
		(start 88.347296 -228.957124)
		(end 88.332564 -228.948488)
		(width 0.0889)
		(layer "B.Cu")
		(net "TP_CPU1_IFST_KOT_LVC1_R")
	)
	(segment
		(start 99.624896 -228.957124)
		(end 99.610164 -228.948488)
		(width 0.0889)
		(layer "B.Cu")
		(net "TP_CPU1_IFST_KOT_LVC1_R")
	)
	(segment
		(start 102.617016 -229.28834)
		(end 102.617016 -229.272846)
		(width 0.0889)
		(layer "B.Cu")
		(net "TP_CPU1_IFST_KOT_LVC1_R")
	)
	(segment
		(start 87.765382 -229.122986)
		(end 86.941152 -229.122986)
		(width 0.0889)
		(layer "B.Cu")
		(net "TP_CPU1_IFST_KOT_LVC1_R")
	)
	(segment
		(start 84.144612 -228.794056)
		(end 83.938618 -229.00005)
		(width 0.0889)
		(layer "B.Cu")
		(net "TP_CPU1_IFST_KOT_LVC1_R")
	)
	(segment
		(start 86.941152 -229.122986)
		(end 86.612222 -228.794056)
		(width 0.0889)
		(layer "B.Cu")
		(net "TP_CPU1_IFST_KOT_LVC1_R")
	)
	(segment
		(start 78.373478 -202.50785)
		(end 78.373478 -201.66203)
		(width 0.12954)
		(layer "B.Cu")
		(net "TP_CPU1_IFST_KOT_LVC1_R")
	)
	(segment
		(start 105.374948 -231.44353)
		(end 105.286048 -231.419908)
		(width 0.0889)
		(layer "B.Cu")
		(net "TP_CPU1_IFST_KOT_LVC1_R")
	)
	(segment
		(start 76.030328 -223.321372)
		(end 76.030328 -204.851)
		(width 0.12954)
		(layer "B.Cu")
		(net "TP_CPU1_IFST_KOT_LVC1_R")
	)
	(segment
		(start 102.438454 -228.953568)
		(end 102.429564 -228.948488)
		(width 0.0889)
		(layer "B.Cu")
		(net "TP_CPU1_IFST_KOT_LVC1_R")
	)
	(segment
		(start 76.030328 -204.851)
		(end 78.373478 -202.50785)
		(width 0.12954)
		(layer "B.Cu")
		(net "TP_CPU1_IFST_KOT_LVC1_R")
	)
	(segment
		(start 104.404414 -231.39019)
		(end 104.389682 -231.398826)
		(width 0.0889)
		(layer "B.Cu")
		(net "TP_CPU1_IFST_KOT_LVC1_R")
	)
	(segment
		(start 105.531412 -231.714548)
		(end 105.374948 -231.44353)
		(width 0.0889)
		(layer "B.Cu")
		(net "TP_CPU1_IFST_KOT_LVC1_R")
	)
	(segment
		(start 94.921324 -228.954584)
		(end 94.91091 -228.948488)
		(width 0.0889)
		(layer "B.Cu")
		(net "TP_CPU1_IFST_KOT_LVC1_R")
	)
	(segment
		(start 103.556816 -230.922576)
		(end 103.556816 -230.900478)
		(width 0.0889)
		(layer "B.Cu")
		(net "TP_CPU1_IFST_KOT_LVC1_R")
	)
	(segment
		(start 81.709006 -229.00005)
		(end 76.030328 -223.321372)
		(width 0.12954)
		(layer "B.Cu")
		(net "TP_CPU1_IFST_KOT_LVC1_R")
	)
	(segment
		(start 102.9081 -229.767384)
		(end 102.89921 -229.762304)
		(width 0.0889)
		(layer "B.Cu")
		(net "TP_CPU1_IFST_KOT_LVC1_R")
	)
	(segment
		(start 96.805496 -228.957124)
		(end 96.790764 -228.948488)
		(width 0.0889)
		(layer "B.Cu")
		(net "TP_CPU1_IFST_KOT_LVC1_R")
	)
	(segment
		(start 100.560378 -228.954584)
		(end 100.549964 -228.948488)
		(width 0.0889)
		(layer "B.Cu")
		(net "TP_CPU1_IFST_KOT_LVC1_R")
	)
	(segment
		(start 101.499924 -228.954584)
		(end 101.48951 -228.948488)
		(width 0.0889)
		(layer "B.Cu")
		(net "TP_CPU1_IFST_KOT_LVC1_R")
	)
	(segment
		(start 87.880444 -229.007924)
		(end 87.765382 -229.122986)
		(width 0.0889)
		(layer "B.Cu")
		(net "TP_CPU1_IFST_KOT_LVC1_R")
	)
	(segment
		(start 90.226896 -228.957124)
		(end 90.212164 -228.948488)
		(width 0.0889)
		(layer "B.Cu")
		(net "TP_CPU1_IFST_KOT_LVC1_R")
	)
	(segment
		(start 98.685096 -228.957124)
		(end 98.678238 -228.95306)
		(width 0.0889)
		(layer "B.Cu")
		(net "TP_CPU1_IFST_KOT_LVC1_R")
	)
	(segment
		(start 103.378254 -230.5812)
		(end 103.369364 -230.57612)
		(width 0.0889)
		(layer "B.Cu")
		(net "TP_CPU1_IFST_KOT_LVC1_R")
	)
	(arc
		(start 90.212164 -228.948488)
		(mid 90.024966 -228.898345)
		(end 89.837768 -228.948488)
		(width 0.0889)
		(layer "B.Cu")
		(net "TP_CPU1_IFST_KOT_LVC1_R")
	)
	(arc
		(start 100.549964 -228.948488)
		(mid 100.362766 -228.898345)
		(end 100.175568 -228.948488)
		(width 0.0889)
		(layer "B.Cu")
		(net "TP_CPU1_IFST_KOT_LVC1_R")
	)
	(arc
		(start 96.790764 -228.948488)
		(mid 96.603566 -228.898345)
		(end 96.416368 -228.948488)
		(width 0.0889)
		(layer "B.Cu")
		(net "TP_CPU1_IFST_KOT_LVC1_R")
	)
	(arc
		(start 105.286048 -231.419908)
		(mid 105.028909 -231.46519)
		(end 104.77881 -231.39019)
		(width 0.0889)
		(layer "B.Cu")
		(net "TP_CPU1_IFST_KOT_LVC1_R")
	)
	(arc
		(start 95.476568 -228.948488)
		(mid 95.199755 -229.024358)
		(end 94.921324 -228.954584)
		(width 0.0889)
		(layer "B.Cu")
		(net "TP_CPU1_IFST_KOT_LVC1_R")
	)
	(arc
		(start 94.91091 -228.948488)
		(mid 94.723712 -228.898345)
		(end 94.536514 -228.948488)
		(width 0.0889)
		(layer "B.Cu")
		(net "TP_CPU1_IFST_KOT_LVC1_R")
	)
	(arc
		(start 103.556816 -230.900478)
		(mid 103.509137 -230.717578)
		(end 103.378254 -230.5812)
		(width 0.0889)
		(layer "B.Cu")
		(net "TP_CPU1_IFST_KOT_LVC1_R")
	)
	(arc
		(start 104.389682 -231.398826)
		(mid 104.113241 -231.465992)
		(end 103.83901 -231.39019)
		(width 0.0889)
		(layer "B.Cu")
		(net "TP_CPU1_IFST_KOT_LVC1_R")
	)
	(arc
		(start 102.429564 -228.948488)
		(mid 102.242366 -228.898345)
		(end 102.055168 -228.948488)
		(width 0.0889)
		(layer "B.Cu")
		(net "TP_CPU1_IFST_KOT_LVC1_R")
	)
	(arc
		(start 87.958168 -228.948488)
		(mid 87.917359 -228.97566)
		(end 87.880444 -229.007924)
		(width 0.0889)
		(layer "B.Cu")
		(net "TP_CPU1_IFST_KOT_LVC1_R")
	)
	(arc
		(start 88.332564 -228.948488)
		(mid 88.145366 -228.898345)
		(end 87.958168 -228.948488)
		(width 0.0889)
		(layer "B.Cu")
		(net "TP_CPU1_IFST_KOT_LVC1_R")
	)
	(arc
		(start 92.091764 -228.948488)
		(mid 91.904566 -228.898345)
		(end 91.717368 -228.948488)
		(width 0.0889)
		(layer "B.Cu")
		(net "TP_CPU1_IFST_KOT_LVC1_R")
	)
	(arc
		(start 97.356168 -228.948488)
		(mid 97.081969 -229.024323)
		(end 96.805496 -228.957124)
		(width 0.0889)
		(layer "B.Cu")
		(net "TP_CPU1_IFST_KOT_LVC1_R")
	)
	(arc
		(start 99.235768 -228.948488)
		(mid 98.961569 -229.024323)
		(end 98.685096 -228.957124)
		(width 0.0889)
		(layer "B.Cu")
		(net "TP_CPU1_IFST_KOT_LVC1_R")
	)
	(arc
		(start 102.89921 -229.762304)
		(mid 102.696387 -229.562073)
		(end 102.617016 -229.28834)
		(width 0.0889)
		(layer "B.Cu")
		(net "TP_CPU1_IFST_KOT_LVC1_R")
	)
	(arc
		(start 104.77881 -231.39019)
		(mid 104.591612 -231.340047)
		(end 104.404414 -231.39019)
		(width 0.0889)
		(layer "B.Cu")
		(net "TP_CPU1_IFST_KOT_LVC1_R")
	)
	(arc
		(start 91.717368 -228.948488)
		(mid 91.434666 -229.024264)
		(end 91.151964 -228.948488)
		(width 0.0889)
		(layer "B.Cu")
		(net "TP_CPU1_IFST_KOT_LVC1_R")
	)
	(arc
		(start 101.115114 -228.948488)
		(mid 100.838555 -229.024231)
		(end 100.560378 -228.954584)
		(width 0.0889)
		(layer "B.Cu")
		(net "TP_CPU1_IFST_KOT_LVC1_R")
	)
	(arc
		(start 90.777568 -228.948488)
		(mid 90.503369 -229.024323)
		(end 90.226896 -228.957124)
		(width 0.0889)
		(layer "B.Cu")
		(net "TP_CPU1_IFST_KOT_LVC1_R")
	)
	(arc
		(start 100.175568 -228.948488)
		(mid 99.901369 -229.024323)
		(end 99.624896 -228.957124)
		(width 0.0889)
		(layer "B.Cu")
		(net "TP_CPU1_IFST_KOT_LVC1_R")
	)
	(arc
		(start 103.363268 -230.572564)
		(mid 103.160681 -230.366213)
		(end 103.086662 -230.086662)
		(width 0.0889)
		(layer "B.Cu")
		(net "TP_CPU1_IFST_KOT_LVC1_R")
	)
	(arc
		(start 101.48951 -228.948488)
		(mid 101.302312 -228.898345)
		(end 101.115114 -228.948488)
		(width 0.0889)
		(layer "B.Cu")
		(net "TP_CPU1_IFST_KOT_LVC1_R")
	)
	(arc
		(start 102.055168 -228.948488)
		(mid 101.778355 -229.024358)
		(end 101.499924 -228.954584)
		(width 0.0889)
		(layer "B.Cu")
		(net "TP_CPU1_IFST_KOT_LVC1_R")
	)
	(arc
		(start 93.031564 -228.948488)
		(mid 92.844366 -228.898345)
		(end 92.657168 -228.948488)
		(width 0.0889)
		(layer "B.Cu")
		(net "TP_CPU1_IFST_KOT_LVC1_R")
	)
	(arc
		(start 97.730564 -228.948488)
		(mid 97.543366 -228.898345)
		(end 97.356168 -228.948488)
		(width 0.0889)
		(layer "B.Cu")
		(net "TP_CPU1_IFST_KOT_LVC1_R")
	)
	(arc
		(start 93.971364 -228.948488)
		(mid 93.784166 -228.898345)
		(end 93.596968 -228.948488)
		(width 0.0889)
		(layer "B.Cu")
		(net "TP_CPU1_IFST_KOT_LVC1_R")
	)
	(arc
		(start 96.416368 -228.948488)
		(mid 96.142169 -229.024323)
		(end 95.865696 -228.957124)
		(width 0.0889)
		(layer "B.Cu")
		(net "TP_CPU1_IFST_KOT_LVC1_R")
	)
	(arc
		(start 95.850964 -228.948488)
		(mid 95.663766 -228.898345)
		(end 95.476568 -228.948488)
		(width 0.0889)
		(layer "B.Cu")
		(net "TP_CPU1_IFST_KOT_LVC1_R")
	)
	(arc
		(start 103.086662 -230.086662)
		(mid 103.038983 -229.903762)
		(end 102.9081 -229.767384)
		(width 0.0889)
		(layer "B.Cu")
		(net "TP_CPU1_IFST_KOT_LVC1_R")
	)
	(arc
		(start 98.295968 -228.948488)
		(mid 98.013266 -229.024264)
		(end 97.730564 -228.948488)
		(width 0.0889)
		(layer "B.Cu")
		(net "TP_CPU1_IFST_KOT_LVC1_R")
	)
	(arc
		(start 102.617016 -229.272846)
		(mid 102.569337 -229.089946)
		(end 102.438454 -228.953568)
		(width 0.0889)
		(layer "B.Cu")
		(net "TP_CPU1_IFST_KOT_LVC1_R")
	)
	(arc
		(start 88.897968 -228.948488)
		(mid 88.623769 -229.024323)
		(end 88.347296 -228.957124)
		(width 0.0889)
		(layer "B.Cu")
		(net "TP_CPU1_IFST_KOT_LVC1_R")
	)
	(arc
		(start 98.670364 -228.948488)
		(mid 98.483166 -228.898345)
		(end 98.295968 -228.948488)
		(width 0.0889)
		(layer "B.Cu")
		(net "TP_CPU1_IFST_KOT_LVC1_R")
	)
	(arc
		(start 89.272364 -228.948488)
		(mid 89.085166 -228.898345)
		(end 88.897968 -228.948488)
		(width 0.0889)
		(layer "B.Cu")
		(net "TP_CPU1_IFST_KOT_LVC1_R")
	)
	(arc
		(start 91.151964 -228.948488)
		(mid 90.964766 -228.898345)
		(end 90.777568 -228.948488)
		(width 0.0889)
		(layer "B.Cu")
		(net "TP_CPU1_IFST_KOT_LVC1_R")
	)
	(arc
		(start 99.610164 -228.948488)
		(mid 99.422966 -228.898345)
		(end 99.235768 -228.948488)
		(width 0.0889)
		(layer "B.Cu")
		(net "TP_CPU1_IFST_KOT_LVC1_R")
	)
	(arc
		(start 94.536514 -228.948488)
		(mid 94.259955 -229.024231)
		(end 93.981778 -228.954584)
		(width 0.0889)
		(layer "B.Cu")
		(net "TP_CPU1_IFST_KOT_LVC1_R")
	)
	(arc
		(start 103.83901 -231.39019)
		(mid 103.637728 -231.192703)
		(end 103.556816 -230.922576)
		(width 0.0889)
		(layer "B.Cu")
		(net "TP_CPU1_IFST_KOT_LVC1_R")
	)
	(arc
		(start 92.657168 -228.948488)
		(mid 92.382969 -229.024323)
		(end 92.106496 -228.957124)
		(width 0.0889)
		(layer "B.Cu")
		(net "TP_CPU1_IFST_KOT_LVC1_R")
	)
	(arc
		(start 93.596968 -228.948488)
		(mid 93.322769 -229.024323)
		(end 93.046296 -228.957124)
		(width 0.0889)
		(layer "B.Cu")
		(net "TP_CPU1_IFST_KOT_LVC1_R")
	)
	(arc
		(start 89.837768 -228.948488)
		(mid 89.563569 -229.024323)
		(end 89.287096 -228.957124)
		(width 0.0889)
		(layer "B.Cu")
		(net "TP_CPU1_IFST_KOT_LVC1_R")
	)
	(segment
		(start 104.591612 -232.250234)
		(end 104.591612 -231.714548)
		(width 0.12954)
		(layer "F.Cu")
		(net "TP_CPU1_IFST_DONE_LVC1_R")
	)
	(segment
		(start 104.591866 -232.250488)
		(end 104.591612 -232.250234)
		(width 0.12954)
		(layer "F.Cu")
		(net "TP_CPU1_IFST_DONE_LVC1_R")
	)
	(via
		(at 78.862428 -230.96474)
		(size 0.6604)
		(drill 0.3302)
		(layers "F.Cu" "B.Cu")
		(net "TP_CPU1_IFST_DONE_LVC1_R")
	)
	(via
		(at 104.591612 -231.714548)
		(size 0.4572)
		(drill 0.2032)
		(layers "F.Cu" "B.Cu")
		(net "TP_CPU1_IFST_DONE_LVC1_R")
	)
	(segment
		(start 94.925896 -231.2162)
		(end 94.911164 -231.224836)
		(width 0.0889)
		(layer "B.Cu")
		(net "TP_CPU1_IFST_DONE_LVC1_R")
	)
	(segment
		(start 93.046296 -231.2162)
		(end 93.031564 -231.224836)
		(width 0.0889)
		(layer "B.Cu")
		(net "TP_CPU1_IFST_DONE_LVC1_R")
	)
	(segment
		(start 104.591612 -231.714548)
		(end 104.748076 -231.985566)
		(width 0.0889)
		(layer "B.Cu")
		(net "TP_CPU1_IFST_DONE_LVC1_R")
	)
	(segment
		(start 98.685096 -231.2162)
		(end 98.678238 -231.220264)
		(width 0.0889)
		(layer "B.Cu")
		(net "TP_CPU1_IFST_DONE_LVC1_R")
	)
	(segment
		(start 101.504496 -231.2162)
		(end 101.489764 -231.224836)
		(width 0.0889)
		(layer "B.Cu")
		(net "TP_CPU1_IFST_DONE_LVC1_R")
	)
	(segment
		(start 88.347296 -231.2162)
		(end 88.332564 -231.224836)
		(width 0.0889)
		(layer "B.Cu")
		(net "TP_CPU1_IFST_DONE_LVC1_R")
	)
	(segment
		(start 91.162124 -231.21874)
		(end 91.15171 -231.224836)
		(width 0.0889)
		(layer "B.Cu")
		(net "TP_CPU1_IFST_DONE_LVC1_R")
	)
	(segment
		(start 79.653638 -231.75595)
		(end 78.862428 -230.96474)
		(width 0.12954)
		(layer "B.Cu")
		(net "TP_CPU1_IFST_DONE_LVC1_R")
	)
	(segment
		(start 92.106496 -231.2162)
		(end 92.091764 -231.224836)
		(width 0.0889)
		(layer "B.Cu")
		(net "TP_CPU1_IFST_DONE_LVC1_R")
	)
	(segment
		(start 90.222578 -231.21874)
		(end 90.212164 -231.224836)
		(width 0.0889)
		(layer "B.Cu")
		(net "TP_CPU1_IFST_DONE_LVC1_R")
	)
	(segment
		(start 104.748076 -231.985566)
		(end 104.726994 -232.063544)
		(width 0.0889)
		(layer "B.Cu")
		(net "TP_CPU1_IFST_DONE_LVC1_R")
	)
	(segment
		(start 95.865696 -231.2162)
		(end 95.850964 -231.224836)
		(width 0.0889)
		(layer "B.Cu")
		(net "TP_CPU1_IFST_DONE_LVC1_R")
	)
	(segment
		(start 87.675466 -231.149144)
		(end 84.321396 -231.149144)
		(width 0.0889)
		(layer "B.Cu")
		(net "TP_CPU1_IFST_DONE_LVC1_R")
	)
	(segment
		(start 97.740724 -231.21874)
		(end 97.73031 -231.224836)
		(width 0.0889)
		(layer "B.Cu")
		(net "TP_CPU1_IFST_DONE_LVC1_R")
	)
	(segment
		(start 84.321396 -231.149144)
		(end 83.71459 -231.75595)
		(width 0.0889)
		(layer "B.Cu")
		(net "TP_CPU1_IFST_DONE_LVC1_R")
	)
	(segment
		(start 98.678238 -231.220264)
		(end 98.670364 -231.224836)
		(width 0.0889)
		(layer "B.Cu")
		(net "TP_CPU1_IFST_DONE_LVC1_R")
	)
	(segment
		(start 89.287096 -231.2162)
		(end 89.272364 -231.224836)
		(width 0.0889)
		(layer "B.Cu")
		(net "TP_CPU1_IFST_DONE_LVC1_R")
	)
	(segment
		(start 99.624896 -231.2162)
		(end 99.610164 -231.224836)
		(width 0.0889)
		(layer "B.Cu")
		(net "TP_CPU1_IFST_DONE_LVC1_R")
	)
	(segment
		(start 103.464614 -232.038906)
		(end 103.449882 -232.03027)
		(width 0.0889)
		(layer "B.Cu")
		(net "TP_CPU1_IFST_DONE_LVC1_R")
	)
	(segment
		(start 83.71459 -231.75595)
		(end 79.653638 -231.75595)
		(width 0.12954)
		(layer "B.Cu")
		(net "TP_CPU1_IFST_DONE_LVC1_R")
	)
	(segment
		(start 104.404414 -232.038906)
		(end 104.389682 -232.03027)
		(width 0.0889)
		(layer "B.Cu")
		(net "TP_CPU1_IFST_DONE_LVC1_R")
	)
	(segment
		(start 102.337362 -231.714548)
		(end 102.337362 -231.69245)
		(width 0.0889)
		(layer "B.Cu")
		(net "TP_CPU1_IFST_DONE_LVC1_R")
	)
	(segment
		(start 96.801178 -231.21874)
		(end 96.790764 -231.224836)
		(width 0.0889)
		(layer "B.Cu")
		(net "TP_CPU1_IFST_DONE_LVC1_R")
	)
	(arc
		(start 99.235768 -231.224836)
		(mid 98.961539 -231.148911)
		(end 98.685096 -231.2162)
		(width 0.0889)
		(layer "B.Cu")
		(net "TP_CPU1_IFST_DONE_LVC1_R")
	)
	(arc
		(start 98.670364 -231.224836)
		(mid 98.483166 -231.274979)
		(end 98.295968 -231.224836)
		(width 0.0889)
		(layer "B.Cu")
		(net "TP_CPU1_IFST_DONE_LVC1_R")
	)
	(arc
		(start 103.449882 -232.03027)
		(mid 103.173407 -231.96295)
		(end 102.89921 -232.038906)
		(width 0.0889)
		(layer "B.Cu")
		(net "TP_CPU1_IFST_DONE_LVC1_R")
	)
	(arc
		(start 92.657168 -231.224836)
		(mid 92.382939 -231.148911)
		(end 92.106496 -231.2162)
		(width 0.0889)
		(layer "B.Cu")
		(net "TP_CPU1_IFST_DONE_LVC1_R")
	)
	(arc
		(start 91.717368 -231.224836)
		(mid 91.440555 -231.149)
		(end 91.162124 -231.21874)
		(width 0.0889)
		(layer "B.Cu")
		(net "TP_CPU1_IFST_DONE_LVC1_R")
	)
	(arc
		(start 89.837768 -231.224836)
		(mid 89.563539 -231.148911)
		(end 89.287096 -231.2162)
		(width 0.0889)
		(layer "B.Cu")
		(net "TP_CPU1_IFST_DONE_LVC1_R")
	)
	(arc
		(start 97.73031 -231.224836)
		(mid 97.543112 -231.274979)
		(end 97.355914 -231.224836)
		(width 0.0889)
		(layer "B.Cu")
		(net "TP_CPU1_IFST_DONE_LVC1_R")
	)
	(arc
		(start 88.897968 -231.224836)
		(mid 88.623739 -231.148911)
		(end 88.347296 -231.2162)
		(width 0.0889)
		(layer "B.Cu")
		(net "TP_CPU1_IFST_DONE_LVC1_R")
	)
	(arc
		(start 93.596968 -231.224836)
		(mid 93.322739 -231.148911)
		(end 93.046296 -231.2162)
		(width 0.0889)
		(layer "B.Cu")
		(net "TP_CPU1_IFST_DONE_LVC1_R")
	)
	(arc
		(start 100.549964 -231.224836)
		(mid 100.362766 -231.274979)
		(end 100.175568 -231.224836)
		(width 0.0889)
		(layer "B.Cu")
		(net "TP_CPU1_IFST_DONE_LVC1_R")
	)
	(arc
		(start 93.031564 -231.224836)
		(mid 92.844366 -231.274979)
		(end 92.657168 -231.224836)
		(width 0.0889)
		(layer "B.Cu")
		(net "TP_CPU1_IFST_DONE_LVC1_R")
	)
	(arc
		(start 97.355914 -231.224836)
		(mid 97.079355 -231.149127)
		(end 96.801178 -231.21874)
		(width 0.0889)
		(layer "B.Cu")
		(net "TP_CPU1_IFST_DONE_LVC1_R")
	)
	(arc
		(start 89.272364 -231.224836)
		(mid 89.085166 -231.274979)
		(end 88.897968 -231.224836)
		(width 0.0889)
		(layer "B.Cu")
		(net "TP_CPU1_IFST_DONE_LVC1_R")
	)
	(arc
		(start 96.790764 -231.224836)
		(mid 96.603566 -231.274979)
		(end 96.416368 -231.224836)
		(width 0.0889)
		(layer "B.Cu")
		(net "TP_CPU1_IFST_DONE_LVC1_R")
	)
	(arc
		(start 98.295968 -231.224836)
		(mid 98.019155 -231.149)
		(end 97.740724 -231.21874)
		(width 0.0889)
		(layer "B.Cu")
		(net "TP_CPU1_IFST_DONE_LVC1_R")
	)
	(arc
		(start 104.726994 -232.063544)
		(mid 104.562898 -232.087891)
		(end 104.404414 -232.038906)
		(width 0.0889)
		(layer "B.Cu")
		(net "TP_CPU1_IFST_DONE_LVC1_R")
	)
	(arc
		(start 99.610164 -231.224836)
		(mid 99.422966 -231.274979)
		(end 99.235768 -231.224836)
		(width 0.0889)
		(layer "B.Cu")
		(net "TP_CPU1_IFST_DONE_LVC1_R")
	)
	(arc
		(start 104.389682 -232.03027)
		(mid 104.113207 -231.96295)
		(end 103.83901 -232.038906)
		(width 0.0889)
		(layer "B.Cu")
		(net "TP_CPU1_IFST_DONE_LVC1_R")
	)
	(arc
		(start 103.83901 -232.038906)
		(mid 103.651812 -232.089049)
		(end 103.464614 -232.038906)
		(width 0.0889)
		(layer "B.Cu")
		(net "TP_CPU1_IFST_DONE_LVC1_R")
	)
	(arc
		(start 93.971364 -231.224836)
		(mid 93.784166 -231.274979)
		(end 93.596968 -231.224836)
		(width 0.0889)
		(layer "B.Cu")
		(net "TP_CPU1_IFST_DONE_LVC1_R")
	)
	(arc
		(start 90.777314 -231.224836)
		(mid 90.500755 -231.149127)
		(end 90.222578 -231.21874)
		(width 0.0889)
		(layer "B.Cu")
		(net "TP_CPU1_IFST_DONE_LVC1_R")
	)
	(arc
		(start 95.476568 -231.224836)
		(mid 95.202339 -231.148911)
		(end 94.925896 -231.2162)
		(width 0.0889)
		(layer "B.Cu")
		(net "TP_CPU1_IFST_DONE_LVC1_R")
	)
	(arc
		(start 94.911164 -231.224836)
		(mid 94.723966 -231.274979)
		(end 94.536768 -231.224836)
		(width 0.0889)
		(layer "B.Cu")
		(net "TP_CPU1_IFST_DONE_LVC1_R")
	)
	(arc
		(start 88.332564 -231.224836)
		(mid 88.145366 -231.274979)
		(end 87.958168 -231.224836)
		(width 0.0889)
		(layer "B.Cu")
		(net "TP_CPU1_IFST_DONE_LVC1_R")
	)
	(arc
		(start 102.89921 -232.038906)
		(mid 102.524735 -232.03886)
		(end 102.337362 -231.714548)
		(width 0.0889)
		(layer "B.Cu")
		(net "TP_CPU1_IFST_DONE_LVC1_R")
	)
	(arc
		(start 102.337362 -231.69245)
		(mid 102.052931 -231.223549)
		(end 101.504496 -231.2162)
		(width 0.0889)
		(layer "B.Cu")
		(net "TP_CPU1_IFST_DONE_LVC1_R")
	)
	(arc
		(start 87.958168 -231.224836)
		(mid 87.821802 -231.168358)
		(end 87.675466 -231.149144)
		(width 0.0889)
		(layer "B.Cu")
		(net "TP_CPU1_IFST_DONE_LVC1_R")
	)
	(arc
		(start 100.175568 -231.224836)
		(mid 99.901339 -231.148911)
		(end 99.624896 -231.2162)
		(width 0.0889)
		(layer "B.Cu")
		(net "TP_CPU1_IFST_DONE_LVC1_R")
	)
	(arc
		(start 92.091764 -231.224836)
		(mid 91.904566 -231.274979)
		(end 91.717368 -231.224836)
		(width 0.0889)
		(layer "B.Cu")
		(net "TP_CPU1_IFST_DONE_LVC1_R")
	)
	(arc
		(start 101.489764 -231.224836)
		(mid 101.302566 -231.274979)
		(end 101.115368 -231.224836)
		(width 0.0889)
		(layer "B.Cu")
		(net "TP_CPU1_IFST_DONE_LVC1_R")
	)
	(arc
		(start 90.212164 -231.224836)
		(mid 90.024966 -231.274979)
		(end 89.837768 -231.224836)
		(width 0.0889)
		(layer "B.Cu")
		(net "TP_CPU1_IFST_DONE_LVC1_R")
	)
	(arc
		(start 101.115368 -231.224836)
		(mid 100.832666 -231.149094)
		(end 100.549964 -231.224836)
		(width 0.0889)
		(layer "B.Cu")
		(net "TP_CPU1_IFST_DONE_LVC1_R")
	)
	(arc
		(start 96.416368 -231.224836)
		(mid 96.142139 -231.148911)
		(end 95.865696 -231.2162)
		(width 0.0889)
		(layer "B.Cu")
		(net "TP_CPU1_IFST_DONE_LVC1_R")
	)
	(arc
		(start 94.536768 -231.224836)
		(mid 94.254066 -231.149094)
		(end 93.971364 -231.224836)
		(width 0.0889)
		(layer "B.Cu")
		(net "TP_CPU1_IFST_DONE_LVC1_R")
	)
	(arc
		(start 95.850964 -231.224836)
		(mid 95.663766 -231.274979)
		(end 95.476568 -231.224836)
		(width 0.0889)
		(layer "B.Cu")
		(net "TP_CPU1_IFST_DONE_LVC1_R")
	)
	(arc
		(start 91.15171 -231.224836)
		(mid 90.964512 -231.274979)
		(end 90.777314 -231.224836)
		(width 0.0889)
		(layer "B.Cu")
		(net "TP_CPU1_IFST_DONE_LVC1_R")
	)
	(segment
		(start 116.809266 -230.622602)
		(end 116.809266 -230.086916)
		(width 0.12954)
		(layer "F.Cu")
		(net "TP_CPU1_IBL_GRST_WARN_CPU1_N")
	)
	(segment
		(start 116.809266 -230.086916)
		(end 116.809012 -230.086662)
		(width 0.12954)
		(layer "F.Cu")
		(net "TP_CPU1_IBL_GRST_WARN_CPU1_N")
	)
	(via
		(at 116.809012 -230.086662)
		(size 0.4572)
		(drill 0.2032)
		(layers "F.Cu" "B.Cu")
		(net "TP_CPU1_IBL_GRST_WARN_CPU1_N")
	)
	(via
		(at 139.965684 -223.256856)
		(size 0.6604)
		(drill 0.3302)
		(layers "F.Cu" "B.Cu")
		(net "TP_CPU1_IBL_GRST_WARN_CPU1_N")
	)
	(segment
		(start 120.300496 -226.33305)
		(end 120.285764 -226.341686)
		(width 0.0889)
		(layer "B.Cu")
		(net "TP_CPU1_IBL_GRST_WARN_CPU1_N")
	)
	(segment
		(start 136.940544 -225.870516)
		(end 136.545066 -226.265994)
		(width 0.0889)
		(layer "B.Cu")
		(net "TP_CPU1_IBL_GRST_WARN_CPU1_N")
	)
	(segment
		(start 118.415054 -227.964238)
		(end 118.406164 -227.969318)
		(width 0.0889)
		(layer "B.Cu")
		(net "TP_CPU1_IBL_GRST_WARN_CPU1_N")
	)
	(segment
		(start 139.069318 -224.79381)
		(end 137.255758 -224.79381)
		(width 0.12954)
		(layer "B.Cu")
		(net "TP_CPU1_IBL_GRST_WARN_CPU1_N")
	)
	(segment
		(start 122.180096 -226.33305)
		(end 122.165364 -226.341686)
		(width 0.0889)
		(layer "B.Cu")
		(net "TP_CPU1_IBL_GRST_WARN_CPU1_N")
	)
	(segment
		(start 116.809012 -230.08717)
		(end 116.809012 -230.086662)
		(width 0.0889)
		(layer "B.Cu")
		(net "TP_CPU1_IBL_GRST_WARN_CPU1_N")
	)
	(segment
		(start 119.345964 -226.341686)
		(end 119.333772 -226.348798)
		(width 0.0889)
		(layer "B.Cu")
		(net "TP_CPU1_IBL_GRST_WARN_CPU1_N")
	)
	(segment
		(start 124.999496 -226.33305)
		(end 124.984764 -226.341686)
		(width 0.0889)
		(layer "B.Cu")
		(net "TP_CPU1_IBL_GRST_WARN_CPU1_N")
	)
	(segment
		(start 128.758696 -226.33305)
		(end 128.743964 -226.341686)
		(width 0.0889)
		(layer "B.Cu")
		(net "TP_CPU1_IBL_GRST_WARN_CPU1_N")
	)
	(segment
		(start 118.123462 -228.444806)
		(end 118.123462 -228.45903)
		(width 0.0889)
		(layer "B.Cu")
		(net "TP_CPU1_IBL_GRST_WARN_CPU1_N")
	)
	(segment
		(start 117.004338 -230.406448)
		(end 116.996464 -230.41102)
		(width 0.0889)
		(layer "B.Cu")
		(net "TP_CPU1_IBL_GRST_WARN_CPU1_N")
	)
	(segment
		(start 117.9449 -228.778308)
		(end 117.93601 -228.783388)
		(width 0.0889)
		(layer "B.Cu")
		(net "TP_CPU1_IBL_GRST_WARN_CPU1_N")
	)
	(segment
		(start 116.653056 -230.35768)
		(end 116.809012 -230.08717)
		(width 0.0889)
		(layer "B.Cu")
		(net "TP_CPU1_IBL_GRST_WARN_CPU1_N")
	)
	(segment
		(start 117.466364 -229.597204)
		(end 117.460268 -229.60076)
		(width 0.0889)
		(layer "B.Cu")
		(net "TP_CPU1_IBL_GRST_WARN_CPU1_N")
	)
	(segment
		(start 129.698496 -226.33305)
		(end 129.683764 -226.341686)
		(width 0.0889)
		(layer "B.Cu")
		(net "TP_CPU1_IBL_GRST_WARN_CPU1_N")
	)
	(segment
		(start 131.578096 -226.33305)
		(end 131.563364 -226.341686)
		(width 0.0889)
		(layer "B.Cu")
		(net "TP_CPU1_IBL_GRST_WARN_CPU1_N")
	)
	(segment
		(start 125.939296 -226.33305)
		(end 125.924564 -226.341686)
		(width 0.0889)
		(layer "B.Cu")
		(net "TP_CPU1_IBL_GRST_WARN_CPU1_N")
	)
	(segment
		(start 139.705334 -223.517206)
		(end 139.705334 -224.157794)
		(width 0.12954)
		(layer "B.Cu")
		(net "TP_CPU1_IBL_GRST_WARN_CPU1_N")
	)
	(segment
		(start 137.049764 -224.999804)
		(end 137.049764 -225.761296)
		(width 0.12954)
		(layer "B.Cu")
		(net "TP_CPU1_IBL_GRST_WARN_CPU1_N")
	)
	(segment
		(start 139.965684 -223.256856)
		(end 139.705334 -223.517206)
		(width 0.12954)
		(layer "B.Cu")
		(net "TP_CPU1_IBL_GRST_WARN_CPU1_N")
	)
	(segment
		(start 137.255758 -224.79381)
		(end 137.049764 -224.999804)
		(width 0.12954)
		(layer "B.Cu")
		(net "TP_CPU1_IBL_GRST_WARN_CPU1_N")
	)
	(segment
		(start 134.397496 -226.33305)
		(end 134.382764 -226.341686)
		(width 0.0889)
		(layer "B.Cu")
		(net "TP_CPU1_IBL_GRST_WARN_CPU1_N")
	)
	(segment
		(start 139.705334 -224.157794)
		(end 139.069318 -224.79381)
		(width 0.12954)
		(layer "B.Cu")
		(net "TP_CPU1_IBL_GRST_WARN_CPU1_N")
	)
	(segment
		(start 137.049764 -225.761296)
		(end 136.940544 -225.870516)
		(width 0.12954)
		(layer "B.Cu")
		(net "TP_CPU1_IBL_GRST_WARN_CPU1_N")
	)
	(segment
		(start 117.653816 -229.257352)
		(end 117.653816 -229.272846)
		(width 0.0889)
		(layer "B.Cu")
		(net "TP_CPU1_IBL_GRST_WARN_CPU1_N")
	)
	(segment
		(start 123.119896 -226.33305)
		(end 123.105164 -226.341686)
		(width 0.0889)
		(layer "B.Cu")
		(net "TP_CPU1_IBL_GRST_WARN_CPU1_N")
	)
	(segment
		(start 118.8847 -227.150422)
		(end 118.87581 -227.155502)
		(width 0.0889)
		(layer "B.Cu")
		(net "TP_CPU1_IBL_GRST_WARN_CPU1_N")
	)
	(segment
		(start 117.475254 -229.592124)
		(end 117.466364 -229.597204)
		(width 0.0889)
		(layer "B.Cu")
		(net "TP_CPU1_IBL_GRST_WARN_CPU1_N")
	)
	(segment
		(start 132.517896 -226.33305)
		(end 132.503164 -226.341686)
		(width 0.0889)
		(layer "B.Cu")
		(net "TP_CPU1_IBL_GRST_WARN_CPU1_N")
	)
	(segment
		(start 116.674138 -230.435912)
		(end 116.653056 -230.35768)
		(width 0.0889)
		(layer "B.Cu")
		(net "TP_CPU1_IBL_GRST_WARN_CPU1_N")
	)
	(segment
		(start 118.593616 -227.629466)
		(end 118.593616 -227.64496)
		(width 0.0889)
		(layer "B.Cu")
		(net "TP_CPU1_IBL_GRST_WARN_CPU1_N")
	)
	(arc
		(start 121.225564 -226.341686)
		(mid 121.038366 -226.391829)
		(end 120.851168 -226.341686)
		(width 0.0889)
		(layer "B.Cu")
		(net "TP_CPU1_IBL_GRST_WARN_CPU1_N")
	)
	(arc
		(start 135.887968 -226.341686)
		(mid 135.605266 -226.26591)
		(end 135.322564 -226.341686)
		(width 0.0889)
		(layer "B.Cu")
		(net "TP_CPU1_IBL_GRST_WARN_CPU1_N")
	)
	(arc
		(start 118.87581 -227.155502)
		(mid 118.672987 -227.355733)
		(end 118.593616 -227.629466)
		(width 0.0889)
		(layer "B.Cu")
		(net "TP_CPU1_IBL_GRST_WARN_CPU1_N")
	)
	(arc
		(start 124.610368 -226.341686)
		(mid 124.327666 -226.26591)
		(end 124.044964 -226.341686)
		(width 0.0889)
		(layer "B.Cu")
		(net "TP_CPU1_IBL_GRST_WARN_CPU1_N")
	)
	(arc
		(start 134.008368 -226.341686)
		(mid 133.725666 -226.26591)
		(end 133.442964 -226.341686)
		(width 0.0889)
		(layer "B.Cu")
		(net "TP_CPU1_IBL_GRST_WARN_CPU1_N")
	)
	(arc
		(start 118.593616 -227.64496)
		(mid 118.545937 -227.82786)
		(end 118.415054 -227.964238)
		(width 0.0889)
		(layer "B.Cu")
		(net "TP_CPU1_IBL_GRST_WARN_CPU1_N")
	)
	(arc
		(start 129.309368 -226.341686)
		(mid 129.035169 -226.265851)
		(end 128.758696 -226.33305)
		(width 0.0889)
		(layer "B.Cu")
		(net "TP_CPU1_IBL_GRST_WARN_CPU1_N")
	)
	(arc
		(start 117.653816 -229.272846)
		(mid 117.606137 -229.455746)
		(end 117.475254 -229.592124)
		(width 0.0889)
		(layer "B.Cu")
		(net "TP_CPU1_IBL_GRST_WARN_CPU1_N")
	)
	(arc
		(start 132.128768 -226.341686)
		(mid 131.854569 -226.265851)
		(end 131.578096 -226.33305)
		(width 0.0889)
		(layer "B.Cu")
		(net "TP_CPU1_IBL_GRST_WARN_CPU1_N")
	)
	(arc
		(start 119.333772 -226.348798)
		(mid 119.135544 -226.554646)
		(end 119.063262 -226.831144)
		(width 0.0889)
		(layer "B.Cu")
		(net "TP_CPU1_IBL_GRST_WARN_CPU1_N")
	)
	(arc
		(start 124.984764 -226.341686)
		(mid 124.797566 -226.391829)
		(end 124.610368 -226.341686)
		(width 0.0889)
		(layer "B.Cu")
		(net "TP_CPU1_IBL_GRST_WARN_CPU1_N")
	)
	(arc
		(start 130.623564 -226.341686)
		(mid 130.436366 -226.391829)
		(end 130.249168 -226.341686)
		(width 0.0889)
		(layer "B.Cu")
		(net "TP_CPU1_IBL_GRST_WARN_CPU1_N")
	)
	(arc
		(start 134.382764 -226.341686)
		(mid 134.195566 -226.391829)
		(end 134.008368 -226.341686)
		(width 0.0889)
		(layer "B.Cu")
		(net "TP_CPU1_IBL_GRST_WARN_CPU1_N")
	)
	(arc
		(start 132.503164 -226.341686)
		(mid 132.315966 -226.391829)
		(end 132.128768 -226.341686)
		(width 0.0889)
		(layer "B.Cu")
		(net "TP_CPU1_IBL_GRST_WARN_CPU1_N")
	)
	(arc
		(start 121.790968 -226.341686)
		(mid 121.508266 -226.26591)
		(end 121.225564 -226.341686)
		(width 0.0889)
		(layer "B.Cu")
		(net "TP_CPU1_IBL_GRST_WARN_CPU1_N")
	)
	(arc
		(start 129.683764 -226.341686)
		(mid 129.496566 -226.391829)
		(end 129.309368 -226.341686)
		(width 0.0889)
		(layer "B.Cu")
		(net "TP_CPU1_IBL_GRST_WARN_CPU1_N")
	)
	(arc
		(start 131.188968 -226.341686)
		(mid 130.906266 -226.26591)
		(end 130.623564 -226.341686)
		(width 0.0889)
		(layer "B.Cu")
		(net "TP_CPU1_IBL_GRST_WARN_CPU1_N")
	)
	(arc
		(start 127.429768 -226.341686)
		(mid 127.147066 -226.26591)
		(end 126.864364 -226.341686)
		(width 0.0889)
		(layer "B.Cu")
		(net "TP_CPU1_IBL_GRST_WARN_CPU1_N")
	)
	(arc
		(start 133.068568 -226.341686)
		(mid 132.794369 -226.265851)
		(end 132.517896 -226.33305)
		(width 0.0889)
		(layer "B.Cu")
		(net "TP_CPU1_IBL_GRST_WARN_CPU1_N")
	)
	(arc
		(start 128.369568 -226.341686)
		(mid 128.086866 -226.26591)
		(end 127.804164 -226.341686)
		(width 0.0889)
		(layer "B.Cu")
		(net "TP_CPU1_IBL_GRST_WARN_CPU1_N")
	)
	(arc
		(start 126.864364 -226.341686)
		(mid 126.677166 -226.391829)
		(end 126.489968 -226.341686)
		(width 0.0889)
		(layer "B.Cu")
		(net "TP_CPU1_IBL_GRST_WARN_CPU1_N")
	)
	(arc
		(start 125.924564 -226.341686)
		(mid 125.737366 -226.391829)
		(end 125.550168 -226.341686)
		(width 0.0889)
		(layer "B.Cu")
		(net "TP_CPU1_IBL_GRST_WARN_CPU1_N")
	)
	(arc
		(start 135.322564 -226.341686)
		(mid 135.135366 -226.391829)
		(end 134.948168 -226.341686)
		(width 0.0889)
		(layer "B.Cu")
		(net "TP_CPU1_IBL_GRST_WARN_CPU1_N")
	)
	(arc
		(start 120.851168 -226.341686)
		(mid 120.576969 -226.265851)
		(end 120.300496 -226.33305)
		(width 0.0889)
		(layer "B.Cu")
		(net "TP_CPU1_IBL_GRST_WARN_CPU1_N")
	)
	(arc
		(start 119.911368 -226.341686)
		(mid 119.628666 -226.26591)
		(end 119.345964 -226.341686)
		(width 0.0889)
		(layer "B.Cu")
		(net "TP_CPU1_IBL_GRST_WARN_CPU1_N")
	)
	(arc
		(start 136.262364 -226.341686)
		(mid 136.075166 -226.391829)
		(end 135.887968 -226.341686)
		(width 0.0889)
		(layer "B.Cu")
		(net "TP_CPU1_IBL_GRST_WARN_CPU1_N")
	)
	(arc
		(start 123.670568 -226.341686)
		(mid 123.396369 -226.265851)
		(end 123.119896 -226.33305)
		(width 0.0889)
		(layer "B.Cu")
		(net "TP_CPU1_IBL_GRST_WARN_CPU1_N")
	)
	(arc
		(start 136.545066 -226.265994)
		(mid 136.398722 -226.285202)
		(end 136.262364 -226.341686)
		(width 0.0889)
		(layer "B.Cu")
		(net "TP_CPU1_IBL_GRST_WARN_CPU1_N")
	)
	(arc
		(start 122.165364 -226.341686)
		(mid 121.978166 -226.391829)
		(end 121.790968 -226.341686)
		(width 0.0889)
		(layer "B.Cu")
		(net "TP_CPU1_IBL_GRST_WARN_CPU1_N")
	)
	(arc
		(start 131.563364 -226.341686)
		(mid 131.376166 -226.391829)
		(end 131.188968 -226.341686)
		(width 0.0889)
		(layer "B.Cu")
		(net "TP_CPU1_IBL_GRST_WARN_CPU1_N")
	)
	(arc
		(start 126.489968 -226.341686)
		(mid 126.215769 -226.265851)
		(end 125.939296 -226.33305)
		(width 0.0889)
		(layer "B.Cu")
		(net "TP_CPU1_IBL_GRST_WARN_CPU1_N")
	)
	(arc
		(start 124.044964 -226.341686)
		(mid 123.857766 -226.391829)
		(end 123.670568 -226.341686)
		(width 0.0889)
		(layer "B.Cu")
		(net "TP_CPU1_IBL_GRST_WARN_CPU1_N")
	)
	(arc
		(start 119.063262 -226.831144)
		(mid 119.015583 -227.014044)
		(end 118.8847 -227.150422)
		(width 0.0889)
		(layer "B.Cu")
		(net "TP_CPU1_IBL_GRST_WARN_CPU1_N")
	)
	(arc
		(start 130.249168 -226.341686)
		(mid 129.974969 -226.265851)
		(end 129.698496 -226.33305)
		(width 0.0889)
		(layer "B.Cu")
		(net "TP_CPU1_IBL_GRST_WARN_CPU1_N")
	)
	(arc
		(start 123.105164 -226.341686)
		(mid 122.917966 -226.391829)
		(end 122.730768 -226.341686)
		(width 0.0889)
		(layer "B.Cu")
		(net "TP_CPU1_IBL_GRST_WARN_CPU1_N")
	)
	(arc
		(start 122.730768 -226.341686)
		(mid 122.456569 -226.265851)
		(end 122.180096 -226.33305)
		(width 0.0889)
		(layer "B.Cu")
		(net "TP_CPU1_IBL_GRST_WARN_CPU1_N")
	)
	(arc
		(start 118.123462 -228.45903)
		(mid 118.075783 -228.64193)
		(end 117.9449 -228.778308)
		(width 0.0889)
		(layer "B.Cu")
		(net "TP_CPU1_IBL_GRST_WARN_CPU1_N")
	)
	(arc
		(start 127.804164 -226.341686)
		(mid 127.616966 -226.391829)
		(end 127.429768 -226.341686)
		(width 0.0889)
		(layer "B.Cu")
		(net "TP_CPU1_IBL_GRST_WARN_CPU1_N")
	)
	(arc
		(start 134.948168 -226.341686)
		(mid 134.673969 -226.265851)
		(end 134.397496 -226.33305)
		(width 0.0889)
		(layer "B.Cu")
		(net "TP_CPU1_IBL_GRST_WARN_CPU1_N")
	)
	(arc
		(start 125.550168 -226.341686)
		(mid 125.275969 -226.265851)
		(end 124.999496 -226.33305)
		(width 0.0889)
		(layer "B.Cu")
		(net "TP_CPU1_IBL_GRST_WARN_CPU1_N")
	)
	(arc
		(start 118.406164 -227.969318)
		(mid 118.202683 -228.170122)
		(end 118.123462 -228.444806)
		(width 0.0889)
		(layer "B.Cu")
		(net "TP_CPU1_IBL_GRST_WARN_CPU1_N")
	)
	(arc
		(start 133.442964 -226.341686)
		(mid 133.255766 -226.391829)
		(end 133.068568 -226.341686)
		(width 0.0889)
		(layer "B.Cu")
		(net "TP_CPU1_IBL_GRST_WARN_CPU1_N")
	)
	(arc
		(start 117.183662 -230.086916)
		(mid 117.135771 -230.270128)
		(end 117.004338 -230.406448)
		(width 0.0889)
		(layer "B.Cu")
		(net "TP_CPU1_IBL_GRST_WARN_CPU1_N")
	)
	(arc
		(start 120.285764 -226.341686)
		(mid 120.098566 -226.391829)
		(end 119.911368 -226.341686)
		(width 0.0889)
		(layer "B.Cu")
		(net "TP_CPU1_IBL_GRST_WARN_CPU1_N")
	)
	(arc
		(start 117.460268 -229.60076)
		(mid 117.257618 -229.807222)
		(end 117.183662 -230.086916)
		(width 0.0889)
		(layer "B.Cu")
		(net "TP_CPU1_IBL_GRST_WARN_CPU1_N")
	)
	(arc
		(start 116.996464 -230.41102)
		(mid 116.838124 -230.460083)
		(end 116.674138 -230.435912)
		(width 0.0889)
		(layer "B.Cu")
		(net "TP_CPU1_IBL_GRST_WARN_CPU1_N")
	)
	(arc
		(start 117.93601 -228.783388)
		(mid 117.733187 -228.983619)
		(end 117.653816 -229.257352)
		(width 0.0889)
		(layer "B.Cu")
		(net "TP_CPU1_IBL_GRST_WARN_CPU1_N")
	)
	(arc
		(start 128.743964 -226.341686)
		(mid 128.556766 -226.391829)
		(end 128.369568 -226.341686)
		(width 0.0889)
		(layer "B.Cu")
		(net "TP_CPU1_IBL_GRST_WARN_CPU1_N")
	)
	(segment
		(start 105.531666 -230.622602)
		(end 105.531666 -230.086916)
		(width 0.12954)
		(layer "F.Cu")
		(net "TP_CPU1_DIE_HVM_EN_LVC1")
	)
	(segment
		(start 105.531666 -230.086916)
		(end 105.531412 -230.086662)
		(width 0.12954)
		(layer "F.Cu")
		(net "TP_CPU1_DIE_HVM_EN_LVC1")
	)
	(via
		(at 84.064602 -225.541586)
		(size 0.6604)
		(drill 0.3302)
		(layers "F.Cu" "B.Cu")
		(net "TP_CPU1_DIE_HVM_EN_LVC1")
	)
	(via
		(at 105.531412 -230.086662)
		(size 0.4572)
		(drill 0.2032)
		(layers "F.Cu" "B.Cu")
		(net "TP_CPU1_DIE_HVM_EN_LVC1")
	)
	(segment
		(start 105.344214 -230.41102)
		(end 105.329482 -230.402384)
		(width 0.0889)
		(layer "B.Cu")
		(net "TP_CPU1_DIE_HVM_EN_LVC1")
	)
	(segment
		(start 103.277162 -228.45903)
		(end 103.277162 -228.436932)
		(width 0.0889)
		(layer "B.Cu")
		(net "TP_CPU1_DIE_HVM_EN_LVC1")
	)
	(segment
		(start 104.404414 -230.41102)
		(end 104.395524 -230.40594)
		(width 0.0889)
		(layer "B.Cu")
		(net "TP_CPU1_DIE_HVM_EN_LVC1")
	)
	(segment
		(start 105.531412 -230.086662)
		(end 105.687876 -230.35768)
		(width 0.0889)
		(layer "B.Cu")
		(net "TP_CPU1_DIE_HVM_EN_LVC1")
	)
	(segment
		(start 89.287096 -226.33305)
		(end 89.272364 -226.341686)
		(width 0.0889)
		(layer "B.Cu")
		(net "TP_CPU1_DIE_HVM_EN_LVC1")
	)
	(segment
		(start 96.805496 -226.33305)
		(end 96.790764 -226.341686)
		(width 0.0889)
		(layer "B.Cu")
		(net "TP_CPU1_DIE_HVM_EN_LVC1")
	)
	(segment
		(start 102.53091 -227.159058)
		(end 102.524814 -227.155502)
		(width 0.0889)
		(layer "B.Cu")
		(net "TP_CPU1_DIE_HVM_EN_LVC1")
	)
	(segment
		(start 90.222578 -226.33559)
		(end 90.212164 -226.341686)
		(width 0.0889)
		(layer "B.Cu")
		(net "TP_CPU1_DIE_HVM_EN_LVC1")
	)
	(segment
		(start 88.622378 -226.192588)
		(end 88.622378 -225.98507)
		(width 0.0889)
		(layer "B.Cu")
		(net "TP_CPU1_DIE_HVM_EN_LVC1")
	)
	(segment
		(start 101.504496 -226.33305)
		(end 101.489764 -226.341686)
		(width 0.0889)
		(layer "B.Cu")
		(net "TP_CPU1_DIE_HVM_EN_LVC1")
	)
	(segment
		(start 91.717368 -226.341686)
		(end 91.706954 -226.33559)
		(width 0.0889)
		(layer "B.Cu")
		(net "TP_CPU1_DIE_HVM_EN_LVC1")
	)
	(segment
		(start 102.524814 -227.155502)
		(end 102.515924 -227.150422)
		(width 0.0889)
		(layer "B.Cu")
		(net "TP_CPU1_DIE_HVM_EN_LVC1")
	)
	(segment
		(start 88.622378 -225.86315)
		(end 88.381078 -225.62185)
		(width 0.12954)
		(layer "B.Cu")
		(net "TP_CPU1_DIE_HVM_EN_LVC1")
	)
	(segment
		(start 88.381078 -225.62185)
		(end 84.576158 -225.62185)
		(width 0.12954)
		(layer "B.Cu")
		(net "TP_CPU1_DIE_HVM_EN_LVC1")
	)
	(segment
		(start 102.337362 -226.831144)
		(end 102.337362 -226.81565)
		(width 0.0889)
		(layer "B.Cu")
		(net "TP_CPU1_DIE_HVM_EN_LVC1")
	)
	(segment
		(start 88.702388 -226.272598)
		(end 88.622378 -226.192588)
		(width 0.0889)
		(layer "B.Cu")
		(net "TP_CPU1_DIE_HVM_EN_LVC1")
	)
	(segment
		(start 97.745296 -226.33305)
		(end 97.730564 -226.341686)
		(width 0.0889)
		(layer "B.Cu")
		(net "TP_CPU1_DIE_HVM_EN_LVC1")
	)
	(segment
		(start 104.216962 -230.086662)
		(end 104.216962 -230.071168)
		(width 0.0889)
		(layer "B.Cu")
		(net "TP_CPU1_DIE_HVM_EN_LVC1")
	)
	(segment
		(start 84.495894 -225.541586)
		(end 84.064602 -225.541586)
		(width 0.12954)
		(layer "B.Cu")
		(net "TP_CPU1_DIE_HVM_EN_LVC1")
	)
	(segment
		(start 103.934768 -229.597204)
		(end 103.925878 -229.592124)
		(width 0.0889)
		(layer "B.Cu")
		(net "TP_CPU1_DIE_HVM_EN_LVC1")
	)
	(segment
		(start 103.464614 -228.783388)
		(end 103.455724 -228.778308)
		(width 0.0889)
		(layer "B.Cu")
		(net "TP_CPU1_DIE_HVM_EN_LVC1")
	)
	(segment
		(start 93.986096 -226.33305)
		(end 93.971364 -226.341686)
		(width 0.0889)
		(layer "B.Cu")
		(net "TP_CPU1_DIE_HVM_EN_LVC1")
	)
	(segment
		(start 88.622378 -225.98507)
		(end 88.622378 -225.86315)
		(width 0.12954)
		(layer "B.Cu")
		(net "TP_CPU1_DIE_HVM_EN_LVC1")
	)
	(segment
		(start 94.925896 -226.33305)
		(end 94.911164 -226.341686)
		(width 0.0889)
		(layer "B.Cu")
		(net "TP_CPU1_DIE_HVM_EN_LVC1")
	)
	(segment
		(start 102.994968 -227.969318)
		(end 102.986078 -227.964238)
		(width 0.0889)
		(layer "B.Cu")
		(net "TP_CPU1_DIE_HVM_EN_LVC1")
	)
	(segment
		(start 103.47071 -228.786944)
		(end 103.464614 -228.783388)
		(width 0.0889)
		(layer "B.Cu")
		(net "TP_CPU1_DIE_HVM_EN_LVC1")
	)
	(segment
		(start 105.687876 -230.35768)
		(end 105.666794 -230.435658)
		(width 0.0889)
		(layer "B.Cu")
		(net "TP_CPU1_DIE_HVM_EN_LVC1")
	)
	(segment
		(start 84.576158 -225.62185)
		(end 84.495894 -225.541586)
		(width 0.12954)
		(layer "B.Cu")
		(net "TP_CPU1_DIE_HVM_EN_LVC1")
	)
	(arc
		(start 90.212164 -226.341686)
		(mid 90.024966 -226.391829)
		(end 89.837768 -226.341686)
		(width 0.0889)
		(layer "B.Cu")
		(net "TP_CPU1_DIE_HVM_EN_LVC1")
	)
	(arc
		(start 105.666794 -230.435658)
		(mid 105.502698 -230.460005)
		(end 105.344214 -230.41102)
		(width 0.0889)
		(layer "B.Cu")
		(net "TP_CPU1_DIE_HVM_EN_LVC1")
	)
	(arc
		(start 103.925878 -229.592124)
		(mid 103.794964 -229.455764)
		(end 103.747316 -229.272846)
		(width 0.0889)
		(layer "B.Cu")
		(net "TP_CPU1_DIE_HVM_EN_LVC1")
	)
	(arc
		(start 96.790764 -226.341686)
		(mid 96.603566 -226.391829)
		(end 96.416368 -226.341686)
		(width 0.0889)
		(layer "B.Cu")
		(net "TP_CPU1_DIE_HVM_EN_LVC1")
	)
	(arc
		(start 90.777314 -226.341686)
		(mid 90.500755 -226.265943)
		(end 90.222578 -226.33559)
		(width 0.0889)
		(layer "B.Cu")
		(net "TP_CPU1_DIE_HVM_EN_LVC1")
	)
	(arc
		(start 99.610164 -226.341686)
		(mid 99.422966 -226.391829)
		(end 99.235768 -226.341686)
		(width 0.0889)
		(layer "B.Cu")
		(net "TP_CPU1_DIE_HVM_EN_LVC1")
	)
	(arc
		(start 92.657168 -226.341686)
		(mid 92.374466 -226.26591)
		(end 92.091764 -226.341686)
		(width 0.0889)
		(layer "B.Cu")
		(net "TP_CPU1_DIE_HVM_EN_LVC1")
	)
	(arc
		(start 93.596968 -226.341686)
		(mid 93.314266 -226.26591)
		(end 93.031564 -226.341686)
		(width 0.0889)
		(layer "B.Cu")
		(net "TP_CPU1_DIE_HVM_EN_LVC1")
	)
	(arc
		(start 98.670364 -226.341686)
		(mid 98.483166 -226.391829)
		(end 98.295968 -226.341686)
		(width 0.0889)
		(layer "B.Cu")
		(net "TP_CPU1_DIE_HVM_EN_LVC1")
	)
	(arc
		(start 100.175568 -226.341686)
		(mid 99.892866 -226.26591)
		(end 99.610164 -226.341686)
		(width 0.0889)
		(layer "B.Cu")
		(net "TP_CPU1_DIE_HVM_EN_LVC1")
	)
	(arc
		(start 101.489764 -226.341686)
		(mid 101.302566 -226.391829)
		(end 101.115368 -226.341686)
		(width 0.0889)
		(layer "B.Cu")
		(net "TP_CPU1_DIE_HVM_EN_LVC1")
	)
	(arc
		(start 88.897968 -226.341686)
		(mid 88.803376 -226.298085)
		(end 88.702388 -226.272598)
		(width 0.0889)
		(layer "B.Cu")
		(net "TP_CPU1_DIE_HVM_EN_LVC1")
	)
	(arc
		(start 95.476568 -226.341686)
		(mid 95.202369 -226.265851)
		(end 94.925896 -226.33305)
		(width 0.0889)
		(layer "B.Cu")
		(net "TP_CPU1_DIE_HVM_EN_LVC1")
	)
	(arc
		(start 104.395524 -230.40594)
		(mid 104.26461 -230.26958)
		(end 104.216962 -230.086662)
		(width 0.0889)
		(layer "B.Cu")
		(net "TP_CPU1_DIE_HVM_EN_LVC1")
	)
	(arc
		(start 105.329482 -230.402384)
		(mid 105.053007 -230.335064)
		(end 104.77881 -230.41102)
		(width 0.0889)
		(layer "B.Cu")
		(net "TP_CPU1_DIE_HVM_EN_LVC1")
	)
	(arc
		(start 102.986078 -227.964238)
		(mid 102.855164 -227.827878)
		(end 102.807516 -227.64496)
		(width 0.0889)
		(layer "B.Cu")
		(net "TP_CPU1_DIE_HVM_EN_LVC1")
	)
	(arc
		(start 102.337362 -226.81565)
		(mid 102.257992 -226.541916)
		(end 102.055168 -226.341686)
		(width 0.0889)
		(layer "B.Cu")
		(net "TP_CPU1_DIE_HVM_EN_LVC1")
	)
	(arc
		(start 97.730564 -226.341686)
		(mid 97.543366 -226.391829)
		(end 97.356168 -226.341686)
		(width 0.0889)
		(layer "B.Cu")
		(net "TP_CPU1_DIE_HVM_EN_LVC1")
	)
	(arc
		(start 94.536768 -226.341686)
		(mid 94.262569 -226.265851)
		(end 93.986096 -226.33305)
		(width 0.0889)
		(layer "B.Cu")
		(net "TP_CPU1_DIE_HVM_EN_LVC1")
	)
	(arc
		(start 89.837768 -226.341686)
		(mid 89.563569 -226.265851)
		(end 89.287096 -226.33305)
		(width 0.0889)
		(layer "B.Cu")
		(net "TP_CPU1_DIE_HVM_EN_LVC1")
	)
	(arc
		(start 104.216962 -230.071168)
		(mid 104.137592 -229.797434)
		(end 103.934768 -229.597204)
		(width 0.0889)
		(layer "B.Cu")
		(net "TP_CPU1_DIE_HVM_EN_LVC1")
	)
	(arc
		(start 89.272364 -226.341686)
		(mid 89.085166 -226.391829)
		(end 88.897968 -226.341686)
		(width 0.0889)
		(layer "B.Cu")
		(net "TP_CPU1_DIE_HVM_EN_LVC1")
	)
	(arc
		(start 94.911164 -226.341686)
		(mid 94.723966 -226.391829)
		(end 94.536768 -226.341686)
		(width 0.0889)
		(layer "B.Cu")
		(net "TP_CPU1_DIE_HVM_EN_LVC1")
	)
	(arc
		(start 103.747316 -229.272846)
		(mid 103.673325 -228.99328)
		(end 103.47071 -228.786944)
		(width 0.0889)
		(layer "B.Cu")
		(net "TP_CPU1_DIE_HVM_EN_LVC1")
	)
	(arc
		(start 100.549964 -226.341686)
		(mid 100.362766 -226.391829)
		(end 100.175568 -226.341686)
		(width 0.0889)
		(layer "B.Cu")
		(net "TP_CPU1_DIE_HVM_EN_LVC1")
	)
	(arc
		(start 97.356168 -226.341686)
		(mid 97.081969 -226.265851)
		(end 96.805496 -226.33305)
		(width 0.0889)
		(layer "B.Cu")
		(net "TP_CPU1_DIE_HVM_EN_LVC1")
	)
	(arc
		(start 102.055168 -226.341686)
		(mid 101.780969 -226.265851)
		(end 101.504496 -226.33305)
		(width 0.0889)
		(layer "B.Cu")
		(net "TP_CPU1_DIE_HVM_EN_LVC1")
	)
	(arc
		(start 93.031564 -226.341686)
		(mid 92.844366 -226.391829)
		(end 92.657168 -226.341686)
		(width 0.0889)
		(layer "B.Cu")
		(net "TP_CPU1_DIE_HVM_EN_LVC1")
	)
	(arc
		(start 104.77881 -230.41102)
		(mid 104.591612 -230.461163)
		(end 104.404414 -230.41102)
		(width 0.0889)
		(layer "B.Cu")
		(net "TP_CPU1_DIE_HVM_EN_LVC1")
	)
	(arc
		(start 98.295968 -226.341686)
		(mid 98.021769 -226.265851)
		(end 97.745296 -226.33305)
		(width 0.0889)
		(layer "B.Cu")
		(net "TP_CPU1_DIE_HVM_EN_LVC1")
	)
	(arc
		(start 96.416368 -226.341686)
		(mid 96.133666 -226.26591)
		(end 95.850964 -226.341686)
		(width 0.0889)
		(layer "B.Cu")
		(net "TP_CPU1_DIE_HVM_EN_LVC1")
	)
	(arc
		(start 93.971364 -226.341686)
		(mid 93.784166 -226.391829)
		(end 93.596968 -226.341686)
		(width 0.0889)
		(layer "B.Cu")
		(net "TP_CPU1_DIE_HVM_EN_LVC1")
	)
	(arc
		(start 102.807516 -227.64496)
		(mid 102.733525 -227.365394)
		(end 102.53091 -227.159058)
		(width 0.0889)
		(layer "B.Cu")
		(net "TP_CPU1_DIE_HVM_EN_LVC1")
	)
	(arc
		(start 103.277162 -228.436932)
		(mid 103.196251 -228.166804)
		(end 102.994968 -227.969318)
		(width 0.0889)
		(layer "B.Cu")
		(net "TP_CPU1_DIE_HVM_EN_LVC1")
	)
	(arc
		(start 91.15171 -226.341686)
		(mid 90.964512 -226.391829)
		(end 90.777314 -226.341686)
		(width 0.0889)
		(layer "B.Cu")
		(net "TP_CPU1_DIE_HVM_EN_LVC1")
	)
	(arc
		(start 92.091764 -226.341686)
		(mid 91.904566 -226.391829)
		(end 91.717368 -226.341686)
		(width 0.0889)
		(layer "B.Cu")
		(net "TP_CPU1_DIE_HVM_EN_LVC1")
	)
	(arc
		(start 103.455724 -228.778308)
		(mid 103.32481 -228.641948)
		(end 103.277162 -228.45903)
		(width 0.0889)
		(layer "B.Cu")
		(net "TP_CPU1_DIE_HVM_EN_LVC1")
	)
	(arc
		(start 95.850964 -226.341686)
		(mid 95.663766 -226.391829)
		(end 95.476568 -226.341686)
		(width 0.0889)
		(layer "B.Cu")
		(net "TP_CPU1_DIE_HVM_EN_LVC1")
	)
	(arc
		(start 101.115368 -226.341686)
		(mid 100.832666 -226.26591)
		(end 100.549964 -226.341686)
		(width 0.0889)
		(layer "B.Cu")
		(net "TP_CPU1_DIE_HVM_EN_LVC1")
	)
	(arc
		(start 91.706954 -226.33559)
		(mid 91.428522 -226.265744)
		(end 91.15171 -226.341686)
		(width 0.0889)
		(layer "B.Cu")
		(net "TP_CPU1_DIE_HVM_EN_LVC1")
	)
	(arc
		(start 99.235768 -226.341686)
		(mid 98.953066 -226.26591)
		(end 98.670364 -226.341686)
		(width 0.0889)
		(layer "B.Cu")
		(net "TP_CPU1_DIE_HVM_EN_LVC1")
	)
	(arc
		(start 102.515924 -227.150422)
		(mid 102.38501 -227.014062)
		(end 102.337362 -226.831144)
		(width 0.0889)
		(layer "B.Cu")
		(net "TP_CPU1_DIE_HVM_EN_LVC1")
	)
	(segment
		(start 88.14562 -223.297242)
		(end 88.14562 -222.76181)
		(width 0.12954)
		(layer "F.Cu")
		(net "TP_CPU1_A0_DEBUG_EN")
	)
	(segment
		(start 88.145366 -223.297496)
		(end 88.14562 -223.297242)
		(width 0.12954)
		(layer "F.Cu")
		(net "TP_CPU1_A0_DEBUG_EN")
	)
	(segment
		(start 88.14562 -222.76181)
		(end 88.145366 -222.761556)
		(width 0.12954)
		(layer "F.Cu")
		(net "TP_CPU1_A0_DEBUG_EN")
	)
	(via
		(at 88.145366 -222.761556)
		(size 0.4572)
		(drill 0.2032)
		(layers "F.Cu" "B.Cu")
		(net "TP_CPU1_A0_DEBUG_EN")
	)
	(via
		(at 84.804758 -220.82887)
		(size 0.6604)
		(drill 0.3302)
		(layers "F.Cu" "B.Cu")
		(net "TP_CPU1_A0_DEBUG_EN")
	)
	(segment
		(start 86.349586 -222.373698)
		(end 84.804758 -220.82887)
		(width 0.12954)
		(layer "B.Cu")
		(net "TP_CPU1_A0_DEBUG_EN")
	)
	(segment
		(start 87.851234 -222.761556)
		(end 87.463376 -222.373698)
		(width 0.0889)
		(layer "B.Cu")
		(net "TP_CPU1_A0_DEBUG_EN")
	)
	(segment
		(start 88.145366 -222.761556)
		(end 87.851234 -222.761556)
		(width 0.0889)
		(layer "B.Cu")
		(net "TP_CPU1_A0_DEBUG_EN")
	)
	(segment
		(start 87.463376 -222.373698)
		(end 86.349586 -222.373698)
		(width 0.0889)
		(layer "B.Cu")
		(net "TP_CPU1_A0_DEBUG_EN")
	)
	(segment
		(start 365.799116 -268.84757)
		(end 365.799116 -269.38351)
		(width 0.12954)
		(layer "F.Cu")
		(net "TP_CPU0_SSC_SYNC")
	)
	(via
		(at 365.799116 -269.38351)
		(size 0.4572)
		(drill 0.2032)
		(layers "F.Cu" "B.Cu")
		(net "TP_CPU0_SSC_SYNC")
	)
	(via
		(at 386.267198 -269.746222)
		(size 0.6604)
		(drill 0.3302)
		(layers "F.Cu" "B.Cu")
		(net "TP_CPU0_SSC_SYNC")
	)
	(segment
		(start 386.267198 -269.746222)
		(end 384.849116 -269.746222)
		(width 0.12954)
		(layer "B.Cu")
		(net "TP_CPU0_SSC_SYNC")
	)
	(segment
		(start 384.142488 -269.249144)
		(end 383.96545 -269.113254)
		(width 0.0889)
		(layer "B.Cu")
		(net "TP_CPU0_SSC_SYNC")
	)
	(segment
		(start 377.829064 -269.059152)
		(end 377.814332 -269.067788)
		(width 0.0889)
		(layer "B.Cu")
		(net "TP_CPU0_SSC_SYNC")
	)
	(segment
		(start 365.663734 -269.034514)
		(end 365.642652 -269.112492)
		(width 0.0889)
		(layer "B.Cu")
		(net "TP_CPU0_SSC_SYNC")
	)
	(segment
		(start 366.940846 -269.067788)
		(end 366.926114 -269.059152)
		(width 0.0889)
		(layer "B.Cu")
		(net "TP_CPU0_SSC_SYNC")
	)
	(segment
		(start 376.889264 -269.059152)
		(end 376.874532 -269.067788)
		(width 0.0889)
		(layer "B.Cu")
		(net "TP_CPU0_SSC_SYNC")
	)
	(segment
		(start 383.875788 -269.078456)
		(end 383.84226 -269.059152)
		(width 0.0889)
		(layer "B.Cu")
		(net "TP_CPU0_SSC_SYNC")
	)
	(segment
		(start 384.849116 -269.746222)
		(end 384.43916 -269.746222)
		(width 0.0889)
		(layer "B.Cu")
		(net "TP_CPU0_SSC_SYNC")
	)
	(segment
		(start 380.648718 -269.059152)
		(end 380.638304 -269.065248)
		(width 0.0889)
		(layer "B.Cu")
		(net "TP_CPU0_SSC_SYNC")
	)
	(segment
		(start 375.949464 -269.059152)
		(end 375.934732 -269.067788)
		(width 0.0889)
		(layer "B.Cu")
		(net "TP_CPU0_SSC_SYNC")
	)
	(segment
		(start 378.768864 -269.059152)
		(end 378.754132 -269.067788)
		(width 0.0889)
		(layer "B.Cu")
		(net "TP_CPU0_SSC_SYNC")
	)
	(segment
		(start 375.009664 -269.059152)
		(end 374.994932 -269.067788)
		(width 0.0889)
		(layer "B.Cu")
		(net "TP_CPU0_SSC_SYNC")
	)
	(segment
		(start 384.215894 -269.32255)
		(end 384.142488 -269.249144)
		(width 0.0889)
		(layer "B.Cu")
		(net "TP_CPU0_SSC_SYNC")
	)
	(segment
		(start 369.755928 -269.065248)
		(end 369.745514 -269.059152)
		(width 0.0889)
		(layer "B.Cu")
		(net "TP_CPU0_SSC_SYNC")
	)
	(segment
		(start 384.43916 -269.746222)
		(end 384.215894 -269.522956)
		(width 0.0889)
		(layer "B.Cu")
		(net "TP_CPU0_SSC_SYNC")
	)
	(segment
		(start 383.467864 -269.059152)
		(end 383.453132 -269.067788)
		(width 0.0889)
		(layer "B.Cu")
		(net "TP_CPU0_SSC_SYNC")
	)
	(segment
		(start 382.528064 -269.059152)
		(end 382.513332 -269.067788)
		(width 0.0889)
		(layer "B.Cu")
		(net "TP_CPU0_SSC_SYNC")
	)
	(segment
		(start 367.876328 -269.065248)
		(end 367.865914 -269.059152)
		(width 0.0889)
		(layer "B.Cu")
		(net "TP_CPU0_SSC_SYNC")
	)
	(segment
		(start 373.130064 -269.059152)
		(end 373.115332 -269.067788)
		(width 0.0889)
		(layer "B.Cu")
		(net "TP_CPU0_SSC_SYNC")
	)
	(segment
		(start 369.371118 -269.059152)
		(end 369.360704 -269.065248)
		(width 0.0889)
		(layer "B.Cu")
		(net "TP_CPU0_SSC_SYNC")
	)
	(segment
		(start 381.588264 -269.059152)
		(end 381.57785 -269.065248)
		(width 0.0889)
		(layer "B.Cu")
		(net "TP_CPU0_SSC_SYNC")
	)
	(segment
		(start 374.069864 -269.059152)
		(end 374.055132 -269.067788)
		(width 0.0889)
		(layer "B.Cu")
		(net "TP_CPU0_SSC_SYNC")
	)
	(segment
		(start 384.215894 -269.522956)
		(end 384.215894 -269.32255)
		(width 0.0889)
		(layer "B.Cu")
		(net "TP_CPU0_SSC_SYNC")
	)
	(segment
		(start 365.642652 -269.112492)
		(end 365.799116 -269.38351)
		(width 0.0889)
		(layer "B.Cu")
		(net "TP_CPU0_SSC_SYNC")
	)
	(segment
		(start 372.190264 -269.059152)
		(end 372.175532 -269.067788)
		(width 0.0889)
		(layer "B.Cu")
		(net "TP_CPU0_SSC_SYNC")
	)
	(segment
		(start 379.708664 -269.059152)
		(end 379.693932 -269.067788)
		(width 0.0889)
		(layer "B.Cu")
		(net "TP_CPU0_SSC_SYNC")
	)
	(arc
		(start 381.023114 -269.059152)
		(mid 380.835916 -269.009009)
		(end 380.648718 -269.059152)
		(width 0.0889)
		(layer "B.Cu")
		(net "TP_CPU0_SSC_SYNC")
	)
	(arc
		(start 373.115332 -269.067788)
		(mid 372.838857 -269.135108)
		(end 372.56466 -269.059152)
		(width 0.0889)
		(layer "B.Cu")
		(net "TP_CPU0_SSC_SYNC")
	)
	(arc
		(start 381.96266 -269.059152)
		(mid 381.775462 -269.009009)
		(end 381.588264 -269.059152)
		(width 0.0889)
		(layer "B.Cu")
		(net "TP_CPU0_SSC_SYNC")
	)
	(arc
		(start 370.68506 -269.059152)
		(mid 370.497862 -269.009009)
		(end 370.310664 -269.059152)
		(width 0.0889)
		(layer "B.Cu")
		(net "TP_CPU0_SSC_SYNC")
	)
	(arc
		(start 381.57785 -269.065248)
		(mid 381.299672 -269.134971)
		(end 381.023114 -269.059152)
		(width 0.0889)
		(layer "B.Cu")
		(net "TP_CPU0_SSC_SYNC")
	)
	(arc
		(start 377.814332 -269.067788)
		(mid 377.537857 -269.135108)
		(end 377.26366 -269.059152)
		(width 0.0889)
		(layer "B.Cu")
		(net "TP_CPU0_SSC_SYNC")
	)
	(arc
		(start 379.14326 -269.059152)
		(mid 378.956062 -269.009009)
		(end 378.768864 -269.059152)
		(width 0.0889)
		(layer "B.Cu")
		(net "TP_CPU0_SSC_SYNC")
	)
	(arc
		(start 382.513332 -269.067788)
		(mid 382.236857 -269.135108)
		(end 381.96266 -269.059152)
		(width 0.0889)
		(layer "B.Cu")
		(net "TP_CPU0_SSC_SYNC")
	)
	(arc
		(start 371.250464 -269.059152)
		(mid 370.967762 -269.134928)
		(end 370.68506 -269.059152)
		(width 0.0889)
		(layer "B.Cu")
		(net "TP_CPU0_SSC_SYNC")
	)
	(arc
		(start 372.175532 -269.067788)
		(mid 371.899057 -269.135108)
		(end 371.62486 -269.059152)
		(width 0.0889)
		(layer "B.Cu")
		(net "TP_CPU0_SSC_SYNC")
	)
	(arc
		(start 379.693932 -269.067788)
		(mid 379.417457 -269.135108)
		(end 379.14326 -269.059152)
		(width 0.0889)
		(layer "B.Cu")
		(net "TP_CPU0_SSC_SYNC")
	)
	(arc
		(start 375.38406 -269.059152)
		(mid 375.196862 -269.009009)
		(end 375.009664 -269.059152)
		(width 0.0889)
		(layer "B.Cu")
		(net "TP_CPU0_SSC_SYNC")
	)
	(arc
		(start 374.994932 -269.067788)
		(mid 374.718457 -269.135108)
		(end 374.44426 -269.059152)
		(width 0.0889)
		(layer "B.Cu")
		(net "TP_CPU0_SSC_SYNC")
	)
	(arc
		(start 370.310664 -269.059152)
		(mid 370.034105 -269.134895)
		(end 369.755928 -269.065248)
		(width 0.0889)
		(layer "B.Cu")
		(net "TP_CPU0_SSC_SYNC")
	)
	(arc
		(start 365.986314 -269.059152)
		(mid 365.827826 -269.010219)
		(end 365.663734 -269.034514)
		(width 0.0889)
		(layer "B.Cu")
		(net "TP_CPU0_SSC_SYNC")
	)
	(arc
		(start 380.08306 -269.059152)
		(mid 379.895862 -269.009009)
		(end 379.708664 -269.059152)
		(width 0.0889)
		(layer "B.Cu")
		(net "TP_CPU0_SSC_SYNC")
	)
	(arc
		(start 378.20346 -269.059152)
		(mid 378.016262 -269.009009)
		(end 377.829064 -269.059152)
		(width 0.0889)
		(layer "B.Cu")
		(net "TP_CPU0_SSC_SYNC")
	)
	(arc
		(start 369.360704 -269.065248)
		(mid 369.082272 -269.135094)
		(end 368.80546 -269.059152)
		(width 0.0889)
		(layer "B.Cu")
		(net "TP_CPU0_SSC_SYNC")
	)
	(arc
		(start 383.96545 -269.113254)
		(mid 383.919884 -269.097751)
		(end 383.875788 -269.078456)
		(width 0.0889)
		(layer "B.Cu")
		(net "TP_CPU0_SSC_SYNC")
	)
	(arc
		(start 367.491518 -269.059152)
		(mid 367.217319 -269.134987)
		(end 366.940846 -269.067788)
		(width 0.0889)
		(layer "B.Cu")
		(net "TP_CPU0_SSC_SYNC")
	)
	(arc
		(start 374.44426 -269.059152)
		(mid 374.257062 -269.009009)
		(end 374.069864 -269.059152)
		(width 0.0889)
		(layer "B.Cu")
		(net "TP_CPU0_SSC_SYNC")
	)
	(arc
		(start 376.32386 -269.059152)
		(mid 376.136662 -269.009009)
		(end 375.949464 -269.059152)
		(width 0.0889)
		(layer "B.Cu")
		(net "TP_CPU0_SSC_SYNC")
	)
	(arc
		(start 380.638304 -269.065248)
		(mid 380.359872 -269.135094)
		(end 380.08306 -269.059152)
		(width 0.0889)
		(layer "B.Cu")
		(net "TP_CPU0_SSC_SYNC")
	)
	(arc
		(start 378.754132 -269.067788)
		(mid 378.477657 -269.135108)
		(end 378.20346 -269.059152)
		(width 0.0889)
		(layer "B.Cu")
		(net "TP_CPU0_SSC_SYNC")
	)
	(arc
		(start 383.84226 -269.059152)
		(mid 383.655062 -269.009009)
		(end 383.467864 -269.059152)
		(width 0.0889)
		(layer "B.Cu")
		(net "TP_CPU0_SSC_SYNC")
	)
	(arc
		(start 372.56466 -269.059152)
		(mid 372.377462 -269.009009)
		(end 372.190264 -269.059152)
		(width 0.0889)
		(layer "B.Cu")
		(net "TP_CPU0_SSC_SYNC")
	)
	(arc
		(start 376.874532 -269.067788)
		(mid 376.598057 -269.135108)
		(end 376.32386 -269.059152)
		(width 0.0889)
		(layer "B.Cu")
		(net "TP_CPU0_SSC_SYNC")
	)
	(arc
		(start 383.453132 -269.067788)
		(mid 383.176657 -269.135108)
		(end 382.90246 -269.059152)
		(width 0.0889)
		(layer "B.Cu")
		(net "TP_CPU0_SSC_SYNC")
	)
	(arc
		(start 373.50446 -269.059152)
		(mid 373.317262 -269.009009)
		(end 373.130064 -269.059152)
		(width 0.0889)
		(layer "B.Cu")
		(net "TP_CPU0_SSC_SYNC")
	)
	(arc
		(start 368.80546 -269.059152)
		(mid 368.618262 -269.009009)
		(end 368.431064 -269.059152)
		(width 0.0889)
		(layer "B.Cu")
		(net "TP_CPU0_SSC_SYNC")
	)
	(arc
		(start 375.934732 -269.067788)
		(mid 375.658257 -269.135108)
		(end 375.38406 -269.059152)
		(width 0.0889)
		(layer "B.Cu")
		(net "TP_CPU0_SSC_SYNC")
	)
	(arc
		(start 371.62486 -269.059152)
		(mid 371.437662 -269.009009)
		(end 371.250464 -269.059152)
		(width 0.0889)
		(layer "B.Cu")
		(net "TP_CPU0_SSC_SYNC")
	)
	(arc
		(start 367.865914 -269.059152)
		(mid 367.678716 -269.009009)
		(end 367.491518 -269.059152)
		(width 0.0889)
		(layer "B.Cu")
		(net "TP_CPU0_SSC_SYNC")
	)
	(arc
		(start 377.26366 -269.059152)
		(mid 377.076462 -269.009009)
		(end 376.889264 -269.059152)
		(width 0.0889)
		(layer "B.Cu")
		(net "TP_CPU0_SSC_SYNC")
	)
	(arc
		(start 374.055132 -269.067788)
		(mid 373.778657 -269.135108)
		(end 373.50446 -269.059152)
		(width 0.0889)
		(layer "B.Cu")
		(net "TP_CPU0_SSC_SYNC")
	)
	(arc
		(start 366.926114 -269.059152)
		(mid 366.738916 -269.009009)
		(end 366.551718 -269.059152)
		(width 0.0889)
		(layer "B.Cu")
		(net "TP_CPU0_SSC_SYNC")
	)
	(arc
		(start 382.90246 -269.059152)
		(mid 382.715262 -269.009009)
		(end 382.528064 -269.059152)
		(width 0.0889)
		(layer "B.Cu")
		(net "TP_CPU0_SSC_SYNC")
	)
	(arc
		(start 368.431064 -269.059152)
		(mid 368.154505 -269.134895)
		(end 367.876328 -269.065248)
		(width 0.0889)
		(layer "B.Cu")
		(net "TP_CPU0_SSC_SYNC")
	)
	(arc
		(start 369.745514 -269.059152)
		(mid 369.558316 -269.009009)
		(end 369.371118 -269.059152)
		(width 0.0889)
		(layer "B.Cu")
		(net "TP_CPU0_SSC_SYNC")
	)
	(arc
		(start 366.551718 -269.059152)
		(mid 366.269016 -269.134928)
		(end 365.986314 -269.059152)
		(width 0.0889)
		(layer "B.Cu")
		(net "TP_CPU0_SSC_SYNC")
	)
	(segment
		(start 364.389162 -264.778236)
		(end 364.389416 -264.77849)
		(width 0.12954)
		(layer "F.Cu")
		(net "TP_CPU0_SPARE9")
	)
	(segment
		(start 364.389416 -264.77849)
		(end 364.389416 -265.314176)
		(width 0.12954)
		(layer "F.Cu")
		(net "TP_CPU0_SPARE9")
	)
	(via
		(at 387.793484 -266.285472)
		(size 0.6604)
		(drill 0.3302)
		(layers "F.Cu" "B.Cu")
		(net "TP_CPU0_SPARE9")
	)
	(via
		(at 364.389416 -265.314176)
		(size 0.4572)
		(drill 0.2032)
		(layers "F.Cu" "B.Cu")
		(net "TP_CPU0_SPARE9")
	)
	(segment
		(start 377.733814 -266.617704)
		(end 377.748546 -266.62634)
		(width 0.0889)
		(layer "B.Cu")
		(net "TP_CPU0_SPARE9")
	)
	(segment
		(start 374.914414 -266.617704)
		(end 374.929146 -266.62634)
		(width 0.0889)
		(layer "B.Cu")
		(net "TP_CPU0_SPARE9")
	)
	(segment
		(start 373.034814 -266.617704)
		(end 373.045228 -266.6238)
		(width 0.0889)
		(layer "B.Cu")
		(net "TP_CPU0_SPARE9")
	)
	(segment
		(start 364.70209 -265.314176)
		(end 364.767368 -265.379454)
		(width 0.0889)
		(layer "B.Cu")
		(net "TP_CPU0_SPARE9")
	)
	(segment
		(start 372.095014 -266.617704)
		(end 372.109746 -266.62634)
		(width 0.0889)
		(layer "B.Cu")
		(net "TP_CPU0_SPARE9")
	)
	(segment
		(start 368.335814 -266.617704)
		(end 368.346228 -266.6238)
		(width 0.0889)
		(layer "B.Cu")
		(net "TP_CPU0_SPARE9")
	)
	(segment
		(start 379.613414 -266.617704)
		(end 379.623828 -266.6238)
		(width 0.0889)
		(layer "B.Cu")
		(net "TP_CPU0_SPARE9")
	)
	(segment
		(start 368.329718 -266.614148)
		(end 368.335814 -266.617704)
		(width 0.0889)
		(layer "B.Cu")
		(net "TP_CPU0_SPARE9")
	)
	(segment
		(start 387.277864 -266.801092)
		(end 387.793484 -266.285472)
		(width 0.12954)
		(layer "B.Cu")
		(net "TP_CPU0_SPARE9")
	)
	(segment
		(start 375.854214 -266.617704)
		(end 375.868946 -266.62634)
		(width 0.0889)
		(layer "B.Cu")
		(net "TP_CPU0_SPARE9")
	)
	(segment
		(start 387.206998 -266.801092)
		(end 387.277864 -266.801092)
		(width 0.12954)
		(layer "B.Cu")
		(net "TP_CPU0_SPARE9")
	)
	(segment
		(start 384.293364 -266.566904)
		(end 384.527552 -266.801092)
		(width 0.0889)
		(layer "B.Cu")
		(net "TP_CPU0_SPARE9")
	)
	(segment
		(start 384.124962 -266.566904)
		(end 384.293364 -266.566904)
		(width 0.0889)
		(layer "B.Cu")
		(net "TP_CPU0_SPARE9")
	)
	(segment
		(start 371.155214 -266.617704)
		(end 371.169946 -266.62634)
		(width 0.0889)
		(layer "B.Cu")
		(net "TP_CPU0_SPARE9")
	)
	(segment
		(start 365.596932 -265.812524)
		(end 365.611664 -265.803888)
		(width 0.0889)
		(layer "B.Cu")
		(net "TP_CPU0_SPARE9")
	)
	(segment
		(start 376.794014 -266.617704)
		(end 376.808746 -266.62634)
		(width 0.0889)
		(layer "B.Cu")
		(net "TP_CPU0_SPARE9")
	)
	(segment
		(start 373.97436 -266.617704)
		(end 373.984774 -266.6238)
		(width 0.0889)
		(layer "B.Cu")
		(net "TP_CPU0_SPARE9")
	)
	(segment
		(start 381.49276 -266.617704)
		(end 381.503174 -266.6238)
		(width 0.0889)
		(layer "B.Cu")
		(net "TP_CPU0_SPARE9")
	)
	(segment
		(start 370.215414 -266.617704)
		(end 370.230146 -266.62634)
		(width 0.0889)
		(layer "B.Cu")
		(net "TP_CPU0_SPARE9")
	)
	(segment
		(start 364.389416 -265.314176)
		(end 364.70209 -265.314176)
		(width 0.0889)
		(layer "B.Cu")
		(net "TP_CPU0_SPARE9")
	)
	(segment
		(start 367.86566 -265.803888)
		(end 367.87455 -265.808968)
		(width 0.0889)
		(layer "B.Cu")
		(net "TP_CPU0_SPARE9")
	)
	(segment
		(start 367.476532 -265.812524)
		(end 367.491264 -265.803888)
		(width 0.0889)
		(layer "B.Cu")
		(net "TP_CPU0_SPARE9")
	)
	(segment
		(start 369.27536 -266.617704)
		(end 369.285774 -266.6238)
		(width 0.0889)
		(layer "B.Cu")
		(net "TP_CPU0_SPARE9")
	)
	(segment
		(start 378.673614 -266.617704)
		(end 378.688346 -266.62634)
		(width 0.0889)
		(layer "B.Cu")
		(net "TP_CPU0_SPARE9")
	)
	(segment
		(start 382.432814 -266.617704)
		(end 382.447546 -266.62634)
		(width 0.0889)
		(layer "B.Cu")
		(net "TP_CPU0_SPARE9")
	)
	(segment
		(start 383.372614 -266.617704)
		(end 383.383028 -266.6238)
		(width 0.0889)
		(layer "B.Cu")
		(net "TP_CPU0_SPARE9")
	)
	(segment
		(start 384.527552 -266.801092)
		(end 387.206998 -266.801092)
		(width 0.0889)
		(layer "B.Cu")
		(net "TP_CPU0_SPARE9")
	)
	(arc
		(start 377.359418 -266.617704)
		(mid 377.546616 -266.567527)
		(end 377.733814 -266.617704)
		(width 0.0889)
		(layer "B.Cu")
		(net "TP_CPU0_SPARE9")
	)
	(arc
		(start 383.383028 -266.6238)
		(mid 383.661206 -266.693523)
		(end 383.937764 -266.617704)
		(width 0.0889)
		(layer "B.Cu")
		(net "TP_CPU0_SPARE9")
	)
	(arc
		(start 373.599964 -266.617704)
		(mid 373.787162 -266.567527)
		(end 373.97436 -266.617704)
		(width 0.0889)
		(layer "B.Cu")
		(net "TP_CPU0_SPARE9")
	)
	(arc
		(start 371.169946 -266.62634)
		(mid 371.446421 -266.69366)
		(end 371.720618 -266.617704)
		(width 0.0889)
		(layer "B.Cu")
		(net "TP_CPU0_SPARE9")
	)
	(arc
		(start 371.720618 -266.617704)
		(mid 371.907816 -266.567527)
		(end 372.095014 -266.617704)
		(width 0.0889)
		(layer "B.Cu")
		(net "TP_CPU0_SPARE9")
	)
	(arc
		(start 382.998218 -266.617704)
		(mid 383.185416 -266.567561)
		(end 383.372614 -266.617704)
		(width 0.0889)
		(layer "B.Cu")
		(net "TP_CPU0_SPARE9")
	)
	(arc
		(start 368.346228 -266.6238)
		(mid 368.624406 -266.693523)
		(end 368.900964 -266.617704)
		(width 0.0889)
		(layer "B.Cu")
		(net "TP_CPU0_SPARE9")
	)
	(arc
		(start 378.688346 -266.62634)
		(mid 378.964821 -266.69366)
		(end 379.239018 -266.617704)
		(width 0.0889)
		(layer "B.Cu")
		(net "TP_CPU0_SPARE9")
	)
	(arc
		(start 372.660418 -266.617704)
		(mid 372.847616 -266.567527)
		(end 373.034814 -266.617704)
		(width 0.0889)
		(layer "B.Cu")
		(net "TP_CPU0_SPARE9")
	)
	(arc
		(start 364.767368 -265.379454)
		(mid 364.856482 -265.624751)
		(end 365.04626 -265.803888)
		(width 0.0889)
		(layer "B.Cu")
		(net "TP_CPU0_SPARE9")
	)
	(arc
		(start 381.503174 -266.6238)
		(mid 381.781606 -266.693646)
		(end 382.058418 -266.617704)
		(width 0.0889)
		(layer "B.Cu")
		(net "TP_CPU0_SPARE9")
	)
	(arc
		(start 365.611664 -265.803888)
		(mid 365.798862 -265.753745)
		(end 365.98606 -265.803888)
		(width 0.0889)
		(layer "B.Cu")
		(net "TP_CPU0_SPARE9")
	)
	(arc
		(start 379.239018 -266.617704)
		(mid 379.426216 -266.567527)
		(end 379.613414 -266.617704)
		(width 0.0889)
		(layer "B.Cu")
		(net "TP_CPU0_SPARE9")
	)
	(arc
		(start 381.118364 -266.617704)
		(mid 381.305562 -266.567527)
		(end 381.49276 -266.617704)
		(width 0.0889)
		(layer "B.Cu")
		(net "TP_CPU0_SPARE9")
	)
	(arc
		(start 373.984774 -266.6238)
		(mid 374.263206 -266.693646)
		(end 374.540018 -266.617704)
		(width 0.0889)
		(layer "B.Cu")
		(net "TP_CPU0_SPARE9")
	)
	(arc
		(start 367.87455 -265.808968)
		(mid 368.005464 -265.945328)
		(end 368.053112 -266.128246)
		(width 0.0889)
		(layer "B.Cu")
		(net "TP_CPU0_SPARE9")
	)
	(arc
		(start 382.058418 -266.617704)
		(mid 382.245616 -266.567527)
		(end 382.432814 -266.617704)
		(width 0.0889)
		(layer "B.Cu")
		(net "TP_CPU0_SPARE9")
	)
	(arc
		(start 365.98606 -265.803888)
		(mid 366.268762 -265.87963)
		(end 366.551464 -265.803888)
		(width 0.0889)
		(layer "B.Cu")
		(net "TP_CPU0_SPARE9")
	)
	(arc
		(start 369.841018 -266.617704)
		(mid 370.028216 -266.567527)
		(end 370.215414 -266.617704)
		(width 0.0889)
		(layer "B.Cu")
		(net "TP_CPU0_SPARE9")
	)
	(arc
		(start 374.540018 -266.617704)
		(mid 374.727216 -266.567527)
		(end 374.914414 -266.617704)
		(width 0.0889)
		(layer "B.Cu")
		(net "TP_CPU0_SPARE9")
	)
	(arc
		(start 373.045228 -266.6238)
		(mid 373.323406 -266.693523)
		(end 373.599964 -266.617704)
		(width 0.0889)
		(layer "B.Cu")
		(net "TP_CPU0_SPARE9")
	)
	(arc
		(start 375.868946 -266.62634)
		(mid 376.145421 -266.69366)
		(end 376.419618 -266.617704)
		(width 0.0889)
		(layer "B.Cu")
		(net "TP_CPU0_SPARE9")
	)
	(arc
		(start 376.419618 -266.617704)
		(mid 376.606816 -266.567527)
		(end 376.794014 -266.617704)
		(width 0.0889)
		(layer "B.Cu")
		(net "TP_CPU0_SPARE9")
	)
	(arc
		(start 372.109746 -266.62634)
		(mid 372.386221 -266.69366)
		(end 372.660418 -266.617704)
		(width 0.0889)
		(layer "B.Cu")
		(net "TP_CPU0_SPARE9")
	)
	(arc
		(start 369.285774 -266.6238)
		(mid 369.564206 -266.693646)
		(end 369.841018 -266.617704)
		(width 0.0889)
		(layer "B.Cu")
		(net "TP_CPU0_SPARE9")
	)
	(arc
		(start 379.623828 -266.6238)
		(mid 379.902006 -266.693523)
		(end 380.178564 -266.617704)
		(width 0.0889)
		(layer "B.Cu")
		(net "TP_CPU0_SPARE9")
	)
	(arc
		(start 376.808746 -266.62634)
		(mid 377.085221 -266.69366)
		(end 377.359418 -266.617704)
		(width 0.0889)
		(layer "B.Cu")
		(net "TP_CPU0_SPARE9")
	)
	(arc
		(start 374.929146 -266.62634)
		(mid 375.205621 -266.69366)
		(end 375.479818 -266.617704)
		(width 0.0889)
		(layer "B.Cu")
		(net "TP_CPU0_SPARE9")
	)
	(arc
		(start 365.04626 -265.803888)
		(mid 365.320489 -265.879813)
		(end 365.596932 -265.812524)
		(width 0.0889)
		(layer "B.Cu")
		(net "TP_CPU0_SPARE9")
	)
	(arc
		(start 382.447546 -266.62634)
		(mid 382.724021 -266.69366)
		(end 382.998218 -266.617704)
		(width 0.0889)
		(layer "B.Cu")
		(net "TP_CPU0_SPARE9")
	)
	(arc
		(start 368.900964 -266.617704)
		(mid 369.088162 -266.567527)
		(end 369.27536 -266.617704)
		(width 0.0889)
		(layer "B.Cu")
		(net "TP_CPU0_SPARE9")
	)
	(arc
		(start 366.551464 -265.803888)
		(mid 366.738662 -265.753779)
		(end 366.92586 -265.803888)
		(width 0.0889)
		(layer "B.Cu")
		(net "TP_CPU0_SPARE9")
	)
	(arc
		(start 380.178564 -266.617704)
		(mid 380.365762 -266.567527)
		(end 380.55296 -266.617704)
		(width 0.0889)
		(layer "B.Cu")
		(net "TP_CPU0_SPARE9")
	)
	(arc
		(start 375.479818 -266.617704)
		(mid 375.667016 -266.567527)
		(end 375.854214 -266.617704)
		(width 0.0889)
		(layer "B.Cu")
		(net "TP_CPU0_SPARE9")
	)
	(arc
		(start 378.299218 -266.617704)
		(mid 378.486416 -266.567527)
		(end 378.673614 -266.617704)
		(width 0.0889)
		(layer "B.Cu")
		(net "TP_CPU0_SPARE9")
	)
	(arc
		(start 377.748546 -266.62634)
		(mid 378.025021 -266.69366)
		(end 378.299218 -266.617704)
		(width 0.0889)
		(layer "B.Cu")
		(net "TP_CPU0_SPARE9")
	)
	(arc
		(start 383.937764 -266.617704)
		(mid 384.028015 -266.579957)
		(end 384.124962 -266.566904)
		(width 0.0889)
		(layer "B.Cu")
		(net "TP_CPU0_SPARE9")
	)
	(arc
		(start 370.780818 -266.617704)
		(mid 370.968016 -266.567527)
		(end 371.155214 -266.617704)
		(width 0.0889)
		(layer "B.Cu")
		(net "TP_CPU0_SPARE9")
	)
	(arc
		(start 367.491264 -265.803888)
		(mid 367.678462 -265.753745)
		(end 367.86566 -265.803888)
		(width 0.0889)
		(layer "B.Cu")
		(net "TP_CPU0_SPARE9")
	)
	(arc
		(start 368.053112 -266.128246)
		(mid 368.127103 -266.407812)
		(end 368.329718 -266.614148)
		(width 0.0889)
		(layer "B.Cu")
		(net "TP_CPU0_SPARE9")
	)
	(arc
		(start 380.55296 -266.617704)
		(mid 380.835662 -266.69348)
		(end 381.118364 -266.617704)
		(width 0.0889)
		(layer "B.Cu")
		(net "TP_CPU0_SPARE9")
	)
	(arc
		(start 370.230146 -266.62634)
		(mid 370.506621 -266.69366)
		(end 370.780818 -266.617704)
		(width 0.0889)
		(layer "B.Cu")
		(net "TP_CPU0_SPARE9")
	)
	(arc
		(start 366.92586 -265.803888)
		(mid 367.200089 -265.879813)
		(end 367.476532 -265.812524)
		(width 0.0889)
		(layer "B.Cu")
		(net "TP_CPU0_SPARE9")
	)
	(segment
		(start 365.328962 -264.778236)
		(end 365.329216 -264.77849)
		(width 0.12954)
		(layer "F.Cu")
		(net "TP_CPU0_SPARE8")
	)
	(segment
		(start 365.329216 -264.77849)
		(end 365.329216 -265.314176)
		(width 0.12954)
		(layer "F.Cu")
		(net "TP_CPU0_SPARE8")
	)
	(via
		(at 365.329216 -265.314176)
		(size 0.4572)
		(drill 0.2032)
		(layers "F.Cu" "B.Cu")
		(net "TP_CPU0_SPARE8")
	)
	(via
		(at 386.777484 -266.285472)
		(size 0.6604)
		(drill 0.3302)
		(layers "F.Cu" "B.Cu")
		(net "TP_CPU0_SPARE8")
	)
	(segment
		(start 366.092486 -265.644884)
		(end 366.081564 -265.638534)
		(width 0.0889)
		(layer "B.Cu")
		(net "TP_CPU0_SPARE8")
	)
	(segment
		(start 384.372358 -266.376658)
		(end 384.124962 -266.376658)
		(width 0.0889)
		(layer "B.Cu")
		(net "TP_CPU0_SPARE8")
	)
	(segment
		(start 385.704842 -266.610846)
		(end 384.606546 -266.610846)
		(width 0.0889)
		(layer "B.Cu")
		(net "TP_CPU0_SPARE8")
	)
	(segment
		(start 386.777484 -266.285472)
		(end 386.030216 -266.285472)
		(width 0.12954)
		(layer "B.Cu")
		(net "TP_CPU0_SPARE8")
	)
	(segment
		(start 378.768864 -266.45235)
		(end 378.754132 -266.443714)
		(width 0.0889)
		(layer "B.Cu")
		(net "TP_CPU0_SPARE8")
	)
	(segment
		(start 375.009664 -266.45235)
		(end 374.994932 -266.443714)
		(width 0.0889)
		(layer "B.Cu")
		(net "TP_CPU0_SPARE8")
	)
	(segment
		(start 371.250464 -266.45235)
		(end 371.235732 -266.443714)
		(width 0.0889)
		(layer "B.Cu")
		(net "TP_CPU0_SPARE8")
	)
	(segment
		(start 386.030216 -266.285472)
		(end 385.90474 -266.410948)
		(width 0.12954)
		(layer "B.Cu")
		(net "TP_CPU0_SPARE8")
	)
	(segment
		(start 376.889264 -266.45235)
		(end 376.874532 -266.443714)
		(width 0.0889)
		(layer "B.Cu")
		(net "TP_CPU0_SPARE8")
	)
	(segment
		(start 383.467864 -266.452604)
		(end 383.453132 -266.443968)
		(width 0.0889)
		(layer "B.Cu")
		(net "TP_CPU0_SPARE8")
	)
	(segment
		(start 367.396014 -265.638534)
		(end 367.385092 -265.644884)
		(width 0.0889)
		(layer "B.Cu")
		(net "TP_CPU0_SPARE8")
	)
	(segment
		(start 370.310664 -266.45235)
		(end 370.295932 -266.443714)
		(width 0.0889)
		(layer "B.Cu")
		(net "TP_CPU0_SPARE8")
	)
	(segment
		(start 373.130064 -266.45235)
		(end 373.115332 -266.443714)
		(width 0.0889)
		(layer "B.Cu")
		(net "TP_CPU0_SPARE8")
	)
	(segment
		(start 366.466374 -265.632692)
		(end 366.45596 -265.638788)
		(width 0.0889)
		(layer "B.Cu")
		(net "TP_CPU0_SPARE8")
	)
	(segment
		(start 372.190264 -266.45235)
		(end 372.175532 -266.443714)
		(width 0.0889)
		(layer "B.Cu")
		(net "TP_CPU0_SPARE8")
	)
	(segment
		(start 364.959138 -265.37158)
		(end 365.016542 -265.314176)
		(width 0.0889)
		(layer "B.Cu")
		(net "TP_CPU0_SPARE8")
	)
	(segment
		(start 383.84226 -266.45235)
		(end 383.831338 -266.4587)
		(width 0.0889)
		(layer "B.Cu")
		(net "TP_CPU0_SPARE8")
	)
	(segment
		(start 382.528064 -266.45235)
		(end 382.513332 -266.443714)
		(width 0.0889)
		(layer "B.Cu")
		(net "TP_CPU0_SPARE8")
	)
	(segment
		(start 365.516414 -265.638534)
		(end 365.505492 -265.644884)
		(width 0.0889)
		(layer "B.Cu")
		(net "TP_CPU0_SPARE8")
	)
	(segment
		(start 385.90474 -266.410948)
		(end 385.704842 -266.610846)
		(width 0.0889)
		(layer "B.Cu")
		(net "TP_CPU0_SPARE8")
	)
	(segment
		(start 368.431064 -266.45235)
		(end 368.41684 -266.444222)
		(width 0.0889)
		(layer "B.Cu")
		(net "TP_CPU0_SPARE8")
	)
	(segment
		(start 377.829064 -266.45235)
		(end 377.814332 -266.443714)
		(width 0.0889)
		(layer "B.Cu")
		(net "TP_CPU0_SPARE8")
	)
	(segment
		(start 375.949464 -266.45235)
		(end 375.934732 -266.443714)
		(width 0.0889)
		(layer "B.Cu")
		(net "TP_CPU0_SPARE8")
	)
	(segment
		(start 379.708664 -266.45235)
		(end 379.693932 -266.443714)
		(width 0.0889)
		(layer "B.Cu")
		(net "TP_CPU0_SPARE8")
	)
	(segment
		(start 368.243612 -266.128246)
		(end 368.243612 -266.106148)
		(width 0.0889)
		(layer "B.Cu")
		(net "TP_CPU0_SPARE8")
	)
	(segment
		(start 384.606546 -266.610846)
		(end 384.372358 -266.376658)
		(width 0.0889)
		(layer "B.Cu")
		(net "TP_CPU0_SPARE8")
	)
	(segment
		(start 367.410746 -265.629898)
		(end 367.396014 -265.638534)
		(width 0.0889)
		(layer "B.Cu")
		(net "TP_CPU0_SPARE8")
	)
	(segment
		(start 382.538986 -266.4587)
		(end 382.528064 -266.45235)
		(width 0.0889)
		(layer "B.Cu")
		(net "TP_CPU0_SPARE8")
	)
	(segment
		(start 365.526828 -265.632438)
		(end 365.516414 -265.638534)
		(width 0.0889)
		(layer "B.Cu")
		(net "TP_CPU0_SPARE8")
	)
	(segment
		(start 365.016542 -265.314176)
		(end 365.329216 -265.314176)
		(width 0.0889)
		(layer "B.Cu")
		(net "TP_CPU0_SPARE8")
	)
	(arc
		(start 368.41684 -266.444222)
		(mid 368.289797 -266.308406)
		(end 368.243612 -266.128246)
		(width 0.0889)
		(layer "B.Cu")
		(net "TP_CPU0_SPARE8")
	)
	(arc
		(start 376.874532 -266.443714)
		(mid 376.598057 -266.376394)
		(end 376.32386 -266.45235)
		(width 0.0889)
		(layer "B.Cu")
		(net "TP_CPU0_SPARE8")
	)
	(arc
		(start 379.693932 -266.443714)
		(mid 379.417457 -266.376394)
		(end 379.14326 -266.45235)
		(width 0.0889)
		(layer "B.Cu")
		(net "TP_CPU0_SPARE8")
	)
	(arc
		(start 373.115332 -266.443714)
		(mid 372.838857 -266.376394)
		(end 372.56466 -266.45235)
		(width 0.0889)
		(layer "B.Cu")
		(net "TP_CPU0_SPARE8")
	)
	(arc
		(start 381.96266 -266.45235)
		(mid 381.775462 -266.502527)
		(end 381.588264 -266.45235)
		(width 0.0889)
		(layer "B.Cu")
		(net "TP_CPU0_SPARE8")
	)
	(arc
		(start 383.453132 -266.443968)
		(mid 383.176657 -266.376648)
		(end 382.90246 -266.452604)
		(width 0.0889)
		(layer "B.Cu")
		(net "TP_CPU0_SPARE8")
	)
	(arc
		(start 365.142018 -265.638788)
		(mid 365.020264 -265.525943)
		(end 364.959138 -265.37158)
		(width 0.0889)
		(layer "B.Cu")
		(net "TP_CPU0_SPARE8")
	)
	(arc
		(start 368.243612 -266.106148)
		(mid 368.162701 -265.83602)
		(end 367.961418 -265.638534)
		(width 0.0889)
		(layer "B.Cu")
		(net "TP_CPU0_SPARE8")
	)
	(arc
		(start 374.994932 -266.443714)
		(mid 374.718457 -266.376394)
		(end 374.44426 -266.45235)
		(width 0.0889)
		(layer "B.Cu")
		(net "TP_CPU0_SPARE8")
	)
	(arc
		(start 375.38406 -266.45235)
		(mid 375.196862 -266.502527)
		(end 375.009664 -266.45235)
		(width 0.0889)
		(layer "B.Cu")
		(net "TP_CPU0_SPARE8")
	)
	(arc
		(start 380.648464 -266.45235)
		(mid 380.365762 -266.376574)
		(end 380.08306 -266.45235)
		(width 0.0889)
		(layer "B.Cu")
		(net "TP_CPU0_SPARE8")
	)
	(arc
		(start 384.124962 -266.376658)
		(mid 383.978618 -266.395866)
		(end 383.84226 -266.45235)
		(width 0.0889)
		(layer "B.Cu")
		(net "TP_CPU0_SPARE8")
	)
	(arc
		(start 374.069864 -266.45235)
		(mid 373.787162 -266.376574)
		(end 373.50446 -266.45235)
		(width 0.0889)
		(layer "B.Cu")
		(net "TP_CPU0_SPARE8")
	)
	(arc
		(start 367.961418 -265.638534)
		(mid 367.687189 -265.562609)
		(end 367.410746 -265.629898)
		(width 0.0889)
		(layer "B.Cu")
		(net "TP_CPU0_SPARE8")
	)
	(arc
		(start 366.45596 -265.638788)
		(mid 366.275016 -265.688845)
		(end 366.092486 -265.644884)
		(width 0.0889)
		(layer "B.Cu")
		(net "TP_CPU0_SPARE8")
	)
	(arc
		(start 372.175532 -266.443714)
		(mid 371.899057 -266.376394)
		(end 371.62486 -266.45235)
		(width 0.0889)
		(layer "B.Cu")
		(net "TP_CPU0_SPARE8")
	)
	(arc
		(start 382.90246 -266.452604)
		(mid 382.721516 -266.502695)
		(end 382.538986 -266.4587)
		(width 0.0889)
		(layer "B.Cu")
		(net "TP_CPU0_SPARE8")
	)
	(arc
		(start 383.831338 -266.4587)
		(mid 383.648808 -266.502724)
		(end 383.467864 -266.452604)
		(width 0.0889)
		(layer "B.Cu")
		(net "TP_CPU0_SPARE8")
	)
	(arc
		(start 373.50446 -266.45235)
		(mid 373.317262 -266.502527)
		(end 373.130064 -266.45235)
		(width 0.0889)
		(layer "B.Cu")
		(net "TP_CPU0_SPARE8")
	)
	(arc
		(start 377.814332 -266.443714)
		(mid 377.537857 -266.376394)
		(end 377.26366 -266.45235)
		(width 0.0889)
		(layer "B.Cu")
		(net "TP_CPU0_SPARE8")
	)
	(arc
		(start 379.14326 -266.45235)
		(mid 378.956062 -266.502527)
		(end 378.768864 -266.45235)
		(width 0.0889)
		(layer "B.Cu")
		(net "TP_CPU0_SPARE8")
	)
	(arc
		(start 372.56466 -266.45235)
		(mid 372.377462 -266.502527)
		(end 372.190264 -266.45235)
		(width 0.0889)
		(layer "B.Cu")
		(net "TP_CPU0_SPARE8")
	)
	(arc
		(start 366.081564 -265.638534)
		(mid 365.805005 -265.562825)
		(end 365.526828 -265.632438)
		(width 0.0889)
		(layer "B.Cu")
		(net "TP_CPU0_SPARE8")
	)
	(arc
		(start 374.44426 -266.45235)
		(mid 374.257062 -266.502527)
		(end 374.069864 -266.45235)
		(width 0.0889)
		(layer "B.Cu")
		(net "TP_CPU0_SPARE8")
	)
	(arc
		(start 378.20346 -266.45235)
		(mid 378.016262 -266.502527)
		(end 377.829064 -266.45235)
		(width 0.0889)
		(layer "B.Cu")
		(net "TP_CPU0_SPARE8")
	)
	(arc
		(start 380.08306 -266.45235)
		(mid 379.895862 -266.502527)
		(end 379.708664 -266.45235)
		(width 0.0889)
		(layer "B.Cu")
		(net "TP_CPU0_SPARE8")
	)
	(arc
		(start 378.754132 -266.443714)
		(mid 378.477657 -266.376394)
		(end 378.20346 -266.45235)
		(width 0.0889)
		(layer "B.Cu")
		(net "TP_CPU0_SPARE8")
	)
	(arc
		(start 381.02286 -266.45235)
		(mid 380.835662 -266.502527)
		(end 380.648464 -266.45235)
		(width 0.0889)
		(layer "B.Cu")
		(net "TP_CPU0_SPARE8")
	)
	(arc
		(start 365.505492 -265.644884)
		(mid 365.322962 -265.688878)
		(end 365.142018 -265.638788)
		(width 0.0889)
		(layer "B.Cu")
		(net "TP_CPU0_SPARE8")
	)
	(arc
		(start 371.62486 -266.45235)
		(mid 371.437662 -266.502527)
		(end 371.250464 -266.45235)
		(width 0.0889)
		(layer "B.Cu")
		(net "TP_CPU0_SPARE8")
	)
	(arc
		(start 369.74526 -266.45235)
		(mid 369.558062 -266.502527)
		(end 369.370864 -266.45235)
		(width 0.0889)
		(layer "B.Cu")
		(net "TP_CPU0_SPARE8")
	)
	(arc
		(start 375.934732 -266.443714)
		(mid 375.658257 -266.376394)
		(end 375.38406 -266.45235)
		(width 0.0889)
		(layer "B.Cu")
		(net "TP_CPU0_SPARE8")
	)
	(arc
		(start 368.80546 -266.45235)
		(mid 368.618262 -266.502527)
		(end 368.431064 -266.45235)
		(width 0.0889)
		(layer "B.Cu")
		(net "TP_CPU0_SPARE8")
	)
	(arc
		(start 370.68506 -266.45235)
		(mid 370.497862 -266.502527)
		(end 370.310664 -266.45235)
		(width 0.0889)
		(layer "B.Cu")
		(net "TP_CPU0_SPARE8")
	)
	(arc
		(start 370.295932 -266.443714)
		(mid 370.019457 -266.376394)
		(end 369.74526 -266.45235)
		(width 0.0889)
		(layer "B.Cu")
		(net "TP_CPU0_SPARE8")
	)
	(arc
		(start 377.26366 -266.45235)
		(mid 377.076462 -266.502527)
		(end 376.889264 -266.45235)
		(width 0.0889)
		(layer "B.Cu")
		(net "TP_CPU0_SPARE8")
	)
	(arc
		(start 367.385092 -265.644884)
		(mid 367.202562 -265.688878)
		(end 367.021618 -265.638788)
		(width 0.0889)
		(layer "B.Cu")
		(net "TP_CPU0_SPARE8")
	)
	(arc
		(start 367.021618 -265.638788)
		(mid 366.744805 -265.562952)
		(end 366.466374 -265.632692)
		(width 0.0889)
		(layer "B.Cu")
		(net "TP_CPU0_SPARE8")
	)
	(arc
		(start 376.32386 -266.45235)
		(mid 376.136662 -266.502527)
		(end 375.949464 -266.45235)
		(width 0.0889)
		(layer "B.Cu")
		(net "TP_CPU0_SPARE8")
	)
	(arc
		(start 382.513332 -266.443714)
		(mid 382.236857 -266.376394)
		(end 381.96266 -266.45235)
		(width 0.0889)
		(layer "B.Cu")
		(net "TP_CPU0_SPARE8")
	)
	(arc
		(start 381.588264 -266.45235)
		(mid 381.305562 -266.376574)
		(end 381.02286 -266.45235)
		(width 0.0889)
		(layer "B.Cu")
		(net "TP_CPU0_SPARE8")
	)
	(arc
		(start 371.235732 -266.443714)
		(mid 370.959257 -266.376394)
		(end 370.68506 -266.45235)
		(width 0.0889)
		(layer "B.Cu")
		(net "TP_CPU0_SPARE8")
	)
	(arc
		(start 369.370864 -266.45235)
		(mid 369.088162 -266.376574)
		(end 368.80546 -266.45235)
		(width 0.0889)
		(layer "B.Cu")
		(net "TP_CPU0_SPARE8")
	)
	(segment
		(start 365.799116 -263.96442)
		(end 365.798862 -263.964674)
		(width 0.12954)
		(layer "F.Cu")
		(net "TP_CPU0_SPARE7")
	)
	(segment
		(start 365.798862 -263.964674)
		(end 365.798862 -264.50036)
		(width 0.12954)
		(layer "F.Cu")
		(net "TP_CPU0_SPARE7")
	)
	(via
		(at 365.798862 -264.50036)
		(size 0.4572)
		(drill 0.2032)
		(layers "F.Cu" "B.Cu")
		(net "TP_CPU0_SPARE7")
	)
	(segment
		(start 369.448334 -247.992392)
		(end 369.44808 -247.992138)
		(width 0.12954)
		(layer "F.Cu")
		(net "TP_CPU0_SPARE6")
	)
	(segment
		(start 369.448334 -248.528078)
		(end 369.448334 -247.992392)
		(width 0.12954)
		(layer "F.Cu")
		(net "TP_CPU0_SPARE6")
	)
	(via
		(at 369.44808 -247.992138)
		(size 0.4572)
		(drill 0.2032)
		(layers "F.Cu" "B.Cu")
		(net "TP_CPU0_SPARE6")
	)
	(via
		(at 389.155178 -246.877078)
		(size 0.6604)
		(drill 0.3302)
		(layers "F.Cu" "B.Cu")
		(net "TP_CPU0_SPARE6")
	)
	(segment
		(start 373.960136 -247.66778)
		(end 373.949722 -247.673876)
		(width 0.0889)
		(layer "B.Cu")
		(net "TP_CPU0_SPARE6")
	)
	(segment
		(start 372.080282 -247.66778)
		(end 372.06555 -247.676416)
		(width 0.0889)
		(layer "B.Cu")
		(net "TP_CPU0_SPARE6")
	)
	(segment
		(start 373.020082 -247.66778)
		(end 373.00535 -247.676416)
		(width 0.0889)
		(layer "B.Cu")
		(net "TP_CPU0_SPARE6")
	)
	(segment
		(start 371.140482 -247.66778)
		(end 371.12575 -247.676416)
		(width 0.0889)
		(layer "B.Cu")
		(net "TP_CPU0_SPARE6")
	)
	(segment
		(start 370.200682 -247.66778)
		(end 370.18595 -247.676416)
		(width 0.0889)
		(layer "B.Cu")
		(net "TP_CPU0_SPARE6")
	)
	(segment
		(start 380.538736 -247.66778)
		(end 380.528322 -247.673876)
		(width 0.0889)
		(layer "B.Cu")
		(net "TP_CPU0_SPARE6")
	)
	(segment
		(start 389.155178 -246.877078)
		(end 388.441438 -247.590818)
		(width 0.12954)
		(layer "B.Cu")
		(net "TP_CPU0_SPARE6")
	)
	(segment
		(start 383.263902 -247.590818)
		(end 383.111248 -247.743472)
		(width 0.12954)
		(layer "B.Cu")
		(net "TP_CPU0_SPARE6")
	)
	(segment
		(start 379.043946 -247.673876)
		(end 379.033532 -247.66778)
		(width 0.0889)
		(layer "B.Cu")
		(net "TP_CPU0_SPARE6")
	)
	(segment
		(start 375.839482 -247.66778)
		(end 375.82475 -247.676416)
		(width 0.0889)
		(layer "B.Cu")
		(net "TP_CPU0_SPARE6")
	)
	(segment
		(start 378.659136 -247.66778)
		(end 378.648722 -247.673876)
		(width 0.0889)
		(layer "B.Cu")
		(net "TP_CPU0_SPARE6")
	)
	(segment
		(start 381.423418 -247.743472)
		(end 381.19558 -247.743472)
		(width 0.0889)
		(layer "B.Cu")
		(net "TP_CPU0_SPARE6")
	)
	(segment
		(start 374.344946 -247.673876)
		(end 374.334532 -247.66778)
		(width 0.0889)
		(layer "B.Cu")
		(net "TP_CPU0_SPARE6")
	)
	(segment
		(start 376.779282 -247.66778)
		(end 376.76455 -247.676416)
		(width 0.0889)
		(layer "B.Cu")
		(net "TP_CPU0_SPARE6")
	)
	(segment
		(start 369.957096 -247.742456)
		(end 369.44808 -247.992138)
		(width 0.0889)
		(layer "B.Cu")
		(net "TP_CPU0_SPARE6")
	)
	(segment
		(start 388.441438 -247.590818)
		(end 383.263902 -247.590818)
		(width 0.12954)
		(layer "B.Cu")
		(net "TP_CPU0_SPARE6")
	)
	(segment
		(start 383.111248 -247.743472)
		(end 381.423418 -247.743472)
		(width 0.12954)
		(layer "B.Cu")
		(net "TP_CPU0_SPARE6")
	)
	(segment
		(start 377.719082 -247.66778)
		(end 377.70435 -247.676416)
		(width 0.0889)
		(layer "B.Cu")
		(net "TP_CPU0_SPARE6")
	)
	(arc
		(start 372.06555 -247.676416)
		(mid 371.789075 -247.743736)
		(end 371.514878 -247.66778)
		(width 0.0889)
		(layer "B.Cu")
		(net "TP_CPU0_SPARE6")
	)
	(arc
		(start 377.153678 -247.66778)
		(mid 376.96648 -247.617637)
		(end 376.779282 -247.66778)
		(width 0.0889)
		(layer "B.Cu")
		(net "TP_CPU0_SPARE6")
	)
	(arc
		(start 374.334532 -247.66778)
		(mid 374.147334 -247.617637)
		(end 373.960136 -247.66778)
		(width 0.0889)
		(layer "B.Cu")
		(net "TP_CPU0_SPARE6")
	)
	(arc
		(start 379.598682 -247.66778)
		(mid 379.322123 -247.743523)
		(end 379.043946 -247.673876)
		(width 0.0889)
		(layer "B.Cu")
		(net "TP_CPU0_SPARE6")
	)
	(arc
		(start 380.528322 -247.673876)
		(mid 380.24989 -247.743722)
		(end 379.973078 -247.66778)
		(width 0.0889)
		(layer "B.Cu")
		(net "TP_CPU0_SPARE6")
	)
	(arc
		(start 379.973078 -247.66778)
		(mid 379.78588 -247.617637)
		(end 379.598682 -247.66778)
		(width 0.0889)
		(layer "B.Cu")
		(net "TP_CPU0_SPARE6")
	)
	(arc
		(start 381.19558 -247.743472)
		(mid 381.049372 -247.724223)
		(end 380.913132 -247.66778)
		(width 0.0889)
		(layer "B.Cu")
		(net "TP_CPU0_SPARE6")
	)
	(arc
		(start 377.70435 -247.676416)
		(mid 377.427875 -247.743736)
		(end 377.153678 -247.66778)
		(width 0.0889)
		(layer "B.Cu")
		(net "TP_CPU0_SPARE6")
	)
	(arc
		(start 380.913132 -247.66778)
		(mid 380.725934 -247.617637)
		(end 380.538736 -247.66778)
		(width 0.0889)
		(layer "B.Cu")
		(net "TP_CPU0_SPARE6")
	)
	(arc
		(start 373.394478 -247.66778)
		(mid 373.20728 -247.617637)
		(end 373.020082 -247.66778)
		(width 0.0889)
		(layer "B.Cu")
		(net "TP_CPU0_SPARE6")
	)
	(arc
		(start 375.274078 -247.66778)
		(mid 375.08688 -247.617637)
		(end 374.899682 -247.66778)
		(width 0.0889)
		(layer "B.Cu")
		(net "TP_CPU0_SPARE6")
	)
	(arc
		(start 376.213878 -247.66778)
		(mid 376.02668 -247.617637)
		(end 375.839482 -247.66778)
		(width 0.0889)
		(layer "B.Cu")
		(net "TP_CPU0_SPARE6")
	)
	(arc
		(start 371.514878 -247.66778)
		(mid 371.32768 -247.617637)
		(end 371.140482 -247.66778)
		(width 0.0889)
		(layer "B.Cu")
		(net "TP_CPU0_SPARE6")
	)
	(arc
		(start 371.12575 -247.676416)
		(mid 370.849275 -247.743736)
		(end 370.575078 -247.66778)
		(width 0.0889)
		(layer "B.Cu")
		(net "TP_CPU0_SPARE6")
	)
	(arc
		(start 378.093478 -247.66778)
		(mid 377.90628 -247.617637)
		(end 377.719082 -247.66778)
		(width 0.0889)
		(layer "B.Cu")
		(net "TP_CPU0_SPARE6")
	)
	(arc
		(start 370.18595 -247.676416)
		(mid 370.075041 -247.721628)
		(end 369.957096 -247.742456)
		(width 0.0889)
		(layer "B.Cu")
		(net "TP_CPU0_SPARE6")
	)
	(arc
		(start 370.575078 -247.66778)
		(mid 370.38788 -247.617637)
		(end 370.200682 -247.66778)
		(width 0.0889)
		(layer "B.Cu")
		(net "TP_CPU0_SPARE6")
	)
	(arc
		(start 372.454678 -247.66778)
		(mid 372.26748 -247.617637)
		(end 372.080282 -247.66778)
		(width 0.0889)
		(layer "B.Cu")
		(net "TP_CPU0_SPARE6")
	)
	(arc
		(start 376.76455 -247.676416)
		(mid 376.488075 -247.743736)
		(end 376.213878 -247.66778)
		(width 0.0889)
		(layer "B.Cu")
		(net "TP_CPU0_SPARE6")
	)
	(arc
		(start 373.00535 -247.676416)
		(mid 372.728875 -247.743736)
		(end 372.454678 -247.66778)
		(width 0.0889)
		(layer "B.Cu")
		(net "TP_CPU0_SPARE6")
	)
	(arc
		(start 375.82475 -247.676416)
		(mid 375.548275 -247.743736)
		(end 375.274078 -247.66778)
		(width 0.0889)
		(layer "B.Cu")
		(net "TP_CPU0_SPARE6")
	)
	(arc
		(start 373.949722 -247.673876)
		(mid 373.67129 -247.743722)
		(end 373.394478 -247.66778)
		(width 0.0889)
		(layer "B.Cu")
		(net "TP_CPU0_SPARE6")
	)
	(arc
		(start 378.648722 -247.673876)
		(mid 378.37029 -247.743722)
		(end 378.093478 -247.66778)
		(width 0.0889)
		(layer "B.Cu")
		(net "TP_CPU0_SPARE6")
	)
	(arc
		(start 374.899682 -247.66778)
		(mid 374.623123 -247.743523)
		(end 374.344946 -247.673876)
		(width 0.0889)
		(layer "B.Cu")
		(net "TP_CPU0_SPARE6")
	)
	(arc
		(start 379.033532 -247.66778)
		(mid 378.846334 -247.617637)
		(end 378.659136 -247.66778)
		(width 0.0889)
		(layer "B.Cu")
		(net "TP_CPU0_SPARE6")
	)
	(segment
		(start 349.822516 -257.988816)
		(end 349.822262 -257.98907)
		(width 0.12954)
		(layer "F.Cu")
		(net "TP_CPU0_SPARE5")
	)
	(segment
		(start 349.822516 -257.45313)
		(end 349.822516 -257.988816)
		(width 0.12954)
		(layer "F.Cu")
		(net "TP_CPU0_SPARE5")
	)
	(via
		(at 324.806056 -257.964686)
		(size 0.6604)
		(drill 0.3302)
		(layers "F.Cu" "B.Cu")
		(net "TP_CPU0_SPARE5")
	)
	(via
		(at 349.822262 -257.98907)
		(size 0.4572)
		(drill 0.2032)
		(layers "F.Cu" "B.Cu")
		(net "TP_CPU0_SPARE5")
	)
	(segment
		(start 344.941398 -257.570732)
		(end 344.930984 -257.576828)
		(width 0.12954)
		(layer "B.Cu")
		(net "TP_CPU0_SPARE5")
	)
	(segment
		(start 349.822262 -257.98907)
		(end 349.339916 -257.723894)
		(width 0.12954)
		(layer "B.Cu")
		(net "TP_CPU0_SPARE5")
	)
	(segment
		(start 343.061544 -257.570732)
		(end 343.046812 -257.579368)
		(width 0.12954)
		(layer "B.Cu")
		(net "TP_CPU0_SPARE5")
	)
	(segment
		(start 344.001344 -257.570732)
		(end 343.986612 -257.579368)
		(width 0.12954)
		(layer "B.Cu")
		(net "TP_CPU0_SPARE5")
	)
	(segment
		(start 340.627208 -257.576828)
		(end 340.616794 -257.570732)
		(width 0.12954)
		(layer "B.Cu")
		(net "TP_CPU0_SPARE5")
	)
	(segment
		(start 337.807554 -257.576828)
		(end 337.79714 -257.570732)
		(width 0.12954)
		(layer "B.Cu")
		(net "TP_CPU0_SPARE5")
	)
	(segment
		(start 335.303622 -257.570732)
		(end 335.014316 -257.281426)
		(width 0.12954)
		(layer "B.Cu")
		(net "TP_CPU0_SPARE5")
	)
	(segment
		(start 335.014316 -257.281426)
		(end 331.847444 -257.281426)
		(width 0.12954)
		(layer "B.Cu")
		(net "TP_CPU0_SPARE5")
	)
	(segment
		(start 337.79714 -257.570732)
		(end 335.303622 -257.570732)
		(width 0.12954)
		(layer "B.Cu")
		(net "TP_CPU0_SPARE5")
	)
	(segment
		(start 331.164184 -257.964686)
		(end 324.806056 -257.964686)
		(width 0.12954)
		(layer "B.Cu")
		(net "TP_CPU0_SPARE5")
	)
	(segment
		(start 346.820998 -257.570732)
		(end 346.810584 -257.576828)
		(width 0.12954)
		(layer "B.Cu")
		(net "TP_CPU0_SPARE5")
	)
	(segment
		(start 342.121744 -257.570732)
		(end 342.107012 -257.579368)
		(width 0.12954)
		(layer "B.Cu")
		(net "TP_CPU0_SPARE5")
	)
	(segment
		(start 340.242398 -257.570732)
		(end 340.231984 -257.576828)
		(width 0.12954)
		(layer "B.Cu")
		(net "TP_CPU0_SPARE5")
	)
	(segment
		(start 349.339916 -257.723894)
		(end 349.07474 -257.570732)
		(width 0.12954)
		(layer "B.Cu")
		(net "TP_CPU0_SPARE5")
	)
	(segment
		(start 348.700344 -257.570732)
		(end 348.685612 -257.579368)
		(width 0.12954)
		(layer "B.Cu")
		(net "TP_CPU0_SPARE5")
	)
	(segment
		(start 345.326208 -257.576828)
		(end 345.315794 -257.570732)
		(width 0.12954)
		(layer "B.Cu")
		(net "TP_CPU0_SPARE5")
	)
	(segment
		(start 331.847444 -257.281426)
		(end 331.164184 -257.964686)
		(width 0.12954)
		(layer "B.Cu")
		(net "TP_CPU0_SPARE5")
	)
	(segment
		(start 347.205808 -257.576828)
		(end 347.195394 -257.570732)
		(width 0.12954)
		(layer "B.Cu")
		(net "TP_CPU0_SPARE5")
	)
	(arc
		(start 346.810584 -257.576828)
		(mid 346.532152 -257.646674)
		(end 346.25534 -257.570732)
		(width 0.12954)
		(layer "B.Cu")
		(net "TP_CPU0_SPARE5")
	)
	(arc
		(start 344.37574 -257.570732)
		(mid 344.188542 -257.520589)
		(end 344.001344 -257.570732)
		(width 0.12954)
		(layer "B.Cu")
		(net "TP_CPU0_SPARE5")
	)
	(arc
		(start 343.046812 -257.579368)
		(mid 342.770337 -257.646688)
		(end 342.49614 -257.570732)
		(width 0.12954)
		(layer "B.Cu")
		(net "TP_CPU0_SPARE5")
	)
	(arc
		(start 348.685612 -257.579368)
		(mid 348.409137 -257.646688)
		(end 348.13494 -257.570732)
		(width 0.12954)
		(layer "B.Cu")
		(net "TP_CPU0_SPARE5")
	)
	(arc
		(start 339.302344 -257.570732)
		(mid 339.046255 -257.645996)
		(end 338.784184 -257.59537)
		(width 0.12954)
		(layer "B.Cu")
		(net "TP_CPU0_SPARE5")
	)
	(arc
		(start 347.195394 -257.570732)
		(mid 347.008196 -257.520589)
		(end 346.820998 -257.570732)
		(width 0.12954)
		(layer "B.Cu")
		(net "TP_CPU0_SPARE5")
	)
	(arc
		(start 342.107012 -257.579368)
		(mid 341.830537 -257.646688)
		(end 341.55634 -257.570732)
		(width 0.12954)
		(layer "B.Cu")
		(net "TP_CPU0_SPARE5")
	)
	(arc
		(start 339.67674 -257.570732)
		(mid 339.489542 -257.520589)
		(end 339.302344 -257.570732)
		(width 0.12954)
		(layer "B.Cu")
		(net "TP_CPU0_SPARE5")
	)
	(arc
		(start 347.760544 -257.570732)
		(mid 347.483985 -257.646475)
		(end 347.205808 -257.576828)
		(width 0.12954)
		(layer "B.Cu")
		(net "TP_CPU0_SPARE5")
	)
	(arc
		(start 338.31784 -257.593338)
		(mid 338.060787 -257.643937)
		(end 337.807554 -257.576828)
		(width 0.12954)
		(layer "B.Cu")
		(net "TP_CPU0_SPARE5")
	)
	(arc
		(start 343.986612 -257.579368)
		(mid 343.710137 -257.646688)
		(end 343.43594 -257.570732)
		(width 0.12954)
		(layer "B.Cu")
		(net "TP_CPU0_SPARE5")
	)
	(arc
		(start 343.43594 -257.570732)
		(mid 343.248742 -257.520589)
		(end 343.061544 -257.570732)
		(width 0.12954)
		(layer "B.Cu")
		(net "TP_CPU0_SPARE5")
	)
	(arc
		(start 338.784184 -257.59537)
		(mid 338.551228 -257.543997)
		(end 338.31784 -257.593338)
		(width 0.12954)
		(layer "B.Cu")
		(net "TP_CPU0_SPARE5")
	)
	(arc
		(start 345.315794 -257.570732)
		(mid 345.128596 -257.520589)
		(end 344.941398 -257.570732)
		(width 0.12954)
		(layer "B.Cu")
		(net "TP_CPU0_SPARE5")
	)
	(arc
		(start 342.49614 -257.570732)
		(mid 342.308942 -257.520589)
		(end 342.121744 -257.570732)
		(width 0.12954)
		(layer "B.Cu")
		(net "TP_CPU0_SPARE5")
	)
	(arc
		(start 348.13494 -257.570732)
		(mid 347.947742 -257.520589)
		(end 347.760544 -257.570732)
		(width 0.12954)
		(layer "B.Cu")
		(net "TP_CPU0_SPARE5")
	)
	(arc
		(start 341.55634 -257.570732)
		(mid 341.369142 -257.520589)
		(end 341.181944 -257.570732)
		(width 0.12954)
		(layer "B.Cu")
		(net "TP_CPU0_SPARE5")
	)
	(arc
		(start 340.616794 -257.570732)
		(mid 340.429596 -257.520589)
		(end 340.242398 -257.570732)
		(width 0.12954)
		(layer "B.Cu")
		(net "TP_CPU0_SPARE5")
	)
	(arc
		(start 349.07474 -257.570732)
		(mid 348.887542 -257.520589)
		(end 348.700344 -257.570732)
		(width 0.12954)
		(layer "B.Cu")
		(net "TP_CPU0_SPARE5")
	)
	(arc
		(start 341.181944 -257.570732)
		(mid 340.905385 -257.646475)
		(end 340.627208 -257.576828)
		(width 0.12954)
		(layer "B.Cu")
		(net "TP_CPU0_SPARE5")
	)
	(arc
		(start 344.930984 -257.576828)
		(mid 344.652552 -257.646674)
		(end 344.37574 -257.570732)
		(width 0.12954)
		(layer "B.Cu")
		(net "TP_CPU0_SPARE5")
	)
	(arc
		(start 345.880944 -257.570732)
		(mid 345.604385 -257.646475)
		(end 345.326208 -257.576828)
		(width 0.12954)
		(layer "B.Cu")
		(net "TP_CPU0_SPARE5")
	)
	(arc
		(start 340.231984 -257.576828)
		(mid 339.953552 -257.646674)
		(end 339.67674 -257.570732)
		(width 0.12954)
		(layer "B.Cu")
		(net "TP_CPU0_SPARE5")
	)
	(arc
		(start 346.25534 -257.570732)
		(mid 346.068142 -257.520589)
		(end 345.880944 -257.570732)
		(width 0.12954)
		(layer "B.Cu")
		(net "TP_CPU0_SPARE5")
	)
	(segment
		(start 370.498116 -272.103342)
		(end 370.497862 -272.639282)
		(width 0.12954)
		(layer "F.Cu")
		(net "TP_CPU0_SPARE4")
	)
	(via
		(at 370.497862 -272.639282)
		(size 0.4572)
		(drill 0.2032)
		(layers "F.Cu" "B.Cu")
		(net "TP_CPU0_SPARE4")
	)
	(segment
		(start 353.111562 -278.336502)
		(end 353.111562 -277.800562)
		(width 0.12954)
		(layer "F.Cu")
		(net "TP_CPU0_SPARE13")
	)
	(via
		(at 353.111562 -278.336502)
		(size 0.4572)
		(drill 0.2032)
		(layers "F.Cu" "B.Cu")
		(net "TP_CPU0_SPARE13")
	)
	(segment
		(start 365.799116 -272.103342)
		(end 365.798862 -272.639282)
		(width 0.12954)
		(layer "F.Cu")
		(net "TP_CPU0_SPARE12")
	)
	(via
		(at 365.798862 -272.639282)
		(size 0.4572)
		(drill 0.2032)
		(layers "F.Cu" "B.Cu")
		(net "TP_CPU0_SPARE12")
	)
	(segment
		(start 362.509562 -271.289272)
		(end 362.509816 -271.825212)
		(width 0.12954)
		(layer "F.Cu")
		(net "TP_CPU0_SPARE11")
	)
	(via
		(at 362.509816 -271.825212)
		(size 0.4572)
		(drill 0.2032)
		(layers "F.Cu" "B.Cu")
		(net "TP_CPU0_SPARE11")
	)
	(segment
		(start 363.919262 -263.964674)
		(end 363.919262 -264.50036)
		(width 0.12954)
		(layer "F.Cu")
		(net "TP_CPU0_SPARE10")
	)
	(segment
		(start 363.919516 -263.96442)
		(end 363.919262 -263.964674)
		(width 0.12954)
		(layer "F.Cu")
		(net "TP_CPU0_SPARE10")
	)
	(via
		(at 363.919262 -264.50036)
		(size 0.4572)
		(drill 0.2032)
		(layers "F.Cu" "B.Cu")
		(net "TP_CPU0_SPARE10")
	)
	(segment
		(start 365.21898 -232.528618)
		(end 365.219234 -232.528364)
		(width 0.12954)
		(layer "F.Cu")
		(net "TP_CPU0_PWRBTN_N")
	)
	(segment
		(start 365.21898 -233.064304)
		(end 365.21898 -232.528618)
		(width 0.12954)
		(layer "F.Cu")
		(net "TP_CPU0_PWRBTN_N")
	)
	(via
		(at 365.219234 -232.528364)
		(size 0.4572)
		(drill 0.2032)
		(layers "F.Cu" "B.Cu")
		(net "TP_CPU0_PWRBTN_N")
	)
	(via
		(at 386.214112 -233.152696)
		(size 0.6604)
		(drill 0.3302)
		(layers "F.Cu" "B.Cu")
		(net "TP_CPU0_PWRBTN_N")
	)
	(segment
		(start 366.360964 -232.844086)
		(end 366.346232 -232.852722)
		(width 0.0889)
		(layer "B.Cu")
		(net "TP_CPU0_PWRBTN_N")
	)
	(segment
		(start 384.80873 -232.491788)
		(end 384.517138 -232.491788)
		(width 0.12954)
		(layer "B.Cu")
		(net "TP_CPU0_PWRBTN_N")
	)
	(segment
		(start 374.429782 -232.852722)
		(end 374.419368 -232.846626)
		(width 0.0889)
		(layer "B.Cu")
		(net "TP_CPU0_PWRBTN_N")
	)
	(segment
		(start 367.296446 -232.846626)
		(end 367.286032 -232.852722)
		(width 0.0889)
		(layer "B.Cu")
		(net "TP_CPU0_PWRBTN_N")
	)
	(segment
		(start 375.758964 -232.844086)
		(end 375.744232 -232.852722)
		(width 0.0889)
		(layer "B.Cu")
		(net "TP_CPU0_PWRBTN_N")
	)
	(segment
		(start 369.731036 -232.852722)
		(end 369.716304 -232.844086)
		(width 0.0889)
		(layer "B.Cu")
		(net "TP_CPU0_PWRBTN_N")
	)
	(segment
		(start 371.059964 -232.844086)
		(end 371.045232 -232.852722)
		(width 0.0889)
		(layer "B.Cu")
		(net "TP_CPU0_PWRBTN_N")
	)
	(segment
		(start 377.638564 -232.844086)
		(end 377.623832 -232.852722)
		(width 0.0889)
		(layer "B.Cu")
		(net "TP_CPU0_PWRBTN_N")
	)
	(segment
		(start 368.235992 -232.846626)
		(end 368.225578 -232.852722)
		(width 0.0889)
		(layer "B.Cu")
		(net "TP_CPU0_PWRBTN_N")
	)
	(segment
		(start 371.999764 -232.844086)
		(end 371.985032 -232.852722)
		(width 0.0889)
		(layer "B.Cu")
		(net "TP_CPU0_PWRBTN_N")
	)
	(segment
		(start 376.698764 -232.844086)
		(end 376.684032 -232.852722)
		(width 0.0889)
		(layer "B.Cu")
		(net "TP_CPU0_PWRBTN_N")
	)
	(segment
		(start 381.008382 -232.852722)
		(end 380.997968 -232.846626)
		(width 0.0889)
		(layer "B.Cu")
		(net "TP_CPU0_PWRBTN_N")
	)
	(segment
		(start 383.641854 -232.491788)
		(end 383.340356 -232.793286)
		(width 0.0889)
		(layer "B.Cu")
		(net "TP_CPU0_PWRBTN_N")
	)
	(segment
		(start 386.214112 -233.152696)
		(end 385.469638 -233.152696)
		(width 0.12954)
		(layer "B.Cu")
		(net "TP_CPU0_PWRBTN_N")
	)
	(segment
		(start 365.845598 -232.798874)
		(end 365.219234 -232.528364)
		(width 0.0889)
		(layer "B.Cu")
		(net "TP_CPU0_PWRBTN_N")
	)
	(segment
		(start 385.469638 -233.152696)
		(end 384.80873 -232.491788)
		(width 0.12954)
		(layer "B.Cu")
		(net "TP_CPU0_PWRBTN_N")
	)
	(segment
		(start 378.578364 -232.844086)
		(end 378.563632 -232.852722)
		(width 0.0889)
		(layer "B.Cu")
		(net "TP_CPU0_PWRBTN_N")
	)
	(segment
		(start 370.120164 -232.844086)
		(end 370.105432 -232.852722)
		(width 0.0889)
		(layer "B.Cu")
		(net "TP_CPU0_PWRBTN_N")
	)
	(segment
		(start 379.518164 -232.844086)
		(end 379.503432 -232.852722)
		(width 0.0889)
		(layer "B.Cu")
		(net "TP_CPU0_PWRBTN_N")
	)
	(segment
		(start 374.814592 -232.846626)
		(end 374.804178 -232.852722)
		(width 0.0889)
		(layer "B.Cu")
		(net "TP_CPU0_PWRBTN_N")
	)
	(segment
		(start 372.939564 -232.844086)
		(end 372.924832 -232.852722)
		(width 0.0889)
		(layer "B.Cu")
		(net "TP_CPU0_PWRBTN_N")
	)
	(segment
		(start 381.948436 -232.852722)
		(end 381.938022 -232.846626)
		(width 0.0889)
		(layer "B.Cu")
		(net "TP_CPU0_PWRBTN_N")
	)
	(segment
		(start 384.517138 -232.491788)
		(end 383.641854 -232.491788)
		(width 0.0889)
		(layer "B.Cu")
		(net "TP_CPU0_PWRBTN_N")
	)
	(arc
		(start 374.804178 -232.852722)
		(mid 374.61698 -232.902865)
		(end 374.429782 -232.852722)
		(width 0.0889)
		(layer "B.Cu")
		(net "TP_CPU0_PWRBTN_N")
	)
	(arc
		(start 382.322832 -232.852722)
		(mid 382.135634 -232.902865)
		(end 381.948436 -232.852722)
		(width 0.0889)
		(layer "B.Cu")
		(net "TP_CPU0_PWRBTN_N")
	)
	(arc
		(start 377.249436 -232.852722)
		(mid 376.975237 -232.776887)
		(end 376.698764 -232.844086)
		(width 0.0889)
		(layer "B.Cu")
		(net "TP_CPU0_PWRBTN_N")
	)
	(arc
		(start 370.105432 -232.852722)
		(mid 369.918234 -232.902865)
		(end 369.731036 -232.852722)
		(width 0.0889)
		(layer "B.Cu")
		(net "TP_CPU0_PWRBTN_N")
	)
	(arc
		(start 380.068836 -232.852722)
		(mid 379.794637 -232.776887)
		(end 379.518164 -232.844086)
		(width 0.0889)
		(layer "B.Cu")
		(net "TP_CPU0_PWRBTN_N")
	)
	(arc
		(start 375.744232 -232.852722)
		(mid 375.557034 -232.902865)
		(end 375.369836 -232.852722)
		(width 0.0889)
		(layer "B.Cu")
		(net "TP_CPU0_PWRBTN_N")
	)
	(arc
		(start 379.503432 -232.852722)
		(mid 379.316234 -232.902865)
		(end 379.129036 -232.852722)
		(width 0.0889)
		(layer "B.Cu")
		(net "TP_CPU0_PWRBTN_N")
	)
	(arc
		(start 368.791236 -232.852722)
		(mid 368.514423 -232.776852)
		(end 368.235992 -232.846626)
		(width 0.0889)
		(layer "B.Cu")
		(net "TP_CPU0_PWRBTN_N")
	)
	(arc
		(start 367.851182 -232.852722)
		(mid 367.574623 -232.776979)
		(end 367.296446 -232.846626)
		(width 0.0889)
		(layer "B.Cu")
		(net "TP_CPU0_PWRBTN_N")
	)
	(arc
		(start 381.938022 -232.846626)
		(mid 381.65959 -232.77678)
		(end 381.382778 -232.852722)
		(width 0.0889)
		(layer "B.Cu")
		(net "TP_CPU0_PWRBTN_N")
	)
	(arc
		(start 376.684032 -232.852722)
		(mid 376.496834 -232.902865)
		(end 376.309636 -232.852722)
		(width 0.0889)
		(layer "B.Cu")
		(net "TP_CPU0_PWRBTN_N")
	)
	(arc
		(start 370.670836 -232.852722)
		(mid 370.396637 -232.776887)
		(end 370.120164 -232.844086)
		(width 0.0889)
		(layer "B.Cu")
		(net "TP_CPU0_PWRBTN_N")
	)
	(arc
		(start 366.346232 -232.852722)
		(mid 366.159034 -232.902865)
		(end 365.971836 -232.852722)
		(width 0.0889)
		(layer "B.Cu")
		(net "TP_CPU0_PWRBTN_N")
	)
	(arc
		(start 366.911636 -232.852722)
		(mid 366.637437 -232.776887)
		(end 366.360964 -232.844086)
		(width 0.0889)
		(layer "B.Cu")
		(net "TP_CPU0_PWRBTN_N")
	)
	(arc
		(start 373.490236 -232.852722)
		(mid 373.216037 -232.776887)
		(end 372.939564 -232.844086)
		(width 0.0889)
		(layer "B.Cu")
		(net "TP_CPU0_PWRBTN_N")
	)
	(arc
		(start 379.129036 -232.852722)
		(mid 378.854837 -232.776887)
		(end 378.578364 -232.844086)
		(width 0.0889)
		(layer "B.Cu")
		(net "TP_CPU0_PWRBTN_N")
	)
	(arc
		(start 383.262632 -232.852722)
		(mid 383.075434 -232.902865)
		(end 382.888236 -232.852722)
		(width 0.0889)
		(layer "B.Cu")
		(net "TP_CPU0_PWRBTN_N")
	)
	(arc
		(start 381.382778 -232.852722)
		(mid 381.19558 -232.902865)
		(end 381.008382 -232.852722)
		(width 0.0889)
		(layer "B.Cu")
		(net "TP_CPU0_PWRBTN_N")
	)
	(arc
		(start 380.997968 -232.846626)
		(mid 380.71979 -232.776903)
		(end 380.443232 -232.852722)
		(width 0.0889)
		(layer "B.Cu")
		(net "TP_CPU0_PWRBTN_N")
	)
	(arc
		(start 365.971836 -232.852722)
		(mid 365.910355 -232.82196)
		(end 365.845598 -232.798874)
		(width 0.0889)
		(layer "B.Cu")
		(net "TP_CPU0_PWRBTN_N")
	)
	(arc
		(start 383.340356 -232.793286)
		(mid 383.303446 -232.825557)
		(end 383.262632 -232.852722)
		(width 0.0889)
		(layer "B.Cu")
		(net "TP_CPU0_PWRBTN_N")
	)
	(arc
		(start 374.419368 -232.846626)
		(mid 374.14119 -232.776903)
		(end 373.864632 -232.852722)
		(width 0.0889)
		(layer "B.Cu")
		(net "TP_CPU0_PWRBTN_N")
	)
	(arc
		(start 372.924832 -232.852722)
		(mid 372.737634 -232.902865)
		(end 372.550436 -232.852722)
		(width 0.0889)
		(layer "B.Cu")
		(net "TP_CPU0_PWRBTN_N")
	)
	(arc
		(start 375.369836 -232.852722)
		(mid 375.093023 -232.776852)
		(end 374.814592 -232.846626)
		(width 0.0889)
		(layer "B.Cu")
		(net "TP_CPU0_PWRBTN_N")
	)
	(arc
		(start 372.550436 -232.852722)
		(mid 372.276237 -232.776887)
		(end 371.999764 -232.844086)
		(width 0.0889)
		(layer "B.Cu")
		(net "TP_CPU0_PWRBTN_N")
	)
	(arc
		(start 376.309636 -232.852722)
		(mid 376.035437 -232.776887)
		(end 375.758964 -232.844086)
		(width 0.0889)
		(layer "B.Cu")
		(net "TP_CPU0_PWRBTN_N")
	)
	(arc
		(start 378.189236 -232.852722)
		(mid 377.915037 -232.776887)
		(end 377.638564 -232.844086)
		(width 0.0889)
		(layer "B.Cu")
		(net "TP_CPU0_PWRBTN_N")
	)
	(arc
		(start 369.165632 -232.852722)
		(mid 368.978434 -232.902865)
		(end 368.791236 -232.852722)
		(width 0.0889)
		(layer "B.Cu")
		(net "TP_CPU0_PWRBTN_N")
	)
	(arc
		(start 371.610636 -232.852722)
		(mid 371.336437 -232.776887)
		(end 371.059964 -232.844086)
		(width 0.0889)
		(layer "B.Cu")
		(net "TP_CPU0_PWRBTN_N")
	)
	(arc
		(start 371.045232 -232.852722)
		(mid 370.858034 -232.902865)
		(end 370.670836 -232.852722)
		(width 0.0889)
		(layer "B.Cu")
		(net "TP_CPU0_PWRBTN_N")
	)
	(arc
		(start 378.563632 -232.852722)
		(mid 378.376434 -232.902865)
		(end 378.189236 -232.852722)
		(width 0.0889)
		(layer "B.Cu")
		(net "TP_CPU0_PWRBTN_N")
	)
	(arc
		(start 377.623832 -232.852722)
		(mid 377.436634 -232.902865)
		(end 377.249436 -232.852722)
		(width 0.0889)
		(layer "B.Cu")
		(net "TP_CPU0_PWRBTN_N")
	)
	(arc
		(start 367.286032 -232.852722)
		(mid 367.098834 -232.902865)
		(end 366.911636 -232.852722)
		(width 0.0889)
		(layer "B.Cu")
		(net "TP_CPU0_PWRBTN_N")
	)
	(arc
		(start 368.225578 -232.852722)
		(mid 368.03838 -232.902899)
		(end 367.851182 -232.852722)
		(width 0.0889)
		(layer "B.Cu")
		(net "TP_CPU0_PWRBTN_N")
	)
	(arc
		(start 380.443232 -232.852722)
		(mid 380.256034 -232.902865)
		(end 380.068836 -232.852722)
		(width 0.0889)
		(layer "B.Cu")
		(net "TP_CPU0_PWRBTN_N")
	)
	(arc
		(start 382.888236 -232.852722)
		(mid 382.605534 -232.776946)
		(end 382.322832 -232.852722)
		(width 0.0889)
		(layer "B.Cu")
		(net "TP_CPU0_PWRBTN_N")
	)
	(arc
		(start 371.985032 -232.852722)
		(mid 371.797834 -232.902865)
		(end 371.610636 -232.852722)
		(width 0.0889)
		(layer "B.Cu")
		(net "TP_CPU0_PWRBTN_N")
	)
	(arc
		(start 369.716304 -232.844086)
		(mid 369.439829 -232.776766)
		(end 369.165632 -232.852722)
		(width 0.0889)
		(layer "B.Cu")
		(net "TP_CPU0_PWRBTN_N")
	)
	(arc
		(start 373.864632 -232.852722)
		(mid 373.677434 -232.902865)
		(end 373.490236 -232.852722)
		(width 0.0889)
		(layer "B.Cu")
		(net "TP_CPU0_PWRBTN_N")
	)
	(segment
		(start 370.498116 -257.45313)
		(end 370.497862 -257.98907)
		(width 0.12954)
		(layer "F.Cu")
		(net "TP_CPU0_PROCDIS_COD_GTL_N")
	)
	(via
		(at 386.997956 -256.911856)
		(size 0.6604)
		(drill 0.3302)
		(layers "F.Cu" "B.Cu")
		(net "TP_CPU0_PROCDIS_COD_GTL_N")
	)
	(via
		(at 370.497862 -257.98907)
		(size 0.4572)
		(drill 0.2032)
		(layers "F.Cu" "B.Cu")
		(net "TP_CPU0_PROCDIS_COD_GTL_N")
	)
	(segment
		(start 376.889264 -258.313428)
		(end 376.874532 -258.304792)
		(width 0.0889)
		(layer "B.Cu")
		(net "TP_CPU0_PROCDIS_COD_GTL_N")
	)
	(segment
		(start 382.528064 -258.313428)
		(end 382.51765 -258.307332)
		(width 0.0889)
		(layer "B.Cu")
		(net "TP_CPU0_PROCDIS_COD_GTL_N")
	)
	(segment
		(start 374.069864 -258.313428)
		(end 374.05945 -258.307332)
		(width 0.0889)
		(layer "B.Cu")
		(net "TP_CPU0_PROCDIS_COD_GTL_N")
	)
	(segment
		(start 385.074414 -258.03987)
		(end 385.074414 -258.258056)
		(width 0.0889)
		(layer "B.Cu")
		(net "TP_CPU0_PROCDIS_COD_GTL_N")
	)
	(segment
		(start 380.648464 -258.313428)
		(end 380.63805 -258.307332)
		(width 0.0889)
		(layer "B.Cu")
		(net "TP_CPU0_PROCDIS_COD_GTL_N")
	)
	(segment
		(start 385.074414 -257.311398)
		(end 385.074414 -258.03987)
		(width 0.12954)
		(layer "B.Cu")
		(net "TP_CPU0_PROCDIS_COD_GTL_N")
	)
	(segment
		(start 384.587496 -258.465574)
		(end 384.525012 -258.40309)
		(width 0.0889)
		(layer "B.Cu")
		(net "TP_CPU0_PROCDIS_COD_GTL_N")
	)
	(segment
		(start 378.768864 -258.313428)
		(end 378.754132 -258.304792)
		(width 0.0889)
		(layer "B.Cu")
		(net "TP_CPU0_PROCDIS_COD_GTL_N")
	)
	(segment
		(start 385.473956 -256.911856)
		(end 385.074414 -257.311398)
		(width 0.12954)
		(layer "B.Cu")
		(net "TP_CPU0_PROCDIS_COD_GTL_N")
	)
	(segment
		(start 386.997956 -256.911856)
		(end 385.473956 -256.911856)
		(width 0.12954)
		(layer "B.Cu")
		(net "TP_CPU0_PROCDIS_COD_GTL_N")
	)
	(segment
		(start 375.949464 -258.313428)
		(end 375.93905 -258.307332)
		(width 0.0889)
		(layer "B.Cu")
		(net "TP_CPU0_PROCDIS_COD_GTL_N")
	)
	(segment
		(start 384.866896 -258.465574)
		(end 384.587496 -258.465574)
		(width 0.0889)
		(layer "B.Cu")
		(net "TP_CPU0_PROCDIS_COD_GTL_N")
	)
	(segment
		(start 379.708918 -258.313428)
		(end 379.698504 -258.307332)
		(width 0.0889)
		(layer "B.Cu")
		(net "TP_CPU0_PROCDIS_COD_GTL_N")
	)
	(segment
		(start 371.250464 -258.313428)
		(end 370.853462 -258.08432)
		(width 0.0889)
		(layer "B.Cu")
		(net "TP_CPU0_PROCDIS_COD_GTL_N")
	)
	(segment
		(start 373.130318 -258.313428)
		(end 373.119904 -258.307332)
		(width 0.0889)
		(layer "B.Cu")
		(net "TP_CPU0_PROCDIS_COD_GTL_N")
	)
	(segment
		(start 381.588518 -258.313428)
		(end 381.578104 -258.307332)
		(width 0.0889)
		(layer "B.Cu")
		(net "TP_CPU0_PROCDIS_COD_GTL_N")
	)
	(segment
		(start 385.074414 -258.258056)
		(end 384.866896 -258.465574)
		(width 0.0889)
		(layer "B.Cu")
		(net "TP_CPU0_PROCDIS_COD_GTL_N")
	)
	(segment
		(start 383.852674 -258.307332)
		(end 383.84226 -258.313428)
		(width 0.0889)
		(layer "B.Cu")
		(net "TP_CPU0_PROCDIS_COD_GTL_N")
	)
	(segment
		(start 372.190264 -258.313428)
		(end 372.175532 -258.304792)
		(width 0.0889)
		(layer "B.Cu")
		(net "TP_CPU0_PROCDIS_COD_GTL_N")
	)
	(segment
		(start 375.009918 -258.313428)
		(end 374.999504 -258.307332)
		(width 0.0889)
		(layer "B.Cu")
		(net "TP_CPU0_PROCDIS_COD_GTL_N")
	)
	(arc
		(start 374.44426 -258.313428)
		(mid 374.257062 -258.363571)
		(end 374.069864 -258.313428)
		(width 0.0889)
		(layer "B.Cu")
		(net "TP_CPU0_PROCDIS_COD_GTL_N")
	)
	(arc
		(start 382.90246 -258.313428)
		(mid 382.715262 -258.363571)
		(end 382.528064 -258.313428)
		(width 0.0889)
		(layer "B.Cu")
		(net "TP_CPU0_PROCDIS_COD_GTL_N")
	)
	(arc
		(start 374.999504 -258.307332)
		(mid 374.721072 -258.237518)
		(end 374.44426 -258.313428)
		(width 0.0889)
		(layer "B.Cu")
		(net "TP_CPU0_PROCDIS_COD_GTL_N")
	)
	(arc
		(start 376.874532 -258.304792)
		(mid 376.598091 -258.237626)
		(end 376.32386 -258.313428)
		(width 0.0889)
		(layer "B.Cu")
		(net "TP_CPU0_PROCDIS_COD_GTL_N")
	)
	(arc
		(start 377.26366 -258.313428)
		(mid 377.076462 -258.363571)
		(end 376.889264 -258.313428)
		(width 0.0889)
		(layer "B.Cu")
		(net "TP_CPU0_PROCDIS_COD_GTL_N")
	)
	(arc
		(start 378.20346 -258.313428)
		(mid 378.016262 -258.363571)
		(end 377.829064 -258.313428)
		(width 0.0889)
		(layer "B.Cu")
		(net "TP_CPU0_PROCDIS_COD_GTL_N")
	)
	(arc
		(start 380.63805 -258.307332)
		(mid 380.359872 -258.23764)
		(end 380.083314 -258.313428)
		(width 0.0889)
		(layer "B.Cu")
		(net "TP_CPU0_PROCDIS_COD_GTL_N")
	)
	(arc
		(start 373.504714 -258.313428)
		(mid 373.317516 -258.363571)
		(end 373.130318 -258.313428)
		(width 0.0889)
		(layer "B.Cu")
		(net "TP_CPU0_PROCDIS_COD_GTL_N")
	)
	(arc
		(start 381.962914 -258.313428)
		(mid 381.775716 -258.363571)
		(end 381.588518 -258.313428)
		(width 0.0889)
		(layer "B.Cu")
		(net "TP_CPU0_PROCDIS_COD_GTL_N")
	)
	(arc
		(start 377.829064 -258.313428)
		(mid 377.546362 -258.237686)
		(end 377.26366 -258.313428)
		(width 0.0889)
		(layer "B.Cu")
		(net "TP_CPU0_PROCDIS_COD_GTL_N")
	)
	(arc
		(start 375.93905 -258.307332)
		(mid 375.660872 -258.23764)
		(end 375.384314 -258.313428)
		(width 0.0889)
		(layer "B.Cu")
		(net "TP_CPU0_PROCDIS_COD_GTL_N")
	)
	(arc
		(start 378.754132 -258.304792)
		(mid 378.477691 -258.237626)
		(end 378.20346 -258.313428)
		(width 0.0889)
		(layer "B.Cu")
		(net "TP_CPU0_PROCDIS_COD_GTL_N")
	)
	(arc
		(start 371.62486 -258.313428)
		(mid 371.437662 -258.363571)
		(end 371.250464 -258.313428)
		(width 0.0889)
		(layer "B.Cu")
		(net "TP_CPU0_PROCDIS_COD_GTL_N")
	)
	(arc
		(start 379.698504 -258.307332)
		(mid 379.420072 -258.237518)
		(end 379.14326 -258.313428)
		(width 0.0889)
		(layer "B.Cu")
		(net "TP_CPU0_PROCDIS_COD_GTL_N")
	)
	(arc
		(start 383.84226 -258.313428)
		(mid 383.655062 -258.363571)
		(end 383.467864 -258.313428)
		(width 0.0889)
		(layer "B.Cu")
		(net "TP_CPU0_PROCDIS_COD_GTL_N")
	)
	(arc
		(start 381.578104 -258.307332)
		(mid 381.299672 -258.237518)
		(end 381.02286 -258.313428)
		(width 0.0889)
		(layer "B.Cu")
		(net "TP_CPU0_PROCDIS_COD_GTL_N")
	)
	(arc
		(start 381.02286 -258.313428)
		(mid 380.835662 -258.363571)
		(end 380.648464 -258.313428)
		(width 0.0889)
		(layer "B.Cu")
		(net "TP_CPU0_PROCDIS_COD_GTL_N")
	)
	(arc
		(start 384.407918 -258.313428)
		(mid 384.131105 -258.237592)
		(end 383.852674 -258.307332)
		(width 0.0889)
		(layer "B.Cu")
		(net "TP_CPU0_PROCDIS_COD_GTL_N")
	)
	(arc
		(start 375.384314 -258.313428)
		(mid 375.197116 -258.363571)
		(end 375.009918 -258.313428)
		(width 0.0889)
		(layer "B.Cu")
		(net "TP_CPU0_PROCDIS_COD_GTL_N")
	)
	(arc
		(start 383.467864 -258.313428)
		(mid 383.185162 -258.237686)
		(end 382.90246 -258.313428)
		(width 0.0889)
		(layer "B.Cu")
		(net "TP_CPU0_PROCDIS_COD_GTL_N")
	)
	(arc
		(start 376.32386 -258.313428)
		(mid 376.136662 -258.363571)
		(end 375.949464 -258.313428)
		(width 0.0889)
		(layer "B.Cu")
		(net "TP_CPU0_PROCDIS_COD_GTL_N")
	)
	(arc
		(start 372.56466 -258.313428)
		(mid 372.377462 -258.363571)
		(end 372.190264 -258.313428)
		(width 0.0889)
		(layer "B.Cu")
		(net "TP_CPU0_PROCDIS_COD_GTL_N")
	)
	(arc
		(start 380.083314 -258.313428)
		(mid 379.896116 -258.363571)
		(end 379.708918 -258.313428)
		(width 0.0889)
		(layer "B.Cu")
		(net "TP_CPU0_PROCDIS_COD_GTL_N")
	)
	(arc
		(start 373.119904 -258.307332)
		(mid 372.841472 -258.237518)
		(end 372.56466 -258.313428)
		(width 0.0889)
		(layer "B.Cu")
		(net "TP_CPU0_PROCDIS_COD_GTL_N")
	)
	(arc
		(start 374.05945 -258.307332)
		(mid 373.781272 -258.23764)
		(end 373.504714 -258.313428)
		(width 0.0889)
		(layer "B.Cu")
		(net "TP_CPU0_PROCDIS_COD_GTL_N")
	)
	(arc
		(start 370.853462 -258.08432)
		(mid 370.681929 -258.013299)
		(end 370.497862 -257.98907)
		(width 0.0889)
		(layer "B.Cu")
		(net "TP_CPU0_PROCDIS_COD_GTL_N")
	)
	(arc
		(start 382.51765 -258.307332)
		(mid 382.239472 -258.23764)
		(end 381.962914 -258.313428)
		(width 0.0889)
		(layer "B.Cu")
		(net "TP_CPU0_PROCDIS_COD_GTL_N")
	)
	(arc
		(start 379.14326 -258.313428)
		(mid 378.956062 -258.363571)
		(end 378.768864 -258.313428)
		(width 0.0889)
		(layer "B.Cu")
		(net "TP_CPU0_PROCDIS_COD_GTL_N")
	)
	(arc
		(start 372.175532 -258.304792)
		(mid 371.899091 -258.237626)
		(end 371.62486 -258.313428)
		(width 0.0889)
		(layer "B.Cu")
		(net "TP_CPU0_PROCDIS_COD_GTL_N")
	)
	(arc
		(start 384.525012 -258.40309)
		(mid 384.469396 -258.354432)
		(end 384.407918 -258.313428)
		(width 0.0889)
		(layer "B.Cu")
		(net "TP_CPU0_PROCDIS_COD_GTL_N")
	)
	(segment
		(start 336.55508 -224.111312)
		(end 336.55508 -223.575626)
		(width 0.12954)
		(layer "F.Cu")
		(net "TP_CPU0_PPD")
	)
	(segment
		(start 336.555334 -224.111566)
		(end 336.55508 -224.111312)
		(width 0.12954)
		(layer "F.Cu")
		(net "TP_CPU0_PPD")
	)
	(via
		(at 336.55508 -223.575626)
		(size 0.4572)
		(drill 0.2032)
		(layers "F.Cu" "B.Cu")
		(net "TP_CPU0_PPD")
	)
	(segment
		(start 353.94138 -233.064304)
		(end 353.941634 -233.06405)
		(width 0.12954)
		(layer "F.Cu")
		(net "TP_CPU0_IFST_TRIG_LVC1_R")
	)
	(segment
		(start 353.941634 -233.06405)
		(end 353.941634 -232.528364)
		(width 0.12954)
		(layer "F.Cu")
		(net "TP_CPU0_IFST_TRIG_LVC1_R")
	)
	(via
		(at 353.941634 -232.528364)
		(size 0.4572)
		(drill 0.2032)
		(layers "F.Cu" "B.Cu")
		(net "TP_CPU0_IFST_TRIG_LVC1_R")
	)
	(via
		(at 327.217278 -234.08767)
		(size 0.6604)
		(drill 0.3302)
		(layers "F.Cu" "B.Cu")
		(net "TP_CPU0_IFST_TRIG_LVC1_R")
	)
	(segment
		(start 347.564964 -232.844086)
		(end 347.550232 -232.852722)
		(width 0.0889)
		(layer "B.Cu")
		(net "TP_CPU0_IFST_TRIG_LVC1_R")
	)
	(segment
		(start 337.227164 -232.844086)
		(end 337.212432 -232.852722)
		(width 0.0889)
		(layer "B.Cu")
		(net "TP_CPU0_IFST_TRIG_LVC1_R")
	)
	(segment
		(start 335.145634 -232.903268)
		(end 335.060798 -232.903268)
		(width 0.0889)
		(layer "B.Cu")
		(net "TP_CPU0_IFST_TRIG_LVC1_R")
	)
	(segment
		(start 336.287364 -232.844086)
		(end 336.272632 -232.852722)
		(width 0.0889)
		(layer "B.Cu")
		(net "TP_CPU0_IFST_TRIG_LVC1_R")
	)
	(segment
		(start 350.384364 -232.844086)
		(end 350.369632 -232.852722)
		(width 0.0889)
		(layer "B.Cu")
		(net "TP_CPU0_IFST_TRIG_LVC1_R")
	)
	(segment
		(start 349.444564 -232.844086)
		(end 349.429832 -232.852722)
		(width 0.0889)
		(layer "B.Cu")
		(net "TP_CPU0_IFST_TRIG_LVC1_R")
	)
	(segment
		(start 342.865964 -232.844086)
		(end 342.851232 -232.852722)
		(width 0.0889)
		(layer "B.Cu")
		(net "TP_CPU0_IFST_TRIG_LVC1_R")
	)
	(segment
		(start 344.745564 -232.844086)
		(end 344.730832 -232.852722)
		(width 0.0889)
		(layer "B.Cu")
		(net "TP_CPU0_IFST_TRIG_LVC1_R")
	)
	(segment
		(start 351.324164 -232.844086)
		(end 351.309432 -232.852722)
		(width 0.0889)
		(layer "B.Cu")
		(net "TP_CPU0_IFST_TRIG_LVC1_R")
	)
	(segment
		(start 352.263964 -232.844086)
		(end 352.249232 -232.852722)
		(width 0.0889)
		(layer "B.Cu")
		(net "TP_CPU0_IFST_TRIG_LVC1_R")
	)
	(segment
		(start 331.747368 -233.200956)
		(end 331.576934 -233.37139)
		(width 0.0889)
		(layer "B.Cu")
		(net "TP_CPU0_IFST_TRIG_LVC1_R")
	)
	(segment
		(start 340.986364 -232.844086)
		(end 340.971632 -232.852722)
		(width 0.0889)
		(layer "B.Cu")
		(net "TP_CPU0_IFST_TRIG_LVC1_R")
	)
	(segment
		(start 348.504764 -232.844086)
		(end 348.490032 -232.852722)
		(width 0.0889)
		(layer "B.Cu")
		(net "TP_CPU0_IFST_TRIG_LVC1_R")
	)
	(segment
		(start 334.76311 -233.200956)
		(end 331.747368 -233.200956)
		(width 0.0889)
		(layer "B.Cu")
		(net "TP_CPU0_IFST_TRIG_LVC1_R")
	)
	(segment
		(start 338.166964 -232.844086)
		(end 338.152232 -232.852722)
		(width 0.0889)
		(layer "B.Cu")
		(net "TP_CPU0_IFST_TRIG_LVC1_R")
	)
	(segment
		(start 339.657182 -232.852722)
		(end 339.646768 -232.846626)
		(width 0.0889)
		(layer "B.Cu")
		(net "TP_CPU0_IFST_TRIG_LVC1_R")
	)
	(segment
		(start 327.788778 -233.51617)
		(end 327.217278 -234.08767)
		(width 0.12954)
		(layer "B.Cu")
		(net "TP_CPU0_IFST_TRIG_LVC1_R")
	)
	(segment
		(start 343.805764 -232.844086)
		(end 343.791032 -232.852722)
		(width 0.0889)
		(layer "B.Cu")
		(net "TP_CPU0_IFST_TRIG_LVC1_R")
	)
	(segment
		(start 335.060798 -232.903268)
		(end 334.76311 -233.200956)
		(width 0.0889)
		(layer "B.Cu")
		(net "TP_CPU0_IFST_TRIG_LVC1_R")
	)
	(segment
		(start 331.432154 -233.51617)
		(end 327.788778 -233.51617)
		(width 0.12954)
		(layer "B.Cu")
		(net "TP_CPU0_IFST_TRIG_LVC1_R")
	)
	(segment
		(start 341.926164 -232.844086)
		(end 341.911432 -232.852722)
		(width 0.0889)
		(layer "B.Cu")
		(net "TP_CPU0_IFST_TRIG_LVC1_R")
	)
	(segment
		(start 346.620592 -232.846626)
		(end 346.610178 -232.852722)
		(width 0.0889)
		(layer "B.Cu")
		(net "TP_CPU0_IFST_TRIG_LVC1_R")
	)
	(segment
		(start 331.576934 -233.37139)
		(end 331.432154 -233.51617)
		(width 0.12954)
		(layer "B.Cu")
		(net "TP_CPU0_IFST_TRIG_LVC1_R")
	)
	(segment
		(start 353.203764 -232.844086)
		(end 353.189032 -232.852722)
		(width 0.0889)
		(layer "B.Cu")
		(net "TP_CPU0_IFST_TRIG_LVC1_R")
	)
	(segment
		(start 340.041992 -232.846626)
		(end 340.031578 -232.852722)
		(width 0.0889)
		(layer "B.Cu")
		(net "TP_CPU0_IFST_TRIG_LVC1_R")
	)
	(segment
		(start 353.941634 -232.528364)
		(end 353.376992 -232.78465)
		(width 0.0889)
		(layer "B.Cu")
		(net "TP_CPU0_IFST_TRIG_LVC1_R")
	)
	(segment
		(start 346.235782 -232.852722)
		(end 346.225368 -232.846626)
		(width 0.0889)
		(layer "B.Cu")
		(net "TP_CPU0_IFST_TRIG_LVC1_R")
	)
	(arc
		(start 343.416636 -232.852722)
		(mid 343.142437 -232.776887)
		(end 342.865964 -232.844086)
		(width 0.0889)
		(layer "B.Cu")
		(net "TP_CPU0_IFST_TRIG_LVC1_R")
	)
	(arc
		(start 335.332832 -232.852722)
		(mid 335.24256 -232.890321)
		(end 335.145634 -232.903268)
		(width 0.0889)
		(layer "B.Cu")
		(net "TP_CPU0_IFST_TRIG_LVC1_R")
	)
	(arc
		(start 347.550232 -232.852722)
		(mid 347.363034 -232.902865)
		(end 347.175836 -232.852722)
		(width 0.0889)
		(layer "B.Cu")
		(net "TP_CPU0_IFST_TRIG_LVC1_R")
	)
	(arc
		(start 339.092032 -232.852722)
		(mid 338.904834 -232.902865)
		(end 338.717636 -232.852722)
		(width 0.0889)
		(layer "B.Cu")
		(net "TP_CPU0_IFST_TRIG_LVC1_R")
	)
	(arc
		(start 341.537036 -232.852722)
		(mid 341.262837 -232.776887)
		(end 340.986364 -232.844086)
		(width 0.0889)
		(layer "B.Cu")
		(net "TP_CPU0_IFST_TRIG_LVC1_R")
	)
	(arc
		(start 349.429832 -232.852722)
		(mid 349.242634 -232.902865)
		(end 349.055436 -232.852722)
		(width 0.0889)
		(layer "B.Cu")
		(net "TP_CPU0_IFST_TRIG_LVC1_R")
	)
	(arc
		(start 344.730832 -232.852722)
		(mid 344.543634 -232.902865)
		(end 344.356436 -232.852722)
		(width 0.0889)
		(layer "B.Cu")
		(net "TP_CPU0_IFST_TRIG_LVC1_R")
	)
	(arc
		(start 338.152232 -232.852722)
		(mid 337.965034 -232.902865)
		(end 337.777836 -232.852722)
		(width 0.0889)
		(layer "B.Cu")
		(net "TP_CPU0_IFST_TRIG_LVC1_R")
	)
	(arc
		(start 350.369632 -232.852722)
		(mid 350.182434 -232.902865)
		(end 349.995236 -232.852722)
		(width 0.0889)
		(layer "B.Cu")
		(net "TP_CPU0_IFST_TRIG_LVC1_R")
	)
	(arc
		(start 345.296236 -232.852722)
		(mid 345.022037 -232.776887)
		(end 344.745564 -232.844086)
		(width 0.0889)
		(layer "B.Cu")
		(net "TP_CPU0_IFST_TRIG_LVC1_R")
	)
	(arc
		(start 349.055436 -232.852722)
		(mid 348.781237 -232.776887)
		(end 348.504764 -232.844086)
		(width 0.0889)
		(layer "B.Cu")
		(net "TP_CPU0_IFST_TRIG_LVC1_R")
	)
	(arc
		(start 336.272632 -232.852722)
		(mid 336.085434 -232.902865)
		(end 335.898236 -232.852722)
		(width 0.0889)
		(layer "B.Cu")
		(net "TP_CPU0_IFST_TRIG_LVC1_R")
	)
	(arc
		(start 346.225368 -232.846626)
		(mid 345.94719 -232.776903)
		(end 345.670632 -232.852722)
		(width 0.0889)
		(layer "B.Cu")
		(net "TP_CPU0_IFST_TRIG_LVC1_R")
	)
	(arc
		(start 343.791032 -232.852722)
		(mid 343.603834 -232.902865)
		(end 343.416636 -232.852722)
		(width 0.0889)
		(layer "B.Cu")
		(net "TP_CPU0_IFST_TRIG_LVC1_R")
	)
	(arc
		(start 335.898236 -232.852722)
		(mid 335.615534 -232.776946)
		(end 335.332832 -232.852722)
		(width 0.0889)
		(layer "B.Cu")
		(net "TP_CPU0_IFST_TRIG_LVC1_R")
	)
	(arc
		(start 347.175836 -232.852722)
		(mid 346.899023 -232.776852)
		(end 346.620592 -232.846626)
		(width 0.0889)
		(layer "B.Cu")
		(net "TP_CPU0_IFST_TRIG_LVC1_R")
	)
	(arc
		(start 351.309432 -232.852722)
		(mid 351.122234 -232.902865)
		(end 350.935036 -232.852722)
		(width 0.0889)
		(layer "B.Cu")
		(net "TP_CPU0_IFST_TRIG_LVC1_R")
	)
	(arc
		(start 352.814636 -232.852722)
		(mid 352.540437 -232.776887)
		(end 352.263964 -232.844086)
		(width 0.0889)
		(layer "B.Cu")
		(net "TP_CPU0_IFST_TRIG_LVC1_R")
	)
	(arc
		(start 344.356436 -232.852722)
		(mid 344.082237 -232.776887)
		(end 343.805764 -232.844086)
		(width 0.0889)
		(layer "B.Cu")
		(net "TP_CPU0_IFST_TRIG_LVC1_R")
	)
	(arc
		(start 348.115636 -232.852722)
		(mid 347.841437 -232.776887)
		(end 347.564964 -232.844086)
		(width 0.0889)
		(layer "B.Cu")
		(net "TP_CPU0_IFST_TRIG_LVC1_R")
	)
	(arc
		(start 339.646768 -232.846626)
		(mid 339.36859 -232.776903)
		(end 339.092032 -232.852722)
		(width 0.0889)
		(layer "B.Cu")
		(net "TP_CPU0_IFST_TRIG_LVC1_R")
	)
	(arc
		(start 346.610178 -232.852722)
		(mid 346.42298 -232.902865)
		(end 346.235782 -232.852722)
		(width 0.0889)
		(layer "B.Cu")
		(net "TP_CPU0_IFST_TRIG_LVC1_R")
	)
	(arc
		(start 342.476836 -232.852722)
		(mid 342.202637 -232.776887)
		(end 341.926164 -232.844086)
		(width 0.0889)
		(layer "B.Cu")
		(net "TP_CPU0_IFST_TRIG_LVC1_R")
	)
	(arc
		(start 340.597236 -232.852722)
		(mid 340.320423 -232.776852)
		(end 340.041992 -232.846626)
		(width 0.0889)
		(layer "B.Cu")
		(net "TP_CPU0_IFST_TRIG_LVC1_R")
	)
	(arc
		(start 337.212432 -232.852722)
		(mid 337.025234 -232.902865)
		(end 336.838036 -232.852722)
		(width 0.0889)
		(layer "B.Cu")
		(net "TP_CPU0_IFST_TRIG_LVC1_R")
	)
	(arc
		(start 351.874836 -232.852722)
		(mid 351.600637 -232.776887)
		(end 351.324164 -232.844086)
		(width 0.0889)
		(layer "B.Cu")
		(net "TP_CPU0_IFST_TRIG_LVC1_R")
	)
	(arc
		(start 338.717636 -232.852722)
		(mid 338.443437 -232.776887)
		(end 338.166964 -232.844086)
		(width 0.0889)
		(layer "B.Cu")
		(net "TP_CPU0_IFST_TRIG_LVC1_R")
	)
	(arc
		(start 349.995236 -232.852722)
		(mid 349.721037 -232.776887)
		(end 349.444564 -232.844086)
		(width 0.0889)
		(layer "B.Cu")
		(net "TP_CPU0_IFST_TRIG_LVC1_R")
	)
	(arc
		(start 340.971632 -232.852722)
		(mid 340.784434 -232.902865)
		(end 340.597236 -232.852722)
		(width 0.0889)
		(layer "B.Cu")
		(net "TP_CPU0_IFST_TRIG_LVC1_R")
	)
	(arc
		(start 342.851232 -232.852722)
		(mid 342.664034 -232.902865)
		(end 342.476836 -232.852722)
		(width 0.0889)
		(layer "B.Cu")
		(net "TP_CPU0_IFST_TRIG_LVC1_R")
	)
	(arc
		(start 341.911432 -232.852722)
		(mid 341.724234 -232.902865)
		(end 341.537036 -232.852722)
		(width 0.0889)
		(layer "B.Cu")
		(net "TP_CPU0_IFST_TRIG_LVC1_R")
	)
	(arc
		(start 353.189032 -232.852722)
		(mid 353.001834 -232.902865)
		(end 352.814636 -232.852722)
		(width 0.0889)
		(layer "B.Cu")
		(net "TP_CPU0_IFST_TRIG_LVC1_R")
	)
	(arc
		(start 345.670632 -232.852722)
		(mid 345.483434 -232.902865)
		(end 345.296236 -232.852722)
		(width 0.0889)
		(layer "B.Cu")
		(net "TP_CPU0_IFST_TRIG_LVC1_R")
	)
	(arc
		(start 336.838036 -232.852722)
		(mid 336.563837 -232.776887)
		(end 336.287364 -232.844086)
		(width 0.0889)
		(layer "B.Cu")
		(net "TP_CPU0_IFST_TRIG_LVC1_R")
	)
	(arc
		(start 340.031578 -232.852722)
		(mid 339.84438 -232.902865)
		(end 339.657182 -232.852722)
		(width 0.0889)
		(layer "B.Cu")
		(net "TP_CPU0_IFST_TRIG_LVC1_R")
	)
	(arc
		(start 350.935036 -232.852722)
		(mid 350.660837 -232.776887)
		(end 350.384364 -232.844086)
		(width 0.0889)
		(layer "B.Cu")
		(net "TP_CPU0_IFST_TRIG_LVC1_R")
	)
	(arc
		(start 352.249232 -232.852722)
		(mid 352.062034 -232.902865)
		(end 351.874836 -232.852722)
		(width 0.0889)
		(layer "B.Cu")
		(net "TP_CPU0_IFST_TRIG_LVC1_R")
	)
	(arc
		(start 348.490032 -232.852722)
		(mid 348.302834 -232.902865)
		(end 348.115636 -232.852722)
		(width 0.0889)
		(layer "B.Cu")
		(net "TP_CPU0_IFST_TRIG_LVC1_R")
	)
	(arc
		(start 353.376992 -232.78465)
		(mid 353.287956 -232.807309)
		(end 353.203764 -232.844086)
		(width 0.0889)
		(layer "B.Cu")
		(net "TP_CPU0_IFST_TRIG_LVC1_R")
	)
	(arc
		(start 337.777836 -232.852722)
		(mid 337.503637 -232.776887)
		(end 337.227164 -232.844086)
		(width 0.0889)
		(layer "B.Cu")
		(net "TP_CPU0_IFST_TRIG_LVC1_R")
	)
	(segment
		(start 353.471734 -232.250488)
		(end 353.47148 -232.250234)
		(width 0.12954)
		(layer "F.Cu")
		(net "TP_CPU0_IFST_KOT_LVC1_R")
	)
	(segment
		(start 353.47148 -232.250234)
		(end 353.47148 -231.714548)
		(width 0.12954)
		(layer "F.Cu")
		(net "TP_CPU0_IFST_KOT_LVC1_R")
	)
	(via
		(at 322.643246 -224.874074)
		(size 0.6604)
		(drill 0.3302)
		(layers "F.Cu" "B.Cu")
		(net "TP_CPU0_IFST_KOT_LVC1_R")
	)
	(via
		(at 353.47148 -231.714548)
		(size 0.4572)
		(drill 0.2032)
		(layers "F.Cu" "B.Cu")
		(net "TP_CPU0_IFST_KOT_LVC1_R")
	)
	(segment
		(start 330.402184 -228.47681)
		(end 326.245982 -228.47681)
		(width 0.12954)
		(layer "B.Cu")
		(net "TP_CPU0_IFST_KOT_LVC1_R")
	)
	(segment
		(start 337.227164 -228.957124)
		(end 337.212432 -228.948488)
		(width 0.0889)
		(layer "B.Cu")
		(net "TP_CPU0_IFST_KOT_LVC1_R")
	)
	(segment
		(start 340.986364 -228.957124)
		(end 340.971632 -228.948488)
		(width 0.0889)
		(layer "B.Cu")
		(net "TP_CPU0_IFST_KOT_LVC1_R")
	)
	(segment
		(start 326.245982 -228.47681)
		(end 322.643246 -224.874074)
		(width 0.12954)
		(layer "B.Cu")
		(net "TP_CPU0_IFST_KOT_LVC1_R")
	)
	(segment
		(start 335.820512 -229.007924)
		(end 335.70545 -229.122986)
		(width 0.0889)
		(layer "B.Cu")
		(net "TP_CPU0_IFST_KOT_LVC1_R")
	)
	(segment
		(start 350.378522 -228.953568)
		(end 350.369632 -228.948488)
		(width 0.0889)
		(layer "B.Cu")
		(net "TP_CPU0_IFST_KOT_LVC1_R")
	)
	(segment
		(start 332.144878 -228.88829)
		(end 330.813664 -228.88829)
		(width 0.12954)
		(layer "B.Cu")
		(net "TP_CPU0_IFST_KOT_LVC1_R")
	)
	(segment
		(start 347.564964 -228.957124)
		(end 347.550232 -228.948488)
		(width 0.0889)
		(layer "B.Cu")
		(net "TP_CPU0_IFST_KOT_LVC1_R")
	)
	(segment
		(start 352.344482 -231.39019)
		(end 352.32975 -231.398826)
		(width 0.0889)
		(layer "B.Cu")
		(net "TP_CPU0_IFST_KOT_LVC1_R")
	)
	(segment
		(start 342.861392 -228.954584)
		(end 342.850978 -228.948488)
		(width 0.0889)
		(layer "B.Cu")
		(net "TP_CPU0_IFST_KOT_LVC1_R")
	)
	(segment
		(start 351.318322 -230.5812)
		(end 351.309432 -230.57612)
		(width 0.0889)
		(layer "B.Cu")
		(net "TP_CPU0_IFST_KOT_LVC1_R")
	)
	(segment
		(start 334.88122 -229.122986)
		(end 334.646524 -228.88829)
		(width 0.0889)
		(layer "B.Cu")
		(net "TP_CPU0_IFST_KOT_LVC1_R")
	)
	(segment
		(start 351.496884 -230.922576)
		(end 351.496884 -230.900478)
		(width 0.0889)
		(layer "B.Cu")
		(net "TP_CPU0_IFST_KOT_LVC1_R")
	)
	(segment
		(start 346.625164 -228.957124)
		(end 346.610432 -228.948488)
		(width 0.0889)
		(layer "B.Cu")
		(net "TP_CPU0_IFST_KOT_LVC1_R")
	)
	(segment
		(start 340.046564 -228.957124)
		(end 340.031832 -228.948488)
		(width 0.0889)
		(layer "B.Cu")
		(net "TP_CPU0_IFST_KOT_LVC1_R")
	)
	(segment
		(start 351.309432 -230.57612)
		(end 351.303336 -230.572564)
		(width 0.0889)
		(layer "B.Cu")
		(net "TP_CPU0_IFST_KOT_LVC1_R")
	)
	(segment
		(start 349.439992 -228.954584)
		(end 349.429578 -228.948488)
		(width 0.0889)
		(layer "B.Cu")
		(net "TP_CPU0_IFST_KOT_LVC1_R")
	)
	(segment
		(start 335.70545 -229.122986)
		(end 334.88122 -229.122986)
		(width 0.0889)
		(layer "B.Cu")
		(net "TP_CPU0_IFST_KOT_LVC1_R")
	)
	(segment
		(start 343.805764 -228.957124)
		(end 343.791032 -228.948488)
		(width 0.0889)
		(layer "B.Cu")
		(net "TP_CPU0_IFST_KOT_LVC1_R")
	)
	(segment
		(start 350.557084 -229.28834)
		(end 350.557084 -229.272846)
		(width 0.0889)
		(layer "B.Cu")
		(net "TP_CPU0_IFST_KOT_LVC1_R")
	)
	(segment
		(start 353.47148 -231.714548)
		(end 353.315016 -231.44353)
		(width 0.0889)
		(layer "B.Cu")
		(net "TP_CPU0_IFST_KOT_LVC1_R")
	)
	(segment
		(start 344.745564 -228.957124)
		(end 344.730832 -228.948488)
		(width 0.0889)
		(layer "B.Cu")
		(net "TP_CPU0_IFST_KOT_LVC1_R")
	)
	(segment
		(start 330.813664 -228.88829)
		(end 330.402184 -228.47681)
		(width 0.12954)
		(layer "B.Cu")
		(net "TP_CPU0_IFST_KOT_LVC1_R")
	)
	(segment
		(start 338.166964 -228.957124)
		(end 338.152232 -228.948488)
		(width 0.0889)
		(layer "B.Cu")
		(net "TP_CPU0_IFST_KOT_LVC1_R")
	)
	(segment
		(start 348.500446 -228.954584)
		(end 348.490032 -228.948488)
		(width 0.0889)
		(layer "B.Cu")
		(net "TP_CPU0_IFST_KOT_LVC1_R")
	)
	(segment
		(start 341.921846 -228.954584)
		(end 341.911432 -228.948488)
		(width 0.0889)
		(layer "B.Cu")
		(net "TP_CPU0_IFST_KOT_LVC1_R")
	)
	(segment
		(start 350.848168 -229.767384)
		(end 350.839278 -229.762304)
		(width 0.0889)
		(layer "B.Cu")
		(net "TP_CPU0_IFST_KOT_LVC1_R")
	)
	(segment
		(start 334.646524 -228.88829)
		(end 332.144878 -228.88829)
		(width 0.0889)
		(layer "B.Cu")
		(net "TP_CPU0_IFST_KOT_LVC1_R")
	)
	(segment
		(start 353.315016 -231.44353)
		(end 353.226116 -231.419908)
		(width 0.0889)
		(layer "B.Cu")
		(net "TP_CPU0_IFST_KOT_LVC1_R")
	)
	(segment
		(start 336.287364 -228.957124)
		(end 336.272632 -228.948488)
		(width 0.0889)
		(layer "B.Cu")
		(net "TP_CPU0_IFST_KOT_LVC1_R")
	)
	(arc
		(start 346.610432 -228.948488)
		(mid 346.423234 -228.898345)
		(end 346.236036 -228.948488)
		(width 0.0889)
		(layer "B.Cu")
		(net "TP_CPU0_IFST_KOT_LVC1_R")
	)
	(arc
		(start 341.911432 -228.948488)
		(mid 341.724234 -228.898345)
		(end 341.537036 -228.948488)
		(width 0.0889)
		(layer "B.Cu")
		(net "TP_CPU0_IFST_KOT_LVC1_R")
	)
	(arc
		(start 352.32975 -231.398826)
		(mid 352.053309 -231.465992)
		(end 351.779078 -231.39019)
		(width 0.0889)
		(layer "B.Cu")
		(net "TP_CPU0_IFST_KOT_LVC1_R")
	)
	(arc
		(start 348.115636 -228.948488)
		(mid 347.841437 -229.024323)
		(end 347.564964 -228.957124)
		(width 0.0889)
		(layer "B.Cu")
		(net "TP_CPU0_IFST_KOT_LVC1_R")
	)
	(arc
		(start 345.296236 -228.948488)
		(mid 345.022037 -229.024323)
		(end 344.745564 -228.957124)
		(width 0.0889)
		(layer "B.Cu")
		(net "TP_CPU0_IFST_KOT_LVC1_R")
	)
	(arc
		(start 344.730832 -228.948488)
		(mid 344.543634 -228.898345)
		(end 344.356436 -228.948488)
		(width 0.0889)
		(layer "B.Cu")
		(net "TP_CPU0_IFST_KOT_LVC1_R")
	)
	(arc
		(start 347.175836 -228.948488)
		(mid 346.901637 -229.024323)
		(end 346.625164 -228.957124)
		(width 0.0889)
		(layer "B.Cu")
		(net "TP_CPU0_IFST_KOT_LVC1_R")
	)
	(arc
		(start 347.550232 -228.948488)
		(mid 347.363034 -228.898345)
		(end 347.175836 -228.948488)
		(width 0.0889)
		(layer "B.Cu")
		(net "TP_CPU0_IFST_KOT_LVC1_R")
	)
	(arc
		(start 335.898236 -228.948488)
		(mid 335.857427 -228.97566)
		(end 335.820512 -229.007924)
		(width 0.0889)
		(layer "B.Cu")
		(net "TP_CPU0_IFST_KOT_LVC1_R")
	)
	(arc
		(start 340.031832 -228.948488)
		(mid 339.844634 -228.898345)
		(end 339.657436 -228.948488)
		(width 0.0889)
		(layer "B.Cu")
		(net "TP_CPU0_IFST_KOT_LVC1_R")
	)
	(arc
		(start 349.429578 -228.948488)
		(mid 349.24238 -228.898345)
		(end 349.055182 -228.948488)
		(width 0.0889)
		(layer "B.Cu")
		(net "TP_CPU0_IFST_KOT_LVC1_R")
	)
	(arc
		(start 343.416636 -228.948488)
		(mid 343.139823 -229.024358)
		(end 342.861392 -228.954584)
		(width 0.0889)
		(layer "B.Cu")
		(net "TP_CPU0_IFST_KOT_LVC1_R")
	)
	(arc
		(start 341.537036 -228.948488)
		(mid 341.262837 -229.024323)
		(end 340.986364 -228.957124)
		(width 0.0889)
		(layer "B.Cu")
		(net "TP_CPU0_IFST_KOT_LVC1_R")
	)
	(arc
		(start 346.236036 -228.948488)
		(mid 345.953334 -229.024264)
		(end 345.670632 -228.948488)
		(width 0.0889)
		(layer "B.Cu")
		(net "TP_CPU0_IFST_KOT_LVC1_R")
	)
	(arc
		(start 339.657436 -228.948488)
		(mid 339.374734 -229.024264)
		(end 339.092032 -228.948488)
		(width 0.0889)
		(layer "B.Cu")
		(net "TP_CPU0_IFST_KOT_LVC1_R")
	)
	(arc
		(start 344.356436 -228.948488)
		(mid 344.082237 -229.024323)
		(end 343.805764 -228.957124)
		(width 0.0889)
		(layer "B.Cu")
		(net "TP_CPU0_IFST_KOT_LVC1_R")
	)
	(arc
		(start 349.995236 -228.948488)
		(mid 349.718423 -229.024358)
		(end 349.439992 -228.954584)
		(width 0.0889)
		(layer "B.Cu")
		(net "TP_CPU0_IFST_KOT_LVC1_R")
	)
	(arc
		(start 352.718878 -231.39019)
		(mid 352.53168 -231.340047)
		(end 352.344482 -231.39019)
		(width 0.0889)
		(layer "B.Cu")
		(net "TP_CPU0_IFST_KOT_LVC1_R")
	)
	(arc
		(start 342.476582 -228.948488)
		(mid 342.200023 -229.024231)
		(end 341.921846 -228.954584)
		(width 0.0889)
		(layer "B.Cu")
		(net "TP_CPU0_IFST_KOT_LVC1_R")
	)
	(arc
		(start 350.839278 -229.762304)
		(mid 350.636455 -229.562073)
		(end 350.557084 -229.28834)
		(width 0.0889)
		(layer "B.Cu")
		(net "TP_CPU0_IFST_KOT_LVC1_R")
	)
	(arc
		(start 337.777836 -228.948488)
		(mid 337.503637 -229.024323)
		(end 337.227164 -228.957124)
		(width 0.0889)
		(layer "B.Cu")
		(net "TP_CPU0_IFST_KOT_LVC1_R")
	)
	(arc
		(start 338.717636 -228.948488)
		(mid 338.443437 -229.024323)
		(end 338.166964 -228.957124)
		(width 0.0889)
		(layer "B.Cu")
		(net "TP_CPU0_IFST_KOT_LVC1_R")
	)
	(arc
		(start 351.02673 -230.086662)
		(mid 350.979051 -229.903762)
		(end 350.848168 -229.767384)
		(width 0.0889)
		(layer "B.Cu")
		(net "TP_CPU0_IFST_KOT_LVC1_R")
	)
	(arc
		(start 340.971632 -228.948488)
		(mid 340.784434 -228.898345)
		(end 340.597236 -228.948488)
		(width 0.0889)
		(layer "B.Cu")
		(net "TP_CPU0_IFST_KOT_LVC1_R")
	)
	(arc
		(start 343.791032 -228.948488)
		(mid 343.603834 -228.898345)
		(end 343.416636 -228.948488)
		(width 0.0889)
		(layer "B.Cu")
		(net "TP_CPU0_IFST_KOT_LVC1_R")
	)
	(arc
		(start 342.850978 -228.948488)
		(mid 342.66378 -228.898345)
		(end 342.476582 -228.948488)
		(width 0.0889)
		(layer "B.Cu")
		(net "TP_CPU0_IFST_KOT_LVC1_R")
	)
	(arc
		(start 340.597236 -228.948488)
		(mid 340.323037 -229.024323)
		(end 340.046564 -228.957124)
		(width 0.0889)
		(layer "B.Cu")
		(net "TP_CPU0_IFST_KOT_LVC1_R")
	)
	(arc
		(start 348.490032 -228.948488)
		(mid 348.302834 -228.898345)
		(end 348.115636 -228.948488)
		(width 0.0889)
		(layer "B.Cu")
		(net "TP_CPU0_IFST_KOT_LVC1_R")
	)
	(arc
		(start 349.055182 -228.948488)
		(mid 348.778623 -229.024231)
		(end 348.500446 -228.954584)
		(width 0.0889)
		(layer "B.Cu")
		(net "TP_CPU0_IFST_KOT_LVC1_R")
	)
	(arc
		(start 336.838036 -228.948488)
		(mid 336.563837 -229.024323)
		(end 336.287364 -228.957124)
		(width 0.0889)
		(layer "B.Cu")
		(net "TP_CPU0_IFST_KOT_LVC1_R")
	)
	(arc
		(start 351.779078 -231.39019)
		(mid 351.577796 -231.192703)
		(end 351.496884 -230.922576)
		(width 0.0889)
		(layer "B.Cu")
		(net "TP_CPU0_IFST_KOT_LVC1_R")
	)
	(arc
		(start 345.670632 -228.948488)
		(mid 345.483434 -228.898345)
		(end 345.296236 -228.948488)
		(width 0.0889)
		(layer "B.Cu")
		(net "TP_CPU0_IFST_KOT_LVC1_R")
	)
	(arc
		(start 339.092032 -228.948488)
		(mid 338.904834 -228.898345)
		(end 338.717636 -228.948488)
		(width 0.0889)
		(layer "B.Cu")
		(net "TP_CPU0_IFST_KOT_LVC1_R")
	)
	(arc
		(start 353.226116 -231.419908)
		(mid 352.968977 -231.46519)
		(end 352.718878 -231.39019)
		(width 0.0889)
		(layer "B.Cu")
		(net "TP_CPU0_IFST_KOT_LVC1_R")
	)
	(arc
		(start 350.557084 -229.272846)
		(mid 350.509405 -229.089946)
		(end 350.378522 -228.953568)
		(width 0.0889)
		(layer "B.Cu")
		(net "TP_CPU0_IFST_KOT_LVC1_R")
	)
	(arc
		(start 338.152232 -228.948488)
		(mid 337.965034 -228.898345)
		(end 337.777836 -228.948488)
		(width 0.0889)
		(layer "B.Cu")
		(net "TP_CPU0_IFST_KOT_LVC1_R")
	)
	(arc
		(start 351.496884 -230.900478)
		(mid 351.449205 -230.717578)
		(end 351.318322 -230.5812)
		(width 0.0889)
		(layer "B.Cu")
		(net "TP_CPU0_IFST_KOT_LVC1_R")
	)
	(arc
		(start 336.272632 -228.948488)
		(mid 336.085434 -228.898345)
		(end 335.898236 -228.948488)
		(width 0.0889)
		(layer "B.Cu")
		(net "TP_CPU0_IFST_KOT_LVC1_R")
	)
	(arc
		(start 350.369632 -228.948488)
		(mid 350.182434 -228.898345)
		(end 349.995236 -228.948488)
		(width 0.0889)
		(layer "B.Cu")
		(net "TP_CPU0_IFST_KOT_LVC1_R")
	)
	(arc
		(start 337.212432 -228.948488)
		(mid 337.025234 -228.898345)
		(end 336.838036 -228.948488)
		(width 0.0889)
		(layer "B.Cu")
		(net "TP_CPU0_IFST_KOT_LVC1_R")
	)
	(arc
		(start 351.303336 -230.572564)
		(mid 351.100749 -230.366213)
		(end 351.02673 -230.086662)
		(width 0.0889)
		(layer "B.Cu")
		(net "TP_CPU0_IFST_KOT_LVC1_R")
	)
	(segment
		(start 352.53168 -232.250234)
		(end 352.53168 -231.714548)
		(width 0.12954)
		(layer "F.Cu")
		(net "TP_CPU0_IFST_DONE_LVC1_R")
	)
	(segment
		(start 352.531934 -232.250488)
		(end 352.53168 -232.250234)
		(width 0.12954)
		(layer "F.Cu")
		(net "TP_CPU0_IFST_DONE_LVC1_R")
	)
	(via
		(at 322.936108 -229.819454)
		(size 0.6604)
		(drill 0.3302)
		(layers "F.Cu" "B.Cu")
		(net "TP_CPU0_IFST_DONE_LVC1_R")
	)
	(via
		(at 352.53168 -231.714548)
		(size 0.4572)
		(drill 0.2032)
		(layers "F.Cu" "B.Cu")
		(net "TP_CPU0_IFST_DONE_LVC1_R")
	)
	(segment
		(start 338.162646 -231.21874)
		(end 338.152232 -231.224836)
		(width 0.0889)
		(layer "B.Cu")
		(net "TP_CPU0_IFST_DONE_LVC1_R")
	)
	(segment
		(start 351.404682 -232.038906)
		(end 351.38995 -232.03027)
		(width 0.0889)
		(layer "B.Cu")
		(net "TP_CPU0_IFST_DONE_LVC1_R")
	)
	(segment
		(start 349.444564 -231.2162)
		(end 349.429832 -231.224836)
		(width 0.0889)
		(layer "B.Cu")
		(net "TP_CPU0_IFST_DONE_LVC1_R")
	)
	(segment
		(start 342.865964 -231.2162)
		(end 342.851232 -231.224836)
		(width 0.0889)
		(layer "B.Cu")
		(net "TP_CPU0_IFST_DONE_LVC1_R")
	)
	(segment
		(start 340.986364 -231.2162)
		(end 340.971632 -231.224836)
		(width 0.0889)
		(layer "B.Cu")
		(net "TP_CPU0_IFST_DONE_LVC1_R")
	)
	(segment
		(start 352.53168 -231.714548)
		(end 352.001836 -231.966262)
		(width 0.0889)
		(layer "B.Cu")
		(net "TP_CPU0_IFST_DONE_LVC1_R")
	)
	(segment
		(start 334.158844 -231.149144)
		(end 334.057498 -231.25049)
		(width 0.0889)
		(layer "B.Cu")
		(net "TP_CPU0_IFST_DONE_LVC1_R")
	)
	(segment
		(start 337.227164 -231.2162)
		(end 337.212432 -231.224836)
		(width 0.0889)
		(layer "B.Cu")
		(net "TP_CPU0_IFST_DONE_LVC1_R")
	)
	(segment
		(start 339.102192 -231.21874)
		(end 339.091778 -231.224836)
		(width 0.0889)
		(layer "B.Cu")
		(net "TP_CPU0_IFST_DONE_LVC1_R")
	)
	(segment
		(start 336.287364 -231.2162)
		(end 336.272632 -231.224836)
		(width 0.0889)
		(layer "B.Cu")
		(net "TP_CPU0_IFST_DONE_LVC1_R")
	)
	(segment
		(start 340.046564 -231.2162)
		(end 340.031832 -231.224836)
		(width 0.0889)
		(layer "B.Cu")
		(net "TP_CPU0_IFST_DONE_LVC1_R")
	)
	(segment
		(start 347.564964 -231.2162)
		(end 347.550232 -231.224836)
		(width 0.0889)
		(layer "B.Cu")
		(net "TP_CPU0_IFST_DONE_LVC1_R")
	)
	(segment
		(start 350.27743 -231.714548)
		(end 350.27743 -231.69245)
		(width 0.0889)
		(layer "B.Cu")
		(net "TP_CPU0_IFST_DONE_LVC1_R")
	)
	(segment
		(start 335.615534 -231.149144)
		(end 334.158844 -231.149144)
		(width 0.0889)
		(layer "B.Cu")
		(net "TP_CPU0_IFST_DONE_LVC1_R")
	)
	(segment
		(start 345.680792 -231.21874)
		(end 345.670378 -231.224836)
		(width 0.0889)
		(layer "B.Cu")
		(net "TP_CPU0_IFST_DONE_LVC1_R")
	)
	(segment
		(start 343.805764 -231.2162)
		(end 343.791032 -231.224836)
		(width 0.0889)
		(layer "B.Cu")
		(net "TP_CPU0_IFST_DONE_LVC1_R")
	)
	(segment
		(start 333.714598 -231.25049)
		(end 324.367144 -231.25049)
		(width 0.12954)
		(layer "B.Cu")
		(net "TP_CPU0_IFST_DONE_LVC1_R")
	)
	(segment
		(start 324.367144 -231.25049)
		(end 322.936108 -229.819454)
		(width 0.12954)
		(layer "B.Cu")
		(net "TP_CPU0_IFST_DONE_LVC1_R")
	)
	(segment
		(start 344.741246 -231.21874)
		(end 344.730832 -231.224836)
		(width 0.0889)
		(layer "B.Cu")
		(net "TP_CPU0_IFST_DONE_LVC1_R")
	)
	(segment
		(start 346.625164 -231.2162)
		(end 346.610432 -231.224836)
		(width 0.0889)
		(layer "B.Cu")
		(net "TP_CPU0_IFST_DONE_LVC1_R")
	)
	(segment
		(start 334.057498 -231.25049)
		(end 333.714598 -231.25049)
		(width 0.0889)
		(layer "B.Cu")
		(net "TP_CPU0_IFST_DONE_LVC1_R")
	)
	(arc
		(start 335.898236 -231.224836)
		(mid 335.76187 -231.168358)
		(end 335.615534 -231.149144)
		(width 0.0889)
		(layer "B.Cu")
		(net "TP_CPU0_IFST_DONE_LVC1_R")
	)
	(arc
		(start 348.115636 -231.224836)
		(mid 347.841407 -231.148911)
		(end 347.564964 -231.2162)
		(width 0.0889)
		(layer "B.Cu")
		(net "TP_CPU0_IFST_DONE_LVC1_R")
	)
	(arc
		(start 351.38995 -232.03027)
		(mid 351.113475 -231.96295)
		(end 350.839278 -232.038906)
		(width 0.0889)
		(layer "B.Cu")
		(net "TP_CPU0_IFST_DONE_LVC1_R")
	)
	(arc
		(start 337.212432 -231.224836)
		(mid 337.025234 -231.274979)
		(end 336.838036 -231.224836)
		(width 0.0889)
		(layer "B.Cu")
		(net "TP_CPU0_IFST_DONE_LVC1_R")
	)
	(arc
		(start 340.031832 -231.224836)
		(mid 339.844634 -231.274979)
		(end 339.657436 -231.224836)
		(width 0.0889)
		(layer "B.Cu")
		(net "TP_CPU0_IFST_DONE_LVC1_R")
	)
	(arc
		(start 336.272632 -231.224836)
		(mid 336.085434 -231.274979)
		(end 335.898236 -231.224836)
		(width 0.0889)
		(layer "B.Cu")
		(net "TP_CPU0_IFST_DONE_LVC1_R")
	)
	(arc
		(start 347.550232 -231.224836)
		(mid 347.363034 -231.274979)
		(end 347.175836 -231.224836)
		(width 0.0889)
		(layer "B.Cu")
		(net "TP_CPU0_IFST_DONE_LVC1_R")
	)
	(arc
		(start 339.091778 -231.224836)
		(mid 338.90458 -231.274979)
		(end 338.717382 -231.224836)
		(width 0.0889)
		(layer "B.Cu")
		(net "TP_CPU0_IFST_DONE_LVC1_R")
	)
	(arc
		(start 336.838036 -231.224836)
		(mid 336.563807 -231.148911)
		(end 336.287364 -231.2162)
		(width 0.0889)
		(layer "B.Cu")
		(net "TP_CPU0_IFST_DONE_LVC1_R")
	)
	(arc
		(start 349.429832 -231.224836)
		(mid 349.242634 -231.274979)
		(end 349.055436 -231.224836)
		(width 0.0889)
		(layer "B.Cu")
		(net "TP_CPU0_IFST_DONE_LVC1_R")
	)
	(arc
		(start 352.001836 -231.966262)
		(mid 351.886662 -231.990938)
		(end 351.779078 -232.038906)
		(width 0.0889)
		(layer "B.Cu")
		(net "TP_CPU0_IFST_DONE_LVC1_R")
	)
	(arc
		(start 350.27743 -231.69245)
		(mid 349.992999 -231.223549)
		(end 349.444564 -231.2162)
		(width 0.0889)
		(layer "B.Cu")
		(net "TP_CPU0_IFST_DONE_LVC1_R")
	)
	(arc
		(start 351.779078 -232.038906)
		(mid 351.59188 -232.089049)
		(end 351.404682 -232.038906)
		(width 0.0889)
		(layer "B.Cu")
		(net "TP_CPU0_IFST_DONE_LVC1_R")
	)
	(arc
		(start 342.476836 -231.224836)
		(mid 342.194134 -231.149094)
		(end 341.911432 -231.224836)
		(width 0.0889)
		(layer "B.Cu")
		(net "TP_CPU0_IFST_DONE_LVC1_R")
	)
	(arc
		(start 340.971632 -231.224836)
		(mid 340.784434 -231.274979)
		(end 340.597236 -231.224836)
		(width 0.0889)
		(layer "B.Cu")
		(net "TP_CPU0_IFST_DONE_LVC1_R")
	)
	(arc
		(start 349.055436 -231.224836)
		(mid 348.772734 -231.149094)
		(end 348.490032 -231.224836)
		(width 0.0889)
		(layer "B.Cu")
		(net "TP_CPU0_IFST_DONE_LVC1_R")
	)
	(arc
		(start 340.597236 -231.224836)
		(mid 340.323007 -231.148911)
		(end 340.046564 -231.2162)
		(width 0.0889)
		(layer "B.Cu")
		(net "TP_CPU0_IFST_DONE_LVC1_R")
	)
	(arc
		(start 338.152232 -231.224836)
		(mid 337.965034 -231.274979)
		(end 337.777836 -231.224836)
		(width 0.0889)
		(layer "B.Cu")
		(net "TP_CPU0_IFST_DONE_LVC1_R")
	)
	(arc
		(start 338.717382 -231.224836)
		(mid 338.440823 -231.149127)
		(end 338.162646 -231.21874)
		(width 0.0889)
		(layer "B.Cu")
		(net "TP_CPU0_IFST_DONE_LVC1_R")
	)
	(arc
		(start 343.416636 -231.224836)
		(mid 343.142407 -231.148911)
		(end 342.865964 -231.2162)
		(width 0.0889)
		(layer "B.Cu")
		(net "TP_CPU0_IFST_DONE_LVC1_R")
	)
	(arc
		(start 341.537036 -231.224836)
		(mid 341.262807 -231.148911)
		(end 340.986364 -231.2162)
		(width 0.0889)
		(layer "B.Cu")
		(net "TP_CPU0_IFST_DONE_LVC1_R")
	)
	(arc
		(start 342.851232 -231.224836)
		(mid 342.664034 -231.274979)
		(end 342.476836 -231.224836)
		(width 0.0889)
		(layer "B.Cu")
		(net "TP_CPU0_IFST_DONE_LVC1_R")
	)
	(arc
		(start 346.236036 -231.224836)
		(mid 345.959223 -231.149)
		(end 345.680792 -231.21874)
		(width 0.0889)
		(layer "B.Cu")
		(net "TP_CPU0_IFST_DONE_LVC1_R")
	)
	(arc
		(start 343.791032 -231.224836)
		(mid 343.603834 -231.274979)
		(end 343.416636 -231.224836)
		(width 0.0889)
		(layer "B.Cu")
		(net "TP_CPU0_IFST_DONE_LVC1_R")
	)
	(arc
		(start 344.730832 -231.224836)
		(mid 344.543634 -231.274979)
		(end 344.356436 -231.224836)
		(width 0.0889)
		(layer "B.Cu")
		(net "TP_CPU0_IFST_DONE_LVC1_R")
	)
	(arc
		(start 348.490032 -231.224836)
		(mid 348.302834 -231.274979)
		(end 348.115636 -231.224836)
		(width 0.0889)
		(layer "B.Cu")
		(net "TP_CPU0_IFST_DONE_LVC1_R")
	)
	(arc
		(start 346.610432 -231.224836)
		(mid 346.423234 -231.274979)
		(end 346.236036 -231.224836)
		(width 0.0889)
		(layer "B.Cu")
		(net "TP_CPU0_IFST_DONE_LVC1_R")
	)
	(arc
		(start 337.777836 -231.224836)
		(mid 337.503607 -231.148911)
		(end 337.227164 -231.2162)
		(width 0.0889)
		(layer "B.Cu")
		(net "TP_CPU0_IFST_DONE_LVC1_R")
	)
	(arc
		(start 350.839278 -232.038906)
		(mid 350.464803 -232.03886)
		(end 350.27743 -231.714548)
		(width 0.0889)
		(layer "B.Cu")
		(net "TP_CPU0_IFST_DONE_LVC1_R")
	)
	(arc
		(start 339.657436 -231.224836)
		(mid 339.380623 -231.149)
		(end 339.102192 -231.21874)
		(width 0.0889)
		(layer "B.Cu")
		(net "TP_CPU0_IFST_DONE_LVC1_R")
	)
	(arc
		(start 345.295982 -231.224836)
		(mid 345.019423 -231.149127)
		(end 344.741246 -231.21874)
		(width 0.0889)
		(layer "B.Cu")
		(net "TP_CPU0_IFST_DONE_LVC1_R")
	)
	(arc
		(start 347.175836 -231.224836)
		(mid 346.901607 -231.148911)
		(end 346.625164 -231.2162)
		(width 0.0889)
		(layer "B.Cu")
		(net "TP_CPU0_IFST_DONE_LVC1_R")
	)
	(arc
		(start 341.911432 -231.224836)
		(mid 341.724234 -231.274979)
		(end 341.537036 -231.224836)
		(width 0.0889)
		(layer "B.Cu")
		(net "TP_CPU0_IFST_DONE_LVC1_R")
	)
	(arc
		(start 344.356436 -231.224836)
		(mid 344.082207 -231.148911)
		(end 343.805764 -231.2162)
		(width 0.0889)
		(layer "B.Cu")
		(net "TP_CPU0_IFST_DONE_LVC1_R")
	)
	(arc
		(start 345.670378 -231.224836)
		(mid 345.48318 -231.274979)
		(end 345.295982 -231.224836)
		(width 0.0889)
		(layer "B.Cu")
		(net "TP_CPU0_IFST_DONE_LVC1_R")
	)
	(segment
		(start 353.471734 -230.086916)
		(end 353.47148 -230.086662)
		(width 0.12954)
		(layer "F.Cu")
		(net "TP_CPU0_DIE_HVM_EN_LVC1")
	)
	(segment
		(start 353.471734 -230.622602)
		(end 353.471734 -230.086916)
		(width 0.12954)
		(layer "F.Cu")
		(net "TP_CPU0_DIE_HVM_EN_LVC1")
	)
	(via
		(at 353.47148 -230.086662)
		(size 0.4572)
		(drill 0.2032)
		(layers "F.Cu" "B.Cu")
		(net "TP_CPU0_DIE_HVM_EN_LVC1")
	)
	(via
		(at 332.160118 -225.61931)
		(size 0.6604)
		(drill 0.3302)
		(layers "F.Cu" "B.Cu")
		(net "TP_CPU0_DIE_HVM_EN_LVC1")
	)
	(segment
		(start 333.000858 -226.28225)
		(end 332.897988 -226.17938)
		(width 0.0889)
		(layer "B.Cu")
		(net "TP_CPU0_DIE_HVM_EN_LVC1")
	)
	(segment
		(start 338.162646 -226.33559)
		(end 338.152232 -226.341686)
		(width 0.0889)
		(layer "B.Cu")
		(net "TP_CPU0_DIE_HVM_EN_LVC1")
	)
	(segment
		(start 350.470978 -227.159058)
		(end 350.464882 -227.155502)
		(width 0.0889)
		(layer "B.Cu")
		(net "TP_CPU0_DIE_HVM_EN_LVC1")
	)
	(segment
		(start 352.344482 -230.41102)
		(end 352.335592 -230.40594)
		(width 0.0889)
		(layer "B.Cu")
		(net "TP_CPU0_DIE_HVM_EN_LVC1")
	)
	(segment
		(start 350.935036 -227.969318)
		(end 350.926146 -227.964238)
		(width 0.0889)
		(layer "B.Cu")
		(net "TP_CPU0_DIE_HVM_EN_LVC1")
	)
	(segment
		(start 350.464882 -227.155502)
		(end 350.455992 -227.150422)
		(width 0.0889)
		(layer "B.Cu")
		(net "TP_CPU0_DIE_HVM_EN_LVC1")
	)
	(segment
		(start 336.287364 -226.33305)
		(end 336.272632 -226.341686)
		(width 0.0889)
		(layer "B.Cu")
		(net "TP_CPU0_DIE_HVM_EN_LVC1")
	)
	(segment
		(start 352.15703 -230.086662)
		(end 352.15703 -230.071168)
		(width 0.0889)
		(layer "B.Cu")
		(net "TP_CPU0_DIE_HVM_EN_LVC1")
	)
	(segment
		(start 339.657436 -226.341686)
		(end 339.647022 -226.33559)
		(width 0.0889)
		(layer "B.Cu")
		(net "TP_CPU0_DIE_HVM_EN_LVC1")
	)
	(segment
		(start 353.47148 -230.086662)
		(end 353.050094 -230.337106)
		(width 0.0889)
		(layer "B.Cu")
		(net "TP_CPU0_DIE_HVM_EN_LVC1")
	)
	(segment
		(start 351.21723 -228.45903)
		(end 351.21723 -228.436932)
		(width 0.0889)
		(layer "B.Cu")
		(net "TP_CPU0_DIE_HVM_EN_LVC1")
	)
	(segment
		(start 345.685364 -226.33305)
		(end 345.670632 -226.341686)
		(width 0.0889)
		(layer "B.Cu")
		(net "TP_CPU0_DIE_HVM_EN_LVC1")
	)
	(segment
		(start 332.720188 -226.17938)
		(end 332.160118 -225.61931)
		(width 0.12954)
		(layer "B.Cu")
		(net "TP_CPU0_DIE_HVM_EN_LVC1")
	)
	(segment
		(start 349.444564 -226.33305)
		(end 349.429832 -226.341686)
		(width 0.0889)
		(layer "B.Cu")
		(net "TP_CPU0_DIE_HVM_EN_LVC1")
	)
	(segment
		(start 344.745564 -226.33305)
		(end 344.730832 -226.341686)
		(width 0.0889)
		(layer "B.Cu")
		(net "TP_CPU0_DIE_HVM_EN_LVC1")
	)
	(segment
		(start 335.898236 -226.341686)
		(end 335.887822 -226.33559)
		(width 0.0889)
		(layer "B.Cu")
		(net "TP_CPU0_DIE_HVM_EN_LVC1")
	)
	(segment
		(start 351.874836 -229.597204)
		(end 351.865946 -229.592124)
		(width 0.0889)
		(layer "B.Cu")
		(net "TP_CPU0_DIE_HVM_EN_LVC1")
	)
	(segment
		(start 351.410778 -228.786944)
		(end 351.404682 -228.783388)
		(width 0.0889)
		(layer "B.Cu")
		(net "TP_CPU0_DIE_HVM_EN_LVC1")
	)
	(segment
		(start 337.227164 -226.33305)
		(end 337.212432 -226.341686)
		(width 0.0889)
		(layer "B.Cu")
		(net "TP_CPU0_DIE_HVM_EN_LVC1")
	)
	(segment
		(start 350.27743 -226.831144)
		(end 350.27743 -226.81565)
		(width 0.0889)
		(layer "B.Cu")
		(net "TP_CPU0_DIE_HVM_EN_LVC1")
	)
	(segment
		(start 342.865964 -226.33305)
		(end 342.851232 -226.341686)
		(width 0.0889)
		(layer "B.Cu")
		(net "TP_CPU0_DIE_HVM_EN_LVC1")
	)
	(segment
		(start 351.404682 -228.783388)
		(end 351.395792 -228.778308)
		(width 0.0889)
		(layer "B.Cu")
		(net "TP_CPU0_DIE_HVM_EN_LVC1")
	)
	(segment
		(start 334.403446 -226.33559)
		(end 334.393032 -226.341686)
		(width 0.0889)
		(layer "B.Cu")
		(net "TP_CPU0_DIE_HVM_EN_LVC1")
	)
	(segment
		(start 341.926164 -226.33305)
		(end 341.911432 -226.341686)
		(width 0.0889)
		(layer "B.Cu")
		(net "TP_CPU0_DIE_HVM_EN_LVC1")
	)
	(segment
		(start 334.018636 -226.341686)
		(end 334.008222 -226.33559)
		(width 0.0889)
		(layer "B.Cu")
		(net "TP_CPU0_DIE_HVM_EN_LVC1")
	)
	(segment
		(start 332.897988 -226.17938)
		(end 332.720188 -226.17938)
		(width 0.0889)
		(layer "B.Cu")
		(net "TP_CPU0_DIE_HVM_EN_LVC1")
	)
	(arc
		(start 350.27743 -226.81565)
		(mid 350.19806 -226.541916)
		(end 349.995236 -226.341686)
		(width 0.0889)
		(layer "B.Cu")
		(net "TP_CPU0_DIE_HVM_EN_LVC1")
	)
	(arc
		(start 348.115636 -226.341686)
		(mid 347.832934 -226.26591)
		(end 347.550232 -226.341686)
		(width 0.0889)
		(layer "B.Cu")
		(net "TP_CPU0_DIE_HVM_EN_LVC1")
	)
	(arc
		(start 352.718878 -230.41102)
		(mid 352.53168 -230.461163)
		(end 352.344482 -230.41102)
		(width 0.0889)
		(layer "B.Cu")
		(net "TP_CPU0_DIE_HVM_EN_LVC1")
	)
	(arc
		(start 335.332578 -226.341686)
		(mid 335.14538 -226.391829)
		(end 334.958182 -226.341686)
		(width 0.0889)
		(layer "B.Cu")
		(net "TP_CPU0_DIE_HVM_EN_LVC1")
	)
	(arc
		(start 339.091778 -226.341686)
		(mid 338.90458 -226.391829)
		(end 338.717382 -226.341686)
		(width 0.0889)
		(layer "B.Cu")
		(net "TP_CPU0_DIE_HVM_EN_LVC1")
	)
	(arc
		(start 345.296236 -226.341686)
		(mid 345.022037 -226.265851)
		(end 344.745564 -226.33305)
		(width 0.0889)
		(layer "B.Cu")
		(net "TP_CPU0_DIE_HVM_EN_LVC1")
	)
	(arc
		(start 337.777836 -226.341686)
		(mid 337.503637 -226.265851)
		(end 337.227164 -226.33305)
		(width 0.0889)
		(layer "B.Cu")
		(net "TP_CPU0_DIE_HVM_EN_LVC1")
	)
	(arc
		(start 340.031832 -226.341686)
		(mid 339.844634 -226.391829)
		(end 339.657436 -226.341686)
		(width 0.0889)
		(layer "B.Cu")
		(net "TP_CPU0_DIE_HVM_EN_LVC1")
	)
	(arc
		(start 340.971632 -226.341686)
		(mid 340.784434 -226.391829)
		(end 340.597236 -226.341686)
		(width 0.0889)
		(layer "B.Cu")
		(net "TP_CPU0_DIE_HVM_EN_LVC1")
	)
	(arc
		(start 349.055436 -226.341686)
		(mid 348.772734 -226.26591)
		(end 348.490032 -226.341686)
		(width 0.0889)
		(layer "B.Cu")
		(net "TP_CPU0_DIE_HVM_EN_LVC1")
	)
	(arc
		(start 344.730832 -226.341686)
		(mid 344.543634 -226.391829)
		(end 344.356436 -226.341686)
		(width 0.0889)
		(layer "B.Cu")
		(net "TP_CPU0_DIE_HVM_EN_LVC1")
	)
	(arc
		(start 338.152232 -226.341686)
		(mid 337.965034 -226.391829)
		(end 337.777836 -226.341686)
		(width 0.0889)
		(layer "B.Cu")
		(net "TP_CPU0_DIE_HVM_EN_LVC1")
	)
	(arc
		(start 334.008222 -226.33559)
		(mid 333.72979 -226.265744)
		(end 333.452978 -226.341686)
		(width 0.0889)
		(layer "B.Cu")
		(net "TP_CPU0_DIE_HVM_EN_LVC1")
	)
	(arc
		(start 349.429832 -226.341686)
		(mid 349.242634 -226.391829)
		(end 349.055436 -226.341686)
		(width 0.0889)
		(layer "B.Cu")
		(net "TP_CPU0_DIE_HVM_EN_LVC1")
	)
	(arc
		(start 348.490032 -226.341686)
		(mid 348.302834 -226.391829)
		(end 348.115636 -226.341686)
		(width 0.0889)
		(layer "B.Cu")
		(net "TP_CPU0_DIE_HVM_EN_LVC1")
	)
	(arc
		(start 351.865946 -229.592124)
		(mid 351.735032 -229.455764)
		(end 351.687384 -229.272846)
		(width 0.0889)
		(layer "B.Cu")
		(net "TP_CPU0_DIE_HVM_EN_LVC1")
	)
	(arc
		(start 346.236036 -226.341686)
		(mid 345.961837 -226.265851)
		(end 345.685364 -226.33305)
		(width 0.0889)
		(layer "B.Cu")
		(net "TP_CPU0_DIE_HVM_EN_LVC1")
	)
	(arc
		(start 344.356436 -226.341686)
		(mid 344.073734 -226.26591)
		(end 343.791032 -226.341686)
		(width 0.0889)
		(layer "B.Cu")
		(net "TP_CPU0_DIE_HVM_EN_LVC1")
	)
	(arc
		(start 337.212432 -226.341686)
		(mid 337.025234 -226.391829)
		(end 336.838036 -226.341686)
		(width 0.0889)
		(layer "B.Cu")
		(net "TP_CPU0_DIE_HVM_EN_LVC1")
	)
	(arc
		(start 350.747584 -227.64496)
		(mid 350.673593 -227.365394)
		(end 350.470978 -227.159058)
		(width 0.0889)
		(layer "B.Cu")
		(net "TP_CPU0_DIE_HVM_EN_LVC1")
	)
	(arc
		(start 342.476836 -226.341686)
		(mid 342.202637 -226.265851)
		(end 341.926164 -226.33305)
		(width 0.0889)
		(layer "B.Cu")
		(net "TP_CPU0_DIE_HVM_EN_LVC1")
	)
	(arc
		(start 350.926146 -227.964238)
		(mid 350.795232 -227.827878)
		(end 350.747584 -227.64496)
		(width 0.0889)
		(layer "B.Cu")
		(net "TP_CPU0_DIE_HVM_EN_LVC1")
	)
	(arc
		(start 346.610432 -226.341686)
		(mid 346.423234 -226.391829)
		(end 346.236036 -226.341686)
		(width 0.0889)
		(layer "B.Cu")
		(net "TP_CPU0_DIE_HVM_EN_LVC1")
	)
	(arc
		(start 340.597236 -226.341686)
		(mid 340.314534 -226.26591)
		(end 340.031832 -226.341686)
		(width 0.0889)
		(layer "B.Cu")
		(net "TP_CPU0_DIE_HVM_EN_LVC1")
	)
	(arc
		(start 343.791032 -226.341686)
		(mid 343.603834 -226.391829)
		(end 343.416636 -226.341686)
		(width 0.0889)
		(layer "B.Cu")
		(net "TP_CPU0_DIE_HVM_EN_LVC1")
	)
	(arc
		(start 350.455992 -227.150422)
		(mid 350.325078 -227.014062)
		(end 350.27743 -226.831144)
		(width 0.0889)
		(layer "B.Cu")
		(net "TP_CPU0_DIE_HVM_EN_LVC1")
	)
	(arc
		(start 351.687384 -229.272846)
		(mid 351.613393 -228.99328)
		(end 351.410778 -228.786944)
		(width 0.0889)
		(layer "B.Cu")
		(net "TP_CPU0_DIE_HVM_EN_LVC1")
	)
	(arc
		(start 336.838036 -226.341686)
		(mid 336.563837 -226.265851)
		(end 336.287364 -226.33305)
		(width 0.0889)
		(layer "B.Cu")
		(net "TP_CPU0_DIE_HVM_EN_LVC1")
	)
	(arc
		(start 333.078582 -226.341686)
		(mid 333.037773 -226.314514)
		(end 333.000858 -226.28225)
		(width 0.0889)
		(layer "B.Cu")
		(net "TP_CPU0_DIE_HVM_EN_LVC1")
	)
	(arc
		(start 347.175836 -226.341686)
		(mid 346.893134 -226.26591)
		(end 346.610432 -226.341686)
		(width 0.0889)
		(layer "B.Cu")
		(net "TP_CPU0_DIE_HVM_EN_LVC1")
	)
	(arc
		(start 335.887822 -226.33559)
		(mid 335.60939 -226.265744)
		(end 335.332578 -226.341686)
		(width 0.0889)
		(layer "B.Cu")
		(net "TP_CPU0_DIE_HVM_EN_LVC1")
	)
	(arc
		(start 342.851232 -226.341686)
		(mid 342.664034 -226.391829)
		(end 342.476836 -226.341686)
		(width 0.0889)
		(layer "B.Cu")
		(net "TP_CPU0_DIE_HVM_EN_LVC1")
	)
	(arc
		(start 353.050094 -230.337106)
		(mid 352.878796 -230.348592)
		(end 352.718878 -230.41102)
		(width 0.0889)
		(layer "B.Cu")
		(net "TP_CPU0_DIE_HVM_EN_LVC1")
	)
	(arc
		(start 338.717382 -226.341686)
		(mid 338.440823 -226.265943)
		(end 338.162646 -226.33559)
		(width 0.0889)
		(layer "B.Cu")
		(net "TP_CPU0_DIE_HVM_EN_LVC1")
	)
	(arc
		(start 352.335592 -230.40594)
		(mid 352.204678 -230.26958)
		(end 352.15703 -230.086662)
		(width 0.0889)
		(layer "B.Cu")
		(net "TP_CPU0_DIE_HVM_EN_LVC1")
	)
	(arc
		(start 341.911432 -226.341686)
		(mid 341.724234 -226.391829)
		(end 341.537036 -226.341686)
		(width 0.0889)
		(layer "B.Cu")
		(net "TP_CPU0_DIE_HVM_EN_LVC1")
	)
	(arc
		(start 336.272632 -226.341686)
		(mid 336.085434 -226.391829)
		(end 335.898236 -226.341686)
		(width 0.0889)
		(layer "B.Cu")
		(net "TP_CPU0_DIE_HVM_EN_LVC1")
	)
	(arc
		(start 352.15703 -230.071168)
		(mid 352.07766 -229.797434)
		(end 351.874836 -229.597204)
		(width 0.0889)
		(layer "B.Cu")
		(net "TP_CPU0_DIE_HVM_EN_LVC1")
	)
	(arc
		(start 339.647022 -226.33559)
		(mid 339.36859 -226.265744)
		(end 339.091778 -226.341686)
		(width 0.0889)
		(layer "B.Cu")
		(net "TP_CPU0_DIE_HVM_EN_LVC1")
	)
	(arc
		(start 343.416636 -226.341686)
		(mid 343.142437 -226.265851)
		(end 342.865964 -226.33305)
		(width 0.0889)
		(layer "B.Cu")
		(net "TP_CPU0_DIE_HVM_EN_LVC1")
	)
	(arc
		(start 349.995236 -226.341686)
		(mid 349.721037 -226.265851)
		(end 349.444564 -226.33305)
		(width 0.0889)
		(layer "B.Cu")
		(net "TP_CPU0_DIE_HVM_EN_LVC1")
	)
	(arc
		(start 333.452978 -226.341686)
		(mid 333.26578 -226.391829)
		(end 333.078582 -226.341686)
		(width 0.0889)
		(layer "B.Cu")
		(net "TP_CPU0_DIE_HVM_EN_LVC1")
	)
	(arc
		(start 347.550232 -226.341686)
		(mid 347.363034 -226.391829)
		(end 347.175836 -226.341686)
		(width 0.0889)
		(layer "B.Cu")
		(net "TP_CPU0_DIE_HVM_EN_LVC1")
	)
	(arc
		(start 341.537036 -226.341686)
		(mid 341.254334 -226.26591)
		(end 340.971632 -226.341686)
		(width 0.0889)
		(layer "B.Cu")
		(net "TP_CPU0_DIE_HVM_EN_LVC1")
	)
	(arc
		(start 351.21723 -228.436932)
		(mid 351.136319 -228.166804)
		(end 350.935036 -227.969318)
		(width 0.0889)
		(layer "B.Cu")
		(net "TP_CPU0_DIE_HVM_EN_LVC1")
	)
	(arc
		(start 334.393032 -226.341686)
		(mid 334.205834 -226.391829)
		(end 334.018636 -226.341686)
		(width 0.0889)
		(layer "B.Cu")
		(net "TP_CPU0_DIE_HVM_EN_LVC1")
	)
	(arc
		(start 351.395792 -228.778308)
		(mid 351.264878 -228.641948)
		(end 351.21723 -228.45903)
		(width 0.0889)
		(layer "B.Cu")
		(net "TP_CPU0_DIE_HVM_EN_LVC1")
	)
	(arc
		(start 334.958182 -226.341686)
		(mid 334.681623 -226.265943)
		(end 334.403446 -226.33559)
		(width 0.0889)
		(layer "B.Cu")
		(net "TP_CPU0_DIE_HVM_EN_LVC1")
	)
	(arc
		(start 345.670632 -226.341686)
		(mid 345.483434 -226.391829)
		(end 345.296236 -226.341686)
		(width 0.0889)
		(layer "B.Cu")
		(net "TP_CPU0_DIE_HVM_EN_LVC1")
	)
	(segment
		(start 336.08518 -223.297242)
		(end 336.08518 -222.76181)
		(width 0.12954)
		(layer "F.Cu")
		(net "TP_CPU0_A0_DEBUG_EN")
	)
	(segment
		(start 336.085434 -223.297496)
		(end 336.08518 -223.297242)
		(width 0.12954)
		(layer "F.Cu")
		(net "TP_CPU0_A0_DEBUG_EN")
	)
	(segment
		(start 336.08518 -222.76181)
		(end 336.085434 -222.761556)
		(width 0.12954)
		(layer "F.Cu")
		(net "TP_CPU0_A0_DEBUG_EN")
	)
	(via
		(at 336.085434 -222.761556)
		(size 0.4572)
		(drill 0.2032)
		(layers "F.Cu" "B.Cu")
		(net "TP_CPU0_A0_DEBUG_EN")
	)
	(via
		(at 333.097378 -220.48597)
		(size 0.6604)
		(drill 0.3302)
		(layers "F.Cu" "B.Cu")
		(net "TP_CPU0_A0_DEBUG_EN")
	)
	(segment
		(start 335.790794 -222.761556)
		(end 335.382108 -222.35287)
		(width 0.12954)
		(layer "B.Cu")
		(net "TP_CPU0_A0_DEBUG_EN")
	)
	(segment
		(start 334.296258 -222.35287)
		(end 333.097378 -221.15399)
		(width 0.12954)
		(layer "B.Cu")
		(net "TP_CPU0_A0_DEBUG_EN")
	)
	(segment
		(start 336.085434 -222.761556)
		(end 335.790794 -222.761556)
		(width 0.12954)
		(layer "B.Cu")
		(net "TP_CPU0_A0_DEBUG_EN")
	)
	(segment
		(start 335.382108 -222.35287)
		(end 334.296258 -222.35287)
		(width 0.12954)
		(layer "B.Cu")
		(net "TP_CPU0_A0_DEBUG_EN")
	)
	(segment
		(start 333.097378 -221.15399)
		(end 333.097378 -220.48597)
		(width 0.12954)
		(layer "B.Cu")
		(net "TP_CPU0_A0_DEBUG_EN")
	)
	(segment
		(start 251.074428 -99.313238)
		(end 250.901454 -99.140264)
		(width 0.1143)
		(layer "F.Cu")
		(net "TP_CLK_PFT_IN_DP")
	)
	(segment
		(start 250.226322 -99.140264)
		(end 250.06046 -99.306126)
		(width 0.1143)
		(layer "F.Cu")
		(net "TP_CLK_PFT_IN_DP")
	)
	(segment
		(start 251.807726 -99.313238)
		(end 251.074428 -99.313238)
		(width 0.1143)
		(layer "F.Cu")
		(net "TP_CLK_PFT_IN_DP")
	)
	(segment
		(start 250.901454 -99.140264)
		(end 250.226322 -99.140264)
		(width 0.1143)
		(layer "F.Cu")
		(net "TP_CLK_PFT_IN_DP")
	)
	(segment
		(start 250.06046 -99.578668)
		(end 249.92838 -99.710748)
		(width 0.1143)
		(layer "F.Cu")
		(net "TP_CLK_PFT_IN_DP")
	)
	(segment
		(start 250.06046 -99.306126)
		(end 250.06046 -99.578668)
		(width 0.1143)
		(layer "F.Cu")
		(net "TP_CLK_PFT_IN_DP")
	)
	(via
		(at 249.92838 -99.710748)
		(size 0.762)
		(drill 0.254)
		(layers "F.Cu" "B.Cu")
		(net "TP_CLK_PFT_IN_DP")
	)
	(segment
		(start 248.376694 -99.618292)
		(end 247.85447 -99.618292)
		(width 0.1143)
		(layer "F.Cu")
		(net "TP_CLK_PFT_IN_DN")
	)
	(segment
		(start 249.950478 -98.704908)
		(end 249.749818 -98.905568)
		(width 0.1143)
		(layer "F.Cu")
		(net "TP_CLK_PFT_IN_DN")
	)
	(segment
		(start 249.089418 -98.905568)
		(end 248.376694 -99.618292)
		(width 0.1143)
		(layer "F.Cu")
		(net "TP_CLK_PFT_IN_DN")
	)
	(segment
		(start 251.807726 -98.813112)
		(end 251.22632 -98.813112)
		(width 0.1143)
		(layer "F.Cu")
		(net "TP_CLK_PFT_IN_DN")
	)
	(segment
		(start 251.118116 -98.704908)
		(end 249.950478 -98.704908)
		(width 0.1143)
		(layer "F.Cu")
		(net "TP_CLK_PFT_IN_DN")
	)
	(segment
		(start 251.22632 -98.813112)
		(end 251.118116 -98.704908)
		(width 0.1143)
		(layer "F.Cu")
		(net "TP_CLK_PFT_IN_DN")
	)
	(segment
		(start 249.749818 -98.905568)
		(end 249.089418 -98.905568)
		(width 0.1143)
		(layer "F.Cu")
		(net "TP_CLK_PFT_IN_DN")
	)
	(segment
		(start 247.85447 -99.618292)
		(end 247.82018 -99.584002)
		(width 0.1143)
		(layer "F.Cu")
		(net "TP_CLK_PFT_IN_DN")
	)
	(via
		(at 247.82018 -99.584002)
		(size 0.508)
		(drill 0.254)
		(layers "F.Cu" "B.Cu")
		(net "TP_CLK_PFT_IN_DN")
	)
	(segment
		(start 250.137168 -100.531168)
		(end 249.3518 -100.531168)
		(width 0.1143)
		(layer "F.Cu")
		(net "TP_CLK_CK440_PFT_OUT_DP")
	)
	(segment
		(start 249.3518 -100.531168)
		(end 248.807986 -101.074982)
		(width 0.1143)
		(layer "F.Cu")
		(net "TP_CLK_CK440_PFT_OUT_DP")
	)
	(segment
		(start 251.807726 -100.313236)
		(end 250.663964 -100.313236)
		(width 0.1143)
		(layer "F.Cu")
		(net "TP_CLK_CK440_PFT_OUT_DP")
	)
	(segment
		(start 248.807986 -101.074982)
		(end 248.807986 -101.437948)
		(width 0.1143)
		(layer "F.Cu")
		(net "TP_CLK_CK440_PFT_OUT_DP")
	)
	(segment
		(start 250.663964 -100.313236)
		(end 250.137168 -100.531168)
		(width 0.1143)
		(layer "F.Cu")
		(net "TP_CLK_CK440_PFT_OUT_DP")
	)
	(via
		(at 248.807986 -101.437948)
		(size 0.762)
		(drill 0.254)
		(layers "F.Cu" "B.Cu")
		(net "TP_CLK_CK440_PFT_OUT_DP")
	)
	(segment
		(start 250.57989 -100.025708)
		(end 250.015502 -100.259388)
		(width 0.1143)
		(layer "F.Cu")
		(net "TP_CLK_CK440_PFT_OUT_DN")
	)
	(segment
		(start 251.807726 -99.81311)
		(end 251.432568 -99.81311)
		(width 0.1143)
		(layer "F.Cu")
		(net "TP_CLK_CK440_PFT_OUT_DN")
	)
	(segment
		(start 248.09196 -100.259388)
		(end 247.73382 -100.617528)
		(width 0.1143)
		(layer "F.Cu")
		(net "TP_CLK_CK440_PFT_OUT_DN")
	)
	(segment
		(start 251.432568 -99.81311)
		(end 251.21997 -100.025708)
		(width 0.1143)
		(layer "F.Cu")
		(net "TP_CLK_CK440_PFT_OUT_DN")
	)
	(segment
		(start 250.015502 -100.259388)
		(end 248.09196 -100.259388)
		(width 0.1143)
		(layer "F.Cu")
		(net "TP_CLK_CK440_PFT_OUT_DN")
	)
	(segment
		(start 251.21997 -100.025708)
		(end 250.57989 -100.025708)
		(width 0.1143)
		(layer "F.Cu")
		(net "TP_CLK_CK440_PFT_OUT_DN")
	)
	(via
		(at 247.73382 -100.617528)
		(size 0.762)
		(drill 0.381)
		(layers "F.Cu" "B.Cu")
		(net "TP_CLK_CK440_PFT_OUT_DN")
	)
	(segment
		(start 354.521516 -265.592306)
		(end 354.521262 -265.592306)
		(width 0.12954)
		(layer "F.Cu")
		(net "TP_CLK_66M_ESPI_IBL_CPU0_LVC1")
	)
	(segment
		(start 354.521262 -265.592306)
		(end 354.521262 -266.128246)
		(width 0.12954)
		(layer "F.Cu")
		(net "TP_CLK_66M_ESPI_IBL_CPU0_LVC1")
	)
	(via
		(at 354.521262 -266.128246)
		(size 0.4572)
		(drill 0.2032)
		(layers "F.Cu" "B.Cu")
		(net "TP_CLK_66M_ESPI_IBL_CPU0_LVC1")
	)
	(segment
		(start 215.564212 -14.10081)
		(end 215.31961 -14.345412)
		(width 0.12954)
		(layer "F.Cu")
		(net "TP_CLK_50M_PCH_LOM")
	)
	(segment
		(start 219.701618 -15.489682)
		(end 218.312746 -14.10081)
		(width 0.12954)
		(layer "F.Cu")
		(net "TP_CLK_50M_PCH_LOM")
	)
	(segment
		(start 215.31961 -14.345412)
		(end 215.31961 -14.845792)
		(width 0.12954)
		(layer "F.Cu")
		(net "TP_CLK_50M_PCH_LOM")
	)
	(segment
		(start 218.312746 -14.10081)
		(end 215.564212 -14.10081)
		(width 0.12954)
		(layer "F.Cu")
		(net "TP_CLK_50M_PCH_LOM")
	)
	(via
		(at 219.701618 -15.489682)
		(size 0.762)
		(drill 0.381)
		(layers "F.Cu" "B.Cu")
		(net "TP_CLK_50M_PCH_LOM")
	)
	(segment
		(start 326.337676 -69.160136)
		(end 327.6092 -67.888612)
		(width 0.12954)
		(layer "F.Cu")
		(net "TP_CLK_100M_PCH_9_DP")
	)
	(segment
		(start 333.352394 -58.355992)
		(end 333.398114 -58.310272)
		(width 0.0889)
		(layer "F.Cu")
		(net "TP_CLK_100M_PCH_9_DP")
	)
	(segment
		(start 332.372208 -60.870084)
		(end 333.111094 -60.131198)
		(width 0.0889)
		(layer "F.Cu")
		(net "TP_CLK_100M_PCH_9_DP")
	)
	(segment
		(start 333.111094 -60.131198)
		(end 333.111094 -59.496198)
		(width 0.0889)
		(layer "F.Cu")
		(net "TP_CLK_100M_PCH_9_DP")
	)
	(segment
		(start 332.110588 -61.501782)
		(end 332.372208 -60.870084)
		(width 0.0889)
		(layer "F.Cu")
		(net "TP_CLK_100M_PCH_9_DP")
	)
	(segment
		(start 333.111094 -59.496198)
		(end 333.207614 -59.399678)
		(width 0.0889)
		(layer "F.Cu")
		(net "TP_CLK_100M_PCH_9_DP")
	)
	(segment
		(start 327.6092 -66.00317)
		(end 331.812646 -61.799724)
		(width 0.12954)
		(layer "F.Cu")
		(net "TP_CLK_100M_PCH_9_DP")
	)
	(segment
		(start 331.812646 -61.799724)
		(end 332.110588 -61.501782)
		(width 0.0889)
		(layer "F.Cu")
		(net "TP_CLK_100M_PCH_9_DP")
	)
	(segment
		(start 333.090012 -58.703972)
		(end 333.352394 -58.355992)
		(width 0.0889)
		(layer "F.Cu")
		(net "TP_CLK_100M_PCH_9_DP")
	)
	(segment
		(start 333.090012 -58.98261)
		(end 333.090012 -58.703972)
		(width 0.0889)
		(layer "F.Cu")
		(net "TP_CLK_100M_PCH_9_DP")
	)
	(segment
		(start 333.398114 -58.310272)
		(end 333.398114 -58.020204)
		(width 0.0889)
		(layer "F.Cu")
		(net "TP_CLK_100M_PCH_9_DP")
	)
	(segment
		(start 327.6092 -67.888612)
		(end 327.6092 -66.00317)
		(width 0.12954)
		(layer "F.Cu")
		(net "TP_CLK_100M_PCH_9_DP")
	)
	(segment
		(start 333.207614 -59.100212)
		(end 333.090012 -58.98261)
		(width 0.0889)
		(layer "F.Cu")
		(net "TP_CLK_100M_PCH_9_DP")
	)
	(segment
		(start 333.207614 -59.399678)
		(end 333.207614 -59.100212)
		(width 0.0889)
		(layer "F.Cu")
		(net "TP_CLK_100M_PCH_9_DP")
	)
	(via
		(at 326.337676 -69.160136)
		(size 0.762)
		(drill 0.381)
		(layers "F.Cu" "B.Cu")
		(net "TP_CLK_100M_PCH_9_DP")
	)
	(segment
		(start 325.116698 -71.488554)
		(end 326.5551 -70.050152)
		(width 0.12954)
		(layer "F.Cu")
		(net "TP_CLK_100M_PCH_9_DN")
	)
	(segment
		(start 333.050388 -60.60186)
		(end 333.176118 -60.47613)
		(width 0.0889)
		(layer "F.Cu")
		(net "TP_CLK_100M_PCH_9_DN")
	)
	(segment
		(start 326.5551 -70.050152)
		(end 326.5551 -69.85)
		(width 0.12954)
		(layer "F.Cu")
		(net "TP_CLK_100M_PCH_9_DN")
	)
	(segment
		(start 327.96734 -68.43776)
		(end 327.96734 -66.023744)
		(width 0.12954)
		(layer "F.Cu")
		(net "TP_CLK_100M_PCH_9_DN")
	)
	(segment
		(start 332.377542 -61.613542)
		(end 332.716378 -60.795408)
		(width 0.0889)
		(layer "F.Cu")
		(net "TP_CLK_100M_PCH_9_DN")
	)
	(segment
		(start 333.176118 -60.47613)
		(end 333.176118 -60.335668)
		(width 0.0889)
		(layer "F.Cu")
		(net "TP_CLK_100M_PCH_9_DN")
	)
	(segment
		(start 333.301594 -60.210192)
		(end 333.301594 -59.575192)
		(width 0.0889)
		(layer "F.Cu")
		(net "TP_CLK_100M_PCH_9_DN")
	)
	(segment
		(start 332.716378 -60.795408)
		(end 332.909926 -60.60186)
		(width 0.0889)
		(layer "F.Cu")
		(net "TP_CLK_100M_PCH_9_DN")
	)
	(segment
		(start 326.5551 -69.85)
		(end 327.96734 -68.43776)
		(width 0.12954)
		(layer "F.Cu")
		(net "TP_CLK_100M_PCH_9_DN")
	)
	(segment
		(start 333.301594 -59.575192)
		(end 333.398114 -59.478672)
		(width 0.0889)
		(layer "F.Cu")
		(net "TP_CLK_100M_PCH_9_DN")
	)
	(segment
		(start 327.96734 -66.023744)
		(end 332.145386 -61.845698)
		(width 0.12954)
		(layer "F.Cu")
		(net "TP_CLK_100M_PCH_9_DN")
	)
	(segment
		(start 333.398114 -59.478672)
		(end 333.398114 -58.850276)
		(width 0.0889)
		(layer "F.Cu")
		(net "TP_CLK_100M_PCH_9_DN")
	)
	(segment
		(start 332.909926 -60.60186)
		(end 333.050388 -60.60186)
		(width 0.0889)
		(layer "F.Cu")
		(net "TP_CLK_100M_PCH_9_DN")
	)
	(segment
		(start 333.176118 -60.335668)
		(end 333.301594 -60.210192)
		(width 0.0889)
		(layer "F.Cu")
		(net "TP_CLK_100M_PCH_9_DN")
	)
	(segment
		(start 332.145386 -61.845698)
		(end 332.377542 -61.613542)
		(width 0.0889)
		(layer "F.Cu")
		(net "TP_CLK_100M_PCH_9_DN")
	)
	(segment
		(start 325.116698 -72.99325)
		(end 325.116698 -71.488554)
		(width 0.12954)
		(layer "F.Cu")
		(net "TP_CLK_100M_PCH_9_DN")
	)
	(via
		(at 325.116698 -72.99325)
		(size 0.762)
		(drill 0.381)
		(layers "F.Cu" "B.Cu")
		(net "TP_CLK_100M_PCH_9_DN")
	)
	(segment
		(start 325.29145 -70.361302)
		(end 325.29145 -66.670174)
		(width 0.12954)
		(layer "F.Cu")
		(net "TP_CLK_100M_PCH_5_DP")
	)
	(segment
		(start 331.589126 -59.119008)
		(end 331.752194 -58.889392)
		(width 0.0889)
		(layer "F.Cu")
		(net "TP_CLK_100M_PCH_5_DP")
	)
	(segment
		(start 325.29145 -66.670174)
		(end 326.642476 -65.319148)
		(width 0.12954)
		(layer "F.Cu")
		(net "TP_CLK_100M_PCH_5_DP")
	)
	(segment
		(start 331.531214 -61.000386)
		(end 331.735176 -60.796424)
		(width 0.0889)
		(layer "F.Cu")
		(net "TP_CLK_100M_PCH_5_DP")
	)
	(segment
		(start 331.752194 -58.889392)
		(end 331.897482 -58.744104)
		(width 0.0889)
		(layer "F.Cu")
		(net "TP_CLK_100M_PCH_5_DP")
	)
	(segment
		(start 327.212452 -65.319148)
		(end 331.531214 -61.000386)
		(width 0.12954)
		(layer "F.Cu")
		(net "TP_CLK_100M_PCH_5_DP")
	)
	(segment
		(start 326.642476 -65.319148)
		(end 327.212452 -65.319148)
		(width 0.12954)
		(layer "F.Cu")
		(net "TP_CLK_100M_PCH_5_DP")
	)
	(segment
		(start 331.735176 -60.796424)
		(end 331.735176 -59.597036)
		(width 0.0889)
		(layer "F.Cu")
		(net "TP_CLK_100M_PCH_5_DP")
	)
	(segment
		(start 331.897482 -58.744104)
		(end 331.897482 -58.43524)
		(width 0.0889)
		(layer "F.Cu")
		(net "TP_CLK_100M_PCH_5_DP")
	)
	(segment
		(start 331.589126 -59.450986)
		(end 331.589126 -59.119008)
		(width 0.0889)
		(layer "F.Cu")
		(net "TP_CLK_100M_PCH_5_DP")
	)
	(segment
		(start 331.735176 -59.597036)
		(end 331.589126 -59.450986)
		(width 0.0889)
		(layer "F.Cu")
		(net "TP_CLK_100M_PCH_5_DP")
	)
	(via
		(at 325.29145 -70.361302)
		(size 0.762)
		(drill 0.381)
		(layers "F.Cu" "B.Cu")
		(net "TP_CLK_100M_PCH_5_DP")
	)
	(segment
		(start 331.925676 -59.293506)
		(end 331.897482 -59.265312)
		(width 0.0889)
		(layer "F.Cu")
		(net "TP_CLK_100M_PCH_5_DN")
	)
	(segment
		(start 327.28408 -65.865502)
		(end 331.714602 -61.43498)
		(width 0.12954)
		(layer "F.Cu")
		(net "TP_CLK_100M_PCH_5_DN")
	)
	(segment
		(start 327.28408 -66.840608)
		(end 327.28408 -65.865502)
		(width 0.12954)
		(layer "F.Cu")
		(net "TP_CLK_100M_PCH_5_DN")
	)
	(segment
		(start 331.714602 -61.43498)
		(end 331.925676 -61.223906)
		(width 0.0889)
		(layer "F.Cu")
		(net "TP_CLK_100M_PCH_5_DN")
	)
	(segment
		(start 331.925676 -61.223906)
		(end 331.925676 -59.293506)
		(width 0.0889)
		(layer "F.Cu")
		(net "TP_CLK_100M_PCH_5_DN")
	)
	(segment
		(start 326.705214 -67.419474)
		(end 327.28408 -66.840608)
		(width 0.12954)
		(layer "F.Cu")
		(net "TP_CLK_100M_PCH_5_DN")
	)
	(segment
		(start 326.300592 -67.419474)
		(end 326.705214 -67.419474)
		(width 0.12954)
		(layer "F.Cu")
		(net "TP_CLK_100M_PCH_5_DN")
	)
	(via
		(at 326.300592 -67.419474)
		(size 0.762)
		(drill 0.381)
		(layers "F.Cu" "B.Cu")
		(net "TP_CLK_100M_PCH_5_DN")
	)
	(segment
		(start 332.108048 -65.96888)
		(end 334.531716 -63.545212)
		(width 0.0889)
		(layer "F.Cu")
		(net "TP_CLK_100M_PCH_4_DP")
	)
	(segment
		(start 331.397356 -67.372484)
		(end 331.397356 -66.679572)
		(width 0.12954)
		(layer "F.Cu")
		(net "TP_CLK_100M_PCH_4_DP")
	)
	(segment
		(start 335.091024 -59.02325)
		(end 335.091024 -58.703972)
		(width 0.0889)
		(layer "F.Cu")
		(net "TP_CLK_100M_PCH_4_DP")
	)
	(segment
		(start 335.193894 -60.833254)
		(end 335.193894 -59.412124)
		(width 0.0889)
		(layer "F.Cu")
		(net "TP_CLK_100M_PCH_4_DP")
	)
	(segment
		(start 335.183226 -59.115452)
		(end 335.091024 -59.02325)
		(width 0.0889)
		(layer "F.Cu")
		(net "TP_CLK_100M_PCH_4_DP")
	)
	(segment
		(start 335.091024 -58.703972)
		(end 335.399126 -58.39587)
		(width 0.0889)
		(layer "F.Cu")
		(net "TP_CLK_100M_PCH_4_DP")
	)
	(segment
		(start 334.531716 -61.495432)
		(end 335.193894 -60.833254)
		(width 0.0889)
		(layer "F.Cu")
		(net "TP_CLK_100M_PCH_4_DP")
	)
	(segment
		(start 335.193894 -59.412124)
		(end 335.183226 -59.401456)
		(width 0.0889)
		(layer "F.Cu")
		(net "TP_CLK_100M_PCH_4_DP")
	)
	(segment
		(start 335.183226 -59.401456)
		(end 335.183226 -59.115452)
		(width 0.0889)
		(layer "F.Cu")
		(net "TP_CLK_100M_PCH_4_DP")
	)
	(segment
		(start 335.399126 -58.39587)
		(end 335.399126 -58.020204)
		(width 0.0889)
		(layer "F.Cu")
		(net "TP_CLK_100M_PCH_4_DP")
	)
	(segment
		(start 331.397356 -66.679572)
		(end 332.108048 -65.96888)
		(width 0.12954)
		(layer "F.Cu")
		(net "TP_CLK_100M_PCH_4_DP")
	)
	(segment
		(start 334.531716 -63.545212)
		(end 334.531716 -61.495432)
		(width 0.0889)
		(layer "F.Cu")
		(net "TP_CLK_100M_PCH_4_DP")
	)
	(via
		(at 331.397356 -67.372484)
		(size 0.762)
		(drill 0.381)
		(layers "F.Cu" "B.Cu")
		(net "TP_CLK_100M_PCH_4_DP")
	)
	(segment
		(start 331.511656 -68.624196)
		(end 332.397862 -67.73799)
		(width 0.12954)
		(layer "F.Cu")
		(net "TP_CLK_100M_PCH_4_DN")
	)
	(segment
		(start 335.384394 -59.412124)
		(end 335.399126 -59.397392)
		(width 0.0889)
		(layer "F.Cu")
		(net "TP_CLK_100M_PCH_4_DN")
	)
	(segment
		(start 334.722216 -61.615066)
		(end 335.384394 -60.952888)
		(width 0.0889)
		(layer "F.Cu")
		(net "TP_CLK_100M_PCH_4_DN")
	)
	(segment
		(start 332.397862 -67.73799)
		(end 332.397862 -65.978532)
		(width 0.12954)
		(layer "F.Cu")
		(net "TP_CLK_100M_PCH_4_DN")
	)
	(segment
		(start 332.397862 -65.978532)
		(end 334.722216 -63.654178)
		(width 0.0889)
		(layer "F.Cu")
		(net "TP_CLK_100M_PCH_4_DN")
	)
	(segment
		(start 331.511656 -69.253608)
		(end 331.511656 -68.624196)
		(width 0.12954)
		(layer "F.Cu")
		(net "TP_CLK_100M_PCH_4_DN")
	)
	(segment
		(start 335.384394 -60.952888)
		(end 335.384394 -59.412124)
		(width 0.0889)
		(layer "F.Cu")
		(net "TP_CLK_100M_PCH_4_DN")
	)
	(segment
		(start 335.399126 -59.397392)
		(end 335.399126 -58.850276)
		(width 0.0889)
		(layer "F.Cu")
		(net "TP_CLK_100M_PCH_4_DN")
	)
	(segment
		(start 334.722216 -63.654178)
		(end 334.722216 -61.615066)
		(width 0.0889)
		(layer "F.Cu")
		(net "TP_CLK_100M_PCH_4_DN")
	)
	(via
		(at 331.511656 -69.253608)
		(size 0.762)
		(drill 0.381)
		(layers "F.Cu" "B.Cu")
		(net "TP_CLK_100M_PCH_4_DN")
	)
	(segment
		(start 334.590644 -59.448192)
		(end 334.590644 -59.119008)
		(width 0.0889)
		(layer "F.Cu")
		(net "TP_CLK_100M_PCH_16_DP")
	)
	(segment
		(start 330.487528 -71.314056)
		(end 330.487528 -66.221864)
		(width 0.12954)
		(layer "F.Cu")
		(net "TP_CLK_100M_PCH_16_DP")
	)
	(segment
		(start 334.590644 -59.119008)
		(end 334.898746 -58.810906)
		(width 0.0889)
		(layer "F.Cu")
		(net "TP_CLK_100M_PCH_16_DP")
	)
	(segment
		(start 334.1116 -62.134242)
		(end 334.1116 -61.326268)
		(width 0.0889)
		(layer "F.Cu")
		(net "TP_CLK_100M_PCH_16_DP")
	)
	(segment
		(start 333.411322 -62.83452)
		(end 334.1116 -62.134242)
		(width 0.0889)
		(layer "F.Cu")
		(net "TP_CLK_100M_PCH_16_DP")
	)
	(segment
		(start 333.411322 -63.085472)
		(end 333.411322 -62.83452)
		(width 0.0889)
		(layer "F.Cu")
		(net "TP_CLK_100M_PCH_16_DP")
	)
	(segment
		(start 334.898746 -58.810906)
		(end 334.898746 -58.43524)
		(width 0.0889)
		(layer "F.Cu")
		(net "TP_CLK_100M_PCH_16_DP")
	)
	(segment
		(start 330.637642 -65.859152)
		(end 333.411322 -63.085472)
		(width 0.12954)
		(layer "F.Cu")
		(net "TP_CLK_100M_PCH_16_DP")
	)
	(segment
		(start 334.1116 -61.326268)
		(end 334.774794 -60.663074)
		(width 0.0889)
		(layer "F.Cu")
		(net "TP_CLK_100M_PCH_16_DP")
	)
	(segment
		(start 334.774794 -60.663074)
		(end 334.774794 -59.632342)
		(width 0.0889)
		(layer "F.Cu")
		(net "TP_CLK_100M_PCH_16_DP")
	)
	(segment
		(start 331.49286 -72.319388)
		(end 330.487528 -71.314056)
		(width 0.12954)
		(layer "F.Cu")
		(net "TP_CLK_100M_PCH_16_DP")
	)
	(segment
		(start 334.774794 -59.632342)
		(end 334.590644 -59.448192)
		(width 0.0889)
		(layer "F.Cu")
		(net "TP_CLK_100M_PCH_16_DP")
	)
	(segment
		(start 330.487528 -66.221864)
		(end 330.637642 -65.859152)
		(width 0.12954)
		(layer "F.Cu")
		(net "TP_CLK_100M_PCH_16_DP")
	)
	(via
		(at 331.49286 -72.319388)
		(size 0.762)
		(drill 0.381)
		(layers "F.Cu" "B.Cu")
		(net "TP_CLK_100M_PCH_16_DP")
	)
	(segment
		(start 330.792328 -66.928238)
		(end 332.005178 -65.715388)
		(width 0.0889)
		(layer "F.Cu")
		(net "TP_CLK_100M_PCH_16_DN")
	)
	(segment
		(start 332.076298 -65.715388)
		(end 334.340962 -63.450724)
		(width 0.0889)
		(layer "F.Cu")
		(net "TP_CLK_100M_PCH_16_DN")
	)
	(segment
		(start 331.45222 -70.752208)
		(end 330.792328 -70.092316)
		(width 0.12954)
		(layer "F.Cu")
		(net "TP_CLK_100M_PCH_16_DN")
	)
	(segment
		(start 330.792328 -66.999358)
		(end 330.792328 -66.928238)
		(width 0.0889)
		(layer "F.Cu")
		(net "TP_CLK_100M_PCH_16_DN")
	)
	(segment
		(start 334.898746 -59.394344)
		(end 334.898746 -59.265312)
		(width 0.0889)
		(layer "F.Cu")
		(net "TP_CLK_100M_PCH_16_DN")
	)
	(segment
		(start 332.005178 -65.715388)
		(end 332.076298 -65.715388)
		(width 0.0889)
		(layer "F.Cu")
		(net "TP_CLK_100M_PCH_16_DN")
	)
	(segment
		(start 334.340962 -63.450724)
		(end 334.340962 -61.37148)
		(width 0.0889)
		(layer "F.Cu")
		(net "TP_CLK_100M_PCH_16_DN")
	)
	(segment
		(start 334.340962 -61.37148)
		(end 334.974946 -60.737496)
		(width 0.0889)
		(layer "F.Cu")
		(net "TP_CLK_100M_PCH_16_DN")
	)
	(segment
		(start 330.792328 -70.092316)
		(end 330.792328 -66.999358)
		(width 0.12954)
		(layer "F.Cu")
		(net "TP_CLK_100M_PCH_16_DN")
	)
	(segment
		(start 334.974946 -59.470544)
		(end 334.898746 -59.394344)
		(width 0.0889)
		(layer "F.Cu")
		(net "TP_CLK_100M_PCH_16_DN")
	)
	(segment
		(start 334.974946 -60.737496)
		(end 334.974946 -59.470544)
		(width 0.0889)
		(layer "F.Cu")
		(net "TP_CLK_100M_PCH_16_DN")
	)
	(via
		(at 331.45222 -70.752208)
		(size 0.762)
		(drill 0.381)
		(layers "F.Cu" "B.Cu")
		(net "TP_CLK_100M_PCH_16_DN")
	)
	(segment
		(start 327.942194 -60.54725)
		(end 328.533506 -59.955938)
		(width 0.0889)
		(layer "F.Cu")
		(net "TP_CLK_100M_PCH_15_DP")
	)
	(segment
		(start 328.651616 -59.01436)
		(end 328.689716 -58.98134)
		(width 0.0889)
		(layer "F.Cu")
		(net "TP_CLK_100M_PCH_15_DP")
	)
	(segment
		(start 327.942194 -60.787788)
		(end 327.942194 -60.54725)
		(width 0.0889)
		(layer "F.Cu")
		(net "TP_CLK_100M_PCH_15_DP")
	)
	(segment
		(start 328.539602 -59.400948)
		(end 328.541634 -59.229498)
		(width 0.0889)
		(layer "F.Cu")
		(net "TP_CLK_100M_PCH_15_DP")
	)
	(segment
		(start 328.689716 -58.98134)
		(end 328.735436 -58.949082)
		(width 0.0889)
		(layer "F.Cu")
		(net "TP_CLK_100M_PCH_15_DP")
	)
	(segment
		(start 328.32802 -61.077348)
		(end 328.329798 -61.077348)
		(width 0.0889)
		(layer "F.Cu")
		(net "TP_CLK_100M_PCH_15_DP")
	)
	(segment
		(start 328.329798 -61.077348)
		(end 328.329798 -61.073792)
		(width 0.0889)
		(layer "F.Cu")
		(net "TP_CLK_100M_PCH_15_DP")
	)
	(segment
		(start 328.541634 -59.229498)
		(end 328.570336 -59.124342)
		(width 0.0889)
		(layer "F.Cu")
		(net "TP_CLK_100M_PCH_15_DP")
	)
	(segment
		(start 328.777854 -58.909966)
		(end 328.895964 -58.685684)
		(width 0.0889)
		(layer "F.Cu")
		(net "TP_CLK_100M_PCH_15_DP")
	)
	(segment
		(start 328.228198 -61.073792)
		(end 327.942194 -60.787788)
		(width 0.0889)
		(layer "F.Cu")
		(net "TP_CLK_100M_PCH_15_DP")
	)
	(segment
		(start 328.533506 -59.955938)
		(end 328.539602 -59.400948)
		(width 0.0889)
		(layer "F.Cu")
		(net "TP_CLK_100M_PCH_15_DP")
	)
	(segment
		(start 328.895964 -58.685684)
		(end 328.895964 -58.43524)
		(width 0.0889)
		(layer "F.Cu")
		(net "TP_CLK_100M_PCH_15_DP")
	)
	(segment
		(start 328.570336 -59.124342)
		(end 328.602086 -59.069986)
		(width 0.0889)
		(layer "F.Cu")
		(net "TP_CLK_100M_PCH_15_DP")
	)
	(segment
		(start 328.329798 -61.073792)
		(end 328.228198 -61.073792)
		(width 0.0889)
		(layer "F.Cu")
		(net "TP_CLK_100M_PCH_15_DP")
	)
	(segment
		(start 328.735436 -58.949082)
		(end 328.777854 -58.909966)
		(width 0.0889)
		(layer "F.Cu")
		(net "TP_CLK_100M_PCH_15_DP")
	)
	(segment
		(start 328.602086 -59.069986)
		(end 328.651616 -59.01436)
		(width 0.0889)
		(layer "F.Cu")
		(net "TP_CLK_100M_PCH_15_DP")
	)
	(via
		(at 328.32802 -61.077348)
		(size 0.508)
		(drill 0.254)
		(layers "F.Cu" "B.Cu")
		(net "TP_CLK_100M_PCH_15_DP")
	)
	(segment
		(start 327.313798 -61.073792)
		(end 327.415398 -61.073792)
		(width 0.0889)
		(layer "F.Cu")
		(net "TP_CLK_100M_PCH_15_DN")
	)
	(segment
		(start 328.340974 -59.878976)
		(end 328.340974 -59.252866)
		(width 0.0889)
		(layer "F.Cu")
		(net "TP_CLK_100M_PCH_15_DN")
	)
	(segment
		(start 327.415398 -61.073792)
		(end 327.751694 -60.737496)
		(width 0.0889)
		(layer "F.Cu")
		(net "TP_CLK_100M_PCH_15_DN")
	)
	(segment
		(start 328.340974 -59.252866)
		(end 328.393298 -58.990992)
		(width 0.0889)
		(layer "F.Cu")
		(net "TP_CLK_100M_PCH_15_DN")
	)
	(segment
		(start 327.751694 -60.468256)
		(end 328.340974 -59.878976)
		(width 0.0889)
		(layer "F.Cu")
		(net "TP_CLK_100M_PCH_15_DN")
	)
	(segment
		(start 327.751694 -60.737496)
		(end 327.751694 -60.468256)
		(width 0.0889)
		(layer "F.Cu")
		(net "TP_CLK_100M_PCH_15_DN")
	)
	(segment
		(start 328.395076 -58.980832)
		(end 328.395076 -58.850784)
		(width 0.0889)
		(layer "F.Cu")
		(net "TP_CLK_100M_PCH_15_DN")
	)
	(segment
		(start 328.395076 -58.850784)
		(end 328.395584 -58.850276)
		(width 0.0889)
		(layer "F.Cu")
		(net "TP_CLK_100M_PCH_15_DN")
	)
	(via
		(at 327.313798 -61.073792)
		(size 0.508)
		(drill 0.254)
		(layers "F.Cu" "B.Cu")
		(net "TP_CLK_100M_PCH_15_DN")
	)
	(arc
		(start 328.393298 -58.990992)
		(mid 328.394246 -58.985922)
		(end 328.395076 -58.980832)
		(width 0.0889)
		(layer "F.Cu")
		(net "TP_CLK_100M_PCH_15_DN")
	)
	(segment
		(start 329.39609 -58.3184)
		(end 329.233022 -58.481468)
		(width 0.0889)
		(layer "F.Cu")
		(net "TP_CLK_100M_PCH_14_DP")
	)
	(segment
		(start 322.112132 -67.362832)
		(end 322.112132 -71.044562)
		(width 0.12954)
		(layer "F.Cu")
		(net "TP_CLK_100M_PCH_14_DP")
	)
	(segment
		(start 322.950332 -66.524632)
		(end 322.112132 -67.362832)
		(width 0.12954)
		(layer "F.Cu")
		(net "TP_CLK_100M_PCH_14_DP")
	)
	(segment
		(start 329.09383 -58.937652)
		(end 329.150472 -59.02579)
		(width 0.0889)
		(layer "F.Cu")
		(net "TP_CLK_100M_PCH_14_DP")
	)
	(segment
		(start 325.487792 -61.622432)
		(end 323.932296 -63.177928)
		(width 0.12954)
		(layer "F.Cu")
		(net "TP_CLK_100M_PCH_14_DP")
	)
	(segment
		(start 329.21829 -60.820808)
		(end 328.416666 -61.622432)
		(width 0.0889)
		(layer "F.Cu")
		(net "TP_CLK_100M_PCH_14_DP")
	)
	(segment
		(start 329.262994 -59.302396)
		(end 329.21829 -59.551824)
		(width 0.0889)
		(layer "F.Cu")
		(net "TP_CLK_100M_PCH_14_DP")
	)
	(segment
		(start 322.112132 -71.044562)
		(end 322.744084 -71.676514)
		(width 0.12954)
		(layer "F.Cu")
		(net "TP_CLK_100M_PCH_14_DP")
	)
	(segment
		(start 329.39609 -58.020204)
		(end 329.39609 -58.3184)
		(width 0.0889)
		(layer "F.Cu")
		(net "TP_CLK_100M_PCH_14_DP")
	)
	(segment
		(start 329.082654 -58.819288)
		(end 329.09383 -58.937652)
		(width 0.0889)
		(layer "F.Cu")
		(net "TP_CLK_100M_PCH_14_DP")
	)
	(segment
		(start 329.233022 -58.481468)
		(end 329.11923 -58.729118)
		(width 0.0889)
		(layer "F.Cu")
		(net "TP_CLK_100M_PCH_14_DP")
	)
	(segment
		(start 329.262994 -59.224418)
		(end 329.262994 -59.302396)
		(width 0.0889)
		(layer "F.Cu")
		(net "TP_CLK_100M_PCH_14_DP")
	)
	(segment
		(start 328.416666 -61.622432)
		(end 325.487792 -61.622432)
		(width 0.0889)
		(layer "F.Cu")
		(net "TP_CLK_100M_PCH_14_DP")
	)
	(segment
		(start 329.11923 -58.729118)
		(end 329.082654 -58.819288)
		(width 0.0889)
		(layer "F.Cu")
		(net "TP_CLK_100M_PCH_14_DP")
	)
	(segment
		(start 329.202288 -59.084972)
		(end 329.262994 -59.224418)
		(width 0.0889)
		(layer "F.Cu")
		(net "TP_CLK_100M_PCH_14_DP")
	)
	(segment
		(start 322.950332 -64.659764)
		(end 322.950332 -66.524632)
		(width 0.12954)
		(layer "F.Cu")
		(net "TP_CLK_100M_PCH_14_DP")
	)
	(segment
		(start 329.150472 -59.02579)
		(end 329.202288 -59.084972)
		(width 0.0889)
		(layer "F.Cu")
		(net "TP_CLK_100M_PCH_14_DP")
	)
	(segment
		(start 323.932296 -63.177928)
		(end 323.932296 -63.6778)
		(width 0.12954)
		(layer "F.Cu")
		(net "TP_CLK_100M_PCH_14_DP")
	)
	(segment
		(start 323.932296 -63.6778)
		(end 322.950332 -64.659764)
		(width 0.12954)
		(layer "F.Cu")
		(net "TP_CLK_100M_PCH_14_DP")
	)
	(segment
		(start 329.21829 -59.551824)
		(end 329.21829 -60.820808)
		(width 0.0889)
		(layer "F.Cu")
		(net "TP_CLK_100M_PCH_14_DP")
	)
	(via
		(at 322.744084 -71.676514)
		(size 0.762)
		(drill 0.381)
		(layers "F.Cu" "B.Cu")
		(net "TP_CLK_100M_PCH_14_DP")
	)
	(segment
		(start 325.322438 -62.161928)
		(end 324.383654 -63.100712)
		(width 0.12954)
		(layer "F.Cu")
		(net "TP_CLK_100M_PCH_14_DN")
	)
	(segment
		(start 328.53249 -61.812932)
		(end 327.184766 -61.812932)
		(width 0.0889)
		(layer "F.Cu")
		(net "TP_CLK_100M_PCH_14_DN")
	)
	(segment
		(start 327.184766 -61.812932)
		(end 327.098406 -61.899292)
		(width 0.0889)
		(layer "F.Cu")
		(net "TP_CLK_100M_PCH_14_DN")
	)
	(segment
		(start 326.83577 -62.161928)
		(end 325.322438 -62.161928)
		(width 0.12954)
		(layer "F.Cu")
		(net "TP_CLK_100M_PCH_14_DN")
	)
	(segment
		(start 324.383654 -64.078866)
		(end 323.99097 -64.47155)
		(width 0.12954)
		(layer "F.Cu")
		(net "TP_CLK_100M_PCH_14_DN")
	)
	(segment
		(start 323.99097 -64.47155)
		(end 323.99097 -64.917574)
		(width 0.12954)
		(layer "F.Cu")
		(net "TP_CLK_100M_PCH_14_DN")
	)
	(segment
		(start 329.453494 -60.891928)
		(end 328.53249 -61.812932)
		(width 0.0889)
		(layer "F.Cu")
		(net "TP_CLK_100M_PCH_14_DN")
	)
	(segment
		(start 329.39609 -58.850276)
		(end 329.453494 -59.139074)
		(width 0.0889)
		(layer "F.Cu")
		(net "TP_CLK_100M_PCH_14_DN")
	)
	(segment
		(start 324.322694 -65.249298)
		(end 324.322694 -65.99301)
		(width 0.12954)
		(layer "F.Cu")
		(net "TP_CLK_100M_PCH_14_DN")
	)
	(segment
		(start 324.383654 -63.100712)
		(end 324.383654 -64.078866)
		(width 0.12954)
		(layer "F.Cu")
		(net "TP_CLK_100M_PCH_14_DN")
	)
	(segment
		(start 323.99097 -64.917574)
		(end 324.322694 -65.249298)
		(width 0.12954)
		(layer "F.Cu")
		(net "TP_CLK_100M_PCH_14_DN")
	)
	(segment
		(start 327.098406 -61.899292)
		(end 326.83577 -62.161928)
		(width 0.12954)
		(layer "F.Cu")
		(net "TP_CLK_100M_PCH_14_DN")
	)
	(segment
		(start 324.322694 -65.99301)
		(end 322.744084 -67.57162)
		(width 0.12954)
		(layer "F.Cu")
		(net "TP_CLK_100M_PCH_14_DN")
	)
	(segment
		(start 322.744084 -67.57162)
		(end 322.744084 -70.406514)
		(width 0.12954)
		(layer "F.Cu")
		(net "TP_CLK_100M_PCH_14_DN")
	)
	(segment
		(start 329.453494 -59.139074)
		(end 329.453494 -60.891928)
		(width 0.0889)
		(layer "F.Cu")
		(net "TP_CLK_100M_PCH_14_DN")
	)
	(via
		(at 322.744084 -70.406514)
		(size 0.762)
		(drill 0.381)
		(layers "F.Cu" "B.Cu")
		(net "TP_CLK_100M_PCH_14_DN")
	)
	(segment
		(start 329.834494 -61.085476)
		(end 329.834494 -59.806078)
		(width 0.0889)
		(layer "F.Cu")
		(net "TP_CLK_100M_PCH_13_DP")
	)
	(segment
		(start 328.217022 -62.398148)
		(end 328.521822 -62.398148)
		(width 0.0889)
		(layer "F.Cu")
		(net "TP_CLK_100M_PCH_13_DP")
	)
	(segment
		(start 327.734422 -62.880748)
		(end 328.217022 -62.398148)
		(width 0.0889)
		(layer "F.Cu")
		(net "TP_CLK_100M_PCH_13_DP")
	)
	(segment
		(start 330.204572 -59.119008)
		(end 329.89647 -58.810906)
		(width 0.0889)
		(layer "F.Cu")
		(net "TP_CLK_100M_PCH_13_DP")
	)
	(segment
		(start 329.834494 -59.806078)
		(end 330.204572 -59.436)
		(width 0.0889)
		(layer "F.Cu")
		(net "TP_CLK_100M_PCH_13_DP")
	)
	(segment
		(start 329.89647 -58.810906)
		(end 329.89647 -58.43524)
		(width 0.0889)
		(layer "F.Cu")
		(net "TP_CLK_100M_PCH_13_DP")
	)
	(segment
		(start 328.521822 -62.398148)
		(end 329.834494 -61.085476)
		(width 0.0889)
		(layer "F.Cu")
		(net "TP_CLK_100M_PCH_13_DP")
	)
	(segment
		(start 330.204572 -59.436)
		(end 330.204572 -59.119008)
		(width 0.0889)
		(layer "F.Cu")
		(net "TP_CLK_100M_PCH_13_DP")
	)
	(via
		(at 327.734422 -62.880748)
		(size 0.508)
		(drill 0.254)
		(layers "F.Cu" "B.Cu")
		(net "TP_CLK_100M_PCH_13_DP")
	)
	(segment
		(start 328.514456 -62.118748)
		(end 327.681082 -62.118748)
		(width 0.0889)
		(layer "F.Cu")
		(net "TP_CLK_100M_PCH_13_DN")
	)
	(segment
		(start 329.643994 -59.70397)
		(end 329.643994 -60.98921)
		(width 0.0889)
		(layer "F.Cu")
		(net "TP_CLK_100M_PCH_13_DN")
	)
	(segment
		(start 327.681082 -62.118748)
		(end 326.713596 -63.086234)
		(width 0.0889)
		(layer "F.Cu")
		(net "TP_CLK_100M_PCH_13_DN")
	)
	(segment
		(start 329.89647 -59.265312)
		(end 329.89647 -59.451494)
		(width 0.0889)
		(layer "F.Cu")
		(net "TP_CLK_100M_PCH_13_DN")
	)
	(segment
		(start 329.89647 -59.451494)
		(end 329.643994 -59.70397)
		(width 0.0889)
		(layer "F.Cu")
		(net "TP_CLK_100M_PCH_13_DN")
	)
	(segment
		(start 326.713596 -63.148972)
		(end 326.57034 -63.292228)
		(width 0.0889)
		(layer "F.Cu")
		(net "TP_CLK_100M_PCH_13_DN")
	)
	(segment
		(start 326.713596 -63.086234)
		(end 326.713596 -63.148972)
		(width 0.0889)
		(layer "F.Cu")
		(net "TP_CLK_100M_PCH_13_DN")
	)
	(segment
		(start 329.643994 -60.98921)
		(end 328.514456 -62.118748)
		(width 0.0889)
		(layer "F.Cu")
		(net "TP_CLK_100M_PCH_13_DN")
	)
	(via
		(at 326.57034 -63.292228)
		(size 0.508)
		(drill 0.254)
		(layers "F.Cu" "B.Cu")
		(net "TP_CLK_100M_PCH_13_DN")
	)
	(segment
		(start 330.896976 -58.778394)
		(end 330.896976 -58.43524)
		(width 0.0889)
		(layer "F.Cu")
		(net "TP_CLK_100M_PCH_12_DP")
	)
	(segment
		(start 330.553822 -59.629548)
		(end 330.553822 -59.121548)
		(width 0.0889)
		(layer "F.Cu")
		(net "TP_CLK_100M_PCH_12_DP")
	)
	(segment
		(start 330.553822 -59.121548)
		(end 330.896976 -58.778394)
		(width 0.0889)
		(layer "F.Cu")
		(net "TP_CLK_100M_PCH_12_DP")
	)
	(segment
		(start 330.299822 -59.883548)
		(end 330.553822 -59.629548)
		(width 0.0889)
		(layer "F.Cu")
		(net "TP_CLK_100M_PCH_12_DP")
	)
	(via
		(at 330.299822 -59.883548)
		(size 0.4572)
		(drill 0.2032)
		(layers "F.Cu" "B.Cu")
		(net "TP_CLK_100M_PCH_12_DP")
	)
	(segment
		(start 330.325222 -60.467748)
		(end 330.896976 -59.895994)
		(width 0.0889)
		(layer "F.Cu")
		(net "TP_CLK_100M_PCH_12_DN")
	)
	(segment
		(start 330.896976 -59.895994)
		(end 330.896976 -59.265312)
		(width 0.0889)
		(layer "F.Cu")
		(net "TP_CLK_100M_PCH_12_DN")
	)
	(via
		(at 330.325222 -60.467748)
		(size 0.4572)
		(drill 0.2032)
		(layers "F.Cu" "B.Cu")
		(net "TP_CLK_100M_PCH_12_DN")
	)
	(segment
		(start 333.23657 -55.968646)
		(end 332.697582 -55.968646)
		(width 0.12954)
		(layer "F.Cu")
		(net "TP_CLK_100M_PCH_11_DP")
	)
	(via
		(at 332.697582 -55.968646)
		(size 0.4572)
		(drill 0.2032)
		(layers "F.Cu" "B.Cu")
		(net "TP_CLK_100M_PCH_11_DP")
	)
	(segment
		(start 334.05064 -56.438546)
		(end 333.510382 -56.438546)
		(width 0.12954)
		(layer "F.Cu")
		(net "TP_CLK_100M_PCH_11_DN")
	)
	(via
		(at 334.00238 -55.822088)
		(size 0.6604)
		(drill 0.3302)
		(layers "F.Cu" "B.Cu")
		(net "TP_CLK_100M_PCH_11_DN")
	)
	(via
		(at 333.510382 -56.438546)
		(size 0.4572)
		(drill 0.2032)
		(layers "F.Cu" "B.Cu")
		(net "TP_CLK_100M_PCH_11_DN")
	)
	(segment
		(start 333.9592 -55.822088)
		(end 334.00238 -55.822088)
		(width 0.12954)
		(layer "B.Cu")
		(net "TP_CLK_100M_PCH_11_DN")
	)
	(segment
		(start 333.510382 -56.438546)
		(end 333.510382 -56.270906)
		(width 0.12954)
		(layer "B.Cu")
		(net "TP_CLK_100M_PCH_11_DN")
	)
	(segment
		(start 333.510382 -56.270906)
		(end 333.9592 -55.822088)
		(width 0.12954)
		(layer "B.Cu")
		(net "TP_CLK_100M_PCH_11_DN")
	)
	(segment
		(start 333.70774 -59.568588)
		(end 333.590138 -59.450986)
		(width 0.0889)
		(layer "F.Cu")
		(net "TP_CLK_100M_PCH_0_DP")
	)
	(segment
		(start 332.503272 -61.845444)
		(end 332.614778 -61.733938)
		(width 0.0889)
		(layer "F.Cu")
		(net "TP_CLK_100M_PCH_0_DP")
	)
	(segment
		(start 333.89824 -58.810906)
		(end 333.89824 -58.43524)
		(width 0.0889)
		(layer "F.Cu")
		(net "TP_CLK_100M_PCH_0_DP")
	)
	(segment
		(start 333.590138 -59.450986)
		(end 333.590138 -59.119008)
		(width 0.0889)
		(layer "F.Cu")
		(net "TP_CLK_100M_PCH_0_DP")
	)
	(segment
		(start 333.590138 -59.119008)
		(end 333.89824 -58.810906)
		(width 0.0889)
		(layer "F.Cu")
		(net "TP_CLK_100M_PCH_0_DP")
	)
	(segment
		(start 333.70774 -60.296552)
		(end 333.70774 -59.568588)
		(width 0.0889)
		(layer "F.Cu")
		(net "TP_CLK_100M_PCH_0_DP")
	)
	(segment
		(start 325.969884 -71.603362)
		(end 326.983344 -70.589902)
		(width 0.12954)
		(layer "F.Cu")
		(net "TP_CLK_100M_PCH_0_DP")
	)
	(segment
		(start 328.296016 -66.0527)
		(end 332.503272 -61.845444)
		(width 0.12954)
		(layer "F.Cu")
		(net "TP_CLK_100M_PCH_0_DP")
	)
	(segment
		(start 332.85811 -61.146182)
		(end 333.70774 -60.296552)
		(width 0.0889)
		(layer "F.Cu")
		(net "TP_CLK_100M_PCH_0_DP")
	)
	(segment
		(start 326.983344 -70.101714)
		(end 328.296016 -68.789042)
		(width 0.12954)
		(layer "F.Cu")
		(net "TP_CLK_100M_PCH_0_DP")
	)
	(segment
		(start 326.983344 -70.589902)
		(end 326.983344 -70.101714)
		(width 0.12954)
		(layer "F.Cu")
		(net "TP_CLK_100M_PCH_0_DP")
	)
	(segment
		(start 332.614778 -61.733938)
		(end 332.85811 -61.146182)
		(width 0.0889)
		(layer "F.Cu")
		(net "TP_CLK_100M_PCH_0_DP")
	)
	(segment
		(start 328.296016 -68.789042)
		(end 328.296016 -66.0527)
		(width 0.12954)
		(layer "F.Cu")
		(net "TP_CLK_100M_PCH_0_DP")
	)
	(via
		(at 325.969884 -71.603362)
		(size 0.762)
		(drill 0.381)
		(layers "F.Cu" "B.Cu")
		(net "TP_CLK_100M_PCH_0_DP")
	)
	(segment
		(start 328.068178 -72.077326)
		(end 328.515472 -71.630032)
		(width 0.12954)
		(layer "F.Cu")
		(net "TP_CLK_100M_PCH_0_DN")
	)
	(segment
		(start 327.328022 -72.077326)
		(end 328.068178 -72.077326)
		(width 0.12954)
		(layer "F.Cu")
		(net "TP_CLK_100M_PCH_0_DN")
	)
	(segment
		(start 328.590656 -66.162174)
		(end 332.968346 -61.784484)
		(width 0.12954)
		(layer "F.Cu")
		(net "TP_CLK_100M_PCH_0_DN")
	)
	(segment
		(start 333.89824 -60.375546)
		(end 333.89824 -59.265312)
		(width 0.0889)
		(layer "F.Cu")
		(net "TP_CLK_100M_PCH_0_DN")
	)
	(segment
		(start 328.590656 -69.018912)
		(end 328.590656 -66.162174)
		(width 0.12954)
		(layer "F.Cu")
		(net "TP_CLK_100M_PCH_0_DN")
	)
	(segment
		(start 333.068422 -61.684408)
		(end 333.068422 -61.205364)
		(width 0.0889)
		(layer "F.Cu")
		(net "TP_CLK_100M_PCH_0_DN")
	)
	(segment
		(start 328.515472 -69.094096)
		(end 328.590656 -69.018912)
		(width 0.12954)
		(layer "F.Cu")
		(net "TP_CLK_100M_PCH_0_DN")
	)
	(segment
		(start 333.068422 -61.205364)
		(end 333.89824 -60.375546)
		(width 0.0889)
		(layer "F.Cu")
		(net "TP_CLK_100M_PCH_0_DN")
	)
	(segment
		(start 332.968346 -61.784484)
		(end 333.068422 -61.684408)
		(width 0.0889)
		(layer "F.Cu")
		(net "TP_CLK_100M_PCH_0_DN")
	)
	(segment
		(start 328.515472 -71.630032)
		(end 328.515472 -69.094096)
		(width 0.12954)
		(layer "F.Cu")
		(net "TP_CLK_100M_PCH_0_DN")
	)
	(via
		(at 327.328022 -72.077326)
		(size 0.762)
		(drill 0.381)
		(layers "F.Cu" "B.Cu")
		(net "TP_CLK_100M_PCH_0_DN")
	)
	(segment
		(start 253.93269 -104.962198)
		(end 253.338076 -105.556812)
		(width 0.12954)
		(layer "F.Cu")
		(net "TP_CK440_SBI_DATA_OUT")
	)
	(segment
		(start 253.93269 -103.438198)
		(end 253.93269 -104.962198)
		(width 0.12954)
		(layer "F.Cu")
		(net "TP_CK440_SBI_DATA_OUT")
	)
	(via
		(at 253.338076 -105.556812)
		(size 0.762)
		(drill 0.254)
		(layers "F.Cu" "B.Cu")
		(net "TP_CK440_SBI_DATA_OUT")
	)
	(segment
		(start 208.176114 -242.3668)
		(end 207.071214 -242.3668)
		(width 0.12954)
		(layer "F.Cu")
		(net "TP_CHH_CPU1_DIMM2_FRU_6")
	)
	(via
		(at 207.071214 -242.3668)
		(size 0.4572)
		(drill 0.2032)
		(layers "F.Cu" "B.Cu")
		(net "TP_CHH_CPU1_DIMM2_FRU_6")
	)
	(via
		(at 208.04759 -241.91341)
		(size 0.6604)
		(drill 0.3302)
		(layers "F.Cu" "B.Cu")
		(net "TP_CHH_CPU1_DIMM2_FRU_6")
	)
	(segment
		(start 207.5942 -242.3668)
		(end 208.04759 -241.91341)
		(width 0.12954)
		(layer "B.Cu")
		(net "TP_CHH_CPU1_DIMM2_FRU_6")
	)
	(segment
		(start 207.071214 -242.3668)
		(end 207.5942 -242.3668)
		(width 0.12954)
		(layer "B.Cu")
		(net "TP_CHH_CPU1_DIMM2_FRU_6")
	)
	(segment
		(start 208.176114 -243.216684)
		(end 207.071214 -243.216684)
		(width 0.12954)
		(layer "F.Cu")
		(net "TP_CHH_CPU1_DIMM2_FRU_5")
	)
	(via
		(at 207.071214 -243.216684)
		(size 0.4572)
		(drill 0.2032)
		(layers "F.Cu" "B.Cu")
		(net "TP_CHH_CPU1_DIMM2_FRU_5")
	)
	(via
		(at 208.04759 -243.65331)
		(size 0.6604)
		(drill 0.3302)
		(layers "F.Cu" "B.Cu")
		(net "TP_CHH_CPU1_DIMM2_FRU_5")
	)
	(segment
		(start 207.610964 -243.216684)
		(end 208.04759 -243.65331)
		(width 0.12954)
		(layer "B.Cu")
		(net "TP_CHH_CPU1_DIMM2_FRU_5")
	)
	(segment
		(start 207.071214 -243.216684)
		(end 207.610964 -243.216684)
		(width 0.12954)
		(layer "B.Cu")
		(net "TP_CHH_CPU1_DIMM2_FRU_5")
	)
	(segment
		(start 207.071214 -252.566678)
		(end 208.176114 -252.566678)
		(width 0.12954)
		(layer "F.Cu")
		(net "TP_CHH_CPU1_DIMM2_FRU_4")
	)
	(via
		(at 207.071214 -252.566678)
		(size 0.4572)
		(drill 0.2032)
		(layers "F.Cu" "B.Cu")
		(net "TP_CHH_CPU1_DIMM2_FRU_4")
	)
	(via
		(at 208.172558 -250.91771)
		(size 0.6604)
		(drill 0.3302)
		(layers "F.Cu" "B.Cu")
		(net "TP_CHH_CPU1_DIMM2_FRU_4")
	)
	(segment
		(start 208.172558 -251.465334)
		(end 208.172558 -250.91771)
		(width 0.12954)
		(layer "B.Cu")
		(net "TP_CHH_CPU1_DIMM2_FRU_4")
	)
	(segment
		(start 207.071214 -252.566678)
		(end 208.172558 -251.465334)
		(width 0.12954)
		(layer "B.Cu")
		(net "TP_CHH_CPU1_DIMM2_FRU_4")
	)
	(segment
		(start 207.071214 -317.166752)
		(end 208.176114 -317.166752)
		(width 0.12954)
		(layer "F.Cu")
		(net "TP_CHH_CPU1_DIMM2_FRU_3")
	)
	(via
		(at 207.071214 -317.166752)
		(size 0.4572)
		(drill 0.2032)
		(layers "F.Cu" "B.Cu")
		(net "TP_CHH_CPU1_DIMM2_FRU_3")
	)
	(via
		(at 206.126334 -317.166752)
		(size 0.6604)
		(drill 0.3302)
		(layers "F.Cu" "B.Cu")
		(net "TP_CHH_CPU1_DIMM2_FRU_3")
	)
	(segment
		(start 207.071214 -317.166752)
		(end 206.126334 -317.166752)
		(width 0.12954)
		(layer "B.Cu")
		(net "TP_CHH_CPU1_DIMM2_FRU_3")
	)
	(segment
		(start 208.176114 -318.016636)
		(end 209.264758 -318.016636)
		(width 0.12954)
		(layer "F.Cu")
		(net "TP_CHH_CPU1_DIMM2_FRU_2")
	)
	(via
		(at 209.364072 -319.076324)
		(size 0.6604)
		(drill 0.3302)
		(layers "F.Cu" "B.Cu")
		(net "TP_CHH_CPU1_DIMM2_FRU_2")
	)
	(via
		(at 209.264758 -318.016636)
		(size 0.4572)
		(drill 0.2032)
		(layers "F.Cu" "B.Cu")
		(net "TP_CHH_CPU1_DIMM2_FRU_2")
	)
	(segment
		(start 209.364072 -319.076324)
		(end 209.148172 -318.860424)
		(width 0.12954)
		(layer "B.Cu")
		(net "TP_CHH_CPU1_DIMM2_FRU_2")
	)
	(segment
		(start 209.148172 -318.133222)
		(end 209.264758 -318.016636)
		(width 0.12954)
		(layer "B.Cu")
		(net "TP_CHH_CPU1_DIMM2_FRU_2")
	)
	(segment
		(start 209.148172 -318.860424)
		(end 209.148172 -318.133222)
		(width 0.12954)
		(layer "B.Cu")
		(net "TP_CHH_CPU1_DIMM2_FRU_2")
	)
	(segment
		(start 202.543918 -194.90563)
		(end 203.937108 -194.90563)
		(width 0.12954)
		(layer "F.Cu")
		(net "TP_CHH_CPU1_DIMM2_FRU_1")
	)
	(segment
		(start 203.937108 -194.90563)
		(end 204.076046 -194.766692)
		(width 0.12954)
		(layer "F.Cu")
		(net "TP_CHH_CPU1_DIMM2_FRU_1")
	)
	(via
		(at 201.843132 -195.606416)
		(size 0.6604)
		(drill 0.3302)
		(layers "F.Cu" "B.Cu")
		(net "TP_CHH_CPU1_DIMM2_FRU_1")
	)
	(via
		(at 202.543918 -194.90563)
		(size 0.4572)
		(drill 0.2032)
		(layers "F.Cu" "B.Cu")
		(net "TP_CHH_CPU1_DIMM2_FRU_1")
	)
	(segment
		(start 201.843132 -195.606416)
		(end 202.543918 -194.90563)
		(width 0.12954)
		(layer "B.Cu")
		(net "TP_CHH_CPU1_DIMM2_FRU_1")
	)
	(segment
		(start 204.076046 -320.566796)
		(end 202.40752 -320.566796)
		(width 0.12954)
		(layer "F.Cu")
		(net "TP_CHH_CPU1_DIMM2_FRU_0")
	)
	(via
		(at 202.40752 -320.566796)
		(size 0.4572)
		(drill 0.2032)
		(layers "F.Cu" "B.Cu")
		(net "TP_CHH_CPU1_DIMM2_FRU_0")
	)
	(segment
		(start 215.719914 -242.3668)
		(end 214.589614 -242.3668)
		(width 0.12954)
		(layer "F.Cu")
		(net "TP_CHH_CPU1_DIMM1_FRU_6")
	)
	(via
		(at 215.56599 -241.91341)
		(size 0.6604)
		(drill 0.3302)
		(layers "F.Cu" "B.Cu")
		(net "TP_CHH_CPU1_DIMM1_FRU_6")
	)
	(via
		(at 214.589614 -242.3668)
		(size 0.4572)
		(drill 0.2032)
		(layers "F.Cu" "B.Cu")
		(net "TP_CHH_CPU1_DIMM1_FRU_6")
	)
	(segment
		(start 214.589614 -242.3668)
		(end 215.1126 -242.3668)
		(width 0.12954)
		(layer "B.Cu")
		(net "TP_CHH_CPU1_DIMM1_FRU_6")
	)
	(segment
		(start 215.1126 -242.3668)
		(end 215.56599 -241.91341)
		(width 0.12954)
		(layer "B.Cu")
		(net "TP_CHH_CPU1_DIMM1_FRU_6")
	)
	(segment
		(start 215.719914 -243.216684)
		(end 214.589614 -243.216684)
		(width 0.12954)
		(layer "F.Cu")
		(net "TP_CHH_CPU1_DIMM1_FRU_5")
	)
	(via
		(at 215.56599 -243.65331)
		(size 0.6604)
		(drill 0.3302)
		(layers "F.Cu" "B.Cu")
		(net "TP_CHH_CPU1_DIMM1_FRU_5")
	)
	(via
		(at 214.589614 -243.216684)
		(size 0.4572)
		(drill 0.2032)
		(layers "F.Cu" "B.Cu")
		(net "TP_CHH_CPU1_DIMM1_FRU_5")
	)
	(segment
		(start 215.129364 -243.216684)
		(end 215.56599 -243.65331)
		(width 0.12954)
		(layer "B.Cu")
		(net "TP_CHH_CPU1_DIMM1_FRU_5")
	)
	(segment
		(start 214.589614 -243.216684)
		(end 215.129364 -243.216684)
		(width 0.12954)
		(layer "B.Cu")
		(net "TP_CHH_CPU1_DIMM1_FRU_5")
	)
	(segment
		(start 214.589614 -252.566678)
		(end 215.719914 -252.566678)
		(width 0.12954)
		(layer "F.Cu")
		(net "TP_CHH_CPU1_DIMM1_FRU_4")
	)
	(via
		(at 214.589614 -252.566678)
		(size 0.4572)
		(drill 0.2032)
		(layers "F.Cu" "B.Cu")
		(net "TP_CHH_CPU1_DIMM1_FRU_4")
	)
	(via
		(at 215.690958 -250.91771)
		(size 0.6604)
		(drill 0.3302)
		(layers "F.Cu" "B.Cu")
		(net "TP_CHH_CPU1_DIMM1_FRU_4")
	)
	(segment
		(start 215.690958 -251.465334)
		(end 214.589614 -252.566678)
		(width 0.12954)
		(layer "B.Cu")
		(net "TP_CHH_CPU1_DIMM1_FRU_4")
	)
	(segment
		(start 215.690958 -250.91771)
		(end 215.690958 -251.465334)
		(width 0.12954)
		(layer "B.Cu")
		(net "TP_CHH_CPU1_DIMM1_FRU_4")
	)
	(segment
		(start 215.083644 -317.03137)
		(end 215.219026 -317.166752)
		(width 0.12954)
		(layer "F.Cu")
		(net "TP_CHH_CPU1_DIMM1_FRU_3")
	)
	(segment
		(start 215.219026 -317.166752)
		(end 215.719914 -317.166752)
		(width 0.12954)
		(layer "F.Cu")
		(net "TP_CHH_CPU1_DIMM1_FRU_3")
	)
	(segment
		(start 214.629238 -317.03137)
		(end 215.083644 -317.03137)
		(width 0.12954)
		(layer "F.Cu")
		(net "TP_CHH_CPU1_DIMM1_FRU_3")
	)
	(via
		(at 214.629238 -317.03137)
		(size 0.4572)
		(drill 0.2032)
		(layers "F.Cu" "B.Cu")
		(net "TP_CHH_CPU1_DIMM1_FRU_3")
	)
	(via
		(at 213.803738 -316.67323)
		(size 0.6604)
		(drill 0.3302)
		(layers "F.Cu" "B.Cu")
		(net "TP_CHH_CPU1_DIMM1_FRU_3")
	)
	(segment
		(start 214.271098 -316.67323)
		(end 213.803738 -316.67323)
		(width 0.12954)
		(layer "B.Cu")
		(net "TP_CHH_CPU1_DIMM1_FRU_3")
	)
	(segment
		(start 214.629238 -317.03137)
		(end 214.271098 -316.67323)
		(width 0.12954)
		(layer "B.Cu")
		(net "TP_CHH_CPU1_DIMM1_FRU_3")
	)
	(segment
		(start 215.719914 -318.016636)
		(end 214.615014 -318.016636)
		(width 0.12954)
		(layer "F.Cu")
		(net "TP_CHH_CPU1_DIMM1_FRU_2")
	)
	(via
		(at 214.615014 -318.016636)
		(size 0.4572)
		(drill 0.2032)
		(layers "F.Cu" "B.Cu")
		(net "TP_CHH_CPU1_DIMM1_FRU_2")
	)
	(segment
		(start 210.489546 -194.766692)
		(end 211.619846 -194.766692)
		(width 0.12954)
		(layer "F.Cu")
		(net "TP_CHH_CPU1_DIMM1_FRU_1")
	)
	(via
		(at 209.65795 -195.598288)
		(size 0.6604)
		(drill 0.3302)
		(layers "F.Cu" "B.Cu")
		(net "TP_CHH_CPU1_DIMM1_FRU_1")
	)
	(via
		(at 210.489546 -194.766692)
		(size 0.4572)
		(drill 0.2032)
		(layers "F.Cu" "B.Cu")
		(net "TP_CHH_CPU1_DIMM1_FRU_1")
	)
	(segment
		(start 209.65795 -195.598288)
		(end 210.489546 -194.766692)
		(width 0.12954)
		(layer "B.Cu")
		(net "TP_CHH_CPU1_DIMM1_FRU_1")
	)
	(segment
		(start 211.619846 -320.566796)
		(end 209.9945 -320.566796)
		(width 0.12954)
		(layer "F.Cu")
		(net "TP_CHH_CPU1_DIMM1_FRU_0")
	)
	(via
		(at 209.9945 -320.566796)
		(size 0.4572)
		(drill 0.2032)
		(layers "F.Cu" "B.Cu")
		(net "TP_CHH_CPU1_DIMM1_FRU_0")
	)
	(segment
		(start 455.011282 -242.3668)
		(end 456.116182 -242.3668)
		(width 0.12954)
		(layer "F.Cu")
		(net "TP_CHH_CPU0_DIMM2_FRU_6")
	)
	(via
		(at 455.011282 -242.3668)
		(size 0.4572)
		(drill 0.2032)
		(layers "F.Cu" "B.Cu")
		(net "TP_CHH_CPU0_DIMM2_FRU_6")
	)
	(via
		(at 454.034906 -241.930174)
		(size 0.6604)
		(drill 0.3302)
		(layers "F.Cu" "B.Cu")
		(net "TP_CHH_CPU0_DIMM2_FRU_6")
	)
	(segment
		(start 454.471532 -242.3668)
		(end 454.034906 -241.930174)
		(width 0.12954)
		(layer "B.Cu")
		(net "TP_CHH_CPU0_DIMM2_FRU_6")
	)
	(segment
		(start 455.011282 -242.3668)
		(end 454.471532 -242.3668)
		(width 0.12954)
		(layer "B.Cu")
		(net "TP_CHH_CPU0_DIMM2_FRU_6")
	)
	(segment
		(start 455.011282 -243.216684)
		(end 456.116182 -243.216684)
		(width 0.12954)
		(layer "F.Cu")
		(net "TP_CHH_CPU0_DIMM2_FRU_5")
	)
	(via
		(at 455.011282 -243.216684)
		(size 0.4572)
		(drill 0.2032)
		(layers "F.Cu" "B.Cu")
		(net "TP_CHH_CPU0_DIMM2_FRU_5")
	)
	(via
		(at 454.034906 -243.670074)
		(size 0.6604)
		(drill 0.3302)
		(layers "F.Cu" "B.Cu")
		(net "TP_CHH_CPU0_DIMM2_FRU_5")
	)
	(segment
		(start 454.488296 -243.216684)
		(end 454.034906 -243.670074)
		(width 0.12954)
		(layer "B.Cu")
		(net "TP_CHH_CPU0_DIMM2_FRU_5")
	)
	(segment
		(start 455.011282 -243.216684)
		(end 454.488296 -243.216684)
		(width 0.12954)
		(layer "B.Cu")
		(net "TP_CHH_CPU0_DIMM2_FRU_5")
	)
	(segment
		(start 456.116182 -252.566678)
		(end 455.011282 -252.566678)
		(width 0.12954)
		(layer "F.Cu")
		(net "TP_CHH_CPU0_DIMM2_FRU_4")
	)
	(via
		(at 455.011282 -252.566678)
		(size 0.4572)
		(drill 0.2032)
		(layers "F.Cu" "B.Cu")
		(net "TP_CHH_CPU0_DIMM2_FRU_4")
	)
	(via
		(at 455.788268 -251.232162)
		(size 0.6604)
		(drill 0.3302)
		(layers "F.Cu" "B.Cu")
		(net "TP_CHH_CPU0_DIMM2_FRU_4")
	)
	(segment
		(start 455.788268 -251.789692)
		(end 455.788268 -251.232162)
		(width 0.12954)
		(layer "B.Cu")
		(net "TP_CHH_CPU0_DIMM2_FRU_4")
	)
	(segment
		(start 455.011282 -252.566678)
		(end 455.788268 -251.789692)
		(width 0.12954)
		(layer "B.Cu")
		(net "TP_CHH_CPU0_DIMM2_FRU_4")
	)
	(segment
		(start 456.116182 -317.166752)
		(end 455.011282 -317.166752)
		(width 0.12954)
		(layer "F.Cu")
		(net "TP_CHH_CPU0_DIMM2_FRU_3")
	)
	(via
		(at 455.011282 -317.166752)
		(size 0.4572)
		(drill 0.2032)
		(layers "F.Cu" "B.Cu")
		(net "TP_CHH_CPU0_DIMM2_FRU_3")
	)
	(via
		(at 454.286874 -317.166752)
		(size 0.6604)
		(drill 0.3302)
		(layers "F.Cu" "B.Cu")
		(net "TP_CHH_CPU0_DIMM2_FRU_3")
	)
	(segment
		(start 455.011282 -317.166752)
		(end 454.286874 -317.166752)
		(width 0.12954)
		(layer "B.Cu")
		(net "TP_CHH_CPU0_DIMM2_FRU_3")
	)
	(segment
		(start 456.116182 -318.016636)
		(end 457.204826 -318.016636)
		(width 0.12954)
		(layer "F.Cu")
		(net "TP_CHH_CPU0_DIMM2_FRU_2")
	)
	(via
		(at 458.052678 -317.805816)
		(size 0.6604)
		(drill 0.3302)
		(layers "F.Cu" "B.Cu")
		(net "TP_CHH_CPU0_DIMM2_FRU_2")
	)
	(via
		(at 457.204826 -318.016636)
		(size 0.4572)
		(drill 0.2032)
		(layers "F.Cu" "B.Cu")
		(net "TP_CHH_CPU0_DIMM2_FRU_2")
	)
	(segment
		(start 457.204826 -318.016636)
		(end 457.415646 -317.805816)
		(width 0.12954)
		(layer "B.Cu")
		(net "TP_CHH_CPU0_DIMM2_FRU_2")
	)
	(segment
		(start 457.415646 -317.805816)
		(end 458.052678 -317.805816)
		(width 0.12954)
		(layer "B.Cu")
		(net "TP_CHH_CPU0_DIMM2_FRU_2")
	)
	(segment
		(start 450.622924 -194.766692)
		(end 452.016114 -194.766692)
		(width 0.12954)
		(layer "F.Cu")
		(net "TP_CHH_CPU0_DIMM2_FRU_1")
	)
	(segment
		(start 450.483986 -194.90563)
		(end 450.622924 -194.766692)
		(width 0.12954)
		(layer "F.Cu")
		(net "TP_CHH_CPU0_DIMM2_FRU_1")
	)
	(via
		(at 450.483986 -194.90563)
		(size 0.4572)
		(drill 0.2032)
		(layers "F.Cu" "B.Cu")
		(net "TP_CHH_CPU0_DIMM2_FRU_1")
	)
	(via
		(at 450.483986 -193.965068)
		(size 0.6604)
		(drill 0.3302)
		(layers "F.Cu" "B.Cu")
		(net "TP_CHH_CPU0_DIMM2_FRU_1")
	)
	(segment
		(start 450.483986 -194.90563)
		(end 450.483986 -193.965068)
		(width 0.12954)
		(layer "B.Cu")
		(net "TP_CHH_CPU0_DIMM2_FRU_1")
	)
	(segment
		(start 450.44106 -320.566796)
		(end 452.016114 -320.566796)
		(width 0.12954)
		(layer "F.Cu")
		(net "TP_CHH_CPU0_DIMM2_FRU_0")
	)
	(via
		(at 450.44106 -320.566796)
		(size 0.4572)
		(drill 0.2032)
		(layers "F.Cu" "B.Cu")
		(net "TP_CHH_CPU0_DIMM2_FRU_0")
	)
	(segment
		(start 462.529682 -242.3668)
		(end 463.659982 -242.3668)
		(width 0.12954)
		(layer "F.Cu")
		(net "TP_CHH_CPU0_DIMM1_FRU_6")
	)
	(via
		(at 463.506058 -241.91341)
		(size 0.6604)
		(drill 0.3302)
		(layers "F.Cu" "B.Cu")
		(net "TP_CHH_CPU0_DIMM1_FRU_6")
	)
	(via
		(at 462.529682 -242.3668)
		(size 0.4572)
		(drill 0.2032)
		(layers "F.Cu" "B.Cu")
		(net "TP_CHH_CPU0_DIMM1_FRU_6")
	)
	(segment
		(start 462.529682 -242.3668)
		(end 463.052668 -242.3668)
		(width 0.12954)
		(layer "B.Cu")
		(net "TP_CHH_CPU0_DIMM1_FRU_6")
	)
	(segment
		(start 463.052668 -242.3668)
		(end 463.506058 -241.91341)
		(width 0.12954)
		(layer "B.Cu")
		(net "TP_CHH_CPU0_DIMM1_FRU_6")
	)
	(segment
		(start 462.529682 -243.216684)
		(end 463.659982 -243.216684)
		(width 0.12954)
		(layer "F.Cu")
		(net "TP_CHH_CPU0_DIMM1_FRU_5")
	)
	(via
		(at 463.506058 -243.65331)
		(size 0.6604)
		(drill 0.3302)
		(layers "F.Cu" "B.Cu")
		(net "TP_CHH_CPU0_DIMM1_FRU_5")
	)
	(via
		(at 462.529682 -243.216684)
		(size 0.4572)
		(drill 0.2032)
		(layers "F.Cu" "B.Cu")
		(net "TP_CHH_CPU0_DIMM1_FRU_5")
	)
	(segment
		(start 463.069432 -243.216684)
		(end 462.529682 -243.216684)
		(width 0.12954)
		(layer "B.Cu")
		(net "TP_CHH_CPU0_DIMM1_FRU_5")
	)
	(segment
		(start 463.506058 -243.65331)
		(end 463.069432 -243.216684)
		(width 0.12954)
		(layer "B.Cu")
		(net "TP_CHH_CPU0_DIMM1_FRU_5")
	)
	(segment
		(start 463.659982 -252.566678)
		(end 462.529682 -252.566678)
		(width 0.12954)
		(layer "F.Cu")
		(net "TP_CHH_CPU0_DIMM1_FRU_4")
	)
	(via
		(at 463.306668 -251.232162)
		(size 0.6604)
		(drill 0.3302)
		(layers "F.Cu" "B.Cu")
		(net "TP_CHH_CPU0_DIMM1_FRU_4")
	)
	(via
		(at 462.529682 -252.566678)
		(size 0.4572)
		(drill 0.2032)
		(layers "F.Cu" "B.Cu")
		(net "TP_CHH_CPU0_DIMM1_FRU_4")
	)
	(segment
		(start 463.306668 -251.232162)
		(end 463.306668 -251.789692)
		(width 0.12954)
		(layer "B.Cu")
		(net "TP_CHH_CPU0_DIMM1_FRU_4")
	)
	(segment
		(start 463.306668 -251.789692)
		(end 462.529682 -252.566678)
		(width 0.12954)
		(layer "B.Cu")
		(net "TP_CHH_CPU0_DIMM1_FRU_4")
	)
	(segment
		(start 462.569306 -317.03137)
		(end 462.924144 -317.03137)
		(width 0.12954)
		(layer "F.Cu")
		(net "TP_CHH_CPU0_DIMM1_FRU_3")
	)
	(segment
		(start 463.059526 -317.166752)
		(end 463.659982 -317.166752)
		(width 0.12954)
		(layer "F.Cu")
		(net "TP_CHH_CPU0_DIMM1_FRU_3")
	)
	(segment
		(start 462.924144 -317.03137)
		(end 463.059526 -317.166752)
		(width 0.12954)
		(layer "F.Cu")
		(net "TP_CHH_CPU0_DIMM1_FRU_3")
	)
	(via
		(at 462.569306 -317.03137)
		(size 0.4572)
		(drill 0.2032)
		(layers "F.Cu" "B.Cu")
		(net "TP_CHH_CPU0_DIMM1_FRU_3")
	)
	(via
		(at 461.84566 -313.042808)
		(size 0.6604)
		(drill 0.3302)
		(layers "F.Cu" "B.Cu")
		(net "TP_CHH_CPU0_DIMM1_FRU_3")
	)
	(segment
		(start 462.0387 -313.235848)
		(end 461.84566 -313.042808)
		(width 0.12954)
		(layer "B.Cu")
		(net "TP_CHH_CPU0_DIMM1_FRU_3")
	)
	(segment
		(start 462.569306 -317.03137)
		(end 462.0387 -316.500764)
		(width 0.12954)
		(layer "B.Cu")
		(net "TP_CHH_CPU0_DIMM1_FRU_3")
	)
	(segment
		(start 462.0387 -316.500764)
		(end 462.0387 -313.235848)
		(width 0.12954)
		(layer "B.Cu")
		(net "TP_CHH_CPU0_DIMM1_FRU_3")
	)
	(segment
		(start 463.659982 -318.016636)
		(end 462.555082 -318.016636)
		(width 0.12954)
		(layer "F.Cu")
		(net "TP_CHH_CPU0_DIMM1_FRU_2")
	)
	(via
		(at 462.555082 -318.016636)
		(size 0.4572)
		(drill 0.2032)
		(layers "F.Cu" "B.Cu")
		(net "TP_CHH_CPU0_DIMM1_FRU_2")
	)
	(segment
		(start 459.559914 -194.766692)
		(end 458.429614 -194.766692)
		(width 0.12954)
		(layer "F.Cu")
		(net "TP_CHH_CPU0_DIMM1_FRU_1")
	)
	(via
		(at 458.429614 -194.766692)
		(size 0.4572)
		(drill 0.2032)
		(layers "F.Cu" "B.Cu")
		(net "TP_CHH_CPU0_DIMM1_FRU_1")
	)
	(via
		(at 458.429614 -193.82613)
		(size 0.6604)
		(drill 0.3302)
		(layers "F.Cu" "B.Cu")
		(net "TP_CHH_CPU0_DIMM1_FRU_1")
	)
	(segment
		(start 458.429614 -193.82613)
		(end 458.429614 -194.766692)
		(width 0.12954)
		(layer "B.Cu")
		(net "TP_CHH_CPU0_DIMM1_FRU_1")
	)
	(segment
		(start 457.9874 -320.566796)
		(end 459.559914 -320.566796)
		(width 0.12954)
		(layer "F.Cu")
		(net "TP_CHH_CPU0_DIMM1_FRU_0")
	)
	(via
		(at 457.9874 -320.566796)
		(size 0.4572)
		(drill 0.2032)
		(layers "F.Cu" "B.Cu")
		(net "TP_CHH_CPU0_DIMM1_FRU_0")
	)
	(segment
		(start 193.088514 -242.3668)
		(end 191.983614 -242.3668)
		(width 0.12954)
		(layer "F.Cu")
		(net "TP_CHG_CPU1_DIMM2_FRU_6")
	)
	(via
		(at 191.983614 -242.3668)
		(size 0.4572)
		(drill 0.2032)
		(layers "F.Cu" "B.Cu")
		(net "TP_CHG_CPU1_DIMM2_FRU_6")
	)
	(via
		(at 191.007238 -241.930174)
		(size 0.6604)
		(drill 0.3302)
		(layers "F.Cu" "B.Cu")
		(net "TP_CHG_CPU1_DIMM2_FRU_6")
	)
	(segment
		(start 191.983614 -242.3668)
		(end 191.443864 -242.3668)
		(width 0.12954)
		(layer "B.Cu")
		(net "TP_CHG_CPU1_DIMM2_FRU_6")
	)
	(segment
		(start 191.443864 -242.3668)
		(end 191.007238 -241.930174)
		(width 0.12954)
		(layer "B.Cu")
		(net "TP_CHG_CPU1_DIMM2_FRU_6")
	)
	(segment
		(start 193.088514 -243.216684)
		(end 191.983614 -243.216684)
		(width 0.12954)
		(layer "F.Cu")
		(net "TP_CHG_CPU1_DIMM2_FRU_5")
	)
	(via
		(at 191.007238 -243.670074)
		(size 0.6604)
		(drill 0.3302)
		(layers "F.Cu" "B.Cu")
		(net "TP_CHG_CPU1_DIMM2_FRU_5")
	)
	(via
		(at 191.983614 -243.216684)
		(size 0.4572)
		(drill 0.2032)
		(layers "F.Cu" "B.Cu")
		(net "TP_CHG_CPU1_DIMM2_FRU_5")
	)
	(segment
		(start 191.983614 -243.216684)
		(end 191.460628 -243.216684)
		(width 0.12954)
		(layer "B.Cu")
		(net "TP_CHG_CPU1_DIMM2_FRU_5")
	)
	(segment
		(start 191.460628 -243.216684)
		(end 191.007238 -243.670074)
		(width 0.12954)
		(layer "B.Cu")
		(net "TP_CHG_CPU1_DIMM2_FRU_5")
	)
	(segment
		(start 191.983614 -252.566678)
		(end 193.088514 -252.566678)
		(width 0.12954)
		(layer "F.Cu")
		(net "TP_CHG_CPU1_DIMM2_FRU_4")
	)
	(via
		(at 191.983614 -252.566678)
		(size 0.4572)
		(drill 0.2032)
		(layers "F.Cu" "B.Cu")
		(net "TP_CHG_CPU1_DIMM2_FRU_4")
	)
	(via
		(at 190.88227 -250.91771)
		(size 0.6604)
		(drill 0.3302)
		(layers "F.Cu" "B.Cu")
		(net "TP_CHG_CPU1_DIMM2_FRU_4")
	)
	(segment
		(start 191.983614 -252.566678)
		(end 190.88227 -251.465334)
		(width 0.12954)
		(layer "B.Cu")
		(net "TP_CHG_CPU1_DIMM2_FRU_4")
	)
	(segment
		(start 190.88227 -251.465334)
		(end 190.88227 -250.91771)
		(width 0.12954)
		(layer "B.Cu")
		(net "TP_CHG_CPU1_DIMM2_FRU_4")
	)
	(segment
		(start 191.983614 -317.166752)
		(end 193.088514 -317.166752)
		(width 0.12954)
		(layer "F.Cu")
		(net "TP_CHG_CPU1_DIMM2_FRU_3")
	)
	(via
		(at 191.983614 -317.166752)
		(size 0.4572)
		(drill 0.2032)
		(layers "F.Cu" "B.Cu")
		(net "TP_CHG_CPU1_DIMM2_FRU_3")
	)
	(via
		(at 191.428624 -317.571374)
		(size 0.6604)
		(drill 0.3302)
		(layers "F.Cu" "B.Cu")
		(net "TP_CHG_CPU1_DIMM2_FRU_3")
	)
	(segment
		(start 191.983614 -317.166752)
		(end 191.833246 -317.166752)
		(width 0.12954)
		(layer "B.Cu")
		(net "TP_CHG_CPU1_DIMM2_FRU_3")
	)
	(segment
		(start 191.833246 -317.166752)
		(end 191.428624 -317.571374)
		(width 0.12954)
		(layer "B.Cu")
		(net "TP_CHG_CPU1_DIMM2_FRU_3")
	)
	(segment
		(start 193.088514 -318.016636)
		(end 191.983614 -318.016636)
		(width 0.12954)
		(layer "F.Cu")
		(net "TP_CHG_CPU1_DIMM2_FRU_2")
	)
	(via
		(at 192.823846 -316.897004)
		(size 0.6604)
		(drill 0.3302)
		(layers "F.Cu" "B.Cu")
		(net "TP_CHG_CPU1_DIMM2_FRU_2")
	)
	(via
		(at 191.983614 -318.016636)
		(size 0.4572)
		(drill 0.2032)
		(layers "F.Cu" "B.Cu")
		(net "TP_CHG_CPU1_DIMM2_FRU_2")
	)
	(segment
		(start 192.823846 -317.176404)
		(end 192.823846 -316.897004)
		(width 0.12954)
		(layer "B.Cu")
		(net "TP_CHG_CPU1_DIMM2_FRU_2")
	)
	(segment
		(start 191.983614 -318.016636)
		(end 192.823846 -317.176404)
		(width 0.12954)
		(layer "B.Cu")
		(net "TP_CHG_CPU1_DIMM2_FRU_2")
	)
	(segment
		(start 187.883546 -194.766692)
		(end 188.988446 -194.766692)
		(width 0.12954)
		(layer "F.Cu")
		(net "TP_CHG_CPU1_DIMM2_FRU_1")
	)
	(via
		(at 187.05195 -195.598288)
		(size 0.6604)
		(drill 0.3302)
		(layers "F.Cu" "B.Cu")
		(net "TP_CHG_CPU1_DIMM2_FRU_1")
	)
	(via
		(at 187.883546 -194.766692)
		(size 0.4572)
		(drill 0.2032)
		(layers "F.Cu" "B.Cu")
		(net "TP_CHG_CPU1_DIMM2_FRU_1")
	)
	(segment
		(start 187.05195 -195.598288)
		(end 187.376308 -195.27393)
		(width 0.12954)
		(layer "B.Cu")
		(net "TP_CHG_CPU1_DIMM2_FRU_1")
	)
	(segment
		(start 187.376308 -195.27393)
		(end 187.62091 -195.172584)
		(width 0.12954)
		(layer "B.Cu")
		(net "TP_CHG_CPU1_DIMM2_FRU_1")
	)
	(segment
		(start 187.883546 -194.909948)
		(end 187.883546 -194.766692)
		(width 0.12954)
		(layer "B.Cu")
		(net "TP_CHG_CPU1_DIMM2_FRU_1")
	)
	(segment
		(start 187.62091 -195.172584)
		(end 187.883546 -194.909948)
		(width 0.12954)
		(layer "B.Cu")
		(net "TP_CHG_CPU1_DIMM2_FRU_1")
	)
	(segment
		(start 188.988446 -320.566796)
		(end 187.34532 -320.566796)
		(width 0.12954)
		(layer "F.Cu")
		(net "TP_CHG_CPU1_DIMM2_FRU_0")
	)
	(via
		(at 187.34532 -320.566796)
		(size 0.4572)
		(drill 0.2032)
		(layers "F.Cu" "B.Cu")
		(net "TP_CHG_CPU1_DIMM2_FRU_0")
	)
	(segment
		(start 200.632314 -242.3668)
		(end 199.527414 -242.3668)
		(width 0.12954)
		(layer "F.Cu")
		(net "TP_CHG_CPU1_DIMM1_FRU_6")
	)
	(via
		(at 200.50379 -241.91341)
		(size 0.6604)
		(drill 0.3302)
		(layers "F.Cu" "B.Cu")
		(net "TP_CHG_CPU1_DIMM1_FRU_6")
	)
	(via
		(at 199.527414 -242.3668)
		(size 0.4572)
		(drill 0.2032)
		(layers "F.Cu" "B.Cu")
		(net "TP_CHG_CPU1_DIMM1_FRU_6")
	)
	(segment
		(start 199.527414 -242.3668)
		(end 200.0504 -242.3668)
		(width 0.12954)
		(layer "B.Cu")
		(net "TP_CHG_CPU1_DIMM1_FRU_6")
	)
	(segment
		(start 200.0504 -242.3668)
		(end 200.50379 -241.91341)
		(width 0.12954)
		(layer "B.Cu")
		(net "TP_CHG_CPU1_DIMM1_FRU_6")
	)
	(segment
		(start 200.632314 -243.216684)
		(end 199.527414 -243.216684)
		(width 0.12954)
		(layer "F.Cu")
		(net "TP_CHG_CPU1_DIMM1_FRU_5")
	)
	(via
		(at 200.50379 -243.65331)
		(size 0.6604)
		(drill 0.3302)
		(layers "F.Cu" "B.Cu")
		(net "TP_CHG_CPU1_DIMM1_FRU_5")
	)
	(via
		(at 199.527414 -243.216684)
		(size 0.4572)
		(drill 0.2032)
		(layers "F.Cu" "B.Cu")
		(net "TP_CHG_CPU1_DIMM1_FRU_5")
	)
	(segment
		(start 200.067164 -243.216684)
		(end 200.50379 -243.65331)
		(width 0.12954)
		(layer "B.Cu")
		(net "TP_CHG_CPU1_DIMM1_FRU_5")
	)
	(segment
		(start 199.527414 -243.216684)
		(end 200.067164 -243.216684)
		(width 0.12954)
		(layer "B.Cu")
		(net "TP_CHG_CPU1_DIMM1_FRU_5")
	)
	(segment
		(start 199.527414 -252.566678)
		(end 200.632314 -252.566678)
		(width 0.12954)
		(layer "F.Cu")
		(net "TP_CHG_CPU1_DIMM1_FRU_4")
	)
	(via
		(at 200.628758 -250.91771)
		(size 0.6604)
		(drill 0.3302)
		(layers "F.Cu" "B.Cu")
		(net "TP_CHG_CPU1_DIMM1_FRU_4")
	)
	(via
		(at 199.527414 -252.566678)
		(size 0.4572)
		(drill 0.2032)
		(layers "F.Cu" "B.Cu")
		(net "TP_CHG_CPU1_DIMM1_FRU_4")
	)
	(segment
		(start 200.628758 -251.465334)
		(end 200.628758 -250.91771)
		(width 0.12954)
		(layer "B.Cu")
		(net "TP_CHG_CPU1_DIMM1_FRU_4")
	)
	(segment
		(start 199.527414 -252.566678)
		(end 200.628758 -251.465334)
		(width 0.12954)
		(layer "B.Cu")
		(net "TP_CHG_CPU1_DIMM1_FRU_4")
	)
	(segment
		(start 199.527414 -317.166752)
		(end 200.632314 -317.166752)
		(width 0.12954)
		(layer "F.Cu")
		(net "TP_CHG_CPU1_DIMM1_FRU_3")
	)
	(via
		(at 199.527414 -317.166752)
		(size 0.4572)
		(drill 0.2032)
		(layers "F.Cu" "B.Cu")
		(net "TP_CHG_CPU1_DIMM1_FRU_3")
	)
	(via
		(at 200.37806 -317.166752)
		(size 0.6604)
		(drill 0.3302)
		(layers "F.Cu" "B.Cu")
		(net "TP_CHG_CPU1_DIMM1_FRU_3")
	)
	(segment
		(start 199.527414 -317.166752)
		(end 200.37806 -317.166752)
		(width 0.12954)
		(layer "B.Cu")
		(net "TP_CHG_CPU1_DIMM1_FRU_3")
	)
	(segment
		(start 200.632314 -318.016636)
		(end 201.715878 -318.016636)
		(width 0.12954)
		(layer "F.Cu")
		(net "TP_CHG_CPU1_DIMM1_FRU_2")
	)
	(via
		(at 201.715878 -317.16599)
		(size 0.6604)
		(drill 0.3302)
		(layers "F.Cu" "B.Cu")
		(net "TP_CHG_CPU1_DIMM1_FRU_2")
	)
	(via
		(at 201.715878 -318.016636)
		(size 0.4572)
		(drill 0.2032)
		(layers "F.Cu" "B.Cu")
		(net "TP_CHG_CPU1_DIMM1_FRU_2")
	)
	(segment
		(start 201.715878 -318.016636)
		(end 201.715878 -317.16599)
		(width 0.12954)
		(layer "B.Cu")
		(net "TP_CHG_CPU1_DIMM1_FRU_2")
	)
	(segment
		(start 196.532246 -194.766692)
		(end 195.427346 -194.766692)
		(width 0.12954)
		(layer "F.Cu")
		(net "TP_CHG_CPU1_DIMM1_FRU_1")
	)
	(via
		(at 195.427346 -194.766692)
		(size 0.4572)
		(drill 0.2032)
		(layers "F.Cu" "B.Cu")
		(net "TP_CHG_CPU1_DIMM1_FRU_1")
	)
	(via
		(at 194.59575 -195.598288)
		(size 0.6604)
		(drill 0.3302)
		(layers "F.Cu" "B.Cu")
		(net "TP_CHG_CPU1_DIMM1_FRU_1")
	)
	(segment
		(start 194.59575 -195.598288)
		(end 195.427346 -194.766692)
		(width 0.12954)
		(layer "B.Cu")
		(net "TP_CHG_CPU1_DIMM1_FRU_1")
	)
	(segment
		(start 196.532246 -320.566796)
		(end 194.83832 -320.566796)
		(width 0.12954)
		(layer "F.Cu")
		(net "TP_CHG_CPU1_DIMM1_FRU_0")
	)
	(via
		(at 194.83832 -320.566796)
		(size 0.4572)
		(drill 0.2032)
		(layers "F.Cu" "B.Cu")
		(net "TP_CHG_CPU1_DIMM1_FRU_0")
	)
	(segment
		(start 439.923682 -242.3668)
		(end 441.028582 -242.3668)
		(width 0.12954)
		(layer "F.Cu")
		(net "TP_CHG_CPU0_DIMM2_FRU_6")
	)
	(via
		(at 438.947306 -241.930174)
		(size 0.6604)
		(drill 0.3302)
		(layers "F.Cu" "B.Cu")
		(net "TP_CHG_CPU0_DIMM2_FRU_6")
	)
	(via
		(at 439.923682 -242.3668)
		(size 0.4572)
		(drill 0.2032)
		(layers "F.Cu" "B.Cu")
		(net "TP_CHG_CPU0_DIMM2_FRU_6")
	)
	(segment
		(start 439.923682 -242.3668)
		(end 439.383932 -242.3668)
		(width 0.12954)
		(layer "B.Cu")
		(net "TP_CHG_CPU0_DIMM2_FRU_6")
	)
	(segment
		(start 439.383932 -242.3668)
		(end 438.947306 -241.930174)
		(width 0.12954)
		(layer "B.Cu")
		(net "TP_CHG_CPU0_DIMM2_FRU_6")
	)
	(segment
		(start 439.923682 -243.216684)
		(end 441.028582 -243.216684)
		(width 0.12954)
		(layer "F.Cu")
		(net "TP_CHG_CPU0_DIMM2_FRU_5")
	)
	(via
		(at 439.923682 -243.216684)
		(size 0.4572)
		(drill 0.2032)
		(layers "F.Cu" "B.Cu")
		(net "TP_CHG_CPU0_DIMM2_FRU_5")
	)
	(via
		(at 438.947306 -243.670074)
		(size 0.6604)
		(drill 0.3302)
		(layers "F.Cu" "B.Cu")
		(net "TP_CHG_CPU0_DIMM2_FRU_5")
	)
	(segment
		(start 439.923682 -243.216684)
		(end 439.400696 -243.216684)
		(width 0.12954)
		(layer "B.Cu")
		(net "TP_CHG_CPU0_DIMM2_FRU_5")
	)
	(segment
		(start 439.400696 -243.216684)
		(end 438.947306 -243.670074)
		(width 0.12954)
		(layer "B.Cu")
		(net "TP_CHG_CPU0_DIMM2_FRU_5")
	)
	(segment
		(start 441.028582 -252.566678)
		(end 439.923682 -252.566678)
		(width 0.12954)
		(layer "F.Cu")
		(net "TP_CHG_CPU0_DIMM2_FRU_4")
	)
	(via
		(at 439.146696 -250.93549)
		(size 0.6604)
		(drill 0.3302)
		(layers "F.Cu" "B.Cu")
		(net "TP_CHG_CPU0_DIMM2_FRU_4")
	)
	(via
		(at 439.923682 -252.566678)
		(size 0.4572)
		(drill 0.2032)
		(layers "F.Cu" "B.Cu")
		(net "TP_CHG_CPU0_DIMM2_FRU_4")
	)
	(segment
		(start 439.923682 -252.566678)
		(end 439.146696 -251.789692)
		(width 0.12954)
		(layer "B.Cu")
		(net "TP_CHG_CPU0_DIMM2_FRU_4")
	)
	(segment
		(start 439.146696 -251.789692)
		(end 439.146696 -250.93549)
		(width 0.12954)
		(layer "B.Cu")
		(net "TP_CHG_CPU0_DIMM2_FRU_4")
	)
	(segment
		(start 441.028582 -317.166752)
		(end 439.923682 -317.166752)
		(width 0.12954)
		(layer "F.Cu")
		(net "TP_CHG_CPU0_DIMM2_FRU_3")
	)
	(via
		(at 439.033158 -315.71057)
		(size 0.6604)
		(drill 0.3302)
		(layers "F.Cu" "B.Cu")
		(net "TP_CHG_CPU0_DIMM2_FRU_3")
	)
	(via
		(at 439.923682 -317.166752)
		(size 0.4572)
		(drill 0.2032)
		(layers "F.Cu" "B.Cu")
		(net "TP_CHG_CPU0_DIMM2_FRU_3")
	)
	(segment
		(start 439.923682 -317.166752)
		(end 439.033158 -316.276228)
		(width 0.12954)
		(layer "B.Cu")
		(net "TP_CHG_CPU0_DIMM2_FRU_3")
	)
	(segment
		(start 439.033158 -316.276228)
		(end 439.033158 -315.71057)
		(width 0.12954)
		(layer "B.Cu")
		(net "TP_CHG_CPU0_DIMM2_FRU_3")
	)
	(segment
		(start 441.028582 -318.016636)
		(end 439.923682 -318.016636)
		(width 0.12954)
		(layer "F.Cu")
		(net "TP_CHG_CPU0_DIMM2_FRU_2")
	)
	(via
		(at 439.923682 -318.016636)
		(size 0.4572)
		(drill 0.2032)
		(layers "F.Cu" "B.Cu")
		(net "TP_CHG_CPU0_DIMM2_FRU_2")
	)
	(via
		(at 441.12561 -317.34887)
		(size 0.6604)
		(drill 0.3302)
		(layers "F.Cu" "B.Cu")
		(net "TP_CHG_CPU0_DIMM2_FRU_2")
	)
	(segment
		(start 440.591448 -317.34887)
		(end 441.12561 -317.34887)
		(width 0.12954)
		(layer "B.Cu")
		(net "TP_CHG_CPU0_DIMM2_FRU_2")
	)
	(segment
		(start 439.923682 -318.016636)
		(end 440.591448 -317.34887)
		(width 0.12954)
		(layer "B.Cu")
		(net "TP_CHG_CPU0_DIMM2_FRU_2")
	)
	(segment
		(start 436.928514 -194.766692)
		(end 435.823614 -194.766692)
		(width 0.12954)
		(layer "F.Cu")
		(net "TP_CHG_CPU0_DIMM2_FRU_1")
	)
	(via
		(at 435.823614 -194.766692)
		(size 0.4572)
		(drill 0.2032)
		(layers "F.Cu" "B.Cu")
		(net "TP_CHG_CPU0_DIMM2_FRU_1")
	)
	(via
		(at 434.900578 -195.53047)
		(size 0.6604)
		(drill 0.3302)
		(layers "F.Cu" "B.Cu")
		(net "TP_CHG_CPU0_DIMM2_FRU_1")
	)
	(segment
		(start 435.39918 -195.191126)
		(end 435.823614 -194.766692)
		(width 0.12954)
		(layer "B.Cu")
		(net "TP_CHG_CPU0_DIMM2_FRU_1")
	)
	(segment
		(start 435.239922 -195.191126)
		(end 435.39918 -195.191126)
		(width 0.12954)
		(layer "B.Cu")
		(net "TP_CHG_CPU0_DIMM2_FRU_1")
	)
	(segment
		(start 434.900578 -195.53047)
		(end 435.239922 -195.191126)
		(width 0.12954)
		(layer "B.Cu")
		(net "TP_CHG_CPU0_DIMM2_FRU_1")
	)
	(segment
		(start 435.33822 -320.566796)
		(end 436.928514 -320.566796)
		(width 0.12954)
		(layer "F.Cu")
		(net "TP_CHG_CPU0_DIMM2_FRU_0")
	)
	(via
		(at 435.33822 -320.566796)
		(size 0.4572)
		(drill 0.2032)
		(layers "F.Cu" "B.Cu")
		(net "TP_CHG_CPU0_DIMM2_FRU_0")
	)
	(segment
		(start 447.467482 -242.3668)
		(end 448.572382 -242.3668)
		(width 0.12954)
		(layer "F.Cu")
		(net "TP_CHG_CPU0_DIMM1_FRU_6")
	)
	(via
		(at 447.467482 -242.3668)
		(size 0.4572)
		(drill 0.2032)
		(layers "F.Cu" "B.Cu")
		(net "TP_CHG_CPU0_DIMM1_FRU_6")
	)
	(via
		(at 446.491106 -241.930174)
		(size 0.6604)
		(drill 0.3302)
		(layers "F.Cu" "B.Cu")
		(net "TP_CHG_CPU0_DIMM1_FRU_6")
	)
	(segment
		(start 446.927732 -242.3668)
		(end 446.491106 -241.930174)
		(width 0.12954)
		(layer "B.Cu")
		(net "TP_CHG_CPU0_DIMM1_FRU_6")
	)
	(segment
		(start 447.467482 -242.3668)
		(end 446.927732 -242.3668)
		(width 0.12954)
		(layer "B.Cu")
		(net "TP_CHG_CPU0_DIMM1_FRU_6")
	)
	(segment
		(start 447.467482 -243.216684)
		(end 448.572382 -243.216684)
		(width 0.12954)
		(layer "F.Cu")
		(net "TP_CHG_CPU0_DIMM1_FRU_5")
	)
	(via
		(at 446.491106 -243.670074)
		(size 0.6604)
		(drill 0.3302)
		(layers "F.Cu" "B.Cu")
		(net "TP_CHG_CPU0_DIMM1_FRU_5")
	)
	(via
		(at 447.467482 -243.216684)
		(size 0.4572)
		(drill 0.2032)
		(layers "F.Cu" "B.Cu")
		(net "TP_CHG_CPU0_DIMM1_FRU_5")
	)
	(segment
		(start 446.944496 -243.216684)
		(end 446.491106 -243.670074)
		(width 0.12954)
		(layer "B.Cu")
		(net "TP_CHG_CPU0_DIMM1_FRU_5")
	)
	(segment
		(start 447.467482 -243.216684)
		(end 446.944496 -243.216684)
		(width 0.12954)
		(layer "B.Cu")
		(net "TP_CHG_CPU0_DIMM1_FRU_5")
	)
	(segment
		(start 448.572382 -252.566678)
		(end 447.467482 -252.566678)
		(width 0.12954)
		(layer "F.Cu")
		(net "TP_CHG_CPU0_DIMM1_FRU_4")
	)
	(via
		(at 448.244468 -251.232162)
		(size 0.6604)
		(drill 0.3302)
		(layers "F.Cu" "B.Cu")
		(net "TP_CHG_CPU0_DIMM1_FRU_4")
	)
	(via
		(at 447.467482 -252.566678)
		(size 0.4572)
		(drill 0.2032)
		(layers "F.Cu" "B.Cu")
		(net "TP_CHG_CPU0_DIMM1_FRU_4")
	)
	(segment
		(start 447.467482 -252.566678)
		(end 448.244468 -251.789692)
		(width 0.12954)
		(layer "B.Cu")
		(net "TP_CHG_CPU0_DIMM1_FRU_4")
	)
	(segment
		(start 448.244468 -251.789692)
		(end 448.244468 -251.232162)
		(width 0.12954)
		(layer "B.Cu")
		(net "TP_CHG_CPU0_DIMM1_FRU_4")
	)
	(segment
		(start 448.572382 -317.166752)
		(end 447.467482 -317.166752)
		(width 0.12954)
		(layer "F.Cu")
		(net "TP_CHG_CPU0_DIMM1_FRU_3")
	)
	(via
		(at 448.097402 -316.731396)
		(size 0.6604)
		(drill 0.3302)
		(layers "F.Cu" "B.Cu")
		(net "TP_CHG_CPU0_DIMM1_FRU_3")
	)
	(via
		(at 447.467482 -317.166752)
		(size 0.4572)
		(drill 0.2032)
		(layers "F.Cu" "B.Cu")
		(net "TP_CHG_CPU0_DIMM1_FRU_3")
	)
	(segment
		(start 447.902838 -316.731396)
		(end 448.097402 -316.731396)
		(width 0.12954)
		(layer "B.Cu")
		(net "TP_CHG_CPU0_DIMM1_FRU_3")
	)
	(segment
		(start 447.467482 -317.166752)
		(end 447.902838 -316.731396)
		(width 0.12954)
		(layer "B.Cu")
		(net "TP_CHG_CPU0_DIMM1_FRU_3")
	)
	(segment
		(start 448.572382 -318.016636)
		(end 449.655946 -318.016636)
		(width 0.12954)
		(layer "F.Cu")
		(net "TP_CHG_CPU0_DIMM1_FRU_2")
	)
	(via
		(at 449.655946 -317.292228)
		(size 0.6604)
		(drill 0.3302)
		(layers "F.Cu" "B.Cu")
		(net "TP_CHG_CPU0_DIMM1_FRU_2")
	)
	(via
		(at 449.655946 -318.016636)
		(size 0.4572)
		(drill 0.2032)
		(layers "F.Cu" "B.Cu")
		(net "TP_CHG_CPU0_DIMM1_FRU_2")
	)
	(segment
		(start 449.655946 -318.016636)
		(end 449.655946 -317.292228)
		(width 0.12954)
		(layer "B.Cu")
		(net "TP_CHG_CPU0_DIMM1_FRU_2")
	)
	(segment
		(start 443.367414 -194.766692)
		(end 444.472314 -194.766692)
		(width 0.12954)
		(layer "F.Cu")
		(net "TP_CHG_CPU0_DIMM1_FRU_1")
	)
	(via
		(at 443.367414 -194.766692)
		(size 0.4572)
		(drill 0.2032)
		(layers "F.Cu" "B.Cu")
		(net "TP_CHG_CPU0_DIMM1_FRU_1")
	)
	(via
		(at 443.367414 -193.82613)
		(size 0.6604)
		(drill 0.3302)
		(layers "F.Cu" "B.Cu")
		(net "TP_CHG_CPU0_DIMM1_FRU_1")
	)
	(segment
		(start 443.367414 -194.766692)
		(end 443.367414 -193.82613)
		(width 0.12954)
		(layer "B.Cu")
		(net "TP_CHG_CPU0_DIMM1_FRU_1")
	)
	(segment
		(start 442.90234 -320.566796)
		(end 444.472314 -320.566796)
		(width 0.12954)
		(layer "F.Cu")
		(net "TP_CHG_CPU0_DIMM1_FRU_0")
	)
	(via
		(at 442.90234 -320.566796)
		(size 0.4572)
		(drill 0.2032)
		(layers "F.Cu" "B.Cu")
		(net "TP_CHG_CPU0_DIMM1_FRU_0")
	)
	(segment
		(start 178.000914 -242.3668)
		(end 176.896014 -242.3668)
		(width 0.12954)
		(layer "F.Cu")
		(net "TP_CHF_CPU1_DIMM2_FRU_6")
	)
	(via
		(at 176.896014 -242.3668)
		(size 0.4572)
		(drill 0.2032)
		(layers "F.Cu" "B.Cu")
		(net "TP_CHF_CPU1_DIMM2_FRU_6")
	)
	(via
		(at 177.55616 -241.958368)
		(size 0.6604)
		(drill 0.3302)
		(layers "F.Cu" "B.Cu")
		(net "TP_CHF_CPU1_DIMM2_FRU_6")
	)
	(segment
		(start 177.304446 -241.958368)
		(end 177.55616 -241.958368)
		(width 0.12954)
		(layer "B.Cu")
		(net "TP_CHF_CPU1_DIMM2_FRU_6")
	)
	(segment
		(start 176.896014 -242.3668)
		(end 177.304446 -241.958368)
		(width 0.12954)
		(layer "B.Cu")
		(net "TP_CHF_CPU1_DIMM2_FRU_6")
	)
	(segment
		(start 178.000914 -243.216684)
		(end 176.896014 -243.216684)
		(width 0.12954)
		(layer "F.Cu")
		(net "TP_CHF_CPU1_DIMM2_FRU_5")
	)
	(via
		(at 177.52568 -243.650008)
		(size 0.6604)
		(drill 0.3302)
		(layers "F.Cu" "B.Cu")
		(net "TP_CHF_CPU1_DIMM2_FRU_5")
	)
	(via
		(at 176.896014 -243.216684)
		(size 0.4572)
		(drill 0.2032)
		(layers "F.Cu" "B.Cu")
		(net "TP_CHF_CPU1_DIMM2_FRU_5")
	)
	(segment
		(start 177.329338 -243.650008)
		(end 176.896014 -243.216684)
		(width 0.12954)
		(layer "B.Cu")
		(net "TP_CHF_CPU1_DIMM2_FRU_5")
	)
	(segment
		(start 177.52568 -243.650008)
		(end 177.329338 -243.650008)
		(width 0.12954)
		(layer "B.Cu")
		(net "TP_CHF_CPU1_DIMM2_FRU_5")
	)
	(segment
		(start 176.896014 -252.566678)
		(end 178.000914 -252.566678)
		(width 0.12954)
		(layer "F.Cu")
		(net "TP_CHF_CPU1_DIMM2_FRU_4")
	)
	(via
		(at 178.076098 -251.135134)
		(size 0.6604)
		(drill 0.3302)
		(layers "F.Cu" "B.Cu")
		(net "TP_CHF_CPU1_DIMM2_FRU_4")
	)
	(via
		(at 176.896014 -252.566678)
		(size 0.4572)
		(drill 0.2032)
		(layers "F.Cu" "B.Cu")
		(net "TP_CHF_CPU1_DIMM2_FRU_4")
	)
	(segment
		(start 178.076098 -251.135134)
		(end 178.076098 -251.97689)
		(width 0.12954)
		(layer "B.Cu")
		(net "TP_CHF_CPU1_DIMM2_FRU_4")
	)
	(segment
		(start 177.48631 -252.566678)
		(end 176.896014 -252.566678)
		(width 0.12954)
		(layer "B.Cu")
		(net "TP_CHF_CPU1_DIMM2_FRU_4")
	)
	(segment
		(start 178.076098 -251.97689)
		(end 177.48631 -252.566678)
		(width 0.12954)
		(layer "B.Cu")
		(net "TP_CHF_CPU1_DIMM2_FRU_4")
	)
	(segment
		(start 176.896014 -317.166752)
		(end 178.000914 -317.166752)
		(width 0.12954)
		(layer "F.Cu")
		(net "TP_CHF_CPU1_DIMM2_FRU_3")
	)
	(via
		(at 177.593244 -316.532768)
		(size 0.6604)
		(drill 0.3302)
		(layers "F.Cu" "B.Cu")
		(net "TP_CHF_CPU1_DIMM2_FRU_3")
	)
	(via
		(at 176.896014 -317.166752)
		(size 0.4572)
		(drill 0.2032)
		(layers "F.Cu" "B.Cu")
		(net "TP_CHF_CPU1_DIMM2_FRU_3")
	)
	(segment
		(start 176.896014 -317.123318)
		(end 176.896014 -317.166752)
		(width 0.12954)
		(layer "B.Cu")
		(net "TP_CHF_CPU1_DIMM2_FRU_3")
	)
	(segment
		(start 177.593244 -316.532768)
		(end 177.486564 -316.532768)
		(width 0.12954)
		(layer "B.Cu")
		(net "TP_CHF_CPU1_DIMM2_FRU_3")
	)
	(segment
		(start 177.486564 -316.532768)
		(end 176.896014 -317.123318)
		(width 0.12954)
		(layer "B.Cu")
		(net "TP_CHF_CPU1_DIMM2_FRU_3")
	)
	(segment
		(start 178.000914 -318.016636)
		(end 179.079398 -318.016636)
		(width 0.12954)
		(layer "F.Cu")
		(net "TP_CHF_CPU1_DIMM2_FRU_2")
	)
	(via
		(at 178.76266 -317.403988)
		(size 0.6604)
		(drill 0.3302)
		(layers "F.Cu" "B.Cu")
		(net "TP_CHF_CPU1_DIMM2_FRU_2")
	)
	(via
		(at 179.079398 -318.016636)
		(size 0.4572)
		(drill 0.2032)
		(layers "F.Cu" "B.Cu")
		(net "TP_CHF_CPU1_DIMM2_FRU_2")
	)
	(segment
		(start 179.079398 -318.016636)
		(end 178.76266 -317.699898)
		(width 0.12954)
		(layer "B.Cu")
		(net "TP_CHF_CPU1_DIMM2_FRU_2")
	)
	(segment
		(start 178.76266 -317.699898)
		(end 178.76266 -317.403988)
		(width 0.12954)
		(layer "B.Cu")
		(net "TP_CHF_CPU1_DIMM2_FRU_2")
	)
	(segment
		(start 173.900846 -194.766692)
		(end 172.795946 -194.766692)
		(width 0.12954)
		(layer "F.Cu")
		(net "TP_CHF_CPU1_DIMM2_FRU_1")
	)
	(via
		(at 172.795946 -194.766692)
		(size 0.4572)
		(drill 0.2032)
		(layers "F.Cu" "B.Cu")
		(net "TP_CHF_CPU1_DIMM2_FRU_1")
	)
	(via
		(at 171.83989 -195.532248)
		(size 0.6604)
		(drill 0.3302)
		(layers "F.Cu" "B.Cu")
		(net "TP_CHF_CPU1_DIMM2_FRU_1")
	)
	(segment
		(start 172.129958 -194.896232)
		(end 172.129958 -195.24218)
		(width 0.12954)
		(layer "B.Cu")
		(net "TP_CHF_CPU1_DIMM2_FRU_1")
	)
	(segment
		(start 172.259498 -194.766692)
		(end 172.129958 -194.896232)
		(width 0.12954)
		(layer "B.Cu")
		(net "TP_CHF_CPU1_DIMM2_FRU_1")
	)
	(segment
		(start 172.795946 -194.766692)
		(end 172.259498 -194.766692)
		(width 0.12954)
		(layer "B.Cu")
		(net "TP_CHF_CPU1_DIMM2_FRU_1")
	)
	(segment
		(start 172.129958 -195.24218)
		(end 171.83989 -195.532248)
		(width 0.12954)
		(layer "B.Cu")
		(net "TP_CHF_CPU1_DIMM2_FRU_1")
	)
	(segment
		(start 173.900846 -320.566796)
		(end 172.20692 -320.566796)
		(width 0.12954)
		(layer "F.Cu")
		(net "TP_CHF_CPU1_DIMM2_FRU_0")
	)
	(via
		(at 172.20692 -320.566796)
		(size 0.4572)
		(drill 0.2032)
		(layers "F.Cu" "B.Cu")
		(net "TP_CHF_CPU1_DIMM2_FRU_0")
	)
	(segment
		(start 184.414414 -242.3668)
		(end 185.544714 -242.3668)
		(width 0.12954)
		(layer "F.Cu")
		(net "TP_CHF_CPU1_DIMM1_FRU_6")
	)
	(via
		(at 185.39079 -241.91341)
		(size 0.6604)
		(drill 0.3302)
		(layers "F.Cu" "B.Cu")
		(net "TP_CHF_CPU1_DIMM1_FRU_6")
	)
	(via
		(at 184.414414 -242.3668)
		(size 0.4572)
		(drill 0.2032)
		(layers "F.Cu" "B.Cu")
		(net "TP_CHF_CPU1_DIMM1_FRU_6")
	)
	(segment
		(start 184.414414 -242.3668)
		(end 184.9374 -242.3668)
		(width 0.12954)
		(layer "B.Cu")
		(net "TP_CHF_CPU1_DIMM1_FRU_6")
	)
	(segment
		(start 184.9374 -242.3668)
		(end 185.39079 -241.91341)
		(width 0.12954)
		(layer "B.Cu")
		(net "TP_CHF_CPU1_DIMM1_FRU_6")
	)
	(segment
		(start 184.414414 -243.216684)
		(end 185.544714 -243.216684)
		(width 0.12954)
		(layer "F.Cu")
		(net "TP_CHF_CPU1_DIMM1_FRU_5")
	)
	(via
		(at 184.414414 -243.216684)
		(size 0.4572)
		(drill 0.2032)
		(layers "F.Cu" "B.Cu")
		(net "TP_CHF_CPU1_DIMM1_FRU_5")
	)
	(via
		(at 185.39079 -243.65331)
		(size 0.6604)
		(drill 0.3302)
		(layers "F.Cu" "B.Cu")
		(net "TP_CHF_CPU1_DIMM1_FRU_5")
	)
	(segment
		(start 184.954164 -243.216684)
		(end 184.414414 -243.216684)
		(width 0.12954)
		(layer "B.Cu")
		(net "TP_CHF_CPU1_DIMM1_FRU_5")
	)
	(segment
		(start 185.39079 -243.65331)
		(end 184.954164 -243.216684)
		(width 0.12954)
		(layer "B.Cu")
		(net "TP_CHF_CPU1_DIMM1_FRU_5")
	)
	(segment
		(start 184.414414 -252.566678)
		(end 185.544714 -252.566678)
		(width 0.12954)
		(layer "F.Cu")
		(net "TP_CHF_CPU1_DIMM1_FRU_4")
	)
	(via
		(at 183.88965 -250.10745)
		(size 0.6604)
		(drill 0.3302)
		(layers "F.Cu" "B.Cu")
		(net "TP_CHF_CPU1_DIMM1_FRU_4")
	)
	(via
		(at 184.414414 -252.566678)
		(size 0.4572)
		(drill 0.2032)
		(layers "F.Cu" "B.Cu")
		(net "TP_CHF_CPU1_DIMM1_FRU_4")
	)
	(segment
		(start 184.414414 -252.566678)
		(end 183.88965 -252.041914)
		(width 0.12954)
		(layer "B.Cu")
		(net "TP_CHF_CPU1_DIMM1_FRU_4")
	)
	(segment
		(start 183.88965 -252.041914)
		(end 183.88965 -250.10745)
		(width 0.12954)
		(layer "B.Cu")
		(net "TP_CHF_CPU1_DIMM1_FRU_4")
	)
	(segment
		(start 184.439814 -317.166752)
		(end 185.544714 -317.166752)
		(width 0.12954)
		(layer "F.Cu")
		(net "TP_CHF_CPU1_DIMM1_FRU_3")
	)
	(via
		(at 184.439814 -317.166752)
		(size 0.4572)
		(drill 0.2032)
		(layers "F.Cu" "B.Cu")
		(net "TP_CHF_CPU1_DIMM1_FRU_3")
	)
	(via
		(at 183.589168 -317.166752)
		(size 0.6604)
		(drill 0.3302)
		(layers "F.Cu" "B.Cu")
		(net "TP_CHF_CPU1_DIMM1_FRU_3")
	)
	(segment
		(start 184.439814 -317.166752)
		(end 183.589168 -317.166752)
		(width 0.12954)
		(layer "B.Cu")
		(net "TP_CHF_CPU1_DIMM1_FRU_3")
	)
	(segment
		(start 185.544714 -318.016636)
		(end 186.681618 -318.016636)
		(width 0.12954)
		(layer "F.Cu")
		(net "TP_CHF_CPU1_DIMM1_FRU_2")
	)
	(via
		(at 186.681618 -318.016636)
		(size 0.4572)
		(drill 0.2032)
		(layers "F.Cu" "B.Cu")
		(net "TP_CHF_CPU1_DIMM1_FRU_2")
	)
	(via
		(at 187.614052 -318.399414)
		(size 0.6604)
		(drill 0.3302)
		(layers "F.Cu" "B.Cu")
		(net "TP_CHF_CPU1_DIMM1_FRU_2")
	)
	(segment
		(start 187.064396 -318.399414)
		(end 187.614052 -318.399414)
		(width 0.12954)
		(layer "B.Cu")
		(net "TP_CHF_CPU1_DIMM1_FRU_2")
	)
	(segment
		(start 186.681618 -318.016636)
		(end 187.064396 -318.399414)
		(width 0.12954)
		(layer "B.Cu")
		(net "TP_CHF_CPU1_DIMM1_FRU_2")
	)
	(segment
		(start 181.444646 -194.766692)
		(end 180.314346 -194.766692)
		(width 0.12954)
		(layer "F.Cu")
		(net "TP_CHF_CPU1_DIMM1_FRU_1")
	)
	(via
		(at 180.314346 -194.766692)
		(size 0.4572)
		(drill 0.2032)
		(layers "F.Cu" "B.Cu")
		(net "TP_CHF_CPU1_DIMM1_FRU_1")
	)
	(via
		(at 180.445918 -196.51599)
		(size 0.6604)
		(drill 0.3302)
		(layers "F.Cu" "B.Cu")
		(net "TP_CHF_CPU1_DIMM1_FRU_1")
	)
	(segment
		(start 180.314346 -194.766692)
		(end 180.707538 -194.766692)
		(width 0.12954)
		(layer "B.Cu")
		(net "TP_CHF_CPU1_DIMM1_FRU_1")
	)
	(segment
		(start 180.837078 -196.12483)
		(end 180.445918 -196.51599)
		(width 0.12954)
		(layer "B.Cu")
		(net "TP_CHF_CPU1_DIMM1_FRU_1")
	)
	(segment
		(start 180.707538 -194.766692)
		(end 180.837078 -194.896232)
		(width 0.12954)
		(layer "B.Cu")
		(net "TP_CHF_CPU1_DIMM1_FRU_1")
	)
	(segment
		(start 180.837078 -194.896232)
		(end 180.837078 -196.12483)
		(width 0.12954)
		(layer "B.Cu")
		(net "TP_CHF_CPU1_DIMM1_FRU_1")
	)
	(segment
		(start 181.444646 -320.566796)
		(end 179.85486 -320.566796)
		(width 0.12954)
		(layer "F.Cu")
		(net "TP_CHF_CPU1_DIMM1_FRU_0")
	)
	(via
		(at 179.85486 -320.566796)
		(size 0.4572)
		(drill 0.2032)
		(layers "F.Cu" "B.Cu")
		(net "TP_CHF_CPU1_DIMM1_FRU_0")
	)
	(segment
		(start 424.836082 -242.3668)
		(end 425.940982 -242.3668)
		(width 0.12954)
		(layer "F.Cu")
		(net "TP_CHF_CPU0_DIMM2_FRU_6")
	)
	(via
		(at 425.812458 -241.91341)
		(size 0.6604)
		(drill 0.3302)
		(layers "F.Cu" "B.Cu")
		(net "TP_CHF_CPU0_DIMM2_FRU_6")
	)
	(via
		(at 424.836082 -242.3668)
		(size 0.4572)
		(drill 0.2032)
		(layers "F.Cu" "B.Cu")
		(net "TP_CHF_CPU0_DIMM2_FRU_6")
	)
	(segment
		(start 425.359068 -242.3668)
		(end 424.836082 -242.3668)
		(width 0.12954)
		(layer "B.Cu")
		(net "TP_CHF_CPU0_DIMM2_FRU_6")
	)
	(segment
		(start 425.812458 -241.91341)
		(end 425.359068 -242.3668)
		(width 0.12954)
		(layer "B.Cu")
		(net "TP_CHF_CPU0_DIMM2_FRU_6")
	)
	(segment
		(start 424.836082 -243.216684)
		(end 425.940982 -243.216684)
		(width 0.12954)
		(layer "F.Cu")
		(net "TP_CHF_CPU0_DIMM2_FRU_5")
	)
	(via
		(at 425.812458 -243.65331)
		(size 0.6604)
		(drill 0.3302)
		(layers "F.Cu" "B.Cu")
		(net "TP_CHF_CPU0_DIMM2_FRU_5")
	)
	(via
		(at 424.836082 -243.216684)
		(size 0.4572)
		(drill 0.2032)
		(layers "F.Cu" "B.Cu")
		(net "TP_CHF_CPU0_DIMM2_FRU_5")
	)
	(segment
		(start 425.812458 -243.65331)
		(end 425.375832 -243.216684)
		(width 0.12954)
		(layer "B.Cu")
		(net "TP_CHF_CPU0_DIMM2_FRU_5")
	)
	(segment
		(start 425.375832 -243.216684)
		(end 424.836082 -243.216684)
		(width 0.12954)
		(layer "B.Cu")
		(net "TP_CHF_CPU0_DIMM2_FRU_5")
	)
	(segment
		(start 425.940982 -252.566678)
		(end 424.836082 -252.566678)
		(width 0.12954)
		(layer "F.Cu")
		(net "TP_CHF_CPU0_DIMM2_FRU_4")
	)
	(via
		(at 424.836082 -252.566678)
		(size 0.4572)
		(drill 0.2032)
		(layers "F.Cu" "B.Cu")
		(net "TP_CHF_CPU0_DIMM2_FRU_4")
	)
	(via
		(at 425.613068 -251.232162)
		(size 0.6604)
		(drill 0.3302)
		(layers "F.Cu" "B.Cu")
		(net "TP_CHF_CPU0_DIMM2_FRU_4")
	)
	(segment
		(start 425.613068 -251.232162)
		(end 425.613068 -251.789692)
		(width 0.12954)
		(layer "B.Cu")
		(net "TP_CHF_CPU0_DIMM2_FRU_4")
	)
	(segment
		(start 425.613068 -251.789692)
		(end 424.836082 -252.566678)
		(width 0.12954)
		(layer "B.Cu")
		(net "TP_CHF_CPU0_DIMM2_FRU_4")
	)
	(segment
		(start 425.940982 -317.166752)
		(end 424.836082 -317.166752)
		(width 0.12954)
		(layer "F.Cu")
		(net "TP_CHF_CPU0_DIMM2_FRU_3")
	)
	(via
		(at 424.836082 -317.166752)
		(size 0.4572)
		(drill 0.2032)
		(layers "F.Cu" "B.Cu")
		(net "TP_CHF_CPU0_DIMM2_FRU_3")
	)
	(via
		(at 424.111674 -317.166752)
		(size 0.6604)
		(drill 0.3302)
		(layers "F.Cu" "B.Cu")
		(net "TP_CHF_CPU0_DIMM2_FRU_3")
	)
	(segment
		(start 424.836082 -317.166752)
		(end 424.111674 -317.166752)
		(width 0.12954)
		(layer "B.Cu")
		(net "TP_CHF_CPU0_DIMM2_FRU_3")
	)
	(segment
		(start 425.940982 -318.016636)
		(end 427.019466 -318.016636)
		(width 0.12954)
		(layer "F.Cu")
		(net "TP_CHF_CPU0_DIMM2_FRU_2")
	)
	(via
		(at 427.019466 -318.016636)
		(size 0.4572)
		(drill 0.2032)
		(layers "F.Cu" "B.Cu")
		(net "TP_CHF_CPU0_DIMM2_FRU_2")
	)
	(via
		(at 426.598588 -317.370206)
		(size 0.6604)
		(drill 0.3302)
		(layers "F.Cu" "B.Cu")
		(net "TP_CHF_CPU0_DIMM2_FRU_2")
	)
	(segment
		(start 427.019466 -318.016636)
		(end 427.019466 -317.791084)
		(width 0.12954)
		(layer "B.Cu")
		(net "TP_CHF_CPU0_DIMM2_FRU_2")
	)
	(segment
		(start 427.019466 -317.791084)
		(end 426.598588 -317.370206)
		(width 0.12954)
		(layer "B.Cu")
		(net "TP_CHF_CPU0_DIMM2_FRU_2")
	)
	(segment
		(start 420.736014 -194.766692)
		(end 421.840914 -194.766692)
		(width 0.12954)
		(layer "F.Cu")
		(net "TP_CHF_CPU0_DIMM2_FRU_1")
	)
	(via
		(at 419.812978 -195.53047)
		(size 0.6604)
		(drill 0.3302)
		(layers "F.Cu" "B.Cu")
		(net "TP_CHF_CPU0_DIMM2_FRU_1")
	)
	(via
		(at 420.736014 -194.766692)
		(size 0.4572)
		(drill 0.2032)
		(layers "F.Cu" "B.Cu")
		(net "TP_CHF_CPU0_DIMM2_FRU_1")
	)
	(segment
		(start 420.152322 -195.191126)
		(end 420.31158 -195.191126)
		(width 0.12954)
		(layer "B.Cu")
		(net "TP_CHF_CPU0_DIMM2_FRU_1")
	)
	(segment
		(start 420.31158 -195.191126)
		(end 420.736014 -194.766692)
		(width 0.12954)
		(layer "B.Cu")
		(net "TP_CHF_CPU0_DIMM2_FRU_1")
	)
	(segment
		(start 419.812978 -195.53047)
		(end 420.152322 -195.191126)
		(width 0.12954)
		(layer "B.Cu")
		(net "TP_CHF_CPU0_DIMM2_FRU_1")
	)
	(segment
		(start 420.2684 -320.736468)
		(end 420.6494 -320.736468)
		(width 0.12954)
		(layer "F.Cu")
		(net "TP_CHF_CPU0_DIMM2_FRU_0")
	)
	(segment
		(start 420.819072 -320.566796)
		(end 421.840914 -320.566796)
		(width 0.12954)
		(layer "F.Cu")
		(net "TP_CHF_CPU0_DIMM2_FRU_0")
	)
	(segment
		(start 420.6494 -320.736468)
		(end 420.819072 -320.566796)
		(width 0.12954)
		(layer "F.Cu")
		(net "TP_CHF_CPU0_DIMM2_FRU_0")
	)
	(via
		(at 420.2684 -320.736468)
		(size 0.4572)
		(drill 0.2032)
		(layers "F.Cu" "B.Cu")
		(net "TP_CHF_CPU0_DIMM2_FRU_0")
	)
	(segment
		(start 433.484782 -242.3668)
		(end 432.354482 -242.3668)
		(width 0.12954)
		(layer "F.Cu")
		(net "TP_CHF_CPU0_DIMM1_FRU_6")
	)
	(via
		(at 432.354482 -242.3668)
		(size 0.4572)
		(drill 0.2032)
		(layers "F.Cu" "B.Cu")
		(net "TP_CHF_CPU0_DIMM1_FRU_6")
	)
	(via
		(at 433.330858 -241.91341)
		(size 0.6604)
		(drill 0.3302)
		(layers "F.Cu" "B.Cu")
		(net "TP_CHF_CPU0_DIMM1_FRU_6")
	)
	(segment
		(start 432.877468 -242.3668)
		(end 433.330858 -241.91341)
		(width 0.12954)
		(layer "B.Cu")
		(net "TP_CHF_CPU0_DIMM1_FRU_6")
	)
	(segment
		(start 432.354482 -242.3668)
		(end 432.877468 -242.3668)
		(width 0.12954)
		(layer "B.Cu")
		(net "TP_CHF_CPU0_DIMM1_FRU_6")
	)
	(segment
		(start 433.484782 -243.216684)
		(end 432.354482 -243.216684)
		(width 0.12954)
		(layer "F.Cu")
		(net "TP_CHF_CPU0_DIMM1_FRU_5")
	)
	(via
		(at 433.330858 -243.65331)
		(size 0.6604)
		(drill 0.3302)
		(layers "F.Cu" "B.Cu")
		(net "TP_CHF_CPU0_DIMM1_FRU_5")
	)
	(via
		(at 432.354482 -243.216684)
		(size 0.4572)
		(drill 0.2032)
		(layers "F.Cu" "B.Cu")
		(net "TP_CHF_CPU0_DIMM1_FRU_5")
	)
	(segment
		(start 433.330858 -243.65331)
		(end 432.894232 -243.216684)
		(width 0.12954)
		(layer "B.Cu")
		(net "TP_CHF_CPU0_DIMM1_FRU_5")
	)
	(segment
		(start 432.894232 -243.216684)
		(end 432.354482 -243.216684)
		(width 0.12954)
		(layer "B.Cu")
		(net "TP_CHF_CPU0_DIMM1_FRU_5")
	)
	(segment
		(start 433.484782 -252.566678)
		(end 432.354482 -252.566678)
		(width 0.12954)
		(layer "F.Cu")
		(net "TP_CHF_CPU0_DIMM1_FRU_4")
	)
	(via
		(at 433.131468 -251.232162)
		(size 0.6604)
		(drill 0.3302)
		(layers "F.Cu" "B.Cu")
		(net "TP_CHF_CPU0_DIMM1_FRU_4")
	)
	(via
		(at 432.354482 -252.566678)
		(size 0.4572)
		(drill 0.2032)
		(layers "F.Cu" "B.Cu")
		(net "TP_CHF_CPU0_DIMM1_FRU_4")
	)
	(segment
		(start 433.131468 -251.789692)
		(end 432.354482 -252.566678)
		(width 0.12954)
		(layer "B.Cu")
		(net "TP_CHF_CPU0_DIMM1_FRU_4")
	)
	(segment
		(start 433.131468 -251.232162)
		(end 433.131468 -251.789692)
		(width 0.12954)
		(layer "B.Cu")
		(net "TP_CHF_CPU0_DIMM1_FRU_4")
	)
	(segment
		(start 433.484782 -317.166752)
		(end 432.379882 -317.166752)
		(width 0.12954)
		(layer "F.Cu")
		(net "TP_CHF_CPU0_DIMM1_FRU_3")
	)
	(via
		(at 431.655474 -317.166752)
		(size 0.6604)
		(drill 0.3302)
		(layers "F.Cu" "B.Cu")
		(net "TP_CHF_CPU0_DIMM1_FRU_3")
	)
	(via
		(at 432.379882 -317.166752)
		(size 0.4572)
		(drill 0.2032)
		(layers "F.Cu" "B.Cu")
		(net "TP_CHF_CPU0_DIMM1_FRU_3")
	)
	(segment
		(start 432.379882 -317.166752)
		(end 431.655474 -317.166752)
		(width 0.12954)
		(layer "B.Cu")
		(net "TP_CHF_CPU0_DIMM1_FRU_3")
	)
	(segment
		(start 433.484782 -318.016636)
		(end 434.621686 -318.016636)
		(width 0.12954)
		(layer "F.Cu")
		(net "TP_CHF_CPU0_DIMM1_FRU_2")
	)
	(via
		(at 434.621686 -318.016636)
		(size 0.4572)
		(drill 0.2032)
		(layers "F.Cu" "B.Cu")
		(net "TP_CHF_CPU0_DIMM1_FRU_2")
	)
	(via
		(at 434.432202 -317.279528)
		(size 0.6604)
		(drill 0.3302)
		(layers "F.Cu" "B.Cu")
		(net "TP_CHF_CPU0_DIMM1_FRU_2")
	)
	(segment
		(start 434.621686 -317.469012)
		(end 434.432202 -317.279528)
		(width 0.12954)
		(layer "B.Cu")
		(net "TP_CHF_CPU0_DIMM1_FRU_2")
	)
	(segment
		(start 434.621686 -318.016636)
		(end 434.621686 -317.469012)
		(width 0.12954)
		(layer "B.Cu")
		(net "TP_CHF_CPU0_DIMM1_FRU_2")
	)
	(segment
		(start 428.254414 -194.766692)
		(end 429.384714 -194.766692)
		(width 0.12954)
		(layer "F.Cu")
		(net "TP_CHF_CPU0_DIMM1_FRU_1")
	)
	(via
		(at 428.254414 -193.82613)
		(size 0.6604)
		(drill 0.3302)
		(layers "F.Cu" "B.Cu")
		(net "TP_CHF_CPU0_DIMM1_FRU_1")
	)
	(via
		(at 428.254414 -194.766692)
		(size 0.4572)
		(drill 0.2032)
		(layers "F.Cu" "B.Cu")
		(net "TP_CHF_CPU0_DIMM1_FRU_1")
	)
	(segment
		(start 428.254414 -194.766692)
		(end 428.254414 -193.82613)
		(width 0.12954)
		(layer "B.Cu")
		(net "TP_CHF_CPU0_DIMM1_FRU_1")
	)
	(segment
		(start 427.609 -321.135248)
		(end 428.177452 -320.566796)
		(width 0.12954)
		(layer "F.Cu")
		(net "TP_CHF_CPU0_DIMM1_FRU_0")
	)
	(segment
		(start 428.177452 -320.566796)
		(end 429.384714 -320.566796)
		(width 0.12954)
		(layer "F.Cu")
		(net "TP_CHF_CPU0_DIMM1_FRU_0")
	)
	(via
		(at 427.609 -321.135248)
		(size 0.4572)
		(drill 0.2032)
		(layers "F.Cu" "B.Cu")
		(net "TP_CHF_CPU0_DIMM1_FRU_0")
	)
	(segment
		(start 161.783014 -242.3668)
		(end 162.913314 -242.3668)
		(width 0.12954)
		(layer "F.Cu")
		(net "TP_CHE_CPU1_DIMM2_FRU_6")
	)
	(via
		(at 161.783014 -242.3668)
		(size 0.4572)
		(drill 0.2032)
		(layers "F.Cu" "B.Cu")
		(net "TP_CHE_CPU1_DIMM2_FRU_6")
	)
	(via
		(at 162.75939 -241.91341)
		(size 0.6604)
		(drill 0.3302)
		(layers "F.Cu" "B.Cu")
		(net "TP_CHE_CPU1_DIMM2_FRU_6")
	)
	(segment
		(start 161.783014 -242.3668)
		(end 162.306 -242.3668)
		(width 0.12954)
		(layer "B.Cu")
		(net "TP_CHE_CPU1_DIMM2_FRU_6")
	)
	(segment
		(start 162.306 -242.3668)
		(end 162.75939 -241.91341)
		(width 0.12954)
		(layer "B.Cu")
		(net "TP_CHE_CPU1_DIMM2_FRU_6")
	)
	(segment
		(start 161.783014 -243.216684)
		(end 162.913314 -243.216684)
		(width 0.12954)
		(layer "F.Cu")
		(net "TP_CHE_CPU1_DIMM2_FRU_5")
	)
	(via
		(at 162.75939 -243.65331)
		(size 0.6604)
		(drill 0.3302)
		(layers "F.Cu" "B.Cu")
		(net "TP_CHE_CPU1_DIMM2_FRU_5")
	)
	(via
		(at 161.783014 -243.216684)
		(size 0.4572)
		(drill 0.2032)
		(layers "F.Cu" "B.Cu")
		(net "TP_CHE_CPU1_DIMM2_FRU_5")
	)
	(segment
		(start 162.322764 -243.216684)
		(end 161.783014 -243.216684)
		(width 0.12954)
		(layer "B.Cu")
		(net "TP_CHE_CPU1_DIMM2_FRU_5")
	)
	(segment
		(start 162.75939 -243.65331)
		(end 162.322764 -243.216684)
		(width 0.12954)
		(layer "B.Cu")
		(net "TP_CHE_CPU1_DIMM2_FRU_5")
	)
	(segment
		(start 163.641278 -252.849126)
		(end 163.641278 -254.08255)
		(width 0.12954)
		(layer "F.Cu")
		(net "TP_CHE_CPU1_DIMM2_FRU_4")
	)
	(segment
		(start 163.35883 -252.566678)
		(end 163.641278 -252.849126)
		(width 0.12954)
		(layer "F.Cu")
		(net "TP_CHE_CPU1_DIMM2_FRU_4")
	)
	(segment
		(start 162.913314 -252.566678)
		(end 163.35883 -252.566678)
		(width 0.12954)
		(layer "F.Cu")
		(net "TP_CHE_CPU1_DIMM2_FRU_4")
	)
	(via
		(at 163.641278 -254.08255)
		(size 0.4572)
		(drill 0.2032)
		(layers "F.Cu" "B.Cu")
		(net "TP_CHE_CPU1_DIMM2_FRU_4")
	)
	(via
		(at 164.513006 -253.301754)
		(size 0.6604)
		(drill 0.3302)
		(layers "F.Cu" "B.Cu")
		(net "TP_CHE_CPU1_DIMM2_FRU_4")
	)
	(segment
		(start 164.513006 -253.301754)
		(end 164.380418 -253.434342)
		(width 0.12954)
		(layer "B.Cu")
		(net "TP_CHE_CPU1_DIMM2_FRU_4")
	)
	(segment
		(start 164.380418 -253.434342)
		(end 164.289486 -253.434342)
		(width 0.12954)
		(layer "B.Cu")
		(net "TP_CHE_CPU1_DIMM2_FRU_4")
	)
	(segment
		(start 164.289486 -253.434342)
		(end 163.641278 -254.08255)
		(width 0.12954)
		(layer "B.Cu")
		(net "TP_CHE_CPU1_DIMM2_FRU_4")
	)
	(segment
		(start 162.937952 -317.19139)
		(end 164.057838 -317.19139)
		(width 0.12954)
		(layer "F.Cu")
		(net "TP_CHE_CPU1_DIMM2_FRU_3")
	)
	(segment
		(start 162.913314 -317.166752)
		(end 162.937952 -317.19139)
		(width 0.12954)
		(layer "F.Cu")
		(net "TP_CHE_CPU1_DIMM2_FRU_3")
	)
	(via
		(at 164.057838 -317.19139)
		(size 0.4572)
		(drill 0.2032)
		(layers "F.Cu" "B.Cu")
		(net "TP_CHE_CPU1_DIMM2_FRU_3")
	)
	(via
		(at 163.207192 -317.19139)
		(size 0.6604)
		(drill 0.3302)
		(layers "F.Cu" "B.Cu")
		(net "TP_CHE_CPU1_DIMM2_FRU_3")
	)
	(segment
		(start 164.057838 -317.19139)
		(end 163.207192 -317.19139)
		(width 0.12954)
		(layer "B.Cu")
		(net "TP_CHE_CPU1_DIMM2_FRU_3")
	)
	(segment
		(start 161.808414 -318.016636)
		(end 162.913314 -318.016636)
		(width 0.12954)
		(layer "F.Cu")
		(net "TP_CHE_CPU1_DIMM2_FRU_2")
	)
	(via
		(at 161.808414 -317.16599)
		(size 0.6604)
		(drill 0.3302)
		(layers "F.Cu" "B.Cu")
		(net "TP_CHE_CPU1_DIMM2_FRU_2")
	)
	(via
		(at 161.808414 -318.016636)
		(size 0.4572)
		(drill 0.2032)
		(layers "F.Cu" "B.Cu")
		(net "TP_CHE_CPU1_DIMM2_FRU_2")
	)
	(segment
		(start 161.808414 -318.016636)
		(end 161.808414 -317.16599)
		(width 0.12954)
		(layer "B.Cu")
		(net "TP_CHE_CPU1_DIMM2_FRU_2")
	)
	(segment
		(start 158.894526 -194.685412)
		(end 159.933132 -194.685412)
		(width 0.12954)
		(layer "F.Cu")
		(net "TP_CHE_CPU1_DIMM2_FRU_1")
	)
	(segment
		(start 158.813246 -194.766692)
		(end 158.894526 -194.685412)
		(width 0.12954)
		(layer "F.Cu")
		(net "TP_CHE_CPU1_DIMM2_FRU_1")
	)
	(via
		(at 160.332674 -194.111626)
		(size 0.6604)
		(drill 0.3302)
		(layers "F.Cu" "B.Cu")
		(net "TP_CHE_CPU1_DIMM2_FRU_1")
	)
	(via
		(at 159.933132 -194.685412)
		(size 0.4572)
		(drill 0.2032)
		(layers "F.Cu" "B.Cu")
		(net "TP_CHE_CPU1_DIMM2_FRU_1")
	)
	(segment
		(start 159.933132 -194.685412)
		(end 160.186116 -194.685412)
		(width 0.12954)
		(layer "B.Cu")
		(net "TP_CHE_CPU1_DIMM2_FRU_1")
	)
	(segment
		(start 160.332674 -194.538854)
		(end 160.332674 -194.111626)
		(width 0.12954)
		(layer "B.Cu")
		(net "TP_CHE_CPU1_DIMM2_FRU_1")
	)
	(segment
		(start 160.186116 -194.685412)
		(end 160.332674 -194.538854)
		(width 0.12954)
		(layer "B.Cu")
		(net "TP_CHE_CPU1_DIMM2_FRU_1")
	)
	(segment
		(start 158.813246 -320.566796)
		(end 160.54832 -320.566796)
		(width 0.12954)
		(layer "F.Cu")
		(net "TP_CHE_CPU1_DIMM2_FRU_0")
	)
	(via
		(at 160.54832 -320.566796)
		(size 0.4572)
		(drill 0.2032)
		(layers "F.Cu" "B.Cu")
		(net "TP_CHE_CPU1_DIMM2_FRU_0")
	)
	(segment
		(start 169.326814 -242.3668)
		(end 170.457114 -242.3668)
		(width 0.12954)
		(layer "F.Cu")
		(net "TP_CHE_CPU1_DIMM1_FRU_6")
	)
	(via
		(at 169.326814 -242.3668)
		(size 0.4572)
		(drill 0.2032)
		(layers "F.Cu" "B.Cu")
		(net "TP_CHE_CPU1_DIMM1_FRU_6")
	)
	(via
		(at 170.30319 -241.91341)
		(size 0.6604)
		(drill 0.3302)
		(layers "F.Cu" "B.Cu")
		(net "TP_CHE_CPU1_DIMM1_FRU_6")
	)
	(segment
		(start 169.8498 -242.3668)
		(end 170.30319 -241.91341)
		(width 0.12954)
		(layer "B.Cu")
		(net "TP_CHE_CPU1_DIMM1_FRU_6")
	)
	(segment
		(start 169.326814 -242.3668)
		(end 169.8498 -242.3668)
		(width 0.12954)
		(layer "B.Cu")
		(net "TP_CHE_CPU1_DIMM1_FRU_6")
	)
	(segment
		(start 169.326814 -243.216684)
		(end 170.457114 -243.216684)
		(width 0.12954)
		(layer "F.Cu")
		(net "TP_CHE_CPU1_DIMM1_FRU_5")
	)
	(via
		(at 170.30319 -243.65331)
		(size 0.6604)
		(drill 0.3302)
		(layers "F.Cu" "B.Cu")
		(net "TP_CHE_CPU1_DIMM1_FRU_5")
	)
	(via
		(at 169.326814 -243.216684)
		(size 0.4572)
		(drill 0.2032)
		(layers "F.Cu" "B.Cu")
		(net "TP_CHE_CPU1_DIMM1_FRU_5")
	)
	(segment
		(start 170.30319 -243.65331)
		(end 169.866564 -243.216684)
		(width 0.12954)
		(layer "B.Cu")
		(net "TP_CHE_CPU1_DIMM1_FRU_5")
	)
	(segment
		(start 169.866564 -243.216684)
		(end 169.326814 -243.216684)
		(width 0.12954)
		(layer "B.Cu")
		(net "TP_CHE_CPU1_DIMM1_FRU_5")
	)
	(segment
		(start 170.457114 -252.566678)
		(end 170.457114 -253.40564)
		(width 0.12954)
		(layer "F.Cu")
		(net "TP_CHE_CPU1_DIMM1_FRU_4")
	)
	(segment
		(start 170.457114 -253.40564)
		(end 170.704002 -253.652528)
		(width 0.12954)
		(layer "F.Cu")
		(net "TP_CHE_CPU1_DIMM1_FRU_4")
	)
	(via
		(at 170.704002 -253.652528)
		(size 0.4572)
		(drill 0.2032)
		(layers "F.Cu" "B.Cu")
		(net "TP_CHE_CPU1_DIMM1_FRU_4")
	)
	(via
		(at 171.782486 -252.574044)
		(size 0.6604)
		(drill 0.3302)
		(layers "F.Cu" "B.Cu")
		(net "TP_CHE_CPU1_DIMM1_FRU_4")
	)
	(segment
		(start 171.782486 -252.574044)
		(end 170.704002 -253.652528)
		(width 0.12954)
		(layer "B.Cu")
		(net "TP_CHE_CPU1_DIMM1_FRU_4")
	)
	(segment
		(start 170.457114 -317.166752)
		(end 171.53636 -317.166752)
		(width 0.12954)
		(layer "F.Cu")
		(net "TP_CHE_CPU1_DIMM1_FRU_3")
	)
	(segment
		(start 171.53636 -317.166752)
		(end 171.586398 -317.21679)
		(width 0.12954)
		(layer "F.Cu")
		(net "TP_CHE_CPU1_DIMM1_FRU_3")
	)
	(via
		(at 170.735752 -317.21679)
		(size 0.6604)
		(drill 0.3302)
		(layers "F.Cu" "B.Cu")
		(net "TP_CHE_CPU1_DIMM1_FRU_3")
	)
	(via
		(at 171.586398 -317.21679)
		(size 0.4572)
		(drill 0.2032)
		(layers "F.Cu" "B.Cu")
		(net "TP_CHE_CPU1_DIMM1_FRU_3")
	)
	(segment
		(start 171.586398 -317.21679)
		(end 170.735752 -317.21679)
		(width 0.12954)
		(layer "B.Cu")
		(net "TP_CHE_CPU1_DIMM1_FRU_3")
	)
	(segment
		(start 170.457114 -318.016636)
		(end 169.352214 -318.016636)
		(width 0.12954)
		(layer "F.Cu")
		(net "TP_CHE_CPU1_DIMM1_FRU_2")
	)
	(via
		(at 169.352214 -318.016636)
		(size 0.4572)
		(drill 0.2032)
		(layers "F.Cu" "B.Cu")
		(net "TP_CHE_CPU1_DIMM1_FRU_2")
	)
	(via
		(at 168.836086 -317.479172)
		(size 0.6604)
		(drill 0.3302)
		(layers "F.Cu" "B.Cu")
		(net "TP_CHE_CPU1_DIMM1_FRU_2")
	)
	(segment
		(start 169.144188 -317.80861)
		(end 169.352214 -318.016636)
		(width 0.12954)
		(layer "B.Cu")
		(net "TP_CHE_CPU1_DIMM1_FRU_2")
	)
	(segment
		(start 168.963086 -317.80861)
		(end 169.144188 -317.80861)
		(width 0.12954)
		(layer "B.Cu")
		(net "TP_CHE_CPU1_DIMM1_FRU_2")
	)
	(segment
		(start 168.836086 -317.68161)
		(end 168.963086 -317.80861)
		(width 0.12954)
		(layer "B.Cu")
		(net "TP_CHE_CPU1_DIMM1_FRU_2")
	)
	(segment
		(start 168.836086 -317.479172)
		(end 168.836086 -317.68161)
		(width 0.12954)
		(layer "B.Cu")
		(net "TP_CHE_CPU1_DIMM1_FRU_2")
	)
	(segment
		(start 165.252146 -194.766692)
		(end 166.357046 -194.766692)
		(width 0.12954)
		(layer "F.Cu")
		(net "TP_CHE_CPU1_DIMM1_FRU_1")
	)
	(via
		(at 165.252146 -194.766692)
		(size 0.4572)
		(drill 0.2032)
		(layers "F.Cu" "B.Cu")
		(net "TP_CHE_CPU1_DIMM1_FRU_1")
	)
	(segment
		(start 167.627808 -320.566796)
		(end 167.9956 -320.934588)
		(width 0.12954)
		(layer "F.Cu")
		(net "TP_CHE_CPU1_DIMM1_FRU_0")
	)
	(segment
		(start 166.357046 -320.566796)
		(end 167.627808 -320.566796)
		(width 0.12954)
		(layer "F.Cu")
		(net "TP_CHE_CPU1_DIMM1_FRU_0")
	)
	(via
		(at 167.9956 -320.934588)
		(size 0.4572)
		(drill 0.2032)
		(layers "F.Cu" "B.Cu")
		(net "TP_CHE_CPU1_DIMM1_FRU_0")
	)
	(segment
		(start 410.853382 -242.3668)
		(end 409.723082 -242.3668)
		(width 0.12954)
		(layer "F.Cu")
		(net "TP_CHE_CPU0_DIMM2_FRU_6")
	)
	(via
		(at 410.699458 -241.91341)
		(size 0.6604)
		(drill 0.3302)
		(layers "F.Cu" "B.Cu")
		(net "TP_CHE_CPU0_DIMM2_FRU_6")
	)
	(via
		(at 409.723082 -242.3668)
		(size 0.4572)
		(drill 0.2032)
		(layers "F.Cu" "B.Cu")
		(net "TP_CHE_CPU0_DIMM2_FRU_6")
	)
	(segment
		(start 410.246068 -242.3668)
		(end 410.699458 -241.91341)
		(width 0.12954)
		(layer "B.Cu")
		(net "TP_CHE_CPU0_DIMM2_FRU_6")
	)
	(segment
		(start 409.723082 -242.3668)
		(end 410.246068 -242.3668)
		(width 0.12954)
		(layer "B.Cu")
		(net "TP_CHE_CPU0_DIMM2_FRU_6")
	)
	(segment
		(start 410.853382 -243.216684)
		(end 409.723082 -243.216684)
		(width 0.12954)
		(layer "F.Cu")
		(net "TP_CHE_CPU0_DIMM2_FRU_5")
	)
	(via
		(at 408.746706 -243.670074)
		(size 0.6604)
		(drill 0.3302)
		(layers "F.Cu" "B.Cu")
		(net "TP_CHE_CPU0_DIMM2_FRU_5")
	)
	(via
		(at 409.723082 -243.216684)
		(size 0.4572)
		(drill 0.2032)
		(layers "F.Cu" "B.Cu")
		(net "TP_CHE_CPU0_DIMM2_FRU_5")
	)
	(segment
		(start 409.200096 -243.216684)
		(end 408.746706 -243.670074)
		(width 0.12954)
		(layer "B.Cu")
		(net "TP_CHE_CPU0_DIMM2_FRU_5")
	)
	(segment
		(start 409.723082 -243.216684)
		(end 409.200096 -243.216684)
		(width 0.12954)
		(layer "B.Cu")
		(net "TP_CHE_CPU0_DIMM2_FRU_5")
	)
	(segment
		(start 411.581346 -254.08255)
		(end 411.581346 -253.294642)
		(width 0.12954)
		(layer "F.Cu")
		(net "TP_CHE_CPU0_DIMM2_FRU_4")
	)
	(segment
		(start 411.581346 -253.294642)
		(end 410.853382 -252.566678)
		(width 0.12954)
		(layer "F.Cu")
		(net "TP_CHE_CPU0_DIMM2_FRU_4")
	)
	(via
		(at 412.430976 -253.23292)
		(size 0.6604)
		(drill 0.3302)
		(layers "F.Cu" "B.Cu")
		(net "TP_CHE_CPU0_DIMM2_FRU_4")
	)
	(via
		(at 411.581346 -254.08255)
		(size 0.4572)
		(drill 0.2032)
		(layers "F.Cu" "B.Cu")
		(net "TP_CHE_CPU0_DIMM2_FRU_4")
	)
	(segment
		(start 412.430976 -253.23292)
		(end 411.581346 -254.08255)
		(width 0.12954)
		(layer "B.Cu")
		(net "TP_CHE_CPU0_DIMM2_FRU_4")
	)
	(segment
		(start 409.708858 -317.19647)
		(end 410.823664 -317.19647)
		(width 0.12954)
		(layer "F.Cu")
		(net "TP_CHE_CPU0_DIMM2_FRU_3")
	)
	(segment
		(start 410.823664 -317.19647)
		(end 410.853382 -317.166752)
		(width 0.12954)
		(layer "F.Cu")
		(net "TP_CHE_CPU0_DIMM2_FRU_3")
	)
	(via
		(at 409.708858 -317.19647)
		(size 0.4572)
		(drill 0.2032)
		(layers "F.Cu" "B.Cu")
		(net "TP_CHE_CPU0_DIMM2_FRU_3")
	)
	(via
		(at 412.50616 -316.789308)
		(size 0.6604)
		(drill 0.3302)
		(layers "F.Cu" "B.Cu")
		(net "TP_CHE_CPU0_DIMM2_FRU_3")
	)
	(segment
		(start 410.11602 -316.789308)
		(end 409.708858 -317.19647)
		(width 0.12954)
		(layer "B.Cu")
		(net "TP_CHE_CPU0_DIMM2_FRU_3")
	)
	(segment
		(start 412.50616 -316.789308)
		(end 410.11602 -316.789308)
		(width 0.12954)
		(layer "B.Cu")
		(net "TP_CHE_CPU0_DIMM2_FRU_3")
	)
	(segment
		(start 410.853382 -318.016636)
		(end 409.748482 -318.016636)
		(width 0.12954)
		(layer "F.Cu")
		(net "TP_CHE_CPU0_DIMM2_FRU_2")
	)
	(via
		(at 409.748482 -318.016636)
		(size 0.4572)
		(drill 0.2032)
		(layers "F.Cu" "B.Cu")
		(net "TP_CHE_CPU0_DIMM2_FRU_2")
	)
	(via
		(at 411.341316 -317.31966)
		(size 0.6604)
		(drill 0.3302)
		(layers "F.Cu" "B.Cu")
		(net "TP_CHE_CPU0_DIMM2_FRU_2")
	)
	(segment
		(start 411.341316 -317.31966)
		(end 410.445458 -317.31966)
		(width 0.12954)
		(layer "B.Cu")
		(net "TP_CHE_CPU0_DIMM2_FRU_2")
	)
	(segment
		(start 410.445458 -317.31966)
		(end 409.748482 -318.016636)
		(width 0.12954)
		(layer "B.Cu")
		(net "TP_CHE_CPU0_DIMM2_FRU_2")
	)
	(segment
		(start 407.8732 -194.685412)
		(end 407.79192 -194.766692)
		(width 0.12954)
		(layer "F.Cu")
		(net "TP_CHE_CPU0_DIMM2_FRU_1")
	)
	(segment
		(start 407.79192 -194.766692)
		(end 406.753314 -194.766692)
		(width 0.12954)
		(layer "F.Cu")
		(net "TP_CHE_CPU0_DIMM2_FRU_1")
	)
	(via
		(at 407.8732 -194.685412)
		(size 0.4572)
		(drill 0.2032)
		(layers "F.Cu" "B.Cu")
		(net "TP_CHE_CPU0_DIMM2_FRU_1")
	)
	(via
		(at 408.509978 -196.11975)
		(size 0.6604)
		(drill 0.3302)
		(layers "F.Cu" "B.Cu")
		(net "TP_CHE_CPU0_DIMM2_FRU_1")
	)
	(segment
		(start 408.509978 -196.11975)
		(end 408.509978 -195.32219)
		(width 0.12954)
		(layer "B.Cu")
		(net "TP_CHE_CPU0_DIMM2_FRU_1")
	)
	(segment
		(start 408.509978 -195.32219)
		(end 407.8732 -194.685412)
		(width 0.12954)
		(layer "B.Cu")
		(net "TP_CHE_CPU0_DIMM2_FRU_1")
	)
	(segment
		(start 408.327352 -320.566796)
		(end 406.753314 -320.566796)
		(width 0.12954)
		(layer "F.Cu")
		(net "TP_CHE_CPU0_DIMM2_FRU_0")
	)
	(segment
		(start 408.432 -320.462148)
		(end 408.327352 -320.566796)
		(width 0.12954)
		(layer "F.Cu")
		(net "TP_CHE_CPU0_DIMM2_FRU_0")
	)
	(via
		(at 408.432 -320.462148)
		(size 0.4572)
		(drill 0.2032)
		(layers "F.Cu" "B.Cu")
		(net "TP_CHE_CPU0_DIMM2_FRU_0")
	)
	(segment
		(start 418.397182 -242.3668)
		(end 417.266882 -242.3668)
		(width 0.12954)
		(layer "F.Cu")
		(net "TP_CHE_CPU0_DIMM1_FRU_6")
	)
	(via
		(at 417.266882 -242.3668)
		(size 0.4572)
		(drill 0.2032)
		(layers "F.Cu" "B.Cu")
		(net "TP_CHE_CPU0_DIMM1_FRU_6")
	)
	(via
		(at 418.243258 -241.91341)
		(size 0.6604)
		(drill 0.3302)
		(layers "F.Cu" "B.Cu")
		(net "TP_CHE_CPU0_DIMM1_FRU_6")
	)
	(segment
		(start 417.789868 -242.3668)
		(end 418.243258 -241.91341)
		(width 0.12954)
		(layer "B.Cu")
		(net "TP_CHE_CPU0_DIMM1_FRU_6")
	)
	(segment
		(start 417.266882 -242.3668)
		(end 417.789868 -242.3668)
		(width 0.12954)
		(layer "B.Cu")
		(net "TP_CHE_CPU0_DIMM1_FRU_6")
	)
	(segment
		(start 418.397182 -243.216684)
		(end 417.266882 -243.216684)
		(width 0.12954)
		(layer "F.Cu")
		(net "TP_CHE_CPU0_DIMM1_FRU_5")
	)
	(via
		(at 417.266882 -243.216684)
		(size 0.4572)
		(drill 0.2032)
		(layers "F.Cu" "B.Cu")
		(net "TP_CHE_CPU0_DIMM1_FRU_5")
	)
	(via
		(at 418.243258 -243.65331)
		(size 0.6604)
		(drill 0.3302)
		(layers "F.Cu" "B.Cu")
		(net "TP_CHE_CPU0_DIMM1_FRU_5")
	)
	(segment
		(start 418.243258 -243.65331)
		(end 417.806632 -243.216684)
		(width 0.12954)
		(layer "B.Cu")
		(net "TP_CHE_CPU0_DIMM1_FRU_5")
	)
	(segment
		(start 417.806632 -243.216684)
		(end 417.266882 -243.216684)
		(width 0.12954)
		(layer "B.Cu")
		(net "TP_CHE_CPU0_DIMM1_FRU_5")
	)
	(segment
		(start 418.64407 -253.652528)
		(end 418.397182 -253.40564)
		(width 0.12954)
		(layer "F.Cu")
		(net "TP_CHE_CPU0_DIMM1_FRU_4")
	)
	(segment
		(start 418.397182 -253.40564)
		(end 418.397182 -252.566678)
		(width 0.12954)
		(layer "F.Cu")
		(net "TP_CHE_CPU0_DIMM1_FRU_4")
	)
	(via
		(at 419.456616 -252.180852)
		(size 0.6604)
		(drill 0.3302)
		(layers "F.Cu" "B.Cu")
		(net "TP_CHE_CPU0_DIMM1_FRU_4")
	)
	(via
		(at 418.64407 -253.652528)
		(size 0.4572)
		(drill 0.2032)
		(layers "F.Cu" "B.Cu")
		(net "TP_CHE_CPU0_DIMM1_FRU_4")
	)
	(segment
		(start 419.456616 -252.839982)
		(end 418.64407 -253.652528)
		(width 0.12954)
		(layer "B.Cu")
		(net "TP_CHE_CPU0_DIMM1_FRU_4")
	)
	(segment
		(start 419.456616 -252.180852)
		(end 419.456616 -252.839982)
		(width 0.12954)
		(layer "B.Cu")
		(net "TP_CHE_CPU0_DIMM1_FRU_4")
	)
	(segment
		(start 419.476428 -317.166752)
		(end 418.397182 -317.166752)
		(width 0.12954)
		(layer "F.Cu")
		(net "TP_CHE_CPU0_DIMM1_FRU_3")
	)
	(segment
		(start 419.526466 -317.21679)
		(end 419.476428 -317.166752)
		(width 0.12954)
		(layer "F.Cu")
		(net "TP_CHE_CPU0_DIMM1_FRU_3")
	)
	(via
		(at 419.526466 -317.21679)
		(size 0.4572)
		(drill 0.2032)
		(layers "F.Cu" "B.Cu")
		(net "TP_CHE_CPU0_DIMM1_FRU_3")
	)
	(via
		(at 418.685472 -316.375796)
		(size 0.6604)
		(drill 0.3302)
		(layers "F.Cu" "B.Cu")
		(net "TP_CHE_CPU0_DIMM1_FRU_3")
	)
	(segment
		(start 419.526466 -317.21679)
		(end 418.685472 -316.375796)
		(width 0.12954)
		(layer "B.Cu")
		(net "TP_CHE_CPU0_DIMM1_FRU_3")
	)
	(segment
		(start 418.397182 -318.016636)
		(end 417.292282 -318.016636)
		(width 0.12954)
		(layer "F.Cu")
		(net "TP_CHE_CPU0_DIMM1_FRU_2")
	)
	(via
		(at 417.292282 -318.016636)
		(size 0.4572)
		(drill 0.2032)
		(layers "F.Cu" "B.Cu")
		(net "TP_CHE_CPU0_DIMM1_FRU_2")
	)
	(via
		(at 416.424618 -317.54445)
		(size 0.6604)
		(drill 0.3302)
		(layers "F.Cu" "B.Cu")
		(net "TP_CHE_CPU0_DIMM1_FRU_2")
	)
	(segment
		(start 416.529266 -318.016636)
		(end 416.424618 -317.911988)
		(width 0.12954)
		(layer "B.Cu")
		(net "TP_CHE_CPU0_DIMM1_FRU_2")
	)
	(segment
		(start 417.292282 -318.016636)
		(end 416.529266 -318.016636)
		(width 0.12954)
		(layer "B.Cu")
		(net "TP_CHE_CPU0_DIMM1_FRU_2")
	)
	(segment
		(start 416.424618 -317.911988)
		(end 416.424618 -317.54445)
		(width 0.12954)
		(layer "B.Cu")
		(net "TP_CHE_CPU0_DIMM1_FRU_2")
	)
	(segment
		(start 414.297114 -194.766692)
		(end 413.192214 -194.766692)
		(width 0.12954)
		(layer "F.Cu")
		(net "TP_CHE_CPU0_DIMM1_FRU_1")
	)
	(via
		(at 412.269178 -195.53047)
		(size 0.6604)
		(drill 0.3302)
		(layers "F.Cu" "B.Cu")
		(net "TP_CHE_CPU0_DIMM1_FRU_1")
	)
	(via
		(at 413.192214 -194.766692)
		(size 0.4572)
		(drill 0.2032)
		(layers "F.Cu" "B.Cu")
		(net "TP_CHE_CPU0_DIMM1_FRU_1")
	)
	(segment
		(start 413.192214 -194.766692)
		(end 412.76778 -195.191126)
		(width 0.12954)
		(layer "B.Cu")
		(net "TP_CHE_CPU0_DIMM1_FRU_1")
	)
	(segment
		(start 412.608522 -195.191126)
		(end 412.269178 -195.53047)
		(width 0.12954)
		(layer "B.Cu")
		(net "TP_CHE_CPU0_DIMM1_FRU_1")
	)
	(segment
		(start 412.76778 -195.191126)
		(end 412.608522 -195.191126)
		(width 0.12954)
		(layer "B.Cu")
		(net "TP_CHE_CPU0_DIMM1_FRU_1")
	)
	(segment
		(start 412.6484 -320.566796)
		(end 414.297114 -320.566796)
		(width 0.12954)
		(layer "F.Cu")
		(net "TP_CHE_CPU0_DIMM1_FRU_0")
	)
	(via
		(at 412.6484 -320.566796)
		(size 0.4572)
		(drill 0.2032)
		(layers "F.Cu" "B.Cu")
		(net "TP_CHE_CPU0_DIMM1_FRU_0")
	)
	(segment
		(start 19.784314 -242.3668)
		(end 20.889214 -242.3668)
		(width 0.12954)
		(layer "F.Cu")
		(net "TP_CHD_CPU1_DIMM2_FRU_6")
	)
	(via
		(at 19.912838 -241.930174)
		(size 0.6604)
		(drill 0.3302)
		(layers "F.Cu" "B.Cu")
		(net "TP_CHD_CPU1_DIMM2_FRU_6")
	)
	(via
		(at 20.889214 -242.3668)
		(size 0.4572)
		(drill 0.2032)
		(layers "F.Cu" "B.Cu")
		(net "TP_CHD_CPU1_DIMM2_FRU_6")
	)
	(segment
		(start 20.889214 -242.3668)
		(end 20.349464 -242.3668)
		(width 0.12954)
		(layer "B.Cu")
		(net "TP_CHD_CPU1_DIMM2_FRU_6")
	)
	(segment
		(start 20.349464 -242.3668)
		(end 19.912838 -241.930174)
		(width 0.12954)
		(layer "B.Cu")
		(net "TP_CHD_CPU1_DIMM2_FRU_6")
	)
	(segment
		(start 19.784314 -243.216684)
		(end 20.889214 -243.216684)
		(width 0.12954)
		(layer "F.Cu")
		(net "TP_CHD_CPU1_DIMM2_FRU_5")
	)
	(via
		(at 20.889214 -243.216684)
		(size 0.4572)
		(drill 0.2032)
		(layers "F.Cu" "B.Cu")
		(net "TP_CHD_CPU1_DIMM2_FRU_5")
	)
	(via
		(at 19.912838 -243.670074)
		(size 0.6604)
		(drill 0.3302)
		(layers "F.Cu" "B.Cu")
		(net "TP_CHD_CPU1_DIMM2_FRU_5")
	)
	(segment
		(start 20.889214 -243.216684)
		(end 20.366228 -243.216684)
		(width 0.12954)
		(layer "B.Cu")
		(net "TP_CHD_CPU1_DIMM2_FRU_5")
	)
	(segment
		(start 20.366228 -243.216684)
		(end 19.912838 -243.670074)
		(width 0.12954)
		(layer "B.Cu")
		(net "TP_CHD_CPU1_DIMM2_FRU_5")
	)
	(segment
		(start 19.784314 -252.566678)
		(end 20.889214 -252.566678)
		(width 0.12954)
		(layer "F.Cu")
		(net "TP_CHD_CPU1_DIMM2_FRU_4")
	)
	(via
		(at 20.889214 -252.566678)
		(size 0.4572)
		(drill 0.2032)
		(layers "F.Cu" "B.Cu")
		(net "TP_CHD_CPU1_DIMM2_FRU_4")
	)
	(via
		(at 21.779738 -252.566678)
		(size 0.6604)
		(drill 0.3302)
		(layers "F.Cu" "B.Cu")
		(net "TP_CHD_CPU1_DIMM2_FRU_4")
	)
	(segment
		(start 21.779738 -252.566678)
		(end 20.889214 -252.566678)
		(width 0.12954)
		(layer "B.Cu")
		(net "TP_CHD_CPU1_DIMM2_FRU_4")
	)
	(segment
		(start 20.889214 -317.166752)
		(end 19.784314 -317.166752)
		(width 0.12954)
		(layer "F.Cu")
		(net "TP_CHD_CPU1_DIMM2_FRU_3")
	)
	(via
		(at 20.889214 -318.017398)
		(size 0.6604)
		(drill 0.3302)
		(layers "F.Cu" "B.Cu")
		(net "TP_CHD_CPU1_DIMM2_FRU_3")
	)
	(via
		(at 20.889214 -317.166752)
		(size 0.4572)
		(drill 0.2032)
		(layers "F.Cu" "B.Cu")
		(net "TP_CHD_CPU1_DIMM2_FRU_3")
	)
	(segment
		(start 20.889214 -317.166752)
		(end 20.889214 -318.017398)
		(width 0.12954)
		(layer "B.Cu")
		(net "TP_CHD_CPU1_DIMM2_FRU_3")
	)
	(segment
		(start 18.679414 -318.016636)
		(end 19.784314 -318.016636)
		(width 0.12954)
		(layer "F.Cu")
		(net "TP_CHD_CPU1_DIMM2_FRU_2")
	)
	(via
		(at 18.679414 -318.016636)
		(size 0.4572)
		(drill 0.2032)
		(layers "F.Cu" "B.Cu")
		(net "TP_CHD_CPU1_DIMM2_FRU_2")
	)
	(via
		(at 19.53006 -318.016636)
		(size 0.6604)
		(drill 0.3302)
		(layers "F.Cu" "B.Cu")
		(net "TP_CHD_CPU1_DIMM2_FRU_2")
	)
	(segment
		(start 18.679414 -318.016636)
		(end 19.53006 -318.016636)
		(width 0.12954)
		(layer "B.Cu")
		(net "TP_CHD_CPU1_DIMM2_FRU_2")
	)
	(segment
		(start 14.553946 -194.766692)
		(end 15.684246 -194.766692)
		(width 0.12954)
		(layer "F.Cu")
		(net "TP_CHD_CPU1_DIMM2_FRU_1")
	)
	(via
		(at 14.553946 -194.766692)
		(size 0.4572)
		(drill 0.2032)
		(layers "F.Cu" "B.Cu")
		(net "TP_CHD_CPU1_DIMM2_FRU_1")
	)
	(via
		(at 15.493238 -195.29425)
		(size 0.6604)
		(drill 0.3302)
		(layers "F.Cu" "B.Cu")
		(net "TP_CHD_CPU1_DIMM2_FRU_1")
	)
	(segment
		(start 15.493238 -195.29425)
		(end 14.96568 -194.766692)
		(width 0.12954)
		(layer "B.Cu")
		(net "TP_CHD_CPU1_DIMM2_FRU_1")
	)
	(segment
		(start 14.96568 -194.766692)
		(end 14.553946 -194.766692)
		(width 0.12954)
		(layer "B.Cu")
		(net "TP_CHD_CPU1_DIMM2_FRU_1")
	)
	(segment
		(start 15.684246 -320.566796)
		(end 14.579346 -320.566796)
		(width 0.12954)
		(layer "F.Cu")
		(net "TP_CHD_CPU1_DIMM2_FRU_0")
	)
	(via
		(at 13.87348 -319.758568)
		(size 0.6604)
		(drill 0.3302)
		(layers "F.Cu" "B.Cu")
		(net "TP_CHD_CPU1_DIMM2_FRU_0")
	)
	(via
		(at 14.579346 -320.566796)
		(size 0.4572)
		(drill 0.2032)
		(layers "F.Cu" "B.Cu")
		(net "TP_CHD_CPU1_DIMM2_FRU_0")
	)
	(segment
		(start 14.579346 -320.464434)
		(end 13.87348 -319.758568)
		(width 0.12954)
		(layer "B.Cu")
		(net "TP_CHD_CPU1_DIMM2_FRU_0")
	)
	(segment
		(start 14.579346 -320.566796)
		(end 14.579346 -320.464434)
		(width 0.12954)
		(layer "B.Cu")
		(net "TP_CHD_CPU1_DIMM2_FRU_0")
	)
	(segment
		(start 12.240514 -242.3668)
		(end 13.345414 -242.3668)
		(width 0.12954)
		(layer "F.Cu")
		(net "TP_CHD_CPU1_DIMM1_FRU_6")
	)
	(via
		(at 12.369038 -241.930174)
		(size 0.6604)
		(drill 0.3302)
		(layers "F.Cu" "B.Cu")
		(net "TP_CHD_CPU1_DIMM1_FRU_6")
	)
	(via
		(at 13.345414 -242.3668)
		(size 0.4572)
		(drill 0.2032)
		(layers "F.Cu" "B.Cu")
		(net "TP_CHD_CPU1_DIMM1_FRU_6")
	)
	(segment
		(start 12.805664 -242.3668)
		(end 12.369038 -241.930174)
		(width 0.12954)
		(layer "B.Cu")
		(net "TP_CHD_CPU1_DIMM1_FRU_6")
	)
	(segment
		(start 13.345414 -242.3668)
		(end 12.805664 -242.3668)
		(width 0.12954)
		(layer "B.Cu")
		(net "TP_CHD_CPU1_DIMM1_FRU_6")
	)
	(segment
		(start 12.240514 -243.216684)
		(end 13.345414 -243.216684)
		(width 0.12954)
		(layer "F.Cu")
		(net "TP_CHD_CPU1_DIMM1_FRU_5")
	)
	(via
		(at 13.345414 -243.216684)
		(size 0.4572)
		(drill 0.2032)
		(layers "F.Cu" "B.Cu")
		(net "TP_CHD_CPU1_DIMM1_FRU_5")
	)
	(via
		(at 12.369038 -243.670074)
		(size 0.6604)
		(drill 0.3302)
		(layers "F.Cu" "B.Cu")
		(net "TP_CHD_CPU1_DIMM1_FRU_5")
	)
	(segment
		(start 12.822428 -243.216684)
		(end 12.369038 -243.670074)
		(width 0.12954)
		(layer "B.Cu")
		(net "TP_CHD_CPU1_DIMM1_FRU_5")
	)
	(segment
		(start 13.345414 -243.216684)
		(end 12.822428 -243.216684)
		(width 0.12954)
		(layer "B.Cu")
		(net "TP_CHD_CPU1_DIMM1_FRU_5")
	)
	(segment
		(start 12.240514 -252.566678)
		(end 11.135614 -252.566678)
		(width 0.12954)
		(layer "F.Cu")
		(net "TP_CHD_CPU1_DIMM1_FRU_4")
	)
	(via
		(at 10.03427 -250.91771)
		(size 0.6604)
		(drill 0.3302)
		(layers "F.Cu" "B.Cu")
		(net "TP_CHD_CPU1_DIMM1_FRU_4")
	)
	(via
		(at 11.135614 -252.566678)
		(size 0.4572)
		(drill 0.2032)
		(layers "F.Cu" "B.Cu")
		(net "TP_CHD_CPU1_DIMM1_FRU_4")
	)
	(segment
		(start 10.03427 -250.91771)
		(end 10.03427 -251.465334)
		(width 0.12954)
		(layer "B.Cu")
		(net "TP_CHD_CPU1_DIMM1_FRU_4")
	)
	(segment
		(start 10.03427 -251.465334)
		(end 11.135614 -252.566678)
		(width 0.12954)
		(layer "B.Cu")
		(net "TP_CHD_CPU1_DIMM1_FRU_4")
	)
	(segment
		(start 12.240514 -317.166752)
		(end 11.135614 -317.166752)
		(width 0.12954)
		(layer "F.Cu")
		(net "TP_CHD_CPU1_DIMM1_FRU_3")
	)
	(via
		(at 12.082018 -316.64275)
		(size 0.6604)
		(drill 0.3302)
		(layers "F.Cu" "B.Cu")
		(net "TP_CHD_CPU1_DIMM1_FRU_3")
	)
	(via
		(at 11.135614 -317.166752)
		(size 0.508)
		(drill 0.254)
		(layers "F.Cu" "B.Cu")
		(net "TP_CHD_CPU1_DIMM1_FRU_3")
	)
	(segment
		(start 11.558016 -317.166752)
		(end 11.135614 -317.166752)
		(width 0.12954)
		(layer "B.Cu")
		(net "TP_CHD_CPU1_DIMM1_FRU_3")
	)
	(segment
		(start 12.082018 -316.64275)
		(end 11.558016 -317.166752)
		(width 0.12954)
		(layer "B.Cu")
		(net "TP_CHD_CPU1_DIMM1_FRU_3")
	)
	(segment
		(start 12.240514 -318.016636)
		(end 11.135614 -318.016636)
		(width 0.12954)
		(layer "F.Cu")
		(net "TP_CHD_CPU1_DIMM1_FRU_2")
	)
	(via
		(at 11.135614 -318.016636)
		(size 0.4572)
		(drill 0.2032)
		(layers "F.Cu" "B.Cu")
		(net "TP_CHD_CPU1_DIMM1_FRU_2")
	)
	(via
		(at 11.98626 -318.016636)
		(size 0.6604)
		(drill 0.3302)
		(layers "F.Cu" "B.Cu")
		(net "TP_CHD_CPU1_DIMM1_FRU_2")
	)
	(segment
		(start 11.135614 -318.016636)
		(end 11.98626 -318.016636)
		(width 0.12954)
		(layer "B.Cu")
		(net "TP_CHD_CPU1_DIMM1_FRU_2")
	)
	(segment
		(start 8.140446 -320.566796)
		(end 7.035546 -320.566796)
		(width 0.12954)
		(layer "F.Cu")
		(net "TP_CHD_CPU1_DIMM1_FRU_0")
	)
	(via
		(at 6.260338 -320.566796)
		(size 0.6604)
		(drill 0.3302)
		(layers "F.Cu" "B.Cu")
		(net "TP_CHD_CPU1_DIMM1_FRU_0")
	)
	(via
		(at 7.035546 -320.566796)
		(size 0.4572)
		(drill 0.2032)
		(layers "F.Cu" "B.Cu")
		(net "TP_CHD_CPU1_DIMM1_FRU_0")
	)
	(segment
		(start 7.035546 -320.566796)
		(end 6.260338 -320.566796)
		(width 0.12954)
		(layer "B.Cu")
		(net "TP_CHD_CPU1_DIMM1_FRU_0")
	)
	(segment
		(start 268.829282 -242.3668)
		(end 267.724382 -242.3668)
		(width 0.12954)
		(layer "F.Cu")
		(net "TP_CHD_CPU0_DIMM2_FRU_6")
	)
	(via
		(at 268.829282 -242.3668)
		(size 0.4572)
		(drill 0.2032)
		(layers "F.Cu" "B.Cu")
		(net "TP_CHD_CPU0_DIMM2_FRU_6")
	)
	(via
		(at 269.779242 -241.41684)
		(size 0.6604)
		(drill 0.3302)
		(layers "F.Cu" "B.Cu")
		(net "TP_CHD_CPU0_DIMM2_FRU_6")
	)
	(segment
		(start 269.779242 -241.41684)
		(end 268.829282 -242.3668)
		(width 0.12954)
		(layer "B.Cu")
		(net "TP_CHD_CPU0_DIMM2_FRU_6")
	)
	(segment
		(start 268.829282 -243.216684)
		(end 267.724382 -243.216684)
		(width 0.12954)
		(layer "F.Cu")
		(net "TP_CHD_CPU0_DIMM2_FRU_5")
	)
	(via
		(at 268.829282 -243.216684)
		(size 0.4572)
		(drill 0.2032)
		(layers "F.Cu" "B.Cu")
		(net "TP_CHD_CPU0_DIMM2_FRU_5")
	)
	(via
		(at 269.805658 -243.65331)
		(size 0.6604)
		(drill 0.3302)
		(layers "F.Cu" "B.Cu")
		(net "TP_CHD_CPU0_DIMM2_FRU_5")
	)
	(segment
		(start 269.805658 -243.65331)
		(end 269.369032 -243.216684)
		(width 0.12954)
		(layer "B.Cu")
		(net "TP_CHD_CPU0_DIMM2_FRU_5")
	)
	(segment
		(start 269.369032 -243.216684)
		(end 268.829282 -243.216684)
		(width 0.12954)
		(layer "B.Cu")
		(net "TP_CHD_CPU0_DIMM2_FRU_5")
	)
	(segment
		(start 268.829282 -252.566678)
		(end 267.724382 -252.566678)
		(width 0.12954)
		(layer "F.Cu")
		(net "TP_CHD_CPU0_DIMM2_FRU_4")
	)
	(via
		(at 268.829282 -252.566678)
		(size 0.4572)
		(drill 0.2032)
		(layers "F.Cu" "B.Cu")
		(net "TP_CHD_CPU0_DIMM2_FRU_4")
	)
	(via
		(at 269.706598 -252.566678)
		(size 0.6604)
		(drill 0.3302)
		(layers "F.Cu" "B.Cu")
		(net "TP_CHD_CPU0_DIMM2_FRU_4")
	)
	(segment
		(start 268.829282 -252.566678)
		(end 269.706598 -252.566678)
		(width 0.12954)
		(layer "B.Cu")
		(net "TP_CHD_CPU0_DIMM2_FRU_4")
	)
	(segment
		(start 267.724382 -317.166752)
		(end 268.829282 -317.166752)
		(width 0.12954)
		(layer "F.Cu")
		(net "TP_CHD_CPU0_DIMM2_FRU_3")
	)
	(via
		(at 268.829282 -317.166752)
		(size 0.4572)
		(drill 0.2032)
		(layers "F.Cu" "B.Cu")
		(net "TP_CHD_CPU0_DIMM2_FRU_3")
	)
	(via
		(at 268.104874 -317.166752)
		(size 0.6604)
		(drill 0.3302)
		(layers "F.Cu" "B.Cu")
		(net "TP_CHD_CPU0_DIMM2_FRU_3")
	)
	(segment
		(start 268.829282 -317.166752)
		(end 268.104874 -317.166752)
		(width 0.12954)
		(layer "B.Cu")
		(net "TP_CHD_CPU0_DIMM2_FRU_3")
	)
	(segment
		(start 265.41222 -320.926968)
		(end 265.41222 -319.395348)
		(width 0.12954)
		(layer "F.Cu")
		(net "TP_CHD_CPU0_DIMM2_FRU_2")
	)
	(segment
		(start 266.790932 -318.016636)
		(end 267.724382 -318.016636)
		(width 0.12954)
		(layer "F.Cu")
		(net "TP_CHD_CPU0_DIMM2_FRU_2")
	)
	(segment
		(start 265.41222 -319.395348)
		(end 266.790932 -318.016636)
		(width 0.12954)
		(layer "F.Cu")
		(net "TP_CHD_CPU0_DIMM2_FRU_2")
	)
	(via
		(at 265.41222 -320.926968)
		(size 0.4572)
		(drill 0.2032)
		(layers "F.Cu" "B.Cu")
		(net "TP_CHD_CPU0_DIMM2_FRU_2")
	)
	(segment
		(start 262.494014 -194.766692)
		(end 263.624314 -194.766692)
		(width 0.12954)
		(layer "F.Cu")
		(net "TP_CHD_CPU0_DIMM2_FRU_1")
	)
	(via
		(at 263.434576 -194.766692)
		(size 0.6604)
		(drill 0.3302)
		(layers "F.Cu" "B.Cu")
		(net "TP_CHD_CPU0_DIMM2_FRU_1")
	)
	(via
		(at 262.494014 -194.766692)
		(size 0.4572)
		(drill 0.2032)
		(layers "F.Cu" "B.Cu")
		(net "TP_CHD_CPU0_DIMM2_FRU_1")
	)
	(segment
		(start 262.494014 -194.766692)
		(end 263.434576 -194.766692)
		(width 0.12954)
		(layer "B.Cu")
		(net "TP_CHD_CPU0_DIMM2_FRU_1")
	)
	(segment
		(start 262.470392 -320.566796)
		(end 263.624314 -320.566796)
		(width 0.12954)
		(layer "F.Cu")
		(net "TP_CHD_CPU0_DIMM2_FRU_0")
	)
	(segment
		(start 261.81812 -321.699128)
		(end 261.81812 -321.219068)
		(width 0.12954)
		(layer "F.Cu")
		(net "TP_CHD_CPU0_DIMM2_FRU_0")
	)
	(segment
		(start 261.81812 -321.219068)
		(end 262.470392 -320.566796)
		(width 0.12954)
		(layer "F.Cu")
		(net "TP_CHD_CPU0_DIMM2_FRU_0")
	)
	(via
		(at 261.81812 -321.699128)
		(size 0.4572)
		(drill 0.2032)
		(layers "F.Cu" "B.Cu")
		(net "TP_CHD_CPU0_DIMM2_FRU_0")
	)
	(segment
		(start 261.285482 -242.3668)
		(end 260.180582 -242.3668)
		(width 0.12954)
		(layer "F.Cu")
		(net "TP_CHD_CPU0_DIMM1_FRU_6")
	)
	(via
		(at 261.285482 -242.3668)
		(size 0.4572)
		(drill 0.2032)
		(layers "F.Cu" "B.Cu")
		(net "TP_CHD_CPU0_DIMM1_FRU_6")
	)
	(via
		(at 262.144002 -241.50828)
		(size 0.6604)
		(drill 0.3302)
		(layers "F.Cu" "B.Cu")
		(net "TP_CHD_CPU0_DIMM1_FRU_6")
	)
	(segment
		(start 262.144002 -241.50828)
		(end 261.285482 -242.3668)
		(width 0.12954)
		(layer "B.Cu")
		(net "TP_CHD_CPU0_DIMM1_FRU_6")
	)
	(segment
		(start 261.285482 -243.216684)
		(end 260.180582 -243.216684)
		(width 0.12954)
		(layer "F.Cu")
		(net "TP_CHD_CPU0_DIMM1_FRU_5")
	)
	(via
		(at 262.261858 -243.65331)
		(size 0.6604)
		(drill 0.3302)
		(layers "F.Cu" "B.Cu")
		(net "TP_CHD_CPU0_DIMM1_FRU_5")
	)
	(via
		(at 261.285482 -243.216684)
		(size 0.4572)
		(drill 0.2032)
		(layers "F.Cu" "B.Cu")
		(net "TP_CHD_CPU0_DIMM1_FRU_5")
	)
	(segment
		(start 261.825232 -243.216684)
		(end 261.285482 -243.216684)
		(width 0.12954)
		(layer "B.Cu")
		(net "TP_CHD_CPU0_DIMM1_FRU_5")
	)
	(segment
		(start 262.261858 -243.65331)
		(end 261.825232 -243.216684)
		(width 0.12954)
		(layer "B.Cu")
		(net "TP_CHD_CPU0_DIMM1_FRU_5")
	)
	(segment
		(start 260.180582 -252.566678)
		(end 259.075682 -252.566678)
		(width 0.12954)
		(layer "F.Cu")
		(net "TP_CHD_CPU0_DIMM1_FRU_4")
	)
	(via
		(at 259.075682 -252.566678)
		(size 0.4572)
		(drill 0.2032)
		(layers "F.Cu" "B.Cu")
		(net "TP_CHD_CPU0_DIMM1_FRU_4")
	)
	(via
		(at 259.893562 -251.227082)
		(size 0.6604)
		(drill 0.3302)
		(layers "F.Cu" "B.Cu")
		(net "TP_CHD_CPU0_DIMM1_FRU_4")
	)
	(segment
		(start 259.893562 -251.227082)
		(end 259.893562 -251.748798)
		(width 0.12954)
		(layer "B.Cu")
		(net "TP_CHD_CPU0_DIMM1_FRU_4")
	)
	(segment
		(start 259.893562 -251.748798)
		(end 259.075682 -252.566678)
		(width 0.12954)
		(layer "B.Cu")
		(net "TP_CHD_CPU0_DIMM1_FRU_4")
	)
	(segment
		(start 260.180582 -317.166752)
		(end 259.075682 -317.166752)
		(width 0.12954)
		(layer "F.Cu")
		(net "TP_CHD_CPU0_DIMM1_FRU_3")
	)
	(via
		(at 259.845048 -316.397386)
		(size 0.6604)
		(drill 0.3302)
		(layers "F.Cu" "B.Cu")
		(net "TP_CHD_CPU0_DIMM1_FRU_3")
	)
	(via
		(at 259.075682 -317.166752)
		(size 0.4572)
		(drill 0.2032)
		(layers "F.Cu" "B.Cu")
		(net "TP_CHD_CPU0_DIMM1_FRU_3")
	)
	(segment
		(start 259.075682 -317.166752)
		(end 259.845048 -316.397386)
		(width 0.12954)
		(layer "B.Cu")
		(net "TP_CHD_CPU0_DIMM1_FRU_3")
	)
	(segment
		(start 260.180582 -318.016636)
		(end 259.075682 -318.016636)
		(width 0.12954)
		(layer "F.Cu")
		(net "TP_CHD_CPU0_DIMM1_FRU_2")
	)
	(via
		(at 259.80009 -318.016636)
		(size 0.6604)
		(drill 0.3302)
		(layers "F.Cu" "B.Cu")
		(net "TP_CHD_CPU0_DIMM1_FRU_2")
	)
	(via
		(at 259.075682 -318.016636)
		(size 0.4572)
		(drill 0.2032)
		(layers "F.Cu" "B.Cu")
		(net "TP_CHD_CPU0_DIMM1_FRU_2")
	)
	(segment
		(start 259.075682 -318.016636)
		(end 259.80009 -318.016636)
		(width 0.12954)
		(layer "B.Cu")
		(net "TP_CHD_CPU0_DIMM1_FRU_2")
	)
	(segment
		(start 257.243326 -194.766692)
		(end 256.080514 -194.766692)
		(width 0.12954)
		(layer "F.Cu")
		(net "TP_CHD_CPU0_DIMM1_FRU_1")
	)
	(via
		(at 257.243326 -194.766692)
		(size 0.4572)
		(drill 0.2032)
		(layers "F.Cu" "B.Cu")
		(net "TP_CHD_CPU0_DIMM1_FRU_1")
	)
	(via
		(at 255.890776 -194.766692)
		(size 0.6604)
		(drill 0.3302)
		(layers "F.Cu" "B.Cu")
		(net "TP_CHD_CPU0_DIMM1_FRU_1")
	)
	(segment
		(start 257.243326 -194.766692)
		(end 255.890776 -194.766692)
		(width 0.12954)
		(layer "B.Cu")
		(net "TP_CHD_CPU0_DIMM1_FRU_1")
	)
	(segment
		(start 256.080514 -320.566796)
		(end 254.975614 -320.566796)
		(width 0.12954)
		(layer "F.Cu")
		(net "TP_CHD_CPU0_DIMM1_FRU_0")
	)
	(via
		(at 255.751838 -320.65849)
		(size 0.6604)
		(drill 0.3302)
		(layers "F.Cu" "B.Cu")
		(net "TP_CHD_CPU0_DIMM1_FRU_0")
	)
	(via
		(at 254.975614 -320.566796)
		(size 0.4572)
		(drill 0.2032)
		(layers "F.Cu" "B.Cu")
		(net "TP_CHD_CPU0_DIMM1_FRU_0")
	)
	(segment
		(start 254.975614 -320.566796)
		(end 255.2192 -320.32321)
		(width 0.12954)
		(layer "B.Cu")
		(net "TP_CHD_CPU0_DIMM1_FRU_0")
	)
	(segment
		(start 255.416558 -320.32321)
		(end 255.751838 -320.65849)
		(width 0.12954)
		(layer "B.Cu")
		(net "TP_CHD_CPU0_DIMM1_FRU_0")
	)
	(segment
		(start 255.2192 -320.32321)
		(end 255.416558 -320.32321)
		(width 0.12954)
		(layer "B.Cu")
		(net "TP_CHD_CPU0_DIMM1_FRU_0")
	)
	(segment
		(start 34.871914 -242.3668)
		(end 35.976814 -242.3668)
		(width 0.12954)
		(layer "F.Cu")
		(net "TP_CHC_CPU1_DIMM2_FRU_6")
	)
	(via
		(at 35.976814 -242.3668)
		(size 0.4572)
		(drill 0.2032)
		(layers "F.Cu" "B.Cu")
		(net "TP_CHC_CPU1_DIMM2_FRU_6")
	)
	(via
		(at 36.875974 -241.46764)
		(size 0.6604)
		(drill 0.3302)
		(layers "F.Cu" "B.Cu")
		(net "TP_CHC_CPU1_DIMM2_FRU_6")
	)
	(segment
		(start 36.875974 -241.46764)
		(end 35.976814 -242.3668)
		(width 0.12954)
		(layer "B.Cu")
		(net "TP_CHC_CPU1_DIMM2_FRU_6")
	)
	(segment
		(start 34.871914 -243.216684)
		(end 35.976814 -243.216684)
		(width 0.12954)
		(layer "F.Cu")
		(net "TP_CHC_CPU1_DIMM2_FRU_5")
	)
	(via
		(at 35.976814 -243.216684)
		(size 0.4572)
		(drill 0.2032)
		(layers "F.Cu" "B.Cu")
		(net "TP_CHC_CPU1_DIMM2_FRU_5")
	)
	(via
		(at 36.95319 -243.65331)
		(size 0.6604)
		(drill 0.3302)
		(layers "F.Cu" "B.Cu")
		(net "TP_CHC_CPU1_DIMM2_FRU_5")
	)
	(segment
		(start 35.976814 -243.216684)
		(end 36.516564 -243.216684)
		(width 0.12954)
		(layer "B.Cu")
		(net "TP_CHC_CPU1_DIMM2_FRU_5")
	)
	(segment
		(start 36.516564 -243.216684)
		(end 36.95319 -243.65331)
		(width 0.12954)
		(layer "B.Cu")
		(net "TP_CHC_CPU1_DIMM2_FRU_5")
	)
	(segment
		(start 34.871914 -252.566678)
		(end 35.976814 -252.566678)
		(width 0.12954)
		(layer "F.Cu")
		(net "TP_CHC_CPU1_DIMM2_FRU_4")
	)
	(via
		(at 35.976814 -252.566678)
		(size 0.4572)
		(drill 0.2032)
		(layers "F.Cu" "B.Cu")
		(net "TP_CHC_CPU1_DIMM2_FRU_4")
	)
	(via
		(at 36.867338 -252.566678)
		(size 0.6604)
		(drill 0.3302)
		(layers "F.Cu" "B.Cu")
		(net "TP_CHC_CPU1_DIMM2_FRU_4")
	)
	(segment
		(start 36.867338 -252.566678)
		(end 35.976814 -252.566678)
		(width 0.12954)
		(layer "B.Cu")
		(net "TP_CHC_CPU1_DIMM2_FRU_4")
	)
	(segment
		(start 35.976814 -317.166752)
		(end 34.871914 -317.166752)
		(width 0.12954)
		(layer "F.Cu")
		(net "TP_CHC_CPU1_DIMM2_FRU_3")
	)
	(via
		(at 35.976814 -317.166752)
		(size 0.4572)
		(drill 0.2032)
		(layers "F.Cu" "B.Cu")
		(net "TP_CHC_CPU1_DIMM2_FRU_3")
	)
	(via
		(at 35.976814 -318.017398)
		(size 0.6604)
		(drill 0.3302)
		(layers "F.Cu" "B.Cu")
		(net "TP_CHC_CPU1_DIMM2_FRU_3")
	)
	(segment
		(start 35.976814 -317.166752)
		(end 35.976814 -318.017398)
		(width 0.12954)
		(layer "B.Cu")
		(net "TP_CHC_CPU1_DIMM2_FRU_3")
	)
	(segment
		(start 33.767014 -318.016636)
		(end 34.871914 -318.016636)
		(width 0.12954)
		(layer "F.Cu")
		(net "TP_CHC_CPU1_DIMM2_FRU_2")
	)
	(via
		(at 33.767014 -318.016636)
		(size 0.4572)
		(drill 0.2032)
		(layers "F.Cu" "B.Cu")
		(net "TP_CHC_CPU1_DIMM2_FRU_2")
	)
	(via
		(at 34.54654 -317.470028)
		(size 0.6604)
		(drill 0.3302)
		(layers "F.Cu" "B.Cu")
		(net "TP_CHC_CPU1_DIMM2_FRU_2")
	)
	(segment
		(start 33.767014 -318.016636)
		(end 33.999932 -318.016636)
		(width 0.12954)
		(layer "B.Cu")
		(net "TP_CHC_CPU1_DIMM2_FRU_2")
	)
	(segment
		(start 33.999932 -318.016636)
		(end 34.54654 -317.470028)
		(width 0.12954)
		(layer "B.Cu")
		(net "TP_CHC_CPU1_DIMM2_FRU_2")
	)
	(segment
		(start 29.608018 -194.76085)
		(end 29.61386 -194.766692)
		(width 0.12954)
		(layer "F.Cu")
		(net "TP_CHC_CPU1_DIMM2_FRU_1")
	)
	(segment
		(start 29.61386 -194.766692)
		(end 30.771846 -194.766692)
		(width 0.12954)
		(layer "F.Cu")
		(net "TP_CHC_CPU1_DIMM2_FRU_1")
	)
	(via
		(at 29.608018 -194.76085)
		(size 0.4572)
		(drill 0.2032)
		(layers "F.Cu" "B.Cu")
		(net "TP_CHC_CPU1_DIMM2_FRU_1")
	)
	(via
		(at 29.608018 -193.998596)
		(size 0.6604)
		(drill 0.3302)
		(layers "F.Cu" "B.Cu")
		(net "TP_CHC_CPU1_DIMM2_FRU_1")
	)
	(segment
		(start 29.608018 -194.76085)
		(end 29.608018 -193.998596)
		(width 0.12954)
		(layer "B.Cu")
		(net "TP_CHC_CPU1_DIMM2_FRU_1")
	)
	(segment
		(start 30.771846 -320.566796)
		(end 29.666946 -320.566796)
		(width 0.12954)
		(layer "F.Cu")
		(net "TP_CHC_CPU1_DIMM2_FRU_0")
	)
	(via
		(at 29.666946 -320.566796)
		(size 0.4572)
		(drill 0.2032)
		(layers "F.Cu" "B.Cu")
		(net "TP_CHC_CPU1_DIMM2_FRU_0")
	)
	(via
		(at 28.96108 -319.794128)
		(size 0.6604)
		(drill 0.3302)
		(layers "F.Cu" "B.Cu")
		(net "TP_CHC_CPU1_DIMM2_FRU_0")
	)
	(segment
		(start 29.666946 -320.566796)
		(end 29.666946 -320.499994)
		(width 0.12954)
		(layer "B.Cu")
		(net "TP_CHC_CPU1_DIMM2_FRU_0")
	)
	(segment
		(start 29.666946 -320.499994)
		(end 28.96108 -319.794128)
		(width 0.12954)
		(layer "B.Cu")
		(net "TP_CHC_CPU1_DIMM2_FRU_0")
	)
	(segment
		(start 27.328114 -242.3668)
		(end 28.433014 -242.3668)
		(width 0.12954)
		(layer "F.Cu")
		(net "TP_CHC_CPU1_DIMM1_FRU_6")
	)
	(via
		(at 28.433014 -242.3668)
		(size 0.4572)
		(drill 0.2032)
		(layers "F.Cu" "B.Cu")
		(net "TP_CHC_CPU1_DIMM1_FRU_6")
	)
	(via
		(at 27.456638 -241.930174)
		(size 0.6604)
		(drill 0.3302)
		(layers "F.Cu" "B.Cu")
		(net "TP_CHC_CPU1_DIMM1_FRU_6")
	)
	(segment
		(start 28.433014 -242.3668)
		(end 27.893264 -242.3668)
		(width 0.12954)
		(layer "B.Cu")
		(net "TP_CHC_CPU1_DIMM1_FRU_6")
	)
	(segment
		(start 27.893264 -242.3668)
		(end 27.456638 -241.930174)
		(width 0.12954)
		(layer "B.Cu")
		(net "TP_CHC_CPU1_DIMM1_FRU_6")
	)
	(segment
		(start 27.328114 -243.216684)
		(end 28.433014 -243.216684)
		(width 0.12954)
		(layer "F.Cu")
		(net "TP_CHC_CPU1_DIMM1_FRU_5")
	)
	(via
		(at 28.433014 -243.216684)
		(size 0.4572)
		(drill 0.2032)
		(layers "F.Cu" "B.Cu")
		(net "TP_CHC_CPU1_DIMM1_FRU_5")
	)
	(via
		(at 27.456638 -243.670074)
		(size 0.6604)
		(drill 0.3302)
		(layers "F.Cu" "B.Cu")
		(net "TP_CHC_CPU1_DIMM1_FRU_5")
	)
	(segment
		(start 27.910028 -243.216684)
		(end 27.456638 -243.670074)
		(width 0.12954)
		(layer "B.Cu")
		(net "TP_CHC_CPU1_DIMM1_FRU_5")
	)
	(segment
		(start 28.433014 -243.216684)
		(end 27.910028 -243.216684)
		(width 0.12954)
		(layer "B.Cu")
		(net "TP_CHC_CPU1_DIMM1_FRU_5")
	)
	(segment
		(start 27.328114 -252.566678)
		(end 26.223214 -252.566678)
		(width 0.12954)
		(layer "F.Cu")
		(net "TP_CHC_CPU1_DIMM1_FRU_4")
	)
	(via
		(at 26.223214 -252.566678)
		(size 0.4572)
		(drill 0.2032)
		(layers "F.Cu" "B.Cu")
		(net "TP_CHC_CPU1_DIMM1_FRU_4")
	)
	(via
		(at 25.12187 -250.91771)
		(size 0.6604)
		(drill 0.3302)
		(layers "F.Cu" "B.Cu")
		(net "TP_CHC_CPU1_DIMM1_FRU_4")
	)
	(segment
		(start 25.12187 -250.91771)
		(end 25.12187 -251.465334)
		(width 0.12954)
		(layer "B.Cu")
		(net "TP_CHC_CPU1_DIMM1_FRU_4")
	)
	(segment
		(start 25.12187 -251.465334)
		(end 26.223214 -252.566678)
		(width 0.12954)
		(layer "B.Cu")
		(net "TP_CHC_CPU1_DIMM1_FRU_4")
	)
	(segment
		(start 28.433014 -317.166752)
		(end 27.328114 -317.166752)
		(width 0.12954)
		(layer "F.Cu")
		(net "TP_CHC_CPU1_DIMM1_FRU_3")
	)
	(via
		(at 27.76728 -316.591188)
		(size 0.6604)
		(drill 0.3302)
		(layers "F.Cu" "B.Cu")
		(net "TP_CHC_CPU1_DIMM1_FRU_3")
	)
	(via
		(at 28.433014 -317.166752)
		(size 0.4572)
		(drill 0.2032)
		(layers "F.Cu" "B.Cu")
		(net "TP_CHC_CPU1_DIMM1_FRU_3")
	)
	(segment
		(start 27.85745 -316.591188)
		(end 27.76728 -316.591188)
		(width 0.12954)
		(layer "B.Cu")
		(net "TP_CHC_CPU1_DIMM1_FRU_3")
	)
	(segment
		(start 28.433014 -317.166752)
		(end 27.85745 -316.591188)
		(width 0.12954)
		(layer "B.Cu")
		(net "TP_CHC_CPU1_DIMM1_FRU_3")
	)
	(segment
		(start 26.223214 -318.016636)
		(end 27.328114 -318.016636)
		(width 0.12954)
		(layer "F.Cu")
		(net "TP_CHC_CPU1_DIMM1_FRU_2")
	)
	(via
		(at 26.223214 -318.016636)
		(size 0.4572)
		(drill 0.2032)
		(layers "F.Cu" "B.Cu")
		(net "TP_CHC_CPU1_DIMM1_FRU_2")
	)
	(via
		(at 27.07386 -318.016636)
		(size 0.6604)
		(drill 0.3302)
		(layers "F.Cu" "B.Cu")
		(net "TP_CHC_CPU1_DIMM1_FRU_2")
	)
	(segment
		(start 26.223214 -318.016636)
		(end 27.07386 -318.016636)
		(width 0.12954)
		(layer "B.Cu")
		(net "TP_CHC_CPU1_DIMM1_FRU_2")
	)
	(segment
		(start 22.097746 -194.766692)
		(end 23.228046 -194.766692)
		(width 0.12954)
		(layer "F.Cu")
		(net "TP_CHC_CPU1_DIMM1_FRU_1")
	)
	(via
		(at 22.86 -194.766692)
		(size 0.6604)
		(drill 0.3302)
		(layers "F.Cu" "B.Cu")
		(net "TP_CHC_CPU1_DIMM1_FRU_1")
	)
	(via
		(at 22.097746 -194.766692)
		(size 0.4572)
		(drill 0.2032)
		(layers "F.Cu" "B.Cu")
		(net "TP_CHC_CPU1_DIMM1_FRU_1")
	)
	(segment
		(start 22.097746 -194.766692)
		(end 22.86 -194.766692)
		(width 0.12954)
		(layer "B.Cu")
		(net "TP_CHC_CPU1_DIMM1_FRU_1")
	)
	(segment
		(start 23.228046 -320.566796)
		(end 22.123146 -320.566796)
		(width 0.12954)
		(layer "F.Cu")
		(net "TP_CHC_CPU1_DIMM1_FRU_0")
	)
	(via
		(at 21.43506 -319.781428)
		(size 0.6604)
		(drill 0.3302)
		(layers "F.Cu" "B.Cu")
		(net "TP_CHC_CPU1_DIMM1_FRU_0")
	)
	(via
		(at 22.123146 -320.566796)
		(size 0.4572)
		(drill 0.2032)
		(layers "F.Cu" "B.Cu")
		(net "TP_CHC_CPU1_DIMM1_FRU_0")
	)
	(segment
		(start 22.123146 -320.469514)
		(end 21.43506 -319.781428)
		(width 0.12954)
		(layer "B.Cu")
		(net "TP_CHC_CPU1_DIMM1_FRU_0")
	)
	(segment
		(start 22.123146 -320.566796)
		(end 22.123146 -320.469514)
		(width 0.12954)
		(layer "B.Cu")
		(net "TP_CHC_CPU1_DIMM1_FRU_0")
	)
	(segment
		(start 283.916882 -242.3668)
		(end 282.811982 -242.3668)
		(width 0.12954)
		(layer "F.Cu")
		(net "TP_CHC_CPU0_DIMM2_FRU_6")
	)
	(via
		(at 283.916882 -242.3668)
		(size 0.4572)
		(drill 0.2032)
		(layers "F.Cu" "B.Cu")
		(net "TP_CHC_CPU0_DIMM2_FRU_6")
	)
	(via
		(at 284.866842 -241.41684)
		(size 0.6604)
		(drill 0.3302)
		(layers "F.Cu" "B.Cu")
		(net "TP_CHC_CPU0_DIMM2_FRU_6")
	)
	(segment
		(start 284.866842 -241.41684)
		(end 283.916882 -242.3668)
		(width 0.12954)
		(layer "B.Cu")
		(net "TP_CHC_CPU0_DIMM2_FRU_6")
	)
	(segment
		(start 283.916882 -243.216684)
		(end 282.811982 -243.216684)
		(width 0.12954)
		(layer "F.Cu")
		(net "TP_CHC_CPU0_DIMM2_FRU_5")
	)
	(via
		(at 284.893258 -243.65331)
		(size 0.6604)
		(drill 0.3302)
		(layers "F.Cu" "B.Cu")
		(net "TP_CHC_CPU0_DIMM2_FRU_5")
	)
	(via
		(at 283.916882 -243.216684)
		(size 0.4572)
		(drill 0.2032)
		(layers "F.Cu" "B.Cu")
		(net "TP_CHC_CPU0_DIMM2_FRU_5")
	)
	(segment
		(start 284.456632 -243.216684)
		(end 283.916882 -243.216684)
		(width 0.12954)
		(layer "B.Cu")
		(net "TP_CHC_CPU0_DIMM2_FRU_5")
	)
	(segment
		(start 284.893258 -243.65331)
		(end 284.456632 -243.216684)
		(width 0.12954)
		(layer "B.Cu")
		(net "TP_CHC_CPU0_DIMM2_FRU_5")
	)
	(segment
		(start 283.916882 -252.566678)
		(end 282.811982 -252.566678)
		(width 0.12954)
		(layer "F.Cu")
		(net "TP_CHC_CPU0_DIMM2_FRU_4")
	)
	(via
		(at 284.794198 -252.566678)
		(size 0.6604)
		(drill 0.3302)
		(layers "F.Cu" "B.Cu")
		(net "TP_CHC_CPU0_DIMM2_FRU_4")
	)
	(via
		(at 283.916882 -252.566678)
		(size 0.4572)
		(drill 0.2032)
		(layers "F.Cu" "B.Cu")
		(net "TP_CHC_CPU0_DIMM2_FRU_4")
	)
	(segment
		(start 283.916882 -252.566678)
		(end 284.794198 -252.566678)
		(width 0.12954)
		(layer "B.Cu")
		(net "TP_CHC_CPU0_DIMM2_FRU_4")
	)
	(segment
		(start 282.811982 -317.166752)
		(end 283.916882 -317.166752)
		(width 0.12954)
		(layer "F.Cu")
		(net "TP_CHC_CPU0_DIMM2_FRU_3")
	)
	(via
		(at 283.916882 -317.166752)
		(size 0.4572)
		(drill 0.2032)
		(layers "F.Cu" "B.Cu")
		(net "TP_CHC_CPU0_DIMM2_FRU_3")
	)
	(via
		(at 283.069792 -316.319662)
		(size 0.6604)
		(drill 0.3302)
		(layers "F.Cu" "B.Cu")
		(net "TP_CHC_CPU0_DIMM2_FRU_3")
	)
	(segment
		(start 283.916882 -317.166752)
		(end 283.069792 -316.319662)
		(width 0.12954)
		(layer "B.Cu")
		(net "TP_CHC_CPU0_DIMM2_FRU_3")
	)
	(segment
		(start 280.9748 -317.541148)
		(end 281.450288 -318.016636)
		(width 0.12954)
		(layer "F.Cu")
		(net "TP_CHC_CPU0_DIMM2_FRU_2")
	)
	(segment
		(start 281.450288 -318.016636)
		(end 282.811982 -318.016636)
		(width 0.12954)
		(layer "F.Cu")
		(net "TP_CHC_CPU0_DIMM2_FRU_2")
	)
	(via
		(at 280.9748 -317.541148)
		(size 0.4572)
		(drill 0.2032)
		(layers "F.Cu" "B.Cu")
		(net "TP_CHC_CPU0_DIMM2_FRU_2")
	)
	(segment
		(start 277.548086 -194.76085)
		(end 277.553928 -194.766692)
		(width 0.12954)
		(layer "F.Cu")
		(net "TP_CHC_CPU0_DIMM2_FRU_1")
	)
	(segment
		(start 277.553928 -194.766692)
		(end 278.711914 -194.766692)
		(width 0.12954)
		(layer "F.Cu")
		(net "TP_CHC_CPU0_DIMM2_FRU_1")
	)
	(via
		(at 277.548086 -194.76085)
		(size 0.4572)
		(drill 0.2032)
		(layers "F.Cu" "B.Cu")
		(net "TP_CHC_CPU0_DIMM2_FRU_1")
	)
	(via
		(at 278.180546 -195.208398)
		(size 0.6604)
		(drill 0.3302)
		(layers "F.Cu" "B.Cu")
		(net "TP_CHC_CPU0_DIMM2_FRU_1")
	)
	(segment
		(start 278.137112 -195.208398)
		(end 277.689564 -194.76085)
		(width 0.12954)
		(layer "B.Cu")
		(net "TP_CHC_CPU0_DIMM2_FRU_1")
	)
	(segment
		(start 278.180546 -195.208398)
		(end 278.137112 -195.208398)
		(width 0.12954)
		(layer "B.Cu")
		(net "TP_CHC_CPU0_DIMM2_FRU_1")
	)
	(segment
		(start 277.689564 -194.76085)
		(end 277.548086 -194.76085)
		(width 0.12954)
		(layer "B.Cu")
		(net "TP_CHC_CPU0_DIMM2_FRU_1")
	)
	(segment
		(start 277.114 -320.566796)
		(end 278.711914 -320.566796)
		(width 0.12954)
		(layer "F.Cu")
		(net "TP_CHC_CPU0_DIMM2_FRU_0")
	)
	(via
		(at 277.114 -320.566796)
		(size 0.4572)
		(drill 0.2032)
		(layers "F.Cu" "B.Cu")
		(net "TP_CHC_CPU0_DIMM2_FRU_0")
	)
	(segment
		(start 276.373082 -242.3668)
		(end 275.268182 -242.3668)
		(width 0.12954)
		(layer "F.Cu")
		(net "TP_CHC_CPU0_DIMM1_FRU_6")
	)
	(via
		(at 276.373082 -242.3668)
		(size 0.4572)
		(drill 0.2032)
		(layers "F.Cu" "B.Cu")
		(net "TP_CHC_CPU0_DIMM1_FRU_6")
	)
	(via
		(at 275.396706 -241.930174)
		(size 0.6604)
		(drill 0.3302)
		(layers "F.Cu" "B.Cu")
		(net "TP_CHC_CPU0_DIMM1_FRU_6")
	)
	(segment
		(start 276.373082 -242.3668)
		(end 275.833332 -242.3668)
		(width 0.12954)
		(layer "B.Cu")
		(net "TP_CHC_CPU0_DIMM1_FRU_6")
	)
	(segment
		(start 275.833332 -242.3668)
		(end 275.396706 -241.930174)
		(width 0.12954)
		(layer "B.Cu")
		(net "TP_CHC_CPU0_DIMM1_FRU_6")
	)
	(segment
		(start 276.373082 -243.216684)
		(end 275.268182 -243.216684)
		(width 0.12954)
		(layer "F.Cu")
		(net "TP_CHC_CPU0_DIMM1_FRU_5")
	)
	(via
		(at 275.514562 -244.075204)
		(size 0.6604)
		(drill 0.3302)
		(layers "F.Cu" "B.Cu")
		(net "TP_CHC_CPU0_DIMM1_FRU_5")
	)
	(via
		(at 276.373082 -243.216684)
		(size 0.4572)
		(drill 0.2032)
		(layers "F.Cu" "B.Cu")
		(net "TP_CHC_CPU0_DIMM1_FRU_5")
	)
	(segment
		(start 275.514562 -244.075204)
		(end 276.373082 -243.216684)
		(width 0.12954)
		(layer "B.Cu")
		(net "TP_CHC_CPU0_DIMM1_FRU_5")
	)
	(segment
		(start 275.268182 -252.566678)
		(end 274.163282 -252.566678)
		(width 0.12954)
		(layer "F.Cu")
		(net "TP_CHC_CPU0_DIMM1_FRU_4")
	)
	(via
		(at 274.163282 -252.566678)
		(size 0.4572)
		(drill 0.2032)
		(layers "F.Cu" "B.Cu")
		(net "TP_CHC_CPU0_DIMM1_FRU_4")
	)
	(via
		(at 274.159218 -250.07189)
		(size 0.6604)
		(drill 0.3302)
		(layers "F.Cu" "B.Cu")
		(net "TP_CHC_CPU0_DIMM1_FRU_4")
	)
	(segment
		(start 273.712178 -250.51893)
		(end 274.159218 -250.07189)
		(width 0.12954)
		(layer "B.Cu")
		(net "TP_CHC_CPU0_DIMM1_FRU_4")
	)
	(segment
		(start 273.712178 -251.44603)
		(end 273.712178 -250.51893)
		(width 0.12954)
		(layer "B.Cu")
		(net "TP_CHC_CPU0_DIMM1_FRU_4")
	)
	(segment
		(start 274.163282 -252.566678)
		(end 274.163282 -251.897134)
		(width 0.12954)
		(layer "B.Cu")
		(net "TP_CHC_CPU0_DIMM1_FRU_4")
	)
	(segment
		(start 274.163282 -251.897134)
		(end 273.712178 -251.44603)
		(width 0.12954)
		(layer "B.Cu")
		(net "TP_CHC_CPU0_DIMM1_FRU_4")
	)
	(segment
		(start 275.268182 -317.166752)
		(end 276.373082 -317.166752)
		(width 0.12954)
		(layer "F.Cu")
		(net "TP_CHC_CPU0_DIMM1_FRU_3")
	)
	(via
		(at 276.373082 -317.166752)
		(size 0.4572)
		(drill 0.2032)
		(layers "F.Cu" "B.Cu")
		(net "TP_CHC_CPU0_DIMM1_FRU_3")
	)
	(via
		(at 275.37156 -316.281308)
		(size 0.6604)
		(drill 0.3302)
		(layers "F.Cu" "B.Cu")
		(net "TP_CHC_CPU0_DIMM1_FRU_3")
	)
	(segment
		(start 276.257004 -317.166752)
		(end 275.37156 -316.281308)
		(width 0.12954)
		(layer "B.Cu")
		(net "TP_CHC_CPU0_DIMM1_FRU_3")
	)
	(segment
		(start 276.373082 -317.166752)
		(end 276.257004 -317.166752)
		(width 0.12954)
		(layer "B.Cu")
		(net "TP_CHC_CPU0_DIMM1_FRU_3")
	)
	(segment
		(start 272.91792 -319.420748)
		(end 274.322032 -318.016636)
		(width 0.12954)
		(layer "F.Cu")
		(net "TP_CHC_CPU0_DIMM1_FRU_2")
	)
	(segment
		(start 272.91792 -320.990468)
		(end 272.91792 -319.420748)
		(width 0.12954)
		(layer "F.Cu")
		(net "TP_CHC_CPU0_DIMM1_FRU_2")
	)
	(segment
		(start 274.322032 -318.016636)
		(end 275.268182 -318.016636)
		(width 0.12954)
		(layer "F.Cu")
		(net "TP_CHC_CPU0_DIMM1_FRU_2")
	)
	(via
		(at 272.91792 -320.990468)
		(size 0.4572)
		(drill 0.2032)
		(layers "F.Cu" "B.Cu")
		(net "TP_CHC_CPU0_DIMM1_FRU_2")
	)
	(segment
		(start 270.037814 -194.766692)
		(end 271.168114 -194.766692)
		(width 0.12954)
		(layer "F.Cu")
		(net "TP_CHC_CPU0_DIMM1_FRU_1")
	)
	(via
		(at 270.037814 -194.766692)
		(size 0.4572)
		(drill 0.2032)
		(layers "F.Cu" "B.Cu")
		(net "TP_CHC_CPU0_DIMM1_FRU_1")
	)
	(via
		(at 269.714218 -196.605652)
		(size 0.6604)
		(drill 0.3302)
		(layers "F.Cu" "B.Cu")
		(net "TP_CHC_CPU0_DIMM1_FRU_1")
	)
	(segment
		(start 269.381478 -196.272912)
		(end 269.381478 -195.423028)
		(width 0.12954)
		(layer "B.Cu")
		(net "TP_CHC_CPU0_DIMM1_FRU_1")
	)
	(segment
		(start 269.714218 -196.605652)
		(end 269.381478 -196.272912)
		(width 0.12954)
		(layer "B.Cu")
		(net "TP_CHC_CPU0_DIMM1_FRU_1")
	)
	(segment
		(start 269.381478 -195.423028)
		(end 270.037814 -194.766692)
		(width 0.12954)
		(layer "B.Cu")
		(net "TP_CHC_CPU0_DIMM1_FRU_1")
	)
	(segment
		(start 271.168114 -320.566796)
		(end 269.57782 -320.566796)
		(width 0.12954)
		(layer "F.Cu")
		(net "TP_CHC_CPU0_DIMM1_FRU_0")
	)
	(via
		(at 269.57782 -320.566796)
		(size 0.4572)
		(drill 0.2032)
		(layers "F.Cu" "B.Cu")
		(net "TP_CHC_CPU0_DIMM1_FRU_0")
	)
	(segment
		(start 49.959514 -242.3668)
		(end 51.064414 -242.3668)
		(width 0.12954)
		(layer "F.Cu")
		(net "TP_CHB_CPU1_DIMM2_FRU_6")
	)
	(via
		(at 51.900328 -241.530886)
		(size 0.6604)
		(drill 0.3302)
		(layers "F.Cu" "B.Cu")
		(net "TP_CHB_CPU1_DIMM2_FRU_6")
	)
	(via
		(at 51.064414 -242.3668)
		(size 0.4572)
		(drill 0.2032)
		(layers "F.Cu" "B.Cu")
		(net "TP_CHB_CPU1_DIMM2_FRU_6")
	)
	(segment
		(start 51.064414 -242.3668)
		(end 51.900328 -241.530886)
		(width 0.12954)
		(layer "B.Cu")
		(net "TP_CHB_CPU1_DIMM2_FRU_6")
	)
	(segment
		(start 49.959514 -243.216684)
		(end 51.064414 -243.216684)
		(width 0.12954)
		(layer "F.Cu")
		(net "TP_CHB_CPU1_DIMM2_FRU_5")
	)
	(via
		(at 52.229258 -243.73205)
		(size 0.6604)
		(drill 0.3302)
		(layers "F.Cu" "B.Cu")
		(net "TP_CHB_CPU1_DIMM2_FRU_5")
	)
	(via
		(at 51.064414 -243.216684)
		(size 0.4572)
		(drill 0.2032)
		(layers "F.Cu" "B.Cu")
		(net "TP_CHB_CPU1_DIMM2_FRU_5")
	)
	(segment
		(start 52.229258 -243.73205)
		(end 51.713892 -243.216684)
		(width 0.12954)
		(layer "B.Cu")
		(net "TP_CHB_CPU1_DIMM2_FRU_5")
	)
	(segment
		(start 51.713892 -243.216684)
		(end 51.064414 -243.216684)
		(width 0.12954)
		(layer "B.Cu")
		(net "TP_CHB_CPU1_DIMM2_FRU_5")
	)
	(segment
		(start 49.959514 -252.566678)
		(end 51.064414 -252.566678)
		(width 0.12954)
		(layer "F.Cu")
		(net "TP_CHB_CPU1_DIMM2_FRU_4")
	)
	(via
		(at 51.064414 -252.566678)
		(size 0.4572)
		(drill 0.2032)
		(layers "F.Cu" "B.Cu")
		(net "TP_CHB_CPU1_DIMM2_FRU_4")
	)
	(via
		(at 50.118518 -251.40539)
		(size 0.6604)
		(drill 0.3302)
		(layers "F.Cu" "B.Cu")
		(net "TP_CHB_CPU1_DIMM2_FRU_4")
	)
	(segment
		(start 50.118518 -251.40539)
		(end 50.728118 -252.01499)
		(width 0.12954)
		(layer "B.Cu")
		(net "TP_CHB_CPU1_DIMM2_FRU_4")
	)
	(segment
		(start 50.728118 -252.01499)
		(end 50.728118 -252.230382)
		(width 0.12954)
		(layer "B.Cu")
		(net "TP_CHB_CPU1_DIMM2_FRU_4")
	)
	(segment
		(start 50.728118 -252.230382)
		(end 51.064414 -252.566678)
		(width 0.12954)
		(layer "B.Cu")
		(net "TP_CHB_CPU1_DIMM2_FRU_4")
	)
	(segment
		(start 51.064414 -317.166752)
		(end 49.959514 -317.166752)
		(width 0.12954)
		(layer "F.Cu")
		(net "TP_CHB_CPU1_DIMM2_FRU_3")
	)
	(via
		(at 51.064414 -317.166752)
		(size 0.4572)
		(drill 0.2032)
		(layers "F.Cu" "B.Cu")
		(net "TP_CHB_CPU1_DIMM2_FRU_3")
	)
	(via
		(at 51.064414 -318.017398)
		(size 0.6604)
		(drill 0.3302)
		(layers "F.Cu" "B.Cu")
		(net "TP_CHB_CPU1_DIMM2_FRU_3")
	)
	(segment
		(start 51.064414 -317.166752)
		(end 51.064414 -318.017398)
		(width 0.12954)
		(layer "B.Cu")
		(net "TP_CHB_CPU1_DIMM2_FRU_3")
	)
	(segment
		(start 48.854614 -318.016636)
		(end 49.959514 -318.016636)
		(width 0.12954)
		(layer "F.Cu")
		(net "TP_CHB_CPU1_DIMM2_FRU_2")
	)
	(via
		(at 49.70526 -318.016636)
		(size 0.6604)
		(drill 0.3302)
		(layers "F.Cu" "B.Cu")
		(net "TP_CHB_CPU1_DIMM2_FRU_2")
	)
	(via
		(at 48.854614 -318.016636)
		(size 0.4572)
		(drill 0.2032)
		(layers "F.Cu" "B.Cu")
		(net "TP_CHB_CPU1_DIMM2_FRU_2")
	)
	(segment
		(start 48.854614 -318.016636)
		(end 49.70526 -318.016636)
		(width 0.12954)
		(layer "B.Cu")
		(net "TP_CHB_CPU1_DIMM2_FRU_2")
	)
	(segment
		(start 44.729146 -194.766692)
		(end 45.859446 -194.766692)
		(width 0.12954)
		(layer "F.Cu")
		(net "TP_CHB_CPU1_DIMM2_FRU_1")
	)
	(via
		(at 45.4914 -194.766692)
		(size 0.6604)
		(drill 0.3302)
		(layers "F.Cu" "B.Cu")
		(net "TP_CHB_CPU1_DIMM2_FRU_1")
	)
	(via
		(at 44.729146 -194.766692)
		(size 0.4572)
		(drill 0.2032)
		(layers "F.Cu" "B.Cu")
		(net "TP_CHB_CPU1_DIMM2_FRU_1")
	)
	(segment
		(start 44.729146 -194.766692)
		(end 45.4914 -194.766692)
		(width 0.12954)
		(layer "B.Cu")
		(net "TP_CHB_CPU1_DIMM2_FRU_1")
	)
	(segment
		(start 45.859446 -320.566796)
		(end 44.754546 -320.566796)
		(width 0.12954)
		(layer "F.Cu")
		(net "TP_CHB_CPU1_DIMM2_FRU_0")
	)
	(via
		(at 44.754546 -320.566796)
		(size 0.4572)
		(drill 0.2032)
		(layers "F.Cu" "B.Cu")
		(net "TP_CHB_CPU1_DIMM2_FRU_0")
	)
	(via
		(at 44.13758 -320.088768)
		(size 0.6604)
		(drill 0.3302)
		(layers "F.Cu" "B.Cu")
		(net "TP_CHB_CPU1_DIMM2_FRU_0")
	)
	(segment
		(start 44.276518 -320.088768)
		(end 44.13758 -320.088768)
		(width 0.12954)
		(layer "B.Cu")
		(net "TP_CHB_CPU1_DIMM2_FRU_0")
	)
	(segment
		(start 44.754546 -320.566796)
		(end 44.276518 -320.088768)
		(width 0.12954)
		(layer "B.Cu")
		(net "TP_CHB_CPU1_DIMM2_FRU_0")
	)
	(segment
		(start 42.415714 -242.3668)
		(end 43.520614 -242.3668)
		(width 0.12954)
		(layer "F.Cu")
		(net "TP_CHB_CPU1_DIMM1_FRU_6")
	)
	(via
		(at 43.520614 -242.3668)
		(size 0.4572)
		(drill 0.2032)
		(layers "F.Cu" "B.Cu")
		(net "TP_CHB_CPU1_DIMM1_FRU_6")
	)
	(via
		(at 44.419774 -241.46764)
		(size 0.6604)
		(drill 0.3302)
		(layers "F.Cu" "B.Cu")
		(net "TP_CHB_CPU1_DIMM1_FRU_6")
	)
	(segment
		(start 44.419774 -241.46764)
		(end 43.520614 -242.3668)
		(width 0.12954)
		(layer "B.Cu")
		(net "TP_CHB_CPU1_DIMM1_FRU_6")
	)
	(segment
		(start 42.415714 -243.216684)
		(end 43.520614 -243.216684)
		(width 0.12954)
		(layer "F.Cu")
		(net "TP_CHB_CPU1_DIMM1_FRU_5")
	)
	(via
		(at 44.49699 -243.65331)
		(size 0.6604)
		(drill 0.3302)
		(layers "F.Cu" "B.Cu")
		(net "TP_CHB_CPU1_DIMM1_FRU_5")
	)
	(via
		(at 43.520614 -243.216684)
		(size 0.4572)
		(drill 0.2032)
		(layers "F.Cu" "B.Cu")
		(net "TP_CHB_CPU1_DIMM1_FRU_5")
	)
	(segment
		(start 44.060364 -243.216684)
		(end 43.520614 -243.216684)
		(width 0.12954)
		(layer "B.Cu")
		(net "TP_CHB_CPU1_DIMM1_FRU_5")
	)
	(segment
		(start 44.49699 -243.65331)
		(end 44.060364 -243.216684)
		(width 0.12954)
		(layer "B.Cu")
		(net "TP_CHB_CPU1_DIMM1_FRU_5")
	)
	(segment
		(start 42.415714 -252.566678)
		(end 41.310814 -252.566678)
		(width 0.12954)
		(layer "F.Cu")
		(net "TP_CHB_CPU1_DIMM1_FRU_4")
	)
	(via
		(at 40.75811 -250.23191)
		(size 0.6604)
		(drill 0.3302)
		(layers "F.Cu" "B.Cu")
		(net "TP_CHB_CPU1_DIMM1_FRU_4")
	)
	(via
		(at 41.310814 -252.566678)
		(size 0.4572)
		(drill 0.2032)
		(layers "F.Cu" "B.Cu")
		(net "TP_CHB_CPU1_DIMM1_FRU_4")
	)
	(segment
		(start 41.310814 -252.566678)
		(end 41.310814 -251.906786)
		(width 0.12954)
		(layer "B.Cu")
		(net "TP_CHB_CPU1_DIMM1_FRU_4")
	)
	(segment
		(start 41.310814 -251.906786)
		(end 40.75811 -251.354082)
		(width 0.12954)
		(layer "B.Cu")
		(net "TP_CHB_CPU1_DIMM1_FRU_4")
	)
	(segment
		(start 40.75811 -251.354082)
		(end 40.75811 -250.23191)
		(width 0.12954)
		(layer "B.Cu")
		(net "TP_CHB_CPU1_DIMM1_FRU_4")
	)
	(segment
		(start 43.520614 -317.166752)
		(end 42.415714 -317.166752)
		(width 0.12954)
		(layer "F.Cu")
		(net "TP_CHB_CPU1_DIMM1_FRU_3")
	)
	(via
		(at 43.520614 -318.017398)
		(size 0.6604)
		(drill 0.3302)
		(layers "F.Cu" "B.Cu")
		(net "TP_CHB_CPU1_DIMM1_FRU_3")
	)
	(via
		(at 43.520614 -317.166752)
		(size 0.4572)
		(drill 0.2032)
		(layers "F.Cu" "B.Cu")
		(net "TP_CHB_CPU1_DIMM1_FRU_3")
	)
	(segment
		(start 43.520614 -317.166752)
		(end 43.520614 -318.017398)
		(width 0.12954)
		(layer "B.Cu")
		(net "TP_CHB_CPU1_DIMM1_FRU_3")
	)
	(segment
		(start 41.310814 -318.016636)
		(end 42.415714 -318.016636)
		(width 0.12954)
		(layer "F.Cu")
		(net "TP_CHB_CPU1_DIMM1_FRU_2")
	)
	(via
		(at 41.310814 -318.016636)
		(size 0.4572)
		(drill 0.2032)
		(layers "F.Cu" "B.Cu")
		(net "TP_CHB_CPU1_DIMM1_FRU_2")
	)
	(via
		(at 42.16146 -318.016636)
		(size 0.6604)
		(drill 0.3302)
		(layers "F.Cu" "B.Cu")
		(net "TP_CHB_CPU1_DIMM1_FRU_2")
	)
	(segment
		(start 41.310814 -318.016636)
		(end 42.16146 -318.016636)
		(width 0.12954)
		(layer "B.Cu")
		(net "TP_CHB_CPU1_DIMM1_FRU_2")
	)
	(segment
		(start 37.177218 -194.76085)
		(end 38.309804 -194.76085)
		(width 0.12954)
		(layer "F.Cu")
		(net "TP_CHB_CPU1_DIMM1_FRU_1")
	)
	(segment
		(start 38.309804 -194.76085)
		(end 38.315646 -194.766692)
		(width 0.12954)
		(layer "F.Cu")
		(net "TP_CHB_CPU1_DIMM1_FRU_1")
	)
	(via
		(at 37.9476 -194.766692)
		(size 0.6604)
		(drill 0.3302)
		(layers "F.Cu" "B.Cu")
		(net "TP_CHB_CPU1_DIMM1_FRU_1")
	)
	(via
		(at 37.177218 -194.76085)
		(size 0.4572)
		(drill 0.2032)
		(layers "F.Cu" "B.Cu")
		(net "TP_CHB_CPU1_DIMM1_FRU_1")
	)
	(segment
		(start 37.18306 -194.766692)
		(end 37.177218 -194.76085)
		(width 0.12954)
		(layer "B.Cu")
		(net "TP_CHB_CPU1_DIMM1_FRU_1")
	)
	(segment
		(start 37.9476 -194.766692)
		(end 37.18306 -194.766692)
		(width 0.12954)
		(layer "B.Cu")
		(net "TP_CHB_CPU1_DIMM1_FRU_1")
	)
	(segment
		(start 38.315646 -320.566796)
		(end 37.210746 -320.566796)
		(width 0.12954)
		(layer "F.Cu")
		(net "TP_CHB_CPU1_DIMM1_FRU_0")
	)
	(via
		(at 36.49472 -320.695828)
		(size 0.6604)
		(drill 0.3302)
		(layers "F.Cu" "B.Cu")
		(net "TP_CHB_CPU1_DIMM1_FRU_0")
	)
	(via
		(at 37.210746 -320.566796)
		(size 0.4572)
		(drill 0.2032)
		(layers "F.Cu" "B.Cu")
		(net "TP_CHB_CPU1_DIMM1_FRU_0")
	)
	(segment
		(start 37.083746 -320.695828)
		(end 36.49472 -320.695828)
		(width 0.12954)
		(layer "B.Cu")
		(net "TP_CHB_CPU1_DIMM1_FRU_0")
	)
	(segment
		(start 37.210746 -320.568828)
		(end 37.083746 -320.695828)
		(width 0.12954)
		(layer "B.Cu")
		(net "TP_CHB_CPU1_DIMM1_FRU_0")
	)
	(segment
		(start 37.210746 -320.566796)
		(end 37.210746 -320.568828)
		(width 0.12954)
		(layer "B.Cu")
		(net "TP_CHB_CPU1_DIMM1_FRU_0")
	)
	(segment
		(start 299.004482 -242.3668)
		(end 297.899582 -242.3668)
		(width 0.12954)
		(layer "F.Cu")
		(net "TP_CHB_CPU0_DIMM2_FRU_6")
	)
	(via
		(at 299.954442 -241.41684)
		(size 0.6604)
		(drill 0.3302)
		(layers "F.Cu" "B.Cu")
		(net "TP_CHB_CPU0_DIMM2_FRU_6")
	)
	(via
		(at 299.004482 -242.3668)
		(size 0.4572)
		(drill 0.2032)
		(layers "F.Cu" "B.Cu")
		(net "TP_CHB_CPU0_DIMM2_FRU_6")
	)
	(segment
		(start 299.954442 -241.41684)
		(end 299.004482 -242.3668)
		(width 0.12954)
		(layer "B.Cu")
		(net "TP_CHB_CPU0_DIMM2_FRU_6")
	)
	(segment
		(start 299.004482 -243.216684)
		(end 297.899582 -243.216684)
		(width 0.12954)
		(layer "F.Cu")
		(net "TP_CHB_CPU0_DIMM2_FRU_5")
	)
	(via
		(at 299.004482 -243.216684)
		(size 0.4572)
		(drill 0.2032)
		(layers "F.Cu" "B.Cu")
		(net "TP_CHB_CPU0_DIMM2_FRU_5")
	)
	(via
		(at 299.980858 -243.65331)
		(size 0.6604)
		(drill 0.3302)
		(layers "F.Cu" "B.Cu")
		(net "TP_CHB_CPU0_DIMM2_FRU_5")
	)
	(segment
		(start 299.544232 -243.216684)
		(end 299.004482 -243.216684)
		(width 0.12954)
		(layer "B.Cu")
		(net "TP_CHB_CPU0_DIMM2_FRU_5")
	)
	(segment
		(start 299.980858 -243.65331)
		(end 299.544232 -243.216684)
		(width 0.12954)
		(layer "B.Cu")
		(net "TP_CHB_CPU0_DIMM2_FRU_5")
	)
	(segment
		(start 299.004482 -252.566678)
		(end 297.899582 -252.566678)
		(width 0.12954)
		(layer "F.Cu")
		(net "TP_CHB_CPU0_DIMM2_FRU_4")
	)
	(via
		(at 299.004482 -252.566678)
		(size 0.4572)
		(drill 0.2032)
		(layers "F.Cu" "B.Cu")
		(net "TP_CHB_CPU0_DIMM2_FRU_4")
	)
	(via
		(at 299.881798 -252.566678)
		(size 0.6604)
		(drill 0.3302)
		(layers "F.Cu" "B.Cu")
		(net "TP_CHB_CPU0_DIMM2_FRU_4")
	)
	(segment
		(start 299.004482 -252.566678)
		(end 299.881798 -252.566678)
		(width 0.12954)
		(layer "B.Cu")
		(net "TP_CHB_CPU0_DIMM2_FRU_4")
	)
	(segment
		(start 297.899582 -317.166752)
		(end 298.98848 -317.166752)
		(width 0.12954)
		(layer "F.Cu")
		(net "TP_CHB_CPU0_DIMM2_FRU_3")
	)
	(via
		(at 298.98848 -317.166752)
		(size 0.4572)
		(drill 0.2032)
		(layers "F.Cu" "B.Cu")
		(net "TP_CHB_CPU0_DIMM2_FRU_3")
	)
	(via
		(at 298.280074 -317.166752)
		(size 0.6604)
		(drill 0.3302)
		(layers "F.Cu" "B.Cu")
		(net "TP_CHB_CPU0_DIMM2_FRU_3")
	)
	(segment
		(start 298.98848 -317.166752)
		(end 298.280074 -317.166752)
		(width 0.12954)
		(layer "B.Cu")
		(net "TP_CHB_CPU0_DIMM2_FRU_3")
	)
	(segment
		(start 296.794682 -318.016636)
		(end 297.899582 -318.016636)
		(width 0.12954)
		(layer "F.Cu")
		(net "TP_CHB_CPU0_DIMM2_FRU_2")
	)
	(via
		(at 296.794682 -318.016636)
		(size 0.4572)
		(drill 0.2032)
		(layers "F.Cu" "B.Cu")
		(net "TP_CHB_CPU0_DIMM2_FRU_2")
	)
	(segment
		(start 292.669214 -194.766692)
		(end 293.799514 -194.766692)
		(width 0.12954)
		(layer "F.Cu")
		(net "TP_CHB_CPU0_DIMM2_FRU_1")
	)
	(via
		(at 292.669214 -194.766692)
		(size 0.4572)
		(drill 0.2032)
		(layers "F.Cu" "B.Cu")
		(net "TP_CHB_CPU0_DIMM2_FRU_1")
	)
	(segment
		(start 292.2016 -320.566796)
		(end 293.799514 -320.566796)
		(width 0.12954)
		(layer "F.Cu")
		(net "TP_CHB_CPU0_DIMM2_FRU_0")
	)
	(via
		(at 292.2016 -320.566796)
		(size 0.4572)
		(drill 0.2032)
		(layers "F.Cu" "B.Cu")
		(net "TP_CHB_CPU0_DIMM2_FRU_0")
	)
	(segment
		(start 291.460682 -242.3668)
		(end 290.355782 -242.3668)
		(width 0.12954)
		(layer "F.Cu")
		(net "TP_CHB_CPU0_DIMM1_FRU_6")
	)
	(via
		(at 291.460682 -242.3668)
		(size 0.4572)
		(drill 0.2032)
		(layers "F.Cu" "B.Cu")
		(net "TP_CHB_CPU0_DIMM1_FRU_6")
	)
	(via
		(at 292.410642 -241.41684)
		(size 0.6604)
		(drill 0.3302)
		(layers "F.Cu" "B.Cu")
		(net "TP_CHB_CPU0_DIMM1_FRU_6")
	)
	(segment
		(start 292.410642 -241.41684)
		(end 291.460682 -242.3668)
		(width 0.12954)
		(layer "B.Cu")
		(net "TP_CHB_CPU0_DIMM1_FRU_6")
	)
	(segment
		(start 291.460682 -243.216684)
		(end 290.355782 -243.216684)
		(width 0.12954)
		(layer "F.Cu")
		(net "TP_CHB_CPU0_DIMM1_FRU_5")
	)
	(via
		(at 292.437058 -243.65331)
		(size 0.6604)
		(drill 0.3302)
		(layers "F.Cu" "B.Cu")
		(net "TP_CHB_CPU0_DIMM1_FRU_5")
	)
	(via
		(at 291.460682 -243.216684)
		(size 0.4572)
		(drill 0.2032)
		(layers "F.Cu" "B.Cu")
		(net "TP_CHB_CPU0_DIMM1_FRU_5")
	)
	(segment
		(start 292.437058 -243.65331)
		(end 292.000432 -243.216684)
		(width 0.12954)
		(layer "B.Cu")
		(net "TP_CHB_CPU0_DIMM1_FRU_5")
	)
	(segment
		(start 292.000432 -243.216684)
		(end 291.460682 -243.216684)
		(width 0.12954)
		(layer "B.Cu")
		(net "TP_CHB_CPU0_DIMM1_FRU_5")
	)
	(segment
		(start 290.355782 -252.566678)
		(end 289.250882 -252.566678)
		(width 0.12954)
		(layer "F.Cu")
		(net "TP_CHB_CPU0_DIMM1_FRU_4")
	)
	(via
		(at 289.250882 -252.566678)
		(size 0.4572)
		(drill 0.2032)
		(layers "F.Cu" "B.Cu")
		(net "TP_CHB_CPU0_DIMM1_FRU_4")
	)
	(segment
		(start 290.355782 -317.166752)
		(end 291.460682 -317.166752)
		(width 0.12954)
		(layer "F.Cu")
		(net "TP_CHB_CPU0_DIMM1_FRU_3")
	)
	(via
		(at 291.460682 -317.166752)
		(size 0.4572)
		(drill 0.2032)
		(layers "F.Cu" "B.Cu")
		(net "TP_CHB_CPU0_DIMM1_FRU_3")
	)
	(via
		(at 290.777168 -317.495936)
		(size 0.6604)
		(drill 0.3302)
		(layers "F.Cu" "B.Cu")
		(net "TP_CHB_CPU0_DIMM1_FRU_3")
	)
	(segment
		(start 291.460682 -317.166752)
		(end 291.106352 -317.166752)
		(width 0.12954)
		(layer "B.Cu")
		(net "TP_CHB_CPU0_DIMM1_FRU_3")
	)
	(segment
		(start 291.106352 -317.166752)
		(end 290.777168 -317.495936)
		(width 0.12954)
		(layer "B.Cu")
		(net "TP_CHB_CPU0_DIMM1_FRU_3")
	)
	(segment
		(start 289.250882 -318.016636)
		(end 290.355782 -318.016636)
		(width 0.12954)
		(layer "F.Cu")
		(net "TP_CHB_CPU0_DIMM1_FRU_2")
	)
	(via
		(at 289.508184 -317.077852)
		(size 0.6604)
		(drill 0.3302)
		(layers "F.Cu" "B.Cu")
		(net "TP_CHB_CPU0_DIMM1_FRU_2")
	)
	(via
		(at 289.250882 -318.016636)
		(size 0.4572)
		(drill 0.2032)
		(layers "F.Cu" "B.Cu")
		(net "TP_CHB_CPU0_DIMM1_FRU_2")
	)
	(segment
		(start 289.250882 -317.335154)
		(end 289.508184 -317.077852)
		(width 0.12954)
		(layer "B.Cu")
		(net "TP_CHB_CPU0_DIMM1_FRU_2")
	)
	(segment
		(start 289.250882 -318.016636)
		(end 289.250882 -317.335154)
		(width 0.12954)
		(layer "B.Cu")
		(net "TP_CHB_CPU0_DIMM1_FRU_2")
	)
	(segment
		(start 285.125414 -194.766692)
		(end 286.255714 -194.766692)
		(width 0.12954)
		(layer "F.Cu")
		(net "TP_CHB_CPU0_DIMM1_FRU_1")
	)
	(via
		(at 285.125414 -194.766692)
		(size 0.4572)
		(drill 0.2032)
		(layers "F.Cu" "B.Cu")
		(net "TP_CHB_CPU0_DIMM1_FRU_1")
	)
	(via
		(at 285.799276 -195.252086)
		(size 0.6604)
		(drill 0.3302)
		(layers "F.Cu" "B.Cu")
		(net "TP_CHB_CPU0_DIMM1_FRU_1")
	)
	(segment
		(start 285.125414 -194.92976)
		(end 285.125414 -194.766692)
		(width 0.12954)
		(layer "B.Cu")
		(net "TP_CHB_CPU0_DIMM1_FRU_1")
	)
	(segment
		(start 285.44774 -195.252086)
		(end 285.125414 -194.92976)
		(width 0.12954)
		(layer "B.Cu")
		(net "TP_CHB_CPU0_DIMM1_FRU_1")
	)
	(segment
		(start 285.799276 -195.252086)
		(end 285.44774 -195.252086)
		(width 0.12954)
		(layer "B.Cu")
		(net "TP_CHB_CPU0_DIMM1_FRU_1")
	)
	(segment
		(start 284.6832 -320.566796)
		(end 286.255714 -320.566796)
		(width 0.12954)
		(layer "F.Cu")
		(net "TP_CHB_CPU0_DIMM1_FRU_0")
	)
	(via
		(at 284.6832 -320.566796)
		(size 0.4572)
		(drill 0.2032)
		(layers "F.Cu" "B.Cu")
		(net "TP_CHB_CPU0_DIMM1_FRU_0")
	)
	(segment
		(start 65.047114 -242.3668)
		(end 63.942214 -242.3668)
		(width 0.12954)
		(layer "F.Cu")
		(net "TP_CHA_CPU1_DIMM2_FRU_6")
	)
	(via
		(at 63.942214 -242.3668)
		(size 0.4572)
		(drill 0.2032)
		(layers "F.Cu" "B.Cu")
		(net "TP_CHA_CPU1_DIMM2_FRU_6")
	)
	(via
		(at 64.64808 -242.296188)
		(size 0.6604)
		(drill 0.3302)
		(layers "F.Cu" "B.Cu")
		(net "TP_CHA_CPU1_DIMM2_FRU_6")
	)
	(segment
		(start 64.012826 -242.296188)
		(end 63.942214 -242.3668)
		(width 0.12954)
		(layer "B.Cu")
		(net "TP_CHA_CPU1_DIMM2_FRU_6")
	)
	(segment
		(start 64.64808 -242.296188)
		(end 64.012826 -242.296188)
		(width 0.12954)
		(layer "B.Cu")
		(net "TP_CHA_CPU1_DIMM2_FRU_6")
	)
	(segment
		(start 65.047114 -243.216684)
		(end 63.942214 -243.216684)
		(width 0.12954)
		(layer "F.Cu")
		(net "TP_CHA_CPU1_DIMM2_FRU_5")
	)
	(via
		(at 63.942214 -243.216684)
		(size 0.4572)
		(drill 0.2032)
		(layers "F.Cu" "B.Cu")
		(net "TP_CHA_CPU1_DIMM2_FRU_5")
	)
	(via
		(at 64.55664 -243.672868)
		(size 0.6604)
		(drill 0.3302)
		(layers "F.Cu" "B.Cu")
		(net "TP_CHA_CPU1_DIMM2_FRU_5")
	)
	(segment
		(start 64.398398 -243.672868)
		(end 63.942214 -243.216684)
		(width 0.12954)
		(layer "B.Cu")
		(net "TP_CHA_CPU1_DIMM2_FRU_5")
	)
	(segment
		(start 64.55664 -243.672868)
		(end 64.398398 -243.672868)
		(width 0.12954)
		(layer "B.Cu")
		(net "TP_CHA_CPU1_DIMM2_FRU_5")
	)
	(segment
		(start 63.942214 -252.566678)
		(end 65.047114 -252.566678)
		(width 0.12954)
		(layer "F.Cu")
		(net "TP_CHA_CPU1_DIMM2_FRU_4")
	)
	(via
		(at 63.942214 -252.566678)
		(size 0.4572)
		(drill 0.2032)
		(layers "F.Cu" "B.Cu")
		(net "TP_CHA_CPU1_DIMM2_FRU_4")
	)
	(via
		(at 63.13805 -251.05487)
		(size 0.6604)
		(drill 0.3302)
		(layers "F.Cu" "B.Cu")
		(net "TP_CHA_CPU1_DIMM2_FRU_4")
	)
	(segment
		(start 63.942214 -251.859034)
		(end 63.13805 -251.05487)
		(width 0.12954)
		(layer "B.Cu")
		(net "TP_CHA_CPU1_DIMM2_FRU_4")
	)
	(segment
		(start 63.942214 -252.566678)
		(end 63.942214 -251.859034)
		(width 0.12954)
		(layer "B.Cu")
		(net "TP_CHA_CPU1_DIMM2_FRU_4")
	)
	(segment
		(start 65.047114 -317.166752)
		(end 66.152014 -317.166752)
		(width 0.12954)
		(layer "F.Cu")
		(net "TP_CHA_CPU1_DIMM2_FRU_3")
	)
	(via
		(at 67.00266 -317.166752)
		(size 0.6604)
		(drill 0.3302)
		(layers "F.Cu" "B.Cu")
		(net "TP_CHA_CPU1_DIMM2_FRU_3")
	)
	(via
		(at 66.152014 -317.166752)
		(size 0.4572)
		(drill 0.2032)
		(layers "F.Cu" "B.Cu")
		(net "TP_CHA_CPU1_DIMM2_FRU_3")
	)
	(segment
		(start 66.152014 -317.166752)
		(end 67.00266 -317.166752)
		(width 0.12954)
		(layer "B.Cu")
		(net "TP_CHA_CPU1_DIMM2_FRU_3")
	)
	(segment
		(start 63.933578 -318.016636)
		(end 65.047114 -318.016636)
		(width 0.12954)
		(layer "F.Cu")
		(net "TP_CHA_CPU1_DIMM2_FRU_2")
	)
	(via
		(at 63.933578 -318.016636)
		(size 0.4572)
		(drill 0.2032)
		(layers "F.Cu" "B.Cu")
		(net "TP_CHA_CPU1_DIMM2_FRU_2")
	)
	(via
		(at 62.985142 -317.2968)
		(size 0.6604)
		(drill 0.3302)
		(layers "F.Cu" "B.Cu")
		(net "TP_CHA_CPU1_DIMM2_FRU_2")
	)
	(segment
		(start 63.933578 -318.016636)
		(end 63.704978 -318.016636)
		(width 0.12954)
		(layer "B.Cu")
		(net "TP_CHA_CPU1_DIMM2_FRU_2")
	)
	(segment
		(start 63.704978 -318.016636)
		(end 62.985142 -317.2968)
		(width 0.12954)
		(layer "B.Cu")
		(net "TP_CHA_CPU1_DIMM2_FRU_2")
	)
	(segment
		(start 60.947046 -194.766692)
		(end 59.816746 -194.766692)
		(width 0.12954)
		(layer "F.Cu")
		(net "TP_CHA_CPU1_DIMM2_FRU_1")
	)
	(via
		(at 59.816746 -194.766692)
		(size 0.4572)
		(drill 0.2032)
		(layers "F.Cu" "B.Cu")
		(net "TP_CHA_CPU1_DIMM2_FRU_1")
	)
	(via
		(at 60.011818 -193.95059)
		(size 0.6604)
		(drill 0.3302)
		(layers "F.Cu" "B.Cu")
		(net "TP_CHA_CPU1_DIMM2_FRU_1")
	)
	(segment
		(start 60.011818 -193.95059)
		(end 60.011818 -194.57162)
		(width 0.12954)
		(layer "B.Cu")
		(net "TP_CHA_CPU1_DIMM2_FRU_1")
	)
	(segment
		(start 60.011818 -194.57162)
		(end 59.816746 -194.766692)
		(width 0.12954)
		(layer "B.Cu")
		(net "TP_CHA_CPU1_DIMM2_FRU_1")
	)
	(segment
		(start 59.842146 -320.566796)
		(end 60.947046 -320.566796)
		(width 0.12954)
		(layer "F.Cu")
		(net "TP_CHA_CPU1_DIMM2_FRU_0")
	)
	(via
		(at 59.13628 -319.875408)
		(size 0.6604)
		(drill 0.3302)
		(layers "F.Cu" "B.Cu")
		(net "TP_CHA_CPU1_DIMM2_FRU_0")
	)
	(via
		(at 59.842146 -320.566796)
		(size 0.4572)
		(drill 0.2032)
		(layers "F.Cu" "B.Cu")
		(net "TP_CHA_CPU1_DIMM2_FRU_0")
	)
	(segment
		(start 59.150758 -319.875408)
		(end 59.13628 -319.875408)
		(width 0.12954)
		(layer "B.Cu")
		(net "TP_CHA_CPU1_DIMM2_FRU_0")
	)
	(segment
		(start 59.842146 -320.566796)
		(end 59.150758 -319.875408)
		(width 0.12954)
		(layer "B.Cu")
		(net "TP_CHA_CPU1_DIMM2_FRU_0")
	)
	(segment
		(start 57.503314 -242.3668)
		(end 56.398414 -242.3668)
		(width 0.12954)
		(layer "F.Cu")
		(net "TP_CHA_CPU1_DIMM1_FRU_6")
	)
	(via
		(at 56.398414 -242.3668)
		(size 0.4572)
		(drill 0.2032)
		(layers "F.Cu" "B.Cu")
		(net "TP_CHA_CPU1_DIMM1_FRU_6")
	)
	(via
		(at 55.422038 -241.930174)
		(size 0.6604)
		(drill 0.3302)
		(layers "F.Cu" "B.Cu")
		(net "TP_CHA_CPU1_DIMM1_FRU_6")
	)
	(segment
		(start 56.398414 -242.3668)
		(end 55.858664 -242.3668)
		(width 0.12954)
		(layer "B.Cu")
		(net "TP_CHA_CPU1_DIMM1_FRU_6")
	)
	(segment
		(start 55.858664 -242.3668)
		(end 55.422038 -241.930174)
		(width 0.12954)
		(layer "B.Cu")
		(net "TP_CHA_CPU1_DIMM1_FRU_6")
	)
	(segment
		(start 57.503314 -243.216684)
		(end 56.398414 -243.216684)
		(width 0.12954)
		(layer "F.Cu")
		(net "TP_CHA_CPU1_DIMM1_FRU_5")
	)
	(via
		(at 55.422038 -243.670074)
		(size 0.6604)
		(drill 0.3302)
		(layers "F.Cu" "B.Cu")
		(net "TP_CHA_CPU1_DIMM1_FRU_5")
	)
	(via
		(at 56.398414 -243.216684)
		(size 0.4572)
		(drill 0.2032)
		(layers "F.Cu" "B.Cu")
		(net "TP_CHA_CPU1_DIMM1_FRU_5")
	)
	(segment
		(start 55.422038 -243.670074)
		(end 55.875428 -243.216684)
		(width 0.12954)
		(layer "B.Cu")
		(net "TP_CHA_CPU1_DIMM1_FRU_5")
	)
	(segment
		(start 55.875428 -243.216684)
		(end 56.398414 -243.216684)
		(width 0.12954)
		(layer "B.Cu")
		(net "TP_CHA_CPU1_DIMM1_FRU_5")
	)
	(segment
		(start 56.398414 -252.566678)
		(end 57.503314 -252.566678)
		(width 0.12954)
		(layer "F.Cu")
		(net "TP_CHA_CPU1_DIMM1_FRU_4")
	)
	(via
		(at 57.164478 -251.25807)
		(size 0.6604)
		(drill 0.3302)
		(layers "F.Cu" "B.Cu")
		(net "TP_CHA_CPU1_DIMM1_FRU_4")
	)
	(via
		(at 56.398414 -252.566678)
		(size 0.4572)
		(drill 0.2032)
		(layers "F.Cu" "B.Cu")
		(net "TP_CHA_CPU1_DIMM1_FRU_4")
	)
	(segment
		(start 57.164478 -251.25807)
		(end 57.164478 -251.800614)
		(width 0.12954)
		(layer "B.Cu")
		(net "TP_CHA_CPU1_DIMM1_FRU_4")
	)
	(segment
		(start 57.164478 -251.800614)
		(end 56.398414 -252.566678)
		(width 0.12954)
		(layer "B.Cu")
		(net "TP_CHA_CPU1_DIMM1_FRU_4")
	)
	(segment
		(start 57.503314 -317.166752)
		(end 58.608214 -317.166752)
		(width 0.12954)
		(layer "F.Cu")
		(net "TP_CHA_CPU1_DIMM1_FRU_3")
	)
	(via
		(at 58.441336 -317.892684)
		(size 0.6604)
		(drill 0.3302)
		(layers "F.Cu" "B.Cu")
		(net "TP_CHA_CPU1_DIMM1_FRU_3")
	)
	(via
		(at 58.608214 -317.166752)
		(size 0.4572)
		(drill 0.2032)
		(layers "F.Cu" "B.Cu")
		(net "TP_CHA_CPU1_DIMM1_FRU_3")
	)
	(segment
		(start 58.608214 -317.725806)
		(end 58.608214 -317.166752)
		(width 0.12954)
		(layer "B.Cu")
		(net "TP_CHA_CPU1_DIMM1_FRU_3")
	)
	(segment
		(start 58.441336 -317.892684)
		(end 58.608214 -317.725806)
		(width 0.12954)
		(layer "B.Cu")
		(net "TP_CHA_CPU1_DIMM1_FRU_3")
	)
	(segment
		(start 56.398414 -318.016636)
		(end 57.503314 -318.016636)
		(width 0.12954)
		(layer "F.Cu")
		(net "TP_CHA_CPU1_DIMM1_FRU_2")
	)
	(via
		(at 56.398414 -318.016636)
		(size 0.4572)
		(drill 0.2032)
		(layers "F.Cu" "B.Cu")
		(net "TP_CHA_CPU1_DIMM1_FRU_2")
	)
	(via
		(at 57.24906 -318.016636)
		(size 0.6604)
		(drill 0.3302)
		(layers "F.Cu" "B.Cu")
		(net "TP_CHA_CPU1_DIMM1_FRU_2")
	)
	(segment
		(start 56.398414 -318.016636)
		(end 57.24906 -318.016636)
		(width 0.12954)
		(layer "B.Cu")
		(net "TP_CHA_CPU1_DIMM1_FRU_2")
	)
	(segment
		(start 53.403246 -194.766692)
		(end 52.272946 -194.766692)
		(width 0.12954)
		(layer "F.Cu")
		(net "TP_CHA_CPU1_DIMM1_FRU_1")
	)
	(via
		(at 52.272946 -194.766692)
		(size 0.4572)
		(drill 0.2032)
		(layers "F.Cu" "B.Cu")
		(net "TP_CHA_CPU1_DIMM1_FRU_1")
	)
	(via
		(at 53.031898 -195.08089)
		(size 0.6604)
		(drill 0.3302)
		(layers "F.Cu" "B.Cu")
		(net "TP_CHA_CPU1_DIMM1_FRU_1")
	)
	(segment
		(start 52.7177 -194.766692)
		(end 52.272946 -194.766692)
		(width 0.12954)
		(layer "B.Cu")
		(net "TP_CHA_CPU1_DIMM1_FRU_1")
	)
	(segment
		(start 53.031898 -195.08089)
		(end 52.7177 -194.766692)
		(width 0.12954)
		(layer "B.Cu")
		(net "TP_CHA_CPU1_DIMM1_FRU_1")
	)
	(segment
		(start 52.298346 -320.566796)
		(end 53.403246 -320.566796)
		(width 0.12954)
		(layer "F.Cu")
		(net "TP_CHA_CPU1_DIMM1_FRU_0")
	)
	(via
		(at 51.57216 -320.566796)
		(size 0.6604)
		(drill 0.3302)
		(layers "F.Cu" "B.Cu")
		(net "TP_CHA_CPU1_DIMM1_FRU_0")
	)
	(via
		(at 52.298346 -320.566796)
		(size 0.4572)
		(drill 0.2032)
		(layers "F.Cu" "B.Cu")
		(net "TP_CHA_CPU1_DIMM1_FRU_0")
	)
	(segment
		(start 52.298346 -320.566796)
		(end 51.57216 -320.566796)
		(width 0.12954)
		(layer "B.Cu")
		(net "TP_CHA_CPU1_DIMM1_FRU_0")
	)
	(segment
		(start 312.987182 -242.3668)
		(end 311.882282 -242.3668)
		(width 0.12954)
		(layer "F.Cu")
		(net "TP_CHA_CPU0_DIMM2_FRU_6")
	)
	(via
		(at 311.882282 -242.3668)
		(size 0.4572)
		(drill 0.2032)
		(layers "F.Cu" "B.Cu")
		(net "TP_CHA_CPU0_DIMM2_FRU_6")
	)
	(via
		(at 312.757058 -242.61699)
		(size 0.6604)
		(drill 0.3302)
		(layers "F.Cu" "B.Cu")
		(net "TP_CHA_CPU0_DIMM2_FRU_6")
	)
	(segment
		(start 312.757058 -242.61699)
		(end 312.132472 -242.61699)
		(width 0.12954)
		(layer "B.Cu")
		(net "TP_CHA_CPU0_DIMM2_FRU_6")
	)
	(segment
		(start 312.132472 -242.61699)
		(end 311.882282 -242.3668)
		(width 0.12954)
		(layer "B.Cu")
		(net "TP_CHA_CPU0_DIMM2_FRU_6")
	)
	(segment
		(start 312.987182 -243.216684)
		(end 311.882282 -243.216684)
		(width 0.12954)
		(layer "F.Cu")
		(net "TP_CHA_CPU0_DIMM2_FRU_5")
	)
	(via
		(at 311.882282 -243.216684)
		(size 0.4572)
		(drill 0.2032)
		(layers "F.Cu" "B.Cu")
		(net "TP_CHA_CPU0_DIMM2_FRU_5")
	)
	(via
		(at 311.007506 -242.966494)
		(size 0.6604)
		(drill 0.3302)
		(layers "F.Cu" "B.Cu")
		(net "TP_CHA_CPU0_DIMM2_FRU_5")
	)
	(segment
		(start 311.632092 -242.966494)
		(end 311.882282 -243.216684)
		(width 0.12954)
		(layer "B.Cu")
		(net "TP_CHA_CPU0_DIMM2_FRU_5")
	)
	(segment
		(start 311.007506 -242.966494)
		(end 311.632092 -242.966494)
		(width 0.12954)
		(layer "B.Cu")
		(net "TP_CHA_CPU0_DIMM2_FRU_5")
	)
	(segment
		(start 312.987182 -252.566678)
		(end 311.882282 -252.566678)
		(width 0.12954)
		(layer "F.Cu")
		(net "TP_CHA_CPU0_DIMM2_FRU_4")
	)
	(via
		(at 311.882282 -252.566678)
		(size 0.4572)
		(drill 0.2032)
		(layers "F.Cu" "B.Cu")
		(net "TP_CHA_CPU0_DIMM2_FRU_4")
	)
	(via
		(at 310.903874 -251.02693)
		(size 0.6604)
		(drill 0.3302)
		(layers "F.Cu" "B.Cu")
		(net "TP_CHA_CPU0_DIMM2_FRU_4")
	)
	(segment
		(start 311.882282 -252.005338)
		(end 310.903874 -251.02693)
		(width 0.12954)
		(layer "B.Cu")
		(net "TP_CHA_CPU0_DIMM2_FRU_4")
	)
	(segment
		(start 311.882282 -252.566678)
		(end 311.882282 -252.005338)
		(width 0.12954)
		(layer "B.Cu")
		(net "TP_CHA_CPU0_DIMM2_FRU_4")
	)
	(segment
		(start 314.092082 -317.166752)
		(end 312.987182 -317.166752)
		(width 0.12954)
		(layer "F.Cu")
		(net "TP_CHA_CPU0_DIMM2_FRU_3")
	)
	(via
		(at 314.092082 -317.166752)
		(size 0.4572)
		(drill 0.2032)
		(layers "F.Cu" "B.Cu")
		(net "TP_CHA_CPU0_DIMM2_FRU_3")
	)
	(via
		(at 314.81649 -317.166752)
		(size 0.6604)
		(drill 0.3302)
		(layers "F.Cu" "B.Cu")
		(net "TP_CHA_CPU0_DIMM2_FRU_3")
	)
	(segment
		(start 314.092082 -317.166752)
		(end 314.81649 -317.166752)
		(width 0.12954)
		(layer "B.Cu")
		(net "TP_CHA_CPU0_DIMM2_FRU_3")
	)
	(segment
		(start 312.906156 -317.93561)
		(end 312.987182 -318.016636)
		(width 0.12954)
		(layer "F.Cu")
		(net "TP_CHA_CPU0_DIMM2_FRU_2")
	)
	(segment
		(start 311.873138 -317.93561)
		(end 312.906156 -317.93561)
		(width 0.12954)
		(layer "F.Cu")
		(net "TP_CHA_CPU0_DIMM2_FRU_2")
	)
	(via
		(at 311.873138 -317.93561)
		(size 0.4572)
		(drill 0.2032)
		(layers "F.Cu" "B.Cu")
		(net "TP_CHA_CPU0_DIMM2_FRU_2")
	)
	(via
		(at 310.897778 -317.93561)
		(size 0.6604)
		(drill 0.3302)
		(layers "F.Cu" "B.Cu")
		(net "TP_CHA_CPU0_DIMM2_FRU_2")
	)
	(segment
		(start 311.873138 -317.93561)
		(end 310.897778 -317.93561)
		(width 0.12954)
		(layer "B.Cu")
		(net "TP_CHA_CPU0_DIMM2_FRU_2")
	)
	(segment
		(start 308.887114 -194.766692)
		(end 307.756814 -194.766692)
		(width 0.12954)
		(layer "F.Cu")
		(net "TP_CHA_CPU0_DIMM2_FRU_1")
	)
	(via
		(at 307.756814 -194.766692)
		(size 0.4572)
		(drill 0.2032)
		(layers "F.Cu" "B.Cu")
		(net "TP_CHA_CPU0_DIMM2_FRU_1")
	)
	(via
		(at 307.951378 -196.50075)
		(size 0.6604)
		(drill 0.3302)
		(layers "F.Cu" "B.Cu")
		(net "TP_CHA_CPU0_DIMM2_FRU_1")
	)
	(segment
		(start 308.271418 -195.281296)
		(end 307.756814 -194.766692)
		(width 0.12954)
		(layer "B.Cu")
		(net "TP_CHA_CPU0_DIMM2_FRU_1")
	)
	(segment
		(start 307.951378 -196.50075)
		(end 308.271418 -196.18071)
		(width 0.12954)
		(layer "B.Cu")
		(net "TP_CHA_CPU0_DIMM2_FRU_1")
	)
	(segment
		(start 308.271418 -196.18071)
		(end 308.271418 -195.281296)
		(width 0.12954)
		(layer "B.Cu")
		(net "TP_CHA_CPU0_DIMM2_FRU_1")
	)
	(segment
		(start 307.0225 -321.702684)
		(end 307.0225 -321.236848)
		(width 0.12954)
		(layer "F.Cu")
		(net "TP_CHA_CPU0_DIMM2_FRU_0")
	)
	(segment
		(start 307.0225 -321.236848)
		(end 307.527452 -320.731896)
		(width 0.12954)
		(layer "F.Cu")
		(net "TP_CHA_CPU0_DIMM2_FRU_0")
	)
	(segment
		(start 307.527452 -320.731896)
		(end 308.722014 -320.731896)
		(width 0.12954)
		(layer "F.Cu")
		(net "TP_CHA_CPU0_DIMM2_FRU_0")
	)
	(segment
		(start 308.722014 -320.731896)
		(end 308.887114 -320.566796)
		(width 0.12954)
		(layer "F.Cu")
		(net "TP_CHA_CPU0_DIMM2_FRU_0")
	)
	(via
		(at 307.0225 -321.702684)
		(size 0.4572)
		(drill 0.2032)
		(layers "F.Cu" "B.Cu")
		(net "TP_CHA_CPU0_DIMM2_FRU_0")
	)
	(segment
		(start 305.443382 -242.3668)
		(end 304.338482 -242.3668)
		(width 0.12954)
		(layer "F.Cu")
		(net "TP_CHA_CPU0_DIMM1_FRU_6")
	)
	(via
		(at 305.213258 -242.61699)
		(size 0.6604)
		(drill 0.3302)
		(layers "F.Cu" "B.Cu")
		(net "TP_CHA_CPU0_DIMM1_FRU_6")
	)
	(via
		(at 304.338482 -242.3668)
		(size 0.4572)
		(drill 0.2032)
		(layers "F.Cu" "B.Cu")
		(net "TP_CHA_CPU0_DIMM1_FRU_6")
	)
	(segment
		(start 305.213258 -242.61699)
		(end 304.588672 -242.61699)
		(width 0.12954)
		(layer "B.Cu")
		(net "TP_CHA_CPU0_DIMM1_FRU_6")
	)
	(segment
		(start 304.588672 -242.61699)
		(end 304.338482 -242.3668)
		(width 0.12954)
		(layer "B.Cu")
		(net "TP_CHA_CPU0_DIMM1_FRU_6")
	)
	(segment
		(start 305.443382 -243.216684)
		(end 304.338482 -243.216684)
		(width 0.12954)
		(layer "F.Cu")
		(net "TP_CHA_CPU0_DIMM1_FRU_5")
	)
	(via
		(at 304.338482 -243.216684)
		(size 0.4572)
		(drill 0.2032)
		(layers "F.Cu" "B.Cu")
		(net "TP_CHA_CPU0_DIMM1_FRU_5")
	)
	(via
		(at 305.43373 -244.311932)
		(size 0.6604)
		(drill 0.3302)
		(layers "F.Cu" "B.Cu")
		(net "TP_CHA_CPU0_DIMM1_FRU_5")
	)
	(segment
		(start 304.338482 -243.216684)
		(end 305.43373 -244.311932)
		(width 0.12954)
		(layer "B.Cu")
		(net "TP_CHA_CPU0_DIMM1_FRU_5")
	)
	(segment
		(start 304.338482 -252.566678)
		(end 305.443382 -252.566678)
		(width 0.12954)
		(layer "F.Cu")
		(net "TP_CHA_CPU0_DIMM1_FRU_4")
	)
	(via
		(at 305.156362 -251.227082)
		(size 0.6604)
		(drill 0.3302)
		(layers "F.Cu" "B.Cu")
		(net "TP_CHA_CPU0_DIMM1_FRU_4")
	)
	(via
		(at 304.338482 -252.566678)
		(size 0.4572)
		(drill 0.2032)
		(layers "F.Cu" "B.Cu")
		(net "TP_CHA_CPU0_DIMM1_FRU_4")
	)
	(segment
		(start 305.156362 -251.227082)
		(end 305.156362 -251.748798)
		(width 0.12954)
		(layer "B.Cu")
		(net "TP_CHA_CPU0_DIMM1_FRU_4")
	)
	(segment
		(start 305.156362 -251.748798)
		(end 304.338482 -252.566678)
		(width 0.12954)
		(layer "B.Cu")
		(net "TP_CHA_CPU0_DIMM1_FRU_4")
	)
	(segment
		(start 306.548282 -317.166752)
		(end 305.443382 -317.166752)
		(width 0.12954)
		(layer "F.Cu")
		(net "TP_CHA_CPU0_DIMM1_FRU_3")
	)
	(via
		(at 306.548282 -317.166752)
		(size 0.4572)
		(drill 0.2032)
		(layers "F.Cu" "B.Cu")
		(net "TP_CHA_CPU0_DIMM1_FRU_3")
	)
	(via
		(at 305.856894 -316.127892)
		(size 0.6604)
		(drill 0.3302)
		(layers "F.Cu" "B.Cu")
		(net "TP_CHA_CPU0_DIMM1_FRU_3")
	)
	(segment
		(start 306.40274 -317.166752)
		(end 306.548282 -317.166752)
		(width 0.12954)
		(layer "B.Cu")
		(net "TP_CHA_CPU0_DIMM1_FRU_3")
	)
	(segment
		(start 305.856894 -316.620906)
		(end 306.40274 -317.166752)
		(width 0.12954)
		(layer "B.Cu")
		(net "TP_CHA_CPU0_DIMM1_FRU_3")
	)
	(segment
		(start 305.856894 -316.127892)
		(end 305.856894 -316.620906)
		(width 0.12954)
		(layer "B.Cu")
		(net "TP_CHA_CPU0_DIMM1_FRU_3")
	)
	(segment
		(start 304.338482 -318.016636)
		(end 305.443382 -318.016636)
		(width 0.12954)
		(layer "F.Cu")
		(net "TP_CHA_CPU0_DIMM1_FRU_2")
	)
	(via
		(at 303.554638 -317.90005)
		(size 0.6604)
		(drill 0.3302)
		(layers "F.Cu" "B.Cu")
		(net "TP_CHA_CPU0_DIMM1_FRU_2")
	)
	(via
		(at 304.338482 -318.016636)
		(size 0.4572)
		(drill 0.2032)
		(layers "F.Cu" "B.Cu")
		(net "TP_CHA_CPU0_DIMM1_FRU_2")
	)
	(segment
		(start 303.874678 -318.22009)
		(end 303.554638 -317.90005)
		(width 0.12954)
		(layer "B.Cu")
		(net "TP_CHA_CPU0_DIMM1_FRU_2")
	)
	(segment
		(start 304.338482 -318.016636)
		(end 304.135028 -318.22009)
		(width 0.12954)
		(layer "B.Cu")
		(net "TP_CHA_CPU0_DIMM1_FRU_2")
	)
	(segment
		(start 304.135028 -318.22009)
		(end 303.874678 -318.22009)
		(width 0.12954)
		(layer "B.Cu")
		(net "TP_CHA_CPU0_DIMM1_FRU_2")
	)
	(segment
		(start 301.343314 -194.766692)
		(end 300.213014 -194.766692)
		(width 0.12954)
		(layer "F.Cu")
		(net "TP_CHA_CPU0_DIMM1_FRU_1")
	)
	(via
		(at 300.213014 -194.766692)
		(size 0.4572)
		(drill 0.2032)
		(layers "F.Cu" "B.Cu")
		(net "TP_CHA_CPU0_DIMM1_FRU_1")
	)
	(segment
		(start 299.51172 -321.046348)
		(end 299.991272 -320.566796)
		(width 0.12954)
		(layer "F.Cu")
		(net "TP_CHA_CPU0_DIMM1_FRU_0")
	)
	(segment
		(start 299.991272 -320.566796)
		(end 301.343314 -320.566796)
		(width 0.12954)
		(layer "F.Cu")
		(net "TP_CHA_CPU0_DIMM1_FRU_0")
	)
	(segment
		(start 299.51172 -321.531488)
		(end 299.51172 -321.046348)
		(width 0.12954)
		(layer "F.Cu")
		(net "TP_CHA_CPU0_DIMM1_FRU_0")
	)
	(via
		(at 299.51172 -321.531488)
		(size 0.4572)
		(drill 0.2032)
		(layers "F.Cu" "B.Cu")
		(net "TP_CHA_CPU0_DIMM1_FRU_0")
	)
	(segment
		(start 372.461282 -55.907432)
		(end 371.78488 -56.583834)
		(width 0.12954)
		(layer "F.Cu")
		(net "TP_74CB_B8")
	)
	(segment
		(start 371.78488 -56.583834)
		(end 370.683282 -56.583834)
		(width 0.12954)
		(layer "F.Cu")
		(net "TP_74CB_B8")
	)
	(via
		(at 372.461282 -55.907432)
		(size 0.762)
		(drill 0.381)
		(layers "F.Cu" "B.Cu")
		(net "TP_74CB_B8")
	)
	(segment
		(start 482.011228 -421.400478)
		(end 482.266244 -421.655494)
		(width 0.12954)
		(layer "F.Cu")
		(net "TDR_SE_50_OHM_TOP")
	)
	(segment
		(start 484.311452 -421.655494)
		(end 484.551228 -421.415718)
		(width 0.12954)
		(layer "F.Cu")
		(net "TDR_SE_50_OHM_TOP")
	)
	(segment
		(start 482.266244 -421.655494)
		(end 484.311452 -421.655494)
		(width 0.12954)
		(layer "F.Cu")
		(net "TDR_SE_50_OHM_TOP")
	)
	(segment
		(start 484.551228 -421.415718)
		(end 484.551228 -346.577666)
		(width 0.12954)
		(layer "F.Cu")
		(net "TDR_SE_50_OHM_TOP")
	)
	(segment
		(start 482.011228 -346.577666)
		(end 482.011228 -421.400478)
		(width 0.12954)
		(layer "F.Cu")
		(net "TDR_SE_50_OHM_TOP")
	)
	(segment
		(start 479.097594 -421.335962)
		(end 479.097594 -346.498418)
		(width 0.127)
		(layer "In11.Cu")
		(net "TDR_SE_50_OHM_IN4")
	)
	(segment
		(start 476.823278 -421.581326)
		(end 478.85223 -421.581326)
		(width 0.127)
		(layer "In11.Cu")
		(net "TDR_SE_50_OHM_IN4")
	)
	(segment
		(start 476.557594 -346.498418)
		(end 476.557594 -421.315642)
		(width 0.127)
		(layer "In11.Cu")
		(net "TDR_SE_50_OHM_IN4")
	)
	(segment
		(start 476.557594 -421.315642)
		(end 476.823278 -421.581326)
		(width 0.127)
		(layer "In11.Cu")
		(net "TDR_SE_50_OHM_IN4")
	)
	(segment
		(start 478.85223 -421.581326)
		(end 479.097594 -421.335962)
		(width 0.127)
		(layer "In11.Cu")
		(net "TDR_SE_50_OHM_IN4")
	)
	(segment
		(start 482.258116 -329.465432)
		(end 481.992432 -329.199748)
		(width 0.127)
		(layer "In6.Cu")
		(net "TDR_SE_50_OHM_IN3")
	)
	(segment
		(start 484.532432 -254.382524)
		(end 484.532432 -329.220068)
		(width 0.127)
		(layer "In6.Cu")
		(net "TDR_SE_50_OHM_IN3")
	)
	(segment
		(start 484.287068 -329.465432)
		(end 482.258116 -329.465432)
		(width 0.127)
		(layer "In6.Cu")
		(net "TDR_SE_50_OHM_IN3")
	)
	(segment
		(start 484.532432 -329.220068)
		(end 484.287068 -329.465432)
		(width 0.127)
		(layer "In6.Cu")
		(net "TDR_SE_50_OHM_IN3")
	)
	(segment
		(start 481.992432 -329.199748)
		(end 481.992432 -254.382524)
		(width 0.127)
		(layer "In6.Cu")
		(net "TDR_SE_50_OHM_IN3")
	)
	(segment
		(start 482.113844 -256.643632)
		(end 482.113844 -331.481176)
		(width 0.127)
		(layer "In4.Cu")
		(net "TDR_SE_50_OHM_IN2")
	)
	(segment
		(start 484.653844 -256.663952)
		(end 484.38816 -256.398268)
		(width 0.127)
		(layer "In4.Cu")
		(net "TDR_SE_50_OHM_IN2")
	)
	(segment
		(start 484.653844 -331.481176)
		(end 484.653844 -256.663952)
		(width 0.127)
		(layer "In4.Cu")
		(net "TDR_SE_50_OHM_IN2")
	)
	(segment
		(start 484.38816 -256.398268)
		(end 482.359208 -256.398268)
		(width 0.127)
		(layer "In4.Cu")
		(net "TDR_SE_50_OHM_IN2")
	)
	(segment
		(start 482.359208 -256.398268)
		(end 482.113844 -256.643632)
		(width 0.127)
		(layer "In4.Cu")
		(net "TDR_SE_50_OHM_IN2")
	)
	(segment
		(start 484.480108 -349.381064)
		(end 484.214424 -349.11538)
		(width 0.127)
		(layer "In2.Cu")
		(net "TDR_SE_50_OHM_IN1")
	)
	(segment
		(start 484.480108 -424.198288)
		(end 484.480108 -349.381064)
		(width 0.127)
		(layer "In2.Cu")
		(net "TDR_SE_50_OHM_IN1")
	)
	(segment
		(start 484.214424 -349.11538)
		(end 482.185472 -349.11538)
		(width 0.127)
		(layer "In2.Cu")
		(net "TDR_SE_50_OHM_IN1")
	)
	(segment
		(start 482.185472 -349.11538)
		(end 481.940108 -349.360744)
		(width 0.127)
		(layer "In2.Cu")
		(net "TDR_SE_50_OHM_IN1")
	)
	(segment
		(start 481.940108 -349.360744)
		(end 481.940108 -424.198288)
		(width 0.127)
		(layer "In2.Cu")
		(net "TDR_SE_50_OHM_IN1")
	)
	(segment
		(start 479.22688 -329.209654)
		(end 479.22688 -254.371602)
		(width 0.12954)
		(layer "B.Cu")
		(net "TDR_SE_50_OHM_BOT")
	)
	(segment
		(start 476.68688 -254.371602)
		(end 476.68688 -329.194414)
		(width 0.12954)
		(layer "B.Cu")
		(net "TDR_SE_50_OHM_BOT")
	)
	(segment
		(start 476.940372 -329.447906)
		(end 478.988628 -329.447906)
		(width 0.12954)
		(layer "B.Cu")
		(net "TDR_SE_50_OHM_BOT")
	)
	(segment
		(start 476.68688 -329.194414)
		(end 476.940372 -329.447906)
		(width 0.12954)
		(layer "B.Cu")
		(net "TDR_SE_50_OHM_BOT")
	)
	(segment
		(start 478.988628 -329.447906)
		(end 479.22688 -329.209654)
		(width 0.12954)
		(layer "B.Cu")
		(net "TDR_SE_50_OHM_BOT")
	)
	(segment
		(start 496.869212 -420.984426)
		(end 496.869212 -346.146374)
		(width 0.20066)
		(layer "F.Cu")
		(net "TDR_SE_40_OHM_TOP")
	)
	(segment
		(start 494.584228 -421.224202)
		(end 496.629436 -421.224202)
		(width 0.20066)
		(layer "F.Cu")
		(net "TDR_SE_40_OHM_TOP")
	)
	(segment
		(start 494.329212 -420.969186)
		(end 494.584228 -421.224202)
		(width 0.20066)
		(layer "F.Cu")
		(net "TDR_SE_40_OHM_TOP")
	)
	(segment
		(start 496.629436 -421.224202)
		(end 496.869212 -420.984426)
		(width 0.20066)
		(layer "F.Cu")
		(net "TDR_SE_40_OHM_TOP")
	)
	(segment
		(start 494.329212 -346.146374)
		(end 494.329212 -420.969186)
		(width 0.20066)
		(layer "F.Cu")
		(net "TDR_SE_40_OHM_TOP")
	)
	(segment
		(start 502.335038 -420.986204)
		(end 502.335038 -346.14866)
		(width 0.18288)
		(layer "In11.Cu")
		(net "TDR_SE_40_OHM_IN4")
	)
	(segment
		(start 499.795038 -346.14866)
		(end 499.795038 -420.965884)
		(width 0.18288)
		(layer "In11.Cu")
		(net "TDR_SE_40_OHM_IN4")
	)
	(segment
		(start 502.037858 -421.283384)
		(end 502.335038 -420.986204)
		(width 0.18288)
		(layer "In11.Cu")
		(net "TDR_SE_40_OHM_IN4")
	)
	(segment
		(start 500.112538 -421.283384)
		(end 502.037858 -421.283384)
		(width 0.18288)
		(layer "In11.Cu")
		(net "TDR_SE_40_OHM_IN4")
	)
	(segment
		(start 499.795038 -420.965884)
		(end 500.112538 -421.283384)
		(width 0.18288)
		(layer "In11.Cu")
		(net "TDR_SE_40_OHM_IN4")
	)
	(segment
		(start 496.375436 -349.124778)
		(end 496.692936 -349.442278)
		(width 0.18288)
		(layer "In6.Cu")
		(net "TDR_SE_40_OHM_IN3")
	)
	(segment
		(start 494.152936 -424.259502)
		(end 494.152936 -349.421958)
		(width 0.18288)
		(layer "In6.Cu")
		(net "TDR_SE_40_OHM_IN3")
	)
	(segment
		(start 494.450116 -349.124778)
		(end 496.375436 -349.124778)
		(width 0.18288)
		(layer "In6.Cu")
		(net "TDR_SE_40_OHM_IN3")
	)
	(segment
		(start 496.692936 -349.442278)
		(end 496.692936 -424.259502)
		(width 0.18288)
		(layer "In6.Cu")
		(net "TDR_SE_40_OHM_IN3")
	)
	(segment
		(start 494.152936 -349.421958)
		(end 494.450116 -349.124778)
		(width 0.18288)
		(layer "In6.Cu")
		(net "TDR_SE_40_OHM_IN3")
	)
	(segment
		(start 504.989338 -424.101514)
		(end 504.989338 -349.26397)
		(width 0.18288)
		(layer "In4.Cu")
		(net "TDR_SE_40_OHM_IN2")
	)
	(segment
		(start 504.989338 -349.26397)
		(end 505.286518 -348.96679)
		(width 0.18288)
		(layer "In4.Cu")
		(net "TDR_SE_40_OHM_IN2")
	)
	(segment
		(start 505.286518 -348.96679)
		(end 507.211838 -348.96679)
		(width 0.18288)
		(layer "In4.Cu")
		(net "TDR_SE_40_OHM_IN2")
	)
	(segment
		(start 507.211838 -348.96679)
		(end 507.529338 -349.28429)
		(width 0.18288)
		(layer "In4.Cu")
		(net "TDR_SE_40_OHM_IN2")
	)
	(segment
		(start 507.529338 -349.28429)
		(end 507.529338 -424.101514)
		(width 0.18288)
		(layer "In4.Cu")
		(net "TDR_SE_40_OHM_IN2")
	)
	(segment
		(start 505.108972 -421.039798)
		(end 505.108972 -346.222574)
		(width 0.18288)
		(layer "In2.Cu")
		(net "TDR_SE_40_OHM_IN1")
	)
	(segment
		(start 507.648972 -421.060118)
		(end 507.351792 -421.357298)
		(width 0.18288)
		(layer "In2.Cu")
		(net "TDR_SE_40_OHM_IN1")
	)
	(segment
		(start 505.426472 -421.357298)
		(end 505.108972 -421.039798)
		(width 0.18288)
		(layer "In2.Cu")
		(net "TDR_SE_40_OHM_IN1")
	)
	(segment
		(start 507.648972 -346.222574)
		(end 507.648972 -421.060118)
		(width 0.18288)
		(layer "In2.Cu")
		(net "TDR_SE_40_OHM_IN1")
	)
	(segment
		(start 507.351792 -421.357298)
		(end 505.426472 -421.357298)
		(width 0.18288)
		(layer "In2.Cu")
		(net "TDR_SE_40_OHM_IN1")
	)
	(segment
		(start 491.41253 -349.366332)
		(end 491.41253 -424.189144)
		(width 0.20066)
		(layer "B.Cu")
		(net "TDR_SE_40_OHM_BOT")
	)
	(segment
		(start 488.87253 -349.351092)
		(end 489.121958 -349.101664)
		(width 0.20066)
		(layer "B.Cu")
		(net "TDR_SE_40_OHM_BOT")
	)
	(segment
		(start 488.87253 -424.189144)
		(end 488.87253 -349.351092)
		(width 0.20066)
		(layer "B.Cu")
		(net "TDR_SE_40_OHM_BOT")
	)
	(segment
		(start 489.121958 -349.101664)
		(end 491.147862 -349.101664)
		(width 0.20066)
		(layer "B.Cu")
		(net "TDR_SE_40_OHM_BOT")
	)
	(segment
		(start 491.147862 -349.101664)
		(end 491.41253 -349.366332)
		(width 0.20066)
		(layer "B.Cu")
		(net "TDR_SE_40_OHM_BOT")
	)
	(segment
		(start 526.548604 -303.45253)
		(end 526.376646 -303.624488)
		(width 0.13208)
		(layer "F.Cu")
		(net "TDR_DIFF_85_TOP_DP")
	)
	(segment
		(start 525.408906 -153.205688)
		(end 526.417286 -153.205688)
		(width 0.13208)
		(layer "F.Cu")
		(net "TDR_DIFF_85_TOP_DP")
	)
	(segment
		(start 526.376646 -303.624488)
		(end 525.408906 -303.624488)
		(width 0.13208)
		(layer "F.Cu")
		(net "TDR_DIFF_85_TOP_DP")
	)
	(segment
		(start 526.548604 -153.337006)
		(end 526.548604 -303.45253)
		(width 0.13208)
		(layer "F.Cu")
		(net "TDR_DIFF_85_TOP_DP")
	)
	(segment
		(start 526.417286 -153.205688)
		(end 526.548604 -153.337006)
		(width 0.13208)
		(layer "F.Cu")
		(net "TDR_DIFF_85_TOP_DP")
	)
	(segment
		(start 526.940526 -153.205688)
		(end 527.948906 -153.205688)
		(width 0.13208)
		(layer "F.Cu")
		(net "TDR_DIFF_85_TOP_DN")
	)
	(segment
		(start 527.948906 -303.624488)
		(end 526.977102 -303.624488)
		(width 0.13208)
		(layer "F.Cu")
		(net "TDR_DIFF_85_TOP_DN")
	)
	(segment
		(start 526.807684 -303.45507)
		(end 526.807684 -153.33853)
		(width 0.13208)
		(layer "F.Cu")
		(net "TDR_DIFF_85_TOP_DN")
	)
	(segment
		(start 526.807684 -153.33853)
		(end 526.940526 -153.205688)
		(width 0.13208)
		(layer "F.Cu")
		(net "TDR_DIFF_85_TOP_DN")
	)
	(segment
		(start 526.977102 -303.624488)
		(end 526.807684 -303.45507)
		(width 0.13208)
		(layer "F.Cu")
		(net "TDR_DIFF_85_TOP_DN")
	)
	(segment
		(start 521.177266 -303.474628)
		(end 521.177266 -153.350468)
		(width 0.14732)
		(layer "In11.Cu")
		(net "TDR_DIFF_85_IN4_DP")
	)
	(segment
		(start 521.177266 -153.350468)
		(end 521.029946 -153.203148)
		(width 0.14732)
		(layer "In11.Cu")
		(net "TDR_DIFF_85_IN4_DP")
	)
	(segment
		(start 521.029946 -153.203148)
		(end 520.044426 -153.203148)
		(width 0.14732)
		(layer "In11.Cu")
		(net "TDR_DIFF_85_IN4_DP")
	)
	(segment
		(start 520.044426 -303.621948)
		(end 521.029946 -303.621948)
		(width 0.14732)
		(layer "In11.Cu")
		(net "TDR_DIFF_85_IN4_DP")
	)
	(segment
		(start 521.029946 -303.621948)
		(end 521.177266 -303.474628)
		(width 0.14732)
		(layer "In11.Cu")
		(net "TDR_DIFF_85_IN4_DP")
	)
	(segment
		(start 521.451586 -303.474628)
		(end 521.451586 -153.350468)
		(width 0.14732)
		(layer "In11.Cu")
		(net "TDR_DIFF_85_IN4_DN")
	)
	(segment
		(start 521.598906 -303.621948)
		(end 521.451586 -303.474628)
		(width 0.14732)
		(layer "In11.Cu")
		(net "TDR_DIFF_85_IN4_DN")
	)
	(segment
		(start 522.584426 -303.621948)
		(end 521.598906 -303.621948)
		(width 0.14732)
		(layer "In11.Cu")
		(net "TDR_DIFF_85_IN4_DN")
	)
	(segment
		(start 521.451586 -153.350468)
		(end 521.598906 -153.203148)
		(width 0.14732)
		(layer "In11.Cu")
		(net "TDR_DIFF_85_IN4_DN")
	)
	(segment
		(start 521.598906 -153.203148)
		(end 522.584426 -153.203148)
		(width 0.14732)
		(layer "In11.Cu")
		(net "TDR_DIFF_85_IN4_DN")
	)
	(segment
		(start 494.92281 -153.174192)
		(end 495.90833 -153.174192)
		(width 0.14732)
		(layer "In6.Cu")
		(net "TDR_DIFF_85_IN3_DP")
	)
	(segment
		(start 494.77549 -303.445672)
		(end 494.77549 -153.321512)
		(width 0.14732)
		(layer "In6.Cu")
		(net "TDR_DIFF_85_IN3_DP")
	)
	(segment
		(start 494.77549 -153.321512)
		(end 494.92281 -153.174192)
		(width 0.14732)
		(layer "In6.Cu")
		(net "TDR_DIFF_85_IN3_DP")
	)
	(segment
		(start 494.92281 -303.592992)
		(end 494.77549 -303.445672)
		(width 0.14732)
		(layer "In6.Cu")
		(net "TDR_DIFF_85_IN3_DP")
	)
	(segment
		(start 495.90833 -303.592992)
		(end 494.92281 -303.592992)
		(width 0.14732)
		(layer "In6.Cu")
		(net "TDR_DIFF_85_IN3_DP")
	)
	(segment
		(start 494.35385 -153.174192)
		(end 493.36833 -153.174192)
		(width 0.14732)
		(layer "In6.Cu")
		(net "TDR_DIFF_85_IN3_DN")
	)
	(segment
		(start 494.50117 -303.445672)
		(end 494.50117 -153.321512)
		(width 0.14732)
		(layer "In6.Cu")
		(net "TDR_DIFF_85_IN3_DN")
	)
	(segment
		(start 493.36833 -303.592992)
		(end 494.35385 -303.592992)
		(width 0.14732)
		(layer "In6.Cu")
		(net "TDR_DIFF_85_IN3_DN")
	)
	(segment
		(start 494.35385 -303.592992)
		(end 494.50117 -303.445672)
		(width 0.14732)
		(layer "In6.Cu")
		(net "TDR_DIFF_85_IN3_DN")
	)
	(segment
		(start 494.50117 -153.321512)
		(end 494.35385 -153.174192)
		(width 0.14732)
		(layer "In6.Cu")
		(net "TDR_DIFF_85_IN3_DN")
	)
	(segment
		(start 505.043948 -303.58588)
		(end 505.191268 -303.43856)
		(width 0.14732)
		(layer "In4.Cu")
		(net "TDR_DIFF_85_IN2_DP")
	)
	(segment
		(start 505.043948 -153.16708)
		(end 504.058428 -153.16708)
		(width 0.14732)
		(layer "In4.Cu")
		(net "TDR_DIFF_85_IN2_DP")
	)
	(segment
		(start 505.191268 -303.43856)
		(end 505.191268 -153.3144)
		(width 0.14732)
		(layer "In4.Cu")
		(net "TDR_DIFF_85_IN2_DP")
	)
	(segment
		(start 504.058428 -303.58588)
		(end 505.043948 -303.58588)
		(width 0.14732)
		(layer "In4.Cu")
		(net "TDR_DIFF_85_IN2_DP")
	)
	(segment
		(start 505.191268 -153.3144)
		(end 505.043948 -153.16708)
		(width 0.14732)
		(layer "In4.Cu")
		(net "TDR_DIFF_85_IN2_DP")
	)
	(segment
		(start 505.465588 -303.43856)
		(end 505.612908 -303.58588)
		(width 0.14732)
		(layer "In4.Cu")
		(net "TDR_DIFF_85_IN2_DN")
	)
	(segment
		(start 505.465588 -153.3144)
		(end 505.465588 -303.43856)
		(width 0.14732)
		(layer "In4.Cu")
		(net "TDR_DIFF_85_IN2_DN")
	)
	(segment
		(start 505.612908 -153.16708)
		(end 505.465588 -153.3144)
		(width 0.14732)
		(layer "In4.Cu")
		(net "TDR_DIFF_85_IN2_DN")
	)
	(segment
		(start 505.612908 -303.58588)
		(end 506.598428 -303.58588)
		(width 0.14732)
		(layer "In4.Cu")
		(net "TDR_DIFF_85_IN2_DN")
	)
	(segment
		(start 506.598428 -153.16708)
		(end 505.612908 -153.16708)
		(width 0.14732)
		(layer "In4.Cu")
		(net "TDR_DIFF_85_IN2_DN")
	)
	(segment
		(start 516.125968 -153.36012)
		(end 516.125968 -303.48428)
		(width 0.14732)
		(layer "In2.Cu")
		(net "TDR_DIFF_85_IN1_DP")
	)
	(segment
		(start 517.258808 -153.2128)
		(end 516.273288 -153.2128)
		(width 0.14732)
		(layer "In2.Cu")
		(net "TDR_DIFF_85_IN1_DP")
	)
	(segment
		(start 516.273288 -303.6316)
		(end 517.258808 -303.6316)
		(width 0.14732)
		(layer "In2.Cu")
		(net "TDR_DIFF_85_IN1_DP")
	)
	(segment
		(start 516.125968 -303.48428)
		(end 516.273288 -303.6316)
		(width 0.14732)
		(layer "In2.Cu")
		(net "TDR_DIFF_85_IN1_DP")
	)
	(segment
		(start 516.273288 -153.2128)
		(end 516.125968 -153.36012)
		(width 0.14732)
		(layer "In2.Cu")
		(net "TDR_DIFF_85_IN1_DP")
	)
	(segment
		(start 515.704328 -153.2128)
		(end 515.851648 -153.36012)
		(width 0.14732)
		(layer "In2.Cu")
		(net "TDR_DIFF_85_IN1_DN")
	)
	(segment
		(start 515.851648 -303.48428)
		(end 515.704328 -303.6316)
		(width 0.14732)
		(layer "In2.Cu")
		(net "TDR_DIFF_85_IN1_DN")
	)
	(segment
		(start 514.718808 -153.2128)
		(end 515.704328 -153.2128)
		(width 0.14732)
		(layer "In2.Cu")
		(net "TDR_DIFF_85_IN1_DN")
	)
	(segment
		(start 515.851648 -153.36012)
		(end 515.851648 -303.48428)
		(width 0.14732)
		(layer "In2.Cu")
		(net "TDR_DIFF_85_IN1_DN")
	)
	(segment
		(start 515.704328 -303.6316)
		(end 514.718808 -303.6316)
		(width 0.14732)
		(layer "In2.Cu")
		(net "TDR_DIFF_85_IN1_DN")
	)
	(segment
		(start 489.174028 -153.25979)
		(end 489.04271 -153.128472)
		(width 0.13208)
		(layer "B.Cu")
		(net "TDR_DIFF_85_BOT_DP")
	)
	(segment
		(start 488.03433 -303.547272)
		(end 489.00207 -303.547272)
		(width 0.13208)
		(layer "B.Cu")
		(net "TDR_DIFF_85_BOT_DP")
	)
	(segment
		(start 489.174028 -303.375314)
		(end 489.174028 -153.25979)
		(width 0.13208)
		(layer "B.Cu")
		(net "TDR_DIFF_85_BOT_DP")
	)
	(segment
		(start 489.04271 -153.128472)
		(end 488.03433 -153.128472)
		(width 0.13208)
		(layer "B.Cu")
		(net "TDR_DIFF_85_BOT_DP")
	)
	(segment
		(start 489.00207 -303.547272)
		(end 489.174028 -303.375314)
		(width 0.13208)
		(layer "B.Cu")
		(net "TDR_DIFF_85_BOT_DP")
	)
	(segment
		(start 489.433108 -153.261314)
		(end 489.433108 -303.377854)
		(width 0.13208)
		(layer "B.Cu")
		(net "TDR_DIFF_85_BOT_DN")
	)
	(segment
		(start 489.602526 -303.547272)
		(end 490.57433 -303.547272)
		(width 0.13208)
		(layer "B.Cu")
		(net "TDR_DIFF_85_BOT_DN")
	)
	(segment
		(start 489.433108 -303.377854)
		(end 489.602526 -303.547272)
		(width 0.13208)
		(layer "B.Cu")
		(net "TDR_DIFF_85_BOT_DN")
	)
	(segment
		(start 489.56595 -153.128472)
		(end 489.433108 -153.261314)
		(width 0.13208)
		(layer "B.Cu")
		(net "TDR_DIFF_85_BOT_DN")
	)
	(segment
		(start 490.57433 -153.128472)
		(end 489.56595 -153.128472)
		(width 0.13208)
		(layer "B.Cu")
		(net "TDR_DIFF_85_BOT_DN")
	)
	(segment
		(start 522.584426 -148.123148)
		(end 521.602716 -148.123148)
		(width 0.11176)
		(layer "F.Cu")
		(net "TDR_DIFF_100_TOP_DP")
	)
	(segment
		(start 521.490956 2.183892)
		(end 521.602716 2.295652)
		(width 0.11176)
		(layer "F.Cu")
		(net "TDR_DIFF_100_TOP_DP")
	)
	(segment
		(start 521.602716 -148.123148)
		(end 521.490956 -148.011388)
		(width 0.11176)
		(layer "F.Cu")
		(net "TDR_DIFF_100_TOP_DP")
	)
	(segment
		(start 521.490956 -148.011388)
		(end 521.490956 2.183892)
		(width 0.11176)
		(layer "F.Cu")
		(net "TDR_DIFF_100_TOP_DP")
	)
	(segment
		(start 521.602716 2.295652)
		(end 522.584426 2.295652)
		(width 0.11176)
		(layer "F.Cu")
		(net "TDR_DIFF_100_TOP_DP")
	)
	(segment
		(start 521.026136 -148.123148)
		(end 521.137896 -148.011388)
		(width 0.11176)
		(layer "F.Cu")
		(net "TDR_DIFF_100_TOP_DN")
	)
	(segment
		(start 521.137896 2.183892)
		(end 521.026136 2.295652)
		(width 0.11176)
		(layer "F.Cu")
		(net "TDR_DIFF_100_TOP_DN")
	)
	(segment
		(start 520.044426 -148.123148)
		(end 521.026136 -148.123148)
		(width 0.11176)
		(layer "F.Cu")
		(net "TDR_DIFF_100_TOP_DN")
	)
	(segment
		(start 521.026136 2.295652)
		(end 520.044426 2.295652)
		(width 0.11176)
		(layer "F.Cu")
		(net "TDR_DIFF_100_TOP_DN")
	)
	(segment
		(start 521.137896 -148.011388)
		(end 521.137896 2.183892)
		(width 0.11176)
		(layer "F.Cu")
		(net "TDR_DIFF_100_TOP_DN")
	)
	(segment
		(start 515.683754 -148.1328)
		(end 515.776718 -148.039836)
		(width 0.12446)
		(layer "In11.Cu")
		(net "TDR_DIFF_100_IN4_DP")
	)
	(segment
		(start 514.718808 -148.1328)
		(end 515.683754 -148.1328)
		(width 0.12446)
		(layer "In11.Cu")
		(net "TDR_DIFF_100_IN4_DP")
	)
	(segment
		(start 515.776718 -148.039836)
		(end 515.776718 2.16154)
		(width 0.12446)
		(layer "In11.Cu")
		(net "TDR_DIFF_100_IN4_DP")
	)
	(segment
		(start 515.776718 2.16154)
		(end 515.652258 2.286)
		(width 0.12446)
		(layer "In11.Cu")
		(net "TDR_DIFF_100_IN4_DP")
	)
	(segment
		(start 515.652258 2.286)
		(end 514.718808 2.286)
		(width 0.12446)
		(layer "In11.Cu")
		(net "TDR_DIFF_100_IN4_DP")
	)
	(segment
		(start 517.258808 -148.1328)
		(end 516.304022 -148.1328)
		(width 0.12446)
		(layer "In11.Cu")
		(net "TDR_DIFF_100_IN4_DN")
	)
	(segment
		(start 516.200898 -148.029676)
		(end 516.200898 2.16154)
		(width 0.12446)
		(layer "In11.Cu")
		(net "TDR_DIFF_100_IN4_DN")
	)
	(segment
		(start 516.304022 -148.1328)
		(end 516.200898 -148.029676)
		(width 0.12446)
		(layer "In11.Cu")
		(net "TDR_DIFF_100_IN4_DN")
	)
	(segment
		(start 516.200898 2.16154)
		(end 516.325358 2.286)
		(width 0.12446)
		(layer "In11.Cu")
		(net "TDR_DIFF_100_IN4_DN")
	)
	(segment
		(start 516.325358 2.286)
		(end 517.258808 2.286)
		(width 0.12446)
		(layer "In11.Cu")
		(net "TDR_DIFF_100_IN4_DN")
	)
	(segment
		(start 489.614464 -148.048472)
		(end 489.51642 -147.950428)
		(width 0.12446)
		(layer "In6.Cu")
		(net "TDR_DIFF_100_IN3_DP")
	)
	(segment
		(start 489.51642 -147.950428)
		(end 489.51642 2.245868)
		(width 0.12446)
		(layer "In6.Cu")
		(net "TDR_DIFF_100_IN3_DP")
	)
	(segment
		(start 489.51642 2.245868)
		(end 489.64088 2.370328)
		(width 0.12446)
		(layer "In6.Cu")
		(net "TDR_DIFF_100_IN3_DP")
	)
	(segment
		(start 489.64088 2.370328)
		(end 490.57433 2.370328)
		(width 0.12446)
		(layer "In6.Cu")
		(net "TDR_DIFF_100_IN3_DP")
	)
	(segment
		(start 490.57433 -148.048472)
		(end 489.614464 -148.048472)
		(width 0.12446)
		(layer "In6.Cu")
		(net "TDR_DIFF_100_IN3_DP")
	)
	(segment
		(start 489.09224 2.245868)
		(end 488.96778 2.370328)
		(width 0.12446)
		(layer "In6.Cu")
		(net "TDR_DIFF_100_IN3_DN")
	)
	(segment
		(start 489.09224 -147.94738)
		(end 489.09224 2.245868)
		(width 0.12446)
		(layer "In6.Cu")
		(net "TDR_DIFF_100_IN3_DN")
	)
	(segment
		(start 488.03433 -148.048472)
		(end 488.991148 -148.048472)
		(width 0.12446)
		(layer "In6.Cu")
		(net "TDR_DIFF_100_IN3_DN")
	)
	(segment
		(start 488.96778 2.370328)
		(end 488.03433 2.370328)
		(width 0.12446)
		(layer "In6.Cu")
		(net "TDR_DIFF_100_IN3_DN")
	)
	(segment
		(start 488.991148 -148.048472)
		(end 489.09224 -147.94738)
		(width 0.12446)
		(layer "In6.Cu")
		(net "TDR_DIFF_100_IN3_DN")
	)
	(segment
		(start 499.650766 -148.08454)
		(end 499.751858 -147.983448)
		(width 0.12446)
		(layer "In4.Cu")
		(net "TDR_DIFF_100_IN2_DP")
	)
	(segment
		(start 499.627398 2.33426)
		(end 498.693948 2.33426)
		(width 0.12446)
		(layer "In4.Cu")
		(net "TDR_DIFF_100_IN2_DP")
	)
	(segment
		(start 499.751858 2.2098)
		(end 499.627398 2.33426)
		(width 0.12446)
		(layer "In4.Cu")
		(net "TDR_DIFF_100_IN2_DP")
	)
	(segment
		(start 499.751858 -147.983448)
		(end 499.751858 2.2098)
		(width 0.12446)
		(layer "In4.Cu")
		(net "TDR_DIFF_100_IN2_DP")
	)
	(segment
		(start 498.693948 -148.08454)
		(end 499.650766 -148.08454)
		(width 0.12446)
		(layer "In4.Cu")
		(net "TDR_DIFF_100_IN2_DP")
	)
	(segment
		(start 500.274082 -148.08454)
		(end 500.176038 -147.986496)
		(width 0.12446)
		(layer "In4.Cu")
		(net "TDR_DIFF_100_IN2_DN")
	)
	(segment
		(start 500.176038 -147.986496)
		(end 500.176038 2.2098)
		(width 0.12446)
		(layer "In4.Cu")
		(net "TDR_DIFF_100_IN2_DN")
	)
	(segment
		(start 500.176038 2.2098)
		(end 500.300498 2.33426)
		(width 0.12446)
		(layer "In4.Cu")
		(net "TDR_DIFF_100_IN2_DN")
	)
	(segment
		(start 500.300498 2.33426)
		(end 501.233948 2.33426)
		(width 0.12446)
		(layer "In4.Cu")
		(net "TDR_DIFF_100_IN2_DN")
	)
	(segment
		(start 501.233948 -148.08454)
		(end 500.274082 -148.08454)
		(width 0.12446)
		(layer "In4.Cu")
		(net "TDR_DIFF_100_IN2_DN")
	)
	(segment
		(start 510.442718 -147.985988)
		(end 510.442718 2.20726)
		(width 0.12446)
		(layer "In2.Cu")
		(net "TDR_DIFF_100_IN1_DP")
	)
	(segment
		(start 510.318258 2.33172)
		(end 509.384808 2.33172)
		(width 0.12446)
		(layer "In2.Cu")
		(net "TDR_DIFF_100_IN1_DP")
	)
	(segment
		(start 510.442718 2.20726)
		(end 510.318258 2.33172)
		(width 0.12446)
		(layer "In2.Cu")
		(net "TDR_DIFF_100_IN1_DP")
	)
	(segment
		(start 509.384808 -148.08708)
		(end 510.341626 -148.08708)
		(width 0.12446)
		(layer "In2.Cu")
		(net "TDR_DIFF_100_IN1_DP")
	)
	(segment
		(start 510.341626 -148.08708)
		(end 510.442718 -147.985988)
		(width 0.12446)
		(layer "In2.Cu")
		(net "TDR_DIFF_100_IN1_DP")
	)
	(segment
		(start 510.866898 2.20726)
		(end 510.991358 2.33172)
		(width 0.12446)
		(layer "In2.Cu")
		(net "TDR_DIFF_100_IN1_DN")
	)
	(segment
		(start 511.924808 -148.08708)
		(end 510.964942 -148.08708)
		(width 0.12446)
		(layer "In2.Cu")
		(net "TDR_DIFF_100_IN1_DN")
	)
	(segment
		(start 510.991358 2.33172)
		(end 511.924808 2.33172)
		(width 0.12446)
		(layer "In2.Cu")
		(net "TDR_DIFF_100_IN1_DN")
	)
	(segment
		(start 510.964942 -148.08708)
		(end 510.866898 -147.989036)
		(width 0.12446)
		(layer "In2.Cu")
		(net "TDR_DIFF_100_IN1_DN")
	)
	(segment
		(start 510.866898 -147.989036)
		(end 510.866898 2.20726)
		(width 0.12446)
		(layer "In2.Cu")
		(net "TDR_DIFF_100_IN1_DN")
	)
	(segment
		(start 484.22814 -148.045932)
		(end 485.20985 -148.045932)
		(width 0.11176)
		(layer "B.Cu")
		(net "TDR_DIFF_100_BOT_DP")
	)
	(segment
		(start 484.22814 2.372868)
		(end 484.11638 2.261108)
		(width 0.11176)
		(layer "B.Cu")
		(net "TDR_DIFF_100_BOT_DP")
	)
	(segment
		(start 484.11638 2.261108)
		(end 484.11638 -147.934172)
		(width 0.11176)
		(layer "B.Cu")
		(net "TDR_DIFF_100_BOT_DP")
	)
	(segment
		(start 484.11638 -147.934172)
		(end 484.22814 -148.045932)
		(width 0.11176)
		(layer "B.Cu")
		(net "TDR_DIFF_100_BOT_DP")
	)
	(segment
		(start 485.20985 2.372868)
		(end 484.22814 2.372868)
		(width 0.11176)
		(layer "B.Cu")
		(net "TDR_DIFF_100_BOT_DP")
	)
	(segment
		(start 483.76332 2.261108)
		(end 483.76332 -147.934172)
		(width 0.11176)
		(layer "B.Cu")
		(net "TDR_DIFF_100_BOT_DN")
	)
	(segment
		(start 482.66985 2.372868)
		(end 483.65156 2.372868)
		(width 0.11176)
		(layer "B.Cu")
		(net "TDR_DIFF_100_BOT_DN")
	)
	(segment
		(start 483.65156 -148.045932)
		(end 482.66985 -148.045932)
		(width 0.11176)
		(layer "B.Cu")
		(net "TDR_DIFF_100_BOT_DN")
	)
	(segment
		(start 483.65156 2.372868)
		(end 483.76332 2.261108)
		(width 0.11176)
		(layer "B.Cu")
		(net "TDR_DIFF_100_BOT_DN")
	)
	(segment
		(start 483.76332 -147.934172)
		(end 483.65156 -148.045932)
		(width 0.11176)
		(layer "B.Cu")
		(net "TDR_DIFF_100_BOT_DN")
	)
	(via
		(at 127.01778 -361.73156)
		(size 0.762)
		(drill 0.381)
		(layers "F.Cu" "B.Cu")
		(net "SW_PVPP_HBM_CPU1_SW")
	)
	(via
		(at 374.92178 -361.62996)
		(size 0.762)
		(drill 0.381)
		(layers "F.Cu" "B.Cu")
		(net "SW_PVPP_HBM_CPU0_SW")
	)
	(segment
		(start 25.12568 -178.806094)
		(end 25.12568 -179.339748)
		(width 0.254)
		(layer "F.Cu")
		(net "SW_PVNN_MAIN_CPU1_BST")
	)
	(segment
		(start 25.12568 -179.339748)
		(end 24.537162 -179.928266)
		(width 0.254)
		(layer "F.Cu")
		(net "SW_PVNN_MAIN_CPU1_BST")
	)
	(segment
		(start 25.572466 -178.359308)
		(end 25.12568 -178.806094)
		(width 0.254)
		(layer "F.Cu")
		(net "SW_PVNN_MAIN_CPU1_BST")
	)
	(segment
		(start 25.636474 -178.359308)
		(end 25.572466 -178.359308)
		(width 0.254)
		(layer "F.Cu")
		(net "SW_PVNN_MAIN_CPU1_BST")
	)
	(segment
		(start 24.537162 -179.928266)
		(end 23.954994 -179.928266)
		(width 0.254)
		(layer "F.Cu")
		(net "SW_PVNN_MAIN_CPU1_BST")
	)
	(segment
		(start 435.43728 -178.990498)
		(end 435.38521 -178.990498)
		(width 0.254)
		(layer "F.Cu")
		(net "SW_PVNN_MAIN_CPU0_BST")
	)
	(segment
		(start 434.477922 -180.97627)
		(end 433.766722 -180.97627)
		(width 0.254)
		(layer "F.Cu")
		(net "SW_PVNN_MAIN_CPU0_BST")
	)
	(segment
		(start 434.87848 -180.575712)
		(end 434.477922 -180.97627)
		(width 0.254)
		(layer "F.Cu")
		(net "SW_PVNN_MAIN_CPU0_BST")
	)
	(segment
		(start 434.87848 -179.497228)
		(end 434.87848 -180.575712)
		(width 0.254)
		(layer "F.Cu")
		(net "SW_PVNN_MAIN_CPU0_BST")
	)
	(segment
		(start 435.38521 -178.990498)
		(end 434.87848 -179.497228)
		(width 0.254)
		(layer "F.Cu")
		(net "SW_PVNN_MAIN_CPU0_BST")
	)
	(segment
		(start 138.960352 -346.494608)
		(end 138.960352 -345.816936)
		(width 0.2032)
		(layer "F.Cu")
		(net "SW_PVCCIN_CPU1_BOOTR8")
	)
	(segment
		(start 139.586208 -347.120464)
		(end 138.960352 -346.494608)
		(width 0.2032)
		(layer "F.Cu")
		(net "SW_PVCCIN_CPU1_BOOTR8")
	)
	(segment
		(start 81.836768 -346.494608)
		(end 82.462624 -347.120464)
		(width 0.2032)
		(layer "F.Cu")
		(net "SW_PVCCIN_CPU1_BOOTR7")
	)
	(segment
		(start 81.836768 -345.816936)
		(end 81.836768 -346.494608)
		(width 0.2032)
		(layer "F.Cu")
		(net "SW_PVCCIN_CPU1_BOOTR7")
	)
	(segment
		(start 89.99728 -340.594442)
		(end 89.99728 -340.026244)
		(width 0.2032)
		(layer "F.Cu")
		(net "SW_PVCCIN_CPU1_BOOTR6")
	)
	(segment
		(start 90.623136 -341.220298)
		(end 89.99728 -340.594442)
		(width 0.2032)
		(layer "F.Cu")
		(net "SW_PVCCIN_CPU1_BOOTR6")
	)
	(segment
		(start 90.623136 -341.329772)
		(end 90.623136 -341.220298)
		(width 0.2032)
		(layer "F.Cu")
		(net "SW_PVCCIN_CPU1_BOOTR6")
	)
	(segment
		(start 130.79984 -340.703916)
		(end 130.79984 -340.026244)
		(width 0.2032)
		(layer "F.Cu")
		(net "SW_PVCCIN_CPU1_BOOTR5")
	)
	(segment
		(start 131.425696 -341.329772)
		(end 130.79984 -340.703916)
		(width 0.2032)
		(layer "F.Cu")
		(net "SW_PVCCIN_CPU1_BOOTR5")
	)
	(segment
		(start 122.639328 -337.152234)
		(end 122.639328 -336.61604)
		(width 0.2032)
		(layer "F.Cu")
		(net "SW_PVCCIN_CPU1_BOOTR4")
	)
	(segment
		(start 123.265184 -337.77809)
		(end 122.639328 -337.152234)
		(width 0.2032)
		(layer "F.Cu")
		(net "SW_PVCCIN_CPU1_BOOTR4")
	)
	(segment
		(start 115.052094 -337.77809)
		(end 115.052094 -337.757516)
		(width 0.2032)
		(layer "F.Cu")
		(net "SW_PVCCIN_CPU1_BOOTR3")
	)
	(segment
		(start 115.052094 -337.757516)
		(end 114.478816 -337.184238)
		(width 0.2032)
		(layer "F.Cu")
		(net "SW_PVCCIN_CPU1_BOOTR3")
	)
	(segment
		(start 114.478816 -337.184238)
		(end 114.478816 -336.61604)
		(width 0.2032)
		(layer "F.Cu")
		(net "SW_PVCCIN_CPU1_BOOTR3")
	)
	(segment
		(start 106.318304 -337.10753)
		(end 106.318304 -336.61604)
		(width 0.2032)
		(layer "F.Cu")
		(net "SW_PVCCIN_CPU1_BOOTR2")
	)
	(segment
		(start 106.990896 -337.780122)
		(end 106.318304 -337.10753)
		(width 0.2032)
		(layer "F.Cu")
		(net "SW_PVCCIN_CPU1_BOOTR2")
	)
	(segment
		(start 98.157792 -337.036664)
		(end 98.157792 -336.61604)
		(width 0.2032)
		(layer "F.Cu")
		(net "SW_PVCCIN_CPU1_BOOTR1")
	)
	(segment
		(start 99.067366 -337.780122)
		(end 98.633534 -337.34629)
		(width 0.2032)
		(layer "F.Cu")
		(net "SW_PVCCIN_CPU1_BOOTR1")
	)
	(segment
		(start 98.633534 -337.34629)
		(end 98.467418 -337.34629)
		(width 0.2032)
		(layer "F.Cu")
		(net "SW_PVCCIN_CPU1_BOOTR1")
	)
	(segment
		(start 98.467418 -337.34629)
		(end 98.157792 -337.036664)
		(width 0.2032)
		(layer "F.Cu")
		(net "SW_PVCCIN_CPU1_BOOTR1")
	)
	(segment
		(start 139.586208 -347.920564)
		(end 138.55954 -347.920564)
		(width 0.2032)
		(layer "F.Cu")
		(net "SW_PVCCIN_CPU1_BOOT8_R")
	)
	(segment
		(start 138.55954 -346.668852)
		(end 138.510264 -346.619576)
		(width 0.2032)
		(layer "F.Cu")
		(net "SW_PVCCIN_CPU1_BOOT8")
	)
	(segment
		(start 138.55954 -347.120464)
		(end 138.55954 -346.668852)
		(width 0.2032)
		(layer "F.Cu")
		(net "SW_PVCCIN_CPU1_BOOT8")
	)
	(segment
		(start 138.510264 -346.619576)
		(end 138.510264 -345.816936)
		(width 0.2032)
		(layer "F.Cu")
		(net "SW_PVCCIN_CPU1_BOOT8")
	)
	(segment
		(start 82.462624 -347.920564)
		(end 81.435956 -347.920564)
		(width 0.2032)
		(layer "F.Cu")
		(net "SW_PVCCIN_CPU1_BOOT7_R")
	)
	(segment
		(start 81.435956 -346.682568)
		(end 81.435956 -347.120464)
		(width 0.2032)
		(layer "F.Cu")
		(net "SW_PVCCIN_CPU1_BOOT7")
	)
	(segment
		(start 81.38668 -345.816936)
		(end 81.38668 -346.633292)
		(width 0.2032)
		(layer "F.Cu")
		(net "SW_PVCCIN_CPU1_BOOT7")
	)
	(segment
		(start 81.38668 -346.633292)
		(end 81.435956 -346.682568)
		(width 0.2032)
		(layer "F.Cu")
		(net "SW_PVCCIN_CPU1_BOOT7")
	)
	(segment
		(start 89.596468 -342.129872)
		(end 90.623136 -342.129872)
		(width 0.2032)
		(layer "F.Cu")
		(net "SW_PVCCIN_CPU1_BOOT6_R")
	)
	(segment
		(start 89.596468 -341.329772)
		(end 89.596468 -340.8172)
		(width 0.2032)
		(layer "F.Cu")
		(net "SW_PVCCIN_CPU1_BOOT6")
	)
	(segment
		(start 89.596468 -340.8172)
		(end 89.547192 -340.767924)
		(width 0.2032)
		(layer "F.Cu")
		(net "SW_PVCCIN_CPU1_BOOT6")
	)
	(segment
		(start 89.547192 -340.767924)
		(end 89.547192 -340.026244)
		(width 0.2032)
		(layer "F.Cu")
		(net "SW_PVCCIN_CPU1_BOOT6")
	)
	(segment
		(start 131.425696 -342.129872)
		(end 130.399028 -342.129872)
		(width 0.2032)
		(layer "F.Cu")
		(net "SW_PVCCIN_CPU1_BOOT5_R")
	)
	(segment
		(start 130.399028 -341.329772)
		(end 130.399028 -340.87816)
		(width 0.2032)
		(layer "F.Cu")
		(net "SW_PVCCIN_CPU1_BOOT5")
	)
	(segment
		(start 130.399028 -340.87816)
		(end 130.349752 -340.828884)
		(width 0.2032)
		(layer "F.Cu")
		(net "SW_PVCCIN_CPU1_BOOT5")
	)
	(segment
		(start 130.349752 -340.828884)
		(end 130.349752 -340.026244)
		(width 0.2032)
		(layer "F.Cu")
		(net "SW_PVCCIN_CPU1_BOOT5")
	)
	(segment
		(start 123.265184 -338.57819)
		(end 122.238516 -338.57819)
		(width 0.2032)
		(layer "F.Cu")
		(net "SW_PVCCIN_CPU1_BOOT4_R")
	)
	(segment
		(start 122.18924 -337.367118)
		(end 122.18924 -336.61604)
		(width 0.2032)
		(layer "F.Cu")
		(net "SW_PVCCIN_CPU1_BOOT4")
	)
	(segment
		(start 122.238516 -337.416394)
		(end 122.18924 -337.367118)
		(width 0.2032)
		(layer "F.Cu")
		(net "SW_PVCCIN_CPU1_BOOT4")
	)
	(segment
		(start 122.238516 -337.77809)
		(end 122.238516 -337.416394)
		(width 0.2032)
		(layer "F.Cu")
		(net "SW_PVCCIN_CPU1_BOOT4")
	)
	(segment
		(start 115.052094 -338.57819)
		(end 115.050062 -338.580222)
		(width 0.2032)
		(layer "F.Cu")
		(net "SW_PVCCIN_CPU1_BOOT3_R")
	)
	(segment
		(start 115.050062 -338.580222)
		(end 114.013742 -338.580222)
		(width 0.2032)
		(layer "F.Cu")
		(net "SW_PVCCIN_CPU1_BOOT3_R")
	)
	(segment
		(start 114.028728 -337.765136)
		(end 114.028728 -336.61604)
		(width 0.2032)
		(layer "F.Cu")
		(net "SW_PVCCIN_CPU1_BOOT3")
	)
	(segment
		(start 114.013742 -337.780122)
		(end 114.028728 -337.765136)
		(width 0.2032)
		(layer "F.Cu")
		(net "SW_PVCCIN_CPU1_BOOT3")
	)
	(segment
		(start 106.990896 -338.580222)
		(end 105.944416 -338.580222)
		(width 0.2032)
		(layer "F.Cu")
		(net "SW_PVCCIN_CPU1_BOOT2_R")
	)
	(segment
		(start 105.868216 -337.703922)
		(end 105.868216 -336.61604)
		(width 0.2032)
		(layer "F.Cu")
		(net "SW_PVCCIN_CPU1_BOOT2")
	)
	(segment
		(start 105.944416 -337.780122)
		(end 105.868216 -337.703922)
		(width 0.2032)
		(layer "F.Cu")
		(net "SW_PVCCIN_CPU1_BOOT2")
	)
	(segment
		(start 99.067366 -338.580222)
		(end 98.045016 -338.580222)
		(width 0.2032)
		(layer "F.Cu")
		(net "SW_PVCCIN_CPU1_BOOT1_R")
	)
	(segment
		(start 97.707704 -337.44281)
		(end 97.707704 -336.61604)
		(width 0.2032)
		(layer "F.Cu")
		(net "SW_PVCCIN_CPU1_BOOT1")
	)
	(segment
		(start 98.045016 -337.780122)
		(end 97.707704 -337.44281)
		(width 0.2032)
		(layer "F.Cu")
		(net "SW_PVCCIN_CPU1_BOOT1")
	)
	(segment
		(start 386.900166 -346.494608)
		(end 386.900166 -345.816936)
		(width 0.2032)
		(layer "F.Cu")
		(net "SW_PVCCIN_CPU0_BOOTR8")
	)
	(segment
		(start 387.526022 -347.120464)
		(end 386.900166 -346.494608)
		(width 0.2032)
		(layer "F.Cu")
		(net "SW_PVCCIN_CPU0_BOOTR8")
	)
	(segment
		(start 329.807062 -346.554552)
		(end 329.807062 -345.87688)
		(width 0.2032)
		(layer "F.Cu")
		(net "SW_PVCCIN_CPU0_BOOTR7")
	)
	(segment
		(start 330.432918 -347.180408)
		(end 329.807062 -346.554552)
		(width 0.2032)
		(layer "F.Cu")
		(net "SW_PVCCIN_CPU0_BOOTR7")
	)
	(segment
		(start 337.937094 -340.594442)
		(end 337.937094 -340.026244)
		(width 0.2032)
		(layer "F.Cu")
		(net "SW_PVCCIN_CPU0_BOOTR6")
	)
	(segment
		(start 338.56295 -341.220298)
		(end 337.937094 -340.594442)
		(width 0.2032)
		(layer "F.Cu")
		(net "SW_PVCCIN_CPU0_BOOTR6")
	)
	(segment
		(start 338.56295 -341.329772)
		(end 338.56295 -341.220298)
		(width 0.2032)
		(layer "F.Cu")
		(net "SW_PVCCIN_CPU0_BOOTR6")
	)
	(segment
		(start 379.36551 -341.329772)
		(end 378.739654 -340.703916)
		(width 0.2032)
		(layer "F.Cu")
		(net "SW_PVCCIN_CPU0_BOOTR5")
	)
	(segment
		(start 378.739654 -340.703916)
		(end 378.739654 -340.026244)
		(width 0.2032)
		(layer "F.Cu")
		(net "SW_PVCCIN_CPU0_BOOTR5")
	)
	(segment
		(start 370.579142 -337.152234)
		(end 370.579142 -336.61604)
		(width 0.2032)
		(layer "F.Cu")
		(net "SW_PVCCIN_CPU0_BOOTR4")
	)
	(segment
		(start 371.204998 -337.77809)
		(end 370.579142 -337.152234)
		(width 0.2032)
		(layer "F.Cu")
		(net "SW_PVCCIN_CPU0_BOOTR4")
	)
	(segment
		(start 362.41863 -337.184238)
		(end 362.41863 -336.61604)
		(width 0.2032)
		(layer "F.Cu")
		(net "SW_PVCCIN_CPU0_BOOTR3")
	)
	(segment
		(start 362.991908 -337.757516)
		(end 362.41863 -337.184238)
		(width 0.2032)
		(layer "F.Cu")
		(net "SW_PVCCIN_CPU0_BOOTR3")
	)
	(segment
		(start 362.991908 -337.77809)
		(end 362.991908 -337.757516)
		(width 0.2032)
		(layer "F.Cu")
		(net "SW_PVCCIN_CPU0_BOOTR3")
	)
	(segment
		(start 354.93071 -337.780122)
		(end 354.258118 -337.10753)
		(width 0.2032)
		(layer "F.Cu")
		(net "SW_PVCCIN_CPU0_BOOTR2")
	)
	(segment
		(start 354.258118 -337.10753)
		(end 354.258118 -336.61604)
		(width 0.2032)
		(layer "F.Cu")
		(net "SW_PVCCIN_CPU0_BOOTR2")
	)
	(segment
		(start 346.603828 -337.37677)
		(end 346.462858 -337.37677)
		(width 0.2286)
		(layer "F.Cu")
		(net "SW_PVCCIN_CPU0_BOOTR1")
	)
	(segment
		(start 347.00718 -337.780122)
		(end 346.603828 -337.37677)
		(width 0.2286)
		(layer "F.Cu")
		(net "SW_PVCCIN_CPU0_BOOTR1")
	)
	(segment
		(start 346.462858 -337.37677)
		(end 346.097606 -337.011518)
		(width 0.2286)
		(layer "F.Cu")
		(net "SW_PVCCIN_CPU0_BOOTR1")
	)
	(segment
		(start 346.097606 -337.011518)
		(end 346.097606 -336.61604)
		(width 0.2286)
		(layer "F.Cu")
		(net "SW_PVCCIN_CPU0_BOOTR1")
	)
	(segment
		(start 387.526022 -347.920564)
		(end 386.499354 -347.920564)
		(width 0.2032)
		(layer "F.Cu")
		(net "SW_PVCCIN_CPU0_BOOT8_R")
	)
	(segment
		(start 386.499354 -346.59824)
		(end 386.450078 -346.548964)
		(width 0.2032)
		(layer "F.Cu")
		(net "SW_PVCCIN_CPU0_BOOT8")
	)
	(segment
		(start 386.499354 -347.120464)
		(end 386.499354 -346.59824)
		(width 0.2032)
		(layer "F.Cu")
		(net "SW_PVCCIN_CPU0_BOOT8")
	)
	(segment
		(start 386.450078 -346.548964)
		(end 386.450078 -345.816936)
		(width 0.2032)
		(layer "F.Cu")
		(net "SW_PVCCIN_CPU0_BOOT8")
	)
	(segment
		(start 330.432918 -347.980508)
		(end 329.40625 -347.980508)
		(width 0.2032)
		(layer "F.Cu")
		(net "SW_PVCCIN_CPU0_BOOT7_R")
	)
	(segment
		(start 329.40625 -346.56522)
		(end 329.356974 -346.515944)
		(width 0.2032)
		(layer "F.Cu")
		(net "SW_PVCCIN_CPU0_BOOT7")
	)
	(segment
		(start 329.356974 -346.515944)
		(end 329.356974 -345.87688)
		(width 0.2032)
		(layer "F.Cu")
		(net "SW_PVCCIN_CPU0_BOOT7")
	)
	(segment
		(start 329.40625 -347.180408)
		(end 329.40625 -346.56522)
		(width 0.2032)
		(layer "F.Cu")
		(net "SW_PVCCIN_CPU0_BOOT7")
	)
	(segment
		(start 338.56295 -342.129872)
		(end 337.536282 -342.129872)
		(width 0.2032)
		(layer "F.Cu")
		(net "SW_PVCCIN_CPU0_BOOT6_R")
	)
	(segment
		(start 337.536282 -340.832948)
		(end 337.487006 -340.783672)
		(width 0.2032)
		(layer "F.Cu")
		(net "SW_PVCCIN_CPU0_BOOT6")
	)
	(segment
		(start 337.487006 -340.783672)
		(end 337.487006 -340.026244)
		(width 0.2032)
		(layer "F.Cu")
		(net "SW_PVCCIN_CPU0_BOOT6")
	)
	(segment
		(start 337.536282 -341.329772)
		(end 337.536282 -340.832948)
		(width 0.2032)
		(layer "F.Cu")
		(net "SW_PVCCIN_CPU0_BOOT6")
	)
	(segment
		(start 379.36551 -342.129872)
		(end 378.338842 -342.129872)
		(width 0.2032)
		(layer "F.Cu")
		(net "SW_PVCCIN_CPU0_BOOT5_R")
	)
	(segment
		(start 378.338842 -340.89594)
		(end 378.289566 -340.846664)
		(width 0.2032)
		(layer "F.Cu")
		(net "SW_PVCCIN_CPU0_BOOT5")
	)
	(segment
		(start 378.289566 -340.846664)
		(end 378.289566 -340.026244)
		(width 0.2032)
		(layer "F.Cu")
		(net "SW_PVCCIN_CPU0_BOOT5")
	)
	(segment
		(start 378.338842 -341.329772)
		(end 378.338842 -340.89594)
		(width 0.2032)
		(layer "F.Cu")
		(net "SW_PVCCIN_CPU0_BOOT5")
	)
	(segment
		(start 371.204998 -338.57819)
		(end 370.17833 -338.57819)
		(width 0.2032)
		(layer "F.Cu")
		(net "SW_PVCCIN_CPU0_BOOT4_R")
	)
	(segment
		(start 370.17833 -337.317842)
		(end 370.129054 -337.268566)
		(width 0.2032)
		(layer "F.Cu")
		(net "SW_PVCCIN_CPU0_BOOT4")
	)
	(segment
		(start 370.17833 -337.77809)
		(end 370.17833 -337.317842)
		(width 0.2032)
		(layer "F.Cu")
		(net "SW_PVCCIN_CPU0_BOOT4")
	)
	(segment
		(start 370.129054 -337.268566)
		(end 370.129054 -336.61604)
		(width 0.2032)
		(layer "F.Cu")
		(net "SW_PVCCIN_CPU0_BOOT4")
	)
	(segment
		(start 362.989876 -338.580222)
		(end 361.953556 -338.580222)
		(width 0.2032)
		(layer "F.Cu")
		(net "SW_PVCCIN_CPU0_BOOT3_R")
	)
	(segment
		(start 362.991908 -338.57819)
		(end 362.989876 -338.580222)
		(width 0.2032)
		(layer "F.Cu")
		(net "SW_PVCCIN_CPU0_BOOT3_R")
	)
	(segment
		(start 361.968542 -337.765136)
		(end 361.968542 -336.61604)
		(width 0.2032)
		(layer "F.Cu")
		(net "SW_PVCCIN_CPU0_BOOT3")
	)
	(segment
		(start 361.953556 -337.780122)
		(end 361.968542 -337.765136)
		(width 0.2032)
		(layer "F.Cu")
		(net "SW_PVCCIN_CPU0_BOOT3")
	)
	(segment
		(start 354.93071 -338.580222)
		(end 353.88423 -338.580222)
		(width 0.2032)
		(layer "F.Cu")
		(net "SW_PVCCIN_CPU0_BOOT2_R")
	)
	(segment
		(start 353.80803 -337.703922)
		(end 353.80803 -336.61604)
		(width 0.2032)
		(layer "F.Cu")
		(net "SW_PVCCIN_CPU0_BOOT2")
	)
	(segment
		(start 353.88423 -337.780122)
		(end 353.80803 -337.703922)
		(width 0.2032)
		(layer "F.Cu")
		(net "SW_PVCCIN_CPU0_BOOT2")
	)
	(segment
		(start 347.00718 -338.580222)
		(end 345.98483 -338.580222)
		(width 0.2032)
		(layer "F.Cu")
		(net "SW_PVCCIN_CPU0_BOOT1_R")
	)
	(segment
		(start 345.98483 -337.457288)
		(end 345.647518 -337.119976)
		(width 0.2032)
		(layer "F.Cu")
		(net "SW_PVCCIN_CPU0_BOOT1")
	)
	(segment
		(start 345.647518 -337.119976)
		(end 345.647518 -336.61604)
		(width 0.2032)
		(layer "F.Cu")
		(net "SW_PVCCIN_CPU0_BOOT1")
	)
	(segment
		(start 345.98483 -337.780122)
		(end 345.98483 -337.457288)
		(width 0.2032)
		(layer "F.Cu")
		(net "SW_PVCCIN_CPU0_BOOT1")
	)
	(segment
		(start 51.431444 -149.001988)
		(end 51.999642 -149.001988)
		(width 0.2032)
		(layer "F.Cu")
		(net "SW_PVCCINFAON_CPU1_BOOTR2")
	)
	(segment
		(start 50.837592 -149.575266)
		(end 50.858166 -149.575266)
		(width 0.2032)
		(layer "F.Cu")
		(net "SW_PVCCINFAON_CPU1_BOOTR2")
	)
	(segment
		(start 50.858166 -149.575266)
		(end 51.431444 -149.001988)
		(width 0.2032)
		(layer "F.Cu")
		(net "SW_PVCCINFAON_CPU1_BOOTR2")
	)
	(segment
		(start 50.858166 -158.211266)
		(end 50.837592 -158.211266)
		(width 0.2032)
		(layer "F.Cu")
		(net "SW_PVCCINFAON_CPU1_BOOTR1")
	)
	(segment
		(start 51.431444 -157.637988)
		(end 50.858166 -158.211266)
		(width 0.2032)
		(layer "F.Cu")
		(net "SW_PVCCINFAON_CPU1_BOOTR1")
	)
	(segment
		(start 51.999642 -157.637988)
		(end 51.431444 -157.637988)
		(width 0.2032)
		(layer "F.Cu")
		(net "SW_PVCCINFAON_CPU1_BOOTR1")
	)
	(segment
		(start 50.03546 -149.573234)
		(end 50.03546 -148.536914)
		(width 0.2032)
		(layer "F.Cu")
		(net "SW_PVCCINFAON_CPU1_BOOT2_R")
	)
	(segment
		(start 50.037492 -149.575266)
		(end 50.03546 -149.573234)
		(width 0.2032)
		(layer "F.Cu")
		(net "SW_PVCCINFAON_CPU1_BOOT2_R")
	)
	(segment
		(start 50.83556 -148.536914)
		(end 50.850546 -148.5519)
		(width 0.2032)
		(layer "F.Cu")
		(net "SW_PVCCINFAON_CPU1_BOOT2")
	)
	(segment
		(start 50.850546 -148.5519)
		(end 51.999642 -148.5519)
		(width 0.2032)
		(layer "F.Cu")
		(net "SW_PVCCINFAON_CPU1_BOOT2")
	)
	(segment
		(start 50.03546 -158.209234)
		(end 50.03546 -157.172914)
		(width 0.2032)
		(layer "F.Cu")
		(net "SW_PVCCINFAON_CPU1_BOOT1_R")
	)
	(segment
		(start 50.037492 -158.211266)
		(end 50.03546 -158.209234)
		(width 0.2032)
		(layer "F.Cu")
		(net "SW_PVCCINFAON_CPU1_BOOT1_R")
	)
	(segment
		(start 50.850546 -157.1879)
		(end 50.83556 -157.172914)
		(width 0.2032)
		(layer "F.Cu")
		(net "SW_PVCCINFAON_CPU1_BOOT1")
	)
	(segment
		(start 51.999642 -157.1879)
		(end 50.850546 -157.1879)
		(width 0.2032)
		(layer "F.Cu")
		(net "SW_PVCCINFAON_CPU1_BOOT1")
	)
	(segment
		(start 420.050976 -177.724562)
		(end 419.477698 -178.29784)
		(width 0.2032)
		(layer "F.Cu")
		(net "SW_PVCCINFAON_CPU0_BOOTR2")
	)
	(segment
		(start 419.477698 -178.29784)
		(end 418.9095 -178.29784)
		(width 0.2032)
		(layer "F.Cu")
		(net "SW_PVCCINFAON_CPU0_BOOTR2")
	)
	(segment
		(start 420.07155 -177.724562)
		(end 420.050976 -177.724562)
		(width 0.2032)
		(layer "F.Cu")
		(net "SW_PVCCINFAON_CPU0_BOOTR2")
	)
	(segment
		(start 420.07155 -169.088562)
		(end 420.050976 -169.088562)
		(width 0.2032)
		(layer "F.Cu")
		(net "SW_PVCCINFAON_CPU0_BOOTR1")
	)
	(segment
		(start 419.477698 -169.66184)
		(end 418.9095 -169.66184)
		(width 0.2032)
		(layer "F.Cu")
		(net "SW_PVCCINFAON_CPU0_BOOTR1")
	)
	(segment
		(start 420.050976 -169.088562)
		(end 419.477698 -169.66184)
		(width 0.2032)
		(layer "F.Cu")
		(net "SW_PVCCINFAON_CPU0_BOOTR1")
	)
	(segment
		(start 420.87165 -177.724562)
		(end 420.873682 -177.726594)
		(width 0.2032)
		(layer "F.Cu")
		(net "SW_PVCCINFAON_CPU0_BOOT2_R")
	)
	(segment
		(start 420.873682 -177.726594)
		(end 420.873682 -178.762914)
		(width 0.2032)
		(layer "F.Cu")
		(net "SW_PVCCINFAON_CPU0_BOOT2_R")
	)
	(segment
		(start 420.058596 -178.747928)
		(end 418.9095 -178.747928)
		(width 0.2032)
		(layer "F.Cu")
		(net "SW_PVCCINFAON_CPU0_BOOT2")
	)
	(segment
		(start 420.073582 -178.762914)
		(end 420.058596 -178.747928)
		(width 0.2032)
		(layer "F.Cu")
		(net "SW_PVCCINFAON_CPU0_BOOT2")
	)
	(segment
		(start 420.87165 -169.088562)
		(end 420.873682 -169.090594)
		(width 0.2032)
		(layer "F.Cu")
		(net "SW_PVCCINFAON_CPU0_BOOT1_R")
	)
	(segment
		(start 420.873682 -169.090594)
		(end 420.873682 -170.126914)
		(width 0.2032)
		(layer "F.Cu")
		(net "SW_PVCCINFAON_CPU0_BOOT1_R")
	)
	(segment
		(start 420.073582 -170.126914)
		(end 420.058596 -170.111928)
		(width 0.2032)
		(layer "F.Cu")
		(net "SW_PVCCINFAON_CPU0_BOOT1")
	)
	(segment
		(start 420.058596 -170.111928)
		(end 418.9095 -170.111928)
		(width 0.2032)
		(layer "F.Cu")
		(net "SW_PVCCINFAON_CPU0_BOOT1")
	)
	(segment
		(start 42.725086 -357.354124)
		(end 42.725086 -356.447852)
		(width 0.2032)
		(layer "F.Cu")
		(net "SW_PVCCFA_EHV_FIVRA_CPU1_BOOTR4")
	)
	(segment
		(start 43.350942 -357.97998)
		(end 42.725086 -357.354124)
		(width 0.2032)
		(layer "F.Cu")
		(net "SW_PVCCFA_EHV_FIVRA_CPU1_BOOTR4")
	)
	(segment
		(start 183.49849 -357.648256)
		(end 182.872634 -357.0224)
		(width 0.2032)
		(layer "F.Cu")
		(net "SW_PVCCFA_EHV_FIVRA_CPU1_BOOTR3")
	)
	(segment
		(start 183.49849 -357.75773)
		(end 183.49849 -357.648256)
		(width 0.2032)
		(layer "F.Cu")
		(net "SW_PVCCFA_EHV_FIVRA_CPU1_BOOTR3")
	)
	(segment
		(start 182.872634 -357.0224)
		(end 182.872634 -356.454202)
		(width 0.2032)
		(layer "F.Cu")
		(net "SW_PVCCFA_EHV_FIVRA_CPU1_BOOTR3")
	)
	(segment
		(start 52.413408 -357.455724)
		(end 52.413408 -356.447852)
		(width 0.2032)
		(layer "F.Cu")
		(net "SW_PVCCFA_EHV_FIVRA_CPU1_BOOTR2")
	)
	(segment
		(start 52.759864 -357.80218)
		(end 52.413408 -357.455724)
		(width 0.2032)
		(layer "F.Cu")
		(net "SW_PVCCFA_EHV_FIVRA_CPU1_BOOTR2")
	)
	(segment
		(start 173.184312 -357.0224)
		(end 173.184312 -356.454202)
		(width 0.2032)
		(layer "F.Cu")
		(net "SW_PVCCFA_EHV_FIVRA_CPU1_BOOTR1")
	)
	(segment
		(start 173.810168 -357.75773)
		(end 173.810168 -357.648256)
		(width 0.2032)
		(layer "F.Cu")
		(net "SW_PVCCFA_EHV_FIVRA_CPU1_BOOTR1")
	)
	(segment
		(start 173.810168 -357.648256)
		(end 173.184312 -357.0224)
		(width 0.2032)
		(layer "F.Cu")
		(net "SW_PVCCFA_EHV_FIVRA_CPU1_BOOTR1")
	)
	(segment
		(start 43.350942 -358.78008)
		(end 42.324274 -358.78008)
		(width 0.2032)
		(layer "F.Cu")
		(net "SW_PVCCFA_EHV_FIVRA_CPU1_BOOT4_")
	)
	(segment
		(start 42.274998 -357.930704)
		(end 42.274998 -356.447852)
		(width 0.2032)
		(layer "F.Cu")
		(net "SW_PVCCFA_EHV_FIVRA_CPU1_BOOT4")
	)
	(segment
		(start 42.324274 -357.97998)
		(end 42.274998 -357.930704)
		(width 0.2032)
		(layer "F.Cu")
		(net "SW_PVCCFA_EHV_FIVRA_CPU1_BOOT4")
	)
	(segment
		(start 183.49849 -358.55783)
		(end 182.471822 -358.55783)
		(width 0.2032)
		(layer "F.Cu")
		(net "SW_PVCCFA_EHV_FIVRA_CPU1_BOOT3_")
	)
	(segment
		(start 182.471822 -357.288338)
		(end 182.422546 -357.239062)
		(width 0.2032)
		(layer "F.Cu")
		(net "SW_PVCCFA_EHV_FIVRA_CPU1_BOOT3")
	)
	(segment
		(start 182.422546 -357.239062)
		(end 182.422546 -356.454202)
		(width 0.2032)
		(layer "F.Cu")
		(net "SW_PVCCFA_EHV_FIVRA_CPU1_BOOT3")
	)
	(segment
		(start 182.471822 -357.75773)
		(end 182.471822 -357.288338)
		(width 0.2032)
		(layer "F.Cu")
		(net "SW_PVCCFA_EHV_FIVRA_CPU1_BOOT3")
	)
	(segment
		(start 51.860196 -358.60228)
		(end 52.759864 -358.60228)
		(width 0.2032)
		(layer "F.Cu")
		(net "SW_PVCCFA_EHV_FIVRA_CPU1_BOOT2_")
	)
	(segment
		(start 51.96332 -357.699056)
		(end 51.96332 -356.447852)
		(width 0.2032)
		(layer "F.Cu")
		(net "SW_PVCCFA_EHV_FIVRA_CPU1_BOOT2")
	)
	(segment
		(start 51.860196 -357.80218)
		(end 51.96332 -357.699056)
		(width 0.2032)
		(layer "F.Cu")
		(net "SW_PVCCFA_EHV_FIVRA_CPU1_BOOT2")
	)
	(segment
		(start 173.810168 -358.55783)
		(end 172.7835 -358.55783)
		(width 0.2032)
		(layer "F.Cu")
		(net "SW_PVCCFA_EHV_FIVRA_CPU1_BOOT1_")
	)
	(segment
		(start 172.734224 -357.239062)
		(end 172.734224 -356.454202)
		(width 0.2032)
		(layer "F.Cu")
		(net "SW_PVCCFA_EHV_FIVRA_CPU1_BOOT1")
	)
	(segment
		(start 172.7835 -357.288338)
		(end 172.734224 -357.239062)
		(width 0.2032)
		(layer "F.Cu")
		(net "SW_PVCCFA_EHV_FIVRA_CPU1_BOOT1")
	)
	(segment
		(start 172.7835 -357.75773)
		(end 172.7835 -357.288338)
		(width 0.2032)
		(layer "F.Cu")
		(net "SW_PVCCFA_EHV_FIVRA_CPU1_BOOT1")
	)
	(segment
		(start 290.571936 -366.978946)
		(end 290.571936 -366.869472)
		(width 0.2032)
		(layer "F.Cu")
		(net "SW_PVCCFA_EHV_FIVRA_CPU0_BOOTR4")
	)
	(segment
		(start 290.571936 -366.869472)
		(end 289.94608 -366.243616)
		(width 0.2032)
		(layer "F.Cu")
		(net "SW_PVCCFA_EHV_FIVRA_CPU0_BOOTR4")
	)
	(segment
		(start 289.94608 -366.243616)
		(end 289.94608 -365.675418)
		(width 0.2032)
		(layer "F.Cu")
		(net "SW_PVCCFA_EHV_FIVRA_CPU0_BOOTR4")
	)
	(segment
		(start 427.008798 -365.555784)
		(end 427.008798 -364.987586)
		(width 0.2032)
		(layer "F.Cu")
		(net "SW_PVCCFA_EHV_FIVRA_CPU0_BOOTR3")
	)
	(segment
		(start 427.634654 -366.291114)
		(end 427.634654 -366.18164)
		(width 0.2032)
		(layer "F.Cu")
		(net "SW_PVCCFA_EHV_FIVRA_CPU0_BOOTR3")
	)
	(segment
		(start 427.634654 -366.18164)
		(end 427.008798 -365.555784)
		(width 0.2032)
		(layer "F.Cu")
		(net "SW_PVCCFA_EHV_FIVRA_CPU0_BOOTR3")
	)
	(segment
		(start 299.634402 -366.243616)
		(end 299.634402 -365.675418)
		(width 0.2032)
		(layer "F.Cu")
		(net "SW_PVCCFA_EHV_FIVRA_CPU0_BOOTR2")
	)
	(segment
		(start 300.260258 -366.978946)
		(end 300.260258 -366.869472)
		(width 0.2032)
		(layer "F.Cu")
		(net "SW_PVCCFA_EHV_FIVRA_CPU0_BOOTR2")
	)
	(segment
		(start 300.260258 -366.869472)
		(end 299.634402 -366.243616)
		(width 0.2032)
		(layer "F.Cu")
		(net "SW_PVCCFA_EHV_FIVRA_CPU0_BOOTR2")
	)
	(segment
		(start 417.946332 -366.18164)
		(end 417.320476 -365.555784)
		(width 0.2032)
		(layer "F.Cu")
		(net "SW_PVCCFA_EHV_FIVRA_CPU0_BOOTR1")
	)
	(segment
		(start 417.946332 -366.291114)
		(end 417.946332 -366.18164)
		(width 0.2032)
		(layer "F.Cu")
		(net "SW_PVCCFA_EHV_FIVRA_CPU0_BOOTR1")
	)
	(segment
		(start 417.320476 -365.555784)
		(end 417.320476 -364.987586)
		(width 0.2032)
		(layer "F.Cu")
		(net "SW_PVCCFA_EHV_FIVRA_CPU0_BOOTR1")
	)
	(segment
		(start 290.571936 -367.779046)
		(end 289.545268 -367.779046)
		(width 0.2032)
		(layer "F.Cu")
		(net "SW_PVCCFA_EHV_FIVRA_CPU0_BOOT4_")
	)
	(segment
		(start 289.545268 -366.978946)
		(end 289.545268 -366.463834)
		(width 0.2032)
		(layer "F.Cu")
		(net "SW_PVCCFA_EHV_FIVRA_CPU0_BOOT4")
	)
	(segment
		(start 289.545268 -366.463834)
		(end 289.495992 -366.414558)
		(width 0.2032)
		(layer "F.Cu")
		(net "SW_PVCCFA_EHV_FIVRA_CPU0_BOOT4")
	)
	(segment
		(start 289.495992 -366.414558)
		(end 289.495992 -365.675418)
		(width 0.2032)
		(layer "F.Cu")
		(net "SW_PVCCFA_EHV_FIVRA_CPU0_BOOT4")
	)
	(segment
		(start 427.634654 -367.091214)
		(end 426.607986 -367.091214)
		(width 0.2032)
		(layer "F.Cu")
		(net "SW_PVCCFA_EHV_FIVRA_CPU0_BOOT3_")
	)
	(segment
		(start 426.607986 -366.291114)
		(end 426.607986 -365.888778)
		(width 0.2032)
		(layer "F.Cu")
		(net "SW_PVCCFA_EHV_FIVRA_CPU0_BOOT3")
	)
	(segment
		(start 426.55871 -365.839502)
		(end 426.55871 -364.987586)
		(width 0.2032)
		(layer "F.Cu")
		(net "SW_PVCCFA_EHV_FIVRA_CPU0_BOOT3")
	)
	(segment
		(start 426.607986 -365.888778)
		(end 426.55871 -365.839502)
		(width 0.2032)
		(layer "F.Cu")
		(net "SW_PVCCFA_EHV_FIVRA_CPU0_BOOT3")
	)
	(segment
		(start 300.260258 -367.779046)
		(end 299.23359 -367.779046)
		(width 0.2032)
		(layer "F.Cu")
		(net "SW_PVCCFA_EHV_FIVRA_CPU0_BOOT2_")
	)
	(segment
		(start 299.184314 -366.354614)
		(end 299.184314 -365.675418)
		(width 0.2032)
		(layer "F.Cu")
		(net "SW_PVCCFA_EHV_FIVRA_CPU0_BOOT2")
	)
	(segment
		(start 299.23359 -366.978946)
		(end 299.23359 -366.40389)
		(width 0.2032)
		(layer "F.Cu")
		(net "SW_PVCCFA_EHV_FIVRA_CPU0_BOOT2")
	)
	(segment
		(start 299.23359 -366.40389)
		(end 299.184314 -366.354614)
		(width 0.2032)
		(layer "F.Cu")
		(net "SW_PVCCFA_EHV_FIVRA_CPU0_BOOT2")
	)
	(segment
		(start 417.946332 -367.091214)
		(end 416.919664 -367.091214)
		(width 0.2032)
		(layer "F.Cu")
		(net "SW_PVCCFA_EHV_FIVRA_CPU0_BOOT1_")
	)
	(segment
		(start 416.919664 -365.730282)
		(end 416.870388 -365.681006)
		(width 0.2032)
		(layer "F.Cu")
		(net "SW_PVCCFA_EHV_FIVRA_CPU0_BOOT1")
	)
	(segment
		(start 416.870388 -365.681006)
		(end 416.870388 -364.987586)
		(width 0.2032)
		(layer "F.Cu")
		(net "SW_PVCCFA_EHV_FIVRA_CPU0_BOOT1")
	)
	(segment
		(start 416.919664 -366.291114)
		(end 416.919664 -365.730282)
		(width 0.2032)
		(layer "F.Cu")
		(net "SW_PVCCFA_EHV_FIVRA_CPU0_BOOT1")
	)
	(segment
		(start 50.169572 -176.180242)
		(end 50.469038 -175.880776)
		(width 0.254)
		(layer "F.Cu")
		(net "SW_PVCCFA_EHV_CPU1_BOOTR1")
	)
	(segment
		(start 49.331118 -176.180242)
		(end 50.169572 -176.180242)
		(width 0.254)
		(layer "F.Cu")
		(net "SW_PVCCFA_EHV_CPU1_BOOTR1")
	)
	(segment
		(start 50.469038 -175.880776)
		(end 50.765964 -175.880776)
		(width 0.254)
		(layer "F.Cu")
		(net "SW_PVCCFA_EHV_CPU1_BOOTR1")
	)
	(segment
		(start 48.531018 -176.180242)
		(end 48.531018 -175.179482)
		(width 0.3302)
		(layer "F.Cu")
		(net "SW_PVCCFA_EHV_CPU1_BOOT1_R")
	)
	(segment
		(start 49.622964 -175.179482)
		(end 49.824386 -175.380904)
		(width 0.254)
		(layer "F.Cu")
		(net "SW_PVCCFA_EHV_CPU1_BOOT1")
	)
	(segment
		(start 49.824386 -175.380904)
		(end 50.765964 -175.380904)
		(width 0.254)
		(layer "F.Cu")
		(net "SW_PVCCFA_EHV_CPU1_BOOT1")
	)
	(segment
		(start 49.331118 -175.179482)
		(end 49.622964 -175.179482)
		(width 0.254)
		(layer "F.Cu")
		(net "SW_PVCCFA_EHV_CPU1_BOOT1")
	)
	(segment
		(start 421.202104 -151.419052)
		(end 420.905178 -151.419052)
		(width 0.254)
		(layer "F.Cu")
		(net "SW_PVCCFA_EHV_CPU0_BOOTR1")
	)
	(segment
		(start 421.50157 -151.119586)
		(end 421.202104 -151.419052)
		(width 0.254)
		(layer "F.Cu")
		(net "SW_PVCCFA_EHV_CPU0_BOOTR1")
	)
	(segment
		(start 422.340024 -151.119586)
		(end 421.50157 -151.119586)
		(width 0.254)
		(layer "F.Cu")
		(net "SW_PVCCFA_EHV_CPU0_BOOTR1")
	)
	(segment
		(start 423.140124 -152.017222)
		(end 423.14749 -152.024588)
		(width 0.3302)
		(layer "F.Cu")
		(net "SW_PVCCFA_EHV_CPU0_BOOT1_R")
	)
	(segment
		(start 423.140124 -151.119586)
		(end 423.140124 -152.017222)
		(width 0.3302)
		(layer "F.Cu")
		(net "SW_PVCCFA_EHV_CPU0_BOOT1_R")
	)
	(segment
		(start 421.759126 -151.918924)
		(end 420.905178 -151.918924)
		(width 0.254)
		(layer "F.Cu")
		(net "SW_PVCCFA_EHV_CPU0_BOOT1")
	)
	(segment
		(start 422.34739 -152.024588)
		(end 421.86479 -152.024588)
		(width 0.254)
		(layer "F.Cu")
		(net "SW_PVCCFA_EHV_CPU0_BOOT1")
	)
	(segment
		(start 421.86479 -152.024588)
		(end 421.759126 -151.918924)
		(width 0.254)
		(layer "F.Cu")
		(net "SW_PVCCFA_EHV_CPU0_BOOT1")
	)
	(segment
		(start 51.41087 -166.273988)
		(end 50.837592 -166.847266)
		(width 0.2032)
		(layer "F.Cu")
		(net "SW_PVCCD_HV_CPU1_BOOTR1")
	)
	(segment
		(start 51.999642 -166.273988)
		(end 51.41087 -166.273988)
		(width 0.2032)
		(layer "F.Cu")
		(net "SW_PVCCD_HV_CPU1_BOOTR1")
	)
	(segment
		(start 50.03546 -166.845234)
		(end 50.037492 -166.847266)
		(width 0.2032)
		(layer "F.Cu")
		(net "SW_PVCCD_HV_CPU1_BOOT1_R")
	)
	(segment
		(start 50.03546 -165.808914)
		(end 50.03546 -166.845234)
		(width 0.2032)
		(layer "F.Cu")
		(net "SW_PVCCD_HV_CPU1_BOOT1_R")
	)
	(segment
		(start 51.29276 -165.808914)
		(end 50.83556 -165.808914)
		(width 0.2032)
		(layer "F.Cu")
		(net "SW_PVCCD_HV_CPU1_BOOT1")
	)
	(segment
		(start 51.307746 -165.8239)
		(end 51.29276 -165.808914)
		(width 0.2032)
		(layer "F.Cu")
		(net "SW_PVCCD_HV_CPU1_BOOT1")
	)
	(segment
		(start 51.999642 -165.8239)
		(end 51.307746 -165.8239)
		(width 0.2032)
		(layer "F.Cu")
		(net "SW_PVCCD_HV_CPU1_BOOT1")
	)
	(segment
		(start 420.07155 -160.452562)
		(end 420.050976 -160.452562)
		(width 0.2032)
		(layer "F.Cu")
		(net "SW_PVCCD_HV_CPU0_BOOTR1")
	)
	(segment
		(start 419.477698 -161.02584)
		(end 418.9095 -161.02584)
		(width 0.2032)
		(layer "F.Cu")
		(net "SW_PVCCD_HV_CPU0_BOOTR1")
	)
	(segment
		(start 420.050976 -160.452562)
		(end 419.477698 -161.02584)
		(width 0.2032)
		(layer "F.Cu")
		(net "SW_PVCCD_HV_CPU0_BOOTR1")
	)
	(segment
		(start 420.873682 -160.454594)
		(end 420.873682 -161.490914)
		(width 0.2032)
		(layer "F.Cu")
		(net "SW_PVCCD_HV_CPU0_BOOT1_R")
	)
	(segment
		(start 420.87165 -160.452562)
		(end 420.873682 -160.454594)
		(width 0.2032)
		(layer "F.Cu")
		(net "SW_PVCCD_HV_CPU0_BOOT1_R")
	)
	(segment
		(start 420.058596 -161.475928)
		(end 418.9095 -161.475928)
		(width 0.2032)
		(layer "F.Cu")
		(net "SW_PVCCD_HV_CPU0_BOOT1")
	)
	(segment
		(start 420.073582 -161.490914)
		(end 420.058596 -161.475928)
		(width 0.2032)
		(layer "F.Cu")
		(net "SW_PVCCD_HV_CPU0_BOOT1")
	)
	(via
		(at 460.68996 -71.554848)
		(size 0.6604)
		(drill 0.3302)
		(layers "F.Cu" "B.Cu")
		(net "SW_P3V3_AUX_FLT")
	)
	(via
		(at 457.0095 -75.674728)
		(size 0.6604)
		(drill 0.3302)
		(layers "F.Cu" "B.Cu")
		(net "SW_P3V3_AUX_FLT")
	)
	(via
		(at 453.666606 -73.060814)
		(size 0.508)
		(drill 0.254)
		(layers "F.Cu" "B.Cu")
		(net "SW_P3V3_AUX_FLT")
	)
	(via
		(at 454.848722 -73.060814)
		(size 0.508)
		(drill 0.254)
		(layers "F.Cu" "B.Cu")
		(net "SW_P3V3_AUX_FLT")
	)
	(via
		(at 455.490326 -73.060814)
		(size 0.508)
		(drill 0.254)
		(layers "F.Cu" "B.Cu")
		(net "SW_P3V3_AUX_FLT")
	)
	(via
		(at 453.025002 -73.060814)
		(size 0.508)
		(drill 0.254)
		(layers "F.Cu" "B.Cu")
		(net "SW_P3V3_AUX_FLT")
	)
	(via
		(at 455.071226 -74.788014)
		(size 0.508)
		(drill 0.254)
		(layers "F.Cu" "B.Cu")
		(net "SW_P3V3_AUX_FLT")
	)
	(via
		(at 454.429622 -74.788014)
		(size 0.508)
		(drill 0.254)
		(layers "F.Cu" "B.Cu")
		(net "SW_P3V3_AUX_FLT")
	)
	(segment
		(start 452.886572 -74.140314)
		(end 452.886572 -75.093322)
		(width 0.254)
		(layer "F.Cu")
		(net "SW_P3V3_AUX_BOOT_R")
	)
	(segment
		(start 452.882762 -74.136504)
		(end 452.886572 -74.140314)
		(width 0.254)
		(layer "F.Cu")
		(net "SW_P3V3_AUX_BOOT_R")
	)
	(segment
		(start 452.082662 -74.136504)
		(end 451.72376 -73.777602)
		(width 0.254)
		(layer "F.Cu")
		(net "SW_P3V3_AUX_BOOTR")
	)
	(segment
		(start 451.72376 -73.777602)
		(end 450.768974 -73.777602)
		(width 0.254)
		(layer "F.Cu")
		(net "SW_P3V3_AUX_BOOTR")
	)
	(segment
		(start 451.435724 -74.277474)
		(end 450.768974 -74.277474)
		(width 0.254)
		(layer "F.Cu")
		(net "SW_P3V3_AUX_BOOT")
	)
	(segment
		(start 452.086472 -75.093322)
		(end 452.086472 -74.928222)
		(width 0.254)
		(layer "F.Cu")
		(net "SW_P3V3_AUX_BOOT")
	)
	(segment
		(start 452.086472 -74.928222)
		(end 451.435724 -74.277474)
		(width 0.254)
		(layer "F.Cu")
		(net "SW_P3V3_AUX_BOOT")
	)
	(via
		(at 391.72642 -74.353928)
		(size 0.762)
		(drill 0.381)
		(layers "F.Cu" "B.Cu")
		(net "SW_P1V8_PCH_AUX_FLT")
	)
	(segment
		(start 111.689896 -343.114376)
		(end 112.604804 -344.029284)
		(width 0.508)
		(layer "F.Cu")
		(net "SW_P12V_PVCCIN_CPU1_FLT")
	)
	(segment
		(start 120.0658 -343.906348)
		(end 120.980708 -344.821256)
		(width 0.508)
		(layer "F.Cu")
		(net "SW_P12V_PVCCIN_CPU1_FLT")
	)
	(segment
		(start 104.89946 -344.029284)
		(end 105.814368 -343.114376)
		(width 0.508)
		(layer "F.Cu")
		(net "SW_P12V_PVCCIN_CPU1_FLT")
	)
	(segment
		(start 96.423988 -343.114376)
		(end 97.338896 -344.029284)
		(width 0.508)
		(layer "F.Cu")
		(net "SW_P12V_PVCCIN_CPU1_FLT")
	)
	(segment
		(start 115.467892 -349.41764)
		(end 116.4844 -350.434148)
		(width 0.508)
		(layer "F.Cu")
		(net "SW_P12V_PVCCIN_CPU1_FLT")
	)
	(segment
		(start 112.604804 -344.029284)
		(end 113.519712 -343.114376)
		(width 0.508)
		(layer "F.Cu")
		(net "SW_P12V_PVCCIN_CPU1_FLT")
	)
	(segment
		(start 104.89946 -344.029284)
		(end 105.814368 -344.944192)
		(width 0.508)
		(layer "F.Cu")
		(net "SW_P12V_PVCCIN_CPU1_FLT")
	)
	(segment
		(start 119.150892 -342.99144)
		(end 120.0658 -343.906348)
		(width 0.508)
		(layer "F.Cu")
		(net "SW_P12V_PVCCIN_CPU1_FLT")
	)
	(segment
		(start 97.338896 -344.029284)
		(end 98.253804 -343.114376)
		(width 0.508)
		(layer "F.Cu")
		(net "SW_P12V_PVCCIN_CPU1_FLT")
	)
	(segment
		(start 119.150892 -344.821256)
		(end 120.0658 -343.906348)
		(width 0.508)
		(layer "F.Cu")
		(net "SW_P12V_PVCCIN_CPU1_FLT")
	)
	(segment
		(start 116.4844 -350.434148)
		(end 117.500908 -349.41764)
		(width 0.508)
		(layer "F.Cu")
		(net "SW_P12V_PVCCIN_CPU1_FLT")
	)
	(segment
		(start 96.423988 -344.944192)
		(end 97.338896 -344.029284)
		(width 0.508)
		(layer "F.Cu")
		(net "SW_P12V_PVCCIN_CPU1_FLT")
	)
	(segment
		(start 116.4844 -350.434148)
		(end 117.500908 -351.450656)
		(width 0.508)
		(layer "F.Cu")
		(net "SW_P12V_PVCCIN_CPU1_FLT")
	)
	(segment
		(start 97.338896 -344.029284)
		(end 98.253804 -344.944192)
		(width 0.508)
		(layer "F.Cu")
		(net "SW_P12V_PVCCIN_CPU1_FLT")
	)
	(segment
		(start 115.467892 -351.450656)
		(end 116.4844 -350.434148)
		(width 0.508)
		(layer "F.Cu")
		(net "SW_P12V_PVCCIN_CPU1_FLT")
	)
	(segment
		(start 103.984552 -344.944192)
		(end 104.89946 -344.029284)
		(width 0.508)
		(layer "F.Cu")
		(net "SW_P12V_PVCCIN_CPU1_FLT")
	)
	(segment
		(start 111.689896 -344.944192)
		(end 112.604804 -344.029284)
		(width 0.508)
		(layer "F.Cu")
		(net "SW_P12V_PVCCIN_CPU1_FLT")
	)
	(segment
		(start 103.984552 -343.114376)
		(end 104.89946 -344.029284)
		(width 0.508)
		(layer "F.Cu")
		(net "SW_P12V_PVCCIN_CPU1_FLT")
	)
	(segment
		(start 112.604804 -344.029284)
		(end 113.519712 -344.944192)
		(width 0.508)
		(layer "F.Cu")
		(net "SW_P12V_PVCCIN_CPU1_FLT")
	)
	(segment
		(start 120.0658 -343.906348)
		(end 120.980708 -342.99144)
		(width 0.508)
		(layer "F.Cu")
		(net "SW_P12V_PVCCIN_CPU1_FLT")
	)
	(via
		(at 83.830414 -346.02801)
		(size 0.508)
		(drill 0.254)
		(layers "F.Cu" "B.Cu")
		(net "SW_P12V_PVCCIN_CPU1_FLT")
	)
	(via
		(at 90.1319 -350.115632)
		(size 0.508)
		(drill 0.254)
		(layers "F.Cu" "B.Cu")
		(net "SW_P12V_PVCCIN_CPU1_FLT")
	)
	(via
		(at 140.928598 -345.26601)
		(size 0.508)
		(drill 0.254)
		(layers "F.Cu" "B.Cu")
		(net "SW_P12V_PVCCIN_CPU1_FLT")
	)
	(via
		(at 106.415586 -335.769458)
		(size 0.49022)
		(drill 0.254)
		(layers "F.Cu" "B.Cu")
		(net "SW_P12V_PVCCIN_CPU1_FLT")
	)
	(via
		(at 141.487398 -346.38361)
		(size 0.508)
		(drill 0.254)
		(layers "F.Cu" "B.Cu")
		(net "SW_P12V_PVCCIN_CPU1_FLT")
	)
	(via
		(at 98.846894 -335.578958)
		(size 0.49022)
		(drill 0.254)
		(layers "F.Cu" "B.Cu")
		(net "SW_P12V_PVCCIN_CPU1_FLT")
	)
	(via
		(at 83.28025 -346.44203)
		(size 0.508)
		(drill 0.254)
		(layers "F.Cu" "B.Cu")
		(net "SW_P12V_PVCCIN_CPU1_FLT")
	)
	(via
		(at 90.1319 -348.464632)
		(size 0.508)
		(drill 0.254)
		(layers "F.Cu" "B.Cu")
		(net "SW_P12V_PVCCIN_CPU1_FLT")
	)
	(via
		(at 90.1319 -349.353632)
		(size 0.508)
		(drill 0.254)
		(layers "F.Cu" "B.Cu")
		(net "SW_P12V_PVCCIN_CPU1_FLT")
	)
	(via
		(at 107.761786 -337.241134)
		(size 0.508)
		(drill 0.254)
		(layers "F.Cu" "B.Cu")
		(net "SW_P12V_PVCCIN_CPU1_FLT")
	)
	(via
		(at 124.657612 -337.062572)
		(size 0.508)
		(drill 0.254)
		(layers "F.Cu" "B.Cu")
		(net "SW_P12V_PVCCIN_CPU1_FLT")
	)
	(via
		(at 123.32843 -335.578958)
		(size 0.49022)
		(drill 0.254)
		(layers "F.Cu" "B.Cu")
		(net "SW_P12V_PVCCIN_CPU1_FLT")
	)
	(via
		(at 107.761786 -336.504534)
		(size 0.508)
		(drill 0.254)
		(layers "F.Cu" "B.Cu")
		(net "SW_P12V_PVCCIN_CPU1_FLT")
	)
	(via
		(at 89.502742 -338.989162)
		(size 0.49022)
		(drill 0.254)
		(layers "F.Cu" "B.Cu")
		(net "SW_P12V_PVCCIN_CPU1_FLT")
	)
	(via
		(at 94.882208 -349.395542)
		(size 0.508)
		(drill 0.254)
		(layers "F.Cu" "B.Cu")
		(net "SW_P12V_PVCCIN_CPU1_FLT")
	)
	(via
		(at 91.096338 -348.48546)
		(size 0.508)
		(drill 0.254)
		(layers "F.Cu" "B.Cu")
		(net "SW_P12V_PVCCIN_CPU1_FLT")
	)
	(via
		(at 89.3699 -349.353632)
		(size 0.508)
		(drill 0.254)
		(layers "F.Cu" "B.Cu")
		(net "SW_P12V_PVCCIN_CPU1_FLT")
	)
	(via
		(at 115.759738 -335.769458)
		(size 0.49022)
		(drill 0.254)
		(layers "F.Cu" "B.Cu")
		(net "SW_P12V_PVCCIN_CPU1_FLT")
	)
	(via
		(at 92.524326 -339.856318)
		(size 0.508)
		(drill 0.254)
		(layers "F.Cu" "B.Cu")
		(net "SW_P12V_PVCCIN_CPU1_FLT")
	)
	(via
		(at 100.684838 -336.446114)
		(size 0.508)
		(drill 0.254)
		(layers "F.Cu" "B.Cu")
		(net "SW_P12V_PVCCIN_CPU1_FLT")
	)
	(via
		(at 91.985338 -340.271862)
		(size 0.508)
		(drill 0.254)
		(layers "F.Cu" "B.Cu")
		(net "SW_P12V_PVCCIN_CPU1_FLT")
	)
	(via
		(at 91.440762 -339.914738)
		(size 0.508)
		(drill 0.254)
		(layers "F.Cu" "B.Cu")
		(net "SW_P12V_PVCCIN_CPU1_FLT")
	)
	(via
		(at 95.76435 -348.48546)
		(size 0.508)
		(drill 0.254)
		(layers "F.Cu" "B.Cu")
		(net "SW_P12V_PVCCIN_CPU1_FLT")
	)
	(via
		(at 90.686382 -338.989162)
		(size 0.49022)
		(drill 0.254)
		(layers "F.Cu" "B.Cu")
		(net "SW_P12V_PVCCIN_CPU1_FLT")
	)
	(via
		(at 141.487398 -345.64701)
		(size 0.508)
		(drill 0.254)
		(layers "F.Cu" "B.Cu")
		(net "SW_P12V_PVCCIN_CPU1_FLT")
	)
	(via
		(at 99.601274 -337.241134)
		(size 0.508)
		(drill 0.254)
		(layers "F.Cu" "B.Cu")
		(net "SW_P12V_PVCCIN_CPU1_FLT")
	)
	(via
		(at 90.094562 -339.179662)
		(size 0.49022)
		(drill 0.254)
		(layers "F.Cu" "B.Cu")
		(net "SW_P12V_PVCCIN_CPU1_FLT")
	)
	(via
		(at 139.057634 -344.970354)
		(size 0.49022)
		(drill 0.254)
		(layers "F.Cu" "B.Cu")
		(net "SW_P12V_PVCCIN_CPU1_FLT")
	)
	(via
		(at 132.243322 -339.914738)
		(size 0.508)
		(drill 0.254)
		(layers "F.Cu" "B.Cu")
		(net "SW_P12V_PVCCIN_CPU1_FLT")
	)
	(via
		(at 124.088906 -337.482688)
		(size 0.508)
		(drill 0.254)
		(layers "F.Cu" "B.Cu")
		(net "SW_P12V_PVCCIN_CPU1_FLT")
	)
	(via
		(at 117.005862 -336.446114)
		(size 0.508)
		(drill 0.254)
		(layers "F.Cu" "B.Cu")
		(net "SW_P12V_PVCCIN_CPU1_FLT")
	)
	(via
		(at 100.684838 -337.182714)
		(size 0.508)
		(drill 0.254)
		(layers "F.Cu" "B.Cu")
		(net "SW_P12V_PVCCIN_CPU1_FLT")
	)
	(via
		(at 138.465814 -344.779854)
		(size 0.49022)
		(drill 0.254)
		(layers "F.Cu" "B.Cu")
		(net "SW_P12V_PVCCIN_CPU1_FLT")
	)
	(via
		(at 98.255074 -335.769458)
		(size 0.49022)
		(drill 0.254)
		(layers "F.Cu" "B.Cu")
		(net "SW_P12V_PVCCIN_CPU1_FLT")
	)
	(via
		(at 124.088906 -336.746088)
		(size 0.508)
		(drill 0.254)
		(layers "F.Cu" "B.Cu")
		(net "SW_P12V_PVCCIN_CPU1_FLT")
	)
	(via
		(at 96.52635 -349.37446)
		(size 0.508)
		(drill 0.254)
		(layers "F.Cu" "B.Cu")
		(net "SW_P12V_PVCCIN_CPU1_FLT")
	)
	(via
		(at 89.3699 -348.464632)
		(size 0.508)
		(drill 0.254)
		(layers "F.Cu" "B.Cu")
		(net "SW_P12V_PVCCIN_CPU1_FLT")
	)
	(via
		(at 108.31195 -336.827114)
		(size 0.508)
		(drill 0.254)
		(layers "F.Cu" "B.Cu")
		(net "SW_P12V_PVCCIN_CPU1_FLT")
	)
	(via
		(at 84.44865 -345.55303)
		(size 0.508)
		(drill 0.254)
		(layers "F.Cu" "B.Cu")
		(net "SW_P12V_PVCCIN_CPU1_FLT")
	)
	(via
		(at 132.080762 -339.179662)
		(size 0.49022)
		(drill 0.254)
		(layers "F.Cu" "B.Cu")
		(net "SW_P12V_PVCCIN_CPU1_FLT")
	)
	(via
		(at 92.620338 -349.37446)
		(size 0.508)
		(drill 0.254)
		(layers "F.Cu" "B.Cu")
		(net "SW_P12V_PVCCIN_CPU1_FLT")
	)
	(via
		(at 97.663254 -335.578958)
		(size 0.49022)
		(drill 0.254)
		(layers "F.Cu" "B.Cu")
		(net "SW_P12V_PVCCIN_CPU1_FLT")
	)
	(via
		(at 114.576098 -335.769458)
		(size 0.49022)
		(drill 0.254)
		(layers "F.Cu" "B.Cu")
		(net "SW_P12V_PVCCIN_CPU1_FLT")
	)
	(via
		(at 92.474542 -339.065362)
		(size 0.508)
		(drill 0.254)
		(layers "F.Cu" "B.Cu")
		(net "SW_P12V_PVCCIN_CPU1_FLT")
	)
	(via
		(at 95.76435 -350.13646)
		(size 0.508)
		(drill 0.254)
		(layers "F.Cu" "B.Cu")
		(net "SW_P12V_PVCCIN_CPU1_FLT")
	)
	(via
		(at 89.3699 -350.115632)
		(size 0.508)
		(drill 0.254)
		(layers "F.Cu" "B.Cu")
		(net "SW_P12V_PVCCIN_CPU1_FLT")
	)
	(via
		(at 82.52587 -344.779854)
		(size 0.49022)
		(drill 0.254)
		(layers "F.Cu" "B.Cu")
		(net "SW_P12V_PVCCIN_CPU1_FLT")
	)
	(via
		(at 122.73661 -335.769458)
		(size 0.49022)
		(drill 0.254)
		(layers "F.Cu" "B.Cu")
		(net "SW_P12V_PVCCIN_CPU1_FLT")
	)
	(via
		(at 116.447062 -336.065114)
		(size 0.508)
		(drill 0.254)
		(layers "F.Cu" "B.Cu")
		(net "SW_P12V_PVCCIN_CPU1_FLT")
	)
	(via
		(at 115.922298 -336.504534)
		(size 0.508)
		(drill 0.254)
		(layers "F.Cu" "B.Cu")
		(net "SW_P12V_PVCCIN_CPU1_FLT")
	)
	(via
		(at 108.84535 -336.446114)
		(size 0.508)
		(drill 0.254)
		(layers "F.Cu" "B.Cu")
		(net "SW_P12V_PVCCIN_CPU1_FLT")
	)
	(via
		(at 116.472462 -336.827114)
		(size 0.508)
		(drill 0.254)
		(layers "F.Cu" "B.Cu")
		(net "SW_P12V_PVCCIN_CPU1_FLT")
	)
	(via
		(at 93.382338 -348.48546)
		(size 0.508)
		(drill 0.254)
		(layers "F.Cu" "B.Cu")
		(net "SW_P12V_PVCCIN_CPU1_FLT")
	)
	(via
		(at 91.440762 -340.651338)
		(size 0.508)
		(drill 0.254)
		(layers "F.Cu" "B.Cu")
		(net "SW_P12V_PVCCIN_CPU1_FLT")
	)
	(via
		(at 95.76435 -350.89846)
		(size 0.508)
		(drill 0.254)
		(layers "F.Cu" "B.Cu")
		(net "SW_P12V_PVCCIN_CPU1_FLT")
	)
	(via
		(at 100.126038 -336.065114)
		(size 0.508)
		(drill 0.254)
		(layers "F.Cu" "B.Cu")
		(net "SW_P12V_PVCCIN_CPU1_FLT")
	)
	(via
		(at 139.649454 -344.779854)
		(size 0.49022)
		(drill 0.254)
		(layers "F.Cu" "B.Cu")
		(net "SW_P12V_PVCCIN_CPU1_FLT")
	)
	(via
		(at 130.897122 -339.179662)
		(size 0.49022)
		(drill 0.254)
		(layers "F.Cu" "B.Cu")
		(net "SW_P12V_PVCCIN_CPU1_FLT")
	)
	(via
		(at 93.382338 -349.37446)
		(size 0.508)
		(drill 0.254)
		(layers "F.Cu" "B.Cu")
		(net "SW_P12V_PVCCIN_CPU1_FLT")
	)
	(via
		(at 92.620338 -348.48546)
		(size 0.508)
		(drill 0.254)
		(layers "F.Cu" "B.Cu")
		(net "SW_P12V_PVCCIN_CPU1_FLT")
	)
	(via
		(at 96.52635 -350.89846)
		(size 0.508)
		(drill 0.254)
		(layers "F.Cu" "B.Cu")
		(net "SW_P12V_PVCCIN_CPU1_FLT")
	)
	(via
		(at 131.488942 -338.989162)
		(size 0.49022)
		(drill 0.254)
		(layers "F.Cu" "B.Cu")
		(net "SW_P12V_PVCCIN_CPU1_FLT")
	)
	(via
		(at 89.3699 -350.877632)
		(size 0.508)
		(drill 0.254)
		(layers "F.Cu" "B.Cu")
		(net "SW_P12V_PVCCIN_CPU1_FLT")
	)
	(via
		(at 132.243322 -340.651338)
		(size 0.508)
		(drill 0.254)
		(layers "F.Cu" "B.Cu")
		(net "SW_P12V_PVCCIN_CPU1_FLT")
	)
	(via
		(at 140.953998 -346.02801)
		(size 0.508)
		(drill 0.254)
		(layers "F.Cu" "B.Cu")
		(net "SW_P12V_PVCCIN_CPU1_FLT")
	)
	(via
		(at 92.544138 -340.576662)
		(size 0.508)
		(drill 0.254)
		(layers "F.Cu" "B.Cu")
		(net "SW_P12V_PVCCIN_CPU1_FLT")
	)
	(via
		(at 83.805014 -345.26601)
		(size 0.508)
		(drill 0.254)
		(layers "F.Cu" "B.Cu")
		(net "SW_P12V_PVCCIN_CPU1_FLT")
	)
	(via
		(at 117.005862 -337.182714)
		(size 0.508)
		(drill 0.254)
		(layers "F.Cu" "B.Cu")
		(net "SW_P12V_PVCCIN_CPU1_FLT")
	)
	(via
		(at 88.71204 -348.848172)
		(size 0.508)
		(drill 0.254)
		(layers "F.Cu" "B.Cu")
		(net "SW_P12V_PVCCIN_CPU1_FLT")
	)
	(via
		(at 140.241274 -344.970354)
		(size 0.49022)
		(drill 0.254)
		(layers "F.Cu" "B.Cu")
		(net "SW_P12V_PVCCIN_CPU1_FLT")
	)
	(via
		(at 96.52635 -350.13646)
		(size 0.508)
		(drill 0.254)
		(layers "F.Cu" "B.Cu")
		(net "SW_P12V_PVCCIN_CPU1_FLT")
	)
	(via
		(at 95.76435 -349.37446)
		(size 0.508)
		(drill 0.254)
		(layers "F.Cu" "B.Cu")
		(net "SW_P12V_PVCCIN_CPU1_FLT")
	)
	(via
		(at 108.84535 -335.709514)
		(size 0.508)
		(drill 0.254)
		(layers "F.Cu" "B.Cu")
		(net "SW_P12V_PVCCIN_CPU1_FLT")
	)
	(via
		(at 91.858338 -348.48546)
		(size 0.508)
		(drill 0.254)
		(layers "F.Cu" "B.Cu")
		(net "SW_P12V_PVCCIN_CPU1_FLT")
	)
	(via
		(at 108.84535 -337.182714)
		(size 0.508)
		(drill 0.254)
		(layers "F.Cu" "B.Cu")
		(net "SW_P12V_PVCCIN_CPU1_FLT")
	)
	(via
		(at 83.11769 -344.970354)
		(size 0.49022)
		(drill 0.254)
		(layers "F.Cu" "B.Cu")
		(net "SW_P12V_PVCCIN_CPU1_FLT")
	)
	(via
		(at 133.322568 -340.731348)
		(size 0.508)
		(drill 0.254)
		(layers "F.Cu" "B.Cu")
		(net "SW_P12V_PVCCIN_CPU1_FLT")
	)
	(via
		(at 91.858338 -349.37446)
		(size 0.508)
		(drill 0.254)
		(layers "F.Cu" "B.Cu")
		(net "SW_P12V_PVCCIN_CPU1_FLT")
	)
	(via
		(at 91.278202 -339.179662)
		(size 0.49022)
		(drill 0.254)
		(layers "F.Cu" "B.Cu")
		(net "SW_P12V_PVCCIN_CPU1_FLT")
	)
	(via
		(at 107.599226 -335.769458)
		(size 0.49022)
		(drill 0.254)
		(layers "F.Cu" "B.Cu")
		(net "SW_P12V_PVCCIN_CPU1_FLT")
	)
	(via
		(at 81.93405 -344.970354)
		(size 0.49022)
		(drill 0.254)
		(layers "F.Cu" "B.Cu")
		(net "SW_P12V_PVCCIN_CPU1_FLT")
	)
	(via
		(at 94.120208 -349.395542)
		(size 0.508)
		(drill 0.254)
		(layers "F.Cu" "B.Cu")
		(net "SW_P12V_PVCCIN_CPU1_FLT")
	)
	(via
		(at 94.120208 -348.506542)
		(size 0.508)
		(drill 0.254)
		(layers "F.Cu" "B.Cu")
		(net "SW_P12V_PVCCIN_CPU1_FLT")
	)
	(via
		(at 132.795772 -341.10422)
		(size 0.508)
		(drill 0.254)
		(layers "F.Cu" "B.Cu")
		(net "SW_P12V_PVCCIN_CPU1_FLT")
	)
	(via
		(at 132.786882 -339.060028)
		(size 0.508)
		(drill 0.254)
		(layers "F.Cu" "B.Cu")
		(net "SW_P12V_PVCCIN_CPU1_FLT")
	)
	(via
		(at 91.096338 -350.13646)
		(size 0.508)
		(drill 0.254)
		(layers "F.Cu" "B.Cu")
		(net "SW_P12V_PVCCIN_CPU1_FLT")
	)
	(via
		(at 100.151438 -336.827114)
		(size 0.508)
		(drill 0.254)
		(layers "F.Cu" "B.Cu")
		(net "SW_P12V_PVCCIN_CPU1_FLT")
	)
	(via
		(at 140.403834 -345.70543)
		(size 0.508)
		(drill 0.254)
		(layers "F.Cu" "B.Cu")
		(net "SW_P12V_PVCCIN_CPU1_FLT")
	)
	(via
		(at 141.487398 -344.91041)
		(size 0.508)
		(drill 0.254)
		(layers "F.Cu" "B.Cu")
		(net "SW_P12V_PVCCIN_CPU1_FLT")
	)
	(via
		(at 90.1319 -350.877632)
		(size 0.508)
		(drill 0.254)
		(layers "F.Cu" "B.Cu")
		(net "SW_P12V_PVCCIN_CPU1_FLT")
	)
	(via
		(at 96.52635 -348.48546)
		(size 0.508)
		(drill 0.254)
		(layers "F.Cu" "B.Cu")
		(net "SW_P12V_PVCCIN_CPU1_FLT")
	)
	(via
		(at 91.096338 -349.37446)
		(size 0.508)
		(drill 0.254)
		(layers "F.Cu" "B.Cu")
		(net "SW_P12V_PVCCIN_CPU1_FLT")
	)
	(via
		(at 105.823766 -335.578958)
		(size 0.49022)
		(drill 0.254)
		(layers "F.Cu" "B.Cu")
		(net "SW_P12V_PVCCIN_CPU1_FLT")
	)
	(via
		(at 133.352032 -339.416898)
		(size 0.508)
		(drill 0.254)
		(layers "F.Cu" "B.Cu")
		(net "SW_P12V_PVCCIN_CPU1_FLT")
	)
	(via
		(at 84.44865 -346.28963)
		(size 0.508)
		(drill 0.254)
		(layers "F.Cu" "B.Cu")
		(net "SW_P12V_PVCCIN_CPU1_FLT")
	)
	(via
		(at 113.984278 -335.578958)
		(size 0.49022)
		(drill 0.254)
		(layers "F.Cu" "B.Cu")
		(net "SW_P12V_PVCCIN_CPU1_FLT")
	)
	(via
		(at 130.305302 -338.989162)
		(size 0.49022)
		(drill 0.254)
		(layers "F.Cu" "B.Cu")
		(net "SW_P12V_PVCCIN_CPU1_FLT")
	)
	(via
		(at 125.191012 -335.944972)
		(size 0.508)
		(drill 0.254)
		(layers "F.Cu" "B.Cu")
		(net "SW_P12V_PVCCIN_CPU1_FLT")
	)
	(via
		(at 84.44865 -344.91803)
		(size 0.508)
		(drill 0.254)
		(layers "F.Cu" "B.Cu")
		(net "SW_P12V_PVCCIN_CPU1_FLT")
	)
	(via
		(at 115.922298 -337.241134)
		(size 0.508)
		(drill 0.254)
		(layers "F.Cu" "B.Cu")
		(net "SW_P12V_PVCCIN_CPU1_FLT")
	)
	(via
		(at 124.632212 -336.300572)
		(size 0.508)
		(drill 0.254)
		(layers "F.Cu" "B.Cu")
		(net "SW_P12V_PVCCIN_CPU1_FLT")
	)
	(via
		(at 94.877128 -350.163892)
		(size 0.508)
		(drill 0.254)
		(layers "F.Cu" "B.Cu")
		(net "SW_P12V_PVCCIN_CPU1_FLT")
	)
	(via
		(at 108.28655 -336.065114)
		(size 0.508)
		(drill 0.254)
		(layers "F.Cu" "B.Cu")
		(net "SW_P12V_PVCCIN_CPU1_FLT")
	)
	(via
		(at 81.34223 -344.779854)
		(size 0.49022)
		(drill 0.254)
		(layers "F.Cu" "B.Cu")
		(net "SW_P12V_PVCCIN_CPU1_FLT")
	)
	(via
		(at 91.985338 -339.484462)
		(size 0.508)
		(drill 0.254)
		(layers "F.Cu" "B.Cu")
		(net "SW_P12V_PVCCIN_CPU1_FLT")
	)
	(via
		(at 125.191012 -337.418172)
		(size 0.508)
		(drill 0.254)
		(layers "F.Cu" "B.Cu")
		(net "SW_P12V_PVCCIN_CPU1_FLT")
	)
	(via
		(at 125.191012 -336.681572)
		(size 0.508)
		(drill 0.254)
		(layers "F.Cu" "B.Cu")
		(net "SW_P12V_PVCCIN_CPU1_FLT")
	)
	(via
		(at 83.28025 -345.70543)
		(size 0.508)
		(drill 0.254)
		(layers "F.Cu" "B.Cu")
		(net "SW_P12V_PVCCIN_CPU1_FLT")
	)
	(via
		(at 88.71204 -350.499172)
		(size 0.508)
		(drill 0.254)
		(layers "F.Cu" "B.Cu")
		(net "SW_P12V_PVCCIN_CPU1_FLT")
	)
	(via
		(at 107.007406 -335.578958)
		(size 0.49022)
		(drill 0.254)
		(layers "F.Cu" "B.Cu")
		(net "SW_P12V_PVCCIN_CPU1_FLT")
	)
	(via
		(at 140.403834 -346.44203)
		(size 0.508)
		(drill 0.254)
		(layers "F.Cu" "B.Cu")
		(net "SW_P12V_PVCCIN_CPU1_FLT")
	)
	(via
		(at 117.005862 -335.709514)
		(size 0.508)
		(drill 0.254)
		(layers "F.Cu" "B.Cu")
		(net "SW_P12V_PVCCIN_CPU1_FLT")
	)
	(via
		(at 115.167918 -335.578958)
		(size 0.49022)
		(drill 0.254)
		(layers "F.Cu" "B.Cu")
		(net "SW_P12V_PVCCIN_CPU1_FLT")
	)
	(via
		(at 132.793486 -340.237318)
		(size 0.508)
		(drill 0.254)
		(layers "F.Cu" "B.Cu")
		(net "SW_P12V_PVCCIN_CPU1_FLT")
	)
	(via
		(at 100.684838 -335.709514)
		(size 0.508)
		(drill 0.254)
		(layers "F.Cu" "B.Cu")
		(net "SW_P12V_PVCCIN_CPU1_FLT")
	)
	(via
		(at 88.71204 -349.737172)
		(size 0.508)
		(drill 0.254)
		(layers "F.Cu" "B.Cu")
		(net "SW_P12V_PVCCIN_CPU1_FLT")
	)
	(via
		(at 122.14479 -335.578958)
		(size 0.49022)
		(drill 0.254)
		(layers "F.Cu" "B.Cu")
		(net "SW_P12V_PVCCIN_CPU1_FLT")
	)
	(via
		(at 99.438714 -335.769458)
		(size 0.49022)
		(drill 0.254)
		(layers "F.Cu" "B.Cu")
		(net "SW_P12V_PVCCIN_CPU1_FLT")
	)
	(via
		(at 99.601274 -336.504534)
		(size 0.508)
		(drill 0.254)
		(layers "F.Cu" "B.Cu")
		(net "SW_P12V_PVCCIN_CPU1_FLT")
	)
	(via
		(at 123.92025 -335.769458)
		(size 0.49022)
		(drill 0.254)
		(layers "F.Cu" "B.Cu")
		(net "SW_P12V_PVCCIN_CPU1_FLT")
	)
	(via
		(at 94.882208 -348.506542)
		(size 0.508)
		(drill 0.254)
		(layers "F.Cu" "B.Cu")
		(net "SW_P12V_PVCCIN_CPU1_FLT")
	)
	(segment
		(start 119.150892 -342.99144)
		(end 120.0658 -343.906348)
		(width 0.508)
		(layer "B.Cu")
		(net "SW_P12V_PVCCIN_CPU1_FLT")
	)
	(segment
		(start 120.0658 -343.906348)
		(end 120.980708 -342.99144)
		(width 0.508)
		(layer "B.Cu")
		(net "SW_P12V_PVCCIN_CPU1_FLT")
	)
	(segment
		(start 103.984552 -344.944192)
		(end 104.89946 -344.029284)
		(width 0.508)
		(layer "B.Cu")
		(net "SW_P12V_PVCCIN_CPU1_FLT")
	)
	(segment
		(start 96.423988 -344.944192)
		(end 97.338896 -344.029284)
		(width 0.508)
		(layer "B.Cu")
		(net "SW_P12V_PVCCIN_CPU1_FLT")
	)
	(segment
		(start 115.569492 -351.349056)
		(end 116.4844 -350.434148)
		(width 0.508)
		(layer "B.Cu")
		(net "SW_P12V_PVCCIN_CPU1_FLT")
	)
	(segment
		(start 115.569492 -349.51924)
		(end 116.4844 -350.434148)
		(width 0.508)
		(layer "B.Cu")
		(net "SW_P12V_PVCCIN_CPU1_FLT")
	)
	(segment
		(start 97.338896 -344.029284)
		(end 98.253804 -343.114376)
		(width 0.508)
		(layer "B.Cu")
		(net "SW_P12V_PVCCIN_CPU1_FLT")
	)
	(segment
		(start 119.150892 -344.821256)
		(end 120.0658 -343.906348)
		(width 0.508)
		(layer "B.Cu")
		(net "SW_P12V_PVCCIN_CPU1_FLT")
	)
	(segment
		(start 111.689896 -344.944192)
		(end 112.604804 -344.029284)
		(width 0.508)
		(layer "B.Cu")
		(net "SW_P12V_PVCCIN_CPU1_FLT")
	)
	(segment
		(start 120.0658 -343.906348)
		(end 120.980708 -344.821256)
		(width 0.508)
		(layer "B.Cu")
		(net "SW_P12V_PVCCIN_CPU1_FLT")
	)
	(segment
		(start 104.89946 -344.029284)
		(end 105.814368 -343.114376)
		(width 0.508)
		(layer "B.Cu")
		(net "SW_P12V_PVCCIN_CPU1_FLT")
	)
	(segment
		(start 116.4844 -350.434148)
		(end 117.399308 -349.51924)
		(width 0.508)
		(layer "B.Cu")
		(net "SW_P12V_PVCCIN_CPU1_FLT")
	)
	(segment
		(start 104.89946 -344.029284)
		(end 105.814368 -344.944192)
		(width 0.508)
		(layer "B.Cu")
		(net "SW_P12V_PVCCIN_CPU1_FLT")
	)
	(segment
		(start 96.423988 -343.114376)
		(end 97.338896 -344.029284)
		(width 0.508)
		(layer "B.Cu")
		(net "SW_P12V_PVCCIN_CPU1_FLT")
	)
	(segment
		(start 111.689896 -343.114376)
		(end 112.604804 -344.029284)
		(width 0.508)
		(layer "B.Cu")
		(net "SW_P12V_PVCCIN_CPU1_FLT")
	)
	(segment
		(start 97.338896 -344.029284)
		(end 98.253804 -344.944192)
		(width 0.508)
		(layer "B.Cu")
		(net "SW_P12V_PVCCIN_CPU1_FLT")
	)
	(segment
		(start 112.604804 -344.029284)
		(end 113.519712 -343.114376)
		(width 0.508)
		(layer "B.Cu")
		(net "SW_P12V_PVCCIN_CPU1_FLT")
	)
	(segment
		(start 112.604804 -344.029284)
		(end 113.519712 -344.944192)
		(width 0.508)
		(layer "B.Cu")
		(net "SW_P12V_PVCCIN_CPU1_FLT")
	)
	(segment
		(start 116.4844 -350.434148)
		(end 117.399308 -351.349056)
		(width 0.508)
		(layer "B.Cu")
		(net "SW_P12V_PVCCIN_CPU1_FLT")
	)
	(segment
		(start 103.984552 -343.114376)
		(end 104.89946 -344.029284)
		(width 0.508)
		(layer "B.Cu")
		(net "SW_P12V_PVCCIN_CPU1_FLT")
	)
	(segment
		(start 363.270292 -349.34144)
		(end 364.2868 -350.357948)
		(width 0.508)
		(layer "F.Cu")
		(net "SW_P12V_PVCCIN_CPU0_FLT")
	)
	(segment
		(start 364.2868 -350.357948)
		(end 365.303308 -349.34144)
		(width 0.508)
		(layer "F.Cu")
		(net "SW_P12V_PVCCIN_CPU0_FLT")
	)
	(segment
		(start 368.105182 -343.902284)
		(end 369.12169 -342.885776)
		(width 0.508)
		(layer "F.Cu")
		(net "SW_P12V_PVCCIN_CPU0_FLT")
	)
	(segment
		(start 359.52811 -344.918792)
		(end 360.544618 -343.902284)
		(width 0.508)
		(layer "F.Cu")
		(net "SW_P12V_PVCCIN_CPU0_FLT")
	)
	(segment
		(start 359.52811 -342.885776)
		(end 360.544618 -343.902284)
		(width 0.508)
		(layer "F.Cu")
		(net "SW_P12V_PVCCIN_CPU0_FLT")
	)
	(segment
		(start 368.105182 -343.902284)
		(end 369.12169 -344.918792)
		(width 0.508)
		(layer "F.Cu")
		(net "SW_P12V_PVCCIN_CPU0_FLT")
	)
	(segment
		(start 351.822766 -344.918792)
		(end 352.839274 -343.902284)
		(width 0.508)
		(layer "F.Cu")
		(net "SW_P12V_PVCCIN_CPU0_FLT")
	)
	(segment
		(start 360.544618 -343.902284)
		(end 361.561126 -342.885776)
		(width 0.508)
		(layer "F.Cu")
		(net "SW_P12V_PVCCIN_CPU0_FLT")
	)
	(segment
		(start 367.088674 -342.885776)
		(end 368.105182 -343.902284)
		(width 0.508)
		(layer "F.Cu")
		(net "SW_P12V_PVCCIN_CPU0_FLT")
	)
	(segment
		(start 352.839274 -343.902284)
		(end 353.855782 -342.885776)
		(width 0.508)
		(layer "F.Cu")
		(net "SW_P12V_PVCCIN_CPU0_FLT")
	)
	(segment
		(start 363.270292 -351.374456)
		(end 364.2868 -350.357948)
		(width 0.508)
		(layer "F.Cu")
		(net "SW_P12V_PVCCIN_CPU0_FLT")
	)
	(segment
		(start 364.2868 -350.357948)
		(end 365.303308 -351.374456)
		(width 0.508)
		(layer "F.Cu")
		(net "SW_P12V_PVCCIN_CPU0_FLT")
	)
	(segment
		(start 360.544618 -343.902284)
		(end 361.561126 -344.918792)
		(width 0.508)
		(layer "F.Cu")
		(net "SW_P12V_PVCCIN_CPU0_FLT")
	)
	(segment
		(start 367.088674 -344.918792)
		(end 368.105182 -343.902284)
		(width 0.508)
		(layer "F.Cu")
		(net "SW_P12V_PVCCIN_CPU0_FLT")
	)
	(segment
		(start 344.262202 -342.885776)
		(end 345.27871 -343.902284)
		(width 0.508)
		(layer "F.Cu")
		(net "SW_P12V_PVCCIN_CPU0_FLT")
	)
	(segment
		(start 344.262202 -344.918792)
		(end 345.27871 -343.902284)
		(width 0.508)
		(layer "F.Cu")
		(net "SW_P12V_PVCCIN_CPU0_FLT")
	)
	(segment
		(start 352.839274 -343.902284)
		(end 353.855782 -344.918792)
		(width 0.508)
		(layer "F.Cu")
		(net "SW_P12V_PVCCIN_CPU0_FLT")
	)
	(segment
		(start 351.822766 -342.885776)
		(end 352.839274 -343.902284)
		(width 0.508)
		(layer "F.Cu")
		(net "SW_P12V_PVCCIN_CPU0_FLT")
	)
	(segment
		(start 345.27871 -343.902284)
		(end 346.295218 -342.885776)
		(width 0.508)
		(layer "F.Cu")
		(net "SW_P12V_PVCCIN_CPU0_FLT")
	)
	(segment
		(start 345.27871 -343.902284)
		(end 346.295218 -344.918792)
		(width 0.508)
		(layer "F.Cu")
		(net "SW_P12V_PVCCIN_CPU0_FLT")
	)
	(via
		(at 341.933022 -348.620842)
		(size 0.508)
		(drill 0.254)
		(layers "F.Cu" "B.Cu")
		(net "SW_P12V_PVCCIN_CPU0_FLT")
	)
	(via
		(at 361.924092 -335.578958)
		(size 0.49022)
		(drill 0.254)
		(layers "F.Cu" "B.Cu")
		(net "SW_P12V_PVCCIN_CPU0_FLT")
	)
	(via
		(at 347.541088 -336.504534)
		(size 0.508)
		(drill 0.254)
		(layers "F.Cu" "B.Cu")
		(net "SW_P12V_PVCCIN_CPU0_FLT")
	)
	(via
		(at 338.909152 -348.59976)
		(size 0.508)
		(drill 0.254)
		(layers "F.Cu" "B.Cu")
		(net "SW_P12V_PVCCIN_CPU0_FLT")
	)
	(via
		(at 338.034376 -339.179662)
		(size 0.49022)
		(drill 0.254)
		(layers "F.Cu" "B.Cu")
		(net "SW_P12V_PVCCIN_CPU0_FLT")
	)
	(via
		(at 378.836936 -339.179662)
		(size 0.49022)
		(drill 0.254)
		(layers "F.Cu" "B.Cu")
		(net "SW_P12V_PVCCIN_CPU0_FLT")
	)
	(via
		(at 380.020576 -339.179662)
		(size 0.49022)
		(drill 0.254)
		(layers "F.Cu" "B.Cu")
		(net "SW_P12V_PVCCIN_CPU0_FLT")
	)
	(via
		(at 340.433152 -348.59976)
		(size 0.508)
		(drill 0.254)
		(layers "F.Cu" "B.Cu")
		(net "SW_P12V_PVCCIN_CPU0_FLT")
	)
	(via
		(at 389.427212 -346.38361)
		(size 0.508)
		(drill 0.254)
		(layers "F.Cu" "B.Cu")
		(net "SW_P12V_PVCCIN_CPU0_FLT")
	)
	(via
		(at 364.386876 -336.065114)
		(size 0.508)
		(drill 0.254)
		(layers "F.Cu" "B.Cu")
		(net "SW_P12V_PVCCIN_CPU0_FLT")
	)
	(via
		(at 355.7016 -336.504534)
		(size 0.508)
		(drill 0.254)
		(layers "F.Cu" "B.Cu")
		(net "SW_P12V_PVCCIN_CPU0_FLT")
	)
	(via
		(at 348.624652 -337.182714)
		(size 0.508)
		(drill 0.254)
		(layers "F.Cu" "B.Cu")
		(net "SW_P12V_PVCCIN_CPU0_FLT")
	)
	(via
		(at 381.291846 -339.416898)
		(size 0.508)
		(drill 0.254)
		(layers "F.Cu" "B.Cu")
		(net "SW_P12V_PVCCIN_CPU0_FLT")
	)
	(via
		(at 353.76358 -335.578958)
		(size 0.49022)
		(drill 0.254)
		(layers "F.Cu" "B.Cu")
		(net "SW_P12V_PVCCIN_CPU0_FLT")
	)
	(via
		(at 386.997448 -344.970354)
		(size 0.49022)
		(drill 0.254)
		(layers "F.Cu" "B.Cu")
		(net "SW_P12V_PVCCIN_CPU0_FLT")
	)
	(via
		(at 347.541088 -337.241134)
		(size 0.508)
		(drill 0.254)
		(layers "F.Cu" "B.Cu")
		(net "SW_P12V_PVCCIN_CPU0_FLT")
	)
	(via
		(at 355.7016 -337.241134)
		(size 0.508)
		(drill 0.254)
		(layers "F.Cu" "B.Cu")
		(net "SW_P12V_PVCCIN_CPU0_FLT")
	)
	(via
		(at 343.577164 -349.48876)
		(size 0.508)
		(drill 0.254)
		(layers "F.Cu" "B.Cu")
		(net "SW_P12V_PVCCIN_CPU0_FLT")
	)
	(via
		(at 329.904344 -345.030298)
		(size 0.49022)
		(drill 0.254)
		(layers "F.Cu" "B.Cu")
		(net "SW_P12V_PVCCIN_CPU0_FLT")
	)
	(via
		(at 363.699552 -335.769458)
		(size 0.49022)
		(drill 0.254)
		(layers "F.Cu" "B.Cu")
		(net "SW_P12V_PVCCIN_CPU0_FLT")
	)
	(via
		(at 381.262382 -340.731348)
		(size 0.508)
		(drill 0.254)
		(layers "F.Cu" "B.Cu")
		(net "SW_P12V_PVCCIN_CPU0_FLT")
	)
	(via
		(at 389.427212 -344.91041)
		(size 0.508)
		(drill 0.254)
		(layers "F.Cu" "B.Cu")
		(net "SW_P12V_PVCCIN_CPU0_FLT")
	)
	(via
		(at 389.427212 -345.64701)
		(size 0.508)
		(drill 0.254)
		(layers "F.Cu" "B.Cu")
		(net "SW_P12V_PVCCIN_CPU0_FLT")
	)
	(via
		(at 347.37929 -335.509616)
		(size 0.49022)
		(drill 0.254)
		(layers "F.Cu" "B.Cu")
		(net "SW_P12V_PVCCIN_CPU0_FLT")
	)
	(via
		(at 388.343648 -345.70543)
		(size 0.508)
		(drill 0.254)
		(layers "F.Cu" "B.Cu")
		(net "SW_P12V_PVCCIN_CPU0_FLT")
	)
	(via
		(at 331.220064 -346.44203)
		(size 0.508)
		(drill 0.254)
		(layers "F.Cu" "B.Cu")
		(net "SW_P12V_PVCCIN_CPU0_FLT")
	)
	(via
		(at 340.483952 -340.576662)
		(size 0.508)
		(drill 0.254)
		(layers "F.Cu" "B.Cu")
		(net "SW_P12V_PVCCIN_CPU0_FLT")
	)
	(via
		(at 331.087984 -345.030298)
		(size 0.49022)
		(drill 0.254)
		(layers "F.Cu" "B.Cu")
		(net "SW_P12V_PVCCIN_CPU0_FLT")
	)
	(via
		(at 354.3554 -335.769458)
		(size 0.49022)
		(drill 0.254)
		(layers "F.Cu" "B.Cu")
		(net "SW_P12V_PVCCIN_CPU0_FLT")
	)
	(via
		(at 345.590622 -335.755488)
		(size 0.49022)
		(drill 0.254)
		(layers "F.Cu" "B.Cu")
		(net "SW_P12V_PVCCIN_CPU0_FLT")
	)
	(via
		(at 378.245116 -338.989162)
		(size 0.49022)
		(drill 0.254)
		(layers "F.Cu" "B.Cu")
		(net "SW_P12V_PVCCIN_CPU0_FLT")
	)
	(via
		(at 329.312524 -344.839798)
		(size 0.49022)
		(drill 0.254)
		(layers "F.Cu" "B.Cu")
		(net "SW_P12V_PVCCIN_CPU0_FLT")
	)
	(via
		(at 340.433152 -349.48876)
		(size 0.508)
		(drill 0.254)
		(layers "F.Cu" "B.Cu")
		(net "SW_P12V_PVCCIN_CPU0_FLT")
	)
	(via
		(at 372.02872 -336.746088)
		(size 0.508)
		(drill 0.254)
		(layers "F.Cu" "B.Cu")
		(net "SW_P12V_PVCCIN_CPU0_FLT")
	)
	(via
		(at 339.218016 -339.179662)
		(size 0.49022)
		(drill 0.254)
		(layers "F.Cu" "B.Cu")
		(net "SW_P12V_PVCCIN_CPU0_FLT")
	)
	(via
		(at 339.380576 -339.914738)
		(size 0.508)
		(drill 0.254)
		(layers "F.Cu" "B.Cu")
		(net "SW_P12V_PVCCIN_CPU0_FLT")
	)
	(via
		(at 380.726696 -339.060028)
		(size 0.508)
		(drill 0.254)
		(layers "F.Cu" "B.Cu")
		(net "SW_P12V_PVCCIN_CPU0_FLT")
	)
	(via
		(at 337.442556 -338.989162)
		(size 0.49022)
		(drill 0.254)
		(layers "F.Cu" "B.Cu")
		(net "SW_P12V_PVCCIN_CPU0_FLT")
	)
	(via
		(at 348.624652 -336.446114)
		(size 0.508)
		(drill 0.254)
		(layers "F.Cu" "B.Cu")
		(net "SW_P12V_PVCCIN_CPU0_FLT")
	)
	(via
		(at 371.860064 -335.769458)
		(size 0.49022)
		(drill 0.254)
		(layers "F.Cu" "B.Cu")
		(net "SW_P12V_PVCCIN_CPU0_FLT")
	)
	(via
		(at 380.183136 -339.914738)
		(size 0.508)
		(drill 0.254)
		(layers "F.Cu" "B.Cu")
		(net "SW_P12V_PVCCIN_CPU0_FLT")
	)
	(via
		(at 332.388464 -345.55303)
		(size 0.508)
		(drill 0.254)
		(layers "F.Cu" "B.Cu")
		(net "SW_P12V_PVCCIN_CPU0_FLT")
	)
	(via
		(at 342.815164 -349.48876)
		(size 0.508)
		(drill 0.254)
		(layers "F.Cu" "B.Cu")
		(net "SW_P12V_PVCCIN_CPU0_FLT")
	)
	(via
		(at 341.933022 -349.509842)
		(size 0.508)
		(drill 0.254)
		(layers "F.Cu" "B.Cu")
		(net "SW_P12V_PVCCIN_CPU0_FLT")
	)
	(via
		(at 336.420714 -348.655132)
		(size 0.508)
		(drill 0.254)
		(layers "F.Cu" "B.Cu")
		(net "SW_P12V_PVCCIN_CPU0_FLT")
	)
	(via
		(at 373.130826 -337.418172)
		(size 0.508)
		(drill 0.254)
		(layers "F.Cu" "B.Cu")
		(net "SW_P12V_PVCCIN_CPU0_FLT")
	)
	(via
		(at 339.925152 -340.271862)
		(size 0.508)
		(drill 0.254)
		(layers "F.Cu" "B.Cu")
		(net "SW_P12V_PVCCIN_CPU0_FLT")
	)
	(via
		(at 338.147152 -350.15424)
		(size 0.508)
		(drill 0.254)
		(layers "F.Cu" "B.Cu")
		(net "SW_P12V_PVCCIN_CPU0_FLT")
	)
	(via
		(at 370.676424 -335.769458)
		(size 0.49022)
		(drill 0.254)
		(layers "F.Cu" "B.Cu")
		(net "SW_P12V_PVCCIN_CPU0_FLT")
	)
	(via
		(at 337.182714 -350.895412)
		(size 0.508)
		(drill 0.254)
		(layers "F.Cu" "B.Cu")
		(net "SW_P12V_PVCCIN_CPU0_FLT")
	)
	(via
		(at 332.388464 -346.28963)
		(size 0.508)
		(drill 0.254)
		(layers "F.Cu" "B.Cu")
		(net "SW_P12V_PVCCIN_CPU0_FLT")
	)
	(via
		(at 363.107732 -335.578958)
		(size 0.49022)
		(drill 0.254)
		(layers "F.Cu" "B.Cu")
		(net "SW_P12V_PVCCIN_CPU0_FLT")
	)
	(via
		(at 387.589268 -344.779854)
		(size 0.49022)
		(drill 0.254)
		(layers "F.Cu" "B.Cu")
		(net "SW_P12V_PVCCIN_CPU0_FLT")
	)
	(via
		(at 340.414356 -339.052662)
		(size 0.508)
		(drill 0.254)
		(layers "F.Cu" "B.Cu")
		(net "SW_P12V_PVCCIN_CPU0_FLT")
	)
	(via
		(at 343.577164 -350.91624)
		(size 0.508)
		(drill 0.254)
		(layers "F.Cu" "B.Cu")
		(net "SW_P12V_PVCCIN_CPU0_FLT")
	)
	(via
		(at 380.735586 -341.10422)
		(size 0.508)
		(drill 0.254)
		(layers "F.Cu" "B.Cu")
		(net "SW_P12V_PVCCIN_CPU0_FLT")
	)
	(via
		(at 388.343648 -346.44203)
		(size 0.508)
		(drill 0.254)
		(layers "F.Cu" "B.Cu")
		(net "SW_P12V_PVCCIN_CPU0_FLT")
	)
	(via
		(at 362.515912 -335.769458)
		(size 0.49022)
		(drill 0.254)
		(layers "F.Cu" "B.Cu")
		(net "SW_P12V_PVCCIN_CPU0_FLT")
	)
	(via
		(at 342.815164 -350.91624)
		(size 0.508)
		(drill 0.254)
		(layers "F.Cu" "B.Cu")
		(net "SW_P12V_PVCCIN_CPU0_FLT")
	)
	(via
		(at 370.084604 -335.578958)
		(size 0.49022)
		(drill 0.254)
		(layers "F.Cu" "B.Cu")
		(net "SW_P12V_PVCCIN_CPU0_FLT")
	)
	(via
		(at 338.626196 -338.989162)
		(size 0.49022)
		(drill 0.254)
		(layers "F.Cu" "B.Cu")
		(net "SW_P12V_PVCCIN_CPU0_FLT")
	)
	(via
		(at 342.815164 -350.15424)
		(size 0.508)
		(drill 0.254)
		(layers "F.Cu" "B.Cu")
		(net "SW_P12V_PVCCIN_CPU0_FLT")
	)
	(via
		(at 331.220064 -345.70543)
		(size 0.508)
		(drill 0.254)
		(layers "F.Cu" "B.Cu")
		(net "SW_P12V_PVCCIN_CPU0_FLT")
	)
	(via
		(at 363.862112 -337.241134)
		(size 0.508)
		(drill 0.254)
		(layers "F.Cu" "B.Cu")
		(net "SW_P12V_PVCCIN_CPU0_FLT")
	)
	(via
		(at 372.572026 -336.300572)
		(size 0.508)
		(drill 0.254)
		(layers "F.Cu" "B.Cu")
		(net "SW_P12V_PVCCIN_CPU0_FLT")
	)
	(via
		(at 343.577164 -350.15424)
		(size 0.508)
		(drill 0.254)
		(layers "F.Cu" "B.Cu")
		(net "SW_P12V_PVCCIN_CPU0_FLT")
	)
	(via
		(at 336.420714 -350.895412)
		(size 0.508)
		(drill 0.254)
		(layers "F.Cu" "B.Cu")
		(net "SW_P12V_PVCCIN_CPU0_FLT")
	)
	(via
		(at 372.597426 -337.062572)
		(size 0.508)
		(drill 0.254)
		(layers "F.Cu" "B.Cu")
		(net "SW_P12V_PVCCIN_CPU0_FLT")
	)
	(via
		(at 356.785164 -335.709514)
		(size 0.508)
		(drill 0.254)
		(layers "F.Cu" "B.Cu")
		(net "SW_P12V_PVCCIN_CPU0_FLT")
	)
	(via
		(at 337.182714 -350.133412)
		(size 0.508)
		(drill 0.254)
		(layers "F.Cu" "B.Cu")
		(net "SW_P12V_PVCCIN_CPU0_FLT")
	)
	(via
		(at 339.671152 -349.48876)
		(size 0.508)
		(drill 0.254)
		(layers "F.Cu" "B.Cu")
		(net "SW_P12V_PVCCIN_CPU0_FLT")
	)
	(via
		(at 336.420714 -349.467932)
		(size 0.508)
		(drill 0.254)
		(layers "F.Cu" "B.Cu")
		(net "SW_P12V_PVCCIN_CPU0_FLT")
	)
	(via
		(at 380.7333 -340.237318)
		(size 0.508)
		(drill 0.254)
		(layers "F.Cu" "B.Cu")
		(net "SW_P12V_PVCCIN_CPU0_FLT")
	)
	(via
		(at 388.893812 -346.02801)
		(size 0.508)
		(drill 0.254)
		(layers "F.Cu" "B.Cu")
		(net "SW_P12V_PVCCIN_CPU0_FLT")
	)
	(via
		(at 388.868412 -345.26601)
		(size 0.508)
		(drill 0.254)
		(layers "F.Cu" "B.Cu")
		(net "SW_P12V_PVCCIN_CPU0_FLT")
	)
	(via
		(at 348.624652 -335.709514)
		(size 0.508)
		(drill 0.254)
		(layers "F.Cu" "B.Cu")
		(net "SW_P12V_PVCCIN_CPU0_FLT")
	)
	(via
		(at 372.02872 -337.482688)
		(size 0.508)
		(drill 0.254)
		(layers "F.Cu" "B.Cu")
		(net "SW_P12V_PVCCIN_CPU0_FLT")
	)
	(via
		(at 380.183136 -340.651338)
		(size 0.508)
		(drill 0.254)
		(layers "F.Cu" "B.Cu")
		(net "SW_P12V_PVCCIN_CPU0_FLT")
	)
	(via
		(at 348.091252 -336.827114)
		(size 0.508)
		(drill 0.254)
		(layers "F.Cu" "B.Cu")
		(net "SW_P12V_PVCCIN_CPU0_FLT")
	)
	(via
		(at 373.130826 -336.681572)
		(size 0.508)
		(drill 0.254)
		(layers "F.Cu" "B.Cu")
		(net "SW_P12V_PVCCIN_CPU0_FLT")
	)
	(via
		(at 363.862112 -336.504534)
		(size 0.508)
		(drill 0.254)
		(layers "F.Cu" "B.Cu")
		(net "SW_P12V_PVCCIN_CPU0_FLT")
	)
	(via
		(at 336.420714 -350.133412)
		(size 0.508)
		(drill 0.254)
		(layers "F.Cu" "B.Cu")
		(net "SW_P12V_PVCCIN_CPU0_FLT")
	)
	(via
		(at 356.251764 -336.827114)
		(size 0.508)
		(drill 0.254)
		(layers "F.Cu" "B.Cu")
		(net "SW_P12V_PVCCIN_CPU0_FLT")
	)
	(via
		(at 364.945676 -337.182714)
		(size 0.508)
		(drill 0.254)
		(layers "F.Cu" "B.Cu")
		(net "SW_P12V_PVCCIN_CPU0_FLT")
	)
	(via
		(at 341.171022 -349.509842)
		(size 0.508)
		(drill 0.254)
		(layers "F.Cu" "B.Cu")
		(net "SW_P12V_PVCCIN_CPU0_FLT")
	)
	(via
		(at 348.065852 -336.065114)
		(size 0.508)
		(drill 0.254)
		(layers "F.Cu" "B.Cu")
		(net "SW_P12V_PVCCIN_CPU0_FLT")
	)
	(via
		(at 386.405628 -344.779854)
		(size 0.49022)
		(drill 0.254)
		(layers "F.Cu" "B.Cu")
		(net "SW_P12V_PVCCIN_CPU0_FLT")
	)
	(via
		(at 338.909152 -349.48876)
		(size 0.508)
		(drill 0.254)
		(layers "F.Cu" "B.Cu")
		(net "SW_P12V_PVCCIN_CPU0_FLT")
	)
	(via
		(at 339.925152 -339.484462)
		(size 0.508)
		(drill 0.254)
		(layers "F.Cu" "B.Cu")
		(net "SW_P12V_PVCCIN_CPU0_FLT")
	)
	(via
		(at 373.130826 -335.944972)
		(size 0.508)
		(drill 0.254)
		(layers "F.Cu" "B.Cu")
		(net "SW_P12V_PVCCIN_CPU0_FLT")
	)
	(via
		(at 338.147152 -349.48876)
		(size 0.508)
		(drill 0.254)
		(layers "F.Cu" "B.Cu")
		(net "SW_P12V_PVCCIN_CPU0_FLT")
	)
	(via
		(at 356.785164 -336.446114)
		(size 0.508)
		(drill 0.254)
		(layers "F.Cu" "B.Cu")
		(net "SW_P12V_PVCCIN_CPU0_FLT")
	)
	(via
		(at 330.496164 -344.839798)
		(size 0.49022)
		(drill 0.254)
		(layers "F.Cu" "B.Cu")
		(net "SW_P12V_PVCCIN_CPU0_FLT")
	)
	(via
		(at 337.182714 -349.467932)
		(size 0.508)
		(drill 0.254)
		(layers "F.Cu" "B.Cu")
		(net "SW_P12V_PVCCIN_CPU0_FLT")
	)
	(via
		(at 332.388464 -344.91803)
		(size 0.508)
		(drill 0.254)
		(layers "F.Cu" "B.Cu")
		(net "SW_P12V_PVCCIN_CPU0_FLT")
	)
	(via
		(at 339.380576 -340.651338)
		(size 0.508)
		(drill 0.254)
		(layers "F.Cu" "B.Cu")
		(net "SW_P12V_PVCCIN_CPU0_FLT")
	)
	(via
		(at 337.182714 -348.578932)
		(size 0.508)
		(drill 0.254)
		(layers "F.Cu" "B.Cu")
		(net "SW_P12V_PVCCIN_CPU0_FLT")
	)
	(via
		(at 371.268244 -335.578958)
		(size 0.49022)
		(drill 0.254)
		(layers "F.Cu" "B.Cu")
		(net "SW_P12V_PVCCIN_CPU0_FLT")
	)
	(via
		(at 341.171022 -348.620842)
		(size 0.508)
		(drill 0.254)
		(layers "F.Cu" "B.Cu")
		(net "SW_P12V_PVCCIN_CPU0_FLT")
	)
	(via
		(at 364.945676 -335.709514)
		(size 0.508)
		(drill 0.254)
		(layers "F.Cu" "B.Cu")
		(net "SW_P12V_PVCCIN_CPU0_FLT")
	)
	(via
		(at 354.94722 -335.578958)
		(size 0.49022)
		(drill 0.254)
		(layers "F.Cu" "B.Cu")
		(net "SW_P12V_PVCCIN_CPU0_FLT")
	)
	(via
		(at 364.412276 -336.827114)
		(size 0.508)
		(drill 0.254)
		(layers "F.Cu" "B.Cu")
		(net "SW_P12V_PVCCIN_CPU0_FLT")
	)
	(via
		(at 379.428756 -338.989162)
		(size 0.49022)
		(drill 0.254)
		(layers "F.Cu" "B.Cu")
		(net "SW_P12V_PVCCIN_CPU0_FLT")
	)
	(via
		(at 356.226364 -336.065114)
		(size 0.508)
		(drill 0.254)
		(layers "F.Cu" "B.Cu")
		(net "SW_P12V_PVCCIN_CPU0_FLT")
	)
	(via
		(at 388.181088 -344.970354)
		(size 0.49022)
		(drill 0.254)
		(layers "F.Cu" "B.Cu")
		(net "SW_P12V_PVCCIN_CPU0_FLT")
	)
	(via
		(at 340.46414 -339.856318)
		(size 0.508)
		(drill 0.254)
		(layers "F.Cu" "B.Cu")
		(net "SW_P12V_PVCCIN_CPU0_FLT")
	)
	(via
		(at 355.53904 -335.769458)
		(size 0.49022)
		(drill 0.254)
		(layers "F.Cu" "B.Cu")
		(net "SW_P12V_PVCCIN_CPU0_FLT")
	)
	(via
		(at 331.744828 -345.26601)
		(size 0.508)
		(drill 0.254)
		(layers "F.Cu" "B.Cu")
		(net "SW_P12V_PVCCIN_CPU0_FLT")
	)
	(via
		(at 356.785164 -337.182714)
		(size 0.508)
		(drill 0.254)
		(layers "F.Cu" "B.Cu")
		(net "SW_P12V_PVCCIN_CPU0_FLT")
	)
	(via
		(at 346.805504 -335.772252)
		(size 0.49022)
		(drill 0.254)
		(layers "F.Cu" "B.Cu")
		(net "SW_P12V_PVCCIN_CPU0_FLT")
	)
	(via
		(at 339.671152 -348.59976)
		(size 0.508)
		(drill 0.254)
		(layers "F.Cu" "B.Cu")
		(net "SW_P12V_PVCCIN_CPU0_FLT")
	)
	(via
		(at 364.945676 -336.446114)
		(size 0.508)
		(drill 0.254)
		(layers "F.Cu" "B.Cu")
		(net "SW_P12V_PVCCIN_CPU0_FLT")
	)
	(via
		(at 346.226892 -335.521554)
		(size 0.49022)
		(drill 0.254)
		(layers "F.Cu" "B.Cu")
		(net "SW_P12V_PVCCIN_CPU0_FLT")
	)
	(via
		(at 331.770228 -346.02801)
		(size 0.508)
		(drill 0.254)
		(layers "F.Cu" "B.Cu")
		(net "SW_P12V_PVCCIN_CPU0_FLT")
	)
	(via
		(at 338.147152 -348.59976)
		(size 0.508)
		(drill 0.254)
		(layers "F.Cu" "B.Cu")
		(net "SW_P12V_PVCCIN_CPU0_FLT")
	)
	(segment
		(start 368.105182 -343.902284)
		(end 369.02009 -344.817192)
		(width 0.508)
		(layer "B.Cu")
		(net "SW_P12V_PVCCIN_CPU0_FLT")
	)
	(segment
		(start 359.62971 -344.817192)
		(end 360.544618 -343.902284)
		(width 0.508)
		(layer "B.Cu")
		(net "SW_P12V_PVCCIN_CPU0_FLT")
	)
	(segment
		(start 351.924366 -342.987376)
		(end 352.839274 -343.902284)
		(width 0.508)
		(layer "B.Cu")
		(net "SW_P12V_PVCCIN_CPU0_FLT")
	)
	(segment
		(start 352.839274 -343.902284)
		(end 353.754182 -342.987376)
		(width 0.508)
		(layer "B.Cu")
		(net "SW_P12V_PVCCIN_CPU0_FLT")
	)
	(segment
		(start 344.363802 -344.817192)
		(end 345.27871 -343.902284)
		(width 0.508)
		(layer "B.Cu")
		(net "SW_P12V_PVCCIN_CPU0_FLT")
	)
	(segment
		(start 345.27871 -343.902284)
		(end 346.193618 -344.817192)
		(width 0.508)
		(layer "B.Cu")
		(net "SW_P12V_PVCCIN_CPU0_FLT")
	)
	(segment
		(start 345.27871 -343.902284)
		(end 346.193618 -342.987376)
		(width 0.508)
		(layer "B.Cu")
		(net "SW_P12V_PVCCIN_CPU0_FLT")
	)
	(segment
		(start 364.2868 -350.357948)
		(end 365.201708 -349.44304)
		(width 0.508)
		(layer "B.Cu")
		(net "SW_P12V_PVCCIN_CPU0_FLT")
	)
	(segment
		(start 359.62971 -342.987376)
		(end 360.544618 -343.902284)
		(width 0.508)
		(layer "B.Cu")
		(net "SW_P12V_PVCCIN_CPU0_FLT")
	)
	(segment
		(start 367.190274 -344.817192)
		(end 368.105182 -343.902284)
		(width 0.508)
		(layer "B.Cu")
		(net "SW_P12V_PVCCIN_CPU0_FLT")
	)
	(segment
		(start 368.105182 -343.902284)
		(end 369.02009 -342.987376)
		(width 0.508)
		(layer "B.Cu")
		(net "SW_P12V_PVCCIN_CPU0_FLT")
	)
	(segment
		(start 363.371892 -349.44304)
		(end 364.2868 -350.357948)
		(width 0.508)
		(layer "B.Cu")
		(net "SW_P12V_PVCCIN_CPU0_FLT")
	)
	(segment
		(start 352.839274 -343.902284)
		(end 353.754182 -344.817192)
		(width 0.508)
		(layer "B.Cu")
		(net "SW_P12V_PVCCIN_CPU0_FLT")
	)
	(segment
		(start 363.371892 -351.272856)
		(end 364.2868 -350.357948)
		(width 0.508)
		(layer "B.Cu")
		(net "SW_P12V_PVCCIN_CPU0_FLT")
	)
	(segment
		(start 351.924366 -344.817192)
		(end 352.839274 -343.902284)
		(width 0.508)
		(layer "B.Cu")
		(net "SW_P12V_PVCCIN_CPU0_FLT")
	)
	(segment
		(start 364.2868 -350.357948)
		(end 365.201708 -351.272856)
		(width 0.508)
		(layer "B.Cu")
		(net "SW_P12V_PVCCIN_CPU0_FLT")
	)
	(segment
		(start 367.190274 -342.987376)
		(end 368.105182 -343.902284)
		(width 0.508)
		(layer "B.Cu")
		(net "SW_P12V_PVCCIN_CPU0_FLT")
	)
	(segment
		(start 344.363802 -342.987376)
		(end 345.27871 -343.902284)
		(width 0.508)
		(layer "B.Cu")
		(net "SW_P12V_PVCCIN_CPU0_FLT")
	)
	(segment
		(start 360.544618 -343.902284)
		(end 361.459526 -344.817192)
		(width 0.508)
		(layer "B.Cu")
		(net "SW_P12V_PVCCIN_CPU0_FLT")
	)
	(segment
		(start 360.544618 -343.902284)
		(end 361.459526 -342.987376)
		(width 0.508)
		(layer "B.Cu")
		(net "SW_P12V_PVCCIN_CPU0_FLT")
	)
	(via
		(at 44.869354 -152.299162)
		(size 0.508)
		(drill 0.254)
		(layers "F.Cu" "B.Cu")
		(net "SW_P12V_PVCCINFAON_CPU1_FLT")
	)
	(via
		(at 50.35169 -177.538126)
		(size 0.508)
		(drill 0.254)
		(layers "F.Cu" "B.Cu")
		(net "SW_P12V_PVCCINFAON_CPU1_FLT")
	)
	(via
		(at 52.846224 -166.37127)
		(size 0.49022)
		(drill 0.254)
		(layers "F.Cu" "B.Cu")
		(net "SW_P12V_PVCCINFAON_CPU1_FLT")
	)
	(via
		(at 52.906168 -151.529034)
		(size 0.508)
		(drill 0.254)
		(layers "F.Cu" "B.Cu")
		(net "SW_P12V_PVCCINFAON_CPU1_FLT")
	)
	(via
		(at 45.504354 -152.299162)
		(size 0.508)
		(drill 0.254)
		(layers "F.Cu" "B.Cu")
		(net "SW_P12V_PVCCINFAON_CPU1_FLT")
	)
	(via
		(at 51.432968 -151.529034)
		(size 0.508)
		(drill 0.254)
		(layers "F.Cu" "B.Cu")
		(net "SW_P12V_PVCCINFAON_CPU1_FLT")
	)
	(via
		(at 52.169568 -151.529034)
		(size 0.508)
		(drill 0.254)
		(layers "F.Cu" "B.Cu")
		(net "SW_P12V_PVCCINFAON_CPU1_FLT")
	)
	(via
		(at 52.906168 -168.801034)
		(size 0.508)
		(drill 0.254)
		(layers "F.Cu" "B.Cu")
		(net "SW_P12V_PVCCINFAON_CPU1_FLT")
	)
	(via
		(at 53.036724 -148.50745)
		(size 0.49022)
		(drill 0.254)
		(layers "F.Cu" "B.Cu")
		(net "SW_P12V_PVCCINFAON_CPU1_FLT")
	)
	(via
		(at 52.906168 -160.165034)
		(size 0.508)
		(drill 0.254)
		(layers "F.Cu" "B.Cu")
		(net "SW_P12V_PVCCINFAON_CPU1_FLT")
	)
	(via
		(at 51.612546 -175.261524)
		(size 0.508)
		(drill 0.254)
		(layers "F.Cu" "B.Cu")
		(net "SW_P12V_PVCCINFAON_CPU1_FLT")
	)
	(via
		(at 52.169568 -160.165034)
		(size 0.508)
		(drill 0.254)
		(layers "F.Cu" "B.Cu")
		(net "SW_P12V_PVCCINFAON_CPU1_FLT")
	)
	(via
		(at 51.374548 -167.71747)
		(size 0.508)
		(drill 0.254)
		(layers "F.Cu" "B.Cu")
		(net "SW_P12V_PVCCINFAON_CPU1_FLT")
	)
	(via
		(at 53.036724 -166.96309)
		(size 0.49022)
		(drill 0.254)
		(layers "F.Cu" "B.Cu")
		(net "SW_P12V_PVCCINFAON_CPU1_FLT")
	)
	(via
		(at 51.374548 -159.08147)
		(size 0.508)
		(drill 0.254)
		(layers "F.Cu" "B.Cu")
		(net "SW_P12V_PVCCINFAON_CPU1_FLT")
	)
	(via
		(at 46.139354 -152.299162)
		(size 0.508)
		(drill 0.254)
		(layers "F.Cu" "B.Cu")
		(net "SW_P12V_PVCCINFAON_CPU1_FLT")
	)
	(via
		(at 52.61356 -176.183544)
		(size 0.508)
		(drill 0.254)
		(layers "F.Cu" "B.Cu")
		(net "SW_P12V_PVCCINFAON_CPU1_FLT")
	)
	(via
		(at 47.446184 -152.30729)
		(size 0.508)
		(drill 0.254)
		(layers "F.Cu" "B.Cu")
		(net "SW_P12V_PVCCINFAON_CPU1_FLT")
	)
	(via
		(at 44.165012 -152.335738)
		(size 0.508)
		(drill 0.254)
		(layers "F.Cu" "B.Cu")
		(net "SW_P12V_PVCCINFAON_CPU1_FLT")
	)
	(via
		(at 53.036724 -165.77945)
		(size 0.49022)
		(drill 0.254)
		(layers "F.Cu" "B.Cu")
		(net "SW_P12V_PVCCINFAON_CPU1_FLT")
	)
	(via
		(at 52.846224 -157.73527)
		(size 0.49022)
		(drill 0.254)
		(layers "F.Cu" "B.Cu")
		(net "SW_P12V_PVCCINFAON_CPU1_FLT")
	)
	(via
		(at 52.846224 -150.28291)
		(size 0.49022)
		(drill 0.254)
		(layers "F.Cu" "B.Cu")
		(net "SW_P12V_PVCCINFAON_CPU1_FLT")
	)
	(via
		(at 52.550568 -159.606234)
		(size 0.508)
		(drill 0.254)
		(layers "F.Cu" "B.Cu")
		(net "SW_P12V_PVCCINFAON_CPU1_FLT")
	)
	(via
		(at 50.98669 -176.903126)
		(size 0.508)
		(drill 0.254)
		(layers "F.Cu" "B.Cu")
		(net "SW_P12V_PVCCINFAON_CPU1_FLT")
	)
	(via
		(at 47.446184 -151.61641)
		(size 0.508)
		(drill 0.254)
		(layers "F.Cu" "B.Cu")
		(net "SW_P12V_PVCCINFAON_CPU1_FLT")
	)
	(via
		(at 45.504354 -151.608282)
		(size 0.508)
		(drill 0.254)
		(layers "F.Cu" "B.Cu")
		(net "SW_P12V_PVCCINFAON_CPU1_FLT")
	)
	(via
		(at 51.607466 -176.181004)
		(size 0.508)
		(drill 0.254)
		(layers "F.Cu" "B.Cu")
		(net "SW_P12V_PVCCINFAON_CPU1_FLT")
	)
	(via
		(at 44.869354 -150.917402)
		(size 0.508)
		(drill 0.254)
		(layers "F.Cu" "B.Cu")
		(net "SW_P12V_PVCCINFAON_CPU1_FLT")
	)
	(via
		(at 52.550568 -150.970234)
		(size 0.508)
		(drill 0.254)
		(layers "F.Cu" "B.Cu")
		(net "SW_P12V_PVCCINFAON_CPU1_FLT")
	)
	(via
		(at 45.504354 -150.917402)
		(size 0.508)
		(drill 0.254)
		(layers "F.Cu" "B.Cu")
		(net "SW_P12V_PVCCINFAON_CPU1_FLT")
	)
	(via
		(at 52.169568 -168.801034)
		(size 0.508)
		(drill 0.254)
		(layers "F.Cu" "B.Cu")
		(net "SW_P12V_PVCCINFAON_CPU1_FLT")
	)
	(via
		(at 46.139354 -151.608282)
		(size 0.508)
		(drill 0.254)
		(layers "F.Cu" "B.Cu")
		(net "SW_P12V_PVCCINFAON_CPU1_FLT")
	)
	(via
		(at 52.846224 -158.91891)
		(size 0.49022)
		(drill 0.254)
		(layers "F.Cu" "B.Cu")
		(net "SW_P12V_PVCCINFAON_CPU1_FLT")
	)
	(via
		(at 50.98669 -177.538126)
		(size 0.508)
		(drill 0.254)
		(layers "F.Cu" "B.Cu")
		(net "SW_P12V_PVCCINFAON_CPU1_FLT")
	)
	(via
		(at 51.374548 -150.44547)
		(size 0.508)
		(drill 0.254)
		(layers "F.Cu" "B.Cu")
		(net "SW_P12V_PVCCINFAON_CPU1_FLT")
	)
	(via
		(at 52.111148 -159.08147)
		(size 0.508)
		(drill 0.254)
		(layers "F.Cu" "B.Cu")
		(net "SW_P12V_PVCCINFAON_CPU1_FLT")
	)
	(via
		(at 53.036724 -157.14345)
		(size 0.49022)
		(drill 0.254)
		(layers "F.Cu" "B.Cu")
		(net "SW_P12V_PVCCINFAON_CPU1_FLT")
	)
	(via
		(at 51.788568 -159.631634)
		(size 0.508)
		(drill 0.254)
		(layers "F.Cu" "B.Cu")
		(net "SW_P12V_PVCCINFAON_CPU1_FLT")
	)
	(via
		(at 47.446184 -150.92553)
		(size 0.508)
		(drill 0.254)
		(layers "F.Cu" "B.Cu")
		(net "SW_P12V_PVCCINFAON_CPU1_FLT")
	)
	(via
		(at 46.774354 -152.299162)
		(size 0.508)
		(drill 0.254)
		(layers "F.Cu" "B.Cu")
		(net "SW_P12V_PVCCINFAON_CPU1_FLT")
	)
	(via
		(at 46.139354 -150.917402)
		(size 0.508)
		(drill 0.254)
		(layers "F.Cu" "B.Cu")
		(net "SW_P12V_PVCCINFAON_CPU1_FLT")
	)
	(via
		(at 53.036724 -158.32709)
		(size 0.49022)
		(drill 0.254)
		(layers "F.Cu" "B.Cu")
		(net "SW_P12V_PVCCINFAON_CPU1_FLT")
	)
	(via
		(at 52.846224 -167.55491)
		(size 0.49022)
		(drill 0.254)
		(layers "F.Cu" "B.Cu")
		(net "SW_P12V_PVCCINFAON_CPU1_FLT")
	)
	(via
		(at 44.165012 -151.644858)
		(size 0.508)
		(drill 0.254)
		(layers "F.Cu" "B.Cu")
		(net "SW_P12V_PVCCINFAON_CPU1_FLT")
	)
	(via
		(at 44.165012 -150.953978)
		(size 0.508)
		(drill 0.254)
		(layers "F.Cu" "B.Cu")
		(net "SW_P12V_PVCCINFAON_CPU1_FLT")
	)
	(via
		(at 52.550568 -168.242234)
		(size 0.508)
		(drill 0.254)
		(layers "F.Cu" "B.Cu")
		(net "SW_P12V_PVCCINFAON_CPU1_FLT")
	)
	(via
		(at 51.788568 -168.267634)
		(size 0.508)
		(drill 0.254)
		(layers "F.Cu" "B.Cu")
		(net "SW_P12V_PVCCINFAON_CPU1_FLT")
	)
	(via
		(at 49.71669 -176.903126)
		(size 0.508)
		(drill 0.254)
		(layers "F.Cu" "B.Cu")
		(net "SW_P12V_PVCCINFAON_CPU1_FLT")
	)
	(via
		(at 51.788568 -150.995634)
		(size 0.508)
		(drill 0.254)
		(layers "F.Cu" "B.Cu")
		(net "SW_P12V_PVCCINFAON_CPU1_FLT")
	)
	(via
		(at 46.774354 -151.608282)
		(size 0.508)
		(drill 0.254)
		(layers "F.Cu" "B.Cu")
		(net "SW_P12V_PVCCINFAON_CPU1_FLT")
	)
	(via
		(at 50.35169 -176.903126)
		(size 0.508)
		(drill 0.254)
		(layers "F.Cu" "B.Cu")
		(net "SW_P12V_PVCCINFAON_CPU1_FLT")
	)
	(via
		(at 46.774354 -150.917402)
		(size 0.508)
		(drill 0.254)
		(layers "F.Cu" "B.Cu")
		(net "SW_P12V_PVCCINFAON_CPU1_FLT")
	)
	(via
		(at 51.432968 -160.165034)
		(size 0.508)
		(drill 0.254)
		(layers "F.Cu" "B.Cu")
		(net "SW_P12V_PVCCINFAON_CPU1_FLT")
	)
	(via
		(at 51.432968 -168.801034)
		(size 0.508)
		(drill 0.254)
		(layers "F.Cu" "B.Cu")
		(net "SW_P12V_PVCCINFAON_CPU1_FLT")
	)
	(via
		(at 52.111148 -150.44547)
		(size 0.508)
		(drill 0.254)
		(layers "F.Cu" "B.Cu")
		(net "SW_P12V_PVCCINFAON_CPU1_FLT")
	)
	(via
		(at 52.846224 -149.09927)
		(size 0.49022)
		(drill 0.254)
		(layers "F.Cu" "B.Cu")
		(net "SW_P12V_PVCCINFAON_CPU1_FLT")
	)
	(via
		(at 44.869354 -151.608282)
		(size 0.508)
		(drill 0.254)
		(layers "F.Cu" "B.Cu")
		(net "SW_P12V_PVCCINFAON_CPU1_FLT")
	)
	(via
		(at 52.111148 -167.71747)
		(size 0.508)
		(drill 0.254)
		(layers "F.Cu" "B.Cu")
		(net "SW_P12V_PVCCINFAON_CPU1_FLT")
	)
	(via
		(at 53.036724 -149.69109)
		(size 0.49022)
		(drill 0.254)
		(layers "F.Cu" "B.Cu")
		(net "SW_P12V_PVCCINFAON_CPU1_FLT")
	)
	(via
		(at 52.610766 -175.266858)
		(size 0.508)
		(drill 0.254)
		(layers "F.Cu" "B.Cu")
		(net "SW_P12V_PVCCINFAON_CPU1_FLT")
	)
	(via
		(at 419.476174 -175.770794)
		(size 0.508)
		(drill 0.254)
		(layers "F.Cu" "B.Cu")
		(net "SW_P12V_PVCCINFAON_CPU0_FLT")
	)
	(via
		(at 417.872418 -170.156378)
		(size 0.49022)
		(drill 0.254)
		(layers "F.Cu" "B.Cu")
		(net "SW_P12V_PVCCINFAON_CPU0_FLT")
	)
	(via
		(at 425.862496 -163.170616)
		(size 0.508)
		(drill 0.254)
		(layers "F.Cu" "B.Cu")
		(net "SW_P12V_PVCCINFAON_CPU0_FLT")
	)
	(via
		(at 420.058596 -152.038304)
		(size 0.508)
		(drill 0.254)
		(layers "F.Cu" "B.Cu")
		(net "SW_P12V_PVCCINFAON_CPU0_FLT")
	)
	(via
		(at 418.002974 -167.134794)
		(size 0.508)
		(drill 0.254)
		(layers "F.Cu" "B.Cu")
		(net "SW_P12V_PVCCINFAON_CPU0_FLT")
	)
	(via
		(at 418.797994 -168.218358)
		(size 0.508)
		(drill 0.254)
		(layers "F.Cu" "B.Cu")
		(net "SW_P12V_PVCCINFAON_CPU0_FLT")
	)
	(via
		(at 425.867576 -165.79723)
		(size 0.508)
		(drill 0.254)
		(layers "F.Cu" "B.Cu")
		(net "SW_P12V_PVCCINFAON_CPU0_FLT")
	)
	(via
		(at 426.527976 -163.81603)
		(size 0.508)
		(drill 0.254)
		(layers "F.Cu" "B.Cu")
		(net "SW_P12V_PVCCINFAON_CPU0_FLT")
	)
	(via
		(at 419.534594 -176.854358)
		(size 0.508)
		(drill 0.254)
		(layers "F.Cu" "B.Cu")
		(net "SW_P12V_PVCCINFAON_CPU0_FLT")
	)
	(via
		(at 417.872418 -160.336738)
		(size 0.49022)
		(drill 0.254)
		(layers "F.Cu" "B.Cu")
		(net "SW_P12V_PVCCINFAON_CPU0_FLT")
	)
	(via
		(at 426.527976 -163.15563)
		(size 0.508)
		(drill 0.254)
		(layers "F.Cu" "B.Cu")
		(net "SW_P12V_PVCCINFAON_CPU0_FLT")
	)
	(via
		(at 418.739574 -158.498794)
		(size 0.508)
		(drill 0.254)
		(layers "F.Cu" "B.Cu")
		(net "SW_P12V_PVCCINFAON_CPU0_FLT")
	)
	(via
		(at 417.872418 -168.972738)
		(size 0.49022)
		(drill 0.254)
		(layers "F.Cu" "B.Cu")
		(net "SW_P12V_PVCCINFAON_CPU0_FLT")
	)
	(via
		(at 419.057582 -151.116284)
		(size 0.508)
		(drill 0.254)
		(layers "F.Cu" "B.Cu")
		(net "SW_P12V_PVCCINFAON_CPU0_FLT")
	)
	(via
		(at 418.739574 -167.134794)
		(size 0.508)
		(drill 0.254)
		(layers "F.Cu" "B.Cu")
		(net "SW_P12V_PVCCINFAON_CPU0_FLT")
	)
	(via
		(at 419.476174 -158.498794)
		(size 0.508)
		(drill 0.254)
		(layers "F.Cu" "B.Cu")
		(net "SW_P12V_PVCCINFAON_CPU0_FLT")
	)
	(via
		(at 426.527976 -165.79723)
		(size 0.508)
		(drill 0.254)
		(layers "F.Cu" "B.Cu")
		(net "SW_P12V_PVCCINFAON_CPU0_FLT")
	)
	(via
		(at 417.872418 -177.608738)
		(size 0.49022)
		(drill 0.254)
		(layers "F.Cu" "B.Cu")
		(net "SW_P12V_PVCCINFAON_CPU0_FLT")
	)
	(via
		(at 425.867576 -163.81603)
		(size 0.508)
		(drill 0.254)
		(layers "F.Cu" "B.Cu")
		(net "SW_P12V_PVCCINFAON_CPU0_FLT")
	)
	(via
		(at 427.193456 -165.121844)
		(size 0.508)
		(drill 0.254)
		(layers "F.Cu" "B.Cu")
		(net "SW_P12V_PVCCINFAON_CPU0_FLT")
	)
	(via
		(at 425.867576 -164.47643)
		(size 0.508)
		(drill 0.254)
		(layers "F.Cu" "B.Cu")
		(net "SW_P12V_PVCCINFAON_CPU0_FLT")
	)
	(via
		(at 418.358574 -176.329594)
		(size 0.508)
		(drill 0.254)
		(layers "F.Cu" "B.Cu")
		(net "SW_P12V_PVCCINFAON_CPU0_FLT")
	)
	(via
		(at 419.120574 -167.668194)
		(size 0.508)
		(drill 0.254)
		(layers "F.Cu" "B.Cu")
		(net "SW_P12V_PVCCINFAON_CPU0_FLT")
	)
	(via
		(at 418.797994 -176.854358)
		(size 0.508)
		(drill 0.254)
		(layers "F.Cu" "B.Cu")
		(net "SW_P12V_PVCCINFAON_CPU0_FLT")
	)
	(via
		(at 426.527976 -164.47643)
		(size 0.508)
		(drill 0.254)
		(layers "F.Cu" "B.Cu")
		(net "SW_P12V_PVCCINFAON_CPU0_FLT")
	)
	(via
		(at 427.193456 -164.461444)
		(size 0.508)
		(drill 0.254)
		(layers "F.Cu" "B.Cu")
		(net "SW_P12V_PVCCINFAON_CPU0_FLT")
	)
	(via
		(at 417.872418 -161.520378)
		(size 0.49022)
		(drill 0.254)
		(layers "F.Cu" "B.Cu")
		(net "SW_P12V_PVCCINFAON_CPU0_FLT")
	)
	(via
		(at 418.739574 -175.770794)
		(size 0.508)
		(drill 0.254)
		(layers "F.Cu" "B.Cu")
		(net "SW_P12V_PVCCINFAON_CPU0_FLT")
	)
	(via
		(at 425.867576 -166.45763)
		(size 0.508)
		(drill 0.254)
		(layers "F.Cu" "B.Cu")
		(net "SW_P12V_PVCCINFAON_CPU0_FLT")
	)
	(via
		(at 418.062918 -178.200558)
		(size 0.49022)
		(drill 0.254)
		(layers "F.Cu" "B.Cu")
		(net "SW_P12V_PVCCINFAON_CPU0_FLT")
	)
	(via
		(at 426.527976 -166.45763)
		(size 0.508)
		(drill 0.254)
		(layers "F.Cu" "B.Cu")
		(net "SW_P12V_PVCCINFAON_CPU0_FLT")
	)
	(via
		(at 419.120574 -159.032194)
		(size 0.508)
		(drill 0.254)
		(layers "F.Cu" "B.Cu")
		(net "SW_P12V_PVCCINFAON_CPU0_FLT")
	)
	(via
		(at 421.954452 -150.396702)
		(size 0.508)
		(drill 0.254)
		(layers "F.Cu" "B.Cu")
		(net "SW_P12V_PVCCINFAON_CPU0_FLT")
	)
	(via
		(at 418.797994 -159.582358)
		(size 0.508)
		(drill 0.254)
		(layers "F.Cu" "B.Cu")
		(net "SW_P12V_PVCCINFAON_CPU0_FLT")
	)
	(via
		(at 418.358574 -159.057594)
		(size 0.508)
		(drill 0.254)
		(layers "F.Cu" "B.Cu")
		(net "SW_P12V_PVCCINFAON_CPU0_FLT")
	)
	(via
		(at 427.193456 -165.782244)
		(size 0.508)
		(drill 0.254)
		(layers "F.Cu" "B.Cu")
		(net "SW_P12V_PVCCINFAON_CPU0_FLT")
	)
	(via
		(at 419.060376 -152.03297)
		(size 0.508)
		(drill 0.254)
		(layers "F.Cu" "B.Cu")
		(net "SW_P12V_PVCCINFAON_CPU0_FLT")
	)
	(via
		(at 418.062918 -177.016918)
		(size 0.49022)
		(drill 0.254)
		(layers "F.Cu" "B.Cu")
		(net "SW_P12V_PVCCINFAON_CPU0_FLT")
	)
	(via
		(at 418.358574 -167.693594)
		(size 0.508)
		(drill 0.254)
		(layers "F.Cu" "B.Cu")
		(net "SW_P12V_PVCCINFAON_CPU0_FLT")
	)
	(via
		(at 427.193456 -163.801044)
		(size 0.508)
		(drill 0.254)
		(layers "F.Cu" "B.Cu")
		(net "SW_P12V_PVCCINFAON_CPU0_FLT")
	)
	(via
		(at 419.534594 -159.582358)
		(size 0.508)
		(drill 0.254)
		(layers "F.Cu" "B.Cu")
		(net "SW_P12V_PVCCINFAON_CPU0_FLT")
	)
	(via
		(at 418.062918 -169.564558)
		(size 0.49022)
		(drill 0.254)
		(layers "F.Cu" "B.Cu")
		(net "SW_P12V_PVCCINFAON_CPU0_FLT")
	)
	(via
		(at 425.867576 -165.13683)
		(size 0.508)
		(drill 0.254)
		(layers "F.Cu" "B.Cu")
		(net "SW_P12V_PVCCINFAON_CPU0_FLT")
	)
	(via
		(at 421.319452 -150.396702)
		(size 0.508)
		(drill 0.254)
		(layers "F.Cu" "B.Cu")
		(net "SW_P12V_PVCCINFAON_CPU0_FLT")
	)
	(via
		(at 420.684452 -150.396702)
		(size 0.508)
		(drill 0.254)
		(layers "F.Cu" "B.Cu")
		(net "SW_P12V_PVCCINFAON_CPU0_FLT")
	)
	(via
		(at 427.193456 -166.442644)
		(size 0.508)
		(drill 0.254)
		(layers "F.Cu" "B.Cu")
		(net "SW_P12V_PVCCINFAON_CPU0_FLT")
	)
	(via
		(at 417.872418 -178.792378)
		(size 0.49022)
		(drill 0.254)
		(layers "F.Cu" "B.Cu")
		(net "SW_P12V_PVCCINFAON_CPU0_FLT")
	)
	(via
		(at 418.062918 -159.744918)
		(size 0.49022)
		(drill 0.254)
		(layers "F.Cu" "B.Cu")
		(net "SW_P12V_PVCCINFAON_CPU0_FLT")
	)
	(via
		(at 424.3578 -151.018748)
		(size 0.508)
		(drill 0.254)
		(layers "F.Cu" "B.Cu")
		(net "SW_P12V_PVCCINFAON_CPU0_FLT")
	)
	(via
		(at 418.002974 -175.770794)
		(size 0.508)
		(drill 0.254)
		(layers "F.Cu" "B.Cu")
		(net "SW_P12V_PVCCINFAON_CPU0_FLT")
	)
	(via
		(at 418.002974 -158.498794)
		(size 0.508)
		(drill 0.254)
		(layers "F.Cu" "B.Cu")
		(net "SW_P12V_PVCCINFAON_CPU0_FLT")
	)
	(via
		(at 418.062918 -160.928558)
		(size 0.49022)
		(drill 0.254)
		(layers "F.Cu" "B.Cu")
		(net "SW_P12V_PVCCINFAON_CPU0_FLT")
	)
	(via
		(at 419.476174 -167.134794)
		(size 0.508)
		(drill 0.254)
		(layers "F.Cu" "B.Cu")
		(net "SW_P12V_PVCCINFAON_CPU0_FLT")
	)
	(via
		(at 426.527976 -165.13683)
		(size 0.508)
		(drill 0.254)
		(layers "F.Cu" "B.Cu")
		(net "SW_P12V_PVCCINFAON_CPU0_FLT")
	)
	(via
		(at 424.815 -151.501348)
		(size 0.508)
		(drill 0.254)
		(layers "F.Cu" "B.Cu")
		(net "SW_P12V_PVCCINFAON_CPU0_FLT")
	)
	(via
		(at 420.063676 -151.118824)
		(size 0.508)
		(drill 0.254)
		(layers "F.Cu" "B.Cu")
		(net "SW_P12V_PVCCINFAON_CPU0_FLT")
	)
	(via
		(at 419.534594 -168.218358)
		(size 0.508)
		(drill 0.254)
		(layers "F.Cu" "B.Cu")
		(net "SW_P12V_PVCCINFAON_CPU0_FLT")
	)
	(via
		(at 419.120574 -176.304194)
		(size 0.508)
		(drill 0.254)
		(layers "F.Cu" "B.Cu")
		(net "SW_P12V_PVCCINFAON_CPU0_FLT")
	)
	(via
		(at 418.062918 -168.380918)
		(size 0.49022)
		(drill 0.254)
		(layers "F.Cu" "B.Cu")
		(net "SW_P12V_PVCCINFAON_CPU0_FLT")
	)
	(via
		(at 427.193456 -163.140644)
		(size 0.508)
		(drill 0.254)
		(layers "F.Cu" "B.Cu")
		(net "SW_P12V_PVCCINFAON_CPU0_FLT")
	)
	(via
		(at 176.960276 -362.699046)
		(size 0.508)
		(drill 0.254)
		(layers "F.Cu" "B.Cu")
		(net "SW_P12V_PVCCFA_EHV_FIVRA_CPU1_R")
	)
	(via
		(at 175.546766 -361.518962)
		(size 0.508)
		(drill 0.254)
		(layers "F.Cu" "B.Cu")
		(net "SW_P12V_PVCCFA_EHV_FIVRA_CPU1_R")
	)
	(via
		(at 177.722276 -362.699046)
		(size 0.508)
		(drill 0.254)
		(layers "F.Cu" "B.Cu")
		(net "SW_P12V_PVCCFA_EHV_FIVRA_CPU1_R")
	)
	(via
		(at 177.722276 -363.334046)
		(size 0.508)
		(drill 0.254)
		(layers "F.Cu" "B.Cu")
		(net "SW_P12V_PVCCFA_EHV_FIVRA_CPU1_R")
	)
	(via
		(at 176.960276 -362.064046)
		(size 0.508)
		(drill 0.254)
		(layers "F.Cu" "B.Cu")
		(net "SW_P12V_PVCCFA_EHV_FIVRA_CPU1_R")
	)
	(via
		(at 184.84088 -355.903276)
		(size 0.508)
		(drill 0.254)
		(layers "F.Cu" "B.Cu")
		(net "SW_P12V_PVCCFA_EHV_FIVRA_CPU1_R")
	)
	(via
		(at 184.153556 -355.60762)
		(size 0.49022)
		(drill 0.254)
		(layers "F.Cu" "B.Cu")
		(net "SW_P12V_PVCCFA_EHV_FIVRA_CPU1_R")
	)
	(via
		(at 185.39968 -355.547676)
		(size 0.508)
		(drill 0.254)
		(layers "F.Cu" "B.Cu")
		(net "SW_P12V_PVCCFA_EHV_FIVRA_CPU1_R")
	)
	(via
		(at 177.737516 -360.631486)
		(size 0.508)
		(drill 0.254)
		(layers "F.Cu" "B.Cu")
		(net "SW_P12V_PVCCFA_EHV_FIVRA_CPU1_R")
	)
	(via
		(at 173.281594 -355.60762)
		(size 0.49022)
		(drill 0.254)
		(layers "F.Cu" "B.Cu")
		(net "SW_P12V_PVCCFA_EHV_FIVRA_CPU1_R")
	)
	(via
		(at 172.689774 -355.41712)
		(size 0.49022)
		(drill 0.254)
		(layers "F.Cu" "B.Cu")
		(net "SW_P12V_PVCCFA_EHV_FIVRA_CPU1_R")
	)
	(via
		(at 175.177958 -356.665276)
		(size 0.508)
		(drill 0.254)
		(layers "F.Cu" "B.Cu")
		(net "SW_P12V_PVCCFA_EHV_FIVRA_CPU1_R")
	)
	(via
		(at 176.983136 -361.343956)
		(size 0.508)
		(drill 0.254)
		(layers "F.Cu" "B.Cu")
		(net "SW_P12V_PVCCFA_EHV_FIVRA_CPU1_R")
	)
	(via
		(at 176.975516 -360.631486)
		(size 0.508)
		(drill 0.254)
		(layers "F.Cu" "B.Cu")
		(net "SW_P12V_PVCCFA_EHV_FIVRA_CPU1_R")
	)
	(via
		(at 185.39968 -356.284276)
		(size 0.508)
		(drill 0.254)
		(layers "F.Cu" "B.Cu")
		(net "SW_P12V_PVCCFA_EHV_FIVRA_CPU1_R")
	)
	(via
		(at 175.711358 -357.020876)
		(size 0.508)
		(drill 0.254)
		(layers "F.Cu" "B.Cu")
		(net "SW_P12V_PVCCFA_EHV_FIVRA_CPU1_R")
	)
	(via
		(at 185.985404 -354.637848)
		(size 0.508)
		(drill 0.254)
		(layers "F.Cu" "B.Cu")
		(net "SW_P12V_PVCCFA_EHV_FIVRA_CPU1_R")
	)
	(via
		(at 176.427384 -354.634292)
		(size 0.508)
		(drill 0.254)
		(layers "F.Cu" "B.Cu")
		(net "SW_P12V_PVCCFA_EHV_FIVRA_CPU1_R")
	)
	(via
		(at 175.711358 -355.547676)
		(size 0.508)
		(drill 0.254)
		(layers "F.Cu" "B.Cu")
		(net "SW_P12V_PVCCFA_EHV_FIVRA_CPU1_R")
	)
	(via
		(at 183.561736 -355.41712)
		(size 0.49022)
		(drill 0.254)
		(layers "F.Cu" "B.Cu")
		(net "SW_P12V_PVCCFA_EHV_FIVRA_CPU1_R")
	)
	(via
		(at 185.39968 -357.020876)
		(size 0.508)
		(drill 0.254)
		(layers "F.Cu" "B.Cu")
		(net "SW_P12V_PVCCFA_EHV_FIVRA_CPU1_R")
	)
	(via
		(at 176.308766 -360.751882)
		(size 0.508)
		(drill 0.254)
		(layers "F.Cu" "B.Cu")
		(net "SW_P12V_PVCCFA_EHV_FIVRA_CPU1_R")
	)
	(via
		(at 184.316116 -357.079296)
		(size 0.508)
		(drill 0.254)
		(layers "F.Cu" "B.Cu")
		(net "SW_P12V_PVCCFA_EHV_FIVRA_CPU1_R")
	)
	(via
		(at 182.378096 -355.41712)
		(size 0.49022)
		(drill 0.254)
		(layers "F.Cu" "B.Cu")
		(net "SW_P12V_PVCCFA_EHV_FIVRA_CPU1_R")
	)
	(via
		(at 182.969916 -355.60762)
		(size 0.49022)
		(drill 0.254)
		(layers "F.Cu" "B.Cu")
		(net "SW_P12V_PVCCFA_EHV_FIVRA_CPU1_R")
	)
	(via
		(at 174.465234 -355.60762)
		(size 0.49022)
		(drill 0.254)
		(layers "F.Cu" "B.Cu")
		(net "SW_P12V_PVCCFA_EHV_FIVRA_CPU1_R")
	)
	(via
		(at 175.711358 -356.284276)
		(size 0.508)
		(drill 0.254)
		(layers "F.Cu" "B.Cu")
		(net "SW_P12V_PVCCFA_EHV_FIVRA_CPU1_R")
	)
	(via
		(at 176.960276 -363.334046)
		(size 0.508)
		(drill 0.254)
		(layers "F.Cu" "B.Cu")
		(net "SW_P12V_PVCCFA_EHV_FIVRA_CPU1_R")
	)
	(via
		(at 177.745136 -361.343956)
		(size 0.508)
		(drill 0.254)
		(layers "F.Cu" "B.Cu")
		(net "SW_P12V_PVCCFA_EHV_FIVRA_CPU1_R")
	)
	(via
		(at 176.308766 -361.518962)
		(size 0.508)
		(drill 0.254)
		(layers "F.Cu" "B.Cu")
		(net "SW_P12V_PVCCFA_EHV_FIVRA_CPU1_R")
	)
	(via
		(at 184.316116 -356.342696)
		(size 0.508)
		(drill 0.254)
		(layers "F.Cu" "B.Cu")
		(net "SW_P12V_PVCCFA_EHV_FIVRA_CPU1_R")
	)
	(via
		(at 175.546766 -360.751882)
		(size 0.508)
		(drill 0.254)
		(layers "F.Cu" "B.Cu")
		(net "SW_P12V_PVCCFA_EHV_FIVRA_CPU1_R")
	)
	(via
		(at 184.86628 -356.665276)
		(size 0.508)
		(drill 0.254)
		(layers "F.Cu" "B.Cu")
		(net "SW_P12V_PVCCFA_EHV_FIVRA_CPU1_R")
	)
	(via
		(at 174.627794 -357.079296)
		(size 0.508)
		(drill 0.254)
		(layers "F.Cu" "B.Cu")
		(net "SW_P12V_PVCCFA_EHV_FIVRA_CPU1_R")
	)
	(via
		(at 174.627794 -356.342696)
		(size 0.508)
		(drill 0.254)
		(layers "F.Cu" "B.Cu")
		(net "SW_P12V_PVCCFA_EHV_FIVRA_CPU1_R")
	)
	(via
		(at 175.152558 -355.903276)
		(size 0.508)
		(drill 0.254)
		(layers "F.Cu" "B.Cu")
		(net "SW_P12V_PVCCFA_EHV_FIVRA_CPU1_R")
	)
	(via
		(at 173.873414 -355.41712)
		(size 0.49022)
		(drill 0.254)
		(layers "F.Cu" "B.Cu")
		(net "SW_P12V_PVCCFA_EHV_FIVRA_CPU1_R")
	)
	(via
		(at 177.722276 -362.064046)
		(size 0.508)
		(drill 0.254)
		(layers "F.Cu" "B.Cu")
		(net "SW_P12V_PVCCFA_EHV_FIVRA_CPU1_R")
	)
	(via
		(at 53.85689 -356.336346)
		(size 0.508)
		(drill 0.254)
		(layers "F.Cu" "B.Cu")
		(net "SW_P12V_PVCCFA_EHV_FIVRA_CPU1_L")
	)
	(via
		(at 47.26305 -363.962696)
		(size 0.508)
		(drill 0.254)
		(layers "F.Cu" "B.Cu")
		(net "SW_P12V_PVCCFA_EHV_FIVRA_CPU1_L")
	)
	(via
		(at 45.328332 -355.414326)
		(size 0.508)
		(drill 0.254)
		(layers "F.Cu" "B.Cu")
		(net "SW_P12V_PVCCFA_EHV_FIVRA_CPU1_L")
	)
	(via
		(at 44.794932 -356.531926)
		(size 0.508)
		(drill 0.254)
		(layers "F.Cu" "B.Cu")
		(net "SW_P12V_PVCCFA_EHV_FIVRA_CPU1_L")
	)
	(via
		(at 47.28591 -361.337606)
		(size 0.508)
		(drill 0.254)
		(layers "F.Cu" "B.Cu")
		(net "SW_P12V_PVCCFA_EHV_FIVRA_CPU1_L")
	)
	(via
		(at 42.230548 -355.41077)
		(size 0.49022)
		(drill 0.254)
		(layers "F.Cu" "B.Cu")
		(net "SW_P12V_PVCCFA_EHV_FIVRA_CPU1_L")
	)
	(via
		(at 55.004716 -355.413056)
		(size 0.508)
		(drill 0.254)
		(layers "F.Cu" "B.Cu")
		(net "SW_P12V_PVCCFA_EHV_FIVRA_CPU1_L")
	)
	(via
		(at 44.168568 -357.034846)
		(size 0.508)
		(drill 0.254)
		(layers "F.Cu" "B.Cu")
		(net "SW_P12V_PVCCFA_EHV_FIVRA_CPU1_L")
	)
	(via
		(at 45.84954 -361.512612)
		(size 0.508)
		(drill 0.254)
		(layers "F.Cu" "B.Cu")
		(net "SW_P12V_PVCCFA_EHV_FIVRA_CPU1_L")
	)
	(via
		(at 46.50105 -363.962696)
		(size 0.508)
		(drill 0.254)
		(layers "F.Cu" "B.Cu")
		(net "SW_P12V_PVCCFA_EHV_FIVRA_CPU1_L")
	)
	(via
		(at 46.52391 -361.337606)
		(size 0.508)
		(drill 0.254)
		(layers "F.Cu" "B.Cu")
		(net "SW_P12V_PVCCFA_EHV_FIVRA_CPU1_L")
	)
	(via
		(at 45.08754 -361.512612)
		(size 0.508)
		(drill 0.254)
		(layers "F.Cu" "B.Cu")
		(net "SW_P12V_PVCCFA_EHV_FIVRA_CPU1_L")
	)
	(via
		(at 51.91887 -355.41077)
		(size 0.49022)
		(drill 0.254)
		(layers "F.Cu" "B.Cu")
		(net "SW_P12V_PVCCFA_EHV_FIVRA_CPU1_L")
	)
	(via
		(at 46.50105 -363.327696)
		(size 0.508)
		(drill 0.254)
		(layers "F.Cu" "B.Cu")
		(net "SW_P12V_PVCCFA_EHV_FIVRA_CPU1_L")
	)
	(via
		(at 47.26305 -362.057696)
		(size 0.508)
		(drill 0.254)
		(layers "F.Cu" "B.Cu")
		(net "SW_P12V_PVCCFA_EHV_FIVRA_CPU1_L")
	)
	(via
		(at 46.50105 -362.057696)
		(size 0.508)
		(drill 0.254)
		(layers "F.Cu" "B.Cu")
		(net "SW_P12V_PVCCFA_EHV_FIVRA_CPU1_L")
	)
	(via
		(at 47.27829 -360.625136)
		(size 0.508)
		(drill 0.254)
		(layers "F.Cu" "B.Cu")
		(net "SW_P12V_PVCCFA_EHV_FIVRA_CPU1_L")
	)
	(via
		(at 45.328332 -356.150926)
		(size 0.508)
		(drill 0.254)
		(layers "F.Cu" "B.Cu")
		(net "SW_P12V_PVCCFA_EHV_FIVRA_CPU1_L")
	)
	(via
		(at 45.08754 -360.745532)
		(size 0.508)
		(drill 0.254)
		(layers "F.Cu" "B.Cu")
		(net "SW_P12V_PVCCFA_EHV_FIVRA_CPU1_L")
	)
	(via
		(at 54.381654 -355.896926)
		(size 0.508)
		(drill 0.254)
		(layers "F.Cu" "B.Cu")
		(net "SW_P12V_PVCCFA_EHV_FIVRA_CPU1_L")
	)
	(via
		(at 44.168568 -356.298246)
		(size 0.508)
		(drill 0.254)
		(layers "F.Cu" "B.Cu")
		(net "SW_P12V_PVCCFA_EHV_FIVRA_CPU1_L")
	)
	(via
		(at 53.69433 -355.60127)
		(size 0.49022)
		(drill 0.254)
		(layers "F.Cu" "B.Cu")
		(net "SW_P12V_PVCCFA_EHV_FIVRA_CPU1_L")
	)
	(via
		(at 44.769532 -355.769926)
		(size 0.508)
		(drill 0.254)
		(layers "F.Cu" "B.Cu")
		(net "SW_P12V_PVCCFA_EHV_FIVRA_CPU1_L")
	)
	(via
		(at 45.968158 -354.627942)
		(size 0.508)
		(drill 0.254)
		(layers "F.Cu" "B.Cu")
		(net "SW_P12V_PVCCFA_EHV_FIVRA_CPU1_L")
	)
	(via
		(at 46.50105 -362.692696)
		(size 0.508)
		(drill 0.254)
		(layers "F.Cu" "B.Cu")
		(net "SW_P12V_PVCCFA_EHV_FIVRA_CPU1_L")
	)
	(via
		(at 55.004716 -356.886256)
		(size 0.508)
		(drill 0.254)
		(layers "F.Cu" "B.Cu")
		(net "SW_P12V_PVCCFA_EHV_FIVRA_CPU1_L")
	)
	(via
		(at 55.004716 -356.149656)
		(size 0.508)
		(drill 0.254)
		(layers "F.Cu" "B.Cu")
		(net "SW_P12V_PVCCFA_EHV_FIVRA_CPU1_L")
	)
	(via
		(at 53.10251 -355.41077)
		(size 0.49022)
		(drill 0.254)
		(layers "F.Cu" "B.Cu")
		(net "SW_P12V_PVCCFA_EHV_FIVRA_CPU1_L")
	)
	(via
		(at 46.51629 -360.625136)
		(size 0.508)
		(drill 0.254)
		(layers "F.Cu" "B.Cu")
		(net "SW_P12V_PVCCFA_EHV_FIVRA_CPU1_L")
	)
	(via
		(at 52.51069 -355.60127)
		(size 0.49022)
		(drill 0.254)
		(layers "F.Cu" "B.Cu")
		(net "SW_P12V_PVCCFA_EHV_FIVRA_CPU1_L")
	)
	(via
		(at 42.822368 -355.60127)
		(size 0.49022)
		(drill 0.254)
		(layers "F.Cu" "B.Cu")
		(net "SW_P12V_PVCCFA_EHV_FIVRA_CPU1_L")
	)
	(via
		(at 45.328332 -356.887526)
		(size 0.508)
		(drill 0.254)
		(layers "F.Cu" "B.Cu")
		(net "SW_P12V_PVCCFA_EHV_FIVRA_CPU1_L")
	)
	(via
		(at 44.006008 -355.60127)
		(size 0.49022)
		(drill 0.254)
		(layers "F.Cu" "B.Cu")
		(net "SW_P12V_PVCCFA_EHV_FIVRA_CPU1_L")
	)
	(via
		(at 43.414188 -355.41077)
		(size 0.49022)
		(drill 0.254)
		(layers "F.Cu" "B.Cu")
		(net "SW_P12V_PVCCFA_EHV_FIVRA_CPU1_L")
	)
	(via
		(at 53.85689 -357.072946)
		(size 0.508)
		(drill 0.254)
		(layers "F.Cu" "B.Cu")
		(net "SW_P12V_PVCCFA_EHV_FIVRA_CPU1_L")
	)
	(via
		(at 47.26305 -362.692696)
		(size 0.508)
		(drill 0.254)
		(layers "F.Cu" "B.Cu")
		(net "SW_P12V_PVCCFA_EHV_FIVRA_CPU1_L")
	)
	(via
		(at 54.407054 -356.658926)
		(size 0.508)
		(drill 0.254)
		(layers "F.Cu" "B.Cu")
		(net "SW_P12V_PVCCFA_EHV_FIVRA_CPU1_L")
	)
	(via
		(at 47.26305 -363.327696)
		(size 0.508)
		(drill 0.254)
		(layers "F.Cu" "B.Cu")
		(net "SW_P12V_PVCCFA_EHV_FIVRA_CPU1_L")
	)
	(via
		(at 45.84954 -360.745532)
		(size 0.508)
		(drill 0.254)
		(layers "F.Cu" "B.Cu")
		(net "SW_P12V_PVCCFA_EHV_FIVRA_CPU1_L")
	)
	(via
		(at 421.8813 -369.87734)
		(size 0.508)
		(drill 0.254)
		(layers "F.Cu" "B.Cu")
		(net "SW_P12V_PVCCFA_EHV_FIVRA_CPU0_R")
	)
	(via
		(at 429.535844 -364.81766)
		(size 0.508)
		(drill 0.254)
		(layers "F.Cu" "B.Cu")
		(net "SW_P12V_PVCCFA_EHV_FIVRA_CPU0_R")
	)
	(via
		(at 428.45228 -364.87608)
		(size 0.508)
		(drill 0.254)
		(layers "F.Cu" "B.Cu")
		(net "SW_P12V_PVCCFA_EHV_FIVRA_CPU0_R")
	)
	(via
		(at 419.68293 -370.052346)
		(size 0.508)
		(drill 0.254)
		(layers "F.Cu" "B.Cu")
		(net "SW_P12V_PVCCFA_EHV_FIVRA_CPU0_R")
	)
	(via
		(at 427.6979 -363.950504)
		(size 0.49022)
		(drill 0.254)
		(layers "F.Cu" "B.Cu")
		(net "SW_P12V_PVCCFA_EHV_FIVRA_CPU0_R")
	)
	(via
		(at 421.85844 -370.59743)
		(size 0.508)
		(drill 0.254)
		(layers "F.Cu" "B.Cu")
		(net "SW_P12V_PVCCFA_EHV_FIVRA_CPU0_R")
	)
	(via
		(at 420.44493 -370.052346)
		(size 0.508)
		(drill 0.254)
		(layers "F.Cu" "B.Cu")
		(net "SW_P12V_PVCCFA_EHV_FIVRA_CPU0_R")
	)
	(via
		(at 420.44493 -369.285266)
		(size 0.508)
		(drill 0.254)
		(layers "F.Cu" "B.Cu")
		(net "SW_P12V_PVCCFA_EHV_FIVRA_CPU0_R")
	)
	(via
		(at 421.1193 -369.87734)
		(size 0.508)
		(drill 0.254)
		(layers "F.Cu" "B.Cu")
		(net "SW_P12V_PVCCFA_EHV_FIVRA_CPU0_R")
	)
	(via
		(at 418.763958 -365.53648)
		(size 0.508)
		(drill 0.254)
		(layers "F.Cu" "B.Cu")
		(net "SW_P12V_PVCCFA_EHV_FIVRA_CPU0_R")
	)
	(via
		(at 429.535844 -364.08106)
		(size 0.508)
		(drill 0.254)
		(layers "F.Cu" "B.Cu")
		(net "SW_P12V_PVCCFA_EHV_FIVRA_CPU0_R")
	)
	(via
		(at 420.563548 -363.167676)
		(size 0.508)
		(drill 0.254)
		(layers "F.Cu" "B.Cu")
		(net "SW_P12V_PVCCFA_EHV_FIVRA_CPU0_R")
	)
	(via
		(at 419.923722 -363.92866)
		(size 0.508)
		(drill 0.254)
		(layers "F.Cu" "B.Cu")
		(net "SW_P12V_PVCCFA_EHV_FIVRA_CPU0_R")
	)
	(via
		(at 421.09644 -372.50243)
		(size 0.508)
		(drill 0.254)
		(layers "F.Cu" "B.Cu")
		(net "SW_P12V_PVCCFA_EHV_FIVRA_CPU0_R")
	)
	(via
		(at 421.85844 -372.50243)
		(size 0.508)
		(drill 0.254)
		(layers "F.Cu" "B.Cu")
		(net "SW_P12V_PVCCFA_EHV_FIVRA_CPU0_R")
	)
	(via
		(at 429.535844 -365.55426)
		(size 0.508)
		(drill 0.254)
		(layers "F.Cu" "B.Cu")
		(net "SW_P12V_PVCCFA_EHV_FIVRA_CPU0_R")
	)
	(via
		(at 418.009578 -363.950504)
		(size 0.49022)
		(drill 0.254)
		(layers "F.Cu" "B.Cu")
		(net "SW_P12V_PVCCFA_EHV_FIVRA_CPU0_R")
	)
	(via
		(at 428.45228 -365.61268)
		(size 0.508)
		(drill 0.254)
		(layers "F.Cu" "B.Cu")
		(net "SW_P12V_PVCCFA_EHV_FIVRA_CPU0_R")
	)
	(via
		(at 416.825938 -363.950504)
		(size 0.49022)
		(drill 0.254)
		(layers "F.Cu" "B.Cu")
		(net "SW_P12V_PVCCFA_EHV_FIVRA_CPU0_R")
	)
	(via
		(at 427.10608 -364.141004)
		(size 0.49022)
		(drill 0.254)
		(layers "F.Cu" "B.Cu")
		(net "SW_P12V_PVCCFA_EHV_FIVRA_CPU0_R")
	)
	(via
		(at 429.002444 -365.19866)
		(size 0.508)
		(drill 0.254)
		(layers "F.Cu" "B.Cu")
		(net "SW_P12V_PVCCFA_EHV_FIVRA_CPU0_R")
	)
	(via
		(at 418.601398 -364.141004)
		(size 0.49022)
		(drill 0.254)
		(layers "F.Cu" "B.Cu")
		(net "SW_P12V_PVCCFA_EHV_FIVRA_CPU0_R")
	)
	(via
		(at 419.68293 -369.285266)
		(size 0.508)
		(drill 0.254)
		(layers "F.Cu" "B.Cu")
		(net "SW_P12V_PVCCFA_EHV_FIVRA_CPU0_R")
	)
	(via
		(at 428.28972 -364.141004)
		(size 0.49022)
		(drill 0.254)
		(layers "F.Cu" "B.Cu")
		(net "SW_P12V_PVCCFA_EHV_FIVRA_CPU0_R")
	)
	(via
		(at 421.11168 -369.16487)
		(size 0.508)
		(drill 0.254)
		(layers "F.Cu" "B.Cu")
		(net "SW_P12V_PVCCFA_EHV_FIVRA_CPU0_R")
	)
	(via
		(at 417.417758 -364.141004)
		(size 0.49022)
		(drill 0.254)
		(layers "F.Cu" "B.Cu")
		(net "SW_P12V_PVCCFA_EHV_FIVRA_CPU0_R")
	)
	(via
		(at 430.121568 -363.171232)
		(size 0.508)
		(drill 0.254)
		(layers "F.Cu" "B.Cu")
		(net "SW_P12V_PVCCFA_EHV_FIVRA_CPU0_R")
	)
	(via
		(at 419.390322 -365.04626)
		(size 0.508)
		(drill 0.254)
		(layers "F.Cu" "B.Cu")
		(net "SW_P12V_PVCCFA_EHV_FIVRA_CPU0_R")
	)
	(via
		(at 428.977044 -364.43666)
		(size 0.508)
		(drill 0.254)
		(layers "F.Cu" "B.Cu")
		(net "SW_P12V_PVCCFA_EHV_FIVRA_CPU0_R")
	)
	(via
		(at 419.923722 -365.40186)
		(size 0.508)
		(drill 0.254)
		(layers "F.Cu" "B.Cu")
		(net "SW_P12V_PVCCFA_EHV_FIVRA_CPU0_R")
	)
	(via
		(at 421.09644 -371.86743)
		(size 0.508)
		(drill 0.254)
		(layers "F.Cu" "B.Cu")
		(net "SW_P12V_PVCCFA_EHV_FIVRA_CPU0_R")
	)
	(via
		(at 418.763958 -364.79988)
		(size 0.508)
		(drill 0.254)
		(layers "F.Cu" "B.Cu")
		(net "SW_P12V_PVCCFA_EHV_FIVRA_CPU0_R")
	)
	(via
		(at 421.87368 -369.16487)
		(size 0.508)
		(drill 0.254)
		(layers "F.Cu" "B.Cu")
		(net "SW_P12V_PVCCFA_EHV_FIVRA_CPU0_R")
	)
	(via
		(at 419.364922 -364.28426)
		(size 0.508)
		(drill 0.254)
		(layers "F.Cu" "B.Cu")
		(net "SW_P12V_PVCCFA_EHV_FIVRA_CPU0_R")
	)
	(via
		(at 421.85844 -371.23243)
		(size 0.508)
		(drill 0.254)
		(layers "F.Cu" "B.Cu")
		(net "SW_P12V_PVCCFA_EHV_FIVRA_CPU0_R")
	)
	(via
		(at 421.09644 -371.23243)
		(size 0.508)
		(drill 0.254)
		(layers "F.Cu" "B.Cu")
		(net "SW_P12V_PVCCFA_EHV_FIVRA_CPU0_R")
	)
	(via
		(at 426.51426 -363.950504)
		(size 0.49022)
		(drill 0.254)
		(layers "F.Cu" "B.Cu")
		(net "SW_P12V_PVCCFA_EHV_FIVRA_CPU0_R")
	)
	(via
		(at 421.85844 -371.86743)
		(size 0.508)
		(drill 0.254)
		(layers "F.Cu" "B.Cu")
		(net "SW_P12V_PVCCFA_EHV_FIVRA_CPU0_R")
	)
	(via
		(at 421.09644 -370.59743)
		(size 0.508)
		(drill 0.254)
		(layers "F.Cu" "B.Cu")
		(net "SW_P12V_PVCCFA_EHV_FIVRA_CPU0_R")
	)
	(via
		(at 419.923722 -364.66526)
		(size 0.508)
		(drill 0.254)
		(layers "F.Cu" "B.Cu")
		(net "SW_P12V_PVCCFA_EHV_FIVRA_CPU0_R")
	)
	(via
		(at 293.722044 -371.920262)
		(size 0.508)
		(drill 0.254)
		(layers "F.Cu" "B.Cu")
		(net "SW_P12V_PVCCFA_EHV_FIVRA_CPU0_L")
	)
	(via
		(at 301.077884 -365.563912)
		(size 0.508)
		(drill 0.254)
		(layers "F.Cu" "B.Cu")
		(net "SW_P12V_PVCCFA_EHV_FIVRA_CPU0_L")
	)
	(via
		(at 302.747172 -363.859064)
		(size 0.508)
		(drill 0.254)
		(layers "F.Cu" "B.Cu")
		(net "SW_P12V_PVCCFA_EHV_FIVRA_CPU0_L")
	)
	(via
		(at 292.523926 -364.667292)
		(size 0.508)
		(drill 0.254)
		(layers "F.Cu" "B.Cu")
		(net "SW_P12V_PVCCFA_EHV_FIVRA_CPU0_L")
	)
	(via
		(at 291.990526 -365.784892)
		(size 0.508)
		(drill 0.254)
		(layers "F.Cu" "B.Cu")
		(net "SW_P12V_PVCCFA_EHV_FIVRA_CPU0_L")
	)
	(via
		(at 291.389562 -366.259872)
		(size 0.508)
		(drill 0.254)
		(layers "F.Cu" "B.Cu")
		(net "SW_P12V_PVCCFA_EHV_FIVRA_CPU0_L")
	)
	(via
		(at 302.161448 -365.505492)
		(size 0.508)
		(drill 0.254)
		(layers "F.Cu" "B.Cu")
		(net "SW_P12V_PVCCFA_EHV_FIVRA_CPU0_L")
	)
	(via
		(at 299.731684 -364.828836)
		(size 0.49022)
		(drill 0.254)
		(layers "F.Cu" "B.Cu")
		(net "SW_P12V_PVCCFA_EHV_FIVRA_CPU0_L")
	)
	(via
		(at 300.323504 -364.638336)
		(size 0.49022)
		(drill 0.254)
		(layers "F.Cu" "B.Cu")
		(net "SW_P12V_PVCCFA_EHV_FIVRA_CPU0_L")
	)
	(via
		(at 293.744904 -370.565172)
		(size 0.508)
		(drill 0.254)
		(layers "F.Cu" "B.Cu")
		(net "SW_P12V_PVCCFA_EHV_FIVRA_CPU0_L")
	)
	(via
		(at 289.451542 -364.638336)
		(size 0.49022)
		(drill 0.254)
		(layers "F.Cu" "B.Cu")
		(net "SW_P12V_PVCCFA_EHV_FIVRA_CPU0_L")
	)
	(via
		(at 292.308534 -370.740178)
		(size 0.508)
		(drill 0.254)
		(layers "F.Cu" "B.Cu")
		(net "SW_P12V_PVCCFA_EHV_FIVRA_CPU0_L")
	)
	(via
		(at 294.484044 -373.190262)
		(size 0.508)
		(drill 0.254)
		(layers "F.Cu" "B.Cu")
		(net "SW_P12V_PVCCFA_EHV_FIVRA_CPU0_L")
	)
	(via
		(at 294.484044 -371.920262)
		(size 0.508)
		(drill 0.254)
		(layers "F.Cu" "B.Cu")
		(net "SW_P12V_PVCCFA_EHV_FIVRA_CPU0_L")
	)
	(via
		(at 291.965126 -365.022892)
		(size 0.508)
		(drill 0.254)
		(layers "F.Cu" "B.Cu")
		(net "SW_P12V_PVCCFA_EHV_FIVRA_CPU0_L")
	)
	(via
		(at 293.722044 -373.190262)
		(size 0.508)
		(drill 0.254)
		(layers "F.Cu" "B.Cu")
		(net "SW_P12V_PVCCFA_EHV_FIVRA_CPU0_L")
	)
	(via
		(at 293.722044 -371.285262)
		(size 0.508)
		(drill 0.254)
		(layers "F.Cu" "B.Cu")
		(net "SW_P12V_PVCCFA_EHV_FIVRA_CPU0_L")
	)
	(via
		(at 302.161448 -364.768892)
		(size 0.508)
		(drill 0.254)
		(layers "F.Cu" "B.Cu")
		(net "SW_P12V_PVCCFA_EHV_FIVRA_CPU0_L")
	)
	(via
		(at 292.523926 -365.403892)
		(size 0.508)
		(drill 0.254)
		(layers "F.Cu" "B.Cu")
		(net "SW_P12V_PVCCFA_EHV_FIVRA_CPU0_L")
	)
	(via
		(at 301.077884 -366.300512)
		(size 0.508)
		(drill 0.254)
		(layers "F.Cu" "B.Cu")
		(net "SW_P12V_PVCCFA_EHV_FIVRA_CPU0_L")
	)
	(via
		(at 292.308534 -369.973098)
		(size 0.508)
		(drill 0.254)
		(layers "F.Cu" "B.Cu")
		(net "SW_P12V_PVCCFA_EHV_FIVRA_CPU0_L")
	)
	(via
		(at 290.043362 -364.828836)
		(size 0.49022)
		(drill 0.254)
		(layers "F.Cu" "B.Cu")
		(net "SW_P12V_PVCCFA_EHV_FIVRA_CPU0_L")
	)
	(via
		(at 300.915324 -364.828836)
		(size 0.49022)
		(drill 0.254)
		(layers "F.Cu" "B.Cu")
		(net "SW_P12V_PVCCFA_EHV_FIVRA_CPU0_L")
	)
	(via
		(at 293.070534 -369.973098)
		(size 0.508)
		(drill 0.254)
		(layers "F.Cu" "B.Cu")
		(net "SW_P12V_PVCCFA_EHV_FIVRA_CPU0_L")
	)
	(via
		(at 301.628048 -365.886492)
		(size 0.508)
		(drill 0.254)
		(layers "F.Cu" "B.Cu")
		(net "SW_P12V_PVCCFA_EHV_FIVRA_CPU0_L")
	)
	(via
		(at 301.602648 -365.124492)
		(size 0.508)
		(drill 0.254)
		(layers "F.Cu" "B.Cu")
		(net "SW_P12V_PVCCFA_EHV_FIVRA_CPU0_L")
	)
	(via
		(at 293.737284 -369.852702)
		(size 0.508)
		(drill 0.254)
		(layers "F.Cu" "B.Cu")
		(net "SW_P12V_PVCCFA_EHV_FIVRA_CPU0_L")
	)
	(via
		(at 293.189152 -363.855508)
		(size 0.508)
		(drill 0.254)
		(layers "F.Cu" "B.Cu")
		(net "SW_P12V_PVCCFA_EHV_FIVRA_CPU0_L")
	)
	(via
		(at 294.499284 -369.852702)
		(size 0.508)
		(drill 0.254)
		(layers "F.Cu" "B.Cu")
		(net "SW_P12V_PVCCFA_EHV_FIVRA_CPU0_L")
	)
	(via
		(at 302.161448 -366.242092)
		(size 0.508)
		(drill 0.254)
		(layers "F.Cu" "B.Cu")
		(net "SW_P12V_PVCCFA_EHV_FIVRA_CPU0_L")
	)
	(via
		(at 294.484044 -371.285262)
		(size 0.508)
		(drill 0.254)
		(layers "F.Cu" "B.Cu")
		(net "SW_P12V_PVCCFA_EHV_FIVRA_CPU0_L")
	)
	(via
		(at 293.070534 -370.740178)
		(size 0.508)
		(drill 0.254)
		(layers "F.Cu" "B.Cu")
		(net "SW_P12V_PVCCFA_EHV_FIVRA_CPU0_L")
	)
	(via
		(at 292.523926 -366.140492)
		(size 0.508)
		(drill 0.254)
		(layers "F.Cu" "B.Cu")
		(net "SW_P12V_PVCCFA_EHV_FIVRA_CPU0_L")
	)
	(via
		(at 294.484044 -372.555262)
		(size 0.508)
		(drill 0.254)
		(layers "F.Cu" "B.Cu")
		(net "SW_P12V_PVCCFA_EHV_FIVRA_CPU0_L")
	)
	(via
		(at 293.722044 -372.555262)
		(size 0.508)
		(drill 0.254)
		(layers "F.Cu" "B.Cu")
		(net "SW_P12V_PVCCFA_EHV_FIVRA_CPU0_L")
	)
	(via
		(at 299.139864 -364.638336)
		(size 0.49022)
		(drill 0.254)
		(layers "F.Cu" "B.Cu")
		(net "SW_P12V_PVCCFA_EHV_FIVRA_CPU0_L")
	)
	(via
		(at 291.227002 -364.828836)
		(size 0.49022)
		(drill 0.254)
		(layers "F.Cu" "B.Cu")
		(net "SW_P12V_PVCCFA_EHV_FIVRA_CPU0_L")
	)
	(via
		(at 290.635182 -364.638336)
		(size 0.49022)
		(drill 0.254)
		(layers "F.Cu" "B.Cu")
		(net "SW_P12V_PVCCFA_EHV_FIVRA_CPU0_L")
	)
	(via
		(at 294.506904 -370.565172)
		(size 0.508)
		(drill 0.254)
		(layers "F.Cu" "B.Cu")
		(net "SW_P12V_PVCCFA_EHV_FIVRA_CPU0_L")
	)
	(via
		(at 291.389562 -365.523272)
		(size 0.508)
		(drill 0.254)
		(layers "F.Cu" "B.Cu")
		(net "SW_P12V_PVCCFA_EHV_FIVRA_CPU0_L")
	)
	(via
		(at 252.664722 -73.620122)
		(size 0.508)
		(drill 0.254)
		(layers "F.Cu" "B.Cu")
		(net "SW_P12V_AUX_P1V05_PCH_AUX_FLT")
	)
	(segment
		(start 104.963214 -357.448358)
		(end 105.70337 -357.448358)
		(width 0.12954)
		(layer "F.Cu")
		(net "SVID_DIO_PVCCIN_CPU1_R")
	)
	(segment
		(start 104.424734 -356.909878)
		(end 104.963214 -357.448358)
		(width 0.12954)
		(layer "F.Cu")
		(net "SVID_DIO_PVCCIN_CPU1_R")
	)
	(segment
		(start 103.245666 -356.668578)
		(end 103.486966 -356.909878)
		(width 0.12954)
		(layer "F.Cu")
		(net "SVID_DIO_PVCCIN_CPU1_R")
	)
	(segment
		(start 103.486966 -356.909878)
		(end 104.424734 -356.909878)
		(width 0.12954)
		(layer "F.Cu")
		(net "SVID_DIO_PVCCIN_CPU1_R")
	)
	(via
		(at 104.424734 -356.909878)
		(size 0.762)
		(drill 0.381)
		(layers "F.Cu" "B.Cu")
		(net "SVID_DIO_PVCCIN_CPU1_R")
	)
	(segment
		(start 352.364548 -356.909878)
		(end 352.302572 -356.847902)
		(width 0.12954)
		(layer "F.Cu")
		(net "SVID_DIO_PVCCIN_CPU0_R")
	)
	(segment
		(start 352.302572 -356.847902)
		(end 351.364804 -356.847902)
		(width 0.12954)
		(layer "F.Cu")
		(net "SVID_DIO_PVCCIN_CPU0_R")
	)
	(segment
		(start 353.643184 -357.448358)
		(end 352.903028 -357.448358)
		(width 0.12954)
		(layer "F.Cu")
		(net "SVID_DIO_PVCCIN_CPU0_R")
	)
	(segment
		(start 351.364804 -356.847902)
		(end 351.18548 -356.668578)
		(width 0.12954)
		(layer "F.Cu")
		(net "SVID_DIO_PVCCIN_CPU0_R")
	)
	(segment
		(start 352.903028 -357.448358)
		(end 352.364548 -356.909878)
		(width 0.12954)
		(layer "F.Cu")
		(net "SVID_DIO_PVCCIN_CPU0_R")
	)
	(via
		(at 352.364548 -356.909878)
		(size 0.762)
		(drill 0.381)
		(layers "F.Cu" "B.Cu")
		(net "SVID_DIO_PVCCIN_CPU0_R")
	)
	(segment
		(start 36.427918 -130.63347)
		(end 35.550094 -130.63347)
		(width 0.12954)
		(layer "F.Cu")
		(net "SVID_DIO_PVCCINFAON_CPU1_R")
	)
	(segment
		(start 36.556188 -130.76174)
		(end 36.427918 -130.63347)
		(width 0.12954)
		(layer "F.Cu")
		(net "SVID_DIO_PVCCINFAON_CPU1_R")
	)
	(segment
		(start 35.550094 -130.63347)
		(end 34.461196 -130.63347)
		(width 0.12954)
		(layer "F.Cu")
		(net "SVID_DIO_PVCCINFAON_CPU1_R")
	)
	(via
		(at 35.550094 -130.63347)
		(size 0.4064)
		(drill 0.2032)
		(layers "F.Cu" "B.Cu")
		(net "SVID_DIO_PVCCINFAON_CPU1_R")
	)
	(segment
		(start 428.61103 -137.414508)
		(end 428.105062 -137.414508)
		(width 0.12954)
		(layer "F.Cu")
		(net "SVID_DIO_PVCCINFAON_CPU0_R")
	)
	(segment
		(start 428.781464 -137.584942)
		(end 428.61103 -137.414508)
		(width 0.12954)
		(layer "F.Cu")
		(net "SVID_DIO_PVCCINFAON_CPU0_R")
	)
	(segment
		(start 430.200054 -137.542778)
		(end 430.15789 -137.584942)
		(width 0.12954)
		(layer "F.Cu")
		(net "SVID_DIO_PVCCINFAON_CPU0_R")
	)
	(segment
		(start 430.15789 -137.584942)
		(end 429.19777 -137.584942)
		(width 0.12954)
		(layer "F.Cu")
		(net "SVID_DIO_PVCCINFAON_CPU0_R")
	)
	(segment
		(start 429.19777 -137.584942)
		(end 428.781464 -137.584942)
		(width 0.12954)
		(layer "F.Cu")
		(net "SVID_DIO_PVCCINFAON_CPU0_R")
	)
	(via
		(at 429.19777 -137.584942)
		(size 0.4064)
		(drill 0.2032)
		(layers "F.Cu" "B.Cu")
		(net "SVID_DIO_PVCCINFAON_CPU0_R")
	)
	(segment
		(start 23.678388 -163.76396)
		(end 23.979632 -163.76396)
		(width 0.12954)
		(layer "F.Cu")
		(net "SVID_DIO_PVCCD_HV_CPU1_R")
	)
	(segment
		(start 22.53361 -164.735256)
		(end 22.85619 -164.412676)
		(width 0.12954)
		(layer "F.Cu")
		(net "SVID_DIO_PVCCD_HV_CPU1_R")
	)
	(segment
		(start 22.85619 -164.412676)
		(end 23.029672 -164.412676)
		(width 0.12954)
		(layer "F.Cu")
		(net "SVID_DIO_PVCCD_HV_CPU1_R")
	)
	(segment
		(start 24.638 -163.827206)
		(end 24.574754 -163.76396)
		(width 0.12954)
		(layer "F.Cu")
		(net "SVID_DIO_PVCCD_HV_CPU1_R")
	)
	(segment
		(start 24.574754 -163.76396)
		(end 23.979632 -163.76396)
		(width 0.12954)
		(layer "F.Cu")
		(net "SVID_DIO_PVCCD_HV_CPU1_R")
	)
	(segment
		(start 25.26284 -163.827206)
		(end 24.638 -163.827206)
		(width 0.12954)
		(layer "F.Cu")
		(net "SVID_DIO_PVCCD_HV_CPU1_R")
	)
	(segment
		(start 23.029672 -164.412676)
		(end 23.678388 -163.76396)
		(width 0.12954)
		(layer "F.Cu")
		(net "SVID_DIO_PVCCD_HV_CPU1_R")
	)
	(via
		(at 23.979632 -163.76396)
		(size 0.762)
		(drill 0.381)
		(layers "F.Cu" "B.Cu")
		(net "SVID_DIO_PVCCD_HV_CPU1_R")
	)
	(segment
		(start 435.934612 -124.685298)
		(end 435.23789 -123.988576)
		(width 0.12954)
		(layer "F.Cu")
		(net "SVID_DIO_PVCCD_HV_CPU0_R")
	)
	(segment
		(start 436.13959 -124.680726)
		(end 435.934612 -124.885704)
		(width 0.12954)
		(layer "F.Cu")
		(net "SVID_DIO_PVCCD_HV_CPU0_R")
	)
	(segment
		(start 435.934612 -124.885704)
		(end 435.934612 -124.685298)
		(width 0.12954)
		(layer "F.Cu")
		(net "SVID_DIO_PVCCD_HV_CPU0_R")
	)
	(segment
		(start 435.23789 -123.988576)
		(end 434.901086 -123.988576)
		(width 0.12954)
		(layer "F.Cu")
		(net "SVID_DIO_PVCCD_HV_CPU0_R")
	)
	(segment
		(start 436.842916 -124.680726)
		(end 436.13959 -124.680726)
		(width 0.12954)
		(layer "F.Cu")
		(net "SVID_DIO_PVCCD_HV_CPU0_R")
	)
	(via
		(at 435.934612 -124.885704)
		(size 0.508)
		(drill 0.254)
		(layers "F.Cu" "B.Cu")
		(net "SVID_DIO_PVCCD_HV_CPU0_R")
	)
	(segment
		(start 21.253196 -164.194744)
		(end 21.134832 -164.194744)
		(width 0.12954)
		(layer "F.Cu")
		(net "SVID_DIO1_CPU1_R")
	)
	(segment
		(start 21.73351 -164.675058)
		(end 21.253196 -164.194744)
		(width 0.12954)
		(layer "F.Cu")
		(net "SVID_DIO1_CPU1_R")
	)
	(segment
		(start 21.134832 -164.152834)
		(end 20.701254 -163.719256)
		(width 0.12954)
		(layer "F.Cu")
		(net "SVID_DIO1_CPU1_R")
	)
	(segment
		(start 21.134832 -164.194744)
		(end 21.134832 -164.152834)
		(width 0.12954)
		(layer "F.Cu")
		(net "SVID_DIO1_CPU1_R")
	)
	(segment
		(start 21.73351 -164.735256)
		(end 21.73351 -164.675058)
		(width 0.12954)
		(layer "F.Cu")
		(net "SVID_DIO1_CPU1_R")
	)
	(segment
		(start 20.701254 -163.719256)
		(end 20.51431 -163.719256)
		(width 0.12954)
		(layer "F.Cu")
		(net "SVID_DIO1_CPU1_R")
	)
	(via
		(at 72.401684 -189.662308)
		(size 0.508)
		(drill 0.254)
		(layers "F.Cu" "B.Cu")
		(net "SVID_DIO1_CPU1_R")
	)
	(via
		(at 21.134832 -164.194744)
		(size 0.508)
		(drill 0.254)
		(layers "F.Cu" "B.Cu")
		(net "SVID_DIO1_CPU1_R")
	)
	(segment
		(start 72.401684 -190.344806)
		(end 73.290684 -190.344806)
		(width 0.12954)
		(layer "B.Cu")
		(net "SVID_DIO1_CPU1_R")
	)
	(segment
		(start 72.401684 -189.662308)
		(end 72.401684 -190.344806)
		(width 0.12954)
		(layer "B.Cu")
		(net "SVID_DIO1_CPU1_R")
	)
	(segment
		(start 73.290684 -190.344806)
		(end 73.316084 -190.319406)
		(width 0.12954)
		(layer "B.Cu")
		(net "SVID_DIO1_CPU1_R")
	)
	(segment
		(start 19.582638 -164.194744)
		(end 14.5034 -169.273982)
		(width 0.127)
		(layer "In13.Cu")
		(net "SVID_DIO1_CPU1_R")
	)
	(segment
		(start 14.5034 -169.273982)
		(end 14.5034 -182.287418)
		(width 0.127)
		(layer "In13.Cu")
		(net "SVID_DIO1_CPU1_R")
	)
	(segment
		(start 21.134832 -164.194744)
		(end 19.582638 -164.194744)
		(width 0.127)
		(layer "In13.Cu")
		(net "SVID_DIO1_CPU1_R")
	)
	(segment
		(start 14.5034 -182.287418)
		(end 17.17675 -184.960768)
		(width 0.127)
		(layer "In13.Cu")
		(net "SVID_DIO1_CPU1_R")
	)
	(segment
		(start 71.827644 -189.088268)
		(end 72.401684 -189.662308)
		(width 0.127)
		(layer "In13.Cu")
		(net "SVID_DIO1_CPU1_R")
	)
	(segment
		(start 63.05042 -184.960768)
		(end 67.17792 -189.088268)
		(width 0.127)
		(layer "In13.Cu")
		(net "SVID_DIO1_CPU1_R")
	)
	(segment
		(start 67.17792 -189.088268)
		(end 71.827644 -189.088268)
		(width 0.127)
		(layer "In13.Cu")
		(net "SVID_DIO1_CPU1_R")
	)
	(segment
		(start 17.17675 -184.960768)
		(end 63.05042 -184.960768)
		(width 0.127)
		(layer "In13.Cu")
		(net "SVID_DIO1_CPU1_R")
	)
	(segment
		(start 108.351066 -233.87812)
		(end 108.351066 -233.342434)
		(width 0.12954)
		(layer "F.Cu")
		(net "SVID_DIO1_CPU1")
	)
	(segment
		(start 108.351066 -233.342434)
		(end 108.350812 -233.34218)
		(width 0.12954)
		(layer "F.Cu")
		(net "SVID_DIO1_CPU1")
	)
	(via
		(at 108.350812 -233.34218)
		(size 0.4572)
		(drill 0.2032)
		(layers "F.Cu" "B.Cu")
		(net "SVID_DIO1_CPU1")
	)
	(via
		(at 68.355718 -223.90989)
		(size 0.6604)
		(drill 0.3302)
		(layers "F.Cu" "B.Cu")
		(net "SVID_DIO1_CPU1")
	)
	(segment
		(start 68.355718 -225.505518)
		(end 68.355718 -223.90989)
		(width 0.12954)
		(layer "B.Cu")
		(net "SVID_DIO1_CPU1")
	)
	(segment
		(start 89.287096 -233.840528)
		(end 89.272364 -233.831892)
		(width 0.0889)
		(layer "B.Cu")
		(net "SVID_DIO1_CPU1")
	)
	(segment
		(start 93.981778 -233.837988)
		(end 93.971364 -233.831892)
		(width 0.0889)
		(layer "B.Cu")
		(net "SVID_DIO1_CPU1")
	)
	(segment
		(start 67.333876 -221.480888)
		(end 67.333876 -206.185516)
		(width 0.12954)
		(layer "B.Cu")
		(net "SVID_DIO1_CPU1")
	)
	(segment
		(start 78.130146 -235.279946)
		(end 68.355718 -225.505518)
		(width 0.12954)
		(layer "B.Cu")
		(net "SVID_DIO1_CPU1")
	)
	(segment
		(start 96.805496 -233.840528)
		(end 96.790764 -233.831892)
		(width 0.0889)
		(layer "B.Cu")
		(net "SVID_DIO1_CPU1")
	)
	(segment
		(start 101.499924 -233.837988)
		(end 101.48951 -233.831892)
		(width 0.0889)
		(layer "B.Cu")
		(net "SVID_DIO1_CPU1")
	)
	(segment
		(start 84.746338 -235.279946)
		(end 82.898996 -235.279946)
		(width 0.0889)
		(layer "B.Cu")
		(net "SVID_DIO1_CPU1")
	)
	(segment
		(start 67.333876 -206.185516)
		(end 68.453 -205.066392)
		(width 0.12954)
		(layer "B.Cu")
		(net "SVID_DIO1_CPU1")
	)
	(segment
		(start 94.921324 -233.837988)
		(end 94.91091 -233.831892)
		(width 0.0889)
		(layer "B.Cu")
		(net "SVID_DIO1_CPU1")
	)
	(segment
		(start 108.350812 -233.34218)
		(end 108.038138 -233.34218)
		(width 0.0889)
		(layer "B.Cu")
		(net "SVID_DIO1_CPU1")
	)
	(segment
		(start 68.355718 -223.90989)
		(end 68.355718 -222.50273)
		(width 0.12954)
		(layer "B.Cu")
		(net "SVID_DIO1_CPU1")
	)
	(segment
		(start 88.347296 -233.840528)
		(end 88.332564 -233.831892)
		(width 0.0889)
		(layer "B.Cu")
		(net "SVID_DIO1_CPU1")
	)
	(segment
		(start 82.898996 -235.279946)
		(end 78.130146 -235.279946)
		(width 0.12954)
		(layer "B.Cu")
		(net "SVID_DIO1_CPU1")
	)
	(segment
		(start 104.323896 -233.840528)
		(end 104.309164 -233.831892)
		(width 0.0889)
		(layer "B.Cu")
		(net "SVID_DIO1_CPU1")
	)
	(segment
		(start 98.678238 -233.836464)
		(end 98.670364 -233.831892)
		(width 0.0889)
		(layer "B.Cu")
		(net "SVID_DIO1_CPU1")
	)
	(segment
		(start 70.810628 -201.315574)
		(end 70.810628 -199.80148)
		(width 0.12954)
		(layer "B.Cu")
		(net "SVID_DIO1_CPU1")
	)
	(segment
		(start 71.982584 -192.74028)
		(end 72.401684 -191.728344)
		(width 0.12954)
		(layer "B.Cu")
		(net "SVID_DIO1_CPU1")
	)
	(segment
		(start 102.444296 -233.840528)
		(end 102.429564 -233.831892)
		(width 0.0889)
		(layer "B.Cu")
		(net "SVID_DIO1_CPU1")
	)
	(segment
		(start 90.226896 -233.840528)
		(end 90.212164 -233.831892)
		(width 0.0889)
		(layer "B.Cu")
		(net "SVID_DIO1_CPU1")
	)
	(segment
		(start 107.143296 -233.840528)
		(end 107.128564 -233.831892)
		(width 0.0889)
		(layer "B.Cu")
		(net "SVID_DIO1_CPU1")
	)
	(segment
		(start 95.865696 -233.840528)
		(end 95.850964 -233.831892)
		(width 0.0889)
		(layer "B.Cu")
		(net "SVID_DIO1_CPU1")
	)
	(segment
		(start 105.263696 -233.840528)
		(end 105.248964 -233.831892)
		(width 0.0889)
		(layer "B.Cu")
		(net "SVID_DIO1_CPU1")
	)
	(segment
		(start 70.810628 -199.80148)
		(end 71.982584 -198.629524)
		(width 0.12954)
		(layer "B.Cu")
		(net "SVID_DIO1_CPU1")
	)
	(segment
		(start 68.453 -205.066392)
		(end 68.453 -203.673202)
		(width 0.12954)
		(layer "B.Cu")
		(net "SVID_DIO1_CPU1")
	)
	(segment
		(start 87.675466 -233.907584)
		(end 86.1187 -233.907584)
		(width 0.0889)
		(layer "B.Cu")
		(net "SVID_DIO1_CPU1")
	)
	(segment
		(start 98.685096 -233.840528)
		(end 98.678238 -233.836464)
		(width 0.0889)
		(layer "B.Cu")
		(net "SVID_DIO1_CPU1")
	)
	(segment
		(start 86.1187 -233.907584)
		(end 84.746338 -235.279946)
		(width 0.0889)
		(layer "B.Cu")
		(net "SVID_DIO1_CPU1")
	)
	(segment
		(start 68.355718 -222.50273)
		(end 67.333876 -221.480888)
		(width 0.12954)
		(layer "B.Cu")
		(net "SVID_DIO1_CPU1")
	)
	(segment
		(start 92.106496 -233.840528)
		(end 92.091764 -233.831892)
		(width 0.0889)
		(layer "B.Cu")
		(net "SVID_DIO1_CPU1")
	)
	(segment
		(start 72.401684 -191.728344)
		(end 72.401684 -191.144906)
		(width 0.12954)
		(layer "B.Cu")
		(net "SVID_DIO1_CPU1")
	)
	(segment
		(start 93.046296 -233.840528)
		(end 93.031564 -233.831892)
		(width 0.0889)
		(layer "B.Cu")
		(net "SVID_DIO1_CPU1")
	)
	(segment
		(start 100.560378 -233.837988)
		(end 100.549964 -233.831892)
		(width 0.0889)
		(layer "B.Cu")
		(net "SVID_DIO1_CPU1")
	)
	(segment
		(start 99.624896 -233.840528)
		(end 99.610164 -233.831892)
		(width 0.0889)
		(layer "B.Cu")
		(net "SVID_DIO1_CPU1")
	)
	(segment
		(start 106.203496 -233.840528)
		(end 106.188764 -233.831892)
		(width 0.0889)
		(layer "B.Cu")
		(net "SVID_DIO1_CPU1")
	)
	(segment
		(start 68.453 -203.673202)
		(end 70.810628 -201.315574)
		(width 0.12954)
		(layer "B.Cu")
		(net "SVID_DIO1_CPU1")
	)
	(segment
		(start 108.038138 -233.34218)
		(end 107.97286 -233.407458)
		(width 0.0889)
		(layer "B.Cu")
		(net "SVID_DIO1_CPU1")
	)
	(segment
		(start 71.982584 -198.629524)
		(end 71.982584 -192.74028)
		(width 0.12954)
		(layer "B.Cu")
		(net "SVID_DIO1_CPU1")
	)
	(segment
		(start 103.384096 -233.840528)
		(end 103.369364 -233.831892)
		(width 0.0889)
		(layer "B.Cu")
		(net "SVID_DIO1_CPU1")
	)
	(arc
		(start 90.777568 -233.831892)
		(mid 90.503339 -233.907817)
		(end 90.226896 -233.840528)
		(width 0.0889)
		(layer "B.Cu")
		(net "SVID_DIO1_CPU1")
	)
	(arc
		(start 101.48951 -233.831892)
		(mid 101.302312 -233.781749)
		(end 101.115114 -233.831892)
		(width 0.0889)
		(layer "B.Cu")
		(net "SVID_DIO1_CPU1")
	)
	(arc
		(start 88.897968 -233.831892)
		(mid 88.623739 -233.907817)
		(end 88.347296 -233.840528)
		(width 0.0889)
		(layer "B.Cu")
		(net "SVID_DIO1_CPU1")
	)
	(arc
		(start 100.549964 -233.831892)
		(mid 100.362766 -233.781749)
		(end 100.175568 -233.831892)
		(width 0.0889)
		(layer "B.Cu")
		(net "SVID_DIO1_CPU1")
	)
	(arc
		(start 107.97286 -233.407458)
		(mid 107.883746 -233.652755)
		(end 107.693968 -233.831892)
		(width 0.0889)
		(layer "B.Cu")
		(net "SVID_DIO1_CPU1")
	)
	(arc
		(start 95.476568 -233.831892)
		(mid 95.199755 -233.907728)
		(end 94.921324 -233.837988)
		(width 0.0889)
		(layer "B.Cu")
		(net "SVID_DIO1_CPU1")
	)
	(arc
		(start 106.754168 -233.831892)
		(mid 106.479939 -233.907817)
		(end 106.203496 -233.840528)
		(width 0.0889)
		(layer "B.Cu")
		(net "SVID_DIO1_CPU1")
	)
	(arc
		(start 89.837768 -233.831892)
		(mid 89.563539 -233.907817)
		(end 89.287096 -233.840528)
		(width 0.0889)
		(layer "B.Cu")
		(net "SVID_DIO1_CPU1")
	)
	(arc
		(start 96.790764 -233.831892)
		(mid 96.603566 -233.781749)
		(end 96.416368 -233.831892)
		(width 0.0889)
		(layer "B.Cu")
		(net "SVID_DIO1_CPU1")
	)
	(arc
		(start 100.175568 -233.831892)
		(mid 99.901339 -233.907817)
		(end 99.624896 -233.840528)
		(width 0.0889)
		(layer "B.Cu")
		(net "SVID_DIO1_CPU1")
	)
	(arc
		(start 99.610164 -233.831892)
		(mid 99.422966 -233.781749)
		(end 99.235768 -233.831892)
		(width 0.0889)
		(layer "B.Cu")
		(net "SVID_DIO1_CPU1")
	)
	(arc
		(start 91.717368 -233.831892)
		(mid 91.434666 -233.907634)
		(end 91.151964 -233.831892)
		(width 0.0889)
		(layer "B.Cu")
		(net "SVID_DIO1_CPU1")
	)
	(arc
		(start 92.657168 -233.831892)
		(mid 92.382939 -233.907817)
		(end 92.106496 -233.840528)
		(width 0.0889)
		(layer "B.Cu")
		(net "SVID_DIO1_CPU1")
	)
	(arc
		(start 105.814368 -233.831892)
		(mid 105.540139 -233.907817)
		(end 105.263696 -233.840528)
		(width 0.0889)
		(layer "B.Cu")
		(net "SVID_DIO1_CPU1")
	)
	(arc
		(start 92.091764 -233.831892)
		(mid 91.904566 -233.781749)
		(end 91.717368 -233.831892)
		(width 0.0889)
		(layer "B.Cu")
		(net "SVID_DIO1_CPU1")
	)
	(arc
		(start 104.309164 -233.831892)
		(mid 104.121966 -233.781749)
		(end 103.934768 -233.831892)
		(width 0.0889)
		(layer "B.Cu")
		(net "SVID_DIO1_CPU1")
	)
	(arc
		(start 107.128564 -233.831892)
		(mid 106.941366 -233.781749)
		(end 106.754168 -233.831892)
		(width 0.0889)
		(layer "B.Cu")
		(net "SVID_DIO1_CPU1")
	)
	(arc
		(start 96.416368 -233.831892)
		(mid 96.142139 -233.907817)
		(end 95.865696 -233.840528)
		(width 0.0889)
		(layer "B.Cu")
		(net "SVID_DIO1_CPU1")
	)
	(arc
		(start 104.874568 -233.831892)
		(mid 104.600339 -233.907817)
		(end 104.323896 -233.840528)
		(width 0.0889)
		(layer "B.Cu")
		(net "SVID_DIO1_CPU1")
	)
	(arc
		(start 93.971364 -233.831892)
		(mid 93.784166 -233.781749)
		(end 93.596968 -233.831892)
		(width 0.0889)
		(layer "B.Cu")
		(net "SVID_DIO1_CPU1")
	)
	(arc
		(start 94.536514 -233.831892)
		(mid 94.259955 -233.907601)
		(end 93.981778 -233.837988)
		(width 0.0889)
		(layer "B.Cu")
		(net "SVID_DIO1_CPU1")
	)
	(arc
		(start 88.332564 -233.831892)
		(mid 88.145366 -233.781749)
		(end 87.958168 -233.831892)
		(width 0.0889)
		(layer "B.Cu")
		(net "SVID_DIO1_CPU1")
	)
	(arc
		(start 89.272364 -233.831892)
		(mid 89.085166 -233.781749)
		(end 88.897968 -233.831892)
		(width 0.0889)
		(layer "B.Cu")
		(net "SVID_DIO1_CPU1")
	)
	(arc
		(start 94.91091 -233.831892)
		(mid 94.723712 -233.781749)
		(end 94.536514 -233.831892)
		(width 0.0889)
		(layer "B.Cu")
		(net "SVID_DIO1_CPU1")
	)
	(arc
		(start 90.212164 -233.831892)
		(mid 90.024966 -233.781749)
		(end 89.837768 -233.831892)
		(width 0.0889)
		(layer "B.Cu")
		(net "SVID_DIO1_CPU1")
	)
	(arc
		(start 87.958168 -233.831892)
		(mid 87.821802 -233.88837)
		(end 87.675466 -233.907584)
		(width 0.0889)
		(layer "B.Cu")
		(net "SVID_DIO1_CPU1")
	)
	(arc
		(start 102.055168 -233.831892)
		(mid 101.778355 -233.907728)
		(end 101.499924 -233.837988)
		(width 0.0889)
		(layer "B.Cu")
		(net "SVID_DIO1_CPU1")
	)
	(arc
		(start 103.369364 -233.831892)
		(mid 103.182166 -233.781749)
		(end 102.994968 -233.831892)
		(width 0.0889)
		(layer "B.Cu")
		(net "SVID_DIO1_CPU1")
	)
	(arc
		(start 98.670364 -233.831892)
		(mid 98.483166 -233.781749)
		(end 98.295968 -233.831892)
		(width 0.0889)
		(layer "B.Cu")
		(net "SVID_DIO1_CPU1")
	)
	(arc
		(start 93.596968 -233.831892)
		(mid 93.322739 -233.907817)
		(end 93.046296 -233.840528)
		(width 0.0889)
		(layer "B.Cu")
		(net "SVID_DIO1_CPU1")
	)
	(arc
		(start 102.994968 -233.831892)
		(mid 102.720739 -233.907817)
		(end 102.444296 -233.840528)
		(width 0.0889)
		(layer "B.Cu")
		(net "SVID_DIO1_CPU1")
	)
	(arc
		(start 103.934768 -233.831892)
		(mid 103.660539 -233.907817)
		(end 103.384096 -233.840528)
		(width 0.0889)
		(layer "B.Cu")
		(net "SVID_DIO1_CPU1")
	)
	(arc
		(start 95.850964 -233.831892)
		(mid 95.663766 -233.781749)
		(end 95.476568 -233.831892)
		(width 0.0889)
		(layer "B.Cu")
		(net "SVID_DIO1_CPU1")
	)
	(arc
		(start 102.429564 -233.831892)
		(mid 102.242366 -233.781749)
		(end 102.055168 -233.831892)
		(width 0.0889)
		(layer "B.Cu")
		(net "SVID_DIO1_CPU1")
	)
	(arc
		(start 98.295968 -233.831892)
		(mid 98.013266 -233.907634)
		(end 97.730564 -233.831892)
		(width 0.0889)
		(layer "B.Cu")
		(net "SVID_DIO1_CPU1")
	)
	(arc
		(start 97.730564 -233.831892)
		(mid 97.543366 -233.781749)
		(end 97.356168 -233.831892)
		(width 0.0889)
		(layer "B.Cu")
		(net "SVID_DIO1_CPU1")
	)
	(arc
		(start 107.693968 -233.831892)
		(mid 107.419739 -233.907817)
		(end 107.143296 -233.840528)
		(width 0.0889)
		(layer "B.Cu")
		(net "SVID_DIO1_CPU1")
	)
	(arc
		(start 93.031564 -233.831892)
		(mid 92.844366 -233.781749)
		(end 92.657168 -233.831892)
		(width 0.0889)
		(layer "B.Cu")
		(net "SVID_DIO1_CPU1")
	)
	(arc
		(start 99.235768 -233.831892)
		(mid 98.961539 -233.907817)
		(end 98.685096 -233.840528)
		(width 0.0889)
		(layer "B.Cu")
		(net "SVID_DIO1_CPU1")
	)
	(arc
		(start 97.356168 -233.831892)
		(mid 97.081939 -233.907817)
		(end 96.805496 -233.840528)
		(width 0.0889)
		(layer "B.Cu")
		(net "SVID_DIO1_CPU1")
	)
	(arc
		(start 91.151964 -233.831892)
		(mid 90.964766 -233.781749)
		(end 90.777568 -233.831892)
		(width 0.0889)
		(layer "B.Cu")
		(net "SVID_DIO1_CPU1")
	)
	(arc
		(start 106.188764 -233.831892)
		(mid 106.001566 -233.781749)
		(end 105.814368 -233.831892)
		(width 0.0889)
		(layer "B.Cu")
		(net "SVID_DIO1_CPU1")
	)
	(arc
		(start 101.115114 -233.831892)
		(mid 100.838555 -233.907601)
		(end 100.560378 -233.837988)
		(width 0.0889)
		(layer "B.Cu")
		(net "SVID_DIO1_CPU1")
	)
	(arc
		(start 105.248964 -233.831892)
		(mid 105.061766 -233.781749)
		(end 104.874568 -233.831892)
		(width 0.0889)
		(layer "B.Cu")
		(net "SVID_DIO1_CPU1")
	)
	(segment
		(start 439.95848 -126.215648)
		(end 439.70448 -125.961648)
		(width 0.12954)
		(layer "F.Cu")
		(net "SVID_DIO1_CPU0_R")
	)
	(segment
		(start 438.862216 -124.680726)
		(end 438.862216 -125.119384)
		(width 0.12954)
		(layer "F.Cu")
		(net "SVID_DIO1_CPU0_R")
	)
	(segment
		(start 333.3877 -162.847274)
		(end 333.3877 -136.919462)
		(width 0.12954)
		(layer "F.Cu")
		(net "SVID_DIO1_CPU0_R")
	)
	(segment
		(start 437.643016 -124.680726)
		(end 438.862216 -124.680726)
		(width 0.12954)
		(layer "F.Cu")
		(net "SVID_DIO1_CPU0_R")
	)
	(segment
		(start 441.447174 -120.078754)
		(end 442.93028 -121.56186)
		(width 0.12954)
		(layer "F.Cu")
		(net "SVID_DIO1_CPU0_R")
	)
	(segment
		(start 318.205866 -178.029108)
		(end 333.3877 -162.847274)
		(width 0.12954)
		(layer "F.Cu")
		(net "SVID_DIO1_CPU0_R")
	)
	(segment
		(start 307.616098 -192.15227)
		(end 307.95214 -191.816228)
		(width 0.12954)
		(layer "F.Cu")
		(net "SVID_DIO1_CPU0_R")
	)
	(segment
		(start 307.95214 -191.342772)
		(end 307.06568 -190.456312)
		(width 0.12954)
		(layer "F.Cu")
		(net "SVID_DIO1_CPU0_R")
	)
	(segment
		(start 439.720228 -114.249708)
		(end 441.447174 -115.976654)
		(width 0.12954)
		(layer "F.Cu")
		(net "SVID_DIO1_CPU0_R")
	)
	(segment
		(start 442.93028 -121.56186)
		(end 442.93028 -125.694948)
		(width 0.12954)
		(layer "F.Cu")
		(net "SVID_DIO1_CPU0_R")
	)
	(segment
		(start 333.3877 -136.919462)
		(end 339.008974 -131.298188)
		(width 0.12954)
		(layer "F.Cu")
		(net "SVID_DIO1_CPU0_R")
	)
	(segment
		(start 307.06568 -190.456312)
		(end 307.06568 -180.702966)
		(width 0.12954)
		(layer "F.Cu")
		(net "SVID_DIO1_CPU0_R")
	)
	(segment
		(start 307.95214 -191.816228)
		(end 307.95214 -191.342772)
		(width 0.12954)
		(layer "F.Cu")
		(net "SVID_DIO1_CPU0_R")
	)
	(segment
		(start 409.812998 -131.298188)
		(end 426.861478 -114.249708)
		(width 0.12954)
		(layer "F.Cu")
		(net "SVID_DIO1_CPU0_R")
	)
	(segment
		(start 441.447174 -115.976654)
		(end 441.447174 -120.078754)
		(width 0.12954)
		(layer "F.Cu")
		(net "SVID_DIO1_CPU0_R")
	)
	(segment
		(start 426.861478 -114.249708)
		(end 439.720228 -114.249708)
		(width 0.12954)
		(layer "F.Cu")
		(net "SVID_DIO1_CPU0_R")
	)
	(segment
		(start 307.06568 -180.702966)
		(end 309.739538 -178.029108)
		(width 0.12954)
		(layer "F.Cu")
		(net "SVID_DIO1_CPU0_R")
	)
	(segment
		(start 307.344318 -192.15227)
		(end 307.616098 -192.15227)
		(width 0.12954)
		(layer "F.Cu")
		(net "SVID_DIO1_CPU0_R")
	)
	(segment
		(start 438.862216 -125.119384)
		(end 439.70448 -125.961648)
		(width 0.12954)
		(layer "F.Cu")
		(net "SVID_DIO1_CPU0_R")
	)
	(segment
		(start 339.008974 -131.298188)
		(end 409.812998 -131.298188)
		(width 0.12954)
		(layer "F.Cu")
		(net "SVID_DIO1_CPU0_R")
	)
	(segment
		(start 442.93028 -125.694948)
		(end 442.40958 -126.215648)
		(width 0.12954)
		(layer "F.Cu")
		(net "SVID_DIO1_CPU0_R")
	)
	(segment
		(start 442.40958 -126.215648)
		(end 439.95848 -126.215648)
		(width 0.12954)
		(layer "F.Cu")
		(net "SVID_DIO1_CPU0_R")
	)
	(segment
		(start 309.739538 -178.029108)
		(end 318.205866 -178.029108)
		(width 0.12954)
		(layer "F.Cu")
		(net "SVID_DIO1_CPU0_R")
	)
	(segment
		(start 306.732178 -191.54013)
		(end 307.344318 -192.15227)
		(width 0.12954)
		(layer "F.Cu")
		(net "SVID_DIO1_CPU0_R")
	)
	(via
		(at 306.732178 -191.54013)
		(size 0.508)
		(drill 0.254)
		(layers "F.Cu" "B.Cu")
		(net "SVID_DIO1_CPU0_R")
	)
	(via
		(at 439.70448 -125.961648)
		(size 0.762)
		(drill 0.381)
		(layers "F.Cu" "B.Cu")
		(net "SVID_DIO1_CPU0_R")
	)
	(segment
		(start 307.069998 -192.20942)
		(end 307.069998 -191.87795)
		(width 0.12954)
		(layer "B.Cu")
		(net "SVID_DIO1_CPU0_R")
	)
	(segment
		(start 306.732178 -191.08674)
		(end 306.968398 -190.85052)
		(width 0.12954)
		(layer "B.Cu")
		(net "SVID_DIO1_CPU0_R")
	)
	(segment
		(start 307.069998 -191.87795)
		(end 306.732178 -191.54013)
		(width 0.12954)
		(layer "B.Cu")
		(net "SVID_DIO1_CPU0_R")
	)
	(segment
		(start 306.732178 -191.54013)
		(end 306.732178 -191.08674)
		(width 0.12954)
		(layer "B.Cu")
		(net "SVID_DIO1_CPU0_R")
	)
	(segment
		(start 356.291134 -233.342434)
		(end 356.29088 -233.34218)
		(width 0.12954)
		(layer "F.Cu")
		(net "SVID_DIO1_CPU0")
	)
	(segment
		(start 356.291134 -233.87812)
		(end 356.291134 -233.342434)
		(width 0.12954)
		(layer "F.Cu")
		(net "SVID_DIO1_CPU0")
	)
	(via
		(at 328.369168 -235.895896)
		(size 0.6604)
		(drill 0.3302)
		(layers "F.Cu" "B.Cu")
		(net "SVID_DIO1_CPU0")
	)
	(via
		(at 356.29088 -233.34218)
		(size 0.4572)
		(drill 0.2032)
		(layers "F.Cu" "B.Cu")
		(net "SVID_DIO1_CPU0")
	)
	(segment
		(start 351.324164 -233.840528)
		(end 351.309432 -233.831892)
		(width 0.0889)
		(layer "B.Cu")
		(net "SVID_DIO1_CPU0")
	)
	(segment
		(start 340.046564 -233.840528)
		(end 340.031832 -233.831892)
		(width 0.0889)
		(layer "B.Cu")
		(net "SVID_DIO1_CPU0")
	)
	(segment
		(start 311.248298 -236.11459)
		(end 311.144158 -236.01045)
		(width 0.12954)
		(layer "B.Cu")
		(net "SVID_DIO1_CPU0")
	)
	(segment
		(start 310.778398 -235.65231)
		(end 310.194198 -235.65231)
		(width 0.12954)
		(layer "B.Cu")
		(net "SVID_DIO1_CPU0")
	)
	(segment
		(start 329.070208 -235.194856)
		(end 328.369168 -235.895896)
		(width 0.12954)
		(layer "B.Cu")
		(net "SVID_DIO1_CPU0")
	)
	(segment
		(start 355.083364 -233.840528)
		(end 355.068632 -233.831892)
		(width 0.0889)
		(layer "B.Cu")
		(net "SVID_DIO1_CPU0")
	)
	(segment
		(start 308.835298 -205.19009)
		(end 308.835298 -194.77482)
		(width 0.12954)
		(layer "B.Cu")
		(net "SVID_DIO1_CPU0")
	)
	(segment
		(start 340.986364 -233.840528)
		(end 340.971632 -233.831892)
		(width 0.0889)
		(layer "B.Cu")
		(net "SVID_DIO1_CPU0")
	)
	(segment
		(start 312.909458 -236.11459)
		(end 311.248298 -236.11459)
		(width 0.12954)
		(layer "B.Cu")
		(net "SVID_DIO1_CPU0")
	)
	(segment
		(start 349.439992 -233.837988)
		(end 349.429578 -233.831892)
		(width 0.0889)
		(layer "B.Cu")
		(net "SVID_DIO1_CPU0")
	)
	(segment
		(start 328.369168 -235.895896)
		(end 327.71461 -236.550454)
		(width 0.12954)
		(layer "B.Cu")
		(net "SVID_DIO1_CPU0")
	)
	(segment
		(start 332.642972 -235.194856)
		(end 329.070208 -235.194856)
		(width 0.12954)
		(layer "B.Cu")
		(net "SVID_DIO1_CPU0")
	)
	(segment
		(start 333.597758 -234.24007)
		(end 332.642972 -235.194856)
		(width 0.12954)
		(layer "B.Cu")
		(net "SVID_DIO1_CPU0")
	)
	(segment
		(start 348.500446 -233.837988)
		(end 348.490032 -233.831892)
		(width 0.0889)
		(layer "B.Cu")
		(net "SVID_DIO1_CPU0")
	)
	(segment
		(start 336.287364 -233.840528)
		(end 336.272632 -233.831892)
		(width 0.0889)
		(layer "B.Cu")
		(net "SVID_DIO1_CPU0")
	)
	(segment
		(start 354.143564 -233.840528)
		(end 354.128832 -233.831892)
		(width 0.0889)
		(layer "B.Cu")
		(net "SVID_DIO1_CPU0")
	)
	(segment
		(start 313.345322 -236.550454)
		(end 312.909458 -236.11459)
		(width 0.12954)
		(layer "B.Cu")
		(net "SVID_DIO1_CPU0")
	)
	(segment
		(start 344.745564 -233.840528)
		(end 344.730832 -233.831892)
		(width 0.0889)
		(layer "B.Cu")
		(net "SVID_DIO1_CPU0")
	)
	(segment
		(start 356.29088 -233.34218)
		(end 356.28834 -233.341418)
		(width 0.0889)
		(layer "B.Cu")
		(net "SVID_DIO1_CPU0")
	)
	(segment
		(start 308.835298 -194.77482)
		(end 307.069998 -193.00952)
		(width 0.12954)
		(layer "B.Cu")
		(net "SVID_DIO1_CPU0")
	)
	(segment
		(start 341.921846 -233.837988)
		(end 341.911432 -233.831892)
		(width 0.0889)
		(layer "B.Cu")
		(net "SVID_DIO1_CPU0")
	)
	(segment
		(start 338.166964 -233.840528)
		(end 338.152232 -233.831892)
		(width 0.0889)
		(layer "B.Cu")
		(net "SVID_DIO1_CPU0")
	)
	(segment
		(start 327.71461 -236.550454)
		(end 313.345322 -236.550454)
		(width 0.12954)
		(layer "B.Cu")
		(net "SVID_DIO1_CPU0")
	)
	(segment
		(start 342.861392 -233.837988)
		(end 342.850978 -233.831892)
		(width 0.0889)
		(layer "B.Cu")
		(net "SVID_DIO1_CPU0")
	)
	(segment
		(start 308.482238 -205.54315)
		(end 308.835298 -205.19009)
		(width 0.12954)
		(layer "B.Cu")
		(net "SVID_DIO1_CPU0")
	)
	(segment
		(start 311.136538 -236.01045)
		(end 310.778398 -235.65231)
		(width 0.12954)
		(layer "B.Cu")
		(net "SVID_DIO1_CPU0")
	)
	(segment
		(start 353.203764 -233.840528)
		(end 353.189032 -233.831892)
		(width 0.0889)
		(layer "B.Cu")
		(net "SVID_DIO1_CPU0")
	)
	(segment
		(start 352.263964 -233.840528)
		(end 352.249232 -233.831892)
		(width 0.0889)
		(layer "B.Cu")
		(net "SVID_DIO1_CPU0")
	)
	(segment
		(start 347.564964 -233.840528)
		(end 347.550232 -233.831892)
		(width 0.0889)
		(layer "B.Cu")
		(net "SVID_DIO1_CPU0")
	)
	(segment
		(start 335.113884 -234.04195)
		(end 333.842868 -234.04195)
		(width 0.0889)
		(layer "B.Cu")
		(net "SVID_DIO1_CPU0")
	)
	(segment
		(start 346.625164 -233.840528)
		(end 346.610432 -233.831892)
		(width 0.0889)
		(layer "B.Cu")
		(net "SVID_DIO1_CPU0")
	)
	(segment
		(start 337.227164 -233.840528)
		(end 337.212432 -233.831892)
		(width 0.0889)
		(layer "B.Cu")
		(net "SVID_DIO1_CPU0")
	)
	(segment
		(start 308.482238 -233.94035)
		(end 308.482238 -205.54315)
		(width 0.12954)
		(layer "B.Cu")
		(net "SVID_DIO1_CPU0")
	)
	(segment
		(start 311.144158 -236.01045)
		(end 311.136538 -236.01045)
		(width 0.12954)
		(layer "B.Cu")
		(net "SVID_DIO1_CPU0")
	)
	(segment
		(start 343.805764 -233.840528)
		(end 343.791032 -233.831892)
		(width 0.0889)
		(layer "B.Cu")
		(net "SVID_DIO1_CPU0")
	)
	(segment
		(start 350.384364 -233.840528)
		(end 350.369632 -233.831892)
		(width 0.0889)
		(layer "B.Cu")
		(net "SVID_DIO1_CPU0")
	)
	(segment
		(start 333.762604 -234.075224)
		(end 333.597758 -234.24007)
		(width 0.0889)
		(layer "B.Cu")
		(net "SVID_DIO1_CPU0")
	)
	(segment
		(start 310.194198 -235.65231)
		(end 308.482238 -233.94035)
		(width 0.12954)
		(layer "B.Cu")
		(net "SVID_DIO1_CPU0")
	)
	(segment
		(start 356.28834 -233.341418)
		(end 355.323394 -233.84637)
		(width 0.0889)
		(layer "B.Cu")
		(net "SVID_DIO1_CPU0")
	)
	(arc
		(start 346.236036 -233.831892)
		(mid 345.953334 -233.907634)
		(end 345.670632 -233.831892)
		(width 0.0889)
		(layer "B.Cu")
		(net "SVID_DIO1_CPU0")
	)
	(arc
		(start 341.911432 -233.831892)
		(mid 341.724234 -233.781749)
		(end 341.537036 -233.831892)
		(width 0.0889)
		(layer "B.Cu")
		(net "SVID_DIO1_CPU0")
	)
	(arc
		(start 333.842868 -234.04195)
		(mid 333.799433 -234.050608)
		(end 333.762604 -234.075224)
		(width 0.0889)
		(layer "B.Cu")
		(net "SVID_DIO1_CPU0")
	)
	(arc
		(start 340.597236 -233.831892)
		(mid 340.323007 -233.907817)
		(end 340.046564 -233.840528)
		(width 0.0889)
		(layer "B.Cu")
		(net "SVID_DIO1_CPU0")
	)
	(arc
		(start 354.694236 -233.831892)
		(mid 354.420007 -233.907817)
		(end 354.143564 -233.840528)
		(width 0.0889)
		(layer "B.Cu")
		(net "SVID_DIO1_CPU0")
	)
	(arc
		(start 337.212432 -233.831892)
		(mid 337.025234 -233.781749)
		(end 336.838036 -233.831892)
		(width 0.0889)
		(layer "B.Cu")
		(net "SVID_DIO1_CPU0")
	)
	(arc
		(start 344.356436 -233.831892)
		(mid 344.082207 -233.907817)
		(end 343.805764 -233.840528)
		(width 0.0889)
		(layer "B.Cu")
		(net "SVID_DIO1_CPU0")
	)
	(arc
		(start 352.249232 -233.831892)
		(mid 352.062034 -233.781749)
		(end 351.874836 -233.831892)
		(width 0.0889)
		(layer "B.Cu")
		(net "SVID_DIO1_CPU0")
	)
	(arc
		(start 343.416636 -233.831892)
		(mid 343.139823 -233.907728)
		(end 342.861392 -233.837988)
		(width 0.0889)
		(layer "B.Cu")
		(net "SVID_DIO1_CPU0")
	)
	(arc
		(start 346.610432 -233.831892)
		(mid 346.423234 -233.781749)
		(end 346.236036 -233.831892)
		(width 0.0889)
		(layer "B.Cu")
		(net "SVID_DIO1_CPU0")
	)
	(arc
		(start 339.657436 -233.831892)
		(mid 339.374734 -233.907634)
		(end 339.092032 -233.831892)
		(width 0.0889)
		(layer "B.Cu")
		(net "SVID_DIO1_CPU0")
	)
	(arc
		(start 345.670632 -233.831892)
		(mid 345.483434 -233.781749)
		(end 345.296236 -233.831892)
		(width 0.0889)
		(layer "B.Cu")
		(net "SVID_DIO1_CPU0")
	)
	(arc
		(start 347.175836 -233.831892)
		(mid 346.901607 -233.907817)
		(end 346.625164 -233.840528)
		(width 0.0889)
		(layer "B.Cu")
		(net "SVID_DIO1_CPU0")
	)
	(arc
		(start 337.777836 -233.831892)
		(mid 337.503607 -233.907817)
		(end 337.227164 -233.840528)
		(width 0.0889)
		(layer "B.Cu")
		(net "SVID_DIO1_CPU0")
	)
	(arc
		(start 352.814636 -233.831892)
		(mid 352.540407 -233.907817)
		(end 352.263964 -233.840528)
		(width 0.0889)
		(layer "B.Cu")
		(net "SVID_DIO1_CPU0")
	)
	(arc
		(start 338.152232 -233.831892)
		(mid 337.965034 -233.781749)
		(end 337.777836 -233.831892)
		(width 0.0889)
		(layer "B.Cu")
		(net "SVID_DIO1_CPU0")
	)
	(arc
		(start 342.850978 -233.831892)
		(mid 342.66378 -233.781749)
		(end 342.476582 -233.831892)
		(width 0.0889)
		(layer "B.Cu")
		(net "SVID_DIO1_CPU0")
	)
	(arc
		(start 341.537036 -233.831892)
		(mid 341.262807 -233.907817)
		(end 340.986364 -233.840528)
		(width 0.0889)
		(layer "B.Cu")
		(net "SVID_DIO1_CPU0")
	)
	(arc
		(start 349.429578 -233.831892)
		(mid 349.24238 -233.781749)
		(end 349.055182 -233.831892)
		(width 0.0889)
		(layer "B.Cu")
		(net "SVID_DIO1_CPU0")
	)
	(arc
		(start 348.490032 -233.831892)
		(mid 348.302834 -233.781749)
		(end 348.115636 -233.831892)
		(width 0.0889)
		(layer "B.Cu")
		(net "SVID_DIO1_CPU0")
	)
	(arc
		(start 344.730832 -233.831892)
		(mid 344.543634 -233.781749)
		(end 344.356436 -233.831892)
		(width 0.0889)
		(layer "B.Cu")
		(net "SVID_DIO1_CPU0")
	)
	(arc
		(start 350.935036 -233.831892)
		(mid 350.660807 -233.907817)
		(end 350.384364 -233.840528)
		(width 0.0889)
		(layer "B.Cu")
		(net "SVID_DIO1_CPU0")
	)
	(arc
		(start 349.055182 -233.831892)
		(mid 348.778623 -233.907601)
		(end 348.500446 -233.837988)
		(width 0.0889)
		(layer "B.Cu")
		(net "SVID_DIO1_CPU0")
	)
	(arc
		(start 342.476582 -233.831892)
		(mid 342.200023 -233.907601)
		(end 341.921846 -233.837988)
		(width 0.0889)
		(layer "B.Cu")
		(net "SVID_DIO1_CPU0")
	)
	(arc
		(start 354.128832 -233.831892)
		(mid 353.941634 -233.781749)
		(end 353.754436 -233.831892)
		(width 0.0889)
		(layer "B.Cu")
		(net "SVID_DIO1_CPU0")
	)
	(arc
		(start 335.898236 -233.831892)
		(mid 335.519884 -233.988545)
		(end 335.113884 -234.04195)
		(width 0.0889)
		(layer "B.Cu")
		(net "SVID_DIO1_CPU0")
	)
	(arc
		(start 339.092032 -233.831892)
		(mid 338.904834 -233.781749)
		(end 338.717636 -233.831892)
		(width 0.0889)
		(layer "B.Cu")
		(net "SVID_DIO1_CPU0")
	)
	(arc
		(start 336.272632 -233.831892)
		(mid 336.085434 -233.781749)
		(end 335.898236 -233.831892)
		(width 0.0889)
		(layer "B.Cu")
		(net "SVID_DIO1_CPU0")
	)
	(arc
		(start 350.369632 -233.831892)
		(mid 350.182434 -233.781749)
		(end 349.995236 -233.831892)
		(width 0.0889)
		(layer "B.Cu")
		(net "SVID_DIO1_CPU0")
	)
	(arc
		(start 355.323394 -233.84637)
		(mid 355.202615 -233.874515)
		(end 355.083364 -233.840528)
		(width 0.0889)
		(layer "B.Cu")
		(net "SVID_DIO1_CPU0")
	)
	(arc
		(start 343.791032 -233.831892)
		(mid 343.603834 -233.781749)
		(end 343.416636 -233.831892)
		(width 0.0889)
		(layer "B.Cu")
		(net "SVID_DIO1_CPU0")
	)
	(arc
		(start 340.031832 -233.831892)
		(mid 339.844634 -233.781749)
		(end 339.657436 -233.831892)
		(width 0.0889)
		(layer "B.Cu")
		(net "SVID_DIO1_CPU0")
	)
	(arc
		(start 336.838036 -233.831892)
		(mid 336.563807 -233.907817)
		(end 336.287364 -233.840528)
		(width 0.0889)
		(layer "B.Cu")
		(net "SVID_DIO1_CPU0")
	)
	(arc
		(start 355.068632 -233.831892)
		(mid 354.881434 -233.781749)
		(end 354.694236 -233.831892)
		(width 0.0889)
		(layer "B.Cu")
		(net "SVID_DIO1_CPU0")
	)
	(arc
		(start 353.754436 -233.831892)
		(mid 353.480207 -233.907817)
		(end 353.203764 -233.840528)
		(width 0.0889)
		(layer "B.Cu")
		(net "SVID_DIO1_CPU0")
	)
	(arc
		(start 349.995236 -233.831892)
		(mid 349.718423 -233.907728)
		(end 349.439992 -233.837988)
		(width 0.0889)
		(layer "B.Cu")
		(net "SVID_DIO1_CPU0")
	)
	(arc
		(start 351.874836 -233.831892)
		(mid 351.600607 -233.907817)
		(end 351.324164 -233.840528)
		(width 0.0889)
		(layer "B.Cu")
		(net "SVID_DIO1_CPU0")
	)
	(arc
		(start 340.971632 -233.831892)
		(mid 340.784434 -233.781749)
		(end 340.597236 -233.831892)
		(width 0.0889)
		(layer "B.Cu")
		(net "SVID_DIO1_CPU0")
	)
	(arc
		(start 351.309432 -233.831892)
		(mid 351.122234 -233.781749)
		(end 350.935036 -233.831892)
		(width 0.0889)
		(layer "B.Cu")
		(net "SVID_DIO1_CPU0")
	)
	(arc
		(start 345.296236 -233.831892)
		(mid 345.022007 -233.907817)
		(end 344.745564 -233.840528)
		(width 0.0889)
		(layer "B.Cu")
		(net "SVID_DIO1_CPU0")
	)
	(arc
		(start 353.189032 -233.831892)
		(mid 353.001834 -233.781749)
		(end 352.814636 -233.831892)
		(width 0.0889)
		(layer "B.Cu")
		(net "SVID_DIO1_CPU0")
	)
	(arc
		(start 338.717636 -233.831892)
		(mid 338.443407 -233.907817)
		(end 338.166964 -233.840528)
		(width 0.0889)
		(layer "B.Cu")
		(net "SVID_DIO1_CPU0")
	)
	(arc
		(start 347.550232 -233.831892)
		(mid 347.363034 -233.781749)
		(end 347.175836 -233.831892)
		(width 0.0889)
		(layer "B.Cu")
		(net "SVID_DIO1_CPU0")
	)
	(arc
		(start 348.115636 -233.831892)
		(mid 347.841407 -233.907817)
		(end 347.564964 -233.840528)
		(width 0.0889)
		(layer "B.Cu")
		(net "SVID_DIO1_CPU0")
	)
	(segment
		(start 38.794182 -132.418582)
		(end 38.794182 -131.897374)
		(width 0.12954)
		(layer "F.Cu")
		(net "SVID_DIO0_CPU1_R")
	)
	(segment
		(start 39.280338 -132.532882)
		(end 38.908482 -132.532882)
		(width 0.12954)
		(layer "F.Cu")
		(net "SVID_DIO0_CPU1_R")
	)
	(segment
		(start 38.794182 -131.897374)
		(end 38.794182 -131.394962)
		(width 0.12954)
		(layer "F.Cu")
		(net "SVID_DIO0_CPU1_R")
	)
	(segment
		(start 101.835204 -356.795578)
		(end 102.318566 -356.795578)
		(width 0.12954)
		(layer "F.Cu")
		(net "SVID_DIO0_CPU1_R")
	)
	(segment
		(start 102.318566 -356.795578)
		(end 102.445566 -356.668578)
		(width 0.12954)
		(layer "F.Cu")
		(net "SVID_DIO0_CPU1_R")
	)
	(segment
		(start 38.908482 -132.532882)
		(end 38.794182 -132.418582)
		(width 0.12954)
		(layer "F.Cu")
		(net "SVID_DIO0_CPU1_R")
	)
	(segment
		(start 38.794182 -131.394962)
		(end 38.679882 -131.280662)
		(width 0.12954)
		(layer "F.Cu")
		(net "SVID_DIO0_CPU1_R")
	)
	(segment
		(start 37.488368 -131.280662)
		(end 37.356288 -131.148582)
		(width 0.12954)
		(layer "F.Cu")
		(net "SVID_DIO0_CPU1_R")
	)
	(segment
		(start 38.679882 -131.280662)
		(end 37.488368 -131.280662)
		(width 0.12954)
		(layer "F.Cu")
		(net "SVID_DIO0_CPU1_R")
	)
	(segment
		(start 37.356288 -131.148582)
		(end 37.356288 -130.76174)
		(width 0.12954)
		(layer "F.Cu")
		(net "SVID_DIO0_CPU1_R")
	)
	(via
		(at 98.254058 -363.09935)
		(size 0.508)
		(drill 0.254)
		(layers "F.Cu" "B.Cu")
		(net "SVID_DIO0_CPU1_R")
	)
	(via
		(at 95.2246 -389.661908)
		(size 0.508)
		(drill 0.254)
		(layers "F.Cu" "B.Cu")
		(net "SVID_DIO0_CPU1_R")
	)
	(via
		(at 69.90334 -187.477908)
		(size 0.508)
		(drill 0.254)
		(layers "F.Cu" "B.Cu")
		(net "SVID_DIO0_CPU1_R")
	)
	(via
		(at 63.5254 -132.532882)
		(size 0.508)
		(drill 0.254)
		(layers "F.Cu" "B.Cu")
		(net "SVID_DIO0_CPU1_R")
	)
	(via
		(at 101.835204 -356.795578)
		(size 0.508)
		(drill 0.254)
		(layers "F.Cu" "B.Cu")
		(net "SVID_DIO0_CPU1_R")
	)
	(via
		(at 39.280338 -132.532882)
		(size 0.508)
		(drill 0.254)
		(layers "F.Cu" "B.Cu")
		(net "SVID_DIO0_CPU1_R")
	)
	(segment
		(start 70.369684 -188.058806)
		(end 70.359524 -188.068966)
		(width 0.12954)
		(layer "B.Cu")
		(net "SVID_DIO0_CPU1_R")
	)
	(segment
		(start 101.835204 -356.795578)
		(end 100.864924 -356.795578)
		(width 0.12954)
		(layer "B.Cu")
		(net "SVID_DIO0_CPU1_R")
	)
	(segment
		(start 70.359524 -188.068966)
		(end 69.342 -188.068966)
		(width 0.12954)
		(layer "B.Cu")
		(net "SVID_DIO0_CPU1_R")
	)
	(segment
		(start 100.864924 -356.795578)
		(end 100.706936 -356.63759)
		(width 0.12954)
		(layer "B.Cu")
		(net "SVID_DIO0_CPU1_R")
	)
	(segment
		(start 69.90334 -187.477908)
		(end 70.369684 -187.944252)
		(width 0.12954)
		(layer "B.Cu")
		(net "SVID_DIO0_CPU1_R")
	)
	(segment
		(start 70.369684 -187.944252)
		(end 70.369684 -188.058806)
		(width 0.12954)
		(layer "B.Cu")
		(net "SVID_DIO0_CPU1_R")
	)
	(segment
		(start 71.151496 -190.209424)
		(end 70.85838 -189.916308)
		(width 0.127)
		(layer "In2.Cu")
		(net "SVID_DIO0_CPU1_R")
	)
	(segment
		(start 75.255882 -190.20917)
		(end 75.25512 -190.209424)
		(width 0.127)
		(layer "In2.Cu")
		(net "SVID_DIO0_CPU1_R")
	)
	(segment
		(start 81.43367 -184.031382)
		(end 75.255882 -190.20917)
		(width 0.127)
		(layer "In2.Cu")
		(net "SVID_DIO0_CPU1_R")
	)
	(segment
		(start 63.5254 -132.532882)
		(end 65.539874 -132.532882)
		(width 0.127)
		(layer "In2.Cu")
		(net "SVID_DIO0_CPU1_R")
	)
	(segment
		(start 76.16698 -145.365724)
		(end 76.783438 -145.982182)
		(width 0.127)
		(layer "In2.Cu")
		(net "SVID_DIO0_CPU1_R")
	)
	(segment
		(start 79.426562 -158.316422)
		(end 79.426562 -159.773874)
		(width 0.127)
		(layer "In2.Cu")
		(net "SVID_DIO0_CPU1_R")
	)
	(segment
		(start 76.783438 -155.673298)
		(end 79.426562 -158.316422)
		(width 0.127)
		(layer "In2.Cu")
		(net "SVID_DIO0_CPU1_R")
	)
	(segment
		(start 79.426562 -159.773874)
		(end 81.43367 -161.780982)
		(width 0.127)
		(layer "In2.Cu")
		(net "SVID_DIO0_CPU1_R")
	)
	(segment
		(start 65.539874 -132.532882)
		(end 76.16698 -143.159988)
		(width 0.127)
		(layer "In2.Cu")
		(net "SVID_DIO0_CPU1_R")
	)
	(segment
		(start 70.85838 -189.916308)
		(end 70.85838 -188.432948)
		(width 0.127)
		(layer "In2.Cu")
		(net "SVID_DIO0_CPU1_R")
	)
	(segment
		(start 76.16698 -143.159988)
		(end 76.16698 -145.365724)
		(width 0.127)
		(layer "In2.Cu")
		(net "SVID_DIO0_CPU1_R")
	)
	(segment
		(start 70.85838 -188.432948)
		(end 69.90334 -187.477908)
		(width 0.127)
		(layer "In2.Cu")
		(net "SVID_DIO0_CPU1_R")
	)
	(segment
		(start 81.43367 -161.780982)
		(end 81.43367 -184.031382)
		(width 0.127)
		(layer "In2.Cu")
		(net "SVID_DIO0_CPU1_R")
	)
	(segment
		(start 75.25512 -190.209424)
		(end 71.151496 -190.209424)
		(width 0.127)
		(layer "In2.Cu")
		(net "SVID_DIO0_CPU1_R")
	)
	(segment
		(start 76.783438 -145.982182)
		(end 76.783438 -155.673298)
		(width 0.127)
		(layer "In2.Cu")
		(net "SVID_DIO0_CPU1_R")
	)
	(segment
		(start 39.280338 -132.532882)
		(end 63.5254 -132.532882)
		(width 0.127)
		(layer "In6.Cu")
		(net "SVID_DIO0_CPU1_R")
	)
	(segment
		(start 21.892514 -127.696722)
		(end 21.892514 -147.651978)
		(width 0.127)
		(layer "In11.Cu")
		(net "SVID_DIO0_CPU1_R")
	)
	(segment
		(start 32.37484 -330.681838)
		(end 32.37484 -336.959702)
		(width 0.127)
		(layer "In11.Cu")
		(net "SVID_DIO0_CPU1_R")
	)
	(segment
		(start 40.223186 -123.246134)
		(end 40.223186 -123.066302)
		(width 0.127)
		(layer "In11.Cu")
		(net "SVID_DIO0_CPU1_R")
	)
	(segment
		(start 13.9192 -189.121542)
		(end 12.30122 -190.739522)
		(width 0.127)
		(layer "In11.Cu")
		(net "SVID_DIO0_CPU1_R")
	)
	(segment
		(start 9.492234 -256.885948)
		(end 8.0645 -258.313682)
		(width 0.127)
		(layer "In11.Cu")
		(net "SVID_DIO0_CPU1_R")
	)
	(segment
		(start 12.30122 -190.739522)
		(end 12.30122 -255.164082)
		(width 0.127)
		(layer "In11.Cu")
		(net "SVID_DIO0_CPU1_R")
	)
	(segment
		(start 16.410178 -169.604436)
		(end 10.745724 -175.26889)
		(width 0.127)
		(layer "In11.Cu")
		(net "SVID_DIO0_CPU1_R")
	)
	(segment
		(start 57.825894 -390.121648)
		(end 94.76486 -390.121648)
		(width 0.127)
		(layer "In11.Cu")
		(net "SVID_DIO0_CPU1_R")
	)
	(segment
		(start 11.524234 -324.790308)
		(end 26.48331 -324.790308)
		(width 0.127)
		(layer "In11.Cu")
		(net "SVID_DIO0_CPU1_R")
	)
	(segment
		(start 98.254058 -359.15473)
		(end 98.254058 -363.09935)
		(width 0.127)
		(layer "In11.Cu")
		(net "SVID_DIO0_CPU1_R")
	)
	(segment
		(start 40.445944 -128.716024)
		(end 41.102026 -128.716024)
		(width 0.127)
		(layer "In11.Cu")
		(net "SVID_DIO0_CPU1_R")
	)
	(segment
		(start 13.9192 -184.607454)
		(end 13.9192 -189.121542)
		(width 0.127)
		(layer "In11.Cu")
		(net "SVID_DIO0_CPU1_R")
	)
	(segment
		(start 26.48331 -324.790308)
		(end 32.37484 -330.681838)
		(width 0.127)
		(layer "In11.Cu")
		(net "SVID_DIO0_CPU1_R")
	)
	(segment
		(start 21.892514 -147.651978)
		(end 16.410178 -153.134314)
		(width 0.127)
		(layer "In11.Cu")
		(net "SVID_DIO0_CPU1_R")
	)
	(segment
		(start 40.672258 -123.515374)
		(end 40.492426 -123.515374)
		(width 0.127)
		(layer "In11.Cu")
		(net "SVID_DIO0_CPU1_R")
	)
	(segment
		(start 10.745724 -181.433978)
		(end 13.9192 -184.607454)
		(width 0.127)
		(layer "In11.Cu")
		(net "SVID_DIO0_CPU1_R")
	)
	(segment
		(start 39.584122 -121.729246)
		(end 38.285166 -120.43029)
		(width 0.127)
		(layer "In11.Cu")
		(net "SVID_DIO0_CPU1_R")
	)
	(segment
		(start 40.482266 -122.62739)
		(end 40.213026 -122.35815)
		(width 0.127)
		(layer "In11.Cu")
		(net "SVID_DIO0_CPU1_R")
	)
	(segment
		(start 94.76486 -390.121648)
		(end 95.2246 -389.661908)
		(width 0.127)
		(layer "In11.Cu")
		(net "SVID_DIO0_CPU1_R")
	)
	(segment
		(start 42.723562 -124.868686)
		(end 41.11117 -123.256294)
		(width 0.127)
		(layer "In11.Cu")
		(net "SVID_DIO0_CPU1_R")
	)
	(segment
		(start 40.033194 -122.35815)
		(end 39.774114 -122.61723)
		(width 0.127)
		(layer "In11.Cu")
		(net "SVID_DIO0_CPU1_R")
	)
	(segment
		(start 41.102026 -128.716024)
		(end 42.723562 -127.094488)
		(width 0.127)
		(layer "In11.Cu")
		(net "SVID_DIO0_CPU1_R")
	)
	(segment
		(start 40.492426 -123.515374)
		(end 40.223186 -123.246134)
		(width 0.127)
		(layer "In11.Cu")
		(net "SVID_DIO0_CPU1_R")
	)
	(segment
		(start 40.223186 -123.066302)
		(end 40.482266 -122.807222)
		(width 0.127)
		(layer "In11.Cu")
		(net "SVID_DIO0_CPU1_R")
	)
	(segment
		(start 40.931338 -123.256294)
		(end 40.672258 -123.515374)
		(width 0.127)
		(layer "In11.Cu")
		(net "SVID_DIO0_CPU1_R")
	)
	(segment
		(start 12.30122 -255.164082)
		(end 10.579354 -256.885948)
		(width 0.127)
		(layer "In11.Cu")
		(net "SVID_DIO0_CPU1_R")
	)
	(segment
		(start 29.43098 -339.903562)
		(end 29.43098 -361.726734)
		(width 0.127)
		(layer "In11.Cu")
		(net "SVID_DIO0_CPU1_R")
	)
	(segment
		(start 101.835204 -356.795578)
		(end 100.431092 -358.19969)
		(width 0.127)
		(layer "In11.Cu")
		(net "SVID_DIO0_CPU1_R")
	)
	(segment
		(start 40.117014 -129.044954)
		(end 40.445944 -128.716024)
		(width 0.127)
		(layer "In11.Cu")
		(net "SVID_DIO0_CPU1_R")
	)
	(segment
		(start 16.410178 -153.134314)
		(end 16.410178 -169.604436)
		(width 0.127)
		(layer "In11.Cu")
		(net "SVID_DIO0_CPU1_R")
	)
	(segment
		(start 39.584122 -121.909078)
		(end 39.584122 -121.729246)
		(width 0.127)
		(layer "In11.Cu")
		(net "SVID_DIO0_CPU1_R")
	)
	(segment
		(start 32.37484 -336.959702)
		(end 29.43098 -339.903562)
		(width 0.127)
		(layer "In11.Cu")
		(net "SVID_DIO0_CPU1_R")
	)
	(segment
		(start 40.482266 -122.807222)
		(end 40.482266 -122.62739)
		(width 0.127)
		(layer "In11.Cu")
		(net "SVID_DIO0_CPU1_R")
	)
	(segment
		(start 39.325042 -122.34799)
		(end 39.325042 -122.168158)
		(width 0.127)
		(layer "In11.Cu")
		(net "SVID_DIO0_CPU1_R")
	)
	(segment
		(start 38.285166 -120.43029)
		(end 29.158946 -120.43029)
		(width 0.127)
		(layer "In11.Cu")
		(net "SVID_DIO0_CPU1_R")
	)
	(segment
		(start 42.723562 -127.094488)
		(end 42.723562 -124.868686)
		(width 0.127)
		(layer "In11.Cu")
		(net "SVID_DIO0_CPU1_R")
	)
	(segment
		(start 39.325042 -122.168158)
		(end 39.584122 -121.909078)
		(width 0.127)
		(layer "In11.Cu")
		(net "SVID_DIO0_CPU1_R")
	)
	(segment
		(start 40.117014 -131.696206)
		(end 40.117014 -129.044954)
		(width 0.127)
		(layer "In11.Cu")
		(net "SVID_DIO0_CPU1_R")
	)
	(segment
		(start 39.774114 -122.61723)
		(end 39.594282 -122.61723)
		(width 0.127)
		(layer "In11.Cu")
		(net "SVID_DIO0_CPU1_R")
	)
	(segment
		(start 10.579354 -256.885948)
		(end 9.492234 -256.885948)
		(width 0.127)
		(layer "In11.Cu")
		(net "SVID_DIO0_CPU1_R")
	)
	(segment
		(start 41.11117 -123.256294)
		(end 40.931338 -123.256294)
		(width 0.127)
		(layer "In11.Cu")
		(net "SVID_DIO0_CPU1_R")
	)
	(segment
		(start 40.213026 -122.35815)
		(end 40.033194 -122.35815)
		(width 0.127)
		(layer "In11.Cu")
		(net "SVID_DIO0_CPU1_R")
	)
	(segment
		(start 8.0645 -258.313682)
		(end 8.0645 -321.330574)
		(width 0.127)
		(layer "In11.Cu")
		(net "SVID_DIO0_CPU1_R")
	)
	(segment
		(start 100.431092 -358.19969)
		(end 99.209098 -358.19969)
		(width 0.127)
		(layer "In11.Cu")
		(net "SVID_DIO0_CPU1_R")
	)
	(segment
		(start 10.745724 -175.26889)
		(end 10.745724 -181.433978)
		(width 0.127)
		(layer "In11.Cu")
		(net "SVID_DIO0_CPU1_R")
	)
	(segment
		(start 8.0645 -321.330574)
		(end 11.524234 -324.790308)
		(width 0.127)
		(layer "In11.Cu")
		(net "SVID_DIO0_CPU1_R")
	)
	(segment
		(start 99.209098 -358.19969)
		(end 98.254058 -359.15473)
		(width 0.127)
		(layer "In11.Cu")
		(net "SVID_DIO0_CPU1_R")
	)
	(segment
		(start 29.158946 -120.43029)
		(end 21.892514 -127.696722)
		(width 0.127)
		(layer "In11.Cu")
		(net "SVID_DIO0_CPU1_R")
	)
	(segment
		(start 39.280338 -132.532882)
		(end 40.117014 -131.696206)
		(width 0.127)
		(layer "In11.Cu")
		(net "SVID_DIO0_CPU1_R")
	)
	(segment
		(start 39.594282 -122.61723)
		(end 39.325042 -122.34799)
		(width 0.127)
		(layer "In11.Cu")
		(net "SVID_DIO0_CPU1_R")
	)
	(segment
		(start 29.43098 -361.726734)
		(end 57.825894 -390.121648)
		(width 0.127)
		(layer "In11.Cu")
		(net "SVID_DIO0_CPU1_R")
	)
	(segment
		(start 97.27438 -365.656368)
		(end 97.27438 -364.079028)
		(width 0.127)
		(layer "In13.Cu")
		(net "SVID_DIO0_CPU1_R")
	)
	(segment
		(start 97.27438 -364.079028)
		(end 98.254058 -363.09935)
		(width 0.127)
		(layer "In13.Cu")
		(net "SVID_DIO0_CPU1_R")
	)
	(segment
		(start 95.76816 -388.285228)
		(end 95.76816 -367.162588)
		(width 0.127)
		(layer "In13.Cu")
		(net "SVID_DIO0_CPU1_R")
	)
	(segment
		(start 95.76816 -367.162588)
		(end 97.27438 -365.656368)
		(width 0.127)
		(layer "In13.Cu")
		(net "SVID_DIO0_CPU1_R")
	)
	(segment
		(start 95.2246 -388.828788)
		(end 95.76816 -388.285228)
		(width 0.127)
		(layer "In13.Cu")
		(net "SVID_DIO0_CPU1_R")
	)
	(segment
		(start 95.2246 -389.661908)
		(end 95.2246 -388.828788)
		(width 0.127)
		(layer "In13.Cu")
		(net "SVID_DIO0_CPU1_R")
	)
	(segment
		(start 104.875838 -234.877864)
		(end 104.615488 -235.017056)
		(width 0.12954)
		(layer "F.Cu")
		(net "SVID_DIO0_CPU1")
	)
	(segment
		(start 105.061512 -234.69219)
		(end 104.875838 -234.877864)
		(width 0.12954)
		(layer "F.Cu")
		(net "SVID_DIO0_CPU1")
	)
	(via
		(at 104.615488 -235.017056)
		(size 0.4572)
		(drill 0.2032)
		(layers "F.Cu" "B.Cu")
		(net "SVID_DIO0_CPU1")
	)
	(via
		(at 70.141338 -232.72115)
		(size 0.6604)
		(drill 0.3302)
		(layers "F.Cu" "B.Cu")
		(net "SVID_DIO0_CPU1")
	)
	(segment
		(start 95.006414 -235.294424)
		(end 94.991682 -235.285788)
		(width 0.0889)
		(layer "B.Cu")
		(net "SVID_DIO0_CPU1")
	)
	(segment
		(start 90.692478 -235.288328)
		(end 90.682064 -235.294424)
		(width 0.0889)
		(layer "B.Cu")
		(net "SVID_DIO0_CPU1")
	)
	(segment
		(start 95.946214 -235.294424)
		(end 95.931482 -235.285788)
		(width 0.0889)
		(layer "B.Cu")
		(net "SVID_DIO0_CPU1")
	)
	(segment
		(start 96.886268 -235.294424)
		(end 96.875854 -235.288328)
		(width 0.0889)
		(layer "B.Cu")
		(net "SVID_DIO0_CPU1")
	)
	(segment
		(start 89.367614 -235.294424)
		(end 89.352882 -235.285788)
		(width 0.0889)
		(layer "B.Cu")
		(net "SVID_DIO0_CPU1")
	)
	(segment
		(start 69.393308 -200.575926)
		(end 69.393308 -199.1487)
		(width 0.12954)
		(layer "B.Cu")
		(net "SVID_DIO0_CPU1")
	)
	(segment
		(start 77.330554 -236.697266)
		(end 73.354438 -232.72115)
		(width 0.12954)
		(layer "B.Cu")
		(net "SVID_DIO0_CPU1")
	)
	(segment
		(start 70.442836 -198.099172)
		(end 70.442836 -192.593214)
		(width 0.12954)
		(layer "B.Cu")
		(net "SVID_DIO0_CPU1")
	)
	(segment
		(start 66.70294 -204.270102)
		(end 66.70294 -203.266294)
		(width 0.12954)
		(layer "B.Cu")
		(net "SVID_DIO0_CPU1")
	)
	(segment
		(start 69.393308 -199.1487)
		(end 70.442836 -198.099172)
		(width 0.12954)
		(layer "B.Cu")
		(net "SVID_DIO0_CPU1")
	)
	(segment
		(start 85.631274 -236.697266)
		(end 77.330554 -236.697266)
		(width 0.12954)
		(layer "B.Cu")
		(net "SVID_DIO0_CPU1")
	)
	(segment
		(start 66.70294 -203.266294)
		(end 69.393308 -200.575926)
		(width 0.12954)
		(layer "B.Cu")
		(net "SVID_DIO0_CPU1")
	)
	(segment
		(start 97.271078 -235.288328)
		(end 97.260664 -235.294424)
		(width 0.0889)
		(layer "B.Cu")
		(net "SVID_DIO0_CPU1")
	)
	(segment
		(start 73.354438 -232.72115)
		(end 70.141338 -232.72115)
		(width 0.12954)
		(layer "B.Cu")
		(net "SVID_DIO0_CPU1")
	)
	(segment
		(start 64.860424 -205.809342)
		(end 65.978786 -204.69098)
		(width 0.12954)
		(layer "B.Cu")
		(net "SVID_DIO0_CPU1")
	)
	(segment
		(start 101.585014 -235.294424)
		(end 101.570282 -235.285788)
		(width 0.0889)
		(layer "B.Cu")
		(net "SVID_DIO0_CPU1")
	)
	(segment
		(start 98.765614 -235.294424)
		(end 98.750882 -235.285788)
		(width 0.0889)
		(layer "B.Cu")
		(net "SVID_DIO0_CPU1")
	)
	(segment
		(start 104.615488 -235.017056)
		(end 104.301544 -235.017056)
		(width 0.0889)
		(layer "B.Cu")
		(net "SVID_DIO0_CPU1")
	)
	(segment
		(start 88.246458 -235.131356)
		(end 87.197184 -235.131356)
		(width 0.0889)
		(layer "B.Cu")
		(net "SVID_DIO0_CPU1")
	)
	(segment
		(start 90.307668 -235.294424)
		(end 90.297254 -235.288328)
		(width 0.0889)
		(layer "B.Cu")
		(net "SVID_DIO0_CPU1")
	)
	(segment
		(start 70.442836 -192.593214)
		(end 70.849998 -191.610488)
		(width 0.12954)
		(layer "B.Cu")
		(net "SVID_DIO0_CPU1")
	)
	(segment
		(start 100.645214 -235.294424)
		(end 100.630482 -235.285788)
		(width 0.0889)
		(layer "B.Cu")
		(net "SVID_DIO0_CPU1")
	)
	(segment
		(start 104.301544 -235.017056)
		(end 104.240076 -234.955588)
		(width 0.0889)
		(layer "B.Cu")
		(net "SVID_DIO0_CPU1")
	)
	(segment
		(start 70.849998 -191.610488)
		(end 70.849998 -189.33922)
		(width 0.12954)
		(layer "B.Cu")
		(net "SVID_DIO0_CPU1")
	)
	(segment
		(start 104.240076 -234.955588)
		(end 102.317042 -234.955588)
		(width 0.0889)
		(layer "B.Cu")
		(net "SVID_DIO0_CPU1")
	)
	(segment
		(start 87.197184 -235.131356)
		(end 85.631274 -236.697266)
		(width 0.12954)
		(layer "B.Cu")
		(net "SVID_DIO0_CPU1")
	)
	(segment
		(start 93.126814 -235.294424)
		(end 93.112082 -235.285788)
		(width 0.0889)
		(layer "B.Cu")
		(net "SVID_DIO0_CPU1")
	)
	(segment
		(start 70.141338 -232.72115)
		(end 66.276728 -232.72115)
		(width 0.12954)
		(layer "B.Cu")
		(net "SVID_DIO0_CPU1")
	)
	(segment
		(start 88.35009 -235.234988)
		(end 88.246458 -235.131356)
		(width 0.0889)
		(layer "B.Cu")
		(net "SVID_DIO0_CPU1")
	)
	(segment
		(start 65.978786 -204.69098)
		(end 66.282062 -204.69098)
		(width 0.12954)
		(layer "B.Cu")
		(net "SVID_DIO0_CPU1")
	)
	(segment
		(start 94.066614 -235.294424)
		(end 94.051882 -235.285788)
		(width 0.0889)
		(layer "B.Cu")
		(net "SVID_DIO0_CPU1")
	)
	(segment
		(start 66.282062 -204.69098)
		(end 66.70294 -204.270102)
		(width 0.12954)
		(layer "B.Cu")
		(net "SVID_DIO0_CPU1")
	)
	(segment
		(start 66.276728 -232.72115)
		(end 65.865248 -232.550716)
		(width 0.12954)
		(layer "B.Cu")
		(net "SVID_DIO0_CPU1")
	)
	(segment
		(start 64.860424 -223.134428)
		(end 64.860424 -205.809342)
		(width 0.12954)
		(layer "B.Cu")
		(net "SVID_DIO0_CPU1")
	)
	(segment
		(start 65.21196 -223.485964)
		(end 64.860424 -223.134428)
		(width 0.12954)
		(layer "B.Cu")
		(net "SVID_DIO0_CPU1")
	)
	(segment
		(start 99.705414 -235.294424)
		(end 99.690682 -235.285788)
		(width 0.0889)
		(layer "B.Cu")
		(net "SVID_DIO0_CPU1")
	)
	(segment
		(start 92.187014 -235.294424)
		(end 92.172282 -235.285788)
		(width 0.0889)
		(layer "B.Cu")
		(net "SVID_DIO0_CPU1")
	)
	(segment
		(start 65.21196 -231.897428)
		(end 65.21196 -223.485964)
		(width 0.12954)
		(layer "B.Cu")
		(net "SVID_DIO0_CPU1")
	)
	(segment
		(start 65.865248 -232.550716)
		(end 65.21196 -231.897428)
		(width 0.12954)
		(layer "B.Cu")
		(net "SVID_DIO0_CPU1")
	)
	(segment
		(start 102.317042 -234.955588)
		(end 102.037388 -235.235242)
		(width 0.0889)
		(layer "B.Cu")
		(net "SVID_DIO0_CPU1")
	)
	(segment
		(start 70.849998 -189.33922)
		(end 70.369684 -188.858906)
		(width 0.12954)
		(layer "B.Cu")
		(net "SVID_DIO0_CPU1")
	)
	(arc
		(start 93.112082 -235.285788)
		(mid 92.835607 -235.218468)
		(end 92.56141 -235.294424)
		(width 0.0889)
		(layer "B.Cu")
		(net "SVID_DIO0_CPU1")
	)
	(arc
		(start 91.247214 -235.294424)
		(mid 90.970655 -235.218681)
		(end 90.692478 -235.288328)
		(width 0.0889)
		(layer "B.Cu")
		(net "SVID_DIO0_CPU1")
	)
	(arc
		(start 102.037388 -235.235242)
		(mid 102.000338 -235.267388)
		(end 101.95941 -235.294424)
		(width 0.0889)
		(layer "B.Cu")
		(net "SVID_DIO0_CPU1")
	)
	(arc
		(start 92.172282 -235.285788)
		(mid 91.895807 -235.218468)
		(end 91.62161 -235.294424)
		(width 0.0889)
		(layer "B.Cu")
		(net "SVID_DIO0_CPU1")
	)
	(arc
		(start 98.750882 -235.285788)
		(mid 98.474407 -235.218468)
		(end 98.20021 -235.294424)
		(width 0.0889)
		(layer "B.Cu")
		(net "SVID_DIO0_CPU1")
	)
	(arc
		(start 99.14001 -235.294424)
		(mid 98.952812 -235.344567)
		(end 98.765614 -235.294424)
		(width 0.0889)
		(layer "B.Cu")
		(net "SVID_DIO0_CPU1")
	)
	(arc
		(start 101.01961 -235.294424)
		(mid 100.832412 -235.344567)
		(end 100.645214 -235.294424)
		(width 0.0889)
		(layer "B.Cu")
		(net "SVID_DIO0_CPU1")
	)
	(arc
		(start 100.07981 -235.294424)
		(mid 99.892612 -235.344567)
		(end 99.705414 -235.294424)
		(width 0.0889)
		(layer "B.Cu")
		(net "SVID_DIO0_CPU1")
	)
	(arc
		(start 100.630482 -235.285788)
		(mid 100.354007 -235.218468)
		(end 100.07981 -235.294424)
		(width 0.0889)
		(layer "B.Cu")
		(net "SVID_DIO0_CPU1")
	)
	(arc
		(start 94.051882 -235.285788)
		(mid 93.775407 -235.218468)
		(end 93.50121 -235.294424)
		(width 0.0889)
		(layer "B.Cu")
		(net "SVID_DIO0_CPU1")
	)
	(arc
		(start 98.20021 -235.294424)
		(mid 98.013012 -235.344567)
		(end 97.825814 -235.294424)
		(width 0.0889)
		(layer "B.Cu")
		(net "SVID_DIO0_CPU1")
	)
	(arc
		(start 97.260664 -235.294424)
		(mid 97.073466 -235.344567)
		(end 96.886268 -235.294424)
		(width 0.0889)
		(layer "B.Cu")
		(net "SVID_DIO0_CPU1")
	)
	(arc
		(start 88.80221 -235.294424)
		(mid 88.566027 -235.341511)
		(end 88.35009 -235.234988)
		(width 0.0889)
		(layer "B.Cu")
		(net "SVID_DIO0_CPU1")
	)
	(arc
		(start 90.682064 -235.294424)
		(mid 90.494866 -235.344567)
		(end 90.307668 -235.294424)
		(width 0.0889)
		(layer "B.Cu")
		(net "SVID_DIO0_CPU1")
	)
	(arc
		(start 94.44101 -235.294424)
		(mid 94.253812 -235.344567)
		(end 94.066614 -235.294424)
		(width 0.0889)
		(layer "B.Cu")
		(net "SVID_DIO0_CPU1")
	)
	(arc
		(start 95.38081 -235.294424)
		(mid 95.193612 -235.344567)
		(end 95.006414 -235.294424)
		(width 0.0889)
		(layer "B.Cu")
		(net "SVID_DIO0_CPU1")
	)
	(arc
		(start 101.95941 -235.294424)
		(mid 101.772212 -235.344567)
		(end 101.585014 -235.294424)
		(width 0.0889)
		(layer "B.Cu")
		(net "SVID_DIO0_CPU1")
	)
	(arc
		(start 89.352882 -235.285788)
		(mid 89.076407 -235.218468)
		(end 88.80221 -235.294424)
		(width 0.0889)
		(layer "B.Cu")
		(net "SVID_DIO0_CPU1")
	)
	(arc
		(start 89.74201 -235.294424)
		(mid 89.554812 -235.344567)
		(end 89.367614 -235.294424)
		(width 0.0889)
		(layer "B.Cu")
		(net "SVID_DIO0_CPU1")
	)
	(arc
		(start 93.50121 -235.294424)
		(mid 93.314012 -235.344567)
		(end 93.126814 -235.294424)
		(width 0.0889)
		(layer "B.Cu")
		(net "SVID_DIO0_CPU1")
	)
	(arc
		(start 91.62161 -235.294424)
		(mid 91.434412 -235.344567)
		(end 91.247214 -235.294424)
		(width 0.0889)
		(layer "B.Cu")
		(net "SVID_DIO0_CPU1")
	)
	(arc
		(start 97.825814 -235.294424)
		(mid 97.549255 -235.218681)
		(end 97.271078 -235.288328)
		(width 0.0889)
		(layer "B.Cu")
		(net "SVID_DIO0_CPU1")
	)
	(arc
		(start 95.931482 -235.285788)
		(mid 95.655007 -235.218468)
		(end 95.38081 -235.294424)
		(width 0.0889)
		(layer "B.Cu")
		(net "SVID_DIO0_CPU1")
	)
	(arc
		(start 101.570282 -235.285788)
		(mid 101.293807 -235.218468)
		(end 101.01961 -235.294424)
		(width 0.0889)
		(layer "B.Cu")
		(net "SVID_DIO0_CPU1")
	)
	(arc
		(start 90.297254 -235.288328)
		(mid 90.018822 -235.218482)
		(end 89.74201 -235.294424)
		(width 0.0889)
		(layer "B.Cu")
		(net "SVID_DIO0_CPU1")
	)
	(arc
		(start 94.991682 -235.285788)
		(mid 94.715207 -235.218468)
		(end 94.44101 -235.294424)
		(width 0.0889)
		(layer "B.Cu")
		(net "SVID_DIO0_CPU1")
	)
	(arc
		(start 92.56141 -235.294424)
		(mid 92.374212 -235.344567)
		(end 92.187014 -235.294424)
		(width 0.0889)
		(layer "B.Cu")
		(net "SVID_DIO0_CPU1")
	)
	(arc
		(start 96.875854 -235.288328)
		(mid 96.597422 -235.218482)
		(end 96.32061 -235.294424)
		(width 0.0889)
		(layer "B.Cu")
		(net "SVID_DIO0_CPU1")
	)
	(arc
		(start 96.32061 -235.294424)
		(mid 96.133412 -235.344567)
		(end 95.946214 -235.294424)
		(width 0.0889)
		(layer "B.Cu")
		(net "SVID_DIO0_CPU1")
	)
	(arc
		(start 99.690682 -235.285788)
		(mid 99.414207 -235.218468)
		(end 99.14001 -235.294424)
		(width 0.0889)
		(layer "B.Cu")
		(net "SVID_DIO0_CPU1")
	)
	(segment
		(start 432.29784 -138.157712)
		(end 432.187604 -138.047476)
		(width 0.12954)
		(layer "F.Cu")
		(net "SVID_DIO0_CPU0_R")
	)
	(segment
		(start 347.64472 -362.748068)
		(end 346.292678 -361.396026)
		(width 0.12954)
		(layer "F.Cu")
		(net "SVID_DIO0_CPU0_R")
	)
	(segment
		(start 348.253304 -355.970332)
		(end 348.761304 -356.478332)
		(width 0.12954)
		(layer "F.Cu")
		(net "SVID_DIO0_CPU0_R")
	)
	(segment
		(start 346.292678 -356.75697)
		(end 347.079316 -355.970332)
		(width 0.12954)
		(layer "F.Cu")
		(net "SVID_DIO0_CPU0_R")
	)
	(segment
		(start 431.000154 -137.843006)
		(end 431.000154 -137.542778)
		(width 0.12954)
		(layer "F.Cu")
		(net "SVID_DIO0_CPU0_R")
	)
	(segment
		(start 347.079316 -355.970332)
		(end 348.253304 -355.970332)
		(width 0.12954)
		(layer "F.Cu")
		(net "SVID_DIO0_CPU0_R")
	)
	(segment
		(start 433.876704 -138.157712)
		(end 432.80584 -138.157712)
		(width 0.12954)
		(layer "F.Cu")
		(net "SVID_DIO0_CPU0_R")
	)
	(segment
		(start 348.761304 -356.478332)
		(end 348.790514 -356.478332)
		(width 0.12954)
		(layer "F.Cu")
		(net "SVID_DIO0_CPU0_R")
	)
	(segment
		(start 350.38538 -356.668578)
		(end 350.25838 -356.795578)
		(width 0.12954)
		(layer "F.Cu")
		(net "SVID_DIO0_CPU0_R")
	)
	(segment
		(start 349.10776 -356.795578)
		(end 348.790514 -356.478332)
		(width 0.12954)
		(layer "F.Cu")
		(net "SVID_DIO0_CPU0_R")
	)
	(segment
		(start 346.292678 -361.396026)
		(end 346.292678 -356.75697)
		(width 0.12954)
		(layer "F.Cu")
		(net "SVID_DIO0_CPU0_R")
	)
	(segment
		(start 434.25872 -138.539728)
		(end 433.876704 -138.157712)
		(width 0.12954)
		(layer "F.Cu")
		(net "SVID_DIO0_CPU0_R")
	)
	(segment
		(start 431.204624 -138.047476)
		(end 431.000154 -137.843006)
		(width 0.12954)
		(layer "F.Cu")
		(net "SVID_DIO0_CPU0_R")
	)
	(segment
		(start 347.37548 -363.593888)
		(end 347.64472 -363.324648)
		(width 0.12954)
		(layer "F.Cu")
		(net "SVID_DIO0_CPU0_R")
	)
	(segment
		(start 347.64472 -363.324648)
		(end 347.64472 -362.748068)
		(width 0.12954)
		(layer "F.Cu")
		(net "SVID_DIO0_CPU0_R")
	)
	(segment
		(start 350.25838 -356.795578)
		(end 349.10776 -356.795578)
		(width 0.12954)
		(layer "F.Cu")
		(net "SVID_DIO0_CPU0_R")
	)
	(segment
		(start 432.187604 -138.047476)
		(end 431.204624 -138.047476)
		(width 0.12954)
		(layer "F.Cu")
		(net "SVID_DIO0_CPU0_R")
	)
	(segment
		(start 432.80584 -138.157712)
		(end 432.29784 -138.157712)
		(width 0.12954)
		(layer "F.Cu")
		(net "SVID_DIO0_CPU0_R")
	)
	(via
		(at 305.385978 -192.298828)
		(size 0.508)
		(drill 0.254)
		(layers "F.Cu" "B.Cu")
		(net "SVID_DIO0_CPU0_R")
	)
	(via
		(at 347.37548 -363.593888)
		(size 0.508)
		(drill 0.254)
		(layers "F.Cu" "B.Cu")
		(net "SVID_DIO0_CPU0_R")
	)
	(via
		(at 434.25872 -138.539728)
		(size 0.762)
		(drill 0.254)
		(layers "F.Cu" "B.Cu")
		(net "SVID_DIO0_CPU0_R")
	)
	(segment
		(start 304.926238 -194.32016)
		(end 304.926238 -193.65849)
		(width 0.12954)
		(layer "B.Cu")
		(net "SVID_DIO0_CPU0_R")
	)
	(segment
		(start 304.878232 -192.850516)
		(end 304.697638 -192.850516)
		(width 0.12954)
		(layer "B.Cu")
		(net "SVID_DIO0_CPU0_R")
	)
	(segment
		(start 305.385978 -192.34277)
		(end 304.878232 -192.850516)
		(width 0.12954)
		(layer "B.Cu")
		(net "SVID_DIO0_CPU0_R")
	)
	(segment
		(start 305.385978 -192.298828)
		(end 305.385978 -192.34277)
		(width 0.12954)
		(layer "B.Cu")
		(net "SVID_DIO0_CPU0_R")
	)
	(segment
		(start 304.926238 -193.65849)
		(end 304.697638 -193.42989)
		(width 0.12954)
		(layer "B.Cu")
		(net "SVID_DIO0_CPU0_R")
	)
	(segment
		(start 304.697638 -193.42989)
		(end 304.697638 -192.850516)
		(width 0.12954)
		(layer "B.Cu")
		(net "SVID_DIO0_CPU0_R")
	)
	(segment
		(start 347.37548 -363.593888)
		(end 350.25838 -363.593888)
		(width 0.127)
		(layer "In6.Cu")
		(net "SVID_DIO0_CPU0_R")
	)
	(segment
		(start 351.263204 -381.791972)
		(end 353.457764 -383.986532)
		(width 0.127)
		(layer "In6.Cu")
		(net "SVID_DIO0_CPU0_R")
	)
	(segment
		(start 435.984142 -370.131086)
		(end 435.984142 -362.861098)
		(width 0.127)
		(layer "In6.Cu")
		(net "SVID_DIO0_CPU0_R")
	)
	(segment
		(start 438.587134 -142.346426)
		(end 434.780436 -138.539728)
		(width 0.127)
		(layer "In6.Cu")
		(net "SVID_DIO0_CPU0_R")
	)
	(segment
		(start 464.77047 -334.07477)
		(end 465.66328 -331.919326)
		(width 0.127)
		(layer "In6.Cu")
		(net "SVID_DIO0_CPU0_R")
	)
	(segment
		(start 425.30268 -380.812548)
		(end 435.984142 -370.131086)
		(width 0.127)
		(layer "In6.Cu")
		(net "SVID_DIO0_CPU0_R")
	)
	(segment
		(start 444.997078 -142.346426)
		(end 438.587134 -142.346426)
		(width 0.127)
		(layer "In6.Cu")
		(net "SVID_DIO0_CPU0_R")
	)
	(segment
		(start 388.862824 -383.986532)
		(end 390.353296 -385.477004)
		(width 0.127)
		(layer "In6.Cu")
		(net "SVID_DIO0_CPU0_R")
	)
	(segment
		(start 465.66328 -178.861212)
		(end 448.797934 -161.995866)
		(width 0.127)
		(layer "In6.Cu")
		(net "SVID_DIO0_CPU0_R")
	)
	(segment
		(start 353.457764 -383.986532)
		(end 388.862824 -383.986532)
		(width 0.127)
		(layer "In6.Cu")
		(net "SVID_DIO0_CPU0_R")
	)
	(segment
		(start 350.25838 -363.593888)
		(end 351.263204 -364.598712)
		(width 0.127)
		(layer "In6.Cu")
		(net "SVID_DIO0_CPU0_R")
	)
	(segment
		(start 351.263204 -364.598712)
		(end 351.263204 -381.791972)
		(width 0.127)
		(layer "In6.Cu")
		(net "SVID_DIO0_CPU0_R")
	)
	(segment
		(start 435.984142 -362.861098)
		(end 464.77047 -334.07477)
		(width 0.127)
		(layer "In6.Cu")
		(net "SVID_DIO0_CPU0_R")
	)
	(segment
		(start 448.797934 -146.147282)
		(end 444.997078 -142.346426)
		(width 0.127)
		(layer "In6.Cu")
		(net "SVID_DIO0_CPU0_R")
	)
	(segment
		(start 448.797934 -161.995866)
		(end 448.797934 -146.147282)
		(width 0.127)
		(layer "In6.Cu")
		(net "SVID_DIO0_CPU0_R")
	)
	(segment
		(start 390.353296 -385.477004)
		(end 404.483824 -385.477004)
		(width 0.127)
		(layer "In6.Cu")
		(net "SVID_DIO0_CPU0_R")
	)
	(segment
		(start 409.14828 -380.812548)
		(end 425.30268 -380.812548)
		(width 0.127)
		(layer "In6.Cu")
		(net "SVID_DIO0_CPU0_R")
	)
	(segment
		(start 434.780436 -138.539728)
		(end 434.25872 -138.539728)
		(width 0.127)
		(layer "In6.Cu")
		(net "SVID_DIO0_CPU0_R")
	)
	(segment
		(start 404.483824 -385.477004)
		(end 409.14828 -380.812548)
		(width 0.127)
		(layer "In6.Cu")
		(net "SVID_DIO0_CPU0_R")
	)
	(segment
		(start 465.66328 -331.919326)
		(end 465.66328 -178.861212)
		(width 0.127)
		(layer "In6.Cu")
		(net "SVID_DIO0_CPU0_R")
	)
	(segment
		(start 394.767816 -148.694648)
		(end 348.836996 -148.694648)
		(width 0.127)
		(layer "In13.Cu")
		(net "SVID_DIO0_CPU0_R")
	)
	(segment
		(start 305.32578 -186.187588)
		(end 305.32578 -190.203328)
		(width 0.127)
		(layer "In13.Cu")
		(net "SVID_DIO0_CPU0_R")
	)
	(segment
		(start 303.25568 -184.117488)
		(end 305.32578 -186.187588)
		(width 0.127)
		(layer "In13.Cu")
		(net "SVID_DIO0_CPU0_R")
	)
	(segment
		(start 304.82032 -191.67729)
		(end 305.385978 -192.242948)
		(width 0.127)
		(layer "In13.Cu")
		(net "SVID_DIO0_CPU0_R")
	)
	(segment
		(start 434.25872 -141.584172)
		(end 430.683924 -145.158968)
		(width 0.127)
		(layer "In13.Cu")
		(net "SVID_DIO0_CPU0_R")
	)
	(segment
		(start 421.773096 -145.158968)
		(end 421.557196 -144.943068)
		(width 0.127)
		(layer "In13.Cu")
		(net "SVID_DIO0_CPU0_R")
	)
	(segment
		(start 430.683924 -145.158968)
		(end 421.773096 -145.158968)
		(width 0.127)
		(layer "In13.Cu")
		(net "SVID_DIO0_CPU0_R")
	)
	(segment
		(start 421.557196 -144.943068)
		(end 401.732496 -144.943068)
		(width 0.127)
		(layer "In13.Cu")
		(net "SVID_DIO0_CPU0_R")
	)
	(segment
		(start 303.25568 -153.985468)
		(end 303.25568 -184.117488)
		(width 0.127)
		(layer "In13.Cu")
		(net "SVID_DIO0_CPU0_R")
	)
	(segment
		(start 305.32578 -190.203328)
		(end 304.82032 -190.708788)
		(width 0.127)
		(layer "In13.Cu")
		(net "SVID_DIO0_CPU0_R")
	)
	(segment
		(start 434.25872 -138.539728)
		(end 434.25872 -141.584172)
		(width 0.127)
		(layer "In13.Cu")
		(net "SVID_DIO0_CPU0_R")
	)
	(segment
		(start 401.732496 -144.943068)
		(end 398.958816 -147.716748)
		(width 0.127)
		(layer "In13.Cu")
		(net "SVID_DIO0_CPU0_R")
	)
	(segment
		(start 305.385978 -192.242948)
		(end 305.385978 -192.298828)
		(width 0.127)
		(layer "In13.Cu")
		(net "SVID_DIO0_CPU0_R")
	)
	(segment
		(start 304.82032 -190.708788)
		(end 304.82032 -191.67729)
		(width 0.127)
		(layer "In13.Cu")
		(net "SVID_DIO0_CPU0_R")
	)
	(segment
		(start 398.958816 -147.716748)
		(end 395.745716 -147.716748)
		(width 0.127)
		(layer "In13.Cu")
		(net "SVID_DIO0_CPU0_R")
	)
	(segment
		(start 347.859096 -149.672548)
		(end 307.5686 -149.672548)
		(width 0.127)
		(layer "In13.Cu")
		(net "SVID_DIO0_CPU0_R")
	)
	(segment
		(start 348.836996 -148.694648)
		(end 347.859096 -149.672548)
		(width 0.127)
		(layer "In13.Cu")
		(net "SVID_DIO0_CPU0_R")
	)
	(segment
		(start 307.5686 -149.672548)
		(end 303.25568 -153.985468)
		(width 0.127)
		(layer "In13.Cu")
		(net "SVID_DIO0_CPU0_R")
	)
	(segment
		(start 395.745716 -147.716748)
		(end 394.767816 -148.694648)
		(width 0.127)
		(layer "In13.Cu")
		(net "SVID_DIO0_CPU0_R")
	)
	(segment
		(start 353.216718 -234.907328)
		(end 353.4537 -235.005626)
		(width 0.12954)
		(layer "F.Cu")
		(net "SVID_DIO0_CPU0")
	)
	(segment
		(start 353.00158 -234.69219)
		(end 353.216718 -234.907328)
		(width 0.12954)
		(layer "F.Cu")
		(net "SVID_DIO0_CPU0")
	)
	(via
		(at 316.073282 -238.62411)
		(size 0.6604)
		(drill 0.3302)
		(layers "F.Cu" "B.Cu")
		(net "SVID_DIO0_CPU0")
	)
	(via
		(at 353.4537 -235.005626)
		(size 0.4572)
		(drill 0.2032)
		(layers "F.Cu" "B.Cu")
		(net "SVID_DIO0_CPU0")
	)
	(segment
		(start 345.211146 -235.288328)
		(end 345.200732 -235.294424)
		(width 0.0889)
		(layer "B.Cu")
		(net "SVID_DIO0_CPU0")
	)
	(segment
		(start 304.926238 -195.68033)
		(end 304.926238 -195.12026)
		(width 0.12954)
		(layer "B.Cu")
		(net "SVID_DIO0_CPU0")
	)
	(segment
		(start 308.106318 -238.37011)
		(end 305.388518 -235.65231)
		(width 0.12954)
		(layer "B.Cu")
		(net "SVID_DIO0_CPU0")
	)
	(segment
		(start 343.886282 -235.294424)
		(end 343.87155 -235.285788)
		(width 0.0889)
		(layer "B.Cu")
		(net "SVID_DIO0_CPU0")
	)
	(segment
		(start 347.645482 -235.294424)
		(end 347.63075 -235.285788)
		(width 0.0889)
		(layer "B.Cu")
		(net "SVID_DIO0_CPU0")
	)
	(segment
		(start 328.182478 -238.62411)
		(end 316.073282 -238.62411)
		(width 0.12954)
		(layer "B.Cu")
		(net "SVID_DIO0_CPU0")
	)
	(segment
		(start 330.340208 -236.46638)
		(end 328.182478 -238.62411)
		(width 0.12954)
		(layer "B.Cu")
		(net "SVID_DIO0_CPU0")
	)
	(segment
		(start 342.946482 -235.294424)
		(end 342.93175 -235.285788)
		(width 0.0889)
		(layer "B.Cu")
		(net "SVID_DIO0_CPU0")
	)
	(segment
		(start 336.186526 -235.131356)
		(end 335.667858 -235.131356)
		(width 0.0889)
		(layer "B.Cu")
		(net "SVID_DIO0_CPU0")
	)
	(segment
		(start 338.247736 -235.294424)
		(end 338.237322 -235.288328)
		(width 0.0889)
		(layer "B.Cu")
		(net "SVID_DIO0_CPU0")
	)
	(segment
		(start 305.388518 -235.65231)
		(end 305.388518 -196.14261)
		(width 0.12954)
		(layer "B.Cu")
		(net "SVID_DIO0_CPU0")
	)
	(segment
		(start 337.307682 -235.294424)
		(end 337.29295 -235.285788)
		(width 0.0889)
		(layer "B.Cu")
		(net "SVID_DIO0_CPU0")
	)
	(segment
		(start 349.525082 -235.294424)
		(end 349.51035 -235.285788)
		(width 0.0889)
		(layer "B.Cu")
		(net "SVID_DIO0_CPU0")
	)
	(segment
		(start 335.667858 -235.131356)
		(end 335.093056 -235.131356)
		(width 0.12954)
		(layer "B.Cu")
		(net "SVID_DIO0_CPU0")
	)
	(segment
		(start 311.260998 -238.62411)
		(end 311.006998 -238.37011)
		(width 0.12954)
		(layer "B.Cu")
		(net "SVID_DIO0_CPU0")
	)
	(segment
		(start 353.4537 -235.005626)
		(end 350.207072 -235.005626)
		(width 0.0889)
		(layer "B.Cu")
		(net "SVID_DIO0_CPU0")
	)
	(segment
		(start 311.006998 -238.37011)
		(end 308.106318 -238.37011)
		(width 0.12954)
		(layer "B.Cu")
		(net "SVID_DIO0_CPU0")
	)
	(segment
		(start 350.207072 -235.005626)
		(end 349.977456 -235.235242)
		(width 0.0889)
		(layer "B.Cu")
		(net "SVID_DIO0_CPU0")
	)
	(segment
		(start 344.826336 -235.294424)
		(end 344.815922 -235.288328)
		(width 0.0889)
		(layer "B.Cu")
		(net "SVID_DIO0_CPU0")
	)
	(segment
		(start 341.066882 -235.294424)
		(end 341.05215 -235.285788)
		(width 0.0889)
		(layer "B.Cu")
		(net "SVID_DIO0_CPU0")
	)
	(segment
		(start 316.073282 -238.62411)
		(end 311.260998 -238.62411)
		(width 0.12954)
		(layer "B.Cu")
		(net "SVID_DIO0_CPU0")
	)
	(segment
		(start 346.705682 -235.294424)
		(end 346.69095 -235.285788)
		(width 0.0889)
		(layer "B.Cu")
		(net "SVID_DIO0_CPU0")
	)
	(segment
		(start 338.632546 -235.288328)
		(end 338.622132 -235.294424)
		(width 0.0889)
		(layer "B.Cu")
		(net "SVID_DIO0_CPU0")
	)
	(segment
		(start 340.127082 -235.294424)
		(end 340.11235 -235.285788)
		(width 0.0889)
		(layer "B.Cu")
		(net "SVID_DIO0_CPU0")
	)
	(segment
		(start 336.290158 -235.234988)
		(end 336.186526 -235.131356)
		(width 0.0889)
		(layer "B.Cu")
		(net "SVID_DIO0_CPU0")
	)
	(segment
		(start 348.585282 -235.294424)
		(end 348.57055 -235.285788)
		(width 0.0889)
		(layer "B.Cu")
		(net "SVID_DIO0_CPU0")
	)
	(segment
		(start 305.388518 -196.14261)
		(end 304.926238 -195.68033)
		(width 0.12954)
		(layer "B.Cu")
		(net "SVID_DIO0_CPU0")
	)
	(segment
		(start 342.006682 -235.294424)
		(end 341.99195 -235.285788)
		(width 0.0889)
		(layer "B.Cu")
		(net "SVID_DIO0_CPU0")
	)
	(segment
		(start 333.758032 -236.46638)
		(end 330.340208 -236.46638)
		(width 0.12954)
		(layer "B.Cu")
		(net "SVID_DIO0_CPU0")
	)
	(segment
		(start 335.093056 -235.131356)
		(end 333.758032 -236.46638)
		(width 0.12954)
		(layer "B.Cu")
		(net "SVID_DIO0_CPU0")
	)
	(arc
		(start 346.69095 -235.285788)
		(mid 346.414475 -235.218468)
		(end 346.140278 -235.294424)
		(width 0.0889)
		(layer "B.Cu")
		(net "SVID_DIO0_CPU0")
	)
	(arc
		(start 347.080078 -235.294424)
		(mid 346.89288 -235.344567)
		(end 346.705682 -235.294424)
		(width 0.0889)
		(layer "B.Cu")
		(net "SVID_DIO0_CPU0")
	)
	(arc
		(start 343.320878 -235.294424)
		(mid 343.13368 -235.344567)
		(end 342.946482 -235.294424)
		(width 0.0889)
		(layer "B.Cu")
		(net "SVID_DIO0_CPU0")
	)
	(arc
		(start 345.200732 -235.294424)
		(mid 345.013534 -235.344567)
		(end 344.826336 -235.294424)
		(width 0.0889)
		(layer "B.Cu")
		(net "SVID_DIO0_CPU0")
	)
	(arc
		(start 337.682078 -235.294424)
		(mid 337.49488 -235.344567)
		(end 337.307682 -235.294424)
		(width 0.0889)
		(layer "B.Cu")
		(net "SVID_DIO0_CPU0")
	)
	(arc
		(start 339.187282 -235.294424)
		(mid 338.910723 -235.218681)
		(end 338.632546 -235.288328)
		(width 0.0889)
		(layer "B.Cu")
		(net "SVID_DIO0_CPU0")
	)
	(arc
		(start 342.381078 -235.294424)
		(mid 342.19388 -235.344567)
		(end 342.006682 -235.294424)
		(width 0.0889)
		(layer "B.Cu")
		(net "SVID_DIO0_CPU0")
	)
	(arc
		(start 349.899478 -235.294424)
		(mid 349.71228 -235.344567)
		(end 349.525082 -235.294424)
		(width 0.0889)
		(layer "B.Cu")
		(net "SVID_DIO0_CPU0")
	)
	(arc
		(start 347.63075 -235.285788)
		(mid 347.354275 -235.218468)
		(end 347.080078 -235.294424)
		(width 0.0889)
		(layer "B.Cu")
		(net "SVID_DIO0_CPU0")
	)
	(arc
		(start 348.019878 -235.294424)
		(mid 347.83268 -235.344567)
		(end 347.645482 -235.294424)
		(width 0.0889)
		(layer "B.Cu")
		(net "SVID_DIO0_CPU0")
	)
	(arc
		(start 336.742278 -235.294424)
		(mid 336.506095 -235.341511)
		(end 336.290158 -235.234988)
		(width 0.0889)
		(layer "B.Cu")
		(net "SVID_DIO0_CPU0")
	)
	(arc
		(start 348.57055 -235.285788)
		(mid 348.294075 -235.218468)
		(end 348.019878 -235.294424)
		(width 0.0889)
		(layer "B.Cu")
		(net "SVID_DIO0_CPU0")
	)
	(arc
		(start 345.765882 -235.294424)
		(mid 345.489323 -235.218681)
		(end 345.211146 -235.288328)
		(width 0.0889)
		(layer "B.Cu")
		(net "SVID_DIO0_CPU0")
	)
	(arc
		(start 348.959678 -235.294424)
		(mid 348.77248 -235.344567)
		(end 348.585282 -235.294424)
		(width 0.0889)
		(layer "B.Cu")
		(net "SVID_DIO0_CPU0")
	)
	(arc
		(start 338.237322 -235.288328)
		(mid 337.95889 -235.218482)
		(end 337.682078 -235.294424)
		(width 0.0889)
		(layer "B.Cu")
		(net "SVID_DIO0_CPU0")
	)
	(arc
		(start 343.87155 -235.285788)
		(mid 343.595075 -235.218468)
		(end 343.320878 -235.294424)
		(width 0.0889)
		(layer "B.Cu")
		(net "SVID_DIO0_CPU0")
	)
	(arc
		(start 337.29295 -235.285788)
		(mid 337.016475 -235.218468)
		(end 336.742278 -235.294424)
		(width 0.0889)
		(layer "B.Cu")
		(net "SVID_DIO0_CPU0")
	)
	(arc
		(start 342.93175 -235.285788)
		(mid 342.655275 -235.218468)
		(end 342.381078 -235.294424)
		(width 0.0889)
		(layer "B.Cu")
		(net "SVID_DIO0_CPU0")
	)
	(arc
		(start 344.815922 -235.288328)
		(mid 344.53749 -235.218482)
		(end 344.260678 -235.294424)
		(width 0.0889)
		(layer "B.Cu")
		(net "SVID_DIO0_CPU0")
	)
	(arc
		(start 340.501478 -235.294424)
		(mid 340.31428 -235.344567)
		(end 340.127082 -235.294424)
		(width 0.0889)
		(layer "B.Cu")
		(net "SVID_DIO0_CPU0")
	)
	(arc
		(start 339.561678 -235.294424)
		(mid 339.37448 -235.344567)
		(end 339.187282 -235.294424)
		(width 0.0889)
		(layer "B.Cu")
		(net "SVID_DIO0_CPU0")
	)
	(arc
		(start 341.05215 -235.285788)
		(mid 340.775675 -235.218468)
		(end 340.501478 -235.294424)
		(width 0.0889)
		(layer "B.Cu")
		(net "SVID_DIO0_CPU0")
	)
	(arc
		(start 346.140278 -235.294424)
		(mid 345.95308 -235.344567)
		(end 345.765882 -235.294424)
		(width 0.0889)
		(layer "B.Cu")
		(net "SVID_DIO0_CPU0")
	)
	(arc
		(start 340.11235 -235.285788)
		(mid 339.835875 -235.218468)
		(end 339.561678 -235.294424)
		(width 0.0889)
		(layer "B.Cu")
		(net "SVID_DIO0_CPU0")
	)
	(arc
		(start 341.99195 -235.285788)
		(mid 341.715475 -235.218468)
		(end 341.441278 -235.294424)
		(width 0.0889)
		(layer "B.Cu")
		(net "SVID_DIO0_CPU0")
	)
	(arc
		(start 338.622132 -235.294424)
		(mid 338.434934 -235.344567)
		(end 338.247736 -235.294424)
		(width 0.0889)
		(layer "B.Cu")
		(net "SVID_DIO0_CPU0")
	)
	(arc
		(start 341.441278 -235.294424)
		(mid 341.25408 -235.344567)
		(end 341.066882 -235.294424)
		(width 0.0889)
		(layer "B.Cu")
		(net "SVID_DIO0_CPU0")
	)
	(arc
		(start 344.260678 -235.294424)
		(mid 344.07348 -235.344567)
		(end 343.886282 -235.294424)
		(width 0.0889)
		(layer "B.Cu")
		(net "SVID_DIO0_CPU0")
	)
	(arc
		(start 349.51035 -235.285788)
		(mid 349.233875 -235.218468)
		(end 348.959678 -235.294424)
		(width 0.0889)
		(layer "B.Cu")
		(net "SVID_DIO0_CPU0")
	)
	(arc
		(start 349.977456 -235.235242)
		(mid 349.940406 -235.267388)
		(end 349.899478 -235.294424)
		(width 0.0889)
		(layer "B.Cu")
		(net "SVID_DIO0_CPU0")
	)
	(segment
		(start 104.4321 -357.673402)
		(end 104.735884 -357.673402)
		(width 0.12954)
		(layer "F.Cu")
		(net "SVID_CLK_PVCCIN_CPU1_R")
	)
	(segment
		(start 104.735884 -357.673402)
		(end 104.91089 -357.848408)
		(width 0.12954)
		(layer "F.Cu")
		(net "SVID_CLK_PVCCIN_CPU1_R")
	)
	(segment
		(start 103.35514 -357.673402)
		(end 104.4321 -357.673402)
		(width 0.12954)
		(layer "F.Cu")
		(net "SVID_CLK_PVCCIN_CPU1_R")
	)
	(segment
		(start 103.244396 -357.562658)
		(end 103.35514 -357.673402)
		(width 0.12954)
		(layer "F.Cu")
		(net "SVID_CLK_PVCCIN_CPU1_R")
	)
	(segment
		(start 104.91089 -357.848408)
		(end 105.70337 -357.848408)
		(width 0.12954)
		(layer "F.Cu")
		(net "SVID_CLK_PVCCIN_CPU1_R")
	)
	(via
		(at 104.4321 -357.673402)
		(size 0.508)
		(drill 0.254)
		(layers "F.Cu" "B.Cu")
		(net "SVID_CLK_PVCCIN_CPU1_R")
	)
	(segment
		(start 351.294954 -357.673402)
		(end 351.18421 -357.562658)
		(width 0.12954)
		(layer "F.Cu")
		(net "SVID_CLK_PVCCIN_CPU0_R")
	)
	(segment
		(start 353.643184 -357.848408)
		(end 352.591116 -357.848408)
		(width 0.12954)
		(layer "F.Cu")
		(net "SVID_CLK_PVCCIN_CPU0_R")
	)
	(segment
		(start 352.371914 -357.673402)
		(end 351.294954 -357.673402)
		(width 0.12954)
		(layer "F.Cu")
		(net "SVID_CLK_PVCCIN_CPU0_R")
	)
	(segment
		(start 352.591116 -357.848408)
		(end 352.41611 -357.673402)
		(width 0.12954)
		(layer "F.Cu")
		(net "SVID_CLK_PVCCIN_CPU0_R")
	)
	(segment
		(start 352.41611 -357.673402)
		(end 352.371914 -357.673402)
		(width 0.12954)
		(layer "F.Cu")
		(net "SVID_CLK_PVCCIN_CPU0_R")
	)
	(via
		(at 352.371914 -357.673402)
		(size 0.508)
		(drill 0.254)
		(layers "F.Cu" "B.Cu")
		(net "SVID_CLK_PVCCIN_CPU0_R")
	)
	(segment
		(start 35.229292 -130.23342)
		(end 35.275012 -130.1877)
		(width 0.12954)
		(layer "F.Cu")
		(net "SVID_CLK_PVCCINFAON_CPU1_R")
	)
	(segment
		(start 34.461196 -130.23342)
		(end 35.229292 -130.23342)
		(width 0.12954)
		(layer "F.Cu")
		(net "SVID_CLK_PVCCINFAON_CPU1_R")
	)
	(segment
		(start 36.114228 -130.1877)
		(end 36.556188 -129.74574)
		(width 0.12954)
		(layer "F.Cu")
		(net "SVID_CLK_PVCCINFAON_CPU1_R")
	)
	(segment
		(start 35.275012 -130.1877)
		(end 36.114228 -130.1877)
		(width 0.12954)
		(layer "F.Cu")
		(net "SVID_CLK_PVCCINFAON_CPU1_R")
	)
	(via
		(at 35.275012 -130.1877)
		(size 0.508)
		(drill 0.254)
		(layers "F.Cu" "B.Cu")
		(net "SVID_CLK_PVCCINFAON_CPU1_R")
	)
	(segment
		(start 429.134524 -137.130028)
		(end 429.246284 -137.130028)
		(width 0.12954)
		(layer "F.Cu")
		(net "SVID_CLK_PVCCINFAON_CPU0_R")
	)
	(segment
		(start 429.849534 -136.526778)
		(end 430.200054 -136.526778)
		(width 0.12954)
		(layer "F.Cu")
		(net "SVID_CLK_PVCCINFAON_CPU0_R")
	)
	(segment
		(start 428.105062 -137.014458)
		(end 428.829724 -137.014458)
		(width 0.12954)
		(layer "F.Cu")
		(net "SVID_CLK_PVCCINFAON_CPU0_R")
	)
	(segment
		(start 428.945294 -137.130028)
		(end 429.134524 -137.130028)
		(width 0.12954)
		(layer "F.Cu")
		(net "SVID_CLK_PVCCINFAON_CPU0_R")
	)
	(segment
		(start 429.246284 -137.130028)
		(end 429.849534 -136.526778)
		(width 0.12954)
		(layer "F.Cu")
		(net "SVID_CLK_PVCCINFAON_CPU0_R")
	)
	(segment
		(start 428.829724 -137.014458)
		(end 428.945294 -137.130028)
		(width 0.12954)
		(layer "F.Cu")
		(net "SVID_CLK_PVCCINFAON_CPU0_R")
	)
	(via
		(at 429.134524 -137.130028)
		(size 0.508)
		(drill 0.254)
		(layers "F.Cu" "B.Cu")
		(net "SVID_CLK_PVCCINFAON_CPU0_R")
	)
	(segment
		(start 23.133812 -164.994336)
		(end 23.69058 -164.437568)
		(width 0.12954)
		(layer "F.Cu")
		(net "SVID_CLK_PVCCD_HV_CPU1_R")
	)
	(segment
		(start 24.506936 -164.437568)
		(end 24.717248 -164.227256)
		(width 0.12954)
		(layer "F.Cu")
		(net "SVID_CLK_PVCCD_HV_CPU1_R")
	)
	(segment
		(start 24.717248 -164.227256)
		(end 25.26284 -164.227256)
		(width 0.12954)
		(layer "F.Cu")
		(net "SVID_CLK_PVCCD_HV_CPU1_R")
	)
	(segment
		(start 23.69058 -164.437568)
		(end 24.506936 -164.437568)
		(width 0.12954)
		(layer "F.Cu")
		(net "SVID_CLK_PVCCD_HV_CPU1_R")
	)
	(segment
		(start 22.53361 -165.594538)
		(end 23.133812 -164.994336)
		(width 0.12954)
		(layer "F.Cu")
		(net "SVID_CLK_PVCCD_HV_CPU1_R")
	)
	(segment
		(start 22.53361 -165.751256)
		(end 22.53361 -165.594538)
		(width 0.12954)
		(layer "F.Cu")
		(net "SVID_CLK_PVCCD_HV_CPU1_R")
	)
	(via
		(at 23.133812 -164.994336)
		(size 0.508)
		(drill 0.254)
		(layers "F.Cu" "B.Cu")
		(net "SVID_CLK_PVCCD_HV_CPU1_R")
	)
	(segment
		(start 435.58968 -123.87199)
		(end 435.903624 -123.87199)
		(width 0.12954)
		(layer "F.Cu")
		(net "SVID_CLK_PVCCD_HV_CPU0_R")
	)
	(segment
		(start 434.901086 -123.588526)
		(end 435.306216 -123.588526)
		(width 0.12954)
		(layer "F.Cu")
		(net "SVID_CLK_PVCCD_HV_CPU0_R")
	)
	(segment
		(start 436.110888 -123.664726)
		(end 435.903624 -123.87199)
		(width 0.12954)
		(layer "F.Cu")
		(net "SVID_CLK_PVCCD_HV_CPU0_R")
	)
	(segment
		(start 435.306216 -123.588526)
		(end 435.58968 -123.87199)
		(width 0.12954)
		(layer "F.Cu")
		(net "SVID_CLK_PVCCD_HV_CPU0_R")
	)
	(segment
		(start 436.842916 -123.664726)
		(end 436.110888 -123.664726)
		(width 0.12954)
		(layer "F.Cu")
		(net "SVID_CLK_PVCCD_HV_CPU0_R")
	)
	(via
		(at 435.903624 -123.87199)
		(size 0.508)
		(drill 0.254)
		(layers "F.Cu" "B.Cu")
		(net "SVID_CLK_PVCCD_HV_CPU0_R")
	)
	(segment
		(start 21.12391 -165.751256)
		(end 20.51431 -165.751256)
		(width 0.12954)
		(layer "F.Cu")
		(net "SVID_CLK1_CPU1_R")
	)
	(segment
		(start 21.73351 -165.751256)
		(end 21.12391 -165.751256)
		(width 0.12954)
		(layer "F.Cu")
		(net "SVID_CLK1_CPU1_R")
	)
	(via
		(at 21.12391 -165.751256)
		(size 0.508)
		(drill 0.254)
		(layers "F.Cu" "B.Cu")
		(net "SVID_CLK1_CPU1_R")
	)
	(via
		(at 71.385684 -187.436252)
		(size 0.508)
		(drill 0.254)
		(layers "F.Cu" "B.Cu")
		(net "SVID_CLK1_CPU1_R")
	)
	(segment
		(start 71.385684 -188.058806)
		(end 71.385684 -187.436252)
		(width 0.12954)
		(layer "B.Cu")
		(net "SVID_CLK1_CPU1_R")
	)
	(segment
		(start 71.385684 -187.831984)
		(end 71.385684 -187.436252)
		(width 0.127)
		(layer "In13.Cu")
		(net "SVID_CLK1_CPU1_R")
	)
	(segment
		(start 17.272 -184.445148)
		(end 63.9572 -184.445148)
		(width 0.127)
		(layer "In13.Cu")
		(net "SVID_CLK1_CPU1_R")
	)
	(segment
		(start 70.71868 -188.498988)
		(end 71.385684 -187.831984)
		(width 0.127)
		(layer "In13.Cu")
		(net "SVID_CLK1_CPU1_R")
	)
	(segment
		(start 63.9572 -184.445148)
		(end 68.01104 -188.498988)
		(width 0.127)
		(layer "In13.Cu")
		(net "SVID_CLK1_CPU1_R")
	)
	(segment
		(start 21.12391 -165.751256)
		(end 18.636996 -165.751256)
		(width 0.127)
		(layer "In13.Cu")
		(net "SVID_CLK1_CPU1_R")
	)
	(segment
		(start 18.636996 -165.751256)
		(end 14.9352 -169.453052)
		(width 0.127)
		(layer "In13.Cu")
		(net "SVID_CLK1_CPU1_R")
	)
	(segment
		(start 68.01104 -188.498988)
		(end 70.71868 -188.498988)
		(width 0.127)
		(layer "In13.Cu")
		(net "SVID_CLK1_CPU1_R")
	)
	(segment
		(start 14.9352 -182.108348)
		(end 17.272 -184.445148)
		(width 0.127)
		(layer "In13.Cu")
		(net "SVID_CLK1_CPU1_R")
	)
	(segment
		(start 14.9352 -169.453052)
		(end 14.9352 -182.108348)
		(width 0.127)
		(layer "In13.Cu")
		(net "SVID_CLK1_CPU1_R")
	)
	(segment
		(start 106.001312 -234.69219)
		(end 106.001312 -234.156504)
		(width 0.12954)
		(layer "F.Cu")
		(net "SVID_CLK1_CPU1")
	)
	(segment
		(start 106.001312 -234.156504)
		(end 106.001566 -234.15625)
		(width 0.12954)
		(layer "F.Cu")
		(net "SVID_CLK1_CPU1")
	)
	(via
		(at 106.001566 -234.15625)
		(size 0.4572)
		(drill 0.2032)
		(layers "F.Cu" "B.Cu")
		(net "SVID_CLK1_CPU1")
	)
	(via
		(at 70.921118 -229.28199)
		(size 0.6604)
		(drill 0.3302)
		(layers "F.Cu" "B.Cu")
		(net "SVID_CLK1_CPU1")
	)
	(segment
		(start 66.7258 -218.440254)
		(end 66.110612 -218.440254)
		(width 0.12954)
		(layer "B.Cu")
		(net "SVID_CLK1_CPU1")
	)
	(segment
		(start 66.431922 -208.717642)
		(end 66.431922 -208.339182)
		(width 0.12954)
		(layer "B.Cu")
		(net "SVID_CLK1_CPU1")
	)
	(segment
		(start 65.981072 -218.310714)
		(end 65.981072 -217.932254)
		(width 0.12954)
		(layer "B.Cu")
		(net "SVID_CLK1_CPU1")
	)
	(segment
		(start 71.451216 -192.675256)
		(end 71.891398 -191.612774)
		(width 0.12954)
		(layer "B.Cu")
		(net "SVID_CLK1_CPU1")
	)
	(segment
		(start 77.80782 -235.752386)
		(end 72.716644 -230.66121)
		(width 0.12954)
		(layer "B.Cu")
		(net "SVID_CLK1_CPU1")
	)
	(segment
		(start 65.94348 -208.209642)
		(end 65.81394 -208.080102)
		(width 0.12954)
		(layer "B.Cu")
		(net "SVID_CLK1_CPU1")
	)
	(segment
		(start 66.302382 -208.209642)
		(end 65.94348 -208.209642)
		(width 0.12954)
		(layer "B.Cu")
		(net "SVID_CLK1_CPU1")
	)
	(segment
		(start 84.907628 -235.752386)
		(end 77.80782 -235.752386)
		(width 0.12954)
		(layer "B.Cu")
		(net "SVID_CLK1_CPU1")
	)
	(segment
		(start 71.891398 -191.612774)
		(end 71.891398 -189.36462)
		(width 0.12954)
		(layer "B.Cu")
		(net "SVID_CLK1_CPU1")
	)
	(segment
		(start 67.98056 -204.870558)
		(end 67.98056 -203.431902)
		(width 0.12954)
		(layer "B.Cu")
		(net "SVID_CLK1_CPU1")
	)
	(segment
		(start 67.608958 -222.424498)
		(end 66.85534 -221.67088)
		(width 0.12954)
		(layer "B.Cu")
		(net "SVID_CLK1_CPU1")
	)
	(segment
		(start 86.33587 -234.570524)
		(end 86.08949 -234.570524)
		(width 0.0889)
		(layer "B.Cu")
		(net "SVID_CLK1_CPU1")
	)
	(segment
		(start 70.338188 -201.074274)
		(end 70.338188 -199.56272)
		(width 0.12954)
		(layer "B.Cu")
		(net "SVID_CLK1_CPU1")
	)
	(segment
		(start 89.287096 -234.471972)
		(end 89.272364 -234.480608)
		(width 0.0889)
		(layer "B.Cu")
		(net "SVID_CLK1_CPU1")
	)
	(segment
		(start 65.81394 -208.080102)
		(end 65.81394 -207.037178)
		(width 0.12954)
		(layer "B.Cu")
		(net "SVID_CLK1_CPU1")
	)
	(segment
		(start 99.624896 -234.471972)
		(end 99.610164 -234.480608)
		(width 0.0889)
		(layer "B.Cu")
		(net "SVID_CLK1_CPU1")
	)
	(segment
		(start 92.106496 -234.471972)
		(end 92.091764 -234.480608)
		(width 0.0889)
		(layer "B.Cu")
		(net "SVID_CLK1_CPU1")
	)
	(segment
		(start 70.921118 -229.28199)
		(end 67.608958 -225.96983)
		(width 0.12954)
		(layer "B.Cu")
		(net "SVID_CLK1_CPU1")
	)
	(segment
		(start 66.85534 -218.569794)
		(end 66.7258 -218.440254)
		(width 0.12954)
		(layer "B.Cu")
		(net "SVID_CLK1_CPU1")
	)
	(segment
		(start 66.7258 -217.802714)
		(end 66.85534 -217.673174)
		(width 0.12954)
		(layer "B.Cu")
		(net "SVID_CLK1_CPU1")
	)
	(segment
		(start 88.332564 -234.480608)
		(end 88.332818 -234.480862)
		(width 0.0889)
		(layer "B.Cu")
		(net "SVID_CLK1_CPU1")
	)
	(segment
		(start 87.958168 -234.480608)
		(end 87.943436 -234.471972)
		(width 0.0889)
		(layer "B.Cu")
		(net "SVID_CLK1_CPU1")
	)
	(segment
		(start 66.85534 -211.255864)
		(end 65.81394 -210.214464)
		(width 0.12954)
		(layer "B.Cu")
		(net "SVID_CLK1_CPU1")
	)
	(segment
		(start 88.347296 -234.471972)
		(end 88.332564 -234.480608)
		(width 0.0889)
		(layer "B.Cu")
		(net "SVID_CLK1_CPU1")
	)
	(segment
		(start 71.891398 -189.36462)
		(end 71.385684 -188.858906)
		(width 0.12954)
		(layer "B.Cu")
		(net "SVID_CLK1_CPU1")
	)
	(segment
		(start 88.023446 -234.531154)
		(end 87.994998 -234.502706)
		(width 0.0889)
		(layer "B.Cu")
		(net "SVID_CLK1_CPU1")
	)
	(segment
		(start 67.98056 -203.431902)
		(end 70.338188 -201.074274)
		(width 0.12954)
		(layer "B.Cu")
		(net "SVID_CLK1_CPU1")
	)
	(segment
		(start 66.85534 -217.673174)
		(end 66.85534 -211.255864)
		(width 0.12954)
		(layer "B.Cu")
		(net "SVID_CLK1_CPU1")
	)
	(segment
		(start 91.166696 -234.471972)
		(end 91.151964 -234.480608)
		(width 0.0889)
		(layer "B.Cu")
		(net "SVID_CLK1_CPU1")
	)
	(segment
		(start 104.874568 -234.480608)
		(end 104.859836 -234.471972)
		(width 0.0889)
		(layer "B.Cu")
		(net "SVID_CLK1_CPU1")
	)
	(segment
		(start 66.110612 -217.802714)
		(end 66.7258 -217.802714)
		(width 0.12954)
		(layer "B.Cu")
		(net "SVID_CLK1_CPU1")
	)
	(segment
		(start 66.431922 -208.339182)
		(end 66.302382 -208.209642)
		(width 0.12954)
		(layer "B.Cu")
		(net "SVID_CLK1_CPU1")
	)
	(segment
		(start 65.81394 -210.214464)
		(end 65.81394 -208.976722)
		(width 0.12954)
		(layer "B.Cu")
		(net "SVID_CLK1_CPU1")
	)
	(segment
		(start 65.94348 -208.847182)
		(end 66.302382 -208.847182)
		(width 0.12954)
		(layer "B.Cu")
		(net "SVID_CLK1_CPU1")
	)
	(segment
		(start 65.81394 -208.976722)
		(end 65.94348 -208.847182)
		(width 0.12954)
		(layer "B.Cu")
		(net "SVID_CLK1_CPU1")
	)
	(segment
		(start 65.981072 -217.932254)
		(end 66.110612 -217.802714)
		(width 0.12954)
		(layer "B.Cu")
		(net "SVID_CLK1_CPU1")
	)
	(segment
		(start 66.302382 -208.847182)
		(end 66.431922 -208.717642)
		(width 0.12954)
		(layer "B.Cu")
		(net "SVID_CLK1_CPU1")
	)
	(segment
		(start 97.745296 -234.471972)
		(end 97.730564 -234.480608)
		(width 0.0889)
		(layer "B.Cu")
		(net "SVID_CLK1_CPU1")
	)
	(segment
		(start 86.08949 -234.570524)
		(end 85.682074 -234.97794)
		(width 0.0889)
		(layer "B.Cu")
		(net "SVID_CLK1_CPU1")
	)
	(segment
		(start 94.921324 -234.474512)
		(end 94.91091 -234.480608)
		(width 0.0889)
		(layer "B.Cu")
		(net "SVID_CLK1_CPU1")
	)
	(segment
		(start 100.560378 -234.474512)
		(end 100.549964 -234.480608)
		(width 0.0889)
		(layer "B.Cu")
		(net "SVID_CLK1_CPU1")
	)
	(segment
		(start 65.81394 -207.037178)
		(end 67.98056 -204.870558)
		(width 0.12954)
		(layer "B.Cu")
		(net "SVID_CLK1_CPU1")
	)
	(segment
		(start 95.865696 -234.471972)
		(end 95.850964 -234.480608)
		(width 0.0889)
		(layer "B.Cu")
		(net "SVID_CLK1_CPU1")
	)
	(segment
		(start 88.145366 -234.531154)
		(end 88.023446 -234.531154)
		(width 0.0889)
		(layer "B.Cu")
		(net "SVID_CLK1_CPU1")
	)
	(segment
		(start 102.994968 -234.480608)
		(end 102.980236 -234.471972)
		(width 0.0889)
		(layer "B.Cu")
		(net "SVID_CLK1_CPU1")
	)
	(segment
		(start 93.046296 -234.471972)
		(end 93.031564 -234.480608)
		(width 0.0889)
		(layer "B.Cu")
		(net "SVID_CLK1_CPU1")
	)
	(segment
		(start 98.685096 -234.471972)
		(end 98.678238 -234.476036)
		(width 0.0889)
		(layer "B.Cu")
		(net "SVID_CLK1_CPU1")
	)
	(segment
		(start 87.018368 -234.480608)
		(end 87.007954 -234.474512)
		(width 0.0889)
		(layer "B.Cu")
		(net "SVID_CLK1_CPU1")
	)
	(segment
		(start 66.85534 -221.67088)
		(end 66.85534 -218.569794)
		(width 0.12954)
		(layer "B.Cu")
		(net "SVID_CLK1_CPU1")
	)
	(segment
		(start 72.300338 -230.66121)
		(end 70.921118 -229.28199)
		(width 0.12954)
		(layer "B.Cu")
		(net "SVID_CLK1_CPU1")
	)
	(segment
		(start 93.981778 -234.474512)
		(end 93.971364 -234.480608)
		(width 0.0889)
		(layer "B.Cu")
		(net "SVID_CLK1_CPU1")
	)
	(segment
		(start 72.716644 -230.66121)
		(end 72.300338 -230.66121)
		(width 0.12954)
		(layer "B.Cu")
		(net "SVID_CLK1_CPU1")
	)
	(segment
		(start 70.338188 -199.56272)
		(end 71.451216 -198.449692)
		(width 0.12954)
		(layer "B.Cu")
		(net "SVID_CLK1_CPU1")
	)
	(segment
		(start 71.451216 -198.449692)
		(end 71.451216 -192.675256)
		(width 0.12954)
		(layer "B.Cu")
		(net "SVID_CLK1_CPU1")
	)
	(segment
		(start 85.682074 -234.97794)
		(end 84.907628 -235.752386)
		(width 0.12954)
		(layer "B.Cu")
		(net "SVID_CLK1_CPU1")
	)
	(segment
		(start 66.110612 -218.440254)
		(end 65.981072 -218.310714)
		(width 0.12954)
		(layer "B.Cu")
		(net "SVID_CLK1_CPU1")
	)
	(segment
		(start 87.994998 -234.502706)
		(end 87.958168 -234.480608)
		(width 0.0889)
		(layer "B.Cu")
		(net "SVID_CLK1_CPU1")
	)
	(segment
		(start 106.001566 -234.15625)
		(end 105.592372 -234.407964)
		(width 0.0889)
		(layer "B.Cu")
		(net "SVID_CLK1_CPU1")
	)
	(segment
		(start 101.499924 -234.474512)
		(end 101.48951 -234.480608)
		(width 0.0889)
		(layer "B.Cu")
		(net "SVID_CLK1_CPU1")
	)
	(segment
		(start 103.934768 -234.480608)
		(end 103.920036 -234.471972)
		(width 0.0889)
		(layer "B.Cu")
		(net "SVID_CLK1_CPU1")
	)
	(segment
		(start 67.608958 -225.96983)
		(end 67.608958 -222.424498)
		(width 0.12954)
		(layer "B.Cu")
		(net "SVID_CLK1_CPU1")
	)
	(segment
		(start 98.678238 -234.476036)
		(end 98.670364 -234.480608)
		(width 0.0889)
		(layer "B.Cu")
		(net "SVID_CLK1_CPU1")
	)
	(arc
		(start 94.536514 -234.480608)
		(mid 94.259955 -234.404865)
		(end 93.981778 -234.474512)
		(width 0.0889)
		(layer "B.Cu")
		(net "SVID_CLK1_CPU1")
	)
	(arc
		(start 102.429564 -234.480608)
		(mid 102.242366 -234.530751)
		(end 102.055168 -234.480608)
		(width 0.0889)
		(layer "B.Cu")
		(net "SVID_CLK1_CPU1")
	)
	(arc
		(start 104.309164 -234.480608)
		(mid 104.121966 -234.530751)
		(end 103.934768 -234.480608)
		(width 0.0889)
		(layer "B.Cu")
		(net "SVID_CLK1_CPU1")
	)
	(arc
		(start 89.837768 -234.480608)
		(mid 89.563569 -234.404773)
		(end 89.287096 -234.471972)
		(width 0.0889)
		(layer "B.Cu")
		(net "SVID_CLK1_CPU1")
	)
	(arc
		(start 95.850964 -234.480608)
		(mid 95.663766 -234.530751)
		(end 95.476568 -234.480608)
		(width 0.0889)
		(layer "B.Cu")
		(net "SVID_CLK1_CPU1")
	)
	(arc
		(start 103.920036 -234.471972)
		(mid 103.643595 -234.404806)
		(end 103.369364 -234.480608)
		(width 0.0889)
		(layer "B.Cu")
		(net "SVID_CLK1_CPU1")
	)
	(arc
		(start 105.248964 -234.480608)
		(mid 105.061766 -234.530751)
		(end 104.874568 -234.480608)
		(width 0.0889)
		(layer "B.Cu")
		(net "SVID_CLK1_CPU1")
	)
	(arc
		(start 87.392764 -234.480608)
		(mid 87.205566 -234.530751)
		(end 87.018368 -234.480608)
		(width 0.0889)
		(layer "B.Cu")
		(net "SVID_CLK1_CPU1")
	)
	(arc
		(start 90.777568 -234.480608)
		(mid 90.494866 -234.404832)
		(end 90.212164 -234.480608)
		(width 0.0889)
		(layer "B.Cu")
		(net "SVID_CLK1_CPU1")
	)
	(arc
		(start 92.657168 -234.480608)
		(mid 92.382969 -234.404773)
		(end 92.106496 -234.471972)
		(width 0.0889)
		(layer "B.Cu")
		(net "SVID_CLK1_CPU1")
	)
	(arc
		(start 102.980236 -234.471972)
		(mid 102.703795 -234.404806)
		(end 102.429564 -234.480608)
		(width 0.0889)
		(layer "B.Cu")
		(net "SVID_CLK1_CPU1")
	)
	(arc
		(start 91.717368 -234.480608)
		(mid 91.443169 -234.404773)
		(end 91.166696 -234.471972)
		(width 0.0889)
		(layer "B.Cu")
		(net "SVID_CLK1_CPU1")
	)
	(arc
		(start 95.476568 -234.480608)
		(mid 95.199755 -234.404738)
		(end 94.921324 -234.474512)
		(width 0.0889)
		(layer "B.Cu")
		(net "SVID_CLK1_CPU1")
	)
	(arc
		(start 98.295968 -234.480608)
		(mid 98.021769 -234.404773)
		(end 97.745296 -234.471972)
		(width 0.0889)
		(layer "B.Cu")
		(net "SVID_CLK1_CPU1")
	)
	(arc
		(start 93.596968 -234.480608)
		(mid 93.322769 -234.404773)
		(end 93.046296 -234.471972)
		(width 0.0889)
		(layer "B.Cu")
		(net "SVID_CLK1_CPU1")
	)
	(arc
		(start 87.007954 -234.474512)
		(mid 86.729776 -234.40482)
		(end 86.453218 -234.480608)
		(width 0.0889)
		(layer "B.Cu")
		(net "SVID_CLK1_CPU1")
	)
	(arc
		(start 94.91091 -234.480608)
		(mid 94.723712 -234.530751)
		(end 94.536514 -234.480608)
		(width 0.0889)
		(layer "B.Cu")
		(net "SVID_CLK1_CPU1")
	)
	(arc
		(start 101.48951 -234.480608)
		(mid 101.302312 -234.530751)
		(end 101.115114 -234.480608)
		(width 0.0889)
		(layer "B.Cu")
		(net "SVID_CLK1_CPU1")
	)
	(arc
		(start 103.369364 -234.480608)
		(mid 103.182166 -234.530751)
		(end 102.994968 -234.480608)
		(width 0.0889)
		(layer "B.Cu")
		(net "SVID_CLK1_CPU1")
	)
	(arc
		(start 105.592372 -234.407964)
		(mid 105.414887 -234.416965)
		(end 105.248964 -234.480608)
		(width 0.0889)
		(layer "B.Cu")
		(net "SVID_CLK1_CPU1")
	)
	(arc
		(start 102.055168 -234.480608)
		(mid 101.778355 -234.404738)
		(end 101.499924 -234.474512)
		(width 0.0889)
		(layer "B.Cu")
		(net "SVID_CLK1_CPU1")
	)
	(arc
		(start 92.091764 -234.480608)
		(mid 91.904566 -234.530751)
		(end 91.717368 -234.480608)
		(width 0.0889)
		(layer "B.Cu")
		(net "SVID_CLK1_CPU1")
	)
	(arc
		(start 91.151964 -234.480608)
		(mid 90.964766 -234.530751)
		(end 90.777568 -234.480608)
		(width 0.0889)
		(layer "B.Cu")
		(net "SVID_CLK1_CPU1")
	)
	(arc
		(start 100.175568 -234.480608)
		(mid 99.901369 -234.404773)
		(end 99.624896 -234.471972)
		(width 0.0889)
		(layer "B.Cu")
		(net "SVID_CLK1_CPU1")
	)
	(arc
		(start 101.115114 -234.480608)
		(mid 100.838555 -234.404865)
		(end 100.560378 -234.474512)
		(width 0.0889)
		(layer "B.Cu")
		(net "SVID_CLK1_CPU1")
	)
	(arc
		(start 86.453218 -234.480608)
		(mid 86.391591 -234.521712)
		(end 86.33587 -234.570524)
		(width 0.0889)
		(layer "B.Cu")
		(net "SVID_CLK1_CPU1")
	)
	(arc
		(start 88.897968 -234.480608)
		(mid 88.623769 -234.404773)
		(end 88.347296 -234.471972)
		(width 0.0889)
		(layer "B.Cu")
		(net "SVID_CLK1_CPU1")
	)
	(arc
		(start 99.235768 -234.480608)
		(mid 98.961569 -234.404773)
		(end 98.685096 -234.471972)
		(width 0.0889)
		(layer "B.Cu")
		(net "SVID_CLK1_CPU1")
	)
	(arc
		(start 100.549964 -234.480608)
		(mid 100.362766 -234.530751)
		(end 100.175568 -234.480608)
		(width 0.0889)
		(layer "B.Cu")
		(net "SVID_CLK1_CPU1")
	)
	(arc
		(start 93.971364 -234.480608)
		(mid 93.784166 -234.530751)
		(end 93.596968 -234.480608)
		(width 0.0889)
		(layer "B.Cu")
		(net "SVID_CLK1_CPU1")
	)
	(arc
		(start 98.670364 -234.480608)
		(mid 98.483166 -234.530751)
		(end 98.295968 -234.480608)
		(width 0.0889)
		(layer "B.Cu")
		(net "SVID_CLK1_CPU1")
	)
	(arc
		(start 104.859836 -234.471972)
		(mid 104.583395 -234.404806)
		(end 104.309164 -234.480608)
		(width 0.0889)
		(layer "B.Cu")
		(net "SVID_CLK1_CPU1")
	)
	(arc
		(start 88.332818 -234.480862)
		(mid 88.242408 -234.518372)
		(end 88.145366 -234.531154)
		(width 0.0889)
		(layer "B.Cu")
		(net "SVID_CLK1_CPU1")
	)
	(arc
		(start 99.610164 -234.480608)
		(mid 99.422966 -234.530751)
		(end 99.235768 -234.480608)
		(width 0.0889)
		(layer "B.Cu")
		(net "SVID_CLK1_CPU1")
	)
	(arc
		(start 90.212164 -234.480608)
		(mid 90.024966 -234.530751)
		(end 89.837768 -234.480608)
		(width 0.0889)
		(layer "B.Cu")
		(net "SVID_CLK1_CPU1")
	)
	(arc
		(start 97.356168 -234.480608)
		(mid 97.073466 -234.404832)
		(end 96.790764 -234.480608)
		(width 0.0889)
		(layer "B.Cu")
		(net "SVID_CLK1_CPU1")
	)
	(arc
		(start 93.031564 -234.480608)
		(mid 92.844366 -234.530751)
		(end 92.657168 -234.480608)
		(width 0.0889)
		(layer "B.Cu")
		(net "SVID_CLK1_CPU1")
	)
	(arc
		(start 97.730564 -234.480608)
		(mid 97.543366 -234.530751)
		(end 97.356168 -234.480608)
		(width 0.0889)
		(layer "B.Cu")
		(net "SVID_CLK1_CPU1")
	)
	(arc
		(start 96.416368 -234.480608)
		(mid 96.142169 -234.404773)
		(end 95.865696 -234.471972)
		(width 0.0889)
		(layer "B.Cu")
		(net "SVID_CLK1_CPU1")
	)
	(arc
		(start 87.943436 -234.471972)
		(mid 87.666995 -234.404806)
		(end 87.392764 -234.480608)
		(width 0.0889)
		(layer "B.Cu")
		(net "SVID_CLK1_CPU1")
	)
	(arc
		(start 96.790764 -234.480608)
		(mid 96.603566 -234.530751)
		(end 96.416368 -234.480608)
		(width 0.0889)
		(layer "B.Cu")
		(net "SVID_CLK1_CPU1")
	)
	(arc
		(start 89.272364 -234.480608)
		(mid 89.085166 -234.530751)
		(end 88.897968 -234.480608)
		(width 0.0889)
		(layer "B.Cu")
		(net "SVID_CLK1_CPU1")
	)
	(segment
		(start 440.41314 -116.434362)
		(end 439.70702 -116.434362)
		(width 0.12954)
		(layer "F.Cu")
		(net "SVID_CLK1_CPU0_R")
	)
	(segment
		(start 439.70702 -118.987062)
		(end 440.41314 -118.987062)
		(width 0.12954)
		(layer "F.Cu")
		(net "SVID_CLK1_CPU0_R")
	)
	(segment
		(start 439.702194 -122.824748)
		(end 438.862216 -123.664726)
		(width 0.12954)
		(layer "F.Cu")
		(net "SVID_CLK1_CPU0_R")
	)
	(segment
		(start 440.54268 -120.137682)
		(end 440.54268 -120.820688)
		(width 0.12954)
		(layer "F.Cu")
		(net "SVID_CLK1_CPU0_R")
	)
	(segment
		(start 318.4017 -178.501548)
		(end 333.86014 -163.043108)
		(width 0.12954)
		(layer "F.Cu")
		(net "SVID_CLK1_CPU0_R")
	)
	(segment
		(start 439.57748 -118.857522)
		(end 439.70702 -118.987062)
		(width 0.12954)
		(layer "F.Cu")
		(net "SVID_CLK1_CPU0_R")
	)
	(segment
		(start 440.41314 -119.497602)
		(end 439.70702 -119.497602)
		(width 0.12954)
		(layer "F.Cu")
		(net "SVID_CLK1_CPU0_R")
	)
	(segment
		(start 308.45252 -191.991488)
		(end 308.45252 -179.9844)
		(width 0.12954)
		(layer "F.Cu")
		(net "SVID_CLK1_CPU0_R")
	)
	(segment
		(start 339.204808 -131.770628)
		(end 410.008832 -131.770628)
		(width 0.12954)
		(layer "F.Cu")
		(net "SVID_CLK1_CPU0_R")
	)
	(segment
		(start 439.52414 -114.722148)
		(end 440.54268 -115.740688)
		(width 0.12954)
		(layer "F.Cu")
		(net "SVID_CLK1_CPU0_R")
	)
	(segment
		(start 439.57748 -116.815362)
		(end 439.70702 -116.944902)
		(width 0.12954)
		(layer "F.Cu")
		(net "SVID_CLK1_CPU0_R")
	)
	(segment
		(start 333.86014 -163.043108)
		(end 333.86014 -137.115296)
		(width 0.12954)
		(layer "F.Cu")
		(net "SVID_CLK1_CPU0_R")
	)
	(segment
		(start 437.643016 -123.664726)
		(end 438.862216 -123.664726)
		(width 0.12954)
		(layer "F.Cu")
		(net "SVID_CLK1_CPU0_R")
	)
	(segment
		(start 306.433728 -192.78473)
		(end 307.659278 -192.78473)
		(width 0.12954)
		(layer "F.Cu")
		(net "SVID_CLK1_CPU0_R")
	)
	(segment
		(start 440.54268 -119.368062)
		(end 440.41314 -119.497602)
		(width 0.12954)
		(layer "F.Cu")
		(net "SVID_CLK1_CPU0_R")
	)
	(segment
		(start 307.659278 -192.78473)
		(end 308.45252 -191.991488)
		(width 0.12954)
		(layer "F.Cu")
		(net "SVID_CLK1_CPU0_R")
	)
	(segment
		(start 440.41314 -117.455442)
		(end 439.70702 -117.455442)
		(width 0.12954)
		(layer "F.Cu")
		(net "SVID_CLK1_CPU0_R")
	)
	(segment
		(start 440.41314 -116.944902)
		(end 440.54268 -117.074442)
		(width 0.12954)
		(layer "F.Cu")
		(net "SVID_CLK1_CPU0_R")
	)
	(segment
		(start 439.70702 -120.008142)
		(end 440.41314 -120.008142)
		(width 0.12954)
		(layer "F.Cu")
		(net "SVID_CLK1_CPU0_R")
	)
	(segment
		(start 439.57748 -118.606062)
		(end 439.57748 -118.857522)
		(width 0.12954)
		(layer "F.Cu")
		(net "SVID_CLK1_CPU0_R")
	)
	(segment
		(start 440.54268 -117.074442)
		(end 440.54268 -117.325902)
		(width 0.12954)
		(layer "F.Cu")
		(net "SVID_CLK1_CPU0_R")
	)
	(segment
		(start 410.008832 -131.770628)
		(end 427.057312 -114.722148)
		(width 0.12954)
		(layer "F.Cu")
		(net "SVID_CLK1_CPU0_R")
	)
	(segment
		(start 333.86014 -137.115296)
		(end 339.204808 -131.770628)
		(width 0.12954)
		(layer "F.Cu")
		(net "SVID_CLK1_CPU0_R")
	)
	(segment
		(start 439.57748 -116.563902)
		(end 439.57748 -116.815362)
		(width 0.12954)
		(layer "F.Cu")
		(net "SVID_CLK1_CPU0_R")
	)
	(segment
		(start 440.41314 -118.476522)
		(end 439.70702 -118.476522)
		(width 0.12954)
		(layer "F.Cu")
		(net "SVID_CLK1_CPU0_R")
	)
	(segment
		(start 440.54268 -120.820688)
		(end 440.54268 -122.570748)
		(width 0.12954)
		(layer "F.Cu")
		(net "SVID_CLK1_CPU0_R")
	)
	(segment
		(start 440.41314 -118.987062)
		(end 440.54268 -119.116602)
		(width 0.12954)
		(layer "F.Cu")
		(net "SVID_CLK1_CPU0_R")
	)
	(segment
		(start 440.54268 -118.346982)
		(end 440.41314 -118.476522)
		(width 0.12954)
		(layer "F.Cu")
		(net "SVID_CLK1_CPU0_R")
	)
	(segment
		(start 440.54268 -116.304822)
		(end 440.41314 -116.434362)
		(width 0.12954)
		(layer "F.Cu")
		(net "SVID_CLK1_CPU0_R")
	)
	(segment
		(start 440.54268 -117.325902)
		(end 440.41314 -117.455442)
		(width 0.12954)
		(layer "F.Cu")
		(net "SVID_CLK1_CPU0_R")
	)
	(segment
		(start 440.41314 -120.008142)
		(end 440.54268 -120.137682)
		(width 0.12954)
		(layer "F.Cu")
		(net "SVID_CLK1_CPU0_R")
	)
	(segment
		(start 440.54268 -122.570748)
		(end 440.28868 -122.824748)
		(width 0.12954)
		(layer "F.Cu")
		(net "SVID_CLK1_CPU0_R")
	)
	(segment
		(start 440.54268 -118.095522)
		(end 440.54268 -118.346982)
		(width 0.12954)
		(layer "F.Cu")
		(net "SVID_CLK1_CPU0_R")
	)
	(segment
		(start 439.57748 -117.836442)
		(end 439.70702 -117.965982)
		(width 0.12954)
		(layer "F.Cu")
		(net "SVID_CLK1_CPU0_R")
	)
	(segment
		(start 309.935372 -178.501548)
		(end 318.4017 -178.501548)
		(width 0.12954)
		(layer "F.Cu")
		(net "SVID_CLK1_CPU0_R")
	)
	(segment
		(start 439.70702 -116.434362)
		(end 439.57748 -116.563902)
		(width 0.12954)
		(layer "F.Cu")
		(net "SVID_CLK1_CPU0_R")
	)
	(segment
		(start 439.57748 -119.878602)
		(end 439.70702 -120.008142)
		(width 0.12954)
		(layer "F.Cu")
		(net "SVID_CLK1_CPU0_R")
	)
	(segment
		(start 439.57748 -119.627142)
		(end 439.57748 -119.878602)
		(width 0.12954)
		(layer "F.Cu")
		(net "SVID_CLK1_CPU0_R")
	)
	(segment
		(start 439.70702 -118.476522)
		(end 439.57748 -118.606062)
		(width 0.12954)
		(layer "F.Cu")
		(net "SVID_CLK1_CPU0_R")
	)
	(segment
		(start 439.57748 -117.584982)
		(end 439.57748 -117.836442)
		(width 0.12954)
		(layer "F.Cu")
		(net "SVID_CLK1_CPU0_R")
	)
	(segment
		(start 440.54268 -119.116602)
		(end 440.54268 -119.368062)
		(width 0.12954)
		(layer "F.Cu")
		(net "SVID_CLK1_CPU0_R")
	)
	(segment
		(start 440.41314 -117.965982)
		(end 440.54268 -118.095522)
		(width 0.12954)
		(layer "F.Cu")
		(net "SVID_CLK1_CPU0_R")
	)
	(segment
		(start 439.70702 -119.497602)
		(end 439.57748 -119.627142)
		(width 0.12954)
		(layer "F.Cu")
		(net "SVID_CLK1_CPU0_R")
	)
	(segment
		(start 427.057312 -114.722148)
		(end 439.52414 -114.722148)
		(width 0.12954)
		(layer "F.Cu")
		(net "SVID_CLK1_CPU0_R")
	)
	(segment
		(start 439.70702 -116.944902)
		(end 440.41314 -116.944902)
		(width 0.12954)
		(layer "F.Cu")
		(net "SVID_CLK1_CPU0_R")
	)
	(segment
		(start 439.70702 -117.455442)
		(end 439.57748 -117.584982)
		(width 0.12954)
		(layer "F.Cu")
		(net "SVID_CLK1_CPU0_R")
	)
	(segment
		(start 308.45252 -179.9844)
		(end 309.935372 -178.501548)
		(width 0.12954)
		(layer "F.Cu")
		(net "SVID_CLK1_CPU0_R")
	)
	(segment
		(start 439.70702 -117.965982)
		(end 440.41314 -117.965982)
		(width 0.12954)
		(layer "F.Cu")
		(net "SVID_CLK1_CPU0_R")
	)
	(segment
		(start 440.28868 -122.824748)
		(end 439.702194 -122.824748)
		(width 0.12954)
		(layer "F.Cu")
		(net "SVID_CLK1_CPU0_R")
	)
	(segment
		(start 440.54268 -115.740688)
		(end 440.54268 -116.304822)
		(width 0.12954)
		(layer "F.Cu")
		(net "SVID_CLK1_CPU0_R")
	)
	(via
		(at 306.433728 -192.78473)
		(size 0.508)
		(drill 0.254)
		(layers "F.Cu" "B.Cu")
		(net "SVID_CLK1_CPU0_R")
	)
	(via
		(at 440.54268 -120.820688)
		(size 0.762)
		(drill 0.381)
		(layers "F.Cu" "B.Cu")
		(net "SVID_CLK1_CPU0_R")
	)
	(segment
		(start 307.148738 -194.26428)
		(end 307.148738 -194.31762)
		(width 0.12954)
		(layer "B.Cu")
		(net "SVID_CLK1_CPU0_R")
	)
	(segment
		(start 306.433728 -193.54927)
		(end 307.148738 -194.26428)
		(width 0.12954)
		(layer "B.Cu")
		(net "SVID_CLK1_CPU0_R")
	)
	(segment
		(start 306.433728 -192.78473)
		(end 306.433728 -193.54927)
		(width 0.12954)
		(layer "B.Cu")
		(net "SVID_CLK1_CPU0_R")
	)
	(segment
		(start 353.94138 -234.69219)
		(end 353.94138 -234.156504)
		(width 0.12954)
		(layer "F.Cu")
		(net "SVID_CLK1_CPU0")
	)
	(segment
		(start 353.94138 -234.156504)
		(end 353.941634 -234.15625)
		(width 0.12954)
		(layer "F.Cu")
		(net "SVID_CLK1_CPU0")
	)
	(via
		(at 317.55842 -237.076996)
		(size 0.6604)
		(drill 0.3302)
		(layers "F.Cu" "B.Cu")
		(net "SVID_CLK1_CPU0")
	)
	(via
		(at 353.941634 -234.15625)
		(size 0.4572)
		(drill 0.2032)
		(layers "F.Cu" "B.Cu")
		(net "SVID_CLK1_CPU0")
	)
	(via
		(at 307.202078 -200.076308)
		(size 0.6604)
		(drill 0.3302)
		(layers "F.Cu" "B.Cu")
		(net "SVID_CLK1_CPU0")
	)
	(segment
		(start 346.625164 -234.471972)
		(end 346.610432 -234.480608)
		(width 0.0889)
		(layer "B.Cu")
		(net "SVID_CLK1_CPU0")
	)
	(segment
		(start 307.321458 -218.28633)
		(end 307.069998 -218.03487)
		(width 0.12954)
		(layer "B.Cu")
		(net "SVID_CLK1_CPU0")
	)
	(segment
		(start 352.654108 -234.15625)
		(end 352.278696 -234.531662)
		(width 0.0889)
		(layer "B.Cu")
		(net "SVID_CLK1_CPU0")
	)
	(segment
		(start 307.778658 -235.58119)
		(end 307.245258 -235.04779)
		(width 0.12954)
		(layer "B.Cu")
		(net "SVID_CLK1_CPU0")
	)
	(segment
		(start 336.085434 -234.531154)
		(end 335.610454 -234.531154)
		(width 0.0889)
		(layer "B.Cu")
		(net "SVID_CLK1_CPU0")
	)
	(segment
		(start 307.202078 -195.819268)
		(end 307.148738 -195.765928)
		(width 0.12954)
		(layer "B.Cu")
		(net "SVID_CLK1_CPU0")
	)
	(segment
		(start 337.227164 -234.471972)
		(end 337.212432 -234.480608)
		(width 0.0889)
		(layer "B.Cu")
		(net "SVID_CLK1_CPU0")
	)
	(segment
		(start 310.661558 -237.03153)
		(end 309.759858 -237.03153)
		(width 0.12954)
		(layer "B.Cu")
		(net "SVID_CLK1_CPU0")
	)
	(segment
		(start 307.009038 -220.01861)
		(end 307.321458 -219.70619)
		(width 0.12954)
		(layer "B.Cu")
		(net "SVID_CLK1_CPU0")
	)
	(segment
		(start 353.941634 -234.15625)
		(end 352.654108 -234.15625)
		(width 0.0889)
		(layer "B.Cu")
		(net "SVID_CLK1_CPU0")
	)
	(segment
		(start 307.009038 -220.65615)
		(end 307.009038 -220.01861)
		(width 0.12954)
		(layer "B.Cu")
		(net "SVID_CLK1_CPU0")
	)
	(segment
		(start 309.759858 -237.03153)
		(end 308.309518 -235.58119)
		(width 0.12954)
		(layer "B.Cu")
		(net "SVID_CLK1_CPU0")
	)
	(segment
		(start 307.036978 -209.24901)
		(end 307.036978 -208.04505)
		(width 0.12954)
		(layer "B.Cu")
		(net "SVID_CLK1_CPU0")
	)
	(segment
		(start 307.148738 -195.765928)
		(end 307.148738 -195.11772)
		(width 0.12954)
		(layer "B.Cu")
		(net "SVID_CLK1_CPU0")
	)
	(segment
		(start 307.069998 -210.59267)
		(end 307.359558 -210.30311)
		(width 0.12954)
		(layer "B.Cu")
		(net "SVID_CLK1_CPU0")
	)
	(segment
		(start 340.046564 -234.471972)
		(end 340.031832 -234.480608)
		(width 0.0889)
		(layer "B.Cu")
		(net "SVID_CLK1_CPU0")
	)
	(segment
		(start 307.245258 -220.89237)
		(end 307.009038 -220.65615)
		(width 0.12954)
		(layer "B.Cu")
		(net "SVID_CLK1_CPU0")
	)
	(segment
		(start 332.807056 -235.652056)
		(end 329.754992 -235.652056)
		(width 0.12954)
		(layer "B.Cu")
		(net "SVID_CLK1_CPU0")
	)
	(segment
		(start 312.899044 -237.076996)
		(end 312.581798 -236.75975)
		(width 0.12954)
		(layer "B.Cu")
		(net "SVID_CLK1_CPU0")
	)
	(segment
		(start 307.321458 -219.70619)
		(end 307.321458 -218.28633)
		(width 0.12954)
		(layer "B.Cu")
		(net "SVID_CLK1_CPU0")
	)
	(segment
		(start 348.500446 -234.474512)
		(end 348.490032 -234.480608)
		(width 0.0889)
		(layer "B.Cu")
		(net "SVID_CLK1_CPU0")
	)
	(segment
		(start 339.106764 -234.471972)
		(end 339.092032 -234.480608)
		(width 0.0889)
		(layer "B.Cu")
		(net "SVID_CLK1_CPU0")
	)
	(segment
		(start 307.069998 -218.03487)
		(end 307.069998 -210.59267)
		(width 0.12954)
		(layer "B.Cu")
		(net "SVID_CLK1_CPU0")
	)
	(segment
		(start 336.287364 -234.471972)
		(end 336.272632 -234.480608)
		(width 0.0889)
		(layer "B.Cu")
		(net "SVID_CLK1_CPU0")
	)
	(segment
		(start 307.245258 -235.04779)
		(end 307.245258 -220.89237)
		(width 0.12954)
		(layer "B.Cu")
		(net "SVID_CLK1_CPU0")
	)
	(segment
		(start 307.285898 -207.79613)
		(end 307.285898 -207.41005)
		(width 0.12954)
		(layer "B.Cu")
		(net "SVID_CLK1_CPU0")
	)
	(segment
		(start 334.127602 -234.33151)
		(end 333.88427 -234.574842)
		(width 0.0889)
		(layer "B.Cu")
		(net "SVID_CLK1_CPU0")
	)
	(segment
		(start 335.610454 -234.531154)
		(end 335.41081 -234.33151)
		(width 0.0889)
		(layer "B.Cu")
		(net "SVID_CLK1_CPU0")
	)
	(segment
		(start 307.036978 -208.04505)
		(end 307.285898 -207.79613)
		(width 0.12954)
		(layer "B.Cu")
		(net "SVID_CLK1_CPU0")
	)
	(segment
		(start 347.564964 -234.471972)
		(end 347.550232 -234.480608)
		(width 0.0889)
		(layer "B.Cu")
		(net "SVID_CLK1_CPU0")
	)
	(segment
		(start 307.285898 -207.41005)
		(end 306.920138 -207.04429)
		(width 0.12954)
		(layer "B.Cu")
		(net "SVID_CLK1_CPU0")
	)
	(segment
		(start 335.41081 -234.33151)
		(end 334.127602 -234.33151)
		(width 0.0889)
		(layer "B.Cu")
		(net "SVID_CLK1_CPU0")
	)
	(segment
		(start 307.359558 -209.57159)
		(end 307.036978 -209.24901)
		(width 0.12954)
		(layer "B.Cu")
		(net "SVID_CLK1_CPU0")
	)
	(segment
		(start 310.933338 -236.75975)
		(end 310.661558 -237.03153)
		(width 0.12954)
		(layer "B.Cu")
		(net "SVID_CLK1_CPU0")
	)
	(segment
		(start 317.55842 -237.076996)
		(end 312.899044 -237.076996)
		(width 0.12954)
		(layer "B.Cu")
		(net "SVID_CLK1_CPU0")
	)
	(segment
		(start 329.754992 -235.652056)
		(end 328.330052 -237.076996)
		(width 0.12954)
		(layer "B.Cu")
		(net "SVID_CLK1_CPU0")
	)
	(segment
		(start 306.920138 -206.35341)
		(end 307.202078 -206.07147)
		(width 0.12954)
		(layer "B.Cu")
		(net "SVID_CLK1_CPU0")
	)
	(segment
		(start 333.88427 -234.574842)
		(end 332.807056 -235.652056)
		(width 0.12954)
		(layer "B.Cu")
		(net "SVID_CLK1_CPU0")
	)
	(segment
		(start 340.986364 -234.471972)
		(end 340.971632 -234.480608)
		(width 0.0889)
		(layer "B.Cu")
		(net "SVID_CLK1_CPU0")
	)
	(segment
		(start 308.309518 -235.58119)
		(end 307.778658 -235.58119)
		(width 0.12954)
		(layer "B.Cu")
		(net "SVID_CLK1_CPU0")
	)
	(segment
		(start 307.202078 -206.07147)
		(end 307.202078 -200.076308)
		(width 0.12954)
		(layer "B.Cu")
		(net "SVID_CLK1_CPU0")
	)
	(segment
		(start 345.685364 -234.471972)
		(end 345.670632 -234.480608)
		(width 0.0889)
		(layer "B.Cu")
		(net "SVID_CLK1_CPU0")
	)
	(segment
		(start 350.357694 -234.531408)
		(end 350.182434 -234.531408)
		(width 0.0889)
		(layer "B.Cu")
		(net "SVID_CLK1_CPU0")
	)
	(segment
		(start 350.357694 -234.531662)
		(end 350.357694 -234.531408)
		(width 0.0889)
		(layer "B.Cu")
		(net "SVID_CLK1_CPU0")
	)
	(segment
		(start 349.439992 -234.474512)
		(end 349.429578 -234.480608)
		(width 0.0889)
		(layer "B.Cu")
		(net "SVID_CLK1_CPU0")
	)
	(segment
		(start 342.861392 -234.474512)
		(end 342.850978 -234.480608)
		(width 0.0889)
		(layer "B.Cu")
		(net "SVID_CLK1_CPU0")
	)
	(segment
		(start 343.805764 -234.471972)
		(end 343.791032 -234.480608)
		(width 0.0889)
		(layer "B.Cu")
		(net "SVID_CLK1_CPU0")
	)
	(segment
		(start 341.921846 -234.474512)
		(end 341.911432 -234.480608)
		(width 0.0889)
		(layer "B.Cu")
		(net "SVID_CLK1_CPU0")
	)
	(segment
		(start 307.202078 -200.076308)
		(end 307.202078 -195.819268)
		(width 0.12954)
		(layer "B.Cu")
		(net "SVID_CLK1_CPU0")
	)
	(segment
		(start 306.920138 -207.04429)
		(end 306.920138 -206.35341)
		(width 0.12954)
		(layer "B.Cu")
		(net "SVID_CLK1_CPU0")
	)
	(segment
		(start 307.359558 -210.30311)
		(end 307.359558 -209.57159)
		(width 0.12954)
		(layer "B.Cu")
		(net "SVID_CLK1_CPU0")
	)
	(segment
		(start 328.330052 -237.076996)
		(end 317.55842 -237.076996)
		(width 0.12954)
		(layer "B.Cu")
		(net "SVID_CLK1_CPU0")
	)
	(segment
		(start 312.581798 -236.75975)
		(end 310.933338 -236.75975)
		(width 0.12954)
		(layer "B.Cu")
		(net "SVID_CLK1_CPU0")
	)
	(segment
		(start 352.278696 -234.531662)
		(end 350.357694 -234.531662)
		(width 0.0889)
		(layer "B.Cu")
		(net "SVID_CLK1_CPU0")
	)
	(arc
		(start 348.115636 -234.480608)
		(mid 347.841437 -234.404773)
		(end 347.564964 -234.471972)
		(width 0.0889)
		(layer "B.Cu")
		(net "SVID_CLK1_CPU0")
	)
	(arc
		(start 340.971632 -234.480608)
		(mid 340.784434 -234.530751)
		(end 340.597236 -234.480608)
		(width 0.0889)
		(layer "B.Cu")
		(net "SVID_CLK1_CPU0")
	)
	(arc
		(start 337.212432 -234.480608)
		(mid 337.025234 -234.530751)
		(end 336.838036 -234.480608)
		(width 0.0889)
		(layer "B.Cu")
		(net "SVID_CLK1_CPU0")
	)
	(arc
		(start 338.717636 -234.480608)
		(mid 338.434934 -234.404832)
		(end 338.152232 -234.480608)
		(width 0.0889)
		(layer "B.Cu")
		(net "SVID_CLK1_CPU0")
	)
	(arc
		(start 344.730832 -234.480608)
		(mid 344.543634 -234.530751)
		(end 344.356436 -234.480608)
		(width 0.0889)
		(layer "B.Cu")
		(net "SVID_CLK1_CPU0")
	)
	(arc
		(start 344.356436 -234.480608)
		(mid 344.082237 -234.404773)
		(end 343.805764 -234.471972)
		(width 0.0889)
		(layer "B.Cu")
		(net "SVID_CLK1_CPU0")
	)
	(arc
		(start 341.537036 -234.480608)
		(mid 341.262837 -234.404773)
		(end 340.986364 -234.471972)
		(width 0.0889)
		(layer "B.Cu")
		(net "SVID_CLK1_CPU0")
	)
	(arc
		(start 345.670632 -234.480608)
		(mid 345.483434 -234.530751)
		(end 345.296236 -234.480608)
		(width 0.0889)
		(layer "B.Cu")
		(net "SVID_CLK1_CPU0")
	)
	(arc
		(start 339.092032 -234.480608)
		(mid 338.904834 -234.530751)
		(end 338.717636 -234.480608)
		(width 0.0889)
		(layer "B.Cu")
		(net "SVID_CLK1_CPU0")
	)
	(arc
		(start 337.777836 -234.480608)
		(mid 337.503637 -234.404773)
		(end 337.227164 -234.471972)
		(width 0.0889)
		(layer "B.Cu")
		(net "SVID_CLK1_CPU0")
	)
	(arc
		(start 338.152232 -234.480608)
		(mid 337.965034 -234.530751)
		(end 337.777836 -234.480608)
		(width 0.0889)
		(layer "B.Cu")
		(net "SVID_CLK1_CPU0")
	)
	(arc
		(start 348.490032 -234.480608)
		(mid 348.302834 -234.530751)
		(end 348.115636 -234.480608)
		(width 0.0889)
		(layer "B.Cu")
		(net "SVID_CLK1_CPU0")
	)
	(arc
		(start 343.791032 -234.480608)
		(mid 343.603834 -234.530751)
		(end 343.416636 -234.480608)
		(width 0.0889)
		(layer "B.Cu")
		(net "SVID_CLK1_CPU0")
	)
	(arc
		(start 347.175836 -234.480608)
		(mid 346.901637 -234.404773)
		(end 346.625164 -234.471972)
		(width 0.0889)
		(layer "B.Cu")
		(net "SVID_CLK1_CPU0")
	)
	(arc
		(start 349.429578 -234.480608)
		(mid 349.24238 -234.530751)
		(end 349.055182 -234.480608)
		(width 0.0889)
		(layer "B.Cu")
		(net "SVID_CLK1_CPU0")
	)
	(arc
		(start 342.476582 -234.480608)
		(mid 342.200023 -234.404865)
		(end 341.921846 -234.474512)
		(width 0.0889)
		(layer "B.Cu")
		(net "SVID_CLK1_CPU0")
	)
	(arc
		(start 347.550232 -234.480608)
		(mid 347.363034 -234.530751)
		(end 347.175836 -234.480608)
		(width 0.0889)
		(layer "B.Cu")
		(net "SVID_CLK1_CPU0")
	)
	(arc
		(start 349.055182 -234.480608)
		(mid 348.778623 -234.404865)
		(end 348.500446 -234.474512)
		(width 0.0889)
		(layer "B.Cu")
		(net "SVID_CLK1_CPU0")
	)
	(arc
		(start 342.850978 -234.480608)
		(mid 342.66378 -234.530751)
		(end 342.476582 -234.480608)
		(width 0.0889)
		(layer "B.Cu")
		(net "SVID_CLK1_CPU0")
	)
	(arc
		(start 336.272632 -234.480608)
		(mid 336.18236 -234.518207)
		(end 336.085434 -234.531154)
		(width 0.0889)
		(layer "B.Cu")
		(net "SVID_CLK1_CPU0")
	)
	(arc
		(start 350.182434 -234.531408)
		(mid 350.085495 -234.518318)
		(end 349.995236 -234.480608)
		(width 0.0889)
		(layer "B.Cu")
		(net "SVID_CLK1_CPU0")
	)
	(arc
		(start 341.911432 -234.480608)
		(mid 341.724234 -234.530751)
		(end 341.537036 -234.480608)
		(width 0.0889)
		(layer "B.Cu")
		(net "SVID_CLK1_CPU0")
	)
	(arc
		(start 346.610432 -234.480608)
		(mid 346.423234 -234.530751)
		(end 346.236036 -234.480608)
		(width 0.0889)
		(layer "B.Cu")
		(net "SVID_CLK1_CPU0")
	)
	(arc
		(start 346.236036 -234.480608)
		(mid 345.961837 -234.404773)
		(end 345.685364 -234.471972)
		(width 0.0889)
		(layer "B.Cu")
		(net "SVID_CLK1_CPU0")
	)
	(arc
		(start 349.995236 -234.480608)
		(mid 349.718423 -234.404738)
		(end 349.439992 -234.474512)
		(width 0.0889)
		(layer "B.Cu")
		(net "SVID_CLK1_CPU0")
	)
	(arc
		(start 336.838036 -234.480608)
		(mid 336.563837 -234.404773)
		(end 336.287364 -234.471972)
		(width 0.0889)
		(layer "B.Cu")
		(net "SVID_CLK1_CPU0")
	)
	(arc
		(start 339.657436 -234.480608)
		(mid 339.383237 -234.404773)
		(end 339.106764 -234.471972)
		(width 0.0889)
		(layer "B.Cu")
		(net "SVID_CLK1_CPU0")
	)
	(arc
		(start 343.416636 -234.480608)
		(mid 343.139823 -234.404738)
		(end 342.861392 -234.474512)
		(width 0.0889)
		(layer "B.Cu")
		(net "SVID_CLK1_CPU0")
	)
	(arc
		(start 340.597236 -234.480608)
		(mid 340.323037 -234.404773)
		(end 340.046564 -234.471972)
		(width 0.0889)
		(layer "B.Cu")
		(net "SVID_CLK1_CPU0")
	)
	(arc
		(start 345.296236 -234.480608)
		(mid 345.013534 -234.404832)
		(end 344.730832 -234.480608)
		(width 0.0889)
		(layer "B.Cu")
		(net "SVID_CLK1_CPU0")
	)
	(arc
		(start 340.031832 -234.480608)
		(mid 339.844634 -234.530751)
		(end 339.657436 -234.480608)
		(width 0.0889)
		(layer "B.Cu")
		(net "SVID_CLK1_CPU0")
	)
	(segment
		(start 38.247066 -129.378202)
		(end 37.879528 -129.74574)
		(width 0.12954)
		(layer "F.Cu")
		(net "SVID_CLK0_CPU1_R")
	)
	(segment
		(start 37.879528 -129.74574)
		(end 37.356288 -129.74574)
		(width 0.12954)
		(layer "F.Cu")
		(net "SVID_CLK0_CPU1_R")
	)
	(segment
		(start 40.64 -129.553208)
		(end 40.464994 -129.378202)
		(width 0.12954)
		(layer "F.Cu")
		(net "SVID_CLK0_CPU1_R")
	)
	(segment
		(start 102.317296 -357.689658)
		(end 102.444296 -357.562658)
		(width 0.12954)
		(layer "F.Cu")
		(net "SVID_CLK0_CPU1_R")
	)
	(segment
		(start 101.834696 -357.689658)
		(end 102.317296 -357.689658)
		(width 0.12954)
		(layer "F.Cu")
		(net "SVID_CLK0_CPU1_R")
	)
	(segment
		(start 40.464994 -129.378202)
		(end 38.247066 -129.378202)
		(width 0.12954)
		(layer "F.Cu")
		(net "SVID_CLK0_CPU1_R")
	)
	(via
		(at 71.385684 -189.662308)
		(size 0.508)
		(drill 0.254)
		(layers "F.Cu" "B.Cu")
		(net "SVID_CLK0_CPU1_R")
	)
	(via
		(at 95.96882 -389.722868)
		(size 0.508)
		(drill 0.254)
		(layers "F.Cu" "B.Cu")
		(net "SVID_CLK0_CPU1_R")
	)
	(via
		(at 40.64 -129.553208)
		(size 0.508)
		(drill 0.254)
		(layers "F.Cu" "B.Cu")
		(net "SVID_CLK0_CPU1_R")
	)
	(via
		(at 62.4078 -130.368548)
		(size 0.508)
		(drill 0.254)
		(layers "F.Cu" "B.Cu")
		(net "SVID_CLK0_CPU1_R")
	)
	(via
		(at 101.834696 -357.689658)
		(size 0.508)
		(drill 0.254)
		(layers "F.Cu" "B.Cu")
		(net "SVID_CLK0_CPU1_R")
	)
	(via
		(at 97.959418 -364.08995)
		(size 0.508)
		(drill 0.254)
		(layers "F.Cu" "B.Cu")
		(net "SVID_CLK0_CPU1_R")
	)
	(segment
		(start 71.385684 -190.344806)
		(end 71.385684 -189.662308)
		(width 0.12954)
		(layer "B.Cu")
		(net "SVID_CLK0_CPU1_R")
	)
	(segment
		(start 101.834696 -357.689658)
		(end 100.864924 -357.689658)
		(width 0.12954)
		(layer "B.Cu")
		(net "SVID_CLK0_CPU1_R")
	)
	(segment
		(start 40.64 -129.553208)
		(end 40.191944 -129.553208)
		(width 0.12954)
		(layer "B.Cu")
		(net "SVID_CLK0_CPU1_R")
	)
	(segment
		(start 40.191944 -129.553208)
		(end 39.927022 -129.81813)
		(width 0.12954)
		(layer "B.Cu")
		(net "SVID_CLK0_CPU1_R")
	)
	(segment
		(start 100.864924 -357.689658)
		(end 100.706936 -357.53167)
		(width 0.12954)
		(layer "B.Cu")
		(net "SVID_CLK0_CPU1_R")
	)
	(segment
		(start 63.05042 -133.314948)
		(end 65.4558 -133.314948)
		(width 0.127)
		(layer "In2.Cu")
		(net "SVID_CLK0_CPU1_R")
	)
	(segment
		(start 75.8317 -188.826648)
		(end 72.221344 -188.826648)
		(width 0.127)
		(layer "In2.Cu")
		(net "SVID_CLK0_CPU1_R")
	)
	(segment
		(start 76.2762 -146.497548)
		(end 76.2762 -155.920948)
		(width 0.127)
		(layer "In2.Cu")
		(net "SVID_CLK0_CPU1_R")
	)
	(segment
		(start 65.4558 -133.314948)
		(end 75.73518 -143.594328)
		(width 0.127)
		(layer "In2.Cu")
		(net "SVID_CLK0_CPU1_R")
	)
	(segment
		(start 78.9178 -159.972248)
		(end 80.95234 -162.006788)
		(width 0.127)
		(layer "In2.Cu")
		(net "SVID_CLK0_CPU1_R")
	)
	(segment
		(start 80.95234 -162.006788)
		(end 80.95234 -183.706008)
		(width 0.127)
		(layer "In2.Cu")
		(net "SVID_CLK0_CPU1_R")
	)
	(segment
		(start 62.4078 -130.368548)
		(end 62.4078 -132.672328)
		(width 0.127)
		(layer "In2.Cu")
		(net "SVID_CLK0_CPU1_R")
	)
	(segment
		(start 75.73518 -145.956528)
		(end 76.2762 -146.497548)
		(width 0.127)
		(layer "In2.Cu")
		(net "SVID_CLK0_CPU1_R")
	)
	(segment
		(start 76.2762 -155.920948)
		(end 78.9178 -158.562548)
		(width 0.127)
		(layer "In2.Cu")
		(net "SVID_CLK0_CPU1_R")
	)
	(segment
		(start 75.73518 -143.594328)
		(end 75.73518 -145.956528)
		(width 0.127)
		(layer "In2.Cu")
		(net "SVID_CLK0_CPU1_R")
	)
	(segment
		(start 72.221344 -188.826648)
		(end 71.385684 -189.662308)
		(width 0.127)
		(layer "In2.Cu")
		(net "SVID_CLK0_CPU1_R")
	)
	(segment
		(start 62.4078 -132.672328)
		(end 63.05042 -133.314948)
		(width 0.127)
		(layer "In2.Cu")
		(net "SVID_CLK0_CPU1_R")
	)
	(segment
		(start 78.9178 -158.562548)
		(end 78.9178 -159.972248)
		(width 0.127)
		(layer "In2.Cu")
		(net "SVID_CLK0_CPU1_R")
	)
	(segment
		(start 80.95234 -183.706008)
		(end 75.8317 -188.826648)
		(width 0.127)
		(layer "In2.Cu")
		(net "SVID_CLK0_CPU1_R")
	)
	(segment
		(start 62.4078 -131.509008)
		(end 61.815726 -132.101082)
		(width 0.127)
		(layer "In6.Cu")
		(net "SVID_CLK0_CPU1_R")
	)
	(segment
		(start 61.815726 -132.101082)
		(end 41.818814 -132.101082)
		(width 0.127)
		(layer "In6.Cu")
		(net "SVID_CLK0_CPU1_R")
	)
	(segment
		(start 40.64 -130.922268)
		(end 40.64 -129.553208)
		(width 0.127)
		(layer "In6.Cu")
		(net "SVID_CLK0_CPU1_R")
	)
	(segment
		(start 41.818814 -132.101082)
		(end 40.64 -130.922268)
		(width 0.127)
		(layer "In6.Cu")
		(net "SVID_CLK0_CPU1_R")
	)
	(segment
		(start 62.4078 -130.368548)
		(end 62.4078 -131.509008)
		(width 0.127)
		(layer "In6.Cu")
		(net "SVID_CLK0_CPU1_R")
	)
	(segment
		(start 95.96882 -389.722868)
		(end 95.12808 -390.563608)
		(width 0.127)
		(layer "In11.Cu")
		(net "SVID_CLK0_CPU1_R")
	)
	(segment
		(start 7.62254 -321.513708)
		(end 7.62254 -258.130548)
		(width 0.127)
		(layer "In11.Cu")
		(net "SVID_CLK0_CPU1_R")
	)
	(segment
		(start 31.89224 -334.52562)
		(end 31.76524 -334.39862)
		(width 0.127)
		(layer "In11.Cu")
		(net "SVID_CLK0_CPU1_R")
	)
	(segment
		(start 31.08706 -334.27162)
		(end 31.08706 -333.66202)
		(width 0.127)
		(layer "In11.Cu")
		(net "SVID_CLK0_CPU1_R")
	)
	(segment
		(start 31.76524 -333.53502)
		(end 31.89224 -333.40802)
		(width 0.127)
		(layer "In11.Cu")
		(net "SVID_CLK0_CPU1_R")
	)
	(segment
		(start 43.2181 -124.623068)
		(end 43.2181 -127.803148)
		(width 0.127)
		(layer "In11.Cu")
		(net "SVID_CLK0_CPU1_R")
	)
	(segment
		(start 31.89224 -330.810108)
		(end 26.3144 -325.232268)
		(width 0.127)
		(layer "In11.Cu")
		(net "SVID_CLK0_CPU1_R")
	)
	(segment
		(start 10.303764 -181.626764)
		(end 10.303764 -175.085756)
		(width 0.127)
		(layer "In11.Cu")
		(net "SVID_CLK0_CPU1_R")
	)
	(segment
		(start 31.76524 -332.67142)
		(end 31.21406 -332.67142)
		(width 0.127)
		(layer "In11.Cu")
		(net "SVID_CLK0_CPU1_R")
	)
	(segment
		(start 31.21406 -334.39862)
		(end 31.08706 -334.27162)
		(width 0.127)
		(layer "In11.Cu")
		(net "SVID_CLK0_CPU1_R")
	)
	(segment
		(start 15.968218 -169.421302)
		(end 15.968218 -152.95118)
		(width 0.127)
		(layer "In11.Cu")
		(net "SVID_CLK0_CPU1_R")
	)
	(segment
		(start 31.76524 -334.39862)
		(end 31.21406 -334.39862)
		(width 0.127)
		(layer "In11.Cu")
		(net "SVID_CLK0_CPU1_R")
	)
	(segment
		(start 31.21406 -333.53502)
		(end 31.76524 -333.53502)
		(width 0.127)
		(layer "In11.Cu")
		(net "SVID_CLK0_CPU1_R")
	)
	(segment
		(start 7.62254 -258.130548)
		(end 9.3091 -256.443988)
		(width 0.127)
		(layer "In11.Cu")
		(net "SVID_CLK0_CPU1_R")
	)
	(segment
		(start 31.89224 -332.79842)
		(end 31.76524 -332.67142)
		(width 0.127)
		(layer "In11.Cu")
		(net "SVID_CLK0_CPU1_R")
	)
	(segment
		(start 31.76524 -331.80782)
		(end 31.89224 -331.68082)
		(width 0.127)
		(layer "In11.Cu")
		(net "SVID_CLK0_CPU1_R")
	)
	(segment
		(start 31.08706 -332.54442)
		(end 31.08706 -331.93482)
		(width 0.127)
		(layer "In11.Cu")
		(net "SVID_CLK0_CPU1_R")
	)
	(segment
		(start 100.791264 -358.73309)
		(end 100.288598 -358.73309)
		(width 0.127)
		(layer "In11.Cu")
		(net "SVID_CLK0_CPU1_R")
	)
	(segment
		(start 98.806 -360.215688)
		(end 98.806 -363.243368)
		(width 0.127)
		(layer "In11.Cu")
		(net "SVID_CLK0_CPU1_R")
	)
	(segment
		(start 11.85926 -190.556388)
		(end 13.47724 -188.938408)
		(width 0.127)
		(layer "In11.Cu")
		(net "SVID_CLK0_CPU1_R")
	)
	(segment
		(start 95.12808 -390.563608)
		(end 57.64276 -390.563608)
		(width 0.127)
		(layer "In11.Cu")
		(net "SVID_CLK0_CPU1_R")
	)
	(segment
		(start 11.3411 -325.232268)
		(end 7.62254 -321.513708)
		(width 0.127)
		(layer "In11.Cu")
		(net "SVID_CLK0_CPU1_R")
	)
	(segment
		(start 21.450554 -147.468844)
		(end 21.450554 -127.513588)
		(width 0.127)
		(layer "In11.Cu")
		(net "SVID_CLK0_CPU1_R")
	)
	(segment
		(start 28.98902 -339.585808)
		(end 31.89224 -336.682588)
		(width 0.127)
		(layer "In11.Cu")
		(net "SVID_CLK0_CPU1_R")
	)
	(segment
		(start 9.3091 -256.443988)
		(end 10.39622 -256.443988)
		(width 0.127)
		(layer "In11.Cu")
		(net "SVID_CLK0_CPU1_R")
	)
	(segment
		(start 31.21406 -331.80782)
		(end 31.76524 -331.80782)
		(width 0.127)
		(layer "In11.Cu")
		(net "SVID_CLK0_CPU1_R")
	)
	(segment
		(start 28.975812 -119.98833)
		(end 38.583362 -119.98833)
		(width 0.127)
		(layer "In11.Cu")
		(net "SVID_CLK0_CPU1_R")
	)
	(segment
		(start 21.450554 -127.513588)
		(end 28.975812 -119.98833)
		(width 0.127)
		(layer "In11.Cu")
		(net "SVID_CLK0_CPU1_R")
	)
	(segment
		(start 57.64276 -390.563608)
		(end 28.98902 -361.909868)
		(width 0.127)
		(layer "In11.Cu")
		(net "SVID_CLK0_CPU1_R")
	)
	(segment
		(start 13.47724 -184.80024)
		(end 10.303764 -181.626764)
		(width 0.127)
		(layer "In11.Cu")
		(net "SVID_CLK0_CPU1_R")
	)
	(segment
		(start 31.08706 -333.66202)
		(end 31.21406 -333.53502)
		(width 0.127)
		(layer "In11.Cu")
		(net "SVID_CLK0_CPU1_R")
	)
	(segment
		(start 13.47724 -188.938408)
		(end 13.47724 -184.80024)
		(width 0.127)
		(layer "In11.Cu")
		(net "SVID_CLK0_CPU1_R")
	)
	(segment
		(start 15.968218 -152.95118)
		(end 21.450554 -147.468844)
		(width 0.127)
		(layer "In11.Cu")
		(net "SVID_CLK0_CPU1_R")
	)
	(segment
		(start 10.303764 -175.085756)
		(end 15.968218 -169.421302)
		(width 0.127)
		(layer "In11.Cu")
		(net "SVID_CLK0_CPU1_R")
	)
	(segment
		(start 98.806 -363.243368)
		(end 97.959418 -364.08995)
		(width 0.127)
		(layer "In11.Cu")
		(net "SVID_CLK0_CPU1_R")
	)
	(segment
		(start 31.08706 -331.93482)
		(end 31.21406 -331.80782)
		(width 0.127)
		(layer "In11.Cu")
		(net "SVID_CLK0_CPU1_R")
	)
	(segment
		(start 10.39622 -256.443988)
		(end 11.85926 -254.980948)
		(width 0.127)
		(layer "In11.Cu")
		(net "SVID_CLK0_CPU1_R")
	)
	(segment
		(start 31.21406 -332.67142)
		(end 31.08706 -332.54442)
		(width 0.127)
		(layer "In11.Cu")
		(net "SVID_CLK0_CPU1_R")
	)
	(segment
		(start 41.46804 -129.553208)
		(end 40.64 -129.553208)
		(width 0.127)
		(layer "In11.Cu")
		(net "SVID_CLK0_CPU1_R")
	)
	(segment
		(start 31.89224 -333.40802)
		(end 31.89224 -332.79842)
		(width 0.127)
		(layer "In11.Cu")
		(net "SVID_CLK0_CPU1_R")
	)
	(segment
		(start 101.834696 -357.689658)
		(end 100.791264 -358.73309)
		(width 0.127)
		(layer "In11.Cu")
		(net "SVID_CLK0_CPU1_R")
	)
	(segment
		(start 31.89224 -331.68082)
		(end 31.89224 -330.810108)
		(width 0.127)
		(layer "In11.Cu")
		(net "SVID_CLK0_CPU1_R")
	)
	(segment
		(start 31.89224 -336.682588)
		(end 31.89224 -334.52562)
		(width 0.127)
		(layer "In11.Cu")
		(net "SVID_CLK0_CPU1_R")
	)
	(segment
		(start 38.583362 -119.98833)
		(end 43.2181 -124.623068)
		(width 0.127)
		(layer "In11.Cu")
		(net "SVID_CLK0_CPU1_R")
	)
	(segment
		(start 28.98902 -361.909868)
		(end 28.98902 -339.585808)
		(width 0.127)
		(layer "In11.Cu")
		(net "SVID_CLK0_CPU1_R")
	)
	(segment
		(start 26.3144 -325.232268)
		(end 11.3411 -325.232268)
		(width 0.127)
		(layer "In11.Cu")
		(net "SVID_CLK0_CPU1_R")
	)
	(segment
		(start 100.288598 -358.73309)
		(end 98.806 -360.215688)
		(width 0.127)
		(layer "In11.Cu")
		(net "SVID_CLK0_CPU1_R")
	)
	(segment
		(start 43.2181 -127.803148)
		(end 41.46804 -129.553208)
		(width 0.127)
		(layer "In11.Cu")
		(net "SVID_CLK0_CPU1_R")
	)
	(segment
		(start 11.85926 -254.980948)
		(end 11.85926 -190.556388)
		(width 0.127)
		(layer "In11.Cu")
		(net "SVID_CLK0_CPU1_R")
	)
	(segment
		(start 95.96882 -389.722868)
		(end 95.96882 -388.856728)
		(width 0.127)
		(layer "In13.Cu")
		(net "SVID_CLK0_CPU1_R")
	)
	(segment
		(start 95.96882 -388.856728)
		(end 96.19996 -388.625588)
		(width 0.127)
		(layer "In13.Cu")
		(net "SVID_CLK0_CPU1_R")
	)
	(segment
		(start 96.19996 -367.957608)
		(end 97.959418 -366.19815)
		(width 0.127)
		(layer "In13.Cu")
		(net "SVID_CLK0_CPU1_R")
	)
	(segment
		(start 97.959418 -366.19815)
		(end 97.959418 -364.08995)
		(width 0.127)
		(layer "In13.Cu")
		(net "SVID_CLK0_CPU1_R")
	)
	(segment
		(start 96.19996 -388.625588)
		(end 96.19996 -367.957608)
		(width 0.127)
		(layer "In13.Cu")
		(net "SVID_CLK0_CPU1_R")
	)
	(segment
		(start 106.941112 -234.69219)
		(end 106.941366 -234.691936)
		(width 0.12954)
		(layer "F.Cu")
		(net "SVID_CLK0_CPU1")
	)
	(segment
		(start 106.941366 -234.691936)
		(end 106.941366 -234.15625)
		(width 0.12954)
		(layer "F.Cu")
		(net "SVID_CLK0_CPU1")
	)
	(via
		(at 106.941366 -234.15625)
		(size 0.4572)
		(drill 0.2032)
		(layers "F.Cu" "B.Cu")
		(net "SVID_CLK0_CPU1")
	)
	(via
		(at 66.991738 -224.82429)
		(size 0.6604)
		(drill 0.3302)
		(layers "F.Cu" "B.Cu")
		(net "SVID_CLK0_CPU1")
	)
	(segment
		(start 87.87765 -234.654598)
		(end 87.862918 -234.645962)
		(width 0.0889)
		(layer "B.Cu")
		(net "SVID_CLK0_CPU1")
	)
	(segment
		(start 66.991738 -223.019366)
		(end 66.31686 -222.344488)
		(width 0.12954)
		(layer "B.Cu")
		(net "SVID_CLK0_CPU1")
	)
	(segment
		(start 86.048088 -235.128054)
		(end 84.951316 -236.224826)
		(width 0.12954)
		(layer "B.Cu")
		(net "SVID_CLK0_CPU1")
	)
	(segment
		(start 71.934578 -231.56545)
		(end 66.991738 -226.62261)
		(width 0.12954)
		(layer "B.Cu")
		(net "SVID_CLK0_CPU1")
	)
	(segment
		(start 86.93785 -234.654598)
		(end 86.923118 -234.645962)
		(width 0.0889)
		(layer "B.Cu")
		(net "SVID_CLK0_CPU1")
	)
	(segment
		(start 65.921636 -222.344488)
		(end 65.332864 -221.755716)
		(width 0.12954)
		(layer "B.Cu")
		(net "SVID_CLK0_CPU1")
	)
	(segment
		(start 70.971156 -192.566036)
		(end 71.385684 -191.56553)
		(width 0.12954)
		(layer "B.Cu")
		(net "SVID_CLK0_CPU1")
	)
	(segment
		(start 66.991738 -224.82429)
		(end 66.991738 -223.019366)
		(width 0.12954)
		(layer "B.Cu")
		(net "SVID_CLK0_CPU1")
	)
	(segment
		(start 67.50812 -203.170282)
		(end 69.865748 -200.812654)
		(width 0.12954)
		(layer "B.Cu")
		(net "SVID_CLK0_CPU1")
	)
	(segment
		(start 101.97465 -234.654598)
		(end 101.964236 -234.648502)
		(width 0.0889)
		(layer "B.Cu")
		(net "SVID_CLK0_CPU1")
	)
	(segment
		(start 71.385684 -191.56553)
		(end 71.385684 -191.144906)
		(width 0.12954)
		(layer "B.Cu")
		(net "SVID_CLK0_CPU1")
	)
	(segment
		(start 101.964236 -234.648502)
		(end 101.95941 -234.645708)
		(width 0.0889)
		(layer "B.Cu")
		(net "SVID_CLK0_CPU1")
	)
	(segment
		(start 66.599054 -205.18628)
		(end 67.50812 -204.277214)
		(width 0.12954)
		(layer "B.Cu")
		(net "SVID_CLK0_CPU1")
	)
	(segment
		(start 100.645214 -234.645708)
		(end 100.630482 -234.654344)
		(width 0.0889)
		(layer "B.Cu")
		(net "SVID_CLK0_CPU1")
	)
	(segment
		(start 65.332864 -221.755716)
		(end 65.332864 -206.00543)
		(width 0.12954)
		(layer "B.Cu")
		(net "SVID_CLK0_CPU1")
	)
	(segment
		(start 104.79405 -234.654598)
		(end 104.779318 -234.645962)
		(width 0.0889)
		(layer "B.Cu")
		(net "SVID_CLK0_CPU1")
	)
	(segment
		(start 99.705414 -234.645708)
		(end 99.690682 -234.654344)
		(width 0.0889)
		(layer "B.Cu")
		(net "SVID_CLK0_CPU1")
	)
	(segment
		(start 72.889618 -231.56545)
		(end 71.934578 -231.56545)
		(width 0.12954)
		(layer "B.Cu")
		(net "SVID_CLK0_CPU1")
	)
	(segment
		(start 86.470744 -234.705398)
		(end 86.048088 -235.128054)
		(width 0.0889)
		(layer "B.Cu")
		(net "SVID_CLK0_CPU1")
	)
	(segment
		(start 66.991738 -226.62261)
		(end 66.991738 -224.82429)
		(width 0.12954)
		(layer "B.Cu")
		(net "SVID_CLK0_CPU1")
	)
	(segment
		(start 91.247214 -234.645708)
		(end 91.2368 -234.651804)
		(width 0.0889)
		(layer "B.Cu")
		(net "SVID_CLK0_CPU1")
	)
	(segment
		(start 106.183938 -234.601004)
		(end 105.59415 -234.601004)
		(width 0.0889)
		(layer "B.Cu")
		(net "SVID_CLK0_CPU1")
	)
	(segment
		(start 93.126814 -234.645708)
		(end 93.112082 -234.654344)
		(width 0.0889)
		(layer "B.Cu")
		(net "SVID_CLK0_CPU1")
	)
	(segment
		(start 77.548994 -236.224826)
		(end 72.889618 -231.56545)
		(width 0.12954)
		(layer "B.Cu")
		(net "SVID_CLK0_CPU1")
	)
	(segment
		(start 89.367614 -234.645708)
		(end 89.352882 -234.654344)
		(width 0.0889)
		(layer "B.Cu")
		(net "SVID_CLK0_CPU1")
	)
	(segment
		(start 95.946214 -234.645708)
		(end 95.931482 -234.654344)
		(width 0.0889)
		(layer "B.Cu")
		(net "SVID_CLK0_CPU1")
	)
	(segment
		(start 102.91445 -234.654598)
		(end 102.899718 -234.645962)
		(width 0.0889)
		(layer "B.Cu")
		(net "SVID_CLK0_CPU1")
	)
	(segment
		(start 65.332864 -206.00543)
		(end 66.152014 -205.18628)
		(width 0.12954)
		(layer "B.Cu")
		(net "SVID_CLK0_CPU1")
	)
	(segment
		(start 92.187014 -234.645708)
		(end 92.172282 -234.654344)
		(width 0.0889)
		(layer "B.Cu")
		(net "SVID_CLK0_CPU1")
	)
	(segment
		(start 90.307668 -234.645708)
		(end 90.297254 -234.651804)
		(width 0.0889)
		(layer "B.Cu")
		(net "SVID_CLK0_CPU1")
	)
	(segment
		(start 96.886268 -234.645708)
		(end 96.875854 -234.651804)
		(width 0.0889)
		(layer "B.Cu")
		(net "SVID_CLK0_CPU1")
	)
	(segment
		(start 94.066614 -234.645708)
		(end 94.051882 -234.654344)
		(width 0.0889)
		(layer "B.Cu")
		(net "SVID_CLK0_CPU1")
	)
	(segment
		(start 84.951316 -236.224826)
		(end 77.548994 -236.224826)
		(width 0.12954)
		(layer "B.Cu")
		(net "SVID_CLK0_CPU1")
	)
	(segment
		(start 69.865748 -200.812654)
		(end 69.865748 -199.35698)
		(width 0.12954)
		(layer "B.Cu")
		(net "SVID_CLK0_CPU1")
	)
	(segment
		(start 66.152014 -205.18628)
		(end 66.599054 -205.18628)
		(width 0.12954)
		(layer "B.Cu")
		(net "SVID_CLK0_CPU1")
	)
	(segment
		(start 70.971156 -198.251572)
		(end 70.971156 -192.566036)
		(width 0.12954)
		(layer "B.Cu")
		(net "SVID_CLK0_CPU1")
	)
	(segment
		(start 87.944452 -234.7214)
		(end 87.87765 -234.654598)
		(width 0.0889)
		(layer "B.Cu")
		(net "SVID_CLK0_CPU1")
	)
	(segment
		(start 88.145366 -234.7214)
		(end 87.944452 -234.7214)
		(width 0.0889)
		(layer "B.Cu")
		(net "SVID_CLK0_CPU1")
	)
	(segment
		(start 69.865748 -199.35698)
		(end 70.971156 -198.251572)
		(width 0.12954)
		(layer "B.Cu")
		(net "SVID_CLK0_CPU1")
	)
	(segment
		(start 66.31686 -222.344488)
		(end 65.921636 -222.344488)
		(width 0.12954)
		(layer "B.Cu")
		(net "SVID_CLK0_CPU1")
	)
	(segment
		(start 106.941366 -234.15625)
		(end 106.628692 -234.15625)
		(width 0.0889)
		(layer "B.Cu")
		(net "SVID_CLK0_CPU1")
	)
	(segment
		(start 106.628692 -234.15625)
		(end 106.183938 -234.601004)
		(width 0.0889)
		(layer "B.Cu")
		(net "SVID_CLK0_CPU1")
	)
	(segment
		(start 103.85425 -234.654598)
		(end 103.839518 -234.645962)
		(width 0.0889)
		(layer "B.Cu")
		(net "SVID_CLK0_CPU1")
	)
	(segment
		(start 67.50812 -204.277214)
		(end 67.50812 -203.170282)
		(width 0.12954)
		(layer "B.Cu")
		(net "SVID_CLK0_CPU1")
	)
	(segment
		(start 98.765614 -234.645708)
		(end 98.750882 -234.654344)
		(width 0.0889)
		(layer "B.Cu")
		(net "SVID_CLK0_CPU1")
	)
	(segment
		(start 97.825814 -234.645708)
		(end 97.8154 -234.651804)
		(width 0.0889)
		(layer "B.Cu")
		(net "SVID_CLK0_CPU1")
	)
	(arc
		(start 86.548722 -234.645962)
		(mid 86.507787 -234.673126)
		(end 86.470744 -234.705398)
		(width 0.0889)
		(layer "B.Cu")
		(net "SVID_CLK0_CPU1")
	)
	(arc
		(start 90.682064 -234.645708)
		(mid 90.494866 -234.595565)
		(end 90.307668 -234.645708)
		(width 0.0889)
		(layer "B.Cu")
		(net "SVID_CLK0_CPU1")
	)
	(arc
		(start 100.630482 -234.654344)
		(mid 100.354007 -234.721664)
		(end 100.07981 -234.645708)
		(width 0.0889)
		(layer "B.Cu")
		(net "SVID_CLK0_CPU1")
	)
	(arc
		(start 97.8154 -234.651804)
		(mid 97.537222 -234.721527)
		(end 97.260664 -234.645708)
		(width 0.0889)
		(layer "B.Cu")
		(net "SVID_CLK0_CPU1")
	)
	(arc
		(start 99.690682 -234.654344)
		(mid 99.414207 -234.721664)
		(end 99.14001 -234.645708)
		(width 0.0889)
		(layer "B.Cu")
		(net "SVID_CLK0_CPU1")
	)
	(arc
		(start 104.779318 -234.645962)
		(mid 104.59212 -234.595819)
		(end 104.404922 -234.645962)
		(width 0.0889)
		(layer "B.Cu")
		(net "SVID_CLK0_CPU1")
	)
	(arc
		(start 102.525322 -234.645962)
		(mid 102.251093 -234.721887)
		(end 101.97465 -234.654598)
		(width 0.0889)
		(layer "B.Cu")
		(net "SVID_CLK0_CPU1")
	)
	(arc
		(start 104.404922 -234.645962)
		(mid 104.130693 -234.721887)
		(end 103.85425 -234.654598)
		(width 0.0889)
		(layer "B.Cu")
		(net "SVID_CLK0_CPU1")
	)
	(arc
		(start 93.50121 -234.645708)
		(mid 93.314012 -234.595565)
		(end 93.126814 -234.645708)
		(width 0.0889)
		(layer "B.Cu")
		(net "SVID_CLK0_CPU1")
	)
	(arc
		(start 88.80221 -234.645708)
		(mid 88.615012 -234.595565)
		(end 88.427814 -234.645708)
		(width 0.0889)
		(layer "B.Cu")
		(net "SVID_CLK0_CPU1")
	)
	(arc
		(start 94.051882 -234.654344)
		(mid 93.775407 -234.721664)
		(end 93.50121 -234.645708)
		(width 0.0889)
		(layer "B.Cu")
		(net "SVID_CLK0_CPU1")
	)
	(arc
		(start 95.931482 -234.654344)
		(mid 95.655007 -234.721664)
		(end 95.38081 -234.645708)
		(width 0.0889)
		(layer "B.Cu")
		(net "SVID_CLK0_CPU1")
	)
	(arc
		(start 90.297254 -234.651804)
		(mid 90.018822 -234.72165)
		(end 89.74201 -234.645708)
		(width 0.0889)
		(layer "B.Cu")
		(net "SVID_CLK0_CPU1")
	)
	(arc
		(start 101.01961 -234.645708)
		(mid 100.832412 -234.595565)
		(end 100.645214 -234.645708)
		(width 0.0889)
		(layer "B.Cu")
		(net "SVID_CLK0_CPU1")
	)
	(arc
		(start 97.260664 -234.645708)
		(mid 97.073466 -234.595565)
		(end 96.886268 -234.645708)
		(width 0.0889)
		(layer "B.Cu")
		(net "SVID_CLK0_CPU1")
	)
	(arc
		(start 87.488522 -234.645962)
		(mid 87.214293 -234.721887)
		(end 86.93785 -234.654598)
		(width 0.0889)
		(layer "B.Cu")
		(net "SVID_CLK0_CPU1")
	)
	(arc
		(start 98.750882 -234.654344)
		(mid 98.474407 -234.721664)
		(end 98.20021 -234.645708)
		(width 0.0889)
		(layer "B.Cu")
		(net "SVID_CLK0_CPU1")
	)
	(arc
		(start 92.172282 -234.654344)
		(mid 91.895807 -234.721664)
		(end 91.62161 -234.645708)
		(width 0.0889)
		(layer "B.Cu")
		(net "SVID_CLK0_CPU1")
	)
	(arc
		(start 102.899718 -234.645962)
		(mid 102.71252 -234.595819)
		(end 102.525322 -234.645962)
		(width 0.0889)
		(layer "B.Cu")
		(net "SVID_CLK0_CPU1")
	)
	(arc
		(start 95.38081 -234.645708)
		(mid 95.193612 -234.595565)
		(end 95.006414 -234.645708)
		(width 0.0889)
		(layer "B.Cu")
		(net "SVID_CLK0_CPU1")
	)
	(arc
		(start 89.352882 -234.654344)
		(mid 89.076407 -234.721664)
		(end 88.80221 -234.645708)
		(width 0.0889)
		(layer "B.Cu")
		(net "SVID_CLK0_CPU1")
	)
	(arc
		(start 103.465122 -234.645962)
		(mid 103.190893 -234.721887)
		(end 102.91445 -234.654598)
		(width 0.0889)
		(layer "B.Cu")
		(net "SVID_CLK0_CPU1")
	)
	(arc
		(start 105.59415 -234.601004)
		(mid 105.465514 -234.601732)
		(end 105.344722 -234.645962)
		(width 0.0889)
		(layer "B.Cu")
		(net "SVID_CLK0_CPU1")
	)
	(arc
		(start 98.20021 -234.645708)
		(mid 98.013012 -234.595565)
		(end 97.825814 -234.645708)
		(width 0.0889)
		(layer "B.Cu")
		(net "SVID_CLK0_CPU1")
	)
	(arc
		(start 91.62161 -234.645708)
		(mid 91.434412 -234.595565)
		(end 91.247214 -234.645708)
		(width 0.0889)
		(layer "B.Cu")
		(net "SVID_CLK0_CPU1")
	)
	(arc
		(start 101.95941 -234.645708)
		(mid 101.772212 -234.595565)
		(end 101.585014 -234.645708)
		(width 0.0889)
		(layer "B.Cu")
		(net "SVID_CLK0_CPU1")
	)
	(arc
		(start 96.875854 -234.651804)
		(mid 96.597422 -234.72165)
		(end 96.32061 -234.645708)
		(width 0.0889)
		(layer "B.Cu")
		(net "SVID_CLK0_CPU1")
	)
	(arc
		(start 86.923118 -234.645962)
		(mid 86.73592 -234.595819)
		(end 86.548722 -234.645962)
		(width 0.0889)
		(layer "B.Cu")
		(net "SVID_CLK0_CPU1")
	)
	(arc
		(start 94.44101 -234.645708)
		(mid 94.253812 -234.595565)
		(end 94.066614 -234.645708)
		(width 0.0889)
		(layer "B.Cu")
		(net "SVID_CLK0_CPU1")
	)
	(arc
		(start 103.839518 -234.645962)
		(mid 103.65232 -234.595819)
		(end 103.465122 -234.645962)
		(width 0.0889)
		(layer "B.Cu")
		(net "SVID_CLK0_CPU1")
	)
	(arc
		(start 100.07981 -234.645708)
		(mid 99.892612 -234.595565)
		(end 99.705414 -234.645708)
		(width 0.0889)
		(layer "B.Cu")
		(net "SVID_CLK0_CPU1")
	)
	(arc
		(start 95.006414 -234.645708)
		(mid 94.723712 -234.721484)
		(end 94.44101 -234.645708)
		(width 0.0889)
		(layer "B.Cu")
		(net "SVID_CLK0_CPU1")
	)
	(arc
		(start 93.112082 -234.654344)
		(mid 92.835607 -234.721664)
		(end 92.56141 -234.645708)
		(width 0.0889)
		(layer "B.Cu")
		(net "SVID_CLK0_CPU1")
	)
	(arc
		(start 101.585014 -234.645708)
		(mid 101.302312 -234.721484)
		(end 101.01961 -234.645708)
		(width 0.0889)
		(layer "B.Cu")
		(net "SVID_CLK0_CPU1")
	)
	(arc
		(start 99.14001 -234.645708)
		(mid 98.952812 -234.595565)
		(end 98.765614 -234.645708)
		(width 0.0889)
		(layer "B.Cu")
		(net "SVID_CLK0_CPU1")
	)
	(arc
		(start 105.344722 -234.645962)
		(mid 105.070493 -234.721887)
		(end 104.79405 -234.654598)
		(width 0.0889)
		(layer "B.Cu")
		(net "SVID_CLK0_CPU1")
	)
	(arc
		(start 88.427814 -234.645708)
		(mid 88.291572 -234.702142)
		(end 88.145366 -234.7214)
		(width 0.0889)
		(layer "B.Cu")
		(net "SVID_CLK0_CPU1")
	)
	(arc
		(start 89.74201 -234.645708)
		(mid 89.554812 -234.595565)
		(end 89.367614 -234.645708)
		(width 0.0889)
		(layer "B.Cu")
		(net "SVID_CLK0_CPU1")
	)
	(arc
		(start 96.32061 -234.645708)
		(mid 96.133412 -234.595565)
		(end 95.946214 -234.645708)
		(width 0.0889)
		(layer "B.Cu")
		(net "SVID_CLK0_CPU1")
	)
	(arc
		(start 87.862918 -234.645962)
		(mid 87.67572 -234.595819)
		(end 87.488522 -234.645962)
		(width 0.0889)
		(layer "B.Cu")
		(net "SVID_CLK0_CPU1")
	)
	(arc
		(start 92.56141 -234.645708)
		(mid 92.374212 -234.595565)
		(end 92.187014 -234.645708)
		(width 0.0889)
		(layer "B.Cu")
		(net "SVID_CLK0_CPU1")
	)
	(arc
		(start 91.2368 -234.651804)
		(mid 90.958622 -234.721527)
		(end 90.682064 -234.645708)
		(width 0.0889)
		(layer "B.Cu")
		(net "SVID_CLK0_CPU1")
	)
	(segment
		(start 350.38411 -357.562658)
		(end 348.85884 -357.562658)
		(width 0.12954)
		(layer "F.Cu")
		(net "SVID_CLK0_CPU0_R")
	)
	(segment
		(start 431.000154 -136.822942)
		(end 431.22215 -137.044938)
		(width 0.12954)
		(layer "F.Cu")
		(net "SVID_CLK0_CPU0_R")
	)
	(segment
		(start 348.318074 -357.021892)
		(end 348.790514 -357.494332)
		(width 0.12954)
		(layer "F.Cu")
		(net "SVID_CLK0_CPU0_R")
	)
	(segment
		(start 434.176424 -137.450576)
		(end 433.770786 -137.044938)
		(width 0.12954)
		(layer "F.Cu")
		(net "SVID_CLK0_CPU0_R")
	)
	(segment
		(start 346.772738 -361.144566)
		(end 346.772738 -357.229918)
		(width 0.12954)
		(layer "F.Cu")
		(net "SVID_CLK0_CPU0_R")
	)
	(segment
		(start 348.0435 -364.16361)
		(end 348.55404 -363.65307)
		(width 0.12954)
		(layer "F.Cu")
		(net "SVID_CLK0_CPU0_R")
	)
	(segment
		(start 433.770786 -137.044938)
		(end 432.38928 -137.044938)
		(width 0.12954)
		(layer "F.Cu")
		(net "SVID_CLK0_CPU0_R")
	)
	(segment
		(start 431.22215 -137.044938)
		(end 432.38928 -137.044938)
		(width 0.12954)
		(layer "F.Cu")
		(net "SVID_CLK0_CPU0_R")
	)
	(segment
		(start 348.55404 -363.65307)
		(end 348.55404 -362.925868)
		(width 0.12954)
		(layer "F.Cu")
		(net "SVID_CLK0_CPU0_R")
	)
	(segment
		(start 348.85884 -357.562658)
		(end 348.790514 -357.494332)
		(width 0.12954)
		(layer "F.Cu")
		(net "SVID_CLK0_CPU0_R")
	)
	(segment
		(start 346.980764 -357.021892)
		(end 348.318074 -357.021892)
		(width 0.12954)
		(layer "F.Cu")
		(net "SVID_CLK0_CPU0_R")
	)
	(segment
		(start 431.000154 -136.526778)
		(end 431.000154 -136.822942)
		(width 0.12954)
		(layer "F.Cu")
		(net "SVID_CLK0_CPU0_R")
	)
	(segment
		(start 348.55404 -362.925868)
		(end 346.772738 -361.144566)
		(width 0.12954)
		(layer "F.Cu")
		(net "SVID_CLK0_CPU0_R")
	)
	(segment
		(start 346.772738 -357.229918)
		(end 346.980764 -357.021892)
		(width 0.12954)
		(layer "F.Cu")
		(net "SVID_CLK0_CPU0_R")
	)
	(via
		(at 434.176424 -137.450576)
		(size 0.508)
		(drill 0.254)
		(layers "F.Cu" "B.Cu")
		(net "SVID_CLK0_CPU0_R")
	)
	(via
		(at 348.0435 -364.16361)
		(size 0.508)
		(drill 0.254)
		(layers "F.Cu" "B.Cu")
		(net "SVID_CLK0_CPU0_R")
	)
	(via
		(at 305.3842 -191.506348)
		(size 0.508)
		(drill 0.254)
		(layers "F.Cu" "B.Cu")
		(net "SVID_CLK0_CPU0_R")
	)
	(segment
		(start 305.942238 -192.158366)
		(end 305.942238 -194.32016)
		(width 0.12954)
		(layer "B.Cu")
		(net "SVID_CLK0_CPU0_R")
	)
	(segment
		(start 305.3842 -191.600328)
		(end 305.942238 -192.158366)
		(width 0.12954)
		(layer "B.Cu")
		(net "SVID_CLK0_CPU0_R")
	)
	(segment
		(start 305.3842 -191.506348)
		(end 305.3842 -191.600328)
		(width 0.12954)
		(layer "B.Cu")
		(net "SVID_CLK0_CPU0_R")
	)
	(segment
		(start 465.235036 -334.221328)
		(end 436.415942 -363.040422)
		(width 0.127)
		(layer "In6.Cu")
		(net "SVID_CLK0_CPU0_R")
	)
	(segment
		(start 408.19324 -382.707134)
		(end 404.941024 -385.95935)
		(width 0.127)
		(layer "In6.Cu")
		(net "SVID_CLK0_CPU0_R")
	)
	(segment
		(start 427.54042 -381.927608)
		(end 426.760894 -382.707134)
		(width 0.127)
		(layer "In6.Cu")
		(net "SVID_CLK0_CPU0_R")
	)
	(segment
		(start 349.923862 -364.16361)
		(end 348.0435 -364.16361)
		(width 0.127)
		(layer "In6.Cu")
		(net "SVID_CLK0_CPU0_R")
	)
	(segment
		(start 427.54042 -380.106428)
		(end 427.54042 -381.927608)
		(width 0.127)
		(layer "In6.Cu")
		(net "SVID_CLK0_CPU0_R")
	)
	(segment
		(start 435.93258 -139.009628)
		(end 438.787032 -141.86408)
		(width 0.127)
		(layer "In6.Cu")
		(net "SVID_CLK0_CPU0_R")
	)
	(segment
		(start 350.742504 -382.007872)
		(end 350.742504 -364.982252)
		(width 0.127)
		(layer "In6.Cu")
		(net "SVID_CLK0_CPU0_R")
	)
	(segment
		(start 435.14518 -137.536428)
		(end 435.93258 -138.323828)
		(width 0.127)
		(layer "In6.Cu")
		(net "SVID_CLK0_CPU0_R")
	)
	(segment
		(start 390.099042 -385.95935)
		(end 388.646924 -384.507232)
		(width 0.127)
		(layer "In6.Cu")
		(net "SVID_CLK0_CPU0_R")
	)
	(segment
		(start 466.1408 -332.034388)
		(end 465.235036 -334.221328)
		(width 0.127)
		(layer "In6.Cu")
		(net "SVID_CLK0_CPU0_R")
	)
	(segment
		(start 436.415942 -363.040422)
		(end 436.415942 -371.230906)
		(width 0.127)
		(layer "In6.Cu")
		(net "SVID_CLK0_CPU0_R")
	)
	(segment
		(start 445.196976 -141.86408)
		(end 449.28028 -145.947384)
		(width 0.127)
		(layer "In6.Cu")
		(net "SVID_CLK0_CPU0_R")
	)
	(segment
		(start 388.646924 -384.507232)
		(end 353.241864 -384.507232)
		(width 0.127)
		(layer "In6.Cu")
		(net "SVID_CLK0_CPU0_R")
	)
	(segment
		(start 426.760894 -382.707134)
		(end 425.361354 -382.707134)
		(width 0.127)
		(layer "In6.Cu")
		(net "SVID_CLK0_CPU0_R")
	)
	(segment
		(start 436.415942 -371.230906)
		(end 428.05858 -379.588268)
		(width 0.127)
		(layer "In6.Cu")
		(net "SVID_CLK0_CPU0_R")
	)
	(segment
		(start 434.176424 -137.450576)
		(end 434.262276 -137.536428)
		(width 0.127)
		(layer "In6.Cu")
		(net "SVID_CLK0_CPU0_R")
	)
	(segment
		(start 350.742504 -364.982252)
		(end 349.923862 -364.16361)
		(width 0.127)
		(layer "In6.Cu")
		(net "SVID_CLK0_CPU0_R")
	)
	(segment
		(start 435.93258 -138.323828)
		(end 435.93258 -139.009628)
		(width 0.127)
		(layer "In6.Cu")
		(net "SVID_CLK0_CPU0_R")
	)
	(segment
		(start 466.1408 -178.656488)
		(end 466.1408 -332.034388)
		(width 0.127)
		(layer "In6.Cu")
		(net "SVID_CLK0_CPU0_R")
	)
	(segment
		(start 404.941024 -385.95935)
		(end 390.099042 -385.95935)
		(width 0.127)
		(layer "In6.Cu")
		(net "SVID_CLK0_CPU0_R")
	)
	(segment
		(start 438.787032 -141.86408)
		(end 445.196976 -141.86408)
		(width 0.127)
		(layer "In6.Cu")
		(net "SVID_CLK0_CPU0_R")
	)
	(segment
		(start 434.262276 -137.536428)
		(end 435.14518 -137.536428)
		(width 0.127)
		(layer "In6.Cu")
		(net "SVID_CLK0_CPU0_R")
	)
	(segment
		(start 449.28028 -145.947384)
		(end 449.28028 -161.795968)
		(width 0.127)
		(layer "In6.Cu")
		(net "SVID_CLK0_CPU0_R")
	)
	(segment
		(start 428.05858 -379.588268)
		(end 427.54042 -380.106428)
		(width 0.127)
		(layer "In6.Cu")
		(net "SVID_CLK0_CPU0_R")
	)
	(segment
		(start 449.28028 -161.795968)
		(end 466.1408 -178.656488)
		(width 0.127)
		(layer "In6.Cu")
		(net "SVID_CLK0_CPU0_R")
	)
	(segment
		(start 353.241864 -384.507232)
		(end 350.742504 -382.007872)
		(width 0.127)
		(layer "In6.Cu")
		(net "SVID_CLK0_CPU0_R")
	)
	(segment
		(start 425.361354 -382.707134)
		(end 408.19324 -382.707134)
		(width 0.127)
		(layer "In6.Cu")
		(net "SVID_CLK0_CPU0_R")
	)
	(segment
		(start 430.862994 -145.590768)
		(end 421.594026 -145.590768)
		(width 0.127)
		(layer "In13.Cu")
		(net "SVID_CLK0_CPU0_R")
	)
	(segment
		(start 395.53515 -148.958808)
		(end 395.36751 -149.126448)
		(width 0.127)
		(layer "In13.Cu")
		(net "SVID_CLK0_CPU0_R")
	)
	(segment
		(start 434.75656 -141.697202)
		(end 430.862994 -145.590768)
		(width 0.127)
		(layer "In13.Cu")
		(net "SVID_CLK0_CPU0_R")
	)
	(segment
		(start 349.16237 -149.126448)
		(end 348.18447 -150.104348)
		(width 0.127)
		(layer "In13.Cu")
		(net "SVID_CLK0_CPU0_R")
	)
	(segment
		(start 305.75758 -186.008518)
		(end 305.75758 -190.853568)
		(width 0.127)
		(layer "In13.Cu")
		(net "SVID_CLK0_CPU0_R")
	)
	(segment
		(start 421.378126 -145.374868)
		(end 401.995386 -145.374868)
		(width 0.127)
		(layer "In13.Cu")
		(net "SVID_CLK0_CPU0_R")
	)
	(segment
		(start 421.594026 -145.590768)
		(end 421.378126 -145.374868)
		(width 0.127)
		(layer "In13.Cu")
		(net "SVID_CLK0_CPU0_R")
	)
	(segment
		(start 434.75656 -138.030712)
		(end 434.75656 -141.697202)
		(width 0.127)
		(layer "In13.Cu")
		(net "SVID_CLK0_CPU0_R")
	)
	(segment
		(start 307.74767 -150.104348)
		(end 303.68748 -154.164538)
		(width 0.127)
		(layer "In13.Cu")
		(net "SVID_CLK0_CPU0_R")
	)
	(segment
		(start 395.36751 -149.126448)
		(end 349.16237 -149.126448)
		(width 0.127)
		(layer "In13.Cu")
		(net "SVID_CLK0_CPU0_R")
	)
	(segment
		(start 303.68748 -154.164538)
		(end 303.68748 -183.938418)
		(width 0.127)
		(layer "In13.Cu")
		(net "SVID_CLK0_CPU0_R")
	)
	(segment
		(start 305.3842 -191.226948)
		(end 305.3842 -191.506348)
		(width 0.127)
		(layer "In13.Cu")
		(net "SVID_CLK0_CPU0_R")
	)
	(segment
		(start 434.176424 -137.450576)
		(end 434.75656 -138.030712)
		(width 0.127)
		(layer "In13.Cu")
		(net "SVID_CLK0_CPU0_R")
	)
	(segment
		(start 348.18447 -150.104348)
		(end 307.74767 -150.104348)
		(width 0.127)
		(layer "In13.Cu")
		(net "SVID_CLK0_CPU0_R")
	)
	(segment
		(start 303.68748 -183.938418)
		(end 305.75758 -186.008518)
		(width 0.127)
		(layer "In13.Cu")
		(net "SVID_CLK0_CPU0_R")
	)
	(segment
		(start 398.411446 -148.958808)
		(end 395.53515 -148.958808)
		(width 0.127)
		(layer "In13.Cu")
		(net "SVID_CLK0_CPU0_R")
	)
	(segment
		(start 401.995386 -145.374868)
		(end 398.411446 -148.958808)
		(width 0.127)
		(layer "In13.Cu")
		(net "SVID_CLK0_CPU0_R")
	)
	(segment
		(start 305.75758 -190.853568)
		(end 305.3842 -191.226948)
		(width 0.127)
		(layer "In13.Cu")
		(net "SVID_CLK0_CPU0_R")
	)
	(segment
		(start 354.881434 -234.691936)
		(end 354.881434 -234.15625)
		(width 0.12954)
		(layer "F.Cu")
		(net "SVID_CLK0_CPU0")
	)
	(segment
		(start 354.88118 -234.69219)
		(end 354.881434 -234.691936)
		(width 0.12954)
		(layer "F.Cu")
		(net "SVID_CLK0_CPU0")
	)
	(via
		(at 320.265298 -237.65891)
		(size 0.6604)
		(drill 0.3302)
		(layers "F.Cu" "B.Cu")
		(net "SVID_CLK0_CPU0")
	)
	(via
		(at 354.881434 -234.15625)
		(size 0.4572)
		(drill 0.2032)
		(layers "F.Cu" "B.Cu")
		(net "SVID_CLK0_CPU0")
	)
	(segment
		(start 346.705682 -234.645708)
		(end 346.69095 -234.654344)
		(width 0.0889)
		(layer "B.Cu")
		(net "SVID_CLK0_CPU0")
	)
	(segment
		(start 311.128918 -237.46079)
		(end 310.920638 -237.66907)
		(width 0.12954)
		(layer "B.Cu")
		(net "SVID_CLK0_CPU0")
	)
	(segment
		(start 335.224628 -234.7214)
		(end 335.109058 -234.60583)
		(width 0.0889)
		(layer "B.Cu")
		(net "SVID_CLK0_CPU0")
	)
	(segment
		(start 308.456838 -237.06455)
		(end 307.499258 -237.06455)
		(width 0.12954)
		(layer "B.Cu")
		(net "SVID_CLK0_CPU0")
	)
	(segment
		(start 305.967638 -195.661788)
		(end 305.942238 -195.636388)
		(width 0.12954)
		(layer "B.Cu")
		(net "SVID_CLK0_CPU0")
	)
	(segment
		(start 336.085688 -234.7214)
		(end 335.224628 -234.7214)
		(width 0.0889)
		(layer "B.Cu")
		(net "SVID_CLK0_CPU0")
	)
	(segment
		(start 345.765882 -234.645708)
		(end 345.755468 -234.651804)
		(width 0.0889)
		(layer "B.Cu")
		(net "SVID_CLK0_CPU0")
	)
	(segment
		(start 337.307682 -234.645708)
		(end 337.29295 -234.654344)
		(width 0.0889)
		(layer "B.Cu")
		(net "SVID_CLK0_CPU0")
	)
	(segment
		(start 309.061358 -237.66907)
		(end 308.456838 -237.06455)
		(width 0.12954)
		(layer "B.Cu")
		(net "SVID_CLK0_CPU0")
	)
	(segment
		(start 353.940872 -234.57789)
		(end 352.636582 -234.57789)
		(width 0.0889)
		(layer "B.Cu")
		(net "SVID_CLK0_CPU0")
	)
	(segment
		(start 354.096828 -234.530646)
		(end 353.940872 -234.57789)
		(width 0.0889)
		(layer "B.Cu")
		(net "SVID_CLK0_CPU0")
	)
	(segment
		(start 312.310018 -237.65891)
		(end 312.111898 -237.46079)
		(width 0.12954)
		(layer "B.Cu")
		(net "SVID_CLK0_CPU0")
	)
	(segment
		(start 320.265298 -237.65891)
		(end 312.310018 -237.65891)
		(width 0.12954)
		(layer "B.Cu")
		(net "SVID_CLK0_CPU0")
	)
	(segment
		(start 330.109576 -235.988352)
		(end 328.439018 -237.65891)
		(width 0.12954)
		(layer "B.Cu")
		(net "SVID_CLK0_CPU0")
	)
	(segment
		(start 333.086456 -235.988352)
		(end 330.109576 -235.988352)
		(width 0.12954)
		(layer "B.Cu")
		(net "SVID_CLK0_CPU0")
	)
	(segment
		(start 338.247736 -234.645708)
		(end 338.237322 -234.651804)
		(width 0.0889)
		(layer "B.Cu")
		(net "SVID_CLK0_CPU0")
	)
	(segment
		(start 310.920638 -237.66907)
		(end 309.061358 -237.66907)
		(width 0.12954)
		(layer "B.Cu")
		(net "SVID_CLK0_CPU0")
	)
	(segment
		(start 333.816452 -235.258356)
		(end 333.086456 -235.988352)
		(width 0.12954)
		(layer "B.Cu")
		(net "SVID_CLK0_CPU0")
	)
	(segment
		(start 334.468978 -234.60583)
		(end 333.816452 -235.258356)
		(width 0.0889)
		(layer "B.Cu")
		(net "SVID_CLK0_CPU0")
	)
	(segment
		(start 339.187282 -234.645708)
		(end 339.176868 -234.651804)
		(width 0.0889)
		(layer "B.Cu")
		(net "SVID_CLK0_CPU0")
	)
	(segment
		(start 343.886282 -234.645708)
		(end 343.87155 -234.654344)
		(width 0.0889)
		(layer "B.Cu")
		(net "SVID_CLK0_CPU0")
	)
	(segment
		(start 340.127082 -234.645708)
		(end 340.11235 -234.654344)
		(width 0.0889)
		(layer "B.Cu")
		(net "SVID_CLK0_CPU0")
	)
	(segment
		(start 305.942238 -195.636388)
		(end 305.942238 -195.12026)
		(width 0.12954)
		(layer "B.Cu")
		(net "SVID_CLK0_CPU0")
	)
	(segment
		(start 354.881434 -234.15625)
		(end 354.471224 -234.15625)
		(width 0.0889)
		(layer "B.Cu")
		(net "SVID_CLK0_CPU0")
	)
	(segment
		(start 347.645482 -234.645708)
		(end 347.63075 -234.654344)
		(width 0.0889)
		(layer "B.Cu")
		(net "SVID_CLK0_CPU0")
	)
	(segment
		(start 354.471224 -234.15625)
		(end 354.096828 -234.530646)
		(width 0.0889)
		(layer "B.Cu")
		(net "SVID_CLK0_CPU0")
	)
	(segment
		(start 350.276922 -234.721654)
		(end 350.182434 -234.721654)
		(width 0.0889)
		(layer "B.Cu")
		(net "SVID_CLK0_CPU0")
	)
	(segment
		(start 348.585282 -234.645708)
		(end 348.57055 -234.654344)
		(width 0.0889)
		(layer "B.Cu")
		(net "SVID_CLK0_CPU0")
	)
	(segment
		(start 328.439018 -237.65891)
		(end 320.265298 -237.65891)
		(width 0.12954)
		(layer "B.Cu")
		(net "SVID_CLK0_CPU0")
	)
	(segment
		(start 352.636582 -234.57789)
		(end 352.45421 -234.760262)
		(width 0.0889)
		(layer "B.Cu")
		(net "SVID_CLK0_CPU0")
	)
	(segment
		(start 335.109058 -234.60583)
		(end 334.468978 -234.60583)
		(width 0.0889)
		(layer "B.Cu")
		(net "SVID_CLK0_CPU0")
	)
	(segment
		(start 341.066882 -234.645708)
		(end 341.05215 -234.654344)
		(width 0.0889)
		(layer "B.Cu")
		(net "SVID_CLK0_CPU0")
	)
	(segment
		(start 342.006682 -234.645708)
		(end 341.99195 -234.654344)
		(width 0.0889)
		(layer "B.Cu")
		(net "SVID_CLK0_CPU0")
	)
	(segment
		(start 307.499258 -237.06455)
		(end 305.967638 -235.53293)
		(width 0.12954)
		(layer "B.Cu")
		(net "SVID_CLK0_CPU0")
	)
	(segment
		(start 350.31553 -234.760262)
		(end 350.276922 -234.721654)
		(width 0.0889)
		(layer "B.Cu")
		(net "SVID_CLK0_CPU0")
	)
	(segment
		(start 352.45421 -234.760262)
		(end 350.31553 -234.760262)
		(width 0.0889)
		(layer "B.Cu")
		(net "SVID_CLK0_CPU0")
	)
	(segment
		(start 344.826336 -234.645708)
		(end 344.815922 -234.651804)
		(width 0.0889)
		(layer "B.Cu")
		(net "SVID_CLK0_CPU0")
	)
	(segment
		(start 305.967638 -235.53293)
		(end 305.967638 -195.661788)
		(width 0.12954)
		(layer "B.Cu")
		(net "SVID_CLK0_CPU0")
	)
	(segment
		(start 312.111898 -237.46079)
		(end 311.128918 -237.46079)
		(width 0.12954)
		(layer "B.Cu")
		(net "SVID_CLK0_CPU0")
	)
	(arc
		(start 338.622132 -234.645708)
		(mid 338.434934 -234.595565)
		(end 338.247736 -234.645708)
		(width 0.0889)
		(layer "B.Cu")
		(net "SVID_CLK0_CPU0")
	)
	(arc
		(start 337.682078 -234.645708)
		(mid 337.49488 -234.595565)
		(end 337.307682 -234.645708)
		(width 0.0889)
		(layer "B.Cu")
		(net "SVID_CLK0_CPU0")
	)
	(arc
		(start 344.260678 -234.645708)
		(mid 344.07348 -234.595565)
		(end 343.886282 -234.645708)
		(width 0.0889)
		(layer "B.Cu")
		(net "SVID_CLK0_CPU0")
	)
	(arc
		(start 343.320878 -234.645708)
		(mid 343.13368 -234.595565)
		(end 342.946482 -234.645708)
		(width 0.0889)
		(layer "B.Cu")
		(net "SVID_CLK0_CPU0")
	)
	(arc
		(start 336.742278 -234.645708)
		(mid 336.55508 -234.595565)
		(end 336.367882 -234.645708)
		(width 0.0889)
		(layer "B.Cu")
		(net "SVID_CLK0_CPU0")
	)
	(arc
		(start 339.561678 -234.645708)
		(mid 339.37448 -234.595565)
		(end 339.187282 -234.645708)
		(width 0.0889)
		(layer "B.Cu")
		(net "SVID_CLK0_CPU0")
	)
	(arc
		(start 348.019878 -234.645708)
		(mid 347.83268 -234.595565)
		(end 347.645482 -234.645708)
		(width 0.0889)
		(layer "B.Cu")
		(net "SVID_CLK0_CPU0")
	)
	(arc
		(start 344.815922 -234.651804)
		(mid 344.53749 -234.72165)
		(end 344.260678 -234.645708)
		(width 0.0889)
		(layer "B.Cu")
		(net "SVID_CLK0_CPU0")
	)
	(arc
		(start 338.237322 -234.651804)
		(mid 337.95889 -234.72165)
		(end 337.682078 -234.645708)
		(width 0.0889)
		(layer "B.Cu")
		(net "SVID_CLK0_CPU0")
	)
	(arc
		(start 349.899478 -234.645708)
		(mid 349.71228 -234.595565)
		(end 349.525082 -234.645708)
		(width 0.0889)
		(layer "B.Cu")
		(net "SVID_CLK0_CPU0")
	)
	(arc
		(start 336.12201 -234.720384)
		(mid 336.103857 -234.721187)
		(end 336.085688 -234.7214)
		(width 0.0889)
		(layer "B.Cu")
		(net "SVID_CLK0_CPU0")
	)
	(arc
		(start 349.525082 -234.645708)
		(mid 349.24238 -234.721484)
		(end 348.959678 -234.645708)
		(width 0.0889)
		(layer "B.Cu")
		(net "SVID_CLK0_CPU0")
	)
	(arc
		(start 341.441278 -234.645708)
		(mid 341.25408 -234.595565)
		(end 341.066882 -234.645708)
		(width 0.0889)
		(layer "B.Cu")
		(net "SVID_CLK0_CPU0")
	)
	(arc
		(start 347.63075 -234.654344)
		(mid 347.354275 -234.721664)
		(end 347.080078 -234.645708)
		(width 0.0889)
		(layer "B.Cu")
		(net "SVID_CLK0_CPU0")
	)
	(arc
		(start 342.381078 -234.645708)
		(mid 342.19388 -234.595565)
		(end 342.006682 -234.645708)
		(width 0.0889)
		(layer "B.Cu")
		(net "SVID_CLK0_CPU0")
	)
	(arc
		(start 345.200732 -234.645708)
		(mid 345.013534 -234.595565)
		(end 344.826336 -234.645708)
		(width 0.0889)
		(layer "B.Cu")
		(net "SVID_CLK0_CPU0")
	)
	(arc
		(start 348.959678 -234.645708)
		(mid 348.77248 -234.595565)
		(end 348.585282 -234.645708)
		(width 0.0889)
		(layer "B.Cu")
		(net "SVID_CLK0_CPU0")
	)
	(arc
		(start 345.755468 -234.651804)
		(mid 345.47729 -234.721527)
		(end 345.200732 -234.645708)
		(width 0.0889)
		(layer "B.Cu")
		(net "SVID_CLK0_CPU0")
	)
	(arc
		(start 341.99195 -234.654344)
		(mid 341.715475 -234.721664)
		(end 341.441278 -234.645708)
		(width 0.0889)
		(layer "B.Cu")
		(net "SVID_CLK0_CPU0")
	)
	(arc
		(start 350.182434 -234.721654)
		(mid 350.035947 -234.702339)
		(end 349.899478 -234.645708)
		(width 0.0889)
		(layer "B.Cu")
		(net "SVID_CLK0_CPU0")
	)
	(arc
		(start 343.87155 -234.654344)
		(mid 343.595075 -234.721664)
		(end 343.320878 -234.645708)
		(width 0.0889)
		(layer "B.Cu")
		(net "SVID_CLK0_CPU0")
	)
	(arc
		(start 341.05215 -234.654344)
		(mid 340.775675 -234.721664)
		(end 340.501478 -234.645708)
		(width 0.0889)
		(layer "B.Cu")
		(net "SVID_CLK0_CPU0")
	)
	(arc
		(start 348.57055 -234.654344)
		(mid 348.294075 -234.721664)
		(end 348.019878 -234.645708)
		(width 0.0889)
		(layer "B.Cu")
		(net "SVID_CLK0_CPU0")
	)
	(arc
		(start 339.176868 -234.651804)
		(mid 338.89869 -234.721527)
		(end 338.622132 -234.645708)
		(width 0.0889)
		(layer "B.Cu")
		(net "SVID_CLK0_CPU0")
	)
	(arc
		(start 336.367882 -234.645708)
		(mid 336.249251 -234.697228)
		(end 336.12201 -234.720384)
		(width 0.0889)
		(layer "B.Cu")
		(net "SVID_CLK0_CPU0")
	)
	(arc
		(start 342.946482 -234.645708)
		(mid 342.66378 -234.721484)
		(end 342.381078 -234.645708)
		(width 0.0889)
		(layer "B.Cu")
		(net "SVID_CLK0_CPU0")
	)
	(arc
		(start 346.140278 -234.645708)
		(mid 345.95308 -234.595565)
		(end 345.765882 -234.645708)
		(width 0.0889)
		(layer "B.Cu")
		(net "SVID_CLK0_CPU0")
	)
	(arc
		(start 340.501478 -234.645708)
		(mid 340.31428 -234.595565)
		(end 340.127082 -234.645708)
		(width 0.0889)
		(layer "B.Cu")
		(net "SVID_CLK0_CPU0")
	)
	(arc
		(start 337.29295 -234.654344)
		(mid 337.016475 -234.721664)
		(end 336.742278 -234.645708)
		(width 0.0889)
		(layer "B.Cu")
		(net "SVID_CLK0_CPU0")
	)
	(arc
		(start 347.080078 -234.645708)
		(mid 346.89288 -234.595565)
		(end 346.705682 -234.645708)
		(width 0.0889)
		(layer "B.Cu")
		(net "SVID_CLK0_CPU0")
	)
	(arc
		(start 340.11235 -234.654344)
		(mid 339.835875 -234.721664)
		(end 339.561678 -234.645708)
		(width 0.0889)
		(layer "B.Cu")
		(net "SVID_CLK0_CPU0")
	)
	(arc
		(start 346.69095 -234.654344)
		(mid 346.414475 -234.721664)
		(end 346.140278 -234.645708)
		(width 0.0889)
		(layer "B.Cu")
		(net "SVID_CLK0_CPU0")
	)
	(segment
		(start 105.273856 -357.048308)
		(end 105.70337 -357.048308)
		(width 0.12954)
		(layer "F.Cu")
		(net "SVID_ALERT_PVCCIN_CPU1_R")
	)
	(segment
		(start 105.074466 -356.848918)
		(end 105.273856 -357.048308)
		(width 0.12954)
		(layer "F.Cu")
		(net "SVID_ALERT_PVCCIN_CPU1_R")
	)
	(segment
		(start 103.245666 -355.773736)
		(end 103.376222 -355.773736)
		(width 0.12954)
		(layer "F.Cu")
		(net "SVID_ALERT_PVCCIN_CPU1_R")
	)
	(segment
		(start 103.376222 -355.773736)
		(end 103.86441 -356.261924)
		(width 0.12954)
		(layer "F.Cu")
		(net "SVID_ALERT_PVCCIN_CPU1_R")
	)
	(segment
		(start 104.662732 -356.261924)
		(end 105.074466 -356.673658)
		(width 0.12954)
		(layer "F.Cu")
		(net "SVID_ALERT_PVCCIN_CPU1_R")
	)
	(segment
		(start 103.86441 -356.261924)
		(end 104.662732 -356.261924)
		(width 0.12954)
		(layer "F.Cu")
		(net "SVID_ALERT_PVCCIN_CPU1_R")
	)
	(segment
		(start 105.074466 -356.673658)
		(end 105.074466 -356.848918)
		(width 0.12954)
		(layer "F.Cu")
		(net "SVID_ALERT_PVCCIN_CPU1_R")
	)
	(via
		(at 103.86441 -356.261924)
		(size 0.508)
		(drill 0.254)
		(layers "F.Cu" "B.Cu")
		(net "SVID_ALERT_PVCCIN_CPU1_R")
	)
	(segment
		(start 352.048064 -355.773736)
		(end 352.314764 -356.040436)
		(width 0.12954)
		(layer "F.Cu")
		(net "SVID_ALERT_PVCCIN_CPU0_R")
	)
	(segment
		(start 353.20859 -357.048308)
		(end 353.643184 -357.048308)
		(width 0.12954)
		(layer "F.Cu")
		(net "SVID_ALERT_PVCCIN_CPU0_R")
	)
	(segment
		(start 352.314764 -356.040436)
		(end 352.977704 -356.703376)
		(width 0.12954)
		(layer "F.Cu")
		(net "SVID_ALERT_PVCCIN_CPU0_R")
	)
	(segment
		(start 351.18548 -355.773736)
		(end 352.048064 -355.773736)
		(width 0.12954)
		(layer "F.Cu")
		(net "SVID_ALERT_PVCCIN_CPU0_R")
	)
	(segment
		(start 352.977704 -356.703376)
		(end 352.977704 -356.817422)
		(width 0.12954)
		(layer "F.Cu")
		(net "SVID_ALERT_PVCCIN_CPU0_R")
	)
	(segment
		(start 352.977704 -356.817422)
		(end 353.20859 -357.048308)
		(width 0.12954)
		(layer "F.Cu")
		(net "SVID_ALERT_PVCCIN_CPU0_R")
	)
	(via
		(at 352.314764 -356.040436)
		(size 0.508)
		(drill 0.254)
		(layers "F.Cu" "B.Cu")
		(net "SVID_ALERT_PVCCIN_CPU0_R")
	)
	(segment
		(start 35.19932 -131.03352)
		(end 35.344862 -131.179062)
		(width 0.12954)
		(layer "F.Cu")
		(net "SVID_ALERT_PVCCINFAON_CPU1_R")
	)
	(segment
		(start 35.344862 -131.179062)
		(end 35.95751 -131.179062)
		(width 0.12954)
		(layer "F.Cu")
		(net "SVID_ALERT_PVCCINFAON_CPU1_R")
	)
	(segment
		(start 35.95751 -131.179062)
		(end 36.556188 -131.77774)
		(width 0.12954)
		(layer "F.Cu")
		(net "SVID_ALERT_PVCCINFAON_CPU1_R")
	)
	(segment
		(start 34.461196 -131.03352)
		(end 35.19932 -131.03352)
		(width 0.12954)
		(layer "F.Cu")
		(net "SVID_ALERT_PVCCINFAON_CPU1_R")
	)
	(via
		(at 35.344862 -131.179062)
		(size 0.508)
		(drill 0.254)
		(layers "F.Cu" "B.Cu")
		(net "SVID_ALERT_PVCCINFAON_CPU1_R")
	)
	(segment
		(start 428.884588 -138.143996)
		(end 428.55515 -137.814558)
		(width 0.12954)
		(layer "F.Cu")
		(net "SVID_ALERT_PVCCINFAON_CPU0_R")
	)
	(segment
		(start 428.55515 -137.814558)
		(end 428.105062 -137.814558)
		(width 0.12954)
		(layer "F.Cu")
		(net "SVID_ALERT_PVCCINFAON_CPU0_R")
	)
	(segment
		(start 429.144176 -138.143996)
		(end 428.884588 -138.143996)
		(width 0.12954)
		(layer "F.Cu")
		(net "SVID_ALERT_PVCCINFAON_CPU0_R")
	)
	(segment
		(start 430.200054 -138.558778)
		(end 429.785272 -138.143996)
		(width 0.12954)
		(layer "F.Cu")
		(net "SVID_ALERT_PVCCINFAON_CPU0_R")
	)
	(segment
		(start 429.785272 -138.143996)
		(end 429.144176 -138.143996)
		(width 0.12954)
		(layer "F.Cu")
		(net "SVID_ALERT_PVCCINFAON_CPU0_R")
	)
	(via
		(at 429.144176 -138.143996)
		(size 0.508)
		(drill 0.254)
		(layers "F.Cu" "B.Cu")
		(net "SVID_ALERT_PVCCINFAON_CPU0_R")
	)
	(segment
		(start 23.009098 -163.719256)
		(end 22.53361 -163.719256)
		(width 0.12954)
		(layer "F.Cu")
		(net "SVID_ALERT_PVCCD_HV_CPU1_R")
	)
	(segment
		(start 23.120858 -163.392104)
		(end 23.120858 -163.607496)
		(width 0.12954)
		(layer "F.Cu")
		(net "SVID_ALERT_PVCCD_HV_CPU1_R")
	)
	(segment
		(start 24.416766 -163.052252)
		(end 23.46071 -163.052252)
		(width 0.12954)
		(layer "F.Cu")
		(net "SVID_ALERT_PVCCD_HV_CPU1_R")
	)
	(segment
		(start 23.46071 -163.052252)
		(end 23.120858 -163.392104)
		(width 0.12954)
		(layer "F.Cu")
		(net "SVID_ALERT_PVCCD_HV_CPU1_R")
	)
	(segment
		(start 25.26284 -163.427156)
		(end 24.79167 -163.427156)
		(width 0.12954)
		(layer "F.Cu")
		(net "SVID_ALERT_PVCCD_HV_CPU1_R")
	)
	(segment
		(start 23.120858 -163.607496)
		(end 23.009098 -163.719256)
		(width 0.12954)
		(layer "F.Cu")
		(net "SVID_ALERT_PVCCD_HV_CPU1_R")
	)
	(segment
		(start 24.79167 -163.427156)
		(end 24.416766 -163.052252)
		(width 0.12954)
		(layer "F.Cu")
		(net "SVID_ALERT_PVCCD_HV_CPU1_R")
	)
	(via
		(at 23.120858 -163.392104)
		(size 0.508)
		(drill 0.254)
		(layers "F.Cu" "B.Cu")
		(net "SVID_ALERT_PVCCD_HV_CPU1_R")
	)
	(segment
		(start 435.174136 -124.388626)
		(end 434.901086 -124.388626)
		(width 0.12954)
		(layer "F.Cu")
		(net "SVID_ALERT_PVCCD_HV_CPU0_R")
	)
	(segment
		(start 435.416198 -125.706378)
		(end 435.416198 -124.630688)
		(width 0.12954)
		(layer "F.Cu")
		(net "SVID_ALERT_PVCCD_HV_CPU0_R")
	)
	(segment
		(start 435.416198 -124.630688)
		(end 435.174136 -124.388626)
		(width 0.12954)
		(layer "F.Cu")
		(net "SVID_ALERT_PVCCD_HV_CPU0_R")
	)
	(segment
		(start 435.60873 -125.89891)
		(end 435.416198 -125.706378)
		(width 0.12954)
		(layer "F.Cu")
		(net "SVID_ALERT_PVCCD_HV_CPU0_R")
	)
	(segment
		(start 435.886098 -125.89891)
		(end 435.60873 -125.89891)
		(width 0.12954)
		(layer "F.Cu")
		(net "SVID_ALERT_PVCCD_HV_CPU0_R")
	)
	(segment
		(start 436.539132 -126.00051)
		(end 436.842916 -125.696726)
		(width 0.12954)
		(layer "F.Cu")
		(net "SVID_ALERT_PVCCD_HV_CPU0_R")
	)
	(segment
		(start 435.886098 -125.89891)
		(end 435.987698 -126.00051)
		(width 0.12954)
		(layer "F.Cu")
		(net "SVID_ALERT_PVCCD_HV_CPU0_R")
	)
	(segment
		(start 435.987698 -126.00051)
		(end 436.539132 -126.00051)
		(width 0.12954)
		(layer "F.Cu")
		(net "SVID_ALERT_PVCCD_HV_CPU0_R")
	)
	(via
		(at 435.886098 -125.89891)
		(size 0.508)
		(drill 0.254)
		(layers "F.Cu" "B.Cu")
		(net "SVID_ALERT_PVCCD_HV_CPU0_R")
	)
	(segment
		(start 21.304758 -163.185348)
		(end 21.73351 -163.6141)
		(width 0.12954)
		(layer "F.Cu")
		(net "SVID_ALERT1_CPU1_R_N")
	)
	(segment
		(start 20.5486 -163.185348)
		(end 21.304758 -163.185348)
		(width 0.12954)
		(layer "F.Cu")
		(net "SVID_ALERT1_CPU1_R_N")
	)
	(segment
		(start 21.73351 -163.6141)
		(end 21.73351 -163.719256)
		(width 0.12954)
		(layer "F.Cu")
		(net "SVID_ALERT1_CPU1_R_N")
	)
	(segment
		(start 20.3962 -163.032948)
		(end 20.5486 -163.185348)
		(width 0.12954)
		(layer "F.Cu")
		(net "SVID_ALERT1_CPU1_R_N")
	)
	(via
		(at 72.401684 -187.442856)
		(size 0.762)
		(drill 0.254)
		(layers "F.Cu" "B.Cu")
		(net "SVID_ALERT1_CPU1_R_N")
	)
	(via
		(at 20.3962 -163.032948)
		(size 0.508)
		(drill 0.254)
		(layers "F.Cu" "B.Cu")
		(net "SVID_ALERT1_CPU1_R_N")
	)
	(segment
		(start 72.401684 -188.058806)
		(end 72.401684 -187.442856)
		(width 0.12954)
		(layer "B.Cu")
		(net "SVID_ALERT1_CPU1_R_N")
	)
	(segment
		(start 72.401684 -187.442856)
		(end 71.385684 -186.426856)
		(width 0.12954)
		(layer "B.Cu")
		(net "SVID_ALERT1_CPU1_R_N")
	)
	(segment
		(start 71.385684 -186.426856)
		(end 71.385684 -186.191906)
		(width 0.12954)
		(layer "B.Cu")
		(net "SVID_ALERT1_CPU1_R_N")
	)
	(segment
		(start 72.9615 -190.000128)
		(end 72.9615 -188.002672)
		(width 0.127)
		(layer "In13.Cu")
		(net "SVID_ALERT1_CPU1_R_N")
	)
	(segment
		(start 72.617838 -190.34379)
		(end 72.9615 -190.000128)
		(width 0.127)
		(layer "In13.Cu")
		(net "SVID_ALERT1_CPU1_R_N")
	)
	(segment
		(start 14.0716 -169.007028)
		(end 14.0716 -182.466488)
		(width 0.127)
		(layer "In13.Cu")
		(net "SVID_ALERT1_CPU1_R_N")
	)
	(segment
		(start 14.15415 -168.924732)
		(end 14.153896 -168.924732)
		(width 0.127)
		(layer "In13.Cu")
		(net "SVID_ALERT1_CPU1_R_N")
	)
	(segment
		(start 14.0716 -182.466488)
		(end 16.99768 -185.392568)
		(width 0.127)
		(layer "In13.Cu")
		(net "SVID_ALERT1_CPU1_R_N")
	)
	(segment
		(start 16.99768 -185.392568)
		(end 62.2935 -185.392568)
		(width 0.127)
		(layer "In13.Cu")
		(net "SVID_ALERT1_CPU1_R_N")
	)
	(segment
		(start 20.3962 -163.032948)
		(end 20.045934 -163.032948)
		(width 0.127)
		(layer "In13.Cu")
		(net "SVID_ALERT1_CPU1_R_N")
	)
	(segment
		(start 62.2935 -185.392568)
		(end 67.244722 -190.34379)
		(width 0.127)
		(layer "In13.Cu")
		(net "SVID_ALERT1_CPU1_R_N")
	)
	(segment
		(start 20.045934 -163.032948)
		(end 14.15415 -168.924732)
		(width 0.127)
		(layer "In13.Cu")
		(net "SVID_ALERT1_CPU1_R_N")
	)
	(segment
		(start 14.153896 -168.924732)
		(end 14.0716 -169.007028)
		(width 0.127)
		(layer "In13.Cu")
		(net "SVID_ALERT1_CPU1_R_N")
	)
	(segment
		(start 72.9615 -188.002672)
		(end 72.401684 -187.442856)
		(width 0.127)
		(layer "In13.Cu")
		(net "SVID_ALERT1_CPU1_R_N")
	)
	(segment
		(start 67.244722 -190.34379)
		(end 72.617838 -190.34379)
		(width 0.127)
		(layer "In13.Cu")
		(net "SVID_ALERT1_CPU1_R_N")
	)
	(segment
		(start 107.411266 -233.87812)
		(end 107.411266 -233.342434)
		(width 0.12954)
		(layer "F.Cu")
		(net "SVID_ALERT1_CPU1_N")
	)
	(segment
		(start 107.411266 -233.342434)
		(end 107.411012 -233.34218)
		(width 0.12954)
		(layer "F.Cu")
		(net "SVID_ALERT1_CPU1_N")
	)
	(via
		(at 72.192642 -199.370188)
		(size 0.6604)
		(drill 0.3302)
		(layers "F.Cu" "B.Cu")
		(net "SVID_ALERT1_CPU1_N")
	)
	(via
		(at 107.411012 -233.34218)
		(size 0.4572)
		(drill 0.2032)
		(layers "F.Cu" "B.Cu")
		(net "SVID_ALERT1_CPU1_N")
	)
	(segment
		(start 104.404414 -233.666538)
		(end 104.389682 -233.657902)
		(width 0.0889)
		(layer "B.Cu")
		(net "SVID_ALERT1_CPU1_N")
	)
	(segment
		(start 98.765614 -233.666538)
		(end 98.7552 -233.660442)
		(width 0.0889)
		(layer "B.Cu")
		(net "SVID_ALERT1_CPU1_N")
	)
	(segment
		(start 78.368906 -234.807506)
		(end 69.117718 -225.556318)
		(width 0.12954)
		(layer "B.Cu")
		(net "SVID_ALERT1_CPU1_N")
	)
	(segment
		(start 67.806316 -221.2848)
		(end 67.806316 -206.411576)
		(width 0.12954)
		(layer "B.Cu")
		(net "SVID_ALERT1_CPU1_N")
	)
	(segment
		(start 72.192642 -199.370188)
		(end 72.785478 -198.777352)
		(width 0.12954)
		(layer "B.Cu")
		(net "SVID_ALERT1_CPU1_N")
	)
	(segment
		(start 107.411012 -233.34218)
		(end 107.723686 -233.34218)
		(width 0.0889)
		(layer "B.Cu")
		(net "SVID_ALERT1_CPU1_N")
	)
	(segment
		(start 107.223814 -233.666538)
		(end 107.209082 -233.657902)
		(width 0.0889)
		(layer "B.Cu")
		(net "SVID_ALERT1_CPU1_N")
	)
	(segment
		(start 96.886014 -233.666538)
		(end 96.871282 -233.657902)
		(width 0.0889)
		(layer "B.Cu")
		(net "SVID_ALERT1_CPU1_N")
	)
	(segment
		(start 94.066614 -233.666538)
		(end 94.051882 -233.657902)
		(width 0.0889)
		(layer "B.Cu")
		(net "SVID_ALERT1_CPU1_N")
	)
	(segment
		(start 99.705414 -233.666538)
		(end 99.690682 -233.657902)
		(width 0.0889)
		(layer "B.Cu")
		(net "SVID_ALERT1_CPU1_N")
	)
	(segment
		(start 83.520026 -234.807506)
		(end 78.368906 -234.807506)
		(width 0.12954)
		(layer "B.Cu")
		(net "SVID_ALERT1_CPU1_N")
	)
	(segment
		(start 69.117718 -225.556318)
		(end 69.117718 -222.596202)
		(width 0.12954)
		(layer "B.Cu")
		(net "SVID_ALERT1_CPU1_N")
	)
	(segment
		(start 69.117718 -222.596202)
		(end 67.806316 -221.2848)
		(width 0.12954)
		(layer "B.Cu")
		(net "SVID_ALERT1_CPU1_N")
	)
	(segment
		(start 91.247468 -233.666538)
		(end 91.237054 -233.660442)
		(width 0.0889)
		(layer "B.Cu")
		(net "SVID_ALERT1_CPU1_N")
	)
	(segment
		(start 68.92544 -205.292452)
		(end 68.92544 -203.901294)
		(width 0.12954)
		(layer "B.Cu")
		(net "SVID_ALERT1_CPU1_N")
	)
	(segment
		(start 103.464614 -233.666538)
		(end 103.449882 -233.657902)
		(width 0.0889)
		(layer "B.Cu")
		(net "SVID_ALERT1_CPU1_N")
	)
	(segment
		(start 71.283068 -200.279762)
		(end 72.192642 -199.370188)
		(width 0.12954)
		(layer "B.Cu")
		(net "SVID_ALERT1_CPU1_N")
	)
	(segment
		(start 90.307414 -233.666538)
		(end 90.292682 -233.657902)
		(width 0.0889)
		(layer "B.Cu")
		(net "SVID_ALERT1_CPU1_N")
	)
	(segment
		(start 72.753728 -189.21095)
		(end 72.401684 -188.858906)
		(width 0.12954)
		(layer "B.Cu")
		(net "SVID_ALERT1_CPU1_N")
	)
	(segment
		(start 85.783166 -233.608626)
		(end 84.584286 -234.807506)
		(width 0.0889)
		(layer "B.Cu")
		(net "SVID_ALERT1_CPU1_N")
	)
	(segment
		(start 93.126814 -233.666538)
		(end 93.112082 -233.657902)
		(width 0.0889)
		(layer "B.Cu")
		(net "SVID_ALERT1_CPU1_N")
	)
	(segment
		(start 92.187014 -233.666538)
		(end 92.1766 -233.660442)
		(width 0.0889)
		(layer "B.Cu")
		(net "SVID_ALERT1_CPU1_N")
	)
	(segment
		(start 67.806316 -206.411576)
		(end 68.92544 -205.292452)
		(width 0.12954)
		(layer "B.Cu")
		(net "SVID_ALERT1_CPU1_N")
	)
	(segment
		(start 88.427814 -233.666538)
		(end 88.4174 -233.660442)
		(width 0.0889)
		(layer "B.Cu")
		(net "SVID_ALERT1_CPU1_N")
	)
	(segment
		(start 73.821798 -191.842644)
		(end 73.821798 -190.141606)
		(width 0.12954)
		(layer "B.Cu")
		(net "SVID_ALERT1_CPU1_N")
	)
	(segment
		(start 84.584286 -234.807506)
		(end 83.520026 -234.807506)
		(width 0.0889)
		(layer "B.Cu")
		(net "SVID_ALERT1_CPU1_N")
	)
	(segment
		(start 105.344214 -233.666538)
		(end 105.329482 -233.657902)
		(width 0.0889)
		(layer "B.Cu")
		(net "SVID_ALERT1_CPU1_N")
	)
	(segment
		(start 68.92544 -203.901294)
		(end 71.283068 -201.543666)
		(width 0.12954)
		(layer "B.Cu")
		(net "SVID_ALERT1_CPU1_N")
	)
	(segment
		(start 97.826068 -233.666538)
		(end 97.815654 -233.660442)
		(width 0.0889)
		(layer "B.Cu")
		(net "SVID_ALERT1_CPU1_N")
	)
	(segment
		(start 87.675466 -233.717338)
		(end 87.495126 -233.717338)
		(width 0.0889)
		(layer "B.Cu")
		(net "SVID_ALERT1_CPU1_N")
	)
	(segment
		(start 87.386414 -233.608626)
		(end 85.783166 -233.608626)
		(width 0.0889)
		(layer "B.Cu")
		(net "SVID_ALERT1_CPU1_N")
	)
	(segment
		(start 100.645214 -233.666538)
		(end 100.630482 -233.657902)
		(width 0.0889)
		(layer "B.Cu")
		(net "SVID_ALERT1_CPU1_N")
	)
	(segment
		(start 72.785478 -192.878964)
		(end 73.821798 -191.842644)
		(width 0.12954)
		(layer "B.Cu")
		(net "SVID_ALERT1_CPU1_N")
	)
	(segment
		(start 95.946214 -233.666538)
		(end 95.931482 -233.657902)
		(width 0.0889)
		(layer "B.Cu")
		(net "SVID_ALERT1_CPU1_N")
	)
	(segment
		(start 106.284014 -233.666538)
		(end 106.269282 -233.657902)
		(width 0.0889)
		(layer "B.Cu")
		(net "SVID_ALERT1_CPU1_N")
	)
	(segment
		(start 73.821798 -190.141606)
		(end 72.891142 -189.21095)
		(width 0.12954)
		(layer "B.Cu")
		(net "SVID_ALERT1_CPU1_N")
	)
	(segment
		(start 89.367614 -233.666538)
		(end 89.352882 -233.657902)
		(width 0.0889)
		(layer "B.Cu")
		(net "SVID_ALERT1_CPU1_N")
	)
	(segment
		(start 102.524814 -233.666538)
		(end 102.510082 -233.657902)
		(width 0.0889)
		(layer "B.Cu")
		(net "SVID_ALERT1_CPU1_N")
	)
	(segment
		(start 107.723686 -233.34218)
		(end 107.78109 -233.399584)
		(width 0.0889)
		(layer "B.Cu")
		(net "SVID_ALERT1_CPU1_N")
	)
	(segment
		(start 72.891142 -189.21095)
		(end 72.753728 -189.21095)
		(width 0.12954)
		(layer "B.Cu")
		(net "SVID_ALERT1_CPU1_N")
	)
	(segment
		(start 87.495126 -233.717338)
		(end 87.386414 -233.608626)
		(width 0.0889)
		(layer "B.Cu")
		(net "SVID_ALERT1_CPU1_N")
	)
	(segment
		(start 71.283068 -201.543666)
		(end 71.283068 -200.279762)
		(width 0.12954)
		(layer "B.Cu")
		(net "SVID_ALERT1_CPU1_N")
	)
	(segment
		(start 72.785478 -198.777352)
		(end 72.785478 -192.878964)
		(width 0.12954)
		(layer "B.Cu")
		(net "SVID_ALERT1_CPU1_N")
	)
	(arc
		(start 93.50121 -233.666538)
		(mid 93.314012 -233.716681)
		(end 93.126814 -233.666538)
		(width 0.0889)
		(layer "B.Cu")
		(net "SVID_ALERT1_CPU1_N")
	)
	(arc
		(start 91.237054 -233.660442)
		(mid 90.958622 -233.590628)
		(end 90.68181 -233.666538)
		(width 0.0889)
		(layer "B.Cu")
		(net "SVID_ALERT1_CPU1_N")
	)
	(arc
		(start 99.14001 -233.666538)
		(mid 98.952812 -233.716681)
		(end 98.765614 -233.666538)
		(width 0.0889)
		(layer "B.Cu")
		(net "SVID_ALERT1_CPU1_N")
	)
	(arc
		(start 90.68181 -233.666538)
		(mid 90.494612 -233.716681)
		(end 90.307414 -233.666538)
		(width 0.0889)
		(layer "B.Cu")
		(net "SVID_ALERT1_CPU1_N")
	)
	(arc
		(start 105.329482 -233.657902)
		(mid 105.053041 -233.590736)
		(end 104.77881 -233.666538)
		(width 0.0889)
		(layer "B.Cu")
		(net "SVID_ALERT1_CPU1_N")
	)
	(arc
		(start 93.112082 -233.657902)
		(mid 92.835641 -233.590736)
		(end 92.56141 -233.666538)
		(width 0.0889)
		(layer "B.Cu")
		(net "SVID_ALERT1_CPU1_N")
	)
	(arc
		(start 100.630482 -233.657902)
		(mid 100.354041 -233.590736)
		(end 100.07981 -233.666538)
		(width 0.0889)
		(layer "B.Cu")
		(net "SVID_ALERT1_CPU1_N")
	)
	(arc
		(start 101.01961 -233.666538)
		(mid 100.832412 -233.716681)
		(end 100.645214 -233.666538)
		(width 0.0889)
		(layer "B.Cu")
		(net "SVID_ALERT1_CPU1_N")
	)
	(arc
		(start 103.449882 -233.657902)
		(mid 103.173441 -233.590736)
		(end 102.89921 -233.666538)
		(width 0.0889)
		(layer "B.Cu")
		(net "SVID_ALERT1_CPU1_N")
	)
	(arc
		(start 96.871282 -233.657902)
		(mid 96.594841 -233.590736)
		(end 96.32061 -233.666538)
		(width 0.0889)
		(layer "B.Cu")
		(net "SVID_ALERT1_CPU1_N")
	)
	(arc
		(start 98.7552 -233.660442)
		(mid 98.477022 -233.59075)
		(end 98.200464 -233.666538)
		(width 0.0889)
		(layer "B.Cu")
		(net "SVID_ALERT1_CPU1_N")
	)
	(arc
		(start 95.931482 -233.657902)
		(mid 95.655041 -233.590736)
		(end 95.38081 -233.666538)
		(width 0.0889)
		(layer "B.Cu")
		(net "SVID_ALERT1_CPU1_N")
	)
	(arc
		(start 89.74201 -233.666538)
		(mid 89.554812 -233.716681)
		(end 89.367614 -233.666538)
		(width 0.0889)
		(layer "B.Cu")
		(net "SVID_ALERT1_CPU1_N")
	)
	(arc
		(start 104.77881 -233.666538)
		(mid 104.591612 -233.716681)
		(end 104.404414 -233.666538)
		(width 0.0889)
		(layer "B.Cu")
		(net "SVID_ALERT1_CPU1_N")
	)
	(arc
		(start 105.71861 -233.666538)
		(mid 105.531412 -233.716681)
		(end 105.344214 -233.666538)
		(width 0.0889)
		(layer "B.Cu")
		(net "SVID_ALERT1_CPU1_N")
	)
	(arc
		(start 92.56141 -233.666538)
		(mid 92.374212 -233.716681)
		(end 92.187014 -233.666538)
		(width 0.0889)
		(layer "B.Cu")
		(net "SVID_ALERT1_CPU1_N")
	)
	(arc
		(start 95.38081 -233.666538)
		(mid 95.193612 -233.716681)
		(end 95.006414 -233.666538)
		(width 0.0889)
		(layer "B.Cu")
		(net "SVID_ALERT1_CPU1_N")
	)
	(arc
		(start 89.352882 -233.657902)
		(mid 89.076441 -233.590736)
		(end 88.80221 -233.666538)
		(width 0.0889)
		(layer "B.Cu")
		(net "SVID_ALERT1_CPU1_N")
	)
	(arc
		(start 91.621864 -233.666538)
		(mid 91.434666 -233.716681)
		(end 91.247468 -233.666538)
		(width 0.0889)
		(layer "B.Cu")
		(net "SVID_ALERT1_CPU1_N")
	)
	(arc
		(start 90.292682 -233.657902)
		(mid 90.016241 -233.590736)
		(end 89.74201 -233.666538)
		(width 0.0889)
		(layer "B.Cu")
		(net "SVID_ALERT1_CPU1_N")
	)
	(arc
		(start 104.389682 -233.657902)
		(mid 104.113241 -233.590736)
		(end 103.83901 -233.666538)
		(width 0.0889)
		(layer "B.Cu")
		(net "SVID_ALERT1_CPU1_N")
	)
	(arc
		(start 101.585014 -233.666538)
		(mid 101.302312 -233.590796)
		(end 101.01961 -233.666538)
		(width 0.0889)
		(layer "B.Cu")
		(net "SVID_ALERT1_CPU1_N")
	)
	(arc
		(start 100.07981 -233.666538)
		(mid 99.892612 -233.716681)
		(end 99.705414 -233.666538)
		(width 0.0889)
		(layer "B.Cu")
		(net "SVID_ALERT1_CPU1_N")
	)
	(arc
		(start 92.1766 -233.660442)
		(mid 91.898422 -233.59075)
		(end 91.621864 -233.666538)
		(width 0.0889)
		(layer "B.Cu")
		(net "SVID_ALERT1_CPU1_N")
	)
	(arc
		(start 107.209082 -233.657902)
		(mid 106.932641 -233.590736)
		(end 106.65841 -233.666538)
		(width 0.0889)
		(layer "B.Cu")
		(net "SVID_ALERT1_CPU1_N")
	)
	(arc
		(start 94.44101 -233.666538)
		(mid 94.253812 -233.716681)
		(end 94.066614 -233.666538)
		(width 0.0889)
		(layer "B.Cu")
		(net "SVID_ALERT1_CPU1_N")
	)
	(arc
		(start 96.32061 -233.666538)
		(mid 96.133412 -233.716681)
		(end 95.946214 -233.666538)
		(width 0.0889)
		(layer "B.Cu")
		(net "SVID_ALERT1_CPU1_N")
	)
	(arc
		(start 88.4174 -233.660442)
		(mid 88.139222 -233.59075)
		(end 87.862664 -233.666538)
		(width 0.0889)
		(layer "B.Cu")
		(net "SVID_ALERT1_CPU1_N")
	)
	(arc
		(start 106.269282 -233.657902)
		(mid 105.992841 -233.590736)
		(end 105.71861 -233.666538)
		(width 0.0889)
		(layer "B.Cu")
		(net "SVID_ALERT1_CPU1_N")
	)
	(arc
		(start 97.815654 -233.660442)
		(mid 97.537222 -233.590628)
		(end 97.26041 -233.666538)
		(width 0.0889)
		(layer "B.Cu")
		(net "SVID_ALERT1_CPU1_N")
	)
	(arc
		(start 95.006414 -233.666538)
		(mid 94.723712 -233.590796)
		(end 94.44101 -233.666538)
		(width 0.0889)
		(layer "B.Cu")
		(net "SVID_ALERT1_CPU1_N")
	)
	(arc
		(start 98.200464 -233.666538)
		(mid 98.013266 -233.716681)
		(end 97.826068 -233.666538)
		(width 0.0889)
		(layer "B.Cu")
		(net "SVID_ALERT1_CPU1_N")
	)
	(arc
		(start 87.862664 -233.666538)
		(mid 87.772408 -233.70426)
		(end 87.675466 -233.717338)
		(width 0.0889)
		(layer "B.Cu")
		(net "SVID_ALERT1_CPU1_N")
	)
	(arc
		(start 101.95941 -233.666538)
		(mid 101.772212 -233.716681)
		(end 101.585014 -233.666538)
		(width 0.0889)
		(layer "B.Cu")
		(net "SVID_ALERT1_CPU1_N")
	)
	(arc
		(start 88.80221 -233.666538)
		(mid 88.615012 -233.716681)
		(end 88.427814 -233.666538)
		(width 0.0889)
		(layer "B.Cu")
		(net "SVID_ALERT1_CPU1_N")
	)
	(arc
		(start 102.510082 -233.657902)
		(mid 102.233641 -233.590736)
		(end 101.95941 -233.666538)
		(width 0.0889)
		(layer "B.Cu")
		(net "SVID_ALERT1_CPU1_N")
	)
	(arc
		(start 103.83901 -233.666538)
		(mid 103.651812 -233.716681)
		(end 103.464614 -233.666538)
		(width 0.0889)
		(layer "B.Cu")
		(net "SVID_ALERT1_CPU1_N")
	)
	(arc
		(start 106.65841 -233.666538)
		(mid 106.471212 -233.716681)
		(end 106.284014 -233.666538)
		(width 0.0889)
		(layer "B.Cu")
		(net "SVID_ALERT1_CPU1_N")
	)
	(arc
		(start 94.051882 -233.657902)
		(mid 93.775441 -233.590736)
		(end 93.50121 -233.666538)
		(width 0.0889)
		(layer "B.Cu")
		(net "SVID_ALERT1_CPU1_N")
	)
	(arc
		(start 102.89921 -233.666538)
		(mid 102.712012 -233.716681)
		(end 102.524814 -233.666538)
		(width 0.0889)
		(layer "B.Cu")
		(net "SVID_ALERT1_CPU1_N")
	)
	(arc
		(start 97.26041 -233.666538)
		(mid 97.073212 -233.716681)
		(end 96.886014 -233.666538)
		(width 0.0889)
		(layer "B.Cu")
		(net "SVID_ALERT1_CPU1_N")
	)
	(arc
		(start 99.690682 -233.657902)
		(mid 99.414241 -233.590736)
		(end 99.14001 -233.666538)
		(width 0.0889)
		(layer "B.Cu")
		(net "SVID_ALERT1_CPU1_N")
	)
	(arc
		(start 107.78109 -233.399584)
		(mid 107.572807 -233.67993)
		(end 107.223814 -233.666538)
		(width 0.0889)
		(layer "B.Cu")
		(net "SVID_ALERT1_CPU1_N")
	)
	(segment
		(start 443.40272 -125.891036)
		(end 443.40272 -121.265188)
		(width 0.12954)
		(layer "F.Cu")
		(net "SVID_ALERT1_CPU0_R_N")
	)
	(segment
		(start 309.543704 -177.556668)
		(end 306.045108 -181.055264)
		(width 0.12954)
		(layer "F.Cu")
		(net "SVID_ALERT1_CPU0_R_N")
	)
	(segment
		(start 338.81314 -130.825748)
		(end 332.91526 -136.723628)
		(width 0.12954)
		(layer "F.Cu")
		(net "SVID_ALERT1_CPU0_R_N")
	)
	(segment
		(start 443.40272 -121.265188)
		(end 441.96508 -119.827548)
		(width 0.12954)
		(layer "F.Cu")
		(net "SVID_ALERT1_CPU0_R_N")
	)
	(segment
		(start 306.045108 -181.055264)
		(end 306.045108 -190.16853)
		(width 0.12954)
		(layer "F.Cu")
		(net "SVID_ALERT1_CPU0_R_N")
	)
	(segment
		(start 438.991502 -127.045212)
		(end 440.69254 -127.045212)
		(width 0.12954)
		(layer "F.Cu")
		(net "SVID_ALERT1_CPU0_R_N")
	)
	(segment
		(start 332.91526 -136.723628)
		(end 332.91526 -162.65144)
		(width 0.12954)
		(layer "F.Cu")
		(net "SVID_ALERT1_CPU0_R_N")
	)
	(segment
		(start 332.91526 -162.65144)
		(end 318.010032 -177.556668)
		(width 0.12954)
		(layer "F.Cu")
		(net "SVID_ALERT1_CPU0_R_N")
	)
	(segment
		(start 439.916316 -113.777268)
		(end 426.665644 -113.777268)
		(width 0.12954)
		(layer "F.Cu")
		(net "SVID_ALERT1_CPU0_R_N")
	)
	(segment
		(start 409.617164 -130.825748)
		(end 338.81314 -130.825748)
		(width 0.12954)
		(layer "F.Cu")
		(net "SVID_ALERT1_CPU0_R_N")
	)
	(segment
		(start 441.96508 -119.827548)
		(end 441.96508 -115.826032)
		(width 0.12954)
		(layer "F.Cu")
		(net "SVID_ALERT1_CPU0_R_N")
	)
	(segment
		(start 426.665644 -113.777268)
		(end 409.617164 -130.825748)
		(width 0.12954)
		(layer "F.Cu")
		(net "SVID_ALERT1_CPU0_R_N")
	)
	(segment
		(start 440.69254 -127.045212)
		(end 442.248544 -127.045212)
		(width 0.12954)
		(layer "F.Cu")
		(net "SVID_ALERT1_CPU0_R_N")
	)
	(segment
		(start 437.643016 -125.696726)
		(end 438.991502 -127.045212)
		(width 0.12954)
		(layer "F.Cu")
		(net "SVID_ALERT1_CPU0_R_N")
	)
	(segment
		(start 442.248544 -127.045212)
		(end 443.40272 -125.891036)
		(width 0.12954)
		(layer "F.Cu")
		(net "SVID_ALERT1_CPU0_R_N")
	)
	(segment
		(start 306.045108 -190.16853)
		(end 307.413152 -191.536574)
		(width 0.12954)
		(layer "F.Cu")
		(net "SVID_ALERT1_CPU0_R_N")
	)
	(segment
		(start 318.010032 -177.556668)
		(end 309.543704 -177.556668)
		(width 0.12954)
		(layer "F.Cu")
		(net "SVID_ALERT1_CPU0_R_N")
	)
	(segment
		(start 441.96508 -115.826032)
		(end 439.916316 -113.777268)
		(width 0.12954)
		(layer "F.Cu")
		(net "SVID_ALERT1_CPU0_R_N")
	)
	(via
		(at 307.413152 -191.536574)
		(size 0.508)
		(drill 0.254)
		(layers "F.Cu" "B.Cu")
		(net "SVID_ALERT1_CPU0_R_N")
	)
	(via
		(at 440.69254 -127.045212)
		(size 0.762)
		(drill 0.381)
		(layers "F.Cu" "B.Cu")
		(net "SVID_ALERT1_CPU0_R_N")
	)
	(segment
		(start 308.085998 -192.20942)
		(end 307.413152 -191.536574)
		(width 0.12954)
		(layer "B.Cu")
		(net "SVID_ALERT1_CPU0_R_N")
	)
	(segment
		(start 307.413152 -191.536574)
		(end 307.883814 -191.536574)
		(width 0.12954)
		(layer "B.Cu")
		(net "SVID_ALERT1_CPU0_R_N")
	)
	(segment
		(start 307.883814 -191.536574)
		(end 307.984398 -191.43599)
		(width 0.12954)
		(layer "B.Cu")
		(net "SVID_ALERT1_CPU0_R_N")
	)
	(segment
		(start 307.984398 -191.43599)
		(end 307.984398 -190.85052)
		(width 0.12954)
		(layer "B.Cu")
		(net "SVID_ALERT1_CPU0_R_N")
	)
	(segment
		(start 355.351334 -233.87812)
		(end 355.351334 -233.342434)
		(width 0.12954)
		(layer "F.Cu")
		(net "SVID_ALERT1_CPU0_N")
	)
	(segment
		(start 355.351334 -233.342434)
		(end 355.35108 -233.34218)
		(width 0.12954)
		(layer "F.Cu")
		(net "SVID_ALERT1_CPU0_N")
	)
	(via
		(at 316.036198 -235.927138)
		(size 0.6604)
		(drill 0.3302)
		(layers "F.Cu" "B.Cu")
		(net "SVID_ALERT1_CPU0_N")
	)
	(via
		(at 355.35108 -233.34218)
		(size 0.4572)
		(drill 0.2032)
		(layers "F.Cu" "B.Cu")
		(net "SVID_ALERT1_CPU0_N")
	)
	(segment
		(start 312.325258 -234.46613)
		(end 311.375044 -234.46613)
		(width 0.12954)
		(layer "B.Cu")
		(net "SVID_ALERT1_CPU0_N")
	)
	(segment
		(start 315.09335 -234.98429)
		(end 312.843418 -234.98429)
		(width 0.12954)
		(layer "B.Cu")
		(net "SVID_ALERT1_CPU0_N")
	)
	(segment
		(start 309.508398 -194.43192)
		(end 308.085998 -193.00952)
		(width 0.12954)
		(layer "B.Cu")
		(net "SVID_ALERT1_CPU0_N")
	)
	(segment
		(start 343.886282 -233.666538)
		(end 343.87155 -233.657902)
		(width 0.0889)
		(layer "B.Cu")
		(net "SVID_ALERT1_CPU0_N")
	)
	(segment
		(start 327.381616 -235.927138)
		(end 316.036198 -235.927138)
		(width 0.12954)
		(layer "B.Cu")
		(net "SVID_ALERT1_CPU0_N")
	)
	(segment
		(start 351.404682 -233.666538)
		(end 351.38995 -233.657902)
		(width 0.0889)
		(layer "B.Cu")
		(net "SVID_ALERT1_CPU0_N")
	)
	(segment
		(start 336.367882 -233.666538)
		(end 336.357468 -233.660442)
		(width 0.0889)
		(layer "B.Cu")
		(net "SVID_ALERT1_CPU0_N")
	)
	(segment
		(start 332.558898 -234.71251)
		(end 328.596244 -234.71251)
		(width 0.12954)
		(layer "B.Cu")
		(net "SVID_ALERT1_CPU0_N")
	)
	(segment
		(start 309.798212 -233.61523)
		(end 309.051198 -232.868216)
		(width 0.12954)
		(layer "B.Cu")
		(net "SVID_ALERT1_CPU0_N")
	)
	(segment
		(start 340.127082 -233.666538)
		(end 340.116668 -233.660442)
		(width 0.0889)
		(layer "B.Cu")
		(net "SVID_ALERT1_CPU0_N")
	)
	(segment
		(start 345.766136 -233.666538)
		(end 345.755722 -233.660442)
		(width 0.0889)
		(layer "B.Cu")
		(net "SVID_ALERT1_CPU0_N")
	)
	(segment
		(start 309.508398 -205.383638)
		(end 309.508398 -194.43192)
		(width 0.12954)
		(layer "B.Cu")
		(net "SVID_ALERT1_CPU0_N")
	)
	(segment
		(start 316.036198 -235.927138)
		(end 315.09335 -234.98429)
		(width 0.12954)
		(layer "B.Cu")
		(net "SVID_ALERT1_CPU0_N")
	)
	(segment
		(start 312.843418 -234.98429)
		(end 312.325258 -234.46613)
		(width 0.12954)
		(layer "B.Cu")
		(net "SVID_ALERT1_CPU0_N")
	)
	(segment
		(start 344.826082 -233.666538)
		(end 344.81135 -233.657902)
		(width 0.0889)
		(layer "B.Cu")
		(net "SVID_ALERT1_CPU0_N")
	)
	(segment
		(start 346.705682 -233.666538)
		(end 346.695268 -233.660442)
		(width 0.0889)
		(layer "B.Cu")
		(net "SVID_ALERT1_CPU0_N")
	)
	(segment
		(start 353.284282 -233.666538)
		(end 353.26955 -233.657902)
		(width 0.0889)
		(layer "B.Cu")
		(net "SVID_ALERT1_CPU0_N")
	)
	(segment
		(start 335.425796 -233.768138)
		(end 333.50327 -233.768138)
		(width 0.0889)
		(layer "B.Cu")
		(net "SVID_ALERT1_CPU0_N")
	)
	(segment
		(start 333.50327 -233.768138)
		(end 333.277718 -233.99369)
		(width 0.0889)
		(layer "B.Cu")
		(net "SVID_ALERT1_CPU0_N")
	)
	(segment
		(start 339.187536 -233.666538)
		(end 339.177122 -233.660442)
		(width 0.0889)
		(layer "B.Cu")
		(net "SVID_ALERT1_CPU0_N")
	)
	(segment
		(start 342.006682 -233.666538)
		(end 341.99195 -233.657902)
		(width 0.0889)
		(layer "B.Cu")
		(net "SVID_ALERT1_CPU0_N")
	)
	(segment
		(start 309.051198 -205.840838)
		(end 309.508398 -205.383638)
		(width 0.12954)
		(layer "B.Cu")
		(net "SVID_ALERT1_CPU0_N")
	)
	(segment
		(start 309.051198 -232.868216)
		(end 309.051198 -205.840838)
		(width 0.12954)
		(layer "B.Cu")
		(net "SVID_ALERT1_CPU0_N")
	)
	(segment
		(start 328.596244 -234.71251)
		(end 327.381616 -235.927138)
		(width 0.12954)
		(layer "B.Cu")
		(net "SVID_ALERT1_CPU0_N")
	)
	(segment
		(start 350.464882 -233.666538)
		(end 350.45015 -233.657902)
		(width 0.0889)
		(layer "B.Cu")
		(net "SVID_ALERT1_CPU0_N")
	)
	(segment
		(start 310.524144 -233.61523)
		(end 309.798212 -233.61523)
		(width 0.12954)
		(layer "B.Cu")
		(net "SVID_ALERT1_CPU0_N")
	)
	(segment
		(start 337.307682 -233.666538)
		(end 337.29295 -233.657902)
		(width 0.0889)
		(layer "B.Cu")
		(net "SVID_ALERT1_CPU0_N")
	)
	(segment
		(start 355.35108 -233.34218)
		(end 354.703888 -233.619294)
		(width 0.0889)
		(layer "B.Cu")
		(net "SVID_ALERT1_CPU0_N")
	)
	(segment
		(start 338.247482 -233.666538)
		(end 338.23275 -233.657902)
		(width 0.0889)
		(layer "B.Cu")
		(net "SVID_ALERT1_CPU0_N")
	)
	(segment
		(start 341.066882 -233.666538)
		(end 341.05215 -233.657902)
		(width 0.0889)
		(layer "B.Cu")
		(net "SVID_ALERT1_CPU0_N")
	)
	(segment
		(start 348.585282 -233.666538)
		(end 348.57055 -233.657902)
		(width 0.0889)
		(layer "B.Cu")
		(net "SVID_ALERT1_CPU0_N")
	)
	(segment
		(start 352.344482 -233.666538)
		(end 352.32975 -233.657902)
		(width 0.0889)
		(layer "B.Cu")
		(net "SVID_ALERT1_CPU0_N")
	)
	(segment
		(start 311.375044 -234.46613)
		(end 310.524144 -233.61523)
		(width 0.12954)
		(layer "B.Cu")
		(net "SVID_ALERT1_CPU0_N")
	)
	(segment
		(start 347.645482 -233.666538)
		(end 347.63075 -233.657902)
		(width 0.0889)
		(layer "B.Cu")
		(net "SVID_ALERT1_CPU0_N")
	)
	(segment
		(start 333.277718 -233.99369)
		(end 332.558898 -234.71251)
		(width 0.12954)
		(layer "B.Cu")
		(net "SVID_ALERT1_CPU0_N")
	)
	(segment
		(start 354.224082 -233.666538)
		(end 354.20935 -233.657902)
		(width 0.0889)
		(layer "B.Cu")
		(net "SVID_ALERT1_CPU0_N")
	)
	(arc
		(start 348.019878 -233.666538)
		(mid 347.83268 -233.716681)
		(end 347.645482 -233.666538)
		(width 0.0889)
		(layer "B.Cu")
		(net "SVID_ALERT1_CPU0_N")
	)
	(arc
		(start 342.946482 -233.666538)
		(mid 342.66378 -233.590796)
		(end 342.381078 -233.666538)
		(width 0.0889)
		(layer "B.Cu")
		(net "SVID_ALERT1_CPU0_N")
	)
	(arc
		(start 342.381078 -233.666538)
		(mid 342.19388 -233.716681)
		(end 342.006682 -233.666538)
		(width 0.0889)
		(layer "B.Cu")
		(net "SVID_ALERT1_CPU0_N")
	)
	(arc
		(start 349.525082 -233.666538)
		(mid 349.24238 -233.590796)
		(end 348.959678 -233.666538)
		(width 0.0889)
		(layer "B.Cu")
		(net "SVID_ALERT1_CPU0_N")
	)
	(arc
		(start 335.802732 -233.666538)
		(mid 335.620998 -233.742339)
		(end 335.425796 -233.768138)
		(width 0.0889)
		(layer "B.Cu")
		(net "SVID_ALERT1_CPU0_N")
	)
	(arc
		(start 352.32975 -233.657902)
		(mid 352.053309 -233.590736)
		(end 351.779078 -233.666538)
		(width 0.0889)
		(layer "B.Cu")
		(net "SVID_ALERT1_CPU0_N")
	)
	(arc
		(start 354.20935 -233.657902)
		(mid 353.932909 -233.590736)
		(end 353.658678 -233.666538)
		(width 0.0889)
		(layer "B.Cu")
		(net "SVID_ALERT1_CPU0_N")
	)
	(arc
		(start 339.561932 -233.666538)
		(mid 339.374734 -233.716681)
		(end 339.187536 -233.666538)
		(width 0.0889)
		(layer "B.Cu")
		(net "SVID_ALERT1_CPU0_N")
	)
	(arc
		(start 339.177122 -233.660442)
		(mid 338.89869 -233.590628)
		(end 338.621878 -233.666538)
		(width 0.0889)
		(layer "B.Cu")
		(net "SVID_ALERT1_CPU0_N")
	)
	(arc
		(start 346.695268 -233.660442)
		(mid 346.41709 -233.59075)
		(end 346.140532 -233.666538)
		(width 0.0889)
		(layer "B.Cu")
		(net "SVID_ALERT1_CPU0_N")
	)
	(arc
		(start 353.658678 -233.666538)
		(mid 353.47148 -233.716681)
		(end 353.284282 -233.666538)
		(width 0.0889)
		(layer "B.Cu")
		(net "SVID_ALERT1_CPU0_N")
	)
	(arc
		(start 338.23275 -233.657902)
		(mid 337.956309 -233.590736)
		(end 337.682078 -233.666538)
		(width 0.0889)
		(layer "B.Cu")
		(net "SVID_ALERT1_CPU0_N")
	)
	(arc
		(start 346.140532 -233.666538)
		(mid 345.953334 -233.716681)
		(end 345.766136 -233.666538)
		(width 0.0889)
		(layer "B.Cu")
		(net "SVID_ALERT1_CPU0_N")
	)
	(arc
		(start 351.38995 -233.657902)
		(mid 351.113509 -233.590736)
		(end 350.839278 -233.666538)
		(width 0.0889)
		(layer "B.Cu")
		(net "SVID_ALERT1_CPU0_N")
	)
	(arc
		(start 340.501478 -233.666538)
		(mid 340.31428 -233.716681)
		(end 340.127082 -233.666538)
		(width 0.0889)
		(layer "B.Cu")
		(net "SVID_ALERT1_CPU0_N")
	)
	(arc
		(start 340.116668 -233.660442)
		(mid 339.83849 -233.59075)
		(end 339.561932 -233.666538)
		(width 0.0889)
		(layer "B.Cu")
		(net "SVID_ALERT1_CPU0_N")
	)
	(arc
		(start 352.718878 -233.666538)
		(mid 352.53168 -233.716681)
		(end 352.344482 -233.666538)
		(width 0.0889)
		(layer "B.Cu")
		(net "SVID_ALERT1_CPU0_N")
	)
	(arc
		(start 345.200478 -233.666538)
		(mid 345.01328 -233.716681)
		(end 344.826082 -233.666538)
		(width 0.0889)
		(layer "B.Cu")
		(net "SVID_ALERT1_CPU0_N")
	)
	(arc
		(start 351.779078 -233.666538)
		(mid 351.59188 -233.716681)
		(end 351.404682 -233.666538)
		(width 0.0889)
		(layer "B.Cu")
		(net "SVID_ALERT1_CPU0_N")
	)
	(arc
		(start 347.080078 -233.666538)
		(mid 346.89288 -233.716681)
		(end 346.705682 -233.666538)
		(width 0.0889)
		(layer "B.Cu")
		(net "SVID_ALERT1_CPU0_N")
	)
	(arc
		(start 344.260678 -233.666538)
		(mid 344.07348 -233.716681)
		(end 343.886282 -233.666538)
		(width 0.0889)
		(layer "B.Cu")
		(net "SVID_ALERT1_CPU0_N")
	)
	(arc
		(start 341.99195 -233.657902)
		(mid 341.715509 -233.590736)
		(end 341.441278 -233.666538)
		(width 0.0889)
		(layer "B.Cu")
		(net "SVID_ALERT1_CPU0_N")
	)
	(arc
		(start 343.320878 -233.666538)
		(mid 343.13368 -233.716681)
		(end 342.946482 -233.666538)
		(width 0.0889)
		(layer "B.Cu")
		(net "SVID_ALERT1_CPU0_N")
	)
	(arc
		(start 336.357468 -233.660442)
		(mid 336.07929 -233.59075)
		(end 335.802732 -233.666538)
		(width 0.0889)
		(layer "B.Cu")
		(net "SVID_ALERT1_CPU0_N")
	)
	(arc
		(start 350.45015 -233.657902)
		(mid 350.173709 -233.590736)
		(end 349.899478 -233.666538)
		(width 0.0889)
		(layer "B.Cu")
		(net "SVID_ALERT1_CPU0_N")
	)
	(arc
		(start 353.26955 -233.657902)
		(mid 352.993109 -233.590736)
		(end 352.718878 -233.666538)
		(width 0.0889)
		(layer "B.Cu")
		(net "SVID_ALERT1_CPU0_N")
	)
	(arc
		(start 344.81135 -233.657902)
		(mid 344.534909 -233.590736)
		(end 344.260678 -233.666538)
		(width 0.0889)
		(layer "B.Cu")
		(net "SVID_ALERT1_CPU0_N")
	)
	(arc
		(start 336.742278 -233.666538)
		(mid 336.55508 -233.716681)
		(end 336.367882 -233.666538)
		(width 0.0889)
		(layer "B.Cu")
		(net "SVID_ALERT1_CPU0_N")
	)
	(arc
		(start 341.05215 -233.657902)
		(mid 340.775709 -233.590736)
		(end 340.501478 -233.666538)
		(width 0.0889)
		(layer "B.Cu")
		(net "SVID_ALERT1_CPU0_N")
	)
	(arc
		(start 354.703888 -233.619294)
		(mid 354.64997 -233.640211)
		(end 354.598478 -233.666538)
		(width 0.0889)
		(layer "B.Cu")
		(net "SVID_ALERT1_CPU0_N")
	)
	(arc
		(start 348.57055 -233.657902)
		(mid 348.294109 -233.590736)
		(end 348.019878 -233.666538)
		(width 0.0889)
		(layer "B.Cu")
		(net "SVID_ALERT1_CPU0_N")
	)
	(arc
		(start 338.621878 -233.666538)
		(mid 338.43468 -233.716681)
		(end 338.247482 -233.666538)
		(width 0.0889)
		(layer "B.Cu")
		(net "SVID_ALERT1_CPU0_N")
	)
	(arc
		(start 347.63075 -233.657902)
		(mid 347.354309 -233.590736)
		(end 347.080078 -233.666538)
		(width 0.0889)
		(layer "B.Cu")
		(net "SVID_ALERT1_CPU0_N")
	)
	(arc
		(start 354.598478 -233.666538)
		(mid 354.41128 -233.716681)
		(end 354.224082 -233.666538)
		(width 0.0889)
		(layer "B.Cu")
		(net "SVID_ALERT1_CPU0_N")
	)
	(arc
		(start 348.959678 -233.666538)
		(mid 348.77248 -233.716681)
		(end 348.585282 -233.666538)
		(width 0.0889)
		(layer "B.Cu")
		(net "SVID_ALERT1_CPU0_N")
	)
	(arc
		(start 341.441278 -233.666538)
		(mid 341.25408 -233.716681)
		(end 341.066882 -233.666538)
		(width 0.0889)
		(layer "B.Cu")
		(net "SVID_ALERT1_CPU0_N")
	)
	(arc
		(start 337.29295 -233.657902)
		(mid 337.016509 -233.590736)
		(end 336.742278 -233.666538)
		(width 0.0889)
		(layer "B.Cu")
		(net "SVID_ALERT1_CPU0_N")
	)
	(arc
		(start 345.755722 -233.660442)
		(mid 345.47729 -233.590628)
		(end 345.200478 -233.666538)
		(width 0.0889)
		(layer "B.Cu")
		(net "SVID_ALERT1_CPU0_N")
	)
	(arc
		(start 343.87155 -233.657902)
		(mid 343.595109 -233.590736)
		(end 343.320878 -233.666538)
		(width 0.0889)
		(layer "B.Cu")
		(net "SVID_ALERT1_CPU0_N")
	)
	(arc
		(start 349.899478 -233.666538)
		(mid 349.71228 -233.716681)
		(end 349.525082 -233.666538)
		(width 0.0889)
		(layer "B.Cu")
		(net "SVID_ALERT1_CPU0_N")
	)
	(arc
		(start 337.682078 -233.666538)
		(mid 337.49488 -233.716681)
		(end 337.307682 -233.666538)
		(width 0.0889)
		(layer "B.Cu")
		(net "SVID_ALERT1_CPU0_N")
	)
	(arc
		(start 350.839278 -233.666538)
		(mid 350.65208 -233.716681)
		(end 350.464882 -233.666538)
		(width 0.0889)
		(layer "B.Cu")
		(net "SVID_ALERT1_CPU0_N")
	)
	(segment
		(start 102.163626 -355.398832)
		(end 101.874066 -355.398832)
		(width 0.12954)
		(layer "F.Cu")
		(net "SVID_ALERT0_CPU1_R_N")
	)
	(segment
		(start 37.974016 -132.049774)
		(end 37.701982 -131.77774)
		(width 0.12954)
		(layer "F.Cu")
		(net "SVID_ALERT0_CPU1_R_N")
	)
	(segment
		(start 37.701982 -131.77774)
		(end 37.356288 -131.77774)
		(width 0.12954)
		(layer "F.Cu")
		(net "SVID_ALERT0_CPU1_R_N")
	)
	(segment
		(start 102.445566 -355.773736)
		(end 102.445566 -355.680772)
		(width 0.12954)
		(layer "F.Cu")
		(net "SVID_ALERT0_CPU1_R_N")
	)
	(segment
		(start 101.361748 -355.398832)
		(end 101.220778 -355.257862)
		(width 0.12954)
		(layer "F.Cu")
		(net "SVID_ALERT0_CPU1_R_N")
	)
	(segment
		(start 101.874066 -355.398832)
		(end 101.361748 -355.398832)
		(width 0.12954)
		(layer "F.Cu")
		(net "SVID_ALERT0_CPU1_R_N")
	)
	(segment
		(start 102.445566 -355.680772)
		(end 102.163626 -355.398832)
		(width 0.12954)
		(layer "F.Cu")
		(net "SVID_ALERT0_CPU1_R_N")
	)
	(via
		(at 101.874066 -355.398832)
		(size 0.508)
		(drill 0.254)
		(layers "F.Cu" "B.Cu")
		(net "SVID_ALERT0_CPU1_R_N")
	)
	(via
		(at 64.697102 -131.69011)
		(size 0.508)
		(drill 0.254)
		(layers "F.Cu" "B.Cu")
		(net "SVID_ALERT0_CPU1_R_N")
	)
	(via
		(at 94.4499 -389.651748)
		(size 0.762)
		(drill 0.254)
		(layers "F.Cu" "B.Cu")
		(net "SVID_ALERT0_CPU1_R_N")
	)
	(via
		(at 70.369684 -189.662308)
		(size 0.508)
		(drill 0.254)
		(layers "F.Cu" "B.Cu")
		(net "SVID_ALERT0_CPU1_R_N")
	)
	(via
		(at 37.974016 -132.049774)
		(size 0.508)
		(drill 0.254)
		(layers "F.Cu" "B.Cu")
		(net "SVID_ALERT0_CPU1_R_N")
	)
	(via
		(at 97.152206 -362.833412)
		(size 0.508)
		(drill 0.254)
		(layers "F.Cu" "B.Cu")
		(net "SVID_ALERT0_CPU1_R_N")
	)
	(segment
		(start 69.6595 -191.05499)
		(end 69.5452 -191.05499)
		(width 0.12954)
		(layer "B.Cu")
		(net "SVID_ALERT0_CPU1_R_N")
	)
	(segment
		(start 70.369684 -190.344806)
		(end 69.6595 -191.05499)
		(width 0.12954)
		(layer "B.Cu")
		(net "SVID_ALERT0_CPU1_R_N")
	)
	(segment
		(start 69.5452 -191.05499)
		(end 69.404484 -191.195706)
		(width 0.12954)
		(layer "B.Cu")
		(net "SVID_ALERT0_CPU1_R_N")
	)
	(segment
		(start 70.369684 -189.662308)
		(end 70.369684 -190.344806)
		(width 0.12954)
		(layer "B.Cu")
		(net "SVID_ALERT0_CPU1_R_N")
	)
	(segment
		(start 80.026256 -159.267652)
		(end 81.908396 -161.149792)
		(width 0.127)
		(layer "In2.Cu")
		(net "SVID_ALERT0_CPU1_R_N")
	)
	(segment
		(start 80.026256 -158.190184)
		(end 80.026256 -159.267652)
		(width 0.127)
		(layer "In2.Cu")
		(net "SVID_ALERT0_CPU1_R_N")
	)
	(segment
		(start 65.913762 -131.69011)
		(end 77.240892 -143.01724)
		(width 0.127)
		(layer "In2.Cu")
		(net "SVID_ALERT0_CPU1_R_N")
	)
	(segment
		(start 64.697102 -131.69011)
		(end 65.913762 -131.69011)
		(width 0.127)
		(layer "In2.Cu")
		(net "SVID_ALERT0_CPU1_R_N")
	)
	(segment
		(start 77.240892 -155.40482)
		(end 80.026256 -158.190184)
		(width 0.127)
		(layer "In2.Cu")
		(net "SVID_ALERT0_CPU1_R_N")
	)
	(segment
		(start 70.8533 -190.945008)
		(end 70.369684 -190.461392)
		(width 0.127)
		(layer "In2.Cu")
		(net "SVID_ALERT0_CPU1_R_N")
	)
	(segment
		(start 77.240892 -143.01724)
		(end 77.240892 -155.40482)
		(width 0.127)
		(layer "In2.Cu")
		(net "SVID_ALERT0_CPU1_R_N")
	)
	(segment
		(start 81.908396 -184.228232)
		(end 75.19162 -190.945008)
		(width 0.127)
		(layer "In2.Cu")
		(net "SVID_ALERT0_CPU1_R_N")
	)
	(segment
		(start 75.19162 -190.945008)
		(end 70.8533 -190.945008)
		(width 0.127)
		(layer "In2.Cu")
		(net "SVID_ALERT0_CPU1_R_N")
	)
	(segment
		(start 81.908396 -161.149792)
		(end 81.908396 -184.228232)
		(width 0.127)
		(layer "In2.Cu")
		(net "SVID_ALERT0_CPU1_R_N")
	)
	(segment
		(start 70.369684 -190.461392)
		(end 70.369684 -189.662308)
		(width 0.127)
		(layer "In2.Cu")
		(net "SVID_ALERT0_CPU1_R_N")
	)
	(segment
		(start 64.284606 -133.002782)
		(end 38.927024 -133.002782)
		(width 0.127)
		(layer "In6.Cu")
		(net "SVID_ALERT0_CPU1_R_N")
	)
	(segment
		(start 64.697102 -132.590286)
		(end 64.284606 -133.002782)
		(width 0.127)
		(layer "In6.Cu")
		(net "SVID_ALERT0_CPU1_R_N")
	)
	(segment
		(start 38.927024 -133.002782)
		(end 37.974016 -132.049774)
		(width 0.127)
		(layer "In6.Cu")
		(net "SVID_ALERT0_CPU1_R_N")
	)
	(segment
		(start 64.697102 -131.69011)
		(end 64.697102 -132.590286)
		(width 0.127)
		(layer "In6.Cu")
		(net "SVID_ALERT0_CPU1_R_N")
	)
	(segment
		(start 9.68502 -257.350768)
		(end 10.77214 -257.350768)
		(width 0.127)
		(layer "In11.Cu")
		(net "SVID_ALERT0_CPU1_R_N")
	)
	(segment
		(start 29.8958 -361.533948)
		(end 29.8958 -340.096348)
		(width 0.127)
		(layer "In11.Cu")
		(net "SVID_ALERT0_CPU1_R_N")
	)
	(segment
		(start 94.44482 -389.656828)
		(end 58.01868 -389.656828)
		(width 0.127)
		(layer "In11.Cu")
		(net "SVID_ALERT0_CPU1_R_N")
	)
	(segment
		(start 101.874066 -355.398832)
		(end 101.263958 -355.398832)
		(width 0.127)
		(layer "In11.Cu")
		(net "SVID_ALERT0_CPU1_R_N")
	)
	(segment
		(start 40.5892 -124.704348)
		(end 40.5892 -127.366268)
		(width 0.127)
		(layer "In11.Cu")
		(net "SVID_ALERT0_CPU1_R_N")
	)
	(segment
		(start 39.3573 -130.203448)
		(end 39.61638 -130.462528)
		(width 0.127)
		(layer "In11.Cu")
		(net "SVID_ALERT0_CPU1_R_N")
	)
	(segment
		(start 94.4499 -389.651748)
		(end 94.44482 -389.656828)
		(width 0.127)
		(layer "In11.Cu")
		(net "SVID_ALERT0_CPU1_R_N")
	)
	(segment
		(start 99.508818 -354.47859)
		(end 98.652838 -355.33457)
		(width 0.127)
		(layer "In11.Cu")
		(net "SVID_ALERT0_CPU1_R_N")
	)
	(segment
		(start 22.357334 -127.889508)
		(end 29.351732 -120.89511)
		(width 0.127)
		(layer "In11.Cu")
		(net "SVID_ALERT0_CPU1_R_N")
	)
	(segment
		(start 8.52932 -321.137788)
		(end 8.52932 -258.506468)
		(width 0.127)
		(layer "In11.Cu")
		(net "SVID_ALERT0_CPU1_R_N")
	)
	(segment
		(start 12.76604 -190.932308)
		(end 14.38402 -189.314328)
		(width 0.127)
		(layer "In11.Cu")
		(net "SVID_ALERT0_CPU1_R_N")
	)
	(segment
		(start 26.70556 -324.325488)
		(end 11.71702 -324.325488)
		(width 0.127)
		(layer "In11.Cu")
		(net "SVID_ALERT0_CPU1_R_N")
	)
	(segment
		(start 11.71702 -324.325488)
		(end 8.52932 -321.137788)
		(width 0.127)
		(layer "In11.Cu")
		(net "SVID_ALERT0_CPU1_R_N")
	)
	(segment
		(start 11.210544 -175.461676)
		(end 16.874998 -169.797222)
		(width 0.127)
		(layer "In11.Cu")
		(net "SVID_ALERT0_CPU1_R_N")
	)
	(segment
		(start 38.283642 -131.740148)
		(end 37.974016 -132.049774)
		(width 0.127)
		(layer "In11.Cu")
		(net "SVID_ALERT0_CPU1_R_N")
	)
	(segment
		(start 39.61638 -131.290568)
		(end 39.1668 -131.740148)
		(width 0.127)
		(layer "In11.Cu")
		(net "SVID_ALERT0_CPU1_R_N")
	)
	(segment
		(start 98.652838 -358.026716)
		(end 97.152206 -359.527348)
		(width 0.127)
		(layer "In11.Cu")
		(net "SVID_ALERT0_CPU1_R_N")
	)
	(segment
		(start 40.5892 -127.366268)
		(end 39.3573 -128.598168)
		(width 0.127)
		(layer "In11.Cu")
		(net "SVID_ALERT0_CPU1_R_N")
	)
	(segment
		(start 100.343716 -354.47859)
		(end 99.508818 -354.47859)
		(width 0.127)
		(layer "In11.Cu")
		(net "SVID_ALERT0_CPU1_R_N")
	)
	(segment
		(start 14.38402 -184.41162)
		(end 11.210544 -181.238144)
		(width 0.127)
		(layer "In11.Cu")
		(net "SVID_ALERT0_CPU1_R_N")
	)
	(segment
		(start 39.61638 -130.462528)
		(end 39.61638 -131.290568)
		(width 0.127)
		(layer "In11.Cu")
		(net "SVID_ALERT0_CPU1_R_N")
	)
	(segment
		(start 16.874998 -153.3271)
		(end 22.357334 -147.844764)
		(width 0.127)
		(layer "In11.Cu")
		(net "SVID_ALERT0_CPU1_R_N")
	)
	(segment
		(start 29.351732 -120.89511)
		(end 37.694362 -120.89511)
		(width 0.127)
		(layer "In11.Cu")
		(net "SVID_ALERT0_CPU1_R_N")
	)
	(segment
		(start 38.5318 -122.646948)
		(end 40.5892 -124.704348)
		(width 0.127)
		(layer "In11.Cu")
		(net "SVID_ALERT0_CPU1_R_N")
	)
	(segment
		(start 58.01868 -389.656828)
		(end 29.8958 -361.533948)
		(width 0.127)
		(layer "In11.Cu")
		(net "SVID_ALERT0_CPU1_R_N")
	)
	(segment
		(start 8.52932 -258.506468)
		(end 9.68502 -257.350768)
		(width 0.127)
		(layer "In11.Cu")
		(net "SVID_ALERT0_CPU1_R_N")
	)
	(segment
		(start 38.5318 -121.732548)
		(end 38.5318 -122.646948)
		(width 0.127)
		(layer "In11.Cu")
		(net "SVID_ALERT0_CPU1_R_N")
	)
	(segment
		(start 97.152206 -359.527348)
		(end 97.152206 -362.833412)
		(width 0.127)
		(layer "In11.Cu")
		(net "SVID_ALERT0_CPU1_R_N")
	)
	(segment
		(start 101.263958 -355.398832)
		(end 100.343716 -354.47859)
		(width 0.127)
		(layer "In11.Cu")
		(net "SVID_ALERT0_CPU1_R_N")
	)
	(segment
		(start 22.357334 -147.844764)
		(end 22.357334 -127.889508)
		(width 0.127)
		(layer "In11.Cu")
		(net "SVID_ALERT0_CPU1_R_N")
	)
	(segment
		(start 32.85744 -330.477368)
		(end 26.70556 -324.325488)
		(width 0.127)
		(layer "In11.Cu")
		(net "SVID_ALERT0_CPU1_R_N")
	)
	(segment
		(start 39.3573 -128.598168)
		(end 39.3573 -130.203448)
		(width 0.127)
		(layer "In11.Cu")
		(net "SVID_ALERT0_CPU1_R_N")
	)
	(segment
		(start 37.694362 -120.89511)
		(end 38.5318 -121.732548)
		(width 0.127)
		(layer "In11.Cu")
		(net "SVID_ALERT0_CPU1_R_N")
	)
	(segment
		(start 32.85744 -337.134708)
		(end 32.85744 -330.477368)
		(width 0.127)
		(layer "In11.Cu")
		(net "SVID_ALERT0_CPU1_R_N")
	)
	(segment
		(start 29.8958 -340.096348)
		(end 32.85744 -337.134708)
		(width 0.127)
		(layer "In11.Cu")
		(net "SVID_ALERT0_CPU1_R_N")
	)
	(segment
		(start 39.1668 -131.740148)
		(end 38.283642 -131.740148)
		(width 0.127)
		(layer "In11.Cu")
		(net "SVID_ALERT0_CPU1_R_N")
	)
	(segment
		(start 12.76604 -255.356868)
		(end 12.76604 -190.932308)
		(width 0.127)
		(layer "In11.Cu")
		(net "SVID_ALERT0_CPU1_R_N")
	)
	(segment
		(start 98.652838 -355.33457)
		(end 98.652838 -358.026716)
		(width 0.127)
		(layer "In11.Cu")
		(net "SVID_ALERT0_CPU1_R_N")
	)
	(segment
		(start 10.77214 -257.350768)
		(end 12.76604 -255.356868)
		(width 0.127)
		(layer "In11.Cu")
		(net "SVID_ALERT0_CPU1_R_N")
	)
	(segment
		(start 14.38402 -189.314328)
		(end 14.38402 -184.41162)
		(width 0.127)
		(layer "In11.Cu")
		(net "SVID_ALERT0_CPU1_R_N")
	)
	(segment
		(start 16.874998 -169.797222)
		(end 16.874998 -153.3271)
		(width 0.127)
		(layer "In11.Cu")
		(net "SVID_ALERT0_CPU1_R_N")
	)
	(segment
		(start 11.210544 -181.238144)
		(end 11.210544 -175.461676)
		(width 0.127)
		(layer "In11.Cu")
		(net "SVID_ALERT0_CPU1_R_N")
	)
	(segment
		(start 95.33636 -364.649258)
		(end 95.33636 -387.929628)
		(width 0.127)
		(layer "In13.Cu")
		(net "SVID_ALERT0_CPU1_R_N")
	)
	(segment
		(start 95.33636 -387.929628)
		(end 94.4499 -388.816088)
		(width 0.127)
		(layer "In13.Cu")
		(net "SVID_ALERT0_CPU1_R_N")
	)
	(segment
		(start 97.152206 -362.833412)
		(end 95.33636 -364.649258)
		(width 0.127)
		(layer "In13.Cu")
		(net "SVID_ALERT0_CPU1_R_N")
	)
	(segment
		(start 94.4499 -388.816088)
		(end 94.4499 -389.651748)
		(width 0.127)
		(layer "In13.Cu")
		(net "SVID_ALERT0_CPU1_R_N")
	)
	(segment
		(start 107.881166 -234.691936)
		(end 107.881166 -234.15625)
		(width 0.12954)
		(layer "F.Cu")
		(net "SVID_ALERT0_CPU1_N")
	)
	(segment
		(start 107.880912 -234.69219)
		(end 107.881166 -234.691936)
		(width 0.12954)
		(layer "F.Cu")
		(net "SVID_ALERT0_CPU1_N")
	)
	(via
		(at 107.881166 -234.15625)
		(size 0.4572)
		(drill 0.2032)
		(layers "F.Cu" "B.Cu")
		(net "SVID_ALERT0_CPU1_N")
	)
	(via
		(at 69.529198 -198.05777)
		(size 0.6604)
		(drill 0.3302)
		(layers "F.Cu" "B.Cu")
		(net "SVID_ALERT0_CPU1_N")
	)
	(segment
		(start 64.67856 -224.075244)
		(end 64.387984 -223.784668)
		(width 0.12954)
		(layer "B.Cu")
		(net "SVID_ALERT0_CPU1_N")
	)
	(segment
		(start 87.467186 -235.408978)
		(end 87.383366 -235.408978)
		(width 0.0889)
		(layer "B.Cu")
		(net "SVID_ALERT0_CPU1_N")
	)
	(segment
		(start 95.865696 -235.46816)
		(end 95.850964 -235.459524)
		(width 0.0889)
		(layer "B.Cu")
		(net "SVID_ALERT0_CPU1_N")
	)
	(segment
		(start 64.387984 -223.784668)
		(end 64.387984 -204.86243)
		(width 0.12954)
		(layer "B.Cu")
		(net "SVID_ALERT0_CPU1_N")
	)
	(segment
		(start 98.685096 -235.46816)
		(end 98.678238 -235.464096)
		(width 0.0889)
		(layer "B.Cu")
		(net "SVID_ALERT0_CPU1_N")
	)
	(segment
		(start 104.1146 -235.151168)
		(end 102.390702 -235.151168)
		(width 0.0889)
		(layer "B.Cu")
		(net "SVID_ALERT0_CPU1_N")
	)
	(segment
		(start 101.504496 -235.46816)
		(end 101.489764 -235.459524)
		(width 0.0889)
		(layer "B.Cu")
		(net "SVID_ALERT0_CPU1_N")
	)
	(segment
		(start 98.678238 -235.464096)
		(end 98.670364 -235.459524)
		(width 0.0889)
		(layer "B.Cu")
		(net "SVID_ALERT0_CPU1_N")
	)
	(segment
		(start 99.624896 -235.46816)
		(end 99.610164 -235.459524)
		(width 0.0889)
		(layer "B.Cu")
		(net "SVID_ALERT0_CPU1_N")
	)
	(segment
		(start 93.986096 -235.46816)
		(end 93.971364 -235.459524)
		(width 0.0889)
		(layer "B.Cu")
		(net "SVID_ALERT0_CPU1_N")
	)
	(segment
		(start 107.09529 -234.942126)
		(end 105.363772 -234.942126)
		(width 0.0889)
		(layer "B.Cu")
		(net "SVID_ALERT0_CPU1_N")
	)
	(segment
		(start 68.920868 -200.329546)
		(end 68.920868 -198.6661)
		(width 0.12954)
		(layer "B.Cu")
		(net "SVID_ALERT0_CPU1_N")
	)
	(segment
		(start 97.740724 -235.46562)
		(end 97.73031 -235.459524)
		(width 0.0889)
		(layer "B.Cu")
		(net "SVID_ALERT0_CPU1_N")
	)
	(segment
		(start 97.355914 -235.459524)
		(end 97.3455 -235.46562)
		(width 0.0889)
		(layer "B.Cu")
		(net "SVID_ALERT0_CPU1_N")
	)
	(segment
		(start 64.939672 -232.544874)
		(end 64.67856 -232.283762)
		(width 0.12954)
		(layer "B.Cu")
		(net "SVID_ALERT0_CPU1_N")
	)
	(segment
		(start 64.67856 -232.283762)
		(end 64.67856 -224.075244)
		(width 0.12954)
		(layer "B.Cu")
		(net "SVID_ALERT0_CPU1_N")
	)
	(segment
		(start 105.363772 -234.942126)
		(end 104.914192 -235.391706)
		(width 0.0889)
		(layer "B.Cu")
		(net "SVID_ALERT0_CPU1_N")
	)
	(segment
		(start 102.390702 -235.151168)
		(end 102.172008 -235.369862)
		(width 0.0889)
		(layer "B.Cu")
		(net "SVID_ALERT0_CPU1_N")
	)
	(segment
		(start 77.109574 -237.169706)
		(end 73.389998 -233.45013)
		(width 0.12954)
		(layer "B.Cu")
		(net "SVID_ALERT0_CPU1_N")
	)
	(segment
		(start 94.925896 -235.46816)
		(end 94.911164 -235.459524)
		(width 0.0889)
		(layer "B.Cu")
		(net "SVID_ALERT0_CPU1_N")
	)
	(segment
		(start 104.355138 -235.391706)
		(end 104.1146 -235.151168)
		(width 0.0889)
		(layer "B.Cu")
		(net "SVID_ALERT0_CPU1_N")
	)
	(segment
		(start 91.162124 -235.46562)
		(end 91.15171 -235.459524)
		(width 0.0889)
		(layer "B.Cu")
		(net "SVID_ALERT0_CPU1_N")
	)
	(segment
		(start 69.912484 -197.674484)
		(end 69.912484 -192.552828)
		(width 0.12954)
		(layer "B.Cu")
		(net "SVID_ALERT0_CPU1_N")
	)
	(segment
		(start 90.777314 -235.459524)
		(end 90.7669 -235.46562)
		(width 0.0889)
		(layer "B.Cu")
		(net "SVID_ALERT0_CPU1_N")
	)
	(segment
		(start 88.347296 -235.46816)
		(end 88.332564 -235.459524)
		(width 0.0889)
		(layer "B.Cu")
		(net "SVID_ALERT0_CPU1_N")
	)
	(segment
		(start 65.927986 -233.205274)
		(end 64.939672 -232.544874)
		(width 0.12954)
		(layer "B.Cu")
		(net "SVID_ALERT0_CPU1_N")
	)
	(segment
		(start 104.914192 -235.391706)
		(end 104.355138 -235.391706)
		(width 0.0889)
		(layer "B.Cu")
		(net "SVID_ALERT0_CPU1_N")
	)
	(segment
		(start 84.010246 -237.000034)
		(end 83.840574 -237.169706)
		(width 0.12954)
		(layer "B.Cu")
		(net "SVID_ALERT0_CPU1_N")
	)
	(segment
		(start 83.840574 -237.169706)
		(end 77.109574 -237.169706)
		(width 0.12954)
		(layer "B.Cu")
		(net "SVID_ALERT0_CPU1_N")
	)
	(segment
		(start 107.881166 -234.15625)
		(end 107.09529 -234.942126)
		(width 0.0889)
		(layer "B.Cu")
		(net "SVID_ALERT0_CPU1_N")
	)
	(segment
		(start 66.519552 -233.45013)
		(end 65.927986 -233.205274)
		(width 0.12954)
		(layer "B.Cu")
		(net "SVID_ALERT0_CPU1_N")
	)
	(segment
		(start 89.287096 -235.46816)
		(end 89.272364 -235.459524)
		(width 0.0889)
		(layer "B.Cu")
		(net "SVID_ALERT0_CPU1_N")
	)
	(segment
		(start 92.106496 -235.46816)
		(end 92.091764 -235.459524)
		(width 0.0889)
		(layer "B.Cu")
		(net "SVID_ALERT0_CPU1_N")
	)
	(segment
		(start 100.564696 -235.46816)
		(end 100.549964 -235.459524)
		(width 0.0889)
		(layer "B.Cu")
		(net "SVID_ALERT0_CPU1_N")
	)
	(segment
		(start 68.920868 -198.6661)
		(end 69.529198 -198.05777)
		(width 0.12954)
		(layer "B.Cu")
		(net "SVID_ALERT0_CPU1_N")
	)
	(segment
		(start 73.389998 -233.45013)
		(end 66.519552 -233.45013)
		(width 0.12954)
		(layer "B.Cu")
		(net "SVID_ALERT0_CPU1_N")
	)
	(segment
		(start 64.387984 -204.86243)
		(end 68.920868 -200.329546)
		(width 0.12954)
		(layer "B.Cu")
		(net "SVID_ALERT0_CPU1_N")
	)
	(segment
		(start 85.79231 -237.000034)
		(end 84.010246 -237.000034)
		(width 0.12954)
		(layer "B.Cu")
		(net "SVID_ALERT0_CPU1_N")
	)
	(segment
		(start 70.369684 -191.449706)
		(end 70.369684 -191.144906)
		(width 0.12954)
		(layer "B.Cu")
		(net "SVID_ALERT0_CPU1_N")
	)
	(segment
		(start 69.529198 -198.05777)
		(end 69.912484 -197.674484)
		(width 0.12954)
		(layer "B.Cu")
		(net "SVID_ALERT0_CPU1_N")
	)
	(segment
		(start 87.383366 -235.408978)
		(end 85.79231 -237.000034)
		(width 0.12954)
		(layer "B.Cu")
		(net "SVID_ALERT0_CPU1_N")
	)
	(segment
		(start 69.912484 -192.552828)
		(end 70.369684 -191.449706)
		(width 0.12954)
		(layer "B.Cu")
		(net "SVID_ALERT0_CPU1_N")
	)
	(segment
		(start 88.21547 -235.369608)
		(end 87.467186 -235.408978)
		(width 0.0889)
		(layer "B.Cu")
		(net "SVID_ALERT0_CPU1_N")
	)
	(segment
		(start 93.046296 -235.46816)
		(end 93.031564 -235.459524)
		(width 0.0889)
		(layer "B.Cu")
		(net "SVID_ALERT0_CPU1_N")
	)
	(arc
		(start 98.670364 -235.459524)
		(mid 98.483166 -235.409381)
		(end 98.295968 -235.459524)
		(width 0.0889)
		(layer "B.Cu")
		(net "SVID_ALERT0_CPU1_N")
	)
	(arc
		(start 89.272364 -235.459524)
		(mid 89.085166 -235.409381)
		(end 88.897968 -235.459524)
		(width 0.0889)
		(layer "B.Cu")
		(net "SVID_ALERT0_CPU1_N")
	)
	(arc
		(start 97.3455 -235.46562)
		(mid 97.067322 -235.535343)
		(end 96.790764 -235.459524)
		(width 0.0889)
		(layer "B.Cu")
		(net "SVID_ALERT0_CPU1_N")
	)
	(arc
		(start 98.295968 -235.459524)
		(mid 98.019155 -235.535394)
		(end 97.740724 -235.46562)
		(width 0.0889)
		(layer "B.Cu")
		(net "SVID_ALERT0_CPU1_N")
	)
	(arc
		(start 100.549964 -235.459524)
		(mid 100.362766 -235.409381)
		(end 100.175568 -235.459524)
		(width 0.0889)
		(layer "B.Cu")
		(net "SVID_ALERT0_CPU1_N")
	)
	(arc
		(start 93.596968 -235.459524)
		(mid 93.322769 -235.535359)
		(end 93.046296 -235.46816)
		(width 0.0889)
		(layer "B.Cu")
		(net "SVID_ALERT0_CPU1_N")
	)
	(arc
		(start 94.911164 -235.459524)
		(mid 94.723966 -235.409381)
		(end 94.536768 -235.459524)
		(width 0.0889)
		(layer "B.Cu")
		(net "SVID_ALERT0_CPU1_N")
	)
	(arc
		(start 96.790764 -235.459524)
		(mid 96.603566 -235.409381)
		(end 96.416368 -235.459524)
		(width 0.0889)
		(layer "B.Cu")
		(net "SVID_ALERT0_CPU1_N")
	)
	(arc
		(start 96.416368 -235.459524)
		(mid 96.142169 -235.535359)
		(end 95.865696 -235.46816)
		(width 0.0889)
		(layer "B.Cu")
		(net "SVID_ALERT0_CPU1_N")
	)
	(arc
		(start 92.657168 -235.459524)
		(mid 92.382969 -235.535359)
		(end 92.106496 -235.46816)
		(width 0.0889)
		(layer "B.Cu")
		(net "SVID_ALERT0_CPU1_N")
	)
	(arc
		(start 99.610164 -235.459524)
		(mid 99.422966 -235.409381)
		(end 99.235768 -235.459524)
		(width 0.0889)
		(layer "B.Cu")
		(net "SVID_ALERT0_CPU1_N")
	)
	(arc
		(start 94.536768 -235.459524)
		(mid 94.262569 -235.535359)
		(end 93.986096 -235.46816)
		(width 0.0889)
		(layer "B.Cu")
		(net "SVID_ALERT0_CPU1_N")
	)
	(arc
		(start 92.091764 -235.459524)
		(mid 91.904566 -235.409381)
		(end 91.717368 -235.459524)
		(width 0.0889)
		(layer "B.Cu")
		(net "SVID_ALERT0_CPU1_N")
	)
	(arc
		(start 101.489764 -235.459524)
		(mid 101.302566 -235.409381)
		(end 101.115368 -235.459524)
		(width 0.0889)
		(layer "B.Cu")
		(net "SVID_ALERT0_CPU1_N")
	)
	(arc
		(start 89.837768 -235.459524)
		(mid 89.563569 -235.535359)
		(end 89.287096 -235.46816)
		(width 0.0889)
		(layer "B.Cu")
		(net "SVID_ALERT0_CPU1_N")
	)
	(arc
		(start 90.212164 -235.459524)
		(mid 90.024966 -235.409381)
		(end 89.837768 -235.459524)
		(width 0.0889)
		(layer "B.Cu")
		(net "SVID_ALERT0_CPU1_N")
	)
	(arc
		(start 97.73031 -235.459524)
		(mid 97.543112 -235.409381)
		(end 97.355914 -235.459524)
		(width 0.0889)
		(layer "B.Cu")
		(net "SVID_ALERT0_CPU1_N")
	)
	(arc
		(start 95.850964 -235.459524)
		(mid 95.663766 -235.409381)
		(end 95.476568 -235.459524)
		(width 0.0889)
		(layer "B.Cu")
		(net "SVID_ALERT0_CPU1_N")
	)
	(arc
		(start 90.7669 -235.46562)
		(mid 90.488722 -235.535343)
		(end 90.212164 -235.459524)
		(width 0.0889)
		(layer "B.Cu")
		(net "SVID_ALERT0_CPU1_N")
	)
	(arc
		(start 91.15171 -235.459524)
		(mid 90.964512 -235.409381)
		(end 90.777314 -235.459524)
		(width 0.0889)
		(layer "B.Cu")
		(net "SVID_ALERT0_CPU1_N")
	)
	(arc
		(start 101.115368 -235.459524)
		(mid 100.841169 -235.535359)
		(end 100.564696 -235.46816)
		(width 0.0889)
		(layer "B.Cu")
		(net "SVID_ALERT0_CPU1_N")
	)
	(arc
		(start 100.175568 -235.459524)
		(mid 99.901369 -235.535359)
		(end 99.624896 -235.46816)
		(width 0.0889)
		(layer "B.Cu")
		(net "SVID_ALERT0_CPU1_N")
	)
	(arc
		(start 99.235768 -235.459524)
		(mid 98.961569 -235.535359)
		(end 98.685096 -235.46816)
		(width 0.0889)
		(layer "B.Cu")
		(net "SVID_ALERT0_CPU1_N")
	)
	(arc
		(start 91.717368 -235.459524)
		(mid 91.440555 -235.535394)
		(end 91.162124 -235.46562)
		(width 0.0889)
		(layer "B.Cu")
		(net "SVID_ALERT0_CPU1_N")
	)
	(arc
		(start 95.476568 -235.459524)
		(mid 95.202369 -235.535359)
		(end 94.925896 -235.46816)
		(width 0.0889)
		(layer "B.Cu")
		(net "SVID_ALERT0_CPU1_N")
	)
	(arc
		(start 88.897968 -235.459524)
		(mid 88.623769 -235.535359)
		(end 88.347296 -235.46816)
		(width 0.0889)
		(layer "B.Cu")
		(net "SVID_ALERT0_CPU1_N")
	)
	(arc
		(start 93.971364 -235.459524)
		(mid 93.784166 -235.409381)
		(end 93.596968 -235.459524)
		(width 0.0889)
		(layer "B.Cu")
		(net "SVID_ALERT0_CPU1_N")
	)
	(arc
		(start 102.172008 -235.369862)
		(mid 101.854528 -235.529439)
		(end 101.504496 -235.46816)
		(width 0.0889)
		(layer "B.Cu")
		(net "SVID_ALERT0_CPU1_N")
	)
	(arc
		(start 93.031564 -235.459524)
		(mid 92.844366 -235.409381)
		(end 92.657168 -235.459524)
		(width 0.0889)
		(layer "B.Cu")
		(net "SVID_ALERT0_CPU1_N")
	)
	(arc
		(start 88.332564 -235.459524)
		(mid 88.271075 -235.418398)
		(end 88.21547 -235.369608)
		(width 0.0889)
		(layer "B.Cu")
		(net "SVID_ALERT0_CPU1_N")
	)
	(segment
		(start 349.841058 -355.02977)
		(end 349.173292 -355.02977)
		(width 0.12954)
		(layer "F.Cu")
		(net "SVID_ALERT0_CPU0_R_N")
	)
	(segment
		(start 347.147896 -354.804472)
		(end 348.250002 -354.804472)
		(width 0.12954)
		(layer "F.Cu")
		(net "SVID_ALERT0_CPU0_R_N")
	)
	(segment
		(start 345.807538 -361.911646)
		(end 345.807538 -356.14483)
		(width 0.12954)
		(layer "F.Cu")
		(net "SVID_ALERT0_CPU0_R_N")
	)
	(segment
		(start 350.204278 -355.592634)
		(end 350.204278 -355.39299)
		(width 0.12954)
		(layer "F.Cu")
		(net "SVID_ALERT0_CPU0_R_N")
	)
	(segment
		(start 431.482246 -138.558778)
		(end 431.000154 -138.558778)
		(width 0.12954)
		(layer "F.Cu")
		(net "SVID_ALERT0_CPU0_R_N")
	)
	(segment
		(start 350.204278 -355.39299)
		(end 349.841058 -355.02977)
		(width 0.12954)
		(layer "F.Cu")
		(net "SVID_ALERT0_CPU0_R_N")
	)
	(segment
		(start 348.8436 -355.359462)
		(end 348.804992 -355.359462)
		(width 0.12954)
		(layer "F.Cu")
		(net "SVID_ALERT0_CPU0_R_N")
	)
	(segment
		(start 348.250002 -354.804472)
		(end 348.804992 -355.359462)
		(width 0.12954)
		(layer "F.Cu")
		(net "SVID_ALERT0_CPU0_R_N")
	)
	(segment
		(start 345.807538 -356.14483)
		(end 347.147896 -354.804472)
		(width 0.12954)
		(layer "F.Cu")
		(net "SVID_ALERT0_CPU0_R_N")
	)
	(segment
		(start 350.38538 -355.773736)
		(end 350.204278 -355.592634)
		(width 0.12954)
		(layer "F.Cu")
		(net "SVID_ALERT0_CPU0_R_N")
	)
	(segment
		(start 349.173292 -355.02977)
		(end 348.8436 -355.359462)
		(width 0.12954)
		(layer "F.Cu")
		(net "SVID_ALERT0_CPU0_R_N")
	)
	(segment
		(start 432.639724 -139.716256)
		(end 431.482246 -138.558778)
		(width 0.12954)
		(layer "F.Cu")
		(net "SVID_ALERT0_CPU0_R_N")
	)
	(segment
		(start 346.76969 -362.873798)
		(end 345.807538 -361.911646)
		(width 0.12954)
		(layer "F.Cu")
		(net "SVID_ALERT0_CPU0_R_N")
	)
	(via
		(at 432.639724 -139.716256)
		(size 0.508)
		(drill 0.254)
		(layers "F.Cu" "B.Cu")
		(net "SVID_ALERT0_CPU0_R_N")
	)
	(via
		(at 301.164498 -189.09665)
		(size 0.508)
		(drill 0.254)
		(layers "F.Cu" "B.Cu")
		(net "SVID_ALERT0_CPU0_R_N")
	)
	(via
		(at 346.76969 -362.873798)
		(size 0.508)
		(drill 0.254)
		(layers "F.Cu" "B.Cu")
		(net "SVID_ALERT0_CPU0_R_N")
	)
	(segment
		(start 303.205896 -192.857628)
		(end 303.554638 -192.857628)
		(width 0.12954)
		(layer "B.Cu")
		(net "SVID_ALERT0_CPU0_R_N")
	)
	(segment
		(start 301.164498 -189.09665)
		(end 302.914558 -190.84671)
		(width 0.12954)
		(layer "B.Cu")
		(net "SVID_ALERT0_CPU0_R_N")
	)
	(segment
		(start 303.554638 -194.32016)
		(end 303.554638 -192.857628)
		(width 0.12954)
		(layer "B.Cu")
		(net "SVID_ALERT0_CPU0_R_N")
	)
	(segment
		(start 302.914558 -190.84671)
		(end 302.914558 -192.56629)
		(width 0.12954)
		(layer "B.Cu")
		(net "SVID_ALERT0_CPU0_R_N")
	)
	(segment
		(start 302.914558 -192.56629)
		(end 303.205896 -192.857628)
		(width 0.12954)
		(layer "B.Cu")
		(net "SVID_ALERT0_CPU0_R_N")
	)
	(segment
		(start 464.21802 -178.152552)
		(end 464.21802 -334.016096)
		(width 0.127)
		(layer "In6.Cu")
		(net "SVID_ALERT0_CPU0_R_N")
	)
	(segment
		(start 435.220364 -139.716256)
		(end 438.371234 -142.867126)
		(width 0.127)
		(layer "In6.Cu")
		(net "SVID_ALERT0_CPU0_R_N")
	)
	(segment
		(start 390.453372 -384.956304)
		(end 388.9629 -383.465832)
		(width 0.127)
		(layer "In6.Cu")
		(net "SVID_ALERT0_CPU0_R_N")
	)
	(segment
		(start 464.21802 -334.016096)
		(end 435.552342 -362.681774)
		(width 0.127)
		(layer "In6.Cu")
		(net "SVID_ALERT0_CPU0_R_N")
	)
	(segment
		(start 353.673664 -383.465832)
		(end 351.783904 -381.576072)
		(width 0.127)
		(layer "In6.Cu")
		(net "SVID_ALERT0_CPU0_R_N")
	)
	(segment
		(start 409.45308 -379.847348)
		(end 404.344124 -384.956304)
		(width 0.127)
		(layer "In6.Cu")
		(net "SVID_ALERT0_CPU0_R_N")
	)
	(segment
		(start 425.60748 -379.847348)
		(end 409.45308 -379.847348)
		(width 0.127)
		(layer "In6.Cu")
		(net "SVID_ALERT0_CPU0_R_N")
	)
	(segment
		(start 438.371234 -142.867126)
		(end 444.781178 -142.867126)
		(width 0.127)
		(layer "In6.Cu")
		(net "SVID_ALERT0_CPU0_R_N")
	)
	(segment
		(start 351.783904 -381.576072)
		(end 351.783904 -364.382812)
		(width 0.127)
		(layer "In6.Cu")
		(net "SVID_ALERT0_CPU0_R_N")
	)
	(segment
		(start 448.277234 -162.211766)
		(end 464.21802 -178.152552)
		(width 0.127)
		(layer "In6.Cu")
		(net "SVID_ALERT0_CPU0_R_N")
	)
	(segment
		(start 435.552342 -369.902486)
		(end 425.60748 -379.847348)
		(width 0.127)
		(layer "In6.Cu")
		(net "SVID_ALERT0_CPU0_R_N")
	)
	(segment
		(start 388.9629 -383.465832)
		(end 353.673664 -383.465832)
		(width 0.127)
		(layer "In6.Cu")
		(net "SVID_ALERT0_CPU0_R_N")
	)
	(segment
		(start 448.277234 -146.363182)
		(end 448.277234 -162.211766)
		(width 0.127)
		(layer "In6.Cu")
		(net "SVID_ALERT0_CPU0_R_N")
	)
	(segment
		(start 444.781178 -142.867126)
		(end 448.277234 -146.363182)
		(width 0.127)
		(layer "In6.Cu")
		(net "SVID_ALERT0_CPU0_R_N")
	)
	(segment
		(start 404.344124 -384.956304)
		(end 390.453372 -384.956304)
		(width 0.127)
		(layer "In6.Cu")
		(net "SVID_ALERT0_CPU0_R_N")
	)
	(segment
		(start 435.552342 -362.681774)
		(end 435.552342 -369.902486)
		(width 0.127)
		(layer "In6.Cu")
		(net "SVID_ALERT0_CPU0_R_N")
	)
	(segment
		(start 351.783904 -364.382812)
		(end 350.27489 -362.873798)
		(width 0.127)
		(layer "In6.Cu")
		(net "SVID_ALERT0_CPU0_R_N")
	)
	(segment
		(start 432.639724 -139.716256)
		(end 435.220364 -139.716256)
		(width 0.127)
		(layer "In6.Cu")
		(net "SVID_ALERT0_CPU0_R_N")
	)
	(segment
		(start 350.27489 -362.873798)
		(end 346.76969 -362.873798)
		(width 0.127)
		(layer "In6.Cu")
		(net "SVID_ALERT0_CPU0_R_N")
	)
	(segment
		(start 421.9194 -144.511268)
		(end 401.553426 -144.511268)
		(width 0.127)
		(layer "In13.Cu")
		(net "SVID_ALERT0_CPU0_R_N")
	)
	(segment
		(start 347.679772 -149.240748)
		(end 307.316124 -149.240748)
		(width 0.127)
		(layer "In13.Cu")
		(net "SVID_ALERT0_CPU0_R_N")
	)
	(segment
		(start 394.588746 -148.262848)
		(end 348.657672 -148.262848)
		(width 0.127)
		(layer "In13.Cu")
		(net "SVID_ALERT0_CPU0_R_N")
	)
	(segment
		(start 395.566646 -147.284948)
		(end 394.588746 -148.262848)
		(width 0.127)
		(layer "In13.Cu")
		(net "SVID_ALERT0_CPU0_R_N")
	)
	(segment
		(start 433.10048 -142.131288)
		(end 430.5046 -144.727168)
		(width 0.127)
		(layer "In13.Cu")
		(net "SVID_ALERT0_CPU0_R_N")
	)
	(segment
		(start 427.13402 -144.727168)
		(end 426.4406 -144.033748)
		(width 0.127)
		(layer "In13.Cu")
		(net "SVID_ALERT0_CPU0_R_N")
	)
	(segment
		(start 398.779746 -147.284948)
		(end 395.566646 -147.284948)
		(width 0.127)
		(layer "In13.Cu")
		(net "SVID_ALERT0_CPU0_R_N")
	)
	(segment
		(start 348.657672 -148.262848)
		(end 347.679772 -149.240748)
		(width 0.127)
		(layer "In13.Cu")
		(net "SVID_ALERT0_CPU0_R_N")
	)
	(segment
		(start 430.5046 -144.727168)
		(end 427.13402 -144.727168)
		(width 0.127)
		(layer "In13.Cu")
		(net "SVID_ALERT0_CPU0_R_N")
	)
	(segment
		(start 302.82388 -184.450228)
		(end 301.164498 -186.10961)
		(width 0.127)
		(layer "In13.Cu")
		(net "SVID_ALERT0_CPU0_R_N")
	)
	(segment
		(start 401.553426 -144.511268)
		(end 398.779746 -147.284948)
		(width 0.127)
		(layer "In13.Cu")
		(net "SVID_ALERT0_CPU0_R_N")
	)
	(segment
		(start 302.82388 -153.732992)
		(end 302.82388 -184.450228)
		(width 0.127)
		(layer "In13.Cu")
		(net "SVID_ALERT0_CPU0_R_N")
	)
	(segment
		(start 426.4406 -144.033748)
		(end 422.39692 -144.033748)
		(width 0.127)
		(layer "In13.Cu")
		(net "SVID_ALERT0_CPU0_R_N")
	)
	(segment
		(start 432.639724 -139.716256)
		(end 433.10048 -140.177012)
		(width 0.127)
		(layer "In13.Cu")
		(net "SVID_ALERT0_CPU0_R_N")
	)
	(segment
		(start 433.10048 -140.177012)
		(end 433.10048 -142.131288)
		(width 0.127)
		(layer "In13.Cu")
		(net "SVID_ALERT0_CPU0_R_N")
	)
	(segment
		(start 301.164498 -186.10961)
		(end 301.164498 -189.09665)
		(width 0.127)
		(layer "In13.Cu")
		(net "SVID_ALERT0_CPU0_R_N")
	)
	(segment
		(start 422.39692 -144.033748)
		(end 421.9194 -144.511268)
		(width 0.127)
		(layer "In13.Cu")
		(net "SVID_ALERT0_CPU0_R_N")
	)
	(segment
		(start 307.316124 -149.240748)
		(end 302.82388 -153.732992)
		(width 0.127)
		(layer "In13.Cu")
		(net "SVID_ALERT0_CPU0_R_N")
	)
	(segment
		(start 355.82098 -234.69219)
		(end 355.821234 -234.691936)
		(width 0.12954)
		(layer "F.Cu")
		(net "SVID_ALERT0_CPU0_N")
	)
	(segment
		(start 355.821234 -234.691936)
		(end 355.821234 -234.15625)
		(width 0.12954)
		(layer "F.Cu")
		(net "SVID_ALERT0_CPU0_N")
	)
	(via
		(at 318.558164 -239.395254)
		(size 0.6604)
		(drill 0.3302)
		(layers "F.Cu" "B.Cu")
		(net "SVID_ALERT0_CPU0_N")
	)
	(via
		(at 355.821234 -234.15625)
		(size 0.4572)
		(drill 0.2032)
		(layers "F.Cu" "B.Cu")
		(net "SVID_ALERT0_CPU0_N")
	)
	(segment
		(start 341.926164 -235.46816)
		(end 341.911432 -235.459524)
		(width 0.0889)
		(layer "B.Cu")
		(net "SVID_ALERT0_CPU0_N")
	)
	(segment
		(start 318.558164 -239.395254)
		(end 314.759086 -239.395254)
		(width 0.12954)
		(layer "B.Cu")
		(net "SVID_ALERT0_CPU0_N")
	)
	(segment
		(start 343.805764 -235.46816)
		(end 343.791032 -235.459524)
		(width 0.0889)
		(layer "B.Cu")
		(net "SVID_ALERT0_CPU0_N")
	)
	(segment
		(start 340.986364 -235.46816)
		(end 340.971632 -235.459524)
		(width 0.0889)
		(layer "B.Cu")
		(net "SVID_ALERT0_CPU0_N")
	)
	(segment
		(start 335.312258 -235.54563)
		(end 334.955388 -235.9025)
		(width 0.12954)
		(layer "B.Cu")
		(net "SVID_ALERT0_CPU0_N")
	)
	(segment
		(start 355.447092 -234.530392)
		(end 354.466906 -234.530392)
		(width 0.0889)
		(layer "B.Cu")
		(net "SVID_ALERT0_CPU0_N")
	)
	(segment
		(start 348.504764 -235.46816)
		(end 348.490032 -235.459524)
		(width 0.0889)
		(layer "B.Cu")
		(net "SVID_ALERT0_CPU0_N")
	)
	(segment
		(start 338.717382 -235.459524)
		(end 338.706968 -235.46562)
		(width 0.0889)
		(layer "B.Cu")
		(net "SVID_ALERT0_CPU0_N")
	)
	(segment
		(start 355.821234 -234.15625)
		(end 355.447092 -234.530392)
		(width 0.0889)
		(layer "B.Cu")
		(net "SVID_ALERT0_CPU0_N")
	)
	(segment
		(start 310.77916 -239.809274)
		(end 307.411882 -239.809274)
		(width 0.12954)
		(layer "B.Cu")
		(net "SVID_ALERT0_CPU0_N")
	)
	(segment
		(start 347.564964 -235.46816)
		(end 347.550232 -235.459524)
		(width 0.0889)
		(layer "B.Cu")
		(net "SVID_ALERT0_CPU0_N")
	)
	(segment
		(start 342.865964 -235.46816)
		(end 342.851232 -235.459524)
		(width 0.0889)
		(layer "B.Cu")
		(net "SVID_ALERT0_CPU0_N")
	)
	(segment
		(start 350.21012 -235.271818)
		(end 350.112076 -235.369862)
		(width 0.0889)
		(layer "B.Cu")
		(net "SVID_ALERT0_CPU0_N")
	)
	(segment
		(start 307.411882 -239.809274)
		(end 304.834798 -237.23219)
		(width 0.12954)
		(layer "B.Cu")
		(net "SVID_ALERT0_CPU0_N")
	)
	(segment
		(start 304.834798 -237.23219)
		(end 304.834798 -197.86473)
		(width 0.12954)
		(layer "B.Cu")
		(net "SVID_ALERT0_CPU0_N")
	)
	(segment
		(start 346.625164 -235.46816)
		(end 346.610432 -235.459524)
		(width 0.0889)
		(layer "B.Cu")
		(net "SVID_ALERT0_CPU0_N")
	)
	(segment
		(start 335.755996 -235.46943)
		(end 335.388458 -235.46943)
		(width 0.0889)
		(layer "B.Cu")
		(net "SVID_ALERT0_CPU0_N")
	)
	(segment
		(start 314.759086 -239.395254)
		(end 314.58916 -239.225328)
		(width 0.12954)
		(layer "B.Cu")
		(net "SVID_ALERT0_CPU0_N")
	)
	(segment
		(start 349.444564 -235.46816)
		(end 349.429832 -235.459524)
		(width 0.0889)
		(layer "B.Cu")
		(net "SVID_ALERT0_CPU0_N")
	)
	(segment
		(start 339.102192 -235.46562)
		(end 339.091778 -235.459524)
		(width 0.0889)
		(layer "B.Cu")
		(net "SVID_ALERT0_CPU0_N")
	)
	(segment
		(start 340.046564 -235.46816)
		(end 340.031832 -235.459524)
		(width 0.0889)
		(layer "B.Cu")
		(net "SVID_ALERT0_CPU0_N")
	)
	(segment
		(start 330.624434 -236.92358)
		(end 328.15276 -239.395254)
		(width 0.12954)
		(layer "B.Cu")
		(net "SVID_ALERT0_CPU0_N")
	)
	(segment
		(start 335.388458 -235.46943)
		(end 335.312258 -235.54563)
		(width 0.0889)
		(layer "B.Cu")
		(net "SVID_ALERT0_CPU0_N")
	)
	(segment
		(start 336.155538 -235.369608)
		(end 335.855818 -235.369608)
		(width 0.0889)
		(layer "B.Cu")
		(net "SVID_ALERT0_CPU0_N")
	)
	(segment
		(start 353.015804 -235.271818)
		(end 350.21012 -235.271818)
		(width 0.0889)
		(layer "B.Cu")
		(net "SVID_ALERT0_CPU0_N")
	)
	(segment
		(start 328.15276 -239.395254)
		(end 318.558164 -239.395254)
		(width 0.12954)
		(layer "B.Cu")
		(net "SVID_ALERT0_CPU0_N")
	)
	(segment
		(start 334.795368 -235.9025)
		(end 333.774288 -236.92358)
		(width 0.12954)
		(layer "B.Cu")
		(net "SVID_ALERT0_CPU0_N")
	)
	(segment
		(start 311.363106 -239.225328)
		(end 310.77916 -239.809274)
		(width 0.12954)
		(layer "B.Cu")
		(net "SVID_ALERT0_CPU0_N")
	)
	(segment
		(start 345.680792 -235.46562)
		(end 345.670378 -235.459524)
		(width 0.0889)
		(layer "B.Cu")
		(net "SVID_ALERT0_CPU0_N")
	)
	(segment
		(start 354.466906 -234.530392)
		(end 353.608132 -235.389166)
		(width 0.0889)
		(layer "B.Cu")
		(net "SVID_ALERT0_CPU0_N")
	)
	(segment
		(start 333.774288 -236.92358)
		(end 330.624434 -236.92358)
		(width 0.12954)
		(layer "B.Cu")
		(net "SVID_ALERT0_CPU0_N")
	)
	(segment
		(start 353.183444 -235.389166)
		(end 353.015804 -235.271818)
		(width 0.0889)
		(layer "B.Cu")
		(net "SVID_ALERT0_CPU0_N")
	)
	(segment
		(start 335.855818 -235.369608)
		(end 335.755996 -235.46943)
		(width 0.0889)
		(layer "B.Cu")
		(net "SVID_ALERT0_CPU0_N")
	)
	(segment
		(start 353.608132 -235.389166)
		(end 353.183444 -235.389166)
		(width 0.0889)
		(layer "B.Cu")
		(net "SVID_ALERT0_CPU0_N")
	)
	(segment
		(start 303.554638 -196.58457)
		(end 303.554638 -195.12026)
		(width 0.12954)
		(layer "B.Cu")
		(net "SVID_ALERT0_CPU0_N")
	)
	(segment
		(start 334.955388 -235.9025)
		(end 334.795368 -235.9025)
		(width 0.12954)
		(layer "B.Cu")
		(net "SVID_ALERT0_CPU0_N")
	)
	(segment
		(start 337.227164 -235.46816)
		(end 337.212432 -235.459524)
		(width 0.0889)
		(layer "B.Cu")
		(net "SVID_ALERT0_CPU0_N")
	)
	(segment
		(start 336.287364 -235.46816)
		(end 336.272632 -235.459524)
		(width 0.0889)
		(layer "B.Cu")
		(net "SVID_ALERT0_CPU0_N")
	)
	(segment
		(start 304.834798 -197.86473)
		(end 303.554638 -196.58457)
		(width 0.12954)
		(layer "B.Cu")
		(net "SVID_ALERT0_CPU0_N")
	)
	(segment
		(start 345.295982 -235.459524)
		(end 345.285568 -235.46562)
		(width 0.0889)
		(layer "B.Cu")
		(net "SVID_ALERT0_CPU0_N")
	)
	(segment
		(start 314.58916 -239.225328)
		(end 311.363106 -239.225328)
		(width 0.12954)
		(layer "B.Cu")
		(net "SVID_ALERT0_CPU0_N")
	)
	(arc
		(start 339.657436 -235.459524)
		(mid 339.380623 -235.535394)
		(end 339.102192 -235.46562)
		(width 0.0889)
		(layer "B.Cu")
		(net "SVID_ALERT0_CPU0_N")
	)
	(arc
		(start 345.285568 -235.46562)
		(mid 345.00739 -235.535343)
		(end 344.730832 -235.459524)
		(width 0.0889)
		(layer "B.Cu")
		(net "SVID_ALERT0_CPU0_N")
	)
	(arc
		(start 346.236036 -235.459524)
		(mid 345.959223 -235.535394)
		(end 345.680792 -235.46562)
		(width 0.0889)
		(layer "B.Cu")
		(net "SVID_ALERT0_CPU0_N")
	)
	(arc
		(start 343.416636 -235.459524)
		(mid 343.142437 -235.535359)
		(end 342.865964 -235.46816)
		(width 0.0889)
		(layer "B.Cu")
		(net "SVID_ALERT0_CPU0_N")
	)
	(arc
		(start 344.730832 -235.459524)
		(mid 344.543634 -235.409381)
		(end 344.356436 -235.459524)
		(width 0.0889)
		(layer "B.Cu")
		(net "SVID_ALERT0_CPU0_N")
	)
	(arc
		(start 337.212432 -235.459524)
		(mid 337.025234 -235.409381)
		(end 336.838036 -235.459524)
		(width 0.0889)
		(layer "B.Cu")
		(net "SVID_ALERT0_CPU0_N")
	)
	(arc
		(start 338.152232 -235.459524)
		(mid 337.965034 -235.409381)
		(end 337.777836 -235.459524)
		(width 0.0889)
		(layer "B.Cu")
		(net "SVID_ALERT0_CPU0_N")
	)
	(arc
		(start 341.537036 -235.459524)
		(mid 341.262837 -235.535359)
		(end 340.986364 -235.46816)
		(width 0.0889)
		(layer "B.Cu")
		(net "SVID_ALERT0_CPU0_N")
	)
	(arc
		(start 340.597236 -235.459524)
		(mid 340.323037 -235.535359)
		(end 340.046564 -235.46816)
		(width 0.0889)
		(layer "B.Cu")
		(net "SVID_ALERT0_CPU0_N")
	)
	(arc
		(start 350.112076 -235.369862)
		(mid 349.794596 -235.529439)
		(end 349.444564 -235.46816)
		(width 0.0889)
		(layer "B.Cu")
		(net "SVID_ALERT0_CPU0_N")
	)
	(arc
		(start 342.851232 -235.459524)
		(mid 342.664034 -235.409381)
		(end 342.476836 -235.459524)
		(width 0.0889)
		(layer "B.Cu")
		(net "SVID_ALERT0_CPU0_N")
	)
	(arc
		(start 346.610432 -235.459524)
		(mid 346.423234 -235.409381)
		(end 346.236036 -235.459524)
		(width 0.0889)
		(layer "B.Cu")
		(net "SVID_ALERT0_CPU0_N")
	)
	(arc
		(start 340.971632 -235.459524)
		(mid 340.784434 -235.409381)
		(end 340.597236 -235.459524)
		(width 0.0889)
		(layer "B.Cu")
		(net "SVID_ALERT0_CPU0_N")
	)
	(arc
		(start 339.091778 -235.459524)
		(mid 338.90458 -235.409381)
		(end 338.717382 -235.459524)
		(width 0.0889)
		(layer "B.Cu")
		(net "SVID_ALERT0_CPU0_N")
	)
	(arc
		(start 344.356436 -235.459524)
		(mid 344.082237 -235.535359)
		(end 343.805764 -235.46816)
		(width 0.0889)
		(layer "B.Cu")
		(net "SVID_ALERT0_CPU0_N")
	)
	(arc
		(start 343.791032 -235.459524)
		(mid 343.603834 -235.409381)
		(end 343.416636 -235.459524)
		(width 0.0889)
		(layer "B.Cu")
		(net "SVID_ALERT0_CPU0_N")
	)
	(arc
		(start 342.476836 -235.459524)
		(mid 342.202637 -235.535359)
		(end 341.926164 -235.46816)
		(width 0.0889)
		(layer "B.Cu")
		(net "SVID_ALERT0_CPU0_N")
	)
	(arc
		(start 347.175836 -235.459524)
		(mid 346.901637 -235.535359)
		(end 346.625164 -235.46816)
		(width 0.0889)
		(layer "B.Cu")
		(net "SVID_ALERT0_CPU0_N")
	)
	(arc
		(start 340.031832 -235.459524)
		(mid 339.844634 -235.409381)
		(end 339.657436 -235.459524)
		(width 0.0889)
		(layer "B.Cu")
		(net "SVID_ALERT0_CPU0_N")
	)
	(arc
		(start 349.055436 -235.459524)
		(mid 348.781237 -235.535359)
		(end 348.504764 -235.46816)
		(width 0.0889)
		(layer "B.Cu")
		(net "SVID_ALERT0_CPU0_N")
	)
	(arc
		(start 348.490032 -235.459524)
		(mid 348.302834 -235.409381)
		(end 348.115636 -235.459524)
		(width 0.0889)
		(layer "B.Cu")
		(net "SVID_ALERT0_CPU0_N")
	)
	(arc
		(start 347.550232 -235.459524)
		(mid 347.363034 -235.409381)
		(end 347.175836 -235.459524)
		(width 0.0889)
		(layer "B.Cu")
		(net "SVID_ALERT0_CPU0_N")
	)
	(arc
		(start 348.115636 -235.459524)
		(mid 347.841437 -235.535359)
		(end 347.564964 -235.46816)
		(width 0.0889)
		(layer "B.Cu")
		(net "SVID_ALERT0_CPU0_N")
	)
	(arc
		(start 338.706968 -235.46562)
		(mid 338.42879 -235.535343)
		(end 338.152232 -235.459524)
		(width 0.0889)
		(layer "B.Cu")
		(net "SVID_ALERT0_CPU0_N")
	)
	(arc
		(start 336.272632 -235.459524)
		(mid 336.211143 -235.418398)
		(end 336.155538 -235.369608)
		(width 0.0889)
		(layer "B.Cu")
		(net "SVID_ALERT0_CPU0_N")
	)
	(arc
		(start 345.670378 -235.459524)
		(mid 345.48318 -235.409381)
		(end 345.295982 -235.459524)
		(width 0.0889)
		(layer "B.Cu")
		(net "SVID_ALERT0_CPU0_N")
	)
	(arc
		(start 337.777836 -235.459524)
		(mid 337.503637 -235.535359)
		(end 337.227164 -235.46816)
		(width 0.0889)
		(layer "B.Cu")
		(net "SVID_ALERT0_CPU0_N")
	)
	(arc
		(start 341.911432 -235.459524)
		(mid 341.724234 -235.409381)
		(end 341.537036 -235.459524)
		(width 0.0889)
		(layer "B.Cu")
		(net "SVID_ALERT0_CPU0_N")
	)
	(arc
		(start 336.838036 -235.459524)
		(mid 336.563837 -235.535359)
		(end 336.287364 -235.46816)
		(width 0.0889)
		(layer "B.Cu")
		(net "SVID_ALERT0_CPU0_N")
	)
	(arc
		(start 349.429832 -235.459524)
		(mid 349.242634 -235.409381)
		(end 349.055436 -235.459524)
		(width 0.0889)
		(layer "B.Cu")
		(net "SVID_ALERT0_CPU0_N")
	)
	(segment
		(start 184.461658 -17.549622)
		(end 184.33796 -17.67332)
		(width 0.12954)
		(layer "F.Cu")
		(net "SPI_TPM_CS_N")
	)
	(segment
		(start 184.461912 -16.550132)
		(end 184.461658 -16.550386)
		(width 0.12954)
		(layer "F.Cu")
		(net "SPI_TPM_CS_N")
	)
	(segment
		(start 184.461658 -16.550386)
		(end 184.461658 -17.549622)
		(width 0.12954)
		(layer "F.Cu")
		(net "SPI_TPM_CS_N")
	)
	(via
		(at 184.33796 -17.67332)
		(size 0.508)
		(drill 0.254)
		(layers "F.Cu" "B.Cu")
		(net "SPI_TPM_CS_N")
	)
	(via
		(at 332.74 -28.842208)
		(size 0.6604)
		(drill 0.3302)
		(layers "F.Cu" "B.Cu")
		(net "SPI_TPM_CS_N")
	)
	(segment
		(start 292.13302 -32.842962)
		(end 303.540414 -21.435568)
		(width 0.12954)
		(layer "B.Cu")
		(net "SPI_TPM_CS_N")
	)
	(segment
		(start 166.3954 -24.874728)
		(end 166.3954 -32.230568)
		(width 0.12954)
		(layer "B.Cu")
		(net "SPI_TPM_CS_N")
	)
	(segment
		(start 326.64908 -22.906228)
		(end 330.58862 -22.906228)
		(width 0.12954)
		(layer "B.Cu")
		(net "SPI_TPM_CS_N")
	)
	(segment
		(start 332.543912 -30.734254)
		(end 332.543912 -30.986222)
		(width 0.12954)
		(layer "B.Cu")
		(net "SPI_TPM_CS_N")
	)
	(segment
		(start 181.597554 -43.151298)
		(end 183.06161 -43.151298)
		(width 0.12954)
		(layer "B.Cu")
		(net "SPI_TPM_CS_N")
	)
	(segment
		(start 206.27467 -45.916088)
		(end 213.905846 -49.077118)
		(width 0.12954)
		(layer "B.Cu")
		(net "SPI_TPM_CS_N")
	)
	(segment
		(start 319.640712 -21.826474)
		(end 322.067428 -21.826474)
		(width 0.12954)
		(layer "B.Cu")
		(net "SPI_TPM_CS_N")
	)
	(segment
		(start 285.32582 -49.276762)
		(end 292.13302 -32.842962)
		(width 0.12954)
		(layer "B.Cu")
		(net "SPI_TPM_CS_N")
	)
	(segment
		(start 333.65186 -26.706068)
		(end 333.65186 -27.930348)
		(width 0.12954)
		(layer "B.Cu")
		(net "SPI_TPM_CS_N")
	)
	(segment
		(start 166.3954 -32.230568)
		(end 170.25366 -36.088828)
		(width 0.12954)
		(layer "B.Cu")
		(net "SPI_TPM_CS_N")
	)
	(segment
		(start 241.11204 -67.053968)
		(end 242.0493 -67.991228)
		(width 0.12954)
		(layer "B.Cu")
		(net "SPI_TPM_CS_N")
	)
	(segment
		(start 333.65186 -27.930348)
		(end 332.74 -28.842208)
		(width 0.12954)
		(layer "B.Cu")
		(net "SPI_TPM_CS_N")
	)
	(segment
		(start 183.656478 -16.991838)
		(end 166.293038 -16.991838)
		(width 0.12954)
		(layer "B.Cu")
		(net "SPI_TPM_CS_N")
	)
	(segment
		(start 184.33796 -17.67332)
		(end 183.656478 -16.991838)
		(width 0.12954)
		(layer "B.Cu")
		(net "SPI_TPM_CS_N")
	)
	(segment
		(start 183.48452 -44.467018)
		(end 186.230768 -47.213266)
		(width 0.12954)
		(layer "B.Cu")
		(net "SPI_TPM_CS_N")
	)
	(segment
		(start 325.17842 -21.435568)
		(end 326.64908 -22.906228)
		(width 0.12954)
		(layer "B.Cu")
		(net "SPI_TPM_CS_N")
	)
	(segment
		(start 332.74 -28.842208)
		(end 332.74 -30.260798)
		(width 0.12954)
		(layer "B.Cu")
		(net "SPI_TPM_CS_N")
	)
	(segment
		(start 322.458334 -21.435568)
		(end 325.17842 -21.435568)
		(width 0.12954)
		(layer "B.Cu")
		(net "SPI_TPM_CS_N")
	)
	(segment
		(start 249.06986 -67.053968)
		(end 253.554738 -67.053968)
		(width 0.12954)
		(layer "B.Cu")
		(net "SPI_TPM_CS_N")
	)
	(segment
		(start 273.070574 -61.532008)
		(end 285.32582 -49.276762)
		(width 0.12954)
		(layer "B.Cu")
		(net "SPI_TPM_CS_N")
	)
	(segment
		(start 248.1326 -67.991228)
		(end 249.06986 -67.053968)
		(width 0.12954)
		(layer "B.Cu")
		(net "SPI_TPM_CS_N")
	)
	(segment
		(start 332.74 -30.260798)
		(end 332.543912 -30.734254)
		(width 0.12954)
		(layer "B.Cu")
		(net "SPI_TPM_CS_N")
	)
	(segment
		(start 183.06161 -43.151298)
		(end 183.48452 -43.574208)
		(width 0.12954)
		(layer "B.Cu")
		(net "SPI_TPM_CS_N")
	)
	(segment
		(start 253.554738 -67.053968)
		(end 258.292346 -62.31636)
		(width 0.12954)
		(layer "B.Cu")
		(net "SPI_TPM_CS_N")
	)
	(segment
		(start 198.62038 -45.916088)
		(end 206.27467 -45.916088)
		(width 0.12954)
		(layer "B.Cu")
		(net "SPI_TPM_CS_N")
	)
	(segment
		(start 170.25366 -37.523928)
		(end 172.15993 -39.430198)
		(width 0.12954)
		(layer "B.Cu")
		(net "SPI_TPM_CS_N")
	)
	(segment
		(start 183.48452 -43.574208)
		(end 183.48452 -44.467018)
		(width 0.12954)
		(layer "B.Cu")
		(net "SPI_TPM_CS_N")
	)
	(segment
		(start 173.72584 -39.430198)
		(end 180.811424 -42.365168)
		(width 0.12954)
		(layer "B.Cu")
		(net "SPI_TPM_CS_N")
	)
	(segment
		(start 164.82695 -18.457926)
		(end 164.82695 -23.306278)
		(width 0.12954)
		(layer "B.Cu")
		(net "SPI_TPM_CS_N")
	)
	(segment
		(start 197.323202 -47.213266)
		(end 198.62038 -45.916088)
		(width 0.12954)
		(layer "B.Cu")
		(net "SPI_TPM_CS_N")
	)
	(segment
		(start 180.811424 -42.365168)
		(end 181.597554 -43.151298)
		(width 0.12954)
		(layer "B.Cu")
		(net "SPI_TPM_CS_N")
	)
	(segment
		(start 258.292346 -62.31636)
		(end 260.185916 -61.532008)
		(width 0.12954)
		(layer "B.Cu")
		(net "SPI_TPM_CS_N")
	)
	(segment
		(start 332.23708 -24.554688)
		(end 332.23708 -25.291288)
		(width 0.12954)
		(layer "B.Cu")
		(net "SPI_TPM_CS_N")
	)
	(segment
		(start 213.905846 -49.077118)
		(end 230.584756 -65.756028)
		(width 0.12954)
		(layer "B.Cu")
		(net "SPI_TPM_CS_N")
	)
	(segment
		(start 330.58862 -22.906228)
		(end 332.23708 -24.554688)
		(width 0.12954)
		(layer "B.Cu")
		(net "SPI_TPM_CS_N")
	)
	(segment
		(start 164.82695 -23.306278)
		(end 166.3954 -24.874728)
		(width 0.12954)
		(layer "B.Cu")
		(net "SPI_TPM_CS_N")
	)
	(segment
		(start 172.15993 -39.430198)
		(end 173.72584 -39.430198)
		(width 0.12954)
		(layer "B.Cu")
		(net "SPI_TPM_CS_N")
	)
	(segment
		(start 233.718862 -67.053968)
		(end 241.11204 -67.053968)
		(width 0.12954)
		(layer "B.Cu")
		(net "SPI_TPM_CS_N")
	)
	(segment
		(start 166.293038 -16.991838)
		(end 164.82695 -18.457926)
		(width 0.12954)
		(layer "B.Cu")
		(net "SPI_TPM_CS_N")
	)
	(segment
		(start 230.584756 -65.756028)
		(end 233.718862 -67.053968)
		(width 0.12954)
		(layer "B.Cu")
		(net "SPI_TPM_CS_N")
	)
	(segment
		(start 260.185916 -61.532008)
		(end 273.070574 -61.532008)
		(width 0.12954)
		(layer "B.Cu")
		(net "SPI_TPM_CS_N")
	)
	(segment
		(start 186.230768 -47.213266)
		(end 197.323202 -47.213266)
		(width 0.12954)
		(layer "B.Cu")
		(net "SPI_TPM_CS_N")
	)
	(segment
		(start 319.249806 -21.435568)
		(end 319.640712 -21.826474)
		(width 0.12954)
		(layer "B.Cu")
		(net "SPI_TPM_CS_N")
	)
	(segment
		(start 322.067428 -21.826474)
		(end 322.458334 -21.435568)
		(width 0.12954)
		(layer "B.Cu")
		(net "SPI_TPM_CS_N")
	)
	(segment
		(start 303.540414 -21.435568)
		(end 319.249806 -21.435568)
		(width 0.12954)
		(layer "B.Cu")
		(net "SPI_TPM_CS_N")
	)
	(segment
		(start 332.23708 -25.291288)
		(end 333.65186 -26.706068)
		(width 0.12954)
		(layer "B.Cu")
		(net "SPI_TPM_CS_N")
	)
	(segment
		(start 242.0493 -67.991228)
		(end 248.1326 -67.991228)
		(width 0.12954)
		(layer "B.Cu")
		(net "SPI_TPM_CS_N")
	)
	(segment
		(start 170.25366 -36.088828)
		(end 170.25366 -37.523928)
		(width 0.12954)
		(layer "B.Cu")
		(net "SPI_TPM_CS_N")
	)
	(segment
		(start 170.466766 -17.94637)
		(end 169.65676 -18.756376)
		(width 0.12954)
		(layer "F.Cu")
		(net "SPI_SYS_WP_IO2")
	)
	(segment
		(start 170.46702 -16.550132)
		(end 170.46702 -17.465802)
		(width 0.12954)
		(layer "F.Cu")
		(net "SPI_SYS_WP_IO2")
	)
	(segment
		(start 169.65676 -18.756376)
		(end 169.65676 -20.356068)
		(width 0.12954)
		(layer "F.Cu")
		(net "SPI_SYS_WP_IO2")
	)
	(segment
		(start 170.466766 -17.466056)
		(end 170.466766 -17.94637)
		(width 0.12954)
		(layer "F.Cu")
		(net "SPI_SYS_WP_IO2")
	)
	(segment
		(start 170.46702 -17.465802)
		(end 170.466766 -17.466056)
		(width 0.12954)
		(layer "F.Cu")
		(net "SPI_SYS_WP_IO2")
	)
	(via
		(at 169.65676 -20.356068)
		(size 0.508)
		(drill 0.254)
		(layers "F.Cu" "B.Cu")
		(net "SPI_SYS_WP_IO2")
	)
	(segment
		(start 282.908756 -42.916348)
		(end 283.33954 -42.916348)
		(width 0.12954)
		(layer "B.Cu")
		(net "SPI_SYS_WP_IO2")
	)
	(segment
		(start 336.738976 -25.273254)
		(end 336.738976 -27.330908)
		(width 0.12954)
		(layer "B.Cu")
		(net "SPI_SYS_WP_IO2")
	)
	(segment
		(start 283.33954 -40.366188)
		(end 283.46908 -40.236648)
		(width 0.12954)
		(layer "B.Cu")
		(net "SPI_SYS_WP_IO2")
	)
	(segment
		(start 282.779216 -42.149268)
		(end 282.779216 -41.770808)
		(width 0.12954)
		(layer "B.Cu")
		(net "SPI_SYS_WP_IO2")
	)
	(segment
		(start 332.00594 -21.796248)
		(end 335.134712 -21.796248)
		(width 0.12954)
		(layer "B.Cu")
		(net "SPI_SYS_WP_IO2")
	)
	(segment
		(start 197.97395 -44.128436)
		(end 211.12353 -44.128436)
		(width 0.12954)
		(layer "B.Cu")
		(net "SPI_SYS_WP_IO2")
	)
	(segment
		(start 196.788532 -45.313854)
		(end 197.97395 -44.128436)
		(width 0.12954)
		(layer "B.Cu")
		(net "SPI_SYS_WP_IO2")
	)
	(segment
		(start 282.908756 -42.278808)
		(end 282.779216 -42.149268)
		(width 0.12954)
		(layer "B.Cu")
		(net "SPI_SYS_WP_IO2")
	)
	(segment
		(start 334.46212 -30.122622)
		(end 334.46212 -32.490918)
		(width 0.12954)
		(layer "B.Cu")
		(net "SPI_SYS_WP_IO2")
	)
	(segment
		(start 283.46908 -42.408348)
		(end 283.33954 -42.278808)
		(width 0.12954)
		(layer "B.Cu")
		(net "SPI_SYS_WP_IO2")
	)
	(segment
		(start 282.908756 -41.641268)
		(end 283.33954 -41.641268)
		(width 0.12954)
		(layer "B.Cu")
		(net "SPI_SYS_WP_IO2")
	)
	(segment
		(start 282.779216 -45.974508)
		(end 282.779216 -45.596048)
		(width 0.12954)
		(layer "B.Cu")
		(net "SPI_SYS_WP_IO2")
	)
	(segment
		(start 231.45115 -64.456056)
		(end 233.240326 -65.197228)
		(width 0.12954)
		(layer "B.Cu")
		(net "SPI_SYS_WP_IO2")
	)
	(segment
		(start 283.46908 -40.236648)
		(end 283.46908 -39.858188)
		(width 0.12954)
		(layer "B.Cu")
		(net "SPI_SYS_WP_IO2")
	)
	(segment
		(start 282.908756 -40.366188)
		(end 283.33954 -40.366188)
		(width 0.12954)
		(layer "B.Cu")
		(net "SPI_SYS_WP_IO2")
	)
	(segment
		(start 283.46908 -38.961568)
		(end 283.46908 -38.159436)
		(width 0.12954)
		(layer "B.Cu")
		(net "SPI_SYS_WP_IO2")
	)
	(segment
		(start 283.46908 -44.958508)
		(end 283.33954 -44.828968)
		(width 0.12954)
		(layer "B.Cu")
		(net "SPI_SYS_WP_IO2")
	)
	(segment
		(start 183.77408 -40.452802)
		(end 183.77408 -41.332658)
		(width 0.12954)
		(layer "B.Cu")
		(net "SPI_SYS_WP_IO2")
	)
	(segment
		(start 283.46908 -42.786808)
		(end 283.46908 -42.408348)
		(width 0.12954)
		(layer "B.Cu")
		(net "SPI_SYS_WP_IO2")
	)
	(segment
		(start 180.388006 -37.066728)
		(end 183.77408 -40.452802)
		(width 0.12954)
		(layer "B.Cu")
		(net "SPI_SYS_WP_IO2")
	)
	(segment
		(start 336.47888 -22.701504)
		(end 337.56473 -23.787354)
		(width 0.12954)
		(layer "B.Cu")
		(net "SPI_SYS_WP_IO2")
	)
	(segment
		(start 282.908756 -39.728648)
		(end 282.779216 -39.599108)
		(width 0.12954)
		(layer "B.Cu")
		(net "SPI_SYS_WP_IO2")
	)
	(segment
		(start 312.83275 -18.912078)
		(end 329.12177 -18.912078)
		(width 0.12954)
		(layer "B.Cu")
		(net "SPI_SYS_WP_IO2")
	)
	(segment
		(start 283.33954 -42.278808)
		(end 282.908756 -42.278808)
		(width 0.12954)
		(layer "B.Cu")
		(net "SPI_SYS_WP_IO2")
	)
	(segment
		(start 169.65676 -20.356068)
		(end 168.4782 -21.534628)
		(width 0.12954)
		(layer "B.Cu")
		(net "SPI_SYS_WP_IO2")
	)
	(segment
		(start 259.880354 -60.000388)
		(end 271.976088 -60.000388)
		(width 0.12954)
		(layer "B.Cu")
		(net "SPI_SYS_WP_IO2")
	)
	(segment
		(start 283.33954 -43.553888)
		(end 282.908756 -43.553888)
		(width 0.12954)
		(layer "B.Cu")
		(net "SPI_SYS_WP_IO2")
	)
	(segment
		(start 283.46908 -38.159436)
		(end 302.105568 -19.522948)
		(width 0.12954)
		(layer "B.Cu")
		(net "SPI_SYS_WP_IO2")
	)
	(segment
		(start 233.240326 -65.197228)
		(end 253.245112 -65.197228)
		(width 0.12954)
		(layer "B.Cu")
		(net "SPI_SYS_WP_IO2")
	)
	(segment
		(start 282.908756 -47.379128)
		(end 282.779216 -47.249588)
		(width 0.12954)
		(layer "B.Cu")
		(net "SPI_SYS_WP_IO2")
	)
	(segment
		(start 282.908756 -44.828968)
		(end 282.779216 -44.699428)
		(width 0.12954)
		(layer "B.Cu")
		(net "SPI_SYS_WP_IO2")
	)
	(segment
		(start 257.424936 -61.017404)
		(end 259.880354 -60.000388)
		(width 0.12954)
		(layer "B.Cu")
		(net "SPI_SYS_WP_IO2")
	)
	(segment
		(start 282.779216 -39.220648)
		(end 282.908756 -39.091108)
		(width 0.12954)
		(layer "B.Cu")
		(net "SPI_SYS_WP_IO2")
	)
	(segment
		(start 282.779216 -40.495728)
		(end 282.908756 -40.366188)
		(width 0.12954)
		(layer "B.Cu")
		(net "SPI_SYS_WP_IO2")
	)
	(segment
		(start 282.779216 -43.424348)
		(end 282.779216 -43.045888)
		(width 0.12954)
		(layer "B.Cu")
		(net "SPI_SYS_WP_IO2")
	)
	(segment
		(start 183.77408 -41.332658)
		(end 187.755276 -45.313854)
		(width 0.12954)
		(layer "B.Cu")
		(net "SPI_SYS_WP_IO2")
	)
	(segment
		(start 282.779216 -39.599108)
		(end 282.779216 -39.220648)
		(width 0.12954)
		(layer "B.Cu")
		(net "SPI_SYS_WP_IO2")
	)
	(segment
		(start 215.350344 -48.35525)
		(end 231.45115 -64.456056)
		(width 0.12954)
		(layer "B.Cu")
		(net "SPI_SYS_WP_IO2")
	)
	(segment
		(start 282.908756 -39.091108)
		(end 283.33954 -39.091108)
		(width 0.12954)
		(layer "B.Cu")
		(net "SPI_SYS_WP_IO2")
	)
	(segment
		(start 283.46908 -48.507396)
		(end 283.46908 -47.508668)
		(width 0.12954)
		(layer "B.Cu")
		(net "SPI_SYS_WP_IO2")
	)
	(segment
		(start 168.4782 -30.183328)
		(end 175.3616 -37.066728)
		(width 0.12954)
		(layer "B.Cu")
		(net "SPI_SYS_WP_IO2")
	)
	(segment
		(start 211.12353 -44.128436)
		(end 214.730584 -47.73549)
		(width 0.12954)
		(layer "B.Cu")
		(net "SPI_SYS_WP_IO2")
	)
	(segment
		(start 337.061556 -28.625038)
		(end 336.553302 -29.133292)
		(width 0.12954)
		(layer "B.Cu")
		(net "SPI_SYS_WP_IO2")
	)
	(segment
		(start 283.33954 -46.741588)
		(end 283.46908 -46.612048)
		(width 0.12954)
		(layer "B.Cu")
		(net "SPI_SYS_WP_IO2")
	)
	(segment
		(start 282.779216 -44.699428)
		(end 282.779216 -44.320968)
		(width 0.12954)
		(layer "B.Cu")
		(net "SPI_SYS_WP_IO2")
	)
	(segment
		(start 282.779216 -45.596048)
		(end 282.908756 -45.466508)
		(width 0.12954)
		(layer "B.Cu")
		(net "SPI_SYS_WP_IO2")
	)
	(segment
		(start 283.33954 -39.091108)
		(end 283.46908 -38.961568)
		(width 0.12954)
		(layer "B.Cu")
		(net "SPI_SYS_WP_IO2")
	)
	(segment
		(start 283.33954 -42.916348)
		(end 283.46908 -42.786808)
		(width 0.12954)
		(layer "B.Cu")
		(net "SPI_SYS_WP_IO2")
	)
	(segment
		(start 282.779216 -44.320968)
		(end 282.908756 -44.191428)
		(width 0.12954)
		(layer "B.Cu")
		(net "SPI_SYS_WP_IO2")
	)
	(segment
		(start 282.779216 -40.874188)
		(end 282.779216 -40.495728)
		(width 0.12954)
		(layer "B.Cu")
		(net "SPI_SYS_WP_IO2")
	)
	(segment
		(start 283.46908 -45.336968)
		(end 283.46908 -44.958508)
		(width 0.12954)
		(layer "B.Cu")
		(net "SPI_SYS_WP_IO2")
	)
	(segment
		(start 337.56473 -23.787354)
		(end 337.56473 -24.4475)
		(width 0.12954)
		(layer "B.Cu")
		(net "SPI_SYS_WP_IO2")
	)
	(segment
		(start 214.730584 -47.73549)
		(end 214.892128 -47.73549)
		(width 0.12954)
		(layer "B.Cu")
		(net "SPI_SYS_WP_IO2")
	)
	(segment
		(start 215.852248 -47.530004)
		(end 215.852248 -47.691548)
		(width 0.12954)
		(layer "B.Cu")
		(net "SPI_SYS_WP_IO2")
	)
	(segment
		(start 336.039968 -22.701504)
		(end 336.47888 -22.701504)
		(width 0.12954)
		(layer "B.Cu")
		(net "SPI_SYS_WP_IO2")
	)
	(segment
		(start 283.33954 -41.641268)
		(end 283.46908 -41.511728)
		(width 0.12954)
		(layer "B.Cu")
		(net "SPI_SYS_WP_IO2")
	)
	(segment
		(start 282.779216 -46.871128)
		(end 282.908756 -46.741588)
		(width 0.12954)
		(layer "B.Cu")
		(net "SPI_SYS_WP_IO2")
	)
	(segment
		(start 336.553302 -29.133292)
		(end 335.45145 -29.133292)
		(width 0.12954)
		(layer "B.Cu")
		(net "SPI_SYS_WP_IO2")
	)
	(segment
		(start 334.46212 -32.490918)
		(end 334.744314 -32.773112)
		(width 0.12954)
		(layer "B.Cu")
		(net "SPI_SYS_WP_IO2")
	)
	(segment
		(start 283.46908 -39.858188)
		(end 283.33954 -39.728648)
		(width 0.12954)
		(layer "B.Cu")
		(net "SPI_SYS_WP_IO2")
	)
	(segment
		(start 302.105568 -19.522948)
		(end 312.22188 -19.522948)
		(width 0.12954)
		(layer "B.Cu")
		(net "SPI_SYS_WP_IO2")
	)
	(segment
		(start 335.134712 -21.796248)
		(end 336.039968 -22.701504)
		(width 0.12954)
		(layer "B.Cu")
		(net "SPI_SYS_WP_IO2")
	)
	(segment
		(start 283.33954 -45.466508)
		(end 283.46908 -45.336968)
		(width 0.12954)
		(layer "B.Cu")
		(net "SPI_SYS_WP_IO2")
	)
	(segment
		(start 168.4782 -21.534628)
		(end 168.4782 -30.183328)
		(width 0.12954)
		(layer "B.Cu")
		(net "SPI_SYS_WP_IO2")
	)
	(segment
		(start 283.46908 -43.683428)
		(end 283.33954 -43.553888)
		(width 0.12954)
		(layer "B.Cu")
		(net "SPI_SYS_WP_IO2")
	)
	(segment
		(start 215.852248 -47.691548)
		(end 215.350344 -48.193706)
		(width 0.12954)
		(layer "B.Cu")
		(net "SPI_SYS_WP_IO2")
	)
	(segment
		(start 283.33954 -39.728648)
		(end 282.908756 -39.728648)
		(width 0.12954)
		(layer "B.Cu")
		(net "SPI_SYS_WP_IO2")
	)
	(segment
		(start 283.33954 -44.191428)
		(end 283.46908 -44.061888)
		(width 0.12954)
		(layer "B.Cu")
		(net "SPI_SYS_WP_IO2")
	)
	(segment
		(start 283.46908 -41.511728)
		(end 283.46908 -41.133268)
		(width 0.12954)
		(layer "B.Cu")
		(net "SPI_SYS_WP_IO2")
	)
	(segment
		(start 337.56473 -24.4475)
		(end 336.738976 -25.273254)
		(width 0.12954)
		(layer "B.Cu")
		(net "SPI_SYS_WP_IO2")
	)
	(segment
		(start 283.33954 -47.379128)
		(end 282.908756 -47.379128)
		(width 0.12954)
		(layer "B.Cu")
		(net "SPI_SYS_WP_IO2")
	)
	(segment
		(start 282.908756 -43.553888)
		(end 282.779216 -43.424348)
		(width 0.12954)
		(layer "B.Cu")
		(net "SPI_SYS_WP_IO2")
	)
	(segment
		(start 271.976088 -60.000388)
		(end 283.46908 -48.507396)
		(width 0.12954)
		(layer "B.Cu")
		(net "SPI_SYS_WP_IO2")
	)
	(segment
		(start 215.350344 -48.193706)
		(end 215.350344 -48.35525)
		(width 0.12954)
		(layer "B.Cu")
		(net "SPI_SYS_WP_IO2")
	)
	(segment
		(start 282.908756 -46.104048)
		(end 282.779216 -45.974508)
		(width 0.12954)
		(layer "B.Cu")
		(net "SPI_SYS_WP_IO2")
	)
	(segment
		(start 282.908756 -44.191428)
		(end 283.33954 -44.191428)
		(width 0.12954)
		(layer "B.Cu")
		(net "SPI_SYS_WP_IO2")
	)
	(segment
		(start 282.779216 -47.249588)
		(end 282.779216 -46.871128)
		(width 0.12954)
		(layer "B.Cu")
		(net "SPI_SYS_WP_IO2")
	)
	(segment
		(start 253.245112 -65.197228)
		(end 257.424936 -61.017404)
		(width 0.12954)
		(layer "B.Cu")
		(net "SPI_SYS_WP_IO2")
	)
	(segment
		(start 282.779216 -43.045888)
		(end 282.908756 -42.916348)
		(width 0.12954)
		(layer "B.Cu")
		(net "SPI_SYS_WP_IO2")
	)
	(segment
		(start 283.33954 -41.003728)
		(end 282.908756 -41.003728)
		(width 0.12954)
		(layer "B.Cu")
		(net "SPI_SYS_WP_IO2")
	)
	(segment
		(start 329.12177 -18.912078)
		(end 332.00594 -21.796248)
		(width 0.12954)
		(layer "B.Cu")
		(net "SPI_SYS_WP_IO2")
	)
	(segment
		(start 214.892128 -47.73549)
		(end 215.394032 -47.233332)
		(width 0.12954)
		(layer "B.Cu")
		(net "SPI_SYS_WP_IO2")
	)
	(segment
		(start 282.908756 -46.741588)
		(end 283.33954 -46.741588)
		(width 0.12954)
		(layer "B.Cu")
		(net "SPI_SYS_WP_IO2")
	)
	(segment
		(start 282.908756 -41.003728)
		(end 282.779216 -40.874188)
		(width 0.12954)
		(layer "B.Cu")
		(net "SPI_SYS_WP_IO2")
	)
	(segment
		(start 335.45145 -29.133292)
		(end 334.46212 -30.122622)
		(width 0.12954)
		(layer "B.Cu")
		(net "SPI_SYS_WP_IO2")
	)
	(segment
		(start 215.394032 -47.233332)
		(end 215.555576 -47.233332)
		(width 0.12954)
		(layer "B.Cu")
		(net "SPI_SYS_WP_IO2")
	)
	(segment
		(start 337.061556 -27.653488)
		(end 337.061556 -28.625038)
		(width 0.12954)
		(layer "B.Cu")
		(net "SPI_SYS_WP_IO2")
	)
	(segment
		(start 312.22188 -19.522948)
		(end 312.83275 -18.912078)
		(width 0.12954)
		(layer "B.Cu")
		(net "SPI_SYS_WP_IO2")
	)
	(segment
		(start 187.755276 -45.313854)
		(end 196.788532 -45.313854)
		(width 0.12954)
		(layer "B.Cu")
		(net "SPI_SYS_WP_IO2")
	)
	(segment
		(start 283.46908 -46.233588)
		(end 283.33954 -46.104048)
		(width 0.12954)
		(layer "B.Cu")
		(net "SPI_SYS_WP_IO2")
	)
	(segment
		(start 282.779216 -41.770808)
		(end 282.908756 -41.641268)
		(width 0.12954)
		(layer "B.Cu")
		(net "SPI_SYS_WP_IO2")
	)
	(segment
		(start 283.46908 -46.612048)
		(end 283.46908 -46.233588)
		(width 0.12954)
		(layer "B.Cu")
		(net "SPI_SYS_WP_IO2")
	)
	(segment
		(start 175.3616 -37.066728)
		(end 180.388006 -37.066728)
		(width 0.12954)
		(layer "B.Cu")
		(net "SPI_SYS_WP_IO2")
	)
	(segment
		(start 283.33954 -44.828968)
		(end 282.908756 -44.828968)
		(width 0.12954)
		(layer "B.Cu")
		(net "SPI_SYS_WP_IO2")
	)
	(segment
		(start 283.46908 -41.133268)
		(end 283.33954 -41.003728)
		(width 0.12954)
		(layer "B.Cu")
		(net "SPI_SYS_WP_IO2")
	)
	(segment
		(start 215.555576 -47.233332)
		(end 215.852248 -47.530004)
		(width 0.12954)
		(layer "B.Cu")
		(net "SPI_SYS_WP_IO2")
	)
	(segment
		(start 283.46908 -44.061888)
		(end 283.46908 -43.683428)
		(width 0.12954)
		(layer "B.Cu")
		(net "SPI_SYS_WP_IO2")
	)
	(segment
		(start 283.33954 -46.104048)
		(end 282.908756 -46.104048)
		(width 0.12954)
		(layer "B.Cu")
		(net "SPI_SYS_WP_IO2")
	)
	(segment
		(start 336.738976 -27.330908)
		(end 337.061556 -27.653488)
		(width 0.12954)
		(layer "B.Cu")
		(net "SPI_SYS_WP_IO2")
	)
	(segment
		(start 283.46908 -47.508668)
		(end 283.33954 -47.379128)
		(width 0.12954)
		(layer "B.Cu")
		(net "SPI_SYS_WP_IO2")
	)
	(segment
		(start 282.908756 -45.466508)
		(end 283.33954 -45.466508)
		(width 0.12954)
		(layer "B.Cu")
		(net "SPI_SYS_WP_IO2")
	)
	(segment
		(start 171.666662 -17.466056)
		(end 171.666662 -18.466816)
		(width 0.12954)
		(layer "F.Cu")
		(net "SPI_SYS_MOSI")
	)
	(segment
		(start 171.666662 -18.466816)
		(end 171.20489 -18.928588)
		(width 0.12954)
		(layer "F.Cu")
		(net "SPI_SYS_MOSI")
	)
	(segment
		(start 171.666916 -16.550132)
		(end 171.666916 -17.465802)
		(width 0.12954)
		(layer "F.Cu")
		(net "SPI_SYS_MOSI")
	)
	(segment
		(start 171.666916 -17.465802)
		(end 171.666662 -17.466056)
		(width 0.12954)
		(layer "F.Cu")
		(net "SPI_SYS_MOSI")
	)
	(via
		(at 171.20489 -18.928588)
		(size 0.508)
		(drill 0.254)
		(layers "F.Cu" "B.Cu")
		(net "SPI_SYS_MOSI")
	)
	(segment
		(start 286.790892 -37.253418)
		(end 286.13989 -36.602416)
		(width 0.12954)
		(layer "B.Cu")
		(net "SPI_SYS_MOSI")
	)
	(segment
		(start 326.0979 -19.422618)
		(end 313.59221 -19.422618)
		(width 0.12954)
		(layer "B.Cu")
		(net "SPI_SYS_MOSI")
	)
	(segment
		(start 287.759902 -34.799016)
		(end 287.49244 -35.066478)
		(width 0.12954)
		(layer "B.Cu")
		(net "SPI_SYS_MOSI")
	)
	(segment
		(start 184.68594 -42.990008)
		(end 183.66994 -41.974008)
		(width 0.12954)
		(layer "B.Cu")
		(net "SPI_SYS_MOSI")
	)
	(segment
		(start 286.13989 -36.602416)
		(end 285.956502 -36.602416)
		(width 0.12954)
		(layer "B.Cu")
		(net "SPI_SYS_MOSI")
	)
	(segment
		(start 288.68878 -35.361118)
		(end 288.505392 -35.361118)
		(width 0.12954)
		(layer "B.Cu")
		(net "SPI_SYS_MOSI")
	)
	(segment
		(start 167.9448 -21.148548)
		(end 170.16476 -18.928588)
		(width 0.12954)
		(layer "B.Cu")
		(net "SPI_SYS_MOSI")
	)
	(segment
		(start 231.162606 -64.889634)
		(end 210.98764 -44.714668)
		(width 0.12954)
		(layer "B.Cu")
		(net "SPI_SYS_MOSI")
	)
	(segment
		(start 285.956502 -36.602416)
		(end 285.68904 -36.869878)
		(width 0.12954)
		(layer "B.Cu")
		(net "SPI_SYS_MOSI")
	)
	(segment
		(start 285.23819 -37.504116)
		(end 285.054802 -37.504116)
		(width 0.12954)
		(layer "B.Cu")
		(net "SPI_SYS_MOSI")
	)
	(segment
		(start 288.956242 -35.093656)
		(end 288.68878 -35.361118)
		(width 0.12954)
		(layer "B.Cu")
		(net "SPI_SYS_MOSI")
	)
	(segment
		(start 334.939132 -22.360128)
		(end 331.74686 -22.360128)
		(width 0.12954)
		(layer "B.Cu")
		(net "SPI_SYS_MOSI")
	)
	(segment
		(start 285.889192 -38.155118)
		(end 285.23819 -37.504116)
		(width 0.12954)
		(layer "B.Cu")
		(net "SPI_SYS_MOSI")
	)
	(segment
		(start 272.39595 -60.510928)
		(end 259.981954 -60.510928)
		(width 0.12954)
		(layer "B.Cu")
		(net "SPI_SYS_MOSI")
	)
	(segment
		(start 328.80935 -19.422618)
		(end 326.99452 -19.422618)
		(width 0.12954)
		(layer "B.Cu")
		(net "SPI_SYS_MOSI")
	)
	(segment
		(start 333.94904 -29.649928)
		(end 335.17332 -28.425648)
		(width 0.12954)
		(layer "B.Cu")
		(net "SPI_SYS_MOSI")
	)
	(segment
		(start 285.054802 -37.504116)
		(end 284.12694 -38.431978)
		(width 0.12954)
		(layer "B.Cu")
		(net "SPI_SYS_MOSI")
	)
	(segment
		(start 177.74666 -37.701728)
		(end 175.274224 -37.701728)
		(width 0.12954)
		(layer "B.Cu")
		(net "SPI_SYS_MOSI")
	)
	(segment
		(start 184.68594 -43.969178)
		(end 184.68594 -42.990008)
		(width 0.12954)
		(layer "B.Cu")
		(net "SPI_SYS_MOSI")
	)
	(segment
		(start 285.68904 -36.869878)
		(end 285.68904 -37.053266)
		(width 0.12954)
		(layer "B.Cu")
		(net "SPI_SYS_MOSI")
	)
	(segment
		(start 286.858202 -35.700716)
		(end 286.59074 -35.968178)
		(width 0.12954)
		(layer "B.Cu")
		(net "SPI_SYS_MOSI")
	)
	(segment
		(start 233.493056 -65.855088)
		(end 231.162606 -64.889634)
		(width 0.12954)
		(layer "B.Cu")
		(net "SPI_SYS_MOSI")
	)
	(segment
		(start 182.01894 -41.974008)
		(end 177.74666 -37.701728)
		(width 0.12954)
		(layer "B.Cu")
		(net "SPI_SYS_MOSI")
	)
	(segment
		(start 336.93608 -24.308562)
		(end 336.93608 -23.88108)
		(width 0.12954)
		(layer "B.Cu")
		(net "SPI_SYS_MOSI")
	)
	(segment
		(start 289.29584 -33.446466)
		(end 289.857942 -34.008568)
		(width 0.12954)
		(layer "B.Cu")
		(net "SPI_SYS_MOSI")
	)
	(segment
		(start 286.59074 -35.968178)
		(end 286.59074 -36.151566)
		(width 0.12954)
		(layer "B.Cu")
		(net "SPI_SYS_MOSI")
	)
	(segment
		(start 326.99452 -19.422618)
		(end 326.86498 -19.552158)
		(width 0.12954)
		(layer "B.Cu")
		(net "SPI_SYS_MOSI")
	)
	(segment
		(start 286.340042 -37.704268)
		(end 286.340042 -37.887656)
		(width 0.12954)
		(layer "B.Cu")
		(net "SPI_SYS_MOSI")
	)
	(segment
		(start 175.274224 -37.701728)
		(end 167.9448 -30.372304)
		(width 0.12954)
		(layer "B.Cu")
		(net "SPI_SYS_MOSI")
	)
	(segment
		(start 335.17332 -28.425648)
		(end 335.17332 -26.370788)
		(width 0.12954)
		(layer "B.Cu")
		(net "SPI_SYS_MOSI")
	)
	(segment
		(start 287.49244 -35.249866)
		(end 288.143442 -35.900868)
		(width 0.12954)
		(layer "B.Cu")
		(net "SPI_SYS_MOSI")
	)
	(segment
		(start 198.12254 -44.714668)
		(end 196.825362 -46.011846)
		(width 0.12954)
		(layer "B.Cu")
		(net "SPI_SYS_MOSI")
	)
	(segment
		(start 287.94329 -34.799016)
		(end 287.759902 -34.799016)
		(width 0.12954)
		(layer "B.Cu")
		(net "SPI_SYS_MOSI")
	)
	(segment
		(start 287.692592 -36.351718)
		(end 287.04159 -35.700716)
		(width 0.12954)
		(layer "B.Cu")
		(net "SPI_SYS_MOSI")
	)
	(segment
		(start 288.505392 -35.361118)
		(end 287.94329 -34.799016)
		(width 0.12954)
		(layer "B.Cu")
		(net "SPI_SYS_MOSI")
	)
	(segment
		(start 286.59074 -36.151566)
		(end 287.241742 -36.802568)
		(width 0.12954)
		(layer "B.Cu")
		(net "SPI_SYS_MOSI")
	)
	(segment
		(start 288.143442 -36.084256)
		(end 287.87598 -36.351718)
		(width 0.12954)
		(layer "B.Cu")
		(net "SPI_SYS_MOSI")
	)
	(segment
		(start 331.74686 -22.360128)
		(end 328.80935 -19.422618)
		(width 0.12954)
		(layer "B.Cu")
		(net "SPI_SYS_MOSI")
	)
	(segment
		(start 289.59048 -34.459418)
		(end 289.407092 -34.459418)
		(width 0.12954)
		(layer "B.Cu")
		(net "SPI_SYS_MOSI")
	)
	(segment
		(start 336.93608 -23.88108)
		(end 336.270854 -23.215854)
		(width 0.12954)
		(layer "B.Cu")
		(net "SPI_SYS_MOSI")
	)
	(segment
		(start 288.661602 -33.897316)
		(end 288.39414 -34.164778)
		(width 0.12954)
		(layer "B.Cu")
		(net "SPI_SYS_MOSI")
	)
	(segment
		(start 326.73544 -19.970242)
		(end 326.35698 -19.970242)
		(width 0.12954)
		(layer "B.Cu")
		(net "SPI_SYS_MOSI")
	)
	(segment
		(start 289.857942 -34.008568)
		(end 289.857942 -34.191956)
		(width 0.12954)
		(layer "B.Cu")
		(net "SPI_SYS_MOSI")
	)
	(segment
		(start 289.29584 -33.263078)
		(end 289.29584 -33.446466)
		(width 0.12954)
		(layer "B.Cu")
		(net "SPI_SYS_MOSI")
	)
	(segment
		(start 288.143442 -35.900868)
		(end 288.143442 -36.084256)
		(width 0.12954)
		(layer "B.Cu")
		(net "SPI_SYS_MOSI")
	)
	(segment
		(start 284.12694 -48.779938)
		(end 272.39595 -60.510928)
		(width 0.12954)
		(layer "B.Cu")
		(net "SPI_SYS_MOSI")
	)
	(segment
		(start 253.309374 -65.855088)
		(end 233.493056 -65.855088)
		(width 0.12954)
		(layer "B.Cu")
		(net "SPI_SYS_MOSI")
	)
	(segment
		(start 287.04159 -35.700716)
		(end 286.858202 -35.700716)
		(width 0.12954)
		(layer "B.Cu")
		(net "SPI_SYS_MOSI")
	)
	(segment
		(start 289.407092 -34.459418)
		(end 288.84499 -33.897316)
		(width 0.12954)
		(layer "B.Cu")
		(net "SPI_SYS_MOSI")
	)
	(segment
		(start 257.714242 -61.45022)
		(end 253.309374 -65.855088)
		(width 0.12954)
		(layer "B.Cu")
		(net "SPI_SYS_MOSI")
	)
	(segment
		(start 196.825362 -46.011846)
		(end 186.728608 -46.011846)
		(width 0.12954)
		(layer "B.Cu")
		(net "SPI_SYS_MOSI")
	)
	(segment
		(start 288.956242 -34.910268)
		(end 288.956242 -35.093656)
		(width 0.12954)
		(layer "B.Cu")
		(net "SPI_SYS_MOSI")
	)
	(segment
		(start 302.40097 -20.157948)
		(end 289.29584 -33.263078)
		(width 0.12954)
		(layer "B.Cu")
		(net "SPI_SYS_MOSI")
	)
	(segment
		(start 288.39414 -34.348166)
		(end 288.956242 -34.910268)
		(width 0.12954)
		(layer "B.Cu")
		(net "SPI_SYS_MOSI")
	)
	(segment
		(start 312.85688 -20.157948)
		(end 302.40097 -20.157948)
		(width 0.12954)
		(layer "B.Cu")
		(net "SPI_SYS_MOSI")
	)
	(segment
		(start 326.35698 -19.970242)
		(end 326.22744 -19.840702)
		(width 0.12954)
		(layer "B.Cu")
		(net "SPI_SYS_MOSI")
	)
	(segment
		(start 326.86498 -19.840702)
		(end 326.73544 -19.970242)
		(width 0.12954)
		(layer "B.Cu")
		(net "SPI_SYS_MOSI")
	)
	(segment
		(start 313.59221 -19.422618)
		(end 312.85688 -20.157948)
		(width 0.12954)
		(layer "B.Cu")
		(net "SPI_SYS_MOSI")
	)
	(segment
		(start 259.981954 -60.510928)
		(end 257.714242 -61.45022)
		(width 0.12954)
		(layer "B.Cu")
		(net "SPI_SYS_MOSI")
	)
	(segment
		(start 333.824326 -30.997652)
		(end 333.824326 -30.697678)
		(width 0.12954)
		(layer "B.Cu")
		(net "SPI_SYS_MOSI")
	)
	(segment
		(start 335.794858 -23.215854)
		(end 334.939132 -22.360128)
		(width 0.12954)
		(layer "B.Cu")
		(net "SPI_SYS_MOSI")
	)
	(segment
		(start 286.97428 -37.253418)
		(end 286.790892 -37.253418)
		(width 0.12954)
		(layer "B.Cu")
		(net "SPI_SYS_MOSI")
	)
	(segment
		(start 287.49244 -35.066478)
		(end 287.49244 -35.249866)
		(width 0.12954)
		(layer "B.Cu")
		(net "SPI_SYS_MOSI")
	)
	(segment
		(start 336.270854 -23.215854)
		(end 335.794858 -23.215854)
		(width 0.12954)
		(layer "B.Cu")
		(net "SPI_SYS_MOSI")
	)
	(segment
		(start 333.824326 -30.697678)
		(end 333.94904 -30.572964)
		(width 0.12954)
		(layer "B.Cu")
		(net "SPI_SYS_MOSI")
	)
	(segment
		(start 287.241742 -36.985956)
		(end 286.97428 -37.253418)
		(width 0.12954)
		(layer "B.Cu")
		(net "SPI_SYS_MOSI")
	)
	(segment
		(start 183.66994 -41.974008)
		(end 182.01894 -41.974008)
		(width 0.12954)
		(layer "B.Cu")
		(net "SPI_SYS_MOSI")
	)
	(segment
		(start 288.84499 -33.897316)
		(end 288.661602 -33.897316)
		(width 0.12954)
		(layer "B.Cu")
		(net "SPI_SYS_MOSI")
	)
	(segment
		(start 287.241742 -36.802568)
		(end 287.241742 -36.985956)
		(width 0.12954)
		(layer "B.Cu")
		(net "SPI_SYS_MOSI")
	)
	(segment
		(start 286.07258 -38.155118)
		(end 285.889192 -38.155118)
		(width 0.12954)
		(layer "B.Cu")
		(net "SPI_SYS_MOSI")
	)
	(segment
		(start 286.340042 -37.887656)
		(end 286.07258 -38.155118)
		(width 0.12954)
		(layer "B.Cu")
		(net "SPI_SYS_MOSI")
	)
	(segment
		(start 170.16476 -18.928588)
		(end 171.20489 -18.928588)
		(width 0.12954)
		(layer "B.Cu")
		(net "SPI_SYS_MOSI")
	)
	(segment
		(start 289.857942 -34.191956)
		(end 289.59048 -34.459418)
		(width 0.12954)
		(layer "B.Cu")
		(net "SPI_SYS_MOSI")
	)
	(segment
		(start 186.728608 -46.011846)
		(end 184.68594 -43.969178)
		(width 0.12954)
		(layer "B.Cu")
		(net "SPI_SYS_MOSI")
	)
	(segment
		(start 287.87598 -36.351718)
		(end 287.692592 -36.351718)
		(width 0.12954)
		(layer "B.Cu")
		(net "SPI_SYS_MOSI")
	)
	(segment
		(start 336.001868 -25.242774)
		(end 336.93608 -24.308562)
		(width 0.12954)
		(layer "B.Cu")
		(net "SPI_SYS_MOSI")
	)
	(segment
		(start 326.22744 -19.840702)
		(end 326.22744 -19.552158)
		(width 0.12954)
		(layer "B.Cu")
		(net "SPI_SYS_MOSI")
	)
	(segment
		(start 288.39414 -34.164778)
		(end 288.39414 -34.348166)
		(width 0.12954)
		(layer "B.Cu")
		(net "SPI_SYS_MOSI")
	)
	(segment
		(start 210.98764 -44.714668)
		(end 198.12254 -44.714668)
		(width 0.12954)
		(layer "B.Cu")
		(net "SPI_SYS_MOSI")
	)
	(segment
		(start 326.22744 -19.552158)
		(end 326.0979 -19.422618)
		(width 0.12954)
		(layer "B.Cu")
		(net "SPI_SYS_MOSI")
	)
	(segment
		(start 326.86498 -19.552158)
		(end 326.86498 -19.840702)
		(width 0.12954)
		(layer "B.Cu")
		(net "SPI_SYS_MOSI")
	)
	(segment
		(start 336.001868 -25.54224)
		(end 336.001868 -25.242774)
		(width 0.12954)
		(layer "B.Cu")
		(net "SPI_SYS_MOSI")
	)
	(segment
		(start 285.68904 -37.053266)
		(end 286.340042 -37.704268)
		(width 0.12954)
		(layer "B.Cu")
		(net "SPI_SYS_MOSI")
	)
	(segment
		(start 284.12694 -38.431978)
		(end 284.12694 -48.779938)
		(width 0.12954)
		(layer "B.Cu")
		(net "SPI_SYS_MOSI")
	)
	(segment
		(start 333.94904 -30.572964)
		(end 333.94904 -29.649928)
		(width 0.12954)
		(layer "B.Cu")
		(net "SPI_SYS_MOSI")
	)
	(segment
		(start 335.17332 -26.370788)
		(end 336.001868 -25.54224)
		(width 0.12954)
		(layer "B.Cu")
		(net "SPI_SYS_MOSI")
	)
	(segment
		(start 167.9448 -30.372304)
		(end 167.9448 -21.148548)
		(width 0.12954)
		(layer "B.Cu")
		(net "SPI_SYS_MOSI")
	)
	(segment
		(start 171.066968 -16.550132)
		(end 171.066968 -17.465802)
		(width 0.12954)
		(layer "F.Cu")
		(net "SPI_SYS_MISO")
	)
	(segment
		(start 171.066968 -17.465802)
		(end 171.066714 -17.466056)
		(width 0.12954)
		(layer "F.Cu")
		(net "SPI_SYS_MISO")
	)
	(segment
		(start 170.39336 -18.745708)
		(end 170.39336 -21.816568)
		(width 0.12954)
		(layer "F.Cu")
		(net "SPI_SYS_MISO")
	)
	(segment
		(start 171.066714 -17.466056)
		(end 171.066714 -18.072354)
		(width 0.12954)
		(layer "F.Cu")
		(net "SPI_SYS_MISO")
	)
	(segment
		(start 170.39336 -21.816568)
		(end 170.3832 -21.826728)
		(width 0.12954)
		(layer "F.Cu")
		(net "SPI_SYS_MISO")
	)
	(segment
		(start 171.066714 -18.072354)
		(end 170.39336 -18.745708)
		(width 0.12954)
		(layer "F.Cu")
		(net "SPI_SYS_MISO")
	)
	(via
		(at 170.3832 -21.826728)
		(size 0.508)
		(drill 0.254)
		(layers "F.Cu" "B.Cu")
		(net "SPI_SYS_MISO")
	)
	(segment
		(start 280.680922 -40.952166)
		(end 280.680922 -39.050722)
		(width 0.12954)
		(layer "B.Cu")
		(net "SPI_SYS_MISO")
	)
	(segment
		(start 341.05088 -27.625548)
		(end 338.090002 -30.586426)
		(width 0.12954)
		(layer "B.Cu")
		(net "SPI_SYS_MISO")
	)
	(segment
		(start 279.822402 -41.211246)
		(end 279.951942 -41.081706)
		(width 0.12954)
		(layer "B.Cu")
		(net "SPI_SYS_MISO")
	)
	(segment
		(start 181.537864 -35.743388)
		(end 187.644024 -41.849548)
		(width 0.12954)
		(layer "B.Cu")
		(net "SPI_SYS_MISO")
	)
	(segment
		(start 217.31986 -48.521112)
		(end 232.172764 -63.374016)
		(width 0.12954)
		(layer "B.Cu")
		(net "SPI_SYS_MISO")
	)
	(segment
		(start 336.167222 -31.026862)
		(end 336.167222 -32.80537)
		(width 0.12954)
		(layer "B.Cu")
		(net "SPI_SYS_MISO")
	)
	(segment
		(start 280.680922 -43.502326)
		(end 280.680922 -43.123866)
		(width 0.12954)
		(layer "B.Cu")
		(net "SPI_SYS_MISO")
	)
	(segment
		(start 338.090002 -30.586426)
		(end 336.607658 -30.586426)
		(width 0.12954)
		(layer "B.Cu")
		(net "SPI_SYS_MISO")
	)
	(segment
		(start 169.80154 -29.703014)
		(end 175.841914 -35.743388)
		(width 0.12954)
		(layer "B.Cu")
		(net "SPI_SYS_MISO")
	)
	(segment
		(start 279.951942 -47.457106)
		(end 280.551382 -47.457106)
		(width 0.12954)
		(layer "B.Cu")
		(net "SPI_SYS_MISO")
	)
	(segment
		(start 280.551382 -48.094646)
		(end 279.951942 -48.094646)
		(width 0.12954)
		(layer "B.Cu")
		(net "SPI_SYS_MISO")
	)
	(segment
		(start 196.80428 -41.849802)
		(end 197.799706 -42.845228)
		(width 0.12954)
		(layer "B.Cu")
		(net "SPI_SYS_MISO")
	)
	(segment
		(start 330.11999 -17.636998)
		(end 330.85278 -18.369788)
		(width 0.12954)
		(layer "B.Cu")
		(net "SPI_SYS_MISO")
	)
	(segment
		(start 336.46872 -18.369788)
		(end 341.05088 -22.951948)
		(width 0.12954)
		(layer "B.Cu")
		(net "SPI_SYS_MISO")
	)
	(segment
		(start 280.680922 -44.777406)
		(end 280.680922 -44.398946)
		(width 0.12954)
		(layer "B.Cu")
		(net "SPI_SYS_MISO")
	)
	(segment
		(start 169.80154 -22.962108)
		(end 169.80154 -29.703014)
		(width 0.12954)
		(layer "B.Cu")
		(net "SPI_SYS_MISO")
	)
	(segment
		(start 280.551382 -46.819566)
		(end 279.951942 -46.819566)
		(width 0.12954)
		(layer "B.Cu")
		(net "SPI_SYS_MISO")
	)
	(segment
		(start 311.07888 -17.998948)
		(end 311.44083 -17.636998)
		(width 0.12954)
		(layer "B.Cu")
		(net "SPI_SYS_MISO")
	)
	(segment
		(start 280.680922 -44.398946)
		(end 280.551382 -44.269406)
		(width 0.12954)
		(layer "B.Cu")
		(net "SPI_SYS_MISO")
	)
	(segment
		(start 195.687188 -41.849802)
		(end 196.80428 -41.849802)
		(width 0.12954)
		(layer "B.Cu")
		(net "SPI_SYS_MISO")
	)
	(segment
		(start 301.732696 -17.998948)
		(end 311.07888 -17.998948)
		(width 0.12954)
		(layer "B.Cu")
		(net "SPI_SYS_MISO")
	)
	(segment
		(start 280.551382 -45.544486)
		(end 279.951942 -45.544486)
		(width 0.12954)
		(layer "B.Cu")
		(net "SPI_SYS_MISO")
	)
	(segment
		(start 280.551382 -42.994326)
		(end 279.951942 -42.994326)
		(width 0.12954)
		(layer "B.Cu")
		(net "SPI_SYS_MISO")
	)
	(segment
		(start 279.822402 -41.589706)
		(end 279.822402 -41.211246)
		(width 0.12954)
		(layer "B.Cu")
		(net "SPI_SYS_MISO")
	)
	(segment
		(start 279.951942 -44.906946)
		(end 280.551382 -44.906946)
		(width 0.12954)
		(layer "B.Cu")
		(net "SPI_SYS_MISO")
	)
	(segment
		(start 195.686934 -41.849548)
		(end 195.687188 -41.849802)
		(width 0.12954)
		(layer "B.Cu")
		(net "SPI_SYS_MISO")
	)
	(segment
		(start 280.551382 -42.356786)
		(end 280.680922 -42.227246)
		(width 0.12954)
		(layer "B.Cu")
		(net "SPI_SYS_MISO")
	)
	(segment
		(start 279.822402 -43.761406)
		(end 279.951942 -43.631866)
		(width 0.12954)
		(layer "B.Cu")
		(net "SPI_SYS_MISO")
	)
	(segment
		(start 280.680922 -42.227246)
		(end 280.680922 -41.848786)
		(width 0.12954)
		(layer "B.Cu")
		(net "SPI_SYS_MISO")
	)
	(segment
		(start 280.680922 -45.674026)
		(end 280.551382 -45.544486)
		(width 0.12954)
		(layer "B.Cu")
		(net "SPI_SYS_MISO")
	)
	(segment
		(start 279.951942 -43.631866)
		(end 280.551382 -43.631866)
		(width 0.12954)
		(layer "B.Cu")
		(net "SPI_SYS_MISO")
	)
	(segment
		(start 341.05088 -22.951948)
		(end 341.05088 -27.625548)
		(width 0.12954)
		(layer "B.Cu")
		(net "SPI_SYS_MISO")
	)
	(segment
		(start 197.799706 -42.845228)
		(end 214.05596 -42.845228)
		(width 0.12954)
		(layer "B.Cu")
		(net "SPI_SYS_MISO")
	)
	(segment
		(start 271.354296 -58.725308)
		(end 280.680922 -49.398682)
		(width 0.12954)
		(layer "B.Cu")
		(net "SPI_SYS_MISO")
	)
	(segment
		(start 280.680922 -47.327566)
		(end 280.680922 -46.949106)
		(width 0.12954)
		(layer "B.Cu")
		(net "SPI_SYS_MISO")
	)
	(segment
		(start 280.551382 -41.719246)
		(end 279.951942 -41.719246)
		(width 0.12954)
		(layer "B.Cu")
		(net "SPI_SYS_MISO")
	)
	(segment
		(start 280.551382 -41.081706)
		(end 280.680922 -40.952166)
		(width 0.12954)
		(layer "B.Cu")
		(net "SPI_SYS_MISO")
	)
	(segment
		(start 280.680922 -41.848786)
		(end 280.551382 -41.719246)
		(width 0.12954)
		(layer "B.Cu")
		(net "SPI_SYS_MISO")
	)
	(segment
		(start 217.31986 -46.109128)
		(end 217.31986 -48.521112)
		(width 0.12954)
		(layer "B.Cu")
		(net "SPI_SYS_MISO")
	)
	(segment
		(start 280.680922 -48.224186)
		(end 280.551382 -48.094646)
		(width 0.12954)
		(layer "B.Cu")
		(net "SPI_SYS_MISO")
	)
	(segment
		(start 280.551382 -43.631866)
		(end 280.680922 -43.502326)
		(width 0.12954)
		(layer "B.Cu")
		(net "SPI_SYS_MISO")
	)
	(segment
		(start 279.951942 -44.269406)
		(end 279.822402 -44.139866)
		(width 0.12954)
		(layer "B.Cu")
		(net "SPI_SYS_MISO")
	)
	(segment
		(start 279.822402 -47.965106)
		(end 279.822402 -47.586646)
		(width 0.12954)
		(layer "B.Cu")
		(net "SPI_SYS_MISO")
	)
	(segment
		(start 279.822402 -46.311566)
		(end 279.951942 -46.182026)
		(width 0.12954)
		(layer "B.Cu")
		(net "SPI_SYS_MISO")
	)
	(segment
		(start 280.551382 -46.182026)
		(end 280.680922 -46.052486)
		(width 0.12954)
		(layer "B.Cu")
		(net "SPI_SYS_MISO")
	)
	(segment
		(start 279.822402 -44.139866)
		(end 279.822402 -43.761406)
		(width 0.12954)
		(layer "B.Cu")
		(net "SPI_SYS_MISO")
	)
	(segment
		(start 279.822402 -42.864786)
		(end 279.822402 -42.486326)
		(width 0.12954)
		(layer "B.Cu")
		(net "SPI_SYS_MISO")
	)
	(segment
		(start 280.551382 -44.269406)
		(end 279.951942 -44.269406)
		(width 0.12954)
		(layer "B.Cu")
		(net "SPI_SYS_MISO")
	)
	(segment
		(start 252.74524 -63.856108)
		(end 256.63906 -59.962288)
		(width 0.12954)
		(layer "B.Cu")
		(net "SPI_SYS_MISO")
	)
	(segment
		(start 279.951942 -48.094646)
		(end 279.822402 -47.965106)
		(width 0.12954)
		(layer "B.Cu")
		(net "SPI_SYS_MISO")
	)
	(segment
		(start 336.607658 -30.586426)
		(end 336.167222 -31.026862)
		(width 0.12954)
		(layer "B.Cu")
		(net "SPI_SYS_MISO")
	)
	(segment
		(start 279.822402 -42.486326)
		(end 279.951942 -42.356786)
		(width 0.12954)
		(layer "B.Cu")
		(net "SPI_SYS_MISO")
	)
	(segment
		(start 280.680922 -46.949106)
		(end 280.551382 -46.819566)
		(width 0.12954)
		(layer "B.Cu")
		(net "SPI_SYS_MISO")
	)
	(segment
		(start 279.951942 -45.544486)
		(end 279.822402 -45.414946)
		(width 0.12954)
		(layer "B.Cu")
		(net "SPI_SYS_MISO")
	)
	(segment
		(start 279.822402 -45.414946)
		(end 279.822402 -45.036486)
		(width 0.12954)
		(layer "B.Cu")
		(net "SPI_SYS_MISO")
	)
	(segment
		(start 279.822402 -46.690026)
		(end 279.822402 -46.311566)
		(width 0.12954)
		(layer "B.Cu")
		(net "SPI_SYS_MISO")
	)
	(segment
		(start 330.85278 -18.369788)
		(end 336.46872 -18.369788)
		(width 0.12954)
		(layer "B.Cu")
		(net "SPI_SYS_MISO")
	)
	(segment
		(start 175.841914 -35.743388)
		(end 181.537864 -35.743388)
		(width 0.12954)
		(layer "B.Cu")
		(net "SPI_SYS_MISO")
	)
	(segment
		(start 259.625592 -58.725308)
		(end 271.354296 -58.725308)
		(width 0.12954)
		(layer "B.Cu")
		(net "SPI_SYS_MISO")
	)
	(segment
		(start 256.63906 -59.962288)
		(end 259.625592 -58.725308)
		(width 0.12954)
		(layer "B.Cu")
		(net "SPI_SYS_MISO")
	)
	(segment
		(start 279.951942 -42.356786)
		(end 280.551382 -42.356786)
		(width 0.12954)
		(layer "B.Cu")
		(net "SPI_SYS_MISO")
	)
	(segment
		(start 187.644024 -41.849548)
		(end 195.686934 -41.849548)
		(width 0.12954)
		(layer "B.Cu")
		(net "SPI_SYS_MISO")
	)
	(segment
		(start 280.551382 -44.906946)
		(end 280.680922 -44.777406)
		(width 0.12954)
		(layer "B.Cu")
		(net "SPI_SYS_MISO")
	)
	(segment
		(start 279.822402 -45.036486)
		(end 279.951942 -44.906946)
		(width 0.12954)
		(layer "B.Cu")
		(net "SPI_SYS_MISO")
	)
	(segment
		(start 279.951942 -46.182026)
		(end 280.551382 -46.182026)
		(width 0.12954)
		(layer "B.Cu")
		(net "SPI_SYS_MISO")
	)
	(segment
		(start 214.05596 -42.845228)
		(end 217.31986 -46.109128)
		(width 0.12954)
		(layer "B.Cu")
		(net "SPI_SYS_MISO")
	)
	(segment
		(start 279.822402 -47.586646)
		(end 279.951942 -47.457106)
		(width 0.12954)
		(layer "B.Cu")
		(net "SPI_SYS_MISO")
	)
	(segment
		(start 279.951942 -41.081706)
		(end 280.551382 -41.081706)
		(width 0.12954)
		(layer "B.Cu")
		(net "SPI_SYS_MISO")
	)
	(segment
		(start 280.551382 -47.457106)
		(end 280.680922 -47.327566)
		(width 0.12954)
		(layer "B.Cu")
		(net "SPI_SYS_MISO")
	)
	(segment
		(start 280.680922 -43.123866)
		(end 280.551382 -42.994326)
		(width 0.12954)
		(layer "B.Cu")
		(net "SPI_SYS_MISO")
	)
	(segment
		(start 170.3832 -22.380448)
		(end 169.80154 -22.962108)
		(width 0.12954)
		(layer "B.Cu")
		(net "SPI_SYS_MISO")
	)
	(segment
		(start 279.951942 -41.719246)
		(end 279.822402 -41.589706)
		(width 0.12954)
		(layer "B.Cu")
		(net "SPI_SYS_MISO")
	)
	(segment
		(start 279.951942 -46.819566)
		(end 279.822402 -46.690026)
		(width 0.12954)
		(layer "B.Cu")
		(net "SPI_SYS_MISO")
	)
	(segment
		(start 170.3832 -21.826728)
		(end 170.3832 -22.380448)
		(width 0.12954)
		(layer "B.Cu")
		(net "SPI_SYS_MISO")
	)
	(segment
		(start 233.33583 -63.856108)
		(end 252.74524 -63.856108)
		(width 0.12954)
		(layer "B.Cu")
		(net "SPI_SYS_MISO")
	)
	(segment
		(start 280.680922 -39.050722)
		(end 301.732696 -17.998948)
		(width 0.12954)
		(layer "B.Cu")
		(net "SPI_SYS_MISO")
	)
	(segment
		(start 280.680922 -49.398682)
		(end 280.680922 -48.224186)
		(width 0.12954)
		(layer "B.Cu")
		(net "SPI_SYS_MISO")
	)
	(segment
		(start 279.951942 -42.994326)
		(end 279.822402 -42.864786)
		(width 0.12954)
		(layer "B.Cu")
		(net "SPI_SYS_MISO")
	)
	(segment
		(start 280.680922 -46.052486)
		(end 280.680922 -45.674026)
		(width 0.12954)
		(layer "B.Cu")
		(net "SPI_SYS_MISO")
	)
	(segment
		(start 311.44083 -17.636998)
		(end 330.11999 -17.636998)
		(width 0.12954)
		(layer "B.Cu")
		(net "SPI_SYS_MISO")
	)
	(segment
		(start 232.172764 -63.374016)
		(end 233.33583 -63.856108)
		(width 0.12954)
		(layer "B.Cu")
		(net "SPI_SYS_MISO")
	)
	(segment
		(start 169.867072 -16.550132)
		(end 169.867072 -17.465802)
		(width 0.12954)
		(layer "F.Cu")
		(net "SPI_SYS_HOLD_IO3")
	)
	(segment
		(start 168.840912 -22.3266)
		(end 169.67708 -23.162768)
		(width 0.12954)
		(layer "F.Cu")
		(net "SPI_SYS_HOLD_IO3")
	)
	(segment
		(start 169.866818 -17.820386)
		(end 169.177716 -18.509488)
		(width 0.12954)
		(layer "F.Cu")
		(net "SPI_SYS_HOLD_IO3")
	)
	(segment
		(start 168.840912 -19.322542)
		(end 168.840912 -22.3266)
		(width 0.12954)
		(layer "F.Cu")
		(net "SPI_SYS_HOLD_IO3")
	)
	(segment
		(start 169.867072 -17.465802)
		(end 169.866818 -17.466056)
		(width 0.12954)
		(layer "F.Cu")
		(net "SPI_SYS_HOLD_IO3")
	)
	(segment
		(start 169.67708 -23.162768)
		(end 170.51528 -23.162768)
		(width 0.12954)
		(layer "F.Cu")
		(net "SPI_SYS_HOLD_IO3")
	)
	(segment
		(start 169.866818 -17.466056)
		(end 169.866818 -17.820386)
		(width 0.12954)
		(layer "F.Cu")
		(net "SPI_SYS_HOLD_IO3")
	)
	(segment
		(start 169.177716 -18.509488)
		(end 168.840912 -19.322542)
		(width 0.12954)
		(layer "F.Cu")
		(net "SPI_SYS_HOLD_IO3")
	)
	(via
		(at 170.51528 -23.162768)
		(size 0.508)
		(drill 0.254)
		(layers "F.Cu" "B.Cu")
		(net "SPI_SYS_HOLD_IO3")
	)
	(segment
		(start 279.174448 -44.078398)
		(end 278.998172 -44.078398)
		(width 0.12954)
		(layer "B.Cu")
		(net "SPI_SYS_HOLD_IO3")
	)
	(segment
		(start 338.297774 -31.293308)
		(end 337.166712 -31.293308)
		(width 0.12954)
		(layer "B.Cu")
		(net "SPI_SYS_HOLD_IO3")
	)
	(segment
		(start 233.50728 -63.289688)
		(end 252.56744 -63.289688)
		(width 0.12954)
		(layer "B.Cu")
		(net "SPI_SYS_HOLD_IO3")
	)
	(segment
		(start 341.46236 -21.694648)
		(end 342.245442 -22.47773)
		(width 0.12954)
		(layer "B.Cu")
		(net "SPI_SYS_HOLD_IO3")
	)
	(segment
		(start 278.998172 -41.528238)
		(end 278.868632 -41.398698)
		(width 0.12954)
		(layer "B.Cu")
		(net "SPI_SYS_HOLD_IO3")
	)
	(segment
		(start 342.84666 -20.546568)
		(end 341.84844 -20.546568)
		(width 0.12954)
		(layer "B.Cu")
		(net "SPI_SYS_HOLD_IO3")
	)
	(segment
		(start 342.245442 -22.47773)
		(end 343.52738 -25.57272)
		(width 0.12954)
		(layer "B.Cu")
		(net "SPI_SYS_HOLD_IO3")
	)
	(segment
		(start 217.88628 -48.365156)
		(end 232.462578 -62.941454)
		(width 0.12954)
		(layer "B.Cu")
		(net "SPI_SYS_HOLD_IO3")
	)
	(segment
		(start 279.174448 -43.440858)
		(end 279.303988 -43.311318)
		(width 0.12954)
		(layer "B.Cu")
		(net "SPI_SYS_HOLD_IO3")
	)
	(segment
		(start 278.998172 -43.440858)
		(end 279.174448 -43.440858)
		(width 0.12954)
		(layer "B.Cu")
		(net "SPI_SYS_HOLD_IO3")
	)
	(segment
		(start 217.88628 -45.888656)
		(end 217.88628 -48.365156)
		(width 0.12954)
		(layer "B.Cu")
		(net "SPI_SYS_HOLD_IO3")
	)
	(segment
		(start 301.56658 -17.363948)
		(end 310.18988 -17.363948)
		(width 0.12954)
		(layer "B.Cu")
		(net "SPI_SYS_HOLD_IO3")
	)
	(segment
		(start 181.802532 -35.062668)
		(end 186.52363 -39.783766)
		(width 0.12954)
		(layer "B.Cu")
		(net "SPI_SYS_HOLD_IO3")
	)
	(segment
		(start 343.52738 -25.57272)
		(end 343.52738 -26.779474)
		(width 0.12954)
		(layer "B.Cu")
		(net "SPI_SYS_HOLD_IO3")
	)
	(segment
		(start 252.56744 -63.289688)
		(end 256.312162 -59.544966)
		(width 0.12954)
		(layer "B.Cu")
		(net "SPI_SYS_HOLD_IO3")
	)
	(segment
		(start 256.312162 -59.544966)
		(end 259.53593 -58.209688)
		(width 0.12954)
		(layer "B.Cu")
		(net "SPI_SYS_HOLD_IO3")
	)
	(segment
		(start 340.725506 -16.352774)
		(end 343.50452 -19.131788)
		(width 0.12954)
		(layer "B.Cu")
		(net "SPI_SYS_HOLD_IO3")
	)
	(segment
		(start 279.174448 -41.528238)
		(end 278.998172 -41.528238)
		(width 0.12954)
		(layer "B.Cu")
		(net "SPI_SYS_HOLD_IO3")
	)
	(segment
		(start 279.174448 -42.165778)
		(end 279.303988 -42.036238)
		(width 0.12954)
		(layer "B.Cu")
		(net "SPI_SYS_HOLD_IO3")
	)
	(segment
		(start 278.998172 -42.165778)
		(end 279.174448 -42.165778)
		(width 0.12954)
		(layer "B.Cu")
		(net "SPI_SYS_HOLD_IO3")
	)
	(segment
		(start 279.303988 -42.932858)
		(end 279.174448 -42.803318)
		(width 0.12954)
		(layer "B.Cu")
		(net "SPI_SYS_HOLD_IO3")
	)
	(segment
		(start 279.303988 -39.62654)
		(end 301.56658 -17.363948)
		(width 0.12954)
		(layer "B.Cu")
		(net "SPI_SYS_HOLD_IO3")
	)
	(segment
		(start 278.998172 -44.078398)
		(end 278.868632 -43.948858)
		(width 0.12954)
		(layer "B.Cu")
		(net "SPI_SYS_HOLD_IO3")
	)
	(segment
		(start 341.84844 -20.546568)
		(end 341.46236 -20.932648)
		(width 0.12954)
		(layer "B.Cu")
		(net "SPI_SYS_HOLD_IO3")
	)
	(segment
		(start 196.891148 -41.214548)
		(end 198.011288 -42.334688)
		(width 0.12954)
		(layer "B.Cu")
		(net "SPI_SYS_HOLD_IO3")
	)
	(segment
		(start 170.51528 -23.162768)
		(end 170.51528 -29.02458)
		(width 0.12954)
		(layer "B.Cu")
		(net "SPI_SYS_HOLD_IO3")
	)
	(segment
		(start 326.97293 -17.126458)
		(end 330.862686 -16.352774)
		(width 0.12954)
		(layer "B.Cu")
		(net "SPI_SYS_HOLD_IO3")
	)
	(segment
		(start 198.011288 -42.334688)
		(end 214.332312 -42.334688)
		(width 0.12954)
		(layer "B.Cu")
		(net "SPI_SYS_HOLD_IO3")
	)
	(segment
		(start 279.303988 -40.761158)
		(end 279.303988 -39.62654)
		(width 0.12954)
		(layer "B.Cu")
		(net "SPI_SYS_HOLD_IO3")
	)
	(segment
		(start 279.303988 -42.036238)
		(end 279.303988 -41.657778)
		(width 0.12954)
		(layer "B.Cu")
		(net "SPI_SYS_HOLD_IO3")
	)
	(segment
		(start 343.50452 -19.131788)
		(end 343.50452 -19.888708)
		(width 0.12954)
		(layer "B.Cu")
		(net "SPI_SYS_HOLD_IO3")
	)
	(segment
		(start 174.978568 -34.15792)
		(end 177.162714 -35.062668)
		(width 0.12954)
		(layer "B.Cu")
		(net "SPI_SYS_HOLD_IO3")
	)
	(segment
		(start 278.868632 -42.673778)
		(end 278.868632 -42.295318)
		(width 0.12954)
		(layer "B.Cu")
		(net "SPI_SYS_HOLD_IO3")
	)
	(segment
		(start 343.50452 -19.888708)
		(end 342.84666 -20.546568)
		(width 0.12954)
		(layer "B.Cu")
		(net "SPI_SYS_HOLD_IO3")
	)
	(segment
		(start 278.998172 -42.803318)
		(end 278.868632 -42.673778)
		(width 0.12954)
		(layer "B.Cu")
		(net "SPI_SYS_HOLD_IO3")
	)
	(segment
		(start 341.477854 -28.113228)
		(end 338.297774 -31.293308)
		(width 0.12954)
		(layer "B.Cu")
		(net "SPI_SYS_HOLD_IO3")
	)
	(segment
		(start 186.52363 -39.783766)
		(end 189.977776 -41.214548)
		(width 0.12954)
		(layer "B.Cu")
		(net "SPI_SYS_HOLD_IO3")
	)
	(segment
		(start 310.42737 -17.126458)
		(end 326.97293 -17.126458)
		(width 0.12954)
		(layer "B.Cu")
		(net "SPI_SYS_HOLD_IO3")
	)
	(segment
		(start 278.868632 -43.948858)
		(end 278.868632 -43.570398)
		(width 0.12954)
		(layer "B.Cu")
		(net "SPI_SYS_HOLD_IO3")
	)
	(segment
		(start 278.868632 -41.020238)
		(end 278.998172 -40.890698)
		(width 0.12954)
		(layer "B.Cu")
		(net "SPI_SYS_HOLD_IO3")
	)
	(segment
		(start 170.988736 -30.168088)
		(end 174.978568 -34.15792)
		(width 0.12954)
		(layer "B.Cu")
		(net "SPI_SYS_HOLD_IO3")
	)
	(segment
		(start 279.174448 -40.890698)
		(end 279.303988 -40.761158)
		(width 0.12954)
		(layer "B.Cu")
		(net "SPI_SYS_HOLD_IO3")
	)
	(segment
		(start 278.868632 -43.570398)
		(end 278.998172 -43.440858)
		(width 0.12954)
		(layer "B.Cu")
		(net "SPI_SYS_HOLD_IO3")
	)
	(segment
		(start 279.303988 -50.05324)
		(end 279.303988 -44.207938)
		(width 0.12954)
		(layer "B.Cu")
		(net "SPI_SYS_HOLD_IO3")
	)
	(segment
		(start 330.862686 -16.352774)
		(end 340.725506 -16.352774)
		(width 0.12954)
		(layer "B.Cu")
		(net "SPI_SYS_HOLD_IO3")
	)
	(segment
		(start 279.303988 -43.311318)
		(end 279.303988 -42.932858)
		(width 0.12954)
		(layer "B.Cu")
		(net "SPI_SYS_HOLD_IO3")
	)
	(segment
		(start 279.303988 -41.657778)
		(end 279.174448 -41.528238)
		(width 0.12954)
		(layer "B.Cu")
		(net "SPI_SYS_HOLD_IO3")
	)
	(segment
		(start 343.52738 -26.779474)
		(end 342.699848 -27.607006)
		(width 0.12954)
		(layer "B.Cu")
		(net "SPI_SYS_HOLD_IO3")
	)
	(segment
		(start 259.53593 -58.209688)
		(end 271.14754 -58.209688)
		(width 0.12954)
		(layer "B.Cu")
		(net "SPI_SYS_HOLD_IO3")
	)
	(segment
		(start 278.998172 -40.890698)
		(end 279.174448 -40.890698)
		(width 0.12954)
		(layer "B.Cu")
		(net "SPI_SYS_HOLD_IO3")
	)
	(segment
		(start 214.332312 -42.334688)
		(end 217.88628 -45.888656)
		(width 0.12954)
		(layer "B.Cu")
		(net "SPI_SYS_HOLD_IO3")
	)
	(segment
		(start 341.46236 -20.932648)
		(end 341.46236 -21.694648)
		(width 0.12954)
		(layer "B.Cu")
		(net "SPI_SYS_HOLD_IO3")
	)
	(segment
		(start 278.868632 -41.398698)
		(end 278.868632 -41.020238)
		(width 0.12954)
		(layer "B.Cu")
		(net "SPI_SYS_HOLD_IO3")
	)
	(segment
		(start 342.699848 -27.607006)
		(end 341.477854 -28.113228)
		(width 0.12954)
		(layer "B.Cu")
		(net "SPI_SYS_HOLD_IO3")
	)
	(segment
		(start 271.14754 -58.209688)
		(end 279.303988 -50.05324)
		(width 0.12954)
		(layer "B.Cu")
		(net "SPI_SYS_HOLD_IO3")
	)
	(segment
		(start 279.174448 -42.803318)
		(end 278.998172 -42.803318)
		(width 0.12954)
		(layer "B.Cu")
		(net "SPI_SYS_HOLD_IO3")
	)
	(segment
		(start 278.868632 -42.295318)
		(end 278.998172 -42.165778)
		(width 0.12954)
		(layer "B.Cu")
		(net "SPI_SYS_HOLD_IO3")
	)
	(segment
		(start 177.162714 -35.062668)
		(end 181.802532 -35.062668)
		(width 0.12954)
		(layer "B.Cu")
		(net "SPI_SYS_HOLD_IO3")
	)
	(segment
		(start 310.18988 -17.363948)
		(end 310.42737 -17.126458)
		(width 0.12954)
		(layer "B.Cu")
		(net "SPI_SYS_HOLD_IO3")
	)
	(segment
		(start 189.977776 -41.214548)
		(end 196.891148 -41.214548)
		(width 0.12954)
		(layer "B.Cu")
		(net "SPI_SYS_HOLD_IO3")
	)
	(segment
		(start 279.303988 -44.207938)
		(end 279.174448 -44.078398)
		(width 0.12954)
		(layer "B.Cu")
		(net "SPI_SYS_HOLD_IO3")
	)
	(segment
		(start 170.51528 -29.02458)
		(end 170.988736 -30.168088)
		(width 0.12954)
		(layer "B.Cu")
		(net "SPI_SYS_HOLD_IO3")
	)
	(segment
		(start 232.462578 -62.941454)
		(end 233.50728 -63.289688)
		(width 0.12954)
		(layer "B.Cu")
		(net "SPI_SYS_HOLD_IO3")
	)
	(segment
		(start 172.267118 -17.465802)
		(end 172.20692 -17.526)
		(width 0.12954)
		(layer "F.Cu")
		(net "SPI_SYS_CS0_N")
	)
	(segment
		(start 171.93006 -19.022568)
		(end 171.93006 -19.888708)
		(width 0.12954)
		(layer "F.Cu")
		(net "SPI_SYS_CS0_N")
	)
	(segment
		(start 172.20692 -17.526)
		(end 172.20692 -18.745708)
		(width 0.12954)
		(layer "F.Cu")
		(net "SPI_SYS_CS0_N")
	)
	(segment
		(start 172.267118 -16.550132)
		(end 172.267118 -17.465802)
		(width 0.12954)
		(layer "F.Cu")
		(net "SPI_SYS_CS0_N")
	)
	(segment
		(start 172.20692 -18.745708)
		(end 171.93006 -19.022568)
		(width 0.12954)
		(layer "F.Cu")
		(net "SPI_SYS_CS0_N")
	)
	(segment
		(start 171.93006 -19.888708)
		(end 171.33316 -20.485608)
		(width 0.12954)
		(layer "F.Cu")
		(net "SPI_SYS_CS0_N")
	)
	(via
		(at 171.33316 -20.485608)
		(size 0.508)
		(drill 0.254)
		(layers "F.Cu" "B.Cu")
		(net "SPI_SYS_CS0_N")
	)
	(segment
		(start 287.751774 -41.44645)
		(end 287.821878 -41.615106)
		(width 0.12954)
		(layer "B.Cu")
		(net "SPI_SYS_CS0_N")
	)
	(segment
		(start 170.13428 -18.222468)
		(end 171.54652 -18.222468)
		(width 0.12954)
		(layer "B.Cu")
		(net "SPI_SYS_CS0_N")
	)
	(segment
		(start 253.411736 -66.474848)
		(end 233.655108 -66.474848)
		(width 0.12954)
		(layer "B.Cu")
		(net "SPI_SYS_CS0_N")
	)
	(segment
		(start 285.724092 -46.677326)
		(end 285.554928 -46.74743)
		(width 0.12954)
		(layer "B.Cu")
		(net "SPI_SYS_CS0_N")
	)
	(segment
		(start 175.090582 -38.240208)
		(end 172.197522 -35.347148)
		(width 0.12954)
		(layer "B.Cu")
		(net "SPI_SYS_CS0_N")
	)
	(segment
		(start 286.30499 -43.467528)
		(end 286.375094 -43.636692)
		(width 0.12954)
		(layer "B.Cu")
		(net "SPI_SYS_CS0_N")
	)
	(segment
		(start 186.471814 -46.631606)
		(end 184.06618 -44.225972)
		(width 0.12954)
		(layer "B.Cu")
		(net "SPI_SYS_CS0_N")
	)
	(segment
		(start 288.165032 -40.787066)
		(end 287.995868 -40.85717)
		(width 0.12954)
		(layer "B.Cu")
		(net "SPI_SYS_CS0_N")
	)
	(segment
		(start 183.413146 -42.593768)
		(end 181.762146 -42.593768)
		(width 0.12954)
		(layer "B.Cu")
		(net "SPI_SYS_CS0_N")
	)
	(segment
		(start 286.938212 -41.939718)
		(end 286.793178 -42.289476)
		(width 0.12954)
		(layer "B.Cu")
		(net "SPI_SYS_CS0_N")
	)
	(segment
		(start 285.310834 -47.33671)
		(end 285.380938 -47.50562)
		(width 0.12954)
		(layer "B.Cu")
		(net "SPI_SYS_CS0_N")
	)
	(segment
		(start 302.642524 -20.792948)
		(end 292.063932 -31.37154)
		(width 0.12954)
		(layer "B.Cu")
		(net "SPI_SYS_CS0_N")
	)
	(segment
		(start 287.019492 -43.213274)
		(end 286.619188 -43.047666)
		(width 0.12954)
		(layer "B.Cu")
		(net "SPI_SYS_CS0_N")
	)
	(segment
		(start 170.60418 -35.347148)
		(end 166.9796 -31.722568)
		(width 0.12954)
		(layer "B.Cu")
		(net "SPI_SYS_CS0_N")
	)
	(segment
		(start 334.56118 -24.453088)
		(end 335.085182 -23.929086)
		(width 0.12954)
		(layer "B.Cu")
		(net "SPI_SYS_CS0_N")
	)
	(segment
		(start 285.398718 -45.992796)
		(end 285.799022 -46.158658)
		(width 0.12954)
		(layer "B.Cu")
		(net "SPI_SYS_CS0_N")
	)
	(segment
		(start 286.863282 -42.45864)
		(end 287.263586 -42.624502)
		(width 0.12954)
		(layer "B.Cu")
		(net "SPI_SYS_CS0_N")
	)
	(segment
		(start 286.043116 -45.569378)
		(end 285.642812 -45.40377)
		(width 0.12954)
		(layer "B.Cu")
		(net "SPI_SYS_CS0_N")
	)
	(segment
		(start 333.29626 -29.417772)
		(end 334.56118 -28.152852)
		(width 0.12954)
		(layer "B.Cu")
		(net "SPI_SYS_CS0_N")
	)
	(segment
		(start 286.28721 -44.980606)
		(end 286.357314 -45.149262)
		(width 0.12954)
		(layer "B.Cu")
		(net "SPI_SYS_CS0_N")
	)
	(segment
		(start 286.450024 -43.11777)
		(end 286.30499 -43.467528)
		(width 0.12954)
		(layer "B.Cu")
		(net "SPI_SYS_CS0_N")
	)
	(segment
		(start 230.873554 -65.322704)
		(end 210.885278 -45.334428)
		(width 0.12954)
		(layer "B.Cu")
		(net "SPI_SYS_CS0_N")
	)
	(segment
		(start 285.554928 -46.74743)
		(end 285.154624 -46.581822)
		(width 0.12954)
		(layer "B.Cu")
		(net "SPI_SYS_CS0_N")
	)
	(segment
		(start 286.131 -44.225718)
		(end 285.961836 -44.295822)
		(width 0.12954)
		(layer "B.Cu")
		(net "SPI_SYS_CS0_N")
	)
	(segment
		(start 286.357314 -45.149262)
		(end 286.21228 -45.499274)
		(width 0.12954)
		(layer "B.Cu")
		(net "SPI_SYS_CS0_N")
	)
	(segment
		(start 287.281366 -41.111424)
		(end 287.35147 -41.280588)
		(width 0.12954)
		(layer "B.Cu")
		(net "SPI_SYS_CS0_N")
	)
	(segment
		(start 272.761964 -61.021468)
		(end 260.084062 -61.021468)
		(width 0.12954)
		(layer "B.Cu")
		(net "SPI_SYS_CS0_N")
	)
	(segment
		(start 181.762146 -42.593768)
		(end 178.229514 -39.061136)
		(width 0.12954)
		(layer "B.Cu")
		(net "SPI_SYS_CS0_N")
	)
	(segment
		(start 166.6748 -21.681948)
		(end 170.13428 -18.222468)
		(width 0.12954)
		(layer "B.Cu")
		(net "SPI_SYS_CS0_N")
	)
	(segment
		(start 285.380938 -47.50562)
		(end 284.7467 -49.036732)
		(width 0.12954)
		(layer "B.Cu")
		(net "SPI_SYS_CS0_N")
	)
	(segment
		(start 286.700468 -44.321222)
		(end 286.531304 -44.391326)
		(width 0.12954)
		(layer "B.Cu")
		(net "SPI_SYS_CS0_N")
	)
	(segment
		(start 327.4568 -22.177248)
		(end 325.21271 -19.933158)
		(width 0.12954)
		(layer "B.Cu")
		(net "SPI_SYS_CS0_N")
	)
	(segment
		(start 286.793178 -42.289476)
		(end 286.863282 -42.45864)
		(width 0.12954)
		(layer "B.Cu")
		(net "SPI_SYS_CS0_N")
	)
	(segment
		(start 287.676844 -41.965118)
		(end 287.50768 -42.035222)
		(width 0.12954)
		(layer "B.Cu")
		(net "SPI_SYS_CS0_N")
	)
	(segment
		(start 285.154624 -46.581822)
		(end 284.98546 -46.651926)
		(width 0.12954)
		(layer "B.Cu")
		(net "SPI_SYS_CS0_N")
	)
	(segment
		(start 335.085182 -23.29815)
		(end 334.68818 -22.901148)
		(width 0.12954)
		(layer "B.Cu")
		(net "SPI_SYS_CS0_N")
	)
	(segment
		(start 285.869126 -46.327314)
		(end 285.724092 -46.677326)
		(width 0.12954)
		(layer "B.Cu")
		(net "SPI_SYS_CS0_N")
	)
	(segment
		(start 292.063932 -31.37154)
		(end 288.165032 -40.787066)
		(width 0.12954)
		(layer "B.Cu")
		(net "SPI_SYS_CS0_N")
	)
	(segment
		(start 287.35147 -41.280588)
		(end 287.751774 -41.44645)
		(width 0.12954)
		(layer "B.Cu")
		(net "SPI_SYS_CS0_N")
	)
	(segment
		(start 176.247806 -38.240208)
		(end 175.090582 -38.240208)
		(width 0.12954)
		(layer "B.Cu")
		(net "SPI_SYS_CS0_N")
	)
	(segment
		(start 210.885278 -45.334428)
		(end 198.379334 -45.334428)
		(width 0.12954)
		(layer "B.Cu")
		(net "SPI_SYS_CS0_N")
	)
	(segment
		(start 285.799022 -46.158658)
		(end 285.869126 -46.327314)
		(width 0.12954)
		(layer "B.Cu")
		(net "SPI_SYS_CS0_N")
	)
	(segment
		(start 286.775398 -43.802554)
		(end 286.845502 -43.97121)
		(width 0.12954)
		(layer "B.Cu")
		(net "SPI_SYS_CS0_N")
	)
	(segment
		(start 333.218536 -32.065722)
		(end 333.218536 -30.482032)
		(width 0.12954)
		(layer "B.Cu")
		(net "SPI_SYS_CS0_N")
	)
	(segment
		(start 333.218536 -30.482032)
		(end 333.29626 -30.404308)
		(width 0.12954)
		(layer "B.Cu")
		(net "SPI_SYS_CS0_N")
	)
	(segment
		(start 285.886906 -44.814744)
		(end 286.28721 -44.980606)
		(width 0.12954)
		(layer "B.Cu")
		(net "SPI_SYS_CS0_N")
	)
	(segment
		(start 286.531304 -44.391326)
		(end 286.131 -44.225718)
		(width 0.12954)
		(layer "B.Cu")
		(net "SPI_SYS_CS0_N")
	)
	(segment
		(start 172.197522 -35.347148)
		(end 170.60418 -35.347148)
		(width 0.12954)
		(layer "B.Cu")
		(net "SPI_SYS_CS0_N")
	)
	(segment
		(start 285.642812 -45.40377)
		(end 285.473648 -45.473874)
		(width 0.12954)
		(layer "B.Cu")
		(net "SPI_SYS_CS0_N")
	)
	(segment
		(start 314.22467 -19.933158)
		(end 313.36488 -20.792948)
		(width 0.12954)
		(layer "B.Cu")
		(net "SPI_SYS_CS0_N")
	)
	(segment
		(start 178.229514 -39.061136)
		(end 176.247806 -38.240208)
		(width 0.12954)
		(layer "B.Cu")
		(net "SPI_SYS_CS0_N")
	)
	(segment
		(start 184.06618 -43.246802)
		(end 183.413146 -42.593768)
		(width 0.12954)
		(layer "B.Cu")
		(net "SPI_SYS_CS0_N")
	)
	(segment
		(start 333.29626 -30.404308)
		(end 333.29626 -29.417772)
		(width 0.12954)
		(layer "B.Cu")
		(net "SPI_SYS_CS0_N")
	)
	(segment
		(start 287.595564 -40.691562)
		(end 287.4264 -40.761666)
		(width 0.12954)
		(layer "B.Cu")
		(net "SPI_SYS_CS0_N")
	)
	(segment
		(start 334.56118 -28.152852)
		(end 334.56118 -24.453088)
		(width 0.12954)
		(layer "B.Cu")
		(net "SPI_SYS_CS0_N")
	)
	(segment
		(start 332.7781 -32.773366)
		(end 332.7781 -32.506158)
		(width 0.12954)
		(layer "B.Cu")
		(net "SPI_SYS_CS0_N")
	)
	(segment
		(start 285.816802 -44.64558)
		(end 285.886906 -44.814744)
		(width 0.12954)
		(layer "B.Cu")
		(net "SPI_SYS_CS0_N")
	)
	(segment
		(start 197.082156 -46.631606)
		(end 186.471814 -46.631606)
		(width 0.12954)
		(layer "B.Cu")
		(net "SPI_SYS_CS0_N")
	)
	(segment
		(start 285.473648 -45.473874)
		(end 285.328614 -45.823632)
		(width 0.12954)
		(layer "B.Cu")
		(net "SPI_SYS_CS0_N")
	)
	(segment
		(start 285.328614 -45.823632)
		(end 285.398718 -45.992796)
		(width 0.12954)
		(layer "B.Cu")
		(net "SPI_SYS_CS0_N")
	)
	(segment
		(start 198.379334 -45.334428)
		(end 197.082156 -46.631606)
		(width 0.12954)
		(layer "B.Cu")
		(net "SPI_SYS_CS0_N")
	)
	(segment
		(start 287.188656 -43.14317)
		(end 287.019492 -43.213274)
		(width 0.12954)
		(layer "B.Cu")
		(net "SPI_SYS_CS0_N")
	)
	(segment
		(start 332.7781 -32.506158)
		(end 333.218536 -32.065722)
		(width 0.12954)
		(layer "B.Cu")
		(net "SPI_SYS_CS0_N")
	)
	(segment
		(start 330.64704 -22.177248)
		(end 327.4568 -22.177248)
		(width 0.12954)
		(layer "B.Cu")
		(net "SPI_SYS_CS0_N")
	)
	(segment
		(start 287.821878 -41.615106)
		(end 287.676844 -41.965118)
		(width 0.12954)
		(layer "B.Cu")
		(net "SPI_SYS_CS0_N")
	)
	(segment
		(start 284.840426 -47.001684)
		(end 284.91053 -47.170848)
		(width 0.12954)
		(layer "B.Cu")
		(net "SPI_SYS_CS0_N")
	)
	(segment
		(start 166.9796 -23.866348)
		(end 166.6748 -23.561548)
		(width 0.12954)
		(layer "B.Cu")
		(net "SPI_SYS_CS0_N")
	)
	(segment
		(start 287.4264 -40.761666)
		(end 287.281366 -41.111424)
		(width 0.12954)
		(layer "B.Cu")
		(net "SPI_SYS_CS0_N")
	)
	(segment
		(start 171.91736 -18.593308)
		(end 171.91736 -19.901408)
		(width 0.12954)
		(layer "B.Cu")
		(net "SPI_SYS_CS0_N")
	)
	(segment
		(start 335.085182 -23.929086)
		(end 335.085182 -23.29815)
		(width 0.12954)
		(layer "B.Cu")
		(net "SPI_SYS_CS0_N")
	)
	(segment
		(start 287.50768 -42.035222)
		(end 287.107376 -41.869614)
		(width 0.12954)
		(layer "B.Cu")
		(net "SPI_SYS_CS0_N")
	)
	(segment
		(start 287.33369 -42.793158)
		(end 287.188656 -43.14317)
		(width 0.12954)
		(layer "B.Cu")
		(net "SPI_SYS_CS0_N")
	)
	(segment
		(start 284.7467 -49.036732)
		(end 272.761964 -61.021468)
		(width 0.12954)
		(layer "B.Cu")
		(net "SPI_SYS_CS0_N")
	)
	(segment
		(start 284.98546 -46.651926)
		(end 284.840426 -47.001684)
		(width 0.12954)
		(layer "B.Cu")
		(net "SPI_SYS_CS0_N")
	)
	(segment
		(start 285.961836 -44.295822)
		(end 285.816802 -44.64558)
		(width 0.12954)
		(layer "B.Cu")
		(net "SPI_SYS_CS0_N")
	)
	(segment
		(start 166.9796 -31.722568)
		(end 166.9796 -23.866348)
		(width 0.12954)
		(layer "B.Cu")
		(net "SPI_SYS_CS0_N")
	)
	(segment
		(start 331.37094 -22.901148)
		(end 330.64704 -22.177248)
		(width 0.12954)
		(layer "B.Cu")
		(net "SPI_SYS_CS0_N")
	)
	(segment
		(start 286.845502 -43.97121)
		(end 286.700468 -44.321222)
		(width 0.12954)
		(layer "B.Cu")
		(net "SPI_SYS_CS0_N")
	)
	(segment
		(start 287.107376 -41.869614)
		(end 286.938212 -41.939718)
		(width 0.12954)
		(layer "B.Cu")
		(net "SPI_SYS_CS0_N")
	)
	(segment
		(start 287.263586 -42.624502)
		(end 287.33369 -42.793158)
		(width 0.12954)
		(layer "B.Cu")
		(net "SPI_SYS_CS0_N")
	)
	(segment
		(start 286.375094 -43.636692)
		(end 286.775398 -43.802554)
		(width 0.12954)
		(layer "B.Cu")
		(net "SPI_SYS_CS0_N")
	)
	(segment
		(start 258.003294 -61.88329)
		(end 253.411736 -66.474848)
		(width 0.12954)
		(layer "B.Cu")
		(net "SPI_SYS_CS0_N")
	)
	(segment
		(start 284.91053 -47.170848)
		(end 285.310834 -47.33671)
		(width 0.12954)
		(layer "B.Cu")
		(net "SPI_SYS_CS0_N")
	)
	(segment
		(start 184.06618 -44.225972)
		(end 184.06618 -43.246802)
		(width 0.12954)
		(layer "B.Cu")
		(net "SPI_SYS_CS0_N")
	)
	(segment
		(start 286.619188 -43.047666)
		(end 286.450024 -43.11777)
		(width 0.12954)
		(layer "B.Cu")
		(net "SPI_SYS_CS0_N")
	)
	(segment
		(start 286.21228 -45.499274)
		(end 286.043116 -45.569378)
		(width 0.12954)
		(layer "B.Cu")
		(net "SPI_SYS_CS0_N")
	)
	(segment
		(start 233.655108 -66.474848)
		(end 230.873554 -65.322704)
		(width 0.12954)
		(layer "B.Cu")
		(net "SPI_SYS_CS0_N")
	)
	(segment
		(start 171.91736 -19.901408)
		(end 171.33316 -20.485608)
		(width 0.12954)
		(layer "B.Cu")
		(net "SPI_SYS_CS0_N")
	)
	(segment
		(start 325.21271 -19.933158)
		(end 314.22467 -19.933158)
		(width 0.12954)
		(layer "B.Cu")
		(net "SPI_SYS_CS0_N")
	)
	(segment
		(start 334.68818 -22.901148)
		(end 331.37094 -22.901148)
		(width 0.12954)
		(layer "B.Cu")
		(net "SPI_SYS_CS0_N")
	)
	(segment
		(start 171.54652 -18.222468)
		(end 171.91736 -18.593308)
		(width 0.12954)
		(layer "B.Cu")
		(net "SPI_SYS_CS0_N")
	)
	(segment
		(start 287.995868 -40.85717)
		(end 287.595564 -40.691562)
		(width 0.12954)
		(layer "B.Cu")
		(net "SPI_SYS_CS0_N")
	)
	(segment
		(start 260.084062 -61.021468)
		(end 258.003294 -61.88329)
		(width 0.12954)
		(layer "B.Cu")
		(net "SPI_SYS_CS0_N")
	)
	(segment
		(start 166.6748 -23.561548)
		(end 166.6748 -21.681948)
		(width 0.12954)
		(layer "B.Cu")
		(net "SPI_SYS_CS0_N")
	)
	(segment
		(start 313.36488 -20.792948)
		(end 302.642524 -20.792948)
		(width 0.12954)
		(layer "B.Cu")
		(net "SPI_SYS_CS0_N")
	)
	(segment
		(start 172.866812 -17.466056)
		(end 172.867066 -17.465802)
		(width 0.12954)
		(layer "F.Cu")
		(net "SPI_SYS_CLK")
	)
	(segment
		(start 172.866812 -19.301968)
		(end 172.866812 -17.466056)
		(width 0.12954)
		(layer "F.Cu")
		(net "SPI_SYS_CLK")
	)
	(segment
		(start 172.867066 -17.465802)
		(end 172.867066 -16.550132)
		(width 0.12954)
		(layer "F.Cu")
		(net "SPI_SYS_CLK")
	)
	(via
		(at 172.866812 -19.301968)
		(size 0.508)
		(drill 0.254)
		(layers "F.Cu" "B.Cu")
		(net "SPI_SYS_CLK")
	)
	(segment
		(start 281.605228 -43.218354)
		(end 281.475688 -43.347894)
		(width 0.12954)
		(layer "B.Cu")
		(net "SPI_SYS_CLK")
	)
	(segment
		(start 281.475688 -46.276514)
		(end 281.605228 -46.406054)
		(width 0.12954)
		(layer "B.Cu")
		(net "SPI_SYS_CLK")
	)
	(segment
		(start 281.605228 -42.580814)
		(end 281.764486 -42.580814)
		(width 0.12954)
		(layer "B.Cu")
		(net "SPI_SYS_CLK")
	)
	(segment
		(start 172.745654 -20.264374)
		(end 172.866812 -19.971766)
		(width 0.12954)
		(layer "B.Cu")
		(net "SPI_SYS_CLK")
	)
	(segment
		(start 281.764486 -47.681134)
		(end 281.894026 -47.810674)
		(width 0.12954)
		(layer "B.Cu")
		(net "SPI_SYS_CLK")
	)
	(segment
		(start 281.475688 -43.347894)
		(end 281.475688 -43.726354)
		(width 0.12954)
		(layer "B.Cu")
		(net "SPI_SYS_CLK")
	)
	(segment
		(start 213.504526 -44.937934)
		(end 213.504526 -44.754546)
		(width 0.12954)
		(layer "B.Cu")
		(net "SPI_SYS_CLK")
	)
	(segment
		(start 336.24012 -29.886148)
		(end 337.77428 -29.886148)
		(width 0.12954)
		(layer "B.Cu")
		(net "SPI_SYS_CLK")
	)
	(segment
		(start 252.995938 -64.544448)
		(end 233.331512 -64.544448)
		(width 0.12954)
		(layer "B.Cu")
		(net "SPI_SYS_CLK")
	)
	(segment
		(start 281.605228 -41.305734)
		(end 281.764486 -41.305734)
		(width 0.12954)
		(layer "B.Cu")
		(net "SPI_SYS_CLK")
	)
	(segment
		(start 175.5775 -36.380928)
		(end 169.1386 -29.942028)
		(width 0.12954)
		(layer "B.Cu")
		(net "SPI_SYS_CLK")
	)
	(segment
		(start 281.475688 -43.726354)
		(end 281.605228 -43.855894)
		(width 0.12954)
		(layer "B.Cu")
		(net "SPI_SYS_CLK")
	)
	(segment
		(start 281.475688 -44.622974)
		(end 281.475688 -45.001434)
		(width 0.12954)
		(layer "B.Cu")
		(net "SPI_SYS_CLK")
	)
	(segment
		(start 281.605228 -45.768514)
		(end 281.475688 -45.898054)
		(width 0.12954)
		(layer "B.Cu")
		(net "SPI_SYS_CLK")
	)
	(segment
		(start 335.280254 -20.098766)
		(end 334.304386 -19.122898)
		(width 0.12954)
		(layer "B.Cu")
		(net "SPI_SYS_CLK")
	)
	(segment
		(start 195.272152 -43.482768)
		(end 194.078606 -44.676314)
		(width 0.12954)
		(layer "B.Cu")
		(net "SPI_SYS_CLK")
	)
	(segment
		(start 340.39048 -27.269948)
		(end 340.39048 -23.381716)
		(width 0.12954)
		(layer "B.Cu")
		(net "SPI_SYS_CLK")
	)
	(segment
		(start 281.894026 -41.813734)
		(end 281.764486 -41.943274)
		(width 0.12954)
		(layer "B.Cu")
		(net "SPI_SYS_CLK")
	)
	(segment
		(start 281.475688 -41.176194)
		(end 281.605228 -41.305734)
		(width 0.12954)
		(layer "B.Cu")
		(net "SPI_SYS_CLK")
	)
	(segment
		(start 214.820246 -44.523914)
		(end 214.636858 -44.523914)
		(width 0.12954)
		(layer "B.Cu")
		(net "SPI_SYS_CLK")
	)
	(segment
		(start 335.099152 -30.994858)
		(end 335.13141 -30.994858)
		(width 0.12954)
		(layer "B.Cu")
		(net "SPI_SYS_CLK")
	)
	(segment
		(start 329.55611 -18.274538)
		(end 312.20029 -18.274538)
		(width 0.12954)
		(layer "B.Cu")
		(net "SPI_SYS_CLK")
	)
	(segment
		(start 281.475688 -45.001434)
		(end 281.605228 -45.130974)
		(width 0.12954)
		(layer "B.Cu")
		(net "SPI_SYS_CLK")
	)
	(segment
		(start 281.894026 -45.638974)
		(end 281.764486 -45.768514)
		(width 0.12954)
		(layer "B.Cu")
		(net "SPI_SYS_CLK")
	)
	(segment
		(start 281.475688 -40.797734)
		(end 281.475688 -41.176194)
		(width 0.12954)
		(layer "B.Cu")
		(net "SPI_SYS_CLK")
	)
	(segment
		(start 216.68232 -46.385988)
		(end 214.820246 -44.523914)
		(width 0.12954)
		(layer "B.Cu")
		(net "SPI_SYS_CLK")
	)
	(segment
		(start 281.764486 -40.668194)
		(end 281.605228 -40.668194)
		(width 0.12954)
		(layer "B.Cu")
		(net "SPI_SYS_CLK")
	)
	(segment
		(start 281.894026 -43.985434)
		(end 281.894026 -44.363894)
		(width 0.12954)
		(layer "B.Cu")
		(net "SPI_SYS_CLK")
	)
	(segment
		(start 189.013846 -44.676314)
		(end 180.71846 -36.380928)
		(width 0.12954)
		(layer "B.Cu")
		(net "SPI_SYS_CLK")
	)
	(segment
		(start 312.20029 -18.274538)
		(end 311.71388 -18.760948)
		(width 0.12954)
		(layer "B.Cu")
		(net "SPI_SYS_CLK")
	)
	(segment
		(start 213.955376 -45.205396)
		(end 213.771988 -45.205396)
		(width 0.12954)
		(layer "B.Cu")
		(net "SPI_SYS_CLK")
	)
	(segment
		(start 281.764486 -45.130974)
		(end 281.894026 -45.260514)
		(width 0.12954)
		(layer "B.Cu")
		(net "SPI_SYS_CLK")
	)
	(segment
		(start 281.894026 -38.8112)
		(end 281.894026 -40.538654)
		(width 0.12954)
		(layer "B.Cu")
		(net "SPI_SYS_CLK")
	)
	(segment
		(start 281.764486 -41.943274)
		(end 281.605228 -41.943274)
		(width 0.12954)
		(layer "B.Cu")
		(net "SPI_SYS_CLK")
	)
	(segment
		(start 281.894026 -41.435274)
		(end 281.894026 -41.813734)
		(width 0.12954)
		(layer "B.Cu")
		(net "SPI_SYS_CLK")
	)
	(segment
		(start 213.771988 -45.205396)
		(end 213.504526 -44.937934)
		(width 0.12954)
		(layer "B.Cu")
		(net "SPI_SYS_CLK")
	)
	(segment
		(start 194.078606 -44.676314)
		(end 189.013846 -44.676314)
		(width 0.12954)
		(layer "B.Cu")
		(net "SPI_SYS_CLK")
	)
	(segment
		(start 281.764486 -46.406054)
		(end 281.894026 -46.535594)
		(width 0.12954)
		(layer "B.Cu")
		(net "SPI_SYS_CLK")
	)
	(segment
		(start 216.68232 -48.785272)
		(end 216.68232 -46.385988)
		(width 0.12954)
		(layer "B.Cu")
		(net "SPI_SYS_CLK")
	)
	(segment
		(start 281.605228 -40.668194)
		(end 281.475688 -40.797734)
		(width 0.12954)
		(layer "B.Cu")
		(net "SPI_SYS_CLK")
	)
	(segment
		(start 281.605228 -41.943274)
		(end 281.475688 -42.072814)
		(width 0.12954)
		(layer "B.Cu")
		(net "SPI_SYS_CLK")
	)
	(segment
		(start 281.894026 -44.363894)
		(end 281.764486 -44.493434)
		(width 0.12954)
		(layer "B.Cu")
		(net "SPI_SYS_CLK")
	)
	(segment
		(start 281.764486 -47.043594)
		(end 281.605228 -47.043594)
		(width 0.12954)
		(layer "B.Cu")
		(net "SPI_SYS_CLK")
	)
	(segment
		(start 334.304386 -19.122898)
		(end 330.40447 -19.122898)
		(width 0.12954)
		(layer "B.Cu")
		(net "SPI_SYS_CLK")
	)
	(segment
		(start 337.77428 -29.886148)
		(end 340.39048 -27.269948)
		(width 0.12954)
		(layer "B.Cu")
		(net "SPI_SYS_CLK")
	)
	(segment
		(start 214.186008 -44.073064)
		(end 214.186008 -43.889676)
		(width 0.12954)
		(layer "B.Cu")
		(net "SPI_SYS_CLK")
	)
	(segment
		(start 281.605228 -47.681134)
		(end 281.764486 -47.681134)
		(width 0.12954)
		(layer "B.Cu")
		(net "SPI_SYS_CLK")
	)
	(segment
		(start 281.894026 -43.088814)
		(end 281.764486 -43.218354)
		(width 0.12954)
		(layer "B.Cu")
		(net "SPI_SYS_CLK")
	)
	(segment
		(start 180.71846 -36.380928)
		(end 175.5775 -36.380928)
		(width 0.12954)
		(layer "B.Cu")
		(net "SPI_SYS_CLK")
	)
	(segment
		(start 281.894026 -49.15916)
		(end 271.690338 -59.362848)
		(width 0.12954)
		(layer "B.Cu")
		(net "SPI_SYS_CLK")
	)
	(segment
		(start 337.10753 -20.098766)
		(end 335.280254 -20.098766)
		(width 0.12954)
		(layer "B.Cu")
		(net "SPI_SYS_CLK")
	)
	(segment
		(start 281.764486 -43.855894)
		(end 281.894026 -43.985434)
		(width 0.12954)
		(layer "B.Cu")
		(net "SPI_SYS_CLK")
	)
	(segment
		(start 330.40447 -19.122898)
		(end 329.55611 -18.274538)
		(width 0.12954)
		(layer "B.Cu")
		(net "SPI_SYS_CLK")
	)
	(segment
		(start 281.605228 -44.493434)
		(end 281.475688 -44.622974)
		(width 0.12954)
		(layer "B.Cu")
		(net "SPI_SYS_CLK")
	)
	(segment
		(start 281.475688 -45.898054)
		(end 281.475688 -46.276514)
		(width 0.12954)
		(layer "B.Cu")
		(net "SPI_SYS_CLK")
	)
	(segment
		(start 281.764486 -45.768514)
		(end 281.605228 -45.768514)
		(width 0.12954)
		(layer "B.Cu")
		(net "SPI_SYS_CLK")
	)
	(segment
		(start 257.063494 -60.476892)
		(end 252.995938 -64.544448)
		(width 0.12954)
		(layer "B.Cu")
		(net "SPI_SYS_CLK")
	)
	(segment
		(start 281.605228 -46.406054)
		(end 281.764486 -46.406054)
		(width 0.12954)
		(layer "B.Cu")
		(net "SPI_SYS_CLK")
	)
	(segment
		(start 214.186008 -43.889676)
		(end 213.7791 -43.482768)
		(width 0.12954)
		(layer "B.Cu")
		(net "SPI_SYS_CLK")
	)
	(segment
		(start 281.894026 -45.260514)
		(end 281.894026 -45.638974)
		(width 0.12954)
		(layer "B.Cu")
		(net "SPI_SYS_CLK")
	)
	(segment
		(start 172.866812 -19.971766)
		(end 172.866812 -19.301968)
		(width 0.12954)
		(layer "B.Cu")
		(net "SPI_SYS_CLK")
	)
	(segment
		(start 214.636858 -44.523914)
		(end 213.955376 -45.205396)
		(width 0.12954)
		(layer "B.Cu")
		(net "SPI_SYS_CLK")
	)
	(segment
		(start 213.504526 -44.754546)
		(end 214.186008 -44.073064)
		(width 0.12954)
		(layer "B.Cu")
		(net "SPI_SYS_CLK")
	)
	(segment
		(start 335.13141 -30.994858)
		(end 336.24012 -29.886148)
		(width 0.12954)
		(layer "B.Cu")
		(net "SPI_SYS_CLK")
	)
	(segment
		(start 340.39048 -23.381716)
		(end 337.10753 -20.098766)
		(width 0.12954)
		(layer "B.Cu")
		(net "SPI_SYS_CLK")
	)
	(segment
		(start 213.7791 -43.482768)
		(end 195.272152 -43.482768)
		(width 0.12954)
		(layer "B.Cu")
		(net "SPI_SYS_CLK")
	)
	(segment
		(start 281.764486 -44.493434)
		(end 281.605228 -44.493434)
		(width 0.12954)
		(layer "B.Cu")
		(net "SPI_SYS_CLK")
	)
	(segment
		(start 281.605228 -47.043594)
		(end 281.475688 -47.173134)
		(width 0.12954)
		(layer "B.Cu")
		(net "SPI_SYS_CLK")
	)
	(segment
		(start 281.894026 -40.538654)
		(end 281.764486 -40.668194)
		(width 0.12954)
		(layer "B.Cu")
		(net "SPI_SYS_CLK")
	)
	(segment
		(start 271.690338 -59.362848)
		(end 259.7531 -59.362848)
		(width 0.12954)
		(layer "B.Cu")
		(net "SPI_SYS_CLK")
	)
	(segment
		(start 281.475688 -47.551594)
		(end 281.605228 -47.681134)
		(width 0.12954)
		(layer "B.Cu")
		(net "SPI_SYS_CLK")
	)
	(segment
		(start 231.812338 -63.91529)
		(end 216.68232 -48.785272)
		(width 0.12954)
		(layer "B.Cu")
		(net "SPI_SYS_CLK")
	)
	(segment
		(start 171.69892 -21.311108)
		(end 172.745654 -20.264374)
		(width 0.12954)
		(layer "B.Cu")
		(net "SPI_SYS_CLK")
	)
	(segment
		(start 311.71388 -18.760948)
		(end 301.944278 -18.760948)
		(width 0.12954)
		(layer "B.Cu")
		(net "SPI_SYS_CLK")
	)
	(segment
		(start 281.475688 -47.173134)
		(end 281.475688 -47.551594)
		(width 0.12954)
		(layer "B.Cu")
		(net "SPI_SYS_CLK")
	)
	(segment
		(start 281.894026 -47.810674)
		(end 281.894026 -49.15916)
		(width 0.12954)
		(layer "B.Cu")
		(net "SPI_SYS_CLK")
	)
	(segment
		(start 281.764486 -42.580814)
		(end 281.894026 -42.710354)
		(width 0.12954)
		(layer "B.Cu")
		(net "SPI_SYS_CLK")
	)
	(segment
		(start 259.7531 -59.362848)
		(end 257.063494 -60.476892)
		(width 0.12954)
		(layer "B.Cu")
		(net "SPI_SYS_CLK")
	)
	(segment
		(start 281.894026 -42.710354)
		(end 281.894026 -43.088814)
		(width 0.12954)
		(layer "B.Cu")
		(net "SPI_SYS_CLK")
	)
	(segment
		(start 281.475688 -42.451274)
		(end 281.605228 -42.580814)
		(width 0.12954)
		(layer "B.Cu")
		(net "SPI_SYS_CLK")
	)
	(segment
		(start 281.605228 -43.855894)
		(end 281.764486 -43.855894)
		(width 0.12954)
		(layer "B.Cu")
		(net "SPI_SYS_CLK")
	)
	(segment
		(start 281.894026 -46.914054)
		(end 281.764486 -47.043594)
		(width 0.12954)
		(layer "B.Cu")
		(net "SPI_SYS_CLK")
	)
	(segment
		(start 171.0817 -21.311108)
		(end 171.69892 -21.311108)
		(width 0.12954)
		(layer "B.Cu")
		(net "SPI_SYS_CLK")
	)
	(segment
		(start 281.894026 -46.535594)
		(end 281.894026 -46.914054)
		(width 0.12954)
		(layer "B.Cu")
		(net "SPI_SYS_CLK")
	)
	(segment
		(start 170.72864 -20.958048)
		(end 171.0817 -21.311108)
		(width 0.12954)
		(layer "B.Cu")
		(net "SPI_SYS_CLK")
	)
	(segment
		(start 281.764486 -41.305734)
		(end 281.894026 -41.435274)
		(width 0.12954)
		(layer "B.Cu")
		(net "SPI_SYS_CLK")
	)
	(segment
		(start 281.605228 -45.130974)
		(end 281.764486 -45.130974)
		(width 0.12954)
		(layer "B.Cu")
		(net "SPI_SYS_CLK")
	)
	(segment
		(start 169.1386 -21.834348)
		(end 170.0149 -20.958048)
		(width 0.12954)
		(layer "B.Cu")
		(net "SPI_SYS_CLK")
	)
	(segment
		(start 301.944278 -18.760948)
		(end 281.894026 -38.8112)
		(width 0.12954)
		(layer "B.Cu")
		(net "SPI_SYS_CLK")
	)
	(segment
		(start 233.331512 -64.544448)
		(end 231.812338 -63.91529)
		(width 0.12954)
		(layer "B.Cu")
		(net "SPI_SYS_CLK")
	)
	(segment
		(start 281.764486 -43.218354)
		(end 281.605228 -43.218354)
		(width 0.12954)
		(layer "B.Cu")
		(net "SPI_SYS_CLK")
	)
	(segment
		(start 170.0149 -20.958048)
		(end 170.72864 -20.958048)
		(width 0.12954)
		(layer "B.Cu")
		(net "SPI_SYS_CLK")
	)
	(segment
		(start 169.1386 -29.942028)
		(end 169.1386 -21.834348)
		(width 0.12954)
		(layer "B.Cu")
		(net "SPI_SYS_CLK")
	)
	(segment
		(start 281.475688 -42.072814)
		(end 281.475688 -42.451274)
		(width 0.12954)
		(layer "B.Cu")
		(net "SPI_SYS_CLK")
	)
	(segment
		(start 331.608176 -39.992046)
		(end 331.067918 -39.992046)
		(width 0.12954)
		(layer "F.Cu")
		(net "SPI_PCH_TPM_CS_N")
	)
	(via
		(at 331.067918 -39.992046)
		(size 0.4572)
		(drill 0.2032)
		(layers "F.Cu" "B.Cu")
		(net "SPI_PCH_TPM_CS_N")
	)
	(via
		(at 331.49921 -36.248848)
		(size 0.6604)
		(drill 0.3302)
		(layers "F.Cu" "B.Cu")
		(net "SPI_PCH_TPM_CS_N")
	)
	(segment
		(start 331.49921 -37.536882)
		(end 331.49921 -36.248848)
		(width 0.12954)
		(layer "B.Cu")
		(net "SPI_PCH_TPM_CS_N")
	)
	(segment
		(start 331.067918 -39.992046)
		(end 331.067918 -38.847268)
		(width 0.12954)
		(layer "B.Cu")
		(net "SPI_PCH_TPM_CS_N")
	)
	(segment
		(start 331.369162 -38.546024)
		(end 331.369162 -37.66693)
		(width 0.12954)
		(layer "B.Cu")
		(net "SPI_PCH_TPM_CS_N")
	)
	(segment
		(start 331.067918 -38.847268)
		(end 331.369162 -38.546024)
		(width 0.12954)
		(layer "B.Cu")
		(net "SPI_PCH_TPM_CS_N")
	)
	(segment
		(start 331.49921 -33.723072)
		(end 332.162912 -33.05937)
		(width 0.12954)
		(layer "B.Cu")
		(net "SPI_PCH_TPM_CS_N")
	)
	(segment
		(start 332.162912 -33.05937)
		(end 332.162912 -32.167322)
		(width 0.12954)
		(layer "B.Cu")
		(net "SPI_PCH_TPM_CS_N")
	)
	(segment
		(start 331.49921 -36.248848)
		(end 331.49921 -33.723072)
		(width 0.12954)
		(layer "B.Cu")
		(net "SPI_PCH_TPM_CS_N")
	)
	(segment
		(start 332.162912 -32.167322)
		(end 332.543912 -31.786322)
		(width 0.12954)
		(layer "B.Cu")
		(net "SPI_PCH_TPM_CS_N")
	)
	(segment
		(start 331.369162 -37.66693)
		(end 331.49921 -37.536882)
		(width 0.12954)
		(layer "B.Cu")
		(net "SPI_PCH_TPM_CS_N")
	)
	(segment
		(start 334.05064 -40.461946)
		(end 333.511398 -40.461946)
		(width 0.12954)
		(layer "F.Cu")
		(net "SPI_PCH_IO3")
	)
	(via
		(at 333.511398 -40.461946)
		(size 0.4572)
		(drill 0.2032)
		(layers "F.Cu" "B.Cu")
		(net "SPI_PCH_IO3")
	)
	(via
		(at 335.50352 -36.43122)
		(size 0.6604)
		(drill 0.3302)
		(layers "F.Cu" "B.Cu")
		(net "SPI_PCH_IO3")
	)
	(segment
		(start 337.166712 -32.093408)
		(end 337.166712 -32.413448)
		(width 0.12954)
		(layer "B.Cu")
		(net "SPI_PCH_IO3")
	)
	(segment
		(start 335.1911 -36.74364)
		(end 335.1911 -37.765736)
		(width 0.12954)
		(layer "B.Cu")
		(net "SPI_PCH_IO3")
	)
	(segment
		(start 336.387186 -35.547554)
		(end 335.50352 -36.43122)
		(width 0.12954)
		(layer "B.Cu")
		(net "SPI_PCH_IO3")
	)
	(segment
		(start 337.166712 -32.413448)
		(end 336.924142 -32.656018)
		(width 0.12954)
		(layer "B.Cu")
		(net "SPI_PCH_IO3")
	)
	(segment
		(start 335.50352 -36.43122)
		(end 335.1911 -36.74364)
		(width 0.12954)
		(layer "B.Cu")
		(net "SPI_PCH_IO3")
	)
	(segment
		(start 333.511398 -39.445438)
		(end 333.511398 -40.461946)
		(width 0.12954)
		(layer "B.Cu")
		(net "SPI_PCH_IO3")
	)
	(segment
		(start 336.924142 -34.292794)
		(end 336.387186 -34.82975)
		(width 0.12954)
		(layer "B.Cu")
		(net "SPI_PCH_IO3")
	)
	(segment
		(start 336.924142 -32.656018)
		(end 336.924142 -34.292794)
		(width 0.12954)
		(layer "B.Cu")
		(net "SPI_PCH_IO3")
	)
	(segment
		(start 336.387186 -34.82975)
		(end 336.387186 -35.547554)
		(width 0.12954)
		(layer "B.Cu")
		(net "SPI_PCH_IO3")
	)
	(segment
		(start 335.1911 -37.765736)
		(end 333.511398 -39.445438)
		(width 0.12954)
		(layer "B.Cu")
		(net "SPI_PCH_IO3")
	)
	(segment
		(start 333.23657 -41.871646)
		(end 332.697328 -41.871646)
		(width 0.12954)
		(layer "F.Cu")
		(net "SPI_PCH_IO2")
	)
	(via
		(at 334.01508 -35.499548)
		(size 0.6604)
		(drill 0.3302)
		(layers "F.Cu" "B.Cu")
		(net "SPI_PCH_IO2")
	)
	(via
		(at 332.697328 -41.871646)
		(size 0.4572)
		(drill 0.2032)
		(layers "F.Cu" "B.Cu")
		(net "SPI_PCH_IO2")
	)
	(segment
		(start 332.823312 -38.620446)
		(end 332.823312 -38.354254)
		(width 0.12954)
		(layer "B.Cu")
		(net "SPI_PCH_IO2")
	)
	(segment
		(start 334.59928 -33.998408)
		(end 334.744314 -33.853374)
		(width 0.12954)
		(layer "B.Cu")
		(net "SPI_PCH_IO2")
	)
	(segment
		(start 332.227936 -40.019478)
		(end 332.227936 -39.215822)
		(width 0.12954)
		(layer "B.Cu")
		(net "SPI_PCH_IO2")
	)
	(segment
		(start 333.547974 -37.629592)
		(end 333.547974 -35.966654)
		(width 0.12954)
		(layer "B.Cu")
		(net "SPI_PCH_IO2")
	)
	(segment
		(start 334.01508 -35.397948)
		(end 334.59928 -34.813748)
		(width 0.12954)
		(layer "B.Cu")
		(net "SPI_PCH_IO2")
	)
	(segment
		(start 333.547974 -35.966654)
		(end 334.01508 -35.499548)
		(width 0.12954)
		(layer "B.Cu")
		(net "SPI_PCH_IO2")
	)
	(segment
		(start 332.823312 -38.354254)
		(end 333.547974 -37.629592)
		(width 0.12954)
		(layer "B.Cu")
		(net "SPI_PCH_IO2")
	)
	(segment
		(start 334.744314 -33.853374)
		(end 334.744314 -33.573212)
		(width 0.12954)
		(layer "B.Cu")
		(net "SPI_PCH_IO2")
	)
	(segment
		(start 332.697328 -41.871646)
		(end 332.290166 -41.166796)
		(width 0.12954)
		(layer "B.Cu")
		(net "SPI_PCH_IO2")
	)
	(segment
		(start 332.227936 -39.215822)
		(end 332.823312 -38.620446)
		(width 0.12954)
		(layer "B.Cu")
		(net "SPI_PCH_IO2")
	)
	(segment
		(start 334.01508 -35.499548)
		(end 334.01508 -35.397948)
		(width 0.12954)
		(layer "B.Cu")
		(net "SPI_PCH_IO2")
	)
	(segment
		(start 334.59928 -34.813748)
		(end 334.59928 -33.998408)
		(width 0.12954)
		(layer "B.Cu")
		(net "SPI_PCH_IO2")
	)
	(arc
		(start 332.290166 -40.696896)
		(mid 332.353092 -40.461946)
		(end 332.290166 -40.226996)
		(width 0.12954)
		(layer "B.Cu")
		(net "SPI_PCH_IO2")
	)
	(arc
		(start 332.290166 -41.166796)
		(mid 332.22724 -40.931846)
		(end 332.290166 -40.696896)
		(width 0.12954)
		(layer "B.Cu")
		(net "SPI_PCH_IO2")
	)
	(arc
		(start 332.290166 -40.226996)
		(mid 332.246933 -40.12687)
		(end 332.227936 -40.019478)
		(width 0.12954)
		(layer "B.Cu")
		(net "SPI_PCH_IO2")
	)
	(segment
		(start 334.05064 -41.401746)
		(end 333.511398 -41.401746)
		(width 0.12954)
		(layer "F.Cu")
		(net "SPI_PCH_IO1")
	)
	(via
		(at 333.511398 -41.401746)
		(size 0.4572)
		(drill 0.2032)
		(layers "F.Cu" "B.Cu")
		(net "SPI_PCH_IO1")
	)
	(via
		(at 335.723738 -34.772346)
		(size 0.6604)
		(drill 0.3302)
		(layers "F.Cu" "B.Cu")
		(net "SPI_PCH_IO1")
	)
	(segment
		(start 335.723738 -35.417252)
		(end 334.68056 -36.46043)
		(width 0.12954)
		(layer "B.Cu")
		(net "SPI_PCH_IO1")
	)
	(segment
		(start 335.798414 -34.482278)
		(end 335.798414 -34.69767)
		(width 0.12954)
		(layer "B.Cu")
		(net "SPI_PCH_IO1")
	)
	(segment
		(start 336.167222 -34.11347)
		(end 335.798414 -34.482278)
		(width 0.12954)
		(layer "B.Cu")
		(net "SPI_PCH_IO1")
	)
	(segment
		(start 334.68056 -37.697156)
		(end 333.164688 -39.213028)
		(width 0.12954)
		(layer "B.Cu")
		(net "SPI_PCH_IO1")
	)
	(segment
		(start 333.10449 -40.696896)
		(end 333.511398 -41.401746)
		(width 0.12954)
		(layer "B.Cu")
		(net "SPI_PCH_IO1")
	)
	(segment
		(start 336.167222 -33.60547)
		(end 336.167222 -34.11347)
		(width 0.12954)
		(layer "B.Cu")
		(net "SPI_PCH_IO1")
	)
	(segment
		(start 334.68056 -36.46043)
		(end 334.68056 -37.697156)
		(width 0.12954)
		(layer "B.Cu")
		(net "SPI_PCH_IO1")
	)
	(segment
		(start 335.723738 -34.772346)
		(end 335.723738 -35.417252)
		(width 0.12954)
		(layer "B.Cu")
		(net "SPI_PCH_IO1")
	)
	(segment
		(start 333.164688 -39.213028)
		(end 333.164688 -40.042846)
		(width 0.12954)
		(layer "B.Cu")
		(net "SPI_PCH_IO1")
	)
	(segment
		(start 335.798414 -34.69767)
		(end 335.723738 -34.772346)
		(width 0.12954)
		(layer "B.Cu")
		(net "SPI_PCH_IO1")
	)
	(arc
		(start 333.10449 -40.226996)
		(mid 333.04153 -40.461946)
		(end 333.10449 -40.696896)
		(width 0.12954)
		(layer "B.Cu")
		(net "SPI_PCH_IO1")
	)
	(arc
		(start 333.164688 -40.042846)
		(mid 333.14419 -40.138061)
		(end 333.10449 -40.226996)
		(width 0.12954)
		(layer "B.Cu")
		(net "SPI_PCH_IO1")
	)
	(segment
		(start 332.422246 -40.461946)
		(end 331.883004 -40.461946)
		(width 0.12954)
		(layer "F.Cu")
		(net "SPI_PCH_IO0")
	)
	(via
		(at 332.96352 -36.431474)
		(size 0.6604)
		(drill 0.3302)
		(layers "F.Cu" "B.Cu")
		(net "SPI_PCH_IO0")
	)
	(via
		(at 331.883004 -40.461946)
		(size 0.4572)
		(drill 0.2032)
		(layers "F.Cu" "B.Cu")
		(net "SPI_PCH_IO0")
	)
	(segment
		(start 333.17688 -35.296348)
		(end 333.17688 -34.204148)
		(width 0.12954)
		(layer "B.Cu")
		(net "SPI_PCH_IO0")
	)
	(segment
		(start 332.96352 -36.431474)
		(end 332.96352 -35.509708)
		(width 0.12954)
		(layer "B.Cu")
		(net "SPI_PCH_IO0")
	)
	(segment
		(start 333.17688 -34.204148)
		(end 333.33817 -34.042858)
		(width 0.12954)
		(layer "B.Cu")
		(net "SPI_PCH_IO0")
	)
	(segment
		(start 332.313026 -38.68928)
		(end 332.313026 -38.16731)
		(width 0.12954)
		(layer "B.Cu")
		(net "SPI_PCH_IO0")
	)
	(segment
		(start 333.824326 -32.231584)
		(end 333.824326 -31.797752)
		(width 0.12954)
		(layer "B.Cu")
		(net "SPI_PCH_IO0")
	)
	(segment
		(start 332.96352 -37.516816)
		(end 332.96352 -36.431474)
		(width 0.12954)
		(layer "B.Cu")
		(net "SPI_PCH_IO0")
	)
	(segment
		(start 332.96352 -35.509708)
		(end 333.17688 -35.296348)
		(width 0.12954)
		(layer "B.Cu")
		(net "SPI_PCH_IO0")
	)
	(segment
		(start 333.33817 -34.042858)
		(end 333.33817 -32.71774)
		(width 0.12954)
		(layer "B.Cu")
		(net "SPI_PCH_IO0")
	)
	(segment
		(start 333.33817 -32.71774)
		(end 333.824326 -32.231584)
		(width 0.12954)
		(layer "B.Cu")
		(net "SPI_PCH_IO0")
	)
	(segment
		(start 332.313026 -38.16731)
		(end 332.96352 -37.516816)
		(width 0.12954)
		(layer "B.Cu")
		(net "SPI_PCH_IO0")
	)
	(segment
		(start 331.883004 -40.461946)
		(end 331.883004 -39.119302)
		(width 0.12954)
		(layer "B.Cu")
		(net "SPI_PCH_IO0")
	)
	(segment
		(start 331.883004 -39.119302)
		(end 332.313026 -38.68928)
		(width 0.12954)
		(layer "B.Cu")
		(net "SPI_PCH_IO0")
	)
	(segment
		(start 332.422246 -41.401746)
		(end 331.883004 -41.401746)
		(width 0.12954)
		(layer "F.Cu")
		(net "SPI_PCH_CS0_R_N")
	)
	(via
		(at 332.44155 -34.727134)
		(size 0.6604)
		(drill 0.3302)
		(layers "F.Cu" "B.Cu")
		(net "SPI_PCH_CS0_R_N")
	)
	(via
		(at 331.883004 -41.401746)
		(size 0.4572)
		(drill 0.2032)
		(layers "F.Cu" "B.Cu")
		(net "SPI_PCH_CS0_R_N")
	)
	(segment
		(start 331.475588 -40.696896)
		(end 331.475334 -40.696896)
		(width 0.12954)
		(layer "B.Cu")
		(net "SPI_PCH_CS0_R_N")
	)
	(segment
		(start 332.44155 -37.316664)
		(end 332.44155 -34.727134)
		(width 0.12954)
		(layer "B.Cu")
		(net "SPI_PCH_CS0_R_N")
	)
	(segment
		(start 331.883004 -41.401746)
		(end 331.475588 -40.696896)
		(width 0.12954)
		(layer "B.Cu")
		(net "SPI_PCH_CS0_R_N")
	)
	(segment
		(start 331.492352 -38.958774)
		(end 331.879702 -38.571424)
		(width 0.12954)
		(layer "B.Cu")
		(net "SPI_PCH_CS0_R_N")
	)
	(segment
		(start 331.879702 -37.878512)
		(end 332.44155 -37.316664)
		(width 0.12954)
		(layer "B.Cu")
		(net "SPI_PCH_CS0_R_N")
	)
	(segment
		(start 331.879702 -38.571424)
		(end 331.879702 -37.878512)
		(width 0.12954)
		(layer "B.Cu")
		(net "SPI_PCH_CS0_R_N")
	)
	(segment
		(start 332.44155 -33.910016)
		(end 332.7781 -33.573466)
		(width 0.12954)
		(layer "B.Cu")
		(net "SPI_PCH_CS0_R_N")
	)
	(segment
		(start 331.492352 -40.163496)
		(end 331.492352 -38.958774)
		(width 0.12954)
		(layer "B.Cu")
		(net "SPI_PCH_CS0_R_N")
	)
	(segment
		(start 332.44155 -34.727134)
		(end 332.44155 -33.910016)
		(width 0.12954)
		(layer "B.Cu")
		(net "SPI_PCH_CS0_R_N")
	)
	(arc
		(start 331.475334 -40.226996)
		(mid 331.488022 -40.196366)
		(end 331.492352 -40.163496)
		(width 0.12954)
		(layer "B.Cu")
		(net "SPI_PCH_CS0_R_N")
	)
	(arc
		(start 331.475334 -40.696896)
		(mid 331.412476 -40.461946)
		(end 331.475334 -40.226996)
		(width 0.12954)
		(layer "B.Cu")
		(net "SPI_PCH_CS0_R_N")
	)
	(segment
		(start 333.23657 -39.992046)
		(end 332.697328 -39.992046)
		(width 0.12954)
		(layer "F.Cu")
		(net "SPI_PCH_CLK")
	)
	(via
		(at 332.697328 -39.992046)
		(size 0.4572)
		(drill 0.2032)
		(layers "F.Cu" "B.Cu")
		(net "SPI_PCH_CLK")
	)
	(via
		(at 334.099662 -37.09162)
		(size 0.6604)
		(drill 0.3302)
		(layers "F.Cu" "B.Cu")
		(net "SPI_PCH_CLK")
	)
	(segment
		(start 333.208376 -38.601142)
		(end 334.099662 -37.709856)
		(width 0.12954)
		(layer "B.Cu")
		(net "SPI_PCH_CLK")
	)
	(segment
		(start 333.208376 -38.718998)
		(end 333.208376 -38.601142)
		(width 0.12954)
		(layer "B.Cu")
		(net "SPI_PCH_CLK")
	)
	(segment
		(start 332.697328 -39.992046)
		(end 332.697328 -39.230046)
		(width 0.12954)
		(layer "B.Cu")
		(net "SPI_PCH_CLK")
	)
	(segment
		(start 334.099662 -37.709856)
		(end 334.099662 -37.09162)
		(width 0.12954)
		(layer "B.Cu")
		(net "SPI_PCH_CLK")
	)
	(segment
		(start 334.099662 -36.318952)
		(end 335.080864 -35.33775)
		(width 0.12954)
		(layer "B.Cu")
		(net "SPI_PCH_CLK")
	)
	(segment
		(start 335.513426 -32.209232)
		(end 335.099152 -31.794958)
		(width 0.12954)
		(layer "B.Cu")
		(net "SPI_PCH_CLK")
	)
	(segment
		(start 335.513426 -33.81756)
		(end 335.513426 -32.209232)
		(width 0.12954)
		(layer "B.Cu")
		(net "SPI_PCH_CLK")
	)
	(segment
		(start 332.697328 -39.230046)
		(end 333.208376 -38.718998)
		(width 0.12954)
		(layer "B.Cu")
		(net "SPI_PCH_CLK")
	)
	(segment
		(start 335.080864 -35.33775)
		(end 335.080864 -34.250122)
		(width 0.12954)
		(layer "B.Cu")
		(net "SPI_PCH_CLK")
	)
	(segment
		(start 334.099662 -37.09162)
		(end 334.099662 -36.318952)
		(width 0.12954)
		(layer "B.Cu")
		(net "SPI_PCH_CLK")
	)
	(segment
		(start 335.080864 -34.250122)
		(end 335.513426 -33.81756)
		(width 0.12954)
		(layer "B.Cu")
		(net "SPI_PCH_CLK")
	)
	(segment
		(start 143.990822 -370.550948)
		(end 141.78788 -370.550948)
		(width 0.12954)
		(layer "F.Cu")
		(net "SMB_VR_3V3AUX_SDA_R3")
	)
	(segment
		(start 166.027862 -361.973368)
		(end 163.34232 -361.973368)
		(width 0.12954)
		(layer "F.Cu")
		(net "SMB_VR_3V3AUX_SDA_R3")
	)
	(segment
		(start 137.695178 -370.25961)
		(end 137.695178 -365.85779)
		(width 0.12954)
		(layer "F.Cu")
		(net "SMB_VR_3V3AUX_SDA_R3")
	)
	(segment
		(start 144.585944 -366.864138)
		(end 142.404084 -369.045998)
		(width 0.12954)
		(layer "F.Cu")
		(net "SMB_VR_3V3AUX_SDA_R3")
	)
	(segment
		(start 166.25316 -361.74807)
		(end 166.027862 -361.973368)
		(width 0.12954)
		(layer "F.Cu")
		(net "SMB_VR_3V3AUX_SDA_R3")
	)
	(segment
		(start 141.18082 -369.943888)
		(end 141.18082 -369.526058)
		(width 0.12954)
		(layer "F.Cu")
		(net "SMB_VR_3V3AUX_SDA_R3")
	)
	(segment
		(start 144.120362 -370.421408)
		(end 143.990822 -370.550948)
		(width 0.12954)
		(layer "F.Cu")
		(net "SMB_VR_3V3AUX_SDA_R3")
	)
	(segment
		(start 138.604498 -364.94847)
		(end 143.467836 -364.94847)
		(width 0.12954)
		(layer "F.Cu")
		(net "SMB_VR_3V3AUX_SDA_R3")
	)
	(segment
		(start 116.018818 -365.14659)
		(end 118.243858 -365.14659)
		(width 0.12954)
		(layer "F.Cu")
		(net "SMB_VR_3V3AUX_SDA_R3")
	)
	(segment
		(start 356.38994 -367.894616)
		(end 355.740208 -368.544348)
		(width 0.12954)
		(layer "F.Cu")
		(net "SMB_VR_3V3AUX_SDA_R3")
	)
	(segment
		(start 365.15802 -368.828828)
		(end 365.15802 -368.453416)
		(width 0.12954)
		(layer "F.Cu")
		(net "SMB_VR_3V3AUX_SDA_R3")
	)
	(segment
		(start 143.467836 -364.94847)
		(end 144.585944 -366.066578)
		(width 0.12954)
		(layer "F.Cu")
		(net "SMB_VR_3V3AUX_SDA_R3")
	)
	(segment
		(start 119.546878 -370.67871)
		(end 120.938798 -372.07063)
		(width 0.12954)
		(layer "F.Cu")
		(net "SMB_VR_3V3AUX_SDA_R3")
	)
	(segment
		(start 102.793038 -365.55553)
		(end 102.793038 -367.62309)
		(width 0.12954)
		(layer "F.Cu")
		(net "SMB_VR_3V3AUX_SDA_R3")
	)
	(segment
		(start 101.471222 -363.873034)
		(end 101.471222 -364.233714)
		(width 0.12954)
		(layer "F.Cu")
		(net "SMB_VR_3V3AUX_SDA_R3")
	)
	(segment
		(start 144.585944 -366.066578)
		(end 144.585944 -366.864138)
		(width 0.12954)
		(layer "F.Cu")
		(net "SMB_VR_3V3AUX_SDA_R3")
	)
	(segment
		(start 355.740208 -368.544348)
		(end 352.77298 -368.544348)
		(width 0.12954)
		(layer "F.Cu")
		(net "SMB_VR_3V3AUX_SDA_R3")
	)
	(segment
		(start 144.249902 -369.962684)
		(end 144.120362 -370.092224)
		(width 0.12954)
		(layer "F.Cu")
		(net "SMB_VR_3V3AUX_SDA_R3")
	)
	(segment
		(start 163.34232 -361.973368)
		(end 154.76474 -370.550948)
		(width 0.12954)
		(layer "F.Cu")
		(net "SMB_VR_3V3AUX_SDA_R3")
	)
	(segment
		(start 120.938798 -372.07063)
		(end 135.884158 -372.07063)
		(width 0.12954)
		(layer "F.Cu")
		(net "SMB_VR_3V3AUX_SDA_R3")
	)
	(segment
		(start 102.906322 -363.873034)
		(end 101.471222 -363.873034)
		(width 0.12954)
		(layer "F.Cu")
		(net "SMB_VR_3V3AUX_SDA_R3")
	)
	(segment
		(start 144.757902 -370.092224)
		(end 144.628362 -369.962684)
		(width 0.12954)
		(layer "F.Cu")
		(net "SMB_VR_3V3AUX_SDA_R3")
	)
	(segment
		(start 351.69348 -364.372398)
		(end 351.97288 -364.092998)
		(width 0.12954)
		(layer "F.Cu")
		(net "SMB_VR_3V3AUX_SDA_R3")
	)
	(segment
		(start 142.404084 -369.045998)
		(end 141.66088 -369.045998)
		(width 0.12954)
		(layer "F.Cu")
		(net "SMB_VR_3V3AUX_SDA_R3")
	)
	(segment
		(start 351.69348 -367.464848)
		(end 351.69348 -364.372398)
		(width 0.12954)
		(layer "F.Cu")
		(net "SMB_VR_3V3AUX_SDA_R3")
	)
	(segment
		(start 141.78788 -370.550948)
		(end 141.18082 -369.943888)
		(width 0.12954)
		(layer "F.Cu")
		(net "SMB_VR_3V3AUX_SDA_R3")
	)
	(segment
		(start 144.887442 -370.550948)
		(end 144.757902 -370.421408)
		(width 0.12954)
		(layer "F.Cu")
		(net "SMB_VR_3V3AUX_SDA_R3")
	)
	(segment
		(start 352.77298 -368.544348)
		(end 351.69348 -367.464848)
		(width 0.12954)
		(layer "F.Cu")
		(net "SMB_VR_3V3AUX_SDA_R3")
	)
	(segment
		(start 154.76474 -370.550948)
		(end 144.887442 -370.550948)
		(width 0.12954)
		(layer "F.Cu")
		(net "SMB_VR_3V3AUX_SDA_R3")
	)
	(segment
		(start 102.922578 -367.75263)
		(end 113.412778 -367.75263)
		(width 0.12954)
		(layer "F.Cu")
		(net "SMB_VR_3V3AUX_SDA_R3")
	)
	(segment
		(start 144.628362 -369.962684)
		(end 144.249902 -369.962684)
		(width 0.12954)
		(layer "F.Cu")
		(net "SMB_VR_3V3AUX_SDA_R3")
	)
	(segment
		(start 144.120362 -370.092224)
		(end 144.120362 -370.421408)
		(width 0.12954)
		(layer "F.Cu")
		(net "SMB_VR_3V3AUX_SDA_R3")
	)
	(segment
		(start 118.243858 -365.14659)
		(end 119.546878 -366.44961)
		(width 0.12954)
		(layer "F.Cu")
		(net "SMB_VR_3V3AUX_SDA_R3")
	)
	(segment
		(start 365.15802 -368.453416)
		(end 364.59922 -367.894616)
		(width 0.12954)
		(layer "F.Cu")
		(net "SMB_VR_3V3AUX_SDA_R3")
	)
	(segment
		(start 119.546878 -366.44961)
		(end 119.546878 -370.67871)
		(width 0.12954)
		(layer "F.Cu")
		(net "SMB_VR_3V3AUX_SDA_R3")
	)
	(segment
		(start 364.59922 -367.894616)
		(end 356.38994 -367.894616)
		(width 0.12954)
		(layer "F.Cu")
		(net "SMB_VR_3V3AUX_SDA_R3")
	)
	(segment
		(start 365.87176 -369.542568)
		(end 365.15802 -368.828828)
		(width 0.12954)
		(layer "F.Cu")
		(net "SMB_VR_3V3AUX_SDA_R3")
	)
	(segment
		(start 135.884158 -372.07063)
		(end 137.695178 -370.25961)
		(width 0.12954)
		(layer "F.Cu")
		(net "SMB_VR_3V3AUX_SDA_R3")
	)
	(segment
		(start 141.18082 -369.526058)
		(end 141.66088 -369.045998)
		(width 0.12954)
		(layer "F.Cu")
		(net "SMB_VR_3V3AUX_SDA_R3")
	)
	(segment
		(start 101.471222 -364.233714)
		(end 102.793038 -365.55553)
		(width 0.12954)
		(layer "F.Cu")
		(net "SMB_VR_3V3AUX_SDA_R3")
	)
	(segment
		(start 102.793038 -367.62309)
		(end 102.922578 -367.75263)
		(width 0.12954)
		(layer "F.Cu")
		(net "SMB_VR_3V3AUX_SDA_R3")
	)
	(segment
		(start 144.757902 -370.421408)
		(end 144.757902 -370.092224)
		(width 0.12954)
		(layer "F.Cu")
		(net "SMB_VR_3V3AUX_SDA_R3")
	)
	(segment
		(start 113.412778 -367.75263)
		(end 116.018818 -365.14659)
		(width 0.12954)
		(layer "F.Cu")
		(net "SMB_VR_3V3AUX_SDA_R3")
	)
	(segment
		(start 137.695178 -365.85779)
		(end 138.604498 -364.94847)
		(width 0.12954)
		(layer "F.Cu")
		(net "SMB_VR_3V3AUX_SDA_R3")
	)
	(via
		(at 365.87176 -369.542568)
		(size 0.508)
		(drill 0.254)
		(layers "F.Cu" "B.Cu")
		(net "SMB_VR_3V3AUX_SDA_R3")
	)
	(via
		(at 166.25316 -361.74807)
		(size 0.508)
		(drill 0.254)
		(layers "F.Cu" "B.Cu")
		(net "SMB_VR_3V3AUX_SDA_R3")
	)
	(via
		(at 253.06528 -326.151748)
		(size 0.508)
		(drill 0.254)
		(layers "F.Cu" "B.Cu")
		(net "SMB_VR_3V3AUX_SDA_R3")
	)
	(via
		(at 191.87668 -361.406948)
		(size 0.508)
		(drill 0.254)
		(layers "F.Cu" "B.Cu")
		(net "SMB_VR_3V3AUX_SDA_R3")
	)
	(segment
		(start 170.561254 -367.929922)
		(end 167.633904 -365.002572)
		(width 0.12954)
		(layer "B.Cu")
		(net "SMB_VR_3V3AUX_SDA_R3")
	)
	(segment
		(start 167.633904 -365.002572)
		(end 167.633904 -362.592112)
		(width 0.12954)
		(layer "B.Cu")
		(net "SMB_VR_3V3AUX_SDA_R3")
	)
	(segment
		(start 190.343536 -361.635548)
		(end 189.00394 -362.975144)
		(width 0.12954)
		(layer "B.Cu")
		(net "SMB_VR_3V3AUX_SDA_R3")
	)
	(segment
		(start 361.552236 -374.516142)
		(end 355.09962 -380.968758)
		(width 0.12954)
		(layer "B.Cu")
		(net "SMB_VR_3V3AUX_SDA_R3")
	)
	(segment
		(start 253.919228 -325.900288)
		(end 253.31674 -325.900288)
		(width 0.12954)
		(layer "B.Cu")
		(net "SMB_VR_3V3AUX_SDA_R3")
	)
	(segment
		(start 253.31674 -325.900288)
		(end 253.06528 -326.151748)
		(width 0.12954)
		(layer "B.Cu")
		(net "SMB_VR_3V3AUX_SDA_R3")
	)
	(segment
		(start 273.35734 -367.581434)
		(end 273.35734 -345.67241)
		(width 0.12954)
		(layer "B.Cu")
		(net "SMB_VR_3V3AUX_SDA_R3")
	)
	(segment
		(start 361.55249 -374.516142)
		(end 361.552236 -374.516142)
		(width 0.12954)
		(layer "B.Cu")
		(net "SMB_VR_3V3AUX_SDA_R3")
	)
	(segment
		(start 189.00394 -362.975144)
		(end 189.00394 -364.049056)
		(width 0.12954)
		(layer "B.Cu")
		(net "SMB_VR_3V3AUX_SDA_R3")
	)
	(segment
		(start 166.453058 -361.947968)
		(end 166.25316 -361.74807)
		(width 0.12954)
		(layer "B.Cu")
		(net "SMB_VR_3V3AUX_SDA_R3")
	)
	(segment
		(start 365.13008 -370.284248)
		(end 365.13008 -370.938552)
		(width 0.12954)
		(layer "B.Cu")
		(net "SMB_VR_3V3AUX_SDA_R3")
	)
	(segment
		(start 273.35734 -345.67241)
		(end 257.523488 -329.838558)
		(width 0.12954)
		(layer "B.Cu")
		(net "SMB_VR_3V3AUX_SDA_R3")
	)
	(segment
		(start 191.64808 -361.635548)
		(end 190.343536 -361.635548)
		(width 0.12954)
		(layer "B.Cu")
		(net "SMB_VR_3V3AUX_SDA_R3")
	)
	(segment
		(start 257.523488 -329.838558)
		(end 257.523488 -329.504548)
		(width 0.12954)
		(layer "B.Cu")
		(net "SMB_VR_3V3AUX_SDA_R3")
	)
	(segment
		(start 355.09962 -380.968758)
		(end 286.744664 -380.968758)
		(width 0.12954)
		(layer "B.Cu")
		(net "SMB_VR_3V3AUX_SDA_R3")
	)
	(segment
		(start 257.523488 -329.504548)
		(end 253.919228 -325.900288)
		(width 0.12954)
		(layer "B.Cu")
		(net "SMB_VR_3V3AUX_SDA_R3")
	)
	(segment
		(start 167.633904 -362.592112)
		(end 166.98976 -361.947968)
		(width 0.12954)
		(layer "B.Cu")
		(net "SMB_VR_3V3AUX_SDA_R3")
	)
	(segment
		(start 191.87668 -361.406948)
		(end 191.64808 -361.635548)
		(width 0.12954)
		(layer "B.Cu")
		(net "SMB_VR_3V3AUX_SDA_R3")
	)
	(segment
		(start 286.744664 -380.968758)
		(end 273.35734 -367.581434)
		(width 0.12954)
		(layer "B.Cu")
		(net "SMB_VR_3V3AUX_SDA_R3")
	)
	(segment
		(start 185.123074 -367.929922)
		(end 170.561254 -367.929922)
		(width 0.12954)
		(layer "B.Cu")
		(net "SMB_VR_3V3AUX_SDA_R3")
	)
	(segment
		(start 365.13008 -370.938552)
		(end 361.55249 -374.516142)
		(width 0.12954)
		(layer "B.Cu")
		(net "SMB_VR_3V3AUX_SDA_R3")
	)
	(segment
		(start 365.87176 -369.542568)
		(end 365.13008 -370.284248)
		(width 0.12954)
		(layer "B.Cu")
		(net "SMB_VR_3V3AUX_SDA_R3")
	)
	(segment
		(start 166.98976 -361.947968)
		(end 166.453058 -361.947968)
		(width 0.12954)
		(layer "B.Cu")
		(net "SMB_VR_3V3AUX_SDA_R3")
	)
	(segment
		(start 189.00394 -364.049056)
		(end 185.123074 -367.929922)
		(width 0.12954)
		(layer "B.Cu")
		(net "SMB_VR_3V3AUX_SDA_R3")
	)
	(segment
		(start 253.520956 -325.923148)
		(end 253.87808 -326.280272)
		(width 0.127)
		(layer "In6.Cu")
		(net "SMB_VR_3V3AUX_SDA_R3")
	)
	(segment
		(start 194.846956 -361.483148)
		(end 194.846956 -361.250992)
		(width 0.127)
		(layer "In6.Cu")
		(net "SMB_VR_3V3AUX_SDA_R3")
	)
	(segment
		(start 194.084956 -361.610148)
		(end 193.703956 -361.610148)
		(width 0.127)
		(layer "In6.Cu")
		(net "SMB_VR_3V3AUX_SDA_R3")
	)
	(segment
		(start 193.576956 -361.250992)
		(end 193.449956 -361.123992)
		(width 0.127)
		(layer "In6.Cu")
		(net "SMB_VR_3V3AUX_SDA_R3")
	)
	(segment
		(start 192.941956 -361.483148)
		(end 192.814956 -361.610148)
		(width 0.127)
		(layer "In6.Cu")
		(net "SMB_VR_3V3AUX_SDA_R3")
	)
	(segment
		(start 194.211956 -361.483148)
		(end 194.084956 -361.610148)
		(width 0.127)
		(layer "In6.Cu")
		(net "SMB_VR_3V3AUX_SDA_R3")
	)
	(segment
		(start 253.29388 -325.923148)
		(end 253.520956 -325.923148)
		(width 0.127)
		(layer "In6.Cu")
		(net "SMB_VR_3V3AUX_SDA_R3")
	)
	(segment
		(start 192.814956 -361.610148)
		(end 192.07988 -361.610148)
		(width 0.127)
		(layer "In6.Cu")
		(net "SMB_VR_3V3AUX_SDA_R3")
	)
	(segment
		(start 193.449956 -361.123992)
		(end 193.068956 -361.123992)
		(width 0.127)
		(layer "In6.Cu")
		(net "SMB_VR_3V3AUX_SDA_R3")
	)
	(segment
		(start 203.432156 -361.610148)
		(end 194.973956 -361.610148)
		(width 0.127)
		(layer "In6.Cu")
		(net "SMB_VR_3V3AUX_SDA_R3")
	)
	(segment
		(start 253.87808 -326.280272)
		(end 253.87808 -337.285584)
		(width 0.127)
		(layer "In6.Cu")
		(net "SMB_VR_3V3AUX_SDA_R3")
	)
	(segment
		(start 253.87808 -337.285584)
		(end 247.231916 -343.931748)
		(width 0.127)
		(layer "In6.Cu")
		(net "SMB_VR_3V3AUX_SDA_R3")
	)
	(segment
		(start 212.195156 -352.847148)
		(end 203.432156 -361.610148)
		(width 0.127)
		(layer "In6.Cu")
		(net "SMB_VR_3V3AUX_SDA_R3")
	)
	(segment
		(start 224.590356 -352.847148)
		(end 212.195156 -352.847148)
		(width 0.127)
		(layer "In6.Cu")
		(net "SMB_VR_3V3AUX_SDA_R3")
	)
	(segment
		(start 192.941956 -361.250992)
		(end 192.941956 -361.483148)
		(width 0.127)
		(layer "In6.Cu")
		(net "SMB_VR_3V3AUX_SDA_R3")
	)
	(segment
		(start 193.068956 -361.123992)
		(end 192.941956 -361.250992)
		(width 0.127)
		(layer "In6.Cu")
		(net "SMB_VR_3V3AUX_SDA_R3")
	)
	(segment
		(start 247.231916 -343.931748)
		(end 233.505756 -343.931748)
		(width 0.127)
		(layer "In6.Cu")
		(net "SMB_VR_3V3AUX_SDA_R3")
	)
	(segment
		(start 193.703956 -361.610148)
		(end 193.576956 -361.483148)
		(width 0.127)
		(layer "In6.Cu")
		(net "SMB_VR_3V3AUX_SDA_R3")
	)
	(segment
		(start 193.576956 -361.483148)
		(end 193.576956 -361.250992)
		(width 0.127)
		(layer "In6.Cu")
		(net "SMB_VR_3V3AUX_SDA_R3")
	)
	(segment
		(start 194.973956 -361.610148)
		(end 194.846956 -361.483148)
		(width 0.127)
		(layer "In6.Cu")
		(net "SMB_VR_3V3AUX_SDA_R3")
	)
	(segment
		(start 194.338956 -361.123992)
		(end 194.211956 -361.250992)
		(width 0.127)
		(layer "In6.Cu")
		(net "SMB_VR_3V3AUX_SDA_R3")
	)
	(segment
		(start 253.06528 -326.151748)
		(end 253.29388 -325.923148)
		(width 0.127)
		(layer "In6.Cu")
		(net "SMB_VR_3V3AUX_SDA_R3")
	)
	(segment
		(start 192.07988 -361.610148)
		(end 191.87668 -361.406948)
		(width 0.127)
		(layer "In6.Cu")
		(net "SMB_VR_3V3AUX_SDA_R3")
	)
	(segment
		(start 233.505756 -343.931748)
		(end 224.590356 -352.847148)
		(width 0.127)
		(layer "In6.Cu")
		(net "SMB_VR_3V3AUX_SDA_R3")
	)
	(segment
		(start 194.211956 -361.250992)
		(end 194.211956 -361.483148)
		(width 0.127)
		(layer "In6.Cu")
		(net "SMB_VR_3V3AUX_SDA_R3")
	)
	(segment
		(start 194.846956 -361.250992)
		(end 194.719956 -361.123992)
		(width 0.127)
		(layer "In6.Cu")
		(net "SMB_VR_3V3AUX_SDA_R3")
	)
	(segment
		(start 194.719956 -361.123992)
		(end 194.338956 -361.123992)
		(width 0.127)
		(layer "In6.Cu")
		(net "SMB_VR_3V3AUX_SDA_R3")
	)
	(segment
		(start 33.100518 -121.980452)
		(end 33.739582 -121.980452)
		(width 0.12954)
		(layer "F.Cu")
		(net "SMB_VR_3V3AUX_SDA_R2")
	)
	(segment
		(start 434.080158 -118.168166)
		(end 434.080158 -116.469668)
		(width 0.12954)
		(layer "F.Cu")
		(net "SMB_VR_3V3AUX_SDA_R2")
	)
	(segment
		(start 431.686462 -130.329178)
		(end 431.000154 -130.329178)
		(width 0.12954)
		(layer "F.Cu")
		(net "SMB_VR_3V3AUX_SDA_R2")
	)
	(via
		(at 33.739582 -121.980452)
		(size 0.508)
		(drill 0.254)
		(layers "F.Cu" "B.Cu")
		(net "SMB_VR_3V3AUX_SDA_R2")
	)
	(via
		(at 434.080158 -116.469668)
		(size 0.508)
		(drill 0.254)
		(layers "F.Cu" "B.Cu")
		(net "SMB_VR_3V3AUX_SDA_R2")
	)
	(via
		(at 431.686462 -130.329178)
		(size 0.508)
		(drill 0.254)
		(layers "F.Cu" "B.Cu")
		(net "SMB_VR_3V3AUX_SDA_R2")
	)
	(segment
		(start 442.5696 -123.471432)
		(end 442.97219 -123.471432)
		(width 0.127)
		(layer "In2.Cu")
		(net "SMB_VR_3V3AUX_SDA_R2")
	)
	(segment
		(start 438.658 -127.726948)
		(end 434.8226 -131.562348)
		(width 0.127)
		(layer "In2.Cu")
		(net "SMB_VR_3V3AUX_SDA_R2")
	)
	(segment
		(start 441.71108 -127.726948)
		(end 438.658 -127.726948)
		(width 0.127)
		(layer "In2.Cu")
		(net "SMB_VR_3V3AUX_SDA_R2")
	)
	(segment
		(start 443.09919 -120.822974)
		(end 443.09919 -122.709432)
		(width 0.127)
		(layer "In2.Cu")
		(net "SMB_VR_3V3AUX_SDA_R2")
	)
	(segment
		(start 442.97219 -122.836432)
		(end 442.5696 -122.836432)
		(width 0.127)
		(layer "In2.Cu")
		(net "SMB_VR_3V3AUX_SDA_R2")
	)
	(segment
		(start 434.080158 -116.469668)
		(end 434.495702 -116.885212)
		(width 0.127)
		(layer "In2.Cu")
		(net "SMB_VR_3V3AUX_SDA_R2")
	)
	(segment
		(start 442.4426 -122.963432)
		(end 442.4426 -123.344432)
		(width 0.127)
		(layer "In2.Cu")
		(net "SMB_VR_3V3AUX_SDA_R2")
	)
	(segment
		(start 436.83301 -117.814852)
		(end 440.091068 -117.814852)
		(width 0.127)
		(layer "In2.Cu")
		(net "SMB_VR_3V3AUX_SDA_R2")
	)
	(segment
		(start 434.8226 -131.562348)
		(end 432.919632 -131.562348)
		(width 0.127)
		(layer "In2.Cu")
		(net "SMB_VR_3V3AUX_SDA_R2")
	)
	(segment
		(start 432.919632 -131.562348)
		(end 431.686462 -130.329178)
		(width 0.127)
		(layer "In2.Cu")
		(net "SMB_VR_3V3AUX_SDA_R2")
	)
	(segment
		(start 442.97219 -123.471432)
		(end 443.09919 -123.598432)
		(width 0.127)
		(layer "In2.Cu")
		(net "SMB_VR_3V3AUX_SDA_R2")
	)
	(segment
		(start 442.4426 -123.344432)
		(end 442.5696 -123.471432)
		(width 0.127)
		(layer "In2.Cu")
		(net "SMB_VR_3V3AUX_SDA_R2")
	)
	(segment
		(start 443.09919 -126.338838)
		(end 441.71108 -127.726948)
		(width 0.127)
		(layer "In2.Cu")
		(net "SMB_VR_3V3AUX_SDA_R2")
	)
	(segment
		(start 443.09919 -122.709432)
		(end 442.97219 -122.836432)
		(width 0.127)
		(layer "In2.Cu")
		(net "SMB_VR_3V3AUX_SDA_R2")
	)
	(segment
		(start 434.495702 -116.885212)
		(end 435.90337 -116.885212)
		(width 0.127)
		(layer "In2.Cu")
		(net "SMB_VR_3V3AUX_SDA_R2")
	)
	(segment
		(start 443.09919 -123.598432)
		(end 443.09919 -126.338838)
		(width 0.127)
		(layer "In2.Cu")
		(net "SMB_VR_3V3AUX_SDA_R2")
	)
	(segment
		(start 442.5696 -122.836432)
		(end 442.4426 -122.963432)
		(width 0.127)
		(layer "In2.Cu")
		(net "SMB_VR_3V3AUX_SDA_R2")
	)
	(segment
		(start 435.90337 -116.885212)
		(end 436.83301 -117.814852)
		(width 0.127)
		(layer "In2.Cu")
		(net "SMB_VR_3V3AUX_SDA_R2")
	)
	(segment
		(start 440.091068 -117.814852)
		(end 443.09919 -120.822974)
		(width 0.127)
		(layer "In2.Cu")
		(net "SMB_VR_3V3AUX_SDA_R2")
	)
	(segment
		(start 193.264282 -126.964948)
		(end 168.394888 -126.964948)
		(width 0.127)
		(layer "In13.Cu")
		(net "SMB_VR_3V3AUX_SDA_R2")
	)
	(segment
		(start 105.292144 -122.831352)
		(end 49.054004 -122.831352)
		(width 0.127)
		(layer "In13.Cu")
		(net "SMB_VR_3V3AUX_SDA_R2")
	)
	(segment
		(start 204.035406 -124.203968)
		(end 201.699368 -126.540006)
		(width 0.127)
		(layer "In13.Cu")
		(net "SMB_VR_3V3AUX_SDA_R2")
	)
	(segment
		(start 417.22929 -124.303028)
		(end 252.27026 -124.303028)
		(width 0.127)
		(layer "In13.Cu")
		(net "SMB_VR_3V3AUX_SDA_R2")
	)
	(segment
		(start 132.480812 -118.709948)
		(end 131.468876 -117.698012)
		(width 0.127)
		(layer "In13.Cu")
		(net "SMB_VR_3V3AUX_SDA_R2")
	)
	(segment
		(start 148.140674 -127.107188)
		(end 139.743434 -118.709948)
		(width 0.127)
		(layer "In13.Cu")
		(net "SMB_VR_3V3AUX_SDA_R2")
	)
	(segment
		(start 233.12628 -117.744748)
		(end 223.4946 -117.744748)
		(width 0.127)
		(layer "In13.Cu")
		(net "SMB_VR_3V3AUX_SDA_R2")
	)
	(segment
		(start 233.90352 -118.521988)
		(end 233.12628 -117.744748)
		(width 0.127)
		(layer "In13.Cu")
		(net "SMB_VR_3V3AUX_SDA_R2")
	)
	(segment
		(start 429.206152 -115.80876)
		(end 425.723558 -115.80876)
		(width 0.127)
		(layer "In13.Cu")
		(net "SMB_VR_3V3AUX_SDA_R2")
	)
	(segment
		(start 150.397718 -126.05004)
		(end 149.34057 -127.107188)
		(width 0.127)
		(layer "In13.Cu")
		(net "SMB_VR_3V3AUX_SDA_R2")
	)
	(segment
		(start 139.743434 -118.709948)
		(end 132.480812 -118.709948)
		(width 0.127)
		(layer "In13.Cu")
		(net "SMB_VR_3V3AUX_SDA_R2")
	)
	(segment
		(start 193.689224 -126.540006)
		(end 193.264282 -126.964948)
		(width 0.127)
		(layer "In13.Cu")
		(net "SMB_VR_3V3AUX_SDA_R2")
	)
	(segment
		(start 201.699368 -126.540006)
		(end 193.689224 -126.540006)
		(width 0.127)
		(layer "In13.Cu")
		(net "SMB_VR_3V3AUX_SDA_R2")
	)
	(segment
		(start 246.48922 -118.521988)
		(end 233.90352 -118.521988)
		(width 0.127)
		(layer "In13.Cu")
		(net "SMB_VR_3V3AUX_SDA_R2")
	)
	(segment
		(start 223.4946 -117.744748)
		(end 217.03538 -124.203968)
		(width 0.127)
		(layer "In13.Cu")
		(net "SMB_VR_3V3AUX_SDA_R2")
	)
	(segment
		(start 425.723558 -115.80876)
		(end 417.22929 -124.303028)
		(width 0.127)
		(layer "In13.Cu")
		(net "SMB_VR_3V3AUX_SDA_R2")
	)
	(segment
		(start 167.47998 -126.05004)
		(end 150.397718 -126.05004)
		(width 0.127)
		(layer "In13.Cu")
		(net "SMB_VR_3V3AUX_SDA_R2")
	)
	(segment
		(start 49.054004 -122.831352)
		(end 47.51578 -121.293128)
		(width 0.127)
		(layer "In13.Cu")
		(net "SMB_VR_3V3AUX_SDA_R2")
	)
	(segment
		(start 252.27026 -124.303028)
		(end 246.48922 -118.521988)
		(width 0.127)
		(layer "In13.Cu")
		(net "SMB_VR_3V3AUX_SDA_R2")
	)
	(segment
		(start 429.86706 -116.469668)
		(end 429.206152 -115.80876)
		(width 0.127)
		(layer "In13.Cu")
		(net "SMB_VR_3V3AUX_SDA_R2")
	)
	(segment
		(start 131.468876 -117.698012)
		(end 110.425484 -117.698012)
		(width 0.127)
		(layer "In13.Cu")
		(net "SMB_VR_3V3AUX_SDA_R2")
	)
	(segment
		(start 434.080158 -116.469668)
		(end 429.86706 -116.469668)
		(width 0.127)
		(layer "In13.Cu")
		(net "SMB_VR_3V3AUX_SDA_R2")
	)
	(segment
		(start 149.34057 -127.107188)
		(end 148.140674 -127.107188)
		(width 0.127)
		(layer "In13.Cu")
		(net "SMB_VR_3V3AUX_SDA_R2")
	)
	(segment
		(start 168.394888 -126.964948)
		(end 167.47998 -126.05004)
		(width 0.127)
		(layer "In13.Cu")
		(net "SMB_VR_3V3AUX_SDA_R2")
	)
	(segment
		(start 34.426906 -121.293128)
		(end 33.739582 -121.980452)
		(width 0.127)
		(layer "In13.Cu")
		(net "SMB_VR_3V3AUX_SDA_R2")
	)
	(segment
		(start 217.03538 -124.203968)
		(end 204.035406 -124.203968)
		(width 0.127)
		(layer "In13.Cu")
		(net "SMB_VR_3V3AUX_SDA_R2")
	)
	(segment
		(start 110.425484 -117.698012)
		(end 105.292144 -122.831352)
		(width 0.127)
		(layer "In13.Cu")
		(net "SMB_VR_3V3AUX_SDA_R2")
	)
	(segment
		(start 47.51578 -121.293128)
		(end 34.426906 -121.293128)
		(width 0.127)
		(layer "In13.Cu")
		(net "SMB_VR_3V3AUX_SDA_R2")
	)
	(segment
		(start 21.16328 -113.083848)
		(end 21.847302 -112.399826)
		(width 0.12954)
		(layer "F.Cu")
		(net "SMB_VR_3V3AUX_SDA_R1")
	)
	(segment
		(start 23.209504 -113.199926)
		(end 22.409404 -112.399826)
		(width 0.12954)
		(layer "F.Cu")
		(net "SMB_VR_3V3AUX_SDA_R1")
	)
	(segment
		(start 21.847302 -112.399826)
		(end 22.409404 -112.399826)
		(width 0.12954)
		(layer "F.Cu")
		(net "SMB_VR_3V3AUX_SDA_R1")
	)
	(segment
		(start 23.209504 -113.415826)
		(end 23.209504 -113.199926)
		(width 0.12954)
		(layer "F.Cu")
		(net "SMB_VR_3V3AUX_SDA_R1")
	)
	(segment
		(start 30.49524 -122.780552)
		(end 29.927296 -122.780552)
		(width 0.12954)
		(layer "F.Cu")
		(net "SMB_VR_3V3AUX_SDA_R1")
	)
	(segment
		(start 29.927296 -122.780552)
		(end 29.507434 -123.200414)
		(width 0.12954)
		(layer "F.Cu")
		(net "SMB_VR_3V3AUX_SDA_R1")
	)
	(via
		(at 29.507434 -123.200414)
		(size 0.508)
		(drill 0.254)
		(layers "F.Cu" "B.Cu")
		(net "SMB_VR_3V3AUX_SDA_R1")
	)
	(via
		(at 28.132024 -118.355872)
		(size 0.6604)
		(drill 0.3302)
		(layers "F.Cu" "B.Cu")
		(net "SMB_VR_3V3AUX_SDA_R1")
	)
	(via
		(at 21.16328 -113.083848)
		(size 0.508)
		(drill 0.254)
		(layers "F.Cu" "B.Cu")
		(net "SMB_VR_3V3AUX_SDA_R1")
	)
	(segment
		(start 22.003766 -110.600236)
		(end 20.59686 -110.600236)
		(width 0.12954)
		(layer "B.Cu")
		(net "SMB_VR_3V3AUX_SDA_R1")
	)
	(segment
		(start 20.59686 -110.600236)
		(end 19.493484 -111.703612)
		(width 0.12954)
		(layer "B.Cu")
		(net "SMB_VR_3V3AUX_SDA_R1")
	)
	(segment
		(start 21.16328 -113.083848)
		(end 22.638258 -111.60887)
		(width 0.12954)
		(layer "B.Cu")
		(net "SMB_VR_3V3AUX_SDA_R1")
	)
	(segment
		(start 19.493484 -114.84864)
		(end 21.534882 -116.890038)
		(width 0.12954)
		(layer "B.Cu")
		(net "SMB_VR_3V3AUX_SDA_R1")
	)
	(segment
		(start 21.534882 -116.890038)
		(end 26.66619 -116.890038)
		(width 0.12954)
		(layer "B.Cu")
		(net "SMB_VR_3V3AUX_SDA_R1")
	)
	(segment
		(start 19.493484 -111.703612)
		(end 19.493484 -114.84864)
		(width 0.12954)
		(layer "B.Cu")
		(net "SMB_VR_3V3AUX_SDA_R1")
	)
	(segment
		(start 22.638258 -111.234728)
		(end 22.003766 -110.600236)
		(width 0.12954)
		(layer "B.Cu")
		(net "SMB_VR_3V3AUX_SDA_R1")
	)
	(segment
		(start 28.132024 -118.355872)
		(end 29.507434 -119.731282)
		(width 0.12954)
		(layer "B.Cu")
		(net "SMB_VR_3V3AUX_SDA_R1")
	)
	(segment
		(start 26.66619 -116.890038)
		(end 28.132024 -118.355872)
		(width 0.12954)
		(layer "B.Cu")
		(net "SMB_VR_3V3AUX_SDA_R1")
	)
	(segment
		(start 22.638258 -111.60887)
		(end 22.638258 -111.234728)
		(width 0.12954)
		(layer "B.Cu")
		(net "SMB_VR_3V3AUX_SDA_R1")
	)
	(segment
		(start 29.507434 -119.731282)
		(end 29.507434 -123.200414)
		(width 0.12954)
		(layer "B.Cu")
		(net "SMB_VR_3V3AUX_SDA_R1")
	)
	(segment
		(start 175.866806 -13.599922)
		(end 175.86706 -13.600176)
		(width 0.12954)
		(layer "F.Cu")
		(net "SMB_VR_3V3AUX_SDA_R0")
	)
	(segment
		(start 175.866806 -11.795506)
		(end 175.866806 -13.599922)
		(width 0.12954)
		(layer "F.Cu")
		(net "SMB_VR_3V3AUX_SDA_R0")
	)
	(via
		(at 175.866806 -11.795506)
		(size 0.508)
		(drill 0.254)
		(layers "F.Cu" "B.Cu")
		(net "SMB_VR_3V3AUX_SDA_R0")
	)
	(segment
		(start 180.01996 -10.973308)
		(end 180.01996 -13.071856)
		(width 0.12954)
		(layer "B.Cu")
		(net "SMB_VR_3V3AUX_SDA_R0")
	)
	(segment
		(start 175.866806 -11.795506)
		(end 176.42586 -11.236452)
		(width 0.12954)
		(layer "B.Cu")
		(net "SMB_VR_3V3AUX_SDA_R0")
	)
	(segment
		(start 178.84902 -9.802368)
		(end 180.01996 -10.973308)
		(width 0.12954)
		(layer "B.Cu")
		(net "SMB_VR_3V3AUX_SDA_R0")
	)
	(segment
		(start 177.08626 -9.802368)
		(end 178.84902 -9.802368)
		(width 0.12954)
		(layer "B.Cu")
		(net "SMB_VR_3V3AUX_SDA_R0")
	)
	(segment
		(start 176.42586 -10.462768)
		(end 177.08626 -9.802368)
		(width 0.12954)
		(layer "B.Cu")
		(net "SMB_VR_3V3AUX_SDA_R0")
	)
	(segment
		(start 176.42586 -11.236452)
		(end 176.42586 -10.462768)
		(width 0.12954)
		(layer "B.Cu")
		(net "SMB_VR_3V3AUX_SDA_R0")
	)
	(segment
		(start 180.01996 -13.071856)
		(end 179.729638 -13.362178)
		(width 0.12954)
		(layer "B.Cu")
		(net "SMB_VR_3V3AUX_SDA_R0")
	)
	(segment
		(start 31.53918 -122.780552)
		(end 33.100518 -122.780552)
		(width 0.12954)
		(layer "F.Cu")
		(net "SMB_VR_3V3AUX_SDA_R")
	)
	(segment
		(start 33.34893 -124.269754)
		(end 33.34893 -123.906788)
		(width 0.12954)
		(layer "F.Cu")
		(net "SMB_VR_3V3AUX_SDA_R")
	)
	(segment
		(start 33.34893 -123.906788)
		(end 33.100518 -123.658376)
		(width 0.12954)
		(layer "F.Cu")
		(net "SMB_VR_3V3AUX_SDA_R")
	)
	(segment
		(start 100.671122 -363.993938)
		(end 100.671122 -363.873034)
		(width 0.12954)
		(layer "F.Cu")
		(net "SMB_VR_3V3AUX_SDA_R")
	)
	(segment
		(start 33.021524 -124.59716)
		(end 33.34893 -124.269754)
		(width 0.12954)
		(layer "F.Cu")
		(net "SMB_VR_3V3AUX_SDA_R")
	)
	(segment
		(start 100.093018 -364.572042)
		(end 100.671122 -363.993938)
		(width 0.12954)
		(layer "F.Cu")
		(net "SMB_VR_3V3AUX_SDA_R")
	)
	(segment
		(start 33.100518 -123.658376)
		(end 33.100518 -122.780552)
		(width 0.12954)
		(layer "F.Cu")
		(net "SMB_VR_3V3AUX_SDA_R")
	)
	(via
		(at 100.093018 -364.572042)
		(size 0.508)
		(drill 0.254)
		(layers "F.Cu" "B.Cu")
		(net "SMB_VR_3V3AUX_SDA_R")
	)
	(via
		(at 18.937986 -169.624756)
		(size 0.508)
		(drill 0.254)
		(layers "F.Cu" "B.Cu")
		(net "SMB_VR_3V3AUX_SDA_R")
	)
	(via
		(at 30.53588 -336.464148)
		(size 0.508)
		(drill 0.254)
		(layers "F.Cu" "B.Cu")
		(net "SMB_VR_3V3AUX_SDA_R")
	)
	(via
		(at 33.34893 -123.906788)
		(size 0.508)
		(drill 0.254)
		(layers "F.Cu" "B.Cu")
		(net "SMB_VR_3V3AUX_SDA_R")
	)
	(segment
		(start 31.035244 -336.995008)
		(end 30.53588 -336.495644)
		(width 0.12954)
		(layer "B.Cu")
		(net "SMB_VR_3V3AUX_SDA_R")
	)
	(segment
		(start 38.906196 -332.869032)
		(end 34.78022 -336.995008)
		(width 0.12954)
		(layer "B.Cu")
		(net "SMB_VR_3V3AUX_SDA_R")
	)
	(segment
		(start 30.53588 -336.495644)
		(end 30.53588 -336.464148)
		(width 0.12954)
		(layer "B.Cu")
		(net "SMB_VR_3V3AUX_SDA_R")
	)
	(segment
		(start 78.050644 -365.86033)
		(end 65.368678 -353.178364)
		(width 0.12954)
		(layer "B.Cu")
		(net "SMB_VR_3V3AUX_SDA_R")
	)
	(segment
		(start 65.368678 -353.178364)
		(end 65.368678 -334.999584)
		(width 0.12954)
		(layer "B.Cu")
		(net "SMB_VR_3V3AUX_SDA_R")
	)
	(segment
		(start 34.78022 -336.995008)
		(end 31.035244 -336.995008)
		(width 0.12954)
		(layer "B.Cu")
		(net "SMB_VR_3V3AUX_SDA_R")
	)
	(segment
		(start 18.937986 -169.624756)
		(end 21.495004 -172.181774)
		(width 0.12954)
		(layer "B.Cu")
		(net "SMB_VR_3V3AUX_SDA_R")
	)
	(segment
		(start 63.238126 -332.869032)
		(end 38.906196 -332.869032)
		(width 0.12954)
		(layer "B.Cu")
		(net "SMB_VR_3V3AUX_SDA_R")
	)
	(segment
		(start 98.80473 -365.86033)
		(end 78.050644 -365.86033)
		(width 0.12954)
		(layer "B.Cu")
		(net "SMB_VR_3V3AUX_SDA_R")
	)
	(segment
		(start 65.368678 -334.999584)
		(end 63.238126 -332.869032)
		(width 0.12954)
		(layer "B.Cu")
		(net "SMB_VR_3V3AUX_SDA_R")
	)
	(segment
		(start 100.093018 -364.572042)
		(end 98.80473 -365.86033)
		(width 0.12954)
		(layer "B.Cu")
		(net "SMB_VR_3V3AUX_SDA_R")
	)
	(segment
		(start 21.495004 -172.181774)
		(end 22.588982 -172.181774)
		(width 0.12954)
		(layer "B.Cu")
		(net "SMB_VR_3V3AUX_SDA_R")
	)
	(segment
		(start 17.709896 -173.74108)
		(end 17.46631 -173.497494)
		(width 0.127)
		(layer "In2.Cu")
		(net "SMB_VR_3V3AUX_SDA_R")
	)
	(segment
		(start 35.240722 -140.977112)
		(end 35.367722 -141.104112)
		(width 0.127)
		(layer "In2.Cu")
		(net "SMB_VR_3V3AUX_SDA_R")
	)
	(segment
		(start 19.46148 -253.634748)
		(end 19.46148 -256.301748)
		(width 0.127)
		(layer "In2.Cu")
		(net "SMB_VR_3V3AUX_SDA_R")
	)
	(segment
		(start 18.01368 -193.929)
		(end 18.01368 -195.40347)
		(width 0.127)
		(layer "In2.Cu")
		(net "SMB_VR_3V3AUX_SDA_R")
	)
	(segment
		(start 17.889728 -173.74108)
		(end 17.709896 -173.74108)
		(width 0.127)
		(layer "In2.Cu")
		(net "SMB_VR_3V3AUX_SDA_R")
	)
	(segment
		(start 18.158968 -173.47184)
		(end 17.889728 -173.74108)
		(width 0.127)
		(layer "In2.Cu")
		(net "SMB_VR_3V3AUX_SDA_R")
	)
	(segment
		(start 16.811752 -174.639224)
		(end 16.568166 -174.395638)
		(width 0.127)
		(layer "In2.Cu")
		(net "SMB_VR_3V3AUX_SDA_R")
	)
	(segment
		(start 29.37891 -328.780648)
		(end 30.53588 -329.937618)
		(width 0.127)
		(layer "In2.Cu")
		(net "SMB_VR_3V3AUX_SDA_R")
	)
	(segment
		(start 16.36268 -175.268128)
		(end 14.48308 -177.147728)
		(width 0.127)
		(layer "In2.Cu")
		(net "SMB_VR_3V3AUX_SDA_R")
	)
	(segment
		(start 18.364454 -172.59935)
		(end 18.184622 -172.59935)
		(width 0.127)
		(layer "In2.Cu")
		(net "SMB_VR_3V3AUX_SDA_R")
	)
	(segment
		(start 13.2842 -189.19952)
		(end 18.01368 -193.929)
		(width 0.127)
		(layer "In2.Cu")
		(net "SMB_VR_3V3AUX_SDA_R")
	)
	(segment
		(start 17.017238 -173.766734)
		(end 17.017238 -173.946566)
		(width 0.127)
		(layer "In2.Cu")
		(net "SMB_VR_3V3AUX_SDA_R")
	)
	(segment
		(start 17.915382 -173.048422)
		(end 18.158968 -173.292008)
		(width 0.127)
		(layer "In2.Cu")
		(net "SMB_VR_3V3AUX_SDA_R")
	)
	(segment
		(start 16.991584 -174.639224)
		(end 16.811752 -174.639224)
		(width 0.127)
		(layer "In2.Cu")
		(net "SMB_VR_3V3AUX_SDA_R")
	)
	(segment
		(start 17.915382 -172.86859)
		(end 17.915382 -173.048422)
		(width 0.127)
		(layer "In2.Cu")
		(net "SMB_VR_3V3AUX_SDA_R")
	)
	(segment
		(start 16.119094 -174.84471)
		(end 16.36268 -175.088296)
		(width 0.127)
		(layer "In2.Cu")
		(net "SMB_VR_3V3AUX_SDA_R")
	)
	(segment
		(start 14.48308 -177.147728)
		(end 14.48308 -184.52592)
		(width 0.127)
		(layer "In2.Cu")
		(net "SMB_VR_3V3AUX_SDA_R")
	)
	(segment
		(start 18.787872 -172.842936)
		(end 18.60804 -172.842936)
		(width 0.127)
		(layer "In2.Cu")
		(net "SMB_VR_3V3AUX_SDA_R")
	)
	(segment
		(start 19.76882 -154.109928)
		(end 19.76882 -164.574728)
		(width 0.127)
		(layer "In2.Cu")
		(net "SMB_VR_3V3AUX_SDA_R")
	)
	(segment
		(start 34.813494 -140.469112)
		(end 34.813494 -140.850112)
		(width 0.127)
		(layer "In2.Cu")
		(net "SMB_VR_3V3AUX_SDA_R")
	)
	(segment
		(start 17.286478 -173.497494)
		(end 17.017238 -173.766734)
		(width 0.127)
		(layer "In2.Cu")
		(net "SMB_VR_3V3AUX_SDA_R")
	)
	(segment
		(start 19.46148 -256.301748)
		(end 17.803114 -257.960114)
		(width 0.127)
		(layer "In2.Cu")
		(net "SMB_VR_3V3AUX_SDA_R")
	)
	(segment
		(start 18.937986 -169.624756)
		(end 18.937986 -172.692822)
		(width 0.127)
		(layer "In2.Cu")
		(net "SMB_VR_3V3AUX_SDA_R")
	)
	(segment
		(start 17.803114 -257.960114)
		(end 17.803114 -323.332602)
		(width 0.127)
		(layer "In2.Cu")
		(net "SMB_VR_3V3AUX_SDA_R")
	)
	(segment
		(start 16.36268 -175.088296)
		(end 16.36268 -175.268128)
		(width 0.127)
		(layer "In2.Cu")
		(net "SMB_VR_3V3AUX_SDA_R")
	)
	(segment
		(start 34.23412 -147.084288)
		(end 26.79446 -147.084288)
		(width 0.127)
		(layer "In2.Cu")
		(net "SMB_VR_3V3AUX_SDA_R")
	)
	(segment
		(start 16.388334 -174.395638)
		(end 16.119094 -174.664878)
		(width 0.127)
		(layer "In2.Cu")
		(net "SMB_VR_3V3AUX_SDA_R")
	)
	(segment
		(start 13.2842 -185.7248)
		(end 13.2842 -189.19952)
		(width 0.127)
		(layer "In2.Cu")
		(net "SMB_VR_3V3AUX_SDA_R")
	)
	(segment
		(start 17.017238 -173.946566)
		(end 17.260824 -174.190152)
		(width 0.127)
		(layer "In2.Cu")
		(net "SMB_VR_3V3AUX_SDA_R")
	)
	(segment
		(start 18.937986 -172.692822)
		(end 18.787872 -172.842936)
		(width 0.127)
		(layer "In2.Cu")
		(net "SMB_VR_3V3AUX_SDA_R")
	)
	(segment
		(start 26.79446 -147.084288)
		(end 19.76882 -154.109928)
		(width 0.127)
		(layer "In2.Cu")
		(net "SMB_VR_3V3AUX_SDA_R")
	)
	(segment
		(start 17.803114 -195.614036)
		(end 17.803114 -251.976382)
		(width 0.127)
		(layer "In2.Cu")
		(net "SMB_VR_3V3AUX_SDA_R")
	)
	(segment
		(start 19.40814 -169.154602)
		(end 18.937986 -169.624756)
		(width 0.127)
		(layer "In2.Cu")
		(net "SMB_VR_3V3AUX_SDA_R")
	)
	(segment
		(start 19.40814 -164.935408)
		(end 19.40814 -169.154602)
		(width 0.127)
		(layer "In2.Cu")
		(net "SMB_VR_3V3AUX_SDA_R")
	)
	(segment
		(start 18.184622 -172.59935)
		(end 17.915382 -172.86859)
		(width 0.127)
		(layer "In2.Cu")
		(net "SMB_VR_3V3AUX_SDA_R")
	)
	(segment
		(start 35.367722 -141.104112)
		(end 35.367722 -145.950686)
		(width 0.127)
		(layer "In2.Cu")
		(net "SMB_VR_3V3AUX_SDA_R")
	)
	(segment
		(start 34.323528 -131.11734)
		(end 35.367722 -132.161534)
		(width 0.127)
		(layer "In2.Cu")
		(net "SMB_VR_3V3AUX_SDA_R")
	)
	(segment
		(start 17.803114 -251.976382)
		(end 19.46148 -253.634748)
		(width 0.127)
		(layer "In2.Cu")
		(net "SMB_VR_3V3AUX_SDA_R")
	)
	(segment
		(start 17.260824 -174.369984)
		(end 16.991584 -174.639224)
		(width 0.127)
		(layer "In2.Cu")
		(net "SMB_VR_3V3AUX_SDA_R")
	)
	(segment
		(start 17.803114 -323.332602)
		(end 23.25116 -328.780648)
		(width 0.127)
		(layer "In2.Cu")
		(net "SMB_VR_3V3AUX_SDA_R")
	)
	(segment
		(start 16.568166 -174.395638)
		(end 16.388334 -174.395638)
		(width 0.127)
		(layer "In2.Cu")
		(net "SMB_VR_3V3AUX_SDA_R")
	)
	(segment
		(start 14.48308 -184.52592)
		(end 13.2842 -185.7248)
		(width 0.127)
		(layer "In2.Cu")
		(net "SMB_VR_3V3AUX_SDA_R")
	)
	(segment
		(start 34.940494 -140.342112)
		(end 34.813494 -140.469112)
		(width 0.127)
		(layer "In2.Cu")
		(net "SMB_VR_3V3AUX_SDA_R")
	)
	(segment
		(start 17.260824 -174.190152)
		(end 17.260824 -174.369984)
		(width 0.127)
		(layer "In2.Cu")
		(net "SMB_VR_3V3AUX_SDA_R")
	)
	(segment
		(start 17.46631 -173.497494)
		(end 17.286478 -173.497494)
		(width 0.127)
		(layer "In2.Cu")
		(net "SMB_VR_3V3AUX_SDA_R")
	)
	(segment
		(start 35.240722 -140.342112)
		(end 34.940494 -140.342112)
		(width 0.127)
		(layer "In2.Cu")
		(net "SMB_VR_3V3AUX_SDA_R")
	)
	(segment
		(start 34.940494 -140.977112)
		(end 35.240722 -140.977112)
		(width 0.127)
		(layer "In2.Cu")
		(net "SMB_VR_3V3AUX_SDA_R")
	)
	(segment
		(start 34.323528 -124.881386)
		(end 34.323528 -131.11734)
		(width 0.127)
		(layer "In2.Cu")
		(net "SMB_VR_3V3AUX_SDA_R")
	)
	(segment
		(start 35.367722 -145.950686)
		(end 34.23412 -147.084288)
		(width 0.127)
		(layer "In2.Cu")
		(net "SMB_VR_3V3AUX_SDA_R")
	)
	(segment
		(start 35.367722 -132.161534)
		(end 35.367722 -140.215112)
		(width 0.127)
		(layer "In2.Cu")
		(net "SMB_VR_3V3AUX_SDA_R")
	)
	(segment
		(start 19.76882 -164.574728)
		(end 19.40814 -164.935408)
		(width 0.127)
		(layer "In2.Cu")
		(net "SMB_VR_3V3AUX_SDA_R")
	)
	(segment
		(start 30.53588 -329.937618)
		(end 30.53588 -336.464148)
		(width 0.127)
		(layer "In2.Cu")
		(net "SMB_VR_3V3AUX_SDA_R")
	)
	(segment
		(start 18.01368 -195.40347)
		(end 17.803114 -195.614036)
		(width 0.127)
		(layer "In2.Cu")
		(net "SMB_VR_3V3AUX_SDA_R")
	)
	(segment
		(start 23.25116 -328.780648)
		(end 29.37891 -328.780648)
		(width 0.127)
		(layer "In2.Cu")
		(net "SMB_VR_3V3AUX_SDA_R")
	)
	(segment
		(start 33.34893 -123.906788)
		(end 34.323528 -124.881386)
		(width 0.127)
		(layer "In2.Cu")
		(net "SMB_VR_3V3AUX_SDA_R")
	)
	(segment
		(start 18.158968 -173.292008)
		(end 18.158968 -173.47184)
		(width 0.127)
		(layer "In2.Cu")
		(net "SMB_VR_3V3AUX_SDA_R")
	)
	(segment
		(start 18.60804 -172.842936)
		(end 18.364454 -172.59935)
		(width 0.127)
		(layer "In2.Cu")
		(net "SMB_VR_3V3AUX_SDA_R")
	)
	(segment
		(start 34.813494 -140.850112)
		(end 34.940494 -140.977112)
		(width 0.127)
		(layer "In2.Cu")
		(net "SMB_VR_3V3AUX_SDA_R")
	)
	(segment
		(start 16.119094 -174.664878)
		(end 16.119094 -174.84471)
		(width 0.127)
		(layer "In2.Cu")
		(net "SMB_VR_3V3AUX_SDA_R")
	)
	(segment
		(start 35.367722 -140.215112)
		(end 35.240722 -140.342112)
		(width 0.127)
		(layer "In2.Cu")
		(net "SMB_VR_3V3AUX_SDA_R")
	)
	(segment
		(start 38.95344 -114.074448)
		(end 38.95344 -119.045736)
		(width 0.12954)
		(layer "F.Cu")
		(net "SMB_VR_3V3AUX_SDA")
	)
	(segment
		(start 53.842666 -113.97869)
		(end 53.141626 -113.97869)
		(width 0.12954)
		(layer "F.Cu")
		(net "SMB_VR_3V3AUX_SDA")
	)
	(segment
		(start 37.411914 -120.587262)
		(end 31.915354 -120.587262)
		(width 0.12954)
		(layer "F.Cu")
		(net "SMB_VR_3V3AUX_SDA")
	)
	(segment
		(start 45.350684 -115.266724)
		(end 45.940472 -114.676936)
		(width 0.12954)
		(layer "F.Cu")
		(net "SMB_VR_3V3AUX_SDA")
	)
	(segment
		(start 31.53918 -120.963436)
		(end 31.53918 -121.980452)
		(width 0.12954)
		(layer "F.Cu")
		(net "SMB_VR_3V3AUX_SDA")
	)
	(segment
		(start 53.141626 -113.97869)
		(end 51.993546 -115.12677)
		(width 0.12954)
		(layer "F.Cu")
		(net "SMB_VR_3V3AUX_SDA")
	)
	(segment
		(start 45.940472 -114.676936)
		(end 48.234346 -114.676936)
		(width 0.12954)
		(layer "F.Cu")
		(net "SMB_VR_3V3AUX_SDA")
	)
	(segment
		(start 48.463454 -114.447828)
		(end 51.314604 -114.447828)
		(width 0.12954)
		(layer "F.Cu")
		(net "SMB_VR_3V3AUX_SDA")
	)
	(segment
		(start 51.314604 -114.447828)
		(end 51.993546 -115.12677)
		(width 0.12954)
		(layer "F.Cu")
		(net "SMB_VR_3V3AUX_SDA")
	)
	(segment
		(start 30.49524 -121.980452)
		(end 31.53918 -121.980452)
		(width 0.12954)
		(layer "F.Cu")
		(net "SMB_VR_3V3AUX_SDA")
	)
	(segment
		(start 48.234346 -114.676936)
		(end 48.463454 -114.447828)
		(width 0.12954)
		(layer "F.Cu")
		(net "SMB_VR_3V3AUX_SDA")
	)
	(segment
		(start 31.915354 -120.587262)
		(end 31.53918 -120.963436)
		(width 0.12954)
		(layer "F.Cu")
		(net "SMB_VR_3V3AUX_SDA")
	)
	(segment
		(start 38.95344 -119.045736)
		(end 37.411914 -120.587262)
		(width 0.12954)
		(layer "F.Cu")
		(net "SMB_VR_3V3AUX_SDA")
	)
	(via
		(at 38.95344 -114.074448)
		(size 0.508)
		(drill 0.254)
		(layers "F.Cu" "B.Cu")
		(net "SMB_VR_3V3AUX_SDA")
	)
	(via
		(at 45.350684 -115.266724)
		(size 0.508)
		(drill 0.254)
		(layers "F.Cu" "B.Cu")
		(net "SMB_VR_3V3AUX_SDA")
	)
	(segment
		(start 40.78097 -115.901978)
		(end 38.95344 -114.074448)
		(width 0.127)
		(layer "In4.Cu")
		(net "SMB_VR_3V3AUX_SDA")
	)
	(segment
		(start 45.350684 -115.266724)
		(end 45.350684 -115.684046)
		(width 0.127)
		(layer "In4.Cu")
		(net "SMB_VR_3V3AUX_SDA")
	)
	(segment
		(start 45.350684 -115.684046)
		(end 45.132752 -115.901978)
		(width 0.127)
		(layer "In4.Cu")
		(net "SMB_VR_3V3AUX_SDA")
	)
	(segment
		(start 45.132752 -115.901978)
		(end 40.78097 -115.901978)
		(width 0.127)
		(layer "In4.Cu")
		(net "SMB_VR_3V3AUX_SDA")
	)
	(segment
		(start 139.505944 -367.033302)
		(end 139.505944 -366.066578)
		(width 0.12954)
		(layer "F.Cu")
		(net "SMB_VR_3V3AUX_SCL_R3")
	)
	(segment
		(start 115.099338 -367.48339)
		(end 115.099338 -367.666778)
		(width 0.12954)
		(layer "F.Cu")
		(net "SMB_VR_3V3AUX_SCL_R3")
	)
	(segment
		(start 114.373152 -367.658904)
		(end 114.189764 -367.658904)
		(width 0.12954)
		(layer "F.Cu")
		(net "SMB_VR_3V3AUX_SCL_R3")
	)
	(segment
		(start 138.65225 -366.066578)
		(end 138.332718 -366.38611)
		(width 0.12954)
		(layer "F.Cu")
		(net "SMB_VR_3V3AUX_SCL_R3")
	)
	(segment
		(start 138.332718 -366.38611)
		(end 138.332718 -370.46789)
		(width 0.12954)
		(layer "F.Cu")
		(net "SMB_VR_3V3AUX_SCL_R3")
	)
	(segment
		(start 101.471222 -362.602526)
		(end 101.471222 -363.064806)
		(width 0.12954)
		(layer "F.Cu")
		(net "SMB_VR_3V3AUX_SCL_R3")
	)
	(segment
		(start 99.257358 -365.87303)
		(end 99.257358 -364.528608)
		(width 0.12954)
		(layer "F.Cu")
		(net "SMB_VR_3V3AUX_SCL_R3")
	)
	(segment
		(start 140.208 -370.023898)
		(end 140.208 -369.045998)
		(width 0.12954)
		(layer "F.Cu")
		(net "SMB_VR_3V3AUX_SCL_R3")
	)
	(segment
		(start 119.092218 -366.638078)
		(end 118.05539 -365.60125)
		(width 0.12954)
		(layer "F.Cu")
		(net "SMB_VR_3V3AUX_SCL_R3")
	)
	(segment
		(start 116.247418 -365.60125)
		(end 114.824002 -367.024666)
		(width 0.12954)
		(layer "F.Cu")
		(net "SMB_VR_3V3AUX_SCL_R3")
	)
	(segment
		(start 114.831876 -367.93424)
		(end 114.648488 -367.93424)
		(width 0.12954)
		(layer "F.Cu")
		(net "SMB_VR_3V3AUX_SCL_R3")
	)
	(segment
		(start 118.05539 -365.60125)
		(end 116.247418 -365.60125)
		(width 0.12954)
		(layer "F.Cu")
		(net "SMB_VR_3V3AUX_SCL_R3")
	)
	(segment
		(start 114.648488 -367.93424)
		(end 114.373152 -367.658904)
		(width 0.12954)
		(layer "F.Cu")
		(net "SMB_VR_3V3AUX_SCL_R3")
	)
	(segment
		(start 139.505944 -366.066578)
		(end 138.65225 -366.066578)
		(width 0.12954)
		(layer "F.Cu")
		(net "SMB_VR_3V3AUX_SCL_R3")
	)
	(segment
		(start 114.824002 -367.208054)
		(end 115.099338 -367.48339)
		(width 0.12954)
		(layer "F.Cu")
		(net "SMB_VR_3V3AUX_SCL_R3")
	)
	(segment
		(start 100.507038 -363.27715)
		(end 99.257358 -364.52683)
		(width 0.12954)
		(layer "F.Cu")
		(net "SMB_VR_3V3AUX_SCL_R3")
	)
	(segment
		(start 101.471222 -363.064806)
		(end 101.258878 -363.27715)
		(width 0.12954)
		(layer "F.Cu")
		(net "SMB_VR_3V3AUX_SCL_R3")
	)
	(segment
		(start 99.257358 -364.52683)
		(end 99.257358 -364.528608)
		(width 0.12954)
		(layer "F.Cu")
		(net "SMB_VR_3V3AUX_SCL_R3")
	)
	(segment
		(start 113.626138 -368.22253)
		(end 101.606858 -368.22253)
		(width 0.12954)
		(layer "F.Cu")
		(net "SMB_VR_3V3AUX_SCL_R3")
	)
	(segment
		(start 102.906322 -362.602526)
		(end 101.471222 -362.602526)
		(width 0.12954)
		(layer "F.Cu")
		(net "SMB_VR_3V3AUX_SCL_R3")
	)
	(segment
		(start 120.75033 -372.52529)
		(end 119.092218 -370.867178)
		(width 0.12954)
		(layer "F.Cu")
		(net "SMB_VR_3V3AUX_SCL_R3")
	)
	(segment
		(start 115.099338 -367.666778)
		(end 114.831876 -367.93424)
		(width 0.12954)
		(layer "F.Cu")
		(net "SMB_VR_3V3AUX_SCL_R3")
	)
	(segment
		(start 101.606858 -368.22253)
		(end 99.257358 -365.87303)
		(width 0.12954)
		(layer "F.Cu")
		(net "SMB_VR_3V3AUX_SCL_R3")
	)
	(segment
		(start 114.189764 -367.658904)
		(end 113.626138 -368.22253)
		(width 0.12954)
		(layer "F.Cu")
		(net "SMB_VR_3V3AUX_SCL_R3")
	)
	(segment
		(start 114.824002 -367.024666)
		(end 114.824002 -367.208054)
		(width 0.12954)
		(layer "F.Cu")
		(net "SMB_VR_3V3AUX_SCL_R3")
	)
	(segment
		(start 139.538456 -368.86515)
		(end 139.538456 -367.065814)
		(width 0.12954)
		(layer "F.Cu")
		(net "SMB_VR_3V3AUX_SCL_R3")
	)
	(segment
		(start 119.092218 -370.867178)
		(end 119.092218 -366.638078)
		(width 0.12954)
		(layer "F.Cu")
		(net "SMB_VR_3V3AUX_SCL_R3")
	)
	(segment
		(start 139.719304 -369.045998)
		(end 139.538456 -368.86515)
		(width 0.12954)
		(layer "F.Cu")
		(net "SMB_VR_3V3AUX_SCL_R3")
	)
	(segment
		(start 139.538456 -367.065814)
		(end 139.505944 -367.033302)
		(width 0.12954)
		(layer "F.Cu")
		(net "SMB_VR_3V3AUX_SCL_R3")
	)
	(segment
		(start 140.208 -369.045998)
		(end 139.719304 -369.045998)
		(width 0.12954)
		(layer "F.Cu")
		(net "SMB_VR_3V3AUX_SCL_R3")
	)
	(segment
		(start 136.275318 -372.52529)
		(end 120.75033 -372.52529)
		(width 0.12954)
		(layer "F.Cu")
		(net "SMB_VR_3V3AUX_SCL_R3")
	)
	(segment
		(start 101.258878 -363.27715)
		(end 100.507038 -363.27715)
		(width 0.12954)
		(layer "F.Cu")
		(net "SMB_VR_3V3AUX_SCL_R3")
	)
	(segment
		(start 138.332718 -370.46789)
		(end 136.275318 -372.52529)
		(width 0.12954)
		(layer "F.Cu")
		(net "SMB_VR_3V3AUX_SCL_R3")
	)
	(via
		(at 99.257358 -364.528608)
		(size 0.508)
		(drill 0.254)
		(layers "F.Cu" "B.Cu")
		(net "SMB_VR_3V3AUX_SCL_R3")
	)
	(segment
		(start 432.238404 -131.599178)
		(end 431.000154 -131.599178)
		(width 0.12954)
		(layer "F.Cu")
		(net "SMB_VR_3V3AUX_SCL_R2")
	)
	(segment
		(start 34.370518 -121.980452)
		(end 35.062668 -121.980452)
		(width 0.12954)
		(layer "F.Cu")
		(net "SMB_VR_3V3AUX_SCL_R2")
	)
	(segment
		(start 435.350158 -118.168166)
		(end 435.350158 -116.112798)
		(width 0.12954)
		(layer "F.Cu")
		(net "SMB_VR_3V3AUX_SCL_R2")
	)
	(via
		(at 435.350158 -116.112798)
		(size 0.508)
		(drill 0.254)
		(layers "F.Cu" "B.Cu")
		(net "SMB_VR_3V3AUX_SCL_R2")
	)
	(via
		(at 432.238404 -131.599178)
		(size 0.508)
		(drill 0.254)
		(layers "F.Cu" "B.Cu")
		(net "SMB_VR_3V3AUX_SCL_R2")
	)
	(via
		(at 35.062668 -121.980452)
		(size 0.508)
		(drill 0.254)
		(layers "F.Cu" "B.Cu")
		(net "SMB_VR_3V3AUX_SCL_R2")
	)
	(segment
		(start 441.96508 -128.285748)
		(end 439.057288 -128.285748)
		(width 0.127)
		(layer "In2.Cu")
		(net "SMB_VR_3V3AUX_SCL_R2")
	)
	(segment
		(start 435.893972 -116.112798)
		(end 437.01843 -117.237256)
		(width 0.127)
		(layer "In2.Cu")
		(net "SMB_VR_3V3AUX_SCL_R2")
	)
	(segment
		(start 443.644528 -126.6063)
		(end 441.96508 -128.285748)
		(width 0.127)
		(layer "In2.Cu")
		(net "SMB_VR_3V3AUX_SCL_R2")
	)
	(segment
		(start 437.01843 -117.237256)
		(end 440.124596 -117.237256)
		(width 0.127)
		(layer "In2.Cu")
		(net "SMB_VR_3V3AUX_SCL_R2")
	)
	(segment
		(start 435.301644 -132.041392)
		(end 432.680618 -132.041392)
		(width 0.127)
		(layer "In2.Cu")
		(net "SMB_VR_3V3AUX_SCL_R2")
	)
	(segment
		(start 432.680618 -132.041392)
		(end 432.238404 -131.599178)
		(width 0.127)
		(layer "In2.Cu")
		(net "SMB_VR_3V3AUX_SCL_R2")
	)
	(segment
		(start 439.057288 -128.285748)
		(end 435.301644 -132.041392)
		(width 0.127)
		(layer "In2.Cu")
		(net "SMB_VR_3V3AUX_SCL_R2")
	)
	(segment
		(start 435.350158 -116.112798)
		(end 435.893972 -116.112798)
		(width 0.127)
		(layer "In2.Cu")
		(net "SMB_VR_3V3AUX_SCL_R2")
	)
	(segment
		(start 440.124596 -117.237256)
		(end 443.644528 -120.757188)
		(width 0.127)
		(layer "In2.Cu")
		(net "SMB_VR_3V3AUX_SCL_R2")
	)
	(segment
		(start 443.644528 -120.757188)
		(end 443.644528 -126.6063)
		(width 0.127)
		(layer "In2.Cu")
		(net "SMB_VR_3V3AUX_SCL_R2")
	)
	(segment
		(start 433.04714 -116.919248)
		(end 433.418234 -117.290342)
		(width 0.127)
		(layer "In13.Cu")
		(net "SMB_VR_3V3AUX_SCL_R2")
	)
	(segment
		(start 232.946956 -118.176548)
		(end 233.734356 -118.963948)
		(width 0.127)
		(layer "In13.Cu")
		(net "SMB_VR_3V3AUX_SCL_R2")
	)
	(segment
		(start 132.365242 -119.205248)
		(end 139.54506 -119.205248)
		(width 0.127)
		(layer "In13.Cu")
		(net "SMB_VR_3V3AUX_SCL_R2")
	)
	(segment
		(start 139.54506 -119.205248)
		(end 147.8788 -127.538988)
		(width 0.127)
		(layer "In13.Cu")
		(net "SMB_VR_3V3AUX_SCL_R2")
	)
	(segment
		(start 105.471214 -123.263152)
		(end 110.604554 -118.129812)
		(width 0.127)
		(layer "In13.Cu")
		(net "SMB_VR_3V3AUX_SCL_R2")
	)
	(segment
		(start 200.93178 -128.095248)
		(end 204.3303 -124.696728)
		(width 0.127)
		(layer "In13.Cu")
		(net "SMB_VR_3V3AUX_SCL_R2")
	)
	(segment
		(start 429.68926 -116.919248)
		(end 433.04714 -116.919248)
		(width 0.127)
		(layer "In13.Cu")
		(net "SMB_VR_3V3AUX_SCL_R2")
	)
	(segment
		(start 196.787516 -129.418588)
		(end 198.110856 -128.095248)
		(width 0.127)
		(layer "In13.Cu")
		(net "SMB_VR_3V3AUX_SCL_R2")
	)
	(segment
		(start 150.03145 -127.027178)
		(end 164.844984 -127.027178)
		(width 0.127)
		(layer "In13.Cu")
		(net "SMB_VR_3V3AUX_SCL_R2")
	)
	(segment
		(start 191.520064 -129.418588)
		(end 196.787516 -129.418588)
		(width 0.127)
		(layer "In13.Cu")
		(net "SMB_VR_3V3AUX_SCL_R2")
	)
	(segment
		(start 434.547518 -117.290342)
		(end 435.350158 -116.487702)
		(width 0.127)
		(layer "In13.Cu")
		(net "SMB_VR_3V3AUX_SCL_R2")
	)
	(segment
		(start 164.844984 -127.027178)
		(end 165.198806 -127.381)
		(width 0.127)
		(layer "In13.Cu")
		(net "SMB_VR_3V3AUX_SCL_R2")
	)
	(segment
		(start 168.215818 -127.396748)
		(end 189.498224 -127.396748)
		(width 0.127)
		(layer "In13.Cu")
		(net "SMB_VR_3V3AUX_SCL_R2")
	)
	(segment
		(start 204.3303 -124.696728)
		(end 217.3351 -124.696728)
		(width 0.127)
		(layer "In13.Cu")
		(net "SMB_VR_3V3AUX_SCL_R2")
	)
	(segment
		(start 251.96038 -124.734828)
		(end 417.40836 -124.734828)
		(width 0.127)
		(layer "In13.Cu")
		(net "SMB_VR_3V3AUX_SCL_R2")
	)
	(segment
		(start 131.289806 -118.129812)
		(end 132.365242 -119.205248)
		(width 0.127)
		(layer "In13.Cu")
		(net "SMB_VR_3V3AUX_SCL_R2")
	)
	(segment
		(start 47.588424 -121.980452)
		(end 48.871124 -123.263152)
		(width 0.127)
		(layer "In13.Cu")
		(net "SMB_VR_3V3AUX_SCL_R2")
	)
	(segment
		(start 189.498224 -127.396748)
		(end 191.520064 -129.418588)
		(width 0.127)
		(layer "In13.Cu")
		(net "SMB_VR_3V3AUX_SCL_R2")
	)
	(segment
		(start 223.85528 -118.176548)
		(end 232.946956 -118.176548)
		(width 0.127)
		(layer "In13.Cu")
		(net "SMB_VR_3V3AUX_SCL_R2")
	)
	(segment
		(start 233.734356 -118.963948)
		(end 246.1895 -118.963948)
		(width 0.127)
		(layer "In13.Cu")
		(net "SMB_VR_3V3AUX_SCL_R2")
	)
	(segment
		(start 246.1895 -118.963948)
		(end 251.96038 -124.734828)
		(width 0.127)
		(layer "In13.Cu")
		(net "SMB_VR_3V3AUX_SCL_R2")
	)
	(segment
		(start 165.198806 -127.381)
		(end 168.20007 -127.381)
		(width 0.127)
		(layer "In13.Cu")
		(net "SMB_VR_3V3AUX_SCL_R2")
	)
	(segment
		(start 149.51964 -127.538988)
		(end 150.03145 -127.027178)
		(width 0.127)
		(layer "In13.Cu")
		(net "SMB_VR_3V3AUX_SCL_R2")
	)
	(segment
		(start 435.350158 -116.487702)
		(end 435.350158 -116.112798)
		(width 0.127)
		(layer "In13.Cu")
		(net "SMB_VR_3V3AUX_SCL_R2")
	)
	(segment
		(start 198.110856 -128.095248)
		(end 200.93178 -128.095248)
		(width 0.127)
		(layer "In13.Cu")
		(net "SMB_VR_3V3AUX_SCL_R2")
	)
	(segment
		(start 417.40836 -124.734828)
		(end 425.872148 -116.27104)
		(width 0.127)
		(layer "In13.Cu")
		(net "SMB_VR_3V3AUX_SCL_R2")
	)
	(segment
		(start 168.20007 -127.381)
		(end 168.215818 -127.396748)
		(width 0.127)
		(layer "In13.Cu")
		(net "SMB_VR_3V3AUX_SCL_R2")
	)
	(segment
		(start 429.041052 -116.27104)
		(end 429.68926 -116.919248)
		(width 0.127)
		(layer "In13.Cu")
		(net "SMB_VR_3V3AUX_SCL_R2")
	)
	(segment
		(start 48.871124 -123.263152)
		(end 105.471214 -123.263152)
		(width 0.127)
		(layer "In13.Cu")
		(net "SMB_VR_3V3AUX_SCL_R2")
	)
	(segment
		(start 35.062668 -121.980452)
		(end 47.588424 -121.980452)
		(width 0.127)
		(layer "In13.Cu")
		(net "SMB_VR_3V3AUX_SCL_R2")
	)
	(segment
		(start 110.604554 -118.129812)
		(end 131.289806 -118.129812)
		(width 0.127)
		(layer "In13.Cu")
		(net "SMB_VR_3V3AUX_SCL_R2")
	)
	(segment
		(start 425.872148 -116.27104)
		(end 429.041052 -116.27104)
		(width 0.127)
		(layer "In13.Cu")
		(net "SMB_VR_3V3AUX_SCL_R2")
	)
	(segment
		(start 433.418234 -117.290342)
		(end 434.547518 -117.290342)
		(width 0.127)
		(layer "In13.Cu")
		(net "SMB_VR_3V3AUX_SCL_R2")
	)
	(segment
		(start 147.8788 -127.538988)
		(end 149.51964 -127.538988)
		(width 0.127)
		(layer "In13.Cu")
		(net "SMB_VR_3V3AUX_SCL_R2")
	)
	(segment
		(start 217.3351 -124.696728)
		(end 223.85528 -118.176548)
		(width 0.127)
		(layer "In13.Cu")
		(net "SMB_VR_3V3AUX_SCL_R2")
	)
	(segment
		(start 37.890196 -122.780552)
		(end 36.884102 -122.780552)
		(width 0.12954)
		(layer "F.Cu")
		(net "SMB_VR_3V3AUX_SCL_R1")
	)
	(segment
		(start 36.884102 -122.780552)
		(end 36.884102 -122.831098)
		(width 0.12954)
		(layer "F.Cu")
		(net "SMB_VR_3V3AUX_SCL_R1")
	)
	(segment
		(start 36.884102 -122.831098)
		(end 38.128702 -124.075698)
		(width 0.12954)
		(layer "F.Cu")
		(net "SMB_VR_3V3AUX_SCL_R1")
	)
	(segment
		(start 22.409404 -111.383826)
		(end 21.44014 -111.383826)
		(width 0.12954)
		(layer "F.Cu")
		(net "SMB_VR_3V3AUX_SCL_R1")
	)
	(via
		(at 21.44014 -111.383826)
		(size 0.508)
		(drill 0.254)
		(layers "F.Cu" "B.Cu")
		(net "SMB_VR_3V3AUX_SCL_R1")
	)
	(via
		(at 38.128702 -124.075698)
		(size 0.508)
		(drill 0.254)
		(layers "F.Cu" "B.Cu")
		(net "SMB_VR_3V3AUX_SCL_R1")
	)
	(segment
		(start 20.2311 -114.287808)
		(end 21.88718 -115.943888)
		(width 0.12954)
		(layer "B.Cu")
		(net "SMB_VR_3V3AUX_SCL_R1")
	)
	(segment
		(start 21.88718 -115.943888)
		(end 29.996892 -115.943888)
		(width 0.12954)
		(layer "B.Cu")
		(net "SMB_VR_3V3AUX_SCL_R1")
	)
	(segment
		(start 29.996892 -115.943888)
		(end 38.128702 -124.075698)
		(width 0.12954)
		(layer "B.Cu")
		(net "SMB_VR_3V3AUX_SCL_R1")
	)
	(segment
		(start 21.44014 -111.383826)
		(end 20.2311 -112.592866)
		(width 0.12954)
		(layer "B.Cu")
		(net "SMB_VR_3V3AUX_SCL_R1")
	)
	(segment
		(start 20.2311 -112.592866)
		(end 20.2311 -114.287808)
		(width 0.12954)
		(layer "B.Cu")
		(net "SMB_VR_3V3AUX_SCL_R1")
	)
	(segment
		(start 176.467008 -10.946384)
		(end 175.841406 -10.320782)
		(width 0.12954)
		(layer "F.Cu")
		(net "SMB_VR_3V3AUX_SCL_R0")
	)
	(segment
		(start 176.467008 -13.600176)
		(end 176.467008 -10.946384)
		(width 0.12954)
		(layer "F.Cu")
		(net "SMB_VR_3V3AUX_SCL_R0")
	)
	(via
		(at 175.841406 -10.320782)
		(size 0.508)
		(drill 0.254)
		(layers "F.Cu" "B.Cu")
		(net "SMB_VR_3V3AUX_SCL_R0")
	)
	(segment
		(start 180.814218 -10.9601)
		(end 180.814218 -13.372338)
		(width 0.12954)
		(layer "B.Cu")
		(net "SMB_VR_3V3AUX_SCL_R0")
	)
	(segment
		(start 177.09896 -9.063228)
		(end 178.917346 -9.063228)
		(width 0.12954)
		(layer "B.Cu")
		(net "SMB_VR_3V3AUX_SCL_R0")
	)
	(segment
		(start 178.917346 -9.063228)
		(end 180.814218 -10.9601)
		(width 0.12954)
		(layer "B.Cu")
		(net "SMB_VR_3V3AUX_SCL_R0")
	)
	(segment
		(start 175.841406 -10.320782)
		(end 177.09896 -9.063228)
		(width 0.12954)
		(layer "B.Cu")
		(net "SMB_VR_3V3AUX_SCL_R0")
	)
	(segment
		(start 34.291524 -123.37415)
		(end 34.370518 -123.295156)
		(width 0.12954)
		(layer "F.Cu")
		(net "SMB_VR_3V3AUX_SCL_R")
	)
	(segment
		(start 34.291524 -124.59716)
		(end 34.291524 -123.889262)
		(width 0.12954)
		(layer "F.Cu")
		(net "SMB_VR_3V3AUX_SCL_R")
	)
	(segment
		(start 34.291524 -123.889262)
		(end 34.291524 -123.37415)
		(width 0.12954)
		(layer "F.Cu")
		(net "SMB_VR_3V3AUX_SCL_R")
	)
	(segment
		(start 99.234498 -363.655102)
		(end 100.287074 -362.602526)
		(width 0.12954)
		(layer "F.Cu")
		(net "SMB_VR_3V3AUX_SCL_R")
	)
	(segment
		(start 35.840162 -122.780552)
		(end 34.370518 -122.780552)
		(width 0.12954)
		(layer "F.Cu")
		(net "SMB_VR_3V3AUX_SCL_R")
	)
	(segment
		(start 34.370518 -123.295156)
		(end 34.370518 -122.780552)
		(width 0.12954)
		(layer "F.Cu")
		(net "SMB_VR_3V3AUX_SCL_R")
	)
	(segment
		(start 100.287074 -362.602526)
		(end 100.671122 -362.602526)
		(width 0.12954)
		(layer "F.Cu")
		(net "SMB_VR_3V3AUX_SCL_R")
	)
	(via
		(at 99.234498 -363.655102)
		(size 0.508)
		(drill 0.254)
		(layers "F.Cu" "B.Cu")
		(net "SMB_VR_3V3AUX_SCL_R")
	)
	(via
		(at 34.291524 -123.889262)
		(size 0.508)
		(drill 0.254)
		(layers "F.Cu" "B.Cu")
		(net "SMB_VR_3V3AUX_SCL_R")
	)
	(via
		(at 20.35429 -169.654982)
		(size 0.508)
		(drill 0.254)
		(layers "F.Cu" "B.Cu")
		(net "SMB_VR_3V3AUX_SCL_R")
	)
	(via
		(at 31.29788 -336.464148)
		(size 0.508)
		(drill 0.254)
		(layers "F.Cu" "B.Cu")
		(net "SMB_VR_3V3AUX_SCL_R")
	)
	(segment
		(start 44.083478 -332.305152)
		(end 44.083478 -331.988414)
		(width 0.12954)
		(layer "B.Cu")
		(net "SMB_VR_3V3AUX_SCL_R")
	)
	(segment
		(start 44.850558 -332.434692)
		(end 63.693802 -332.434692)
		(width 0.12954)
		(layer "B.Cu")
		(net "SMB_VR_3V3AUX_SCL_R")
	)
	(segment
		(start 65.997836 -352.917506)
		(end 78.41996 -365.33963)
		(width 0.12954)
		(layer "B.Cu")
		(net "SMB_VR_3V3AUX_SCL_R")
	)
	(segment
		(start 42.678858 -332.434692)
		(end 42.808398 -332.305152)
		(width 0.12954)
		(layer "B.Cu")
		(net "SMB_VR_3V3AUX_SCL_R")
	)
	(segment
		(start 31.29788 -336.464148)
		(end 34.696654 -336.464148)
		(width 0.12954)
		(layer "B.Cu")
		(net "SMB_VR_3V3AUX_SCL_R")
	)
	(segment
		(start 43.316398 -331.858874)
		(end 43.445938 -331.988414)
		(width 0.12954)
		(layer "B.Cu")
		(net "SMB_VR_3V3AUX_SCL_R")
	)
	(segment
		(start 43.953938 -332.434692)
		(end 44.083478 -332.305152)
		(width 0.12954)
		(layer "B.Cu")
		(net "SMB_VR_3V3AUX_SCL_R")
	)
	(segment
		(start 97.54997 -365.33963)
		(end 99.234498 -363.655102)
		(width 0.12954)
		(layer "B.Cu")
		(net "SMB_VR_3V3AUX_SCL_R")
	)
	(segment
		(start 78.41996 -365.33963)
		(end 97.54997 -365.33963)
		(width 0.12954)
		(layer "B.Cu")
		(net "SMB_VR_3V3AUX_SCL_R")
	)
	(segment
		(start 42.937938 -331.858874)
		(end 43.316398 -331.858874)
		(width 0.12954)
		(layer "B.Cu")
		(net "SMB_VR_3V3AUX_SCL_R")
	)
	(segment
		(start 44.591478 -331.858874)
		(end 44.721018 -331.988414)
		(width 0.12954)
		(layer "B.Cu")
		(net "SMB_VR_3V3AUX_SCL_R")
	)
	(segment
		(start 44.721018 -332.305152)
		(end 44.850558 -332.434692)
		(width 0.12954)
		(layer "B.Cu")
		(net "SMB_VR_3V3AUX_SCL_R")
	)
	(segment
		(start 42.808398 -331.988414)
		(end 42.937938 -331.858874)
		(width 0.12954)
		(layer "B.Cu")
		(net "SMB_VR_3V3AUX_SCL_R")
	)
	(segment
		(start 44.213018 -331.858874)
		(end 44.591478 -331.858874)
		(width 0.12954)
		(layer "B.Cu")
		(net "SMB_VR_3V3AUX_SCL_R")
	)
	(segment
		(start 44.083478 -331.988414)
		(end 44.213018 -331.858874)
		(width 0.12954)
		(layer "B.Cu")
		(net "SMB_VR_3V3AUX_SCL_R")
	)
	(segment
		(start 20.35429 -169.654982)
		(end 21.865082 -171.165774)
		(width 0.12954)
		(layer "B.Cu")
		(net "SMB_VR_3V3AUX_SCL_R")
	)
	(segment
		(start 34.696654 -336.464148)
		(end 38.72611 -332.434692)
		(width 0.12954)
		(layer "B.Cu")
		(net "SMB_VR_3V3AUX_SCL_R")
	)
	(segment
		(start 65.997836 -334.738726)
		(end 65.997836 -352.917506)
		(width 0.12954)
		(layer "B.Cu")
		(net "SMB_VR_3V3AUX_SCL_R")
	)
	(segment
		(start 43.445938 -331.988414)
		(end 43.445938 -332.305152)
		(width 0.12954)
		(layer "B.Cu")
		(net "SMB_VR_3V3AUX_SCL_R")
	)
	(segment
		(start 21.865082 -171.165774)
		(end 22.588982 -171.165774)
		(width 0.12954)
		(layer "B.Cu")
		(net "SMB_VR_3V3AUX_SCL_R")
	)
	(segment
		(start 44.721018 -331.988414)
		(end 44.721018 -332.305152)
		(width 0.12954)
		(layer "B.Cu")
		(net "SMB_VR_3V3AUX_SCL_R")
	)
	(segment
		(start 42.808398 -332.305152)
		(end 42.808398 -331.988414)
		(width 0.12954)
		(layer "B.Cu")
		(net "SMB_VR_3V3AUX_SCL_R")
	)
	(segment
		(start 43.575478 -332.434692)
		(end 43.953938 -332.434692)
		(width 0.12954)
		(layer "B.Cu")
		(net "SMB_VR_3V3AUX_SCL_R")
	)
	(segment
		(start 43.445938 -332.305152)
		(end 43.575478 -332.434692)
		(width 0.12954)
		(layer "B.Cu")
		(net "SMB_VR_3V3AUX_SCL_R")
	)
	(segment
		(start 38.72611 -332.434692)
		(end 42.678858 -332.434692)
		(width 0.12954)
		(layer "B.Cu")
		(net "SMB_VR_3V3AUX_SCL_R")
	)
	(segment
		(start 63.693802 -332.434692)
		(end 65.997836 -334.738726)
		(width 0.12954)
		(layer "B.Cu")
		(net "SMB_VR_3V3AUX_SCL_R")
	)
	(segment
		(start 20.35429 -171.887388)
		(end 14.91488 -177.326798)
		(width 0.127)
		(layer "In2.Cu")
		(net "SMB_VR_3V3AUX_SCL_R")
	)
	(segment
		(start 36.87318 -130.824732)
		(end 36.87318 -124.594112)
		(width 0.127)
		(layer "In2.Cu")
		(net "SMB_VR_3V3AUX_SCL_R")
	)
	(segment
		(start 29.55798 -328.348848)
		(end 31.29788 -330.088748)
		(width 0.127)
		(layer "In2.Cu")
		(net "SMB_VR_3V3AUX_SCL_R")
	)
	(segment
		(start 18.234914 -195.93306)
		(end 18.234914 -251.722382)
		(width 0.127)
		(layer "In2.Cu")
		(net "SMB_VR_3V3AUX_SCL_R")
	)
	(segment
		(start 35.868864 -146.060414)
		(end 35.868864 -131.829048)
		(width 0.127)
		(layer "In2.Cu")
		(net "SMB_VR_3V3AUX_SCL_R")
	)
	(segment
		(start 20.35429 -169.654982)
		(end 19.8628 -169.163492)
		(width 0.127)
		(layer "In2.Cu")
		(net "SMB_VR_3V3AUX_SCL_R")
	)
	(segment
		(start 36.16833 -123.889262)
		(end 34.291524 -123.889262)
		(width 0.127)
		(layer "In2.Cu")
		(net "SMB_VR_3V3AUX_SCL_R")
	)
	(segment
		(start 31.29788 -330.088748)
		(end 31.29788 -336.464148)
		(width 0.127)
		(layer "In2.Cu")
		(net "SMB_VR_3V3AUX_SCL_R")
	)
	(segment
		(start 13.716 -186.055)
		(end 13.716 -188.976)
		(width 0.127)
		(layer "In2.Cu")
		(net "SMB_VR_3V3AUX_SCL_R")
	)
	(segment
		(start 14.91488 -177.326798)
		(end 14.91488 -184.85612)
		(width 0.127)
		(layer "In2.Cu")
		(net "SMB_VR_3V3AUX_SCL_R")
	)
	(segment
		(start 18.3388 -192.3542)
		(end 19.10588 -192.3542)
		(width 0.127)
		(layer "In2.Cu")
		(net "SMB_VR_3V3AUX_SCL_R")
	)
	(segment
		(start 20.8788 -163.413948)
		(end 20.8788 -153.610818)
		(width 0.127)
		(layer "In2.Cu")
		(net "SMB_VR_3V3AUX_SCL_R")
	)
	(segment
		(start 16.2814 -191.5414)
		(end 17.526 -191.5414)
		(width 0.127)
		(layer "In2.Cu")
		(net "SMB_VR_3V3AUX_SCL_R")
	)
	(segment
		(start 23.455376 -328.348848)
		(end 29.55798 -328.348848)
		(width 0.127)
		(layer "In2.Cu")
		(net "SMB_VR_3V3AUX_SCL_R")
	)
	(segment
		(start 13.716 -188.976)
		(end 16.2814 -191.5414)
		(width 0.127)
		(layer "In2.Cu")
		(net "SMB_VR_3V3AUX_SCL_R")
	)
	(segment
		(start 20.2946 -164.887148)
		(end 20.2946 -163.998148)
		(width 0.127)
		(layer "In2.Cu")
		(net "SMB_VR_3V3AUX_SCL_R")
	)
	(segment
		(start 19.94408 -253.431548)
		(end 19.94408 -256.534412)
		(width 0.127)
		(layer "In2.Cu")
		(net "SMB_VR_3V3AUX_SCL_R")
	)
	(segment
		(start 35.868864 -131.829048)
		(end 36.87318 -130.824732)
		(width 0.127)
		(layer "In2.Cu")
		(net "SMB_VR_3V3AUX_SCL_R")
	)
	(segment
		(start 19.94408 -256.534412)
		(end 18.234914 -258.243578)
		(width 0.127)
		(layer "In2.Cu")
		(net "SMB_VR_3V3AUX_SCL_R")
	)
	(segment
		(start 14.91488 -184.85612)
		(end 13.716 -186.055)
		(width 0.127)
		(layer "In2.Cu")
		(net "SMB_VR_3V3AUX_SCL_R")
	)
	(segment
		(start 26.97353 -147.516088)
		(end 34.41319 -147.516088)
		(width 0.127)
		(layer "In2.Cu")
		(net "SMB_VR_3V3AUX_SCL_R")
	)
	(segment
		(start 36.87318 -124.594112)
		(end 36.16833 -123.889262)
		(width 0.127)
		(layer "In2.Cu")
		(net "SMB_VR_3V3AUX_SCL_R")
	)
	(segment
		(start 19.8628 -165.318948)
		(end 20.2946 -164.887148)
		(width 0.127)
		(layer "In2.Cu")
		(net "SMB_VR_3V3AUX_SCL_R")
	)
	(segment
		(start 19.10588 -192.3542)
		(end 19.28368 -192.532)
		(width 0.127)
		(layer "In2.Cu")
		(net "SMB_VR_3V3AUX_SCL_R")
	)
	(segment
		(start 18.234914 -251.722382)
		(end 19.94408 -253.431548)
		(width 0.127)
		(layer "In2.Cu")
		(net "SMB_VR_3V3AUX_SCL_R")
	)
	(segment
		(start 20.35429 -169.654982)
		(end 20.35429 -171.887388)
		(width 0.127)
		(layer "In2.Cu")
		(net "SMB_VR_3V3AUX_SCL_R")
	)
	(segment
		(start 19.8628 -169.163492)
		(end 19.8628 -165.318948)
		(width 0.127)
		(layer "In2.Cu")
		(net "SMB_VR_3V3AUX_SCL_R")
	)
	(segment
		(start 17.526 -191.5414)
		(end 18.3388 -192.3542)
		(width 0.127)
		(layer "In2.Cu")
		(net "SMB_VR_3V3AUX_SCL_R")
	)
	(segment
		(start 18.234914 -258.243578)
		(end 18.234914 -323.128386)
		(width 0.127)
		(layer "In2.Cu")
		(net "SMB_VR_3V3AUX_SCL_R")
	)
	(segment
		(start 20.2946 -163.998148)
		(end 20.8788 -163.413948)
		(width 0.127)
		(layer "In2.Cu")
		(net "SMB_VR_3V3AUX_SCL_R")
	)
	(segment
		(start 34.41319 -147.516088)
		(end 35.868864 -146.060414)
		(width 0.127)
		(layer "In2.Cu")
		(net "SMB_VR_3V3AUX_SCL_R")
	)
	(segment
		(start 20.8788 -153.610818)
		(end 26.97353 -147.516088)
		(width 0.127)
		(layer "In2.Cu")
		(net "SMB_VR_3V3AUX_SCL_R")
	)
	(segment
		(start 19.28368 -194.884294)
		(end 18.234914 -195.93306)
		(width 0.127)
		(layer "In2.Cu")
		(net "SMB_VR_3V3AUX_SCL_R")
	)
	(segment
		(start 19.28368 -192.532)
		(end 19.28368 -194.884294)
		(width 0.127)
		(layer "In2.Cu")
		(net "SMB_VR_3V3AUX_SCL_R")
	)
	(segment
		(start 18.234914 -323.128386)
		(end 23.455376 -328.348848)
		(width 0.127)
		(layer "In2.Cu")
		(net "SMB_VR_3V3AUX_SCL_R")
	)
	(segment
		(start 39.701724 -116.651278)
		(end 39.831264 -116.521738)
		(width 0.12954)
		(layer "F.Cu")
		(net "SMB_VR_3V3AUX_SCL")
	)
	(segment
		(start 40.437816 -118.815358)
		(end 39.831264 -118.815358)
		(width 0.12954)
		(layer "F.Cu")
		(net "SMB_VR_3V3AUX_SCL")
	)
	(segment
		(start 40.437816 -119.579898)
		(end 40.567356 -119.450358)
		(width 0.12954)
		(layer "F.Cu")
		(net "SMB_VR_3V3AUX_SCL")
	)
	(segment
		(start 39.831264 -118.815358)
		(end 39.701724 -118.685818)
		(width 0.12954)
		(layer "F.Cu")
		(net "SMB_VR_3V3AUX_SCL")
	)
	(segment
		(start 39.701724 -115.627658)
		(end 39.701724 -114.05743)
		(width 0.12954)
		(layer "F.Cu")
		(net "SMB_VR_3V3AUX_SCL")
	)
	(segment
		(start 40.437816 -117.286278)
		(end 39.831264 -117.286278)
		(width 0.12954)
		(layer "F.Cu")
		(net "SMB_VR_3V3AUX_SCL")
	)
	(segment
		(start 40.567356 -115.886738)
		(end 40.437816 -115.757198)
		(width 0.12954)
		(layer "F.Cu")
		(net "SMB_VR_3V3AUX_SCL")
	)
	(segment
		(start 40.437816 -116.521738)
		(end 40.567356 -116.392198)
		(width 0.12954)
		(layer "F.Cu")
		(net "SMB_VR_3V3AUX_SCL")
	)
	(segment
		(start 40.437816 -118.050818)
		(end 40.567356 -117.921278)
		(width 0.12954)
		(layer "F.Cu")
		(net "SMB_VR_3V3AUX_SCL")
	)
	(segment
		(start 48.099472 -113.07445)
		(end 51.338226 -113.07445)
		(width 0.12954)
		(layer "F.Cu")
		(net "SMB_VR_3V3AUX_SCL")
	)
	(segment
		(start 51.338226 -113.07445)
		(end 51.993546 -113.72977)
		(width 0.12954)
		(layer "F.Cu")
		(net "SMB_VR_3V3AUX_SCL")
	)
	(segment
		(start 39.831264 -115.757198)
		(end 39.701724 -115.627658)
		(width 0.12954)
		(layer "F.Cu")
		(net "SMB_VR_3V3AUX_SCL")
	)
	(segment
		(start 52.760626 -112.96269)
		(end 51.993546 -113.72977)
		(width 0.12954)
		(layer "F.Cu")
		(net "SMB_VR_3V3AUX_SCL")
	)
	(segment
		(start 40.567356 -117.415818)
		(end 40.437816 -117.286278)
		(width 0.12954)
		(layer "F.Cu")
		(net "SMB_VR_3V3AUX_SCL")
	)
	(segment
		(start 40.567356 -117.921278)
		(end 40.567356 -117.415818)
		(width 0.12954)
		(layer "F.Cu")
		(net "SMB_VR_3V3AUX_SCL")
	)
	(segment
		(start 35.840162 -121.980452)
		(end 36.884102 -121.980452)
		(width 0.12954)
		(layer "F.Cu")
		(net "SMB_VR_3V3AUX_SCL")
	)
	(segment
		(start 40.567356 -116.392198)
		(end 40.567356 -115.886738)
		(width 0.12954)
		(layer "F.Cu")
		(net "SMB_VR_3V3AUX_SCL")
	)
	(segment
		(start 39.831264 -118.050818)
		(end 40.437816 -118.050818)
		(width 0.12954)
		(layer "F.Cu")
		(net "SMB_VR_3V3AUX_SCL")
	)
	(segment
		(start 39.701724 -117.156738)
		(end 39.701724 -116.651278)
		(width 0.12954)
		(layer "F.Cu")
		(net "SMB_VR_3V3AUX_SCL")
	)
	(segment
		(start 39.284656 -119.579898)
		(end 40.437816 -119.579898)
		(width 0.12954)
		(layer "F.Cu")
		(net "SMB_VR_3V3AUX_SCL")
	)
	(segment
		(start 47.592234 -113.581688)
		(end 48.099472 -113.07445)
		(width 0.12954)
		(layer "F.Cu")
		(net "SMB_VR_3V3AUX_SCL")
	)
	(segment
		(start 36.884102 -121.980452)
		(end 39.284656 -119.579898)
		(width 0.12954)
		(layer "F.Cu")
		(net "SMB_VR_3V3AUX_SCL")
	)
	(segment
		(start 40.437816 -115.757198)
		(end 39.831264 -115.757198)
		(width 0.12954)
		(layer "F.Cu")
		(net "SMB_VR_3V3AUX_SCL")
	)
	(segment
		(start 40.567356 -119.450358)
		(end 40.567356 -118.944898)
		(width 0.12954)
		(layer "F.Cu")
		(net "SMB_VR_3V3AUX_SCL")
	)
	(segment
		(start 40.567356 -118.944898)
		(end 40.437816 -118.815358)
		(width 0.12954)
		(layer "F.Cu")
		(net "SMB_VR_3V3AUX_SCL")
	)
	(segment
		(start 39.701724 -118.180358)
		(end 39.831264 -118.050818)
		(width 0.12954)
		(layer "F.Cu")
		(net "SMB_VR_3V3AUX_SCL")
	)
	(segment
		(start 53.842666 -112.96269)
		(end 52.760626 -112.96269)
		(width 0.12954)
		(layer "F.Cu")
		(net "SMB_VR_3V3AUX_SCL")
	)
	(segment
		(start 39.831264 -117.286278)
		(end 39.701724 -117.156738)
		(width 0.12954)
		(layer "F.Cu")
		(net "SMB_VR_3V3AUX_SCL")
	)
	(segment
		(start 39.701724 -118.685818)
		(end 39.701724 -118.180358)
		(width 0.12954)
		(layer "F.Cu")
		(net "SMB_VR_3V3AUX_SCL")
	)
	(segment
		(start 39.831264 -116.521738)
		(end 40.437816 -116.521738)
		(width 0.12954)
		(layer "F.Cu")
		(net "SMB_VR_3V3AUX_SCL")
	)
	(via
		(at 47.592234 -113.581688)
		(size 0.508)
		(drill 0.254)
		(layers "F.Cu" "B.Cu")
		(net "SMB_VR_3V3AUX_SCL")
	)
	(via
		(at 39.701724 -114.05743)
		(size 0.508)
		(drill 0.254)
		(layers "F.Cu" "B.Cu")
		(net "SMB_VR_3V3AUX_SCL")
	)
	(segment
		(start 39.701724 -114.05743)
		(end 40.180768 -114.536474)
		(width 0.127)
		(layer "In4.Cu")
		(net "SMB_VR_3V3AUX_SCL")
	)
	(segment
		(start 40.180768 -114.536474)
		(end 47.146718 -114.536474)
		(width 0.127)
		(layer "In4.Cu")
		(net "SMB_VR_3V3AUX_SCL")
	)
	(segment
		(start 47.592234 -114.090958)
		(end 47.592234 -113.581688)
		(width 0.127)
		(layer "In4.Cu")
		(net "SMB_VR_3V3AUX_SCL")
	)
	(segment
		(start 47.146718 -114.536474)
		(end 47.592234 -114.090958)
		(width 0.127)
		(layer "In4.Cu")
		(net "SMB_VR_3V3AUX_SCL")
	)
	(segment
		(start 174.66691 -13.600176)
		(end 174.66691 -13.194284)
		(width 0.12954)
		(layer "F.Cu")
		(net "SMB_SML1_PMBUS_3V3AUX_PCH_SDA_R")
	)
	(segment
		(start 174.77232 -12.109704)
		(end 174.585376 -11.92276)
		(width 0.12954)
		(layer "F.Cu")
		(net "SMB_SML1_PMBUS_3V3AUX_PCH_SDA_R")
	)
	(segment
		(start 174.66691 -13.194284)
		(end 174.77232 -13.088874)
		(width 0.12954)
		(layer "F.Cu")
		(net "SMB_SML1_PMBUS_3V3AUX_PCH_SDA_R")
	)
	(segment
		(start 174.77232 -13.088874)
		(end 174.77232 -12.109704)
		(width 0.12954)
		(layer "F.Cu")
		(net "SMB_SML1_PMBUS_3V3AUX_PCH_SDA_R")
	)
	(via
		(at 174.585376 -11.92276)
		(size 0.508)
		(drill 0.254)
		(layers "F.Cu" "B.Cu")
		(net "SMB_SML1_PMBUS_3V3AUX_PCH_SDA_R")
	)
	(segment
		(start 175.33493 -12.614148)
		(end 176.235868 -12.987274)
		(width 0.12954)
		(layer "B.Cu")
		(net "SMB_SML1_PMBUS_3V3AUX_PCH_SDA_R")
	)
	(segment
		(start 175.159416 -12.4968)
		(end 175.33493 -12.614148)
		(width 0.12954)
		(layer "B.Cu")
		(net "SMB_SML1_PMBUS_3V3AUX_PCH_SDA_R")
	)
	(segment
		(start 176.3776 -13.129006)
		(end 176.3776 -13.362178)
		(width 0.12954)
		(layer "B.Cu")
		(net "SMB_SML1_PMBUS_3V3AUX_PCH_SDA_R")
	)
	(segment
		(start 176.235868 -12.987274)
		(end 176.3776 -13.129006)
		(width 0.12954)
		(layer "B.Cu")
		(net "SMB_SML1_PMBUS_3V3AUX_PCH_SDA_R")
	)
	(segment
		(start 174.585376 -11.92276)
		(end 175.159416 -12.4968)
		(width 0.12954)
		(layer "B.Cu")
		(net "SMB_SML1_PMBUS_3V3AUX_PCH_SDA_R")
	)
	(segment
		(start 7.02183 -54.955948)
		(end 6.27888 -54.955948)
		(width 0.12954)
		(layer "F.Cu")
		(net "SMB_SML1_PMBUS_3V3AUX_PCH_SDA")
	)
	(segment
		(start 177.927 -19.014948)
		(end 178.28895 -19.376898)
		(width 0.12954)
		(layer "F.Cu")
		(net "SMB_SML1_PMBUS_3V3AUX_PCH_SDA")
	)
	(segment
		(start 8.68553 -55.451248)
		(end 9.18083 -54.955948)
		(width 0.12954)
		(layer "F.Cu")
		(net "SMB_SML1_PMBUS_3V3AUX_PCH_SDA")
	)
	(segment
		(start 178.28895 -19.376898)
		(end 178.816 -19.376898)
		(width 0.12954)
		(layer "F.Cu")
		(net "SMB_SML1_PMBUS_3V3AUX_PCH_SDA")
	)
	(segment
		(start 7.51713 -55.451248)
		(end 8.68553 -55.451248)
		(width 0.12954)
		(layer "F.Cu")
		(net "SMB_SML1_PMBUS_3V3AUX_PCH_SDA")
	)
	(segment
		(start 7.02183 -54.955948)
		(end 7.51713 -55.451248)
		(width 0.12954)
		(layer "F.Cu")
		(net "SMB_SML1_PMBUS_3V3AUX_PCH_SDA")
	)
	(via
		(at 6.27888 -54.955948)
		(size 0.508)
		(drill 0.254)
		(layers "F.Cu" "B.Cu")
		(net "SMB_SML1_PMBUS_3V3AUX_PCH_SDA")
	)
	(via
		(at 176.3776 -14.771878)
		(size 0.508)
		(drill 0.254)
		(layers "F.Cu" "B.Cu")
		(net "SMB_SML1_PMBUS_3V3AUX_PCH_SDA")
	)
	(via
		(at 177.927 -19.014948)
		(size 0.508)
		(drill 0.254)
		(layers "F.Cu" "B.Cu")
		(net "SMB_SML1_PMBUS_3V3AUX_PCH_SDA")
	)
	(segment
		(start 176.3776 -14.162278)
		(end 176.3776 -14.771878)
		(width 0.12954)
		(layer "B.Cu")
		(net "SMB_SML1_PMBUS_3V3AUX_PCH_SDA")
	)
	(segment
		(start 178.03495 -19.122898)
		(end 178.689 -19.122898)
		(width 0.12954)
		(layer "B.Cu")
		(net "SMB_SML1_PMBUS_3V3AUX_PCH_SDA")
	)
	(segment
		(start 177.927 -19.014948)
		(end 178.03495 -19.122898)
		(width 0.12954)
		(layer "B.Cu")
		(net "SMB_SML1_PMBUS_3V3AUX_PCH_SDA")
	)
	(segment
		(start 159.44596 -18.494248)
		(end 160.2359 -17.704308)
		(width 0.127)
		(layer "In6.Cu")
		(net "SMB_SML1_PMBUS_3V3AUX_PCH_SDA")
	)
	(segment
		(start 101.65588 -30.310836)
		(end 105.077768 -26.888948)
		(width 0.127)
		(layer "In6.Cu")
		(net "SMB_SML1_PMBUS_3V3AUX_PCH_SDA")
	)
	(segment
		(start 111.30788 -26.888948)
		(end 118.589044 -34.170112)
		(width 0.127)
		(layer "In6.Cu")
		(net "SMB_SML1_PMBUS_3V3AUX_PCH_SDA")
	)
	(segment
		(start 44.980606 -48.556926)
		(end 54.075584 -39.461948)
		(width 0.127)
		(layer "In6.Cu")
		(net "SMB_SML1_PMBUS_3V3AUX_PCH_SDA")
	)
	(segment
		(start 159.74314 -14.293088)
		(end 159.61614 -14.166088)
		(width 0.127)
		(layer "In6.Cu")
		(net "SMB_SML1_PMBUS_3V3AUX_PCH_SDA")
	)
	(segment
		(start 7.079996 -55.757064)
		(end 9.036304 -55.757064)
		(width 0.127)
		(layer "In6.Cu")
		(net "SMB_SML1_PMBUS_3V3AUX_PCH_SDA")
	)
	(segment
		(start 65.913 -39.944548)
		(end 68.58508 -39.944548)
		(width 0.127)
		(layer "In6.Cu")
		(net "SMB_SML1_PMBUS_3V3AUX_PCH_SDA")
	)
	(segment
		(start 68.58508 -39.944548)
		(end 69.52488 -40.884348)
		(width 0.127)
		(layer "In6.Cu")
		(net "SMB_SML1_PMBUS_3V3AUX_PCH_SDA")
	)
	(segment
		(start 172.605954 -12.715748)
		(end 175.165766 -12.715748)
		(width 0.127)
		(layer "In6.Cu")
		(net "SMB_SML1_PMBUS_3V3AUX_PCH_SDA")
	)
	(segment
		(start 160.502346 -12.964922)
		(end 172.35678 -12.964922)
		(width 0.127)
		(layer "In6.Cu")
		(net "SMB_SML1_PMBUS_3V3AUX_PCH_SDA")
	)
	(segment
		(start 159.74314 -13.658088)
		(end 160.1089 -13.658088)
		(width 0.127)
		(layer "In6.Cu")
		(net "SMB_SML1_PMBUS_3V3AUX_PCH_SDA")
	)
	(segment
		(start 54.075584 -39.461948)
		(end 62.43828 -39.461948)
		(width 0.127)
		(layer "In6.Cu")
		(net "SMB_SML1_PMBUS_3V3AUX_PCH_SDA")
	)
	(segment
		(start 160.2359 -13.531088)
		(end 160.2359 -13.231368)
		(width 0.127)
		(layer "In6.Cu")
		(net "SMB_SML1_PMBUS_3V3AUX_PCH_SDA")
	)
	(segment
		(start 160.2359 -14.420088)
		(end 160.1089 -14.293088)
		(width 0.127)
		(layer "In6.Cu")
		(net "SMB_SML1_PMBUS_3V3AUX_PCH_SDA")
	)
	(segment
		(start 78.61808 -40.884348)
		(end 80.12938 -39.373048)
		(width 0.127)
		(layer "In6.Cu")
		(net "SMB_SML1_PMBUS_3V3AUX_PCH_SDA")
	)
	(segment
		(start 10.004552 -54.788816)
		(end 16.532098 -54.788816)
		(width 0.127)
		(layer "In6.Cu")
		(net "SMB_SML1_PMBUS_3V3AUX_PCH_SDA")
	)
	(segment
		(start 159.61614 -14.166088)
		(end 159.61614 -13.785088)
		(width 0.127)
		(layer "In6.Cu")
		(net "SMB_SML1_PMBUS_3V3AUX_PCH_SDA")
	)
	(segment
		(start 69.52488 -40.884348)
		(end 78.61808 -40.884348)
		(width 0.127)
		(layer "In6.Cu")
		(net "SMB_SML1_PMBUS_3V3AUX_PCH_SDA")
	)
	(segment
		(start 22.763988 -48.556926)
		(end 44.980606 -48.556926)
		(width 0.127)
		(layer "In6.Cu")
		(net "SMB_SML1_PMBUS_3V3AUX_PCH_SDA")
	)
	(segment
		(start 159.61614 -13.785088)
		(end 159.74314 -13.658088)
		(width 0.127)
		(layer "In6.Cu")
		(net "SMB_SML1_PMBUS_3V3AUX_PCH_SDA")
	)
	(segment
		(start 176.3776 -13.927582)
		(end 176.3776 -14.771878)
		(width 0.127)
		(layer "In6.Cu")
		(net "SMB_SML1_PMBUS_3V3AUX_PCH_SDA")
	)
	(segment
		(start 105.077768 -26.888948)
		(end 111.30788 -26.888948)
		(width 0.127)
		(layer "In6.Cu")
		(net "SMB_SML1_PMBUS_3V3AUX_PCH_SDA")
	)
	(segment
		(start 175.165766 -12.715748)
		(end 176.3776 -13.927582)
		(width 0.127)
		(layer "In6.Cu")
		(net "SMB_SML1_PMBUS_3V3AUX_PCH_SDA")
	)
	(segment
		(start 160.2359 -17.704308)
		(end 160.2359 -14.420088)
		(width 0.127)
		(layer "In6.Cu")
		(net "SMB_SML1_PMBUS_3V3AUX_PCH_SDA")
	)
	(segment
		(start 63.65748 -40.681148)
		(end 65.1764 -40.681148)
		(width 0.127)
		(layer "In6.Cu")
		(net "SMB_SML1_PMBUS_3V3AUX_PCH_SDA")
	)
	(segment
		(start 80.12938 -39.373048)
		(end 90.0557 -39.373048)
		(width 0.127)
		(layer "In6.Cu")
		(net "SMB_SML1_PMBUS_3V3AUX_PCH_SDA")
	)
	(segment
		(start 62.43828 -39.461948)
		(end 63.65748 -40.681148)
		(width 0.127)
		(layer "In6.Cu")
		(net "SMB_SML1_PMBUS_3V3AUX_PCH_SDA")
	)
	(segment
		(start 160.2359 -13.231368)
		(end 160.502346 -12.964922)
		(width 0.127)
		(layer "In6.Cu")
		(net "SMB_SML1_PMBUS_3V3AUX_PCH_SDA")
	)
	(segment
		(start 159.44596 -24.596598)
		(end 159.44596 -18.494248)
		(width 0.127)
		(layer "In6.Cu")
		(net "SMB_SML1_PMBUS_3V3AUX_PCH_SDA")
	)
	(segment
		(start 93.79458 -35.634168)
		(end 99.302824 -35.634168)
		(width 0.127)
		(layer "In6.Cu")
		(net "SMB_SML1_PMBUS_3V3AUX_PCH_SDA")
	)
	(segment
		(start 16.532098 -54.788816)
		(end 22.763988 -48.556926)
		(width 0.127)
		(layer "In6.Cu")
		(net "SMB_SML1_PMBUS_3V3AUX_PCH_SDA")
	)
	(segment
		(start 65.1764 -40.681148)
		(end 65.913 -39.944548)
		(width 0.127)
		(layer "In6.Cu")
		(net "SMB_SML1_PMBUS_3V3AUX_PCH_SDA")
	)
	(segment
		(start 118.589044 -34.170112)
		(end 124.981716 -34.170112)
		(width 0.127)
		(layer "In6.Cu")
		(net "SMB_SML1_PMBUS_3V3AUX_PCH_SDA")
	)
	(segment
		(start 9.036304 -55.757064)
		(end 10.004552 -54.788816)
		(width 0.127)
		(layer "In6.Cu")
		(net "SMB_SML1_PMBUS_3V3AUX_PCH_SDA")
	)
	(segment
		(start 137.784586 -27.666188)
		(end 156.37637 -27.666188)
		(width 0.127)
		(layer "In6.Cu")
		(net "SMB_SML1_PMBUS_3V3AUX_PCH_SDA")
	)
	(segment
		(start 160.1089 -14.293088)
		(end 159.74314 -14.293088)
		(width 0.127)
		(layer "In6.Cu")
		(net "SMB_SML1_PMBUS_3V3AUX_PCH_SDA")
	)
	(segment
		(start 101.65588 -33.281112)
		(end 101.65588 -30.310836)
		(width 0.127)
		(layer "In6.Cu")
		(net "SMB_SML1_PMBUS_3V3AUX_PCH_SDA")
	)
	(segment
		(start 6.27888 -54.955948)
		(end 7.079996 -55.757064)
		(width 0.127)
		(layer "In6.Cu")
		(net "SMB_SML1_PMBUS_3V3AUX_PCH_SDA")
	)
	(segment
		(start 156.37637 -27.666188)
		(end 159.44596 -24.596598)
		(width 0.127)
		(layer "In6.Cu")
		(net "SMB_SML1_PMBUS_3V3AUX_PCH_SDA")
	)
	(segment
		(start 124.981716 -34.170112)
		(end 125.89764 -33.254188)
		(width 0.127)
		(layer "In6.Cu")
		(net "SMB_SML1_PMBUS_3V3AUX_PCH_SDA")
	)
	(segment
		(start 132.196586 -33.254188)
		(end 137.784586 -27.666188)
		(width 0.127)
		(layer "In6.Cu")
		(net "SMB_SML1_PMBUS_3V3AUX_PCH_SDA")
	)
	(segment
		(start 90.0557 -39.373048)
		(end 93.79458 -35.634168)
		(width 0.127)
		(layer "In6.Cu")
		(net "SMB_SML1_PMBUS_3V3AUX_PCH_SDA")
	)
	(segment
		(start 160.1089 -13.658088)
		(end 160.2359 -13.531088)
		(width 0.127)
		(layer "In6.Cu")
		(net "SMB_SML1_PMBUS_3V3AUX_PCH_SDA")
	)
	(segment
		(start 125.89764 -33.254188)
		(end 132.196586 -33.254188)
		(width 0.127)
		(layer "In6.Cu")
		(net "SMB_SML1_PMBUS_3V3AUX_PCH_SDA")
	)
	(segment
		(start 99.302824 -35.634168)
		(end 101.65588 -33.281112)
		(width 0.127)
		(layer "In6.Cu")
		(net "SMB_SML1_PMBUS_3V3AUX_PCH_SDA")
	)
	(segment
		(start 172.35678 -12.964922)
		(end 172.605954 -12.715748)
		(width 0.127)
		(layer "In6.Cu")
		(net "SMB_SML1_PMBUS_3V3AUX_PCH_SDA")
	)
	(segment
		(start 176.9872 -17.765268)
		(end 177.546 -18.324068)
		(width 0.127)
		(layer "In13.Cu")
		(net "SMB_SML1_PMBUS_3V3AUX_PCH_SDA")
	)
	(segment
		(start 177.546 -18.633948)
		(end 177.927 -19.014948)
		(width 0.127)
		(layer "In13.Cu")
		(net "SMB_SML1_PMBUS_3V3AUX_PCH_SDA")
	)
	(segment
		(start 177.546 -18.324068)
		(end 177.546 -18.633948)
		(width 0.127)
		(layer "In13.Cu")
		(net "SMB_SML1_PMBUS_3V3AUX_PCH_SDA")
	)
	(segment
		(start 176.9872 -15.381478)
		(end 176.9872 -17.765268)
		(width 0.127)
		(layer "In13.Cu")
		(net "SMB_SML1_PMBUS_3V3AUX_PCH_SDA")
	)
	(segment
		(start 176.3776 -14.771878)
		(end 176.9872 -15.381478)
		(width 0.127)
		(layer "In13.Cu")
		(net "SMB_SML1_PMBUS_3V3AUX_PCH_SDA")
	)
	(segment
		(start 174.52848 -10.112248)
		(end 174.52848 -10.066528)
		(width 0.12954)
		(layer "F.Cu")
		(net "SMB_SML1_PMBUS_3V3AUX_PCH_SCL_R")
	)
	(segment
		(start 175.267112 -10.85088)
		(end 174.52848 -10.112248)
		(width 0.12954)
		(layer "F.Cu")
		(net "SMB_SML1_PMBUS_3V3AUX_PCH_SCL_R")
	)
	(segment
		(start 175.267112 -13.600176)
		(end 175.267112 -10.85088)
		(width 0.12954)
		(layer "F.Cu")
		(net "SMB_SML1_PMBUS_3V3AUX_PCH_SCL_R")
	)
	(via
		(at 174.52848 -10.066528)
		(size 0.508)
		(drill 0.254)
		(layers "F.Cu" "B.Cu")
		(net "SMB_SML1_PMBUS_3V3AUX_PCH_SCL_R")
	)
	(segment
		(start 175.782986 -12.32916)
		(end 175.558196 -12.235942)
		(width 0.12954)
		(layer "B.Cu")
		(net "SMB_SML1_PMBUS_3V3AUX_PCH_SCL_R")
	)
	(segment
		(start 175.558196 -12.235942)
		(end 175.28794 -11.965686)
		(width 0.12954)
		(layer "B.Cu")
		(net "SMB_SML1_PMBUS_3V3AUX_PCH_SCL_R")
	)
	(segment
		(start 175.28794 -10.566908)
		(end 175.11776 -10.396728)
		(width 0.12954)
		(layer "B.Cu")
		(net "SMB_SML1_PMBUS_3V3AUX_PCH_SCL_R")
	)
	(segment
		(start 174.85868 -10.396728)
		(end 174.52848 -10.066528)
		(width 0.12954)
		(layer "B.Cu")
		(net "SMB_SML1_PMBUS_3V3AUX_PCH_SCL_R")
	)
	(segment
		(start 175.28794 -11.965686)
		(end 175.28794 -10.566908)
		(width 0.12954)
		(layer "B.Cu")
		(net "SMB_SML1_PMBUS_3V3AUX_PCH_SCL_R")
	)
	(segment
		(start 177.443638 -12.92733)
		(end 175.999648 -12.32916)
		(width 0.12954)
		(layer "B.Cu")
		(net "SMB_SML1_PMBUS_3V3AUX_PCH_SCL_R")
	)
	(segment
		(start 175.11776 -10.396728)
		(end 174.85868 -10.396728)
		(width 0.12954)
		(layer "B.Cu")
		(net "SMB_SML1_PMBUS_3V3AUX_PCH_SCL_R")
	)
	(segment
		(start 175.999648 -12.32916)
		(end 175.782986 -12.32916)
		(width 0.12954)
		(layer "B.Cu")
		(net "SMB_SML1_PMBUS_3V3AUX_PCH_SCL_R")
	)
	(segment
		(start 177.443638 -13.362178)
		(end 177.443638 -12.92733)
		(width 0.12954)
		(layer "B.Cu")
		(net "SMB_SML1_PMBUS_3V3AUX_PCH_SCL_R")
	)
	(segment
		(start 9.18083 -56.982868)
		(end 8.65251 -56.454548)
		(width 0.12954)
		(layer "F.Cu")
		(net "SMB_SML1_PMBUS_3V3AUX_PCH_SCL")
	)
	(segment
		(start 8.65251 -56.454548)
		(end 7.55523 -56.454548)
		(width 0.12954)
		(layer "F.Cu")
		(net "SMB_SML1_PMBUS_3V3AUX_PCH_SCL")
	)
	(segment
		(start 7.02183 -56.987948)
		(end 6.27888 -56.987948)
		(width 0.12954)
		(layer "F.Cu")
		(net "SMB_SML1_PMBUS_3V3AUX_PCH_SCL")
	)
	(segment
		(start 7.55523 -56.454548)
		(end 7.02183 -56.987948)
		(width 0.12954)
		(layer "F.Cu")
		(net "SMB_SML1_PMBUS_3V3AUX_PCH_SCL")
	)
	(via
		(at 177.22088 -14.773148)
		(size 0.508)
		(drill 0.254)
		(layers "F.Cu" "B.Cu")
		(net "SMB_SML1_PMBUS_3V3AUX_PCH_SCL")
	)
	(via
		(at 180.3908 -17.694148)
		(size 0.508)
		(drill 0.254)
		(layers "F.Cu" "B.Cu")
		(net "SMB_SML1_PMBUS_3V3AUX_PCH_SCL")
	)
	(via
		(at 6.27888 -56.987948)
		(size 0.508)
		(drill 0.254)
		(layers "F.Cu" "B.Cu")
		(net "SMB_SML1_PMBUS_3V3AUX_PCH_SCL")
	)
	(segment
		(start 177.446178 -14.159738)
		(end 177.443638 -14.162278)
		(width 0.12954)
		(layer "B.Cu")
		(net "SMB_SML1_PMBUS_3V3AUX_PCH_SCL")
	)
	(segment
		(start 177.443638 -14.55039)
		(end 177.443638 -14.162278)
		(width 0.12954)
		(layer "B.Cu")
		(net "SMB_SML1_PMBUS_3V3AUX_PCH_SCL")
	)
	(segment
		(start 180.3908 -18.462498)
		(end 179.7304 -19.122898)
		(width 0.12954)
		(layer "B.Cu")
		(net "SMB_SML1_PMBUS_3V3AUX_PCH_SCL")
	)
	(segment
		(start 179.7304 -19.122898)
		(end 179.705 -19.122898)
		(width 0.12954)
		(layer "B.Cu")
		(net "SMB_SML1_PMBUS_3V3AUX_PCH_SCL")
	)
	(segment
		(start 177.22088 -14.773148)
		(end 177.443638 -14.55039)
		(width 0.12954)
		(layer "B.Cu")
		(net "SMB_SML1_PMBUS_3V3AUX_PCH_SCL")
	)
	(segment
		(start 178.50866 -14.159738)
		(end 177.446178 -14.159738)
		(width 0.12954)
		(layer "B.Cu")
		(net "SMB_SML1_PMBUS_3V3AUX_PCH_SCL")
	)
	(segment
		(start 180.3908 -17.694148)
		(end 180.3908 -18.462498)
		(width 0.12954)
		(layer "B.Cu")
		(net "SMB_SML1_PMBUS_3V3AUX_PCH_SCL")
	)
	(segment
		(start 81.09458 -39.804848)
		(end 79.55788 -41.341548)
		(width 0.127)
		(layer "In6.Cu")
		(net "SMB_SML1_PMBUS_3V3AUX_PCH_SCL")
	)
	(segment
		(start 176.75225 -15.241778)
		(end 176.182528 -15.241778)
		(width 0.127)
		(layer "In6.Cu")
		(net "SMB_SML1_PMBUS_3V3AUX_PCH_SCL")
	)
	(segment
		(start 60.9092 -39.944548)
		(end 54.203854 -39.944548)
		(width 0.127)
		(layer "In6.Cu")
		(net "SMB_SML1_PMBUS_3V3AUX_PCH_SCL")
	)
	(segment
		(start 176.182528 -15.241778)
		(end 175.9077 -14.96695)
		(width 0.127)
		(layer "In6.Cu")
		(net "SMB_SML1_PMBUS_3V3AUX_PCH_SCL")
	)
	(segment
		(start 10.183622 -55.220616)
		(end 9.215374 -56.188864)
		(width 0.127)
		(layer "In6.Cu")
		(net "SMB_SML1_PMBUS_3V3AUX_PCH_SCL")
	)
	(segment
		(start 175.037496 -13.198348)
		(end 172.781214 -13.198348)
		(width 0.127)
		(layer "In6.Cu")
		(net "SMB_SML1_PMBUS_3V3AUX_PCH_SCL")
	)
	(segment
		(start 102.08768 -33.460182)
		(end 99.481894 -36.065968)
		(width 0.127)
		(layer "In6.Cu")
		(net "SMB_SML1_PMBUS_3V3AUX_PCH_SCL")
	)
	(segment
		(start 132.276596 -33.785048)
		(end 126.0602 -33.785048)
		(width 0.127)
		(layer "In6.Cu")
		(net "SMB_SML1_PMBUS_3V3AUX_PCH_SCL")
	)
	(segment
		(start 73.33234 -41.646348)
		(end 69.4182 -41.646348)
		(width 0.127)
		(layer "In6.Cu")
		(net "SMB_SML1_PMBUS_3V3AUX_PCH_SCL")
	)
	(segment
		(start 160.69818 -18.052288)
		(end 159.87776 -18.872708)
		(width 0.127)
		(layer "In6.Cu")
		(net "SMB_SML1_PMBUS_3V3AUX_PCH_SCL")
	)
	(segment
		(start 105.256838 -27.320748)
		(end 102.08768 -30.489906)
		(width 0.127)
		(layer "In6.Cu")
		(net "SMB_SML1_PMBUS_3V3AUX_PCH_SCL")
	)
	(segment
		(start 159.87776 -24.775668)
		(end 156.29128 -28.362148)
		(width 0.127)
		(layer "In6.Cu")
		(net "SMB_SML1_PMBUS_3V3AUX_PCH_SCL")
	)
	(segment
		(start 99.481894 -36.065968)
		(end 93.9927 -36.065968)
		(width 0.127)
		(layer "In6.Cu")
		(net "SMB_SML1_PMBUS_3V3AUX_PCH_SCL")
	)
	(segment
		(start 138.34364 -29.271468)
		(end 136.790176 -29.271468)
		(width 0.127)
		(layer "In6.Cu")
		(net "SMB_SML1_PMBUS_3V3AUX_PCH_SCL")
	)
	(segment
		(start 175.9077 -14.068552)
		(end 175.037496 -13.198348)
		(width 0.127)
		(layer "In6.Cu")
		(net "SMB_SML1_PMBUS_3V3AUX_PCH_SCL")
	)
	(segment
		(start 17.053052 -55.220616)
		(end 10.183622 -55.220616)
		(width 0.127)
		(layer "In6.Cu")
		(net "SMB_SML1_PMBUS_3V3AUX_PCH_SCL")
	)
	(segment
		(start 7.077964 -56.188864)
		(end 6.27888 -56.987948)
		(width 0.127)
		(layer "In6.Cu")
		(net "SMB_SML1_PMBUS_3V3AUX_PCH_SCL")
	)
	(segment
		(start 139.25296 -28.362148)
		(end 138.34364 -29.271468)
		(width 0.127)
		(layer "In6.Cu")
		(net "SMB_SML1_PMBUS_3V3AUX_PCH_SCL")
	)
	(segment
		(start 172.781214 -13.198348)
		(end 172.58284 -13.396722)
		(width 0.127)
		(layer "In6.Cu")
		(net "SMB_SML1_PMBUS_3V3AUX_PCH_SCL")
	)
	(segment
		(start 23.284942 -48.988726)
		(end 17.053052 -55.220616)
		(width 0.127)
		(layer "In6.Cu")
		(net "SMB_SML1_PMBUS_3V3AUX_PCH_SCL")
	)
	(segment
		(start 175.9077 -14.96695)
		(end 175.9077 -14.068552)
		(width 0.127)
		(layer "In6.Cu")
		(net "SMB_SML1_PMBUS_3V3AUX_PCH_SCL")
	)
	(segment
		(start 172.58284 -13.396722)
		(end 161.287206 -13.396722)
		(width 0.127)
		(layer "In6.Cu")
		(net "SMB_SML1_PMBUS_3V3AUX_PCH_SCL")
	)
	(segment
		(start 68.9864 -41.214548)
		(end 62.1792 -41.214548)
		(width 0.127)
		(layer "In6.Cu")
		(net "SMB_SML1_PMBUS_3V3AUX_PCH_SCL")
	)
	(segment
		(start 156.29128 -28.362148)
		(end 139.25296 -28.362148)
		(width 0.127)
		(layer "In6.Cu")
		(net "SMB_SML1_PMBUS_3V3AUX_PCH_SCL")
	)
	(segment
		(start 90.25382 -39.804848)
		(end 81.09458 -39.804848)
		(width 0.127)
		(layer "In6.Cu")
		(net "SMB_SML1_PMBUS_3V3AUX_PCH_SCL")
	)
	(segment
		(start 54.203854 -39.944548)
		(end 45.159676 -48.988726)
		(width 0.127)
		(layer "In6.Cu")
		(net "SMB_SML1_PMBUS_3V3AUX_PCH_SCL")
	)
	(segment
		(start 69.4182 -41.646348)
		(end 68.9864 -41.214548)
		(width 0.127)
		(layer "In6.Cu")
		(net "SMB_SML1_PMBUS_3V3AUX_PCH_SCL")
	)
	(segment
		(start 102.08768 -30.489906)
		(end 102.08768 -33.460182)
		(width 0.127)
		(layer "In6.Cu")
		(net "SMB_SML1_PMBUS_3V3AUX_PCH_SCL")
	)
	(segment
		(start 125.243336 -34.601912)
		(end 118.409974 -34.601912)
		(width 0.127)
		(layer "In6.Cu")
		(net "SMB_SML1_PMBUS_3V3AUX_PCH_SCL")
	)
	(segment
		(start 126.0602 -33.785048)
		(end 125.243336 -34.601912)
		(width 0.127)
		(layer "In6.Cu")
		(net "SMB_SML1_PMBUS_3V3AUX_PCH_SCL")
	)
	(segment
		(start 177.22088 -14.773148)
		(end 176.75225 -15.241778)
		(width 0.127)
		(layer "In6.Cu")
		(net "SMB_SML1_PMBUS_3V3AUX_PCH_SCL")
	)
	(segment
		(start 111.12881 -27.320748)
		(end 105.256838 -27.320748)
		(width 0.127)
		(layer "In6.Cu")
		(net "SMB_SML1_PMBUS_3V3AUX_PCH_SCL")
	)
	(segment
		(start 79.55788 -41.341548)
		(end 73.63714 -41.341548)
		(width 0.127)
		(layer "In6.Cu")
		(net "SMB_SML1_PMBUS_3V3AUX_PCH_SCL")
	)
	(segment
		(start 9.215374 -56.188864)
		(end 7.077964 -56.188864)
		(width 0.127)
		(layer "In6.Cu")
		(net "SMB_SML1_PMBUS_3V3AUX_PCH_SCL")
	)
	(segment
		(start 93.9927 -36.065968)
		(end 90.25382 -39.804848)
		(width 0.127)
		(layer "In6.Cu")
		(net "SMB_SML1_PMBUS_3V3AUX_PCH_SCL")
	)
	(segment
		(start 136.790176 -29.271468)
		(end 132.276596 -33.785048)
		(width 0.127)
		(layer "In6.Cu")
		(net "SMB_SML1_PMBUS_3V3AUX_PCH_SCL")
	)
	(segment
		(start 118.409974 -34.601912)
		(end 111.12881 -27.320748)
		(width 0.127)
		(layer "In6.Cu")
		(net "SMB_SML1_PMBUS_3V3AUX_PCH_SCL")
	)
	(segment
		(start 159.87776 -18.872708)
		(end 159.87776 -24.775668)
		(width 0.127)
		(layer "In6.Cu")
		(net "SMB_SML1_PMBUS_3V3AUX_PCH_SCL")
	)
	(segment
		(start 45.159676 -48.988726)
		(end 23.284942 -48.988726)
		(width 0.127)
		(layer "In6.Cu")
		(net "SMB_SML1_PMBUS_3V3AUX_PCH_SCL")
	)
	(segment
		(start 161.287206 -13.396722)
		(end 160.69818 -13.985748)
		(width 0.127)
		(layer "In6.Cu")
		(net "SMB_SML1_PMBUS_3V3AUX_PCH_SCL")
	)
	(segment
		(start 73.63714 -41.341548)
		(end 73.33234 -41.646348)
		(width 0.127)
		(layer "In6.Cu")
		(net "SMB_SML1_PMBUS_3V3AUX_PCH_SCL")
	)
	(segment
		(start 62.1792 -41.214548)
		(end 60.9092 -39.944548)
		(width 0.127)
		(layer "In6.Cu")
		(net "SMB_SML1_PMBUS_3V3AUX_PCH_SCL")
	)
	(segment
		(start 160.69818 -13.985748)
		(end 160.69818 -18.052288)
		(width 0.127)
		(layer "In6.Cu")
		(net "SMB_SML1_PMBUS_3V3AUX_PCH_SCL")
	)
	(segment
		(start 178.54168 -16.093948)
		(end 179.5399 -16.093948)
		(width 0.127)
		(layer "In13.Cu")
		(net "SMB_SML1_PMBUS_3V3AUX_PCH_SCL")
	)
	(segment
		(start 180.3908 -16.944848)
		(end 180.3908 -17.694148)
		(width 0.127)
		(layer "In13.Cu")
		(net "SMB_SML1_PMBUS_3V3AUX_PCH_SCL")
	)
	(segment
		(start 177.22088 -14.773148)
		(end 178.54168 -16.093948)
		(width 0.127)
		(layer "In13.Cu")
		(net "SMB_SML1_PMBUS_3V3AUX_PCH_SCL")
	)
	(segment
		(start 179.5399 -16.093948)
		(end 180.3908 -16.944848)
		(width 0.127)
		(layer "In13.Cu")
		(net "SMB_SML1_PMBUS_3V3AUX_PCH_SCL")
	)
	(segment
		(start 8.55218 -59.019948)
		(end 9.18083 -59.019948)
		(width 0.12954)
		(layer "F.Cu")
		(net "SMB_SML0_3V3AUX_SDA")
	)
	(segment
		(start 7.82193 -59.019948)
		(end 8.55218 -59.019948)
		(width 0.12954)
		(layer "F.Cu")
		(net "SMB_SML0_3V3AUX_SDA")
	)
	(via
		(at 8.55218 -59.019948)
		(size 0.508)
		(drill 0.254)
		(layers "F.Cu" "B.Cu")
		(net "SMB_SML0_3V3AUX_SDA")
	)
	(via
		(at 161.29 -14.569948)
		(size 0.508)
		(drill 0.254)
		(layers "F.Cu" "B.Cu")
		(net "SMB_SML0_3V3AUX_SDA")
	)
	(segment
		(start 161.29 -13.826998)
		(end 161.29 -14.569948)
		(width 0.12954)
		(layer "B.Cu")
		(net "SMB_SML0_3V3AUX_SDA")
	)
	(segment
		(start 161.29 -14.569948)
		(end 161.29 -15.312898)
		(width 0.12954)
		(layer "B.Cu")
		(net "SMB_SML0_3V3AUX_SDA")
	)
	(segment
		(start 82.605626 -40.300402)
		(end 90.372438 -40.300402)
		(width 0.127)
		(layer "In6.Cu")
		(net "SMB_SML0_3V3AUX_SDA")
	)
	(segment
		(start 99.660964 -36.497768)
		(end 102.51948 -33.639252)
		(width 0.127)
		(layer "In6.Cu")
		(net "SMB_SML0_3V3AUX_SDA")
	)
	(segment
		(start 102.51948 -30.668976)
		(end 105.435908 -27.752548)
		(width 0.127)
		(layer "In6.Cu")
		(net "SMB_SML0_3V3AUX_SDA")
	)
	(segment
		(start 24.798528 -49.420526)
		(end 45.338746 -49.420526)
		(width 0.127)
		(layer "In6.Cu")
		(net "SMB_SML0_3V3AUX_SDA")
	)
	(segment
		(start 162.37458 -15.654528)
		(end 161.29 -14.569948)
		(width 0.127)
		(layer "In6.Cu")
		(net "SMB_SML0_3V3AUX_SDA")
	)
	(segment
		(start 8.55218 -59.019948)
		(end 9.348724 -59.816492)
		(width 0.127)
		(layer "In6.Cu")
		(net "SMB_SML0_3V3AUX_SDA")
	)
	(segment
		(start 156.470858 -28.793948)
		(end 161.69132 -23.573486)
		(width 0.127)
		(layer "In6.Cu")
		(net "SMB_SML0_3V3AUX_SDA")
	)
	(segment
		(start 102.51948 -33.639252)
		(end 102.51948 -30.668976)
		(width 0.127)
		(layer "In6.Cu")
		(net "SMB_SML0_3V3AUX_SDA")
	)
	(segment
		(start 9.348724 -59.816492)
		(end 10.236708 -59.816492)
		(width 0.127)
		(layer "In6.Cu")
		(net "SMB_SML0_3V3AUX_SDA")
	)
	(segment
		(start 10.236708 -59.816492)
		(end 13.537184 -56.516016)
		(width 0.127)
		(layer "In6.Cu")
		(net "SMB_SML0_3V3AUX_SDA")
	)
	(segment
		(start 94.175072 -36.497768)
		(end 99.660964 -36.497768)
		(width 0.127)
		(layer "In6.Cu")
		(net "SMB_SML0_3V3AUX_SDA")
	)
	(segment
		(start 125.497336 -35.033712)
		(end 126.29642 -34.234628)
		(width 0.127)
		(layer "In6.Cu")
		(net "SMB_SML0_3V3AUX_SDA")
	)
	(segment
		(start 73.46188 -42.586148)
		(end 80.31988 -42.586148)
		(width 0.127)
		(layer "In6.Cu")
		(net "SMB_SML0_3V3AUX_SDA")
	)
	(segment
		(start 90.372438 -40.300402)
		(end 94.175072 -36.497768)
		(width 0.127)
		(layer "In6.Cu")
		(net "SMB_SML0_3V3AUX_SDA")
	)
	(segment
		(start 68.96608 -41.900348)
		(end 69.24548 -42.179748)
		(width 0.127)
		(layer "In6.Cu")
		(net "SMB_SML0_3V3AUX_SDA")
	)
	(segment
		(start 13.537184 -56.516016)
		(end 17.703038 -56.516016)
		(width 0.127)
		(layer "In6.Cu")
		(net "SMB_SML0_3V3AUX_SDA")
	)
	(segment
		(start 161.69132 -23.573486)
		(end 161.69132 -21.133308)
		(width 0.127)
		(layer "In6.Cu")
		(net "SMB_SML0_3V3AUX_SDA")
	)
	(segment
		(start 52.858924 -41.900348)
		(end 68.96608 -41.900348)
		(width 0.127)
		(layer "In6.Cu")
		(net "SMB_SML0_3V3AUX_SDA")
	)
	(segment
		(start 118.230904 -35.033712)
		(end 125.497336 -35.033712)
		(width 0.127)
		(layer "In6.Cu")
		(net "SMB_SML0_3V3AUX_SDA")
	)
	(segment
		(start 139.466574 -28.793948)
		(end 156.470858 -28.793948)
		(width 0.127)
		(layer "In6.Cu")
		(net "SMB_SML0_3V3AUX_SDA")
	)
	(segment
		(start 73.05548 -42.179748)
		(end 73.46188 -42.586148)
		(width 0.127)
		(layer "In6.Cu")
		(net "SMB_SML0_3V3AUX_SDA")
	)
	(segment
		(start 17.703038 -56.516016)
		(end 24.798528 -49.420526)
		(width 0.127)
		(layer "In6.Cu")
		(net "SMB_SML0_3V3AUX_SDA")
	)
	(segment
		(start 45.338746 -49.420526)
		(end 52.858924 -41.900348)
		(width 0.127)
		(layer "In6.Cu")
		(net "SMB_SML0_3V3AUX_SDA")
	)
	(segment
		(start 105.435908 -27.752548)
		(end 110.94974 -27.752548)
		(width 0.127)
		(layer "In6.Cu")
		(net "SMB_SML0_3V3AUX_SDA")
	)
	(segment
		(start 161.69132 -21.133308)
		(end 162.37458 -20.450048)
		(width 0.127)
		(layer "In6.Cu")
		(net "SMB_SML0_3V3AUX_SDA")
	)
	(segment
		(start 80.31988 -42.586148)
		(end 82.605626 -40.300402)
		(width 0.127)
		(layer "In6.Cu")
		(net "SMB_SML0_3V3AUX_SDA")
	)
	(segment
		(start 134.025894 -34.234628)
		(end 139.466574 -28.793948)
		(width 0.127)
		(layer "In6.Cu")
		(net "SMB_SML0_3V3AUX_SDA")
	)
	(segment
		(start 110.94974 -27.752548)
		(end 118.230904 -35.033712)
		(width 0.127)
		(layer "In6.Cu")
		(net "SMB_SML0_3V3AUX_SDA")
	)
	(segment
		(start 162.37458 -20.450048)
		(end 162.37458 -15.654528)
		(width 0.127)
		(layer "In6.Cu")
		(net "SMB_SML0_3V3AUX_SDA")
	)
	(segment
		(start 126.29642 -34.234628)
		(end 134.025894 -34.234628)
		(width 0.127)
		(layer "In6.Cu")
		(net "SMB_SML0_3V3AUX_SDA")
	)
	(segment
		(start 69.24548 -42.179748)
		(end 73.05548 -42.179748)
		(width 0.127)
		(layer "In6.Cu")
		(net "SMB_SML0_3V3AUX_SDA")
	)
	(segment
		(start 8.55218 -61.051948)
		(end 9.18083 -61.051948)
		(width 0.12954)
		(layer "F.Cu")
		(net "SMB_SML0_3V3AUX_SCL")
	)
	(segment
		(start 7.82193 -61.051948)
		(end 8.55218 -61.051948)
		(width 0.12954)
		(layer "F.Cu")
		(net "SMB_SML0_3V3AUX_SCL")
	)
	(via
		(at 8.55218 -61.051948)
		(size 0.508)
		(drill 0.254)
		(layers "F.Cu" "B.Cu")
		(net "SMB_SML0_3V3AUX_SCL")
	)
	(via
		(at 162.179 -14.569948)
		(size 0.508)
		(drill 0.254)
		(layers "F.Cu" "B.Cu")
		(net "SMB_SML0_3V3AUX_SCL")
	)
	(segment
		(start 162.179 -15.185898)
		(end 162.306 -15.312898)
		(width 0.12954)
		(layer "B.Cu")
		(net "SMB_SML0_3V3AUX_SCL")
	)
	(segment
		(start 162.179 -14.569948)
		(end 162.179 -15.185898)
		(width 0.12954)
		(layer "B.Cu")
		(net "SMB_SML0_3V3AUX_SCL")
	)
	(segment
		(start 162.179 -13.953998)
		(end 162.179 -14.569948)
		(width 0.12954)
		(layer "B.Cu")
		(net "SMB_SML0_3V3AUX_SCL")
	)
	(segment
		(start 162.306 -13.826998)
		(end 162.179 -13.953998)
		(width 0.12954)
		(layer "B.Cu")
		(net "SMB_SML0_3V3AUX_SCL")
	)
	(segment
		(start 162.13074 -23.74519)
		(end 162.13074 -21.397468)
		(width 0.127)
		(layer "In6.Cu")
		(net "SMB_SML0_3V3AUX_SCL")
	)
	(segment
		(start 139.72286 -29.225748)
		(end 156.650182 -29.225748)
		(width 0.127)
		(layer "In6.Cu")
		(net "SMB_SML0_3V3AUX_SCL")
	)
	(segment
		(start 102.95128 -30.848046)
		(end 105.614978 -28.184348)
		(width 0.127)
		(layer "In6.Cu")
		(net "SMB_SML0_3V3AUX_SCL")
	)
	(segment
		(start 110.77067 -28.184348)
		(end 118.051834 -35.465512)
		(width 0.127)
		(layer "In6.Cu")
		(net "SMB_SML0_3V3AUX_SCL")
	)
	(segment
		(start 52.910994 -42.459148)
		(end 68.48348 -42.459148)
		(width 0.127)
		(layer "In6.Cu")
		(net "SMB_SML0_3V3AUX_SCL")
	)
	(segment
		(start 118.051834 -35.465512)
		(end 125.720856 -35.465512)
		(width 0.127)
		(layer "In6.Cu")
		(net "SMB_SML0_3V3AUX_SCL")
	)
	(segment
		(start 8.55218 -61.051948)
		(end 9.355836 -60.248292)
		(width 0.127)
		(layer "In6.Cu")
		(net "SMB_SML0_3V3AUX_SCL")
	)
	(segment
		(start 105.614978 -28.184348)
		(end 110.77067 -28.184348)
		(width 0.127)
		(layer "In6.Cu")
		(net "SMB_SML0_3V3AUX_SCL")
	)
	(segment
		(start 156.650182 -29.225748)
		(end 162.13074 -23.74519)
		(width 0.127)
		(layer "In6.Cu")
		(net "SMB_SML0_3V3AUX_SCL")
	)
	(segment
		(start 126.46152 -34.724848)
		(end 134.22376 -34.724848)
		(width 0.127)
		(layer "In6.Cu")
		(net "SMB_SML0_3V3AUX_SCL")
	)
	(segment
		(start 162.13074 -21.397468)
		(end 162.89782 -20.630388)
		(width 0.127)
		(layer "In6.Cu")
		(net "SMB_SML0_3V3AUX_SCL")
	)
	(segment
		(start 125.720856 -35.465512)
		(end 126.46152 -34.724848)
		(width 0.127)
		(layer "In6.Cu")
		(net "SMB_SML0_3V3AUX_SCL")
	)
	(segment
		(start 45.517816 -49.852326)
		(end 52.910994 -42.459148)
		(width 0.127)
		(layer "In6.Cu")
		(net "SMB_SML0_3V3AUX_SCL")
	)
	(segment
		(start 19.12874 -56.947816)
		(end 26.22423 -49.852326)
		(width 0.127)
		(layer "In6.Cu")
		(net "SMB_SML0_3V3AUX_SCL")
	)
	(segment
		(start 162.89782 -20.630388)
		(end 162.89782 -15.288768)
		(width 0.127)
		(layer "In6.Cu")
		(net "SMB_SML0_3V3AUX_SCL")
	)
	(segment
		(start 80.448404 -43.068748)
		(end 82.78495 -40.732202)
		(width 0.127)
		(layer "In6.Cu")
		(net "SMB_SML0_3V3AUX_SCL")
	)
	(segment
		(start 72.78116 -42.687748)
		(end 73.16216 -43.068748)
		(width 0.127)
		(layer "In6.Cu")
		(net "SMB_SML0_3V3AUX_SCL")
	)
	(segment
		(start 162.89782 -15.288768)
		(end 162.179 -14.569948)
		(width 0.127)
		(layer "In6.Cu")
		(net "SMB_SML0_3V3AUX_SCL")
	)
	(segment
		(start 9.355836 -60.248292)
		(end 10.415778 -60.248292)
		(width 0.127)
		(layer "In6.Cu")
		(net "SMB_SML0_3V3AUX_SCL")
	)
	(segment
		(start 13.716254 -56.947816)
		(end 19.12874 -56.947816)
		(width 0.127)
		(layer "In6.Cu")
		(net "SMB_SML0_3V3AUX_SCL")
	)
	(segment
		(start 73.16216 -43.068748)
		(end 80.448404 -43.068748)
		(width 0.127)
		(layer "In6.Cu")
		(net "SMB_SML0_3V3AUX_SCL")
	)
	(segment
		(start 134.22376 -34.724848)
		(end 139.72286 -29.225748)
		(width 0.127)
		(layer "In6.Cu")
		(net "SMB_SML0_3V3AUX_SCL")
	)
	(segment
		(start 68.48348 -42.459148)
		(end 68.71208 -42.687748)
		(width 0.127)
		(layer "In6.Cu")
		(net "SMB_SML0_3V3AUX_SCL")
	)
	(segment
		(start 26.22423 -49.852326)
		(end 45.517816 -49.852326)
		(width 0.127)
		(layer "In6.Cu")
		(net "SMB_SML0_3V3AUX_SCL")
	)
	(segment
		(start 102.95128 -33.818322)
		(end 102.95128 -30.848046)
		(width 0.127)
		(layer "In6.Cu")
		(net "SMB_SML0_3V3AUX_SCL")
	)
	(segment
		(start 68.71208 -42.687748)
		(end 72.78116 -42.687748)
		(width 0.127)
		(layer "In6.Cu")
		(net "SMB_SML0_3V3AUX_SCL")
	)
	(segment
		(start 10.415778 -60.248292)
		(end 13.716254 -56.947816)
		(width 0.127)
		(layer "In6.Cu")
		(net "SMB_SML0_3V3AUX_SCL")
	)
	(segment
		(start 90.551508 -40.732202)
		(end 94.354142 -36.929568)
		(width 0.127)
		(layer "In6.Cu")
		(net "SMB_SML0_3V3AUX_SCL")
	)
	(segment
		(start 94.354142 -36.929568)
		(end 99.840034 -36.929568)
		(width 0.127)
		(layer "In6.Cu")
		(net "SMB_SML0_3V3AUX_SCL")
	)
	(segment
		(start 82.78495 -40.732202)
		(end 90.551508 -40.732202)
		(width 0.127)
		(layer "In6.Cu")
		(net "SMB_SML0_3V3AUX_SCL")
	)
	(segment
		(start 99.840034 -36.929568)
		(end 102.95128 -33.818322)
		(width 0.127)
		(layer "In6.Cu")
		(net "SMB_SML0_3V3AUX_SCL")
	)
	(segment
		(start 326.902064 -40.786558)
		(end 327.1012 -40.786558)
		(width 0.0889)
		(layer "F.Cu")
		(net "SMB_SML0_3V3AUX_PCH_SDA")
	)
	(segment
		(start 319.12814 -34.665158)
		(end 319.783968 -34.665158)
		(width 0.12954)
		(layer "F.Cu")
		(net "SMB_SML0_3V3AUX_PCH_SDA")
	)
	(segment
		(start 326.718422 -40.665146)
		(end 326.721978 -40.66667)
		(width 0.0889)
		(layer "F.Cu")
		(net "SMB_SML0_3V3AUX_PCH_SDA")
	)
	(segment
		(start 326.453754 -40.652954)
		(end 326.718422 -40.665146)
		(width 0.0889)
		(layer "F.Cu")
		(net "SMB_SML0_3V3AUX_PCH_SDA")
	)
	(segment
		(start 315.22289 -29.057346)
		(end 315.760862 -31.761684)
		(width 0.12954)
		(layer "F.Cu")
		(net "SMB_SML0_3V3AUX_PCH_SDA")
	)
	(segment
		(start 326.721978 -40.66667)
		(end 326.902064 -40.786558)
		(width 0.0889)
		(layer "F.Cu")
		(net "SMB_SML0_3V3AUX_PCH_SDA")
	)
	(segment
		(start 325.962264 -40.675814)
		(end 326.338184 -40.675814)
		(width 0.0889)
		(layer "F.Cu")
		(net "SMB_SML0_3V3AUX_PCH_SDA")
	)
	(segment
		(start 322.266818 -37.148008)
		(end 322.434458 -37.148008)
		(width 0.12954)
		(layer "F.Cu")
		(net "SMB_SML0_3V3AUX_PCH_SDA")
	)
	(segment
		(start 327.1012 -40.786558)
		(end 327.441306 -40.446452)
		(width 0.0889)
		(layer "F.Cu")
		(net "SMB_SML0_3V3AUX_PCH_SDA")
	)
	(segment
		(start 315.760862 -31.761684)
		(end 317.159386 -32.696404)
		(width 0.12954)
		(layer "F.Cu")
		(net "SMB_SML0_3V3AUX_PCH_SDA")
	)
	(segment
		(start 326.338184 -40.675814)
		(end 326.453754 -40.652954)
		(width 0.0889)
		(layer "F.Cu")
		(net "SMB_SML0_3V3AUX_PCH_SDA")
	)
	(segment
		(start 322.434458 -37.148008)
		(end 324.970394 -39.683944)
		(width 0.12954)
		(layer "F.Cu")
		(net "SMB_SML0_3V3AUX_PCH_SDA")
	)
	(segment
		(start 7.02183 -59.019948)
		(end 6.27888 -59.019948)
		(width 0.12954)
		(layer "F.Cu")
		(net "SMB_SML0_3V3AUX_PCH_SDA")
	)
	(segment
		(start 319.783968 -34.665158)
		(end 322.266818 -37.148008)
		(width 0.12954)
		(layer "F.Cu")
		(net "SMB_SML0_3V3AUX_PCH_SDA")
	)
	(segment
		(start 324.970394 -39.683944)
		(end 325.962264 -40.675814)
		(width 0.0889)
		(layer "F.Cu")
		(net "SMB_SML0_3V3AUX_PCH_SDA")
	)
	(segment
		(start 327.441306 -40.446452)
		(end 327.829926 -40.446452)
		(width 0.0889)
		(layer "F.Cu")
		(net "SMB_SML0_3V3AUX_PCH_SDA")
	)
	(segment
		(start 317.159386 -32.696404)
		(end 319.12814 -34.665158)
		(width 0.12954)
		(layer "F.Cu")
		(net "SMB_SML0_3V3AUX_PCH_SDA")
	)
	(via
		(at 285.74619 -76.854812)
		(size 0.508)
		(drill 0.254)
		(layers "F.Cu" "B.Cu")
		(net "SMB_SML0_3V3AUX_PCH_SDA")
	)
	(via
		(at 315.22289 -29.057346)
		(size 0.508)
		(drill 0.254)
		(layers "F.Cu" "B.Cu")
		(net "SMB_SML0_3V3AUX_PCH_SDA")
	)
	(via
		(at 6.27888 -59.019948)
		(size 0.508)
		(drill 0.254)
		(layers "F.Cu" "B.Cu")
		(net "SMB_SML0_3V3AUX_PCH_SDA")
	)
	(segment
		(start 285.22295 -76.495148)
		(end 283.57068 -74.842878)
		(width 0.127)
		(layer "In2.Cu")
		(net "SMB_SML0_3V3AUX_PCH_SDA")
	)
	(segment
		(start 266.37488 -38.263068)
		(end 264.52449 -36.412678)
		(width 0.127)
		(layer "In2.Cu")
		(net "SMB_SML0_3V3AUX_PCH_SDA")
	)
	(segment
		(start 266.37488 -41.620948)
		(end 266.37488 -38.263068)
		(width 0.127)
		(layer "In2.Cu")
		(net "SMB_SML0_3V3AUX_PCH_SDA")
	)
	(segment
		(start 267.59408 -42.840148)
		(end 266.37488 -41.620948)
		(width 0.127)
		(layer "In2.Cu")
		(net "SMB_SML0_3V3AUX_PCH_SDA")
	)
	(segment
		(start 283.57068 -52.744624)
		(end 273.666204 -42.840148)
		(width 0.127)
		(layer "In2.Cu")
		(net "SMB_SML0_3V3AUX_PCH_SDA")
	)
	(segment
		(start 283.57068 -74.842878)
		(end 283.57068 -52.744624)
		(width 0.127)
		(layer "In2.Cu")
		(net "SMB_SML0_3V3AUX_PCH_SDA")
	)
	(segment
		(start 273.666204 -42.840148)
		(end 267.59408 -42.840148)
		(width 0.127)
		(layer "In2.Cu")
		(net "SMB_SML0_3V3AUX_PCH_SDA")
	)
	(segment
		(start 285.74619 -76.854812)
		(end 285.386526 -76.495148)
		(width 0.127)
		(layer "In2.Cu")
		(net "SMB_SML0_3V3AUX_PCH_SDA")
	)
	(segment
		(start 285.386526 -76.495148)
		(end 285.22295 -76.495148)
		(width 0.127)
		(layer "In2.Cu")
		(net "SMB_SML0_3V3AUX_PCH_SDA")
	)
	(segment
		(start 245.49608 -83.704938)
		(end 240.23447 -88.966548)
		(width 0.127)
		(layer "In6.Cu")
		(net "SMB_SML0_3V3AUX_PCH_SDA")
	)
	(segment
		(start 149.208236 -67.452748)
		(end 148.197316 -66.441828)
		(width 0.127)
		(layer "In6.Cu")
		(net "SMB_SML0_3V3AUX_PCH_SDA")
	)
	(segment
		(start 276.86889 -83.704938)
		(end 245.49608 -83.704938)
		(width 0.127)
		(layer "In6.Cu")
		(net "SMB_SML0_3V3AUX_PCH_SDA")
	)
	(segment
		(start 285.74619 -76.854812)
		(end 283.719016 -76.854812)
		(width 0.127)
		(layer "In6.Cu")
		(net "SMB_SML0_3V3AUX_PCH_SDA")
	)
	(segment
		(start 153.924762 -70.703948)
		(end 150.673562 -67.452748)
		(width 0.127)
		(layer "In6.Cu")
		(net "SMB_SML0_3V3AUX_PCH_SDA")
	)
	(segment
		(start 20.533614 -63.041276)
		(end 7.887208 -63.041276)
		(width 0.127)
		(layer "In6.Cu")
		(net "SMB_SML0_3V3AUX_PCH_SDA")
	)
	(segment
		(start 192.967864 -82.256122)
		(end 175.975264 -82.256122)
		(width 0.127)
		(layer "In6.Cu")
		(net "SMB_SML0_3V3AUX_PCH_SDA")
	)
	(segment
		(start 57.90184 -56.51881)
		(end 27.05608 -56.51881)
		(width 0.127)
		(layer "In6.Cu")
		(net "SMB_SML0_3V3AUX_PCH_SDA")
	)
	(segment
		(start 7.887208 -63.041276)
		(end 7.04088 -62.194948)
		(width 0.127)
		(layer "In6.Cu")
		(net "SMB_SML0_3V3AUX_PCH_SDA")
	)
	(segment
		(start 150.673562 -67.452748)
		(end 149.208236 -67.452748)
		(width 0.127)
		(layer "In6.Cu")
		(net "SMB_SML0_3V3AUX_PCH_SDA")
	)
	(segment
		(start 240.23447 -88.966548)
		(end 212.396578 -88.966548)
		(width 0.127)
		(layer "In6.Cu")
		(net "SMB_SML0_3V3AUX_PCH_SDA")
	)
	(segment
		(start 175.975264 -82.256122)
		(end 164.42309 -70.703948)
		(width 0.127)
		(layer "In6.Cu")
		(net "SMB_SML0_3V3AUX_PCH_SDA")
	)
	(segment
		(start 193.489834 -82.778092)
		(end 192.967864 -82.256122)
		(width 0.127)
		(layer "In6.Cu")
		(net "SMB_SML0_3V3AUX_PCH_SDA")
	)
	(segment
		(start 7.04088 -62.194948)
		(end 7.04088 -59.781948)
		(width 0.127)
		(layer "In6.Cu")
		(net "SMB_SML0_3V3AUX_PCH_SDA")
	)
	(segment
		(start 7.04088 -59.781948)
		(end 6.27888 -59.019948)
		(width 0.127)
		(layer "In6.Cu")
		(net "SMB_SML0_3V3AUX_PCH_SDA")
	)
	(segment
		(start 206.208122 -82.778092)
		(end 193.489834 -82.778092)
		(width 0.127)
		(layer "In6.Cu")
		(net "SMB_SML0_3V3AUX_PCH_SDA")
	)
	(segment
		(start 69.013578 -67.630548)
		(end 57.90184 -56.51881)
		(width 0.127)
		(layer "In6.Cu")
		(net "SMB_SML0_3V3AUX_PCH_SDA")
	)
	(segment
		(start 135.31596 -66.441828)
		(end 134.12724 -67.630548)
		(width 0.127)
		(layer "In6.Cu")
		(net "SMB_SML0_3V3AUX_PCH_SDA")
	)
	(segment
		(start 283.719016 -76.854812)
		(end 276.86889 -83.704938)
		(width 0.127)
		(layer "In6.Cu")
		(net "SMB_SML0_3V3AUX_PCH_SDA")
	)
	(segment
		(start 134.12724 -67.630548)
		(end 69.013578 -67.630548)
		(width 0.127)
		(layer "In6.Cu")
		(net "SMB_SML0_3V3AUX_PCH_SDA")
	)
	(segment
		(start 148.197316 -66.441828)
		(end 135.31596 -66.441828)
		(width 0.127)
		(layer "In6.Cu")
		(net "SMB_SML0_3V3AUX_PCH_SDA")
	)
	(segment
		(start 212.396578 -88.966548)
		(end 206.208122 -82.778092)
		(width 0.127)
		(layer "In6.Cu")
		(net "SMB_SML0_3V3AUX_PCH_SDA")
	)
	(segment
		(start 27.05608 -56.51881)
		(end 20.533614 -63.041276)
		(width 0.127)
		(layer "In6.Cu")
		(net "SMB_SML0_3V3AUX_PCH_SDA")
	)
	(segment
		(start 164.42309 -70.703948)
		(end 153.924762 -70.703948)
		(width 0.127)
		(layer "In6.Cu")
		(net "SMB_SML0_3V3AUX_PCH_SDA")
	)
	(segment
		(start 309.5752 -42.390568)
		(end 293.188136 -42.390568)
		(width 0.127)
		(layer "In11.Cu")
		(net "SMB_SML0_3V3AUX_PCH_SDA")
	)
	(segment
		(start 315.22289 -32.683958)
		(end 316.03188 -33.492948)
		(width 0.127)
		(layer "In11.Cu")
		(net "SMB_SML0_3V3AUX_PCH_SDA")
	)
	(segment
		(start 266.50188 -41.824148)
		(end 266.50188 -38.390068)
		(width 0.127)
		(layer "In11.Cu")
		(net "SMB_SML0_3V3AUX_PCH_SDA")
	)
	(segment
		(start 273.361404 -42.535348)
		(end 267.21308 -42.535348)
		(width 0.127)
		(layer "In11.Cu")
		(net "SMB_SML0_3V3AUX_PCH_SDA")
	)
	(segment
		(start 309.81142 -42.154348)
		(end 309.5752 -42.390568)
		(width 0.127)
		(layer "In11.Cu")
		(net "SMB_SML0_3V3AUX_PCH_SDA")
	)
	(segment
		(start 289.690556 -45.888148)
		(end 276.714204 -45.888148)
		(width 0.127)
		(layer "In11.Cu")
		(net "SMB_SML0_3V3AUX_PCH_SDA")
	)
	(segment
		(start 293.188136 -42.390568)
		(end 289.690556 -45.888148)
		(width 0.127)
		(layer "In11.Cu")
		(net "SMB_SML0_3V3AUX_PCH_SDA")
	)
	(segment
		(start 315.22289 -29.057346)
		(end 315.22289 -32.683958)
		(width 0.127)
		(layer "In11.Cu")
		(net "SMB_SML0_3V3AUX_PCH_SDA")
	)
	(segment
		(start 316.03188 -39.080948)
		(end 312.95848 -42.154348)
		(width 0.127)
		(layer "In11.Cu")
		(net "SMB_SML0_3V3AUX_PCH_SDA")
	)
	(segment
		(start 312.95848 -42.154348)
		(end 309.81142 -42.154348)
		(width 0.127)
		(layer "In11.Cu")
		(net "SMB_SML0_3V3AUX_PCH_SDA")
	)
	(segment
		(start 276.714204 -45.888148)
		(end 273.361404 -42.535348)
		(width 0.127)
		(layer "In11.Cu")
		(net "SMB_SML0_3V3AUX_PCH_SDA")
	)
	(segment
		(start 316.03188 -33.492948)
		(end 316.03188 -39.080948)
		(width 0.127)
		(layer "In11.Cu")
		(net "SMB_SML0_3V3AUX_PCH_SDA")
	)
	(segment
		(start 267.21308 -42.535348)
		(end 266.50188 -41.824148)
		(width 0.127)
		(layer "In11.Cu")
		(net "SMB_SML0_3V3AUX_PCH_SDA")
	)
	(segment
		(start 266.50188 -38.390068)
		(end 264.52449 -36.412678)
		(width 0.127)
		(layer "In11.Cu")
		(net "SMB_SML0_3V3AUX_PCH_SDA")
	)
	(segment
		(start 326.828404 -39.73957)
		(end 327.034652 -39.773606)
		(width 0.0889)
		(layer "F.Cu")
		(net "SMB_SML0_3V3AUX_PCH_SCL")
	)
	(segment
		(start 325.828152 -38.818312)
		(end 326.061832 -39.051992)
		(width 0.0889)
		(layer "F.Cu")
		(net "SMB_SML0_3V3AUX_PCH_SCL")
	)
	(segment
		(start 320.937382 -30.430724)
		(end 319.695576 -32.288734)
		(width 0.12954)
		(layer "F.Cu")
		(net "SMB_SML0_3V3AUX_PCH_SCL")
	)
	(segment
		(start 319.695576 -33.018222)
		(end 320.033142 -33.355788)
		(width 0.12954)
		(layer "F.Cu")
		(net "SMB_SML0_3V3AUX_PCH_SCL")
	)
	(segment
		(start 320.033142 -33.355788)
		(end 320.365628 -33.355788)
		(width 0.12954)
		(layer "F.Cu")
		(net "SMB_SML0_3V3AUX_PCH_SCL")
	)
	(segment
		(start 318.652906 -29.949648)
		(end 320.734436 -29.949648)
		(width 0.12954)
		(layer "F.Cu")
		(net "SMB_SML0_3V3AUX_PCH_SCL")
	)
	(segment
		(start 319.695576 -32.288734)
		(end 319.695576 -33.018222)
		(width 0.12954)
		(layer "F.Cu")
		(net "SMB_SML0_3V3AUX_PCH_SCL")
	)
	(segment
		(start 327.069196 -39.756588)
		(end 327.22312 -39.680642)
		(width 0.0889)
		(layer "F.Cu")
		(net "SMB_SML0_3V3AUX_PCH_SCL")
	)
	(segment
		(start 320.734436 -29.949648)
		(end 320.937382 -30.152594)
		(width 0.12954)
		(layer "F.Cu")
		(net "SMB_SML0_3V3AUX_PCH_SCL")
	)
	(segment
		(start 318.48298 -29.301694)
		(end 318.48298 -29.779722)
		(width 0.12954)
		(layer "F.Cu")
		(net "SMB_SML0_3V3AUX_PCH_SCL")
	)
	(segment
		(start 327.034652 -39.773606)
		(end 327.069196 -39.756588)
		(width 0.0889)
		(layer "F.Cu")
		(net "SMB_SML0_3V3AUX_PCH_SCL")
	)
	(segment
		(start 318.681608 -29.103066)
		(end 318.48298 -29.301694)
		(width 0.12954)
		(layer "F.Cu")
		(net "SMB_SML0_3V3AUX_PCH_SCL")
	)
	(segment
		(start 320.937382 -30.152594)
		(end 320.937382 -30.430724)
		(width 0.12954)
		(layer "F.Cu")
		(net "SMB_SML0_3V3AUX_PCH_SCL")
	)
	(segment
		(start 319.425574 -29.103066)
		(end 318.681608 -29.103066)
		(width 0.12954)
		(layer "F.Cu")
		(net "SMB_SML0_3V3AUX_PCH_SCL")
	)
	(segment
		(start 320.365628 -33.355788)
		(end 325.828152 -38.818312)
		(width 0.12954)
		(layer "F.Cu")
		(net "SMB_SML0_3V3AUX_PCH_SCL")
	)
	(segment
		(start 327.22312 -39.680642)
		(end 327.495154 -39.445946)
		(width 0.0889)
		(layer "F.Cu")
		(net "SMB_SML0_3V3AUX_PCH_SCL")
	)
	(segment
		(start 318.48298 -29.779722)
		(end 318.652906 -29.949648)
		(width 0.12954)
		(layer "F.Cu")
		(net "SMB_SML0_3V3AUX_PCH_SCL")
	)
	(segment
		(start 326.140826 -39.051992)
		(end 326.828404 -39.73957)
		(width 0.0889)
		(layer "F.Cu")
		(net "SMB_SML0_3V3AUX_PCH_SCL")
	)
	(segment
		(start 7.02183 -61.051948)
		(end 6.27888 -61.051948)
		(width 0.12954)
		(layer "F.Cu")
		(net "SMB_SML0_3V3AUX_PCH_SCL")
	)
	(segment
		(start 326.061832 -39.051992)
		(end 326.140826 -39.051992)
		(width 0.0889)
		(layer "F.Cu")
		(net "SMB_SML0_3V3AUX_PCH_SCL")
	)
	(segment
		(start 327.495154 -39.445946)
		(end 327.829926 -39.445946)
		(width 0.0889)
		(layer "F.Cu")
		(net "SMB_SML0_3V3AUX_PCH_SCL")
	)
	(via
		(at 319.425574 -29.103066)
		(size 0.508)
		(drill 0.254)
		(layers "F.Cu" "B.Cu")
		(net "SMB_SML0_3V3AUX_PCH_SCL")
	)
	(via
		(at 6.27888 -61.051948)
		(size 0.508)
		(drill 0.254)
		(layers "F.Cu" "B.Cu")
		(net "SMB_SML0_3V3AUX_PCH_SCL")
	)
	(via
		(at 285.002986 -77.640942)
		(size 0.508)
		(drill 0.254)
		(layers "F.Cu" "B.Cu")
		(net "SMB_SML0_3V3AUX_PCH_SCL")
	)
	(segment
		(start 283.01188 -54.461918)
		(end 283.13888 -54.334918)
		(width 0.127)
		(layer "In2.Cu")
		(net "SMB_SML0_3V3AUX_PCH_SCL")
	)
	(segment
		(start 283.13888 -57.179718)
		(end 283.01188 -57.052718)
		(width 0.127)
		(layer "In2.Cu")
		(net "SMB_SML0_3V3AUX_PCH_SCL")
	)
	(segment
		(start 273.48688 -43.271948)
		(end 266.30376 -43.271948)
		(width 0.127)
		(layer "In2.Cu")
		(net "SMB_SML0_3V3AUX_PCH_SCL")
	)
	(segment
		(start 281.99842 -56.316118)
		(end 282.12542 -56.189118)
		(width 0.127)
		(layer "In2.Cu")
		(net "SMB_SML0_3V3AUX_PCH_SCL")
	)
	(segment
		(start 281.99842 -56.925718)
		(end 281.99842 -56.316118)
		(width 0.127)
		(layer "In2.Cu")
		(net "SMB_SML0_3V3AUX_PCH_SCL")
	)
	(segment
		(start 283.13888 -54.334918)
		(end 283.13888 -52.923948)
		(width 0.127)
		(layer "In2.Cu")
		(net "SMB_SML0_3V3AUX_PCH_SCL")
	)
	(segment
		(start 283.01188 -55.325518)
		(end 282.12542 -55.325518)
		(width 0.127)
		(layer "In2.Cu")
		(net "SMB_SML0_3V3AUX_PCH_SCL")
	)
	(segment
		(start 281.99842 -54.588918)
		(end 282.12542 -54.461918)
		(width 0.127)
		(layer "In2.Cu")
		(net "SMB_SML0_3V3AUX_PCH_SCL")
	)
	(segment
		(start 285.002986 -77.640942)
		(end 285.002986 -76.886054)
		(width 0.127)
		(layer "In2.Cu")
		(net "SMB_SML0_3V3AUX_PCH_SCL")
	)
	(segment
		(start 283.13888 -75.021948)
		(end 283.13888 -57.179718)
		(width 0.127)
		(layer "In2.Cu")
		(net "SMB_SML0_3V3AUX_PCH_SCL")
	)
	(segment
		(start 283.13888 -52.923948)
		(end 273.48688 -43.271948)
		(width 0.127)
		(layer "In2.Cu")
		(net "SMB_SML0_3V3AUX_PCH_SCL")
	)
	(segment
		(start 282.12542 -55.325518)
		(end 281.99842 -55.198518)
		(width 0.127)
		(layer "In2.Cu")
		(net "SMB_SML0_3V3AUX_PCH_SCL")
	)
	(segment
		(start 283.01188 -56.189118)
		(end 283.13888 -56.062118)
		(width 0.127)
		(layer "In2.Cu")
		(net "SMB_SML0_3V3AUX_PCH_SCL")
	)
	(segment
		(start 285.002986 -76.886054)
		(end 283.13888 -75.021948)
		(width 0.127)
		(layer "In2.Cu")
		(net "SMB_SML0_3V3AUX_PCH_SCL")
	)
	(segment
		(start 282.12542 -56.189118)
		(end 283.01188 -56.189118)
		(width 0.127)
		(layer "In2.Cu")
		(net "SMB_SML0_3V3AUX_PCH_SCL")
	)
	(segment
		(start 283.01188 -57.052718)
		(end 282.12542 -57.052718)
		(width 0.127)
		(layer "In2.Cu")
		(net "SMB_SML0_3V3AUX_PCH_SCL")
	)
	(segment
		(start 266.30376 -43.271948)
		(end 264.52449 -41.492678)
		(width 0.127)
		(layer "In2.Cu")
		(net "SMB_SML0_3V3AUX_PCH_SCL")
	)
	(segment
		(start 283.13888 -56.062118)
		(end 283.13888 -55.452518)
		(width 0.127)
		(layer "In2.Cu")
		(net "SMB_SML0_3V3AUX_PCH_SCL")
	)
	(segment
		(start 283.13888 -55.452518)
		(end 283.01188 -55.325518)
		(width 0.127)
		(layer "In2.Cu")
		(net "SMB_SML0_3V3AUX_PCH_SCL")
	)
	(segment
		(start 282.12542 -57.052718)
		(end 281.99842 -56.925718)
		(width 0.127)
		(layer "In2.Cu")
		(net "SMB_SML0_3V3AUX_PCH_SCL")
	)
	(segment
		(start 282.12542 -54.461918)
		(end 283.01188 -54.461918)
		(width 0.127)
		(layer "In2.Cu")
		(net "SMB_SML0_3V3AUX_PCH_SCL")
	)
	(segment
		(start 281.99842 -55.198518)
		(end 281.99842 -54.588918)
		(width 0.127)
		(layer "In2.Cu")
		(net "SMB_SML0_3V3AUX_PCH_SCL")
	)
	(segment
		(start 279.54097 -82.453226)
		(end 279.54097 -82.63255)
		(width 0.127)
		(layer "In6.Cu")
		(net "SMB_SML0_3V3AUX_PCH_SCL")
	)
	(segment
		(start 279.54097 -82.63255)
		(end 279.109424 -83.064096)
		(width 0.127)
		(layer "In6.Cu")
		(net "SMB_SML0_3V3AUX_PCH_SCL")
	)
	(segment
		(start 164.24402 -71.135748)
		(end 153.745692 -71.135748)
		(width 0.127)
		(layer "In6.Cu")
		(net "SMB_SML0_3V3AUX_PCH_SCL")
	)
	(segment
		(start 279.22601 -82.138012)
		(end 279.54097 -82.453226)
		(width 0.127)
		(layer "In6.Cu")
		(net "SMB_SML0_3V3AUX_PCH_SCL")
	)
	(segment
		(start 148.017992 -66.873628)
		(end 135.67918 -66.873628)
		(width 0.127)
		(layer "In6.Cu")
		(net "SMB_SML0_3V3AUX_PCH_SCL")
	)
	(segment
		(start 68.834508 -68.062348)
		(end 57.72277 -56.95061)
		(width 0.127)
		(layer "In6.Cu")
		(net "SMB_SML0_3V3AUX_PCH_SCL")
	)
	(segment
		(start 6.27888 -62.448948)
		(end 6.27888 -61.051948)
		(width 0.127)
		(layer "In6.Cu")
		(net "SMB_SML0_3V3AUX_PCH_SCL")
	)
	(segment
		(start 57.72277 -56.95061)
		(end 27.23515 -56.95061)
		(width 0.127)
		(layer "In6.Cu")
		(net "SMB_SML0_3V3AUX_PCH_SCL")
	)
	(segment
		(start 278.61514 -82.748882)
		(end 278.435816 -82.748882)
		(width 0.127)
		(layer "In6.Cu")
		(net "SMB_SML0_3V3AUX_PCH_SCL")
	)
	(segment
		(start 279.109424 -83.064096)
		(end 278.9301 -83.064096)
		(width 0.127)
		(layer "In6.Cu")
		(net "SMB_SML0_3V3AUX_PCH_SCL")
	)
	(segment
		(start 280.76271 -81.41081)
		(end 280.331164 -81.842356)
		(width 0.127)
		(layer "In6.Cu")
		(net "SMB_SML0_3V3AUX_PCH_SCL")
	)
	(segment
		(start 280.44775 -80.916272)
		(end 280.76271 -81.231486)
		(width 0.127)
		(layer "In6.Cu")
		(net "SMB_SML0_3V3AUX_PCH_SCL")
	)
	(segment
		(start 135.67918 -66.873628)
		(end 134.49046 -68.062348)
		(width 0.127)
		(layer "In6.Cu")
		(net "SMB_SML0_3V3AUX_PCH_SCL")
	)
	(segment
		(start 283.543756 -77.640942)
		(end 280.44775 -80.736948)
		(width 0.127)
		(layer "In6.Cu")
		(net "SMB_SML0_3V3AUX_PCH_SCL")
	)
	(segment
		(start 279.657556 -81.527142)
		(end 279.22601 -81.958688)
		(width 0.127)
		(layer "In6.Cu")
		(net "SMB_SML0_3V3AUX_PCH_SCL")
	)
	(segment
		(start 278.9301 -83.064096)
		(end 278.61514 -82.748882)
		(width 0.127)
		(layer "In6.Cu")
		(net "SMB_SML0_3V3AUX_PCH_SCL")
	)
	(segment
		(start 279.83688 -81.527142)
		(end 279.657556 -81.527142)
		(width 0.127)
		(layer "In6.Cu")
		(net "SMB_SML0_3V3AUX_PCH_SCL")
	)
	(segment
		(start 206.029052 -83.209892)
		(end 193.310764 -83.209892)
		(width 0.127)
		(layer "In6.Cu")
		(net "SMB_SML0_3V3AUX_PCH_SCL")
	)
	(segment
		(start 27.23515 -56.95061)
		(end 20.712684 -63.473076)
		(width 0.127)
		(layer "In6.Cu")
		(net "SMB_SML0_3V3AUX_PCH_SCL")
	)
	(segment
		(start 285.002986 -77.640942)
		(end 283.543756 -77.640942)
		(width 0.127)
		(layer "In6.Cu")
		(net "SMB_SML0_3V3AUX_PCH_SCL")
	)
	(segment
		(start 280.331164 -81.842356)
		(end 280.15184 -81.842356)
		(width 0.127)
		(layer "In6.Cu")
		(net "SMB_SML0_3V3AUX_PCH_SCL")
	)
	(segment
		(start 280.44775 -80.736948)
		(end 280.44775 -80.916272)
		(width 0.127)
		(layer "In6.Cu")
		(net "SMB_SML0_3V3AUX_PCH_SCL")
	)
	(segment
		(start 150.494492 -67.884548)
		(end 149.028912 -67.884548)
		(width 0.127)
		(layer "In6.Cu")
		(net "SMB_SML0_3V3AUX_PCH_SCL")
	)
	(segment
		(start 193.310764 -83.209892)
		(end 192.788794 -82.687922)
		(width 0.127)
		(layer "In6.Cu")
		(net "SMB_SML0_3V3AUX_PCH_SCL")
	)
	(segment
		(start 149.028912 -67.884548)
		(end 148.017992 -66.873628)
		(width 0.127)
		(layer "In6.Cu")
		(net "SMB_SML0_3V3AUX_PCH_SCL")
	)
	(segment
		(start 277.04796 -84.136738)
		(end 245.67515 -84.136738)
		(width 0.127)
		(layer "In6.Cu")
		(net "SMB_SML0_3V3AUX_PCH_SCL")
	)
	(segment
		(start 134.49046 -68.062348)
		(end 68.834508 -68.062348)
		(width 0.127)
		(layer "In6.Cu")
		(net "SMB_SML0_3V3AUX_PCH_SCL")
	)
	(segment
		(start 280.15184 -81.842356)
		(end 279.83688 -81.527142)
		(width 0.127)
		(layer "In6.Cu")
		(net "SMB_SML0_3V3AUX_PCH_SCL")
	)
	(segment
		(start 20.712684 -63.473076)
		(end 7.303008 -63.473076)
		(width 0.127)
		(layer "In6.Cu")
		(net "SMB_SML0_3V3AUX_PCH_SCL")
	)
	(segment
		(start 175.796194 -82.687922)
		(end 164.24402 -71.135748)
		(width 0.127)
		(layer "In6.Cu")
		(net "SMB_SML0_3V3AUX_PCH_SCL")
	)
	(segment
		(start 7.303008 -63.473076)
		(end 6.27888 -62.448948)
		(width 0.127)
		(layer "In6.Cu")
		(net "SMB_SML0_3V3AUX_PCH_SCL")
	)
	(segment
		(start 212.217508 -89.398348)
		(end 206.029052 -83.209892)
		(width 0.127)
		(layer "In6.Cu")
		(net "SMB_SML0_3V3AUX_PCH_SCL")
	)
	(segment
		(start 245.67515 -84.136738)
		(end 240.41354 -89.398348)
		(width 0.127)
		(layer "In6.Cu")
		(net "SMB_SML0_3V3AUX_PCH_SCL")
	)
	(segment
		(start 279.22601 -81.958688)
		(end 279.22601 -82.138012)
		(width 0.127)
		(layer "In6.Cu")
		(net "SMB_SML0_3V3AUX_PCH_SCL")
	)
	(segment
		(start 192.788794 -82.687922)
		(end 175.796194 -82.687922)
		(width 0.127)
		(layer "In6.Cu")
		(net "SMB_SML0_3V3AUX_PCH_SCL")
	)
	(segment
		(start 240.41354 -89.398348)
		(end 212.217508 -89.398348)
		(width 0.127)
		(layer "In6.Cu")
		(net "SMB_SML0_3V3AUX_PCH_SCL")
	)
	(segment
		(start 280.76271 -81.231486)
		(end 280.76271 -81.41081)
		(width 0.127)
		(layer "In6.Cu")
		(net "SMB_SML0_3V3AUX_PCH_SCL")
	)
	(segment
		(start 153.745692 -71.135748)
		(end 150.494492 -67.884548)
		(width 0.127)
		(layer "In6.Cu")
		(net "SMB_SML0_3V3AUX_PCH_SCL")
	)
	(segment
		(start 278.435816 -82.748882)
		(end 277.04796 -84.136738)
		(width 0.127)
		(layer "In6.Cu")
		(net "SMB_SML0_3V3AUX_PCH_SCL")
	)
	(segment
		(start 306.79771 -43.449748)
		(end 306.17033 -42.822368)
		(width 0.127)
		(layer "In11.Cu")
		(net "SMB_SML0_3V3AUX_PCH_SCL")
	)
	(segment
		(start 289.86988 -46.319948)
		(end 276.53488 -46.319948)
		(width 0.127)
		(layer "In11.Cu")
		(net "SMB_SML0_3V3AUX_PCH_SCL")
	)
	(segment
		(start 276.53488 -46.319948)
		(end 273.18208 -42.967148)
		(width 0.127)
		(layer "In11.Cu")
		(net "SMB_SML0_3V3AUX_PCH_SCL")
	)
	(segment
		(start 317.02248 -34.871406)
		(end 316.59068 -34.871406)
		(width 0.127)
		(layer "In11.Cu")
		(net "SMB_SML0_3V3AUX_PCH_SCL")
	)
	(segment
		(start 312.27395 -43.449748)
		(end 306.79771 -43.449748)
		(width 0.127)
		(layer "In11.Cu")
		(net "SMB_SML0_3V3AUX_PCH_SCL")
	)
	(segment
		(start 265.559286 -41.492678)
		(end 264.52449 -41.492678)
		(width 0.127)
		(layer "In11.Cu")
		(net "SMB_SML0_3V3AUX_PCH_SCL")
	)
	(segment
		(start 297.48988 -44.089828)
		(end 292.1 -44.089828)
		(width 0.127)
		(layer "In11.Cu")
		(net "SMB_SML0_3V3AUX_PCH_SCL")
	)
	(segment
		(start 316.46368 -33.313878)
		(end 316.46368 -33.880806)
		(width 0.127)
		(layer "In11.Cu")
		(net "SMB_SML0_3V3AUX_PCH_SCL")
	)
	(segment
		(start 317.14948 -34.744406)
		(end 317.02248 -34.871406)
		(width 0.127)
		(layer "In11.Cu")
		(net "SMB_SML0_3V3AUX_PCH_SCL")
	)
	(segment
		(start 267.033756 -42.967148)
		(end 265.559286 -41.492678)
		(width 0.127)
		(layer "In11.Cu")
		(net "SMB_SML0_3V3AUX_PCH_SCL")
	)
	(segment
		(start 316.59068 -34.007806)
		(end 317.02248 -34.007806)
		(width 0.127)
		(layer "In11.Cu")
		(net "SMB_SML0_3V3AUX_PCH_SCL")
	)
	(segment
		(start 316.46368 -39.260018)
		(end 312.27395 -43.449748)
		(width 0.127)
		(layer "In11.Cu")
		(net "SMB_SML0_3V3AUX_PCH_SCL")
	)
	(segment
		(start 273.18208 -42.967148)
		(end 267.033756 -42.967148)
		(width 0.127)
		(layer "In11.Cu")
		(net "SMB_SML0_3V3AUX_PCH_SCL")
	)
	(segment
		(start 317.02248 -34.007806)
		(end 317.14948 -34.134806)
		(width 0.127)
		(layer "In11.Cu")
		(net "SMB_SML0_3V3AUX_PCH_SCL")
	)
	(segment
		(start 298.75734 -42.822368)
		(end 297.48988 -44.089828)
		(width 0.127)
		(layer "In11.Cu")
		(net "SMB_SML0_3V3AUX_PCH_SCL")
	)
	(segment
		(start 316.59068 -34.871406)
		(end 316.46368 -34.998406)
		(width 0.127)
		(layer "In11.Cu")
		(net "SMB_SML0_3V3AUX_PCH_SCL")
	)
	(segment
		(start 292.1 -44.089828)
		(end 289.86988 -46.319948)
		(width 0.127)
		(layer "In11.Cu")
		(net "SMB_SML0_3V3AUX_PCH_SCL")
	)
	(segment
		(start 306.17033 -42.822368)
		(end 298.75734 -42.822368)
		(width 0.127)
		(layer "In11.Cu")
		(net "SMB_SML0_3V3AUX_PCH_SCL")
	)
	(segment
		(start 317.429134 -29.103066)
		(end 315.85789 -30.67431)
		(width 0.127)
		(layer "In11.Cu")
		(net "SMB_SML0_3V3AUX_PCH_SCL")
	)
	(segment
		(start 316.46368 -34.998406)
		(end 316.46368 -39.260018)
		(width 0.127)
		(layer "In11.Cu")
		(net "SMB_SML0_3V3AUX_PCH_SCL")
	)
	(segment
		(start 316.46368 -33.880806)
		(end 316.59068 -34.007806)
		(width 0.127)
		(layer "In11.Cu")
		(net "SMB_SML0_3V3AUX_PCH_SCL")
	)
	(segment
		(start 317.14948 -34.134806)
		(end 317.14948 -34.744406)
		(width 0.127)
		(layer "In11.Cu")
		(net "SMB_SML0_3V3AUX_PCH_SCL")
	)
	(segment
		(start 319.425574 -29.103066)
		(end 317.429134 -29.103066)
		(width 0.127)
		(layer "In11.Cu")
		(net "SMB_SML0_3V3AUX_PCH_SCL")
	)
	(segment
		(start 315.85789 -32.708088)
		(end 316.46368 -33.313878)
		(width 0.127)
		(layer "In11.Cu")
		(net "SMB_SML0_3V3AUX_PCH_SCL")
	)
	(segment
		(start 315.85789 -30.67431)
		(end 315.85789 -32.708088)
		(width 0.127)
		(layer "In11.Cu")
		(net "SMB_SML0_3V3AUX_PCH_SCL")
	)
	(segment
		(start 318.42329 -38.222428)
		(end 318.788542 -38.222428)
		(width 0.12954)
		(layer "F.Cu")
		(net "SMB_SML0B_3V3AUX_SDA")
	)
	(segment
		(start 309.122572 -35.479482)
		(end 309.417466 -35.184588)
		(width 0.12954)
		(layer "F.Cu")
		(net "SMB_SML0B_3V3AUX_SDA")
	)
	(segment
		(start 322.543424 -40.951658)
		(end 322.85305 -41.261284)
		(width 0.0889)
		(layer "F.Cu")
		(net "SMB_SML0B_3V3AUX_SDA")
	)
	(segment
		(start 324.633082 -42.658792)
		(end 326.729344 -42.658792)
		(width 0.0889)
		(layer "F.Cu")
		(net "SMB_SML0B_3V3AUX_SDA")
	)
	(segment
		(start 322.158868 -39.90467)
		(end 322.158868 -40.567102)
		(width 0.12954)
		(layer "F.Cu")
		(net "SMB_SML0B_3V3AUX_SDA")
	)
	(segment
		(start 321.683126 -39.428928)
		(end 322.158868 -39.90467)
		(width 0.12954)
		(layer "F.Cu")
		(net "SMB_SML0B_3V3AUX_SDA")
	)
	(segment
		(start 312.977276 -35.184588)
		(end 313.482736 -35.690048)
		(width 0.12954)
		(layer "F.Cu")
		(net "SMB_SML0B_3V3AUX_SDA")
	)
	(segment
		(start 326.861424 -42.746676)
		(end 327.130664 -42.746676)
		(width 0.0889)
		(layer "F.Cu")
		(net "SMB_SML0B_3V3AUX_SDA")
	)
	(segment
		(start 322.158868 -40.567102)
		(end 322.543424 -40.951658)
		(width 0.12954)
		(layer "F.Cu")
		(net "SMB_SML0B_3V3AUX_SDA")
	)
	(segment
		(start 314.300616 -36.180268)
		(end 316.38113 -36.180268)
		(width 0.12954)
		(layer "F.Cu")
		(net "SMB_SML0B_3V3AUX_SDA")
	)
	(segment
		(start 319.047622 -37.963348)
		(end 320.513202 -39.428928)
		(width 0.12954)
		(layer "F.Cu")
		(net "SMB_SML0B_3V3AUX_SDA")
	)
	(segment
		(start 318.788542 -38.222428)
		(end 319.047622 -37.963348)
		(width 0.12954)
		(layer "F.Cu")
		(net "SMB_SML0B_3V3AUX_SDA")
	)
	(segment
		(start 327.429876 -42.447464)
		(end 327.829926 -42.447464)
		(width 0.0889)
		(layer "F.Cu")
		(net "SMB_SML0B_3V3AUX_SDA")
	)
	(segment
		(start 313.482736 -35.690048)
		(end 313.810396 -35.690048)
		(width 0.12954)
		(layer "F.Cu")
		(net "SMB_SML0B_3V3AUX_SDA")
	)
	(segment
		(start 316.38113 -36.180268)
		(end 318.42329 -38.222428)
		(width 0.12954)
		(layer "F.Cu")
		(net "SMB_SML0B_3V3AUX_SDA")
	)
	(segment
		(start 309.122572 -35.804348)
		(end 309.122572 -35.479482)
		(width 0.12954)
		(layer "F.Cu")
		(net "SMB_SML0B_3V3AUX_SDA")
	)
	(segment
		(start 327.130664 -42.746676)
		(end 327.429876 -42.447464)
		(width 0.0889)
		(layer "F.Cu")
		(net "SMB_SML0B_3V3AUX_SDA")
	)
	(segment
		(start 323.235574 -41.261284)
		(end 324.633082 -42.658792)
		(width 0.0889)
		(layer "F.Cu")
		(net "SMB_SML0B_3V3AUX_SDA")
	)
	(segment
		(start 309.417466 -35.184588)
		(end 312.977276 -35.184588)
		(width 0.12954)
		(layer "F.Cu")
		(net "SMB_SML0B_3V3AUX_SDA")
	)
	(segment
		(start 322.85305 -41.261284)
		(end 323.235574 -41.261284)
		(width 0.0889)
		(layer "F.Cu")
		(net "SMB_SML0B_3V3AUX_SDA")
	)
	(segment
		(start 313.810396 -35.690048)
		(end 314.300616 -36.180268)
		(width 0.12954)
		(layer "F.Cu")
		(net "SMB_SML0B_3V3AUX_SDA")
	)
	(segment
		(start 326.729344 -42.658792)
		(end 326.861424 -42.746676)
		(width 0.0889)
		(layer "F.Cu")
		(net "SMB_SML0B_3V3AUX_SDA")
	)
	(segment
		(start 320.513202 -39.428928)
		(end 321.683126 -39.428928)
		(width 0.12954)
		(layer "F.Cu")
		(net "SMB_SML0B_3V3AUX_SDA")
	)
	(via
		(at 319.047622 -37.963348)
		(size 0.508)
		(drill 0.254)
		(layers "F.Cu" "B.Cu")
		(net "SMB_SML0B_3V3AUX_SDA")
	)
	(segment
		(start 318.04864 -29.057092)
		(end 318.04864 -30.627828)
		(width 0.12954)
		(layer "F.Cu")
		(net "SMB_SML0B_3V3AUX_SCL")
	)
	(segment
		(start 318.04864 -30.627828)
		(end 319.251076 -31.830264)
		(width 0.12954)
		(layer "F.Cu")
		(net "SMB_SML0B_3V3AUX_SCL")
	)
	(segment
		(start 319.679066 -33.796478)
		(end 320.191638 -33.796478)
		(width 0.12954)
		(layer "F.Cu")
		(net "SMB_SML0B_3V3AUX_SCL")
	)
	(segment
		(start 316.075822 -26.062432)
		(end 316.923166 -26.909776)
		(width 0.12954)
		(layer "F.Cu")
		(net "SMB_SML0B_3V3AUX_SCL")
	)
	(segment
		(start 325.626222 -39.680134)
		(end 326.132444 -40.186356)
		(width 0.0889)
		(layer "F.Cu")
		(net "SMB_SML0B_3V3AUX_SCL")
	)
	(segment
		(start 313.93511 -26.062432)
		(end 316.075822 -26.062432)
		(width 0.12954)
		(layer "F.Cu")
		(net "SMB_SML0B_3V3AUX_SCL")
	)
	(segment
		(start 320.191638 -33.796478)
		(end 325.419212 -39.024052)
		(width 0.12954)
		(layer "F.Cu")
		(net "SMB_SML0B_3V3AUX_SCL")
	)
	(segment
		(start 325.419212 -39.024052)
		(end 325.626222 -39.231062)
		(width 0.0889)
		(layer "F.Cu")
		(net "SMB_SML0B_3V3AUX_SCL")
	)
	(segment
		(start 326.685656 -40.249348)
		(end 326.718422 -40.235124)
		(width 0.0889)
		(layer "F.Cu")
		(net "SMB_SML0B_3V3AUX_SCL")
	)
	(segment
		(start 319.251076 -31.830264)
		(end 319.251076 -33.368488)
		(width 0.12954)
		(layer "F.Cu")
		(net "SMB_SML0B_3V3AUX_SCL")
	)
	(segment
		(start 319.251076 -33.368488)
		(end 319.679066 -33.796478)
		(width 0.12954)
		(layer "F.Cu")
		(net "SMB_SML0B_3V3AUX_SCL")
	)
	(segment
		(start 327.15962 -39.946072)
		(end 327.41489 -39.946072)
		(width 0.0889)
		(layer "F.Cu")
		(net "SMB_SML0B_3V3AUX_SCL")
	)
	(segment
		(start 316.923166 -27.931618)
		(end 317.337948 -28.3464)
		(width 0.12954)
		(layer "F.Cu")
		(net "SMB_SML0B_3V3AUX_SCL")
	)
	(segment
		(start 316.923166 -26.909776)
		(end 316.923166 -27.931618)
		(width 0.12954)
		(layer "F.Cu")
		(net "SMB_SML0B_3V3AUX_SCL")
	)
	(segment
		(start 325.626222 -39.231062)
		(end 325.626222 -39.680134)
		(width 0.0889)
		(layer "F.Cu")
		(net "SMB_SML0B_3V3AUX_SCL")
	)
	(segment
		(start 326.744584 -40.223694)
		(end 327.15962 -39.946072)
		(width 0.0889)
		(layer "F.Cu")
		(net "SMB_SML0B_3V3AUX_SCL")
	)
	(segment
		(start 326.718422 -40.235124)
		(end 326.744584 -40.223694)
		(width 0.0889)
		(layer "F.Cu")
		(net "SMB_SML0B_3V3AUX_SCL")
	)
	(segment
		(start 326.456548 -40.249348)
		(end 326.685656 -40.249348)
		(width 0.0889)
		(layer "F.Cu")
		(net "SMB_SML0B_3V3AUX_SCL")
	)
	(segment
		(start 326.242426 -40.186356)
		(end 326.456548 -40.249348)
		(width 0.0889)
		(layer "F.Cu")
		(net "SMB_SML0B_3V3AUX_SCL")
	)
	(segment
		(start 317.337948 -28.3464)
		(end 318.04864 -29.057092)
		(width 0.12954)
		(layer "F.Cu")
		(net "SMB_SML0B_3V3AUX_SCL")
	)
	(segment
		(start 326.132444 -40.186356)
		(end 326.242426 -40.186356)
		(width 0.0889)
		(layer "F.Cu")
		(net "SMB_SML0B_3V3AUX_SCL")
	)
	(via
		(at 317.337948 -28.3464)
		(size 0.508)
		(drill 0.254)
		(layers "F.Cu" "B.Cu")
		(net "SMB_SML0B_3V3AUX_SCL")
	)
	(segment
		(start 109.52988 -130.206242)
		(end 111.069882 -130.206242)
		(width 0.12954)
		(layer "F.Cu")
		(net "SMB_SENSOR_M2_P0_3V3AUX_SDA")
	)
	(segment
		(start 138.40968 -77.942948)
		(end 138.40968 -76.799948)
		(width 0.12954)
		(layer "F.Cu")
		(net "SMB_SENSOR_M2_P0_3V3AUX_SDA")
	)
	(segment
		(start 138.40968 -76.799948)
		(end 153.90368 -61.305948)
		(width 0.12954)
		(layer "F.Cu")
		(net "SMB_SENSOR_M2_P0_3V3AUX_SDA")
	)
	(segment
		(start 113.094262 -131.440682)
		(end 112.304322 -131.440682)
		(width 0.12954)
		(layer "F.Cu")
		(net "SMB_SENSOR_M2_P0_3V3AUX_SDA")
	)
	(segment
		(start 111.069882 -130.206242)
		(end 111.732822 -130.869182)
		(width 0.12954)
		(layer "F.Cu")
		(net "SMB_SENSOR_M2_P0_3V3AUX_SDA")
	)
	(segment
		(start 153.90368 -61.305948)
		(end 153.90368 -57.622948)
		(width 0.12954)
		(layer "F.Cu")
		(net "SMB_SENSOR_M2_P0_3V3AUX_SDA")
	)
	(segment
		(start 155.06573 -56.460898)
		(end 156.467556 -56.460898)
		(width 0.12954)
		(layer "F.Cu")
		(net "SMB_SENSOR_M2_P0_3V3AUX_SDA")
	)
	(segment
		(start 153.90368 -57.622948)
		(end 155.06573 -56.460898)
		(width 0.12954)
		(layer "F.Cu")
		(net "SMB_SENSOR_M2_P0_3V3AUX_SDA")
	)
	(segment
		(start 112.304322 -131.440682)
		(end 111.732822 -130.869182)
		(width 0.12954)
		(layer "F.Cu")
		(net "SMB_SENSOR_M2_P0_3V3AUX_SDA")
	)
	(via
		(at 138.40968 -77.942948)
		(size 0.508)
		(drill 0.254)
		(layers "F.Cu" "B.Cu")
		(net "SMB_SENSOR_M2_P0_3V3AUX_SDA")
	)
	(via
		(at 106.65968 -85.893148)
		(size 0.508)
		(drill 0.254)
		(layers "F.Cu" "B.Cu")
		(net "SMB_SENSOR_M2_P0_3V3AUX_SDA")
	)
	(via
		(at 109.52988 -130.206242)
		(size 0.508)
		(drill 0.254)
		(layers "F.Cu" "B.Cu")
		(net "SMB_SENSOR_M2_P0_3V3AUX_SDA")
	)
	(segment
		(start 103.33228 -124.008642)
		(end 103.33228 -109.592618)
		(width 0.127)
		(layer "In2.Cu")
		(net "SMB_SENSOR_M2_P0_3V3AUX_SDA")
	)
	(segment
		(start 103.33228 -109.592618)
		(end 103.02748 -109.287818)
		(width 0.127)
		(layer "In2.Cu")
		(net "SMB_SENSOR_M2_P0_3V3AUX_SDA")
	)
	(segment
		(start 103.89108 -89.245948)
		(end 106.65968 -86.477348)
		(width 0.127)
		(layer "In2.Cu")
		(net "SMB_SENSOR_M2_P0_3V3AUX_SDA")
	)
	(segment
		(start 106.65968 -86.477348)
		(end 106.65968 -85.893148)
		(width 0.127)
		(layer "In2.Cu")
		(net "SMB_SENSOR_M2_P0_3V3AUX_SDA")
	)
	(segment
		(start 103.89108 -99.990148)
		(end 103.89108 -89.245948)
		(width 0.127)
		(layer "In2.Cu")
		(net "SMB_SENSOR_M2_P0_3V3AUX_SDA")
	)
	(segment
		(start 103.02748 -100.853748)
		(end 103.89108 -99.990148)
		(width 0.127)
		(layer "In2.Cu")
		(net "SMB_SENSOR_M2_P0_3V3AUX_SDA")
	)
	(segment
		(start 109.52988 -130.206242)
		(end 103.33228 -124.008642)
		(width 0.127)
		(layer "In2.Cu")
		(net "SMB_SENSOR_M2_P0_3V3AUX_SDA")
	)
	(segment
		(start 103.02748 -109.287818)
		(end 103.02748 -100.853748)
		(width 0.127)
		(layer "In2.Cu")
		(net "SMB_SENSOR_M2_P0_3V3AUX_SDA")
	)
	(segment
		(start 138.40968 -77.942948)
		(end 138.40968 -77.943202)
		(width 0.127)
		(layer "In4.Cu")
		(net "SMB_SENSOR_M2_P0_3V3AUX_SDA")
	)
	(segment
		(start 135.709152 -80.64373)
		(end 118.437152 -80.64373)
		(width 0.127)
		(layer "In4.Cu")
		(net "SMB_SENSOR_M2_P0_3V3AUX_SDA")
	)
	(segment
		(start 115.160552 -83.92033)
		(end 107.362752 -83.92033)
		(width 0.127)
		(layer "In4.Cu")
		(net "SMB_SENSOR_M2_P0_3V3AUX_SDA")
	)
	(segment
		(start 138.40968 -77.943202)
		(end 135.709152 -80.64373)
		(width 0.127)
		(layer "In4.Cu")
		(net "SMB_SENSOR_M2_P0_3V3AUX_SDA")
	)
	(segment
		(start 107.362752 -83.92033)
		(end 106.845862 -84.43722)
		(width 0.127)
		(layer "In4.Cu")
		(net "SMB_SENSOR_M2_P0_3V3AUX_SDA")
	)
	(segment
		(start 118.437152 -80.64373)
		(end 115.160552 -83.92033)
		(width 0.127)
		(layer "In4.Cu")
		(net "SMB_SENSOR_M2_P0_3V3AUX_SDA")
	)
	(segment
		(start 106.65968 -85.372448)
		(end 106.65968 -85.893148)
		(width 0.127)
		(layer "In4.Cu")
		(net "SMB_SENSOR_M2_P0_3V3AUX_SDA")
	)
	(segment
		(start 106.845862 -85.186266)
		(end 106.65968 -85.372448)
		(width 0.127)
		(layer "In4.Cu")
		(net "SMB_SENSOR_M2_P0_3V3AUX_SDA")
	)
	(segment
		(start 106.845862 -84.43722)
		(end 106.845862 -85.186266)
		(width 0.127)
		(layer "In4.Cu")
		(net "SMB_SENSOR_M2_P0_3V3AUX_SDA")
	)
	(segment
		(start 109.52988 -128.814322)
		(end 111.074962 -128.814322)
		(width 0.12954)
		(layer "F.Cu")
		(net "SMB_SENSOR_M2_P0_3V3AUX_SCL")
	)
	(segment
		(start 112.685322 -130.424682)
		(end 111.732822 -129.472182)
		(width 0.12954)
		(layer "F.Cu")
		(net "SMB_SENSOR_M2_P0_3V3AUX_SCL")
	)
	(segment
		(start 113.094262 -130.424682)
		(end 112.685322 -130.424682)
		(width 0.12954)
		(layer "F.Cu")
		(net "SMB_SENSOR_M2_P0_3V3AUX_SCL")
	)
	(segment
		(start 154.553666 -57.892188)
		(end 155.33497 -57.110884)
		(width 0.12954)
		(layer "F.Cu")
		(net "SMB_SENSOR_M2_P0_3V3AUX_SCL")
	)
	(segment
		(start 154.553666 -61.417708)
		(end 154.553666 -57.892188)
		(width 0.12954)
		(layer "F.Cu")
		(net "SMB_SENSOR_M2_P0_3V3AUX_SCL")
	)
	(segment
		(start 111.074962 -128.814322)
		(end 111.732822 -129.472182)
		(width 0.12954)
		(layer "F.Cu")
		(net "SMB_SENSOR_M2_P0_3V3AUX_SCL")
	)
	(segment
		(start 139.04468 -77.942948)
		(end 139.04468 -76.926694)
		(width 0.12954)
		(layer "F.Cu")
		(net "SMB_SENSOR_M2_P0_3V3AUX_SCL")
	)
	(segment
		(start 139.04468 -76.926694)
		(end 154.553666 -61.417708)
		(width 0.12954)
		(layer "F.Cu")
		(net "SMB_SENSOR_M2_P0_3V3AUX_SCL")
	)
	(segment
		(start 155.33497 -57.110884)
		(end 156.467556 -57.110884)
		(width 0.12954)
		(layer "F.Cu")
		(net "SMB_SENSOR_M2_P0_3V3AUX_SCL")
	)
	(via
		(at 107.29468 -85.893148)
		(size 0.508)
		(drill 0.254)
		(layers "F.Cu" "B.Cu")
		(net "SMB_SENSOR_M2_P0_3V3AUX_SCL")
	)
	(via
		(at 109.52988 -128.814322)
		(size 0.508)
		(drill 0.254)
		(layers "F.Cu" "B.Cu")
		(net "SMB_SENSOR_M2_P0_3V3AUX_SCL")
	)
	(via
		(at 139.04468 -77.942948)
		(size 0.508)
		(drill 0.254)
		(layers "F.Cu" "B.Cu")
		(net "SMB_SENSOR_M2_P0_3V3AUX_SCL")
	)
	(segment
		(start 104.32288 -100.169218)
		(end 104.32288 -89.425018)
		(width 0.127)
		(layer "In2.Cu")
		(net "SMB_SENSOR_M2_P0_3V3AUX_SCL")
	)
	(segment
		(start 109.52988 -128.814322)
		(end 103.76408 -123.048522)
		(width 0.127)
		(layer "In2.Cu")
		(net "SMB_SENSOR_M2_P0_3V3AUX_SCL")
	)
	(segment
		(start 104.32288 -89.425018)
		(end 107.29468 -86.453218)
		(width 0.127)
		(layer "In2.Cu")
		(net "SMB_SENSOR_M2_P0_3V3AUX_SCL")
	)
	(segment
		(start 103.45928 -109.108748)
		(end 103.45928 -101.032818)
		(width 0.127)
		(layer "In2.Cu")
		(net "SMB_SENSOR_M2_P0_3V3AUX_SCL")
	)
	(segment
		(start 103.45928 -101.032818)
		(end 104.32288 -100.169218)
		(width 0.127)
		(layer "In2.Cu")
		(net "SMB_SENSOR_M2_P0_3V3AUX_SCL")
	)
	(segment
		(start 107.29468 -86.453218)
		(end 107.29468 -85.893148)
		(width 0.127)
		(layer "In2.Cu")
		(net "SMB_SENSOR_M2_P0_3V3AUX_SCL")
	)
	(segment
		(start 103.76408 -123.048522)
		(end 103.76408 -109.413548)
		(width 0.127)
		(layer "In2.Cu")
		(net "SMB_SENSOR_M2_P0_3V3AUX_SCL")
	)
	(segment
		(start 103.76408 -109.413548)
		(end 103.45928 -109.108748)
		(width 0.127)
		(layer "In2.Cu")
		(net "SMB_SENSOR_M2_P0_3V3AUX_SCL")
	)
	(segment
		(start 139.04468 -78.067408)
		(end 136.01954 -81.092548)
		(width 0.127)
		(layer "In4.Cu")
		(net "SMB_SENSOR_M2_P0_3V3AUX_SCL")
	)
	(segment
		(start 136.01954 -81.092548)
		(end 118.62308 -81.092548)
		(width 0.127)
		(layer "In4.Cu")
		(net "SMB_SENSOR_M2_P0_3V3AUX_SCL")
	)
	(segment
		(start 107.54868 -84.369148)
		(end 107.29468 -84.623148)
		(width 0.127)
		(layer "In4.Cu")
		(net "SMB_SENSOR_M2_P0_3V3AUX_SCL")
	)
	(segment
		(start 107.29468 -84.623148)
		(end 107.29468 -85.893148)
		(width 0.127)
		(layer "In4.Cu")
		(net "SMB_SENSOR_M2_P0_3V3AUX_SCL")
	)
	(segment
		(start 115.34648 -84.369148)
		(end 107.54868 -84.369148)
		(width 0.127)
		(layer "In4.Cu")
		(net "SMB_SENSOR_M2_P0_3V3AUX_SCL")
	)
	(segment
		(start 118.62308 -81.092548)
		(end 115.34648 -84.369148)
		(width 0.127)
		(layer "In4.Cu")
		(net "SMB_SENSOR_M2_P0_3V3AUX_SCL")
	)
	(segment
		(start 139.04468 -77.942948)
		(end 139.04468 -78.067408)
		(width 0.127)
		(layer "In4.Cu")
		(net "SMB_SENSOR_M2_P0_3V3AUX_SCL")
	)
	(segment
		(start 173.30166 -12.626086)
		(end 173.30166 -11.892788)
		(width 0.12954)
		(layer "F.Cu")
		(net "I3C_BMC_SWB_SDA")
	)
	(segment
		(start 173.467014 -13.025374)
		(end 173.30166 -12.626086)
		(width 0.12954)
		(layer "F.Cu")
		(net "I3C_BMC_SWB_SDA")
	)
	(segment
		(start 173.467014 -13.600176)
		(end 173.467014 -13.025374)
		(width 0.12954)
		(layer "F.Cu")
		(net "I3C_BMC_SWB_SDA")
	)
	(via
		(at 173.30166 -11.892788)
		(size 0.508)
		(drill 0.254)
		(layers "F.Cu" "B.Cu")
		(net "I3C_BMC_SWB_SDA")
	)
	(segment
		(start 173.28896 -12.570714)
		(end 173.28896 -11.897614)
		(width 0.12954)
		(layer "B.Cu")
		(net "I3C_BMC_SWB_SDA")
	)
	(segment
		(start 172.92828 -11.14806)
		(end 173.190916 -11.782044)
		(width 0.12954)
		(layer "B.Cu")
		(net "I3C_BMC_SWB_SDA")
	)
	(segment
		(start 173.29404 -11.892534)
		(end 173.301406 -11.892534)
		(width 0.12954)
		(layer "B.Cu")
		(net "I3C_BMC_SWB_SDA")
	)
	(segment
		(start 173.24832 -10.231628)
		(end 172.92828 -10.551668)
		(width 0.12954)
		(layer "B.Cu")
		(net "I3C_BMC_SWB_SDA")
	)
	(segment
		(start 173.28896 -11.897614)
		(end 173.29404 -11.892534)
		(width 0.12954)
		(layer "B.Cu")
		(net "I3C_BMC_SWB_SDA")
	)
	(segment
		(start 173.30166 -11.892788)
		(end 173.301406 -11.892534)
		(width 0.12954)
		(layer "B.Cu")
		(net "I3C_BMC_SWB_SDA")
	)
	(segment
		(start 172.92828 -10.551668)
		(end 172.92828 -11.14806)
		(width 0.12954)
		(layer "B.Cu")
		(net "I3C_BMC_SWB_SDA")
	)
	(segment
		(start 173.190916 -11.782044)
		(end 173.301406 -11.892534)
		(width 0.12954)
		(layer "B.Cu")
		(net "I3C_BMC_SWB_SDA")
	)
	(segment
		(start 174.080424 -13.362178)
		(end 173.28896 -12.570714)
		(width 0.12954)
		(layer "B.Cu")
		(net "I3C_BMC_SWB_SDA")
	)
	(segment
		(start 173.24832 -9.409176)
		(end 173.24832 -10.231628)
		(width 0.12954)
		(layer "B.Cu")
		(net "I3C_BMC_SWB_SDA")
	)
	(segment
		(start 172.746162 -8.907018)
		(end 173.24832 -9.409176)
		(width 0.12954)
		(layer "B.Cu")
		(net "I3C_BMC_SWB_SDA")
	)
	(segment
		(start 174.235872 -13.362178)
		(end 174.080424 -13.362178)
		(width 0.12954)
		(layer "B.Cu")
		(net "I3C_BMC_SWB_SDA")
	)
	(segment
		(start 173.59376 -11.02614)
		(end 173.59376 -10.879328)
		(width 0.12954)
		(layer "F.Cu")
		(net "I3C_BMC_SWB_SCL")
	)
	(segment
		(start 174.066962 -13.600176)
		(end 174.066962 -11.499342)
		(width 0.12954)
		(layer "F.Cu")
		(net "I3C_BMC_SWB_SCL")
	)
	(segment
		(start 174.066962 -11.499342)
		(end 173.59376 -11.02614)
		(width 0.12954)
		(layer "F.Cu")
		(net "I3C_BMC_SWB_SCL")
	)
	(via
		(at 173.59376 -10.879328)
		(size 0.508)
		(drill 0.254)
		(layers "F.Cu" "B.Cu")
		(net "I3C_BMC_SWB_SCL")
	)
	(segment
		(start 173.91888 -9.06018)
		(end 173.763178 -8.904478)
		(width 0.12954)
		(layer "B.Cu")
		(net "I3C_BMC_SWB_SCL")
	)
	(segment
		(start 173.59376 -10.879328)
		(end 174.02048 -11.306048)
		(width 0.12954)
		(layer "B.Cu")
		(net "I3C_BMC_SWB_SCL")
	)
	(segment
		(start 174.02048 -12.329414)
		(end 175.053244 -13.362178)
		(width 0.12954)
		(layer "B.Cu")
		(net "I3C_BMC_SWB_SCL")
	)
	(segment
		(start 173.91888 -10.554208)
		(end 173.91888 -9.06018)
		(width 0.12954)
		(layer "B.Cu")
		(net "I3C_BMC_SWB_SCL")
	)
	(segment
		(start 174.02048 -11.306048)
		(end 174.02048 -12.329414)
		(width 0.12954)
		(layer "B.Cu")
		(net "I3C_BMC_SWB_SCL")
	)
	(segment
		(start 175.053244 -13.362178)
		(end 175.31588 -13.362178)
		(width 0.12954)
		(layer "B.Cu")
		(net "I3C_BMC_SWB_SCL")
	)
	(segment
		(start 173.59376 -10.879328)
		(end 173.91888 -10.554208)
		(width 0.12954)
		(layer "B.Cu")
		(net "I3C_BMC_SWB_SCL")
	)
	(segment
		(start 151.456898 -12.683998)
		(end 151.456898 -13.600176)
		(width 0.12954)
		(layer "F.Cu")
		(net "SMB_S3M_CPU_3V3AUX_SDA_R0")
	)
	(segment
		(start 150.715726 -11.603228)
		(end 151.421084 -12.308586)
		(width 0.12954)
		(layer "F.Cu")
		(net "SMB_S3M_CPU_3V3AUX_SDA_R0")
	)
	(segment
		(start 151.421084 -12.648184)
		(end 151.456898 -12.683998)
		(width 0.12954)
		(layer "F.Cu")
		(net "SMB_S3M_CPU_3V3AUX_SDA_R0")
	)
	(segment
		(start 151.421084 -12.308586)
		(end 151.421084 -12.648184)
		(width 0.12954)
		(layer "F.Cu")
		(net "SMB_S3M_CPU_3V3AUX_SDA_R0")
	)
	(via
		(at 150.715726 -11.603228)
		(size 0.508)
		(drill 0.254)
		(layers "F.Cu" "B.Cu")
		(net "SMB_S3M_CPU_3V3AUX_SDA_R0")
	)
	(segment
		(start 151.35098 -12.911836)
		(end 150.900638 -13.362178)
		(width 0.12954)
		(layer "B.Cu")
		(net "SMB_S3M_CPU_3V3AUX_SDA_R0")
	)
	(segment
		(start 150.715726 -11.603228)
		(end 151.35098 -12.238482)
		(width 0.12954)
		(layer "B.Cu")
		(net "SMB_S3M_CPU_3V3AUX_SDA_R0")
	)
	(segment
		(start 151.35098 -12.238482)
		(end 151.35098 -12.911836)
		(width 0.12954)
		(layer "B.Cu")
		(net "SMB_S3M_CPU_3V3AUX_SDA_R0")
	)
	(segment
		(start 149.670008 -73.96988)
		(end 152.286208 -73.96988)
		(width 0.12954)
		(layer "F.Cu")
		(net "SMB_S3M_CPU_3V3AUX_SDA")
	)
	(segment
		(start 149.5679 -74.071988)
		(end 149.670008 -73.96988)
		(width 0.12954)
		(layer "F.Cu")
		(net "SMB_S3M_CPU_3V3AUX_SDA")
	)
	(via
		(at 151.05888 -24.69388)
		(size 0.508)
		(drill 0.254)
		(layers "F.Cu" "B.Cu")
		(net "SMB_S3M_CPU_3V3AUX_SDA")
	)
	(via
		(at 149.5679 -74.071988)
		(size 0.508)
		(drill 0.254)
		(layers "F.Cu" "B.Cu")
		(net "SMB_S3M_CPU_3V3AUX_SDA")
	)
	(segment
		(start 150.78583 -22.424898)
		(end 150.42388 -22.424898)
		(width 0.12954)
		(layer "B.Cu")
		(net "SMB_S3M_CPU_3V3AUX_SDA")
	)
	(segment
		(start 150.42388 -22.424898)
		(end 150.63978 -22.208998)
		(width 0.12954)
		(layer "B.Cu")
		(net "SMB_S3M_CPU_3V3AUX_SDA")
	)
	(segment
		(start 151.05888 -24.69388)
		(end 151.05888 -22.697948)
		(width 0.12954)
		(layer "B.Cu")
		(net "SMB_S3M_CPU_3V3AUX_SDA")
	)
	(segment
		(start 151.05888 -22.697948)
		(end 150.78583 -22.424898)
		(width 0.12954)
		(layer "B.Cu")
		(net "SMB_S3M_CPU_3V3AUX_SDA")
	)
	(segment
		(start 150.63978 -22.208998)
		(end 150.63978 -15.878302)
		(width 0.12954)
		(layer "B.Cu")
		(net "SMB_S3M_CPU_3V3AUX_SDA")
	)
	(segment
		(start 150.63978 -15.878302)
		(end 150.900638 -15.617444)
		(width 0.12954)
		(layer "B.Cu")
		(net "SMB_S3M_CPU_3V3AUX_SDA")
	)
	(segment
		(start 150.900638 -15.617444)
		(end 150.900638 -14.162278)
		(width 0.12954)
		(layer "B.Cu")
		(net "SMB_S3M_CPU_3V3AUX_SDA")
	)
	(segment
		(start 151.12492 -32.263588)
		(end 152.02408 -33.162748)
		(width 0.127)
		(layer "In2.Cu")
		(net "SMB_S3M_CPU_3V3AUX_SDA")
	)
	(segment
		(start 152.02408 -33.162748)
		(end 152.02408 -40.049196)
		(width 0.127)
		(layer "In2.Cu")
		(net "SMB_S3M_CPU_3V3AUX_SDA")
	)
	(segment
		(start 151.54148 -25.17648)
		(end 151.54148 -31.016448)
		(width 0.127)
		(layer "In2.Cu")
		(net "SMB_S3M_CPU_3V3AUX_SDA")
	)
	(segment
		(start 152.02408 -40.049196)
		(end 148.2852 -43.788076)
		(width 0.127)
		(layer "In2.Cu")
		(net "SMB_S3M_CPU_3V3AUX_SDA")
	)
	(segment
		(start 151.54148 -31.016448)
		(end 151.12492 -31.433008)
		(width 0.127)
		(layer "In2.Cu")
		(net "SMB_S3M_CPU_3V3AUX_SDA")
	)
	(segment
		(start 150.93188 -72.708008)
		(end 149.5679 -74.071988)
		(width 0.127)
		(layer "In2.Cu")
		(net "SMB_S3M_CPU_3V3AUX_SDA")
	)
	(segment
		(start 152.35174 -63.515748)
		(end 150.93188 -64.935608)
		(width 0.127)
		(layer "In2.Cu")
		(net "SMB_S3M_CPU_3V3AUX_SDA")
	)
	(segment
		(start 150.93188 -64.935608)
		(end 150.93188 -72.708008)
		(width 0.127)
		(layer "In2.Cu")
		(net "SMB_S3M_CPU_3V3AUX_SDA")
	)
	(segment
		(start 150.93188 -50.510948)
		(end 150.93188 -54.435248)
		(width 0.127)
		(layer "In2.Cu")
		(net "SMB_S3M_CPU_3V3AUX_SDA")
	)
	(segment
		(start 148.2852 -43.788076)
		(end 148.2852 -47.864268)
		(width 0.127)
		(layer "In2.Cu")
		(net "SMB_S3M_CPU_3V3AUX_SDA")
	)
	(segment
		(start 148.2852 -47.864268)
		(end 150.93188 -50.510948)
		(width 0.127)
		(layer "In2.Cu")
		(net "SMB_S3M_CPU_3V3AUX_SDA")
	)
	(segment
		(start 152.35174 -55.855108)
		(end 152.35174 -63.515748)
		(width 0.127)
		(layer "In2.Cu")
		(net "SMB_S3M_CPU_3V3AUX_SDA")
	)
	(segment
		(start 151.05888 -24.69388)
		(end 151.54148 -25.17648)
		(width 0.127)
		(layer "In2.Cu")
		(net "SMB_S3M_CPU_3V3AUX_SDA")
	)
	(segment
		(start 150.93188 -54.435248)
		(end 152.35174 -55.855108)
		(width 0.127)
		(layer "In2.Cu")
		(net "SMB_S3M_CPU_3V3AUX_SDA")
	)
	(segment
		(start 151.12492 -31.433008)
		(end 151.12492 -32.263588)
		(width 0.127)
		(layer "In2.Cu")
		(net "SMB_S3M_CPU_3V3AUX_SDA")
	)
	(segment
		(start 152.0571 -13.600176)
		(end 152.0571 -12.380468)
		(width 0.12954)
		(layer "F.Cu")
		(net "SMB_S3M_CPU_3V3AUX_SCL_R0")
	)
	(segment
		(start 152.0571 -12.380468)
		(end 151.88057 -12.203938)
		(width 0.12954)
		(layer "F.Cu")
		(net "SMB_S3M_CPU_3V3AUX_SCL_R0")
	)
	(via
		(at 151.88057 -12.203938)
		(size 0.508)
		(drill 0.254)
		(layers "F.Cu" "B.Cu")
		(net "SMB_S3M_CPU_3V3AUX_SCL_R0")
	)
	(segment
		(start 151.99487 -12.318238)
		(end 151.99487 -13.362178)
		(width 0.12954)
		(layer "B.Cu")
		(net "SMB_S3M_CPU_3V3AUX_SCL_R0")
	)
	(segment
		(start 151.88057 -12.203938)
		(end 151.99487 -12.318238)
		(width 0.12954)
		(layer "B.Cu")
		(net "SMB_S3M_CPU_3V3AUX_SCL_R0")
	)
	(segment
		(start 151.844248 -74.619866)
		(end 152.286208 -74.619866)
		(width 0.12954)
		(layer "F.Cu")
		(net "SMB_S3M_CPU_3V3AUX_SCL")
	)
	(segment
		(start 150.815802 -75.107546)
		(end 150.935944 -75.227688)
		(width 0.12954)
		(layer "F.Cu")
		(net "SMB_S3M_CPU_3V3AUX_SCL")
	)
	(segment
		(start 151.236426 -75.227688)
		(end 151.844248 -74.619866)
		(width 0.12954)
		(layer "F.Cu")
		(net "SMB_S3M_CPU_3V3AUX_SCL")
	)
	(segment
		(start 150.815802 -74.675746)
		(end 150.815802 -75.107546)
		(width 0.12954)
		(layer "F.Cu")
		(net "SMB_S3M_CPU_3V3AUX_SCL")
	)
	(segment
		(start 150.935944 -75.227688)
		(end 151.236426 -75.227688)
		(width 0.12954)
		(layer "F.Cu")
		(net "SMB_S3M_CPU_3V3AUX_SCL")
	)
	(via
		(at 152.45588 -24.602948)
		(size 0.508)
		(drill 0.254)
		(layers "F.Cu" "B.Cu")
		(net "SMB_S3M_CPU_3V3AUX_SCL")
	)
	(via
		(at 150.815802 -74.675746)
		(size 0.508)
		(drill 0.254)
		(layers "F.Cu" "B.Cu")
		(net "SMB_S3M_CPU_3V3AUX_SCL")
	)
	(segment
		(start 151.30399 -22.060408)
		(end 151.30399 -16.560038)
		(width 0.12954)
		(layer "B.Cu")
		(net "SMB_S3M_CPU_3V3AUX_SCL")
	)
	(segment
		(start 152.30983 -22.424898)
		(end 151.69388 -22.424898)
		(width 0.12954)
		(layer "B.Cu")
		(net "SMB_S3M_CPU_3V3AUX_SCL")
	)
	(segment
		(start 151.69388 -22.424898)
		(end 151.66848 -22.424898)
		(width 0.12954)
		(layer "B.Cu")
		(net "SMB_S3M_CPU_3V3AUX_SCL")
	)
	(segment
		(start 151.30399 -16.560038)
		(end 151.99487 -15.869158)
		(width 0.12954)
		(layer "B.Cu")
		(net "SMB_S3M_CPU_3V3AUX_SCL")
	)
	(segment
		(start 151.66848 -22.424898)
		(end 151.30399 -22.060408)
		(width 0.12954)
		(layer "B.Cu")
		(net "SMB_S3M_CPU_3V3AUX_SCL")
	)
	(segment
		(start 152.45588 -24.602948)
		(end 152.45588 -22.570948)
		(width 0.12954)
		(layer "B.Cu")
		(net "SMB_S3M_CPU_3V3AUX_SCL")
	)
	(segment
		(start 152.45588 -22.570948)
		(end 152.30983 -22.424898)
		(width 0.12954)
		(layer "B.Cu")
		(net "SMB_S3M_CPU_3V3AUX_SCL")
	)
	(segment
		(start 151.99487 -15.869158)
		(end 151.99487 -14.162278)
		(width 0.12954)
		(layer "B.Cu")
		(net "SMB_S3M_CPU_3V3AUX_SCL")
	)
	(segment
		(start 148.80336 -43.88104)
		(end 148.80336 -47.607474)
		(width 0.127)
		(layer "In2.Cu")
		(net "SMB_S3M_CPU_3V3AUX_SCL")
	)
	(segment
		(start 148.80336 -47.607474)
		(end 151.36368 -50.167794)
		(width 0.127)
		(layer "In2.Cu")
		(net "SMB_S3M_CPU_3V3AUX_SCL")
	)
	(segment
		(start 151.36368 -65.114678)
		(end 151.36368 -74.127868)
		(width 0.127)
		(layer "In2.Cu")
		(net "SMB_S3M_CPU_3V3AUX_SCL")
	)
	(segment
		(start 152.78354 -55.676038)
		(end 152.78354 -63.694818)
		(width 0.127)
		(layer "In2.Cu")
		(net "SMB_S3M_CPU_3V3AUX_SCL")
	)
	(segment
		(start 151.36368 -50.167794)
		(end 151.36368 -54.256178)
		(width 0.127)
		(layer "In2.Cu")
		(net "SMB_S3M_CPU_3V3AUX_SCL")
	)
	(segment
		(start 152.49652 -40.18788)
		(end 148.80336 -43.88104)
		(width 0.127)
		(layer "In2.Cu")
		(net "SMB_S3M_CPU_3V3AUX_SCL")
	)
	(segment
		(start 151.36368 -54.256178)
		(end 152.78354 -55.676038)
		(width 0.127)
		(layer "In2.Cu")
		(net "SMB_S3M_CPU_3V3AUX_SCL")
	)
	(segment
		(start 151.97328 -28.613354)
		(end 152.49652 -29.136594)
		(width 0.127)
		(layer "In2.Cu")
		(net "SMB_S3M_CPU_3V3AUX_SCL")
	)
	(segment
		(start 152.78354 -63.694818)
		(end 151.36368 -65.114678)
		(width 0.127)
		(layer "In2.Cu")
		(net "SMB_S3M_CPU_3V3AUX_SCL")
	)
	(segment
		(start 151.36368 -74.127868)
		(end 150.815802 -74.675746)
		(width 0.127)
		(layer "In2.Cu")
		(net "SMB_S3M_CPU_3V3AUX_SCL")
	)
	(segment
		(start 152.49652 -29.136594)
		(end 152.49652 -40.18788)
		(width 0.127)
		(layer "In2.Cu")
		(net "SMB_S3M_CPU_3V3AUX_SCL")
	)
	(segment
		(start 152.10028 -24.602948)
		(end 151.97328 -24.729948)
		(width 0.127)
		(layer "In2.Cu")
		(net "SMB_S3M_CPU_3V3AUX_SCL")
	)
	(segment
		(start 151.97328 -24.729948)
		(end 151.97328 -28.613354)
		(width 0.127)
		(layer "In2.Cu")
		(net "SMB_S3M_CPU_3V3AUX_SCL")
	)
	(segment
		(start 152.45588 -24.602948)
		(end 152.10028 -24.602948)
		(width 0.127)
		(layer "In2.Cu")
		(net "SMB_S3M_CPU_3V3AUX_SCL")
	)
	(segment
		(start 178.70043 -189.460378)
		(end 179.18557 -189.460378)
		(width 0.12954)
		(layer "F.Cu")
		(net "SMB_S3M_CPU1_SDA")
	)
	(segment
		(start 226.503738 -218.721686)
		(end 226.503738 -220.415866)
		(width 0.12954)
		(layer "F.Cu")
		(net "SMB_S3M_CPU1_SDA")
	)
	(segment
		(start 114.569494 -266.405868)
		(end 114.569748 -266.406122)
		(width 0.12954)
		(layer "F.Cu")
		(net "SMB_S3M_CPU1_SDA")
	)
	(segment
		(start 215.6968 -190.668148)
		(end 216.5604 -191.531748)
		(width 0.12954)
		(layer "F.Cu")
		(net "SMB_S3M_CPU1_SDA")
	)
	(segment
		(start 209.371946 -187.619894)
		(end 212.4202 -190.668148)
		(width 0.12954)
		(layer "F.Cu")
		(net "SMB_S3M_CPU1_SDA")
	)
	(segment
		(start 202.856592 -186.00674)
		(end 204.469746 -187.619894)
		(width 0.12954)
		(layer "F.Cu")
		(net "SMB_S3M_CPU1_SDA")
	)
	(segment
		(start 114.569748 -266.406122)
		(end 114.569748 -266.941808)
		(width 0.12954)
		(layer "F.Cu")
		(net "SMB_S3M_CPU1_SDA")
	)
	(segment
		(start 193.675 -186.781948)
		(end 194.450208 -186.00674)
		(width 0.12954)
		(layer "F.Cu")
		(net "SMB_S3M_CPU1_SDA")
	)
	(segment
		(start 212.4202 -190.668148)
		(end 215.6968 -190.668148)
		(width 0.12954)
		(layer "F.Cu")
		(net "SMB_S3M_CPU1_SDA")
	)
	(segment
		(start 222.5294 -214.747348)
		(end 226.503738 -218.721686)
		(width 0.12954)
		(layer "F.Cu")
		(net "SMB_S3M_CPU1_SDA")
	)
	(segment
		(start 217.98788 -191.531748)
		(end 222.5294 -196.073268)
		(width 0.12954)
		(layer "F.Cu")
		(net "SMB_S3M_CPU1_SDA")
	)
	(segment
		(start 194.450208 -186.00674)
		(end 202.856592 -186.00674)
		(width 0.12954)
		(layer "F.Cu")
		(net "SMB_S3M_CPU1_SDA")
	)
	(segment
		(start 204.469746 -187.619894)
		(end 209.371946 -187.619894)
		(width 0.12954)
		(layer "F.Cu")
		(net "SMB_S3M_CPU1_SDA")
	)
	(segment
		(start 179.18557 -189.460378)
		(end 181.864 -186.781948)
		(width 0.12954)
		(layer "F.Cu")
		(net "SMB_S3M_CPU1_SDA")
	)
	(segment
		(start 222.5294 -196.073268)
		(end 222.5294 -214.747348)
		(width 0.12954)
		(layer "F.Cu")
		(net "SMB_S3M_CPU1_SDA")
	)
	(segment
		(start 216.5604 -191.531748)
		(end 217.98788 -191.531748)
		(width 0.12954)
		(layer "F.Cu")
		(net "SMB_S3M_CPU1_SDA")
	)
	(segment
		(start 181.864 -186.781948)
		(end 193.675 -186.781948)
		(width 0.12954)
		(layer "F.Cu")
		(net "SMB_S3M_CPU1_SDA")
	)
	(via
		(at 114.569748 -266.941808)
		(size 0.4572)
		(drill 0.2032)
		(layers "F.Cu" "B.Cu")
		(net "SMB_S3M_CPU1_SDA")
	)
	(via
		(at 178.70043 -189.460378)
		(size 0.508)
		(drill 0.254)
		(layers "F.Cu" "B.Cu")
		(net "SMB_S3M_CPU1_SDA")
	)
	(via
		(at 150.445978 -261.92099)
		(size 0.6604)
		(drill 0.3302)
		(layers "F.Cu" "B.Cu")
		(net "SMB_S3M_CPU1_SDA")
	)
	(segment
		(start 167.456358 -253.14783)
		(end 166.783258 -253.82093)
		(width 0.12954)
		(layer "B.Cu")
		(net "SMB_S3M_CPU1_SDA")
	)
	(segment
		(start 130.748278 -263.370822)
		(end 130.733546 -263.362186)
		(width 0.0889)
		(layer "B.Cu")
		(net "SMB_S3M_CPU1_SDA")
	)
	(segment
		(start 145.696178 -261.92099)
		(end 144.821402 -262.795766)
		(width 0.12954)
		(layer "B.Cu")
		(net "SMB_S3M_CPU1_SDA")
	)
	(segment
		(start 114.70513 -267.290804)
		(end 114.726212 -267.212826)
		(width 0.0889)
		(layer "B.Cu")
		(net "SMB_S3M_CPU1_SDA")
	)
	(segment
		(start 172.048678 -251.26823)
		(end 171.875958 -251.44095)
		(width 0.12954)
		(layer "B.Cu")
		(net "SMB_S3M_CPU1_SDA")
	)
	(segment
		(start 161.601658 -263.22655)
		(end 160.744408 -262.3693)
		(width 0.12954)
		(layer "B.Cu")
		(net "SMB_S3M_CPU1_SDA")
	)
	(segment
		(start 144.821402 -262.795766)
		(end 140.829284 -262.795766)
		(width 0.12954)
		(layer "B.Cu")
		(net "SMB_S3M_CPU1_SDA")
	)
	(segment
		(start 165.078918 -262.41121)
		(end 164.263578 -263.22655)
		(width 0.12954)
		(layer "B.Cu")
		(net "SMB_S3M_CPU1_SDA")
	)
	(segment
		(start 140.829284 -262.795766)
		(end 139.816332 -263.215374)
		(width 0.12954)
		(layer "B.Cu")
		(net "SMB_S3M_CPU1_SDA")
	)
	(segment
		(start 160.744408 -262.3693)
		(end 156.524198 -262.3693)
		(width 0.12954)
		(layer "B.Cu")
		(net "SMB_S3M_CPU1_SDA")
	)
	(segment
		(start 128.86436 -263.368282)
		(end 128.853946 -263.362186)
		(width 0.0889)
		(layer "B.Cu")
		(net "SMB_S3M_CPU1_SDA")
	)
	(segment
		(start 170.285918 -251.44095)
		(end 168.579038 -253.14783)
		(width 0.12954)
		(layer "B.Cu")
		(net "SMB_S3M_CPU1_SDA")
	)
	(segment
		(start 139.71016 -263.321546)
		(end 139.71016 -263.33069)
		(width 0.0889)
		(layer "B.Cu")
		(net "SMB_S3M_CPU1_SDA")
	)
	(segment
		(start 166.293038 -261.720584)
		(end 165.602412 -262.41121)
		(width 0.12954)
		(layer "B.Cu")
		(net "SMB_S3M_CPU1_SDA")
	)
	(segment
		(start 123.225306 -263.368282)
		(end 123.214892 -263.362186)
		(width 0.0889)
		(layer "B.Cu")
		(net "SMB_S3M_CPU1_SDA")
	)
	(segment
		(start 124.169678 -263.370822)
		(end 124.154946 -263.362186)
		(width 0.0889)
		(layer "B.Cu")
		(net "SMB_S3M_CPU1_SDA")
	)
	(segment
		(start 119.363744 -264.252202)
		(end 119.363744 -264.515854)
		(width 0.0889)
		(layer "B.Cu")
		(net "SMB_S3M_CPU1_SDA")
	)
	(segment
		(start 114.38255 -266.61745)
		(end 114.37366 -266.62253)
		(width 0.0889)
		(layer "B.Cu")
		(net "SMB_S3M_CPU1_SDA")
	)
	(segment
		(start 150.445978 -261.92099)
		(end 145.696178 -261.92099)
		(width 0.12954)
		(layer "B.Cu")
		(net "SMB_S3M_CPU1_SDA")
	)
	(segment
		(start 175.69307 -191.548258)
		(end 174.865538 -192.37579)
		(width 0.12954)
		(layer "B.Cu")
		(net "SMB_S3M_CPU1_SDA")
	)
	(segment
		(start 174.558198 -195.42633)
		(end 174.558198 -196.81317)
		(width 0.12954)
		(layer "B.Cu")
		(net "SMB_S3M_CPU1_SDA")
	)
	(segment
		(start 176.61255 -191.548258)
		(end 175.69307 -191.548258)
		(width 0.12954)
		(layer "B.Cu")
		(net "SMB_S3M_CPU1_SDA")
	)
	(segment
		(start 127.928878 -263.370822)
		(end 127.914146 -263.362186)
		(width 0.0889)
		(layer "B.Cu")
		(net "SMB_S3M_CPU1_SDA")
	)
	(segment
		(start 168.579038 -253.14783)
		(end 167.456358 -253.14783)
		(width 0.12954)
		(layer "B.Cu")
		(net "SMB_S3M_CPU1_SDA")
	)
	(segment
		(start 133.567678 -263.370822)
		(end 133.552946 -263.362186)
		(width 0.0889)
		(layer "B.Cu")
		(net "SMB_S3M_CPU1_SDA")
	)
	(segment
		(start 166.783258 -257.41503)
		(end 166.293038 -257.90525)
		(width 0.12954)
		(layer "B.Cu")
		(net "SMB_S3M_CPU1_SDA")
	)
	(segment
		(start 118.526306 -264.995914)
		(end 118.515892 -264.989818)
		(width 0.0889)
		(layer "B.Cu")
		(net "SMB_S3M_CPU1_SDA")
	)
	(segment
		(start 156.524198 -262.3693)
		(end 156.075888 -261.92099)
		(width 0.12954)
		(layer "B.Cu")
		(net "SMB_S3M_CPU1_SDA")
	)
	(segment
		(start 121.750582 -263.422384)
		(end 121.05132 -264.121646)
		(width 0.0889)
		(layer "B.Cu")
		(net "SMB_S3M_CPU1_SDA")
	)
	(segment
		(start 178.70043 -189.460378)
		(end 176.61255 -191.548258)
		(width 0.12954)
		(layer "B.Cu")
		(net "SMB_S3M_CPU1_SDA")
	)
	(segment
		(start 174.865538 -192.37579)
		(end 174.865538 -195.11899)
		(width 0.12954)
		(layer "B.Cu")
		(net "SMB_S3M_CPU1_SDA")
	)
	(segment
		(start 139.816332 -263.215374)
		(end 139.71016 -263.321546)
		(width 0.12954)
		(layer "B.Cu")
		(net "SMB_S3M_CPU1_SDA")
	)
	(segment
		(start 173.153578 -251.26823)
		(end 172.048678 -251.26823)
		(width 0.12954)
		(layer "B.Cu")
		(net "SMB_S3M_CPU1_SDA")
	)
	(segment
		(start 119.4943 -264.121646)
		(end 119.363744 -264.252202)
		(width 0.0889)
		(layer "B.Cu")
		(net "SMB_S3M_CPU1_SDA")
	)
	(segment
		(start 115.711478 -264.998454)
		(end 115.696746 -264.989818)
		(width 0.0889)
		(layer "B.Cu")
		(net "SMB_S3M_CPU1_SDA")
	)
	(segment
		(start 139.71016 -263.33069)
		(end 139.394946 -263.461246)
		(width 0.0889)
		(layer "B.Cu")
		(net "SMB_S3M_CPU1_SDA")
	)
	(segment
		(start 174.558198 -196.81317)
		(end 173.877478 -197.49389)
		(width 0.12954)
		(layer "B.Cu")
		(net "SMB_S3M_CPU1_SDA")
	)
	(segment
		(start 173.877478 -250.54433)
		(end 173.153578 -251.26823)
		(width 0.12954)
		(layer "B.Cu")
		(net "SMB_S3M_CPU1_SDA")
	)
	(segment
		(start 174.865538 -195.11899)
		(end 174.558198 -195.42633)
		(width 0.12954)
		(layer "B.Cu")
		(net "SMB_S3M_CPU1_SDA")
	)
	(segment
		(start 121.05132 -264.121646)
		(end 119.4943 -264.121646)
		(width 0.0889)
		(layer "B.Cu")
		(net "SMB_S3M_CPU1_SDA")
	)
	(segment
		(start 164.263578 -263.22655)
		(end 161.601658 -263.22655)
		(width 0.12954)
		(layer "B.Cu")
		(net "SMB_S3M_CPU1_SDA")
	)
	(segment
		(start 171.875958 -251.44095)
		(end 170.285918 -251.44095)
		(width 0.12954)
		(layer "B.Cu")
		(net "SMB_S3M_CPU1_SDA")
	)
	(segment
		(start 114.864388 -265.796522)
		(end 114.843306 -265.808714)
		(width 0.0889)
		(layer "B.Cu")
		(net "SMB_S3M_CPU1_SDA")
	)
	(segment
		(start 126.989078 -263.370822)
		(end 126.974346 -263.362186)
		(width 0.0889)
		(layer "B.Cu")
		(net "SMB_S3M_CPU1_SDA")
	)
	(segment
		(start 132.627878 -263.370822)
		(end 132.613146 -263.362186)
		(width 0.0889)
		(layer "B.Cu")
		(net "SMB_S3M_CPU1_SDA")
	)
	(segment
		(start 139.394946 -263.461246)
		(end 137.681716 -263.461246)
		(width 0.0889)
		(layer "B.Cu")
		(net "SMB_S3M_CPU1_SDA")
	)
	(segment
		(start 126.049278 -263.370822)
		(end 126.034546 -263.362186)
		(width 0.0889)
		(layer "B.Cu")
		(net "SMB_S3M_CPU1_SDA")
	)
	(segment
		(start 156.075888 -261.92099)
		(end 150.445978 -261.92099)
		(width 0.12954)
		(layer "B.Cu")
		(net "SMB_S3M_CPU1_SDA")
	)
	(segment
		(start 173.877478 -197.49389)
		(end 173.877478 -250.54433)
		(width 0.12954)
		(layer "B.Cu")
		(net "SMB_S3M_CPU1_SDA")
	)
	(segment
		(start 129.803906 -263.368282)
		(end 129.793492 -263.362186)
		(width 0.0889)
		(layer "B.Cu")
		(net "SMB_S3M_CPU1_SDA")
	)
	(segment
		(start 134.50316 -263.368282)
		(end 134.492746 -263.362186)
		(width 0.0889)
		(layer "B.Cu")
		(net "SMB_S3M_CPU1_SDA")
	)
	(segment
		(start 114.664744 -266.127992)
		(end 114.664744 -266.143486)
		(width 0.0889)
		(layer "B.Cu")
		(net "SMB_S3M_CPU1_SDA")
	)
	(segment
		(start 117.58676 -264.995914)
		(end 117.576346 -264.989818)
		(width 0.0889)
		(layer "B.Cu")
		(net "SMB_S3M_CPU1_SDA")
	)
	(segment
		(start 166.293038 -257.90525)
		(end 166.293038 -261.720584)
		(width 0.12954)
		(layer "B.Cu")
		(net "SMB_S3M_CPU1_SDA")
	)
	(segment
		(start 166.783258 -253.82093)
		(end 166.783258 -257.41503)
		(width 0.12954)
		(layer "B.Cu")
		(net "SMB_S3M_CPU1_SDA")
	)
	(segment
		(start 116.651278 -264.998454)
		(end 116.636546 -264.989818)
		(width 0.0889)
		(layer "B.Cu")
		(net "SMB_S3M_CPU1_SDA")
	)
	(segment
		(start 114.726212 -267.212826)
		(end 114.569748 -266.941808)
		(width 0.0889)
		(layer "B.Cu")
		(net "SMB_S3M_CPU1_SDA")
	)
	(segment
		(start 165.602412 -262.41121)
		(end 165.078918 -262.41121)
		(width 0.12954)
		(layer "B.Cu")
		(net "SMB_S3M_CPU1_SDA")
	)
	(segment
		(start 122.840496 -263.362186)
		(end 122.830082 -263.368282)
		(width 0.0889)
		(layer "B.Cu")
		(net "SMB_S3M_CPU1_SDA")
	)
	(arc
		(start 133.552946 -263.362186)
		(mid 133.365748 -263.312043)
		(end 133.17855 -263.362186)
		(width 0.0889)
		(layer "B.Cu")
		(net "SMB_S3M_CPU1_SDA")
	)
	(arc
		(start 125.094746 -263.362186)
		(mid 124.907548 -263.312043)
		(end 124.72035 -263.362186)
		(width 0.0889)
		(layer "B.Cu")
		(net "SMB_S3M_CPU1_SDA")
	)
	(arc
		(start 129.793492 -263.362186)
		(mid 129.606294 -263.312043)
		(end 129.419096 -263.362186)
		(width 0.0889)
		(layer "B.Cu")
		(net "SMB_S3M_CPU1_SDA")
	)
	(arc
		(start 137.311892 -263.362186)
		(mid 137.124694 -263.312043)
		(end 136.937496 -263.362186)
		(width 0.0889)
		(layer "B.Cu")
		(net "SMB_S3M_CPU1_SDA")
	)
	(arc
		(start 127.914146 -263.362186)
		(mid 127.726948 -263.312043)
		(end 127.53975 -263.362186)
		(width 0.0889)
		(layer "B.Cu")
		(net "SMB_S3M_CPU1_SDA")
	)
	(arc
		(start 135.057896 -263.362186)
		(mid 134.781337 -263.437895)
		(end 134.50316 -263.368282)
		(width 0.0889)
		(layer "B.Cu")
		(net "SMB_S3M_CPU1_SDA")
	)
	(arc
		(start 134.492746 -263.362186)
		(mid 134.305548 -263.312043)
		(end 134.11835 -263.362186)
		(width 0.0889)
		(layer "B.Cu")
		(net "SMB_S3M_CPU1_SDA")
	)
	(arc
		(start 126.974346 -263.362186)
		(mid 126.787148 -263.312043)
		(end 126.59995 -263.362186)
		(width 0.0889)
		(layer "B.Cu")
		(net "SMB_S3M_CPU1_SDA")
	)
	(arc
		(start 117.576346 -264.989818)
		(mid 117.389148 -264.939675)
		(end 117.20195 -264.989818)
		(width 0.0889)
		(layer "B.Cu")
		(net "SMB_S3M_CPU1_SDA")
	)
	(arc
		(start 118.515892 -264.989818)
		(mid 118.328694 -264.939675)
		(end 118.141496 -264.989818)
		(width 0.0889)
		(layer "B.Cu")
		(net "SMB_S3M_CPU1_SDA")
	)
	(arc
		(start 136.372092 -263.362186)
		(mid 136.184894 -263.312043)
		(end 135.997696 -263.362186)
		(width 0.0889)
		(layer "B.Cu")
		(net "SMB_S3M_CPU1_SDA")
	)
	(arc
		(start 124.72035 -263.362186)
		(mid 124.446121 -263.438111)
		(end 124.169678 -263.370822)
		(width 0.0889)
		(layer "B.Cu")
		(net "SMB_S3M_CPU1_SDA")
	)
	(arc
		(start 114.843306 -265.808714)
		(mid 114.712392 -265.945074)
		(end 114.664744 -266.127992)
		(width 0.0889)
		(layer "B.Cu")
		(net "SMB_S3M_CPU1_SDA")
	)
	(arc
		(start 130.35915 -263.362186)
		(mid 130.082337 -263.438022)
		(end 129.803906 -263.368282)
		(width 0.0889)
		(layer "B.Cu")
		(net "SMB_S3M_CPU1_SDA")
	)
	(arc
		(start 121.90095 -263.362186)
		(mid 121.827929 -263.397685)
		(end 121.750582 -263.422384)
		(width 0.0889)
		(layer "B.Cu")
		(net "SMB_S3M_CPU1_SDA")
	)
	(arc
		(start 134.11835 -263.362186)
		(mid 133.844121 -263.438111)
		(end 133.567678 -263.370822)
		(width 0.0889)
		(layer "B.Cu")
		(net "SMB_S3M_CPU1_SDA")
	)
	(arc
		(start 122.830082 -263.368282)
		(mid 122.551904 -263.437974)
		(end 122.275346 -263.362186)
		(width 0.0889)
		(layer "B.Cu")
		(net "SMB_S3M_CPU1_SDA")
	)
	(arc
		(start 131.673346 -263.362186)
		(mid 131.486148 -263.312043)
		(end 131.29895 -263.362186)
		(width 0.0889)
		(layer "B.Cu")
		(net "SMB_S3M_CPU1_SDA")
	)
	(arc
		(start 131.29895 -263.362186)
		(mid 131.024721 -263.438111)
		(end 130.748278 -263.370822)
		(width 0.0889)
		(layer "B.Cu")
		(net "SMB_S3M_CPU1_SDA")
	)
	(arc
		(start 130.733546 -263.362186)
		(mid 130.546348 -263.312043)
		(end 130.35915 -263.362186)
		(width 0.0889)
		(layer "B.Cu")
		(net "SMB_S3M_CPU1_SDA")
	)
	(arc
		(start 127.53975 -263.362186)
		(mid 127.265521 -263.438111)
		(end 126.989078 -263.370822)
		(width 0.0889)
		(layer "B.Cu")
		(net "SMB_S3M_CPU1_SDA")
	)
	(arc
		(start 133.17855 -263.362186)
		(mid 132.904321 -263.438111)
		(end 132.627878 -263.370822)
		(width 0.0889)
		(layer "B.Cu")
		(net "SMB_S3M_CPU1_SDA")
	)
	(arc
		(start 116.26215 -264.989818)
		(mid 115.987951 -265.065653)
		(end 115.711478 -264.998454)
		(width 0.0889)
		(layer "B.Cu")
		(net "SMB_S3M_CPU1_SDA")
	)
	(arc
		(start 117.20195 -264.989818)
		(mid 116.927751 -265.065653)
		(end 116.651278 -264.998454)
		(width 0.0889)
		(layer "B.Cu")
		(net "SMB_S3M_CPU1_SDA")
	)
	(arc
		(start 135.432292 -263.362186)
		(mid 135.245094 -263.312043)
		(end 135.057896 -263.362186)
		(width 0.0889)
		(layer "B.Cu")
		(net "SMB_S3M_CPU1_SDA")
	)
	(arc
		(start 129.419096 -263.362186)
		(mid 129.142537 -263.437895)
		(end 128.86436 -263.368282)
		(width 0.0889)
		(layer "B.Cu")
		(net "SMB_S3M_CPU1_SDA")
	)
	(arc
		(start 114.664744 -266.143486)
		(mid 114.585374 -266.41722)
		(end 114.38255 -266.61745)
		(width 0.0889)
		(layer "B.Cu")
		(net "SMB_S3M_CPU1_SDA")
	)
	(arc
		(start 123.78055 -263.362186)
		(mid 123.503737 -263.438022)
		(end 123.225306 -263.368282)
		(width 0.0889)
		(layer "B.Cu")
		(net "SMB_S3M_CPU1_SDA")
	)
	(arc
		(start 126.034546 -263.362186)
		(mid 125.847348 -263.312043)
		(end 125.66015 -263.362186)
		(width 0.0889)
		(layer "B.Cu")
		(net "SMB_S3M_CPU1_SDA")
	)
	(arc
		(start 135.997696 -263.362186)
		(mid 135.714994 -263.437928)
		(end 135.432292 -263.362186)
		(width 0.0889)
		(layer "B.Cu")
		(net "SMB_S3M_CPU1_SDA")
	)
	(arc
		(start 124.154946 -263.362186)
		(mid 123.967748 -263.312043)
		(end 123.78055 -263.362186)
		(width 0.0889)
		(layer "B.Cu")
		(net "SMB_S3M_CPU1_SDA")
	)
	(arc
		(start 115.134898 -265.314176)
		(mid 115.062663 -265.5907)
		(end 114.864388 -265.796522)
		(width 0.0889)
		(layer "B.Cu")
		(net "SMB_S3M_CPU1_SDA")
	)
	(arc
		(start 132.613146 -263.362186)
		(mid 132.425948 -263.312043)
		(end 132.23875 -263.362186)
		(width 0.0889)
		(layer "B.Cu")
		(net "SMB_S3M_CPU1_SDA")
	)
	(arc
		(start 128.853946 -263.362186)
		(mid 128.666748 -263.312043)
		(end 128.47955 -263.362186)
		(width 0.0889)
		(layer "B.Cu")
		(net "SMB_S3M_CPU1_SDA")
	)
	(arc
		(start 118.141496 -264.989818)
		(mid 117.864937 -265.065561)
		(end 117.58676 -264.995914)
		(width 0.0889)
		(layer "B.Cu")
		(net "SMB_S3M_CPU1_SDA")
	)
	(arc
		(start 122.275346 -263.362186)
		(mid 122.088148 -263.312043)
		(end 121.90095 -263.362186)
		(width 0.0889)
		(layer "B.Cu")
		(net "SMB_S3M_CPU1_SDA")
	)
	(arc
		(start 114.37366 -266.62253)
		(mid 114.233948 -267.108236)
		(end 114.70513 -267.290804)
		(width 0.0889)
		(layer "B.Cu")
		(net "SMB_S3M_CPU1_SDA")
	)
	(arc
		(start 126.59995 -263.362186)
		(mid 126.325721 -263.438111)
		(end 126.049278 -263.370822)
		(width 0.0889)
		(layer "B.Cu")
		(net "SMB_S3M_CPU1_SDA")
	)
	(arc
		(start 128.47955 -263.362186)
		(mid 128.205321 -263.438111)
		(end 127.928878 -263.370822)
		(width 0.0889)
		(layer "B.Cu")
		(net "SMB_S3M_CPU1_SDA")
	)
	(arc
		(start 116.636546 -264.989818)
		(mid 116.449348 -264.939675)
		(end 116.26215 -264.989818)
		(width 0.0889)
		(layer "B.Cu")
		(net "SMB_S3M_CPU1_SDA")
	)
	(arc
		(start 123.214892 -263.362186)
		(mid 123.027694 -263.312043)
		(end 122.840496 -263.362186)
		(width 0.0889)
		(layer "B.Cu")
		(net "SMB_S3M_CPU1_SDA")
	)
	(arc
		(start 119.363744 -264.515854)
		(mid 119.079746 -264.990858)
		(end 118.526306 -264.995914)
		(width 0.0889)
		(layer "B.Cu")
		(net "SMB_S3M_CPU1_SDA")
	)
	(arc
		(start 132.23875 -263.362186)
		(mid 131.956048 -263.437928)
		(end 131.673346 -263.362186)
		(width 0.0889)
		(layer "B.Cu")
		(net "SMB_S3M_CPU1_SDA")
	)
	(arc
		(start 125.66015 -263.362186)
		(mid 125.377448 -263.437928)
		(end 125.094746 -263.362186)
		(width 0.0889)
		(layer "B.Cu")
		(net "SMB_S3M_CPU1_SDA")
	)
	(arc
		(start 115.696746 -264.989818)
		(mid 115.322271 -264.989864)
		(end 115.134898 -265.314176)
		(width 0.0889)
		(layer "B.Cu")
		(net "SMB_S3M_CPU1_SDA")
	)
	(arc
		(start 136.937496 -263.362186)
		(mid 136.654794 -263.437928)
		(end 136.372092 -263.362186)
		(width 0.0889)
		(layer "B.Cu")
		(net "SMB_S3M_CPU1_SDA")
	)
	(arc
		(start 137.681716 -263.461246)
		(mid 137.490289 -263.436045)
		(end 137.311892 -263.362186)
		(width 0.0889)
		(layer "B.Cu")
		(net "SMB_S3M_CPU1_SDA")
	)
	(segment
		(start 217.807794 -191.966088)
		(end 222.09506 -196.253354)
		(width 0.12954)
		(layer "F.Cu")
		(net "SMB_S3M_CPU1_SCL")
	)
	(segment
		(start 182.044086 -187.216288)
		(end 193.855086 -187.216288)
		(width 0.12954)
		(layer "F.Cu")
		(net "SMB_S3M_CPU1_SCL")
	)
	(segment
		(start 177.927 -189.906148)
		(end 178.05527 -190.034418)
		(width 0.12954)
		(layer "F.Cu")
		(net "SMB_S3M_CPU1_SCL")
	)
	(segment
		(start 194.630294 -186.44108)
		(end 202.554586 -186.44108)
		(width 0.12954)
		(layer "F.Cu")
		(net "SMB_S3M_CPU1_SCL")
	)
	(segment
		(start 215.516714 -191.102488)
		(end 216.380314 -191.966088)
		(width 0.12954)
		(layer "F.Cu")
		(net "SMB_S3M_CPU1_SCL")
	)
	(segment
		(start 209.19186 -188.054234)
		(end 212.240114 -191.102488)
		(width 0.12954)
		(layer "F.Cu")
		(net "SMB_S3M_CPU1_SCL")
	)
	(segment
		(start 225.525838 -218.358212)
		(end 225.525838 -220.415866)
		(width 0.12954)
		(layer "F.Cu")
		(net "SMB_S3M_CPU1_SCL")
	)
	(segment
		(start 216.380314 -191.966088)
		(end 217.807794 -191.966088)
		(width 0.12954)
		(layer "F.Cu")
		(net "SMB_S3M_CPU1_SCL")
	)
	(segment
		(start 202.554586 -186.44108)
		(end 204.16774 -188.054234)
		(width 0.12954)
		(layer "F.Cu")
		(net "SMB_S3M_CPU1_SCL")
	)
	(segment
		(start 179.225956 -190.034418)
		(end 182.044086 -187.216288)
		(width 0.12954)
		(layer "F.Cu")
		(net "SMB_S3M_CPU1_SCL")
	)
	(segment
		(start 212.240114 -191.102488)
		(end 215.516714 -191.102488)
		(width 0.12954)
		(layer "F.Cu")
		(net "SMB_S3M_CPU1_SCL")
	)
	(segment
		(start 115.039648 -267.219938)
		(end 115.039394 -267.755878)
		(width 0.12954)
		(layer "F.Cu")
		(net "SMB_S3M_CPU1_SCL")
	)
	(segment
		(start 222.09506 -214.927434)
		(end 225.525838 -218.358212)
		(width 0.12954)
		(layer "F.Cu")
		(net "SMB_S3M_CPU1_SCL")
	)
	(segment
		(start 177.927 -189.448948)
		(end 177.927 -189.906148)
		(width 0.12954)
		(layer "F.Cu")
		(net "SMB_S3M_CPU1_SCL")
	)
	(segment
		(start 204.16774 -188.054234)
		(end 209.19186 -188.054234)
		(width 0.12954)
		(layer "F.Cu")
		(net "SMB_S3M_CPU1_SCL")
	)
	(segment
		(start 178.05527 -190.034418)
		(end 179.225956 -190.034418)
		(width 0.12954)
		(layer "F.Cu")
		(net "SMB_S3M_CPU1_SCL")
	)
	(segment
		(start 222.09506 -196.253354)
		(end 222.09506 -214.927434)
		(width 0.12954)
		(layer "F.Cu")
		(net "SMB_S3M_CPU1_SCL")
	)
	(segment
		(start 193.855086 -187.216288)
		(end 194.630294 -186.44108)
		(width 0.12954)
		(layer "F.Cu")
		(net "SMB_S3M_CPU1_SCL")
	)
	(via
		(at 115.039394 -267.755878)
		(size 0.4572)
		(drill 0.2032)
		(layers "F.Cu" "B.Cu")
		(net "SMB_S3M_CPU1_SCL")
	)
	(via
		(at 142.533878 -261.55269)
		(size 0.6604)
		(drill 0.3302)
		(layers "F.Cu" "B.Cu")
		(net "SMB_S3M_CPU1_SCL")
	)
	(via
		(at 177.927 -189.448948)
		(size 0.508)
		(drill 0.254)
		(layers "F.Cu" "B.Cu")
		(net "SMB_S3M_CPU1_SCL")
	)
	(segment
		(start 122.75566 -263.190736)
		(end 122.745246 -263.196832)
		(width 0.0889)
		(layer "B.Cu")
		(net "SMB_S3M_CPU1_SCL")
	)
	(segment
		(start 134.587996 -263.196832)
		(end 134.573264 -263.188196)
		(width 0.0889)
		(layer "B.Cu")
		(net "SMB_S3M_CPU1_SCL")
	)
	(segment
		(start 126.129796 -263.196832)
		(end 126.119382 -263.190736)
		(width 0.0889)
		(layer "B.Cu")
		(net "SMB_S3M_CPU1_SCL")
	)
	(segment
		(start 114.286792 -266.45235)
		(end 114.280696 -266.455906)
		(width 0.0889)
		(layer "B.Cu")
		(net "SMB_S3M_CPU1_SCL")
	)
	(segment
		(start 122.37085 -263.196832)
		(end 122.360436 -263.190736)
		(width 0.0889)
		(layer "B.Cu")
		(net "SMB_S3M_CPU1_SCL")
	)
	(segment
		(start 174.111158 -195.24853)
		(end 174.111158 -196.64299)
		(width 0.12954)
		(layer "B.Cu")
		(net "SMB_S3M_CPU1_SCL")
	)
	(segment
		(start 121.61774 -263.247886)
		(end 121.583958 -263.247886)
		(width 0.0889)
		(layer "B.Cu")
		(net "SMB_S3M_CPU1_SCL")
	)
	(segment
		(start 139.207748 -261.55269)
		(end 138.404346 -262.356092)
		(width 0.12954)
		(layer "B.Cu")
		(net "SMB_S3M_CPU1_SCL")
	)
	(segment
		(start 133.648196 -263.196832)
		(end 133.633464 -263.188196)
		(width 0.0889)
		(layer "B.Cu")
		(net "SMB_S3M_CPU1_SCL")
	)
	(segment
		(start 142.533878 -261.55269)
		(end 139.207748 -261.55269)
		(width 0.12954)
		(layer "B.Cu")
		(net "SMB_S3M_CPU1_SCL")
	)
	(segment
		(start 128.009396 -263.196832)
		(end 127.994664 -263.188196)
		(width 0.0889)
		(layer "B.Cu")
		(net "SMB_S3M_CPU1_SCL")
	)
	(segment
		(start 117.671596 -264.824718)
		(end 117.656864 -264.816082)
		(width 0.0889)
		(layer "B.Cu")
		(net "SMB_S3M_CPU1_SCL")
	)
	(segment
		(start 177.927 -189.448948)
		(end 177.927 -189.476888)
		(width 0.12954)
		(layer "B.Cu")
		(net "SMB_S3M_CPU1_SCL")
	)
	(segment
		(start 176.308258 -191.09563)
		(end 175.520604 -191.09563)
		(width 0.12954)
		(layer "B.Cu")
		(net "SMB_S3M_CPU1_SCL")
	)
	(segment
		(start 128.949196 -263.196832)
		(end 128.934464 -263.188196)
		(width 0.0889)
		(layer "B.Cu")
		(net "SMB_S3M_CPU1_SCL")
	)
	(segment
		(start 118.994682 -264.819638)
		(end 118.985792 -264.824718)
		(width 0.0889)
		(layer "B.Cu")
		(net "SMB_S3M_CPU1_SCL")
	)
	(segment
		(start 171.025058 -250.04141)
		(end 168.523158 -252.54331)
		(width 0.12954)
		(layer "B.Cu")
		(net "SMB_S3M_CPU1_SCL")
	)
	(segment
		(start 114.88293 -267.48486)
		(end 115.039394 -267.755878)
		(width 0.0889)
		(layer "B.Cu")
		(net "SMB_S3M_CPU1_SCL")
	)
	(segment
		(start 167.176958 -252.54331)
		(end 166.346378 -253.37389)
		(width 0.12954)
		(layer "B.Cu")
		(net "SMB_S3M_CPU1_SCL")
	)
	(segment
		(start 115.226592 -264.824718)
		(end 115.220496 -264.828274)
		(width 0.0889)
		(layer "B.Cu")
		(net "SMB_S3M_CPU1_SCL")
	)
	(segment
		(start 173.245018 -249.56897)
		(end 172.035978 -249.56897)
		(width 0.12954)
		(layer "B.Cu")
		(net "SMB_S3M_CPU1_SCL")
	)
	(segment
		(start 166.346378 -257.17373)
		(end 165.833298 -257.68681)
		(width 0.12954)
		(layer "B.Cu")
		(net "SMB_S3M_CPU1_SCL")
	)
	(segment
		(start 138.002772 -262.757666)
		(end 138.002772 -263.05002)
		(width 0.0889)
		(layer "B.Cu")
		(net "SMB_S3M_CPU1_SCL")
	)
	(segment
		(start 119.415306 -263.931146)
		(end 119.173244 -264.173208)
		(width 0.0889)
		(layer "B.Cu")
		(net "SMB_S3M_CPU1_SCL")
	)
	(segment
		(start 165.833298 -257.68681)
		(end 165.833298 -260.42747)
		(width 0.12954)
		(layer "B.Cu")
		(net "SMB_S3M_CPU1_SCL")
	)
	(segment
		(start 119.173244 -264.173208)
		(end 119.173244 -264.50036)
		(width 0.0889)
		(layer "B.Cu")
		(net "SMB_S3M_CPU1_SCL")
	)
	(segment
		(start 161.563558 -262.19277)
		(end 160.575498 -261.20471)
		(width 0.12954)
		(layer "B.Cu")
		(net "SMB_S3M_CPU1_SCL")
	)
	(segment
		(start 125.19025 -263.196832)
		(end 125.179836 -263.190736)
		(width 0.0889)
		(layer "B.Cu")
		(net "SMB_S3M_CPU1_SCL")
	)
	(segment
		(start 168.523158 -252.54331)
		(end 167.176958 -252.54331)
		(width 0.12954)
		(layer "B.Cu")
		(net "SMB_S3M_CPU1_SCL")
	)
	(segment
		(start 174.418498 -192.197736)
		(end 174.418498 -194.94119)
		(width 0.12954)
		(layer "B.Cu")
		(net "SMB_S3M_CPU1_SCL")
	)
	(segment
		(start 174.111158 -196.64299)
		(end 173.374558 -197.37959)
		(width 0.12954)
		(layer "B.Cu")
		(net "SMB_S3M_CPU1_SCL")
	)
	(segment
		(start 143.168878 -261.55269)
		(end 142.533878 -261.55269)
		(width 0.12954)
		(layer "B.Cu")
		(net "SMB_S3M_CPU1_SCL")
	)
	(segment
		(start 173.374558 -249.43943)
		(end 173.245018 -249.56897)
		(width 0.12954)
		(layer "B.Cu")
		(net "SMB_S3M_CPU1_SCL")
	)
	(segment
		(start 114.765582 -265.633454)
		(end 114.756692 -265.638534)
		(width 0.0889)
		(layer "B.Cu")
		(net "SMB_S3M_CPU1_SCL")
	)
	(segment
		(start 132.708396 -263.196832)
		(end 132.697982 -263.190736)
		(width 0.0889)
		(layer "B.Cu")
		(net "SMB_S3M_CPU1_SCL")
	)
	(segment
		(start 172.035978 -249.56897)
		(end 171.563538 -250.04141)
		(width 0.12954)
		(layer "B.Cu")
		(net "SMB_S3M_CPU1_SCL")
	)
	(segment
		(start 114.474244 -266.118086)
		(end 114.474244 -266.127992)
		(width 0.0889)
		(layer "B.Cu")
		(net "SMB_S3M_CPU1_SCL")
	)
	(segment
		(start 131.76885 -263.196832)
		(end 131.758436 -263.190736)
		(width 0.0889)
		(layer "B.Cu")
		(net "SMB_S3M_CPU1_SCL")
	)
	(segment
		(start 175.520604 -191.09563)
		(end 174.418498 -192.197736)
		(width 0.12954)
		(layer "B.Cu")
		(net "SMB_S3M_CPU1_SCL")
	)
	(segment
		(start 171.563538 -250.04141)
		(end 171.025058 -250.04141)
		(width 0.12954)
		(layer "B.Cu")
		(net "SMB_S3M_CPU1_SCL")
	)
	(segment
		(start 130.828796 -263.196832)
		(end 130.814064 -263.188196)
		(width 0.0889)
		(layer "B.Cu")
		(net "SMB_S3M_CPU1_SCL")
	)
	(segment
		(start 124.250196 -263.196832)
		(end 124.235464 -263.188196)
		(width 0.0889)
		(layer "B.Cu")
		(net "SMB_S3M_CPU1_SCL")
	)
	(segment
		(start 121.583958 -263.247886)
		(end 120.900698 -263.931146)
		(width 0.0889)
		(layer "B.Cu")
		(net "SMB_S3M_CPU1_SCL")
	)
	(segment
		(start 116.731796 -264.824718)
		(end 116.717064 -264.816082)
		(width 0.0889)
		(layer "B.Cu")
		(net "SMB_S3M_CPU1_SCL")
	)
	(segment
		(start 115.791996 -264.824718)
		(end 115.777264 -264.816082)
		(width 0.0889)
		(layer "B.Cu")
		(net "SMB_S3M_CPU1_SCL")
	)
	(segment
		(start 177.927 -189.476888)
		(end 176.308258 -191.09563)
		(width 0.12954)
		(layer "B.Cu")
		(net "SMB_S3M_CPU1_SCL")
	)
	(segment
		(start 114.79403 -267.461238)
		(end 114.88293 -267.48486)
		(width 0.0889)
		(layer "B.Cu")
		(net "SMB_S3M_CPU1_SCL")
	)
	(segment
		(start 138.002772 -263.05002)
		(end 137.924032 -263.12876)
		(width 0.0889)
		(layer "B.Cu")
		(net "SMB_S3M_CPU1_SCL")
	)
	(segment
		(start 174.418498 -194.94119)
		(end 174.111158 -195.24853)
		(width 0.12954)
		(layer "B.Cu")
		(net "SMB_S3M_CPU1_SCL")
	)
	(segment
		(start 164.067998 -262.19277)
		(end 161.563558 -262.19277)
		(width 0.12954)
		(layer "B.Cu")
		(net "SMB_S3M_CPU1_SCL")
	)
	(segment
		(start 173.374558 -197.37959)
		(end 173.374558 -249.43943)
		(width 0.12954)
		(layer "B.Cu")
		(net "SMB_S3M_CPU1_SCL")
	)
	(segment
		(start 120.900698 -263.931146)
		(end 119.415306 -263.931146)
		(width 0.0889)
		(layer "B.Cu")
		(net "SMB_S3M_CPU1_SCL")
	)
	(segment
		(start 138.404346 -262.356092)
		(end 138.002772 -262.757666)
		(width 0.0889)
		(layer "B.Cu")
		(net "SMB_S3M_CPU1_SCL")
	)
	(segment
		(start 166.346378 -253.37389)
		(end 166.346378 -257.17373)
		(width 0.12954)
		(layer "B.Cu")
		(net "SMB_S3M_CPU1_SCL")
	)
	(segment
		(start 114.004344 -266.941808)
		(end 114.004344 -266.956032)
		(width 0.0889)
		(layer "B.Cu")
		(net "SMB_S3M_CPU1_SCL")
	)
	(segment
		(start 143.516858 -261.20471)
		(end 143.168878 -261.55269)
		(width 0.12954)
		(layer "B.Cu")
		(net "SMB_S3M_CPU1_SCL")
	)
	(segment
		(start 127.069596 -263.196832)
		(end 127.054864 -263.188196)
		(width 0.0889)
		(layer "B.Cu")
		(net "SMB_S3M_CPU1_SCL")
	)
	(segment
		(start 165.833298 -260.42747)
		(end 164.067998 -262.19277)
		(width 0.12954)
		(layer "B.Cu")
		(net "SMB_S3M_CPU1_SCL")
	)
	(segment
		(start 114.295682 -266.44727)
		(end 114.286792 -266.45235)
		(width 0.0889)
		(layer "B.Cu")
		(net "SMB_S3M_CPU1_SCL")
	)
	(segment
		(start 160.575498 -261.20471)
		(end 143.516858 -261.20471)
		(width 0.12954)
		(layer "B.Cu")
		(net "SMB_S3M_CPU1_SCL")
	)
	(arc
		(start 126.119382 -263.190736)
		(mid 125.841204 -263.121044)
		(end 125.564646 -263.196832)
		(width 0.0889)
		(layer "B.Cu")
		(net "SMB_S3M_CPU1_SCL")
	)
	(arc
		(start 125.564646 -263.196832)
		(mid 125.377448 -263.246975)
		(end 125.19025 -263.196832)
		(width 0.0889)
		(layer "B.Cu")
		(net "SMB_S3M_CPU1_SCL")
	)
	(arc
		(start 134.022592 -263.196832)
		(mid 133.835394 -263.246975)
		(end 133.648196 -263.196832)
		(width 0.0889)
		(layer "B.Cu")
		(net "SMB_S3M_CPU1_SCL")
	)
	(arc
		(start 127.443992 -263.196832)
		(mid 127.256794 -263.246975)
		(end 127.069596 -263.196832)
		(width 0.0889)
		(layer "B.Cu")
		(net "SMB_S3M_CPU1_SCL")
	)
	(arc
		(start 114.756692 -265.638534)
		(mid 114.552357 -265.841139)
		(end 114.474244 -266.118086)
		(width 0.0889)
		(layer "B.Cu")
		(net "SMB_S3M_CPU1_SCL")
	)
	(arc
		(start 117.106192 -264.824718)
		(mid 116.918994 -264.874861)
		(end 116.731796 -264.824718)
		(width 0.0889)
		(layer "B.Cu")
		(net "SMB_S3M_CPU1_SCL")
	)
	(arc
		(start 134.962392 -263.196832)
		(mid 134.775194 -263.246975)
		(end 134.587996 -263.196832)
		(width 0.0889)
		(layer "B.Cu")
		(net "SMB_S3M_CPU1_SCL")
	)
	(arc
		(start 114.286792 -267.43152)
		(mid 114.536889 -267.506546)
		(end 114.79403 -267.461238)
		(width 0.0889)
		(layer "B.Cu")
		(net "SMB_S3M_CPU1_SCL")
	)
	(arc
		(start 121.805192 -263.196832)
		(mid 121.714834 -263.234735)
		(end 121.61774 -263.247886)
		(width 0.0889)
		(layer "B.Cu")
		(net "SMB_S3M_CPU1_SCL")
	)
	(arc
		(start 119.173244 -264.50036)
		(mid 119.125565 -264.68326)
		(end 118.994682 -264.819638)
		(width 0.0889)
		(layer "B.Cu")
		(net "SMB_S3M_CPU1_SCL")
	)
	(arc
		(start 117.656864 -264.816082)
		(mid 117.380389 -264.748762)
		(end 117.106192 -264.824718)
		(width 0.0889)
		(layer "B.Cu")
		(net "SMB_S3M_CPU1_SCL")
	)
	(arc
		(start 118.045992 -264.824718)
		(mid 117.858794 -264.874861)
		(end 117.671596 -264.824718)
		(width 0.0889)
		(layer "B.Cu")
		(net "SMB_S3M_CPU1_SCL")
	)
	(arc
		(start 133.633464 -263.188196)
		(mid 133.357023 -263.12103)
		(end 133.082792 -263.196832)
		(width 0.0889)
		(layer "B.Cu")
		(net "SMB_S3M_CPU1_SCL")
	)
	(arc
		(start 126.504192 -263.196832)
		(mid 126.316994 -263.246975)
		(end 126.129796 -263.196832)
		(width 0.0889)
		(layer "B.Cu")
		(net "SMB_S3M_CPU1_SCL")
	)
	(arc
		(start 125.179836 -263.190736)
		(mid 124.901404 -263.120922)
		(end 124.624592 -263.196832)
		(width 0.0889)
		(layer "B.Cu")
		(net "SMB_S3M_CPU1_SCL")
	)
	(arc
		(start 123.310396 -263.196832)
		(mid 123.033837 -263.121123)
		(end 122.75566 -263.190736)
		(width 0.0889)
		(layer "B.Cu")
		(net "SMB_S3M_CPU1_SCL")
	)
	(arc
		(start 136.467596 -263.196832)
		(mid 136.184894 -263.12109)
		(end 135.902192 -263.196832)
		(width 0.0889)
		(layer "B.Cu")
		(net "SMB_S3M_CPU1_SCL")
	)
	(arc
		(start 137.407396 -263.196832)
		(mid 137.124694 -263.12109)
		(end 136.841992 -263.196832)
		(width 0.0889)
		(layer "B.Cu")
		(net "SMB_S3M_CPU1_SCL")
	)
	(arc
		(start 131.203192 -263.196832)
		(mid 131.015994 -263.246975)
		(end 130.828796 -263.196832)
		(width 0.0889)
		(layer "B.Cu")
		(net "SMB_S3M_CPU1_SCL")
	)
	(arc
		(start 128.383792 -263.196832)
		(mid 128.196594 -263.246975)
		(end 128.009396 -263.196832)
		(width 0.0889)
		(layer "B.Cu")
		(net "SMB_S3M_CPU1_SCL")
	)
	(arc
		(start 122.360436 -263.190736)
		(mid 122.082004 -263.120922)
		(end 121.805192 -263.196832)
		(width 0.0889)
		(layer "B.Cu")
		(net "SMB_S3M_CPU1_SCL")
	)
	(arc
		(start 127.994664 -263.188196)
		(mid 127.718223 -263.12103)
		(end 127.443992 -263.196832)
		(width 0.0889)
		(layer "B.Cu")
		(net "SMB_S3M_CPU1_SCL")
	)
	(arc
		(start 123.684792 -263.196832)
		(mid 123.497594 -263.246975)
		(end 123.310396 -263.196832)
		(width 0.0889)
		(layer "B.Cu")
		(net "SMB_S3M_CPU1_SCL")
	)
	(arc
		(start 114.474244 -266.127992)
		(mid 114.426565 -266.310892)
		(end 114.295682 -266.44727)
		(width 0.0889)
		(layer "B.Cu")
		(net "SMB_S3M_CPU1_SCL")
	)
	(arc
		(start 124.235464 -263.188196)
		(mid 123.959023 -263.12103)
		(end 123.684792 -263.196832)
		(width 0.0889)
		(layer "B.Cu")
		(net "SMB_S3M_CPU1_SCL")
	)
	(arc
		(start 135.527796 -263.196832)
		(mid 135.245094 -263.12109)
		(end 134.962392 -263.196832)
		(width 0.0889)
		(layer "B.Cu")
		(net "SMB_S3M_CPU1_SCL")
	)
	(arc
		(start 114.280696 -266.455906)
		(mid 114.078283 -266.662319)
		(end 114.004344 -266.941808)
		(width 0.0889)
		(layer "B.Cu")
		(net "SMB_S3M_CPU1_SCL")
	)
	(arc
		(start 134.573264 -263.188196)
		(mid 134.296823 -263.12103)
		(end 134.022592 -263.196832)
		(width 0.0889)
		(layer "B.Cu")
		(net "SMB_S3M_CPU1_SCL")
	)
	(arc
		(start 115.777264 -264.816082)
		(mid 115.500789 -264.748762)
		(end 115.226592 -264.824718)
		(width 0.0889)
		(layer "B.Cu")
		(net "SMB_S3M_CPU1_SCL")
	)
	(arc
		(start 137.924032 -263.12876)
		(mid 137.677254 -263.250494)
		(end 137.407396 -263.196832)
		(width 0.0889)
		(layer "B.Cu")
		(net "SMB_S3M_CPU1_SCL")
	)
	(arc
		(start 114.944144 -265.314176)
		(mid 114.896465 -265.497076)
		(end 114.765582 -265.633454)
		(width 0.0889)
		(layer "B.Cu")
		(net "SMB_S3M_CPU1_SCL")
	)
	(arc
		(start 114.004344 -266.956032)
		(mid 114.083485 -267.230655)
		(end 114.286792 -267.43152)
		(width 0.0889)
		(layer "B.Cu")
		(net "SMB_S3M_CPU1_SCL")
	)
	(arc
		(start 115.220496 -264.828274)
		(mid 115.018083 -265.034687)
		(end 114.944144 -265.314176)
		(width 0.0889)
		(layer "B.Cu")
		(net "SMB_S3M_CPU1_SCL")
	)
	(arc
		(start 124.624592 -263.196832)
		(mid 124.437394 -263.246975)
		(end 124.250196 -263.196832)
		(width 0.0889)
		(layer "B.Cu")
		(net "SMB_S3M_CPU1_SCL")
	)
	(arc
		(start 131.758436 -263.190736)
		(mid 131.480004 -263.120922)
		(end 131.203192 -263.196832)
		(width 0.0889)
		(layer "B.Cu")
		(net "SMB_S3M_CPU1_SCL")
	)
	(arc
		(start 128.934464 -263.188196)
		(mid 128.658023 -263.12103)
		(end 128.383792 -263.196832)
		(width 0.0889)
		(layer "B.Cu")
		(net "SMB_S3M_CPU1_SCL")
	)
	(arc
		(start 118.985792 -264.824718)
		(mid 118.798594 -264.874861)
		(end 118.611396 -264.824718)
		(width 0.0889)
		(layer "B.Cu")
		(net "SMB_S3M_CPU1_SCL")
	)
	(arc
		(start 129.888996 -263.196832)
		(mid 129.606294 -263.12109)
		(end 129.323592 -263.196832)
		(width 0.0889)
		(layer "B.Cu")
		(net "SMB_S3M_CPU1_SCL")
	)
	(arc
		(start 132.697982 -263.190736)
		(mid 132.419804 -263.121044)
		(end 132.143246 -263.196832)
		(width 0.0889)
		(layer "B.Cu")
		(net "SMB_S3M_CPU1_SCL")
	)
	(arc
		(start 116.717064 -264.816082)
		(mid 116.440589 -264.748762)
		(end 116.166392 -264.824718)
		(width 0.0889)
		(layer "B.Cu")
		(net "SMB_S3M_CPU1_SCL")
	)
	(arc
		(start 133.082792 -263.196832)
		(mid 132.895594 -263.246975)
		(end 132.708396 -263.196832)
		(width 0.0889)
		(layer "B.Cu")
		(net "SMB_S3M_CPU1_SCL")
	)
	(arc
		(start 129.323592 -263.196832)
		(mid 129.136394 -263.246975)
		(end 128.949196 -263.196832)
		(width 0.0889)
		(layer "B.Cu")
		(net "SMB_S3M_CPU1_SCL")
	)
	(arc
		(start 116.166392 -264.824718)
		(mid 115.979194 -264.874861)
		(end 115.791996 -264.824718)
		(width 0.0889)
		(layer "B.Cu")
		(net "SMB_S3M_CPU1_SCL")
	)
	(arc
		(start 118.611396 -264.824718)
		(mid 118.328694 -264.748942)
		(end 118.045992 -264.824718)
		(width 0.0889)
		(layer "B.Cu")
		(net "SMB_S3M_CPU1_SCL")
	)
	(arc
		(start 127.054864 -263.188196)
		(mid 126.778423 -263.12103)
		(end 126.504192 -263.196832)
		(width 0.0889)
		(layer "B.Cu")
		(net "SMB_S3M_CPU1_SCL")
	)
	(arc
		(start 135.902192 -263.196832)
		(mid 135.714994 -263.246975)
		(end 135.527796 -263.196832)
		(width 0.0889)
		(layer "B.Cu")
		(net "SMB_S3M_CPU1_SCL")
	)
	(arc
		(start 136.841992 -263.196832)
		(mid 136.654794 -263.246975)
		(end 136.467596 -263.196832)
		(width 0.0889)
		(layer "B.Cu")
		(net "SMB_S3M_CPU1_SCL")
	)
	(arc
		(start 122.745246 -263.196832)
		(mid 122.558048 -263.246975)
		(end 122.37085 -263.196832)
		(width 0.0889)
		(layer "B.Cu")
		(net "SMB_S3M_CPU1_SCL")
	)
	(arc
		(start 130.263392 -263.196832)
		(mid 130.076194 -263.246975)
		(end 129.888996 -263.196832)
		(width 0.0889)
		(layer "B.Cu")
		(net "SMB_S3M_CPU1_SCL")
	)
	(arc
		(start 130.814064 -263.188196)
		(mid 130.537623 -263.12103)
		(end 130.263392 -263.196832)
		(width 0.0889)
		(layer "B.Cu")
		(net "SMB_S3M_CPU1_SCL")
	)
	(arc
		(start 132.143246 -263.196832)
		(mid 131.956048 -263.246975)
		(end 131.76885 -263.196832)
		(width 0.0889)
		(layer "B.Cu")
		(net "SMB_S3M_CPU1_SCL")
	)
	(segment
		(start 226.503738 -222.09887)
		(end 226.503738 -221.215966)
		(width 0.12954)
		(layer "F.Cu")
		(net "SMB_S3M_CPU1_R_SDA")
	)
	(segment
		(start 226.503738 -222.56623)
		(end 226.671632 -222.734124)
		(width 0.12954)
		(layer "F.Cu")
		(net "SMB_S3M_CPU1_R_SDA")
	)
	(segment
		(start 226.671632 -223.3168)
		(end 226.671632 -224.124012)
		(width 0.12954)
		(layer "F.Cu")
		(net "SMB_S3M_CPU1_R_SDA")
	)
	(segment
		(start 226.671632 -222.734124)
		(end 226.671632 -223.3168)
		(width 0.12954)
		(layer "F.Cu")
		(net "SMB_S3M_CPU1_R_SDA")
	)
	(segment
		(start 226.503738 -222.09887)
		(end 226.503738 -222.56623)
		(width 0.12954)
		(layer "F.Cu")
		(net "SMB_S3M_CPU1_R_SDA")
	)
	(segment
		(start 226.671632 -224.124012)
		(end 226.568 -224.227644)
		(width 0.12954)
		(layer "F.Cu")
		(net "SMB_S3M_CPU1_R_SDA")
	)
	(segment
		(start 226.568 -224.227644)
		(end 226.568 -225.288348)
		(width 0.12954)
		(layer "F.Cu")
		(net "SMB_S3M_CPU1_R_SDA")
	)
	(via
		(at 226.671632 -223.3168)
		(size 0.762)
		(drill 0.381)
		(layers "F.Cu" "B.Cu")
		(net "SMB_S3M_CPU1_R_SDA")
	)
	(segment
		(start 225.525838 -222.09887)
		(end 225.525838 -221.215966)
		(width 0.12954)
		(layer "F.Cu")
		(net "SMB_S3M_CPU1_R_SCL")
	)
	(segment
		(start 225.334068 -224.037144)
		(end 225.298 -224.073212)
		(width 0.12954)
		(layer "F.Cu")
		(net "SMB_S3M_CPU1_R_SCL")
	)
	(segment
		(start 225.525838 -222.58147)
		(end 225.334068 -222.77324)
		(width 0.12954)
		(layer "F.Cu")
		(net "SMB_S3M_CPU1_R_SCL")
	)
	(segment
		(start 225.334068 -222.77324)
		(end 225.334068 -223.31553)
		(width 0.12954)
		(layer "F.Cu")
		(net "SMB_S3M_CPU1_R_SCL")
	)
	(segment
		(start 225.334068 -223.31553)
		(end 225.334068 -224.037144)
		(width 0.12954)
		(layer "F.Cu")
		(net "SMB_S3M_CPU1_R_SCL")
	)
	(segment
		(start 225.525838 -222.09887)
		(end 225.525838 -222.58147)
		(width 0.12954)
		(layer "F.Cu")
		(net "SMB_S3M_CPU1_R_SCL")
	)
	(segment
		(start 225.298 -224.073212)
		(end 225.298 -225.288348)
		(width 0.12954)
		(layer "F.Cu")
		(net "SMB_S3M_CPU1_R_SCL")
	)
	(via
		(at 225.334068 -223.31553)
		(size 0.762)
		(drill 0.381)
		(layers "F.Cu" "B.Cu")
		(net "SMB_S3M_CPU1_R_SCL")
	)
	(segment
		(start 160.564322 -77.87005)
		(end 160.828482 -77.87005)
		(width 0.12954)
		(layer "F.Cu")
		(net "SMB_S3M_CPU1_3V3AUX_SDA_R")
	)
	(segment
		(start 157.985968 -77.87005)
		(end 160.564322 -77.87005)
		(width 0.12954)
		(layer "F.Cu")
		(net "SMB_S3M_CPU1_3V3AUX_SDA_R")
	)
	(segment
		(start 160.828482 -77.87005)
		(end 161.94278 -78.984348)
		(width 0.12954)
		(layer "F.Cu")
		(net "SMB_S3M_CPU1_3V3AUX_SDA_R")
	)
	(via
		(at 160.564322 -77.87005)
		(size 0.508)
		(drill 0.254)
		(layers "F.Cu" "B.Cu")
		(net "SMB_S3M_CPU1_3V3AUX_SDA_R")
	)
	(segment
		(start 226.648518 -233.76255)
		(end 226.648518 -232.631488)
		(width 0.12954)
		(layer "F.Cu")
		(net "SMB_S3M_CPU1_3V3AUX_SDA")
	)
	(segment
		(start 226.568 -231.580182)
		(end 226.568 -230.571548)
		(width 0.12954)
		(layer "F.Cu")
		(net "SMB_S3M_CPU1_3V3AUX_SDA")
	)
	(segment
		(start 226.648518 -231.6607)
		(end 226.568 -231.580182)
		(width 0.12954)
		(layer "F.Cu")
		(net "SMB_S3M_CPU1_3V3AUX_SDA")
	)
	(segment
		(start 162.74288 -78.984348)
		(end 163.5252 -78.984348)
		(width 0.12954)
		(layer "F.Cu")
		(net "SMB_S3M_CPU1_3V3AUX_SDA")
	)
	(segment
		(start 226.648518 -232.631488)
		(end 226.648518 -231.6607)
		(width 0.12954)
		(layer "F.Cu")
		(net "SMB_S3M_CPU1_3V3AUX_SDA")
	)
	(segment
		(start 391.08888 -148.408898)
		(end 391.08888 -147.792948)
		(width 0.12954)
		(layer "F.Cu")
		(net "SMB_S3M_CPU1_3V3AUX_SDA")
	)
	(via
		(at 226.648518 -232.631488)
		(size 0.508)
		(drill 0.254)
		(layers "F.Cu" "B.Cu")
		(net "SMB_S3M_CPU1_3V3AUX_SDA")
	)
	(via
		(at 163.5252 -78.984348)
		(size 0.508)
		(drill 0.254)
		(layers "F.Cu" "B.Cu")
		(net "SMB_S3M_CPU1_3V3AUX_SDA")
	)
	(via
		(at 391.08888 -147.792948)
		(size 0.508)
		(drill 0.254)
		(layers "F.Cu" "B.Cu")
		(net "SMB_S3M_CPU1_3V3AUX_SDA")
	)
	(segment
		(start 354.211382 -60.677298)
		(end 354.211382 -69.5706)
		(width 0.127)
		(layer "In6.Cu")
		(net "SMB_S3M_CPU1_3V3AUX_SDA")
	)
	(segment
		(start 252.076966 -89.21623)
		(end 260.806184 -89.21623)
		(width 0.127)
		(layer "In6.Cu")
		(net "SMB_S3M_CPU1_3V3AUX_SDA")
	)
	(segment
		(start 357.46182 -77.291692)
		(end 357.46182 -80.352138)
		(width 0.127)
		(layer "In6.Cu")
		(net "SMB_S3M_CPU1_3V3AUX_SDA")
	)
	(segment
		(start 329.82662 -82.781648)
		(end 334.424528 -78.18374)
		(width 0.127)
		(layer "In6.Cu")
		(net "SMB_S3M_CPU1_3V3AUX_SDA")
	)
	(segment
		(start 357.46182 -76.402692)
		(end 357.58882 -76.529692)
		(width 0.127)
		(layer "In6.Cu")
		(net "SMB_S3M_CPU1_3V3AUX_SDA")
	)
	(segment
		(start 241.748564 -92.565728)
		(end 243.408454 -90.905838)
		(width 0.127)
		(layer "In6.Cu")
		(net "SMB_S3M_CPU1_3V3AUX_SDA")
	)
	(segment
		(start 357.58882 -77.164692)
		(end 357.46182 -77.291692)
		(width 0.127)
		(layer "In6.Cu")
		(net "SMB_S3M_CPU1_3V3AUX_SDA")
	)
	(segment
		(start 360.64444 -85.361018)
		(end 364.86084 -89.577418)
		(width 0.127)
		(layer "In6.Cu")
		(net "SMB_S3M_CPU1_3V3AUX_SDA")
	)
	(segment
		(start 210.341464 -93.52026)
		(end 215.168734 -93.52026)
		(width 0.127)
		(layer "In6.Cu")
		(net "SMB_S3M_CPU1_3V3AUX_SDA")
	)
	(segment
		(start 338.42452 -74.672698)
		(end 338.42452 -72.71004)
		(width 0.127)
		(layer "In6.Cu")
		(net "SMB_S3M_CPU1_3V3AUX_SDA")
	)
	(segment
		(start 334.424528 -78.18374)
		(end 334.913478 -78.18374)
		(width 0.127)
		(layer "In6.Cu")
		(net "SMB_S3M_CPU1_3V3AUX_SDA")
	)
	(segment
		(start 352.581464 -59.04738)
		(end 354.211382 -60.677298)
		(width 0.127)
		(layer "In6.Cu")
		(net "SMB_S3M_CPU1_3V3AUX_SDA")
	)
	(segment
		(start 348.1832 -62.013338)
		(end 348.1832 -59.854338)
		(width 0.127)
		(layer "In6.Cu")
		(net "SMB_S3M_CPU1_3V3AUX_SDA")
	)
	(segment
		(start 338.42452 -72.71004)
		(end 341.472012 -69.662548)
		(width 0.127)
		(layer "In6.Cu")
		(net "SMB_S3M_CPU1_3V3AUX_SDA")
	)
	(segment
		(start 348.1832 -59.854338)
		(end 348.990158 -59.04738)
		(width 0.127)
		(layer "In6.Cu")
		(net "SMB_S3M_CPU1_3V3AUX_SDA")
	)
	(segment
		(start 345.2876 -68.443348)
		(end 345.2876 -64.908938)
		(width 0.127)
		(layer "In6.Cu")
		(net "SMB_S3M_CPU1_3V3AUX_SDA")
	)
	(segment
		(start 358.560624 -75.386692)
		(end 358.560624 -75.767692)
		(width 0.127)
		(layer "In6.Cu")
		(net "SMB_S3M_CPU1_3V3AUX_SDA")
	)
	(segment
		(start 379.81128 -100.927408)
		(end 389.96366 -111.079788)
		(width 0.127)
		(layer "In6.Cu")
		(net "SMB_S3M_CPU1_3V3AUX_SDA")
	)
	(segment
		(start 167.645842 -79.35595)
		(end 174.025814 -85.735922)
		(width 0.127)
		(layer "In6.Cu")
		(net "SMB_S3M_CPU1_3V3AUX_SDA")
	)
	(segment
		(start 341.472012 -69.662548)
		(end 344.0684 -69.662548)
		(width 0.127)
		(layer "In6.Cu")
		(net "SMB_S3M_CPU1_3V3AUX_SDA")
	)
	(segment
		(start 348.990158 -59.04738)
		(end 352.581464 -59.04738)
		(width 0.127)
		(layer "In6.Cu")
		(net "SMB_S3M_CPU1_3V3AUX_SDA")
	)
	(segment
		(start 364.86084 -93.38183)
		(end 372.406418 -100.927408)
		(width 0.127)
		(layer "In6.Cu")
		(net "SMB_S3M_CPU1_3V3AUX_SDA")
	)
	(segment
		(start 360.64444 -83.534758)
		(end 360.64444 -85.361018)
		(width 0.127)
		(layer "In6.Cu")
		(net "SMB_S3M_CPU1_3V3AUX_SDA")
	)
	(segment
		(start 249.703336 -90.905838)
		(end 250.870974 -90.422222)
		(width 0.127)
		(layer "In6.Cu")
		(net "SMB_S3M_CPU1_3V3AUX_SDA")
	)
	(segment
		(start 358.560624 -77.037692)
		(end 358.433624 -77.164692)
		(width 0.127)
		(layer "In6.Cu")
		(net "SMB_S3M_CPU1_3V3AUX_SDA")
	)
	(segment
		(start 345.2876 -64.908938)
		(end 348.1832 -62.013338)
		(width 0.127)
		(layer "In6.Cu")
		(net "SMB_S3M_CPU1_3V3AUX_SDA")
	)
	(segment
		(start 243.408454 -90.905838)
		(end 249.703336 -90.905838)
		(width 0.127)
		(layer "In6.Cu")
		(net "SMB_S3M_CPU1_3V3AUX_SDA")
	)
	(segment
		(start 191.53759 -85.735922)
		(end 192.050416 -86.248748)
		(width 0.127)
		(layer "In6.Cu")
		(net "SMB_S3M_CPU1_3V3AUX_SDA")
	)
	(segment
		(start 364.86084 -89.577418)
		(end 364.86084 -93.38183)
		(width 0.127)
		(layer "In6.Cu")
		(net "SMB_S3M_CPU1_3V3AUX_SDA")
	)
	(segment
		(start 163.896802 -79.35595)
		(end 167.645842 -79.35595)
		(width 0.127)
		(layer "In6.Cu")
		(net "SMB_S3M_CPU1_3V3AUX_SDA")
	)
	(segment
		(start 357.46182 -80.352138)
		(end 360.64444 -83.534758)
		(width 0.127)
		(layer "In6.Cu")
		(net "SMB_S3M_CPU1_3V3AUX_SDA")
	)
	(segment
		(start 358.433624 -75.259692)
		(end 358.560624 -75.386692)
		(width 0.127)
		(layer "In6.Cu")
		(net "SMB_S3M_CPU1_3V3AUX_SDA")
	)
	(segment
		(start 357.46182 -75.132692)
		(end 357.58882 -75.259692)
		(width 0.127)
		(layer "In6.Cu")
		(net "SMB_S3M_CPU1_3V3AUX_SDA")
	)
	(segment
		(start 358.560624 -75.767692)
		(end 358.433624 -75.894692)
		(width 0.127)
		(layer "In6.Cu")
		(net "SMB_S3M_CPU1_3V3AUX_SDA")
	)
	(segment
		(start 303.315116 -82.781648)
		(end 329.82662 -82.781648)
		(width 0.127)
		(layer "In6.Cu")
		(net "SMB_S3M_CPU1_3V3AUX_SDA")
	)
	(segment
		(start 204.537564 -86.248748)
		(end 207.76565 -89.476834)
		(width 0.127)
		(layer "In6.Cu")
		(net "SMB_S3M_CPU1_3V3AUX_SDA")
	)
	(segment
		(start 174.025814 -85.735922)
		(end 191.53759 -85.735922)
		(width 0.127)
		(layer "In6.Cu")
		(net "SMB_S3M_CPU1_3V3AUX_SDA")
	)
	(segment
		(start 357.58882 -75.894692)
		(end 357.46182 -76.021692)
		(width 0.127)
		(layer "In6.Cu")
		(net "SMB_S3M_CPU1_3V3AUX_SDA")
	)
	(segment
		(start 207.76565 -90.944446)
		(end 210.341464 -93.52026)
		(width 0.127)
		(layer "In6.Cu")
		(net "SMB_S3M_CPU1_3V3AUX_SDA")
	)
	(segment
		(start 250.870974 -90.422222)
		(end 252.076966 -89.21623)
		(width 0.127)
		(layer "In6.Cu")
		(net "SMB_S3M_CPU1_3V3AUX_SDA")
	)
	(segment
		(start 207.76565 -89.476834)
		(end 207.76565 -90.944446)
		(width 0.127)
		(layer "In6.Cu")
		(net "SMB_S3M_CPU1_3V3AUX_SDA")
	)
	(segment
		(start 358.560624 -76.656692)
		(end 358.560624 -77.037692)
		(width 0.127)
		(layer "In6.Cu")
		(net "SMB_S3M_CPU1_3V3AUX_SDA")
	)
	(segment
		(start 358.433624 -75.894692)
		(end 357.58882 -75.894692)
		(width 0.127)
		(layer "In6.Cu")
		(net "SMB_S3M_CPU1_3V3AUX_SDA")
	)
	(segment
		(start 372.406418 -100.927408)
		(end 379.81128 -100.927408)
		(width 0.127)
		(layer "In6.Cu")
		(net "SMB_S3M_CPU1_3V3AUX_SDA")
	)
	(segment
		(start 357.46182 -72.821038)
		(end 357.46182 -75.132692)
		(width 0.127)
		(layer "In6.Cu")
		(net "SMB_S3M_CPU1_3V3AUX_SDA")
	)
	(segment
		(start 358.433624 -76.529692)
		(end 358.560624 -76.656692)
		(width 0.127)
		(layer "In6.Cu")
		(net "SMB_S3M_CPU1_3V3AUX_SDA")
	)
	(segment
		(start 389.96366 -111.079788)
		(end 389.96366 -146.667728)
		(width 0.127)
		(layer "In6.Cu")
		(net "SMB_S3M_CPU1_3V3AUX_SDA")
	)
	(segment
		(start 357.46182 -76.021692)
		(end 357.46182 -76.402692)
		(width 0.127)
		(layer "In6.Cu")
		(net "SMB_S3M_CPU1_3V3AUX_SDA")
	)
	(segment
		(start 354.211382 -69.5706)
		(end 357.46182 -72.821038)
		(width 0.127)
		(layer "In6.Cu")
		(net "SMB_S3M_CPU1_3V3AUX_SDA")
	)
	(segment
		(start 192.050416 -86.248748)
		(end 204.537564 -86.248748)
		(width 0.127)
		(layer "In6.Cu")
		(net "SMB_S3M_CPU1_3V3AUX_SDA")
	)
	(segment
		(start 163.5252 -78.984348)
		(end 163.896802 -79.35595)
		(width 0.127)
		(layer "In6.Cu")
		(net "SMB_S3M_CPU1_3V3AUX_SDA")
	)
	(segment
		(start 216.123266 -92.565728)
		(end 241.748564 -92.565728)
		(width 0.127)
		(layer "In6.Cu")
		(net "SMB_S3M_CPU1_3V3AUX_SDA")
	)
	(segment
		(start 260.806184 -89.21623)
		(end 262.107426 -87.914988)
		(width 0.127)
		(layer "In6.Cu")
		(net "SMB_S3M_CPU1_3V3AUX_SDA")
	)
	(segment
		(start 298.181776 -87.914988)
		(end 303.315116 -82.781648)
		(width 0.127)
		(layer "In6.Cu")
		(net "SMB_S3M_CPU1_3V3AUX_SDA")
	)
	(segment
		(start 215.168734 -93.52026)
		(end 216.123266 -92.565728)
		(width 0.127)
		(layer "In6.Cu")
		(net "SMB_S3M_CPU1_3V3AUX_SDA")
	)
	(segment
		(start 344.0684 -69.662548)
		(end 345.2876 -68.443348)
		(width 0.127)
		(layer "In6.Cu")
		(net "SMB_S3M_CPU1_3V3AUX_SDA")
	)
	(segment
		(start 389.96366 -146.667728)
		(end 391.08888 -147.792948)
		(width 0.127)
		(layer "In6.Cu")
		(net "SMB_S3M_CPU1_3V3AUX_SDA")
	)
	(segment
		(start 358.433624 -77.164692)
		(end 357.58882 -77.164692)
		(width 0.127)
		(layer "In6.Cu")
		(net "SMB_S3M_CPU1_3V3AUX_SDA")
	)
	(segment
		(start 357.58882 -75.259692)
		(end 358.433624 -75.259692)
		(width 0.127)
		(layer "In6.Cu")
		(net "SMB_S3M_CPU1_3V3AUX_SDA")
	)
	(segment
		(start 334.913478 -78.18374)
		(end 338.42452 -74.672698)
		(width 0.127)
		(layer "In6.Cu")
		(net "SMB_S3M_CPU1_3V3AUX_SDA")
	)
	(segment
		(start 357.58882 -76.529692)
		(end 358.433624 -76.529692)
		(width 0.127)
		(layer "In6.Cu")
		(net "SMB_S3M_CPU1_3V3AUX_SDA")
	)
	(segment
		(start 262.107426 -87.914988)
		(end 298.181776 -87.914988)
		(width 0.127)
		(layer "In6.Cu")
		(net "SMB_S3M_CPU1_3V3AUX_SDA")
	)
	(segment
		(start 387.380734 -147.068032)
		(end 387.380734 -146.395948)
		(width 0.127)
		(layer "In13.Cu")
		(net "SMB_S3M_CPU1_3V3AUX_SDA")
	)
	(segment
		(start 385.348734 -147.195032)
		(end 384.967734 -147.195032)
		(width 0.127)
		(layer "In13.Cu")
		(net "SMB_S3M_CPU1_3V3AUX_SDA")
	)
	(segment
		(start 385.983734 -146.268948)
		(end 385.602734 -146.268948)
		(width 0.127)
		(layer "In13.Cu")
		(net "SMB_S3M_CPU1_3V3AUX_SDA")
	)
	(segment
		(start 384.205734 -146.395948)
		(end 384.205734 -147.068032)
		(width 0.127)
		(layer "In13.Cu")
		(net "SMB_S3M_CPU1_3V3AUX_SDA")
	)
	(segment
		(start 386.110734 -146.395948)
		(end 385.983734 -146.268948)
		(width 0.127)
		(layer "In13.Cu")
		(net "SMB_S3M_CPU1_3V3AUX_SDA")
	)
	(segment
		(start 386.745734 -147.068032)
		(end 386.618734 -147.195032)
		(width 0.127)
		(layer "In13.Cu")
		(net "SMB_S3M_CPU1_3V3AUX_SDA")
	)
	(segment
		(start 386.237734 -147.195032)
		(end 386.110734 -147.068032)
		(width 0.127)
		(layer "In13.Cu")
		(net "SMB_S3M_CPU1_3V3AUX_SDA")
	)
	(segment
		(start 384.967734 -147.195032)
		(end 384.840734 -147.068032)
		(width 0.127)
		(layer "In13.Cu")
		(net "SMB_S3M_CPU1_3V3AUX_SDA")
	)
	(segment
		(start 384.332734 -146.268948)
		(end 384.205734 -146.395948)
		(width 0.127)
		(layer "In13.Cu")
		(net "SMB_S3M_CPU1_3V3AUX_SDA")
	)
	(segment
		(start 384.205734 -147.068032)
		(end 384.078734 -147.195032)
		(width 0.127)
		(layer "In13.Cu")
		(net "SMB_S3M_CPU1_3V3AUX_SDA")
	)
	(segment
		(start 349.883984 -146.268948)
		(end 347.420184 -148.732748)
		(width 0.127)
		(layer "In13.Cu")
		(net "SMB_S3M_CPU1_3V3AUX_SDA")
	)
	(segment
		(start 229.08768 -227.124768)
		(end 226.648518 -229.56393)
		(width 0.127)
		(layer "In13.Cu")
		(net "SMB_S3M_CPU1_3V3AUX_SDA")
	)
	(segment
		(start 386.745734 -146.395948)
		(end 386.745734 -147.068032)
		(width 0.127)
		(layer "In13.Cu")
		(net "SMB_S3M_CPU1_3V3AUX_SDA")
	)
	(segment
		(start 347.420184 -148.732748)
		(end 307.01615 -148.732748)
		(width 0.127)
		(layer "In13.Cu")
		(net "SMB_S3M_CPU1_3V3AUX_SDA")
	)
	(segment
		(start 387.253734 -146.268948)
		(end 386.872734 -146.268948)
		(width 0.127)
		(layer "In13.Cu")
		(net "SMB_S3M_CPU1_3V3AUX_SDA")
	)
	(segment
		(start 387.507734 -147.195032)
		(end 387.380734 -147.068032)
		(width 0.127)
		(layer "In13.Cu")
		(net "SMB_S3M_CPU1_3V3AUX_SDA")
	)
	(segment
		(start 388.015734 -147.068032)
		(end 387.888734 -147.195032)
		(width 0.127)
		(layer "In13.Cu")
		(net "SMB_S3M_CPU1_3V3AUX_SDA")
	)
	(segment
		(start 384.713734 -146.268948)
		(end 384.332734 -146.268948)
		(width 0.127)
		(layer "In13.Cu")
		(net "SMB_S3M_CPU1_3V3AUX_SDA")
	)
	(segment
		(start 384.840734 -146.395948)
		(end 384.713734 -146.268948)
		(width 0.127)
		(layer "In13.Cu")
		(net "SMB_S3M_CPU1_3V3AUX_SDA")
	)
	(segment
		(start 385.475734 -147.068032)
		(end 385.348734 -147.195032)
		(width 0.127)
		(layer "In13.Cu")
		(net "SMB_S3M_CPU1_3V3AUX_SDA")
	)
	(segment
		(start 385.475734 -146.395948)
		(end 385.475734 -147.068032)
		(width 0.127)
		(layer "In13.Cu")
		(net "SMB_S3M_CPU1_3V3AUX_SDA")
	)
	(segment
		(start 384.078734 -147.195032)
		(end 383.697734 -147.195032)
		(width 0.127)
		(layer "In13.Cu")
		(net "SMB_S3M_CPU1_3V3AUX_SDA")
	)
	(segment
		(start 299.268134 -154.066748)
		(end 265.562334 -187.772548)
		(width 0.127)
		(layer "In13.Cu")
		(net "SMB_S3M_CPU1_3V3AUX_SDA")
	)
	(segment
		(start 388.015734 -146.395948)
		(end 388.015734 -147.068032)
		(width 0.127)
		(layer "In13.Cu")
		(net "SMB_S3M_CPU1_3V3AUX_SDA")
	)
	(segment
		(start 383.570734 -147.068032)
		(end 383.570734 -146.395948)
		(width 0.127)
		(layer "In13.Cu")
		(net "SMB_S3M_CPU1_3V3AUX_SDA")
	)
	(segment
		(start 386.872734 -146.268948)
		(end 386.745734 -146.395948)
		(width 0.127)
		(layer "In13.Cu")
		(net "SMB_S3M_CPU1_3V3AUX_SDA")
	)
	(segment
		(start 383.570734 -146.395948)
		(end 383.443734 -146.268948)
		(width 0.127)
		(layer "In13.Cu")
		(net "SMB_S3M_CPU1_3V3AUX_SDA")
	)
	(segment
		(start 389.56488 -146.268948)
		(end 388.142734 -146.268948)
		(width 0.127)
		(layer "In13.Cu")
		(net "SMB_S3M_CPU1_3V3AUX_SDA")
	)
	(segment
		(start 301.68215 -154.066748)
		(end 299.268134 -154.066748)
		(width 0.127)
		(layer "In13.Cu")
		(net "SMB_S3M_CPU1_3V3AUX_SDA")
	)
	(segment
		(start 307.01615 -148.732748)
		(end 301.68215 -154.066748)
		(width 0.127)
		(layer "In13.Cu")
		(net "SMB_S3M_CPU1_3V3AUX_SDA")
	)
	(segment
		(start 384.840734 -147.068032)
		(end 384.840734 -146.395948)
		(width 0.127)
		(layer "In13.Cu")
		(net "SMB_S3M_CPU1_3V3AUX_SDA")
	)
	(segment
		(start 383.443734 -146.268948)
		(end 349.883984 -146.268948)
		(width 0.127)
		(layer "In13.Cu")
		(net "SMB_S3M_CPU1_3V3AUX_SDA")
	)
	(segment
		(start 387.380734 -146.395948)
		(end 387.253734 -146.268948)
		(width 0.127)
		(layer "In13.Cu")
		(net "SMB_S3M_CPU1_3V3AUX_SDA")
	)
	(segment
		(start 386.618734 -147.195032)
		(end 386.237734 -147.195032)
		(width 0.127)
		(layer "In13.Cu")
		(net "SMB_S3M_CPU1_3V3AUX_SDA")
	)
	(segment
		(start 383.697734 -147.195032)
		(end 383.570734 -147.068032)
		(width 0.127)
		(layer "In13.Cu")
		(net "SMB_S3M_CPU1_3V3AUX_SDA")
	)
	(segment
		(start 388.142734 -146.268948)
		(end 388.015734 -146.395948)
		(width 0.127)
		(layer "In13.Cu")
		(net "SMB_S3M_CPU1_3V3AUX_SDA")
	)
	(segment
		(start 385.602734 -146.268948)
		(end 385.475734 -146.395948)
		(width 0.127)
		(layer "In13.Cu")
		(net "SMB_S3M_CPU1_3V3AUX_SDA")
	)
	(segment
		(start 391.08888 -147.792948)
		(end 389.56488 -146.268948)
		(width 0.127)
		(layer "In13.Cu")
		(net "SMB_S3M_CPU1_3V3AUX_SDA")
	)
	(segment
		(start 252.569726 -187.772548)
		(end 229.08768 -211.254594)
		(width 0.127)
		(layer "In13.Cu")
		(net "SMB_S3M_CPU1_3V3AUX_SDA")
	)
	(segment
		(start 229.08768 -211.254594)
		(end 229.08768 -227.124768)
		(width 0.127)
		(layer "In13.Cu")
		(net "SMB_S3M_CPU1_3V3AUX_SDA")
	)
	(segment
		(start 387.888734 -147.195032)
		(end 387.507734 -147.195032)
		(width 0.127)
		(layer "In13.Cu")
		(net "SMB_S3M_CPU1_3V3AUX_SDA")
	)
	(segment
		(start 386.110734 -147.068032)
		(end 386.110734 -146.395948)
		(width 0.127)
		(layer "In13.Cu")
		(net "SMB_S3M_CPU1_3V3AUX_SDA")
	)
	(segment
		(start 226.648518 -229.56393)
		(end 226.648518 -232.631488)
		(width 0.127)
		(layer "In13.Cu")
		(net "SMB_S3M_CPU1_3V3AUX_SDA")
	)
	(segment
		(start 265.562334 -187.772548)
		(end 252.569726 -187.772548)
		(width 0.127)
		(layer "In13.Cu")
		(net "SMB_S3M_CPU1_3V3AUX_SDA")
	)
	(segment
		(start 157.985968 -78.520036)
		(end 159.4104 -78.520036)
		(width 0.12954)
		(layer "F.Cu")
		(net "SMB_S3M_CPU1_3V3AUX_SCL_R")
	)
	(segment
		(start 159.4104 -78.520036)
		(end 160.303718 -78.520036)
		(width 0.12954)
		(layer "F.Cu")
		(net "SMB_S3M_CPU1_3V3AUX_SCL_R")
	)
	(segment
		(start 160.303718 -78.520036)
		(end 161.94278 -80.159098)
		(width 0.12954)
		(layer "F.Cu")
		(net "SMB_S3M_CPU1_3V3AUX_SCL_R")
	)
	(via
		(at 159.4104 -78.520036)
		(size 0.508)
		(drill 0.254)
		(layers "F.Cu" "B.Cu")
		(net "SMB_S3M_CPU1_3V3AUX_SCL_R")
	)
	(segment
		(start 225.670618 -233.76255)
		(end 224.693226 -232.785158)
		(width 0.12954)
		(layer "F.Cu")
		(net "SMB_S3M_CPU1_3V3AUX_SCL")
	)
	(segment
		(start 394.39088 -148.408898)
		(end 394.39088 -147.792948)
		(width 0.12954)
		(layer "F.Cu")
		(net "SMB_S3M_CPU1_3V3AUX_SCL")
	)
	(segment
		(start 163.80079 -80.159098)
		(end 162.74288 -80.159098)
		(width 0.12954)
		(layer "F.Cu")
		(net "SMB_S3M_CPU1_3V3AUX_SCL")
	)
	(segment
		(start 164.08146 -79.878428)
		(end 163.80079 -80.159098)
		(width 0.12954)
		(layer "F.Cu")
		(net "SMB_S3M_CPU1_3V3AUX_SCL")
	)
	(segment
		(start 225.298 -232.180384)
		(end 225.298 -230.571548)
		(width 0.12954)
		(layer "F.Cu")
		(net "SMB_S3M_CPU1_3V3AUX_SCL")
	)
	(segment
		(start 224.693226 -232.785158)
		(end 225.298 -232.180384)
		(width 0.12954)
		(layer "F.Cu")
		(net "SMB_S3M_CPU1_3V3AUX_SCL")
	)
	(via
		(at 224.693226 -232.785158)
		(size 0.508)
		(drill 0.254)
		(layers "F.Cu" "B.Cu")
		(net "SMB_S3M_CPU1_3V3AUX_SCL")
	)
	(via
		(at 164.08146 -79.878428)
		(size 0.508)
		(drill 0.254)
		(layers "F.Cu" "B.Cu")
		(net "SMB_S3M_CPU1_3V3AUX_SCL")
	)
	(via
		(at 394.39088 -147.792948)
		(size 0.508)
		(drill 0.254)
		(layers "F.Cu" "B.Cu")
		(net "SMB_S3M_CPU1_3V3AUX_SCL")
	)
	(segment
		(start 191.35852 -86.167722)
		(end 173.846744 -86.167722)
		(width 0.127)
		(layer "In6.Cu")
		(net "SMB_S3M_CPU1_3V3AUX_SCL")
	)
	(segment
		(start 349.169228 -59.47918)
		(end 348.615 -60.033408)
		(width 0.127)
		(layer "In6.Cu")
		(net "SMB_S3M_CPU1_3V3AUX_SCL")
	)
	(segment
		(start 334.603598 -78.61554)
		(end 330.00569 -83.213448)
		(width 0.127)
		(layer "In6.Cu")
		(net "SMB_S3M_CPU1_3V3AUX_SCL")
	)
	(segment
		(start 364.39856 -93.541088)
		(end 364.39856 -89.726008)
		(width 0.127)
		(layer "In6.Cu")
		(net "SMB_S3M_CPU1_3V3AUX_SCL")
	)
	(segment
		(start 164.172138 -79.78775)
		(end 164.08146 -79.878428)
		(width 0.127)
		(layer "In6.Cu")
		(net "SMB_S3M_CPU1_3V3AUX_SCL")
	)
	(segment
		(start 372.21668 -101.359208)
		(end 364.39856 -93.541088)
		(width 0.127)
		(layer "In6.Cu")
		(net "SMB_S3M_CPU1_3V3AUX_SCL")
	)
	(segment
		(start 364.39856 -89.726008)
		(end 360.21264 -85.540088)
		(width 0.127)
		(layer "In6.Cu")
		(net "SMB_S3M_CPU1_3V3AUX_SCL")
	)
	(segment
		(start 345.81973 -68.825618)
		(end 344.5002 -70.145148)
		(width 0.127)
		(layer "In6.Cu")
		(net "SMB_S3M_CPU1_3V3AUX_SCL")
	)
	(segment
		(start 338.85632 -74.851768)
		(end 335.092548 -78.61554)
		(width 0.127)
		(layer "In6.Cu")
		(net "SMB_S3M_CPU1_3V3AUX_SCL")
	)
	(segment
		(start 348.615 -60.033408)
		(end 348.615 -62.192408)
		(width 0.127)
		(layer "In6.Cu")
		(net "SMB_S3M_CPU1_3V3AUX_SCL")
	)
	(segment
		(start 357.03002 -80.531208)
		(end 357.03002 -73.000108)
		(width 0.127)
		(layer "In6.Cu")
		(net "SMB_S3M_CPU1_3V3AUX_SCL")
	)
	(segment
		(start 207.307688 -89.629742)
		(end 204.358494 -86.680548)
		(width 0.127)
		(layer "In6.Cu")
		(net "SMB_S3M_CPU1_3V3AUX_SCL")
	)
	(segment
		(start 173.846744 -86.167722)
		(end 167.466772 -79.78775)
		(width 0.127)
		(layer "In6.Cu")
		(net "SMB_S3M_CPU1_3V3AUX_SCL")
	)
	(segment
		(start 210.16976 -93.997272)
		(end 207.307688 -91.1352)
		(width 0.127)
		(layer "In6.Cu")
		(net "SMB_S3M_CPU1_3V3AUX_SCL")
	)
	(segment
		(start 360.21264 -85.540088)
		(end 360.21264 -83.713828)
		(width 0.127)
		(layer "In6.Cu")
		(net "SMB_S3M_CPU1_3V3AUX_SCL")
	)
	(segment
		(start 241.927634 -92.997528)
		(end 216.435686 -92.997528)
		(width 0.127)
		(layer "In6.Cu")
		(net "SMB_S3M_CPU1_3V3AUX_SCL")
	)
	(segment
		(start 215.435942 -93.997272)
		(end 210.16976 -93.997272)
		(width 0.127)
		(layer "In6.Cu")
		(net "SMB_S3M_CPU1_3V3AUX_SCL")
	)
	(segment
		(start 261.083044 -89.691464)
		(end 252.311916 -89.691464)
		(width 0.127)
		(layer "In6.Cu")
		(net "SMB_S3M_CPU1_3V3AUX_SCL")
	)
	(segment
		(start 303.494186 -83.213448)
		(end 298.360846 -88.346788)
		(width 0.127)
		(layer "In6.Cu")
		(net "SMB_S3M_CPU1_3V3AUX_SCL")
	)
	(segment
		(start 204.358494 -86.680548)
		(end 191.871346 -86.680548)
		(width 0.127)
		(layer "In6.Cu")
		(net "SMB_S3M_CPU1_3V3AUX_SCL")
	)
	(segment
		(start 345.81973 -64.987678)
		(end 345.81973 -68.825618)
		(width 0.127)
		(layer "In6.Cu")
		(net "SMB_S3M_CPU1_3V3AUX_SCL")
	)
	(segment
		(start 389.53186 -147.094448)
		(end 389.53186 -111.258858)
		(width 0.127)
		(layer "In6.Cu")
		(net "SMB_S3M_CPU1_3V3AUX_SCL")
	)
	(segment
		(start 360.21264 -83.713828)
		(end 357.03002 -80.531208)
		(width 0.127)
		(layer "In6.Cu")
		(net "SMB_S3M_CPU1_3V3AUX_SCL")
	)
	(segment
		(start 338.85632 -72.9869)
		(end 338.85632 -74.851768)
		(width 0.127)
		(layer "In6.Cu")
		(net "SMB_S3M_CPU1_3V3AUX_SCL")
	)
	(segment
		(start 353.779582 -69.74967)
		(end 353.779582 -60.856368)
		(width 0.127)
		(layer "In6.Cu")
		(net "SMB_S3M_CPU1_3V3AUX_SCL")
	)
	(segment
		(start 243.587524 -91.337638)
		(end 241.927634 -92.997528)
		(width 0.127)
		(layer "In6.Cu")
		(net "SMB_S3M_CPU1_3V3AUX_SCL")
	)
	(segment
		(start 249.931682 -91.337638)
		(end 243.587524 -91.337638)
		(width 0.127)
		(layer "In6.Cu")
		(net "SMB_S3M_CPU1_3V3AUX_SCL")
	)
	(segment
		(start 251.184664 -90.818716)
		(end 249.931682 -91.337638)
		(width 0.127)
		(layer "In6.Cu")
		(net "SMB_S3M_CPU1_3V3AUX_SCL")
	)
	(segment
		(start 394.39088 -147.792948)
		(end 393.5603 -148.623528)
		(width 0.127)
		(layer "In6.Cu")
		(net "SMB_S3M_CPU1_3V3AUX_SCL")
	)
	(segment
		(start 389.53186 -111.258858)
		(end 379.63221 -101.359208)
		(width 0.127)
		(layer "In6.Cu")
		(net "SMB_S3M_CPU1_3V3AUX_SCL")
	)
	(segment
		(start 298.360846 -88.346788)
		(end 262.42772 -88.346788)
		(width 0.127)
		(layer "In6.Cu")
		(net "SMB_S3M_CPU1_3V3AUX_SCL")
	)
	(segment
		(start 393.5603 -148.623528)
		(end 391.06094 -148.623528)
		(width 0.127)
		(layer "In6.Cu")
		(net "SMB_S3M_CPU1_3V3AUX_SCL")
	)
	(segment
		(start 341.698072 -70.145148)
		(end 338.85632 -72.9869)
		(width 0.127)
		(layer "In6.Cu")
		(net "SMB_S3M_CPU1_3V3AUX_SCL")
	)
	(segment
		(start 352.402394 -59.47918)
		(end 349.169228 -59.47918)
		(width 0.127)
		(layer "In6.Cu")
		(net "SMB_S3M_CPU1_3V3AUX_SCL")
	)
	(segment
		(start 344.5002 -70.145148)
		(end 341.698072 -70.145148)
		(width 0.127)
		(layer "In6.Cu")
		(net "SMB_S3M_CPU1_3V3AUX_SCL")
	)
	(segment
		(start 252.311916 -89.691464)
		(end 251.184664 -90.818716)
		(width 0.127)
		(layer "In6.Cu")
		(net "SMB_S3M_CPU1_3V3AUX_SCL")
	)
	(segment
		(start 335.092548 -78.61554)
		(end 334.603598 -78.61554)
		(width 0.127)
		(layer "In6.Cu")
		(net "SMB_S3M_CPU1_3V3AUX_SCL")
	)
	(segment
		(start 348.615 -62.192408)
		(end 345.81973 -64.987678)
		(width 0.127)
		(layer "In6.Cu")
		(net "SMB_S3M_CPU1_3V3AUX_SCL")
	)
	(segment
		(start 216.435686 -92.997528)
		(end 215.435942 -93.997272)
		(width 0.127)
		(layer "In6.Cu")
		(net "SMB_S3M_CPU1_3V3AUX_SCL")
	)
	(segment
		(start 330.00569 -83.213448)
		(end 303.494186 -83.213448)
		(width 0.127)
		(layer "In6.Cu")
		(net "SMB_S3M_CPU1_3V3AUX_SCL")
	)
	(segment
		(start 357.03002 -73.000108)
		(end 353.779582 -69.74967)
		(width 0.127)
		(layer "In6.Cu")
		(net "SMB_S3M_CPU1_3V3AUX_SCL")
	)
	(segment
		(start 262.42772 -88.346788)
		(end 261.083044 -89.691464)
		(width 0.127)
		(layer "In6.Cu")
		(net "SMB_S3M_CPU1_3V3AUX_SCL")
	)
	(segment
		(start 191.871346 -86.680548)
		(end 191.35852 -86.167722)
		(width 0.127)
		(layer "In6.Cu")
		(net "SMB_S3M_CPU1_3V3AUX_SCL")
	)
	(segment
		(start 391.06094 -148.623528)
		(end 389.53186 -147.094448)
		(width 0.127)
		(layer "In6.Cu")
		(net "SMB_S3M_CPU1_3V3AUX_SCL")
	)
	(segment
		(start 207.307688 -91.1352)
		(end 207.307688 -89.629742)
		(width 0.127)
		(layer "In6.Cu")
		(net "SMB_S3M_CPU1_3V3AUX_SCL")
	)
	(segment
		(start 379.63221 -101.359208)
		(end 372.21668 -101.359208)
		(width 0.127)
		(layer "In6.Cu")
		(net "SMB_S3M_CPU1_3V3AUX_SCL")
	)
	(segment
		(start 353.779582 -60.856368)
		(end 352.402394 -59.47918)
		(width 0.127)
		(layer "In6.Cu")
		(net "SMB_S3M_CPU1_3V3AUX_SCL")
	)
	(segment
		(start 167.466772 -79.78775)
		(end 164.172138 -79.78775)
		(width 0.127)
		(layer "In6.Cu")
		(net "SMB_S3M_CPU1_3V3AUX_SCL")
	)
	(segment
		(start 265.33348 -187.315348)
		(end 252.416056 -187.315348)
		(width 0.127)
		(layer "In13.Cu")
		(net "SMB_S3M_CPU1_3V3AUX_SCL")
	)
	(segment
		(start 301.51578 -153.622248)
		(end 299.02658 -153.622248)
		(width 0.127)
		(layer "In13.Cu")
		(net "SMB_S3M_CPU1_3V3AUX_SCL")
	)
	(segment
		(start 394.39088 -147.792948)
		(end 392.43508 -145.837148)
		(width 0.127)
		(layer "In13.Cu")
		(net "SMB_S3M_CPU1_3V3AUX_SCL")
	)
	(segment
		(start 252.416056 -187.315348)
		(end 228.65588 -211.075524)
		(width 0.127)
		(layer "In13.Cu")
		(net "SMB_S3M_CPU1_3V3AUX_SCL")
	)
	(segment
		(start 228.65588 -226.945698)
		(end 224.693226 -230.908352)
		(width 0.127)
		(layer "In13.Cu")
		(net "SMB_S3M_CPU1_3V3AUX_SCL")
	)
	(segment
		(start 306.83708 -148.300948)
		(end 301.51578 -153.622248)
		(width 0.127)
		(layer "In13.Cu")
		(net "SMB_S3M_CPU1_3V3AUX_SCL")
	)
	(segment
		(start 349.704914 -145.837148)
		(end 347.241114 -148.300948)
		(width 0.127)
		(layer "In13.Cu")
		(net "SMB_S3M_CPU1_3V3AUX_SCL")
	)
	(segment
		(start 228.65588 -211.075524)
		(end 228.65588 -226.945698)
		(width 0.127)
		(layer "In13.Cu")
		(net "SMB_S3M_CPU1_3V3AUX_SCL")
	)
	(segment
		(start 392.43508 -145.837148)
		(end 349.704914 -145.837148)
		(width 0.127)
		(layer "In13.Cu")
		(net "SMB_S3M_CPU1_3V3AUX_SCL")
	)
	(segment
		(start 347.241114 -148.300948)
		(end 306.83708 -148.300948)
		(width 0.127)
		(layer "In13.Cu")
		(net "SMB_S3M_CPU1_3V3AUX_SCL")
	)
	(segment
		(start 299.02658 -153.622248)
		(end 265.33348 -187.315348)
		(width 0.127)
		(layer "In13.Cu")
		(net "SMB_S3M_CPU1_3V3AUX_SCL")
	)
	(segment
		(start 224.693226 -230.908352)
		(end 224.693226 -232.785158)
		(width 0.127)
		(layer "In13.Cu")
		(net "SMB_S3M_CPU1_3V3AUX_SCL")
	)
	(segment
		(start 393.425172 -180.31079)
		(end 392.578082 -179.4637)
		(width 0.12954)
		(layer "F.Cu")
		(net "SMB_S3M_CPU0_SDA")
	)
	(segment
		(start 392.540998 -163.52139)
		(end 392.763248 -163.29914)
		(width 0.12954)
		(layer "F.Cu")
		(net "SMB_S3M_CPU0_SDA")
	)
	(segment
		(start 392.540998 -177.62601)
		(end 392.540998 -163.52139)
		(width 0.12954)
		(layer "F.Cu")
		(net "SMB_S3M_CPU0_SDA")
	)
	(segment
		(start 392.763248 -163.29914)
		(end 392.763248 -162.760914)
		(width 0.12954)
		(layer "F.Cu")
		(net "SMB_S3M_CPU0_SDA")
	)
	(segment
		(start 392.578082 -179.4637)
		(end 392.578082 -177.663094)
		(width 0.12954)
		(layer "F.Cu")
		(net "SMB_S3M_CPU0_SDA")
	)
	(segment
		(start 392.578082 -177.663094)
		(end 392.540998 -177.62601)
		(width 0.12954)
		(layer "F.Cu")
		(net "SMB_S3M_CPU0_SDA")
	)
	(segment
		(start 393.79906 -180.31079)
		(end 393.425172 -180.31079)
		(width 0.12954)
		(layer "F.Cu")
		(net "SMB_S3M_CPU0_SDA")
	)
	(segment
		(start 362.509562 -266.941808)
		(end 362.509562 -266.405868)
		(width 0.12954)
		(layer "F.Cu")
		(net "SMB_S3M_CPU0_SDA")
	)
	(via
		(at 393.79906 -180.31079)
		(size 0.508)
		(drill 0.254)
		(layers "F.Cu" "B.Cu")
		(net "SMB_S3M_CPU0_SDA")
	)
	(via
		(at 392.106658 -259.37845)
		(size 0.6604)
		(drill 0.3302)
		(layers "F.Cu" "B.Cu")
		(net "SMB_S3M_CPU0_SDA")
	)
	(via
		(at 362.509562 -266.941808)
		(size 0.4572)
		(drill 0.2032)
		(layers "F.Cu" "B.Cu")
		(net "SMB_S3M_CPU0_SDA")
	)
	(segment
		(start 387.640322 -263.26973)
		(end 386.887974 -263.26973)
		(width 0.12954)
		(layer "B.Cu")
		(net "SMB_S3M_CPU0_SDA")
	)
	(segment
		(start 395.528038 -183.296306)
		(end 397.81988 -185.588148)
		(width 0.12954)
		(layer "B.Cu")
		(net "SMB_S3M_CPU0_SDA")
	)
	(segment
		(start 399.655538 -253.52629)
		(end 393.803378 -259.37845)
		(width 0.12954)
		(layer "B.Cu")
		(net "SMB_S3M_CPU0_SDA")
	)
	(segment
		(start 378.768864 -263.196832)
		(end 378.754132 -263.188196)
		(width 0.0889)
		(layer "B.Cu")
		(net "SMB_S3M_CPU0_SDA")
	)
	(segment
		(start 399.655538 -243.97843)
		(end 399.655538 -253.52629)
		(width 0.12954)
		(layer "B.Cu")
		(net "SMB_S3M_CPU0_SDA")
	)
	(segment
		(start 397.81988 -185.588148)
		(end 397.81988 -186.553348)
		(width 0.12954)
		(layer "B.Cu")
		(net "SMB_S3M_CPU0_SDA")
	)
	(segment
		(start 408.642058 -236.97819)
		(end 407.100278 -238.51997)
		(width 0.12954)
		(layer "B.Cu")
		(net "SMB_S3M_CPU0_SDA")
	)
	(segment
		(start 408.380438 -235.19511)
		(end 408.380438 -235.98505)
		(width 0.12954)
		(layer "B.Cu")
		(net "SMB_S3M_CPU0_SDA")
	)
	(segment
		(start 382.528064 -263.196832)
		(end 382.513332 -263.188196)
		(width 0.0889)
		(layer "B.Cu")
		(net "SMB_S3M_CPU0_SDA")
	)
	(segment
		(start 379.708918 -263.196832)
		(end 379.698504 -263.190736)
		(width 0.0889)
		(layer "B.Cu")
		(net "SMB_S3M_CPU0_SDA")
	)
	(segment
		(start 405.733758 -193.55181)
		(end 406.960578 -194.77863)
		(width 0.12954)
		(layer "B.Cu")
		(net "SMB_S3M_CPU0_SDA")
	)
	(segment
		(start 363.645704 -265.633454)
		(end 363.636814 -265.638534)
		(width 0.0889)
		(layer "B.Cu")
		(net "SMB_S3M_CPU0_SDA")
	)
	(segment
		(start 393.79906 -180.31079)
		(end 394.212318 -180.31079)
		(width 0.12954)
		(layer "B.Cu")
		(net "SMB_S3M_CPU0_SDA")
	)
	(segment
		(start 362.744512 -267.233654)
		(end 362.66628 -267.212826)
		(width 0.0889)
		(layer "B.Cu")
		(net "SMB_S3M_CPU0_SDA")
	)
	(segment
		(start 369.557808 -263.247886)
		(end 369.318794 -263.247886)
		(width 0.0889)
		(layer "B.Cu")
		(net "SMB_S3M_CPU0_SDA")
	)
	(segment
		(start 407.100278 -238.51997)
		(end 405.113998 -238.51997)
		(width 0.12954)
		(layer "B.Cu")
		(net "SMB_S3M_CPU0_SDA")
	)
	(segment
		(start 370.695728 -263.190736)
		(end 370.685314 -263.196832)
		(width 0.0889)
		(layer "B.Cu")
		(net "SMB_S3M_CPU0_SDA")
	)
	(segment
		(start 369.318794 -263.247886)
		(end 368.44605 -264.12063)
		(width 0.0889)
		(layer "B.Cu")
		(net "SMB_S3M_CPU0_SDA")
	)
	(segment
		(start 363.824266 -265.298682)
		(end 363.824266 -265.314176)
		(width 0.0889)
		(layer "B.Cu")
		(net "SMB_S3M_CPU0_SDA")
	)
	(segment
		(start 391.531602 -259.37845)
		(end 387.640322 -263.26973)
		(width 0.12954)
		(layer "B.Cu")
		(net "SMB_S3M_CPU0_SDA")
	)
	(segment
		(start 368.44605 -264.12063)
		(end 367.493042 -264.12063)
		(width 0.0889)
		(layer "B.Cu")
		(net "SMB_S3M_CPU0_SDA")
	)
	(segment
		(start 367.493042 -264.12063)
		(end 367.113312 -264.50036)
		(width 0.0889)
		(layer "B.Cu")
		(net "SMB_S3M_CPU0_SDA")
	)
	(segment
		(start 363.180884 -266.444222)
		(end 363.16666 -266.45235)
		(width 0.0889)
		(layer "B.Cu")
		(net "SMB_S3M_CPU0_SDA")
	)
	(segment
		(start 364.671864 -264.824718)
		(end 364.657132 -264.816082)
		(width 0.0889)
		(layer "B.Cu")
		(net "SMB_S3M_CPU0_SDA")
	)
	(segment
		(start 376.889264 -263.196832)
		(end 376.874532 -263.188196)
		(width 0.0889)
		(layer "B.Cu")
		(net "SMB_S3M_CPU0_SDA")
	)
	(segment
		(start 365.611664 -264.824718)
		(end 365.596932 -264.816082)
		(width 0.0889)
		(layer "B.Cu")
		(net "SMB_S3M_CPU0_SDA")
	)
	(segment
		(start 370.310918 -263.196832)
		(end 370.300504 -263.190736)
		(width 0.0889)
		(layer "B.Cu")
		(net "SMB_S3M_CPU0_SDA")
	)
	(segment
		(start 380.648464 -263.196832)
		(end 380.63805 -263.190736)
		(width 0.0889)
		(layer "B.Cu")
		(net "SMB_S3M_CPU0_SDA")
	)
	(segment
		(start 386.411978 -263.26973)
		(end 386.277104 -263.190736)
		(width 0.0889)
		(layer "B.Cu")
		(net "SMB_S3M_CPU0_SDA")
	)
	(segment
		(start 393.803378 -259.37845)
		(end 392.106658 -259.37845)
		(width 0.12954)
		(layer "B.Cu")
		(net "SMB_S3M_CPU0_SDA")
	)
	(segment
		(start 381.588264 -263.196832)
		(end 381.573532 -263.188196)
		(width 0.0889)
		(layer "B.Cu")
		(net "SMB_S3M_CPU0_SDA")
	)
	(segment
		(start 401.252436 -187.035948)
		(end 405.733758 -191.51727)
		(width 0.12954)
		(layer "B.Cu")
		(net "SMB_S3M_CPU0_SDA")
	)
	(segment
		(start 398.30248 -187.035948)
		(end 401.252436 -187.035948)
		(width 0.12954)
		(layer "B.Cu")
		(net "SMB_S3M_CPU0_SDA")
	)
	(segment
		(start 405.733758 -191.51727)
		(end 405.733758 -193.55181)
		(width 0.12954)
		(layer "B.Cu")
		(net "SMB_S3M_CPU0_SDA")
	)
	(segment
		(start 406.960578 -197.12305)
		(end 408.659838 -198.82231)
		(width 0.12954)
		(layer "B.Cu")
		(net "SMB_S3M_CPU0_SDA")
	)
	(segment
		(start 362.66628 -267.212826)
		(end 362.509562 -266.941808)
		(width 0.0889)
		(layer "B.Cu")
		(net "SMB_S3M_CPU0_SDA")
	)
	(segment
		(start 406.960578 -194.77863)
		(end 406.960578 -197.12305)
		(width 0.12954)
		(layer "B.Cu")
		(net "SMB_S3M_CPU0_SDA")
	)
	(segment
		(start 366.93475 -264.819638)
		(end 366.92586 -264.824718)
		(width 0.0889)
		(layer "B.Cu")
		(net "SMB_S3M_CPU0_SDA")
	)
	(segment
		(start 363.354112 -266.114022)
		(end 363.354112 -266.128246)
		(width 0.0889)
		(layer "B.Cu")
		(net "SMB_S3M_CPU0_SDA")
	)
	(segment
		(start 408.642058 -236.24667)
		(end 408.642058 -236.97819)
		(width 0.12954)
		(layer "B.Cu")
		(net "SMB_S3M_CPU0_SDA")
	)
	(segment
		(start 408.380438 -235.98505)
		(end 408.642058 -236.24667)
		(width 0.12954)
		(layer "B.Cu")
		(net "SMB_S3M_CPU0_SDA")
	)
	(segment
		(start 397.81988 -186.553348)
		(end 398.30248 -187.035948)
		(width 0.12954)
		(layer "B.Cu")
		(net "SMB_S3M_CPU0_SDA")
	)
	(segment
		(start 395.528038 -181.62651)
		(end 395.528038 -183.296306)
		(width 0.12954)
		(layer "B.Cu")
		(net "SMB_S3M_CPU0_SDA")
	)
	(segment
		(start 375.009664 -263.196832)
		(end 374.994932 -263.188196)
		(width 0.0889)
		(layer "B.Cu")
		(net "SMB_S3M_CPU0_SDA")
	)
	(segment
		(start 392.106658 -259.37845)
		(end 391.531602 -259.37845)
		(width 0.12954)
		(layer "B.Cu")
		(net "SMB_S3M_CPU0_SDA")
	)
	(segment
		(start 362.884466 -266.926314)
		(end 362.884466 -266.941808)
		(width 0.0889)
		(layer "B.Cu")
		(net "SMB_S3M_CPU0_SDA")
	)
	(segment
		(start 408.659838 -234.91571)
		(end 408.380438 -235.19511)
		(width 0.12954)
		(layer "B.Cu")
		(net "SMB_S3M_CPU0_SDA")
	)
	(segment
		(start 373.130318 -263.196832)
		(end 373.119904 -263.190736)
		(width 0.0889)
		(layer "B.Cu")
		(net "SMB_S3M_CPU0_SDA")
	)
	(segment
		(start 408.659838 -198.82231)
		(end 408.659838 -234.91571)
		(width 0.12954)
		(layer "B.Cu")
		(net "SMB_S3M_CPU0_SDA")
	)
	(segment
		(start 394.212318 -180.31079)
		(end 395.528038 -181.62651)
		(width 0.12954)
		(layer "B.Cu")
		(net "SMB_S3M_CPU0_SDA")
	)
	(segment
		(start 375.949464 -263.196832)
		(end 375.934732 -263.188196)
		(width 0.0889)
		(layer "B.Cu")
		(net "SMB_S3M_CPU0_SDA")
	)
	(segment
		(start 374.069864 -263.196832)
		(end 374.05945 -263.190736)
		(width 0.0889)
		(layer "B.Cu")
		(net "SMB_S3M_CPU0_SDA")
	)
	(segment
		(start 405.113998 -238.51997)
		(end 399.655538 -243.97843)
		(width 0.12954)
		(layer "B.Cu")
		(net "SMB_S3M_CPU0_SDA")
	)
	(segment
		(start 386.887974 -263.26973)
		(end 386.411978 -263.26973)
		(width 0.0889)
		(layer "B.Cu")
		(net "SMB_S3M_CPU0_SDA")
	)
	(segment
		(start 372.190264 -263.196832)
		(end 372.175532 -263.188196)
		(width 0.0889)
		(layer "B.Cu")
		(net "SMB_S3M_CPU0_SDA")
	)
	(arc
		(start 376.32386 -263.196832)
		(mid 376.136662 -263.246975)
		(end 375.949464 -263.196832)
		(width 0.0889)
		(layer "B.Cu")
		(net "SMB_S3M_CPU0_SDA")
	)
	(arc
		(start 370.685314 -263.196832)
		(mid 370.498116 -263.246975)
		(end 370.310918 -263.196832)
		(width 0.0889)
		(layer "B.Cu")
		(net "SMB_S3M_CPU0_SDA")
	)
	(arc
		(start 371.62486 -263.196832)
		(mid 371.437662 -263.246975)
		(end 371.250464 -263.196832)
		(width 0.0889)
		(layer "B.Cu")
		(net "SMB_S3M_CPU0_SDA")
	)
	(arc
		(start 365.596932 -264.816082)
		(mid 365.320457 -264.748762)
		(end 365.04626 -264.824718)
		(width 0.0889)
		(layer "B.Cu")
		(net "SMB_S3M_CPU0_SDA")
	)
	(arc
		(start 363.354112 -266.128246)
		(mid 363.307973 -266.308431)
		(end 363.180884 -266.444222)
		(width 0.0889)
		(layer "B.Cu")
		(net "SMB_S3M_CPU0_SDA")
	)
	(arc
		(start 363.824266 -265.314176)
		(mid 363.776587 -265.497076)
		(end 363.645704 -265.633454)
		(width 0.0889)
		(layer "B.Cu")
		(net "SMB_S3M_CPU0_SDA")
	)
	(arc
		(start 370.300504 -263.190736)
		(mid 370.022072 -263.120922)
		(end 369.74526 -263.196832)
		(width 0.0889)
		(layer "B.Cu")
		(net "SMB_S3M_CPU0_SDA")
	)
	(arc
		(start 367.113312 -264.50036)
		(mid 367.065633 -264.68326)
		(end 366.93475 -264.819638)
		(width 0.0889)
		(layer "B.Cu")
		(net "SMB_S3M_CPU0_SDA")
	)
	(arc
		(start 378.754132 -263.188196)
		(mid 378.477691 -263.12103)
		(end 378.20346 -263.196832)
		(width 0.0889)
		(layer "B.Cu")
		(net "SMB_S3M_CPU0_SDA")
	)
	(arc
		(start 363.636814 -265.638534)
		(mid 363.433333 -265.839338)
		(end 363.354112 -266.114022)
		(width 0.0889)
		(layer "B.Cu")
		(net "SMB_S3M_CPU0_SDA")
	)
	(arc
		(start 383.84226 -263.196832)
		(mid 383.655062 -263.246975)
		(end 383.467864 -263.196832)
		(width 0.0889)
		(layer "B.Cu")
		(net "SMB_S3M_CPU0_SDA")
	)
	(arc
		(start 366.92586 -264.824718)
		(mid 366.738662 -264.874861)
		(end 366.551464 -264.824718)
		(width 0.0889)
		(layer "B.Cu")
		(net "SMB_S3M_CPU0_SDA")
	)
	(arc
		(start 378.20346 -263.196832)
		(mid 378.016262 -263.246975)
		(end 377.829064 -263.196832)
		(width 0.0889)
		(layer "B.Cu")
		(net "SMB_S3M_CPU0_SDA")
	)
	(arc
		(start 372.56466 -263.196832)
		(mid 372.377462 -263.246975)
		(end 372.190264 -263.196832)
		(width 0.0889)
		(layer "B.Cu")
		(net "SMB_S3M_CPU0_SDA")
	)
	(arc
		(start 377.26366 -263.196832)
		(mid 377.076462 -263.246975)
		(end 376.889264 -263.196832)
		(width 0.0889)
		(layer "B.Cu")
		(net "SMB_S3M_CPU0_SDA")
	)
	(arc
		(start 365.04626 -264.824718)
		(mid 364.859062 -264.874861)
		(end 364.671864 -264.824718)
		(width 0.0889)
		(layer "B.Cu")
		(net "SMB_S3M_CPU0_SDA")
	)
	(arc
		(start 386.277104 -263.190736)
		(mid 385.998672 -263.120922)
		(end 385.72186 -263.196832)
		(width 0.0889)
		(layer "B.Cu")
		(net "SMB_S3M_CPU0_SDA")
	)
	(arc
		(start 384.407664 -263.196832)
		(mid 384.124962 -263.12109)
		(end 383.84226 -263.196832)
		(width 0.0889)
		(layer "B.Cu")
		(net "SMB_S3M_CPU0_SDA")
	)
	(arc
		(start 380.083314 -263.196832)
		(mid 379.896116 -263.246975)
		(end 379.708918 -263.196832)
		(width 0.0889)
		(layer "B.Cu")
		(net "SMB_S3M_CPU0_SDA")
	)
	(arc
		(start 380.63805 -263.190736)
		(mid 380.359872 -263.121044)
		(end 380.083314 -263.196832)
		(width 0.0889)
		(layer "B.Cu")
		(net "SMB_S3M_CPU0_SDA")
	)
	(arc
		(start 385.347464 -263.196832)
		(mid 385.064762 -263.12109)
		(end 384.78206 -263.196832)
		(width 0.0889)
		(layer "B.Cu")
		(net "SMB_S3M_CPU0_SDA")
	)
	(arc
		(start 381.96266 -263.196832)
		(mid 381.775462 -263.246975)
		(end 381.588264 -263.196832)
		(width 0.0889)
		(layer "B.Cu")
		(net "SMB_S3M_CPU0_SDA")
	)
	(arc
		(start 371.250464 -263.196832)
		(mid 370.973905 -263.121123)
		(end 370.695728 -263.190736)
		(width 0.0889)
		(layer "B.Cu")
		(net "SMB_S3M_CPU0_SDA")
	)
	(arc
		(start 381.573532 -263.188196)
		(mid 381.297091 -263.12103)
		(end 381.02286 -263.196832)
		(width 0.0889)
		(layer "B.Cu")
		(net "SMB_S3M_CPU0_SDA")
	)
	(arc
		(start 362.884466 -266.941808)
		(mid 362.847606 -267.103605)
		(end 362.744512 -267.233654)
		(width 0.0889)
		(layer "B.Cu")
		(net "SMB_S3M_CPU0_SDA")
	)
	(arc
		(start 382.90246 -263.196832)
		(mid 382.715262 -263.246975)
		(end 382.528064 -263.196832)
		(width 0.0889)
		(layer "B.Cu")
		(net "SMB_S3M_CPU0_SDA")
	)
	(arc
		(start 373.119904 -263.190736)
		(mid 372.841472 -263.120922)
		(end 372.56466 -263.196832)
		(width 0.0889)
		(layer "B.Cu")
		(net "SMB_S3M_CPU0_SDA")
	)
	(arc
		(start 384.78206 -263.196832)
		(mid 384.594862 -263.246975)
		(end 384.407664 -263.196832)
		(width 0.0889)
		(layer "B.Cu")
		(net "SMB_S3M_CPU0_SDA")
	)
	(arc
		(start 382.513332 -263.188196)
		(mid 382.236891 -263.12103)
		(end 381.96266 -263.196832)
		(width 0.0889)
		(layer "B.Cu")
		(net "SMB_S3M_CPU0_SDA")
	)
	(arc
		(start 379.14326 -263.196832)
		(mid 378.956062 -263.246975)
		(end 378.768864 -263.196832)
		(width 0.0889)
		(layer "B.Cu")
		(net "SMB_S3M_CPU0_SDA")
	)
	(arc
		(start 383.467864 -263.196832)
		(mid 383.185162 -263.12109)
		(end 382.90246 -263.196832)
		(width 0.0889)
		(layer "B.Cu")
		(net "SMB_S3M_CPU0_SDA")
	)
	(arc
		(start 369.74526 -263.196832)
		(mid 369.654902 -263.234735)
		(end 369.557808 -263.247886)
		(width 0.0889)
		(layer "B.Cu")
		(net "SMB_S3M_CPU0_SDA")
	)
	(arc
		(start 381.02286 -263.196832)
		(mid 380.835662 -263.246975)
		(end 380.648464 -263.196832)
		(width 0.0889)
		(layer "B.Cu")
		(net "SMB_S3M_CPU0_SDA")
	)
	(arc
		(start 385.72186 -263.196832)
		(mid 385.534662 -263.246975)
		(end 385.347464 -263.196832)
		(width 0.0889)
		(layer "B.Cu")
		(net "SMB_S3M_CPU0_SDA")
	)
	(arc
		(start 379.698504 -263.190736)
		(mid 379.420072 -263.120922)
		(end 379.14326 -263.196832)
		(width 0.0889)
		(layer "B.Cu")
		(net "SMB_S3M_CPU0_SDA")
	)
	(arc
		(start 365.98606 -264.824718)
		(mid 365.798862 -264.874861)
		(end 365.611664 -264.824718)
		(width 0.0889)
		(layer "B.Cu")
		(net "SMB_S3M_CPU0_SDA")
	)
	(arc
		(start 374.994932 -263.188196)
		(mid 374.718491 -263.12103)
		(end 374.44426 -263.196832)
		(width 0.0889)
		(layer "B.Cu")
		(net "SMB_S3M_CPU0_SDA")
	)
	(arc
		(start 375.38406 -263.196832)
		(mid 375.196862 -263.246975)
		(end 375.009664 -263.196832)
		(width 0.0889)
		(layer "B.Cu")
		(net "SMB_S3M_CPU0_SDA")
	)
	(arc
		(start 375.934732 -263.188196)
		(mid 375.658291 -263.12103)
		(end 375.38406 -263.196832)
		(width 0.0889)
		(layer "B.Cu")
		(net "SMB_S3M_CPU0_SDA")
	)
	(arc
		(start 377.829064 -263.196832)
		(mid 377.546362 -263.12109)
		(end 377.26366 -263.196832)
		(width 0.0889)
		(layer "B.Cu")
		(net "SMB_S3M_CPU0_SDA")
	)
	(arc
		(start 376.874532 -263.188196)
		(mid 376.598091 -263.12103)
		(end 376.32386 -263.196832)
		(width 0.0889)
		(layer "B.Cu")
		(net "SMB_S3M_CPU0_SDA")
	)
	(arc
		(start 364.657132 -264.816082)
		(mid 364.380657 -264.748762)
		(end 364.10646 -264.824718)
		(width 0.0889)
		(layer "B.Cu")
		(net "SMB_S3M_CPU0_SDA")
	)
	(arc
		(start 374.44426 -263.196832)
		(mid 374.257062 -263.246975)
		(end 374.069864 -263.196832)
		(width 0.0889)
		(layer "B.Cu")
		(net "SMB_S3M_CPU0_SDA")
	)
	(arc
		(start 366.551464 -264.824718)
		(mid 366.268762 -264.748942)
		(end 365.98606 -264.824718)
		(width 0.0889)
		(layer "B.Cu")
		(net "SMB_S3M_CPU0_SDA")
	)
	(arc
		(start 373.504714 -263.196832)
		(mid 373.317516 -263.246975)
		(end 373.130318 -263.196832)
		(width 0.0889)
		(layer "B.Cu")
		(net "SMB_S3M_CPU0_SDA")
	)
	(arc
		(start 374.05945 -263.190736)
		(mid 373.781272 -263.121044)
		(end 373.504714 -263.196832)
		(width 0.0889)
		(layer "B.Cu")
		(net "SMB_S3M_CPU0_SDA")
	)
	(arc
		(start 364.10646 -264.824718)
		(mid 363.903637 -265.024949)
		(end 363.824266 -265.298682)
		(width 0.0889)
		(layer "B.Cu")
		(net "SMB_S3M_CPU0_SDA")
	)
	(arc
		(start 363.16666 -266.45235)
		(mid 362.963837 -266.652581)
		(end 362.884466 -266.926314)
		(width 0.0889)
		(layer "B.Cu")
		(net "SMB_S3M_CPU0_SDA")
	)
	(arc
		(start 372.175532 -263.188196)
		(mid 371.899091 -263.12103)
		(end 371.62486 -263.196832)
		(width 0.0889)
		(layer "B.Cu")
		(net "SMB_S3M_CPU0_SDA")
	)
	(segment
		(start 393.741148 -163.36264)
		(end 393.741148 -162.760914)
		(width 0.12954)
		(layer "F.Cu")
		(net "SMB_S3M_CPU0_SCL")
	)
	(segment
		(start 393.142978 -163.96081)
		(end 393.741148 -163.36264)
		(width 0.12954)
		(layer "F.Cu")
		(net "SMB_S3M_CPU0_SCL")
	)
	(segment
		(start 393.142978 -177.20945)
		(end 393.142978 -163.96081)
		(width 0.12954)
		(layer "F.Cu")
		(net "SMB_S3M_CPU0_SCL")
	)
	(segment
		(start 393.932918 -177.99939)
		(end 393.142978 -177.20945)
		(width 0.12954)
		(layer "F.Cu")
		(net "SMB_S3M_CPU0_SCL")
	)
	(segment
		(start 362.979716 -267.219938)
		(end 362.979462 -267.755878)
		(width 0.12954)
		(layer "F.Cu")
		(net "SMB_S3M_CPU0_SCL")
	)
	(segment
		(start 393.932918 -178.900328)
		(end 393.932918 -177.99939)
		(width 0.12954)
		(layer "F.Cu")
		(net "SMB_S3M_CPU0_SCL")
	)
	(via
		(at 362.979462 -267.755878)
		(size 0.4572)
		(drill 0.2032)
		(layers "F.Cu" "B.Cu")
		(net "SMB_S3M_CPU0_SCL")
	)
	(via
		(at 391.217658 -260.88213)
		(size 0.6604)
		(drill 0.3302)
		(layers "F.Cu" "B.Cu")
		(net "SMB_S3M_CPU0_SCL")
	)
	(via
		(at 393.932918 -178.900328)
		(size 0.508)
		(drill 0.254)
		(layers "F.Cu" "B.Cu")
		(net "SMB_S3M_CPU0_SCL")
	)
	(segment
		(start 409.094178 -198.64197)
		(end 409.094178 -235.23067)
		(width 0.12954)
		(layer "B.Cu")
		(net "SMB_S3M_CPU0_SCL")
	)
	(segment
		(start 398.30248 -185.740548)
		(end 398.50568 -185.943748)
		(width 0.12954)
		(layer "B.Cu")
		(net "SMB_S3M_CPU0_SCL")
	)
	(segment
		(start 378.688346 -263.370822)
		(end 378.673614 -263.362186)
		(width 0.0889)
		(layer "B.Cu")
		(net "SMB_S3M_CPU0_SCL")
	)
	(segment
		(start 382.443228 -263.368282)
		(end 382.432814 -263.362186)
		(width 0.0889)
		(layer "B.Cu")
		(net "SMB_S3M_CPU0_SCL")
	)
	(segment
		(start 393.932918 -178.900328)
		(end 393.932918 -179.41671)
		(width 0.12954)
		(layer "B.Cu")
		(net "SMB_S3M_CPU0_SCL")
	)
	(segment
		(start 368.431064 -264.824718)
		(end 368.416332 -264.816082)
		(width 0.0889)
		(layer "B.Cu")
		(net "SMB_S3M_CPU0_SCL")
	)
	(segment
		(start 387.938518 -263.713976)
		(end 386.887974 -263.713976)
		(width 0.12954)
		(layer "B.Cu")
		(net "SMB_S3M_CPU0_SCL")
	)
	(segment
		(start 377.743974 -263.368282)
		(end 377.73356 -263.362186)
		(width 0.0889)
		(layer "B.Cu")
		(net "SMB_S3M_CPU0_SCL")
	)
	(segment
		(start 369.124738 -263.711182)
		(end 369.124738 -264.57656)
		(width 0.0889)
		(layer "B.Cu")
		(net "SMB_S3M_CPU0_SCL")
	)
	(segment
		(start 374.929146 -263.370822)
		(end 374.914414 -263.362186)
		(width 0.0889)
		(layer "B.Cu")
		(net "SMB_S3M_CPU0_SCL")
	)
	(segment
		(start 395.990318 -182.869586)
		(end 398.30248 -185.181748)
		(width 0.12954)
		(layer "B.Cu")
		(net "SMB_S3M_CPU0_SCL")
	)
	(segment
		(start 408.619198 -198.16699)
		(end 409.094178 -198.64197)
		(width 0.12954)
		(layer "B.Cu")
		(net "SMB_S3M_CPU0_SCL")
	)
	(segment
		(start 380.567946 -263.370822)
		(end 380.553214 -263.362186)
		(width 0.0889)
		(layer "B.Cu")
		(net "SMB_S3M_CPU0_SCL")
	)
	(segment
		(start 395.990318 -181.47411)
		(end 395.990318 -182.869586)
		(width 0.12954)
		(layer "B.Cu")
		(net "SMB_S3M_CPU0_SCL")
	)
	(segment
		(start 392.980418 -260.88213)
		(end 391.217658 -260.88213)
		(width 0.12954)
		(layer "B.Cu")
		(net "SMB_S3M_CPU0_SCL")
	)
	(segment
		(start 407.407618 -194.58813)
		(end 407.407618 -195.95973)
		(width 0.12954)
		(layer "B.Cu")
		(net "SMB_S3M_CPU0_SCL")
	)
	(segment
		(start 391.217658 -260.88213)
		(end 390.770364 -260.88213)
		(width 0.12954)
		(layer "B.Cu")
		(net "SMB_S3M_CPU0_SCL")
	)
	(segment
		(start 409.094178 -235.23067)
		(end 408.972258 -235.35259)
		(width 0.12954)
		(layer "B.Cu")
		(net "SMB_S3M_CPU0_SCL")
	)
	(segment
		(start 363.732064 -265.803888)
		(end 363.723174 -265.808968)
		(width 0.0889)
		(layer "B.Cu")
		(net "SMB_S3M_CPU0_SCL")
	)
	(segment
		(start 363.262418 -266.617704)
		(end 363.248194 -266.625832)
		(width 0.0889)
		(layer "B.Cu")
		(net "SMB_S3M_CPU0_SCL")
	)
	(segment
		(start 400.216878 -244.23243)
		(end 400.216878 -253.64567)
		(width 0.12954)
		(layer "B.Cu")
		(net "SMB_S3M_CPU0_SCL")
	)
	(segment
		(start 385.817618 -263.362186)
		(end 385.817364 -263.362186)
		(width 0.0889)
		(layer "B.Cu")
		(net "SMB_S3M_CPU0_SCL")
	)
	(segment
		(start 393.932918 -179.41671)
		(end 395.990318 -181.47411)
		(width 0.12954)
		(layer "B.Cu")
		(net "SMB_S3M_CPU0_SCL")
	)
	(segment
		(start 364.014766 -265.314176)
		(end 364.014766 -265.3284)
		(width 0.0889)
		(layer "B.Cu")
		(net "SMB_S3M_CPU0_SCL")
	)
	(segment
		(start 362.822998 -267.48486)
		(end 362.979462 -267.755878)
		(width 0.0889)
		(layer "B.Cu")
		(net "SMB_S3M_CPU0_SCL")
	)
	(segment
		(start 398.50568 -185.943748)
		(end 400.896836 -185.943748)
		(width 0.12954)
		(layer "B.Cu")
		(net "SMB_S3M_CPU0_SCL")
	)
	(segment
		(start 367.26876 -264.824718)
		(end 367.170462 -264.865358)
		(width 0.0889)
		(layer "B.Cu")
		(net "SMB_S3M_CPU0_SCL")
	)
	(segment
		(start 400.896836 -185.943748)
		(end 406.419558 -191.46647)
		(width 0.12954)
		(layer "B.Cu")
		(net "SMB_S3M_CPU0_SCL")
	)
	(segment
		(start 408.972258 -235.80217)
		(end 409.094178 -235.92409)
		(width 0.12954)
		(layer "B.Cu")
		(net "SMB_S3M_CPU0_SCL")
	)
	(segment
		(start 408.972258 -235.35259)
		(end 408.972258 -235.80217)
		(width 0.12954)
		(layer "B.Cu")
		(net "SMB_S3M_CPU0_SCL")
	)
	(segment
		(start 370.780564 -263.362186)
		(end 370.77015 -263.368282)
		(width 0.0889)
		(layer "B.Cu")
		(net "SMB_S3M_CPU0_SCL")
	)
	(segment
		(start 398.30248 -185.181748)
		(end 398.30248 -185.740548)
		(width 0.12954)
		(layer "B.Cu")
		(net "SMB_S3M_CPU0_SCL")
	)
	(segment
		(start 376.804428 -263.368282)
		(end 376.794014 -263.362186)
		(width 0.0889)
		(layer "B.Cu")
		(net "SMB_S3M_CPU0_SCL")
	)
	(segment
		(start 406.419558 -191.46647)
		(end 406.419558 -193.60007)
		(width 0.12954)
		(layer "B.Cu")
		(net "SMB_S3M_CPU0_SCL")
	)
	(segment
		(start 364.591346 -264.998454)
		(end 364.576614 -264.989818)
		(width 0.0889)
		(layer "B.Cu")
		(net "SMB_S3M_CPU0_SCL")
	)
	(segment
		(start 408.619198 -197.17131)
		(end 408.619198 -198.16699)
		(width 0.12954)
		(layer "B.Cu")
		(net "SMB_S3M_CPU0_SCL")
	)
	(segment
		(start 369.397788 -263.438132)
		(end 369.124738 -263.711182)
		(width 0.0889)
		(layer "B.Cu")
		(net "SMB_S3M_CPU0_SCL")
	)
	(segment
		(start 365.526828 -264.995914)
		(end 365.516414 -264.989818)
		(width 0.0889)
		(layer "B.Cu")
		(net "SMB_S3M_CPU0_SCL")
	)
	(segment
		(start 381.507746 -263.370822)
		(end 381.493014 -263.362186)
		(width 0.0889)
		(layer "B.Cu")
		(net "SMB_S3M_CPU0_SCL")
	)
	(segment
		(start 406.419558 -193.60007)
		(end 407.407618 -194.58813)
		(width 0.12954)
		(layer "B.Cu")
		(net "SMB_S3M_CPU0_SCL")
	)
	(segment
		(start 390.770364 -260.88213)
		(end 387.938518 -263.713976)
		(width 0.12954)
		(layer "B.Cu")
		(net "SMB_S3M_CPU0_SCL")
	)
	(segment
		(start 386.543804 -263.713976)
		(end 386.192014 -263.362186)
		(width 0.0889)
		(layer "B.Cu")
		(net "SMB_S3M_CPU0_SCL")
	)
	(segment
		(start 369.558062 -263.438132)
		(end 369.397788 -263.438132)
		(width 0.0889)
		(layer "B.Cu")
		(net "SMB_S3M_CPU0_SCL")
	)
	(segment
		(start 407.407618 -195.95973)
		(end 408.619198 -197.17131)
		(width 0.12954)
		(layer "B.Cu")
		(net "SMB_S3M_CPU0_SCL")
	)
	(segment
		(start 373.989346 -263.370822)
		(end 373.974614 -263.362186)
		(width 0.0889)
		(layer "B.Cu")
		(net "SMB_S3M_CPU0_SCL")
	)
	(segment
		(start 363.074966 -266.941808)
		(end 363.074966 -266.956032)
		(width 0.0889)
		(layer "B.Cu")
		(net "SMB_S3M_CPU0_SCL")
	)
	(segment
		(start 386.887974 -263.713976)
		(end 386.543804 -263.713976)
		(width 0.0889)
		(layer "B.Cu")
		(net "SMB_S3M_CPU0_SCL")
	)
	(segment
		(start 409.094178 -237.39221)
		(end 407.041858 -239.44453)
		(width 0.12954)
		(layer "B.Cu")
		(net "SMB_S3M_CPU0_SCL")
	)
	(segment
		(start 364.202218 -264.989818)
		(end 364.193328 -264.994898)
		(width 0.0889)
		(layer "B.Cu")
		(net "SMB_S3M_CPU0_SCL")
	)
	(segment
		(start 405.004778 -239.44453)
		(end 400.216878 -244.23243)
		(width 0.12954)
		(layer "B.Cu")
		(net "SMB_S3M_CPU0_SCL")
	)
	(segment
		(start 407.041858 -239.44453)
		(end 405.004778 -239.44453)
		(width 0.12954)
		(layer "B.Cu")
		(net "SMB_S3M_CPU0_SCL")
	)
	(segment
		(start 375.868946 -263.370822)
		(end 375.854214 -263.362186)
		(width 0.0889)
		(layer "B.Cu")
		(net "SMB_S3M_CPU0_SCL")
	)
	(segment
		(start 409.094178 -235.92409)
		(end 409.094178 -237.39221)
		(width 0.12954)
		(layer "B.Cu")
		(net "SMB_S3M_CPU0_SCL")
	)
	(segment
		(start 366.466374 -264.995914)
		(end 366.45596 -264.989818)
		(width 0.0889)
		(layer "B.Cu")
		(net "SMB_S3M_CPU0_SCL")
	)
	(segment
		(start 400.216878 -253.64567)
		(end 392.980418 -260.88213)
		(width 0.12954)
		(layer "B.Cu")
		(net "SMB_S3M_CPU0_SCL")
	)
	(segment
		(start 367.491518 -264.824718)
		(end 367.26876 -264.824718)
		(width 0.0889)
		(layer "B.Cu")
		(net "SMB_S3M_CPU0_SCL")
	)
	(segment
		(start 363.544612 -266.128246)
		(end 363.544612 -266.14374)
		(width 0.0889)
		(layer "B.Cu")
		(net "SMB_S3M_CPU0_SCL")
	)
	(segment
		(start 369.124738 -264.57656)
		(end 368.92992 -264.771378)
		(width 0.0889)
		(layer "B.Cu")
		(net "SMB_S3M_CPU0_SCL")
	)
	(segment
		(start 362.847128 -267.395706)
		(end 362.822998 -267.48486)
		(width 0.0889)
		(layer "B.Cu")
		(net "SMB_S3M_CPU0_SCL")
	)
	(segment
		(start 372.109746 -263.370822)
		(end 372.095014 -263.362186)
		(width 0.0889)
		(layer "B.Cu")
		(net "SMB_S3M_CPU0_SCL")
	)
	(segment
		(start 371.165374 -263.368282)
		(end 371.15496 -263.362186)
		(width 0.0889)
		(layer "B.Cu")
		(net "SMB_S3M_CPU0_SCL")
	)
	(arc
		(start 385.817364 -263.362186)
		(mid 385.534662 -263.437928)
		(end 385.25196 -263.362186)
		(width 0.0889)
		(layer "B.Cu")
		(net "SMB_S3M_CPU0_SCL")
	)
	(arc
		(start 368.416332 -264.816082)
		(mid 368.139857 -264.748762)
		(end 367.86566 -264.824718)
		(width 0.0889)
		(layer "B.Cu")
		(net "SMB_S3M_CPU0_SCL")
	)
	(arc
		(start 379.239018 -263.362186)
		(mid 378.964789 -263.438111)
		(end 378.688346 -263.370822)
		(width 0.0889)
		(layer "B.Cu")
		(net "SMB_S3M_CPU0_SCL")
	)
	(arc
		(start 380.178818 -263.362186)
		(mid 379.896116 -263.437928)
		(end 379.613414 -263.362186)
		(width 0.0889)
		(layer "B.Cu")
		(net "SMB_S3M_CPU0_SCL")
	)
	(arc
		(start 374.540018 -263.362186)
		(mid 374.265789 -263.438111)
		(end 373.989346 -263.370822)
		(width 0.0889)
		(layer "B.Cu")
		(net "SMB_S3M_CPU0_SCL")
	)
	(arc
		(start 370.77015 -263.368282)
		(mid 370.491972 -263.437974)
		(end 370.215414 -263.362186)
		(width 0.0889)
		(layer "B.Cu")
		(net "SMB_S3M_CPU0_SCL")
	)
	(arc
		(start 363.074966 -266.956032)
		(mid 363.011757 -267.202149)
		(end 362.847128 -267.395706)
		(width 0.0889)
		(layer "B.Cu")
		(net "SMB_S3M_CPU0_SCL")
	)
	(arc
		(start 377.73356 -263.362186)
		(mid 377.546362 -263.312043)
		(end 377.359164 -263.362186)
		(width 0.0889)
		(layer "B.Cu")
		(net "SMB_S3M_CPU0_SCL")
	)
	(arc
		(start 366.081564 -264.989818)
		(mid 365.805005 -265.065561)
		(end 365.526828 -264.995914)
		(width 0.0889)
		(layer "B.Cu")
		(net "SMB_S3M_CPU0_SCL")
	)
	(arc
		(start 386.192014 -263.362186)
		(mid 386.004816 -263.312043)
		(end 385.817618 -263.362186)
		(width 0.0889)
		(layer "B.Cu")
		(net "SMB_S3M_CPU0_SCL")
	)
	(arc
		(start 365.516414 -264.989818)
		(mid 365.329216 -264.939675)
		(end 365.142018 -264.989818)
		(width 0.0889)
		(layer "B.Cu")
		(net "SMB_S3M_CPU0_SCL")
	)
	(arc
		(start 364.014766 -265.3284)
		(mid 363.935547 -265.603085)
		(end 363.732064 -265.803888)
		(width 0.0889)
		(layer "B.Cu")
		(net "SMB_S3M_CPU0_SCL")
	)
	(arc
		(start 374.914414 -263.362186)
		(mid 374.727216 -263.312043)
		(end 374.540018 -263.362186)
		(width 0.0889)
		(layer "B.Cu")
		(net "SMB_S3M_CPU0_SCL")
	)
	(arc
		(start 376.419618 -263.362186)
		(mid 376.145389 -263.438111)
		(end 375.868946 -263.370822)
		(width 0.0889)
		(layer "B.Cu")
		(net "SMB_S3M_CPU0_SCL")
	)
	(arc
		(start 364.193328 -264.994898)
		(mid 364.062414 -265.131258)
		(end 364.014766 -265.314176)
		(width 0.0889)
		(layer "B.Cu")
		(net "SMB_S3M_CPU0_SCL")
	)
	(arc
		(start 367.170462 -264.865358)
		(mid 366.841723 -265.056286)
		(end 366.466374 -264.995914)
		(width 0.0889)
		(layer "B.Cu")
		(net "SMB_S3M_CPU0_SCL")
	)
	(arc
		(start 385.25196 -263.362186)
		(mid 385.064762 -263.312043)
		(end 384.877564 -263.362186)
		(width 0.0889)
		(layer "B.Cu")
		(net "SMB_S3M_CPU0_SCL")
	)
	(arc
		(start 366.45596 -264.989818)
		(mid 366.268762 -264.939675)
		(end 366.081564 -264.989818)
		(width 0.0889)
		(layer "B.Cu")
		(net "SMB_S3M_CPU0_SCL")
	)
	(arc
		(start 382.432814 -263.362186)
		(mid 382.245616 -263.312043)
		(end 382.058418 -263.362186)
		(width 0.0889)
		(layer "B.Cu")
		(net "SMB_S3M_CPU0_SCL")
	)
	(arc
		(start 382.058418 -263.362186)
		(mid 381.784189 -263.438111)
		(end 381.507746 -263.370822)
		(width 0.0889)
		(layer "B.Cu")
		(net "SMB_S3M_CPU0_SCL")
	)
	(arc
		(start 370.215414 -263.362186)
		(mid 370.028216 -263.312043)
		(end 369.841018 -263.362186)
		(width 0.0889)
		(layer "B.Cu")
		(net "SMB_S3M_CPU0_SCL")
	)
	(arc
		(start 381.118618 -263.362186)
		(mid 380.844389 -263.438111)
		(end 380.567946 -263.370822)
		(width 0.0889)
		(layer "B.Cu")
		(net "SMB_S3M_CPU0_SCL")
	)
	(arc
		(start 364.576614 -264.989818)
		(mid 364.389416 -264.939675)
		(end 364.202218 -264.989818)
		(width 0.0889)
		(layer "B.Cu")
		(net "SMB_S3M_CPU0_SCL")
	)
	(arc
		(start 368.80546 -264.824718)
		(mid 368.618262 -264.874861)
		(end 368.431064 -264.824718)
		(width 0.0889)
		(layer "B.Cu")
		(net "SMB_S3M_CPU0_SCL")
	)
	(arc
		(start 363.248194 -266.625832)
		(mid 363.121151 -266.761648)
		(end 363.074966 -266.941808)
		(width 0.0889)
		(layer "B.Cu")
		(net "SMB_S3M_CPU0_SCL")
	)
	(arc
		(start 367.86566 -264.824718)
		(mid 367.678606 -264.874768)
		(end 367.491518 -264.824718)
		(width 0.0889)
		(layer "B.Cu")
		(net "SMB_S3M_CPU0_SCL")
	)
	(arc
		(start 380.553214 -263.362186)
		(mid 380.366016 -263.312043)
		(end 380.178818 -263.362186)
		(width 0.0889)
		(layer "B.Cu")
		(net "SMB_S3M_CPU0_SCL")
	)
	(arc
		(start 382.997964 -263.362186)
		(mid 382.721405 -263.437895)
		(end 382.443228 -263.368282)
		(width 0.0889)
		(layer "B.Cu")
		(net "SMB_S3M_CPU0_SCL")
	)
	(arc
		(start 379.613414 -263.362186)
		(mid 379.426216 -263.312043)
		(end 379.239018 -263.362186)
		(width 0.0889)
		(layer "B.Cu")
		(net "SMB_S3M_CPU0_SCL")
	)
	(arc
		(start 375.479818 -263.362186)
		(mid 375.205589 -263.438111)
		(end 374.929146 -263.370822)
		(width 0.0889)
		(layer "B.Cu")
		(net "SMB_S3M_CPU0_SCL")
	)
	(arc
		(start 373.034814 -263.362186)
		(mid 372.847616 -263.312043)
		(end 372.660418 -263.362186)
		(width 0.0889)
		(layer "B.Cu")
		(net "SMB_S3M_CPU0_SCL")
	)
	(arc
		(start 384.877564 -263.362186)
		(mid 384.594862 -263.437928)
		(end 384.31216 -263.362186)
		(width 0.0889)
		(layer "B.Cu")
		(net "SMB_S3M_CPU0_SCL")
	)
	(arc
		(start 371.720618 -263.362186)
		(mid 371.443805 -263.438022)
		(end 371.165374 -263.368282)
		(width 0.0889)
		(layer "B.Cu")
		(net "SMB_S3M_CPU0_SCL")
	)
	(arc
		(start 384.31216 -263.362186)
		(mid 384.124962 -263.312043)
		(end 383.937764 -263.362186)
		(width 0.0889)
		(layer "B.Cu")
		(net "SMB_S3M_CPU0_SCL")
	)
	(arc
		(start 375.854214 -263.362186)
		(mid 375.667016 -263.312043)
		(end 375.479818 -263.362186)
		(width 0.0889)
		(layer "B.Cu")
		(net "SMB_S3M_CPU0_SCL")
	)
	(arc
		(start 381.493014 -263.362186)
		(mid 381.305816 -263.312043)
		(end 381.118618 -263.362186)
		(width 0.0889)
		(layer "B.Cu")
		(net "SMB_S3M_CPU0_SCL")
	)
	(arc
		(start 373.974614 -263.362186)
		(mid 373.787416 -263.312043)
		(end 373.600218 -263.362186)
		(width 0.0889)
		(layer "B.Cu")
		(net "SMB_S3M_CPU0_SCL")
	)
	(arc
		(start 383.937764 -263.362186)
		(mid 383.655062 -263.437928)
		(end 383.37236 -263.362186)
		(width 0.0889)
		(layer "B.Cu")
		(net "SMB_S3M_CPU0_SCL")
	)
	(arc
		(start 363.544612 -266.14374)
		(mid 363.465242 -266.417474)
		(end 363.262418 -266.617704)
		(width 0.0889)
		(layer "B.Cu")
		(net "SMB_S3M_CPU0_SCL")
	)
	(arc
		(start 376.794014 -263.362186)
		(mid 376.606816 -263.312043)
		(end 376.419618 -263.362186)
		(width 0.0889)
		(layer "B.Cu")
		(net "SMB_S3M_CPU0_SCL")
	)
	(arc
		(start 365.142018 -264.989818)
		(mid 364.867819 -265.065653)
		(end 364.591346 -264.998454)
		(width 0.0889)
		(layer "B.Cu")
		(net "SMB_S3M_CPU0_SCL")
	)
	(arc
		(start 377.359164 -263.362186)
		(mid 377.082605 -263.437895)
		(end 376.804428 -263.368282)
		(width 0.0889)
		(layer "B.Cu")
		(net "SMB_S3M_CPU0_SCL")
	)
	(arc
		(start 369.841018 -263.362186)
		(mid 369.704545 -263.41882)
		(end 369.558062 -263.438132)
		(width 0.0889)
		(layer "B.Cu")
		(net "SMB_S3M_CPU0_SCL")
	)
	(arc
		(start 378.673614 -263.362186)
		(mid 378.486416 -263.312043)
		(end 378.299218 -263.362186)
		(width 0.0889)
		(layer "B.Cu")
		(net "SMB_S3M_CPU0_SCL")
	)
	(arc
		(start 363.723174 -265.808968)
		(mid 363.59226 -265.945328)
		(end 363.544612 -266.128246)
		(width 0.0889)
		(layer "B.Cu")
		(net "SMB_S3M_CPU0_SCL")
	)
	(arc
		(start 378.299218 -263.362186)
		(mid 378.022405 -263.438022)
		(end 377.743974 -263.368282)
		(width 0.0889)
		(layer "B.Cu")
		(net "SMB_S3M_CPU0_SCL")
	)
	(arc
		(start 371.15496 -263.362186)
		(mid 370.967762 -263.312043)
		(end 370.780564 -263.362186)
		(width 0.0889)
		(layer "B.Cu")
		(net "SMB_S3M_CPU0_SCL")
	)
	(arc
		(start 372.660418 -263.362186)
		(mid 372.386189 -263.438111)
		(end 372.109746 -263.370822)
		(width 0.0889)
		(layer "B.Cu")
		(net "SMB_S3M_CPU0_SCL")
	)
	(arc
		(start 372.095014 -263.362186)
		(mid 371.907816 -263.312043)
		(end 371.720618 -263.362186)
		(width 0.0889)
		(layer "B.Cu")
		(net "SMB_S3M_CPU0_SCL")
	)
	(arc
		(start 373.600218 -263.362186)
		(mid 373.317516 -263.437928)
		(end 373.034814 -263.362186)
		(width 0.0889)
		(layer "B.Cu")
		(net "SMB_S3M_CPU0_SCL")
	)
	(arc
		(start 383.37236 -263.362186)
		(mid 383.185162 -263.312043)
		(end 382.997964 -263.362186)
		(width 0.0889)
		(layer "B.Cu")
		(net "SMB_S3M_CPU0_SCL")
	)
	(arc
		(start 368.92992 -264.771378)
		(mid 368.866095 -264.794323)
		(end 368.80546 -264.824718)
		(width 0.0889)
		(layer "B.Cu")
		(net "SMB_S3M_CPU0_SCL")
	)
	(segment
		(start 392.763248 -161.960814)
		(end 392.763248 -161.07791)
		(width 0.12954)
		(layer "F.Cu")
		(net "SMB_S3M_CPU0_R_SDA")
	)
	(segment
		(start 392.14933 -159.838644)
		(end 392.14933 -160.221676)
		(width 0.12954)
		(layer "F.Cu")
		(net "SMB_S3M_CPU0_R_SDA")
	)
	(segment
		(start 392.681206 -158.84398)
		(end 392.14933 -159.375856)
		(width 0.12954)
		(layer "F.Cu")
		(net "SMB_S3M_CPU0_R_SDA")
	)
	(segment
		(start 392.763248 -160.835594)
		(end 392.763248 -161.07791)
		(width 0.12954)
		(layer "F.Cu")
		(net "SMB_S3M_CPU0_R_SDA")
	)
	(segment
		(start 392.681206 -157.997652)
		(end 392.681206 -158.84398)
		(width 0.12954)
		(layer "F.Cu")
		(net "SMB_S3M_CPU0_R_SDA")
	)
	(segment
		(start 392.14933 -159.375856)
		(end 392.14933 -159.838644)
		(width 0.12954)
		(layer "F.Cu")
		(net "SMB_S3M_CPU0_R_SDA")
	)
	(segment
		(start 392.14933 -160.221676)
		(end 392.763248 -160.835594)
		(width 0.12954)
		(layer "F.Cu")
		(net "SMB_S3M_CPU0_R_SDA")
	)
	(via
		(at 392.14933 -159.838644)
		(size 0.762)
		(drill 0.381)
		(layers "F.Cu" "B.Cu")
		(net "SMB_S3M_CPU0_R_SDA")
	)
	(segment
		(start 393.59586 -159.455358)
		(end 393.59586 -159.84093)
		(width 0.12954)
		(layer "F.Cu")
		(net "SMB_S3M_CPU0_R_SCL")
	)
	(segment
		(start 393.951206 -159.100012)
		(end 393.59586 -159.455358)
		(width 0.12954)
		(layer "F.Cu")
		(net "SMB_S3M_CPU0_R_SCL")
	)
	(segment
		(start 393.741148 -161.960814)
		(end 393.741148 -161.07791)
		(width 0.12954)
		(layer "F.Cu")
		(net "SMB_S3M_CPU0_R_SCL")
	)
	(segment
		(start 393.951206 -157.997652)
		(end 393.951206 -159.100012)
		(width 0.12954)
		(layer "F.Cu")
		(net "SMB_S3M_CPU0_R_SCL")
	)
	(segment
		(start 393.741148 -160.490154)
		(end 393.741148 -161.07791)
		(width 0.12954)
		(layer "F.Cu")
		(net "SMB_S3M_CPU0_R_SCL")
	)
	(segment
		(start 393.59586 -159.84093)
		(end 393.59586 -160.344866)
		(width 0.12954)
		(layer "F.Cu")
		(net "SMB_S3M_CPU0_R_SCL")
	)
	(segment
		(start 393.59586 -160.344866)
		(end 393.741148 -160.490154)
		(width 0.12954)
		(layer "F.Cu")
		(net "SMB_S3M_CPU0_R_SCL")
	)
	(via
		(at 393.59586 -159.84093)
		(size 0.762)
		(drill 0.381)
		(layers "F.Cu" "B.Cu")
		(net "SMB_S3M_CPU0_R_SCL")
	)
	(segment
		(start 157.985968 -75.919838)
		(end 159.4993 -75.919838)
		(width 0.12954)
		(layer "F.Cu")
		(net "SMB_S3M_CPU0_3V3AUX_SDA_R")
	)
	(segment
		(start 161.79038 -75.919838)
		(end 161.94278 -75.767438)
		(width 0.12954)
		(layer "F.Cu")
		(net "SMB_S3M_CPU0_3V3AUX_SDA_R")
	)
	(segment
		(start 159.4993 -75.919838)
		(end 161.79038 -75.919838)
		(width 0.12954)
		(layer "F.Cu")
		(net "SMB_S3M_CPU0_3V3AUX_SDA_R")
	)
	(via
		(at 159.4993 -75.919838)
		(size 0.508)
		(drill 0.254)
		(layers "F.Cu" "B.Cu")
		(net "SMB_S3M_CPU0_3V3AUX_SDA_R")
	)
	(segment
		(start 391.08888 -149.824948)
		(end 391.08888 -149.208998)
		(width 0.12954)
		(layer "F.Cu")
		(net "SMB_S3M_CPU0_3V3AUX_SDA")
	)
	(segment
		(start 162.74288 -75.767438)
		(end 163.5252 -75.767438)
		(width 0.12954)
		(layer "F.Cu")
		(net "SMB_S3M_CPU0_3V3AUX_SDA")
	)
	(segment
		(start 392.10488 -149.916896)
		(end 392.10488 -149.208998)
		(width 0.12954)
		(layer "F.Cu")
		(net "SMB_S3M_CPU0_3V3AUX_SDA")
	)
	(segment
		(start 391.558272 -150.88108)
		(end 391.558272 -150.463504)
		(width 0.12954)
		(layer "F.Cu")
		(net "SMB_S3M_CPU0_3V3AUX_SDA")
	)
	(segment
		(start 391.08888 -149.208998)
		(end 392.10488 -149.208998)
		(width 0.12954)
		(layer "F.Cu")
		(net "SMB_S3M_CPU0_3V3AUX_SDA")
	)
	(segment
		(start 392.681206 -152.004014)
		(end 391.558272 -150.88108)
		(width 0.12954)
		(layer "F.Cu")
		(net "SMB_S3M_CPU0_3V3AUX_SDA")
	)
	(segment
		(start 392.681206 -152.714452)
		(end 392.681206 -152.004014)
		(width 0.12954)
		(layer "F.Cu")
		(net "SMB_S3M_CPU0_3V3AUX_SDA")
	)
	(segment
		(start 391.558272 -150.463504)
		(end 392.10488 -149.916896)
		(width 0.12954)
		(layer "F.Cu")
		(net "SMB_S3M_CPU0_3V3AUX_SDA")
	)
	(via
		(at 391.08888 -149.824948)
		(size 0.508)
		(drill 0.254)
		(layers "F.Cu" "B.Cu")
		(net "SMB_S3M_CPU0_3V3AUX_SDA")
	)
	(via
		(at 163.5252 -75.767438)
		(size 0.508)
		(drill 0.254)
		(layers "F.Cu" "B.Cu")
		(net "SMB_S3M_CPU0_3V3AUX_SDA")
	)
	(via
		(at 391.558272 -150.88108)
		(size 0.762)
		(drill 0.381)
		(layers "F.Cu" "B.Cu")
		(net "SMB_S3M_CPU0_3V3AUX_SDA")
	)
	(segment
		(start 344.1954 -64.308228)
		(end 346.63634 -61.867288)
		(width 0.127)
		(layer "In6.Cu")
		(net "SMB_S3M_CPU0_3V3AUX_SDA")
	)
	(segment
		(start 250.29414 -89.675716)
		(end 251.784358 -88.185498)
		(width 0.127)
		(layer "In6.Cu")
		(net "SMB_S3M_CPU0_3V3AUX_SDA")
	)
	(segment
		(start 337.314032 -72.405748)
		(end 341.149432 -68.570348)
		(width 0.127)
		(layer "In6.Cu")
		(net "SMB_S3M_CPU0_3V3AUX_SDA")
	)
	(segment
		(start 241.390424 -91.702128)
		(end 243.079524 -90.013028)
		(width 0.127)
		(layer "In6.Cu")
		(net "SMB_S3M_CPU0_3V3AUX_SDA")
	)
	(segment
		(start 371.997986 -99.266248)
		(end 380.49962 -99.266248)
		(width 0.127)
		(layer "In6.Cu")
		(net "SMB_S3M_CPU0_3V3AUX_SDA")
	)
	(segment
		(start 355.153722 -60.29833)
		(end 355.153722 -67.129914)
		(width 0.127)
		(layer "In6.Cu")
		(net "SMB_S3M_CPU0_3V3AUX_SDA")
	)
	(segment
		(start 380.49962 -99.266248)
		(end 391.62482 -110.391448)
		(width 0.127)
		(layer "In6.Cu")
		(net "SMB_S3M_CPU0_3V3AUX_SDA")
	)
	(segment
		(start 333.12354 -75.946508)
		(end 336.6643 -72.405748)
		(width 0.127)
		(layer "In6.Cu")
		(net "SMB_S3M_CPU0_3V3AUX_SDA")
	)
	(segment
		(start 344.1954 -67.909948)
		(end 344.1954 -64.308228)
		(width 0.127)
		(layer "In6.Cu")
		(net "SMB_S3M_CPU0_3V3AUX_SDA")
	)
	(segment
		(start 395.51356 -149.36724)
		(end 394.512292 -150.368508)
		(width 0.127)
		(layer "In6.Cu")
		(net "SMB_S3M_CPU0_3V3AUX_SDA")
	)
	(segment
		(start 351.24644 -58.113168)
		(end 352.96856 -58.113168)
		(width 0.127)
		(layer "In6.Cu")
		(net "SMB_S3M_CPU0_3V3AUX_SDA")
	)
	(segment
		(start 391.63244 -150.368508)
		(end 391.08888 -149.824948)
		(width 0.127)
		(layer "In6.Cu")
		(net "SMB_S3M_CPU0_3V3AUX_SDA")
	)
	(segment
		(start 366.38992 -93.658182)
		(end 371.997986 -99.266248)
		(width 0.127)
		(layer "In6.Cu")
		(net "SMB_S3M_CPU0_3V3AUX_SDA")
	)
	(segment
		(start 249.479562 -90.013028)
		(end 250.29414 -89.675716)
		(width 0.127)
		(layer "In6.Cu")
		(net "SMB_S3M_CPU0_3V3AUX_SDA")
	)
	(segment
		(start 329.43546 -81.918048)
		(end 333.12354 -78.229968)
		(width 0.127)
		(layer "In6.Cu")
		(net "SMB_S3M_CPU0_3V3AUX_SDA")
	)
	(segment
		(start 366.38992 -89.672668)
		(end 366.38992 -93.658182)
		(width 0.127)
		(layer "In6.Cu")
		(net "SMB_S3M_CPU0_3V3AUX_SDA")
	)
	(segment
		(start 302.377856 -81.918048)
		(end 329.43546 -81.918048)
		(width 0.127)
		(layer "In6.Cu")
		(net "SMB_S3M_CPU0_3V3AUX_SDA")
	)
	(segment
		(start 346.63634 -56.655208)
		(end 347.25356 -56.037988)
		(width 0.127)
		(layer "In6.Cu")
		(net "SMB_S3M_CPU0_3V3AUX_SDA")
	)
	(segment
		(start 391.62482 -143.146018)
		(end 395.51356 -147.034758)
		(width 0.127)
		(layer "In6.Cu")
		(net "SMB_S3M_CPU0_3V3AUX_SDA")
	)
	(segment
		(start 211.346288 -91.702128)
		(end 241.390424 -91.702128)
		(width 0.127)
		(layer "In6.Cu")
		(net "SMB_S3M_CPU0_3V3AUX_SDA")
	)
	(segment
		(start 347.25356 -56.037988)
		(end 349.17126 -56.037988)
		(width 0.127)
		(layer "In6.Cu")
		(net "SMB_S3M_CPU0_3V3AUX_SDA")
	)
	(segment
		(start 336.6643 -72.405748)
		(end 337.314032 -72.405748)
		(width 0.127)
		(layer "In6.Cu")
		(net "SMB_S3M_CPU0_3V3AUX_SDA")
	)
	(segment
		(start 163.81095 -76.053188)
		(end 165.93312 -76.053188)
		(width 0.127)
		(layer "In6.Cu")
		(net "SMB_S3M_CPU0_3V3AUX_SDA")
	)
	(segment
		(start 394.512292 -150.368508)
		(end 391.63244 -150.368508)
		(width 0.127)
		(layer "In6.Cu")
		(net "SMB_S3M_CPU0_3V3AUX_SDA")
	)
	(segment
		(start 361.54106 -73.517252)
		(end 361.54106 -84.823808)
		(width 0.127)
		(layer "In6.Cu")
		(net "SMB_S3M_CPU0_3V3AUX_SDA")
	)
	(segment
		(start 174.752254 -84.872322)
		(end 191.89573 -84.872322)
		(width 0.127)
		(layer "In6.Cu")
		(net "SMB_S3M_CPU0_3V3AUX_SDA")
	)
	(segment
		(start 355.153722 -67.129914)
		(end 361.54106 -73.517252)
		(width 0.127)
		(layer "In6.Cu")
		(net "SMB_S3M_CPU0_3V3AUX_SDA")
	)
	(segment
		(start 346.63634 -61.867288)
		(end 346.63634 -56.655208)
		(width 0.127)
		(layer "In6.Cu")
		(net "SMB_S3M_CPU0_3V3AUX_SDA")
	)
	(segment
		(start 192.408556 -85.385148)
		(end 205.029308 -85.385148)
		(width 0.127)
		(layer "In6.Cu")
		(net "SMB_S3M_CPU0_3V3AUX_SDA")
	)
	(segment
		(start 260.247638 -88.185498)
		(end 261.386828 -87.046308)
		(width 0.127)
		(layer "In6.Cu")
		(net "SMB_S3M_CPU0_3V3AUX_SDA")
	)
	(segment
		(start 243.079524 -90.013028)
		(end 249.479562 -90.013028)
		(width 0.127)
		(layer "In6.Cu")
		(net "SMB_S3M_CPU0_3V3AUX_SDA")
	)
	(segment
		(start 205.029308 -85.385148)
		(end 211.346288 -91.702128)
		(width 0.127)
		(layer "In6.Cu")
		(net "SMB_S3M_CPU0_3V3AUX_SDA")
	)
	(segment
		(start 352.96856 -58.113168)
		(end 355.153722 -60.29833)
		(width 0.127)
		(layer "In6.Cu")
		(net "SMB_S3M_CPU0_3V3AUX_SDA")
	)
	(segment
		(start 361.54106 -84.823808)
		(end 366.38992 -89.672668)
		(width 0.127)
		(layer "In6.Cu")
		(net "SMB_S3M_CPU0_3V3AUX_SDA")
	)
	(segment
		(start 261.386828 -87.046308)
		(end 297.249596 -87.046308)
		(width 0.127)
		(layer "In6.Cu")
		(net "SMB_S3M_CPU0_3V3AUX_SDA")
	)
	(segment
		(start 341.149432 -68.570348)
		(end 343.535 -68.570348)
		(width 0.127)
		(layer "In6.Cu")
		(net "SMB_S3M_CPU0_3V3AUX_SDA")
	)
	(segment
		(start 333.12354 -78.229968)
		(end 333.12354 -75.946508)
		(width 0.127)
		(layer "In6.Cu")
		(net "SMB_S3M_CPU0_3V3AUX_SDA")
	)
	(segment
		(start 191.89573 -84.872322)
		(end 192.408556 -85.385148)
		(width 0.127)
		(layer "In6.Cu")
		(net "SMB_S3M_CPU0_3V3AUX_SDA")
	)
	(segment
		(start 349.17126 -56.037988)
		(end 351.24644 -58.113168)
		(width 0.127)
		(layer "In6.Cu")
		(net "SMB_S3M_CPU0_3V3AUX_SDA")
	)
	(segment
		(start 251.784358 -88.185498)
		(end 260.247638 -88.185498)
		(width 0.127)
		(layer "In6.Cu")
		(net "SMB_S3M_CPU0_3V3AUX_SDA")
	)
	(segment
		(start 343.535 -68.570348)
		(end 344.1954 -67.909948)
		(width 0.127)
		(layer "In6.Cu")
		(net "SMB_S3M_CPU0_3V3AUX_SDA")
	)
	(segment
		(start 163.5252 -75.767438)
		(end 163.81095 -76.053188)
		(width 0.127)
		(layer "In6.Cu")
		(net "SMB_S3M_CPU0_3V3AUX_SDA")
	)
	(segment
		(start 165.93312 -76.053188)
		(end 174.752254 -84.872322)
		(width 0.127)
		(layer "In6.Cu")
		(net "SMB_S3M_CPU0_3V3AUX_SDA")
	)
	(segment
		(start 391.62482 -110.391448)
		(end 391.62482 -143.146018)
		(width 0.127)
		(layer "In6.Cu")
		(net "SMB_S3M_CPU0_3V3AUX_SDA")
	)
	(segment
		(start 297.249596 -87.046308)
		(end 302.377856 -81.918048)
		(width 0.127)
		(layer "In6.Cu")
		(net "SMB_S3M_CPU0_3V3AUX_SDA")
	)
	(segment
		(start 395.51356 -147.034758)
		(end 395.51356 -149.36724)
		(width 0.127)
		(layer "In6.Cu")
		(net "SMB_S3M_CPU0_3V3AUX_SDA")
	)
	(segment
		(start 160.8201 -76.570078)
		(end 161.74212 -76.570078)
		(width 0.12954)
		(layer "F.Cu")
		(net "SMB_S3M_CPU0_3V3AUX_SCL_R")
	)
	(segment
		(start 161.74212 -76.570078)
		(end 161.94278 -76.770738)
		(width 0.12954)
		(layer "F.Cu")
		(net "SMB_S3M_CPU0_3V3AUX_SCL_R")
	)
	(segment
		(start 157.985968 -76.570078)
		(end 160.8201 -76.570078)
		(width 0.12954)
		(layer "F.Cu")
		(net "SMB_S3M_CPU0_3V3AUX_SCL_R")
	)
	(via
		(at 160.8201 -76.570078)
		(size 0.508)
		(drill 0.254)
		(layers "F.Cu" "B.Cu")
		(net "SMB_S3M_CPU0_3V3AUX_SCL_R")
	)
	(segment
		(start 393.430252 -150.833328)
		(end 393.37488 -150.777956)
		(width 0.12954)
		(layer "F.Cu")
		(net "SMB_S3M_CPU0_3V3AUX_SCL")
	)
	(segment
		(start 394.39088 -149.208998)
		(end 393.37488 -149.208998)
		(width 0.12954)
		(layer "F.Cu")
		(net "SMB_S3M_CPU0_3V3AUX_SCL")
	)
	(segment
		(start 393.37488 -150.777956)
		(end 393.37488 -149.208998)
		(width 0.12954)
		(layer "F.Cu")
		(net "SMB_S3M_CPU0_3V3AUX_SCL")
	)
	(segment
		(start 394.39088 -149.824948)
		(end 394.39088 -149.208998)
		(width 0.12954)
		(layer "F.Cu")
		(net "SMB_S3M_CPU0_3V3AUX_SCL")
	)
	(segment
		(start 393.951206 -152.714452)
		(end 393.951206 -151.354282)
		(width 0.12954)
		(layer "F.Cu")
		(net "SMB_S3M_CPU0_3V3AUX_SCL")
	)
	(segment
		(start 393.951206 -151.354282)
		(end 393.430252 -150.833328)
		(width 0.12954)
		(layer "F.Cu")
		(net "SMB_S3M_CPU0_3V3AUX_SCL")
	)
	(segment
		(start 162.74288 -76.770738)
		(end 163.5252 -76.770738)
		(width 0.12954)
		(layer "F.Cu")
		(net "SMB_S3M_CPU0_3V3AUX_SCL")
	)
	(via
		(at 393.430252 -150.833328)
		(size 0.762)
		(drill 0.381)
		(layers "F.Cu" "B.Cu")
		(net "SMB_S3M_CPU0_3V3AUX_SCL")
	)
	(via
		(at 394.39088 -149.824948)
		(size 0.508)
		(drill 0.254)
		(layers "F.Cu" "B.Cu")
		(net "SMB_S3M_CPU0_3V3AUX_SCL")
	)
	(via
		(at 163.5252 -76.770738)
		(size 0.508)
		(drill 0.254)
		(layers "F.Cu" "B.Cu")
		(net "SMB_S3M_CPU0_3V3AUX_SCL")
	)
	(segment
		(start 337.476592 -72.913748)
		(end 336.76717 -72.913748)
		(width 0.127)
		(layer "In6.Cu")
		(net "SMB_S3M_CPU0_3V3AUX_SCL")
	)
	(segment
		(start 260.532626 -88.746076)
		(end 251.8537 -88.746076)
		(width 0.127)
		(layer "In6.Cu")
		(net "SMB_S3M_CPU0_3V3AUX_SCL")
	)
	(segment
		(start 395.08176 -149.134068)
		(end 395.08176 -147.213828)
		(width 0.127)
		(layer "In6.Cu")
		(net "SMB_S3M_CPU0_3V3AUX_SCL")
	)
	(segment
		(start 360.13136 -78.848204)
		(end 360.25836 -78.721204)
		(width 0.127)
		(layer "In6.Cu")
		(net "SMB_S3M_CPU0_3V3AUX_SCL")
	)
	(segment
		(start 360.98226 -78.721204)
		(end 361.10926 -78.594204)
		(width 0.127)
		(layer "In6.Cu")
		(net "SMB_S3M_CPU0_3V3AUX_SCL")
	)
	(segment
		(start 250.532138 -90.067638)
		(end 249.621548 -90.444828)
		(width 0.127)
		(layer "In6.Cu")
		(net "SMB_S3M_CPU0_3V3AUX_SCL")
	)
	(segment
		(start 261.800594 -87.478108)
		(end 260.532626 -88.746076)
		(width 0.127)
		(layer "In6.Cu")
		(net "SMB_S3M_CPU0_3V3AUX_SCL")
	)
	(segment
		(start 336.76717 -72.913748)
		(end 333.55534 -76.125578)
		(width 0.127)
		(layer "In6.Cu")
		(net "SMB_S3M_CPU0_3V3AUX_SCL")
	)
	(segment
		(start 333.55534 -78.409038)
		(end 329.61453 -82.349848)
		(width 0.127)
		(layer "In6.Cu")
		(net "SMB_S3M_CPU0_3V3AUX_SCL")
	)
	(segment
		(start 395.08176 -147.213828)
		(end 391.19302 -143.325088)
		(width 0.127)
		(layer "In6.Cu")
		(net "SMB_S3M_CPU0_3V3AUX_SCL")
	)
	(segment
		(start 360.98226 -81.312004)
		(end 360.25836 -81.312004)
		(width 0.127)
		(layer "In6.Cu")
		(net "SMB_S3M_CPU0_3V3AUX_SCL")
	)
	(segment
		(start 361.10926 -78.594204)
		(end 361.10926 -77.984604)
		(width 0.127)
		(layer "In6.Cu")
		(net "SMB_S3M_CPU0_3V3AUX_SCL")
	)
	(segment
		(start 351.06737 -58.544968)
		(end 348.99219 -56.469788)
		(width 0.127)
		(layer "In6.Cu")
		(net "SMB_S3M_CPU0_3V3AUX_SCL")
	)
	(segment
		(start 344.681048 -64.43345)
		(end 344.681048 -68.2117)
		(width 0.127)
		(layer "In6.Cu")
		(net "SMB_S3M_CPU0_3V3AUX_SCL")
	)
	(segment
		(start 360.25836 -77.857604)
		(end 360.13136 -77.730604)
		(width 0.127)
		(layer "In6.Cu")
		(net "SMB_S3M_CPU0_3V3AUX_SCL")
	)
	(segment
		(start 333.55534 -76.125578)
		(end 333.55534 -78.409038)
		(width 0.127)
		(layer "In6.Cu")
		(net "SMB_S3M_CPU0_3V3AUX_SCL")
	)
	(segment
		(start 360.98226 -80.448404)
		(end 361.10926 -80.321404)
		(width 0.127)
		(layer "In6.Cu")
		(net "SMB_S3M_CPU0_3V3AUX_SCL")
	)
	(segment
		(start 204.716634 -85.816948)
		(end 192.229486 -85.816948)
		(width 0.127)
		(layer "In6.Cu")
		(net "SMB_S3M_CPU0_3V3AUX_SCL")
	)
	(segment
		(start 354.658676 -67.245738)
		(end 354.658676 -60.502546)
		(width 0.127)
		(layer "In6.Cu")
		(net "SMB_S3M_CPU0_3V3AUX_SCL")
	)
	(segment
		(start 213.33714 -93.024198)
		(end 211.219288 -93.024198)
		(width 0.127)
		(layer "In6.Cu")
		(net "SMB_S3M_CPU0_3V3AUX_SCL")
	)
	(segment
		(start 360.13136 -81.185004)
		(end 360.13136 -80.575404)
		(width 0.127)
		(layer "In6.Cu")
		(net "SMB_S3M_CPU0_3V3AUX_SCL")
	)
	(segment
		(start 360.98226 -79.584804)
		(end 360.25836 -79.584804)
		(width 0.127)
		(layer "In6.Cu")
		(net "SMB_S3M_CPU0_3V3AUX_SCL")
	)
	(segment
		(start 165.75405 -76.484988)
		(end 163.81095 -76.484988)
		(width 0.127)
		(layer "In6.Cu")
		(net "SMB_S3M_CPU0_3V3AUX_SCL")
	)
	(segment
		(start 380.32055 -99.698048)
		(end 371.798596 -99.698048)
		(width 0.127)
		(layer "In6.Cu")
		(net "SMB_S3M_CPU0_3V3AUX_SCL")
	)
	(segment
		(start 352.701098 -58.544968)
		(end 351.06737 -58.544968)
		(width 0.127)
		(layer "In6.Cu")
		(net "SMB_S3M_CPU0_3V3AUX_SCL")
	)
	(segment
		(start 251.8537 -88.746076)
		(end 250.532138 -90.067638)
		(width 0.127)
		(layer "In6.Cu")
		(net "SMB_S3M_CPU0_3V3AUX_SCL")
	)
	(segment
		(start 174.573184 -85.304122)
		(end 165.75405 -76.484988)
		(width 0.127)
		(layer "In6.Cu")
		(net "SMB_S3M_CPU0_3V3AUX_SCL")
	)
	(segment
		(start 360.13136 -79.457804)
		(end 360.13136 -78.848204)
		(width 0.127)
		(layer "In6.Cu")
		(net "SMB_S3M_CPU0_3V3AUX_SCL")
	)
	(segment
		(start 347.06814 -62.046358)
		(end 344.681048 -64.43345)
		(width 0.127)
		(layer "In6.Cu")
		(net "SMB_S3M_CPU0_3V3AUX_SCL")
	)
	(segment
		(start 360.25836 -79.584804)
		(end 360.13136 -79.457804)
		(width 0.127)
		(layer "In6.Cu")
		(net "SMB_S3M_CPU0_3V3AUX_SCL")
	)
	(segment
		(start 344.681048 -68.2117)
		(end 343.8144 -69.078348)
		(width 0.127)
		(layer "In6.Cu")
		(net "SMB_S3M_CPU0_3V3AUX_SCL")
	)
	(segment
		(start 361.10926 -76.867004)
		(end 361.10926 -73.696322)
		(width 0.127)
		(layer "In6.Cu")
		(net "SMB_S3M_CPU0_3V3AUX_SCL")
	)
	(segment
		(start 360.98226 -77.857604)
		(end 360.25836 -77.857604)
		(width 0.127)
		(layer "In6.Cu")
		(net "SMB_S3M_CPU0_3V3AUX_SCL")
	)
	(segment
		(start 361.10926 -81.439004)
		(end 360.98226 -81.312004)
		(width 0.127)
		(layer "In6.Cu")
		(net "SMB_S3M_CPU0_3V3AUX_SCL")
	)
	(segment
		(start 360.13136 -80.575404)
		(end 360.25836 -80.448404)
		(width 0.127)
		(layer "In6.Cu")
		(net "SMB_S3M_CPU0_3V3AUX_SCL")
	)
	(segment
		(start 360.25836 -76.994004)
		(end 360.98226 -76.994004)
		(width 0.127)
		(layer "In6.Cu")
		(net "SMB_S3M_CPU0_3V3AUX_SCL")
	)
	(segment
		(start 249.621548 -90.444828)
		(end 243.258594 -90.444828)
		(width 0.127)
		(layer "In6.Cu")
		(net "SMB_S3M_CPU0_3V3AUX_SCL")
	)
	(segment
		(start 391.19302 -110.570518)
		(end 380.32055 -99.698048)
		(width 0.127)
		(layer "In6.Cu")
		(net "SMB_S3M_CPU0_3V3AUX_SCL")
	)
	(segment
		(start 214.22741 -92.133928)
		(end 213.33714 -93.024198)
		(width 0.127)
		(layer "In6.Cu")
		(net "SMB_S3M_CPU0_3V3AUX_SCL")
	)
	(segment
		(start 360.25836 -81.312004)
		(end 360.13136 -81.185004)
		(width 0.127)
		(layer "In6.Cu")
		(net "SMB_S3M_CPU0_3V3AUX_SCL")
	)
	(segment
		(start 360.25836 -78.721204)
		(end 360.98226 -78.721204)
		(width 0.127)
		(layer "In6.Cu")
		(net "SMB_S3M_CPU0_3V3AUX_SCL")
	)
	(segment
		(start 361.10926 -77.984604)
		(end 360.98226 -77.857604)
		(width 0.127)
		(layer "In6.Cu")
		(net "SMB_S3M_CPU0_3V3AUX_SCL")
	)
	(segment
		(start 192.229486 -85.816948)
		(end 191.71666 -85.304122)
		(width 0.127)
		(layer "In6.Cu")
		(net "SMB_S3M_CPU0_3V3AUX_SCL")
	)
	(segment
		(start 365.68888 -93.588332)
		(end 365.68888 -89.582498)
		(width 0.127)
		(layer "In6.Cu")
		(net "SMB_S3M_CPU0_3V3AUX_SCL")
	)
	(segment
		(start 297.428666 -87.478108)
		(end 261.800594 -87.478108)
		(width 0.127)
		(layer "In6.Cu")
		(net "SMB_S3M_CPU0_3V3AUX_SCL")
	)
	(segment
		(start 243.258594 -90.444828)
		(end 241.569494 -92.133928)
		(width 0.127)
		(layer "In6.Cu")
		(net "SMB_S3M_CPU0_3V3AUX_SCL")
	)
	(segment
		(start 360.98226 -76.994004)
		(end 361.10926 -76.867004)
		(width 0.127)
		(layer "In6.Cu")
		(net "SMB_S3M_CPU0_3V3AUX_SCL")
	)
	(segment
		(start 391.19302 -143.325088)
		(end 391.19302 -110.570518)
		(width 0.127)
		(layer "In6.Cu")
		(net "SMB_S3M_CPU0_3V3AUX_SCL")
	)
	(segment
		(start 302.556926 -82.349848)
		(end 297.428666 -87.478108)
		(width 0.127)
		(layer "In6.Cu")
		(net "SMB_S3M_CPU0_3V3AUX_SCL")
	)
	(segment
		(start 209.38744 -91.19235)
		(end 209.38744 -90.487754)
		(width 0.127)
		(layer "In6.Cu")
		(net "SMB_S3M_CPU0_3V3AUX_SCL")
	)
	(segment
		(start 347.43263 -56.469788)
		(end 347.06814 -56.834278)
		(width 0.127)
		(layer "In6.Cu")
		(net "SMB_S3M_CPU0_3V3AUX_SCL")
	)
	(segment
		(start 209.38744 -90.487754)
		(end 204.716634 -85.816948)
		(width 0.127)
		(layer "In6.Cu")
		(net "SMB_S3M_CPU0_3V3AUX_SCL")
	)
	(segment
		(start 329.61453 -82.349848)
		(end 302.556926 -82.349848)
		(width 0.127)
		(layer "In6.Cu")
		(net "SMB_S3M_CPU0_3V3AUX_SCL")
	)
	(segment
		(start 360.13136 -77.121004)
		(end 360.25836 -76.994004)
		(width 0.127)
		(layer "In6.Cu")
		(net "SMB_S3M_CPU0_3V3AUX_SCL")
	)
	(segment
		(start 348.99219 -56.469788)
		(end 347.43263 -56.469788)
		(width 0.127)
		(layer "In6.Cu")
		(net "SMB_S3M_CPU0_3V3AUX_SCL")
	)
	(segment
		(start 361.10926 -85.002878)
		(end 361.10926 -81.439004)
		(width 0.127)
		(layer "In6.Cu")
		(net "SMB_S3M_CPU0_3V3AUX_SCL")
	)
	(segment
		(start 341.311992 -69.078348)
		(end 337.476592 -72.913748)
		(width 0.127)
		(layer "In6.Cu")
		(net "SMB_S3M_CPU0_3V3AUX_SCL")
	)
	(segment
		(start 394.39088 -149.824948)
		(end 395.08176 -149.134068)
		(width 0.127)
		(layer "In6.Cu")
		(net "SMB_S3M_CPU0_3V3AUX_SCL")
	)
	(segment
		(start 163.81095 -76.484988)
		(end 163.5252 -76.770738)
		(width 0.127)
		(layer "In6.Cu")
		(net "SMB_S3M_CPU0_3V3AUX_SCL")
	)
	(segment
		(start 361.10926 -79.711804)
		(end 360.98226 -79.584804)
		(width 0.127)
		(layer "In6.Cu")
		(net "SMB_S3M_CPU0_3V3AUX_SCL")
	)
	(segment
		(start 360.13136 -77.730604)
		(end 360.13136 -77.121004)
		(width 0.127)
		(layer "In6.Cu")
		(net "SMB_S3M_CPU0_3V3AUX_SCL")
	)
	(segment
		(start 365.68888 -89.582498)
		(end 361.10926 -85.002878)
		(width 0.127)
		(layer "In6.Cu")
		(net "SMB_S3M_CPU0_3V3AUX_SCL")
	)
	(segment
		(start 211.219288 -93.024198)
		(end 209.38744 -91.19235)
		(width 0.127)
		(layer "In6.Cu")
		(net "SMB_S3M_CPU0_3V3AUX_SCL")
	)
	(segment
		(start 343.8144 -69.078348)
		(end 341.311992 -69.078348)
		(width 0.127)
		(layer "In6.Cu")
		(net "SMB_S3M_CPU0_3V3AUX_SCL")
	)
	(segment
		(start 241.569494 -92.133928)
		(end 214.22741 -92.133928)
		(width 0.127)
		(layer "In6.Cu")
		(net "SMB_S3M_CPU0_3V3AUX_SCL")
	)
	(segment
		(start 347.06814 -56.834278)
		(end 347.06814 -62.046358)
		(width 0.127)
		(layer "In6.Cu")
		(net "SMB_S3M_CPU0_3V3AUX_SCL")
	)
	(segment
		(start 354.658676 -60.502546)
		(end 352.701098 -58.544968)
		(width 0.127)
		(layer "In6.Cu")
		(net "SMB_S3M_CPU0_3V3AUX_SCL")
	)
	(segment
		(start 371.798596 -99.698048)
		(end 365.68888 -93.588332)
		(width 0.127)
		(layer "In6.Cu")
		(net "SMB_S3M_CPU0_3V3AUX_SCL")
	)
	(segment
		(start 361.10926 -73.696322)
		(end 354.658676 -67.245738)
		(width 0.127)
		(layer "In6.Cu")
		(net "SMB_S3M_CPU0_3V3AUX_SCL")
	)
	(segment
		(start 361.10926 -80.321404)
		(end 361.10926 -79.711804)
		(width 0.127)
		(layer "In6.Cu")
		(net "SMB_S3M_CPU0_3V3AUX_SCL")
	)
	(segment
		(start 360.25836 -80.448404)
		(end 360.98226 -80.448404)
		(width 0.127)
		(layer "In6.Cu")
		(net "SMB_S3M_CPU0_3V3AUX_SCL")
	)
	(segment
		(start 191.71666 -85.304122)
		(end 174.573184 -85.304122)
		(width 0.127)
		(layer "In6.Cu")
		(net "SMB_S3M_CPU0_3V3AUX_SCL")
	)
	(via
		(at 13.177012 -186.416188)
		(size 0.6604)
		(drill 0.3302)
		(layers "F.Cu" "B.Cu")
		(net "SMB_PEHPCPU1_LVC3_SDA_R0")
	)
	(segment
		(start 8.935212 -186.416188)
		(end 7.0866 -188.2648)
		(width 0.12954)
		(layer "B.Cu")
		(net "SMB_PEHPCPU1_LVC3_SDA_R0")
	)
	(segment
		(start 13.177012 -186.416188)
		(end 8.935212 -186.416188)
		(width 0.12954)
		(layer "B.Cu")
		(net "SMB_PEHPCPU1_LVC3_SDA_R0")
	)
	(segment
		(start 7.385304 -192.449704)
		(end 9.581134 -192.449704)
		(width 0.12954)
		(layer "B.Cu")
		(net "SMB_PEHPCPU1_LVC3_SDA_R0")
	)
	(segment
		(start 13.177012 -186.416188)
		(end 13.5382 -186.055)
		(width 0.12954)
		(layer "B.Cu")
		(net "SMB_PEHPCPU1_LVC3_SDA_R0")
	)
	(segment
		(start 13.5382 -183.954674)
		(end 13.066522 -183.482996)
		(width 0.12954)
		(layer "B.Cu")
		(net "SMB_PEHPCPU1_LVC3_SDA_R0")
	)
	(segment
		(start 13.5382 -186.055)
		(end 13.5382 -183.954674)
		(width 0.12954)
		(layer "B.Cu")
		(net "SMB_PEHPCPU1_LVC3_SDA_R0")
	)
	(segment
		(start 7.0866 -188.2648)
		(end 7.0866 -192.151)
		(width 0.12954)
		(layer "B.Cu")
		(net "SMB_PEHPCPU1_LVC3_SDA_R0")
	)
	(segment
		(start 7.0866 -192.151)
		(end 7.385304 -192.449704)
		(width 0.12954)
		(layer "B.Cu")
		(net "SMB_PEHPCPU1_LVC3_SDA_R0")
	)
	(segment
		(start 148.379942 -126.599188)
		(end 148.072602 -126.291848)
		(width 0.12954)
		(layer "F.Cu")
		(net "SMB_PEHPCPU1_LVC3_SDA")
	)
	(segment
		(start 148.072602 -126.291848)
		(end 147.48383 -126.291848)
		(width 0.12954)
		(layer "F.Cu")
		(net "SMB_PEHPCPU1_LVC3_SDA")
	)
	(via
		(at 148.379942 -126.599188)
		(size 0.508)
		(drill 0.254)
		(layers "F.Cu" "B.Cu")
		(net "SMB_PEHPCPU1_LVC3_SDA")
	)
	(via
		(at 9.70788 -150.586948)
		(size 0.508)
		(drill 0.254)
		(layers "F.Cu" "B.Cu")
		(net "SMB_PEHPCPU1_LVC3_SDA")
	)
	(segment
		(start 6.597396 -183.482996)
		(end 4.57962 -181.46522)
		(width 0.12954)
		(layer "B.Cu")
		(net "SMB_PEHPCPU1_LVC3_SDA")
	)
	(segment
		(start 4.57962 -181.46522)
		(end 4.57962 -153.454608)
		(width 0.12954)
		(layer "B.Cu")
		(net "SMB_PEHPCPU1_LVC3_SDA")
	)
	(segment
		(start 10.158222 -183.482996)
		(end 6.597396 -183.482996)
		(width 0.12954)
		(layer "B.Cu")
		(net "SMB_PEHPCPU1_LVC3_SDA")
	)
	(segment
		(start 12.065 -182.753)
		(end 10.4394 -182.753)
		(width 0.12954)
		(layer "B.Cu")
		(net "SMB_PEHPCPU1_LVC3_SDA")
	)
	(segment
		(start 10.158222 -183.034178)
		(end 10.158222 -183.482996)
		(width 0.12954)
		(layer "B.Cu")
		(net "SMB_PEHPCPU1_LVC3_SDA")
	)
	(segment
		(start 12.266422 -183.482996)
		(end 12.266422 -182.954422)
		(width 0.12954)
		(layer "B.Cu")
		(net "SMB_PEHPCPU1_LVC3_SDA")
	)
	(segment
		(start 10.4394 -182.753)
		(end 10.158222 -183.034178)
		(width 0.12954)
		(layer "B.Cu")
		(net "SMB_PEHPCPU1_LVC3_SDA")
	)
	(segment
		(start 7.44728 -150.586948)
		(end 9.70788 -150.586948)
		(width 0.12954)
		(layer "B.Cu")
		(net "SMB_PEHPCPU1_LVC3_SDA")
	)
	(segment
		(start 12.266422 -182.954422)
		(end 12.065 -182.753)
		(width 0.12954)
		(layer "B.Cu")
		(net "SMB_PEHPCPU1_LVC3_SDA")
	)
	(segment
		(start 4.57962 -153.454608)
		(end 7.44728 -150.586948)
		(width 0.12954)
		(layer "B.Cu")
		(net "SMB_PEHPCPU1_LVC3_SDA")
	)
	(segment
		(start 106.56062 -124.691648)
		(end 97.78238 -124.691648)
		(width 0.127)
		(layer "In6.Cu")
		(net "SMB_PEHPCPU1_LVC3_SDA")
	)
	(segment
		(start 137.100056 -125.707648)
		(end 133.378956 -121.986548)
		(width 0.127)
		(layer "In6.Cu")
		(net "SMB_PEHPCPU1_LVC3_SDA")
	)
	(segment
		(start 24.39035 -120.208548)
		(end 15.09268 -129.506218)
		(width 0.127)
		(layer "In6.Cu")
		(net "SMB_PEHPCPU1_LVC3_SDA")
	)
	(segment
		(start 95.89008 -126.583948)
		(end 51.13401 -126.583948)
		(width 0.127)
		(layer "In6.Cu")
		(net "SMB_PEHPCPU1_LVC3_SDA")
	)
	(segment
		(start 12.60475 -150.586948)
		(end 9.70788 -150.586948)
		(width 0.127)
		(layer "In6.Cu")
		(net "SMB_PEHPCPU1_LVC3_SDA")
	)
	(segment
		(start 147.488402 -125.707648)
		(end 137.100056 -125.707648)
		(width 0.127)
		(layer "In6.Cu")
		(net "SMB_PEHPCPU1_LVC3_SDA")
	)
	(segment
		(start 15.09268 -148.099018)
		(end 12.60475 -150.586948)
		(width 0.127)
		(layer "In6.Cu")
		(net "SMB_PEHPCPU1_LVC3_SDA")
	)
	(segment
		(start 15.09268 -129.506218)
		(end 15.09268 -148.099018)
		(width 0.127)
		(layer "In6.Cu")
		(net "SMB_PEHPCPU1_LVC3_SDA")
	)
	(segment
		(start 43.36161 -118.811548)
		(end 31.19755 -118.811548)
		(width 0.127)
		(layer "In6.Cu")
		(net "SMB_PEHPCPU1_LVC3_SDA")
	)
	(segment
		(start 133.378956 -121.986548)
		(end 130.704336 -121.986548)
		(width 0.127)
		(layer "In6.Cu")
		(net "SMB_PEHPCPU1_LVC3_SDA")
	)
	(segment
		(start 130.704336 -121.986548)
		(end 127.300736 -118.582948)
		(width 0.127)
		(layer "In6.Cu")
		(net "SMB_PEHPCPU1_LVC3_SDA")
	)
	(segment
		(start 148.379942 -126.599188)
		(end 147.488402 -125.707648)
		(width 0.127)
		(layer "In6.Cu")
		(net "SMB_PEHPCPU1_LVC3_SDA")
	)
	(segment
		(start 97.78238 -124.691648)
		(end 95.89008 -126.583948)
		(width 0.127)
		(layer "In6.Cu")
		(net "SMB_PEHPCPU1_LVC3_SDA")
	)
	(segment
		(start 127.300736 -118.582948)
		(end 112.66932 -118.582948)
		(width 0.127)
		(layer "In6.Cu")
		(net "SMB_PEHPCPU1_LVC3_SDA")
	)
	(segment
		(start 112.66932 -118.582948)
		(end 106.56062 -124.691648)
		(width 0.127)
		(layer "In6.Cu")
		(net "SMB_PEHPCPU1_LVC3_SDA")
	)
	(segment
		(start 29.80055 -120.208548)
		(end 24.39035 -120.208548)
		(width 0.127)
		(layer "In6.Cu")
		(net "SMB_PEHPCPU1_LVC3_SDA")
	)
	(segment
		(start 51.13401 -126.583948)
		(end 43.36161 -118.811548)
		(width 0.127)
		(layer "In6.Cu")
		(net "SMB_PEHPCPU1_LVC3_SDA")
	)
	(segment
		(start 31.19755 -118.811548)
		(end 29.80055 -120.208548)
		(width 0.127)
		(layer "In6.Cu")
		(net "SMB_PEHPCPU1_LVC3_SDA")
	)
	(via
		(at 9.906 -185.8264)
		(size 0.6604)
		(drill 0.3302)
		(layers "F.Cu" "B.Cu")
		(net "SMB_PEHPCPU1_LVC3_SCL_R0")
	)
	(segment
		(start 8.763 -185.8264)
		(end 6.5278 -188.0616)
		(width 0.12954)
		(layer "B.Cu")
		(net "SMB_PEHPCPU1_LVC3_SCL_R0")
	)
	(segment
		(start 9.906 -185.8264)
		(end 8.763 -185.8264)
		(width 0.12954)
		(layer "B.Cu")
		(net "SMB_PEHPCPU1_LVC3_SCL_R0")
	)
	(segment
		(start 9.906 -185.8264)
		(end 12.370054 -185.8264)
		(width 0.12954)
		(layer "B.Cu")
		(net "SMB_PEHPCPU1_LVC3_SCL_R0")
	)
	(segment
		(start 13.066522 -185.129932)
		(end 13.066522 -184.625996)
		(width 0.12954)
		(layer "B.Cu")
		(net "SMB_PEHPCPU1_LVC3_SCL_R0")
	)
	(segment
		(start 7.019544 -193.099944)
		(end 9.581134 -193.099944)
		(width 0.12954)
		(layer "B.Cu")
		(net "SMB_PEHPCPU1_LVC3_SCL_R0")
	)
	(segment
		(start 12.370054 -185.8264)
		(end 13.066522 -185.129932)
		(width 0.12954)
		(layer "B.Cu")
		(net "SMB_PEHPCPU1_LVC3_SCL_R0")
	)
	(segment
		(start 6.5278 -192.6082)
		(end 7.019544 -193.099944)
		(width 0.12954)
		(layer "B.Cu")
		(net "SMB_PEHPCPU1_LVC3_SCL_R0")
	)
	(segment
		(start 6.5278 -188.0616)
		(end 6.5278 -192.6082)
		(width 0.12954)
		(layer "B.Cu")
		(net "SMB_PEHPCPU1_LVC3_SCL_R0")
	)
	(segment
		(start 147.48383 -125.275848)
		(end 148.13788 -125.275848)
		(width 0.12954)
		(layer "F.Cu")
		(net "SMB_PEHPCPU1_LVC3_SCL")
	)
	(via
		(at 148.13788 -125.275848)
		(size 0.508)
		(drill 0.254)
		(layers "F.Cu" "B.Cu")
		(net "SMB_PEHPCPU1_LVC3_SCL")
	)
	(via
		(at 9.70788 -149.824948)
		(size 0.508)
		(drill 0.254)
		(layers "F.Cu" "B.Cu")
		(net "SMB_PEHPCPU1_LVC3_SCL")
	)
	(segment
		(start 12.266422 -184.625996)
		(end 12.266422 -184.989978)
		(width 0.12954)
		(layer "B.Cu")
		(net "SMB_PEHPCPU1_LVC3_SCL")
	)
	(segment
		(start 4.1148 -153.106628)
		(end 7.39648 -149.824948)
		(width 0.12954)
		(layer "B.Cu")
		(net "SMB_PEHPCPU1_LVC3_SCL")
	)
	(segment
		(start 10.3632 -185.293)
		(end 10.158222 -185.088022)
		(width 0.12954)
		(layer "B.Cu")
		(net "SMB_PEHPCPU1_LVC3_SCL")
	)
	(segment
		(start 4.1148 -181.658006)
		(end 4.1148 -153.106628)
		(width 0.12954)
		(layer "B.Cu")
		(net "SMB_PEHPCPU1_LVC3_SCL")
	)
	(segment
		(start 7.08279 -184.625996)
		(end 4.1148 -181.658006)
		(width 0.12954)
		(layer "B.Cu")
		(net "SMB_PEHPCPU1_LVC3_SCL")
	)
	(segment
		(start 11.9634 -185.293)
		(end 10.3632 -185.293)
		(width 0.12954)
		(layer "B.Cu")
		(net "SMB_PEHPCPU1_LVC3_SCL")
	)
	(segment
		(start 12.266422 -184.989978)
		(end 11.9634 -185.293)
		(width 0.12954)
		(layer "B.Cu")
		(net "SMB_PEHPCPU1_LVC3_SCL")
	)
	(segment
		(start 10.158222 -184.625996)
		(end 7.08279 -184.625996)
		(width 0.12954)
		(layer "B.Cu")
		(net "SMB_PEHPCPU1_LVC3_SCL")
	)
	(segment
		(start 10.158222 -185.088022)
		(end 10.158222 -184.625996)
		(width 0.12954)
		(layer "B.Cu")
		(net "SMB_PEHPCPU1_LVC3_SCL")
	)
	(segment
		(start 7.39648 -149.824948)
		(end 9.70788 -149.824948)
		(width 0.12954)
		(layer "B.Cu")
		(net "SMB_PEHPCPU1_LVC3_SCL")
	)
	(segment
		(start 127.48006 -118.151148)
		(end 112.489996 -118.151148)
		(width 0.127)
		(layer "In6.Cu")
		(net "SMB_PEHPCPU1_LVC3_SCL")
	)
	(segment
		(start 12.75588 -149.824948)
		(end 9.70788 -149.824948)
		(width 0.127)
		(layer "In6.Cu")
		(net "SMB_PEHPCPU1_LVC3_SCL")
	)
	(segment
		(start 31.01848 -118.379748)
		(end 29.62148 -119.776748)
		(width 0.127)
		(layer "In6.Cu")
		(net "SMB_PEHPCPU1_LVC3_SCL")
	)
	(segment
		(start 133.55828 -121.554748)
		(end 130.88366 -121.554748)
		(width 0.127)
		(layer "In6.Cu")
		(net "SMB_PEHPCPU1_LVC3_SCL")
	)
	(segment
		(start 112.489996 -118.151148)
		(end 106.381296 -124.259848)
		(width 0.127)
		(layer "In6.Cu")
		(net "SMB_PEHPCPU1_LVC3_SCL")
	)
	(segment
		(start 95.710756 -126.152148)
		(end 51.31308 -126.152148)
		(width 0.127)
		(layer "In6.Cu")
		(net "SMB_PEHPCPU1_LVC3_SCL")
	)
	(segment
		(start 51.31308 -126.152148)
		(end 43.54068 -118.379748)
		(width 0.127)
		(layer "In6.Cu")
		(net "SMB_PEHPCPU1_LVC3_SCL")
	)
	(segment
		(start 130.88366 -121.554748)
		(end 127.48006 -118.151148)
		(width 0.127)
		(layer "In6.Cu")
		(net "SMB_PEHPCPU1_LVC3_SCL")
	)
	(segment
		(start 14.66088 -147.919948)
		(end 12.75588 -149.824948)
		(width 0.127)
		(layer "In6.Cu")
		(net "SMB_PEHPCPU1_LVC3_SCL")
	)
	(segment
		(start 137.27938 -125.275848)
		(end 133.55828 -121.554748)
		(width 0.127)
		(layer "In6.Cu")
		(net "SMB_PEHPCPU1_LVC3_SCL")
	)
	(segment
		(start 14.66088 -129.327148)
		(end 14.66088 -147.919948)
		(width 0.127)
		(layer "In6.Cu")
		(net "SMB_PEHPCPU1_LVC3_SCL")
	)
	(segment
		(start 106.381296 -124.259848)
		(end 97.603056 -124.259848)
		(width 0.127)
		(layer "In6.Cu")
		(net "SMB_PEHPCPU1_LVC3_SCL")
	)
	(segment
		(start 148.13788 -125.275848)
		(end 137.27938 -125.275848)
		(width 0.127)
		(layer "In6.Cu")
		(net "SMB_PEHPCPU1_LVC3_SCL")
	)
	(segment
		(start 97.603056 -124.259848)
		(end 95.710756 -126.152148)
		(width 0.127)
		(layer "In6.Cu")
		(net "SMB_PEHPCPU1_LVC3_SCL")
	)
	(segment
		(start 29.62148 -119.776748)
		(end 24.21128 -119.776748)
		(width 0.127)
		(layer "In6.Cu")
		(net "SMB_PEHPCPU1_LVC3_SCL")
	)
	(segment
		(start 43.54068 -118.379748)
		(end 31.01848 -118.379748)
		(width 0.127)
		(layer "In6.Cu")
		(net "SMB_PEHPCPU1_LVC3_SCL")
	)
	(segment
		(start 24.21128 -119.776748)
		(end 14.66088 -129.327148)
		(width 0.127)
		(layer "In6.Cu")
		(net "SMB_PEHPCPU1_LVC3_SCL")
	)
	(segment
		(start 112.579912 -234.69219)
		(end 112.580166 -234.691936)
		(width 0.12954)
		(layer "F.Cu")
		(net "SMB_PEHPCPU1_GTL_SDA")
	)
	(segment
		(start 112.580166 -234.691936)
		(end 112.580166 -234.15625)
		(width 0.12954)
		(layer "F.Cu")
		(net "SMB_PEHPCPU1_GTL_SDA")
	)
	(via
		(at 152.6159 -229.133654)
		(size 0.6604)
		(drill 0.3302)
		(layers "F.Cu" "B.Cu")
		(net "SMB_PEHPCPU1_GTL_SDA")
	)
	(via
		(at 112.580166 -234.15625)
		(size 0.4572)
		(drill 0.2032)
		(layers "F.Cu" "B.Cu")
		(net "SMB_PEHPCPU1_GTL_SDA")
	)
	(segment
		(start 128.743964 -233.831892)
		(end 128.754378 -233.837988)
		(width 0.0889)
		(layer "B.Cu")
		(net "SMB_PEHPCPU1_GTL_SDA")
	)
	(segment
		(start 153.121614 -228.62794)
		(end 153.121614 -228.116892)
		(width 0.12954)
		(layer "B.Cu")
		(net "SMB_PEHPCPU1_GTL_SDA")
	)
	(segment
		(start 118.406164 -233.831892)
		(end 118.420896 -233.840528)
		(width 0.0889)
		(layer "B.Cu")
		(net "SMB_PEHPCPU1_GTL_SDA")
	)
	(segment
		(start 137.870438 -234.214416)
		(end 138.094212 -234.43819)
		(width 0.12954)
		(layer "B.Cu")
		(net "SMB_PEHPCPU1_GTL_SDA")
	)
	(segment
		(start 115.099084 -234.727496)
		(end 117.653562 -234.727496)
		(width 0.0889)
		(layer "B.Cu")
		(net "SMB_PEHPCPU1_GTL_SDA")
	)
	(segment
		(start 117.844316 -234.536742)
		(end 117.844316 -234.15625)
		(width 0.0889)
		(layer "B.Cu")
		(net "SMB_PEHPCPU1_GTL_SDA")
	)
	(segment
		(start 137.870438 -234.21467)
		(end 137.870438 -234.214416)
		(width 0.12954)
		(layer "B.Cu")
		(net "SMB_PEHPCPU1_GTL_SDA")
	)
	(segment
		(start 129.68351 -233.831892)
		(end 129.693924 -233.837988)
		(width 0.0889)
		(layer "B.Cu")
		(net "SMB_PEHPCPU1_GTL_SDA")
	)
	(segment
		(start 122.165364 -233.831892)
		(end 122.175778 -233.837988)
		(width 0.0889)
		(layer "B.Cu")
		(net "SMB_PEHPCPU1_GTL_SDA")
	)
	(segment
		(start 121.780554 -233.837988)
		(end 121.790968 -233.831892)
		(width 0.0889)
		(layer "B.Cu")
		(net "SMB_PEHPCPU1_GTL_SDA")
	)
	(segment
		(start 127.804164 -233.831892)
		(end 127.818896 -233.840528)
		(width 0.0889)
		(layer "B.Cu")
		(net "SMB_PEHPCPU1_GTL_SDA")
	)
	(segment
		(start 120.285764 -233.831892)
		(end 120.296178 -233.837988)
		(width 0.0889)
		(layer "B.Cu")
		(net "SMB_PEHPCPU1_GTL_SDA")
	)
	(segment
		(start 137.697718 -234.04195)
		(end 137.870438 -234.21467)
		(width 0.0889)
		(layer "B.Cu")
		(net "SMB_PEHPCPU1_GTL_SDA")
	)
	(segment
		(start 124.044964 -233.831892)
		(end 124.059696 -233.840528)
		(width 0.0889)
		(layer "B.Cu")
		(net "SMB_PEHPCPU1_GTL_SDA")
	)
	(segment
		(start 147.082764 -234.66679)
		(end 152.6159 -229.133654)
		(width 0.12954)
		(layer "B.Cu")
		(net "SMB_PEHPCPU1_GTL_SDA")
	)
	(segment
		(start 123.10491 -233.831892)
		(end 123.115324 -233.837988)
		(width 0.0889)
		(layer "B.Cu")
		(net "SMB_PEHPCPU1_GTL_SDA")
	)
	(segment
		(start 140.931138 -234.66679)
		(end 147.082764 -234.66679)
		(width 0.12954)
		(layer "B.Cu")
		(net "SMB_PEHPCPU1_GTL_SDA")
	)
	(segment
		(start 152.6159 -229.133654)
		(end 153.121614 -228.62794)
		(width 0.12954)
		(layer "B.Cu")
		(net "SMB_PEHPCPU1_GTL_SDA")
	)
	(segment
		(start 112.73663 -233.885232)
		(end 112.82553 -233.86161)
		(width 0.0889)
		(layer "B.Cu")
		(net "SMB_PEHPCPU1_GTL_SDA")
	)
	(segment
		(start 114.834416 -234.15625)
		(end 114.834416 -234.462828)
		(width 0.0889)
		(layer "B.Cu")
		(net "SMB_PEHPCPU1_GTL_SDA")
	)
	(segment
		(start 124.984764 -233.831892)
		(end 124.999496 -233.840528)
		(width 0.0889)
		(layer "B.Cu")
		(net "SMB_PEHPCPU1_GTL_SDA")
	)
	(segment
		(start 119.345964 -233.831892)
		(end 119.360696 -233.840528)
		(width 0.0889)
		(layer "B.Cu")
		(net "SMB_PEHPCPU1_GTL_SDA")
	)
	(segment
		(start 126.864364 -233.831892)
		(end 126.879096 -233.840528)
		(width 0.0889)
		(layer "B.Cu")
		(net "SMB_PEHPCPU1_GTL_SDA")
	)
	(segment
		(start 140.702538 -234.43819)
		(end 140.931138 -234.66679)
		(width 0.12954)
		(layer "B.Cu")
		(net "SMB_PEHPCPU1_GTL_SDA")
	)
	(segment
		(start 117.653562 -234.727496)
		(end 117.844316 -234.536742)
		(width 0.0889)
		(layer "B.Cu")
		(net "SMB_PEHPCPU1_GTL_SDA")
	)
	(segment
		(start 112.580166 -234.15625)
		(end 112.73663 -233.885232)
		(width 0.0889)
		(layer "B.Cu")
		(net "SMB_PEHPCPU1_GTL_SDA")
	)
	(segment
		(start 138.094212 -234.43819)
		(end 140.702538 -234.43819)
		(width 0.12954)
		(layer "B.Cu")
		(net "SMB_PEHPCPU1_GTL_SDA")
	)
	(segment
		(start 130.623564 -233.831892)
		(end 130.638296 -233.840528)
		(width 0.0889)
		(layer "B.Cu")
		(net "SMB_PEHPCPU1_GTL_SDA")
	)
	(segment
		(start 137.046716 -234.04195)
		(end 137.697718 -234.04195)
		(width 0.0889)
		(layer "B.Cu")
		(net "SMB_PEHPCPU1_GTL_SDA")
	)
	(segment
		(start 118.022878 -233.836972)
		(end 118.031768 -233.831892)
		(width 0.0889)
		(layer "B.Cu")
		(net "SMB_PEHPCPU1_GTL_SDA")
	)
	(segment
		(start 153.121614 -228.116892)
		(end 153.81097 -227.427536)
		(width 0.12954)
		(layer "B.Cu")
		(net "SMB_PEHPCPU1_GTL_SDA")
	)
	(segment
		(start 114.834416 -234.462828)
		(end 115.099084 -234.727496)
		(width 0.0889)
		(layer "B.Cu")
		(net "SMB_PEHPCPU1_GTL_SDA")
	)
	(segment
		(start 131.563364 -233.831892)
		(end 131.578096 -233.840528)
		(width 0.0889)
		(layer "B.Cu")
		(net "SMB_PEHPCPU1_GTL_SDA")
	)
	(arc
		(start 120.850914 -233.831892)
		(mid 121.038112 -233.781749)
		(end 121.22531 -233.831892)
		(width 0.0889)
		(layer "B.Cu")
		(net "SMB_PEHPCPU1_GTL_SDA")
	)
	(arc
		(start 119.360696 -233.840528)
		(mid 119.637137 -233.907694)
		(end 119.911368 -233.831892)
		(width 0.0889)
		(layer "B.Cu")
		(net "SMB_PEHPCPU1_GTL_SDA")
	)
	(arc
		(start 113.707164 -233.831892)
		(mid 113.989866 -233.907634)
		(end 114.272568 -233.831892)
		(width 0.0889)
		(layer "B.Cu")
		(net "SMB_PEHPCPU1_GTL_SDA")
	)
	(arc
		(start 112.82553 -233.86161)
		(mid 113.082669 -233.906892)
		(end 113.332768 -233.831892)
		(width 0.0889)
		(layer "B.Cu")
		(net "SMB_PEHPCPU1_GTL_SDA")
	)
	(arc
		(start 130.249168 -233.831892)
		(mid 130.436366 -233.781749)
		(end 130.623564 -233.831892)
		(width 0.0889)
		(layer "B.Cu")
		(net "SMB_PEHPCPU1_GTL_SDA")
	)
	(arc
		(start 122.730514 -233.831892)
		(mid 122.917712 -233.781749)
		(end 123.10491 -233.831892)
		(width 0.0889)
		(layer "B.Cu")
		(net "SMB_PEHPCPU1_GTL_SDA")
	)
	(arc
		(start 118.971568 -233.831892)
		(mid 119.158766 -233.781749)
		(end 119.345964 -233.831892)
		(width 0.0889)
		(layer "B.Cu")
		(net "SMB_PEHPCPU1_GTL_SDA")
	)
	(arc
		(start 123.115324 -233.837988)
		(mid 123.393756 -233.907802)
		(end 123.670568 -233.831892)
		(width 0.0889)
		(layer "B.Cu")
		(net "SMB_PEHPCPU1_GTL_SDA")
	)
	(arc
		(start 127.429768 -233.831892)
		(mid 127.616966 -233.781749)
		(end 127.804164 -233.831892)
		(width 0.0889)
		(layer "B.Cu")
		(net "SMB_PEHPCPU1_GTL_SDA")
	)
	(arc
		(start 136.262364 -233.831892)
		(mid 136.640716 -233.988545)
		(end 137.046716 -234.04195)
		(width 0.0889)
		(layer "B.Cu")
		(net "SMB_PEHPCPU1_GTL_SDA")
	)
	(arc
		(start 121.22531 -233.831892)
		(mid 121.502123 -233.907728)
		(end 121.780554 -233.837988)
		(width 0.0889)
		(layer "B.Cu")
		(net "SMB_PEHPCPU1_GTL_SDA")
	)
	(arc
		(start 127.818896 -233.840528)
		(mid 128.095337 -233.907694)
		(end 128.369568 -233.831892)
		(width 0.0889)
		(layer "B.Cu")
		(net "SMB_PEHPCPU1_GTL_SDA")
	)
	(arc
		(start 120.296178 -233.837988)
		(mid 120.574356 -233.90768)
		(end 120.850914 -233.831892)
		(width 0.0889)
		(layer "B.Cu")
		(net "SMB_PEHPCPU1_GTL_SDA")
	)
	(arc
		(start 121.790968 -233.831892)
		(mid 121.978166 -233.781749)
		(end 122.165364 -233.831892)
		(width 0.0889)
		(layer "B.Cu")
		(net "SMB_PEHPCPU1_GTL_SDA")
	)
	(arc
		(start 131.188968 -233.831892)
		(mid 131.376166 -233.781749)
		(end 131.563364 -233.831892)
		(width 0.0889)
		(layer "B.Cu")
		(net "SMB_PEHPCPU1_GTL_SDA")
	)
	(arc
		(start 131.578096 -233.840528)
		(mid 131.854537 -233.907694)
		(end 132.128768 -233.831892)
		(width 0.0889)
		(layer "B.Cu")
		(net "SMB_PEHPCPU1_GTL_SDA")
	)
	(arc
		(start 133.442964 -233.831892)
		(mid 133.725666 -233.907634)
		(end 134.008368 -233.831892)
		(width 0.0889)
		(layer "B.Cu")
		(net "SMB_PEHPCPU1_GTL_SDA")
	)
	(arc
		(start 134.382764 -233.831892)
		(mid 134.665466 -233.907634)
		(end 134.948168 -233.831892)
		(width 0.0889)
		(layer "B.Cu")
		(net "SMB_PEHPCPU1_GTL_SDA")
	)
	(arc
		(start 119.911368 -233.831892)
		(mid 120.098566 -233.781749)
		(end 120.285764 -233.831892)
		(width 0.0889)
		(layer "B.Cu")
		(net "SMB_PEHPCPU1_GTL_SDA")
	)
	(arc
		(start 125.924564 -233.831892)
		(mid 126.207266 -233.907634)
		(end 126.489968 -233.831892)
		(width 0.0889)
		(layer "B.Cu")
		(net "SMB_PEHPCPU1_GTL_SDA")
	)
	(arc
		(start 130.638296 -233.840528)
		(mid 130.914737 -233.907694)
		(end 131.188968 -233.831892)
		(width 0.0889)
		(layer "B.Cu")
		(net "SMB_PEHPCPU1_GTL_SDA")
	)
	(arc
		(start 122.175778 -233.837988)
		(mid 122.453956 -233.90768)
		(end 122.730514 -233.831892)
		(width 0.0889)
		(layer "B.Cu")
		(net "SMB_PEHPCPU1_GTL_SDA")
	)
	(arc
		(start 124.999496 -233.840528)
		(mid 125.275937 -233.907694)
		(end 125.550168 -233.831892)
		(width 0.0889)
		(layer "B.Cu")
		(net "SMB_PEHPCPU1_GTL_SDA")
	)
	(arc
		(start 125.550168 -233.831892)
		(mid 125.737366 -233.781749)
		(end 125.924564 -233.831892)
		(width 0.0889)
		(layer "B.Cu")
		(net "SMB_PEHPCPU1_GTL_SDA")
	)
	(arc
		(start 124.059696 -233.840528)
		(mid 124.336137 -233.907694)
		(end 124.610368 -233.831892)
		(width 0.0889)
		(layer "B.Cu")
		(net "SMB_PEHPCPU1_GTL_SDA")
	)
	(arc
		(start 129.693924 -233.837988)
		(mid 129.972356 -233.907802)
		(end 130.249168 -233.831892)
		(width 0.0889)
		(layer "B.Cu")
		(net "SMB_PEHPCPU1_GTL_SDA")
	)
	(arc
		(start 129.309114 -233.831892)
		(mid 129.496312 -233.781749)
		(end 129.68351 -233.831892)
		(width 0.0889)
		(layer "B.Cu")
		(net "SMB_PEHPCPU1_GTL_SDA")
	)
	(arc
		(start 134.008368 -233.831892)
		(mid 134.195566 -233.781749)
		(end 134.382764 -233.831892)
		(width 0.0889)
		(layer "B.Cu")
		(net "SMB_PEHPCPU1_GTL_SDA")
	)
	(arc
		(start 128.754378 -233.837988)
		(mid 129.032556 -233.90768)
		(end 129.309114 -233.831892)
		(width 0.0889)
		(layer "B.Cu")
		(net "SMB_PEHPCPU1_GTL_SDA")
	)
	(arc
		(start 128.369568 -233.831892)
		(mid 128.556766 -233.781749)
		(end 128.743964 -233.831892)
		(width 0.0889)
		(layer "B.Cu")
		(net "SMB_PEHPCPU1_GTL_SDA")
	)
	(arc
		(start 123.670568 -233.831892)
		(mid 123.857766 -233.781749)
		(end 124.044964 -233.831892)
		(width 0.0889)
		(layer "B.Cu")
		(net "SMB_PEHPCPU1_GTL_SDA")
	)
	(arc
		(start 126.879096 -233.840528)
		(mid 127.155537 -233.907694)
		(end 127.429768 -233.831892)
		(width 0.0889)
		(layer "B.Cu")
		(net "SMB_PEHPCPU1_GTL_SDA")
	)
	(arc
		(start 118.031768 -233.831892)
		(mid 118.218966 -233.781749)
		(end 118.406164 -233.831892)
		(width 0.0889)
		(layer "B.Cu")
		(net "SMB_PEHPCPU1_GTL_SDA")
	)
	(arc
		(start 113.332768 -233.831892)
		(mid 113.519966 -233.781749)
		(end 113.707164 -233.831892)
		(width 0.0889)
		(layer "B.Cu")
		(net "SMB_PEHPCPU1_GTL_SDA")
	)
	(arc
		(start 132.128768 -233.831892)
		(mid 132.315966 -233.781749)
		(end 132.503164 -233.831892)
		(width 0.0889)
		(layer "B.Cu")
		(net "SMB_PEHPCPU1_GTL_SDA")
	)
	(arc
		(start 133.068568 -233.831892)
		(mid 133.255766 -233.781749)
		(end 133.442964 -233.831892)
		(width 0.0889)
		(layer "B.Cu")
		(net "SMB_PEHPCPU1_GTL_SDA")
	)
	(arc
		(start 134.948168 -233.831892)
		(mid 135.135366 -233.781749)
		(end 135.322564 -233.831892)
		(width 0.0889)
		(layer "B.Cu")
		(net "SMB_PEHPCPU1_GTL_SDA")
	)
	(arc
		(start 126.489968 -233.831892)
		(mid 126.677166 -233.781749)
		(end 126.864364 -233.831892)
		(width 0.0889)
		(layer "B.Cu")
		(net "SMB_PEHPCPU1_GTL_SDA")
	)
	(arc
		(start 132.503164 -233.831892)
		(mid 132.785866 -233.907634)
		(end 133.068568 -233.831892)
		(width 0.0889)
		(layer "B.Cu")
		(net "SMB_PEHPCPU1_GTL_SDA")
	)
	(arc
		(start 118.420896 -233.840528)
		(mid 118.697337 -233.907694)
		(end 118.971568 -233.831892)
		(width 0.0889)
		(layer "B.Cu")
		(net "SMB_PEHPCPU1_GTL_SDA")
	)
	(arc
		(start 135.887968 -233.831892)
		(mid 136.075166 -233.781749)
		(end 136.262364 -233.831892)
		(width 0.0889)
		(layer "B.Cu")
		(net "SMB_PEHPCPU1_GTL_SDA")
	)
	(arc
		(start 124.610368 -233.831892)
		(mid 124.797566 -233.781749)
		(end 124.984764 -233.831892)
		(width 0.0889)
		(layer "B.Cu")
		(net "SMB_PEHPCPU1_GTL_SDA")
	)
	(arc
		(start 135.322564 -233.831892)
		(mid 135.605266 -233.907634)
		(end 135.887968 -233.831892)
		(width 0.0889)
		(layer "B.Cu")
		(net "SMB_PEHPCPU1_GTL_SDA")
	)
	(arc
		(start 117.844316 -234.15625)
		(mid 117.891995 -233.97335)
		(end 118.022878 -233.836972)
		(width 0.0889)
		(layer "B.Cu")
		(net "SMB_PEHPCPU1_GTL_SDA")
	)
	(arc
		(start 114.272568 -233.831892)
		(mid 114.647043 -233.831938)
		(end 114.834416 -234.15625)
		(width 0.0889)
		(layer "B.Cu")
		(net "SMB_PEHPCPU1_GTL_SDA")
	)
	(segment
		(start 113.049812 -233.877866)
		(end 113.049812 -233.34218)
		(width 0.12954)
		(layer "F.Cu")
		(net "SMB_PEHPCPU1_GTL_SCL")
	)
	(segment
		(start 113.050066 -233.87812)
		(end 113.049812 -233.877866)
		(width 0.12954)
		(layer "F.Cu")
		(net "SMB_PEHPCPU1_GTL_SCL")
	)
	(via
		(at 144.797018 -234.04195)
		(size 0.6604)
		(drill 0.3302)
		(layers "F.Cu" "B.Cu")
		(net "SMB_PEHPCPU1_GTL_SCL")
	)
	(via
		(at 113.049812 -233.34218)
		(size 0.4572)
		(drill 0.2032)
		(layers "F.Cu" "B.Cu")
		(net "SMB_PEHPCPU1_GTL_SCL")
	)
	(segment
		(start 120.75541 -233.666538)
		(end 120.765824 -233.660442)
		(width 0.0889)
		(layer "B.Cu")
		(net "SMB_PEHPCPU1_GTL_SCL")
	)
	(segment
		(start 125.065282 -233.657902)
		(end 125.080014 -233.666538)
		(width 0.0889)
		(layer "B.Cu")
		(net "SMB_PEHPCPU1_GTL_SCL")
	)
	(segment
		(start 151.561038 -229.48519)
		(end 151.561038 -228.656388)
		(width 0.12954)
		(layer "B.Cu")
		(net "SMB_PEHPCPU1_GTL_SCL")
	)
	(segment
		(start 137.832846 -233.717338)
		(end 138.157458 -234.04195)
		(width 0.12954)
		(layer "B.Cu")
		(net "SMB_PEHPCPU1_GTL_SCL")
	)
	(segment
		(start 138.157458 -234.04195)
		(end 144.797018 -234.04195)
		(width 0.12954)
		(layer "B.Cu")
		(net "SMB_PEHPCPU1_GTL_SCL")
	)
	(segment
		(start 117.653816 -234.449112)
		(end 117.653816 -234.134152)
		(width 0.0889)
		(layer "B.Cu")
		(net "SMB_PEHPCPU1_GTL_SCL")
	)
	(segment
		(start 126.009654 -233.660442)
		(end 126.020068 -233.666538)
		(width 0.0889)
		(layer "B.Cu")
		(net "SMB_PEHPCPU1_GTL_SCL")
	)
	(segment
		(start 115.178078 -234.53725)
		(end 117.565678 -234.53725)
		(width 0.0889)
		(layer "B.Cu")
		(net "SMB_PEHPCPU1_GTL_SCL")
	)
	(segment
		(start 115.024916 -234.384088)
		(end 115.178078 -234.53725)
		(width 0.0889)
		(layer "B.Cu")
		(net "SMB_PEHPCPU1_GTL_SCL")
	)
	(segment
		(start 117.565678 -234.53725)
		(end 117.653816 -234.449112)
		(width 0.0889)
		(layer "B.Cu")
		(net "SMB_PEHPCPU1_GTL_SCL")
	)
	(segment
		(start 114.7318 -233.660442)
		(end 114.742214 -233.666538)
		(width 0.0889)
		(layer "B.Cu")
		(net "SMB_PEHPCPU1_GTL_SCL")
	)
	(segment
		(start 132.588254 -233.660442)
		(end 132.598668 -233.666538)
		(width 0.0889)
		(layer "B.Cu")
		(net "SMB_PEHPCPU1_GTL_SCL")
	)
	(segment
		(start 151.561038 -228.656388)
		(end 153.81097 -226.406456)
		(width 0.12954)
		(layer "B.Cu")
		(net "SMB_PEHPCPU1_GTL_SCL")
	)
	(segment
		(start 137.245598 -233.717338)
		(end 137.499598 -233.717338)
		(width 0.0889)
		(layer "B.Cu")
		(net "SMB_PEHPCPU1_GTL_SCL")
	)
	(segment
		(start 115.024916 -234.142026)
		(end 115.024916 -234.384088)
		(width 0.0889)
		(layer "B.Cu")
		(net "SMB_PEHPCPU1_GTL_SCL")
	)
	(segment
		(start 120.366282 -233.657902)
		(end 120.381014 -233.666538)
		(width 0.0889)
		(layer "B.Cu")
		(net "SMB_PEHPCPU1_GTL_SCL")
	)
	(segment
		(start 118.486682 -233.657902)
		(end 118.501414 -233.666538)
		(width 0.0889)
		(layer "B.Cu")
		(net "SMB_PEHPCPU1_GTL_SCL")
	)
	(segment
		(start 124.125482 -233.657902)
		(end 124.140214 -233.666538)
		(width 0.0889)
		(layer "B.Cu")
		(net "SMB_PEHPCPU1_GTL_SCL")
	)
	(segment
		(start 119.426482 -233.657902)
		(end 119.441214 -233.666538)
		(width 0.0889)
		(layer "B.Cu")
		(net "SMB_PEHPCPU1_GTL_SCL")
	)
	(segment
		(start 126.9492 -233.660442)
		(end 126.959614 -233.666538)
		(width 0.0889)
		(layer "B.Cu")
		(net "SMB_PEHPCPU1_GTL_SCL")
	)
	(segment
		(start 127.884682 -233.657902)
		(end 127.899414 -233.666538)
		(width 0.0889)
		(layer "B.Cu")
		(net "SMB_PEHPCPU1_GTL_SCL")
	)
	(segment
		(start 130.704082 -233.657902)
		(end 130.718814 -233.666538)
		(width 0.0889)
		(layer "B.Cu")
		(net "SMB_PEHPCPU1_GTL_SCL")
	)
	(segment
		(start 137.244836 -233.716576)
		(end 137.245598 -233.717338)
		(width 0.0889)
		(layer "B.Cu")
		(net "SMB_PEHPCPU1_GTL_SCL")
	)
	(segment
		(start 128.824482 -233.657902)
		(end 128.839214 -233.666538)
		(width 0.0889)
		(layer "B.Cu")
		(net "SMB_PEHPCPU1_GTL_SCL")
	)
	(segment
		(start 144.797018 -234.04195)
		(end 147.004278 -234.04195)
		(width 0.12954)
		(layer "B.Cu")
		(net "SMB_PEHPCPU1_GTL_SCL")
	)
	(segment
		(start 147.004278 -234.04195)
		(end 151.561038 -229.48519)
		(width 0.12954)
		(layer "B.Cu")
		(net "SMB_PEHPCPU1_GTL_SCL")
	)
	(segment
		(start 131.643882 -233.657902)
		(end 131.658614 -233.666538)
		(width 0.0889)
		(layer "B.Cu")
		(net "SMB_PEHPCPU1_GTL_SCL")
	)
	(segment
		(start 122.2502 -233.660442)
		(end 122.260614 -233.666538)
		(width 0.0889)
		(layer "B.Cu")
		(net "SMB_PEHPCPU1_GTL_SCL")
	)
	(segment
		(start 112.893348 -233.613198)
		(end 112.91443 -233.691176)
		(width 0.0889)
		(layer "B.Cu")
		(net "SMB_PEHPCPU1_GTL_SCL")
	)
	(segment
		(start 113.792254 -233.660442)
		(end 113.802668 -233.666538)
		(width 0.0889)
		(layer "B.Cu")
		(net "SMB_PEHPCPU1_GTL_SCL")
	)
	(segment
		(start 137.499598 -233.717338)
		(end 137.832846 -233.717338)
		(width 0.12954)
		(layer "B.Cu")
		(net "SMB_PEHPCPU1_GTL_SCL")
	)
	(segment
		(start 113.049812 -233.34218)
		(end 112.893348 -233.613198)
		(width 0.0889)
		(layer "B.Cu")
		(net "SMB_PEHPCPU1_GTL_SCL")
	)
	(segment
		(start 136.545066 -233.716576)
		(end 137.244836 -233.716576)
		(width 0.0889)
		(layer "B.Cu")
		(net "SMB_PEHPCPU1_GTL_SCL")
	)
	(arc
		(start 117.93601 -233.666538)
		(mid 118.210239 -233.590613)
		(end 118.486682 -233.657902)
		(width 0.0889)
		(layer "B.Cu")
		(net "SMB_PEHPCPU1_GTL_SCL")
	)
	(arc
		(start 130.15341 -233.666538)
		(mid 130.427639 -233.590613)
		(end 130.704082 -233.657902)
		(width 0.0889)
		(layer "B.Cu")
		(net "SMB_PEHPCPU1_GTL_SCL")
	)
	(arc
		(start 114.742214 -233.666538)
		(mid 114.945695 -233.867342)
		(end 115.024916 -234.142026)
		(width 0.0889)
		(layer "B.Cu")
		(net "SMB_PEHPCPU1_GTL_SCL")
	)
	(arc
		(start 134.478268 -233.666538)
		(mid 134.665466 -233.716681)
		(end 134.852664 -233.666538)
		(width 0.0889)
		(layer "B.Cu")
		(net "SMB_PEHPCPU1_GTL_SCL")
	)
	(arc
		(start 118.501414 -233.666538)
		(mid 118.688612 -233.716681)
		(end 118.87581 -233.666538)
		(width 0.0889)
		(layer "B.Cu")
		(net "SMB_PEHPCPU1_GTL_SCL")
	)
	(arc
		(start 127.899414 -233.666538)
		(mid 128.086612 -233.716681)
		(end 128.27381 -233.666538)
		(width 0.0889)
		(layer "B.Cu")
		(net "SMB_PEHPCPU1_GTL_SCL")
	)
	(arc
		(start 128.27381 -233.666538)
		(mid 128.548039 -233.590613)
		(end 128.824482 -233.657902)
		(width 0.0889)
		(layer "B.Cu")
		(net "SMB_PEHPCPU1_GTL_SCL")
	)
	(arc
		(start 118.87581 -233.666538)
		(mid 119.150039 -233.590613)
		(end 119.426482 -233.657902)
		(width 0.0889)
		(layer "B.Cu")
		(net "SMB_PEHPCPU1_GTL_SCL")
	)
	(arc
		(start 114.177064 -233.666538)
		(mid 114.453623 -233.590829)
		(end 114.7318 -233.660442)
		(width 0.0889)
		(layer "B.Cu")
		(net "SMB_PEHPCPU1_GTL_SCL")
	)
	(arc
		(start 128.839214 -233.666538)
		(mid 129.026412 -233.716681)
		(end 129.21361 -233.666538)
		(width 0.0889)
		(layer "B.Cu")
		(net "SMB_PEHPCPU1_GTL_SCL")
	)
	(arc
		(start 132.973064 -233.666538)
		(mid 133.255766 -233.590796)
		(end 133.538468 -233.666538)
		(width 0.0889)
		(layer "B.Cu")
		(net "SMB_PEHPCPU1_GTL_SCL")
	)
	(arc
		(start 124.140214 -233.666538)
		(mid 124.327412 -233.716681)
		(end 124.51461 -233.666538)
		(width 0.0889)
		(layer "B.Cu")
		(net "SMB_PEHPCPU1_GTL_SCL")
	)
	(arc
		(start 113.23701 -233.666538)
		(mid 113.513823 -233.590702)
		(end 113.792254 -233.660442)
		(width 0.0889)
		(layer "B.Cu")
		(net "SMB_PEHPCPU1_GTL_SCL")
	)
	(arc
		(start 123.57481 -233.666538)
		(mid 123.849039 -233.590613)
		(end 124.125482 -233.657902)
		(width 0.0889)
		(layer "B.Cu")
		(net "SMB_PEHPCPU1_GTL_SCL")
	)
	(arc
		(start 132.598668 -233.666538)
		(mid 132.785866 -233.716681)
		(end 132.973064 -233.666538)
		(width 0.0889)
		(layer "B.Cu")
		(net "SMB_PEHPCPU1_GTL_SCL")
	)
	(arc
		(start 117.653816 -234.134152)
		(mid 117.734727 -233.864024)
		(end 117.93601 -233.666538)
		(width 0.0889)
		(layer "B.Cu")
		(net "SMB_PEHPCPU1_GTL_SCL")
	)
	(arc
		(start 112.91443 -233.691176)
		(mid 113.078526 -233.715523)
		(end 113.23701 -233.666538)
		(width 0.0889)
		(layer "B.Cu")
		(net "SMB_PEHPCPU1_GTL_SCL")
	)
	(arc
		(start 123.200414 -233.666538)
		(mid 123.387612 -233.716681)
		(end 123.57481 -233.666538)
		(width 0.0889)
		(layer "B.Cu")
		(net "SMB_PEHPCPU1_GTL_SCL")
	)
	(arc
		(start 120.765824 -233.660442)
		(mid 121.044256 -233.590628)
		(end 121.321068 -233.666538)
		(width 0.0889)
		(layer "B.Cu")
		(net "SMB_PEHPCPU1_GTL_SCL")
	)
	(arc
		(start 113.802668 -233.666538)
		(mid 113.989866 -233.716681)
		(end 114.177064 -233.666538)
		(width 0.0889)
		(layer "B.Cu")
		(net "SMB_PEHPCPU1_GTL_SCL")
	)
	(arc
		(start 119.81561 -233.666538)
		(mid 120.089839 -233.590613)
		(end 120.366282 -233.657902)
		(width 0.0889)
		(layer "B.Cu")
		(net "SMB_PEHPCPU1_GTL_SCL")
	)
	(arc
		(start 134.852664 -233.666538)
		(mid 135.135366 -233.590796)
		(end 135.418068 -233.666538)
		(width 0.0889)
		(layer "B.Cu")
		(net "SMB_PEHPCPU1_GTL_SCL")
	)
	(arc
		(start 129.779014 -233.666538)
		(mid 129.966212 -233.716681)
		(end 130.15341 -233.666538)
		(width 0.0889)
		(layer "B.Cu")
		(net "SMB_PEHPCPU1_GTL_SCL")
	)
	(arc
		(start 133.538468 -233.666538)
		(mid 133.725666 -233.716681)
		(end 133.912864 -233.666538)
		(width 0.0889)
		(layer "B.Cu")
		(net "SMB_PEHPCPU1_GTL_SCL")
	)
	(arc
		(start 122.260614 -233.666538)
		(mid 122.447812 -233.716681)
		(end 122.63501 -233.666538)
		(width 0.0889)
		(layer "B.Cu")
		(net "SMB_PEHPCPU1_GTL_SCL")
	)
	(arc
		(start 121.695464 -233.666538)
		(mid 121.972023 -233.590829)
		(end 122.2502 -233.660442)
		(width 0.0889)
		(layer "B.Cu")
		(net "SMB_PEHPCPU1_GTL_SCL")
	)
	(arc
		(start 126.959614 -233.666538)
		(mid 127.146812 -233.716681)
		(end 127.33401 -233.666538)
		(width 0.0889)
		(layer "B.Cu")
		(net "SMB_PEHPCPU1_GTL_SCL")
	)
	(arc
		(start 135.792464 -233.666538)
		(mid 136.075166 -233.590796)
		(end 136.357868 -233.666538)
		(width 0.0889)
		(layer "B.Cu")
		(net "SMB_PEHPCPU1_GTL_SCL")
	)
	(arc
		(start 130.718814 -233.666538)
		(mid 130.906012 -233.716681)
		(end 131.09321 -233.666538)
		(width 0.0889)
		(layer "B.Cu")
		(net "SMB_PEHPCPU1_GTL_SCL")
	)
	(arc
		(start 125.45441 -233.666538)
		(mid 125.731223 -233.590702)
		(end 126.009654 -233.660442)
		(width 0.0889)
		(layer "B.Cu")
		(net "SMB_PEHPCPU1_GTL_SCL")
	)
	(arc
		(start 124.51461 -233.666538)
		(mid 124.788839 -233.590613)
		(end 125.065282 -233.657902)
		(width 0.0889)
		(layer "B.Cu")
		(net "SMB_PEHPCPU1_GTL_SCL")
	)
	(arc
		(start 120.381014 -233.666538)
		(mid 120.568212 -233.716681)
		(end 120.75541 -233.666538)
		(width 0.0889)
		(layer "B.Cu")
		(net "SMB_PEHPCPU1_GTL_SCL")
	)
	(arc
		(start 133.912864 -233.666538)
		(mid 134.195566 -233.590796)
		(end 134.478268 -233.666538)
		(width 0.0889)
		(layer "B.Cu")
		(net "SMB_PEHPCPU1_GTL_SCL")
	)
	(arc
		(start 131.658614 -233.666538)
		(mid 131.845812 -233.716681)
		(end 132.03301 -233.666538)
		(width 0.0889)
		(layer "B.Cu")
		(net "SMB_PEHPCPU1_GTL_SCL")
	)
	(arc
		(start 126.394464 -233.666538)
		(mid 126.671023 -233.590829)
		(end 126.9492 -233.660442)
		(width 0.0889)
		(layer "B.Cu")
		(net "SMB_PEHPCPU1_GTL_SCL")
	)
	(arc
		(start 129.21361 -233.666538)
		(mid 129.496312 -233.590796)
		(end 129.779014 -233.666538)
		(width 0.0889)
		(layer "B.Cu")
		(net "SMB_PEHPCPU1_GTL_SCL")
	)
	(arc
		(start 119.441214 -233.666538)
		(mid 119.628412 -233.716681)
		(end 119.81561 -233.666538)
		(width 0.0889)
		(layer "B.Cu")
		(net "SMB_PEHPCPU1_GTL_SCL")
	)
	(arc
		(start 135.418068 -233.666538)
		(mid 135.605266 -233.716681)
		(end 135.792464 -233.666538)
		(width 0.0889)
		(layer "B.Cu")
		(net "SMB_PEHPCPU1_GTL_SCL")
	)
	(arc
		(start 127.33401 -233.666538)
		(mid 127.608239 -233.590613)
		(end 127.884682 -233.657902)
		(width 0.0889)
		(layer "B.Cu")
		(net "SMB_PEHPCPU1_GTL_SCL")
	)
	(arc
		(start 132.03301 -233.666538)
		(mid 132.309823 -233.590702)
		(end 132.588254 -233.660442)
		(width 0.0889)
		(layer "B.Cu")
		(net "SMB_PEHPCPU1_GTL_SCL")
	)
	(arc
		(start 125.080014 -233.666538)
		(mid 125.267212 -233.716681)
		(end 125.45441 -233.666538)
		(width 0.0889)
		(layer "B.Cu")
		(net "SMB_PEHPCPU1_GTL_SCL")
	)
	(arc
		(start 136.357868 -233.666538)
		(mid 136.448175 -233.703867)
		(end 136.545066 -233.716576)
		(width 0.0889)
		(layer "B.Cu")
		(net "SMB_PEHPCPU1_GTL_SCL")
	)
	(arc
		(start 126.020068 -233.666538)
		(mid 126.207266 -233.716681)
		(end 126.394464 -233.666538)
		(width 0.0889)
		(layer "B.Cu")
		(net "SMB_PEHPCPU1_GTL_SCL")
	)
	(arc
		(start 122.63501 -233.666538)
		(mid 122.917712 -233.590796)
		(end 123.200414 -233.666538)
		(width 0.0889)
		(layer "B.Cu")
		(net "SMB_PEHPCPU1_GTL_SCL")
	)
	(arc
		(start 121.321068 -233.666538)
		(mid 121.508266 -233.716681)
		(end 121.695464 -233.666538)
		(width 0.0889)
		(layer "B.Cu")
		(net "SMB_PEHPCPU1_GTL_SCL")
	)
	(arc
		(start 131.09321 -233.666538)
		(mid 131.367439 -233.590613)
		(end 131.643882 -233.657902)
		(width 0.0889)
		(layer "B.Cu")
		(net "SMB_PEHPCPU1_GTL_SCL")
	)
	(segment
		(start 69.107558 -193.91503)
		(end 68.848478 -193.65595)
		(width 0.12954)
		(layer "F.Cu")
		(net "SMB_PEHPCPU1_GTL_R_SDA")
	)
	(segment
		(start 152.721818 -191.71031)
		(end 151.055578 -193.37655)
		(width 0.12954)
		(layer "F.Cu")
		(net "SMB_PEHPCPU1_GTL_R_SDA")
	)
	(segment
		(start 94.296738 -193.37655)
		(end 93.758258 -193.91503)
		(width 0.12954)
		(layer "F.Cu")
		(net "SMB_PEHPCPU1_GTL_R_SDA")
	)
	(segment
		(start 160.562798 -191.71031)
		(end 152.721818 -191.71031)
		(width 0.12954)
		(layer "F.Cu")
		(net "SMB_PEHPCPU1_GTL_R_SDA")
	)
	(segment
		(start 151.055578 -193.37655)
		(end 94.296738 -193.37655)
		(width 0.12954)
		(layer "F.Cu")
		(net "SMB_PEHPCPU1_GTL_R_SDA")
	)
	(segment
		(start 160.819338 -192.68313)
		(end 160.819338 -191.96685)
		(width 0.12954)
		(layer "F.Cu")
		(net "SMB_PEHPCPU1_GTL_R_SDA")
	)
	(segment
		(start 160.819338 -191.96685)
		(end 160.562798 -191.71031)
		(width 0.12954)
		(layer "F.Cu")
		(net "SMB_PEHPCPU1_GTL_R_SDA")
	)
	(segment
		(start 93.758258 -193.91503)
		(end 69.107558 -193.91503)
		(width 0.12954)
		(layer "F.Cu")
		(net "SMB_PEHPCPU1_GTL_R_SDA")
	)
	(via
		(at 21.812758 -192.85585)
		(size 0.508)
		(drill 0.254)
		(layers "F.Cu" "B.Cu")
		(net "SMB_PEHPCPU1_GTL_R_SDA")
	)
	(via
		(at 160.819338 -192.68313)
		(size 0.508)
		(drill 0.254)
		(layers "F.Cu" "B.Cu")
		(net "SMB_PEHPCPU1_GTL_R_SDA")
	)
	(via
		(at 68.848478 -193.65595)
		(size 0.508)
		(drill 0.254)
		(layers "F.Cu" "B.Cu")
		(net "SMB_PEHPCPU1_GTL_R_SDA")
	)
	(via
		(at 15.630906 -192.052702)
		(size 0.6604)
		(drill 0.3302)
		(layers "F.Cu" "B.Cu")
		(net "SMB_PEHPCPU1_GTL_R_SDA")
	)
	(segment
		(start 156.656278 -201.70775)
		(end 156.656278 -221.04731)
		(width 0.12954)
		(layer "B.Cu")
		(net "SMB_PEHPCPU1_GTL_R_SDA")
	)
	(segment
		(start 156.656278 -221.04731)
		(end 155.90266 -221.800928)
		(width 0.12954)
		(layer "B.Cu")
		(net "SMB_PEHPCPU1_GTL_R_SDA")
	)
	(segment
		(start 17.93748 -191.08801)
		(end 17.325086 -191.700404)
		(width 0.12954)
		(layer "B.Cu")
		(net "SMB_PEHPCPU1_GTL_R_SDA")
	)
	(segment
		(start 159.409638 -198.95439)
		(end 156.656278 -201.70775)
		(width 0.12954)
		(layer "B.Cu")
		(net "SMB_PEHPCPU1_GTL_R_SDA")
	)
	(segment
		(start 15.983204 -191.700404)
		(end 15.630906 -192.052702)
		(width 0.12954)
		(layer "B.Cu")
		(net "SMB_PEHPCPU1_GTL_R_SDA")
	)
	(segment
		(start 159.739838 -196.84111)
		(end 159.409638 -197.17131)
		(width 0.12954)
		(layer "B.Cu")
		(net "SMB_PEHPCPU1_GTL_R_SDA")
	)
	(segment
		(start 159.409638 -197.17131)
		(end 159.409638 -198.95439)
		(width 0.12954)
		(layer "B.Cu")
		(net "SMB_PEHPCPU1_GTL_R_SDA")
	)
	(segment
		(start 160.377378 -196.84111)
		(end 159.739838 -196.84111)
		(width 0.12954)
		(layer "B.Cu")
		(net "SMB_PEHPCPU1_GTL_R_SDA")
	)
	(segment
		(start 160.819338 -192.68313)
		(end 161.360104 -193.223896)
		(width 0.12954)
		(layer "B.Cu")
		(net "SMB_PEHPCPU1_GTL_R_SDA")
	)
	(segment
		(start 17.325086 -191.700404)
		(end 15.983204 -191.700404)
		(width 0.12954)
		(layer "B.Cu")
		(net "SMB_PEHPCPU1_GTL_R_SDA")
	)
	(segment
		(start 20.044918 -191.08801)
		(end 17.93748 -191.08801)
		(width 0.12954)
		(layer "B.Cu")
		(net "SMB_PEHPCPU1_GTL_R_SDA")
	)
	(segment
		(start 15.233904 -192.449704)
		(end 13.931138 -192.449704)
		(width 0.12954)
		(layer "B.Cu")
		(net "SMB_PEHPCPU1_GTL_R_SDA")
	)
	(segment
		(start 15.630906 -192.052702)
		(end 15.233904 -192.449704)
		(width 0.12954)
		(layer "B.Cu")
		(net "SMB_PEHPCPU1_GTL_R_SDA")
	)
	(segment
		(start 161.360104 -195.858384)
		(end 160.377378 -196.84111)
		(width 0.12954)
		(layer "B.Cu")
		(net "SMB_PEHPCPU1_GTL_R_SDA")
	)
	(segment
		(start 161.360104 -193.223896)
		(end 161.360104 -195.858384)
		(width 0.12954)
		(layer "B.Cu")
		(net "SMB_PEHPCPU1_GTL_R_SDA")
	)
	(segment
		(start 155.90266 -221.800928)
		(end 155.90266 -226.135946)
		(width 0.12954)
		(layer "B.Cu")
		(net "SMB_PEHPCPU1_GTL_R_SDA")
	)
	(segment
		(start 21.812758 -192.85585)
		(end 20.044918 -191.08801)
		(width 0.12954)
		(layer "B.Cu")
		(net "SMB_PEHPCPU1_GTL_R_SDA")
	)
	(segment
		(start 155.90266 -226.135946)
		(end 154.61107 -227.427536)
		(width 0.12954)
		(layer "B.Cu")
		(net "SMB_PEHPCPU1_GTL_R_SDA")
	)
	(segment
		(start 25.80767 -193.80327)
		(end 24.86025 -192.85585)
		(width 0.127)
		(layer "In4.Cu")
		(net "SMB_PEHPCPU1_GTL_R_SDA")
	)
	(segment
		(start 68.33108 -194.173348)
		(end 37.817044 -194.173348)
		(width 0.127)
		(layer "In4.Cu")
		(net "SMB_PEHPCPU1_GTL_R_SDA")
	)
	(segment
		(start 37.817044 -194.173348)
		(end 37.446966 -193.80327)
		(width 0.127)
		(layer "In4.Cu")
		(net "SMB_PEHPCPU1_GTL_R_SDA")
	)
	(segment
		(start 68.848478 -193.65595)
		(end 68.33108 -194.173348)
		(width 0.127)
		(layer "In4.Cu")
		(net "SMB_PEHPCPU1_GTL_R_SDA")
	)
	(segment
		(start 24.86025 -192.85585)
		(end 21.812758 -192.85585)
		(width 0.127)
		(layer "In4.Cu")
		(net "SMB_PEHPCPU1_GTL_R_SDA")
	)
	(segment
		(start 37.446966 -193.80327)
		(end 25.80767 -193.80327)
		(width 0.127)
		(layer "In4.Cu")
		(net "SMB_PEHPCPU1_GTL_R_SDA")
	)
	(segment
		(start 157.809438 -192.15735)
		(end 152.899364 -192.15735)
		(width 0.12954)
		(layer "F.Cu")
		(net "SMB_PEHPCPU1_GTL_R_SCL")
	)
	(segment
		(start 93.901768 -194.44335)
		(end 68.848478 -194.44335)
		(width 0.12954)
		(layer "F.Cu")
		(net "SMB_PEHPCPU1_GTL_R_SCL")
	)
	(segment
		(start 94.493588 -193.85153)
		(end 93.901768 -194.44335)
		(width 0.12954)
		(layer "F.Cu")
		(net "SMB_PEHPCPU1_GTL_R_SCL")
	)
	(segment
		(start 151.205184 -193.85153)
		(end 94.493588 -193.85153)
		(width 0.12954)
		(layer "F.Cu")
		(net "SMB_PEHPCPU1_GTL_R_SCL")
	)
	(segment
		(start 157.964378 -192.31229)
		(end 157.809438 -192.15735)
		(width 0.12954)
		(layer "F.Cu")
		(net "SMB_PEHPCPU1_GTL_R_SCL")
	)
	(segment
		(start 160.125918 -192.31229)
		(end 157.964378 -192.31229)
		(width 0.12954)
		(layer "F.Cu")
		(net "SMB_PEHPCPU1_GTL_R_SCL")
	)
	(segment
		(start 152.899364 -192.15735)
		(end 151.205184 -193.85153)
		(width 0.12954)
		(layer "F.Cu")
		(net "SMB_PEHPCPU1_GTL_R_SCL")
	)
	(via
		(at 20.819364 -192.848484)
		(size 0.508)
		(drill 0.254)
		(layers "F.Cu" "B.Cu")
		(net "SMB_PEHPCPU1_GTL_R_SCL")
	)
	(via
		(at 16.125698 -193.32067)
		(size 0.6604)
		(drill 0.3302)
		(layers "F.Cu" "B.Cu")
		(net "SMB_PEHPCPU1_GTL_R_SCL")
	)
	(via
		(at 68.848478 -194.44335)
		(size 0.508)
		(drill 0.254)
		(layers "F.Cu" "B.Cu")
		(net "SMB_PEHPCPU1_GTL_R_SCL")
	)
	(via
		(at 160.125918 -192.31229)
		(size 0.508)
		(drill 0.254)
		(layers "F.Cu" "B.Cu")
		(net "SMB_PEHPCPU1_GTL_R_SCL")
	)
	(segment
		(start 16.597884 -192.848484)
		(end 16.125698 -193.32067)
		(width 0.12954)
		(layer "B.Cu")
		(net "SMB_PEHPCPU1_GTL_R_SCL")
	)
	(segment
		(start 154.61107 -226.406456)
		(end 155.444698 -225.572828)
		(width 0.12954)
		(layer "B.Cu")
		(net "SMB_PEHPCPU1_GTL_R_SCL")
	)
	(segment
		(start 155.444698 -221.555818)
		(end 156.1592 -220.841316)
		(width 0.12954)
		(layer "B.Cu")
		(net "SMB_PEHPCPU1_GTL_R_SCL")
	)
	(segment
		(start 20.246594 -192.275714)
		(end 17.897856 -192.275714)
		(width 0.12954)
		(layer "B.Cu")
		(net "SMB_PEHPCPU1_GTL_R_SCL")
	)
	(segment
		(start 160.082738 -196.29755)
		(end 160.86328 -195.517008)
		(width 0.12954)
		(layer "B.Cu")
		(net "SMB_PEHPCPU1_GTL_R_SCL")
	)
	(segment
		(start 20.819364 -192.848484)
		(end 20.246594 -192.275714)
		(width 0.12954)
		(layer "B.Cu")
		(net "SMB_PEHPCPU1_GTL_R_SCL")
	)
	(segment
		(start 160.125918 -192.781174)
		(end 160.125918 -192.31229)
		(width 0.12954)
		(layer "B.Cu")
		(net "SMB_PEHPCPU1_GTL_R_SCL")
	)
	(segment
		(start 15.607538 -193.32067)
		(end 15.386812 -193.099944)
		(width 0.12954)
		(layer "B.Cu")
		(net "SMB_PEHPCPU1_GTL_R_SCL")
	)
	(segment
		(start 16.125698 -193.32067)
		(end 15.607538 -193.32067)
		(width 0.12954)
		(layer "B.Cu")
		(net "SMB_PEHPCPU1_GTL_R_SCL")
	)
	(segment
		(start 159.638238 -196.29755)
		(end 160.082738 -196.29755)
		(width 0.12954)
		(layer "B.Cu")
		(net "SMB_PEHPCPU1_GTL_R_SCL")
	)
	(segment
		(start 17.325086 -192.848484)
		(end 16.597884 -192.848484)
		(width 0.12954)
		(layer "B.Cu")
		(net "SMB_PEHPCPU1_GTL_R_SCL")
	)
	(segment
		(start 160.86328 -193.518536)
		(end 160.125918 -192.781174)
		(width 0.12954)
		(layer "B.Cu")
		(net "SMB_PEHPCPU1_GTL_R_SCL")
	)
	(segment
		(start 17.897856 -192.275714)
		(end 17.325086 -192.848484)
		(width 0.12954)
		(layer "B.Cu")
		(net "SMB_PEHPCPU1_GTL_R_SCL")
	)
	(segment
		(start 158.91256 -197.023228)
		(end 159.638238 -196.29755)
		(width 0.12954)
		(layer "B.Cu")
		(net "SMB_PEHPCPU1_GTL_R_SCL")
	)
	(segment
		(start 15.386812 -193.099944)
		(end 13.931138 -193.099944)
		(width 0.12954)
		(layer "B.Cu")
		(net "SMB_PEHPCPU1_GTL_R_SCL")
	)
	(segment
		(start 156.1592 -201.501756)
		(end 158.91256 -198.748396)
		(width 0.12954)
		(layer "B.Cu")
		(net "SMB_PEHPCPU1_GTL_R_SCL")
	)
	(segment
		(start 160.86328 -195.517008)
		(end 160.86328 -193.518536)
		(width 0.12954)
		(layer "B.Cu")
		(net "SMB_PEHPCPU1_GTL_R_SCL")
	)
	(segment
		(start 156.1592 -220.841316)
		(end 156.1592 -201.501756)
		(width 0.12954)
		(layer "B.Cu")
		(net "SMB_PEHPCPU1_GTL_R_SCL")
	)
	(segment
		(start 158.91256 -198.748396)
		(end 158.91256 -197.023228)
		(width 0.12954)
		(layer "B.Cu")
		(net "SMB_PEHPCPU1_GTL_R_SCL")
	)
	(segment
		(start 155.444698 -225.572828)
		(end 155.444698 -221.555818)
		(width 0.12954)
		(layer "B.Cu")
		(net "SMB_PEHPCPU1_GTL_R_SCL")
	)
	(segment
		(start 25.046432 -192.190878)
		(end 21.47697 -192.190878)
		(width 0.127)
		(layer "In4.Cu")
		(net "SMB_PEHPCPU1_GTL_R_SCL")
	)
	(segment
		(start 66.68008 -193.741548)
		(end 38.3667 -193.741548)
		(width 0.127)
		(layer "In4.Cu")
		(net "SMB_PEHPCPU1_GTL_R_SCL")
	)
	(segment
		(start 69.60108 -193.426334)
		(end 69.179694 -193.004948)
		(width 0.127)
		(layer "In4.Cu")
		(net "SMB_PEHPCPU1_GTL_R_SCL")
	)
	(segment
		(start 26.220928 -193.365374)
		(end 25.046432 -192.190878)
		(width 0.127)
		(layer "In4.Cu")
		(net "SMB_PEHPCPU1_GTL_R_SCL")
	)
	(segment
		(start 69.179694 -193.004948)
		(end 67.41668 -193.004948)
		(width 0.127)
		(layer "In4.Cu")
		(net "SMB_PEHPCPU1_GTL_R_SCL")
	)
	(segment
		(start 67.41668 -193.004948)
		(end 66.68008 -193.741548)
		(width 0.127)
		(layer "In4.Cu")
		(net "SMB_PEHPCPU1_GTL_R_SCL")
	)
	(segment
		(start 31.863792 -193.365374)
		(end 26.220928 -193.365374)
		(width 0.127)
		(layer "In4.Cu")
		(net "SMB_PEHPCPU1_GTL_R_SCL")
	)
	(segment
		(start 32.643064 -192.586102)
		(end 31.863792 -193.365374)
		(width 0.127)
		(layer "In4.Cu")
		(net "SMB_PEHPCPU1_GTL_R_SCL")
	)
	(segment
		(start 37.211254 -192.586102)
		(end 32.643064 -192.586102)
		(width 0.127)
		(layer "In4.Cu")
		(net "SMB_PEHPCPU1_GTL_R_SCL")
	)
	(segment
		(start 68.848478 -194.44335)
		(end 69.331078 -194.44335)
		(width 0.127)
		(layer "In4.Cu")
		(net "SMB_PEHPCPU1_GTL_R_SCL")
	)
	(segment
		(start 69.331078 -194.44335)
		(end 69.60108 -194.173348)
		(width 0.127)
		(layer "In4.Cu")
		(net "SMB_PEHPCPU1_GTL_R_SCL")
	)
	(segment
		(start 38.3667 -193.741548)
		(end 37.211254 -192.586102)
		(width 0.127)
		(layer "In4.Cu")
		(net "SMB_PEHPCPU1_GTL_R_SCL")
	)
	(segment
		(start 69.60108 -194.173348)
		(end 69.60108 -193.426334)
		(width 0.127)
		(layer "In4.Cu")
		(net "SMB_PEHPCPU1_GTL_R_SCL")
	)
	(segment
		(start 21.47697 -192.190878)
		(end 20.819364 -192.848484)
		(width 0.127)
		(layer "In4.Cu")
		(net "SMB_PEHPCPU1_GTL_R_SCL")
	)
	(via
		(at 365.7981 -185.466228)
		(size 0.6604)
		(drill 0.3302)
		(layers "F.Cu" "B.Cu")
		(net "SMB_PEHPCPU0_LVC3_SDA_R0")
	)
	(segment
		(start 366.463326 -184.801002)
		(end 367.034572 -184.801002)
		(width 0.12954)
		(layer "B.Cu")
		(net "SMB_PEHPCPU0_LVC3_SDA_R0")
	)
	(segment
		(start 368.029236 -185.466228)
		(end 365.7981 -185.466228)
		(width 0.12954)
		(layer "B.Cu")
		(net "SMB_PEHPCPU0_LVC3_SDA_R0")
	)
	(segment
		(start 365.7981 -185.466228)
		(end 366.463326 -184.801002)
		(width 0.12954)
		(layer "B.Cu")
		(net "SMB_PEHPCPU0_LVC3_SDA_R0")
	)
	(segment
		(start 368.248438 -185.68543)
		(end 368.029236 -185.466228)
		(width 0.12954)
		(layer "B.Cu")
		(net "SMB_PEHPCPU0_LVC3_SDA_R0")
	)
	(segment
		(start 368.044984 -186.856624)
		(end 368.248438 -186.65317)
		(width 0.12954)
		(layer "B.Cu")
		(net "SMB_PEHPCPU0_LVC3_SDA_R0")
	)
	(segment
		(start 367.302034 -186.856624)
		(end 368.044984 -186.856624)
		(width 0.12954)
		(layer "B.Cu")
		(net "SMB_PEHPCPU0_LVC3_SDA_R0")
	)
	(segment
		(start 368.248438 -186.65317)
		(end 368.248438 -185.68543)
		(width 0.12954)
		(layer "B.Cu")
		(net "SMB_PEHPCPU0_LVC3_SDA_R0")
	)
	(segment
		(start 414.770062 -141.616938)
		(end 392.52779 -141.616938)
		(width 0.12954)
		(layer "F.Cu")
		(net "SMB_PEHPCPU0_LVC3_SDA")
	)
	(segment
		(start 379.15342 -154.991308)
		(end 379.15342 -157.905196)
		(width 0.12954)
		(layer "F.Cu")
		(net "SMB_PEHPCPU0_LVC3_SDA")
	)
	(segment
		(start 466.221064 -127.748792)
		(end 448.043808 -145.926048)
		(width 0.12954)
		(layer "F.Cu")
		(net "SMB_PEHPCPU0_LVC3_SDA")
	)
	(segment
		(start 345.878658 -166.83609)
		(end 345.878658 -172.88891)
		(width 0.12954)
		(layer "F.Cu")
		(net "SMB_PEHPCPU0_LVC3_SDA")
	)
	(segment
		(start 350.726248 -161.9885)
		(end 345.878658 -166.83609)
		(width 0.12954)
		(layer "F.Cu")
		(net "SMB_PEHPCPU0_LVC3_SDA")
	)
	(segment
		(start 379.15342 -157.905196)
		(end 375.070116 -161.9885)
		(width 0.12954)
		(layer "F.Cu")
		(net "SMB_PEHPCPU0_LVC3_SDA")
	)
	(segment
		(start 466.221064 -118.699534)
		(end 466.221064 -127.748792)
		(width 0.12954)
		(layer "F.Cu")
		(net "SMB_PEHPCPU0_LVC3_SDA")
	)
	(segment
		(start 375.070116 -161.9885)
		(end 350.726248 -161.9885)
		(width 0.12954)
		(layer "F.Cu")
		(net "SMB_PEHPCPU0_LVC3_SDA")
	)
	(segment
		(start 392.52779 -141.616938)
		(end 379.15342 -154.991308)
		(width 0.12954)
		(layer "F.Cu")
		(net "SMB_PEHPCPU0_LVC3_SDA")
	)
	(segment
		(start 448.043808 -145.926048)
		(end 419.079172 -145.926048)
		(width 0.12954)
		(layer "F.Cu")
		(net "SMB_PEHPCPU0_LVC3_SDA")
	)
	(segment
		(start 419.079172 -145.926048)
		(end 414.770062 -141.616938)
		(width 0.12954)
		(layer "F.Cu")
		(net "SMB_PEHPCPU0_LVC3_SDA")
	)
	(via
		(at 345.878658 -172.88891)
		(size 0.508)
		(drill 0.254)
		(layers "F.Cu" "B.Cu")
		(net "SMB_PEHPCPU0_LVC3_SDA")
	)
	(segment
		(start 352.881438 -176.94275)
		(end 353.384358 -176.94275)
		(width 0.12954)
		(layer "B.Cu")
		(net "SMB_PEHPCPU0_LVC3_SDA")
	)
	(segment
		(start 346.546678 -174.17415)
		(end 347.638878 -175.26635)
		(width 0.12954)
		(layer "B.Cu")
		(net "SMB_PEHPCPU0_LVC3_SDA")
	)
	(segment
		(start 345.878658 -172.88891)
		(end 346.546678 -173.55693)
		(width 0.12954)
		(layer "B.Cu")
		(net "SMB_PEHPCPU0_LVC3_SDA")
	)
	(segment
		(start 364.613952 -178.53279)
		(end 366.511078 -180.429916)
		(width 0.12954)
		(layer "B.Cu")
		(net "SMB_PEHPCPU0_LVC3_SDA")
	)
	(segment
		(start 346.546678 -173.55693)
		(end 346.546678 -174.17415)
		(width 0.12954)
		(layer "B.Cu")
		(net "SMB_PEHPCPU0_LVC3_SDA")
	)
	(segment
		(start 366.511078 -180.429916)
		(end 366.511078 -182.436008)
		(width 0.12954)
		(layer "B.Cu")
		(net "SMB_PEHPCPU0_LVC3_SDA")
	)
	(segment
		(start 353.384358 -176.94275)
		(end 354.974398 -178.53279)
		(width 0.12954)
		(layer "B.Cu")
		(net "SMB_PEHPCPU0_LVC3_SDA")
	)
	(segment
		(start 366.511078 -182.436008)
		(end 368.075972 -184.000902)
		(width 0.12954)
		(layer "B.Cu")
		(net "SMB_PEHPCPU0_LVC3_SDA")
	)
	(segment
		(start 351.205038 -175.26635)
		(end 352.881438 -176.94275)
		(width 0.12954)
		(layer "B.Cu")
		(net "SMB_PEHPCPU0_LVC3_SDA")
	)
	(segment
		(start 368.075972 -184.000902)
		(end 367.034572 -184.000902)
		(width 0.12954)
		(layer "B.Cu")
		(net "SMB_PEHPCPU0_LVC3_SDA")
	)
	(segment
		(start 354.974398 -178.53279)
		(end 364.613952 -178.53279)
		(width 0.12954)
		(layer "B.Cu")
		(net "SMB_PEHPCPU0_LVC3_SDA")
	)
	(segment
		(start 347.638878 -175.26635)
		(end 351.205038 -175.26635)
		(width 0.12954)
		(layer "B.Cu")
		(net "SMB_PEHPCPU0_LVC3_SDA")
	)
	(via
		(at 369.745768 -185.775854)
		(size 0.762)
		(drill 0.254)
		(layers "F.Cu" "B.Cu")
		(net "SMB_PEHPCPU0_LVC3_SCL_R0")
	)
	(segment
		(start 369.745768 -185.775854)
		(end 370.084858 -185.436764)
		(width 0.12954)
		(layer "B.Cu")
		(net "SMB_PEHPCPU0_LVC3_SCL_R0")
	)
	(segment
		(start 370.084858 -185.436764)
		(end 370.084858 -185.23458)
		(width 0.12954)
		(layer "B.Cu")
		(net "SMB_PEHPCPU0_LVC3_SCL_R0")
	)
	(segment
		(start 370.518436 -184.801002)
		(end 370.539772 -184.801002)
		(width 0.12954)
		(layer "B.Cu")
		(net "SMB_PEHPCPU0_LVC3_SCL_R0")
	)
	(segment
		(start 370.084858 -185.23458)
		(end 370.518436 -184.801002)
		(width 0.12954)
		(layer "B.Cu")
		(net "SMB_PEHPCPU0_LVC3_SCL_R0")
	)
	(segment
		(start 367.302034 -187.506864)
		(end 368.014758 -187.506864)
		(width 0.12954)
		(layer "B.Cu")
		(net "SMB_PEHPCPU0_LVC3_SCL_R0")
	)
	(segment
		(start 368.014758 -187.506864)
		(end 369.745768 -185.775854)
		(width 0.12954)
		(layer "B.Cu")
		(net "SMB_PEHPCPU0_LVC3_SCL_R0")
	)
	(segment
		(start 375.64314 -163.37153)
		(end 351.344738 -163.37153)
		(width 0.12954)
		(layer "F.Cu")
		(net "SMB_PEHPCPU0_LVC3_SCL")
	)
	(segment
		(start 347.90634 -173.163992)
		(end 348.032578 -173.29023)
		(width 0.12954)
		(layer "F.Cu")
		(net "SMB_PEHPCPU0_LVC3_SCL")
	)
	(segment
		(start 347.90634 -166.809928)
		(end 347.90634 -173.163992)
		(width 0.12954)
		(layer "F.Cu")
		(net "SMB_PEHPCPU0_LVC3_SCL")
	)
	(segment
		(start 466.221064 -117.676422)
		(end 466.8901 -118.345458)
		(width 0.12954)
		(layer "F.Cu")
		(net "SMB_PEHPCPU0_LVC3_SCL")
	)
	(segment
		(start 415.35858 -142.999968)
		(end 393.887706 -142.999968)
		(width 0.12954)
		(layer "F.Cu")
		(net "SMB_PEHPCPU0_LVC3_SCL")
	)
	(segment
		(start 380.931928 -155.955746)
		(end 380.931928 -158.082742)
		(width 0.12954)
		(layer "F.Cu")
		(net "SMB_PEHPCPU0_LVC3_SCL")
	)
	(segment
		(start 466.8901 -128.902968)
		(end 449.43268 -146.360388)
		(width 0.12954)
		(layer "F.Cu")
		(net "SMB_PEHPCPU0_LVC3_SCL")
	)
	(segment
		(start 418.719 -146.360388)
		(end 415.35858 -142.999968)
		(width 0.12954)
		(layer "F.Cu")
		(net "SMB_PEHPCPU0_LVC3_SCL")
	)
	(segment
		(start 466.221064 -117.651022)
		(end 466.221064 -117.676422)
		(width 0.12954)
		(layer "F.Cu")
		(net "SMB_PEHPCPU0_LVC3_SCL")
	)
	(segment
		(start 380.931928 -158.082742)
		(end 375.64314 -163.37153)
		(width 0.12954)
		(layer "F.Cu")
		(net "SMB_PEHPCPU0_LVC3_SCL")
	)
	(segment
		(start 466.8901 -118.345458)
		(end 466.8901 -128.902968)
		(width 0.12954)
		(layer "F.Cu")
		(net "SMB_PEHPCPU0_LVC3_SCL")
	)
	(segment
		(start 449.43268 -146.360388)
		(end 418.719 -146.360388)
		(width 0.12954)
		(layer "F.Cu")
		(net "SMB_PEHPCPU0_LVC3_SCL")
	)
	(segment
		(start 393.887706 -142.999968)
		(end 380.931928 -155.955746)
		(width 0.12954)
		(layer "F.Cu")
		(net "SMB_PEHPCPU0_LVC3_SCL")
	)
	(segment
		(start 351.344738 -163.37153)
		(end 347.90634 -166.809928)
		(width 0.12954)
		(layer "F.Cu")
		(net "SMB_PEHPCPU0_LVC3_SCL")
	)
	(via
		(at 348.032578 -173.29023)
		(size 0.508)
		(drill 0.254)
		(layers "F.Cu" "B.Cu")
		(net "SMB_PEHPCPU0_LVC3_SCL")
	)
	(segment
		(start 348.032578 -173.29023)
		(end 347.659198 -173.66361)
		(width 0.12954)
		(layer "B.Cu")
		(net "SMB_PEHPCPU0_LVC3_SCL")
	)
	(segment
		(start 352.781362 -174.70501)
		(end 354.365814 -175.361346)
		(width 0.12954)
		(layer "B.Cu")
		(net "SMB_PEHPCPU0_LVC3_SCL")
	)
	(segment
		(start 354.365814 -175.361346)
		(end 356.996238 -177.99177)
		(width 0.12954)
		(layer "B.Cu")
		(net "SMB_PEHPCPU0_LVC3_SCL")
	)
	(segment
		(start 369.559332 -184.024016)
		(end 369.140486 -184.024016)
		(width 0.12954)
		(layer "B.Cu")
		(net "SMB_PEHPCPU0_LVC3_SCL")
	)
	(segment
		(start 370.539772 -184.000902)
		(end 370.516658 -184.024016)
		(width 0.12954)
		(layer "B.Cu")
		(net "SMB_PEHPCPU0_LVC3_SCL")
	)
	(segment
		(start 369.140486 -184.024016)
		(end 369.117372 -184.000902)
		(width 0.12954)
		(layer "B.Cu")
		(net "SMB_PEHPCPU0_LVC3_SCL")
	)
	(segment
		(start 370.074698 -184.000902)
		(end 369.582446 -184.000902)
		(width 0.12954)
		(layer "B.Cu")
		(net "SMB_PEHPCPU0_LVC3_SCL")
	)
	(segment
		(start 370.097812 -184.024016)
		(end 370.074698 -184.000902)
		(width 0.12954)
		(layer "B.Cu")
		(net "SMB_PEHPCPU0_LVC3_SCL")
	)
	(segment
		(start 364.778798 -177.99177)
		(end 366.945418 -180.15839)
		(width 0.12954)
		(layer "B.Cu")
		(net "SMB_PEHPCPU0_LVC3_SCL")
	)
	(segment
		(start 366.945418 -180.15839)
		(end 366.945418 -181.828948)
		(width 0.12954)
		(layer "B.Cu")
		(net "SMB_PEHPCPU0_LVC3_SCL")
	)
	(segment
		(start 369.582446 -184.000902)
		(end 369.559332 -184.024016)
		(width 0.12954)
		(layer "B.Cu")
		(net "SMB_PEHPCPU0_LVC3_SCL")
	)
	(segment
		(start 356.996238 -177.99177)
		(end 364.778798 -177.99177)
		(width 0.12954)
		(layer "B.Cu")
		(net "SMB_PEHPCPU0_LVC3_SCL")
	)
	(segment
		(start 366.945418 -181.828948)
		(end 369.117372 -184.000902)
		(width 0.12954)
		(layer "B.Cu")
		(net "SMB_PEHPCPU0_LVC3_SCL")
	)
	(segment
		(start 348.210378 -174.70501)
		(end 352.781362 -174.70501)
		(width 0.12954)
		(layer "B.Cu")
		(net "SMB_PEHPCPU0_LVC3_SCL")
	)
	(segment
		(start 347.659198 -174.15383)
		(end 348.210378 -174.70501)
		(width 0.12954)
		(layer "B.Cu")
		(net "SMB_PEHPCPU0_LVC3_SCL")
	)
	(segment
		(start 370.516658 -184.024016)
		(end 370.097812 -184.024016)
		(width 0.12954)
		(layer "B.Cu")
		(net "SMB_PEHPCPU0_LVC3_SCL")
	)
	(segment
		(start 347.659198 -173.66361)
		(end 347.659198 -174.15383)
		(width 0.12954)
		(layer "B.Cu")
		(net "SMB_PEHPCPU0_LVC3_SCL")
	)
	(segment
		(start 464.61299 -117.89156)
		(end 465.420964 -118.699534)
		(width 0.12954)
		(layer "F.Cu")
		(net "SMB_PEHPCPU0_LVC3_R_SDA")
	)
	(segment
		(start 460.648812 -117.89156)
		(end 462.68132 -117.89156)
		(width 0.12954)
		(layer "F.Cu")
		(net "SMB_PEHPCPU0_LVC3_R_SDA")
	)
	(segment
		(start 462.68132 -117.89156)
		(end 464.61299 -117.89156)
		(width 0.12954)
		(layer "F.Cu")
		(net "SMB_PEHPCPU0_LVC3_R_SDA")
	)
	(via
		(at 462.68132 -117.89156)
		(size 0.762)
		(drill 0.381)
		(layers "F.Cu" "B.Cu")
		(net "SMB_PEHPCPU0_LVC3_R_SDA")
	)
	(segment
		(start 460.648812 -117.241574)
		(end 464.16722 -117.241574)
		(width 0.12954)
		(layer "F.Cu")
		(net "SMB_PEHPCPU0_LVC3_R_SCL")
	)
	(segment
		(start 464.16722 -117.241574)
		(end 465.011516 -117.241574)
		(width 0.12954)
		(layer "F.Cu")
		(net "SMB_PEHPCPU0_LVC3_R_SCL")
	)
	(segment
		(start 465.011516 -117.241574)
		(end 465.420964 -117.651022)
		(width 0.12954)
		(layer "F.Cu")
		(net "SMB_PEHPCPU0_LVC3_R_SCL")
	)
	(via
		(at 464.16722 -117.241574)
		(size 0.762)
		(drill 0.381)
		(layers "F.Cu" "B.Cu")
		(net "SMB_PEHPCPU0_LVC3_R_SCL")
	)
	(segment
		(start 360.51998 -234.69219)
		(end 360.520234 -234.691936)
		(width 0.12954)
		(layer "F.Cu")
		(net "SMB_PEHPCPU0_GTL_SDA")
	)
	(segment
		(start 360.520234 -234.691936)
		(end 360.520234 -234.15625)
		(width 0.12954)
		(layer "F.Cu")
		(net "SMB_PEHPCPU0_GTL_SDA")
	)
	(via
		(at 375.88698 -194.015868)
		(size 0.6604)
		(drill 0.3302)
		(layers "F.Cu" "B.Cu")
		(net "SMB_PEHPCPU0_GTL_SDA")
	)
	(via
		(at 360.520234 -234.15625)
		(size 0.4572)
		(drill 0.2032)
		(layers "F.Cu" "B.Cu")
		(net "SMB_PEHPCPU0_GTL_SDA")
	)
	(segment
		(start 365.038132 -227.317046)
		(end 365.023146 -227.325682)
		(width 0.0889)
		(layer "B.Cu")
		(net "SMB_PEHPCPU0_GTL_SDA")
	)
	(segment
		(start 364.561882 -228.134672)
		(end 364.552992 -228.139752)
		(width 0.0889)
		(layer "B.Cu")
		(net "SMB_PEHPCPU0_GTL_SDA")
	)
	(segment
		(start 362.682536 -231.39019)
		(end 362.679234 -231.391968)
		(width 0.0889)
		(layer "B.Cu")
		(net "SMB_PEHPCPU0_GTL_SDA")
	)
	(segment
		(start 362.025184 -232.528364)
		(end 362.025184 -232.53827)
		(width 0.0889)
		(layer "B.Cu")
		(net "SMB_PEHPCPU0_GTL_SDA")
	)
	(segment
		(start 364.37443 -228.45903)
		(end 364.37443 -228.474524)
		(width 0.0889)
		(layer "B.Cu")
		(net "SMB_PEHPCPU0_GTL_SDA")
	)
	(segment
		(start 379.152912 -194.015868)
		(end 383.654554 -198.51751)
		(width 0.12954)
		(layer "B.Cu")
		(net "SMB_PEHPCPU0_GTL_SDA")
	)
	(segment
		(start 371.999764 -225.701606)
		(end 371.985032 -225.69297)
		(width 0.0889)
		(layer "B.Cu")
		(net "SMB_PEHPCPU0_GTL_SDA")
	)
	(segment
		(start 360.676698 -233.885232)
		(end 360.520234 -234.15625)
		(width 0.0889)
		(layer "B.Cu")
		(net "SMB_PEHPCPU0_GTL_SDA")
	)
	(segment
		(start 383.654554 -198.51751)
		(end 384.857498 -198.51751)
		(width 0.12954)
		(layer "B.Cu")
		(net "SMB_PEHPCPU0_GTL_SDA")
	)
	(segment
		(start 388.182104 -223.20631)
		(end 388.090664 -223.29775)
		(width 0.12954)
		(layer "B.Cu")
		(net "SMB_PEHPCPU0_GTL_SDA")
	)
	(segment
		(start 365.784384 -226.017328)
		(end 365.784384 -226.027234)
		(width 0.0889)
		(layer "B.Cu")
		(net "SMB_PEHPCPU0_GTL_SDA")
	)
	(segment
		(start 362.965238 -230.891842)
		(end 362.965238 -230.914702)
		(width 0.0889)
		(layer "B.Cu")
		(net "SMB_PEHPCPU0_GTL_SDA")
	)
	(segment
		(start 362.495084 -231.714548)
		(end 362.495084 -231.730042)
		(width 0.0889)
		(layer "B.Cu")
		(net "SMB_PEHPCPU0_GTL_SDA")
	)
	(segment
		(start 364.092236 -228.948488)
		(end 364.083346 -228.953568)
		(width 0.0889)
		(layer "B.Cu")
		(net "SMB_PEHPCPU0_GTL_SDA")
	)
	(segment
		(start 361.742736 -233.017822)
		(end 361.733846 -233.022902)
		(width 0.0889)
		(layer "B.Cu")
		(net "SMB_PEHPCPU0_GTL_SDA")
	)
	(segment
		(start 374.562624 -192.691512)
		(end 375.88698 -194.015868)
		(width 0.12954)
		(layer "B.Cu")
		(net "SMB_PEHPCPU0_GTL_SDA")
	)
	(segment
		(start 375.88698 -194.015868)
		(end 379.152912 -194.015868)
		(width 0.12954)
		(layer "B.Cu")
		(net "SMB_PEHPCPU0_GTL_SDA")
	)
	(segment
		(start 384.110484 -225.203258)
		(end 384.110484 -225.2218)
		(width 0.0889)
		(layer "B.Cu")
		(net "SMB_PEHPCPU0_GTL_SDA")
	)
	(segment
		(start 363.434884 -230.078026)
		(end 363.434884 -230.096568)
		(width 0.0889)
		(layer "B.Cu")
		(net "SMB_PEHPCPU0_GTL_SDA")
	)
	(segment
		(start 376.698764 -225.701606)
		(end 376.684032 -225.69297)
		(width 0.0889)
		(layer "B.Cu")
		(net "SMB_PEHPCPU0_GTL_SDA")
	)
	(segment
		(start 384.857498 -198.51751)
		(end 388.182104 -201.842116)
		(width 0.12954)
		(layer "B.Cu")
		(net "SMB_PEHPCPU0_GTL_SDA")
	)
	(segment
		(start 384.580384 -224.389442)
		(end 384.580384 -224.399348)
		(width 0.0889)
		(layer "B.Cu")
		(net "SMB_PEHPCPU0_GTL_SDA")
	)
	(segment
		(start 374.819164 -225.701606)
		(end 374.804432 -225.69297)
		(width 0.0889)
		(layer "B.Cu")
		(net "SMB_PEHPCPU0_GTL_SDA")
	)
	(segment
		(start 367.300764 -225.701606)
		(end 367.286032 -225.69297)
		(width 0.0889)
		(layer "B.Cu")
		(net "SMB_PEHPCPU0_GTL_SDA")
	)
	(segment
		(start 378.578364 -225.701606)
		(end 378.563632 -225.69297)
		(width 0.0889)
		(layer "B.Cu")
		(net "SMB_PEHPCPU0_GTL_SDA")
	)
	(segment
		(start 375.758964 -225.701606)
		(end 375.744232 -225.69297)
		(width 0.0889)
		(layer "B.Cu")
		(net "SMB_PEHPCPU0_GTL_SDA")
	)
	(segment
		(start 362.212636 -232.204006)
		(end 362.203746 -232.209086)
		(width 0.0889)
		(layer "B.Cu")
		(net "SMB_PEHPCPU0_GTL_SDA")
	)
	(segment
		(start 388.182104 -201.842116)
		(end 388.182104 -223.20631)
		(width 0.12954)
		(layer "B.Cu")
		(net "SMB_PEHPCPU0_GTL_SDA")
	)
	(segment
		(start 365.501936 -226.506786)
		(end 365.493046 -226.511866)
		(width 0.0889)
		(layer "B.Cu")
		(net "SMB_PEHPCPU0_GTL_SDA")
	)
	(segment
		(start 387.370828 -224.017586)
		(end 386.879592 -224.017586)
		(width 0.0889)
		(layer "B.Cu")
		(net "SMB_PEHPCPU0_GTL_SDA")
	)
	(segment
		(start 360.765598 -233.86161)
		(end 360.676698 -233.885232)
		(width 0.0889)
		(layer "B.Cu")
		(net "SMB_PEHPCPU0_GTL_SDA")
	)
	(segment
		(start 371.059964 -225.701606)
		(end 371.045232 -225.69297)
		(width 0.0889)
		(layer "B.Cu")
		(net "SMB_PEHPCPU0_GTL_SDA")
	)
	(segment
		(start 374.562624 -191.103504)
		(end 374.562624 -192.691512)
		(width 0.12954)
		(layer "B.Cu")
		(net "SMB_PEHPCPU0_GTL_SDA")
	)
	(segment
		(start 384.297936 -224.8789)
		(end 384.289046 -224.88398)
		(width 0.0889)
		(layer "B.Cu")
		(net "SMB_PEHPCPU0_GTL_SDA")
	)
	(segment
		(start 369.180364 -225.701606)
		(end 369.165632 -225.69297)
		(width 0.0889)
		(layer "B.Cu")
		(net "SMB_PEHPCPU0_GTL_SDA")
	)
	(segment
		(start 380.457964 -225.701606)
		(end 380.443232 -225.69297)
		(width 0.0889)
		(layer "B.Cu")
		(net "SMB_PEHPCPU0_GTL_SDA")
	)
	(segment
		(start 373.879364 -225.701606)
		(end 373.864632 -225.69297)
		(width 0.0889)
		(layer "B.Cu")
		(net "SMB_PEHPCPU0_GTL_SDA")
	)
	(segment
		(start 372.939564 -225.701606)
		(end 372.924832 -225.69297)
		(width 0.0889)
		(layer "B.Cu")
		(net "SMB_PEHPCPU0_GTL_SDA")
	)
	(segment
		(start 370.120164 -225.701606)
		(end 370.105432 -225.69297)
		(width 0.0889)
		(layer "B.Cu")
		(net "SMB_PEHPCPU0_GTL_SDA")
	)
	(segment
		(start 379.518164 -225.701606)
		(end 379.503432 -225.69297)
		(width 0.0889)
		(layer "B.Cu")
		(net "SMB_PEHPCPU0_GTL_SDA")
	)
	(segment
		(start 361.555284 -233.34218)
		(end 361.555284 -233.356404)
		(width 0.0889)
		(layer "B.Cu")
		(net "SMB_PEHPCPU0_GTL_SDA")
	)
	(segment
		(start 388.090664 -223.29775)
		(end 387.370828 -224.017586)
		(width 0.0889)
		(layer "B.Cu")
		(net "SMB_PEHPCPU0_GTL_SDA")
	)
	(segment
		(start 366.360964 -225.701606)
		(end 366.346232 -225.69297)
		(width 0.0889)
		(layer "B.Cu")
		(net "SMB_PEHPCPU0_GTL_SDA")
	)
	(segment
		(start 368.240564 -225.701606)
		(end 368.225832 -225.69297)
		(width 0.0889)
		(layer "B.Cu")
		(net "SMB_PEHPCPU0_GTL_SDA")
	)
	(segment
		(start 377.638564 -225.701606)
		(end 377.623832 -225.69297)
		(width 0.0889)
		(layer "B.Cu")
		(net "SMB_PEHPCPU0_GTL_SDA")
	)
	(segment
		(start 363.628178 -229.758748)
		(end 363.622082 -229.762304)
		(width 0.0889)
		(layer "B.Cu")
		(net "SMB_PEHPCPU0_GTL_SDA")
	)
	(segment
		(start 364.844584 -227.64496)
		(end 364.844584 -227.659184)
		(width 0.0889)
		(layer "B.Cu")
		(net "SMB_PEHPCPU0_GTL_SDA")
	)
	(arc
		(start 364.552992 -228.139752)
		(mid 364.422078 -228.276112)
		(end 364.37443 -228.45903)
		(width 0.0889)
		(layer "B.Cu")
		(net "SMB_PEHPCPU0_GTL_SDA")
	)
	(arc
		(start 369.731036 -225.69297)
		(mid 369.456807 -225.768895)
		(end 369.180364 -225.701606)
		(width 0.0889)
		(layer "B.Cu")
		(net "SMB_PEHPCPU0_GTL_SDA")
	)
	(arc
		(start 382.322832 -225.69297)
		(mid 382.135634 -225.642827)
		(end 381.948436 -225.69297)
		(width 0.0889)
		(layer "B.Cu")
		(net "SMB_PEHPCPU0_GTL_SDA")
	)
	(arc
		(start 376.309636 -225.69297)
		(mid 376.035407 -225.768895)
		(end 375.758964 -225.701606)
		(width 0.0889)
		(layer "B.Cu")
		(net "SMB_PEHPCPU0_GTL_SDA")
	)
	(arc
		(start 364.37443 -228.474524)
		(mid 364.29506 -228.748258)
		(end 364.092236 -228.948488)
		(width 0.0889)
		(layer "B.Cu")
		(net "SMB_PEHPCPU0_GTL_SDA")
	)
	(arc
		(start 371.610636 -225.69297)
		(mid 371.336407 -225.768895)
		(end 371.059964 -225.701606)
		(width 0.0889)
		(layer "B.Cu")
		(net "SMB_PEHPCPU0_GTL_SDA")
	)
	(arc
		(start 369.165632 -225.69297)
		(mid 368.978434 -225.642827)
		(end 368.791236 -225.69297)
		(width 0.0889)
		(layer "B.Cu")
		(net "SMB_PEHPCPU0_GTL_SDA")
	)
	(arc
		(start 363.622082 -229.762304)
		(mid 363.487149 -229.895658)
		(end 363.434884 -230.078026)
		(width 0.0889)
		(layer "B.Cu")
		(net "SMB_PEHPCPU0_GTL_SDA")
	)
	(arc
		(start 375.369836 -225.69297)
		(mid 375.095607 -225.768895)
		(end 374.819164 -225.701606)
		(width 0.0889)
		(layer "B.Cu")
		(net "SMB_PEHPCPU0_GTL_SDA")
	)
	(arc
		(start 377.249436 -225.69297)
		(mid 376.975207 -225.768895)
		(end 376.698764 -225.701606)
		(width 0.0889)
		(layer "B.Cu")
		(net "SMB_PEHPCPU0_GTL_SDA")
	)
	(arc
		(start 365.314484 -226.831144)
		(mid 365.240568 -227.110646)
		(end 365.038132 -227.317046)
		(width 0.0889)
		(layer "B.Cu")
		(net "SMB_PEHPCPU0_GTL_SDA")
	)
	(arc
		(start 370.105432 -225.69297)
		(mid 369.918234 -225.642827)
		(end 369.731036 -225.69297)
		(width 0.0889)
		(layer "B.Cu")
		(net "SMB_PEHPCPU0_GTL_SDA")
	)
	(arc
		(start 373.490236 -225.69297)
		(mid 373.216007 -225.768895)
		(end 372.939564 -225.701606)
		(width 0.0889)
		(layer "B.Cu")
		(net "SMB_PEHPCPU0_GTL_SDA")
	)
	(arc
		(start 362.679234 -231.391968)
		(mid 362.544376 -231.528832)
		(end 362.495084 -231.714548)
		(width 0.0889)
		(layer "B.Cu")
		(net "SMB_PEHPCPU0_GTL_SDA")
	)
	(arc
		(start 364.844584 -227.659184)
		(mid 364.765365 -227.933869)
		(end 364.561882 -228.134672)
		(width 0.0889)
		(layer "B.Cu")
		(net "SMB_PEHPCPU0_GTL_SDA")
	)
	(arc
		(start 372.924832 -225.69297)
		(mid 372.737634 -225.642827)
		(end 372.550436 -225.69297)
		(width 0.0889)
		(layer "B.Cu")
		(net "SMB_PEHPCPU0_GTL_SDA")
	)
	(arc
		(start 385.707636 -224.065084)
		(mid 385.424934 -224.14086)
		(end 385.142232 -224.065084)
		(width 0.0889)
		(layer "B.Cu")
		(net "SMB_PEHPCPU0_GTL_SDA")
	)
	(arc
		(start 378.189236 -225.69297)
		(mid 377.915007 -225.768895)
		(end 377.638564 -225.701606)
		(width 0.0889)
		(layer "B.Cu")
		(net "SMB_PEHPCPU0_GTL_SDA")
	)
	(arc
		(start 376.684032 -225.69297)
		(mid 376.496834 -225.642827)
		(end 376.309636 -225.69297)
		(width 0.0889)
		(layer "B.Cu")
		(net "SMB_PEHPCPU0_GTL_SDA")
	)
	(arc
		(start 371.985032 -225.69297)
		(mid 371.797834 -225.642827)
		(end 371.610636 -225.69297)
		(width 0.0889)
		(layer "B.Cu")
		(net "SMB_PEHPCPU0_GTL_SDA")
	)
	(arc
		(start 380.443232 -225.69297)
		(mid 380.256034 -225.642827)
		(end 380.068836 -225.69297)
		(width 0.0889)
		(layer "B.Cu")
		(net "SMB_PEHPCPU0_GTL_SDA")
	)
	(arc
		(start 363.434884 -230.096568)
		(mid 363.356773 -230.373517)
		(end 363.152436 -230.57612)
		(width 0.0889)
		(layer "B.Cu")
		(net "SMB_PEHPCPU0_GTL_SDA")
	)
	(arc
		(start 370.670836 -225.69297)
		(mid 370.396607 -225.768895)
		(end 370.120164 -225.701606)
		(width 0.0889)
		(layer "B.Cu")
		(net "SMB_PEHPCPU0_GTL_SDA")
	)
	(arc
		(start 365.784384 -226.027234)
		(mid 365.706273 -226.304183)
		(end 365.501936 -226.506786)
		(width 0.0889)
		(layer "B.Cu")
		(net "SMB_PEHPCPU0_GTL_SDA")
	)
	(arc
		(start 368.225832 -225.69297)
		(mid 368.038634 -225.642827)
		(end 367.851436 -225.69297)
		(width 0.0889)
		(layer "B.Cu")
		(net "SMB_PEHPCPU0_GTL_SDA")
	)
	(arc
		(start 380.068836 -225.69297)
		(mid 379.794607 -225.768895)
		(end 379.518164 -225.701606)
		(width 0.0889)
		(layer "B.Cu")
		(net "SMB_PEHPCPU0_GTL_SDA")
	)
	(arc
		(start 381.008636 -225.69297)
		(mid 380.734407 -225.768895)
		(end 380.457964 -225.701606)
		(width 0.0889)
		(layer "B.Cu")
		(net "SMB_PEHPCPU0_GTL_SDA")
	)
	(arc
		(start 366.911636 -225.69297)
		(mid 366.637407 -225.768895)
		(end 366.360964 -225.701606)
		(width 0.0889)
		(layer "B.Cu")
		(net "SMB_PEHPCPU0_GTL_SDA")
	)
	(arc
		(start 379.503432 -225.69297)
		(mid 379.316234 -225.642827)
		(end 379.129036 -225.69297)
		(width 0.0889)
		(layer "B.Cu")
		(net "SMB_PEHPCPU0_GTL_SDA")
	)
	(arc
		(start 384.289046 -224.88398)
		(mid 384.158132 -225.02034)
		(end 384.110484 -225.203258)
		(width 0.0889)
		(layer "B.Cu")
		(net "SMB_PEHPCPU0_GTL_SDA")
	)
	(arc
		(start 382.888236 -225.69297)
		(mid 382.605534 -225.768712)
		(end 382.322832 -225.69297)
		(width 0.0889)
		(layer "B.Cu")
		(net "SMB_PEHPCPU0_GTL_SDA")
	)
	(arc
		(start 368.791236 -225.69297)
		(mid 368.517007 -225.768895)
		(end 368.240564 -225.701606)
		(width 0.0889)
		(layer "B.Cu")
		(net "SMB_PEHPCPU0_GTL_SDA")
	)
	(arc
		(start 372.550436 -225.69297)
		(mid 372.276207 -225.768895)
		(end 371.999764 -225.701606)
		(width 0.0889)
		(layer "B.Cu")
		(net "SMB_PEHPCPU0_GTL_SDA")
	)
	(arc
		(start 361.555284 -233.356404)
		(mid 361.29462 -233.818644)
		(end 360.765598 -233.86161)
		(width 0.0889)
		(layer "B.Cu")
		(net "SMB_PEHPCPU0_GTL_SDA")
	)
	(arc
		(start 364.083346 -228.953568)
		(mid 363.952432 -229.089928)
		(end 363.904784 -229.272846)
		(width 0.0889)
		(layer "B.Cu")
		(net "SMB_PEHPCPU0_GTL_SDA")
	)
	(arc
		(start 381.948436 -225.69297)
		(mid 381.665734 -225.768712)
		(end 381.383032 -225.69297)
		(width 0.0889)
		(layer "B.Cu")
		(net "SMB_PEHPCPU0_GTL_SDA")
	)
	(arc
		(start 367.851436 -225.69297)
		(mid 367.577207 -225.768895)
		(end 367.300764 -225.701606)
		(width 0.0889)
		(layer "B.Cu")
		(net "SMB_PEHPCPU0_GTL_SDA")
	)
	(arc
		(start 362.203746 -232.209086)
		(mid 362.072832 -232.345446)
		(end 362.025184 -232.528364)
		(width 0.0889)
		(layer "B.Cu")
		(net "SMB_PEHPCPU0_GTL_SDA")
	)
	(arc
		(start 375.744232 -225.69297)
		(mid 375.557034 -225.642827)
		(end 375.369836 -225.69297)
		(width 0.0889)
		(layer "B.Cu")
		(net "SMB_PEHPCPU0_GTL_SDA")
	)
	(arc
		(start 378.563632 -225.69297)
		(mid 378.376434 -225.642827)
		(end 378.189236 -225.69297)
		(width 0.0889)
		(layer "B.Cu")
		(net "SMB_PEHPCPU0_GTL_SDA")
	)
	(arc
		(start 363.904784 -229.272846)
		(mid 363.830793 -229.552412)
		(end 363.628178 -229.758748)
		(width 0.0889)
		(layer "B.Cu")
		(net "SMB_PEHPCPU0_GTL_SDA")
	)
	(arc
		(start 365.023146 -227.325682)
		(mid 364.892232 -227.462042)
		(end 364.844584 -227.64496)
		(width 0.0889)
		(layer "B.Cu")
		(net "SMB_PEHPCPU0_GTL_SDA")
	)
	(arc
		(start 374.804432 -225.69297)
		(mid 374.617234 -225.642827)
		(end 374.430036 -225.69297)
		(width 0.0889)
		(layer "B.Cu")
		(net "SMB_PEHPCPU0_GTL_SDA")
	)
	(arc
		(start 366.346232 -225.69297)
		(mid 365.971757 -225.693016)
		(end 365.784384 -226.017328)
		(width 0.0889)
		(layer "B.Cu")
		(net "SMB_PEHPCPU0_GTL_SDA")
	)
	(arc
		(start 386.879592 -224.017586)
		(mid 386.759647 -224.022461)
		(end 386.647436 -224.065084)
		(width 0.0889)
		(layer "B.Cu")
		(net "SMB_PEHPCPU0_GTL_SDA")
	)
	(arc
		(start 367.286032 -225.69297)
		(mid 367.098834 -225.642827)
		(end 366.911636 -225.69297)
		(width 0.0889)
		(layer "B.Cu")
		(net "SMB_PEHPCPU0_GTL_SDA")
	)
	(arc
		(start 362.965238 -230.914702)
		(mid 362.886019 -231.189387)
		(end 362.682536 -231.39019)
		(width 0.0889)
		(layer "B.Cu")
		(net "SMB_PEHPCPU0_GTL_SDA")
	)
	(arc
		(start 371.045232 -225.69297)
		(mid 370.858034 -225.642827)
		(end 370.670836 -225.69297)
		(width 0.0889)
		(layer "B.Cu")
		(net "SMB_PEHPCPU0_GTL_SDA")
	)
	(arc
		(start 379.129036 -225.69297)
		(mid 378.854807 -225.768895)
		(end 378.578364 -225.701606)
		(width 0.0889)
		(layer "B.Cu")
		(net "SMB_PEHPCPU0_GTL_SDA")
	)
	(arc
		(start 362.025184 -232.53827)
		(mid 361.947073 -232.815219)
		(end 361.742736 -233.017822)
		(width 0.0889)
		(layer "B.Cu")
		(net "SMB_PEHPCPU0_GTL_SDA")
	)
	(arc
		(start 384.110484 -225.2218)
		(mid 383.820006 -225.697519)
		(end 383.262632 -225.69297)
		(width 0.0889)
		(layer "B.Cu")
		(net "SMB_PEHPCPU0_GTL_SDA")
	)
	(arc
		(start 386.082032 -224.065084)
		(mid 385.894834 -224.014941)
		(end 385.707636 -224.065084)
		(width 0.0889)
		(layer "B.Cu")
		(net "SMB_PEHPCPU0_GTL_SDA")
	)
	(arc
		(start 373.864632 -225.69297)
		(mid 373.677434 -225.642827)
		(end 373.490236 -225.69297)
		(width 0.0889)
		(layer "B.Cu")
		(net "SMB_PEHPCPU0_GTL_SDA")
	)
	(arc
		(start 363.152436 -230.57612)
		(mid 363.017503 -230.709474)
		(end 362.965238 -230.891842)
		(width 0.0889)
		(layer "B.Cu")
		(net "SMB_PEHPCPU0_GTL_SDA")
	)
	(arc
		(start 386.647436 -224.065084)
		(mid 386.364734 -224.14086)
		(end 386.082032 -224.065084)
		(width 0.0889)
		(layer "B.Cu")
		(net "SMB_PEHPCPU0_GTL_SDA")
	)
	(arc
		(start 384.580384 -224.399348)
		(mid 384.502273 -224.676297)
		(end 384.297936 -224.8789)
		(width 0.0889)
		(layer "B.Cu")
		(net "SMB_PEHPCPU0_GTL_SDA")
	)
	(arc
		(start 383.262632 -225.69297)
		(mid 383.075434 -225.642827)
		(end 382.888236 -225.69297)
		(width 0.0889)
		(layer "B.Cu")
		(net "SMB_PEHPCPU0_GTL_SDA")
	)
	(arc
		(start 377.623832 -225.69297)
		(mid 377.436634 -225.642827)
		(end 377.249436 -225.69297)
		(width 0.0889)
		(layer "B.Cu")
		(net "SMB_PEHPCPU0_GTL_SDA")
	)
	(arc
		(start 374.430036 -225.69297)
		(mid 374.155807 -225.768895)
		(end 373.879364 -225.701606)
		(width 0.0889)
		(layer "B.Cu")
		(net "SMB_PEHPCPU0_GTL_SDA")
	)
	(arc
		(start 362.495084 -231.730042)
		(mid 362.415635 -232.003838)
		(end 362.212636 -232.204006)
		(width 0.0889)
		(layer "B.Cu")
		(net "SMB_PEHPCPU0_GTL_SDA")
	)
	(arc
		(start 365.493046 -226.511866)
		(mid 365.362132 -226.648226)
		(end 365.314484 -226.831144)
		(width 0.0889)
		(layer "B.Cu")
		(net "SMB_PEHPCPU0_GTL_SDA")
	)
	(arc
		(start 361.733846 -233.022902)
		(mid 361.602932 -233.159262)
		(end 361.555284 -233.34218)
		(width 0.0889)
		(layer "B.Cu")
		(net "SMB_PEHPCPU0_GTL_SDA")
	)
	(arc
		(start 381.383032 -225.69297)
		(mid 381.195834 -225.642827)
		(end 381.008636 -225.69297)
		(width 0.0889)
		(layer "B.Cu")
		(net "SMB_PEHPCPU0_GTL_SDA")
	)
	(arc
		(start 385.142232 -224.065084)
		(mid 384.767757 -224.06513)
		(end 384.580384 -224.389442)
		(width 0.0889)
		(layer "B.Cu")
		(net "SMB_PEHPCPU0_GTL_SDA")
	)
	(segment
		(start 360.990134 -233.87812)
		(end 360.98988 -233.877866)
		(width 0.12954)
		(layer "F.Cu")
		(net "SMB_PEHPCPU0_GTL_SCL")
	)
	(segment
		(start 360.98988 -233.877866)
		(end 360.98988 -233.34218)
		(width 0.12954)
		(layer "F.Cu")
		(net "SMB_PEHPCPU0_GTL_SCL")
	)
	(via
		(at 360.98988 -233.34218)
		(size 0.4572)
		(drill 0.2032)
		(layers "F.Cu" "B.Cu")
		(net "SMB_PEHPCPU0_GTL_SCL")
	)
	(via
		(at 378.924312 -194.78625)
		(size 0.6604)
		(drill 0.3302)
		(layers "F.Cu" "B.Cu")
		(net "SMB_PEHPCPU0_GTL_SCL")
	)
	(segment
		(start 378.924312 -194.78625)
		(end 383.092452 -198.95439)
		(width 0.12954)
		(layer "B.Cu")
		(net "SMB_PEHPCPU0_GTL_SCL")
	)
	(segment
		(start 387.747764 -202.022456)
		(end 387.747764 -223.16567)
		(width 0.12954)
		(layer "B.Cu")
		(net "SMB_PEHPCPU0_GTL_SCL")
	)
	(segment
		(start 379.598682 -225.527616)
		(end 379.58395 -225.51898)
		(width 0.0889)
		(layer "B.Cu")
		(net "SMB_PEHPCPU0_GTL_SCL")
	)
	(segment
		(start 381.478536 -225.527616)
		(end 381.468122 -225.52152)
		(width 0.0889)
		(layer "B.Cu")
		(net "SMB_PEHPCPU0_GTL_SCL")
	)
	(segment
		(start 373.959882 -225.527616)
		(end 373.94515 -225.51898)
		(width 0.0889)
		(layer "B.Cu")
		(net "SMB_PEHPCPU0_GTL_SCL")
	)
	(segment
		(start 387.747764 -223.16567)
		(end 387.089142 -223.824292)
		(width 0.0889)
		(layer "B.Cu")
		(net "SMB_PEHPCPU0_GTL_SCL")
	)
	(segment
		(start 374.899682 -225.527616)
		(end 374.88495 -225.51898)
		(width 0.0889)
		(layer "B.Cu")
		(net "SMB_PEHPCPU0_GTL_SCL")
	)
	(segment
		(start 365.415322 -226.336606)
		(end 365.39424 -226.348798)
		(width 0.0889)
		(layer "B.Cu")
		(net "SMB_PEHPCPU0_GTL_SCL")
	)
	(segment
		(start 364.654084 -227.629466)
		(end 364.654084 -227.64496)
		(width 0.0889)
		(layer "B.Cu")
		(net "SMB_PEHPCPU0_GTL_SCL")
	)
	(segment
		(start 385.237736 -223.899984)
		(end 385.227322 -223.893888)
		(width 0.0889)
		(layer "B.Cu")
		(net "SMB_PEHPCPU0_GTL_SCL")
	)
	(segment
		(start 375.839482 -225.527616)
		(end 375.82475 -225.51898)
		(width 0.0889)
		(layer "B.Cu")
		(net "SMB_PEHPCPU0_GTL_SCL")
	)
	(segment
		(start 364.18393 -228.444806)
		(end 364.18393 -228.45903)
		(width 0.0889)
		(layer "B.Cu")
		(net "SMB_PEHPCPU0_GTL_SCL")
	)
	(segment
		(start 362.117386 -232.038906)
		(end 362.11129 -232.042462)
		(width 0.0889)
		(layer "B.Cu")
		(net "SMB_PEHPCPU0_GTL_SCL")
	)
	(segment
		(start 384.389884 -224.373948)
		(end 384.389884 -224.389442)
		(width 0.0889)
		(layer "B.Cu")
		(net "SMB_PEHPCPU0_GTL_SCL")
	)
	(segment
		(start 364.475522 -227.964238)
		(end 364.466632 -227.969318)
		(width 0.0889)
		(layer "B.Cu")
		(net "SMB_PEHPCPU0_GTL_SCL")
	)
	(segment
		(start 363.24413 -230.086662)
		(end 363.24413 -230.095298)
		(width 0.0889)
		(layer "B.Cu")
		(net "SMB_PEHPCPU0_GTL_SCL")
	)
	(segment
		(start 364.945168 -227.150422)
		(end 364.936278 -227.155502)
		(width 0.0889)
		(layer "B.Cu")
		(net "SMB_PEHPCPU0_GTL_SCL")
	)
	(segment
		(start 369.260882 -225.527616)
		(end 369.24615 -225.51898)
		(width 0.0889)
		(layer "B.Cu")
		(net "SMB_PEHPCPU0_GTL_SCL")
	)
	(segment
		(start 375.516902 -194.78625)
		(end 378.924312 -194.78625)
		(width 0.12954)
		(layer "B.Cu")
		(net "SMB_PEHPCPU0_GTL_SCL")
	)
	(segment
		(start 384.679698 -198.95439)
		(end 387.747764 -202.022456)
		(width 0.12954)
		(layer "B.Cu")
		(net "SMB_PEHPCPU0_GTL_SCL")
	)
	(segment
		(start 368.321082 -225.527616)
		(end 368.30635 -225.51898)
		(width 0.0889)
		(layer "B.Cu")
		(net "SMB_PEHPCPU0_GTL_SCL")
	)
	(segment
		(start 384.211322 -224.70872)
		(end 384.202432 -224.7138)
		(width 0.0889)
		(layer "B.Cu")
		(net "SMB_PEHPCPU0_GTL_SCL")
	)
	(segment
		(start 372.080282 -225.527616)
		(end 372.06555 -225.51898)
		(width 0.0889)
		(layer "B.Cu")
		(net "SMB_PEHPCPU0_GTL_SCL")
	)
	(segment
		(start 362.590334 -231.223058)
		(end 362.587032 -231.224836)
		(width 0.0889)
		(layer "B.Cu")
		(net "SMB_PEHPCPU0_GTL_SCL")
	)
	(segment
		(start 383.919984 -225.193352)
		(end 383.919984 -225.203258)
		(width 0.0889)
		(layer "B.Cu")
		(net "SMB_PEHPCPU0_GTL_SCL")
	)
	(segment
		(start 361.656122 -232.847642)
		(end 361.63504 -232.859834)
		(width 0.0889)
		(layer "B.Cu")
		(net "SMB_PEHPCPU0_GTL_SCL")
	)
	(segment
		(start 362.774484 -230.890572)
		(end 362.774484 -230.900478)
		(width 0.0889)
		(layer "B.Cu")
		(net "SMB_PEHPCPU0_GTL_SCL")
	)
	(segment
		(start 363.714284 -229.257352)
		(end 363.714284 -229.272846)
		(width 0.0889)
		(layer "B.Cu")
		(net "SMB_PEHPCPU0_GTL_SCL")
	)
	(segment
		(start 377.719082 -225.527616)
		(end 377.70435 -225.51898)
		(width 0.0889)
		(layer "B.Cu")
		(net "SMB_PEHPCPU0_GTL_SCL")
	)
	(segment
		(start 360.833416 -233.613198)
		(end 360.98988 -233.34218)
		(width 0.0889)
		(layer "B.Cu")
		(net "SMB_PEHPCPU0_GTL_SCL")
	)
	(segment
		(start 367.381282 -225.527616)
		(end 367.36655 -225.51898)
		(width 0.0889)
		(layer "B.Cu")
		(net "SMB_PEHPCPU0_GTL_SCL")
	)
	(segment
		(start 373.020082 -225.527616)
		(end 373.00535 -225.51898)
		(width 0.0889)
		(layer "B.Cu")
		(net "SMB_PEHPCPU0_GTL_SCL")
	)
	(segment
		(start 364.005368 -228.778308)
		(end 363.996478 -228.783388)
		(width 0.0889)
		(layer "B.Cu")
		(net "SMB_PEHPCPU0_GTL_SCL")
	)
	(segment
		(start 378.658882 -225.527616)
		(end 378.64415 -225.51898)
		(width 0.0889)
		(layer "B.Cu")
		(net "SMB_PEHPCPU0_GTL_SCL")
	)
	(segment
		(start 370.200682 -225.527616)
		(end 370.18595 -225.51898)
		(width 0.0889)
		(layer "B.Cu")
		(net "SMB_PEHPCPU0_GTL_SCL")
	)
	(segment
		(start 365.593884 -225.99523)
		(end 365.593884 -226.017328)
		(width 0.0889)
		(layer "B.Cu")
		(net "SMB_PEHPCPU0_GTL_SCL")
	)
	(segment
		(start 373.546624 -191.103504)
		(end 373.546624 -192.815972)
		(width 0.12954)
		(layer "B.Cu")
		(net "SMB_PEHPCPU0_GTL_SCL")
	)
	(segment
		(start 387.089142 -223.824292)
		(end 386.831078 -223.824292)
		(width 0.0889)
		(layer "B.Cu")
		(net "SMB_PEHPCPU0_GTL_SCL")
	)
	(segment
		(start 373.546624 -192.815972)
		(end 375.516902 -194.78625)
		(width 0.12954)
		(layer "B.Cu")
		(net "SMB_PEHPCPU0_GTL_SCL")
	)
	(segment
		(start 380.538482 -225.527616)
		(end 380.52375 -225.51898)
		(width 0.0889)
		(layer "B.Cu")
		(net "SMB_PEHPCPU0_GTL_SCL")
	)
	(segment
		(start 366.441482 -225.527616)
		(end 366.42675 -225.51898)
		(width 0.0889)
		(layer "B.Cu")
		(net "SMB_PEHPCPU0_GTL_SCL")
	)
	(segment
		(start 376.779282 -225.527616)
		(end 376.76455 -225.51898)
		(width 0.0889)
		(layer "B.Cu")
		(net "SMB_PEHPCPU0_GTL_SCL")
	)
	(segment
		(start 362.304584 -231.69245)
		(end 362.304584 -231.723184)
		(width 0.0889)
		(layer "B.Cu")
		(net "SMB_PEHPCPU0_GTL_SCL")
	)
	(segment
		(start 360.854498 -233.691176)
		(end 360.833416 -233.613198)
		(width 0.0889)
		(layer "B.Cu")
		(net "SMB_PEHPCPU0_GTL_SCL")
	)
	(segment
		(start 363.535722 -229.592124)
		(end 363.520736 -229.60076)
		(width 0.0889)
		(layer "B.Cu")
		(net "SMB_PEHPCPU0_GTL_SCL")
	)
	(segment
		(start 371.140482 -225.527616)
		(end 371.12575 -225.51898)
		(width 0.0889)
		(layer "B.Cu")
		(net "SMB_PEHPCPU0_GTL_SCL")
	)
	(segment
		(start 383.092452 -198.95439)
		(end 384.679698 -198.95439)
		(width 0.12954)
		(layer "B.Cu")
		(net "SMB_PEHPCPU0_GTL_SCL")
	)
	(arc
		(start 373.94515 -225.51898)
		(mid 373.668709 -225.451814)
		(end 373.394478 -225.527616)
		(width 0.0889)
		(layer "B.Cu")
		(net "SMB_PEHPCPU0_GTL_SCL")
	)
	(arc
		(start 386.551932 -223.899984)
		(mid 386.364734 -223.950127)
		(end 386.177536 -223.899984)
		(width 0.0889)
		(layer "B.Cu")
		(net "SMB_PEHPCPU0_GTL_SCL")
	)
	(arc
		(start 368.30635 -225.51898)
		(mid 368.029909 -225.451814)
		(end 367.755678 -225.527616)
		(width 0.0889)
		(layer "B.Cu")
		(net "SMB_PEHPCPU0_GTL_SCL")
	)
	(arc
		(start 361.63504 -232.859834)
		(mid 361.436812 -233.065682)
		(end 361.36453 -233.34218)
		(width 0.0889)
		(layer "B.Cu")
		(net "SMB_PEHPCPU0_GTL_SCL")
	)
	(arc
		(start 379.973078 -225.527616)
		(mid 379.78588 -225.577759)
		(end 379.598682 -225.527616)
		(width 0.0889)
		(layer "B.Cu")
		(net "SMB_PEHPCPU0_GTL_SCL")
	)
	(arc
		(start 386.177536 -223.899984)
		(mid 385.894834 -223.824208)
		(end 385.612132 -223.899984)
		(width 0.0889)
		(layer "B.Cu")
		(net "SMB_PEHPCPU0_GTL_SCL")
	)
	(arc
		(start 364.936278 -227.155502)
		(mid 364.733455 -227.355733)
		(end 364.654084 -227.629466)
		(width 0.0889)
		(layer "B.Cu")
		(net "SMB_PEHPCPU0_GTL_SCL")
	)
	(arc
		(start 383.919984 -225.203258)
		(mid 383.732685 -225.527699)
		(end 383.358136 -225.527616)
		(width 0.0889)
		(layer "B.Cu")
		(net "SMB_PEHPCPU0_GTL_SCL")
	)
	(arc
		(start 375.82475 -225.51898)
		(mid 375.548309 -225.451814)
		(end 375.274078 -225.527616)
		(width 0.0889)
		(layer "B.Cu")
		(net "SMB_PEHPCPU0_GTL_SCL")
	)
	(arc
		(start 363.996478 -228.783388)
		(mid 363.793655 -228.983619)
		(end 363.714284 -229.257352)
		(width 0.0889)
		(layer "B.Cu")
		(net "SMB_PEHPCPU0_GTL_SCL")
	)
	(arc
		(start 364.18393 -228.45903)
		(mid 364.136251 -228.64193)
		(end 364.005368 -228.778308)
		(width 0.0889)
		(layer "B.Cu")
		(net "SMB_PEHPCPU0_GTL_SCL")
	)
	(arc
		(start 381.468122 -225.52152)
		(mid 381.18969 -225.451706)
		(end 380.912878 -225.527616)
		(width 0.0889)
		(layer "B.Cu")
		(net "SMB_PEHPCPU0_GTL_SCL")
	)
	(arc
		(start 377.70435 -225.51898)
		(mid 377.427909 -225.451814)
		(end 377.153678 -225.527616)
		(width 0.0889)
		(layer "B.Cu")
		(net "SMB_PEHPCPU0_GTL_SCL")
	)
	(arc
		(start 371.12575 -225.51898)
		(mid 370.849309 -225.451814)
		(end 370.575078 -225.527616)
		(width 0.0889)
		(layer "B.Cu")
		(net "SMB_PEHPCPU0_GTL_SCL")
	)
	(arc
		(start 361.834684 -232.528364)
		(mid 361.787005 -232.711264)
		(end 361.656122 -232.847642)
		(width 0.0889)
		(layer "B.Cu")
		(net "SMB_PEHPCPU0_GTL_SCL")
	)
	(arc
		(start 367.755678 -225.527616)
		(mid 367.56848 -225.577759)
		(end 367.381282 -225.527616)
		(width 0.0889)
		(layer "B.Cu")
		(net "SMB_PEHPCPU0_GTL_SCL")
	)
	(arc
		(start 361.36453 -233.34218)
		(mid 361.201552 -233.65117)
		(end 360.854498 -233.691176)
		(width 0.0889)
		(layer "B.Cu")
		(net "SMB_PEHPCPU0_GTL_SCL")
	)
	(arc
		(start 376.76455 -225.51898)
		(mid 376.488109 -225.451814)
		(end 376.213878 -225.527616)
		(width 0.0889)
		(layer "B.Cu")
		(net "SMB_PEHPCPU0_GTL_SCL")
	)
	(arc
		(start 380.52375 -225.51898)
		(mid 380.247309 -225.451814)
		(end 379.973078 -225.527616)
		(width 0.0889)
		(layer "B.Cu")
		(net "SMB_PEHPCPU0_GTL_SCL")
	)
	(arc
		(start 386.831078 -223.824292)
		(mid 386.686571 -223.843953)
		(end 386.551932 -223.899984)
		(width 0.0889)
		(layer "B.Cu")
		(net "SMB_PEHPCPU0_GTL_SCL")
	)
	(arc
		(start 367.36655 -225.51898)
		(mid 367.090109 -225.451814)
		(end 366.815878 -225.527616)
		(width 0.0889)
		(layer "B.Cu")
		(net "SMB_PEHPCPU0_GTL_SCL")
	)
	(arc
		(start 380.912878 -225.527616)
		(mid 380.72568 -225.577759)
		(end 380.538482 -225.527616)
		(width 0.0889)
		(layer "B.Cu")
		(net "SMB_PEHPCPU0_GTL_SCL")
	)
	(arc
		(start 371.514878 -225.527616)
		(mid 371.32768 -225.577759)
		(end 371.140482 -225.527616)
		(width 0.0889)
		(layer "B.Cu")
		(net "SMB_PEHPCPU0_GTL_SCL")
	)
	(arc
		(start 363.520736 -229.60076)
		(mid 363.318149 -229.807111)
		(end 363.24413 -230.086662)
		(width 0.0889)
		(layer "B.Cu")
		(net "SMB_PEHPCPU0_GTL_SCL")
	)
	(arc
		(start 363.24413 -230.095298)
		(mid 363.19186 -230.277663)
		(end 363.056932 -230.41102)
		(width 0.0889)
		(layer "B.Cu")
		(net "SMB_PEHPCPU0_GTL_SCL")
	)
	(arc
		(start 381.852932 -225.527616)
		(mid 381.665734 -225.577759)
		(end 381.478536 -225.527616)
		(width 0.0889)
		(layer "B.Cu")
		(net "SMB_PEHPCPU0_GTL_SCL")
	)
	(arc
		(start 365.593884 -226.017328)
		(mid 365.546205 -226.200228)
		(end 365.415322 -226.336606)
		(width 0.0889)
		(layer "B.Cu")
		(net "SMB_PEHPCPU0_GTL_SCL")
	)
	(arc
		(start 385.227322 -223.893888)
		(mid 384.673847 -223.898883)
		(end 384.389884 -224.373948)
		(width 0.0889)
		(layer "B.Cu")
		(net "SMB_PEHPCPU0_GTL_SCL")
	)
	(arc
		(start 366.815878 -225.527616)
		(mid 366.62868 -225.577759)
		(end 366.441482 -225.527616)
		(width 0.0889)
		(layer "B.Cu")
		(net "SMB_PEHPCPU0_GTL_SCL")
	)
	(arc
		(start 373.00535 -225.51898)
		(mid 372.728909 -225.451814)
		(end 372.454678 -225.527616)
		(width 0.0889)
		(layer "B.Cu")
		(net "SMB_PEHPCPU0_GTL_SCL")
	)
	(arc
		(start 372.454678 -225.527616)
		(mid 372.26748 -225.577759)
		(end 372.080282 -225.527616)
		(width 0.0889)
		(layer "B.Cu")
		(net "SMB_PEHPCPU0_GTL_SCL")
	)
	(arc
		(start 379.58395 -225.51898)
		(mid 379.307509 -225.451814)
		(end 379.033278 -225.527616)
		(width 0.0889)
		(layer "B.Cu")
		(net "SMB_PEHPCPU0_GTL_SCL")
	)
	(arc
		(start 378.64415 -225.51898)
		(mid 378.367709 -225.451814)
		(end 378.093478 -225.527616)
		(width 0.0889)
		(layer "B.Cu")
		(net "SMB_PEHPCPU0_GTL_SCL")
	)
	(arc
		(start 382.792732 -225.527616)
		(mid 382.605534 -225.577759)
		(end 382.418336 -225.527616)
		(width 0.0889)
		(layer "B.Cu")
		(net "SMB_PEHPCPU0_GTL_SCL")
	)
	(arc
		(start 375.274078 -225.527616)
		(mid 375.08688 -225.577759)
		(end 374.899682 -225.527616)
		(width 0.0889)
		(layer "B.Cu")
		(net "SMB_PEHPCPU0_GTL_SCL")
	)
	(arc
		(start 365.12373 -226.831144)
		(mid 365.076051 -227.014044)
		(end 364.945168 -227.150422)
		(width 0.0889)
		(layer "B.Cu")
		(net "SMB_PEHPCPU0_GTL_SCL")
	)
	(arc
		(start 372.06555 -225.51898)
		(mid 371.789109 -225.451814)
		(end 371.514878 -225.527616)
		(width 0.0889)
		(layer "B.Cu")
		(net "SMB_PEHPCPU0_GTL_SCL")
	)
	(arc
		(start 370.18595 -225.51898)
		(mid 369.909509 -225.451814)
		(end 369.635278 -225.527616)
		(width 0.0889)
		(layer "B.Cu")
		(net "SMB_PEHPCPU0_GTL_SCL")
	)
	(arc
		(start 364.654084 -227.64496)
		(mid 364.606405 -227.82786)
		(end 364.475522 -227.964238)
		(width 0.0889)
		(layer "B.Cu")
		(net "SMB_PEHPCPU0_GTL_SCL")
	)
	(arc
		(start 366.42675 -225.51898)
		(mid 365.878254 -225.526222)
		(end 365.593884 -225.99523)
		(width 0.0889)
		(layer "B.Cu")
		(net "SMB_PEHPCPU0_GTL_SCL")
	)
	(arc
		(start 384.389884 -224.389442)
		(mid 384.342205 -224.572342)
		(end 384.211322 -224.70872)
		(width 0.0889)
		(layer "B.Cu")
		(net "SMB_PEHPCPU0_GTL_SCL")
	)
	(arc
		(start 378.093478 -225.527616)
		(mid 377.90628 -225.577759)
		(end 377.719082 -225.527616)
		(width 0.0889)
		(layer "B.Cu")
		(net "SMB_PEHPCPU0_GTL_SCL")
	)
	(arc
		(start 369.24615 -225.51898)
		(mid 368.969709 -225.451814)
		(end 368.695478 -225.527616)
		(width 0.0889)
		(layer "B.Cu")
		(net "SMB_PEHPCPU0_GTL_SCL")
	)
	(arc
		(start 362.774484 -230.900478)
		(mid 362.725209 -231.086204)
		(end 362.590334 -231.223058)
		(width 0.0889)
		(layer "B.Cu")
		(net "SMB_PEHPCPU0_GTL_SCL")
	)
	(arc
		(start 362.304584 -231.723184)
		(mid 362.252314 -231.905549)
		(end 362.117386 -232.038906)
		(width 0.0889)
		(layer "B.Cu")
		(net "SMB_PEHPCPU0_GTL_SCL")
	)
	(arc
		(start 374.334278 -225.527616)
		(mid 374.14708 -225.577759)
		(end 373.959882 -225.527616)
		(width 0.0889)
		(layer "B.Cu")
		(net "SMB_PEHPCPU0_GTL_SCL")
	)
	(arc
		(start 383.358136 -225.527616)
		(mid 383.075434 -225.451874)
		(end 382.792732 -225.527616)
		(width 0.0889)
		(layer "B.Cu")
		(net "SMB_PEHPCPU0_GTL_SCL")
	)
	(arc
		(start 362.587032 -231.224836)
		(mid 362.385576 -231.422261)
		(end 362.304584 -231.69245)
		(width 0.0889)
		(layer "B.Cu")
		(net "SMB_PEHPCPU0_GTL_SCL")
	)
	(arc
		(start 363.714284 -229.272846)
		(mid 363.666605 -229.455746)
		(end 363.535722 -229.592124)
		(width 0.0889)
		(layer "B.Cu")
		(net "SMB_PEHPCPU0_GTL_SCL")
	)
	(arc
		(start 376.213878 -225.527616)
		(mid 376.02668 -225.577759)
		(end 375.839482 -225.527616)
		(width 0.0889)
		(layer "B.Cu")
		(net "SMB_PEHPCPU0_GTL_SCL")
	)
	(arc
		(start 385.612132 -223.899984)
		(mid 385.424934 -223.950127)
		(end 385.237736 -223.899984)
		(width 0.0889)
		(layer "B.Cu")
		(net "SMB_PEHPCPU0_GTL_SCL")
	)
	(arc
		(start 377.153678 -225.527616)
		(mid 376.96648 -225.577759)
		(end 376.779282 -225.527616)
		(width 0.0889)
		(layer "B.Cu")
		(net "SMB_PEHPCPU0_GTL_SCL")
	)
	(arc
		(start 379.033278 -225.527616)
		(mid 378.84608 -225.577759)
		(end 378.658882 -225.527616)
		(width 0.0889)
		(layer "B.Cu")
		(net "SMB_PEHPCPU0_GTL_SCL")
	)
	(arc
		(start 374.88495 -225.51898)
		(mid 374.608509 -225.451814)
		(end 374.334278 -225.527616)
		(width 0.0889)
		(layer "B.Cu")
		(net "SMB_PEHPCPU0_GTL_SCL")
	)
	(arc
		(start 373.394478 -225.527616)
		(mid 373.20728 -225.577759)
		(end 373.020082 -225.527616)
		(width 0.0889)
		(layer "B.Cu")
		(net "SMB_PEHPCPU0_GTL_SCL")
	)
	(arc
		(start 364.466632 -227.969318)
		(mid 364.263151 -228.170122)
		(end 364.18393 -228.444806)
		(width 0.0889)
		(layer "B.Cu")
		(net "SMB_PEHPCPU0_GTL_SCL")
	)
	(arc
		(start 368.695478 -225.527616)
		(mid 368.50828 -225.577759)
		(end 368.321082 -225.527616)
		(width 0.0889)
		(layer "B.Cu")
		(net "SMB_PEHPCPU0_GTL_SCL")
	)
	(arc
		(start 384.202432 -224.7138)
		(mid 383.998097 -224.916405)
		(end 383.919984 -225.193352)
		(width 0.0889)
		(layer "B.Cu")
		(net "SMB_PEHPCPU0_GTL_SCL")
	)
	(arc
		(start 365.39424 -226.348798)
		(mid 365.196012 -226.554646)
		(end 365.12373 -226.831144)
		(width 0.0889)
		(layer "B.Cu")
		(net "SMB_PEHPCPU0_GTL_SCL")
	)
	(arc
		(start 363.056932 -230.41102)
		(mid 362.852597 -230.613625)
		(end 362.774484 -230.890572)
		(width 0.0889)
		(layer "B.Cu")
		(net "SMB_PEHPCPU0_GTL_SCL")
	)
	(arc
		(start 382.418336 -225.527616)
		(mid 382.135634 -225.451874)
		(end 381.852932 -225.527616)
		(width 0.0889)
		(layer "B.Cu")
		(net "SMB_PEHPCPU0_GTL_SCL")
	)
	(arc
		(start 362.11129 -232.042462)
		(mid 361.908703 -232.248813)
		(end 361.834684 -232.528364)
		(width 0.0889)
		(layer "B.Cu")
		(net "SMB_PEHPCPU0_GTL_SCL")
	)
	(arc
		(start 369.635278 -225.527616)
		(mid 369.44808 -225.577759)
		(end 369.260882 -225.527616)
		(width 0.0889)
		(layer "B.Cu")
		(net "SMB_PEHPCPU0_GTL_SCL")
	)
	(arc
		(start 370.575078 -225.527616)
		(mid 370.38788 -225.577759)
		(end 370.200682 -225.527616)
		(width 0.0889)
		(layer "B.Cu")
		(net "SMB_PEHPCPU0_GTL_SCL")
	)
	(via
		(at 374.396 -187.797948)
		(size 0.6604)
		(drill 0.3302)
		(layers "F.Cu" "B.Cu")
		(net "SMB_PEHPCPU0_GTL_R_SDA")
	)
	(segment
		(start 374.954038 -189.91199)
		(end 374.954038 -188.01461)
		(width 0.12954)
		(layer "B.Cu")
		(net "SMB_PEHPCPU0_GTL_R_SDA")
	)
	(segment
		(start 374.396 -187.797948)
		(end 373.143272 -186.54522)
		(width 0.12954)
		(layer "B.Cu")
		(net "SMB_PEHPCPU0_GTL_R_SDA")
	)
	(segment
		(start 372.831614 -186.856624)
		(end 373.143018 -186.54522)
		(width 0.12954)
		(layer "B.Cu")
		(net "SMB_PEHPCPU0_GTL_R_SDA")
	)
	(segment
		(start 374.954038 -188.01461)
		(end 374.737376 -187.797948)
		(width 0.12954)
		(layer "B.Cu")
		(net "SMB_PEHPCPU0_GTL_R_SDA")
	)
	(segment
		(start 371.652038 -186.856624)
		(end 372.831614 -186.856624)
		(width 0.12954)
		(layer "B.Cu")
		(net "SMB_PEHPCPU0_GTL_R_SDA")
	)
	(segment
		(start 374.737376 -187.797948)
		(end 374.396 -187.797948)
		(width 0.12954)
		(layer "B.Cu")
		(net "SMB_PEHPCPU0_GTL_R_SDA")
	)
	(segment
		(start 373.143272 -186.54522)
		(end 373.143018 -186.54522)
		(width 0.12954)
		(layer "B.Cu")
		(net "SMB_PEHPCPU0_GTL_R_SDA")
	)
	(segment
		(start 374.562624 -190.303404)
		(end 374.954038 -189.91199)
		(width 0.12954)
		(layer "B.Cu")
		(net "SMB_PEHPCPU0_GTL_R_SDA")
	)
	(via
		(at 374.324118 -189.147196)
		(size 0.6604)
		(drill 0.3302)
		(layers "F.Cu" "B.Cu")
		(net "SMB_PEHPCPU0_GTL_R_SCL")
	)
	(segment
		(start 373.025162 -187.506864)
		(end 373.112538 -187.59424)
		(width 0.12954)
		(layer "B.Cu")
		(net "SMB_PEHPCPU0_GTL_R_SCL")
	)
	(segment
		(start 373.546624 -189.92469)
		(end 374.324118 -189.147196)
		(width 0.12954)
		(layer "B.Cu")
		(net "SMB_PEHPCPU0_GTL_R_SCL")
	)
	(segment
		(start 371.652038 -187.506864)
		(end 373.025162 -187.506864)
		(width 0.12954)
		(layer "B.Cu")
		(net "SMB_PEHPCPU0_GTL_R_SCL")
	)
	(segment
		(start 373.546624 -190.303404)
		(end 373.546624 -189.92469)
		(width 0.12954)
		(layer "B.Cu")
		(net "SMB_PEHPCPU0_GTL_R_SCL")
	)
	(segment
		(start 374.324118 -188.487812)
		(end 373.430546 -187.59424)
		(width 0.12954)
		(layer "B.Cu")
		(net "SMB_PEHPCPU0_GTL_R_SCL")
	)
	(segment
		(start 373.430546 -187.59424)
		(end 373.112538 -187.59424)
		(width 0.12954)
		(layer "B.Cu")
		(net "SMB_PEHPCPU0_GTL_R_SCL")
	)
	(segment
		(start 374.324118 -189.147196)
		(end 374.324118 -188.487812)
		(width 0.12954)
		(layer "B.Cu")
		(net "SMB_PEHPCPU0_GTL_R_SCL")
	)
	(segment
		(start 155.70962 -57.761124)
		(end 155.532074 -57.93867)
		(width 0.12954)
		(layer "F.Cu")
		(net "SMB_PCIE_M2_0_EN")
	)
	(segment
		(start 159.99206 -57.833768)
		(end 159.42183 -58.403998)
		(width 0.12954)
		(layer "F.Cu")
		(net "SMB_PCIE_M2_0_EN")
	)
	(segment
		(start 155.532074 -58.23331)
		(end 155.709874 -58.41111)
		(width 0.12954)
		(layer "F.Cu")
		(net "SMB_PCIE_M2_0_EN")
	)
	(segment
		(start 161.15665 -57.833768)
		(end 159.99206 -57.833768)
		(width 0.12954)
		(layer "F.Cu")
		(net "SMB_PCIE_M2_0_EN")
	)
	(segment
		(start 156.467556 -57.761124)
		(end 155.70962 -57.761124)
		(width 0.12954)
		(layer "F.Cu")
		(net "SMB_PCIE_M2_0_EN")
	)
	(segment
		(start 159.42183 -58.403998)
		(end 159.42183 -58.511948)
		(width 0.12954)
		(layer "F.Cu")
		(net "SMB_PCIE_M2_0_EN")
	)
	(segment
		(start 161.83483 -58.511948)
		(end 161.15665 -57.833768)
		(width 0.12954)
		(layer "F.Cu")
		(net "SMB_PCIE_M2_0_EN")
	)
	(segment
		(start 159.42183 -58.511948)
		(end 158.17342 -58.511948)
		(width 0.12954)
		(layer "F.Cu")
		(net "SMB_PCIE_M2_0_EN")
	)
	(segment
		(start 157.308296 -58.41111)
		(end 156.467556 -58.41111)
		(width 0.12954)
		(layer "F.Cu")
		(net "SMB_PCIE_M2_0_EN")
	)
	(segment
		(start 157.409134 -58.511948)
		(end 157.308296 -58.41111)
		(width 0.12954)
		(layer "F.Cu")
		(net "SMB_PCIE_M2_0_EN")
	)
	(segment
		(start 155.709874 -58.41111)
		(end 156.467556 -58.41111)
		(width 0.12954)
		(layer "F.Cu")
		(net "SMB_PCIE_M2_0_EN")
	)
	(segment
		(start 158.17342 -58.511948)
		(end 157.409134 -58.511948)
		(width 0.12954)
		(layer "F.Cu")
		(net "SMB_PCIE_M2_0_EN")
	)
	(segment
		(start 155.532074 -57.93867)
		(end 155.532074 -58.23331)
		(width 0.12954)
		(layer "F.Cu")
		(net "SMB_PCIE_M2_0_EN")
	)
	(via
		(at 158.17342 -58.511948)
		(size 0.508)
		(drill 0.254)
		(layers "F.Cu" "B.Cu")
		(net "SMB_PCIE_M2_0_EN")
	)
	(segment
		(start 152.657048 -12.683998)
		(end 152.621742 -12.648692)
		(width 0.12954)
		(layer "F.Cu")
		(net "SMB_PCIE3_3V3AUX_SDA_R")
	)
	(segment
		(start 152.621742 -12.648692)
		(end 152.621742 -11.23315)
		(width 0.12954)
		(layer "F.Cu")
		(net "SMB_PCIE3_3V3AUX_SDA_R")
	)
	(segment
		(start 152.621742 -11.23315)
		(end 152.3492 -10.960608)
		(width 0.12954)
		(layer "F.Cu")
		(net "SMB_PCIE3_3V3AUX_SDA_R")
	)
	(segment
		(start 152.657048 -13.600176)
		(end 152.657048 -12.683998)
		(width 0.12954)
		(layer "F.Cu")
		(net "SMB_PCIE3_3V3AUX_SDA_R")
	)
	(via
		(at 152.3492 -10.960608)
		(size 0.508)
		(drill 0.254)
		(layers "F.Cu" "B.Cu")
		(net "SMB_PCIE3_3V3AUX_SDA_R")
	)
	(segment
		(start 152.621742 -12.98702)
		(end 152.9969 -13.362178)
		(width 0.12954)
		(layer "B.Cu")
		(net "SMB_PCIE3_3V3AUX_SDA_R")
	)
	(segment
		(start 152.621742 -11.23315)
		(end 152.621742 -12.98702)
		(width 0.12954)
		(layer "B.Cu")
		(net "SMB_PCIE3_3V3AUX_SDA_R")
	)
	(segment
		(start 152.3492 -10.960608)
		(end 152.621742 -11.23315)
		(width 0.12954)
		(layer "B.Cu")
		(net "SMB_PCIE3_3V3AUX_SDA_R")
	)
	(segment
		(start 153.256996 -13.600176)
		(end 153.256996 -12.276836)
		(width 0.12954)
		(layer "F.Cu")
		(net "SMB_PCIE3_3V3AUX_SCL_R")
	)
	(segment
		(start 153.256996 -12.276836)
		(end 153.178002 -12.197842)
		(width 0.12954)
		(layer "F.Cu")
		(net "SMB_PCIE3_3V3AUX_SCL_R")
	)
	(via
		(at 153.178002 -12.197842)
		(size 0.508)
		(drill 0.254)
		(layers "F.Cu" "B.Cu")
		(net "SMB_PCIE3_3V3AUX_SCL_R")
	)
	(segment
		(start 153.178002 -12.197842)
		(end 154.00782 -13.02766)
		(width 0.12954)
		(layer "B.Cu")
		(net "SMB_PCIE3_3V3AUX_SCL_R")
	)
	(segment
		(start 154.00782 -13.02766)
		(end 154.00782 -13.362178)
		(width 0.12954)
		(layer "B.Cu")
		(net "SMB_PCIE3_3V3AUX_SCL_R")
	)
	(segment
		(start 156.856938 -13.600176)
		(end 156.856938 -12.232386)
		(width 0.12954)
		(layer "F.Cu")
		(net "SMB_PCIE2_3V3AUX_SDA_R0")
	)
	(segment
		(start 156.3116 -11.687048)
		(end 156.0576 -11.687048)
		(width 0.12954)
		(layer "F.Cu")
		(net "SMB_PCIE2_3V3AUX_SDA_R0")
	)
	(segment
		(start 156.856938 -12.232386)
		(end 156.3116 -11.687048)
		(width 0.12954)
		(layer "F.Cu")
		(net "SMB_PCIE2_3V3AUX_SDA_R0")
	)
	(via
		(at 156.0576 -11.687048)
		(size 0.508)
		(drill 0.254)
		(layers "F.Cu" "B.Cu")
		(net "SMB_PCIE2_3V3AUX_SDA_R0")
	)
	(segment
		(start 155.18638 -12.558268)
		(end 155.18638 -13.364718)
		(width 0.12954)
		(layer "B.Cu")
		(net "SMB_PCIE2_3V3AUX_SDA_R0")
	)
	(segment
		(start 156.0576 -11.687048)
		(end 155.18638 -12.558268)
		(width 0.12954)
		(layer "B.Cu")
		(net "SMB_PCIE2_3V3AUX_SDA_R0")
	)
	(segment
		(start 31.86938 -439.720228)
		(end 30.71114 -438.561988)
		(width 0.12954)
		(layer "F.Cu")
		(net "SMB_2_BMC_GPU_SDA")
	)
	(segment
		(start 32.380428 -439.720228)
		(end 31.86938 -439.720228)
		(width 0.12954)
		(layer "F.Cu")
		(net "SMB_2_BMC_GPU_SDA")
	)
	(segment
		(start 30.71114 -438.561988)
		(end 29.826204 -438.561988)
		(width 0.12954)
		(layer "F.Cu")
		(net "SMB_2_BMC_GPU_SDA")
	)
	(via
		(at 35.48888 -45.507148)
		(size 0.508)
		(drill 0.254)
		(layers "F.Cu" "B.Cu")
		(net "SMB_2_BMC_GPU_SDA")
	)
	(via
		(at 156.25318 -18.748248)
		(size 0.508)
		(drill 0.254)
		(layers "F.Cu" "B.Cu")
		(net "SMB_2_BMC_GPU_SDA")
	)
	(via
		(at 29.826204 -438.561988)
		(size 0.508)
		(drill 0.254)
		(layers "F.Cu" "B.Cu")
		(net "SMB_2_BMC_GPU_SDA")
	)
	(segment
		(start 156.274516 -16.067532)
		(end 156.738066 -16.067532)
		(width 0.12954)
		(layer "B.Cu")
		(net "SMB_2_BMC_GPU_SDA")
	)
	(segment
		(start 156.738066 -16.705072)
		(end 156.274516 -16.705072)
		(width 0.12954)
		(layer "B.Cu")
		(net "SMB_2_BMC_GPU_SDA")
	)
	(segment
		(start 156.867606 -16.834612)
		(end 156.738066 -16.705072)
		(width 0.12954)
		(layer "B.Cu")
		(net "SMB_2_BMC_GPU_SDA")
	)
	(segment
		(start 156.738066 -16.067532)
		(end 156.867606 -15.937992)
		(width 0.12954)
		(layer "B.Cu")
		(net "SMB_2_BMC_GPU_SDA")
	)
	(segment
		(start 156.867606 -15.937992)
		(end 156.867606 -15.083028)
		(width 0.12954)
		(layer "B.Cu")
		(net "SMB_2_BMC_GPU_SDA")
	)
	(segment
		(start 155.4353 -14.882368)
		(end 155.18638 -14.633448)
		(width 0.12954)
		(layer "B.Cu")
		(net "SMB_2_BMC_GPU_SDA")
	)
	(segment
		(start 156.274516 -16.705072)
		(end 156.144976 -16.575532)
		(width 0.12954)
		(layer "B.Cu")
		(net "SMB_2_BMC_GPU_SDA")
	)
	(segment
		(start 156.144976 -16.575532)
		(end 156.144976 -16.197072)
		(width 0.12954)
		(layer "B.Cu")
		(net "SMB_2_BMC_GPU_SDA")
	)
	(segment
		(start 156.25318 -18.748248)
		(end 156.867606 -18.133822)
		(width 0.12954)
		(layer "B.Cu")
		(net "SMB_2_BMC_GPU_SDA")
	)
	(segment
		(start 155.18638 -14.633448)
		(end 155.18638 -14.164818)
		(width 0.12954)
		(layer "B.Cu")
		(net "SMB_2_BMC_GPU_SDA")
	)
	(segment
		(start 156.144976 -16.197072)
		(end 156.274516 -16.067532)
		(width 0.12954)
		(layer "B.Cu")
		(net "SMB_2_BMC_GPU_SDA")
	)
	(segment
		(start 156.666946 -14.882368)
		(end 155.4353 -14.882368)
		(width 0.12954)
		(layer "B.Cu")
		(net "SMB_2_BMC_GPU_SDA")
	)
	(segment
		(start 156.867606 -18.133822)
		(end 156.867606 -16.834612)
		(width 0.12954)
		(layer "B.Cu")
		(net "SMB_2_BMC_GPU_SDA")
	)
	(segment
		(start 156.867606 -15.083028)
		(end 156.666946 -14.882368)
		(width 0.12954)
		(layer "B.Cu")
		(net "SMB_2_BMC_GPU_SDA")
	)
	(segment
		(start 33.302702 -47.789084)
		(end 33.302702 -48.170084)
		(width 0.127)
		(layer "In2.Cu")
		(net "SMB_2_BMC_GPU_SDA")
	)
	(segment
		(start 33.302702 -49.440084)
		(end 33.429702 -49.567084)
		(width 0.127)
		(layer "In2.Cu")
		(net "SMB_2_BMC_GPU_SDA")
	)
	(segment
		(start 34.47288 -49.567084)
		(end 34.59988 -49.694084)
		(width 0.127)
		(layer "In2.Cu")
		(net "SMB_2_BMC_GPU_SDA")
	)
	(segment
		(start 25.50922 -89.167208)
		(end 25.50922 -95.166688)
		(width 0.127)
		(layer "In2.Cu")
		(net "SMB_2_BMC_GPU_SDA")
	)
	(segment
		(start 34.59988 -48.424084)
		(end 34.59988 -48.805084)
		(width 0.127)
		(layer "In2.Cu")
		(net "SMB_2_BMC_GPU_SDA")
	)
	(segment
		(start 34.59988 -47.535084)
		(end 34.47288 -47.662084)
		(width 0.127)
		(layer "In2.Cu")
		(net "SMB_2_BMC_GPU_SDA")
	)
	(segment
		(start 16.47698 -114.868198)
		(end 16.28521 -114.868198)
		(width 0.127)
		(layer "In2.Cu")
		(net "SMB_2_BMC_GPU_SDA")
	)
	(segment
		(start 23.51786 -112.474248)
		(end 21.25726 -114.734848)
		(width 0.127)
		(layer "In2.Cu")
		(net "SMB_2_BMC_GPU_SDA")
	)
	(segment
		(start 14.9606 -171.265088)
		(end 11.88974 -174.335948)
		(width 0.127)
		(layer "In2.Cu")
		(net "SMB_2_BMC_GPU_SDA")
	)
	(segment
		(start 17.17802 -163.338256)
		(end 14.9606 -165.555676)
		(width 0.127)
		(layer "In2.Cu")
		(net "SMB_2_BMC_GPU_SDA")
	)
	(segment
		(start 34.47288 -50.202084)
		(end 33.429702 -50.202084)
		(width 0.127)
		(layer "In2.Cu")
		(net "SMB_2_BMC_GPU_SDA")
	)
	(segment
		(start 11.88974 -174.335948)
		(end 11.88974 -181.386988)
		(width 0.127)
		(layer "In2.Cu")
		(net "SMB_2_BMC_GPU_SDA")
	)
	(segment
		(start 14.9606 -165.555676)
		(end 14.9606 -171.265088)
		(width 0.127)
		(layer "In2.Cu")
		(net "SMB_2_BMC_GPU_SDA")
	)
	(segment
		(start 25.50922 -95.166688)
		(end 24.96566 -95.710248)
		(width 0.127)
		(layer "In2.Cu")
		(net "SMB_2_BMC_GPU_SDA")
	)
	(segment
		(start 34.59988 -51.345084)
		(end 34.47288 -51.472084)
		(width 0.127)
		(layer "In2.Cu")
		(net "SMB_2_BMC_GPU_SDA")
	)
	(segment
		(start 35.61588 -402.457158)
		(end 35.61588 -432.344576)
		(width 0.127)
		(layer "In2.Cu")
		(net "SMB_2_BMC_GPU_SDA")
	)
	(segment
		(start 34.59988 -52.234084)
		(end 34.59988 -80.076548)
		(width 0.127)
		(layer "In2.Cu")
		(net "SMB_2_BMC_GPU_SDA")
	)
	(segment
		(start 7.01548 -186.261248)
		(end 7.01548 -190.777622)
		(width 0.127)
		(layer "In2.Cu")
		(net "SMB_2_BMC_GPU_SDA")
	)
	(segment
		(start 24.96566 -95.710248)
		(end 24.96566 -100.574348)
		(width 0.127)
		(layer "In2.Cu")
		(net "SMB_2_BMC_GPU_SDA")
	)
	(segment
		(start 5.83438 -125.319028)
		(end 5.83438 -136.029446)
		(width 0.127)
		(layer "In2.Cu")
		(net "SMB_2_BMC_GPU_SDA")
	)
	(segment
		(start 34.47288 -48.932084)
		(end 33.429702 -48.932084)
		(width 0.127)
		(layer "In2.Cu")
		(net "SMB_2_BMC_GPU_SDA")
	)
	(segment
		(start 19.81708 -345.328748)
		(end 19.81708 -361.791758)
		(width 0.127)
		(layer "In2.Cu")
		(net "SMB_2_BMC_GPU_SDA")
	)
	(segment
		(start 8.255508 -192.01765)
		(end 8.255508 -195.089272)
		(width 0.127)
		(layer "In2.Cu")
		(net "SMB_2_BMC_GPU_SDA")
	)
	(segment
		(start 34.47288 -48.297084)
		(end 34.59988 -48.424084)
		(width 0.127)
		(layer "In2.Cu")
		(net "SMB_2_BMC_GPU_SDA")
	)
	(segment
		(start 19.81708 -361.791758)
		(end 33.49752 -375.472198)
		(width 0.127)
		(layer "In2.Cu")
		(net "SMB_2_BMC_GPU_SDA")
	)
	(segment
		(start 33.429702 -50.202084)
		(end 33.302702 -50.329084)
		(width 0.127)
		(layer "In2.Cu")
		(net "SMB_2_BMC_GPU_SDA")
	)
	(segment
		(start 33.302702 -51.980084)
		(end 33.429702 -52.107084)
		(width 0.127)
		(layer "In2.Cu")
		(net "SMB_2_BMC_GPU_SDA")
	)
	(segment
		(start 34.59988 -48.805084)
		(end 34.47288 -48.932084)
		(width 0.127)
		(layer "In2.Cu")
		(net "SMB_2_BMC_GPU_SDA")
	)
	(segment
		(start 23.51786 -102.022148)
		(end 23.51786 -112.474248)
		(width 0.127)
		(layer "In2.Cu")
		(net "SMB_2_BMC_GPU_SDA")
	)
	(segment
		(start 11.88974 -181.386988)
		(end 7.01548 -186.261248)
		(width 0.127)
		(layer "In2.Cu")
		(net "SMB_2_BMC_GPU_SDA")
	)
	(segment
		(start 33.429702 -52.107084)
		(end 34.47288 -52.107084)
		(width 0.127)
		(layer "In2.Cu")
		(net "SMB_2_BMC_GPU_SDA")
	)
	(segment
		(start 17.17802 -147.373086)
		(end 17.17802 -163.338256)
		(width 0.127)
		(layer "In2.Cu")
		(net "SMB_2_BMC_GPU_SDA")
	)
	(segment
		(start 33.429702 -51.472084)
		(end 33.302702 -51.599084)
		(width 0.127)
		(layer "In2.Cu")
		(net "SMB_2_BMC_GPU_SDA")
	)
	(segment
		(start 34.59988 -50.964084)
		(end 34.59988 -51.345084)
		(width 0.127)
		(layer "In2.Cu")
		(net "SMB_2_BMC_GPU_SDA")
	)
	(segment
		(start 34.47288 -51.472084)
		(end 33.429702 -51.472084)
		(width 0.127)
		(layer "In2.Cu")
		(net "SMB_2_BMC_GPU_SDA")
	)
	(segment
		(start 34.47288 -47.662084)
		(end 33.429702 -47.662084)
		(width 0.127)
		(layer "In2.Cu")
		(net "SMB_2_BMC_GPU_SDA")
	)
	(segment
		(start 33.302702 -51.599084)
		(end 33.302702 -51.980084)
		(width 0.127)
		(layer "In2.Cu")
		(net "SMB_2_BMC_GPU_SDA")
	)
	(segment
		(start 33.429702 -48.932084)
		(end 33.302702 -49.059084)
		(width 0.127)
		(layer "In2.Cu")
		(net "SMB_2_BMC_GPU_SDA")
	)
	(segment
		(start 35.61588 -432.344576)
		(end 29.826204 -438.134252)
		(width 0.127)
		(layer "In2.Cu")
		(net "SMB_2_BMC_GPU_SDA")
	)
	(segment
		(start 33.302702 -50.710084)
		(end 33.429702 -50.837084)
		(width 0.127)
		(layer "In2.Cu")
		(net "SMB_2_BMC_GPU_SDA")
	)
	(segment
		(start 33.302702 -48.170084)
		(end 33.429702 -48.297084)
		(width 0.127)
		(layer "In2.Cu")
		(net "SMB_2_BMC_GPU_SDA")
	)
	(segment
		(start 33.429702 -50.837084)
		(end 34.47288 -50.837084)
		(width 0.127)
		(layer "In2.Cu")
		(net "SMB_2_BMC_GPU_SDA")
	)
	(segment
		(start 33.49752 -375.472198)
		(end 33.49752 -400.338798)
		(width 0.127)
		(layer "In2.Cu")
		(net "SMB_2_BMC_GPU_SDA")
	)
	(segment
		(start 33.302702 -50.329084)
		(end 33.302702 -50.710084)
		(width 0.127)
		(layer "In2.Cu")
		(net "SMB_2_BMC_GPU_SDA")
	)
	(segment
		(start 34.47288 -50.837084)
		(end 34.59988 -50.964084)
		(width 0.127)
		(layer "In2.Cu")
		(net "SMB_2_BMC_GPU_SDA")
	)
	(segment
		(start 21.25726 -114.734848)
		(end 16.61033 -114.734848)
		(width 0.127)
		(layer "In2.Cu")
		(net "SMB_2_BMC_GPU_SDA")
	)
	(segment
		(start 6.29158 -197.0532)
		(end 6.29158 -331.803248)
		(width 0.127)
		(layer "In2.Cu")
		(net "SMB_2_BMC_GPU_SDA")
	)
	(segment
		(start 33.49752 -400.338798)
		(end 35.61588 -402.457158)
		(width 0.127)
		(layer "In2.Cu")
		(net "SMB_2_BMC_GPU_SDA")
	)
	(segment
		(start 33.302702 -49.059084)
		(end 33.302702 -49.440084)
		(width 0.127)
		(layer "In2.Cu")
		(net "SMB_2_BMC_GPU_SDA")
	)
	(segment
		(start 16.61033 -114.734848)
		(end 16.47698 -114.868198)
		(width 0.127)
		(layer "In2.Cu")
		(net "SMB_2_BMC_GPU_SDA")
	)
	(segment
		(start 34.59988 -50.075084)
		(end 34.47288 -50.202084)
		(width 0.127)
		(layer "In2.Cu")
		(net "SMB_2_BMC_GPU_SDA")
	)
	(segment
		(start 16.28521 -114.868198)
		(end 5.83438 -125.319028)
		(width 0.127)
		(layer "In2.Cu")
		(net "SMB_2_BMC_GPU_SDA")
	)
	(segment
		(start 5.83438 -136.029446)
		(end 17.17802 -147.373086)
		(width 0.127)
		(layer "In2.Cu")
		(net "SMB_2_BMC_GPU_SDA")
	)
	(segment
		(start 8.255508 -195.089272)
		(end 6.29158 -197.0532)
		(width 0.127)
		(layer "In2.Cu")
		(net "SMB_2_BMC_GPU_SDA")
	)
	(segment
		(start 6.29158 -331.803248)
		(end 19.81708 -345.328748)
		(width 0.127)
		(layer "In2.Cu")
		(net "SMB_2_BMC_GPU_SDA")
	)
	(segment
		(start 34.59988 -49.694084)
		(end 34.59988 -50.075084)
		(width 0.127)
		(layer "In2.Cu")
		(net "SMB_2_BMC_GPU_SDA")
	)
	(segment
		(start 7.01548 -190.777622)
		(end 8.255508 -192.01765)
		(width 0.127)
		(layer "In2.Cu")
		(net "SMB_2_BMC_GPU_SDA")
	)
	(segment
		(start 24.96566 -100.574348)
		(end 23.51786 -102.022148)
		(width 0.127)
		(layer "In2.Cu")
		(net "SMB_2_BMC_GPU_SDA")
	)
	(segment
		(start 35.48888 -45.507148)
		(end 34.59988 -46.396148)
		(width 0.127)
		(layer "In2.Cu")
		(net "SMB_2_BMC_GPU_SDA")
	)
	(segment
		(start 33.429702 -47.662084)
		(end 33.302702 -47.789084)
		(width 0.127)
		(layer "In2.Cu")
		(net "SMB_2_BMC_GPU_SDA")
	)
	(segment
		(start 34.59988 -80.076548)
		(end 25.50922 -89.167208)
		(width 0.127)
		(layer "In2.Cu")
		(net "SMB_2_BMC_GPU_SDA")
	)
	(segment
		(start 33.429702 -48.297084)
		(end 34.47288 -48.297084)
		(width 0.127)
		(layer "In2.Cu")
		(net "SMB_2_BMC_GPU_SDA")
	)
	(segment
		(start 34.47288 -52.107084)
		(end 34.59988 -52.234084)
		(width 0.127)
		(layer "In2.Cu")
		(net "SMB_2_BMC_GPU_SDA")
	)
	(segment
		(start 33.429702 -49.567084)
		(end 34.47288 -49.567084)
		(width 0.127)
		(layer "In2.Cu")
		(net "SMB_2_BMC_GPU_SDA")
	)
	(segment
		(start 34.59988 -46.396148)
		(end 34.59988 -47.535084)
		(width 0.127)
		(layer "In2.Cu")
		(net "SMB_2_BMC_GPU_SDA")
	)
	(segment
		(start 29.826204 -438.134252)
		(end 29.826204 -438.561988)
		(width 0.127)
		(layer "In2.Cu")
		(net "SMB_2_BMC_GPU_SDA")
	)
	(segment
		(start 152.099772 -16.982948)
		(end 154.48788 -16.982948)
		(width 0.127)
		(layer "In6.Cu")
		(net "SMB_2_BMC_GPU_SDA")
	)
	(segment
		(start 68.051426 -36.439348)
		(end 68.229226 -36.617148)
		(width 0.127)
		(layer "In6.Cu")
		(net "SMB_2_BMC_GPU_SDA")
	)
	(segment
		(start 122.73788 -30.825948)
		(end 130.725672 -30.825948)
		(width 0.127)
		(layer "In6.Cu")
		(net "SMB_2_BMC_GPU_SDA")
	)
	(segment
		(start 79.09687 -37.125148)
		(end 79.88427 -36.337748)
		(width 0.127)
		(layer "In6.Cu")
		(net "SMB_2_BMC_GPU_SDA")
	)
	(segment
		(start 79.88427 -36.337748)
		(end 88.9762 -36.337748)
		(width 0.127)
		(layer "In6.Cu")
		(net "SMB_2_BMC_GPU_SDA")
	)
	(segment
		(start 99.87788 -29.645356)
		(end 104.361488 -25.161748)
		(width 0.127)
		(layer "In6.Cu")
		(net "SMB_2_BMC_GPU_SDA")
	)
	(segment
		(start 145.038572 -24.044148)
		(end 152.099772 -16.982948)
		(width 0.127)
		(layer "In6.Cu")
		(net "SMB_2_BMC_GPU_SDA")
	)
	(segment
		(start 53.810408 -37.150548)
		(end 65.206626 -37.150548)
		(width 0.127)
		(layer "In6.Cu")
		(net "SMB_2_BMC_GPU_SDA")
	)
	(segment
		(start 130.725672 -30.825948)
		(end 137.507472 -24.044148)
		(width 0.127)
		(layer "In6.Cu")
		(net "SMB_2_BMC_GPU_SDA")
	)
	(segment
		(start 77.0636 -37.125148)
		(end 79.09687 -37.125148)
		(width 0.127)
		(layer "In6.Cu")
		(net "SMB_2_BMC_GPU_SDA")
	)
	(segment
		(start 116.51488 -24.602948)
		(end 122.73788 -30.825948)
		(width 0.127)
		(layer "In6.Cu")
		(net "SMB_2_BMC_GPU_SDA")
	)
	(segment
		(start 76.5556 -36.617148)
		(end 77.0636 -37.125148)
		(width 0.127)
		(layer "In6.Cu")
		(net "SMB_2_BMC_GPU_SDA")
	)
	(segment
		(start 154.48788 -16.982948)
		(end 156.25318 -18.748248)
		(width 0.127)
		(layer "In6.Cu")
		(net "SMB_2_BMC_GPU_SDA")
	)
	(segment
		(start 92.3798 -32.934148)
		(end 93.244924 -32.934148)
		(width 0.127)
		(layer "In6.Cu")
		(net "SMB_2_BMC_GPU_SDA")
	)
	(segment
		(start 35.48888 -45.507148)
		(end 45.453808 -45.507148)
		(width 0.127)
		(layer "In6.Cu")
		(net "SMB_2_BMC_GPU_SDA")
	)
	(segment
		(start 137.507472 -24.044148)
		(end 145.038572 -24.044148)
		(width 0.127)
		(layer "In6.Cu")
		(net "SMB_2_BMC_GPU_SDA")
	)
	(segment
		(start 88.9762 -36.337748)
		(end 92.3798 -32.934148)
		(width 0.127)
		(layer "In6.Cu")
		(net "SMB_2_BMC_GPU_SDA")
	)
	(segment
		(start 65.917826 -36.439348)
		(end 68.051426 -36.439348)
		(width 0.127)
		(layer "In6.Cu")
		(net "SMB_2_BMC_GPU_SDA")
	)
	(segment
		(start 99.87788 -32.476948)
		(end 99.87788 -29.645356)
		(width 0.127)
		(layer "In6.Cu")
		(net "SMB_2_BMC_GPU_SDA")
	)
	(segment
		(start 45.453808 -45.507148)
		(end 53.810408 -37.150548)
		(width 0.127)
		(layer "In6.Cu")
		(net "SMB_2_BMC_GPU_SDA")
	)
	(segment
		(start 68.229226 -36.617148)
		(end 76.5556 -36.617148)
		(width 0.127)
		(layer "In6.Cu")
		(net "SMB_2_BMC_GPU_SDA")
	)
	(segment
		(start 110.92688 -24.602948)
		(end 116.51488 -24.602948)
		(width 0.127)
		(layer "In6.Cu")
		(net "SMB_2_BMC_GPU_SDA")
	)
	(segment
		(start 65.206626 -37.150548)
		(end 65.917826 -36.439348)
		(width 0.127)
		(layer "In6.Cu")
		(net "SMB_2_BMC_GPU_SDA")
	)
	(segment
		(start 104.361488 -25.161748)
		(end 110.36808 -25.161748)
		(width 0.127)
		(layer "In6.Cu")
		(net "SMB_2_BMC_GPU_SDA")
	)
	(segment
		(start 98.44786 -33.906968)
		(end 99.87788 -32.476948)
		(width 0.127)
		(layer "In6.Cu")
		(net "SMB_2_BMC_GPU_SDA")
	)
	(segment
		(start 94.217744 -33.906968)
		(end 98.44786 -33.906968)
		(width 0.127)
		(layer "In6.Cu")
		(net "SMB_2_BMC_GPU_SDA")
	)
	(segment
		(start 110.36808 -25.161748)
		(end 110.92688 -24.602948)
		(width 0.127)
		(layer "In6.Cu")
		(net "SMB_2_BMC_GPU_SDA")
	)
	(segment
		(start 93.244924 -32.934148)
		(end 94.217744 -33.906968)
		(width 0.127)
		(layer "In6.Cu")
		(net "SMB_2_BMC_GPU_SDA")
	)
	(segment
		(start 157.45714 -12.583414)
		(end 157.368748 -12.495022)
		(width 0.12954)
		(layer "F.Cu")
		(net "SMB_PCIE2_3V3AUX_SCL_R0")
	)
	(segment
		(start 157.45714 -13.600176)
		(end 157.45714 -12.583414)
		(width 0.12954)
		(layer "F.Cu")
		(net "SMB_PCIE2_3V3AUX_SCL_R0")
	)
	(via
		(at 156.34462 -13.409168)
		(size 0.6604)
		(drill 0.3302)
		(layers "F.Cu" "B.Cu")
		(net "SMB_PCIE2_3V3AUX_SCL_R0")
	)
	(via
		(at 157.368748 -12.495022)
		(size 0.508)
		(drill 0.254)
		(layers "F.Cu" "B.Cu")
		(net "SMB_PCIE2_3V3AUX_SCL_R0")
	)
	(segment
		(start 157.368748 -12.495022)
		(end 157.258766 -12.495022)
		(width 0.12954)
		(layer "B.Cu")
		(net "SMB_PCIE2_3V3AUX_SCL_R0")
	)
	(segment
		(start 156.34462 -13.409168)
		(end 157.457648 -13.409168)
		(width 0.12954)
		(layer "B.Cu")
		(net "SMB_PCIE2_3V3AUX_SCL_R0")
	)
	(segment
		(start 157.258766 -12.495022)
		(end 156.34462 -13.409168)
		(width 0.12954)
		(layer "B.Cu")
		(net "SMB_PCIE2_3V3AUX_SCL_R0")
	)
	(segment
		(start 157.457648 -13.409168)
		(end 157.504638 -13.362178)
		(width 0.12954)
		(layer "B.Cu")
		(net "SMB_PCIE2_3V3AUX_SCL_R0")
	)
	(segment
		(start 47.043848 -440.187588)
		(end 50.5587 -440.187588)
		(width 0.12954)
		(layer "F.Cu")
		(net "SMB_2_BMC_GPU_SCL")
	)
	(segment
		(start 47.026068 -440.205368)
		(end 47.043848 -440.187588)
		(width 0.12954)
		(layer "F.Cu")
		(net "SMB_2_BMC_GPU_SCL")
	)
	(segment
		(start 50.5587 -440.187588)
		(end 50.5587 -438.513474)
		(width 0.12954)
		(layer "F.Cu")
		(net "SMB_2_BMC_GPU_SCL")
	)
	(via
		(at 35.94608 -46.091348)
		(size 0.508)
		(drill 0.254)
		(layers "F.Cu" "B.Cu")
		(net "SMB_2_BMC_GPU_SCL")
	)
	(via
		(at 50.5587 -438.513474)
		(size 0.508)
		(drill 0.254)
		(layers "F.Cu" "B.Cu")
		(net "SMB_2_BMC_GPU_SCL")
	)
	(via
		(at 156.26588 -19.522948)
		(size 0.508)
		(drill 0.254)
		(layers "F.Cu" "B.Cu")
		(net "SMB_2_BMC_GPU_SCL")
	)
	(segment
		(start 156.26588 -19.522948)
		(end 157.504638 -18.28419)
		(width 0.12954)
		(layer "B.Cu")
		(net "SMB_2_BMC_GPU_SCL")
	)
	(segment
		(start 157.504638 -18.28419)
		(end 157.504638 -14.162278)
		(width 0.12954)
		(layer "B.Cu")
		(net "SMB_2_BMC_GPU_SCL")
	)
	(segment
		(start 8.43788 -256.504948)
		(end 8.43788 -253.837948)
		(width 0.127)
		(layer "In2.Cu")
		(net "SMB_2_BMC_GPU_SCL")
	)
	(segment
		(start 26.34742 -95.395288)
		(end 26.34742 -88.939878)
		(width 0.127)
		(layer "In2.Cu")
		(net "SMB_2_BMC_GPU_SCL")
	)
	(segment
		(start 7.52348 -186.553348)
		(end 12.32154 -181.755288)
		(width 0.127)
		(layer "In2.Cu")
		(net "SMB_2_BMC_GPU_SCL")
	)
	(segment
		(start 21.49856 -115.166648)
		(end 24.29256 -112.372648)
		(width 0.127)
		(layer "In2.Cu")
		(net "SMB_2_BMC_GPU_SCL")
	)
	(segment
		(start 49.506886 -438.513474)
		(end 46.473872 -435.48046)
		(width 0.127)
		(layer "In2.Cu")
		(net "SMB_2_BMC_GPU_SCL")
	)
	(segment
		(start 12.32154 -174.515018)
		(end 15.3924 -171.444158)
		(width 0.127)
		(layer "In2.Cu")
		(net "SMB_2_BMC_GPU_SCL")
	)
	(segment
		(start 35.03168 -47.005748)
		(end 35.94608 -46.091348)
		(width 0.127)
		(layer "In2.Cu")
		(net "SMB_2_BMC_GPU_SCL")
	)
	(segment
		(start 50.5587 -438.513474)
		(end 49.506886 -438.513474)
		(width 0.127)
		(layer "In2.Cu")
		(net "SMB_2_BMC_GPU_SCL")
	)
	(segment
		(start 38.101778 -434.593238)
		(end 36.04768 -432.53914)
		(width 0.127)
		(layer "In2.Cu")
		(net "SMB_2_BMC_GPU_SCL")
	)
	(segment
		(start 7.43458 -332.335378)
		(end 7.43458 -325.338948)
		(width 0.127)
		(layer "In2.Cu")
		(net "SMB_2_BMC_GPU_SCL")
	)
	(segment
		(start 25.43302 -97.699068)
		(end 26.18232 -96.949768)
		(width 0.127)
		(layer "In2.Cu")
		(net "SMB_2_BMC_GPU_SCL")
	)
	(segment
		(start 33.92932 -400.159728)
		(end 33.92932 -375.293128)
		(width 0.127)
		(layer "In2.Cu")
		(net "SMB_2_BMC_GPU_SCL")
	)
	(segment
		(start 17.60982 -163.51758)
		(end 17.60982 -147.194016)
		(width 0.127)
		(layer "In2.Cu")
		(net "SMB_2_BMC_GPU_SCL")
	)
	(segment
		(start 20.24888 -345.149678)
		(end 7.43458 -332.335378)
		(width 0.127)
		(layer "In2.Cu")
		(net "SMB_2_BMC_GPU_SCL")
	)
	(segment
		(start 9.78154 -192.824608)
		(end 7.52348 -190.566548)
		(width 0.127)
		(layer "In2.Cu")
		(net "SMB_2_BMC_GPU_SCL")
	)
	(segment
		(start 8.43788 -253.837948)
		(end 9.78154 -252.494288)
		(width 0.127)
		(layer "In2.Cu")
		(net "SMB_2_BMC_GPU_SCL")
	)
	(segment
		(start 17.60982 -147.194016)
		(end 6.26618 -135.850376)
		(width 0.127)
		(layer "In2.Cu")
		(net "SMB_2_BMC_GPU_SCL")
	)
	(segment
		(start 26.18232 -95.560388)
		(end 26.34742 -95.395288)
		(width 0.127)
		(layer "In2.Cu")
		(net "SMB_2_BMC_GPU_SCL")
	)
	(segment
		(start 9.78154 -252.494288)
		(end 9.78154 -192.824608)
		(width 0.127)
		(layer "In2.Cu")
		(net "SMB_2_BMC_GPU_SCL")
	)
	(segment
		(start 25.43302 -100.868988)
		(end 25.43302 -97.699068)
		(width 0.127)
		(layer "In2.Cu")
		(net "SMB_2_BMC_GPU_SCL")
	)
	(segment
		(start 26.18232 -96.949768)
		(end 26.18232 -95.560388)
		(width 0.127)
		(layer "In2.Cu")
		(net "SMB_2_BMC_GPU_SCL")
	)
	(segment
		(start 12.32154 -181.755288)
		(end 12.32154 -174.515018)
		(width 0.127)
		(layer "In2.Cu")
		(net "SMB_2_BMC_GPU_SCL")
	)
	(segment
		(start 9.70788 -323.065648)
		(end 9.70788 -257.774948)
		(width 0.127)
		(layer "In2.Cu")
		(net "SMB_2_BMC_GPU_SCL")
	)
	(segment
		(start 24.29256 -102.009448)
		(end 25.43302 -100.868988)
		(width 0.127)
		(layer "In2.Cu")
		(net "SMB_2_BMC_GPU_SCL")
	)
	(segment
		(start 15.3924 -165.735)
		(end 17.60982 -163.51758)
		(width 0.127)
		(layer "In2.Cu")
		(net "SMB_2_BMC_GPU_SCL")
	)
	(segment
		(start 6.26618 -125.689868)
		(end 16.7894 -115.166648)
		(width 0.127)
		(layer "In2.Cu")
		(net "SMB_2_BMC_GPU_SCL")
	)
	(segment
		(start 7.43458 -325.338948)
		(end 9.70788 -323.065648)
		(width 0.127)
		(layer "In2.Cu")
		(net "SMB_2_BMC_GPU_SCL")
	)
	(segment
		(start 20.24888 -361.612688)
		(end 20.24888 -345.149678)
		(width 0.127)
		(layer "In2.Cu")
		(net "SMB_2_BMC_GPU_SCL")
	)
	(segment
		(start 15.3924 -171.444158)
		(end 15.3924 -165.735)
		(width 0.127)
		(layer "In2.Cu")
		(net "SMB_2_BMC_GPU_SCL")
	)
	(segment
		(start 35.03168 -80.255618)
		(end 35.03168 -47.005748)
		(width 0.127)
		(layer "In2.Cu")
		(net "SMB_2_BMC_GPU_SCL")
	)
	(segment
		(start 24.29256 -112.372648)
		(end 24.29256 -102.009448)
		(width 0.127)
		(layer "In2.Cu")
		(net "SMB_2_BMC_GPU_SCL")
	)
	(segment
		(start 36.04768 -432.53914)
		(end 36.04768 -402.278088)
		(width 0.127)
		(layer "In2.Cu")
		(net "SMB_2_BMC_GPU_SCL")
	)
	(segment
		(start 41.08323 -435.48046)
		(end 40.196008 -434.593238)
		(width 0.127)
		(layer "In2.Cu")
		(net "SMB_2_BMC_GPU_SCL")
	)
	(segment
		(start 7.52348 -190.566548)
		(end 7.52348 -186.553348)
		(width 0.127)
		(layer "In2.Cu")
		(net "SMB_2_BMC_GPU_SCL")
	)
	(segment
		(start 36.04768 -402.278088)
		(end 33.92932 -400.159728)
		(width 0.127)
		(layer "In2.Cu")
		(net "SMB_2_BMC_GPU_SCL")
	)
	(segment
		(start 6.26618 -135.850376)
		(end 6.26618 -125.689868)
		(width 0.127)
		(layer "In2.Cu")
		(net "SMB_2_BMC_GPU_SCL")
	)
	(segment
		(start 33.92932 -375.293128)
		(end 20.24888 -361.612688)
		(width 0.127)
		(layer "In2.Cu")
		(net "SMB_2_BMC_GPU_SCL")
	)
	(segment
		(start 46.473872 -435.48046)
		(end 41.08323 -435.48046)
		(width 0.127)
		(layer "In2.Cu")
		(net "SMB_2_BMC_GPU_SCL")
	)
	(segment
		(start 9.70788 -257.774948)
		(end 8.43788 -256.504948)
		(width 0.127)
		(layer "In2.Cu")
		(net "SMB_2_BMC_GPU_SCL")
	)
	(segment
		(start 26.34742 -88.939878)
		(end 35.03168 -80.255618)
		(width 0.127)
		(layer "In2.Cu")
		(net "SMB_2_BMC_GPU_SCL")
	)
	(segment
		(start 16.7894 -115.166648)
		(end 21.49856 -115.166648)
		(width 0.127)
		(layer "In2.Cu")
		(net "SMB_2_BMC_GPU_SCL")
	)
	(segment
		(start 40.196008 -434.593238)
		(end 38.101778 -434.593238)
		(width 0.127)
		(layer "In2.Cu")
		(net "SMB_2_BMC_GPU_SCL")
	)
	(segment
		(start 79.27594 -37.556948)
		(end 76.835 -37.556948)
		(width 0.127)
		(layer "In6.Cu")
		(net "SMB_2_BMC_GPU_SCL")
	)
	(segment
		(start 76.835 -37.556948)
		(end 76.4286 -37.150548)
		(width 0.127)
		(layer "In6.Cu")
		(net "SMB_2_BMC_GPU_SCL")
	)
	(segment
		(start 100.30968 -29.824426)
		(end 100.30968 -32.656018)
		(width 0.127)
		(layer "In6.Cu")
		(net "SMB_2_BMC_GPU_SCL")
	)
	(segment
		(start 53.989478 -37.582348)
		(end 45.480478 -46.091348)
		(width 0.127)
		(layer "In6.Cu")
		(net "SMB_2_BMC_GPU_SCL")
	)
	(segment
		(start 66.17208 -36.871148)
		(end 65.46088 -37.582348)
		(width 0.127)
		(layer "In6.Cu")
		(net "SMB_2_BMC_GPU_SCL")
	)
	(segment
		(start 140.276326 -24.602948)
		(end 140.276326 -25.122124)
		(width 0.127)
		(layer "In6.Cu")
		(net "SMB_2_BMC_GPU_SCL")
	)
	(segment
		(start 68.12788 -37.150548)
		(end 67.84848 -36.871148)
		(width 0.127)
		(layer "In6.Cu")
		(net "SMB_2_BMC_GPU_SCL")
	)
	(segment
		(start 140.276326 -25.122124)
		(end 140.149326 -25.249124)
		(width 0.127)
		(layer "In6.Cu")
		(net "SMB_2_BMC_GPU_SCL")
	)
	(segment
		(start 151.466042 -18.227548)
		(end 145.217642 -24.475948)
		(width 0.127)
		(layer "In6.Cu")
		(net "SMB_2_BMC_GPU_SCL")
	)
	(segment
		(start 154.97048 -18.227548)
		(end 151.466042 -18.227548)
		(width 0.127)
		(layer "In6.Cu")
		(net "SMB_2_BMC_GPU_SCL")
	)
	(segment
		(start 156.26588 -19.522948)
		(end 154.97048 -18.227548)
		(width 0.127)
		(layer "In6.Cu")
		(net "SMB_2_BMC_GPU_SCL")
	)
	(segment
		(start 116.33581 -25.034748)
		(end 111.10595 -25.034748)
		(width 0.127)
		(layer "In6.Cu")
		(net "SMB_2_BMC_GPU_SCL")
	)
	(segment
		(start 76.4286 -37.150548)
		(end 68.12788 -37.150548)
		(width 0.127)
		(layer "In6.Cu")
		(net "SMB_2_BMC_GPU_SCL")
	)
	(segment
		(start 122.55881 -31.257748)
		(end 116.33581 -25.034748)
		(width 0.127)
		(layer "In6.Cu")
		(net "SMB_2_BMC_GPU_SCL")
	)
	(segment
		(start 140.149326 -25.249124)
		(end 139.768326 -25.249124)
		(width 0.127)
		(layer "In6.Cu")
		(net "SMB_2_BMC_GPU_SCL")
	)
	(segment
		(start 98.62693 -34.338768)
		(end 93.99651 -34.338768)
		(width 0.127)
		(layer "In6.Cu")
		(net "SMB_2_BMC_GPU_SCL")
	)
	(segment
		(start 93.20149 -33.543748)
		(end 92.5322 -33.543748)
		(width 0.127)
		(layer "In6.Cu")
		(net "SMB_2_BMC_GPU_SCL")
	)
	(segment
		(start 89.3064 -36.769548)
		(end 80.06334 -36.769548)
		(width 0.127)
		(layer "In6.Cu")
		(net "SMB_2_BMC_GPU_SCL")
	)
	(segment
		(start 137.708132 -24.475948)
		(end 130.926332 -31.257748)
		(width 0.127)
		(layer "In6.Cu")
		(net "SMB_2_BMC_GPU_SCL")
	)
	(segment
		(start 140.403326 -24.475948)
		(end 140.276326 -24.602948)
		(width 0.127)
		(layer "In6.Cu")
		(net "SMB_2_BMC_GPU_SCL")
	)
	(segment
		(start 139.641326 -25.122124)
		(end 139.641326 -24.602948)
		(width 0.127)
		(layer "In6.Cu")
		(net "SMB_2_BMC_GPU_SCL")
	)
	(segment
		(start 67.84848 -36.871148)
		(end 66.17208 -36.871148)
		(width 0.127)
		(layer "In6.Cu")
		(net "SMB_2_BMC_GPU_SCL")
	)
	(segment
		(start 130.926332 -31.257748)
		(end 122.55881 -31.257748)
		(width 0.127)
		(layer "In6.Cu")
		(net "SMB_2_BMC_GPU_SCL")
	)
	(segment
		(start 100.30968 -32.656018)
		(end 98.62693 -34.338768)
		(width 0.127)
		(layer "In6.Cu")
		(net "SMB_2_BMC_GPU_SCL")
	)
	(segment
		(start 139.641326 -24.602948)
		(end 139.514326 -24.475948)
		(width 0.127)
		(layer "In6.Cu")
		(net "SMB_2_BMC_GPU_SCL")
	)
	(segment
		(start 93.99651 -34.338768)
		(end 93.20149 -33.543748)
		(width 0.127)
		(layer "In6.Cu")
		(net "SMB_2_BMC_GPU_SCL")
	)
	(segment
		(start 139.514326 -24.475948)
		(end 137.708132 -24.475948)
		(width 0.127)
		(layer "In6.Cu")
		(net "SMB_2_BMC_GPU_SCL")
	)
	(segment
		(start 110.54715 -25.593548)
		(end 104.540558 -25.593548)
		(width 0.127)
		(layer "In6.Cu")
		(net "SMB_2_BMC_GPU_SCL")
	)
	(segment
		(start 65.46088 -37.582348)
		(end 53.989478 -37.582348)
		(width 0.127)
		(layer "In6.Cu")
		(net "SMB_2_BMC_GPU_SCL")
	)
	(segment
		(start 139.768326 -25.249124)
		(end 139.641326 -25.122124)
		(width 0.127)
		(layer "In6.Cu")
		(net "SMB_2_BMC_GPU_SCL")
	)
	(segment
		(start 92.5322 -33.543748)
		(end 89.3064 -36.769548)
		(width 0.127)
		(layer "In6.Cu")
		(net "SMB_2_BMC_GPU_SCL")
	)
	(segment
		(start 145.217642 -24.475948)
		(end 140.403326 -24.475948)
		(width 0.127)
		(layer "In6.Cu")
		(net "SMB_2_BMC_GPU_SCL")
	)
	(segment
		(start 104.540558 -25.593548)
		(end 100.30968 -29.824426)
		(width 0.127)
		(layer "In6.Cu")
		(net "SMB_2_BMC_GPU_SCL")
	)
	(segment
		(start 80.06334 -36.769548)
		(end 79.27594 -37.556948)
		(width 0.127)
		(layer "In6.Cu")
		(net "SMB_2_BMC_GPU_SCL")
	)
	(segment
		(start 111.10595 -25.034748)
		(end 110.54715 -25.593548)
		(width 0.127)
		(layer "In6.Cu")
		(net "SMB_2_BMC_GPU_SCL")
	)
	(segment
		(start 45.480478 -46.091348)
		(end 35.94608 -46.091348)
		(width 0.127)
		(layer "In6.Cu")
		(net "SMB_2_BMC_GPU_SCL")
	)
	(segment
		(start 116.471192 -132.996432)
		(end 118.108476 -132.996432)
		(width 0.12954)
		(layer "F.Cu")
		(net "SMB_PCIE0_3V3AUX_SDA_R3")
	)
	(segment
		(start 116.193824 -132.719064)
		(end 116.471192 -132.996432)
		(width 0.12954)
		(layer "F.Cu")
		(net "SMB_PCIE0_3V3AUX_SDA_R3")
	)
	(segment
		(start 113.894362 -131.440682)
		(end 115.172744 -132.719064)
		(width 0.12954)
		(layer "F.Cu")
		(net "SMB_PCIE0_3V3AUX_SDA_R3")
	)
	(segment
		(start 115.172744 -132.719064)
		(end 116.193824 -132.719064)
		(width 0.12954)
		(layer "F.Cu")
		(net "SMB_PCIE0_3V3AUX_SDA_R3")
	)
	(via
		(at 116.193824 -132.719064)
		(size 0.508)
		(drill 0.254)
		(layers "F.Cu" "B.Cu")
		(net "SMB_PCIE0_3V3AUX_SDA_R3")
	)
	(segment
		(start 124.689362 -136.896602)
		(end 123.708668 -136.896602)
		(width 0.12954)
		(layer "F.Cu")
		(net "SMB_PCIE0_3V3AUX_SDA_R")
	)
	(segment
		(start 133.30428 -138.511026)
		(end 132.763768 -138.511026)
		(width 0.12954)
		(layer "F.Cu")
		(net "SMB_PCIE0_3V3AUX_SDA_R")
	)
	(segment
		(start 132.763768 -138.511026)
		(end 131.228846 -140.045948)
		(width 0.12954)
		(layer "F.Cu")
		(net "SMB_PCIE0_3V3AUX_SDA_R")
	)
	(segment
		(start 127.838708 -140.045948)
		(end 124.689362 -136.896602)
		(width 0.12954)
		(layer "F.Cu")
		(net "SMB_PCIE0_3V3AUX_SDA_R")
	)
	(segment
		(start 131.228846 -140.045948)
		(end 127.838708 -140.045948)
		(width 0.12954)
		(layer "F.Cu")
		(net "SMB_PCIE0_3V3AUX_SDA_R")
	)
	(via
		(at 148.89099 -92.270834)
		(size 0.508)
		(drill 0.254)
		(layers "F.Cu" "B.Cu")
		(net "SMB_PCIE0_3V3AUX_SDA_R")
	)
	(via
		(at 161.4932 -11.623548)
		(size 0.6604)
		(drill 0.3302)
		(layers "F.Cu" "B.Cu")
		(net "SMB_PCIE0_3V3AUX_SDA_R")
	)
	(via
		(at 133.30428 -138.511026)
		(size 0.508)
		(drill 0.254)
		(layers "F.Cu" "B.Cu")
		(net "SMB_PCIE0_3V3AUX_SDA_R")
	)
	(via
		(at 159.97428 -11.445748)
		(size 0.508)
		(drill 0.254)
		(layers "F.Cu" "B.Cu")
		(net "SMB_PCIE0_3V3AUX_SDA_R")
	)
	(segment
		(start 148.89099 -105.298494)
		(end 143.218916 -110.970568)
		(width 0.12954)
		(layer "B.Cu")
		(net "SMB_PCIE0_3V3AUX_SDA_R")
	)
	(segment
		(start 162.43935 -9.572498)
		(end 162.43935 -11.261598)
		(width 0.12954)
		(layer "B.Cu")
		(net "SMB_PCIE0_3V3AUX_SDA_R")
	)
	(segment
		(start 135.28548 -138.521948)
		(end 133.315202 -138.521948)
		(width 0.12954)
		(layer "B.Cu")
		(net "SMB_PCIE0_3V3AUX_SDA_R")
	)
	(segment
		(start 162.0774 -11.623548)
		(end 161.4932 -11.623548)
		(width 0.12954)
		(layer "B.Cu")
		(net "SMB_PCIE0_3V3AUX_SDA_R")
	)
	(segment
		(start 161.4932 -11.623548)
		(end 160.15208 -11.623548)
		(width 0.12954)
		(layer "B.Cu")
		(net "SMB_PCIE0_3V3AUX_SDA_R")
	)
	(segment
		(start 163.494974 -8.516874)
		(end 162.43935 -9.572498)
		(width 0.12954)
		(layer "B.Cu")
		(net "SMB_PCIE0_3V3AUX_SDA_R")
	)
	(segment
		(start 160.15208 -11.623548)
		(end 159.97428 -11.445748)
		(width 0.12954)
		(layer "B.Cu")
		(net "SMB_PCIE0_3V3AUX_SDA_R")
	)
	(segment
		(start 163.851082 -8.516874)
		(end 163.494974 -8.516874)
		(width 0.12954)
		(layer "B.Cu")
		(net "SMB_PCIE0_3V3AUX_SDA_R")
	)
	(segment
		(start 137.36828 -125.348492)
		(end 137.36828 -136.439148)
		(width 0.12954)
		(layer "B.Cu")
		(net "SMB_PCIE0_3V3AUX_SDA_R")
	)
	(segment
		(start 143.218916 -110.970568)
		(end 143.218916 -119.497856)
		(width 0.12954)
		(layer "B.Cu")
		(net "SMB_PCIE0_3V3AUX_SDA_R")
	)
	(segment
		(start 143.218916 -119.497856)
		(end 137.36828 -125.348492)
		(width 0.12954)
		(layer "B.Cu")
		(net "SMB_PCIE0_3V3AUX_SDA_R")
	)
	(segment
		(start 133.315202 -138.521948)
		(end 133.30428 -138.511026)
		(width 0.12954)
		(layer "B.Cu")
		(net "SMB_PCIE0_3V3AUX_SDA_R")
	)
	(segment
		(start 137.36828 -136.439148)
		(end 135.28548 -138.521948)
		(width 0.12954)
		(layer "B.Cu")
		(net "SMB_PCIE0_3V3AUX_SDA_R")
	)
	(segment
		(start 148.89099 -92.270834)
		(end 148.89099 -105.298494)
		(width 0.12954)
		(layer "B.Cu")
		(net "SMB_PCIE0_3V3AUX_SDA_R")
	)
	(segment
		(start 162.43935 -11.261598)
		(end 162.0774 -11.623548)
		(width 0.12954)
		(layer "B.Cu")
		(net "SMB_PCIE0_3V3AUX_SDA_R")
	)
	(segment
		(start 152.562814 -14.138148)
		(end 156.87548 -14.138148)
		(width 0.127)
		(layer "In2.Cu")
		(net "SMB_PCIE0_3V3AUX_SDA_R")
	)
	(segment
		(start 157.38348 -11.775948)
		(end 157.38348 -11.150092)
		(width 0.127)
		(layer "In2.Cu")
		(net "SMB_PCIE0_3V3AUX_SDA_R")
	)
	(segment
		(start 148.75256 -40.869108)
		(end 148.0947 -40.211248)
		(width 0.127)
		(layer "In2.Cu")
		(net "SMB_PCIE0_3V3AUX_SDA_R")
	)
	(segment
		(start 148.89099 -92.270834)
		(end 149.124924 -92.0369)
		(width 0.127)
		(layer "In2.Cu")
		(net "SMB_PCIE0_3V3AUX_SDA_R")
	)
	(segment
		(start 157.91688 -12.309348)
		(end 157.38348 -11.775948)
		(width 0.127)
		(layer "In2.Cu")
		(net "SMB_PCIE0_3V3AUX_SDA_R")
	)
	(segment
		(start 149.124924 -92.0369)
		(end 149.124924 -91.104212)
		(width 0.127)
		(layer "In2.Cu")
		(net "SMB_PCIE0_3V3AUX_SDA_R")
	)
	(segment
		(start 148.75256 -35.410648)
		(end 148.75256 -17.948402)
		(width 0.127)
		(layer "In2.Cu")
		(net "SMB_PCIE0_3V3AUX_SDA_R")
	)
	(segment
		(start 148.31568 -90.294968)
		(end 148.31568 -82.003392)
		(width 0.127)
		(layer "In2.Cu")
		(net "SMB_PCIE0_3V3AUX_SDA_R")
	)
	(segment
		(start 146.43608 -59.781948)
		(end 146.43608 -45.026072)
		(width 0.127)
		(layer "In2.Cu")
		(net "SMB_PCIE0_3V3AUX_SDA_R")
	)
	(segment
		(start 148.31568 -82.003392)
		(end 146.21002 -79.897732)
		(width 0.127)
		(layer "In2.Cu")
		(net "SMB_PCIE0_3V3AUX_SDA_R")
	)
	(segment
		(start 148.0947 -40.211248)
		(end 148.0947 -36.068508)
		(width 0.127)
		(layer "In2.Cu")
		(net "SMB_PCIE0_3V3AUX_SDA_R")
	)
	(segment
		(start 149.124924 -91.104212)
		(end 148.31568 -90.294968)
		(width 0.127)
		(layer "In2.Cu")
		(net "SMB_PCIE0_3V3AUX_SDA_R")
	)
	(segment
		(start 157.91688 -13.096748)
		(end 157.91688 -12.309348)
		(width 0.127)
		(layer "In2.Cu")
		(net "SMB_PCIE0_3V3AUX_SDA_R")
	)
	(segment
		(start 146.43608 -45.026072)
		(end 148.75256 -42.709592)
		(width 0.127)
		(layer "In2.Cu")
		(net "SMB_PCIE0_3V3AUX_SDA_R")
	)
	(segment
		(start 146.21002 -79.897732)
		(end 146.21002 -71.058532)
		(width 0.127)
		(layer "In2.Cu")
		(net "SMB_PCIE0_3V3AUX_SDA_R")
	)
	(segment
		(start 148.739606 -62.085474)
		(end 146.43608 -59.781948)
		(width 0.127)
		(layer "In2.Cu")
		(net "SMB_PCIE0_3V3AUX_SDA_R")
	)
	(segment
		(start 148.0947 -36.068508)
		(end 148.75256 -35.410648)
		(width 0.127)
		(layer "In2.Cu")
		(net "SMB_PCIE0_3V3AUX_SDA_R")
	)
	(segment
		(start 148.75256 -42.709592)
		(end 148.75256 -40.869108)
		(width 0.127)
		(layer "In2.Cu")
		(net "SMB_PCIE0_3V3AUX_SDA_R")
	)
	(segment
		(start 159.67456 -11.445748)
		(end 159.97428 -11.445748)
		(width 0.127)
		(layer "In2.Cu")
		(net "SMB_PCIE0_3V3AUX_SDA_R")
	)
	(segment
		(start 148.739606 -68.528946)
		(end 148.739606 -62.085474)
		(width 0.127)
		(layer "In2.Cu")
		(net "SMB_PCIE0_3V3AUX_SDA_R")
	)
	(segment
		(start 156.87548 -14.138148)
		(end 157.91688 -13.096748)
		(width 0.127)
		(layer "In2.Cu")
		(net "SMB_PCIE0_3V3AUX_SDA_R")
	)
	(segment
		(start 148.75256 -17.948402)
		(end 152.562814 -14.138148)
		(width 0.127)
		(layer "In2.Cu")
		(net "SMB_PCIE0_3V3AUX_SDA_R")
	)
	(segment
		(start 146.21002 -71.058532)
		(end 148.739606 -68.528946)
		(width 0.127)
		(layer "In2.Cu")
		(net "SMB_PCIE0_3V3AUX_SDA_R")
	)
	(segment
		(start 157.722824 -10.810748)
		(end 159.03956 -10.810748)
		(width 0.127)
		(layer "In2.Cu")
		(net "SMB_PCIE0_3V3AUX_SDA_R")
	)
	(segment
		(start 157.38348 -11.150092)
		(end 157.722824 -10.810748)
		(width 0.127)
		(layer "In2.Cu")
		(net "SMB_PCIE0_3V3AUX_SDA_R")
	)
	(segment
		(start 159.03956 -10.810748)
		(end 159.67456 -11.445748)
		(width 0.127)
		(layer "In2.Cu")
		(net "SMB_PCIE0_3V3AUX_SDA_R")
	)
	(segment
		(start 165.06698 -12.683998)
		(end 165.066726 -12.683744)
		(width 0.12954)
		(layer "F.Cu")
		(net "SMB_PCIE0_3V3AUX_SDA")
	)
	(segment
		(start 165.066726 -12.683744)
		(end 165.066726 -10.752836)
		(width 0.12954)
		(layer "F.Cu")
		(net "SMB_PCIE0_3V3AUX_SDA")
	)
	(segment
		(start 165.066726 -10.752836)
		(end 164.875718 -10.561828)
		(width 0.12954)
		(layer "F.Cu")
		(net "SMB_PCIE0_3V3AUX_SDA")
	)
	(segment
		(start 165.06698 -13.600176)
		(end 165.06698 -12.683998)
		(width 0.12954)
		(layer "F.Cu")
		(net "SMB_PCIE0_3V3AUX_SDA")
	)
	(segment
		(start 164.875718 -10.561828)
		(end 163.68776 -10.561828)
		(width 0.12954)
		(layer "F.Cu")
		(net "SMB_PCIE0_3V3AUX_SDA")
	)
	(segment
		(start 163.68776 -10.561828)
		(end 163.54552 -10.704068)
		(width 0.12954)
		(layer "F.Cu")
		(net "SMB_PCIE0_3V3AUX_SDA")
	)
	(via
		(at 163.54552 -10.704068)
		(size 0.508)
		(drill 0.254)
		(layers "F.Cu" "B.Cu")
		(net "SMB_PCIE0_3V3AUX_SDA")
	)
	(segment
		(start 164.857938 -9.31799)
		(end 164.856922 -9.316974)
		(width 0.12954)
		(layer "B.Cu")
		(net "SMB_PCIE0_3V3AUX_SDA")
	)
	(segment
		(start 163.54552 -10.704068)
		(end 163.851082 -10.398506)
		(width 0.12954)
		(layer "B.Cu")
		(net "SMB_PCIE0_3V3AUX_SDA")
	)
	(segment
		(start 163.851082 -10.398506)
		(end 163.851082 -9.316974)
		(width 0.12954)
		(layer "B.Cu")
		(net "SMB_PCIE0_3V3AUX_SDA")
	)
	(segment
		(start 164.856922 -9.316974)
		(end 163.851082 -9.316974)
		(width 0.12954)
		(layer "B.Cu")
		(net "SMB_PCIE0_3V3AUX_SDA")
	)
	(segment
		(start 116.752878 -132.346446)
		(end 115.23472 -130.828288)
		(width 0.12954)
		(layer "F.Cu")
		(net "SMB_PCIE0_3V3AUX_SCL_R3")
	)
	(segment
		(start 115.23472 -130.828288)
		(end 114.297968 -130.828288)
		(width 0.12954)
		(layer "F.Cu")
		(net "SMB_PCIE0_3V3AUX_SCL_R3")
	)
	(segment
		(start 114.297968 -130.828288)
		(end 113.894362 -130.424682)
		(width 0.12954)
		(layer "F.Cu")
		(net "SMB_PCIE0_3V3AUX_SCL_R3")
	)
	(segment
		(start 118.108476 -132.346446)
		(end 116.752878 -132.346446)
		(width 0.12954)
		(layer "F.Cu")
		(net "SMB_PCIE0_3V3AUX_SCL_R3")
	)
	(via
		(at 115.23472 -130.828288)
		(size 0.508)
		(drill 0.254)
		(layers "F.Cu" "B.Cu")
		(net "SMB_PCIE0_3V3AUX_SCL_R3")
	)
	(segment
		(start 132.31368 -138.130026)
		(end 126.684786 -138.130026)
		(width 0.12954)
		(layer "F.Cu")
		(net "SMB_PCIE0_3V3AUX_SCL_R")
	)
	(segment
		(start 126.684786 -138.130026)
		(end 124.801376 -136.246616)
		(width 0.12954)
		(layer "F.Cu")
		(net "SMB_PCIE0_3V3AUX_SCL_R")
	)
	(segment
		(start 133.32968 -137.114026)
		(end 132.31368 -138.130026)
		(width 0.12954)
		(layer "F.Cu")
		(net "SMB_PCIE0_3V3AUX_SCL_R")
	)
	(segment
		(start 124.801376 -136.246616)
		(end 123.708668 -136.246616)
		(width 0.12954)
		(layer "F.Cu")
		(net "SMB_PCIE0_3V3AUX_SCL_R")
	)
	(via
		(at 155.39974 -8.7376)
		(size 0.508)
		(drill 0.254)
		(layers "F.Cu" "B.Cu")
		(net "SMB_PCIE0_3V3AUX_SCL_R")
	)
	(via
		(at 148.25599 -92.270834)
		(size 0.508)
		(drill 0.254)
		(layers "F.Cu" "B.Cu")
		(net "SMB_PCIE0_3V3AUX_SCL_R")
	)
	(via
		(at 133.32968 -137.114026)
		(size 0.508)
		(drill 0.254)
		(layers "F.Cu" "B.Cu")
		(net "SMB_PCIE0_3V3AUX_SCL_R")
	)
	(segment
		(start 135.61568 -137.099548)
		(end 136.73328 -135.981948)
		(width 0.12954)
		(layer "B.Cu")
		(net "SMB_PCIE0_3V3AUX_SCL_R")
	)
	(segment
		(start 148.12645 -95.944944)
		(end 147.845018 -95.944944)
		(width 0.12954)
		(layer "B.Cu")
		(net "SMB_PCIE0_3V3AUX_SCL_R")
	)
	(segment
		(start 148.25599 -94.799404)
		(end 148.12645 -94.669864)
		(width 0.12954)
		(layer "B.Cu")
		(net "SMB_PCIE0_3V3AUX_SCL_R")
	)
	(segment
		(start 136.73328 -125.334268)
		(end 142.72768 -119.339868)
		(width 0.12954)
		(layer "B.Cu")
		(net "SMB_PCIE0_3V3AUX_SCL_R")
	)
	(segment
		(start 142.72768 -119.339868)
		(end 142.72768 -110.817152)
		(width 0.12954)
		(layer "B.Cu")
		(net "SMB_PCIE0_3V3AUX_SCL_R")
	)
	(segment
		(start 148.12645 -95.307404)
		(end 148.25599 -95.177864)
		(width 0.12954)
		(layer "B.Cu")
		(net "SMB_PCIE0_3V3AUX_SCL_R")
	)
	(segment
		(start 147.715478 -94.161864)
		(end 147.845018 -94.032324)
		(width 0.12954)
		(layer "B.Cu")
		(net "SMB_PCIE0_3V3AUX_SCL_R")
	)
	(segment
		(start 148.25599 -105.288842)
		(end 148.25599 -96.074484)
		(width 0.12954)
		(layer "B.Cu")
		(net "SMB_PCIE0_3V3AUX_SCL_R")
	)
	(segment
		(start 148.25599 -96.074484)
		(end 148.12645 -95.944944)
		(width 0.12954)
		(layer "B.Cu")
		(net "SMB_PCIE0_3V3AUX_SCL_R")
	)
	(segment
		(start 156.4005 -9.830308)
		(end 156.62783 -9.830308)
		(width 0.12954)
		(layer "B.Cu")
		(net "SMB_PCIE0_3V3AUX_SCL_R")
	)
	(segment
		(start 148.25599 -95.177864)
		(end 148.25599 -94.799404)
		(width 0.12954)
		(layer "B.Cu")
		(net "SMB_PCIE0_3V3AUX_SCL_R")
	)
	(segment
		(start 147.715478 -95.436944)
		(end 147.845018 -95.307404)
		(width 0.12954)
		(layer "B.Cu")
		(net "SMB_PCIE0_3V3AUX_SCL_R")
	)
	(segment
		(start 142.72768 -110.817152)
		(end 148.25599 -105.288842)
		(width 0.12954)
		(layer "B.Cu")
		(net "SMB_PCIE0_3V3AUX_SCL_R")
	)
	(segment
		(start 155.39974 -8.829548)
		(end 156.4005 -9.830308)
		(width 0.12954)
		(layer "B.Cu")
		(net "SMB_PCIE0_3V3AUX_SCL_R")
	)
	(segment
		(start 136.73328 -135.981948)
		(end 136.73328 -125.334268)
		(width 0.12954)
		(layer "B.Cu")
		(net "SMB_PCIE0_3V3AUX_SCL_R")
	)
	(segment
		(start 147.715478 -94.540324)
		(end 147.715478 -94.161864)
		(width 0.12954)
		(layer "B.Cu")
		(net "SMB_PCIE0_3V3AUX_SCL_R")
	)
	(segment
		(start 147.845018 -95.307404)
		(end 148.12645 -95.307404)
		(width 0.12954)
		(layer "B.Cu")
		(net "SMB_PCIE0_3V3AUX_SCL_R")
	)
	(segment
		(start 155.39974 -8.7376)
		(end 155.39974 -8.829548)
		(width 0.12954)
		(layer "B.Cu")
		(net "SMB_PCIE0_3V3AUX_SCL_R")
	)
	(segment
		(start 147.845018 -94.669864)
		(end 147.715478 -94.540324)
		(width 0.12954)
		(layer "B.Cu")
		(net "SMB_PCIE0_3V3AUX_SCL_R")
	)
	(segment
		(start 147.845018 -94.032324)
		(end 148.12645 -94.032324)
		(width 0.12954)
		(layer "B.Cu")
		(net "SMB_PCIE0_3V3AUX_SCL_R")
	)
	(segment
		(start 148.12645 -94.669864)
		(end 147.845018 -94.669864)
		(width 0.12954)
		(layer "B.Cu")
		(net "SMB_PCIE0_3V3AUX_SCL_R")
	)
	(segment
		(start 133.32968 -137.114026)
		(end 133.344158 -137.099548)
		(width 0.12954)
		(layer "B.Cu")
		(net "SMB_PCIE0_3V3AUX_SCL_R")
	)
	(segment
		(start 148.25599 -93.902784)
		(end 148.25599 -92.270834)
		(width 0.12954)
		(layer "B.Cu")
		(net "SMB_PCIE0_3V3AUX_SCL_R")
	)
	(segment
		(start 133.344158 -137.099548)
		(end 135.61568 -137.099548)
		(width 0.12954)
		(layer "B.Cu")
		(net "SMB_PCIE0_3V3AUX_SCL_R")
	)
	(segment
		(start 148.12645 -94.032324)
		(end 148.25599 -93.902784)
		(width 0.12954)
		(layer "B.Cu")
		(net "SMB_PCIE0_3V3AUX_SCL_R")
	)
	(segment
		(start 147.715478 -95.815404)
		(end 147.715478 -95.436944)
		(width 0.12954)
		(layer "B.Cu")
		(net "SMB_PCIE0_3V3AUX_SCL_R")
	)
	(segment
		(start 147.845018 -95.944944)
		(end 147.715478 -95.815404)
		(width 0.12954)
		(layer "B.Cu")
		(net "SMB_PCIE0_3V3AUX_SCL_R")
	)
	(segment
		(start 148.25599 -92.270834)
		(end 148.442426 -92.084398)
		(width 0.127)
		(layer "In2.Cu")
		(net "SMB_PCIE0_3V3AUX_SCL_R")
	)
	(segment
		(start 147.08886 -43.762168)
		(end 147.08886 -36.317428)
		(width 0.127)
		(layer "In2.Cu")
		(net "SMB_PCIE0_3V3AUX_SCL_R")
	)
	(segment
		(start 148.307806 -68.349622)
		(end 148.307806 -62.264798)
		(width 0.127)
		(layer "In2.Cu")
		(net "SMB_PCIE0_3V3AUX_SCL_R")
	)
	(segment
		(start 156.08808 -13.706348)
		(end 156.74848 -13.045948)
		(width 0.127)
		(layer "In2.Cu")
		(net "SMB_PCIE0_3V3AUX_SCL_R")
	)
	(segment
		(start 146.00428 -59.961272)
		(end 146.00428 -44.846748)
		(width 0.127)
		(layer "In2.Cu")
		(net "SMB_PCIE0_3V3AUX_SCL_R")
	)
	(segment
		(start 147.88388 -90.503248)
		(end 147.88388 -82.182716)
		(width 0.127)
		(layer "In2.Cu")
		(net "SMB_PCIE0_3V3AUX_SCL_R")
	)
	(segment
		(start 148.32076 -35.085528)
		(end 148.32076 -17.769332)
		(width 0.127)
		(layer "In2.Cu")
		(net "SMB_PCIE0_3V3AUX_SCL_R")
	)
	(segment
		(start 147.88388 -82.182716)
		(end 145.77822 -80.077056)
		(width 0.127)
		(layer "In2.Cu")
		(net "SMB_PCIE0_3V3AUX_SCL_R")
	)
	(segment
		(start 148.442426 -92.084398)
		(end 148.442426 -91.061794)
		(width 0.127)
		(layer "In2.Cu")
		(net "SMB_PCIE0_3V3AUX_SCL_R")
	)
	(segment
		(start 156.74848 -13.045948)
		(end 156.74848 -11.123168)
		(width 0.127)
		(layer "In2.Cu")
		(net "SMB_PCIE0_3V3AUX_SCL_R")
	)
	(segment
		(start 155.701492 -8.7376)
		(end 155.39974 -8.7376)
		(width 0.127)
		(layer "In2.Cu")
		(net "SMB_PCIE0_3V3AUX_SCL_R")
	)
	(segment
		(start 148.442426 -91.061794)
		(end 147.88388 -90.503248)
		(width 0.127)
		(layer "In2.Cu")
		(net "SMB_PCIE0_3V3AUX_SCL_R")
	)
	(segment
		(start 152.383744 -13.706348)
		(end 156.08808 -13.706348)
		(width 0.127)
		(layer "In2.Cu")
		(net "SMB_PCIE0_3V3AUX_SCL_R")
	)
	(segment
		(start 147.08886 -36.317428)
		(end 148.32076 -35.085528)
		(width 0.127)
		(layer "In2.Cu")
		(net "SMB_PCIE0_3V3AUX_SCL_R")
	)
	(segment
		(start 156.74848 -11.123168)
		(end 157.01518 -10.856468)
		(width 0.127)
		(layer "In2.Cu")
		(net "SMB_PCIE0_3V3AUX_SCL_R")
	)
	(segment
		(start 148.32076 -17.769332)
		(end 152.383744 -13.706348)
		(width 0.127)
		(layer "In2.Cu")
		(net "SMB_PCIE0_3V3AUX_SCL_R")
	)
	(segment
		(start 146.00428 -44.846748)
		(end 147.08886 -43.762168)
		(width 0.127)
		(layer "In2.Cu")
		(net "SMB_PCIE0_3V3AUX_SCL_R")
	)
	(segment
		(start 145.77822 -70.879208)
		(end 148.307806 -68.349622)
		(width 0.127)
		(layer "In2.Cu")
		(net "SMB_PCIE0_3V3AUX_SCL_R")
	)
	(segment
		(start 145.77822 -80.077056)
		(end 145.77822 -70.879208)
		(width 0.127)
		(layer "In2.Cu")
		(net "SMB_PCIE0_3V3AUX_SCL_R")
	)
	(segment
		(start 157.01518 -10.856468)
		(end 157.01518 -10.051288)
		(width 0.127)
		(layer "In2.Cu")
		(net "SMB_PCIE0_3V3AUX_SCL_R")
	)
	(segment
		(start 148.307806 -62.264798)
		(end 146.00428 -59.961272)
		(width 0.127)
		(layer "In2.Cu")
		(net "SMB_PCIE0_3V3AUX_SCL_R")
	)
	(segment
		(start 157.01518 -10.051288)
		(end 155.701492 -8.7376)
		(width 0.127)
		(layer "In2.Cu")
		(net "SMB_PCIE0_3V3AUX_SCL_R")
	)
	(segment
		(start 165.666674 -12.683744)
		(end 165.666928 -12.683998)
		(width 0.12954)
		(layer "F.Cu")
		(net "SMB_PCIE0_3V3AUX_SCL")
	)
	(segment
		(start 165.185852 -10.023348)
		(end 165.666674 -10.50417)
		(width 0.12954)
		(layer "F.Cu")
		(net "SMB_PCIE0_3V3AUX_SCL")
	)
	(segment
		(start 160.322768 -10.46226)
		(end 162.583368 -10.46226)
		(width 0.12954)
		(layer "F.Cu")
		(net "SMB_PCIE0_3V3AUX_SCL")
	)
	(segment
		(start 162.583368 -10.46226)
		(end 163.02228 -10.023348)
		(width 0.12954)
		(layer "F.Cu")
		(net "SMB_PCIE0_3V3AUX_SCL")
	)
	(segment
		(start 165.666674 -10.50417)
		(end 165.666674 -12.683744)
		(width 0.12954)
		(layer "F.Cu")
		(net "SMB_PCIE0_3V3AUX_SCL")
	)
	(segment
		(start 165.666928 -12.683998)
		(end 165.666928 -13.600176)
		(width 0.12954)
		(layer "F.Cu")
		(net "SMB_PCIE0_3V3AUX_SCL")
	)
	(segment
		(start 163.02228 -10.023348)
		(end 165.185852 -10.023348)
		(width 0.12954)
		(layer "F.Cu")
		(net "SMB_PCIE0_3V3AUX_SCL")
	)
	(segment
		(start 159.97428 -10.810748)
		(end 160.322768 -10.46226)
		(width 0.12954)
		(layer "F.Cu")
		(net "SMB_PCIE0_3V3AUX_SCL")
	)
	(via
		(at 159.97428 -10.810748)
		(size 0.508)
		(drill 0.254)
		(layers "F.Cu" "B.Cu")
		(net "SMB_PCIE0_3V3AUX_SCL")
	)
	(via
		(at 158.75 -11.163808)
		(size 0.6604)
		(drill 0.3302)
		(layers "F.Cu" "B.Cu")
		(net "SMB_PCIE0_3V3AUX_SCL")
	)
	(segment
		(start 158.75 -11.163808)
		(end 157.42793 -9.841738)
		(width 0.12954)
		(layer "B.Cu")
		(net "SMB_PCIE0_3V3AUX_SCL")
	)
	(segment
		(start 157.43555 -9.822688)
		(end 157.43555 -8.801608)
		(width 0.12954)
		(layer "B.Cu")
		(net "SMB_PCIE0_3V3AUX_SCL")
	)
	(segment
		(start 157.42793 -9.841738)
		(end 157.42793 -9.830308)
		(width 0.12954)
		(layer "B.Cu")
		(net "SMB_PCIE0_3V3AUX_SCL")
	)
	(segment
		(start 157.42793 -9.830308)
		(end 157.43555 -9.822688)
		(width 0.12954)
		(layer "B.Cu")
		(net "SMB_PCIE0_3V3AUX_SCL")
	)
	(segment
		(start 159.97428 -10.810748)
		(end 159.10306 -10.810748)
		(width 0.12954)
		(layer "B.Cu")
		(net "SMB_PCIE0_3V3AUX_SCL")
	)
	(segment
		(start 159.10306 -10.810748)
		(end 158.75 -11.163808)
		(width 0.12954)
		(layer "B.Cu")
		(net "SMB_PCIE0_3V3AUX_SCL")
	)
	(segment
		(start 439.27776 -43.429428)
		(end 439.27776 -43.960288)
		(width 0.12954)
		(layer "F.Cu")
		(net "SMB_OCP_SFF_3V3AUX_SDA")
	)
	(segment
		(start 438.99328 -43.144948)
		(end 439.27776 -43.429428)
		(width 0.12954)
		(layer "F.Cu")
		(net "SMB_OCP_SFF_3V3AUX_SDA")
	)
	(segment
		(start 439.66257 -44.345098)
		(end 442.698378 -44.345098)
		(width 0.12954)
		(layer "F.Cu")
		(net "SMB_OCP_SFF_3V3AUX_SDA")
	)
	(segment
		(start 439.27776 -43.960288)
		(end 439.66257 -44.345098)
		(width 0.12954)
		(layer "F.Cu")
		(net "SMB_OCP_SFF_3V3AUX_SDA")
	)
	(via
		(at 182.47995 -19.782028)
		(size 0.508)
		(drill 0.254)
		(layers "F.Cu" "B.Cu")
		(net "SMB_OCP_SFF_3V3AUX_SDA")
	)
	(via
		(at 438.99328 -43.144948)
		(size 0.508)
		(drill 0.254)
		(layers "F.Cu" "B.Cu")
		(net "SMB_OCP_SFF_3V3AUX_SDA")
	)
	(segment
		(start 182.795418 -19.110198)
		(end 182.871618 -19.110198)
		(width 0.12954)
		(layer "B.Cu")
		(net "SMB_OCP_SFF_3V3AUX_SDA")
	)
	(segment
		(start 182.47995 -19.782028)
		(end 182.47995 -19.425666)
		(width 0.12954)
		(layer "B.Cu")
		(net "SMB_OCP_SFF_3V3AUX_SDA")
	)
	(segment
		(start 182.47995 -19.425666)
		(end 182.795418 -19.110198)
		(width 0.12954)
		(layer "B.Cu")
		(net "SMB_OCP_SFF_3V3AUX_SDA")
	)
	(segment
		(start 244.01272 -42.923968)
		(end 243.306092 -42.21734)
		(width 0.127)
		(layer "In15.Cu")
		(net "SMB_OCP_SFF_3V3AUX_SDA")
	)
	(segment
		(start 322.68795 -14.366748)
		(end 310.296814 -14.366748)
		(width 0.127)
		(layer "In15.Cu")
		(net "SMB_OCP_SFF_3V3AUX_SDA")
	)
	(segment
		(start 183.41721 -20.719288)
		(end 182.47995 -19.782028)
		(width 0.127)
		(layer "In15.Cu")
		(net "SMB_OCP_SFF_3V3AUX_SDA")
	)
	(segment
		(start 263.139174 -42.992548)
		(end 262.123174 -44.008548)
		(width 0.127)
		(layer "In15.Cu")
		(net "SMB_OCP_SFF_3V3AUX_SDA")
	)
	(segment
		(start 247.51411 -42.296588)
		(end 246.88673 -42.923968)
		(width 0.127)
		(layer "In15.Cu")
		(net "SMB_OCP_SFF_3V3AUX_SDA")
	)
	(segment
		(start 371.91569 -33.005268)
		(end 352.89617 -13.985748)
		(width 0.127)
		(layer "In15.Cu")
		(net "SMB_OCP_SFF_3V3AUX_SDA")
	)
	(segment
		(start 307.840634 -16.822928)
		(end 303.191418 -16.822928)
		(width 0.127)
		(layer "In15.Cu")
		(net "SMB_OCP_SFF_3V3AUX_SDA")
	)
	(segment
		(start 434.235098 -43.350688)
		(end 432.83886 -41.95445)
		(width 0.127)
		(layer "In15.Cu")
		(net "SMB_OCP_SFF_3V3AUX_SDA")
	)
	(segment
		(start 430.792382 -25.992328)
		(end 399.120106 -25.992328)
		(width 0.127)
		(layer "In15.Cu")
		(net "SMB_OCP_SFF_3V3AUX_SDA")
	)
	(segment
		(start 253.394464 -42.296588)
		(end 247.51411 -42.296588)
		(width 0.127)
		(layer "In15.Cu")
		(net "SMB_OCP_SFF_3V3AUX_SDA")
	)
	(segment
		(start 273.689826 -42.992548)
		(end 263.139174 -42.992548)
		(width 0.127)
		(layer "In15.Cu")
		(net "SMB_OCP_SFF_3V3AUX_SDA")
	)
	(segment
		(start 384.91795 -33.005268)
		(end 371.91569 -33.005268)
		(width 0.127)
		(layer "In15.Cu")
		(net "SMB_OCP_SFF_3V3AUX_SDA")
	)
	(segment
		(start 210.18881 -33.416748)
		(end 194.52082 -33.416748)
		(width 0.127)
		(layer "In15.Cu")
		(net "SMB_OCP_SFF_3V3AUX_SDA")
	)
	(segment
		(start 182.87238 -26.543254)
		(end 182.87238 -22.91461)
		(width 0.127)
		(layer "In15.Cu")
		(net "SMB_OCP_SFF_3V3AUX_SDA")
	)
	(segment
		(start 395.492986 -29.619448)
		(end 388.30377 -29.619448)
		(width 0.127)
		(layer "In15.Cu")
		(net "SMB_OCP_SFF_3V3AUX_SDA")
	)
	(segment
		(start 323.06895 -13.985748)
		(end 322.68795 -14.366748)
		(width 0.127)
		(layer "In15.Cu")
		(net "SMB_OCP_SFF_3V3AUX_SDA")
	)
	(segment
		(start 438.99328 -43.144948)
		(end 438.78754 -43.350688)
		(width 0.127)
		(layer "In15.Cu")
		(net "SMB_OCP_SFF_3V3AUX_SDA")
	)
	(segment
		(start 190.20155 -33.872424)
		(end 182.87238 -26.543254)
		(width 0.127)
		(layer "In15.Cu")
		(net "SMB_OCP_SFF_3V3AUX_SDA")
	)
	(segment
		(start 225.03511 -40.777668)
		(end 220.51899 -36.261548)
		(width 0.127)
		(layer "In15.Cu")
		(net "SMB_OCP_SFF_3V3AUX_SDA")
	)
	(segment
		(start 352.89617 -13.985748)
		(end 323.06895 -13.985748)
		(width 0.127)
		(layer "In15.Cu")
		(net "SMB_OCP_SFF_3V3AUX_SDA")
	)
	(segment
		(start 262.123174 -44.008548)
		(end 256.477262 -44.008548)
		(width 0.127)
		(layer "In15.Cu")
		(net "SMB_OCP_SFF_3V3AUX_SDA")
	)
	(segment
		(start 388.30377 -29.619448)
		(end 384.91795 -33.005268)
		(width 0.127)
		(layer "In15.Cu")
		(net "SMB_OCP_SFF_3V3AUX_SDA")
	)
	(segment
		(start 246.88673 -42.923968)
		(end 244.01272 -42.923968)
		(width 0.127)
		(layer "In15.Cu")
		(net "SMB_OCP_SFF_3V3AUX_SDA")
	)
	(segment
		(start 310.296814 -14.366748)
		(end 307.840634 -16.822928)
		(width 0.127)
		(layer "In15.Cu")
		(net "SMB_OCP_SFF_3V3AUX_SDA")
	)
	(segment
		(start 399.120106 -25.992328)
		(end 395.492986 -29.619448)
		(width 0.127)
		(layer "In15.Cu")
		(net "SMB_OCP_SFF_3V3AUX_SDA")
	)
	(segment
		(start 254.06477 -42.57421)
		(end 253.394464 -42.296588)
		(width 0.127)
		(layer "In15.Cu")
		(net "SMB_OCP_SFF_3V3AUX_SDA")
	)
	(segment
		(start 220.51899 -36.261548)
		(end 213.03361 -36.261548)
		(width 0.127)
		(layer "In15.Cu")
		(net "SMB_OCP_SFF_3V3AUX_SDA")
	)
	(segment
		(start 297.503088 -19.179286)
		(end 273.689826 -42.992548)
		(width 0.127)
		(layer "In15.Cu")
		(net "SMB_OCP_SFF_3V3AUX_SDA")
	)
	(segment
		(start 213.03361 -36.261548)
		(end 210.18881 -33.416748)
		(width 0.127)
		(layer "In15.Cu")
		(net "SMB_OCP_SFF_3V3AUX_SDA")
	)
	(segment
		(start 303.191418 -16.822928)
		(end 297.503088 -19.179286)
		(width 0.127)
		(layer "In15.Cu")
		(net "SMB_OCP_SFF_3V3AUX_SDA")
	)
	(segment
		(start 182.87238 -22.91461)
		(end 183.41721 -22.36978)
		(width 0.127)
		(layer "In15.Cu")
		(net "SMB_OCP_SFF_3V3AUX_SDA")
	)
	(segment
		(start 438.78754 -43.350688)
		(end 434.235098 -43.350688)
		(width 0.127)
		(layer "In15.Cu")
		(net "SMB_OCP_SFF_3V3AUX_SDA")
	)
	(segment
		(start 183.41721 -22.36978)
		(end 183.41721 -20.719288)
		(width 0.127)
		(layer "In15.Cu")
		(net "SMB_OCP_SFF_3V3AUX_SDA")
	)
	(segment
		(start 432.83886 -28.038806)
		(end 430.792382 -25.992328)
		(width 0.127)
		(layer "In15.Cu")
		(net "SMB_OCP_SFF_3V3AUX_SDA")
	)
	(segment
		(start 243.306092 -42.21734)
		(end 234.206034 -42.21734)
		(width 0.127)
		(layer "In15.Cu")
		(net "SMB_OCP_SFF_3V3AUX_SDA")
	)
	(segment
		(start 194.52082 -33.416748)
		(end 194.065144 -33.872424)
		(width 0.127)
		(layer "In15.Cu")
		(net "SMB_OCP_SFF_3V3AUX_SDA")
	)
	(segment
		(start 194.065144 -33.872424)
		(end 190.20155 -33.872424)
		(width 0.127)
		(layer "In15.Cu")
		(net "SMB_OCP_SFF_3V3AUX_SDA")
	)
	(segment
		(start 234.206034 -42.21734)
		(end 232.766362 -40.777668)
		(width 0.127)
		(layer "In15.Cu")
		(net "SMB_OCP_SFF_3V3AUX_SDA")
	)
	(segment
		(start 432.83886 -41.95445)
		(end 432.83886 -28.038806)
		(width 0.127)
		(layer "In15.Cu")
		(net "SMB_OCP_SFF_3V3AUX_SDA")
	)
	(segment
		(start 255.042924 -42.57421)
		(end 254.06477 -42.57421)
		(width 0.127)
		(layer "In15.Cu")
		(net "SMB_OCP_SFF_3V3AUX_SDA")
	)
	(segment
		(start 232.766362 -40.777668)
		(end 225.03511 -40.777668)
		(width 0.127)
		(layer "In15.Cu")
		(net "SMB_OCP_SFF_3V3AUX_SDA")
	)
	(segment
		(start 256.477262 -44.008548)
		(end 255.042924 -42.57421)
		(width 0.127)
		(layer "In15.Cu")
		(net "SMB_OCP_SFF_3V3AUX_SDA")
	)
	(segment
		(start 442.698378 -44.995338)
		(end 441.31738 -44.995338)
		(width 0.12954)
		(layer "F.Cu")
		(net "SMB_OCP_SFF_3V3AUX_SCL")
	)
	(segment
		(start 439.29681 -44.995338)
		(end 439.27776 -44.976288)
		(width 0.12954)
		(layer "F.Cu")
		(net "SMB_OCP_SFF_3V3AUX_SCL")
	)
	(segment
		(start 441.31738 -44.995338)
		(end 439.29681 -44.995338)
		(width 0.12954)
		(layer "F.Cu")
		(net "SMB_OCP_SFF_3V3AUX_SCL")
	)
	(via
		(at 441.31738 -44.995338)
		(size 0.508)
		(drill 0.254)
		(layers "F.Cu" "B.Cu")
		(net "SMB_OCP_SFF_3V3AUX_SCL")
	)
	(via
		(at 183.49341 -19.776948)
		(size 0.508)
		(drill 0.254)
		(layers "F.Cu" "B.Cu")
		(net "SMB_OCP_SFF_3V3AUX_SCL")
	)
	(segment
		(start 183.49341 -19.425666)
		(end 183.808878 -19.110198)
		(width 0.12954)
		(layer "B.Cu")
		(net "SMB_OCP_SFF_3V3AUX_SCL")
	)
	(segment
		(start 183.49341 -19.776948)
		(end 183.49341 -19.425666)
		(width 0.12954)
		(layer "B.Cu")
		(net "SMB_OCP_SFF_3V3AUX_SCL")
	)
	(segment
		(start 183.808878 -19.110198)
		(end 183.885078 -19.110198)
		(width 0.12954)
		(layer "B.Cu")
		(net "SMB_OCP_SFF_3V3AUX_SCL")
	)
	(segment
		(start 220.69806 -35.829748)
		(end 225.21418 -40.345868)
		(width 0.127)
		(layer "In15.Cu")
		(net "SMB_OCP_SFF_3V3AUX_SCL")
	)
	(segment
		(start 388.1247 -29.187648)
		(end 395.313916 -29.187648)
		(width 0.127)
		(layer "In15.Cu")
		(net "SMB_OCP_SFF_3V3AUX_SCL")
	)
	(segment
		(start 307.79466 -16.248888)
		(end 310.1086 -13.934948)
		(width 0.127)
		(layer "In15.Cu")
		(net "SMB_OCP_SFF_3V3AUX_SCL")
	)
	(segment
		(start 440.2201 -42.644568)
		(end 440.79668 -43.221148)
		(width 0.127)
		(layer "In15.Cu")
		(net "SMB_OCP_SFF_3V3AUX_SCL")
	)
	(segment
		(start 244.23878 -42.492168)
		(end 246.70766 -42.492168)
		(width 0.127)
		(layer "In15.Cu")
		(net "SMB_OCP_SFF_3V3AUX_SCL")
	)
	(segment
		(start 384.73888 -32.573468)
		(end 388.1247 -29.187648)
		(width 0.127)
		(layer "In15.Cu")
		(net "SMB_OCP_SFF_3V3AUX_SCL")
	)
	(segment
		(start 440.79668 -43.221148)
		(end 440.79668 -44.474638)
		(width 0.127)
		(layer "In15.Cu")
		(net "SMB_OCP_SFF_3V3AUX_SCL")
	)
	(segment
		(start 372.10746 -32.573468)
		(end 384.73888 -32.573468)
		(width 0.127)
		(layer "In15.Cu")
		(net "SMB_OCP_SFF_3V3AUX_SCL")
	)
	(segment
		(start 297.277282 -18.722086)
		(end 303.24806 -16.248888)
		(width 0.127)
		(layer "In15.Cu")
		(net "SMB_OCP_SFF_3V3AUX_SCL")
	)
	(segment
		(start 225.21418 -40.345868)
		(end 233.03484 -40.345868)
		(width 0.127)
		(layer "In15.Cu")
		(net "SMB_OCP_SFF_3V3AUX_SCL")
	)
	(segment
		(start 395.313916 -29.187648)
		(end 398.941036 -25.560528)
		(width 0.127)
		(layer "In15.Cu")
		(net "SMB_OCP_SFF_3V3AUX_SCL")
	)
	(segment
		(start 262.94969 -42.535348)
		(end 273.46402 -42.535348)
		(width 0.127)
		(layer "In15.Cu")
		(net "SMB_OCP_SFF_3V3AUX_SCL")
	)
	(segment
		(start 246.70766 -42.492168)
		(end 247.630188 -41.56964)
		(width 0.127)
		(layer "In15.Cu")
		(net "SMB_OCP_SFF_3V3AUX_SCL")
	)
	(segment
		(start 322.88988 -13.553948)
		(end 353.08794 -13.553948)
		(width 0.127)
		(layer "In15.Cu")
		(net "SMB_OCP_SFF_3V3AUX_SCL")
	)
	(segment
		(start 183.84901 -22.566884)
		(end 183.30418 -23.111714)
		(width 0.127)
		(layer "In15.Cu")
		(net "SMB_OCP_SFF_3V3AUX_SCL")
	)
	(segment
		(start 273.46402 -42.535348)
		(end 297.277282 -18.722086)
		(width 0.127)
		(layer "In15.Cu")
		(net "SMB_OCP_SFF_3V3AUX_SCL")
	)
	(segment
		(start 255.274572 -41.56964)
		(end 257.25628 -43.551348)
		(width 0.127)
		(layer "In15.Cu")
		(net "SMB_OCP_SFF_3V3AUX_SCL")
	)
	(segment
		(start 183.49341 -19.776948)
		(end 183.84901 -20.132548)
		(width 0.127)
		(layer "In15.Cu")
		(net "SMB_OCP_SFF_3V3AUX_SCL")
	)
	(segment
		(start 190.428118 -33.430718)
		(end 193.869564 -33.430718)
		(width 0.127)
		(layer "In15.Cu")
		(net "SMB_OCP_SFF_3V3AUX_SCL")
	)
	(segment
		(start 183.84901 -20.132548)
		(end 183.84901 -22.566884)
		(width 0.127)
		(layer "In15.Cu")
		(net "SMB_OCP_SFF_3V3AUX_SCL")
	)
	(segment
		(start 398.941036 -25.560528)
		(end 431.03292 -25.560528)
		(width 0.127)
		(layer "In15.Cu")
		(net "SMB_OCP_SFF_3V3AUX_SCL")
	)
	(segment
		(start 233.03484 -40.345868)
		(end 234.46867 -41.779698)
		(width 0.127)
		(layer "In15.Cu")
		(net "SMB_OCP_SFF_3V3AUX_SCL")
	)
	(segment
		(start 431.03292 -25.560528)
		(end 433.27066 -27.798268)
		(width 0.127)
		(layer "In15.Cu")
		(net "SMB_OCP_SFF_3V3AUX_SCL")
	)
	(segment
		(start 257.25628 -43.551348)
		(end 261.93369 -43.551348)
		(width 0.127)
		(layer "In15.Cu")
		(net "SMB_OCP_SFF_3V3AUX_SCL")
	)
	(segment
		(start 194.315334 -32.984948)
		(end 210.36788 -32.984948)
		(width 0.127)
		(layer "In15.Cu")
		(net "SMB_OCP_SFF_3V3AUX_SCL")
	)
	(segment
		(start 303.24806 -16.248888)
		(end 307.79466 -16.248888)
		(width 0.127)
		(layer "In15.Cu")
		(net "SMB_OCP_SFF_3V3AUX_SCL")
	)
	(segment
		(start 440.79668 -44.474638)
		(end 441.31738 -44.995338)
		(width 0.127)
		(layer "In15.Cu")
		(net "SMB_OCP_SFF_3V3AUX_SCL")
	)
	(segment
		(start 183.30418 -26.30678)
		(end 190.428118 -33.430718)
		(width 0.127)
		(layer "In15.Cu")
		(net "SMB_OCP_SFF_3V3AUX_SCL")
	)
	(segment
		(start 261.93369 -43.551348)
		(end 262.94969 -42.535348)
		(width 0.127)
		(layer "In15.Cu")
		(net "SMB_OCP_SFF_3V3AUX_SCL")
	)
	(segment
		(start 247.630188 -41.56964)
		(end 255.274572 -41.56964)
		(width 0.127)
		(layer "In15.Cu")
		(net "SMB_OCP_SFF_3V3AUX_SCL")
	)
	(segment
		(start 434.228494 -42.644568)
		(end 440.2201 -42.644568)
		(width 0.127)
		(layer "In15.Cu")
		(net "SMB_OCP_SFF_3V3AUX_SCL")
	)
	(segment
		(start 183.30418 -23.111714)
		(end 183.30418 -26.30678)
		(width 0.127)
		(layer "In15.Cu")
		(net "SMB_OCP_SFF_3V3AUX_SCL")
	)
	(segment
		(start 213.21268 -35.829748)
		(end 220.69806 -35.829748)
		(width 0.127)
		(layer "In15.Cu")
		(net "SMB_OCP_SFF_3V3AUX_SCL")
	)
	(segment
		(start 433.27066 -27.798268)
		(end 433.27066 -41.686734)
		(width 0.127)
		(layer "In15.Cu")
		(net "SMB_OCP_SFF_3V3AUX_SCL")
	)
	(segment
		(start 353.08794 -13.553948)
		(end 372.10746 -32.573468)
		(width 0.127)
		(layer "In15.Cu")
		(net "SMB_OCP_SFF_3V3AUX_SCL")
	)
	(segment
		(start 243.52631 -41.779698)
		(end 244.23878 -42.492168)
		(width 0.127)
		(layer "In15.Cu")
		(net "SMB_OCP_SFF_3V3AUX_SCL")
	)
	(segment
		(start 310.1086 -13.934948)
		(end 322.50888 -13.934948)
		(width 0.127)
		(layer "In15.Cu")
		(net "SMB_OCP_SFF_3V3AUX_SCL")
	)
	(segment
		(start 234.46867 -41.779698)
		(end 243.52631 -41.779698)
		(width 0.127)
		(layer "In15.Cu")
		(net "SMB_OCP_SFF_3V3AUX_SCL")
	)
	(segment
		(start 193.869564 -33.430718)
		(end 194.315334 -32.984948)
		(width 0.127)
		(layer "In15.Cu")
		(net "SMB_OCP_SFF_3V3AUX_SCL")
	)
	(segment
		(start 322.50888 -13.934948)
		(end 322.88988 -13.553948)
		(width 0.127)
		(layer "In15.Cu")
		(net "SMB_OCP_SFF_3V3AUX_SCL")
	)
	(segment
		(start 433.27066 -41.686734)
		(end 434.228494 -42.644568)
		(width 0.127)
		(layer "In15.Cu")
		(net "SMB_OCP_SFF_3V3AUX_SCL")
	)
	(segment
		(start 210.36788 -32.984948)
		(end 213.21268 -35.829748)
		(width 0.127)
		(layer "In15.Cu")
		(net "SMB_OCP_SFF_3V3AUX_SCL")
	)
	(segment
		(start 146.9263 -55.514748)
		(end 146.45513 -55.514748)
		(width 0.12954)
		(layer "F.Cu")
		(net "SMB_M2_P0_1V8AUX_SDA_R")
	)
	(segment
		(start 148.53793 -56.225948)
		(end 148.77288 -56.460898)
		(width 0.12954)
		(layer "F.Cu")
		(net "SMB_M2_P0_1V8AUX_SDA_R")
	)
	(segment
		(start 148.77288 -56.460898)
		(end 151.997664 -56.460898)
		(width 0.12954)
		(layer "F.Cu")
		(net "SMB_M2_P0_1V8AUX_SDA_R")
	)
	(segment
		(start 148.53793 -56.225948)
		(end 147.82673 -55.514748)
		(width 0.12954)
		(layer "F.Cu")
		(net "SMB_M2_P0_1V8AUX_SDA_R")
	)
	(segment
		(start 146.45513 -55.514748)
		(end 145.74393 -56.225948)
		(width 0.12954)
		(layer "F.Cu")
		(net "SMB_M2_P0_1V8AUX_SDA_R")
	)
	(segment
		(start 147.82673 -55.514748)
		(end 146.9263 -55.514748)
		(width 0.12954)
		(layer "F.Cu")
		(net "SMB_M2_P0_1V8AUX_SDA_R")
	)
	(via
		(at 146.9263 -55.514748)
		(size 0.508)
		(drill 0.254)
		(layers "F.Cu" "B.Cu")
		(net "SMB_M2_P0_1V8AUX_SDA_R")
	)
	(segment
		(start 165.53942 -45.011848)
		(end 166.577518 -46.049946)
		(width 0.12954)
		(layer "F.Cu")
		(net "SMB_M2_P0_1V8AUX_SDA")
	)
	(segment
		(start 166.577518 -46.049946)
		(end 169.557954 -46.049946)
		(width 0.12954)
		(layer "F.Cu")
		(net "SMB_M2_P0_1V8AUX_SDA")
	)
	(segment
		(start 144.94383 -56.225948)
		(end 144.20342 -56.225948)
		(width 0.12954)
		(layer "F.Cu")
		(net "SMB_M2_P0_1V8AUX_SDA")
	)
	(via
		(at 165.53942 -45.011848)
		(size 0.508)
		(drill 0.254)
		(layers "F.Cu" "B.Cu")
		(net "SMB_M2_P0_1V8AUX_SDA")
	)
	(via
		(at 144.20342 -56.225948)
		(size 0.508)
		(drill 0.254)
		(layers "F.Cu" "B.Cu")
		(net "SMB_M2_P0_1V8AUX_SDA")
	)
	(segment
		(start 147.38604 -57.836308)
		(end 144.02562 -57.836308)
		(width 0.127)
		(layer "In6.Cu")
		(net "SMB_M2_P0_1V8AUX_SDA")
	)
	(segment
		(start 143.67256 -56.756808)
		(end 144.20342 -56.225948)
		(width 0.127)
		(layer "In6.Cu")
		(net "SMB_M2_P0_1V8AUX_SDA")
	)
	(segment
		(start 154.04084 -57.114948)
		(end 148.1074 -57.114948)
		(width 0.127)
		(layer "In6.Cu")
		(net "SMB_M2_P0_1V8AUX_SDA")
	)
	(segment
		(start 157.26664 -53.889148)
		(end 154.04084 -57.114948)
		(width 0.127)
		(layer "In6.Cu")
		(net "SMB_M2_P0_1V8AUX_SDA")
	)
	(segment
		(start 148.1074 -57.114948)
		(end 147.38604 -57.836308)
		(width 0.127)
		(layer "In6.Cu")
		(net "SMB_M2_P0_1V8AUX_SDA")
	)
	(segment
		(start 165.76548 -45.237908)
		(end 165.76548 -46.411388)
		(width 0.127)
		(layer "In6.Cu")
		(net "SMB_M2_P0_1V8AUX_SDA")
	)
	(segment
		(start 165.53942 -45.011848)
		(end 165.76548 -45.237908)
		(width 0.127)
		(layer "In6.Cu")
		(net "SMB_M2_P0_1V8AUX_SDA")
	)
	(segment
		(start 143.67256 -57.483248)
		(end 143.67256 -56.756808)
		(width 0.127)
		(layer "In6.Cu")
		(net "SMB_M2_P0_1V8AUX_SDA")
	)
	(segment
		(start 158.28772 -53.889148)
		(end 157.26664 -53.889148)
		(width 0.127)
		(layer "In6.Cu")
		(net "SMB_M2_P0_1V8AUX_SDA")
	)
	(segment
		(start 165.76548 -46.411388)
		(end 158.28772 -53.889148)
		(width 0.127)
		(layer "In6.Cu")
		(net "SMB_M2_P0_1V8AUX_SDA")
	)
	(segment
		(start 144.02562 -57.836308)
		(end 143.67256 -57.483248)
		(width 0.127)
		(layer "In6.Cu")
		(net "SMB_M2_P0_1V8AUX_SDA")
	)
	(segment
		(start 148.06803 -57.711848)
		(end 148.53793 -57.241948)
		(width 0.12954)
		(layer "F.Cu")
		(net "SMB_M2_P0_1V8AUX_SCL_R")
	)
	(segment
		(start 145.74393 -57.241948)
		(end 146.91106 -57.241948)
		(width 0.12954)
		(layer "F.Cu")
		(net "SMB_M2_P0_1V8AUX_SCL_R")
	)
	(segment
		(start 151.997664 -57.110884)
		(end 148.668994 -57.110884)
		(width 0.12954)
		(layer "F.Cu")
		(net "SMB_M2_P0_1V8AUX_SCL_R")
	)
	(segment
		(start 146.91106 -57.241948)
		(end 147.38096 -57.711848)
		(width 0.12954)
		(layer "F.Cu")
		(net "SMB_M2_P0_1V8AUX_SCL_R")
	)
	(segment
		(start 147.38096 -57.711848)
		(end 148.06803 -57.711848)
		(width 0.12954)
		(layer "F.Cu")
		(net "SMB_M2_P0_1V8AUX_SCL_R")
	)
	(segment
		(start 148.668994 -57.110884)
		(end 148.53793 -57.241948)
		(width 0.12954)
		(layer "F.Cu")
		(net "SMB_M2_P0_1V8AUX_SCL_R")
	)
	(via
		(at 146.91106 -57.241948)
		(size 0.508)
		(drill 0.254)
		(layers "F.Cu" "B.Cu")
		(net "SMB_M2_P0_1V8AUX_SCL_R")
	)
	(segment
		(start 144.94383 -57.241948)
		(end 144.20342 -57.241948)
		(width 0.12954)
		(layer "F.Cu")
		(net "SMB_M2_P0_1V8AUX_SCL")
	)
	(segment
		(start 165.403784 -46.550072)
		(end 169.557954 -46.550072)
		(width 0.12954)
		(layer "F.Cu")
		(net "SMB_M2_P0_1V8AUX_SCL")
	)
	(segment
		(start 165.06698 -46.213268)
		(end 165.403784 -46.550072)
		(width 0.12954)
		(layer "F.Cu")
		(net "SMB_M2_P0_1V8AUX_SCL")
	)
	(via
		(at 165.06698 -46.213268)
		(size 0.508)
		(drill 0.254)
		(layers "F.Cu" "B.Cu")
		(net "SMB_M2_P0_1V8AUX_SCL")
	)
	(via
		(at 144.20342 -57.241948)
		(size 0.508)
		(drill 0.254)
		(layers "F.Cu" "B.Cu")
		(net "SMB_M2_P0_1V8AUX_SCL")
	)
	(segment
		(start 165.06698 -46.213268)
		(end 165.065456 -46.213268)
		(width 0.127)
		(layer "In6.Cu")
		(net "SMB_M2_P0_1V8AUX_SCL")
	)
	(segment
		(start 153.777696 -56.479948)
		(end 147.89658 -56.479948)
		(width 0.127)
		(layer "In6.Cu")
		(net "SMB_M2_P0_1V8AUX_SCL")
	)
	(segment
		(start 144.71396 -56.731408)
		(end 144.20342 -57.241948)
		(width 0.127)
		(layer "In6.Cu")
		(net "SMB_M2_P0_1V8AUX_SCL")
	)
	(segment
		(start 147.89658 -56.479948)
		(end 147.64512 -56.731408)
		(width 0.127)
		(layer "In6.Cu")
		(net "SMB_M2_P0_1V8AUX_SCL")
	)
	(segment
		(start 147.64512 -56.731408)
		(end 144.71396 -56.731408)
		(width 0.127)
		(layer "In6.Cu")
		(net "SMB_M2_P0_1V8AUX_SCL")
	)
	(segment
		(start 165.065456 -46.213268)
		(end 158.010352 -53.268372)
		(width 0.127)
		(layer "In6.Cu")
		(net "SMB_M2_P0_1V8AUX_SCL")
	)
	(segment
		(start 156.989272 -53.268372)
		(end 153.777696 -56.479948)
		(width 0.127)
		(layer "In6.Cu")
		(net "SMB_M2_P0_1V8AUX_SCL")
	)
	(segment
		(start 158.010352 -53.268372)
		(end 156.989272 -53.268372)
		(width 0.127)
		(layer "In6.Cu")
		(net "SMB_M2_P0_1V8AUX_SCL")
	)
	(segment
		(start 236.037374 -128.804924)
		(end 236.24794 -129.017776)
		(width 0.12954)
		(layer "F.Cu")
		(net "SMB_HOST_DB2000_3V3AUX_SDA")
	)
	(segment
		(start 260.48462 -131.985258)
		(end 261.036562 -132.5372)
		(width 0.12954)
		(layer "F.Cu")
		(net "SMB_HOST_DB2000_3V3AUX_SDA")
	)
	(segment
		(start 261.036562 -132.5372)
		(end 261.036562 -133.001512)
		(width 0.12954)
		(layer "F.Cu")
		(net "SMB_HOST_DB2000_3V3AUX_SDA")
	)
	(segment
		(start 236.037374 -128.545844)
		(end 236.037374 -128.804924)
		(width 0.12954)
		(layer "F.Cu")
		(net "SMB_HOST_DB2000_3V3AUX_SDA")
	)
	(via
		(at 236.037374 -128.545844)
		(size 0.49022)
		(drill 0.254)
		(layers "F.Cu" "B.Cu")
		(net "SMB_HOST_DB2000_3V3AUX_SDA")
	)
	(via
		(at 260.48462 -131.985258)
		(size 0.508)
		(drill 0.254)
		(layers "F.Cu" "B.Cu")
		(net "SMB_HOST_DB2000_3V3AUX_SDA")
	)
	(segment
		(start 260.970014 -128.958848)
		(end 260.065266 -128.958848)
		(width 0.127)
		(layer "In13.Cu")
		(net "SMB_HOST_DB2000_3V3AUX_SDA")
	)
	(segment
		(start 261.568184 -130.51155)
		(end 261.568184 -129.557018)
		(width 0.127)
		(layer "In13.Cu")
		(net "SMB_HOST_DB2000_3V3AUX_SDA")
	)
	(segment
		(start 242.28425 -131.742942)
		(end 239.748314 -129.207006)
		(width 0.127)
		(layer "In13.Cu")
		(net "SMB_HOST_DB2000_3V3AUX_SDA")
	)
	(segment
		(start 260.065266 -128.958848)
		(end 257.281172 -131.742942)
		(width 0.127)
		(layer "In13.Cu")
		(net "SMB_HOST_DB2000_3V3AUX_SDA")
	)
	(segment
		(start 261.568184 -129.557018)
		(end 260.970014 -128.958848)
		(width 0.127)
		(layer "In13.Cu")
		(net "SMB_HOST_DB2000_3V3AUX_SDA")
	)
	(segment
		(start 236.698536 -129.207006)
		(end 236.037374 -128.545844)
		(width 0.127)
		(layer "In13.Cu")
		(net "SMB_HOST_DB2000_3V3AUX_SDA")
	)
	(segment
		(start 257.281172 -131.742942)
		(end 242.28425 -131.742942)
		(width 0.127)
		(layer "In13.Cu")
		(net "SMB_HOST_DB2000_3V3AUX_SDA")
	)
	(segment
		(start 260.48462 -131.985258)
		(end 260.48462 -131.595114)
		(width 0.127)
		(layer "In13.Cu")
		(net "SMB_HOST_DB2000_3V3AUX_SDA")
	)
	(segment
		(start 260.48462 -131.595114)
		(end 261.568184 -130.51155)
		(width 0.127)
		(layer "In13.Cu")
		(net "SMB_HOST_DB2000_3V3AUX_SDA")
	)
	(segment
		(start 239.748314 -129.207006)
		(end 236.698536 -129.207006)
		(width 0.127)
		(layer "In13.Cu")
		(net "SMB_HOST_DB2000_3V3AUX_SDA")
	)
	(segment
		(start 235.748576 -128.926082)
		(end 235.748068 -129.017776)
		(width 0.12954)
		(layer "F.Cu")
		(net "SMB_HOST_DB2000_3V3AUX_SCL")
	)
	(segment
		(start 260.1468 -129.631948)
		(end 260.1468 -130.096768)
		(width 0.12954)
		(layer "F.Cu")
		(net "SMB_HOST_DB2000_3V3AUX_SCL")
	)
	(segment
		(start 260.650736 -130.600704)
		(end 261.036562 -130.600704)
		(width 0.12954)
		(layer "F.Cu")
		(net "SMB_HOST_DB2000_3V3AUX_SCL")
	)
	(segment
		(start 235.365798 -128.541526)
		(end 235.748576 -128.926082)
		(width 0.12954)
		(layer "F.Cu")
		(net "SMB_HOST_DB2000_3V3AUX_SCL")
	)
	(segment
		(start 260.1468 -130.096768)
		(end 260.650736 -130.600704)
		(width 0.12954)
		(layer "F.Cu")
		(net "SMB_HOST_DB2000_3V3AUX_SCL")
	)
	(via
		(at 260.1468 -129.631948)
		(size 0.508)
		(drill 0.254)
		(layers "F.Cu" "B.Cu")
		(net "SMB_HOST_DB2000_3V3AUX_SCL")
	)
	(via
		(at 235.365798 -128.541526)
		(size 0.49022)
		(drill 0.254)
		(layers "F.Cu" "B.Cu")
		(net "SMB_HOST_DB2000_3V3AUX_SCL")
	)
	(segment
		(start 239.57407 -129.678684)
		(end 236.502956 -129.678684)
		(width 0.127)
		(layer "In13.Cu")
		(net "SMB_HOST_DB2000_3V3AUX_SCL")
	)
	(segment
		(start 260.1468 -129.631948)
		(end 257.564128 -132.21462)
		(width 0.127)
		(layer "In13.Cu")
		(net "SMB_HOST_DB2000_3V3AUX_SCL")
	)
	(segment
		(start 236.502956 -129.678684)
		(end 235.365798 -128.541526)
		(width 0.127)
		(layer "In13.Cu")
		(net "SMB_HOST_DB2000_3V3AUX_SCL")
	)
	(segment
		(start 257.564128 -132.21462)
		(end 242.110006 -132.21462)
		(width 0.127)
		(layer "In13.Cu")
		(net "SMB_HOST_DB2000_3V3AUX_SCL")
	)
	(segment
		(start 242.110006 -132.21462)
		(end 239.57407 -129.678684)
		(width 0.127)
		(layer "In13.Cu")
		(net "SMB_HOST_DB2000_3V3AUX_SCL")
	)
	(segment
		(start 248.36374 -98.875088)
		(end 247.189498 -98.875088)
		(width 0.12954)
		(layer "F.Cu")
		(net "SMB_HOST_CLK_3V3AUX_SDA")
	)
	(segment
		(start 249.630184 -98.643948)
		(end 248.59488 -98.643948)
		(width 0.12954)
		(layer "F.Cu")
		(net "SMB_HOST_CLK_3V3AUX_SDA")
	)
	(segment
		(start 235.51388 -256.523998)
		(end 235.51388 -257.139948)
		(width 0.12954)
		(layer "F.Cu")
		(net "SMB_HOST_CLK_3V3AUX_SDA")
	)
	(segment
		(start 249.780806 -98.493326)
		(end 249.630184 -98.643948)
		(width 0.12954)
		(layer "F.Cu")
		(net "SMB_HOST_CLK_3V3AUX_SDA")
	)
	(segment
		(start 247.189498 -98.875088)
		(end 246.94388 -99.120706)
		(width 0.12954)
		(layer "F.Cu")
		(net "SMB_HOST_CLK_3V3AUX_SDA")
	)
	(segment
		(start 251.281438 -98.563176)
		(end 251.211588 -98.493326)
		(width 0.0889)
		(layer "F.Cu")
		(net "SMB_HOST_CLK_3V3AUX_SDA")
	)
	(segment
		(start 252.557788 -98.563176)
		(end 251.281438 -98.563176)
		(width 0.0889)
		(layer "F.Cu")
		(net "SMB_HOST_CLK_3V3AUX_SDA")
	)
	(segment
		(start 251.211588 -98.493326)
		(end 249.780806 -98.493326)
		(width 0.0889)
		(layer "F.Cu")
		(net "SMB_HOST_CLK_3V3AUX_SDA")
	)
	(segment
		(start 248.59488 -98.643948)
		(end 248.36374 -98.875088)
		(width 0.12954)
		(layer "F.Cu")
		(net "SMB_HOST_CLK_3V3AUX_SDA")
	)
	(via
		(at 246.94388 -99.120706)
		(size 0.508)
		(drill 0.254)
		(layers "F.Cu" "B.Cu")
		(net "SMB_HOST_CLK_3V3AUX_SDA")
	)
	(via
		(at 235.51388 -257.139948)
		(size 0.508)
		(drill 0.254)
		(layers "F.Cu" "B.Cu")
		(net "SMB_HOST_CLK_3V3AUX_SDA")
	)
	(via
		(at 245.33606 -103.115618)
		(size 0.508)
		(drill 0.254)
		(layers "F.Cu" "B.Cu")
		(net "SMB_HOST_CLK_3V3AUX_SDA")
	)
	(via
		(at 226.26828 -98.897948)
		(size 0.508)
		(drill 0.254)
		(layers "F.Cu" "B.Cu")
		(net "SMB_HOST_CLK_3V3AUX_SDA")
	)
	(segment
		(start 244.749066 -102.528624)
		(end 243.401088 -102.528624)
		(width 0.12954)
		(layer "B.Cu")
		(net "SMB_HOST_CLK_3V3AUX_SDA")
	)
	(segment
		(start 245.33606 -103.115618)
		(end 244.749066 -102.528624)
		(width 0.12954)
		(layer "B.Cu")
		(net "SMB_HOST_CLK_3V3AUX_SDA")
	)
	(segment
		(start 240.8555 -156.086048)
		(end 222.22968 -137.460228)
		(width 0.127)
		(layer "In2.Cu")
		(net "SMB_HOST_CLK_3V3AUX_SDA")
	)
	(segment
		(start 245.33606 -103.115618)
		(end 245.33606 -100.728526)
		(width 0.127)
		(layer "In2.Cu")
		(net "SMB_HOST_CLK_3V3AUX_SDA")
	)
	(segment
		(start 223.784922 -101.202236)
		(end 223.390206 -100.80752)
		(width 0.127)
		(layer "In2.Cu")
		(net "SMB_HOST_CLK_3V3AUX_SDA")
	)
	(segment
		(start 223.15678 -102.009448)
		(end 223.784922 -101.381306)
		(width 0.127)
		(layer "In2.Cu")
		(net "SMB_HOST_CLK_3V3AUX_SDA")
	)
	(segment
		(start 244.094 -171.469812)
		(end 240.8555 -168.231312)
		(width 0.127)
		(layer "In2.Cu")
		(net "SMB_HOST_CLK_3V3AUX_SDA")
	)
	(segment
		(start 222.22968 -137.460228)
		(end 222.22968 -133.015228)
		(width 0.127)
		(layer "In2.Cu")
		(net "SMB_HOST_CLK_3V3AUX_SDA")
	)
	(segment
		(start 225.79584 -127.864108)
		(end 223.15678 -125.225048)
		(width 0.127)
		(layer "In2.Cu")
		(net "SMB_HOST_CLK_3V3AUX_SDA")
	)
	(segment
		(start 223.839278 -100.358194)
		(end 224.233994 -100.75291)
		(width 0.127)
		(layer "In2.Cu")
		(net "SMB_HOST_CLK_3V3AUX_SDA")
	)
	(segment
		(start 245.33606 -100.728526)
		(end 246.94388 -99.120706)
		(width 0.127)
		(layer "In2.Cu")
		(net "SMB_HOST_CLK_3V3AUX_SDA")
	)
	(segment
		(start 223.8121 -131.432808)
		(end 224.20326 -131.432808)
		(width 0.127)
		(layer "In2.Cu")
		(net "SMB_HOST_CLK_3V3AUX_SDA")
	)
	(segment
		(start 224.20326 -131.432808)
		(end 225.79584 -129.840228)
		(width 0.127)
		(layer "In2.Cu")
		(net "SMB_HOST_CLK_3V3AUX_SDA")
	)
	(segment
		(start 223.15678 -125.225048)
		(end 223.15678 -102.009448)
		(width 0.127)
		(layer "In2.Cu")
		(net "SMB_HOST_CLK_3V3AUX_SDA")
	)
	(segment
		(start 235.51388 -257.139948)
		(end 231.327706 -252.953774)
		(width 0.127)
		(layer "In2.Cu")
		(net "SMB_HOST_CLK_3V3AUX_SDA")
	)
	(segment
		(start 223.784922 -101.381306)
		(end 223.784922 -101.202236)
		(width 0.127)
		(layer "In2.Cu")
		(net "SMB_HOST_CLK_3V3AUX_SDA")
	)
	(segment
		(start 231.327706 -243.471446)
		(end 244.094 -230.705152)
		(width 0.127)
		(layer "In2.Cu")
		(net "SMB_HOST_CLK_3V3AUX_SDA")
	)
	(segment
		(start 224.233994 -100.75291)
		(end 224.413318 -100.75291)
		(width 0.127)
		(layer "In2.Cu")
		(net "SMB_HOST_CLK_3V3AUX_SDA")
	)
	(segment
		(start 223.390206 -100.627942)
		(end 223.659954 -100.358194)
		(width 0.127)
		(layer "In2.Cu")
		(net "SMB_HOST_CLK_3V3AUX_SDA")
	)
	(segment
		(start 240.8555 -168.231312)
		(end 240.8555 -156.086048)
		(width 0.127)
		(layer "In2.Cu")
		(net "SMB_HOST_CLK_3V3AUX_SDA")
	)
	(segment
		(start 223.390206 -100.80752)
		(end 223.390206 -100.627942)
		(width 0.127)
		(layer "In2.Cu")
		(net "SMB_HOST_CLK_3V3AUX_SDA")
	)
	(segment
		(start 231.327706 -252.953774)
		(end 231.327706 -243.471446)
		(width 0.127)
		(layer "In2.Cu")
		(net "SMB_HOST_CLK_3V3AUX_SDA")
	)
	(segment
		(start 225.79584 -129.840228)
		(end 225.79584 -127.864108)
		(width 0.127)
		(layer "In2.Cu")
		(net "SMB_HOST_CLK_3V3AUX_SDA")
	)
	(segment
		(start 222.22968 -133.015228)
		(end 223.8121 -131.432808)
		(width 0.127)
		(layer "In2.Cu")
		(net "SMB_HOST_CLK_3V3AUX_SDA")
	)
	(segment
		(start 224.413318 -100.75291)
		(end 226.26828 -98.897948)
		(width 0.127)
		(layer "In2.Cu")
		(net "SMB_HOST_CLK_3V3AUX_SDA")
	)
	(segment
		(start 223.659954 -100.358194)
		(end 223.839278 -100.358194)
		(width 0.127)
		(layer "In2.Cu")
		(net "SMB_HOST_CLK_3V3AUX_SDA")
	)
	(segment
		(start 244.094 -230.705152)
		(end 244.094 -171.469812)
		(width 0.127)
		(layer "In2.Cu")
		(net "SMB_HOST_CLK_3V3AUX_SDA")
	)
	(segment
		(start 235.476034 -97.022666)
		(end 235.296202 -97.022666)
		(width 0.127)
		(layer "In15.Cu")
		(net "SMB_HOST_CLK_3V3AUX_SDA")
	)
	(segment
		(start 235.745274 -96.573594)
		(end 235.745274 -96.753426)
		(width 0.127)
		(layer "In15.Cu")
		(net "SMB_HOST_CLK_3V3AUX_SDA")
	)
	(segment
		(start 232.58272 -98.897948)
		(end 226.26828 -98.897948)
		(width 0.127)
		(layer "In15.Cu")
		(net "SMB_HOST_CLK_3V3AUX_SDA")
	)
	(segment
		(start 235.745274 -96.753426)
		(end 235.476034 -97.022666)
		(width 0.127)
		(layer "In15.Cu")
		(net "SMB_HOST_CLK_3V3AUX_SDA")
	)
	(segment
		(start 234.967018 -96.693482)
		(end 234.787186 -96.693482)
		(width 0.127)
		(layer "In15.Cu")
		(net "SMB_HOST_CLK_3V3AUX_SDA")
	)
	(segment
		(start 234.787186 -96.693482)
		(end 232.58272 -98.897948)
		(width 0.127)
		(layer "In15.Cu")
		(net "SMB_HOST_CLK_3V3AUX_SDA")
	)
	(segment
		(start 246.38254 -98.559366)
		(end 246.38254 -98.362008)
		(width 0.127)
		(layer "In15.Cu")
		(net "SMB_HOST_CLK_3V3AUX_SDA")
	)
	(segment
		(start 235.41609 -96.064578)
		(end 235.41609 -96.24441)
		(width 0.127)
		(layer "In15.Cu")
		(net "SMB_HOST_CLK_3V3AUX_SDA")
	)
	(segment
		(start 246.94388 -99.120706)
		(end 246.38254 -98.559366)
		(width 0.127)
		(layer "In15.Cu")
		(net "SMB_HOST_CLK_3V3AUX_SDA")
	)
	(segment
		(start 246.38254 -98.362008)
		(end 242.6843 -94.663768)
		(width 0.127)
		(layer "In15.Cu")
		(net "SMB_HOST_CLK_3V3AUX_SDA")
	)
	(segment
		(start 235.296202 -97.022666)
		(end 234.967018 -96.693482)
		(width 0.127)
		(layer "In15.Cu")
		(net "SMB_HOST_CLK_3V3AUX_SDA")
	)
	(segment
		(start 236.8169 -94.663768)
		(end 235.41609 -96.064578)
		(width 0.127)
		(layer "In15.Cu")
		(net "SMB_HOST_CLK_3V3AUX_SDA")
	)
	(segment
		(start 235.41609 -96.24441)
		(end 235.745274 -96.573594)
		(width 0.127)
		(layer "In15.Cu")
		(net "SMB_HOST_CLK_3V3AUX_SDA")
	)
	(segment
		(start 242.6843 -94.663768)
		(end 236.8169 -94.663768)
		(width 0.127)
		(layer "In15.Cu")
		(net "SMB_HOST_CLK_3V3AUX_SDA")
	)
	(segment
		(start 249.607578 -98.234246)
		(end 249.48769 -98.114358)
		(width 0.12954)
		(layer "F.Cu")
		(net "SMB_HOST_CLK_3V3AUX_SCL")
	)
	(segment
		(start 249.48769 -98.114358)
		(end 248.534428 -98.114358)
		(width 0.12954)
		(layer "F.Cu")
		(net "SMB_HOST_CLK_3V3AUX_SCL")
	)
	(segment
		(start 248.385838 -98.262948)
		(end 247.83288 -98.262948)
		(width 0.12954)
		(layer "F.Cu")
		(net "SMB_HOST_CLK_3V3AUX_SCL")
	)
	(segment
		(start 247.65508 -98.440748)
		(end 247.83288 -98.262948)
		(width 0.12954)
		(layer "F.Cu")
		(net "SMB_HOST_CLK_3V3AUX_SCL")
	)
	(segment
		(start 251.336556 -98.31324)
		(end 251.257562 -98.234246)
		(width 0.12954)
		(layer "F.Cu")
		(net "SMB_HOST_CLK_3V3AUX_SCL")
	)
	(segment
		(start 246.94388 -98.293682)
		(end 247.090946 -98.440748)
		(width 0.12954)
		(layer "F.Cu")
		(net "SMB_HOST_CLK_3V3AUX_SCL")
	)
	(segment
		(start 246.94388 -98.107754)
		(end 246.94388 -98.293682)
		(width 0.12954)
		(layer "F.Cu")
		(net "SMB_HOST_CLK_3V3AUX_SCL")
	)
	(segment
		(start 251.257562 -98.234246)
		(end 249.607578 -98.234246)
		(width 0.12954)
		(layer "F.Cu")
		(net "SMB_HOST_CLK_3V3AUX_SCL")
	)
	(segment
		(start 247.090946 -98.440748)
		(end 247.65508 -98.440748)
		(width 0.12954)
		(layer "F.Cu")
		(net "SMB_HOST_CLK_3V3AUX_SCL")
	)
	(segment
		(start 251.807726 -98.31324)
		(end 251.336556 -98.31324)
		(width 0.12954)
		(layer "F.Cu")
		(net "SMB_HOST_CLK_3V3AUX_SCL")
	)
	(segment
		(start 248.534428 -98.114358)
		(end 248.385838 -98.262948)
		(width 0.12954)
		(layer "F.Cu")
		(net "SMB_HOST_CLK_3V3AUX_SCL")
	)
	(via
		(at 242.947698 -100.287074)
		(size 0.508)
		(drill 0.254)
		(layers "F.Cu" "B.Cu")
		(net "SMB_HOST_CLK_3V3AUX_SCL")
	)
	(via
		(at 246.94388 -98.107754)
		(size 0.508)
		(drill 0.254)
		(layers "F.Cu" "B.Cu")
		(net "SMB_HOST_CLK_3V3AUX_SCL")
	)
	(via
		(at 247.83288 -98.262948)
		(size 0.762)
		(drill 0.381)
		(layers "F.Cu" "B.Cu")
		(net "SMB_HOST_CLK_3V3AUX_SCL")
	)
	(segment
		(start 246.94388 -98.107754)
		(end 247.24995 -97.801684)
		(width 0.12954)
		(layer "B.Cu")
		(net "SMB_HOST_CLK_3V3AUX_SCL")
	)
	(segment
		(start 243.401088 -100.740464)
		(end 243.401088 -101.447854)
		(width 0.12954)
		(layer "B.Cu")
		(net "SMB_HOST_CLK_3V3AUX_SCL")
	)
	(segment
		(start 247.24995 -97.801684)
		(end 247.24995 -96.761808)
		(width 0.12954)
		(layer "B.Cu")
		(net "SMB_HOST_CLK_3V3AUX_SCL")
	)
	(segment
		(start 242.947698 -100.287074)
		(end 243.401088 -100.740464)
		(width 0.12954)
		(layer "B.Cu")
		(net "SMB_HOST_CLK_3V3AUX_SCL")
	)
	(segment
		(start 245.22938 -98.058732)
		(end 243.001038 -100.287074)
		(width 0.127)
		(layer "In6.Cu")
		(net "SMB_HOST_CLK_3V3AUX_SCL")
	)
	(segment
		(start 246.894858 -98.058732)
		(end 245.22938 -98.058732)
		(width 0.127)
		(layer "In6.Cu")
		(net "SMB_HOST_CLK_3V3AUX_SCL")
	)
	(segment
		(start 246.94388 -98.107754)
		(end 246.894858 -98.058732)
		(width 0.127)
		(layer "In6.Cu")
		(net "SMB_HOST_CLK_3V3AUX_SCL")
	)
	(segment
		(start 243.001038 -100.287074)
		(end 242.947698 -100.287074)
		(width 0.127)
		(layer "In6.Cu")
		(net "SMB_HOST_CLK_3V3AUX_SCL")
	)
	(segment
		(start 320.6623 -48.023018)
		(end 322.805552 -48.023018)
		(width 0.12954)
		(layer "F.Cu")
		(net "SMB_HOST_BMC_3V3AUX_SDA")
	)
	(segment
		(start 4.333494 -49.877472)
		(end 4.333494 -49.148492)
		(width 0.12954)
		(layer "F.Cu")
		(net "SMB_HOST_BMC_3V3AUX_SDA")
	)
	(segment
		(start 305.13274 -48.732948)
		(end 309.533036 -48.732948)
		(width 0.12954)
		(layer "F.Cu")
		(net "SMB_HOST_BMC_3V3AUX_SDA")
	)
	(segment
		(start 309.533036 -48.732948)
		(end 309.922672 -48.343312)
		(width 0.12954)
		(layer "F.Cu")
		(net "SMB_HOST_BMC_3V3AUX_SDA")
	)
	(segment
		(start 322.933822 -47.894748)
		(end 326.235822 -47.894748)
		(width 0.0889)
		(layer "F.Cu")
		(net "SMB_HOST_BMC_3V3AUX_SDA")
	)
	(segment
		(start 310.603392 -47.442628)
		(end 315.474604 -47.442628)
		(width 0.12954)
		(layer "F.Cu")
		(net "SMB_HOST_BMC_3V3AUX_SDA")
	)
	(segment
		(start 326.235822 -47.894748)
		(end 326.291194 -47.95012)
		(width 0.0889)
		(layer "F.Cu")
		(net "SMB_HOST_BMC_3V3AUX_SDA")
	)
	(segment
		(start 316.033404 -48.001428)
		(end 316.650878 -48.001428)
		(width 0.12954)
		(layer "F.Cu")
		(net "SMB_HOST_BMC_3V3AUX_SDA")
	)
	(segment
		(start 322.805552 -48.023018)
		(end 322.933822 -47.894748)
		(width 0.0889)
		(layer "F.Cu")
		(net "SMB_HOST_BMC_3V3AUX_SDA")
	)
	(segment
		(start 4.333494 -49.148492)
		(end 4.29895 -49.113948)
		(width 0.12954)
		(layer "F.Cu")
		(net "SMB_HOST_BMC_3V3AUX_SDA")
	)
	(segment
		(start 309.922672 -48.123348)
		(end 310.603392 -47.442628)
		(width 0.12954)
		(layer "F.Cu")
		(net "SMB_HOST_BMC_3V3AUX_SDA")
	)
	(segment
		(start 317.028322 -48.378872)
		(end 320.306446 -48.378872)
		(width 0.12954)
		(layer "F.Cu")
		(net "SMB_HOST_BMC_3V3AUX_SDA")
	)
	(segment
		(start 304.98288 -48.583088)
		(end 305.13274 -48.732948)
		(width 0.12954)
		(layer "F.Cu")
		(net "SMB_HOST_BMC_3V3AUX_SDA")
	)
	(segment
		(start 315.474604 -47.442628)
		(end 316.033404 -48.001428)
		(width 0.12954)
		(layer "F.Cu")
		(net "SMB_HOST_BMC_3V3AUX_SDA")
	)
	(segment
		(start 304.98288 -47.716948)
		(end 304.98288 -48.583088)
		(width 0.12954)
		(layer "F.Cu")
		(net "SMB_HOST_BMC_3V3AUX_SDA")
	)
	(segment
		(start 309.922672 -48.343312)
		(end 309.922672 -48.123348)
		(width 0.12954)
		(layer "F.Cu")
		(net "SMB_HOST_BMC_3V3AUX_SDA")
	)
	(segment
		(start 326.291194 -47.95012)
		(end 326.584818 -47.95012)
		(width 0.0889)
		(layer "F.Cu")
		(net "SMB_HOST_BMC_3V3AUX_SDA")
	)
	(segment
		(start 320.306446 -48.378872)
		(end 320.6623 -48.023018)
		(width 0.12954)
		(layer "F.Cu")
		(net "SMB_HOST_BMC_3V3AUX_SDA")
	)
	(segment
		(start 316.650878 -48.001428)
		(end 317.028322 -48.378872)
		(width 0.12954)
		(layer "F.Cu")
		(net "SMB_HOST_BMC_3V3AUX_SDA")
	)
	(via
		(at 304.98288 -47.716948)
		(size 0.508)
		(drill 0.254)
		(layers "F.Cu" "B.Cu")
		(net "SMB_HOST_BMC_3V3AUX_SDA")
	)
	(via
		(at 4.333494 -49.877472)
		(size 0.508)
		(drill 0.254)
		(layers "F.Cu" "B.Cu")
		(net "SMB_HOST_BMC_3V3AUX_SDA")
	)
	(via
		(at 301.31512 -75.938888)
		(size 0.508)
		(drill 0.254)
		(layers "F.Cu" "B.Cu")
		(net "SMB_HOST_BMC_3V3AUX_SDA")
	)
	(segment
		(start 153.387552 -71.999348)
		(end 150.147782 -68.759578)
		(width 0.127)
		(layer "In6.Cu")
		(net "SMB_HOST_BMC_3V3AUX_SDA")
	)
	(segment
		(start 163.88588 -71.999348)
		(end 153.387552 -71.999348)
		(width 0.127)
		(layer "In6.Cu")
		(net "SMB_HOST_BMC_3V3AUX_SDA")
	)
	(segment
		(start 293.60241 -85.000338)
		(end 246.03329 -85.000338)
		(width 0.127)
		(layer "In6.Cu")
		(net "SMB_HOST_BMC_3V3AUX_SDA")
	)
	(segment
		(start 6.89102 -64.336676)
		(end 3.61188 -61.057536)
		(width 0.127)
		(layer "In6.Cu")
		(net "SMB_HOST_BMC_3V3AUX_SDA")
	)
	(segment
		(start 246.03329 -85.000338)
		(end 240.77168 -90.261948)
		(width 0.127)
		(layer "In6.Cu")
		(net "SMB_HOST_BMC_3V3AUX_SDA")
	)
	(segment
		(start 57.36463 -57.81421)
		(end 27.59329 -57.81421)
		(width 0.127)
		(layer "In6.Cu")
		(net "SMB_HOST_BMC_3V3AUX_SDA")
	)
	(segment
		(start 21.070824 -64.336676)
		(end 6.89102 -64.336676)
		(width 0.127)
		(layer "In6.Cu")
		(net "SMB_HOST_BMC_3V3AUX_SDA")
	)
	(segment
		(start 150.147782 -68.759578)
		(end 145.193766 -68.759578)
		(width 0.127)
		(layer "In6.Cu")
		(net "SMB_HOST_BMC_3V3AUX_SDA")
	)
	(segment
		(start 3.61188 -50.599086)
		(end 4.333494 -49.877472)
		(width 0.127)
		(layer "In6.Cu")
		(net "SMB_HOST_BMC_3V3AUX_SDA")
	)
	(segment
		(start 301.31512 -75.938888)
		(end 300.72838 -76.525628)
		(width 0.127)
		(layer "In6.Cu")
		(net "SMB_HOST_BMC_3V3AUX_SDA")
	)
	(segment
		(start 68.476368 -68.925948)
		(end 57.36463 -57.81421)
		(width 0.127)
		(layer "In6.Cu")
		(net "SMB_HOST_BMC_3V3AUX_SDA")
	)
	(segment
		(start 27.59329 -57.81421)
		(end 21.070824 -64.336676)
		(width 0.127)
		(layer "In6.Cu")
		(net "SMB_HOST_BMC_3V3AUX_SDA")
	)
	(segment
		(start 135.0137 -68.925948)
		(end 68.476368 -68.925948)
		(width 0.127)
		(layer "In6.Cu")
		(net "SMB_HOST_BMC_3V3AUX_SDA")
	)
	(segment
		(start 205.670912 -84.073492)
		(end 192.952624 -84.073492)
		(width 0.127)
		(layer "In6.Cu")
		(net "SMB_HOST_BMC_3V3AUX_SDA")
	)
	(segment
		(start 300.72838 -76.525628)
		(end 300.72838 -77.874368)
		(width 0.127)
		(layer "In6.Cu")
		(net "SMB_HOST_BMC_3V3AUX_SDA")
	)
	(segment
		(start 145.193766 -68.759578)
		(end 144.283176 -67.848988)
		(width 0.127)
		(layer "In6.Cu")
		(net "SMB_HOST_BMC_3V3AUX_SDA")
	)
	(segment
		(start 3.61188 -61.057536)
		(end 3.61188 -50.599086)
		(width 0.127)
		(layer "In6.Cu")
		(net "SMB_HOST_BMC_3V3AUX_SDA")
	)
	(segment
		(start 144.283176 -67.848988)
		(end 136.09066 -67.848988)
		(width 0.127)
		(layer "In6.Cu")
		(net "SMB_HOST_BMC_3V3AUX_SDA")
	)
	(segment
		(start 192.952624 -84.073492)
		(end 192.430654 -83.551522)
		(width 0.127)
		(layer "In6.Cu")
		(net "SMB_HOST_BMC_3V3AUX_SDA")
	)
	(segment
		(start 136.09066 -67.848988)
		(end 135.0137 -68.925948)
		(width 0.127)
		(layer "In6.Cu")
		(net "SMB_HOST_BMC_3V3AUX_SDA")
	)
	(segment
		(start 240.77168 -90.261948)
		(end 211.859368 -90.261948)
		(width 0.127)
		(layer "In6.Cu")
		(net "SMB_HOST_BMC_3V3AUX_SDA")
	)
	(segment
		(start 300.72838 -77.874368)
		(end 293.60241 -85.000338)
		(width 0.127)
		(layer "In6.Cu")
		(net "SMB_HOST_BMC_3V3AUX_SDA")
	)
	(segment
		(start 211.859368 -90.261948)
		(end 205.670912 -84.073492)
		(width 0.127)
		(layer "In6.Cu")
		(net "SMB_HOST_BMC_3V3AUX_SDA")
	)
	(segment
		(start 192.430654 -83.551522)
		(end 175.438054 -83.551522)
		(width 0.127)
		(layer "In6.Cu")
		(net "SMB_HOST_BMC_3V3AUX_SDA")
	)
	(segment
		(start 175.438054 -83.551522)
		(end 163.88588 -71.999348)
		(width 0.127)
		(layer "In6.Cu")
		(net "SMB_HOST_BMC_3V3AUX_SDA")
	)
	(segment
		(start 302.846994 -48.623728)
		(end 304.0761 -48.623728)
		(width 0.127)
		(layer "In11.Cu")
		(net "SMB_HOST_BMC_3V3AUX_SDA")
	)
	(segment
		(start 301.85614 -50.900838)
		(end 301.85614 -50.392838)
		(width 0.127)
		(layer "In11.Cu")
		(net "SMB_HOST_BMC_3V3AUX_SDA")
	)
	(segment
		(start 302.4378 -51.154838)
		(end 302.3108 -51.027838)
		(width 0.127)
		(layer "In11.Cu")
		(net "SMB_HOST_BMC_3V3AUX_SDA")
	)
	(segment
		(start 302.4378 -49.032922)
		(end 302.846994 -48.623728)
		(width 0.127)
		(layer "In11.Cu")
		(net "SMB_HOST_BMC_3V3AUX_SDA")
	)
	(segment
		(start 301.31512 -75.938888)
		(end 301.02048 -75.644248)
		(width 0.127)
		(layer "In11.Cu")
		(net "SMB_HOST_BMC_3V3AUX_SDA")
	)
	(segment
		(start 301.02048 -75.644248)
		(end 301.02048 -54.290468)
		(width 0.127)
		(layer "In11.Cu")
		(net "SMB_HOST_BMC_3V3AUX_SDA")
	)
	(segment
		(start 302.3108 -51.027838)
		(end 301.98314 -51.027838)
		(width 0.127)
		(layer "In11.Cu")
		(net "SMB_HOST_BMC_3V3AUX_SDA")
	)
	(segment
		(start 302.3108 -50.265838)
		(end 302.4378 -50.138838)
		(width 0.127)
		(layer "In11.Cu")
		(net "SMB_HOST_BMC_3V3AUX_SDA")
	)
	(segment
		(start 302.4378 -52.873148)
		(end 302.4378 -51.154838)
		(width 0.127)
		(layer "In11.Cu")
		(net "SMB_HOST_BMC_3V3AUX_SDA")
	)
	(segment
		(start 304.0761 -48.623728)
		(end 304.98288 -47.716948)
		(width 0.127)
		(layer "In11.Cu")
		(net "SMB_HOST_BMC_3V3AUX_SDA")
	)
	(segment
		(start 301.02048 -54.290468)
		(end 302.4378 -52.873148)
		(width 0.127)
		(layer "In11.Cu")
		(net "SMB_HOST_BMC_3V3AUX_SDA")
	)
	(segment
		(start 301.85614 -50.392838)
		(end 301.98314 -50.265838)
		(width 0.127)
		(layer "In11.Cu")
		(net "SMB_HOST_BMC_3V3AUX_SDA")
	)
	(segment
		(start 301.98314 -51.027838)
		(end 301.85614 -50.900838)
		(width 0.127)
		(layer "In11.Cu")
		(net "SMB_HOST_BMC_3V3AUX_SDA")
	)
	(segment
		(start 302.4378 -50.138838)
		(end 302.4378 -49.032922)
		(width 0.127)
		(layer "In11.Cu")
		(net "SMB_HOST_BMC_3V3AUX_SDA")
	)
	(segment
		(start 301.98314 -50.265838)
		(end 302.3108 -50.265838)
		(width 0.127)
		(layer "In11.Cu")
		(net "SMB_HOST_BMC_3V3AUX_SDA")
	)
	(segment
		(start 314.272168 -45.759116)
		(end 316.43447 -45.759116)
		(width 0.12954)
		(layer "F.Cu")
		(net "SMB_HOST_BMC_3V3AUX_SCL")
	)
	(segment
		(start 324.103492 -47.186088)
		(end 324.122796 -47.205392)
		(width 0.12954)
		(layer "F.Cu")
		(net "SMB_HOST_BMC_3V3AUX_SCL")
	)
	(segment
		(start 324.378066 -47.205392)
		(end 324.622414 -47.44974)
		(width 0.0889)
		(layer "F.Cu")
		(net "SMB_HOST_BMC_3V3AUX_SCL")
	)
	(segment
		(start 309.604156 -46.573948)
		(end 309.959756 -46.218348)
		(width 0.12954)
		(layer "F.Cu")
		(net "SMB_HOST_BMC_3V3AUX_SCL")
	)
	(segment
		(start 324.122796 -47.205392)
		(end 324.378066 -47.205392)
		(width 0.0889)
		(layer "F.Cu")
		(net "SMB_HOST_BMC_3V3AUX_SCL")
	)
	(segment
		(start 321.295776 -47.205392)
		(end 321.31508 -47.186088)
		(width 0.12954)
		(layer "F.Cu")
		(net "SMB_HOST_BMC_3V3AUX_SCL")
	)
	(segment
		(start 316.43447 -45.759116)
		(end 316.645036 -45.969682)
		(width 0.12954)
		(layer "F.Cu")
		(net "SMB_HOST_BMC_3V3AUX_SCL")
	)
	(segment
		(start 321.31508 -47.186088)
		(end 324.103492 -47.186088)
		(width 0.12954)
		(layer "F.Cu")
		(net "SMB_HOST_BMC_3V3AUX_SCL")
	)
	(segment
		(start 304.98288 -46.954948)
		(end 305.36388 -46.573948)
		(width 0.12954)
		(layer "F.Cu")
		(net "SMB_HOST_BMC_3V3AUX_SCL")
	)
	(segment
		(start 317.112396 -45.969682)
		(end 318.348106 -47.205392)
		(width 0.12954)
		(layer "F.Cu")
		(net "SMB_HOST_BMC_3V3AUX_SCL")
	)
	(segment
		(start 316.645036 -45.969682)
		(end 317.112396 -45.969682)
		(width 0.12954)
		(layer "F.Cu")
		(net "SMB_HOST_BMC_3V3AUX_SCL")
	)
	(segment
		(start 313.812936 -46.218348)
		(end 314.272168 -45.759116)
		(width 0.12954)
		(layer "F.Cu")
		(net "SMB_HOST_BMC_3V3AUX_SCL")
	)
	(segment
		(start 309.959756 -46.218348)
		(end 313.812936 -46.218348)
		(width 0.12954)
		(layer "F.Cu")
		(net "SMB_HOST_BMC_3V3AUX_SCL")
	)
	(segment
		(start 324.622414 -47.44974)
		(end 326.999854 -47.44974)
		(width 0.0889)
		(layer "F.Cu")
		(net "SMB_HOST_BMC_3V3AUX_SCL")
	)
	(segment
		(start 4.29895 -50.891948)
		(end 4.29895 -51.654964)
		(width 0.12954)
		(layer "F.Cu")
		(net "SMB_HOST_BMC_3V3AUX_SCL")
	)
	(segment
		(start 318.348106 -47.205392)
		(end 321.295776 -47.205392)
		(width 0.12954)
		(layer "F.Cu")
		(net "SMB_HOST_BMC_3V3AUX_SCL")
	)
	(segment
		(start 305.36388 -46.573948)
		(end 309.604156 -46.573948)
		(width 0.12954)
		(layer "F.Cu")
		(net "SMB_HOST_BMC_3V3AUX_SCL")
	)
	(via
		(at 300.0883 -77.737208)
		(size 0.508)
		(drill 0.254)
		(layers "F.Cu" "B.Cu")
		(net "SMB_HOST_BMC_3V3AUX_SCL")
	)
	(via
		(at 4.29895 -51.654964)
		(size 0.508)
		(drill 0.254)
		(layers "F.Cu" "B.Cu")
		(net "SMB_HOST_BMC_3V3AUX_SCL")
	)
	(via
		(at 304.98288 -46.954948)
		(size 0.508)
		(drill 0.254)
		(layers "F.Cu" "B.Cu")
		(net "SMB_HOST_BMC_3V3AUX_SCL")
	)
	(segment
		(start 290.413948 -84.568538)
		(end 290.286948 -84.441538)
		(width 0.127)
		(layer "In6.Cu")
		(net "SMB_HOST_BMC_3V3AUX_SCL")
	)
	(segment
		(start 288.762948 -84.441538)
		(end 288.762948 -83.856068)
		(width 0.127)
		(layer "In6.Cu")
		(net "SMB_HOST_BMC_3V3AUX_SCL")
	)
	(segment
		(start 293.14775 -84.568538)
		(end 290.413948 -84.568538)
		(width 0.127)
		(layer "In6.Cu")
		(net "SMB_HOST_BMC_3V3AUX_SCL")
	)
	(segment
		(start 193.131694 -83.641692)
		(end 192.609724 -83.119722)
		(width 0.127)
		(layer "In6.Cu")
		(net "SMB_HOST_BMC_3V3AUX_SCL")
	)
	(segment
		(start 299.97908 -77.737208)
		(end 293.14775 -84.568538)
		(width 0.127)
		(layer "In6.Cu")
		(net "SMB_HOST_BMC_3V3AUX_SCL")
	)
	(segment
		(start 68.655438 -68.494148)
		(end 57.5437 -57.38241)
		(width 0.127)
		(layer "In6.Cu")
		(net "SMB_HOST_BMC_3V3AUX_SCL")
	)
	(segment
		(start 134.78002 -68.494148)
		(end 68.655438 -68.494148)
		(width 0.127)
		(layer "In6.Cu")
		(net "SMB_HOST_BMC_3V3AUX_SCL")
	)
	(segment
		(start 150.326852 -68.327778)
		(end 145.372836 -68.327778)
		(width 0.127)
		(layer "In6.Cu")
		(net "SMB_HOST_BMC_3V3AUX_SCL")
	)
	(segment
		(start 212.038438 -89.830148)
		(end 205.849982 -83.641692)
		(width 0.127)
		(layer "In6.Cu")
		(net "SMB_HOST_BMC_3V3AUX_SCL")
	)
	(segment
		(start 289.651948 -83.729068)
		(end 289.524948 -83.856068)
		(width 0.127)
		(layer "In6.Cu")
		(net "SMB_HOST_BMC_3V3AUX_SCL")
	)
	(segment
		(start 290.159948 -83.729068)
		(end 289.651948 -83.729068)
		(width 0.127)
		(layer "In6.Cu")
		(net "SMB_HOST_BMC_3V3AUX_SCL")
	)
	(segment
		(start 7.07009 -63.904876)
		(end 4.14528 -60.980066)
		(width 0.127)
		(layer "In6.Cu")
		(net "SMB_HOST_BMC_3V3AUX_SCL")
	)
	(segment
		(start 288.889948 -84.568538)
		(end 288.762948 -84.441538)
		(width 0.127)
		(layer "In6.Cu")
		(net "SMB_HOST_BMC_3V3AUX_SCL")
	)
	(segment
		(start 192.609724 -83.119722)
		(end 175.617124 -83.119722)
		(width 0.127)
		(layer "In6.Cu")
		(net "SMB_HOST_BMC_3V3AUX_SCL")
	)
	(segment
		(start 287.873948 -84.568538)
		(end 245.85422 -84.568538)
		(width 0.127)
		(layer "In6.Cu")
		(net "SMB_HOST_BMC_3V3AUX_SCL")
	)
	(segment
		(start 240.59261 -89.830148)
		(end 212.038438 -89.830148)
		(width 0.127)
		(layer "In6.Cu")
		(net "SMB_HOST_BMC_3V3AUX_SCL")
	)
	(segment
		(start 20.891754 -63.904876)
		(end 7.07009 -63.904876)
		(width 0.127)
		(layer "In6.Cu")
		(net "SMB_HOST_BMC_3V3AUX_SCL")
	)
	(segment
		(start 290.286948 -83.856068)
		(end 290.159948 -83.729068)
		(width 0.127)
		(layer "In6.Cu")
		(net "SMB_HOST_BMC_3V3AUX_SCL")
	)
	(segment
		(start 57.5437 -57.38241)
		(end 27.41422 -57.38241)
		(width 0.127)
		(layer "In6.Cu")
		(net "SMB_HOST_BMC_3V3AUX_SCL")
	)
	(segment
		(start 135.85698 -67.417188)
		(end 134.78002 -68.494148)
		(width 0.127)
		(layer "In6.Cu")
		(net "SMB_HOST_BMC_3V3AUX_SCL")
	)
	(segment
		(start 245.85422 -84.568538)
		(end 240.59261 -89.830148)
		(width 0.127)
		(layer "In6.Cu")
		(net "SMB_HOST_BMC_3V3AUX_SCL")
	)
	(segment
		(start 205.849982 -83.641692)
		(end 193.131694 -83.641692)
		(width 0.127)
		(layer "In6.Cu")
		(net "SMB_HOST_BMC_3V3AUX_SCL")
	)
	(segment
		(start 145.372836 -68.327778)
		(end 144.462246 -67.417188)
		(width 0.127)
		(layer "In6.Cu")
		(net "SMB_HOST_BMC_3V3AUX_SCL")
	)
	(segment
		(start 288.000948 -84.441538)
		(end 287.873948 -84.568538)
		(width 0.127)
		(layer "In6.Cu")
		(net "SMB_HOST_BMC_3V3AUX_SCL")
	)
	(segment
		(start 300.0883 -77.737208)
		(end 299.97908 -77.737208)
		(width 0.127)
		(layer "In6.Cu")
		(net "SMB_HOST_BMC_3V3AUX_SCL")
	)
	(segment
		(start 175.617124 -83.119722)
		(end 164.06495 -71.567548)
		(width 0.127)
		(layer "In6.Cu")
		(net "SMB_HOST_BMC_3V3AUX_SCL")
	)
	(segment
		(start 289.524948 -83.856068)
		(end 289.524948 -84.441538)
		(width 0.127)
		(layer "In6.Cu")
		(net "SMB_HOST_BMC_3V3AUX_SCL")
	)
	(segment
		(start 144.462246 -67.417188)
		(end 135.85698 -67.417188)
		(width 0.127)
		(layer "In6.Cu")
		(net "SMB_HOST_BMC_3V3AUX_SCL")
	)
	(segment
		(start 290.286948 -84.441538)
		(end 290.286948 -83.856068)
		(width 0.127)
		(layer "In6.Cu")
		(net "SMB_HOST_BMC_3V3AUX_SCL")
	)
	(segment
		(start 288.127948 -83.729068)
		(end 288.000948 -83.856068)
		(width 0.127)
		(layer "In6.Cu")
		(net "SMB_HOST_BMC_3V3AUX_SCL")
	)
	(segment
		(start 288.762948 -83.856068)
		(end 288.635948 -83.729068)
		(width 0.127)
		(layer "In6.Cu")
		(net "SMB_HOST_BMC_3V3AUX_SCL")
	)
	(segment
		(start 164.06495 -71.567548)
		(end 153.566622 -71.567548)
		(width 0.127)
		(layer "In6.Cu")
		(net "SMB_HOST_BMC_3V3AUX_SCL")
	)
	(segment
		(start 27.41422 -57.38241)
		(end 20.891754 -63.904876)
		(width 0.127)
		(layer "In6.Cu")
		(net "SMB_HOST_BMC_3V3AUX_SCL")
	)
	(segment
		(start 4.14528 -51.808634)
		(end 4.29895 -51.654964)
		(width 0.127)
		(layer "In6.Cu")
		(net "SMB_HOST_BMC_3V3AUX_SCL")
	)
	(segment
		(start 4.14528 -60.980066)
		(end 4.14528 -51.808634)
		(width 0.127)
		(layer "In6.Cu")
		(net "SMB_HOST_BMC_3V3AUX_SCL")
	)
	(segment
		(start 288.635948 -83.729068)
		(end 288.127948 -83.729068)
		(width 0.127)
		(layer "In6.Cu")
		(net "SMB_HOST_BMC_3V3AUX_SCL")
	)
	(segment
		(start 289.524948 -84.441538)
		(end 289.397948 -84.568538)
		(width 0.127)
		(layer "In6.Cu")
		(net "SMB_HOST_BMC_3V3AUX_SCL")
	)
	(segment
		(start 289.397948 -84.568538)
		(end 288.889948 -84.568538)
		(width 0.127)
		(layer "In6.Cu")
		(net "SMB_HOST_BMC_3V3AUX_SCL")
	)
	(segment
		(start 153.566622 -71.567548)
		(end 150.326852 -68.327778)
		(width 0.127)
		(layer "In6.Cu")
		(net "SMB_HOST_BMC_3V3AUX_SCL")
	)
	(segment
		(start 288.000948 -83.856068)
		(end 288.000948 -84.441538)
		(width 0.127)
		(layer "In6.Cu")
		(net "SMB_HOST_BMC_3V3AUX_SCL")
	)
	(segment
		(start 300.2915 -77.534008)
		(end 300.0883 -77.737208)
		(width 0.127)
		(layer "In11.Cu")
		(net "SMB_HOST_BMC_3V3AUX_SCL")
	)
	(segment
		(start 304.98288 -46.954948)
		(end 303.24298 -46.954948)
		(width 0.127)
		(layer "In11.Cu")
		(net "SMB_HOST_BMC_3V3AUX_SCL")
	)
	(segment
		(start 300.58868 -75.225148)
		(end 300.2915 -75.522328)
		(width 0.127)
		(layer "In11.Cu")
		(net "SMB_HOST_BMC_3V3AUX_SCL")
	)
	(segment
		(start 300.02734 -52.286408)
		(end 300.58868 -52.847748)
		(width 0.127)
		(layer "In11.Cu")
		(net "SMB_HOST_BMC_3V3AUX_SCL")
	)
	(segment
		(start 300.58868 -49.982628)
		(end 300.58868 -50.823368)
		(width 0.127)
		(layer "In11.Cu")
		(net "SMB_HOST_BMC_3V3AUX_SCL")
	)
	(segment
		(start 300.2915 -75.522328)
		(end 300.2915 -77.534008)
		(width 0.127)
		(layer "In11.Cu")
		(net "SMB_HOST_BMC_3V3AUX_SCL")
	)
	(segment
		(start 302.50638 -48.064928)
		(end 300.58868 -49.982628)
		(width 0.127)
		(layer "In11.Cu")
		(net "SMB_HOST_BMC_3V3AUX_SCL")
	)
	(segment
		(start 302.50638 -47.691548)
		(end 302.50638 -48.064928)
		(width 0.127)
		(layer "In11.Cu")
		(net "SMB_HOST_BMC_3V3AUX_SCL")
	)
	(segment
		(start 300.02734 -51.384708)
		(end 300.02734 -52.286408)
		(width 0.127)
		(layer "In11.Cu")
		(net "SMB_HOST_BMC_3V3AUX_SCL")
	)
	(segment
		(start 300.58868 -50.823368)
		(end 300.02734 -51.384708)
		(width 0.127)
		(layer "In11.Cu")
		(net "SMB_HOST_BMC_3V3AUX_SCL")
	)
	(segment
		(start 303.24298 -46.954948)
		(end 302.50638 -47.691548)
		(width 0.127)
		(layer "In11.Cu")
		(net "SMB_HOST_BMC_3V3AUX_SCL")
	)
	(segment
		(start 300.58868 -52.847748)
		(end 300.58868 -75.225148)
		(width 0.127)
		(layer "In11.Cu")
		(net "SMB_HOST_BMC_3V3AUX_SCL")
	)
	(segment
		(start 177.066956 -12.246864)
		(end 176.996852 -12.17676)
		(width 0.12954)
		(layer "F.Cu")
		(net "SMB_HOST_3V3AUX_SDA_R0")
	)
	(segment
		(start 177.066956 -13.600176)
		(end 177.066956 -12.246864)
		(width 0.12954)
		(layer "F.Cu")
		(net "SMB_HOST_3V3AUX_SDA_R0")
	)
	(via
		(at 181.102 -17.694148)
		(size 0.508)
		(drill 0.254)
		(layers "F.Cu" "B.Cu")
		(net "SMB_HOST_3V3AUX_SDA_R0")
	)
	(via
		(at 176.996852 -12.17676)
		(size 0.508)
		(drill 0.254)
		(layers "F.Cu" "B.Cu")
		(net "SMB_HOST_3V3AUX_SDA_R0")
	)
	(segment
		(start 181.102 -18.056098)
		(end 180.848 -18.310098)
		(width 0.12954)
		(layer "B.Cu")
		(net "SMB_HOST_3V3AUX_SDA_R0")
	)
	(segment
		(start 181.102 -17.694148)
		(end 181.102 -18.056098)
		(width 0.12954)
		(layer "B.Cu")
		(net "SMB_HOST_3V3AUX_SDA_R0")
	)
	(segment
		(start 178.19878 -13.879068)
		(end 176.996852 -12.67714)
		(width 0.127)
		(layer "In6.Cu")
		(net "SMB_HOST_3V3AUX_SDA_R0")
	)
	(segment
		(start 179.5526 -15.506446)
		(end 180.46954 -15.506446)
		(width 0.127)
		(layer "In6.Cu")
		(net "SMB_HOST_3V3AUX_SDA_R0")
	)
	(segment
		(start 179.4256 -15.633446)
		(end 179.5526 -15.506446)
		(width 0.127)
		(layer "In6.Cu")
		(net "SMB_HOST_3V3AUX_SDA_R0")
	)
	(segment
		(start 179.4256 -16.014446)
		(end 179.4256 -15.633446)
		(width 0.127)
		(layer "In6.Cu")
		(net "SMB_HOST_3V3AUX_SDA_R0")
	)
	(segment
		(start 180.59654 -15.379446)
		(end 180.59654 -15.083536)
		(width 0.127)
		(layer "In6.Cu")
		(net "SMB_HOST_3V3AUX_SDA_R0")
	)
	(segment
		(start 180.59654 -15.083536)
		(end 179.392072 -13.879068)
		(width 0.127)
		(layer "In6.Cu")
		(net "SMB_HOST_3V3AUX_SDA_R0")
	)
	(segment
		(start 176.996852 -12.67714)
		(end 176.996852 -12.17676)
		(width 0.127)
		(layer "In6.Cu")
		(net "SMB_HOST_3V3AUX_SDA_R0")
	)
	(segment
		(start 179.392072 -13.879068)
		(end 178.19878 -13.879068)
		(width 0.127)
		(layer "In6.Cu")
		(net "SMB_HOST_3V3AUX_SDA_R0")
	)
	(segment
		(start 181.102 -17.694148)
		(end 181.102 -16.773906)
		(width 0.127)
		(layer "In6.Cu")
		(net "SMB_HOST_3V3AUX_SDA_R0")
	)
	(segment
		(start 180.46954 -15.506446)
		(end 180.59654 -15.379446)
		(width 0.127)
		(layer "In6.Cu")
		(net "SMB_HOST_3V3AUX_SDA_R0")
	)
	(segment
		(start 179.5526 -16.141446)
		(end 179.4256 -16.014446)
		(width 0.127)
		(layer "In6.Cu")
		(net "SMB_HOST_3V3AUX_SDA_R0")
	)
	(segment
		(start 181.102 -16.773906)
		(end 180.46954 -16.141446)
		(width 0.127)
		(layer "In6.Cu")
		(net "SMB_HOST_3V3AUX_SDA_R0")
	)
	(segment
		(start 180.46954 -16.141446)
		(end 179.5526 -16.141446)
		(width 0.127)
		(layer "In6.Cu")
		(net "SMB_HOST_3V3AUX_SDA_R0")
	)
	(via
		(at 238.79556 -130.79095)
		(size 0.508)
		(drill 0.254)
		(layers "F.Cu" "B.Cu")
		(net "SMB_HOST_3V3AUX_SDA_R")
	)
	(via
		(at 241.27968 -102.768908)
		(size 0.508)
		(drill 0.254)
		(layers "F.Cu" "B.Cu")
		(net "SMB_HOST_3V3AUX_SDA_R")
	)
	(segment
		(start 237.69447 -130.298952)
		(end 238.161322 -130.765804)
		(width 0.12954)
		(layer "B.Cu")
		(net "SMB_HOST_3V3AUX_SDA_R")
	)
	(segment
		(start 239.615726 -129.070862)
		(end 239.149382 -129.537206)
		(width 0.12954)
		(layer "B.Cu")
		(net "SMB_HOST_3V3AUX_SDA_R")
	)
	(segment
		(start 242.360704 -102.768908)
		(end 242.600988 -102.528624)
		(width 0.12954)
		(layer "B.Cu")
		(net "SMB_HOST_3V3AUX_SDA_R")
	)
	(segment
		(start 237.69447 -129.662936)
		(end 237.69447 -130.298952)
		(width 0.12954)
		(layer "B.Cu")
		(net "SMB_HOST_3V3AUX_SDA_R")
	)
	(segment
		(start 237.8202 -129.537206)
		(end 237.69447 -129.662936)
		(width 0.12954)
		(layer "B.Cu")
		(net "SMB_HOST_3V3AUX_SDA_R")
	)
	(segment
		(start 238.161322 -130.765804)
		(end 238.161322 -130.79095)
		(width 0.12954)
		(layer "B.Cu")
		(net "SMB_HOST_3V3AUX_SDA_R")
	)
	(segment
		(start 239.149382 -129.537206)
		(end 237.8202 -129.537206)
		(width 0.12954)
		(layer "B.Cu")
		(net "SMB_HOST_3V3AUX_SDA_R")
	)
	(segment
		(start 238.79556 -130.79095)
		(end 238.161322 -130.79095)
		(width 0.12954)
		(layer "B.Cu")
		(net "SMB_HOST_3V3AUX_SDA_R")
	)
	(segment
		(start 241.27968 -102.768908)
		(end 242.360704 -102.768908)
		(width 0.12954)
		(layer "B.Cu")
		(net "SMB_HOST_3V3AUX_SDA_R")
	)
	(segment
		(start 239.94364 -122.970544)
		(end 239.6744 -122.970544)
		(width 0.127)
		(layer "In2.Cu")
		(net "SMB_HOST_3V3AUX_SDA_R")
	)
	(segment
		(start 239.42802 -124.274072)
		(end 239.94364 -124.274072)
		(width 0.127)
		(layer "In2.Cu")
		(net "SMB_HOST_3V3AUX_SDA_R")
	)
	(segment
		(start 240.07064 -125.264672)
		(end 239.94364 -125.137672)
		(width 0.127)
		(layer "In2.Cu")
		(net "SMB_HOST_3V3AUX_SDA_R")
	)
	(segment
		(start 239.94364 -124.274072)
		(end 240.07064 -124.147072)
		(width 0.127)
		(layer "In2.Cu")
		(net "SMB_HOST_3V3AUX_SDA_R")
	)
	(segment
		(start 245.80088 -110.30458)
		(end 245.67388 -110.17758)
		(width 0.127)
		(layer "In2.Cu")
		(net "SMB_HOST_3V3AUX_SDA_R")
	)
	(segment
		(start 240.07064 -123.097544)
		(end 239.94364 -122.970544)
		(width 0.127)
		(layer "In2.Cu")
		(net "SMB_HOST_3V3AUX_SDA_R")
	)
	(segment
		(start 239.19688 -128.107948)
		(end 239.19688 -127.472948)
		(width 0.127)
		(layer "In2.Cu")
		(net "SMB_HOST_3V3AUX_SDA_R")
	)
	(segment
		(start 239.42802 -125.137672)
		(end 239.30102 -125.010672)
		(width 0.127)
		(layer "In2.Cu")
		(net "SMB_HOST_3V3AUX_SDA_R")
	)
	(segment
		(start 238.568992 -128.735836)
		(end 239.19688 -128.107948)
		(width 0.127)
		(layer "In2.Cu")
		(net "SMB_HOST_3V3AUX_SDA_R")
	)
	(segment
		(start 244.3099 -108.39958)
		(end 244.4369 -108.27258)
		(width 0.127)
		(layer "In2.Cu")
		(net "SMB_HOST_3V3AUX_SDA_R")
	)
	(segment
		(start 239.5474 -122.843544)
		(end 239.5474 -122.462544)
		(width 0.127)
		(layer "In2.Cu")
		(net "SMB_HOST_3V3AUX_SDA_R")
	)
	(segment
		(start 244.4369 -108.90758)
		(end 244.3099 -108.78058)
		(width 0.127)
		(layer "In2.Cu")
		(net "SMB_HOST_3V3AUX_SDA_R")
	)
	(segment
		(start 239.19688 -127.472948)
		(end 240.07064 -126.599188)
		(width 0.127)
		(layer "In2.Cu")
		(net "SMB_HOST_3V3AUX_SDA_R")
	)
	(segment
		(start 239.5474 -122.462544)
		(end 239.6744 -122.335544)
		(width 0.127)
		(layer "In2.Cu")
		(net "SMB_HOST_3V3AUX_SDA_R")
	)
	(segment
		(start 240.07064 -124.147072)
		(end 240.07064 -123.097544)
		(width 0.127)
		(layer "In2.Cu")
		(net "SMB_HOST_3V3AUX_SDA_R")
	)
	(segment
		(start 238.568992 -130.564382)
		(end 238.568992 -128.735836)
		(width 0.127)
		(layer "In2.Cu")
		(net "SMB_HOST_3V3AUX_SDA_R")
	)
	(segment
		(start 239.94364 -121.065544)
		(end 240.07064 -120.938544)
		(width 0.127)
		(layer "In2.Cu")
		(net "SMB_HOST_3V3AUX_SDA_R")
	)
	(segment
		(start 245.80088 -108.14558)
		(end 245.80088 -106.515408)
		(width 0.127)
		(layer "In2.Cu")
		(net "SMB_HOST_3V3AUX_SDA_R")
	)
	(segment
		(start 244.4369 -110.17758)
		(end 244.3099 -110.05058)
		(width 0.127)
		(layer "In2.Cu")
		(net "SMB_HOST_3V3AUX_SDA_R")
	)
	(segment
		(start 240.07064 -122.208544)
		(end 240.07064 -121.827544)
		(width 0.127)
		(layer "In2.Cu")
		(net "SMB_HOST_3V3AUX_SDA_R")
	)
	(segment
		(start 245.67388 -109.54258)
		(end 245.80088 -109.41558)
		(width 0.127)
		(layer "In2.Cu")
		(net "SMB_HOST_3V3AUX_SDA_R")
	)
	(segment
		(start 245.80088 -106.515408)
		(end 242.05438 -102.768908)
		(width 0.127)
		(layer "In2.Cu")
		(net "SMB_HOST_3V3AUX_SDA_R")
	)
	(segment
		(start 244.3099 -109.66958)
		(end 244.4369 -109.54258)
		(width 0.127)
		(layer "In2.Cu")
		(net "SMB_HOST_3V3AUX_SDA_R")
	)
	(segment
		(start 239.6744 -122.970544)
		(end 239.5474 -122.843544)
		(width 0.127)
		(layer "In2.Cu")
		(net "SMB_HOST_3V3AUX_SDA_R")
	)
	(segment
		(start 244.3099 -108.78058)
		(end 244.3099 -108.39958)
		(width 0.127)
		(layer "In2.Cu")
		(net "SMB_HOST_3V3AUX_SDA_R")
	)
	(segment
		(start 244.4369 -109.54258)
		(end 245.67388 -109.54258)
		(width 0.127)
		(layer "In2.Cu")
		(net "SMB_HOST_3V3AUX_SDA_R")
	)
	(segment
		(start 242.05438 -102.768908)
		(end 241.27968 -102.768908)
		(width 0.127)
		(layer "In2.Cu")
		(net "SMB_HOST_3V3AUX_SDA_R")
	)
	(segment
		(start 245.80088 -109.41558)
		(end 245.80088 -109.03458)
		(width 0.127)
		(layer "In2.Cu")
		(net "SMB_HOST_3V3AUX_SDA_R")
	)
	(segment
		(start 240.07064 -121.827544)
		(end 239.94364 -121.700544)
		(width 0.127)
		(layer "In2.Cu")
		(net "SMB_HOST_3V3AUX_SDA_R")
	)
	(segment
		(start 245.67388 -108.90758)
		(end 244.4369 -108.90758)
		(width 0.127)
		(layer "In2.Cu")
		(net "SMB_HOST_3V3AUX_SDA_R")
	)
	(segment
		(start 239.5474 -121.192544)
		(end 239.6744 -121.065544)
		(width 0.127)
		(layer "In2.Cu")
		(net "SMB_HOST_3V3AUX_SDA_R")
	)
	(segment
		(start 245.67388 -110.17758)
		(end 244.4369 -110.17758)
		(width 0.127)
		(layer "In2.Cu")
		(net "SMB_HOST_3V3AUX_SDA_R")
	)
	(segment
		(start 239.94364 -121.700544)
		(end 239.6744 -121.700544)
		(width 0.127)
		(layer "In2.Cu")
		(net "SMB_HOST_3V3AUX_SDA_R")
	)
	(segment
		(start 238.79556 -130.79095)
		(end 238.568992 -130.564382)
		(width 0.127)
		(layer "In2.Cu")
		(net "SMB_HOST_3V3AUX_SDA_R")
	)
	(segment
		(start 239.94364 -122.335544)
		(end 240.07064 -122.208544)
		(width 0.127)
		(layer "In2.Cu")
		(net "SMB_HOST_3V3AUX_SDA_R")
	)
	(segment
		(start 239.6744 -121.700544)
		(end 239.5474 -121.573544)
		(width 0.127)
		(layer "In2.Cu")
		(net "SMB_HOST_3V3AUX_SDA_R")
	)
	(segment
		(start 239.6744 -121.065544)
		(end 239.94364 -121.065544)
		(width 0.127)
		(layer "In2.Cu")
		(net "SMB_HOST_3V3AUX_SDA_R")
	)
	(segment
		(start 244.3099 -110.05058)
		(end 244.3099 -109.66958)
		(width 0.127)
		(layer "In2.Cu")
		(net "SMB_HOST_3V3AUX_SDA_R")
	)
	(segment
		(start 240.07064 -120.433084)
		(end 245.80088 -114.702844)
		(width 0.127)
		(layer "In2.Cu")
		(net "SMB_HOST_3V3AUX_SDA_R")
	)
	(segment
		(start 239.30102 -125.010672)
		(end 239.30102 -124.401072)
		(width 0.127)
		(layer "In2.Cu")
		(net "SMB_HOST_3V3AUX_SDA_R")
	)
	(segment
		(start 239.30102 -124.401072)
		(end 239.42802 -124.274072)
		(width 0.127)
		(layer "In2.Cu")
		(net "SMB_HOST_3V3AUX_SDA_R")
	)
	(segment
		(start 240.07064 -126.599188)
		(end 240.07064 -125.264672)
		(width 0.127)
		(layer "In2.Cu")
		(net "SMB_HOST_3V3AUX_SDA_R")
	)
	(segment
		(start 244.4369 -108.27258)
		(end 245.67388 -108.27258)
		(width 0.127)
		(layer "In2.Cu")
		(net "SMB_HOST_3V3AUX_SDA_R")
	)
	(segment
		(start 245.80088 -114.702844)
		(end 245.80088 -110.30458)
		(width 0.127)
		(layer "In2.Cu")
		(net "SMB_HOST_3V3AUX_SDA_R")
	)
	(segment
		(start 239.94364 -125.137672)
		(end 239.42802 -125.137672)
		(width 0.127)
		(layer "In2.Cu")
		(net "SMB_HOST_3V3AUX_SDA_R")
	)
	(segment
		(start 245.67388 -108.27258)
		(end 245.80088 -108.14558)
		(width 0.127)
		(layer "In2.Cu")
		(net "SMB_HOST_3V3AUX_SDA_R")
	)
	(segment
		(start 240.07064 -120.938544)
		(end 240.07064 -120.433084)
		(width 0.127)
		(layer "In2.Cu")
		(net "SMB_HOST_3V3AUX_SDA_R")
	)
	(segment
		(start 239.6744 -122.335544)
		(end 239.94364 -122.335544)
		(width 0.127)
		(layer "In2.Cu")
		(net "SMB_HOST_3V3AUX_SDA_R")
	)
	(segment
		(start 239.5474 -121.573544)
		(end 239.5474 -121.192544)
		(width 0.127)
		(layer "In2.Cu")
		(net "SMB_HOST_3V3AUX_SDA_R")
	)
	(segment
		(start 245.80088 -109.03458)
		(end 245.67388 -108.90758)
		(width 0.127)
		(layer "In2.Cu")
		(net "SMB_HOST_3V3AUX_SDA_R")
	)
	(via
		(at 180.463444 -19.73453)
		(size 0.6604)
		(drill 0.254)
		(layers "F.Cu" "B.Cu")
		(net "SMB_HOST_3V3AUX_SDA")
	)
	(segment
		(start 180.87975 -20.970748)
		(end 180.8734 -20.964398)
		(width 0.12954)
		(layer "B.Cu")
		(net "SMB_HOST_3V3AUX_SDA")
	)
	(segment
		(start 180.463444 -20.554442)
		(end 180.8734 -20.964398)
		(width 0.12954)
		(layer "B.Cu")
		(net "SMB_HOST_3V3AUX_SDA")
	)
	(segment
		(start 181.84495 -20.970748)
		(end 180.87975 -20.970748)
		(width 0.12954)
		(layer "B.Cu")
		(net "SMB_HOST_3V3AUX_SDA")
	)
	(segment
		(start 179.85994 -20.964398)
		(end 180.8734 -20.964398)
		(width 0.12954)
		(layer "B.Cu")
		(net "SMB_HOST_3V3AUX_SDA")
	)
	(segment
		(start 180.848 -19.349974)
		(end 180.463444 -19.73453)
		(width 0.12954)
		(layer "B.Cu")
		(net "SMB_HOST_3V3AUX_SDA")
	)
	(segment
		(start 180.463444 -19.73453)
		(end 180.463444 -20.554442)
		(width 0.12954)
		(layer "B.Cu")
		(net "SMB_HOST_3V3AUX_SDA")
	)
	(segment
		(start 180.848 -19.110198)
		(end 180.848 -19.349974)
		(width 0.12954)
		(layer "B.Cu")
		(net "SMB_HOST_3V3AUX_SDA")
	)
	(segment
		(start 177.047144 -10.695432)
		(end 176.9872 -10.695432)
		(width 0.12954)
		(layer "F.Cu")
		(net "SMB_HOST_3V3AUX_SCL_R0")
	)
	(segment
		(start 177.666904 -11.315192)
		(end 177.047144 -10.695432)
		(width 0.12954)
		(layer "F.Cu")
		(net "SMB_HOST_3V3AUX_SCL_R0")
	)
	(segment
		(start 177.666904 -13.600176)
		(end 177.666904 -11.315192)
		(width 0.12954)
		(layer "F.Cu")
		(net "SMB_HOST_3V3AUX_SCL_R0")
	)
	(via
		(at 176.9872 -10.695432)
		(size 0.508)
		(drill 0.254)
		(layers "F.Cu" "B.Cu")
		(net "SMB_HOST_3V3AUX_SCL_R0")
	)
	(via
		(at 181.86146 -17.694148)
		(size 0.508)
		(drill 0.254)
		(layers "F.Cu" "B.Cu")
		(net "SMB_HOST_3V3AUX_SCL_R0")
	)
	(segment
		(start 181.86146 -18.310098)
		(end 181.86146 -17.694148)
		(width 0.12954)
		(layer "B.Cu")
		(net "SMB_HOST_3V3AUX_SCL_R0")
	)
	(segment
		(start 178.09464 -12.875768)
		(end 179.09032 -12.875768)
		(width 0.127)
		(layer "In6.Cu")
		(net "SMB_HOST_3V3AUX_SCL_R0")
	)
	(segment
		(start 176.9872 -10.695432)
		(end 177.123344 -10.695432)
		(width 0.127)
		(layer "In6.Cu")
		(net "SMB_HOST_3V3AUX_SCL_R0")
	)
	(segment
		(start 181.019704 -14.805152)
		(end 181.86146 -16.836898)
		(width 0.127)
		(layer "In6.Cu")
		(net "SMB_HOST_3V3AUX_SCL_R0")
	)
	(segment
		(start 177.7873 -12.568428)
		(end 178.09464 -12.875768)
		(width 0.127)
		(layer "In6.Cu")
		(net "SMB_HOST_3V3AUX_SCL_R0")
	)
	(segment
		(start 177.7873 -11.359388)
		(end 177.7873 -12.568428)
		(width 0.127)
		(layer "In6.Cu")
		(net "SMB_HOST_3V3AUX_SCL_R0")
	)
	(segment
		(start 177.123344 -10.695432)
		(end 177.7873 -11.359388)
		(width 0.127)
		(layer "In6.Cu")
		(net "SMB_HOST_3V3AUX_SCL_R0")
	)
	(segment
		(start 179.09032 -12.875768)
		(end 181.019704 -14.805152)
		(width 0.127)
		(layer "In6.Cu")
		(net "SMB_HOST_3V3AUX_SCL_R0")
	)
	(segment
		(start 181.86146 -16.836898)
		(end 181.86146 -17.694148)
		(width 0.127)
		(layer "In6.Cu")
		(net "SMB_HOST_3V3AUX_SCL_R0")
	)
	(via
		(at 240.163096 -130.932682)
		(size 0.508)
		(drill 0.254)
		(layers "F.Cu" "B.Cu")
		(net "SMB_HOST_3V3AUX_SCL_R")
	)
	(via
		(at 241.46764 -101.465888)
		(size 0.508)
		(drill 0.254)
		(layers "F.Cu" "B.Cu")
		(net "SMB_HOST_3V3AUX_SCL_R")
	)
	(segment
		(start 237.029244 -132.864352)
		(end 237.029244 -132.445506)
		(width 0.12954)
		(layer "B.Cu")
		(net "SMB_HOST_3V3AUX_SCL_R")
	)
	(segment
		(start 235.811822 -132.503164)
		(end 236.341158 -132.503164)
		(width 0.12954)
		(layer "B.Cu")
		(net "SMB_HOST_3V3AUX_SCL_R")
	)
	(segment
		(start 240.317528 -131.305808)
		(end 240.317528 -131.720082)
		(width 0.12954)
		(layer "B.Cu")
		(net "SMB_HOST_3V3AUX_SCL_R")
	)
	(segment
		(start 240.317528 -131.720082)
		(end 239.808258 -132.949442)
		(width 0.12954)
		(layer "B.Cu")
		(net "SMB_HOST_3V3AUX_SCL_R")
	)
	(segment
		(start 238.424466 -133.40588)
		(end 238.117634 -133.099048)
		(width 0.12954)
		(layer "B.Cu")
		(net "SMB_HOST_3V3AUX_SCL_R")
	)
	(segment
		(start 236.42193 -132.422392)
		(end 237.00613 -132.422392)
		(width 0.12954)
		(layer "B.Cu")
		(net "SMB_HOST_3V3AUX_SCL_R")
	)
	(segment
		(start 237.26394 -133.099048)
		(end 237.029244 -132.864352)
		(width 0.12954)
		(layer "B.Cu")
		(net "SMB_HOST_3V3AUX_SCL_R")
	)
	(segment
		(start 239.808258 -132.949442)
		(end 239.35182 -133.40588)
		(width 0.12954)
		(layer "B.Cu")
		(net "SMB_HOST_3V3AUX_SCL_R")
	)
	(segment
		(start 237.029244 -132.445506)
		(end 237.00613 -132.422392)
		(width 0.12954)
		(layer "B.Cu")
		(net "SMB_HOST_3V3AUX_SCL_R")
	)
	(segment
		(start 241.46764 -101.465888)
		(end 242.582954 -101.465888)
		(width 0.12954)
		(layer "B.Cu")
		(net "SMB_HOST_3V3AUX_SCL_R")
	)
	(segment
		(start 239.35182 -133.40588)
		(end 238.424466 -133.40588)
		(width 0.12954)
		(layer "B.Cu")
		(net "SMB_HOST_3V3AUX_SCL_R")
	)
	(segment
		(start 240.163096 -130.932682)
		(end 240.317528 -131.305808)
		(width 0.12954)
		(layer "B.Cu")
		(net "SMB_HOST_3V3AUX_SCL_R")
	)
	(segment
		(start 238.117634 -133.099048)
		(end 237.26394 -133.099048)
		(width 0.12954)
		(layer "B.Cu")
		(net "SMB_HOST_3V3AUX_SCL_R")
	)
	(segment
		(start 242.582954 -101.465888)
		(end 242.600988 -101.447854)
		(width 0.12954)
		(layer "B.Cu")
		(net "SMB_HOST_3V3AUX_SCL_R")
	)
	(segment
		(start 236.341158 -132.503164)
		(end 236.42193 -132.422392)
		(width 0.12954)
		(layer "B.Cu")
		(net "SMB_HOST_3V3AUX_SCL_R")
	)
	(segment
		(start 246.23268 -114.882168)
		(end 246.23268 -106.230928)
		(width 0.127)
		(layer "In2.Cu")
		(net "SMB_HOST_3V3AUX_SCL_R")
	)
	(segment
		(start 239.70488 -127.575818)
		(end 240.50244 -126.778258)
		(width 0.127)
		(layer "In2.Cu")
		(net "SMB_HOST_3V3AUX_SCL_R")
	)
	(segment
		(start 240.50244 -120.612408)
		(end 246.23268 -114.882168)
		(width 0.127)
		(layer "In2.Cu")
		(net "SMB_HOST_3V3AUX_SCL_R")
	)
	(segment
		(start 240.50244 -126.778258)
		(end 240.50244 -120.612408)
		(width 0.127)
		(layer "In2.Cu")
		(net "SMB_HOST_3V3AUX_SCL_R")
	)
	(segment
		(start 240.163096 -130.932682)
		(end 240.163096 -129.594356)
		(width 0.127)
		(layer "In2.Cu")
		(net "SMB_HOST_3V3AUX_SCL_R")
	)
	(segment
		(start 239.70488 -129.13614)
		(end 239.70488 -127.575818)
		(width 0.127)
		(layer "In2.Cu")
		(net "SMB_HOST_3V3AUX_SCL_R")
	)
	(segment
		(start 246.23268 -106.230928)
		(end 241.46764 -101.465888)
		(width 0.127)
		(layer "In2.Cu")
		(net "SMB_HOST_3V3AUX_SCL_R")
	)
	(segment
		(start 240.163096 -129.594356)
		(end 239.70488 -129.13614)
		(width 0.127)
		(layer "In2.Cu")
		(net "SMB_HOST_3V3AUX_SCL_R")
	)
	(segment
		(start 222.67672 -112.306608)
		(end 223.81718 -111.166148)
		(width 0.12954)
		(layer "F.Cu")
		(net "SMB_HOST_3V3AUX_SCL")
	)
	(segment
		(start 225.848926 -85.402928)
		(end 226.93376 -85.402928)
		(width 0.12954)
		(layer "F.Cu")
		(net "SMB_HOST_3V3AUX_SCL")
	)
	(segment
		(start 215.081104 -92.517468)
		(end 214.23249 -91.668854)
		(width 0.12954)
		(layer "F.Cu")
		(net "SMB_HOST_3V3AUX_SCL")
	)
	(segment
		(start 219.966032 -92.517468)
		(end 215.081104 -92.517468)
		(width 0.12954)
		(layer "F.Cu")
		(net "SMB_HOST_3V3AUX_SCL")
	)
	(segment
		(start 245.969536 -61.787786)
		(end 239.110774 -68.646548)
		(width 0.12954)
		(layer "F.Cu")
		(net "SMB_HOST_3V3AUX_SCL")
	)
	(segment
		(start 214.221568 -116.507768)
		(end 216.49436 -116.507768)
		(width 0.12954)
		(layer "F.Cu")
		(net "SMB_HOST_3V3AUX_SCL")
	)
	(segment
		(start 210.693 -92.517468)
		(end 208.788 -92.517468)
		(width 0.12954)
		(layer "F.Cu")
		(net "SMB_HOST_3V3AUX_SCL")
	)
	(segment
		(start 225.683318 -84.359496)
		(end 225.683318 -85.23732)
		(width 0.12954)
		(layer "F.Cu")
		(net "SMB_HOST_3V3AUX_SCL")
	)
	(segment
		(start 208.788 -92.517468)
		(end 206.55534 -94.750128)
		(width 0.12954)
		(layer "F.Cu")
		(net "SMB_HOST_3V3AUX_SCL")
	)
	(segment
		(start 245.969536 -61.480954)
		(end 245.969536 -61.787786)
		(width 0.12954)
		(layer "F.Cu")
		(net "SMB_HOST_3V3AUX_SCL")
	)
	(segment
		(start 239.110774 -68.646548)
		(end 236.006386 -68.646548)
		(width 0.12954)
		(layer "F.Cu")
		(net "SMB_HOST_3V3AUX_SCL")
	)
	(segment
		(start 217.79992 -115.202208)
		(end 217.79992 -113.195608)
		(width 0.12954)
		(layer "F.Cu")
		(net "SMB_HOST_3V3AUX_SCL")
	)
	(segment
		(start 214.23249 -91.668854)
		(end 211.541614 -91.668854)
		(width 0.12954)
		(layer "F.Cu")
		(net "SMB_HOST_3V3AUX_SCL")
	)
	(segment
		(start 226.518978 -78.133956)
		(end 226.518978 -83.523836)
		(width 0.12954)
		(layer "F.Cu")
		(net "SMB_HOST_3V3AUX_SCL")
	)
	(segment
		(start 236.006386 -68.646548)
		(end 226.518978 -78.133956)
		(width 0.12954)
		(layer "F.Cu")
		(net "SMB_HOST_3V3AUX_SCL")
	)
	(segment
		(start 211.541614 -91.668854)
		(end 210.693 -92.517468)
		(width 0.12954)
		(layer "F.Cu")
		(net "SMB_HOST_3V3AUX_SCL")
	)
	(segment
		(start 213.6648 -115.951)
		(end 214.221568 -116.507768)
		(width 0.12954)
		(layer "F.Cu")
		(net "SMB_HOST_3V3AUX_SCL")
	)
	(segment
		(start 223.81718 -96.368616)
		(end 219.966032 -92.517468)
		(width 0.12954)
		(layer "F.Cu")
		(net "SMB_HOST_3V3AUX_SCL")
	)
	(segment
		(start 206.55534 -94.750128)
		(end 206.55534 -95.070168)
		(width 0.12954)
		(layer "F.Cu")
		(net "SMB_HOST_3V3AUX_SCL")
	)
	(segment
		(start 223.81718 -111.166148)
		(end 223.81718 -96.368616)
		(width 0.12954)
		(layer "F.Cu")
		(net "SMB_HOST_3V3AUX_SCL")
	)
	(segment
		(start 216.49436 -116.507768)
		(end 217.79992 -115.202208)
		(width 0.12954)
		(layer "F.Cu")
		(net "SMB_HOST_3V3AUX_SCL")
	)
	(segment
		(start 226.518978 -83.523836)
		(end 225.683318 -84.359496)
		(width 0.12954)
		(layer "F.Cu")
		(net "SMB_HOST_3V3AUX_SCL")
	)
	(segment
		(start 217.79992 -113.195608)
		(end 218.68892 -112.306608)
		(width 0.12954)
		(layer "F.Cu")
		(net "SMB_HOST_3V3AUX_SCL")
	)
	(segment
		(start 225.683318 -85.23732)
		(end 225.848926 -85.402928)
		(width 0.12954)
		(layer "F.Cu")
		(net "SMB_HOST_3V3AUX_SCL")
	)
	(segment
		(start 218.68892 -112.306608)
		(end 222.67672 -112.306608)
		(width 0.12954)
		(layer "F.Cu")
		(net "SMB_HOST_3V3AUX_SCL")
	)
	(via
		(at 206.55534 -95.070168)
		(size 0.508)
		(drill 0.254)
		(layers "F.Cu" "B.Cu")
		(net "SMB_HOST_3V3AUX_SCL")
	)
	(via
		(at 245.969536 -61.480954)
		(size 0.508)
		(drill 0.254)
		(layers "F.Cu" "B.Cu")
		(net "SMB_HOST_3V3AUX_SCL")
	)
	(via
		(at 238.8997 -131.4196)
		(size 0.508)
		(drill 0.254)
		(layers "F.Cu" "B.Cu")
		(net "SMB_HOST_3V3AUX_SCL")
	)
	(via
		(at 226.93376 -85.402928)
		(size 0.508)
		(drill 0.254)
		(layers "F.Cu" "B.Cu")
		(net "SMB_HOST_3V3AUX_SCL")
	)
	(via
		(at 213.6648 -115.951)
		(size 0.508)
		(drill 0.254)
		(layers "F.Cu" "B.Cu")
		(net "SMB_HOST_3V3AUX_SCL")
	)
	(segment
		(start 184.6453 -20.951698)
		(end 184.912 -20.684998)
		(width 0.12954)
		(layer "B.Cu")
		(net "SMB_HOST_3V3AUX_SCL")
	)
	(segment
		(start 181.86146 -19.110198)
		(end 181.86146 -19.901408)
		(width 0.12954)
		(layer "B.Cu")
		(net "SMB_HOST_3V3AUX_SCL")
	)
	(segment
		(start 236.849666 -55.722266)
		(end 244.543326 -55.722266)
		(width 0.12954)
		(layer "B.Cu")
		(net "SMB_HOST_3V3AUX_SCL")
	)
	(segment
		(start 244.543326 -55.722266)
		(end 245.969536 -57.148476)
		(width 0.12954)
		(layer "B.Cu")
		(net "SMB_HOST_3V3AUX_SCL")
	)
	(segment
		(start 238.772192 -131.547108)
		(end 238.20374 -131.547108)
		(width 0.12954)
		(layer "B.Cu")
		(net "SMB_HOST_3V3AUX_SCL")
	)
	(segment
		(start 183.438546 -20.284948)
		(end 183.7436 -20.590002)
		(width 0.12954)
		(layer "B.Cu")
		(net "SMB_HOST_3V3AUX_SCL")
	)
	(segment
		(start 182.245 -20.284948)
		(end 183.438546 -20.284948)
		(width 0.12954)
		(layer "B.Cu")
		(net "SMB_HOST_3V3AUX_SCL")
	)
	(segment
		(start 238.8997 -131.4196)
		(end 238.772192 -131.547108)
		(width 0.12954)
		(layer "B.Cu")
		(net "SMB_HOST_3V3AUX_SCL")
	)
	(segment
		(start 182.16626 -23.310088)
		(end 182.16626 -27.013916)
		(width 0.12954)
		(layer "B.Cu")
		(net "SMB_HOST_3V3AUX_SCL")
	)
	(segment
		(start 186.530742 -38.36035)
		(end 193.875152 -38.36035)
		(width 0.12954)
		(layer "B.Cu")
		(net "SMB_HOST_3V3AUX_SCL")
	)
	(segment
		(start 184.912 -20.684998)
		(end 184.912 -22.266148)
		(width 0.12954)
		(layer "B.Cu")
		(net "SMB_HOST_3V3AUX_SCL")
	)
	(segment
		(start 185.104532 -34.880296)
		(end 185.104532 -36.93414)
		(width 0.12954)
		(layer "B.Cu")
		(net "SMB_HOST_3V3AUX_SCL")
	)
	(segment
		(start 181.86146 -19.901408)
		(end 182.245 -20.284948)
		(width 0.12954)
		(layer "B.Cu")
		(net "SMB_HOST_3V3AUX_SCL")
	)
	(segment
		(start 182.6387 -22.837648)
		(end 182.16626 -23.310088)
		(width 0.12954)
		(layer "B.Cu")
		(net "SMB_HOST_3V3AUX_SCL")
	)
	(segment
		(start 184.3405 -22.837648)
		(end 182.6387 -22.837648)
		(width 0.12954)
		(layer "B.Cu")
		(net "SMB_HOST_3V3AUX_SCL")
	)
	(segment
		(start 237.195868 -130.539236)
		(end 237.195868 -130.0988)
		(width 0.12954)
		(layer "B.Cu")
		(net "SMB_HOST_3V3AUX_SCL")
	)
	(segment
		(start 183.606948 -33.382712)
		(end 185.104532 -34.880296)
		(width 0.12954)
		(layer "B.Cu")
		(net "SMB_HOST_3V3AUX_SCL")
	)
	(segment
		(start 237.195868 -130.0988)
		(end 237.16996 -130.072892)
		(width 0.12954)
		(layer "B.Cu")
		(net "SMB_HOST_3V3AUX_SCL")
	)
	(segment
		(start 213.29777 -39.444168)
		(end 222.07474 -48.221138)
		(width 0.12954)
		(layer "B.Cu")
		(net "SMB_HOST_3V3AUX_SCL")
	)
	(segment
		(start 194.739006 -37.496496)
		(end 196.48424 -37.496496)
		(width 0.12954)
		(layer "B.Cu")
		(net "SMB_HOST_3V3AUX_SCL")
	)
	(segment
		(start 183.24195 -33.382712)
		(end 183.606948 -33.382712)
		(width 0.12954)
		(layer "B.Cu")
		(net "SMB_HOST_3V3AUX_SCL")
	)
	(segment
		(start 223.526604 -48.221138)
		(end 224.542604 -49.237138)
		(width 0.12954)
		(layer "B.Cu")
		(net "SMB_HOST_3V3AUX_SCL")
	)
	(segment
		(start 180.249068 -30.38983)
		(end 183.24195 -33.382712)
		(width 0.12954)
		(layer "B.Cu")
		(net "SMB_HOST_3V3AUX_SCL")
	)
	(segment
		(start 183.7436 -20.590002)
		(end 183.7436 -20.951698)
		(width 0.12954)
		(layer "B.Cu")
		(net "SMB_HOST_3V3AUX_SCL")
	)
	(segment
		(start 183.7436 -20.951698)
		(end 184.6453 -20.951698)
		(width 0.12954)
		(layer "B.Cu")
		(net "SMB_HOST_3V3AUX_SCL")
	)
	(segment
		(start 231.674162 -50.546762)
		(end 236.849666 -55.722266)
		(width 0.12954)
		(layer "B.Cu")
		(net "SMB_HOST_3V3AUX_SCL")
	)
	(segment
		(start 245.969536 -57.148476)
		(end 245.969536 -61.480954)
		(width 0.12954)
		(layer "B.Cu")
		(net "SMB_HOST_3V3AUX_SCL")
	)
	(segment
		(start 198.431912 -39.444168)
		(end 213.29777 -39.444168)
		(width 0.12954)
		(layer "B.Cu")
		(net "SMB_HOST_3V3AUX_SCL")
	)
	(segment
		(start 229.313994 -49.237138)
		(end 230.623618 -50.546762)
		(width 0.12954)
		(layer "B.Cu")
		(net "SMB_HOST_3V3AUX_SCL")
	)
	(segment
		(start 182.16626 -27.013916)
		(end 180.249068 -28.931108)
		(width 0.12954)
		(layer "B.Cu")
		(net "SMB_HOST_3V3AUX_SCL")
	)
	(segment
		(start 185.104532 -36.93414)
		(end 186.530742 -38.36035)
		(width 0.12954)
		(layer "B.Cu")
		(net "SMB_HOST_3V3AUX_SCL")
	)
	(segment
		(start 222.07474 -48.221138)
		(end 223.526604 -48.221138)
		(width 0.12954)
		(layer "B.Cu")
		(net "SMB_HOST_3V3AUX_SCL")
	)
	(segment
		(start 224.542604 -49.237138)
		(end 229.313994 -49.237138)
		(width 0.12954)
		(layer "B.Cu")
		(net "SMB_HOST_3V3AUX_SCL")
	)
	(segment
		(start 238.20374 -131.547108)
		(end 237.195868 -130.539236)
		(width 0.12954)
		(layer "B.Cu")
		(net "SMB_HOST_3V3AUX_SCL")
	)
	(segment
		(start 180.249068 -28.931108)
		(end 180.249068 -30.38983)
		(width 0.12954)
		(layer "B.Cu")
		(net "SMB_HOST_3V3AUX_SCL")
	)
	(segment
		(start 196.48424 -37.496496)
		(end 198.431912 -39.444168)
		(width 0.12954)
		(layer "B.Cu")
		(net "SMB_HOST_3V3AUX_SCL")
	)
	(segment
		(start 193.875152 -38.36035)
		(end 194.739006 -37.496496)
		(width 0.12954)
		(layer "B.Cu")
		(net "SMB_HOST_3V3AUX_SCL")
	)
	(segment
		(start 184.912 -22.266148)
		(end 184.3405 -22.837648)
		(width 0.12954)
		(layer "B.Cu")
		(net "SMB_HOST_3V3AUX_SCL")
	)
	(segment
		(start 230.623618 -50.546762)
		(end 231.674162 -50.546762)
		(width 0.12954)
		(layer "B.Cu")
		(net "SMB_HOST_3V3AUX_SCL")
	)
	(segment
		(start 228.38664 -126.710694)
		(end 228.38664 -121.899934)
		(width 0.127)
		(layer "In11.Cu")
		(net "SMB_HOST_3V3AUX_SCL")
	)
	(segment
		(start 212.860128 -93.424248)
		(end 215.383618 -90.900758)
		(width 0.127)
		(layer "In11.Cu")
		(net "SMB_HOST_3V3AUX_SCL")
	)
	(segment
		(start 228.38664 -121.899934)
		(end 224.503234 -118.016528)
		(width 0.127)
		(layer "In11.Cu")
		(net "SMB_HOST_3V3AUX_SCL")
	)
	(segment
		(start 229.88524 -128.209294)
		(end 228.38664 -126.710694)
		(width 0.127)
		(layer "In11.Cu")
		(net "SMB_HOST_3V3AUX_SCL")
	)
	(segment
		(start 229.88524 -130.438398)
		(end 229.88524 -128.209294)
		(width 0.127)
		(layer "In11.Cu")
		(net "SMB_HOST_3V3AUX_SCL")
	)
	(segment
		(start 206.55534 -94.310708)
		(end 207.4418 -93.424248)
		(width 0.127)
		(layer "In11.Cu")
		(net "SMB_HOST_3V3AUX_SCL")
	)
	(segment
		(start 230.951786 -131.504944)
		(end 229.88524 -130.438398)
		(width 0.127)
		(layer "In11.Cu")
		(net "SMB_HOST_3V3AUX_SCL")
	)
	(segment
		(start 216.05875 -90.900758)
		(end 221.55658 -85.402928)
		(width 0.127)
		(layer "In11.Cu")
		(net "SMB_HOST_3V3AUX_SCL")
	)
	(segment
		(start 215.730328 -118.016528)
		(end 213.6648 -115.951)
		(width 0.127)
		(layer "In11.Cu")
		(net "SMB_HOST_3V3AUX_SCL")
	)
	(segment
		(start 215.383618 -90.900758)
		(end 216.05875 -90.900758)
		(width 0.127)
		(layer "In11.Cu")
		(net "SMB_HOST_3V3AUX_SCL")
	)
	(segment
		(start 238.8997 -131.4196)
		(end 238.814356 -131.504944)
		(width 0.127)
		(layer "In11.Cu")
		(net "SMB_HOST_3V3AUX_SCL")
	)
	(segment
		(start 224.503234 -118.016528)
		(end 215.730328 -118.016528)
		(width 0.127)
		(layer "In11.Cu")
		(net "SMB_HOST_3V3AUX_SCL")
	)
	(segment
		(start 221.55658 -85.402928)
		(end 226.93376 -85.402928)
		(width 0.127)
		(layer "In11.Cu")
		(net "SMB_HOST_3V3AUX_SCL")
	)
	(segment
		(start 206.55534 -95.070168)
		(end 206.55534 -94.310708)
		(width 0.127)
		(layer "In11.Cu")
		(net "SMB_HOST_3V3AUX_SCL")
	)
	(segment
		(start 238.814356 -131.504944)
		(end 230.951786 -131.504944)
		(width 0.127)
		(layer "In11.Cu")
		(net "SMB_HOST_3V3AUX_SCL")
	)
	(segment
		(start 207.4418 -93.424248)
		(end 212.860128 -93.424248)
		(width 0.127)
		(layer "In11.Cu")
		(net "SMB_HOST_3V3AUX_SCL")
	)
	(segment
		(start 128.001522 -131.018026)
		(end 127.451866 -131.567682)
		(width 0.12954)
		(layer "F.Cu")
		(net "SMB_FRU_3V3AUX_SDA_R")
	)
	(segment
		(start 126.726442 -131.567682)
		(end 125.840236 -131.567682)
		(width 0.12954)
		(layer "F.Cu")
		(net "SMB_FRU_3V3AUX_SDA_R")
	)
	(segment
		(start 125.840236 -131.567682)
		(end 125.711458 -131.69646)
		(width 0.12954)
		(layer "F.Cu")
		(net "SMB_FRU_3V3AUX_SDA_R")
	)
	(segment
		(start 125.711458 -131.69646)
		(end 123.708668 -131.69646)
		(width 0.12954)
		(layer "F.Cu")
		(net "SMB_FRU_3V3AUX_SDA_R")
	)
	(segment
		(start 127.451866 -131.567682)
		(end 126.726442 -131.567682)
		(width 0.12954)
		(layer "F.Cu")
		(net "SMB_FRU_3V3AUX_SDA_R")
	)
	(via
		(at 126.726442 -131.567682)
		(size 0.762)
		(drill 0.381)
		(layers "F.Cu" "B.Cu")
		(net "SMB_FRU_3V3AUX_SDA_R")
	)
	(segment
		(start 127.689102 -132.346446)
		(end 126.185676 -132.346446)
		(width 0.12954)
		(layer "F.Cu")
		(net "SMB_FRU_3V3AUX_SCL_R")
	)
	(segment
		(start 125.4633 -133.068822)
		(end 124.740924 -132.346446)
		(width 0.12954)
		(layer "F.Cu")
		(net "SMB_FRU_3V3AUX_SCL_R")
	)
	(segment
		(start 124.740924 -132.346446)
		(end 123.708668 -132.346446)
		(width 0.12954)
		(layer "F.Cu")
		(net "SMB_FRU_3V3AUX_SCL_R")
	)
	(segment
		(start 126.185676 -132.346446)
		(end 125.4633 -133.068822)
		(width 0.12954)
		(layer "F.Cu")
		(net "SMB_FRU_3V3AUX_SCL_R")
	)
	(segment
		(start 128.001522 -132.034026)
		(end 127.689102 -132.346446)
		(width 0.12954)
		(layer "F.Cu")
		(net "SMB_FRU_3V3AUX_SCL_R")
	)
	(via
		(at 125.4633 -133.068822)
		(size 0.762)
		(drill 0.381)
		(layers "F.Cu" "B.Cu")
		(net "SMB_FRU_3V3AUX_SCL_R")
	)
	(segment
		(start 158.057088 -13.600176)
		(end 158.057088 -14.719554)
		(width 0.12954)
		(layer "F.Cu")
		(net "SMB_FAN_3V3AUX_SDA")
	)
	(segment
		(start 158.057088 -14.719554)
		(end 158.056834 -14.719808)
		(width 0.12954)
		(layer "F.Cu")
		(net "SMB_FAN_3V3AUX_SDA")
	)
	(via
		(at 158.71444 -14.404848)
		(size 0.6604)
		(drill 0.3302)
		(layers "F.Cu" "B.Cu")
		(net "SMB_FAN_3V3AUX_SDA")
	)
	(via
		(at 158.056834 -14.719808)
		(size 0.508)
		(drill 0.254)
		(layers "F.Cu" "B.Cu")
		(net "SMB_FAN_3V3AUX_SDA")
	)
	(segment
		(start 158.056834 -14.719808)
		(end 158.056834 -15.196312)
		(width 0.12954)
		(layer "B.Cu")
		(net "SMB_FAN_3V3AUX_SDA")
	)
	(segment
		(start 158.71444 -14.404848)
		(end 158.71444 -14.249908)
		(width 0.12954)
		(layer "B.Cu")
		(net "SMB_FAN_3V3AUX_SDA")
	)
	(segment
		(start 158.42361 -15.563088)
		(end 158.71444 -15.272258)
		(width 0.12954)
		(layer "B.Cu")
		(net "SMB_FAN_3V3AUX_SDA")
	)
	(segment
		(start 158.71444 -15.272258)
		(end 158.71444 -14.404848)
		(width 0.12954)
		(layer "B.Cu")
		(net "SMB_FAN_3V3AUX_SDA")
	)
	(segment
		(start 157.30347 -11.650218)
		(end 157.24886 -11.650218)
		(width 0.12954)
		(layer "B.Cu")
		(net "SMB_FAN_3V3AUX_SDA")
	)
	(segment
		(start 158.71444 -14.249908)
		(end 158.05658 -13.592048)
		(width 0.12954)
		(layer "B.Cu")
		(net "SMB_FAN_3V3AUX_SDA")
	)
	(segment
		(start 158.056834 -15.196312)
		(end 158.42361 -15.563088)
		(width 0.12954)
		(layer "B.Cu")
		(net "SMB_FAN_3V3AUX_SDA")
	)
	(segment
		(start 158.05658 -12.403328)
		(end 157.30347 -11.650218)
		(width 0.12954)
		(layer "B.Cu")
		(net "SMB_FAN_3V3AUX_SDA")
	)
	(segment
		(start 158.05658 -13.592048)
		(end 158.05658 -12.403328)
		(width 0.12954)
		(layer "B.Cu")
		(net "SMB_FAN_3V3AUX_SDA")
	)
	(segment
		(start 158.657036 -13.600176)
		(end 158.657036 -12.495276)
		(width 0.12954)
		(layer "F.Cu")
		(net "SMB_FAN_3V3AUX_SCL")
	)
	(segment
		(start 158.657036 -12.495276)
		(end 158.656782 -12.495022)
		(width 0.12954)
		(layer "F.Cu")
		(net "SMB_FAN_3V3AUX_SCL")
	)
	(via
		(at 158.656782 -12.495022)
		(size 0.508)
		(drill 0.254)
		(layers "F.Cu" "B.Cu")
		(net "SMB_FAN_3V3AUX_SCL")
	)
	(via
		(at 159.12846 -13.099288)
		(size 0.6604)
		(drill 0.3302)
		(layers "F.Cu" "B.Cu")
		(net "SMB_FAN_3V3AUX_SCL")
	)
	(segment
		(start 159.12846 -13.099288)
		(end 159.261048 -13.099288)
		(width 0.12954)
		(layer "B.Cu")
		(net "SMB_FAN_3V3AUX_SCL")
	)
	(segment
		(start 158.656782 -12.495022)
		(end 159.12846 -12.9667)
		(width 0.12954)
		(layer "B.Cu")
		(net "SMB_FAN_3V3AUX_SCL")
	)
	(segment
		(start 160.28924 -13.174218)
		(end 160.28924 -13.594842)
		(width 0.12954)
		(layer "B.Cu")
		(net "SMB_FAN_3V3AUX_SCL")
	)
	(segment
		(start 160.30702 -13.612622)
		(end 160.30702 -14.14526)
		(width 0.12954)
		(layer "B.Cu")
		(net "SMB_FAN_3V3AUX_SCL")
	)
	(segment
		(start 160.28924 -13.594842)
		(end 160.30702 -13.612622)
		(width 0.12954)
		(layer "B.Cu")
		(net "SMB_FAN_3V3AUX_SCL")
	)
	(segment
		(start 159.261048 -13.099288)
		(end 160.30702 -14.14526)
		(width 0.12954)
		(layer "B.Cu")
		(net "SMB_FAN_3V3AUX_SCL")
	)
	(segment
		(start 160.30702 -14.14526)
		(end 160.30702 -14.149578)
		(width 0.12954)
		(layer "B.Cu")
		(net "SMB_FAN_3V3AUX_SCL")
	)
	(segment
		(start 159.12846 -12.9667)
		(end 159.12846 -13.099288)
		(width 0.12954)
		(layer "B.Cu")
		(net "SMB_FAN_3V3AUX_SCL")
	)
	(segment
		(start 105.70337 -361.334812)
		(end 105.70337 -361.0483)
		(width 0.12954)
		(layer "F.Cu")
		(net "SMB_DIO_PVCCIN_CPU1")
	)
	(segment
		(start 104.701594 -363.169454)
		(end 105.079038 -362.79201)
		(width 0.12954)
		(layer "F.Cu")
		(net "SMB_DIO_PVCCIN_CPU1")
	)
	(segment
		(start 105.087166 -361.951016)
		(end 105.70337 -361.334812)
		(width 0.12954)
		(layer "F.Cu")
		(net "SMB_DIO_PVCCIN_CPU1")
	)
	(segment
		(start 105.087166 -362.783882)
		(end 105.087166 -361.951016)
		(width 0.12954)
		(layer "F.Cu")
		(net "SMB_DIO_PVCCIN_CPU1")
	)
	(segment
		(start 105.079038 -362.79201)
		(end 105.087166 -362.783882)
		(width 0.12954)
		(layer "F.Cu")
		(net "SMB_DIO_PVCCIN_CPU1")
	)
	(segment
		(start 104.410002 -363.169454)
		(end 104.701594 -363.169454)
		(width 0.12954)
		(layer "F.Cu")
		(net "SMB_DIO_PVCCIN_CPU1")
	)
	(segment
		(start 103.706422 -363.873034)
		(end 104.410002 -363.169454)
		(width 0.12954)
		(layer "F.Cu")
		(net "SMB_DIO_PVCCIN_CPU1")
	)
	(via
		(at 105.079038 -362.79201)
		(size 0.762)
		(drill 0.381)
		(layers "F.Cu" "B.Cu")
		(net "SMB_DIO_PVCCIN_CPU1")
	)
	(segment
		(start 353.10318 -361.681268)
		(end 353.10318 -362.162598)
		(width 0.12954)
		(layer "F.Cu")
		(net "SMB_DIO_PVCCIN_CPU0")
	)
	(segment
		(start 353.10318 -361.681268)
		(end 353.10318 -361.295188)
		(width 0.12954)
		(layer "F.Cu")
		(net "SMB_DIO_PVCCIN_CPU0")
	)
	(segment
		(start 353.10318 -362.162598)
		(end 351.97288 -363.292898)
		(width 0.12954)
		(layer "F.Cu")
		(net "SMB_DIO_PVCCIN_CPU0")
	)
	(segment
		(start 353.350068 -361.0483)
		(end 353.643184 -361.0483)
		(width 0.12954)
		(layer "F.Cu")
		(net "SMB_DIO_PVCCIN_CPU0")
	)
	(segment
		(start 353.10318 -361.295188)
		(end 353.350068 -361.0483)
		(width 0.12954)
		(layer "F.Cu")
		(net "SMB_DIO_PVCCIN_CPU0")
	)
	(via
		(at 353.10318 -361.681268)
		(size 0.508)
		(drill 0.254)
		(layers "F.Cu" "B.Cu")
		(net "SMB_DIO_PVCCIN_CPU0")
	)
	(segment
		(start 33.461198 -125.51156)
		(end 33.461198 -126.05893)
		(width 0.12954)
		(layer "F.Cu")
		(net "SMB_DIO_PVCCINFAON_CPU1")
	)
	(segment
		(start 33.346898 -125.39726)
		(end 33.461198 -125.51156)
		(width 0.12954)
		(layer "F.Cu")
		(net "SMB_DIO_PVCCINFAON_CPU1")
	)
	(segment
		(start 33.021524 -125.39726)
		(end 33.346898 -125.39726)
		(width 0.12954)
		(layer "F.Cu")
		(net "SMB_DIO_PVCCINFAON_CPU1")
	)
	(segment
		(start 33.461198 -126.05893)
		(end 33.461198 -127.233426)
		(width 0.12954)
		(layer "F.Cu")
		(net "SMB_DIO_PVCCINFAON_CPU1")
	)
	(via
		(at 33.461198 -126.05893)
		(size 0.508)
		(drill 0.254)
		(layers "F.Cu" "B.Cu")
		(net "SMB_DIO_PVCCINFAON_CPU1")
	)
	(segment
		(start 428.347124 -131.204208)
		(end 428.347124 -132.091684)
		(width 0.12954)
		(layer "F.Cu")
		(net "SMB_DIO_PVCCINFAON_CPU0")
	)
	(segment
		(start 427.105064 -133.333744)
		(end 427.105064 -134.014464)
		(width 0.12954)
		(layer "F.Cu")
		(net "SMB_DIO_PVCCINFAON_CPU0")
	)
	(segment
		(start 429.513746 -130.329178)
		(end 429.222154 -130.329178)
		(width 0.12954)
		(layer "F.Cu")
		(net "SMB_DIO_PVCCINFAON_CPU0")
	)
	(segment
		(start 428.347124 -132.091684)
		(end 427.105064 -133.333744)
		(width 0.12954)
		(layer "F.Cu")
		(net "SMB_DIO_PVCCINFAON_CPU0")
	)
	(segment
		(start 430.200054 -130.329178)
		(end 429.513746 -130.329178)
		(width 0.12954)
		(layer "F.Cu")
		(net "SMB_DIO_PVCCINFAON_CPU0")
	)
	(segment
		(start 429.222154 -130.329178)
		(end 428.347124 -131.204208)
		(width 0.12954)
		(layer "F.Cu")
		(net "SMB_DIO_PVCCINFAON_CPU0")
	)
	(via
		(at 429.513746 -130.329178)
		(size 0.508)
		(drill 0.254)
		(layers "F.Cu" "B.Cu")
		(net "SMB_DIO_PVCCINFAON_CPU0")
	)
	(segment
		(start 26.262838 -167.22725)
		(end 26.262838 -169.487088)
		(width 0.12954)
		(layer "F.Cu")
		(net "SMB_DIO_PVCCD_HV_CPU1")
	)
	(via
		(at 26.262838 -169.487088)
		(size 0.508)
		(drill 0.254)
		(layers "F.Cu" "B.Cu")
		(net "SMB_DIO_PVCCD_HV_CPU1")
	)
	(segment
		(start 26.262838 -169.487088)
		(end 26.262838 -170.044872)
		(width 0.12954)
		(layer "B.Cu")
		(net "SMB_DIO_PVCCD_HV_CPU1")
	)
	(segment
		(start 24.125936 -172.181774)
		(end 23.389082 -172.181774)
		(width 0.12954)
		(layer "B.Cu")
		(net "SMB_DIO_PVCCD_HV_CPU1")
	)
	(segment
		(start 26.262838 -170.044872)
		(end 24.125936 -172.181774)
		(width 0.12954)
		(layer "B.Cu")
		(net "SMB_DIO_PVCCD_HV_CPU1")
	)
	(segment
		(start 433.901088 -119.763286)
		(end 433.901088 -120.588532)
		(width 0.12954)
		(layer "F.Cu")
		(net "SMB_DIO_PVCCD_HV_CPU0")
	)
	(segment
		(start 434.080158 -118.968266)
		(end 434.080158 -119.584216)
		(width 0.12954)
		(layer "F.Cu")
		(net "SMB_DIO_PVCCD_HV_CPU0")
	)
	(segment
		(start 434.080158 -119.584216)
		(end 433.901088 -119.763286)
		(width 0.12954)
		(layer "F.Cu")
		(net "SMB_DIO_PVCCD_HV_CPU0")
	)
	(via
		(at 434.080158 -119.584216)
		(size 0.508)
		(drill 0.254)
		(layers "F.Cu" "B.Cu")
		(net "SMB_DIO_PVCCD_HV_CPU0")
	)
	(segment
		(start 118.328694 -273.452844)
		(end 118.328948 -273.453098)
		(width 0.12954)
		(layer "F.Cu")
		(net "SMB_S3M_CPU1_PIROM_3V3AUX_SDA_1")
	)
	(segment
		(start 118.328694 -272.917158)
		(end 118.328694 -273.452844)
		(width 0.12954)
		(layer "F.Cu")
		(net "SMB_S3M_CPU1_PIROM_3V3AUX_SDA_1")
	)
	(via
		(at 118.328948 -273.453098)
		(size 0.4572)
		(drill 0.2032)
		(layers "F.Cu" "B.Cu")
		(net "SMB_S3M_CPU1_PIROM_3V3AUX_SDA_1")
	)
	(via
		(at 175.83912 -330.843128)
		(size 0.508)
		(drill 0.254)
		(layers "F.Cu" "B.Cu")
		(net "SMB_S3M_CPU1_PIROM_3V3AUX_SDA_1")
	)
	(segment
		(start 178.231546 -330.508864)
		(end 178.21783 -330.495148)
		(width 0.12954)
		(layer "B.Cu")
		(net "SMB_S3M_CPU1_PIROM_3V3AUX_SDA_1")
	)
	(segment
		(start 178.21783 -331.638148)
		(end 178.21783 -330.706222)
		(width 0.12954)
		(layer "B.Cu")
		(net "SMB_S3M_CPU1_PIROM_3V3AUX_SDA_1")
	)
	(segment
		(start 178.09083 -331.765148)
		(end 178.21783 -331.638148)
		(width 0.12954)
		(layer "B.Cu")
		(net "SMB_S3M_CPU1_PIROM_3V3AUX_SDA_1")
	)
	(segment
		(start 178.231546 -330.692506)
		(end 178.231546 -330.508864)
		(width 0.12954)
		(layer "B.Cu")
		(net "SMB_S3M_CPU1_PIROM_3V3AUX_SDA_1")
	)
	(segment
		(start 178.21783 -330.706222)
		(end 178.231546 -330.692506)
		(width 0.12954)
		(layer "B.Cu")
		(net "SMB_S3M_CPU1_PIROM_3V3AUX_SDA_1")
	)
	(segment
		(start 176.76114 -331.765148)
		(end 178.09083 -331.765148)
		(width 0.12954)
		(layer "B.Cu")
		(net "SMB_S3M_CPU1_PIROM_3V3AUX_SDA_1")
	)
	(segment
		(start 175.83912 -330.843128)
		(end 176.76114 -331.765148)
		(width 0.12954)
		(layer "B.Cu")
		(net "SMB_S3M_CPU1_PIROM_3V3AUX_SDA_1")
	)
	(segment
		(start 122.337068 -282.82138)
		(end 122.322844 -282.812998)
		(width 0.0889)
		(layer "In6.Cu")
		(net "SMB_S3M_CPU1_PIROM_3V3AUX_SDA_1")
	)
	(segment
		(start 132.660898 -284.440884)
		(end 132.660644 -284.44063)
		(width 0.0889)
		(layer "In6.Cu")
		(net "SMB_S3M_CPU1_PIROM_3V3AUX_SDA_1")
	)
	(segment
		(start 150.721314 -303.29251)
		(end 140.435076 -293.006272)
		(width 0.127)
		(layer "In6.Cu")
		(net "SMB_S3M_CPU1_PIROM_3V3AUX_SDA_1")
	)
	(segment
		(start 162.841178 -322.92925)
		(end 162.329876 -322.417948)
		(width 0.127)
		(layer "In6.Cu")
		(net "SMB_S3M_CPU1_PIROM_3V3AUX_SDA_1")
	)
	(segment
		(start 120.443498 -275.487892)
		(end 120.443244 -275.487638)
		(width 0.0889)
		(layer "In6.Cu")
		(net "SMB_S3M_CPU1_PIROM_3V3AUX_SDA_1")
	)
	(segment
		(start 121.85777 -278.746204)
		(end 121.852944 -278.74341)
		(width 0.0889)
		(layer "In6.Cu")
		(net "SMB_S3M_CPU1_PIROM_3V3AUX_SDA_1")
	)
	(segment
		(start 121.618248 -278.35098)
		(end 121.618248 -278.336502)
		(width 0.0889)
		(layer "In6.Cu")
		(net "SMB_S3M_CPU1_PIROM_3V3AUX_SDA_1")
	)
	(segment
		(start 119.738648 -275.080984)
		(end 119.738648 -275.08073)
		(width 0.0889)
		(layer "In6.Cu")
		(net "SMB_S3M_CPU1_PIROM_3V3AUX_SDA_1")
	)
	(segment
		(start 129.841244 -284.44063)
		(end 129.827782 -284.432756)
		(width 0.0889)
		(layer "In6.Cu")
		(net "SMB_S3M_CPU1_PIROM_3V3AUX_SDA_1")
	)
	(segment
		(start 127.021844 -284.44063)
		(end 127.008382 -284.432756)
		(width 0.0889)
		(layer "In6.Cu")
		(net "SMB_S3M_CPU1_PIROM_3V3AUX_SDA_1")
	)
	(segment
		(start 123.262898 -284.44063)
		(end 123.262644 -284.44063)
		(width 0.0889)
		(layer "In6.Cu")
		(net "SMB_S3M_CPU1_PIROM_3V3AUX_SDA_1")
	)
	(segment
		(start 174.073058 -330.166726)
		(end 174.073058 -326.222614)
		(width 0.127)
		(layer "In6.Cu")
		(net "SMB_S3M_CPU1_PIROM_3V3AUX_SDA_1")
	)
	(segment
		(start 133.600698 -285.254446)
		(end 133.600444 -285.254446)
		(width 0.0889)
		(layer "In6.Cu")
		(net "SMB_S3M_CPU1_PIROM_3V3AUX_SDA_1")
	)
	(segment
		(start 175.83912 -330.843128)
		(end 174.74946 -330.843128)
		(width 0.127)
		(layer "In6.Cu")
		(net "SMB_S3M_CPU1_PIROM_3V3AUX_SDA_1")
	)
	(segment
		(start 120.443244 -275.487638)
		(end 120.429782 -275.495512)
		(width 0.0889)
		(layer "In6.Cu")
		(net "SMB_S3M_CPU1_PIROM_3V3AUX_SDA_1")
	)
	(segment
		(start 167.479218 -323.349874)
		(end 167.058594 -322.92925)
		(width 0.127)
		(layer "In6.Cu")
		(net "SMB_S3M_CPU1_PIROM_3V3AUX_SDA_1")
	)
	(segment
		(start 124.202444 -284.44063)
		(end 124.188982 -284.432756)
		(width 0.0889)
		(layer "In6.Cu")
		(net "SMB_S3M_CPU1_PIROM_3V3AUX_SDA_1")
	)
	(segment
		(start 150.721314 -316.390782)
		(end 150.721314 -303.29251)
		(width 0.127)
		(layer "In6.Cu")
		(net "SMB_S3M_CPU1_PIROM_3V3AUX_SDA_1")
	)
	(segment
		(start 134.070344 -285.254446)
		(end 134.070598 -285.254446)
		(width 0.0889)
		(layer "In6.Cu")
		(net "SMB_S3M_CPU1_PIROM_3V3AUX_SDA_1")
	)
	(segment
		(start 123.732544 -284.44063)
		(end 123.732798 -284.44063)
		(width 0.0889)
		(layer "In6.Cu")
		(net "SMB_S3M_CPU1_PIROM_3V3AUX_SDA_1")
	)
	(segment
		(start 120.913144 -276.301708)
		(end 120.913144 -276.301454)
		(width 0.0889)
		(layer "In6.Cu")
		(net "SMB_S3M_CPU1_PIROM_3V3AUX_SDA_1")
	)
	(segment
		(start 127.961644 -284.44063)
		(end 127.948182 -284.432756)
		(width 0.0889)
		(layer "In6.Cu")
		(net "SMB_S3M_CPU1_PIROM_3V3AUX_SDA_1")
	)
	(segment
		(start 137.889996 -286.959802)
		(end 137.714228 -286.868616)
		(width 0.0889)
		(layer "In6.Cu")
		(net "SMB_S3M_CPU1_PIROM_3V3AUX_SDA_1")
	)
	(segment
		(start 122.558048 -281.59202)
		(end 122.558048 -281.582368)
		(width 0.0889)
		(layer "In6.Cu")
		(net "SMB_S3M_CPU1_PIROM_3V3AUX_SDA_1")
	)
	(segment
		(start 119.033544 -273.860006)
		(end 119.033798 -273.860006)
		(width 0.0889)
		(layer "In6.Cu")
		(net "SMB_S3M_CPU1_PIROM_3V3AUX_SDA_1")
	)
	(segment
		(start 122.79757 -283.629608)
		(end 122.792744 -283.626814)
		(width 0.0889)
		(layer "In6.Cu")
		(net "SMB_S3M_CPU1_PIROM_3V3AUX_SDA_1")
	)
	(segment
		(start 136.02462 -285.297626)
		(end 135.940546 -285.248858)
		(width 0.0889)
		(layer "In6.Cu")
		(net "SMB_S3M_CPU1_PIROM_3V3AUX_SDA_1")
	)
	(segment
		(start 162.329876 -322.417948)
		(end 156.74848 -322.417948)
		(width 0.127)
		(layer "In6.Cu")
		(net "SMB_S3M_CPU1_PIROM_3V3AUX_SDA_1")
	)
	(segment
		(start 132.895848 -284.85719)
		(end 132.895848 -284.847538)
		(width 0.0889)
		(layer "In6.Cu")
		(net "SMB_S3M_CPU1_PIROM_3V3AUX_SDA_1")
	)
	(segment
		(start 173.303438 -325.452994)
		(end 172.555916 -325.452994)
		(width 0.127)
		(layer "In6.Cu")
		(net "SMB_S3M_CPU1_PIROM_3V3AUX_SDA_1")
	)
	(segment
		(start 119.514112 -274.680172)
		(end 119.498618 -274.671028)
		(width 0.0889)
		(layer "In6.Cu")
		(net "SMB_S3M_CPU1_PIROM_3V3AUX_SDA_1")
	)
	(segment
		(start 122.558048 -279.973786)
		(end 122.558048 -279.964134)
		(width 0.0889)
		(layer "In6.Cu")
		(net "SMB_S3M_CPU1_PIROM_3V3AUX_SDA_1")
	)
	(segment
		(start 174.073058 -326.222614)
		(end 173.303438 -325.452994)
		(width 0.127)
		(layer "In6.Cu")
		(net "SMB_S3M_CPU1_PIROM_3V3AUX_SDA_1")
	)
	(segment
		(start 122.558048 -283.229558)
		(end 122.558048 -283.219906)
		(width 0.0889)
		(layer "In6.Cu")
		(net "SMB_S3M_CPU1_PIROM_3V3AUX_SDA_1")
	)
	(segment
		(start 125.142498 -284.44063)
		(end 125.132846 -284.435042)
		(width 0.0889)
		(layer "In6.Cu")
		(net "SMB_S3M_CPU1_PIROM_3V3AUX_SDA_1")
	)
	(segment
		(start 122.318018 -282.001722)
		(end 122.333512 -281.992578)
		(width 0.0889)
		(layer "In6.Cu")
		(net "SMB_S3M_CPU1_PIROM_3V3AUX_SDA_1")
	)
	(segment
		(start 136.668764 -286.559752)
		(end 136.667748 -286.45485)
		(width 0.0889)
		(layer "In6.Cu")
		(net "SMB_S3M_CPU1_PIROM_3V3AUX_SDA_1")
	)
	(segment
		(start 139.671552 -286.990282)
		(end 138.542014 -286.990282)
		(width 0.127)
		(layer "In6.Cu")
		(net "SMB_S3M_CPU1_PIROM_3V3AUX_SDA_1")
	)
	(segment
		(start 131.720844 -284.44063)
		(end 131.707382 -284.432756)
		(width 0.0889)
		(layer "In6.Cu")
		(net "SMB_S3M_CPU1_PIROM_3V3AUX_SDA_1")
	)
	(segment
		(start 174.74946 -330.843128)
		(end 174.073058 -330.166726)
		(width 0.127)
		(layer "In6.Cu")
		(net "SMB_S3M_CPU1_PIROM_3V3AUX_SDA_1")
	)
	(segment
		(start 128.901444 -284.44063)
		(end 128.887982 -284.432756)
		(width 0.0889)
		(layer "In6.Cu")
		(net "SMB_S3M_CPU1_PIROM_3V3AUX_SDA_1")
	)
	(segment
		(start 140.435076 -293.006272)
		(end 140.435076 -287.753806)
		(width 0.127)
		(layer "In6.Cu")
		(net "SMB_S3M_CPU1_PIROM_3V3AUX_SDA_1")
	)
	(segment
		(start 120.44426 -275.487638)
		(end 120.443498 -275.487892)
		(width 0.0889)
		(layer "In6.Cu")
		(net "SMB_S3M_CPU1_PIROM_3V3AUX_SDA_1")
	)
	(segment
		(start 140.435076 -287.753806)
		(end 139.671552 -286.990282)
		(width 0.127)
		(layer "In6.Cu")
		(net "SMB_S3M_CPU1_PIROM_3V3AUX_SDA_1")
	)
	(segment
		(start 119.03837 -273.8628)
		(end 119.033544 -273.860006)
		(width 0.0889)
		(layer "In6.Cu")
		(net "SMB_S3M_CPU1_PIROM_3V3AUX_SDA_1")
	)
	(segment
		(start 130.781044 -284.44063)
		(end 130.767582 -284.432756)
		(width 0.0889)
		(layer "In6.Cu")
		(net "SMB_S3M_CPU1_PIROM_3V3AUX_SDA_1")
	)
	(segment
		(start 121.393712 -277.935944)
		(end 121.383044 -277.929594)
		(width 0.0889)
		(layer "In6.Cu")
		(net "SMB_S3M_CPU1_PIROM_3V3AUX_SDA_1")
	)
	(segment
		(start 172.555916 -325.452994)
		(end 167.479218 -323.349874)
		(width 0.127)
		(layer "In6.Cu")
		(net "SMB_S3M_CPU1_PIROM_3V3AUX_SDA_1")
	)
	(segment
		(start 136.979406 -286.950912)
		(end 136.915652 -286.91713)
		(width 0.0889)
		(layer "In6.Cu")
		(net "SMB_S3M_CPU1_PIROM_3V3AUX_SDA_1")
	)
	(segment
		(start 134.540244 -285.254446)
		(end 134.526782 -285.26232)
		(width 0.0889)
		(layer "In6.Cu")
		(net "SMB_S3M_CPU1_PIROM_3V3AUX_SDA_1")
	)
	(segment
		(start 167.058594 -322.92925)
		(end 162.841178 -322.92925)
		(width 0.127)
		(layer "In6.Cu")
		(net "SMB_S3M_CPU1_PIROM_3V3AUX_SDA_1")
	)
	(segment
		(start 126.082044 -284.44063)
		(end 126.072392 -284.435042)
		(width 0.0889)
		(layer "In6.Cu")
		(net "SMB_S3M_CPU1_PIROM_3V3AUX_SDA_1")
	)
	(segment
		(start 156.74848 -322.417948)
		(end 150.721314 -316.390782)
		(width 0.127)
		(layer "In6.Cu")
		(net "SMB_S3M_CPU1_PIROM_3V3AUX_SDA_1")
	)
	(segment
		(start 123.262644 -284.44063)
		(end 123.257818 -284.437836)
		(width 0.0889)
		(layer "In6.Cu")
		(net "SMB_S3M_CPU1_PIROM_3V3AUX_SDA_1")
	)
	(segment
		(start 121.148094 -277.535894)
		(end 121.148094 -277.522432)
		(width 0.0889)
		(layer "In6.Cu")
		(net "SMB_S3M_CPU1_PIROM_3V3AUX_SDA_1")
	)
	(segment
		(start 120.91797 -277.118318)
		(end 120.913144 -277.115524)
		(width 0.0889)
		(layer "In6.Cu")
		(net "SMB_S3M_CPU1_PIROM_3V3AUX_SDA_1")
	)
	(segment
		(start 136.43356 -286.094424)
		(end 136.380474 -286.063944)
		(width 0.0889)
		(layer "In6.Cu")
		(net "SMB_S3M_CPU1_PIROM_3V3AUX_SDA_1")
	)
	(segment
		(start 122.333512 -279.563576)
		(end 122.318018 -279.554432)
		(width 0.0889)
		(layer "In6.Cu")
		(net "SMB_S3M_CPU1_PIROM_3V3AUX_SDA_1")
	)
	(segment
		(start 132.660644 -284.44063)
		(end 132.647182 -284.432756)
		(width 0.0889)
		(layer "In6.Cu")
		(net "SMB_S3M_CPU1_PIROM_3V3AUX_SDA_1")
	)
	(segment
		(start 122.792744 -281.185112)
		(end 122.79757 -281.182318)
		(width 0.0889)
		(layer "In6.Cu")
		(net "SMB_S3M_CPU1_PIROM_3V3AUX_SDA_1")
	)
	(segment
		(start 119.033798 -273.860006)
		(end 118.328948 -273.453098)
		(width 0.0889)
		(layer "In6.Cu")
		(net "SMB_S3M_CPU1_PIROM_3V3AUX_SDA_1")
	)
	(segment
		(start 138.542014 -286.990282)
		(end 138.064748 -286.990282)
		(width 0.0889)
		(layer "In6.Cu")
		(net "SMB_S3M_CPU1_PIROM_3V3AUX_SDA_1")
	)
	(arc
		(start 121.383044 -277.929594)
		(mid 121.214321 -277.763328)
		(end 121.148094 -277.535894)
		(width 0.0889)
		(layer "In6.Cu")
		(net "SMB_S3M_CPU1_PIROM_3V3AUX_SDA_1")
	)
	(arc
		(start 132.647182 -284.432756)
		(mid 132.417929 -284.377512)
		(end 132.190744 -284.44063)
		(width 0.0889)
		(layer "In6.Cu")
		(net "SMB_S3M_CPU1_PIROM_3V3AUX_SDA_1")
	)
	(arc
		(start 136.915652 -286.91713)
		(mid 136.74892 -286.768334)
		(end 136.668764 -286.559752)
		(width 0.0889)
		(layer "In6.Cu")
		(net "SMB_S3M_CPU1_PIROM_3V3AUX_SDA_1")
	)
	(arc
		(start 119.268494 -274.266914)
		(mid 119.206931 -274.034391)
		(end 119.03837 -273.8628)
		(width 0.0889)
		(layer "In6.Cu")
		(net "SMB_S3M_CPU1_PIROM_3V3AUX_SDA_1")
	)
	(arc
		(start 120.913144 -275.487638)
		(mid 120.678702 -275.42483)
		(end 120.44426 -275.487638)
		(width 0.0889)
		(layer "In6.Cu")
		(net "SMB_S3M_CPU1_PIROM_3V3AUX_SDA_1")
	)
	(arc
		(start 135.010144 -285.254446)
		(mid 134.775194 -285.191486)
		(end 134.540244 -285.254446)
		(width 0.0889)
		(layer "In6.Cu")
		(net "SMB_S3M_CPU1_PIROM_3V3AUX_SDA_1")
	)
	(arc
		(start 130.767582 -284.432756)
		(mid 130.538329 -284.377512)
		(end 130.311144 -284.44063)
		(width 0.0889)
		(layer "In6.Cu")
		(net "SMB_S3M_CPU1_PIROM_3V3AUX_SDA_1")
	)
	(arc
		(start 120.429782 -275.495512)
		(mid 120.200529 -275.550756)
		(end 119.973344 -275.487638)
		(width 0.0889)
		(layer "In6.Cu")
		(net "SMB_S3M_CPU1_PIROM_3V3AUX_SDA_1")
	)
	(arc
		(start 133.600444 -285.254446)
		(mid 133.134761 -285.256852)
		(end 132.895848 -284.85719)
		(width 0.0889)
		(layer "In6.Cu")
		(net "SMB_S3M_CPU1_PIROM_3V3AUX_SDA_1")
	)
	(arc
		(start 125.612398 -284.44063)
		(mid 125.377448 -284.50359)
		(end 125.142498 -284.44063)
		(width 0.0889)
		(layer "In6.Cu")
		(net "SMB_S3M_CPU1_PIROM_3V3AUX_SDA_1")
	)
	(arc
		(start 119.498618 -274.671028)
		(mid 119.330062 -274.499434)
		(end 119.268494 -274.266914)
		(width 0.0889)
		(layer "In6.Cu")
		(net "SMB_S3M_CPU1_PIROM_3V3AUX_SDA_1")
	)
	(arc
		(start 119.973344 -275.487638)
		(mid 119.801531 -275.315745)
		(end 119.738648 -275.080984)
		(width 0.0889)
		(layer "In6.Cu")
		(net "SMB_S3M_CPU1_PIROM_3V3AUX_SDA_1")
	)
	(arc
		(start 121.618248 -278.336502)
		(mid 121.558293 -278.106892)
		(end 121.393712 -277.935944)
		(width 0.0889)
		(layer "In6.Cu")
		(net "SMB_S3M_CPU1_PIROM_3V3AUX_SDA_1")
	)
	(arc
		(start 127.008382 -284.432756)
		(mid 126.779129 -284.377512)
		(end 126.551944 -284.44063)
		(width 0.0889)
		(layer "In6.Cu")
		(net "SMB_S3M_CPU1_PIROM_3V3AUX_SDA_1")
	)
	(arc
		(start 124.672344 -284.44063)
		(mid 124.437394 -284.50359)
		(end 124.202444 -284.44063)
		(width 0.0889)
		(layer "In6.Cu")
		(net "SMB_S3M_CPU1_PIROM_3V3AUX_SDA_1")
	)
	(arc
		(start 135.480044 -285.254446)
		(mid 135.245094 -285.317406)
		(end 135.010144 -285.254446)
		(width 0.0889)
		(layer "In6.Cu")
		(net "SMB_S3M_CPU1_PIROM_3V3AUX_SDA_1")
	)
	(arc
		(start 126.551944 -284.44063)
		(mid 126.316994 -284.50359)
		(end 126.082044 -284.44063)
		(width 0.0889)
		(layer "In6.Cu")
		(net "SMB_S3M_CPU1_PIROM_3V3AUX_SDA_1")
	)
	(arc
		(start 130.311144 -284.44063)
		(mid 130.076194 -284.50359)
		(end 129.841244 -284.44063)
		(width 0.0889)
		(layer "In6.Cu")
		(net "SMB_S3M_CPU1_PIROM_3V3AUX_SDA_1")
	)
	(arc
		(start 123.257818 -284.437836)
		(mid 123.089262 -284.266242)
		(end 123.027694 -284.033722)
		(width 0.0889)
		(layer "In6.Cu")
		(net "SMB_S3M_CPU1_PIROM_3V3AUX_SDA_1")
	)
	(arc
		(start 135.940546 -285.248858)
		(mid 135.709561 -285.191375)
		(end 135.480044 -285.254446)
		(width 0.0889)
		(layer "In6.Cu")
		(net "SMB_S3M_CPU1_PIROM_3V3AUX_SDA_1")
	)
	(arc
		(start 122.79757 -281.182318)
		(mid 123.02768 -280.775352)
		(end 122.792744 -280.371042)
		(width 0.0889)
		(layer "In6.Cu")
		(net "SMB_S3M_CPU1_PIROM_3V3AUX_SDA_1")
	)
	(arc
		(start 129.827782 -284.432756)
		(mid 129.598529 -284.377512)
		(end 129.371344 -284.44063)
		(width 0.0889)
		(layer "In6.Cu")
		(net "SMB_S3M_CPU1_PIROM_3V3AUX_SDA_1")
	)
	(arc
		(start 134.070598 -285.254446)
		(mid 133.835648 -285.191486)
		(end 133.600698 -285.254446)
		(width 0.0889)
		(layer "In6.Cu")
		(net "SMB_S3M_CPU1_PIROM_3V3AUX_SDA_1")
	)
	(arc
		(start 137.714228 -286.868616)
		(mid 137.554137 -286.880233)
		(end 137.405364 -286.940498)
		(width 0.0889)
		(layer "In6.Cu")
		(net "SMB_S3M_CPU1_PIROM_3V3AUX_SDA_1")
	)
	(arc
		(start 120.913144 -276.301454)
		(mid 121.148189 -275.894546)
		(end 120.913144 -275.487638)
		(width 0.0889)
		(layer "In6.Cu")
		(net "SMB_S3M_CPU1_PIROM_3V3AUX_SDA_1")
	)
	(arc
		(start 136.380474 -286.063944)
		(mid 136.239653 -285.890913)
		(end 136.192768 -285.672784)
		(width 0.0889)
		(layer "In6.Cu")
		(net "SMB_S3M_CPU1_PIROM_3V3AUX_SDA_1")
	)
	(arc
		(start 119.738648 -275.08073)
		(mid 119.678693 -274.85112)
		(end 119.514112 -274.680172)
		(width 0.0889)
		(layer "In6.Cu")
		(net "SMB_S3M_CPU1_PIROM_3V3AUX_SDA_1")
	)
	(arc
		(start 122.558048 -279.964134)
		(mid 122.498093 -279.734524)
		(end 122.333512 -279.563576)
		(width 0.0889)
		(layer "In6.Cu")
		(net "SMB_S3M_CPU1_PIROM_3V3AUX_SDA_1")
	)
	(arc
		(start 122.792744 -280.371042)
		(mid 122.623294 -280.203196)
		(end 122.558048 -279.973786)
		(width 0.0889)
		(layer "In6.Cu")
		(net "SMB_S3M_CPU1_PIROM_3V3AUX_SDA_1")
	)
	(arc
		(start 122.322844 -282.812998)
		(mid 122.087715 -282.408689)
		(end 122.318018 -282.001722)
		(width 0.0889)
		(layer "In6.Cu")
		(net "SMB_S3M_CPU1_PIROM_3V3AUX_SDA_1")
	)
	(arc
		(start 132.895848 -284.847538)
		(mid 132.832888 -284.612715)
		(end 132.660898 -284.440884)
		(width 0.0889)
		(layer "In6.Cu")
		(net "SMB_S3M_CPU1_PIROM_3V3AUX_SDA_1")
	)
	(arc
		(start 131.707382 -284.432756)
		(mid 131.478129 -284.377512)
		(end 131.250944 -284.44063)
		(width 0.0889)
		(layer "In6.Cu")
		(net "SMB_S3M_CPU1_PIROM_3V3AUX_SDA_1")
	)
	(arc
		(start 134.526782 -285.26232)
		(mid 134.297529 -285.317564)
		(end 134.070344 -285.254446)
		(width 0.0889)
		(layer "In6.Cu")
		(net "SMB_S3M_CPU1_PIROM_3V3AUX_SDA_1")
	)
	(arc
		(start 123.027694 -284.033722)
		(mid 122.966131 -283.801199)
		(end 122.79757 -283.629608)
		(width 0.0889)
		(layer "In6.Cu")
		(net "SMB_S3M_CPU1_PIROM_3V3AUX_SDA_1")
	)
	(arc
		(start 125.132846 -284.435042)
		(mid 124.901861 -284.377559)
		(end 124.672344 -284.44063)
		(width 0.0889)
		(layer "In6.Cu")
		(net "SMB_S3M_CPU1_PIROM_3V3AUX_SDA_1")
	)
	(arc
		(start 122.558048 -281.582368)
		(mid 122.623291 -281.352956)
		(end 122.792744 -281.185112)
		(width 0.0889)
		(layer "In6.Cu")
		(net "SMB_S3M_CPU1_PIROM_3V3AUX_SDA_1")
	)
	(arc
		(start 127.491744 -284.44063)
		(mid 127.256794 -284.50359)
		(end 127.021844 -284.44063)
		(width 0.0889)
		(layer "In6.Cu")
		(net "SMB_S3M_CPU1_PIROM_3V3AUX_SDA_1")
	)
	(arc
		(start 122.087894 -279.150318)
		(mid 122.026331 -278.917795)
		(end 121.85777 -278.746204)
		(width 0.0889)
		(layer "In6.Cu")
		(net "SMB_S3M_CPU1_PIROM_3V3AUX_SDA_1")
	)
	(arc
		(start 120.913144 -277.115524)
		(mid 120.678353 -276.708616)
		(end 120.913144 -276.301708)
		(width 0.0889)
		(layer "In6.Cu")
		(net "SMB_S3M_CPU1_PIROM_3V3AUX_SDA_1")
	)
	(arc
		(start 122.318018 -279.554432)
		(mid 122.149462 -279.382838)
		(end 122.087894 -279.150318)
		(width 0.0889)
		(layer "In6.Cu")
		(net "SMB_S3M_CPU1_PIROM_3V3AUX_SDA_1")
	)
	(arc
		(start 121.852944 -278.74341)
		(mid 121.68464 -278.57767)
		(end 121.618248 -278.35098)
		(width 0.0889)
		(layer "In6.Cu")
		(net "SMB_S3M_CPU1_PIROM_3V3AUX_SDA_1")
	)
	(arc
		(start 138.064748 -286.990282)
		(mid 137.976048 -286.982628)
		(end 137.889996 -286.959802)
		(width 0.0889)
		(layer "In6.Cu")
		(net "SMB_S3M_CPU1_PIROM_3V3AUX_SDA_1")
	)
	(arc
		(start 127.948182 -284.432756)
		(mid 127.718929 -284.377512)
		(end 127.491744 -284.44063)
		(width 0.0889)
		(layer "In6.Cu")
		(net "SMB_S3M_CPU1_PIROM_3V3AUX_SDA_1")
	)
	(arc
		(start 126.072392 -284.435042)
		(mid 125.841661 -284.377681)
		(end 125.612398 -284.44063)
		(width 0.0889)
		(layer "In6.Cu")
		(net "SMB_S3M_CPU1_PIROM_3V3AUX_SDA_1")
	)
	(arc
		(start 129.371344 -284.44063)
		(mid 129.136394 -284.50359)
		(end 128.901444 -284.44063)
		(width 0.0889)
		(layer "In6.Cu")
		(net "SMB_S3M_CPU1_PIROM_3V3AUX_SDA_1")
	)
	(arc
		(start 122.792744 -283.626814)
		(mid 122.623294 -283.458968)
		(end 122.558048 -283.229558)
		(width 0.0889)
		(layer "In6.Cu")
		(net "SMB_S3M_CPU1_PIROM_3V3AUX_SDA_1")
	)
	(arc
		(start 136.192768 -285.672784)
		(mid 136.151101 -285.466204)
		(end 136.02462 -285.297626)
		(width 0.0889)
		(layer "In6.Cu")
		(net "SMB_S3M_CPU1_PIROM_3V3AUX_SDA_1")
	)
	(arc
		(start 128.431544 -284.44063)
		(mid 128.196594 -284.50359)
		(end 127.961644 -284.44063)
		(width 0.0889)
		(layer "In6.Cu")
		(net "SMB_S3M_CPU1_PIROM_3V3AUX_SDA_1")
	)
	(arc
		(start 122.333512 -281.992578)
		(mid 122.498054 -281.821608)
		(end 122.558048 -281.59202)
		(width 0.0889)
		(layer "In6.Cu")
		(net "SMB_S3M_CPU1_PIROM_3V3AUX_SDA_1")
	)
	(arc
		(start 124.188982 -284.432756)
		(mid 123.959729 -284.377512)
		(end 123.732544 -284.44063)
		(width 0.0889)
		(layer "In6.Cu")
		(net "SMB_S3M_CPU1_PIROM_3V3AUX_SDA_1")
	)
	(arc
		(start 136.667748 -286.45485)
		(mid 136.593954 -286.246486)
		(end 136.43356 -286.094424)
		(width 0.0889)
		(layer "In6.Cu")
		(net "SMB_S3M_CPU1_PIROM_3V3AUX_SDA_1")
	)
	(arc
		(start 137.405364 -286.940498)
		(mid 137.193748 -287.001939)
		(end 136.979406 -286.950912)
		(width 0.0889)
		(layer "In6.Cu")
		(net "SMB_S3M_CPU1_PIROM_3V3AUX_SDA_1")
	)
	(arc
		(start 132.190744 -284.44063)
		(mid 131.955794 -284.50359)
		(end 131.720844 -284.44063)
		(width 0.0889)
		(layer "In6.Cu")
		(net "SMB_S3M_CPU1_PIROM_3V3AUX_SDA_1")
	)
	(arc
		(start 123.732798 -284.44063)
		(mid 123.497848 -284.50359)
		(end 123.262898 -284.44063)
		(width 0.0889)
		(layer "In6.Cu")
		(net "SMB_S3M_CPU1_PIROM_3V3AUX_SDA_1")
	)
	(arc
		(start 131.250944 -284.44063)
		(mid 131.015994 -284.50359)
		(end 130.781044 -284.44063)
		(width 0.0889)
		(layer "In6.Cu")
		(net "SMB_S3M_CPU1_PIROM_3V3AUX_SDA_1")
	)
	(arc
		(start 121.148094 -277.522432)
		(mid 121.086531 -277.289909)
		(end 120.91797 -277.118318)
		(width 0.0889)
		(layer "In6.Cu")
		(net "SMB_S3M_CPU1_PIROM_3V3AUX_SDA_1")
	)
	(arc
		(start 122.558048 -283.219906)
		(mid 122.49911 -282.992054)
		(end 122.337068 -282.82138)
		(width 0.0889)
		(layer "In6.Cu")
		(net "SMB_S3M_CPU1_PIROM_3V3AUX_SDA_1")
	)
	(arc
		(start 128.887982 -284.432756)
		(mid 128.658729 -284.377512)
		(end 128.431544 -284.44063)
		(width 0.0889)
		(layer "In6.Cu")
		(net "SMB_S3M_CPU1_PIROM_3V3AUX_SDA_1")
	)
	(segment
		(start 120.678448 -272.103342)
		(end 120.678194 -272.639282)
		(width 0.12954)
		(layer "F.Cu")
		(net "SMB_S3M_CPU1_PIROM_3V3AUX_SCL_1")
	)
	(via
		(at 176.98974 -330.241148)
		(size 0.508)
		(drill 0.254)
		(layers "F.Cu" "B.Cu")
		(net "SMB_S3M_CPU1_PIROM_3V3AUX_SCL_1")
	)
	(via
		(at 120.678194 -272.639282)
		(size 0.4572)
		(drill 0.2032)
		(layers "F.Cu" "B.Cu")
		(net "SMB_S3M_CPU1_PIROM_3V3AUX_SCL_1")
	)
	(segment
		(start 178.21783 -329.479148)
		(end 177.75174 -329.479148)
		(width 0.12954)
		(layer "B.Cu")
		(net "SMB_S3M_CPU1_PIROM_3V3AUX_SCL_1")
	)
	(segment
		(start 177.75174 -329.479148)
		(end 176.98974 -330.241148)
		(width 0.12954)
		(layer "B.Cu")
		(net "SMB_S3M_CPU1_PIROM_3V3AUX_SCL_1")
	)
	(segment
		(start 162.59048 -321.884548)
		(end 156.980636 -321.884548)
		(width 0.127)
		(layer "In6.Cu")
		(net "SMB_S3M_CPU1_PIROM_3V3AUX_SCL_1")
	)
	(segment
		(start 178.457098 -325.84009)
		(end 177.585878 -324.96887)
		(width 0.127)
		(layer "In6.Cu")
		(net "SMB_S3M_CPU1_PIROM_3V3AUX_SCL_1")
	)
	(segment
		(start 123.267724 -279.56002)
		(end 123.258072 -279.554432)
		(width 0.0889)
		(layer "In6.Cu")
		(net "SMB_S3M_CPU1_PIROM_3V3AUX_SCL_1")
	)
	(segment
		(start 138.352784 -286.122618)
		(end 138.253978 -286.064706)
		(width 0.0889)
		(layer "In6.Cu")
		(net "SMB_S3M_CPU1_PIROM_3V3AUX_SCL_1")
	)
	(segment
		(start 124.437648 -281.601672)
		(end 124.437648 -281.59202)
		(width 0.0889)
		(layer "In6.Cu")
		(net "SMB_S3M_CPU1_PIROM_3V3AUX_SCL_1")
	)
	(segment
		(start 174.03318 -324.84949)
		(end 173.9138 -324.96887)
		(width 0.127)
		(layer "In6.Cu")
		(net "SMB_S3M_CPU1_PIROM_3V3AUX_SCL_1")
	)
	(segment
		(start 121.859802 -275.491702)
		(end 121.852944 -275.487638)
		(width 0.0889)
		(layer "In6.Cu")
		(net "SMB_S3M_CPU1_PIROM_3V3AUX_SCL_1")
	)
	(segment
		(start 120.678448 -273.46275)
		(end 120.678448 -273.453098)
		(width 0.0889)
		(layer "In6.Cu")
		(net "SMB_S3M_CPU1_PIROM_3V3AUX_SCL_1")
	)
	(segment
		(start 176.98974 -328.829416)
		(end 178.457098 -327.362058)
		(width 0.127)
		(layer "In6.Cu")
		(net "SMB_S3M_CPU1_PIROM_3V3AUX_SCL_1")
	)
	(segment
		(start 156.980636 -321.884548)
		(end 151.205438 -316.10935)
		(width 0.127)
		(layer "In6.Cu")
		(net "SMB_S3M_CPU1_PIROM_3V3AUX_SCL_1")
	)
	(segment
		(start 136.430766 -284.447234)
		(end 136.419844 -284.44063)
		(width 0.0889)
		(layer "In6.Cu")
		(net "SMB_S3M_CPU1_PIROM_3V3AUX_SCL_1")
	)
	(segment
		(start 133.130544 -283.627068)
		(end 133.130544 -283.626814)
		(width 0.0889)
		(layer "In6.Cu")
		(net "SMB_S3M_CPU1_PIROM_3V3AUX_SCL_1")
	)
	(segment
		(start 174.80788 -324.96887)
		(end 174.6885 -324.84949)
		(width 0.127)
		(layer "In6.Cu")
		(net "SMB_S3M_CPU1_PIROM_3V3AUX_SCL_1")
	)
	(segment
		(start 140.9192 -286.994854)
		(end 140.113004 -286.188658)
		(width 0.127)
		(layer "In6.Cu")
		(net "SMB_S3M_CPU1_PIROM_3V3AUX_SCL_1")
	)
	(segment
		(start 122.793252 -278.743918)
		(end 122.792744 -278.74341)
		(width 0.0889)
		(layer "In6.Cu")
		(net "SMB_S3M_CPU1_PIROM_3V3AUX_SCL_1")
	)
	(segment
		(start 177.585878 -324.96887)
		(end 176.11852 -324.96887)
		(width 0.127)
		(layer "In6.Cu")
		(net "SMB_S3M_CPU1_PIROM_3V3AUX_SCL_1")
	)
	(segment
		(start 175.99914 -324.50405)
		(end 175.87976 -324.38467)
		(width 0.127)
		(layer "In6.Cu")
		(net "SMB_S3M_CPU1_PIROM_3V3AUX_SCL_1")
	)
	(segment
		(start 151.205438 -303.09185)
		(end 140.9192 -292.805612)
		(width 0.127)
		(layer "In6.Cu")
		(net "SMB_S3M_CPU1_PIROM_3V3AUX_SCL_1")
	)
	(segment
		(start 175.87976 -324.38467)
		(end 175.4632 -324.38467)
		(width 0.127)
		(layer "In6.Cu")
		(net "SMB_S3M_CPU1_PIROM_3V3AUX_SCL_1")
	)
	(segment
		(start 140.9192 -292.805612)
		(end 140.9192 -286.994854)
		(width 0.127)
		(layer "In6.Cu")
		(net "SMB_S3M_CPU1_PIROM_3V3AUX_SCL_1")
	)
	(segment
		(start 167.81907 -323.004942)
		(end 167.232076 -322.417948)
		(width 0.127)
		(layer "In6.Cu")
		(net "SMB_S3M_CPU1_PIROM_3V3AUX_SCL_1")
	)
	(segment
		(start 175.34382 -324.50405)
		(end 175.34382 -324.84949)
		(width 0.127)
		(layer "In6.Cu")
		(net "SMB_S3M_CPU1_PIROM_3V3AUX_SCL_1")
	)
	(segment
		(start 120.913144 -273.860006)
		(end 120.678448 -273.46275)
		(width 0.0889)
		(layer "In6.Cu")
		(net "SMB_S3M_CPU1_PIROM_3V3AUX_SCL_1")
	)
	(segment
		(start 163.12388 -322.417948)
		(end 162.59048 -321.884548)
		(width 0.127)
		(layer "In6.Cu")
		(net "SMB_S3M_CPU1_PIROM_3V3AUX_SCL_1")
	)
	(segment
		(start 123.497848 -279.978612)
		(end 123.497848 -279.964134)
		(width 0.0889)
		(layer "In6.Cu")
		(net "SMB_S3M_CPU1_PIROM_3V3AUX_SCL_1")
	)
	(segment
		(start 126.317248 -283.234384)
		(end 126.317248 -283.219906)
		(width 0.0889)
		(layer "In6.Cu")
		(net "SMB_S3M_CPU1_PIROM_3V3AUX_SCL_1")
	)
	(segment
		(start 174.6885 -324.84949)
		(end 174.6885 -324.50405)
		(width 0.127)
		(layer "In6.Cu")
		(net "SMB_S3M_CPU1_PIROM_3V3AUX_SCL_1")
	)
	(segment
		(start 127.961644 -283.626814)
		(end 127.948182 -283.634688)
		(width 0.0889)
		(layer "In6.Cu")
		(net "SMB_S3M_CPU1_PIROM_3V3AUX_SCL_1")
	)
	(segment
		(start 174.6885 -324.50405)
		(end 174.56912 -324.38467)
		(width 0.127)
		(layer "In6.Cu")
		(net "SMB_S3M_CPU1_PIROM_3V3AUX_SCL_1")
	)
	(segment
		(start 122.327924 -276.304502)
		(end 122.318272 -276.298914)
		(width 0.0889)
		(layer "In6.Cu")
		(net "SMB_S3M_CPU1_PIROM_3V3AUX_SCL_1")
	)
	(segment
		(start 124.213112 -281.191462)
		(end 124.197618 -281.182318)
		(width 0.0889)
		(layer "In6.Cu")
		(net "SMB_S3M_CPU1_PIROM_3V3AUX_SCL_1")
	)
	(segment
		(start 122.558048 -276.718268)
		(end 122.558048 -276.708616)
		(width 0.0889)
		(layer "In6.Cu")
		(net "SMB_S3M_CPU1_PIROM_3V3AUX_SCL_1")
	)
	(segment
		(start 131.720844 -283.626814)
		(end 131.707382 -283.634688)
		(width 0.0889)
		(layer "In6.Cu")
		(net "SMB_S3M_CPU1_PIROM_3V3AUX_SCL_1")
	)
	(segment
		(start 175.34382 -324.84949)
		(end 175.22444 -324.96887)
		(width 0.127)
		(layer "In6.Cu")
		(net "SMB_S3M_CPU1_PIROM_3V3AUX_SCL_1")
	)
	(segment
		(start 134.070344 -284.44063)
		(end 134.070598 -284.44063)
		(width 0.0889)
		(layer "In6.Cu")
		(net "SMB_S3M_CPU1_PIROM_3V3AUX_SCL_1")
	)
	(segment
		(start 133.600698 -284.44063)
		(end 133.600444 -284.44063)
		(width 0.0889)
		(layer "In6.Cu")
		(net "SMB_S3M_CPU1_PIROM_3V3AUX_SCL_1")
	)
	(segment
		(start 137.508234 -286.168338)
		(end 137.37463 -286.091122)
		(width 0.0889)
		(layer "In6.Cu")
		(net "SMB_S3M_CPU1_PIROM_3V3AUX_SCL_1")
	)
	(segment
		(start 172.560488 -324.96887)
		(end 167.81907 -323.004942)
		(width 0.127)
		(layer "In6.Cu")
		(net "SMB_S3M_CPU1_PIROM_3V3AUX_SCL_1")
	)
	(segment
		(start 125.612144 -282.812998)
		(end 125.612398 -282.812998)
		(width 0.0889)
		(layer "In6.Cu")
		(net "SMB_S3M_CPU1_PIROM_3V3AUX_SCL_1")
	)
	(segment
		(start 123.967494 -280.778204)
		(end 123.967494 -280.77795)
		(width 0.0889)
		(layer "In6.Cu")
		(net "SMB_S3M_CPU1_PIROM_3V3AUX_SCL_1")
	)
	(segment
		(start 178.457098 -327.362058)
		(end 178.457098 -325.84009)
		(width 0.127)
		(layer "In6.Cu")
		(net "SMB_S3M_CPU1_PIROM_3V3AUX_SCL_1")
	)
	(segment
		(start 174.15256 -324.38467)
		(end 174.03318 -324.50405)
		(width 0.127)
		(layer "In6.Cu")
		(net "SMB_S3M_CPU1_PIROM_3V3AUX_SCL_1")
	)
	(segment
		(start 176.11852 -324.96887)
		(end 175.99914 -324.84949)
		(width 0.127)
		(layer "In6.Cu")
		(net "SMB_S3M_CPU1_PIROM_3V3AUX_SCL_1")
	)
	(segment
		(start 137.37463 -286.091122)
		(end 137.37463 -286.091376)
		(width 0.0889)
		(layer "In6.Cu")
		(net "SMB_S3M_CPU1_PIROM_3V3AUX_SCL_1")
	)
	(segment
		(start 120.678448 -273.453098)
		(end 120.678194 -272.639282)
		(width 0.0889)
		(layer "In6.Cu")
		(net "SMB_S3M_CPU1_PIROM_3V3AUX_SCL_1")
	)
	(segment
		(start 120.927368 -273.868388)
		(end 120.913144 -273.860006)
		(width 0.0889)
		(layer "In6.Cu")
		(net "SMB_S3M_CPU1_PIROM_3V3AUX_SCL_1")
	)
	(segment
		(start 137.13968 -285.684468)
		(end 137.13968 -285.669736)
		(width 0.0889)
		(layer "In6.Cu")
		(net "SMB_S3M_CPU1_PIROM_3V3AUX_SCL_1")
	)
	(segment
		(start 174.03318 -324.50405)
		(end 174.03318 -324.84949)
		(width 0.127)
		(layer "In6.Cu")
		(net "SMB_S3M_CPU1_PIROM_3V3AUX_SCL_1")
	)
	(segment
		(start 122.79757 -277.118318)
		(end 122.792744 -277.115524)
		(width 0.0889)
		(layer "In6.Cu")
		(net "SMB_S3M_CPU1_PIROM_3V3AUX_SCL_1")
	)
	(segment
		(start 134.540244 -284.44063)
		(end 134.526782 -284.432756)
		(width 0.0889)
		(layer "In6.Cu")
		(net "SMB_S3M_CPU1_PIROM_3V3AUX_SCL_1")
	)
	(segment
		(start 175.22444 -324.96887)
		(end 174.80788 -324.96887)
		(width 0.127)
		(layer "In6.Cu")
		(net "SMB_S3M_CPU1_PIROM_3V3AUX_SCL_1")
	)
	(segment
		(start 140.113004 -286.188658)
		(end 138.596116 -286.188658)
		(width 0.127)
		(layer "In6.Cu")
		(net "SMB_S3M_CPU1_PIROM_3V3AUX_SCL_1")
	)
	(segment
		(start 133.600444 -284.44063)
		(end 133.595618 -284.437836)
		(width 0.0889)
		(layer "In6.Cu")
		(net "SMB_S3M_CPU1_PIROM_3V3AUX_SCL_1")
	)
	(segment
		(start 175.4632 -324.38467)
		(end 175.34382 -324.50405)
		(width 0.127)
		(layer "In6.Cu")
		(net "SMB_S3M_CPU1_PIROM_3V3AUX_SCL_1")
	)
	(segment
		(start 176.98974 -330.241148)
		(end 176.98974 -328.829416)
		(width 0.127)
		(layer "In6.Cu")
		(net "SMB_S3M_CPU1_PIROM_3V3AUX_SCL_1")
	)
	(segment
		(start 128.901444 -283.626814)
		(end 128.887982 -283.634688)
		(width 0.0889)
		(layer "In6.Cu")
		(net "SMB_S3M_CPU1_PIROM_3V3AUX_SCL_1")
	)
	(segment
		(start 174.56912 -324.38467)
		(end 174.15256 -324.38467)
		(width 0.127)
		(layer "In6.Cu")
		(net "SMB_S3M_CPU1_PIROM_3V3AUX_SCL_1")
	)
	(segment
		(start 121.388124 -274.676616)
		(end 121.378472 -274.671028)
		(width 0.0889)
		(layer "In6.Cu")
		(net "SMB_S3M_CPU1_PIROM_3V3AUX_SCL_1")
	)
	(segment
		(start 121.618248 -275.090382)
		(end 121.618248 -275.08073)
		(width 0.0889)
		(layer "In6.Cu")
		(net "SMB_S3M_CPU1_PIROM_3V3AUX_SCL_1")
	)
	(segment
		(start 151.205438 -316.10935)
		(end 151.205438 -303.09185)
		(width 0.127)
		(layer "In6.Cu")
		(net "SMB_S3M_CPU1_PIROM_3V3AUX_SCL_1")
	)
	(segment
		(start 173.9138 -324.96887)
		(end 172.560488 -324.96887)
		(width 0.127)
		(layer "In6.Cu")
		(net "SMB_S3M_CPU1_PIROM_3V3AUX_SCL_1")
	)
	(segment
		(start 167.232076 -322.417948)
		(end 163.12388 -322.417948)
		(width 0.127)
		(layer "In6.Cu")
		(net "SMB_S3M_CPU1_PIROM_3V3AUX_SCL_1")
	)
	(segment
		(start 124.907294 -282.419298)
		(end 124.907294 -282.405836)
		(width 0.0889)
		(layer "In6.Cu")
		(net "SMB_S3M_CPU1_PIROM_3V3AUX_SCL_1")
	)
	(segment
		(start 124.67717 -282.001722)
		(end 124.672344 -281.998928)
		(width 0.0889)
		(layer "In6.Cu")
		(net "SMB_S3M_CPU1_PIROM_3V3AUX_SCL_1")
	)
	(segment
		(start 136.904984 -285.277306)
		(end 136.832086 -285.235142)
		(width 0.0889)
		(layer "In6.Cu")
		(net "SMB_S3M_CPU1_PIROM_3V3AUX_SCL_1")
	)
	(segment
		(start 136.662414 -284.858714)
		(end 136.662414 -284.858968)
		(width 0.0889)
		(layer "In6.Cu")
		(net "SMB_S3M_CPU1_PIROM_3V3AUX_SCL_1")
	)
	(segment
		(start 175.99914 -324.84949)
		(end 175.99914 -324.50405)
		(width 0.127)
		(layer "In6.Cu")
		(net "SMB_S3M_CPU1_PIROM_3V3AUX_SCL_1")
	)
	(arc
		(start 134.526782 -284.432756)
		(mid 134.297529 -284.377512)
		(end 134.070344 -284.44063)
		(width 0.0889)
		(layer "In6.Cu")
		(net "SMB_S3M_CPU1_PIROM_3V3AUX_SCL_1")
	)
	(arc
		(start 135.949944 -284.44063)
		(mid 135.714994 -284.50359)
		(end 135.480044 -284.44063)
		(width 0.0889)
		(layer "In6.Cu")
		(net "SMB_S3M_CPU1_PIROM_3V3AUX_SCL_1")
	)
	(arc
		(start 128.887982 -283.634688)
		(mid 128.658729 -283.689932)
		(end 128.431544 -283.626814)
		(width 0.0889)
		(layer "In6.Cu")
		(net "SMB_S3M_CPU1_PIROM_3V3AUX_SCL_1")
	)
	(arc
		(start 133.595618 -284.437836)
		(mid 133.427062 -284.266242)
		(end 133.365494 -284.033722)
		(width 0.0889)
		(layer "In6.Cu")
		(net "SMB_S3M_CPU1_PIROM_3V3AUX_SCL_1")
	)
	(arc
		(start 121.618248 -275.08073)
		(mid 121.556685 -274.848207)
		(end 121.388124 -274.676616)
		(width 0.0889)
		(layer "In6.Cu")
		(net "SMB_S3M_CPU1_PIROM_3V3AUX_SCL_1")
	)
	(arc
		(start 127.948182 -283.634688)
		(mid 127.718929 -283.689932)
		(end 127.491744 -283.626814)
		(width 0.0889)
		(layer "In6.Cu")
		(net "SMB_S3M_CPU1_PIROM_3V3AUX_SCL_1")
	)
	(arc
		(start 121.148348 -274.266914)
		(mid 121.08941 -274.039062)
		(end 120.927368 -273.868388)
		(width 0.0889)
		(layer "In6.Cu")
		(net "SMB_S3M_CPU1_PIROM_3V3AUX_SCL_1")
	)
	(arc
		(start 124.672344 -281.998928)
		(mid 124.502894 -281.831082)
		(end 124.437648 -281.601672)
		(width 0.0889)
		(layer "In6.Cu")
		(net "SMB_S3M_CPU1_PIROM_3V3AUX_SCL_1")
	)
	(arc
		(start 129.841244 -283.626814)
		(mid 129.606294 -283.689774)
		(end 129.371344 -283.626814)
		(width 0.0889)
		(layer "In6.Cu")
		(net "SMB_S3M_CPU1_PIROM_3V3AUX_SCL_1")
	)
	(arc
		(start 121.378472 -274.671028)
		(mid 121.209916 -274.499434)
		(end 121.148348 -274.266914)
		(width 0.0889)
		(layer "In6.Cu")
		(net "SMB_S3M_CPU1_PIROM_3V3AUX_SCL_1")
	)
	(arc
		(start 137.37463 -286.091376)
		(mid 137.202658 -285.919394)
		(end 137.13968 -285.684468)
		(width 0.0889)
		(layer "In6.Cu")
		(net "SMB_S3M_CPU1_PIROM_3V3AUX_SCL_1")
	)
	(arc
		(start 123.732544 -280.371042)
		(mid 123.56424 -280.205302)
		(end 123.497848 -279.978612)
		(width 0.0889)
		(layer "In6.Cu")
		(net "SMB_S3M_CPU1_PIROM_3V3AUX_SCL_1")
	)
	(arc
		(start 131.250944 -283.626814)
		(mid 131.015994 -283.563854)
		(end 130.781044 -283.626814)
		(width 0.0889)
		(layer "In6.Cu")
		(net "SMB_S3M_CPU1_PIROM_3V3AUX_SCL_1")
	)
	(arc
		(start 136.832086 -285.235142)
		(mid 136.704485 -285.066214)
		(end 136.662414 -284.858714)
		(width 0.0889)
		(layer "In6.Cu")
		(net "SMB_S3M_CPU1_PIROM_3V3AUX_SCL_1")
	)
	(arc
		(start 121.852944 -275.487638)
		(mid 121.683494 -275.319792)
		(end 121.618248 -275.090382)
		(width 0.0889)
		(layer "In6.Cu")
		(net "SMB_S3M_CPU1_PIROM_3V3AUX_SCL_1")
	)
	(arc
		(start 122.792744 -277.115524)
		(mid 122.623294 -276.947678)
		(end 122.558048 -276.718268)
		(width 0.0889)
		(layer "In6.Cu")
		(net "SMB_S3M_CPU1_PIROM_3V3AUX_SCL_1")
	)
	(arc
		(start 133.130544 -283.626814)
		(mid 132.895594 -283.563854)
		(end 132.660644 -283.626814)
		(width 0.0889)
		(layer "In6.Cu")
		(net "SMB_S3M_CPU1_PIROM_3V3AUX_SCL_1")
	)
	(arc
		(start 132.660644 -283.626814)
		(mid 132.425694 -283.689774)
		(end 132.190744 -283.626814)
		(width 0.0889)
		(layer "In6.Cu")
		(net "SMB_S3M_CPU1_PIROM_3V3AUX_SCL_1")
	)
	(arc
		(start 138.253978 -286.064706)
		(mid 138.051902 -286.046467)
		(end 137.859516 -286.110934)
		(width 0.0889)
		(layer "In6.Cu")
		(net "SMB_S3M_CPU1_PIROM_3V3AUX_SCL_1")
	)
	(arc
		(start 123.258072 -279.554432)
		(mid 123.089516 -279.382838)
		(end 123.027948 -279.150318)
		(width 0.0889)
		(layer "In6.Cu")
		(net "SMB_S3M_CPU1_PIROM_3V3AUX_SCL_1")
	)
	(arc
		(start 136.419844 -284.44063)
		(mid 136.184894 -284.37767)
		(end 135.949944 -284.44063)
		(width 0.0889)
		(layer "In6.Cu")
		(net "SMB_S3M_CPU1_PIROM_3V3AUX_SCL_1")
	)
	(arc
		(start 128.431544 -283.626814)
		(mid 128.196594 -283.563854)
		(end 127.961644 -283.626814)
		(width 0.0889)
		(layer "In6.Cu")
		(net "SMB_S3M_CPU1_PIROM_3V3AUX_SCL_1")
	)
	(arc
		(start 123.497848 -279.964134)
		(mid 123.436285 -279.731611)
		(end 123.267724 -279.56002)
		(width 0.0889)
		(layer "In6.Cu")
		(net "SMB_S3M_CPU1_PIROM_3V3AUX_SCL_1")
	)
	(arc
		(start 127.491744 -283.626814)
		(mid 127.256794 -283.563854)
		(end 127.021844 -283.626814)
		(width 0.0889)
		(layer "In6.Cu")
		(net "SMB_S3M_CPU1_PIROM_3V3AUX_SCL_1")
	)
	(arc
		(start 122.558048 -276.708616)
		(mid 122.496485 -276.476093)
		(end 122.327924 -276.304502)
		(width 0.0889)
		(layer "In6.Cu")
		(net "SMB_S3M_CPU1_PIROM_3V3AUX_SCL_1")
	)
	(arc
		(start 137.859516 -286.110934)
		(mid 137.689219 -286.172287)
		(end 137.508234 -286.168338)
		(width 0.0889)
		(layer "In6.Cu")
		(net "SMB_S3M_CPU1_PIROM_3V3AUX_SCL_1")
	)
	(arc
		(start 126.317248 -283.219906)
		(mid 126.082195 -282.812901)
		(end 125.612144 -282.812998)
		(width 0.0889)
		(layer "In6.Cu")
		(net "SMB_S3M_CPU1_PIROM_3V3AUX_SCL_1")
	)
	(arc
		(start 133.365494 -284.033722)
		(mid 133.302534 -283.798899)
		(end 133.130544 -283.627068)
		(width 0.0889)
		(layer "In6.Cu")
		(net "SMB_S3M_CPU1_PIROM_3V3AUX_SCL_1")
	)
	(arc
		(start 130.311144 -283.626814)
		(mid 130.076194 -283.563854)
		(end 129.841244 -283.626814)
		(width 0.0889)
		(layer "In6.Cu")
		(net "SMB_S3M_CPU1_PIROM_3V3AUX_SCL_1")
	)
	(arc
		(start 124.907294 -282.405836)
		(mid 124.845731 -282.173313)
		(end 124.67717 -282.001722)
		(width 0.0889)
		(layer "In6.Cu")
		(net "SMB_S3M_CPU1_PIROM_3V3AUX_SCL_1")
	)
	(arc
		(start 123.967494 -280.77795)
		(mid 123.904544 -280.543008)
		(end 123.732544 -280.371042)
		(width 0.0889)
		(layer "In6.Cu")
		(net "SMB_S3M_CPU1_PIROM_3V3AUX_SCL_1")
	)
	(arc
		(start 125.612398 -282.812998)
		(mid 125.148043 -282.816437)
		(end 124.907294 -282.419298)
		(width 0.0889)
		(layer "In6.Cu")
		(net "SMB_S3M_CPU1_PIROM_3V3AUX_SCL_1")
	)
	(arc
		(start 130.781044 -283.626814)
		(mid 130.546094 -283.689774)
		(end 130.311144 -283.626814)
		(width 0.0889)
		(layer "In6.Cu")
		(net "SMB_S3M_CPU1_PIROM_3V3AUX_SCL_1")
	)
	(arc
		(start 122.792744 -277.929594)
		(mid 123.027873 -277.525285)
		(end 122.79757 -277.118318)
		(width 0.0889)
		(layer "In6.Cu")
		(net "SMB_S3M_CPU1_PIROM_3V3AUX_SCL_1")
	)
	(arc
		(start 124.437648 -281.59202)
		(mid 124.377693 -281.36241)
		(end 124.213112 -281.191462)
		(width 0.0889)
		(layer "In6.Cu")
		(net "SMB_S3M_CPU1_PIROM_3V3AUX_SCL_1")
	)
	(arc
		(start 135.010144 -284.44063)
		(mid 134.775194 -284.50359)
		(end 134.540244 -284.44063)
		(width 0.0889)
		(layer "In6.Cu")
		(net "SMB_S3M_CPU1_PIROM_3V3AUX_SCL_1")
	)
	(arc
		(start 135.480044 -284.44063)
		(mid 135.245094 -284.37767)
		(end 135.010144 -284.44063)
		(width 0.0889)
		(layer "In6.Cu")
		(net "SMB_S3M_CPU1_PIROM_3V3AUX_SCL_1")
	)
	(arc
		(start 136.662414 -284.858968)
		(mid 136.603071 -284.621323)
		(end 136.430766 -284.447234)
		(width 0.0889)
		(layer "In6.Cu")
		(net "SMB_S3M_CPU1_PIROM_3V3AUX_SCL_1")
	)
	(arc
		(start 122.088148 -275.8948)
		(mid 122.027091 -275.663167)
		(end 121.859802 -275.491702)
		(width 0.0889)
		(layer "In6.Cu")
		(net "SMB_S3M_CPU1_PIROM_3V3AUX_SCL_1")
	)
	(arc
		(start 122.318272 -276.298914)
		(mid 122.149716 -276.12732)
		(end 122.088148 -275.8948)
		(width 0.0889)
		(layer "In6.Cu")
		(net "SMB_S3M_CPU1_PIROM_3V3AUX_SCL_1")
	)
	(arc
		(start 131.707382 -283.634688)
		(mid 131.478129 -283.689932)
		(end 131.250944 -283.626814)
		(width 0.0889)
		(layer "In6.Cu")
		(net "SMB_S3M_CPU1_PIROM_3V3AUX_SCL_1")
	)
	(arc
		(start 124.197618 -281.182318)
		(mid 124.029062 -281.010724)
		(end 123.967494 -280.778204)
		(width 0.0889)
		(layer "In6.Cu")
		(net "SMB_S3M_CPU1_PIROM_3V3AUX_SCL_1")
	)
	(arc
		(start 132.190744 -283.626814)
		(mid 131.955794 -283.563854)
		(end 131.720844 -283.626814)
		(width 0.0889)
		(layer "In6.Cu")
		(net "SMB_S3M_CPU1_PIROM_3V3AUX_SCL_1")
	)
	(arc
		(start 137.13968 -285.669736)
		(mid 137.073289 -285.443045)
		(end 136.904984 -285.277306)
		(width 0.0889)
		(layer "In6.Cu")
		(net "SMB_S3M_CPU1_PIROM_3V3AUX_SCL_1")
	)
	(arc
		(start 123.027948 -279.150318)
		(mid 122.965054 -278.915677)
		(end 122.793252 -278.743918)
		(width 0.0889)
		(layer "In6.Cu")
		(net "SMB_S3M_CPU1_PIROM_3V3AUX_SCL_1")
	)
	(arc
		(start 134.070598 -284.44063)
		(mid 133.835648 -284.50359)
		(end 133.600698 -284.44063)
		(width 0.0889)
		(layer "In6.Cu")
		(net "SMB_S3M_CPU1_PIROM_3V3AUX_SCL_1")
	)
	(arc
		(start 138.596116 -286.188658)
		(mid 138.470058 -286.171839)
		(end 138.352784 -286.122618)
		(width 0.0889)
		(layer "In6.Cu")
		(net "SMB_S3M_CPU1_PIROM_3V3AUX_SCL_1")
	)
	(arc
		(start 122.792744 -278.74341)
		(mid 122.557953 -278.336502)
		(end 122.792744 -277.929594)
		(width 0.0889)
		(layer "In6.Cu")
		(net "SMB_S3M_CPU1_PIROM_3V3AUX_SCL_1")
	)
	(arc
		(start 129.371344 -283.626814)
		(mid 129.136394 -283.563854)
		(end 128.901444 -283.626814)
		(width 0.0889)
		(layer "In6.Cu")
		(net "SMB_S3M_CPU1_PIROM_3V3AUX_SCL_1")
	)
	(arc
		(start 127.021844 -283.626814)
		(mid 126.558266 -283.630399)
		(end 126.317248 -283.234384)
		(width 0.0889)
		(layer "In6.Cu")
		(net "SMB_S3M_CPU1_PIROM_3V3AUX_SCL_1")
	)
	(segment
		(start 366.268762 -272.917158)
		(end 366.268762 -273.452844)
		(width 0.12954)
		(layer "F.Cu")
		(net "SMB_S3M_CPU0_PIROM_3V3AUX_SDA_1")
	)
	(segment
		(start 366.268762 -273.452844)
		(end 366.269016 -273.453098)
		(width 0.12954)
		(layer "F.Cu")
		(net "SMB_S3M_CPU0_PIROM_3V3AUX_SDA_1")
	)
	(via
		(at 280.79192 -385.567428)
		(size 0.508)
		(drill 0.254)
		(layers "F.Cu" "B.Cu")
		(net "SMB_S3M_CPU0_PIROM_3V3AUX_SDA_1")
	)
	(via
		(at 416.766248 -322.58508)
		(size 0.508)
		(drill 0.254)
		(layers "F.Cu" "B.Cu")
		(net "SMB_S3M_CPU0_PIROM_3V3AUX_SDA_1")
	)
	(via
		(at 366.269016 -273.453098)
		(size 0.4572)
		(drill 0.2032)
		(layers "F.Cu" "B.Cu")
		(net "SMB_S3M_CPU0_PIROM_3V3AUX_SDA_1")
	)
	(via
		(at 181.53888 -326.685148)
		(size 0.508)
		(drill 0.254)
		(layers "F.Cu" "B.Cu")
		(net "SMB_S3M_CPU0_PIROM_3V3AUX_SDA_1")
	)
	(segment
		(start 181.47792 -328.626978)
		(end 181.605174 -328.754232)
		(width 0.12954)
		(layer "B.Cu")
		(net "SMB_S3M_CPU0_PIROM_3V3AUX_SDA_1")
	)
	(segment
		(start 182.120032 -329.761088)
		(end 181.992778 -329.888342)
		(width 0.12954)
		(layer "B.Cu")
		(net "SMB_S3M_CPU0_PIROM_3V3AUX_SDA_1")
	)
	(segment
		(start 181.865524 -328.754232)
		(end 181.992778 -328.881486)
		(width 0.12954)
		(layer "B.Cu")
		(net "SMB_S3M_CPU0_PIROM_3V3AUX_SDA_1")
	)
	(segment
		(start 181.605174 -328.319892)
		(end 181.47792 -328.447146)
		(width 0.12954)
		(layer "B.Cu")
		(net "SMB_S3M_CPU0_PIROM_3V3AUX_SDA_1")
	)
	(segment
		(start 181.992778 -329.199494)
		(end 182.120032 -329.326748)
		(width 0.12954)
		(layer "B.Cu")
		(net "SMB_S3M_CPU0_PIROM_3V3AUX_SDA_1")
	)
	(segment
		(start 181.53888 -327.411588)
		(end 181.992778 -327.865486)
		(width 0.12954)
		(layer "B.Cu")
		(net "SMB_S3M_CPU0_PIROM_3V3AUX_SDA_1")
	)
	(segment
		(start 181.992778 -328.881486)
		(end 181.992778 -329.199494)
		(width 0.12954)
		(layer "B.Cu")
		(net "SMB_S3M_CPU0_PIROM_3V3AUX_SDA_1")
	)
	(segment
		(start 181.865524 -328.319892)
		(end 181.605174 -328.319892)
		(width 0.12954)
		(layer "B.Cu")
		(net "SMB_S3M_CPU0_PIROM_3V3AUX_SDA_1")
	)
	(segment
		(start 182.45582 -329.633834)
		(end 182.328566 -329.761088)
		(width 0.12954)
		(layer "B.Cu")
		(net "SMB_S3M_CPU0_PIROM_3V3AUX_SDA_1")
	)
	(segment
		(start 181.992778 -327.865486)
		(end 181.992778 -328.192638)
		(width 0.12954)
		(layer "B.Cu")
		(net "SMB_S3M_CPU0_PIROM_3V3AUX_SDA_1")
	)
	(segment
		(start 181.47792 -328.447146)
		(end 181.47792 -328.626978)
		(width 0.12954)
		(layer "B.Cu")
		(net "SMB_S3M_CPU0_PIROM_3V3AUX_SDA_1")
	)
	(segment
		(start 181.53888 -326.685148)
		(end 181.53888 -327.411588)
		(width 0.12954)
		(layer "B.Cu")
		(net "SMB_S3M_CPU0_PIROM_3V3AUX_SDA_1")
	)
	(segment
		(start 181.992778 -330.227178)
		(end 181.724808 -330.495148)
		(width 0.12954)
		(layer "B.Cu")
		(net "SMB_S3M_CPU0_PIROM_3V3AUX_SDA_1")
	)
	(segment
		(start 181.992778 -329.888342)
		(end 181.992778 -330.227178)
		(width 0.12954)
		(layer "B.Cu")
		(net "SMB_S3M_CPU0_PIROM_3V3AUX_SDA_1")
	)
	(segment
		(start 181.605174 -328.754232)
		(end 181.865524 -328.754232)
		(width 0.12954)
		(layer "B.Cu")
		(net "SMB_S3M_CPU0_PIROM_3V3AUX_SDA_1")
	)
	(segment
		(start 182.45582 -329.454002)
		(end 182.45582 -329.633834)
		(width 0.12954)
		(layer "B.Cu")
		(net "SMB_S3M_CPU0_PIROM_3V3AUX_SDA_1")
	)
	(segment
		(start 182.328566 -329.326748)
		(end 182.45582 -329.454002)
		(width 0.12954)
		(layer "B.Cu")
		(net "SMB_S3M_CPU0_PIROM_3V3AUX_SDA_1")
	)
	(segment
		(start 181.992778 -328.192638)
		(end 181.865524 -328.319892)
		(width 0.12954)
		(layer "B.Cu")
		(net "SMB_S3M_CPU0_PIROM_3V3AUX_SDA_1")
	)
	(segment
		(start 181.724808 -330.495148)
		(end 181.30393 -330.495148)
		(width 0.12954)
		(layer "B.Cu")
		(net "SMB_S3M_CPU0_PIROM_3V3AUX_SDA_1")
	)
	(segment
		(start 182.328566 -329.761088)
		(end 182.120032 -329.761088)
		(width 0.12954)
		(layer "B.Cu")
		(net "SMB_S3M_CPU0_PIROM_3V3AUX_SDA_1")
	)
	(segment
		(start 182.120032 -329.326748)
		(end 182.328566 -329.326748)
		(width 0.12954)
		(layer "B.Cu")
		(net "SMB_S3M_CPU0_PIROM_3V3AUX_SDA_1")
	)
	(segment
		(start 368.853212 -276.301708)
		(end 368.853212 -276.301454)
		(width 0.127)
		(layer "In6.Cu")
		(net "SMB_S3M_CPU0_PIROM_3V3AUX_SDA_1")
	)
	(segment
		(start 374.022112 -284.44063)
		(end 374.01246 -284.435042)
		(width 0.127)
		(layer "In6.Cu")
		(net "SMB_S3M_CPU0_PIROM_3V3AUX_SDA_1")
	)
	(segment
		(start 368.383312 -275.487638)
		(end 368.36985 -275.495512)
		(width 0.127)
		(layer "In6.Cu")
		(net "SMB_S3M_CPU0_PIROM_3V3AUX_SDA_1")
	)
	(segment
		(start 382.010412 -285.254446)
		(end 382.010666 -285.254446)
		(width 0.127)
		(layer "In6.Cu")
		(net "SMB_S3M_CPU0_PIROM_3V3AUX_SDA_1")
	)
	(segment
		(start 416.766248 -322.58508)
		(end 416.480498 -322.87083)
		(width 0.127)
		(layer "In6.Cu")
		(net "SMB_S3M_CPU0_PIROM_3V3AUX_SDA_1")
	)
	(segment
		(start 369.088162 -275.8948)
		(end 369.088162 -275.881338)
		(width 0.127)
		(layer "In6.Cu")
		(net "SMB_S3M_CPU0_PIROM_3V3AUX_SDA_1")
	)
	(segment
		(start 374.961912 -284.44063)
		(end 374.94845 -284.432756)
		(width 0.127)
		(layer "In6.Cu")
		(net "SMB_S3M_CPU0_PIROM_3V3AUX_SDA_1")
	)
	(segment
		(start 367.45418 -274.680172)
		(end 367.443512 -274.673822)
		(width 0.127)
		(layer "In6.Cu")
		(net "SMB_S3M_CPU0_PIROM_3V3AUX_SDA_1")
	)
	(segment
		(start 370.498116 -279.973786)
		(end 370.498116 -279.964134)
		(width 0.127)
		(layer "In6.Cu")
		(net "SMB_S3M_CPU0_PIROM_3V3AUX_SDA_1")
	)
	(segment
		(start 380.835916 -284.85719)
		(end 380.835916 -284.847538)
		(width 0.127)
		(layer "In6.Cu")
		(net "SMB_S3M_CPU0_PIROM_3V3AUX_SDA_1")
	)
	(segment
		(start 367.443512 -274.673822)
		(end 367.438686 -274.671028)
		(width 0.127)
		(layer "In6.Cu")
		(net "SMB_S3M_CPU0_PIROM_3V3AUX_SDA_1")
	)
	(segment
		(start 370.498116 -281.59202)
		(end 370.498116 -281.582368)
		(width 0.127)
		(layer "In6.Cu")
		(net "SMB_S3M_CPU0_PIROM_3V3AUX_SDA_1")
	)
	(segment
		(start 388.375144 -289.504882)
		(end 385.830064 -286.959802)
		(width 0.127)
		(layer "In6.Cu")
		(net "SMB_S3M_CPU0_PIROM_3V3AUX_SDA_1")
	)
	(segment
		(start 380.600712 -284.44063)
		(end 380.58725 -284.432756)
		(width 0.127)
		(layer "In6.Cu")
		(net "SMB_S3M_CPU0_PIROM_3V3AUX_SDA_1")
	)
	(segment
		(start 370.258086 -282.001722)
		(end 370.262912 -281.998928)
		(width 0.127)
		(layer "In6.Cu")
		(net "SMB_S3M_CPU0_PIROM_3V3AUX_SDA_1")
	)
	(segment
		(start 370.027962 -282.419298)
		(end 370.027962 -282.405836)
		(width 0.127)
		(layer "In6.Cu")
		(net "SMB_S3M_CPU0_PIROM_3V3AUX_SDA_1")
	)
	(segment
		(start 384.608832 -286.559752)
		(end 384.608324 -286.501586)
		(width 0.127)
		(layer "In6.Cu")
		(net "SMB_S3M_CPU0_PIROM_3V3AUX_SDA_1")
	)
	(segment
		(start 371.672612 -284.44063)
		(end 371.672866 -284.44063)
		(width 0.127)
		(layer "In6.Cu")
		(net "SMB_S3M_CPU0_PIROM_3V3AUX_SDA_1")
	)
	(segment
		(start 369.797838 -278.746204)
		(end 369.793012 -278.74341)
		(width 0.127)
		(layer "In6.Cu")
		(net "SMB_S3M_CPU0_PIROM_3V3AUX_SDA_1")
	)
	(segment
		(start 369.558316 -278.35098)
		(end 369.558316 -278.336502)
		(width 0.127)
		(layer "In6.Cu")
		(net "SMB_S3M_CPU0_PIROM_3V3AUX_SDA_1")
	)
	(segment
		(start 375.901712 -284.44063)
		(end 375.88825 -284.432756)
		(width 0.127)
		(layer "In6.Cu")
		(net "SMB_S3M_CPU0_PIROM_3V3AUX_SDA_1")
	)
	(segment
		(start 371.202712 -284.44063)
		(end 371.197886 -284.437836)
		(width 0.127)
		(layer "In6.Cu")
		(net "SMB_S3M_CPU0_PIROM_3V3AUX_SDA_1")
	)
	(segment
		(start 376.841512 -284.44063)
		(end 376.82805 -284.432756)
		(width 0.127)
		(layer "In6.Cu")
		(net "SMB_S3M_CPU0_PIROM_3V3AUX_SDA_1")
	)
	(segment
		(start 372.142512 -284.44063)
		(end 372.12905 -284.432756)
		(width 0.127)
		(layer "In6.Cu")
		(net "SMB_S3M_CPU0_PIROM_3V3AUX_SDA_1")
	)
	(segment
		(start 384.919474 -286.950912)
		(end 384.85572 -286.91713)
		(width 0.127)
		(layer "In6.Cu")
		(net "SMB_S3M_CPU0_PIROM_3V3AUX_SDA_1")
	)
	(segment
		(start 378.721112 -284.44063)
		(end 378.70765 -284.432756)
		(width 0.127)
		(layer "In6.Cu")
		(net "SMB_S3M_CPU0_PIROM_3V3AUX_SDA_1")
	)
	(segment
		(start 368.383566 -275.487892)
		(end 368.383312 -275.487638)
		(width 0.127)
		(layer "In6.Cu")
		(net "SMB_S3M_CPU0_PIROM_3V3AUX_SDA_1")
	)
	(segment
		(start 370.277136 -282.82138)
		(end 370.262912 -282.812998)
		(width 0.127)
		(layer "In6.Cu")
		(net "SMB_S3M_CPU0_PIROM_3V3AUX_SDA_1")
	)
	(segment
		(start 385.830064 -286.959802)
		(end 385.654296 -286.868616)
		(width 0.127)
		(layer "In6.Cu")
		(net "SMB_S3M_CPU0_PIROM_3V3AUX_SDA_1")
	)
	(segment
		(start 381.540766 -285.254446)
		(end 381.540512 -285.254446)
		(width 0.127)
		(layer "In6.Cu")
		(net "SMB_S3M_CPU0_PIROM_3V3AUX_SDA_1")
	)
	(segment
		(start 370.967762 -280.778204)
		(end 370.967762 -280.764742)
		(width 0.127)
		(layer "In6.Cu")
		(net "SMB_S3M_CPU0_PIROM_3V3AUX_SDA_1")
	)
	(segment
		(start 370.262912 -279.557226)
		(end 370.258086 -279.554432)
		(width 0.127)
		(layer "In6.Cu")
		(net "SMB_S3M_CPU0_PIROM_3V3AUX_SDA_1")
	)
	(segment
		(start 388.375144 -294.177212)
		(end 388.375144 -289.504882)
		(width 0.127)
		(layer "In6.Cu")
		(net "SMB_S3M_CPU0_PIROM_3V3AUX_SDA_1")
	)
	(segment
		(start 398.661382 -310.13019)
		(end 398.661382 -304.46345)
		(width 0.127)
		(layer "In6.Cu")
		(net "SMB_S3M_CPU0_PIROM_3V3AUX_SDA_1")
	)
	(segment
		(start 366.973612 -273.860006)
		(end 366.973866 -273.860006)
		(width 0.127)
		(layer "In6.Cu")
		(net "SMB_S3M_CPU0_PIROM_3V3AUX_SDA_1")
	)
	(segment
		(start 379.660912 -284.44063)
		(end 379.64745 -284.432756)
		(width 0.127)
		(layer "In6.Cu")
		(net "SMB_S3M_CPU0_PIROM_3V3AUX_SDA_1")
	)
	(segment
		(start 416.480498 -322.87083)
		(end 407.418794 -322.87083)
		(width 0.127)
		(layer "In6.Cu")
		(net "SMB_S3M_CPU0_PIROM_3V3AUX_SDA_1")
	)
	(segment
		(start 398.661382 -304.46345)
		(end 388.375144 -294.177212)
		(width 0.127)
		(layer "In6.Cu")
		(net "SMB_S3M_CPU0_PIROM_3V3AUX_SDA_1")
	)
	(segment
		(start 403.865334 -319.31737)
		(end 403.865334 -315.334142)
		(width 0.127)
		(layer "In6.Cu")
		(net "SMB_S3M_CPU0_PIROM_3V3AUX_SDA_1")
	)
	(segment
		(start 407.418794 -322.87083)
		(end 403.865334 -319.31737)
		(width 0.127)
		(layer "In6.Cu")
		(net "SMB_S3M_CPU0_PIROM_3V3AUX_SDA_1")
	)
	(segment
		(start 368.618516 -276.718268)
		(end 368.618516 -276.698964)
		(width 0.127)
		(layer "In6.Cu")
		(net "SMB_S3M_CPU0_PIROM_3V3AUX_SDA_1")
	)
	(segment
		(start 377.781312 -284.44063)
		(end 377.76785 -284.432756)
		(width 0.127)
		(layer "In6.Cu")
		(net "SMB_S3M_CPU0_PIROM_3V3AUX_SDA_1")
	)
	(segment
		(start 370.737638 -283.629608)
		(end 370.732812 -283.626814)
		(width 0.127)
		(layer "In6.Cu")
		(net "SMB_S3M_CPU0_PIROM_3V3AUX_SDA_1")
	)
	(segment
		(start 371.202966 -284.44063)
		(end 371.202712 -284.44063)
		(width 0.127)
		(layer "In6.Cu")
		(net "SMB_S3M_CPU0_PIROM_3V3AUX_SDA_1")
	)
	(segment
		(start 383.964688 -285.297626)
		(end 383.880614 -285.248858)
		(width 0.127)
		(layer "In6.Cu")
		(net "SMB_S3M_CPU0_PIROM_3V3AUX_SDA_1")
	)
	(segment
		(start 366.978438 -273.8628)
		(end 366.973612 -273.860006)
		(width 0.127)
		(layer "In6.Cu")
		(net "SMB_S3M_CPU0_PIROM_3V3AUX_SDA_1")
	)
	(segment
		(start 367.678716 -275.080984)
		(end 367.678716 -275.08073)
		(width 0.127)
		(layer "In6.Cu")
		(net "SMB_S3M_CPU0_PIROM_3V3AUX_SDA_1")
	)
	(segment
		(start 368.858038 -277.118318)
		(end 368.853212 -277.115524)
		(width 0.127)
		(layer "In6.Cu")
		(net "SMB_S3M_CPU0_PIROM_3V3AUX_SDA_1")
	)
	(segment
		(start 370.498116 -283.229558)
		(end 370.498116 -283.219906)
		(width 0.127)
		(layer "In6.Cu")
		(net "SMB_S3M_CPU0_PIROM_3V3AUX_SDA_1")
	)
	(segment
		(start 382.480312 -285.254446)
		(end 382.46685 -285.26232)
		(width 0.127)
		(layer "In6.Cu")
		(net "SMB_S3M_CPU0_PIROM_3V3AUX_SDA_1")
	)
	(segment
		(start 384.608324 -286.501586)
		(end 384.607816 -286.45485)
		(width 0.127)
		(layer "In6.Cu")
		(net "SMB_S3M_CPU0_PIROM_3V3AUX_SDA_1")
	)
	(segment
		(start 366.973866 -273.860006)
		(end 366.269016 -273.453098)
		(width 0.127)
		(layer "In6.Cu")
		(net "SMB_S3M_CPU0_PIROM_3V3AUX_SDA_1")
	)
	(segment
		(start 369.33378 -277.935944)
		(end 369.323112 -277.929594)
		(width 0.127)
		(layer "In6.Cu")
		(net "SMB_S3M_CPU0_PIROM_3V3AUX_SDA_1")
	)
	(segment
		(start 373.082566 -284.44063)
		(end 373.072914 -284.435042)
		(width 0.127)
		(layer "In6.Cu")
		(net "SMB_S3M_CPU0_PIROM_3V3AUX_SDA_1")
	)
	(segment
		(start 369.088162 -277.535894)
		(end 369.088162 -277.522432)
		(width 0.127)
		(layer "In6.Cu")
		(net "SMB_S3M_CPU0_PIROM_3V3AUX_SDA_1")
	)
	(segment
		(start 370.732812 -281.185112)
		(end 370.737638 -281.182318)
		(width 0.127)
		(layer "In6.Cu")
		(net "SMB_S3M_CPU0_PIROM_3V3AUX_SDA_1")
	)
	(segment
		(start 368.384328 -275.487638)
		(end 368.383566 -275.487892)
		(width 0.127)
		(layer "In6.Cu")
		(net "SMB_S3M_CPU0_PIROM_3V3AUX_SDA_1")
	)
	(segment
		(start 380.600966 -284.440884)
		(end 380.600712 -284.44063)
		(width 0.127)
		(layer "In6.Cu")
		(net "SMB_S3M_CPU0_PIROM_3V3AUX_SDA_1")
	)
	(segment
		(start 370.262912 -281.998928)
		(end 370.27358 -281.992578)
		(width 0.127)
		(layer "In6.Cu")
		(net "SMB_S3M_CPU0_PIROM_3V3AUX_SDA_1")
	)
	(segment
		(start 384.373628 -286.094424)
		(end 384.320542 -286.063944)
		(width 0.127)
		(layer "In6.Cu")
		(net "SMB_S3M_CPU0_PIROM_3V3AUX_SDA_1")
	)
	(segment
		(start 403.865334 -315.334142)
		(end 398.661382 -310.13019)
		(width 0.127)
		(layer "In6.Cu")
		(net "SMB_S3M_CPU0_PIROM_3V3AUX_SDA_1")
	)
	(segment
		(start 370.27358 -279.563576)
		(end 370.262912 -279.557226)
		(width 0.127)
		(layer "In6.Cu")
		(net "SMB_S3M_CPU0_PIROM_3V3AUX_SDA_1")
	)
	(arc
		(start 382.010666 -285.254446)
		(mid 381.775716 -285.191486)
		(end 381.540766 -285.254446)
		(width 0.127)
		(layer "In6.Cu")
		(net "SMB_S3M_CPU0_PIROM_3V3AUX_SDA_1")
	)
	(arc
		(start 370.027962 -279.150318)
		(mid 369.966399 -278.917795)
		(end 369.797838 -278.746204)
		(width 0.127)
		(layer "In6.Cu")
		(net "SMB_S3M_CPU0_PIROM_3V3AUX_SDA_1")
	)
	(arc
		(start 369.088162 -275.881338)
		(mid 369.021939 -275.653901)
		(end 368.853212 -275.487638)
		(width 0.127)
		(layer "In6.Cu")
		(net "SMB_S3M_CPU0_PIROM_3V3AUX_SDA_1")
	)
	(arc
		(start 371.672866 -284.44063)
		(mid 371.437916 -284.50359)
		(end 371.202966 -284.44063)
		(width 0.127)
		(layer "In6.Cu")
		(net "SMB_S3M_CPU0_PIROM_3V3AUX_SDA_1")
	)
	(arc
		(start 378.70765 -284.432756)
		(mid 378.478397 -284.377512)
		(end 378.251212 -284.44063)
		(width 0.127)
		(layer "In6.Cu")
		(net "SMB_S3M_CPU0_PIROM_3V3AUX_SDA_1")
	)
	(arc
		(start 383.420112 -285.254446)
		(mid 383.185162 -285.317406)
		(end 382.950212 -285.254446)
		(width 0.127)
		(layer "In6.Cu")
		(net "SMB_S3M_CPU0_PIROM_3V3AUX_SDA_1")
	)
	(arc
		(start 370.498116 -281.582368)
		(mid 370.563359 -281.352956)
		(end 370.732812 -281.185112)
		(width 0.127)
		(layer "In6.Cu")
		(net "SMB_S3M_CPU0_PIROM_3V3AUX_SDA_1")
	)
	(arc
		(start 382.950212 -285.254446)
		(mid 382.715262 -285.191486)
		(end 382.480312 -285.254446)
		(width 0.127)
		(layer "In6.Cu")
		(net "SMB_S3M_CPU0_PIROM_3V3AUX_SDA_1")
	)
	(arc
		(start 384.85572 -286.91713)
		(mid 384.688988 -286.768334)
		(end 384.608832 -286.559752)
		(width 0.127)
		(layer "In6.Cu")
		(net "SMB_S3M_CPU0_PIROM_3V3AUX_SDA_1")
	)
	(arc
		(start 384.607816 -286.45485)
		(mid 384.534022 -286.246486)
		(end 384.373628 -286.094424)
		(width 0.127)
		(layer "In6.Cu")
		(net "SMB_S3M_CPU0_PIROM_3V3AUX_SDA_1")
	)
	(arc
		(start 380.58725 -284.432756)
		(mid 380.357997 -284.377512)
		(end 380.130812 -284.44063)
		(width 0.127)
		(layer "In6.Cu")
		(net "SMB_S3M_CPU0_PIROM_3V3AUX_SDA_1")
	)
	(arc
		(start 377.76785 -284.432756)
		(mid 377.538597 -284.377512)
		(end 377.311412 -284.44063)
		(width 0.127)
		(layer "In6.Cu")
		(net "SMB_S3M_CPU0_PIROM_3V3AUX_SDA_1")
	)
	(arc
		(start 369.558316 -278.336502)
		(mid 369.498361 -278.106892)
		(end 369.33378 -277.935944)
		(width 0.127)
		(layer "In6.Cu")
		(net "SMB_S3M_CPU0_PIROM_3V3AUX_SDA_1")
	)
	(arc
		(start 385.345432 -286.940498)
		(mid 385.133816 -287.001939)
		(end 384.919474 -286.950912)
		(width 0.127)
		(layer "In6.Cu")
		(net "SMB_S3M_CPU0_PIROM_3V3AUX_SDA_1")
	)
	(arc
		(start 379.191012 -284.44063)
		(mid 378.956062 -284.50359)
		(end 378.721112 -284.44063)
		(width 0.127)
		(layer "In6.Cu")
		(net "SMB_S3M_CPU0_PIROM_3V3AUX_SDA_1")
	)
	(arc
		(start 371.197886 -284.437836)
		(mid 371.02933 -284.266242)
		(end 370.967762 -284.033722)
		(width 0.127)
		(layer "In6.Cu")
		(net "SMB_S3M_CPU0_PIROM_3V3AUX_SDA_1")
	)
	(arc
		(start 367.438686 -274.671028)
		(mid 367.27013 -274.499434)
		(end 367.208562 -274.266914)
		(width 0.127)
		(layer "In6.Cu")
		(net "SMB_S3M_CPU0_PIROM_3V3AUX_SDA_1")
	)
	(arc
		(start 383.880614 -285.248858)
		(mid 383.649629 -285.191375)
		(end 383.420112 -285.254446)
		(width 0.127)
		(layer "In6.Cu")
		(net "SMB_S3M_CPU0_PIROM_3V3AUX_SDA_1")
	)
	(arc
		(start 368.853212 -277.115524)
		(mid 368.683762 -276.947678)
		(end 368.618516 -276.718268)
		(width 0.127)
		(layer "In6.Cu")
		(net "SMB_S3M_CPU0_PIROM_3V3AUX_SDA_1")
	)
	(arc
		(start 376.371612 -284.44063)
		(mid 376.136662 -284.50359)
		(end 375.901712 -284.44063)
		(width 0.127)
		(layer "In6.Cu")
		(net "SMB_S3M_CPU0_PIROM_3V3AUX_SDA_1")
	)
	(arc
		(start 368.853212 -275.487638)
		(mid 368.61877 -275.42483)
		(end 368.384328 -275.487638)
		(width 0.127)
		(layer "In6.Cu")
		(net "SMB_S3M_CPU0_PIROM_3V3AUX_SDA_1")
	)
	(arc
		(start 370.967762 -284.033722)
		(mid 370.906199 -283.801199)
		(end 370.737638 -283.629608)
		(width 0.127)
		(layer "In6.Cu")
		(net "SMB_S3M_CPU0_PIROM_3V3AUX_SDA_1")
	)
	(arc
		(start 375.88825 -284.432756)
		(mid 375.658997 -284.377512)
		(end 375.431812 -284.44063)
		(width 0.127)
		(layer "In6.Cu")
		(net "SMB_S3M_CPU0_PIROM_3V3AUX_SDA_1")
	)
	(arc
		(start 374.94845 -284.432756)
		(mid 374.719197 -284.377512)
		(end 374.492012 -284.44063)
		(width 0.127)
		(layer "In6.Cu")
		(net "SMB_S3M_CPU0_PIROM_3V3AUX_SDA_1")
	)
	(arc
		(start 367.913412 -275.487638)
		(mid 367.741599 -275.315745)
		(end 367.678716 -275.080984)
		(width 0.127)
		(layer "In6.Cu")
		(net "SMB_S3M_CPU0_PIROM_3V3AUX_SDA_1")
	)
	(arc
		(start 367.208562 -274.266914)
		(mid 367.146999 -274.034391)
		(end 366.978438 -273.8628)
		(width 0.127)
		(layer "In6.Cu")
		(net "SMB_S3M_CPU0_PIROM_3V3AUX_SDA_1")
	)
	(arc
		(start 377.311412 -284.44063)
		(mid 377.076462 -284.50359)
		(end 376.841512 -284.44063)
		(width 0.127)
		(layer "In6.Cu")
		(net "SMB_S3M_CPU0_PIROM_3V3AUX_SDA_1")
	)
	(arc
		(start 378.251212 -284.44063)
		(mid 378.016262 -284.50359)
		(end 377.781312 -284.44063)
		(width 0.127)
		(layer "In6.Cu")
		(net "SMB_S3M_CPU0_PIROM_3V3AUX_SDA_1")
	)
	(arc
		(start 384.320542 -286.063944)
		(mid 384.179721 -285.890913)
		(end 384.132836 -285.672784)
		(width 0.127)
		(layer "In6.Cu")
		(net "SMB_S3M_CPU0_PIROM_3V3AUX_SDA_1")
	)
	(arc
		(start 372.12905 -284.432756)
		(mid 371.899797 -284.377512)
		(end 371.672612 -284.44063)
		(width 0.127)
		(layer "In6.Cu")
		(net "SMB_S3M_CPU0_PIROM_3V3AUX_SDA_1")
	)
	(arc
		(start 369.793012 -278.74341)
		(mid 369.624708 -278.57767)
		(end 369.558316 -278.35098)
		(width 0.127)
		(layer "In6.Cu")
		(net "SMB_S3M_CPU0_PIROM_3V3AUX_SDA_1")
	)
	(arc
		(start 381.070612 -285.254446)
		(mid 380.901162 -285.0866)
		(end 380.835916 -284.85719)
		(width 0.127)
		(layer "In6.Cu")
		(net "SMB_S3M_CPU0_PIROM_3V3AUX_SDA_1")
	)
	(arc
		(start 370.498116 -279.964134)
		(mid 370.438161 -279.734524)
		(end 370.27358 -279.563576)
		(width 0.127)
		(layer "In6.Cu")
		(net "SMB_S3M_CPU0_PIROM_3V3AUX_SDA_1")
	)
	(arc
		(start 373.072914 -284.435042)
		(mid 372.841929 -284.377559)
		(end 372.612412 -284.44063)
		(width 0.127)
		(layer "In6.Cu")
		(net "SMB_S3M_CPU0_PIROM_3V3AUX_SDA_1")
	)
	(arc
		(start 368.36985 -275.495512)
		(mid 368.140597 -275.550756)
		(end 367.913412 -275.487638)
		(width 0.127)
		(layer "In6.Cu")
		(net "SMB_S3M_CPU0_PIROM_3V3AUX_SDA_1")
	)
	(arc
		(start 367.678716 -275.08073)
		(mid 367.618761 -274.85112)
		(end 367.45418 -274.680172)
		(width 0.127)
		(layer "In6.Cu")
		(net "SMB_S3M_CPU0_PIROM_3V3AUX_SDA_1")
	)
	(arc
		(start 369.088162 -277.522432)
		(mid 369.026599 -277.289909)
		(end 368.858038 -277.118318)
		(width 0.127)
		(layer "In6.Cu")
		(net "SMB_S3M_CPU0_PIROM_3V3AUX_SDA_1")
	)
	(arc
		(start 370.498116 -283.219906)
		(mid 370.439178 -282.992054)
		(end 370.277136 -282.82138)
		(width 0.127)
		(layer "In6.Cu")
		(net "SMB_S3M_CPU0_PIROM_3V3AUX_SDA_1")
	)
	(arc
		(start 385.654296 -286.868616)
		(mid 385.494205 -286.880233)
		(end 385.345432 -286.940498)
		(width 0.127)
		(layer "In6.Cu")
		(net "SMB_S3M_CPU0_PIROM_3V3AUX_SDA_1")
	)
	(arc
		(start 370.262912 -282.812998)
		(mid 370.094189 -282.646732)
		(end 370.027962 -282.419298)
		(width 0.127)
		(layer "In6.Cu")
		(net "SMB_S3M_CPU0_PIROM_3V3AUX_SDA_1")
	)
	(arc
		(start 370.027962 -282.405836)
		(mid 370.089525 -282.173313)
		(end 370.258086 -282.001722)
		(width 0.127)
		(layer "In6.Cu")
		(net "SMB_S3M_CPU0_PIROM_3V3AUX_SDA_1")
	)
	(arc
		(start 370.732812 -283.626814)
		(mid 370.563362 -283.458968)
		(end 370.498116 -283.229558)
		(width 0.127)
		(layer "In6.Cu")
		(net "SMB_S3M_CPU0_PIROM_3V3AUX_SDA_1")
	)
	(arc
		(start 368.853212 -276.301454)
		(mid 369.02521 -276.129614)
		(end 369.088162 -275.8948)
		(width 0.127)
		(layer "In6.Cu")
		(net "SMB_S3M_CPU0_PIROM_3V3AUX_SDA_1")
	)
	(arc
		(start 370.732812 -280.371042)
		(mid 370.563362 -280.203196)
		(end 370.498116 -279.973786)
		(width 0.127)
		(layer "In6.Cu")
		(net "SMB_S3M_CPU0_PIROM_3V3AUX_SDA_1")
	)
	(arc
		(start 375.431812 -284.44063)
		(mid 375.196862 -284.50359)
		(end 374.961912 -284.44063)
		(width 0.127)
		(layer "In6.Cu")
		(net "SMB_S3M_CPU0_PIROM_3V3AUX_SDA_1")
	)
	(arc
		(start 381.540512 -285.254446)
		(mid 381.305562 -285.317406)
		(end 381.070612 -285.254446)
		(width 0.127)
		(layer "In6.Cu")
		(net "SMB_S3M_CPU0_PIROM_3V3AUX_SDA_1")
	)
	(arc
		(start 369.323112 -277.929594)
		(mid 369.154389 -277.763328)
		(end 369.088162 -277.535894)
		(width 0.127)
		(layer "In6.Cu")
		(net "SMB_S3M_CPU0_PIROM_3V3AUX_SDA_1")
	)
	(arc
		(start 380.835916 -284.847538)
		(mid 380.772956 -284.612715)
		(end 380.600966 -284.440884)
		(width 0.127)
		(layer "In6.Cu")
		(net "SMB_S3M_CPU0_PIROM_3V3AUX_SDA_1")
	)
	(arc
		(start 380.130812 -284.44063)
		(mid 379.895862 -284.50359)
		(end 379.660912 -284.44063)
		(width 0.127)
		(layer "In6.Cu")
		(net "SMB_S3M_CPU0_PIROM_3V3AUX_SDA_1")
	)
	(arc
		(start 374.492012 -284.44063)
		(mid 374.257062 -284.50359)
		(end 374.022112 -284.44063)
		(width 0.127)
		(layer "In6.Cu")
		(net "SMB_S3M_CPU0_PIROM_3V3AUX_SDA_1")
	)
	(arc
		(start 382.46685 -285.26232)
		(mid 382.237597 -285.317564)
		(end 382.010412 -285.254446)
		(width 0.127)
		(layer "In6.Cu")
		(net "SMB_S3M_CPU0_PIROM_3V3AUX_SDA_1")
	)
	(arc
		(start 373.552466 -284.44063)
		(mid 373.317516 -284.50359)
		(end 373.082566 -284.44063)
		(width 0.127)
		(layer "In6.Cu")
		(net "SMB_S3M_CPU0_PIROM_3V3AUX_SDA_1")
	)
	(arc
		(start 379.64745 -284.432756)
		(mid 379.418197 -284.377512)
		(end 379.191012 -284.44063)
		(width 0.127)
		(layer "In6.Cu")
		(net "SMB_S3M_CPU0_PIROM_3V3AUX_SDA_1")
	)
	(arc
		(start 384.132836 -285.672784)
		(mid 384.091169 -285.466204)
		(end 383.964688 -285.297626)
		(width 0.127)
		(layer "In6.Cu")
		(net "SMB_S3M_CPU0_PIROM_3V3AUX_SDA_1")
	)
	(arc
		(start 370.258086 -279.554432)
		(mid 370.08953 -279.382838)
		(end 370.027962 -279.150318)
		(width 0.127)
		(layer "In6.Cu")
		(net "SMB_S3M_CPU0_PIROM_3V3AUX_SDA_1")
	)
	(arc
		(start 372.612412 -284.44063)
		(mid 372.377462 -284.50359)
		(end 372.142512 -284.44063)
		(width 0.127)
		(layer "In6.Cu")
		(net "SMB_S3M_CPU0_PIROM_3V3AUX_SDA_1")
	)
	(arc
		(start 370.967762 -280.764742)
		(mid 370.901539 -280.537305)
		(end 370.732812 -280.371042)
		(width 0.127)
		(layer "In6.Cu")
		(net "SMB_S3M_CPU0_PIROM_3V3AUX_SDA_1")
	)
	(arc
		(start 368.618516 -276.698964)
		(mid 368.683759 -276.469552)
		(end 368.853212 -276.301708)
		(width 0.127)
		(layer "In6.Cu")
		(net "SMB_S3M_CPU0_PIROM_3V3AUX_SDA_1")
	)
	(arc
		(start 374.01246 -284.435042)
		(mid 373.781729 -284.377681)
		(end 373.552466 -284.44063)
		(width 0.127)
		(layer "In6.Cu")
		(net "SMB_S3M_CPU0_PIROM_3V3AUX_SDA_1")
	)
	(arc
		(start 370.27358 -281.992578)
		(mid 370.438122 -281.821608)
		(end 370.498116 -281.59202)
		(width 0.127)
		(layer "In6.Cu")
		(net "SMB_S3M_CPU0_PIROM_3V3AUX_SDA_1")
	)
	(arc
		(start 370.737638 -281.182318)
		(mid 370.906194 -281.010724)
		(end 370.967762 -280.778204)
		(width 0.127)
		(layer "In6.Cu")
		(net "SMB_S3M_CPU0_PIROM_3V3AUX_SDA_1")
	)
	(arc
		(start 376.82805 -284.432756)
		(mid 376.598797 -284.377512)
		(end 376.371612 -284.44063)
		(width 0.127)
		(layer "In6.Cu")
		(net "SMB_S3M_CPU0_PIROM_3V3AUX_SDA_1")
	)
	(segment
		(start 430.98466 -376.43435)
		(end 426.211238 -376.43435)
		(width 0.127)
		(layer "In11.Cu")
		(net "SMB_S3M_CPU0_PIROM_3V3AUX_SDA_1")
	)
	(segment
		(start 280.91003 -385.567428)
		(end 280.79192 -385.567428)
		(width 0.127)
		(layer "In11.Cu")
		(net "SMB_S3M_CPU0_PIROM_3V3AUX_SDA_1")
	)
	(segment
		(start 423.94124 -378.704348)
		(end 423.04462 -378.704348)
		(width 0.127)
		(layer "In11.Cu")
		(net "SMB_S3M_CPU0_PIROM_3V3AUX_SDA_1")
	)
	(segment
		(start 294.311578 -383.504948)
		(end 289.528758 -388.287768)
		(width 0.127)
		(layer "In11.Cu")
		(net "SMB_S3M_CPU0_PIROM_3V3AUX_SDA_1")
	)
	(segment
		(start 416.766248 -323.482716)
		(end 420.09568 -326.812148)
		(width 0.127)
		(layer "In11.Cu")
		(net "SMB_S3M_CPU0_PIROM_3V3AUX_SDA_1")
	)
	(segment
		(start 435.84368 -343.320878)
		(end 435.84368 -371.57533)
		(width 0.127)
		(layer "In11.Cu")
		(net "SMB_S3M_CPU0_PIROM_3V3AUX_SDA_1")
	)
	(segment
		(start 435.84368 -371.57533)
		(end 430.98466 -376.43435)
		(width 0.127)
		(layer "In11.Cu")
		(net "SMB_S3M_CPU0_PIROM_3V3AUX_SDA_1")
	)
	(segment
		(start 423.04462 -378.704348)
		(end 418.24402 -383.504948)
		(width 0.127)
		(layer "In11.Cu")
		(net "SMB_S3M_CPU0_PIROM_3V3AUX_SDA_1")
	)
	(segment
		(start 418.24402 -383.504948)
		(end 294.311578 -383.504948)
		(width 0.127)
		(layer "In11.Cu")
		(net "SMB_S3M_CPU0_PIROM_3V3AUX_SDA_1")
	)
	(segment
		(start 416.766248 -322.58508)
		(end 416.766248 -323.482716)
		(width 0.127)
		(layer "In11.Cu")
		(net "SMB_S3M_CPU0_PIROM_3V3AUX_SDA_1")
	)
	(segment
		(start 284.15488 -387.49224)
		(end 282.834842 -387.49224)
		(width 0.127)
		(layer "In11.Cu")
		(net "SMB_S3M_CPU0_PIROM_3V3AUX_SDA_1")
	)
	(segment
		(start 426.211238 -376.43435)
		(end 423.94124 -378.704348)
		(width 0.127)
		(layer "In11.Cu")
		(net "SMB_S3M_CPU0_PIROM_3V3AUX_SDA_1")
	)
	(segment
		(start 420.09568 -333.313278)
		(end 427.33595 -340.553548)
		(width 0.127)
		(layer "In11.Cu")
		(net "SMB_S3M_CPU0_PIROM_3V3AUX_SDA_1")
	)
	(segment
		(start 284.950408 -388.287768)
		(end 284.15488 -387.49224)
		(width 0.127)
		(layer "In11.Cu")
		(net "SMB_S3M_CPU0_PIROM_3V3AUX_SDA_1")
	)
	(segment
		(start 289.528758 -388.287768)
		(end 284.950408 -388.287768)
		(width 0.127)
		(layer "In11.Cu")
		(net "SMB_S3M_CPU0_PIROM_3V3AUX_SDA_1")
	)
	(segment
		(start 433.07635 -340.553548)
		(end 435.84368 -343.320878)
		(width 0.127)
		(layer "In11.Cu")
		(net "SMB_S3M_CPU0_PIROM_3V3AUX_SDA_1")
	)
	(segment
		(start 282.834842 -387.49224)
		(end 280.91003 -385.567428)
		(width 0.127)
		(layer "In11.Cu")
		(net "SMB_S3M_CPU0_PIROM_3V3AUX_SDA_1")
	)
	(segment
		(start 420.09568 -326.812148)
		(end 420.09568 -333.313278)
		(width 0.127)
		(layer "In11.Cu")
		(net "SMB_S3M_CPU0_PIROM_3V3AUX_SDA_1")
	)
	(segment
		(start 427.33595 -340.553548)
		(end 433.07635 -340.553548)
		(width 0.127)
		(layer "In11.Cu")
		(net "SMB_S3M_CPU0_PIROM_3V3AUX_SDA_1")
	)
	(segment
		(start 183.26735 -330.215748)
		(end 181.37378 -328.322178)
		(width 0.127)
		(layer "In15.Cu")
		(net "SMB_S3M_CPU0_PIROM_3V3AUX_SDA_1")
	)
	(segment
		(start 234.704128 -368.241326)
		(end 211.79155 -345.328748)
		(width 0.127)
		(layer "In15.Cu")
		(net "SMB_S3M_CPU0_PIROM_3V3AUX_SDA_1")
	)
	(segment
		(start 181.37378 -327.554336)
		(end 181.53888 -327.389236)
		(width 0.127)
		(layer "In15.Cu")
		(net "SMB_S3M_CPU0_PIROM_3V3AUX_SDA_1")
	)
	(segment
		(start 189.87135 -330.215748)
		(end 183.26735 -330.215748)
		(width 0.127)
		(layer "In15.Cu")
		(net "SMB_S3M_CPU0_PIROM_3V3AUX_SDA_1")
	)
	(segment
		(start 280.79192 -385.567428)
		(end 276.95271 -385.567428)
		(width 0.127)
		(layer "In15.Cu")
		(net "SMB_S3M_CPU0_PIROM_3V3AUX_SDA_1")
	)
	(segment
		(start 181.53888 -327.389236)
		(end 181.53888 -326.685148)
		(width 0.127)
		(layer "In15.Cu")
		(net "SMB_S3M_CPU0_PIROM_3V3AUX_SDA_1")
	)
	(segment
		(start 181.37378 -328.322178)
		(end 181.37378 -327.554336)
		(width 0.127)
		(layer "In15.Cu")
		(net "SMB_S3M_CPU0_PIROM_3V3AUX_SDA_1")
	)
	(segment
		(start 204.98435 -345.328748)
		(end 189.87135 -330.215748)
		(width 0.127)
		(layer "In15.Cu")
		(net "SMB_S3M_CPU0_PIROM_3V3AUX_SDA_1")
	)
	(segment
		(start 276.95271 -385.567428)
		(end 259.626608 -368.241326)
		(width 0.127)
		(layer "In15.Cu")
		(net "SMB_S3M_CPU0_PIROM_3V3AUX_SDA_1")
	)
	(segment
		(start 211.79155 -345.328748)
		(end 204.98435 -345.328748)
		(width 0.127)
		(layer "In15.Cu")
		(net "SMB_S3M_CPU0_PIROM_3V3AUX_SDA_1")
	)
	(segment
		(start 259.626608 -368.241326)
		(end 234.704128 -368.241326)
		(width 0.127)
		(layer "In15.Cu")
		(net "SMB_S3M_CPU0_PIROM_3V3AUX_SDA_1")
	)
	(segment
		(start 368.618262 -272.103596)
		(end 368.618262 -272.639282)
		(width 0.12954)
		(layer "F.Cu")
		(net "SMB_S3M_CPU0_PIROM_3V3AUX_SCL_1")
	)
	(segment
		(start 368.618516 -272.103342)
		(end 368.618262 -272.103596)
		(width 0.12954)
		(layer "F.Cu")
		(net "SMB_S3M_CPU0_PIROM_3V3AUX_SCL_1")
	)
	(via
		(at 368.618262 -272.639282)
		(size 0.4572)
		(drill 0.2032)
		(layers "F.Cu" "B.Cu")
		(net "SMB_S3M_CPU0_PIROM_3V3AUX_SCL_1")
	)
	(via
		(at 180.77688 -326.685148)
		(size 0.508)
		(drill 0.254)
		(layers "F.Cu" "B.Cu")
		(net "SMB_S3M_CPU0_PIROM_3V3AUX_SCL_1")
	)
	(via
		(at 282.12415 -385.583684)
		(size 0.508)
		(drill 0.254)
		(layers "F.Cu" "B.Cu")
		(net "SMB_S3M_CPU0_PIROM_3V3AUX_SCL_1")
	)
	(via
		(at 416.122358 -322.34251)
		(size 0.508)
		(drill 0.254)
		(layers "F.Cu" "B.Cu")
		(net "SMB_S3M_CPU0_PIROM_3V3AUX_SCL_1")
	)
	(segment
		(start 181.30393 -329.189588)
		(end 181.01437 -328.900028)
		(width 0.12954)
		(layer "B.Cu")
		(net "SMB_S3M_CPU0_PIROM_3V3AUX_SCL_1")
	)
	(segment
		(start 181.30393 -329.479148)
		(end 181.30393 -329.189588)
		(width 0.12954)
		(layer "B.Cu")
		(net "SMB_S3M_CPU0_PIROM_3V3AUX_SCL_1")
	)
	(segment
		(start 181.01437 -328.900028)
		(end 181.01437 -326.922638)
		(width 0.12954)
		(layer "B.Cu")
		(net "SMB_S3M_CPU0_PIROM_3V3AUX_SCL_1")
	)
	(segment
		(start 181.01437 -326.922638)
		(end 180.77688 -326.685148)
		(width 0.12954)
		(layer "B.Cu")
		(net "SMB_S3M_CPU0_PIROM_3V3AUX_SCL_1")
	)
	(segment
		(start 368.853212 -273.860006)
		(end 368.618516 -273.46275)
		(width 0.127)
		(layer "In6.Cu")
		(net "SMB_S3M_CPU0_PIROM_3V3AUX_SCL_1")
	)
	(segment
		(start 407.575258 -322.34251)
		(end 404.349458 -319.11671)
		(width 0.127)
		(layer "In6.Cu")
		(net "SMB_S3M_CPU0_PIROM_3V3AUX_SCL_1")
	)
	(segment
		(start 370.267992 -276.304502)
		(end 370.25834 -276.298914)
		(width 0.127)
		(layer "In6.Cu")
		(net "SMB_S3M_CPU0_PIROM_3V3AUX_SCL_1")
	)
	(segment
		(start 369.558316 -275.090382)
		(end 369.558316 -275.08073)
		(width 0.127)
		(layer "In6.Cu")
		(net "SMB_S3M_CPU0_PIROM_3V3AUX_SCL_1")
	)
	(segment
		(start 388.859268 -288.409126)
		(end 386.6388 -286.188658)
		(width 0.127)
		(layer "In6.Cu")
		(net "SMB_S3M_CPU0_PIROM_3V3AUX_SCL_1")
	)
	(segment
		(start 370.73332 -278.743918)
		(end 370.732812 -278.74341)
		(width 0.127)
		(layer "In6.Cu")
		(net "SMB_S3M_CPU0_PIROM_3V3AUX_SCL_1")
	)
	(segment
		(start 411.190186 -321.92595)
		(end 411.070806 -321.80657)
		(width 0.127)
		(layer "In6.Cu")
		(net "SMB_S3M_CPU0_PIROM_3V3AUX_SCL_1")
	)
	(segment
		(start 385.314698 -286.091122)
		(end 385.314698 -286.091376)
		(width 0.127)
		(layer "In6.Cu")
		(net "SMB_S3M_CPU0_PIROM_3V3AUX_SCL_1")
	)
	(segment
		(start 409.879546 -321.83959)
		(end 409.760166 -321.72021)
		(width 0.127)
		(layer "In6.Cu")
		(net "SMB_S3M_CPU0_PIROM_3V3AUX_SCL_1")
	)
	(segment
		(start 373.552212 -282.812998)
		(end 373.552466 -282.812998)
		(width 0.127)
		(layer "In6.Cu")
		(net "SMB_S3M_CPU0_PIROM_3V3AUX_SCL_1")
	)
	(segment
		(start 384.602482 -284.858714)
		(end 384.602482 -284.858968)
		(width 0.127)
		(layer "In6.Cu")
		(net "SMB_S3M_CPU0_PIROM_3V3AUX_SCL_1")
	)
	(segment
		(start 371.907562 -280.778204)
		(end 371.907562 -280.77795)
		(width 0.127)
		(layer "In6.Cu")
		(net "SMB_S3M_CPU0_PIROM_3V3AUX_SCL_1")
	)
	(segment
		(start 381.540512 -284.44063)
		(end 381.535686 -284.437836)
		(width 0.127)
		(layer "In6.Cu")
		(net "SMB_S3M_CPU0_PIROM_3V3AUX_SCL_1")
	)
	(segment
		(start 373.082566 -282.812998)
		(end 373.082312 -282.812998)
		(width 0.127)
		(layer "In6.Cu")
		(net "SMB_S3M_CPU0_PIROM_3V3AUX_SCL_1")
	)
	(segment
		(start 385.079748 -285.684468)
		(end 385.079748 -285.669736)
		(width 0.127)
		(layer "In6.Cu")
		(net "SMB_S3M_CPU0_PIROM_3V3AUX_SCL_1")
	)
	(segment
		(start 374.027192 -282.815792)
		(end 374.012714 -282.80741)
		(width 0.127)
		(layer "In6.Cu")
		(net "SMB_S3M_CPU0_PIROM_3V3AUX_SCL_1")
	)
	(segment
		(start 410.534866 -321.92595)
		(end 410.534866 -322.22313)
		(width 0.127)
		(layer "In6.Cu")
		(net "SMB_S3M_CPU0_PIROM_3V3AUX_SCL_1")
	)
	(segment
		(start 381.540766 -284.44063)
		(end 381.540512 -284.44063)
		(width 0.127)
		(layer "In6.Cu")
		(net "SMB_S3M_CPU0_PIROM_3V3AUX_SCL_1")
	)
	(segment
		(start 404.349458 -315.133482)
		(end 399.145506 -309.92953)
		(width 0.127)
		(layer "In6.Cu")
		(net "SMB_S3M_CPU0_PIROM_3V3AUX_SCL_1")
	)
	(segment
		(start 386.292852 -286.122618)
		(end 386.194046 -286.064706)
		(width 0.127)
		(layer "In6.Cu")
		(net "SMB_S3M_CPU0_PIROM_3V3AUX_SCL_1")
	)
	(segment
		(start 368.867436 -273.868388)
		(end 368.853212 -273.860006)
		(width 0.127)
		(layer "In6.Cu")
		(net "SMB_S3M_CPU0_PIROM_3V3AUX_SCL_1")
	)
	(segment
		(start 376.841512 -283.626814)
		(end 376.82805 -283.634688)
		(width 0.127)
		(layer "In6.Cu")
		(net "SMB_S3M_CPU0_PIROM_3V3AUX_SCL_1")
	)
	(segment
		(start 399.145506 -309.92953)
		(end 399.145506 -304.26279)
		(width 0.127)
		(layer "In6.Cu")
		(net "SMB_S3M_CPU0_PIROM_3V3AUX_SCL_1")
	)
	(segment
		(start 388.859268 -293.976552)
		(end 388.859268 -288.409126)
		(width 0.127)
		(layer "In6.Cu")
		(net "SMB_S3M_CPU0_PIROM_3V3AUX_SCL_1")
	)
	(segment
		(start 368.618516 -273.46275)
		(end 368.618516 -273.453098)
		(width 0.127)
		(layer "In6.Cu")
		(net "SMB_S3M_CPU0_PIROM_3V3AUX_SCL_1")
	)
	(segment
		(start 404.349458 -319.11671)
		(end 404.349458 -315.133482)
		(width 0.127)
		(layer "In6.Cu")
		(net "SMB_S3M_CPU0_PIROM_3V3AUX_SCL_1")
	)
	(segment
		(start 370.498116 -278.346154)
		(end 370.498116 -278.336248)
		(width 0.127)
		(layer "In6.Cu")
		(net "SMB_S3M_CPU0_PIROM_3V3AUX_SCL_1")
	)
	(segment
		(start 369.79987 -275.491702)
		(end 369.793012 -275.487638)
		(width 0.127)
		(layer "In6.Cu")
		(net "SMB_S3M_CPU0_PIROM_3V3AUX_SCL_1")
	)
	(segment
		(start 409.998926 -322.34251)
		(end 409.879546 -322.22313)
		(width 0.127)
		(layer "In6.Cu")
		(net "SMB_S3M_CPU0_PIROM_3V3AUX_SCL_1")
	)
	(segment
		(start 409.104846 -322.34251)
		(end 407.575258 -322.34251)
		(width 0.127)
		(layer "In6.Cu")
		(net "SMB_S3M_CPU0_PIROM_3V3AUX_SCL_1")
	)
	(segment
		(start 409.224226 -321.83959)
		(end 409.224226 -322.22313)
		(width 0.127)
		(layer "In6.Cu")
		(net "SMB_S3M_CPU0_PIROM_3V3AUX_SCL_1")
	)
	(segment
		(start 411.309566 -322.34251)
		(end 411.190186 -322.22313)
		(width 0.127)
		(layer "In6.Cu")
		(net "SMB_S3M_CPU0_PIROM_3V3AUX_SCL_1")
	)
	(segment
		(start 386.6388 -286.188658)
		(end 386.536184 -286.188658)
		(width 0.127)
		(layer "In6.Cu")
		(net "SMB_S3M_CPU0_PIROM_3V3AUX_SCL_1")
	)
	(segment
		(start 381.070612 -283.627068)
		(end 381.070612 -283.626814)
		(width 0.127)
		(layer "In6.Cu")
		(net "SMB_S3M_CPU0_PIROM_3V3AUX_SCL_1")
	)
	(segment
		(start 411.190186 -322.22313)
		(end 411.190186 -321.92595)
		(width 0.127)
		(layer "In6.Cu")
		(net "SMB_S3M_CPU0_PIROM_3V3AUX_SCL_1")
	)
	(segment
		(start 409.343606 -321.72021)
		(end 409.224226 -321.83959)
		(width 0.127)
		(layer "In6.Cu")
		(net "SMB_S3M_CPU0_PIROM_3V3AUX_SCL_1")
	)
	(segment
		(start 409.879546 -322.22313)
		(end 409.879546 -321.83959)
		(width 0.127)
		(layer "In6.Cu")
		(net "SMB_S3M_CPU0_PIROM_3V3AUX_SCL_1")
	)
	(segment
		(start 414.386014 -322.34251)
		(end 414.175194 -322.13169)
		(width 0.127)
		(layer "In6.Cu")
		(net "SMB_S3M_CPU0_PIROM_3V3AUX_SCL_1")
	)
	(segment
		(start 416.122358 -322.34251)
		(end 414.386014 -322.34251)
		(width 0.127)
		(layer "In6.Cu")
		(net "SMB_S3M_CPU0_PIROM_3V3AUX_SCL_1")
	)
	(segment
		(start 370.737638 -277.118318)
		(end 370.732812 -277.115524)
		(width 0.127)
		(layer "In6.Cu")
		(net "SMB_S3M_CPU0_PIROM_3V3AUX_SCL_1")
	)
	(segment
		(start 409.224226 -322.22313)
		(end 409.104846 -322.34251)
		(width 0.127)
		(layer "In6.Cu")
		(net "SMB_S3M_CPU0_PIROM_3V3AUX_SCL_1")
	)
	(segment
		(start 399.145506 -304.26279)
		(end 388.859268 -293.976552)
		(width 0.127)
		(layer "In6.Cu")
		(net "SMB_S3M_CPU0_PIROM_3V3AUX_SCL_1")
	)
	(segment
		(start 382.480312 -284.44063)
		(end 382.46685 -284.432756)
		(width 0.127)
		(layer "In6.Cu")
		(net "SMB_S3M_CPU0_PIROM_3V3AUX_SCL_1")
	)
	(segment
		(start 372.377716 -281.601672)
		(end 372.377716 -281.59202)
		(width 0.127)
		(layer "In6.Cu")
		(net "SMB_S3M_CPU0_PIROM_3V3AUX_SCL_1")
	)
	(segment
		(start 369.328192 -274.676616)
		(end 369.31854 -274.671028)
		(width 0.127)
		(layer "In6.Cu")
		(net "SMB_S3M_CPU0_PIROM_3V3AUX_SCL_1")
	)
	(segment
		(start 372.847362 -282.419298)
		(end 372.847362 -282.405836)
		(width 0.127)
		(layer "In6.Cu")
		(net "SMB_S3M_CPU0_PIROM_3V3AUX_SCL_1")
	)
	(segment
		(start 370.498116 -276.718268)
		(end 370.498116 -276.708616)
		(width 0.127)
		(layer "In6.Cu")
		(net "SMB_S3M_CPU0_PIROM_3V3AUX_SCL_1")
	)
	(segment
		(start 384.845052 -285.277306)
		(end 384.772154 -285.235142)
		(width 0.127)
		(layer "In6.Cu")
		(net "SMB_S3M_CPU0_PIROM_3V3AUX_SCL_1")
	)
	(segment
		(start 372.15318 -281.191462)
		(end 372.142512 -281.185112)
		(width 0.127)
		(layer "In6.Cu")
		(net "SMB_S3M_CPU0_PIROM_3V3AUX_SCL_1")
	)
	(segment
		(start 372.617238 -282.001722)
		(end 372.612412 -281.998928)
		(width 0.127)
		(layer "In6.Cu")
		(net "SMB_S3M_CPU0_PIROM_3V3AUX_SCL_1")
	)
	(segment
		(start 370.967762 -277.535894)
		(end 370.967762 -277.522432)
		(width 0.127)
		(layer "In6.Cu")
		(net "SMB_S3M_CPU0_PIROM_3V3AUX_SCL_1")
	)
	(segment
		(start 410.654246 -321.80657)
		(end 410.534866 -321.92595)
		(width 0.127)
		(layer "In6.Cu")
		(net "SMB_S3M_CPU0_PIROM_3V3AUX_SCL_1")
	)
	(segment
		(start 379.660912 -283.626814)
		(end 379.64745 -283.634688)
		(width 0.127)
		(layer "In6.Cu")
		(net "SMB_S3M_CPU0_PIROM_3V3AUX_SCL_1")
	)
	(segment
		(start 371.207792 -279.56002)
		(end 371.19814 -279.554432)
		(width 0.127)
		(layer "In6.Cu")
		(net "SMB_S3M_CPU0_PIROM_3V3AUX_SCL_1")
	)
	(segment
		(start 375.901712 -283.626814)
		(end 375.88825 -283.634688)
		(width 0.127)
		(layer "In6.Cu")
		(net "SMB_S3M_CPU0_PIROM_3V3AUX_SCL_1")
	)
	(segment
		(start 371.437916 -279.978612)
		(end 371.437916 -279.964134)
		(width 0.127)
		(layer "In6.Cu")
		(net "SMB_S3M_CPU0_PIROM_3V3AUX_SCL_1")
	)
	(segment
		(start 372.142512 -281.185112)
		(end 372.137686 -281.182318)
		(width 0.127)
		(layer "In6.Cu")
		(net "SMB_S3M_CPU0_PIROM_3V3AUX_SCL_1")
	)
	(segment
		(start 410.415486 -322.34251)
		(end 409.998926 -322.34251)
		(width 0.127)
		(layer "In6.Cu")
		(net "SMB_S3M_CPU0_PIROM_3V3AUX_SCL_1")
	)
	(segment
		(start 410.534866 -322.22313)
		(end 410.415486 -322.34251)
		(width 0.127)
		(layer "In6.Cu")
		(net "SMB_S3M_CPU0_PIROM_3V3AUX_SCL_1")
	)
	(segment
		(start 368.618516 -273.453098)
		(end 368.618262 -272.639282)
		(width 0.127)
		(layer "In6.Cu")
		(net "SMB_S3M_CPU0_PIROM_3V3AUX_SCL_1")
	)
	(segment
		(start 384.370834 -284.447234)
		(end 384.359912 -284.44063)
		(width 0.127)
		(layer "In6.Cu")
		(net "SMB_S3M_CPU0_PIROM_3V3AUX_SCL_1")
	)
	(segment
		(start 385.448302 -286.168338)
		(end 385.314698 -286.091122)
		(width 0.127)
		(layer "In6.Cu")
		(net "SMB_S3M_CPU0_PIROM_3V3AUX_SCL_1")
	)
	(segment
		(start 382.010412 -284.44063)
		(end 382.010666 -284.44063)
		(width 0.127)
		(layer "In6.Cu")
		(net "SMB_S3M_CPU0_PIROM_3V3AUX_SCL_1")
	)
	(segment
		(start 409.760166 -321.72021)
		(end 409.343606 -321.72021)
		(width 0.127)
		(layer "In6.Cu")
		(net "SMB_S3M_CPU0_PIROM_3V3AUX_SCL_1")
	)
	(segment
		(start 411.070806 -321.80657)
		(end 410.654246 -321.80657)
		(width 0.127)
		(layer "In6.Cu")
		(net "SMB_S3M_CPU0_PIROM_3V3AUX_SCL_1")
	)
	(segment
		(start 413.491934 -322.34251)
		(end 411.309566 -322.34251)
		(width 0.127)
		(layer "In6.Cu")
		(net "SMB_S3M_CPU0_PIROM_3V3AUX_SCL_1")
	)
	(segment
		(start 374.257316 -283.234384)
		(end 374.257316 -283.219906)
		(width 0.127)
		(layer "In6.Cu")
		(net "SMB_S3M_CPU0_PIROM_3V3AUX_SCL_1")
	)
	(segment
		(start 414.175194 -322.13169)
		(end 413.702754 -322.13169)
		(width 0.127)
		(layer "In6.Cu")
		(net "SMB_S3M_CPU0_PIROM_3V3AUX_SCL_1")
	)
	(segment
		(start 413.702754 -322.13169)
		(end 413.491934 -322.34251)
		(width 0.127)
		(layer "In6.Cu")
		(net "SMB_S3M_CPU0_PIROM_3V3AUX_SCL_1")
	)
	(arc
		(start 383.420112 -284.44063)
		(mid 383.185162 -284.37767)
		(end 382.950212 -284.44063)
		(width 0.127)
		(layer "In6.Cu")
		(net "SMB_S3M_CPU0_PIROM_3V3AUX_SCL_1")
	)
	(arc
		(start 371.437916 -279.964134)
		(mid 371.376353 -279.731611)
		(end 371.207792 -279.56002)
		(width 0.127)
		(layer "In6.Cu")
		(net "SMB_S3M_CPU0_PIROM_3V3AUX_SCL_1")
	)
	(arc
		(start 384.772154 -285.235142)
		(mid 384.644553 -285.066214)
		(end 384.602482 -284.858714)
		(width 0.127)
		(layer "In6.Cu")
		(net "SMB_S3M_CPU0_PIROM_3V3AUX_SCL_1")
	)
	(arc
		(start 370.732812 -278.74341)
		(mid 370.563362 -278.575564)
		(end 370.498116 -278.346154)
		(width 0.127)
		(layer "In6.Cu")
		(net "SMB_S3M_CPU0_PIROM_3V3AUX_SCL_1")
	)
	(arc
		(start 370.498116 -278.336248)
		(mid 370.561 -278.101488)
		(end 370.732812 -277.929594)
		(width 0.127)
		(layer "In6.Cu")
		(net "SMB_S3M_CPU0_PIROM_3V3AUX_SCL_1")
	)
	(arc
		(start 370.732812 -277.115524)
		(mid 370.563362 -276.947678)
		(end 370.498116 -276.718268)
		(width 0.127)
		(layer "In6.Cu")
		(net "SMB_S3M_CPU0_PIROM_3V3AUX_SCL_1")
	)
	(arc
		(start 369.31854 -274.671028)
		(mid 369.149984 -274.499434)
		(end 369.088416 -274.266914)
		(width 0.127)
		(layer "In6.Cu")
		(net "SMB_S3M_CPU0_PIROM_3V3AUX_SCL_1")
	)
	(arc
		(start 383.890012 -284.44063)
		(mid 383.655062 -284.50359)
		(end 383.420112 -284.44063)
		(width 0.127)
		(layer "In6.Cu")
		(net "SMB_S3M_CPU0_PIROM_3V3AUX_SCL_1")
	)
	(arc
		(start 372.612412 -281.998928)
		(mid 372.442962 -281.831082)
		(end 372.377716 -281.601672)
		(width 0.127)
		(layer "In6.Cu")
		(net "SMB_S3M_CPU0_PIROM_3V3AUX_SCL_1")
	)
	(arc
		(start 384.602482 -284.858968)
		(mid 384.543139 -284.621323)
		(end 384.370834 -284.447234)
		(width 0.127)
		(layer "In6.Cu")
		(net "SMB_S3M_CPU0_PIROM_3V3AUX_SCL_1")
	)
	(arc
		(start 382.46685 -284.432756)
		(mid 382.237597 -284.377512)
		(end 382.010412 -284.44063)
		(width 0.127)
		(layer "In6.Cu")
		(net "SMB_S3M_CPU0_PIROM_3V3AUX_SCL_1")
	)
	(arc
		(start 381.535686 -284.437836)
		(mid 381.36713 -284.266242)
		(end 381.305562 -284.033722)
		(width 0.127)
		(layer "In6.Cu")
		(net "SMB_S3M_CPU0_PIROM_3V3AUX_SCL_1")
	)
	(arc
		(start 382.950212 -284.44063)
		(mid 382.715262 -284.50359)
		(end 382.480312 -284.44063)
		(width 0.127)
		(layer "In6.Cu")
		(net "SMB_S3M_CPU0_PIROM_3V3AUX_SCL_1")
	)
	(arc
		(start 370.968016 -279.150318)
		(mid 370.905122 -278.915677)
		(end 370.73332 -278.743918)
		(width 0.127)
		(layer "In6.Cu")
		(net "SMB_S3M_CPU0_PIROM_3V3AUX_SCL_1")
	)
	(arc
		(start 373.082312 -282.812998)
		(mid 372.913589 -282.646732)
		(end 372.847362 -282.419298)
		(width 0.127)
		(layer "In6.Cu")
		(net "SMB_S3M_CPU0_PIROM_3V3AUX_SCL_1")
	)
	(arc
		(start 379.191012 -283.626814)
		(mid 378.956062 -283.563854)
		(end 378.721112 -283.626814)
		(width 0.127)
		(layer "In6.Cu")
		(net "SMB_S3M_CPU0_PIROM_3V3AUX_SCL_1")
	)
	(arc
		(start 385.314698 -286.091376)
		(mid 385.142726 -285.919394)
		(end 385.079748 -285.684468)
		(width 0.127)
		(layer "In6.Cu")
		(net "SMB_S3M_CPU0_PIROM_3V3AUX_SCL_1")
	)
	(arc
		(start 369.558316 -275.08073)
		(mid 369.496753 -274.848207)
		(end 369.328192 -274.676616)
		(width 0.127)
		(layer "In6.Cu")
		(net "SMB_S3M_CPU0_PIROM_3V3AUX_SCL_1")
	)
	(arc
		(start 372.847362 -282.405836)
		(mid 372.785799 -282.173313)
		(end 372.617238 -282.001722)
		(width 0.127)
		(layer "In6.Cu")
		(net "SMB_S3M_CPU0_PIROM_3V3AUX_SCL_1")
	)
	(arc
		(start 374.012714 -282.80741)
		(mid 373.781729 -282.749927)
		(end 373.552212 -282.812998)
		(width 0.127)
		(layer "In6.Cu")
		(net "SMB_S3M_CPU0_PIROM_3V3AUX_SCL_1")
	)
	(arc
		(start 376.82805 -283.634688)
		(mid 376.598797 -283.689932)
		(end 376.371612 -283.626814)
		(width 0.127)
		(layer "In6.Cu")
		(net "SMB_S3M_CPU0_PIROM_3V3AUX_SCL_1")
	)
	(arc
		(start 384.359912 -284.44063)
		(mid 384.124962 -284.37767)
		(end 383.890012 -284.44063)
		(width 0.127)
		(layer "In6.Cu")
		(net "SMB_S3M_CPU0_PIROM_3V3AUX_SCL_1")
	)
	(arc
		(start 371.672612 -280.371042)
		(mid 371.504308 -280.205302)
		(end 371.437916 -279.978612)
		(width 0.127)
		(layer "In6.Cu")
		(net "SMB_S3M_CPU0_PIROM_3V3AUX_SCL_1")
	)
	(arc
		(start 377.781312 -283.626814)
		(mid 377.546362 -283.689774)
		(end 377.311412 -283.626814)
		(width 0.127)
		(layer "In6.Cu")
		(net "SMB_S3M_CPU0_PIROM_3V3AUX_SCL_1")
	)
	(arc
		(start 385.079748 -285.669736)
		(mid 385.013357 -285.443045)
		(end 384.845052 -285.277306)
		(width 0.127)
		(layer "In6.Cu")
		(net "SMB_S3M_CPU0_PIROM_3V3AUX_SCL_1")
	)
	(arc
		(start 371.907562 -280.77795)
		(mid 371.844612 -280.543008)
		(end 371.672612 -280.371042)
		(width 0.127)
		(layer "In6.Cu")
		(net "SMB_S3M_CPU0_PIROM_3V3AUX_SCL_1")
	)
	(arc
		(start 371.19814 -279.554432)
		(mid 371.029584 -279.382838)
		(end 370.968016 -279.150318)
		(width 0.127)
		(layer "In6.Cu")
		(net "SMB_S3M_CPU0_PIROM_3V3AUX_SCL_1")
	)
	(arc
		(start 374.492012 -283.626814)
		(mid 374.323708 -283.461074)
		(end 374.257316 -283.234384)
		(width 0.127)
		(layer "In6.Cu")
		(net "SMB_S3M_CPU0_PIROM_3V3AUX_SCL_1")
	)
	(arc
		(start 373.552466 -282.812998)
		(mid 373.317516 -282.875924)
		(end 373.082566 -282.812998)
		(width 0.127)
		(layer "In6.Cu")
		(net "SMB_S3M_CPU0_PIROM_3V3AUX_SCL_1")
	)
	(arc
		(start 378.251212 -283.626814)
		(mid 378.016262 -283.563854)
		(end 377.781312 -283.626814)
		(width 0.127)
		(layer "In6.Cu")
		(net "SMB_S3M_CPU0_PIROM_3V3AUX_SCL_1")
	)
	(arc
		(start 370.732812 -277.929594)
		(mid 370.901535 -277.763328)
		(end 370.967762 -277.535894)
		(width 0.127)
		(layer "In6.Cu")
		(net "SMB_S3M_CPU0_PIROM_3V3AUX_SCL_1")
	)
	(arc
		(start 370.25834 -276.298914)
		(mid 370.089784 -276.12732)
		(end 370.028216 -275.8948)
		(width 0.127)
		(layer "In6.Cu")
		(net "SMB_S3M_CPU0_PIROM_3V3AUX_SCL_1")
	)
	(arc
		(start 380.130812 -283.626814)
		(mid 379.895862 -283.563854)
		(end 379.660912 -283.626814)
		(width 0.127)
		(layer "In6.Cu")
		(net "SMB_S3M_CPU0_PIROM_3V3AUX_SCL_1")
	)
	(arc
		(start 379.64745 -283.634688)
		(mid 379.418197 -283.689932)
		(end 379.191012 -283.626814)
		(width 0.127)
		(layer "In6.Cu")
		(net "SMB_S3M_CPU0_PIROM_3V3AUX_SCL_1")
	)
	(arc
		(start 386.536184 -286.188658)
		(mid 386.410126 -286.171839)
		(end 386.292852 -286.122618)
		(width 0.127)
		(layer "In6.Cu")
		(net "SMB_S3M_CPU0_PIROM_3V3AUX_SCL_1")
	)
	(arc
		(start 382.010666 -284.44063)
		(mid 381.775716 -284.50359)
		(end 381.540766 -284.44063)
		(width 0.127)
		(layer "In6.Cu")
		(net "SMB_S3M_CPU0_PIROM_3V3AUX_SCL_1")
	)
	(arc
		(start 374.961912 -283.626814)
		(mid 374.726962 -283.689774)
		(end 374.492012 -283.626814)
		(width 0.127)
		(layer "In6.Cu")
		(net "SMB_S3M_CPU0_PIROM_3V3AUX_SCL_1")
	)
	(arc
		(start 386.194046 -286.064706)
		(mid 385.99197 -286.046467)
		(end 385.799584 -286.110934)
		(width 0.127)
		(layer "In6.Cu")
		(net "SMB_S3M_CPU0_PIROM_3V3AUX_SCL_1")
	)
	(arc
		(start 376.371612 -283.626814)
		(mid 376.136662 -283.563854)
		(end 375.901712 -283.626814)
		(width 0.127)
		(layer "In6.Cu")
		(net "SMB_S3M_CPU0_PIROM_3V3AUX_SCL_1")
	)
	(arc
		(start 372.137686 -281.182318)
		(mid 371.96913 -281.010724)
		(end 371.907562 -280.778204)
		(width 0.127)
		(layer "In6.Cu")
		(net "SMB_S3M_CPU0_PIROM_3V3AUX_SCL_1")
	)
	(arc
		(start 377.311412 -283.626814)
		(mid 377.076462 -283.563854)
		(end 376.841512 -283.626814)
		(width 0.127)
		(layer "In6.Cu")
		(net "SMB_S3M_CPU0_PIROM_3V3AUX_SCL_1")
	)
	(arc
		(start 369.793012 -275.487638)
		(mid 369.623562 -275.319792)
		(end 369.558316 -275.090382)
		(width 0.127)
		(layer "In6.Cu")
		(net "SMB_S3M_CPU0_PIROM_3V3AUX_SCL_1")
	)
	(arc
		(start 369.088416 -274.266914)
		(mid 369.029478 -274.039062)
		(end 368.867436 -273.868388)
		(width 0.127)
		(layer "In6.Cu")
		(net "SMB_S3M_CPU0_PIROM_3V3AUX_SCL_1")
	)
	(arc
		(start 372.377716 -281.59202)
		(mid 372.317761 -281.36241)
		(end 372.15318 -281.191462)
		(width 0.127)
		(layer "In6.Cu")
		(net "SMB_S3M_CPU0_PIROM_3V3AUX_SCL_1")
	)
	(arc
		(start 375.88825 -283.634688)
		(mid 375.658997 -283.689932)
		(end 375.431812 -283.626814)
		(width 0.127)
		(layer "In6.Cu")
		(net "SMB_S3M_CPU0_PIROM_3V3AUX_SCL_1")
	)
	(arc
		(start 370.028216 -275.8948)
		(mid 369.967159 -275.663167)
		(end 369.79987 -275.491702)
		(width 0.127)
		(layer "In6.Cu")
		(net "SMB_S3M_CPU0_PIROM_3V3AUX_SCL_1")
	)
	(arc
		(start 381.070612 -283.626814)
		(mid 380.835662 -283.563854)
		(end 380.600712 -283.626814)
		(width 0.127)
		(layer "In6.Cu")
		(net "SMB_S3M_CPU0_PIROM_3V3AUX_SCL_1")
	)
	(arc
		(start 378.721112 -283.626814)
		(mid 378.486162 -283.689774)
		(end 378.251212 -283.626814)
		(width 0.127)
		(layer "In6.Cu")
		(net "SMB_S3M_CPU0_PIROM_3V3AUX_SCL_1")
	)
	(arc
		(start 381.305562 -284.033722)
		(mid 381.242602 -283.798899)
		(end 381.070612 -283.627068)
		(width 0.127)
		(layer "In6.Cu")
		(net "SMB_S3M_CPU0_PIROM_3V3AUX_SCL_1")
	)
	(arc
		(start 374.257316 -283.219906)
		(mid 374.195753 -282.987383)
		(end 374.027192 -282.815792)
		(width 0.127)
		(layer "In6.Cu")
		(net "SMB_S3M_CPU0_PIROM_3V3AUX_SCL_1")
	)
	(arc
		(start 370.498116 -276.708616)
		(mid 370.436553 -276.476093)
		(end 370.267992 -276.304502)
		(width 0.127)
		(layer "In6.Cu")
		(net "SMB_S3M_CPU0_PIROM_3V3AUX_SCL_1")
	)
	(arc
		(start 380.600712 -283.626814)
		(mid 380.365762 -283.689774)
		(end 380.130812 -283.626814)
		(width 0.127)
		(layer "In6.Cu")
		(net "SMB_S3M_CPU0_PIROM_3V3AUX_SCL_1")
	)
	(arc
		(start 385.799584 -286.110934)
		(mid 385.629287 -286.172287)
		(end 385.448302 -286.168338)
		(width 0.127)
		(layer "In6.Cu")
		(net "SMB_S3M_CPU0_PIROM_3V3AUX_SCL_1")
	)
	(arc
		(start 370.967762 -277.522432)
		(mid 370.906199 -277.289909)
		(end 370.737638 -277.118318)
		(width 0.127)
		(layer "In6.Cu")
		(net "SMB_S3M_CPU0_PIROM_3V3AUX_SCL_1")
	)
	(arc
		(start 375.431812 -283.626814)
		(mid 375.196862 -283.563854)
		(end 374.961912 -283.626814)
		(width 0.127)
		(layer "In6.Cu")
		(net "SMB_S3M_CPU0_PIROM_3V3AUX_SCL_1")
	)
	(segment
		(start 435.41188 -343.499948)
		(end 432.89728 -340.985348)
		(width 0.127)
		(layer "In11.Cu")
		(net "SMB_S3M_CPU0_PIROM_3V3AUX_SCL_1")
	)
	(segment
		(start 425.998386 -375.966736)
		(end 430.814988 -375.966736)
		(width 0.127)
		(layer "In11.Cu")
		(net "SMB_S3M_CPU0_PIROM_3V3AUX_SCL_1")
	)
	(segment
		(start 282.12415 -386.11683)
		(end 282.92806 -386.92074)
		(width 0.127)
		(layer "In11.Cu")
		(net "SMB_S3M_CPU0_PIROM_3V3AUX_SCL_1")
	)
	(segment
		(start 284.24632 -386.92074)
		(end 285.145988 -387.820408)
		(width 0.127)
		(layer "In11.Cu")
		(net "SMB_S3M_CPU0_PIROM_3V3AUX_SCL_1")
	)
	(segment
		(start 422.76522 -378.272548)
		(end 423.692574 -378.272548)
		(width 0.127)
		(layer "In11.Cu")
		(net "SMB_S3M_CPU0_PIROM_3V3AUX_SCL_1")
	)
	(segment
		(start 289.385248 -387.820408)
		(end 294.132508 -383.073148)
		(width 0.127)
		(layer "In11.Cu")
		(net "SMB_S3M_CPU0_PIROM_3V3AUX_SCL_1")
	)
	(segment
		(start 435.41188 -371.369844)
		(end 435.41188 -343.499948)
		(width 0.127)
		(layer "In11.Cu")
		(net "SMB_S3M_CPU0_PIROM_3V3AUX_SCL_1")
	)
	(segment
		(start 294.132508 -383.073148)
		(end 417.96462 -383.073148)
		(width 0.127)
		(layer "In11.Cu")
		(net "SMB_S3M_CPU0_PIROM_3V3AUX_SCL_1")
	)
	(segment
		(start 417.96462 -383.073148)
		(end 422.76522 -378.272548)
		(width 0.127)
		(layer "In11.Cu")
		(net "SMB_S3M_CPU0_PIROM_3V3AUX_SCL_1")
	)
	(segment
		(start 432.89728 -340.985348)
		(end 427.15688 -340.985348)
		(width 0.127)
		(layer "In11.Cu")
		(net "SMB_S3M_CPU0_PIROM_3V3AUX_SCL_1")
	)
	(segment
		(start 416.122358 -323.44995)
		(end 416.122358 -322.34251)
		(width 0.127)
		(layer "In11.Cu")
		(net "SMB_S3M_CPU0_PIROM_3V3AUX_SCL_1")
	)
	(segment
		(start 282.12415 -385.583684)
		(end 282.12415 -386.11683)
		(width 0.127)
		(layer "In11.Cu")
		(net "SMB_S3M_CPU0_PIROM_3V3AUX_SCL_1")
	)
	(segment
		(start 423.692574 -378.272548)
		(end 425.998386 -375.966736)
		(width 0.127)
		(layer "In11.Cu")
		(net "SMB_S3M_CPU0_PIROM_3V3AUX_SCL_1")
	)
	(segment
		(start 419.66388 -333.492348)
		(end 419.66388 -326.991472)
		(width 0.127)
		(layer "In11.Cu")
		(net "SMB_S3M_CPU0_PIROM_3V3AUX_SCL_1")
	)
	(segment
		(start 430.814988 -375.966736)
		(end 435.41188 -371.369844)
		(width 0.127)
		(layer "In11.Cu")
		(net "SMB_S3M_CPU0_PIROM_3V3AUX_SCL_1")
	)
	(segment
		(start 427.15688 -340.985348)
		(end 419.66388 -333.492348)
		(width 0.127)
		(layer "In11.Cu")
		(net "SMB_S3M_CPU0_PIROM_3V3AUX_SCL_1")
	)
	(segment
		(start 282.92806 -386.92074)
		(end 284.24632 -386.92074)
		(width 0.127)
		(layer "In11.Cu")
		(net "SMB_S3M_CPU0_PIROM_3V3AUX_SCL_1")
	)
	(segment
		(start 419.66388 -326.991472)
		(end 416.122358 -323.44995)
		(width 0.127)
		(layer "In11.Cu")
		(net "SMB_S3M_CPU0_PIROM_3V3AUX_SCL_1")
	)
	(segment
		(start 285.145988 -387.820408)
		(end 289.385248 -387.820408)
		(width 0.127)
		(layer "In11.Cu")
		(net "SMB_S3M_CPU0_PIROM_3V3AUX_SCL_1")
	)
	(segment
		(start 183.08828 -330.647548)
		(end 180.94198 -328.501248)
		(width 0.127)
		(layer "In15.Cu")
		(net "SMB_S3M_CPU0_PIROM_3V3AUX_SCL_1")
	)
	(segment
		(start 276.787356 -386.084826)
		(end 259.426456 -368.723926)
		(width 0.127)
		(layer "In15.Cu")
		(net "SMB_S3M_CPU0_PIROM_3V3AUX_SCL_1")
	)
	(segment
		(start 204.80528 -345.760548)
		(end 189.69228 -330.647548)
		(width 0.127)
		(layer "In15.Cu")
		(net "SMB_S3M_CPU0_PIROM_3V3AUX_SCL_1")
	)
	(segment
		(start 282.12415 -385.583684)
		(end 281.623008 -386.084826)
		(width 0.127)
		(layer "In15.Cu")
		(net "SMB_S3M_CPU0_PIROM_3V3AUX_SCL_1")
	)
	(segment
		(start 281.623008 -386.084826)
		(end 276.787356 -386.084826)
		(width 0.127)
		(layer "In15.Cu")
		(net "SMB_S3M_CPU0_PIROM_3V3AUX_SCL_1")
	)
	(segment
		(start 180.77688 -327.389236)
		(end 180.77688 -326.685148)
		(width 0.127)
		(layer "In15.Cu")
		(net "SMB_S3M_CPU0_PIROM_3V3AUX_SCL_1")
	)
	(segment
		(start 259.426456 -368.723926)
		(end 234.575858 -368.723926)
		(width 0.127)
		(layer "In15.Cu")
		(net "SMB_S3M_CPU0_PIROM_3V3AUX_SCL_1")
	)
	(segment
		(start 211.61248 -345.760548)
		(end 204.80528 -345.760548)
		(width 0.127)
		(layer "In15.Cu")
		(net "SMB_S3M_CPU0_PIROM_3V3AUX_SCL_1")
	)
	(segment
		(start 234.575858 -368.723926)
		(end 211.61248 -345.760548)
		(width 0.127)
		(layer "In15.Cu")
		(net "SMB_S3M_CPU0_PIROM_3V3AUX_SCL_1")
	)
	(segment
		(start 180.94198 -328.501248)
		(end 180.94198 -327.554336)
		(width 0.127)
		(layer "In15.Cu")
		(net "SMB_S3M_CPU0_PIROM_3V3AUX_SCL_1")
	)
	(segment
		(start 180.94198 -327.554336)
		(end 180.77688 -327.389236)
		(width 0.127)
		(layer "In15.Cu")
		(net "SMB_S3M_CPU0_PIROM_3V3AUX_SCL_1")
	)
	(segment
		(start 189.69228 -330.647548)
		(end 183.08828 -330.647548)
		(width 0.127)
		(layer "In15.Cu")
		(net "SMB_S3M_CPU0_PIROM_3V3AUX_SCL_1")
	)
	(segment
		(start 104.158796 -362.150152)
		(end 103.706422 -362.602526)
		(width 0.12954)
		(layer "F.Cu")
		(net "SMB_CLK_PVCCIN_CPU1")
	)
	(segment
		(start 105.70337 -360.648504)
		(end 105.384854 -360.648504)
		(width 0.12954)
		(layer "F.Cu")
		(net "SMB_CLK_PVCCIN_CPU1")
	)
	(segment
		(start 105.384854 -360.648504)
		(end 105.06202 -360.971338)
		(width 0.12954)
		(layer "F.Cu")
		(net "SMB_CLK_PVCCIN_CPU1")
	)
	(segment
		(start 104.158796 -361.948222)
		(end 104.158796 -362.150152)
		(width 0.12954)
		(layer "F.Cu")
		(net "SMB_CLK_PVCCIN_CPU1")
	)
	(segment
		(start 105.06202 -360.971338)
		(end 105.06202 -361.044998)
		(width 0.12954)
		(layer "F.Cu")
		(net "SMB_CLK_PVCCIN_CPU1")
	)
	(segment
		(start 105.06202 -361.044998)
		(end 104.158796 -361.948222)
		(width 0.12954)
		(layer "F.Cu")
		(net "SMB_CLK_PVCCIN_CPU1")
	)
	(via
		(at 104.158796 -361.948222)
		(size 0.508)
		(drill 0.254)
		(layers "F.Cu" "B.Cu")
		(net "SMB_CLK_PVCCIN_CPU1")
	)
	(segment
		(start 351.25914 -362.755434)
		(end 351.390966 -362.623608)
		(width 0.12954)
		(layer "F.Cu")
		(net "SMB_CLK_PVCCIN_CPU0")
	)
	(segment
		(start 163.52266 -362.407708)
		(end 154.94508 -370.985288)
		(width 0.12954)
		(layer "F.Cu")
		(net "SMB_CLK_PVCCIN_CPU0")
	)
	(segment
		(start 355.920548 -368.978688)
		(end 352.592894 -368.978688)
		(width 0.12954)
		(layer "F.Cu")
		(net "SMB_CLK_PVCCIN_CPU0")
	)
	(segment
		(start 364.4138 -368.328956)
		(end 356.57028 -368.328956)
		(width 0.12954)
		(layer "F.Cu")
		(net "SMB_CLK_PVCCIN_CPU0")
	)
	(segment
		(start 154.94508 -370.985288)
		(end 140.36929 -370.985288)
		(width 0.12954)
		(layer "F.Cu")
		(net "SMB_CLK_PVCCIN_CPU0")
	)
	(segment
		(start 166.25316 -362.61167)
		(end 166.049198 -362.407708)
		(width 0.12954)
		(layer "F.Cu")
		(net "SMB_CLK_PVCCIN_CPU0")
	)
	(segment
		(start 351.82302 -362.623608)
		(end 352.40976 -362.036868)
		(width 0.12954)
		(layer "F.Cu")
		(net "SMB_CLK_PVCCIN_CPU0")
	)
	(segment
		(start 352.40976 -362.036868)
		(end 352.40976 -361.574588)
		(width 0.12954)
		(layer "F.Cu")
		(net "SMB_CLK_PVCCIN_CPU0")
	)
	(segment
		(start 364.41888 -369.534948)
		(end 364.72368 -369.230148)
		(width 0.12954)
		(layer "F.Cu")
		(net "SMB_CLK_PVCCIN_CPU0")
	)
	(segment
		(start 352.592894 -368.978688)
		(end 351.25914 -367.644934)
		(width 0.12954)
		(layer "F.Cu")
		(net "SMB_CLK_PVCCIN_CPU0")
	)
	(segment
		(start 364.72368 -368.638836)
		(end 364.4138 -368.328956)
		(width 0.12954)
		(layer "F.Cu")
		(net "SMB_CLK_PVCCIN_CPU0")
	)
	(segment
		(start 166.049198 -362.407708)
		(end 163.52266 -362.407708)
		(width 0.12954)
		(layer "F.Cu")
		(net "SMB_CLK_PVCCIN_CPU0")
	)
	(segment
		(start 364.72368 -369.230148)
		(end 364.72368 -368.638836)
		(width 0.12954)
		(layer "F.Cu")
		(net "SMB_CLK_PVCCIN_CPU0")
	)
	(segment
		(start 140.36929 -370.985288)
		(end 140.208 -370.823998)
		(width 0.12954)
		(layer "F.Cu")
		(net "SMB_CLK_PVCCIN_CPU0")
	)
	(segment
		(start 351.390966 -362.623608)
		(end 351.82302 -362.623608)
		(width 0.12954)
		(layer "F.Cu")
		(net "SMB_CLK_PVCCIN_CPU0")
	)
	(segment
		(start 351.25914 -367.644934)
		(end 351.25914 -362.755434)
		(width 0.12954)
		(layer "F.Cu")
		(net "SMB_CLK_PVCCIN_CPU0")
	)
	(segment
		(start 352.40976 -361.574588)
		(end 353.335844 -360.648504)
		(width 0.12954)
		(layer "F.Cu")
		(net "SMB_CLK_PVCCIN_CPU0")
	)
	(segment
		(start 356.57028 -368.328956)
		(end 355.920548 -368.978688)
		(width 0.12954)
		(layer "F.Cu")
		(net "SMB_CLK_PVCCIN_CPU0")
	)
	(segment
		(start 353.335844 -360.648504)
		(end 353.643184 -360.648504)
		(width 0.12954)
		(layer "F.Cu")
		(net "SMB_CLK_PVCCIN_CPU0")
	)
	(via
		(at 364.41888 -369.534948)
		(size 0.508)
		(drill 0.254)
		(layers "F.Cu" "B.Cu")
		(net "SMB_CLK_PVCCIN_CPU0")
	)
	(via
		(at 166.25316 -362.61167)
		(size 0.508)
		(drill 0.254)
		(layers "F.Cu" "B.Cu")
		(net "SMB_CLK_PVCCIN_CPU0")
	)
	(via
		(at 191.87668 -362.270548)
		(size 0.508)
		(drill 0.254)
		(layers "F.Cu" "B.Cu")
		(net "SMB_CLK_PVCCIN_CPU0")
	)
	(via
		(at 351.390966 -362.623608)
		(size 0.508)
		(drill 0.254)
		(layers "F.Cu" "B.Cu")
		(net "SMB_CLK_PVCCIN_CPU0")
	)
	(via
		(at 253.06528 -325.293482)
		(size 0.508)
		(drill 0.254)
		(layers "F.Cu" "B.Cu")
		(net "SMB_CLK_PVCCIN_CPU0")
	)
	(segment
		(start 259.233924 -330.005944)
		(end 259.501386 -330.273406)
		(width 0.12954)
		(layer "B.Cu")
		(net "SMB_CLK_PVCCIN_CPU0")
	)
	(segment
		(start 259.501386 -330.273406)
		(end 259.501386 -330.456794)
		(width 0.12954)
		(layer "B.Cu")
		(net "SMB_CLK_PVCCIN_CPU0")
	)
	(segment
		(start 258.769612 -330.286868)
		(end 259.050536 -330.005944)
		(width 0.12954)
		(layer "B.Cu")
		(net "SMB_CLK_PVCCIN_CPU0")
	)
	(segment
		(start 364.69574 -369.811808)
		(end 364.41888 -369.534948)
		(width 0.12954)
		(layer "B.Cu")
		(net "SMB_CLK_PVCCIN_CPU0")
	)
	(segment
		(start 273.79168 -345.492324)
		(end 273.79168 -367.401348)
		(width 0.12954)
		(layer "B.Cu")
		(net "SMB_CLK_PVCCIN_CPU0")
	)
	(segment
		(start 259.220462 -330.737718)
		(end 259.220462 -330.921106)
		(width 0.12954)
		(layer "B.Cu")
		(net "SMB_CLK_PVCCIN_CPU0")
	)
	(segment
		(start 286.92475 -380.534418)
		(end 354.919534 -380.534418)
		(width 0.12954)
		(layer "B.Cu")
		(net "SMB_CLK_PVCCIN_CPU0")
	)
	(segment
		(start 189.43828 -364.229396)
		(end 185.303414 -368.364262)
		(width 0.12954)
		(layer "B.Cu")
		(net "SMB_CLK_PVCCIN_CPU0")
	)
	(segment
		(start 167.199564 -362.930186)
		(end 166.748206 -362.478828)
		(width 0.12954)
		(layer "B.Cu")
		(net "SMB_CLK_PVCCIN_CPU0")
	)
	(segment
		(start 259.220462 -330.921106)
		(end 273.79168 -345.492324)
		(width 0.12954)
		(layer "B.Cu")
		(net "SMB_CLK_PVCCIN_CPU0")
	)
	(segment
		(start 258.586224 -330.286868)
		(end 258.769612 -330.286868)
		(width 0.12954)
		(layer "B.Cu")
		(net "SMB_CLK_PVCCIN_CPU0")
	)
	(segment
		(start 364.69574 -370.758212)
		(end 364.69574 -369.811808)
		(width 0.12954)
		(layer "B.Cu")
		(net "SMB_CLK_PVCCIN_CPU0")
	)
	(segment
		(start 354.919534 -380.534418)
		(end 364.69574 -370.758212)
		(width 0.12954)
		(layer "B.Cu")
		(net "SMB_CLK_PVCCIN_CPU0")
	)
	(segment
		(start 259.501386 -330.456794)
		(end 259.220462 -330.737718)
		(width 0.12954)
		(layer "B.Cu")
		(net "SMB_CLK_PVCCIN_CPU0")
	)
	(segment
		(start 185.303414 -368.364262)
		(end 170.380914 -368.364262)
		(width 0.12954)
		(layer "B.Cu")
		(net "SMB_CLK_PVCCIN_CPU0")
	)
	(segment
		(start 273.79168 -367.401348)
		(end 286.92475 -380.534418)
		(width 0.12954)
		(layer "B.Cu")
		(net "SMB_CLK_PVCCIN_CPU0")
	)
	(segment
		(start 190.523876 -362.069888)
		(end 189.43828 -363.155484)
		(width 0.12954)
		(layer "B.Cu")
		(net "SMB_CLK_PVCCIN_CPU0")
	)
	(segment
		(start 170.380914 -368.364262)
		(end 167.199564 -365.182912)
		(width 0.12954)
		(layer "B.Cu")
		(net "SMB_CLK_PVCCIN_CPU0")
	)
	(segment
		(start 254.109728 -325.465948)
		(end 257.989578 -329.345798)
		(width 0.12954)
		(layer "B.Cu")
		(net "SMB_CLK_PVCCIN_CPU0")
	)
	(segment
		(start 166.386002 -362.478828)
		(end 166.25316 -362.61167)
		(width 0.12954)
		(layer "B.Cu")
		(net "SMB_CLK_PVCCIN_CPU0")
	)
	(segment
		(start 191.67602 -362.069888)
		(end 190.523876 -362.069888)
		(width 0.12954)
		(layer "B.Cu")
		(net "SMB_CLK_PVCCIN_CPU0")
	)
	(segment
		(start 253.237746 -325.465948)
		(end 254.109728 -325.465948)
		(width 0.12954)
		(layer "B.Cu")
		(net "SMB_CLK_PVCCIN_CPU0")
	)
	(segment
		(start 257.989578 -329.345798)
		(end 257.989578 -329.690222)
		(width 0.12954)
		(layer "B.Cu")
		(net "SMB_CLK_PVCCIN_CPU0")
	)
	(segment
		(start 259.050536 -330.005944)
		(end 259.233924 -330.005944)
		(width 0.12954)
		(layer "B.Cu")
		(net "SMB_CLK_PVCCIN_CPU0")
	)
	(segment
		(start 257.989578 -329.690222)
		(end 258.586224 -330.286868)
		(width 0.12954)
		(layer "B.Cu")
		(net "SMB_CLK_PVCCIN_CPU0")
	)
	(segment
		(start 189.43828 -363.155484)
		(end 189.43828 -364.229396)
		(width 0.12954)
		(layer "B.Cu")
		(net "SMB_CLK_PVCCIN_CPU0")
	)
	(segment
		(start 167.199564 -365.182912)
		(end 167.199564 -362.930186)
		(width 0.12954)
		(layer "B.Cu")
		(net "SMB_CLK_PVCCIN_CPU0")
	)
	(segment
		(start 253.06528 -325.293482)
		(end 253.237746 -325.465948)
		(width 0.12954)
		(layer "B.Cu")
		(net "SMB_CLK_PVCCIN_CPU0")
	)
	(segment
		(start 166.748206 -362.478828)
		(end 166.386002 -362.478828)
		(width 0.12954)
		(layer "B.Cu")
		(net "SMB_CLK_PVCCIN_CPU0")
	)
	(segment
		(start 191.87668 -362.270548)
		(end 191.67602 -362.069888)
		(width 0.12954)
		(layer "B.Cu")
		(net "SMB_CLK_PVCCIN_CPU0")
	)
	(segment
		(start 253.70028 -325.491348)
		(end 254.30988 -326.100948)
		(width 0.127)
		(layer "In6.Cu")
		(net "SMB_CLK_PVCCIN_CPU0")
	)
	(segment
		(start 247.41124 -344.363548)
		(end 233.68508 -344.363548)
		(width 0.127)
		(layer "In6.Cu")
		(net "SMB_CLK_PVCCIN_CPU0")
	)
	(segment
		(start 253.06528 -325.293482)
		(end 253.263146 -325.491348)
		(width 0.127)
		(layer "In6.Cu")
		(net "SMB_CLK_PVCCIN_CPU0")
	)
	(segment
		(start 212.37448 -353.278948)
		(end 203.61148 -362.041948)
		(width 0.127)
		(layer "In6.Cu")
		(net "SMB_CLK_PVCCIN_CPU0")
	)
	(segment
		(start 254.30988 -326.100948)
		(end 254.30988 -337.464908)
		(width 0.127)
		(layer "In6.Cu")
		(net "SMB_CLK_PVCCIN_CPU0")
	)
	(segment
		(start 203.61148 -362.041948)
		(end 192.10528 -362.041948)
		(width 0.127)
		(layer "In6.Cu")
		(net "SMB_CLK_PVCCIN_CPU0")
	)
	(segment
		(start 253.263146 -325.491348)
		(end 253.70028 -325.491348)
		(width 0.127)
		(layer "In6.Cu")
		(net "SMB_CLK_PVCCIN_CPU0")
	)
	(segment
		(start 192.10528 -362.041948)
		(end 191.87668 -362.270548)
		(width 0.127)
		(layer "In6.Cu")
		(net "SMB_CLK_PVCCIN_CPU0")
	)
	(segment
		(start 254.30988 -337.464908)
		(end 247.41124 -344.363548)
		(width 0.127)
		(layer "In6.Cu")
		(net "SMB_CLK_PVCCIN_CPU0")
	)
	(segment
		(start 233.68508 -344.363548)
		(end 224.76968 -353.278948)
		(width 0.127)
		(layer "In6.Cu")
		(net "SMB_CLK_PVCCIN_CPU0")
	)
	(segment
		(start 224.76968 -353.278948)
		(end 212.37448 -353.278948)
		(width 0.127)
		(layer "In6.Cu")
		(net "SMB_CLK_PVCCIN_CPU0")
	)
	(segment
		(start 34.793428 -126.26086)
		(end 34.793428 -125.899164)
		(width 0.12954)
		(layer "F.Cu")
		(net "SMB_CLK_PVCCINFAON_CPU1")
	)
	(segment
		(start 34.1249 -126.26086)
		(end 34.793428 -126.26086)
		(width 0.12954)
		(layer "F.Cu")
		(net "SMB_CLK_PVCCINFAON_CPU1")
	)
	(segment
		(start 33.861248 -126.524512)
		(end 34.1249 -126.26086)
		(width 0.12954)
		(layer "F.Cu")
		(net "SMB_CLK_PVCCINFAON_CPU1")
	)
	(segment
		(start 33.861248 -127.233426)
		(end 33.861248 -126.524512)
		(width 0.12954)
		(layer "F.Cu")
		(net "SMB_CLK_PVCCINFAON_CPU1")
	)
	(segment
		(start 34.793428 -125.899164)
		(end 34.291524 -125.39726)
		(width 0.12954)
		(layer "F.Cu")
		(net "SMB_CLK_PVCCINFAON_CPU1")
	)
	(via
		(at 34.793428 -126.26086)
		(size 0.508)
		(drill 0.254)
		(layers "F.Cu" "B.Cu")
		(net "SMB_CLK_PVCCINFAON_CPU1")
	)
	(segment
		(start 430.200054 -131.599178)
		(end 428.947072 -131.599178)
		(width 0.12954)
		(layer "F.Cu")
		(net "SMB_CLK_PVCCINFAON_CPU0")
	)
	(segment
		(start 428.947072 -132.244592)
		(end 427.505114 -133.68655)
		(width 0.12954)
		(layer "F.Cu")
		(net "SMB_CLK_PVCCINFAON_CPU0")
	)
	(segment
		(start 428.947072 -131.599178)
		(end 428.947072 -132.244592)
		(width 0.12954)
		(layer "F.Cu")
		(net "SMB_CLK_PVCCINFAON_CPU0")
	)
	(segment
		(start 427.505114 -133.68655)
		(end 427.505114 -134.014464)
		(width 0.12954)
		(layer "F.Cu")
		(net "SMB_CLK_PVCCINFAON_CPU0")
	)
	(via
		(at 428.947072 -131.599178)
		(size 0.508)
		(drill 0.254)
		(layers "F.Cu" "B.Cu")
		(net "SMB_CLK_PVCCINFAON_CPU0")
	)
	(segment
		(start 25.8191 -167.270938)
		(end 25.8191 -167.920162)
		(width 0.12954)
		(layer "F.Cu")
		(net "SMB_CLK_PVCCD_HV_CPU1")
	)
	(segment
		(start 25.862788 -167.22725)
		(end 25.8191 -167.270938)
		(width 0.12954)
		(layer "F.Cu")
		(net "SMB_CLK_PVCCD_HV_CPU1")
	)
	(segment
		(start 25.8191 -167.920162)
		(end 25.151334 -168.587928)
		(width 0.12954)
		(layer "F.Cu")
		(net "SMB_CLK_PVCCD_HV_CPU1")
	)
	(via
		(at 25.151334 -168.587928)
		(size 0.508)
		(drill 0.254)
		(layers "F.Cu" "B.Cu")
		(net "SMB_CLK_PVCCD_HV_CPU1")
	)
	(segment
		(start 25.151334 -169.908728)
		(end 23.894288 -171.165774)
		(width 0.12954)
		(layer "B.Cu")
		(net "SMB_CLK_PVCCD_HV_CPU1")
	)
	(segment
		(start 25.151334 -168.587928)
		(end 25.151334 -169.908728)
		(width 0.12954)
		(layer "B.Cu")
		(net "SMB_CLK_PVCCD_HV_CPU1")
	)
	(segment
		(start 23.894288 -171.165774)
		(end 23.389082 -171.165774)
		(width 0.12954)
		(layer "B.Cu")
		(net "SMB_CLK_PVCCD_HV_CPU1")
	)
	(segment
		(start 435.024784 -119.584216)
		(end 434.341016 -120.267984)
		(width 0.12954)
		(layer "F.Cu")
		(net "SMB_CLK_PVCCD_HV_CPU0")
	)
	(segment
		(start 435.350158 -118.968266)
		(end 435.350158 -119.584216)
		(width 0.12954)
		(layer "F.Cu")
		(net "SMB_CLK_PVCCD_HV_CPU0")
	)
	(segment
		(start 434.341016 -120.548654)
		(end 434.301138 -120.588532)
		(width 0.12954)
		(layer "F.Cu")
		(net "SMB_CLK_PVCCD_HV_CPU0")
	)
	(segment
		(start 434.341016 -120.267984)
		(end 434.341016 -120.548654)
		(width 0.12954)
		(layer "F.Cu")
		(net "SMB_CLK_PVCCD_HV_CPU0")
	)
	(segment
		(start 435.350158 -119.584216)
		(end 435.024784 -119.584216)
		(width 0.12954)
		(layer "F.Cu")
		(net "SMB_CLK_PVCCD_HV_CPU0")
	)
	(via
		(at 435.350158 -119.584216)
		(size 0.508)
		(drill 0.254)
		(layers "F.Cu" "B.Cu")
		(net "SMB_CLK_PVCCD_HV_CPU0")
	)
	(segment
		(start 121.251472 -357.51643)
		(end 120.066054 -357.51643)
		(width 0.254)
		(layer "F.Cu")
		(net "SH_PVPP_HBM_CPU1_P")
	)
	(segment
		(start 119.630698 -358.13111)
		(end 120.066054 -357.695754)
		(width 0.254)
		(layer "F.Cu")
		(net "SH_PVPP_HBM_CPU1_P")
	)
	(segment
		(start 120.066054 -357.695754)
		(end 120.066054 -357.51643)
		(width 0.254)
		(layer "F.Cu")
		(net "SH_PVPP_HBM_CPU1_P")
	)
	(via
		(at 119.57812 -357.37292)
		(size 0.7112)
		(drill 0.3556)
		(layers "F.Cu" "B.Cu")
		(net "SH_PVPP_HBM_CPU1_P")
	)
	(via
		(at 119.630698 -358.13111)
		(size 0.508)
		(drill 0.254)
		(layers "F.Cu" "B.Cu")
		(net "SH_PVPP_HBM_CPU1_P")
	)
	(segment
		(start 119.531638 -358.03205)
		(end 119.531638 -357.419402)
		(width 0.254)
		(layer "B.Cu")
		(net "SH_PVPP_HBM_CPU1_P")
	)
	(segment
		(start 119.531638 -357.419402)
		(end 119.57812 -357.37292)
		(width 0.254)
		(layer "B.Cu")
		(net "SH_PVPP_HBM_CPU1_P")
	)
	(segment
		(start 120.73255 -357.675688)
		(end 120.73255 -358.57307)
		(width 0.254)
		(layer "B.Cu")
		(net "SH_PVPP_HBM_CPU1_P")
	)
	(segment
		(start 120.373648 -357.675688)
		(end 120.73255 -357.675688)
		(width 0.254)
		(layer "B.Cu")
		(net "SH_PVPP_HBM_CPU1_P")
	)
	(segment
		(start 120.07088 -357.37292)
		(end 120.373648 -357.675688)
		(width 0.254)
		(layer "B.Cu")
		(net "SH_PVPP_HBM_CPU1_P")
	)
	(segment
		(start 119.57812 -357.37292)
		(end 120.07088 -357.37292)
		(width 0.254)
		(layer "B.Cu")
		(net "SH_PVPP_HBM_CPU1_P")
	)
	(segment
		(start 119.630698 -358.13111)
		(end 119.531638 -358.03205)
		(width 0.254)
		(layer "B.Cu")
		(net "SH_PVPP_HBM_CPU1_P")
	)
	(segment
		(start 120.73255 -358.57307)
		(end 120.458484 -358.847136)
		(width 0.254)
		(layer "B.Cu")
		(net "SH_PVPP_HBM_CPU1_P")
	)
	(segment
		(start 123.401836 -357.961184)
		(end 122.957082 -357.51643)
		(width 0.254)
		(layer "F.Cu")
		(net "SH_PVPP_HBM_CPU1_N")
	)
	(segment
		(start 119.14632 -360.2736)
		(end 119.48922 -360.6165)
		(width 0.254)
		(layer "F.Cu")
		(net "SH_PVPP_HBM_CPU1_N")
	)
	(segment
		(start 121.830084 -357.979218)
		(end 122.292872 -357.51643)
		(width 0.254)
		(layer "F.Cu")
		(net "SH_PVPP_HBM_CPU1_N")
	)
	(segment
		(start 123.50115 -358.060498)
		(end 123.401836 -357.961184)
		(width 0.12954)
		(layer "F.Cu")
		(net "SH_PVPP_HBM_CPU1_N")
	)
	(segment
		(start 117.960394 -362.55071)
		(end 117.70614 -362.804964)
		(width 0.254)
		(layer "F.Cu")
		(net "SH_PVPP_HBM_CPU1_N")
	)
	(segment
		(start 122.427238 -358.12857)
		(end 122.427238 -358.176576)
		(width 0.254)
		(layer "F.Cu")
		(net "SH_PVPP_HBM_CPU1_N")
	)
	(segment
		(start 117.70614 -362.804964)
		(end 117.70614 -363.602016)
		(width 0.254)
		(layer "F.Cu")
		(net "SH_PVPP_HBM_CPU1_N")
	)
	(segment
		(start 119.196358 -362.55071)
		(end 117.960394 -362.55071)
		(width 0.254)
		(layer "F.Cu")
		(net "SH_PVPP_HBM_CPU1_N")
	)
	(segment
		(start 122.427238 -358.176576)
		(end 122.173238 -358.430576)
		(width 0.254)
		(layer "F.Cu")
		(net "SH_PVPP_HBM_CPU1_N")
	)
	(segment
		(start 119.09552 -360.2736)
		(end 119.14632 -360.2736)
		(width 0.254)
		(layer "F.Cu")
		(net "SH_PVPP_HBM_CPU1_N")
	)
	(segment
		(start 119.48922 -362.257848)
		(end 119.196358 -362.55071)
		(width 0.254)
		(layer "F.Cu")
		(net "SH_PVPP_HBM_CPU1_N")
	)
	(segment
		(start 122.957082 -357.51643)
		(end 122.292872 -357.51643)
		(width 0.254)
		(layer "F.Cu")
		(net "SH_PVPP_HBM_CPU1_N")
	)
	(segment
		(start 124.314966 -358.060498)
		(end 123.50115 -358.060498)
		(width 0.12954)
		(layer "F.Cu")
		(net "SH_PVPP_HBM_CPU1_N")
	)
	(segment
		(start 121.830084 -358.430576)
		(end 121.830084 -357.979218)
		(width 0.254)
		(layer "F.Cu")
		(net "SH_PVPP_HBM_CPU1_N")
	)
	(segment
		(start 119.48922 -360.6165)
		(end 119.48922 -362.257848)
		(width 0.254)
		(layer "F.Cu")
		(net "SH_PVPP_HBM_CPU1_N")
	)
	(segment
		(start 122.173238 -358.430576)
		(end 121.830084 -358.430576)
		(width 0.254)
		(layer "F.Cu")
		(net "SH_PVPP_HBM_CPU1_N")
	)
	(via
		(at 119.09552 -360.2736)
		(size 0.508)
		(drill 0.254)
		(layers "F.Cu" "B.Cu")
		(net "SH_PVPP_HBM_CPU1_N")
	)
	(via
		(at 122.427238 -358.12857)
		(size 0.508)
		(drill 0.254)
		(layers "F.Cu" "B.Cu")
		(net "SH_PVPP_HBM_CPU1_N")
	)
	(segment
		(start 121.53265 -357.675688)
		(end 121.53265 -358.549702)
		(width 0.254)
		(layer "B.Cu")
		(net "SH_PVPP_HBM_CPU1_N")
	)
	(segment
		(start 121.53265 -358.549702)
		(end 121.830084 -358.847136)
		(width 0.254)
		(layer "B.Cu")
		(net "SH_PVPP_HBM_CPU1_N")
	)
	(segment
		(start 122.427238 -358.12857)
		(end 121.974356 -357.675688)
		(width 0.254)
		(layer "B.Cu")
		(net "SH_PVPP_HBM_CPU1_N")
	)
	(segment
		(start 121.974356 -357.675688)
		(end 121.53265 -357.675688)
		(width 0.254)
		(layer "B.Cu")
		(net "SH_PVPP_HBM_CPU1_N")
	)
	(segment
		(start 121.977658 -358.12857)
		(end 122.427238 -358.12857)
		(width 0.254)
		(layer "In6.Cu")
		(net "SH_PVPP_HBM_CPU1_N")
	)
	(segment
		(start 119.21236 -360.03992)
		(end 119.768112 -359.484168)
		(width 0.254)
		(layer "In6.Cu")
		(net "SH_PVPP_HBM_CPU1_N")
	)
	(segment
		(start 119.09552 -360.2736)
		(end 119.21236 -360.15676)
		(width 0.254)
		(layer "In6.Cu")
		(net "SH_PVPP_HBM_CPU1_N")
	)
	(segment
		(start 119.21236 -360.15676)
		(end 119.21236 -360.03992)
		(width 0.254)
		(layer "In6.Cu")
		(net "SH_PVPP_HBM_CPU1_N")
	)
	(segment
		(start 120.62206 -359.484168)
		(end 121.977658 -358.12857)
		(width 0.254)
		(layer "In6.Cu")
		(net "SH_PVPP_HBM_CPU1_N")
	)
	(segment
		(start 119.768112 -359.484168)
		(end 120.62206 -359.484168)
		(width 0.254)
		(layer "In6.Cu")
		(net "SH_PVPP_HBM_CPU1_N")
	)
	(segment
		(start 369.191286 -357.51643)
		(end 368.005868 -357.51643)
		(width 0.254)
		(layer "F.Cu")
		(net "SH_PVPP_HBM_CPU0_P")
	)
	(segment
		(start 367.088674 -358.818688)
		(end 368.005868 -357.901494)
		(width 0.12954)
		(layer "F.Cu")
		(net "SH_PVPP_HBM_CPU0_P")
	)
	(segment
		(start 367.03508 -358.818688)
		(end 367.088674 -358.818688)
		(width 0.12954)
		(layer "F.Cu")
		(net "SH_PVPP_HBM_CPU0_P")
	)
	(segment
		(start 368.005868 -357.901494)
		(end 368.005868 -357.51643)
		(width 0.254)
		(layer "F.Cu")
		(net "SH_PVPP_HBM_CPU0_P")
	)
	(via
		(at 367.03508 -358.818688)
		(size 0.508)
		(drill 0.254)
		(layers "F.Cu" "B.Cu")
		(net "SH_PVPP_HBM_CPU0_P")
	)
	(segment
		(start 368.018568 -357.667306)
		(end 368.652298 -357.667306)
		(width 0.254)
		(layer "B.Cu")
		(net "SH_PVPP_HBM_CPU0_P")
	)
	(segment
		(start 367.03508 -358.818688)
		(end 367.03508 -358.650794)
		(width 0.254)
		(layer "B.Cu")
		(net "SH_PVPP_HBM_CPU0_P")
	)
	(segment
		(start 368.398298 -358.836976)
		(end 368.652298 -358.582976)
		(width 0.254)
		(layer "B.Cu")
		(net "SH_PVPP_HBM_CPU0_P")
	)
	(segment
		(start 368.652298 -357.667306)
		(end 368.655092 -357.667306)
		(width 0.254)
		(layer "B.Cu")
		(net "SH_PVPP_HBM_CPU0_P")
	)
	(segment
		(start 368.652298 -358.582976)
		(end 368.652298 -357.667306)
		(width 0.254)
		(layer "B.Cu")
		(net "SH_PVPP_HBM_CPU0_P")
	)
	(segment
		(start 367.03508 -358.650794)
		(end 368.018568 -357.667306)
		(width 0.254)
		(layer "B.Cu")
		(net "SH_PVPP_HBM_CPU0_P")
	)
	(segment
		(start 370.232686 -357.51643)
		(end 370.896896 -357.51643)
		(width 0.254)
		(layer "F.Cu")
		(net "SH_PVPP_HBM_CPU0_N")
	)
	(segment
		(start 365.694468 -363.886496)
		(end 365.694468 -364.978696)
		(width 0.254)
		(layer "F.Cu")
		(net "SH_PVPP_HBM_CPU0_N")
	)
	(segment
		(start 370.367052 -358.12857)
		(end 370.367052 -358.176576)
		(width 0.254)
		(layer "F.Cu")
		(net "SH_PVPP_HBM_CPU0_N")
	)
	(segment
		(start 369.769898 -357.979218)
		(end 370.232686 -357.51643)
		(width 0.254)
		(layer "F.Cu")
		(net "SH_PVPP_HBM_CPU0_N")
	)
	(segment
		(start 372.25478 -358.060498)
		(end 371.440964 -358.060498)
		(width 0.12954)
		(layer "F.Cu")
		(net "SH_PVPP_HBM_CPU0_N")
	)
	(segment
		(start 369.769898 -358.430576)
		(end 369.769898 -357.979218)
		(width 0.254)
		(layer "F.Cu")
		(net "SH_PVPP_HBM_CPU0_N")
	)
	(segment
		(start 370.367052 -358.176576)
		(end 370.113052 -358.430576)
		(width 0.254)
		(layer "F.Cu")
		(net "SH_PVPP_HBM_CPU0_N")
	)
	(segment
		(start 371.440964 -358.060498)
		(end 371.34165 -357.961184)
		(width 0.12954)
		(layer "F.Cu")
		(net "SH_PVPP_HBM_CPU0_N")
	)
	(segment
		(start 370.113052 -358.430576)
		(end 369.769898 -358.430576)
		(width 0.254)
		(layer "F.Cu")
		(net "SH_PVPP_HBM_CPU0_N")
	)
	(segment
		(start 371.34165 -357.961184)
		(end 370.896896 -357.51643)
		(width 0.254)
		(layer "F.Cu")
		(net "SH_PVPP_HBM_CPU0_N")
	)
	(via
		(at 370.367052 -358.12857)
		(size 0.508)
		(drill 0.254)
		(layers "F.Cu" "B.Cu")
		(net "SH_PVPP_HBM_CPU0_N")
	)
	(via
		(at 365.694468 -364.978696)
		(size 0.508)
		(drill 0.254)
		(layers "F.Cu" "B.Cu")
		(net "SH_PVPP_HBM_CPU0_N")
	)
	(via
		(at 370.896896 -357.51643)
		(size 0.508)
		(drill 0.254)
		(layers "F.Cu" "B.Cu")
		(net "SH_PVPP_HBM_CPU0_N")
	)
	(segment
		(start 369.455192 -358.52227)
		(end 369.769898 -358.836976)
		(width 0.254)
		(layer "B.Cu")
		(net "SH_PVPP_HBM_CPU0_N")
	)
	(segment
		(start 369.455192 -357.667306)
		(end 369.455192 -358.52227)
		(width 0.254)
		(layer "B.Cu")
		(net "SH_PVPP_HBM_CPU0_N")
	)
	(segment
		(start 370.367052 -358.12857)
		(end 369.905788 -357.667306)
		(width 0.254)
		(layer "B.Cu")
		(net "SH_PVPP_HBM_CPU0_N")
	)
	(segment
		(start 369.905788 -357.667306)
		(end 369.455192 -357.667306)
		(width 0.254)
		(layer "B.Cu")
		(net "SH_PVPP_HBM_CPU0_N")
	)
	(segment
		(start 367.674398 -359.576624)
		(end 367.674398 -364.729776)
		(width 0.254)
		(layer "In2.Cu")
		(net "SH_PVPP_HBM_CPU0_N")
	)
	(segment
		(start 370.609876 -357.22941)
		(end 370.021612 -357.22941)
		(width 0.254)
		(layer "In2.Cu")
		(net "SH_PVPP_HBM_CPU0_N")
	)
	(segment
		(start 370.896896 -357.51643)
		(end 370.609876 -357.22941)
		(width 0.254)
		(layer "In2.Cu")
		(net "SH_PVPP_HBM_CPU0_N")
	)
	(segment
		(start 367.425478 -364.978696)
		(end 365.694468 -364.978696)
		(width 0.254)
		(layer "In2.Cu")
		(net "SH_PVPP_HBM_CPU0_N")
	)
	(segment
		(start 370.021612 -357.22941)
		(end 367.674398 -359.576624)
		(width 0.254)
		(layer "In2.Cu")
		(net "SH_PVPP_HBM_CPU0_N")
	)
	(segment
		(start 367.674398 -364.729776)
		(end 367.425478 -364.978696)
		(width 0.254)
		(layer "In2.Cu")
		(net "SH_PVPP_HBM_CPU0_N")
	)
	(segment
		(start 106.378502 -354.600002)
		(end 106.15168 -354.37318)
		(width 0.1778)
		(layer "F.Cu")
		(net "SH_PVCCIN_CPU1_R")
	)
	(segment
		(start 106.15168 -353.857052)
		(end 105.512108 -353.21748)
		(width 0.254)
		(layer "F.Cu")
		(net "SH_PVCCIN_CPU1_R")
	)
	(segment
		(start 105.507282 -353.14255)
		(end 105.512108 -353.137724)
		(width 0.254)
		(layer "F.Cu")
		(net "SH_PVCCIN_CPU1_R")
	)
	(segment
		(start 104.62006 -353.14255)
		(end 105.507282 -353.14255)
		(width 0.254)
		(layer "F.Cu")
		(net "SH_PVCCIN_CPU1_R")
	)
	(segment
		(start 105.512108 -353.21748)
		(end 105.512108 -353.137724)
		(width 0.254)
		(layer "F.Cu")
		(net "SH_PVCCIN_CPU1_R")
	)
	(segment
		(start 106.15168 -354.37318)
		(end 106.15168 -353.857052)
		(width 0.254)
		(layer "F.Cu")
		(net "SH_PVCCIN_CPU1_R")
	)
	(segment
		(start 106.378502 -355.97338)
		(end 106.378502 -354.600002)
		(width 0.1778)
		(layer "F.Cu")
		(net "SH_PVCCIN_CPU1_R")
	)
	(via
		(at 106.15168 -354.37318)
		(size 0.762)
		(drill 0.381)
		(layers "F.Cu" "B.Cu")
		(net "SH_PVCCIN_CPU1_R")
	)
	(segment
		(start 102.42804 -353.350068)
		(end 102.635558 -353.14255)
		(width 0.254)
		(layer "F.Cu")
		(net "SH_PVCCIN_CPU1")
	)
	(segment
		(start 102.635558 -353.14255)
		(end 103.81996 -353.14255)
		(width 0.254)
		(layer "F.Cu")
		(net "SH_PVCCIN_CPU1")
	)
	(segment
		(start 102.069646 -352.991674)
		(end 102.42804 -353.350068)
		(width 0.254)
		(layer "F.Cu")
		(net "SH_PVCCIN_CPU1")
	)
	(segment
		(start 102.069646 -352.02114)
		(end 102.069646 -352.991674)
		(width 0.254)
		(layer "F.Cu")
		(net "SH_PVCCIN_CPU1")
	)
	(via
		(at 102.42804 -353.350068)
		(size 0.762)
		(drill 0.381)
		(layers "F.Cu" "B.Cu")
		(net "SH_PVCCIN_CPU1")
	)
	(segment
		(start 354.065078 -354.349812)
		(end 353.451922 -353.736656)
		(width 0.1778)
		(layer "F.Cu")
		(net "SH_PVCCIN_CPU0_R")
	)
	(segment
		(start 353.451922 -353.137724)
		(end 352.744786 -353.137724)
		(width 0.1778)
		(layer "F.Cu")
		(net "SH_PVCCIN_CPU0_R")
	)
	(segment
		(start 354.318316 -355.97338)
		(end 354.318316 -354.60305)
		(width 0.1778)
		(layer "F.Cu")
		(net "SH_PVCCIN_CPU0_R")
	)
	(segment
		(start 353.451922 -353.736656)
		(end 353.451922 -353.137724)
		(width 0.1778)
		(layer "F.Cu")
		(net "SH_PVCCIN_CPU0_R")
	)
	(segment
		(start 354.318316 -354.60305)
		(end 354.065078 -354.349812)
		(width 0.1778)
		(layer "F.Cu")
		(net "SH_PVCCIN_CPU0_R")
	)
	(segment
		(start 352.73742 -353.14509)
		(end 352.361754 -353.14509)
		(width 0.1778)
		(layer "F.Cu")
		(net "SH_PVCCIN_CPU0_R")
	)
	(segment
		(start 352.744786 -353.137724)
		(end 352.73742 -353.14509)
		(width 0.1778)
		(layer "F.Cu")
		(net "SH_PVCCIN_CPU0_R")
	)
	(via
		(at 354.065078 -354.349812)
		(size 0.762)
		(drill 0.381)
		(layers "F.Cu" "B.Cu")
		(net "SH_PVCCIN_CPU0_R")
	)
	(segment
		(start 349.87738 -353.322128)
		(end 350.99752 -353.322128)
		(width 0.254)
		(layer "F.Cu")
		(net "SH_PVCCIN_CPU0")
	)
	(segment
		(start 350.99752 -353.322128)
		(end 351.174558 -353.14509)
		(width 0.254)
		(layer "F.Cu")
		(net "SH_PVCCIN_CPU0")
	)
	(segment
		(start 349.87738 -352.664268)
		(end 349.87738 -353.322128)
		(width 0.254)
		(layer "F.Cu")
		(net "SH_PVCCIN_CPU0")
	)
	(segment
		(start 350.00946 -352.532188)
		(end 349.87738 -352.664268)
		(width 0.254)
		(layer "F.Cu")
		(net "SH_PVCCIN_CPU0")
	)
	(segment
		(start 350.00946 -352.02114)
		(end 350.00946 -352.532188)
		(width 0.254)
		(layer "F.Cu")
		(net "SH_PVCCIN_CPU0")
	)
	(segment
		(start 351.174558 -353.14509)
		(end 351.561654 -353.14509)
		(width 0.254)
		(layer "F.Cu")
		(net "SH_PVCCIN_CPU0")
	)
	(via
		(at 349.87738 -353.322128)
		(size 0.762)
		(drill 0.381)
		(layers "F.Cu" "B.Cu")
		(net "SH_PVCCIN_CPU0")
	)
	(segment
		(start 33.861248 -132.532882)
		(end 33.861248 -132.033518)
		(width 0.1778)
		(layer "F.Cu")
		(net "SH_PVCCINFAON_CPU1_R")
	)
	(segment
		(start 34.16935 -132.840984)
		(end 33.861248 -132.532882)
		(width 0.254)
		(layer "F.Cu")
		(net "SH_PVCCINFAON_CPU1_R")
	)
	(segment
		(start 34.16935 -133.444996)
		(end 34.16935 -132.840984)
		(width 0.254)
		(layer "F.Cu")
		(net "SH_PVCCINFAON_CPU1_R")
	)
	(segment
		(start 35.176206 -133.444996)
		(end 34.16935 -133.444996)
		(width 0.254)
		(layer "F.Cu")
		(net "SH_PVCCINFAON_CPU1_R")
	)
	(segment
		(start 35.176206 -134.245096)
		(end 35.176206 -135.631682)
		(width 0.254)
		(layer "F.Cu")
		(net "SH_PVCCINFAON_CPU1")
	)
	(segment
		(start 35.176206 -135.631682)
		(end 35.171126 -135.636762)
		(width 0.254)
		(layer "F.Cu")
		(net "SH_PVCCINFAON_CPU1")
	)
	(segment
		(start 428.407576 -139.84351)
		(end 428.407576 -140.269214)
		(width 0.254)
		(layer "F.Cu")
		(net "SH_PVCCINFAON_CPU0_R")
	)
	(segment
		(start 429.265334 -140.269214)
		(end 429.28032 -140.254228)
		(width 0.254)
		(layer "F.Cu")
		(net "SH_PVCCINFAON_CPU0_R")
	)
	(segment
		(start 427.505114 -138.941048)
		(end 428.407576 -139.84351)
		(width 0.254)
		(layer "F.Cu")
		(net "SH_PVCCINFAON_CPU0_R")
	)
	(segment
		(start 427.505114 -138.814556)
		(end 427.505114 -138.941048)
		(width 0.1778)
		(layer "F.Cu")
		(net "SH_PVCCINFAON_CPU0_R")
	)
	(segment
		(start 428.407576 -140.269214)
		(end 429.265334 -140.269214)
		(width 0.254)
		(layer "F.Cu")
		(net "SH_PVCCINFAON_CPU0_R")
	)
	(segment
		(start 429.267112 -142.4178)
		(end 429.28032 -141.054328)
		(width 0.254)
		(layer "F.Cu")
		(net "SH_PVCCINFAON_CPU0")
	)
	(segment
		(start 113.939066 -354.940616)
		(end 113.820956 -354.822506)
		(width 0.254)
		(layer "F.Cu")
		(net "SH_PVCCFA_EHV_FIVRA_CPU1_R")
	)
	(segment
		(start 114.557556 -354.940616)
		(end 114.557556 -354.065586)
		(width 0.254)
		(layer "F.Cu")
		(net "SH_PVCCFA_EHV_FIVRA_CPU1_R")
	)
	(segment
		(start 114.557556 -354.940616)
		(end 113.939066 -354.940616)
		(width 0.254)
		(layer "F.Cu")
		(net "SH_PVCCFA_EHV_FIVRA_CPU1_R")
	)
	(segment
		(start 113.820956 -355.52126)
		(end 112.68202 -356.660196)
		(width 0.1778)
		(layer "F.Cu")
		(net "SH_PVCCFA_EHV_FIVRA_CPU1_R")
	)
	(segment
		(start 112.51438 -357.276908)
		(end 111.94288 -357.848408)
		(width 0.1778)
		(layer "F.Cu")
		(net "SH_PVCCFA_EHV_FIVRA_CPU1_R")
	)
	(segment
		(start 113.820956 -354.822506)
		(end 113.820956 -354.790248)
		(width 0.254)
		(layer "F.Cu")
		(net "SH_PVCCFA_EHV_FIVRA_CPU1_R")
	)
	(segment
		(start 112.68202 -356.87254)
		(end 112.51438 -357.276908)
		(width 0.1778)
		(layer "F.Cu")
		(net "SH_PVCCFA_EHV_FIVRA_CPU1_R")
	)
	(segment
		(start 112.68202 -356.660196)
		(end 112.68202 -356.87254)
		(width 0.1778)
		(layer "F.Cu")
		(net "SH_PVCCFA_EHV_FIVRA_CPU1_R")
	)
	(segment
		(start 111.94288 -357.848408)
		(end 111.453422 -357.848408)
		(width 0.1778)
		(layer "F.Cu")
		(net "SH_PVCCFA_EHV_FIVRA_CPU1_R")
	)
	(segment
		(start 113.820956 -354.822506)
		(end 113.820956 -355.52126)
		(width 0.1778)
		(layer "F.Cu")
		(net "SH_PVCCFA_EHV_FIVRA_CPU1_R")
	)
	(via
		(at 113.820956 -354.790248)
		(size 0.508)
		(drill 0.254)
		(layers "F.Cu" "B.Cu")
		(net "SH_PVCCFA_EHV_FIVRA_CPU1_R")
	)
	(segment
		(start 115.251992 -356.735126)
		(end 114.557556 -356.04069)
		(width 0.254)
		(layer "F.Cu")
		(net "SH_PVCCFA_EHV_FIVRA_CPU1")
	)
	(segment
		(start 115.680236 -356.735126)
		(end 115.251992 -356.735126)
		(width 0.254)
		(layer "F.Cu")
		(net "SH_PVCCFA_EHV_FIVRA_CPU1")
	)
	(segment
		(start 114.557556 -356.04069)
		(end 114.557556 -355.740716)
		(width 0.254)
		(layer "F.Cu")
		(net "SH_PVCCFA_EHV_FIVRA_CPU1")
	)
	(segment
		(start 362.49737 -354.065586)
		(end 362.49737 -354.940616)
		(width 0.254)
		(layer "F.Cu")
		(net "SH_PVCCFA_EHV_FIVRA_CPU0_R")
	)
	(segment
		(start 360.454194 -357.276908)
		(end 359.882694 -357.848408)
		(width 0.1778)
		(layer "F.Cu")
		(net "SH_PVCCFA_EHV_FIVRA_CPU0_R")
	)
	(segment
		(start 359.882694 -357.848408)
		(end 359.393236 -357.848408)
		(width 0.1778)
		(layer "F.Cu")
		(net "SH_PVCCFA_EHV_FIVRA_CPU0_R")
	)
	(segment
		(start 361.76077 -355.569012)
		(end 360.621834 -356.707948)
		(width 0.1778)
		(layer "F.Cu")
		(net "SH_PVCCFA_EHV_FIVRA_CPU0_R")
	)
	(segment
		(start 360.621834 -356.87254)
		(end 360.454194 -357.276908)
		(width 0.1778)
		(layer "F.Cu")
		(net "SH_PVCCFA_EHV_FIVRA_CPU0_R")
	)
	(segment
		(start 361.961938 -354.940616)
		(end 361.76077 -354.739448)
		(width 0.254)
		(layer "F.Cu")
		(net "SH_PVCCFA_EHV_FIVRA_CPU0_R")
	)
	(segment
		(start 362.49737 -354.940616)
		(end 361.961938 -354.940616)
		(width 0.254)
		(layer "F.Cu")
		(net "SH_PVCCFA_EHV_FIVRA_CPU0_R")
	)
	(segment
		(start 360.621834 -356.707948)
		(end 360.621834 -356.87254)
		(width 0.1778)
		(layer "F.Cu")
		(net "SH_PVCCFA_EHV_FIVRA_CPU0_R")
	)
	(segment
		(start 361.76077 -354.739448)
		(end 361.76077 -355.569012)
		(width 0.1778)
		(layer "F.Cu")
		(net "SH_PVCCFA_EHV_FIVRA_CPU0_R")
	)
	(via
		(at 361.76077 -354.739448)
		(size 0.508)
		(drill 0.254)
		(layers "F.Cu" "B.Cu")
		(net "SH_PVCCFA_EHV_FIVRA_CPU0_R")
	)
	(segment
		(start 362.49737 -356.158038)
		(end 362.49737 -355.740716)
		(width 0.254)
		(layer "F.Cu")
		(net "SH_PVCCFA_EHV_FIVRA_CPU0")
	)
	(segment
		(start 363.62005 -356.735126)
		(end 363.074458 -356.735126)
		(width 0.254)
		(layer "F.Cu")
		(net "SH_PVCCFA_EHV_FIVRA_CPU0")
	)
	(segment
		(start 363.074458 -356.735126)
		(end 362.49737 -356.158038)
		(width 0.254)
		(layer "F.Cu")
		(net "SH_PVCCFA_EHV_FIVRA_CPU0")
	)
	(segment
		(start 28.659074 -133.018022)
		(end 28.635706 -133.04139)
		(width 0.254)
		(layer "F.Cu")
		(net "SH_PVCCFA_EHV_CPU1_R")
	)
	(segment
		(start 28.659074 -132.431282)
		(end 28.659074 -133.018022)
		(width 0.254)
		(layer "F.Cu")
		(net "SH_PVCCFA_EHV_CPU1_R")
	)
	(segment
		(start 27.595322 -133.030468)
		(end 27.606244 -133.04139)
		(width 0.254)
		(layer "F.Cu")
		(net "SH_PVCCFA_EHV_CPU1_R")
	)
	(segment
		(start 29.075888 -131.31546)
		(end 29.075888 -131.807712)
		(width 0.1778)
		(layer "F.Cu")
		(net "SH_PVCCFA_EHV_CPU1_R")
	)
	(segment
		(start 29.661104 -131.03352)
		(end 29.357828 -131.03352)
		(width 0.1778)
		(layer "F.Cu")
		(net "SH_PVCCFA_EHV_CPU1_R")
	)
	(segment
		(start 29.075888 -132.014468)
		(end 28.659074 -132.431282)
		(width 0.254)
		(layer "F.Cu")
		(net "SH_PVCCFA_EHV_CPU1_R")
	)
	(segment
		(start 29.075888 -131.807712)
		(end 29.075888 -132.014468)
		(width 0.254)
		(layer "F.Cu")
		(net "SH_PVCCFA_EHV_CPU1_R")
	)
	(segment
		(start 27.606244 -133.04139)
		(end 28.635706 -133.04139)
		(width 0.254)
		(layer "F.Cu")
		(net "SH_PVCCFA_EHV_CPU1_R")
	)
	(segment
		(start 29.357828 -131.03352)
		(end 29.075888 -131.31546)
		(width 0.1778)
		(layer "F.Cu")
		(net "SH_PVCCFA_EHV_CPU1_R")
	)
	(segment
		(start 27.595322 -133.830568)
		(end 27.587702 -133.838188)
		(width 0.254)
		(layer "F.Cu")
		(net "SH_PVCCFA_EHV_CPU1")
	)
	(segment
		(start 27.587702 -133.838188)
		(end 27.587702 -135.001)
		(width 0.254)
		(layer "F.Cu")
		(net "SH_PVCCFA_EHV_CPU1")
	)
	(segment
		(start 422.078912 -139.797028)
		(end 421.04945 -139.797028)
		(width 0.254)
		(layer "F.Cu")
		(net "SH_PVCCFA_EHV_CPU0_R")
	)
	(segment
		(start 423.30497 -137.814558)
		(end 423.001694 -137.814558)
		(width 0.1778)
		(layer "F.Cu")
		(net "SH_PVCCFA_EHV_CPU0_R")
	)
	(segment
		(start 422.078912 -139.436348)
		(end 422.078912 -139.797028)
		(width 0.254)
		(layer "F.Cu")
		(net "SH_PVCCFA_EHV_CPU0_R")
	)
	(segment
		(start 422.719754 -138.096498)
		(end 422.719754 -138.58875)
		(width 0.1778)
		(layer "F.Cu")
		(net "SH_PVCCFA_EHV_CPU0_R")
	)
	(segment
		(start 422.719754 -138.58875)
		(end 422.719754 -138.795506)
		(width 0.254)
		(layer "F.Cu")
		(net "SH_PVCCFA_EHV_CPU0_R")
	)
	(segment
		(start 421.04945 -139.797028)
		(end 421.038528 -139.786106)
		(width 0.254)
		(layer "F.Cu")
		(net "SH_PVCCFA_EHV_CPU0_R")
	)
	(segment
		(start 422.719754 -138.795506)
		(end 422.078912 -139.436348)
		(width 0.254)
		(layer "F.Cu")
		(net "SH_PVCCFA_EHV_CPU0_R")
	)
	(segment
		(start 423.001694 -137.814558)
		(end 422.719754 -138.096498)
		(width 0.1778)
		(layer "F.Cu")
		(net "SH_PVCCFA_EHV_CPU0_R")
	)
	(segment
		(start 421.038528 -140.586206)
		(end 421.030908 -140.593826)
		(width 0.254)
		(layer "F.Cu")
		(net "SH_PVCCFA_EHV_CPU0")
	)
	(segment
		(start 421.030908 -140.593826)
		(end 421.030908 -141.756638)
		(width 0.254)
		(layer "F.Cu")
		(net "SH_PVCCFA_EHV_CPU0")
	)
	(segment
		(start 23.601172 -162.60572)
		(end 22.991572 -162.60572)
		(width 0.254)
		(layer "F.Cu")
		(net "SH_PVCCD_HV_CPU1_R")
	)
	(segment
		(start 21.920708 -162.60572)
		(end 22.991572 -162.60572)
		(width 0.254)
		(layer "F.Cu")
		(net "SH_PVCCD_HV_CPU1_R")
	)
	(segment
		(start 25.862788 -162.294316)
		(end 25.741884 -162.173412)
		(width 0.1778)
		(layer "F.Cu")
		(net "SH_PVCCD_HV_CPU1_R")
	)
	(segment
		(start 24.692864 -162.173412)
		(end 24.532844 -162.013392)
		(width 0.254)
		(layer "F.Cu")
		(net "SH_PVCCD_HV_CPU1_R")
	)
	(segment
		(start 25.741884 -162.173412)
		(end 24.692864 -162.173412)
		(width 0.1778)
		(layer "F.Cu")
		(net "SH_PVCCD_HV_CPU1_R")
	)
	(segment
		(start 24.532844 -162.013392)
		(end 24.1935 -162.013392)
		(width 0.254)
		(layer "F.Cu")
		(net "SH_PVCCD_HV_CPU1_R")
	)
	(segment
		(start 24.1935 -162.013392)
		(end 23.601172 -162.60572)
		(width 0.254)
		(layer "F.Cu")
		(net "SH_PVCCD_HV_CPU1_R")
	)
	(segment
		(start 25.862788 -162.427158)
		(end 25.862788 -162.294316)
		(width 0.1778)
		(layer "F.Cu")
		(net "SH_PVCCD_HV_CPU1_R")
	)
	(via
		(at 24.1935 -162.013392)
		(size 0.762)
		(drill 0.381)
		(layers "F.Cu" "B.Cu")
		(net "SH_PVCCD_HV_CPU1_R")
	)
	(segment
		(start 20.809966 -161.80562)
		(end 20.802346 -161.81324)
		(width 0.254)
		(layer "F.Cu")
		(net "SH_PVCCD_HV_CPU1")
	)
	(segment
		(start 21.920708 -161.80562)
		(end 20.809966 -161.80562)
		(width 0.254)
		(layer "F.Cu")
		(net "SH_PVCCD_HV_CPU1")
	)
	(segment
		(start 434.301138 -125.908816)
		(end 435.24297 -126.850648)
		(width 0.1778)
		(layer "F.Cu")
		(net "SH_PVCCD_HV_CPU0_R")
	)
	(segment
		(start 435.28107 -126.837948)
		(end 436.282084 -126.837948)
		(width 0.254)
		(layer "F.Cu")
		(net "SH_PVCCD_HV_CPU0_R")
	)
	(segment
		(start 436.282084 -126.837948)
		(end 436.292244 -126.848108)
		(width 0.254)
		(layer "F.Cu")
		(net "SH_PVCCD_HV_CPU0_R")
	)
	(segment
		(start 435.26837 -126.850648)
		(end 435.28107 -126.837948)
		(width 0.254)
		(layer "F.Cu")
		(net "SH_PVCCD_HV_CPU0_R")
	)
	(segment
		(start 435.24297 -126.850648)
		(end 435.26837 -126.850648)
		(width 0.1778)
		(layer "F.Cu")
		(net "SH_PVCCD_HV_CPU0_R")
	)
	(segment
		(start 434.301138 -125.388624)
		(end 434.301138 -125.908816)
		(width 0.1778)
		(layer "F.Cu")
		(net "SH_PVCCD_HV_CPU0_R")
	)
	(segment
		(start 436.337964 -127.693928)
		(end 436.337964 -128.877314)
		(width 0.254)
		(layer "F.Cu")
		(net "SH_PVCCD_HV_CPU0")
	)
	(segment
		(start 436.292244 -127.648208)
		(end 436.337964 -127.693928)
		(width 0.254)
		(layer "F.Cu")
		(net "SH_PVCCD_HV_CPU0")
	)
	(segment
		(start 261.37235 -77.549502)
		(end 261.708646 -77.885798)
		(width 0.254)
		(layer "F.Cu")
		(net "SH_P1V05_PCH_AUX_P")
	)
	(segment
		(start 263.214612 -78.077822)
		(end 262.134604 -78.077822)
		(width 0.254)
		(layer "F.Cu")
		(net "SH_P1V05_PCH_AUX_P")
	)
	(segment
		(start 262.134604 -78.077822)
		(end 261.94258 -77.885798)
		(width 0.254)
		(layer "F.Cu")
		(net "SH_P1V05_PCH_AUX_P")
	)
	(segment
		(start 260.961632 -77.549502)
		(end 261.37235 -77.549502)
		(width 0.254)
		(layer "F.Cu")
		(net "SH_P1V05_PCH_AUX_P")
	)
	(segment
		(start 260.961632 -76.533502)
		(end 260.961632 -77.549502)
		(width 0.254)
		(layer "F.Cu")
		(net "SH_P1V05_PCH_AUX_P")
	)
	(segment
		(start 261.708646 -77.885798)
		(end 261.94258 -77.885798)
		(width 0.254)
		(layer "F.Cu")
		(net "SH_P1V05_PCH_AUX_P")
	)
	(via
		(at 263.214612 -78.077822)
		(size 0.508)
		(drill 0.254)
		(layers "F.Cu" "B.Cu")
		(net "SH_P1V05_PCH_AUX_P")
	)
	(segment
		(start 261.745476 -78.68285)
		(end 262.048244 -78.985618)
		(width 0.254)
		(layer "B.Cu")
		(net "SH_P1V05_PCH_AUX_P")
	)
	(segment
		(start 265.456924 -78.985618)
		(end 266.156694 -78.285848)
		(width 0.254)
		(layer "B.Cu")
		(net "SH_P1V05_PCH_AUX_P")
	)
	(segment
		(start 317.06566 -72.809608)
		(end 322.55206 -72.809608)
		(width 0.254)
		(layer "B.Cu")
		(net "SH_P1V05_PCH_AUX_P")
	)
	(segment
		(start 263.051036 -77.914246)
		(end 261.988808 -77.914246)
		(width 0.254)
		(layer "B.Cu")
		(net "SH_P1V05_PCH_AUX_P")
	)
	(segment
		(start 299.790358 -80.843628)
		(end 302.348138 -78.285848)
		(width 0.254)
		(layer "B.Cu")
		(net "SH_P1V05_PCH_AUX_P")
	)
	(segment
		(start 324.43547 -74.058272)
		(end 324.939406 -73.554336)
		(width 0.254)
		(layer "B.Cu")
		(net "SH_P1V05_PCH_AUX_P")
	)
	(segment
		(start 261.988808 -77.914246)
		(end 261.745476 -78.157578)
		(width 0.254)
		(layer "B.Cu")
		(net "SH_P1V05_PCH_AUX_P")
	)
	(segment
		(start 311.58942 -78.285848)
		(end 317.06566 -72.809608)
		(width 0.254)
		(layer "B.Cu")
		(net "SH_P1V05_PCH_AUX_P")
	)
	(segment
		(start 262.048244 -78.985618)
		(end 265.456924 -78.985618)
		(width 0.254)
		(layer "B.Cu")
		(net "SH_P1V05_PCH_AUX_P")
	)
	(segment
		(start 263.214612 -78.077822)
		(end 263.051036 -77.914246)
		(width 0.254)
		(layer "B.Cu")
		(net "SH_P1V05_PCH_AUX_P")
	)
	(segment
		(start 324.939406 -73.554336)
		(end 324.939406 -73.499472)
		(width 0.254)
		(layer "B.Cu")
		(net "SH_P1V05_PCH_AUX_P")
	)
	(segment
		(start 288.486596 -80.843628)
		(end 299.790358 -80.843628)
		(width 0.254)
		(layer "B.Cu")
		(net "SH_P1V05_PCH_AUX_P")
	)
	(segment
		(start 261.745476 -78.157578)
		(end 261.745476 -78.68285)
		(width 0.254)
		(layer "B.Cu")
		(net "SH_P1V05_PCH_AUX_P")
	)
	(segment
		(start 302.348138 -78.285848)
		(end 311.58942 -78.285848)
		(width 0.254)
		(layer "B.Cu")
		(net "SH_P1V05_PCH_AUX_P")
	)
	(segment
		(start 285.928816 -78.285848)
		(end 288.486596 -80.843628)
		(width 0.254)
		(layer "B.Cu")
		(net "SH_P1V05_PCH_AUX_P")
	)
	(segment
		(start 322.55206 -72.809608)
		(end 323.800724 -74.058272)
		(width 0.254)
		(layer "B.Cu")
		(net "SH_P1V05_PCH_AUX_P")
	)
	(segment
		(start 323.800724 -74.058272)
		(end 324.43547 -74.058272)
		(width 0.254)
		(layer "B.Cu")
		(net "SH_P1V05_PCH_AUX_P")
	)
	(segment
		(start 266.156694 -78.285848)
		(end 285.928816 -78.285848)
		(width 0.254)
		(layer "B.Cu")
		(net "SH_P1V05_PCH_AUX_P")
	)
	(segment
		(start 261.474966 -76.01839)
		(end 261.88035 -76.01839)
		(width 0.254)
		(layer "F.Cu")
		(net "SH_P1V05_PCH_AUX_N")
	)
	(segment
		(start 261.915402 -77.085698)
		(end 261.88035 -77.050646)
		(width 0.254)
		(layer "F.Cu")
		(net "SH_P1V05_PCH_AUX_N")
	)
	(segment
		(start 261.258558 -73.918572)
		(end 260.890766 -74.806556)
		(width 0.254)
		(layer "F.Cu")
		(net "SH_P1V05_PCH_AUX_N")
	)
	(segment
		(start 261.88035 -76.100686)
		(end 261.88035 -76.01839)
		(width 0.254)
		(layer "F.Cu")
		(net "SH_P1V05_PCH_AUX_N")
	)
	(segment
		(start 260.890766 -75.43419)
		(end 260.961632 -75.505056)
		(width 0.254)
		(layer "F.Cu")
		(net "SH_P1V05_PCH_AUX_N")
	)
	(segment
		(start 261.94258 -77.085698)
		(end 261.915402 -77.085698)
		(width 0.254)
		(layer "F.Cu")
		(net "SH_P1V05_PCH_AUX_N")
	)
	(segment
		(start 260.890766 -74.806556)
		(end 260.890766 -75.43419)
		(width 0.254)
		(layer "F.Cu")
		(net "SH_P1V05_PCH_AUX_N")
	)
	(segment
		(start 261.88035 -77.050646)
		(end 261.88035 -76.100686)
		(width 0.254)
		(layer "F.Cu")
		(net "SH_P1V05_PCH_AUX_N")
	)
	(segment
		(start 261.373112 -75.916536)
		(end 260.961632 -75.505056)
		(width 0.254)
		(layer "F.Cu")
		(net "SH_P1V05_PCH_AUX_N")
	)
	(segment
		(start 261.304532 -73.807574)
		(end 261.258558 -73.918572)
		(width 0.12954)
		(layer "F.Cu")
		(net "SH_P1V05_PCH_AUX_N")
	)
	(segment
		(start 261.373112 -75.916536)
		(end 261.474966 -76.01839)
		(width 0.254)
		(layer "F.Cu")
		(net "SH_P1V05_PCH_AUX_N")
	)
	(segment
		(start 261.304532 -72.841104)
		(end 261.304532 -73.807574)
		(width 0.12954)
		(layer "F.Cu")
		(net "SH_P1V05_PCH_AUX_N")
	)
	(segment
		(start 263.214612 -77.214222)
		(end 262.071104 -77.214222)
		(width 0.254)
		(layer "F.Cu")
		(net "SH_P1V05_PCH_AUX_N")
	)
	(segment
		(start 262.071104 -77.214222)
		(end 261.94258 -77.085698)
		(width 0.254)
		(layer "F.Cu")
		(net "SH_P1V05_PCH_AUX_N")
	)
	(via
		(at 263.214612 -77.214222)
		(size 0.762)
		(drill 0.254)
		(layers "F.Cu" "B.Cu")
		(net "SH_P1V05_PCH_AUX_N")
	)
	(segment
		(start 261.364476 -78.840838)
		(end 261.890256 -79.366618)
		(width 0.254)
		(layer "B.Cu")
		(net "SH_P1V05_PCH_AUX_N")
	)
	(segment
		(start 261.828788 -77.533246)
		(end 261.364476 -77.997558)
		(width 0.254)
		(layer "B.Cu")
		(net "SH_P1V05_PCH_AUX_N")
	)
	(segment
		(start 302.506126 -78.666848)
		(end 311.747662 -78.666848)
		(width 0.254)
		(layer "B.Cu")
		(net "SH_P1V05_PCH_AUX_N")
	)
	(segment
		(start 299.948346 -81.224628)
		(end 302.506126 -78.666848)
		(width 0.254)
		(layer "B.Cu")
		(net "SH_P1V05_PCH_AUX_N")
	)
	(segment
		(start 285.770828 -78.666848)
		(end 288.328608 -81.224628)
		(width 0.254)
		(layer "B.Cu")
		(net "SH_P1V05_PCH_AUX_N")
	)
	(segment
		(start 265.614912 -79.366618)
		(end 266.314682 -78.666848)
		(width 0.254)
		(layer "B.Cu")
		(net "SH_P1V05_PCH_AUX_N")
	)
	(segment
		(start 266.314682 -78.666848)
		(end 285.770828 -78.666848)
		(width 0.254)
		(layer "B.Cu")
		(net "SH_P1V05_PCH_AUX_N")
	)
	(segment
		(start 262.895588 -77.533246)
		(end 261.828788 -77.533246)
		(width 0.254)
		(layer "B.Cu")
		(net "SH_P1V05_PCH_AUX_N")
	)
	(segment
		(start 261.364476 -77.997558)
		(end 261.364476 -78.840838)
		(width 0.254)
		(layer "B.Cu")
		(net "SH_P1V05_PCH_AUX_N")
	)
	(segment
		(start 263.214612 -77.214222)
		(end 262.895588 -77.533246)
		(width 0.254)
		(layer "B.Cu")
		(net "SH_P1V05_PCH_AUX_N")
	)
	(segment
		(start 261.890256 -79.366618)
		(end 265.614912 -79.366618)
		(width 0.254)
		(layer "B.Cu")
		(net "SH_P1V05_PCH_AUX_N")
	)
	(segment
		(start 322.394072 -73.190608)
		(end 323.642736 -74.439272)
		(width 0.254)
		(layer "B.Cu")
		(net "SH_P1V05_PCH_AUX_N")
	)
	(segment
		(start 311.747662 -78.666848)
		(end 317.223902 -73.190608)
		(width 0.254)
		(layer "B.Cu")
		(net "SH_P1V05_PCH_AUX_N")
	)
	(segment
		(start 317.223902 -73.190608)
		(end 322.394072 -73.190608)
		(width 0.254)
		(layer "B.Cu")
		(net "SH_P1V05_PCH_AUX_N")
	)
	(segment
		(start 288.328608 -81.224628)
		(end 299.948346 -81.224628)
		(width 0.254)
		(layer "B.Cu")
		(net "SH_P1V05_PCH_AUX_N")
	)
	(segment
		(start 323.642736 -74.439272)
		(end 324.507606 -74.439272)
		(width 0.254)
		(layer "B.Cu")
		(net "SH_P1V05_PCH_AUX_N")
	)
	(segment
		(start 324.507606 -74.439272)
		(end 324.939406 -74.871072)
		(width 0.254)
		(layer "B.Cu")
		(net "SH_P1V05_PCH_AUX_N")
	)
	(segment
		(start 451.36181 -11.26998)
		(end 451.36181 -12.35583)
		(width 0.12954)
		(layer "F.Cu")
		(net "SGPIO_OCP_SFF_LD_N")
	)
	(segment
		(start 451.36181 -12.35583)
		(end 451.300596 -12.417044)
		(width 0.12954)
		(layer "F.Cu")
		(net "SGPIO_OCP_SFF_LD_N")
	)
	(segment
		(start 363.52607 -78.589378)
		(end 355.29012 -86.825328)
		(width 0.12954)
		(layer "F.Cu")
		(net "SGPIO_OCP_SFF_LD_N")
	)
	(segment
		(start 451.300596 -13.588492)
		(end 451.28434 -13.604748)
		(width 0.12954)
		(layer "F.Cu")
		(net "SGPIO_OCP_SFF_LD_N")
	)
	(segment
		(start 303.07788 -82.464148)
		(end 284.5943 -82.464148)
		(width 0.12954)
		(layer "F.Cu")
		(net "SGPIO_OCP_SFF_LD_N")
	)
	(segment
		(start 284.5943 -82.464148)
		(end 277.90902 -75.778868)
		(width 0.12954)
		(layer "F.Cu")
		(net "SGPIO_OCP_SFF_LD_N")
	)
	(segment
		(start 172.555662 -116.975382)
		(end 172.155612 -117.375432)
		(width 0.12954)
		(layer "F.Cu")
		(net "SGPIO_OCP_SFF_LD_N")
	)
	(segment
		(start 307.43906 -86.825328)
		(end 303.07788 -82.464148)
		(width 0.12954)
		(layer "F.Cu")
		(net "SGPIO_OCP_SFF_LD_N")
	)
	(segment
		(start 355.29012 -86.825328)
		(end 307.43906 -86.825328)
		(width 0.12954)
		(layer "F.Cu")
		(net "SGPIO_OCP_SFF_LD_N")
	)
	(segment
		(start 451.300596 -12.417044)
		(end 451.300596 -13.588492)
		(width 0.12954)
		(layer "F.Cu")
		(net "SGPIO_OCP_SFF_LD_N")
	)
	(segment
		(start 364.82909 -78.589378)
		(end 363.52607 -78.589378)
		(width 0.12954)
		(layer "F.Cu")
		(net "SGPIO_OCP_SFF_LD_N")
	)
	(via
		(at 277.90902 -75.778868)
		(size 0.508)
		(drill 0.254)
		(layers "F.Cu" "B.Cu")
		(net "SGPIO_OCP_SFF_LD_N")
	)
	(via
		(at 364.82909 -78.589378)
		(size 0.508)
		(drill 0.254)
		(layers "F.Cu" "B.Cu")
		(net "SGPIO_OCP_SFF_LD_N")
	)
	(via
		(at 451.28434 -13.604748)
		(size 0.508)
		(drill 0.254)
		(layers "F.Cu" "B.Cu")
		(net "SGPIO_OCP_SFF_LD_N")
	)
	(via
		(at 172.155612 -117.375432)
		(size 0.4572)
		(drill 0.254)
		(layers "F.Cu" "B.Cu")
		(net "SGPIO_OCP_SFF_LD_N")
	)
	(segment
		(start 451.28434 -13.604748)
		(end 451.28434 -12.786868)
		(width 0.12954)
		(layer "B.Cu")
		(net "SGPIO_OCP_SFF_LD_N")
	)
	(segment
		(start 451.28434 -12.786868)
		(end 452.62546 -11.445748)
		(width 0.12954)
		(layer "B.Cu")
		(net "SGPIO_OCP_SFF_LD_N")
	)
	(segment
		(start 452.62546 -11.445748)
		(end 452.62546 -11.00582)
		(width 0.12954)
		(layer "B.Cu")
		(net "SGPIO_OCP_SFF_LD_N")
	)
	(segment
		(start 423.836338 -51.864006)
		(end 418.83584 -56.864504)
		(width 0.127)
		(layer "In6.Cu")
		(net "SGPIO_OCP_SFF_LD_N")
	)
	(segment
		(start 431.916586 -43.79722)
		(end 431.916586 -45.790104)
		(width 0.127)
		(layer "In6.Cu")
		(net "SGPIO_OCP_SFF_LD_N")
	)
	(segment
		(start 397.90497 -82.560668)
		(end 368.80038 -82.560668)
		(width 0.127)
		(layer "In6.Cu")
		(net "SGPIO_OCP_SFF_LD_N")
	)
	(segment
		(start 418.83584 -56.864504)
		(end 418.83584 -61.629798)
		(width 0.127)
		(layer "In6.Cu")
		(net "SGPIO_OCP_SFF_LD_N")
	)
	(segment
		(start 418.83584 -61.629798)
		(end 397.90497 -82.560668)
		(width 0.127)
		(layer "In6.Cu")
		(net "SGPIO_OCP_SFF_LD_N")
	)
	(segment
		(start 452.58482 -39.873428)
		(end 439.300112 -39.873428)
		(width 0.127)
		(layer "In6.Cu")
		(net "SGPIO_OCP_SFF_LD_N")
	)
	(segment
		(start 457.0857 -35.372548)
		(end 452.58482 -39.873428)
		(width 0.127)
		(layer "In6.Cu")
		(net "SGPIO_OCP_SFF_LD_N")
	)
	(segment
		(start 431.916586 -45.790104)
		(end 425.842684 -51.864006)
		(width 0.127)
		(layer "In6.Cu")
		(net "SGPIO_OCP_SFF_LD_N")
	)
	(segment
		(start 436.32374 -42.8498)
		(end 432.864006 -42.8498)
		(width 0.127)
		(layer "In6.Cu")
		(net "SGPIO_OCP_SFF_LD_N")
	)
	(segment
		(start 453.9869 -13.360908)
		(end 457.0857 -16.459708)
		(width 0.127)
		(layer "In6.Cu")
		(net "SGPIO_OCP_SFF_LD_N")
	)
	(segment
		(start 439.300112 -39.873428)
		(end 436.32374 -42.8498)
		(width 0.127)
		(layer "In6.Cu")
		(net "SGPIO_OCP_SFF_LD_N")
	)
	(segment
		(start 457.0857 -16.459708)
		(end 457.0857 -35.372548)
		(width 0.127)
		(layer "In6.Cu")
		(net "SGPIO_OCP_SFF_LD_N")
	)
	(segment
		(start 432.864006 -42.8498)
		(end 431.916586 -43.79722)
		(width 0.127)
		(layer "In6.Cu")
		(net "SGPIO_OCP_SFF_LD_N")
	)
	(segment
		(start 368.80038 -82.560668)
		(end 364.82909 -78.589378)
		(width 0.127)
		(layer "In6.Cu")
		(net "SGPIO_OCP_SFF_LD_N")
	)
	(segment
		(start 451.28434 -13.604748)
		(end 451.52818 -13.360908)
		(width 0.127)
		(layer "In6.Cu")
		(net "SGPIO_OCP_SFF_LD_N")
	)
	(segment
		(start 425.842684 -51.864006)
		(end 423.836338 -51.864006)
		(width 0.127)
		(layer "In6.Cu")
		(net "SGPIO_OCP_SFF_LD_N")
	)
	(segment
		(start 451.52818 -13.360908)
		(end 453.9869 -13.360908)
		(width 0.127)
		(layer "In6.Cu")
		(net "SGPIO_OCP_SFF_LD_N")
	)
	(segment
		(start 167.45458 -108.234734)
		(end 167.32758 -108.361734)
		(width 0.127)
		(layer "In13.Cu")
		(net "SGPIO_OCP_SFF_LD_N")
	)
	(segment
		(start 170.321478 -112.968532)
		(end 171.515532 -112.968532)
		(width 0.127)
		(layer "In13.Cu")
		(net "SGPIO_OCP_SFF_LD_N")
	)
	(segment
		(start 181.066694 -83.513168)
		(end 175.828706 -88.751156)
		(width 0.127)
		(layer "In13.Cu")
		(net "SGPIO_OCP_SFF_LD_N")
	)
	(segment
		(start 166.97198 -107.726734)
		(end 167.32758 -107.726734)
		(width 0.127)
		(layer "In13.Cu")
		(net "SGPIO_OCP_SFF_LD_N")
	)
	(segment
		(start 169.12209 -111.769144)
		(end 169.135552 -111.782606)
		(width 0.127)
		(layer "In13.Cu")
		(net "SGPIO_OCP_SFF_LD_N")
	)
	(segment
		(start 169.048176 -111.769144)
		(end 169.12209 -111.769144)
		(width 0.127)
		(layer "In13.Cu")
		(net "SGPIO_OCP_SFF_LD_N")
	)
	(segment
		(start 277.90902 -77.130402)
		(end 277.31593 -77.723492)
		(width 0.127)
		(layer "In13.Cu")
		(net "SGPIO_OCP_SFF_LD_N")
	)
	(segment
		(start 231.12984 -74.567288)
		(end 222.18396 -83.513168)
		(width 0.127)
		(layer "In13.Cu")
		(net "SGPIO_OCP_SFF_LD_N")
	)
	(segment
		(start 169.752772 -111.782606)
		(end 169.982896 -112.01273)
		(width 0.127)
		(layer "In13.Cu")
		(net "SGPIO_OCP_SFF_LD_N")
	)
	(segment
		(start 166.84498 -109.565948)
		(end 169.048176 -111.769144)
		(width 0.127)
		(layer "In13.Cu")
		(net "SGPIO_OCP_SFF_LD_N")
	)
	(segment
		(start 277.90902 -75.778868)
		(end 277.90902 -77.130402)
		(width 0.127)
		(layer "In13.Cu")
		(net "SGPIO_OCP_SFF_LD_N")
	)
	(segment
		(start 168.59758 -88.751156)
		(end 167.823134 -89.525602)
		(width 0.127)
		(layer "In13.Cu")
		(net "SGPIO_OCP_SFF_LD_N")
	)
	(segment
		(start 273.651472 -81.38795)
		(end 247.0277 -81.38795)
		(width 0.127)
		(layer "In13.Cu")
		(net "SGPIO_OCP_SFF_LD_N")
	)
	(segment
		(start 175.828706 -88.751156)
		(end 168.59758 -88.751156)
		(width 0.127)
		(layer "In13.Cu")
		(net "SGPIO_OCP_SFF_LD_N")
	)
	(segment
		(start 166.84498 -107.599734)
		(end 166.97198 -107.726734)
		(width 0.127)
		(layer "In13.Cu")
		(net "SGPIO_OCP_SFF_LD_N")
	)
	(segment
		(start 166.84498 -108.488734)
		(end 166.84498 -109.565948)
		(width 0.127)
		(layer "In13.Cu")
		(net "SGPIO_OCP_SFF_LD_N")
	)
	(segment
		(start 169.982896 -112.01273)
		(end 169.982896 -112.62995)
		(width 0.127)
		(layer "In13.Cu")
		(net "SGPIO_OCP_SFF_LD_N")
	)
	(segment
		(start 222.18396 -83.513168)
		(end 181.066694 -83.513168)
		(width 0.127)
		(layer "In13.Cu")
		(net "SGPIO_OCP_SFF_LD_N")
	)
	(segment
		(start 167.32758 -107.726734)
		(end 167.45458 -107.853734)
		(width 0.127)
		(layer "In13.Cu")
		(net "SGPIO_OCP_SFF_LD_N")
	)
	(segment
		(start 247.0277 -81.38795)
		(end 240.207038 -74.567288)
		(width 0.127)
		(layer "In13.Cu")
		(net "SGPIO_OCP_SFF_LD_N")
	)
	(segment
		(start 171.75988 -113.21288)
		(end 171.75988 -116.9797)
		(width 0.127)
		(layer "In13.Cu")
		(net "SGPIO_OCP_SFF_LD_N")
	)
	(segment
		(start 166.84498 -99.736148)
		(end 166.84498 -107.599734)
		(width 0.127)
		(layer "In13.Cu")
		(net "SGPIO_OCP_SFF_LD_N")
	)
	(segment
		(start 277.31593 -77.902816)
		(end 277.566628 -78.153768)
		(width 0.127)
		(layer "In13.Cu")
		(net "SGPIO_OCP_SFF_LD_N")
	)
	(segment
		(start 169.982896 -112.62995)
		(end 170.321478 -112.968532)
		(width 0.127)
		(layer "In13.Cu")
		(net "SGPIO_OCP_SFF_LD_N")
	)
	(segment
		(start 277.31593 -77.723492)
		(end 277.31593 -77.902816)
		(width 0.127)
		(layer "In13.Cu")
		(net "SGPIO_OCP_SFF_LD_N")
	)
	(segment
		(start 171.515532 -112.968532)
		(end 171.75988 -113.21288)
		(width 0.127)
		(layer "In13.Cu")
		(net "SGPIO_OCP_SFF_LD_N")
	)
	(segment
		(start 167.45458 -107.853734)
		(end 167.45458 -108.234734)
		(width 0.127)
		(layer "In13.Cu")
		(net "SGPIO_OCP_SFF_LD_N")
	)
	(segment
		(start 171.75988 -116.9797)
		(end 172.155612 -117.375432)
		(width 0.127)
		(layer "In13.Cu")
		(net "SGPIO_OCP_SFF_LD_N")
	)
	(segment
		(start 277.259288 -78.461108)
		(end 277.00859 -78.210156)
		(width 0.127)
		(layer "In13.Cu")
		(net "SGPIO_OCP_SFF_LD_N")
	)
	(segment
		(start 167.32758 -108.361734)
		(end 166.97198 -108.361734)
		(width 0.127)
		(layer "In13.Cu")
		(net "SGPIO_OCP_SFF_LD_N")
	)
	(segment
		(start 277.566628 -78.333092)
		(end 277.438612 -78.461108)
		(width 0.127)
		(layer "In13.Cu")
		(net "SGPIO_OCP_SFF_LD_N")
	)
	(segment
		(start 240.207038 -74.567288)
		(end 231.12984 -74.567288)
		(width 0.127)
		(layer "In13.Cu")
		(net "SGPIO_OCP_SFF_LD_N")
	)
	(segment
		(start 277.438612 -78.461108)
		(end 277.259288 -78.461108)
		(width 0.127)
		(layer "In13.Cu")
		(net "SGPIO_OCP_SFF_LD_N")
	)
	(segment
		(start 277.00859 -78.210156)
		(end 276.829266 -78.210156)
		(width 0.127)
		(layer "In13.Cu")
		(net "SGPIO_OCP_SFF_LD_N")
	)
	(segment
		(start 167.823134 -98.757994)
		(end 166.84498 -99.736148)
		(width 0.127)
		(layer "In13.Cu")
		(net "SGPIO_OCP_SFF_LD_N")
	)
	(segment
		(start 277.566628 -78.153768)
		(end 277.566628 -78.333092)
		(width 0.127)
		(layer "In13.Cu")
		(net "SGPIO_OCP_SFF_LD_N")
	)
	(segment
		(start 167.823134 -89.525602)
		(end 167.823134 -98.757994)
		(width 0.127)
		(layer "In13.Cu")
		(net "SGPIO_OCP_SFF_LD_N")
	)
	(segment
		(start 276.829266 -78.210156)
		(end 273.651472 -81.38795)
		(width 0.127)
		(layer "In13.Cu")
		(net "SGPIO_OCP_SFF_LD_N")
	)
	(segment
		(start 166.97198 -108.361734)
		(end 166.84498 -108.488734)
		(width 0.127)
		(layer "In13.Cu")
		(net "SGPIO_OCP_SFF_LD_N")
	)
	(segment
		(start 169.135552 -111.782606)
		(end 169.752772 -111.782606)
		(width 0.127)
		(layer "In13.Cu")
		(net "SGPIO_OCP_SFF_LD_N")
	)
	(segment
		(start 302.520096 -83.810602)
		(end 283.573474 -83.810602)
		(width 0.12954)
		(layer "F.Cu")
		(net "SGPIO_OCP_SFF_DATAOUT")
	)
	(segment
		(start 276.00402 -76.241148)
		(end 276.00402 -75.778868)
		(width 0.12954)
		(layer "F.Cu")
		(net "SGPIO_OCP_SFF_DATAOUT")
	)
	(segment
		(start 364.77448 -80.841088)
		(end 363.178598 -80.841088)
		(width 0.12954)
		(layer "F.Cu")
		(net "SGPIO_OCP_SFF_DATAOUT")
	)
	(segment
		(start 170.084496 -116.975382)
		(end 170.155616 -116.975382)
		(width 0.12954)
		(layer "F.Cu")
		(net "SGPIO_OCP_SFF_DATAOUT")
	)
	(segment
		(start 450.030596 -12.417044)
		(end 450.030596 -13.635228)
		(width 0.12954)
		(layer "F.Cu")
		(net "SGPIO_OCP_SFF_DATAOUT")
	)
	(segment
		(start 283.573474 -83.810602)
		(end 276.00402 -76.241148)
		(width 0.12954)
		(layer "F.Cu")
		(net "SGPIO_OCP_SFF_DATAOUT")
	)
	(segment
		(start 450.161914 -11.26998)
		(end 450.161914 -12.285726)
		(width 0.12954)
		(layer "F.Cu")
		(net "SGPIO_OCP_SFF_DATAOUT")
	)
	(segment
		(start 363.178598 -80.841088)
		(end 355.847904 -88.171782)
		(width 0.12954)
		(layer "F.Cu")
		(net "SGPIO_OCP_SFF_DATAOUT")
	)
	(segment
		(start 450.161914 -12.285726)
		(end 450.030596 -12.417044)
		(width 0.12954)
		(layer "F.Cu")
		(net "SGPIO_OCP_SFF_DATAOUT")
	)
	(segment
		(start 169.689018 -117.37086)
		(end 170.084496 -116.975382)
		(width 0.12954)
		(layer "F.Cu")
		(net "SGPIO_OCP_SFF_DATAOUT")
	)
	(segment
		(start 306.881276 -88.171782)
		(end 302.520096 -83.810602)
		(width 0.12954)
		(layer "F.Cu")
		(net "SGPIO_OCP_SFF_DATAOUT")
	)
	(segment
		(start 355.847904 -88.171782)
		(end 306.881276 -88.171782)
		(width 0.12954)
		(layer "F.Cu")
		(net "SGPIO_OCP_SFF_DATAOUT")
	)
	(via
		(at 364.77448 -80.841088)
		(size 0.508)
		(drill 0.254)
		(layers "F.Cu" "B.Cu")
		(net "SGPIO_OCP_SFF_DATAOUT")
	)
	(via
		(at 169.689018 -117.37086)
		(size 0.4572)
		(drill 0.254)
		(layers "F.Cu" "B.Cu")
		(net "SGPIO_OCP_SFF_DATAOUT")
	)
	(via
		(at 450.030596 -13.635228)
		(size 0.508)
		(drill 0.254)
		(layers "F.Cu" "B.Cu")
		(net "SGPIO_OCP_SFF_DATAOUT")
	)
	(via
		(at 276.00402 -75.778868)
		(size 0.508)
		(drill 0.254)
		(layers "F.Cu" "B.Cu")
		(net "SGPIO_OCP_SFF_DATAOUT")
	)
	(segment
		(start 450.030596 -13.635228)
		(end 450.09054 -13.575284)
		(width 0.12954)
		(layer "B.Cu")
		(net "SGPIO_OCP_SFF_DATAOUT")
	)
	(segment
		(start 450.09054 -13.575284)
		(end 450.09054 -12.322048)
		(width 0.12954)
		(layer "B.Cu")
		(net "SGPIO_OCP_SFF_DATAOUT")
	)
	(segment
		(start 450.09054 -12.322048)
		(end 450.482716 -11.929872)
		(width 0.12954)
		(layer "B.Cu")
		(net "SGPIO_OCP_SFF_DATAOUT")
	)
	(segment
		(start 450.482716 -11.929872)
		(end 450.482716 -10.994136)
		(width 0.12954)
		(layer "B.Cu")
		(net "SGPIO_OCP_SFF_DATAOUT")
	)
	(segment
		(start 420.01186 -57.35193)
		(end 420.01186 -62.117224)
		(width 0.127)
		(layer "In6.Cu")
		(net "SGPIO_OCP_SFF_DATAOUT")
	)
	(segment
		(start 458.26172 -35.859974)
		(end 453.072246 -41.049448)
		(width 0.127)
		(layer "In6.Cu")
		(net "SGPIO_OCP_SFF_DATAOUT")
	)
	(segment
		(start 450.030596 -12.635992)
		(end 450.72808 -11.938508)
		(width 0.127)
		(layer "In6.Cu")
		(net "SGPIO_OCP_SFF_DATAOUT")
	)
	(segment
		(start 453.072246 -41.049448)
		(end 439.789316 -41.049448)
		(width 0.127)
		(layer "In6.Cu")
		(net "SGPIO_OCP_SFF_DATAOUT")
	)
	(segment
		(start 454.3425 -11.938508)
		(end 458.26172 -15.857728)
		(width 0.127)
		(layer "In6.Cu")
		(net "SGPIO_OCP_SFF_DATAOUT")
	)
	(segment
		(start 365.20374 -80.841088)
		(end 364.77448 -80.841088)
		(width 0.127)
		(layer "In6.Cu")
		(net "SGPIO_OCP_SFF_DATAOUT")
	)
	(segment
		(start 450.030596 -13.635228)
		(end 450.030596 -12.635992)
		(width 0.127)
		(layer "In6.Cu")
		(net "SGPIO_OCP_SFF_DATAOUT")
	)
	(segment
		(start 433.951634 -43.825668)
		(end 433.092606 -44.684696)
		(width 0.127)
		(layer "In6.Cu")
		(net "SGPIO_OCP_SFF_DATAOUT")
	)
	(segment
		(start 437.013096 -43.825668)
		(end 433.951634 -43.825668)
		(width 0.127)
		(layer "In6.Cu")
		(net "SGPIO_OCP_SFF_DATAOUT")
	)
	(segment
		(start 433.092606 -44.684696)
		(end 433.092606 -46.27753)
		(width 0.127)
		(layer "In6.Cu")
		(net "SGPIO_OCP_SFF_DATAOUT")
	)
	(segment
		(start 426.33011 -53.040026)
		(end 424.323764 -53.040026)
		(width 0.127)
		(layer "In6.Cu")
		(net "SGPIO_OCP_SFF_DATAOUT")
	)
	(segment
		(start 420.01186 -62.117224)
		(end 398.392396 -83.736688)
		(width 0.127)
		(layer "In6.Cu")
		(net "SGPIO_OCP_SFF_DATAOUT")
	)
	(segment
		(start 398.392396 -83.736688)
		(end 368.09934 -83.736688)
		(width 0.127)
		(layer "In6.Cu")
		(net "SGPIO_OCP_SFF_DATAOUT")
	)
	(segment
		(start 450.72808 -11.938508)
		(end 454.3425 -11.938508)
		(width 0.127)
		(layer "In6.Cu")
		(net "SGPIO_OCP_SFF_DATAOUT")
	)
	(segment
		(start 433.092606 -46.27753)
		(end 426.33011 -53.040026)
		(width 0.127)
		(layer "In6.Cu")
		(net "SGPIO_OCP_SFF_DATAOUT")
	)
	(segment
		(start 439.789316 -41.049448)
		(end 437.013096 -43.825668)
		(width 0.127)
		(layer "In6.Cu")
		(net "SGPIO_OCP_SFF_DATAOUT")
	)
	(segment
		(start 368.09934 -83.736688)
		(end 365.20374 -80.841088)
		(width 0.127)
		(layer "In6.Cu")
		(net "SGPIO_OCP_SFF_DATAOUT")
	)
	(segment
		(start 458.26172 -15.857728)
		(end 458.26172 -35.859974)
		(width 0.127)
		(layer "In6.Cu")
		(net "SGPIO_OCP_SFF_DATAOUT")
	)
	(segment
		(start 424.323764 -53.040026)
		(end 420.01186 -57.35193)
		(width 0.127)
		(layer "In6.Cu")
		(net "SGPIO_OCP_SFF_DATAOUT")
	)
	(segment
		(start 162.81654 -101.460808)
		(end 162.81654 -102.172008)
		(width 0.127)
		(layer "In13.Cu")
		(net "SGPIO_OCP_SFF_DATAOUT")
	)
	(segment
		(start 230.16718 -72.657208)
		(end 222.224346 -80.600042)
		(width 0.127)
		(layer "In13.Cu")
		(net "SGPIO_OCP_SFF_DATAOUT")
	)
	(segment
		(start 169.32656 -117.008402)
		(end 169.689018 -117.37086)
		(width 0.127)
		(layer "In13.Cu")
		(net "SGPIO_OCP_SFF_DATAOUT")
	)
	(segment
		(start 165.712394 -94.84995)
		(end 163.3093 -97.253044)
		(width 0.127)
		(layer "In13.Cu")
		(net "SGPIO_OCP_SFF_DATAOUT")
	)
	(segment
		(start 165.0111 -104.690672)
		(end 165.0111 -110.437168)
		(width 0.127)
		(layer "In13.Cu")
		(net "SGPIO_OCP_SFF_DATAOUT")
	)
	(segment
		(start 276.00402 -77.202538)
		(end 273.114008 -80.09255)
		(width 0.127)
		(layer "In13.Cu")
		(net "SGPIO_OCP_SFF_DATAOUT")
	)
	(segment
		(start 165.0111 -110.437168)
		(end 169.32656 -114.752628)
		(width 0.127)
		(layer "In13.Cu")
		(net "SGPIO_OCP_SFF_DATAOUT")
	)
	(segment
		(start 273.114008 -80.09255)
		(end 248.34088 -80.09255)
		(width 0.127)
		(layer "In13.Cu")
		(net "SGPIO_OCP_SFF_DATAOUT")
	)
	(segment
		(start 175.917606 -85.979)
		(end 168.044622 -85.979)
		(width 0.127)
		(layer "In13.Cu")
		(net "SGPIO_OCP_SFF_DATAOUT")
	)
	(segment
		(start 162.81654 -102.172008)
		(end 163.957 -103.312468)
		(width 0.127)
		(layer "In13.Cu")
		(net "SGPIO_OCP_SFF_DATAOUT")
	)
	(segment
		(start 180.600858 -81.295748)
		(end 175.917606 -85.979)
		(width 0.127)
		(layer "In13.Cu")
		(net "SGPIO_OCP_SFF_DATAOUT")
	)
	(segment
		(start 242.055142 -72.657208)
		(end 230.16718 -72.657208)
		(width 0.127)
		(layer "In13.Cu")
		(net "SGPIO_OCP_SFF_DATAOUT")
	)
	(segment
		(start 163.957 -103.312468)
		(end 163.957 -103.636572)
		(width 0.127)
		(layer "In13.Cu")
		(net "SGPIO_OCP_SFF_DATAOUT")
	)
	(segment
		(start 243.906802 -70.805548)
		(end 242.055142 -72.657208)
		(width 0.127)
		(layer "In13.Cu")
		(net "SGPIO_OCP_SFF_DATAOUT")
	)
	(segment
		(start 168.044622 -85.979)
		(end 165.712394 -88.311228)
		(width 0.127)
		(layer "In13.Cu")
		(net "SGPIO_OCP_SFF_DATAOUT")
	)
	(segment
		(start 169.32656 -114.752628)
		(end 169.32656 -117.008402)
		(width 0.127)
		(layer "In13.Cu")
		(net "SGPIO_OCP_SFF_DATAOUT")
	)
	(segment
		(start 165.712394 -88.311228)
		(end 165.712394 -94.84995)
		(width 0.127)
		(layer "In13.Cu")
		(net "SGPIO_OCP_SFF_DATAOUT")
	)
	(segment
		(start 197.44436 -80.600042)
		(end 196.748654 -81.295748)
		(width 0.127)
		(layer "In13.Cu")
		(net "SGPIO_OCP_SFF_DATAOUT")
	)
	(segment
		(start 196.748654 -81.295748)
		(end 180.600858 -81.295748)
		(width 0.127)
		(layer "In13.Cu")
		(net "SGPIO_OCP_SFF_DATAOUT")
	)
	(segment
		(start 245.58752 -71.303642)
		(end 245.089426 -70.805548)
		(width 0.127)
		(layer "In13.Cu")
		(net "SGPIO_OCP_SFF_DATAOUT")
	)
	(segment
		(start 245.58752 -77.33919)
		(end 245.58752 -71.303642)
		(width 0.127)
		(layer "In13.Cu")
		(net "SGPIO_OCP_SFF_DATAOUT")
	)
	(segment
		(start 248.34088 -80.09255)
		(end 245.58752 -77.33919)
		(width 0.127)
		(layer "In13.Cu")
		(net "SGPIO_OCP_SFF_DATAOUT")
	)
	(segment
		(start 276.00402 -75.778868)
		(end 276.00402 -77.202538)
		(width 0.127)
		(layer "In13.Cu")
		(net "SGPIO_OCP_SFF_DATAOUT")
	)
	(segment
		(start 222.224346 -80.600042)
		(end 197.44436 -80.600042)
		(width 0.127)
		(layer "In13.Cu")
		(net "SGPIO_OCP_SFF_DATAOUT")
	)
	(segment
		(start 163.957 -103.636572)
		(end 165.0111 -104.690672)
		(width 0.127)
		(layer "In13.Cu")
		(net "SGPIO_OCP_SFF_DATAOUT")
	)
	(segment
		(start 163.3093 -97.253044)
		(end 163.3093 -100.968048)
		(width 0.127)
		(layer "In13.Cu")
		(net "SGPIO_OCP_SFF_DATAOUT")
	)
	(segment
		(start 245.089426 -70.805548)
		(end 243.906802 -70.805548)
		(width 0.127)
		(layer "In13.Cu")
		(net "SGPIO_OCP_SFF_DATAOUT")
	)
	(segment
		(start 163.3093 -100.968048)
		(end 162.81654 -101.460808)
		(width 0.127)
		(layer "In13.Cu")
		(net "SGPIO_OCP_SFF_DATAOUT")
	)
	(segment
		(start 307.253132 -87.274146)
		(end 302.891952 -82.912966)
		(width 0.12954)
		(layer "F.Cu")
		(net "SGPIO_OCP_SFF_DATAIN")
	)
	(segment
		(start 450.761862 -12.320778)
		(end 450.665596 -12.417044)
		(width 0.12954)
		(layer "F.Cu")
		(net "SGPIO_OCP_SFF_DATAIN")
	)
	(segment
		(start 364.81258 -79.398368)
		(end 364.799118 -79.384906)
		(width 0.12954)
		(layer "F.Cu")
		(net "SGPIO_OCP_SFF_DATAIN")
	)
	(segment
		(start 450.665596 -12.417044)
		(end 450.665596 -12.888468)
		(width 0.12954)
		(layer "F.Cu")
		(net "SGPIO_OCP_SFF_DATAIN")
	)
	(segment
		(start 302.891952 -82.912966)
		(end 283.948378 -82.912966)
		(width 0.12954)
		(layer "F.Cu")
		(net "SGPIO_OCP_SFF_DATAIN")
	)
	(segment
		(start 171.755562 -117.775482)
		(end 171.355512 -118.175532)
		(width 0.12954)
		(layer "F.Cu")
		(net "SGPIO_OCP_SFF_DATAIN")
	)
	(segment
		(start 355.476048 -87.274146)
		(end 307.253132 -87.274146)
		(width 0.12954)
		(layer "F.Cu")
		(net "SGPIO_OCP_SFF_DATAIN")
	)
	(segment
		(start 277.27402 -76.238608)
		(end 277.27402 -75.778868)
		(width 0.12954)
		(layer "F.Cu")
		(net "SGPIO_OCP_SFF_DATAIN")
	)
	(segment
		(start 283.948378 -82.912966)
		(end 277.27402 -76.238608)
		(width 0.12954)
		(layer "F.Cu")
		(net "SGPIO_OCP_SFF_DATAIN")
	)
	(segment
		(start 363.365288 -79.384906)
		(end 355.476048 -87.274146)
		(width 0.12954)
		(layer "F.Cu")
		(net "SGPIO_OCP_SFF_DATAIN")
	)
	(segment
		(start 364.799118 -79.384906)
		(end 363.365288 -79.384906)
		(width 0.12954)
		(layer "F.Cu")
		(net "SGPIO_OCP_SFF_DATAIN")
	)
	(segment
		(start 450.761862 -11.26998)
		(end 450.761862 -12.320778)
		(width 0.12954)
		(layer "F.Cu")
		(net "SGPIO_OCP_SFF_DATAIN")
	)
	(via
		(at 171.355512 -118.175532)
		(size 0.4572)
		(drill 0.254)
		(layers "F.Cu" "B.Cu")
		(net "SGPIO_OCP_SFF_DATAIN")
	)
	(via
		(at 450.665596 -12.888468)
		(size 0.508)
		(drill 0.254)
		(layers "F.Cu" "B.Cu")
		(net "SGPIO_OCP_SFF_DATAIN")
	)
	(via
		(at 277.27402 -75.778868)
		(size 0.508)
		(drill 0.254)
		(layers "F.Cu" "B.Cu")
		(net "SGPIO_OCP_SFF_DATAIN")
	)
	(via
		(at 364.81258 -79.398368)
		(size 0.762)
		(drill 0.254)
		(layers "F.Cu" "B.Cu")
		(net "SGPIO_OCP_SFF_DATAIN")
	)
	(segment
		(start 450.665596 -12.888468)
		(end 451.549516 -12.004548)
		(width 0.12954)
		(layer "B.Cu")
		(net "SGPIO_OCP_SFF_DATAIN")
	)
	(segment
		(start 451.549516 -12.004548)
		(end 451.549516 -11.034776)
		(width 0.12954)
		(layer "B.Cu")
		(net "SGPIO_OCP_SFF_DATAIN")
	)
	(segment
		(start 432.551586 -46.053248)
		(end 426.105828 -52.499006)
		(width 0.127)
		(layer "In6.Cu")
		(net "SGPIO_OCP_SFF_DATAIN")
	)
	(segment
		(start 398.168114 -83.195668)
		(end 368.60988 -83.195668)
		(width 0.127)
		(layer "In6.Cu")
		(net "SGPIO_OCP_SFF_DATAIN")
	)
	(segment
		(start 424.099482 -52.499006)
		(end 419.47084 -57.127648)
		(width 0.127)
		(layer "In6.Cu")
		(net "SGPIO_OCP_SFF_DATAIN")
	)
	(segment
		(start 457.7207 -16.132048)
		(end 457.7207 -35.635692)
		(width 0.127)
		(layer "In6.Cu")
		(net "SGPIO_OCP_SFF_DATAIN")
	)
	(segment
		(start 436.753254 -43.320208)
		(end 433.242212 -43.320208)
		(width 0.127)
		(layer "In6.Cu")
		(net "SGPIO_OCP_SFF_DATAIN")
	)
	(segment
		(start 439.565034 -40.508428)
		(end 436.753254 -43.320208)
		(width 0.127)
		(layer "In6.Cu")
		(net "SGPIO_OCP_SFF_DATAIN")
	)
	(segment
		(start 452.847964 -40.508428)
		(end 439.565034 -40.508428)
		(width 0.127)
		(layer "In6.Cu")
		(net "SGPIO_OCP_SFF_DATAIN")
	)
	(segment
		(start 419.47084 -61.892942)
		(end 398.168114 -83.195668)
		(width 0.127)
		(layer "In6.Cu")
		(net "SGPIO_OCP_SFF_DATAIN")
	)
	(segment
		(start 457.7207 -35.635692)
		(end 452.847964 -40.508428)
		(width 0.127)
		(layer "In6.Cu")
		(net "SGPIO_OCP_SFF_DATAIN")
	)
	(segment
		(start 368.60988 -83.195668)
		(end 364.81258 -79.398368)
		(width 0.127)
		(layer "In6.Cu")
		(net "SGPIO_OCP_SFF_DATAIN")
	)
	(segment
		(start 451.155816 -12.398248)
		(end 453.9869 -12.398248)
		(width 0.127)
		(layer "In6.Cu")
		(net "SGPIO_OCP_SFF_DATAIN")
	)
	(segment
		(start 419.47084 -57.127648)
		(end 419.47084 -61.892942)
		(width 0.127)
		(layer "In6.Cu")
		(net "SGPIO_OCP_SFF_DATAIN")
	)
	(segment
		(start 433.242212 -43.320208)
		(end 432.551586 -44.010834)
		(width 0.127)
		(layer "In6.Cu")
		(net "SGPIO_OCP_SFF_DATAIN")
	)
	(segment
		(start 426.105828 -52.499006)
		(end 424.099482 -52.499006)
		(width 0.127)
		(layer "In6.Cu")
		(net "SGPIO_OCP_SFF_DATAIN")
	)
	(segment
		(start 450.665596 -12.888468)
		(end 451.155816 -12.398248)
		(width 0.127)
		(layer "In6.Cu")
		(net "SGPIO_OCP_SFF_DATAIN")
	)
	(segment
		(start 432.551586 -44.010834)
		(end 432.551586 -46.053248)
		(width 0.127)
		(layer "In6.Cu")
		(net "SGPIO_OCP_SFF_DATAIN")
	)
	(segment
		(start 453.9869 -12.398248)
		(end 457.7207 -16.132048)
		(width 0.127)
		(layer "In6.Cu")
		(net "SGPIO_OCP_SFF_DATAIN")
	)
	(segment
		(start 277.27402 -77.154532)
		(end 273.472402 -80.95615)
		(width 0.127)
		(layer "In13.Cu")
		(net "SGPIO_OCP_SFF_DATAIN")
	)
	(segment
		(start 167.213534 -98.742754)
		(end 166.41318 -99.543108)
		(width 0.127)
		(layer "In13.Cu")
		(net "SGPIO_OCP_SFF_DATAIN")
	)
	(segment
		(start 166.41318 -99.543108)
		(end 166.41318 -109.89818)
		(width 0.127)
		(layer "In13.Cu")
		(net "SGPIO_OCP_SFF_DATAIN")
	)
	(segment
		(start 277.27402 -75.778868)
		(end 277.27402 -77.154532)
		(width 0.127)
		(layer "In13.Cu")
		(net "SGPIO_OCP_SFF_DATAIN")
	)
	(segment
		(start 221.82328 -83.081368)
		(end 180.887624 -83.081368)
		(width 0.127)
		(layer "In13.Cu")
		(net "SGPIO_OCP_SFF_DATAIN")
	)
	(segment
		(start 166.41318 -109.89818)
		(end 170.94962 -114.43462)
		(width 0.127)
		(layer "In13.Cu")
		(net "SGPIO_OCP_SFF_DATAIN")
	)
	(segment
		(start 167.213534 -89.48166)
		(end 167.213534 -98.742754)
		(width 0.127)
		(layer "In13.Cu")
		(net "SGPIO_OCP_SFF_DATAIN")
	)
	(segment
		(start 170.94962 -117.76964)
		(end 171.355512 -118.175532)
		(width 0.127)
		(layer "In13.Cu")
		(net "SGPIO_OCP_SFF_DATAIN")
	)
	(segment
		(start 273.472402 -80.95615)
		(end 247.465342 -80.95615)
		(width 0.127)
		(layer "In13.Cu")
		(net "SGPIO_OCP_SFF_DATAIN")
	)
	(segment
		(start 170.94962 -114.43462)
		(end 170.94962 -117.76964)
		(width 0.127)
		(layer "In13.Cu")
		(net "SGPIO_OCP_SFF_DATAIN")
	)
	(segment
		(start 247.465342 -80.95615)
		(end 240.4618 -73.952608)
		(width 0.127)
		(layer "In13.Cu")
		(net "SGPIO_OCP_SFF_DATAIN")
	)
	(segment
		(start 180.887624 -83.081368)
		(end 175.848518 -88.120474)
		(width 0.127)
		(layer "In13.Cu")
		(net "SGPIO_OCP_SFF_DATAIN")
	)
	(segment
		(start 230.95204 -73.952608)
		(end 221.82328 -83.081368)
		(width 0.127)
		(layer "In13.Cu")
		(net "SGPIO_OCP_SFF_DATAIN")
	)
	(segment
		(start 240.4618 -73.952608)
		(end 230.95204 -73.952608)
		(width 0.127)
		(layer "In13.Cu")
		(net "SGPIO_OCP_SFF_DATAIN")
	)
	(segment
		(start 175.848518 -88.120474)
		(end 168.57472 -88.120474)
		(width 0.127)
		(layer "In13.Cu")
		(net "SGPIO_OCP_SFF_DATAIN")
	)
	(segment
		(start 168.57472 -88.120474)
		(end 167.213534 -89.48166)
		(width 0.127)
		(layer "In13.Cu")
		(net "SGPIO_OCP_SFF_DATAIN")
	)
	(segment
		(start 306.695348 -88.6206)
		(end 302.334168 -84.25942)
		(width 0.12954)
		(layer "F.Cu")
		(net "SGPIO_OCP_SFF_CLK")
	)
	(segment
		(start 449.395596 -12.417044)
		(end 449.395596 -12.888468)
		(width 0.12954)
		(layer "F.Cu")
		(net "SGPIO_OCP_SFF_CLK")
	)
	(segment
		(start 356.033832 -88.6206)
		(end 306.695348 -88.6206)
		(width 0.12954)
		(layer "F.Cu")
		(net "SGPIO_OCP_SFF_CLK")
	)
	(segment
		(start 449.561966 -11.26998)
		(end 449.561966 -12.250674)
		(width 0.12954)
		(layer "F.Cu")
		(net "SGPIO_OCP_SFF_CLK")
	)
	(segment
		(start 363.031024 -81.623408)
		(end 356.033832 -88.6206)
		(width 0.12954)
		(layer "F.Cu")
		(net "SGPIO_OCP_SFF_CLK")
	)
	(segment
		(start 283.252672 -84.25942)
		(end 275.36902 -76.375768)
		(width 0.12954)
		(layer "F.Cu")
		(net "SGPIO_OCP_SFF_CLK")
	)
	(segment
		(start 449.561966 -12.250674)
		(end 449.395596 -12.417044)
		(width 0.12954)
		(layer "F.Cu")
		(net "SGPIO_OCP_SFF_CLK")
	)
	(segment
		(start 170.955716 -117.775482)
		(end 170.555666 -118.175532)
		(width 0.12954)
		(layer "F.Cu")
		(net "SGPIO_OCP_SFF_CLK")
	)
	(segment
		(start 364.7567 -81.623408)
		(end 363.031024 -81.623408)
		(width 0.12954)
		(layer "F.Cu")
		(net "SGPIO_OCP_SFF_CLK")
	)
	(segment
		(start 275.36902 -76.375768)
		(end 275.36902 -75.778868)
		(width 0.12954)
		(layer "F.Cu")
		(net "SGPIO_OCP_SFF_CLK")
	)
	(segment
		(start 302.334168 -84.25942)
		(end 283.252672 -84.25942)
		(width 0.12954)
		(layer "F.Cu")
		(net "SGPIO_OCP_SFF_CLK")
	)
	(via
		(at 364.7567 -81.623408)
		(size 0.508)
		(drill 0.254)
		(layers "F.Cu" "B.Cu")
		(net "SGPIO_OCP_SFF_CLK")
	)
	(via
		(at 170.555666 -118.175532)
		(size 0.4572)
		(drill 0.254)
		(layers "F.Cu" "B.Cu")
		(net "SGPIO_OCP_SFF_CLK")
	)
	(via
		(at 275.36902 -75.778868)
		(size 0.508)
		(drill 0.254)
		(layers "F.Cu" "B.Cu")
		(net "SGPIO_OCP_SFF_CLK")
	)
	(via
		(at 449.395596 -12.888468)
		(size 0.508)
		(drill 0.254)
		(layers "F.Cu" "B.Cu")
		(net "SGPIO_OCP_SFF_CLK")
	)
	(segment
		(start 449.5546 -12.729464)
		(end 449.5546 -10.994136)
		(width 0.12954)
		(layer "B.Cu")
		(net "SGPIO_OCP_SFF_CLK")
	)
	(segment
		(start 449.395596 -12.888468)
		(end 449.5546 -12.729464)
		(width 0.12954)
		(layer "B.Cu")
		(net "SGPIO_OCP_SFF_CLK")
	)
	(segment
		(start 434.74386 -45.52442)
		(end 426.593254 -53.675026)
		(width 0.127)
		(layer "In6.Cu")
		(net "SGPIO_OCP_SFF_CLK")
	)
	(segment
		(start 365.280956 -81.623408)
		(end 364.7567 -81.623408)
		(width 0.127)
		(layer "In6.Cu")
		(net "SGPIO_OCP_SFF_CLK")
	)
	(segment
		(start 420.64686 -62.380368)
		(end 398.65554 -84.371688)
		(width 0.127)
		(layer "In6.Cu")
		(net "SGPIO_OCP_SFF_CLK")
	)
	(segment
		(start 458.89672 -36.123118)
		(end 453.33539 -41.684448)
		(width 0.127)
		(layer "In6.Cu")
		(net "SGPIO_OCP_SFF_CLK")
	)
	(segment
		(start 420.64686 -57.615074)
		(end 420.64686 -62.380368)
		(width 0.127)
		(layer "In6.Cu")
		(net "SGPIO_OCP_SFF_CLK")
	)
	(segment
		(start 453.33539 -41.684448)
		(end 442.005212 -41.684448)
		(width 0.127)
		(layer "In6.Cu")
		(net "SGPIO_OCP_SFF_CLK")
	)
	(segment
		(start 426.593254 -53.675026)
		(end 424.586908 -53.675026)
		(width 0.127)
		(layer "In6.Cu")
		(net "SGPIO_OCP_SFF_CLK")
	)
	(segment
		(start 458.89672 -15.740888)
		(end 458.89672 -36.123118)
		(width 0.127)
		(layer "In6.Cu")
		(net "SGPIO_OCP_SFF_CLK")
	)
	(segment
		(start 424.586908 -53.675026)
		(end 420.64686 -57.615074)
		(width 0.127)
		(layer "In6.Cu")
		(net "SGPIO_OCP_SFF_CLK")
	)
	(segment
		(start 438.16524 -45.52442)
		(end 434.74386 -45.52442)
		(width 0.127)
		(layer "In6.Cu")
		(net "SGPIO_OCP_SFF_CLK")
	)
	(segment
		(start 449.395596 -12.597892)
		(end 450.51218 -11.481308)
		(width 0.127)
		(layer "In6.Cu")
		(net "SGPIO_OCP_SFF_CLK")
	)
	(segment
		(start 398.65554 -84.371688)
		(end 368.029236 -84.371688)
		(width 0.127)
		(layer "In6.Cu")
		(net "SGPIO_OCP_SFF_CLK")
	)
	(segment
		(start 449.395596 -12.888468)
		(end 449.395596 -12.597892)
		(width 0.127)
		(layer "In6.Cu")
		(net "SGPIO_OCP_SFF_CLK")
	)
	(segment
		(start 442.005212 -41.684448)
		(end 438.16524 -45.52442)
		(width 0.127)
		(layer "In6.Cu")
		(net "SGPIO_OCP_SFF_CLK")
	)
	(segment
		(start 454.63714 -11.481308)
		(end 458.89672 -15.740888)
		(width 0.127)
		(layer "In6.Cu")
		(net "SGPIO_OCP_SFF_CLK")
	)
	(segment
		(start 450.51218 -11.481308)
		(end 454.63714 -11.481308)
		(width 0.127)
		(layer "In6.Cu")
		(net "SGPIO_OCP_SFF_CLK")
	)
	(segment
		(start 368.029236 -84.371688)
		(end 365.280956 -81.623408)
		(width 0.127)
		(layer "In6.Cu")
		(net "SGPIO_OCP_SFF_CLK")
	)
	(segment
		(start 196.636132 -80.584548)
		(end 197.0532 -80.16748)
		(width 0.127)
		(layer "In13.Cu")
		(net "SGPIO_OCP_SFF_CLK")
	)
	(segment
		(start 245.25986 -70.264528)
		(end 246.12854 -71.133208)
		(width 0.127)
		(layer "In13.Cu")
		(net "SGPIO_OCP_SFF_CLK")
	)
	(segment
		(start 246.12854 -77.114908)
		(end 248.674382 -79.66075)
		(width 0.127)
		(layer "In13.Cu")
		(net "SGPIO_OCP_SFF_CLK")
	)
	(segment
		(start 197.0532 -80.16748)
		(end 221.920308 -80.16748)
		(width 0.127)
		(layer "In13.Cu")
		(net "SGPIO_OCP_SFF_CLK")
	)
	(segment
		(start 165.145974 -88.266524)
		(end 167.948102 -85.464396)
		(width 0.127)
		(layer "In13.Cu")
		(net "SGPIO_OCP_SFF_CLK")
	)
	(segment
		(start 168.83634 -114.973608)
		(end 164.64788 -110.785148)
		(width 0.127)
		(layer "In13.Cu")
		(net "SGPIO_OCP_SFF_CLK")
	)
	(segment
		(start 169.31132 -117.772688)
		(end 168.83634 -117.297708)
		(width 0.127)
		(layer "In13.Cu")
		(net "SGPIO_OCP_SFF_CLK")
	)
	(segment
		(start 272.934938 -79.66075)
		(end 275.36902 -77.226668)
		(width 0.127)
		(layer "In13.Cu")
		(net "SGPIO_OCP_SFF_CLK")
	)
	(segment
		(start 248.674382 -79.66075)
		(end 272.934938 -79.66075)
		(width 0.127)
		(layer "In13.Cu")
		(net "SGPIO_OCP_SFF_CLK")
	)
	(segment
		(start 243.68252 -70.264528)
		(end 245.25986 -70.264528)
		(width 0.127)
		(layer "In13.Cu")
		(net "SGPIO_OCP_SFF_CLK")
	)
	(segment
		(start 162.8775 -100.348288)
		(end 162.8775 -96.883728)
		(width 0.127)
		(layer "In13.Cu")
		(net "SGPIO_OCP_SFF_CLK")
	)
	(segment
		(start 163.91128 -110.429548)
		(end 163.91128 -109.997748)
		(width 0.127)
		(layer "In13.Cu")
		(net "SGPIO_OCP_SFF_CLK")
	)
	(segment
		(start 181.134512 -80.147668)
		(end 193.832988 -80.147668)
		(width 0.127)
		(layer "In13.Cu")
		(net "SGPIO_OCP_SFF_CLK")
	)
	(segment
		(start 165.145974 -94.615254)
		(end 165.145974 -88.266524)
		(width 0.127)
		(layer "In13.Cu")
		(net "SGPIO_OCP_SFF_CLK")
	)
	(segment
		(start 162.8775 -96.883728)
		(end 165.145974 -94.615254)
		(width 0.127)
		(layer "In13.Cu")
		(net "SGPIO_OCP_SFF_CLK")
	)
	(segment
		(start 164.10178 -109.807248)
		(end 164.10178 -104.392476)
		(width 0.127)
		(layer "In13.Cu")
		(net "SGPIO_OCP_SFF_CLK")
	)
	(segment
		(start 170.152822 -117.772688)
		(end 169.31132 -117.772688)
		(width 0.127)
		(layer "In13.Cu")
		(net "SGPIO_OCP_SFF_CLK")
	)
	(segment
		(start 229.86238 -72.225408)
		(end 241.72164 -72.225408)
		(width 0.127)
		(layer "In13.Cu")
		(net "SGPIO_OCP_SFF_CLK")
	)
	(segment
		(start 221.920308 -80.16748)
		(end 229.86238 -72.225408)
		(width 0.127)
		(layer "In13.Cu")
		(net "SGPIO_OCP_SFF_CLK")
	)
	(segment
		(start 164.64788 -110.785148)
		(end 164.26688 -110.785148)
		(width 0.127)
		(layer "In13.Cu")
		(net "SGPIO_OCP_SFF_CLK")
	)
	(segment
		(start 161.70402 -101.521768)
		(end 162.8775 -100.348288)
		(width 0.127)
		(layer "In13.Cu")
		(net "SGPIO_OCP_SFF_CLK")
	)
	(segment
		(start 167.948102 -85.464396)
		(end 175.817784 -85.464396)
		(width 0.127)
		(layer "In13.Cu")
		(net "SGPIO_OCP_SFF_CLK")
	)
	(segment
		(start 163.91128 -109.997748)
		(end 164.10178 -109.807248)
		(width 0.127)
		(layer "In13.Cu")
		(net "SGPIO_OCP_SFF_CLK")
	)
	(segment
		(start 194.269868 -80.584548)
		(end 196.636132 -80.584548)
		(width 0.127)
		(layer "In13.Cu")
		(net "SGPIO_OCP_SFF_CLK")
	)
	(segment
		(start 175.817784 -85.464396)
		(end 181.134512 -80.147668)
		(width 0.127)
		(layer "In13.Cu")
		(net "SGPIO_OCP_SFF_CLK")
	)
	(segment
		(start 193.832988 -80.147668)
		(end 194.269868 -80.584548)
		(width 0.127)
		(layer "In13.Cu")
		(net "SGPIO_OCP_SFF_CLK")
	)
	(segment
		(start 170.555666 -118.175532)
		(end 170.152822 -117.772688)
		(width 0.127)
		(layer "In13.Cu")
		(net "SGPIO_OCP_SFF_CLK")
	)
	(segment
		(start 246.12854 -71.133208)
		(end 246.12854 -77.114908)
		(width 0.127)
		(layer "In13.Cu")
		(net "SGPIO_OCP_SFF_CLK")
	)
	(segment
		(start 241.72164 -72.225408)
		(end 243.68252 -70.264528)
		(width 0.127)
		(layer "In13.Cu")
		(net "SGPIO_OCP_SFF_CLK")
	)
	(segment
		(start 275.36902 -77.226668)
		(end 275.36902 -75.778868)
		(width 0.127)
		(layer "In13.Cu")
		(net "SGPIO_OCP_SFF_CLK")
	)
	(segment
		(start 161.70402 -101.994716)
		(end 161.70402 -101.521768)
		(width 0.127)
		(layer "In13.Cu")
		(net "SGPIO_OCP_SFF_CLK")
	)
	(segment
		(start 164.26688 -110.785148)
		(end 163.91128 -110.429548)
		(width 0.127)
		(layer "In13.Cu")
		(net "SGPIO_OCP_SFF_CLK")
	)
	(segment
		(start 164.10178 -104.392476)
		(end 161.70402 -101.994716)
		(width 0.127)
		(layer "In13.Cu")
		(net "SGPIO_OCP_SFF_CLK")
	)
	(segment
		(start 168.83634 -117.297708)
		(end 168.83634 -114.973608)
		(width 0.127)
		(layer "In13.Cu")
		(net "SGPIO_OCP_SFF_CLK")
	)
	(segment
		(start 153.21788 -22.266148)
		(end 153.38552 -22.433788)
		(width 0.12954)
		(layer "F.Cu")
		(net "SGPIO_LD_1")
	)
	(segment
		(start 164.06495 -99.786948)
		(end 164.06495 -99.043998)
		(width 0.12954)
		(layer "F.Cu")
		(net "SGPIO_LD_1")
	)
	(segment
		(start 153.856944 -19.417284)
		(end 153.21788 -20.056348)
		(width 0.12954)
		(layer "F.Cu")
		(net "SGPIO_LD_1")
	)
	(segment
		(start 153.38552 -22.433788)
		(end 153.38552 -23.851108)
		(width 0.12954)
		(layer "F.Cu")
		(net "SGPIO_LD_1")
	)
	(segment
		(start 153.21788 -20.056348)
		(end 153.21788 -22.266148)
		(width 0.12954)
		(layer "F.Cu")
		(net "SGPIO_LD_1")
	)
	(segment
		(start 153.856944 -16.550132)
		(end 153.856944 -19.417284)
		(width 0.12954)
		(layer "F.Cu")
		(net "SGPIO_LD_1")
	)
	(via
		(at 153.38552 -23.851108)
		(size 0.762)
		(drill 0.254)
		(layers "F.Cu" "B.Cu")
		(net "SGPIO_LD_1")
	)
	(via
		(at 164.06495 -99.043998)
		(size 0.508)
		(drill 0.254)
		(layers "F.Cu" "B.Cu")
		(net "SGPIO_LD_1")
	)
	(segment
		(start 162.80384 -43.043348)
		(end 163.33724 -42.509948)
		(width 0.127)
		(layer "In2.Cu")
		(net "SGPIO_LD_1")
	)
	(segment
		(start 153.21788 -21.382228)
		(end 153.21788 -23.683468)
		(width 0.127)
		(layer "In2.Cu")
		(net "SGPIO_LD_1")
	)
	(segment
		(start 160.04794 -27.348688)
		(end 160.04794 -26.360628)
		(width 0.127)
		(layer "In2.Cu")
		(net "SGPIO_LD_1")
	)
	(segment
		(start 158.88208 -54.930548)
		(end 160.64992 -53.162708)
		(width 0.127)
		(layer "In2.Cu")
		(net "SGPIO_LD_1")
	)
	(segment
		(start 160.04794 -26.360628)
		(end 160.40608 -26.002488)
		(width 0.127)
		(layer "In2.Cu")
		(net "SGPIO_LD_1")
	)
	(segment
		(start 156.56052 -66.563748)
		(end 157.22092 -65.903348)
		(width 0.127)
		(layer "In2.Cu")
		(net "SGPIO_LD_1")
	)
	(segment
		(start 160.40608 -26.002488)
		(end 160.40608 -22.951948)
		(width 0.127)
		(layer "In2.Cu")
		(net "SGPIO_LD_1")
	)
	(segment
		(start 157.22092 -57.8358)
		(end 158.88208 -56.17464)
		(width 0.127)
		(layer "In2.Cu")
		(net "SGPIO_LD_1")
	)
	(segment
		(start 156.56052 -78.656688)
		(end 156.56052 -66.563748)
		(width 0.127)
		(layer "In2.Cu")
		(net "SGPIO_LD_1")
	)
	(segment
		(start 163.33724 -42.509948)
		(end 163.33724 -30.637988)
		(width 0.127)
		(layer "In2.Cu")
		(net "SGPIO_LD_1")
	)
	(segment
		(start 163.33724 -30.637988)
		(end 160.04794 -27.348688)
		(width 0.127)
		(layer "In2.Cu")
		(net "SGPIO_LD_1")
	)
	(segment
		(start 160.64992 -50.429668)
		(end 162.40252 -48.677068)
		(width 0.127)
		(layer "In2.Cu")
		(net "SGPIO_LD_1")
	)
	(segment
		(start 153.65476 -20.945348)
		(end 153.21788 -21.382228)
		(width 0.127)
		(layer "In2.Cu")
		(net "SGPIO_LD_1")
	)
	(segment
		(start 157.74924 -79.845408)
		(end 156.56052 -78.656688)
		(width 0.127)
		(layer "In2.Cu")
		(net "SGPIO_LD_1")
	)
	(segment
		(start 160.64992 -53.162708)
		(end 160.64992 -50.429668)
		(width 0.127)
		(layer "In2.Cu")
		(net "SGPIO_LD_1")
	)
	(segment
		(start 164.06495 -97.265998)
		(end 162.69208 -95.893128)
		(width 0.127)
		(layer "In2.Cu")
		(net "SGPIO_LD_1")
	)
	(segment
		(start 157.74924 -82.321908)
		(end 157.74924 -79.845408)
		(width 0.127)
		(layer "In2.Cu")
		(net "SGPIO_LD_1")
	)
	(segment
		(start 158.88208 -56.17464)
		(end 158.88208 -54.930548)
		(width 0.127)
		(layer "In2.Cu")
		(net "SGPIO_LD_1")
	)
	(segment
		(start 164.06495 -99.043998)
		(end 164.06495 -97.265998)
		(width 0.127)
		(layer "In2.Cu")
		(net "SGPIO_LD_1")
	)
	(segment
		(start 162.80384 -46.337728)
		(end 162.80384 -43.043348)
		(width 0.127)
		(layer "In2.Cu")
		(net "SGPIO_LD_1")
	)
	(segment
		(start 162.69208 -87.264748)
		(end 157.74924 -82.321908)
		(width 0.127)
		(layer "In2.Cu")
		(net "SGPIO_LD_1")
	)
	(segment
		(start 160.40608 -22.951948)
		(end 158.39948 -20.945348)
		(width 0.127)
		(layer "In2.Cu")
		(net "SGPIO_LD_1")
	)
	(segment
		(start 162.40252 -48.677068)
		(end 162.40252 -46.739048)
		(width 0.127)
		(layer "In2.Cu")
		(net "SGPIO_LD_1")
	)
	(segment
		(start 162.69208 -95.893128)
		(end 162.69208 -87.264748)
		(width 0.127)
		(layer "In2.Cu")
		(net "SGPIO_LD_1")
	)
	(segment
		(start 158.39948 -20.945348)
		(end 153.65476 -20.945348)
		(width 0.127)
		(layer "In2.Cu")
		(net "SGPIO_LD_1")
	)
	(segment
		(start 162.40252 -46.739048)
		(end 162.80384 -46.337728)
		(width 0.127)
		(layer "In2.Cu")
		(net "SGPIO_LD_1")
	)
	(segment
		(start 153.21788 -23.683468)
		(end 153.38552 -23.851108)
		(width 0.127)
		(layer "In2.Cu")
		(net "SGPIO_LD_1")
	)
	(segment
		(start 157.22092 -65.903348)
		(end 157.22092 -57.8358)
		(width 0.127)
		(layer "In2.Cu")
		(net "SGPIO_LD_1")
	)
	(segment
		(start 156.856938 -23.882096)
		(end 156.821886 -23.917148)
		(width 0.12954)
		(layer "F.Cu")
		(net "SGPIO_LD_0")
	)
	(segment
		(start 156.856938 -16.550132)
		(end 156.856938 -23.882096)
		(width 0.12954)
		(layer "F.Cu")
		(net "SGPIO_LD_0")
	)
	(segment
		(start 160.76295 -99.102418)
		(end 160.76295 -99.786948)
		(width 0.12954)
		(layer "F.Cu")
		(net "SGPIO_LD_0")
	)
	(segment
		(start 160.68548 -99.024948)
		(end 160.76295 -99.102418)
		(width 0.12954)
		(layer "F.Cu")
		(net "SGPIO_LD_0")
	)
	(via
		(at 156.821886 -23.917148)
		(size 0.508)
		(drill 0.254)
		(layers "F.Cu" "B.Cu")
		(net "SGPIO_LD_0")
	)
	(via
		(at 160.68548 -99.024948)
		(size 0.508)
		(drill 0.254)
		(layers "F.Cu" "B.Cu")
		(net "SGPIO_LD_0")
	)
	(segment
		(start 155.856432 -42.232326)
		(end 154.57678 -43.511978)
		(width 0.127)
		(layer "In2.Cu")
		(net "SGPIO_LD_0")
	)
	(segment
		(start 154.25928 -70.93585)
		(end 153.90368 -70.93585)
		(width 0.127)
		(layer "In2.Cu")
		(net "SGPIO_LD_0")
	)
	(segment
		(start 153.90368 -70.50151)
		(end 154.25928 -70.50151)
		(width 0.127)
		(layer "In2.Cu")
		(net "SGPIO_LD_0")
	)
	(segment
		(start 157.60192 -39.347648)
		(end 157.740096 -39.485824)
		(width 0.127)
		(layer "In2.Cu")
		(net "SGPIO_LD_0")
	)
	(segment
		(start 153.90368 -73.54189)
		(end 153.77668 -73.66889)
		(width 0.127)
		(layer "In2.Cu")
		(net "SGPIO_LD_0")
	)
	(segment
		(start 158.80588 -25.484328)
		(end 158.30804 -25.982168)
		(width 0.127)
		(layer "In2.Cu")
		(net "SGPIO_LD_0")
	)
	(segment
		(start 154.38628 -70.80885)
		(end 154.25928 -70.93585)
		(width 0.127)
		(layer "In2.Cu")
		(net "SGPIO_LD_0")
	)
	(segment
		(start 154.38628 -69.94017)
		(end 154.25928 -70.06717)
		(width 0.127)
		(layer "In2.Cu")
		(net "SGPIO_LD_0")
	)
	(segment
		(start 153.90368 -70.06717)
		(end 153.77668 -70.19417)
		(width 0.127)
		(layer "In2.Cu")
		(net "SGPIO_LD_0")
	)
	(segment
		(start 154.25928 -71.80453)
		(end 153.90368 -71.80453)
		(width 0.127)
		(layer "In2.Cu")
		(net "SGPIO_LD_0")
	)
	(segment
		(start 155.42768 -49.24806)
		(end 157.10154 -49.24806)
		(width 0.127)
		(layer "In2.Cu")
		(net "SGPIO_LD_0")
	)
	(segment
		(start 153.77668 -72.80021)
		(end 153.77668 -72.98055)
		(width 0.127)
		(layer "In2.Cu")
		(net "SGPIO_LD_0")
	)
	(segment
		(start 154.38628 -70.62851)
		(end 154.38628 -70.80885)
		(width 0.127)
		(layer "In2.Cu")
		(net "SGPIO_LD_0")
	)
	(segment
		(start 156.789374 -42.232326)
		(end 155.856432 -42.232326)
		(width 0.127)
		(layer "In2.Cu")
		(net "SGPIO_LD_0")
	)
	(segment
		(start 160.68548 -91.470988)
		(end 160.68548 -99.024948)
		(width 0.127)
		(layer "In2.Cu")
		(net "SGPIO_LD_0")
	)
	(segment
		(start 153.77668 -70.37451)
		(end 153.90368 -70.50151)
		(width 0.127)
		(layer "In2.Cu")
		(net "SGPIO_LD_0")
	)
	(segment
		(start 154.25928 -71.37019)
		(end 154.38628 -71.49719)
		(width 0.127)
		(layer "In2.Cu")
		(net "SGPIO_LD_0")
	)
	(segment
		(start 154.38628 -69.154548)
		(end 154.38628 -69.94017)
		(width 0.127)
		(layer "In2.Cu")
		(net "SGPIO_LD_0")
	)
	(segment
		(start 154.38628 -73.41489)
		(end 154.25928 -73.54189)
		(width 0.127)
		(layer "In2.Cu")
		(net "SGPIO_LD_0")
	)
	(segment
		(start 154.38628 -82.621628)
		(end 154.38628 -85.171788)
		(width 0.127)
		(layer "In2.Cu")
		(net "SGPIO_LD_0")
	)
	(segment
		(start 157.740096 -41.281604)
		(end 156.789374 -42.232326)
		(width 0.127)
		(layer "In2.Cu")
		(net "SGPIO_LD_0")
	)
	(segment
		(start 158.22168 -23.129748)
		(end 158.80588 -23.713948)
		(width 0.127)
		(layer "In2.Cu")
		(net "SGPIO_LD_0")
	)
	(segment
		(start 154.25928 -73.97623)
		(end 154.38628 -74.10323)
		(width 0.127)
		(layer "In2.Cu")
		(net "SGPIO_LD_0")
	)
	(segment
		(start 154.38628 -85.171788)
		(end 160.68548 -91.470988)
		(width 0.127)
		(layer "In2.Cu")
		(net "SGPIO_LD_0")
	)
	(segment
		(start 158.30804 -25.982168)
		(end 158.30804 -32.073088)
		(width 0.127)
		(layer "In2.Cu")
		(net "SGPIO_LD_0")
	)
	(segment
		(start 158.80588 -23.713948)
		(end 158.80588 -25.484328)
		(width 0.127)
		(layer "In2.Cu")
		(net "SGPIO_LD_0")
	)
	(segment
		(start 153.77668 -71.06285)
		(end 153.77668 -71.24319)
		(width 0.127)
		(layer "In2.Cu")
		(net "SGPIO_LD_0")
	)
	(segment
		(start 154.25928 -73.54189)
		(end 153.90368 -73.54189)
		(width 0.127)
		(layer "In2.Cu")
		(net "SGPIO_LD_0")
	)
	(segment
		(start 153.90368 -72.23887)
		(end 154.25928 -72.23887)
		(width 0.127)
		(layer "In2.Cu")
		(net "SGPIO_LD_0")
	)
	(segment
		(start 153.90368 -71.37019)
		(end 154.25928 -71.37019)
		(width 0.127)
		(layer "In2.Cu")
		(net "SGPIO_LD_0")
	)
	(segment
		(start 154.38628 -72.54621)
		(end 154.25928 -72.67321)
		(width 0.127)
		(layer "In2.Cu")
		(net "SGPIO_LD_0")
	)
	(segment
		(start 154.38628 -71.67753)
		(end 154.25928 -71.80453)
		(width 0.127)
		(layer "In2.Cu")
		(net "SGPIO_LD_0")
	)
	(segment
		(start 153.90368 -72.67321)
		(end 153.77668 -72.80021)
		(width 0.127)
		(layer "In2.Cu")
		(net "SGPIO_LD_0")
	)
	(segment
		(start 153.93924 -66.991738)
		(end 153.93924 -68.707508)
		(width 0.127)
		(layer "In2.Cu")
		(net "SGPIO_LD_0")
	)
	(segment
		(start 157.45206 -49.59858)
		(end 157.45206 -55.739538)
		(width 0.127)
		(layer "In2.Cu")
		(net "SGPIO_LD_0")
	)
	(segment
		(start 157.45206 -55.739538)
		(end 155.90266 -57.288938)
		(width 0.127)
		(layer "In2.Cu")
		(net "SGPIO_LD_0")
	)
	(segment
		(start 156.821886 -23.869142)
		(end 157.56128 -23.129748)
		(width 0.127)
		(layer "In2.Cu")
		(net "SGPIO_LD_0")
	)
	(segment
		(start 154.25928 -70.06717)
		(end 153.90368 -70.06717)
		(width 0.127)
		(layer "In2.Cu")
		(net "SGPIO_LD_0")
	)
	(segment
		(start 154.38628 -79.172308)
		(end 155.28544 -80.071468)
		(width 0.127)
		(layer "In2.Cu")
		(net "SGPIO_LD_0")
	)
	(segment
		(start 155.28544 -81.722468)
		(end 154.38628 -82.621628)
		(width 0.127)
		(layer "In2.Cu")
		(net "SGPIO_LD_0")
	)
	(segment
		(start 153.77668 -72.11187)
		(end 153.90368 -72.23887)
		(width 0.127)
		(layer "In2.Cu")
		(net "SGPIO_LD_0")
	)
	(segment
		(start 153.77668 -70.19417)
		(end 153.77668 -70.37451)
		(width 0.127)
		(layer "In2.Cu")
		(net "SGPIO_LD_0")
	)
	(segment
		(start 156.821886 -23.917148)
		(end 156.821886 -23.869142)
		(width 0.127)
		(layer "In2.Cu")
		(net "SGPIO_LD_0")
	)
	(segment
		(start 153.77668 -73.66889)
		(end 153.77668 -73.84923)
		(width 0.127)
		(layer "In2.Cu")
		(net "SGPIO_LD_0")
	)
	(segment
		(start 154.25928 -72.67321)
		(end 153.90368 -72.67321)
		(width 0.127)
		(layer "In2.Cu")
		(net "SGPIO_LD_0")
	)
	(segment
		(start 154.38628 -74.10323)
		(end 154.38628 -79.172308)
		(width 0.127)
		(layer "In2.Cu")
		(net "SGPIO_LD_0")
	)
	(segment
		(start 154.38628 -73.23455)
		(end 154.38628 -73.41489)
		(width 0.127)
		(layer "In2.Cu")
		(net "SGPIO_LD_0")
	)
	(segment
		(start 157.60192 -32.779208)
		(end 157.60192 -39.347648)
		(width 0.127)
		(layer "In2.Cu")
		(net "SGPIO_LD_0")
	)
	(segment
		(start 154.25928 -72.23887)
		(end 154.38628 -72.36587)
		(width 0.127)
		(layer "In2.Cu")
		(net "SGPIO_LD_0")
	)
	(segment
		(start 155.90266 -57.288938)
		(end 155.90266 -65.028318)
		(width 0.127)
		(layer "In2.Cu")
		(net "SGPIO_LD_0")
	)
	(segment
		(start 158.30804 -32.073088)
		(end 157.60192 -32.779208)
		(width 0.127)
		(layer "In2.Cu")
		(net "SGPIO_LD_0")
	)
	(segment
		(start 153.77668 -72.98055)
		(end 153.90368 -73.10755)
		(width 0.127)
		(layer "In2.Cu")
		(net "SGPIO_LD_0")
	)
	(segment
		(start 157.56128 -23.129748)
		(end 158.22168 -23.129748)
		(width 0.127)
		(layer "In2.Cu")
		(net "SGPIO_LD_0")
	)
	(segment
		(start 153.77668 -71.24319)
		(end 153.90368 -71.37019)
		(width 0.127)
		(layer "In2.Cu")
		(net "SGPIO_LD_0")
	)
	(segment
		(start 154.38628 -71.49719)
		(end 154.38628 -71.67753)
		(width 0.127)
		(layer "In2.Cu")
		(net "SGPIO_LD_0")
	)
	(segment
		(start 153.93924 -68.707508)
		(end 154.38628 -69.154548)
		(width 0.127)
		(layer "In2.Cu")
		(net "SGPIO_LD_0")
	)
	(segment
		(start 155.28544 -80.071468)
		(end 155.28544 -81.722468)
		(width 0.127)
		(layer "In2.Cu")
		(net "SGPIO_LD_0")
	)
	(segment
		(start 153.77668 -73.84923)
		(end 153.90368 -73.97623)
		(width 0.127)
		(layer "In2.Cu")
		(net "SGPIO_LD_0")
	)
	(segment
		(start 157.740096 -39.485824)
		(end 157.740096 -41.281604)
		(width 0.127)
		(layer "In2.Cu")
		(net "SGPIO_LD_0")
	)
	(segment
		(start 154.57678 -43.511978)
		(end 154.57678 -48.39716)
		(width 0.127)
		(layer "In2.Cu")
		(net "SGPIO_LD_0")
	)
	(segment
		(start 154.57678 -48.39716)
		(end 155.42768 -49.24806)
		(width 0.127)
		(layer "In2.Cu")
		(net "SGPIO_LD_0")
	)
	(segment
		(start 157.10154 -49.24806)
		(end 157.45206 -49.59858)
		(width 0.127)
		(layer "In2.Cu")
		(net "SGPIO_LD_0")
	)
	(segment
		(start 153.90368 -73.10755)
		(end 154.25928 -73.10755)
		(width 0.127)
		(layer "In2.Cu")
		(net "SGPIO_LD_0")
	)
	(segment
		(start 154.38628 -72.36587)
		(end 154.38628 -72.54621)
		(width 0.127)
		(layer "In2.Cu")
		(net "SGPIO_LD_0")
	)
	(segment
		(start 153.90368 -73.97623)
		(end 154.25928 -73.97623)
		(width 0.127)
		(layer "In2.Cu")
		(net "SGPIO_LD_0")
	)
	(segment
		(start 153.90368 -71.80453)
		(end 153.77668 -71.93153)
		(width 0.127)
		(layer "In2.Cu")
		(net "SGPIO_LD_0")
	)
	(segment
		(start 154.25928 -70.50151)
		(end 154.38628 -70.62851)
		(width 0.127)
		(layer "In2.Cu")
		(net "SGPIO_LD_0")
	)
	(segment
		(start 154.25928 -73.10755)
		(end 154.38628 -73.23455)
		(width 0.127)
		(layer "In2.Cu")
		(net "SGPIO_LD_0")
	)
	(segment
		(start 153.77668 -71.93153)
		(end 153.77668 -72.11187)
		(width 0.127)
		(layer "In2.Cu")
		(net "SGPIO_LD_0")
	)
	(segment
		(start 155.90266 -65.028318)
		(end 153.93924 -66.991738)
		(width 0.127)
		(layer "In2.Cu")
		(net "SGPIO_LD_0")
	)
	(segment
		(start 153.90368 -70.93585)
		(end 153.77668 -71.06285)
		(width 0.127)
		(layer "In2.Cu")
		(net "SGPIO_LD_0")
	)
	(segment
		(start 163.449 -101.844348)
		(end 163.449 -103.337868)
		(width 0.12954)
		(layer "F.Cu")
		(net "SGPIO_DO_1")
	)
	(segment
		(start 155.657042 -16.550132)
		(end 155.657042 -23.17496)
		(width 0.12954)
		(layer "F.Cu")
		(net "SGPIO_DO_1")
	)
	(segment
		(start 163.449 -103.337868)
		(end 163.45408 -103.342948)
		(width 0.12954)
		(layer "F.Cu")
		(net "SGPIO_DO_1")
	)
	(segment
		(start 163.45408 -103.342948)
		(end 164.19195 -103.342948)
		(width 0.12954)
		(layer "F.Cu")
		(net "SGPIO_DO_1")
	)
	(segment
		(start 155.70708 -23.224998)
		(end 155.70708 -23.917148)
		(width 0.12954)
		(layer "F.Cu")
		(net "SGPIO_DO_1")
	)
	(segment
		(start 155.657042 -23.17496)
		(end 155.70708 -23.224998)
		(width 0.12954)
		(layer "F.Cu")
		(net "SGPIO_DO_1")
	)
	(via
		(at 163.449 -101.844348)
		(size 0.508)
		(drill 0.254)
		(layers "F.Cu" "B.Cu")
		(net "SGPIO_DO_1")
	)
	(via
		(at 155.70708 -23.917148)
		(size 0.762)
		(drill 0.254)
		(layers "F.Cu" "B.Cu")
		(net "SGPIO_DO_1")
	)
	(segment
		(start 162.3187 -97.970848)
		(end 161.163 -96.815148)
		(width 0.127)
		(layer "In2.Cu")
		(net "SGPIO_DO_1")
	)
	(segment
		(start 155.45308 -82.827876)
		(end 155.45308 -82.641948)
		(width 0.127)
		(layer "In2.Cu")
		(net "SGPIO_DO_1")
	)
	(segment
		(start 161.88944 -40.356028)
		(end 161.88944 -30.909768)
		(width 0.127)
		(layer "In2.Cu")
		(net "SGPIO_DO_1")
	)
	(segment
		(start 159.56534 -52.560728)
		(end 159.56534 -50.185828)
		(width 0.127)
		(layer "In2.Cu")
		(net "SGPIO_DO_1")
	)
	(segment
		(start 161.88944 -30.909768)
		(end 158.7627 -27.783028)
		(width 0.127)
		(layer "In2.Cu")
		(net "SGPIO_DO_1")
	)
	(segment
		(start 157.8991 -54.226968)
		(end 159.56534 -52.560728)
		(width 0.127)
		(layer "In2.Cu")
		(net "SGPIO_DO_1")
	)
	(segment
		(start 160.95472 -41.290748)
		(end 161.88944 -40.356028)
		(width 0.127)
		(layer "In2.Cu")
		(net "SGPIO_DO_1")
	)
	(segment
		(start 161.66084 -43.729148)
		(end 160.95472 -43.023028)
		(width 0.127)
		(layer "In2.Cu")
		(net "SGPIO_DO_1")
	)
	(segment
		(start 154.94508 -82.954876)
		(end 155.32608 -82.954876)
		(width 0.127)
		(layer "In2.Cu")
		(net "SGPIO_DO_1")
	)
	(segment
		(start 158.52648 -22.596348)
		(end 157.00248 -22.596348)
		(width 0.127)
		(layer "In2.Cu")
		(net "SGPIO_DO_1")
	)
	(segment
		(start 161.19602 -48.555148)
		(end 161.19602 -45.908468)
		(width 0.127)
		(layer "In2.Cu")
		(net "SGPIO_DO_1")
	)
	(segment
		(start 155.45308 -82.641948)
		(end 155.84678 -82.248248)
		(width 0.127)
		(layer "In2.Cu")
		(net "SGPIO_DO_1")
	)
	(segment
		(start 162.3187 -99.952048)
		(end 162.3187 -97.970848)
		(width 0.127)
		(layer "In2.Cu")
		(net "SGPIO_DO_1")
	)
	(segment
		(start 163.449 -101.844348)
		(end 163.449 -101.082348)
		(width 0.127)
		(layer "In2.Cu")
		(net "SGPIO_DO_1")
	)
	(segment
		(start 155.32608 -82.954876)
		(end 155.45308 -82.827876)
		(width 0.127)
		(layer "In2.Cu")
		(net "SGPIO_DO_1")
	)
	(segment
		(start 154.81808 -83.262216)
		(end 154.81808 -83.081876)
		(width 0.127)
		(layer "In2.Cu")
		(net "SGPIO_DO_1")
	)
	(segment
		(start 156.3497 -65.213738)
		(end 156.3497 -57.474358)
		(width 0.127)
		(layer "In2.Cu")
		(net "SGPIO_DO_1")
	)
	(segment
		(start 160.95472 -43.023028)
		(end 160.95472 -41.290748)
		(width 0.127)
		(layer "In2.Cu")
		(net "SGPIO_DO_1")
	)
	(segment
		(start 155.45308 -83.516216)
		(end 155.32608 -83.389216)
		(width 0.127)
		(layer "In2.Cu")
		(net "SGPIO_DO_1")
	)
	(segment
		(start 154.81808 -83.081876)
		(end 154.94508 -82.954876)
		(width 0.127)
		(layer "In2.Cu")
		(net "SGPIO_DO_1")
	)
	(segment
		(start 158.7627 -27.783028)
		(end 158.7627 -26.203148)
		(width 0.127)
		(layer "In2.Cu")
		(net "SGPIO_DO_1")
	)
	(segment
		(start 154.37104 -67.192398)
		(end 156.3497 -65.213738)
		(width 0.127)
		(layer "In2.Cu")
		(net "SGPIO_DO_1")
	)
	(segment
		(start 159.56534 -50.185828)
		(end 161.19602 -48.555148)
		(width 0.127)
		(layer "In2.Cu")
		(net "SGPIO_DO_1")
	)
	(segment
		(start 155.1432 -69.240908)
		(end 154.37104 -68.468748)
		(width 0.127)
		(layer "In2.Cu")
		(net "SGPIO_DO_1")
	)
	(segment
		(start 155.32608 -83.389216)
		(end 154.94508 -83.389216)
		(width 0.127)
		(layer "In2.Cu")
		(net "SGPIO_DO_1")
	)
	(segment
		(start 161.66084 -45.443648)
		(end 161.66084 -43.729148)
		(width 0.127)
		(layer "In2.Cu")
		(net "SGPIO_DO_1")
	)
	(segment
		(start 157.00248 -22.596348)
		(end 155.70708 -23.891748)
		(width 0.127)
		(layer "In2.Cu")
		(net "SGPIO_DO_1")
	)
	(segment
		(start 154.94508 -83.389216)
		(end 154.81808 -83.262216)
		(width 0.127)
		(layer "In2.Cu")
		(net "SGPIO_DO_1")
	)
	(segment
		(start 161.163 -96.815148)
		(end 161.163 -91.316048)
		(width 0.127)
		(layer "In2.Cu")
		(net "SGPIO_DO_1")
	)
	(segment
		(start 161.19602 -45.908468)
		(end 161.66084 -45.443648)
		(width 0.127)
		(layer "In2.Cu")
		(net "SGPIO_DO_1")
	)
	(segment
		(start 158.7627 -26.203148)
		(end 159.23768 -25.728168)
		(width 0.127)
		(layer "In2.Cu")
		(net "SGPIO_DO_1")
	)
	(segment
		(start 155.70708 -23.891748)
		(end 155.70708 -23.917148)
		(width 0.127)
		(layer "In2.Cu")
		(net "SGPIO_DO_1")
	)
	(segment
		(start 161.163 -91.316048)
		(end 155.45308 -85.606128)
		(width 0.127)
		(layer "In2.Cu")
		(net "SGPIO_DO_1")
	)
	(segment
		(start 159.23768 -23.307548)
		(end 158.52648 -22.596348)
		(width 0.127)
		(layer "In2.Cu")
		(net "SGPIO_DO_1")
	)
	(segment
		(start 155.84678 -82.248248)
		(end 155.84678 -79.962248)
		(width 0.127)
		(layer "In2.Cu")
		(net "SGPIO_DO_1")
	)
	(segment
		(start 156.3497 -57.474358)
		(end 157.8991 -55.924958)
		(width 0.127)
		(layer "In2.Cu")
		(net "SGPIO_DO_1")
	)
	(segment
		(start 155.84678 -79.962248)
		(end 155.1432 -79.258668)
		(width 0.127)
		(layer "In2.Cu")
		(net "SGPIO_DO_1")
	)
	(segment
		(start 163.449 -101.082348)
		(end 162.3187 -99.952048)
		(width 0.127)
		(layer "In2.Cu")
		(net "SGPIO_DO_1")
	)
	(segment
		(start 154.37104 -68.468748)
		(end 154.37104 -67.192398)
		(width 0.127)
		(layer "In2.Cu")
		(net "SGPIO_DO_1")
	)
	(segment
		(start 159.23768 -25.728168)
		(end 159.23768 -23.307548)
		(width 0.127)
		(layer "In2.Cu")
		(net "SGPIO_DO_1")
	)
	(segment
		(start 155.1432 -79.258668)
		(end 155.1432 -69.240908)
		(width 0.127)
		(layer "In2.Cu")
		(net "SGPIO_DO_1")
	)
	(segment
		(start 155.45308 -85.606128)
		(end 155.45308 -83.516216)
		(width 0.127)
		(layer "In2.Cu")
		(net "SGPIO_DO_1")
	)
	(segment
		(start 157.8991 -55.924958)
		(end 157.8991 -54.226968)
		(width 0.127)
		(layer "In2.Cu")
		(net "SGPIO_DO_1")
	)
	(segment
		(start 158.657036 -16.550132)
		(end 158.657036 -18.281904)
		(width 0.12954)
		(layer "F.Cu")
		(net "SGPIO_DO_0")
	)
	(segment
		(start 159.004 -18.628868)
		(end 159.004 -24.549608)
		(width 0.12954)
		(layer "F.Cu")
		(net "SGPIO_DO_0")
	)
	(segment
		(start 159.639 -102.961948)
		(end 160.02 -103.342948)
		(width 0.12954)
		(layer "F.Cu")
		(net "SGPIO_DO_0")
	)
	(segment
		(start 160.02 -103.342948)
		(end 160.38195 -103.342948)
		(width 0.12954)
		(layer "F.Cu")
		(net "SGPIO_DO_0")
	)
	(segment
		(start 158.12516 -25.428448)
		(end 157.61716 -25.428448)
		(width 0.12954)
		(layer "F.Cu")
		(net "SGPIO_DO_0")
	)
	(segment
		(start 159.639 -102.199948)
		(end 159.639 -102.961948)
		(width 0.12954)
		(layer "F.Cu")
		(net "SGPIO_DO_0")
	)
	(segment
		(start 159.004 -24.549608)
		(end 158.12516 -25.428448)
		(width 0.12954)
		(layer "F.Cu")
		(net "SGPIO_DO_0")
	)
	(segment
		(start 158.657036 -18.281904)
		(end 159.004 -18.628868)
		(width 0.12954)
		(layer "F.Cu")
		(net "SGPIO_DO_0")
	)
	(via
		(at 157.61716 -25.428448)
		(size 0.508)
		(drill 0.254)
		(layers "F.Cu" "B.Cu")
		(net "SGPIO_DO_0")
	)
	(via
		(at 159.639 -102.199948)
		(size 0.508)
		(drill 0.254)
		(layers "F.Cu" "B.Cu")
		(net "SGPIO_DO_0")
	)
	(segment
		(start 153.77668 -81.005172)
		(end 153.90368 -81.132172)
		(width 0.127)
		(layer "In2.Cu")
		(net "SGPIO_DO_0")
	)
	(segment
		(start 153.40457 -77.530452)
		(end 153.77668 -77.530452)
		(width 0.127)
		(layer "In2.Cu")
		(net "SGPIO_DO_0")
	)
	(segment
		(start 155.46324 -64.8462)
		(end 153.27757 -67.03187)
		(width 0.127)
		(layer "In2.Cu")
		(net "SGPIO_DO_0")
	)
	(segment
		(start 153.90368 -80.263492)
		(end 153.90368 -80.443832)
		(width 0.127)
		(layer "In2.Cu")
		(net "SGPIO_DO_0")
	)
	(segment
		(start 157.61716 -25.428448)
		(end 157.6578 -25.469088)
		(width 0.127)
		(layer "In2.Cu")
		(net "SGPIO_DO_0")
	)
	(segment
		(start 153.77668 -83.176872)
		(end 153.40457 -83.176872)
		(width 0.127)
		(layer "In2.Cu")
		(net "SGPIO_DO_0")
	)
	(segment
		(start 157.1625 -41.09974)
		(end 156.56814 -41.6941)
		(width 0.127)
		(layer "In2.Cu")
		(net "SGPIO_DO_0")
	)
	(segment
		(start 153.90368 -83.049872)
		(end 153.77668 -83.176872)
		(width 0.127)
		(layer "In2.Cu")
		(net "SGPIO_DO_0")
	)
	(segment
		(start 153.77668 -81.873852)
		(end 153.90368 -82.000852)
		(width 0.127)
		(layer "In2.Cu")
		(net "SGPIO_DO_0")
	)
	(segment
		(start 153.77668 -77.964792)
		(end 153.40457 -77.964792)
		(width 0.127)
		(layer "In2.Cu")
		(net "SGPIO_DO_0")
	)
	(segment
		(start 153.40457 -81.873852)
		(end 153.77668 -81.873852)
		(width 0.127)
		(layer "In2.Cu")
		(net "SGPIO_DO_0")
	)
	(segment
		(start 153.90368 -77.657452)
		(end 153.90368 -77.837792)
		(width 0.127)
		(layer "In2.Cu")
		(net "SGPIO_DO_0")
	)
	(segment
		(start 157.1625 -39.548308)
		(end 157.1625 -41.09974)
		(width 0.127)
		(layer "In2.Cu")
		(net "SGPIO_DO_0")
	)
	(segment
		(start 157.6578 -31.692088)
		(end 157.07868 -32.271208)
		(width 0.127)
		(layer "In2.Cu")
		(net "SGPIO_DO_0")
	)
	(segment
		(start 155.744672 -41.6941)
		(end 153.84526 -43.593512)
		(width 0.127)
		(layer "In2.Cu")
		(net "SGPIO_DO_0")
	)
	(segment
		(start 153.27757 -78.272132)
		(end 153.40457 -78.399132)
		(width 0.127)
		(layer "In2.Cu")
		(net "SGPIO_DO_0")
	)
	(segment
		(start 153.84526 -48.697388)
		(end 155.531566 -50.383694)
		(width 0.127)
		(layer "In2.Cu")
		(net "SGPIO_DO_0")
	)
	(segment
		(start 153.90368 -82.869532)
		(end 153.90368 -83.049872)
		(width 0.127)
		(layer "In2.Cu")
		(net "SGPIO_DO_0")
	)
	(segment
		(start 153.27757 -79.829152)
		(end 153.27757 -80.009492)
		(width 0.127)
		(layer "In2.Cu")
		(net "SGPIO_DO_0")
	)
	(segment
		(start 153.27757 -82.615532)
		(end 153.40457 -82.742532)
		(width 0.127)
		(layer "In2.Cu")
		(net "SGPIO_DO_0")
	)
	(segment
		(start 153.77668 -78.833472)
		(end 153.40457 -78.833472)
		(width 0.127)
		(layer "In2.Cu")
		(net "SGPIO_DO_0")
	)
	(segment
		(start 153.90368 -82.181192)
		(end 153.77668 -82.308192)
		(width 0.127)
		(layer "In2.Cu")
		(net "SGPIO_DO_0")
	)
	(segment
		(start 153.27757 -80.697832)
		(end 153.27757 -80.878172)
		(width 0.127)
		(layer "In2.Cu")
		(net "SGPIO_DO_0")
	)
	(segment
		(start 155.46324 -57.10682)
		(end 155.46324 -64.8462)
		(width 0.127)
		(layer "In2.Cu")
		(net "SGPIO_DO_0")
	)
	(segment
		(start 153.90368 -82.000852)
		(end 153.90368 -82.181192)
		(width 0.127)
		(layer "In2.Cu")
		(net "SGPIO_DO_0")
	)
	(segment
		(start 153.77668 -79.702152)
		(end 153.40457 -79.702152)
		(width 0.127)
		(layer "In2.Cu")
		(net "SGPIO_DO_0")
	)
	(segment
		(start 153.90368 -79.575152)
		(end 153.77668 -79.702152)
		(width 0.127)
		(layer "In2.Cu")
		(net "SGPIO_DO_0")
	)
	(segment
		(start 153.40457 -78.833472)
		(end 153.27757 -78.960472)
		(width 0.127)
		(layer "In2.Cu")
		(net "SGPIO_DO_0")
	)
	(segment
		(start 153.40457 -79.702152)
		(end 153.27757 -79.829152)
		(width 0.127)
		(layer "In2.Cu")
		(net "SGPIO_DO_0")
	)
	(segment
		(start 157.01264 -55.55742)
		(end 155.46324 -57.10682)
		(width 0.127)
		(layer "In2.Cu")
		(net "SGPIO_DO_0")
	)
	(segment
		(start 156.56814 -41.6941)
		(end 155.744672 -41.6941)
		(width 0.127)
		(layer "In2.Cu")
		(net "SGPIO_DO_0")
	)
	(segment
		(start 153.77668 -78.399132)
		(end 153.90368 -78.526132)
		(width 0.127)
		(layer "In2.Cu")
		(net "SGPIO_DO_0")
	)
	(segment
		(start 153.27757 -77.403452)
		(end 153.40457 -77.530452)
		(width 0.127)
		(layer "In2.Cu")
		(net "SGPIO_DO_0")
	)
	(segment
		(start 153.90368 -81.312512)
		(end 153.77668 -81.439512)
		(width 0.127)
		(layer "In2.Cu")
		(net "SGPIO_DO_0")
	)
	(segment
		(start 153.77668 -82.308192)
		(end 153.40457 -82.308192)
		(width 0.127)
		(layer "In2.Cu")
		(net "SGPIO_DO_0")
	)
	(segment
		(start 153.27757 -84.710016)
		(end 160.24606 -91.678506)
		(width 0.127)
		(layer "In2.Cu")
		(net "SGPIO_DO_0")
	)
	(segment
		(start 153.27757 -81.566512)
		(end 153.27757 -81.746852)
		(width 0.127)
		(layer "In2.Cu")
		(net "SGPIO_DO_0")
	)
	(segment
		(start 156.680154 -50.383694)
		(end 157.01264 -50.71618)
		(width 0.127)
		(layer "In2.Cu")
		(net "SGPIO_DO_0")
	)
	(segment
		(start 153.40457 -81.439512)
		(end 153.27757 -81.566512)
		(width 0.127)
		(layer "In2.Cu")
		(net "SGPIO_DO_0")
	)
	(segment
		(start 157.07868 -32.271208)
		(end 157.07868 -39.464488)
		(width 0.127)
		(layer "In2.Cu")
		(net "SGPIO_DO_0")
	)
	(segment
		(start 153.90368 -78.526132)
		(end 153.90368 -78.706472)
		(width 0.127)
		(layer "In2.Cu")
		(net "SGPIO_DO_0")
	)
	(segment
		(start 153.27757 -83.303872)
		(end 153.27757 -84.710016)
		(width 0.127)
		(layer "In2.Cu")
		(net "SGPIO_DO_0")
	)
	(segment
		(start 153.77668 -79.267812)
		(end 153.90368 -79.394812)
		(width 0.127)
		(layer "In2.Cu")
		(net "SGPIO_DO_0")
	)
	(segment
		(start 153.40457 -83.176872)
		(end 153.27757 -83.303872)
		(width 0.127)
		(layer "In2.Cu")
		(net "SGPIO_DO_0")
	)
	(segment
		(start 157.6578 -25.469088)
		(end 157.6578 -31.692088)
		(width 0.127)
		(layer "In2.Cu")
		(net "SGPIO_DO_0")
	)
	(segment
		(start 153.40457 -80.570832)
		(end 153.27757 -80.697832)
		(width 0.127)
		(layer "In2.Cu")
		(net "SGPIO_DO_0")
	)
	(segment
		(start 153.27757 -80.878172)
		(end 153.40457 -81.005172)
		(width 0.127)
		(layer "In2.Cu")
		(net "SGPIO_DO_0")
	)
	(segment
		(start 153.27757 -82.435192)
		(end 153.27757 -82.615532)
		(width 0.127)
		(layer "In2.Cu")
		(net "SGPIO_DO_0")
	)
	(segment
		(start 153.27757 -67.03187)
		(end 153.27757 -77.403452)
		(width 0.127)
		(layer "In2.Cu")
		(net "SGPIO_DO_0")
	)
	(segment
		(start 153.90368 -77.837792)
		(end 153.77668 -77.964792)
		(width 0.127)
		(layer "In2.Cu")
		(net "SGPIO_DO_0")
	)
	(segment
		(start 153.27757 -81.746852)
		(end 153.40457 -81.873852)
		(width 0.127)
		(layer "In2.Cu")
		(net "SGPIO_DO_0")
	)
	(segment
		(start 153.77668 -81.439512)
		(end 153.40457 -81.439512)
		(width 0.127)
		(layer "In2.Cu")
		(net "SGPIO_DO_0")
	)
	(segment
		(start 153.27757 -78.091792)
		(end 153.27757 -78.272132)
		(width 0.127)
		(layer "In2.Cu")
		(net "SGPIO_DO_0")
	)
	(segment
		(start 153.77668 -82.742532)
		(end 153.90368 -82.869532)
		(width 0.127)
		(layer "In2.Cu")
		(net "SGPIO_DO_0")
	)
	(segment
		(start 153.90368 -81.132172)
		(end 153.90368 -81.312512)
		(width 0.127)
		(layer "In2.Cu")
		(net "SGPIO_DO_0")
	)
	(segment
		(start 153.40457 -80.136492)
		(end 153.77668 -80.136492)
		(width 0.127)
		(layer "In2.Cu")
		(net "SGPIO_DO_0")
	)
	(segment
		(start 153.90368 -78.706472)
		(end 153.77668 -78.833472)
		(width 0.127)
		(layer "In2.Cu")
		(net "SGPIO_DO_0")
	)
	(segment
		(start 153.40457 -78.399132)
		(end 153.77668 -78.399132)
		(width 0.127)
		(layer "In2.Cu")
		(net "SGPIO_DO_0")
	)
	(segment
		(start 153.27757 -80.009492)
		(end 153.40457 -80.136492)
		(width 0.127)
		(layer "In2.Cu")
		(net "SGPIO_DO_0")
	)
	(segment
		(start 153.40457 -77.964792)
		(end 153.27757 -78.091792)
		(width 0.127)
		(layer "In2.Cu")
		(net "SGPIO_DO_0")
	)
	(segment
		(start 153.77668 -80.570832)
		(end 153.40457 -80.570832)
		(width 0.127)
		(layer "In2.Cu")
		(net "SGPIO_DO_0")
	)
	(segment
		(start 157.07868 -39.464488)
		(end 157.1625 -39.548308)
		(width 0.127)
		(layer "In2.Cu")
		(net "SGPIO_DO_0")
	)
	(segment
		(start 153.27757 -78.960472)
		(end 153.27757 -79.140812)
		(width 0.127)
		(layer "In2.Cu")
		(net "SGPIO_DO_0")
	)
	(segment
		(start 153.40457 -79.267812)
		(end 153.77668 -79.267812)
		(width 0.127)
		(layer "In2.Cu")
		(net "SGPIO_DO_0")
	)
	(segment
		(start 153.27757 -79.140812)
		(end 153.40457 -79.267812)
		(width 0.127)
		(layer "In2.Cu")
		(net "SGPIO_DO_0")
	)
	(segment
		(start 153.90368 -80.443832)
		(end 153.77668 -80.570832)
		(width 0.127)
		(layer "In2.Cu")
		(net "SGPIO_DO_0")
	)
	(segment
		(start 153.90368 -79.394812)
		(end 153.90368 -79.575152)
		(width 0.127)
		(layer "In2.Cu")
		(net "SGPIO_DO_0")
	)
	(segment
		(start 160.24606 -98.417888)
		(end 159.639 -99.024948)
		(width 0.127)
		(layer "In2.Cu")
		(net "SGPIO_DO_0")
	)
	(segment
		(start 153.40457 -82.308192)
		(end 153.27757 -82.435192)
		(width 0.127)
		(layer "In2.Cu")
		(net "SGPIO_DO_0")
	)
	(segment
		(start 160.24606 -91.678506)
		(end 160.24606 -98.417888)
		(width 0.127)
		(layer "In2.Cu")
		(net "SGPIO_DO_0")
	)
	(segment
		(start 153.84526 -43.593512)
		(end 153.84526 -48.697388)
		(width 0.127)
		(layer "In2.Cu")
		(net "SGPIO_DO_0")
	)
	(segment
		(start 159.639 -99.024948)
		(end 159.639 -102.199948)
		(width 0.127)
		(layer "In2.Cu")
		(net "SGPIO_DO_0")
	)
	(segment
		(start 155.531566 -50.383694)
		(end 156.680154 -50.383694)
		(width 0.127)
		(layer "In2.Cu")
		(net "SGPIO_DO_0")
	)
	(segment
		(start 153.40457 -81.005172)
		(end 153.77668 -81.005172)
		(width 0.127)
		(layer "In2.Cu")
		(net "SGPIO_DO_0")
	)
	(segment
		(start 153.77668 -77.530452)
		(end 153.90368 -77.657452)
		(width 0.127)
		(layer "In2.Cu")
		(net "SGPIO_DO_0")
	)
	(segment
		(start 153.77668 -80.136492)
		(end 153.90368 -80.263492)
		(width 0.127)
		(layer "In2.Cu")
		(net "SGPIO_DO_0")
	)
	(segment
		(start 153.40457 -82.742532)
		(end 153.77668 -82.742532)
		(width 0.127)
		(layer "In2.Cu")
		(net "SGPIO_DO_0")
	)
	(segment
		(start 157.01264 -50.71618)
		(end 157.01264 -55.55742)
		(width 0.127)
		(layer "In2.Cu")
		(net "SGPIO_DO_0")
	)
	(segment
		(start 154.456892 -20.011136)
		(end 153.92908 -20.538948)
		(width 0.12954)
		(layer "F.Cu")
		(net "SGPIO_DI_1")
	)
	(segment
		(start 151.26208 -85.257132)
		(end 151.26208 -79.974948)
		(width 0.12954)
		(layer "F.Cu")
		(net "SGPIO_DI_1")
	)
	(segment
		(start 154.456892 -16.550132)
		(end 154.456892 -20.011136)
		(width 0.12954)
		(layer "F.Cu")
		(net "SGPIO_DI_1")
	)
	(segment
		(start 153.92908 -20.538948)
		(end 153.92908 -21.478748)
		(width 0.12954)
		(layer "F.Cu")
		(net "SGPIO_DI_1")
	)
	(segment
		(start 155.630372 -89.625424)
		(end 151.26208 -85.257132)
		(width 0.12954)
		(layer "F.Cu")
		(net "SGPIO_DI_1")
	)
	(segment
		(start 155.630372 -107.534456)
		(end 155.630372 -89.625424)
		(width 0.12954)
		(layer "F.Cu")
		(net "SGPIO_DI_1")
	)
	(segment
		(start 155.12288 -117.566948)
		(end 154.29357 -116.737638)
		(width 0.12954)
		(layer "F.Cu")
		(net "SGPIO_DI_1")
	)
	(segment
		(start 154.29357 -108.871258)
		(end 155.630372 -107.534456)
		(width 0.12954)
		(layer "F.Cu")
		(net "SGPIO_DI_1")
	)
	(segment
		(start 154.29357 -116.737638)
		(end 154.29357 -108.871258)
		(width 0.12954)
		(layer "F.Cu")
		(net "SGPIO_DI_1")
	)
	(via
		(at 153.92908 -21.478748)
		(size 0.508)
		(drill 0.254)
		(layers "F.Cu" "B.Cu")
		(net "SGPIO_DI_1")
	)
	(via
		(at 155.12288 -117.566948)
		(size 0.508)
		(drill 0.254)
		(layers "F.Cu" "B.Cu")
		(net "SGPIO_DI_1")
	)
	(via
		(at 151.26208 -79.974948)
		(size 0.508)
		(drill 0.254)
		(layers "F.Cu" "B.Cu")
		(net "SGPIO_DI_1")
	)
	(segment
		(start 155.12288 -117.211348)
		(end 155.30068 -117.033548)
		(width 0.12954)
		(layer "B.Cu")
		(net "SGPIO_DI_1")
	)
	(segment
		(start 155.12288 -117.566948)
		(end 155.12288 -117.211348)
		(width 0.12954)
		(layer "B.Cu")
		(net "SGPIO_DI_1")
	)
	(segment
		(start 155.30068 -117.033548)
		(end 156.44368 -117.033548)
		(width 0.12954)
		(layer "B.Cu")
		(net "SGPIO_DI_1")
	)
	(segment
		(start 156.44368 -117.033548)
		(end 156.62783 -117.217698)
		(width 0.12954)
		(layer "B.Cu")
		(net "SGPIO_DI_1")
	)
	(segment
		(start 156.62783 -117.217698)
		(end 156.62783 -117.566948)
		(width 0.12954)
		(layer "B.Cu")
		(net "SGPIO_DI_1")
	)
	(segment
		(start 153.92908 -34.699448)
		(end 154.96794 -35.738308)
		(width 0.127)
		(layer "In2.Cu")
		(net "SGPIO_DI_1")
	)
	(segment
		(start 153.92908 -21.478748)
		(end 153.92908 -34.699448)
		(width 0.127)
		(layer "In2.Cu")
		(net "SGPIO_DI_1")
	)
	(segment
		(start 153.482294 -40.853614)
		(end 152.595326 -40.853614)
		(width 0.127)
		(layer "In2.Cu")
		(net "SGPIO_DI_1")
	)
	(segment
		(start 151.86152 -65.227962)
		(end 151.86152 -79.375508)
		(width 0.127)
		(layer "In2.Cu")
		(net "SGPIO_DI_1")
	)
	(segment
		(start 154.96794 -39.367968)
		(end 153.482294 -40.853614)
		(width 0.127)
		(layer "In2.Cu")
		(net "SGPIO_DI_1")
	)
	(segment
		(start 153.72588 -63.363602)
		(end 151.86152 -65.227962)
		(width 0.127)
		(layer "In2.Cu")
		(net "SGPIO_DI_1")
	)
	(segment
		(start 154.96794 -35.738308)
		(end 154.96794 -39.367968)
		(width 0.127)
		(layer "In2.Cu")
		(net "SGPIO_DI_1")
	)
	(segment
		(start 152.595326 -40.853614)
		(end 149.3012 -44.14774)
		(width 0.127)
		(layer "In2.Cu")
		(net "SGPIO_DI_1")
	)
	(segment
		(start 153.72588 -52.291488)
		(end 153.72588 -63.363602)
		(width 0.127)
		(layer "In2.Cu")
		(net "SGPIO_DI_1")
	)
	(segment
		(start 151.86152 -79.375508)
		(end 151.26208 -79.974948)
		(width 0.127)
		(layer "In2.Cu")
		(net "SGPIO_DI_1")
	)
	(segment
		(start 151.79548 -50.361088)
		(end 153.72588 -52.291488)
		(width 0.127)
		(layer "In2.Cu")
		(net "SGPIO_DI_1")
	)
	(segment
		(start 151.79548 -49.48428)
		(end 151.79548 -50.361088)
		(width 0.127)
		(layer "In2.Cu")
		(net "SGPIO_DI_1")
	)
	(segment
		(start 149.3012 -46.99)
		(end 151.79548 -49.48428)
		(width 0.127)
		(layer "In2.Cu")
		(net "SGPIO_DI_1")
	)
	(segment
		(start 149.3012 -44.14774)
		(end 149.3012 -46.99)
		(width 0.127)
		(layer "In2.Cu")
		(net "SGPIO_DI_1")
	)
	(segment
		(start 161.93008 -116.906548)
		(end 155.04668 -116.906548)
		(width 0.12954)
		(layer "F.Cu")
		(net "SGPIO_DI_0")
	)
	(segment
		(start 157.45714 -16.550132)
		(end 157.45714 -24.112728)
		(width 0.12954)
		(layer "F.Cu")
		(net "SGPIO_DI_0")
	)
	(segment
		(start 152.48128 -80.127348)
		(end 152.30348 -79.949548)
		(width 0.12954)
		(layer "F.Cu")
		(net "SGPIO_DI_0")
	)
	(segment
		(start 163.22548 -118.201948)
		(end 161.93008 -116.906548)
		(width 0.12954)
		(layer "F.Cu")
		(net "SGPIO_DI_0")
	)
	(segment
		(start 156.036772 -89.52484)
		(end 152.48128 -85.969348)
		(width 0.12954)
		(layer "F.Cu")
		(net "SGPIO_DI_0")
	)
	(segment
		(start 155.04668 -116.906548)
		(end 154.65171 -116.511578)
		(width 0.12954)
		(layer "F.Cu")
		(net "SGPIO_DI_0")
	)
	(segment
		(start 157.45714 -24.112728)
		(end 156.86659 -24.703278)
		(width 0.12954)
		(layer "F.Cu")
		(net "SGPIO_DI_0")
	)
	(segment
		(start 154.65171 -116.511578)
		(end 154.65171 -109.097318)
		(width 0.12954)
		(layer "F.Cu")
		(net "SGPIO_DI_0")
	)
	(segment
		(start 163.957254 -118.201948)
		(end 163.22548 -118.201948)
		(width 0.12954)
		(layer "F.Cu")
		(net "SGPIO_DI_0")
	)
	(segment
		(start 156.036772 -107.712256)
		(end 156.036772 -89.52484)
		(width 0.12954)
		(layer "F.Cu")
		(net "SGPIO_DI_0")
	)
	(segment
		(start 152.48128 -85.969348)
		(end 152.48128 -80.127348)
		(width 0.12954)
		(layer "F.Cu")
		(net "SGPIO_DI_0")
	)
	(segment
		(start 164.24783 -117.566948)
		(end 164.24783 -117.911372)
		(width 0.12954)
		(layer "F.Cu")
		(net "SGPIO_DI_0")
	)
	(segment
		(start 154.65171 -109.097318)
		(end 156.036772 -107.712256)
		(width 0.12954)
		(layer "F.Cu")
		(net "SGPIO_DI_0")
	)
	(segment
		(start 164.24783 -117.911372)
		(end 163.957254 -118.201948)
		(width 0.12954)
		(layer "F.Cu")
		(net "SGPIO_DI_0")
	)
	(via
		(at 156.86659 -24.703278)
		(size 0.762)
		(drill 0.254)
		(layers "F.Cu" "B.Cu")
		(net "SGPIO_DI_0")
	)
	(via
		(at 152.30348 -79.949548)
		(size 0.508)
		(drill 0.254)
		(layers "F.Cu" "B.Cu")
		(net "SGPIO_DI_0")
	)
	(segment
		(start 154.15768 -63.769748)
		(end 152.30348 -65.623948)
		(width 0.127)
		(layer "In2.Cu")
		(net "SGPIO_DI_0")
	)
	(segment
		(start 152.30348 -65.623948)
		(end 152.30348 -79.949548)
		(width 0.127)
		(layer "In2.Cu")
		(net "SGPIO_DI_0")
	)
	(segment
		(start 154.78252 -41.361868)
		(end 152.86482 -43.279568)
		(width 0.127)
		(layer "In2.Cu")
		(net "SGPIO_DI_0")
	)
	(segment
		(start 155.96108 -25.608788)
		(end 155.96108 -29.324808)
		(width 0.127)
		(layer "In2.Cu")
		(net "SGPIO_DI_0")
	)
	(segment
		(start 155.50134 -35.311588)
		(end 156.1211 -35.931348)
		(width 0.127)
		(layer "In2.Cu")
		(net "SGPIO_DI_0")
	)
	(segment
		(start 156.1211 -35.931348)
		(end 156.1211 -39.667688)
		(width 0.127)
		(layer "In2.Cu")
		(net "SGPIO_DI_0")
	)
	(segment
		(start 154.78252 -41.006268)
		(end 154.78252 -41.361868)
		(width 0.127)
		(layer "In2.Cu")
		(net "SGPIO_DI_0")
	)
	(segment
		(start 155.50134 -29.784548)
		(end 155.50134 -35.311588)
		(width 0.127)
		(layer "In2.Cu")
		(net "SGPIO_DI_0")
	)
	(segment
		(start 156.1211 -39.667688)
		(end 154.78252 -41.006268)
		(width 0.127)
		(layer "In2.Cu")
		(net "SGPIO_DI_0")
	)
	(segment
		(start 152.86482 -43.279568)
		(end 152.86482 -50.68062)
		(width 0.127)
		(layer "In2.Cu")
		(net "SGPIO_DI_0")
	)
	(segment
		(start 155.96108 -29.324808)
		(end 155.50134 -29.784548)
		(width 0.127)
		(layer "In2.Cu")
		(net "SGPIO_DI_0")
	)
	(segment
		(start 156.86659 -24.703278)
		(end 155.96108 -25.608788)
		(width 0.127)
		(layer "In2.Cu")
		(net "SGPIO_DI_0")
	)
	(segment
		(start 152.86482 -50.68062)
		(end 154.15768 -51.97348)
		(width 0.127)
		(layer "In2.Cu")
		(net "SGPIO_DI_0")
	)
	(segment
		(start 154.15768 -51.97348)
		(end 154.15768 -63.769748)
		(width 0.127)
		(layer "In2.Cu")
		(net "SGPIO_DI_0")
	)
	(segment
		(start 174.155608 -115.375436)
		(end 173.755558 -115.775486)
		(width 0.12954)
		(layer "F.Cu")
		(net "SGPIO_BMC_LD_N")
	)
	(segment
		(start 164.86505 -99.786948)
		(end 164.86505 -99.043998)
		(width 0.12954)
		(layer "F.Cu")
		(net "SGPIO_BMC_LD_N")
	)
	(via
		(at 164.86505 -99.043998)
		(size 0.508)
		(drill 0.254)
		(layers "F.Cu" "B.Cu")
		(net "SGPIO_BMC_LD_N")
	)
	(via
		(at 173.755558 -115.775486)
		(size 0.4572)
		(drill 0.254)
		(layers "F.Cu" "B.Cu")
		(net "SGPIO_BMC_LD_N")
	)
	(segment
		(start 173.35246 -113.952528)
		(end 172.66412 -113.264188)
		(width 0.127)
		(layer "In2.Cu")
		(net "SGPIO_BMC_LD_N")
	)
	(segment
		(start 168.985438 -111.769906)
		(end 168.26738 -111.051848)
		(width 0.127)
		(layer "In2.Cu")
		(net "SGPIO_BMC_LD_N")
	)
	(segment
		(start 173.35246 -115.372388)
		(end 173.35246 -113.952528)
		(width 0.127)
		(layer "In2.Cu")
		(net "SGPIO_BMC_LD_N")
	)
	(segment
		(start 172.130212 -112.9792)
		(end 171.20362 -112.9792)
		(width 0.127)
		(layer "In2.Cu")
		(net "SGPIO_BMC_LD_N")
	)
	(segment
		(start 168.26738 -103.988108)
		(end 168.39184 -103.863648)
		(width 0.127)
		(layer "In2.Cu")
		(net "SGPIO_BMC_LD_N")
	)
	(segment
		(start 168.39184 -100.802948)
		(end 166.63289 -99.043998)
		(width 0.127)
		(layer "In2.Cu")
		(net "SGPIO_BMC_LD_N")
	)
	(segment
		(start 168.39184 -103.863648)
		(end 168.39184 -100.802948)
		(width 0.127)
		(layer "In2.Cu")
		(net "SGPIO_BMC_LD_N")
	)
	(segment
		(start 173.755558 -115.775486)
		(end 173.35246 -115.372388)
		(width 0.127)
		(layer "In2.Cu")
		(net "SGPIO_BMC_LD_N")
	)
	(segment
		(start 168.26738 -111.051848)
		(end 168.26738 -103.988108)
		(width 0.127)
		(layer "In2.Cu")
		(net "SGPIO_BMC_LD_N")
	)
	(segment
		(start 170.524424 -111.9886)
		(end 170.199558 -111.9886)
		(width 0.127)
		(layer "In2.Cu")
		(net "SGPIO_BMC_LD_N")
	)
	(segment
		(start 170.948604 -112.724184)
		(end 170.948604 -112.41278)
		(width 0.127)
		(layer "In2.Cu")
		(net "SGPIO_BMC_LD_N")
	)
	(segment
		(start 169.980864 -111.769906)
		(end 168.985438 -111.769906)
		(width 0.127)
		(layer "In2.Cu")
		(net "SGPIO_BMC_LD_N")
	)
	(segment
		(start 170.199558 -111.9886)
		(end 169.980864 -111.769906)
		(width 0.127)
		(layer "In2.Cu")
		(net "SGPIO_BMC_LD_N")
	)
	(segment
		(start 171.20362 -112.9792)
		(end 170.948604 -112.724184)
		(width 0.127)
		(layer "In2.Cu")
		(net "SGPIO_BMC_LD_N")
	)
	(segment
		(start 172.4152 -113.264188)
		(end 172.130212 -112.9792)
		(width 0.127)
		(layer "In2.Cu")
		(net "SGPIO_BMC_LD_N")
	)
	(segment
		(start 172.66412 -113.264188)
		(end 172.4152 -113.264188)
		(width 0.127)
		(layer "In2.Cu")
		(net "SGPIO_BMC_LD_N")
	)
	(segment
		(start 166.63289 -99.043998)
		(end 164.86505 -99.043998)
		(width 0.127)
		(layer "In2.Cu")
		(net "SGPIO_BMC_LD_N")
	)
	(segment
		(start 170.948604 -112.41278)
		(end 170.524424 -111.9886)
		(width 0.127)
		(layer "In2.Cu")
		(net "SGPIO_BMC_LD_N")
	)
	(segment
		(start 165.8874 -103.596948)
		(end 165.6334 -103.342948)
		(width 0.12954)
		(layer "F.Cu")
		(net "SGPIO_BMC_DOUT")
	)
	(segment
		(start 165.6334 -103.342948)
		(end 164.99205 -103.342948)
		(width 0.12954)
		(layer "F.Cu")
		(net "SGPIO_BMC_DOUT")
	)
	(segment
		(start 171.755562 -115.375436)
		(end 171.355512 -115.775486)
		(width 0.12954)
		(layer "F.Cu")
		(net "SGPIO_BMC_DOUT")
	)
	(via
		(at 165.8874 -103.596948)
		(size 0.508)
		(drill 0.254)
		(layers "F.Cu" "B.Cu")
		(net "SGPIO_BMC_DOUT")
	)
	(via
		(at 171.355512 -115.775486)
		(size 0.4572)
		(drill 0.254)
		(layers "F.Cu" "B.Cu")
		(net "SGPIO_BMC_DOUT")
	)
	(segment
		(start 166.48176 -104.271572)
		(end 166.97198 -104.761792)
		(width 0.127)
		(layer "In2.Cu")
		(net "SGPIO_BMC_DOUT")
	)
	(segment
		(start 170.710352 -114.2492)
		(end 170.94962 -114.488468)
		(width 0.127)
		(layer "In2.Cu")
		(net "SGPIO_BMC_DOUT")
	)
	(segment
		(start 170.94962 -115.369594)
		(end 171.355512 -115.775486)
		(width 0.127)
		(layer "In2.Cu")
		(net "SGPIO_BMC_DOUT")
	)
	(segment
		(start 165.8874 -103.596948)
		(end 166.48176 -104.191308)
		(width 0.127)
		(layer "In2.Cu")
		(net "SGPIO_BMC_DOUT")
	)
	(segment
		(start 169.590212 -114.2492)
		(end 170.710352 -114.2492)
		(width 0.127)
		(layer "In2.Cu")
		(net "SGPIO_BMC_DOUT")
	)
	(segment
		(start 166.97198 -104.761792)
		(end 166.97198 -111.630968)
		(width 0.127)
		(layer "In2.Cu")
		(net "SGPIO_BMC_DOUT")
	)
	(segment
		(start 166.48176 -104.191308)
		(end 166.48176 -104.271572)
		(width 0.127)
		(layer "In2.Cu")
		(net "SGPIO_BMC_DOUT")
	)
	(segment
		(start 170.94962 -114.488468)
		(end 170.94962 -115.369594)
		(width 0.127)
		(layer "In2.Cu")
		(net "SGPIO_BMC_DOUT")
	)
	(segment
		(start 166.97198 -111.630968)
		(end 169.590212 -114.2492)
		(width 0.127)
		(layer "In2.Cu")
		(net "SGPIO_BMC_DOUT")
	)
	(segment
		(start 174.955708 -115.375436)
		(end 174.555658 -115.775486)
		(width 0.12954)
		(layer "F.Cu")
		(net "SGPIO_BMC_DIN_R")
	)
	(via
		(at 174.555658 -115.775486)
		(size 0.4572)
		(drill 0.254)
		(layers "F.Cu" "B.Cu")
		(net "SGPIO_BMC_DIN_R")
	)
	(via
		(at 159.1056 -117.554248)
		(size 0.508)
		(drill 0.254)
		(layers "F.Cu" "B.Cu")
		(net "SGPIO_BMC_DIN_R")
	)
	(segment
		(start 157.42793 -117.243098)
		(end 157.42793 -117.566948)
		(width 0.12954)
		(layer "B.Cu")
		(net "SGPIO_BMC_DIN_R")
	)
	(segment
		(start 159.1056 -117.554248)
		(end 158.6103 -117.058948)
		(width 0.12954)
		(layer "B.Cu")
		(net "SGPIO_BMC_DIN_R")
	)
	(segment
		(start 157.61208 -117.058948)
		(end 157.42793 -117.243098)
		(width 0.12954)
		(layer "B.Cu")
		(net "SGPIO_BMC_DIN_R")
	)
	(segment
		(start 158.6103 -117.058948)
		(end 157.61208 -117.058948)
		(width 0.12954)
		(layer "B.Cu")
		(net "SGPIO_BMC_DIN_R")
	)
	(segment
		(start 173.34992 -116.33708)
		(end 173.187868 -116.175028)
		(width 0.127)
		(layer "In6.Cu")
		(net "SGPIO_BMC_DIN_R")
	)
	(segment
		(start 164.26434 -116.6114)
		(end 163.21532 -116.6114)
		(width 0.127)
		(layer "In6.Cu")
		(net "SGPIO_BMC_DIN_R")
	)
	(segment
		(start 162.849052 -116.977668)
		(end 159.68218 -116.977668)
		(width 0.127)
		(layer "In6.Cu")
		(net "SGPIO_BMC_DIN_R")
	)
	(segment
		(start 159.68218 -116.977668)
		(end 159.1056 -117.554248)
		(width 0.127)
		(layer "In6.Cu")
		(net "SGPIO_BMC_DIN_R")
	)
	(segment
		(start 173.34992 -116.94668)
		(end 173.34992 -116.33708)
		(width 0.127)
		(layer "In6.Cu")
		(net "SGPIO_BMC_DIN_R")
	)
	(segment
		(start 164.55898 -116.90604)
		(end 164.26434 -116.6114)
		(width 0.127)
		(layer "In6.Cu")
		(net "SGPIO_BMC_DIN_R")
	)
	(segment
		(start 173.5074 -117.10416)
		(end 173.34992 -116.94668)
		(width 0.127)
		(layer "In6.Cu")
		(net "SGPIO_BMC_DIN_R")
	)
	(segment
		(start 165.79596 -116.90604)
		(end 164.55898 -116.90604)
		(width 0.127)
		(layer "In6.Cu")
		(net "SGPIO_BMC_DIN_R")
	)
	(segment
		(start 174.318676 -115.775486)
		(end 174.152306 -115.941856)
		(width 0.127)
		(layer "In6.Cu")
		(net "SGPIO_BMC_DIN_R")
	)
	(segment
		(start 173.187868 -116.175028)
		(end 166.526972 -116.175028)
		(width 0.127)
		(layer "In6.Cu")
		(net "SGPIO_BMC_DIN_R")
	)
	(segment
		(start 163.21532 -116.6114)
		(end 162.849052 -116.977668)
		(width 0.127)
		(layer "In6.Cu")
		(net "SGPIO_BMC_DIN_R")
	)
	(segment
		(start 174.152306 -115.941856)
		(end 174.152306 -116.971318)
		(width 0.127)
		(layer "In6.Cu")
		(net "SGPIO_BMC_DIN_R")
	)
	(segment
		(start 166.526972 -116.175028)
		(end 165.79596 -116.90604)
		(width 0.127)
		(layer "In6.Cu")
		(net "SGPIO_BMC_DIN_R")
	)
	(segment
		(start 174.152306 -116.971318)
		(end 174.019464 -117.10416)
		(width 0.127)
		(layer "In6.Cu")
		(net "SGPIO_BMC_DIN_R")
	)
	(segment
		(start 174.019464 -117.10416)
		(end 173.5074 -117.10416)
		(width 0.127)
		(layer "In6.Cu")
		(net "SGPIO_BMC_DIN_R")
	)
	(segment
		(start 174.555658 -115.775486)
		(end 174.318676 -115.775486)
		(width 0.127)
		(layer "In6.Cu")
		(net "SGPIO_BMC_DIN_R")
	)
	(segment
		(start 164.99205 -102.199948)
		(end 165.608 -102.199948)
		(width 0.12954)
		(layer "F.Cu")
		(net "SGPIO_BMC_CLK")
	)
	(segment
		(start 172.555662 -115.375436)
		(end 172.155612 -115.775486)
		(width 0.12954)
		(layer "F.Cu")
		(net "SGPIO_BMC_CLK")
	)
	(via
		(at 165.608 -102.199948)
		(size 0.508)
		(drill 0.254)
		(layers "F.Cu" "B.Cu")
		(net "SGPIO_BMC_CLK")
	)
	(via
		(at 172.155612 -115.775486)
		(size 0.4572)
		(drill 0.254)
		(layers "F.Cu" "B.Cu")
		(net "SGPIO_BMC_CLK")
	)
	(segment
		(start 169.818812 -113.8428)
		(end 167.40378 -111.427768)
		(width 0.127)
		(layer "In2.Cu")
		(net "SGPIO_BMC_CLK")
	)
	(segment
		(start 171.1325 -113.8428)
		(end 169.818812 -113.8428)
		(width 0.127)
		(layer "In2.Cu")
		(net "SGPIO_BMC_CLK")
	)
	(segment
		(start 171.75988 -113.9698)
		(end 171.572682 -113.782602)
		(width 0.127)
		(layer "In2.Cu")
		(net "SGPIO_BMC_CLK")
	)
	(segment
		(start 171.572682 -113.782602)
		(end 171.192698 -113.782602)
		(width 0.127)
		(layer "In2.Cu")
		(net "SGPIO_BMC_CLK")
	)
	(segment
		(start 172.155612 -115.775486)
		(end 171.75988 -115.379754)
		(width 0.127)
		(layer "In2.Cu")
		(net "SGPIO_BMC_CLK")
	)
	(segment
		(start 166.91356 -104.092502)
		(end 166.91356 -103.530908)
		(width 0.127)
		(layer "In2.Cu")
		(net "SGPIO_BMC_CLK")
	)
	(segment
		(start 165.608 -102.225348)
		(end 165.608 -102.199948)
		(width 0.127)
		(layer "In2.Cu")
		(net "SGPIO_BMC_CLK")
	)
	(segment
		(start 167.40378 -111.427768)
		(end 167.40378 -104.582722)
		(width 0.127)
		(layer "In2.Cu")
		(net "SGPIO_BMC_CLK")
	)
	(segment
		(start 171.75988 -115.379754)
		(end 171.75988 -113.9698)
		(width 0.127)
		(layer "In2.Cu")
		(net "SGPIO_BMC_CLK")
	)
	(segment
		(start 167.40378 -104.582722)
		(end 166.91356 -104.092502)
		(width 0.127)
		(layer "In2.Cu")
		(net "SGPIO_BMC_CLK")
	)
	(segment
		(start 171.192698 -113.782602)
		(end 171.1325 -113.8428)
		(width 0.127)
		(layer "In2.Cu")
		(net "SGPIO_BMC_CLK")
	)
	(segment
		(start 166.91356 -103.530908)
		(end 165.608 -102.225348)
		(width 0.127)
		(layer "In2.Cu")
		(net "SGPIO_BMC_CLK")
	)
	(segment
		(start 164.5158 -101.387148)
		(end 164.19195 -101.710998)
		(width 0.12954)
		(layer "F.Cu")
		(net "SGPIO_CLK_1")
	)
	(segment
		(start 154.58948 -20.970748)
		(end 154.58948 -23.917148)
		(width 0.12954)
		(layer "F.Cu")
		(net "SGPIO_CLK_1")
	)
	(segment
		(start 164.19195 -101.710998)
		(end 164.19195 -102.199948)
		(width 0.12954)
		(layer "F.Cu")
		(net "SGPIO_CLK_1")
	)
	(segment
		(start 155.057094 -20.503134)
		(end 154.58948 -20.970748)
		(width 0.12954)
		(layer "F.Cu")
		(net "SGPIO_CLK_1")
	)
	(segment
		(start 155.057094 -16.550132)
		(end 155.057094 -20.503134)
		(width 0.12954)
		(layer "F.Cu")
		(net "SGPIO_CLK_1")
	)
	(via
		(at 154.58948 -23.917148)
		(size 0.508)
		(drill 0.254)
		(layers "F.Cu" "B.Cu")
		(net "SGPIO_CLK_1")
	)
	(via
		(at 164.5158 -101.387148)
		(size 0.508)
		(drill 0.254)
		(layers "F.Cu" "B.Cu")
		(net "SGPIO_CLK_1")
	)
	(segment
		(start 158.52648 -21.859748)
		(end 155.96108 -21.859748)
		(width 0.127)
		(layer "In2.Cu")
		(net "SGPIO_CLK_1")
	)
	(segment
		(start 155.96108 -21.859748)
		(end 154.58948 -23.231348)
		(width 0.127)
		(layer "In2.Cu")
		(net "SGPIO_CLK_1")
	)
	(segment
		(start 161.5948 -91.12631)
		(end 156.85008 -86.38159)
		(width 0.127)
		(layer "In2.Cu")
		(net "SGPIO_CLK_1")
	)
	(segment
		(start 155.575 -68.936108)
		(end 154.80284 -68.163948)
		(width 0.127)
		(layer "In2.Cu")
		(net "SGPIO_CLK_1")
	)
	(segment
		(start 155.575 -79.045308)
		(end 155.575 -68.936108)
		(width 0.127)
		(layer "In2.Cu")
		(net "SGPIO_CLK_1")
	)
	(segment
		(start 159.45104 -27.803348)
		(end 159.45104 -26.243788)
		(width 0.127)
		(layer "In2.Cu")
		(net "SGPIO_CLK_1")
	)
	(segment
		(start 164.5158 -101.387148)
		(end 164.3126 -101.183948)
		(width 0.127)
		(layer "In2.Cu")
		(net "SGPIO_CLK_1")
	)
	(segment
		(start 159.45104 -26.243788)
		(end 159.87268 -25.822148)
		(width 0.127)
		(layer "In2.Cu")
		(net "SGPIO_CLK_1")
	)
	(segment
		(start 162.61334 -40.930068)
		(end 162.61334 -30.965648)
		(width 0.127)
		(layer "In2.Cu")
		(net "SGPIO_CLK_1")
	)
	(segment
		(start 161.86912 -42.949368)
		(end 161.86912 -41.674288)
		(width 0.127)
		(layer "In2.Cu")
		(net "SGPIO_CLK_1")
	)
	(segment
		(start 160.17494 -50.292508)
		(end 161.92754 -48.539908)
		(width 0.127)
		(layer "In2.Cu")
		(net "SGPIO_CLK_1")
	)
	(segment
		(start 154.80284 -68.163948)
		(end 154.80284 -67.409568)
		(width 0.127)
		(layer "In2.Cu")
		(net "SGPIO_CLK_1")
	)
	(segment
		(start 156.85008 -86.38159)
		(end 156.85008 -80.320388)
		(width 0.127)
		(layer "In2.Cu")
		(net "SGPIO_CLK_1")
	)
	(segment
		(start 159.87268 -23.205948)
		(end 158.52648 -21.859748)
		(width 0.127)
		(layer "In2.Cu")
		(net "SGPIO_CLK_1")
	)
	(segment
		(start 154.58948 -23.231348)
		(end 154.58948 -23.917148)
		(width 0.127)
		(layer "In2.Cu")
		(net "SGPIO_CLK_1")
	)
	(segment
		(start 154.80284 -67.409568)
		(end 156.78912 -65.423288)
		(width 0.127)
		(layer "In2.Cu")
		(net "SGPIO_CLK_1")
	)
	(segment
		(start 156.78912 -57.656476)
		(end 158.33852 -56.107076)
		(width 0.127)
		(layer "In2.Cu")
		(net "SGPIO_CLK_1")
	)
	(segment
		(start 158.33852 -56.107076)
		(end 158.33852 -54.709568)
		(width 0.127)
		(layer "In2.Cu")
		(net "SGPIO_CLK_1")
	)
	(segment
		(start 161.92754 -48.539908)
		(end 161.92754 -46.223428)
		(width 0.127)
		(layer "In2.Cu")
		(net "SGPIO_CLK_1")
	)
	(segment
		(start 164.3126 -101.183948)
		(end 164.161724 -101.183948)
		(width 0.127)
		(layer "In2.Cu")
		(net "SGPIO_CLK_1")
	)
	(segment
		(start 159.87268 -25.822148)
		(end 159.87268 -23.205948)
		(width 0.127)
		(layer "In2.Cu")
		(net "SGPIO_CLK_1")
	)
	(segment
		(start 162.61334 -30.965648)
		(end 159.45104 -27.803348)
		(width 0.127)
		(layer "In2.Cu")
		(net "SGPIO_CLK_1")
	)
	(segment
		(start 161.86912 -41.674288)
		(end 162.61334 -40.930068)
		(width 0.127)
		(layer "In2.Cu")
		(net "SGPIO_CLK_1")
	)
	(segment
		(start 162.9156 -99.937824)
		(end 162.9156 -97.602548)
		(width 0.127)
		(layer "In2.Cu")
		(net "SGPIO_CLK_1")
	)
	(segment
		(start 161.5948 -96.281748)
		(end 161.5948 -91.12631)
		(width 0.127)
		(layer "In2.Cu")
		(net "SGPIO_CLK_1")
	)
	(segment
		(start 162.9156 -97.602548)
		(end 161.5948 -96.281748)
		(width 0.127)
		(layer "In2.Cu")
		(net "SGPIO_CLK_1")
	)
	(segment
		(start 156.85008 -80.320388)
		(end 155.575 -79.045308)
		(width 0.127)
		(layer "In2.Cu")
		(net "SGPIO_CLK_1")
	)
	(segment
		(start 164.161724 -101.183948)
		(end 162.9156 -99.937824)
		(width 0.127)
		(layer "In2.Cu")
		(net "SGPIO_CLK_1")
	)
	(segment
		(start 161.92754 -46.223428)
		(end 162.21202 -45.938948)
		(width 0.127)
		(layer "In2.Cu")
		(net "SGPIO_CLK_1")
	)
	(segment
		(start 160.17494 -52.873148)
		(end 160.17494 -50.292508)
		(width 0.127)
		(layer "In2.Cu")
		(net "SGPIO_CLK_1")
	)
	(segment
		(start 156.78912 -65.423288)
		(end 156.78912 -57.656476)
		(width 0.127)
		(layer "In2.Cu")
		(net "SGPIO_CLK_1")
	)
	(segment
		(start 158.33852 -54.709568)
		(end 160.17494 -52.873148)
		(width 0.127)
		(layer "In2.Cu")
		(net "SGPIO_CLK_1")
	)
	(segment
		(start 162.21202 -43.292268)
		(end 161.86912 -42.949368)
		(width 0.127)
		(layer "In2.Cu")
		(net "SGPIO_CLK_1")
	)
	(segment
		(start 162.21202 -45.938948)
		(end 162.21202 -43.292268)
		(width 0.127)
		(layer "In2.Cu")
		(net "SGPIO_CLK_1")
	)
	(segment
		(start 158.31566 -19.934428)
		(end 158.31566 -22.097238)
		(width 0.12954)
		(layer "F.Cu")
		(net "SGPIO_CLK_0")
	)
	(segment
		(start 158.057088 -16.550132)
		(end 158.057088 -18.819622)
		(width 0.12954)
		(layer "F.Cu")
		(net "SGPIO_CLK_0")
	)
	(segment
		(start 158.31566 -19.078194)
		(end 158.31566 -19.934428)
		(width 0.12954)
		(layer "F.Cu")
		(net "SGPIO_CLK_0")
	)
	(segment
		(start 158.057088 -18.819622)
		(end 158.31566 -19.078194)
		(width 0.12954)
		(layer "F.Cu")
		(net "SGPIO_CLK_0")
	)
	(segment
		(start 158.31566 -22.097238)
		(end 157.988 -22.424898)
		(width 0.12954)
		(layer "F.Cu")
		(net "SGPIO_CLK_0")
	)
	(via
		(at 158.31566 -19.934428)
		(size 0.762)
		(drill 0.381)
		(layers "F.Cu" "B.Cu")
		(net "SGPIO_CLK_0")
	)
	(segment
		(start 161.56305 -99.786948)
		(end 161.56305 -99.024948)
		(width 0.12954)
		(layer "F.Cu")
		(net "SGPIO_DEBUG_PLD_LD_N")
	)
	(segment
		(start 172.555662 -116.175536)
		(end 172.155612 -116.575586)
		(width 0.12954)
		(layer "F.Cu")
		(net "SGPIO_DEBUG_PLD_LD_N")
	)
	(via
		(at 172.155612 -116.575586)
		(size 0.4572)
		(drill 0.254)
		(layers "F.Cu" "B.Cu")
		(net "SGPIO_DEBUG_PLD_LD_N")
	)
	(via
		(at 161.56305 -99.024948)
		(size 0.508)
		(drill 0.254)
		(layers "F.Cu" "B.Cu")
		(net "SGPIO_DEBUG_PLD_LD_N")
	)
	(segment
		(start 164.299646 -102.733348)
		(end 165.4302 -103.863902)
		(width 0.127)
		(layer "In2.Cu")
		(net "SGPIO_DEBUG_PLD_LD_N")
	)
	(segment
		(start 165.4302 -104.821482)
		(end 166.54018 -105.931462)
		(width 0.127)
		(layer "In2.Cu")
		(net "SGPIO_DEBUG_PLD_LD_N")
	)
	(segment
		(start 170.15968 -114.681)
		(end 170.15968 -115.943888)
		(width 0.127)
		(layer "In2.Cu")
		(net "SGPIO_DEBUG_PLD_LD_N")
	)
	(segment
		(start 166.54018 -111.834168)
		(end 169.260012 -114.554)
		(width 0.127)
		(layer "In2.Cu")
		(net "SGPIO_DEBUG_PLD_LD_N")
	)
	(segment
		(start 165.4302 -103.863902)
		(end 165.4302 -104.821482)
		(width 0.127)
		(layer "In2.Cu")
		(net "SGPIO_DEBUG_PLD_LD_N")
	)
	(segment
		(start 161.56305 -100.491798)
		(end 162.814 -101.742748)
		(width 0.127)
		(layer "In2.Cu")
		(net "SGPIO_DEBUG_PLD_LD_N")
	)
	(segment
		(start 166.54018 -105.931462)
		(end 166.54018 -111.834168)
		(width 0.127)
		(layer "In2.Cu")
		(net "SGPIO_DEBUG_PLD_LD_N")
	)
	(segment
		(start 170.03268 -114.554)
		(end 170.15968 -114.681)
		(width 0.127)
		(layer "In2.Cu")
		(net "SGPIO_DEBUG_PLD_LD_N")
	)
	(segment
		(start 161.56305 -99.024948)
		(end 161.56305 -100.491798)
		(width 0.127)
		(layer "In2.Cu")
		(net "SGPIO_DEBUG_PLD_LD_N")
	)
	(segment
		(start 163.220654 -102.733348)
		(end 164.299646 -102.733348)
		(width 0.127)
		(layer "In2.Cu")
		(net "SGPIO_DEBUG_PLD_LD_N")
	)
	(segment
		(start 171.755054 -116.175028)
		(end 172.155612 -116.575586)
		(width 0.127)
		(layer "In2.Cu")
		(net "SGPIO_DEBUG_PLD_LD_N")
	)
	(segment
		(start 170.39082 -116.175028)
		(end 171.755054 -116.175028)
		(width 0.127)
		(layer "In2.Cu")
		(net "SGPIO_DEBUG_PLD_LD_N")
	)
	(segment
		(start 169.260012 -114.554)
		(end 170.03268 -114.554)
		(width 0.127)
		(layer "In2.Cu")
		(net "SGPIO_DEBUG_PLD_LD_N")
	)
	(segment
		(start 162.814 -101.742748)
		(end 162.814 -102.326694)
		(width 0.127)
		(layer "In2.Cu")
		(net "SGPIO_DEBUG_PLD_LD_N")
	)
	(segment
		(start 170.15968 -115.943888)
		(end 170.39082 -116.175028)
		(width 0.127)
		(layer "In2.Cu")
		(net "SGPIO_DEBUG_PLD_LD_N")
	)
	(segment
		(start 162.814 -102.326694)
		(end 163.220654 -102.733348)
		(width 0.127)
		(layer "In2.Cu")
		(net "SGPIO_DEBUG_PLD_LD_N")
	)
	(segment
		(start 170.155616 -116.175536)
		(end 169.755566 -116.575586)
		(width 0.12954)
		(layer "F.Cu")
		(net "SGPIO_DEBUG_PLD_DOUT")
	)
	(segment
		(start 162.2298 -101.844348)
		(end 162.2298 -102.911148)
		(width 0.12954)
		(layer "F.Cu")
		(net "SGPIO_DEBUG_PLD_DOUT")
	)
	(segment
		(start 161.798 -103.342948)
		(end 161.18205 -103.342948)
		(width 0.12954)
		(layer "F.Cu")
		(net "SGPIO_DEBUG_PLD_DOUT")
	)
	(segment
		(start 162.2298 -102.911148)
		(end 161.798 -103.342948)
		(width 0.12954)
		(layer "F.Cu")
		(net "SGPIO_DEBUG_PLD_DOUT")
	)
	(via
		(at 162.2298 -101.844348)
		(size 0.508)
		(drill 0.254)
		(layers "F.Cu" "B.Cu")
		(net "SGPIO_DEBUG_PLD_DOUT")
	)
	(via
		(at 169.755566 -116.575586)
		(size 0.4572)
		(drill 0.254)
		(layers "F.Cu" "B.Cu")
		(net "SGPIO_DEBUG_PLD_DOUT")
	)
	(segment
		(start 169.28846 -115.235228)
		(end 166.10838 -112.055148)
		(width 0.127)
		(layer "In2.Cu")
		(net "SGPIO_DEBUG_PLD_DOUT")
	)
	(segment
		(start 169.28846 -116.10848)
		(end 169.28846 -115.235228)
		(width 0.127)
		(layer "In2.Cu")
		(net "SGPIO_DEBUG_PLD_DOUT")
	)
	(segment
		(start 164.9984 -104.067356)
		(end 164.113972 -103.182928)
		(width 0.127)
		(layer "In2.Cu")
		(net "SGPIO_DEBUG_PLD_DOUT")
	)
	(segment
		(start 162.179 -101.895148)
		(end 162.2298 -101.844348)
		(width 0.127)
		(layer "In2.Cu")
		(net "SGPIO_DEBUG_PLD_DOUT")
	)
	(segment
		(start 166.10838 -106.110532)
		(end 164.9984 -105.000552)
		(width 0.127)
		(layer "In2.Cu")
		(net "SGPIO_DEBUG_PLD_DOUT")
	)
	(segment
		(start 162.90544 -103.182928)
		(end 162.179 -102.456488)
		(width 0.127)
		(layer "In2.Cu")
		(net "SGPIO_DEBUG_PLD_DOUT")
	)
	(segment
		(start 162.179 -102.456488)
		(end 162.179 -101.895148)
		(width 0.127)
		(layer "In2.Cu")
		(net "SGPIO_DEBUG_PLD_DOUT")
	)
	(segment
		(start 164.9984 -105.000552)
		(end 164.9984 -104.067356)
		(width 0.127)
		(layer "In2.Cu")
		(net "SGPIO_DEBUG_PLD_DOUT")
	)
	(segment
		(start 169.755566 -116.575586)
		(end 169.28846 -116.10848)
		(width 0.127)
		(layer "In2.Cu")
		(net "SGPIO_DEBUG_PLD_DOUT")
	)
	(segment
		(start 164.113972 -103.182928)
		(end 162.90544 -103.182928)
		(width 0.127)
		(layer "In2.Cu")
		(net "SGPIO_DEBUG_PLD_DOUT")
	)
	(segment
		(start 166.10838 -112.055148)
		(end 166.10838 -106.110532)
		(width 0.127)
		(layer "In2.Cu")
		(net "SGPIO_DEBUG_PLD_DOUT")
	)
	(segment
		(start 166.5732 -117.203728)
		(end 166.02202 -117.203728)
		(width 0.12954)
		(layer "F.Cu")
		(net "SGPIO_DEBUG_PLD_DIN")
	)
	(segment
		(start 166.02202 -117.203728)
		(end 165.6588 -117.566948)
		(width 0.12954)
		(layer "F.Cu")
		(net "SGPIO_DEBUG_PLD_DIN")
	)
	(segment
		(start 165.6588 -117.566948)
		(end 165.04793 -117.566948)
		(width 0.12954)
		(layer "F.Cu")
		(net "SGPIO_DEBUG_PLD_DIN")
	)
	(segment
		(start 171.755562 -116.175536)
		(end 171.355512 -116.575586)
		(width 0.12954)
		(layer "F.Cu")
		(net "SGPIO_DEBUG_PLD_DIN")
	)
	(via
		(at 166.5732 -117.203728)
		(size 0.508)
		(drill 0.254)
		(layers "F.Cu" "B.Cu")
		(net "SGPIO_DEBUG_PLD_DIN")
	)
	(via
		(at 171.355512 -116.575586)
		(size 0.4572)
		(drill 0.254)
		(layers "F.Cu" "B.Cu")
		(net "SGPIO_DEBUG_PLD_DIN")
	)
	(segment
		(start 166.5732 -117.185948)
		(end 166.7891 -116.970048)
		(width 0.127)
		(layer "In6.Cu")
		(net "SGPIO_DEBUG_PLD_DIN")
	)
	(segment
		(start 170.96105 -116.970048)
		(end 171.355512 -116.575586)
		(width 0.127)
		(layer "In6.Cu")
		(net "SGPIO_DEBUG_PLD_DIN")
	)
	(segment
		(start 166.7891 -116.970048)
		(end 170.96105 -116.970048)
		(width 0.127)
		(layer "In6.Cu")
		(net "SGPIO_DEBUG_PLD_DIN")
	)
	(segment
		(start 166.5732 -117.203728)
		(end 166.5732 -117.185948)
		(width 0.127)
		(layer "In6.Cu")
		(net "SGPIO_DEBUG_PLD_DIN")
	)
	(segment
		(start 158.3182 -23.555198)
		(end 157.988 -23.224998)
		(width 0.12954)
		(layer "F.Cu")
		(net "SGPIO_DEBUG_PLD_CLK")
	)
	(segment
		(start 170.955716 -116.175536)
		(end 170.555666 -116.575586)
		(width 0.12954)
		(layer "F.Cu")
		(net "SGPIO_DEBUG_PLD_CLK")
	)
	(segment
		(start 158.3182 -24.323548)
		(end 158.3182 -23.555198)
		(width 0.12954)
		(layer "F.Cu")
		(net "SGPIO_DEBUG_PLD_CLK")
	)
	(via
		(at 158.3182 -24.323548)
		(size 0.508)
		(drill 0.254)
		(layers "F.Cu" "B.Cu")
		(net "SGPIO_DEBUG_PLD_CLK")
	)
	(via
		(at 170.555666 -116.575586)
		(size 0.4572)
		(drill 0.254)
		(layers "F.Cu" "B.Cu")
		(net "SGPIO_DEBUG_PLD_CLK")
	)
	(segment
		(start 154.89936 -61.947806)
		(end 154.71648 -61.947806)
		(width 0.127)
		(layer "In2.Cu")
		(net "SGPIO_DEBUG_PLD_CLK")
	)
	(segment
		(start 154.71648 -60.644786)
		(end 154.89936 -60.644786)
		(width 0.127)
		(layer "In2.Cu")
		(net "SGPIO_DEBUG_PLD_CLK")
	)
	(segment
		(start 168.92524 -116.307108)
		(end 168.92524 -115.514628)
		(width 0.127)
		(layer "In2.Cu")
		(net "SGPIO_DEBUG_PLD_CLK")
	)
	(segment
		(start 154.89936 -62.816486)
		(end 154.71648 -62.816486)
		(width 0.127)
		(layer "In2.Cu")
		(net "SGPIO_DEBUG_PLD_CLK")
	)
	(segment
		(start 155.02636 -62.943486)
		(end 154.89936 -62.816486)
		(width 0.127)
		(layer "In2.Cu")
		(net "SGPIO_DEBUG_PLD_CLK")
	)
	(segment
		(start 160.008824 -103.254048)
		(end 159.1691 -102.414324)
		(width 0.127)
		(layer "In2.Cu")
		(net "SGPIO_DEBUG_PLD_CLK")
	)
	(segment
		(start 154.58948 -59.034426)
		(end 154.71648 -58.907426)
		(width 0.127)
		(layer "In2.Cu")
		(net "SGPIO_DEBUG_PLD_CLK")
	)
	(segment
		(start 159.1691 -102.414324)
		(end 159.1691 -96.686878)
		(width 0.127)
		(layer "In2.Cu")
		(net "SGPIO_DEBUG_PLD_CLK")
	)
	(segment
		(start 154.89936 -59.776106)
		(end 155.02636 -59.649106)
		(width 0.127)
		(layer "In2.Cu")
		(net "SGPIO_DEBUG_PLD_CLK")
	)
	(segment
		(start 162.726116 -103.614728)
		(end 162.365436 -103.254048)
		(width 0.127)
		(layer "In2.Cu")
		(net "SGPIO_DEBUG_PLD_CLK")
	)
	(segment
		(start 154.58948 -58.165746)
		(end 154.71648 -58.038746)
		(width 0.127)
		(layer "In2.Cu")
		(net "SGPIO_DEBUG_PLD_CLK")
	)
	(segment
		(start 154.71648 -58.473086)
		(end 154.58948 -58.346086)
		(width 0.127)
		(layer "In2.Cu")
		(net "SGPIO_DEBUG_PLD_CLK")
	)
	(segment
		(start 154.9527 -51.49088)
		(end 153.32964 -49.86782)
		(width 0.127)
		(layer "In2.Cu")
		(net "SGPIO_DEBUG_PLD_CLK")
	)
	(segment
		(start 154.58948 -60.083446)
		(end 154.58948 -59.903106)
		(width 0.127)
		(layer "In2.Cu")
		(net "SGPIO_DEBUG_PLD_CLK")
	)
	(segment
		(start 154.71648 -62.382146)
		(end 154.89936 -62.382146)
		(width 0.127)
		(layer "In2.Cu")
		(net "SGPIO_DEBUG_PLD_CLK")
	)
	(segment
		(start 154.71648 -57.604406)
		(end 154.58948 -57.477406)
		(width 0.127)
		(layer "In2.Cu")
		(net "SGPIO_DEBUG_PLD_CLK")
	)
	(segment
		(start 155.02636 -62.074806)
		(end 154.89936 -61.947806)
		(width 0.127)
		(layer "In2.Cu")
		(net "SGPIO_DEBUG_PLD_CLK")
	)
	(segment
		(start 155.02636 -58.780426)
		(end 155.02636 -58.600086)
		(width 0.127)
		(layer "In2.Cu")
		(net "SGPIO_DEBUG_PLD_CLK")
	)
	(segment
		(start 170.161204 -116.970048)
		(end 169.58818 -116.970048)
		(width 0.127)
		(layer "In2.Cu")
		(net "SGPIO_DEBUG_PLD_CLK")
	)
	(segment
		(start 154.71648 -58.038746)
		(end 154.89936 -58.038746)
		(width 0.127)
		(layer "In2.Cu")
		(net "SGPIO_DEBUG_PLD_CLK")
	)
	(segment
		(start 165.67658 -106.289602)
		(end 164.5666 -105.179622)
		(width 0.127)
		(layer "In2.Cu")
		(net "SGPIO_DEBUG_PLD_CLK")
	)
	(segment
		(start 155.02636 -57.731406)
		(end 154.89936 -57.604406)
		(width 0.127)
		(layer "In2.Cu")
		(net "SGPIO_DEBUG_PLD_CLK")
	)
	(segment
		(start 155.02636 -57.911746)
		(end 155.02636 -57.731406)
		(width 0.127)
		(layer "In2.Cu")
		(net "SGPIO_DEBUG_PLD_CLK")
	)
	(segment
		(start 164.5666 -105.179622)
		(end 164.5666 -104.246426)
		(width 0.127)
		(layer "In2.Cu")
		(net "SGPIO_DEBUG_PLD_CLK")
	)
	(segment
		(start 154.58948 -62.689486)
		(end 154.58948 -62.509146)
		(width 0.127)
		(layer "In2.Cu")
		(net "SGPIO_DEBUG_PLD_CLK")
	)
	(segment
		(start 155.9433 -51.49088)
		(end 154.9527 -51.49088)
		(width 0.127)
		(layer "In2.Cu")
		(net "SGPIO_DEBUG_PLD_CLK")
	)
	(segment
		(start 154.71648 -60.210446)
		(end 154.58948 -60.083446)
		(width 0.127)
		(layer "In2.Cu")
		(net "SGPIO_DEBUG_PLD_CLK")
	)
	(segment
		(start 153.32964 -49.86782)
		(end 153.32964 -43.462448)
		(width 0.127)
		(layer "In2.Cu")
		(net "SGPIO_DEBUG_PLD_CLK")
	)
	(segment
		(start 155.35402 -41.438068)
		(end 155.35402 -41.194228)
		(width 0.127)
		(layer "In2.Cu")
		(net "SGPIO_DEBUG_PLD_CLK")
	)
	(segment
		(start 154.71648 -59.341766)
		(end 154.58948 -59.214766)
		(width 0.127)
		(layer "In2.Cu")
		(net "SGPIO_DEBUG_PLD_CLK")
	)
	(segment
		(start 154.58948 -61.640466)
		(end 154.71648 -61.513466)
		(width 0.127)
		(layer "In2.Cu")
		(net "SGPIO_DEBUG_PLD_CLK")
	)
	(segment
		(start 154.89936 -62.382146)
		(end 155.02636 -62.255146)
		(width 0.127)
		(layer "In2.Cu")
		(net "SGPIO_DEBUG_PLD_CLK")
	)
	(segment
		(start 154.71648 -57.170066)
		(end 154.89936 -57.170066)
		(width 0.127)
		(layer "In2.Cu")
		(net "SGPIO_DEBUG_PLD_CLK")
	)
	(segment
		(start 159.778446 -91.828874)
		(end 152.77338 -84.823808)
		(width 0.127)
		(layer "In2.Cu")
		(net "SGPIO_DEBUG_PLD_CLK")
	)
	(segment
		(start 155.02636 -58.600086)
		(end 154.89936 -58.473086)
		(width 0.127)
		(layer "In2.Cu")
		(net "SGPIO_DEBUG_PLD_CLK")
	)
	(segment
		(start 154.89936 -58.473086)
		(end 154.71648 -58.473086)
		(width 0.127)
		(layer "In2.Cu")
		(net "SGPIO_DEBUG_PLD_CLK")
	)
	(segment
		(start 154.71648 -62.816486)
		(end 154.58948 -62.689486)
		(width 0.127)
		(layer "In2.Cu")
		(net "SGPIO_DEBUG_PLD_CLK")
	)
	(segment
		(start 154.89936 -60.644786)
		(end 155.02636 -60.517786)
		(width 0.127)
		(layer "In2.Cu")
		(net "SGPIO_DEBUG_PLD_CLK")
	)
	(segment
		(start 155.02636 -56.925718)
		(end 156.57576 -55.376318)
		(width 0.127)
		(layer "In2.Cu")
		(net "SGPIO_DEBUG_PLD_CLK")
	)
	(segment
		(start 154.71648 -61.513466)
		(end 154.89936 -61.513466)
		(width 0.127)
		(layer "In2.Cu")
		(net "SGPIO_DEBUG_PLD_CLK")
	)
	(segment
		(start 155.02636 -60.517786)
		(end 155.02636 -60.337446)
		(width 0.127)
		(layer "In2.Cu")
		(net "SGPIO_DEBUG_PLD_CLK")
	)
	(segment
		(start 155.02636 -59.649106)
		(end 155.02636 -59.468766)
		(width 0.127)
		(layer "In2.Cu")
		(net "SGPIO_DEBUG_PLD_CLK")
	)
	(segment
		(start 152.77338 -84.823808)
		(end 152.77338 -66.918078)
		(width 0.127)
		(layer "In2.Cu")
		(net "SGPIO_DEBUG_PLD_CLK")
	)
	(segment
		(start 165.67658 -112.265968)
		(end 165.67658 -106.289602)
		(width 0.127)
		(layer "In2.Cu")
		(net "SGPIO_DEBUG_PLD_CLK")
	)
	(segment
		(start 154.71648 -61.947806)
		(end 154.58948 -61.820806)
		(width 0.127)
		(layer "In2.Cu")
		(net "SGPIO_DEBUG_PLD_CLK")
	)
	(segment
		(start 155.02636 -62.255146)
		(end 155.02636 -62.074806)
		(width 0.127)
		(layer "In2.Cu")
		(net "SGPIO_DEBUG_PLD_CLK")
	)
	(segment
		(start 158.01086 -24.323548)
		(end 158.3182 -24.323548)
		(width 0.127)
		(layer "In2.Cu")
		(net "SGPIO_DEBUG_PLD_CLK")
	)
	(segment
		(start 154.89936 -57.604406)
		(end 154.71648 -57.604406)
		(width 0.127)
		(layer "In2.Cu")
		(net "SGPIO_DEBUG_PLD_CLK")
	)
	(segment
		(start 153.32964 -43.462448)
		(end 155.35402 -41.438068)
		(width 0.127)
		(layer "In2.Cu")
		(net "SGPIO_DEBUG_PLD_CLK")
	)
	(segment
		(start 155.02636 -57.043066)
		(end 155.02636 -56.925718)
		(width 0.127)
		(layer "In2.Cu")
		(net "SGPIO_DEBUG_PLD_CLK")
	)
	(segment
		(start 155.02636 -59.468766)
		(end 154.89936 -59.341766)
		(width 0.127)
		(layer "In2.Cu")
		(net "SGPIO_DEBUG_PLD_CLK")
	)
	(segment
		(start 155.02636 -61.206126)
		(end 154.89936 -61.079126)
		(width 0.127)
		(layer "In2.Cu")
		(net "SGPIO_DEBUG_PLD_CLK")
	)
	(segment
		(start 163.934902 -103.614728)
		(end 162.726116 -103.614728)
		(width 0.127)
		(layer "In2.Cu")
		(net "SGPIO_DEBUG_PLD_CLK")
	)
	(segment
		(start 154.58948 -59.214766)
		(end 154.58948 -59.034426)
		(width 0.127)
		(layer "In2.Cu")
		(net "SGPIO_DEBUG_PLD_CLK")
	)
	(segment
		(start 154.89936 -58.038746)
		(end 155.02636 -57.911746)
		(width 0.127)
		(layer "In2.Cu")
		(net "SGPIO_DEBUG_PLD_CLK")
	)
	(segment
		(start 154.58948 -58.346086)
		(end 154.58948 -58.165746)
		(width 0.127)
		(layer "In2.Cu")
		(net "SGPIO_DEBUG_PLD_CLK")
	)
	(segment
		(start 154.58948 -61.820806)
		(end 154.58948 -61.640466)
		(width 0.127)
		(layer "In2.Cu")
		(net "SGPIO_DEBUG_PLD_CLK")
	)
	(segment
		(start 154.71648 -59.776106)
		(end 154.89936 -59.776106)
		(width 0.127)
		(layer "In2.Cu")
		(net "SGPIO_DEBUG_PLD_CLK")
	)
	(segment
		(start 169.58818 -116.970048)
		(end 168.92524 -116.307108)
		(width 0.127)
		(layer "In2.Cu")
		(net "SGPIO_DEBUG_PLD_CLK")
	)
	(segment
		(start 154.71648 -58.907426)
		(end 154.89936 -58.907426)
		(width 0.127)
		(layer "In2.Cu")
		(net "SGPIO_DEBUG_PLD_CLK")
	)
	(segment
		(start 154.71648 -61.079126)
		(end 154.58948 -60.952126)
		(width 0.127)
		(layer "In2.Cu")
		(net "SGPIO_DEBUG_PLD_CLK")
	)
	(segment
		(start 156.61132 -39.936928)
		(end 156.61132 -25.723088)
		(width 0.127)
		(layer "In2.Cu")
		(net "SGPIO_DEBUG_PLD_CLK")
	)
	(segment
		(start 154.58948 -57.297066)
		(end 154.71648 -57.170066)
		(width 0.127)
		(layer "In2.Cu")
		(net "SGPIO_DEBUG_PLD_CLK")
	)
	(segment
		(start 154.89936 -61.513466)
		(end 155.02636 -61.386466)
		(width 0.127)
		(layer "In2.Cu")
		(net "SGPIO_DEBUG_PLD_CLK")
	)
	(segment
		(start 154.89936 -57.170066)
		(end 155.02636 -57.043066)
		(width 0.127)
		(layer "In2.Cu")
		(net "SGPIO_DEBUG_PLD_CLK")
	)
	(segment
		(start 152.77338 -66.918078)
		(end 155.02636 -64.665098)
		(width 0.127)
		(layer "In2.Cu")
		(net "SGPIO_DEBUG_PLD_CLK")
	)
	(segment
		(start 156.57576 -52.12334)
		(end 155.9433 -51.49088)
		(width 0.127)
		(layer "In2.Cu")
		(net "SGPIO_DEBUG_PLD_CLK")
	)
	(segment
		(start 154.89936 -60.210446)
		(end 154.71648 -60.210446)
		(width 0.127)
		(layer "In2.Cu")
		(net "SGPIO_DEBUG_PLD_CLK")
	)
	(segment
		(start 155.02636 -64.665098)
		(end 155.02636 -62.943486)
		(width 0.127)
		(layer "In2.Cu")
		(net "SGPIO_DEBUG_PLD_CLK")
	)
	(segment
		(start 155.02636 -60.337446)
		(end 154.89936 -60.210446)
		(width 0.127)
		(layer "In2.Cu")
		(net "SGPIO_DEBUG_PLD_CLK")
	)
	(segment
		(start 154.58948 -57.477406)
		(end 154.58948 -57.297066)
		(width 0.127)
		(layer "In2.Cu")
		(net "SGPIO_DEBUG_PLD_CLK")
	)
	(segment
		(start 154.58948 -59.903106)
		(end 154.71648 -59.776106)
		(width 0.127)
		(layer "In2.Cu")
		(net "SGPIO_DEBUG_PLD_CLK")
	)
	(segment
		(start 154.89936 -59.341766)
		(end 154.71648 -59.341766)
		(width 0.127)
		(layer "In2.Cu")
		(net "SGPIO_DEBUG_PLD_CLK")
	)
	(segment
		(start 164.5666 -104.246426)
		(end 163.934902 -103.614728)
		(width 0.127)
		(layer "In2.Cu")
		(net "SGPIO_DEBUG_PLD_CLK")
	)
	(segment
		(start 154.58948 -60.952126)
		(end 154.58948 -60.771786)
		(width 0.127)
		(layer "In2.Cu")
		(net "SGPIO_DEBUG_PLD_CLK")
	)
	(segment
		(start 154.58948 -62.509146)
		(end 154.71648 -62.382146)
		(width 0.127)
		(layer "In2.Cu")
		(net "SGPIO_DEBUG_PLD_CLK")
	)
	(segment
		(start 159.1691 -96.686878)
		(end 159.778446 -96.077532)
		(width 0.127)
		(layer "In2.Cu")
		(net "SGPIO_DEBUG_PLD_CLK")
	)
	(segment
		(start 154.89936 -58.907426)
		(end 155.02636 -58.780426)
		(width 0.127)
		(layer "In2.Cu")
		(net "SGPIO_DEBUG_PLD_CLK")
	)
	(segment
		(start 162.365436 -103.254048)
		(end 160.008824 -103.254048)
		(width 0.127)
		(layer "In2.Cu")
		(net "SGPIO_DEBUG_PLD_CLK")
	)
	(segment
		(start 155.35402 -41.194228)
		(end 156.61132 -39.936928)
		(width 0.127)
		(layer "In2.Cu")
		(net "SGPIO_DEBUG_PLD_CLK")
	)
	(segment
		(start 156.61132 -25.723088)
		(end 158.01086 -24.323548)
		(width 0.127)
		(layer "In2.Cu")
		(net "SGPIO_DEBUG_PLD_CLK")
	)
	(segment
		(start 168.92524 -115.514628)
		(end 165.67658 -112.265968)
		(width 0.127)
		(layer "In2.Cu")
		(net "SGPIO_DEBUG_PLD_CLK")
	)
	(segment
		(start 159.778446 -96.077532)
		(end 159.778446 -91.828874)
		(width 0.127)
		(layer "In2.Cu")
		(net "SGPIO_DEBUG_PLD_CLK")
	)
	(segment
		(start 154.58948 -60.771786)
		(end 154.71648 -60.644786)
		(width 0.127)
		(layer "In2.Cu")
		(net "SGPIO_DEBUG_PLD_CLK")
	)
	(segment
		(start 155.02636 -61.386466)
		(end 155.02636 -61.206126)
		(width 0.127)
		(layer "In2.Cu")
		(net "SGPIO_DEBUG_PLD_CLK")
	)
	(segment
		(start 154.89936 -61.079126)
		(end 154.71648 -61.079126)
		(width 0.127)
		(layer "In2.Cu")
		(net "SGPIO_DEBUG_PLD_CLK")
	)
	(segment
		(start 156.57576 -55.376318)
		(end 156.57576 -52.12334)
		(width 0.127)
		(layer "In2.Cu")
		(net "SGPIO_DEBUG_PLD_CLK")
	)
	(segment
		(start 170.555666 -116.575586)
		(end 170.161204 -116.970048)
		(width 0.127)
		(layer "In2.Cu")
		(net "SGPIO_DEBUG_PLD_CLK")
	)
	(segment
		(start 324.56628 -35.733228)
		(end 325.199756 -35.733228)
		(width 0.12954)
		(layer "F.Cu")
		(net "RTC_EXT_CAP")
	)
	(segment
		(start 328.395584 -37.60851)
		(end 328.395584 -38.050216)
		(width 0.0889)
		(layer "F.Cu")
		(net "RTC_EXT_CAP")
	)
	(segment
		(start 324.234302 -35.733228)
		(end 324.56628 -35.733228)
		(width 0.12954)
		(layer "F.Cu")
		(net "RTC_EXT_CAP")
	)
	(segment
		(start 327.853548 -36.982146)
		(end 327.853548 -37.066474)
		(width 0.0889)
		(layer "F.Cu")
		(net "RTC_EXT_CAP")
	)
	(segment
		(start 325.982076 -36.515548)
		(end 326.718422 -36.515548)
		(width 0.12954)
		(layer "F.Cu")
		(net "RTC_EXT_CAP")
	)
	(segment
		(start 327.516236 -36.644834)
		(end 327.853548 -36.982146)
		(width 0.0889)
		(layer "F.Cu")
		(net "RTC_EXT_CAP")
	)
	(segment
		(start 326.718422 -36.515548)
		(end 327.204324 -36.515548)
		(width 0.0889)
		(layer "F.Cu")
		(net "RTC_EXT_CAP")
	)
	(segment
		(start 327.853548 -37.066474)
		(end 328.395584 -37.60851)
		(width 0.0889)
		(layer "F.Cu")
		(net "RTC_EXT_CAP")
	)
	(segment
		(start 327.204324 -36.515548)
		(end 327.516236 -36.644834)
		(width 0.0889)
		(layer "F.Cu")
		(net "RTC_EXT_CAP")
	)
	(segment
		(start 322.632578 -34.131504)
		(end 324.234302 -35.733228)
		(width 0.12954)
		(layer "F.Cu")
		(net "RTC_EXT_CAP")
	)
	(segment
		(start 325.199756 -35.733228)
		(end 325.982076 -36.515548)
		(width 0.12954)
		(layer "F.Cu")
		(net "RTC_EXT_CAP")
	)
	(via
		(at 324.56628 -35.733228)
		(size 0.508)
		(drill 0.254)
		(layers "F.Cu" "B.Cu")
		(net "RTC_EXT_CAP")
	)
	(segment
		(start 325.227696 -27.435302)
		(end 325.593964 -27.069034)
		(width 0.12954)
		(layer "F.Cu")
		(net "RST_SRTCRST_N")
	)
	(segment
		(start 208.08188 -104.715056)
		(end 206.96809 -104.715056)
		(width 0.12954)
		(layer "F.Cu")
		(net "RST_SRTCRST_N")
	)
	(segment
		(start 329.948794 -35.902392)
		(end 329.948794 -34.252662)
		(width 0.0889)
		(layer "F.Cu")
		(net "RST_SRTCRST_N")
	)
	(segment
		(start 330.419456 -37.755068)
		(end 330.419456 -36.373054)
		(width 0.0889)
		(layer "F.Cu")
		(net "RST_SRTCRST_N")
	)
	(segment
		(start 329.030076 -33.333944)
		(end 329.030076 -33.229804)
		(width 0.0889)
		(layer "F.Cu")
		(net "RST_SRTCRST_N")
	)
	(segment
		(start 327.607422 -31.19247)
		(end 327.607422 -31.15691)
		(width 0.12954)
		(layer "F.Cu")
		(net "RST_SRTCRST_N")
	)
	(segment
		(start 327.45426 -31.003748)
		(end 325.991474 -28.693872)
		(width 0.12954)
		(layer "F.Cu")
		(net "RST_SRTCRST_N")
	)
	(segment
		(start 330.396596 -37.777928)
		(end 330.419456 -37.755068)
		(width 0.0889)
		(layer "F.Cu")
		(net "RST_SRTCRST_N")
	)
	(segment
		(start 325.593964 -25.102312)
		(end 325.593964 -26.143712)
		(width 0.12954)
		(layer "F.Cu")
		(net "RST_SRTCRST_N")
	)
	(segment
		(start 330.419456 -36.373054)
		(end 329.948794 -35.902392)
		(width 0.0889)
		(layer "F.Cu")
		(net "RST_SRTCRST_N")
	)
	(segment
		(start 325.593964 -24.273256)
		(end 325.593964 -25.102312)
		(width 0.12954)
		(layer "F.Cu")
		(net "RST_SRTCRST_N")
	)
	(segment
		(start 330.396596 -38.050216)
		(end 330.396596 -37.777928)
		(width 0.0889)
		(layer "F.Cu")
		(net "RST_SRTCRST_N")
	)
	(segment
		(start 328.331322 -32.530542)
		(end 328.331322 -31.91637)
		(width 0.12954)
		(layer "F.Cu")
		(net "RST_SRTCRST_N")
	)
	(segment
		(start 206.96809 -104.715056)
		(end 203.52639 -104.715056)
		(width 0.12954)
		(layer "F.Cu")
		(net "RST_SRTCRST_N")
	)
	(segment
		(start 329.030076 -33.229804)
		(end 328.90714 -33.106868)
		(width 0.0889)
		(layer "F.Cu")
		(net "RST_SRTCRST_N")
	)
	(segment
		(start 329.948794 -34.252662)
		(end 329.030076 -33.333944)
		(width 0.0889)
		(layer "F.Cu")
		(net "RST_SRTCRST_N")
	)
	(segment
		(start 328.90714 -33.106868)
		(end 328.331322 -32.530542)
		(width 0.12954)
		(layer "F.Cu")
		(net "RST_SRTCRST_N")
	)
	(segment
		(start 325.991474 -28.693872)
		(end 325.227696 -27.930094)
		(width 0.12954)
		(layer "F.Cu")
		(net "RST_SRTCRST_N")
	)
	(segment
		(start 325.593964 -27.069034)
		(end 325.593964 -26.143712)
		(width 0.12954)
		(layer "F.Cu")
		(net "RST_SRTCRST_N")
	)
	(segment
		(start 328.331322 -31.91637)
		(end 327.607422 -31.19247)
		(width 0.12954)
		(layer "F.Cu")
		(net "RST_SRTCRST_N")
	)
	(segment
		(start 203.52639 -104.715056)
		(end 203.326492 -104.914954)
		(width 0.12954)
		(layer "F.Cu")
		(net "RST_SRTCRST_N")
	)
	(segment
		(start 325.552816 -24.232108)
		(end 325.593964 -24.273256)
		(width 0.12954)
		(layer "F.Cu")
		(net "RST_SRTCRST_N")
	)
	(segment
		(start 325.227696 -27.930094)
		(end 325.227696 -27.435302)
		(width 0.12954)
		(layer "F.Cu")
		(net "RST_SRTCRST_N")
	)
	(segment
		(start 327.607422 -31.15691)
		(end 327.45426 -31.003748)
		(width 0.12954)
		(layer "F.Cu")
		(net "RST_SRTCRST_N")
	)
	(via
		(at 200.0504 -90.1446)
		(size 0.508)
		(drill 0.254)
		(layers "F.Cu" "B.Cu")
		(net "RST_SRTCRST_N")
	)
	(via
		(at 325.552816 -24.232108)
		(size 0.508)
		(drill 0.254)
		(layers "F.Cu" "B.Cu")
		(net "RST_SRTCRST_N")
	)
	(via
		(at 208.08188 -104.715056)
		(size 0.508)
		(drill 0.254)
		(layers "F.Cu" "B.Cu")
		(net "RST_SRTCRST_N")
	)
	(segment
		(start 208.08188 -103.215948)
		(end 208.08188 -104.715056)
		(width 0.127)
		(layer "In2.Cu")
		(net "RST_SRTCRST_N")
	)
	(segment
		(start 200.0504 -90.1446)
		(end 200.0504 -95.184468)
		(width 0.127)
		(layer "In2.Cu")
		(net "RST_SRTCRST_N")
	)
	(segment
		(start 200.0504 -95.184468)
		(end 208.08188 -103.215948)
		(width 0.127)
		(layer "In2.Cu")
		(net "RST_SRTCRST_N")
	)
	(segment
		(start 319.630298 -24.997156)
		(end 320.892678 -24.997156)
		(width 0.127)
		(layer "In15.Cu")
		(net "RST_SRTCRST_N")
	)
	(segment
		(start 262.15086 -63.998348)
		(end 274.60575 -63.998348)
		(width 0.127)
		(layer "In15.Cu")
		(net "RST_SRTCRST_N")
	)
	(segment
		(start 303.412652 -28.77439)
		(end 305.664108 -28.77439)
		(width 0.127)
		(layer "In15.Cu")
		(net "RST_SRTCRST_N")
	)
	(segment
		(start 322.154296 -23.735538)
		(end 325.128128 -23.735538)
		(width 0.127)
		(layer "In15.Cu")
		(net "RST_SRTCRST_N")
	)
	(segment
		(start 297.82262 -35.633914)
		(end 297.82262 -34.364422)
		(width 0.127)
		(layer "In15.Cu")
		(net "RST_SRTCRST_N")
	)
	(segment
		(start 200.03008 -89.182448)
		(end 200.03008 -82.821018)
		(width 0.127)
		(layer "In15.Cu")
		(net "RST_SRTCRST_N")
	)
	(segment
		(start 308.15915 -26.279348)
		(end 318.348106 -26.279348)
		(width 0.127)
		(layer "In15.Cu")
		(net "RST_SRTCRST_N")
	)
	(segment
		(start 201.14895 -81.702148)
		(end 222.45955 -81.702148)
		(width 0.127)
		(layer "In15.Cu")
		(net "RST_SRTCRST_N")
	)
	(segment
		(start 325.128128 -23.735538)
		(end 325.552816 -24.160226)
		(width 0.127)
		(layer "In15.Cu")
		(net "RST_SRTCRST_N")
	)
	(segment
		(start 297.82262 -34.364422)
		(end 303.412652 -28.77439)
		(width 0.127)
		(layer "In15.Cu")
		(net "RST_SRTCRST_N")
	)
	(segment
		(start 320.892678 -24.997156)
		(end 322.154296 -23.735538)
		(width 0.127)
		(layer "In15.Cu")
		(net "RST_SRTCRST_N")
	)
	(segment
		(start 318.348106 -26.279348)
		(end 319.630298 -24.997156)
		(width 0.127)
		(layer "In15.Cu")
		(net "RST_SRTCRST_N")
	)
	(segment
		(start 252.998478 -65.81902)
		(end 262.15086 -63.998348)
		(width 0.127)
		(layer "In15.Cu")
		(net "RST_SRTCRST_N")
	)
	(segment
		(start 233.96575 -70.195948)
		(end 243.633244 -70.195948)
		(width 0.127)
		(layer "In15.Cu")
		(net "RST_SRTCRST_N")
	)
	(segment
		(start 290.96208 -44.157646)
		(end 294.8305 -40.289226)
		(width 0.127)
		(layer "In15.Cu")
		(net "RST_SRTCRST_N")
	)
	(segment
		(start 200.03008 -82.821018)
		(end 201.14895 -81.702148)
		(width 0.127)
		(layer "In15.Cu")
		(net "RST_SRTCRST_N")
	)
	(segment
		(start 246.560594 -67.268598)
		(end 251.5489 -67.268598)
		(width 0.127)
		(layer "In15.Cu")
		(net "RST_SRTCRST_N")
	)
	(segment
		(start 243.633244 -70.195948)
		(end 246.560594 -67.268598)
		(width 0.127)
		(layer "In15.Cu")
		(net "RST_SRTCRST_N")
	)
	(segment
		(start 274.60575 -63.998348)
		(end 290.96208 -47.642018)
		(width 0.127)
		(layer "In15.Cu")
		(net "RST_SRTCRST_N")
	)
	(segment
		(start 222.45955 -81.702148)
		(end 233.96575 -70.195948)
		(width 0.127)
		(layer "In15.Cu")
		(net "RST_SRTCRST_N")
	)
	(segment
		(start 294.8305 -38.626034)
		(end 297.82262 -35.633914)
		(width 0.127)
		(layer "In15.Cu")
		(net "RST_SRTCRST_N")
	)
	(segment
		(start 294.8305 -40.289226)
		(end 294.8305 -38.626034)
		(width 0.127)
		(layer "In15.Cu")
		(net "RST_SRTCRST_N")
	)
	(segment
		(start 200.0504 -90.1446)
		(end 200.0504 -89.202768)
		(width 0.127)
		(layer "In15.Cu")
		(net "RST_SRTCRST_N")
	)
	(segment
		(start 290.96208 -47.642018)
		(end 290.96208 -44.157646)
		(width 0.127)
		(layer "In15.Cu")
		(net "RST_SRTCRST_N")
	)
	(segment
		(start 325.552816 -24.160226)
		(end 325.552816 -24.232108)
		(width 0.127)
		(layer "In15.Cu")
		(net "RST_SRTCRST_N")
	)
	(segment
		(start 251.5489 -67.268598)
		(end 252.998478 -65.81902)
		(width 0.127)
		(layer "In15.Cu")
		(net "RST_SRTCRST_N")
	)
	(segment
		(start 305.664108 -28.77439)
		(end 308.15915 -26.279348)
		(width 0.127)
		(layer "In15.Cu")
		(net "RST_SRTCRST_N")
	)
	(segment
		(start 200.0504 -89.202768)
		(end 200.03008 -89.182448)
		(width 0.127)
		(layer "In15.Cu")
		(net "RST_SRTCRST_N")
	)
	(segment
		(start 113.094262 -136.520682)
		(end 113.066322 -136.520682)
		(width 0.12954)
		(layer "F.Cu")
		(net "RST_SMB_SWITCH_N")
	)
	(segment
		(start 457.62672 -93.627448)
		(end 458.487526 -93.627448)
		(width 0.12954)
		(layer "F.Cu")
		(net "RST_SMB_SWITCH_N")
	)
	(segment
		(start 151.444706 -66.131694)
		(end 151.444706 -65.413128)
		(width 0.12954)
		(layer "F.Cu")
		(net "RST_SMB_SWITCH_N")
	)
	(segment
		(start 152.11806 -66.805048)
		(end 151.444706 -66.131694)
		(width 0.12954)
		(layer "F.Cu")
		(net "RST_SMB_SWITCH_N")
	)
	(segment
		(start 53.842666 -114.99469)
		(end 53.522626 -114.99469)
		(width 0.12954)
		(layer "F.Cu")
		(net "RST_SMB_SWITCH_N")
	)
	(segment
		(start 15.197582 -410.402786)
		(end 15.197582 -408.916886)
		(width 0.12954)
		(layer "F.Cu")
		(net "RST_SMB_SWITCH_N")
	)
	(segment
		(start 111.077502 -137.198862)
		(end 111.732822 -137.854182)
		(width 0.12954)
		(layer "F.Cu")
		(net "RST_SMB_SWITCH_N")
	)
	(segment
		(start 159.704786 -66.805048)
		(end 152.11806 -66.805048)
		(width 0.12954)
		(layer "F.Cu")
		(net "RST_SMB_SWITCH_N")
	)
	(segment
		(start 190.6778 -108.765848)
		(end 187.58662 -108.765848)
		(width 0.12954)
		(layer "F.Cu")
		(net "RST_SMB_SWITCH_N")
	)
	(segment
		(start 165.751764 -73.727818)
		(end 162.74288 -73.727818)
		(width 0.12954)
		(layer "F.Cu")
		(net "RST_SMB_SWITCH_N")
	)
	(segment
		(start 165.48608 -96.180148)
		(end 163.83508 -94.529148)
		(width 0.12954)
		(layer "F.Cu")
		(net "RST_SMB_SWITCH_N")
	)
	(segment
		(start 192.9765 -105.616248)
		(end 192.74536 -105.847388)
		(width 0.12954)
		(layer "F.Cu")
		(net "RST_SMB_SWITCH_N")
	)
	(segment
		(start 51.343306 -115.87353)
		(end 50.325782 -115.87353)
		(width 0.12954)
		(layer "F.Cu")
		(net "RST_SMB_SWITCH_N")
	)
	(segment
		(start 195.250054 -106.129582)
		(end 194.73672 -105.616248)
		(width 0.12954)
		(layer "F.Cu")
		(net "RST_SMB_SWITCH_N")
	)
	(segment
		(start 51.993546 -116.52377)
		(end 51.343306 -115.87353)
		(width 0.12954)
		(layer "F.Cu")
		(net "RST_SMB_SWITCH_N")
	)
	(segment
		(start 165.77818 -87.658448)
		(end 165.77818 -73.754234)
		(width 0.12954)
		(layer "F.Cu")
		(net "RST_SMB_SWITCH_N")
	)
	(segment
		(start 163.83508 -94.529148)
		(end 163.83508 -89.601548)
		(width 0.12954)
		(layer "F.Cu")
		(net "RST_SMB_SWITCH_N")
	)
	(segment
		(start 50.325782 -115.87353)
		(end 50.2031 -115.750848)
		(width 0.12954)
		(layer "F.Cu")
		(net "RST_SMB_SWITCH_N")
	)
	(segment
		(start 15.197582 -408.916886)
		(end 16.54048 -408.916886)
		(width 0.12954)
		(layer "F.Cu")
		(net "RST_SMB_SWITCH_N")
	)
	(segment
		(start 457.24572 -93.246448)
		(end 457.62672 -93.627448)
		(width 0.12954)
		(layer "F.Cu")
		(net "RST_SMB_SWITCH_N")
	)
	(segment
		(start 53.522626 -114.99469)
		(end 51.993546 -116.52377)
		(width 0.12954)
		(layer "F.Cu")
		(net "RST_SMB_SWITCH_N")
	)
	(segment
		(start 457.24064 -92.085668)
		(end 457.24572 -92.090748)
		(width 0.12954)
		(layer "F.Cu")
		(net "RST_SMB_SWITCH_N")
	)
	(segment
		(start 195.250054 -106.340148)
		(end 195.250054 -106.129582)
		(width 0.12954)
		(layer "F.Cu")
		(net "RST_SMB_SWITCH_N")
	)
	(segment
		(start 162.74288 -69.843142)
		(end 159.704786 -66.805048)
		(width 0.12954)
		(layer "F.Cu")
		(net "RST_SMB_SWITCH_N")
	)
	(segment
		(start 457.24572 -92.090748)
		(end 457.24572 -93.246448)
		(width 0.12954)
		(layer "F.Cu")
		(net "RST_SMB_SWITCH_N")
	)
	(segment
		(start 165.77818 -73.754234)
		(end 165.751764 -73.727818)
		(width 0.12954)
		(layer "F.Cu")
		(net "RST_SMB_SWITCH_N")
	)
	(segment
		(start 192.74536 -106.698288)
		(end 190.6778 -108.765848)
		(width 0.12954)
		(layer "F.Cu")
		(net "RST_SMB_SWITCH_N")
	)
	(segment
		(start 162.74288 -73.727818)
		(end 162.74288 -69.843142)
		(width 0.12954)
		(layer "F.Cu")
		(net "RST_SMB_SWITCH_N")
	)
	(segment
		(start 110.31728 -137.198862)
		(end 111.077502 -137.198862)
		(width 0.12954)
		(layer "F.Cu")
		(net "RST_SMB_SWITCH_N")
	)
	(segment
		(start 152.6032 -109.4486)
		(end 152.96388 -109.08792)
		(width 0.12954)
		(layer "F.Cu")
		(net "RST_SMB_SWITCH_N")
	)
	(segment
		(start 187.58662 -108.765848)
		(end 187.37707 -108.975398)
		(width 0.12954)
		(layer "F.Cu")
		(net "RST_SMB_SWITCH_N")
	)
	(segment
		(start 192.74536 -105.847388)
		(end 192.74536 -106.698288)
		(width 0.12954)
		(layer "F.Cu")
		(net "RST_SMB_SWITCH_N")
	)
	(segment
		(start 163.83508 -89.601548)
		(end 165.77818 -87.658448)
		(width 0.12954)
		(layer "F.Cu")
		(net "RST_SMB_SWITCH_N")
	)
	(segment
		(start 152.96388 -109.08792)
		(end 152.96388 -108.361988)
		(width 0.12954)
		(layer "F.Cu")
		(net "RST_SMB_SWITCH_N")
	)
	(segment
		(start 113.066322 -136.520682)
		(end 111.732822 -137.854182)
		(width 0.12954)
		(layer "F.Cu")
		(net "RST_SMB_SWITCH_N")
	)
	(segment
		(start 194.73672 -105.616248)
		(end 192.9765 -105.616248)
		(width 0.12954)
		(layer "F.Cu")
		(net "RST_SMB_SWITCH_N")
	)
	(segment
		(start 187.37707 -108.975398)
		(end 186.955684 -108.975398)
		(width 0.12954)
		(layer "F.Cu")
		(net "RST_SMB_SWITCH_N")
	)
	(via
		(at 457.24064 -92.085668)
		(size 0.508)
		(drill 0.254)
		(layers "F.Cu" "B.Cu")
		(net "RST_SMB_SWITCH_N")
	)
	(via
		(at 50.2031 -115.750848)
		(size 0.508)
		(drill 0.254)
		(layers "F.Cu" "B.Cu")
		(net "RST_SMB_SWITCH_N")
	)
	(via
		(at 16.54048 -408.916886)
		(size 0.762)
		(drill 0.254)
		(layers "F.Cu" "B.Cu")
		(net "RST_SMB_SWITCH_N")
	)
	(via
		(at 273.84248 -104.460548)
		(size 0.508)
		(drill 0.254)
		(layers "F.Cu" "B.Cu")
		(net "RST_SMB_SWITCH_N")
	)
	(via
		(at 110.31728 -137.198862)
		(size 0.508)
		(drill 0.254)
		(layers "F.Cu" "B.Cu")
		(net "RST_SMB_SWITCH_N")
	)
	(via
		(at 165.48608 -96.180148)
		(size 0.508)
		(drill 0.254)
		(layers "F.Cu" "B.Cu")
		(net "RST_SMB_SWITCH_N")
	)
	(via
		(at 152.6032 -109.4486)
		(size 0.508)
		(drill 0.254)
		(layers "F.Cu" "B.Cu")
		(net "RST_SMB_SWITCH_N")
	)
	(via
		(at 4.17068 -106.848148)
		(size 0.508)
		(drill 0.254)
		(layers "F.Cu" "B.Cu")
		(net "RST_SMB_SWITCH_N")
	)
	(via
		(at 195.250054 -106.340148)
		(size 0.508)
		(drill 0.254)
		(layers "F.Cu" "B.Cu")
		(net "RST_SMB_SWITCH_N")
	)
	(segment
		(start 127.76708 -139.410948)
		(end 136.097264 -139.410948)
		(width 0.12954)
		(layer "B.Cu")
		(net "RST_SMB_SWITCH_N")
	)
	(segment
		(start 151.81834 -107.55122)
		(end 151.81834 -101.588316)
		(width 0.12954)
		(layer "B.Cu")
		(net "RST_SMB_SWITCH_N")
	)
	(segment
		(start 149.73808 -111.72952)
		(end 151.977852 -109.489748)
		(width 0.12954)
		(layer "B.Cu")
		(net "RST_SMB_SWITCH_N")
	)
	(segment
		(start 136.097264 -139.410948)
		(end 137.32256 -140.636244)
		(width 0.12954)
		(layer "B.Cu")
		(net "RST_SMB_SWITCH_N")
	)
	(segment
		(start 110.319566 -137.201148)
		(end 125.55728 -137.201148)
		(width 0.12954)
		(layer "B.Cu")
		(net "RST_SMB_SWITCH_N")
	)
	(segment
		(start 141.836902 -127.262128)
		(end 145.906236 -123.192794)
		(width 0.12954)
		(layer "B.Cu")
		(net "RST_SMB_SWITCH_N")
	)
	(segment
		(start 137.32256 -140.636244)
		(end 142.23619 -140.636244)
		(width 0.12954)
		(layer "B.Cu")
		(net "RST_SMB_SWITCH_N")
	)
	(segment
		(start 152.98928 -108.72216)
		(end 151.81834 -107.55122)
		(width 0.12954)
		(layer "B.Cu")
		(net "RST_SMB_SWITCH_N")
	)
	(segment
		(start 152.98928 -109.06252)
		(end 152.98928 -108.72216)
		(width 0.12954)
		(layer "B.Cu")
		(net "RST_SMB_SWITCH_N")
	)
	(segment
		(start 125.55728 -137.201148)
		(end 127.76708 -139.410948)
		(width 0.12954)
		(layer "B.Cu")
		(net "RST_SMB_SWITCH_N")
	)
	(segment
		(start 145.906236 -123.192794)
		(end 145.906236 -117.766592)
		(width 0.12954)
		(layer "B.Cu")
		(net "RST_SMB_SWITCH_N")
	)
	(segment
		(start 151.977852 -109.489748)
		(end 152.562052 -109.489748)
		(width 0.12954)
		(layer "B.Cu")
		(net "RST_SMB_SWITCH_N")
	)
	(segment
		(start 143.157448 -138.854942)
		(end 141.836902 -137.534396)
		(width 0.12954)
		(layer "B.Cu")
		(net "RST_SMB_SWITCH_N")
	)
	(segment
		(start 155.453588 -97.953068)
		(end 163.71316 -97.953068)
		(width 0.12954)
		(layer "B.Cu")
		(net "RST_SMB_SWITCH_N")
	)
	(segment
		(start 149.73808 -113.934748)
		(end 149.73808 -111.72952)
		(width 0.12954)
		(layer "B.Cu")
		(net "RST_SMB_SWITCH_N")
	)
	(segment
		(start 152.6032 -109.4486)
		(end 152.98928 -109.06252)
		(width 0.12954)
		(layer "B.Cu")
		(net "RST_SMB_SWITCH_N")
	)
	(segment
		(start 145.906236 -117.766592)
		(end 149.73808 -113.934748)
		(width 0.12954)
		(layer "B.Cu")
		(net "RST_SMB_SWITCH_N")
	)
	(segment
		(start 143.157448 -139.714986)
		(end 143.157448 -138.854942)
		(width 0.12954)
		(layer "B.Cu")
		(net "RST_SMB_SWITCH_N")
	)
	(segment
		(start 163.71316 -97.953068)
		(end 165.48608 -96.180148)
		(width 0.12954)
		(layer "B.Cu")
		(net "RST_SMB_SWITCH_N")
	)
	(segment
		(start 152.562052 -109.489748)
		(end 152.6032 -109.4486)
		(width 0.12954)
		(layer "B.Cu")
		(net "RST_SMB_SWITCH_N")
	)
	(segment
		(start 142.23619 -140.636244)
		(end 143.157448 -139.714986)
		(width 0.12954)
		(layer "B.Cu")
		(net "RST_SMB_SWITCH_N")
	)
	(segment
		(start 110.31728 -137.198862)
		(end 110.319566 -137.201148)
		(width 0.12954)
		(layer "B.Cu")
		(net "RST_SMB_SWITCH_N")
	)
	(segment
		(start 141.836902 -137.534396)
		(end 141.836902 -127.262128)
		(width 0.12954)
		(layer "B.Cu")
		(net "RST_SMB_SWITCH_N")
	)
	(segment
		(start 151.81834 -101.588316)
		(end 155.453588 -97.953068)
		(width 0.12954)
		(layer "B.Cu")
		(net "RST_SMB_SWITCH_N")
	)
	(segment
		(start 3.92938 -107.089448)
		(end 4.17068 -106.848148)
		(width 0.127)
		(layer "In2.Cu")
		(net "RST_SMB_SWITCH_N")
	)
	(segment
		(start 4.31038 -157.102048)
		(end 7.77748 -153.634948)
		(width 0.127)
		(layer "In2.Cu")
		(net "RST_SMB_SWITCH_N")
	)
	(segment
		(start 17.53108 -407.926286)
		(end 17.53108 -403.135084)
		(width 0.127)
		(layer "In2.Cu")
		(net "RST_SMB_SWITCH_N")
	)
	(segment
		(start 6.07822 -375.501916)
		(end 17.53108 -364.049056)
		(width 0.127)
		(layer "In2.Cu")
		(net "RST_SMB_SWITCH_N")
	)
	(segment
		(start 4.31038 -332.666848)
		(end 4.31038 -157.102048)
		(width 0.127)
		(layer "In2.Cu")
		(net "RST_SMB_SWITCH_N")
	)
	(segment
		(start 7.77748 -153.634948)
		(end 9.88568 -153.634948)
		(width 0.127)
		(layer "In2.Cu")
		(net "RST_SMB_SWITCH_N")
	)
	(segment
		(start 6.07822 -391.682224)
		(end 6.07822 -375.501916)
		(width 0.127)
		(layer "In2.Cu")
		(net "RST_SMB_SWITCH_N")
	)
	(segment
		(start 17.53108 -345.887548)
		(end 4.31038 -332.666848)
		(width 0.127)
		(layer "In2.Cu")
		(net "RST_SMB_SWITCH_N")
	)
	(segment
		(start 16.54048 -408.916886)
		(end 17.53108 -407.926286)
		(width 0.127)
		(layer "In2.Cu")
		(net "RST_SMB_SWITCH_N")
	)
	(segment
		(start 10.59688 -143.742156)
		(end 3.92938 -137.074656)
		(width 0.127)
		(layer "In2.Cu")
		(net "RST_SMB_SWITCH_N")
	)
	(segment
		(start 9.88568 -153.634948)
		(end 10.59688 -152.923748)
		(width 0.127)
		(layer "In2.Cu")
		(net "RST_SMB_SWITCH_N")
	)
	(segment
		(start 17.53108 -364.049056)
		(end 17.53108 -345.887548)
		(width 0.127)
		(layer "In2.Cu")
		(net "RST_SMB_SWITCH_N")
	)
	(segment
		(start 17.53108 -403.135084)
		(end 6.07822 -391.682224)
		(width 0.127)
		(layer "In2.Cu")
		(net "RST_SMB_SWITCH_N")
	)
	(segment
		(start 10.59688 -152.923748)
		(end 10.59688 -143.742156)
		(width 0.127)
		(layer "In2.Cu")
		(net "RST_SMB_SWITCH_N")
	)
	(segment
		(start 3.92938 -137.074656)
		(end 3.92938 -107.089448)
		(width 0.127)
		(layer "In2.Cu")
		(net "RST_SMB_SWITCH_N")
	)
	(segment
		(start 446.252092 -100.777548)
		(end 439.504074 -107.525566)
		(width 0.127)
		(layer "In4.Cu")
		(net "RST_SMB_SWITCH_N")
	)
	(segment
		(start 451.6882 -94.722188)
		(end 451.6882 -98.730308)
		(width 0.127)
		(layer "In4.Cu")
		(net "RST_SMB_SWITCH_N")
	)
	(segment
		(start 74.30008 -141.671548)
		(end 58.32348 -141.671548)
		(width 0.127)
		(layer "In4.Cu")
		(net "RST_SMB_SWITCH_N")
	)
	(segment
		(start 274.397724 -105.015792)
		(end 273.84248 -104.460548)
		(width 0.127)
		(layer "In4.Cu")
		(net "RST_SMB_SWITCH_N")
	)
	(segment
		(start 97.18548 -149.850348)
		(end 82.17408 -149.850348)
		(width 0.127)
		(layer "In4.Cu")
		(net "RST_SMB_SWITCH_N")
	)
	(segment
		(start 76.28128 -150.307548)
		(end 76.28128 -145.557748)
		(width 0.127)
		(layer "In4.Cu")
		(net "RST_SMB_SWITCH_N")
	)
	(segment
		(start 109.836966 -137.198862)
		(end 97.18548 -149.850348)
		(width 0.127)
		(layer "In4.Cu")
		(net "RST_SMB_SWITCH_N")
	)
	(segment
		(start 80.90408 -151.120348)
		(end 77.09408 -151.120348)
		(width 0.127)
		(layer "In4.Cu")
		(net "RST_SMB_SWITCH_N")
	)
	(segment
		(start 439.504074 -109.611414)
		(end 437.02224 -112.093248)
		(width 0.127)
		(layer "In4.Cu")
		(net "RST_SMB_SWITCH_N")
	)
	(segment
		(start 379.136656 -105.015792)
		(end 378.7775 -105.374948)
		(width 0.127)
		(layer "In4.Cu")
		(net "RST_SMB_SWITCH_N")
	)
	(segment
		(start 82.17408 -149.850348)
		(end 80.90408 -151.120348)
		(width 0.127)
		(layer "In4.Cu")
		(net "RST_SMB_SWITCH_N")
	)
	(segment
		(start 378.7775 -105.374948)
		(end 376.4534 -105.374948)
		(width 0.127)
		(layer "In4.Cu")
		(net "RST_SMB_SWITCH_N")
	)
	(segment
		(start 437.02224 -112.093248)
		(end 415.06394 -112.093248)
		(width 0.127)
		(layer "In4.Cu")
		(net "RST_SMB_SWITCH_N")
	)
	(segment
		(start 376.4534 -105.374948)
		(end 376.094244 -105.015792)
		(width 0.127)
		(layer "In4.Cu")
		(net "RST_SMB_SWITCH_N")
	)
	(segment
		(start 76.28128 -145.557748)
		(end 75.77328 -145.049748)
		(width 0.127)
		(layer "In4.Cu")
		(net "RST_SMB_SWITCH_N")
	)
	(segment
		(start 454.32472 -92.085668)
		(end 451.6882 -94.722188)
		(width 0.127)
		(layer "In4.Cu")
		(net "RST_SMB_SWITCH_N")
	)
	(segment
		(start 451.6882 -98.730308)
		(end 449.64096 -100.777548)
		(width 0.127)
		(layer "In4.Cu")
		(net "RST_SMB_SWITCH_N")
	)
	(segment
		(start 457.24064 -92.085668)
		(end 454.32472 -92.085668)
		(width 0.127)
		(layer "In4.Cu")
		(net "RST_SMB_SWITCH_N")
	)
	(segment
		(start 75.77328 -145.049748)
		(end 75.77328 -143.144748)
		(width 0.127)
		(layer "In4.Cu")
		(net "RST_SMB_SWITCH_N")
	)
	(segment
		(start 51.906678 -135.254746)
		(end 51.906678 -117.454426)
		(width 0.127)
		(layer "In4.Cu")
		(net "RST_SMB_SWITCH_N")
	)
	(segment
		(start 407.986484 -105.015792)
		(end 379.136656 -105.015792)
		(width 0.127)
		(layer "In4.Cu")
		(net "RST_SMB_SWITCH_N")
	)
	(segment
		(start 75.77328 -143.144748)
		(end 74.30008 -141.671548)
		(width 0.127)
		(layer "In4.Cu")
		(net "RST_SMB_SWITCH_N")
	)
	(segment
		(start 439.504074 -107.525566)
		(end 439.504074 -109.611414)
		(width 0.127)
		(layer "In4.Cu")
		(net "RST_SMB_SWITCH_N")
	)
	(segment
		(start 58.32348 -141.671548)
		(end 51.906678 -135.254746)
		(width 0.127)
		(layer "In4.Cu")
		(net "RST_SMB_SWITCH_N")
	)
	(segment
		(start 51.906678 -117.454426)
		(end 50.2031 -115.750848)
		(width 0.127)
		(layer "In4.Cu")
		(net "RST_SMB_SWITCH_N")
	)
	(segment
		(start 77.09408 -151.120348)
		(end 76.28128 -150.307548)
		(width 0.127)
		(layer "In4.Cu")
		(net "RST_SMB_SWITCH_N")
	)
	(segment
		(start 110.31728 -137.198862)
		(end 109.836966 -137.198862)
		(width 0.127)
		(layer "In4.Cu")
		(net "RST_SMB_SWITCH_N")
	)
	(segment
		(start 449.64096 -100.777548)
		(end 446.252092 -100.777548)
		(width 0.127)
		(layer "In4.Cu")
		(net "RST_SMB_SWITCH_N")
	)
	(segment
		(start 415.06394 -112.093248)
		(end 407.986484 -105.015792)
		(width 0.127)
		(layer "In4.Cu")
		(net "RST_SMB_SWITCH_N")
	)
	(segment
		(start 376.094244 -105.015792)
		(end 274.397724 -105.015792)
		(width 0.127)
		(layer "In4.Cu")
		(net "RST_SMB_SWITCH_N")
	)
	(segment
		(start 193.49466 -102.174548)
		(end 194.534028 -101.13518)
		(width 0.127)
		(layer "In6.Cu")
		(net "RST_SMB_SWITCH_N")
	)
	(segment
		(start 180.429408 -100.076)
		(end 181.014116 -100.318316)
		(width 0.127)
		(layer "In6.Cu")
		(net "RST_SMB_SWITCH_N")
	)
	(segment
		(start 165.48608 -96.180148)
		(end 169.75074 -96.180148)
		(width 0.127)
		(layer "In6.Cu")
		(net "RST_SMB_SWITCH_N")
	)
	(segment
		(start 195.557648 -101.13518)
		(end 196.01688 -100.675948)
		(width 0.127)
		(layer "In6.Cu")
		(net "RST_SMB_SWITCH_N")
	)
	(segment
		(start 196.65188 -100.675948)
		(end 197.15988 -101.183948)
		(width 0.127)
		(layer "In6.Cu")
		(net "RST_SMB_SWITCH_N")
	)
	(segment
		(start 175.046894 -98.174048)
		(end 175.3616 -98.488754)
		(width 0.127)
		(layer "In6.Cu")
		(net "RST_SMB_SWITCH_N")
	)
	(segment
		(start 195.250054 -105.708958)
		(end 195.250054 -106.340148)
		(width 0.127)
		(layer "In6.Cu")
		(net "RST_SMB_SWITCH_N")
	)
	(segment
		(start 182.870348 -102.174548)
		(end 193.49466 -102.174548)
		(width 0.127)
		(layer "In6.Cu")
		(net "RST_SMB_SWITCH_N")
	)
	(segment
		(start 196.01688 -100.675948)
		(end 196.65188 -100.675948)
		(width 0.127)
		(layer "In6.Cu")
		(net "RST_SMB_SWITCH_N")
	)
	(segment
		(start 175.3616 -99.604068)
		(end 175.833532 -100.076)
		(width 0.127)
		(layer "In6.Cu")
		(net "RST_SMB_SWITCH_N")
	)
	(segment
		(start 169.75074 -96.180148)
		(end 171.74464 -98.174048)
		(width 0.127)
		(layer "In6.Cu")
		(net "RST_SMB_SWITCH_N")
	)
	(segment
		(start 171.74464 -98.174048)
		(end 175.046894 -98.174048)
		(width 0.127)
		(layer "In6.Cu")
		(net "RST_SMB_SWITCH_N")
	)
	(segment
		(start 181.014116 -100.318316)
		(end 182.870348 -102.174548)
		(width 0.127)
		(layer "In6.Cu")
		(net "RST_SMB_SWITCH_N")
	)
	(segment
		(start 175.3616 -98.488754)
		(end 175.3616 -99.604068)
		(width 0.127)
		(layer "In6.Cu")
		(net "RST_SMB_SWITCH_N")
	)
	(segment
		(start 197.15988 -101.183948)
		(end 197.15988 -103.799132)
		(width 0.127)
		(layer "In6.Cu")
		(net "RST_SMB_SWITCH_N")
	)
	(segment
		(start 194.534028 -101.13518)
		(end 195.557648 -101.13518)
		(width 0.127)
		(layer "In6.Cu")
		(net "RST_SMB_SWITCH_N")
	)
	(segment
		(start 197.15988 -103.799132)
		(end 195.250054 -105.708958)
		(width 0.127)
		(layer "In6.Cu")
		(net "RST_SMB_SWITCH_N")
	)
	(segment
		(start 175.833532 -100.076)
		(end 180.429408 -100.076)
		(width 0.127)
		(layer "In6.Cu")
		(net "RST_SMB_SWITCH_N")
	)
	(segment
		(start 208.321148 -110.835948)
		(end 208.830164 -111.344964)
		(width 0.127)
		(layer "In13.Cu")
		(net "RST_SMB_SWITCH_N")
	)
	(segment
		(start 244.583712 -112.613948)
		(end 245.85676 -112.613948)
		(width 0.127)
		(layer "In13.Cu")
		(net "RST_SMB_SWITCH_N")
	)
	(segment
		(start 200.63968 -109.162088)
		(end 202.31354 -110.835948)
		(width 0.127)
		(layer "In13.Cu")
		(net "RST_SMB_SWITCH_N")
	)
	(segment
		(start 263.0551 -111.536988)
		(end 270.13154 -104.460548)
		(width 0.127)
		(layer "In13.Cu")
		(net "RST_SMB_SWITCH_N")
	)
	(segment
		(start 270.13154 -104.460548)
		(end 273.84248 -104.460548)
		(width 0.127)
		(layer "In13.Cu")
		(net "RST_SMB_SWITCH_N")
	)
	(segment
		(start 218.66606 -110.812072)
		(end 230.314754 -110.812072)
		(width 0.127)
		(layer "In13.Cu")
		(net "RST_SMB_SWITCH_N")
	)
	(segment
		(start 235.07573 -106.051096)
		(end 241.053112 -106.051096)
		(width 0.127)
		(layer "In13.Cu")
		(net "RST_SMB_SWITCH_N")
	)
	(segment
		(start 17.622774 -115.89258)
		(end 17.703546 -115.811808)
		(width 0.127)
		(layer "In13.Cu")
		(net "RST_SMB_SWITCH_N")
	)
	(segment
		(start 7.680198 -115.89258)
		(end 17.622774 -115.89258)
		(width 0.127)
		(layer "In13.Cu")
		(net "RST_SMB_SWITCH_N")
	)
	(segment
		(start 245.85676 -112.613948)
		(end 246.93372 -111.536988)
		(width 0.127)
		(layer "In13.Cu")
		(net "RST_SMB_SWITCH_N")
	)
	(segment
		(start 50.14214 -115.811808)
		(end 50.2031 -115.750848)
		(width 0.127)
		(layer "In13.Cu")
		(net "RST_SMB_SWITCH_N")
	)
	(segment
		(start 230.314754 -110.812072)
		(end 235.07573 -106.051096)
		(width 0.127)
		(layer "In13.Cu")
		(net "RST_SMB_SWITCH_N")
	)
	(segment
		(start 4.17068 -106.848148)
		(end 4.962144 -107.639612)
		(width 0.127)
		(layer "In13.Cu")
		(net "RST_SMB_SWITCH_N")
	)
	(segment
		(start 4.962144 -107.639612)
		(end 4.962144 -113.174526)
		(width 0.127)
		(layer "In13.Cu")
		(net "RST_SMB_SWITCH_N")
	)
	(segment
		(start 196.97954 -106.774488)
		(end 199.36714 -109.162088)
		(width 0.127)
		(layer "In13.Cu")
		(net "RST_SMB_SWITCH_N")
	)
	(segment
		(start 202.31354 -110.835948)
		(end 208.321148 -110.835948)
		(width 0.127)
		(layer "In13.Cu")
		(net "RST_SMB_SWITCH_N")
	)
	(segment
		(start 199.36714 -109.162088)
		(end 200.63968 -109.162088)
		(width 0.127)
		(layer "In13.Cu")
		(net "RST_SMB_SWITCH_N")
	)
	(segment
		(start 17.703546 -115.811808)
		(end 50.14214 -115.811808)
		(width 0.127)
		(layer "In13.Cu")
		(net "RST_SMB_SWITCH_N")
	)
	(segment
		(start 195.250054 -106.340148)
		(end 195.684394 -106.774488)
		(width 0.127)
		(layer "In13.Cu")
		(net "RST_SMB_SWITCH_N")
	)
	(segment
		(start 246.93372 -111.536988)
		(end 263.0551 -111.536988)
		(width 0.127)
		(layer "In13.Cu")
		(net "RST_SMB_SWITCH_N")
	)
	(segment
		(start 218.133168 -111.344964)
		(end 218.66606 -110.812072)
		(width 0.127)
		(layer "In13.Cu")
		(net "RST_SMB_SWITCH_N")
	)
	(segment
		(start 241.053112 -106.051096)
		(end 243.12118 -108.119164)
		(width 0.127)
		(layer "In13.Cu")
		(net "RST_SMB_SWITCH_N")
	)
	(segment
		(start 243.12118 -111.151416)
		(end 244.583712 -112.613948)
		(width 0.127)
		(layer "In13.Cu")
		(net "RST_SMB_SWITCH_N")
	)
	(segment
		(start 4.962144 -113.174526)
		(end 7.680198 -115.89258)
		(width 0.127)
		(layer "In13.Cu")
		(net "RST_SMB_SWITCH_N")
	)
	(segment
		(start 243.12118 -108.119164)
		(end 243.12118 -111.151416)
		(width 0.127)
		(layer "In13.Cu")
		(net "RST_SMB_SWITCH_N")
	)
	(segment
		(start 208.830164 -111.344964)
		(end 218.133168 -111.344964)
		(width 0.127)
		(layer "In13.Cu")
		(net "RST_SMB_SWITCH_N")
	)
	(segment
		(start 195.684394 -106.774488)
		(end 196.97954 -106.774488)
		(width 0.127)
		(layer "In13.Cu")
		(net "RST_SMB_SWITCH_N")
	)
	(segment
		(start 161.92119 -73.706228)
		(end 161.94278 -73.727818)
		(width 0.12954)
		(layer "F.Cu")
		(net "RST_SMB_S3M_N")
	)
	(segment
		(start 160.19018 -73.706228)
		(end 160.492694 -73.706228)
		(width 0.12954)
		(layer "F.Cu")
		(net "RST_SMB_S3M_N")
	)
	(segment
		(start 159.276542 -74.619866)
		(end 160.19018 -73.706228)
		(width 0.12954)
		(layer "F.Cu")
		(net "RST_SMB_S3M_N")
	)
	(segment
		(start 160.492694 -73.706228)
		(end 161.92119 -73.706228)
		(width 0.12954)
		(layer "F.Cu")
		(net "RST_SMB_S3M_N")
	)
	(segment
		(start 157.985968 -74.619866)
		(end 159.276542 -74.619866)
		(width 0.12954)
		(layer "F.Cu")
		(net "RST_SMB_S3M_N")
	)
	(via
		(at 160.492694 -73.706228)
		(size 0.762)
		(drill 0.381)
		(layers "F.Cu" "B.Cu")
		(net "RST_SMB_S3M_N")
	)
	(segment
		(start 182.155592 -114.575336)
		(end 182.555642 -114.975386)
		(width 0.12954)
		(layer "F.Cu")
		(net "RST_SGPIO_RESET_N_R")
	)
	(segment
		(start 196.79031 -116.804948)
		(end 196.18071 -116.804948)
		(width 0.12954)
		(layer "F.Cu")
		(net "RST_SGPIO_RESET_N_R")
	)
	(via
		(at 196.18071 -116.804948)
		(size 0.508)
		(drill 0.254)
		(layers "F.Cu" "B.Cu")
		(net "RST_SGPIO_RESET_N_R")
	)
	(via
		(at 182.555642 -114.975386)
		(size 0.4572)
		(drill 0.254)
		(layers "F.Cu" "B.Cu")
		(net "RST_SGPIO_RESET_N_R")
	)
	(segment
		(start 186.567826 -115.854734)
		(end 186.08294 -115.369848)
		(width 0.127)
		(layer "In6.Cu")
		(net "RST_SGPIO_RESET_N_R")
	)
	(segment
		(start 196.18071 -116.804948)
		(end 195.60921 -117.376448)
		(width 0.127)
		(layer "In6.Cu")
		(net "RST_SGPIO_RESET_N_R")
	)
	(segment
		(start 182.950104 -115.369848)
		(end 182.555642 -114.975386)
		(width 0.127)
		(layer "In6.Cu")
		(net "RST_SGPIO_RESET_N_R")
	)
	(segment
		(start 186.08294 -115.369848)
		(end 182.950104 -115.369848)
		(width 0.127)
		(layer "In6.Cu")
		(net "RST_SGPIO_RESET_N_R")
	)
	(segment
		(start 193.95186 -117.376448)
		(end 192.430146 -115.854734)
		(width 0.127)
		(layer "In6.Cu")
		(net "RST_SGPIO_RESET_N_R")
	)
	(segment
		(start 195.60921 -117.376448)
		(end 193.95186 -117.376448)
		(width 0.127)
		(layer "In6.Cu")
		(net "RST_SGPIO_RESET_N_R")
	)
	(segment
		(start 192.430146 -115.854734)
		(end 186.567826 -115.854734)
		(width 0.127)
		(layer "In6.Cu")
		(net "RST_SGPIO_RESET_N_R")
	)
	(segment
		(start 148.62048 -16.444468)
		(end 150.1902 -14.874748)
		(width 0.12954)
		(layer "F.Cu")
		(net "RST_SGPIO_RESET_N")
	)
	(segment
		(start 144.328134 -27.681428)
		(end 148.62048 -23.389082)
		(width 0.12954)
		(layer "F.Cu")
		(net "RST_SGPIO_RESET_N")
	)
	(segment
		(start 137.6807 -53.790596)
		(end 129.47523 -45.585126)
		(width 0.12954)
		(layer "F.Cu")
		(net "RST_SGPIO_RESET_N")
	)
	(segment
		(start 129.47523 -45.585126)
		(end 129.47523 -33.357058)
		(width 0.12954)
		(layer "F.Cu")
		(net "RST_SGPIO_RESET_N")
	)
	(segment
		(start 152.656794 -15.6337)
		(end 152.657048 -15.633954)
		(width 0.12954)
		(layer "F.Cu")
		(net "RST_SGPIO_RESET_N")
	)
	(segment
		(start 152.04948 -14.874748)
		(end 152.656794 -15.482062)
		(width 0.12954)
		(layer "F.Cu")
		(net "RST_SGPIO_RESET_N")
	)
	(segment
		(start 150.1902 -14.874748)
		(end 152.04948 -14.874748)
		(width 0.12954)
		(layer "F.Cu")
		(net "RST_SGPIO_RESET_N")
	)
	(segment
		(start 141.327632 -27.681428)
		(end 144.328134 -27.681428)
		(width 0.12954)
		(layer "F.Cu")
		(net "RST_SGPIO_RESET_N")
	)
	(segment
		(start 197.59041 -116.804948)
		(end 198.20001 -116.804948)
		(width 0.12954)
		(layer "F.Cu")
		(net "RST_SGPIO_RESET_N")
	)
	(segment
		(start 137.775188 -31.233872)
		(end 141.327632 -27.681428)
		(width 0.12954)
		(layer "F.Cu")
		(net "RST_SGPIO_RESET_N")
	)
	(segment
		(start 152.657048 -15.633954)
		(end 152.657048 -16.550132)
		(width 0.12954)
		(layer "F.Cu")
		(net "RST_SGPIO_RESET_N")
	)
	(segment
		(start 131.598416 -31.233872)
		(end 137.775188 -31.233872)
		(width 0.12954)
		(layer "F.Cu")
		(net "RST_SGPIO_RESET_N")
	)
	(segment
		(start 137.6807 -58.857388)
		(end 137.6807 -53.790596)
		(width 0.12954)
		(layer "F.Cu")
		(net "RST_SGPIO_RESET_N")
	)
	(segment
		(start 129.47523 -33.357058)
		(end 131.598416 -31.233872)
		(width 0.12954)
		(layer "F.Cu")
		(net "RST_SGPIO_RESET_N")
	)
	(segment
		(start 152.656794 -15.482062)
		(end 152.656794 -15.6337)
		(width 0.12954)
		(layer "F.Cu")
		(net "RST_SGPIO_RESET_N")
	)
	(segment
		(start 148.62048 -23.389082)
		(end 148.62048 -16.444468)
		(width 0.12954)
		(layer "F.Cu")
		(net "RST_SGPIO_RESET_N")
	)
	(via
		(at 198.20001 -116.804948)
		(size 0.508)
		(drill 0.254)
		(layers "F.Cu" "B.Cu")
		(net "RST_SGPIO_RESET_N")
	)
	(via
		(at 137.6807 -58.857388)
		(size 0.762)
		(drill 0.254)
		(layers "F.Cu" "B.Cu")
		(net "RST_SGPIO_RESET_N")
	)
	(segment
		(start 188.095382 -86.27745)
		(end 188.96076 -87.142828)
		(width 0.127)
		(layer "In4.Cu")
		(net "RST_SGPIO_RESET_N")
	)
	(segment
		(start 142.75054 -71.008748)
		(end 161.38144 -71.008748)
		(width 0.127)
		(layer "In4.Cu")
		(net "RST_SGPIO_RESET_N")
	)
	(segment
		(start 176.650142 -86.27745)
		(end 188.095382 -86.27745)
		(width 0.127)
		(layer "In4.Cu")
		(net "RST_SGPIO_RESET_N")
	)
	(segment
		(start 191.212216 -97.111312)
		(end 191.212216 -114.108484)
		(width 0.127)
		(layer "In4.Cu")
		(net "RST_SGPIO_RESET_N")
	)
	(segment
		(start 188.96076 -87.142828)
		(end 188.96076 -94.859856)
		(width 0.127)
		(layer "In4.Cu")
		(net "RST_SGPIO_RESET_N")
	)
	(segment
		(start 188.96076 -94.859856)
		(end 191.212216 -97.111312)
		(width 0.127)
		(layer "In4.Cu")
		(net "RST_SGPIO_RESET_N")
	)
	(segment
		(start 161.38144 -71.008748)
		(end 176.650142 -86.27745)
		(width 0.127)
		(layer "In4.Cu")
		(net "RST_SGPIO_RESET_N")
	)
	(segment
		(start 191.212216 -114.108484)
		(end 193.37528 -116.271548)
		(width 0.127)
		(layer "In4.Cu")
		(net "RST_SGPIO_RESET_N")
	)
	(segment
		(start 197.23608 -116.271548)
		(end 197.76948 -116.804948)
		(width 0.127)
		(layer "In4.Cu")
		(net "RST_SGPIO_RESET_N")
	)
	(segment
		(start 137.6807 -65.938908)
		(end 142.75054 -71.008748)
		(width 0.127)
		(layer "In4.Cu")
		(net "RST_SGPIO_RESET_N")
	)
	(segment
		(start 137.6807 -58.857388)
		(end 137.6807 -65.938908)
		(width 0.127)
		(layer "In4.Cu")
		(net "RST_SGPIO_RESET_N")
	)
	(segment
		(start 193.37528 -116.271548)
		(end 197.23608 -116.271548)
		(width 0.127)
		(layer "In4.Cu")
		(net "RST_SGPIO_RESET_N")
	)
	(segment
		(start 197.76948 -116.804948)
		(end 198.20001 -116.804948)
		(width 0.127)
		(layer "In4.Cu")
		(net "RST_SGPIO_RESET_N")
	)
	(segment
		(start 329.59167 -37.039296)
		(end 329.59167 -37.70249)
		(width 0.0889)
		(layer "F.Cu")
		(net "RST_RTCRST_N")
	)
	(segment
		(start 405.3205 -32.51327)
		(end 405.3205 -40.46347)
		(width 0.12954)
		(layer "F.Cu")
		(net "RST_RTCRST_N")
	)
	(segment
		(start 329.59167 -37.70249)
		(end 329.628754 -37.792152)
		(width 0.0889)
		(layer "F.Cu")
		(net "RST_RTCRST_N")
	)
	(segment
		(start 329.64882 -38.259766)
		(end 329.39609 -38.512496)
		(width 0.0889)
		(layer "F.Cu")
		(net "RST_RTCRST_N")
	)
	(segment
		(start 405.3205 -40.46347)
		(end 392.623802 -40.46347)
		(width 0.12954)
		(layer "F.Cu")
		(net "RST_RTCRST_N")
	)
	(segment
		(start 303.600612 -35.337496)
		(end 302.566324 -35.337496)
		(width 0.12954)
		(layer "F.Cu")
		(net "RST_RTCRST_N")
	)
	(segment
		(start 206.96809 -101.006656)
		(end 203.52639 -101.006656)
		(width 0.12954)
		(layer "F.Cu")
		(net "RST_RTCRST_N")
	)
	(segment
		(start 329.720194 -38.087554)
		(end 329.64882 -38.259766)
		(width 0.0889)
		(layer "F.Cu")
		(net "RST_RTCRST_N")
	)
	(segment
		(start 329.628754 -37.792152)
		(end 329.720194 -37.883592)
		(width 0.0889)
		(layer "F.Cu")
		(net "RST_RTCRST_N")
	)
	(segment
		(start 329.720194 -37.883592)
		(end 329.720194 -38.087554)
		(width 0.0889)
		(layer "F.Cu")
		(net "RST_RTCRST_N")
	)
	(segment
		(start 203.52639 -101.006656)
		(end 203.326492 -101.206554)
		(width 0.12954)
		(layer "F.Cu")
		(net "RST_RTCRST_N")
	)
	(segment
		(start 329.39609 -38.512496)
		(end 329.39609 -38.880288)
		(width 0.0889)
		(layer "F.Cu")
		(net "RST_RTCRST_N")
	)
	(segment
		(start 208.08188 -101.006656)
		(end 206.96809 -101.006656)
		(width 0.12954)
		(layer "F.Cu")
		(net "RST_RTCRST_N")
	)
	(segment
		(start 301.602902 -36.355528)
		(end 302.566324 -35.392106)
		(width 0.12954)
		(layer "F.Cu")
		(net "RST_RTCRST_N")
	)
	(segment
		(start 302.566324 -35.392106)
		(end 302.566324 -35.337496)
		(width 0.12954)
		(layer "F.Cu")
		(net "RST_RTCRST_N")
	)
	(via
		(at 329.59167 -37.039296)
		(size 0.49022)
		(drill 0.254)
		(layers "F.Cu" "B.Cu")
		(net "RST_RTCRST_N")
	)
	(via
		(at 208.08188 -101.006656)
		(size 0.508)
		(drill 0.254)
		(layers "F.Cu" "B.Cu")
		(net "RST_RTCRST_N")
	)
	(via
		(at 392.623802 -40.46347)
		(size 0.508)
		(drill 0.254)
		(layers "F.Cu" "B.Cu")
		(net "RST_RTCRST_N")
	)
	(via
		(at 313.61888 -96.611948)
		(size 0.508)
		(drill 0.254)
		(layers "F.Cu" "B.Cu")
		(net "RST_RTCRST_N")
	)
	(via
		(at 301.602902 -36.355528)
		(size 0.508)
		(drill 0.254)
		(layers "F.Cu" "B.Cu")
		(net "RST_RTCRST_N")
	)
	(segment
		(start 392.623802 -40.46347)
		(end 392.623802 -47.16907)
		(width 0.12954)
		(layer "B.Cu")
		(net "RST_RTCRST_N")
	)
	(segment
		(start 382.461516 -69.842888)
		(end 375.733056 -69.842888)
		(width 0.12954)
		(layer "B.Cu")
		(net "RST_RTCRST_N")
	)
	(segment
		(start 392.623802 -47.16907)
		(end 392.92276 -47.468028)
		(width 0.12954)
		(layer "B.Cu")
		(net "RST_RTCRST_N")
	)
	(segment
		(start 313.61888 -95.290894)
		(end 313.61888 -96.611948)
		(width 0.12954)
		(layer "B.Cu")
		(net "RST_RTCRST_N")
	)
	(segment
		(start 371.09908 -71.784464)
		(end 371.09908 -79.252064)
		(width 0.12954)
		(layer "B.Cu")
		(net "RST_RTCRST_N")
	)
	(segment
		(start 375.733056 -69.842888)
		(end 374.922796 -70.653148)
		(width 0.12954)
		(layer "B.Cu")
		(net "RST_RTCRST_N")
	)
	(segment
		(start 314.101226 -94.808548)
		(end 313.61888 -95.290894)
		(width 0.12954)
		(layer "B.Cu")
		(net "RST_RTCRST_N")
	)
	(segment
		(start 354.856796 -95.494348)
		(end 330.967334 -95.494348)
		(width 0.12954)
		(layer "B.Cu")
		(net "RST_RTCRST_N")
	)
	(segment
		(start 392.92276 -47.468028)
		(end 392.92276 -59.381644)
		(width 0.12954)
		(layer "B.Cu")
		(net "RST_RTCRST_N")
	)
	(segment
		(start 374.922796 -70.653148)
		(end 372.230396 -70.653148)
		(width 0.12954)
		(layer "B.Cu")
		(net "RST_RTCRST_N")
	)
	(segment
		(start 392.92276 -59.381644)
		(end 382.461516 -69.842888)
		(width 0.12954)
		(layer "B.Cu")
		(net "RST_RTCRST_N")
	)
	(segment
		(start 330.281534 -94.808548)
		(end 314.101226 -94.808548)
		(width 0.12954)
		(layer "B.Cu")
		(net "RST_RTCRST_N")
	)
	(segment
		(start 371.09908 -79.252064)
		(end 354.856796 -95.494348)
		(width 0.12954)
		(layer "B.Cu")
		(net "RST_RTCRST_N")
	)
	(segment
		(start 372.230396 -70.653148)
		(end 371.09908 -71.784464)
		(width 0.12954)
		(layer "B.Cu")
		(net "RST_RTCRST_N")
	)
	(segment
		(start 330.967334 -95.494348)
		(end 330.281534 -94.808548)
		(width 0.12954)
		(layer "B.Cu")
		(net "RST_RTCRST_N")
	)
	(segment
		(start 238.39932 -102.395528)
		(end 222.377508 -102.395528)
		(width 0.127)
		(layer "In11.Cu")
		(net "RST_RTCRST_N")
	)
	(segment
		(start 276.915372 -98.186748)
		(end 263.351518 -111.750602)
		(width 0.127)
		(layer "In11.Cu")
		(net "RST_RTCRST_N")
	)
	(segment
		(start 313.08548 -95.138748)
		(end 310.413908 -95.138748)
		(width 0.127)
		(layer "In11.Cu")
		(net "RST_RTCRST_N")
	)
	(segment
		(start 246.51081 -108.600748)
		(end 244.60454 -108.600748)
		(width 0.127)
		(layer "In11.Cu")
		(net "RST_RTCRST_N")
	)
	(segment
		(start 313.61888 -96.611948)
		(end 313.61888 -95.672148)
		(width 0.127)
		(layer "In11.Cu")
		(net "RST_RTCRST_N")
	)
	(segment
		(start 219.587572 -102.395528)
		(end 209.470752 -102.395528)
		(width 0.127)
		(layer "In11.Cu")
		(net "RST_RTCRST_N")
	)
	(segment
		(start 222.377508 -102.395528)
		(end 221.74708 -101.7651)
		(width 0.127)
		(layer "In11.Cu")
		(net "RST_RTCRST_N")
	)
	(segment
		(start 244.60454 -108.600748)
		(end 238.39932 -102.395528)
		(width 0.127)
		(layer "In11.Cu")
		(net "RST_RTCRST_N")
	)
	(segment
		(start 220.218 -101.7651)
		(end 219.587572 -102.395528)
		(width 0.127)
		(layer "In11.Cu")
		(net "RST_RTCRST_N")
	)
	(segment
		(start 307.365908 -98.186748)
		(end 276.915372 -98.186748)
		(width 0.127)
		(layer "In11.Cu")
		(net "RST_RTCRST_N")
	)
	(segment
		(start 209.470752 -102.395528)
		(end 208.08188 -101.006656)
		(width 0.127)
		(layer "In11.Cu")
		(net "RST_RTCRST_N")
	)
	(segment
		(start 263.351518 -111.750602)
		(end 249.660664 -111.750602)
		(width 0.127)
		(layer "In11.Cu")
		(net "RST_RTCRST_N")
	)
	(segment
		(start 310.413908 -95.138748)
		(end 307.365908 -98.186748)
		(width 0.127)
		(layer "In11.Cu")
		(net "RST_RTCRST_N")
	)
	(segment
		(start 249.660664 -111.750602)
		(end 246.51081 -108.600748)
		(width 0.127)
		(layer "In11.Cu")
		(net "RST_RTCRST_N")
	)
	(segment
		(start 313.61888 -95.672148)
		(end 313.08548 -95.138748)
		(width 0.127)
		(layer "In11.Cu")
		(net "RST_RTCRST_N")
	)
	(segment
		(start 221.74708 -101.7651)
		(end 220.218 -101.7651)
		(width 0.127)
		(layer "In11.Cu")
		(net "RST_RTCRST_N")
	)
	(segment
		(start 355.87178 -47.864268)
		(end 369.85956 -47.864268)
		(width 0.127)
		(layer "In15.Cu")
		(net "RST_RTCRST_N")
	)
	(segment
		(start 329.59167 -37.039296)
		(end 329.162918 -37.468048)
		(width 0.127)
		(layer "In15.Cu")
		(net "RST_RTCRST_N")
	)
	(segment
		(start 309.008018 -35.223704)
		(end 307.211476 -37.020246)
		(width 0.127)
		(layer "In15.Cu")
		(net "RST_RTCRST_N")
	)
	(segment
		(start 329.59167 -37.039296)
		(end 330.445618 -36.185348)
		(width 0.127)
		(layer "In15.Cu")
		(net "RST_RTCRST_N")
	)
	(segment
		(start 343.98712 -35.070288)
		(end 344.51798 -35.601148)
		(width 0.127)
		(layer "In15.Cu")
		(net "RST_RTCRST_N")
	)
	(segment
		(start 312.073036 -35.223704)
		(end 309.008018 -35.223704)
		(width 0.127)
		(layer "In15.Cu")
		(net "RST_RTCRST_N")
	)
	(segment
		(start 349.44812 -37.686488)
		(end 349.44812 -41.440608)
		(width 0.127)
		(layer "In15.Cu")
		(net "RST_RTCRST_N")
	)
	(segment
		(start 326.68718 -37.468048)
		(end 326.42048 -37.201348)
		(width 0.127)
		(layer "In15.Cu")
		(net "RST_RTCRST_N")
	)
	(segment
		(start 374.83288 -42.890948)
		(end 390.196324 -42.890948)
		(width 0.127)
		(layer "In15.Cu")
		(net "RST_RTCRST_N")
	)
	(segment
		(start 348.3229 -36.561268)
		(end 349.44812 -37.686488)
		(width 0.127)
		(layer "In15.Cu")
		(net "RST_RTCRST_N")
	)
	(segment
		(start 302.052228 -37.020246)
		(end 301.602902 -36.57092)
		(width 0.127)
		(layer "In15.Cu")
		(net "RST_RTCRST_N")
	)
	(segment
		(start 329.162918 -37.468048)
		(end 326.68718 -37.468048)
		(width 0.127)
		(layer "In15.Cu")
		(net "RST_RTCRST_N")
	)
	(segment
		(start 344.51798 -35.601148)
		(end 346.004896 -35.601148)
		(width 0.127)
		(layer "In15.Cu")
		(net "RST_RTCRST_N")
	)
	(segment
		(start 346.004896 -35.601148)
		(end 348.3229 -36.561268)
		(width 0.127)
		(layer "In15.Cu")
		(net "RST_RTCRST_N")
	)
	(segment
		(start 332.25994 -35.070288)
		(end 343.98712 -35.070288)
		(width 0.127)
		(layer "In15.Cu")
		(net "RST_RTCRST_N")
	)
	(segment
		(start 312.39968 -35.550348)
		(end 312.073036 -35.223704)
		(width 0.127)
		(layer "In15.Cu")
		(net "RST_RTCRST_N")
	)
	(segment
		(start 326.42048 -37.201348)
		(end 324.76948 -37.201348)
		(width 0.127)
		(layer "In15.Cu")
		(net "RST_RTCRST_N")
	)
	(segment
		(start 330.445618 -36.185348)
		(end 331.14488 -36.185348)
		(width 0.127)
		(layer "In15.Cu")
		(net "RST_RTCRST_N")
	)
	(segment
		(start 301.602902 -36.57092)
		(end 301.602902 -36.355528)
		(width 0.127)
		(layer "In15.Cu")
		(net "RST_RTCRST_N")
	)
	(segment
		(start 324.76948 -37.201348)
		(end 323.11848 -35.550348)
		(width 0.127)
		(layer "In15.Cu")
		(net "RST_RTCRST_N")
	)
	(segment
		(start 369.85956 -47.864268)
		(end 374.83288 -42.890948)
		(width 0.127)
		(layer "In15.Cu")
		(net "RST_RTCRST_N")
	)
	(segment
		(start 349.44812 -41.440608)
		(end 355.87178 -47.864268)
		(width 0.127)
		(layer "In15.Cu")
		(net "RST_RTCRST_N")
	)
	(segment
		(start 323.11848 -35.550348)
		(end 312.39968 -35.550348)
		(width 0.127)
		(layer "In15.Cu")
		(net "RST_RTCRST_N")
	)
	(segment
		(start 331.14488 -36.185348)
		(end 332.25994 -35.070288)
		(width 0.127)
		(layer "In15.Cu")
		(net "RST_RTCRST_N")
	)
	(segment
		(start 390.196324 -42.890948)
		(end 392.623802 -40.46347)
		(width 0.127)
		(layer "In15.Cu")
		(net "RST_RTCRST_N")
	)
	(segment
		(start 307.211476 -37.020246)
		(end 302.052228 -37.020246)
		(width 0.127)
		(layer "In15.Cu")
		(net "RST_RTCRST_N")
	)
	(segment
		(start 9.18083 -52.923948)
		(end 8.55218 -52.923948)
		(width 0.12954)
		(layer "F.Cu")
		(net "RST_RSMRST_PLD_R_N")
	)
	(segment
		(start 106.236516 -102.943152)
		(end 107.056428 -102.943152)
		(width 0.12954)
		(layer "F.Cu")
		(net "RST_RSMRST_PLD_R_N")
	)
	(segment
		(start 325.61276 -22.275038)
		(end 324.96506 -22.275038)
		(width 0.12954)
		(layer "F.Cu")
		(net "RST_RSMRST_PLD_R_N")
	)
	(segment
		(start 196.79031 -119.344948)
		(end 196.18071 -119.344948)
		(width 0.12954)
		(layer "F.Cu")
		(net "RST_RSMRST_PLD_R_N")
	)
	(segment
		(start 183.755538 -116.975382)
		(end 184.155588 -117.375432)
		(width 0.12954)
		(layer "F.Cu")
		(net "RST_RSMRST_PLD_R_N")
	)
	(segment
		(start 105.794556 -103.385112)
		(end 106.236516 -102.943152)
		(width 0.12954)
		(layer "F.Cu")
		(net "RST_RSMRST_PLD_R_N")
	)
	(via
		(at 184.155588 -117.375432)
		(size 0.4572)
		(drill 0.254)
		(layers "F.Cu" "B.Cu")
		(net "RST_RSMRST_PLD_R_N")
	)
	(via
		(at 326.19188 -117.693948)
		(size 0.508)
		(drill 0.254)
		(layers "F.Cu" "B.Cu")
		(net "RST_RSMRST_PLD_R_N")
	)
	(via
		(at 105.794556 -103.385112)
		(size 0.508)
		(drill 0.254)
		(layers "F.Cu" "B.Cu")
		(net "RST_RSMRST_PLD_R_N")
	)
	(via
		(at 324.96506 -22.275038)
		(size 0.508)
		(drill 0.254)
		(layers "F.Cu" "B.Cu")
		(net "RST_RSMRST_PLD_R_N")
	)
	(via
		(at 196.18071 -119.344948)
		(size 0.508)
		(drill 0.254)
		(layers "F.Cu" "B.Cu")
		(net "RST_RSMRST_PLD_R_N")
	)
	(via
		(at 8.55218 -52.923948)
		(size 0.508)
		(drill 0.254)
		(layers "F.Cu" "B.Cu")
		(net "RST_RSMRST_PLD_R_N")
	)
	(segment
		(start 327.1139 -58.433208)
		(end 327.1139 -38.357048)
		(width 0.127)
		(layer "In2.Cu")
		(net "RST_RSMRST_PLD_R_N")
	)
	(segment
		(start 326.7456 -24.055578)
		(end 324.96506 -22.275038)
		(width 0.127)
		(layer "In2.Cu")
		(net "RST_RSMRST_PLD_R_N")
	)
	(segment
		(start 329.5142 -35.956748)
		(end 329.5142 -30.190948)
		(width 0.127)
		(layer "In2.Cu")
		(net "RST_RSMRST_PLD_R_N")
	)
	(segment
		(start 326.67194 -73.020428)
		(end 327.4187 -72.273668)
		(width 0.127)
		(layer "In2.Cu")
		(net "RST_RSMRST_PLD_R_N")
	)
	(segment
		(start 326.19188 -117.693948)
		(end 326.67194 -117.213888)
		(width 0.127)
		(layer "In2.Cu")
		(net "RST_RSMRST_PLD_R_N")
	)
	(segment
		(start 326.7456 -27.422348)
		(end 326.7456 -24.055578)
		(width 0.127)
		(layer "In2.Cu")
		(net "RST_RSMRST_PLD_R_N")
	)
	(segment
		(start 326.67194 -117.213888)
		(end 326.67194 -73.020428)
		(width 0.127)
		(layer "In2.Cu")
		(net "RST_RSMRST_PLD_R_N")
	)
	(segment
		(start 327.4187 -72.273668)
		(end 327.4187 -63.343028)
		(width 0.127)
		(layer "In2.Cu")
		(net "RST_RSMRST_PLD_R_N")
	)
	(segment
		(start 327.1139 -38.357048)
		(end 329.5142 -35.956748)
		(width 0.127)
		(layer "In2.Cu")
		(net "RST_RSMRST_PLD_R_N")
	)
	(segment
		(start 326.26046 -59.286648)
		(end 327.1139 -58.433208)
		(width 0.127)
		(layer "In2.Cu")
		(net "RST_RSMRST_PLD_R_N")
	)
	(segment
		(start 327.4187 -63.343028)
		(end 326.26046 -62.184788)
		(width 0.127)
		(layer "In2.Cu")
		(net "RST_RSMRST_PLD_R_N")
	)
	(segment
		(start 326.26046 -62.184788)
		(end 326.26046 -59.286648)
		(width 0.127)
		(layer "In2.Cu")
		(net "RST_RSMRST_PLD_R_N")
	)
	(segment
		(start 329.5142 -30.190948)
		(end 326.7456 -27.422348)
		(width 0.127)
		(layer "In2.Cu")
		(net "RST_RSMRST_PLD_R_N")
	)
	(segment
		(start 222.57512 -114.559588)
		(end 232.91038 -114.559588)
		(width 0.127)
		(layer "In15.Cu")
		(net "RST_RSMRST_PLD_R_N")
	)
	(segment
		(start 174.35322 -103.190548)
		(end 174.76978 -103.607108)
		(width 0.127)
		(layer "In15.Cu")
		(net "RST_RSMRST_PLD_R_N")
	)
	(segment
		(start 209.1944 -119.761)
		(end 212.484208 -119.761)
		(width 0.127)
		(layer "In15.Cu")
		(net "RST_RSMRST_PLD_R_N")
	)
	(segment
		(start 52.02682 -75.357228)
		(end 52.02682 -63.764668)
		(width 0.127)
		(layer "In15.Cu")
		(net "RST_RSMRST_PLD_R_N")
	)
	(segment
		(start 248.96826 -120.297448)
		(end 268.717776 -120.297448)
		(width 0.127)
		(layer "In15.Cu")
		(net "RST_RSMRST_PLD_R_N")
	)
	(segment
		(start 221.488 -115.646708)
		(end 222.57512 -114.559588)
		(width 0.127)
		(layer "In15.Cu")
		(net "RST_RSMRST_PLD_R_N")
	)
	(segment
		(start 104.15778 -105.021888)
		(end 102.72268 -105.021888)
		(width 0.127)
		(layer "In15.Cu")
		(net "RST_RSMRST_PLD_R_N")
	)
	(segment
		(start 192.7352 -119.634)
		(end 193.378328 -120.277128)
		(width 0.127)
		(layer "In15.Cu")
		(net "RST_RSMRST_PLD_R_N")
	)
	(segment
		(start 179.13604 -113.187988)
		(end 181.32552 -113.187988)
		(width 0.127)
		(layer "In15.Cu")
		(net "RST_RSMRST_PLD_R_N")
	)
	(segment
		(start 283.959808 -117.795548)
		(end 322.834 -117.795548)
		(width 0.127)
		(layer "In15.Cu")
		(net "RST_RSMRST_PLD_R_N")
	)
	(segment
		(start 47.8663 -59.604148)
		(end 27.7114 -59.604148)
		(width 0.127)
		(layer "In15.Cu")
		(net "RST_RSMRST_PLD_R_N")
	)
	(segment
		(start 212.484208 -119.761)
		(end 216.5985 -115.646708)
		(width 0.127)
		(layer "In15.Cu")
		(net "RST_RSMRST_PLD_R_N")
	)
	(segment
		(start 110.4138 -101.115368)
		(end 112.99825 -98.530918)
		(width 0.127)
		(layer "In15.Cu")
		(net "RST_RSMRST_PLD_R_N")
	)
	(segment
		(start 184.155588 -117.375432)
		(end 184.55894 -116.97208)
		(width 0.127)
		(layer "In15.Cu")
		(net "RST_RSMRST_PLD_R_N")
	)
	(segment
		(start 182.1561 -114.018568)
		(end 182.1561 -114.399568)
		(width 0.127)
		(layer "In15.Cu")
		(net "RST_RSMRST_PLD_R_N")
	)
	(segment
		(start 27.7114 -59.604148)
		(end 21.0312 -52.923948)
		(width 0.127)
		(layer "In15.Cu")
		(net "RST_RSMRST_PLD_R_N")
	)
	(segment
		(start 196.18071 -119.344948)
		(end 196.89953 -120.063768)
		(width 0.127)
		(layer "In15.Cu")
		(net "RST_RSMRST_PLD_R_N")
	)
	(segment
		(start 176.7078 -109.768386)
		(end 178.178206 -109.768386)
		(width 0.127)
		(layer "In15.Cu")
		(net "RST_RSMRST_PLD_R_N")
	)
	(segment
		(start 195.24345 -120.282208)
		(end 196.18071 -119.344948)
		(width 0.127)
		(layer "In15.Cu")
		(net "RST_RSMRST_PLD_R_N")
	)
	(segment
		(start 175.762666 -105.082594)
		(end 175.762666 -107.138216)
		(width 0.127)
		(layer "In15.Cu")
		(net "RST_RSMRST_PLD_R_N")
	)
	(segment
		(start 183.515 -114.569748)
		(end 183.75122 -114.805968)
		(width 0.127)
		(layer "In15.Cu")
		(net "RST_RSMRST_PLD_R_N")
	)
	(segment
		(start 233.9975 -115.646708)
		(end 235.54182 -115.646708)
		(width 0.127)
		(layer "In15.Cu")
		(net "RST_RSMRST_PLD_R_N")
	)
	(segment
		(start 325.68388 -117.185948)
		(end 326.19188 -117.693948)
		(width 0.127)
		(layer "In15.Cu")
		(net "RST_RSMRST_PLD_R_N")
	)
	(segment
		(start 175.762666 -107.138216)
		(end 175.99279 -107.36834)
		(width 0.127)
		(layer "In15.Cu")
		(net "RST_RSMRST_PLD_R_N")
	)
	(segment
		(start 247.05818 -118.387368)
		(end 248.96826 -120.297448)
		(width 0.127)
		(layer "In15.Cu")
		(net "RST_RSMRST_PLD_R_N")
	)
	(segment
		(start 105.794556 -103.385112)
		(end 104.15778 -105.021888)
		(width 0.127)
		(layer "In15.Cu")
		(net "RST_RSMRST_PLD_R_N")
	)
	(segment
		(start 187.91428 -116.169948)
		(end 188.17844 -116.434108)
		(width 0.127)
		(layer "In15.Cu")
		(net "RST_RSMRST_PLD_R_N")
	)
	(segment
		(start 238.28248 -118.387368)
		(end 247.05818 -118.387368)
		(width 0.127)
		(layer "In15.Cu")
		(net "RST_RSMRST_PLD_R_N")
	)
	(segment
		(start 163.7538 -101.361748)
		(end 165.3032 -102.911148)
		(width 0.127)
		(layer "In15.Cu")
		(net "RST_RSMRST_PLD_R_N")
	)
	(segment
		(start 178.74742 -110.3376)
		(end 178.74742 -112.799368)
		(width 0.127)
		(layer "In15.Cu")
		(net "RST_RSMRST_PLD_R_N")
	)
	(segment
		(start 183.75122 -114.805968)
		(end 183.75122 -116.764308)
		(width 0.127)
		(layer "In15.Cu")
		(net "RST_RSMRST_PLD_R_N")
	)
	(segment
		(start 65.15354 -88.483948)
		(end 52.02682 -75.357228)
		(width 0.127)
		(layer "In15.Cu")
		(net "RST_RSMRST_PLD_R_N")
	)
	(segment
		(start 176.304194 -107.36834)
		(end 176.5554 -107.619546)
		(width 0.127)
		(layer "In15.Cu")
		(net "RST_RSMRST_PLD_R_N")
	)
	(segment
		(start 235.54182 -115.646708)
		(end 238.28248 -118.387368)
		(width 0.127)
		(layer "In15.Cu")
		(net "RST_RSMRST_PLD_R_N")
	)
	(segment
		(start 96.93148 -91.153488)
		(end 94.26194 -88.483948)
		(width 0.127)
		(layer "In15.Cu")
		(net "RST_RSMRST_PLD_R_N")
	)
	(segment
		(start 108.0643 -101.115368)
		(end 110.4138 -101.115368)
		(width 0.127)
		(layer "In15.Cu")
		(net "RST_RSMRST_PLD_R_N")
	)
	(segment
		(start 184.55894 -116.332508)
		(end 184.7215 -116.169948)
		(width 0.127)
		(layer "In15.Cu")
		(net "RST_RSMRST_PLD_R_N")
	)
	(segment
		(start 176.5554 -109.615986)
		(end 176.7078 -109.768386)
		(width 0.127)
		(layer "In15.Cu")
		(net "RST_RSMRST_PLD_R_N")
	)
	(segment
		(start 196.89953 -120.063768)
		(end 206.021178 -120.063768)
		(width 0.127)
		(layer "In15.Cu")
		(net "RST_RSMRST_PLD_R_N")
	)
	(segment
		(start 174.76978 -103.607108)
		(end 174.76978 -104.089708)
		(width 0.127)
		(layer "In15.Cu")
		(net "RST_RSMRST_PLD_R_N")
	)
	(segment
		(start 283.147008 -118.608348)
		(end 283.959808 -117.795548)
		(width 0.127)
		(layer "In15.Cu")
		(net "RST_RSMRST_PLD_R_N")
	)
	(segment
		(start 184.55894 -116.97208)
		(end 184.55894 -116.332508)
		(width 0.127)
		(layer "In15.Cu")
		(net "RST_RSMRST_PLD_R_N")
	)
	(segment
		(start 96.93148 -99.230688)
		(end 96.93148 -91.153488)
		(width 0.127)
		(layer "In15.Cu")
		(net "RST_RSMRST_PLD_R_N")
	)
	(segment
		(start 206.021178 -120.063768)
		(end 206.984346 -119.1006)
		(width 0.127)
		(layer "In15.Cu")
		(net "RST_RSMRST_PLD_R_N")
	)
	(segment
		(start 166.5732 -103.190548)
		(end 174.35322 -103.190548)
		(width 0.127)
		(layer "In15.Cu")
		(net "RST_RSMRST_PLD_R_N")
	)
	(segment
		(start 112.99825 -98.530918)
		(end 120.19915 -98.530918)
		(width 0.127)
		(layer "In15.Cu")
		(net "RST_RSMRST_PLD_R_N")
	)
	(segment
		(start 206.984346 -119.1006)
		(end 208.534 -119.1006)
		(width 0.127)
		(layer "In15.Cu")
		(net "RST_RSMRST_PLD_R_N")
	)
	(segment
		(start 322.834 -117.795548)
		(end 323.4436 -117.185948)
		(width 0.127)
		(layer "In15.Cu")
		(net "RST_RSMRST_PLD_R_N")
	)
	(segment
		(start 120.66016 -98.069908)
		(end 143.55699 -98.069908)
		(width 0.127)
		(layer "In15.Cu")
		(net "RST_RSMRST_PLD_R_N")
	)
	(segment
		(start 216.5985 -115.646708)
		(end 221.488 -115.646708)
		(width 0.127)
		(layer "In15.Cu")
		(net "RST_RSMRST_PLD_R_N")
	)
	(segment
		(start 181.32552 -113.187988)
		(end 182.1561 -114.018568)
		(width 0.127)
		(layer "In15.Cu")
		(net "RST_RSMRST_PLD_R_N")
	)
	(segment
		(start 270.406876 -118.608348)
		(end 283.147008 -118.608348)
		(width 0.127)
		(layer "In15.Cu")
		(net "RST_RSMRST_PLD_R_N")
	)
	(segment
		(start 178.74742 -112.799368)
		(end 179.13604 -113.187988)
		(width 0.127)
		(layer "In15.Cu")
		(net "RST_RSMRST_PLD_R_N")
	)
	(segment
		(start 232.91038 -114.559588)
		(end 233.9975 -115.646708)
		(width 0.127)
		(layer "In15.Cu")
		(net "RST_RSMRST_PLD_R_N")
	)
	(segment
		(start 105.794556 -103.385112)
		(end 108.0643 -101.115368)
		(width 0.127)
		(layer "In15.Cu")
		(net "RST_RSMRST_PLD_R_N")
	)
	(segment
		(start 323.4436 -117.185948)
		(end 325.68388 -117.185948)
		(width 0.127)
		(layer "In15.Cu")
		(net "RST_RSMRST_PLD_R_N")
	)
	(segment
		(start 194.120008 -120.282208)
		(end 195.24345 -120.282208)
		(width 0.127)
		(layer "In15.Cu")
		(net "RST_RSMRST_PLD_R_N")
	)
	(segment
		(start 21.0312 -52.923948)
		(end 8.55218 -52.923948)
		(width 0.127)
		(layer "In15.Cu")
		(net "RST_RSMRST_PLD_R_N")
	)
	(segment
		(start 192.137792 -119.634)
		(end 192.7352 -119.634)
		(width 0.127)
		(layer "In15.Cu")
		(net "RST_RSMRST_PLD_R_N")
	)
	(segment
		(start 188.17844 -116.434108)
		(end 188.9379 -116.434108)
		(width 0.127)
		(layer "In15.Cu")
		(net "RST_RSMRST_PLD_R_N")
	)
	(segment
		(start 143.55699 -98.069908)
		(end 146.84883 -101.361748)
		(width 0.127)
		(layer "In15.Cu")
		(net "RST_RSMRST_PLD_R_N")
	)
	(segment
		(start 176.5554 -107.619546)
		(end 176.5554 -109.615986)
		(width 0.127)
		(layer "In15.Cu")
		(net "RST_RSMRST_PLD_R_N")
	)
	(segment
		(start 183.75122 -116.764308)
		(end 184.155588 -117.168676)
		(width 0.127)
		(layer "In15.Cu")
		(net "RST_RSMRST_PLD_R_N")
	)
	(segment
		(start 120.19915 -98.530918)
		(end 120.66016 -98.069908)
		(width 0.127)
		(layer "In15.Cu")
		(net "RST_RSMRST_PLD_R_N")
	)
	(segment
		(start 182.32628 -114.569748)
		(end 183.515 -114.569748)
		(width 0.127)
		(layer "In15.Cu")
		(net "RST_RSMRST_PLD_R_N")
	)
	(segment
		(start 166.2938 -102.911148)
		(end 166.5732 -103.190548)
		(width 0.127)
		(layer "In15.Cu")
		(net "RST_RSMRST_PLD_R_N")
	)
	(segment
		(start 178.178206 -109.768386)
		(end 178.74742 -110.3376)
		(width 0.127)
		(layer "In15.Cu")
		(net "RST_RSMRST_PLD_R_N")
	)
	(segment
		(start 165.3032 -102.911148)
		(end 166.2938 -102.911148)
		(width 0.127)
		(layer "In15.Cu")
		(net "RST_RSMRST_PLD_R_N")
	)
	(segment
		(start 188.9379 -116.434108)
		(end 192.137792 -119.634)
		(width 0.127)
		(layer "In15.Cu")
		(net "RST_RSMRST_PLD_R_N")
	)
	(segment
		(start 146.84883 -101.361748)
		(end 163.7538 -101.361748)
		(width 0.127)
		(layer "In15.Cu")
		(net "RST_RSMRST_PLD_R_N")
	)
	(segment
		(start 208.534 -119.1006)
		(end 209.1944 -119.761)
		(width 0.127)
		(layer "In15.Cu")
		(net "RST_RSMRST_PLD_R_N")
	)
	(segment
		(start 184.7215 -116.169948)
		(end 187.91428 -116.169948)
		(width 0.127)
		(layer "In15.Cu")
		(net "RST_RSMRST_PLD_R_N")
	)
	(segment
		(start 174.76978 -104.089708)
		(end 175.762666 -105.082594)
		(width 0.127)
		(layer "In15.Cu")
		(net "RST_RSMRST_PLD_R_N")
	)
	(segment
		(start 194.114928 -120.277128)
		(end 194.120008 -120.282208)
		(width 0.127)
		(layer "In15.Cu")
		(net "RST_RSMRST_PLD_R_N")
	)
	(segment
		(start 268.717776 -120.297448)
		(end 270.406876 -118.608348)
		(width 0.127)
		(layer "In15.Cu")
		(net "RST_RSMRST_PLD_R_N")
	)
	(segment
		(start 184.155588 -117.168676)
		(end 184.155588 -117.375432)
		(width 0.127)
		(layer "In15.Cu")
		(net "RST_RSMRST_PLD_R_N")
	)
	(segment
		(start 193.378328 -120.277128)
		(end 194.114928 -120.277128)
		(width 0.127)
		(layer "In15.Cu")
		(net "RST_RSMRST_PLD_R_N")
	)
	(segment
		(start 52.02682 -63.764668)
		(end 47.8663 -59.604148)
		(width 0.127)
		(layer "In15.Cu")
		(net "RST_RSMRST_PLD_R_N")
	)
	(segment
		(start 182.1561 -114.399568)
		(end 182.32628 -114.569748)
		(width 0.127)
		(layer "In15.Cu")
		(net "RST_RSMRST_PLD_R_N")
	)
	(segment
		(start 175.99279 -107.36834)
		(end 176.304194 -107.36834)
		(width 0.127)
		(layer "In15.Cu")
		(net "RST_RSMRST_PLD_R_N")
	)
	(segment
		(start 94.26194 -88.483948)
		(end 65.15354 -88.483948)
		(width 0.127)
		(layer "In15.Cu")
		(net "RST_RSMRST_PLD_R_N")
	)
	(segment
		(start 102.72268 -105.021888)
		(end 96.93148 -99.230688)
		(width 0.127)
		(layer "In15.Cu")
		(net "RST_RSMRST_PLD_R_N")
	)
	(segment
		(start 396.06474 -45.496988)
		(end 390.0043 -39.436548)
		(width 0.12954)
		(layer "F.Cu")
		(net "RST_RSMRST_PCH_N")
	)
	(segment
		(start 330.766928 -38.090602)
		(end 330.766928 -38.015418)
		(width 0.0889)
		(layer "F.Cu")
		(net "RST_RSMRST_PCH_N")
	)
	(segment
		(start 329.226672 -33.207198)
		(end 329.226672 -32.869632)
		(width 0.0889)
		(layer "F.Cu")
		(net "RST_RSMRST_PCH_N")
	)
	(segment
		(start 328.725022 -32.36722)
		(end 328.725022 -31.753048)
		(width 0.12954)
		(layer "F.Cu")
		(net "RST_RSMRST_PCH_N")
	)
	(segment
		(start 330.396596 -38.880288)
		(end 330.396596 -38.518084)
		(width 0.0889)
		(layer "F.Cu")
		(net "RST_RSMRST_PCH_N")
	)
	(segment
		(start 326.444356 -27.309318)
		(end 326.070976 -26.935938)
		(width 0.12954)
		(layer "F.Cu")
		(net "RST_RSMRST_PCH_N")
	)
	(segment
		(start 330.61656 -37.789358)
		(end 330.61656 -36.239958)
		(width 0.0889)
		(layer "F.Cu")
		(net "RST_RSMRST_PCH_N")
	)
	(segment
		(start 328.001122 -30.993588)
		(end 327.727056 -30.719776)
		(width 0.12954)
		(layer "F.Cu")
		(net "RST_RSMRST_PCH_N")
	)
	(segment
		(start 405.436832 -45.496988)
		(end 396.06474 -45.496988)
		(width 0.12954)
		(layer "F.Cu")
		(net "RST_RSMRST_PCH_N")
	)
	(segment
		(start 330.177394 -35.800792)
		(end 330.177394 -34.15792)
		(width 0.0889)
		(layer "F.Cu")
		(net "RST_RSMRST_PCH_N")
	)
	(segment
		(start 328.725022 -31.753048)
		(end 328.001122 -31.029148)
		(width 0.12954)
		(layer "F.Cu")
		(net "RST_RSMRST_PCH_N")
	)
	(segment
		(start 330.766928 -38.015418)
		(end 330.61656 -37.789358)
		(width 0.0889)
		(layer "F.Cu")
		(net "RST_RSMRST_PCH_N")
	)
	(segment
		(start 408.014424 -48.07458)
		(end 405.436832 -45.496988)
		(width 0.12954)
		(layer "F.Cu")
		(net "RST_RSMRST_PCH_N")
	)
	(segment
		(start 210.14563 -127.528828)
		(end 210.75523 -127.528828)
		(width 0.12954)
		(layer "F.Cu")
		(net "RST_RSMRST_PCH_N")
	)
	(segment
		(start 327.727056 -30.719776)
		(end 326.444356 -28.319984)
		(width 0.12954)
		(layer "F.Cu")
		(net "RST_RSMRST_PCH_N")
	)
	(segment
		(start 330.177394 -34.15792)
		(end 329.226672 -33.207198)
		(width 0.0889)
		(layer "F.Cu")
		(net "RST_RSMRST_PCH_N")
	)
	(segment
		(start 326.444356 -28.319984)
		(end 326.444356 -27.309318)
		(width 0.12954)
		(layer "F.Cu")
		(net "RST_RSMRST_PCH_N")
	)
	(segment
		(start 325.61276 -23.424388)
		(end 325.61276 -23.075138)
		(width 0.12954)
		(layer "F.Cu")
		(net "RST_RSMRST_PCH_N")
	)
	(segment
		(start 329.226672 -32.869632)
		(end 329.017122 -32.659828)
		(width 0.0889)
		(layer "F.Cu")
		(net "RST_RSMRST_PCH_N")
	)
	(segment
		(start 330.736702 -38.151562)
		(end 330.766928 -38.090602)
		(width 0.0889)
		(layer "F.Cu")
		(net "RST_RSMRST_PCH_N")
	)
	(segment
		(start 326.070976 -26.935938)
		(end 326.070976 -23.882604)
		(width 0.12954)
		(layer "F.Cu")
		(net "RST_RSMRST_PCH_N")
	)
	(segment
		(start 408.014424 -51.848004)
		(end 408.014424 -48.07458)
		(width 0.12954)
		(layer "F.Cu")
		(net "RST_RSMRST_PCH_N")
	)
	(segment
		(start 325.61276 -23.075138)
		(end 324.97141 -23.075138)
		(width 0.12954)
		(layer "F.Cu")
		(net "RST_RSMRST_PCH_N")
	)
	(segment
		(start 326.070976 -23.882604)
		(end 325.61276 -23.424388)
		(width 0.12954)
		(layer "F.Cu")
		(net "RST_RSMRST_PCH_N")
	)
	(segment
		(start 407.30932 -52.553108)
		(end 408.014424 -51.848004)
		(width 0.12954)
		(layer "F.Cu")
		(net "RST_RSMRST_PCH_N")
	)
	(segment
		(start 328.001122 -31.029148)
		(end 328.001122 -30.993588)
		(width 0.12954)
		(layer "F.Cu")
		(net "RST_RSMRST_PCH_N")
	)
	(segment
		(start 329.017122 -32.659828)
		(end 328.725022 -32.36722)
		(width 0.12954)
		(layer "F.Cu")
		(net "RST_RSMRST_PCH_N")
	)
	(segment
		(start 330.396596 -38.518084)
		(end 330.569062 -38.345618)
		(width 0.0889)
		(layer "F.Cu")
		(net "RST_RSMRST_PCH_N")
	)
	(segment
		(start 330.61656 -36.239958)
		(end 330.177394 -35.800792)
		(width 0.0889)
		(layer "F.Cu")
		(net "RST_RSMRST_PCH_N")
	)
	(segment
		(start 330.569062 -38.345618)
		(end 330.736702 -38.151562)
		(width 0.0889)
		(layer "F.Cu")
		(net "RST_RSMRST_PCH_N")
	)
	(via
		(at 390.0043 -39.436548)
		(size 0.508)
		(drill 0.254)
		(layers "F.Cu" "B.Cu")
		(net "RST_RSMRST_PCH_N")
	)
	(via
		(at 324.97141 -23.075138)
		(size 0.508)
		(drill 0.254)
		(layers "F.Cu" "B.Cu")
		(net "RST_RSMRST_PCH_N")
	)
	(via
		(at 204.70114 -90.173048)
		(size 0.508)
		(drill 0.254)
		(layers "F.Cu" "B.Cu")
		(net "RST_RSMRST_PCH_N")
	)
	(via
		(at 210.75523 -127.528828)
		(size 0.508)
		(drill 0.254)
		(layers "F.Cu" "B.Cu")
		(net "RST_RSMRST_PCH_N")
	)
	(via
		(at 407.30932 -52.553108)
		(size 0.508)
		(drill 0.254)
		(layers "F.Cu" "B.Cu")
		(net "RST_RSMRST_PCH_N")
	)
	(segment
		(start 407.14041 -52.722018)
		(end 404.406862 -52.722018)
		(width 0.12954)
		(layer "B.Cu")
		(net "RST_RSMRST_PCH_N")
	)
	(segment
		(start 407.30932 -52.553108)
		(end 407.14041 -52.722018)
		(width 0.12954)
		(layer "B.Cu")
		(net "RST_RSMRST_PCH_N")
	)
	(segment
		(start 328.992484 -22.540214)
		(end 327.687432 -21.235162)
		(width 0.127)
		(layer "In2.Cu")
		(net "RST_RSMRST_PCH_N")
	)
	(segment
		(start 323.84111 -23.735538)
		(end 324.31101 -23.735538)
		(width 0.127)
		(layer "In2.Cu")
		(net "RST_RSMRST_PCH_N")
	)
	(segment
		(start 342.051132 -18.70202)
		(end 338.212938 -22.540214)
		(width 0.127)
		(layer "In2.Cu")
		(net "RST_RSMRST_PCH_N")
	)
	(segment
		(start 390.0043 -39.436548)
		(end 377.470924 -39.436548)
		(width 0.127)
		(layer "In2.Cu")
		(net "RST_RSMRST_PCH_N")
	)
	(segment
		(start 377.470924 -39.436548)
		(end 361.364784 -23.330408)
		(width 0.127)
		(layer "In2.Cu")
		(net "RST_RSMRST_PCH_N")
	)
	(segment
		(start 324.31101 -23.735538)
		(end 324.97141 -23.075138)
		(width 0.127)
		(layer "In2.Cu")
		(net "RST_RSMRST_PCH_N")
	)
	(segment
		(start 361.364784 -23.330408)
		(end 349.762572 -23.330408)
		(width 0.127)
		(layer "In2.Cu")
		(net "RST_RSMRST_PCH_N")
	)
	(segment
		(start 323.17436 -22.187154)
		(end 323.17436 -23.068788)
		(width 0.127)
		(layer "In2.Cu")
		(net "RST_RSMRST_PCH_N")
	)
	(segment
		(start 349.762572 -23.330408)
		(end 345.134184 -18.70202)
		(width 0.127)
		(layer "In2.Cu")
		(net "RST_RSMRST_PCH_N")
	)
	(segment
		(start 327.687432 -21.235162)
		(end 324.126352 -21.235162)
		(width 0.127)
		(layer "In2.Cu")
		(net "RST_RSMRST_PCH_N")
	)
	(segment
		(start 345.134184 -18.70202)
		(end 342.051132 -18.70202)
		(width 0.127)
		(layer "In2.Cu")
		(net "RST_RSMRST_PCH_N")
	)
	(segment
		(start 324.126352 -21.235162)
		(end 323.17436 -22.187154)
		(width 0.127)
		(layer "In2.Cu")
		(net "RST_RSMRST_PCH_N")
	)
	(segment
		(start 323.17436 -23.068788)
		(end 323.84111 -23.735538)
		(width 0.127)
		(layer "In2.Cu")
		(net "RST_RSMRST_PCH_N")
	)
	(segment
		(start 338.212938 -22.540214)
		(end 328.992484 -22.540214)
		(width 0.127)
		(layer "In2.Cu")
		(net "RST_RSMRST_PCH_N")
	)
	(segment
		(start 202.37958 -104.13619)
		(end 206.6036 -108.36021)
		(width 0.127)
		(layer "In4.Cu")
		(net "RST_RSMRST_PCH_N")
	)
	(segment
		(start 206.6036 -108.36021)
		(end 206.6036 -111.99241)
		(width 0.127)
		(layer "In4.Cu")
		(net "RST_RSMRST_PCH_N")
	)
	(segment
		(start 206.6036 -111.99241)
		(end 209.217768 -114.606578)
		(width 0.127)
		(layer "In4.Cu")
		(net "RST_RSMRST_PCH_N")
	)
	(segment
		(start 204.2414 -91.3384)
		(end 204.2414 -101.43109)
		(width 0.127)
		(layer "In4.Cu")
		(net "RST_RSMRST_PCH_N")
	)
	(segment
		(start 204.70114 -90.173048)
		(end 204.70114 -90.87866)
		(width 0.127)
		(layer "In4.Cu")
		(net "RST_RSMRST_PCH_N")
	)
	(segment
		(start 210.7946 -127.528828)
		(end 210.75523 -127.528828)
		(width 0.127)
		(layer "In4.Cu")
		(net "RST_RSMRST_PCH_N")
	)
	(segment
		(start 212.01634 -126.307088)
		(end 210.7946 -127.528828)
		(width 0.127)
		(layer "In4.Cu")
		(net "RST_RSMRST_PCH_N")
	)
	(segment
		(start 204.2414 -101.43109)
		(end 202.37958 -103.29291)
		(width 0.127)
		(layer "In4.Cu")
		(net "RST_RSMRST_PCH_N")
	)
	(segment
		(start 212.01634 -118.745)
		(end 212.01634 -126.307088)
		(width 0.127)
		(layer "In4.Cu")
		(net "RST_RSMRST_PCH_N")
	)
	(segment
		(start 204.70114 -90.87866)
		(end 204.2414 -91.3384)
		(width 0.127)
		(layer "In4.Cu")
		(net "RST_RSMRST_PCH_N")
	)
	(segment
		(start 209.217768 -114.606578)
		(end 209.217768 -115.946428)
		(width 0.127)
		(layer "In4.Cu")
		(net "RST_RSMRST_PCH_N")
	)
	(segment
		(start 202.37958 -103.29291)
		(end 202.37958 -104.13619)
		(width 0.127)
		(layer "In4.Cu")
		(net "RST_RSMRST_PCH_N")
	)
	(segment
		(start 209.217768 -115.946428)
		(end 212.01634 -118.745)
		(width 0.127)
		(layer "In4.Cu")
		(net "RST_RSMRST_PCH_N")
	)
	(segment
		(start 313.767978 -33.18129)
		(end 318.792606 -33.18129)
		(width 0.127)
		(layer "In15.Cu")
		(net "RST_RSMRST_PCH_N")
	)
	(segment
		(start 283.22016 -60.053728)
		(end 293.32174 -49.952148)
		(width 0.127)
		(layer "In15.Cu")
		(net "RST_RSMRST_PCH_N")
	)
	(segment
		(start 326.0979 -23.739348)
		(end 325.43369 -23.075138)
		(width 0.127)
		(layer "In15.Cu")
		(net "RST_RSMRST_PCH_N")
	)
	(segment
		(start 205.2193 -91.3765)
		(end 205.2193 -91.787218)
		(width 0.127)
		(layer "In15.Cu")
		(net "RST_RSMRST_PCH_N")
	)
	(segment
		(start 323.779388 -28.194508)
		(end 324.485 -28.194508)
		(width 0.127)
		(layer "In15.Cu")
		(net "RST_RSMRST_PCH_N")
	)
	(segment
		(start 246.28602 -85.120988)
		(end 274.33524 -85.120988)
		(width 0.127)
		(layer "In15.Cu")
		(net "RST_RSMRST_PCH_N")
	)
	(segment
		(start 318.792606 -33.18129)
		(end 323.779388 -28.194508)
		(width 0.127)
		(layer "In15.Cu")
		(net "RST_RSMRST_PCH_N")
	)
	(segment
		(start 297.54068 -39.494968)
		(end 301.49292 -35.542728)
		(width 0.127)
		(layer "In15.Cu")
		(net "RST_RSMRST_PCH_N")
	)
	(segment
		(start 222.89643 -92.0623)
		(end 239.344708 -92.0623)
		(width 0.127)
		(layer "In15.Cu")
		(net "RST_RSMRST_PCH_N")
	)
	(segment
		(start 204.70114 -90.173048)
		(end 204.70114 -90.85834)
		(width 0.127)
		(layer "In15.Cu")
		(net "RST_RSMRST_PCH_N")
	)
	(segment
		(start 325.43369 -23.075138)
		(end 324.97141 -23.075138)
		(width 0.127)
		(layer "In15.Cu")
		(net "RST_RSMRST_PCH_N")
	)
	(segment
		(start 274.33524 -85.120988)
		(end 283.22016 -76.236068)
		(width 0.127)
		(layer "In15.Cu")
		(net "RST_RSMRST_PCH_N")
	)
	(segment
		(start 204.70114 -90.85834)
		(end 205.2193 -91.3765)
		(width 0.127)
		(layer "In15.Cu")
		(net "RST_RSMRST_PCH_N")
	)
	(segment
		(start 326.0979 -26.581608)
		(end 326.0979 -23.739348)
		(width 0.127)
		(layer "In15.Cu")
		(net "RST_RSMRST_PCH_N")
	)
	(segment
		(start 205.494382 -92.0623)
		(end 210.784694 -92.0623)
		(width 0.127)
		(layer "In15.Cu")
		(net "RST_RSMRST_PCH_N")
	)
	(segment
		(start 222.252032 -91.417902)
		(end 222.89643 -92.0623)
		(width 0.127)
		(layer "In15.Cu")
		(net "RST_RSMRST_PCH_N")
	)
	(segment
		(start 293.32174 -44.514008)
		(end 297.54068 -40.295068)
		(width 0.127)
		(layer "In15.Cu")
		(net "RST_RSMRST_PCH_N")
	)
	(segment
		(start 324.485 -28.194508)
		(end 326.0979 -26.581608)
		(width 0.127)
		(layer "In15.Cu")
		(net "RST_RSMRST_PCH_N")
	)
	(segment
		(start 307.104034 -36.006786)
		(end 308.43982 -34.671)
		(width 0.127)
		(layer "In15.Cu")
		(net "RST_RSMRST_PCH_N")
	)
	(segment
		(start 306.121308 -36.006786)
		(end 307.104034 -36.006786)
		(width 0.127)
		(layer "In15.Cu")
		(net "RST_RSMRST_PCH_N")
	)
	(segment
		(start 305.65725 -35.542728)
		(end 306.121308 -36.006786)
		(width 0.127)
		(layer "In15.Cu")
		(net "RST_RSMRST_PCH_N")
	)
	(segment
		(start 239.344708 -92.0623)
		(end 246.28602 -85.120988)
		(width 0.127)
		(layer "In15.Cu")
		(net "RST_RSMRST_PCH_N")
	)
	(segment
		(start 205.2193 -91.787218)
		(end 205.494382 -92.0623)
		(width 0.127)
		(layer "In15.Cu")
		(net "RST_RSMRST_PCH_N")
	)
	(segment
		(start 211.429092 -91.417902)
		(end 222.252032 -91.417902)
		(width 0.127)
		(layer "In15.Cu")
		(net "RST_RSMRST_PCH_N")
	)
	(segment
		(start 293.32174 -49.952148)
		(end 293.32174 -44.514008)
		(width 0.127)
		(layer "In15.Cu")
		(net "RST_RSMRST_PCH_N")
	)
	(segment
		(start 308.43982 -34.671)
		(end 312.278268 -34.671)
		(width 0.127)
		(layer "In15.Cu")
		(net "RST_RSMRST_PCH_N")
	)
	(segment
		(start 312.278268 -34.671)
		(end 313.767978 -33.18129)
		(width 0.127)
		(layer "In15.Cu")
		(net "RST_RSMRST_PCH_N")
	)
	(segment
		(start 210.784694 -92.0623)
		(end 211.429092 -91.417902)
		(width 0.127)
		(layer "In15.Cu")
		(net "RST_RSMRST_PCH_N")
	)
	(segment
		(start 283.22016 -76.236068)
		(end 283.22016 -60.053728)
		(width 0.127)
		(layer "In15.Cu")
		(net "RST_RSMRST_PCH_N")
	)
	(segment
		(start 301.49292 -35.542728)
		(end 305.65725 -35.542728)
		(width 0.127)
		(layer "In15.Cu")
		(net "RST_RSMRST_PCH_N")
	)
	(segment
		(start 297.54068 -40.295068)
		(end 297.54068 -39.494968)
		(width 0.127)
		(layer "In15.Cu")
		(net "RST_RSMRST_PCH_N")
	)
	(segment
		(start 185.355738 -117.775482)
		(end 185.755788 -118.175532)
		(width 0.12954)
		(layer "F.Cu")
		(net "RST_PLTRST_PLD_N")
	)
	(via
		(at 188.08954 -118.175532)
		(size 0.6604)
		(drill 0.3302)
		(layers "F.Cu" "B.Cu")
		(net "RST_PLTRST_PLD_N")
	)
	(via
		(at 185.755788 -118.175532)
		(size 0.4572)
		(drill 0.254)
		(layers "F.Cu" "B.Cu")
		(net "RST_PLTRST_PLD_N")
	)
	(segment
		(start 188.08954 -118.175532)
		(end 190.528956 -120.614948)
		(width 0.12954)
		(layer "B.Cu")
		(net "RST_PLTRST_PLD_N")
	)
	(segment
		(start 190.528956 -120.614948)
		(end 192.98031 -120.614948)
		(width 0.12954)
		(layer "B.Cu")
		(net "RST_PLTRST_PLD_N")
	)
	(segment
		(start 185.755788 -118.175532)
		(end 188.08954 -118.175532)
		(width 0.12954)
		(layer "B.Cu")
		(net "RST_PLTRST_PLD_N")
	)
	(segment
		(start 196.25691 -118.608348)
		(end 193.223134 -118.608348)
		(width 0.12954)
		(layer "F.Cu")
		(net "RST_PLTRST_PLD_B_N")
	)
	(segment
		(start 200.12025 -118.555008)
		(end 197.27037 -118.555008)
		(width 0.12954)
		(layer "F.Cu")
		(net "RST_PLTRST_PLD_B_N")
	)
	(segment
		(start 192.98031 -118.365524)
		(end 192.98031 -118.074948)
		(width 0.12954)
		(layer "F.Cu")
		(net "RST_PLTRST_PLD_B_N")
	)
	(segment
		(start 197.27037 -118.555008)
		(end 196.79031 -118.074948)
		(width 0.12954)
		(layer "F.Cu")
		(net "RST_PLTRST_PLD_B_N")
	)
	(segment
		(start 196.79031 -118.074948)
		(end 196.25691 -118.608348)
		(width 0.12954)
		(layer "F.Cu")
		(net "RST_PLTRST_PLD_B_N")
	)
	(segment
		(start 200.60031 -118.074948)
		(end 200.12025 -118.555008)
		(width 0.12954)
		(layer "F.Cu")
		(net "RST_PLTRST_PLD_B_N")
	)
	(segment
		(start 186.955684 -115.375436)
		(end 189.829948 -115.375436)
		(width 0.12954)
		(layer "F.Cu")
		(net "RST_PLTRST_PLD_B_N")
	)
	(segment
		(start 192.15862 -118.074948)
		(end 192.98031 -118.074948)
		(width 0.12954)
		(layer "F.Cu")
		(net "RST_PLTRST_PLD_B_N")
	)
	(segment
		(start 193.223134 -118.608348)
		(end 192.98031 -118.365524)
		(width 0.12954)
		(layer "F.Cu")
		(net "RST_PLTRST_PLD_B_N")
	)
	(segment
		(start 189.829948 -115.375436)
		(end 190.57366 -116.119148)
		(width 0.12954)
		(layer "F.Cu")
		(net "RST_PLTRST_PLD_B_N")
	)
	(segment
		(start 190.57366 -116.489988)
		(end 192.15862 -118.074948)
		(width 0.12954)
		(layer "F.Cu")
		(net "RST_PLTRST_PLD_B_N")
	)
	(segment
		(start 190.57366 -116.119148)
		(end 190.57366 -116.489988)
		(width 0.12954)
		(layer "F.Cu")
		(net "RST_PLTRST_PLD_B_N")
	)
	(via
		(at 190.57366 -116.119148)
		(size 0.762)
		(drill 0.381)
		(layers "F.Cu" "B.Cu")
		(net "RST_PLTRST_PLD_B_N")
	)
	(segment
		(start 319.095882 -51.021488)
		(end 319.985136 -51.021488)
		(width 0.12954)
		(layer "F.Cu")
		(net "RST_PLTRST_N")
	)
	(segment
		(start 313.8805 -51.689508)
		(end 314.954666 -51.689508)
		(width 0.12954)
		(layer "F.Cu")
		(net "RST_PLTRST_N")
	)
	(segment
		(start 322.534026 -50.682398)
		(end 322.641976 -50.574448)
		(width 0.12954)
		(layer "F.Cu")
		(net "RST_PLTRST_N")
	)
	(segment
		(start 326.845168 -49.749202)
		(end 327.14946 -49.749202)
		(width 0.0889)
		(layer "F.Cu")
		(net "RST_PLTRST_N")
	)
	(segment
		(start 311.23128 -51.227228)
		(end 312.17616 -52.172108)
		(width 0.12954)
		(layer "F.Cu")
		(net "RST_PLTRST_N")
	)
	(segment
		(start 314.954666 -51.689508)
		(end 316.095126 -50.549048)
		(width 0.12954)
		(layer "F.Cu")
		(net "RST_PLTRST_N")
	)
	(segment
		(start 320.179192 -50.827432)
		(end 322.099178 -50.827432)
		(width 0.12954)
		(layer "F.Cu")
		(net "RST_PLTRST_N")
	)
	(segment
		(start 325.028052 -50.093118)
		(end 325.458836 -49.662334)
		(width 0.0889)
		(layer "F.Cu")
		(net "RST_PLTRST_N")
	)
	(segment
		(start 322.244212 -50.682398)
		(end 322.534026 -50.682398)
		(width 0.12954)
		(layer "F.Cu")
		(net "RST_PLTRST_N")
	)
	(segment
		(start 311.23128 -50.841148)
		(end 311.23128 -51.227228)
		(width 0.12954)
		(layer "F.Cu")
		(net "RST_PLTRST_N")
	)
	(segment
		(start 318.623442 -50.549048)
		(end 319.095882 -51.021488)
		(width 0.12954)
		(layer "F.Cu")
		(net "RST_PLTRST_N")
	)
	(segment
		(start 325.458836 -49.662334)
		(end 326.740012 -49.662334)
		(width 0.0889)
		(layer "F.Cu")
		(net "RST_PLTRST_N")
	)
	(segment
		(start 322.641976 -50.574448)
		(end 323.123306 -50.093118)
		(width 0.0889)
		(layer "F.Cu")
		(net "RST_PLTRST_N")
	)
	(segment
		(start 101.87178 -99.423982)
		(end 102.689914 -99.423982)
		(width 0.12954)
		(layer "F.Cu")
		(net "RST_PLTRST_N")
	)
	(segment
		(start 313.3979 -52.172108)
		(end 313.8805 -51.689508)
		(width 0.12954)
		(layer "F.Cu")
		(net "RST_PLTRST_N")
	)
	(segment
		(start 327.14946 -49.749202)
		(end 327.44791 -49.450752)
		(width 0.0889)
		(layer "F.Cu")
		(net "RST_PLTRST_N")
	)
	(segment
		(start 316.095126 -50.549048)
		(end 318.623442 -50.549048)
		(width 0.12954)
		(layer "F.Cu")
		(net "RST_PLTRST_N")
	)
	(segment
		(start 327.44791 -49.450752)
		(end 327.829926 -49.450752)
		(width 0.0889)
		(layer "F.Cu")
		(net "RST_PLTRST_N")
	)
	(segment
		(start 323.123306 -50.093118)
		(end 325.028052 -50.093118)
		(width 0.0889)
		(layer "F.Cu")
		(net "RST_PLTRST_N")
	)
	(segment
		(start 322.099178 -50.827432)
		(end 322.244212 -50.682398)
		(width 0.12954)
		(layer "F.Cu")
		(net "RST_PLTRST_N")
	)
	(segment
		(start 326.740012 -49.662334)
		(end 326.845168 -49.749202)
		(width 0.0889)
		(layer "F.Cu")
		(net "RST_PLTRST_N")
	)
	(segment
		(start 319.985136 -51.021488)
		(end 320.179192 -50.827432)
		(width 0.12954)
		(layer "F.Cu")
		(net "RST_PLTRST_N")
	)
	(segment
		(start 312.17616 -52.172108)
		(end 313.3979 -52.172108)
		(width 0.12954)
		(layer "F.Cu")
		(net "RST_PLTRST_N")
	)
	(via
		(at 101.62032 -120.053608)
		(size 0.508)
		(drill 0.254)
		(layers "F.Cu" "B.Cu")
		(net "RST_PLTRST_N")
	)
	(via
		(at 196.180456 -120.665748)
		(size 0.508)
		(drill 0.254)
		(layers "F.Cu" "B.Cu")
		(net "RST_PLTRST_N")
	)
	(via
		(at 323.70268 -117.693948)
		(size 0.508)
		(drill 0.254)
		(layers "F.Cu" "B.Cu")
		(net "RST_PLTRST_N")
	)
	(via
		(at 141.78788 -116.677948)
		(size 0.508)
		(drill 0.254)
		(layers "F.Cu" "B.Cu")
		(net "RST_PLTRST_N")
	)
	(via
		(at 311.23128 -50.841148)
		(size 0.508)
		(drill 0.254)
		(layers "F.Cu" "B.Cu")
		(net "RST_PLTRST_N")
	)
	(via
		(at 102.689914 -99.423982)
		(size 0.508)
		(drill 0.254)
		(layers "F.Cu" "B.Cu")
		(net "RST_PLTRST_N")
	)
	(segment
		(start 196.79031 -120.614948)
		(end 196.73951 -120.665748)
		(width 0.12954)
		(layer "B.Cu")
		(net "RST_PLTRST_N")
	)
	(segment
		(start 193.78041 -120.291098)
		(end 193.78041 -120.614948)
		(width 0.12954)
		(layer "B.Cu")
		(net "RST_PLTRST_N")
	)
	(segment
		(start 194.09156 -119.979948)
		(end 193.78041 -120.291098)
		(width 0.12954)
		(layer "B.Cu")
		(net "RST_PLTRST_N")
	)
	(segment
		(start 196.180456 -120.665748)
		(end 196.18325 -120.665748)
		(width 0.12954)
		(layer "B.Cu")
		(net "RST_PLTRST_N")
	)
	(segment
		(start 196.18325 -120.665748)
		(end 195.49745 -119.979948)
		(width 0.12954)
		(layer "B.Cu")
		(net "RST_PLTRST_N")
	)
	(segment
		(start 196.73951 -120.665748)
		(end 196.18325 -120.665748)
		(width 0.12954)
		(layer "B.Cu")
		(net "RST_PLTRST_N")
	)
	(segment
		(start 195.49745 -119.979948)
		(end 194.09156 -119.979948)
		(width 0.12954)
		(layer "B.Cu")
		(net "RST_PLTRST_N")
	)
	(segment
		(start 314.19673 -58.558938)
		(end 314.19673 -64.558418)
		(width 0.127)
		(layer "In2.Cu")
		(net "RST_PLTRST_N")
	)
	(segment
		(start 313.61888 -66.485516)
		(end 316.23381 -72.798432)
		(width 0.127)
		(layer "In2.Cu")
		(net "RST_PLTRST_N")
	)
	(segment
		(start 101.62032 -120.053608)
		(end 101.62032 -112.679988)
		(width 0.127)
		(layer "In2.Cu")
		(net "RST_PLTRST_N")
	)
	(segment
		(start 311.23128 -51.303428)
		(end 311.77992 -51.852068)
		(width 0.127)
		(layer "In2.Cu")
		(net "RST_PLTRST_N")
	)
	(segment
		(start 316.23381 -72.798432)
		(end 323.70268 -80.267302)
		(width 0.127)
		(layer "In2.Cu")
		(net "RST_PLTRST_N")
	)
	(segment
		(start 311.77992 -56.142128)
		(end 314.19673 -58.558938)
		(width 0.127)
		(layer "In2.Cu")
		(net "RST_PLTRST_N")
	)
	(segment
		(start 100.89388 -111.953548)
		(end 100.89388 -101.220016)
		(width 0.127)
		(layer "In2.Cu")
		(net "RST_PLTRST_N")
	)
	(segment
		(start 323.70268 -80.267302)
		(end 323.70268 -117.693948)
		(width 0.127)
		(layer "In2.Cu")
		(net "RST_PLTRST_N")
	)
	(segment
		(start 311.23128 -50.841148)
		(end 311.23128 -51.303428)
		(width 0.127)
		(layer "In2.Cu")
		(net "RST_PLTRST_N")
	)
	(segment
		(start 101.62032 -112.679988)
		(end 100.89388 -111.953548)
		(width 0.127)
		(layer "In2.Cu")
		(net "RST_PLTRST_N")
	)
	(segment
		(start 100.89388 -101.220016)
		(end 102.689914 -99.423982)
		(width 0.127)
		(layer "In2.Cu")
		(net "RST_PLTRST_N")
	)
	(segment
		(start 313.61888 -65.136268)
		(end 313.61888 -66.485516)
		(width 0.127)
		(layer "In2.Cu")
		(net "RST_PLTRST_N")
	)
	(segment
		(start 314.19673 -64.558418)
		(end 313.61888 -65.136268)
		(width 0.127)
		(layer "In2.Cu")
		(net "RST_PLTRST_N")
	)
	(segment
		(start 311.77992 -51.852068)
		(end 311.77992 -56.142128)
		(width 0.127)
		(layer "In2.Cu")
		(net "RST_PLTRST_N")
	)
	(segment
		(start 140.90904 -116.41074)
		(end 140.90904 -109.761782)
		(width 0.127)
		(layer "In4.Cu")
		(net "RST_PLTRST_N")
	)
	(segment
		(start 177.73396 -96.827848)
		(end 181.43474 -96.827848)
		(width 0.127)
		(layer "In4.Cu")
		(net "RST_PLTRST_N")
	)
	(segment
		(start 152.153874 -98.516948)
		(end 169.37228 -98.516948)
		(width 0.127)
		(layer "In4.Cu")
		(net "RST_PLTRST_N")
	)
	(segment
		(start 181.43474 -96.827848)
		(end 182.25516 -96.007428)
		(width 0.127)
		(layer "In4.Cu")
		(net "RST_PLTRST_N")
	)
	(segment
		(start 189.9031 -117.734588)
		(end 190.7159 -118.547388)
		(width 0.127)
		(layer "In4.Cu")
		(net "RST_PLTRST_N")
	)
	(segment
		(start 187.066428 -96.007428)
		(end 188.23051 -97.17151)
		(width 0.127)
		(layer "In4.Cu")
		(net "RST_PLTRST_N")
	)
	(segment
		(start 140.90904 -109.761782)
		(end 152.153874 -98.516948)
		(width 0.127)
		(layer "In4.Cu")
		(net "RST_PLTRST_N")
	)
	(segment
		(start 189.9031 -99.108768)
		(end 189.9031 -117.734588)
		(width 0.127)
		(layer "In4.Cu")
		(net "RST_PLTRST_N")
	)
	(segment
		(start 195.12534 -118.547388)
		(end 195.30822 -118.730268)
		(width 0.127)
		(layer "In4.Cu")
		(net "RST_PLTRST_N")
	)
	(segment
		(start 177.0761 -97.485708)
		(end 177.73396 -96.827848)
		(width 0.127)
		(layer "In4.Cu")
		(net "RST_PLTRST_N")
	)
	(segment
		(start 188.23051 -97.436178)
		(end 189.9031 -99.108768)
		(width 0.127)
		(layer "In4.Cu")
		(net "RST_PLTRST_N")
	)
	(segment
		(start 141.176248 -116.677948)
		(end 140.90904 -116.41074)
		(width 0.127)
		(layer "In4.Cu")
		(net "RST_PLTRST_N")
	)
	(segment
		(start 195.30822 -119.790718)
		(end 196.18325 -120.665748)
		(width 0.127)
		(layer "In4.Cu")
		(net "RST_PLTRST_N")
	)
	(segment
		(start 170.40352 -97.485708)
		(end 177.0761 -97.485708)
		(width 0.127)
		(layer "In4.Cu")
		(net "RST_PLTRST_N")
	)
	(segment
		(start 169.37228 -98.516948)
		(end 170.40352 -97.485708)
		(width 0.127)
		(layer "In4.Cu")
		(net "RST_PLTRST_N")
	)
	(segment
		(start 190.7159 -118.547388)
		(end 195.12534 -118.547388)
		(width 0.127)
		(layer "In4.Cu")
		(net "RST_PLTRST_N")
	)
	(segment
		(start 196.18325 -120.665748)
		(end 196.180456 -120.665748)
		(width 0.127)
		(layer "In4.Cu")
		(net "RST_PLTRST_N")
	)
	(segment
		(start 141.78788 -116.677948)
		(end 141.176248 -116.677948)
		(width 0.127)
		(layer "In4.Cu")
		(net "RST_PLTRST_N")
	)
	(segment
		(start 182.25516 -96.007428)
		(end 187.066428 -96.007428)
		(width 0.127)
		(layer "In4.Cu")
		(net "RST_PLTRST_N")
	)
	(segment
		(start 188.23051 -97.17151)
		(end 188.23051 -97.436178)
		(width 0.127)
		(layer "In4.Cu")
		(net "RST_PLTRST_N")
	)
	(segment
		(start 195.30822 -118.730268)
		(end 195.30822 -119.790718)
		(width 0.127)
		(layer "In4.Cu")
		(net "RST_PLTRST_N")
	)
	(segment
		(start 107.0102 -119.776748)
		(end 101.89718 -119.776748)
		(width 0.127)
		(layer "In6.Cu")
		(net "RST_PLTRST_N")
	)
	(segment
		(start 110.594648 -116.1923)
		(end 107.0102 -119.776748)
		(width 0.127)
		(layer "In6.Cu")
		(net "RST_PLTRST_N")
	)
	(segment
		(start 129.04724 -116.1923)
		(end 110.594648 -116.1923)
		(width 0.127)
		(layer "In6.Cu")
		(net "RST_PLTRST_N")
	)
	(segment
		(start 141.78788 -116.677948)
		(end 131.75488 -116.677948)
		(width 0.127)
		(layer "In6.Cu")
		(net "RST_PLTRST_N")
	)
	(segment
		(start 101.89718 -119.776748)
		(end 101.62032 -120.053608)
		(width 0.127)
		(layer "In6.Cu")
		(net "RST_PLTRST_N")
	)
	(segment
		(start 129.685288 -116.830348)
		(end 129.04724 -116.1923)
		(width 0.127)
		(layer "In6.Cu")
		(net "RST_PLTRST_N")
	)
	(segment
		(start 131.60248 -116.830348)
		(end 129.685288 -116.830348)
		(width 0.127)
		(layer "In6.Cu")
		(net "RST_PLTRST_N")
	)
	(segment
		(start 131.75488 -116.677948)
		(end 131.60248 -116.830348)
		(width 0.127)
		(layer "In6.Cu")
		(net "RST_PLTRST_N")
	)
	(segment
		(start 222.06712 -116.078508)
		(end 223.06788 -115.077748)
		(width 0.127)
		(layer "In15.Cu")
		(net "RST_PLTRST_N")
	)
	(segment
		(start 196.66331 -121.145808)
		(end 206.183992 -121.145808)
		(width 0.127)
		(layer "In15.Cu")
		(net "RST_PLTRST_N")
	)
	(segment
		(start 216.82964 -116.078508)
		(end 222.06712 -116.078508)
		(width 0.127)
		(layer "In15.Cu")
		(net "RST_PLTRST_N")
	)
	(segment
		(start 206.5274 -120.8024)
		(end 206.5274 -120.168416)
		(width 0.127)
		(layer "In15.Cu")
		(net "RST_PLTRST_N")
	)
	(segment
		(start 196.180456 -120.665748)
		(end 196.18325 -120.665748)
		(width 0.127)
		(layer "In15.Cu")
		(net "RST_PLTRST_N")
	)
	(segment
		(start 248.78919 -120.729248)
		(end 268.896846 -120.729248)
		(width 0.127)
		(layer "In15.Cu")
		(net "RST_PLTRST_N")
	)
	(segment
		(start 206.183992 -121.145808)
		(end 206.5274 -120.8024)
		(width 0.127)
		(layer "In15.Cu")
		(net "RST_PLTRST_N")
	)
	(segment
		(start 235.36275 -116.078508)
		(end 238.10341 -118.819168)
		(width 0.127)
		(layer "In15.Cu")
		(net "RST_PLTRST_N")
	)
	(segment
		(start 208.9404 -120.2944)
		(end 212.613748 -120.2944)
		(width 0.127)
		(layer "In15.Cu")
		(net "RST_PLTRST_N")
	)
	(segment
		(start 206.5274 -120.168416)
		(end 207.087216 -119.6086)
		(width 0.127)
		(layer "In15.Cu")
		(net "RST_PLTRST_N")
	)
	(segment
		(start 212.613748 -120.2944)
		(end 216.82964 -116.078508)
		(width 0.127)
		(layer "In15.Cu")
		(net "RST_PLTRST_N")
	)
	(segment
		(start 238.10341 -118.819168)
		(end 246.87911 -118.819168)
		(width 0.127)
		(layer "In15.Cu")
		(net "RST_PLTRST_N")
	)
	(segment
		(start 232.7148 -115.077748)
		(end 233.71556 -116.078508)
		(width 0.127)
		(layer "In15.Cu")
		(net "RST_PLTRST_N")
	)
	(segment
		(start 207.087216 -119.6086)
		(end 208.2546 -119.6086)
		(width 0.127)
		(layer "In15.Cu")
		(net "RST_PLTRST_N")
	)
	(segment
		(start 268.896846 -120.729248)
		(end 270.585946 -119.040148)
		(width 0.127)
		(layer "In15.Cu")
		(net "RST_PLTRST_N")
	)
	(segment
		(start 196.18325 -120.665748)
		(end 196.66331 -121.145808)
		(width 0.127)
		(layer "In15.Cu")
		(net "RST_PLTRST_N")
	)
	(segment
		(start 246.87911 -118.819168)
		(end 248.78919 -120.729248)
		(width 0.127)
		(layer "In15.Cu")
		(net "RST_PLTRST_N")
	)
	(segment
		(start 323.16928 -118.227348)
		(end 323.70268 -117.693948)
		(width 0.127)
		(layer "In15.Cu")
		(net "RST_PLTRST_N")
	)
	(segment
		(start 283.326078 -119.040148)
		(end 284.138878 -118.227348)
		(width 0.127)
		(layer "In15.Cu")
		(net "RST_PLTRST_N")
	)
	(segment
		(start 208.2546 -119.6086)
		(end 208.9404 -120.2944)
		(width 0.127)
		(layer "In15.Cu")
		(net "RST_PLTRST_N")
	)
	(segment
		(start 223.06788 -115.077748)
		(end 232.7148 -115.077748)
		(width 0.127)
		(layer "In15.Cu")
		(net "RST_PLTRST_N")
	)
	(segment
		(start 233.71556 -116.078508)
		(end 235.36275 -116.078508)
		(width 0.127)
		(layer "In15.Cu")
		(net "RST_PLTRST_N")
	)
	(segment
		(start 284.138878 -118.227348)
		(end 323.16928 -118.227348)
		(width 0.127)
		(layer "In15.Cu")
		(net "RST_PLTRST_N")
	)
	(segment
		(start 270.585946 -119.040148)
		(end 283.326078 -119.040148)
		(width 0.127)
		(layer "In15.Cu")
		(net "RST_PLTRST_N")
	)
	(segment
		(start 197.59041 -118.074948)
		(end 198.20001 -118.074948)
		(width 0.12954)
		(layer "F.Cu")
		(net "RST_PLTRST_B_N")
	)
	(segment
		(start 141.147038 -12.162028)
		(end 140.965682 -11.980672)
		(width 0.12954)
		(layer "F.Cu")
		(net "RST_PLTRST_B_N")
	)
	(segment
		(start 141.147038 -13.600176)
		(end 141.147038 -12.162028)
		(width 0.12954)
		(layer "F.Cu")
		(net "RST_PLTRST_B_N")
	)
	(segment
		(start 140.965682 -11.980672)
		(end 140.965682 -11.509248)
		(width 0.12954)
		(layer "F.Cu")
		(net "RST_PLTRST_B_N")
	)
	(via
		(at 138.78306 -58.862468)
		(size 0.508)
		(drill 0.254)
		(layers "F.Cu" "B.Cu")
		(net "RST_PLTRST_B_N")
	)
	(via
		(at 140.965682 -11.509248)
		(size 0.508)
		(drill 0.254)
		(layers "F.Cu" "B.Cu")
		(net "RST_PLTRST_B_N")
	)
	(via
		(at 198.20001 -118.074948)
		(size 0.508)
		(drill 0.254)
		(layers "F.Cu" "B.Cu")
		(net "RST_PLTRST_B_N")
	)
	(segment
		(start 138.38428 -25.133808)
		(end 143.08963 -20.428458)
		(width 0.127)
		(layer "In2.Cu")
		(net "RST_PLTRST_B_N")
	)
	(segment
		(start 138.78306 -58.583068)
		(end 138.63828 -58.438288)
		(width 0.127)
		(layer "In2.Cu")
		(net "RST_PLTRST_B_N")
	)
	(segment
		(start 143.08963 -14.855698)
		(end 141.15288 -12.918948)
		(width 0.127)
		(layer "In2.Cu")
		(net "RST_PLTRST_B_N")
	)
	(segment
		(start 138.63828 -39.787068)
		(end 140.45438 -37.970968)
		(width 0.127)
		(layer "In2.Cu")
		(net "RST_PLTRST_B_N")
	)
	(segment
		(start 140.45438 -37.970968)
		(end 140.45438 -37.066728)
		(width 0.127)
		(layer "In2.Cu")
		(net "RST_PLTRST_B_N")
	)
	(segment
		(start 138.63828 -35.250628)
		(end 138.63828 -33.480248)
		(width 0.127)
		(layer "In2.Cu")
		(net "RST_PLTRST_B_N")
	)
	(segment
		(start 138.78306 -58.862468)
		(end 138.78306 -58.583068)
		(width 0.127)
		(layer "In2.Cu")
		(net "RST_PLTRST_B_N")
	)
	(segment
		(start 138.38428 -33.226248)
		(end 138.38428 -25.133808)
		(width 0.127)
		(layer "In2.Cu")
		(net "RST_PLTRST_B_N")
	)
	(segment
		(start 138.63828 -33.480248)
		(end 138.38428 -33.226248)
		(width 0.127)
		(layer "In2.Cu")
		(net "RST_PLTRST_B_N")
	)
	(segment
		(start 141.15288 -11.696446)
		(end 140.965682 -11.509248)
		(width 0.127)
		(layer "In2.Cu")
		(net "RST_PLTRST_B_N")
	)
	(segment
		(start 141.15288 -12.918948)
		(end 141.15288 -11.696446)
		(width 0.127)
		(layer "In2.Cu")
		(net "RST_PLTRST_B_N")
	)
	(segment
		(start 143.08963 -20.428458)
		(end 143.08963 -14.855698)
		(width 0.127)
		(layer "In2.Cu")
		(net "RST_PLTRST_B_N")
	)
	(segment
		(start 138.63828 -58.438288)
		(end 138.63828 -39.787068)
		(width 0.127)
		(layer "In2.Cu")
		(net "RST_PLTRST_B_N")
	)
	(segment
		(start 140.45438 -37.066728)
		(end 138.63828 -35.250628)
		(width 0.127)
		(layer "In2.Cu")
		(net "RST_PLTRST_B_N")
	)
	(segment
		(start 143.071088 -70.107048)
		(end 161.701988 -70.107048)
		(width 0.127)
		(layer "In4.Cu")
		(net "RST_PLTRST_B_N")
	)
	(segment
		(start 189.82436 -86.78418)
		(end 189.82436 -94.501208)
		(width 0.127)
		(layer "In4.Cu")
		(net "RST_PLTRST_B_N")
	)
	(segment
		(start 198.96582 -117.353588)
		(end 198.24446 -118.074948)
		(width 0.127)
		(layer "In4.Cu")
		(net "RST_PLTRST_B_N")
	)
	(segment
		(start 138.78306 -65.81902)
		(end 143.071088 -70.107048)
		(width 0.127)
		(layer "In4.Cu")
		(net "RST_PLTRST_B_N")
	)
	(segment
		(start 161.701988 -70.107048)
		(end 176.93513 -85.34019)
		(width 0.127)
		(layer "In4.Cu")
		(net "RST_PLTRST_B_N")
	)
	(segment
		(start 199.24776 -110.970568)
		(end 199.24776 -115.763548)
		(width 0.127)
		(layer "In4.Cu")
		(net "RST_PLTRST_B_N")
	)
	(segment
		(start 198.24446 -118.074948)
		(end 198.20001 -118.074948)
		(width 0.127)
		(layer "In4.Cu")
		(net "RST_PLTRST_B_N")
	)
	(segment
		(start 176.93513 -85.34019)
		(end 188.38037 -85.34019)
		(width 0.127)
		(layer "In4.Cu")
		(net "RST_PLTRST_B_N")
	)
	(segment
		(start 188.38037 -85.34019)
		(end 189.82436 -86.78418)
		(width 0.127)
		(layer "In4.Cu")
		(net "RST_PLTRST_B_N")
	)
	(segment
		(start 138.78306 -58.862468)
		(end 138.78306 -65.81902)
		(width 0.127)
		(layer "In4.Cu")
		(net "RST_PLTRST_B_N")
	)
	(segment
		(start 193.21526 -108.936028)
		(end 194.67322 -110.393988)
		(width 0.127)
		(layer "In4.Cu")
		(net "RST_PLTRST_B_N")
	)
	(segment
		(start 193.21526 -101.910388)
		(end 193.21526 -108.936028)
		(width 0.127)
		(layer "In4.Cu")
		(net "RST_PLTRST_B_N")
	)
	(segment
		(start 199.24776 -115.763548)
		(end 198.96582 -116.045488)
		(width 0.127)
		(layer "In4.Cu")
		(net "RST_PLTRST_B_N")
	)
	(segment
		(start 194.67322 -110.393988)
		(end 198.67118 -110.393988)
		(width 0.127)
		(layer "In4.Cu")
		(net "RST_PLTRST_B_N")
	)
	(segment
		(start 198.96582 -116.045488)
		(end 198.96582 -117.353588)
		(width 0.127)
		(layer "In4.Cu")
		(net "RST_PLTRST_B_N")
	)
	(segment
		(start 192.23228 -100.927408)
		(end 193.21526 -101.910388)
		(width 0.127)
		(layer "In4.Cu")
		(net "RST_PLTRST_B_N")
	)
	(segment
		(start 198.67118 -110.393988)
		(end 199.24776 -110.970568)
		(width 0.127)
		(layer "In4.Cu")
		(net "RST_PLTRST_B_N")
	)
	(segment
		(start 192.23228 -96.909128)
		(end 192.23228 -100.927408)
		(width 0.127)
		(layer "In4.Cu")
		(net "RST_PLTRST_B_N")
	)
	(segment
		(start 189.82436 -94.501208)
		(end 192.23228 -96.909128)
		(width 0.127)
		(layer "In4.Cu")
		(net "RST_PLTRST_B_N")
	)
	(segment
		(start 333.770986 -23.844758)
		(end 333.735426 -23.809198)
		(width 0.12954)
		(layer "F.Cu")
		(net "RST_PLTRST_B_MUX_N")
	)
	(segment
		(start 201.40041 -118.074948)
		(end 202.01128 -118.074948)
		(width 0.12954)
		(layer "F.Cu")
		(net "RST_PLTRST_B_MUX_N")
	)
	(segment
		(start 333.735426 -23.809198)
		(end 333.735426 -22.607778)
		(width 0.12954)
		(layer "F.Cu")
		(net "RST_PLTRST_B_MUX_N")
	)
	(via
		(at 202.01128 -118.074948)
		(size 0.508)
		(drill 0.254)
		(layers "F.Cu" "B.Cu")
		(net "RST_PLTRST_B_MUX_N")
	)
	(via
		(at 333.770986 -23.844758)
		(size 0.508)
		(drill 0.254)
		(layers "F.Cu" "B.Cu")
		(net "RST_PLTRST_B_MUX_N")
	)
	(via
		(at 197.46468 -90.160348)
		(size 0.508)
		(drill 0.254)
		(layers "F.Cu" "B.Cu")
		(net "RST_PLTRST_B_MUX_N")
	)
	(via
		(at 243.08308 -67.274948)
		(size 0.508)
		(drill 0.254)
		(layers "F.Cu" "B.Cu")
		(net "RST_PLTRST_B_MUX_N")
	)
	(segment
		(start 299.35678 -35.893248)
		(end 303.45888 -31.791148)
		(width 0.127)
		(layer "In6.Cu")
		(net "RST_PLTRST_B_MUX_N")
	)
	(segment
		(start 259.892038 -65.141348)
		(end 263.383776 -63.695072)
		(width 0.127)
		(layer "In6.Cu")
		(net "RST_PLTRST_B_MUX_N")
	)
	(segment
		(start 330.96708 -30.267148)
		(end 335.89468 -25.339548)
		(width 0.127)
		(layer "In6.Cu")
		(net "RST_PLTRST_B_MUX_N")
	)
	(segment
		(start 335.89468 -24.780748)
		(end 335.43748 -24.323548)
		(width 0.127)
		(layer "In6.Cu")
		(net "RST_PLTRST_B_MUX_N")
	)
	(segment
		(start 243.08308 -66.970148)
		(end 244.91188 -65.141348)
		(width 0.127)
		(layer "In6.Cu")
		(net "RST_PLTRST_B_MUX_N")
	)
	(segment
		(start 265.9507 -61.128148)
		(end 273.181064 -61.128148)
		(width 0.127)
		(layer "In6.Cu")
		(net "RST_PLTRST_B_MUX_N")
	)
	(segment
		(start 325.12381 -29.127958)
		(end 328.96429 -29.127958)
		(width 0.127)
		(layer "In6.Cu")
		(net "RST_PLTRST_B_MUX_N")
	)
	(segment
		(start 335.89468 -25.339548)
		(end 335.89468 -24.780748)
		(width 0.127)
		(layer "In6.Cu")
		(net "RST_PLTRST_B_MUX_N")
	)
	(segment
		(start 320.37528 -31.562548)
		(end 323.47154 -28.466288)
		(width 0.127)
		(layer "In6.Cu")
		(net "RST_PLTRST_B_MUX_N")
	)
	(segment
		(start 330.10348 -30.267148)
		(end 330.96708 -30.267148)
		(width 0.127)
		(layer "In6.Cu")
		(net "RST_PLTRST_B_MUX_N")
	)
	(segment
		(start 335.43748 -24.323548)
		(end 334.249776 -24.323548)
		(width 0.127)
		(layer "In6.Cu")
		(net "RST_PLTRST_B_MUX_N")
	)
	(segment
		(start 244.91188 -65.141348)
		(end 259.892038 -65.141348)
		(width 0.127)
		(layer "In6.Cu")
		(net "RST_PLTRST_B_MUX_N")
	)
	(segment
		(start 328.96429 -29.127958)
		(end 330.10348 -30.267148)
		(width 0.127)
		(layer "In6.Cu")
		(net "RST_PLTRST_B_MUX_N")
	)
	(segment
		(start 324.46214 -28.466288)
		(end 325.12381 -29.127958)
		(width 0.127)
		(layer "In6.Cu")
		(net "RST_PLTRST_B_MUX_N")
	)
	(segment
		(start 309.75808 -31.791148)
		(end 310.67248 -30.876748)
		(width 0.127)
		(layer "In6.Cu")
		(net "RST_PLTRST_B_MUX_N")
	)
	(segment
		(start 334.249776 -24.323548)
		(end 333.770986 -23.844758)
		(width 0.127)
		(layer "In6.Cu")
		(net "RST_PLTRST_B_MUX_N")
	)
	(segment
		(start 243.08308 -67.274948)
		(end 243.08308 -66.970148)
		(width 0.127)
		(layer "In6.Cu")
		(net "RST_PLTRST_B_MUX_N")
	)
	(segment
		(start 263.383776 -63.695072)
		(end 265.9507 -61.128148)
		(width 0.127)
		(layer "In6.Cu")
		(net "RST_PLTRST_B_MUX_N")
	)
	(segment
		(start 273.181064 -61.128148)
		(end 298.415964 -35.893248)
		(width 0.127)
		(layer "In6.Cu")
		(net "RST_PLTRST_B_MUX_N")
	)
	(segment
		(start 298.415964 -35.893248)
		(end 299.35678 -35.893248)
		(width 0.127)
		(layer "In6.Cu")
		(net "RST_PLTRST_B_MUX_N")
	)
	(segment
		(start 314.96508 -30.876748)
		(end 315.65088 -31.562548)
		(width 0.127)
		(layer "In6.Cu")
		(net "RST_PLTRST_B_MUX_N")
	)
	(segment
		(start 323.47154 -28.466288)
		(end 324.46214 -28.466288)
		(width 0.127)
		(layer "In6.Cu")
		(net "RST_PLTRST_B_MUX_N")
	)
	(segment
		(start 303.45888 -31.791148)
		(end 309.75808 -31.791148)
		(width 0.127)
		(layer "In6.Cu")
		(net "RST_PLTRST_B_MUX_N")
	)
	(segment
		(start 315.65088 -31.562548)
		(end 320.37528 -31.562548)
		(width 0.127)
		(layer "In6.Cu")
		(net "RST_PLTRST_B_MUX_N")
	)
	(segment
		(start 310.67248 -30.876748)
		(end 314.96508 -30.876748)
		(width 0.127)
		(layer "In6.Cu")
		(net "RST_PLTRST_B_MUX_N")
	)
	(segment
		(start 199.703182 -119.903748)
		(end 200.18248 -119.903748)
		(width 0.127)
		(layer "In13.Cu")
		(net "RST_PLTRST_B_MUX_N")
	)
	(segment
		(start 189.95644 -115.926108)
		(end 192.62344 -118.593108)
		(width 0.127)
		(layer "In13.Cu")
		(net "RST_PLTRST_B_MUX_N")
	)
	(segment
		(start 189.95644 -100.922328)
		(end 189.95644 -115.926108)
		(width 0.127)
		(layer "In13.Cu")
		(net "RST_PLTRST_B_MUX_N")
	)
	(segment
		(start 197.46468 -90.917268)
		(end 195.6054 -92.776548)
		(width 0.127)
		(layer "In13.Cu")
		(net "RST_PLTRST_B_MUX_N")
	)
	(segment
		(start 200.18248 -119.903748)
		(end 202.01128 -118.074948)
		(width 0.127)
		(layer "In13.Cu")
		(net "RST_PLTRST_B_MUX_N")
	)
	(segment
		(start 195.6054 -95.273368)
		(end 189.95644 -100.922328)
		(width 0.127)
		(layer "In13.Cu")
		(net "RST_PLTRST_B_MUX_N")
	)
	(segment
		(start 198.392542 -118.593108)
		(end 199.703182 -119.903748)
		(width 0.127)
		(layer "In13.Cu")
		(net "RST_PLTRST_B_MUX_N")
	)
	(segment
		(start 192.62344 -118.593108)
		(end 198.392542 -118.593108)
		(width 0.127)
		(layer "In13.Cu")
		(net "RST_PLTRST_B_MUX_N")
	)
	(segment
		(start 195.6054 -92.776548)
		(end 195.6054 -95.273368)
		(width 0.127)
		(layer "In13.Cu")
		(net "RST_PLTRST_B_MUX_N")
	)
	(segment
		(start 197.46468 -90.160348)
		(end 197.46468 -90.917268)
		(width 0.127)
		(layer "In13.Cu")
		(net "RST_PLTRST_B_MUX_N")
	)
	(segment
		(start 233.189272 -68.454016)
		(end 221.66834 -79.974948)
		(width 0.127)
		(layer "In15.Cu")
		(net "RST_PLTRST_B_MUX_N")
	)
	(segment
		(start 197.87108 -82.487008)
		(end 197.87108 -89.004648)
		(width 0.127)
		(layer "In15.Cu")
		(net "RST_PLTRST_B_MUX_N")
	)
	(segment
		(start 200.38314 -79.974948)
		(end 197.87108 -82.487008)
		(width 0.127)
		(layer "In15.Cu")
		(net "RST_PLTRST_B_MUX_N")
	)
	(segment
		(start 243.08308 -67.274948)
		(end 241.904012 -68.454016)
		(width 0.127)
		(layer "In15.Cu")
		(net "RST_PLTRST_B_MUX_N")
	)
	(segment
		(start 197.87108 -89.004648)
		(end 197.46468 -89.411048)
		(width 0.127)
		(layer "In15.Cu")
		(net "RST_PLTRST_B_MUX_N")
	)
	(segment
		(start 221.66834 -79.974948)
		(end 200.38314 -79.974948)
		(width 0.127)
		(layer "In15.Cu")
		(net "RST_PLTRST_B_MUX_N")
	)
	(segment
		(start 241.904012 -68.454016)
		(end 233.189272 -68.454016)
		(width 0.127)
		(layer "In15.Cu")
		(net "RST_PLTRST_B_MUX_N")
	)
	(segment
		(start 197.46468 -89.411048)
		(end 197.46468 -90.160348)
		(width 0.127)
		(layer "In15.Cu")
		(net "RST_PLTRST_B_MUX_N")
	)
	(segment
		(start 85.262974 -102.509574)
		(end 84.726272 -102.509574)
		(width 0.12954)
		(layer "F.Cu")
		(net "RST_PLD_CPU1_DRAM_GH_N")
	)
	(segment
		(start 85.41258 -102.359968)
		(end 85.262974 -102.509574)
		(width 0.12954)
		(layer "F.Cu")
		(net "RST_PLD_CPU1_DRAM_GH_N")
	)
	(segment
		(start 174.155608 -107.375452)
		(end 173.755558 -106.975402)
		(width 0.12954)
		(layer "F.Cu")
		(net "RST_PLD_CPU1_DRAM_GH_N")
	)
	(via
		(at 209.191606 -189.718696)
		(size 0.508)
		(drill 0.254)
		(layers "F.Cu" "B.Cu")
		(net "RST_PLD_CPU1_DRAM_GH_N")
	)
	(via
		(at 173.755558 -106.975402)
		(size 0.4572)
		(drill 0.254)
		(layers "F.Cu" "B.Cu")
		(net "RST_PLD_CPU1_DRAM_GH_N")
	)
	(via
		(at 85.41258 -102.359968)
		(size 0.508)
		(drill 0.254)
		(layers "F.Cu" "B.Cu")
		(net "RST_PLD_CPU1_DRAM_GH_N")
	)
	(segment
		(start 192.280286 -193.215006)
		(end 192.123568 -193.058288)
		(width 0.12954)
		(layer "B.Cu")
		(net "RST_PLD_CPU1_DRAM_GH_N")
	)
	(segment
		(start 209.191606 -189.718696)
		(end 208.702402 -190.2079)
		(width 0.12954)
		(layer "B.Cu")
		(net "RST_PLD_CPU1_DRAM_GH_N")
	)
	(segment
		(start 192.280286 -190.437262)
		(end 192.280286 -193.215006)
		(width 0.12954)
		(layer "B.Cu")
		(net "RST_PLD_CPU1_DRAM_GH_N")
	)
	(segment
		(start 192.854326 -189.261496)
		(end 192.854326 -189.863222)
		(width 0.12954)
		(layer "B.Cu")
		(net "RST_PLD_CPU1_DRAM_GH_N")
	)
	(segment
		(start 195.30568 -190.2079)
		(end 194.122548 -189.024768)
		(width 0.12954)
		(layer "B.Cu")
		(net "RST_PLD_CPU1_DRAM_GH_N")
	)
	(segment
		(start 192.854326 -189.863222)
		(end 192.280286 -190.437262)
		(width 0.12954)
		(layer "B.Cu")
		(net "RST_PLD_CPU1_DRAM_GH_N")
	)
	(segment
		(start 192.123568 -193.058288)
		(end 191.421004 -193.058288)
		(width 0.12954)
		(layer "B.Cu")
		(net "RST_PLD_CPU1_DRAM_GH_N")
	)
	(segment
		(start 191.421004 -193.058288)
		(end 191.264286 -193.215006)
		(width 0.12954)
		(layer "B.Cu")
		(net "RST_PLD_CPU1_DRAM_GH_N")
	)
	(segment
		(start 191.264286 -193.215006)
		(end 191.110108 -193.060828)
		(width 0.12954)
		(layer "B.Cu")
		(net "RST_PLD_CPU1_DRAM_GH_N")
	)
	(segment
		(start 193.091054 -189.024768)
		(end 192.854326 -189.261496)
		(width 0.12954)
		(layer "B.Cu")
		(net "RST_PLD_CPU1_DRAM_GH_N")
	)
	(segment
		(start 191.110108 -193.060828)
		(end 190.402464 -193.060828)
		(width 0.12954)
		(layer "B.Cu")
		(net "RST_PLD_CPU1_DRAM_GH_N")
	)
	(segment
		(start 208.702402 -190.2079)
		(end 195.30568 -190.2079)
		(width 0.12954)
		(layer "B.Cu")
		(net "RST_PLD_CPU1_DRAM_GH_N")
	)
	(segment
		(start 194.122548 -189.024768)
		(end 193.091054 -189.024768)
		(width 0.12954)
		(layer "B.Cu")
		(net "RST_PLD_CPU1_DRAM_GH_N")
	)
	(segment
		(start 190.402464 -193.060828)
		(end 190.248286 -193.215006)
		(width 0.12954)
		(layer "B.Cu")
		(net "RST_PLD_CPU1_DRAM_GH_N")
	)
	(segment
		(start 181.90718 -113.759488)
		(end 180.93436 -113.759488)
		(width 0.127)
		(layer "In2.Cu")
		(net "RST_PLD_CPU1_DRAM_GH_N")
	)
	(segment
		(start 200.64984 -126.538228)
		(end 198.7804 -124.668788)
		(width 0.127)
		(layer "In2.Cu")
		(net "RST_PLD_CPU1_DRAM_GH_N")
	)
	(segment
		(start 182.15356 -114.005868)
		(end 181.90718 -113.759488)
		(width 0.127)
		(layer "In2.Cu")
		(net "RST_PLD_CPU1_DRAM_GH_N")
	)
	(segment
		(start 176.685956 -111.382556)
		(end 176.562766 -111.259366)
		(width 0.127)
		(layer "In2.Cu")
		(net "RST_PLD_CPU1_DRAM_GH_N")
	)
	(segment
		(start 174.95774 -109.195108)
		(end 174.74184 -108.979208)
		(width 0.127)
		(layer "In2.Cu")
		(net "RST_PLD_CPU1_DRAM_GH_N")
	)
	(segment
		(start 183.1594 -115.369848)
		(end 182.95874 -115.169188)
		(width 0.127)
		(layer "In2.Cu")
		(net "RST_PLD_CPU1_DRAM_GH_N")
	)
	(segment
		(start 182.15356 -114.336068)
		(end 182.15356 -114.005868)
		(width 0.127)
		(layer "In2.Cu")
		(net "RST_PLD_CPU1_DRAM_GH_N")
	)
	(segment
		(start 175.08474 -109.776768)
		(end 174.95774 -109.649768)
		(width 0.127)
		(layer "In2.Cu")
		(net "RST_PLD_CPU1_DRAM_GH_N")
	)
	(segment
		(start 182.95874 -115.169188)
		(end 182.95874 -114.795808)
		(width 0.127)
		(layer "In2.Cu")
		(net "RST_PLD_CPU1_DRAM_GH_N")
	)
	(segment
		(start 200.64984 -132.758688)
		(end 200.64984 -126.538228)
		(width 0.127)
		(layer "In2.Cu")
		(net "RST_PLD_CPU1_DRAM_GH_N")
	)
	(segment
		(start 184.55894 -116.408708)
		(end 183.52008 -115.369848)
		(width 0.127)
		(layer "In2.Cu")
		(net "RST_PLD_CPU1_DRAM_GH_N")
	)
	(segment
		(start 213.681818 -145.790666)
		(end 200.64984 -132.758688)
		(width 0.127)
		(layer "In2.Cu")
		(net "RST_PLD_CPU1_DRAM_GH_N")
	)
	(segment
		(start 174.1551 -107.374944)
		(end 173.755558 -106.975402)
		(width 0.127)
		(layer "In2.Cu")
		(net "RST_PLD_CPU1_DRAM_GH_N")
	)
	(segment
		(start 175.5648 -109.776768)
		(end 175.08474 -109.776768)
		(width 0.127)
		(layer "In2.Cu")
		(net "RST_PLD_CPU1_DRAM_GH_N")
	)
	(segment
		(start 174.95774 -109.649768)
		(end 174.95774 -109.195108)
		(width 0.127)
		(layer "In2.Cu")
		(net "RST_PLD_CPU1_DRAM_GH_N")
	)
	(segment
		(start 182.95874 -114.795808)
		(end 182.73776 -114.574828)
		(width 0.127)
		(layer "In2.Cu")
		(net "RST_PLD_CPU1_DRAM_GH_N")
	)
	(segment
		(start 184.76722 -116.970048)
		(end 184.55894 -116.761768)
		(width 0.127)
		(layer "In2.Cu")
		(net "RST_PLD_CPU1_DRAM_GH_N")
	)
	(segment
		(start 174.38624 -108.979208)
		(end 174.1551 -108.748068)
		(width 0.127)
		(layer "In2.Cu")
		(net "RST_PLD_CPU1_DRAM_GH_N")
	)
	(segment
		(start 182.39232 -114.574828)
		(end 182.15356 -114.336068)
		(width 0.127)
		(layer "In2.Cu")
		(net "RST_PLD_CPU1_DRAM_GH_N")
	)
	(segment
		(start 183.52008 -115.369848)
		(end 183.1594 -115.369848)
		(width 0.127)
		(layer "In2.Cu")
		(net "RST_PLD_CPU1_DRAM_GH_N")
	)
	(segment
		(start 186.78906 -116.970048)
		(end 184.76722 -116.970048)
		(width 0.127)
		(layer "In2.Cu")
		(net "RST_PLD_CPU1_DRAM_GH_N")
	)
	(segment
		(start 175.762666 -110.383066)
		(end 175.762666 -109.974634)
		(width 0.127)
		(layer "In2.Cu")
		(net "RST_PLD_CPU1_DRAM_GH_N")
	)
	(segment
		(start 179.25034 -113.264188)
		(end 178.6128 -112.626648)
		(width 0.127)
		(layer "In2.Cu")
		(net "RST_PLD_CPU1_DRAM_GH_N")
	)
	(segment
		(start 182.73776 -114.574828)
		(end 182.39232 -114.574828)
		(width 0.127)
		(layer "In2.Cu")
		(net "RST_PLD_CPU1_DRAM_GH_N")
	)
	(segment
		(start 178.6128 -112.626648)
		(end 178.6128 -111.9124)
		(width 0.127)
		(layer "In2.Cu")
		(net "RST_PLD_CPU1_DRAM_GH_N")
	)
	(segment
		(start 178.6128 -111.9124)
		(end 178.082956 -111.382556)
		(width 0.127)
		(layer "In2.Cu")
		(net "RST_PLD_CPU1_DRAM_GH_N")
	)
	(segment
		(start 184.55894 -116.761768)
		(end 184.55894 -116.408708)
		(width 0.127)
		(layer "In2.Cu")
		(net "RST_PLD_CPU1_DRAM_GH_N")
	)
	(segment
		(start 180.93436 -113.759488)
		(end 180.43906 -113.264188)
		(width 0.127)
		(layer "In2.Cu")
		(net "RST_PLD_CPU1_DRAM_GH_N")
	)
	(segment
		(start 213.681818 -155.39593)
		(end 213.681818 -145.790666)
		(width 0.127)
		(layer "In2.Cu")
		(net "RST_PLD_CPU1_DRAM_GH_N")
	)
	(segment
		(start 175.9458 -110.5662)
		(end 175.762666 -110.383066)
		(width 0.127)
		(layer "In2.Cu")
		(net "RST_PLD_CPU1_DRAM_GH_N")
	)
	(segment
		(start 192.125346 -121.490994)
		(end 191.310006 -121.490994)
		(width 0.127)
		(layer "In2.Cu")
		(net "RST_PLD_CPU1_DRAM_GH_N")
	)
	(segment
		(start 209.389218 -189.521084)
		(end 209.389218 -188.40323)
		(width 0.127)
		(layer "In2.Cu")
		(net "RST_PLD_CPU1_DRAM_GH_N")
	)
	(segment
		(start 174.74184 -108.979208)
		(end 174.38624 -108.979208)
		(width 0.127)
		(layer "In2.Cu")
		(net "RST_PLD_CPU1_DRAM_GH_N")
	)
	(segment
		(start 213.69782 -184.094628)
		(end 213.69782 -155.411932)
		(width 0.127)
		(layer "In2.Cu")
		(net "RST_PLD_CPU1_DRAM_GH_N")
	)
	(segment
		(start 191.310006 -121.490994)
		(end 186.78906 -116.970048)
		(width 0.127)
		(layer "In2.Cu")
		(net "RST_PLD_CPU1_DRAM_GH_N")
	)
	(segment
		(start 176.562766 -111.259366)
		(end 176.562766 -110.802166)
		(width 0.127)
		(layer "In2.Cu")
		(net "RST_PLD_CPU1_DRAM_GH_N")
	)
	(segment
		(start 176.328832 -110.568232)
		(end 175.99279 -110.568232)
		(width 0.127)
		(layer "In2.Cu")
		(net "RST_PLD_CPU1_DRAM_GH_N")
	)
	(segment
		(start 174.1551 -108.748068)
		(end 174.1551 -107.374944)
		(width 0.127)
		(layer "In2.Cu")
		(net "RST_PLD_CPU1_DRAM_GH_N")
	)
	(segment
		(start 198.7804 -124.668788)
		(end 197.74662 -124.668788)
		(width 0.127)
		(layer "In2.Cu")
		(net "RST_PLD_CPU1_DRAM_GH_N")
	)
	(segment
		(start 213.69782 -155.411932)
		(end 213.681818 -155.39593)
		(width 0.127)
		(layer "In2.Cu")
		(net "RST_PLD_CPU1_DRAM_GH_N")
	)
	(segment
		(start 175.99279 -110.568232)
		(end 175.990758 -110.5662)
		(width 0.127)
		(layer "In2.Cu")
		(net "RST_PLD_CPU1_DRAM_GH_N")
	)
	(segment
		(start 178.082956 -111.382556)
		(end 176.685956 -111.382556)
		(width 0.127)
		(layer "In2.Cu")
		(net "RST_PLD_CPU1_DRAM_GH_N")
	)
	(segment
		(start 175.762666 -109.974634)
		(end 175.5648 -109.776768)
		(width 0.127)
		(layer "In2.Cu")
		(net "RST_PLD_CPU1_DRAM_GH_N")
	)
	(segment
		(start 197.74662 -124.668788)
		(end 196.62648 -123.548648)
		(width 0.127)
		(layer "In2.Cu")
		(net "RST_PLD_CPU1_DRAM_GH_N")
	)
	(segment
		(start 194.183 -123.548648)
		(end 192.125346 -121.490994)
		(width 0.127)
		(layer "In2.Cu")
		(net "RST_PLD_CPU1_DRAM_GH_N")
	)
	(segment
		(start 209.389218 -188.40323)
		(end 213.69782 -184.094628)
		(width 0.127)
		(layer "In2.Cu")
		(net "RST_PLD_CPU1_DRAM_GH_N")
	)
	(segment
		(start 209.191606 -189.718696)
		(end 209.389218 -189.521084)
		(width 0.127)
		(layer "In2.Cu")
		(net "RST_PLD_CPU1_DRAM_GH_N")
	)
	(segment
		(start 175.990758 -110.5662)
		(end 175.9458 -110.5662)
		(width 0.127)
		(layer "In2.Cu")
		(net "RST_PLD_CPU1_DRAM_GH_N")
	)
	(segment
		(start 176.562766 -110.802166)
		(end 176.328832 -110.568232)
		(width 0.127)
		(layer "In2.Cu")
		(net "RST_PLD_CPU1_DRAM_GH_N")
	)
	(segment
		(start 196.62648 -123.548648)
		(end 194.183 -123.548648)
		(width 0.127)
		(layer "In2.Cu")
		(net "RST_PLD_CPU1_DRAM_GH_N")
	)
	(segment
		(start 180.43906 -113.264188)
		(end 179.25034 -113.264188)
		(width 0.127)
		(layer "In2.Cu")
		(net "RST_PLD_CPU1_DRAM_GH_N")
	)
	(segment
		(start 89.1413 -98.631248)
		(end 85.41258 -102.359968)
		(width 0.127)
		(layer "In6.Cu")
		(net "RST_PLD_CPU1_DRAM_GH_N")
	)
	(segment
		(start 105.62082 -100.752148)
		(end 102.58298 -97.714308)
		(width 0.127)
		(layer "In6.Cu")
		(net "RST_PLD_CPU1_DRAM_GH_N")
	)
	(segment
		(start 95.75292 -99.957128)
		(end 94.5769 -99.957128)
		(width 0.127)
		(layer "In6.Cu")
		(net "RST_PLD_CPU1_DRAM_GH_N")
	)
	(segment
		(start 143.994124 -99.784408)
		(end 140.153644 -95.943928)
		(width 0.127)
		(layer "In6.Cu")
		(net "RST_PLD_CPU1_DRAM_GH_N")
	)
	(segment
		(start 173.34992 -105.108248)
		(end 173.42866 -105.029508)
		(width 0.127)
		(layer "In6.Cu")
		(net "RST_PLD_CPU1_DRAM_GH_N")
	)
	(segment
		(start 169.885868 -102.169468)
		(end 168.100248 -100.383848)
		(width 0.127)
		(layer "In6.Cu")
		(net "RST_PLD_CPU1_DRAM_GH_N")
	)
	(segment
		(start 173.755558 -106.975402)
		(end 173.34992 -106.569764)
		(width 0.127)
		(layer "In6.Cu")
		(net "RST_PLD_CPU1_DRAM_GH_N")
	)
	(segment
		(start 145.26514 -99.784408)
		(end 143.994124 -99.784408)
		(width 0.127)
		(layer "In6.Cu")
		(net "RST_PLD_CPU1_DRAM_GH_N")
	)
	(segment
		(start 140.153644 -95.943928)
		(end 115.4557 -95.943928)
		(width 0.127)
		(layer "In6.Cu")
		(net "RST_PLD_CPU1_DRAM_GH_N")
	)
	(segment
		(start 145.86458 -100.383848)
		(end 145.26514 -99.784408)
		(width 0.127)
		(layer "In6.Cu")
		(net "RST_PLD_CPU1_DRAM_GH_N")
	)
	(segment
		(start 94.5769 -99.957128)
		(end 93.25102 -98.631248)
		(width 0.127)
		(layer "In6.Cu")
		(net "RST_PLD_CPU1_DRAM_GH_N")
	)
	(segment
		(start 110.64748 -100.752148)
		(end 105.62082 -100.752148)
		(width 0.127)
		(layer "In6.Cu")
		(net "RST_PLD_CPU1_DRAM_GH_N")
	)
	(segment
		(start 115.4557 -95.943928)
		(end 110.64748 -100.752148)
		(width 0.127)
		(layer "In6.Cu")
		(net "RST_PLD_CPU1_DRAM_GH_N")
	)
	(segment
		(start 97.99574 -97.714308)
		(end 95.75292 -99.957128)
		(width 0.127)
		(layer "In6.Cu")
		(net "RST_PLD_CPU1_DRAM_GH_N")
	)
	(segment
		(start 168.100248 -100.383848)
		(end 145.86458 -100.383848)
		(width 0.127)
		(layer "In6.Cu")
		(net "RST_PLD_CPU1_DRAM_GH_N")
	)
	(segment
		(start 173.34992 -106.569764)
		(end 173.34992 -105.108248)
		(width 0.127)
		(layer "In6.Cu")
		(net "RST_PLD_CPU1_DRAM_GH_N")
	)
	(segment
		(start 172.807122 -102.46741)
		(end 172.087794 -102.169468)
		(width 0.127)
		(layer "In6.Cu")
		(net "RST_PLD_CPU1_DRAM_GH_N")
	)
	(segment
		(start 102.58298 -97.714308)
		(end 97.99574 -97.714308)
		(width 0.127)
		(layer "In6.Cu")
		(net "RST_PLD_CPU1_DRAM_GH_N")
	)
	(segment
		(start 93.25102 -98.631248)
		(end 89.1413 -98.631248)
		(width 0.127)
		(layer "In6.Cu")
		(net "RST_PLD_CPU1_DRAM_GH_N")
	)
	(segment
		(start 172.087794 -102.169468)
		(end 169.885868 -102.169468)
		(width 0.127)
		(layer "In6.Cu")
		(net "RST_PLD_CPU1_DRAM_GH_N")
	)
	(segment
		(start 173.42866 -103.088948)
		(end 172.807122 -102.46741)
		(width 0.127)
		(layer "In6.Cu")
		(net "RST_PLD_CPU1_DRAM_GH_N")
	)
	(segment
		(start 173.42866 -105.029508)
		(end 173.42866 -103.088948)
		(width 0.127)
		(layer "In6.Cu")
		(net "RST_PLD_CPU1_DRAM_GH_N")
	)
	(segment
		(start 87.48776 -102.758748)
		(end 86.77529 -102.758748)
		(width 0.12954)
		(layer "F.Cu")
		(net "RST_PLD_CPU1_DRAM_EF_N")
	)
	(segment
		(start 88.22436 -103.495348)
		(end 87.48776 -102.758748)
		(width 0.12954)
		(layer "F.Cu")
		(net "RST_PLD_CPU1_DRAM_EF_N")
	)
	(segment
		(start 173.355762 -106.575352)
		(end 172.955712 -106.175302)
		(width 0.12954)
		(layer "F.Cu")
		(net "RST_PLD_CPU1_DRAM_EF_N")
	)
	(segment
		(start 86.77529 -102.758748)
		(end 86.526116 -102.509574)
		(width 0.12954)
		(layer "F.Cu")
		(net "RST_PLD_CPU1_DRAM_EF_N")
	)
	(via
		(at 88.22436 -103.495348)
		(size 0.508)
		(drill 0.254)
		(layers "F.Cu" "B.Cu")
		(net "RST_PLD_CPU1_DRAM_EF_N")
	)
	(via
		(at 208.435702 -189.138814)
		(size 0.508)
		(drill 0.254)
		(layers "F.Cu" "B.Cu")
		(net "RST_PLD_CPU1_DRAM_EF_N")
	)
	(via
		(at 188.190886 -191.76365)
		(size 0.6604)
		(drill 0.3302)
		(layers "F.Cu" "B.Cu")
		(net "RST_PLD_CPU1_DRAM_EF_N")
	)
	(via
		(at 172.955712 -106.175302)
		(size 0.4572)
		(drill 0.254)
		(layers "F.Cu" "B.Cu")
		(net "RST_PLD_CPU1_DRAM_EF_N")
	)
	(segment
		(start 208.435702 -189.138814)
		(end 208.435702 -188.63945)
		(width 0.12954)
		(layer "B.Cu")
		(net "RST_PLD_CPU1_DRAM_EF_N")
	)
	(segment
		(start 188.190886 -189.59322)
		(end 188.190886 -191.76365)
		(width 0.12954)
		(layer "B.Cu")
		(net "RST_PLD_CPU1_DRAM_EF_N")
	)
	(segment
		(start 188.308996 -189.292992)
		(end 188.308996 -189.47511)
		(width 0.12954)
		(layer "B.Cu")
		(net "RST_PLD_CPU1_DRAM_EF_N")
	)
	(segment
		(start 188.190886 -193.199766)
		(end 188.054488 -193.063368)
		(width 0.12954)
		(layer "B.Cu")
		(net "RST_PLD_CPU1_DRAM_EF_N")
	)
	(segment
		(start 188.054488 -193.063368)
		(end 187.311284 -193.063368)
		(width 0.12954)
		(layer "B.Cu")
		(net "RST_PLD_CPU1_DRAM_EF_N")
	)
	(segment
		(start 186.310524 -193.048128)
		(end 186.158886 -193.199766)
		(width 0.12954)
		(layer "B.Cu")
		(net "RST_PLD_CPU1_DRAM_EF_N")
	)
	(segment
		(start 188.190886 -191.76365)
		(end 188.190886 -193.199766)
		(width 0.12954)
		(layer "B.Cu")
		(net "RST_PLD_CPU1_DRAM_EF_N")
	)
	(segment
		(start 187.311284 -193.063368)
		(end 187.174886 -193.199766)
		(width 0.12954)
		(layer "B.Cu")
		(net "RST_PLD_CPU1_DRAM_EF_N")
	)
	(segment
		(start 207.51927 -187.723018)
		(end 189.87897 -187.723018)
		(width 0.12954)
		(layer "B.Cu")
		(net "RST_PLD_CPU1_DRAM_EF_N")
	)
	(segment
		(start 188.308996 -189.47511)
		(end 188.190886 -189.59322)
		(width 0.12954)
		(layer "B.Cu")
		(net "RST_PLD_CPU1_DRAM_EF_N")
	)
	(segment
		(start 187.023248 -193.048128)
		(end 186.310524 -193.048128)
		(width 0.12954)
		(layer "B.Cu")
		(net "RST_PLD_CPU1_DRAM_EF_N")
	)
	(segment
		(start 187.174886 -193.199766)
		(end 187.023248 -193.048128)
		(width 0.12954)
		(layer "B.Cu")
		(net "RST_PLD_CPU1_DRAM_EF_N")
	)
	(segment
		(start 208.435702 -188.63945)
		(end 207.51927 -187.723018)
		(width 0.12954)
		(layer "B.Cu")
		(net "RST_PLD_CPU1_DRAM_EF_N")
	)
	(segment
		(start 189.87897 -187.723018)
		(end 188.308996 -189.292992)
		(width 0.12954)
		(layer "B.Cu")
		(net "RST_PLD_CPU1_DRAM_EF_N")
	)
	(segment
		(start 174.72406 -109.776768)
		(end 174.95266 -110.005368)
		(width 0.127)
		(layer "In2.Cu")
		(net "RST_PLD_CPU1_DRAM_EF_N")
	)
	(segment
		(start 183.99252 -116.972588)
		(end 184.33542 -116.972588)
		(width 0.127)
		(layer "In2.Cu")
		(net "RST_PLD_CPU1_DRAM_EF_N")
	)
	(segment
		(start 173.35246 -106.57205)
		(end 173.35246 -108.778548)
		(width 0.127)
		(layer "In2.Cu")
		(net "RST_PLD_CPU1_DRAM_EF_N")
	)
	(segment
		(start 180.75402 -114.574828)
		(end 181.96052 -114.574828)
		(width 0.127)
		(layer "In2.Cu")
		(net "RST_PLD_CPU1_DRAM_EF_N")
	)
	(segment
		(start 178.18862 -112.35182)
		(end 178.18862 -112.664748)
		(width 0.127)
		(layer "In2.Cu")
		(net "RST_PLD_CPU1_DRAM_EF_N")
	)
	(segment
		(start 178.18862 -112.664748)
		(end 179.06746 -113.543588)
		(width 0.127)
		(layer "In2.Cu")
		(net "RST_PLD_CPU1_DRAM_EF_N")
	)
	(segment
		(start 184.785 -117.780308)
		(end 186.31154 -117.780308)
		(width 0.127)
		(layer "In2.Cu")
		(net "RST_PLD_CPU1_DRAM_EF_N")
	)
	(segment
		(start 182.15864 -115.197128)
		(end 182.33644 -115.374928)
		(width 0.127)
		(layer "In2.Cu")
		(net "RST_PLD_CPU1_DRAM_EF_N")
	)
	(segment
		(start 174.38878 -109.776768)
		(end 174.72406 -109.776768)
		(width 0.127)
		(layer "In2.Cu")
		(net "RST_PLD_CPU1_DRAM_EF_N")
	)
	(segment
		(start 172.955712 -106.175302)
		(end 173.35246 -106.57205)
		(width 0.127)
		(layer "In2.Cu")
		(net "RST_PLD_CPU1_DRAM_EF_N")
	)
	(segment
		(start 174.1551 -109.543088)
		(end 174.38878 -109.776768)
		(width 0.127)
		(layer "In2.Cu")
		(net "RST_PLD_CPU1_DRAM_EF_N")
	)
	(segment
		(start 175.762666 -112.034066)
		(end 175.897032 -112.168432)
		(width 0.127)
		(layer "In2.Cu")
		(net "RST_PLD_CPU1_DRAM_EF_N")
	)
	(segment
		(start 178.005232 -112.168432)
		(end 178.18862 -112.35182)
		(width 0.127)
		(layer "In2.Cu")
		(net "RST_PLD_CPU1_DRAM_EF_N")
	)
	(segment
		(start 194.834764 -124.764038)
		(end 199.68972 -129.618994)
		(width 0.127)
		(layer "In2.Cu")
		(net "RST_PLD_CPU1_DRAM_EF_N")
	)
	(segment
		(start 186.31154 -117.780308)
		(end 193.29527 -124.764038)
		(width 0.127)
		(layer "In2.Cu")
		(net "RST_PLD_CPU1_DRAM_EF_N")
	)
	(segment
		(start 175.19142 -110.579408)
		(end 175.552608 -110.579408)
		(width 0.127)
		(layer "In2.Cu")
		(net "RST_PLD_CPU1_DRAM_EF_N")
	)
	(segment
		(start 175.897032 -112.168432)
		(end 178.005232 -112.168432)
		(width 0.127)
		(layer "In2.Cu")
		(net "RST_PLD_CPU1_DRAM_EF_N")
	)
	(segment
		(start 212.708998 -146.105626)
		(end 212.708998 -183.69661)
		(width 0.127)
		(layer "In2.Cu")
		(net "RST_PLD_CPU1_DRAM_EF_N")
	)
	(segment
		(start 182.95366 -115.933728)
		(end 183.19496 -116.175028)
		(width 0.127)
		(layer "In2.Cu")
		(net "RST_PLD_CPU1_DRAM_EF_N")
	)
	(segment
		(start 173.5455 -108.971588)
		(end 173.92396 -108.971588)
		(width 0.127)
		(layer "In2.Cu")
		(net "RST_PLD_CPU1_DRAM_EF_N")
	)
	(segment
		(start 182.15864 -114.772948)
		(end 182.15864 -115.197128)
		(width 0.127)
		(layer "In2.Cu")
		(net "RST_PLD_CPU1_DRAM_EF_N")
	)
	(segment
		(start 173.35246 -108.778548)
		(end 173.5455 -108.971588)
		(width 0.127)
		(layer "In2.Cu")
		(net "RST_PLD_CPU1_DRAM_EF_N")
	)
	(segment
		(start 208.435702 -187.969906)
		(end 208.435702 -189.138814)
		(width 0.127)
		(layer "In2.Cu")
		(net "RST_PLD_CPU1_DRAM_EF_N")
	)
	(segment
		(start 182.95366 -115.613688)
		(end 182.95366 -115.933728)
		(width 0.127)
		(layer "In2.Cu")
		(net "RST_PLD_CPU1_DRAM_EF_N")
	)
	(segment
		(start 183.76138 -116.741448)
		(end 183.99252 -116.972588)
		(width 0.127)
		(layer "In2.Cu")
		(net "RST_PLD_CPU1_DRAM_EF_N")
	)
	(segment
		(start 199.68972 -133.086348)
		(end 212.708998 -146.105626)
		(width 0.127)
		(layer "In2.Cu")
		(net "RST_PLD_CPU1_DRAM_EF_N")
	)
	(segment
		(start 175.552608 -110.579408)
		(end 175.762666 -110.789466)
		(width 0.127)
		(layer "In2.Cu")
		(net "RST_PLD_CPU1_DRAM_EF_N")
	)
	(segment
		(start 175.762666 -110.789466)
		(end 175.762666 -112.034066)
		(width 0.127)
		(layer "In2.Cu")
		(net "RST_PLD_CPU1_DRAM_EF_N")
	)
	(segment
		(start 184.5564 -117.193568)
		(end 184.5564 -117.551708)
		(width 0.127)
		(layer "In2.Cu")
		(net "RST_PLD_CPU1_DRAM_EF_N")
	)
	(segment
		(start 183.51754 -116.175028)
		(end 183.76138 -116.418868)
		(width 0.127)
		(layer "In2.Cu")
		(net "RST_PLD_CPU1_DRAM_EF_N")
	)
	(segment
		(start 180.19776 -113.543588)
		(end 180.55336 -113.899188)
		(width 0.127)
		(layer "In2.Cu")
		(net "RST_PLD_CPU1_DRAM_EF_N")
	)
	(segment
		(start 174.95266 -110.340648)
		(end 175.19142 -110.579408)
		(width 0.127)
		(layer "In2.Cu")
		(net "RST_PLD_CPU1_DRAM_EF_N")
	)
	(segment
		(start 173.92396 -108.971588)
		(end 174.1551 -109.202728)
		(width 0.127)
		(layer "In2.Cu")
		(net "RST_PLD_CPU1_DRAM_EF_N")
	)
	(segment
		(start 184.5564 -117.551708)
		(end 184.785 -117.780308)
		(width 0.127)
		(layer "In2.Cu")
		(net "RST_PLD_CPU1_DRAM_EF_N")
	)
	(segment
		(start 174.1551 -109.202728)
		(end 174.1551 -109.543088)
		(width 0.127)
		(layer "In2.Cu")
		(net "RST_PLD_CPU1_DRAM_EF_N")
	)
	(segment
		(start 180.55336 -114.374168)
		(end 180.75402 -114.574828)
		(width 0.127)
		(layer "In2.Cu")
		(net "RST_PLD_CPU1_DRAM_EF_N")
	)
	(segment
		(start 182.7149 -115.374928)
		(end 182.95366 -115.613688)
		(width 0.127)
		(layer "In2.Cu")
		(net "RST_PLD_CPU1_DRAM_EF_N")
	)
	(segment
		(start 174.95266 -110.005368)
		(end 174.95266 -110.340648)
		(width 0.127)
		(layer "In2.Cu")
		(net "RST_PLD_CPU1_DRAM_EF_N")
	)
	(segment
		(start 184.33542 -116.972588)
		(end 184.5564 -117.193568)
		(width 0.127)
		(layer "In2.Cu")
		(net "RST_PLD_CPU1_DRAM_EF_N")
	)
	(segment
		(start 181.96052 -114.574828)
		(end 182.15864 -114.772948)
		(width 0.127)
		(layer "In2.Cu")
		(net "RST_PLD_CPU1_DRAM_EF_N")
	)
	(segment
		(start 182.33644 -115.374928)
		(end 182.7149 -115.374928)
		(width 0.127)
		(layer "In2.Cu")
		(net "RST_PLD_CPU1_DRAM_EF_N")
	)
	(segment
		(start 199.68972 -129.618994)
		(end 199.68972 -133.086348)
		(width 0.127)
		(layer "In2.Cu")
		(net "RST_PLD_CPU1_DRAM_EF_N")
	)
	(segment
		(start 212.708998 -183.69661)
		(end 208.435702 -187.969906)
		(width 0.127)
		(layer "In2.Cu")
		(net "RST_PLD_CPU1_DRAM_EF_N")
	)
	(segment
		(start 180.55336 -113.899188)
		(end 180.55336 -114.374168)
		(width 0.127)
		(layer "In2.Cu")
		(net "RST_PLD_CPU1_DRAM_EF_N")
	)
	(segment
		(start 193.29527 -124.764038)
		(end 194.834764 -124.764038)
		(width 0.127)
		(layer "In2.Cu")
		(net "RST_PLD_CPU1_DRAM_EF_N")
	)
	(segment
		(start 183.19496 -116.175028)
		(end 183.51754 -116.175028)
		(width 0.127)
		(layer "In2.Cu")
		(net "RST_PLD_CPU1_DRAM_EF_N")
	)
	(segment
		(start 183.76138 -116.418868)
		(end 183.76138 -116.741448)
		(width 0.127)
		(layer "In2.Cu")
		(net "RST_PLD_CPU1_DRAM_EF_N")
	)
	(segment
		(start 179.06746 -113.543588)
		(end 180.19776 -113.543588)
		(width 0.127)
		(layer "In2.Cu")
		(net "RST_PLD_CPU1_DRAM_EF_N")
	)
	(segment
		(start 172.55236 -105.113328)
		(end 171.61002 -104.170988)
		(width 0.127)
		(layer "In6.Cu")
		(net "RST_PLD_CPU1_DRAM_EF_N")
	)
	(segment
		(start 168.33596 -103.190548)
		(end 166.751 -103.190548)
		(width 0.127)
		(layer "In6.Cu")
		(net "RST_PLD_CPU1_DRAM_EF_N")
	)
	(segment
		(start 103.91648 -102.692708)
		(end 102.90556 -103.703628)
		(width 0.127)
		(layer "In6.Cu")
		(net "RST_PLD_CPU1_DRAM_EF_N")
	)
	(segment
		(start 143.756126 -103.127048)
		(end 138.818366 -98.189288)
		(width 0.127)
		(layer "In6.Cu")
		(net "RST_PLD_CPU1_DRAM_EF_N")
	)
	(segment
		(start 88.2904 -103.561388)
		(end 88.22436 -103.495348)
		(width 0.127)
		(layer "In6.Cu")
		(net "RST_PLD_CPU1_DRAM_EF_N")
	)
	(segment
		(start 96.44888 -101.750368)
		(end 95.15602 -103.043228)
		(width 0.127)
		(layer "In6.Cu")
		(net "RST_PLD_CPU1_DRAM_EF_N")
	)
	(segment
		(start 116.39296 -101.453188)
		(end 113.10874 -101.453188)
		(width 0.127)
		(layer "In6.Cu")
		(net "RST_PLD_CPU1_DRAM_EF_N")
	)
	(segment
		(start 166.751 -103.190548)
		(end 166.6875 -103.127048)
		(width 0.127)
		(layer "In6.Cu")
		(net "RST_PLD_CPU1_DRAM_EF_N")
	)
	(segment
		(start 138.818366 -98.189288)
		(end 119.65686 -98.189288)
		(width 0.127)
		(layer "In6.Cu")
		(net "RST_PLD_CPU1_DRAM_EF_N")
	)
	(segment
		(start 95.15602 -103.043228)
		(end 92.87002 -103.043228)
		(width 0.127)
		(layer "In6.Cu")
		(net "RST_PLD_CPU1_DRAM_EF_N")
	)
	(segment
		(start 171.61002 -104.170988)
		(end 169.3164 -104.170988)
		(width 0.127)
		(layer "In6.Cu")
		(net "RST_PLD_CPU1_DRAM_EF_N")
	)
	(segment
		(start 108.24718 -103.662988)
		(end 107.2769 -102.692708)
		(width 0.127)
		(layer "In6.Cu")
		(net "RST_PLD_CPU1_DRAM_EF_N")
	)
	(segment
		(start 102.04958 -103.703628)
		(end 100.09632 -101.750368)
		(width 0.127)
		(layer "In6.Cu")
		(net "RST_PLD_CPU1_DRAM_EF_N")
	)
	(segment
		(start 119.65686 -98.189288)
		(end 116.39296 -101.453188)
		(width 0.127)
		(layer "In6.Cu")
		(net "RST_PLD_CPU1_DRAM_EF_N")
	)
	(segment
		(start 172.955712 -106.175302)
		(end 172.55236 -105.77195)
		(width 0.127)
		(layer "In6.Cu")
		(net "RST_PLD_CPU1_DRAM_EF_N")
	)
	(segment
		(start 113.10874 -101.453188)
		(end 110.89894 -103.662988)
		(width 0.127)
		(layer "In6.Cu")
		(net "RST_PLD_CPU1_DRAM_EF_N")
	)
	(segment
		(start 92.35186 -103.561388)
		(end 88.2904 -103.561388)
		(width 0.127)
		(layer "In6.Cu")
		(net "RST_PLD_CPU1_DRAM_EF_N")
	)
	(segment
		(start 92.87002 -103.043228)
		(end 92.35186 -103.561388)
		(width 0.127)
		(layer "In6.Cu")
		(net "RST_PLD_CPU1_DRAM_EF_N")
	)
	(segment
		(start 100.09632 -101.750368)
		(end 96.44888 -101.750368)
		(width 0.127)
		(layer "In6.Cu")
		(net "RST_PLD_CPU1_DRAM_EF_N")
	)
	(segment
		(start 169.3164 -104.170988)
		(end 168.33596 -103.190548)
		(width 0.127)
		(layer "In6.Cu")
		(net "RST_PLD_CPU1_DRAM_EF_N")
	)
	(segment
		(start 166.6875 -103.127048)
		(end 143.756126 -103.127048)
		(width 0.127)
		(layer "In6.Cu")
		(net "RST_PLD_CPU1_DRAM_EF_N")
	)
	(segment
		(start 110.89894 -103.662988)
		(end 108.24718 -103.662988)
		(width 0.127)
		(layer "In6.Cu")
		(net "RST_PLD_CPU1_DRAM_EF_N")
	)
	(segment
		(start 102.90556 -103.703628)
		(end 102.04958 -103.703628)
		(width 0.127)
		(layer "In6.Cu")
		(net "RST_PLD_CPU1_DRAM_EF_N")
	)
	(segment
		(start 107.2769 -102.692708)
		(end 103.91648 -102.692708)
		(width 0.127)
		(layer "In6.Cu")
		(net "RST_PLD_CPU1_DRAM_EF_N")
	)
	(segment
		(start 172.55236 -105.77195)
		(end 172.55236 -105.113328)
		(width 0.127)
		(layer "In6.Cu")
		(net "RST_PLD_CPU1_DRAM_EF_N")
	)
	(segment
		(start 86.526116 -99.477322)
		(end 87.211916 -99.477322)
		(width 0.12954)
		(layer "F.Cu")
		(net "RST_PLD_CPU1_DRAM_CD_N")
	)
	(segment
		(start 173.355762 -105.775506)
		(end 172.955712 -105.375456)
		(width 0.12954)
		(layer "F.Cu")
		(net "RST_PLD_CPU1_DRAM_CD_N")
	)
	(via
		(at 172.955712 -105.375456)
		(size 0.4572)
		(drill 0.254)
		(layers "F.Cu" "B.Cu")
		(net "RST_PLD_CPU1_DRAM_CD_N")
	)
	(via
		(at 87.211916 -99.477322)
		(size 0.508)
		(drill 0.254)
		(layers "F.Cu" "B.Cu")
		(net "RST_PLD_CPU1_DRAM_CD_N")
	)
	(segment
		(start 19.0119 -163.746688)
		(end 14.889988 -167.8686)
		(width 0.12954)
		(layer "B.Cu")
		(net "RST_PLD_CPU1_DRAM_CD_N")
	)
	(segment
		(start 25.343866 -192.752726)
		(end 24.327866 -192.752726)
		(width 0.12954)
		(layer "B.Cu")
		(net "RST_PLD_CPU1_DRAM_CD_N")
	)
	(segment
		(start 32.32658 -140.594588)
		(end 19.0119 -153.909268)
		(width 0.12954)
		(layer "B.Cu")
		(net "RST_PLD_CPU1_DRAM_CD_N")
	)
	(segment
		(start 16.551148 -190.261748)
		(end 20.724876 -190.261748)
		(width 0.12954)
		(layer "B.Cu")
		(net "RST_PLD_CPU1_DRAM_CD_N")
	)
	(segment
		(start 23.215854 -192.752726)
		(end 24.327866 -192.752726)
		(width 0.12954)
		(layer "B.Cu")
		(net "RST_PLD_CPU1_DRAM_CD_N")
	)
	(segment
		(start 19.0119 -153.909268)
		(end 19.0119 -163.746688)
		(width 0.12954)
		(layer "B.Cu")
		(net "RST_PLD_CPU1_DRAM_CD_N")
	)
	(segment
		(start 20.724876 -190.261748)
		(end 23.215854 -192.752726)
		(width 0.12954)
		(layer "B.Cu")
		(net "RST_PLD_CPU1_DRAM_CD_N")
	)
	(segment
		(start 6.66496 -167.8686)
		(end 6.08076 -168.4528)
		(width 0.12954)
		(layer "B.Cu")
		(net "RST_PLD_CPU1_DRAM_CD_N")
	)
	(segment
		(start 87.211916 -99.477322)
		(end 85.968586 -99.477322)
		(width 0.12954)
		(layer "B.Cu")
		(net "RST_PLD_CPU1_DRAM_CD_N")
	)
	(segment
		(start 26.359866 -192.752726)
		(end 25.343866 -192.752726)
		(width 0.12954)
		(layer "B.Cu")
		(net "RST_PLD_CPU1_DRAM_CD_N")
	)
	(segment
		(start 84.02066 -101.425248)
		(end 84.02066 -128.664208)
		(width 0.12954)
		(layer "B.Cu")
		(net "RST_PLD_CPU1_DRAM_CD_N")
	)
	(segment
		(start 6.08076 -168.4528)
		(end 6.08076 -173.72076)
		(width 0.12954)
		(layer "B.Cu")
		(net "RST_PLD_CPU1_DRAM_CD_N")
	)
	(segment
		(start 6.08076 -173.72076)
		(end 15.748 -183.388)
		(width 0.12954)
		(layer "B.Cu")
		(net "RST_PLD_CPU1_DRAM_CD_N")
	)
	(segment
		(start 15.748 -183.388)
		(end 15.748 -189.4586)
		(width 0.12954)
		(layer "B.Cu")
		(net "RST_PLD_CPU1_DRAM_CD_N")
	)
	(segment
		(start 72.09028 -140.594588)
		(end 32.32658 -140.594588)
		(width 0.12954)
		(layer "B.Cu")
		(net "RST_PLD_CPU1_DRAM_CD_N")
	)
	(segment
		(start 84.02066 -128.664208)
		(end 72.09028 -140.594588)
		(width 0.12954)
		(layer "B.Cu")
		(net "RST_PLD_CPU1_DRAM_CD_N")
	)
	(segment
		(start 85.968586 -99.477322)
		(end 84.02066 -101.425248)
		(width 0.12954)
		(layer "B.Cu")
		(net "RST_PLD_CPU1_DRAM_CD_N")
	)
	(segment
		(start 15.748 -189.4586)
		(end 16.551148 -190.261748)
		(width 0.12954)
		(layer "B.Cu")
		(net "RST_PLD_CPU1_DRAM_CD_N")
	)
	(segment
		(start 14.889988 -167.8686)
		(end 6.66496 -167.8686)
		(width 0.12954)
		(layer "B.Cu")
		(net "RST_PLD_CPU1_DRAM_CD_N")
	)
	(segment
		(start 96.30664 -100.856288)
		(end 93.2561 -100.856288)
		(width 0.127)
		(layer "In6.Cu")
		(net "RST_PLD_CPU1_DRAM_CD_N")
	)
	(segment
		(start 167.07104 -102.156768)
		(end 166.42842 -101.514148)
		(width 0.127)
		(layer "In6.Cu")
		(net "RST_PLD_CPU1_DRAM_CD_N")
	)
	(segment
		(start 115.89258 -96.853248)
		(end 111.0234 -101.722428)
		(width 0.127)
		(layer "In6.Cu")
		(net "RST_PLD_CPU1_DRAM_CD_N")
	)
	(segment
		(start 159.8676 -101.666548)
		(end 145.8595 -101.666548)
		(width 0.127)
		(layer "In6.Cu")
		(net "RST_PLD_CPU1_DRAM_CD_N")
	)
	(segment
		(start 86.771226 -99.477322)
		(end 87.211916 -99.477322)
		(width 0.127)
		(layer "In6.Cu")
		(net "RST_PLD_CPU1_DRAM_CD_N")
	)
	(segment
		(start 139.80541 -96.853248)
		(end 115.89258 -96.853248)
		(width 0.127)
		(layer "In6.Cu")
		(net "RST_PLD_CPU1_DRAM_CD_N")
	)
	(segment
		(start 84.48548 -103.962708)
		(end 84.07146 -103.548688)
		(width 0.127)
		(layer "In6.Cu")
		(net "RST_PLD_CPU1_DRAM_CD_N")
	)
	(segment
		(start 111.0234 -101.722428)
		(end 103.64216 -101.722428)
		(width 0.127)
		(layer "In6.Cu")
		(net "RST_PLD_CPU1_DRAM_CD_N")
	)
	(segment
		(start 164.3888 -102.022148)
		(end 163.6395 -101.272848)
		(width 0.127)
		(layer "In6.Cu")
		(net "RST_PLD_CPU1_DRAM_CD_N")
	)
	(segment
		(start 100.62972 -98.709988)
		(end 98.45294 -98.709988)
		(width 0.127)
		(layer "In6.Cu")
		(net "RST_PLD_CPU1_DRAM_CD_N")
	)
	(segment
		(start 172.5168 -104.391968)
		(end 172.5168 -103.492808)
		(width 0.127)
		(layer "In6.Cu")
		(net "RST_PLD_CPU1_DRAM_CD_N")
	)
	(segment
		(start 164.6047 -102.022148)
		(end 164.3888 -102.022148)
		(width 0.127)
		(layer "In6.Cu")
		(net "RST_PLD_CPU1_DRAM_CD_N")
	)
	(segment
		(start 86.3854 -103.962708)
		(end 84.48548 -103.962708)
		(width 0.127)
		(layer "In6.Cu")
		(net "RST_PLD_CPU1_DRAM_CD_N")
	)
	(segment
		(start 172.5168 -103.492808)
		(end 172.21454 -103.190548)
		(width 0.127)
		(layer "In6.Cu")
		(net "RST_PLD_CPU1_DRAM_CD_N")
	)
	(segment
		(start 92.09278 -102.019608)
		(end 88.3285 -102.019608)
		(width 0.127)
		(layer "In6.Cu")
		(net "RST_PLD_CPU1_DRAM_CD_N")
	)
	(segment
		(start 144.86636 -100.673408)
		(end 143.62557 -100.673408)
		(width 0.127)
		(layer "In6.Cu")
		(net "RST_PLD_CPU1_DRAM_CD_N")
	)
	(segment
		(start 166.42842 -101.514148)
		(end 165.1127 -101.514148)
		(width 0.127)
		(layer "In6.Cu")
		(net "RST_PLD_CPU1_DRAM_CD_N")
	)
	(segment
		(start 165.1127 -101.514148)
		(end 164.6047 -102.022148)
		(width 0.127)
		(layer "In6.Cu")
		(net "RST_PLD_CPU1_DRAM_CD_N")
	)
	(segment
		(start 162.0647 -101.272848)
		(end 161.2646 -102.072948)
		(width 0.127)
		(layer "In6.Cu")
		(net "RST_PLD_CPU1_DRAM_CD_N")
	)
	(segment
		(start 84.07146 -102.177088)
		(end 86.771226 -99.477322)
		(width 0.127)
		(layer "In6.Cu")
		(net "RST_PLD_CPU1_DRAM_CD_N")
	)
	(segment
		(start 172.955712 -104.83088)
		(end 172.5168 -104.391968)
		(width 0.127)
		(layer "In6.Cu")
		(net "RST_PLD_CPU1_DRAM_CD_N")
	)
	(segment
		(start 172.955712 -105.375456)
		(end 172.955712 -104.83088)
		(width 0.127)
		(layer "In6.Cu")
		(net "RST_PLD_CPU1_DRAM_CD_N")
	)
	(segment
		(start 145.8595 -101.666548)
		(end 144.86636 -100.673408)
		(width 0.127)
		(layer "In6.Cu")
		(net "RST_PLD_CPU1_DRAM_CD_N")
	)
	(segment
		(start 88.3285 -102.019608)
		(end 86.3854 -103.962708)
		(width 0.127)
		(layer "In6.Cu")
		(net "RST_PLD_CPU1_DRAM_CD_N")
	)
	(segment
		(start 161.2646 -102.072948)
		(end 160.274 -102.072948)
		(width 0.127)
		(layer "In6.Cu")
		(net "RST_PLD_CPU1_DRAM_CD_N")
	)
	(segment
		(start 172.21454 -103.190548)
		(end 169.62882 -103.190548)
		(width 0.127)
		(layer "In6.Cu")
		(net "RST_PLD_CPU1_DRAM_CD_N")
	)
	(segment
		(start 168.59504 -102.156768)
		(end 167.07104 -102.156768)
		(width 0.127)
		(layer "In6.Cu")
		(net "RST_PLD_CPU1_DRAM_CD_N")
	)
	(segment
		(start 98.45294 -98.709988)
		(end 96.30664 -100.856288)
		(width 0.127)
		(layer "In6.Cu")
		(net "RST_PLD_CPU1_DRAM_CD_N")
	)
	(segment
		(start 163.6395 -101.272848)
		(end 162.0647 -101.272848)
		(width 0.127)
		(layer "In6.Cu")
		(net "RST_PLD_CPU1_DRAM_CD_N")
	)
	(segment
		(start 103.64216 -101.722428)
		(end 100.62972 -98.709988)
		(width 0.127)
		(layer "In6.Cu")
		(net "RST_PLD_CPU1_DRAM_CD_N")
	)
	(segment
		(start 160.274 -102.072948)
		(end 159.8676 -101.666548)
		(width 0.127)
		(layer "In6.Cu")
		(net "RST_PLD_CPU1_DRAM_CD_N")
	)
	(segment
		(start 143.62557 -100.673408)
		(end 139.80541 -96.853248)
		(width 0.127)
		(layer "In6.Cu")
		(net "RST_PLD_CPU1_DRAM_CD_N")
	)
	(segment
		(start 93.2561 -100.856288)
		(end 92.09278 -102.019608)
		(width 0.127)
		(layer "In6.Cu")
		(net "RST_PLD_CPU1_DRAM_CD_N")
	)
	(segment
		(start 84.07146 -103.548688)
		(end 84.07146 -102.177088)
		(width 0.127)
		(layer "In6.Cu")
		(net "RST_PLD_CPU1_DRAM_CD_N")
	)
	(segment
		(start 169.62882 -103.190548)
		(end 168.59504 -102.156768)
		(width 0.127)
		(layer "In6.Cu")
		(net "RST_PLD_CPU1_DRAM_CD_N")
	)
	(segment
		(start 172.44822 -98.468688)
		(end 171.50334 -97.523808)
		(width 0.12954)
		(layer "F.Cu")
		(net "RST_PLD_CPU1_DRAM_AB_N")
	)
	(segment
		(start 172.555662 -104.975406)
		(end 173.41088 -104.120188)
		(width 0.12954)
		(layer "F.Cu")
		(net "RST_PLD_CPU1_DRAM_AB_N")
	)
	(segment
		(start 94.0308 -104.033828)
		(end 94.0308 -103.033322)
		(width 0.12954)
		(layer "F.Cu")
		(net "RST_PLD_CPU1_DRAM_AB_N")
	)
	(segment
		(start 94.756986 -102.697788)
		(end 94.9452 -102.509574)
		(width 0.12954)
		(layer "F.Cu")
		(net "RST_PLD_CPU1_DRAM_AB_N")
	)
	(segment
		(start 173.41088 -104.120188)
		(end 173.41088 -102.617016)
		(width 0.12954)
		(layer "F.Cu")
		(net "RST_PLD_CPU1_DRAM_AB_N")
	)
	(segment
		(start 94.0308 -103.033322)
		(end 94.366334 -102.697788)
		(width 0.12954)
		(layer "F.Cu")
		(net "RST_PLD_CPU1_DRAM_AB_N")
	)
	(segment
		(start 160.60674 -97.523808)
		(end 157.91688 -94.833948)
		(width 0.12954)
		(layer "F.Cu")
		(net "RST_PLD_CPU1_DRAM_AB_N")
	)
	(segment
		(start 172.44822 -100.777548)
		(end 172.44822 -98.468688)
		(width 0.12954)
		(layer "F.Cu")
		(net "RST_PLD_CPU1_DRAM_AB_N")
	)
	(segment
		(start 172.790866 -101.120194)
		(end 172.44822 -100.777548)
		(width 0.12954)
		(layer "F.Cu")
		(net "RST_PLD_CPU1_DRAM_AB_N")
	)
	(segment
		(start 173.41088 -102.617016)
		(end 172.790866 -101.120194)
		(width 0.12954)
		(layer "F.Cu")
		(net "RST_PLD_CPU1_DRAM_AB_N")
	)
	(segment
		(start 94.366334 -102.697788)
		(end 94.756986 -102.697788)
		(width 0.12954)
		(layer "F.Cu")
		(net "RST_PLD_CPU1_DRAM_AB_N")
	)
	(segment
		(start 171.50334 -97.523808)
		(end 160.60674 -97.523808)
		(width 0.12954)
		(layer "F.Cu")
		(net "RST_PLD_CPU1_DRAM_AB_N")
	)
	(via
		(at 94.0308 -104.033828)
		(size 0.508)
		(drill 0.254)
		(layers "F.Cu" "B.Cu")
		(net "RST_PLD_CPU1_DRAM_AB_N")
	)
	(via
		(at 157.91688 -94.833948)
		(size 0.508)
		(drill 0.254)
		(layers "F.Cu" "B.Cu")
		(net "RST_PLD_CPU1_DRAM_AB_N")
	)
	(via
		(at 16.23822 -187.7822)
		(size 0.508)
		(drill 0.254)
		(layers "F.Cu" "B.Cu")
		(net "RST_PLD_CPU1_DRAM_AB_N")
	)
	(segment
		(start 24.215598 -190.57239)
		(end 31.010098 -190.57239)
		(width 0.12954)
		(layer "B.Cu")
		(net "RST_PLD_CPU1_DRAM_AB_N")
	)
	(segment
		(start 32.961834 -192.524126)
		(end 34.551366 -192.524126)
		(width 0.12954)
		(layer "B.Cu")
		(net "RST_PLD_CPU1_DRAM_AB_N")
	)
	(segment
		(start 36.583366 -192.524126)
		(end 35.567366 -192.524126)
		(width 0.12954)
		(layer "B.Cu")
		(net "RST_PLD_CPU1_DRAM_AB_N")
	)
	(segment
		(start 34.551366 -192.524126)
		(end 35.567366 -192.524126)
		(width 0.12954)
		(layer "B.Cu")
		(net "RST_PLD_CPU1_DRAM_AB_N")
	)
	(segment
		(start 16.9418 -186.294268)
		(end 20.547076 -186.294268)
		(width 0.12954)
		(layer "B.Cu")
		(net "RST_PLD_CPU1_DRAM_AB_N")
	)
	(segment
		(start 16.8148 -186.421268)
		(end 16.9418 -186.294268)
		(width 0.12954)
		(layer "B.Cu")
		(net "RST_PLD_CPU1_DRAM_AB_N")
	)
	(segment
		(start 22.486874 -188.843666)
		(end 24.215598 -190.57239)
		(width 0.12954)
		(layer "B.Cu")
		(net "RST_PLD_CPU1_DRAM_AB_N")
	)
	(segment
		(start 31.010098 -190.57239)
		(end 32.961834 -192.524126)
		(width 0.12954)
		(layer "B.Cu")
		(net "RST_PLD_CPU1_DRAM_AB_N")
	)
	(segment
		(start 20.547076 -186.294268)
		(end 22.486874 -188.234066)
		(width 0.12954)
		(layer "B.Cu")
		(net "RST_PLD_CPU1_DRAM_AB_N")
	)
	(segment
		(start 16.8148 -187.20562)
		(end 16.8148 -186.421268)
		(width 0.12954)
		(layer "B.Cu")
		(net "RST_PLD_CPU1_DRAM_AB_N")
	)
	(segment
		(start 16.23822 -187.7822)
		(end 16.8148 -187.20562)
		(width 0.12954)
		(layer "B.Cu")
		(net "RST_PLD_CPU1_DRAM_AB_N")
	)
	(segment
		(start 22.486874 -188.234066)
		(end 22.486874 -188.843666)
		(width 0.12954)
		(layer "B.Cu")
		(net "RST_PLD_CPU1_DRAM_AB_N")
	)
	(segment
		(start 111.09706 -97.907348)
		(end 99.42068 -97.907348)
		(width 0.127)
		(layer "In4.Cu")
		(net "RST_PLD_CPU1_DRAM_AB_N")
	)
	(segment
		(start 99.42068 -97.907348)
		(end 95.70466 -101.623368)
		(width 0.127)
		(layer "In4.Cu")
		(net "RST_PLD_CPU1_DRAM_AB_N")
	)
	(segment
		(start 145.72488 -87.721948)
		(end 121.28246 -87.721948)
		(width 0.127)
		(layer "In4.Cu")
		(net "RST_PLD_CPU1_DRAM_AB_N")
	)
	(segment
		(start 157.91688 -95.596964)
		(end 157.585664 -95.92818)
		(width 0.127)
		(layer "In4.Cu")
		(net "RST_PLD_CPU1_DRAM_AB_N")
	)
	(segment
		(start 157.585664 -95.92818)
		(end 153.931112 -95.92818)
		(width 0.127)
		(layer "In4.Cu")
		(net "RST_PLD_CPU1_DRAM_AB_N")
	)
	(segment
		(start 95.70466 -101.623368)
		(end 95.70466 -103.655368)
		(width 0.127)
		(layer "In4.Cu")
		(net "RST_PLD_CPU1_DRAM_AB_N")
	)
	(segment
		(start 153.931112 -95.92818)
		(end 145.72488 -87.721948)
		(width 0.127)
		(layer "In4.Cu")
		(net "RST_PLD_CPU1_DRAM_AB_N")
	)
	(segment
		(start 121.28246 -87.721948)
		(end 111.09706 -97.907348)
		(width 0.127)
		(layer "In4.Cu")
		(net "RST_PLD_CPU1_DRAM_AB_N")
	)
	(segment
		(start 157.91688 -94.833948)
		(end 157.91688 -95.596964)
		(width 0.127)
		(layer "In4.Cu")
		(net "RST_PLD_CPU1_DRAM_AB_N")
	)
	(segment
		(start 95.70466 -103.655368)
		(end 95.3262 -104.033828)
		(width 0.127)
		(layer "In4.Cu")
		(net "RST_PLD_CPU1_DRAM_AB_N")
	)
	(segment
		(start 95.3262 -104.033828)
		(end 94.0308 -104.033828)
		(width 0.127)
		(layer "In4.Cu")
		(net "RST_PLD_CPU1_DRAM_AB_N")
	)
	(segment
		(start 44.78528 -116.169948)
		(end 49.17948 -120.564148)
		(width 0.127)
		(layer "In6.Cu")
		(net "RST_PLD_CPU1_DRAM_AB_N")
	)
	(segment
		(start 16.41094 -186.05754)
		(end 16.41094 -184.595008)
		(width 0.127)
		(layer "In6.Cu")
		(net "RST_PLD_CPU1_DRAM_AB_N")
	)
	(segment
		(start 7.42188 -132.573268)
		(end 22.5298 -117.465348)
		(width 0.127)
		(layer "In6.Cu")
		(net "RST_PLD_CPU1_DRAM_AB_N")
	)
	(segment
		(start 94.0308 -105.036112)
		(end 94.0308 -104.033828)
		(width 0.127)
		(layer "In6.Cu")
		(net "RST_PLD_CPU1_DRAM_AB_N")
	)
	(segment
		(start 78.97749 -106.077258)
		(end 92.989654 -106.077258)
		(width 0.127)
		(layer "In6.Cu")
		(net "RST_PLD_CPU1_DRAM_AB_N")
	)
	(segment
		(start 49.17948 -120.564148)
		(end 64.4906 -120.564148)
		(width 0.127)
		(layer "In6.Cu")
		(net "RST_PLD_CPU1_DRAM_AB_N")
	)
	(segment
		(start 29.972 -116.169948)
		(end 44.78528 -116.169948)
		(width 0.127)
		(layer "In6.Cu")
		(net "RST_PLD_CPU1_DRAM_AB_N")
	)
	(segment
		(start 92.989654 -106.077258)
		(end 94.0308 -105.036112)
		(width 0.127)
		(layer "In6.Cu")
		(net "RST_PLD_CPU1_DRAM_AB_N")
	)
	(segment
		(start 16.8148 -186.4614)
		(end 16.41094 -186.05754)
		(width 0.127)
		(layer "In6.Cu")
		(net "RST_PLD_CPU1_DRAM_AB_N")
	)
	(segment
		(start 15.808198 -152.444958)
		(end 13.294614 -152.444958)
		(width 0.127)
		(layer "In6.Cu")
		(net "RST_PLD_CPU1_DRAM_AB_N")
	)
	(segment
		(start 16.8148 -187.20562)
		(end 16.8148 -186.4614)
		(width 0.127)
		(layer "In6.Cu")
		(net "RST_PLD_CPU1_DRAM_AB_N")
	)
	(segment
		(start 16.716756 -153.353516)
		(end 15.808198 -152.444958)
		(width 0.127)
		(layer "In6.Cu")
		(net "RST_PLD_CPU1_DRAM_AB_N")
	)
	(segment
		(start 16.41094 -184.595008)
		(end 15.75308 -183.937148)
		(width 0.127)
		(layer "In6.Cu")
		(net "RST_PLD_CPU1_DRAM_AB_N")
	)
	(segment
		(start 28.6766 -117.465348)
		(end 29.972 -116.169948)
		(width 0.127)
		(layer "In6.Cu")
		(net "RST_PLD_CPU1_DRAM_AB_N")
	)
	(segment
		(start 15.75308 -168.341548)
		(end 16.716756 -167.377872)
		(width 0.127)
		(layer "In6.Cu")
		(net "RST_PLD_CPU1_DRAM_AB_N")
	)
	(segment
		(start 7.42188 -153.380948)
		(end 7.42188 -132.573268)
		(width 0.127)
		(layer "In6.Cu")
		(net "RST_PLD_CPU1_DRAM_AB_N")
	)
	(segment
		(start 16.23822 -187.7822)
		(end 16.8148 -187.20562)
		(width 0.127)
		(layer "In6.Cu")
		(net "RST_PLD_CPU1_DRAM_AB_N")
	)
	(segment
		(start 8.00608 -153.965148)
		(end 7.42188 -153.380948)
		(width 0.127)
		(layer "In6.Cu")
		(net "RST_PLD_CPU1_DRAM_AB_N")
	)
	(segment
		(start 13.294614 -152.444958)
		(end 11.774424 -153.965148)
		(width 0.127)
		(layer "In6.Cu")
		(net "RST_PLD_CPU1_DRAM_AB_N")
	)
	(segment
		(start 16.716756 -167.377872)
		(end 16.716756 -153.353516)
		(width 0.127)
		(layer "In6.Cu")
		(net "RST_PLD_CPU1_DRAM_AB_N")
	)
	(segment
		(start 15.75308 -183.937148)
		(end 15.75308 -168.341548)
		(width 0.127)
		(layer "In6.Cu")
		(net "RST_PLD_CPU1_DRAM_AB_N")
	)
	(segment
		(start 11.774424 -153.965148)
		(end 8.00608 -153.965148)
		(width 0.127)
		(layer "In6.Cu")
		(net "RST_PLD_CPU1_DRAM_AB_N")
	)
	(segment
		(start 64.4906 -120.564148)
		(end 78.97749 -106.077258)
		(width 0.127)
		(layer "In6.Cu")
		(net "RST_PLD_CPU1_DRAM_AB_N")
	)
	(segment
		(start 22.5298 -117.465348)
		(end 28.6766 -117.465348)
		(width 0.127)
		(layer "In6.Cu")
		(net "RST_PLD_CPU1_DRAM_AB_N")
	)
	(segment
		(start 95.631 -96.176846)
		(end 94.9452 -96.176846)
		(width 0.12954)
		(layer "F.Cu")
		(net "RST_PLD_CPU0_DRAM_GH_N")
	)
	(segment
		(start 175.755554 -108.975398)
		(end 175.355504 -108.575348)
		(width 0.12954)
		(layer "F.Cu")
		(net "RST_PLD_CPU0_DRAM_GH_N")
	)
	(via
		(at 427.17974 -191.25057)
		(size 0.508)
		(drill 0.254)
		(layers "F.Cu" "B.Cu")
		(net "RST_PLD_CPU0_DRAM_GH_N")
	)
	(via
		(at 373.13108 -164.363908)
		(size 0.508)
		(drill 0.254)
		(layers "F.Cu" "B.Cu")
		(net "RST_PLD_CPU0_DRAM_GH_N")
	)
	(via
		(at 175.355504 -108.575348)
		(size 0.4572)
		(drill 0.254)
		(layers "F.Cu" "B.Cu")
		(net "RST_PLD_CPU0_DRAM_GH_N")
	)
	(via
		(at 95.631 -96.176846)
		(size 0.508)
		(drill 0.254)
		(layers "F.Cu" "B.Cu")
		(net "RST_PLD_CPU0_DRAM_GH_N")
	)
	(segment
		(start 427.17974 -191.25057)
		(end 431.679604 -191.25057)
		(width 0.12954)
		(layer "B.Cu")
		(net "RST_PLD_CPU0_DRAM_GH_N")
	)
	(segment
		(start 433.564792 -193.165222)
		(end 433.566824 -193.167254)
		(width 0.12954)
		(layer "B.Cu")
		(net "RST_PLD_CPU0_DRAM_GH_N")
	)
	(segment
		(start 433.566824 -193.167254)
		(end 434.57241 -193.167254)
		(width 0.12954)
		(layer "B.Cu")
		(net "RST_PLD_CPU0_DRAM_GH_N")
	)
	(segment
		(start 433.564792 -193.165222)
		(end 432.523392 -193.165222)
		(width 0.12954)
		(layer "B.Cu")
		(net "RST_PLD_CPU0_DRAM_GH_N")
	)
	(segment
		(start 431.679604 -191.25057)
		(end 432.523392 -192.094358)
		(width 0.12954)
		(layer "B.Cu")
		(net "RST_PLD_CPU0_DRAM_GH_N")
	)
	(segment
		(start 432.523392 -192.094358)
		(end 432.523392 -193.165222)
		(width 0.12954)
		(layer "B.Cu")
		(net "RST_PLD_CPU0_DRAM_GH_N")
	)
	(segment
		(start 393.937236 -174.018448)
		(end 385.35356 -174.018448)
		(width 0.127)
		(layer "In2.Cu")
		(net "RST_PLD_CPU0_DRAM_GH_N")
	)
	(segment
		(start 394.613638 -183.81345)
		(end 395.529308 -182.89778)
		(width 0.127)
		(layer "In2.Cu")
		(net "RST_PLD_CPU0_DRAM_GH_N")
	)
	(segment
		(start 427.17974 -191.25057)
		(end 421.960548 -191.25057)
		(width 0.127)
		(layer "In2.Cu")
		(net "RST_PLD_CPU0_DRAM_GH_N")
	)
	(segment
		(start 395.529308 -182.89778)
		(end 395.529308 -175.61052)
		(width 0.127)
		(layer "In2.Cu")
		(net "RST_PLD_CPU0_DRAM_GH_N")
	)
	(segment
		(start 395.529308 -175.61052)
		(end 393.937236 -174.018448)
		(width 0.127)
		(layer "In2.Cu")
		(net "RST_PLD_CPU0_DRAM_GH_N")
	)
	(segment
		(start 395.61643 -188.710062)
		(end 394.613638 -187.70727)
		(width 0.127)
		(layer "In2.Cu")
		(net "RST_PLD_CPU0_DRAM_GH_N")
	)
	(segment
		(start 394.613638 -187.70727)
		(end 394.613638 -183.81345)
		(width 0.127)
		(layer "In2.Cu")
		(net "RST_PLD_CPU0_DRAM_GH_N")
	)
	(segment
		(start 421.073326 -190.363348)
		(end 407.014426 -190.363348)
		(width 0.127)
		(layer "In2.Cu")
		(net "RST_PLD_CPU0_DRAM_GH_N")
	)
	(segment
		(start 375.9454 -164.610288)
		(end 373.37746 -164.610288)
		(width 0.127)
		(layer "In2.Cu")
		(net "RST_PLD_CPU0_DRAM_GH_N")
	)
	(segment
		(start 421.960548 -191.25057)
		(end 421.073326 -190.363348)
		(width 0.127)
		(layer "In2.Cu")
		(net "RST_PLD_CPU0_DRAM_GH_N")
	)
	(segment
		(start 405.36114 -188.710062)
		(end 395.61643 -188.710062)
		(width 0.127)
		(layer "In2.Cu")
		(net "RST_PLD_CPU0_DRAM_GH_N")
	)
	(segment
		(start 385.35356 -174.018448)
		(end 375.9454 -164.610288)
		(width 0.127)
		(layer "In2.Cu")
		(net "RST_PLD_CPU0_DRAM_GH_N")
	)
	(segment
		(start 407.014426 -190.363348)
		(end 405.36114 -188.710062)
		(width 0.127)
		(layer "In2.Cu")
		(net "RST_PLD_CPU0_DRAM_GH_N")
	)
	(segment
		(start 373.37746 -164.610288)
		(end 373.13108 -164.363908)
		(width 0.127)
		(layer "In2.Cu")
		(net "RST_PLD_CPU0_DRAM_GH_N")
	)
	(segment
		(start 253.0602 -126.020068)
		(end 246.888 -119.847868)
		(width 0.127)
		(layer "In6.Cu")
		(net "RST_PLD_CPU0_DRAM_GH_N")
	)
	(segment
		(start 103.97236 -94.165928)
		(end 111.6457 -94.165928)
		(width 0.127)
		(layer "In6.Cu")
		(net "RST_PLD_CPU0_DRAM_GH_N")
	)
	(segment
		(start 184.55386 -118.817898)
		(end 184.318402 -118.58244)
		(width 0.127)
		(layer "In6.Cu")
		(net "RST_PLD_CPU0_DRAM_GH_N")
	)
	(segment
		(start 102.0572 -93.703648)
		(end 103.51008 -93.703648)
		(width 0.127)
		(layer "In6.Cu")
		(net "RST_PLD_CPU0_DRAM_GH_N")
	)
	(segment
		(start 253.0602 -130.312668)
		(end 253.0602 -126.020068)
		(width 0.127)
		(layer "In6.Cu")
		(net "RST_PLD_CPU0_DRAM_GH_N")
	)
	(segment
		(start 218.465908 -122.5804)
		(end 207.7466 -122.5804)
		(width 0.127)
		(layer "In6.Cu")
		(net "RST_PLD_CPU0_DRAM_GH_N")
	)
	(segment
		(start 146.273012 -98.186748)
		(end 155.570174 -98.186748)
		(width 0.127)
		(layer "In6.Cu")
		(net "RST_PLD_CPU0_DRAM_GH_N")
	)
	(segment
		(start 187.031376 -119.377968)
		(end 184.77738 -119.377968)
		(width 0.127)
		(layer "In6.Cu")
		(net "RST_PLD_CPU0_DRAM_GH_N")
	)
	(segment
		(start 183.76265 -118.026688)
		(end 183.50865 -117.772688)
		(width 0.127)
		(layer "In6.Cu")
		(net "RST_PLD_CPU0_DRAM_GH_N")
	)
	(segment
		(start 175.73244 -105.776268)
		(end 175.12284 -105.776268)
		(width 0.127)
		(layer "In6.Cu")
		(net "RST_PLD_CPU0_DRAM_GH_N")
	)
	(segment
		(start 369.54714 -162.118548)
		(end 357.251 -149.822408)
		(width 0.127)
		(layer "In6.Cu")
		(net "RST_PLD_CPU0_DRAM_GH_N")
	)
	(segment
		(start 198.658734 -122.3264)
		(end 198.274686 -122.710448)
		(width 0.127)
		(layer "In6.Cu")
		(net "RST_PLD_CPU0_DRAM_GH_N")
	)
	(segment
		(start 192.30086 -122.354848)
		(end 189.28334 -119.337328)
		(width 0.127)
		(layer "In6.Cu")
		(net "RST_PLD_CPU0_DRAM_GH_N")
	)
	(segment
		(start 178.034188 -108.971588)
		(end 175.751744 -108.971588)
		(width 0.127)
		(layer "In6.Cu")
		(net "RST_PLD_CPU0_DRAM_GH_N")
	)
	(segment
		(start 95.631 -96.176846)
		(end 95.631 -94.361)
		(width 0.127)
		(layer "In6.Cu")
		(net "RST_PLD_CPU0_DRAM_GH_N")
	)
	(segment
		(start 223.11868 -117.927628)
		(end 218.465908 -122.5804)
		(width 0.127)
		(layer "In6.Cu")
		(net "RST_PLD_CPU0_DRAM_GH_N")
	)
	(segment
		(start 144.8435 -98.003868)
		(end 146.090132 -98.003868)
		(width 0.127)
		(layer "In6.Cu")
		(net "RST_PLD_CPU0_DRAM_GH_N")
	)
	(segment
		(start 97.79 -92.202)
		(end 100.555552 -92.202)
		(width 0.127)
		(layer "In6.Cu")
		(net "RST_PLD_CPU0_DRAM_GH_N")
	)
	(segment
		(start 178.92522 -113.652808)
		(end 178.3588 -113.086388)
		(width 0.127)
		(layer "In6.Cu")
		(net "RST_PLD_CPU0_DRAM_GH_N")
	)
	(segment
		(start 174.78375 -100.894388)
		(end 175.286162 -101.3968)
		(width 0.127)
		(layer "In6.Cu")
		(net "RST_PLD_CPU0_DRAM_GH_N")
	)
	(segment
		(start 171.878244 -100.071428)
		(end 173.865286 -100.894388)
		(width 0.127)
		(layer "In6.Cu")
		(net "RST_PLD_CPU0_DRAM_GH_N")
	)
	(segment
		(start 178.3588 -109.2962)
		(end 178.034188 -108.971588)
		(width 0.127)
		(layer "In6.Cu")
		(net "RST_PLD_CPU0_DRAM_GH_N")
	)
	(segment
		(start 156.090874 -97.666048)
		(end 167.897048 -97.666048)
		(width 0.127)
		(layer "In6.Cu")
		(net "RST_PLD_CPU0_DRAM_GH_N")
	)
	(segment
		(start 195.263008 -122.710448)
		(end 194.907408 -122.354848)
		(width 0.127)
		(layer "In6.Cu")
		(net "RST_PLD_CPU0_DRAM_GH_N")
	)
	(segment
		(start 167.897048 -97.666048)
		(end 170.302428 -100.071428)
		(width 0.127)
		(layer "In6.Cu")
		(net "RST_PLD_CPU0_DRAM_GH_N")
	)
	(segment
		(start 176.47158 -102.064058)
		(end 176.59858 -102.191058)
		(width 0.127)
		(layer "In6.Cu")
		(net "RST_PLD_CPU0_DRAM_GH_N")
	)
	(segment
		(start 175.751744 -108.971588)
		(end 175.355504 -108.575348)
		(width 0.127)
		(layer "In6.Cu")
		(net "RST_PLD_CPU0_DRAM_GH_N")
	)
	(segment
		(start 176.59858 -104.910128)
		(end 175.73244 -105.776268)
		(width 0.127)
		(layer "In6.Cu")
		(net "RST_PLD_CPU0_DRAM_GH_N")
	)
	(segment
		(start 175.95469 -102.064058)
		(end 176.47158 -102.064058)
		(width 0.127)
		(layer "In6.Cu")
		(net "RST_PLD_CPU0_DRAM_GH_N")
	)
	(segment
		(start 139.956032 -93.1164)
		(end 144.8435 -98.003868)
		(width 0.127)
		(layer "In6.Cu")
		(net "RST_PLD_CPU0_DRAM_GH_N")
	)
	(segment
		(start 194.907408 -122.354848)
		(end 192.30086 -122.354848)
		(width 0.127)
		(layer "In6.Cu")
		(net "RST_PLD_CPU0_DRAM_GH_N")
	)
	(segment
		(start 119.88927 -93.1164)
		(end 139.956032 -93.1164)
		(width 0.127)
		(layer "In6.Cu")
		(net "RST_PLD_CPU0_DRAM_GH_N")
	)
	(segment
		(start 258.14274 -130.736848)
		(end 257.51536 -131.364228)
		(width 0.127)
		(layer "In6.Cu")
		(net "RST_PLD_CPU0_DRAM_GH_N")
	)
	(segment
		(start 184.006744 -118.58244)
		(end 183.76265 -118.338346)
		(width 0.127)
		(layer "In6.Cu")
		(net "RST_PLD_CPU0_DRAM_GH_N")
	)
	(segment
		(start 239.48644 -119.847868)
		(end 237.91418 -118.275608)
		(width 0.127)
		(layer "In6.Cu")
		(net "RST_PLD_CPU0_DRAM_GH_N")
	)
	(segment
		(start 254.11176 -131.364228)
		(end 253.0602 -130.312668)
		(width 0.127)
		(layer "In6.Cu")
		(net "RST_PLD_CPU0_DRAM_GH_N")
	)
	(segment
		(start 324.17766 -130.736848)
		(end 258.14274 -130.736848)
		(width 0.127)
		(layer "In6.Cu")
		(net "RST_PLD_CPU0_DRAM_GH_N")
	)
	(segment
		(start 372.08206 -162.118548)
		(end 369.54714 -162.118548)
		(width 0.127)
		(layer "In6.Cu")
		(net "RST_PLD_CPU0_DRAM_GH_N")
	)
	(segment
		(start 198.274686 -122.710448)
		(end 195.263008 -122.710448)
		(width 0.127)
		(layer "In6.Cu")
		(net "RST_PLD_CPU0_DRAM_GH_N")
	)
	(segment
		(start 332.232 -138.791188)
		(end 324.17766 -130.736848)
		(width 0.127)
		(layer "In6.Cu")
		(net "RST_PLD_CPU0_DRAM_GH_N")
	)
	(segment
		(start 175.5648 -107.381548)
		(end 175.748442 -107.56519)
		(width 0.127)
		(layer "In6.Cu")
		(net "RST_PLD_CPU0_DRAM_GH_N")
	)
	(segment
		(start 179.1462 -117.772688)
		(end 178.92522 -117.551708)
		(width 0.127)
		(layer "In6.Cu")
		(net "RST_PLD_CPU0_DRAM_GH_N")
	)
	(segment
		(start 173.865286 -100.894388)
		(end 174.78375 -100.894388)
		(width 0.127)
		(layer "In6.Cu")
		(net "RST_PLD_CPU0_DRAM_GH_N")
	)
	(segment
		(start 175.286162 -101.3968)
		(end 175.287432 -101.3968)
		(width 0.127)
		(layer "In6.Cu")
		(net "RST_PLD_CPU0_DRAM_GH_N")
	)
	(segment
		(start 119.531638 -93.474032)
		(end 119.88927 -93.1164)
		(width 0.127)
		(layer "In6.Cu")
		(net "RST_PLD_CPU0_DRAM_GH_N")
	)
	(segment
		(start 339.3059 -138.791188)
		(end 332.232 -138.791188)
		(width 0.127)
		(layer "In6.Cu")
		(net "RST_PLD_CPU0_DRAM_GH_N")
	)
	(segment
		(start 184.318402 -118.58244)
		(end 184.006744 -118.58244)
		(width 0.127)
		(layer "In6.Cu")
		(net "RST_PLD_CPU0_DRAM_GH_N")
	)
	(segment
		(start 232.97642 -117.927628)
		(end 223.11868 -117.927628)
		(width 0.127)
		(layer "In6.Cu")
		(net "RST_PLD_CPU0_DRAM_GH_N")
	)
	(segment
		(start 199.22363 -122.3264)
		(end 198.658734 -122.3264)
		(width 0.127)
		(layer "In6.Cu")
		(net "RST_PLD_CPU0_DRAM_GH_N")
	)
	(segment
		(start 170.302428 -100.071428)
		(end 171.878244 -100.071428)
		(width 0.127)
		(layer "In6.Cu")
		(net "RST_PLD_CPU0_DRAM_GH_N")
	)
	(segment
		(start 155.570174 -98.186748)
		(end 156.090874 -97.666048)
		(width 0.127)
		(layer "In6.Cu")
		(net "RST_PLD_CPU0_DRAM_GH_N")
	)
	(segment
		(start 103.51008 -93.703648)
		(end 103.97236 -94.165928)
		(width 0.127)
		(layer "In6.Cu")
		(net "RST_PLD_CPU0_DRAM_GH_N")
	)
	(segment
		(start 233.3244 -118.275608)
		(end 232.97642 -117.927628)
		(width 0.127)
		(layer "In6.Cu")
		(net "RST_PLD_CPU0_DRAM_GH_N")
	)
	(segment
		(start 237.91418 -118.275608)
		(end 233.3244 -118.275608)
		(width 0.127)
		(layer "In6.Cu")
		(net "RST_PLD_CPU0_DRAM_GH_N")
	)
	(segment
		(start 146.090132 -98.003868)
		(end 146.273012 -98.186748)
		(width 0.127)
		(layer "In6.Cu")
		(net "RST_PLD_CPU0_DRAM_GH_N")
	)
	(segment
		(start 175.12284 -105.776268)
		(end 174.95012 -105.948988)
		(width 0.127)
		(layer "In6.Cu")
		(net "RST_PLD_CPU0_DRAM_GH_N")
	)
	(segment
		(start 175.748442 -107.56519)
		(end 175.748442 -108.18241)
		(width 0.127)
		(layer "In6.Cu")
		(net "RST_PLD_CPU0_DRAM_GH_N")
	)
	(segment
		(start 184.77738 -119.377968)
		(end 184.55386 -119.154448)
		(width 0.127)
		(layer "In6.Cu")
		(net "RST_PLD_CPU0_DRAM_GH_N")
	)
	(segment
		(start 199.398382 -122.151648)
		(end 199.22363 -122.3264)
		(width 0.127)
		(layer "In6.Cu")
		(net "RST_PLD_CPU0_DRAM_GH_N")
	)
	(segment
		(start 95.631 -94.361)
		(end 97.79 -92.202)
		(width 0.127)
		(layer "In6.Cu")
		(net "RST_PLD_CPU0_DRAM_GH_N")
	)
	(segment
		(start 111.6457 -94.165928)
		(end 112.337596 -93.474032)
		(width 0.127)
		(layer "In6.Cu")
		(net "RST_PLD_CPU0_DRAM_GH_N")
	)
	(segment
		(start 112.337596 -93.474032)
		(end 119.531638 -93.474032)
		(width 0.127)
		(layer "In6.Cu")
		(net "RST_PLD_CPU0_DRAM_GH_N")
	)
	(segment
		(start 350.33712 -149.822408)
		(end 339.3059 -138.791188)
		(width 0.127)
		(layer "In6.Cu")
		(net "RST_PLD_CPU0_DRAM_GH_N")
	)
	(segment
		(start 189.28334 -119.337328)
		(end 187.072016 -119.337328)
		(width 0.127)
		(layer "In6.Cu")
		(net "RST_PLD_CPU0_DRAM_GH_N")
	)
	(segment
		(start 178.3588 -113.086388)
		(end 178.3588 -109.2962)
		(width 0.127)
		(layer "In6.Cu")
		(net "RST_PLD_CPU0_DRAM_GH_N")
	)
	(segment
		(start 257.51536 -131.364228)
		(end 254.11176 -131.364228)
		(width 0.127)
		(layer "In6.Cu")
		(net "RST_PLD_CPU0_DRAM_GH_N")
	)
	(segment
		(start 174.95012 -107.147868)
		(end 175.1838 -107.381548)
		(width 0.127)
		(layer "In6.Cu")
		(net "RST_PLD_CPU0_DRAM_GH_N")
	)
	(segment
		(start 174.95012 -105.948988)
		(end 174.95012 -107.147868)
		(width 0.127)
		(layer "In6.Cu")
		(net "RST_PLD_CPU0_DRAM_GH_N")
	)
	(segment
		(start 246.888 -119.847868)
		(end 239.48644 -119.847868)
		(width 0.127)
		(layer "In6.Cu")
		(net "RST_PLD_CPU0_DRAM_GH_N")
	)
	(segment
		(start 183.50865 -117.772688)
		(end 179.1462 -117.772688)
		(width 0.127)
		(layer "In6.Cu")
		(net "RST_PLD_CPU0_DRAM_GH_N")
	)
	(segment
		(start 175.287432 -101.3968)
		(end 175.95469 -102.064058)
		(width 0.127)
		(layer "In6.Cu")
		(net "RST_PLD_CPU0_DRAM_GH_N")
	)
	(segment
		(start 199.85863 -122.22226)
		(end 199.788018 -122.151648)
		(width 0.127)
		(layer "In6.Cu")
		(net "RST_PLD_CPU0_DRAM_GH_N")
	)
	(segment
		(start 187.072016 -119.337328)
		(end 187.031376 -119.377968)
		(width 0.127)
		(layer "In6.Cu")
		(net "RST_PLD_CPU0_DRAM_GH_N")
	)
	(segment
		(start 176.59858 -102.191058)
		(end 176.59858 -104.910128)
		(width 0.127)
		(layer "In6.Cu")
		(net "RST_PLD_CPU0_DRAM_GH_N")
	)
	(segment
		(start 199.788018 -122.151648)
		(end 199.398382 -122.151648)
		(width 0.127)
		(layer "In6.Cu")
		(net "RST_PLD_CPU0_DRAM_GH_N")
	)
	(segment
		(start 184.55386 -119.154448)
		(end 184.55386 -118.817898)
		(width 0.127)
		(layer "In6.Cu")
		(net "RST_PLD_CPU0_DRAM_GH_N")
	)
	(segment
		(start 183.76265 -118.338346)
		(end 183.76265 -118.026688)
		(width 0.127)
		(layer "In6.Cu")
		(net "RST_PLD_CPU0_DRAM_GH_N")
	)
	(segment
		(start 207.38846 -122.22226)
		(end 199.85863 -122.22226)
		(width 0.127)
		(layer "In6.Cu")
		(net "RST_PLD_CPU0_DRAM_GH_N")
	)
	(segment
		(start 175.1838 -107.381548)
		(end 175.5648 -107.381548)
		(width 0.127)
		(layer "In6.Cu")
		(net "RST_PLD_CPU0_DRAM_GH_N")
	)
	(segment
		(start 373.13108 -163.167568)
		(end 372.08206 -162.118548)
		(width 0.127)
		(layer "In6.Cu")
		(net "RST_PLD_CPU0_DRAM_GH_N")
	)
	(segment
		(start 373.13108 -164.363908)
		(end 373.13108 -163.167568)
		(width 0.127)
		(layer "In6.Cu")
		(net "RST_PLD_CPU0_DRAM_GH_N")
	)
	(segment
		(start 357.251 -149.822408)
		(end 350.33712 -149.822408)
		(width 0.127)
		(layer "In6.Cu")
		(net "RST_PLD_CPU0_DRAM_GH_N")
	)
	(segment
		(start 207.7466 -122.5804)
		(end 207.38846 -122.22226)
		(width 0.127)
		(layer "In6.Cu")
		(net "RST_PLD_CPU0_DRAM_GH_N")
	)
	(segment
		(start 178.92522 -117.551708)
		(end 178.92522 -113.652808)
		(width 0.127)
		(layer "In6.Cu")
		(net "RST_PLD_CPU0_DRAM_GH_N")
	)
	(segment
		(start 175.748442 -108.18241)
		(end 175.355504 -108.575348)
		(width 0.127)
		(layer "In6.Cu")
		(net "RST_PLD_CPU0_DRAM_GH_N")
	)
	(segment
		(start 100.555552 -92.202)
		(end 102.0572 -93.703648)
		(width 0.127)
		(layer "In6.Cu")
		(net "RST_PLD_CPU0_DRAM_GH_N")
	)
	(segment
		(start 174.955708 -108.175552)
		(end 174.555658 -107.775502)
		(width 0.12954)
		(layer "F.Cu")
		(net "RST_PLD_CPU0_DRAM_EF_N")
	)
	(segment
		(start 93.145356 -96.176846)
		(end 92.459556 -96.176846)
		(width 0.12954)
		(layer "F.Cu")
		(net "RST_PLD_CPU0_DRAM_EF_N")
	)
	(via
		(at 419.483286 -192.148968)
		(size 0.508)
		(drill 0.254)
		(layers "F.Cu" "B.Cu")
		(net "RST_PLD_CPU0_DRAM_EF_N")
	)
	(via
		(at 92.459556 -96.176846)
		(size 0.508)
		(drill 0.254)
		(layers "F.Cu" "B.Cu")
		(net "RST_PLD_CPU0_DRAM_EF_N")
	)
	(via
		(at 372.153434 -164.371528)
		(size 0.508)
		(drill 0.254)
		(layers "F.Cu" "B.Cu")
		(net "RST_PLD_CPU0_DRAM_EF_N")
	)
	(via
		(at 174.555658 -107.775502)
		(size 0.4572)
		(drill 0.254)
		(layers "F.Cu" "B.Cu")
		(net "RST_PLD_CPU0_DRAM_EF_N")
	)
	(segment
		(start 422.314624 -192.953386)
		(end 421.304466 -192.953386)
		(width 0.12954)
		(layer "B.Cu")
		(net "RST_PLD_CPU0_DRAM_EF_N")
	)
	(segment
		(start 420.285418 -192.9511)
		(end 420.285418 -192.953386)
		(width 0.12954)
		(layer "B.Cu")
		(net "RST_PLD_CPU0_DRAM_EF_N")
	)
	(segment
		(start 421.304466 -192.953386)
		(end 420.285418 -192.953386)
		(width 0.12954)
		(layer "B.Cu")
		(net "RST_PLD_CPU0_DRAM_EF_N")
	)
	(segment
		(start 419.483286 -192.148968)
		(end 420.285418 -192.9511)
		(width 0.12954)
		(layer "B.Cu")
		(net "RST_PLD_CPU0_DRAM_EF_N")
	)
	(segment
		(start 384.97383 -174.935134)
		(end 375.56567 -165.526974)
		(width 0.127)
		(layer "In2.Cu")
		(net "RST_PLD_CPU0_DRAM_EF_N")
	)
	(segment
		(start 394.428218 -175.805846)
		(end 393.557506 -174.935134)
		(width 0.127)
		(layer "In2.Cu")
		(net "RST_PLD_CPU0_DRAM_EF_N")
	)
	(segment
		(start 393.557506 -174.935134)
		(end 384.97383 -174.935134)
		(width 0.127)
		(layer "In2.Cu")
		(net "RST_PLD_CPU0_DRAM_EF_N")
	)
	(segment
		(start 393.67968 -183.266588)
		(end 394.428218 -182.51805)
		(width 0.127)
		(layer "In2.Cu")
		(net "RST_PLD_CPU0_DRAM_EF_N")
	)
	(segment
		(start 406.352502 -191.307974)
		(end 404.819358 -189.77483)
		(width 0.127)
		(layer "In2.Cu")
		(net "RST_PLD_CPU0_DRAM_EF_N")
	)
	(segment
		(start 375.56567 -165.526974)
		(end 372.50497 -165.526974)
		(width 0.127)
		(layer "In2.Cu")
		(net "RST_PLD_CPU0_DRAM_EF_N")
	)
	(segment
		(start 393.67968 -188.177932)
		(end 393.67968 -183.266588)
		(width 0.127)
		(layer "In2.Cu")
		(net "RST_PLD_CPU0_DRAM_EF_N")
	)
	(segment
		(start 372.50497 -165.526974)
		(end 372.153434 -165.175438)
		(width 0.127)
		(layer "In2.Cu")
		(net "RST_PLD_CPU0_DRAM_EF_N")
	)
	(segment
		(start 400.467576 -190.414148)
		(end 395.915896 -190.414148)
		(width 0.127)
		(layer "In2.Cu")
		(net "RST_PLD_CPU0_DRAM_EF_N")
	)
	(segment
		(start 395.915896 -190.414148)
		(end 393.67968 -188.177932)
		(width 0.127)
		(layer "In2.Cu")
		(net "RST_PLD_CPU0_DRAM_EF_N")
	)
	(segment
		(start 419.483286 -192.148968)
		(end 418.642292 -191.307974)
		(width 0.127)
		(layer "In2.Cu")
		(net "RST_PLD_CPU0_DRAM_EF_N")
	)
	(segment
		(start 372.153434 -165.175438)
		(end 372.153434 -164.371528)
		(width 0.127)
		(layer "In2.Cu")
		(net "RST_PLD_CPU0_DRAM_EF_N")
	)
	(segment
		(start 394.428218 -182.51805)
		(end 394.428218 -175.805846)
		(width 0.127)
		(layer "In2.Cu")
		(net "RST_PLD_CPU0_DRAM_EF_N")
	)
	(segment
		(start 404.819358 -189.77483)
		(end 401.106894 -189.77483)
		(width 0.127)
		(layer "In2.Cu")
		(net "RST_PLD_CPU0_DRAM_EF_N")
	)
	(segment
		(start 418.642292 -191.307974)
		(end 406.352502 -191.307974)
		(width 0.127)
		(layer "In2.Cu")
		(net "RST_PLD_CPU0_DRAM_EF_N")
	)
	(segment
		(start 401.106894 -189.77483)
		(end 400.467576 -190.414148)
		(width 0.127)
		(layer "In2.Cu")
		(net "RST_PLD_CPU0_DRAM_EF_N")
	)
	(segment
		(start 207.69072 -124.689108)
		(end 220.23578 -124.689108)
		(width 0.127)
		(layer "In6.Cu")
		(net "RST_PLD_CPU0_DRAM_EF_N")
	)
	(segment
		(start 173.935898 -101.894894)
		(end 171.67987 -100.960428)
		(width 0.127)
		(layer "In6.Cu")
		(net "RST_PLD_CPU0_DRAM_EF_N")
	)
	(segment
		(start 159.8295 -98.555048)
		(end 158.9278 -99.456748)
		(width 0.127)
		(layer "In6.Cu")
		(net "RST_PLD_CPU0_DRAM_EF_N")
	)
	(segment
		(start 228.80193 -122.198638)
		(end 244.50675 -122.198638)
		(width 0.127)
		(layer "In6.Cu")
		(net "RST_PLD_CPU0_DRAM_EF_N")
	)
	(segment
		(start 372.17096 -164.354002)
		(end 372.153434 -164.371528)
		(width 0.127)
		(layer "In6.Cu")
		(net "RST_PLD_CPU0_DRAM_EF_N")
	)
	(segment
		(start 184.32526 -120.973088)
		(end 184.55894 -121.206768)
		(width 0.127)
		(layer "In6.Cu")
		(net "RST_PLD_CPU0_DRAM_EF_N")
	)
	(segment
		(start 254.62738 -133.175248)
		(end 272.445226 -133.175248)
		(width 0.127)
		(layer "In6.Cu")
		(net "RST_PLD_CPU0_DRAM_EF_N")
	)
	(segment
		(start 183.9595 -120.973088)
		(end 184.32526 -120.973088)
		(width 0.127)
		(layer "In6.Cu")
		(net "RST_PLD_CPU0_DRAM_EF_N")
	)
	(segment
		(start 189.2427 -123.078748)
		(end 191.77254 -125.608588)
		(width 0.127)
		(layer "In6.Cu")
		(net "RST_PLD_CPU0_DRAM_EF_N")
	)
	(segment
		(start 174.1551 -108.17606)
		(end 174.1551 -112.840008)
		(width 0.127)
		(layer "In6.Cu")
		(net "RST_PLD_CPU0_DRAM_EF_N")
	)
	(segment
		(start 220.23578 -124.689108)
		(end 224.03054 -120.894348)
		(width 0.127)
		(layer "In6.Cu")
		(net "RST_PLD_CPU0_DRAM_EF_N")
	)
	(segment
		(start 103.14178 -94.592648)
		(end 98.27006 -94.592648)
		(width 0.127)
		(layer "In6.Cu")
		(net "RST_PLD_CPU0_DRAM_EF_N")
	)
	(segment
		(start 174.56404 -103.990648)
		(end 174.56404 -102.523036)
		(width 0.127)
		(layer "In6.Cu")
		(net "RST_PLD_CPU0_DRAM_EF_N")
	)
	(segment
		(start 144.38884 -98.895408)
		(end 140.54836 -95.054928)
		(width 0.127)
		(layer "In6.Cu")
		(net "RST_PLD_CPU0_DRAM_EF_N")
	)
	(segment
		(start 183.53024 -120.175528)
		(end 183.76138 -120.406668)
		(width 0.127)
		(layer "In6.Cu")
		(net "RST_PLD_CPU0_DRAM_EF_N")
	)
	(segment
		(start 179.11826 -119.380508)
		(end 182.7403 -119.380508)
		(width 0.127)
		(layer "In6.Cu")
		(net "RST_PLD_CPU0_DRAM_EF_N")
	)
	(segment
		(start 371.70106 -163.038028)
		(end 372.17096 -163.507928)
		(width 0.127)
		(layer "In6.Cu")
		(net "RST_PLD_CPU0_DRAM_EF_N")
	)
	(segment
		(start 184.55894 -121.577608)
		(end 184.75452 -121.773188)
		(width 0.127)
		(layer "In6.Cu")
		(net "RST_PLD_CPU0_DRAM_EF_N")
	)
	(segment
		(start 184.75452 -121.773188)
		(end 185.43016 -121.773188)
		(width 0.127)
		(layer "In6.Cu")
		(net "RST_PLD_CPU0_DRAM_EF_N")
	)
	(segment
		(start 171.67987 -100.960428)
		(end 169.934128 -100.960428)
		(width 0.127)
		(layer "In6.Cu")
		(net "RST_PLD_CPU0_DRAM_EF_N")
	)
	(segment
		(start 174.16018 -104.394508)
		(end 174.56404 -103.990648)
		(width 0.127)
		(layer "In6.Cu")
		(net "RST_PLD_CPU0_DRAM_EF_N")
	)
	(segment
		(start 182.7403 -119.380508)
		(end 182.95112 -119.591328)
		(width 0.127)
		(layer "In6.Cu")
		(net "RST_PLD_CPU0_DRAM_EF_N")
	)
	(segment
		(start 103.60406 -95.054928)
		(end 103.14178 -94.592648)
		(width 0.127)
		(layer "In6.Cu")
		(net "RST_PLD_CPU0_DRAM_EF_N")
	)
	(segment
		(start 140.54836 -95.054928)
		(end 103.60406 -95.054928)
		(width 0.127)
		(layer "In6.Cu")
		(net "RST_PLD_CPU0_DRAM_EF_N")
	)
	(segment
		(start 338.9249 -139.710668)
		(end 349.95612 -150.741888)
		(width 0.127)
		(layer "In6.Cu")
		(net "RST_PLD_CPU0_DRAM_EF_N")
	)
	(segment
		(start 227.49764 -120.894348)
		(end 228.80193 -122.198638)
		(width 0.127)
		(layer "In6.Cu")
		(net "RST_PLD_CPU0_DRAM_EF_N")
	)
	(segment
		(start 244.50675 -122.198638)
		(end 245.96852 -120.736868)
		(width 0.127)
		(layer "In6.Cu")
		(net "RST_PLD_CPU0_DRAM_EF_N")
	)
	(segment
		(start 174.64024 -113.325148)
		(end 177.72126 -113.325148)
		(width 0.127)
		(layer "In6.Cu")
		(net "RST_PLD_CPU0_DRAM_EF_N")
	)
	(segment
		(start 331.851 -139.710668)
		(end 338.9249 -139.710668)
		(width 0.127)
		(layer "In6.Cu")
		(net "RST_PLD_CPU0_DRAM_EF_N")
	)
	(segment
		(start 205.92034 -126.459488)
		(end 207.69072 -124.689108)
		(width 0.127)
		(layer "In6.Cu")
		(net "RST_PLD_CPU0_DRAM_EF_N")
	)
	(segment
		(start 182.95112 -119.591328)
		(end 182.95112 -119.957088)
		(width 0.127)
		(layer "In6.Cu")
		(net "RST_PLD_CPU0_DRAM_EF_N")
	)
	(segment
		(start 158.9278 -99.456748)
		(end 146.21764 -99.456748)
		(width 0.127)
		(layer "In6.Cu")
		(net "RST_PLD_CPU0_DRAM_EF_N")
	)
	(segment
		(start 169.934128 -100.960428)
		(end 167.528748 -98.555048)
		(width 0.127)
		(layer "In6.Cu")
		(net "RST_PLD_CPU0_DRAM_EF_N")
	)
	(segment
		(start 174.16018 -107.380024)
		(end 174.16018 -104.394508)
		(width 0.127)
		(layer "In6.Cu")
		(net "RST_PLD_CPU0_DRAM_EF_N")
	)
	(segment
		(start 174.56404 -102.523036)
		(end 173.935898 -101.894894)
		(width 0.127)
		(layer "In6.Cu")
		(net "RST_PLD_CPU0_DRAM_EF_N")
	)
	(segment
		(start 183.76138 -120.774968)
		(end 183.9595 -120.973088)
		(width 0.127)
		(layer "In6.Cu")
		(net "RST_PLD_CPU0_DRAM_EF_N")
	)
	(segment
		(start 94.5769 -96.937068)
		(end 93.816678 -96.176846)
		(width 0.127)
		(layer "In6.Cu")
		(net "RST_PLD_CPU0_DRAM_EF_N")
	)
	(segment
		(start 178.28514 -118.547388)
		(end 179.11826 -119.380508)
		(width 0.127)
		(layer "In6.Cu")
		(net "RST_PLD_CPU0_DRAM_EF_N")
	)
	(segment
		(start 177.72126 -113.325148)
		(end 178.28514 -113.889028)
		(width 0.127)
		(layer "In6.Cu")
		(net "RST_PLD_CPU0_DRAM_EF_N")
	)
	(segment
		(start 369.16614 -163.038028)
		(end 371.70106 -163.038028)
		(width 0.127)
		(layer "In6.Cu")
		(net "RST_PLD_CPU0_DRAM_EF_N")
	)
	(segment
		(start 174.1551 -112.840008)
		(end 174.64024 -113.325148)
		(width 0.127)
		(layer "In6.Cu")
		(net "RST_PLD_CPU0_DRAM_EF_N")
	)
	(segment
		(start 194.78752 -126.459488)
		(end 205.92034 -126.459488)
		(width 0.127)
		(layer "In6.Cu")
		(net "RST_PLD_CPU0_DRAM_EF_N")
	)
	(segment
		(start 372.17096 -163.507928)
		(end 372.17096 -164.354002)
		(width 0.127)
		(layer "In6.Cu")
		(net "RST_PLD_CPU0_DRAM_EF_N")
	)
	(segment
		(start 174.555658 -107.775502)
		(end 174.1551 -108.17606)
		(width 0.127)
		(layer "In6.Cu")
		(net "RST_PLD_CPU0_DRAM_EF_N")
	)
	(segment
		(start 246.5197 -120.736868)
		(end 252.1712 -126.388368)
		(width 0.127)
		(layer "In6.Cu")
		(net "RST_PLD_CPU0_DRAM_EF_N")
	)
	(segment
		(start 193.93662 -125.608588)
		(end 194.78752 -126.459488)
		(width 0.127)
		(layer "In6.Cu")
		(net "RST_PLD_CPU0_DRAM_EF_N")
	)
	(segment
		(start 98.27006 -94.592648)
		(end 95.92564 -96.937068)
		(width 0.127)
		(layer "In6.Cu")
		(net "RST_PLD_CPU0_DRAM_EF_N")
	)
	(segment
		(start 252.1712 -126.388368)
		(end 252.1712 -130.719068)
		(width 0.127)
		(layer "In6.Cu")
		(net "RST_PLD_CPU0_DRAM_EF_N")
	)
	(segment
		(start 95.92564 -96.937068)
		(end 94.5769 -96.937068)
		(width 0.127)
		(layer "In6.Cu")
		(net "RST_PLD_CPU0_DRAM_EF_N")
	)
	(segment
		(start 174.555658 -107.775502)
		(end 174.16018 -107.380024)
		(width 0.127)
		(layer "In6.Cu")
		(net "RST_PLD_CPU0_DRAM_EF_N")
	)
	(segment
		(start 224.03054 -120.894348)
		(end 227.49764 -120.894348)
		(width 0.127)
		(layer "In6.Cu")
		(net "RST_PLD_CPU0_DRAM_EF_N")
	)
	(segment
		(start 186.73572 -123.078748)
		(end 189.2427 -123.078748)
		(width 0.127)
		(layer "In6.Cu")
		(net "RST_PLD_CPU0_DRAM_EF_N")
	)
	(segment
		(start 272.445226 -133.175248)
		(end 273.875246 -131.745228)
		(width 0.127)
		(layer "In6.Cu")
		(net "RST_PLD_CPU0_DRAM_EF_N")
	)
	(segment
		(start 184.55894 -121.206768)
		(end 184.55894 -121.577608)
		(width 0.127)
		(layer "In6.Cu")
		(net "RST_PLD_CPU0_DRAM_EF_N")
	)
	(segment
		(start 191.77254 -125.608588)
		(end 193.93662 -125.608588)
		(width 0.127)
		(layer "In6.Cu")
		(net "RST_PLD_CPU0_DRAM_EF_N")
	)
	(segment
		(start 273.875246 -131.745228)
		(end 323.88556 -131.745228)
		(width 0.127)
		(layer "In6.Cu")
		(net "RST_PLD_CPU0_DRAM_EF_N")
	)
	(segment
		(start 167.528748 -98.555048)
		(end 159.8295 -98.555048)
		(width 0.127)
		(layer "In6.Cu")
		(net "RST_PLD_CPU0_DRAM_EF_N")
	)
	(segment
		(start 323.88556 -131.745228)
		(end 331.851 -139.710668)
		(width 0.127)
		(layer "In6.Cu")
		(net "RST_PLD_CPU0_DRAM_EF_N")
	)
	(segment
		(start 356.87 -150.741888)
		(end 369.16614 -163.038028)
		(width 0.127)
		(layer "In6.Cu")
		(net "RST_PLD_CPU0_DRAM_EF_N")
	)
	(segment
		(start 183.16956 -120.175528)
		(end 183.53024 -120.175528)
		(width 0.127)
		(layer "In6.Cu")
		(net "RST_PLD_CPU0_DRAM_EF_N")
	)
	(segment
		(start 185.43016 -121.773188)
		(end 186.73572 -123.078748)
		(width 0.127)
		(layer "In6.Cu")
		(net "RST_PLD_CPU0_DRAM_EF_N")
	)
	(segment
		(start 245.96852 -120.736868)
		(end 246.5197 -120.736868)
		(width 0.127)
		(layer "In6.Cu")
		(net "RST_PLD_CPU0_DRAM_EF_N")
	)
	(segment
		(start 93.816678 -96.176846)
		(end 92.459556 -96.176846)
		(width 0.127)
		(layer "In6.Cu")
		(net "RST_PLD_CPU0_DRAM_EF_N")
	)
	(segment
		(start 349.95612 -150.741888)
		(end 356.87 -150.741888)
		(width 0.127)
		(layer "In6.Cu")
		(net "RST_PLD_CPU0_DRAM_EF_N")
	)
	(segment
		(start 178.28514 -113.889028)
		(end 178.28514 -118.547388)
		(width 0.127)
		(layer "In6.Cu")
		(net "RST_PLD_CPU0_DRAM_EF_N")
	)
	(segment
		(start 182.95112 -119.957088)
		(end 183.16956 -120.175528)
		(width 0.127)
		(layer "In6.Cu")
		(net "RST_PLD_CPU0_DRAM_EF_N")
	)
	(segment
		(start 145.6563 -98.895408)
		(end 144.38884 -98.895408)
		(width 0.127)
		(layer "In6.Cu")
		(net "RST_PLD_CPU0_DRAM_EF_N")
	)
	(segment
		(start 146.21764 -99.456748)
		(end 145.6563 -98.895408)
		(width 0.127)
		(layer "In6.Cu")
		(net "RST_PLD_CPU0_DRAM_EF_N")
	)
	(segment
		(start 252.1712 -130.719068)
		(end 254.62738 -133.175248)
		(width 0.127)
		(layer "In6.Cu")
		(net "RST_PLD_CPU0_DRAM_EF_N")
	)
	(segment
		(start 183.76138 -120.406668)
		(end 183.76138 -120.774968)
		(width 0.127)
		(layer "In6.Cu")
		(net "RST_PLD_CPU0_DRAM_EF_N")
	)
	(segment
		(start 95.97898 -94.051628)
		(end 95.97898 -93.411294)
		(width 0.12954)
		(layer "F.Cu")
		(net "RST_PLD_CPU0_DRAM_CD_N")
	)
	(segment
		(start 97.29724 -102.499668)
		(end 97.020634 -102.223062)
		(width 0.12954)
		(layer "F.Cu")
		(net "RST_PLD_CPU0_DRAM_CD_N")
	)
	(segment
		(start 97.020634 -95.093282)
		(end 95.97898 -94.051628)
		(width 0.12954)
		(layer "F.Cu")
		(net "RST_PLD_CPU0_DRAM_CD_N")
	)
	(segment
		(start 172.555662 -105.775506)
		(end 172.155612 -105.375456)
		(width 0.12954)
		(layer "F.Cu")
		(net "RST_PLD_CPU0_DRAM_CD_N")
	)
	(segment
		(start 97.020634 -102.223062)
		(end 97.020634 -95.093282)
		(width 0.12954)
		(layer "F.Cu")
		(net "RST_PLD_CPU0_DRAM_CD_N")
	)
	(segment
		(start 95.631 -93.063314)
		(end 94.9452 -93.063314)
		(width 0.12954)
		(layer "F.Cu")
		(net "RST_PLD_CPU0_DRAM_CD_N")
	)
	(segment
		(start 95.97898 -93.411294)
		(end 95.631 -93.063314)
		(width 0.12954)
		(layer "F.Cu")
		(net "RST_PLD_CPU0_DRAM_CD_N")
	)
	(via
		(at 172.155612 -105.375456)
		(size 0.4572)
		(drill 0.254)
		(layers "F.Cu" "B.Cu")
		(net "RST_PLD_CPU0_DRAM_CD_N")
	)
	(via
		(at 97.29724 -102.499668)
		(size 0.508)
		(drill 0.254)
		(layers "F.Cu" "B.Cu")
		(net "RST_PLD_CPU0_DRAM_CD_N")
	)
	(via
		(at 211.20862 -165.590728)
		(size 0.508)
		(drill 0.254)
		(layers "F.Cu" "B.Cu")
		(net "RST_PLD_CPU0_DRAM_CD_N")
	)
	(via
		(at 95.631 -93.063314)
		(size 0.508)
		(drill 0.254)
		(layers "F.Cu" "B.Cu")
		(net "RST_PLD_CPU0_DRAM_CD_N")
	)
	(segment
		(start 265.95451 -191.40551)
		(end 267.652246 -193.103246)
		(width 0.12954)
		(layer "B.Cu")
		(net "RST_PLD_CPU0_DRAM_CD_N")
	)
	(segment
		(start 211.20862 -165.590728)
		(end 226.537012 -165.590728)
		(width 0.12954)
		(layer "B.Cu")
		(net "RST_PLD_CPU0_DRAM_CD_N")
	)
	(segment
		(start 226.537012 -165.590728)
		(end 233.255312 -172.309028)
		(width 0.12954)
		(layer "B.Cu")
		(net "RST_PLD_CPU0_DRAM_CD_N")
	)
	(segment
		(start 268.668246 -193.103246)
		(end 268.531848 -192.966848)
		(width 0.12954)
		(layer "B.Cu")
		(net "RST_PLD_CPU0_DRAM_CD_N")
	)
	(segment
		(start 233.255312 -172.309028)
		(end 246.111776 -172.309028)
		(width 0.12954)
		(layer "B.Cu")
		(net "RST_PLD_CPU0_DRAM_CD_N")
	)
	(segment
		(start 246.111776 -172.309028)
		(end 265.208258 -191.40551)
		(width 0.12954)
		(layer "B.Cu")
		(net "RST_PLD_CPU0_DRAM_CD_N")
	)
	(segment
		(start 268.531848 -192.966848)
		(end 267.788644 -192.966848)
		(width 0.12954)
		(layer "B.Cu")
		(net "RST_PLD_CPU0_DRAM_CD_N")
	)
	(segment
		(start 268.809724 -192.961768)
		(end 268.668246 -193.103246)
		(width 0.12954)
		(layer "B.Cu")
		(net "RST_PLD_CPU0_DRAM_CD_N")
	)
	(segment
		(start 269.542768 -192.961768)
		(end 268.809724 -192.961768)
		(width 0.12954)
		(layer "B.Cu")
		(net "RST_PLD_CPU0_DRAM_CD_N")
	)
	(segment
		(start 269.684246 -193.103246)
		(end 269.542768 -192.961768)
		(width 0.12954)
		(layer "B.Cu")
		(net "RST_PLD_CPU0_DRAM_CD_N")
	)
	(segment
		(start 267.788644 -192.966848)
		(end 267.652246 -193.103246)
		(width 0.12954)
		(layer "B.Cu")
		(net "RST_PLD_CPU0_DRAM_CD_N")
	)
	(segment
		(start 265.208258 -191.40551)
		(end 265.95451 -191.40551)
		(width 0.12954)
		(layer "B.Cu")
		(net "RST_PLD_CPU0_DRAM_CD_N")
	)
	(segment
		(start 182.758334 -116.179854)
		(end 182.389526 -116.179854)
		(width 0.127)
		(layer "In2.Cu")
		(net "RST_PLD_CPU0_DRAM_CD_N")
	)
	(segment
		(start 173.13148 -108.979208)
		(end 172.75556 -108.979208)
		(width 0.127)
		(layer "In2.Cu")
		(net "RST_PLD_CPU0_DRAM_CD_N")
	)
	(segment
		(start 179.75834 -115.179348)
		(end 179.75834 -113.988088)
		(width 0.127)
		(layer "In2.Cu")
		(net "RST_PLD_CPU0_DRAM_CD_N")
	)
	(segment
		(start 185.9788 -118.577868)
		(end 184.78754 -118.577868)
		(width 0.127)
		(layer "In2.Cu")
		(net "RST_PLD_CPU0_DRAM_CD_N")
	)
	(segment
		(start 184.55894 -118.349268)
		(end 184.55894 -118.03634)
		(width 0.127)
		(layer "In2.Cu")
		(net "RST_PLD_CPU0_DRAM_CD_N")
	)
	(segment
		(start 182.95747 -116.747798)
		(end 182.95747 -116.37899)
		(width 0.127)
		(layer "In2.Cu")
		(net "RST_PLD_CPU0_DRAM_CD_N")
	)
	(segment
		(start 178.12766 -113.101628)
		(end 175.26508 -113.101628)
		(width 0.127)
		(layer "In2.Cu")
		(net "RST_PLD_CPU0_DRAM_CD_N")
	)
	(segment
		(start 174.27702 -110.574328)
		(end 174.15256 -110.449868)
		(width 0.127)
		(layer "In2.Cu")
		(net "RST_PLD_CPU0_DRAM_CD_N")
	)
	(segment
		(start 186.16168 -118.760748)
		(end 185.9788 -118.577868)
		(width 0.127)
		(layer "In2.Cu")
		(net "RST_PLD_CPU0_DRAM_CD_N")
	)
	(segment
		(start 173.571916 -109.772958)
		(end 173.35246 -109.553502)
		(width 0.127)
		(layer "In2.Cu")
		(net "RST_PLD_CPU0_DRAM_CD_N")
	)
	(segment
		(start 174.752 -110.574328)
		(end 174.27702 -110.574328)
		(width 0.127)
		(layer "In2.Cu")
		(net "RST_PLD_CPU0_DRAM_CD_N")
	)
	(segment
		(start 172.54982 -105.769664)
		(end 172.155612 -105.375456)
		(width 0.127)
		(layer "In2.Cu")
		(net "RST_PLD_CPU0_DRAM_CD_N")
	)
	(segment
		(start 186.16168 -119.137176)
		(end 186.16168 -118.760748)
		(width 0.127)
		(layer "In2.Cu")
		(net "RST_PLD_CPU0_DRAM_CD_N")
	)
	(segment
		(start 184.318402 -117.782594)
		(end 183.992266 -117.782594)
		(width 0.127)
		(layer "In2.Cu")
		(net "RST_PLD_CPU0_DRAM_CD_N")
	)
	(segment
		(start 187.297822 -120.273318)
		(end 186.16168 -119.137176)
		(width 0.127)
		(layer "In2.Cu")
		(net "RST_PLD_CPU0_DRAM_CD_N")
	)
	(segment
		(start 174.15256 -109.974888)
		(end 173.95063 -109.772958)
		(width 0.127)
		(layer "In2.Cu")
		(net "RST_PLD_CPU0_DRAM_CD_N")
	)
	(segment
		(start 184.548526 -118.025926)
		(end 184.548526 -118.012718)
		(width 0.127)
		(layer "In2.Cu")
		(net "RST_PLD_CPU0_DRAM_CD_N")
	)
	(segment
		(start 183.76138 -117.551708)
		(end 183.76138 -117.183408)
		(width 0.127)
		(layer "In2.Cu")
		(net "RST_PLD_CPU0_DRAM_CD_N")
	)
	(segment
		(start 184.548526 -118.012718)
		(end 184.318402 -117.782594)
		(width 0.127)
		(layer "In2.Cu")
		(net "RST_PLD_CPU0_DRAM_CD_N")
	)
	(segment
		(start 174.95774 -112.794288)
		(end 174.95774 -110.780068)
		(width 0.127)
		(layer "In2.Cu")
		(net "RST_PLD_CPU0_DRAM_CD_N")
	)
	(segment
		(start 172.75556 -108.979208)
		(end 172.54982 -108.773468)
		(width 0.127)
		(layer "In2.Cu")
		(net "RST_PLD_CPU0_DRAM_CD_N")
	)
	(segment
		(start 183.992266 -117.782594)
		(end 183.76138 -117.551708)
		(width 0.127)
		(layer "In2.Cu")
		(net "RST_PLD_CPU0_DRAM_CD_N")
	)
	(segment
		(start 184.78754 -118.577868)
		(end 184.55894 -118.349268)
		(width 0.127)
		(layer "In2.Cu")
		(net "RST_PLD_CPU0_DRAM_CD_N")
	)
	(segment
		(start 174.15256 -110.449868)
		(end 174.15256 -109.974888)
		(width 0.127)
		(layer "In2.Cu")
		(net "RST_PLD_CPU0_DRAM_CD_N")
	)
	(segment
		(start 179.95646 -115.377468)
		(end 179.75834 -115.179348)
		(width 0.127)
		(layer "In2.Cu")
		(net "RST_PLD_CPU0_DRAM_CD_N")
	)
	(segment
		(start 183.76138 -117.183408)
		(end 183.55056 -116.972588)
		(width 0.127)
		(layer "In2.Cu")
		(net "RST_PLD_CPU0_DRAM_CD_N")
	)
	(segment
		(start 211.20862 -165.590728)
		(end 211.7852 -165.014148)
		(width 0.127)
		(layer "In2.Cu")
		(net "RST_PLD_CPU0_DRAM_CD_N")
	)
	(segment
		(start 211.7852 -165.014148)
		(end 211.7852 -146.5453)
		(width 0.127)
		(layer "In2.Cu")
		(net "RST_PLD_CPU0_DRAM_CD_N")
	)
	(segment
		(start 179.75834 -113.988088)
		(end 179.54498 -113.774728)
		(width 0.127)
		(layer "In2.Cu")
		(net "RST_PLD_CPU0_DRAM_CD_N")
	)
	(segment
		(start 175.26508 -113.101628)
		(end 174.95774 -112.794288)
		(width 0.127)
		(layer "In2.Cu")
		(net "RST_PLD_CPU0_DRAM_CD_N")
	)
	(segment
		(start 179.54498 -113.774728)
		(end 178.80076 -113.774728)
		(width 0.127)
		(layer "In2.Cu")
		(net "RST_PLD_CPU0_DRAM_CD_N")
	)
	(segment
		(start 187.47867 -120.273318)
		(end 187.297822 -120.273318)
		(width 0.127)
		(layer "In2.Cu")
		(net "RST_PLD_CPU0_DRAM_CD_N")
	)
	(segment
		(start 184.55894 -118.03634)
		(end 184.548526 -118.025926)
		(width 0.127)
		(layer "In2.Cu")
		(net "RST_PLD_CPU0_DRAM_CD_N")
	)
	(segment
		(start 183.18226 -116.972588)
		(end 182.95747 -116.747798)
		(width 0.127)
		(layer "In2.Cu")
		(net "RST_PLD_CPU0_DRAM_CD_N")
	)
	(segment
		(start 182.389526 -116.179854)
		(end 182.16118 -115.951508)
		(width 0.127)
		(layer "In2.Cu")
		(net "RST_PLD_CPU0_DRAM_CD_N")
	)
	(segment
		(start 182.16118 -115.951508)
		(end 182.16118 -115.621308)
		(width 0.127)
		(layer "In2.Cu")
		(net "RST_PLD_CPU0_DRAM_CD_N")
	)
	(segment
		(start 182.16118 -115.621308)
		(end 181.91734 -115.377468)
		(width 0.127)
		(layer "In2.Cu")
		(net "RST_PLD_CPU0_DRAM_CD_N")
	)
	(segment
		(start 183.55056 -116.972588)
		(end 183.18226 -116.972588)
		(width 0.127)
		(layer "In2.Cu")
		(net "RST_PLD_CPU0_DRAM_CD_N")
	)
	(segment
		(start 182.95747 -116.37899)
		(end 182.758334 -116.179854)
		(width 0.127)
		(layer "In2.Cu")
		(net "RST_PLD_CPU0_DRAM_CD_N")
	)
	(segment
		(start 173.35246 -109.200188)
		(end 173.13148 -108.979208)
		(width 0.127)
		(layer "In2.Cu")
		(net "RST_PLD_CPU0_DRAM_CD_N")
	)
	(segment
		(start 193.423794 -128.183894)
		(end 193.423794 -126.218442)
		(width 0.127)
		(layer "In2.Cu")
		(net "RST_PLD_CPU0_DRAM_CD_N")
	)
	(segment
		(start 178.80076 -113.774728)
		(end 178.12766 -113.101628)
		(width 0.127)
		(layer "In2.Cu")
		(net "RST_PLD_CPU0_DRAM_CD_N")
	)
	(segment
		(start 173.95063 -109.772958)
		(end 173.571916 -109.772958)
		(width 0.127)
		(layer "In2.Cu")
		(net "RST_PLD_CPU0_DRAM_CD_N")
	)
	(segment
		(start 172.54982 -108.773468)
		(end 172.54982 -105.769664)
		(width 0.127)
		(layer "In2.Cu")
		(net "RST_PLD_CPU0_DRAM_CD_N")
	)
	(segment
		(start 174.95774 -110.780068)
		(end 174.752 -110.574328)
		(width 0.127)
		(layer "In2.Cu")
		(net "RST_PLD_CPU0_DRAM_CD_N")
	)
	(segment
		(start 193.423794 -126.218442)
		(end 187.47867 -120.273318)
		(width 0.127)
		(layer "In2.Cu")
		(net "RST_PLD_CPU0_DRAM_CD_N")
	)
	(segment
		(start 181.91734 -115.377468)
		(end 179.95646 -115.377468)
		(width 0.127)
		(layer "In2.Cu")
		(net "RST_PLD_CPU0_DRAM_CD_N")
	)
	(segment
		(start 211.7852 -146.5453)
		(end 193.423794 -128.183894)
		(width 0.127)
		(layer "In2.Cu")
		(net "RST_PLD_CPU0_DRAM_CD_N")
	)
	(segment
		(start 173.35246 -109.553502)
		(end 173.35246 -109.200188)
		(width 0.127)
		(layer "In2.Cu")
		(net "RST_PLD_CPU0_DRAM_CD_N")
	)
	(segment
		(start 172.155612 -105.375456)
		(end 171.753784 -104.973628)
		(width 0.127)
		(layer "In6.Cu")
		(net "RST_PLD_CPU0_DRAM_CD_N")
	)
	(segment
		(start 170.0784 -105.067608)
		(end 168.88714 -105.067608)
		(width 0.127)
		(layer "In6.Cu")
		(net "RST_PLD_CPU0_DRAM_CD_N")
	)
	(segment
		(start 171.753784 -104.973628)
		(end 170.17238 -104.973628)
		(width 0.127)
		(layer "In6.Cu")
		(net "RST_PLD_CPU0_DRAM_CD_N")
	)
	(segment
		(start 168.17086 -104.351328)
		(end 164.15258 -104.351328)
		(width 0.127)
		(layer "In6.Cu")
		(net "RST_PLD_CPU0_DRAM_CD_N")
	)
	(segment
		(start 163.8173 -104.016048)
		(end 137.25398 -104.016048)
		(width 0.127)
		(layer "In6.Cu")
		(net "RST_PLD_CPU0_DRAM_CD_N")
	)
	(segment
		(start 170.17238 -104.973628)
		(end 170.0784 -105.067608)
		(width 0.127)
		(layer "In6.Cu")
		(net "RST_PLD_CPU0_DRAM_CD_N")
	)
	(segment
		(start 168.88714 -105.067608)
		(end 168.17086 -104.351328)
		(width 0.127)
		(layer "In6.Cu")
		(net "RST_PLD_CPU0_DRAM_CD_N")
	)
	(segment
		(start 116.33708 -103.317548)
		(end 112.92078 -103.317548)
		(width 0.127)
		(layer "In6.Cu")
		(net "RST_PLD_CPU0_DRAM_CD_N")
	)
	(segment
		(start 110.59414 -105.644188)
		(end 100.44176 -105.644188)
		(width 0.127)
		(layer "In6.Cu")
		(net "RST_PLD_CPU0_DRAM_CD_N")
	)
	(segment
		(start 112.92078 -103.317548)
		(end 110.59414 -105.644188)
		(width 0.127)
		(layer "In6.Cu")
		(net "RST_PLD_CPU0_DRAM_CD_N")
	)
	(segment
		(start 133.56844 -100.330508)
		(end 118.8593 -100.330508)
		(width 0.127)
		(layer "In6.Cu")
		(net "RST_PLD_CPU0_DRAM_CD_N")
	)
	(segment
		(start 118.8593 -100.330508)
		(end 117.16766 -102.022148)
		(width 0.127)
		(layer "In6.Cu")
		(net "RST_PLD_CPU0_DRAM_CD_N")
	)
	(segment
		(start 100.44176 -105.644188)
		(end 97.29724 -102.499668)
		(width 0.127)
		(layer "In6.Cu")
		(net "RST_PLD_CPU0_DRAM_CD_N")
	)
	(segment
		(start 137.25398 -104.016048)
		(end 133.56844 -100.330508)
		(width 0.127)
		(layer "In6.Cu")
		(net "RST_PLD_CPU0_DRAM_CD_N")
	)
	(segment
		(start 164.15258 -104.351328)
		(end 163.8173 -104.016048)
		(width 0.127)
		(layer "In6.Cu")
		(net "RST_PLD_CPU0_DRAM_CD_N")
	)
	(segment
		(start 117.16766 -102.486968)
		(end 116.33708 -103.317548)
		(width 0.127)
		(layer "In6.Cu")
		(net "RST_PLD_CPU0_DRAM_CD_N")
	)
	(segment
		(start 117.16766 -102.022148)
		(end 117.16766 -102.486968)
		(width 0.127)
		(layer "In6.Cu")
		(net "RST_PLD_CPU0_DRAM_CD_N")
	)
	(segment
		(start 186.00928 -155.031948)
		(end 184.90438 -153.927048)
		(width 0.12954)
		(layer "F.Cu")
		(net "RST_PLD_CPU0_DRAM_AB_N")
	)
	(segment
		(start 176.276 -150.785068)
		(end 147.0914 -150.785068)
		(width 0.12954)
		(layer "F.Cu")
		(net "RST_PLD_CPU0_DRAM_AB_N")
	)
	(segment
		(start 202.4888 -152.987248)
		(end 200.31202 -155.164028)
		(width 0.12954)
		(layer "F.Cu")
		(net "RST_PLD_CPU0_DRAM_AB_N")
	)
	(segment
		(start 142.4178 -139.50442)
		(end 142.221458 -139.308078)
		(width 0.12954)
		(layer "F.Cu")
		(net "RST_PLD_CPU0_DRAM_AB_N")
	)
	(segment
		(start 171.83608 -98.766884)
		(end 171.205144 -98.135948)
		(width 0.12954)
		(layer "F.Cu")
		(net "RST_PLD_CPU0_DRAM_AB_N")
	)
	(segment
		(start 200.31202 -155.164028)
		(end 200.31202 -156.807408)
		(width 0.12954)
		(layer "F.Cu")
		(net "RST_PLD_CPU0_DRAM_AB_N")
	)
	(segment
		(start 143.61668 -141.808708)
		(end 142.4178 -140.609828)
		(width 0.12954)
		(layer "F.Cu")
		(net "RST_PLD_CPU0_DRAM_AB_N")
	)
	(segment
		(start 187.48248 -155.031948)
		(end 186.00928 -155.031948)
		(width 0.12954)
		(layer "F.Cu")
		(net "RST_PLD_CPU0_DRAM_AB_N")
	)
	(segment
		(start 202.4888 -152.370282)
		(end 202.4888 -152.987248)
		(width 0.12954)
		(layer "F.Cu")
		(net "RST_PLD_CPU0_DRAM_AB_N")
	)
	(segment
		(start 172.77588 -103.955088)
		(end 172.77588 -102.700582)
		(width 0.12954)
		(layer "F.Cu")
		(net "RST_PLD_CPU0_DRAM_AB_N")
	)
	(segment
		(start 142.4178 -140.609828)
		(end 142.4178 -139.50442)
		(width 0.12954)
		(layer "F.Cu")
		(net "RST_PLD_CPU0_DRAM_AB_N")
	)
	(segment
		(start 188.29528 -155.844748)
		(end 187.48248 -155.031948)
		(width 0.12954)
		(layer "F.Cu")
		(net "RST_PLD_CPU0_DRAM_AB_N")
	)
	(segment
		(start 171.83608 -101.031548)
		(end 171.83608 -98.766884)
		(width 0.12954)
		(layer "F.Cu")
		(net "RST_PLD_CPU0_DRAM_AB_N")
	)
	(segment
		(start 197.46468 -159.654748)
		(end 191.16548 -159.654748)
		(width 0.12954)
		(layer "F.Cu")
		(net "RST_PLD_CPU0_DRAM_AB_N")
	)
	(segment
		(start 147.0914 -150.785068)
		(end 143.61668 -147.310348)
		(width 0.12954)
		(layer "F.Cu")
		(net "RST_PLD_CPU0_DRAM_AB_N")
	)
	(segment
		(start 172.26026 -101.455728)
		(end 171.83608 -101.031548)
		(width 0.12954)
		(layer "F.Cu")
		(net "RST_PLD_CPU0_DRAM_AB_N")
	)
	(segment
		(start 171.755562 -104.975406)
		(end 172.77588 -103.955088)
		(width 0.12954)
		(layer "F.Cu")
		(net "RST_PLD_CPU0_DRAM_AB_N")
	)
	(segment
		(start 172.77588 -102.700582)
		(end 172.26026 -101.455728)
		(width 0.12954)
		(layer "F.Cu")
		(net "RST_PLD_CPU0_DRAM_AB_N")
	)
	(segment
		(start 160.229296 -98.135948)
		(end 157.2514 -95.158052)
		(width 0.12954)
		(layer "F.Cu")
		(net "RST_PLD_CPU0_DRAM_AB_N")
	)
	(segment
		(start 179.41798 -153.927048)
		(end 176.276 -150.785068)
		(width 0.12954)
		(layer "F.Cu")
		(net "RST_PLD_CPU0_DRAM_AB_N")
	)
	(segment
		(start 188.29528 -156.784548)
		(end 188.29528 -155.844748)
		(width 0.12954)
		(layer "F.Cu")
		(net "RST_PLD_CPU0_DRAM_AB_N")
	)
	(segment
		(start 93.145356 -93.063314)
		(end 92.459556 -93.063314)
		(width 0.12954)
		(layer "F.Cu")
		(net "RST_PLD_CPU0_DRAM_AB_N")
	)
	(segment
		(start 171.205144 -98.135948)
		(end 160.229296 -98.135948)
		(width 0.12954)
		(layer "F.Cu")
		(net "RST_PLD_CPU0_DRAM_AB_N")
	)
	(segment
		(start 191.16548 -159.654748)
		(end 188.29528 -156.784548)
		(width 0.12954)
		(layer "F.Cu")
		(net "RST_PLD_CPU0_DRAM_AB_N")
	)
	(segment
		(start 184.90438 -153.927048)
		(end 179.41798 -153.927048)
		(width 0.12954)
		(layer "F.Cu")
		(net "RST_PLD_CPU0_DRAM_AB_N")
	)
	(segment
		(start 200.31202 -156.807408)
		(end 197.46468 -159.654748)
		(width 0.12954)
		(layer "F.Cu")
		(net "RST_PLD_CPU0_DRAM_AB_N")
	)
	(segment
		(start 143.61668 -147.310348)
		(end 143.61668 -141.808708)
		(width 0.12954)
		(layer "F.Cu")
		(net "RST_PLD_CPU0_DRAM_AB_N")
	)
	(via
		(at 202.4888 -152.370282)
		(size 0.508)
		(drill 0.254)
		(layers "F.Cu" "B.Cu")
		(net "RST_PLD_CPU0_DRAM_AB_N")
	)
	(via
		(at 92.459556 -93.063314)
		(size 0.508)
		(drill 0.254)
		(layers "F.Cu" "B.Cu")
		(net "RST_PLD_CPU0_DRAM_AB_N")
	)
	(via
		(at 157.2514 -95.158052)
		(size 0.508)
		(drill 0.254)
		(layers "F.Cu" "B.Cu")
		(net "RST_PLD_CPU0_DRAM_AB_N")
	)
	(via
		(at 142.221458 -139.308078)
		(size 0.508)
		(drill 0.254)
		(layers "F.Cu" "B.Cu")
		(net "RST_PLD_CPU0_DRAM_AB_N")
	)
	(segment
		(start 118.90756 -92.293948)
		(end 118.19636 -93.005148)
		(width 0.12954)
		(layer "B.Cu")
		(net "RST_PLD_CPU0_DRAM_AB_N")
	)
	(segment
		(start 144.387824 -123.43638)
		(end 144.387824 -118.004336)
		(width 0.12954)
		(layer "B.Cu")
		(net "RST_PLD_CPU0_DRAM_AB_N")
	)
	(segment
		(start 270.518382 -187.15863)
		(end 239.71377 -156.354018)
		(width 0.12954)
		(layer "B.Cu")
		(net "RST_PLD_CPU0_DRAM_AB_N")
	)
	(segment
		(start 115.6208 -98.516948)
		(end 114.4016 -97.297748)
		(width 0.12954)
		(layer "B.Cu")
		(net "RST_PLD_CPU0_DRAM_AB_N")
	)
	(segment
		(start 93.863922 -91.658948)
		(end 92.459556 -93.063314)
		(width 0.12954)
		(layer "B.Cu")
		(net "RST_PLD_CPU0_DRAM_AB_N")
	)
	(segment
		(start 150.159212 -107.656884)
		(end 150.159212 -92.620846)
		(width 0.12954)
		(layer "B.Cu")
		(net "RST_PLD_CPU0_DRAM_AB_N")
	)
	(segment
		(start 118.19636 -95.486728)
		(end 118.59006 -95.880428)
		(width 0.12954)
		(layer "B.Cu")
		(net "RST_PLD_CPU0_DRAM_AB_N")
	)
	(segment
		(start 118.59006 -95.880428)
		(end 118.59006 -97.876868)
		(width 0.12954)
		(layer "B.Cu")
		(net "RST_PLD_CPU0_DRAM_AB_N")
	)
	(segment
		(start 140.70076 -137.78738)
		(end 140.70076 -127.123444)
		(width 0.12954)
		(layer "B.Cu")
		(net "RST_PLD_CPU0_DRAM_AB_N")
	)
	(segment
		(start 284.28442 -192.437512)
		(end 284.28442 -188.056012)
		(width 0.12954)
		(layer "B.Cu")
		(net "RST_PLD_CPU0_DRAM_AB_N")
	)
	(segment
		(start 284.28442 -188.056012)
		(end 283.387038 -187.15863)
		(width 0.12954)
		(layer "B.Cu")
		(net "RST_PLD_CPU0_DRAM_AB_N")
	)
	(segment
		(start 114.4016 -94.681802)
		(end 111.378746 -91.658948)
		(width 0.12954)
		(layer "B.Cu")
		(net "RST_PLD_CPU0_DRAM_AB_N")
	)
	(segment
		(start 121.188734 -92.293948)
		(end 118.90756 -92.293948)
		(width 0.12954)
		(layer "B.Cu")
		(net "RST_PLD_CPU0_DRAM_AB_N")
	)
	(segment
		(start 114.4016 -97.297748)
		(end 114.4016 -94.681802)
		(width 0.12954)
		(layer "B.Cu")
		(net "RST_PLD_CPU0_DRAM_AB_N")
	)
	(segment
		(start 206.472536 -156.354018)
		(end 202.4888 -152.370282)
		(width 0.12954)
		(layer "B.Cu")
		(net "RST_PLD_CPU0_DRAM_AB_N")
	)
	(segment
		(start 148.762212 -91.223846)
		(end 140.109448 -91.223846)
		(width 0.12954)
		(layer "B.Cu")
		(net "RST_PLD_CPU0_DRAM_AB_N")
	)
	(segment
		(start 148.77923 -109.036866)
		(end 150.159212 -107.656884)
		(width 0.12954)
		(layer "B.Cu")
		(net "RST_PLD_CPU0_DRAM_AB_N")
	)
	(segment
		(start 123.61037 -89.872312)
		(end 121.188734 -92.293948)
		(width 0.12954)
		(layer "B.Cu")
		(net "RST_PLD_CPU0_DRAM_AB_N")
	)
	(segment
		(start 118.19636 -93.005148)
		(end 118.19636 -95.486728)
		(width 0.12954)
		(layer "B.Cu")
		(net "RST_PLD_CPU0_DRAM_AB_N")
	)
	(segment
		(start 118.59006 -97.876868)
		(end 117.94998 -98.516948)
		(width 0.12954)
		(layer "B.Cu")
		(net "RST_PLD_CPU0_DRAM_AB_N")
	)
	(segment
		(start 283.387038 -187.15863)
		(end 270.518382 -187.15863)
		(width 0.12954)
		(layer "B.Cu")
		(net "RST_PLD_CPU0_DRAM_AB_N")
	)
	(segment
		(start 138.48969 -89.872312)
		(end 123.61037 -89.872312)
		(width 0.12954)
		(layer "B.Cu")
		(net "RST_PLD_CPU0_DRAM_AB_N")
	)
	(segment
		(start 139.330684 -90.445082)
		(end 139.06246 -90.445082)
		(width 0.12954)
		(layer "B.Cu")
		(net "RST_PLD_CPU0_DRAM_AB_N")
	)
	(segment
		(start 150.159212 -92.620846)
		(end 148.762212 -91.223846)
		(width 0.12954)
		(layer "B.Cu")
		(net "RST_PLD_CPU0_DRAM_AB_N")
	)
	(segment
		(start 148.77923 -113.61293)
		(end 148.77923 -109.036866)
		(width 0.12954)
		(layer "B.Cu")
		(net "RST_PLD_CPU0_DRAM_AB_N")
	)
	(segment
		(start 239.71377 -156.354018)
		(end 206.472536 -156.354018)
		(width 0.12954)
		(layer "B.Cu")
		(net "RST_PLD_CPU0_DRAM_AB_N")
	)
	(segment
		(start 285.462726 -193.291206)
		(end 284.446726 -193.291206)
		(width 0.12954)
		(layer "B.Cu")
		(net "RST_PLD_CPU0_DRAM_AB_N")
	)
	(segment
		(start 139.06246 -90.445082)
		(end 138.48969 -89.872312)
		(width 0.12954)
		(layer "B.Cu")
		(net "RST_PLD_CPU0_DRAM_AB_N")
	)
	(segment
		(start 283.430726 -193.291206)
		(end 284.28442 -192.437512)
		(width 0.12954)
		(layer "B.Cu")
		(net "RST_PLD_CPU0_DRAM_AB_N")
	)
	(segment
		(start 111.378746 -91.658948)
		(end 93.863922 -91.658948)
		(width 0.12954)
		(layer "B.Cu")
		(net "RST_PLD_CPU0_DRAM_AB_N")
	)
	(segment
		(start 283.430726 -193.291206)
		(end 284.446726 -193.291206)
		(width 0.12954)
		(layer "B.Cu")
		(net "RST_PLD_CPU0_DRAM_AB_N")
	)
	(segment
		(start 140.70076 -127.123444)
		(end 144.387824 -123.43638)
		(width 0.12954)
		(layer "B.Cu")
		(net "RST_PLD_CPU0_DRAM_AB_N")
	)
	(segment
		(start 142.221458 -139.308078)
		(end 140.70076 -137.78738)
		(width 0.12954)
		(layer "B.Cu")
		(net "RST_PLD_CPU0_DRAM_AB_N")
	)
	(segment
		(start 144.387824 -118.004336)
		(end 148.77923 -113.61293)
		(width 0.12954)
		(layer "B.Cu")
		(net "RST_PLD_CPU0_DRAM_AB_N")
	)
	(segment
		(start 140.109448 -91.223846)
		(end 139.330684 -90.445082)
		(width 0.12954)
		(layer "B.Cu")
		(net "RST_PLD_CPU0_DRAM_AB_N")
	)
	(segment
		(start 117.94998 -98.516948)
		(end 115.6208 -98.516948)
		(width 0.12954)
		(layer "B.Cu")
		(net "RST_PLD_CPU0_DRAM_AB_N")
	)
	(segment
		(start 92.459556 -90.091514)
		(end 92.459556 -93.063314)
		(width 0.127)
		(layer "In4.Cu")
		(net "RST_PLD_CPU0_DRAM_AB_N")
	)
	(segment
		(start 120.777 -87.340948)
		(end 95.210122 -87.340948)
		(width 0.127)
		(layer "In4.Cu")
		(net "RST_PLD_CPU0_DRAM_AB_N")
	)
	(segment
		(start 95.210122 -87.340948)
		(end 92.459556 -90.091514)
		(width 0.127)
		(layer "In4.Cu")
		(net "RST_PLD_CPU0_DRAM_AB_N")
	)
	(segment
		(start 157.2514 -95.158052)
		(end 157.2514 -94.882208)
		(width 0.127)
		(layer "In4.Cu")
		(net "RST_PLD_CPU0_DRAM_AB_N")
	)
	(segment
		(start 149.32914 -86.959948)
		(end 121.158 -86.959948)
		(width 0.127)
		(layer "In4.Cu")
		(net "RST_PLD_CPU0_DRAM_AB_N")
	)
	(segment
		(start 121.158 -86.959948)
		(end 120.777 -87.340948)
		(width 0.127)
		(layer "In4.Cu")
		(net "RST_PLD_CPU0_DRAM_AB_N")
	)
	(segment
		(start 157.2514 -94.882208)
		(end 149.32914 -86.959948)
		(width 0.127)
		(layer "In4.Cu")
		(net "RST_PLD_CPU0_DRAM_AB_N")
	)
	(segment
		(start 197.01383 -103.685848)
		(end 196.40423 -103.685848)
		(width 0.12954)
		(layer "F.Cu")
		(net "RST_PFR_OVR_SRTC_R")
	)
	(segment
		(start 183.755538 -109.775498)
		(end 184.155588 -109.375448)
		(width 0.12954)
		(layer "F.Cu")
		(net "RST_PFR_OVR_SRTC_R")
	)
	(via
		(at 196.40423 -103.685848)
		(size 0.508)
		(drill 0.254)
		(layers "F.Cu" "B.Cu")
		(net "RST_PFR_OVR_SRTC_R")
	)
	(via
		(at 184.155588 -109.375448)
		(size 0.4572)
		(drill 0.254)
		(layers "F.Cu" "B.Cu")
		(net "RST_PFR_OVR_SRTC_R")
	)
	(segment
		(start 189.95136 -109.769148)
		(end 184.549288 -109.769148)
		(width 0.127)
		(layer "In6.Cu")
		(net "RST_PFR_OVR_SRTC_R")
	)
	(segment
		(start 196.40423 -103.943658)
		(end 194.80022 -105.547668)
		(width 0.127)
		(layer "In6.Cu")
		(net "RST_PFR_OVR_SRTC_R")
	)
	(segment
		(start 184.549288 -109.769148)
		(end 184.155588 -109.375448)
		(width 0.127)
		(layer "In6.Cu")
		(net "RST_PFR_OVR_SRTC_R")
	)
	(segment
		(start 196.40423 -103.685848)
		(end 196.40423 -103.943658)
		(width 0.127)
		(layer "In6.Cu")
		(net "RST_PFR_OVR_SRTC_R")
	)
	(segment
		(start 194.80022 -105.547668)
		(end 194.17284 -105.547668)
		(width 0.127)
		(layer "In6.Cu")
		(net "RST_PFR_OVR_SRTC_R")
	)
	(segment
		(start 194.17284 -105.547668)
		(end 189.95136 -109.769148)
		(width 0.127)
		(layer "In6.Cu")
		(net "RST_PFR_OVR_SRTC_R")
	)
	(segment
		(start 202.80376 -105.03916)
		(end 202.679554 -104.914954)
		(width 0.12954)
		(layer "F.Cu")
		(net "RST_PFR_OVR_SRTC")
	)
	(segment
		(start 202.905614 -105.715054)
		(end 202.80376 -105.6132)
		(width 0.12954)
		(layer "F.Cu")
		(net "RST_PFR_OVR_SRTC")
	)
	(segment
		(start 203.326492 -105.715054)
		(end 203.37653 -105.665016)
		(width 0.12954)
		(layer "F.Cu")
		(net "RST_PFR_OVR_SRTC")
	)
	(segment
		(start 201.95413 -104.5464)
		(end 202.322684 -104.914954)
		(width 0.12954)
		(layer "F.Cu")
		(net "RST_PFR_OVR_SRTC")
	)
	(segment
		(start 202.679554 -104.914954)
		(end 202.322684 -104.914954)
		(width 0.12954)
		(layer "F.Cu")
		(net "RST_PFR_OVR_SRTC")
	)
	(segment
		(start 203.326492 -105.715054)
		(end 202.905614 -105.715054)
		(width 0.12954)
		(layer "F.Cu")
		(net "RST_PFR_OVR_SRTC")
	)
	(segment
		(start 199.85482 -104.5464)
		(end 201.95413 -104.5464)
		(width 0.12954)
		(layer "F.Cu")
		(net "RST_PFR_OVR_SRTC")
	)
	(segment
		(start 198.923148 -103.685848)
		(end 197.81393 -103.685848)
		(width 0.12954)
		(layer "F.Cu")
		(net "RST_PFR_OVR_SRTC")
	)
	(segment
		(start 199.7837 -104.5464)
		(end 198.923148 -103.685848)
		(width 0.12954)
		(layer "F.Cu")
		(net "RST_PFR_OVR_SRTC")
	)
	(segment
		(start 203.37653 -105.665016)
		(end 204.968094 -105.665016)
		(width 0.12954)
		(layer "F.Cu")
		(net "RST_PFR_OVR_SRTC")
	)
	(segment
		(start 199.85482 -104.5464)
		(end 199.7837 -104.5464)
		(width 0.12954)
		(layer "F.Cu")
		(net "RST_PFR_OVR_SRTC")
	)
	(segment
		(start 202.80376 -105.6132)
		(end 202.80376 -105.03916)
		(width 0.12954)
		(layer "F.Cu")
		(net "RST_PFR_OVR_SRTC")
	)
	(via
		(at 199.85482 -104.5464)
		(size 0.762)
		(drill 0.381)
		(layers "F.Cu" "B.Cu")
		(net "RST_PFR_OVR_SRTC")
	)
	(segment
		(start 184.555638 -108.975398)
		(end 184.955688 -108.575348)
		(width 0.12954)
		(layer "F.Cu")
		(net "RST_PFR_OVR_RTC_R")
	)
	(segment
		(start 197.01383 -102.415848)
		(end 196.40423 -102.415848)
		(width 0.12954)
		(layer "F.Cu")
		(net "RST_PFR_OVR_RTC_R")
	)
	(via
		(at 196.40423 -102.415848)
		(size 0.508)
		(drill 0.254)
		(layers "F.Cu" "B.Cu")
		(net "RST_PFR_OVR_RTC_R")
	)
	(via
		(at 184.955688 -108.575348)
		(size 0.4572)
		(drill 0.254)
		(layers "F.Cu" "B.Cu")
		(net "RST_PFR_OVR_RTC_R")
	)
	(segment
		(start 196.40423 -102.415848)
		(end 196.40423 -102.88143)
		(width 0.127)
		(layer "In6.Cu")
		(net "RST_PFR_OVR_RTC_R")
	)
	(segment
		(start 189.57036 -108.979208)
		(end 185.359548 -108.979208)
		(width 0.127)
		(layer "In6.Cu")
		(net "RST_PFR_OVR_RTC_R")
	)
	(segment
		(start 194.921632 -104.364028)
		(end 194.18554 -104.364028)
		(width 0.127)
		(layer "In6.Cu")
		(net "RST_PFR_OVR_RTC_R")
	)
	(segment
		(start 196.40423 -102.88143)
		(end 194.921632 -104.364028)
		(width 0.127)
		(layer "In6.Cu")
		(net "RST_PFR_OVR_RTC_R")
	)
	(segment
		(start 194.18554 -104.364028)
		(end 189.57036 -108.979208)
		(width 0.127)
		(layer "In6.Cu")
		(net "RST_PFR_OVR_RTC_R")
	)
	(segment
		(start 185.359548 -108.979208)
		(end 184.955688 -108.575348)
		(width 0.127)
		(layer "In6.Cu")
		(net "RST_PFR_OVR_RTC_R")
	)
	(segment
		(start 204.968094 -101.956616)
		(end 203.37653 -101.956616)
		(width 0.12954)
		(layer "F.Cu")
		(net "RST_PFR_OVR_RTC")
	)
	(segment
		(start 200.62063 -101.842824)
		(end 200.761854 -101.7016)
		(width 0.12954)
		(layer "F.Cu")
		(net "RST_PFR_OVR_RTC")
	)
	(segment
		(start 199.38746 -102.235)
		(end 200.62063 -102.235)
		(width 0.12954)
		(layer "F.Cu")
		(net "RST_PFR_OVR_RTC")
	)
	(segment
		(start 197.81393 -102.415848)
		(end 199.206612 -102.415848)
		(width 0.12954)
		(layer "F.Cu")
		(net "RST_PFR_OVR_RTC")
	)
	(segment
		(start 200.62063 -102.235)
		(end 200.62063 -101.842824)
		(width 0.12954)
		(layer "F.Cu")
		(net "RST_PFR_OVR_RTC")
	)
	(segment
		(start 203.37653 -101.956616)
		(end 203.326492 -102.006654)
		(width 0.12954)
		(layer "F.Cu")
		(net "RST_PFR_OVR_RTC")
	)
	(segment
		(start 200.761854 -101.7016)
		(end 203.021438 -101.7016)
		(width 0.12954)
		(layer "F.Cu")
		(net "RST_PFR_OVR_RTC")
	)
	(segment
		(start 203.021438 -101.7016)
		(end 203.326492 -102.006654)
		(width 0.12954)
		(layer "F.Cu")
		(net "RST_PFR_OVR_RTC")
	)
	(segment
		(start 199.206612 -102.415848)
		(end 199.38746 -102.235)
		(width 0.12954)
		(layer "F.Cu")
		(net "RST_PFR_OVR_RTC")
	)
	(via
		(at 199.206612 -102.415848)
		(size 0.762)
		(drill 0.381)
		(layers "F.Cu" "B.Cu")
		(net "RST_PFR_OVR_RTC")
	)
	(segment
		(start 449.896484 -4.54787)
		(end 449.495926 -4.147312)
		(width 0.12954)
		(layer "F.Cu")
		(net "RST_PERST3_OCP_SFF_N")
	)
	(segment
		(start 451.446138 -6.265418)
		(end 450.713094 -6.265418)
		(width 0.12954)
		(layer "F.Cu")
		(net "RST_PERST3_OCP_SFF_N")
	)
	(segment
		(start 451.779386 -7.206488)
		(end 451.779386 -6.598666)
		(width 0.12954)
		(layer "F.Cu")
		(net "RST_PERST3_OCP_SFF_N")
	)
	(segment
		(start 449.495926 -4.147312)
		(end 449.495926 -3.871976)
		(width 0.12954)
		(layer "F.Cu")
		(net "RST_PERST3_OCP_SFF_N")
	)
	(segment
		(start 451.779386 -6.598666)
		(end 451.446138 -6.265418)
		(width 0.12954)
		(layer "F.Cu")
		(net "RST_PERST3_OCP_SFF_N")
	)
	(segment
		(start 451.961758 -8.320024)
		(end 451.961758 -7.38886)
		(width 0.12954)
		(layer "F.Cu")
		(net "RST_PERST3_OCP_SFF_N")
	)
	(segment
		(start 450.534024 -6.086348)
		(end 449.896484 -4.54787)
		(width 0.12954)
		(layer "F.Cu")
		(net "RST_PERST3_OCP_SFF_N")
	)
	(segment
		(start 450.713094 -6.265418)
		(end 450.534024 -6.086348)
		(width 0.12954)
		(layer "F.Cu")
		(net "RST_PERST3_OCP_SFF_N")
	)
	(segment
		(start 451.961758 -7.38886)
		(end 451.779386 -7.206488)
		(width 0.12954)
		(layer "F.Cu")
		(net "RST_PERST3_OCP_SFF_N")
	)
	(via
		(at 449.495926 -3.871976)
		(size 0.508)
		(drill 0.254)
		(layers "F.Cu" "B.Cu")
		(net "RST_PERST3_OCP_SFF_N")
	)
	(segment
		(start 449.895468 -4.271518)
		(end 450.70649 -4.271518)
		(width 0.12954)
		(layer "B.Cu")
		(net "RST_PERST3_OCP_SFF_N")
	)
	(segment
		(start 449.495926 -3.871976)
		(end 449.895468 -4.271518)
		(width 0.12954)
		(layer "B.Cu")
		(net "RST_PERST3_OCP_SFF_N")
	)
	(segment
		(start 451.868794 -5.453634)
		(end 452.56196 -6.1468)
		(width 0.12954)
		(layer "F.Cu")
		(net "RST_PERST2_OCP_SFF_N")
	)
	(segment
		(start 450.991224 -5.453634)
		(end 451.868794 -5.453634)
		(width 0.12954)
		(layer "F.Cu")
		(net "RST_PERST2_OCP_SFF_N")
	)
	(segment
		(start 452.56196 -6.1468)
		(end 452.56196 -8.320024)
		(width 0.12954)
		(layer "F.Cu")
		(net "RST_PERST2_OCP_SFF_N")
	)
	(via
		(at 450.991224 -5.453634)
		(size 0.508)
		(drill 0.254)
		(layers "F.Cu" "B.Cu")
		(net "RST_PERST2_OCP_SFF_N")
	)
	(segment
		(start 451.858126 -5.453634)
		(end 452.01205 -5.29971)
		(width 0.12954)
		(layer "B.Cu")
		(net "RST_PERST2_OCP_SFF_N")
	)
	(segment
		(start 452.01205 -5.29971)
		(end 452.01205 -4.266438)
		(width 0.12954)
		(layer "B.Cu")
		(net "RST_PERST2_OCP_SFF_N")
	)
	(segment
		(start 450.991224 -5.453634)
		(end 451.858126 -5.453634)
		(width 0.12954)
		(layer "B.Cu")
		(net "RST_PERST2_OCP_SFF_N")
	)
	(segment
		(start 434.366924 -7.17169)
		(end 434.235606 -7.040372)
		(width 0.12954)
		(layer "F.Cu")
		(net "RST_PERST1_OCP_SFF_N")
	)
	(segment
		(start 434.366924 -8.320024)
		(end 434.366924 -7.17169)
		(width 0.12954)
		(layer "F.Cu")
		(net "RST_PERST1_OCP_SFF_N")
	)
	(segment
		(start 434.235606 -7.040372)
		(end 434.235606 -6.619748)
		(width 0.12954)
		(layer "F.Cu")
		(net "RST_PERST1_OCP_SFF_N")
	)
	(via
		(at 434.235606 -6.619748)
		(size 0.508)
		(drill 0.254)
		(layers "F.Cu" "B.Cu")
		(net "RST_PERST1_OCP_SFF_N")
	)
	(segment
		(start 434.235606 -6.619748)
		(end 434.34635 -6.509004)
		(width 0.12954)
		(layer "B.Cu")
		(net "RST_PERST1_OCP_SFF_N")
	)
	(segment
		(start 434.34635 -6.509004)
		(end 434.34635 -5.452618)
		(width 0.12954)
		(layer "B.Cu")
		(net "RST_PERST1_OCP_SFF_N")
	)
	(segment
		(start 435.948328 -15.848076)
		(end 436.08625 -15.848076)
		(width 0.12954)
		(layer "F.Cu")
		(net "RST_PERST0_OCP_SFF_N")
	)
	(segment
		(start 434.966872 -12.736576)
		(end 434.62956 -13.073888)
		(width 0.12954)
		(layer "F.Cu")
		(net "RST_PERST0_OCP_SFF_N")
	)
	(segment
		(start 434.62956 -14.529308)
		(end 435.948328 -15.848076)
		(width 0.12954)
		(layer "F.Cu")
		(net "RST_PERST0_OCP_SFF_N")
	)
	(segment
		(start 434.966872 -11.26998)
		(end 434.966872 -12.736576)
		(width 0.12954)
		(layer "F.Cu")
		(net "RST_PERST0_OCP_SFF_N")
	)
	(segment
		(start 434.62956 -13.073888)
		(end 434.62956 -14.529308)
		(width 0.12954)
		(layer "F.Cu")
		(net "RST_PERST0_OCP_SFF_N")
	)
	(via
		(at 434.62956 -14.529308)
		(size 0.762)
		(drill 0.381)
		(layers "F.Cu" "B.Cu")
		(net "RST_PERST0_OCP_SFF_N")
	)
	(segment
		(start 204.53731 -120.614948)
		(end 203.92771 -120.614948)
		(width 0.12954)
		(layer "F.Cu")
		(net "RST_PCIE_PCH_DEV_PERST_N")
	)
	(segment
		(start 204.53731 -119.344948)
		(end 204.53731 -120.614948)
		(width 0.12954)
		(layer "F.Cu")
		(net "RST_PCIE_PCH_DEV_PERST_N")
	)
	(segment
		(start 182.955692 -115.375436)
		(end 183.355742 -115.775486)
		(width 0.12954)
		(layer "F.Cu")
		(net "RST_PCIE_PCH_DEV_PERST_N")
	)
	(via
		(at 203.92771 -120.614948)
		(size 0.508)
		(drill 0.254)
		(layers "F.Cu" "B.Cu")
		(net "RST_PCIE_PCH_DEV_PERST_N")
	)
	(via
		(at 183.355742 -115.775486)
		(size 0.4572)
		(drill 0.254)
		(layers "F.Cu" "B.Cu")
		(net "RST_PCIE_PCH_DEV_PERST_N")
	)
	(segment
		(start 183.75884 -115.372388)
		(end 187.44692 -115.372388)
		(width 0.12954)
		(layer "B.Cu")
		(net "RST_PCIE_PCH_DEV_PERST_N")
	)
	(segment
		(start 183.355742 -115.775486)
		(end 183.75884 -115.372388)
		(width 0.12954)
		(layer "B.Cu")
		(net "RST_PCIE_PCH_DEV_PERST_N")
	)
	(segment
		(start 190.14948 -118.074948)
		(end 192.98031 -118.074948)
		(width 0.12954)
		(layer "B.Cu")
		(net "RST_PCIE_PCH_DEV_PERST_N")
	)
	(segment
		(start 187.44692 -115.372388)
		(end 190.14948 -118.074948)
		(width 0.12954)
		(layer "B.Cu")
		(net "RST_PCIE_PCH_DEV_PERST_N")
	)
	(segment
		(start 187.93968 -116.38026)
		(end 187.73648 -116.17706)
		(width 0.127)
		(layer "In6.Cu")
		(net "RST_PCIE_PCH_DEV_PERST_N")
	)
	(segment
		(start 199.98182 -118.5926)
		(end 193.36004 -118.5926)
		(width 0.127)
		(layer "In6.Cu")
		(net "RST_PCIE_PCH_DEV_PERST_N")
	)
	(segment
		(start 191.1477 -116.38026)
		(end 187.93968 -116.38026)
		(width 0.127)
		(layer "In6.Cu")
		(net "RST_PCIE_PCH_DEV_PERST_N")
	)
	(segment
		(start 193.36004 -118.5926)
		(end 191.1477 -116.38026)
		(width 0.127)
		(layer "In6.Cu")
		(net "RST_PCIE_PCH_DEV_PERST_N")
	)
	(segment
		(start 203.92771 -120.32361)
		(end 203.317348 -119.713248)
		(width 0.127)
		(layer "In6.Cu")
		(net "RST_PCIE_PCH_DEV_PERST_N")
	)
	(segment
		(start 184.325006 -115.775486)
		(end 183.355742 -115.775486)
		(width 0.127)
		(layer "In6.Cu")
		(net "RST_PCIE_PCH_DEV_PERST_N")
	)
	(segment
		(start 201.102468 -119.713248)
		(end 199.98182 -118.5926)
		(width 0.127)
		(layer "In6.Cu")
		(net "RST_PCIE_PCH_DEV_PERST_N")
	)
	(segment
		(start 203.317348 -119.713248)
		(end 201.102468 -119.713248)
		(width 0.127)
		(layer "In6.Cu")
		(net "RST_PCIE_PCH_DEV_PERST_N")
	)
	(segment
		(start 203.92771 -120.614948)
		(end 203.92771 -120.32361)
		(width 0.127)
		(layer "In6.Cu")
		(net "RST_PCIE_PCH_DEV_PERST_N")
	)
	(segment
		(start 184.72658 -116.17706)
		(end 184.325006 -115.775486)
		(width 0.127)
		(layer "In6.Cu")
		(net "RST_PCIE_PCH_DEV_PERST_N")
	)
	(segment
		(start 187.73648 -116.17706)
		(end 184.72658 -116.17706)
		(width 0.127)
		(layer "In6.Cu")
		(net "RST_PCIE_PCH_DEV_PERST_N")
	)
	(segment
		(start 153.33472 -47.523908)
		(end 153.33472 -43.787568)
		(width 0.12954)
		(layer "F.Cu")
		(net "RST_PCIE_PCH_DEV_0_N")
	)
	(segment
		(start 166.455598 -44.04995)
		(end 166.19855 -44.306998)
		(width 0.12954)
		(layer "F.Cu")
		(net "RST_PCIE_PCH_DEV_0_N")
	)
	(segment
		(start 160.75914 -48.913288)
		(end 160.47212 -49.200308)
		(width 0.12954)
		(layer "F.Cu")
		(net "RST_PCIE_PCH_DEV_0_N")
	)
	(segment
		(start 152.11552 -42.568368)
		(end 150.04034 -42.568368)
		(width 0.12954)
		(layer "F.Cu")
		(net "RST_PCIE_PCH_DEV_0_N")
	)
	(segment
		(start 166.19855 -44.306998)
		(end 162.222942 -44.306998)
		(width 0.12954)
		(layer "F.Cu")
		(net "RST_PCIE_PCH_DEV_0_N")
	)
	(segment
		(start 146.84248 -41.676828)
		(end 143.51381 -41.676828)
		(width 0.12954)
		(layer "F.Cu")
		(net "RST_PCIE_PCH_DEV_0_N")
	)
	(segment
		(start 160.47212 -49.200308)
		(end 155.01112 -49.200308)
		(width 0.12954)
		(layer "F.Cu")
		(net "RST_PCIE_PCH_DEV_0_N")
	)
	(segment
		(start 160.75914 -45.7708)
		(end 160.75914 -48.913288)
		(width 0.12954)
		(layer "F.Cu")
		(net "RST_PCIE_PCH_DEV_0_N")
	)
	(segment
		(start 169.557954 -44.04995)
		(end 166.455598 -44.04995)
		(width 0.12954)
		(layer "F.Cu")
		(net "RST_PCIE_PCH_DEV_0_N")
	)
	(segment
		(start 143.51381 -41.676828)
		(end 142.82293 -40.985948)
		(width 0.12954)
		(layer "F.Cu")
		(net "RST_PCIE_PCH_DEV_0_N")
	)
	(segment
		(start 148.78812 -41.316148)
		(end 147.20316 -41.316148)
		(width 0.12954)
		(layer "F.Cu")
		(net "RST_PCIE_PCH_DEV_0_N")
	)
	(segment
		(start 162.222942 -44.306998)
		(end 160.75914 -45.7708)
		(width 0.12954)
		(layer "F.Cu")
		(net "RST_PCIE_PCH_DEV_0_N")
	)
	(segment
		(start 153.33472 -43.787568)
		(end 152.11552 -42.568368)
		(width 0.12954)
		(layer "F.Cu")
		(net "RST_PCIE_PCH_DEV_0_N")
	)
	(segment
		(start 150.04034 -42.568368)
		(end 148.78812 -41.316148)
		(width 0.12954)
		(layer "F.Cu")
		(net "RST_PCIE_PCH_DEV_0_N")
	)
	(segment
		(start 147.20316 -41.316148)
		(end 146.84248 -41.676828)
		(width 0.12954)
		(layer "F.Cu")
		(net "RST_PCIE_PCH_DEV_0_N")
	)
	(segment
		(start 155.01112 -49.200308)
		(end 153.33472 -47.523908)
		(width 0.12954)
		(layer "F.Cu")
		(net "RST_PCIE_PCH_DEV_0_N")
	)
	(via
		(at 166.19855 -44.306998)
		(size 0.762)
		(drill 0.381)
		(layers "F.Cu" "B.Cu")
		(net "RST_PCIE_PCH_DEV_0_N")
	)
	(segment
		(start 84.819744 -105.861104)
		(end 78.913228 -105.861104)
		(width 0.12954)
		(layer "F.Cu")
		(net "RST_PCIE_CPU1_DEV_PERST_N")
	)
	(segment
		(start 178.9557 -119.375428)
		(end 179.35575 -119.775478)
		(width 0.12954)
		(layer "F.Cu")
		(net "RST_PCIE_CPU1_DEV_PERST_N")
	)
	(segment
		(start 90.218006 -36.643818)
		(end 89.862914 -36.288726)
		(width 0.12954)
		(layer "F.Cu")
		(net "RST_PCIE_CPU1_DEV_PERST_N")
	)
	(segment
		(start 58.43651 -67.775074)
		(end 58.43651 -45.794168)
		(width 0.12954)
		(layer "F.Cu")
		(net "RST_PCIE_CPU1_DEV_PERST_N")
	)
	(segment
		(start 89.862914 -36.288726)
		(end 89.055702 -36.288726)
		(width 0.12954)
		(layer "F.Cu")
		(net "RST_PCIE_CPU1_DEV_PERST_N")
	)
	(segment
		(start 54.98592 -71.225664)
		(end 58.43651 -67.775074)
		(width 0.12954)
		(layer "F.Cu")
		(net "RST_PCIE_CPU1_DEV_PERST_N")
	)
	(segment
		(start 92.905834 -114.16792)
		(end 92.905834 -113.947194)
		(width 0.12954)
		(layer "F.Cu")
		(net "RST_PCIE_CPU1_DEV_PERST_N")
	)
	(segment
		(start 180.64988 -129.866898)
		(end 180.64988 -129.256028)
		(width 0.12954)
		(layer "F.Cu")
		(net "RST_PCIE_CPU1_DEV_PERST_N")
	)
	(segment
		(start 92.905834 -113.947194)
		(end 84.819744 -105.861104)
		(width 0.12954)
		(layer "F.Cu")
		(net "RST_PCIE_CPU1_DEV_PERST_N")
	)
	(segment
		(start 59.665108 -44.56557)
		(end 59.665108 -44.207938)
		(width 0.12954)
		(layer "F.Cu")
		(net "RST_PCIE_CPU1_DEV_PERST_N")
	)
	(segment
		(start 78.913228 -105.861104)
		(end 54.98592 -81.933796)
		(width 0.12954)
		(layer "F.Cu")
		(net "RST_PCIE_CPU1_DEV_PERST_N")
	)
	(segment
		(start 58.43651 -45.794168)
		(end 59.665108 -44.56557)
		(width 0.12954)
		(layer "F.Cu")
		(net "RST_PCIE_CPU1_DEV_PERST_N")
	)
	(segment
		(start 54.98592 -81.933796)
		(end 54.98592 -71.225664)
		(width 0.12954)
		(layer "F.Cu")
		(net "RST_PCIE_CPU1_DEV_PERST_N")
	)
	(via
		(at 90.218006 -36.643818)
		(size 0.508)
		(drill 0.254)
		(layers "F.Cu" "B.Cu")
		(net "RST_PCIE_CPU1_DEV_PERST_N")
	)
	(via
		(at 59.665108 -44.207938)
		(size 0.508)
		(drill 0.254)
		(layers "F.Cu" "B.Cu")
		(net "RST_PCIE_CPU1_DEV_PERST_N")
	)
	(via
		(at 179.35575 -119.775478)
		(size 0.4572)
		(drill 0.254)
		(layers "F.Cu" "B.Cu")
		(net "RST_PCIE_CPU1_DEV_PERST_N")
	)
	(via
		(at 150.50008 -118.786148)
		(size 0.508)
		(drill 0.254)
		(layers "F.Cu" "B.Cu")
		(net "RST_PCIE_CPU1_DEV_PERST_N")
	)
	(via
		(at 92.905834 -114.16792)
		(size 0.508)
		(drill 0.254)
		(layers "F.Cu" "B.Cu")
		(net "RST_PCIE_CPU1_DEV_PERST_N")
	)
	(via
		(at 180.64988 -129.256028)
		(size 0.508)
		(drill 0.254)
		(layers "F.Cu" "B.Cu")
		(net "RST_PCIE_CPU1_DEV_PERST_N")
	)
	(segment
		(start 178.8033 -120.327928)
		(end 179.35575 -119.775478)
		(width 0.127)
		(layer "In2.Cu")
		(net "RST_PCIE_CPU1_DEV_PERST_N")
	)
	(segment
		(start 178.4096 -123.767088)
		(end 178.4096 -123.035568)
		(width 0.127)
		(layer "In2.Cu")
		(net "RST_PCIE_CPU1_DEV_PERST_N")
	)
	(segment
		(start 180.64988 -129.256028)
		(end 179.78882 -128.394968)
		(width 0.127)
		(layer "In2.Cu")
		(net "RST_PCIE_CPU1_DEV_PERST_N")
	)
	(segment
		(start 178.74234 -122.702828)
		(end 178.74234 -121.321068)
		(width 0.127)
		(layer "In2.Cu")
		(net "RST_PCIE_CPU1_DEV_PERST_N")
	)
	(segment
		(start 178.4096 -123.035568)
		(end 178.74234 -122.702828)
		(width 0.127)
		(layer "In2.Cu")
		(net "RST_PCIE_CPU1_DEV_PERST_N")
	)
	(segment
		(start 179.78882 -128.394968)
		(end 179.78882 -127.83058)
		(width 0.127)
		(layer "In2.Cu")
		(net "RST_PCIE_CPU1_DEV_PERST_N")
	)
	(segment
		(start 179.78882 -127.83058)
		(end 178.0413 -126.08306)
		(width 0.127)
		(layer "In2.Cu")
		(net "RST_PCIE_CPU1_DEV_PERST_N")
	)
	(segment
		(start 178.74234 -121.321068)
		(end 178.8033 -121.260108)
		(width 0.127)
		(layer "In2.Cu")
		(net "RST_PCIE_CPU1_DEV_PERST_N")
	)
	(segment
		(start 178.0413 -124.135388)
		(end 178.4096 -123.767088)
		(width 0.127)
		(layer "In2.Cu")
		(net "RST_PCIE_CPU1_DEV_PERST_N")
	)
	(segment
		(start 178.0413 -126.08306)
		(end 178.0413 -124.135388)
		(width 0.127)
		(layer "In2.Cu")
		(net "RST_PCIE_CPU1_DEV_PERST_N")
	)
	(segment
		(start 178.8033 -121.260108)
		(end 178.8033 -120.327928)
		(width 0.127)
		(layer "In2.Cu")
		(net "RST_PCIE_CPU1_DEV_PERST_N")
	)
	(segment
		(start 172.339 -129.720848)
		(end 172.92066 -130.302508)
		(width 0.127)
		(layer "In4.Cu")
		(net "RST_PCIE_CPU1_DEV_PERST_N")
	)
	(segment
		(start 162.70478 -130.157728)
		(end 167.27678 -130.157728)
		(width 0.127)
		(layer "In4.Cu")
		(net "RST_PCIE_CPU1_DEV_PERST_N")
	)
	(segment
		(start 72.525382 -42.27576)
		(end 73.2155 -42.965878)
		(width 0.127)
		(layer "In4.Cu")
		(net "RST_PCIE_CPU1_DEV_PERST_N")
	)
	(segment
		(start 61.597286 -42.27576)
		(end 72.525382 -42.27576)
		(width 0.127)
		(layer "In4.Cu")
		(net "RST_PCIE_CPU1_DEV_PERST_N")
	)
	(segment
		(start 179.6034 -130.302508)
		(end 180.64988 -129.256028)
		(width 0.127)
		(layer "In4.Cu")
		(net "RST_PCIE_CPU1_DEV_PERST_N")
	)
	(segment
		(start 172.92066 -130.302508)
		(end 179.6034 -130.302508)
		(width 0.127)
		(layer "In4.Cu")
		(net "RST_PCIE_CPU1_DEV_PERST_N")
	)
	(segment
		(start 84.80679 -39.653972)
		(end 87.98052 -36.480242)
		(width 0.127)
		(layer "In4.Cu")
		(net "RST_PCIE_CPU1_DEV_PERST_N")
	)
	(segment
		(start 151.3332 -118.786148)
		(end 162.70478 -130.157728)
		(width 0.127)
		(layer "In4.Cu")
		(net "RST_PCIE_CPU1_DEV_PERST_N")
	)
	(segment
		(start 73.2155 -42.965878)
		(end 80.142334 -42.965878)
		(width 0.127)
		(layer "In4.Cu")
		(net "RST_PCIE_CPU1_DEV_PERST_N")
	)
	(segment
		(start 90.05443 -36.480242)
		(end 90.218006 -36.643818)
		(width 0.127)
		(layer "In4.Cu")
		(net "RST_PCIE_CPU1_DEV_PERST_N")
	)
	(segment
		(start 167.27678 -130.157728)
		(end 167.71366 -129.720848)
		(width 0.127)
		(layer "In4.Cu")
		(net "RST_PCIE_CPU1_DEV_PERST_N")
	)
	(segment
		(start 59.665108 -44.207938)
		(end 61.597286 -42.27576)
		(width 0.127)
		(layer "In4.Cu")
		(net "RST_PCIE_CPU1_DEV_PERST_N")
	)
	(segment
		(start 167.71366 -129.720848)
		(end 172.339 -129.720848)
		(width 0.127)
		(layer "In4.Cu")
		(net "RST_PCIE_CPU1_DEV_PERST_N")
	)
	(segment
		(start 83.45424 -39.653972)
		(end 84.80679 -39.653972)
		(width 0.127)
		(layer "In4.Cu")
		(net "RST_PCIE_CPU1_DEV_PERST_N")
	)
	(segment
		(start 80.142334 -42.965878)
		(end 83.45424 -39.653972)
		(width 0.127)
		(layer "In4.Cu")
		(net "RST_PCIE_CPU1_DEV_PERST_N")
	)
	(segment
		(start 150.50008 -118.786148)
		(end 151.3332 -118.786148)
		(width 0.127)
		(layer "In4.Cu")
		(net "RST_PCIE_CPU1_DEV_PERST_N")
	)
	(segment
		(start 87.98052 -36.480242)
		(end 90.05443 -36.480242)
		(width 0.127)
		(layer "In4.Cu")
		(net "RST_PCIE_CPU1_DEV_PERST_N")
	)
	(segment
		(start 147.22348 -113.74882)
		(end 147.22348 -115.509548)
		(width 0.127)
		(layer "In13.Cu")
		(net "RST_PCIE_CPU1_DEV_PERST_N")
	)
	(segment
		(start 143.53032 -111.64824)
		(end 145.1229 -111.64824)
		(width 0.127)
		(layer "In13.Cu")
		(net "RST_PCIE_CPU1_DEV_PERST_N")
	)
	(segment
		(start 138.509248 -110.068868)
		(end 140.459968 -112.019588)
		(width 0.127)
		(layer "In13.Cu")
		(net "RST_PCIE_CPU1_DEV_PERST_N")
	)
	(segment
		(start 147.22348 -115.509548)
		(end 150.50008 -118.786148)
		(width 0.127)
		(layer "In13.Cu")
		(net "RST_PCIE_CPU1_DEV_PERST_N")
	)
	(segment
		(start 103.48468 -114.569748)
		(end 105.66908 -112.385348)
		(width 0.127)
		(layer "In13.Cu")
		(net "RST_PCIE_CPU1_DEV_PERST_N")
	)
	(segment
		(start 143.158972 -112.019588)
		(end 143.53032 -111.64824)
		(width 0.127)
		(layer "In13.Cu")
		(net "RST_PCIE_CPU1_DEV_PERST_N")
	)
	(segment
		(start 140.459968 -112.019588)
		(end 143.158972 -112.019588)
		(width 0.127)
		(layer "In13.Cu")
		(net "RST_PCIE_CPU1_DEV_PERST_N")
	)
	(segment
		(start 92.905834 -114.16792)
		(end 93.307662 -114.569748)
		(width 0.127)
		(layer "In13.Cu")
		(net "RST_PCIE_CPU1_DEV_PERST_N")
	)
	(segment
		(start 145.1229 -111.64824)
		(end 147.22348 -113.74882)
		(width 0.127)
		(layer "In13.Cu")
		(net "RST_PCIE_CPU1_DEV_PERST_N")
	)
	(segment
		(start 105.66908 -112.385348)
		(end 131.14528 -112.385348)
		(width 0.127)
		(layer "In13.Cu")
		(net "RST_PCIE_CPU1_DEV_PERST_N")
	)
	(segment
		(start 131.14528 -112.385348)
		(end 133.46176 -110.068868)
		(width 0.127)
		(layer "In13.Cu")
		(net "RST_PCIE_CPU1_DEV_PERST_N")
	)
	(segment
		(start 93.307662 -114.569748)
		(end 103.48468 -114.569748)
		(width 0.127)
		(layer "In13.Cu")
		(net "RST_PCIE_CPU1_DEV_PERST_N")
	)
	(segment
		(start 133.46176 -110.068868)
		(end 138.509248 -110.068868)
		(width 0.127)
		(layer "In13.Cu")
		(net "RST_PCIE_CPU1_DEV_PERST_N")
	)
	(segment
		(start 178.44008 -125.237748)
		(end 178.08448 -124.882148)
		(width 0.12954)
		(layer "F.Cu")
		(net "RST_PCIE_CPU0_DEV_PERST_N")
	)
	(segment
		(start 178.08448 -124.247148)
		(end 178.56708 -123.764548)
		(width 0.12954)
		(layer "F.Cu")
		(net "RST_PCIE_CPU0_DEV_PERST_N")
	)
	(segment
		(start 179.12588 -129.250948)
		(end 179.12588 -129.866898)
		(width 0.12954)
		(layer "F.Cu")
		(net "RST_PCIE_CPU0_DEV_PERST_N")
	)
	(segment
		(start 178.44008 -129.505202)
		(end 178.44008 -125.237748)
		(width 0.12954)
		(layer "F.Cu")
		(net "RST_PCIE_CPU0_DEV_PERST_N")
	)
	(segment
		(start 178.56708 -120.564148)
		(end 178.9557 -120.175528)
		(width 0.12954)
		(layer "F.Cu")
		(net "RST_PCIE_CPU0_DEV_PERST_N")
	)
	(segment
		(start 178.56708 -123.764548)
		(end 178.56708 -120.564148)
		(width 0.12954)
		(layer "F.Cu")
		(net "RST_PCIE_CPU0_DEV_PERST_N")
	)
	(segment
		(start 393.690602 -32.456374)
		(end 394.510006 -32.456374)
		(width 0.12954)
		(layer "F.Cu")
		(net "RST_PCIE_CPU0_DEV_PERST_N")
	)
	(segment
		(start 179.12588 -129.866898)
		(end 178.801776 -129.866898)
		(width 0.12954)
		(layer "F.Cu")
		(net "RST_PCIE_CPU0_DEV_PERST_N")
	)
	(segment
		(start 178.08448 -124.882148)
		(end 178.08448 -124.247148)
		(width 0.12954)
		(layer "F.Cu")
		(net "RST_PCIE_CPU0_DEV_PERST_N")
	)
	(segment
		(start 178.801776 -129.866898)
		(end 178.44008 -129.505202)
		(width 0.12954)
		(layer "F.Cu")
		(net "RST_PCIE_CPU0_DEV_PERST_N")
	)
	(via
		(at 179.12588 -129.250948)
		(size 0.508)
		(drill 0.254)
		(layers "F.Cu" "B.Cu")
		(net "RST_PCIE_CPU0_DEV_PERST_N")
	)
	(via
		(at 394.510006 -32.456374)
		(size 0.508)
		(drill 0.254)
		(layers "F.Cu" "B.Cu")
		(net "RST_PCIE_CPU0_DEV_PERST_N")
	)
	(via
		(at 313.11088 -95.976948)
		(size 0.762)
		(drill 0.254)
		(layers "F.Cu" "B.Cu")
		(net "RST_PCIE_CPU0_DEV_PERST_N")
	)
	(segment
		(start 391.95248 -47.132748)
		(end 391.95248 -37.683948)
		(width 0.12954)
		(layer "B.Cu")
		(net "RST_PCIE_CPU0_DEV_PERST_N")
	)
	(segment
		(start 374.563132 -70.231254)
		(end 375.360438 -69.433948)
		(width 0.12954)
		(layer "B.Cu")
		(net "RST_PCIE_CPU0_DEV_PERST_N")
	)
	(segment
		(start 331.1779 -94.986348)
		(end 354.64623 -94.986348)
		(width 0.12954)
		(layer "B.Cu")
		(net "RST_PCIE_CPU0_DEV_PERST_N")
	)
	(segment
		(start 314.15228 -94.173548)
		(end 330.3651 -94.173548)
		(width 0.12954)
		(layer "B.Cu")
		(net "RST_PCIE_CPU0_DEV_PERST_N")
	)
	(segment
		(start 370.59108 -79.041498)
		(end 370.59108 -71.669148)
		(width 0.12954)
		(layer "B.Cu")
		(net "RST_PCIE_CPU0_DEV_PERST_N")
	)
	(segment
		(start 372.028974 -70.231254)
		(end 374.563132 -70.231254)
		(width 0.12954)
		(layer "B.Cu")
		(net "RST_PCIE_CPU0_DEV_PERST_N")
	)
	(segment
		(start 391.95248 -37.683948)
		(end 390.38022 -36.111688)
		(width 0.12954)
		(layer "B.Cu")
		(net "RST_PCIE_CPU0_DEV_PERST_N")
	)
	(segment
		(start 375.360438 -69.433948)
		(end 381.349504 -69.433948)
		(width 0.12954)
		(layer "B.Cu")
		(net "RST_PCIE_CPU0_DEV_PERST_N")
	)
	(segment
		(start 392.51382 -47.694088)
		(end 391.95248 -47.132748)
		(width 0.12954)
		(layer "B.Cu")
		(net "RST_PCIE_CPU0_DEV_PERST_N")
	)
	(segment
		(start 390.38022 -36.111688)
		(end 390.38022 -34.628328)
		(width 0.12954)
		(layer "B.Cu")
		(net "RST_PCIE_CPU0_DEV_PERST_N")
	)
	(segment
		(start 370.59108 -71.669148)
		(end 372.028974 -70.231254)
		(width 0.12954)
		(layer "B.Cu")
		(net "RST_PCIE_CPU0_DEV_PERST_N")
	)
	(segment
		(start 392.51382 -58.269632)
		(end 392.51382 -47.694088)
		(width 0.12954)
		(layer "B.Cu")
		(net "RST_PCIE_CPU0_DEV_PERST_N")
	)
	(segment
		(start 393.270232 -33.696148)
		(end 394.510006 -32.456374)
		(width 0.12954)
		(layer "B.Cu")
		(net "RST_PCIE_CPU0_DEV_PERST_N")
	)
	(segment
		(start 390.38022 -34.628328)
		(end 391.3124 -33.696148)
		(width 0.12954)
		(layer "B.Cu")
		(net "RST_PCIE_CPU0_DEV_PERST_N")
	)
	(segment
		(start 313.11088 -95.976948)
		(end 313.11088 -95.214948)
		(width 0.12954)
		(layer "B.Cu")
		(net "RST_PCIE_CPU0_DEV_PERST_N")
	)
	(segment
		(start 381.349504 -69.433948)
		(end 392.51382 -58.269632)
		(width 0.12954)
		(layer "B.Cu")
		(net "RST_PCIE_CPU0_DEV_PERST_N")
	)
	(segment
		(start 330.3651 -94.173548)
		(end 331.1779 -94.986348)
		(width 0.12954)
		(layer "B.Cu")
		(net "RST_PCIE_CPU0_DEV_PERST_N")
	)
	(segment
		(start 354.64623 -94.986348)
		(end 370.59108 -79.041498)
		(width 0.12954)
		(layer "B.Cu")
		(net "RST_PCIE_CPU0_DEV_PERST_N")
	)
	(segment
		(start 391.3124 -33.696148)
		(end 393.270232 -33.696148)
		(width 0.12954)
		(layer "B.Cu")
		(net "RST_PCIE_CPU0_DEV_PERST_N")
	)
	(segment
		(start 313.11088 -95.214948)
		(end 314.15228 -94.173548)
		(width 0.12954)
		(layer "B.Cu")
		(net "RST_PCIE_CPU0_DEV_PERST_N")
	)
	(segment
		(start 185.1914 -97.8408)
		(end 186.944 -96.0882)
		(width 0.127)
		(layer "In11.Cu")
		(net "RST_PCIE_CPU0_DEV_PERST_N")
	)
	(segment
		(start 181.993286 -108.979208)
		(end 180.76926 -108.979208)
		(width 0.127)
		(layer "In11.Cu")
		(net "RST_PCIE_CPU0_DEV_PERST_N")
	)
	(segment
		(start 244.246146 -109.464348)
		(end 246.15267 -109.464348)
		(width 0.127)
		(layer "In11.Cu")
		(net "RST_PCIE_CPU0_DEV_PERST_N")
	)
	(segment
		(start 199.1233 -103.2002)
		(end 207.292194 -103.2002)
		(width 0.127)
		(layer "In11.Cu")
		(net "RST_PCIE_CPU0_DEV_PERST_N")
	)
	(segment
		(start 249.302524 -112.614202)
		(end 263.710166 -112.614202)
		(width 0.127)
		(layer "In11.Cu")
		(net "RST_PCIE_CPU0_DEV_PERST_N")
	)
	(segment
		(start 182.15102 -109.136942)
		(end 181.993286 -108.979208)
		(width 0.127)
		(layer "In11.Cu")
		(net "RST_PCIE_CPU0_DEV_PERST_N")
	)
	(segment
		(start 180.5686 -101.901498)
		(end 180.1495 -101.482398)
		(width 0.127)
		(layer "In11.Cu")
		(net "RST_PCIE_CPU0_DEV_PERST_N")
	)
	(segment
		(start 181.80685 -96.0882)
		(end 181.80685 -97.319084)
		(width 0.127)
		(layer "In11.Cu")
		(net "RST_PCIE_CPU0_DEV_PERST_N")
	)
	(segment
		(start 180.19522 -126.860808)
		(end 181.52872 -126.860808)
		(width 0.127)
		(layer "In11.Cu")
		(net "RST_PCIE_CPU0_DEV_PERST_N")
	)
	(segment
		(start 180.1495 -101.482398)
		(end 180.1495 -99.834446)
		(width 0.127)
		(layer "In11.Cu")
		(net "RST_PCIE_CPU0_DEV_PERST_N")
	)
	(segment
		(start 238.040926 -103.259128)
		(end 244.246146 -109.464348)
		(width 0.127)
		(layer "In11.Cu")
		(net "RST_PCIE_CPU0_DEV_PERST_N")
	)
	(segment
		(start 181.80685 -97.319084)
		(end 182.328566 -97.8408)
		(width 0.127)
		(layer "In11.Cu")
		(net "RST_PCIE_CPU0_DEV_PERST_N")
	)
	(segment
		(start 192.0113 -96.0882)
		(end 199.1233 -103.2002)
		(width 0.127)
		(layer "In11.Cu")
		(net "RST_PCIE_CPU0_DEV_PERST_N")
	)
	(segment
		(start 180.76926 -108.979208)
		(end 180.5686 -108.778548)
		(width 0.127)
		(layer "In11.Cu")
		(net "RST_PCIE_CPU0_DEV_PERST_N")
	)
	(segment
		(start 246.15267 -109.464348)
		(end 249.302524 -112.614202)
		(width 0.127)
		(layer "In11.Cu")
		(net "RST_PCIE_CPU0_DEV_PERST_N")
	)
	(segment
		(start 181.27345 -95.5548)
		(end 181.80685 -96.0882)
		(width 0.127)
		(layer "In11.Cu")
		(net "RST_PCIE_CPU0_DEV_PERST_N")
	)
	(segment
		(start 181.52872 -126.860808)
		(end 182.15102 -126.238508)
		(width 0.127)
		(layer "In11.Cu")
		(net "RST_PCIE_CPU0_DEV_PERST_N")
	)
	(segment
		(start 179.12588 -129.250948)
		(end 179.67452 -128.702308)
		(width 0.127)
		(layer "In11.Cu")
		(net "RST_PCIE_CPU0_DEV_PERST_N")
	)
	(segment
		(start 179.67452 -127.381508)
		(end 180.19522 -126.860808)
		(width 0.127)
		(layer "In11.Cu")
		(net "RST_PCIE_CPU0_DEV_PERST_N")
	)
	(segment
		(start 180.562758 -107.938316)
		(end 180.562758 -107.612688)
		(width 0.127)
		(layer "In11.Cu")
		(net "RST_PCIE_CPU0_DEV_PERST_N")
	)
	(segment
		(start 182.328566 -97.8408)
		(end 185.1914 -97.8408)
		(width 0.127)
		(layer "In11.Cu")
		(net "RST_PCIE_CPU0_DEV_PERST_N")
	)
	(segment
		(start 180.1495 -99.834446)
		(end 179.5653 -99.250246)
		(width 0.127)
		(layer "In11.Cu")
		(net "RST_PCIE_CPU0_DEV_PERST_N")
	)
	(segment
		(start 180.562758 -107.612688)
		(end 180.5686 -107.606846)
		(width 0.127)
		(layer "In11.Cu")
		(net "RST_PCIE_CPU0_DEV_PERST_N")
	)
	(segment
		(start 179.5653 -99.250246)
		(end 179.5653 -95.966534)
		(width 0.127)
		(layer "In11.Cu")
		(net "RST_PCIE_CPU0_DEV_PERST_N")
	)
	(segment
		(start 277.27402 -99.050348)
		(end 312.19648 -99.050348)
		(width 0.127)
		(layer "In11.Cu")
		(net "RST_PCIE_CPU0_DEV_PERST_N")
	)
	(segment
		(start 179.67452 -128.702308)
		(end 179.67452 -127.381508)
		(width 0.127)
		(layer "In11.Cu")
		(net "RST_PCIE_CPU0_DEV_PERST_N")
	)
	(segment
		(start 180.5686 -108.778548)
		(end 180.5686 -107.944158)
		(width 0.127)
		(layer "In11.Cu")
		(net "RST_PCIE_CPU0_DEV_PERST_N")
	)
	(segment
		(start 179.977034 -95.5548)
		(end 181.27345 -95.5548)
		(width 0.127)
		(layer "In11.Cu")
		(net "RST_PCIE_CPU0_DEV_PERST_N")
	)
	(segment
		(start 208.541874 -104.44988)
		(end 211.638388 -104.44988)
		(width 0.127)
		(layer "In11.Cu")
		(net "RST_PCIE_CPU0_DEV_PERST_N")
	)
	(segment
		(start 207.292194 -103.2002)
		(end 208.541874 -104.44988)
		(width 0.127)
		(layer "In11.Cu")
		(net "RST_PCIE_CPU0_DEV_PERST_N")
	)
	(segment
		(start 179.5653 -95.966534)
		(end 179.977034 -95.5548)
		(width 0.127)
		(layer "In11.Cu")
		(net "RST_PCIE_CPU0_DEV_PERST_N")
	)
	(segment
		(start 180.5686 -107.606846)
		(end 180.5686 -101.901498)
		(width 0.127)
		(layer "In11.Cu")
		(net "RST_PCIE_CPU0_DEV_PERST_N")
	)
	(segment
		(start 186.944 -96.0882)
		(end 192.0113 -96.0882)
		(width 0.127)
		(layer "In11.Cu")
		(net "RST_PCIE_CPU0_DEV_PERST_N")
	)
	(segment
		(start 182.15102 -126.238508)
		(end 182.15102 -109.136942)
		(width 0.127)
		(layer "In11.Cu")
		(net "RST_PCIE_CPU0_DEV_PERST_N")
	)
	(segment
		(start 211.638388 -104.44988)
		(end 212.82914 -103.259128)
		(width 0.127)
		(layer "In11.Cu")
		(net "RST_PCIE_CPU0_DEV_PERST_N")
	)
	(segment
		(start 263.710166 -112.614202)
		(end 277.27402 -99.050348)
		(width 0.127)
		(layer "In11.Cu")
		(net "RST_PCIE_CPU0_DEV_PERST_N")
	)
	(segment
		(start 313.11088 -98.135948)
		(end 313.11088 -95.976948)
		(width 0.127)
		(layer "In11.Cu")
		(net "RST_PCIE_CPU0_DEV_PERST_N")
	)
	(segment
		(start 312.19648 -99.050348)
		(end 313.11088 -98.135948)
		(width 0.127)
		(layer "In11.Cu")
		(net "RST_PCIE_CPU0_DEV_PERST_N")
	)
	(segment
		(start 212.82914 -103.259128)
		(end 238.040926 -103.259128)
		(width 0.127)
		(layer "In11.Cu")
		(net "RST_PCIE_CPU0_DEV_PERST_N")
	)
	(segment
		(start 180.5686 -107.944158)
		(end 180.562758 -107.938316)
		(width 0.127)
		(layer "In11.Cu")
		(net "RST_PCIE_CPU0_DEV_PERST_N")
	)
	(segment
		(start 331.065378 -45.630846)
		(end 330.79436 -46.100746)
		(width 0.12954)
		(layer "F.Cu")
		(net "RST_PCH_RSTBTN_R_N")
	)
	(via
		(at 331.065378 -45.630846)
		(size 0.4572)
		(drill 0.2032)
		(layers "F.Cu" "B.Cu")
		(net "RST_PCH_RSTBTN_R_N")
	)
	(via
		(at 324.345808 -44.407836)
		(size 0.6604)
		(drill 0.3302)
		(layers "F.Cu" "B.Cu")
		(net "RST_PCH_RSTBTN_R_N")
	)
	(segment
		(start 328.413618 -45.89272)
		(end 327.852786 -45.331888)
		(width 0.0889)
		(layer "B.Cu")
		(net "RST_PCH_RSTBTN_R_N")
	)
	(segment
		(start 322.326762 -43.110658)
		(end 321.888612 -42.672508)
		(width 0.12954)
		(layer "B.Cu")
		(net "RST_PCH_RSTBTN_R_N")
	)
	(segment
		(start 327.852786 -45.331888)
		(end 327.62063 -45.099732)
		(width 0.12954)
		(layer "B.Cu")
		(net "RST_PCH_RSTBTN_R_N")
	)
	(segment
		(start 328.69886 -45.89272)
		(end 328.413618 -45.89272)
		(width 0.0889)
		(layer "B.Cu")
		(net "RST_PCH_RSTBTN_R_N")
	)
	(segment
		(start 327.62063 -45.099732)
		(end 325.56069 -45.099732)
		(width 0.12954)
		(layer "B.Cu")
		(net "RST_PCH_RSTBTN_R_N")
	)
	(segment
		(start 324.868794 -44.407836)
		(end 324.345808 -44.407836)
		(width 0.12954)
		(layer "B.Cu")
		(net "RST_PCH_RSTBTN_R_N")
	)
	(segment
		(start 318.038988 -39.641018)
		(end 318.038988 -40.49268)
		(width 0.12954)
		(layer "B.Cu")
		(net "RST_PCH_RSTBTN_R_N")
	)
	(segment
		(start 319.162176 -41.615868)
		(end 319.345564 -41.615868)
		(width 0.12954)
		(layer "B.Cu")
		(net "RST_PCH_RSTBTN_R_N")
	)
	(segment
		(start 329.236578 -45.1866)
		(end 328.963782 -45.459396)
		(width 0.0889)
		(layer "B.Cu")
		(net "RST_PCH_RSTBTN_R_N")
	)
	(segment
		(start 329.642978 -45.1866)
		(end 329.236578 -45.1866)
		(width 0.0889)
		(layer "B.Cu")
		(net "RST_PCH_RSTBTN_R_N")
	)
	(segment
		(start 328.963782 -45.627798)
		(end 328.69886 -45.89272)
		(width 0.0889)
		(layer "B.Cu")
		(net "RST_PCH_RSTBTN_R_N")
	)
	(segment
		(start 330.087224 -45.630846)
		(end 329.642978 -45.1866)
		(width 0.0889)
		(layer "B.Cu")
		(net "RST_PCH_RSTBTN_R_N")
	)
	(segment
		(start 328.963782 -45.459396)
		(end 328.963782 -45.627798)
		(width 0.0889)
		(layer "B.Cu")
		(net "RST_PCH_RSTBTN_R_N")
	)
	(segment
		(start 320.66484 -42.672508)
		(end 319.708022 -41.71569)
		(width 0.12954)
		(layer "B.Cu")
		(net "RST_PCH_RSTBTN_R_N")
	)
	(segment
		(start 323.04863 -43.110658)
		(end 322.326762 -43.110658)
		(width 0.12954)
		(layer "B.Cu")
		(net "RST_PCH_RSTBTN_R_N")
	)
	(segment
		(start 325.56069 -45.099732)
		(end 324.868794 -44.407836)
		(width 0.12954)
		(layer "B.Cu")
		(net "RST_PCH_RSTBTN_R_N")
	)
	(segment
		(start 331.065378 -45.630846)
		(end 330.087224 -45.630846)
		(width 0.0889)
		(layer "B.Cu")
		(net "RST_PCH_RSTBTN_R_N")
	)
	(segment
		(start 324.345808 -44.407836)
		(end 323.04863 -43.110658)
		(width 0.12954)
		(layer "B.Cu")
		(net "RST_PCH_RSTBTN_R_N")
	)
	(segment
		(start 321.888612 -42.672508)
		(end 320.66484 -42.672508)
		(width 0.12954)
		(layer "B.Cu")
		(net "RST_PCH_RSTBTN_R_N")
	)
	(segment
		(start 319.345564 -41.615868)
		(end 319.708022 -41.25341)
		(width 0.12954)
		(layer "B.Cu")
		(net "RST_PCH_RSTBTN_R_N")
	)
	(segment
		(start 318.038988 -40.49268)
		(end 319.162176 -41.615868)
		(width 0.12954)
		(layer "B.Cu")
		(net "RST_PCH_RSTBTN_R_N")
	)
	(segment
		(start 319.708022 -41.71569)
		(end 319.708022 -41.25341)
		(width 0.12954)
		(layer "B.Cu")
		(net "RST_PCH_RSTBTN_R_N")
	)
	(segment
		(start 392.890502 -33.708848)
		(end 392.719814 -33.879536)
		(width 0.12954)
		(layer "F.Cu")
		(net "RST_OCP_V3_1_N")
	)
	(segment
		(start 392.719814 -33.879536)
		(end 392.719814 -35.118802)
		(width 0.12954)
		(layer "F.Cu")
		(net "RST_OCP_V3_1_N")
	)
	(segment
		(start 392.890502 -32.456374)
		(end 392.890502 -33.708848)
		(width 0.12954)
		(layer "F.Cu")
		(net "RST_OCP_V3_1_N")
	)
	(via
		(at 392.890502 -33.708848)
		(size 0.762)
		(drill 0.381)
		(layers "F.Cu" "B.Cu")
		(net "RST_OCP_V3_1_N")
	)
	(segment
		(start 458.95768 -38.318948)
		(end 458.927708 -38.288976)
		(width 0.12954)
		(layer "F.Cu")
		(net "RST_OCP_V3_1_BUF_N")
	)
	(segment
		(start 458.927708 -38.288976)
		(end 456.379072 -38.288976)
		(width 0.12954)
		(layer "F.Cu")
		(net "RST_OCP_V3_1_BUF_N")
	)
	(segment
		(start 436.08625 -16.648176)
		(end 436.08625 -17.287748)
		(width 0.12954)
		(layer "F.Cu")
		(net "RST_OCP_V3_1_BUF_N")
	)
	(via
		(at 436.08625 -17.287748)
		(size 0.508)
		(drill 0.254)
		(layers "F.Cu" "B.Cu")
		(net "RST_OCP_V3_1_BUF_N")
	)
	(via
		(at 458.95768 -38.318948)
		(size 0.508)
		(drill 0.254)
		(layers "F.Cu" "B.Cu")
		(net "RST_OCP_V3_1_BUF_N")
	)
	(via
		(at 452.70547 -3.466338)
		(size 0.508)
		(drill 0.254)
		(layers "F.Cu" "B.Cu")
		(net "RST_OCP_V3_1_BUF_N")
	)
	(segment
		(start 450.54012 -3.305048)
		(end 444.51778 -3.305048)
		(width 0.12954)
		(layer "B.Cu")
		(net "RST_OCP_V3_1_BUF_N")
	)
	(segment
		(start 430.175416 -7.484872)
		(end 433.00777 -4.652518)
		(width 0.12954)
		(layer "B.Cu")
		(net "RST_OCP_V3_1_BUF_N")
	)
	(segment
		(start 434.34635 -4.281678)
		(end 434.34635 -4.652518)
		(width 0.12954)
		(layer "B.Cu")
		(net "RST_OCP_V3_1_BUF_N")
	)
	(segment
		(start 436.08625 -17.287748)
		(end 434.695854 -15.897352)
		(width 0.12954)
		(layer "B.Cu")
		(net "RST_OCP_V3_1_BUF_N")
	)
	(segment
		(start 432.341274 -15.897352)
		(end 430.175416 -13.731494)
		(width 0.12954)
		(layer "B.Cu")
		(net "RST_OCP_V3_1_BUF_N")
	)
	(segment
		(start 450.71157 -3.466338)
		(end 452.01205 -3.466338)
		(width 0.12954)
		(layer "B.Cu")
		(net "RST_OCP_V3_1_BUF_N")
	)
	(segment
		(start 450.70649 -3.471418)
		(end 450.54012 -3.305048)
		(width 0.12954)
		(layer "B.Cu")
		(net "RST_OCP_V3_1_BUF_N")
	)
	(segment
		(start 434.695854 -15.897352)
		(end 432.341274 -15.897352)
		(width 0.12954)
		(layer "B.Cu")
		(net "RST_OCP_V3_1_BUF_N")
	)
	(segment
		(start 437.31688 -3.927348)
		(end 434.70068 -3.927348)
		(width 0.12954)
		(layer "B.Cu")
		(net "RST_OCP_V3_1_BUF_N")
	)
	(segment
		(start 430.175416 -13.731494)
		(end 430.175416 -7.484872)
		(width 0.12954)
		(layer "B.Cu")
		(net "RST_OCP_V3_1_BUF_N")
	)
	(segment
		(start 452.01205 -3.466338)
		(end 452.70547 -3.466338)
		(width 0.12954)
		(layer "B.Cu")
		(net "RST_OCP_V3_1_BUF_N")
	)
	(segment
		(start 443.00648 -4.816348)
		(end 438.20588 -4.816348)
		(width 0.12954)
		(layer "B.Cu")
		(net "RST_OCP_V3_1_BUF_N")
	)
	(segment
		(start 438.20588 -4.816348)
		(end 437.31688 -3.927348)
		(width 0.12954)
		(layer "B.Cu")
		(net "RST_OCP_V3_1_BUF_N")
	)
	(segment
		(start 433.00777 -4.652518)
		(end 434.34635 -4.652518)
		(width 0.12954)
		(layer "B.Cu")
		(net "RST_OCP_V3_1_BUF_N")
	)
	(segment
		(start 450.70649 -3.471418)
		(end 450.71157 -3.466338)
		(width 0.12954)
		(layer "B.Cu")
		(net "RST_OCP_V3_1_BUF_N")
	)
	(segment
		(start 434.70068 -3.927348)
		(end 434.34635 -4.281678)
		(width 0.12954)
		(layer "B.Cu")
		(net "RST_OCP_V3_1_BUF_N")
	)
	(segment
		(start 444.51778 -3.305048)
		(end 443.00648 -4.816348)
		(width 0.12954)
		(layer "B.Cu")
		(net "RST_OCP_V3_1_BUF_N")
	)
	(segment
		(start 458.35316 -37.714428)
		(end 458.95768 -38.318948)
		(width 0.127)
		(layer "In2.Cu")
		(net "RST_OCP_V3_1_BUF_N")
	)
	(segment
		(start 451.63486 -7.374128)
		(end 453.03948 -8.778748)
		(width 0.127)
		(layer "In2.Cu")
		(net "RST_OCP_V3_1_BUF_N")
	)
	(segment
		(start 453.03948 -8.778748)
		(end 453.03948 -11.217148)
		(width 0.127)
		(layer "In2.Cu")
		(net "RST_OCP_V3_1_BUF_N")
	)
	(segment
		(start 453.03948 -11.217148)
		(end 458.35316 -16.530828)
		(width 0.127)
		(layer "In2.Cu")
		(net "RST_OCP_V3_1_BUF_N")
	)
	(segment
		(start 458.35316 -16.530828)
		(end 458.35316 -37.714428)
		(width 0.127)
		(layer "In2.Cu")
		(net "RST_OCP_V3_1_BUF_N")
	)
	(segment
		(start 451.63486 -4.536948)
		(end 451.63486 -7.374128)
		(width 0.127)
		(layer "In2.Cu")
		(net "RST_OCP_V3_1_BUF_N")
	)
	(segment
		(start 452.70547 -3.466338)
		(end 451.63486 -4.536948)
		(width 0.127)
		(layer "In2.Cu")
		(net "RST_OCP_V3_1_BUF_N")
	)
	(segment
		(start 197.527418 -269.141702)
		(end 195.503038 -269.141702)
		(width 0.1016)
		(layer "F.Cu")
		(net "RST_M_GH_CPU1_FPGA_N")
	)
	(segment
		(start 200.632314 -268.71676)
		(end 198.275448 -268.71676)
		(width 0.12954)
		(layer "F.Cu")
		(net "RST_M_GH_CPU1_FPGA_N")
	)
	(segment
		(start 205.646782 -269.141702)
		(end 205.071218 -269.141702)
		(width 0.12954)
		(layer "F.Cu")
		(net "RST_M_GH_CPU1_FPGA_N")
	)
	(segment
		(start 206.243682 -268.544802)
		(end 205.646782 -269.141702)
		(width 0.12954)
		(layer "F.Cu")
		(net "RST_M_GH_CPU1_FPGA_N")
	)
	(segment
		(start 195.503038 -269.141702)
		(end 195.281804 -269.141702)
		(width 0.12954)
		(layer "F.Cu")
		(net "RST_M_GH_CPU1_FPGA_N")
	)
	(segment
		(start 210.623658 -269.141702)
		(end 210.35645 -269.141702)
		(width 0.12954)
		(layer "F.Cu")
		(net "RST_M_GH_CPU1_FPGA_N")
	)
	(segment
		(start 207.072484 -268.544802)
		(end 206.243682 -268.544802)
		(width 0.12954)
		(layer "F.Cu")
		(net "RST_M_GH_CPU1_FPGA_N")
	)
	(segment
		(start 195.281804 -269.141702)
		(end 194.637152 -268.49705)
		(width 0.12954)
		(layer "F.Cu")
		(net "RST_M_GH_CPU1_FPGA_N")
	)
	(segment
		(start 202.228196 -269.141702)
		(end 201.803254 -268.71676)
		(width 0.12954)
		(layer "F.Cu")
		(net "RST_M_GH_CPU1_FPGA_N")
	)
	(segment
		(start 207.244442 -268.71676)
		(end 207.072484 -268.544802)
		(width 0.12954)
		(layer "F.Cu")
		(net "RST_M_GH_CPU1_FPGA_N")
	)
	(segment
		(start 212.9917 -269.141702)
		(end 212.622638 -269.141702)
		(width 0.12954)
		(layer "F.Cu")
		(net "RST_M_GH_CPU1_FPGA_N")
	)
	(segment
		(start 205.071218 -269.141702)
		(end 203.062078 -269.141702)
		(width 0.1016)
		(layer "F.Cu")
		(net "RST_M_GH_CPU1_FPGA_N")
	)
	(segment
		(start 215.719914 -268.71676)
		(end 213.416642 -268.71676)
		(width 0.12954)
		(layer "F.Cu")
		(net "RST_M_GH_CPU1_FPGA_N")
	)
	(segment
		(start 193.088514 -268.71676)
		(end 191.907414 -268.71676)
		(width 0.12954)
		(layer "F.Cu")
		(net "RST_M_GH_CPU1_FPGA_N")
	)
	(segment
		(start 203.062078 -269.141702)
		(end 202.228196 -269.141702)
		(width 0.12954)
		(layer "F.Cu")
		(net "RST_M_GH_CPU1_FPGA_N")
	)
	(segment
		(start 194.637152 -268.49705)
		(end 193.833496 -268.49705)
		(width 0.12954)
		(layer "F.Cu")
		(net "RST_M_GH_CPU1_FPGA_N")
	)
	(segment
		(start 210.35645 -269.141702)
		(end 209.678778 -268.46403)
		(width 0.12954)
		(layer "F.Cu")
		(net "RST_M_GH_CPU1_FPGA_N")
	)
	(segment
		(start 193.613786 -268.71676)
		(end 193.088514 -268.71676)
		(width 0.12954)
		(layer "F.Cu")
		(net "RST_M_GH_CPU1_FPGA_N")
	)
	(segment
		(start 193.833496 -268.49705)
		(end 193.613786 -268.71676)
		(width 0.12954)
		(layer "F.Cu")
		(net "RST_M_GH_CPU1_FPGA_N")
	)
	(segment
		(start 208.176114 -268.71676)
		(end 207.244442 -268.71676)
		(width 0.12954)
		(layer "F.Cu")
		(net "RST_M_GH_CPU1_FPGA_N")
	)
	(segment
		(start 209.039714 -268.71676)
		(end 208.176114 -268.71676)
		(width 0.12954)
		(layer "F.Cu")
		(net "RST_M_GH_CPU1_FPGA_N")
	)
	(segment
		(start 198.275448 -268.71676)
		(end 197.850506 -269.141702)
		(width 0.12954)
		(layer "F.Cu")
		(net "RST_M_GH_CPU1_FPGA_N")
	)
	(segment
		(start 213.416642 -268.71676)
		(end 212.9917 -269.141702)
		(width 0.12954)
		(layer "F.Cu")
		(net "RST_M_GH_CPU1_FPGA_N")
	)
	(segment
		(start 209.678778 -268.46403)
		(end 209.292444 -268.46403)
		(width 0.12954)
		(layer "F.Cu")
		(net "RST_M_GH_CPU1_FPGA_N")
	)
	(segment
		(start 212.622638 -269.141702)
		(end 210.623658 -269.141702)
		(width 0.1016)
		(layer "F.Cu")
		(net "RST_M_GH_CPU1_FPGA_N")
	)
	(segment
		(start 209.292444 -268.46403)
		(end 209.039714 -268.71676)
		(width 0.12954)
		(layer "F.Cu")
		(net "RST_M_GH_CPU1_FPGA_N")
	)
	(segment
		(start 201.803254 -268.71676)
		(end 200.632314 -268.71676)
		(width 0.12954)
		(layer "F.Cu")
		(net "RST_M_GH_CPU1_FPGA_N")
	)
	(segment
		(start 197.850506 -269.141702)
		(end 197.527418 -269.141702)
		(width 0.12954)
		(layer "F.Cu")
		(net "RST_M_GH_CPU1_FPGA_N")
	)
	(via
		(at 190.997078 -264.60577)
		(size 0.6604)
		(drill 0.3302)
		(layers "F.Cu" "B.Cu")
		(net "RST_M_GH_CPU1_FPGA_N")
	)
	(via
		(at 191.907414 -268.71676)
		(size 0.4572)
		(drill 0.2032)
		(layers "F.Cu" "B.Cu")
		(net "RST_M_GH_CPU1_FPGA_N")
	)
	(segment
		(start 190.997078 -264.60577)
		(end 190.997078 -257.19151)
		(width 0.12954)
		(layer "B.Cu")
		(net "RST_M_GH_CPU1_FPGA_N")
	)
	(segment
		(start 190.248286 -194.015106)
		(end 189.232286 -194.015106)
		(width 0.12954)
		(layer "B.Cu")
		(net "RST_M_GH_CPU1_FPGA_N")
	)
	(segment
		(start 190.997078 -268.34973)
		(end 190.997078 -264.60577)
		(width 0.12954)
		(layer "B.Cu")
		(net "RST_M_GH_CPU1_FPGA_N")
	)
	(segment
		(start 191.364108 -268.71676)
		(end 190.997078 -268.34973)
		(width 0.12954)
		(layer "B.Cu")
		(net "RST_M_GH_CPU1_FPGA_N")
	)
	(segment
		(start 191.907414 -268.71676)
		(end 191.364108 -268.71676)
		(width 0.12954)
		(layer "B.Cu")
		(net "RST_M_GH_CPU1_FPGA_N")
	)
	(segment
		(start 188.990478 -255.18491)
		(end 188.990478 -194.256914)
		(width 0.12954)
		(layer "B.Cu")
		(net "RST_M_GH_CPU1_FPGA_N")
	)
	(segment
		(start 188.990478 -194.256914)
		(end 189.232286 -194.015106)
		(width 0.12954)
		(layer "B.Cu")
		(net "RST_M_GH_CPU1_FPGA_N")
	)
	(segment
		(start 190.997078 -257.19151)
		(end 188.990478 -255.18491)
		(width 0.12954)
		(layer "B.Cu")
		(net "RST_M_GH_CPU1_FPGA_N")
	)
	(segment
		(start 457.618846 -268.46403)
		(end 457.249784 -268.46403)
		(width 0.12954)
		(layer "F.Cu")
		(net "RST_M_GH_CPU0_FPGA_N")
	)
	(segment
		(start 443.443106 -269.141702)
		(end 443.221872 -269.141702)
		(width 0.12954)
		(layer "F.Cu")
		(net "RST_M_GH_CPU0_FPGA_N")
	)
	(segment
		(start 443.221872 -269.141702)
		(end 442.57722 -268.49705)
		(width 0.12954)
		(layer "F.Cu")
		(net "RST_M_GH_CPU0_FPGA_N")
	)
	(segment
		(start 448.572382 -268.71676)
		(end 446.215516 -268.71676)
		(width 0.12954)
		(layer "F.Cu")
		(net "RST_M_GH_CPU0_FPGA_N")
	)
	(segment
		(start 453.011286 -269.141702)
		(end 451.002146 -269.141702)
		(width 0.1016)
		(layer "F.Cu")
		(net "RST_M_GH_CPU0_FPGA_N")
	)
	(segment
		(start 451.002146 -269.141702)
		(end 450.168264 -269.141702)
		(width 0.12954)
		(layer "F.Cu")
		(net "RST_M_GH_CPU0_FPGA_N")
	)
	(segment
		(start 456.997054 -268.71676)
		(end 456.116182 -268.71676)
		(width 0.12954)
		(layer "F.Cu")
		(net "RST_M_GH_CPU0_FPGA_N")
	)
	(segment
		(start 441.553854 -268.71676)
		(end 441.028582 -268.71676)
		(width 0.12954)
		(layer "F.Cu")
		(net "RST_M_GH_CPU0_FPGA_N")
	)
	(segment
		(start 445.790574 -269.141702)
		(end 445.467486 -269.141702)
		(width 0.12954)
		(layer "F.Cu")
		(net "RST_M_GH_CPU0_FPGA_N")
	)
	(segment
		(start 445.467486 -269.141702)
		(end 443.443106 -269.141702)
		(width 0.1016)
		(layer "F.Cu")
		(net "RST_M_GH_CPU0_FPGA_N")
	)
	(segment
		(start 449.743322 -268.71676)
		(end 448.572382 -268.71676)
		(width 0.12954)
		(layer "F.Cu")
		(net "RST_M_GH_CPU0_FPGA_N")
	)
	(segment
		(start 455.106024 -268.544802)
		(end 454.18375 -268.544802)
		(width 0.12954)
		(layer "F.Cu")
		(net "RST_M_GH_CPU0_FPGA_N")
	)
	(segment
		(start 456.116182 -268.71676)
		(end 455.277982 -268.71676)
		(width 0.12954)
		(layer "F.Cu")
		(net "RST_M_GH_CPU0_FPGA_N")
	)
	(segment
		(start 450.168264 -269.141702)
		(end 449.743322 -268.71676)
		(width 0.12954)
		(layer "F.Cu")
		(net "RST_M_GH_CPU0_FPGA_N")
	)
	(segment
		(start 463.659982 -268.71676)
		(end 461.35671 -268.71676)
		(width 0.12954)
		(layer "F.Cu")
		(net "RST_M_GH_CPU0_FPGA_N")
	)
	(segment
		(start 461.35671 -268.71676)
		(end 460.931768 -269.141702)
		(width 0.12954)
		(layer "F.Cu")
		(net "RST_M_GH_CPU0_FPGA_N")
	)
	(segment
		(start 460.931768 -269.141702)
		(end 460.562706 -269.141702)
		(width 0.12954)
		(layer "F.Cu")
		(net "RST_M_GH_CPU0_FPGA_N")
	)
	(segment
		(start 441.028582 -268.71676)
		(end 439.847482 -268.71676)
		(width 0.12954)
		(layer "F.Cu")
		(net "RST_M_GH_CPU0_FPGA_N")
	)
	(segment
		(start 442.57722 -268.49705)
		(end 441.773564 -268.49705)
		(width 0.12954)
		(layer "F.Cu")
		(net "RST_M_GH_CPU0_FPGA_N")
	)
	(segment
		(start 454.18375 -268.544802)
		(end 453.58685 -269.141702)
		(width 0.12954)
		(layer "F.Cu")
		(net "RST_M_GH_CPU0_FPGA_N")
	)
	(segment
		(start 458.296518 -269.141702)
		(end 457.618846 -268.46403)
		(width 0.12954)
		(layer "F.Cu")
		(net "RST_M_GH_CPU0_FPGA_N")
	)
	(segment
		(start 458.563726 -269.141702)
		(end 458.296518 -269.141702)
		(width 0.12954)
		(layer "F.Cu")
		(net "RST_M_GH_CPU0_FPGA_N")
	)
	(segment
		(start 457.249784 -268.46403)
		(end 456.997054 -268.71676)
		(width 0.12954)
		(layer "F.Cu")
		(net "RST_M_GH_CPU0_FPGA_N")
	)
	(segment
		(start 446.215516 -268.71676)
		(end 445.790574 -269.141702)
		(width 0.12954)
		(layer "F.Cu")
		(net "RST_M_GH_CPU0_FPGA_N")
	)
	(segment
		(start 455.277982 -268.71676)
		(end 455.106024 -268.544802)
		(width 0.12954)
		(layer "F.Cu")
		(net "RST_M_GH_CPU0_FPGA_N")
	)
	(segment
		(start 460.562706 -269.141702)
		(end 458.563726 -269.141702)
		(width 0.1016)
		(layer "F.Cu")
		(net "RST_M_GH_CPU0_FPGA_N")
	)
	(segment
		(start 453.58685 -269.141702)
		(end 453.011286 -269.141702)
		(width 0.12954)
		(layer "F.Cu")
		(net "RST_M_GH_CPU0_FPGA_N")
	)
	(segment
		(start 441.773564 -268.49705)
		(end 441.553854 -268.71676)
		(width 0.12954)
		(layer "F.Cu")
		(net "RST_M_GH_CPU0_FPGA_N")
	)
	(via
		(at 436.696358 -257.35407)
		(size 0.6604)
		(drill 0.3302)
		(layers "F.Cu" "B.Cu")
		(net "RST_M_GH_CPU0_FPGA_N")
	)
	(via
		(at 439.847482 -268.71676)
		(size 0.4572)
		(drill 0.2032)
		(layers "F.Cu" "B.Cu")
		(net "RST_M_GH_CPU0_FPGA_N")
	)
	(segment
		(start 434.57241 -193.967354)
		(end 435.59857 -193.967354)
		(width 0.12954)
		(layer "B.Cu")
		(net "RST_M_GH_CPU0_FPGA_N")
	)
	(segment
		(start 436.371238 -194.32143)
		(end 435.952646 -194.32143)
		(width 0.12954)
		(layer "B.Cu")
		(net "RST_M_GH_CPU0_FPGA_N")
	)
	(segment
		(start 436.696358 -194.64655)
		(end 436.371238 -194.32143)
		(width 0.12954)
		(layer "B.Cu")
		(net "RST_M_GH_CPU0_FPGA_N")
	)
	(segment
		(start 436.696358 -267.29563)
		(end 436.696358 -257.35407)
		(width 0.12954)
		(layer "B.Cu")
		(net "RST_M_GH_CPU0_FPGA_N")
	)
	(segment
		(start 435.952646 -194.32143)
		(end 435.59857 -193.967354)
		(width 0.12954)
		(layer "B.Cu")
		(net "RST_M_GH_CPU0_FPGA_N")
	)
	(segment
		(start 437.316118 -267.91539)
		(end 436.696358 -267.29563)
		(width 0.12954)
		(layer "B.Cu")
		(net "RST_M_GH_CPU0_FPGA_N")
	)
	(segment
		(start 436.696358 -257.35407)
		(end 436.696358 -194.64655)
		(width 0.12954)
		(layer "B.Cu")
		(net "RST_M_GH_CPU0_FPGA_N")
	)
	(segment
		(start 439.847482 -268.71676)
		(end 439.046112 -267.91539)
		(width 0.12954)
		(layer "B.Cu")
		(net "RST_M_GH_CPU0_FPGA_N")
	)
	(segment
		(start 439.046112 -267.91539)
		(end 437.316118 -267.91539)
		(width 0.12954)
		(layer "B.Cu")
		(net "RST_M_GH_CPU0_FPGA_N")
	)
	(segment
		(start 183.752744 -268.844776)
		(end 183.88076 -268.71676)
		(width 0.12954)
		(layer "F.Cu")
		(net "RST_M_EF_CPU1_FPGA_N")
	)
	(segment
		(start 183.88076 -268.71676)
		(end 184.439814 -268.71676)
		(width 0.12954)
		(layer "F.Cu")
		(net "RST_M_EF_CPU1_FPGA_N")
	)
	(segment
		(start 182.740046 -269.141702)
		(end 183.019446 -269.421102)
		(width 0.12954)
		(layer "F.Cu")
		(net "RST_M_EF_CPU1_FPGA_N")
	)
	(segment
		(start 168.664636 -269.34541)
		(end 168.664636 -268.9606)
		(width 0.12954)
		(layer "F.Cu")
		(net "RST_M_EF_CPU1_FPGA_N")
	)
	(segment
		(start 178.000914 -268.71676)
		(end 178.915314 -268.71676)
		(width 0.12954)
		(layer "F.Cu")
		(net "RST_M_EF_CPU1_FPGA_N")
	)
	(segment
		(start 182.383938 -269.141702)
		(end 182.740046 -269.141702)
		(width 0.12954)
		(layer "F.Cu")
		(net "RST_M_EF_CPU1_FPGA_N")
	)
	(segment
		(start 168.550336 -269.45971)
		(end 168.664636 -269.34541)
		(width 0.12954)
		(layer "F.Cu")
		(net "RST_M_EF_CPU1_FPGA_N")
	)
	(segment
		(start 168.908476 -268.71676)
		(end 170.457114 -268.71676)
		(width 0.12954)
		(layer "F.Cu")
		(net "RST_M_EF_CPU1_FPGA_N")
	)
	(segment
		(start 167.352218 -269.141702)
		(end 167.749982 -269.141702)
		(width 0.12954)
		(layer "F.Cu")
		(net "RST_M_EF_CPU1_FPGA_N")
	)
	(segment
		(start 180.18379 -269.141702)
		(end 180.517038 -269.141702)
		(width 0.12954)
		(layer "F.Cu")
		(net "RST_M_EF_CPU1_FPGA_N")
	)
	(segment
		(start 179.518818 -268.47673)
		(end 180.18379 -269.141702)
		(width 0.12954)
		(layer "F.Cu")
		(net "RST_M_EF_CPU1_FPGA_N")
	)
	(segment
		(start 176.932844 -268.50721)
		(end 177.142394 -268.71676)
		(width 0.12954)
		(layer "F.Cu")
		(net "RST_M_EF_CPU1_FPGA_N")
	)
	(segment
		(start 168.06799 -269.45971)
		(end 168.550336 -269.45971)
		(width 0.12954)
		(layer "F.Cu")
		(net "RST_M_EF_CPU1_FPGA_N")
	)
	(segment
		(start 162.913314 -268.71676)
		(end 164.678614 -268.71676)
		(width 0.12954)
		(layer "F.Cu")
		(net "RST_M_EF_CPU1_FPGA_N")
	)
	(segment
		(start 184.439814 -268.71676)
		(end 185.544714 -268.71676)
		(width 0.12954)
		(layer "F.Cu")
		(net "RST_M_EF_CPU1_FPGA_N")
	)
	(segment
		(start 167.749982 -269.141702)
		(end 168.06799 -269.45971)
		(width 0.12954)
		(layer "F.Cu")
		(net "RST_M_EF_CPU1_FPGA_N")
	)
	(segment
		(start 172.05071 -268.71676)
		(end 172.475652 -269.141702)
		(width 0.12954)
		(layer "F.Cu")
		(net "RST_M_EF_CPU1_FPGA_N")
	)
	(segment
		(start 179.155344 -268.47673)
		(end 179.518818 -268.47673)
		(width 0.12954)
		(layer "F.Cu")
		(net "RST_M_EF_CPU1_FPGA_N")
	)
	(segment
		(start 168.664636 -268.9606)
		(end 168.908476 -268.71676)
		(width 0.12954)
		(layer "F.Cu")
		(net "RST_M_EF_CPU1_FPGA_N")
	)
	(segment
		(start 165.103556 -269.141702)
		(end 165.302438 -269.141702)
		(width 0.12954)
		(layer "F.Cu")
		(net "RST_M_EF_CPU1_FPGA_N")
	)
	(segment
		(start 170.457114 -268.71676)
		(end 172.05071 -268.71676)
		(width 0.12954)
		(layer "F.Cu")
		(net "RST_M_EF_CPU1_FPGA_N")
	)
	(segment
		(start 180.517038 -269.141702)
		(end 182.383938 -269.141702)
		(width 0.1016)
		(layer "F.Cu")
		(net "RST_M_EF_CPU1_FPGA_N")
	)
	(segment
		(start 174.911258 -269.141702)
		(end 175.471582 -269.141702)
		(width 0.12954)
		(layer "F.Cu")
		(net "RST_M_EF_CPU1_FPGA_N")
	)
	(segment
		(start 177.142394 -268.71676)
		(end 178.000914 -268.71676)
		(width 0.12954)
		(layer "F.Cu")
		(net "RST_M_EF_CPU1_FPGA_N")
	)
	(segment
		(start 183.752744 -269.242032)
		(end 183.752744 -268.844776)
		(width 0.12954)
		(layer "F.Cu")
		(net "RST_M_EF_CPU1_FPGA_N")
	)
	(segment
		(start 172.475652 -269.141702)
		(end 172.909738 -269.141702)
		(width 0.12954)
		(layer "F.Cu")
		(net "RST_M_EF_CPU1_FPGA_N")
	)
	(segment
		(start 165.302438 -269.141702)
		(end 167.352218 -269.141702)
		(width 0.1016)
		(layer "F.Cu")
		(net "RST_M_EF_CPU1_FPGA_N")
	)
	(segment
		(start 175.471582 -269.141702)
		(end 176.106074 -268.50721)
		(width 0.12954)
		(layer "F.Cu")
		(net "RST_M_EF_CPU1_FPGA_N")
	)
	(segment
		(start 178.915314 -268.71676)
		(end 179.155344 -268.47673)
		(width 0.12954)
		(layer "F.Cu")
		(net "RST_M_EF_CPU1_FPGA_N")
	)
	(segment
		(start 183.019446 -269.421102)
		(end 183.573674 -269.421102)
		(width 0.12954)
		(layer "F.Cu")
		(net "RST_M_EF_CPU1_FPGA_N")
	)
	(segment
		(start 183.573674 -269.421102)
		(end 183.752744 -269.242032)
		(width 0.12954)
		(layer "F.Cu")
		(net "RST_M_EF_CPU1_FPGA_N")
	)
	(segment
		(start 176.106074 -268.50721)
		(end 176.932844 -268.50721)
		(width 0.12954)
		(layer "F.Cu")
		(net "RST_M_EF_CPU1_FPGA_N")
	)
	(segment
		(start 164.678614 -268.71676)
		(end 165.103556 -269.141702)
		(width 0.12954)
		(layer "F.Cu")
		(net "RST_M_EF_CPU1_FPGA_N")
	)
	(segment
		(start 172.909738 -269.141702)
		(end 174.911258 -269.141702)
		(width 0.1016)
		(layer "F.Cu")
		(net "RST_M_EF_CPU1_FPGA_N")
	)
	(via
		(at 185.792618 -265.43381)
		(size 0.6604)
		(drill 0.3302)
		(layers "F.Cu" "B.Cu")
		(net "RST_M_EF_CPU1_FPGA_N")
	)
	(via
		(at 184.439814 -268.71676)
		(size 0.4572)
		(drill 0.2032)
		(layers "F.Cu" "B.Cu")
		(net "RST_M_EF_CPU1_FPGA_N")
	)
	(segment
		(start 186.326018 -252.34265)
		(end 186.031378 -252.04801)
		(width 0.12954)
		(layer "B.Cu")
		(net "RST_M_EF_CPU1_FPGA_N")
	)
	(segment
		(start 185.142886 -193.999866)
		(end 186.158886 -193.999866)
		(width 0.12954)
		(layer "B.Cu")
		(net "RST_M_EF_CPU1_FPGA_N")
	)
	(segment
		(start 185.792618 -256.82575)
		(end 186.326018 -256.29235)
		(width 0.12954)
		(layer "B.Cu")
		(net "RST_M_EF_CPU1_FPGA_N")
	)
	(segment
		(start 185.792618 -265.43381)
		(end 185.792618 -256.82575)
		(width 0.12954)
		(layer "B.Cu")
		(net "RST_M_EF_CPU1_FPGA_N")
	)
	(segment
		(start 185.792618 -268.11097)
		(end 185.792618 -265.43381)
		(width 0.12954)
		(layer "B.Cu")
		(net "RST_M_EF_CPU1_FPGA_N")
	)
	(segment
		(start 186.031378 -194.888358)
		(end 185.142886 -193.999866)
		(width 0.12954)
		(layer "B.Cu")
		(net "RST_M_EF_CPU1_FPGA_N")
	)
	(segment
		(start 185.186828 -268.71676)
		(end 185.792618 -268.11097)
		(width 0.12954)
		(layer "B.Cu")
		(net "RST_M_EF_CPU1_FPGA_N")
	)
	(segment
		(start 186.326018 -256.29235)
		(end 186.326018 -252.34265)
		(width 0.12954)
		(layer "B.Cu")
		(net "RST_M_EF_CPU1_FPGA_N")
	)
	(segment
		(start 184.439814 -268.71676)
		(end 185.186828 -268.71676)
		(width 0.12954)
		(layer "B.Cu")
		(net "RST_M_EF_CPU1_FPGA_N")
	)
	(segment
		(start 186.031378 -252.04801)
		(end 186.031378 -194.888358)
		(width 0.12954)
		(layer "B.Cu")
		(net "RST_M_EF_CPU1_FPGA_N")
	)
	(segment
		(start 427.458886 -268.47673)
		(end 428.123858 -269.141702)
		(width 0.12954)
		(layer "F.Cu")
		(net "RST_M_EF_CPU0_FPGA_N")
	)
	(segment
		(start 425.940982 -268.71676)
		(end 425.387262 -268.71676)
		(width 0.12954)
		(layer "F.Cu")
		(net "RST_M_EF_CPU0_FPGA_N")
	)
	(segment
		(start 426.6819 -268.47673)
		(end 427.458886 -268.47673)
		(width 0.12954)
		(layer "F.Cu")
		(net "RST_M_EF_CPU0_FPGA_N")
	)
	(segment
		(start 425.387262 -268.71676)
		(end 425.177712 -268.50721)
		(width 0.12954)
		(layer "F.Cu")
		(net "RST_M_EF_CPU0_FPGA_N")
	)
	(segment
		(start 416.848544 -268.71676)
		(end 416.604704 -268.9606)
		(width 0.12954)
		(layer "F.Cu")
		(net "RST_M_EF_CPU0_FPGA_N")
	)
	(segment
		(start 432.379882 -268.71676)
		(end 433.484782 -268.71676)
		(width 0.12954)
		(layer "F.Cu")
		(net "RST_M_EF_CPU0_FPGA_N")
	)
	(segment
		(start 416.604704 -269.34541)
		(end 416.490404 -269.45971)
		(width 0.12954)
		(layer "F.Cu")
		(net "RST_M_EF_CPU0_FPGA_N")
	)
	(segment
		(start 425.940982 -268.71676)
		(end 426.44187 -268.71676)
		(width 0.12954)
		(layer "F.Cu")
		(net "RST_M_EF_CPU0_FPGA_N")
	)
	(segment
		(start 431.820828 -268.71676)
		(end 432.379882 -268.71676)
		(width 0.12954)
		(layer "F.Cu")
		(net "RST_M_EF_CPU0_FPGA_N")
	)
	(segment
		(start 416.604704 -268.9606)
		(end 416.604704 -269.34541)
		(width 0.12954)
		(layer "F.Cu")
		(net "RST_M_EF_CPU0_FPGA_N")
	)
	(segment
		(start 420.849806 -269.141702)
		(end 420.41572 -269.141702)
		(width 0.12954)
		(layer "F.Cu")
		(net "RST_M_EF_CPU0_FPGA_N")
	)
	(segment
		(start 415.69005 -269.141702)
		(end 415.292286 -269.141702)
		(width 0.12954)
		(layer "F.Cu")
		(net "RST_M_EF_CPU0_FPGA_N")
	)
	(segment
		(start 431.692812 -269.242032)
		(end 431.692812 -268.844776)
		(width 0.12954)
		(layer "F.Cu")
		(net "RST_M_EF_CPU0_FPGA_N")
	)
	(segment
		(start 423.41165 -269.141702)
		(end 422.851326 -269.141702)
		(width 0.12954)
		(layer "F.Cu")
		(net "RST_M_EF_CPU0_FPGA_N")
	)
	(segment
		(start 416.008058 -269.45971)
		(end 415.69005 -269.141702)
		(width 0.12954)
		(layer "F.Cu")
		(net "RST_M_EF_CPU0_FPGA_N")
	)
	(segment
		(start 413.242506 -269.141702)
		(end 413.043624 -269.141702)
		(width 0.12954)
		(layer "F.Cu")
		(net "RST_M_EF_CPU0_FPGA_N")
	)
	(segment
		(start 420.41572 -269.141702)
		(end 419.990778 -268.71676)
		(width 0.12954)
		(layer "F.Cu")
		(net "RST_M_EF_CPU0_FPGA_N")
	)
	(segment
		(start 430.680114 -269.141702)
		(end 430.959514 -269.421102)
		(width 0.12954)
		(layer "F.Cu")
		(net "RST_M_EF_CPU0_FPGA_N")
	)
	(segment
		(start 425.177712 -268.50721)
		(end 424.046142 -268.50721)
		(width 0.12954)
		(layer "F.Cu")
		(net "RST_M_EF_CPU0_FPGA_N")
	)
	(segment
		(start 428.457106 -269.141702)
		(end 430.324006 -269.141702)
		(width 0.1016)
		(layer "F.Cu")
		(net "RST_M_EF_CPU0_FPGA_N")
	)
	(segment
		(start 426.44187 -268.71676)
		(end 426.6819 -268.47673)
		(width 0.12954)
		(layer "F.Cu")
		(net "RST_M_EF_CPU0_FPGA_N")
	)
	(segment
		(start 419.990778 -268.71676)
		(end 418.397182 -268.71676)
		(width 0.12954)
		(layer "F.Cu")
		(net "RST_M_EF_CPU0_FPGA_N")
	)
	(segment
		(start 412.618682 -268.71676)
		(end 410.853382 -268.71676)
		(width 0.12954)
		(layer "F.Cu")
		(net "RST_M_EF_CPU0_FPGA_N")
	)
	(segment
		(start 416.490404 -269.45971)
		(end 416.008058 -269.45971)
		(width 0.12954)
		(layer "F.Cu")
		(net "RST_M_EF_CPU0_FPGA_N")
	)
	(segment
		(start 430.324006 -269.141702)
		(end 430.680114 -269.141702)
		(width 0.12954)
		(layer "F.Cu")
		(net "RST_M_EF_CPU0_FPGA_N")
	)
	(segment
		(start 418.397182 -268.71676)
		(end 416.848544 -268.71676)
		(width 0.12954)
		(layer "F.Cu")
		(net "RST_M_EF_CPU0_FPGA_N")
	)
	(segment
		(start 430.959514 -269.421102)
		(end 431.513742 -269.421102)
		(width 0.12954)
		(layer "F.Cu")
		(net "RST_M_EF_CPU0_FPGA_N")
	)
	(segment
		(start 424.046142 -268.50721)
		(end 423.41165 -269.141702)
		(width 0.12954)
		(layer "F.Cu")
		(net "RST_M_EF_CPU0_FPGA_N")
	)
	(segment
		(start 422.851326 -269.141702)
		(end 420.849806 -269.141702)
		(width 0.1016)
		(layer "F.Cu")
		(net "RST_M_EF_CPU0_FPGA_N")
	)
	(segment
		(start 431.692812 -268.844776)
		(end 431.820828 -268.71676)
		(width 0.12954)
		(layer "F.Cu")
		(net "RST_M_EF_CPU0_FPGA_N")
	)
	(segment
		(start 413.043624 -269.141702)
		(end 412.618682 -268.71676)
		(width 0.12954)
		(layer "F.Cu")
		(net "RST_M_EF_CPU0_FPGA_N")
	)
	(segment
		(start 415.292286 -269.141702)
		(end 413.242506 -269.141702)
		(width 0.1016)
		(layer "F.Cu")
		(net "RST_M_EF_CPU0_FPGA_N")
	)
	(segment
		(start 431.513742 -269.421102)
		(end 431.692812 -269.242032)
		(width 0.12954)
		(layer "F.Cu")
		(net "RST_M_EF_CPU0_FPGA_N")
	)
	(segment
		(start 428.123858 -269.141702)
		(end 428.457106 -269.141702)
		(width 0.12954)
		(layer "F.Cu")
		(net "RST_M_EF_CPU0_FPGA_N")
	)
	(via
		(at 432.379882 -268.71676)
		(size 0.4572)
		(drill 0.2032)
		(layers "F.Cu" "B.Cu")
		(net "RST_M_EF_CPU0_FPGA_N")
	)
	(via
		(at 430.799494 -257.560826)
		(size 0.6604)
		(drill 0.3302)
		(layers "F.Cu" "B.Cu")
		(net "RST_M_EF_CPU0_FPGA_N")
	)
	(segment
		(start 431.227738 -257.98907)
		(end 430.799494 -257.560826)
		(width 0.12954)
		(layer "B.Cu")
		(net "RST_M_EF_CPU0_FPGA_N")
	)
	(segment
		(start 426.340016 -253.101348)
		(end 424.43908 -253.101348)
		(width 0.12954)
		(layer "B.Cu")
		(net "RST_M_EF_CPU0_FPGA_N")
	)
	(segment
		(start 423.338244 -193.753486)
		(end 422.314624 -193.753486)
		(width 0.12954)
		(layer "B.Cu")
		(net "RST_M_EF_CPU0_FPGA_N")
	)
	(segment
		(start 431.541428 -268.71676)
		(end 431.227738 -268.40307)
		(width 0.12954)
		(layer "B.Cu")
		(net "RST_M_EF_CPU0_FPGA_N")
	)
	(segment
		(start 424.43908 -253.101348)
		(end 423.70248 -252.364748)
		(width 0.12954)
		(layer "B.Cu")
		(net "RST_M_EF_CPU0_FPGA_N")
	)
	(segment
		(start 430.799494 -257.560826)
		(end 426.340016 -253.101348)
		(width 0.12954)
		(layer "B.Cu")
		(net "RST_M_EF_CPU0_FPGA_N")
	)
	(segment
		(start 422.314624 -194.004946)
		(end 422.314624 -193.753486)
		(width 0.12954)
		(layer "B.Cu")
		(net "RST_M_EF_CPU0_FPGA_N")
	)
	(segment
		(start 423.70248 -195.392802)
		(end 422.314624 -194.004946)
		(width 0.12954)
		(layer "B.Cu")
		(net "RST_M_EF_CPU0_FPGA_N")
	)
	(segment
		(start 431.227738 -268.40307)
		(end 431.227738 -257.98907)
		(width 0.12954)
		(layer "B.Cu")
		(net "RST_M_EF_CPU0_FPGA_N")
	)
	(segment
		(start 432.379882 -268.71676)
		(end 431.541428 -268.71676)
		(width 0.12954)
		(layer "B.Cu")
		(net "RST_M_EF_CPU0_FPGA_N")
	)
	(segment
		(start 423.70248 -252.364748)
		(end 423.70248 -195.392802)
		(width 0.12954)
		(layer "B.Cu")
		(net "RST_M_EF_CPU0_FPGA_N")
	)
	(segment
		(start 13.692378 -268.471396)
		(end 14.063726 -268.842744)
		(width 0.12954)
		(layer "F.Cu")
		(net "RST_M_CD_CPU1_FPGA_N")
	)
	(segment
		(start 32.371284 -268.291564)
		(end 31.640018 -268.291564)
		(width 0.12954)
		(layer "F.Cu")
		(net "RST_M_CD_CPU1_FPGA_N")
	)
	(segment
		(start 34.871914 -268.71676)
		(end 35.976814 -268.71676)
		(width 0.12954)
		(layer "F.Cu")
		(net "RST_M_CD_CPU1_FPGA_N")
	)
	(segment
		(start 17.74825 -268.671294)
		(end 18.061178 -268.671294)
		(width 0.12954)
		(layer "F.Cu")
		(net "RST_M_CD_CPU1_FPGA_N")
	)
	(segment
		(start 19.784568 -268.717014)
		(end 19.784314 -268.71676)
		(width 0.12954)
		(layer "F.Cu")
		(net "RST_M_CD_CPU1_FPGA_N")
	)
	(segment
		(start 18.608294 -268.924278)
		(end 18.815812 -268.71676)
		(width 0.12954)
		(layer "F.Cu")
		(net "RST_M_CD_CPU1_FPGA_N")
	)
	(segment
		(start 17.448784 -269.141702)
		(end 17.578578 -269.011908)
		(width 0.12954)
		(layer "F.Cu")
		(net "RST_M_CD_CPU1_FPGA_N")
	)
	(segment
		(start 14.812264 -269.141702)
		(end 16.896334 -269.141702)
		(width 0.1016)
		(layer "F.Cu")
		(net "RST_M_CD_CPU1_FPGA_N")
	)
	(segment
		(start 14.68628 -269.183104)
		(end 14.812264 -269.141702)
		(width 0.12954)
		(layer "F.Cu")
		(net "RST_M_CD_CPU1_FPGA_N")
	)
	(segment
		(start 18.314162 -268.924278)
		(end 18.608294 -268.924278)
		(width 0.12954)
		(layer "F.Cu")
		(net "RST_M_CD_CPU1_FPGA_N")
	)
	(segment
		(start 13.316458 -268.471396)
		(end 13.692378 -268.471396)
		(width 0.12954)
		(layer "F.Cu")
		(net "RST_M_CD_CPU1_FPGA_N")
	)
	(segment
		(start 17.578578 -269.011908)
		(end 17.578578 -268.840966)
		(width 0.12954)
		(layer "F.Cu")
		(net "RST_M_CD_CPU1_FPGA_N")
	)
	(segment
		(start 13.071094 -268.71676)
		(end 13.316458 -268.471396)
		(width 0.12954)
		(layer "F.Cu")
		(net "RST_M_CD_CPU1_FPGA_N")
	)
	(segment
		(start 22.35962 -268.291564)
		(end 21.781008 -268.291564)
		(width 0.12954)
		(layer "F.Cu")
		(net "RST_M_CD_CPU1_FPGA_N")
	)
	(segment
		(start 27.328114 -268.71676)
		(end 25.715468 -268.71676)
		(width 0.12954)
		(layer "F.Cu")
		(net "RST_M_CD_CPU1_FPGA_N")
	)
	(segment
		(start 32.79648 -268.71676)
		(end 32.371284 -268.291564)
		(width 0.12954)
		(layer "F.Cu")
		(net "RST_M_CD_CPU1_FPGA_N")
	)
	(segment
		(start 29.937202 -268.291564)
		(end 28.679394 -268.291564)
		(width 0.12954)
		(layer "F.Cu")
		(net "RST_M_CD_CPU1_FPGA_N")
	)
	(segment
		(start 21.781008 -268.291564)
		(end 21.355558 -268.717014)
		(width 0.12954)
		(layer "F.Cu")
		(net "RST_M_CD_CPU1_FPGA_N")
	)
	(segment
		(start 14.063726 -269.002764)
		(end 14.244066 -269.183104)
		(width 0.12954)
		(layer "F.Cu")
		(net "RST_M_CD_CPU1_FPGA_N")
	)
	(segment
		(start 14.063726 -268.842744)
		(end 14.063726 -269.002764)
		(width 0.12954)
		(layer "F.Cu")
		(net "RST_M_CD_CPU1_FPGA_N")
	)
	(segment
		(start 18.061178 -268.671294)
		(end 18.314162 -268.924278)
		(width 0.12954)
		(layer "F.Cu")
		(net "RST_M_CD_CPU1_FPGA_N")
	)
	(segment
		(start 31.640018 -268.291564)
		(end 29.937202 -268.291564)
		(width 0.1016)
		(layer "F.Cu")
		(net "RST_M_CD_CPU1_FPGA_N")
	)
	(segment
		(start 28.679394 -268.291564)
		(end 28.254198 -268.71676)
		(width 0.12954)
		(layer "F.Cu")
		(net "RST_M_CD_CPU1_FPGA_N")
	)
	(segment
		(start 28.254198 -268.71676)
		(end 27.328114 -268.71676)
		(width 0.12954)
		(layer "F.Cu")
		(net "RST_M_CD_CPU1_FPGA_N")
	)
	(segment
		(start 25.290272 -268.291564)
		(end 24.080978 -268.291564)
		(width 0.12954)
		(layer "F.Cu")
		(net "RST_M_CD_CPU1_FPGA_N")
	)
	(segment
		(start 16.896334 -269.141702)
		(end 17.448784 -269.141702)
		(width 0.12954)
		(layer "F.Cu")
		(net "RST_M_CD_CPU1_FPGA_N")
	)
	(segment
		(start 14.244066 -269.183104)
		(end 14.68628 -269.183104)
		(width 0.12954)
		(layer "F.Cu")
		(net "RST_M_CD_CPU1_FPGA_N")
	)
	(segment
		(start 21.355558 -268.717014)
		(end 19.784568 -268.717014)
		(width 0.12954)
		(layer "F.Cu")
		(net "RST_M_CD_CPU1_FPGA_N")
	)
	(segment
		(start 24.080978 -268.291564)
		(end 22.35962 -268.291564)
		(width 0.1016)
		(layer "F.Cu")
		(net "RST_M_CD_CPU1_FPGA_N")
	)
	(segment
		(start 18.815812 -268.71676)
		(end 19.784314 -268.71676)
		(width 0.12954)
		(layer "F.Cu")
		(net "RST_M_CD_CPU1_FPGA_N")
	)
	(segment
		(start 17.578578 -268.840966)
		(end 17.74825 -268.671294)
		(width 0.12954)
		(layer "F.Cu")
		(net "RST_M_CD_CPU1_FPGA_N")
	)
	(segment
		(start 12.240514 -268.71676)
		(end 13.071094 -268.71676)
		(width 0.12954)
		(layer "F.Cu")
		(net "RST_M_CD_CPU1_FPGA_N")
	)
	(segment
		(start 25.715468 -268.71676)
		(end 25.290272 -268.291564)
		(width 0.12954)
		(layer "F.Cu")
		(net "RST_M_CD_CPU1_FPGA_N")
	)
	(segment
		(start 34.871914 -268.71676)
		(end 32.79648 -268.71676)
		(width 0.12954)
		(layer "F.Cu")
		(net "RST_M_CD_CPU1_FPGA_N")
	)
	(via
		(at 35.976814 -268.71676)
		(size 0.4572)
		(drill 0.2032)
		(layers "F.Cu" "B.Cu")
		(net "RST_M_CD_CPU1_FPGA_N")
	)
	(via
		(at 27.394408 -194.83451)
		(size 0.6604)
		(drill 0.3302)
		(layers "F.Cu" "B.Cu")
		(net "RST_M_CD_CPU1_FPGA_N")
	)
	(segment
		(start 30.622748 -199.3138)
		(end 27.394408 -196.08546)
		(width 0.12954)
		(layer "B.Cu")
		(net "RST_M_CD_CPU1_FPGA_N")
	)
	(segment
		(start 34.6964 -257.41757)
		(end 33.599628 -256.320798)
		(width 0.12954)
		(layer "B.Cu")
		(net "RST_M_CD_CPU1_FPGA_N")
	)
	(segment
		(start 27.394408 -196.08546)
		(end 27.394408 -194.83451)
		(width 0.12954)
		(layer "B.Cu")
		(net "RST_M_CD_CPU1_FPGA_N")
	)
	(segment
		(start 31.585154 -256.320798)
		(end 30.622748 -255.358392)
		(width 0.12954)
		(layer "B.Cu")
		(net "RST_M_CD_CPU1_FPGA_N")
	)
	(segment
		(start 34.6964 -268.224254)
		(end 34.6964 -257.41757)
		(width 0.12954)
		(layer "B.Cu")
		(net "RST_M_CD_CPU1_FPGA_N")
	)
	(segment
		(start 35.188906 -268.71676)
		(end 34.6964 -268.224254)
		(width 0.12954)
		(layer "B.Cu")
		(net "RST_M_CD_CPU1_FPGA_N")
	)
	(segment
		(start 27.375866 -194.815968)
		(end 27.375866 -193.552826)
		(width 0.12954)
		(layer "B.Cu")
		(net "RST_M_CD_CPU1_FPGA_N")
	)
	(segment
		(start 35.976814 -268.71676)
		(end 35.188906 -268.71676)
		(width 0.12954)
		(layer "B.Cu")
		(net "RST_M_CD_CPU1_FPGA_N")
	)
	(segment
		(start 26.359866 -193.552826)
		(end 27.375866 -193.552826)
		(width 0.12954)
		(layer "B.Cu")
		(net "RST_M_CD_CPU1_FPGA_N")
	)
	(segment
		(start 27.394408 -194.83451)
		(end 27.375866 -194.815968)
		(width 0.12954)
		(layer "B.Cu")
		(net "RST_M_CD_CPU1_FPGA_N")
	)
	(segment
		(start 33.599628 -256.320798)
		(end 31.585154 -256.320798)
		(width 0.12954)
		(layer "B.Cu")
		(net "RST_M_CD_CPU1_FPGA_N")
	)
	(segment
		(start 30.622748 -255.358392)
		(end 30.622748 -199.3138)
		(width 0.12954)
		(layer "B.Cu")
		(net "RST_M_CD_CPU1_FPGA_N")
	)
	(segment
		(start 272.021046 -268.291564)
		(end 273.23034 -268.291564)
		(width 0.12954)
		(layer "F.Cu")
		(net "RST_M_CD_CPU0_FPGA_N")
	)
	(segment
		(start 262.003794 -268.842744)
		(end 262.003794 -269.002764)
		(width 0.12954)
		(layer "F.Cu")
		(net "RST_M_CD_CPU0_FPGA_N")
	)
	(segment
		(start 262.752332 -269.141702)
		(end 264.836402 -269.141702)
		(width 0.1016)
		(layer "F.Cu")
		(net "RST_M_CD_CPU0_FPGA_N")
	)
	(segment
		(start 267.724382 -268.71676)
		(end 267.724636 -268.717014)
		(width 0.12954)
		(layer "F.Cu")
		(net "RST_M_CD_CPU0_FPGA_N")
	)
	(segment
		(start 282.811982 -268.71676)
		(end 283.916882 -268.71676)
		(width 0.12954)
		(layer "F.Cu")
		(net "RST_M_CD_CPU0_FPGA_N")
	)
	(segment
		(start 273.655536 -268.71676)
		(end 275.268182 -268.71676)
		(width 0.12954)
		(layer "F.Cu")
		(net "RST_M_CD_CPU0_FPGA_N")
	)
	(segment
		(start 269.721076 -268.291564)
		(end 270.299688 -268.291564)
		(width 0.12954)
		(layer "F.Cu")
		(net "RST_M_CD_CPU0_FPGA_N")
	)
	(segment
		(start 279.580086 -268.291564)
		(end 280.311352 -268.291564)
		(width 0.12954)
		(layer "F.Cu")
		(net "RST_M_CD_CPU0_FPGA_N")
	)
	(segment
		(start 276.194266 -268.71676)
		(end 276.619462 -268.291564)
		(width 0.12954)
		(layer "F.Cu")
		(net "RST_M_CD_CPU0_FPGA_N")
	)
	(segment
		(start 262.003794 -269.002764)
		(end 262.184134 -269.183104)
		(width 0.12954)
		(layer "F.Cu")
		(net "RST_M_CD_CPU0_FPGA_N")
	)
	(segment
		(start 265.388852 -269.141702)
		(end 265.518646 -269.011908)
		(width 0.12954)
		(layer "F.Cu")
		(net "RST_M_CD_CPU0_FPGA_N")
	)
	(segment
		(start 262.626348 -269.183104)
		(end 262.752332 -269.141702)
		(width 0.12954)
		(layer "F.Cu")
		(net "RST_M_CD_CPU0_FPGA_N")
	)
	(segment
		(start 276.619462 -268.291564)
		(end 277.87727 -268.291564)
		(width 0.12954)
		(layer "F.Cu")
		(net "RST_M_CD_CPU0_FPGA_N")
	)
	(segment
		(start 269.295626 -268.717014)
		(end 269.721076 -268.291564)
		(width 0.12954)
		(layer "F.Cu")
		(net "RST_M_CD_CPU0_FPGA_N")
	)
	(segment
		(start 262.184134 -269.183104)
		(end 262.626348 -269.183104)
		(width 0.12954)
		(layer "F.Cu")
		(net "RST_M_CD_CPU0_FPGA_N")
	)
	(segment
		(start 275.268182 -268.71676)
		(end 276.194266 -268.71676)
		(width 0.12954)
		(layer "F.Cu")
		(net "RST_M_CD_CPU0_FPGA_N")
	)
	(segment
		(start 260.180582 -268.71676)
		(end 261.011162 -268.71676)
		(width 0.12954)
		(layer "F.Cu")
		(net "RST_M_CD_CPU0_FPGA_N")
	)
	(segment
		(start 261.011162 -268.71676)
		(end 261.256526 -268.471396)
		(width 0.12954)
		(layer "F.Cu")
		(net "RST_M_CD_CPU0_FPGA_N")
	)
	(segment
		(start 270.299688 -268.291564)
		(end 272.021046 -268.291564)
		(width 0.1016)
		(layer "F.Cu")
		(net "RST_M_CD_CPU0_FPGA_N")
	)
	(segment
		(start 266.548362 -268.924278)
		(end 266.75588 -268.71676)
		(width 0.12954)
		(layer "F.Cu")
		(net "RST_M_CD_CPU0_FPGA_N")
	)
	(segment
		(start 273.23034 -268.291564)
		(end 273.655536 -268.71676)
		(width 0.12954)
		(layer "F.Cu")
		(net "RST_M_CD_CPU0_FPGA_N")
	)
	(segment
		(start 280.311352 -268.291564)
		(end 280.736548 -268.71676)
		(width 0.12954)
		(layer "F.Cu")
		(net "RST_M_CD_CPU0_FPGA_N")
	)
	(segment
		(start 265.688318 -268.671294)
		(end 266.001246 -268.671294)
		(width 0.12954)
		(layer "F.Cu")
		(net "RST_M_CD_CPU0_FPGA_N")
	)
	(segment
		(start 266.75588 -268.71676)
		(end 267.724382 -268.71676)
		(width 0.12954)
		(layer "F.Cu")
		(net "RST_M_CD_CPU0_FPGA_N")
	)
	(segment
		(start 266.001246 -268.671294)
		(end 266.25423 -268.924278)
		(width 0.12954)
		(layer "F.Cu")
		(net "RST_M_CD_CPU0_FPGA_N")
	)
	(segment
		(start 261.256526 -268.471396)
		(end 261.632446 -268.471396)
		(width 0.12954)
		(layer "F.Cu")
		(net "RST_M_CD_CPU0_FPGA_N")
	)
	(segment
		(start 264.836402 -269.141702)
		(end 265.388852 -269.141702)
		(width 0.12954)
		(layer "F.Cu")
		(net "RST_M_CD_CPU0_FPGA_N")
	)
	(segment
		(start 277.87727 -268.291564)
		(end 279.580086 -268.291564)
		(width 0.1016)
		(layer "F.Cu")
		(net "RST_M_CD_CPU0_FPGA_N")
	)
	(segment
		(start 265.518646 -269.011908)
		(end 265.518646 -268.840966)
		(width 0.12954)
		(layer "F.Cu")
		(net "RST_M_CD_CPU0_FPGA_N")
	)
	(segment
		(start 261.632446 -268.471396)
		(end 262.003794 -268.842744)
		(width 0.12954)
		(layer "F.Cu")
		(net "RST_M_CD_CPU0_FPGA_N")
	)
	(segment
		(start 280.736548 -268.71676)
		(end 282.811982 -268.71676)
		(width 0.12954)
		(layer "F.Cu")
		(net "RST_M_CD_CPU0_FPGA_N")
	)
	(segment
		(start 265.518646 -268.840966)
		(end 265.688318 -268.671294)
		(width 0.12954)
		(layer "F.Cu")
		(net "RST_M_CD_CPU0_FPGA_N")
	)
	(segment
		(start 266.25423 -268.924278)
		(end 266.548362 -268.924278)
		(width 0.12954)
		(layer "F.Cu")
		(net "RST_M_CD_CPU0_FPGA_N")
	)
	(segment
		(start 267.724636 -268.717014)
		(end 269.295626 -268.717014)
		(width 0.12954)
		(layer "F.Cu")
		(net "RST_M_CD_CPU0_FPGA_N")
	)
	(via
		(at 277.665688 -256.86004)
		(size 0.6604)
		(drill 0.3302)
		(layers "F.Cu" "B.Cu")
		(net "RST_M_CD_CPU0_FPGA_N")
	)
	(via
		(at 283.916882 -268.71676)
		(size 0.4572)
		(drill 0.2032)
		(layers "F.Cu" "B.Cu")
		(net "RST_M_CD_CPU0_FPGA_N")
	)
	(segment
		(start 278.698198 -257.89255)
		(end 277.665688 -256.86004)
		(width 0.12954)
		(layer "B.Cu")
		(net "RST_M_CD_CPU0_FPGA_N")
	)
	(segment
		(start 282.363418 -257.89255)
		(end 278.698198 -257.89255)
		(width 0.12954)
		(layer "B.Cu")
		(net "RST_M_CD_CPU0_FPGA_N")
	)
	(segment
		(start 272.843498 -252.15469)
		(end 272.843498 -201.26325)
		(width 0.12954)
		(layer "B.Cu")
		(net "RST_M_CD_CPU0_FPGA_N")
	)
	(segment
		(start 270.793718 -199.21347)
		(end 270.793718 -193.996818)
		(width 0.12954)
		(layer "B.Cu")
		(net "RST_M_CD_CPU0_FPGA_N")
	)
	(segment
		(start 274.878292 -253.564136)
		(end 274.388326 -253.07417)
		(width 0.12954)
		(layer "B.Cu")
		(net "RST_M_CD_CPU0_FPGA_N")
	)
	(segment
		(start 273.762978 -253.07417)
		(end 272.843498 -252.15469)
		(width 0.12954)
		(layer "B.Cu")
		(net "RST_M_CD_CPU0_FPGA_N")
	)
	(segment
		(start 283.916882 -268.71676)
		(end 283.252418 -268.052296)
		(width 0.12954)
		(layer "B.Cu")
		(net "RST_M_CD_CPU0_FPGA_N")
	)
	(segment
		(start 282.698698 -258.20751)
		(end 282.678378 -258.20751)
		(width 0.12954)
		(layer "B.Cu")
		(net "RST_M_CD_CPU0_FPGA_N")
	)
	(segment
		(start 270.700246 -193.903346)
		(end 269.684246 -193.903346)
		(width 0.12954)
		(layer "B.Cu")
		(net "RST_M_CD_CPU0_FPGA_N")
	)
	(segment
		(start 282.678378 -258.20751)
		(end 282.363418 -257.89255)
		(width 0.12954)
		(layer "B.Cu")
		(net "RST_M_CD_CPU0_FPGA_N")
	)
	(segment
		(start 283.252418 -258.76123)
		(end 282.698698 -258.20751)
		(width 0.12954)
		(layer "B.Cu")
		(net "RST_M_CD_CPU0_FPGA_N")
	)
	(segment
		(start 283.252418 -268.052296)
		(end 283.252418 -258.76123)
		(width 0.12954)
		(layer "B.Cu")
		(net "RST_M_CD_CPU0_FPGA_N")
	)
	(segment
		(start 272.843498 -201.26325)
		(end 270.793718 -199.21347)
		(width 0.12954)
		(layer "B.Cu")
		(net "RST_M_CD_CPU0_FPGA_N")
	)
	(segment
		(start 275.237702 -254.432054)
		(end 274.878292 -253.564136)
		(width 0.12954)
		(layer "B.Cu")
		(net "RST_M_CD_CPU0_FPGA_N")
	)
	(segment
		(start 277.665688 -256.86004)
		(end 275.237702 -254.432054)
		(width 0.12954)
		(layer "B.Cu")
		(net "RST_M_CD_CPU0_FPGA_N")
	)
	(segment
		(start 274.388326 -253.07417)
		(end 273.762978 -253.07417)
		(width 0.12954)
		(layer "B.Cu")
		(net "RST_M_CD_CPU0_FPGA_N")
	)
	(segment
		(start 270.793718 -193.996818)
		(end 270.700246 -193.903346)
		(width 0.12954)
		(layer "B.Cu")
		(net "RST_M_CD_CPU0_FPGA_N")
	)
	(segment
		(start 43.872658 -268.476476)
		(end 43.153838 -268.476476)
		(width 0.12954)
		(layer "F.Cu")
		(net "RST_M_AB_CPU1_FPGA_N")
	)
	(segment
		(start 44.238926 -269.002764)
		(end 44.238926 -268.842744)
		(width 0.12954)
		(layer "F.Cu")
		(net "RST_M_AB_CPU1_FPGA_N")
	)
	(segment
		(start 54.257448 -269.141702)
		(end 52.546504 -269.141702)
		(width 0.1016)
		(layer "F.Cu")
		(net "RST_M_AB_CPU1_FPGA_N")
	)
	(segment
		(start 44.377864 -269.141702)
		(end 44.238926 -269.002764)
		(width 0.12954)
		(layer "F.Cu")
		(net "RST_M_AB_CPU1_FPGA_N")
	)
	(segment
		(start 48.489362 -268.924278)
		(end 48.236378 -268.671294)
		(width 0.12954)
		(layer "F.Cu")
		(net "RST_M_AB_CPU1_FPGA_N")
	)
	(segment
		(start 46.70425 -269.141702)
		(end 45.017436 -269.141702)
		(width 0.1016)
		(layer "F.Cu")
		(net "RST_M_AB_CPU1_FPGA_N")
	)
	(segment
		(start 48.783494 -268.924278)
		(end 48.489362 -268.924278)
		(width 0.12954)
		(layer "F.Cu")
		(net "RST_M_AB_CPU1_FPGA_N")
	)
	(segment
		(start 57.503314 -268.71676)
		(end 59.034172 -268.71676)
		(width 0.12954)
		(layer "F.Cu")
		(net "RST_M_AB_CPU1_FPGA_N")
	)
	(segment
		(start 47.753778 -268.840966)
		(end 47.753778 -269.011908)
		(width 0.12954)
		(layer "F.Cu")
		(net "RST_M_AB_CPU1_FPGA_N")
	)
	(segment
		(start 47.753778 -269.011908)
		(end 47.623984 -269.141702)
		(width 0.12954)
		(layer "F.Cu")
		(net "RST_M_AB_CPU1_FPGA_N")
	)
	(segment
		(start 51.315874 -268.71676)
		(end 49.959514 -268.71676)
		(width 0.12954)
		(layer "F.Cu")
		(net "RST_M_AB_CPU1_FPGA_N")
	)
	(segment
		(start 52.546504 -269.141702)
		(end 51.740816 -269.141702)
		(width 0.12954)
		(layer "F.Cu")
		(net "RST_M_AB_CPU1_FPGA_N")
	)
	(segment
		(start 61.908944 -269.141702)
		(end 61.909706 -269.142464)
		(width 0.1016)
		(layer "F.Cu")
		(net "RST_M_AB_CPU1_FPGA_N")
	)
	(segment
		(start 48.991012 -268.71676)
		(end 48.783494 -268.924278)
		(width 0.12954)
		(layer "F.Cu")
		(net "RST_M_AB_CPU1_FPGA_N")
	)
	(segment
		(start 48.236378 -268.671294)
		(end 47.92345 -268.671294)
		(width 0.12954)
		(layer "F.Cu")
		(net "RST_M_AB_CPU1_FPGA_N")
	)
	(segment
		(start 59.82843 -269.141702)
		(end 61.908944 -269.141702)
		(width 0.1016)
		(layer "F.Cu")
		(net "RST_M_AB_CPU1_FPGA_N")
	)
	(segment
		(start 59.473084 -269.155672)
		(end 59.786266 -269.155672)
		(width 0.12954)
		(layer "F.Cu")
		(net "RST_M_AB_CPU1_FPGA_N")
	)
	(segment
		(start 65.047114 -268.71676)
		(end 66.152014 -268.71676)
		(width 0.12954)
		(layer "F.Cu")
		(net "RST_M_AB_CPU1_FPGA_N")
	)
	(segment
		(start 49.959514 -268.71676)
		(end 48.991012 -268.71676)
		(width 0.12954)
		(layer "F.Cu")
		(net "RST_M_AB_CPU1_FPGA_N")
	)
	(segment
		(start 57.503314 -268.71676)
		(end 55.266844 -268.71676)
		(width 0.12954)
		(layer "F.Cu")
		(net "RST_M_AB_CPU1_FPGA_N")
	)
	(segment
		(start 62.866016 -268.71676)
		(end 65.047114 -268.71676)
		(width 0.12954)
		(layer "F.Cu")
		(net "RST_M_AB_CPU1_FPGA_N")
	)
	(segment
		(start 61.909706 -269.142464)
		(end 62.147958 -269.142464)
		(width 0.1016)
		(layer "F.Cu")
		(net "RST_M_AB_CPU1_FPGA_N")
	)
	(segment
		(start 62.440312 -269.142464)
		(end 62.866016 -268.71676)
		(width 0.12954)
		(layer "F.Cu")
		(net "RST_M_AB_CPU1_FPGA_N")
	)
	(segment
		(start 55.266844 -268.71676)
		(end 54.841902 -269.141702)
		(width 0.12954)
		(layer "F.Cu")
		(net "RST_M_AB_CPU1_FPGA_N")
	)
	(segment
		(start 54.841902 -269.141702)
		(end 54.257448 -269.141702)
		(width 0.12954)
		(layer "F.Cu")
		(net "RST_M_AB_CPU1_FPGA_N")
	)
	(segment
		(start 45.017436 -269.141702)
		(end 44.377864 -269.141702)
		(width 0.12954)
		(layer "F.Cu")
		(net "RST_M_AB_CPU1_FPGA_N")
	)
	(segment
		(start 44.238926 -268.842744)
		(end 43.872658 -268.476476)
		(width 0.12954)
		(layer "F.Cu")
		(net "RST_M_AB_CPU1_FPGA_N")
	)
	(segment
		(start 43.153838 -268.476476)
		(end 42.913554 -268.71676)
		(width 0.12954)
		(layer "F.Cu")
		(net "RST_M_AB_CPU1_FPGA_N")
	)
	(segment
		(start 47.623984 -269.141702)
		(end 46.70425 -269.141702)
		(width 0.12954)
		(layer "F.Cu")
		(net "RST_M_AB_CPU1_FPGA_N")
	)
	(segment
		(start 42.913554 -268.71676)
		(end 42.415714 -268.71676)
		(width 0.12954)
		(layer "F.Cu")
		(net "RST_M_AB_CPU1_FPGA_N")
	)
	(segment
		(start 62.147958 -269.142464)
		(end 62.440312 -269.142464)
		(width 0.12954)
		(layer "F.Cu")
		(net "RST_M_AB_CPU1_FPGA_N")
	)
	(segment
		(start 59.034172 -268.71676)
		(end 59.473084 -269.155672)
		(width 0.12954)
		(layer "F.Cu")
		(net "RST_M_AB_CPU1_FPGA_N")
	)
	(segment
		(start 59.786266 -269.155672)
		(end 59.82843 -269.141702)
		(width 0.1016)
		(layer "F.Cu")
		(net "RST_M_AB_CPU1_FPGA_N")
	)
	(segment
		(start 47.92345 -268.671294)
		(end 47.753778 -268.840966)
		(width 0.12954)
		(layer "F.Cu")
		(net "RST_M_AB_CPU1_FPGA_N")
	)
	(segment
		(start 51.740816 -269.141702)
		(end 51.315874 -268.71676)
		(width 0.12954)
		(layer "F.Cu")
		(net "RST_M_AB_CPU1_FPGA_N")
	)
	(via
		(at 66.152014 -268.71676)
		(size 0.4572)
		(drill 0.2032)
		(layers "F.Cu" "B.Cu")
		(net "RST_M_AB_CPU1_FPGA_N")
	)
	(via
		(at 64.90462 -268.71676)
		(size 0.6604)
		(drill 0.3302)
		(layers "F.Cu" "B.Cu")
		(net "RST_M_AB_CPU1_FPGA_N")
	)
	(segment
		(start 52.2478 -267.993368)
		(end 51.508406 -268.732762)
		(width 0.12954)
		(layer "B.Cu")
		(net "RST_M_AB_CPU1_FPGA_N")
	)
	(segment
		(start 43.138598 -256.49809)
		(end 39.516558 -256.49809)
		(width 0.12954)
		(layer "B.Cu")
		(net "RST_M_AB_CPU1_FPGA_N")
	)
	(segment
		(start 39.516558 -256.49809)
		(end 37.975286 -254.956818)
		(width 0.12954)
		(layer "B.Cu")
		(net "RST_M_AB_CPU1_FPGA_N")
	)
	(segment
		(start 66.152014 -268.71676)
		(end 64.90462 -268.71676)
		(width 0.12954)
		(layer "B.Cu")
		(net "RST_M_AB_CPU1_FPGA_N")
	)
	(segment
		(start 63.5381 -268.71676)
		(end 62.814708 -267.993368)
		(width 0.12954)
		(layer "B.Cu")
		(net "RST_M_AB_CPU1_FPGA_N")
	)
	(segment
		(start 50.834544 -268.732762)
		(end 49.963578 -267.861796)
		(width 0.12954)
		(layer "B.Cu")
		(net "RST_M_AB_CPU1_FPGA_N")
	)
	(segment
		(start 55.107332 -267.993368)
		(end 52.2478 -267.993368)
		(width 0.12954)
		(layer "B.Cu")
		(net "RST_M_AB_CPU1_FPGA_N")
	)
	(segment
		(start 38.546278 -197.618858)
		(end 38.546278 -194.271138)
		(width 0.12954)
		(layer "B.Cu")
		(net "RST_M_AB_CPU1_FPGA_N")
	)
	(segment
		(start 37.975286 -198.18985)
		(end 38.546278 -197.618858)
		(width 0.12954)
		(layer "B.Cu")
		(net "RST_M_AB_CPU1_FPGA_N")
	)
	(segment
		(start 44.705778 -258.06527)
		(end 43.138598 -256.49809)
		(width 0.12954)
		(layer "B.Cu")
		(net "RST_M_AB_CPU1_FPGA_N")
	)
	(segment
		(start 58.919872 -268.732762)
		(end 55.846726 -268.732762)
		(width 0.12954)
		(layer "B.Cu")
		(net "RST_M_AB_CPU1_FPGA_N")
	)
	(segment
		(start 59.659266 -267.993368)
		(end 58.919872 -268.732762)
		(width 0.12954)
		(layer "B.Cu")
		(net "RST_M_AB_CPU1_FPGA_N")
	)
	(segment
		(start 49.963578 -260.65607)
		(end 48.277018 -258.96951)
		(width 0.12954)
		(layer "B.Cu")
		(net "RST_M_AB_CPU1_FPGA_N")
	)
	(segment
		(start 38.546278 -194.271138)
		(end 37.599366 -193.324226)
		(width 0.12954)
		(layer "B.Cu")
		(net "RST_M_AB_CPU1_FPGA_N")
	)
	(segment
		(start 46.283118 -258.96951)
		(end 45.378878 -258.06527)
		(width 0.12954)
		(layer "B.Cu")
		(net "RST_M_AB_CPU1_FPGA_N")
	)
	(segment
		(start 55.846726 -268.732762)
		(end 55.107332 -267.993368)
		(width 0.12954)
		(layer "B.Cu")
		(net "RST_M_AB_CPU1_FPGA_N")
	)
	(segment
		(start 45.378878 -258.06527)
		(end 44.705778 -258.06527)
		(width 0.12954)
		(layer "B.Cu")
		(net "RST_M_AB_CPU1_FPGA_N")
	)
	(segment
		(start 48.277018 -258.96951)
		(end 46.283118 -258.96951)
		(width 0.12954)
		(layer "B.Cu")
		(net "RST_M_AB_CPU1_FPGA_N")
	)
	(segment
		(start 37.975286 -254.956818)
		(end 37.975286 -198.18985)
		(width 0.12954)
		(layer "B.Cu")
		(net "RST_M_AB_CPU1_FPGA_N")
	)
	(segment
		(start 36.583366 -193.324226)
		(end 37.599366 -193.324226)
		(width 0.12954)
		(layer "B.Cu")
		(net "RST_M_AB_CPU1_FPGA_N")
	)
	(segment
		(start 49.963578 -267.861796)
		(end 49.963578 -260.65607)
		(width 0.12954)
		(layer "B.Cu")
		(net "RST_M_AB_CPU1_FPGA_N")
	)
	(segment
		(start 51.508406 -268.732762)
		(end 50.834544 -268.732762)
		(width 0.12954)
		(layer "B.Cu")
		(net "RST_M_AB_CPU1_FPGA_N")
	)
	(segment
		(start 62.814708 -267.993368)
		(end 59.659266 -267.993368)
		(width 0.12954)
		(layer "B.Cu")
		(net "RST_M_AB_CPU1_FPGA_N")
	)
	(segment
		(start 64.90462 -268.71676)
		(end 63.5381 -268.71676)
		(width 0.12954)
		(layer "B.Cu")
		(net "RST_M_AB_CPU1_FPGA_N")
	)
	(segment
		(start 307.413152 -269.155672)
		(end 307.726334 -269.155672)
		(width 0.12954)
		(layer "F.Cu")
		(net "RST_M_AB_CPU0_FPGA_N")
	)
	(segment
		(start 310.598566 -268.924278)
		(end 311.809384 -268.924278)
		(width 0.12954)
		(layer "F.Cu")
		(net "RST_M_AB_CPU0_FPGA_N")
	)
	(segment
		(start 297.899836 -268.717014)
		(end 299.256196 -268.717014)
		(width 0.12954)
		(layer "F.Cu")
		(net "RST_M_AB_CPU0_FPGA_N")
	)
	(segment
		(start 296.93108 -268.71676)
		(end 297.899582 -268.71676)
		(width 0.12954)
		(layer "F.Cu")
		(net "RST_M_AB_CPU0_FPGA_N")
	)
	(segment
		(start 310.38038 -269.142464)
		(end 310.598566 -268.924278)
		(width 0.12954)
		(layer "F.Cu")
		(net "RST_M_AB_CPU0_FPGA_N")
	)
	(segment
		(start 303.206912 -268.71676)
		(end 305.443382 -268.71676)
		(width 0.12954)
		(layer "F.Cu")
		(net "RST_M_AB_CPU0_FPGA_N")
	)
	(segment
		(start 295.693846 -268.840966)
		(end 295.863518 -268.671294)
		(width 0.12954)
		(layer "F.Cu")
		(net "RST_M_AB_CPU0_FPGA_N")
	)
	(segment
		(start 291.093906 -268.476476)
		(end 291.812726 -268.476476)
		(width 0.12954)
		(layer "F.Cu")
		(net "RST_M_AB_CPU0_FPGA_N")
	)
	(segment
		(start 309.849774 -269.142464)
		(end 310.088026 -269.142464)
		(width 0.1016)
		(layer "F.Cu")
		(net "RST_M_AB_CPU0_FPGA_N")
	)
	(segment
		(start 312.016902 -268.71676)
		(end 312.987182 -268.71676)
		(width 0.12954)
		(layer "F.Cu")
		(net "RST_M_AB_CPU0_FPGA_N")
	)
	(segment
		(start 307.726334 -269.155672)
		(end 307.768498 -269.141702)
		(width 0.1016)
		(layer "F.Cu")
		(net "RST_M_AB_CPU0_FPGA_N")
	)
	(segment
		(start 291.812726 -268.476476)
		(end 292.178994 -268.842744)
		(width 0.12954)
		(layer "F.Cu")
		(net "RST_M_AB_CPU0_FPGA_N")
	)
	(segment
		(start 290.853622 -268.71676)
		(end 291.093906 -268.476476)
		(width 0.12954)
		(layer "F.Cu")
		(net "RST_M_AB_CPU0_FPGA_N")
	)
	(segment
		(start 290.355782 -268.71676)
		(end 290.853622 -268.71676)
		(width 0.12954)
		(layer "F.Cu")
		(net "RST_M_AB_CPU0_FPGA_N")
	)
	(segment
		(start 295.693846 -269.011908)
		(end 295.693846 -268.840966)
		(width 0.12954)
		(layer "F.Cu")
		(net "RST_M_AB_CPU0_FPGA_N")
	)
	(segment
		(start 312.987182 -268.71676)
		(end 314.092082 -268.71676)
		(width 0.12954)
		(layer "F.Cu")
		(net "RST_M_AB_CPU0_FPGA_N")
	)
	(segment
		(start 299.680884 -269.141702)
		(end 300.486572 -269.141702)
		(width 0.12954)
		(layer "F.Cu")
		(net "RST_M_AB_CPU0_FPGA_N")
	)
	(segment
		(start 306.97424 -268.71676)
		(end 307.413152 -269.155672)
		(width 0.12954)
		(layer "F.Cu")
		(net "RST_M_AB_CPU0_FPGA_N")
	)
	(segment
		(start 299.256196 -268.717014)
		(end 299.680884 -269.141702)
		(width 0.12954)
		(layer "F.Cu")
		(net "RST_M_AB_CPU0_FPGA_N")
	)
	(segment
		(start 296.723562 -268.924278)
		(end 296.93108 -268.71676)
		(width 0.12954)
		(layer "F.Cu")
		(net "RST_M_AB_CPU0_FPGA_N")
	)
	(segment
		(start 305.443382 -268.71676)
		(end 306.97424 -268.71676)
		(width 0.12954)
		(layer "F.Cu")
		(net "RST_M_AB_CPU0_FPGA_N")
	)
	(segment
		(start 309.849012 -269.141702)
		(end 309.849774 -269.142464)
		(width 0.1016)
		(layer "F.Cu")
		(net "RST_M_AB_CPU0_FPGA_N")
	)
	(segment
		(start 292.957504 -269.141702)
		(end 294.644318 -269.141702)
		(width 0.1016)
		(layer "F.Cu")
		(net "RST_M_AB_CPU0_FPGA_N")
	)
	(segment
		(start 302.78197 -269.141702)
		(end 303.206912 -268.71676)
		(width 0.12954)
		(layer "F.Cu")
		(net "RST_M_AB_CPU0_FPGA_N")
	)
	(segment
		(start 302.197516 -269.141702)
		(end 302.78197 -269.141702)
		(width 0.12954)
		(layer "F.Cu")
		(net "RST_M_AB_CPU0_FPGA_N")
	)
	(segment
		(start 300.486572 -269.141702)
		(end 302.197516 -269.141702)
		(width 0.1016)
		(layer "F.Cu")
		(net "RST_M_AB_CPU0_FPGA_N")
	)
	(segment
		(start 296.42943 -268.924278)
		(end 296.723562 -268.924278)
		(width 0.12954)
		(layer "F.Cu")
		(net "RST_M_AB_CPU0_FPGA_N")
	)
	(segment
		(start 295.863518 -268.671294)
		(end 296.176446 -268.671294)
		(width 0.12954)
		(layer "F.Cu")
		(net "RST_M_AB_CPU0_FPGA_N")
	)
	(segment
		(start 292.178994 -269.002764)
		(end 292.317932 -269.141702)
		(width 0.12954)
		(layer "F.Cu")
		(net "RST_M_AB_CPU0_FPGA_N")
	)
	(segment
		(start 295.564052 -269.141702)
		(end 295.693846 -269.011908)
		(width 0.12954)
		(layer "F.Cu")
		(net "RST_M_AB_CPU0_FPGA_N")
	)
	(segment
		(start 296.176446 -268.671294)
		(end 296.42943 -268.924278)
		(width 0.12954)
		(layer "F.Cu")
		(net "RST_M_AB_CPU0_FPGA_N")
	)
	(segment
		(start 294.644318 -269.141702)
		(end 295.564052 -269.141702)
		(width 0.12954)
		(layer "F.Cu")
		(net "RST_M_AB_CPU0_FPGA_N")
	)
	(segment
		(start 292.178994 -268.842744)
		(end 292.178994 -269.002764)
		(width 0.12954)
		(layer "F.Cu")
		(net "RST_M_AB_CPU0_FPGA_N")
	)
	(segment
		(start 297.899582 -268.71676)
		(end 297.899836 -268.717014)
		(width 0.12954)
		(layer "F.Cu")
		(net "RST_M_AB_CPU0_FPGA_N")
	)
	(segment
		(start 292.317932 -269.141702)
		(end 292.957504 -269.141702)
		(width 0.12954)
		(layer "F.Cu")
		(net "RST_M_AB_CPU0_FPGA_N")
	)
	(segment
		(start 310.088026 -269.142464)
		(end 310.38038 -269.142464)
		(width 0.12954)
		(layer "F.Cu")
		(net "RST_M_AB_CPU0_FPGA_N")
	)
	(segment
		(start 311.809384 -268.924278)
		(end 312.016902 -268.71676)
		(width 0.12954)
		(layer "F.Cu")
		(net "RST_M_AB_CPU0_FPGA_N")
	)
	(segment
		(start 307.768498 -269.141702)
		(end 309.849012 -269.141702)
		(width 0.1016)
		(layer "F.Cu")
		(net "RST_M_AB_CPU0_FPGA_N")
	)
	(via
		(at 312.955178 -268.71676)
		(size 0.6604)
		(drill 0.3302)
		(layers "F.Cu" "B.Cu")
		(net "RST_M_AB_CPU0_FPGA_N")
	)
	(via
		(at 314.092082 -268.71676)
		(size 0.4572)
		(drill 0.2032)
		(layers "F.Cu" "B.Cu")
		(net "RST_M_AB_CPU0_FPGA_N")
	)
	(segment
		(start 303.798478 -268.30655)
		(end 303.023778 -268.30655)
		(width 0.12954)
		(layer "B.Cu")
		(net "RST_M_AB_CPU0_FPGA_N")
	)
	(segment
		(start 290.758118 -255.92151)
		(end 290.758118 -253.32055)
		(width 0.12954)
		(layer "B.Cu")
		(net "RST_M_AB_CPU0_FPGA_N")
	)
	(segment
		(start 304.039778 -268.54785)
		(end 303.798478 -268.30655)
		(width 0.12954)
		(layer "B.Cu")
		(net "RST_M_AB_CPU0_FPGA_N")
	)
	(segment
		(start 286.478726 -194.091306)
		(end 285.462726 -194.091306)
		(width 0.12954)
		(layer "B.Cu")
		(net "RST_M_AB_CPU0_FPGA_N")
	)
	(segment
		(start 307.166772 -269.16253)
		(end 306.552092 -268.54785)
		(width 0.12954)
		(layer "B.Cu")
		(net "RST_M_AB_CPU0_FPGA_N")
	)
	(segment
		(start 311.593484 -269.16253)
		(end 307.166772 -269.16253)
		(width 0.12954)
		(layer "B.Cu")
		(net "RST_M_AB_CPU0_FPGA_N")
	)
	(segment
		(start 293.596314 -261.46379)
		(end 293.275258 -261.142734)
		(width 0.12954)
		(layer "B.Cu")
		(net "RST_M_AB_CPU0_FPGA_N")
	)
	(segment
		(start 298.124118 -264.85723)
		(end 297.247818 -263.98093)
		(width 0.12954)
		(layer "B.Cu")
		(net "RST_M_AB_CPU0_FPGA_N")
	)
	(segment
		(start 288.047938 -251.13361)
		(end 286.943038 -251.13361)
		(width 0.12954)
		(layer "B.Cu")
		(net "RST_M_AB_CPU0_FPGA_N")
	)
	(segment
		(start 296.087038 -262.01751)
		(end 295.533318 -261.46379)
		(width 0.12954)
		(layer "B.Cu")
		(net "RST_M_AB_CPU0_FPGA_N")
	)
	(segment
		(start 299.584618 -265.71829)
		(end 298.253658 -265.71829)
		(width 0.12954)
		(layer "B.Cu")
		(net "RST_M_AB_CPU0_FPGA_N")
	)
	(segment
		(start 314.092082 -268.71676)
		(end 312.955178 -268.71676)
		(width 0.12954)
		(layer "B.Cu")
		(net "RST_M_AB_CPU0_FPGA_N")
	)
	(segment
		(start 286.622998 -196.52361)
		(end 286.478726 -196.379338)
		(width 0.12954)
		(layer "B.Cu")
		(net "RST_M_AB_CPU0_FPGA_N")
	)
	(segment
		(start 286.943038 -251.13361)
		(end 286.622998 -250.81357)
		(width 0.12954)
		(layer "B.Cu")
		(net "RST_M_AB_CPU0_FPGA_N")
	)
	(segment
		(start 293.275258 -258.43865)
		(end 290.758118 -255.92151)
		(width 0.12954)
		(layer "B.Cu")
		(net "RST_M_AB_CPU0_FPGA_N")
	)
	(segment
		(start 312.955178 -268.71676)
		(end 312.039254 -268.71676)
		(width 0.12954)
		(layer "B.Cu")
		(net "RST_M_AB_CPU0_FPGA_N")
	)
	(segment
		(start 297.247818 -262.53567)
		(end 296.729658 -262.01751)
		(width 0.12954)
		(layer "B.Cu")
		(net "RST_M_AB_CPU0_FPGA_N")
	)
	(segment
		(start 302.020732 -267.83665)
		(end 300.713648 -266.529566)
		(width 0.12954)
		(layer "B.Cu")
		(net "RST_M_AB_CPU0_FPGA_N")
	)
	(segment
		(start 297.247818 -263.98093)
		(end 297.247818 -262.53567)
		(width 0.12954)
		(layer "B.Cu")
		(net "RST_M_AB_CPU0_FPGA_N")
	)
	(segment
		(start 290.758118 -253.32055)
		(end 289.326828 -251.88926)
		(width 0.12954)
		(layer "B.Cu")
		(net "RST_M_AB_CPU0_FPGA_N")
	)
	(segment
		(start 289.326828 -251.88926)
		(end 288.803588 -251.88926)
		(width 0.12954)
		(layer "B.Cu")
		(net "RST_M_AB_CPU0_FPGA_N")
	)
	(segment
		(start 296.729658 -262.01751)
		(end 296.087038 -262.01751)
		(width 0.12954)
		(layer "B.Cu")
		(net "RST_M_AB_CPU0_FPGA_N")
	)
	(segment
		(start 298.124118 -265.58875)
		(end 298.124118 -264.85723)
		(width 0.12954)
		(layer "B.Cu")
		(net "RST_M_AB_CPU0_FPGA_N")
	)
	(segment
		(start 288.803588 -251.88926)
		(end 288.047938 -251.13361)
		(width 0.12954)
		(layer "B.Cu")
		(net "RST_M_AB_CPU0_FPGA_N")
	)
	(segment
		(start 286.622998 -250.81357)
		(end 286.622998 -196.52361)
		(width 0.12954)
		(layer "B.Cu")
		(net "RST_M_AB_CPU0_FPGA_N")
	)
	(segment
		(start 303.023778 -268.30655)
		(end 302.553878 -267.83665)
		(width 0.12954)
		(layer "B.Cu")
		(net "RST_M_AB_CPU0_FPGA_N")
	)
	(segment
		(start 300.713648 -266.529566)
		(end 300.395894 -266.529566)
		(width 0.12954)
		(layer "B.Cu")
		(net "RST_M_AB_CPU0_FPGA_N")
	)
	(segment
		(start 306.552092 -268.54785)
		(end 304.039778 -268.54785)
		(width 0.12954)
		(layer "B.Cu")
		(net "RST_M_AB_CPU0_FPGA_N")
	)
	(segment
		(start 293.275258 -261.142734)
		(end 293.275258 -258.43865)
		(width 0.12954)
		(layer "B.Cu")
		(net "RST_M_AB_CPU0_FPGA_N")
	)
	(segment
		(start 295.533318 -261.46379)
		(end 293.596314 -261.46379)
		(width 0.12954)
		(layer "B.Cu")
		(net "RST_M_AB_CPU0_FPGA_N")
	)
	(segment
		(start 312.039254 -268.71676)
		(end 311.593484 -269.16253)
		(width 0.12954)
		(layer "B.Cu")
		(net "RST_M_AB_CPU0_FPGA_N")
	)
	(segment
		(start 300.395894 -266.529566)
		(end 299.584618 -265.71829)
		(width 0.12954)
		(layer "B.Cu")
		(net "RST_M_AB_CPU0_FPGA_N")
	)
	(segment
		(start 298.253658 -265.71829)
		(end 298.124118 -265.58875)
		(width 0.12954)
		(layer "B.Cu")
		(net "RST_M_AB_CPU0_FPGA_N")
	)
	(segment
		(start 286.478726 -196.379338)
		(end 286.478726 -194.091306)
		(width 0.12954)
		(layer "B.Cu")
		(net "RST_M_AB_CPU0_FPGA_N")
	)
	(segment
		(start 302.553878 -267.83665)
		(end 302.020732 -267.83665)
		(width 0.12954)
		(layer "B.Cu")
		(net "RST_M_AB_CPU0_FPGA_N")
	)
	(segment
		(start 192.99174 -104.955848)
		(end 192.32118 -105.626408)
		(width 0.12954)
		(layer "F.Cu")
		(net "RST_MB_STBY_R_N")
	)
	(segment
		(start 190.72606 -108.130848)
		(end 190.50254 -108.130848)
		(width 0.12954)
		(layer "F.Cu")
		(net "RST_MB_STBY_R_N")
	)
	(segment
		(start 192.32118 -105.626408)
		(end 192.32118 -106.535728)
		(width 0.12954)
		(layer "F.Cu")
		(net "RST_MB_STBY_R_N")
	)
	(segment
		(start 197.01383 -104.955848)
		(end 195.597526 -104.955848)
		(width 0.12954)
		(layer "F.Cu")
		(net "RST_MB_STBY_R_N")
	)
	(segment
		(start 193.20383 -104.955848)
		(end 192.99174 -104.955848)
		(width 0.12954)
		(layer "F.Cu")
		(net "RST_MB_STBY_R_N")
	)
	(segment
		(start 187.28436 -108.549948)
		(end 186.581034 -108.549948)
		(width 0.12954)
		(layer "F.Cu")
		(net "RST_MB_STBY_R_N")
	)
	(segment
		(start 195.008246 -104.366568)
		(end 193.411094 -104.366568)
		(width 0.12954)
		(layer "F.Cu")
		(net "RST_MB_STBY_R_N")
	)
	(segment
		(start 193.20383 -104.573832)
		(end 193.20383 -104.955848)
		(width 0.12954)
		(layer "F.Cu")
		(net "RST_MB_STBY_R_N")
	)
	(segment
		(start 186.581034 -108.549948)
		(end 186.155584 -108.975398)
		(width 0.12954)
		(layer "F.Cu")
		(net "RST_MB_STBY_R_N")
	)
	(segment
		(start 190.50254 -108.130848)
		(end 187.70346 -108.130848)
		(width 0.12954)
		(layer "F.Cu")
		(net "RST_MB_STBY_R_N")
	)
	(segment
		(start 192.32118 -106.535728)
		(end 190.72606 -108.130848)
		(width 0.12954)
		(layer "F.Cu")
		(net "RST_MB_STBY_R_N")
	)
	(segment
		(start 187.70346 -108.130848)
		(end 187.28436 -108.549948)
		(width 0.12954)
		(layer "F.Cu")
		(net "RST_MB_STBY_R_N")
	)
	(segment
		(start 193.411094 -104.366568)
		(end 193.20383 -104.573832)
		(width 0.12954)
		(layer "F.Cu")
		(net "RST_MB_STBY_R_N")
	)
	(segment
		(start 195.597526 -104.955848)
		(end 195.008246 -104.366568)
		(width 0.12954)
		(layer "F.Cu")
		(net "RST_MB_STBY_R_N")
	)
	(via
		(at 190.50254 -108.130848)
		(size 0.762)
		(drill 0.381)
		(layers "F.Cu" "B.Cu")
		(net "RST_MB_STBY_R_N")
	)
	(segment
		(start 144.146778 -11.650726)
		(end 144.147032 -11.65098)
		(width 0.12954)
		(layer "F.Cu")
		(net "RST_MB_STBY_N")
	)
	(segment
		(start 197.81393 -104.955848)
		(end 198.42353 -104.955848)
		(width 0.12954)
		(layer "F.Cu")
		(net "RST_MB_STBY_N")
	)
	(segment
		(start 144.147032 -11.65098)
		(end 144.147032 -13.600176)
		(width 0.12954)
		(layer "F.Cu")
		(net "RST_MB_STBY_N")
	)
	(via
		(at 198.42353 -104.955848)
		(size 0.508)
		(drill 0.254)
		(layers "F.Cu" "B.Cu")
		(net "RST_MB_STBY_N")
	)
	(via
		(at 144.146778 -11.650726)
		(size 0.508)
		(drill 0.254)
		(layers "F.Cu" "B.Cu")
		(net "RST_MB_STBY_N")
	)
	(via
		(at 139.29106 -60.074048)
		(size 0.508)
		(drill 0.254)
		(layers "F.Cu" "B.Cu")
		(net "RST_MB_STBY_N")
	)
	(segment
		(start 139.07008 -58.259218)
		(end 139.29106 -58.480198)
		(width 0.127)
		(layer "In2.Cu")
		(net "RST_MB_STBY_N")
	)
	(segment
		(start 139.29106 -58.480198)
		(end 139.29106 -60.074048)
		(width 0.127)
		(layer "In2.Cu")
		(net "RST_MB_STBY_N")
	)
	(segment
		(start 143.52143 -13.649198)
		(end 143.52143 -20.607528)
		(width 0.127)
		(layer "In2.Cu")
		(net "RST_MB_STBY_N")
	)
	(segment
		(start 144.146778 -13.02385)
		(end 143.52143 -13.649198)
		(width 0.127)
		(layer "In2.Cu")
		(net "RST_MB_STBY_N")
	)
	(segment
		(start 140.93444 -36.637468)
		(end 140.93444 -38.296088)
		(width 0.127)
		(layer "In2.Cu")
		(net "RST_MB_STBY_N")
	)
	(segment
		(start 138.81608 -25.312878)
		(end 138.81608 -32.862774)
		(width 0.127)
		(layer "In2.Cu")
		(net "RST_MB_STBY_N")
	)
	(segment
		(start 144.146778 -11.650726)
		(end 144.146778 -13.02385)
		(width 0.127)
		(layer "In2.Cu")
		(net "RST_MB_STBY_N")
	)
	(segment
		(start 140.93444 -38.296088)
		(end 139.07008 -40.160448)
		(width 0.127)
		(layer "In2.Cu")
		(net "RST_MB_STBY_N")
	)
	(segment
		(start 143.52143 -20.607528)
		(end 138.81608 -25.312878)
		(width 0.127)
		(layer "In2.Cu")
		(net "RST_MB_STBY_N")
	)
	(segment
		(start 139.07008 -40.160448)
		(end 139.07008 -58.259218)
		(width 0.127)
		(layer "In2.Cu")
		(net "RST_MB_STBY_N")
	)
	(segment
		(start 138.81608 -32.862774)
		(end 139.07008 -33.116774)
		(width 0.127)
		(layer "In2.Cu")
		(net "RST_MB_STBY_N")
	)
	(segment
		(start 139.07008 -33.116774)
		(end 139.07008 -34.773108)
		(width 0.127)
		(layer "In2.Cu")
		(net "RST_MB_STBY_N")
	)
	(segment
		(start 139.07008 -34.773108)
		(end 140.93444 -36.637468)
		(width 0.127)
		(layer "In2.Cu")
		(net "RST_MB_STBY_N")
	)
	(segment
		(start 196.23532 -104.93756)
		(end 195.79844 -104.50068)
		(width 0.127)
		(layer "In4.Cu")
		(net "RST_MB_STBY_N")
	)
	(segment
		(start 190.29426 -94.359984)
		(end 190.29426 -86.64321)
		(width 0.127)
		(layer "In4.Cu")
		(net "RST_MB_STBY_N")
	)
	(segment
		(start 195.79844 -99.864164)
		(end 190.29426 -94.359984)
		(width 0.127)
		(layer "In4.Cu")
		(net "RST_MB_STBY_N")
	)
	(segment
		(start 190.29426 -86.64321)
		(end 188.55944 -84.90839)
		(width 0.127)
		(layer "In4.Cu")
		(net "RST_MB_STBY_N")
	)
	(segment
		(start 195.79844 -104.50068)
		(end 195.79844 -99.864164)
		(width 0.127)
		(layer "In4.Cu")
		(net "RST_MB_STBY_N")
	)
	(segment
		(start 160.473898 -68.268088)
		(end 141.842998 -68.268088)
		(width 0.127)
		(layer "In4.Cu")
		(net "RST_MB_STBY_N")
	)
	(segment
		(start 141.842998 -68.268088)
		(end 139.29106 -65.71615)
		(width 0.127)
		(layer "In4.Cu")
		(net "RST_MB_STBY_N")
	)
	(segment
		(start 188.55944 -84.90839)
		(end 177.1142 -84.90839)
		(width 0.127)
		(layer "In4.Cu")
		(net "RST_MB_STBY_N")
	)
	(segment
		(start 198.42353 -104.955848)
		(end 198.405242 -104.93756)
		(width 0.127)
		(layer "In4.Cu")
		(net "RST_MB_STBY_N")
	)
	(segment
		(start 198.405242 -104.93756)
		(end 196.23532 -104.93756)
		(width 0.127)
		(layer "In4.Cu")
		(net "RST_MB_STBY_N")
	)
	(segment
		(start 177.1142 -84.90839)
		(end 160.473898 -68.268088)
		(width 0.127)
		(layer "In4.Cu")
		(net "RST_MB_STBY_N")
	)
	(segment
		(start 139.29106 -65.71615)
		(end 139.29106 -60.074048)
		(width 0.127)
		(layer "In4.Cu")
		(net "RST_MB_STBY_N")
	)
	(segment
		(start 454.453498 -38.903148)
		(end 454.489312 -38.938962)
		(width 0.12954)
		(layer "F.Cu")
		(net "RST_HP_OCP_V3_1_N")
	)
	(segment
		(start 393.669774 -37.518594)
		(end 395.236446 -37.518594)
		(width 0.12954)
		(layer "F.Cu")
		(net "RST_HP_OCP_V3_1_N")
	)
	(segment
		(start 452.20128 -38.903148)
		(end 454.453498 -38.903148)
		(width 0.12954)
		(layer "F.Cu")
		(net "RST_HP_OCP_V3_1_N")
	)
	(via
		(at 395.236446 -37.518594)
		(size 0.508)
		(drill 0.254)
		(layers "F.Cu" "B.Cu")
		(net "RST_HP_OCP_V3_1_N")
	)
	(via
		(at 452.20128 -38.903148)
		(size 0.508)
		(drill 0.254)
		(layers "F.Cu" "B.Cu")
		(net "RST_HP_OCP_V3_1_N")
	)
	(segment
		(start 438.48528 -33.594548)
		(end 436.09768 -33.594548)
		(width 0.12954)
		(layer "B.Cu")
		(net "RST_HP_OCP_V3_1_N")
	)
	(segment
		(start 433.299362 -35.732466)
		(end 397.022574 -35.732466)
		(width 0.12954)
		(layer "B.Cu")
		(net "RST_HP_OCP_V3_1_N")
	)
	(segment
		(start 452.20128 -38.903148)
		(end 443.79388 -38.903148)
		(width 0.12954)
		(layer "B.Cu")
		(net "RST_HP_OCP_V3_1_N")
	)
	(segment
		(start 434.85308 -34.178748)
		(end 433.299362 -35.732466)
		(width 0.12954)
		(layer "B.Cu")
		(net "RST_HP_OCP_V3_1_N")
	)
	(segment
		(start 443.79388 -38.903148)
		(end 438.48528 -33.594548)
		(width 0.12954)
		(layer "B.Cu")
		(net "RST_HP_OCP_V3_1_N")
	)
	(segment
		(start 436.09768 -33.594548)
		(end 435.51348 -34.178748)
		(width 0.12954)
		(layer "B.Cu")
		(net "RST_HP_OCP_V3_1_N")
	)
	(segment
		(start 397.022574 -35.732466)
		(end 395.236446 -37.518594)
		(width 0.12954)
		(layer "B.Cu")
		(net "RST_HP_OCP_V3_1_N")
	)
	(segment
		(start 435.51348 -34.178748)
		(end 434.85308 -34.178748)
		(width 0.12954)
		(layer "B.Cu")
		(net "RST_HP_OCP_V3_1_N")
	)
	(segment
		(start 335.035398 -22.607778)
		(end 335.035398 -23.26513)
		(width 0.12954)
		(layer "F.Cu")
		(net "RST_ESPI_RESET_N_R")
	)
	(segment
		(start 333.071216 -24.117808)
		(end 333.071216 -23.371048)
		(width 0.12954)
		(layer "F.Cu")
		(net "RST_ESPI_RESET_N_R")
	)
	(segment
		(start 335.118456 -23.944326)
		(end 334.746854 -24.315928)
		(width 0.12954)
		(layer "F.Cu")
		(net "RST_ESPI_RESET_N_R")
	)
	(segment
		(start 335.035398 -23.26513)
		(end 335.118456 -23.348188)
		(width 0.12954)
		(layer "F.Cu")
		(net "RST_ESPI_RESET_N_R")
	)
	(segment
		(start 332.871572 -23.171404)
		(end 332.433168 -23.171404)
		(width 0.12954)
		(layer "F.Cu")
		(net "RST_ESPI_RESET_N_R")
	)
	(segment
		(start 333.071216 -23.371048)
		(end 332.871572 -23.171404)
		(width 0.12954)
		(layer "F.Cu")
		(net "RST_ESPI_RESET_N_R")
	)
	(segment
		(start 334.746854 -24.315928)
		(end 333.269336 -24.315928)
		(width 0.12954)
		(layer "F.Cu")
		(net "RST_ESPI_RESET_N_R")
	)
	(segment
		(start 335.118456 -23.348188)
		(end 335.118456 -23.944326)
		(width 0.12954)
		(layer "F.Cu")
		(net "RST_ESPI_RESET_N_R")
	)
	(segment
		(start 333.269336 -24.315928)
		(end 333.071216 -24.117808)
		(width 0.12954)
		(layer "F.Cu")
		(net "RST_ESPI_RESET_N_R")
	)
	(via
		(at 334.746854 -24.315928)
		(size 0.762)
		(drill 0.381)
		(layers "F.Cu" "B.Cu")
		(net "RST_ESPI_RESET_N_R")
	)
	(segment
		(start 334.41894 -34.201608)
		(end 334.127094 -33.909762)
		(width 0.0889)
		(layer "F.Cu")
		(net "RST_ESPI_RESET_N")
	)
	(segment
		(start 332.446884 -27.102308)
		(end 332.446884 -28.064206)
		(width 0.12954)
		(layer "F.Cu")
		(net "RST_ESPI_RESET_N")
	)
	(segment
		(start 332.301596 -26.457148)
		(end 332.301596 -26.95702)
		(width 0.12954)
		(layer "F.Cu")
		(net "RST_ESPI_RESET_N")
	)
	(segment
		(start 333.345536 -31.518606)
		(end 333.055214 -31.808928)
		(width 0.0889)
		(layer "F.Cu")
		(net "RST_ESPI_RESET_N")
	)
	(segment
		(start 333.345536 -29.599128)
		(end 333.345536 -30.509972)
		(width 0.12954)
		(layer "F.Cu")
		(net "RST_ESPI_RESET_N")
	)
	(segment
		(start 334.399128 -37.807392)
		(end 334.399128 -37.18814)
		(width 0.0889)
		(layer "F.Cu")
		(net "RST_ESPI_RESET_N")
	)
	(segment
		(start 332.446884 -28.064206)
		(end 332.896718 -29.15031)
		(width 0.12954)
		(layer "F.Cu")
		(net "RST_ESPI_RESET_N")
	)
	(segment
		(start 333.345536 -30.509972)
		(end 333.345536 -31.518606)
		(width 0.0889)
		(layer "F.Cu")
		(net "RST_ESPI_RESET_N")
	)
	(segment
		(start 332.301596 -26.95702)
		(end 332.446884 -27.102308)
		(width 0.12954)
		(layer "F.Cu")
		(net "RST_ESPI_RESET_N")
	)
	(segment
		(start 334.39862 -38.050216)
		(end 334.39862 -37.8079)
		(width 0.0889)
		(layer "F.Cu")
		(net "RST_ESPI_RESET_N")
	)
	(segment
		(start 332.433168 -23.971504)
		(end 332.446884 -23.98522)
		(width 0.12954)
		(layer "F.Cu")
		(net "RST_ESPI_RESET_N")
	)
	(segment
		(start 334.399128 -37.18814)
		(end 334.41894 -37.168328)
		(width 0.0889)
		(layer "F.Cu")
		(net "RST_ESPI_RESET_N")
	)
	(segment
		(start 332.446884 -23.98522)
		(end 332.446884 -25.766268)
		(width 0.12954)
		(layer "F.Cu")
		(net "RST_ESPI_RESET_N")
	)
	(segment
		(start 333.055214 -33.481772)
		(end 333.055214 -31.808928)
		(width 0.0889)
		(layer "F.Cu")
		(net "RST_ESPI_RESET_N")
	)
	(segment
		(start 333.483204 -33.909762)
		(end 333.055214 -33.481772)
		(width 0.0889)
		(layer "F.Cu")
		(net "RST_ESPI_RESET_N")
	)
	(segment
		(start 334.39862 -37.8079)
		(end 334.399128 -37.807392)
		(width 0.0889)
		(layer "F.Cu")
		(net "RST_ESPI_RESET_N")
	)
	(segment
		(start 332.301596 -25.911556)
		(end 332.301596 -26.457148)
		(width 0.12954)
		(layer "F.Cu")
		(net "RST_ESPI_RESET_N")
	)
	(segment
		(start 332.896718 -29.15031)
		(end 333.345536 -29.599128)
		(width 0.12954)
		(layer "F.Cu")
		(net "RST_ESPI_RESET_N")
	)
	(segment
		(start 332.446884 -25.766268)
		(end 332.301596 -25.911556)
		(width 0.12954)
		(layer "F.Cu")
		(net "RST_ESPI_RESET_N")
	)
	(segment
		(start 334.41894 -37.168328)
		(end 334.41894 -34.201608)
		(width 0.0889)
		(layer "F.Cu")
		(net "RST_ESPI_RESET_N")
	)
	(segment
		(start 334.127094 -33.909762)
		(end 333.483204 -33.909762)
		(width 0.0889)
		(layer "F.Cu")
		(net "RST_ESPI_RESET_N")
	)
	(via
		(at 332.301596 -26.457148)
		(size 0.508)
		(drill 0.254)
		(layers "F.Cu" "B.Cu")
		(net "RST_ESPI_RESET_N")
	)
	(via
		(at 333.055214 -31.808928)
		(size 0.762)
		(drill 0.381)
		(layers "F.Cu" "B.Cu")
		(net "RST_ESPI_RESET_N")
	)
	(segment
		(start 183.755538 -107.375452)
		(end 184.155588 -106.975402)
		(width 0.12954)
		(layer "F.Cu")
		(net "RST_CPU1_LVC1_R_N")
	)
	(via
		(at 187.62218 -106.040428)
		(size 0.6604)
		(drill 0.3302)
		(layers "F.Cu" "B.Cu")
		(net "RST_CPU1_LVC1_R_N")
	)
	(via
		(at 184.155588 -106.975402)
		(size 0.4572)
		(drill 0.254)
		(layers "F.Cu" "B.Cu")
		(net "RST_CPU1_LVC1_R_N")
	)
	(segment
		(start 188.68136 -105.816908)
		(end 188.45784 -106.040428)
		(width 0.12954)
		(layer "B.Cu")
		(net "RST_CPU1_LVC1_R_N")
	)
	(segment
		(start 188.86551 -104.823768)
		(end 188.68136 -105.007918)
		(width 0.12954)
		(layer "B.Cu")
		(net "RST_CPU1_LVC1_R_N")
	)
	(segment
		(start 190.037212 -103.630476)
		(end 190.037212 -103.652066)
		(width 0.12954)
		(layer "B.Cu")
		(net "RST_CPU1_LVC1_R_N")
	)
	(segment
		(start 188.68136 -105.007918)
		(end 188.68136 -105.816908)
		(width 0.12954)
		(layer "B.Cu")
		(net "RST_CPU1_LVC1_R_N")
	)
	(segment
		(start 188.45784 -106.040428)
		(end 187.62218 -106.040428)
		(width 0.12954)
		(layer "B.Cu")
		(net "RST_CPU1_LVC1_R_N")
	)
	(segment
		(start 187.62218 -106.040428)
		(end 187.08624 -106.576368)
		(width 0.12954)
		(layer "B.Cu")
		(net "RST_CPU1_LVC1_R_N")
	)
	(segment
		(start 190.037212 -103.652066)
		(end 188.86551 -104.823768)
		(width 0.12954)
		(layer "B.Cu")
		(net "RST_CPU1_LVC1_R_N")
	)
	(segment
		(start 187.08624 -106.576368)
		(end 184.554622 -106.576368)
		(width 0.12954)
		(layer "B.Cu")
		(net "RST_CPU1_LVC1_R_N")
	)
	(segment
		(start 184.554622 -106.576368)
		(end 184.155588 -106.975402)
		(width 0.12954)
		(layer "B.Cu")
		(net "RST_CPU1_LVC1_R_N")
	)
	(segment
		(start 107.051094 -264.778236)
		(end 107.051348 -264.77849)
		(width 0.12954)
		(layer "F.Cu")
		(net "RST_CPU1_LVC1_N")
	)
	(segment
		(start 107.051348 -264.77849)
		(end 107.051348 -265.314176)
		(width 0.12954)
		(layer "F.Cu")
		(net "RST_CPU1_LVC1_N")
	)
	(via
		(at 107.051348 -265.314176)
		(size 0.4572)
		(drill 0.2032)
		(layers "F.Cu" "B.Cu")
		(net "RST_CPU1_LVC1_N")
	)
	(via
		(at 80.469232 -262.472678)
		(size 0.6604)
		(drill 0.3302)
		(layers "F.Cu" "B.Cu")
		(net "RST_CPU1_LVC1_N")
	)
	(segment
		(start 87.990426 -262.472424)
		(end 82.025998 -262.472424)
		(width 0.12954)
		(layer "B.Cu")
		(net "RST_CPU1_LVC1_N")
	)
	(segment
		(start 88.255094 -262.433562)
		(end 88.029288 -262.433562)
		(width 0.0889)
		(layer "B.Cu")
		(net "RST_CPU1_LVC1_N")
	)
	(segment
		(start 95.035878 -262.37438)
		(end 95.021146 -262.383016)
		(width 0.0889)
		(layer "B.Cu")
		(net "RST_CPU1_LVC1_N")
	)
	(segment
		(start 103.948992 -264.167366)
		(end 103.590598 -263.808972)
		(width 0.0889)
		(layer "B.Cu")
		(net "RST_CPU1_LVC1_N")
	)
	(segment
		(start 99.734878 -262.37438)
		(end 99.720146 -262.383016)
		(width 0.0889)
		(layer "B.Cu")
		(net "RST_CPU1_LVC1_N")
	)
	(segment
		(start 105.373678 -264.998454)
		(end 105.358946 -264.989818)
		(width 0.0889)
		(layer "B.Cu")
		(net "RST_CPU1_LVC1_N")
	)
	(segment
		(start 91.272106 -262.37692)
		(end 91.261692 -262.383016)
		(width 0.0889)
		(layer "B.Cu")
		(net "RST_CPU1_LVC1_N")
	)
	(segment
		(start 80.469232 -262.472678)
		(end 78.867 -262.472678)
		(width 0.12954)
		(layer "B.Cu")
		(net "RST_CPU1_LVC1_N")
	)
	(segment
		(start 100.674678 -262.37438)
		(end 100.659946 -262.383016)
		(width 0.0889)
		(layer "B.Cu")
		(net "RST_CPU1_LVC1_N")
	)
	(segment
		(start 78.867 -262.472678)
		(end 72.989186 -256.594864)
		(width 0.12954)
		(layer "B.Cu")
		(net "RST_CPU1_LVC1_N")
	)
	(segment
		(start 103.590598 -263.808972)
		(end 103.590598 -263.781286)
		(width 0.0889)
		(layer "B.Cu")
		(net "RST_CPU1_LVC1_N")
	)
	(segment
		(start 72.989186 -256.594864)
		(end 72.989186 -247.434608)
		(width 0.12954)
		(layer "B.Cu")
		(net "RST_CPU1_LVC1_N")
	)
	(segment
		(start 101.614478 -262.37438)
		(end 101.599746 -262.383016)
		(width 0.0889)
		(layer "B.Cu")
		(net "RST_CPU1_LVC1_N")
	)
	(segment
		(start 72.989186 -247.434608)
		(end 68.90004 -243.345462)
		(width 0.12954)
		(layer "B.Cu")
		(net "RST_CPU1_LVC1_N")
	)
	(segment
		(start 103.957882 -264.181082)
		(end 103.948992 -264.176002)
		(width 0.0889)
		(layer "B.Cu")
		(net "RST_CPU1_LVC1_N")
	)
	(segment
		(start 107.051348 -265.314176)
		(end 106.327956 -265.006836)
		(width 0.0889)
		(layer "B.Cu")
		(net "RST_CPU1_LVC1_N")
	)
	(segment
		(start 95.975678 -262.37438)
		(end 95.960946 -262.383016)
		(width 0.0889)
		(layer "B.Cu")
		(net "RST_CPU1_LVC1_N")
	)
	(segment
		(start 89.39276 -262.37692)
		(end 89.382346 -262.383016)
		(width 0.0889)
		(layer "B.Cu")
		(net "RST_CPU1_LVC1_N")
	)
	(segment
		(start 88.029288 -262.433562)
		(end 87.990426 -262.472424)
		(width 0.0889)
		(layer "B.Cu")
		(net "RST_CPU1_LVC1_N")
	)
	(segment
		(start 82.025998 -262.472424)
		(end 82.025744 -262.472678)
		(width 0.12954)
		(layer "B.Cu")
		(net "RST_CPU1_LVC1_N")
	)
	(segment
		(start 104.419146 -264.989818)
		(end 104.419146 -264.989564)
		(width 0.0889)
		(layer "B.Cu")
		(net "RST_CPU1_LVC1_N")
	)
	(segment
		(start 104.433878 -264.998454)
		(end 104.419146 -264.989818)
		(width 0.0889)
		(layer "B.Cu")
		(net "RST_CPU1_LVC1_N")
	)
	(segment
		(start 90.887296 -262.383016)
		(end 90.872564 -262.37438)
		(width 0.0889)
		(layer "B.Cu")
		(net "RST_CPU1_LVC1_N")
	)
	(segment
		(start 68.90004 -243.345462)
		(end 66.507614 -243.345462)
		(width 0.12954)
		(layer "B.Cu")
		(net "RST_CPU1_LVC1_N")
	)
	(segment
		(start 97.465896 -262.383016)
		(end 97.455482 -262.37692)
		(width 0.0889)
		(layer "B.Cu")
		(net "RST_CPU1_LVC1_N")
	)
	(segment
		(start 103.590598 -263.781286)
		(end 102.28199 -262.472678)
		(width 0.0889)
		(layer "B.Cu")
		(net "RST_CPU1_LVC1_N")
	)
	(segment
		(start 94.096078 -262.37438)
		(end 94.081346 -262.383016)
		(width 0.0889)
		(layer "B.Cu")
		(net "RST_CPU1_LVC1_N")
	)
	(segment
		(start 97.850706 -262.37692)
		(end 97.840292 -262.383016)
		(width 0.0889)
		(layer "B.Cu")
		(net "RST_CPU1_LVC1_N")
	)
	(segment
		(start 104.419146 -264.989564)
		(end 104.3559 -264.953242)
		(width 0.0889)
		(layer "B.Cu")
		(net "RST_CPU1_LVC1_N")
	)
	(segment
		(start 82.025744 -262.472678)
		(end 80.469232 -262.472678)
		(width 0.12954)
		(layer "B.Cu")
		(net "RST_CPU1_LVC1_N")
	)
	(segment
		(start 103.948992 -264.176002)
		(end 103.948992 -264.167366)
		(width 0.0889)
		(layer "B.Cu")
		(net "RST_CPU1_LVC1_N")
	)
	(segment
		(start 98.795078 -262.37438)
		(end 98.780346 -262.383016)
		(width 0.0889)
		(layer "B.Cu")
		(net "RST_CPU1_LVC1_N")
	)
	(segment
		(start 92.216478 -262.37438)
		(end 92.201746 -262.383016)
		(width 0.0889)
		(layer "B.Cu")
		(net "RST_CPU1_LVC1_N")
	)
	(segment
		(start 93.156278 -262.37438)
		(end 93.141546 -262.383016)
		(width 0.0889)
		(layer "B.Cu")
		(net "RST_CPU1_LVC1_N")
	)
	(segment
		(start 106.327956 -265.006836)
		(end 106.298746 -264.989818)
		(width 0.0889)
		(layer "B.Cu")
		(net "RST_CPU1_LVC1_N")
	)
	(segment
		(start 104.136444 -264.573258)
		(end 104.136444 -264.50036)
		(width 0.0889)
		(layer "B.Cu")
		(net "RST_CPU1_LVC1_N")
	)
	(arc
		(start 97.840292 -262.383016)
		(mid 97.653094 -262.433159)
		(end 97.465896 -262.383016)
		(width 0.0889)
		(layer "B.Cu")
		(net "RST_CPU1_LVC1_N")
	)
	(arc
		(start 98.780346 -262.383016)
		(mid 98.593148 -262.433159)
		(end 98.40595 -262.383016)
		(width 0.0889)
		(layer "B.Cu")
		(net "RST_CPU1_LVC1_N")
	)
	(arc
		(start 100.659946 -262.383016)
		(mid 100.472748 -262.433159)
		(end 100.28555 -262.383016)
		(width 0.0889)
		(layer "B.Cu")
		(net "RST_CPU1_LVC1_N")
	)
	(arc
		(start 104.98455 -264.989818)
		(mid 104.710351 -265.065653)
		(end 104.433878 -264.998454)
		(width 0.0889)
		(layer "B.Cu")
		(net "RST_CPU1_LVC1_N")
	)
	(arc
		(start 88.452706 -262.37692)
		(mid 88.357862 -262.419071)
		(end 88.255094 -262.433562)
		(width 0.0889)
		(layer "B.Cu")
		(net "RST_CPU1_LVC1_N")
	)
	(arc
		(start 97.455482 -262.37692)
		(mid 97.177304 -262.307197)
		(end 96.900746 -262.383016)
		(width 0.0889)
		(layer "B.Cu")
		(net "RST_CPU1_LVC1_N")
	)
	(arc
		(start 98.40595 -262.383016)
		(mid 98.129137 -262.307146)
		(end 97.850706 -262.37692)
		(width 0.0889)
		(layer "B.Cu")
		(net "RST_CPU1_LVC1_N")
	)
	(arc
		(start 95.960946 -262.383016)
		(mid 95.773748 -262.433159)
		(end 95.58655 -262.383016)
		(width 0.0889)
		(layer "B.Cu")
		(net "RST_CPU1_LVC1_N")
	)
	(arc
		(start 91.261692 -262.383016)
		(mid 91.074494 -262.433159)
		(end 90.887296 -262.383016)
		(width 0.0889)
		(layer "B.Cu")
		(net "RST_CPU1_LVC1_N")
	)
	(arc
		(start 99.34575 -262.383016)
		(mid 99.071551 -262.307181)
		(end 98.795078 -262.37438)
		(width 0.0889)
		(layer "B.Cu")
		(net "RST_CPU1_LVC1_N")
	)
	(arc
		(start 93.70695 -262.383016)
		(mid 93.432751 -262.307181)
		(end 93.156278 -262.37438)
		(width 0.0889)
		(layer "B.Cu")
		(net "RST_CPU1_LVC1_N")
	)
	(arc
		(start 95.021146 -262.383016)
		(mid 94.833948 -262.433159)
		(end 94.64675 -262.383016)
		(width 0.0889)
		(layer "B.Cu")
		(net "RST_CPU1_LVC1_N")
	)
	(arc
		(start 95.58655 -262.383016)
		(mid 95.312351 -262.307181)
		(end 95.035878 -262.37438)
		(width 0.0889)
		(layer "B.Cu")
		(net "RST_CPU1_LVC1_N")
	)
	(arc
		(start 89.382346 -262.383016)
		(mid 89.195148 -262.433159)
		(end 89.00795 -262.383016)
		(width 0.0889)
		(layer "B.Cu")
		(net "RST_CPU1_LVC1_N")
	)
	(arc
		(start 100.28555 -262.383016)
		(mid 100.011351 -262.307181)
		(end 99.734878 -262.37438)
		(width 0.0889)
		(layer "B.Cu")
		(net "RST_CPU1_LVC1_N")
	)
	(arc
		(start 94.081346 -262.383016)
		(mid 93.894148 -262.433159)
		(end 93.70695 -262.383016)
		(width 0.0889)
		(layer "B.Cu")
		(net "RST_CPU1_LVC1_N")
	)
	(arc
		(start 96.900746 -262.383016)
		(mid 96.713548 -262.433159)
		(end 96.52635 -262.383016)
		(width 0.0889)
		(layer "B.Cu")
		(net "RST_CPU1_LVC1_N")
	)
	(arc
		(start 96.52635 -262.383016)
		(mid 96.252151 -262.307181)
		(end 95.975678 -262.37438)
		(width 0.0889)
		(layer "B.Cu")
		(net "RST_CPU1_LVC1_N")
	)
	(arc
		(start 105.92435 -264.989818)
		(mid 105.650151 -265.065653)
		(end 105.373678 -264.998454)
		(width 0.0889)
		(layer "B.Cu")
		(net "RST_CPU1_LVC1_N")
	)
	(arc
		(start 89.00795 -262.383016)
		(mid 88.731137 -262.307146)
		(end 88.452706 -262.37692)
		(width 0.0889)
		(layer "B.Cu")
		(net "RST_CPU1_LVC1_N")
	)
	(arc
		(start 106.298746 -264.989818)
		(mid 106.111548 -264.939675)
		(end 105.92435 -264.989818)
		(width 0.0889)
		(layer "B.Cu")
		(net "RST_CPU1_LVC1_N")
	)
	(arc
		(start 89.947496 -262.383016)
		(mid 89.670937 -262.307273)
		(end 89.39276 -262.37692)
		(width 0.0889)
		(layer "B.Cu")
		(net "RST_CPU1_LVC1_N")
	)
	(arc
		(start 104.136444 -264.50036)
		(mid 104.088765 -264.31746)
		(end 103.957882 -264.181082)
		(width 0.0889)
		(layer "B.Cu")
		(net "RST_CPU1_LVC1_N")
	)
	(arc
		(start 102.28199 -262.472678)
		(mid 101.96451 -262.313101)
		(end 101.614478 -262.37438)
		(width 0.0889)
		(layer "B.Cu")
		(net "RST_CPU1_LVC1_N")
	)
	(arc
		(start 99.720146 -262.383016)
		(mid 99.532948 -262.433159)
		(end 99.34575 -262.383016)
		(width 0.0889)
		(layer "B.Cu")
		(net "RST_CPU1_LVC1_N")
	)
	(arc
		(start 92.201746 -262.383016)
		(mid 92.014548 -262.433159)
		(end 91.82735 -262.383016)
		(width 0.0889)
		(layer "B.Cu")
		(net "RST_CPU1_LVC1_N")
	)
	(arc
		(start 94.64675 -262.383016)
		(mid 94.372551 -262.307181)
		(end 94.096078 -262.37438)
		(width 0.0889)
		(layer "B.Cu")
		(net "RST_CPU1_LVC1_N")
	)
	(arc
		(start 101.599746 -262.383016)
		(mid 101.412548 -262.433159)
		(end 101.22535 -262.383016)
		(width 0.0889)
		(layer "B.Cu")
		(net "RST_CPU1_LVC1_N")
	)
	(arc
		(start 90.321892 -262.383016)
		(mid 90.134694 -262.433159)
		(end 89.947496 -262.383016)
		(width 0.0889)
		(layer "B.Cu")
		(net "RST_CPU1_LVC1_N")
	)
	(arc
		(start 92.76715 -262.383016)
		(mid 92.492951 -262.307181)
		(end 92.216478 -262.37438)
		(width 0.0889)
		(layer "B.Cu")
		(net "RST_CPU1_LVC1_N")
	)
	(arc
		(start 90.872564 -262.37438)
		(mid 90.596089 -262.30706)
		(end 90.321892 -262.383016)
		(width 0.0889)
		(layer "B.Cu")
		(net "RST_CPU1_LVC1_N")
	)
	(arc
		(start 104.3559 -264.953242)
		(mid 104.195236 -264.792665)
		(end 104.136444 -264.573258)
		(width 0.0889)
		(layer "B.Cu")
		(net "RST_CPU1_LVC1_N")
	)
	(arc
		(start 105.358946 -264.989818)
		(mid 105.171748 -264.939675)
		(end 104.98455 -264.989818)
		(width 0.0889)
		(layer "B.Cu")
		(net "RST_CPU1_LVC1_N")
	)
	(arc
		(start 101.22535 -262.383016)
		(mid 100.951151 -262.307181)
		(end 100.674678 -262.37438)
		(width 0.0889)
		(layer "B.Cu")
		(net "RST_CPU1_LVC1_N")
	)
	(arc
		(start 91.82735 -262.383016)
		(mid 91.550537 -262.307146)
		(end 91.272106 -262.37692)
		(width 0.0889)
		(layer "B.Cu")
		(net "RST_CPU1_LVC1_N")
	)
	(arc
		(start 93.141546 -262.383016)
		(mid 92.954348 -262.433159)
		(end 92.76715 -262.383016)
		(width 0.0889)
		(layer "B.Cu")
		(net "RST_CPU1_LVC1_N")
	)
	(segment
		(start 126.534926 -119.410734)
		(end 126.534926 -118.032784)
		(width 0.12954)
		(layer "F.Cu")
		(net "RST_CPU1_DRAM_GH_PLD_N")
	)
	(segment
		(start 125.269752 -116.76761)
		(end 125.269752 -116.042948)
		(width 0.12954)
		(layer "F.Cu")
		(net "RST_CPU1_DRAM_GH_PLD_N")
	)
	(segment
		(start 126.534926 -118.032784)
		(end 125.269752 -116.76761)
		(width 0.12954)
		(layer "F.Cu")
		(net "RST_CPU1_DRAM_GH_PLD_N")
	)
	(via
		(at 126.534926 -118.032784)
		(size 0.762)
		(drill 0.381)
		(layers "F.Cu" "B.Cu")
		(net "RST_CPU1_DRAM_GH_PLD_N")
	)
	(segment
		(start 122.087894 -259.894832)
		(end 122.088148 -259.895086)
		(width 0.12954)
		(layer "F.Cu")
		(net "RST_CPU1_DRAM_GH_N")
	)
	(segment
		(start 126.534926 -120.210834)
		(end 126.534926 -120.953784)
		(width 0.12954)
		(layer "F.Cu")
		(net "RST_CPU1_DRAM_GH_N")
	)
	(segment
		(start 122.088148 -259.895086)
		(end 122.088148 -260.430772)
		(width 0.12954)
		(layer "F.Cu")
		(net "RST_CPU1_DRAM_GH_N")
	)
	(segment
		(start 126.534926 -120.953784)
		(end 126.534926 -121.696734)
		(width 0.12954)
		(layer "F.Cu")
		(net "RST_CPU1_DRAM_GH_N")
	)
	(via
		(at 173.598078 -189.27445)
		(size 0.508)
		(drill 0.254)
		(layers "F.Cu" "B.Cu")
		(net "RST_CPU1_DRAM_GH_N")
	)
	(via
		(at 142.9258 -259.705856)
		(size 0.6604)
		(drill 0.3302)
		(layers "F.Cu" "B.Cu")
		(net "RST_CPU1_DRAM_GH_N")
	)
	(via
		(at 126.534926 -120.953784)
		(size 0.508)
		(drill 0.254)
		(layers "F.Cu" "B.Cu")
		(net "RST_CPU1_DRAM_GH_N")
	)
	(via
		(at 122.088148 -260.430772)
		(size 0.4572)
		(drill 0.2032)
		(layers "F.Cu" "B.Cu")
		(net "RST_CPU1_DRAM_GH_N")
	)
	(segment
		(start 125.612144 -260.023864)
		(end 125.598682 -260.031738)
		(width 0.12954)
		(layer "B.Cu")
		(net "RST_CPU1_DRAM_GH_N")
	)
	(segment
		(start 156.963364 -247.06961)
		(end 144.327118 -259.705856)
		(width 0.12954)
		(layer "B.Cu")
		(net "RST_CPU1_DRAM_GH_N")
	)
	(segment
		(start 173.598078 -189.27445)
		(end 173.598078 -194.097656)
		(width 0.12954)
		(layer "B.Cu")
		(net "RST_CPU1_DRAM_GH_N")
	)
	(segment
		(start 135.010144 -260.023864)
		(end 134.996682 -260.031738)
		(width 0.12954)
		(layer "B.Cu")
		(net "RST_CPU1_DRAM_GH_N")
	)
	(segment
		(start 137.881614 -260.011926)
		(end 135.550656 -260.011926)
		(width 0.12954)
		(layer "B.Cu")
		(net "RST_CPU1_DRAM_GH_N")
	)
	(segment
		(start 123.732544 -260.023864)
		(end 123.719082 -260.031738)
		(width 0.12954)
		(layer "B.Cu")
		(net "RST_CPU1_DRAM_GH_N")
	)
	(segment
		(start 132.190744 -260.023864)
		(end 132.177282 -260.031738)
		(width 0.12954)
		(layer "B.Cu")
		(net "RST_CPU1_DRAM_GH_N")
	)
	(segment
		(start 130.311144 -260.023864)
		(end 130.297682 -260.031738)
		(width 0.12954)
		(layer "B.Cu")
		(net "RST_CPU1_DRAM_GH_N")
	)
	(segment
		(start 128.431544 -260.023864)
		(end 128.418082 -260.031738)
		(width 0.12954)
		(layer "B.Cu")
		(net "RST_CPU1_DRAM_GH_N")
	)
	(segment
		(start 161.004758 -247.06961)
		(end 156.963364 -247.06961)
		(width 0.12954)
		(layer "B.Cu")
		(net "RST_CPU1_DRAM_GH_N")
	)
	(segment
		(start 127.491744 -260.023864)
		(end 127.478282 -260.031738)
		(width 0.12954)
		(layer "B.Cu")
		(net "RST_CPU1_DRAM_GH_N")
	)
	(segment
		(start 173.598078 -194.097656)
		(end 173.285658 -194.410076)
		(width 0.12954)
		(layer "B.Cu")
		(net "RST_CPU1_DRAM_GH_N")
	)
	(segment
		(start 134.070344 -260.023864)
		(end 134.056882 -260.031738)
		(width 0.12954)
		(layer "B.Cu")
		(net "RST_CPU1_DRAM_GH_N")
	)
	(segment
		(start 172.340778 -247.98147)
		(end 171.952158 -248.37009)
		(width 0.12954)
		(layer "B.Cu")
		(net "RST_CPU1_DRAM_GH_N")
	)
	(segment
		(start 172.340778 -196.34327)
		(end 172.340778 -247.98147)
		(width 0.12954)
		(layer "B.Cu")
		(net "RST_CPU1_DRAM_GH_N")
	)
	(segment
		(start 168.466516 -248.98731)
		(end 166.699438 -248.98731)
		(width 0.12954)
		(layer "B.Cu")
		(net "RST_CPU1_DRAM_GH_N")
	)
	(segment
		(start 133.130544 -260.023864)
		(end 133.117082 -260.031738)
		(width 0.12954)
		(layer "B.Cu")
		(net "RST_CPU1_DRAM_GH_N")
	)
	(segment
		(start 169.083736 -248.37009)
		(end 168.466516 -248.98731)
		(width 0.12954)
		(layer "B.Cu")
		(net "RST_CPU1_DRAM_GH_N")
	)
	(segment
		(start 173.285658 -194.410076)
		(end 173.285658 -195.85051)
		(width 0.12954)
		(layer "B.Cu")
		(net "RST_CPU1_DRAM_GH_N")
	)
	(segment
		(start 131.250944 -260.023864)
		(end 131.237482 -260.031738)
		(width 0.12954)
		(layer "B.Cu")
		(net "RST_CPU1_DRAM_GH_N")
	)
	(segment
		(start 144.327118 -259.705856)
		(end 142.9258 -259.705856)
		(width 0.12954)
		(layer "B.Cu")
		(net "RST_CPU1_DRAM_GH_N")
	)
	(segment
		(start 173.069758 -196.06641)
		(end 172.617638 -196.06641)
		(width 0.12954)
		(layer "B.Cu")
		(net "RST_CPU1_DRAM_GH_N")
	)
	(segment
		(start 126.551944 -260.023864)
		(end 126.538482 -260.031738)
		(width 0.12954)
		(layer "B.Cu")
		(net "RST_CPU1_DRAM_GH_N")
	)
	(segment
		(start 171.952158 -248.37009)
		(end 169.083736 -248.37009)
		(width 0.12954)
		(layer "B.Cu")
		(net "RST_CPU1_DRAM_GH_N")
	)
	(segment
		(start 124.672344 -260.023864)
		(end 124.658882 -260.031738)
		(width 0.12954)
		(layer "B.Cu")
		(net "RST_CPU1_DRAM_GH_N")
	)
	(segment
		(start 172.617638 -196.06641)
		(end 172.340778 -196.34327)
		(width 0.12954)
		(layer "B.Cu")
		(net "RST_CPU1_DRAM_GH_N")
	)
	(segment
		(start 166.699438 -248.98731)
		(end 164.672518 -246.96039)
		(width 0.12954)
		(layer "B.Cu")
		(net "RST_CPU1_DRAM_GH_N")
	)
	(segment
		(start 164.672518 -246.96039)
		(end 161.113978 -246.96039)
		(width 0.12954)
		(layer "B.Cu")
		(net "RST_CPU1_DRAM_GH_N")
	)
	(segment
		(start 173.285658 -195.85051)
		(end 173.069758 -196.06641)
		(width 0.12954)
		(layer "B.Cu")
		(net "RST_CPU1_DRAM_GH_N")
	)
	(segment
		(start 138.187684 -259.705856)
		(end 137.881614 -260.011926)
		(width 0.12954)
		(layer "B.Cu")
		(net "RST_CPU1_DRAM_GH_N")
	)
	(segment
		(start 161.113978 -246.96039)
		(end 161.004758 -247.06961)
		(width 0.12954)
		(layer "B.Cu")
		(net "RST_CPU1_DRAM_GH_N")
	)
	(segment
		(start 142.9258 -259.705856)
		(end 138.187684 -259.705856)
		(width 0.12954)
		(layer "B.Cu")
		(net "RST_CPU1_DRAM_GH_N")
	)
	(segment
		(start 129.371344 -260.023864)
		(end 129.357882 -260.031738)
		(width 0.12954)
		(layer "B.Cu")
		(net "RST_CPU1_DRAM_GH_N")
	)
	(arc
		(start 128.901444 -260.023864)
		(mid 128.666494 -259.960904)
		(end 128.431544 -260.023864)
		(width 0.12954)
		(layer "B.Cu")
		(net "RST_CPU1_DRAM_GH_N")
	)
	(arc
		(start 131.237482 -260.031738)
		(mid 131.008229 -260.086982)
		(end 130.781044 -260.023864)
		(width 0.12954)
		(layer "B.Cu")
		(net "RST_CPU1_DRAM_GH_N")
	)
	(arc
		(start 126.538482 -260.031738)
		(mid 126.309229 -260.086982)
		(end 126.082044 -260.023864)
		(width 0.12954)
		(layer "B.Cu")
		(net "RST_CPU1_DRAM_GH_N")
	)
	(arc
		(start 125.598682 -260.031738)
		(mid 125.369429 -260.086982)
		(end 125.142244 -260.023864)
		(width 0.12954)
		(layer "B.Cu")
		(net "RST_CPU1_DRAM_GH_N")
	)
	(arc
		(start 132.177282 -260.031738)
		(mid 131.948029 -260.086982)
		(end 131.720844 -260.023864)
		(width 0.12954)
		(layer "B.Cu")
		(net "RST_CPU1_DRAM_GH_N")
	)
	(arc
		(start 133.117082 -260.031738)
		(mid 132.887829 -260.086982)
		(end 132.660644 -260.023864)
		(width 0.12954)
		(layer "B.Cu")
		(net "RST_CPU1_DRAM_GH_N")
	)
	(arc
		(start 128.418082 -260.031738)
		(mid 128.188829 -260.086982)
		(end 127.961644 -260.023864)
		(width 0.12954)
		(layer "B.Cu")
		(net "RST_CPU1_DRAM_GH_N")
	)
	(arc
		(start 127.021844 -260.023864)
		(mid 126.786894 -259.960904)
		(end 126.551944 -260.023864)
		(width 0.12954)
		(layer "B.Cu")
		(net "RST_CPU1_DRAM_GH_N")
	)
	(arc
		(start 123.719082 -260.031738)
		(mid 123.489829 -260.086982)
		(end 123.262644 -260.023864)
		(width 0.12954)
		(layer "B.Cu")
		(net "RST_CPU1_DRAM_GH_N")
	)
	(arc
		(start 134.996682 -260.031738)
		(mid 134.767429 -260.086982)
		(end 134.540244 -260.023864)
		(width 0.12954)
		(layer "B.Cu")
		(net "RST_CPU1_DRAM_GH_N")
	)
	(arc
		(start 130.781044 -260.023864)
		(mid 130.546094 -259.960904)
		(end 130.311144 -260.023864)
		(width 0.12954)
		(layer "B.Cu")
		(net "RST_CPU1_DRAM_GH_N")
	)
	(arc
		(start 124.658882 -260.031738)
		(mid 124.429629 -260.086982)
		(end 124.202444 -260.023864)
		(width 0.12954)
		(layer "B.Cu")
		(net "RST_CPU1_DRAM_GH_N")
	)
	(arc
		(start 130.297682 -260.031738)
		(mid 130.068429 -260.086982)
		(end 129.841244 -260.023864)
		(width 0.12954)
		(layer "B.Cu")
		(net "RST_CPU1_DRAM_GH_N")
	)
	(arc
		(start 123.262644 -260.023864)
		(mid 122.986757 -259.971034)
		(end 122.737626 -260.100826)
		(width 0.12954)
		(layer "B.Cu")
		(net "RST_CPU1_DRAM_GH_N")
	)
	(arc
		(start 134.056882 -260.031738)
		(mid 133.827629 -260.086982)
		(end 133.600444 -260.023864)
		(width 0.12954)
		(layer "B.Cu")
		(net "RST_CPU1_DRAM_GH_N")
	)
	(arc
		(start 129.357882 -260.031738)
		(mid 129.128629 -260.086982)
		(end 128.901444 -260.023864)
		(width 0.12954)
		(layer "B.Cu")
		(net "RST_CPU1_DRAM_GH_N")
	)
	(arc
		(start 135.398002 -259.986272)
		(mid 135.199995 -259.962983)
		(end 135.010144 -260.023864)
		(width 0.12954)
		(layer "B.Cu")
		(net "RST_CPU1_DRAM_GH_N")
	)
	(arc
		(start 134.540244 -260.023864)
		(mid 134.305294 -259.960904)
		(end 134.070344 -260.023864)
		(width 0.12954)
		(layer "B.Cu")
		(net "RST_CPU1_DRAM_GH_N")
	)
	(arc
		(start 125.142244 -260.023864)
		(mid 124.907294 -259.960904)
		(end 124.672344 -260.023864)
		(width 0.12954)
		(layer "B.Cu")
		(net "RST_CPU1_DRAM_GH_N")
	)
	(arc
		(start 131.720844 -260.023864)
		(mid 131.485894 -259.960904)
		(end 131.250944 -260.023864)
		(width 0.12954)
		(layer "B.Cu")
		(net "RST_CPU1_DRAM_GH_N")
	)
	(arc
		(start 129.841244 -260.023864)
		(mid 129.606294 -259.960904)
		(end 129.371344 -260.023864)
		(width 0.12954)
		(layer "B.Cu")
		(net "RST_CPU1_DRAM_GH_N")
	)
	(arc
		(start 122.737626 -260.100826)
		(mid 122.441651 -260.322427)
		(end 122.088148 -260.430772)
		(width 0.12954)
		(layer "B.Cu")
		(net "RST_CPU1_DRAM_GH_N")
	)
	(arc
		(start 132.660644 -260.023864)
		(mid 132.425694 -259.960904)
		(end 132.190744 -260.023864)
		(width 0.12954)
		(layer "B.Cu")
		(net "RST_CPU1_DRAM_GH_N")
	)
	(arc
		(start 127.961644 -260.023864)
		(mid 127.726694 -259.960904)
		(end 127.491744 -260.023864)
		(width 0.12954)
		(layer "B.Cu")
		(net "RST_CPU1_DRAM_GH_N")
	)
	(arc
		(start 127.478282 -260.031738)
		(mid 127.249029 -260.086982)
		(end 127.021844 -260.023864)
		(width 0.12954)
		(layer "B.Cu")
		(net "RST_CPU1_DRAM_GH_N")
	)
	(arc
		(start 126.082044 -260.023864)
		(mid 125.847094 -259.960904)
		(end 125.612144 -260.023864)
		(width 0.12954)
		(layer "B.Cu")
		(net "RST_CPU1_DRAM_GH_N")
	)
	(arc
		(start 124.202444 -260.023864)
		(mid 123.967494 -259.960904)
		(end 123.732544 -260.023864)
		(width 0.12954)
		(layer "B.Cu")
		(net "RST_CPU1_DRAM_GH_N")
	)
	(arc
		(start 133.600444 -260.023864)
		(mid 133.365494 -259.960904)
		(end 133.130544 -260.023864)
		(width 0.12954)
		(layer "B.Cu")
		(net "RST_CPU1_DRAM_GH_N")
	)
	(arc
		(start 135.550656 -260.011926)
		(mid 135.473266 -260.005425)
		(end 135.398002 -259.986272)
		(width 0.12954)
		(layer "B.Cu")
		(net "RST_CPU1_DRAM_GH_N")
	)
	(segment
		(start 126.843282 -124.912628)
		(end 127.0889 -124.66701)
		(width 0.127)
		(layer "In2.Cu")
		(net "RST_CPU1_DRAM_GH_N")
	)
	(segment
		(start 124.31014 -167.305228)
		(end 124.31014 -151.343614)
		(width 0.127)
		(layer "In2.Cu")
		(net "RST_CPU1_DRAM_GH_N")
	)
	(segment
		(start 161.73958 -191.856868)
		(end 161.26206 -191.379348)
		(width 0.127)
		(layer "In2.Cu")
		(net "RST_CPU1_DRAM_GH_N")
	)
	(segment
		(start 161.26206 -191.379348)
		(end 159.87522 -191.379348)
		(width 0.127)
		(layer "In2.Cu")
		(net "RST_CPU1_DRAM_GH_N")
	)
	(segment
		(start 127.0889 -124.66701)
		(end 127.0889 -121.595388)
		(width 0.127)
		(layer "In2.Cu")
		(net "RST_CPU1_DRAM_GH_N")
	)
	(segment
		(start 124.31014 -151.343614)
		(end 126.843282 -148.810472)
		(width 0.127)
		(layer "In2.Cu")
		(net "RST_CPU1_DRAM_GH_N")
	)
	(segment
		(start 127.0889 -121.595388)
		(end 126.534926 -121.041414)
		(width 0.127)
		(layer "In2.Cu")
		(net "RST_CPU1_DRAM_GH_N")
	)
	(segment
		(start 171.90974 -191.856868)
		(end 161.73958 -191.856868)
		(width 0.127)
		(layer "In2.Cu")
		(net "RST_CPU1_DRAM_GH_N")
	)
	(segment
		(start 126.534926 -121.041414)
		(end 126.534926 -120.953784)
		(width 0.127)
		(layer "In2.Cu")
		(net "RST_CPU1_DRAM_GH_N")
	)
	(segment
		(start 173.598078 -189.27445)
		(end 173.598078 -190.16853)
		(width 0.127)
		(layer "In2.Cu")
		(net "RST_CPU1_DRAM_GH_N")
	)
	(segment
		(start 159.61106 -191.643508)
		(end 148.64842 -191.643508)
		(width 0.127)
		(layer "In2.Cu")
		(net "RST_CPU1_DRAM_GH_N")
	)
	(segment
		(start 148.64842 -191.643508)
		(end 124.31014 -167.305228)
		(width 0.127)
		(layer "In2.Cu")
		(net "RST_CPU1_DRAM_GH_N")
	)
	(segment
		(start 126.843282 -148.810472)
		(end 126.843282 -124.912628)
		(width 0.127)
		(layer "In2.Cu")
		(net "RST_CPU1_DRAM_GH_N")
	)
	(segment
		(start 159.87522 -191.379348)
		(end 159.61106 -191.643508)
		(width 0.127)
		(layer "In2.Cu")
		(net "RST_CPU1_DRAM_GH_N")
	)
	(segment
		(start 173.598078 -190.16853)
		(end 171.90974 -191.856868)
		(width 0.127)
		(layer "In2.Cu")
		(net "RST_CPU1_DRAM_GH_N")
	)
	(segment
		(start 125.264926 -119.410734)
		(end 125.264926 -118.032784)
		(width 0.12954)
		(layer "F.Cu")
		(net "RST_CPU1_DRAM_EF_PLD_N")
	)
	(segment
		(start 124.619766 -117.290088)
		(end 124.619766 -116.042948)
		(width 0.12954)
		(layer "F.Cu")
		(net "RST_CPU1_DRAM_EF_PLD_N")
	)
	(segment
		(start 125.264926 -118.032784)
		(end 125.264926 -117.935248)
		(width 0.12954)
		(layer "F.Cu")
		(net "RST_CPU1_DRAM_EF_PLD_N")
	)
	(segment
		(start 125.264926 -117.935248)
		(end 124.619766 -117.290088)
		(width 0.12954)
		(layer "F.Cu")
		(net "RST_CPU1_DRAM_EF_PLD_N")
	)
	(via
		(at 125.264926 -118.032784)
		(size 0.762)
		(drill 0.381)
		(layers "F.Cu" "B.Cu")
		(net "RST_CPU1_DRAM_EF_PLD_N")
	)
	(segment
		(start 125.264926 -120.953784)
		(end 125.264926 -121.696734)
		(width 0.12954)
		(layer "F.Cu")
		(net "RST_CPU1_DRAM_EF_N")
	)
	(segment
		(start 125.264926 -120.210834)
		(end 125.264926 -120.953784)
		(width 0.12954)
		(layer "F.Cu")
		(net "RST_CPU1_DRAM_EF_N")
	)
	(segment
		(start 121.977912 -247.714262)
		(end 121.977912 -247.178576)
		(width 0.12954)
		(layer "F.Cu")
		(net "RST_CPU1_DRAM_EF_N")
	)
	(segment
		(start 121.977912 -247.178576)
		(end 121.978166 -247.178322)
		(width 0.12954)
		(layer "F.Cu")
		(net "RST_CPU1_DRAM_EF_N")
	)
	(via
		(at 171.098718 -189.16269)
		(size 0.508)
		(drill 0.254)
		(layers "F.Cu" "B.Cu")
		(net "RST_CPU1_DRAM_EF_N")
	)
	(via
		(at 125.264926 -120.953784)
		(size 0.508)
		(drill 0.254)
		(layers "F.Cu" "B.Cu")
		(net "RST_CPU1_DRAM_EF_N")
	)
	(via
		(at 121.978166 -247.178322)
		(size 0.4572)
		(drill 0.2032)
		(layers "F.Cu" "B.Cu")
		(net "RST_CPU1_DRAM_EF_N")
	)
	(segment
		(start 132.560568 -246.777002)
		(end 132.550916 -246.771414)
		(width 0.12954)
		(layer "B.Cu")
		(net "RST_CPU1_DRAM_EF_N")
	)
	(segment
		(start 136.012174 -246.599456)
		(end 135.840216 -246.771414)
		(width 0.12954)
		(layer "B.Cu")
		(net "RST_CPU1_DRAM_EF_N")
	)
	(segment
		(start 164.370258 -238.88319)
		(end 161.243518 -238.88319)
		(width 0.12954)
		(layer "B.Cu")
		(net "RST_CPU1_DRAM_EF_N")
	)
	(segment
		(start 130.680968 -246.777002)
		(end 130.671316 -246.771414)
		(width 0.12954)
		(layer "B.Cu")
		(net "RST_CPU1_DRAM_EF_N")
	)
	(segment
		(start 166.615618 -217.54211)
		(end 166.615618 -228.04247)
		(width 0.12954)
		(layer "B.Cu")
		(net "RST_CPU1_DRAM_EF_N")
	)
	(segment
		(start 165.960298 -201.08545)
		(end 165.960298 -216.88679)
		(width 0.12954)
		(layer "B.Cu")
		(net "RST_CPU1_DRAM_EF_N")
	)
	(segment
		(start 165.909498 -237.34395)
		(end 164.370258 -238.88319)
		(width 0.12954)
		(layer "B.Cu")
		(net "RST_CPU1_DRAM_EF_N")
	)
	(segment
		(start 127.865378 -246.779288)
		(end 127.851916 -246.771414)
		(width 0.12954)
		(layer "B.Cu")
		(net "RST_CPU1_DRAM_EF_N")
	)
	(segment
		(start 125.045978 -246.779288)
		(end 125.032516 -246.771414)
		(width 0.12954)
		(layer "B.Cu")
		(net "RST_CPU1_DRAM_EF_N")
	)
	(segment
		(start 169.742358 -191.15405)
		(end 168.218612 -191.15405)
		(width 0.12954)
		(layer "B.Cu")
		(net "RST_CPU1_DRAM_EF_N")
	)
	(segment
		(start 125.981968 -246.777002)
		(end 125.972316 -246.771414)
		(width 0.12954)
		(layer "B.Cu")
		(net "RST_CPU1_DRAM_EF_N")
	)
	(segment
		(start 161.243518 -238.88319)
		(end 160.420558 -239.70615)
		(width 0.12954)
		(layer "B.Cu")
		(net "RST_CPU1_DRAM_EF_N")
	)
	(segment
		(start 160.420558 -239.70615)
		(end 154.888438 -239.70615)
		(width 0.12954)
		(layer "B.Cu")
		(net "RST_CPU1_DRAM_EF_N")
	)
	(segment
		(start 129.744978 -246.779288)
		(end 129.731516 -246.771414)
		(width 0.12954)
		(layer "B.Cu")
		(net "RST_CPU1_DRAM_EF_N")
	)
	(segment
		(start 154.888438 -239.70615)
		(end 152.968198 -241.62639)
		(width 0.12954)
		(layer "B.Cu")
		(net "RST_CPU1_DRAM_EF_N")
	)
	(segment
		(start 126.921514 -246.777002)
		(end 126.911862 -246.771414)
		(width 0.12954)
		(layer "B.Cu")
		(net "RST_CPU1_DRAM_EF_N")
	)
	(segment
		(start 140.448284 -242.840256)
		(end 136.689084 -246.599456)
		(width 0.12954)
		(layer "B.Cu")
		(net "RST_CPU1_DRAM_EF_N")
	)
	(segment
		(start 171.098718 -189.16269)
		(end 171.098718 -189.79769)
		(width 0.12954)
		(layer "B.Cu")
		(net "RST_CPU1_DRAM_EF_N")
	)
	(segment
		(start 171.098718 -189.79769)
		(end 169.742358 -191.15405)
		(width 0.12954)
		(layer "B.Cu")
		(net "RST_CPU1_DRAM_EF_N")
	)
	(segment
		(start 167.075358 -192.297304)
		(end 167.075358 -194.76593)
		(width 0.12954)
		(layer "B.Cu")
		(net "RST_CPU1_DRAM_EF_N")
	)
	(segment
		(start 123.166378 -246.779288)
		(end 123.152916 -246.771414)
		(width 0.12954)
		(layer "B.Cu")
		(net "RST_CPU1_DRAM_EF_N")
	)
	(segment
		(start 167.075358 -194.76593)
		(end 166.874698 -194.96659)
		(width 0.12954)
		(layer "B.Cu")
		(net "RST_CPU1_DRAM_EF_N")
	)
	(segment
		(start 166.874698 -200.17105)
		(end 165.960298 -201.08545)
		(width 0.12954)
		(layer "B.Cu")
		(net "RST_CPU1_DRAM_EF_N")
	)
	(segment
		(start 165.909498 -228.74859)
		(end 165.909498 -237.34395)
		(width 0.12954)
		(layer "B.Cu")
		(net "RST_CPU1_DRAM_EF_N")
	)
	(segment
		(start 166.874698 -194.96659)
		(end 166.874698 -200.17105)
		(width 0.12954)
		(layer "B.Cu")
		(net "RST_CPU1_DRAM_EF_N")
	)
	(segment
		(start 152.968198 -241.62639)
		(end 146.915378 -241.62639)
		(width 0.12954)
		(layer "B.Cu")
		(net "RST_CPU1_DRAM_EF_N")
	)
	(segment
		(start 168.218612 -191.15405)
		(end 167.075358 -192.297304)
		(width 0.12954)
		(layer "B.Cu")
		(net "RST_CPU1_DRAM_EF_N")
	)
	(segment
		(start 146.915378 -241.62639)
		(end 145.701512 -242.840256)
		(width 0.12954)
		(layer "B.Cu")
		(net "RST_CPU1_DRAM_EF_N")
	)
	(segment
		(start 133.030214 -246.765826)
		(end 133.020562 -246.771414)
		(width 0.12954)
		(layer "B.Cu")
		(net "RST_CPU1_DRAM_EF_N")
	)
	(segment
		(start 145.701512 -242.840256)
		(end 140.448284 -242.840256)
		(width 0.12954)
		(layer "B.Cu")
		(net "RST_CPU1_DRAM_EF_N")
	)
	(segment
		(start 165.960298 -216.88679)
		(end 166.615618 -217.54211)
		(width 0.12954)
		(layer "B.Cu")
		(net "RST_CPU1_DRAM_EF_N")
	)
	(segment
		(start 124.106178 -246.779288)
		(end 124.092716 -246.771414)
		(width 0.12954)
		(layer "B.Cu")
		(net "RST_CPU1_DRAM_EF_N")
	)
	(segment
		(start 131.620514 -246.777002)
		(end 131.610862 -246.771414)
		(width 0.12954)
		(layer "B.Cu")
		(net "RST_CPU1_DRAM_EF_N")
	)
	(segment
		(start 136.689084 -246.599456)
		(end 136.012174 -246.599456)
		(width 0.12954)
		(layer "B.Cu")
		(net "RST_CPU1_DRAM_EF_N")
	)
	(segment
		(start 166.615618 -228.04247)
		(end 165.909498 -228.74859)
		(width 0.12954)
		(layer "B.Cu")
		(net "RST_CPU1_DRAM_EF_N")
	)
	(segment
		(start 122.683016 -246.771414)
		(end 121.978166 -247.178322)
		(width 0.12954)
		(layer "B.Cu")
		(net "RST_CPU1_DRAM_EF_N")
	)
	(arc
		(start 123.152916 -246.771414)
		(mid 122.917966 -246.708454)
		(end 122.683016 -246.771414)
		(width 0.12954)
		(layer "B.Cu")
		(net "RST_CPU1_DRAM_EF_N")
	)
	(arc
		(start 127.851916 -246.771414)
		(mid 127.616966 -246.708454)
		(end 127.382016 -246.771414)
		(width 0.12954)
		(layer "B.Cu")
		(net "RST_CPU1_DRAM_EF_N")
	)
	(arc
		(start 135.840216 -246.771414)
		(mid 135.605266 -246.834374)
		(end 135.370316 -246.771414)
		(width 0.12954)
		(layer "B.Cu")
		(net "RST_CPU1_DRAM_EF_N")
	)
	(arc
		(start 131.140962 -246.771414)
		(mid 130.911699 -246.834339)
		(end 130.680968 -246.777002)
		(width 0.12954)
		(layer "B.Cu")
		(net "RST_CPU1_DRAM_EF_N")
	)
	(arc
		(start 125.972316 -246.771414)
		(mid 125.737366 -246.708454)
		(end 125.502416 -246.771414)
		(width 0.12954)
		(layer "B.Cu")
		(net "RST_CPU1_DRAM_EF_N")
	)
	(arc
		(start 124.092716 -246.771414)
		(mid 123.857766 -246.708454)
		(end 123.622816 -246.771414)
		(width 0.12954)
		(layer "B.Cu")
		(net "RST_CPU1_DRAM_EF_N")
	)
	(arc
		(start 126.911862 -246.771414)
		(mid 126.676912 -246.708454)
		(end 126.441962 -246.771414)
		(width 0.12954)
		(layer "B.Cu")
		(net "RST_CPU1_DRAM_EF_N")
	)
	(arc
		(start 125.032516 -246.771414)
		(mid 124.797566 -246.708454)
		(end 124.562616 -246.771414)
		(width 0.12954)
		(layer "B.Cu")
		(net "RST_CPU1_DRAM_EF_N")
	)
	(arc
		(start 135.370316 -246.771414)
		(mid 135.135366 -246.708454)
		(end 134.900416 -246.771414)
		(width 0.12954)
		(layer "B.Cu")
		(net "RST_CPU1_DRAM_EF_N")
	)
	(arc
		(start 129.731516 -246.771414)
		(mid 129.496566 -246.708454)
		(end 129.261616 -246.771414)
		(width 0.12954)
		(layer "B.Cu")
		(net "RST_CPU1_DRAM_EF_N")
	)
	(arc
		(start 132.550916 -246.771414)
		(mid 132.315966 -246.708454)
		(end 132.081016 -246.771414)
		(width 0.12954)
		(layer "B.Cu")
		(net "RST_CPU1_DRAM_EF_N")
	)
	(arc
		(start 130.201416 -246.771414)
		(mid 129.974229 -246.834432)
		(end 129.744978 -246.779288)
		(width 0.12954)
		(layer "B.Cu")
		(net "RST_CPU1_DRAM_EF_N")
	)
	(arc
		(start 128.791716 -246.771414)
		(mid 128.556766 -246.708454)
		(end 128.321816 -246.771414)
		(width 0.12954)
		(layer "B.Cu")
		(net "RST_CPU1_DRAM_EF_N")
	)
	(arc
		(start 126.441962 -246.771414)
		(mid 126.212699 -246.834339)
		(end 125.981968 -246.777002)
		(width 0.12954)
		(layer "B.Cu")
		(net "RST_CPU1_DRAM_EF_N")
	)
	(arc
		(start 128.321816 -246.771414)
		(mid 128.094629 -246.834432)
		(end 127.865378 -246.779288)
		(width 0.12954)
		(layer "B.Cu")
		(net "RST_CPU1_DRAM_EF_N")
	)
	(arc
		(start 127.382016 -246.771414)
		(mid 127.152499 -246.834466)
		(end 126.921514 -246.777002)
		(width 0.12954)
		(layer "B.Cu")
		(net "RST_CPU1_DRAM_EF_N")
	)
	(arc
		(start 130.671316 -246.771414)
		(mid 130.436366 -246.708454)
		(end 130.201416 -246.771414)
		(width 0.12954)
		(layer "B.Cu")
		(net "RST_CPU1_DRAM_EF_N")
	)
	(arc
		(start 134.430516 -246.771414)
		(mid 134.195566 -246.708454)
		(end 133.960616 -246.771414)
		(width 0.12954)
		(layer "B.Cu")
		(net "RST_CPU1_DRAM_EF_N")
	)
	(arc
		(start 132.081016 -246.771414)
		(mid 131.851499 -246.834466)
		(end 131.620514 -246.777002)
		(width 0.12954)
		(layer "B.Cu")
		(net "RST_CPU1_DRAM_EF_N")
	)
	(arc
		(start 124.562616 -246.771414)
		(mid 124.335429 -246.834432)
		(end 124.106178 -246.779288)
		(width 0.12954)
		(layer "B.Cu")
		(net "RST_CPU1_DRAM_EF_N")
	)
	(arc
		(start 134.900416 -246.771414)
		(mid 134.665466 -246.834374)
		(end 134.430516 -246.771414)
		(width 0.12954)
		(layer "B.Cu")
		(net "RST_CPU1_DRAM_EF_N")
	)
	(arc
		(start 133.960616 -246.771414)
		(mid 133.725666 -246.834374)
		(end 133.490716 -246.771414)
		(width 0.12954)
		(layer "B.Cu")
		(net "RST_CPU1_DRAM_EF_N")
	)
	(arc
		(start 123.622816 -246.771414)
		(mid 123.395629 -246.834432)
		(end 123.166378 -246.779288)
		(width 0.12954)
		(layer "B.Cu")
		(net "RST_CPU1_DRAM_EF_N")
	)
	(arc
		(start 133.020562 -246.771414)
		(mid 132.791299 -246.834339)
		(end 132.560568 -246.777002)
		(width 0.12954)
		(layer "B.Cu")
		(net "RST_CPU1_DRAM_EF_N")
	)
	(arc
		(start 131.610862 -246.771414)
		(mid 131.375912 -246.708454)
		(end 131.140962 -246.771414)
		(width 0.12954)
		(layer "B.Cu")
		(net "RST_CPU1_DRAM_EF_N")
	)
	(arc
		(start 133.490716 -246.771414)
		(mid 133.261199 -246.708362)
		(end 133.030214 -246.765826)
		(width 0.12954)
		(layer "B.Cu")
		(net "RST_CPU1_DRAM_EF_N")
	)
	(arc
		(start 125.502416 -246.771414)
		(mid 125.275229 -246.834432)
		(end 125.045978 -246.779288)
		(width 0.12954)
		(layer "B.Cu")
		(net "RST_CPU1_DRAM_EF_N")
	)
	(arc
		(start 129.261616 -246.771414)
		(mid 129.026666 -246.834374)
		(end 128.791716 -246.771414)
		(width 0.12954)
		(layer "B.Cu")
		(net "RST_CPU1_DRAM_EF_N")
	)
	(segment
		(start 127.76454 -125.344428)
		(end 128.29286 -124.816108)
		(width 0.127)
		(layer "In2.Cu")
		(net "RST_CPU1_DRAM_EF_N")
	)
	(segment
		(start 126.13132 -120.028208)
		(end 125.264926 -120.894602)
		(width 0.127)
		(layer "In2.Cu")
		(net "RST_CPU1_DRAM_EF_N")
	)
	(segment
		(start 159.52724 -190.355728)
		(end 159.14624 -190.736728)
		(width 0.127)
		(layer "In2.Cu")
		(net "RST_CPU1_DRAM_EF_N")
	)
	(segment
		(start 128.29286 -120.259348)
		(end 128.06172 -120.028208)
		(width 0.127)
		(layer "In2.Cu")
		(net "RST_CPU1_DRAM_EF_N")
	)
	(segment
		(start 159.14624 -190.736728)
		(end 149.04466 -190.736728)
		(width 0.127)
		(layer "In2.Cu")
		(net "RST_CPU1_DRAM_EF_N")
	)
	(segment
		(start 125.23216 -166.924228)
		(end 125.23216 -151.694388)
		(width 0.127)
		(layer "In2.Cu")
		(net "RST_CPU1_DRAM_EF_N")
	)
	(segment
		(start 149.04466 -190.736728)
		(end 125.23216 -166.924228)
		(width 0.127)
		(layer "In2.Cu")
		(net "RST_CPU1_DRAM_EF_N")
	)
	(segment
		(start 170.81246 -190.924688)
		(end 162.52444 -190.924688)
		(width 0.127)
		(layer "In2.Cu")
		(net "RST_CPU1_DRAM_EF_N")
	)
	(segment
		(start 161.95548 -190.355728)
		(end 159.52724 -190.355728)
		(width 0.127)
		(layer "In2.Cu")
		(net "RST_CPU1_DRAM_EF_N")
	)
	(segment
		(start 128.29286 -124.816108)
		(end 128.29286 -120.259348)
		(width 0.127)
		(layer "In2.Cu")
		(net "RST_CPU1_DRAM_EF_N")
	)
	(segment
		(start 171.098718 -190.63843)
		(end 170.81246 -190.924688)
		(width 0.127)
		(layer "In2.Cu")
		(net "RST_CPU1_DRAM_EF_N")
	)
	(segment
		(start 125.23216 -151.694388)
		(end 127.76454 -149.162008)
		(width 0.127)
		(layer "In2.Cu")
		(net "RST_CPU1_DRAM_EF_N")
	)
	(segment
		(start 127.76454 -149.162008)
		(end 127.76454 -125.344428)
		(width 0.127)
		(layer "In2.Cu")
		(net "RST_CPU1_DRAM_EF_N")
	)
	(segment
		(start 171.098718 -189.16269)
		(end 171.098718 -190.63843)
		(width 0.127)
		(layer "In2.Cu")
		(net "RST_CPU1_DRAM_EF_N")
	)
	(segment
		(start 128.06172 -120.028208)
		(end 126.13132 -120.028208)
		(width 0.127)
		(layer "In2.Cu")
		(net "RST_CPU1_DRAM_EF_N")
	)
	(segment
		(start 125.264926 -120.894602)
		(end 125.264926 -120.953784)
		(width 0.127)
		(layer "In2.Cu")
		(net "RST_CPU1_DRAM_EF_N")
	)
	(segment
		(start 162.52444 -190.924688)
		(end 161.95548 -190.355728)
		(width 0.127)
		(layer "In2.Cu")
		(net "RST_CPU1_DRAM_EF_N")
	)
	(segment
		(start 122.451622 -118.032784)
		(end 123.319794 -117.164612)
		(width 0.12954)
		(layer "F.Cu")
		(net "RST_CPU1_DRAM_CD_PLD_N")
	)
	(segment
		(start 121.708926 -119.410734)
		(end 121.708926 -118.032784)
		(width 0.12954)
		(layer "F.Cu")
		(net "RST_CPU1_DRAM_CD_PLD_N")
	)
	(segment
		(start 121.708926 -118.032784)
		(end 122.451622 -118.032784)
		(width 0.12954)
		(layer "F.Cu")
		(net "RST_CPU1_DRAM_CD_PLD_N")
	)
	(segment
		(start 123.319794 -117.164612)
		(end 123.319794 -116.042948)
		(width 0.12954)
		(layer "F.Cu")
		(net "RST_CPU1_DRAM_CD_PLD_N")
	)
	(via
		(at 121.708926 -118.032784)
		(size 0.762)
		(drill 0.381)
		(layers "F.Cu" "B.Cu")
		(net "RST_CPU1_DRAM_CD_PLD_N")
	)
	(segment
		(start 121.708926 -120.210834)
		(end 121.708926 -120.953784)
		(width 0.12954)
		(layer "F.Cu")
		(net "RST_CPU1_DRAM_CD_N")
	)
	(segment
		(start 102.352094 -257.175)
		(end 102.352348 -257.175254)
		(width 0.12954)
		(layer "F.Cu")
		(net "RST_CPU1_DRAM_CD_N")
	)
	(segment
		(start 121.708926 -120.953784)
		(end 121.708926 -121.696734)
		(width 0.12954)
		(layer "F.Cu")
		(net "RST_CPU1_DRAM_CD_N")
	)
	(segment
		(start 102.352094 -256.639314)
		(end 102.352094 -257.175)
		(width 0.12954)
		(layer "F.Cu")
		(net "RST_CPU1_DRAM_CD_N")
	)
	(via
		(at 121.708926 -120.953784)
		(size 0.508)
		(drill 0.254)
		(layers "F.Cu" "B.Cu")
		(net "RST_CPU1_DRAM_CD_N")
	)
	(via
		(at 60.69076 -182.029608)
		(size 0.508)
		(drill 0.254)
		(layers "F.Cu" "B.Cu")
		(net "RST_CPU1_DRAM_CD_N")
	)
	(via
		(at 102.352348 -257.175254)
		(size 0.4572)
		(drill 0.2032)
		(layers "F.Cu" "B.Cu")
		(net "RST_CPU1_DRAM_CD_N")
	)
	(segment
		(start 61.567314 -237.677706)
		(end 59.126374 -237.677706)
		(width 0.12954)
		(layer "B.Cu")
		(net "RST_CPU1_DRAM_CD_N")
	)
	(segment
		(start 82.025998 -256.292858)
		(end 82.025744 -256.293112)
		(width 0.12954)
		(layer "B.Cu")
		(net "RST_CPU1_DRAM_CD_N")
	)
	(segment
		(start 59.168538 -193.95821)
		(end 58.708798 -193.49847)
		(width 0.12954)
		(layer "B.Cu")
		(net "RST_CPU1_DRAM_CD_N")
	)
	(segment
		(start 94.129098 -256.768346)
		(end 94.119446 -256.762758)
		(width 0.12954)
		(layer "B.Cu")
		(net "RST_CPU1_DRAM_CD_N")
	)
	(segment
		(start 71.682864 -241.924332)
		(end 69.354954 -240.960148)
		(width 0.12954)
		(layer "B.Cu")
		(net "RST_CPU1_DRAM_CD_N")
	)
	(segment
		(start 102.352348 -257.175254)
		(end 101.637592 -256.762758)
		(width 0.12954)
		(layer "B.Cu")
		(net "RST_CPU1_DRAM_CD_N")
	)
	(segment
		(start 77.902562 -256.293112)
		(end 75.278488 -253.669038)
		(width 0.12954)
		(layer "B.Cu")
		(net "RST_CPU1_DRAM_CD_N")
	)
	(segment
		(start 58.708798 -185.787284)
		(end 60.69076 -183.805322)
		(width 0.12954)
		(layer "B.Cu")
		(net "RST_CPU1_DRAM_CD_N")
	)
	(segment
		(start 75.278488 -253.669038)
		(end 75.278488 -245.519956)
		(width 0.12954)
		(layer "B.Cu")
		(net "RST_CPU1_DRAM_CD_N")
	)
	(segment
		(start 92.249244 -256.768346)
		(end 92.235782 -256.760472)
		(width 0.12954)
		(layer "B.Cu")
		(net "RST_CPU1_DRAM_CD_N")
	)
	(segment
		(start 75.278488 -245.519956)
		(end 71.682864 -241.924332)
		(width 0.12954)
		(layer "B.Cu")
		(net "RST_CPU1_DRAM_CD_N")
	)
	(segment
		(start 85.35289 -256.292858)
		(end 82.025998 -256.292858)
		(width 0.12954)
		(layer "B.Cu")
		(net "RST_CPU1_DRAM_CD_N")
	)
	(segment
		(start 58.708798 -193.49847)
		(end 58.708798 -185.787284)
		(width 0.12954)
		(layer "B.Cu")
		(net "RST_CPU1_DRAM_CD_N")
	)
	(segment
		(start 87.54618 -256.768346)
		(end 87.53729 -256.759456)
		(width 0.12954)
		(layer "B.Cu")
		(net "RST_CPU1_DRAM_CD_N")
	)
	(segment
		(start 96.008444 -256.768346)
		(end 95.994982 -256.760472)
		(width 0.12954)
		(layer "B.Cu")
		(net "RST_CPU1_DRAM_CD_N")
	)
	(segment
		(start 96.948244 -256.768346)
		(end 96.934782 -256.760472)
		(width 0.12954)
		(layer "B.Cu")
		(net "RST_CPU1_DRAM_CD_N")
	)
	(segment
		(start 62.363858 -238.47425)
		(end 61.567314 -237.677706)
		(width 0.12954)
		(layer "B.Cu")
		(net "RST_CPU1_DRAM_CD_N")
	)
	(segment
		(start 64.489838 -239.33531)
		(end 63.423038 -239.33531)
		(width 0.12954)
		(layer "B.Cu")
		(net "RST_CPU1_DRAM_CD_N")
	)
	(segment
		(start 98.827844 -256.768346)
		(end 98.814382 -256.760472)
		(width 0.12954)
		(layer "B.Cu")
		(net "RST_CPU1_DRAM_CD_N")
	)
	(segment
		(start 69.354954 -240.960148)
		(end 66.114676 -240.960148)
		(width 0.12954)
		(layer "B.Cu")
		(net "RST_CPU1_DRAM_CD_N")
	)
	(segment
		(start 85.819488 -256.759456)
		(end 85.35289 -256.292858)
		(width 0.12954)
		(layer "B.Cu")
		(net "RST_CPU1_DRAM_CD_N")
	)
	(segment
		(start 88.020144 -256.768346)
		(end 87.982044 -256.790444)
		(width 0.12954)
		(layer "B.Cu")
		(net "RST_CPU1_DRAM_CD_N")
	)
	(segment
		(start 57.316878 -200.13295)
		(end 59.168538 -198.28129)
		(width 0.12954)
		(layer "B.Cu")
		(net "RST_CPU1_DRAM_CD_N")
	)
	(segment
		(start 63.423038 -239.33531)
		(end 62.561978 -238.47425)
		(width 0.12954)
		(layer "B.Cu")
		(net "RST_CPU1_DRAM_CD_N")
	)
	(segment
		(start 62.561978 -238.47425)
		(end 62.363858 -238.47425)
		(width 0.12954)
		(layer "B.Cu")
		(net "RST_CPU1_DRAM_CD_N")
	)
	(segment
		(start 59.126374 -237.677706)
		(end 57.316878 -235.86821)
		(width 0.12954)
		(layer "B.Cu")
		(net "RST_CPU1_DRAM_CD_N")
	)
	(segment
		(start 60.69076 -183.805322)
		(end 60.69076 -182.029608)
		(width 0.12954)
		(layer "B.Cu")
		(net "RST_CPU1_DRAM_CD_N")
	)
	(segment
		(start 82.025744 -256.293112)
		(end 77.902562 -256.293112)
		(width 0.12954)
		(layer "B.Cu")
		(net "RST_CPU1_DRAM_CD_N")
	)
	(segment
		(start 100.707698 -256.768346)
		(end 100.698046 -256.762758)
		(width 0.12954)
		(layer "B.Cu")
		(net "RST_CPU1_DRAM_CD_N")
	)
	(segment
		(start 57.316878 -235.86821)
		(end 57.316878 -200.13295)
		(width 0.12954)
		(layer "B.Cu")
		(net "RST_CPU1_DRAM_CD_N")
	)
	(segment
		(start 66.114676 -240.960148)
		(end 64.489838 -239.33531)
		(width 0.12954)
		(layer "B.Cu")
		(net "RST_CPU1_DRAM_CD_N")
	)
	(segment
		(start 95.068644 -256.768346)
		(end 95.058992 -256.762758)
		(width 0.12954)
		(layer "B.Cu")
		(net "RST_CPU1_DRAM_CD_N")
	)
	(segment
		(start 59.168538 -198.28129)
		(end 59.168538 -193.95821)
		(width 0.12954)
		(layer "B.Cu")
		(net "RST_CPU1_DRAM_CD_N")
	)
	(segment
		(start 87.53729 -256.759456)
		(end 85.819488 -256.759456)
		(width 0.12954)
		(layer "B.Cu")
		(net "RST_CPU1_DRAM_CD_N")
	)
	(arc
		(start 95.058992 -256.762758)
		(mid 94.828261 -256.705397)
		(end 94.598998 -256.768346)
		(width 0.12954)
		(layer "B.Cu")
		(net "RST_CPU1_DRAM_CD_N")
	)
	(arc
		(start 89.899744 -256.768346)
		(mid 89.664794 -256.831306)
		(end 89.429844 -256.768346)
		(width 0.12954)
		(layer "B.Cu")
		(net "RST_CPU1_DRAM_CD_N")
	)
	(arc
		(start 94.119446 -256.762758)
		(mid 93.888461 -256.705275)
		(end 93.658944 -256.768346)
		(width 0.12954)
		(layer "B.Cu")
		(net "RST_CPU1_DRAM_CD_N")
	)
	(arc
		(start 94.598998 -256.768346)
		(mid 94.364048 -256.831306)
		(end 94.129098 -256.768346)
		(width 0.12954)
		(layer "B.Cu")
		(net "RST_CPU1_DRAM_CD_N")
	)
	(arc
		(start 100.698046 -256.762758)
		(mid 100.467061 -256.705275)
		(end 100.237544 -256.768346)
		(width 0.12954)
		(layer "B.Cu")
		(net "RST_CPU1_DRAM_CD_N")
	)
	(arc
		(start 93.189044 -256.768346)
		(mid 92.954094 -256.705386)
		(end 92.719144 -256.768346)
		(width 0.12954)
		(layer "B.Cu")
		(net "RST_CPU1_DRAM_CD_N")
	)
	(arc
		(start 98.357944 -256.768346)
		(mid 98.122994 -256.831306)
		(end 97.888044 -256.768346)
		(width 0.12954)
		(layer "B.Cu")
		(net "RST_CPU1_DRAM_CD_N")
	)
	(arc
		(start 91.779344 -256.768346)
		(mid 91.544394 -256.831306)
		(end 91.309444 -256.768346)
		(width 0.12954)
		(layer "B.Cu")
		(net "RST_CPU1_DRAM_CD_N")
	)
	(arc
		(start 92.719144 -256.768346)
		(mid 92.484194 -256.831306)
		(end 92.249244 -256.768346)
		(width 0.12954)
		(layer "B.Cu")
		(net "RST_CPU1_DRAM_CD_N")
	)
	(arc
		(start 97.418144 -256.768346)
		(mid 97.183194 -256.831306)
		(end 96.948244 -256.768346)
		(width 0.12954)
		(layer "B.Cu")
		(net "RST_CPU1_DRAM_CD_N")
	)
	(arc
		(start 98.814382 -256.760472)
		(mid 98.585129 -256.705228)
		(end 98.357944 -256.768346)
		(width 0.12954)
		(layer "B.Cu")
		(net "RST_CPU1_DRAM_CD_N")
	)
	(arc
		(start 90.839544 -256.768346)
		(mid 90.604594 -256.831306)
		(end 90.369644 -256.768346)
		(width 0.12954)
		(layer "B.Cu")
		(net "RST_CPU1_DRAM_CD_N")
	)
	(arc
		(start 88.490044 -256.768346)
		(mid 88.255094 -256.705386)
		(end 88.020144 -256.768346)
		(width 0.12954)
		(layer "B.Cu")
		(net "RST_CPU1_DRAM_CD_N")
	)
	(arc
		(start 99.767644 -256.768346)
		(mid 99.532694 -256.705386)
		(end 99.297744 -256.768346)
		(width 0.12954)
		(layer "B.Cu")
		(net "RST_CPU1_DRAM_CD_N")
	)
	(arc
		(start 89.429844 -256.768346)
		(mid 89.194894 -256.705386)
		(end 88.959944 -256.768346)
		(width 0.12954)
		(layer "B.Cu")
		(net "RST_CPU1_DRAM_CD_N")
	)
	(arc
		(start 96.934782 -256.760472)
		(mid 96.705529 -256.705228)
		(end 96.478344 -256.768346)
		(width 0.12954)
		(layer "B.Cu")
		(net "RST_CPU1_DRAM_CD_N")
	)
	(arc
		(start 93.658944 -256.768346)
		(mid 93.423994 -256.831306)
		(end 93.189044 -256.768346)
		(width 0.12954)
		(layer "B.Cu")
		(net "RST_CPU1_DRAM_CD_N")
	)
	(arc
		(start 96.478344 -256.768346)
		(mid 96.243394 -256.831306)
		(end 96.008444 -256.768346)
		(width 0.12954)
		(layer "B.Cu")
		(net "RST_CPU1_DRAM_CD_N")
	)
	(arc
		(start 99.297744 -256.768346)
		(mid 99.062794 -256.831306)
		(end 98.827844 -256.768346)
		(width 0.12954)
		(layer "B.Cu")
		(net "RST_CPU1_DRAM_CD_N")
	)
	(arc
		(start 92.235782 -256.760472)
		(mid 92.006529 -256.705228)
		(end 91.779344 -256.768346)
		(width 0.12954)
		(layer "B.Cu")
		(net "RST_CPU1_DRAM_CD_N")
	)
	(arc
		(start 95.994982 -256.760472)
		(mid 95.765729 -256.705228)
		(end 95.538544 -256.768346)
		(width 0.12954)
		(layer "B.Cu")
		(net "RST_CPU1_DRAM_CD_N")
	)
	(arc
		(start 101.637592 -256.762758)
		(mid 101.406861 -256.705397)
		(end 101.177598 -256.768346)
		(width 0.12954)
		(layer "B.Cu")
		(net "RST_CPU1_DRAM_CD_N")
	)
	(arc
		(start 101.177598 -256.768346)
		(mid 100.942648 -256.831306)
		(end 100.707698 -256.768346)
		(width 0.12954)
		(layer "B.Cu")
		(net "RST_CPU1_DRAM_CD_N")
	)
	(arc
		(start 91.309444 -256.768346)
		(mid 91.074494 -256.705386)
		(end 90.839544 -256.768346)
		(width 0.12954)
		(layer "B.Cu")
		(net "RST_CPU1_DRAM_CD_N")
	)
	(arc
		(start 87.982044 -256.790444)
		(mid 87.76139 -256.83285)
		(end 87.54618 -256.768346)
		(width 0.12954)
		(layer "B.Cu")
		(net "RST_CPU1_DRAM_CD_N")
	)
	(arc
		(start 90.369644 -256.768346)
		(mid 90.134694 -256.705386)
		(end 89.899744 -256.768346)
		(width 0.12954)
		(layer "B.Cu")
		(net "RST_CPU1_DRAM_CD_N")
	)
	(arc
		(start 95.538544 -256.768346)
		(mid 95.303594 -256.831306)
		(end 95.068644 -256.768346)
		(width 0.12954)
		(layer "B.Cu")
		(net "RST_CPU1_DRAM_CD_N")
	)
	(arc
		(start 97.888044 -256.768346)
		(mid 97.653094 -256.705386)
		(end 97.418144 -256.768346)
		(width 0.12954)
		(layer "B.Cu")
		(net "RST_CPU1_DRAM_CD_N")
	)
	(arc
		(start 88.959944 -256.768346)
		(mid 88.724994 -256.831306)
		(end 88.490044 -256.768346)
		(width 0.12954)
		(layer "B.Cu")
		(net "RST_CPU1_DRAM_CD_N")
	)
	(arc
		(start 100.237544 -256.768346)
		(mid 100.002594 -256.831306)
		(end 99.767644 -256.768346)
		(width 0.12954)
		(layer "B.Cu")
		(net "RST_CPU1_DRAM_CD_N")
	)
	(segment
		(start 76.35748 -176.469548)
		(end 71.9836 -176.469548)
		(width 0.127)
		(layer "In4.Cu")
		(net "RST_CPU1_DRAM_CD_N")
	)
	(segment
		(start 71.9836 -176.469548)
		(end 71.4248 -175.910748)
		(width 0.127)
		(layer "In4.Cu")
		(net "RST_CPU1_DRAM_CD_N")
	)
	(segment
		(start 119.95658 -120.322848)
		(end 119.37746 -120.901968)
		(width 0.127)
		(layer "In4.Cu")
		(net "RST_CPU1_DRAM_CD_N")
	)
	(segment
		(start 121.2596 -120.322848)
		(end 119.95658 -120.322848)
		(width 0.127)
		(layer "In4.Cu")
		(net "RST_CPU1_DRAM_CD_N")
	)
	(segment
		(start 71.4248 -175.910748)
		(end 68.707254 -175.910748)
		(width 0.127)
		(layer "In4.Cu")
		(net "RST_CPU1_DRAM_CD_N")
	)
	(segment
		(start 119.37746 -120.901968)
		(end 119.37746 -133.449568)
		(width 0.127)
		(layer "In4.Cu")
		(net "RST_CPU1_DRAM_CD_N")
	)
	(segment
		(start 119.37746 -133.449568)
		(end 76.35748 -176.469548)
		(width 0.127)
		(layer "In4.Cu")
		(net "RST_CPU1_DRAM_CD_N")
	)
	(segment
		(start 66.43878 -178.958748)
		(end 65.862454 -178.958748)
		(width 0.127)
		(layer "In4.Cu")
		(net "RST_CPU1_DRAM_CD_N")
	)
	(segment
		(start 67.42938 -177.968148)
		(end 66.43878 -178.958748)
		(width 0.127)
		(layer "In4.Cu")
		(net "RST_CPU1_DRAM_CD_N")
	)
	(segment
		(start 68.707254 -175.910748)
		(end 67.42938 -177.188622)
		(width 0.127)
		(layer "In4.Cu")
		(net "RST_CPU1_DRAM_CD_N")
	)
	(segment
		(start 64.008254 -180.812948)
		(end 61.90742 -180.812948)
		(width 0.127)
		(layer "In4.Cu")
		(net "RST_CPU1_DRAM_CD_N")
	)
	(segment
		(start 67.42938 -177.188622)
		(end 67.42938 -177.968148)
		(width 0.127)
		(layer "In4.Cu")
		(net "RST_CPU1_DRAM_CD_N")
	)
	(segment
		(start 121.708926 -120.772174)
		(end 121.2596 -120.322848)
		(width 0.127)
		(layer "In4.Cu")
		(net "RST_CPU1_DRAM_CD_N")
	)
	(segment
		(start 65.862454 -178.958748)
		(end 64.008254 -180.812948)
		(width 0.127)
		(layer "In4.Cu")
		(net "RST_CPU1_DRAM_CD_N")
	)
	(segment
		(start 121.708926 -120.953784)
		(end 121.708926 -120.772174)
		(width 0.127)
		(layer "In4.Cu")
		(net "RST_CPU1_DRAM_CD_N")
	)
	(segment
		(start 61.90742 -180.812948)
		(end 60.69076 -182.029608)
		(width 0.127)
		(layer "In4.Cu")
		(net "RST_CPU1_DRAM_CD_N")
	)
	(segment
		(start 122.669808 -116.654072)
		(end 122.669808 -116.042948)
		(width 0.12954)
		(layer "F.Cu")
		(net "RST_CPU1_DRAM_AB_PLD_N")
	)
	(segment
		(start 121.346976 -117.124734)
		(end 122.199146 -117.124734)
		(width 0.12954)
		(layer "F.Cu")
		(net "RST_CPU1_DRAM_AB_PLD_N")
	)
	(segment
		(start 120.438926 -118.032784)
		(end 121.346976 -117.124734)
		(width 0.12954)
		(layer "F.Cu")
		(net "RST_CPU1_DRAM_AB_PLD_N")
	)
	(segment
		(start 120.438926 -119.410734)
		(end 120.438926 -118.032784)
		(width 0.12954)
		(layer "F.Cu")
		(net "RST_CPU1_DRAM_AB_PLD_N")
	)
	(segment
		(start 122.199146 -117.124734)
		(end 122.669808 -116.654072)
		(width 0.12954)
		(layer "F.Cu")
		(net "RST_CPU1_DRAM_AB_PLD_N")
	)
	(via
		(at 120.438926 -118.032784)
		(size 0.762)
		(drill 0.381)
		(layers "F.Cu" "B.Cu")
		(net "RST_CPU1_DRAM_AB_PLD_N")
	)
	(segment
		(start 101.882448 -255.825498)
		(end 101.882448 -256.361184)
		(width 0.12954)
		(layer "F.Cu")
		(net "RST_CPU1_DRAM_AB_N")
	)
	(segment
		(start 120.438926 -120.953784)
		(end 120.438926 -121.696734)
		(width 0.12954)
		(layer "F.Cu")
		(net "RST_CPU1_DRAM_AB_N")
	)
	(segment
		(start 120.438926 -120.210834)
		(end 120.438926 -120.953784)
		(width 0.12954)
		(layer "F.Cu")
		(net "RST_CPU1_DRAM_AB_N")
	)
	(segment
		(start 101.882448 -256.361184)
		(end 101.882194 -256.361438)
		(width 0.12954)
		(layer "F.Cu")
		(net "RST_CPU1_DRAM_AB_N")
	)
	(via
		(at 101.882194 -256.361438)
		(size 0.4572)
		(drill 0.2032)
		(layers "F.Cu" "B.Cu")
		(net "RST_CPU1_DRAM_AB_N")
	)
	(via
		(at 61.58484 -182.029608)
		(size 0.508)
		(drill 0.254)
		(layers "F.Cu" "B.Cu")
		(net "RST_CPU1_DRAM_AB_N")
	)
	(via
		(at 120.438926 -120.953784)
		(size 0.508)
		(drill 0.254)
		(layers "F.Cu" "B.Cu")
		(net "RST_CPU1_DRAM_AB_N")
	)
	(segment
		(start 99.767644 -255.95453)
		(end 99.754182 -255.962404)
		(width 0.12954)
		(layer "B.Cu")
		(net "RST_CPU1_DRAM_AB_N")
	)
	(segment
		(start 61.58484 -184.175908)
		(end 61.58484 -182.029608)
		(width 0.12954)
		(layer "B.Cu")
		(net "RST_CPU1_DRAM_AB_N")
	)
	(segment
		(start 61.905134 -236.862366)
		(end 59.464194 -236.862366)
		(width 0.12954)
		(layer "B.Cu")
		(net "RST_CPU1_DRAM_AB_N")
	)
	(segment
		(start 100.707698 -255.95453)
		(end 100.698046 -255.960118)
		(width 0.12954)
		(layer "B.Cu")
		(net "RST_CPU1_DRAM_AB_N")
	)
	(segment
		(start 68.127372 -239.648238)
		(end 67.140328 -239.648238)
		(width 0.12954)
		(layer "B.Cu")
		(net "RST_CPU1_DRAM_AB_N")
	)
	(segment
		(start 87.550244 -255.95453)
		(end 87.525098 -255.969262)
		(width 0.12954)
		(layer "B.Cu")
		(net "RST_CPU1_DRAM_AB_N")
	)
	(segment
		(start 101.882194 -256.361438)
		(end 101.177598 -255.95453)
		(width 0.12954)
		(layer "B.Cu")
		(net "RST_CPU1_DRAM_AB_N")
	)
	(segment
		(start 67.140328 -239.648238)
		(end 65.440052 -239.132364)
		(width 0.12954)
		(layer "B.Cu")
		(net "RST_CPU1_DRAM_AB_N")
	)
	(segment
		(start 60.974478 -198.62927)
		(end 60.974478 -193.88201)
		(width 0.12954)
		(layer "B.Cu")
		(net "RST_CPU1_DRAM_AB_N")
	)
	(segment
		(start 89.429844 -255.95453)
		(end 89.416382 -255.962404)
		(width 0.12954)
		(layer "B.Cu")
		(net "RST_CPU1_DRAM_AB_N")
	)
	(segment
		(start 82.606642 -255.124204)
		(end 81.944718 -254.46228)
		(width 0.12954)
		(layer "B.Cu")
		(net "RST_CPU1_DRAM_AB_N")
	)
	(segment
		(start 63.81115 -237.66907)
		(end 62.711838 -237.66907)
		(width 0.12954)
		(layer "B.Cu")
		(net "RST_CPU1_DRAM_AB_N")
	)
	(segment
		(start 59.464194 -236.862366)
		(end 58.132218 -235.53039)
		(width 0.12954)
		(layer "B.Cu")
		(net "RST_CPU1_DRAM_AB_N")
	)
	(segment
		(start 85.119718 -255.124204)
		(end 82.606642 -255.124204)
		(width 0.12954)
		(layer "B.Cu")
		(net "RST_CPU1_DRAM_AB_N")
	)
	(segment
		(start 58.434478 -200.17613)
		(end 59.427618 -200.17613)
		(width 0.12954)
		(layer "B.Cu")
		(net "RST_CPU1_DRAM_AB_N")
	)
	(segment
		(start 65.440052 -239.132364)
		(end 64.094106 -237.786418)
		(width 0.12954)
		(layer "B.Cu")
		(net "RST_CPU1_DRAM_AB_N")
	)
	(segment
		(start 59.602878 -192.51041)
		(end 59.602878 -186.15787)
		(width 0.12954)
		(layer "B.Cu")
		(net "RST_CPU1_DRAM_AB_N")
	)
	(segment
		(start 59.427618 -200.17613)
		(end 60.974478 -198.62927)
		(width 0.12954)
		(layer "B.Cu")
		(net "RST_CPU1_DRAM_AB_N")
	)
	(segment
		(start 81.944718 -250.160536)
		(end 72.871584 -241.087402)
		(width 0.12954)
		(layer "B.Cu")
		(net "RST_CPU1_DRAM_AB_N")
	)
	(segment
		(start 60.974478 -193.88201)
		(end 59.602878 -192.51041)
		(width 0.12954)
		(layer "B.Cu")
		(net "RST_CPU1_DRAM_AB_N")
	)
	(segment
		(start 96.008444 -255.95453)
		(end 95.994982 -255.962404)
		(width 0.12954)
		(layer "B.Cu")
		(net "RST_CPU1_DRAM_AB_N")
	)
	(segment
		(start 64.094106 -237.786418)
		(end 63.81115 -237.66907)
		(width 0.12954)
		(layer "B.Cu")
		(net "RST_CPU1_DRAM_AB_N")
	)
	(segment
		(start 93.189044 -255.95453)
		(end 93.175582 -255.962404)
		(width 0.12954)
		(layer "B.Cu")
		(net "RST_CPU1_DRAM_AB_N")
	)
	(segment
		(start 58.132218 -235.53039)
		(end 58.132218 -200.47839)
		(width 0.12954)
		(layer "B.Cu")
		(net "RST_CPU1_DRAM_AB_N")
	)
	(segment
		(start 95.068644 -255.95453)
		(end 95.058992 -255.960118)
		(width 0.12954)
		(layer "B.Cu")
		(net "RST_CPU1_DRAM_AB_N")
	)
	(segment
		(start 94.129098 -255.95453)
		(end 94.119446 -255.960118)
		(width 0.12954)
		(layer "B.Cu")
		(net "RST_CPU1_DRAM_AB_N")
	)
	(segment
		(start 86.591902 -255.467866)
		(end 85.46338 -255.467866)
		(width 0.12954)
		(layer "B.Cu")
		(net "RST_CPU1_DRAM_AB_N")
	)
	(segment
		(start 87.078566 -255.95453)
		(end 86.591902 -255.467866)
		(width 0.12954)
		(layer "B.Cu")
		(net "RST_CPU1_DRAM_AB_N")
	)
	(segment
		(start 72.871584 -241.087402)
		(end 68.127372 -239.648238)
		(width 0.12954)
		(layer "B.Cu")
		(net "RST_CPU1_DRAM_AB_N")
	)
	(segment
		(start 97.888044 -255.95453)
		(end 97.874582 -255.962404)
		(width 0.12954)
		(layer "B.Cu")
		(net "RST_CPU1_DRAM_AB_N")
	)
	(segment
		(start 91.309444 -255.95453)
		(end 91.295982 -255.962404)
		(width 0.12954)
		(layer "B.Cu")
		(net "RST_CPU1_DRAM_AB_N")
	)
	(segment
		(start 59.602878 -186.15787)
		(end 61.58484 -184.175908)
		(width 0.12954)
		(layer "B.Cu")
		(net "RST_CPU1_DRAM_AB_N")
	)
	(segment
		(start 96.948244 -255.95453)
		(end 96.934782 -255.962404)
		(width 0.12954)
		(layer "B.Cu")
		(net "RST_CPU1_DRAM_AB_N")
	)
	(segment
		(start 85.46338 -255.467866)
		(end 85.119718 -255.124204)
		(width 0.12954)
		(layer "B.Cu")
		(net "RST_CPU1_DRAM_AB_N")
	)
	(segment
		(start 58.132218 -200.47839)
		(end 58.434478 -200.17613)
		(width 0.12954)
		(layer "B.Cu")
		(net "RST_CPU1_DRAM_AB_N")
	)
	(segment
		(start 62.711838 -237.66907)
		(end 61.905134 -236.862366)
		(width 0.12954)
		(layer "B.Cu")
		(net "RST_CPU1_DRAM_AB_N")
	)
	(segment
		(start 81.944718 -254.46228)
		(end 81.944718 -250.160536)
		(width 0.12954)
		(layer "B.Cu")
		(net "RST_CPU1_DRAM_AB_N")
	)
	(arc
		(start 88.020144 -255.95453)
		(mid 87.785194 -255.89157)
		(end 87.550244 -255.95453)
		(width 0.12954)
		(layer "B.Cu")
		(net "RST_CPU1_DRAM_AB_N")
	)
	(arc
		(start 93.658944 -255.95453)
		(mid 93.423994 -255.89157)
		(end 93.189044 -255.95453)
		(width 0.12954)
		(layer "B.Cu")
		(net "RST_CPU1_DRAM_AB_N")
	)
	(arc
		(start 91.779344 -255.95453)
		(mid 91.544394 -255.89157)
		(end 91.309444 -255.95453)
		(width 0.12954)
		(layer "B.Cu")
		(net "RST_CPU1_DRAM_AB_N")
	)
	(arc
		(start 100.698046 -255.960118)
		(mid 100.467061 -256.017601)
		(end 100.237544 -255.95453)
		(width 0.12954)
		(layer "B.Cu")
		(net "RST_CPU1_DRAM_AB_N")
	)
	(arc
		(start 95.538544 -255.95453)
		(mid 95.303594 -255.89157)
		(end 95.068644 -255.95453)
		(width 0.12954)
		(layer "B.Cu")
		(net "RST_CPU1_DRAM_AB_N")
	)
	(arc
		(start 99.754182 -255.962404)
		(mid 99.524929 -256.017648)
		(end 99.297744 -255.95453)
		(width 0.12954)
		(layer "B.Cu")
		(net "RST_CPU1_DRAM_AB_N")
	)
	(arc
		(start 96.478344 -255.95453)
		(mid 96.243394 -255.89157)
		(end 96.008444 -255.95453)
		(width 0.12954)
		(layer "B.Cu")
		(net "RST_CPU1_DRAM_AB_N")
	)
	(arc
		(start 95.058992 -255.960118)
		(mid 94.828261 -256.017479)
		(end 94.598998 -255.95453)
		(width 0.12954)
		(layer "B.Cu")
		(net "RST_CPU1_DRAM_AB_N")
	)
	(arc
		(start 96.934782 -255.962404)
		(mid 96.705529 -256.017648)
		(end 96.478344 -255.95453)
		(width 0.12954)
		(layer "B.Cu")
		(net "RST_CPU1_DRAM_AB_N")
	)
	(arc
		(start 87.525098 -255.969262)
		(mid 87.29998 -256.018206)
		(end 87.078566 -255.95453)
		(width 0.12954)
		(layer "B.Cu")
		(net "RST_CPU1_DRAM_AB_N")
	)
	(arc
		(start 94.598998 -255.95453)
		(mid 94.364048 -255.89157)
		(end 94.129098 -255.95453)
		(width 0.12954)
		(layer "B.Cu")
		(net "RST_CPU1_DRAM_AB_N")
	)
	(arc
		(start 97.874582 -255.962404)
		(mid 97.645329 -256.017648)
		(end 97.418144 -255.95453)
		(width 0.12954)
		(layer "B.Cu")
		(net "RST_CPU1_DRAM_AB_N")
	)
	(arc
		(start 93.175582 -255.962404)
		(mid 92.946329 -256.017648)
		(end 92.719144 -255.95453)
		(width 0.12954)
		(layer "B.Cu")
		(net "RST_CPU1_DRAM_AB_N")
	)
	(arc
		(start 91.295982 -255.962404)
		(mid 91.066729 -256.017648)
		(end 90.839544 -255.95453)
		(width 0.12954)
		(layer "B.Cu")
		(net "RST_CPU1_DRAM_AB_N")
	)
	(arc
		(start 92.719144 -255.95453)
		(mid 92.484194 -255.89157)
		(end 92.249244 -255.95453)
		(width 0.12954)
		(layer "B.Cu")
		(net "RST_CPU1_DRAM_AB_N")
	)
	(arc
		(start 101.177598 -255.95453)
		(mid 100.942648 -255.89157)
		(end 100.707698 -255.95453)
		(width 0.12954)
		(layer "B.Cu")
		(net "RST_CPU1_DRAM_AB_N")
	)
	(arc
		(start 98.357944 -255.95453)
		(mid 98.122994 -255.89157)
		(end 97.888044 -255.95453)
		(width 0.12954)
		(layer "B.Cu")
		(net "RST_CPU1_DRAM_AB_N")
	)
	(arc
		(start 90.839544 -255.95453)
		(mid 90.604594 -255.89157)
		(end 90.369644 -255.95453)
		(width 0.12954)
		(layer "B.Cu")
		(net "RST_CPU1_DRAM_AB_N")
	)
	(arc
		(start 88.490044 -255.95453)
		(mid 88.255094 -256.01749)
		(end 88.020144 -255.95453)
		(width 0.12954)
		(layer "B.Cu")
		(net "RST_CPU1_DRAM_AB_N")
	)
	(arc
		(start 100.237544 -255.95453)
		(mid 100.002594 -255.89157)
		(end 99.767644 -255.95453)
		(width 0.12954)
		(layer "B.Cu")
		(net "RST_CPU1_DRAM_AB_N")
	)
	(arc
		(start 94.119446 -255.960118)
		(mid 93.888461 -256.017601)
		(end 93.658944 -255.95453)
		(width 0.12954)
		(layer "B.Cu")
		(net "RST_CPU1_DRAM_AB_N")
	)
	(arc
		(start 90.369644 -255.95453)
		(mid 90.134694 -256.01749)
		(end 89.899744 -255.95453)
		(width 0.12954)
		(layer "B.Cu")
		(net "RST_CPU1_DRAM_AB_N")
	)
	(arc
		(start 95.994982 -255.962404)
		(mid 95.765729 -256.017648)
		(end 95.538544 -255.95453)
		(width 0.12954)
		(layer "B.Cu")
		(net "RST_CPU1_DRAM_AB_N")
	)
	(arc
		(start 88.959944 -255.95453)
		(mid 88.724994 -255.89157)
		(end 88.490044 -255.95453)
		(width 0.12954)
		(layer "B.Cu")
		(net "RST_CPU1_DRAM_AB_N")
	)
	(arc
		(start 92.249244 -255.95453)
		(mid 92.014294 -256.01749)
		(end 91.779344 -255.95453)
		(width 0.12954)
		(layer "B.Cu")
		(net "RST_CPU1_DRAM_AB_N")
	)
	(arc
		(start 89.899744 -255.95453)
		(mid 89.664794 -255.89157)
		(end 89.429844 -255.95453)
		(width 0.12954)
		(layer "B.Cu")
		(net "RST_CPU1_DRAM_AB_N")
	)
	(arc
		(start 97.418144 -255.95453)
		(mid 97.183194 -255.89157)
		(end 96.948244 -255.95453)
		(width 0.12954)
		(layer "B.Cu")
		(net "RST_CPU1_DRAM_AB_N")
	)
	(arc
		(start 99.297744 -255.95453)
		(mid 99.062794 -255.89157)
		(end 98.827844 -255.95453)
		(width 0.12954)
		(layer "B.Cu")
		(net "RST_CPU1_DRAM_AB_N")
	)
	(arc
		(start 89.416382 -255.962404)
		(mid 89.187129 -256.017648)
		(end 88.959944 -255.95453)
		(width 0.12954)
		(layer "B.Cu")
		(net "RST_CPU1_DRAM_AB_N")
	)
	(arc
		(start 98.827844 -255.95453)
		(mid 98.592894 -256.01749)
		(end 98.357944 -255.95453)
		(width 0.12954)
		(layer "B.Cu")
		(net "RST_CPU1_DRAM_AB_N")
	)
	(segment
		(start 61.58484 -182.029608)
		(end 64.26454 -182.029608)
		(width 0.127)
		(layer "In4.Cu")
		(net "RST_CPU1_DRAM_AB_N")
	)
	(segment
		(start 120.438926 -121.417334)
		(end 120.438926 -120.953784)
		(width 0.127)
		(layer "In4.Cu")
		(net "RST_CPU1_DRAM_AB_N")
	)
	(segment
		(start 70.41134 -179.695348)
		(end 72.49414 -177.612548)
		(width 0.127)
		(layer "In4.Cu")
		(net "RST_CPU1_DRAM_AB_N")
	)
	(segment
		(start 121.0945 -133.027928)
		(end 121.0945 -122.072908)
		(width 0.127)
		(layer "In4.Cu")
		(net "RST_CPU1_DRAM_AB_N")
	)
	(segment
		(start 64.26454 -182.029608)
		(end 66.421 -179.873148)
		(width 0.127)
		(layer "In4.Cu")
		(net "RST_CPU1_DRAM_AB_N")
	)
	(segment
		(start 67.437 -179.873148)
		(end 67.6148 -179.695348)
		(width 0.127)
		(layer "In4.Cu")
		(net "RST_CPU1_DRAM_AB_N")
	)
	(segment
		(start 66.421 -179.873148)
		(end 67.437 -179.873148)
		(width 0.127)
		(layer "In4.Cu")
		(net "RST_CPU1_DRAM_AB_N")
	)
	(segment
		(start 76.50988 -177.612548)
		(end 121.0945 -133.027928)
		(width 0.127)
		(layer "In4.Cu")
		(net "RST_CPU1_DRAM_AB_N")
	)
	(segment
		(start 67.6148 -179.695348)
		(end 70.41134 -179.695348)
		(width 0.127)
		(layer "In4.Cu")
		(net "RST_CPU1_DRAM_AB_N")
	)
	(segment
		(start 72.49414 -177.612548)
		(end 76.50988 -177.612548)
		(width 0.127)
		(layer "In4.Cu")
		(net "RST_CPU1_DRAM_AB_N")
	)
	(segment
		(start 121.0945 -122.072908)
		(end 120.438926 -121.417334)
		(width 0.127)
		(layer "In4.Cu")
		(net "RST_CPU1_DRAM_AB_N")
	)
	(via
		(at 190.4111 -101.227128)
		(size 0.6604)
		(drill 0.3302)
		(layers "F.Cu" "B.Cu")
		(net "RST_CPU1_BUF_R_N")
	)
	(via
		(at 55.412386 -197.236842)
		(size 0.6604)
		(drill 0.3302)
		(layers "F.Cu" "B.Cu")
		(net "RST_CPU1_BUF_R_N")
	)
	(via
		(at 188.50864 -100.698808)
		(size 0.508)
		(drill 0.254)
		(layers "F.Cu" "B.Cu")
		(net "RST_CPU1_BUF_R_N")
	)
	(via
		(at 55.077868 -192.24371)
		(size 0.508)
		(drill 0.254)
		(layers "F.Cu" "B.Cu")
		(net "RST_CPU1_BUF_R_N")
	)
	(segment
		(start 190.037212 -101.601016)
		(end 190.037212 -102.830376)
		(width 0.12954)
		(layer "B.Cu")
		(net "RST_CPU1_BUF_R_N")
	)
	(segment
		(start 62.191138 -241.87531)
		(end 62.605158 -242.28933)
		(width 0.12954)
		(layer "B.Cu")
		(net "RST_CPU1_BUF_R_N")
	)
	(segment
		(start 54.972458 -239.39119)
		(end 56.026558 -240.44529)
		(width 0.12954)
		(layer "B.Cu")
		(net "RST_CPU1_BUF_R_N")
	)
	(segment
		(start 63.760858 -244.53723)
		(end 64.515746 -244.53723)
		(width 0.12954)
		(layer "B.Cu")
		(net "RST_CPU1_BUF_R_N")
	)
	(segment
		(start 55.759858 -194.40525)
		(end 55.759858 -196.88937)
		(width 0.12954)
		(layer "B.Cu")
		(net "RST_CPU1_BUF_R_N")
	)
	(segment
		(start 189.88278 -100.698808)
		(end 190.4111 -101.227128)
		(width 0.12954)
		(layer "B.Cu")
		(net "RST_CPU1_BUF_R_N")
	)
	(segment
		(start 56.026558 -240.44529)
		(end 57.02808 -240.44529)
		(width 0.12954)
		(layer "B.Cu")
		(net "RST_CPU1_BUF_R_N")
	)
	(segment
		(start 55.759858 -196.88937)
		(end 55.412386 -197.236842)
		(width 0.12954)
		(layer "B.Cu")
		(net "RST_CPU1_BUF_R_N")
	)
	(segment
		(start 62.605158 -243.38153)
		(end 63.760858 -244.53723)
		(width 0.12954)
		(layer "B.Cu")
		(net "RST_CPU1_BUF_R_N")
	)
	(segment
		(start 57.02808 -240.44529)
		(end 57.619138 -241.036348)
		(width 0.12954)
		(layer "B.Cu")
		(net "RST_CPU1_BUF_R_N")
	)
	(segment
		(start 55.412386 -197.236842)
		(end 53.395118 -199.25411)
		(width 0.12954)
		(layer "B.Cu")
		(net "RST_CPU1_BUF_R_N")
	)
	(segment
		(start 188.50864 -100.698808)
		(end 189.88278 -100.698808)
		(width 0.12954)
		(layer "B.Cu")
		(net "RST_CPU1_BUF_R_N")
	)
	(segment
		(start 55.077868 -192.24371)
		(end 55.077868 -193.17462)
		(width 0.12954)
		(layer "B.Cu")
		(net "RST_CPU1_BUF_R_N")
	)
	(segment
		(start 55.695088 -193.79184)
		(end 55.695088 -194.34048)
		(width 0.12954)
		(layer "B.Cu")
		(net "RST_CPU1_BUF_R_N")
	)
	(segment
		(start 53.395118 -236.920786)
		(end 54.972458 -238.498126)
		(width 0.12954)
		(layer "B.Cu")
		(net "RST_CPU1_BUF_R_N")
	)
	(segment
		(start 58.80608 -241.036348)
		(end 59.645042 -241.87531)
		(width 0.12954)
		(layer "B.Cu")
		(net "RST_CPU1_BUF_R_N")
	)
	(segment
		(start 54.972458 -238.498126)
		(end 54.972458 -239.39119)
		(width 0.12954)
		(layer "B.Cu")
		(net "RST_CPU1_BUF_R_N")
	)
	(segment
		(start 62.605158 -242.28933)
		(end 62.605158 -243.38153)
		(width 0.12954)
		(layer "B.Cu")
		(net "RST_CPU1_BUF_R_N")
	)
	(segment
		(start 57.619138 -241.036348)
		(end 58.80608 -241.036348)
		(width 0.12954)
		(layer "B.Cu")
		(net "RST_CPU1_BUF_R_N")
	)
	(segment
		(start 55.077868 -193.17462)
		(end 55.695088 -193.79184)
		(width 0.12954)
		(layer "B.Cu")
		(net "RST_CPU1_BUF_R_N")
	)
	(segment
		(start 190.4111 -101.227128)
		(end 190.037212 -101.601016)
		(width 0.12954)
		(layer "B.Cu")
		(net "RST_CPU1_BUF_R_N")
	)
	(segment
		(start 53.395118 -199.25411)
		(end 53.395118 -236.920786)
		(width 0.12954)
		(layer "B.Cu")
		(net "RST_CPU1_BUF_R_N")
	)
	(segment
		(start 64.515746 -244.53723)
		(end 65.707514 -243.345462)
		(width 0.12954)
		(layer "B.Cu")
		(net "RST_CPU1_BUF_R_N")
	)
	(segment
		(start 55.695088 -194.34048)
		(end 55.759858 -194.40525)
		(width 0.12954)
		(layer "B.Cu")
		(net "RST_CPU1_BUF_R_N")
	)
	(segment
		(start 59.645042 -241.87531)
		(end 62.191138 -241.87531)
		(width 0.12954)
		(layer "B.Cu")
		(net "RST_CPU1_BUF_R_N")
	)
	(segment
		(start 68.199 -181.016148)
		(end 67.577716 -181.637432)
		(width 0.127)
		(layer "In4.Cu")
		(net "RST_CPU1_BUF_R_N")
	)
	(segment
		(start 185.55208 -98.516948)
		(end 185.20664 -98.171508)
		(width 0.127)
		(layer "In4.Cu")
		(net "RST_CPU1_BUF_R_N")
	)
	(segment
		(start 109.497876 -146.959574)
		(end 76.635102 -179.822348)
		(width 0.127)
		(layer "In4.Cu")
		(net "RST_CPU1_BUF_R_N")
	)
	(segment
		(start 147.22348 -128.717802)
		(end 144.827498 -131.113784)
		(width 0.127)
		(layer "In4.Cu")
		(net "RST_CPU1_BUF_R_N")
	)
	(segment
		(start 147.22348 -126.864872)
		(end 147.22348 -128.717802)
		(width 0.127)
		(layer "In4.Cu")
		(net "RST_CPU1_BUF_R_N")
	)
	(segment
		(start 53.903626 -190.490094)
		(end 55.077868 -191.664336)
		(width 0.127)
		(layer "In4.Cu")
		(net "RST_CPU1_BUF_R_N")
	)
	(segment
		(start 76.635102 -179.822348)
		(end 72.15251 -179.822348)
		(width 0.127)
		(layer "In4.Cu")
		(net "RST_CPU1_BUF_R_N")
	)
	(segment
		(start 70.95871 -181.016148)
		(end 68.199 -181.016148)
		(width 0.127)
		(layer "In4.Cu")
		(net "RST_CPU1_BUF_R_N")
	)
	(segment
		(start 52.558696 -190.490094)
		(end 53.903626 -190.490094)
		(width 0.127)
		(layer "In4.Cu")
		(net "RST_CPU1_BUF_R_N")
	)
	(segment
		(start 55.077868 -191.664336)
		(end 55.077868 -192.24371)
		(width 0.127)
		(layer "In4.Cu")
		(net "RST_CPU1_BUF_R_N")
	)
	(segment
		(start 49.61128 -187.542678)
		(end 52.558696 -190.490094)
		(width 0.127)
		(layer "In4.Cu")
		(net "RST_CPU1_BUF_R_N")
	)
	(segment
		(start 50.83175 -184.775348)
		(end 49.61128 -185.995818)
		(width 0.127)
		(layer "In4.Cu")
		(net "RST_CPU1_BUF_R_N")
	)
	(segment
		(start 49.61128 -185.995818)
		(end 49.61128 -187.542678)
		(width 0.127)
		(layer "In4.Cu")
		(net "RST_CPU1_BUF_R_N")
	)
	(segment
		(start 157.040326 -103.977948)
		(end 150.060406 -103.977948)
		(width 0.127)
		(layer "In4.Cu")
		(net "RST_CPU1_BUF_R_N")
	)
	(segment
		(start 67.577716 -181.637432)
		(end 66.55943 -181.637432)
		(width 0.127)
		(layer "In4.Cu")
		(net "RST_CPU1_BUF_R_N")
	)
	(segment
		(start 127.399796 -146.959574)
		(end 109.497876 -146.959574)
		(width 0.127)
		(layer "In4.Cu")
		(net "RST_CPU1_BUF_R_N")
	)
	(segment
		(start 143.245586 -131.113784)
		(end 127.399796 -146.959574)
		(width 0.127)
		(layer "In4.Cu")
		(net "RST_CPU1_BUF_R_N")
	)
	(segment
		(start 142.97406 -122.615452)
		(end 147.22348 -126.864872)
		(width 0.127)
		(layer "In4.Cu")
		(net "RST_CPU1_BUF_R_N")
	)
	(segment
		(start 186.23534 -100.698808)
		(end 185.55208 -100.015548)
		(width 0.127)
		(layer "In4.Cu")
		(net "RST_CPU1_BUF_R_N")
	)
	(segment
		(start 150.060406 -103.977948)
		(end 142.97406 -111.064294)
		(width 0.127)
		(layer "In4.Cu")
		(net "RST_CPU1_BUF_R_N")
	)
	(segment
		(start 142.97406 -111.064294)
		(end 142.97406 -122.615452)
		(width 0.127)
		(layer "In4.Cu")
		(net "RST_CPU1_BUF_R_N")
	)
	(segment
		(start 179.60467 -98.897948)
		(end 178.19751 -100.305108)
		(width 0.127)
		(layer "In4.Cu")
		(net "RST_CPU1_BUF_R_N")
	)
	(segment
		(start 72.15251 -179.822348)
		(end 70.95871 -181.016148)
		(width 0.127)
		(layer "In4.Cu")
		(net "RST_CPU1_BUF_R_N")
	)
	(segment
		(start 66.55943 -181.637432)
		(end 63.421514 -184.775348)
		(width 0.127)
		(layer "In4.Cu")
		(net "RST_CPU1_BUF_R_N")
	)
	(segment
		(start 180.148992 -98.897948)
		(end 179.60467 -98.897948)
		(width 0.127)
		(layer "In4.Cu")
		(net "RST_CPU1_BUF_R_N")
	)
	(segment
		(start 178.19751 -100.305108)
		(end 160.713166 -100.305108)
		(width 0.127)
		(layer "In4.Cu")
		(net "RST_CPU1_BUF_R_N")
	)
	(segment
		(start 63.421514 -184.775348)
		(end 50.83175 -184.775348)
		(width 0.127)
		(layer "In4.Cu")
		(net "RST_CPU1_BUF_R_N")
	)
	(segment
		(start 144.827498 -131.113784)
		(end 143.245586 -131.113784)
		(width 0.127)
		(layer "In4.Cu")
		(net "RST_CPU1_BUF_R_N")
	)
	(segment
		(start 185.20664 -98.171508)
		(end 180.875432 -98.171508)
		(width 0.127)
		(layer "In4.Cu")
		(net "RST_CPU1_BUF_R_N")
	)
	(segment
		(start 160.713166 -100.305108)
		(end 157.040326 -103.977948)
		(width 0.127)
		(layer "In4.Cu")
		(net "RST_CPU1_BUF_R_N")
	)
	(segment
		(start 188.50864 -100.698808)
		(end 186.23534 -100.698808)
		(width 0.127)
		(layer "In4.Cu")
		(net "RST_CPU1_BUF_R_N")
	)
	(segment
		(start 180.875432 -98.171508)
		(end 180.148992 -98.897948)
		(width 0.127)
		(layer "In4.Cu")
		(net "RST_CPU1_BUF_R_N")
	)
	(segment
		(start 185.55208 -100.015548)
		(end 185.55208 -98.516948)
		(width 0.127)
		(layer "In4.Cu")
		(net "RST_CPU1_BUF_R_N")
	)
	(segment
		(start 182.955692 -108.175552)
		(end 183.355742 -107.775502)
		(width 0.12954)
		(layer "F.Cu")
		(net "RST_CPU0_LVC1_R_N")
	)
	(segment
		(start 182.91048 -104.206294)
		(end 182.91048 -100.542598)
		(width 0.12954)
		(layer "F.Cu")
		(net "RST_CPU0_LVC1_R_N")
	)
	(segment
		(start 183.355742 -107.775502)
		(end 183.355742 -104.651556)
		(width 0.12954)
		(layer "F.Cu")
		(net "RST_CPU0_LVC1_R_N")
	)
	(segment
		(start 183.355742 -104.651556)
		(end 182.91048 -104.206294)
		(width 0.12954)
		(layer "F.Cu")
		(net "RST_CPU0_LVC1_R_N")
	)
	(segment
		(start 182.91048 -100.542598)
		(end 182.42788 -100.059998)
		(width 0.12954)
		(layer "F.Cu")
		(net "RST_CPU0_LVC1_R_N")
	)
	(via
		(at 183.355742 -107.775502)
		(size 0.4572)
		(drill 0.254)
		(layers "F.Cu" "B.Cu")
		(net "RST_CPU0_LVC1_R_N")
	)
	(via
		(at 183.355742 -106.967528)
		(size 0.6604)
		(drill 0.3302)
		(layers "F.Cu" "B.Cu")
		(net "RST_CPU0_LVC1_R_N")
	)
	(segment
		(start 185.13679 -104.491028)
		(end 183.60898 -104.491028)
		(width 0.12954)
		(layer "B.Cu")
		(net "RST_CPU0_LVC1_R_N")
	)
	(segment
		(start 183.355742 -106.967528)
		(end 183.355742 -107.775502)
		(width 0.12954)
		(layer "B.Cu")
		(net "RST_CPU0_LVC1_R_N")
	)
	(segment
		(start 183.355742 -104.744266)
		(end 183.355742 -106.967528)
		(width 0.12954)
		(layer "B.Cu")
		(net "RST_CPU0_LVC1_R_N")
	)
	(segment
		(start 183.60898 -104.491028)
		(end 183.355742 -104.744266)
		(width 0.12954)
		(layer "B.Cu")
		(net "RST_CPU0_LVC1_R_N")
	)
	(segment
		(start 354.991162 -265.313922)
		(end 354.991416 -265.314176)
		(width 0.12954)
		(layer "F.Cu")
		(net "RST_CPU0_LVC1_N")
	)
	(segment
		(start 354.991162 -264.778236)
		(end 354.991162 -265.313922)
		(width 0.12954)
		(layer "F.Cu")
		(net "RST_CPU0_LVC1_N")
	)
	(via
		(at 354.991416 -265.314176)
		(size 0.4572)
		(drill 0.2032)
		(layers "F.Cu" "B.Cu")
		(net "RST_CPU0_LVC1_N")
	)
	(via
		(at 321.147948 -266.293346)
		(size 0.6604)
		(drill 0.3302)
		(layers "F.Cu" "B.Cu")
		(net "RST_CPU0_LVC1_N")
	)
	(segment
		(start 340.156546 -262.37438)
		(end 340.141814 -262.383016)
		(width 0.0889)
		(layer "B.Cu")
		(net "RST_CPU0_LVC1_N")
	)
	(segment
		(start 299.683678 -264.01395)
		(end 298.538138 -264.01395)
		(width 0.12954)
		(layer "B.Cu")
		(net "RST_CPU0_LVC1_N")
	)
	(segment
		(start 331.972666 -262.307324)
		(end 329.101704 -265.178286)
		(width 0.12954)
		(layer "B.Cu")
		(net "RST_CPU0_LVC1_N")
	)
	(segment
		(start 311.220104 -267.67917)
		(end 307.489352 -267.67917)
		(width 0.12954)
		(layer "B.Cu")
		(net "RST_CPU0_LVC1_N")
	)
	(segment
		(start 341.096346 -262.37438)
		(end 341.081614 -262.383016)
		(width 0.0889)
		(layer "B.Cu")
		(net "RST_CPU0_LVC1_N")
	)
	(segment
		(start 352.162364 -264.702798)
		(end 352.162364 -264.408666)
		(width 0.0889)
		(layer "B.Cu")
		(net "RST_CPU0_LVC1_N")
	)
	(segment
		(start 350.364044 -262.610346)
		(end 349.419926 -262.610346)
		(width 0.0889)
		(layer "B.Cu")
		(net "RST_CPU0_LVC1_N")
	)
	(segment
		(start 336.195162 -262.433562)
		(end 334.76311 -262.433562)
		(width 0.0889)
		(layer "B.Cu")
		(net "RST_CPU0_LVC1_N")
	)
	(segment
		(start 346.735146 -262.37438)
		(end 346.720414 -262.383016)
		(width 0.0889)
		(layer "B.Cu")
		(net "RST_CPU0_LVC1_N")
	)
	(segment
		(start 302.604932 -266.51331)
		(end 302.183038 -266.51331)
		(width 0.12954)
		(layer "B.Cu")
		(net "RST_CPU0_LVC1_N")
	)
	(segment
		(start 352.162364 -264.408666)
		(end 350.364044 -262.610346)
		(width 0.0889)
		(layer "B.Cu")
		(net "RST_CPU0_LVC1_N")
	)
	(segment
		(start 334.504538 -262.307324)
		(end 331.972666 -262.307324)
		(width 0.12954)
		(layer "B.Cu")
		(net "RST_CPU0_LVC1_N")
	)
	(segment
		(start 322.538344 -266.293346)
		(end 321.147948 -266.293346)
		(width 0.12954)
		(layer "B.Cu")
		(net "RST_CPU0_LVC1_N")
	)
	(segment
		(start 339.212174 -262.37692)
		(end 339.20176 -262.383016)
		(width 0.0889)
		(layer "B.Cu")
		(net "RST_CPU0_LVC1_N")
	)
	(segment
		(start 342.036146 -262.37438)
		(end 342.021414 -262.383016)
		(width 0.0889)
		(layer "B.Cu")
		(net "RST_CPU0_LVC1_N")
	)
	(segment
		(start 354.991416 -265.314176)
		(end 354.362766 -264.840974)
		(width 0.0889)
		(layer "B.Cu")
		(net "RST_CPU0_LVC1_N")
	)
	(segment
		(start 353.394264 -264.824718)
		(end 353.379532 -264.816082)
		(width 0.0889)
		(layer "B.Cu")
		(net "RST_CPU0_LVC1_N")
	)
	(segment
		(start 307.489352 -267.67917)
		(end 307.215032 -267.40485)
		(width 0.12954)
		(layer "B.Cu")
		(net "RST_CPU0_LVC1_N")
	)
	(segment
		(start 329.101704 -265.178286)
		(end 323.653404 -265.178286)
		(width 0.12954)
		(layer "B.Cu")
		(net "RST_CPU0_LVC1_N")
	)
	(segment
		(start 342.975946 -262.37438)
		(end 342.961214 -262.383016)
		(width 0.0889)
		(layer "B.Cu")
		(net "RST_CPU0_LVC1_N")
	)
	(segment
		(start 352.284284 -264.824718)
		(end 352.162364 -264.702798)
		(width 0.0889)
		(layer "B.Cu")
		(net "RST_CPU0_LVC1_N")
	)
	(segment
		(start 334.76311 -262.433562)
		(end 334.636872 -262.307324)
		(width 0.0889)
		(layer "B.Cu")
		(net "RST_CPU0_LVC1_N")
	)
	(segment
		(start 303.496472 -267.40485)
		(end 302.604932 -266.51331)
		(width 0.12954)
		(layer "B.Cu")
		(net "RST_CPU0_LVC1_N")
	)
	(segment
		(start 302.183038 -266.51331)
		(end 299.683678 -264.01395)
		(width 0.12954)
		(layer "B.Cu")
		(net "RST_CPU0_LVC1_N")
	)
	(segment
		(start 298.34205 -263.817862)
		(end 298.34205 -259.171948)
		(width 0.12954)
		(layer "B.Cu")
		(net "RST_CPU0_LVC1_N")
	)
	(segment
		(start 334.636872 -262.307324)
		(end 334.504538 -262.307324)
		(width 0.0889)
		(layer "B.Cu")
		(net "RST_CPU0_LVC1_N")
	)
	(segment
		(start 354.334064 -264.824718)
		(end 354.33381 -264.824718)
		(width 0.0889)
		(layer "B.Cu")
		(net "RST_CPU0_LVC1_N")
	)
	(segment
		(start 298.538138 -264.01395)
		(end 298.34205 -263.817862)
		(width 0.12954)
		(layer "B.Cu")
		(net "RST_CPU0_LVC1_N")
	)
	(segment
		(start 349.419926 -262.610346)
		(end 349.282258 -262.472678)
		(width 0.0889)
		(layer "B.Cu")
		(net "RST_CPU0_LVC1_N")
	)
	(segment
		(start 338.827364 -262.383016)
		(end 338.812632 -262.37438)
		(width 0.0889)
		(layer "B.Cu")
		(net "RST_CPU0_LVC1_N")
	)
	(segment
		(start 343.915746 -262.37438)
		(end 343.901014 -262.383016)
		(width 0.0889)
		(layer "B.Cu")
		(net "RST_CPU0_LVC1_N")
	)
	(segment
		(start 352.454464 -264.824718)
		(end 352.284284 -264.824718)
		(width 0.0889)
		(layer "B.Cu")
		(net "RST_CPU0_LVC1_N")
	)
	(segment
		(start 316.713616 -266.293346)
		(end 315.591952 -267.41501)
		(width 0.12954)
		(layer "B.Cu")
		(net "RST_CPU0_LVC1_N")
	)
	(segment
		(start 323.653404 -265.178286)
		(end 322.538344 -266.293346)
		(width 0.12954)
		(layer "B.Cu")
		(net "RST_CPU0_LVC1_N")
	)
	(segment
		(start 321.147948 -266.293346)
		(end 316.713616 -266.293346)
		(width 0.12954)
		(layer "B.Cu")
		(net "RST_CPU0_LVC1_N")
	)
	(segment
		(start 345.405964 -262.383016)
		(end 345.39555 -262.37692)
		(width 0.0889)
		(layer "B.Cu")
		(net "RST_CPU0_LVC1_N")
	)
	(segment
		(start 345.790774 -262.37692)
		(end 345.78036 -262.383016)
		(width 0.0889)
		(layer "B.Cu")
		(net "RST_CPU0_LVC1_N")
	)
	(segment
		(start 315.591952 -267.41501)
		(end 311.484264 -267.41501)
		(width 0.12954)
		(layer "B.Cu")
		(net "RST_CPU0_LVC1_N")
	)
	(segment
		(start 337.332828 -262.37692)
		(end 337.322414 -262.383016)
		(width 0.0889)
		(layer "B.Cu")
		(net "RST_CPU0_LVC1_N")
	)
	(segment
		(start 348.614746 -262.37438)
		(end 348.600014 -262.383016)
		(width 0.0889)
		(layer "B.Cu")
		(net "RST_CPU0_LVC1_N")
	)
	(segment
		(start 307.215032 -267.40485)
		(end 303.496472 -267.40485)
		(width 0.12954)
		(layer "B.Cu")
		(net "RST_CPU0_LVC1_N")
	)
	(segment
		(start 347.674946 -262.37438)
		(end 347.660214 -262.383016)
		(width 0.0889)
		(layer "B.Cu")
		(net "RST_CPU0_LVC1_N")
	)
	(segment
		(start 311.484264 -267.41501)
		(end 311.220104 -267.67917)
		(width 0.12954)
		(layer "B.Cu")
		(net "RST_CPU0_LVC1_N")
	)
	(segment
		(start 354.362766 -264.840974)
		(end 354.334064 -264.824718)
		(width 0.0889)
		(layer "B.Cu")
		(net "RST_CPU0_LVC1_N")
	)
	(arc
		(start 347.660214 -262.383016)
		(mid 347.473016 -262.433159)
		(end 347.285818 -262.383016)
		(width 0.0889)
		(layer "B.Cu")
		(net "RST_CPU0_LVC1_N")
	)
	(arc
		(start 349.165418 -262.383016)
		(mid 348.891219 -262.307181)
		(end 348.614746 -262.37438)
		(width 0.0889)
		(layer "B.Cu")
		(net "RST_CPU0_LVC1_N")
	)
	(arc
		(start 342.021414 -262.383016)
		(mid 341.834216 -262.433159)
		(end 341.647018 -262.383016)
		(width 0.0889)
		(layer "B.Cu")
		(net "RST_CPU0_LVC1_N")
	)
	(arc
		(start 343.901014 -262.383016)
		(mid 343.713816 -262.433159)
		(end 343.526618 -262.383016)
		(width 0.0889)
		(layer "B.Cu")
		(net "RST_CPU0_LVC1_N")
	)
	(arc
		(start 341.647018 -262.383016)
		(mid 341.372819 -262.307181)
		(end 341.096346 -262.37438)
		(width 0.0889)
		(layer "B.Cu")
		(net "RST_CPU0_LVC1_N")
	)
	(arc
		(start 336.392774 -262.37692)
		(mid 336.29793 -262.419071)
		(end 336.195162 -262.433562)
		(width 0.0889)
		(layer "B.Cu")
		(net "RST_CPU0_LVC1_N")
	)
	(arc
		(start 338.812632 -262.37438)
		(mid 338.536157 -262.30706)
		(end 338.26196 -262.383016)
		(width 0.0889)
		(layer "B.Cu")
		(net "RST_CPU0_LVC1_N")
	)
	(arc
		(start 348.225618 -262.383016)
		(mid 347.951419 -262.307181)
		(end 347.674946 -262.37438)
		(width 0.0889)
		(layer "B.Cu")
		(net "RST_CPU0_LVC1_N")
	)
	(arc
		(start 354.33381 -264.824718)
		(mid 354.051252 -264.749069)
		(end 353.76866 -264.824718)
		(width 0.0889)
		(layer "B.Cu")
		(net "RST_CPU0_LVC1_N")
	)
	(arc
		(start 345.39555 -262.37692)
		(mid 345.117372 -262.307197)
		(end 344.840814 -262.383016)
		(width 0.0889)
		(layer "B.Cu")
		(net "RST_CPU0_LVC1_N")
	)
	(arc
		(start 353.379532 -264.816082)
		(mid 353.103057 -264.748762)
		(end 352.82886 -264.824718)
		(width 0.0889)
		(layer "B.Cu")
		(net "RST_CPU0_LVC1_N")
	)
	(arc
		(start 341.081614 -262.383016)
		(mid 340.894416 -262.433159)
		(end 340.707218 -262.383016)
		(width 0.0889)
		(layer "B.Cu")
		(net "RST_CPU0_LVC1_N")
	)
	(arc
		(start 346.720414 -262.383016)
		(mid 346.533216 -262.433159)
		(end 346.346018 -262.383016)
		(width 0.0889)
		(layer "B.Cu")
		(net "RST_CPU0_LVC1_N")
	)
	(arc
		(start 347.285818 -262.383016)
		(mid 347.011619 -262.307181)
		(end 346.735146 -262.37438)
		(width 0.0889)
		(layer "B.Cu")
		(net "RST_CPU0_LVC1_N")
	)
	(arc
		(start 337.322414 -262.383016)
		(mid 337.135216 -262.433159)
		(end 336.948018 -262.383016)
		(width 0.0889)
		(layer "B.Cu")
		(net "RST_CPU0_LVC1_N")
	)
	(arc
		(start 340.707218 -262.383016)
		(mid 340.433019 -262.307181)
		(end 340.156546 -262.37438)
		(width 0.0889)
		(layer "B.Cu")
		(net "RST_CPU0_LVC1_N")
	)
	(arc
		(start 345.78036 -262.383016)
		(mid 345.593162 -262.433159)
		(end 345.405964 -262.383016)
		(width 0.0889)
		(layer "B.Cu")
		(net "RST_CPU0_LVC1_N")
	)
	(arc
		(start 339.767418 -262.383016)
		(mid 339.490605 -262.307146)
		(end 339.212174 -262.37692)
		(width 0.0889)
		(layer "B.Cu")
		(net "RST_CPU0_LVC1_N")
	)
	(arc
		(start 336.948018 -262.383016)
		(mid 336.671205 -262.307146)
		(end 336.392774 -262.37692)
		(width 0.0889)
		(layer "B.Cu")
		(net "RST_CPU0_LVC1_N")
	)
	(arc
		(start 338.26196 -262.383016)
		(mid 338.074762 -262.433159)
		(end 337.887564 -262.383016)
		(width 0.0889)
		(layer "B.Cu")
		(net "RST_CPU0_LVC1_N")
	)
	(arc
		(start 348.600014 -262.383016)
		(mid 348.412816 -262.433159)
		(end 348.225618 -262.383016)
		(width 0.0889)
		(layer "B.Cu")
		(net "RST_CPU0_LVC1_N")
	)
	(arc
		(start 344.840814 -262.383016)
		(mid 344.653616 -262.433159)
		(end 344.466418 -262.383016)
		(width 0.0889)
		(layer "B.Cu")
		(net "RST_CPU0_LVC1_N")
	)
	(arc
		(start 342.586818 -262.383016)
		(mid 342.312619 -262.307181)
		(end 342.036146 -262.37438)
		(width 0.0889)
		(layer "B.Cu")
		(net "RST_CPU0_LVC1_N")
	)
	(arc
		(start 342.961214 -262.383016)
		(mid 342.774016 -262.433159)
		(end 342.586818 -262.383016)
		(width 0.0889)
		(layer "B.Cu")
		(net "RST_CPU0_LVC1_N")
	)
	(arc
		(start 353.76866 -264.824718)
		(mid 353.581462 -264.874861)
		(end 353.394264 -264.824718)
		(width 0.0889)
		(layer "B.Cu")
		(net "RST_CPU0_LVC1_N")
	)
	(arc
		(start 352.82886 -264.824718)
		(mid 352.641662 -264.874861)
		(end 352.454464 -264.824718)
		(width 0.0889)
		(layer "B.Cu")
		(net "RST_CPU0_LVC1_N")
	)
	(arc
		(start 343.526618 -262.383016)
		(mid 343.252419 -262.307181)
		(end 342.975946 -262.37438)
		(width 0.0889)
		(layer "B.Cu")
		(net "RST_CPU0_LVC1_N")
	)
	(arc
		(start 337.887564 -262.383016)
		(mid 337.611005 -262.307273)
		(end 337.332828 -262.37692)
		(width 0.0889)
		(layer "B.Cu")
		(net "RST_CPU0_LVC1_N")
	)
	(arc
		(start 344.466418 -262.383016)
		(mid 344.192219 -262.307181)
		(end 343.915746 -262.37438)
		(width 0.0889)
		(layer "B.Cu")
		(net "RST_CPU0_LVC1_N")
	)
	(arc
		(start 349.282258 -262.472678)
		(mid 349.22678 -262.424011)
		(end 349.165418 -262.383016)
		(width 0.0889)
		(layer "B.Cu")
		(net "RST_CPU0_LVC1_N")
	)
	(arc
		(start 346.346018 -262.383016)
		(mid 346.069205 -262.307146)
		(end 345.790774 -262.37692)
		(width 0.0889)
		(layer "B.Cu")
		(net "RST_CPU0_LVC1_N")
	)
	(arc
		(start 340.141814 -262.383016)
		(mid 339.954616 -262.433159)
		(end 339.767418 -262.383016)
		(width 0.0889)
		(layer "B.Cu")
		(net "RST_CPU0_LVC1_N")
	)
	(arc
		(start 339.20176 -262.383016)
		(mid 339.014562 -262.433159)
		(end 338.827364 -262.383016)
		(width 0.0889)
		(layer "B.Cu")
		(net "RST_CPU0_LVC1_N")
	)
	(segment
		(start 117.22608 -119.446548)
		(end 117.22608 -118.068598)
		(width 0.12954)
		(layer "F.Cu")
		(net "RST_CPU0_DRAM_GH_PLD_N")
	)
	(segment
		(start 117.22608 -118.068598)
		(end 115.960906 -116.803424)
		(width 0.12954)
		(layer "F.Cu")
		(net "RST_CPU0_DRAM_GH_PLD_N")
	)
	(segment
		(start 115.960906 -116.803424)
		(end 115.960906 -116.078762)
		(width 0.12954)
		(layer "F.Cu")
		(net "RST_CPU0_DRAM_GH_PLD_N")
	)
	(via
		(at 117.22608 -118.068598)
		(size 0.762)
		(drill 0.381)
		(layers "F.Cu" "B.Cu")
		(net "RST_CPU0_DRAM_GH_PLD_N")
	)
	(segment
		(start 117.22608 -120.989598)
		(end 117.22608 -120.246648)
		(width 0.12954)
		(layer "F.Cu")
		(net "RST_CPU0_DRAM_GH_N")
	)
	(segment
		(start 370.027962 -259.894832)
		(end 370.027962 -260.430518)
		(width 0.12954)
		(layer "F.Cu")
		(net "RST_CPU0_DRAM_GH_N")
	)
	(segment
		(start 117.22608 -121.732548)
		(end 117.22608 -120.989598)
		(width 0.12954)
		(layer "F.Cu")
		(net "RST_CPU0_DRAM_GH_N")
	)
	(segment
		(start 370.027962 -260.430518)
		(end 370.028216 -260.430772)
		(width 0.12954)
		(layer "F.Cu")
		(net "RST_CPU0_DRAM_GH_N")
	)
	(via
		(at 387.712458 -259.02539)
		(size 0.6604)
		(drill 0.3302)
		(layers "F.Cu" "B.Cu")
		(net "RST_CPU0_DRAM_GH_N")
	)
	(via
		(at 249.10288 -130.139948)
		(size 0.508)
		(drill 0.254)
		(layers "F.Cu" "B.Cu")
		(net "RST_CPU0_DRAM_GH_N")
	)
	(via
		(at 370.028216 -260.430772)
		(size 0.4572)
		(drill 0.2032)
		(layers "F.Cu" "B.Cu")
		(net "RST_CPU0_DRAM_GH_N")
	)
	(via
		(at 117.22608 -120.989598)
		(size 0.508)
		(drill 0.254)
		(layers "F.Cu" "B.Cu")
		(net "RST_CPU0_DRAM_GH_N")
	)
	(segment
		(start 250.335542 -128.907286)
		(end 249.10288 -130.139948)
		(width 0.12954)
		(layer "B.Cu")
		(net "RST_CPU0_DRAM_GH_N")
	)
	(segment
		(start 392.694668 -179.967636)
		(end 383.920238 -171.193206)
		(width 0.12954)
		(layer "B.Cu")
		(net "RST_CPU0_DRAM_GH_N")
	)
	(segment
		(start 380.15672 -163.33089)
		(end 380.15672 -157.884368)
		(width 0.12954)
		(layer "B.Cu")
		(net "RST_CPU0_DRAM_GH_N")
	)
	(segment
		(start 377.29795 -260.031738)
		(end 377.311412 -260.023864)
		(width 0.12954)
		(layer "B.Cu")
		(net "RST_CPU0_DRAM_GH_N")
	)
	(segment
		(start 404.769828 -196.97446)
		(end 403.14118 -195.345812)
		(width 0.12954)
		(layer "B.Cu")
		(net "RST_CPU0_DRAM_GH_N")
	)
	(segment
		(start 371.65915 -260.031738)
		(end 371.672612 -260.023864)
		(width 0.12954)
		(layer "B.Cu")
		(net "RST_CPU0_DRAM_GH_N")
	)
	(segment
		(start 403.14118 -195.345812)
		(end 403.14118 -190.086488)
		(width 0.12954)
		(layer "B.Cu")
		(net "RST_CPU0_DRAM_GH_N")
	)
	(segment
		(start 383.920238 -167.094408)
		(end 380.15672 -163.33089)
		(width 0.12954)
		(layer "B.Cu")
		(net "RST_CPU0_DRAM_GH_N")
	)
	(segment
		(start 381.05715 -260.031738)
		(end 381.070612 -260.023864)
		(width 0.12954)
		(layer "B.Cu")
		(net "RST_CPU0_DRAM_GH_N")
	)
	(segment
		(start 356.49154 -153.015188)
		(end 345.44508 -141.968728)
		(width 0.12954)
		(layer "B.Cu")
		(net "RST_CPU0_DRAM_GH_N")
	)
	(segment
		(start 345.44508 -141.968728)
		(end 333.37754 -141.968728)
		(width 0.12954)
		(layer "B.Cu")
		(net "RST_CPU0_DRAM_GH_N")
	)
	(segment
		(start 380.11735 -260.031738)
		(end 380.130812 -260.023864)
		(width 0.12954)
		(layer "B.Cu")
		(net "RST_CPU0_DRAM_GH_N")
	)
	(segment
		(start 382.93675 -260.031738)
		(end 382.950212 -260.023864)
		(width 0.12954)
		(layer "B.Cu")
		(net "RST_CPU0_DRAM_GH_N")
	)
	(segment
		(start 379.17755 -260.031738)
		(end 379.191012 -260.023864)
		(width 0.12954)
		(layer "B.Cu")
		(net "RST_CPU0_DRAM_GH_N")
	)
	(segment
		(start 375.28754 -153.015188)
		(end 356.49154 -153.015188)
		(width 0.12954)
		(layer "B.Cu")
		(net "RST_CPU0_DRAM_GH_N")
	)
	(segment
		(start 393.739116 -181.530244)
		(end 392.694668 -179.967636)
		(width 0.12954)
		(layer "B.Cu")
		(net "RST_CPU0_DRAM_GH_N")
	)
	(segment
		(start 400.97964 -187.924948)
		(end 396.65148 -187.924948)
		(width 0.12954)
		(layer "B.Cu")
		(net "RST_CPU0_DRAM_GH_N")
	)
	(segment
		(start 388.300214 -258.437634)
		(end 388.300214 -251.208794)
		(width 0.12954)
		(layer "B.Cu")
		(net "RST_CPU0_DRAM_GH_N")
	)
	(segment
		(start 384.453638 -260.040628)
		(end 385.039108 -259.455158)
		(width 0.12954)
		(layer "B.Cu")
		(net "RST_CPU0_DRAM_GH_N")
	)
	(segment
		(start 404.769828 -197.43166)
		(end 404.769828 -196.97446)
		(width 0.12954)
		(layer "B.Cu")
		(net "RST_CPU0_DRAM_GH_N")
	)
	(segment
		(start 403.14118 -190.086488)
		(end 400.97964 -187.924948)
		(width 0.12954)
		(layer "B.Cu")
		(net "RST_CPU0_DRAM_GH_N")
	)
	(segment
		(start 279.609296 -130.216148)
		(end 276.640036 -127.246888)
		(width 0.12954)
		(layer "B.Cu")
		(net "RST_CPU0_DRAM_GH_N")
	)
	(segment
		(start 303.28108 -130.216148)
		(end 279.609296 -130.216148)
		(width 0.12954)
		(layer "B.Cu")
		(net "RST_CPU0_DRAM_GH_N")
	)
	(segment
		(start 257.879088 -127.246888)
		(end 256.21869 -128.907286)
		(width 0.12954)
		(layer "B.Cu")
		(net "RST_CPU0_DRAM_GH_N")
	)
	(segment
		(start 402.609558 -236.89945)
		(end 405.621998 -236.89945)
		(width 0.12954)
		(layer "B.Cu")
		(net "RST_CPU0_DRAM_GH_N")
	)
	(segment
		(start 333.37754 -141.968728)
		(end 318.621664 -135.856726)
		(width 0.12954)
		(layer "B.Cu")
		(net "RST_CPU0_DRAM_GH_N")
	)
	(segment
		(start 406.094184 -236.427264)
		(end 406.094184 -198.756016)
		(width 0.12954)
		(layer "B.Cu")
		(net "RST_CPU0_DRAM_GH_N")
	)
	(segment
		(start 375.41835 -260.031738)
		(end 375.431812 -260.023864)
		(width 0.12954)
		(layer "B.Cu")
		(net "RST_CPU0_DRAM_GH_N")
	)
	(segment
		(start 396.201392 -187.47486)
		(end 393.739116 -181.530244)
		(width 0.12954)
		(layer "B.Cu")
		(net "RST_CPU0_DRAM_GH_N")
	)
	(segment
		(start 380.15672 -157.884368)
		(end 375.28754 -153.015188)
		(width 0.12954)
		(layer "B.Cu")
		(net "RST_CPU0_DRAM_GH_N")
	)
	(segment
		(start 383.56413 -260.040628)
		(end 384.453638 -260.040628)
		(width 0.12954)
		(layer "B.Cu")
		(net "RST_CPU0_DRAM_GH_N")
	)
	(segment
		(start 387.28269 -259.455158)
		(end 387.712458 -259.02539)
		(width 0.12954)
		(layer "B.Cu")
		(net "RST_CPU0_DRAM_GH_N")
	)
	(segment
		(start 276.640036 -127.246888)
		(end 257.879088 -127.246888)
		(width 0.12954)
		(layer "B.Cu")
		(net "RST_CPU0_DRAM_GH_N")
	)
	(segment
		(start 383.920238 -171.193206)
		(end 383.920238 -167.094408)
		(width 0.12954)
		(layer "B.Cu")
		(net "RST_CPU0_DRAM_GH_N")
	)
	(segment
		(start 318.621664 -135.856726)
		(end 308.921658 -135.856726)
		(width 0.12954)
		(layer "B.Cu")
		(net "RST_CPU0_DRAM_GH_N")
	)
	(segment
		(start 372.59895 -260.031738)
		(end 372.612412 -260.023864)
		(width 0.12954)
		(layer "B.Cu")
		(net "RST_CPU0_DRAM_GH_N")
	)
	(segment
		(start 308.921658 -135.856726)
		(end 303.28108 -130.216148)
		(width 0.12954)
		(layer "B.Cu")
		(net "RST_CPU0_DRAM_GH_N")
	)
	(segment
		(start 387.712458 -259.02539)
		(end 388.300214 -258.437634)
		(width 0.12954)
		(layer "B.Cu")
		(net "RST_CPU0_DRAM_GH_N")
	)
	(segment
		(start 376.35815 -260.031738)
		(end 376.371612 -260.023864)
		(width 0.12954)
		(layer "B.Cu")
		(net "RST_CPU0_DRAM_GH_N")
	)
	(segment
		(start 405.621998 -236.89945)
		(end 406.094184 -236.427264)
		(width 0.12954)
		(layer "B.Cu")
		(net "RST_CPU0_DRAM_GH_N")
	)
	(segment
		(start 256.21869 -128.907286)
		(end 250.335542 -128.907286)
		(width 0.12954)
		(layer "B.Cu")
		(net "RST_CPU0_DRAM_GH_N")
	)
	(segment
		(start 381.99695 -260.031738)
		(end 382.010412 -260.023864)
		(width 0.12954)
		(layer "B.Cu")
		(net "RST_CPU0_DRAM_GH_N")
	)
	(segment
		(start 373.53875 -260.031738)
		(end 373.552212 -260.023864)
		(width 0.12954)
		(layer "B.Cu")
		(net "RST_CPU0_DRAM_GH_N")
	)
	(segment
		(start 396.65148 -187.924948)
		(end 396.201392 -187.47486)
		(width 0.12954)
		(layer "B.Cu")
		(net "RST_CPU0_DRAM_GH_N")
	)
	(segment
		(start 385.039108 -259.455158)
		(end 387.28269 -259.455158)
		(width 0.12954)
		(layer "B.Cu")
		(net "RST_CPU0_DRAM_GH_N")
	)
	(segment
		(start 378.23775 -260.031738)
		(end 378.251212 -260.023864)
		(width 0.12954)
		(layer "B.Cu")
		(net "RST_CPU0_DRAM_GH_N")
	)
	(segment
		(start 374.47855 -260.031738)
		(end 374.492012 -260.023864)
		(width 0.12954)
		(layer "B.Cu")
		(net "RST_CPU0_DRAM_GH_N")
	)
	(segment
		(start 388.300214 -251.208794)
		(end 402.609558 -236.89945)
		(width 0.12954)
		(layer "B.Cu")
		(net "RST_CPU0_DRAM_GH_N")
	)
	(segment
		(start 406.094184 -198.756016)
		(end 404.769828 -197.43166)
		(width 0.12954)
		(layer "B.Cu")
		(net "RST_CPU0_DRAM_GH_N")
	)
	(arc
		(start 379.660912 -260.023864)
		(mid 379.888099 -260.086882)
		(end 380.11735 -260.031738)
		(width 0.12954)
		(layer "B.Cu")
		(net "RST_CPU0_DRAM_GH_N")
	)
	(arc
		(start 382.950212 -260.023864)
		(mid 383.159661 -259.961597)
		(end 383.374646 -260.00075)
		(width 0.12954)
		(layer "B.Cu")
		(net "RST_CPU0_DRAM_GH_N")
	)
	(arc
		(start 376.841512 -260.023864)
		(mid 377.068699 -260.086882)
		(end 377.29795 -260.031738)
		(width 0.12954)
		(layer "B.Cu")
		(net "RST_CPU0_DRAM_GH_N")
	)
	(arc
		(start 380.600712 -260.023864)
		(mid 380.827899 -260.086882)
		(end 381.05715 -260.031738)
		(width 0.12954)
		(layer "B.Cu")
		(net "RST_CPU0_DRAM_GH_N")
	)
	(arc
		(start 373.082312 -260.023864)
		(mid 373.309499 -260.086882)
		(end 373.53875 -260.031738)
		(width 0.12954)
		(layer "B.Cu")
		(net "RST_CPU0_DRAM_GH_N")
	)
	(arc
		(start 370.028216 -260.430772)
		(mid 370.381702 -260.322393)
		(end 370.677694 -260.100826)
		(width 0.12954)
		(layer "B.Cu")
		(net "RST_CPU0_DRAM_GH_N")
	)
	(arc
		(start 381.540512 -260.023864)
		(mid 381.767699 -260.086882)
		(end 381.99695 -260.031738)
		(width 0.12954)
		(layer "B.Cu")
		(net "RST_CPU0_DRAM_GH_N")
	)
	(arc
		(start 377.781312 -260.023864)
		(mid 378.008499 -260.086882)
		(end 378.23775 -260.031738)
		(width 0.12954)
		(layer "B.Cu")
		(net "RST_CPU0_DRAM_GH_N")
	)
	(arc
		(start 371.202712 -260.023864)
		(mid 371.429899 -260.086882)
		(end 371.65915 -260.031738)
		(width 0.12954)
		(layer "B.Cu")
		(net "RST_CPU0_DRAM_GH_N")
	)
	(arc
		(start 372.612412 -260.023864)
		(mid 372.847362 -259.960904)
		(end 373.082312 -260.023864)
		(width 0.12954)
		(layer "B.Cu")
		(net "RST_CPU0_DRAM_GH_N")
	)
	(arc
		(start 379.191012 -260.023864)
		(mid 379.425962 -259.960904)
		(end 379.660912 -260.023864)
		(width 0.12954)
		(layer "B.Cu")
		(net "RST_CPU0_DRAM_GH_N")
	)
	(arc
		(start 378.251212 -260.023864)
		(mid 378.486162 -259.960904)
		(end 378.721112 -260.023864)
		(width 0.12954)
		(layer "B.Cu")
		(net "RST_CPU0_DRAM_GH_N")
	)
	(arc
		(start 374.961912 -260.023864)
		(mid 375.189099 -260.086882)
		(end 375.41835 -260.031738)
		(width 0.12954)
		(layer "B.Cu")
		(net "RST_CPU0_DRAM_GH_N")
	)
	(arc
		(start 374.022112 -260.023864)
		(mid 374.249299 -260.086882)
		(end 374.47855 -260.031738)
		(width 0.12954)
		(layer "B.Cu")
		(net "RST_CPU0_DRAM_GH_N")
	)
	(arc
		(start 380.130812 -260.023864)
		(mid 380.365762 -259.960904)
		(end 380.600712 -260.023864)
		(width 0.12954)
		(layer "B.Cu")
		(net "RST_CPU0_DRAM_GH_N")
	)
	(arc
		(start 371.672612 -260.023864)
		(mid 371.907562 -259.960904)
		(end 372.142512 -260.023864)
		(width 0.12954)
		(layer "B.Cu")
		(net "RST_CPU0_DRAM_GH_N")
	)
	(arc
		(start 375.901712 -260.023864)
		(mid 376.128899 -260.086882)
		(end 376.35815 -260.031738)
		(width 0.12954)
		(layer "B.Cu")
		(net "RST_CPU0_DRAM_GH_N")
	)
	(arc
		(start 377.311412 -260.023864)
		(mid 377.546362 -259.960904)
		(end 377.781312 -260.023864)
		(width 0.12954)
		(layer "B.Cu")
		(net "RST_CPU0_DRAM_GH_N")
	)
	(arc
		(start 374.492012 -260.023864)
		(mid 374.726962 -259.960904)
		(end 374.961912 -260.023864)
		(width 0.12954)
		(layer "B.Cu")
		(net "RST_CPU0_DRAM_GH_N")
	)
	(arc
		(start 375.431812 -260.023864)
		(mid 375.666762 -259.960904)
		(end 375.901712 -260.023864)
		(width 0.12954)
		(layer "B.Cu")
		(net "RST_CPU0_DRAM_GH_N")
	)
	(arc
		(start 382.480312 -260.023864)
		(mid 382.707499 -260.086882)
		(end 382.93675 -260.031738)
		(width 0.12954)
		(layer "B.Cu")
		(net "RST_CPU0_DRAM_GH_N")
	)
	(arc
		(start 381.070612 -260.023864)
		(mid 381.305562 -259.960904)
		(end 381.540512 -260.023864)
		(width 0.12954)
		(layer "B.Cu")
		(net "RST_CPU0_DRAM_GH_N")
	)
	(arc
		(start 378.721112 -260.023864)
		(mid 378.948299 -260.086882)
		(end 379.17755 -260.031738)
		(width 0.12954)
		(layer "B.Cu")
		(net "RST_CPU0_DRAM_GH_N")
	)
	(arc
		(start 372.142512 -260.023864)
		(mid 372.369699 -260.086882)
		(end 372.59895 -260.031738)
		(width 0.12954)
		(layer "B.Cu")
		(net "RST_CPU0_DRAM_GH_N")
	)
	(arc
		(start 370.677694 -260.100826)
		(mid 370.926819 -259.970995)
		(end 371.202712 -260.023864)
		(width 0.12954)
		(layer "B.Cu")
		(net "RST_CPU0_DRAM_GH_N")
	)
	(arc
		(start 383.374646 -260.00075)
		(mid 383.467311 -260.030564)
		(end 383.56413 -260.040628)
		(width 0.12954)
		(layer "B.Cu")
		(net "RST_CPU0_DRAM_GH_N")
	)
	(arc
		(start 382.010412 -260.023864)
		(mid 382.245362 -259.960904)
		(end 382.480312 -260.023864)
		(width 0.12954)
		(layer "B.Cu")
		(net "RST_CPU0_DRAM_GH_N")
	)
	(arc
		(start 376.371612 -260.023864)
		(mid 376.606562 -259.960904)
		(end 376.841512 -260.023864)
		(width 0.12954)
		(layer "B.Cu")
		(net "RST_CPU0_DRAM_GH_N")
	)
	(arc
		(start 373.552212 -260.023864)
		(mid 373.787162 -259.960904)
		(end 374.022112 -260.023864)
		(width 0.12954)
		(layer "B.Cu")
		(net "RST_CPU0_DRAM_GH_N")
	)
	(segment
		(start 234.5182 -132.687568)
		(end 232.95864 -134.247128)
		(width 0.127)
		(layer "In6.Cu")
		(net "RST_CPU0_DRAM_GH_N")
	)
	(segment
		(start 117.49024 -122.523758)
		(end 117.22608 -122.259598)
		(width 0.127)
		(layer "In6.Cu")
		(net "RST_CPU0_DRAM_GH_N")
	)
	(segment
		(start 189.0268 -134.242048)
		(end 188.699648 -134.5692)
		(width 0.127)
		(layer "In6.Cu")
		(net "RST_CPU0_DRAM_GH_N")
	)
	(segment
		(start 118.47449 -123.712478)
		(end 118.47449 -122.912378)
		(width 0.127)
		(layer "In6.Cu")
		(net "RST_CPU0_DRAM_GH_N")
	)
	(segment
		(start 122.54484 -127.782828)
		(end 118.47449 -123.712478)
		(width 0.127)
		(layer "In6.Cu")
		(net "RST_CPU0_DRAM_GH_N")
	)
	(segment
		(start 224.700084 -135.118348)
		(end 201.452734 -135.118348)
		(width 0.127)
		(layer "In6.Cu")
		(net "RST_CPU0_DRAM_GH_N")
	)
	(segment
		(start 137.84834 -132.357368)
		(end 137.84834 -131.971034)
		(width 0.127)
		(layer "In6.Cu")
		(net "RST_CPU0_DRAM_GH_N")
	)
	(segment
		(start 134.442962 -128.09982)
		(end 134.12597 -127.782828)
		(width 0.127)
		(layer "In6.Cu")
		(net "RST_CPU0_DRAM_GH_N")
	)
	(segment
		(start 200.576434 -134.242048)
		(end 189.0268 -134.242048)
		(width 0.127)
		(layer "In6.Cu")
		(net "RST_CPU0_DRAM_GH_N")
	)
	(segment
		(start 168.295574 -135.009128)
		(end 140.5001 -135.009128)
		(width 0.127)
		(layer "In6.Cu")
		(net "RST_CPU0_DRAM_GH_N")
	)
	(segment
		(start 184.741312 -134.816088)
		(end 181.61254 -134.816088)
		(width 0.127)
		(layer "In6.Cu")
		(net "RST_CPU0_DRAM_GH_N")
	)
	(segment
		(start 118.47449 -122.912378)
		(end 118.08587 -122.523758)
		(width 0.127)
		(layer "In6.Cu")
		(net "RST_CPU0_DRAM_GH_N")
	)
	(segment
		(start 184.9882 -134.5692)
		(end 184.741312 -134.816088)
		(width 0.127)
		(layer "In6.Cu")
		(net "RST_CPU0_DRAM_GH_N")
	)
	(segment
		(start 237.590076 -133.387084)
		(end 236.89056 -132.687568)
		(width 0.127)
		(layer "In6.Cu")
		(net "RST_CPU0_DRAM_GH_N")
	)
	(segment
		(start 168.759632 -134.54507)
		(end 168.295574 -135.009128)
		(width 0.127)
		(layer "In6.Cu")
		(net "RST_CPU0_DRAM_GH_N")
	)
	(segment
		(start 118.08587 -122.523758)
		(end 117.49024 -122.523758)
		(width 0.127)
		(layer "In6.Cu")
		(net "RST_CPU0_DRAM_GH_N")
	)
	(segment
		(start 236.89056 -132.687568)
		(end 234.5182 -132.687568)
		(width 0.127)
		(layer "In6.Cu")
		(net "RST_CPU0_DRAM_GH_N")
	)
	(segment
		(start 134.442962 -128.565656)
		(end 134.442962 -128.09982)
		(width 0.127)
		(layer "In6.Cu")
		(net "RST_CPU0_DRAM_GH_N")
	)
	(segment
		(start 201.452734 -135.118348)
		(end 200.576434 -134.242048)
		(width 0.127)
		(layer "In6.Cu")
		(net "RST_CPU0_DRAM_GH_N")
	)
	(segment
		(start 232.95864 -134.247128)
		(end 225.571304 -134.247128)
		(width 0.127)
		(layer "In6.Cu")
		(net "RST_CPU0_DRAM_GH_N")
	)
	(segment
		(start 188.699648 -134.5692)
		(end 184.9882 -134.5692)
		(width 0.127)
		(layer "In6.Cu")
		(net "RST_CPU0_DRAM_GH_N")
	)
	(segment
		(start 247.615964 -133.387084)
		(end 237.590076 -133.387084)
		(width 0.127)
		(layer "In6.Cu")
		(net "RST_CPU0_DRAM_GH_N")
	)
	(segment
		(start 134.12597 -127.782828)
		(end 122.54484 -127.782828)
		(width 0.127)
		(layer "In6.Cu")
		(net "RST_CPU0_DRAM_GH_N")
	)
	(segment
		(start 181.0385 -134.242048)
		(end 169.491406 -134.242048)
		(width 0.127)
		(layer "In6.Cu")
		(net "RST_CPU0_DRAM_GH_N")
	)
	(segment
		(start 249.10288 -131.900168)
		(end 247.615964 -133.387084)
		(width 0.127)
		(layer "In6.Cu")
		(net "RST_CPU0_DRAM_GH_N")
	)
	(segment
		(start 117.22608 -122.259598)
		(end 117.22608 -120.989598)
		(width 0.127)
		(layer "In6.Cu")
		(net "RST_CPU0_DRAM_GH_N")
	)
	(segment
		(start 225.571304 -134.247128)
		(end 224.700084 -135.118348)
		(width 0.127)
		(layer "In6.Cu")
		(net "RST_CPU0_DRAM_GH_N")
	)
	(segment
		(start 140.5001 -135.009128)
		(end 137.84834 -132.357368)
		(width 0.127)
		(layer "In6.Cu")
		(net "RST_CPU0_DRAM_GH_N")
	)
	(segment
		(start 249.10288 -130.139948)
		(end 249.10288 -131.900168)
		(width 0.127)
		(layer "In6.Cu")
		(net "RST_CPU0_DRAM_GH_N")
	)
	(segment
		(start 137.84834 -131.971034)
		(end 134.442962 -128.565656)
		(width 0.127)
		(layer "In6.Cu")
		(net "RST_CPU0_DRAM_GH_N")
	)
	(segment
		(start 181.61254 -134.816088)
		(end 181.0385 -134.242048)
		(width 0.127)
		(layer "In6.Cu")
		(net "RST_CPU0_DRAM_GH_N")
	)
	(segment
		(start 169.491406 -134.242048)
		(end 168.759632 -134.54507)
		(width 0.127)
		(layer "In6.Cu")
		(net "RST_CPU0_DRAM_GH_N")
	)
	(segment
		(start 115.95608 -119.446548)
		(end 115.95608 -118.068598)
		(width 0.12954)
		(layer "F.Cu")
		(net "RST_CPU0_DRAM_EF_PLD_N")
	)
	(segment
		(start 115.95608 -118.068598)
		(end 115.95608 -117.973094)
		(width 0.12954)
		(layer "F.Cu")
		(net "RST_CPU0_DRAM_EF_PLD_N")
	)
	(segment
		(start 115.31092 -117.327934)
		(end 115.31092 -116.078762)
		(width 0.12954)
		(layer "F.Cu")
		(net "RST_CPU0_DRAM_EF_PLD_N")
	)
	(segment
		(start 115.95608 -117.973094)
		(end 115.31092 -117.327934)
		(width 0.12954)
		(layer "F.Cu")
		(net "RST_CPU0_DRAM_EF_PLD_N")
	)
	(via
		(at 115.95608 -118.068598)
		(size 0.762)
		(drill 0.381)
		(layers "F.Cu" "B.Cu")
		(net "RST_CPU0_DRAM_EF_PLD_N")
	)
	(segment
		(start 369.91798 -247.178576)
		(end 369.918234 -247.178322)
		(width 0.12954)
		(layer "F.Cu")
		(net "RST_CPU0_DRAM_EF_N")
	)
	(segment
		(start 369.91798 -247.714262)
		(end 369.91798 -247.178576)
		(width 0.12954)
		(layer "F.Cu")
		(net "RST_CPU0_DRAM_EF_N")
	)
	(segment
		(start 115.95608 -120.989598)
		(end 115.95608 -120.246648)
		(width 0.12954)
		(layer "F.Cu")
		(net "RST_CPU0_DRAM_EF_N")
	)
	(segment
		(start 115.95608 -121.732548)
		(end 115.95608 -120.989598)
		(width 0.12954)
		(layer "F.Cu")
		(net "RST_CPU0_DRAM_EF_N")
	)
	(via
		(at 390.356598 -245.35511)
		(size 0.6604)
		(drill 0.3302)
		(layers "F.Cu" "B.Cu")
		(net "RST_CPU0_DRAM_EF_N")
	)
	(via
		(at 369.918234 -247.178322)
		(size 0.4572)
		(drill 0.2032)
		(layers "F.Cu" "B.Cu")
		(net "RST_CPU0_DRAM_EF_N")
	)
	(via
		(at 246.215154 -130.153664)
		(size 0.508)
		(drill 0.254)
		(layers "F.Cu" "B.Cu")
		(net "RST_CPU0_DRAM_EF_N")
	)
	(via
		(at 115.95608 -120.989598)
		(size 0.508)
		(drill 0.254)
		(layers "F.Cu" "B.Cu")
		(net "RST_CPU0_DRAM_EF_N")
	)
	(segment
		(start 381.817372 -246.929656)
		(end 381.948436 -246.853964)
		(width 0.0889)
		(layer "B.Cu")
		(net "RST_CPU0_DRAM_EF_N")
	)
	(segment
		(start 379.118876 -246.86006)
		(end 379.12929 -246.853964)
		(width 0.0889)
		(layer "B.Cu")
		(net "RST_CPU0_DRAM_EF_N")
	)
	(segment
		(start 383.69621 -246.8753)
		(end 383.788158 -246.783352)
		(width 0.0889)
		(layer "B.Cu")
		(net "RST_CPU0_DRAM_EF_N")
	)
	(segment
		(start 395.256512 -190.590424)
		(end 392.087862 -182.940452)
		(width 0.12954)
		(layer "B.Cu")
		(net "RST_CPU0_DRAM_EF_N")
	)
	(segment
		(start 377.75388 -164.063426)
		(end 377.75388 -158.880302)
		(width 0.12954)
		(layer "B.Cu")
		(net "RST_CPU0_DRAM_EF_N")
	)
	(segment
		(start 390.211056 -245.354856)
		(end 390.21131 -245.35511)
		(width 0.12954)
		(layer "B.Cu")
		(net "RST_CPU0_DRAM_EF_N")
	)
	(segment
		(start 277.511002 -131.155948)
		(end 262.850122 -131.155948)
		(width 0.12954)
		(layer "B.Cu")
		(net "RST_CPU0_DRAM_EF_N")
	)
	(segment
		(start 372.535704 -246.8626)
		(end 372.550436 -246.853964)
		(width 0.0889)
		(layer "B.Cu")
		(net "RST_CPU0_DRAM_EF_N")
	)
	(segment
		(start 403.541738 -201.10069)
		(end 402.096478 -199.65543)
		(width 0.12954)
		(layer "B.Cu")
		(net "RST_CPU0_DRAM_EF_N")
	)
	(segment
		(start 390.21131 -245.35511)
		(end 390.356598 -245.35511)
		(width 0.12954)
		(layer "B.Cu")
		(net "RST_CPU0_DRAM_EF_N")
	)
	(segment
		(start 250.630944 -131.155948)
		(end 246.791226 -130.392424)
		(width 0.12954)
		(layer "B.Cu")
		(net "RST_CPU0_DRAM_EF_N")
	)
	(segment
		(start 262.850122 -131.155948)
		(end 262.542782 -131.463288)
		(width 0.12954)
		(layer "B.Cu")
		(net "RST_CPU0_DRAM_EF_N")
	)
	(segment
		(start 278.974042 -132.618988)
		(end 277.511002 -131.155948)
		(width 0.12954)
		(layer "B.Cu")
		(net "RST_CPU0_DRAM_EF_N")
	)
	(segment
		(start 387.886956 -245.354856)
		(end 390.211056 -245.354856)
		(width 0.12954)
		(layer "B.Cu")
		(net "RST_CPU0_DRAM_EF_N")
	)
	(segment
		(start 378.174504 -246.8626)
		(end 378.189236 -246.853964)
		(width 0.0889)
		(layer "B.Cu")
		(net "RST_CPU0_DRAM_EF_N")
	)
	(segment
		(start 403.541738 -232.16997)
		(end 403.541738 -201.10069)
		(width 0.12954)
		(layer "B.Cu")
		(net "RST_CPU0_DRAM_EF_N")
	)
	(segment
		(start 262.542782 -131.463288)
		(end 259.60832 -131.463288)
		(width 0.12954)
		(layer "B.Cu")
		(net "RST_CPU0_DRAM_EF_N")
	)
	(segment
		(start 392.087862 -182.940452)
		(end 391.11301 -181.481222)
		(width 0.12954)
		(layer "B.Cu")
		(net "RST_CPU0_DRAM_EF_N")
	)
	(segment
		(start 387.378956 -245.862856)
		(end 387.886956 -245.354856)
		(width 0.12954)
		(layer "B.Cu")
		(net "RST_CPU0_DRAM_EF_N")
	)
	(segment
		(start 383.394966 -246.8753)
		(end 383.69621 -246.8753)
		(width 0.0889)
		(layer "B.Cu")
		(net "RST_CPU0_DRAM_EF_N")
	)
	(segment
		(start 369.918234 -247.178322)
		(end 370.42725 -246.92864)
		(width 0.0889)
		(layer "B.Cu")
		(net "RST_CPU0_DRAM_EF_N")
	)
	(segment
		(start 355.495606 -155.418028)
		(end 344.662506 -144.584928)
		(width 0.12954)
		(layer "B.Cu")
		(net "RST_CPU0_DRAM_EF_N")
	)
	(segment
		(start 381.665734 -246.929656)
		(end 381.817372 -246.929656)
		(width 0.0889)
		(layer "B.Cu")
		(net "RST_CPU0_DRAM_EF_N")
	)
	(segment
		(start 302.285146 -132.618988)
		(end 278.974042 -132.618988)
		(width 0.12954)
		(layer "B.Cu")
		(net "RST_CPU0_DRAM_EF_N")
	)
	(segment
		(start 370.656104 -246.8626)
		(end 370.670836 -246.853964)
		(width 0.0889)
		(layer "B.Cu")
		(net "RST_CPU0_DRAM_EF_N")
	)
	(segment
		(start 383.788158 -246.783352)
		(end 385.73837 -246.783352)
		(width 0.12954)
		(layer "B.Cu")
		(net "RST_CPU0_DRAM_EF_N")
	)
	(segment
		(start 371.595904 -246.8626)
		(end 371.610636 -246.853964)
		(width 0.0889)
		(layer "B.Cu")
		(net "RST_CPU0_DRAM_EF_N")
	)
	(segment
		(start 377.234704 -246.8626)
		(end 377.249436 -246.853964)
		(width 0.0889)
		(layer "B.Cu")
		(net "RST_CPU0_DRAM_EF_N")
	)
	(segment
		(start 379.503686 -246.853964)
		(end 379.5141 -246.86006)
		(width 0.0889)
		(layer "B.Cu")
		(net "RST_CPU0_DRAM_EF_N")
	)
	(segment
		(start 391.11301 -181.481222)
		(end 381.525018 -171.89323)
		(width 0.12954)
		(layer "B.Cu")
		(net "RST_CPU0_DRAM_EF_N")
	)
	(segment
		(start 246.791226 -130.392424)
		(end 246.215154 -130.153664)
		(width 0.12954)
		(layer "B.Cu")
		(net "RST_CPU0_DRAM_EF_N")
	)
	(segment
		(start 374.419876 -246.86006)
		(end 374.43029 -246.853964)
		(width 0.0889)
		(layer "B.Cu")
		(net "RST_CPU0_DRAM_EF_N")
	)
	(segment
		(start 259.60832 -131.463288)
		(end 259.30098 -131.155948)
		(width 0.12954)
		(layer "B.Cu")
		(net "RST_CPU0_DRAM_EF_N")
	)
	(segment
		(start 402.096478 -199.65543)
		(end 402.096478 -197.43039)
		(width 0.12954)
		(layer "B.Cu")
		(net "RST_CPU0_DRAM_EF_N")
	)
	(segment
		(start 376.294904 -246.8626)
		(end 376.309636 -246.853964)
		(width 0.0889)
		(layer "B.Cu")
		(net "RST_CPU0_DRAM_EF_N")
	)
	(segment
		(start 332.72984 -144.584928)
		(end 317.458852 -138.259566)
		(width 0.12954)
		(layer "B.Cu")
		(net "RST_CPU0_DRAM_EF_N")
	)
	(segment
		(start 390.356598 -245.35511)
		(end 403.541738 -232.16997)
		(width 0.12954)
		(layer "B.Cu")
		(net "RST_CPU0_DRAM_EF_N")
	)
	(segment
		(start 380.998476 -246.86006)
		(end 381.00889 -246.853964)
		(width 0.0889)
		(layer "B.Cu")
		(net "RST_CPU0_DRAM_EF_N")
	)
	(segment
		(start 381.525018 -171.89323)
		(end 381.525018 -167.834564)
		(width 0.12954)
		(layer "B.Cu")
		(net "RST_CPU0_DRAM_EF_N")
	)
	(segment
		(start 386.658866 -245.862856)
		(end 387.378956 -245.862856)
		(width 0.12954)
		(layer "B.Cu")
		(net "RST_CPU0_DRAM_EF_N")
	)
	(segment
		(start 374.804686 -246.853964)
		(end 374.8151 -246.86006)
		(width 0.0889)
		(layer "B.Cu")
		(net "RST_CPU0_DRAM_EF_N")
	)
	(segment
		(start 307.925724 -138.259566)
		(end 302.285146 -132.618988)
		(width 0.12954)
		(layer "B.Cu")
		(net "RST_CPU0_DRAM_EF_N")
	)
	(segment
		(start 402.096478 -197.43039)
		(end 395.256512 -190.590424)
		(width 0.12954)
		(layer "B.Cu")
		(net "RST_CPU0_DRAM_EF_N")
	)
	(segment
		(start 317.458852 -138.259566)
		(end 307.925724 -138.259566)
		(width 0.12954)
		(layer "B.Cu")
		(net "RST_CPU0_DRAM_EF_N")
	)
	(segment
		(start 344.662506 -144.584928)
		(end 332.72984 -144.584928)
		(width 0.12954)
		(layer "B.Cu")
		(net "RST_CPU0_DRAM_EF_N")
	)
	(segment
		(start 374.291606 -155.418028)
		(end 355.495606 -155.418028)
		(width 0.12954)
		(layer "B.Cu")
		(net "RST_CPU0_DRAM_EF_N")
	)
	(segment
		(start 385.73837 -246.783352)
		(end 386.658866 -245.862856)
		(width 0.12954)
		(layer "B.Cu")
		(net "RST_CPU0_DRAM_EF_N")
	)
	(segment
		(start 377.75388 -158.880302)
		(end 374.291606 -155.418028)
		(width 0.12954)
		(layer "B.Cu")
		(net "RST_CPU0_DRAM_EF_N")
	)
	(segment
		(start 373.475504 -246.8626)
		(end 373.490236 -246.853964)
		(width 0.0889)
		(layer "B.Cu")
		(net "RST_CPU0_DRAM_EF_N")
	)
	(segment
		(start 259.30098 -131.155948)
		(end 250.630944 -131.155948)
		(width 0.12954)
		(layer "B.Cu")
		(net "RST_CPU0_DRAM_EF_N")
	)
	(segment
		(start 381.525018 -167.834564)
		(end 377.75388 -164.063426)
		(width 0.12954)
		(layer "B.Cu")
		(net "RST_CPU0_DRAM_EF_N")
	)
	(arc
		(start 374.8151 -246.86006)
		(mid 375.093278 -246.929783)
		(end 375.369836 -246.853964)
		(width 0.0889)
		(layer "B.Cu")
		(net "RST_CPU0_DRAM_EF_N")
	)
	(arc
		(start 377.249436 -246.853964)
		(mid 377.436634 -246.803821)
		(end 377.623832 -246.853964)
		(width 0.0889)
		(layer "B.Cu")
		(net "RST_CPU0_DRAM_EF_N")
	)
	(arc
		(start 381.948436 -246.853964)
		(mid 382.135634 -246.803821)
		(end 382.322832 -246.853964)
		(width 0.0889)
		(layer "B.Cu")
		(net "RST_CPU0_DRAM_EF_N")
	)
	(arc
		(start 382.888236 -246.853964)
		(mid 383.059927 -246.804142)
		(end 383.2352 -246.839486)
		(width 0.0889)
		(layer "B.Cu")
		(net "RST_CPU0_DRAM_EF_N")
	)
	(arc
		(start 380.068836 -246.853964)
		(mid 380.256034 -246.803821)
		(end 380.443232 -246.853964)
		(width 0.0889)
		(layer "B.Cu")
		(net "RST_CPU0_DRAM_EF_N")
	)
	(arc
		(start 372.924832 -246.853964)
		(mid 373.199031 -246.929799)
		(end 373.475504 -246.8626)
		(width 0.0889)
		(layer "B.Cu")
		(net "RST_CPU0_DRAM_EF_N")
	)
	(arc
		(start 382.322832 -246.853964)
		(mid 382.605534 -246.92974)
		(end 382.888236 -246.853964)
		(width 0.0889)
		(layer "B.Cu")
		(net "RST_CPU0_DRAM_EF_N")
	)
	(arc
		(start 373.864632 -246.853964)
		(mid 374.141445 -246.929834)
		(end 374.419876 -246.86006)
		(width 0.0889)
		(layer "B.Cu")
		(net "RST_CPU0_DRAM_EF_N")
	)
	(arc
		(start 381.383286 -246.853964)
		(mid 381.519528 -246.910398)
		(end 381.665734 -246.929656)
		(width 0.0889)
		(layer "B.Cu")
		(net "RST_CPU0_DRAM_EF_N")
	)
	(arc
		(start 378.563632 -246.853964)
		(mid 378.840445 -246.929834)
		(end 379.118876 -246.86006)
		(width 0.0889)
		(layer "B.Cu")
		(net "RST_CPU0_DRAM_EF_N")
	)
	(arc
		(start 380.443232 -246.853964)
		(mid 380.720045 -246.929834)
		(end 380.998476 -246.86006)
		(width 0.0889)
		(layer "B.Cu")
		(net "RST_CPU0_DRAM_EF_N")
	)
	(arc
		(start 375.369836 -246.853964)
		(mid 375.557034 -246.803821)
		(end 375.744232 -246.853964)
		(width 0.0889)
		(layer "B.Cu")
		(net "RST_CPU0_DRAM_EF_N")
	)
	(arc
		(start 379.5141 -246.86006)
		(mid 379.792278 -246.929783)
		(end 380.068836 -246.853964)
		(width 0.0889)
		(layer "B.Cu")
		(net "RST_CPU0_DRAM_EF_N")
	)
	(arc
		(start 371.985032 -246.853964)
		(mid 372.259231 -246.929799)
		(end 372.535704 -246.8626)
		(width 0.0889)
		(layer "B.Cu")
		(net "RST_CPU0_DRAM_EF_N")
	)
	(arc
		(start 373.490236 -246.853964)
		(mid 373.677434 -246.803821)
		(end 373.864632 -246.853964)
		(width 0.0889)
		(layer "B.Cu")
		(net "RST_CPU0_DRAM_EF_N")
	)
	(arc
		(start 379.12929 -246.853964)
		(mid 379.316488 -246.803821)
		(end 379.503686 -246.853964)
		(width 0.0889)
		(layer "B.Cu")
		(net "RST_CPU0_DRAM_EF_N")
	)
	(arc
		(start 374.43029 -246.853964)
		(mid 374.617488 -246.803821)
		(end 374.804686 -246.853964)
		(width 0.0889)
		(layer "B.Cu")
		(net "RST_CPU0_DRAM_EF_N")
	)
	(arc
		(start 376.309636 -246.853964)
		(mid 376.496834 -246.803821)
		(end 376.684032 -246.853964)
		(width 0.0889)
		(layer "B.Cu")
		(net "RST_CPU0_DRAM_EF_N")
	)
	(arc
		(start 378.189236 -246.853964)
		(mid 378.376434 -246.803821)
		(end 378.563632 -246.853964)
		(width 0.0889)
		(layer "B.Cu")
		(net "RST_CPU0_DRAM_EF_N")
	)
	(arc
		(start 371.610636 -246.853964)
		(mid 371.797834 -246.803821)
		(end 371.985032 -246.853964)
		(width 0.0889)
		(layer "B.Cu")
		(net "RST_CPU0_DRAM_EF_N")
	)
	(arc
		(start 377.623832 -246.853964)
		(mid 377.898031 -246.929799)
		(end 378.174504 -246.8626)
		(width 0.0889)
		(layer "B.Cu")
		(net "RST_CPU0_DRAM_EF_N")
	)
	(arc
		(start 376.684032 -246.853964)
		(mid 376.958231 -246.929799)
		(end 377.234704 -246.8626)
		(width 0.0889)
		(layer "B.Cu")
		(net "RST_CPU0_DRAM_EF_N")
	)
	(arc
		(start 381.00889 -246.853964)
		(mid 381.196088 -246.803821)
		(end 381.383286 -246.853964)
		(width 0.0889)
		(layer "B.Cu")
		(net "RST_CPU0_DRAM_EF_N")
	)
	(arc
		(start 372.550436 -246.853964)
		(mid 372.737634 -246.803821)
		(end 372.924832 -246.853964)
		(width 0.0889)
		(layer "B.Cu")
		(net "RST_CPU0_DRAM_EF_N")
	)
	(arc
		(start 383.2352 -246.839486)
		(mid 383.313102 -246.866227)
		(end 383.394966 -246.8753)
		(width 0.0889)
		(layer "B.Cu")
		(net "RST_CPU0_DRAM_EF_N")
	)
	(arc
		(start 371.045232 -246.853964)
		(mid 371.319431 -246.929799)
		(end 371.595904 -246.8626)
		(width 0.0889)
		(layer "B.Cu")
		(net "RST_CPU0_DRAM_EF_N")
	)
	(arc
		(start 370.42725 -246.92864)
		(mid 370.545192 -246.907802)
		(end 370.656104 -246.8626)
		(width 0.0889)
		(layer "B.Cu")
		(net "RST_CPU0_DRAM_EF_N")
	)
	(arc
		(start 375.744232 -246.853964)
		(mid 376.018431 -246.929799)
		(end 376.294904 -246.8626)
		(width 0.0889)
		(layer "B.Cu")
		(net "RST_CPU0_DRAM_EF_N")
	)
	(arc
		(start 370.670836 -246.853964)
		(mid 370.858034 -246.803821)
		(end 371.045232 -246.853964)
		(width 0.0889)
		(layer "B.Cu")
		(net "RST_CPU0_DRAM_EF_N")
	)
	(segment
		(start 214.643208 -133.403848)
		(end 215.468708 -134.229348)
		(width 0.127)
		(layer "In6.Cu")
		(net "RST_CPU0_DRAM_EF_N")
	)
	(segment
		(start 160.99282 -132.095748)
		(end 167.69842 -132.095748)
		(width 0.127)
		(layer "In6.Cu")
		(net "RST_CPU0_DRAM_EF_N")
	)
	(segment
		(start 119.37238 -122.540268)
		(end 119.37238 -123.340368)
		(width 0.127)
		(layer "In6.Cu")
		(net "RST_CPU0_DRAM_EF_N")
	)
	(segment
		(start 191.515492 -131.915408)
		(end 192.030096 -132.430012)
		(width 0.127)
		(layer "In6.Cu")
		(net "RST_CPU0_DRAM_EF_N")
	)
	(segment
		(start 245.741698 -130.355848)
		(end 245.943882 -130.153664)
		(width 0.127)
		(layer "In6.Cu")
		(net "RST_CPU0_DRAM_EF_N")
	)
	(segment
		(start 115.95608 -120.989598)
		(end 115.95608 -120.739408)
		(width 0.127)
		(layer "In6.Cu")
		(net "RST_CPU0_DRAM_EF_N")
	)
	(segment
		(start 171.692316 -131.906264)
		(end 172.2501 -132.464048)
		(width 0.127)
		(layer "In6.Cu")
		(net "RST_CPU0_DRAM_EF_N")
	)
	(segment
		(start 167.69842 -132.095748)
		(end 167.887904 -131.906264)
		(width 0.127)
		(layer "In6.Cu")
		(net "RST_CPU0_DRAM_EF_N")
	)
	(segment
		(start 119.11584 -122.283728)
		(end 119.37238 -122.540268)
		(width 0.127)
		(layer "In6.Cu")
		(net "RST_CPU0_DRAM_EF_N")
	)
	(segment
		(start 167.887904 -131.906264)
		(end 171.692316 -131.906264)
		(width 0.127)
		(layer "In6.Cu")
		(net "RST_CPU0_DRAM_EF_N")
	)
	(segment
		(start 237.958376 -132.498084)
		(end 242.308888 -132.498084)
		(width 0.127)
		(layer "In6.Cu")
		(net "RST_CPU0_DRAM_EF_N")
	)
	(segment
		(start 115.95608 -120.739408)
		(end 116.33708 -120.358408)
		(width 0.127)
		(layer "In6.Cu")
		(net "RST_CPU0_DRAM_EF_N")
	)
	(segment
		(start 225.203004 -133.358128)
		(end 229.062788 -133.358128)
		(width 0.127)
		(layer "In6.Cu")
		(net "RST_CPU0_DRAM_EF_N")
	)
	(segment
		(start 118.86184 -120.358408)
		(end 119.11584 -120.612408)
		(width 0.127)
		(layer "In6.Cu")
		(net "RST_CPU0_DRAM_EF_N")
	)
	(segment
		(start 202.163172 -133.238748)
		(end 202.328272 -133.403848)
		(width 0.127)
		(layer "In6.Cu")
		(net "RST_CPU0_DRAM_EF_N")
	)
	(segment
		(start 210.472528 -132.66928)
		(end 213.5632 -132.66928)
		(width 0.127)
		(layer "In6.Cu")
		(net "RST_CPU0_DRAM_EF_N")
	)
	(segment
		(start 177.64252 -131.915408)
		(end 191.515492 -131.915408)
		(width 0.127)
		(layer "In6.Cu")
		(net "RST_CPU0_DRAM_EF_N")
	)
	(segment
		(start 242.308888 -132.498084)
		(end 244.451124 -130.355848)
		(width 0.127)
		(layer "In6.Cu")
		(net "RST_CPU0_DRAM_EF_N")
	)
	(segment
		(start 224.331784 -134.229348)
		(end 225.203004 -133.358128)
		(width 0.127)
		(layer "In6.Cu")
		(net "RST_CPU0_DRAM_EF_N")
	)
	(segment
		(start 195.942712 -133.238748)
		(end 202.163172 -133.238748)
		(width 0.127)
		(layer "In6.Cu")
		(net "RST_CPU0_DRAM_EF_N")
	)
	(segment
		(start 134.817612 -126.454408)
		(end 141.594332 -133.231128)
		(width 0.127)
		(layer "In6.Cu")
		(net "RST_CPU0_DRAM_EF_N")
	)
	(segment
		(start 229.062788 -133.358128)
		(end 230.622348 -131.798568)
		(width 0.127)
		(layer "In6.Cu")
		(net "RST_CPU0_DRAM_EF_N")
	)
	(segment
		(start 202.328272 -133.403848)
		(end 209.73796 -133.403848)
		(width 0.127)
		(layer "In6.Cu")
		(net "RST_CPU0_DRAM_EF_N")
	)
	(segment
		(start 172.2501 -132.464048)
		(end 177.09388 -132.464048)
		(width 0.127)
		(layer "In6.Cu")
		(net "RST_CPU0_DRAM_EF_N")
	)
	(segment
		(start 214.297768 -133.403848)
		(end 214.643208 -133.403848)
		(width 0.127)
		(layer "In6.Cu")
		(net "RST_CPU0_DRAM_EF_N")
	)
	(segment
		(start 177.09388 -132.464048)
		(end 177.64252 -131.915408)
		(width 0.127)
		(layer "In6.Cu")
		(net "RST_CPU0_DRAM_EF_N")
	)
	(segment
		(start 209.73796 -133.403848)
		(end 210.472528 -132.66928)
		(width 0.127)
		(layer "In6.Cu")
		(net "RST_CPU0_DRAM_EF_N")
	)
	(segment
		(start 244.451124 -130.355848)
		(end 245.741698 -130.355848)
		(width 0.127)
		(layer "In6.Cu")
		(net "RST_CPU0_DRAM_EF_N")
	)
	(segment
		(start 245.943882 -130.153664)
		(end 246.215154 -130.153664)
		(width 0.127)
		(layer "In6.Cu")
		(net "RST_CPU0_DRAM_EF_N")
	)
	(segment
		(start 122.48642 -126.454408)
		(end 134.817612 -126.454408)
		(width 0.127)
		(layer "In6.Cu")
		(net "RST_CPU0_DRAM_EF_N")
	)
	(segment
		(start 116.33708 -120.358408)
		(end 118.86184 -120.358408)
		(width 0.127)
		(layer "In6.Cu")
		(net "RST_CPU0_DRAM_EF_N")
	)
	(segment
		(start 192.030096 -132.430012)
		(end 195.133976 -132.430012)
		(width 0.127)
		(layer "In6.Cu")
		(net "RST_CPU0_DRAM_EF_N")
	)
	(segment
		(start 215.468708 -134.229348)
		(end 224.331784 -134.229348)
		(width 0.127)
		(layer "In6.Cu")
		(net "RST_CPU0_DRAM_EF_N")
	)
	(segment
		(start 237.25886 -131.798568)
		(end 237.958376 -132.498084)
		(width 0.127)
		(layer "In6.Cu")
		(net "RST_CPU0_DRAM_EF_N")
	)
	(segment
		(start 195.133976 -132.430012)
		(end 195.942712 -133.238748)
		(width 0.127)
		(layer "In6.Cu")
		(net "RST_CPU0_DRAM_EF_N")
	)
	(segment
		(start 119.11584 -120.612408)
		(end 119.11584 -122.283728)
		(width 0.127)
		(layer "In6.Cu")
		(net "RST_CPU0_DRAM_EF_N")
	)
	(segment
		(start 119.37238 -123.340368)
		(end 122.48642 -126.454408)
		(width 0.127)
		(layer "In6.Cu")
		(net "RST_CPU0_DRAM_EF_N")
	)
	(segment
		(start 213.5632 -132.66928)
		(end 214.297768 -133.403848)
		(width 0.127)
		(layer "In6.Cu")
		(net "RST_CPU0_DRAM_EF_N")
	)
	(segment
		(start 230.622348 -131.798568)
		(end 237.25886 -131.798568)
		(width 0.127)
		(layer "In6.Cu")
		(net "RST_CPU0_DRAM_EF_N")
	)
	(segment
		(start 159.85744 -133.231128)
		(end 160.99282 -132.095748)
		(width 0.127)
		(layer "In6.Cu")
		(net "RST_CPU0_DRAM_EF_N")
	)
	(segment
		(start 141.594332 -133.231128)
		(end 159.85744 -133.231128)
		(width 0.127)
		(layer "In6.Cu")
		(net "RST_CPU0_DRAM_EF_N")
	)
	(segment
		(start 113.142776 -118.068598)
		(end 114.010948 -117.200426)
		(width 0.12954)
		(layer "F.Cu")
		(net "RST_CPU0_DRAM_CD_PLD_N")
	)
	(segment
		(start 112.40008 -118.068598)
		(end 113.142776 -118.068598)
		(width 0.12954)
		(layer "F.Cu")
		(net "RST_CPU0_DRAM_CD_PLD_N")
	)
	(segment
		(start 112.40008 -119.446548)
		(end 112.40008 -118.068598)
		(width 0.12954)
		(layer "F.Cu")
		(net "RST_CPU0_DRAM_CD_PLD_N")
	)
	(segment
		(start 114.010948 -117.200426)
		(end 114.010948 -116.078762)
		(width 0.12954)
		(layer "F.Cu")
		(net "RST_CPU0_DRAM_CD_PLD_N")
	)
	(via
		(at 112.40008 -118.068598)
		(size 0.762)
		(drill 0.381)
		(layers "F.Cu" "B.Cu")
		(net "RST_CPU0_DRAM_CD_PLD_N")
	)
	(segment
		(start 112.40008 -120.989598)
		(end 112.40008 -121.732548)
		(width 0.12954)
		(layer "F.Cu")
		(net "RST_CPU0_DRAM_CD_N")
	)
	(segment
		(start 350.292416 -256.639568)
		(end 350.292416 -257.175254)
		(width 0.12954)
		(layer "F.Cu")
		(net "RST_CPU0_DRAM_CD_N")
	)
	(segment
		(start 350.292162 -256.639314)
		(end 350.292416 -256.639568)
		(width 0.12954)
		(layer "F.Cu")
		(net "RST_CPU0_DRAM_CD_N")
	)
	(segment
		(start 112.40008 -120.246648)
		(end 112.40008 -120.989598)
		(width 0.12954)
		(layer "F.Cu")
		(net "RST_CPU0_DRAM_CD_N")
	)
	(via
		(at 350.292416 -257.175254)
		(size 0.4572)
		(drill 0.2032)
		(layers "F.Cu" "B.Cu")
		(net "RST_CPU0_DRAM_CD_N")
	)
	(via
		(at 320.167508 -257.8735)
		(size 0.6604)
		(drill 0.3302)
		(layers "F.Cu" "B.Cu")
		(net "RST_CPU0_DRAM_CD_N")
	)
	(via
		(at 112.40008 -120.989598)
		(size 0.508)
		(drill 0.254)
		(layers "F.Cu" "B.Cu")
		(net "RST_CPU0_DRAM_CD_N")
	)
	(via
		(at 205.92288 -149.062948)
		(size 0.508)
		(drill 0.254)
		(layers "F.Cu" "B.Cu")
		(net "RST_CPU0_DRAM_CD_N")
	)
	(segment
		(start 350.292416 -257.175254)
		(end 349.587312 -256.768346)
		(width 0.12954)
		(layer "B.Cu")
		(net "RST_CPU0_DRAM_CD_N")
	)
	(segment
		(start 321.382898 -256.65811)
		(end 320.167508 -257.8735)
		(width 0.12954)
		(layer "B.Cu")
		(net "RST_CPU0_DRAM_CD_N")
	)
	(segment
		(start 269.889732 -182.164736)
		(end 271.899126 -184.17413)
		(width 0.12954)
		(layer "B.Cu")
		(net "RST_CPU0_DRAM_CD_N")
	)
	(segment
		(start 206.06131 -151.011382)
		(end 208.049876 -152.999948)
		(width 0.12954)
		(layer "B.Cu")
		(net "RST_CPU0_DRAM_CD_N")
	)
	(segment
		(start 315.797438 -262.24357)
		(end 320.167508 -257.8735)
		(width 0.12954)
		(layer "B.Cu")
		(net "RST_CPU0_DRAM_CD_N")
	)
	(segment
		(start 343.948512 -256.768346)
		(end 343.93505 -256.760472)
		(width 0.12954)
		(layer "B.Cu")
		(net "RST_CPU0_DRAM_CD_N")
	)
	(segment
		(start 303.648364 -262.23087)
		(end 307.133498 -262.23087)
		(width 0.12954)
		(layer "B.Cu")
		(net "RST_CPU0_DRAM_CD_N")
	)
	(segment
		(start 307.349398 -262.44677)
		(end 310.986678 -262.44677)
		(width 0.12954)
		(layer "B.Cu")
		(net "RST_CPU0_DRAM_CD_N")
	)
	(segment
		(start 335.492344 -256.768346)
		(end 335.483454 -256.759456)
		(width 0.12954)
		(layer "B.Cu")
		(net "RST_CPU0_DRAM_CD_N")
	)
	(segment
		(start 342.069166 -256.768346)
		(end 342.059514 -256.762758)
		(width 0.12954)
		(layer "B.Cu")
		(net "RST_CPU0_DRAM_CD_N")
	)
	(segment
		(start 291.474398 -193.491866)
		(end 291.995098 -194.012566)
		(width 0.12954)
		(layer "B.Cu")
		(net "RST_CPU0_DRAM_CD_N")
	)
	(segment
		(start 292.614858 -198.13651)
		(end 293.458138 -198.13651)
		(width 0.12954)
		(layer "B.Cu")
		(net "RST_CPU0_DRAM_CD_N")
	)
	(segment
		(start 285.418022 -184.17413)
		(end 287.20542 -185.961528)
		(width 0.12954)
		(layer "B.Cu")
		(net "RST_CPU0_DRAM_CD_N")
	)
	(segment
		(start 300.056804 -254.74041)
		(end 302.942498 -257.626104)
		(width 0.12954)
		(layer "B.Cu")
		(net "RST_CPU0_DRAM_CD_N")
	)
	(segment
		(start 291.995098 -194.012566)
		(end 291.995098 -197.51675)
		(width 0.12954)
		(layer "B.Cu")
		(net "RST_CPU0_DRAM_CD_N")
	)
	(segment
		(start 291.995098 -197.51675)
		(end 292.614858 -198.13651)
		(width 0.12954)
		(layer "B.Cu")
		(net "RST_CPU0_DRAM_CD_N")
	)
	(segment
		(start 295.998138 -251.87275)
		(end 296.290238 -252.16485)
		(width 0.12954)
		(layer "B.Cu")
		(net "RST_CPU0_DRAM_CD_N")
	)
	(segment
		(start 299.320458 -254.74041)
		(end 300.056804 -254.74041)
		(width 0.12954)
		(layer "B.Cu")
		(net "RST_CPU0_DRAM_CD_N")
	)
	(segment
		(start 295.657778 -197.76313)
		(end 295.998138 -198.10349)
		(width 0.12954)
		(layer "B.Cu")
		(net "RST_CPU0_DRAM_CD_N")
	)
	(segment
		(start 271.899126 -184.17413)
		(end 285.418022 -184.17413)
		(width 0.12954)
		(layer "B.Cu")
		(net "RST_CPU0_DRAM_CD_N")
	)
	(segment
		(start 206.06131 -149.201378)
		(end 206.06131 -151.011382)
		(width 0.12954)
		(layer "B.Cu")
		(net "RST_CPU0_DRAM_CD_N")
	)
	(segment
		(start 269.889478 -182.164736)
		(end 269.889732 -182.164736)
		(width 0.12954)
		(layer "B.Cu")
		(net "RST_CPU0_DRAM_CD_N")
	)
	(segment
		(start 334.470756 -256.759456)
		(end 334.369156 -256.657856)
		(width 0.12954)
		(layer "B.Cu")
		(net "RST_CPU0_DRAM_CD_N")
	)
	(segment
		(start 290.123372 -185.961528)
		(end 291.474398 -187.312554)
		(width 0.12954)
		(layer "B.Cu")
		(net "RST_CPU0_DRAM_CD_N")
	)
	(segment
		(start 208.049876 -152.999948)
		(end 240.72469 -152.999948)
		(width 0.12954)
		(layer "B.Cu")
		(net "RST_CPU0_DRAM_CD_N")
	)
	(segment
		(start 348.647766 -256.768346)
		(end 348.638114 -256.762758)
		(width 0.12954)
		(layer "B.Cu")
		(net "RST_CPU0_DRAM_CD_N")
	)
	(segment
		(start 302.942498 -261.525004)
		(end 303.648364 -262.23087)
		(width 0.12954)
		(layer "B.Cu")
		(net "RST_CPU0_DRAM_CD_N")
	)
	(segment
		(start 335.519268 -256.78384)
		(end 335.492344 -256.768346)
		(width 0.12954)
		(layer "B.Cu")
		(net "RST_CPU0_DRAM_CD_N")
	)
	(segment
		(start 334.369156 -256.657856)
		(end 324.35292 -256.657856)
		(width 0.12954)
		(layer "B.Cu")
		(net "RST_CPU0_DRAM_CD_N")
	)
	(segment
		(start 344.888312 -256.768346)
		(end 344.87485 -256.760472)
		(width 0.12954)
		(layer "B.Cu")
		(net "RST_CPU0_DRAM_CD_N")
	)
	(segment
		(start 324.35292 -256.65811)
		(end 321.382898 -256.65811)
		(width 0.12954)
		(layer "B.Cu")
		(net "RST_CPU0_DRAM_CD_N")
	)
	(segment
		(start 340.189312 -256.768346)
		(end 340.17585 -256.760472)
		(width 0.12954)
		(layer "B.Cu")
		(net "RST_CPU0_DRAM_CD_N")
	)
	(segment
		(start 293.458138 -198.13651)
		(end 293.831518 -197.76313)
		(width 0.12954)
		(layer "B.Cu")
		(net "RST_CPU0_DRAM_CD_N")
	)
	(segment
		(start 310.986678 -262.44677)
		(end 311.189878 -262.24357)
		(width 0.12954)
		(layer "B.Cu")
		(net "RST_CPU0_DRAM_CD_N")
	)
	(segment
		(start 311.189878 -262.24357)
		(end 315.797438 -262.24357)
		(width 0.12954)
		(layer "B.Cu")
		(net "RST_CPU0_DRAM_CD_N")
	)
	(segment
		(start 296.290238 -252.16485)
		(end 296.744898 -252.16485)
		(width 0.12954)
		(layer "B.Cu")
		(net "RST_CPU0_DRAM_CD_N")
	)
	(segment
		(start 343.008712 -256.768346)
		(end 342.99906 -256.762758)
		(width 0.12954)
		(layer "B.Cu")
		(net "RST_CPU0_DRAM_CD_N")
	)
	(segment
		(start 349.587312 -256.768346)
		(end 349.57766 -256.762758)
		(width 0.12954)
		(layer "B.Cu")
		(net "RST_CPU0_DRAM_CD_N")
	)
	(segment
		(start 295.998138 -198.10349)
		(end 295.998138 -251.87275)
		(width 0.12954)
		(layer "B.Cu")
		(net "RST_CPU0_DRAM_CD_N")
	)
	(segment
		(start 240.72469 -152.999948)
		(end 269.889478 -182.164736)
		(width 0.12954)
		(layer "B.Cu")
		(net "RST_CPU0_DRAM_CD_N")
	)
	(segment
		(start 302.942498 -257.626104)
		(end 302.942498 -261.525004)
		(width 0.12954)
		(layer "B.Cu")
		(net "RST_CPU0_DRAM_CD_N")
	)
	(segment
		(start 346.767912 -256.768346)
		(end 346.75445 -256.760472)
		(width 0.12954)
		(layer "B.Cu")
		(net "RST_CPU0_DRAM_CD_N")
	)
	(segment
		(start 291.474398 -187.312554)
		(end 291.474398 -193.491866)
		(width 0.12954)
		(layer "B.Cu")
		(net "RST_CPU0_DRAM_CD_N")
	)
	(segment
		(start 293.831518 -197.76313)
		(end 295.657778 -197.76313)
		(width 0.12954)
		(layer "B.Cu")
		(net "RST_CPU0_DRAM_CD_N")
	)
	(segment
		(start 324.35292 -256.657856)
		(end 324.35292 -256.65811)
		(width 0.12954)
		(layer "B.Cu")
		(net "RST_CPU0_DRAM_CD_N")
	)
	(segment
		(start 287.20542 -185.961528)
		(end 290.123372 -185.961528)
		(width 0.12954)
		(layer "B.Cu")
		(net "RST_CPU0_DRAM_CD_N")
	)
	(segment
		(start 307.133498 -262.23087)
		(end 307.349398 -262.44677)
		(width 0.12954)
		(layer "B.Cu")
		(net "RST_CPU0_DRAM_CD_N")
	)
	(segment
		(start 296.744898 -252.16485)
		(end 299.320458 -254.74041)
		(width 0.12954)
		(layer "B.Cu")
		(net "RST_CPU0_DRAM_CD_N")
	)
	(segment
		(start 205.92288 -149.062948)
		(end 206.06131 -149.201378)
		(width 0.12954)
		(layer "B.Cu")
		(net "RST_CPU0_DRAM_CD_N")
	)
	(segment
		(start 335.483454 -256.759456)
		(end 334.470756 -256.759456)
		(width 0.12954)
		(layer "B.Cu")
		(net "RST_CPU0_DRAM_CD_N")
	)
	(arc
		(start 344.87485 -256.760472)
		(mid 344.645597 -256.705228)
		(end 344.418412 -256.768346)
		(width 0.12954)
		(layer "B.Cu")
		(net "RST_CPU0_DRAM_CD_N")
	)
	(arc
		(start 345.828112 -256.768346)
		(mid 345.593162 -256.705386)
		(end 345.358212 -256.768346)
		(width 0.12954)
		(layer "B.Cu")
		(net "RST_CPU0_DRAM_CD_N")
	)
	(arc
		(start 347.237812 -256.768346)
		(mid 347.002862 -256.831306)
		(end 346.767912 -256.768346)
		(width 0.12954)
		(layer "B.Cu")
		(net "RST_CPU0_DRAM_CD_N")
	)
	(arc
		(start 337.369912 -256.768346)
		(mid 337.134962 -256.705386)
		(end 336.900012 -256.768346)
		(width 0.12954)
		(layer "B.Cu")
		(net "RST_CPU0_DRAM_CD_N")
	)
	(arc
		(start 337.839812 -256.768346)
		(mid 337.604862 -256.831306)
		(end 337.369912 -256.768346)
		(width 0.12954)
		(layer "B.Cu")
		(net "RST_CPU0_DRAM_CD_N")
	)
	(arc
		(start 335.960212 -256.768346)
		(mid 335.741681 -256.831019)
		(end 335.519268 -256.78384)
		(width 0.12954)
		(layer "B.Cu")
		(net "RST_CPU0_DRAM_CD_N")
	)
	(arc
		(start 339.719412 -256.768346)
		(mid 339.484462 -256.831306)
		(end 339.249512 -256.768346)
		(width 0.12954)
		(layer "B.Cu")
		(net "RST_CPU0_DRAM_CD_N")
	)
	(arc
		(start 348.638114 -256.762758)
		(mid 348.407129 -256.705275)
		(end 348.177612 -256.768346)
		(width 0.12954)
		(layer "B.Cu")
		(net "RST_CPU0_DRAM_CD_N")
	)
	(arc
		(start 346.298012 -256.768346)
		(mid 346.063062 -256.831306)
		(end 345.828112 -256.768346)
		(width 0.12954)
		(layer "B.Cu")
		(net "RST_CPU0_DRAM_CD_N")
	)
	(arc
		(start 338.779612 -256.768346)
		(mid 338.544662 -256.831306)
		(end 338.309712 -256.768346)
		(width 0.12954)
		(layer "B.Cu")
		(net "RST_CPU0_DRAM_CD_N")
	)
	(arc
		(start 341.599012 -256.768346)
		(mid 341.364062 -256.831306)
		(end 341.129112 -256.768346)
		(width 0.12954)
		(layer "B.Cu")
		(net "RST_CPU0_DRAM_CD_N")
	)
	(arc
		(start 343.93505 -256.760472)
		(mid 343.705797 -256.705228)
		(end 343.478612 -256.768346)
		(width 0.12954)
		(layer "B.Cu")
		(net "RST_CPU0_DRAM_CD_N")
	)
	(arc
		(start 349.57766 -256.762758)
		(mid 349.346929 -256.705397)
		(end 349.117666 -256.768346)
		(width 0.12954)
		(layer "B.Cu")
		(net "RST_CPU0_DRAM_CD_N")
	)
	(arc
		(start 345.358212 -256.768346)
		(mid 345.123262 -256.831306)
		(end 344.888312 -256.768346)
		(width 0.12954)
		(layer "B.Cu")
		(net "RST_CPU0_DRAM_CD_N")
	)
	(arc
		(start 348.177612 -256.768346)
		(mid 347.942662 -256.831306)
		(end 347.707712 -256.768346)
		(width 0.12954)
		(layer "B.Cu")
		(net "RST_CPU0_DRAM_CD_N")
	)
	(arc
		(start 339.249512 -256.768346)
		(mid 339.014562 -256.705386)
		(end 338.779612 -256.768346)
		(width 0.12954)
		(layer "B.Cu")
		(net "RST_CPU0_DRAM_CD_N")
	)
	(arc
		(start 340.17585 -256.760472)
		(mid 339.946597 -256.705228)
		(end 339.719412 -256.768346)
		(width 0.12954)
		(layer "B.Cu")
		(net "RST_CPU0_DRAM_CD_N")
	)
	(arc
		(start 344.418412 -256.768346)
		(mid 344.183462 -256.831306)
		(end 343.948512 -256.768346)
		(width 0.12954)
		(layer "B.Cu")
		(net "RST_CPU0_DRAM_CD_N")
	)
	(arc
		(start 340.659212 -256.768346)
		(mid 340.424262 -256.831306)
		(end 340.189312 -256.768346)
		(width 0.12954)
		(layer "B.Cu")
		(net "RST_CPU0_DRAM_CD_N")
	)
	(arc
		(start 342.99906 -256.762758)
		(mid 342.768329 -256.705397)
		(end 342.539066 -256.768346)
		(width 0.12954)
		(layer "B.Cu")
		(net "RST_CPU0_DRAM_CD_N")
	)
	(arc
		(start 341.129112 -256.768346)
		(mid 340.894162 -256.705386)
		(end 340.659212 -256.768346)
		(width 0.12954)
		(layer "B.Cu")
		(net "RST_CPU0_DRAM_CD_N")
	)
	(arc
		(start 336.900012 -256.768346)
		(mid 336.665062 -256.831306)
		(end 336.430112 -256.768346)
		(width 0.12954)
		(layer "B.Cu")
		(net "RST_CPU0_DRAM_CD_N")
	)
	(arc
		(start 338.309712 -256.768346)
		(mid 338.074762 -256.705386)
		(end 337.839812 -256.768346)
		(width 0.12954)
		(layer "B.Cu")
		(net "RST_CPU0_DRAM_CD_N")
	)
	(arc
		(start 347.707712 -256.768346)
		(mid 347.472762 -256.705386)
		(end 347.237812 -256.768346)
		(width 0.12954)
		(layer "B.Cu")
		(net "RST_CPU0_DRAM_CD_N")
	)
	(arc
		(start 343.478612 -256.768346)
		(mid 343.243662 -256.831306)
		(end 343.008712 -256.768346)
		(width 0.12954)
		(layer "B.Cu")
		(net "RST_CPU0_DRAM_CD_N")
	)
	(arc
		(start 342.059514 -256.762758)
		(mid 341.828529 -256.705275)
		(end 341.599012 -256.768346)
		(width 0.12954)
		(layer "B.Cu")
		(net "RST_CPU0_DRAM_CD_N")
	)
	(arc
		(start 346.75445 -256.760472)
		(mid 346.525197 -256.705228)
		(end 346.298012 -256.768346)
		(width 0.12954)
		(layer "B.Cu")
		(net "RST_CPU0_DRAM_CD_N")
	)
	(arc
		(start 342.539066 -256.768346)
		(mid 342.304116 -256.831306)
		(end 342.069166 -256.768346)
		(width 0.12954)
		(layer "B.Cu")
		(net "RST_CPU0_DRAM_CD_N")
	)
	(arc
		(start 349.117666 -256.768346)
		(mid 348.882716 -256.831306)
		(end 348.647766 -256.768346)
		(width 0.12954)
		(layer "B.Cu")
		(net "RST_CPU0_DRAM_CD_N")
	)
	(arc
		(start 336.430112 -256.768346)
		(mid 336.195162 -256.705386)
		(end 335.960212 -256.768346)
		(width 0.12954)
		(layer "B.Cu")
		(net "RST_CPU0_DRAM_CD_N")
	)
	(segment
		(start 205.92288 -147.693634)
		(end 202.618594 -144.389348)
		(width 0.127)
		(layer "In13.Cu")
		(net "RST_CPU0_DRAM_CD_N")
	)
	(segment
		(start 137.13968 -139.080748)
		(end 116.575332 -139.080748)
		(width 0.127)
		(layer "In13.Cu")
		(net "RST_CPU0_DRAM_CD_N")
	)
	(segment
		(start 137.547604 -138.672824)
		(end 137.13968 -139.080748)
		(width 0.127)
		(layer "In13.Cu")
		(net "RST_CPU0_DRAM_CD_N")
	)
	(segment
		(start 147.729702 -138.672824)
		(end 137.547604 -138.672824)
		(width 0.127)
		(layer "In13.Cu")
		(net "RST_CPU0_DRAM_CD_N")
	)
	(segment
		(start 111.79302 -134.298436)
		(end 111.79302 -123.960128)
		(width 0.127)
		(layer "In13.Cu")
		(net "RST_CPU0_DRAM_CD_N")
	)
	(segment
		(start 112.40008 -121.603008)
		(end 112.40008 -120.989598)
		(width 0.127)
		(layer "In13.Cu")
		(net "RST_CPU0_DRAM_CD_N")
	)
	(segment
		(start 111.79302 -123.960128)
		(end 111.80826 -123.944888)
		(width 0.127)
		(layer "In13.Cu")
		(net "RST_CPU0_DRAM_CD_N")
	)
	(segment
		(start 202.618594 -144.389348)
		(end 153.446226 -144.389348)
		(width 0.127)
		(layer "In13.Cu")
		(net "RST_CPU0_DRAM_CD_N")
	)
	(segment
		(start 111.80826 -123.944888)
		(end 111.80826 -122.194828)
		(width 0.127)
		(layer "In13.Cu")
		(net "RST_CPU0_DRAM_CD_N")
	)
	(segment
		(start 116.575332 -139.080748)
		(end 111.79302 -134.298436)
		(width 0.127)
		(layer "In13.Cu")
		(net "RST_CPU0_DRAM_CD_N")
	)
	(segment
		(start 153.446226 -144.389348)
		(end 147.729702 -138.672824)
		(width 0.127)
		(layer "In13.Cu")
		(net "RST_CPU0_DRAM_CD_N")
	)
	(segment
		(start 205.92288 -149.062948)
		(end 205.92288 -147.693634)
		(width 0.127)
		(layer "In13.Cu")
		(net "RST_CPU0_DRAM_CD_N")
	)
	(segment
		(start 111.80826 -122.194828)
		(end 112.40008 -121.603008)
		(width 0.127)
		(layer "In13.Cu")
		(net "RST_CPU0_DRAM_CD_N")
	)
	(segment
		(start 111.13008 -118.068598)
		(end 112.03813 -117.160548)
		(width 0.12954)
		(layer "F.Cu")
		(net "RST_CPU0_DRAM_AB_PLD_N")
	)
	(segment
		(start 113.360962 -116.689886)
		(end 113.360962 -116.078762)
		(width 0.12954)
		(layer "F.Cu")
		(net "RST_CPU0_DRAM_AB_PLD_N")
	)
	(segment
		(start 112.03813 -117.160548)
		(end 112.8903 -117.160548)
		(width 0.12954)
		(layer "F.Cu")
		(net "RST_CPU0_DRAM_AB_PLD_N")
	)
	(segment
		(start 112.8903 -117.160548)
		(end 113.360962 -116.689886)
		(width 0.12954)
		(layer "F.Cu")
		(net "RST_CPU0_DRAM_AB_PLD_N")
	)
	(segment
		(start 111.13008 -119.446548)
		(end 111.13008 -118.068598)
		(width 0.12954)
		(layer "F.Cu")
		(net "RST_CPU0_DRAM_AB_PLD_N")
	)
	(via
		(at 111.13008 -118.068598)
		(size 0.762)
		(drill 0.381)
		(layers "F.Cu" "B.Cu")
		(net "RST_CPU0_DRAM_AB_PLD_N")
	)
	(segment
		(start 111.13008 -120.989598)
		(end 111.13008 -121.732548)
		(width 0.12954)
		(layer "F.Cu")
		(net "RST_CPU0_DRAM_AB_N")
	)
	(segment
		(start 349.822262 -255.825752)
		(end 349.822262 -256.361438)
		(width 0.12954)
		(layer "F.Cu")
		(net "RST_CPU0_DRAM_AB_N")
	)
	(segment
		(start 111.13008 -120.246648)
		(end 111.13008 -120.989598)
		(width 0.12954)
		(layer "F.Cu")
		(net "RST_CPU0_DRAM_AB_N")
	)
	(segment
		(start 349.822516 -255.825498)
		(end 349.822262 -255.825752)
		(width 0.12954)
		(layer "F.Cu")
		(net "RST_CPU0_DRAM_AB_N")
	)
	(via
		(at 316.814454 -259.791454)
		(size 0.6604)
		(drill 0.3302)
		(layers "F.Cu" "B.Cu")
		(net "RST_CPU0_DRAM_AB_N")
	)
	(via
		(at 207.04048 -150.769828)
		(size 0.508)
		(drill 0.254)
		(layers "F.Cu" "B.Cu")
		(net "RST_CPU0_DRAM_AB_N")
	)
	(via
		(at 349.822262 -256.361438)
		(size 0.4572)
		(drill 0.2032)
		(layers "F.Cu" "B.Cu")
		(net "RST_CPU0_DRAM_AB_N")
	)
	(via
		(at 111.13008 -120.989598)
		(size 0.508)
		(drill 0.254)
		(layers "F.Cu" "B.Cu")
		(net "RST_CPU0_DRAM_AB_N")
	)
	(segment
		(start 290.461192 -185.146188)
		(end 287.54324 -185.146188)
		(width 0.12954)
		(layer "B.Cu")
		(net "RST_CPU0_DRAM_AB_N")
	)
	(segment
		(start 324.18528 -255.133856)
		(end 324.18528 -255.13411)
		(width 0.12954)
		(layer "B.Cu")
		(net "RST_CPU0_DRAM_AB_N")
	)
	(segment
		(start 343.948512 -255.95453)
		(end 343.93505 -255.962404)
		(width 0.12954)
		(layer "B.Cu")
		(net "RST_CPU0_DRAM_AB_N")
	)
	(segment
		(start 300.204378 -253.69647)
		(end 299.460158 -253.69647)
		(width 0.12954)
		(layer "B.Cu")
		(net "RST_CPU0_DRAM_AB_N")
	)
	(segment
		(start 272.2372 -183.35879)
		(end 241.040158 -152.161748)
		(width 0.12954)
		(layer "B.Cu")
		(net "RST_CPU0_DRAM_AB_N")
	)
	(segment
		(start 337.369912 -255.95453)
		(end 337.35645 -255.962404)
		(width 0.12954)
		(layer "B.Cu")
		(net "RST_CPU0_DRAM_AB_N")
	)
	(segment
		(start 304.011838 -260.61289)
		(end 303.793398 -260.39445)
		(width 0.12954)
		(layer "B.Cu")
		(net "RST_CPU0_DRAM_AB_N")
	)
	(segment
		(start 303.793398 -257.28549)
		(end 300.204378 -253.69647)
		(width 0.12954)
		(layer "B.Cu")
		(net "RST_CPU0_DRAM_AB_N")
	)
	(segment
		(start 335.07299 -256.017522)
		(end 334.189324 -255.133856)
		(width 0.12954)
		(layer "B.Cu")
		(net "RST_CPU0_DRAM_AB_N")
	)
	(segment
		(start 342.069166 -255.95453)
		(end 342.059514 -255.960118)
		(width 0.12954)
		(layer "B.Cu")
		(net "RST_CPU0_DRAM_AB_N")
	)
	(segment
		(start 345.828112 -255.95453)
		(end 345.81465 -255.962404)
		(width 0.12954)
		(layer "B.Cu")
		(net "RST_CPU0_DRAM_AB_N")
	)
	(segment
		(start 348.647766 -255.95453)
		(end 348.638114 -255.960118)
		(width 0.12954)
		(layer "B.Cu")
		(net "RST_CPU0_DRAM_AB_N")
	)
	(segment
		(start 310.659018 -261.43585)
		(end 307.611018 -261.43585)
		(width 0.12954)
		(layer "B.Cu")
		(net "RST_CPU0_DRAM_AB_N")
	)
	(segment
		(start 287.54324 -185.146188)
		(end 285.755842 -183.35879)
		(width 0.12954)
		(layer "B.Cu")
		(net "RST_CPU0_DRAM_AB_N")
	)
	(segment
		(start 316.814454 -259.791454)
		(end 316.053978 -260.55193)
		(width 0.12954)
		(layer "B.Cu")
		(net "RST_CPU0_DRAM_AB_N")
	)
	(segment
		(start 307.611018 -261.43585)
		(end 306.788058 -260.61289)
		(width 0.12954)
		(layer "B.Cu")
		(net "RST_CPU0_DRAM_AB_N")
	)
	(segment
		(start 293.23284 -193.808604)
		(end 292.289738 -192.865502)
		(width 0.12954)
		(layer "B.Cu")
		(net "RST_CPU0_DRAM_AB_N")
	)
	(segment
		(start 292.289738 -186.974734)
		(end 290.461192 -185.146188)
		(width 0.12954)
		(layer "B.Cu")
		(net "RST_CPU0_DRAM_AB_N")
	)
	(segment
		(start 241.040158 -152.161748)
		(end 208.4324 -152.161748)
		(width 0.12954)
		(layer "B.Cu")
		(net "RST_CPU0_DRAM_AB_N")
	)
	(segment
		(start 293.23284 -196.359272)
		(end 293.23284 -193.808604)
		(width 0.12954)
		(layer "B.Cu")
		(net "RST_CPU0_DRAM_AB_N")
	)
	(segment
		(start 299.460158 -253.69647)
		(end 297.539918 -251.77623)
		(width 0.12954)
		(layer "B.Cu")
		(net "RST_CPU0_DRAM_AB_N")
	)
	(segment
		(start 343.008712 -255.95453)
		(end 342.99906 -255.960118)
		(width 0.12954)
		(layer "B.Cu")
		(net "RST_CPU0_DRAM_AB_N")
	)
	(segment
		(start 341.129112 -255.95453)
		(end 341.11565 -255.962404)
		(width 0.12954)
		(layer "B.Cu")
		(net "RST_CPU0_DRAM_AB_N")
	)
	(segment
		(start 321.471798 -255.13411)
		(end 316.814454 -259.791454)
		(width 0.12954)
		(layer "B.Cu")
		(net "RST_CPU0_DRAM_AB_N")
	)
	(segment
		(start 306.788058 -260.61289)
		(end 304.011838 -260.61289)
		(width 0.12954)
		(layer "B.Cu")
		(net "RST_CPU0_DRAM_AB_N")
	)
	(segment
		(start 335.255362 -256.017522)
		(end 335.07299 -256.017522)
		(width 0.12954)
		(layer "B.Cu")
		(net "RST_CPU0_DRAM_AB_N")
	)
	(segment
		(start 316.053978 -260.55193)
		(end 311.542938 -260.55193)
		(width 0.12954)
		(layer "B.Cu")
		(net "RST_CPU0_DRAM_AB_N")
	)
	(segment
		(start 347.707712 -255.95453)
		(end 347.69425 -255.962404)
		(width 0.12954)
		(layer "B.Cu")
		(net "RST_CPU0_DRAM_AB_N")
	)
	(segment
		(start 303.793398 -260.39445)
		(end 303.793398 -257.28549)
		(width 0.12954)
		(layer "B.Cu")
		(net "RST_CPU0_DRAM_AB_N")
	)
	(segment
		(start 297.539918 -251.77623)
		(end 297.539918 -197.98411)
		(width 0.12954)
		(layer "B.Cu")
		(net "RST_CPU0_DRAM_AB_N")
	)
	(segment
		(start 296.424858 -196.86905)
		(end 293.742618 -196.86905)
		(width 0.12954)
		(layer "B.Cu")
		(net "RST_CPU0_DRAM_AB_N")
	)
	(segment
		(start 311.542938 -260.55193)
		(end 310.659018 -261.43585)
		(width 0.12954)
		(layer "B.Cu")
		(net "RST_CPU0_DRAM_AB_N")
	)
	(segment
		(start 208.4324 -152.161748)
		(end 207.04048 -150.769828)
		(width 0.12954)
		(layer "B.Cu")
		(net "RST_CPU0_DRAM_AB_N")
	)
	(segment
		(start 324.18528 -255.13411)
		(end 321.471798 -255.13411)
		(width 0.12954)
		(layer "B.Cu")
		(net "RST_CPU0_DRAM_AB_N")
	)
	(segment
		(start 292.289738 -192.865502)
		(end 292.289738 -186.974734)
		(width 0.12954)
		(layer "B.Cu")
		(net "RST_CPU0_DRAM_AB_N")
	)
	(segment
		(start 285.755842 -183.35879)
		(end 272.2372 -183.35879)
		(width 0.12954)
		(layer "B.Cu")
		(net "RST_CPU0_DRAM_AB_N")
	)
	(segment
		(start 334.189324 -255.133856)
		(end 324.18528 -255.133856)
		(width 0.12954)
		(layer "B.Cu")
		(net "RST_CPU0_DRAM_AB_N")
	)
	(segment
		(start 339.249512 -255.95453)
		(end 339.23605 -255.962404)
		(width 0.12954)
		(layer "B.Cu")
		(net "RST_CPU0_DRAM_AB_N")
	)
	(segment
		(start 349.822262 -256.361438)
		(end 349.117666 -255.95453)
		(width 0.12954)
		(layer "B.Cu")
		(net "RST_CPU0_DRAM_AB_N")
	)
	(segment
		(start 293.742618 -196.86905)
		(end 293.23284 -196.359272)
		(width 0.12954)
		(layer "B.Cu")
		(net "RST_CPU0_DRAM_AB_N")
	)
	(segment
		(start 344.888312 -255.95453)
		(end 344.87485 -255.962404)
		(width 0.12954)
		(layer "B.Cu")
		(net "RST_CPU0_DRAM_AB_N")
	)
	(segment
		(start 297.539918 -197.98411)
		(end 296.424858 -196.86905)
		(width 0.12954)
		(layer "B.Cu")
		(net "RST_CPU0_DRAM_AB_N")
	)
	(arc
		(start 344.418412 -255.95453)
		(mid 344.183462 -255.89157)
		(end 343.948512 -255.95453)
		(width 0.12954)
		(layer "B.Cu")
		(net "RST_CPU0_DRAM_AB_N")
	)
	(arc
		(start 346.767912 -255.95453)
		(mid 346.532962 -256.01749)
		(end 346.298012 -255.95453)
		(width 0.12954)
		(layer "B.Cu")
		(net "RST_CPU0_DRAM_AB_N")
	)
	(arc
		(start 337.839812 -255.95453)
		(mid 337.604862 -255.89157)
		(end 337.369912 -255.95453)
		(width 0.12954)
		(layer "B.Cu")
		(net "RST_CPU0_DRAM_AB_N")
	)
	(arc
		(start 335.490312 -255.95453)
		(mid 335.376986 -256.001502)
		(end 335.255362 -256.017522)
		(width 0.12954)
		(layer "B.Cu")
		(net "RST_CPU0_DRAM_AB_N")
	)
	(arc
		(start 347.69425 -255.962404)
		(mid 347.464997 -256.017648)
		(end 347.237812 -255.95453)
		(width 0.12954)
		(layer "B.Cu")
		(net "RST_CPU0_DRAM_AB_N")
	)
	(arc
		(start 339.23605 -255.962404)
		(mid 339.006797 -256.017648)
		(end 338.779612 -255.95453)
		(width 0.12954)
		(layer "B.Cu")
		(net "RST_CPU0_DRAM_AB_N")
	)
	(arc
		(start 336.430112 -255.95453)
		(mid 336.195162 -256.01749)
		(end 335.960212 -255.95453)
		(width 0.12954)
		(layer "B.Cu")
		(net "RST_CPU0_DRAM_AB_N")
	)
	(arc
		(start 337.35645 -255.962404)
		(mid 337.127197 -256.017648)
		(end 336.900012 -255.95453)
		(width 0.12954)
		(layer "B.Cu")
		(net "RST_CPU0_DRAM_AB_N")
	)
	(arc
		(start 347.237812 -255.95453)
		(mid 347.002862 -255.89157)
		(end 346.767912 -255.95453)
		(width 0.12954)
		(layer "B.Cu")
		(net "RST_CPU0_DRAM_AB_N")
	)
	(arc
		(start 341.599012 -255.95453)
		(mid 341.364062 -255.89157)
		(end 341.129112 -255.95453)
		(width 0.12954)
		(layer "B.Cu")
		(net "RST_CPU0_DRAM_AB_N")
	)
	(arc
		(start 348.638114 -255.960118)
		(mid 348.407129 -256.017601)
		(end 348.177612 -255.95453)
		(width 0.12954)
		(layer "B.Cu")
		(net "RST_CPU0_DRAM_AB_N")
	)
	(arc
		(start 342.059514 -255.960118)
		(mid 341.828529 -256.017601)
		(end 341.599012 -255.95453)
		(width 0.12954)
		(layer "B.Cu")
		(net "RST_CPU0_DRAM_AB_N")
	)
	(arc
		(start 335.960212 -255.95453)
		(mid 335.725262 -255.89157)
		(end 335.490312 -255.95453)
		(width 0.12954)
		(layer "B.Cu")
		(net "RST_CPU0_DRAM_AB_N")
	)
	(arc
		(start 338.309712 -255.95453)
		(mid 338.074762 -256.01749)
		(end 337.839812 -255.95453)
		(width 0.12954)
		(layer "B.Cu")
		(net "RST_CPU0_DRAM_AB_N")
	)
	(arc
		(start 341.11565 -255.962404)
		(mid 340.886397 -256.017648)
		(end 340.659212 -255.95453)
		(width 0.12954)
		(layer "B.Cu")
		(net "RST_CPU0_DRAM_AB_N")
	)
	(arc
		(start 349.117666 -255.95453)
		(mid 348.882716 -255.89157)
		(end 348.647766 -255.95453)
		(width 0.12954)
		(layer "B.Cu")
		(net "RST_CPU0_DRAM_AB_N")
	)
	(arc
		(start 340.659212 -255.95453)
		(mid 340.424262 -255.89157)
		(end 340.189312 -255.95453)
		(width 0.12954)
		(layer "B.Cu")
		(net "RST_CPU0_DRAM_AB_N")
	)
	(arc
		(start 343.93505 -255.962404)
		(mid 343.705797 -256.017648)
		(end 343.478612 -255.95453)
		(width 0.12954)
		(layer "B.Cu")
		(net "RST_CPU0_DRAM_AB_N")
	)
	(arc
		(start 345.358212 -255.95453)
		(mid 345.123262 -255.89157)
		(end 344.888312 -255.95453)
		(width 0.12954)
		(layer "B.Cu")
		(net "RST_CPU0_DRAM_AB_N")
	)
	(arc
		(start 342.539066 -255.95453)
		(mid 342.304116 -255.89157)
		(end 342.069166 -255.95453)
		(width 0.12954)
		(layer "B.Cu")
		(net "RST_CPU0_DRAM_AB_N")
	)
	(arc
		(start 345.81465 -255.962404)
		(mid 345.585397 -256.017648)
		(end 345.358212 -255.95453)
		(width 0.12954)
		(layer "B.Cu")
		(net "RST_CPU0_DRAM_AB_N")
	)
	(arc
		(start 340.189312 -255.95453)
		(mid 339.954362 -256.01749)
		(end 339.719412 -255.95453)
		(width 0.12954)
		(layer "B.Cu")
		(net "RST_CPU0_DRAM_AB_N")
	)
	(arc
		(start 346.298012 -255.95453)
		(mid 346.063062 -255.89157)
		(end 345.828112 -255.95453)
		(width 0.12954)
		(layer "B.Cu")
		(net "RST_CPU0_DRAM_AB_N")
	)
	(arc
		(start 342.99906 -255.960118)
		(mid 342.768329 -256.017479)
		(end 342.539066 -255.95453)
		(width 0.12954)
		(layer "B.Cu")
		(net "RST_CPU0_DRAM_AB_N")
	)
	(arc
		(start 336.900012 -255.95453)
		(mid 336.665062 -255.89157)
		(end 336.430112 -255.95453)
		(width 0.12954)
		(layer "B.Cu")
		(net "RST_CPU0_DRAM_AB_N")
	)
	(arc
		(start 348.177612 -255.95453)
		(mid 347.942662 -255.89157)
		(end 347.707712 -255.95453)
		(width 0.12954)
		(layer "B.Cu")
		(net "RST_CPU0_DRAM_AB_N")
	)
	(arc
		(start 339.719412 -255.95453)
		(mid 339.484462 -255.89157)
		(end 339.249512 -255.95453)
		(width 0.12954)
		(layer "B.Cu")
		(net "RST_CPU0_DRAM_AB_N")
	)
	(arc
		(start 343.478612 -255.95453)
		(mid 343.243662 -255.89157)
		(end 343.008712 -255.95453)
		(width 0.12954)
		(layer "B.Cu")
		(net "RST_CPU0_DRAM_AB_N")
	)
	(arc
		(start 344.87485 -255.962404)
		(mid 344.645597 -256.017648)
		(end 344.418412 -255.95453)
		(width 0.12954)
		(layer "B.Cu")
		(net "RST_CPU0_DRAM_AB_N")
	)
	(arc
		(start 338.779612 -255.95453)
		(mid 338.544662 -255.89157)
		(end 338.309712 -255.95453)
		(width 0.12954)
		(layer "B.Cu")
		(net "RST_CPU0_DRAM_AB_N")
	)
	(segment
		(start 207.04048 -150.769828)
		(end 207.4164 -150.769828)
		(width 0.127)
		(layer "In13.Cu")
		(net "RST_CPU0_DRAM_AB_N")
	)
	(segment
		(start 207.57388 -150.612348)
		(end 207.57388 -148.597112)
		(width 0.127)
		(layer "In13.Cu")
		(net "RST_CPU0_DRAM_AB_N")
	)
	(segment
		(start 113.64976 -134.653528)
		(end 112.85474 -133.858508)
		(width 0.127)
		(layer "In13.Cu")
		(net "RST_CPU0_DRAM_AB_N")
	)
	(segment
		(start 146.42846 -134.653528)
		(end 113.64976 -134.653528)
		(width 0.127)
		(layer "In13.Cu")
		(net "RST_CPU0_DRAM_AB_N")
	)
	(segment
		(start 113.41354 -121.902728)
		(end 113.41354 -120.815608)
		(width 0.127)
		(layer "In13.Cu")
		(net "RST_CPU0_DRAM_AB_N")
	)
	(segment
		(start 208.03362 -146.398488)
		(end 204.24648 -142.611348)
		(width 0.127)
		(layer "In13.Cu")
		(net "RST_CPU0_DRAM_AB_N")
	)
	(segment
		(start 112.85474 -123.960128)
		(end 113.02746 -123.787408)
		(width 0.127)
		(layer "In13.Cu")
		(net "RST_CPU0_DRAM_AB_N")
	)
	(segment
		(start 207.4164 -150.769828)
		(end 207.57388 -150.612348)
		(width 0.127)
		(layer "In13.Cu")
		(net "RST_CPU0_DRAM_AB_N")
	)
	(segment
		(start 204.24648 -142.611348)
		(end 154.38628 -142.611348)
		(width 0.127)
		(layer "In13.Cu")
		(net "RST_CPU0_DRAM_AB_N")
	)
	(segment
		(start 113.02746 -123.787408)
		(end 113.02746 -122.288808)
		(width 0.127)
		(layer "In13.Cu")
		(net "RST_CPU0_DRAM_AB_N")
	)
	(segment
		(start 113.02746 -122.288808)
		(end 113.41354 -121.902728)
		(width 0.127)
		(layer "In13.Cu")
		(net "RST_CPU0_DRAM_AB_N")
	)
	(segment
		(start 154.38628 -142.611348)
		(end 146.42846 -134.653528)
		(width 0.127)
		(layer "In13.Cu")
		(net "RST_CPU0_DRAM_AB_N")
	)
	(segment
		(start 112.85474 -133.858508)
		(end 112.85474 -123.960128)
		(width 0.127)
		(layer "In13.Cu")
		(net "RST_CPU0_DRAM_AB_N")
	)
	(segment
		(start 112.95888 -120.360948)
		(end 111.75873 -120.360948)
		(width 0.127)
		(layer "In13.Cu")
		(net "RST_CPU0_DRAM_AB_N")
	)
	(segment
		(start 207.57388 -148.597112)
		(end 208.03362 -148.137372)
		(width 0.127)
		(layer "In13.Cu")
		(net "RST_CPU0_DRAM_AB_N")
	)
	(segment
		(start 111.75873 -120.360948)
		(end 111.13008 -120.989598)
		(width 0.127)
		(layer "In13.Cu")
		(net "RST_CPU0_DRAM_AB_N")
	)
	(segment
		(start 208.03362 -148.137372)
		(end 208.03362 -146.398488)
		(width 0.127)
		(layer "In13.Cu")
		(net "RST_CPU0_DRAM_AB_N")
	)
	(segment
		(start 113.41354 -120.815608)
		(end 112.95888 -120.360948)
		(width 0.127)
		(layer "In13.Cu")
		(net "RST_CPU0_DRAM_AB_N")
	)
	(via
		(at 212.90788 -116.728748)
		(size 0.508)
		(drill 0.254)
		(layers "F.Cu" "B.Cu")
		(net "RST_CPU0_BUF_R_N")
	)
	(via
		(at 192.99428 -134.737348)
		(size 0.508)
		(drill 0.254)
		(layers "F.Cu" "B.Cu")
		(net "RST_CPU0_BUF_R_N")
	)
	(via
		(at 186.74588 -104.353868)
		(size 0.508)
		(drill 0.254)
		(layers "F.Cu" "B.Cu")
		(net "RST_CPU0_BUF_R_N")
	)
	(via
		(at 204.01788 -150.967948)
		(size 0.508)
		(drill 0.254)
		(layers "F.Cu" "B.Cu")
		(net "RST_CPU0_BUF_R_N")
	)
	(via
		(at 289.744658 -250.25477)
		(size 0.6604)
		(drill 0.3302)
		(layers "F.Cu" "B.Cu")
		(net "RST_CPU0_BUF_R_N")
	)
	(segment
		(start 284.871922 -186.34329)
		(end 285.85668 -187.328048)
		(width 0.12954)
		(layer "B.Cu")
		(net "RST_CPU0_BUF_R_N")
	)
	(segment
		(start 291.573458 -252.922024)
		(end 291.573458 -255.522476)
		(width 0.12954)
		(layer "B.Cu")
		(net "RST_CPU0_BUF_R_N")
	)
	(segment
		(start 290.229798 -251.578364)
		(end 291.573458 -252.922024)
		(width 0.12954)
		(layer "B.Cu")
		(net "RST_CPU0_BUF_R_N")
	)
	(segment
		(start 296.672254 -259.171948)
		(end 297.54195 -259.171948)
		(width 0.12954)
		(layer "B.Cu")
		(net "RST_CPU0_BUF_R_N")
	)
	(segment
		(start 290.229798 -250.73991)
		(end 290.229798 -251.578364)
		(width 0.12954)
		(layer "B.Cu")
		(net "RST_CPU0_BUF_R_N")
	)
	(segment
		(start 289.241738 -249.75185)
		(end 289.744658 -250.25477)
		(width 0.12954)
		(layer "B.Cu")
		(net "RST_CPU0_BUF_R_N")
	)
	(segment
		(start 204.01788 -150.967948)
		(end 204.01788 -152.746202)
		(width 0.12954)
		(layer "B.Cu")
		(net "RST_CPU0_BUF_R_N")
	)
	(segment
		(start 293.953438 -257.902456)
		(end 295.402762 -257.902456)
		(width 0.12954)
		(layer "B.Cu")
		(net "RST_CPU0_BUF_R_N")
	)
	(segment
		(start 287.9344 -194.536822)
		(end 287.9344 -199.51827)
		(width 0.12954)
		(layer "B.Cu")
		(net "RST_CPU0_BUF_R_N")
	)
	(segment
		(start 270.856202 -186.34329)
		(end 284.871922 -186.34329)
		(width 0.12954)
		(layer "B.Cu")
		(net "RST_CPU0_BUF_R_N")
	)
	(segment
		(start 295.402762 -257.902456)
		(end 296.672254 -259.171948)
		(width 0.12954)
		(layer "B.Cu")
		(net "RST_CPU0_BUF_R_N")
	)
	(segment
		(start 298.34205 -258.416044)
		(end 298.34205 -258.155948)
		(width 0.12954)
		(layer "B.Cu")
		(net "RST_CPU0_BUF_R_N")
	)
	(segment
		(start 210.26628 -124.780548)
		(end 209.19948 -125.847348)
		(width 0.12954)
		(layer "B.Cu")
		(net "RST_CPU0_BUF_R_N")
	)
	(segment
		(start 297.7896 -258.714748)
		(end 298.043346 -258.714748)
		(width 0.12954)
		(layer "B.Cu")
		(net "RST_CPU0_BUF_R_N")
	)
	(segment
		(start 212.90788 -123.612148)
		(end 211.73948 -124.780548)
		(width 0.12954)
		(layer "B.Cu")
		(net "RST_CPU0_BUF_R_N")
	)
	(segment
		(start 186.7281 -104.371648)
		(end 186.05627 -104.371648)
		(width 0.12954)
		(layer "B.Cu")
		(net "RST_CPU0_BUF_R_N")
	)
	(segment
		(start 288.558478 -249.40641)
		(end 288.903918 -249.75185)
		(width 0.12954)
		(layer "B.Cu")
		(net "RST_CPU0_BUF_R_N")
	)
	(segment
		(start 287.506918 -191.559942)
		(end 287.506918 -194.10934)
		(width 0.12954)
		(layer "B.Cu")
		(net "RST_CPU0_BUF_R_N")
	)
	(segment
		(start 297.54195 -258.962398)
		(end 297.7896 -258.714748)
		(width 0.12954)
		(layer "B.Cu")
		(net "RST_CPU0_BUF_R_N")
	)
	(segment
		(start 212.90788 -116.728748)
		(end 212.90788 -123.612148)
		(width 0.12954)
		(layer "B.Cu")
		(net "RST_CPU0_BUF_R_N")
	)
	(segment
		(start 209.19948 -125.847348)
		(end 209.19948 -127.320548)
		(width 0.12954)
		(layer "B.Cu")
		(net "RST_CPU0_BUF_R_N")
	)
	(segment
		(start 288.558478 -200.142348)
		(end 288.558478 -249.40641)
		(width 0.12954)
		(layer "B.Cu")
		(net "RST_CPU0_BUF_R_N")
	)
	(segment
		(start 298.043346 -258.714748)
		(end 298.34205 -258.416044)
		(width 0.12954)
		(layer "B.Cu")
		(net "RST_CPU0_BUF_R_N")
	)
	(segment
		(start 206.787496 -155.515818)
		(end 240.02873 -155.515818)
		(width 0.12954)
		(layer "B.Cu")
		(net "RST_CPU0_BUF_R_N")
	)
	(segment
		(start 285.85668 -189.909704)
		(end 287.506918 -191.559942)
		(width 0.12954)
		(layer "B.Cu")
		(net "RST_CPU0_BUF_R_N")
	)
	(segment
		(start 186.05627 -104.371648)
		(end 185.93689 -104.491028)
		(width 0.12954)
		(layer "B.Cu")
		(net "RST_CPU0_BUF_R_N")
	)
	(segment
		(start 186.74588 -104.353868)
		(end 186.7281 -104.371648)
		(width 0.12954)
		(layer "B.Cu")
		(net "RST_CPU0_BUF_R_N")
	)
	(segment
		(start 211.73948 -124.780548)
		(end 210.26628 -124.780548)
		(width 0.12954)
		(layer "B.Cu")
		(net "RST_CPU0_BUF_R_N")
	)
	(segment
		(start 287.506918 -194.10934)
		(end 287.9344 -194.536822)
		(width 0.12954)
		(layer "B.Cu")
		(net "RST_CPU0_BUF_R_N")
	)
	(segment
		(start 193.60388 -135.346948)
		(end 192.99428 -134.737348)
		(width 0.12954)
		(layer "B.Cu")
		(net "RST_CPU0_BUF_R_N")
	)
	(segment
		(start 287.9344 -199.51827)
		(end 288.558478 -200.142348)
		(width 0.12954)
		(layer "B.Cu")
		(net "RST_CPU0_BUF_R_N")
	)
	(segment
		(start 288.903918 -249.75185)
		(end 289.241738 -249.75185)
		(width 0.12954)
		(layer "B.Cu")
		(net "RST_CPU0_BUF_R_N")
	)
	(segment
		(start 289.744658 -250.25477)
		(end 290.229798 -250.73991)
		(width 0.12954)
		(layer "B.Cu")
		(net "RST_CPU0_BUF_R_N")
	)
	(segment
		(start 297.54195 -259.171948)
		(end 297.54195 -258.962398)
		(width 0.12954)
		(layer "B.Cu")
		(net "RST_CPU0_BUF_R_N")
	)
	(segment
		(start 209.19948 -127.320548)
		(end 201.17308 -135.346948)
		(width 0.12954)
		(layer "B.Cu")
		(net "RST_CPU0_BUF_R_N")
	)
	(segment
		(start 240.02873 -155.515818)
		(end 270.856202 -186.34329)
		(width 0.12954)
		(layer "B.Cu")
		(net "RST_CPU0_BUF_R_N")
	)
	(segment
		(start 204.01788 -152.746202)
		(end 206.787496 -155.515818)
		(width 0.12954)
		(layer "B.Cu")
		(net "RST_CPU0_BUF_R_N")
	)
	(segment
		(start 285.85668 -187.328048)
		(end 285.85668 -189.909704)
		(width 0.12954)
		(layer "B.Cu")
		(net "RST_CPU0_BUF_R_N")
	)
	(segment
		(start 201.17308 -135.346948)
		(end 193.60388 -135.346948)
		(width 0.12954)
		(layer "B.Cu")
		(net "RST_CPU0_BUF_R_N")
	)
	(segment
		(start 291.573458 -255.522476)
		(end 293.953438 -257.902456)
		(width 0.12954)
		(layer "B.Cu")
		(net "RST_CPU0_BUF_R_N")
	)
	(segment
		(start 203.74102 -150.691088)
		(end 203.74102 -146.568668)
		(width 0.127)
		(layer "In2.Cu")
		(net "RST_CPU0_BUF_R_N")
	)
	(segment
		(start 203.74102 -146.568668)
		(end 192.99428 -135.821928)
		(width 0.127)
		(layer "In2.Cu")
		(net "RST_CPU0_BUF_R_N")
	)
	(segment
		(start 204.01788 -150.967948)
		(end 203.74102 -150.691088)
		(width 0.127)
		(layer "In2.Cu")
		(net "RST_CPU0_BUF_R_N")
	)
	(segment
		(start 192.99428 -135.821928)
		(end 192.99428 -134.737348)
		(width 0.127)
		(layer "In2.Cu")
		(net "RST_CPU0_BUF_R_N")
	)
	(segment
		(start 182.32882 -111.374428)
		(end 187.14212 -111.374428)
		(width 0.127)
		(layer "In6.Cu")
		(net "RST_CPU0_BUF_R_N")
	)
	(segment
		(start 185.77814 -104.353868)
		(end 185.3565 -104.775508)
		(width 0.127)
		(layer "In6.Cu")
		(net "RST_CPU0_BUF_R_N")
	)
	(segment
		(start 199.79132 -109.70641)
		(end 199.83323 -109.70641)
		(width 0.127)
		(layer "In6.Cu")
		(net "RST_CPU0_BUF_R_N")
	)
	(segment
		(start 199.170798 -109.085888)
		(end 199.79132 -109.70641)
		(width 0.127)
		(layer "In6.Cu")
		(net "RST_CPU0_BUF_R_N")
	)
	(segment
		(start 186.74588 -104.353868)
		(end 185.77814 -104.353868)
		(width 0.127)
		(layer "In6.Cu")
		(net "RST_CPU0_BUF_R_N")
	)
	(segment
		(start 203.185522 -110.146846)
		(end 203.84516 -109.487208)
		(width 0.127)
		(layer "In6.Cu")
		(net "RST_CPU0_BUF_R_N")
	)
	(segment
		(start 201.80935 -110.146846)
		(end 203.185522 -110.146846)
		(width 0.127)
		(layer "In6.Cu")
		(net "RST_CPU0_BUF_R_N")
	)
	(segment
		(start 185.3565 -107.224068)
		(end 185.20664 -107.373928)
		(width 0.127)
		(layer "In6.Cu")
		(net "RST_CPU0_BUF_R_N")
	)
	(segment
		(start 210.988402 -116.728748)
		(end 212.90788 -116.728748)
		(width 0.127)
		(layer "In6.Cu")
		(net "RST_CPU0_BUF_R_N")
	)
	(segment
		(start 187.752228 -110.76432)
		(end 191.171068 -110.76432)
		(width 0.127)
		(layer "In6.Cu")
		(net "RST_CPU0_BUF_R_N")
	)
	(segment
		(start 182.16118 -111.206788)
		(end 182.32882 -111.374428)
		(width 0.127)
		(layer "In6.Cu")
		(net "RST_CPU0_BUF_R_N")
	)
	(segment
		(start 187.14212 -111.374428)
		(end 187.752228 -110.76432)
		(width 0.127)
		(layer "In6.Cu")
		(net "RST_CPU0_BUF_R_N")
	)
	(segment
		(start 182.16118 -107.533948)
		(end 182.16118 -111.206788)
		(width 0.127)
		(layer "In6.Cu")
		(net "RST_CPU0_BUF_R_N")
	)
	(segment
		(start 182.3212 -107.373928)
		(end 182.16118 -107.533948)
		(width 0.127)
		(layer "In6.Cu")
		(net "RST_CPU0_BUF_R_N")
	)
	(segment
		(start 195.68414 -109.085888)
		(end 199.170798 -109.085888)
		(width 0.127)
		(layer "In6.Cu")
		(net "RST_CPU0_BUF_R_N")
	)
	(segment
		(start 195.34632 -109.423708)
		(end 195.68414 -109.085888)
		(width 0.127)
		(layer "In6.Cu")
		(net "RST_CPU0_BUF_R_N")
	)
	(segment
		(start 199.926448 -109.799628)
		(end 201.462132 -109.799628)
		(width 0.127)
		(layer "In6.Cu")
		(net "RST_CPU0_BUF_R_N")
	)
	(segment
		(start 199.83323 -109.70641)
		(end 199.926448 -109.799628)
		(width 0.127)
		(layer "In6.Cu")
		(net "RST_CPU0_BUF_R_N")
	)
	(segment
		(start 204.847698 -109.487208)
		(end 205.160118 -109.799628)
		(width 0.127)
		(layer "In6.Cu")
		(net "RST_CPU0_BUF_R_N")
	)
	(segment
		(start 185.3565 -104.775508)
		(end 185.3565 -107.224068)
		(width 0.127)
		(layer "In6.Cu")
		(net "RST_CPU0_BUF_R_N")
	)
	(segment
		(start 205.71714 -111.457486)
		(end 210.988402 -116.728748)
		(width 0.127)
		(layer "In6.Cu")
		(net "RST_CPU0_BUF_R_N")
	)
	(segment
		(start 201.462132 -109.799628)
		(end 201.80935 -110.146846)
		(width 0.127)
		(layer "In6.Cu")
		(net "RST_CPU0_BUF_R_N")
	)
	(segment
		(start 185.20664 -107.373928)
		(end 182.3212 -107.373928)
		(width 0.127)
		(layer "In6.Cu")
		(net "RST_CPU0_BUF_R_N")
	)
	(segment
		(start 205.227428 -109.799628)
		(end 205.71714 -110.28934)
		(width 0.127)
		(layer "In6.Cu")
		(net "RST_CPU0_BUF_R_N")
	)
	(segment
		(start 191.171068 -110.76432)
		(end 192.51168 -109.423708)
		(width 0.127)
		(layer "In6.Cu")
		(net "RST_CPU0_BUF_R_N")
	)
	(segment
		(start 205.160118 -109.799628)
		(end 205.227428 -109.799628)
		(width 0.127)
		(layer "In6.Cu")
		(net "RST_CPU0_BUF_R_N")
	)
	(segment
		(start 192.51168 -109.423708)
		(end 195.34632 -109.423708)
		(width 0.127)
		(layer "In6.Cu")
		(net "RST_CPU0_BUF_R_N")
	)
	(segment
		(start 205.71714 -110.28934)
		(end 205.71714 -111.457486)
		(width 0.127)
		(layer "In6.Cu")
		(net "RST_CPU0_BUF_R_N")
	)
	(segment
		(start 203.84516 -109.487208)
		(end 204.847698 -109.487208)
		(width 0.127)
		(layer "In6.Cu")
		(net "RST_CPU0_BUF_R_N")
	)
	(segment
		(start 183.755538 -116.175536)
		(end 184.155588 -116.575586)
		(width 0.12954)
		(layer "F.Cu")
		(net "ROT_P1_RST_IND_N_R")
	)
	(via
		(at 184.155588 -116.575586)
		(size 0.4572)
		(drill 0.254)
		(layers "F.Cu" "B.Cu")
		(net "ROT_P1_RST_IND_N_R")
	)
	(via
		(at 139.79906 -58.862468)
		(size 0.762)
		(drill 0.254)
		(layers "F.Cu" "B.Cu")
		(net "ROT_P1_RST_IND_N_R")
	)
	(via
		(at 140.89888 -8.346948)
		(size 0.508)
		(drill 0.254)
		(layers "F.Cu" "B.Cu")
		(net "ROT_P1_RST_IND_N_R")
	)
	(via
		(at 202.94346 -120.614948)
		(size 0.508)
		(drill 0.254)
		(layers "F.Cu" "B.Cu")
		(net "ROT_P1_RST_IND_N_R")
	)
	(segment
		(start 140.89888 -8.962898)
		(end 140.89888 -8.346948)
		(width 0.12954)
		(layer "B.Cu")
		(net "ROT_P1_RST_IND_N_R")
	)
	(segment
		(start 191.826134 -119.344948)
		(end 192.98031 -119.344948)
		(width 0.12954)
		(layer "B.Cu")
		(net "ROT_P1_RST_IND_N_R")
	)
	(segment
		(start 191.201294 -118.720108)
		(end 191.826134 -119.344948)
		(width 0.12954)
		(layer "B.Cu")
		(net "ROT_P1_RST_IND_N_R")
	)
	(segment
		(start 184.155588 -116.575586)
		(end 184.551066 -116.180108)
		(width 0.12954)
		(layer "B.Cu")
		(net "ROT_P1_RST_IND_N_R")
	)
	(segment
		(start 184.551066 -116.180108)
		(end 187.61964 -116.180108)
		(width 0.12954)
		(layer "B.Cu")
		(net "ROT_P1_RST_IND_N_R")
	)
	(segment
		(start 190.15964 -118.720108)
		(end 191.201294 -118.720108)
		(width 0.12954)
		(layer "B.Cu")
		(net "ROT_P1_RST_IND_N_R")
	)
	(segment
		(start 187.61964 -116.180108)
		(end 190.15964 -118.720108)
		(width 0.12954)
		(layer "B.Cu")
		(net "ROT_P1_RST_IND_N_R")
	)
	(segment
		(start 140.89888 -8.346948)
		(end 142.16888 -9.616948)
		(width 0.127)
		(layer "In2.Cu")
		(net "ROT_P1_RST_IND_N_R")
	)
	(segment
		(start 139.71016 -33.833308)
		(end 139.71016 -34.615628)
		(width 0.127)
		(layer "In2.Cu")
		(net "ROT_P1_RST_IND_N_R")
	)
	(segment
		(start 144.70888 -13.17244)
		(end 144.70888 -13.172948)
		(width 0.127)
		(layer "In2.Cu")
		(net "ROT_P1_RST_IND_N_R")
	)
	(segment
		(start 145.34388 -12.53744)
		(end 144.70888 -13.17244)
		(width 0.127)
		(layer "In2.Cu")
		(net "ROT_P1_RST_IND_N_R")
	)
	(segment
		(start 139.50188 -40.427148)
		(end 139.50188 -58.080148)
		(width 0.127)
		(layer "In2.Cu")
		(net "ROT_P1_RST_IND_N_R")
	)
	(segment
		(start 143.95323 -13.928598)
		(end 143.95323 -20.786598)
		(width 0.127)
		(layer "In2.Cu")
		(net "ROT_P1_RST_IND_N_R")
	)
	(segment
		(start 141.46784 -36.373308)
		(end 141.46784 -38.461188)
		(width 0.127)
		(layer "In2.Cu")
		(net "ROT_P1_RST_IND_N_R")
	)
	(segment
		(start 143.65224 -9.616948)
		(end 144.21485 -10.179558)
		(width 0.127)
		(layer "In2.Cu")
		(net "ROT_P1_RST_IND_N_R")
	)
	(segment
		(start 143.95323 -20.786598)
		(end 140.589 -24.150828)
		(width 0.127)
		(layer "In2.Cu")
		(net "ROT_P1_RST_IND_N_R")
	)
	(segment
		(start 145.34388 -12.029948)
		(end 145.34388 -12.53744)
		(width 0.127)
		(layer "In2.Cu")
		(net "ROT_P1_RST_IND_N_R")
	)
	(segment
		(start 140.589 -32.954468)
		(end 139.71016 -33.833308)
		(width 0.127)
		(layer "In2.Cu")
		(net "ROT_P1_RST_IND_N_R")
	)
	(segment
		(start 139.50188 -58.080148)
		(end 139.79906 -58.377328)
		(width 0.127)
		(layer "In2.Cu")
		(net "ROT_P1_RST_IND_N_R")
	)
	(segment
		(start 144.21485 -10.179558)
		(end 144.21485 -10.900918)
		(width 0.127)
		(layer "In2.Cu")
		(net "ROT_P1_RST_IND_N_R")
	)
	(segment
		(start 144.21485 -10.900918)
		(end 145.34388 -12.029948)
		(width 0.127)
		(layer "In2.Cu")
		(net "ROT_P1_RST_IND_N_R")
	)
	(segment
		(start 144.70888 -13.172948)
		(end 143.95323 -13.928598)
		(width 0.127)
		(layer "In2.Cu")
		(net "ROT_P1_RST_IND_N_R")
	)
	(segment
		(start 139.79906 -58.377328)
		(end 139.79906 -58.862468)
		(width 0.127)
		(layer "In2.Cu")
		(net "ROT_P1_RST_IND_N_R")
	)
	(segment
		(start 142.16888 -9.616948)
		(end 143.65224 -9.616948)
		(width 0.127)
		(layer "In2.Cu")
		(net "ROT_P1_RST_IND_N_R")
	)
	(segment
		(start 141.46784 -38.461188)
		(end 139.50188 -40.427148)
		(width 0.127)
		(layer "In2.Cu")
		(net "ROT_P1_RST_IND_N_R")
	)
	(segment
		(start 140.589 -24.150828)
		(end 140.589 -32.954468)
		(width 0.127)
		(layer "In2.Cu")
		(net "ROT_P1_RST_IND_N_R")
	)
	(segment
		(start 139.71016 -34.615628)
		(end 141.46784 -36.373308)
		(width 0.127)
		(layer "In2.Cu")
		(net "ROT_P1_RST_IND_N_R")
	)
	(segment
		(start 143.6497 -66.642488)
		(end 143.650716 -66.645028)
		(width 0.127)
		(layer "In4.Cu")
		(net "ROT_P1_RST_IND_N_R")
	)
	(segment
		(start 188.847222 -84.47659)
		(end 190.72606 -86.355428)
		(width 0.127)
		(layer "In4.Cu")
		(net "ROT_P1_RST_IND_N_R")
	)
	(segment
		(start 158.09722 -66.645028)
		(end 159.28848 -67.836288)
		(width 0.127)
		(layer "In4.Cu")
		(net "ROT_P1_RST_IND_N_R")
	)
	(segment
		(start 200.59904 -111.176308)
		(end 200.59904 -117.838728)
		(width 0.127)
		(layer "In4.Cu")
		(net "ROT_P1_RST_IND_N_R")
	)
	(segment
		(start 160.652968 -67.836288)
		(end 177.29327 -84.47659)
		(width 0.127)
		(layer "In4.Cu")
		(net "ROT_P1_RST_IND_N_R")
	)
	(segment
		(start 201.332592 -118.57228)
		(end 202.432412 -118.57228)
		(width 0.127)
		(layer "In4.Cu")
		(net "ROT_P1_RST_IND_N_R")
	)
	(segment
		(start 177.29327 -84.47659)
		(end 188.847222 -84.47659)
		(width 0.127)
		(layer "In4.Cu")
		(net "ROT_P1_RST_IND_N_R")
	)
	(segment
		(start 159.28848 -67.836288)
		(end 160.652968 -67.836288)
		(width 0.127)
		(layer "In4.Cu")
		(net "ROT_P1_RST_IND_N_R")
	)
	(segment
		(start 197.00875 -100.46335)
		(end 197.00875 -102.775258)
		(width 0.127)
		(layer "In4.Cu")
		(net "ROT_P1_RST_IND_N_R")
	)
	(segment
		(start 200.59904 -117.838728)
		(end 201.332592 -118.57228)
		(width 0.127)
		(layer "In4.Cu")
		(net "ROT_P1_RST_IND_N_R")
	)
	(segment
		(start 202.94346 -119.083328)
		(end 202.94346 -120.614948)
		(width 0.127)
		(layer "In4.Cu")
		(net "ROT_P1_RST_IND_N_R")
	)
	(segment
		(start 199.86625 -109.704378)
		(end 199.86625 -110.443518)
		(width 0.127)
		(layer "In4.Cu")
		(net "ROT_P1_RST_IND_N_R")
	)
	(segment
		(start 143.650716 -66.645028)
		(end 158.09722 -66.645028)
		(width 0.127)
		(layer "In4.Cu")
		(net "ROT_P1_RST_IND_N_R")
	)
	(segment
		(start 197.00875 -102.775258)
		(end 198.91756 -104.684068)
		(width 0.127)
		(layer "In4.Cu")
		(net "ROT_P1_RST_IND_N_R")
	)
	(segment
		(start 198.91756 -104.684068)
		(end 198.91756 -108.755688)
		(width 0.127)
		(layer "In4.Cu")
		(net "ROT_P1_RST_IND_N_R")
	)
	(segment
		(start 198.91756 -108.755688)
		(end 199.86625 -109.704378)
		(width 0.127)
		(layer "In4.Cu")
		(net "ROT_P1_RST_IND_N_R")
	)
	(segment
		(start 190.72606 -94.18066)
		(end 197.00875 -100.46335)
		(width 0.127)
		(layer "In4.Cu")
		(net "ROT_P1_RST_IND_N_R")
	)
	(segment
		(start 139.79906 -62.791848)
		(end 143.6497 -66.642488)
		(width 0.127)
		(layer "In4.Cu")
		(net "ROT_P1_RST_IND_N_R")
	)
	(segment
		(start 202.432412 -118.57228)
		(end 202.94346 -119.083328)
		(width 0.127)
		(layer "In4.Cu")
		(net "ROT_P1_RST_IND_N_R")
	)
	(segment
		(start 199.86625 -110.443518)
		(end 200.59904 -111.176308)
		(width 0.127)
		(layer "In4.Cu")
		(net "ROT_P1_RST_IND_N_R")
	)
	(segment
		(start 190.72606 -86.355428)
		(end 190.72606 -94.18066)
		(width 0.127)
		(layer "In4.Cu")
		(net "ROT_P1_RST_IND_N_R")
	)
	(segment
		(start 139.79906 -58.862468)
		(end 139.79906 -62.791848)
		(width 0.127)
		(layer "In4.Cu")
		(net "ROT_P1_RST_IND_N_R")
	)
	(segment
		(start 189.60846 -118.405148)
		(end 192.61836 -121.415048)
		(width 0.127)
		(layer "In6.Cu")
		(net "ROT_P1_RST_IND_N_R")
	)
	(segment
		(start 200.222104 -121.32818)
		(end 200.227184 -121.33326)
		(width 0.127)
		(layer "In6.Cu")
		(net "ROT_P1_RST_IND_N_R")
	)
	(segment
		(start 186.089544 -118.578884)
		(end 186.26328 -118.405148)
		(width 0.127)
		(layer "In6.Cu")
		(net "ROT_P1_RST_IND_N_R")
	)
	(segment
		(start 186.26328 -118.405148)
		(end 189.60846 -118.405148)
		(width 0.127)
		(layer "In6.Cu")
		(net "ROT_P1_RST_IND_N_R")
	)
	(segment
		(start 199.030082 -121.262648)
		(end 200.156318 -121.262648)
		(width 0.127)
		(layer "In6.Cu")
		(net "ROT_P1_RST_IND_N_R")
	)
	(segment
		(start 200.156318 -121.262648)
		(end 200.22185 -121.32818)
		(width 0.127)
		(layer "In6.Cu")
		(net "ROT_P1_RST_IND_N_R")
	)
	(segment
		(start 184.548526 -118.324122)
		(end 184.803288 -118.578884)
		(width 0.127)
		(layer "In6.Cu")
		(net "ROT_P1_RST_IND_N_R")
	)
	(segment
		(start 184.318402 -117.782594)
		(end 184.548526 -118.012718)
		(width 0.127)
		(layer "In6.Cu")
		(net "ROT_P1_RST_IND_N_R")
	)
	(segment
		(start 200.227184 -121.33326)
		(end 202.225148 -121.33326)
		(width 0.127)
		(layer "In6.Cu")
		(net "ROT_P1_RST_IND_N_R")
	)
	(segment
		(start 183.76265 -117.538246)
		(end 184.006998 -117.782594)
		(width 0.127)
		(layer "In6.Cu")
		(net "ROT_P1_RST_IND_N_R")
	)
	(segment
		(start 184.006998 -117.782594)
		(end 184.318402 -117.782594)
		(width 0.127)
		(layer "In6.Cu")
		(net "ROT_P1_RST_IND_N_R")
	)
	(segment
		(start 184.803288 -118.578884)
		(end 186.089544 -118.578884)
		(width 0.127)
		(layer "In6.Cu")
		(net "ROT_P1_RST_IND_N_R")
	)
	(segment
		(start 184.155588 -116.575586)
		(end 183.76265 -116.968524)
		(width 0.127)
		(layer "In6.Cu")
		(net "ROT_P1_RST_IND_N_R")
	)
	(segment
		(start 192.61836 -121.415048)
		(end 198.877682 -121.415048)
		(width 0.127)
		(layer "In6.Cu")
		(net "ROT_P1_RST_IND_N_R")
	)
	(segment
		(start 184.548526 -118.012718)
		(end 184.548526 -118.324122)
		(width 0.127)
		(layer "In6.Cu")
		(net "ROT_P1_RST_IND_N_R")
	)
	(segment
		(start 198.877682 -121.415048)
		(end 199.030082 -121.262648)
		(width 0.127)
		(layer "In6.Cu")
		(net "ROT_P1_RST_IND_N_R")
	)
	(segment
		(start 200.22185 -121.32818)
		(end 200.222104 -121.32818)
		(width 0.127)
		(layer "In6.Cu")
		(net "ROT_P1_RST_IND_N_R")
	)
	(segment
		(start 202.225148 -121.33326)
		(end 202.94346 -120.614948)
		(width 0.127)
		(layer "In6.Cu")
		(net "ROT_P1_RST_IND_N_R")
	)
	(segment
		(start 183.76265 -116.968524)
		(end 183.76265 -117.538246)
		(width 0.127)
		(layer "In6.Cu")
		(net "ROT_P1_RST_IND_N_R")
	)
	(segment
		(start 139.946888 -10.897362)
		(end 139.946634 -10.897108)
		(width 0.12954)
		(layer "F.Cu")
		(net "ROT_P1_RST_IND_N")
	)
	(segment
		(start 139.946888 -13.600176)
		(end 139.946888 -10.897362)
		(width 0.12954)
		(layer "F.Cu")
		(net "ROT_P1_RST_IND_N")
	)
	(via
		(at 139.946634 -10.897108)
		(size 0.508)
		(drill 0.254)
		(layers "F.Cu" "B.Cu")
		(net "ROT_P1_RST_IND_N")
	)
	(segment
		(start 140.89888 -9.944862)
		(end 140.89888 -9.762998)
		(width 0.12954)
		(layer "B.Cu")
		(net "ROT_P1_RST_IND_N")
	)
	(segment
		(start 139.946634 -10.897108)
		(end 140.89888 -9.944862)
		(width 0.12954)
		(layer "B.Cu")
		(net "ROT_P1_RST_IND_N")
	)
	(segment
		(start 197.108064 -78.42377)
		(end 197.89648 -78.42377)
		(width 0.12954)
		(layer "F.Cu")
		(net "RMII_OCP_BMC_RXD_1")
	)
	(segment
		(start 164.467032 -17.981676)
		(end 163.91382 -18.534888)
		(width 0.12954)
		(layer "F.Cu")
		(net "RMII_OCP_BMC_RXD_1")
	)
	(segment
		(start 197.89648 -78.42377)
		(end 199.635364 -78.42377)
		(width 0.12954)
		(layer "F.Cu")
		(net "RMII_OCP_BMC_RXD_1")
	)
	(segment
		(start 164.467032 -16.550132)
		(end 164.467032 -17.981676)
		(width 0.12954)
		(layer "F.Cu")
		(net "RMII_OCP_BMC_RXD_1")
	)
	(via
		(at 197.89648 -78.42377)
		(size 0.508)
		(drill 0.254)
		(layers "F.Cu" "B.Cu")
		(net "RMII_OCP_BMC_RXD_1")
	)
	(via
		(at 218.41968 -78.448408)
		(size 0.508)
		(drill 0.254)
		(layers "F.Cu" "B.Cu")
		(net "RMII_OCP_BMC_RXD_1")
	)
	(via
		(at 163.91382 -18.534888)
		(size 0.508)
		(drill 0.254)
		(layers "F.Cu" "B.Cu")
		(net "RMII_OCP_BMC_RXD_1")
	)
	(segment
		(start 216.65311 -78.448408)
		(end 218.41968 -78.448408)
		(width 0.12954)
		(layer "B.Cu")
		(net "RMII_OCP_BMC_RXD_1")
	)
	(segment
		(start 169.19829 -25.683972)
		(end 166.751 -23.236682)
		(width 0.127)
		(layer "In2.Cu")
		(net "RMII_OCP_BMC_RXD_1")
	)
	(segment
		(start 188.3156 -45.811186)
		(end 185.820558 -43.316144)
		(width 0.127)
		(layer "In2.Cu")
		(net "RMII_OCP_BMC_RXD_1")
	)
	(segment
		(start 180.768244 -24.39035)
		(end 174.689516 -24.39035)
		(width 0.127)
		(layer "In2.Cu")
		(net "RMII_OCP_BMC_RXD_1")
	)
	(segment
		(start 192.154302 -78.42377)
		(end 188.3156 -74.585068)
		(width 0.127)
		(layer "In2.Cu")
		(net "RMII_OCP_BMC_RXD_1")
	)
	(segment
		(start 188.3156 -74.585068)
		(end 188.3156 -45.811186)
		(width 0.127)
		(layer "In2.Cu")
		(net "RMII_OCP_BMC_RXD_1")
	)
	(segment
		(start 163.91382 -18.81886)
		(end 163.91382 -18.534888)
		(width 0.127)
		(layer "In2.Cu")
		(net "RMII_OCP_BMC_RXD_1")
	)
	(segment
		(start 166.751 -22.310852)
		(end 164.38372 -19.943572)
		(width 0.127)
		(layer "In2.Cu")
		(net "RMII_OCP_BMC_RXD_1")
	)
	(segment
		(start 185.820558 -35.084004)
		(end 186.298078 -34.606484)
		(width 0.127)
		(layer "In2.Cu")
		(net "RMII_OCP_BMC_RXD_1")
	)
	(segment
		(start 164.38372 -19.943572)
		(end 164.38372 -19.28876)
		(width 0.127)
		(layer "In2.Cu")
		(net "RMII_OCP_BMC_RXD_1")
	)
	(segment
		(start 197.89648 -78.42377)
		(end 192.154302 -78.42377)
		(width 0.127)
		(layer "In2.Cu")
		(net "RMII_OCP_BMC_RXD_1")
	)
	(segment
		(start 182.183278 -27.761184)
		(end 182.183278 -25.805384)
		(width 0.127)
		(layer "In2.Cu")
		(net "RMII_OCP_BMC_RXD_1")
	)
	(segment
		(start 186.298078 -31.875984)
		(end 182.183278 -27.761184)
		(width 0.127)
		(layer "In2.Cu")
		(net "RMII_OCP_BMC_RXD_1")
	)
	(segment
		(start 173.395894 -25.683972)
		(end 169.19829 -25.683972)
		(width 0.127)
		(layer "In2.Cu")
		(net "RMII_OCP_BMC_RXD_1")
	)
	(segment
		(start 174.689516 -24.39035)
		(end 173.395894 -25.683972)
		(width 0.127)
		(layer "In2.Cu")
		(net "RMII_OCP_BMC_RXD_1")
	)
	(segment
		(start 164.38372 -19.28876)
		(end 163.91382 -18.81886)
		(width 0.127)
		(layer "In2.Cu")
		(net "RMII_OCP_BMC_RXD_1")
	)
	(segment
		(start 185.820558 -43.316144)
		(end 185.820558 -35.084004)
		(width 0.127)
		(layer "In2.Cu")
		(net "RMII_OCP_BMC_RXD_1")
	)
	(segment
		(start 182.183278 -25.805384)
		(end 180.768244 -24.39035)
		(width 0.127)
		(layer "In2.Cu")
		(net "RMII_OCP_BMC_RXD_1")
	)
	(segment
		(start 186.298078 -34.606484)
		(end 186.298078 -31.875984)
		(width 0.127)
		(layer "In2.Cu")
		(net "RMII_OCP_BMC_RXD_1")
	)
	(segment
		(start 166.751 -23.236682)
		(end 166.751 -22.310852)
		(width 0.127)
		(layer "In2.Cu")
		(net "RMII_OCP_BMC_RXD_1")
	)
	(segment
		(start 206.443072 -78.448408)
		(end 204.681074 -80.210406)
		(width 0.127)
		(layer "In4.Cu")
		(net "RMII_OCP_BMC_RXD_1")
	)
	(segment
		(start 204.681074 -80.210406)
		(end 198.53021 -80.210406)
		(width 0.127)
		(layer "In4.Cu")
		(net "RMII_OCP_BMC_RXD_1")
	)
	(segment
		(start 218.41968 -78.448408)
		(end 206.443072 -78.448408)
		(width 0.127)
		(layer "In4.Cu")
		(net "RMII_OCP_BMC_RXD_1")
	)
	(segment
		(start 198.53021 -80.210406)
		(end 197.89648 -79.576676)
		(width 0.127)
		(layer "In4.Cu")
		(net "RMII_OCP_BMC_RXD_1")
	)
	(segment
		(start 197.89648 -79.576676)
		(end 197.89648 -78.42377)
		(width 0.127)
		(layer "In4.Cu")
		(net "RMII_OCP_BMC_RXD_1")
	)
	(segment
		(start 164.991542 -18.547334)
		(end 163.947348 -19.591528)
		(width 0.12954)
		(layer "F.Cu")
		(net "RMII_OCP_BMC_RXD_0")
	)
	(segment
		(start 164.991542 -17.54124)
		(end 164.991542 -18.547334)
		(width 0.12954)
		(layer "F.Cu")
		(net "RMII_OCP_BMC_RXD_0")
	)
	(segment
		(start 165.06698 -16.550132)
		(end 165.06698 -17.465802)
		(width 0.12954)
		(layer "F.Cu")
		(net "RMII_OCP_BMC_RXD_0")
	)
	(segment
		(start 165.06698 -17.465802)
		(end 164.991542 -17.54124)
		(width 0.12954)
		(layer "F.Cu")
		(net "RMII_OCP_BMC_RXD_0")
	)
	(segment
		(start 197.89648 -77.06614)
		(end 199.656954 -77.06614)
		(width 0.12954)
		(layer "F.Cu")
		(net "RMII_OCP_BMC_RXD_0")
	)
	(segment
		(start 163.947348 -19.591528)
		(end 163.91382 -19.591528)
		(width 0.12954)
		(layer "F.Cu")
		(net "RMII_OCP_BMC_RXD_0")
	)
	(segment
		(start 197.129654 -77.06614)
		(end 197.89648 -77.06614)
		(width 0.12954)
		(layer "F.Cu")
		(net "RMII_OCP_BMC_RXD_0")
	)
	(via
		(at 197.89648 -77.06614)
		(size 0.508)
		(drill 0.254)
		(layers "F.Cu" "B.Cu")
		(net "RMII_OCP_BMC_RXD_0")
	)
	(via
		(at 217.29192 -76.121768)
		(size 0.508)
		(drill 0.254)
		(layers "F.Cu" "B.Cu")
		(net "RMII_OCP_BMC_RXD_0")
	)
	(via
		(at 163.91382 -19.591528)
		(size 0.508)
		(drill 0.254)
		(layers "F.Cu" "B.Cu")
		(net "RMII_OCP_BMC_RXD_0")
	)
	(segment
		(start 217.29192 -76.121768)
		(end 216.82202 -76.591668)
		(width 0.12954)
		(layer "B.Cu")
		(net "RMII_OCP_BMC_RXD_0")
	)
	(segment
		(start 216.82202 -76.591668)
		(end 216.612724 -76.591668)
		(width 0.12954)
		(layer "B.Cu")
		(net "RMII_OCP_BMC_RXD_0")
	)
	(segment
		(start 187.8838 -45.990256)
		(end 185.313574 -43.42003)
		(width 0.127)
		(layer "In2.Cu")
		(net "RMII_OCP_BMC_RXD_0")
	)
	(segment
		(start 185.791094 -34.396426)
		(end 185.791094 -32.086042)
		(width 0.127)
		(layer "In2.Cu")
		(net "RMII_OCP_BMC_RXD_0")
	)
	(segment
		(start 185.313574 -43.42003)
		(end 185.313574 -34.873946)
		(width 0.127)
		(layer "In2.Cu")
		(net "RMII_OCP_BMC_RXD_0")
	)
	(segment
		(start 181.676294 -27.971242)
		(end 181.676294 -26.015442)
		(width 0.127)
		(layer "In2.Cu")
		(net "RMII_OCP_BMC_RXD_0")
	)
	(segment
		(start 163.91382 -20.084796)
		(end 163.91382 -19.591528)
		(width 0.127)
		(layer "In2.Cu")
		(net "RMII_OCP_BMC_RXD_0")
	)
	(segment
		(start 197.000368 -80.305148)
		(end 195.028058 -80.305148)
		(width 0.127)
		(layer "In2.Cu")
		(net "RMII_OCP_BMC_RXD_0")
	)
	(segment
		(start 180.558186 -24.897334)
		(end 174.919894 -24.897334)
		(width 0.127)
		(layer "In2.Cu")
		(net "RMII_OCP_BMC_RXD_0")
	)
	(segment
		(start 173.701456 -26.115772)
		(end 169.01922 -26.115772)
		(width 0.127)
		(layer "In2.Cu")
		(net "RMII_OCP_BMC_RXD_0")
	)
	(segment
		(start 169.01922 -26.115772)
		(end 166.30142 -23.397972)
		(width 0.127)
		(layer "In2.Cu")
		(net "RMII_OCP_BMC_RXD_0")
	)
	(segment
		(start 187.8838 -75.118214)
		(end 187.8838 -45.990256)
		(width 0.127)
		(layer "In2.Cu")
		(net "RMII_OCP_BMC_RXD_0")
	)
	(segment
		(start 181.676294 -26.015442)
		(end 180.558186 -24.897334)
		(width 0.127)
		(layer "In2.Cu")
		(net "RMII_OCP_BMC_RXD_0")
	)
	(segment
		(start 185.313574 -34.873946)
		(end 185.791094 -34.396426)
		(width 0.127)
		(layer "In2.Cu")
		(net "RMII_OCP_BMC_RXD_0")
	)
	(segment
		(start 198.65848 -78.647036)
		(end 197.000368 -80.305148)
		(width 0.127)
		(layer "In2.Cu")
		(net "RMII_OCP_BMC_RXD_0")
	)
	(segment
		(start 198.162672 -77.06614)
		(end 198.65848 -77.561948)
		(width 0.127)
		(layer "In2.Cu")
		(net "RMII_OCP_BMC_RXD_0")
	)
	(segment
		(start 197.89648 -77.06614)
		(end 198.162672 -77.06614)
		(width 0.127)
		(layer "In2.Cu")
		(net "RMII_OCP_BMC_RXD_0")
	)
	(segment
		(start 195.028058 -80.305148)
		(end 194.3354 -79.61249)
		(width 0.127)
		(layer "In2.Cu")
		(net "RMII_OCP_BMC_RXD_0")
	)
	(segment
		(start 174.919894 -24.897334)
		(end 173.701456 -26.115772)
		(width 0.127)
		(layer "In2.Cu")
		(net "RMII_OCP_BMC_RXD_0")
	)
	(segment
		(start 166.30142 -23.397972)
		(end 166.30142 -22.472396)
		(width 0.127)
		(layer "In2.Cu")
		(net "RMII_OCP_BMC_RXD_0")
	)
	(segment
		(start 166.30142 -22.472396)
		(end 163.91382 -20.084796)
		(width 0.127)
		(layer "In2.Cu")
		(net "RMII_OCP_BMC_RXD_0")
	)
	(segment
		(start 185.791094 -32.086042)
		(end 181.676294 -27.971242)
		(width 0.127)
		(layer "In2.Cu")
		(net "RMII_OCP_BMC_RXD_0")
	)
	(segment
		(start 192.378076 -79.61249)
		(end 187.8838 -75.118214)
		(width 0.127)
		(layer "In2.Cu")
		(net "RMII_OCP_BMC_RXD_0")
	)
	(segment
		(start 198.65848 -77.561948)
		(end 198.65848 -78.647036)
		(width 0.127)
		(layer "In2.Cu")
		(net "RMII_OCP_BMC_RXD_0")
	)
	(segment
		(start 194.3354 -79.61249)
		(end 192.378076 -79.61249)
		(width 0.127)
		(layer "In2.Cu")
		(net "RMII_OCP_BMC_RXD_0")
	)
	(segment
		(start 217.29192 -76.121768)
		(end 216.99474 -76.418948)
		(width 0.127)
		(layer "In4.Cu")
		(net "RMII_OCP_BMC_RXD_0")
	)
	(segment
		(start 198.594472 -77.06614)
		(end 197.89648 -77.06614)
		(width 0.127)
		(layer "In4.Cu")
		(net "RMII_OCP_BMC_RXD_0")
	)
	(segment
		(start 216.99474 -76.418948)
		(end 207.80248 -76.418948)
		(width 0.127)
		(layer "In4.Cu")
		(net "RMII_OCP_BMC_RXD_0")
	)
	(segment
		(start 207.80248 -76.418948)
		(end 206.20228 -78.019148)
		(width 0.127)
		(layer "In4.Cu")
		(net "RMII_OCP_BMC_RXD_0")
	)
	(segment
		(start 206.20228 -78.019148)
		(end 199.54748 -78.019148)
		(width 0.127)
		(layer "In4.Cu")
		(net "RMII_OCP_BMC_RXD_0")
	)
	(segment
		(start 199.54748 -78.019148)
		(end 198.594472 -77.06614)
		(width 0.127)
		(layer "In4.Cu")
		(net "RMII_OCP_BMC_RXD_0")
	)
	(segment
		(start 168.003728 -17.654778)
		(end 168.043098 -17.694148)
		(width 0.12954)
		(layer "F.Cu")
		(net "RMII_OCP_BMC_CRSDV")
	)
	(segment
		(start 168.003728 -16.613378)
		(end 168.003728 -17.654778)
		(width 0.12954)
		(layer "F.Cu")
		(net "RMII_OCP_BMC_CRSDV")
	)
	(segment
		(start 168.066974 -16.550132)
		(end 168.003728 -16.613378)
		(width 0.12954)
		(layer "F.Cu")
		(net "RMII_OCP_BMC_CRSDV")
	)
	(segment
		(start 194.771518 -76.016866)
		(end 197.476618 -76.016866)
		(width 0.12954)
		(layer "F.Cu")
		(net "RMII_OCP_BMC_CRSDV")
	)
	(segment
		(start 197.476618 -76.016866)
		(end 197.476618 -75.26401)
		(width 0.12954)
		(layer "F.Cu")
		(net "RMII_OCP_BMC_CRSDV")
	)
	(via
		(at 168.043098 -17.694148)
		(size 0.508)
		(drill 0.254)
		(layers "F.Cu" "B.Cu")
		(net "RMII_OCP_BMC_CRSDV")
	)
	(via
		(at 202.672696 -75.782932)
		(size 0.508)
		(drill 0.254)
		(layers "F.Cu" "B.Cu")
		(net "RMII_OCP_BMC_CRSDV")
	)
	(via
		(at 197.476618 -75.26401)
		(size 0.508)
		(drill 0.254)
		(layers "F.Cu" "B.Cu")
		(net "RMII_OCP_BMC_CRSDV")
	)
	(segment
		(start 202.672696 -75.053952)
		(end 202.672696 -75.782932)
		(width 0.12954)
		(layer "B.Cu")
		(net "RMII_OCP_BMC_CRSDV")
	)
	(segment
		(start 191.10198 -71.48322)
		(end 195.555108 -75.936348)
		(width 0.127)
		(layer "In2.Cu")
		(net "RMII_OCP_BMC_CRSDV")
	)
	(segment
		(start 168.3258 -23.398988)
		(end 169.73804 -24.811228)
		(width 0.127)
		(layer "In2.Cu")
		(net "RMII_OCP_BMC_CRSDV")
	)
	(segment
		(start 188.87948 -43.627548)
		(end 191.10198 -45.850048)
		(width 0.127)
		(layer "In2.Cu")
		(net "RMII_OCP_BMC_CRSDV")
	)
	(segment
		(start 181.170072 -23.420832)
		(end 183.152796 -25.403556)
		(width 0.127)
		(layer "In2.Cu")
		(net "RMII_OCP_BMC_CRSDV")
	)
	(segment
		(start 196.80428 -75.936348)
		(end 197.476618 -75.26401)
		(width 0.127)
		(layer "In2.Cu")
		(net "RMII_OCP_BMC_CRSDV")
	)
	(segment
		(start 169.73804 -24.811228)
		(end 172.846492 -24.811228)
		(width 0.127)
		(layer "In2.Cu")
		(net "RMII_OCP_BMC_CRSDV")
	)
	(segment
		(start 166.724838 -19.629374)
		(end 166.43096 -19.923252)
		(width 0.127)
		(layer "In2.Cu")
		(net "RMII_OCP_BMC_CRSDV")
	)
	(segment
		(start 167.386 -18.351246)
		(end 167.386 -19.291808)
		(width 0.127)
		(layer "In2.Cu")
		(net "RMII_OCP_BMC_CRSDV")
	)
	(segment
		(start 168.3258 -22.336252)
		(end 168.3258 -23.398988)
		(width 0.127)
		(layer "In2.Cu")
		(net "RMII_OCP_BMC_CRSDV")
	)
	(segment
		(start 167.048434 -19.629374)
		(end 166.724838 -19.629374)
		(width 0.127)
		(layer "In2.Cu")
		(net "RMII_OCP_BMC_CRSDV")
	)
	(segment
		(start 166.43096 -20.441412)
		(end 168.3258 -22.336252)
		(width 0.127)
		(layer "In2.Cu")
		(net "RMII_OCP_BMC_CRSDV")
	)
	(segment
		(start 191.10198 -45.850048)
		(end 191.10198 -71.48322)
		(width 0.127)
		(layer "In2.Cu")
		(net "RMII_OCP_BMC_CRSDV")
	)
	(segment
		(start 172.846492 -24.811228)
		(end 174.236888 -23.420832)
		(width 0.127)
		(layer "In2.Cu")
		(net "RMII_OCP_BMC_CRSDV")
	)
	(segment
		(start 168.043098 -17.694148)
		(end 167.386 -18.351246)
		(width 0.127)
		(layer "In2.Cu")
		(net "RMII_OCP_BMC_CRSDV")
	)
	(segment
		(start 183.152796 -25.403556)
		(end 183.152796 -27.359356)
		(width 0.127)
		(layer "In2.Cu")
		(net "RMII_OCP_BMC_CRSDV")
	)
	(segment
		(start 166.43096 -19.923252)
		(end 166.43096 -20.441412)
		(width 0.127)
		(layer "In2.Cu")
		(net "RMII_OCP_BMC_CRSDV")
	)
	(segment
		(start 195.555108 -75.936348)
		(end 196.80428 -75.936348)
		(width 0.127)
		(layer "In2.Cu")
		(net "RMII_OCP_BMC_CRSDV")
	)
	(segment
		(start 188.87948 -33.08604)
		(end 188.87948 -43.627548)
		(width 0.127)
		(layer "In2.Cu")
		(net "RMII_OCP_BMC_CRSDV")
	)
	(segment
		(start 167.386 -19.291808)
		(end 167.048434 -19.629374)
		(width 0.127)
		(layer "In2.Cu")
		(net "RMII_OCP_BMC_CRSDV")
	)
	(segment
		(start 174.236888 -23.420832)
		(end 181.170072 -23.420832)
		(width 0.127)
		(layer "In2.Cu")
		(net "RMII_OCP_BMC_CRSDV")
	)
	(segment
		(start 183.152796 -27.359356)
		(end 188.87948 -33.08604)
		(width 0.127)
		(layer "In2.Cu")
		(net "RMII_OCP_BMC_CRSDV")
	)
	(segment
		(start 202.44308 -74.717148)
		(end 197.87108 -74.717148)
		(width 0.127)
		(layer "In4.Cu")
		(net "RMII_OCP_BMC_CRSDV")
	)
	(segment
		(start 202.67168 -75.781916)
		(end 202.67168 -74.945748)
		(width 0.127)
		(layer "In4.Cu")
		(net "RMII_OCP_BMC_CRSDV")
	)
	(segment
		(start 197.476618 -75.11161)
		(end 197.476618 -75.26401)
		(width 0.127)
		(layer "In4.Cu")
		(net "RMII_OCP_BMC_CRSDV")
	)
	(segment
		(start 202.67168 -74.945748)
		(end 202.44308 -74.717148)
		(width 0.127)
		(layer "In4.Cu")
		(net "RMII_OCP_BMC_CRSDV")
	)
	(segment
		(start 202.672696 -75.782932)
		(end 202.67168 -75.781916)
		(width 0.127)
		(layer "In4.Cu")
		(net "RMII_OCP_BMC_CRSDV")
	)
	(segment
		(start 197.87108 -74.717148)
		(end 197.476618 -75.11161)
		(width 0.127)
		(layer "In4.Cu")
		(net "RMII_OCP_BMC_CRSDV")
	)
	(segment
		(start 167.466772 -17.466056)
		(end 167.466772 -18.386044)
		(width 0.12954)
		(layer "F.Cu")
		(net "RMII_BMC_OCP_TX_EN")
	)
	(segment
		(start 214.75827 -74.854308)
		(end 213.32444 -74.854308)
		(width 0.12954)
		(layer "F.Cu")
		(net "RMII_BMC_OCP_TX_EN")
	)
	(segment
		(start 167.467026 -16.550132)
		(end 167.467026 -17.465802)
		(width 0.12954)
		(layer "F.Cu")
		(net "RMII_BMC_OCP_TX_EN")
	)
	(segment
		(start 166.732204 -19.120612)
		(end 166.732204 -19.159474)
		(width 0.12954)
		(layer "F.Cu")
		(net "RMII_BMC_OCP_TX_EN")
	)
	(segment
		(start 167.467026 -17.465802)
		(end 167.466772 -17.466056)
		(width 0.12954)
		(layer "F.Cu")
		(net "RMII_BMC_OCP_TX_EN")
	)
	(segment
		(start 214.75827 -73.041764)
		(end 214.75827 -74.854308)
		(width 0.12954)
		(layer "F.Cu")
		(net "RMII_BMC_OCP_TX_EN")
	)
	(segment
		(start 167.466772 -18.386044)
		(end 166.732204 -19.120612)
		(width 0.12954)
		(layer "F.Cu")
		(net "RMII_BMC_OCP_TX_EN")
	)
	(via
		(at 213.32444 -74.854308)
		(size 0.508)
		(drill 0.254)
		(layers "F.Cu" "B.Cu")
		(net "RMII_BMC_OCP_TX_EN")
	)
	(via
		(at 166.732204 -19.159474)
		(size 0.508)
		(drill 0.254)
		(layers "F.Cu" "B.Cu")
		(net "RMII_BMC_OCP_TX_EN")
	)
	(via
		(at 190.20028 -72.278748)
		(size 0.508)
		(drill 0.254)
		(layers "F.Cu" "B.Cu")
		(net "RMII_BMC_OCP_TX_EN")
	)
	(segment
		(start 191.615822 -69.885306)
		(end 191.615822 -69.46646)
		(width 0.12954)
		(layer "B.Cu")
		(net "RMII_BMC_OCP_TX_EN")
	)
	(segment
		(start 191.592708 -69.90842)
		(end 191.615822 -69.885306)
		(width 0.12954)
		(layer "B.Cu")
		(net "RMII_BMC_OCP_TX_EN")
	)
	(segment
		(start 191.592708 -70.88632)
		(end 191.592708 -69.90842)
		(width 0.12954)
		(layer "B.Cu")
		(net "RMII_BMC_OCP_TX_EN")
	)
	(segment
		(start 191.615822 -69.46646)
		(end 191.592708 -69.443346)
		(width 0.12954)
		(layer "B.Cu")
		(net "RMII_BMC_OCP_TX_EN")
	)
	(segment
		(start 190.20028 -72.278748)
		(end 191.592708 -70.88632)
		(width 0.12954)
		(layer "B.Cu")
		(net "RMII_BMC_OCP_TX_EN")
	)
	(segment
		(start 182.685944 -25.597104)
		(end 180.976524 -23.887684)
		(width 0.127)
		(layer "In2.Cu")
		(net "RMII_BMC_OCP_TX_EN")
	)
	(segment
		(start 174.481236 -23.887684)
		(end 173.118272 -25.250648)
		(width 0.127)
		(layer "In2.Cu")
		(net "RMII_BMC_OCP_TX_EN")
	)
	(segment
		(start 186.450224 -42.065702)
		(end 187.25134 -42.065702)
		(width 0.127)
		(layer "In2.Cu")
		(net "RMII_BMC_OCP_TX_EN")
	)
	(segment
		(start 169.4434 -25.250648)
		(end 167.894 -23.701248)
		(width 0.127)
		(layer "In2.Cu")
		(net "RMII_BMC_OCP_TX_EN")
	)
	(segment
		(start 165.96868 -19.568668)
		(end 166.377874 -19.159474)
		(width 0.127)
		(layer "In2.Cu")
		(net "RMII_BMC_OCP_TX_EN")
	)
	(segment
		(start 186.450224 -41.202102)
		(end 186.323224 -41.075102)
		(width 0.127)
		(layer "In2.Cu")
		(net "RMII_BMC_OCP_TX_EN")
	)
	(segment
		(start 180.976524 -23.887684)
		(end 174.481236 -23.887684)
		(width 0.127)
		(layer "In2.Cu")
		(net "RMII_BMC_OCP_TX_EN")
	)
	(segment
		(start 166.377874 -19.159474)
		(end 166.732204 -19.159474)
		(width 0.127)
		(layer "In2.Cu")
		(net "RMII_BMC_OCP_TX_EN")
	)
	(segment
		(start 187.25134 -42.065702)
		(end 187.37834 -41.938702)
		(width 0.127)
		(layer "In2.Cu")
		(net "RMII_BMC_OCP_TX_EN")
	)
	(segment
		(start 186.323224 -35.292284)
		(end 186.800744 -34.814764)
		(width 0.127)
		(layer "In2.Cu")
		(net "RMII_BMC_OCP_TX_EN")
	)
	(segment
		(start 187.25134 -41.202102)
		(end 186.450224 -41.202102)
		(width 0.127)
		(layer "In2.Cu")
		(net "RMII_BMC_OCP_TX_EN")
	)
	(segment
		(start 167.894 -22.515576)
		(end 165.96868 -20.590256)
		(width 0.127)
		(layer "In2.Cu")
		(net "RMII_BMC_OCP_TX_EN")
	)
	(segment
		(start 187.37834 -41.329102)
		(end 187.25134 -41.202102)
		(width 0.127)
		(layer "In2.Cu")
		(net "RMII_BMC_OCP_TX_EN")
	)
	(segment
		(start 186.800744 -31.667704)
		(end 182.685944 -27.552904)
		(width 0.127)
		(layer "In2.Cu")
		(net "RMII_BMC_OCP_TX_EN")
	)
	(segment
		(start 182.685944 -27.552904)
		(end 182.685944 -25.597104)
		(width 0.127)
		(layer "In2.Cu")
		(net "RMII_BMC_OCP_TX_EN")
	)
	(segment
		(start 186.323224 -43.20794)
		(end 186.323224 -42.192702)
		(width 0.127)
		(layer "In2.Cu")
		(net "RMII_BMC_OCP_TX_EN")
	)
	(segment
		(start 167.894 -23.701248)
		(end 167.894 -22.515576)
		(width 0.127)
		(layer "In2.Cu")
		(net "RMII_BMC_OCP_TX_EN")
	)
	(segment
		(start 188.7474 -45.632116)
		(end 186.323224 -43.20794)
		(width 0.127)
		(layer "In2.Cu")
		(net "RMII_BMC_OCP_TX_EN")
	)
	(segment
		(start 187.37834 -41.938702)
		(end 187.37834 -41.329102)
		(width 0.127)
		(layer "In2.Cu")
		(net "RMII_BMC_OCP_TX_EN")
	)
	(segment
		(start 186.323224 -41.075102)
		(end 186.323224 -35.292284)
		(width 0.127)
		(layer "In2.Cu")
		(net "RMII_BMC_OCP_TX_EN")
	)
	(segment
		(start 173.118272 -25.250648)
		(end 169.4434 -25.250648)
		(width 0.127)
		(layer "In2.Cu")
		(net "RMII_BMC_OCP_TX_EN")
	)
	(segment
		(start 190.20028 -72.278748)
		(end 188.7474 -70.825868)
		(width 0.127)
		(layer "In2.Cu")
		(net "RMII_BMC_OCP_TX_EN")
	)
	(segment
		(start 165.96868 -20.590256)
		(end 165.96868 -19.568668)
		(width 0.127)
		(layer "In2.Cu")
		(net "RMII_BMC_OCP_TX_EN")
	)
	(segment
		(start 186.800744 -34.814764)
		(end 186.800744 -31.667704)
		(width 0.127)
		(layer "In2.Cu")
		(net "RMII_BMC_OCP_TX_EN")
	)
	(segment
		(start 186.323224 -42.192702)
		(end 186.450224 -42.065702)
		(width 0.127)
		(layer "In2.Cu")
		(net "RMII_BMC_OCP_TX_EN")
	)
	(segment
		(start 188.7474 -70.825868)
		(end 188.7474 -45.632116)
		(width 0.127)
		(layer "In2.Cu")
		(net "RMII_BMC_OCP_TX_EN")
	)
	(segment
		(start 204.50048 -75.860148)
		(end 202.82408 -74.183748)
		(width 0.127)
		(layer "In4.Cu")
		(net "RMII_BMC_OCP_TX_EN")
	)
	(segment
		(start 213.32444 -74.854308)
		(end 213.32444 -74.884788)
		(width 0.127)
		(layer "In4.Cu")
		(net "RMII_BMC_OCP_TX_EN")
	)
	(segment
		(start 213.32444 -74.884788)
		(end 212.34908 -75.860148)
		(width 0.127)
		(layer "In4.Cu")
		(net "RMII_BMC_OCP_TX_EN")
	)
	(segment
		(start 191.31788 -74.183748)
		(end 190.20028 -73.066148)
		(width 0.127)
		(layer "In4.Cu")
		(net "RMII_BMC_OCP_TX_EN")
	)
	(segment
		(start 202.82408 -74.183748)
		(end 191.31788 -74.183748)
		(width 0.127)
		(layer "In4.Cu")
		(net "RMII_BMC_OCP_TX_EN")
	)
	(segment
		(start 190.20028 -73.066148)
		(end 190.20028 -72.278748)
		(width 0.127)
		(layer "In4.Cu")
		(net "RMII_BMC_OCP_TX_EN")
	)
	(segment
		(start 212.34908 -75.860148)
		(end 204.50048 -75.860148)
		(width 0.127)
		(layer "In4.Cu")
		(net "RMII_BMC_OCP_TX_EN")
	)
	(segment
		(start 209.510122 -69.86143)
		(end 209.469482 -69.82079)
		(width 0.12954)
		(layer "F.Cu")
		(net "RMII_BMC_OCP_TXD_1")
	)
	(segment
		(start 166.116 -17.846548)
		(end 166.116 -19.295364)
		(width 0.12954)
		(layer "F.Cu")
		(net "RMII_BMC_OCP_TXD_1")
	)
	(segment
		(start 210.77428 -69.86143)
		(end 209.510122 -69.86143)
		(width 0.12954)
		(layer "F.Cu")
		(net "RMII_BMC_OCP_TXD_1")
	)
	(segment
		(start 166.26713 -17.695418)
		(end 166.116 -17.846548)
		(width 0.12954)
		(layer "F.Cu")
		(net "RMII_BMC_OCP_TXD_1")
	)
	(segment
		(start 166.26713 -16.550132)
		(end 166.26713 -17.695418)
		(width 0.12954)
		(layer "F.Cu")
		(net "RMII_BMC_OCP_TXD_1")
	)
	(segment
		(start 211.59724 -69.86143)
		(end 210.77428 -69.86143)
		(width 0.12954)
		(layer "F.Cu")
		(net "RMII_BMC_OCP_TXD_1")
	)
	(segment
		(start 166.116 -19.295364)
		(end 166.91991 -20.099274)
		(width 0.12954)
		(layer "F.Cu")
		(net "RMII_BMC_OCP_TXD_1")
	)
	(via
		(at 166.91991 -20.099274)
		(size 0.762)
		(drill 0.254)
		(layers "F.Cu" "B.Cu")
		(net "RMII_BMC_OCP_TXD_1")
	)
	(via
		(at 210.77428 -69.86143)
		(size 0.508)
		(drill 0.254)
		(layers "F.Cu" "B.Cu")
		(net "RMII_BMC_OCP_TXD_1")
	)
	(via
		(at 206.576422 -72.913748)
		(size 0.508)
		(drill 0.254)
		(layers "F.Cu" "B.Cu")
		(net "RMII_BMC_OCP_TXD_1")
	)
	(segment
		(start 206.576422 -72.214994)
		(end 206.576422 -72.913748)
		(width 0.12954)
		(layer "B.Cu")
		(net "RMII_BMC_OCP_TXD_1")
	)
	(segment
		(start 191.53378 -45.670978)
		(end 191.53378 -66.906394)
		(width 0.127)
		(layer "In2.Cu")
		(net "RMII_BMC_OCP_TXD_1")
	)
	(segment
		(start 191.53378 -66.906394)
		(end 197.871334 -73.243948)
		(width 0.127)
		(layer "In2.Cu")
		(net "RMII_BMC_OCP_TXD_1")
	)
	(segment
		(start 189.89548 -44.032678)
		(end 191.53378 -45.670978)
		(width 0.127)
		(layer "In2.Cu")
		(net "RMII_BMC_OCP_TXD_1")
	)
	(segment
		(start 166.91356 -20.312888)
		(end 168.783 -22.182328)
		(width 0.127)
		(layer "In2.Cu")
		(net "RMII_BMC_OCP_TXD_1")
	)
	(segment
		(start 189.89548 -33.391094)
		(end 189.89548 -44.032678)
		(width 0.127)
		(layer "In2.Cu")
		(net "RMII_BMC_OCP_TXD_1")
	)
	(segment
		(start 183.655462 -25.195276)
		(end 183.655462 -27.151076)
		(width 0.127)
		(layer "In2.Cu")
		(net "RMII_BMC_OCP_TXD_1")
	)
	(segment
		(start 206.246222 -73.243948)
		(end 206.576422 -72.913748)
		(width 0.127)
		(layer "In2.Cu")
		(net "RMII_BMC_OCP_TXD_1")
	)
	(segment
		(start 168.783 -23.130002)
		(end 170.007026 -24.354028)
		(width 0.127)
		(layer "In2.Cu")
		(net "RMII_BMC_OCP_TXD_1")
	)
	(segment
		(start 168.783 -22.182328)
		(end 168.783 -23.130002)
		(width 0.127)
		(layer "In2.Cu")
		(net "RMII_BMC_OCP_TXD_1")
	)
	(segment
		(start 174.028608 -22.918166)
		(end 181.378352 -22.918166)
		(width 0.127)
		(layer "In2.Cu")
		(net "RMII_BMC_OCP_TXD_1")
	)
	(segment
		(start 166.91991 -20.099274)
		(end 166.91356 -20.105624)
		(width 0.127)
		(layer "In2.Cu")
		(net "RMII_BMC_OCP_TXD_1")
	)
	(segment
		(start 183.655462 -27.151076)
		(end 189.89548 -33.391094)
		(width 0.127)
		(layer "In2.Cu")
		(net "RMII_BMC_OCP_TXD_1")
	)
	(segment
		(start 170.007026 -24.354028)
		(end 172.592746 -24.354028)
		(width 0.127)
		(layer "In2.Cu")
		(net "RMII_BMC_OCP_TXD_1")
	)
	(segment
		(start 197.871334 -73.243948)
		(end 206.246222 -73.243948)
		(width 0.127)
		(layer "In2.Cu")
		(net "RMII_BMC_OCP_TXD_1")
	)
	(segment
		(start 172.592746 -24.354028)
		(end 174.028608 -22.918166)
		(width 0.127)
		(layer "In2.Cu")
		(net "RMII_BMC_OCP_TXD_1")
	)
	(segment
		(start 181.378352 -22.918166)
		(end 183.655462 -25.195276)
		(width 0.127)
		(layer "In2.Cu")
		(net "RMII_BMC_OCP_TXD_1")
	)
	(segment
		(start 166.91356 -20.105624)
		(end 166.91356 -20.312888)
		(width 0.127)
		(layer "In2.Cu")
		(net "RMII_BMC_OCP_TXD_1")
	)
	(segment
		(start 210.77428 -69.86143)
		(end 211.40928 -70.49643)
		(width 0.127)
		(layer "In4.Cu")
		(net "RMII_BMC_OCP_TXD_1")
	)
	(segment
		(start 206.96428 -72.177148)
		(end 206.576422 -72.565006)
		(width 0.127)
		(layer "In4.Cu")
		(net "RMII_BMC_OCP_TXD_1")
	)
	(segment
		(start 206.576422 -72.565006)
		(end 206.576422 -72.913748)
		(width 0.127)
		(layer "In4.Cu")
		(net "RMII_BMC_OCP_TXD_1")
	)
	(segment
		(start 210.79968 -72.177148)
		(end 206.96428 -72.177148)
		(width 0.127)
		(layer "In4.Cu")
		(net "RMII_BMC_OCP_TXD_1")
	)
	(segment
		(start 211.40928 -71.567548)
		(end 210.79968 -72.177148)
		(width 0.127)
		(layer "In4.Cu")
		(net "RMII_BMC_OCP_TXD_1")
	)
	(segment
		(start 211.40928 -70.49643)
		(end 211.40928 -71.567548)
		(width 0.127)
		(layer "In4.Cu")
		(net "RMII_BMC_OCP_TXD_1")
	)
	(segment
		(start 210.72348 -71.20763)
		(end 209.586322 -71.20763)
		(width 0.12954)
		(layer "F.Cu")
		(net "RMII_BMC_OCP_TXD_0")
	)
	(segment
		(start 209.586322 -71.20763)
		(end 209.469482 -71.09079)
		(width 0.12954)
		(layer "F.Cu")
		(net "RMII_BMC_OCP_TXD_0")
	)
	(segment
		(start 211.59724 -71.13143)
		(end 211.52104 -71.20763)
		(width 0.12954)
		(layer "F.Cu")
		(net "RMII_BMC_OCP_TXD_0")
	)
	(segment
		(start 211.52104 -71.20763)
		(end 210.72348 -71.20763)
		(width 0.12954)
		(layer "F.Cu")
		(net "RMII_BMC_OCP_TXD_0")
	)
	(segment
		(start 166.867078 -17.57807)
		(end 166.751 -17.694148)
		(width 0.12954)
		(layer "F.Cu")
		(net "RMII_BMC_OCP_TXD_0")
	)
	(segment
		(start 166.867078 -16.550132)
		(end 166.867078 -17.57807)
		(width 0.12954)
		(layer "F.Cu")
		(net "RMII_BMC_OCP_TXD_0")
	)
	(via
		(at 210.72348 -71.20763)
		(size 0.508)
		(drill 0.254)
		(layers "F.Cu" "B.Cu")
		(net "RMII_BMC_OCP_TXD_0")
	)
	(via
		(at 166.751 -17.694148)
		(size 0.508)
		(drill 0.254)
		(layers "F.Cu" "B.Cu")
		(net "RMII_BMC_OCP_TXD_0")
	)
	(via
		(at 205.97368 -71.135748)
		(size 0.508)
		(drill 0.254)
		(layers "F.Cu" "B.Cu")
		(net "RMII_BMC_OCP_TXD_0")
	)
	(segment
		(start 205.97368 -71.135748)
		(end 206.562706 -70.546722)
		(width 0.12954)
		(layer "B.Cu")
		(net "RMII_BMC_OCP_TXD_0")
	)
	(segment
		(start 206.562706 -70.546722)
		(end 206.562706 -70.31228)
		(width 0.12954)
		(layer "B.Cu")
		(net "RMII_BMC_OCP_TXD_0")
	)
	(segment
		(start 191.96558 -66.703448)
		(end 198.07428 -72.812148)
		(width 0.127)
		(layer "In2.Cu")
		(net "RMII_BMC_OCP_TXD_0")
	)
	(segment
		(start 168.68648 -20.767548)
		(end 169.2148 -21.295868)
		(width 0.127)
		(layer "In2.Cu")
		(net "RMII_BMC_OCP_TXD_0")
	)
	(segment
		(start 184.10428 -25.009348)
		(end 184.10428 -26.965148)
		(width 0.127)
		(layer "In2.Cu")
		(net "RMII_BMC_OCP_TXD_0")
	)
	(segment
		(start 168.68648 -17.414748)
		(end 168.68648 -20.767548)
		(width 0.127)
		(layer "In2.Cu")
		(net "RMII_BMC_OCP_TXD_0")
	)
	(segment
		(start 191.96558 -45.468032)
		(end 191.96558 -66.703448)
		(width 0.127)
		(layer "In2.Cu")
		(net "RMII_BMC_OCP_TXD_0")
	)
	(segment
		(start 204.29728 -72.812148)
		(end 205.97368 -71.135748)
		(width 0.127)
		(layer "In2.Cu")
		(net "RMII_BMC_OCP_TXD_0")
	)
	(segment
		(start 198.07428 -72.812148)
		(end 204.29728 -72.812148)
		(width 0.127)
		(layer "In2.Cu")
		(net "RMII_BMC_OCP_TXD_0")
	)
	(segment
		(start 167.319452 -17.125696)
		(end 168.397428 -17.125696)
		(width 0.127)
		(layer "In2.Cu")
		(net "RMII_BMC_OCP_TXD_0")
	)
	(segment
		(start 170.17238 -23.861268)
		(end 172.45076 -23.861268)
		(width 0.127)
		(layer "In2.Cu")
		(net "RMII_BMC_OCP_TXD_0")
	)
	(segment
		(start 184.10428 -26.965148)
		(end 190.32728 -33.188148)
		(width 0.127)
		(layer "In2.Cu")
		(net "RMII_BMC_OCP_TXD_0")
	)
	(segment
		(start 169.2148 -21.295868)
		(end 169.2148 -22.903688)
		(width 0.127)
		(layer "In2.Cu")
		(net "RMII_BMC_OCP_TXD_0")
	)
	(segment
		(start 173.84268 -22.469348)
		(end 181.56428 -22.469348)
		(width 0.127)
		(layer "In2.Cu")
		(net "RMII_BMC_OCP_TXD_0")
	)
	(segment
		(start 181.56428 -22.469348)
		(end 184.10428 -25.009348)
		(width 0.127)
		(layer "In2.Cu")
		(net "RMII_BMC_OCP_TXD_0")
	)
	(segment
		(start 169.2148 -22.903688)
		(end 170.17238 -23.861268)
		(width 0.127)
		(layer "In2.Cu")
		(net "RMII_BMC_OCP_TXD_0")
	)
	(segment
		(start 190.32728 -43.829732)
		(end 191.96558 -45.468032)
		(width 0.127)
		(layer "In2.Cu")
		(net "RMII_BMC_OCP_TXD_0")
	)
	(segment
		(start 168.397428 -17.125696)
		(end 168.68648 -17.414748)
		(width 0.127)
		(layer "In2.Cu")
		(net "RMII_BMC_OCP_TXD_0")
	)
	(segment
		(start 172.45076 -23.861268)
		(end 173.84268 -22.469348)
		(width 0.127)
		(layer "In2.Cu")
		(net "RMII_BMC_OCP_TXD_0")
	)
	(segment
		(start 166.751 -17.694148)
		(end 167.319452 -17.125696)
		(width 0.127)
		(layer "In2.Cu")
		(net "RMII_BMC_OCP_TXD_0")
	)
	(segment
		(start 190.32728 -33.188148)
		(end 190.32728 -43.829732)
		(width 0.127)
		(layer "In2.Cu")
		(net "RMII_BMC_OCP_TXD_0")
	)
	(segment
		(start 209.58048 -71.694548)
		(end 206.53248 -71.694548)
		(width 0.127)
		(layer "In4.Cu")
		(net "RMII_BMC_OCP_TXD_0")
	)
	(segment
		(start 210.72348 -71.20763)
		(end 210.067398 -71.20763)
		(width 0.127)
		(layer "In4.Cu")
		(net "RMII_BMC_OCP_TXD_0")
	)
	(segment
		(start 210.067398 -71.20763)
		(end 209.58048 -71.694548)
		(width 0.127)
		(layer "In4.Cu")
		(net "RMII_BMC_OCP_TXD_0")
	)
	(segment
		(start 206.53248 -71.694548)
		(end 205.97368 -71.135748)
		(width 0.127)
		(layer "In4.Cu")
		(net "RMII_BMC_OCP_TXD_0")
	)
	(segment
		(start 166.07028 -20.569682)
		(end 166.07028 -21.383498)
		(width 0.12954)
		(layer "F.Cu")
		(net "RMII_BMC_OCP_RX_ER")
	)
	(segment
		(start 165.666928 -16.550132)
		(end 165.666928 -17.555972)
		(width 0.12954)
		(layer "F.Cu")
		(net "RMII_BMC_OCP_RX_ER")
	)
	(segment
		(start 165.666928 -17.555972)
		(end 165.52672 -17.69618)
		(width 0.12954)
		(layer "F.Cu")
		(net "RMII_BMC_OCP_RX_ER")
	)
	(segment
		(start 165.52672 -18.748248)
		(end 165.52672 -20.026122)
		(width 0.12954)
		(layer "F.Cu")
		(net "RMII_BMC_OCP_RX_ER")
	)
	(segment
		(start 165.52672 -20.026122)
		(end 166.07028 -20.569682)
		(width 0.12954)
		(layer "F.Cu")
		(net "RMII_BMC_OCP_RX_ER")
	)
	(segment
		(start 165.52672 -17.69618)
		(end 165.52672 -18.748248)
		(width 0.12954)
		(layer "F.Cu")
		(net "RMII_BMC_OCP_RX_ER")
	)
	(via
		(at 165.52672 -18.748248)
		(size 0.508)
		(drill 0.254)
		(layers "F.Cu" "B.Cu")
		(net "RMII_BMC_OCP_RX_ER")
	)
	(segment
		(start 101.874574 -96.123506)
		(end 102.64648 -96.123506)
		(width 0.12954)
		(layer "F.Cu")
		(net "PWRGD_SYS_PWROK_R")
	)
	(segment
		(start 176.555654 -118.575328)
		(end 176.155604 -118.975378)
		(width 0.12954)
		(layer "F.Cu")
		(net "PWRGD_SYS_PWROK_R")
	)
	(via
		(at 305.54168 -29.759148)
		(size 0.508)
		(drill 0.254)
		(layers "F.Cu" "B.Cu")
		(net "PWRGD_SYS_PWROK_R")
	)
	(via
		(at 102.64648 -96.123506)
		(size 0.508)
		(drill 0.254)
		(layers "F.Cu" "B.Cu")
		(net "PWRGD_SYS_PWROK_R")
	)
	(via
		(at 100.46208 -113.883948)
		(size 0.508)
		(drill 0.254)
		(layers "F.Cu" "B.Cu")
		(net "PWRGD_SYS_PWROK_R")
	)
	(via
		(at 176.155604 -118.975378)
		(size 0.4572)
		(drill 0.254)
		(layers "F.Cu" "B.Cu")
		(net "PWRGD_SYS_PWROK_R")
	)
	(via
		(at 310.18988 -96.611948)
		(size 0.508)
		(drill 0.254)
		(layers "F.Cu" "B.Cu")
		(net "PWRGD_SYS_PWROK_R")
	)
	(segment
		(start 314.51296 -30.589982)
		(end 313.26709 -27.582622)
		(width 0.12954)
		(layer "B.Cu")
		(net "PWRGD_SYS_PWROK_R")
	)
	(segment
		(start 317.737236 -34.58464)
		(end 317.737236 -33.814258)
		(width 0.12954)
		(layer "B.Cu")
		(net "PWRGD_SYS_PWROK_R")
	)
	(segment
		(start 318.040512 -34.887916)
		(end 317.737236 -34.58464)
		(width 0.12954)
		(layer "B.Cu")
		(net "PWRGD_SYS_PWROK_R")
	)
	(segment
		(start 312.605166 -26.920698)
		(end 312.090816 -26.920698)
		(width 0.12954)
		(layer "B.Cu")
		(net "PWRGD_SYS_PWROK_R")
	)
	(segment
		(start 317.737236 -33.814258)
		(end 314.51296 -30.589982)
		(width 0.12954)
		(layer "B.Cu")
		(net "PWRGD_SYS_PWROK_R")
	)
	(segment
		(start 313.26709 -27.582622)
		(end 312.605166 -26.920698)
		(width 0.12954)
		(layer "B.Cu")
		(net "PWRGD_SYS_PWROK_R")
	)
	(segment
		(start 305.54168 -29.759148)
		(end 308.38013 -26.920698)
		(width 0.12954)
		(layer "B.Cu")
		(net "PWRGD_SYS_PWROK_R")
	)
	(segment
		(start 308.38013 -26.920698)
		(end 312.090816 -26.920698)
		(width 0.12954)
		(layer "B.Cu")
		(net "PWRGD_SYS_PWROK_R")
	)
	(segment
		(start 309.42788 -93.944948)
		(end 309.42788 -76.926948)
		(width 0.127)
		(layer "In2.Cu")
		(net "PWRGD_SYS_PWROK_R")
	)
	(segment
		(start 307.31968 -62.956948)
		(end 307.31968 -60.269628)
		(width 0.127)
		(layer "In2.Cu")
		(net "PWRGD_SYS_PWROK_R")
	)
	(segment
		(start 306.88788 -63.388748)
		(end 307.31968 -62.956948)
		(width 0.127)
		(layer "In2.Cu")
		(net "PWRGD_SYS_PWROK_R")
	)
	(segment
		(start 304.83048 -38.801548)
		(end 304.83048 -30.470348)
		(width 0.127)
		(layer "In2.Cu")
		(net "PWRGD_SYS_PWROK_R")
	)
	(segment
		(start 307.75148 -73.523348)
		(end 307.75148 -68.798948)
		(width 0.127)
		(layer "In2.Cu")
		(net "PWRGD_SYS_PWROK_R")
	)
	(segment
		(start 304.29708 -50.095658)
		(end 304.6476 -49.745138)
		(width 0.127)
		(layer "In2.Cu")
		(net "PWRGD_SYS_PWROK_R")
	)
	(segment
		(start 307.75148 -68.798948)
		(end 307.06568 -68.113148)
		(width 0.127)
		(layer "In2.Cu")
		(net "PWRGD_SYS_PWROK_R")
	)
	(segment
		(start 307.06568 -68.113148)
		(end 307.06568 -64.557148)
		(width 0.127)
		(layer "In2.Cu")
		(net "PWRGD_SYS_PWROK_R")
	)
	(segment
		(start 100.46208 -113.883948)
		(end 100.46208 -98.307906)
		(width 0.127)
		(layer "In2.Cu")
		(net "PWRGD_SYS_PWROK_R")
	)
	(segment
		(start 307.31968 -60.269628)
		(end 304.29708 -57.247028)
		(width 0.127)
		(layer "In2.Cu")
		(net "PWRGD_SYS_PWROK_R")
	)
	(segment
		(start 304.6476 -48.275748)
		(end 304.4444 -48.072548)
		(width 0.127)
		(layer "In2.Cu")
		(net "PWRGD_SYS_PWROK_R")
	)
	(segment
		(start 304.29708 -57.247028)
		(end 304.29708 -50.095658)
		(width 0.127)
		(layer "In2.Cu")
		(net "PWRGD_SYS_PWROK_R")
	)
	(segment
		(start 307.06568 -64.557148)
		(end 306.88788 -64.379348)
		(width 0.127)
		(layer "In2.Cu")
		(net "PWRGD_SYS_PWROK_R")
	)
	(segment
		(start 306.88788 -64.379348)
		(end 306.88788 -63.388748)
		(width 0.127)
		(layer "In2.Cu")
		(net "PWRGD_SYS_PWROK_R")
	)
	(segment
		(start 303.58588 -40.046148)
		(end 304.83048 -38.801548)
		(width 0.127)
		(layer "In2.Cu")
		(net "PWRGD_SYS_PWROK_R")
	)
	(segment
		(start 308.76748 -74.539348)
		(end 307.75148 -73.523348)
		(width 0.127)
		(layer "In2.Cu")
		(net "PWRGD_SYS_PWROK_R")
	)
	(segment
		(start 100.46208 -98.307906)
		(end 102.64648 -96.123506)
		(width 0.127)
		(layer "In2.Cu")
		(net "PWRGD_SYS_PWROK_R")
	)
	(segment
		(start 309.42788 -76.926948)
		(end 308.76748 -76.266548)
		(width 0.127)
		(layer "In2.Cu")
		(net "PWRGD_SYS_PWROK_R")
	)
	(segment
		(start 304.83048 -30.470348)
		(end 305.54168 -29.759148)
		(width 0.127)
		(layer "In2.Cu")
		(net "PWRGD_SYS_PWROK_R")
	)
	(segment
		(start 303.58588 -44.287948)
		(end 303.58588 -40.046148)
		(width 0.127)
		(layer "In2.Cu")
		(net "PWRGD_SYS_PWROK_R")
	)
	(segment
		(start 310.18988 -96.611948)
		(end 310.18988 -94.706948)
		(width 0.127)
		(layer "In2.Cu")
		(net "PWRGD_SYS_PWROK_R")
	)
	(segment
		(start 304.4444 -48.072548)
		(end 304.4444 -45.146468)
		(width 0.127)
		(layer "In2.Cu")
		(net "PWRGD_SYS_PWROK_R")
	)
	(segment
		(start 304.6476 -49.745138)
		(end 304.6476 -48.275748)
		(width 0.127)
		(layer "In2.Cu")
		(net "PWRGD_SYS_PWROK_R")
	)
	(segment
		(start 304.4444 -45.146468)
		(end 303.58588 -44.287948)
		(width 0.127)
		(layer "In2.Cu")
		(net "PWRGD_SYS_PWROK_R")
	)
	(segment
		(start 308.76748 -76.266548)
		(end 308.76748 -74.539348)
		(width 0.127)
		(layer "In2.Cu")
		(net "PWRGD_SYS_PWROK_R")
	)
	(segment
		(start 310.18988 -94.706948)
		(end 309.42788 -93.944948)
		(width 0.127)
		(layer "In2.Cu")
		(net "PWRGD_SYS_PWROK_R")
	)
	(segment
		(start 253.604776 -88.293194)
		(end 276.674326 -88.293194)
		(width 0.127)
		(layer "In13.Cu")
		(net "PWRGD_SYS_PWROK_R")
	)
	(segment
		(start 251.15139 -90.74658)
		(end 253.604776 -88.293194)
		(width 0.127)
		(layer "In13.Cu")
		(net "PWRGD_SYS_PWROK_R")
	)
	(segment
		(start 176.56048 -117.953028)
		(end 176.74336 -117.770148)
		(width 0.127)
		(layer "In13.Cu")
		(net "PWRGD_SYS_PWROK_R")
	)
	(segment
		(start 176.56048 -118.570502)
		(end 176.56048 -117.953028)
		(width 0.127)
		(layer "In13.Cu")
		(net "PWRGD_SYS_PWROK_R")
	)
	(segment
		(start 245.172992 -90.74658)
		(end 251.15139 -90.74658)
		(width 0.127)
		(layer "In13.Cu")
		(net "PWRGD_SYS_PWROK_R")
	)
	(segment
		(start 187.3758 -95.504)
		(end 187.3758 -94.869)
		(width 0.127)
		(layer "In13.Cu")
		(net "PWRGD_SYS_PWROK_R")
	)
	(segment
		(start 276.674326 -88.293194)
		(end 282.58262 -94.201488)
		(width 0.127)
		(layer "In13.Cu")
		(net "PWRGD_SYS_PWROK_R")
	)
	(segment
		(start 186.9694 -95.9104)
		(end 187.3758 -95.504)
		(width 0.127)
		(layer "In13.Cu")
		(net "PWRGD_SYS_PWROK_R")
	)
	(segment
		(start 176.74336 -117.770148)
		(end 177.18532 -117.770148)
		(width 0.127)
		(layer "In13.Cu")
		(net "PWRGD_SYS_PWROK_R")
	)
	(segment
		(start 179.17668 -100.272088)
		(end 180.24856 -99.200208)
		(width 0.127)
		(layer "In13.Cu")
		(net "PWRGD_SYS_PWROK_R")
	)
	(segment
		(start 307.77942 -94.201488)
		(end 310.18988 -96.611948)
		(width 0.127)
		(layer "In13.Cu")
		(net "PWRGD_SYS_PWROK_R")
	)
	(segment
		(start 176.155604 -118.975378)
		(end 176.56048 -118.570502)
		(width 0.127)
		(layer "In13.Cu")
		(net "PWRGD_SYS_PWROK_R")
	)
	(segment
		(start 282.58262 -94.201488)
		(end 307.77942 -94.201488)
		(width 0.127)
		(layer "In13.Cu")
		(net "PWRGD_SYS_PWROK_R")
	)
	(segment
		(start 178.148742 -107.562142)
		(end 178.148742 -101.614986)
		(width 0.127)
		(layer "In13.Cu")
		(net "PWRGD_SYS_PWROK_R")
	)
	(segment
		(start 177.5714 -108.1786)
		(end 178.054 -108.1786)
		(width 0.127)
		(layer "In13.Cu")
		(net "PWRGD_SYS_PWROK_R")
	)
	(segment
		(start 178.2318 -107.6452)
		(end 178.148742 -107.562142)
		(width 0.127)
		(layer "In13.Cu")
		(net "PWRGD_SYS_PWROK_R")
	)
	(segment
		(start 177.18532 -117.770148)
		(end 177.3555 -117.599968)
		(width 0.127)
		(layer "In13.Cu")
		(net "PWRGD_SYS_PWROK_R")
	)
	(segment
		(start 178.2318 -108.0008)
		(end 178.2318 -107.6452)
		(width 0.127)
		(layer "In13.Cu")
		(net "PWRGD_SYS_PWROK_R")
	)
	(segment
		(start 180.24856 -99.200208)
		(end 183.146192 -99.200208)
		(width 0.127)
		(layer "In13.Cu")
		(net "PWRGD_SYS_PWROK_R")
	)
	(segment
		(start 242.764818 -93.154754)
		(end 245.172992 -90.74658)
		(width 0.127)
		(layer "In13.Cu")
		(net "PWRGD_SYS_PWROK_R")
	)
	(segment
		(start 220.327474 -93.154754)
		(end 242.764818 -93.154754)
		(width 0.127)
		(layer "In13.Cu")
		(net "PWRGD_SYS_PWROK_R")
	)
	(segment
		(start 187.3758 -94.869)
		(end 193.981832 -88.262968)
		(width 0.127)
		(layer "In13.Cu")
		(net "PWRGD_SYS_PWROK_R")
	)
	(segment
		(start 178.054 -108.1786)
		(end 178.2318 -108.0008)
		(width 0.127)
		(layer "In13.Cu")
		(net "PWRGD_SYS_PWROK_R")
	)
	(segment
		(start 215.435688 -88.262968)
		(end 220.327474 -93.154754)
		(width 0.127)
		(layer "In13.Cu")
		(net "PWRGD_SYS_PWROK_R")
	)
	(segment
		(start 186.436 -95.9104)
		(end 186.9694 -95.9104)
		(width 0.127)
		(layer "In13.Cu")
		(net "PWRGD_SYS_PWROK_R")
	)
	(segment
		(start 177.3555 -108.3945)
		(end 177.5714 -108.1786)
		(width 0.127)
		(layer "In13.Cu")
		(net "PWRGD_SYS_PWROK_R")
	)
	(segment
		(start 193.981832 -88.262968)
		(end 215.435688 -88.262968)
		(width 0.127)
		(layer "In13.Cu")
		(net "PWRGD_SYS_PWROK_R")
	)
	(segment
		(start 178.148742 -101.614986)
		(end 179.17668 -100.587048)
		(width 0.127)
		(layer "In13.Cu")
		(net "PWRGD_SYS_PWROK_R")
	)
	(segment
		(start 183.146192 -99.200208)
		(end 186.436 -95.9104)
		(width 0.127)
		(layer "In13.Cu")
		(net "PWRGD_SYS_PWROK_R")
	)
	(segment
		(start 179.17668 -100.587048)
		(end 179.17668 -100.272088)
		(width 0.127)
		(layer "In13.Cu")
		(net "PWRGD_SYS_PWROK_R")
	)
	(segment
		(start 177.3555 -117.599968)
		(end 177.3555 -108.3945)
		(width 0.127)
		(layer "In13.Cu")
		(net "PWRGD_SYS_PWROK_R")
	)
	(segment
		(start 149.060408 -122.7455)
		(end 149.36216 -122.443748)
		(width 0.127)
		(layer "In15.Cu")
		(net "PWRGD_SYS_PWROK_R")
	)
	(segment
		(start 135.12292 -116.51996)
		(end 139.65428 -116.51996)
		(width 0.127)
		(layer "In15.Cu")
		(net "PWRGD_SYS_PWROK_R")
	)
	(segment
		(start 149.36216 -122.443748)
		(end 152.84958 -122.443748)
		(width 0.127)
		(layer "In15.Cu")
		(net "PWRGD_SYS_PWROK_R")
	)
	(segment
		(start 156.57068 -126.164848)
		(end 162.720782 -126.164848)
		(width 0.127)
		(layer "In15.Cu")
		(net "PWRGD_SYS_PWROK_R")
	)
	(segment
		(start 152.84958 -122.443748)
		(end 156.57068 -126.164848)
		(width 0.127)
		(layer "In15.Cu")
		(net "PWRGD_SYS_PWROK_R")
	)
	(segment
		(start 172.327062 -119.369332)
		(end 172.560742 -119.135652)
		(width 0.127)
		(layer "In15.Cu")
		(net "PWRGD_SYS_PWROK_R")
	)
	(segment
		(start 172.560742 -118.75135)
		(end 172.739304 -118.572788)
		(width 0.127)
		(layer "In15.Cu")
		(net "PWRGD_SYS_PWROK_R")
	)
	(segment
		(start 166.89578 -123.939808)
		(end 166.89578 -122.85218)
		(width 0.127)
		(layer "In15.Cu")
		(net "PWRGD_SYS_PWROK_R")
	)
	(segment
		(start 172.560742 -119.135652)
		(end 172.560742 -118.75135)
		(width 0.127)
		(layer "In15.Cu")
		(net "PWRGD_SYS_PWROK_R")
	)
	(segment
		(start 172.739304 -118.572788)
		(end 175.753014 -118.572788)
		(width 0.127)
		(layer "In15.Cu")
		(net "PWRGD_SYS_PWROK_R")
	)
	(segment
		(start 169.45864 -120.79224)
		(end 170.26636 -119.98452)
		(width 0.127)
		(layer "In15.Cu")
		(net "PWRGD_SYS_PWROK_R")
	)
	(segment
		(start 168.95572 -120.79224)
		(end 169.45864 -120.79224)
		(width 0.127)
		(layer "In15.Cu")
		(net "PWRGD_SYS_PWROK_R")
	)
	(segment
		(start 170.26636 -119.98452)
		(end 170.670728 -119.98452)
		(width 0.127)
		(layer "In15.Cu")
		(net "PWRGD_SYS_PWROK_R")
	)
	(segment
		(start 104.32288 -113.883948)
		(end 104.70388 -114.264948)
		(width 0.127)
		(layer "In15.Cu")
		(net "PWRGD_SYS_PWROK_R")
	)
	(segment
		(start 132.867908 -114.264948)
		(end 135.12292 -116.51996)
		(width 0.127)
		(layer "In15.Cu")
		(net "PWRGD_SYS_PWROK_R")
	)
	(segment
		(start 170.670728 -119.98452)
		(end 171.285916 -119.369332)
		(width 0.127)
		(layer "In15.Cu")
		(net "PWRGD_SYS_PWROK_R")
	)
	(segment
		(start 171.285916 -119.369332)
		(end 172.327062 -119.369332)
		(width 0.127)
		(layer "In15.Cu")
		(net "PWRGD_SYS_PWROK_R")
	)
	(segment
		(start 145.87982 -122.7455)
		(end 149.060408 -122.7455)
		(width 0.127)
		(layer "In15.Cu")
		(net "PWRGD_SYS_PWROK_R")
	)
	(segment
		(start 100.46208 -113.883948)
		(end 104.32288 -113.883948)
		(width 0.127)
		(layer "In15.Cu")
		(net "PWRGD_SYS_PWROK_R")
	)
	(segment
		(start 166.89578 -122.85218)
		(end 168.95572 -120.79224)
		(width 0.127)
		(layer "In15.Cu")
		(net "PWRGD_SYS_PWROK_R")
	)
	(segment
		(start 162.720782 -126.164848)
		(end 162.997642 -125.887988)
		(width 0.127)
		(layer "In15.Cu")
		(net "PWRGD_SYS_PWROK_R")
	)
	(segment
		(start 164.9476 -125.887988)
		(end 166.89578 -123.939808)
		(width 0.127)
		(layer "In15.Cu")
		(net "PWRGD_SYS_PWROK_R")
	)
	(segment
		(start 162.997642 -125.887988)
		(end 164.9476 -125.887988)
		(width 0.127)
		(layer "In15.Cu")
		(net "PWRGD_SYS_PWROK_R")
	)
	(segment
		(start 104.70388 -114.264948)
		(end 132.867908 -114.264948)
		(width 0.127)
		(layer "In15.Cu")
		(net "PWRGD_SYS_PWROK_R")
	)
	(segment
		(start 175.753014 -118.572788)
		(end 176.155604 -118.975378)
		(width 0.127)
		(layer "In15.Cu")
		(net "PWRGD_SYS_PWROK_R")
	)
	(segment
		(start 139.65428 -116.51996)
		(end 145.87982 -122.7455)
		(width 0.127)
		(layer "In15.Cu")
		(net "PWRGD_SYS_PWROK_R")
	)
	(segment
		(start 148.91004 -12.520168)
		(end 148.91004 -13.264388)
		(width 0.12954)
		(layer "F.Cu")
		(net "PWRGD_SYS_PWROK")
	)
	(segment
		(start 142.947136 -13.600176)
		(end 142.947136 -12.657582)
		(width 0.12954)
		(layer "F.Cu")
		(net "PWRGD_SYS_PWROK")
	)
	(segment
		(start 143.679926 -10.899648)
		(end 144.515586 -10.063988)
		(width 0.12954)
		(layer "F.Cu")
		(net "PWRGD_SYS_PWROK")
	)
	(segment
		(start 330.921614 -44.691046)
		(end 330.79436 -44.8183)
		(width 0.12954)
		(layer "F.Cu")
		(net "PWRGD_SYS_PWROK")
	)
	(segment
		(start 142.947136 -12.657582)
		(end 142.79626 -12.506706)
		(width 0.12954)
		(layer "F.Cu")
		(net "PWRGD_SYS_PWROK")
	)
	(segment
		(start 142.79626 -11.125962)
		(end 143.022574 -10.899648)
		(width 0.12954)
		(layer "F.Cu")
		(net "PWRGD_SYS_PWROK")
	)
	(segment
		(start 146.45386 -10.063988)
		(end 148.91004 -12.520168)
		(width 0.12954)
		(layer "F.Cu")
		(net "PWRGD_SYS_PWROK")
	)
	(segment
		(start 144.515586 -10.063988)
		(end 146.45386 -10.063988)
		(width 0.12954)
		(layer "F.Cu")
		(net "PWRGD_SYS_PWROK")
	)
	(segment
		(start 330.79436 -44.8183)
		(end 330.79436 -45.160946)
		(width 0.12954)
		(layer "F.Cu")
		(net "PWRGD_SYS_PWROK")
	)
	(segment
		(start 331.065378 -44.691046)
		(end 330.921614 -44.691046)
		(width 0.12954)
		(layer "F.Cu")
		(net "PWRGD_SYS_PWROK")
	)
	(segment
		(start 142.79626 -12.506706)
		(end 142.79626 -11.125962)
		(width 0.12954)
		(layer "F.Cu")
		(net "PWRGD_SYS_PWROK")
	)
	(segment
		(start 143.022574 -10.899648)
		(end 143.679926 -10.899648)
		(width 0.12954)
		(layer "F.Cu")
		(net "PWRGD_SYS_PWROK")
	)
	(via
		(at 301.09668 -39.055548)
		(size 0.508)
		(drill 0.254)
		(layers "F.Cu" "B.Cu")
		(net "PWRGD_SYS_PWROK")
	)
	(via
		(at 331.065378 -44.691046)
		(size 0.4572)
		(drill 0.2032)
		(layers "F.Cu" "B.Cu")
		(net "PWRGD_SYS_PWROK")
	)
	(via
		(at 148.91004 -13.264388)
		(size 0.508)
		(drill 0.254)
		(layers "F.Cu" "B.Cu")
		(net "PWRGD_SYS_PWROK")
	)
	(via
		(at 271.07388 -37.683948)
		(size 0.508)
		(drill 0.254)
		(layers "F.Cu" "B.Cu")
		(net "PWRGD_SYS_PWROK")
	)
	(segment
		(start 321.862704 -37.725858)
		(end 321.059048 -37.725858)
		(width 0.12954)
		(layer "B.Cu")
		(net "PWRGD_SYS_PWROK")
	)
	(segment
		(start 320.37909 -36.211002)
		(end 321.059048 -36.89096)
		(width 0.12954)
		(layer "B.Cu")
		(net "PWRGD_SYS_PWROK")
	)
	(segment
		(start 324.206616 -40.743378)
		(end 324.206616 -40.06977)
		(width 0.12954)
		(layer "B.Cu")
		(net "PWRGD_SYS_PWROK")
	)
	(segment
		(start 324.917054 -41.453816)
		(end 324.206616 -40.743378)
		(width 0.12954)
		(layer "B.Cu")
		(net "PWRGD_SYS_PWROK")
	)
	(segment
		(start 319.71615 -36.211002)
		(end 320.37909 -36.211002)
		(width 0.12954)
		(layer "B.Cu")
		(net "PWRGD_SYS_PWROK")
	)
	(segment
		(start 324.206616 -40.06977)
		(end 321.862704 -37.725858)
		(width 0.12954)
		(layer "B.Cu")
		(net "PWRGD_SYS_PWROK")
	)
	(segment
		(start 325.192898 -42.11955)
		(end 324.917054 -41.453816)
		(width 0.12954)
		(layer "B.Cu")
		(net "PWRGD_SYS_PWROK")
	)
	(segment
		(start 318.606424 -35.453828)
		(end 318.936624 -35.784028)
		(width 0.12954)
		(layer "B.Cu")
		(net "PWRGD_SYS_PWROK")
	)
	(segment
		(start 331.065378 -44.691046)
		(end 330.089764 -44.691046)
		(width 0.12954)
		(layer "B.Cu")
		(net "PWRGD_SYS_PWROK")
	)
	(segment
		(start 327.005696 -43.932348)
		(end 325.192898 -42.11955)
		(width 0.12954)
		(layer "B.Cu")
		(net "PWRGD_SYS_PWROK")
	)
	(segment
		(start 318.936624 -35.784028)
		(end 319.289176 -35.784028)
		(width 0.12954)
		(layer "B.Cu")
		(net "PWRGD_SYS_PWROK")
	)
	(segment
		(start 329.585066 -44.186348)
		(end 329.268836 -44.186348)
		(width 0.12954)
		(layer "B.Cu")
		(net "PWRGD_SYS_PWROK")
	)
	(segment
		(start 329.268836 -44.186348)
		(end 329.014836 -43.932348)
		(width 0.12954)
		(layer "B.Cu")
		(net "PWRGD_SYS_PWROK")
	)
	(segment
		(start 319.289176 -35.784028)
		(end 319.71615 -36.211002)
		(width 0.12954)
		(layer "B.Cu")
		(net "PWRGD_SYS_PWROK")
	)
	(segment
		(start 330.089764 -44.691046)
		(end 329.585066 -44.186348)
		(width 0.12954)
		(layer "B.Cu")
		(net "PWRGD_SYS_PWROK")
	)
	(segment
		(start 321.059048 -36.89096)
		(end 321.059048 -37.725858)
		(width 0.12954)
		(layer "B.Cu")
		(net "PWRGD_SYS_PWROK")
	)
	(segment
		(start 329.014836 -43.932348)
		(end 327.005696 -43.932348)
		(width 0.12954)
		(layer "B.Cu")
		(net "PWRGD_SYS_PWROK")
	)
	(segment
		(start 324.62216 -45.080428)
		(end 313.46521 -45.080428)
		(width 0.127)
		(layer "In6.Cu")
		(net "PWRGD_SYS_PWROK")
	)
	(segment
		(start 312.850022 -45.695616)
		(end 310.539892 -45.695616)
		(width 0.127)
		(layer "In6.Cu")
		(net "PWRGD_SYS_PWROK")
	)
	(segment
		(start 302.56988 -41.900348)
		(end 302.56988 -40.528748)
		(width 0.127)
		(layer "In6.Cu")
		(net "PWRGD_SYS_PWROK")
	)
	(segment
		(start 310.539892 -45.695616)
		(end 308.568852 -43.724576)
		(width 0.127)
		(layer "In6.Cu")
		(net "PWRGD_SYS_PWROK")
	)
	(segment
		(start 330.252324 -45.630846)
		(end 330.251816 -45.630846)
		(width 0.127)
		(layer "In6.Cu")
		(net "PWRGD_SYS_PWROK")
	)
	(segment
		(start 331.065378 -44.691046)
		(end 330.658978 -45.395896)
		(width 0.127)
		(layer "In6.Cu")
		(net "PWRGD_SYS_PWROK")
	)
	(segment
		(start 325.642478 -46.100746)
		(end 324.62216 -45.080428)
		(width 0.127)
		(layer "In6.Cu")
		(net "PWRGD_SYS_PWROK")
	)
	(segment
		(start 329.844654 -45.865796)
		(end 329.844908 -45.865796)
		(width 0.127)
		(layer "In6.Cu")
		(net "PWRGD_SYS_PWROK")
	)
	(segment
		(start 329.451208 -46.100746)
		(end 325.642478 -46.100746)
		(width 0.127)
		(layer "In6.Cu")
		(net "PWRGD_SYS_PWROK")
	)
	(segment
		(start 302.56988 -40.528748)
		(end 301.09668 -39.055548)
		(width 0.127)
		(layer "In6.Cu")
		(net "PWRGD_SYS_PWROK")
	)
	(segment
		(start 313.46521 -45.080428)
		(end 312.850022 -45.695616)
		(width 0.127)
		(layer "In6.Cu")
		(net "PWRGD_SYS_PWROK")
	)
	(segment
		(start 330.658978 -45.395896)
		(end 330.64831 -45.414184)
		(width 0.127)
		(layer "In6.Cu")
		(net "PWRGD_SYS_PWROK")
	)
	(segment
		(start 304.394108 -43.724576)
		(end 302.56988 -41.900348)
		(width 0.127)
		(layer "In6.Cu")
		(net "PWRGD_SYS_PWROK")
	)
	(segment
		(start 308.568852 -43.724576)
		(end 304.394108 -43.724576)
		(width 0.127)
		(layer "In6.Cu")
		(net "PWRGD_SYS_PWROK")
	)
	(arc
		(start 329.844908 -45.865796)
		(mid 329.678642 -46.034519)
		(end 329.451208 -46.100746)
		(width 0.127)
		(layer "In6.Cu")
		(net "PWRGD_SYS_PWROK")
	)
	(arc
		(start 330.251816 -45.630846)
		(mid 330.016762 -45.693753)
		(end 329.844654 -45.865796)
		(width 0.127)
		(layer "In6.Cu")
		(net "PWRGD_SYS_PWROK")
	)
	(arc
		(start 330.64831 -45.414184)
		(mid 330.478029 -45.573142)
		(end 330.252324 -45.630846)
		(width 0.127)
		(layer "In6.Cu")
		(net "PWRGD_SYS_PWROK")
	)
	(segment
		(start 299.82668 -37.785548)
		(end 271.17548 -37.785548)
		(width 0.127)
		(layer "In11.Cu")
		(net "PWRGD_SYS_PWROK")
	)
	(segment
		(start 301.09668 -39.055548)
		(end 299.82668 -37.785548)
		(width 0.127)
		(layer "In11.Cu")
		(net "PWRGD_SYS_PWROK")
	)
	(segment
		(start 271.17548 -37.785548)
		(end 271.07388 -37.683948)
		(width 0.127)
		(layer "In11.Cu")
		(net "PWRGD_SYS_PWROK")
	)
	(segment
		(start 189.38748 -35.220148)
		(end 189.94628 -35.778948)
		(width 0.127)
		(layer "In13.Cu")
		(net "PWRGD_SYS_PWROK")
	)
	(segment
		(start 223.93148 -44.089066)
		(end 228.397562 -48.555148)
		(width 0.127)
		(layer "In13.Cu")
		(net "PWRGD_SYS_PWROK")
	)
	(segment
		(start 271.53108 -38.141148)
		(end 271.07388 -37.683948)
		(width 0.127)
		(layer "In13.Cu")
		(net "PWRGD_SYS_PWROK")
	)
	(segment
		(start 194.886834 -32.76854)
		(end 202.641962 -32.76854)
		(width 0.127)
		(layer "In13.Cu")
		(net "PWRGD_SYS_PWROK")
	)
	(segment
		(start 185.72988 -35.220148)
		(end 189.38748 -35.220148)
		(width 0.127)
		(layer "In13.Cu")
		(net "PWRGD_SYS_PWROK")
	)
	(segment
		(start 189.94628 -35.778948)
		(end 191.876426 -35.778948)
		(width 0.127)
		(layer "In13.Cu")
		(net "PWRGD_SYS_PWROK")
	)
	(segment
		(start 184.48528 -36.464748)
		(end 185.72988 -35.220148)
		(width 0.127)
		(layer "In13.Cu")
		(net "PWRGD_SYS_PWROK")
	)
	(segment
		(start 191.876426 -35.778948)
		(end 194.886834 -32.76854)
		(width 0.127)
		(layer "In13.Cu")
		(net "PWRGD_SYS_PWROK")
	)
	(segment
		(start 240.8682 -47.539148)
		(end 245.622826 -47.539148)
		(width 0.127)
		(layer "In13.Cu")
		(net "PWRGD_SYS_PWROK")
	)
	(segment
		(start 260.642354 -44.199048)
		(end 269.06855 -44.199048)
		(width 0.127)
		(layer "In13.Cu")
		(net "PWRGD_SYS_PWROK")
	)
	(segment
		(start 176.50968 -36.464748)
		(end 184.48528 -36.464748)
		(width 0.127)
		(layer "In13.Cu")
		(net "PWRGD_SYS_PWROK")
	)
	(segment
		(start 248.416826 -44.745148)
		(end 253.69647 -44.745148)
		(width 0.127)
		(layer "In13.Cu")
		(net "PWRGD_SYS_PWROK")
	)
	(segment
		(start 223.93148 -41.48836)
		(end 223.93148 -44.089066)
		(width 0.127)
		(layer "In13.Cu")
		(net "PWRGD_SYS_PWROK")
	)
	(segment
		(start 217.51798 -31.333948)
		(end 218.58732 -32.403288)
		(width 0.127)
		(layer "In13.Cu")
		(net "PWRGD_SYS_PWROK")
	)
	(segment
		(start 218.58732 -36.1442)
		(end 223.93148 -41.48836)
		(width 0.127)
		(layer "In13.Cu")
		(net "PWRGD_SYS_PWROK")
	)
	(segment
		(start 169.82948 -19.162268)
		(end 168.91508 -20.076668)
		(width 0.127)
		(layer "In13.Cu")
		(net "PWRGD_SYS_PWROK")
	)
	(segment
		(start 233.973878 -48.555148)
		(end 235.176314 -47.352712)
		(width 0.127)
		(layer "In13.Cu")
		(net "PWRGD_SYS_PWROK")
	)
	(segment
		(start 202.641962 -32.76854)
		(end 204.076554 -31.333948)
		(width 0.127)
		(layer "In13.Cu")
		(net "PWRGD_SYS_PWROK")
	)
	(segment
		(start 271.53108 -41.736518)
		(end 271.53108 -38.141148)
		(width 0.127)
		(layer "In13.Cu")
		(net "PWRGD_SYS_PWROK")
	)
	(segment
		(start 269.06855 -44.199048)
		(end 271.53108 -41.736518)
		(width 0.127)
		(layer "In13.Cu")
		(net "PWRGD_SYS_PWROK")
	)
	(segment
		(start 228.397562 -48.555148)
		(end 233.973878 -48.555148)
		(width 0.127)
		(layer "In13.Cu")
		(net "PWRGD_SYS_PWROK")
	)
	(segment
		(start 168.91508 -20.076668)
		(end 168.91508 -28.870148)
		(width 0.127)
		(layer "In13.Cu")
		(net "PWRGD_SYS_PWROK")
	)
	(segment
		(start 168.66108 -16.068548)
		(end 169.82948 -17.236948)
		(width 0.127)
		(layer "In13.Cu")
		(net "PWRGD_SYS_PWROK")
	)
	(segment
		(start 240.681764 -47.352712)
		(end 240.8682 -47.539148)
		(width 0.127)
		(layer "In13.Cu")
		(net "PWRGD_SYS_PWROK")
	)
	(segment
		(start 218.58732 -32.403288)
		(end 218.58732 -36.1442)
		(width 0.127)
		(layer "In13.Cu")
		(net "PWRGD_SYS_PWROK")
	)
	(segment
		(start 151.7142 -16.068548)
		(end 168.66108 -16.068548)
		(width 0.127)
		(layer "In13.Cu")
		(net "PWRGD_SYS_PWROK")
	)
	(segment
		(start 169.82948 -17.236948)
		(end 169.82948 -19.162268)
		(width 0.127)
		(layer "In13.Cu")
		(net "PWRGD_SYS_PWROK")
	)
	(segment
		(start 235.176314 -47.352712)
		(end 240.681764 -47.352712)
		(width 0.127)
		(layer "In13.Cu")
		(net "PWRGD_SYS_PWROK")
	)
	(segment
		(start 148.91004 -13.264388)
		(end 151.7142 -16.068548)
		(width 0.127)
		(layer "In13.Cu")
		(net "PWRGD_SYS_PWROK")
	)
	(segment
		(start 253.69647 -44.745148)
		(end 255.24587 -43.195748)
		(width 0.127)
		(layer "In13.Cu")
		(net "PWRGD_SYS_PWROK")
	)
	(segment
		(start 259.639054 -43.195748)
		(end 260.642354 -44.199048)
		(width 0.127)
		(layer "In13.Cu")
		(net "PWRGD_SYS_PWROK")
	)
	(segment
		(start 204.076554 -31.333948)
		(end 217.51798 -31.333948)
		(width 0.127)
		(layer "In13.Cu")
		(net "PWRGD_SYS_PWROK")
	)
	(segment
		(start 255.24587 -43.195748)
		(end 259.639054 -43.195748)
		(width 0.127)
		(layer "In13.Cu")
		(net "PWRGD_SYS_PWROK")
	)
	(segment
		(start 245.622826 -47.539148)
		(end 248.416826 -44.745148)
		(width 0.127)
		(layer "In13.Cu")
		(net "PWRGD_SYS_PWROK")
	)
	(segment
		(start 168.91508 -28.870148)
		(end 176.50968 -36.464748)
		(width 0.127)
		(layer "In13.Cu")
		(net "PWRGD_SYS_PWROK")
	)
	(segment
		(start 123.587764 -355.350572)
		(end 123.72594 -355.488748)
		(width 0.12954)
		(layer "F.Cu")
		(net "PWRGD_PVPP_HBM_CPU1_R")
	)
	(segment
		(start 119.741188 -354.745798)
		(end 120.147588 -354.745798)
		(width 0.12954)
		(layer "F.Cu")
		(net "PWRGD_PVPP_HBM_CPU1_R")
	)
	(segment
		(start 122.184414 -355.69779)
		(end 122.531632 -355.350572)
		(width 0.12954)
		(layer "F.Cu")
		(net "PWRGD_PVPP_HBM_CPU1_R")
	)
	(segment
		(start 122.184414 -355.036882)
		(end 122.184414 -355.69779)
		(width 0.12954)
		(layer "F.Cu")
		(net "PWRGD_PVPP_HBM_CPU1_R")
	)
	(segment
		(start 122.531632 -355.350572)
		(end 123.587764 -355.350572)
		(width 0.12954)
		(layer "F.Cu")
		(net "PWRGD_PVPP_HBM_CPU1_R")
	)
	(segment
		(start 119.741188 -355.71049)
		(end 119.741188 -354.745798)
		(width 0.12954)
		(layer "F.Cu")
		(net "PWRGD_PVPP_HBM_CPU1_R")
	)
	(segment
		(start 120.331738 -354.929948)
		(end 122.07748 -354.929948)
		(width 0.12954)
		(layer "F.Cu")
		(net "PWRGD_PVPP_HBM_CPU1_R")
	)
	(segment
		(start 124.314966 -356.077774)
		(end 123.72594 -355.488748)
		(width 0.12954)
		(layer "F.Cu")
		(net "PWRGD_PVPP_HBM_CPU1_R")
	)
	(segment
		(start 120.147588 -354.745798)
		(end 120.331738 -354.929948)
		(width 0.12954)
		(layer "F.Cu")
		(net "PWRGD_PVPP_HBM_CPU1_R")
	)
	(segment
		(start 124.314966 -356.760526)
		(end 124.314966 -356.077774)
		(width 0.12954)
		(layer "F.Cu")
		(net "PWRGD_PVPP_HBM_CPU1_R")
	)
	(segment
		(start 119.741188 -354.745798)
		(end 119.733314 -354.737924)
		(width 0.12954)
		(layer "F.Cu")
		(net "PWRGD_PVPP_HBM_CPU1_R")
	)
	(segment
		(start 122.07748 -354.929948)
		(end 122.184414 -355.036882)
		(width 0.12954)
		(layer "F.Cu")
		(net "PWRGD_PVPP_HBM_CPU1_R")
	)
	(via
		(at 123.72594 -355.488748)
		(size 0.762)
		(drill 0.381)
		(layers "F.Cu" "B.Cu")
		(net "PWRGD_PVPP_HBM_CPU1_R")
	)
	(segment
		(start 95.792544 -99.137978)
		(end 95.353124 -99.577398)
		(width 0.12954)
		(layer "F.Cu")
		(net "PWRGD_PVPP_HBM_CPU1")
	)
	(segment
		(start 118.480078 -354.737924)
		(end 118.933214 -354.737924)
		(width 0.12954)
		(layer "F.Cu")
		(net "PWRGD_PVPP_HBM_CPU1")
	)
	(segment
		(start 118.350538 -354.867464)
		(end 118.480078 -354.737924)
		(width 0.12954)
		(layer "F.Cu")
		(net "PWRGD_PVPP_HBM_CPU1")
	)
	(segment
		(start 170.155616 -115.375436)
		(end 169.755566 -115.775486)
		(width 0.12954)
		(layer "F.Cu")
		(net "PWRGD_PVPP_HBM_CPU1")
	)
	(segment
		(start 118.350538 -355.18217)
		(end 118.350538 -354.867464)
		(width 0.12954)
		(layer "F.Cu")
		(net "PWRGD_PVPP_HBM_CPU1")
	)
	(segment
		(start 95.353124 -99.577398)
		(end 95.036386 -99.577398)
		(width 0.12954)
		(layer "F.Cu")
		(net "PWRGD_PVPP_HBM_CPU1")
	)
	(via
		(at 97.08388 -110.835948)
		(size 0.508)
		(drill 0.254)
		(layers "F.Cu" "B.Cu")
		(net "PWRGD_PVPP_HBM_CPU1")
	)
	(via
		(at 232.194608 -204.036676)
		(size 0.508)
		(drill 0.254)
		(layers "F.Cu" "B.Cu")
		(net "PWRGD_PVPP_HBM_CPU1")
	)
	(via
		(at 122.5296 -395.81328)
		(size 0.508)
		(drill 0.254)
		(layers "F.Cu" "B.Cu")
		(net "PWRGD_PVPP_HBM_CPU1")
	)
	(via
		(at 172.518578 -396.362428)
		(size 0.508)
		(drill 0.254)
		(layers "F.Cu" "B.Cu")
		(net "PWRGD_PVPP_HBM_CPU1")
	)
	(via
		(at 206.81188 -147.96262)
		(size 0.508)
		(drill 0.254)
		(layers "F.Cu" "B.Cu")
		(net "PWRGD_PVPP_HBM_CPU1")
	)
	(via
		(at 118.350538 -355.18217)
		(size 0.508)
		(drill 0.254)
		(layers "F.Cu" "B.Cu")
		(net "PWRGD_PVPP_HBM_CPU1")
	)
	(via
		(at 95.792544 -99.137978)
		(size 0.508)
		(drill 0.254)
		(layers "F.Cu" "B.Cu")
		(net "PWRGD_PVPP_HBM_CPU1")
	)
	(via
		(at 169.755566 -115.775486)
		(size 0.4572)
		(drill 0.254)
		(layers "F.Cu" "B.Cu")
		(net "PWRGD_PVPP_HBM_CPU1")
	)
	(via
		(at 114.63528 -135.524748)
		(size 0.508)
		(drill 0.254)
		(layers "F.Cu" "B.Cu")
		(net "PWRGD_PVPP_HBM_CPU1")
	)
	(segment
		(start 117.789198 -355.74351)
		(end 118.350538 -355.18217)
		(width 0.12954)
		(layer "B.Cu")
		(net "PWRGD_PVPP_HBM_CPU1")
	)
	(segment
		(start 117.789198 -356.35565)
		(end 117.789198 -355.74351)
		(width 0.12954)
		(layer "B.Cu")
		(net "PWRGD_PVPP_HBM_CPU1")
	)
	(segment
		(start 116.46281 -368.230658)
		(end 117.01018 -367.683288)
		(width 0.12954)
		(layer "B.Cu")
		(net "PWRGD_PVPP_HBM_CPU1")
	)
	(segment
		(start 116.46281 -389.03021)
		(end 116.46281 -368.230658)
		(width 0.12954)
		(layer "B.Cu")
		(net "PWRGD_PVPP_HBM_CPU1")
	)
	(segment
		(start 122.5296 -395.81328)
		(end 121.97588 -395.81328)
		(width 0.12954)
		(layer "B.Cu")
		(net "PWRGD_PVPP_HBM_CPU1")
	)
	(segment
		(start 120.1166 -392.684)
		(end 116.46281 -389.03021)
		(width 0.12954)
		(layer "B.Cu")
		(net "PWRGD_PVPP_HBM_CPU1")
	)
	(segment
		(start 121.97588 -395.81328)
		(end 120.1166 -393.954)
		(width 0.12954)
		(layer "B.Cu")
		(net "PWRGD_PVPP_HBM_CPU1")
	)
	(segment
		(start 117.01018 -357.134668)
		(end 117.789198 -356.35565)
		(width 0.12954)
		(layer "B.Cu")
		(net "PWRGD_PVPP_HBM_CPU1")
	)
	(segment
		(start 117.01018 -367.683288)
		(end 117.01018 -357.134668)
		(width 0.12954)
		(layer "B.Cu")
		(net "PWRGD_PVPP_HBM_CPU1")
	)
	(segment
		(start 120.1166 -393.954)
		(end 120.1166 -392.684)
		(width 0.12954)
		(layer "B.Cu")
		(net "PWRGD_PVPP_HBM_CPU1")
	)
	(segment
		(start 97.08388 -108.930948)
		(end 96.65208 -108.499148)
		(width 0.127)
		(layer "In2.Cu")
		(net "PWRGD_PVPP_HBM_CPU1")
	)
	(segment
		(start 97.08388 -110.835948)
		(end 97.08388 -108.930948)
		(width 0.127)
		(layer "In2.Cu")
		(net "PWRGD_PVPP_HBM_CPU1")
	)
	(segment
		(start 95.792544 -101.197918)
		(end 95.792544 -99.137978)
		(width 0.127)
		(layer "In2.Cu")
		(net "PWRGD_PVPP_HBM_CPU1")
	)
	(segment
		(start 96.65208 -102.057454)
		(end 95.792544 -101.197918)
		(width 0.127)
		(layer "In2.Cu")
		(net "PWRGD_PVPP_HBM_CPU1")
	)
	(segment
		(start 96.65208 -108.499148)
		(end 96.65208 -102.057454)
		(width 0.127)
		(layer "In2.Cu")
		(net "PWRGD_PVPP_HBM_CPU1")
	)
	(segment
		(start 230.664512 -241.186462)
		(end 230.664512 -205.566772)
		(width 0.127)
		(layer "In4.Cu")
		(net "PWRGD_PVPP_HBM_CPU1")
	)
	(segment
		(start 172.518578 -396.362428)
		(end 174.16272 -396.362428)
		(width 0.127)
		(layer "In4.Cu")
		(net "PWRGD_PVPP_HBM_CPU1")
	)
	(segment
		(start 184.110376 -379.409452)
		(end 190.394336 -379.409452)
		(width 0.127)
		(layer "In4.Cu")
		(net "PWRGD_PVPP_HBM_CPU1")
	)
	(segment
		(start 211.909406 -349.82658)
		(end 216.258394 -349.82658)
		(width 0.127)
		(layer "In4.Cu")
		(net "PWRGD_PVPP_HBM_CPU1")
	)
	(segment
		(start 175.675036 -387.844792)
		(end 184.110376 -379.409452)
		(width 0.127)
		(layer "In4.Cu")
		(net "PWRGD_PVPP_HBM_CPU1")
	)
	(segment
		(start 190.394336 -379.409452)
		(end 199.224392 -370.579396)
		(width 0.127)
		(layer "In4.Cu")
		(net "PWRGD_PVPP_HBM_CPU1")
	)
	(segment
		(start 223.425512 -248.425462)
		(end 230.664512 -241.186462)
		(width 0.127)
		(layer "In4.Cu")
		(net "PWRGD_PVPP_HBM_CPU1")
	)
	(segment
		(start 230.664512 -205.566772)
		(end 232.194608 -204.036676)
		(width 0.127)
		(layer "In4.Cu")
		(net "PWRGD_PVPP_HBM_CPU1")
	)
	(segment
		(start 175.675036 -394.850112)
		(end 175.675036 -387.844792)
		(width 0.127)
		(layer "In4.Cu")
		(net "PWRGD_PVPP_HBM_CPU1")
	)
	(segment
		(start 199.224392 -370.579396)
		(end 199.224392 -362.511594)
		(width 0.127)
		(layer "In4.Cu")
		(net "PWRGD_PVPP_HBM_CPU1")
	)
	(segment
		(start 216.258394 -349.82658)
		(end 223.425512 -342.659462)
		(width 0.127)
		(layer "In4.Cu")
		(net "PWRGD_PVPP_HBM_CPU1")
	)
	(segment
		(start 199.224392 -362.511594)
		(end 211.909406 -349.82658)
		(width 0.127)
		(layer "In4.Cu")
		(net "PWRGD_PVPP_HBM_CPU1")
	)
	(segment
		(start 174.16272 -396.362428)
		(end 175.675036 -394.850112)
		(width 0.127)
		(layer "In4.Cu")
		(net "PWRGD_PVPP_HBM_CPU1")
	)
	(segment
		(start 223.425512 -342.659462)
		(end 223.425512 -248.425462)
		(width 0.127)
		(layer "In4.Cu")
		(net "PWRGD_PVPP_HBM_CPU1")
	)
	(segment
		(start 171.345098 -396.362428)
		(end 171.096686 -396.61084)
		(width 0.127)
		(layer "In11.Cu")
		(net "PWRGD_PVPP_HBM_CPU1")
	)
	(segment
		(start 167.24503 -396.61084)
		(end 166.996618 -396.362428)
		(width 0.127)
		(layer "In11.Cu")
		(net "PWRGD_PVPP_HBM_CPU1")
	)
	(segment
		(start 172.518578 -396.362428)
		(end 171.345098 -396.362428)
		(width 0.127)
		(layer "In11.Cu")
		(net "PWRGD_PVPP_HBM_CPU1")
	)
	(segment
		(start 171.096686 -396.61084)
		(end 167.24503 -396.61084)
		(width 0.127)
		(layer "In11.Cu")
		(net "PWRGD_PVPP_HBM_CPU1")
	)
	(segment
		(start 206.81188 -149.113748)
		(end 206.81188 -147.96262)
		(width 0.127)
		(layer "In11.Cu")
		(net "PWRGD_PVPP_HBM_CPU1")
	)
	(segment
		(start 207.57388 -149.875748)
		(end 206.81188 -149.113748)
		(width 0.127)
		(layer "In11.Cu")
		(net "PWRGD_PVPP_HBM_CPU1")
	)
	(segment
		(start 222.633794 -172.274992)
		(end 209.98688 -159.628078)
		(width 0.127)
		(layer "In11.Cu")
		(net "PWRGD_PVPP_HBM_CPU1")
	)
	(segment
		(start 222.633794 -196.840094)
		(end 222.633794 -172.274992)
		(width 0.127)
		(layer "In11.Cu")
		(net "PWRGD_PVPP_HBM_CPU1")
	)
	(segment
		(start 166.10584 -395.81328)
		(end 122.5296 -395.81328)
		(width 0.127)
		(layer "In11.Cu")
		(net "PWRGD_PVPP_HBM_CPU1")
	)
	(segment
		(start 229.830376 -204.036676)
		(end 222.633794 -196.840094)
		(width 0.127)
		(layer "In11.Cu")
		(net "PWRGD_PVPP_HBM_CPU1")
	)
	(segment
		(start 166.996618 -396.362428)
		(end 166.654988 -396.362428)
		(width 0.127)
		(layer "In11.Cu")
		(net "PWRGD_PVPP_HBM_CPU1")
	)
	(segment
		(start 114.63528 -135.524748)
		(end 114.63528 -130.165348)
		(width 0.127)
		(layer "In11.Cu")
		(net "PWRGD_PVPP_HBM_CPU1")
	)
	(segment
		(start 209.98688 -159.628078)
		(end 209.98688 -154.143202)
		(width 0.127)
		(layer "In11.Cu")
		(net "PWRGD_PVPP_HBM_CPU1")
	)
	(segment
		(start 232.194608 -204.036676)
		(end 229.830376 -204.036676)
		(width 0.127)
		(layer "In11.Cu")
		(net "PWRGD_PVPP_HBM_CPU1")
	)
	(segment
		(start 209.98688 -154.143202)
		(end 207.57388 -151.730202)
		(width 0.127)
		(layer "In11.Cu")
		(net "PWRGD_PVPP_HBM_CPU1")
	)
	(segment
		(start 207.57388 -151.730202)
		(end 207.57388 -149.875748)
		(width 0.127)
		(layer "In11.Cu")
		(net "PWRGD_PVPP_HBM_CPU1")
	)
	(segment
		(start 114.63528 -130.165348)
		(end 97.08388 -112.613948)
		(width 0.127)
		(layer "In11.Cu")
		(net "PWRGD_PVPP_HBM_CPU1")
	)
	(segment
		(start 97.08388 -112.613948)
		(end 97.08388 -110.835948)
		(width 0.127)
		(layer "In11.Cu")
		(net "PWRGD_PVPP_HBM_CPU1")
	)
	(segment
		(start 166.654988 -396.362428)
		(end 166.10584 -395.81328)
		(width 0.127)
		(layer "In11.Cu")
		(net "PWRGD_PVPP_HBM_CPU1")
	)
	(segment
		(start 115.37188 -136.261348)
		(end 114.63528 -135.524748)
		(width 0.127)
		(layer "In13.Cu")
		(net "PWRGD_PVPP_HBM_CPU1")
	)
	(segment
		(start 206.81188 -147.96262)
		(end 206.81188 -146.776948)
		(width 0.127)
		(layer "In13.Cu")
		(net "PWRGD_PVPP_HBM_CPU1")
	)
	(segment
		(start 146.642582 -136.261348)
		(end 115.37188 -136.261348)
		(width 0.127)
		(layer "In13.Cu")
		(net "PWRGD_PVPP_HBM_CPU1")
	)
	(segment
		(start 153.881582 -143.500348)
		(end 146.642582 -136.261348)
		(width 0.127)
		(layer "In13.Cu")
		(net "PWRGD_PVPP_HBM_CPU1")
	)
	(segment
		(start 203.53528 -143.500348)
		(end 153.881582 -143.500348)
		(width 0.127)
		(layer "In13.Cu")
		(net "PWRGD_PVPP_HBM_CPU1")
	)
	(segment
		(start 206.81188 -146.776948)
		(end 203.53528 -143.500348)
		(width 0.127)
		(layer "In13.Cu")
		(net "PWRGD_PVPP_HBM_CPU1")
	)
	(segment
		(start 97.54108 -110.378748)
		(end 97.08388 -110.835948)
		(width 0.127)
		(layer "In15.Cu")
		(net "PWRGD_PVPP_HBM_CPU1")
	)
	(segment
		(start 150.67788 -115.47856)
		(end 145.41754 -110.21822)
		(width 0.127)
		(layer "In15.Cu")
		(net "PWRGD_PVPP_HBM_CPU1")
	)
	(segment
		(start 143.3195 -111.0107)
		(end 141.80566 -111.0107)
		(width 0.127)
		(layer "In15.Cu")
		(net "PWRGD_PVPP_HBM_CPU1")
	)
	(segment
		(start 127.10922 -111.443008)
		(end 111.17834 -111.443008)
		(width 0.127)
		(layer "In15.Cu")
		(net "PWRGD_PVPP_HBM_CPU1")
	)
	(segment
		(start 169.19702 -116.334032)
		(end 169.19702 -116.868448)
		(width 0.127)
		(layer "In15.Cu")
		(net "PWRGD_PVPP_HBM_CPU1")
	)
	(segment
		(start 144.11198 -110.21822)
		(end 143.3195 -111.0107)
		(width 0.127)
		(layer "In15.Cu")
		(net "PWRGD_PVPP_HBM_CPU1")
	)
	(segment
		(start 169.755566 -115.775486)
		(end 169.19702 -116.334032)
		(width 0.127)
		(layer "In15.Cu")
		(net "PWRGD_PVPP_HBM_CPU1")
	)
	(segment
		(start 152.96388 -118.735348)
		(end 152.617932 -118.735348)
		(width 0.127)
		(layer "In15.Cu")
		(net "PWRGD_PVPP_HBM_CPU1")
	)
	(segment
		(start 163.93668 -122.128788)
		(end 158.37916 -122.128788)
		(width 0.127)
		(layer "In15.Cu")
		(net "PWRGD_PVPP_HBM_CPU1")
	)
	(segment
		(start 156.92247 -120.672098)
		(end 154.90063 -120.672098)
		(width 0.127)
		(layer "In15.Cu")
		(net "PWRGD_PVPP_HBM_CPU1")
	)
	(segment
		(start 101.45268 -109.896148)
		(end 100.97008 -110.378748)
		(width 0.127)
		(layer "In15.Cu")
		(net "PWRGD_PVPP_HBM_CPU1")
	)
	(segment
		(start 154.90063 -120.672098)
		(end 152.96388 -118.735348)
		(width 0.127)
		(layer "In15.Cu")
		(net "PWRGD_PVPP_HBM_CPU1")
	)
	(segment
		(start 169.19702 -116.868448)
		(end 163.93668 -122.128788)
		(width 0.127)
		(layer "In15.Cu")
		(net "PWRGD_PVPP_HBM_CPU1")
	)
	(segment
		(start 152.617932 -118.735348)
		(end 150.67788 -116.795296)
		(width 0.127)
		(layer "In15.Cu")
		(net "PWRGD_PVPP_HBM_CPU1")
	)
	(segment
		(start 109.63148 -109.896148)
		(end 101.45268 -109.896148)
		(width 0.127)
		(layer "In15.Cu")
		(net "PWRGD_PVPP_HBM_CPU1")
	)
	(segment
		(start 111.17834 -111.443008)
		(end 109.63148 -109.896148)
		(width 0.127)
		(layer "In15.Cu")
		(net "PWRGD_PVPP_HBM_CPU1")
	)
	(segment
		(start 150.67788 -116.795296)
		(end 150.67788 -115.47856)
		(width 0.127)
		(layer "In15.Cu")
		(net "PWRGD_PVPP_HBM_CPU1")
	)
	(segment
		(start 141.80566 -111.0107)
		(end 140.973048 -110.178088)
		(width 0.127)
		(layer "In15.Cu")
		(net "PWRGD_PVPP_HBM_CPU1")
	)
	(segment
		(start 158.37916 -122.128788)
		(end 156.92247 -120.672098)
		(width 0.127)
		(layer "In15.Cu")
		(net "PWRGD_PVPP_HBM_CPU1")
	)
	(segment
		(start 145.41754 -110.21822)
		(end 144.11198 -110.21822)
		(width 0.127)
		(layer "In15.Cu")
		(net "PWRGD_PVPP_HBM_CPU1")
	)
	(segment
		(start 140.973048 -110.178088)
		(end 128.37414 -110.178088)
		(width 0.127)
		(layer "In15.Cu")
		(net "PWRGD_PVPP_HBM_CPU1")
	)
	(segment
		(start 128.37414 -110.178088)
		(end 127.10922 -111.443008)
		(width 0.127)
		(layer "In15.Cu")
		(net "PWRGD_PVPP_HBM_CPU1")
	)
	(segment
		(start 100.97008 -110.378748)
		(end 97.54108 -110.378748)
		(width 0.127)
		(layer "In15.Cu")
		(net "PWRGD_PVPP_HBM_CPU1")
	)
	(segment
		(start 371.397276 -356.150418)
		(end 371.397276 -355.57079)
		(width 0.12954)
		(layer "F.Cu")
		(net "PWRGD_PVPP_HBM_CPU0_R")
	)
	(segment
		(start 367.029238 -355.651816)
		(end 367.029238 -354.660962)
		(width 0.12954)
		(layer "F.Cu")
		(net "PWRGD_PVPP_HBM_CPU0_R")
	)
	(segment
		(start 370.251228 -355.57079)
		(end 371.397276 -355.57079)
		(width 0.12954)
		(layer "F.Cu")
		(net "PWRGD_PVPP_HBM_CPU0_R")
	)
	(segment
		(start 369.252246 -354.825808)
		(end 368.999516 -354.825808)
		(width 0.12954)
		(layer "F.Cu")
		(net "PWRGD_PVPP_HBM_CPU0_R")
	)
	(segment
		(start 368.482118 -354.30841)
		(end 367.38179 -354.30841)
		(width 0.12954)
		(layer "F.Cu")
		(net "PWRGD_PVPP_HBM_CPU0_R")
	)
	(segment
		(start 368.999516 -354.825808)
		(end 368.482118 -354.30841)
		(width 0.12954)
		(layer "F.Cu")
		(net "PWRGD_PVPP_HBM_CPU0_R")
	)
	(segment
		(start 367.029238 -354.660962)
		(end 367.037874 -354.652326)
		(width 0.12954)
		(layer "F.Cu")
		(net "PWRGD_PVPP_HBM_CPU0_R")
	)
	(segment
		(start 370.124228 -355.69779)
		(end 369.252246 -354.825808)
		(width 0.12954)
		(layer "F.Cu")
		(net "PWRGD_PVPP_HBM_CPU0_R")
	)
	(segment
		(start 372.25478 -356.760526)
		(end 372.007384 -356.760526)
		(width 0.12954)
		(layer "F.Cu")
		(net "PWRGD_PVPP_HBM_CPU0_R")
	)
	(segment
		(start 370.124228 -355.69779)
		(end 370.251228 -355.57079)
		(width 0.12954)
		(layer "F.Cu")
		(net "PWRGD_PVPP_HBM_CPU0_R")
	)
	(segment
		(start 367.38179 -354.30841)
		(end 367.037874 -354.652326)
		(width 0.12954)
		(layer "F.Cu")
		(net "PWRGD_PVPP_HBM_CPU0_R")
	)
	(segment
		(start 372.007384 -356.760526)
		(end 371.397276 -356.150418)
		(width 0.12954)
		(layer "F.Cu")
		(net "PWRGD_PVPP_HBM_CPU0_R")
	)
	(via
		(at 371.397276 -355.57079)
		(size 0.762)
		(drill 0.381)
		(layers "F.Cu" "B.Cu")
		(net "PWRGD_PVPP_HBM_CPU0_R")
	)
	(segment
		(start 172.555662 -114.575336)
		(end 172.155612 -114.975386)
		(width 0.12954)
		(layer "F.Cu")
		(net "PWRGD_PVPP_HBM_CPU0")
	)
	(segment
		(start 102.54488 -103.010208)
		(end 102.42042 -102.885748)
		(width 0.12954)
		(layer "F.Cu")
		(net "PWRGD_PVPP_HBM_CPU0")
	)
	(segment
		(start 366.531398 -353.79279)
		(end 366.237774 -354.086414)
		(width 0.12954)
		(layer "F.Cu")
		(net "PWRGD_PVPP_HBM_CPU0")
	)
	(segment
		(start 367.029238 -353.79279)
		(end 366.531398 -353.79279)
		(width 0.12954)
		(layer "F.Cu")
		(net "PWRGD_PVPP_HBM_CPU0")
	)
	(segment
		(start 102.42042 -102.885748)
		(end 102.079298 -102.885748)
		(width 0.12954)
		(layer "F.Cu")
		(net "PWRGD_PVPP_HBM_CPU0")
	)
	(segment
		(start 102.079298 -102.885748)
		(end 101.886766 -102.693216)
		(width 0.12954)
		(layer "F.Cu")
		(net "PWRGD_PVPP_HBM_CPU0")
	)
	(segment
		(start 366.237774 -354.086414)
		(end 366.237774 -354.652326)
		(width 0.12954)
		(layer "F.Cu")
		(net "PWRGD_PVPP_HBM_CPU0")
	)
	(via
		(at 102.54488 -103.010208)
		(size 0.508)
		(drill 0.254)
		(layers "F.Cu" "B.Cu")
		(net "PWRGD_PVPP_HBM_CPU0")
	)
	(via
		(at 102.41788 -110.835948)
		(size 0.508)
		(drill 0.254)
		(layers "F.Cu" "B.Cu")
		(net "PWRGD_PVPP_HBM_CPU0")
	)
	(via
		(at 172.155612 -114.975386)
		(size 0.4572)
		(drill 0.254)
		(layers "F.Cu" "B.Cu")
		(net "PWRGD_PVPP_HBM_CPU0")
	)
	(via
		(at 367.029238 -353.79279)
		(size 0.508)
		(drill 0.254)
		(layers "F.Cu" "B.Cu")
		(net "PWRGD_PVPP_HBM_CPU0")
	)
	(via
		(at 178.89728 -163.896548)
		(size 0.508)
		(drill 0.254)
		(layers "F.Cu" "B.Cu")
		(net "PWRGD_PVPP_HBM_CPU0")
	)
	(segment
		(start 253.595378 -301.92853)
		(end 253.595378 -185.65749)
		(width 0.12954)
		(layer "B.Cu")
		(net "PWRGD_PVPP_HBM_CPU0")
	)
	(segment
		(start 225.083116 -168.854628)
		(end 181.903116 -168.854628)
		(width 0.12954)
		(layer "B.Cu")
		(net "PWRGD_PVPP_HBM_CPU0")
	)
	(segment
		(start 366.516158 -357.56977)
		(end 365.962438 -358.12349)
		(width 0.12954)
		(layer "B.Cu")
		(net "PWRGD_PVPP_HBM_CPU0")
	)
	(segment
		(start 178.89728 -165.848792)
		(end 178.89728 -163.896548)
		(width 0.12954)
		(layer "B.Cu")
		(net "PWRGD_PVPP_HBM_CPU0")
	)
	(segment
		(start 365.962438 -358.12349)
		(end 365.962438 -358.57815)
		(width 0.12954)
		(layer "B.Cu")
		(net "PWRGD_PVPP_HBM_CPU0")
	)
	(segment
		(start 252.68428 -302.839628)
		(end 253.595378 -301.92853)
		(width 0.12954)
		(layer "B.Cu")
		(net "PWRGD_PVPP_HBM_CPU0")
	)
	(segment
		(start 255.805178 -326.07631)
		(end 254.893318 -325.16445)
		(width 0.12954)
		(layer "B.Cu")
		(net "PWRGD_PVPP_HBM_CPU0")
	)
	(segment
		(start 252.68428 -321.389756)
		(end 252.68428 -302.839628)
		(width 0.12954)
		(layer "B.Cu")
		(net "PWRGD_PVPP_HBM_CPU0")
	)
	(segment
		(start 367.09858 -360.525568)
		(end 364.750096 -362.874052)
		(width 0.12954)
		(layer "B.Cu")
		(net "PWRGD_PVPP_HBM_CPU0")
	)
	(segment
		(start 367.029238 -353.79279)
		(end 366.516158 -354.30587)
		(width 0.12954)
		(layer "B.Cu")
		(net "PWRGD_PVPP_HBM_CPU0")
	)
	(segment
		(start 232.042716 -175.814228)
		(end 225.083116 -168.854628)
		(width 0.12954)
		(layer "B.Cu")
		(net "PWRGD_PVPP_HBM_CPU0")
	)
	(segment
		(start 367.09858 -359.714292)
		(end 367.09858 -360.525568)
		(width 0.12954)
		(layer "B.Cu")
		(net "PWRGD_PVPP_HBM_CPU0")
	)
	(segment
		(start 259.792978 -326.65289)
		(end 259.216398 -326.07631)
		(width 0.12954)
		(layer "B.Cu")
		(net "PWRGD_PVPP_HBM_CPU0")
	)
	(segment
		(start 243.752116 -175.814228)
		(end 232.042716 -175.814228)
		(width 0.12954)
		(layer "B.Cu")
		(net "PWRGD_PVPP_HBM_CPU0")
	)
	(segment
		(start 275.116798 -343.403174)
		(end 259.792978 -328.079354)
		(width 0.12954)
		(layer "B.Cu")
		(net "PWRGD_PVPP_HBM_CPU0")
	)
	(segment
		(start 364.750096 -365.876332)
		(end 350.612202 -380.014226)
		(width 0.12954)
		(layer "B.Cu")
		(net "PWRGD_PVPP_HBM_CPU0")
	)
	(segment
		(start 275.116798 -367.472722)
		(end 275.116798 -343.403174)
		(width 0.12954)
		(layer "B.Cu")
		(net "PWRGD_PVPP_HBM_CPU0")
	)
	(segment
		(start 287.658302 -380.014226)
		(end 275.116798 -367.472722)
		(width 0.12954)
		(layer "B.Cu")
		(net "PWRGD_PVPP_HBM_CPU0")
	)
	(segment
		(start 254.893318 -323.598794)
		(end 252.68428 -321.389756)
		(width 0.12954)
		(layer "B.Cu")
		(net "PWRGD_PVPP_HBM_CPU0")
	)
	(segment
		(start 365.962438 -358.57815)
		(end 367.09858 -359.714292)
		(width 0.12954)
		(layer "B.Cu")
		(net "PWRGD_PVPP_HBM_CPU0")
	)
	(segment
		(start 366.516158 -354.30587)
		(end 366.516158 -357.56977)
		(width 0.12954)
		(layer "B.Cu")
		(net "PWRGD_PVPP_HBM_CPU0")
	)
	(segment
		(start 364.750096 -362.874052)
		(end 364.750096 -365.876332)
		(width 0.12954)
		(layer "B.Cu")
		(net "PWRGD_PVPP_HBM_CPU0")
	)
	(segment
		(start 259.216398 -326.07631)
		(end 255.805178 -326.07631)
		(width 0.12954)
		(layer "B.Cu")
		(net "PWRGD_PVPP_HBM_CPU0")
	)
	(segment
		(start 254.893318 -325.16445)
		(end 254.893318 -323.598794)
		(width 0.12954)
		(layer "B.Cu")
		(net "PWRGD_PVPP_HBM_CPU0")
	)
	(segment
		(start 253.595378 -185.65749)
		(end 243.752116 -175.814228)
		(width 0.12954)
		(layer "B.Cu")
		(net "PWRGD_PVPP_HBM_CPU0")
	)
	(segment
		(start 350.612202 -380.014226)
		(end 287.658302 -380.014226)
		(width 0.12954)
		(layer "B.Cu")
		(net "PWRGD_PVPP_HBM_CPU0")
	)
	(segment
		(start 181.903116 -168.854628)
		(end 178.89728 -165.848792)
		(width 0.12954)
		(layer "B.Cu")
		(net "PWRGD_PVPP_HBM_CPU0")
	)
	(segment
		(start 259.792978 -328.079354)
		(end 259.792978 -326.65289)
		(width 0.12954)
		(layer "B.Cu")
		(net "PWRGD_PVPP_HBM_CPU0")
	)
	(segment
		(start 102.41788 -110.835948)
		(end 102.54488 -110.708948)
		(width 0.127)
		(layer "In2.Cu")
		(net "PWRGD_PVPP_HBM_CPU0")
	)
	(segment
		(start 102.54488 -110.708948)
		(end 102.54488 -103.010208)
		(width 0.127)
		(layer "In2.Cu")
		(net "PWRGD_PVPP_HBM_CPU0")
	)
	(segment
		(start 171.75988 -115.371118)
		(end 172.155612 -114.975386)
		(width 0.127)
		(layer "In11.Cu")
		(net "PWRGD_PVPP_HBM_CPU0")
	)
	(segment
		(start 172.14088 -153.685748)
		(end 172.14088 -128.996948)
		(width 0.127)
		(layer "In11.Cu")
		(net "PWRGD_PVPP_HBM_CPU0")
	)
	(segment
		(start 170.911012 -127.878332)
		(end 170.36288 -127.3302)
		(width 0.127)
		(layer "In11.Cu")
		(net "PWRGD_PVPP_HBM_CPU0")
	)
	(segment
		(start 178.89728 -163.896548)
		(end 178.00828 -163.007548)
		(width 0.127)
		(layer "In11.Cu")
		(net "PWRGD_PVPP_HBM_CPU0")
	)
	(segment
		(start 171.75988 -128.615948)
		(end 171.2468 -128.615948)
		(width 0.127)
		(layer "In11.Cu")
		(net "PWRGD_PVPP_HBM_CPU0")
	)
	(segment
		(start 170.36288 -127.3302)
		(end 170.36288 -123.054364)
		(width 0.127)
		(layer "In11.Cu")
		(net "PWRGD_PVPP_HBM_CPU0")
	)
	(segment
		(start 171.121324 -122.29592)
		(end 171.121324 -119.482616)
		(width 0.127)
		(layer "In11.Cu")
		(net "PWRGD_PVPP_HBM_CPU0")
	)
	(segment
		(start 171.576746 -117.772434)
		(end 171.75988 -117.5893)
		(width 0.127)
		(layer "In11.Cu")
		(net "PWRGD_PVPP_HBM_CPU0")
	)
	(segment
		(start 171.75988 -117.5893)
		(end 171.75988 -115.371118)
		(width 0.127)
		(layer "In11.Cu")
		(net "PWRGD_PVPP_HBM_CPU0")
	)
	(segment
		(start 171.2468 -128.615948)
		(end 170.911012 -128.28016)
		(width 0.127)
		(layer "In11.Cu")
		(net "PWRGD_PVPP_HBM_CPU0")
	)
	(segment
		(start 171.121324 -119.482616)
		(end 170.954446 -119.315738)
		(width 0.127)
		(layer "In11.Cu")
		(net "PWRGD_PVPP_HBM_CPU0")
	)
	(segment
		(start 171.13758 -117.772434)
		(end 171.576746 -117.772434)
		(width 0.127)
		(layer "In11.Cu")
		(net "PWRGD_PVPP_HBM_CPU0")
	)
	(segment
		(start 178.00828 -159.553148)
		(end 172.14088 -153.685748)
		(width 0.127)
		(layer "In11.Cu")
		(net "PWRGD_PVPP_HBM_CPU0")
	)
	(segment
		(start 170.954446 -117.955568)
		(end 171.13758 -117.772434)
		(width 0.127)
		(layer "In11.Cu")
		(net "PWRGD_PVPP_HBM_CPU0")
	)
	(segment
		(start 170.36288 -123.054364)
		(end 171.121324 -122.29592)
		(width 0.127)
		(layer "In11.Cu")
		(net "PWRGD_PVPP_HBM_CPU0")
	)
	(segment
		(start 172.14088 -128.996948)
		(end 171.75988 -128.615948)
		(width 0.127)
		(layer "In11.Cu")
		(net "PWRGD_PVPP_HBM_CPU0")
	)
	(segment
		(start 178.00828 -163.007548)
		(end 178.00828 -159.553148)
		(width 0.127)
		(layer "In11.Cu")
		(net "PWRGD_PVPP_HBM_CPU0")
	)
	(segment
		(start 170.954446 -119.315738)
		(end 170.954446 -117.955568)
		(width 0.127)
		(layer "In11.Cu")
		(net "PWRGD_PVPP_HBM_CPU0")
	)
	(segment
		(start 170.911012 -128.28016)
		(end 170.911012 -127.878332)
		(width 0.127)
		(layer "In11.Cu")
		(net "PWRGD_PVPP_HBM_CPU0")
	)
	(segment
		(start 152.604216 -119.671338)
		(end 157.723078 -124.7902)
		(width 0.127)
		(layer "In15.Cu")
		(net "PWRGD_PVPP_HBM_CPU0")
	)
	(segment
		(start 169.102278 -118.56847)
		(end 169.930318 -118.56847)
		(width 0.127)
		(layer "In15.Cu")
		(net "PWRGD_PVPP_HBM_CPU0")
	)
	(segment
		(start 149.62632 -115.8367)
		(end 149.62632 -117.023642)
		(width 0.127)
		(layer "In15.Cu")
		(net "PWRGD_PVPP_HBM_CPU0")
	)
	(segment
		(start 171.1579 -116.177568)
		(end 171.61256 -116.177568)
		(width 0.127)
		(layer "In15.Cu")
		(net "PWRGD_PVPP_HBM_CPU0")
	)
	(segment
		(start 171.61256 -116.177568)
		(end 171.75988 -116.030248)
		(width 0.127)
		(layer "In15.Cu")
		(net "PWRGD_PVPP_HBM_CPU0")
	)
	(segment
		(start 102.41788 -110.835948)
		(end 102.79888 -110.454948)
		(width 0.127)
		(layer "In15.Cu")
		(net "PWRGD_PVPP_HBM_CPU0")
	)
	(segment
		(start 110.39094 -112.332008)
		(end 130.535172 -112.332008)
		(width 0.127)
		(layer "In15.Cu")
		(net "PWRGD_PVPP_HBM_CPU0")
	)
	(segment
		(start 131.48564 -111.38154)
		(end 136.364472 -111.38154)
		(width 0.127)
		(layer "In15.Cu")
		(net "PWRGD_PVPP_HBM_CPU0")
	)
	(segment
		(start 144.798288 -112.893348)
		(end 144.8816 -112.97666)
		(width 0.127)
		(layer "In15.Cu")
		(net "PWRGD_PVPP_HBM_CPU0")
	)
	(segment
		(start 170.1546 -118.344188)
		(end 170.1546 -118.008908)
		(width 0.127)
		(layer "In15.Cu")
		(net "PWRGD_PVPP_HBM_CPU0")
	)
	(segment
		(start 157.723078 -124.7902)
		(end 159.22371 -124.7902)
		(width 0.127)
		(layer "In15.Cu")
		(net "PWRGD_PVPP_HBM_CPU0")
	)
	(segment
		(start 159.627062 -124.386848)
		(end 160.016698 -124.386848)
		(width 0.127)
		(layer "In15.Cu")
		(net "PWRGD_PVPP_HBM_CPU0")
	)
	(segment
		(start 170.95978 -117.612668)
		(end 170.95978 -116.375688)
		(width 0.127)
		(layer "In15.Cu")
		(net "PWRGD_PVPP_HBM_CPU0")
	)
	(segment
		(start 171.75988 -115.371118)
		(end 172.155612 -114.975386)
		(width 0.127)
		(layer "In15.Cu")
		(net "PWRGD_PVPP_HBM_CPU0")
	)
	(segment
		(start 144.8816 -112.97666)
		(end 146.76628 -112.97666)
		(width 0.127)
		(layer "In15.Cu")
		(net "PWRGD_PVPP_HBM_CPU0")
	)
	(segment
		(start 170.1546 -118.008908)
		(end 170.39082 -117.772688)
		(width 0.127)
		(layer "In15.Cu")
		(net "PWRGD_PVPP_HBM_CPU0")
	)
	(segment
		(start 160.501838 -123.901708)
		(end 163.76904 -123.901708)
		(width 0.127)
		(layer "In15.Cu")
		(net "PWRGD_PVPP_HBM_CPU0")
	)
	(segment
		(start 146.76628 -112.97666)
		(end 149.62632 -115.8367)
		(width 0.127)
		(layer "In15.Cu")
		(net "PWRGD_PVPP_HBM_CPU0")
	)
	(segment
		(start 149.62632 -117.023642)
		(end 152.274016 -119.671338)
		(width 0.127)
		(layer "In15.Cu")
		(net "PWRGD_PVPP_HBM_CPU0")
	)
	(segment
		(start 136.364472 -111.38154)
		(end 137.87628 -112.893348)
		(width 0.127)
		(layer "In15.Cu")
		(net "PWRGD_PVPP_HBM_CPU0")
	)
	(segment
		(start 170.39082 -117.772688)
		(end 170.79976 -117.772688)
		(width 0.127)
		(layer "In15.Cu")
		(net "PWRGD_PVPP_HBM_CPU0")
	)
	(segment
		(start 170.79976 -117.772688)
		(end 170.95978 -117.612668)
		(width 0.127)
		(layer "In15.Cu")
		(net "PWRGD_PVPP_HBM_CPU0")
	)
	(segment
		(start 152.274016 -119.671338)
		(end 152.604216 -119.671338)
		(width 0.127)
		(layer "In15.Cu")
		(net "PWRGD_PVPP_HBM_CPU0")
	)
	(segment
		(start 170.95978 -116.375688)
		(end 171.1579 -116.177568)
		(width 0.127)
		(layer "In15.Cu")
		(net "PWRGD_PVPP_HBM_CPU0")
	)
	(segment
		(start 171.75988 -116.030248)
		(end 171.75988 -115.371118)
		(width 0.127)
		(layer "In15.Cu")
		(net "PWRGD_PVPP_HBM_CPU0")
	)
	(segment
		(start 102.79888 -110.454948)
		(end 108.51388 -110.454948)
		(width 0.127)
		(layer "In15.Cu")
		(net "PWRGD_PVPP_HBM_CPU0")
	)
	(segment
		(start 163.76904 -123.901708)
		(end 169.102278 -118.56847)
		(width 0.127)
		(layer "In15.Cu")
		(net "PWRGD_PVPP_HBM_CPU0")
	)
	(segment
		(start 159.22371 -124.7902)
		(end 159.627062 -124.386848)
		(width 0.127)
		(layer "In15.Cu")
		(net "PWRGD_PVPP_HBM_CPU0")
	)
	(segment
		(start 160.016698 -124.386848)
		(end 160.501838 -123.901708)
		(width 0.127)
		(layer "In15.Cu")
		(net "PWRGD_PVPP_HBM_CPU0")
	)
	(segment
		(start 130.535172 -112.332008)
		(end 131.48564 -111.38154)
		(width 0.127)
		(layer "In15.Cu")
		(net "PWRGD_PVPP_HBM_CPU0")
	)
	(segment
		(start 137.87628 -112.893348)
		(end 144.798288 -112.893348)
		(width 0.127)
		(layer "In15.Cu")
		(net "PWRGD_PVPP_HBM_CPU0")
	)
	(segment
		(start 108.51388 -110.454948)
		(end 110.39094 -112.332008)
		(width 0.127)
		(layer "In15.Cu")
		(net "PWRGD_PVPP_HBM_CPU0")
	)
	(segment
		(start 169.930318 -118.56847)
		(end 170.1546 -118.344188)
		(width 0.127)
		(layer "In15.Cu")
		(net "PWRGD_PVPP_HBM_CPU0")
	)
	(segment
		(start 170.955716 -114.575336)
		(end 170.555666 -114.975386)
		(width 0.12954)
		(layer "F.Cu")
		(net "PWRGD_PVNN_PCH_AUX")
	)
	(via
		(at 170.555666 -114.975386)
		(size 0.4572)
		(drill 0.254)
		(layers "F.Cu" "B.Cu")
		(net "PWRGD_PVNN_PCH_AUX")
	)
	(via
		(at 244.49278 -71.834248)
		(size 0.508)
		(drill 0.254)
		(layers "F.Cu" "B.Cu")
		(net "PWRGD_PVNN_PCH_AUX")
	)
	(segment
		(start 251.95784 -69.614288)
		(end 251.95784 -70.190868)
		(width 0.12954)
		(layer "B.Cu")
		(net "PWRGD_PVNN_PCH_AUX")
	)
	(segment
		(start 251.5743 -69.230748)
		(end 251.95784 -69.614288)
		(width 0.12954)
		(layer "B.Cu")
		(net "PWRGD_PVNN_PCH_AUX")
	)
	(segment
		(start 244.49278 -71.834248)
		(end 245.34876 -70.978268)
		(width 0.12954)
		(layer "B.Cu")
		(net "PWRGD_PVNN_PCH_AUX")
	)
	(segment
		(start 245.34876 -69.720968)
		(end 245.83898 -69.230748)
		(width 0.12954)
		(layer "B.Cu")
		(net "PWRGD_PVNN_PCH_AUX")
	)
	(segment
		(start 245.34876 -70.978268)
		(end 245.34876 -69.720968)
		(width 0.12954)
		(layer "B.Cu")
		(net "PWRGD_PVNN_PCH_AUX")
	)
	(segment
		(start 256.271268 -74.504296)
		(end 256.271268 -74.92873)
		(width 0.12954)
		(layer "B.Cu")
		(net "PWRGD_PVNN_PCH_AUX")
	)
	(segment
		(start 245.83898 -69.230748)
		(end 251.5743 -69.230748)
		(width 0.12954)
		(layer "B.Cu")
		(net "PWRGD_PVNN_PCH_AUX")
	)
	(segment
		(start 251.95784 -70.190868)
		(end 256.271268 -74.504296)
		(width 0.12954)
		(layer "B.Cu")
		(net "PWRGD_PVNN_PCH_AUX")
	)
	(segment
		(start 165.1 -103.495348)
		(end 165.1 -101.851968)
		(width 0.127)
		(layer "In13.Cu")
		(net "PWRGD_PVNN_PCH_AUX")
	)
	(segment
		(start 180.708554 -82.649568)
		(end 221.56166 -82.649568)
		(width 0.127)
		(layer "In13.Cu")
		(net "PWRGD_PVNN_PCH_AUX")
	)
	(segment
		(start 166.708074 -98.592894)
		(end 166.708074 -89.182702)
		(width 0.127)
		(layer "In13.Cu")
		(net "PWRGD_PVNN_PCH_AUX")
	)
	(segment
		(start 242.80622 -73.520808)
		(end 244.49278 -71.834248)
		(width 0.127)
		(layer "In13.Cu")
		(net "PWRGD_PVNN_PCH_AUX")
	)
	(segment
		(start 165.89248 -104.287828)
		(end 165.1 -103.495348)
		(width 0.127)
		(layer "In13.Cu")
		(net "PWRGD_PVNN_PCH_AUX")
	)
	(segment
		(start 170.555666 -114.975386)
		(end 170.555666 -114.686334)
		(width 0.127)
		(layer "In13.Cu")
		(net "PWRGD_PVNN_PCH_AUX")
	)
	(segment
		(start 165.735 -101.216968)
		(end 165.735 -99.565968)
		(width 0.127)
		(layer "In13.Cu")
		(net "PWRGD_PVNN_PCH_AUX")
	)
	(segment
		(start 221.56166 -82.649568)
		(end 230.69042 -73.520808)
		(width 0.127)
		(layer "In13.Cu")
		(net "PWRGD_PVNN_PCH_AUX")
	)
	(segment
		(start 165.1 -101.851968)
		(end 165.735 -101.216968)
		(width 0.127)
		(layer "In13.Cu")
		(net "PWRGD_PVNN_PCH_AUX")
	)
	(segment
		(start 165.89248 -110.023148)
		(end 165.89248 -104.287828)
		(width 0.127)
		(layer "In13.Cu")
		(net "PWRGD_PVNN_PCH_AUX")
	)
	(segment
		(start 230.69042 -73.520808)
		(end 242.80622 -73.520808)
		(width 0.127)
		(layer "In13.Cu")
		(net "PWRGD_PVNN_PCH_AUX")
	)
	(segment
		(start 168.30167 -87.589106)
		(end 175.769016 -87.589106)
		(width 0.127)
		(layer "In13.Cu")
		(net "PWRGD_PVNN_PCH_AUX")
	)
	(segment
		(start 165.735 -99.565968)
		(end 166.708074 -98.592894)
		(width 0.127)
		(layer "In13.Cu")
		(net "PWRGD_PVNN_PCH_AUX")
	)
	(segment
		(start 166.708074 -89.182702)
		(end 168.30167 -87.589106)
		(width 0.127)
		(layer "In13.Cu")
		(net "PWRGD_PVNN_PCH_AUX")
	)
	(segment
		(start 175.769016 -87.589106)
		(end 180.708554 -82.649568)
		(width 0.127)
		(layer "In13.Cu")
		(net "PWRGD_PVNN_PCH_AUX")
	)
	(segment
		(start 170.555666 -114.686334)
		(end 165.89248 -110.023148)
		(width 0.127)
		(layer "In13.Cu")
		(net "PWRGD_PVNN_PCH_AUX")
	)
	(segment
		(start 24.7904 -178.32959)
		(end 24.790654 -179.135786)
		(width 0.12954)
		(layer "F.Cu")
		(net "PWRGD_PVNN_MAIN_CPU1_R")
	)
	(segment
		(start 26.01468 -177.104548)
		(end 24.7904 -178.32959)
		(width 0.12954)
		(layer "F.Cu")
		(net "PWRGD_PVNN_MAIN_CPU1_R")
	)
	(segment
		(start 24.498046 -179.428394)
		(end 23.954994 -179.428394)
		(width 0.12954)
		(layer "F.Cu")
		(net "PWRGD_PVNN_MAIN_CPU1_R")
	)
	(segment
		(start 24.790654 -179.135786)
		(end 24.498046 -179.428394)
		(width 0.12954)
		(layer "F.Cu")
		(net "PWRGD_PVNN_MAIN_CPU1_R")
	)
	(via
		(at 25.784048 -178.546506)
		(size 0.6604)
		(drill 0.3302)
		(layers "F.Cu" "B.Cu")
		(net "PWRGD_PVNN_MAIN_CPU1_R")
	)
	(via
		(at 26.01468 -177.104548)
		(size 0.508)
		(drill 0.254)
		(layers "F.Cu" "B.Cu")
		(net "PWRGD_PVNN_MAIN_CPU1_R")
	)
	(segment
		(start 25.34539 -176.293018)
		(end 25.277064 -176.224692)
		(width 0.12954)
		(layer "B.Cu")
		(net "PWRGD_PVNN_MAIN_CPU1_R")
	)
	(segment
		(start 25.271984 -176.219612)
		(end 25.277064 -176.224692)
		(width 0.12954)
		(layer "B.Cu")
		(net "PWRGD_PVNN_MAIN_CPU1_R")
	)
	(segment
		(start 26.01468 -177.104548)
		(end 26.01468 -178.315874)
		(width 0.12954)
		(layer "B.Cu")
		(net "PWRGD_PVNN_MAIN_CPU1_R")
	)
	(segment
		(start 26.01468 -178.315874)
		(end 25.784048 -178.546506)
		(width 0.12954)
		(layer "B.Cu")
		(net "PWRGD_PVNN_MAIN_CPU1_R")
	)
	(segment
		(start 25.34539 -178.107848)
		(end 25.34539 -176.293018)
		(width 0.12954)
		(layer "B.Cu")
		(net "PWRGD_PVNN_MAIN_CPU1_R")
	)
	(segment
		(start 25.784048 -178.546506)
		(end 25.34539 -178.107848)
		(width 0.12954)
		(layer "B.Cu")
		(net "PWRGD_PVNN_MAIN_CPU1_R")
	)
	(segment
		(start 24.352504 -176.219612)
		(end 25.271984 -176.219612)
		(width 0.12954)
		(layer "B.Cu")
		(net "PWRGD_PVNN_MAIN_CPU1_R")
	)
	(segment
		(start 171.755562 -114.575336)
		(end 171.355512 -114.975386)
		(width 0.12954)
		(layer "F.Cu")
		(net "PWRGD_PVNN_MAIN_CPU1")
	)
	(segment
		(start 110.133384 -99.355402)
		(end 109.879384 -99.609402)
		(width 0.12954)
		(layer "F.Cu")
		(net "PWRGD_PVNN_MAIN_CPU1")
	)
	(segment
		(start 109.879384 -99.609402)
		(end 108.925106 -99.609402)
		(width 0.12954)
		(layer "F.Cu")
		(net "PWRGD_PVNN_MAIN_CPU1")
	)
	(via
		(at 171.355512 -114.975386)
		(size 0.4572)
		(drill 0.254)
		(layers "F.Cu" "B.Cu")
		(net "PWRGD_PVNN_MAIN_CPU1")
	)
	(via
		(at 20.64639 -175.210216)
		(size 0.508)
		(drill 0.254)
		(layers "F.Cu" "B.Cu")
		(net "PWRGD_PVNN_MAIN_CPU1")
	)
	(via
		(at 110.133384 -99.355402)
		(size 0.508)
		(drill 0.254)
		(layers "F.Cu" "B.Cu")
		(net "PWRGD_PVNN_MAIN_CPU1")
	)
	(via
		(at 109.61878 -110.620048)
		(size 0.508)
		(drill 0.254)
		(layers "F.Cu" "B.Cu")
		(net "PWRGD_PVNN_MAIN_CPU1")
	)
	(via
		(at 106.30408 -120.284748)
		(size 0.508)
		(drill 0.254)
		(layers "F.Cu" "B.Cu")
		(net "PWRGD_PVNN_MAIN_CPU1")
	)
	(segment
		(start 24.331422 -175.419512)
		(end 24.352504 -175.419512)
		(width 0.12954)
		(layer "B.Cu")
		(net "PWRGD_PVNN_MAIN_CPU1")
	)
	(segment
		(start 21.881592 -175.853852)
		(end 21.237956 -175.210216)
		(width 0.12954)
		(layer "B.Cu")
		(net "PWRGD_PVNN_MAIN_CPU1")
	)
	(segment
		(start 22.960584 -175.853852)
		(end 22.960584 -175.685196)
		(width 0.12954)
		(layer "B.Cu")
		(net "PWRGD_PVNN_MAIN_CPU1")
	)
	(segment
		(start 21.237956 -175.210216)
		(end 20.64639 -175.210216)
		(width 0.12954)
		(layer "B.Cu")
		(net "PWRGD_PVNN_MAIN_CPU1")
	)
	(segment
		(start 23.966678 -175.054768)
		(end 24.331422 -175.419512)
		(width 0.12954)
		(layer "B.Cu")
		(net "PWRGD_PVNN_MAIN_CPU1")
	)
	(segment
		(start 23.591012 -175.054768)
		(end 23.966678 -175.054768)
		(width 0.12954)
		(layer "B.Cu")
		(net "PWRGD_PVNN_MAIN_CPU1")
	)
	(segment
		(start 22.960584 -175.685196)
		(end 23.591012 -175.054768)
		(width 0.12954)
		(layer "B.Cu")
		(net "PWRGD_PVNN_MAIN_CPU1")
	)
	(segment
		(start 22.960584 -175.853852)
		(end 21.881592 -175.853852)
		(width 0.12954)
		(layer "B.Cu")
		(net "PWRGD_PVNN_MAIN_CPU1")
	)
	(segment
		(start 110.133384 -99.355402)
		(end 110.29188 -99.513898)
		(width 0.127)
		(layer "In2.Cu")
		(net "PWRGD_PVNN_MAIN_CPU1")
	)
	(segment
		(start 109.61878 -119.060468)
		(end 108.3945 -120.284748)
		(width 0.127)
		(layer "In2.Cu")
		(net "PWRGD_PVNN_MAIN_CPU1")
	)
	(segment
		(start 109.61878 -110.620048)
		(end 109.61878 -119.060468)
		(width 0.127)
		(layer "In2.Cu")
		(net "PWRGD_PVNN_MAIN_CPU1")
	)
	(segment
		(start 110.29188 -99.513898)
		(end 110.29188 -109.946948)
		(width 0.127)
		(layer "In2.Cu")
		(net "PWRGD_PVNN_MAIN_CPU1")
	)
	(segment
		(start 110.29188 -109.946948)
		(end 109.61878 -110.620048)
		(width 0.127)
		(layer "In2.Cu")
		(net "PWRGD_PVNN_MAIN_CPU1")
	)
	(segment
		(start 108.3945 -120.284748)
		(end 106.30408 -120.284748)
		(width 0.127)
		(layer "In2.Cu")
		(net "PWRGD_PVNN_MAIN_CPU1")
	)
	(segment
		(start 20.5613 -135.242808)
		(end 36.11626 -150.797768)
		(width 0.127)
		(layer "In13.Cu")
		(net "PWRGD_PVNN_MAIN_CPU1")
	)
	(segment
		(start 34.7472 -158.64332)
		(end 34.7472 -169.024808)
		(width 0.127)
		(layer "In13.Cu")
		(net "PWRGD_PVNN_MAIN_CPU1")
	)
	(segment
		(start 36.11626 -157.27426)
		(end 34.7472 -158.64332)
		(width 0.127)
		(layer "In13.Cu")
		(net "PWRGD_PVNN_MAIN_CPU1")
	)
	(segment
		(start 34.7472 -169.024808)
		(end 32.27578 -171.496228)
		(width 0.127)
		(layer "In13.Cu")
		(net "PWRGD_PVNN_MAIN_CPU1")
	)
	(segment
		(start 47.99076 -120.330468)
		(end 25.307544 -120.330468)
		(width 0.127)
		(layer "In13.Cu")
		(net "PWRGD_PVNN_MAIN_CPU1")
	)
	(segment
		(start 106.30408 -120.284748)
		(end 105.6132 -120.284748)
		(width 0.127)
		(layer "In13.Cu")
		(net "PWRGD_PVNN_MAIN_CPU1")
	)
	(segment
		(start 105.6132 -120.284748)
		(end 104.57688 -121.321068)
		(width 0.127)
		(layer "In13.Cu")
		(net "PWRGD_PVNN_MAIN_CPU1")
	)
	(segment
		(start 22.34311 -171.496228)
		(end 20.64639 -173.192948)
		(width 0.127)
		(layer "In13.Cu")
		(net "PWRGD_PVNN_MAIN_CPU1")
	)
	(segment
		(start 104.57688 -121.321068)
		(end 48.98136 -121.321068)
		(width 0.127)
		(layer "In13.Cu")
		(net "PWRGD_PVNN_MAIN_CPU1")
	)
	(segment
		(start 32.27578 -171.496228)
		(end 22.34311 -171.496228)
		(width 0.127)
		(layer "In13.Cu")
		(net "PWRGD_PVNN_MAIN_CPU1")
	)
	(segment
		(start 25.307544 -120.330468)
		(end 20.5613 -125.076712)
		(width 0.127)
		(layer "In13.Cu")
		(net "PWRGD_PVNN_MAIN_CPU1")
	)
	(segment
		(start 20.5613 -125.076712)
		(end 20.5613 -135.242808)
		(width 0.127)
		(layer "In13.Cu")
		(net "PWRGD_PVNN_MAIN_CPU1")
	)
	(segment
		(start 20.64639 -173.192948)
		(end 20.64639 -175.210216)
		(width 0.127)
		(layer "In13.Cu")
		(net "PWRGD_PVNN_MAIN_CPU1")
	)
	(segment
		(start 36.11626 -150.797768)
		(end 36.11626 -157.27426)
		(width 0.127)
		(layer "In13.Cu")
		(net "PWRGD_PVNN_MAIN_CPU1")
	)
	(segment
		(start 48.98136 -121.321068)
		(end 47.99076 -120.330468)
		(width 0.127)
		(layer "In13.Cu")
		(net "PWRGD_PVNN_MAIN_CPU1")
	)
	(segment
		(start 150.16734 -116.895626)
		(end 152.489408 -119.217694)
		(width 0.127)
		(layer "In15.Cu")
		(net "PWRGD_PVNN_MAIN_CPU1")
	)
	(segment
		(start 131.46278 -110.69066)
		(end 140.171932 -110.69066)
		(width 0.127)
		(layer "In15.Cu")
		(net "PWRGD_PVNN_MAIN_CPU1")
	)
	(segment
		(start 109.61878 -110.620048)
		(end 110.88624 -111.887508)
		(width 0.127)
		(layer "In15.Cu")
		(net "PWRGD_PVNN_MAIN_CPU1")
	)
	(segment
		(start 110.88624 -111.887508)
		(end 130.265932 -111.887508)
		(width 0.127)
		(layer "In15.Cu")
		(net "PWRGD_PVNN_MAIN_CPU1")
	)
	(segment
		(start 150.16734 -115.65128)
		(end 150.16734 -116.895626)
		(width 0.127)
		(layer "In15.Cu")
		(net "PWRGD_PVNN_MAIN_CPU1")
	)
	(segment
		(start 170.37558 -115.374928)
		(end 170.95597 -115.374928)
		(width 0.127)
		(layer "In15.Cu")
		(net "PWRGD_PVNN_MAIN_CPU1")
	)
	(segment
		(start 170.95597 -115.374928)
		(end 171.355512 -114.975386)
		(width 0.127)
		(layer "In15.Cu")
		(net "PWRGD_PVNN_MAIN_CPU1")
	)
	(segment
		(start 130.265932 -111.887508)
		(end 131.46278 -110.69066)
		(width 0.127)
		(layer "In15.Cu")
		(net "PWRGD_PVNN_MAIN_CPU1")
	)
	(segment
		(start 158.20644 -122.682)
		(end 158.793688 -123.269248)
		(width 0.127)
		(layer "In15.Cu")
		(net "PWRGD_PVNN_MAIN_CPU1")
	)
	(segment
		(start 146.2024 -111.68634)
		(end 150.16734 -115.65128)
		(width 0.127)
		(layer "In15.Cu")
		(net "PWRGD_PVNN_MAIN_CPU1")
	)
	(segment
		(start 163.74364 -123.269248)
		(end 169.23258 -117.780308)
		(width 0.127)
		(layer "In15.Cu")
		(net "PWRGD_PVNN_MAIN_CPU1")
	)
	(segment
		(start 152.81148 -119.217694)
		(end 156.275786 -122.682)
		(width 0.127)
		(layer "In15.Cu")
		(net "PWRGD_PVNN_MAIN_CPU1")
	)
	(segment
		(start 156.275786 -122.682)
		(end 158.20644 -122.682)
		(width 0.127)
		(layer "In15.Cu")
		(net "PWRGD_PVNN_MAIN_CPU1")
	)
	(segment
		(start 158.793688 -123.269248)
		(end 163.74364 -123.269248)
		(width 0.127)
		(layer "In15.Cu")
		(net "PWRGD_PVNN_MAIN_CPU1")
	)
	(segment
		(start 152.489408 -119.217694)
		(end 152.81148 -119.217694)
		(width 0.127)
		(layer "In15.Cu")
		(net "PWRGD_PVNN_MAIN_CPU1")
	)
	(segment
		(start 169.9387 -117.780308)
		(end 170.15968 -117.559328)
		(width 0.127)
		(layer "In15.Cu")
		(net "PWRGD_PVNN_MAIN_CPU1")
	)
	(segment
		(start 169.23258 -117.780308)
		(end 169.9387 -117.780308)
		(width 0.127)
		(layer "In15.Cu")
		(net "PWRGD_PVNN_MAIN_CPU1")
	)
	(segment
		(start 141.167612 -111.68634)
		(end 146.2024 -111.68634)
		(width 0.127)
		(layer "In15.Cu")
		(net "PWRGD_PVNN_MAIN_CPU1")
	)
	(segment
		(start 170.15968 -115.590828)
		(end 170.37558 -115.374928)
		(width 0.127)
		(layer "In15.Cu")
		(net "PWRGD_PVNN_MAIN_CPU1")
	)
	(segment
		(start 170.15968 -117.559328)
		(end 170.15968 -115.590828)
		(width 0.127)
		(layer "In15.Cu")
		(net "PWRGD_PVNN_MAIN_CPU1")
	)
	(segment
		(start 140.171932 -110.69066)
		(end 141.167612 -111.68634)
		(width 0.127)
		(layer "In15.Cu")
		(net "PWRGD_PVNN_MAIN_CPU1")
	)
	(segment
		(start 434.42509 -180.24983)
		(end 434.122322 -180.552598)
		(width 0.12954)
		(layer "F.Cu")
		(net "PWRGD_PVNN_MAIN_CPU0_R")
	)
	(segment
		(start 433.842922 -180.552598)
		(end 433.766722 -180.476398)
		(width 0.12954)
		(layer "F.Cu")
		(net "PWRGD_PVNN_MAIN_CPU0_R")
	)
	(segment
		(start 434.122322 -180.552598)
		(end 433.842922 -180.552598)
		(width 0.12954)
		(layer "F.Cu")
		(net "PWRGD_PVNN_MAIN_CPU0_R")
	)
	(segment
		(start 435.33568 -178.395884)
		(end 434.52288 -179.208684)
		(width 0.12954)
		(layer "F.Cu")
		(net "PWRGD_PVNN_MAIN_CPU0_R")
	)
	(segment
		(start 435.33568 -178.044348)
		(end 435.33568 -178.395884)
		(width 0.12954)
		(layer "F.Cu")
		(net "PWRGD_PVNN_MAIN_CPU0_R")
	)
	(segment
		(start 434.52288 -180.01361)
		(end 434.42509 -180.24983)
		(width 0.12954)
		(layer "F.Cu")
		(net "PWRGD_PVNN_MAIN_CPU0_R")
	)
	(segment
		(start 434.52288 -179.208684)
		(end 434.52288 -180.01361)
		(width 0.12954)
		(layer "F.Cu")
		(net "PWRGD_PVNN_MAIN_CPU0_R")
	)
	(via
		(at 435.583838 -179.34813)
		(size 0.6604)
		(drill 0.3302)
		(layers "F.Cu" "B.Cu")
		(net "PWRGD_PVNN_MAIN_CPU0_R")
	)
	(via
		(at 435.33568 -178.044348)
		(size 0.508)
		(drill 0.254)
		(layers "F.Cu" "B.Cu")
		(net "PWRGD_PVNN_MAIN_CPU0_R")
	)
	(segment
		(start 435.893718 -179.921154)
		(end 435.255924 -180.558948)
		(width 0.12954)
		(layer "B.Cu")
		(net "PWRGD_PVNN_MAIN_CPU0_R")
	)
	(segment
		(start 435.33568 -178.044348)
		(end 435.583838 -178.292506)
		(width 0.12954)
		(layer "B.Cu")
		(net "PWRGD_PVNN_MAIN_CPU0_R")
	)
	(segment
		(start 434.209444 -180.571648)
		(end 435.243224 -180.571648)
		(width 0.12954)
		(layer "B.Cu")
		(net "PWRGD_PVNN_MAIN_CPU0_R")
	)
	(segment
		(start 435.893718 -179.65801)
		(end 435.893718 -179.921154)
		(width 0.12954)
		(layer "B.Cu")
		(net "PWRGD_PVNN_MAIN_CPU0_R")
	)
	(segment
		(start 435.583838 -178.292506)
		(end 435.583838 -179.34813)
		(width 0.12954)
		(layer "B.Cu")
		(net "PWRGD_PVNN_MAIN_CPU0_R")
	)
	(segment
		(start 435.243224 -180.571648)
		(end 435.255924 -180.558948)
		(width 0.12954)
		(layer "B.Cu")
		(net "PWRGD_PVNN_MAIN_CPU0_R")
	)
	(segment
		(start 435.583838 -179.34813)
		(end 435.893718 -179.65801)
		(width 0.12954)
		(layer "B.Cu")
		(net "PWRGD_PVNN_MAIN_CPU0_R")
	)
	(segment
		(start 363.583474 -67.914012)
		(end 363.77626 -67.721226)
		(width 0.12954)
		(layer "F.Cu")
		(net "PWRGD_PVNN_MAIN_CPU0")
	)
	(segment
		(start 109.983524 -93.015562)
		(end 109.029246 -93.015562)
		(width 0.12954)
		(layer "F.Cu")
		(net "PWRGD_PVNN_MAIN_CPU0")
	)
	(segment
		(start 110.237524 -92.761562)
		(end 109.983524 -93.015562)
		(width 0.12954)
		(layer "F.Cu")
		(net "PWRGD_PVNN_MAIN_CPU0")
	)
	(segment
		(start 370.55552 -67.07124)
		(end 371.68582 -67.07124)
		(width 0.12954)
		(layer "F.Cu")
		(net "PWRGD_PVNN_MAIN_CPU0")
	)
	(segment
		(start 365.78159 -66.009012)
		(end 365.543846 -65.771268)
		(width 0.12954)
		(layer "F.Cu")
		(net "PWRGD_PVNN_MAIN_CPU0")
	)
	(segment
		(start 370.683282 -59.833764)
		(end 371.813582 -59.833764)
		(width 0.12954)
		(layer "F.Cu")
		(net "PWRGD_PVNN_MAIN_CPU0")
	)
	(segment
		(start 307.067204 -87.722964)
		(end 302.706024 -83.361784)
		(width 0.12954)
		(layer "F.Cu")
		(net "PWRGD_PVNN_MAIN_CPU0")
	)
	(segment
		(start 364.77448 -80.206088)
		(end 363.178852 -80.206088)
		(width 0.12954)
		(layer "F.Cu")
		(net "PWRGD_PVNN_MAIN_CPU0")
	)
	(segment
		(start 365.543846 -65.771268)
		(end 364.71352 -65.771268)
		(width 0.12954)
		(layer "F.Cu")
		(net "PWRGD_PVNN_MAIN_CPU0")
	)
	(segment
		(start 364.71352 -67.721226)
		(end 365.466376 -67.721226)
		(width 0.12954)
		(layer "F.Cu")
		(net "PWRGD_PVNN_MAIN_CPU0")
	)
	(segment
		(start 283.744416 -83.361784)
		(end 276.63902 -76.256388)
		(width 0.12954)
		(layer "F.Cu")
		(net "PWRGD_PVNN_MAIN_CPU0")
	)
	(segment
		(start 370.683282 -59.833764)
		(end 369.697254 -59.833764)
		(width 0.12954)
		(layer "F.Cu")
		(net "PWRGD_PVNN_MAIN_CPU0")
	)
	(segment
		(start 363.178852 -80.206088)
		(end 355.661976 -87.722964)
		(width 0.12954)
		(layer "F.Cu")
		(net "PWRGD_PVNN_MAIN_CPU0")
	)
	(segment
		(start 369.697254 -59.833764)
		(end 369.540282 -59.676792)
		(width 0.12954)
		(layer "F.Cu")
		(net "PWRGD_PVNN_MAIN_CPU0")
	)
	(segment
		(start 369.682268 -57.883806)
		(end 370.683282 -57.883806)
		(width 0.12954)
		(layer "F.Cu")
		(net "PWRGD_PVNN_MAIN_CPU0")
	)
	(segment
		(start 364.841282 -60.48375)
		(end 363.710982 -60.48375)
		(width 0.12954)
		(layer "F.Cu")
		(net "PWRGD_PVNN_MAIN_CPU0")
	)
	(segment
		(start 369.540282 -59.676792)
		(end 369.540282 -58.025792)
		(width 0.12954)
		(layer "F.Cu")
		(net "PWRGD_PVNN_MAIN_CPU0")
	)
	(segment
		(start 365.78159 -67.406012)
		(end 365.78159 -66.009012)
		(width 0.12954)
		(layer "F.Cu")
		(net "PWRGD_PVNN_MAIN_CPU0")
	)
	(segment
		(start 365.466376 -67.721226)
		(end 365.78159 -67.406012)
		(width 0.12954)
		(layer "F.Cu")
		(net "PWRGD_PVNN_MAIN_CPU0")
	)
	(segment
		(start 170.155616 -114.575336)
		(end 169.755566 -114.975386)
		(width 0.12954)
		(layer "F.Cu")
		(net "PWRGD_PVNN_MAIN_CPU0")
	)
	(segment
		(start 369.540282 -58.025792)
		(end 369.682268 -57.883806)
		(width 0.12954)
		(layer "F.Cu")
		(net "PWRGD_PVNN_MAIN_CPU0")
	)
	(segment
		(start 363.77626 -67.721226)
		(end 364.71352 -67.721226)
		(width 0.12954)
		(layer "F.Cu")
		(net "PWRGD_PVNN_MAIN_CPU0")
	)
	(segment
		(start 364.841282 -58.533792)
		(end 363.635544 -58.533792)
		(width 0.12954)
		(layer "F.Cu")
		(net "PWRGD_PVNN_MAIN_CPU0")
	)
	(segment
		(start 371.8433 -65.575688)
		(end 371.388894 -65.121282)
		(width 0.12954)
		(layer "F.Cu")
		(net "PWRGD_PVNN_MAIN_CPU0")
	)
	(segment
		(start 302.706024 -83.361784)
		(end 283.744416 -83.361784)
		(width 0.12954)
		(layer "F.Cu")
		(net "PWRGD_PVNN_MAIN_CPU0")
	)
	(segment
		(start 276.63902 -76.256388)
		(end 276.63902 -75.778868)
		(width 0.12954)
		(layer "F.Cu")
		(net "PWRGD_PVNN_MAIN_CPU0")
	)
	(segment
		(start 371.388894 -65.121282)
		(end 370.55552 -65.121282)
		(width 0.12954)
		(layer "F.Cu")
		(net "PWRGD_PVNN_MAIN_CPU0")
	)
	(segment
		(start 355.661976 -87.722964)
		(end 307.067204 -87.722964)
		(width 0.12954)
		(layer "F.Cu")
		(net "PWRGD_PVNN_MAIN_CPU0")
	)
	(via
		(at 363.710982 -60.48375)
		(size 0.508)
		(drill 0.254)
		(layers "F.Cu" "B.Cu")
		(net "PWRGD_PVNN_MAIN_CPU0")
	)
	(via
		(at 377.27128 -66.131948)
		(size 0.508)
		(drill 0.254)
		(layers "F.Cu" "B.Cu")
		(net "PWRGD_PVNN_MAIN_CPU0")
	)
	(via
		(at 363.583474 -67.914012)
		(size 0.508)
		(drill 0.254)
		(layers "F.Cu" "B.Cu")
		(net "PWRGD_PVNN_MAIN_CPU0")
	)
	(via
		(at 431.29708 -178.552348)
		(size 0.508)
		(drill 0.254)
		(layers "F.Cu" "B.Cu")
		(net "PWRGD_PVNN_MAIN_CPU0")
	)
	(via
		(at 111.18088 -110.581948)
		(size 0.508)
		(drill 0.254)
		(layers "F.Cu" "B.Cu")
		(net "PWRGD_PVNN_MAIN_CPU0")
	)
	(via
		(at 364.77448 -80.206088)
		(size 0.508)
		(drill 0.254)
		(layers "F.Cu" "B.Cu")
		(net "PWRGD_PVNN_MAIN_CPU0")
	)
	(via
		(at 110.237524 -92.761562)
		(size 0.508)
		(drill 0.254)
		(layers "F.Cu" "B.Cu")
		(net "PWRGD_PVNN_MAIN_CPU0")
	)
	(via
		(at 276.63902 -75.778868)
		(size 0.508)
		(drill 0.254)
		(layers "F.Cu" "B.Cu")
		(net "PWRGD_PVNN_MAIN_CPU0")
	)
	(via
		(at 363.635544 -58.533792)
		(size 0.508)
		(drill 0.254)
		(layers "F.Cu" "B.Cu")
		(net "PWRGD_PVNN_MAIN_CPU0")
	)
	(via
		(at 371.68582 -67.07124)
		(size 0.508)
		(drill 0.254)
		(layers "F.Cu" "B.Cu")
		(net "PWRGD_PVNN_MAIN_CPU0")
	)
	(via
		(at 371.8433 -65.575688)
		(size 0.508)
		(drill 0.254)
		(layers "F.Cu" "B.Cu")
		(net "PWRGD_PVNN_MAIN_CPU0")
	)
	(via
		(at 371.813582 -59.833764)
		(size 0.508)
		(drill 0.254)
		(layers "F.Cu" "B.Cu")
		(net "PWRGD_PVNN_MAIN_CPU0")
	)
	(via
		(at 373.367554 -109.029754)
		(size 0.508)
		(drill 0.254)
		(layers "F.Cu" "B.Cu")
		(net "PWRGD_PVNN_MAIN_CPU0")
	)
	(via
		(at 169.755566 -114.975386)
		(size 0.4572)
		(drill 0.254)
		(layers "F.Cu" "B.Cu")
		(net "PWRGD_PVNN_MAIN_CPU0")
	)
	(segment
		(start 431.154078 -179.75453)
		(end 431.419762 -179.75453)
		(width 0.12954)
		(layer "B.Cu")
		(net "PWRGD_PVNN_MAIN_CPU0")
	)
	(segment
		(start 371.30736 -65.039748)
		(end 370.54028 -65.039748)
		(width 0.12954)
		(layer "B.Cu")
		(net "PWRGD_PVNN_MAIN_CPU0")
	)
	(segment
		(start 431.419762 -179.75453)
		(end 431.860452 -180.19522)
		(width 0.12954)
		(layer "B.Cu")
		(net "PWRGD_PVNN_MAIN_CPU0")
	)
	(segment
		(start 433.297584 -180.878734)
		(end 433.767484 -181.348634)
		(width 0.12954)
		(layer "B.Cu")
		(net "PWRGD_PVNN_MAIN_CPU0")
	)
	(segment
		(start 430.73828 -179.338732)
		(end 431.154078 -179.75453)
		(width 0.12954)
		(layer "B.Cu")
		(net "PWRGD_PVNN_MAIN_CPU0")
	)
	(segment
		(start 430.73828 -179.111148)
		(end 430.73828 -179.338732)
		(width 0.12954)
		(layer "B.Cu")
		(net "PWRGD_PVNN_MAIN_CPU0")
	)
	(segment
		(start 433.767484 -181.348634)
		(end 434.18633 -181.348634)
		(width 0.12954)
		(layer "B.Cu")
		(net "PWRGD_PVNN_MAIN_CPU0")
	)
	(segment
		(start 431.29708 -178.552348)
		(end 430.73828 -179.111148)
		(width 0.12954)
		(layer "B.Cu")
		(net "PWRGD_PVNN_MAIN_CPU0")
	)
	(segment
		(start 431.860452 -180.19522)
		(end 433.274216 -180.19522)
		(width 0.12954)
		(layer "B.Cu")
		(net "PWRGD_PVNN_MAIN_CPU0")
	)
	(segment
		(start 433.274216 -180.19522)
		(end 433.297584 -180.218588)
		(width 0.12954)
		(layer "B.Cu")
		(net "PWRGD_PVNN_MAIN_CPU0")
	)
	(segment
		(start 370.54028 -65.039748)
		(end 367.666016 -67.914012)
		(width 0.12954)
		(layer "B.Cu")
		(net "PWRGD_PVNN_MAIN_CPU0")
	)
	(segment
		(start 371.8433 -65.575688)
		(end 371.30736 -65.039748)
		(width 0.12954)
		(layer "B.Cu")
		(net "PWRGD_PVNN_MAIN_CPU0")
	)
	(segment
		(start 367.666016 -67.914012)
		(end 363.583474 -67.914012)
		(width 0.12954)
		(layer "B.Cu")
		(net "PWRGD_PVNN_MAIN_CPU0")
	)
	(segment
		(start 434.18633 -181.348634)
		(end 434.209444 -181.371748)
		(width 0.12954)
		(layer "B.Cu")
		(net "PWRGD_PVNN_MAIN_CPU0")
	)
	(segment
		(start 433.297584 -180.218588)
		(end 433.297584 -180.878734)
		(width 0.12954)
		(layer "B.Cu")
		(net "PWRGD_PVNN_MAIN_CPU0")
	)
	(segment
		(start 370.92128 -64.653668)
		(end 370.92128 -60.726066)
		(width 0.127)
		(layer "In2.Cu")
		(net "PWRGD_PVNN_MAIN_CPU0")
	)
	(segment
		(start 363.710982 -60.48375)
		(end 363.635544 -60.408312)
		(width 0.127)
		(layer "In2.Cu")
		(net "PWRGD_PVNN_MAIN_CPU0")
	)
	(segment
		(start 363.635544 -60.408312)
		(end 363.635544 -58.533792)
		(width 0.127)
		(layer "In2.Cu")
		(net "PWRGD_PVNN_MAIN_CPU0")
	)
	(segment
		(start 365.61268 -69.943218)
		(end 363.583474 -67.914012)
		(width 0.127)
		(layer "In2.Cu")
		(net "PWRGD_PVNN_MAIN_CPU0")
	)
	(segment
		(start 371.8433 -65.575688)
		(end 370.92128 -64.653668)
		(width 0.127)
		(layer "In2.Cu")
		(net "PWRGD_PVNN_MAIN_CPU0")
	)
	(segment
		(start 372.88724 -72.809608)
		(end 377.27128 -68.425568)
		(width 0.127)
		(layer "In2.Cu")
		(net "PWRGD_PVNN_MAIN_CPU0")
	)
	(segment
		(start 376.779536 -107.666028)
		(end 378.81052 -105.635044)
		(width 0.127)
		(layer "In2.Cu")
		(net "PWRGD_PVNN_MAIN_CPU0")
	)
	(segment
		(start 370.92128 -60.726066)
		(end 371.813582 -59.833764)
		(width 0.127)
		(layer "In2.Cu")
		(net "PWRGD_PVNN_MAIN_CPU0")
	)
	(segment
		(start 362.69168 -61.503052)
		(end 363.710982 -60.48375)
		(width 0.127)
		(layer "In2.Cu")
		(net "PWRGD_PVNN_MAIN_CPU0")
	)
	(segment
		(start 363.583474 -67.914012)
		(end 363.102144 -67.914012)
		(width 0.127)
		(layer "In2.Cu")
		(net "PWRGD_PVNN_MAIN_CPU0")
	)
	(segment
		(start 379.162564 -103.844852)
		(end 379.162564 -102.351332)
		(width 0.127)
		(layer "In2.Cu")
		(net "PWRGD_PVNN_MAIN_CPU0")
	)
	(segment
		(start 379.162564 -102.351332)
		(end 378.81052 -101.999288)
		(width 0.127)
		(layer "In2.Cu")
		(net "PWRGD_PVNN_MAIN_CPU0")
	)
	(segment
		(start 365.61268 -79.568548)
		(end 365.61268 -69.943218)
		(width 0.127)
		(layer "In2.Cu")
		(net "PWRGD_PVNN_MAIN_CPU0")
	)
	(segment
		(start 374.329706 -109.029754)
		(end 375.693432 -107.666028)
		(width 0.127)
		(layer "In2.Cu")
		(net "PWRGD_PVNN_MAIN_CPU0")
	)
	(segment
		(start 110.72368 -110.124748)
		(end 110.72368 -93.247718)
		(width 0.127)
		(layer "In2.Cu")
		(net "PWRGD_PVNN_MAIN_CPU0")
	)
	(segment
		(start 371.68582 -65.733168)
		(end 371.8433 -65.575688)
		(width 0.127)
		(layer "In2.Cu")
		(net "PWRGD_PVNN_MAIN_CPU0")
	)
	(segment
		(start 371.68582 -67.07124)
		(end 371.68582 -65.733168)
		(width 0.127)
		(layer "In2.Cu")
		(net "PWRGD_PVNN_MAIN_CPU0")
	)
	(segment
		(start 111.18088 -110.581948)
		(end 110.72368 -110.124748)
		(width 0.127)
		(layer "In2.Cu")
		(net "PWRGD_PVNN_MAIN_CPU0")
	)
	(segment
		(start 373.367554 -109.029754)
		(end 374.329706 -109.029754)
		(width 0.127)
		(layer "In2.Cu")
		(net "PWRGD_PVNN_MAIN_CPU0")
	)
	(segment
		(start 378.81052 -104.196896)
		(end 379.162564 -103.844852)
		(width 0.127)
		(layer "In2.Cu")
		(net "PWRGD_PVNN_MAIN_CPU0")
	)
	(segment
		(start 363.102144 -67.914012)
		(end 362.69168 -67.503548)
		(width 0.127)
		(layer "In2.Cu")
		(net "PWRGD_PVNN_MAIN_CPU0")
	)
	(segment
		(start 378.81052 -92.103448)
		(end 372.88724 -86.180168)
		(width 0.127)
		(layer "In2.Cu")
		(net "PWRGD_PVNN_MAIN_CPU0")
	)
	(segment
		(start 372.88724 -86.180168)
		(end 372.88724 -72.809608)
		(width 0.127)
		(layer "In2.Cu")
		(net "PWRGD_PVNN_MAIN_CPU0")
	)
	(segment
		(start 362.69168 -67.503548)
		(end 362.69168 -61.503052)
		(width 0.127)
		(layer "In2.Cu")
		(net "PWRGD_PVNN_MAIN_CPU0")
	)
	(segment
		(start 364.97514 -80.206088)
		(end 365.61268 -79.568548)
		(width 0.127)
		(layer "In2.Cu")
		(net "PWRGD_PVNN_MAIN_CPU0")
	)
	(segment
		(start 378.81052 -101.999288)
		(end 378.81052 -92.103448)
		(width 0.127)
		(layer "In2.Cu")
		(net "PWRGD_PVNN_MAIN_CPU0")
	)
	(segment
		(start 378.81052 -105.635044)
		(end 378.81052 -104.196896)
		(width 0.127)
		(layer "In2.Cu")
		(net "PWRGD_PVNN_MAIN_CPU0")
	)
	(segment
		(start 110.72368 -93.247718)
		(end 110.237524 -92.761562)
		(width 0.127)
		(layer "In2.Cu")
		(net "PWRGD_PVNN_MAIN_CPU0")
	)
	(segment
		(start 377.27128 -68.425568)
		(end 377.27128 -66.131948)
		(width 0.127)
		(layer "In2.Cu")
		(net "PWRGD_PVNN_MAIN_CPU0")
	)
	(segment
		(start 375.693432 -107.666028)
		(end 376.779536 -107.666028)
		(width 0.127)
		(layer "In2.Cu")
		(net "PWRGD_PVNN_MAIN_CPU0")
	)
	(segment
		(start 364.77448 -80.206088)
		(end 364.97514 -80.206088)
		(width 0.127)
		(layer "In2.Cu")
		(net "PWRGD_PVNN_MAIN_CPU0")
	)
	(segment
		(start 380.02718 -109.906308)
		(end 381.14732 -108.786168)
		(width 0.127)
		(layer "In4.Cu")
		(net "PWRGD_PVNN_MAIN_CPU0")
	)
	(segment
		(start 412.60014 -114.58702)
		(end 438.299352 -114.58702)
		(width 0.127)
		(layer "In4.Cu")
		(net "PWRGD_PVNN_MAIN_CPU0")
	)
	(segment
		(start 431.0126 -176.032668)
		(end 431.0126 -178.267868)
		(width 0.127)
		(layer "In4.Cu")
		(net "PWRGD_PVNN_MAIN_CPU0")
	)
	(segment
		(start 373.367554 -109.029754)
		(end 374.870726 -109.029754)
		(width 0.127)
		(layer "In4.Cu")
		(net "PWRGD_PVNN_MAIN_CPU0")
	)
	(segment
		(start 439.3946 -160.365948)
		(end 439.3946 -167.650668)
		(width 0.127)
		(layer "In4.Cu")
		(net "PWRGD_PVNN_MAIN_CPU0")
	)
	(segment
		(start 435.2798 -133.911848)
		(end 435.2798 -156.251148)
		(width 0.127)
		(layer "In4.Cu")
		(net "PWRGD_PVNN_MAIN_CPU0")
	)
	(segment
		(start 443.2808 -125.910848)
		(end 435.2798 -133.911848)
		(width 0.127)
		(layer "In4.Cu")
		(net "PWRGD_PVNN_MAIN_CPU0")
	)
	(segment
		(start 375.74728 -109.906308)
		(end 380.02718 -109.906308)
		(width 0.127)
		(layer "In4.Cu")
		(net "PWRGD_PVNN_MAIN_CPU0")
	)
	(segment
		(start 381.14732 -108.786168)
		(end 406.799288 -108.786168)
		(width 0.127)
		(layer "In4.Cu")
		(net "PWRGD_PVNN_MAIN_CPU0")
	)
	(segment
		(start 435.2798 -156.251148)
		(end 439.3946 -160.365948)
		(width 0.127)
		(layer "In4.Cu")
		(net "PWRGD_PVNN_MAIN_CPU0")
	)
	(segment
		(start 443.2808 -119.568468)
		(end 443.2808 -125.910848)
		(width 0.127)
		(layer "In4.Cu")
		(net "PWRGD_PVNN_MAIN_CPU0")
	)
	(segment
		(start 438.299352 -114.58702)
		(end 443.2808 -119.568468)
		(width 0.127)
		(layer "In4.Cu")
		(net "PWRGD_PVNN_MAIN_CPU0")
	)
	(segment
		(start 431.0126 -178.267868)
		(end 431.29708 -178.552348)
		(width 0.127)
		(layer "In4.Cu")
		(net "PWRGD_PVNN_MAIN_CPU0")
	)
	(segment
		(start 439.3946 -167.650668)
		(end 431.0126 -176.032668)
		(width 0.127)
		(layer "In4.Cu")
		(net "PWRGD_PVNN_MAIN_CPU0")
	)
	(segment
		(start 374.870726 -109.029754)
		(end 375.74728 -109.906308)
		(width 0.127)
		(layer "In4.Cu")
		(net "PWRGD_PVNN_MAIN_CPU0")
	)
	(segment
		(start 406.799288 -108.786168)
		(end 412.60014 -114.58702)
		(width 0.127)
		(layer "In4.Cu")
		(net "PWRGD_PVNN_MAIN_CPU0")
	)
	(segment
		(start 372.82628 -68.748148)
		(end 371.68582 -67.607688)
		(width 0.127)
		(layer "In6.Cu")
		(net "PWRGD_PVNN_MAIN_CPU0")
	)
	(segment
		(start 377.27128 -66.131948)
		(end 377.27128 -67.782948)
		(width 0.127)
		(layer "In6.Cu")
		(net "PWRGD_PVNN_MAIN_CPU0")
	)
	(segment
		(start 371.68582 -67.607688)
		(end 371.68582 -67.07124)
		(width 0.127)
		(layer "In6.Cu")
		(net "PWRGD_PVNN_MAIN_CPU0")
	)
	(segment
		(start 377.27128 -67.782948)
		(end 376.30608 -68.748148)
		(width 0.127)
		(layer "In6.Cu")
		(net "PWRGD_PVNN_MAIN_CPU0")
	)
	(segment
		(start 376.30608 -68.748148)
		(end 372.82628 -68.748148)
		(width 0.127)
		(layer "In6.Cu")
		(net "PWRGD_PVNN_MAIN_CPU0")
	)
	(segment
		(start 248.129552 -80.52435)
		(end 273.293332 -80.52435)
		(width 0.127)
		(layer "In13.Cu")
		(net "PWRGD_PVNN_MAIN_CPU0")
	)
	(segment
		(start 163.88842 -100.775008)
		(end 166.233094 -98.430334)
		(width 0.127)
		(layer "In13.Cu")
		(net "PWRGD_PVNN_MAIN_CPU0")
	)
	(segment
		(start 165.46068 -110.246668)
		(end 165.46068 -104.529128)
		(width 0.127)
		(layer "In13.Cu")
		(net "PWRGD_PVNN_MAIN_CPU0")
	)
	(segment
		(start 164.5666 -103.635048)
		(end 164.5666 -102.271068)
		(width 0.127)
		(layer "In13.Cu")
		(net "PWRGD_PVNN_MAIN_CPU0")
	)
	(segment
		(start 273.293332 -80.52435)
		(end 276.63902 -77.178662)
		(width 0.127)
		(layer "In13.Cu")
		(net "PWRGD_PVNN_MAIN_CPU0")
	)
	(segment
		(start 244.883686 -71.260208)
		(end 245.13286 -71.509382)
		(width 0.127)
		(layer "In13.Cu")
		(net "PWRGD_PVNN_MAIN_CPU0")
	)
	(segment
		(start 230.40721 -73.089008)
		(end 242.26647 -73.089008)
		(width 0.127)
		(layer "In13.Cu")
		(net "PWRGD_PVNN_MAIN_CPU0")
	)
	(segment
		(start 163.88842 -101.592888)
		(end 163.88842 -100.775008)
		(width 0.127)
		(layer "In13.Cu")
		(net "PWRGD_PVNN_MAIN_CPU0")
	)
	(segment
		(start 245.13286 -71.509382)
		(end 245.13286 -77.527658)
		(width 0.127)
		(layer "In13.Cu")
		(net "PWRGD_PVNN_MAIN_CPU0")
	)
	(segment
		(start 164.5666 -102.271068)
		(end 163.88842 -101.592888)
		(width 0.127)
		(layer "In13.Cu")
		(net "PWRGD_PVNN_MAIN_CPU0")
	)
	(segment
		(start 169.755566 -114.975386)
		(end 169.755566 -114.541554)
		(width 0.127)
		(layer "In13.Cu")
		(net "PWRGD_PVNN_MAIN_CPU0")
	)
	(segment
		(start 244.09527 -71.260208)
		(end 244.883686 -71.260208)
		(width 0.127)
		(layer "In13.Cu")
		(net "PWRGD_PVNN_MAIN_CPU0")
	)
	(segment
		(start 242.26647 -73.089008)
		(end 244.09527 -71.260208)
		(width 0.127)
		(layer "In13.Cu")
		(net "PWRGD_PVNN_MAIN_CPU0")
	)
	(segment
		(start 245.13286 -77.527658)
		(end 248.129552 -80.52435)
		(width 0.127)
		(layer "In13.Cu")
		(net "PWRGD_PVNN_MAIN_CPU0")
	)
	(segment
		(start 166.233094 -98.430334)
		(end 166.233094 -88.527128)
		(width 0.127)
		(layer "In13.Cu")
		(net "PWRGD_PVNN_MAIN_CPU0")
	)
	(segment
		(start 180.529484 -82.217768)
		(end 221.27845 -82.217768)
		(width 0.127)
		(layer "In13.Cu")
		(net "PWRGD_PVNN_MAIN_CPU0")
	)
	(segment
		(start 166.233094 -88.527128)
		(end 168.299638 -86.460584)
		(width 0.127)
		(layer "In13.Cu")
		(net "PWRGD_PVNN_MAIN_CPU0")
	)
	(segment
		(start 165.46068 -104.529128)
		(end 164.5666 -103.635048)
		(width 0.127)
		(layer "In13.Cu")
		(net "PWRGD_PVNN_MAIN_CPU0")
	)
	(segment
		(start 221.27845 -82.217768)
		(end 230.40721 -73.089008)
		(width 0.127)
		(layer "In13.Cu")
		(net "PWRGD_PVNN_MAIN_CPU0")
	)
	(segment
		(start 176.286668 -86.460584)
		(end 180.529484 -82.217768)
		(width 0.127)
		(layer "In13.Cu")
		(net "PWRGD_PVNN_MAIN_CPU0")
	)
	(segment
		(start 169.755566 -114.541554)
		(end 165.46068 -110.246668)
		(width 0.127)
		(layer "In13.Cu")
		(net "PWRGD_PVNN_MAIN_CPU0")
	)
	(segment
		(start 276.63902 -77.178662)
		(end 276.63902 -75.778868)
		(width 0.127)
		(layer "In13.Cu")
		(net "PWRGD_PVNN_MAIN_CPU0")
	)
	(segment
		(start 168.299638 -86.460584)
		(end 176.286668 -86.460584)
		(width 0.127)
		(layer "In13.Cu")
		(net "PWRGD_PVNN_MAIN_CPU0")
	)
	(segment
		(start 156.57068 -119.421148)
		(end 155.14828 -119.421148)
		(width 0.127)
		(layer "In15.Cu")
		(net "PWRGD_PVNN_MAIN_CPU0")
	)
	(segment
		(start 168.8846 -116.536216)
		(end 167.133778 -118.287038)
		(width 0.127)
		(layer "In15.Cu")
		(net "PWRGD_PVNN_MAIN_CPU0")
	)
	(segment
		(start 169.755566 -114.975386)
		(end 169.634662 -114.975386)
		(width 0.127)
		(layer "In15.Cu")
		(net "PWRGD_PVNN_MAIN_CPU0")
	)
	(segment
		(start 167.133778 -118.287038)
		(end 166.32301 -118.287038)
		(width 0.127)
		(layer "In15.Cu")
		(net "PWRGD_PVNN_MAIN_CPU0")
	)
	(segment
		(start 153.76652 -117.275356)
		(end 152.172416 -115.681252)
		(width 0.127)
		(layer "In15.Cu")
		(net "PWRGD_PVNN_MAIN_CPU0")
	)
	(segment
		(start 111.61014 -111.011208)
		(end 111.18088 -110.581948)
		(width 0.127)
		(layer "In15.Cu")
		(net "PWRGD_PVNN_MAIN_CPU0")
	)
	(segment
		(start 155.14828 -119.421148)
		(end 153.76652 -118.039388)
		(width 0.127)
		(layer "In15.Cu")
		(net "PWRGD_PVNN_MAIN_CPU0")
	)
	(segment
		(start 126.70282 -111.011208)
		(end 111.61014 -111.011208)
		(width 0.127)
		(layer "In15.Cu")
		(net "PWRGD_PVNN_MAIN_CPU0")
	)
	(segment
		(start 153.76652 -118.039388)
		(end 153.76652 -117.275356)
		(width 0.127)
		(layer "In15.Cu")
		(net "PWRGD_PVNN_MAIN_CPU0")
	)
	(segment
		(start 152.172416 -115.681252)
		(end 151.50846 -115.681252)
		(width 0.127)
		(layer "In15.Cu")
		(net "PWRGD_PVNN_MAIN_CPU0")
	)
	(segment
		(start 163.8681 -120.741948)
		(end 157.89148 -120.741948)
		(width 0.127)
		(layer "In15.Cu")
		(net "PWRGD_PVNN_MAIN_CPU0")
	)
	(segment
		(start 169.634662 -114.975386)
		(end 168.8846 -115.725448)
		(width 0.127)
		(layer "In15.Cu")
		(net "PWRGD_PVNN_MAIN_CPU0")
	)
	(segment
		(start 127.998728 -109.7153)
		(end 126.70282 -111.011208)
		(width 0.127)
		(layer "In15.Cu")
		(net "PWRGD_PVNN_MAIN_CPU0")
	)
	(segment
		(start 151.50846 -115.681252)
		(end 145.542508 -109.7153)
		(width 0.127)
		(layer "In15.Cu")
		(net "PWRGD_PVNN_MAIN_CPU0")
	)
	(segment
		(start 157.89148 -120.741948)
		(end 156.57068 -119.421148)
		(width 0.127)
		(layer "In15.Cu")
		(net "PWRGD_PVNN_MAIN_CPU0")
	)
	(segment
		(start 145.542508 -109.7153)
		(end 127.998728 -109.7153)
		(width 0.127)
		(layer "In15.Cu")
		(net "PWRGD_PVNN_MAIN_CPU0")
	)
	(segment
		(start 166.32301 -118.287038)
		(end 163.8681 -120.741948)
		(width 0.127)
		(layer "In15.Cu")
		(net "PWRGD_PVNN_MAIN_CPU0")
	)
	(segment
		(start 168.8846 -115.725448)
		(end 168.8846 -116.536216)
		(width 0.127)
		(layer "In15.Cu")
		(net "PWRGD_PVNN_MAIN_CPU0")
	)
	(segment
		(start 101.385624 -360.534712)
		(end 101.380036 -360.529124)
		(width 0.12954)
		(layer "F.Cu")
		(net "PWRGD_PVCCIN_CPU1_R")
	)
	(segment
		(start 104.66832 -360.695748)
		(end 103.570786 -360.695748)
		(width 0.12954)
		(layer "F.Cu")
		(net "PWRGD_PVCCIN_CPU1_R")
	)
	(segment
		(start 100.169218 -361.05465)
		(end 100.694744 -360.529124)
		(width 0.12954)
		(layer "F.Cu")
		(net "PWRGD_PVCCIN_CPU1_R")
	)
	(segment
		(start 105.383838 -359.848404)
		(end 104.9909 -360.241342)
		(width 0.12954)
		(layer "F.Cu")
		(net "PWRGD_PVCCIN_CPU1_R")
	)
	(segment
		(start 102.39375 -360.534712)
		(end 101.385624 -360.534712)
		(width 0.12954)
		(layer "F.Cu")
		(net "PWRGD_PVCCIN_CPU1_R")
	)
	(segment
		(start 103.40975 -360.534712)
		(end 102.39375 -360.534712)
		(width 0.12954)
		(layer "F.Cu")
		(net "PWRGD_PVCCIN_CPU1_R")
	)
	(segment
		(start 105.70337 -359.848404)
		(end 105.383838 -359.848404)
		(width 0.12954)
		(layer "F.Cu")
		(net "PWRGD_PVCCIN_CPU1_R")
	)
	(segment
		(start 104.9909 -360.241342)
		(end 104.9909 -360.373168)
		(width 0.12954)
		(layer "F.Cu")
		(net "PWRGD_PVCCIN_CPU1_R")
	)
	(segment
		(start 104.9909 -360.373168)
		(end 104.66832 -360.695748)
		(width 0.12954)
		(layer "F.Cu")
		(net "PWRGD_PVCCIN_CPU1_R")
	)
	(segment
		(start 100.694744 -360.529124)
		(end 101.380036 -360.529124)
		(width 0.12954)
		(layer "F.Cu")
		(net "PWRGD_PVCCIN_CPU1_R")
	)
	(segment
		(start 103.570786 -360.695748)
		(end 103.40975 -360.534712)
		(width 0.12954)
		(layer "F.Cu")
		(net "PWRGD_PVCCIN_CPU1_R")
	)
	(via
		(at 100.169218 -361.05465)
		(size 0.762)
		(drill 0.381)
		(layers "F.Cu" "B.Cu")
		(net "PWRGD_PVCCIN_CPU1_R")
	)
	(segment
		(start 113.99012 -368.696748)
		(end 113.895378 -368.79149)
		(width 0.12954)
		(layer "F.Cu")
		(net "PWRGD_PVCCIN_CPU1")
	)
	(segment
		(start 100.941378 -368.79149)
		(end 98.510598 -366.36071)
		(width 0.12954)
		(layer "F.Cu")
		(net "PWRGD_PVCCIN_CPU1")
	)
	(segment
		(start 98.510598 -366.36071)
		(end 98.510598 -363.67593)
		(width 0.12954)
		(layer "F.Cu")
		(net "PWRGD_PVCCIN_CPU1")
	)
	(segment
		(start 101.22281 -361.94365)
		(end 101.380036 -361.786424)
		(width 0.12954)
		(layer "F.Cu")
		(net "PWRGD_PVCCIN_CPU1")
	)
	(segment
		(start 98.510598 -363.67593)
		(end 100.242878 -361.94365)
		(width 0.12954)
		(layer "F.Cu")
		(net "PWRGD_PVCCIN_CPU1")
	)
	(segment
		(start 100.242878 -361.94365)
		(end 101.22281 -361.94365)
		(width 0.12954)
		(layer "F.Cu")
		(net "PWRGD_PVCCIN_CPU1")
	)
	(segment
		(start 101.380036 -361.786424)
		(end 101.380036 -361.329224)
		(width 0.12954)
		(layer "F.Cu")
		(net "PWRGD_PVCCIN_CPU1")
	)
	(segment
		(start 100.57384 -81.585308)
		(end 101.27488 -81.585308)
		(width 0.12954)
		(layer "F.Cu")
		(net "PWRGD_PVCCIN_CPU1")
	)
	(segment
		(start 174.955708 -118.575328)
		(end 174.555658 -118.975378)
		(width 0.12954)
		(layer "F.Cu")
		(net "PWRGD_PVCCIN_CPU1")
	)
	(segment
		(start 117.63756 -368.696748)
		(end 113.99012 -368.696748)
		(width 0.12954)
		(layer "F.Cu")
		(net "PWRGD_PVCCIN_CPU1")
	)
	(segment
		(start 113.895378 -368.79149)
		(end 100.941378 -368.79149)
		(width 0.12954)
		(layer "F.Cu")
		(net "PWRGD_PVCCIN_CPU1")
	)
	(via
		(at 173.71822 -395.620748)
		(size 0.508)
		(drill 0.254)
		(layers "F.Cu" "B.Cu")
		(net "PWRGD_PVCCIN_CPU1")
	)
	(via
		(at 168.374314 -90.790268)
		(size 0.508)
		(drill 0.254)
		(layers "F.Cu" "B.Cu")
		(net "PWRGD_PVCCIN_CPU1")
	)
	(via
		(at 118.7196 -395.4018)
		(size 0.508)
		(drill 0.254)
		(layers "F.Cu" "B.Cu")
		(net "PWRGD_PVCCIN_CPU1")
	)
	(via
		(at 174.555658 -118.975378)
		(size 0.4572)
		(drill 0.254)
		(layers "F.Cu" "B.Cu")
		(net "PWRGD_PVCCIN_CPU1")
	)
	(via
		(at 117.63756 -368.696748)
		(size 0.508)
		(drill 0.254)
		(layers "F.Cu" "B.Cu")
		(net "PWRGD_PVCCIN_CPU1")
	)
	(via
		(at 175.18888 -134.838948)
		(size 0.508)
		(drill 0.254)
		(layers "F.Cu" "B.Cu")
		(net "PWRGD_PVCCIN_CPU1")
	)
	(via
		(at 208.39938 -151.158448)
		(size 0.508)
		(drill 0.254)
		(layers "F.Cu" "B.Cu")
		(net "PWRGD_PVCCIN_CPU1")
	)
	(via
		(at 101.27488 -81.585308)
		(size 0.508)
		(drill 0.254)
		(layers "F.Cu" "B.Cu")
		(net "PWRGD_PVCCIN_CPU1")
	)
	(via
		(at 232.08488 -203.037948)
		(size 0.508)
		(drill 0.254)
		(layers "F.Cu" "B.Cu")
		(net "PWRGD_PVCCIN_CPU1")
	)
	(segment
		(start 117.430804 -394.824204)
		(end 116.935504 -394.824204)
		(width 0.127)
		(layer "In4.Cu")
		(net "PWRGD_PVCCIN_CPU1")
	)
	(segment
		(start 215.878918 -348.910656)
		(end 211.969858 -348.910656)
		(width 0.127)
		(layer "In4.Cu")
		(net "PWRGD_PVCCIN_CPU1")
	)
	(segment
		(start 232.08488 -203.037948)
		(end 229.748588 -205.37424)
		(width 0.127)
		(layer "In4.Cu")
		(net "PWRGD_PVCCIN_CPU1")
	)
	(segment
		(start 118.432326 -369.491514)
		(end 117.63756 -368.696748)
		(width 0.127)
		(layer "In4.Cu")
		(net "PWRGD_PVCCIN_CPU1")
	)
	(segment
		(start 198.625968 -370.331492)
		(end 190.146432 -378.811028)
		(width 0.127)
		(layer "In4.Cu")
		(net "PWRGD_PVCCIN_CPU1")
	)
	(segment
		(start 229.748588 -240.806986)
		(end 222.509588 -248.045986)
		(width 0.127)
		(layer "In4.Cu")
		(net "PWRGD_PVCCIN_CPU1")
	)
	(segment
		(start 190.146432 -378.811028)
		(end 183.862472 -378.811028)
		(width 0.127)
		(layer "In4.Cu")
		(net "PWRGD_PVCCIN_CPU1")
	)
	(segment
		(start 211.969858 -348.910656)
		(end 198.625968 -362.254546)
		(width 0.127)
		(layer "In4.Cu")
		(net "PWRGD_PVCCIN_CPU1")
	)
	(segment
		(start 222.509588 -342.279986)
		(end 215.878918 -348.910656)
		(width 0.127)
		(layer "In4.Cu")
		(net "PWRGD_PVCCIN_CPU1")
	)
	(segment
		(start 174.187612 -395.620748)
		(end 173.71822 -395.620748)
		(width 0.127)
		(layer "In4.Cu")
		(net "PWRGD_PVCCIN_CPU1")
	)
	(segment
		(start 222.509588 -248.045986)
		(end 222.509588 -342.279986)
		(width 0.127)
		(layer "In4.Cu")
		(net "PWRGD_PVCCIN_CPU1")
	)
	(segment
		(start 114.19332 -392.08202)
		(end 114.19332 -390.108948)
		(width 0.127)
		(layer "In4.Cu")
		(net "PWRGD_PVCCIN_CPU1")
	)
	(segment
		(start 175.243236 -394.565124)
		(end 174.187612 -395.620748)
		(width 0.127)
		(layer "In4.Cu")
		(net "PWRGD_PVCCIN_CPU1")
	)
	(segment
		(start 116.935504 -394.824204)
		(end 114.19332 -392.08202)
		(width 0.127)
		(layer "In4.Cu")
		(net "PWRGD_PVCCIN_CPU1")
	)
	(segment
		(start 183.862472 -378.811028)
		(end 175.243236 -387.430264)
		(width 0.127)
		(layer "In4.Cu")
		(net "PWRGD_PVCCIN_CPU1")
	)
	(segment
		(start 118.432326 -385.869942)
		(end 118.432326 -369.491514)
		(width 0.127)
		(layer "In4.Cu")
		(net "PWRGD_PVCCIN_CPU1")
	)
	(segment
		(start 229.748588 -205.37424)
		(end 229.748588 -240.806986)
		(width 0.127)
		(layer "In4.Cu")
		(net "PWRGD_PVCCIN_CPU1")
	)
	(segment
		(start 118.0084 -395.4018)
		(end 117.430804 -394.824204)
		(width 0.127)
		(layer "In4.Cu")
		(net "PWRGD_PVCCIN_CPU1")
	)
	(segment
		(start 118.7196 -395.4018)
		(end 118.0084 -395.4018)
		(width 0.127)
		(layer "In4.Cu")
		(net "PWRGD_PVCCIN_CPU1")
	)
	(segment
		(start 175.243236 -387.430264)
		(end 175.243236 -394.565124)
		(width 0.127)
		(layer "In4.Cu")
		(net "PWRGD_PVCCIN_CPU1")
	)
	(segment
		(start 198.625968 -362.254546)
		(end 198.625968 -370.331492)
		(width 0.127)
		(layer "In4.Cu")
		(net "PWRGD_PVCCIN_CPU1")
	)
	(segment
		(start 114.19332 -390.108948)
		(end 118.432326 -385.869942)
		(width 0.127)
		(layer "In4.Cu")
		(net "PWRGD_PVCCIN_CPU1")
	)
	(segment
		(start 167.4241 -396.17904)
		(end 166.505128 -395.260068)
		(width 0.127)
		(layer "In11.Cu")
		(net "PWRGD_PVCCIN_CPU1")
	)
	(segment
		(start 175.18888 -134.838948)
		(end 175.95088 -134.076948)
		(width 0.127)
		(layer "In11.Cu")
		(net "PWRGD_PVCCIN_CPU1")
	)
	(segment
		(start 175.95088 -134.076948)
		(end 175.95088 -127.472948)
		(width 0.127)
		(layer "In11.Cu")
		(net "PWRGD_PVCCIN_CPU1")
	)
	(segment
		(start 231.701594 -203.421234)
		(end 229.825804 -203.421234)
		(width 0.127)
		(layer "In11.Cu")
		(net "PWRGD_PVCCIN_CPU1")
	)
	(segment
		(start 210.49488 -153.716228)
		(end 208.39938 -151.620728)
		(width 0.127)
		(layer "In11.Cu")
		(net "PWRGD_PVCCIN_CPU1")
	)
	(segment
		(start 229.825804 -203.421234)
		(end 223.065594 -196.661024)
		(width 0.127)
		(layer "In11.Cu")
		(net "PWRGD_PVCCIN_CPU1")
	)
	(segment
		(start 174.9552 -119.37492)
		(end 174.555658 -118.975378)
		(width 0.127)
		(layer "In11.Cu")
		(net "PWRGD_PVCCIN_CPU1")
	)
	(segment
		(start 232.08488 -203.037948)
		(end 231.701594 -203.421234)
		(width 0.127)
		(layer "In11.Cu")
		(net "PWRGD_PVCCIN_CPU1")
	)
	(segment
		(start 174.80788 -126.329948)
		(end 174.80788 -122.593608)
		(width 0.127)
		(layer "In11.Cu")
		(net "PWRGD_PVCCIN_CPU1")
	)
	(segment
		(start 223.065594 -196.661024)
		(end 223.065594 -172.095922)
		(width 0.127)
		(layer "In11.Cu")
		(net "PWRGD_PVCCIN_CPU1")
	)
	(segment
		(start 171.475908 -395.620748)
		(end 170.917616 -396.17904)
		(width 0.127)
		(layer "In11.Cu")
		(net "PWRGD_PVCCIN_CPU1")
	)
	(segment
		(start 173.71822 -395.620748)
		(end 171.475908 -395.620748)
		(width 0.127)
		(layer "In11.Cu")
		(net "PWRGD_PVCCIN_CPU1")
	)
	(segment
		(start 223.065594 -172.095922)
		(end 210.49488 -159.525208)
		(width 0.127)
		(layer "In11.Cu")
		(net "PWRGD_PVCCIN_CPU1")
	)
	(segment
		(start 208.39938 -151.620728)
		(end 208.39938 -151.158448)
		(width 0.127)
		(layer "In11.Cu")
		(net "PWRGD_PVCCIN_CPU1")
	)
	(segment
		(start 210.49488 -159.525208)
		(end 210.49488 -153.716228)
		(width 0.127)
		(layer "In11.Cu")
		(net "PWRGD_PVCCIN_CPU1")
	)
	(segment
		(start 170.917616 -396.17904)
		(end 167.4241 -396.17904)
		(width 0.127)
		(layer "In11.Cu")
		(net "PWRGD_PVCCIN_CPU1")
	)
	(segment
		(start 118.861332 -395.260068)
		(end 118.7196 -395.4018)
		(width 0.127)
		(layer "In11.Cu")
		(net "PWRGD_PVCCIN_CPU1")
	)
	(segment
		(start 174.9552 -122.446288)
		(end 174.9552 -119.37492)
		(width 0.127)
		(layer "In11.Cu")
		(net "PWRGD_PVCCIN_CPU1")
	)
	(segment
		(start 175.95088 -127.472948)
		(end 174.80788 -126.329948)
		(width 0.127)
		(layer "In11.Cu")
		(net "PWRGD_PVCCIN_CPU1")
	)
	(segment
		(start 166.505128 -395.260068)
		(end 118.861332 -395.260068)
		(width 0.127)
		(layer "In11.Cu")
		(net "PWRGD_PVCCIN_CPU1")
	)
	(segment
		(start 174.80788 -122.593608)
		(end 174.9552 -122.446288)
		(width 0.127)
		(layer "In11.Cu")
		(net "PWRGD_PVCCIN_CPU1")
	)
	(segment
		(start 169.4688 -111.399828)
		(end 170.151044 -111.399828)
		(width 0.127)
		(layer "In13.Cu")
		(net "PWRGD_PVCCIN_CPU1")
	)
	(segment
		(start 168.374314 -90.790268)
		(end 168.374314 -98.890074)
		(width 0.127)
		(layer "In13.Cu")
		(net "PWRGD_PVCCIN_CPU1")
	)
	(segment
		(start 167.94988 -104.841548)
		(end 167.94988 -109.880908)
		(width 0.127)
		(layer "In13.Cu")
		(net "PWRGD_PVCCIN_CPU1")
	)
	(segment
		(start 174.000668 -116.175028)
		(end 174.15002 -116.32438)
		(width 0.127)
		(layer "In13.Cu")
		(net "PWRGD_PVCCIN_CPU1")
	)
	(segment
		(start 167.34536 -102.398068)
		(end 167.34536 -104.237028)
		(width 0.127)
		(layer "In13.Cu")
		(net "PWRGD_PVCCIN_CPU1")
	)
	(segment
		(start 172.78858 -116.175028)
		(end 174.000668 -116.175028)
		(width 0.127)
		(layer "In13.Cu")
		(net "PWRGD_PVCCIN_CPU1")
	)
	(segment
		(start 208.39938 -151.158448)
		(end 209.47888 -150.078948)
		(width 0.127)
		(layer "In13.Cu")
		(net "PWRGD_PVCCIN_CPU1")
	)
	(segment
		(start 174.15002 -118.56974)
		(end 174.555658 -118.975378)
		(width 0.127)
		(layer "In13.Cu")
		(net "PWRGD_PVCCIN_CPU1")
	)
	(segment
		(start 172.366432 -112.168432)
		(end 172.55744 -112.35944)
		(width 0.127)
		(layer "In13.Cu")
		(net "PWRGD_PVCCIN_CPU1")
	)
	(segment
		(start 170.919648 -112.168432)
		(end 172.366432 -112.168432)
		(width 0.127)
		(layer "In13.Cu")
		(net "PWRGD_PVCCIN_CPU1")
	)
	(segment
		(start 167.84066 -99.423728)
		(end 167.84066 -101.902768)
		(width 0.127)
		(layer "In13.Cu")
		(net "PWRGD_PVCCIN_CPU1")
	)
	(segment
		(start 167.34536 -104.237028)
		(end 167.94988 -104.841548)
		(width 0.127)
		(layer "In13.Cu")
		(net "PWRGD_PVCCIN_CPU1")
	)
	(segment
		(start 205.13548 -141.290548)
		(end 177.021236 -141.290548)
		(width 0.127)
		(layer "In13.Cu")
		(net "PWRGD_PVCCIN_CPU1")
	)
	(segment
		(start 168.374314 -98.890074)
		(end 167.84066 -99.423728)
		(width 0.127)
		(layer "In13.Cu")
		(net "PWRGD_PVCCIN_CPU1")
	)
	(segment
		(start 172.55744 -115.943888)
		(end 172.78858 -116.175028)
		(width 0.127)
		(layer "In13.Cu")
		(net "PWRGD_PVCCIN_CPU1")
	)
	(segment
		(start 170.151044 -111.399828)
		(end 170.919648 -112.168432)
		(width 0.127)
		(layer "In13.Cu")
		(net "PWRGD_PVCCIN_CPU1")
	)
	(segment
		(start 177.021236 -141.290548)
		(end 175.18888 -139.458192)
		(width 0.127)
		(layer "In13.Cu")
		(net "PWRGD_PVCCIN_CPU1")
	)
	(segment
		(start 209.47888 -150.078948)
		(end 209.47888 -145.633948)
		(width 0.127)
		(layer "In13.Cu")
		(net "PWRGD_PVCCIN_CPU1")
	)
	(segment
		(start 172.55744 -112.35944)
		(end 172.55744 -115.943888)
		(width 0.127)
		(layer "In13.Cu")
		(net "PWRGD_PVCCIN_CPU1")
	)
	(segment
		(start 167.84066 -101.902768)
		(end 167.34536 -102.398068)
		(width 0.127)
		(layer "In13.Cu")
		(net "PWRGD_PVCCIN_CPU1")
	)
	(segment
		(start 175.18888 -139.458192)
		(end 175.18888 -134.838948)
		(width 0.127)
		(layer "In13.Cu")
		(net "PWRGD_PVCCIN_CPU1")
	)
	(segment
		(start 174.15002 -116.32438)
		(end 174.15002 -118.56974)
		(width 0.127)
		(layer "In13.Cu")
		(net "PWRGD_PVCCIN_CPU1")
	)
	(segment
		(start 209.47888 -145.633948)
		(end 205.13548 -141.290548)
		(width 0.127)
		(layer "In13.Cu")
		(net "PWRGD_PVCCIN_CPU1")
	)
	(segment
		(start 167.94988 -109.880908)
		(end 169.4688 -111.399828)
		(width 0.127)
		(layer "In13.Cu")
		(net "PWRGD_PVCCIN_CPU1")
	)
	(segment
		(start 124.703332 -80.985868)
		(end 127.572008 -78.117192)
		(width 0.127)
		(layer "In15.Cu")
		(net "PWRGD_PVCCIN_CPU1")
	)
	(segment
		(start 127.572008 -78.117192)
		(end 129.983738 -78.117192)
		(width 0.127)
		(layer "In15.Cu")
		(net "PWRGD_PVCCIN_CPU1")
	)
	(segment
		(start 113.17732 -82.817208)
		(end 120.80875 -82.817208)
		(width 0.127)
		(layer "In15.Cu")
		(net "PWRGD_PVCCIN_CPU1")
	)
	(segment
		(start 103.11765 -83.428078)
		(end 112.56645 -83.428078)
		(width 0.127)
		(layer "In15.Cu")
		(net "PWRGD_PVCCIN_CPU1")
	)
	(segment
		(start 133.2992 -78.6638)
		(end 134.7216 -77.2414)
		(width 0.127)
		(layer "In15.Cu")
		(net "PWRGD_PVCCIN_CPU1")
	)
	(segment
		(start 155.374594 -78.329028)
		(end 167.835834 -90.790268)
		(width 0.127)
		(layer "In15.Cu")
		(net "PWRGD_PVCCIN_CPU1")
	)
	(segment
		(start 120.80875 -82.817208)
		(end 122.64009 -80.985868)
		(width 0.127)
		(layer "In15.Cu")
		(net "PWRGD_PVCCIN_CPU1")
	)
	(segment
		(start 130.530346 -78.6638)
		(end 133.2992 -78.6638)
		(width 0.127)
		(layer "In15.Cu")
		(net "PWRGD_PVCCIN_CPU1")
	)
	(segment
		(start 101.27488 -81.585308)
		(end 103.11765 -83.428078)
		(width 0.127)
		(layer "In15.Cu")
		(net "PWRGD_PVCCIN_CPU1")
	)
	(segment
		(start 129.983738 -78.117192)
		(end 130.530346 -78.6638)
		(width 0.127)
		(layer "In15.Cu")
		(net "PWRGD_PVCCIN_CPU1")
	)
	(segment
		(start 112.56645 -83.428078)
		(end 113.17732 -82.817208)
		(width 0.127)
		(layer "In15.Cu")
		(net "PWRGD_PVCCIN_CPU1")
	)
	(segment
		(start 167.835834 -90.790268)
		(end 168.374314 -90.790268)
		(width 0.127)
		(layer "In15.Cu")
		(net "PWRGD_PVCCIN_CPU1")
	)
	(segment
		(start 122.64009 -80.985868)
		(end 124.703332 -80.985868)
		(width 0.127)
		(layer "In15.Cu")
		(net "PWRGD_PVCCIN_CPU1")
	)
	(segment
		(start 134.7216 -77.2414)
		(end 140.6906 -77.2414)
		(width 0.127)
		(layer "In15.Cu")
		(net "PWRGD_PVCCIN_CPU1")
	)
	(segment
		(start 140.6906 -77.2414)
		(end 141.778228 -78.329028)
		(width 0.127)
		(layer "In15.Cu")
		(net "PWRGD_PVCCIN_CPU1")
	)
	(segment
		(start 141.778228 -78.329028)
		(end 155.374594 -78.329028)
		(width 0.127)
		(layer "In15.Cu")
		(net "PWRGD_PVCCIN_CPU1")
	)
	(segment
		(start 350.28378 -361.035854)
		(end 349.782638 -360.534712)
		(width 0.12954)
		(layer "F.Cu")
		(net "PWRGD_PVCCIN_CPU0_R")
	)
	(segment
		(start 350.790764 -360.534712)
		(end 351.806764 -360.534712)
		(width 0.12954)
		(layer "F.Cu")
		(net "PWRGD_PVCCIN_CPU0_R")
	)
	(segment
		(start 350.17964 -362.79836)
		(end 350.28378 -362.69422)
		(width 0.12954)
		(layer "F.Cu")
		(net "PWRGD_PVCCIN_CPU0_R")
	)
	(segment
		(start 353.351084 -359.848404)
		(end 353.643184 -359.848404)
		(width 0.12954)
		(layer "F.Cu")
		(net "PWRGD_PVCCIN_CPU0_R")
	)
	(segment
		(start 353.050348 -360.14914)
		(end 353.351084 -359.848404)
		(width 0.12954)
		(layer "F.Cu")
		(net "PWRGD_PVCCIN_CPU0_R")
	)
	(segment
		(start 350.28378 -362.69422)
		(end 350.28378 -361.035854)
		(width 0.12954)
		(layer "F.Cu")
		(net "PWRGD_PVCCIN_CPU0_R")
	)
	(segment
		(start 352.065082 -360.79303)
		(end 352.673158 -360.79303)
		(width 0.12954)
		(layer "F.Cu")
		(net "PWRGD_PVCCIN_CPU0_R")
	)
	(segment
		(start 352.673158 -360.79303)
		(end 353.050348 -360.41584)
		(width 0.12954)
		(layer "F.Cu")
		(net "PWRGD_PVCCIN_CPU0_R")
	)
	(segment
		(start 353.050348 -360.41584)
		(end 353.050348 -360.14914)
		(width 0.12954)
		(layer "F.Cu")
		(net "PWRGD_PVCCIN_CPU0_R")
	)
	(segment
		(start 351.806764 -360.534712)
		(end 352.065082 -360.79303)
		(width 0.12954)
		(layer "F.Cu")
		(net "PWRGD_PVCCIN_CPU0_R")
	)
	(segment
		(start 349.782638 -360.534712)
		(end 349.77705 -360.529124)
		(width 0.12954)
		(layer "F.Cu")
		(net "PWRGD_PVCCIN_CPU0_R")
	)
	(segment
		(start 350.790764 -360.534712)
		(end 349.782638 -360.534712)
		(width 0.12954)
		(layer "F.Cu")
		(net "PWRGD_PVCCIN_CPU0_R")
	)
	(via
		(at 350.17964 -362.79836)
		(size 0.762)
		(drill 0.381)
		(layers "F.Cu" "B.Cu")
		(net "PWRGD_PVCCIN_CPU0_R")
	)
	(segment
		(start 97.97288 -81.509108)
		(end 98.59772 -81.509108)
		(width 0.12954)
		(layer "F.Cu")
		(net "PWRGD_PVCCIN_CPU0")
	)
	(segment
		(start 349.77705 -361.329224)
		(end 349.77705 -361.953556)
		(width 0.12954)
		(layer "F.Cu")
		(net "PWRGD_PVCCIN_CPU0")
	)
	(segment
		(start 174.155608 -114.575336)
		(end 173.755558 -114.975386)
		(width 0.12954)
		(layer "F.Cu")
		(net "PWRGD_PVCCIN_CPU0")
	)
	(segment
		(start 98.59772 -81.509108)
		(end 98.67392 -81.585308)
		(width 0.12954)
		(layer "F.Cu")
		(net "PWRGD_PVCCIN_CPU0")
	)
	(via
		(at 180.86324 -162.189668)
		(size 0.508)
		(drill 0.254)
		(layers "F.Cu" "B.Cu")
		(net "PWRGD_PVCCIN_CPU0")
	)
	(via
		(at 173.755558 -114.975386)
		(size 0.4572)
		(drill 0.254)
		(layers "F.Cu" "B.Cu")
		(net "PWRGD_PVCCIN_CPU0")
	)
	(via
		(at 164.3634 -90.772488)
		(size 0.508)
		(drill 0.254)
		(layers "F.Cu" "B.Cu")
		(net "PWRGD_PVCCIN_CPU0")
	)
	(via
		(at 97.97288 -81.509108)
		(size 0.508)
		(drill 0.254)
		(layers "F.Cu" "B.Cu")
		(net "PWRGD_PVCCIN_CPU0")
	)
	(via
		(at 349.77705 -361.953556)
		(size 0.508)
		(drill 0.254)
		(layers "F.Cu" "B.Cu")
		(net "PWRGD_PVCCIN_CPU0")
	)
	(via
		(at 347.990414 -370.934996)
		(size 0.508)
		(drill 0.254)
		(layers "F.Cu" "B.Cu")
		(net "PWRGD_PVCCIN_CPU0")
	)
	(segment
		(start 259.434838 -325.53783)
		(end 260.359398 -326.46239)
		(width 0.12954)
		(layer "B.Cu")
		(net "PWRGD_PVCCIN_CPU0")
	)
	(segment
		(start 253.17958 -321.162934)
		(end 255.403858 -323.387212)
		(width 0.12954)
		(layer "B.Cu")
		(net "PWRGD_PVCCIN_CPU0")
	)
	(segment
		(start 339.421724 -379.503686)
		(end 347.990414 -370.934996)
		(width 0.12954)
		(layer "B.Cu")
		(net "PWRGD_PVCCIN_CPU0")
	)
	(segment
		(start 180.86324 -162.189668)
		(end 181.19344 -162.519868)
		(width 0.12954)
		(layer "B.Cu")
		(net "PWRGD_PVCCIN_CPU0")
	)
	(segment
		(start 260.359398 -328.067416)
		(end 275.639022 -343.34704)
		(width 0.12954)
		(layer "B.Cu")
		(net "PWRGD_PVCCIN_CPU0")
	)
	(segment
		(start 253.17958 -303.108106)
		(end 253.17958 -321.162934)
		(width 0.12954)
		(layer "B.Cu")
		(net "PWRGD_PVCCIN_CPU0")
	)
	(segment
		(start 275.639022 -343.34704)
		(end 275.639022 -367.27257)
		(width 0.12954)
		(layer "B.Cu")
		(net "PWRGD_PVCCIN_CPU0")
	)
	(segment
		(start 255.403858 -323.387212)
		(end 255.403858 -324.84187)
		(width 0.12954)
		(layer "B.Cu")
		(net "PWRGD_PVCCIN_CPU0")
	)
	(segment
		(start 232.254298 -175.303688)
		(end 243.963698 -175.303688)
		(width 0.12954)
		(layer "B.Cu")
		(net "PWRGD_PVCCIN_CPU0")
	)
	(segment
		(start 225.294698 -168.344088)
		(end 232.254298 -175.303688)
		(width 0.12954)
		(layer "B.Cu")
		(net "PWRGD_PVCCIN_CPU0")
	)
	(segment
		(start 179.75072 -163.479988)
		(end 179.40528 -163.825428)
		(width 0.12954)
		(layer "B.Cu")
		(net "PWRGD_PVCCIN_CPU0")
	)
	(segment
		(start 275.639022 -367.27257)
		(end 287.870138 -379.503686)
		(width 0.12954)
		(layer "B.Cu")
		(net "PWRGD_PVCCIN_CPU0")
	)
	(segment
		(start 179.40528 -163.825428)
		(end 179.40528 -165.63467)
		(width 0.12954)
		(layer "B.Cu")
		(net "PWRGD_PVCCIN_CPU0")
	)
	(segment
		(start 179.40528 -165.63467)
		(end 182.114698 -168.344088)
		(width 0.12954)
		(layer "B.Cu")
		(net "PWRGD_PVCCIN_CPU0")
	)
	(segment
		(start 255.403858 -324.84187)
		(end 256.099818 -325.53783)
		(width 0.12954)
		(layer "B.Cu")
		(net "PWRGD_PVCCIN_CPU0")
	)
	(segment
		(start 254.004318 -302.283368)
		(end 253.17958 -303.108106)
		(width 0.12954)
		(layer "B.Cu")
		(net "PWRGD_PVCCIN_CPU0")
	)
	(segment
		(start 256.099818 -325.53783)
		(end 259.434838 -325.53783)
		(width 0.12954)
		(layer "B.Cu")
		(net "PWRGD_PVCCIN_CPU0")
	)
	(segment
		(start 243.963698 -175.303688)
		(end 254.004318 -185.344308)
		(width 0.12954)
		(layer "B.Cu")
		(net "PWRGD_PVCCIN_CPU0")
	)
	(segment
		(start 254.004318 -185.344308)
		(end 254.004318 -302.283368)
		(width 0.12954)
		(layer "B.Cu")
		(net "PWRGD_PVCCIN_CPU0")
	)
	(segment
		(start 260.359398 -326.46239)
		(end 260.359398 -328.067416)
		(width 0.12954)
		(layer "B.Cu")
		(net "PWRGD_PVCCIN_CPU0")
	)
	(segment
		(start 181.19344 -163.035488)
		(end 180.74894 -163.479988)
		(width 0.12954)
		(layer "B.Cu")
		(net "PWRGD_PVCCIN_CPU0")
	)
	(segment
		(start 180.74894 -163.479988)
		(end 179.75072 -163.479988)
		(width 0.12954)
		(layer "B.Cu")
		(net "PWRGD_PVCCIN_CPU0")
	)
	(segment
		(start 287.870138 -379.503686)
		(end 339.421724 -379.503686)
		(width 0.12954)
		(layer "B.Cu")
		(net "PWRGD_PVCCIN_CPU0")
	)
	(segment
		(start 181.19344 -162.519868)
		(end 181.19344 -163.035488)
		(width 0.12954)
		(layer "B.Cu")
		(net "PWRGD_PVCCIN_CPU0")
	)
	(segment
		(start 182.114698 -168.344088)
		(end 225.294698 -168.344088)
		(width 0.12954)
		(layer "B.Cu")
		(net "PWRGD_PVCCIN_CPU0")
	)
	(segment
		(start 168.8846 -103.981758)
		(end 168.69918 -104.167178)
		(width 0.127)
		(layer "In2.Cu")
		(net "PWRGD_PVCCIN_CPU0")
	)
	(segment
		(start 168.8846 -95.293688)
		(end 168.8846 -103.981758)
		(width 0.127)
		(layer "In2.Cu")
		(net "PWRGD_PVCCIN_CPU0")
	)
	(segment
		(start 172.562774 -112.313974)
		(end 172.562774 -112.872774)
		(width 0.127)
		(layer "In2.Cu")
		(net "PWRGD_PVCCIN_CPU0")
	)
	(segment
		(start 173.15688 -112.997488)
		(end 174.15002 -113.990628)
		(width 0.127)
		(layer "In2.Cu")
		(net "PWRGD_PVCCIN_CPU0")
	)
	(segment
		(start 164.3634 -90.772488)
		(end 168.8846 -95.293688)
		(width 0.127)
		(layer "In2.Cu")
		(net "PWRGD_PVCCIN_CPU0")
	)
	(segment
		(start 170.456606 -111.43234)
		(end 171.192698 -112.168432)
		(width 0.127)
		(layer "In2.Cu")
		(net "PWRGD_PVCCIN_CPU0")
	)
	(segment
		(start 174.15002 -114.580924)
		(end 173.755558 -114.975386)
		(width 0.127)
		(layer "In2.Cu")
		(net "PWRGD_PVCCIN_CPU0")
	)
	(segment
		(start 172.687488 -112.997488)
		(end 173.15688 -112.997488)
		(width 0.127)
		(layer "In2.Cu")
		(net "PWRGD_PVCCIN_CPU0")
	)
	(segment
		(start 168.69918 -104.167178)
		(end 168.69918 -110.576868)
		(width 0.127)
		(layer "In2.Cu")
		(net "PWRGD_PVCCIN_CPU0")
	)
	(segment
		(start 172.417232 -112.168432)
		(end 172.562774 -112.313974)
		(width 0.127)
		(layer "In2.Cu")
		(net "PWRGD_PVCCIN_CPU0")
	)
	(segment
		(start 172.562774 -112.872774)
		(end 172.687488 -112.997488)
		(width 0.127)
		(layer "In2.Cu")
		(net "PWRGD_PVCCIN_CPU0")
	)
	(segment
		(start 169.554652 -111.43234)
		(end 170.456606 -111.43234)
		(width 0.127)
		(layer "In2.Cu")
		(net "PWRGD_PVCCIN_CPU0")
	)
	(segment
		(start 171.192698 -112.168432)
		(end 172.417232 -112.168432)
		(width 0.127)
		(layer "In2.Cu")
		(net "PWRGD_PVCCIN_CPU0")
	)
	(segment
		(start 168.69918 -110.576868)
		(end 169.554652 -111.43234)
		(width 0.127)
		(layer "In2.Cu")
		(net "PWRGD_PVCCIN_CPU0")
	)
	(segment
		(start 174.15002 -113.990628)
		(end 174.15002 -114.580924)
		(width 0.127)
		(layer "In2.Cu")
		(net "PWRGD_PVCCIN_CPU0")
	)
	(segment
		(start 171.57192 -124.039884)
		(end 172.54982 -123.061984)
		(width 0.127)
		(layer "In11.Cu")
		(net "PWRGD_PVCCIN_CPU0")
	)
	(segment
		(start 174.68088 -153.533348)
		(end 174.68088 -129.123948)
		(width 0.127)
		(layer "In11.Cu")
		(net "PWRGD_PVCCIN_CPU0")
	)
	(segment
		(start 180.06568 -161.356548)
		(end 180.06568 -158.918148)
		(width 0.127)
		(layer "In11.Cu")
		(net "PWRGD_PVCCIN_CPU0")
	)
	(segment
		(start 180.06568 -158.918148)
		(end 174.68088 -153.533348)
		(width 0.127)
		(layer "In11.Cu")
		(net "PWRGD_PVCCIN_CPU0")
	)
	(segment
		(start 172.54982 -123.061984)
		(end 172.54982 -118.778528)
		(width 0.127)
		(layer "In11.Cu")
		(net "PWRGD_PVCCIN_CPU0")
	)
	(segment
		(start 173.4947 -128.0287)
		(end 171.57192 -126.10592)
		(width 0.127)
		(layer "In11.Cu")
		(net "PWRGD_PVCCIN_CPU0")
	)
	(segment
		(start 172.87494 -118.026688)
		(end 173.36008 -117.541548)
		(width 0.127)
		(layer "In11.Cu")
		(net "PWRGD_PVCCIN_CPU0")
	)
	(segment
		(start 180.86324 -162.154108)
		(end 180.06568 -161.356548)
		(width 0.127)
		(layer "In11.Cu")
		(net "PWRGD_PVCCIN_CPU0")
	)
	(segment
		(start 174.21606 -128.659128)
		(end 173.70806 -128.659128)
		(width 0.127)
		(layer "In11.Cu")
		(net "PWRGD_PVCCIN_CPU0")
	)
	(segment
		(start 173.36008 -117.541548)
		(end 173.36008 -115.370864)
		(width 0.127)
		(layer "In11.Cu")
		(net "PWRGD_PVCCIN_CPU0")
	)
	(segment
		(start 172.87494 -118.453408)
		(end 172.87494 -118.026688)
		(width 0.127)
		(layer "In11.Cu")
		(net "PWRGD_PVCCIN_CPU0")
	)
	(segment
		(start 173.36008 -115.370864)
		(end 173.755558 -114.975386)
		(width 0.127)
		(layer "In11.Cu")
		(net "PWRGD_PVCCIN_CPU0")
	)
	(segment
		(start 172.54982 -118.778528)
		(end 172.87494 -118.453408)
		(width 0.127)
		(layer "In11.Cu")
		(net "PWRGD_PVCCIN_CPU0")
	)
	(segment
		(start 180.86324 -162.189668)
		(end 180.86324 -162.154108)
		(width 0.127)
		(layer "In11.Cu")
		(net "PWRGD_PVCCIN_CPU0")
	)
	(segment
		(start 173.4947 -128.445768)
		(end 173.4947 -128.0287)
		(width 0.127)
		(layer "In11.Cu")
		(net "PWRGD_PVCCIN_CPU0")
	)
	(segment
		(start 173.70806 -128.659128)
		(end 173.4947 -128.445768)
		(width 0.127)
		(layer "In11.Cu")
		(net "PWRGD_PVCCIN_CPU0")
	)
	(segment
		(start 174.68088 -129.123948)
		(end 174.21606 -128.659128)
		(width 0.127)
		(layer "In11.Cu")
		(net "PWRGD_PVCCIN_CPU0")
	)
	(segment
		(start 171.57192 -126.10592)
		(end 171.57192 -124.039884)
		(width 0.127)
		(layer "In11.Cu")
		(net "PWRGD_PVCCIN_CPU0")
	)
	(segment
		(start 347.990414 -370.934996)
		(end 349.77705 -369.14836)
		(width 0.127)
		(layer "In15.Cu")
		(net "PWRGD_PVCCIN_CPU0")
	)
	(segment
		(start 122.78868 -81.448148)
		(end 120.95988 -83.276948)
		(width 0.127)
		(layer "In15.Cu")
		(net "PWRGD_PVCCIN_CPU0")
	)
	(segment
		(start 349.77705 -369.14836)
		(end 349.77705 -361.953556)
		(width 0.127)
		(layer "In15.Cu")
		(net "PWRGD_PVCCIN_CPU0")
	)
	(segment
		(start 98.64344 -81.509108)
		(end 97.97288 -81.509108)
		(width 0.127)
		(layer "In15.Cu")
		(net "PWRGD_PVCCIN_CPU0")
	)
	(segment
		(start 129.215388 -79.3242)
		(end 127.09144 -81.448148)
		(width 0.127)
		(layer "In15.Cu")
		(net "PWRGD_PVCCIN_CPU0")
	)
	(segment
		(start 162.69208 -87.427308)
		(end 156.8196 -81.554828)
		(width 0.127)
		(layer "In15.Cu")
		(net "PWRGD_PVCCIN_CPU0")
	)
	(segment
		(start 120.95988 -83.276948)
		(end 113.59388 -83.276948)
		(width 0.127)
		(layer "In15.Cu")
		(net "PWRGD_PVCCIN_CPU0")
	)
	(segment
		(start 113.59388 -83.276948)
		(end 112.53978 -84.331048)
		(width 0.127)
		(layer "In15.Cu")
		(net "PWRGD_PVCCIN_CPU0")
	)
	(segment
		(start 162.69208 -89.101168)
		(end 162.69208 -87.427308)
		(width 0.127)
		(layer "In15.Cu")
		(net "PWRGD_PVCCIN_CPU0")
	)
	(segment
		(start 164.3634 -90.772488)
		(end 162.69208 -89.101168)
		(width 0.127)
		(layer "In15.Cu")
		(net "PWRGD_PVCCIN_CPU0")
	)
	(segment
		(start 112.53978 -84.331048)
		(end 101.46538 -84.331048)
		(width 0.127)
		(layer "In15.Cu")
		(net "PWRGD_PVCCIN_CPU0")
	)
	(segment
		(start 156.8196 -81.554828)
		(end 148.70938 -81.554828)
		(width 0.127)
		(layer "In15.Cu")
		(net "PWRGD_PVCCIN_CPU0")
	)
	(segment
		(start 148.70938 -81.554828)
		(end 146.478752 -79.3242)
		(width 0.127)
		(layer "In15.Cu")
		(net "PWRGD_PVCCIN_CPU0")
	)
	(segment
		(start 101.46538 -84.331048)
		(end 98.64344 -81.509108)
		(width 0.127)
		(layer "In15.Cu")
		(net "PWRGD_PVCCIN_CPU0")
	)
	(segment
		(start 127.09144 -81.448148)
		(end 122.78868 -81.448148)
		(width 0.127)
		(layer "In15.Cu")
		(net "PWRGD_PVCCIN_CPU0")
	)
	(segment
		(start 146.478752 -79.3242)
		(end 129.215388 -79.3242)
		(width 0.127)
		(layer "In15.Cu")
		(net "PWRGD_PVCCIN_CPU0")
	)
	(segment
		(start 35.86988 -127.09906)
		(end 35.86988 -126.69774)
		(width 0.12954)
		(layer "F.Cu")
		(net "PWRGD_PVCCINFAON_CPU1_R")
	)
	(segment
		(start 35.86988 -126.69774)
		(end 36.556188 -126.69774)
		(width 0.12954)
		(layer "F.Cu")
		(net "PWRGD_PVCCINFAON_CPU1_R")
	)
	(segment
		(start 34.735516 -128.233424)
		(end 35.86988 -127.09906)
		(width 0.12954)
		(layer "F.Cu")
		(net "PWRGD_PVCCINFAON_CPU1_R")
	)
	(segment
		(start 34.461196 -128.233424)
		(end 34.735516 -128.233424)
		(width 0.12954)
		(layer "F.Cu")
		(net "PWRGD_PVCCINFAON_CPU1_R")
	)
	(via
		(at 35.39998 -125.11024)
		(size 0.6604)
		(drill 0.3302)
		(layers "F.Cu" "B.Cu")
		(net "PWRGD_PVCCINFAON_CPU1_R")
	)
	(via
		(at 35.86988 -126.69774)
		(size 0.508)
		(drill 0.254)
		(layers "F.Cu" "B.Cu")
		(net "PWRGD_PVCCINFAON_CPU1_R")
	)
	(segment
		(start 35.39998 -125.82398)
		(end 35.86988 -126.29388)
		(width 0.12954)
		(layer "B.Cu")
		(net "PWRGD_PVCCINFAON_CPU1_R")
	)
	(segment
		(start 35.6743 -125.38456)
		(end 35.39998 -125.11024)
		(width 0.12954)
		(layer "B.Cu")
		(net "PWRGD_PVCCINFAON_CPU1_R")
	)
	(segment
		(start 36.271708 -126.69774)
		(end 36.568888 -126.40056)
		(width 0.12954)
		(layer "B.Cu")
		(net "PWRGD_PVCCINFAON_CPU1_R")
	)
	(segment
		(start 35.86988 -126.29388)
		(end 35.86988 -126.69774)
		(width 0.12954)
		(layer "B.Cu")
		(net "PWRGD_PVCCINFAON_CPU1_R")
	)
	(segment
		(start 35.86988 -126.69774)
		(end 36.271708 -126.69774)
		(width 0.12954)
		(layer "B.Cu")
		(net "PWRGD_PVCCINFAON_CPU1_R")
	)
	(segment
		(start 36.568888 -125.38456)
		(end 35.6743 -125.38456)
		(width 0.12954)
		(layer "B.Cu")
		(net "PWRGD_PVCCINFAON_CPU1_R")
	)
	(segment
		(start 35.39998 -125.11024)
		(end 35.39998 -125.82398)
		(width 0.12954)
		(layer "B.Cu")
		(net "PWRGD_PVCCINFAON_CPU1_R")
	)
	(segment
		(start 106.30916 -99.609402)
		(end 107.025186 -99.609402)
		(width 0.12954)
		(layer "F.Cu")
		(net "PWRGD_PVCCINFAON_CPU1")
	)
	(segment
		(start 175.755554 -120.175528)
		(end 175.355504 -120.575578)
		(width 0.12954)
		(layer "F.Cu")
		(net "PWRGD_PVCCINFAON_CPU1")
	)
	(via
		(at 175.355504 -120.575578)
		(size 0.4572)
		(drill 0.254)
		(layers "F.Cu" "B.Cu")
		(net "PWRGD_PVCCINFAON_CPU1")
	)
	(via
		(at 55.31358 -108.778548)
		(size 0.508)
		(drill 0.254)
		(layers "F.Cu" "B.Cu")
		(net "PWRGD_PVCCINFAON_CPU1")
	)
	(via
		(at 41.954704 -127.198628)
		(size 0.508)
		(drill 0.254)
		(layers "F.Cu" "B.Cu")
		(net "PWRGD_PVCCINFAON_CPU1")
	)
	(via
		(at 106.30916 -99.609402)
		(size 0.508)
		(drill 0.254)
		(layers "F.Cu" "B.Cu")
		(net "PWRGD_PVCCINFAON_CPU1")
	)
	(via
		(at 106.14152 -117.333268)
		(size 0.508)
		(drill 0.254)
		(layers "F.Cu" "B.Cu")
		(net "PWRGD_PVCCINFAON_CPU1")
	)
	(segment
		(start 38.21176 -126.16434)
		(end 39.246048 -127.198628)
		(width 0.12954)
		(layer "B.Cu")
		(net "PWRGD_PVCCINFAON_CPU1")
	)
	(segment
		(start 37.368988 -126.40056)
		(end 37.605208 -126.16434)
		(width 0.12954)
		(layer "B.Cu")
		(net "PWRGD_PVCCINFAON_CPU1")
	)
	(segment
		(start 37.605208 -126.16434)
		(end 38.21176 -126.16434)
		(width 0.12954)
		(layer "B.Cu")
		(net "PWRGD_PVCCINFAON_CPU1")
	)
	(segment
		(start 39.246048 -127.198628)
		(end 41.954704 -127.198628)
		(width 0.12954)
		(layer "B.Cu")
		(net "PWRGD_PVCCINFAON_CPU1")
	)
	(segment
		(start 106.14152 -117.333268)
		(end 105.31856 -116.510308)
		(width 0.127)
		(layer "In2.Cu")
		(net "PWRGD_PVCCINFAON_CPU1")
	)
	(segment
		(start 105.31856 -116.510308)
		(end 105.31856 -100.600002)
		(width 0.127)
		(layer "In2.Cu")
		(net "PWRGD_PVCCINFAON_CPU1")
	)
	(segment
		(start 105.31856 -100.600002)
		(end 106.30916 -99.609402)
		(width 0.127)
		(layer "In2.Cu")
		(net "PWRGD_PVCCINFAON_CPU1")
	)
	(segment
		(start 100.45954 -95.552768)
		(end 101.6762 -96.769428)
		(width 0.127)
		(layer "In6.Cu")
		(net "PWRGD_PVCCINFAON_CPU1")
	)
	(segment
		(start 94.12478 -97.861628)
		(end 96.33458 -97.861628)
		(width 0.127)
		(layer "In6.Cu")
		(net "PWRGD_PVCCINFAON_CPU1")
	)
	(segment
		(start 79.974948 -102.2604)
		(end 85.07984 -97.155508)
		(width 0.127)
		(layer "In6.Cu")
		(net "PWRGD_PVCCINFAON_CPU1")
	)
	(segment
		(start 98.64344 -95.552768)
		(end 100.45954 -95.552768)
		(width 0.127)
		(layer "In6.Cu")
		(net "PWRGD_PVCCINFAON_CPU1")
	)
	(segment
		(start 96.33458 -97.861628)
		(end 98.64344 -95.552768)
		(width 0.127)
		(layer "In6.Cu")
		(net "PWRGD_PVCCINFAON_CPU1")
	)
	(segment
		(start 55.31358 -108.115608)
		(end 61.168788 -102.2604)
		(width 0.127)
		(layer "In6.Cu")
		(net "PWRGD_PVCCINFAON_CPU1")
	)
	(segment
		(start 103.469186 -96.769428)
		(end 106.30916 -99.609402)
		(width 0.127)
		(layer "In6.Cu")
		(net "PWRGD_PVCCINFAON_CPU1")
	)
	(segment
		(start 91.31808 -97.724468)
		(end 93.98762 -97.724468)
		(width 0.127)
		(layer "In6.Cu")
		(net "PWRGD_PVCCINFAON_CPU1")
	)
	(segment
		(start 101.6762 -96.769428)
		(end 103.469186 -96.769428)
		(width 0.127)
		(layer "In6.Cu")
		(net "PWRGD_PVCCINFAON_CPU1")
	)
	(segment
		(start 55.31358 -108.778548)
		(end 55.31358 -108.115608)
		(width 0.127)
		(layer "In6.Cu")
		(net "PWRGD_PVCCINFAON_CPU1")
	)
	(segment
		(start 61.168788 -102.2604)
		(end 79.974948 -102.2604)
		(width 0.127)
		(layer "In6.Cu")
		(net "PWRGD_PVCCINFAON_CPU1")
	)
	(segment
		(start 93.98762 -97.724468)
		(end 94.12478 -97.861628)
		(width 0.127)
		(layer "In6.Cu")
		(net "PWRGD_PVCCINFAON_CPU1")
	)
	(segment
		(start 90.74912 -97.155508)
		(end 91.31808 -97.724468)
		(width 0.127)
		(layer "In6.Cu")
		(net "PWRGD_PVCCINFAON_CPU1")
	)
	(segment
		(start 85.07984 -97.155508)
		(end 90.74912 -97.155508)
		(width 0.127)
		(layer "In6.Cu")
		(net "PWRGD_PVCCINFAON_CPU1")
	)
	(segment
		(start 172.79366 -120.975628)
		(end 174.955454 -120.975628)
		(width 0.127)
		(layer "In15.Cu")
		(net "PWRGD_PVCCINFAON_CPU1")
	)
	(segment
		(start 148.12772 -127.178308)
		(end 148.99132 -127.178308)
		(width 0.127)
		(layer "In15.Cu")
		(net "PWRGD_PVCCINFAON_CPU1")
	)
	(segment
		(start 139.793472 -118.84406)
		(end 148.12772 -127.178308)
		(width 0.127)
		(layer "In15.Cu")
		(net "PWRGD_PVCCINFAON_CPU1")
	)
	(segment
		(start 41.954704 -127.198628)
		(end 44.441872 -127.198628)
		(width 0.127)
		(layer "In15.Cu")
		(net "PWRGD_PVCCINFAON_CPU1")
	)
	(segment
		(start 133.505448 -117.333268)
		(end 135.01624 -118.84406)
		(width 0.127)
		(layer "In15.Cu")
		(net "PWRGD_PVCCINFAON_CPU1")
	)
	(segment
		(start 135.01624 -118.84406)
		(end 139.793472 -118.84406)
		(width 0.127)
		(layer "In15.Cu")
		(net "PWRGD_PVCCINFAON_CPU1")
	)
	(segment
		(start 174.955454 -120.975628)
		(end 175.355504 -120.575578)
		(width 0.127)
		(layer "In15.Cu")
		(net "PWRGD_PVCCINFAON_CPU1")
	)
	(segment
		(start 149.8346 -126.335028)
		(end 154.783536 -126.335028)
		(width 0.127)
		(layer "In15.Cu")
		(net "PWRGD_PVCCINFAON_CPU1")
	)
	(segment
		(start 155.908756 -127.460248)
		(end 163.257992 -127.460248)
		(width 0.127)
		(layer "In15.Cu")
		(net "PWRGD_PVCCINFAON_CPU1")
	)
	(segment
		(start 106.14152 -117.333268)
		(end 133.505448 -117.333268)
		(width 0.127)
		(layer "In15.Cu")
		(net "PWRGD_PVCCINFAON_CPU1")
	)
	(segment
		(start 163.534852 -127.183388)
		(end 167.778684 -127.183388)
		(width 0.127)
		(layer "In15.Cu")
		(net "PWRGD_PVCCINFAON_CPU1")
	)
	(segment
		(start 172.54982 -122.412252)
		(end 172.54982 -121.219468)
		(width 0.127)
		(layer "In15.Cu")
		(net "PWRGD_PVCCINFAON_CPU1")
	)
	(segment
		(start 167.778684 -127.183388)
		(end 172.54982 -122.412252)
		(width 0.127)
		(layer "In15.Cu")
		(net "PWRGD_PVCCINFAON_CPU1")
	)
	(segment
		(start 172.54982 -121.219468)
		(end 172.79366 -120.975628)
		(width 0.127)
		(layer "In15.Cu")
		(net "PWRGD_PVCCINFAON_CPU1")
	)
	(segment
		(start 148.99132 -127.178308)
		(end 149.8346 -126.335028)
		(width 0.127)
		(layer "In15.Cu")
		(net "PWRGD_PVCCINFAON_CPU1")
	)
	(segment
		(start 163.257992 -127.460248)
		(end 163.534852 -127.183388)
		(width 0.127)
		(layer "In15.Cu")
		(net "PWRGD_PVCCINFAON_CPU1")
	)
	(segment
		(start 54.58714 -109.504988)
		(end 55.31358 -108.778548)
		(width 0.127)
		(layer "In15.Cu")
		(net "PWRGD_PVCCINFAON_CPU1")
	)
	(segment
		(start 44.441872 -127.198628)
		(end 54.58714 -117.05336)
		(width 0.127)
		(layer "In15.Cu")
		(net "PWRGD_PVCCINFAON_CPU1")
	)
	(segment
		(start 54.58714 -117.05336)
		(end 54.58714 -109.504988)
		(width 0.127)
		(layer "In15.Cu")
		(net "PWRGD_PVCCINFAON_CPU1")
	)
	(segment
		(start 154.783536 -126.335028)
		(end 155.908756 -127.460248)
		(width 0.127)
		(layer "In15.Cu")
		(net "PWRGD_PVCCINFAON_CPU1")
	)
	(segment
		(start 428.459138 -135.014462)
		(end 428.105062 -135.014462)
		(width 0.12954)
		(layer "F.Cu")
		(net "PWRGD_PVCCINFAON_CPU0_R")
	)
	(segment
		(start 429.513746 -133.959854)
		(end 428.459138 -135.014462)
		(width 0.12954)
		(layer "F.Cu")
		(net "PWRGD_PVCCINFAON_CPU0_R")
	)
	(segment
		(start 430.200054 -133.478778)
		(end 429.513746 -133.478778)
		(width 0.12954)
		(layer "F.Cu")
		(net "PWRGD_PVCCINFAON_CPU0_R")
	)
	(segment
		(start 429.513746 -133.478778)
		(end 429.513746 -133.959854)
		(width 0.12954)
		(layer "F.Cu")
		(net "PWRGD_PVCCINFAON_CPU0_R")
	)
	(via
		(at 429.513746 -133.478778)
		(size 0.508)
		(drill 0.254)
		(layers "F.Cu" "B.Cu")
		(net "PWRGD_PVCCINFAON_CPU0_R")
	)
	(via
		(at 427.94174 -132.994908)
		(size 0.6604)
		(drill 0.3302)
		(layers "F.Cu" "B.Cu")
		(net "PWRGD_PVCCINFAON_CPU0_R")
	)
	(segment
		(start 430.200054 -133.478778)
		(end 429.513746 -133.478778)
		(width 0.12954)
		(layer "B.Cu")
		(net "PWRGD_PVCCINFAON_CPU0_R")
	)
	(segment
		(start 429.513746 -133.478778)
		(end 428.42561 -133.478778)
		(width 0.12954)
		(layer "B.Cu")
		(net "PWRGD_PVCCINFAON_CPU0_R")
	)
	(segment
		(start 430.200054 -133.478778)
		(end 430.200054 -132.462778)
		(width 0.12954)
		(layer "B.Cu")
		(net "PWRGD_PVCCINFAON_CPU0_R")
	)
	(segment
		(start 428.42561 -133.478778)
		(end 427.94174 -132.994908)
		(width 0.12954)
		(layer "B.Cu")
		(net "PWRGD_PVCCINFAON_CPU0_R")
	)
	(segment
		(start 174.955708 -117.775482)
		(end 174.555658 -118.175532)
		(width 0.12954)
		(layer "F.Cu")
		(net "PWRGD_PVCCINFAON_CPU0")
	)
	(segment
		(start 106.149648 -93.015562)
		(end 107.129326 -93.015562)
		(width 0.12954)
		(layer "F.Cu")
		(net "PWRGD_PVCCINFAON_CPU0")
	)
	(segment
		(start 105.857548 -93.307662)
		(end 106.149648 -93.015562)
		(width 0.12954)
		(layer "F.Cu")
		(net "PWRGD_PVCCINFAON_CPU0")
	)
	(via
		(at 166.42588 -123.662948)
		(size 0.508)
		(drill 0.254)
		(layers "F.Cu" "B.Cu")
		(net "PWRGD_PVCCINFAON_CPU0")
	)
	(via
		(at 105.857548 -93.307662)
		(size 0.508)
		(drill 0.254)
		(layers "F.Cu" "B.Cu")
		(net "PWRGD_PVCCINFAON_CPU0")
	)
	(via
		(at 434.300376 -131.090924)
		(size 0.508)
		(drill 0.254)
		(layers "F.Cu" "B.Cu")
		(net "PWRGD_PVCCINFAON_CPU0")
	)
	(via
		(at 104.83088 -111.597948)
		(size 0.508)
		(drill 0.254)
		(layers "F.Cu" "B.Cu")
		(net "PWRGD_PVCCINFAON_CPU0")
	)
	(via
		(at 174.555658 -118.175532)
		(size 0.4572)
		(drill 0.254)
		(layers "F.Cu" "B.Cu")
		(net "PWRGD_PVCCINFAON_CPU0")
	)
	(segment
		(start 431.000154 -133.159246)
		(end 431.000154 -133.478778)
		(width 0.12954)
		(layer "B.Cu")
		(net "PWRGD_PVCCINFAON_CPU0")
	)
	(segment
		(start 434.300376 -131.090924)
		(end 432.383692 -133.007608)
		(width 0.12954)
		(layer "B.Cu")
		(net "PWRGD_PVCCINFAON_CPU0")
	)
	(segment
		(start 432.383692 -133.007608)
		(end 431.151792 -133.007608)
		(width 0.12954)
		(layer "B.Cu")
		(net "PWRGD_PVCCINFAON_CPU0")
	)
	(segment
		(start 431.151792 -133.007608)
		(end 431.000154 -133.159246)
		(width 0.12954)
		(layer "B.Cu")
		(net "PWRGD_PVCCINFAON_CPU0")
	)
	(segment
		(start 171.994322 -119.380762)
		(end 171.751752 -119.623332)
		(width 0.127)
		(layer "In2.Cu")
		(net "PWRGD_PVCCINFAON_CPU0")
	)
	(segment
		(start 174.555658 -118.175532)
		(end 174.129954 -117.749828)
		(width 0.127)
		(layer "In2.Cu")
		(net "PWRGD_PVCCINFAON_CPU0")
	)
	(segment
		(start 104.83088 -94.33433)
		(end 105.857548 -93.307662)
		(width 0.127)
		(layer "In2.Cu")
		(net "PWRGD_PVCCINFAON_CPU0")
	)
	(segment
		(start 104.83088 -111.597948)
		(end 104.83088 -94.33433)
		(width 0.127)
		(layer "In2.Cu")
		(net "PWRGD_PVCCINFAON_CPU0")
	)
	(segment
		(start 171.10456 -121.51614)
		(end 168.572688 -121.51614)
		(width 0.127)
		(layer "In2.Cu")
		(net "PWRGD_PVCCINFAON_CPU0")
	)
	(segment
		(start 172.558456 -118.816628)
		(end 172.558456 -119.174514)
		(width 0.127)
		(layer "In2.Cu")
		(net "PWRGD_PVCCINFAON_CPU0")
	)
	(segment
		(start 174.129954 -117.749828)
		(end 173.625256 -117.749828)
		(width 0.127)
		(layer "In2.Cu")
		(net "PWRGD_PVCCINFAON_CPU0")
	)
	(segment
		(start 173.625256 -117.749828)
		(end 172.558456 -118.816628)
		(width 0.127)
		(layer "In2.Cu")
		(net "PWRGD_PVCCINFAON_CPU0")
	)
	(segment
		(start 172.558456 -119.174514)
		(end 172.352208 -119.380762)
		(width 0.127)
		(layer "In2.Cu")
		(net "PWRGD_PVCCINFAON_CPU0")
	)
	(segment
		(start 171.751752 -119.623332)
		(end 171.751752 -120.868948)
		(width 0.127)
		(layer "In2.Cu")
		(net "PWRGD_PVCCINFAON_CPU0")
	)
	(segment
		(start 172.352208 -119.380762)
		(end 171.994322 -119.380762)
		(width 0.127)
		(layer "In2.Cu")
		(net "PWRGD_PVCCINFAON_CPU0")
	)
	(segment
		(start 171.751752 -120.868948)
		(end 171.10456 -121.51614)
		(width 0.127)
		(layer "In2.Cu")
		(net "PWRGD_PVCCINFAON_CPU0")
	)
	(segment
		(start 168.572688 -121.51614)
		(end 166.42588 -123.662948)
		(width 0.127)
		(layer "In2.Cu")
		(net "PWRGD_PVCCINFAON_CPU0")
	)
	(segment
		(start 444.344044 -125.824996)
		(end 442.946028 -127.223012)
		(width 0.127)
		(layer "In13.Cu")
		(net "PWRGD_PVCCINFAON_CPU0")
	)
	(segment
		(start 207.476852 -122.088148)
		(end 208.3816 -121.1834)
		(width 0.127)
		(layer "In13.Cu")
		(net "PWRGD_PVCCINFAON_CPU0")
	)
	(segment
		(start 438.168288 -127.223012)
		(end 434.300376 -131.090924)
		(width 0.127)
		(layer "In13.Cu")
		(net "PWRGD_PVCCINFAON_CPU0")
	)
	(segment
		(start 252.68174 -122.672348)
		(end 416.61842 -122.672348)
		(width 0.127)
		(layer "In13.Cu")
		(net "PWRGD_PVCCINFAON_CPU0")
	)
	(segment
		(start 172.907452 -123.726448)
		(end 174.36338 -123.726448)
		(width 0.127)
		(layer "In13.Cu")
		(net "PWRGD_PVCCINFAON_CPU0")
	)
	(segment
		(start 416.61842 -122.672348)
		(end 425.61002 -113.680748)
		(width 0.127)
		(layer "In13.Cu")
		(net "PWRGD_PVCCINFAON_CPU0")
	)
	(segment
		(start 172.41774 -124.21616)
		(end 172.907452 -123.726448)
		(width 0.127)
		(layer "In13.Cu")
		(net "PWRGD_PVCCINFAON_CPU0")
	)
	(segment
		(start 179.35448 -125.237748)
		(end 180.98008 -123.612148)
		(width 0.127)
		(layer "In13.Cu")
		(net "PWRGD_PVCCINFAON_CPU0")
	)
	(segment
		(start 444.344044 -117.936264)
		(end 444.344044 -125.824996)
		(width 0.127)
		(layer "In13.Cu")
		(net "PWRGD_PVCCINFAON_CPU0")
	)
	(segment
		(start 425.61002 -113.680748)
		(end 440.088528 -113.680748)
		(width 0.127)
		(layer "In13.Cu")
		(net "PWRGD_PVCCINFAON_CPU0")
	)
	(segment
		(start 223.8883 -114.158268)
		(end 240.31194 -114.158268)
		(width 0.127)
		(layer "In13.Cu")
		(net "PWRGD_PVCCINFAON_CPU0")
	)
	(segment
		(start 174.36338 -123.726448)
		(end 174.55388 -123.916948)
		(width 0.127)
		(layer "In13.Cu")
		(net "PWRGD_PVCCINFAON_CPU0")
	)
	(segment
		(start 194.48272 -123.612148)
		(end 196.00672 -122.088148)
		(width 0.127)
		(layer "In13.Cu")
		(net "PWRGD_PVCCINFAON_CPU0")
	)
	(segment
		(start 208.3816 -121.1834)
		(end 210.058 -121.1834)
		(width 0.127)
		(layer "In13.Cu")
		(net "PWRGD_PVCCINFAON_CPU0")
	)
	(segment
		(start 440.088528 -113.680748)
		(end 444.344044 -117.936264)
		(width 0.127)
		(layer "In13.Cu")
		(net "PWRGD_PVCCINFAON_CPU0")
	)
	(segment
		(start 174.55388 -123.916948)
		(end 176.86528 -123.916948)
		(width 0.127)
		(layer "In13.Cu")
		(net "PWRGD_PVCCINFAON_CPU0")
	)
	(segment
		(start 176.86528 -123.916948)
		(end 178.18608 -125.237748)
		(width 0.127)
		(layer "In13.Cu")
		(net "PWRGD_PVCCINFAON_CPU0")
	)
	(segment
		(start 166.48938 -123.726448)
		(end 168.57472 -123.726448)
		(width 0.127)
		(layer "In13.Cu")
		(net "PWRGD_PVCCINFAON_CPU0")
	)
	(segment
		(start 219.022168 -119.0244)
		(end 223.8883 -114.158268)
		(width 0.127)
		(layer "In13.Cu")
		(net "PWRGD_PVCCINFAON_CPU0")
	)
	(segment
		(start 168.57472 -123.726448)
		(end 169.064432 -124.21616)
		(width 0.127)
		(layer "In13.Cu")
		(net "PWRGD_PVCCINFAON_CPU0")
	)
	(segment
		(start 180.98008 -123.612148)
		(end 194.48272 -123.612148)
		(width 0.127)
		(layer "In13.Cu")
		(net "PWRGD_PVCCINFAON_CPU0")
	)
	(segment
		(start 178.18608 -125.237748)
		(end 179.35448 -125.237748)
		(width 0.127)
		(layer "In13.Cu")
		(net "PWRGD_PVCCINFAON_CPU0")
	)
	(segment
		(start 212.217 -119.0244)
		(end 219.022168 -119.0244)
		(width 0.127)
		(layer "In13.Cu")
		(net "PWRGD_PVCCINFAON_CPU0")
	)
	(segment
		(start 442.946028 -127.223012)
		(end 438.168288 -127.223012)
		(width 0.127)
		(layer "In13.Cu")
		(net "PWRGD_PVCCINFAON_CPU0")
	)
	(segment
		(start 246.85498 -116.845588)
		(end 252.68174 -122.672348)
		(width 0.127)
		(layer "In13.Cu")
		(net "PWRGD_PVCCINFAON_CPU0")
	)
	(segment
		(start 242.99926 -116.845588)
		(end 246.85498 -116.845588)
		(width 0.127)
		(layer "In13.Cu")
		(net "PWRGD_PVCCINFAON_CPU0")
	)
	(segment
		(start 169.064432 -124.21616)
		(end 172.41774 -124.21616)
		(width 0.127)
		(layer "In13.Cu")
		(net "PWRGD_PVCCINFAON_CPU0")
	)
	(segment
		(start 166.42588 -123.662948)
		(end 166.48938 -123.726448)
		(width 0.127)
		(layer "In13.Cu")
		(net "PWRGD_PVCCINFAON_CPU0")
	)
	(segment
		(start 240.31194 -114.158268)
		(end 242.99926 -116.845588)
		(width 0.127)
		(layer "In13.Cu")
		(net "PWRGD_PVCCINFAON_CPU0")
	)
	(segment
		(start 196.00672 -122.088148)
		(end 207.476852 -122.088148)
		(width 0.127)
		(layer "In13.Cu")
		(net "PWRGD_PVCCINFAON_CPU0")
	)
	(segment
		(start 210.058 -121.1834)
		(end 212.217 -119.0244)
		(width 0.127)
		(layer "In13.Cu")
		(net "PWRGD_PVCCINFAON_CPU0")
	)
	(segment
		(start 148.69668 -117.38102)
		(end 148.69668 -118.704868)
		(width 0.127)
		(layer "In15.Cu")
		(net "PWRGD_PVCCINFAON_CPU0")
	)
	(segment
		(start 131.015232 -113.629948)
		(end 132.03428 -112.6109)
		(width 0.127)
		(layer "In15.Cu")
		(net "PWRGD_PVCCINFAON_CPU0")
	)
	(segment
		(start 142.998952 -113.769648)
		(end 144.497552 -115.268248)
		(width 0.127)
		(layer "In15.Cu")
		(net "PWRGD_PVCCINFAON_CPU0")
	)
	(segment
		(start 134.68858 -112.6109)
		(end 134.9248 -112.84712)
		(width 0.127)
		(layer "In15.Cu")
		(net "PWRGD_PVCCINFAON_CPU0")
	)
	(segment
		(start 104.83088 -111.597948)
		(end 106.86288 -113.629948)
		(width 0.127)
		(layer "In15.Cu")
		(net "PWRGD_PVCCINFAON_CPU0")
	)
	(segment
		(start 137.14222 -113.769648)
		(end 142.998952 -113.769648)
		(width 0.127)
		(layer "In15.Cu")
		(net "PWRGD_PVCCINFAON_CPU0")
	)
	(segment
		(start 146.583908 -115.268248)
		(end 148.69668 -117.38102)
		(width 0.127)
		(layer "In15.Cu")
		(net "PWRGD_PVCCINFAON_CPU0")
	)
	(segment
		(start 162.541712 -125.733048)
		(end 162.818572 -125.456188)
		(width 0.127)
		(layer "In15.Cu")
		(net "PWRGD_PVCCINFAON_CPU0")
	)
	(segment
		(start 144.497552 -115.268248)
		(end 146.583908 -115.268248)
		(width 0.127)
		(layer "In15.Cu")
		(net "PWRGD_PVCCINFAON_CPU0")
	)
	(segment
		(start 151.00808 -121.016268)
		(end 152.25268 -121.016268)
		(width 0.127)
		(layer "In15.Cu")
		(net "PWRGD_PVCCINFAON_CPU0")
	)
	(segment
		(start 162.818572 -125.456188)
		(end 163.46424 -125.456188)
		(width 0.127)
		(layer "In15.Cu")
		(net "PWRGD_PVCCINFAON_CPU0")
	)
	(segment
		(start 136.219692 -112.84712)
		(end 137.14222 -113.769648)
		(width 0.127)
		(layer "In15.Cu")
		(net "PWRGD_PVCCINFAON_CPU0")
	)
	(segment
		(start 148.69668 -118.704868)
		(end 151.00808 -121.016268)
		(width 0.127)
		(layer "In15.Cu")
		(net "PWRGD_PVCCINFAON_CPU0")
	)
	(segment
		(start 163.46424 -125.456188)
		(end 165.25748 -123.662948)
		(width 0.127)
		(layer "In15.Cu")
		(net "PWRGD_PVCCINFAON_CPU0")
	)
	(segment
		(start 132.03428 -112.6109)
		(end 134.68858 -112.6109)
		(width 0.127)
		(layer "In15.Cu")
		(net "PWRGD_PVCCINFAON_CPU0")
	)
	(segment
		(start 134.9248 -112.84712)
		(end 136.219692 -112.84712)
		(width 0.127)
		(layer "In15.Cu")
		(net "PWRGD_PVCCINFAON_CPU0")
	)
	(segment
		(start 152.25268 -121.016268)
		(end 156.96946 -125.733048)
		(width 0.127)
		(layer "In15.Cu")
		(net "PWRGD_PVCCINFAON_CPU0")
	)
	(segment
		(start 156.96946 -125.733048)
		(end 162.541712 -125.733048)
		(width 0.127)
		(layer "In15.Cu")
		(net "PWRGD_PVCCINFAON_CPU0")
	)
	(segment
		(start 165.25748 -123.662948)
		(end 166.42588 -123.662948)
		(width 0.127)
		(layer "In15.Cu")
		(net "PWRGD_PVCCINFAON_CPU0")
	)
	(segment
		(start 106.86288 -113.629948)
		(end 131.015232 -113.629948)
		(width 0.127)
		(layer "In15.Cu")
		(net "PWRGD_PVCCINFAON_CPU0")
	)
	(segment
		(start 103.877872 -358.248458)
		(end 103.673656 -358.452674)
		(width 0.12954)
		(layer "F.Cu")
		(net "PWRGD_PVCCFA_EHV_FIVRA_CPU1_R")
	)
	(segment
		(start 105.70337 -358.248458)
		(end 103.877872 -358.248458)
		(width 0.12954)
		(layer "F.Cu")
		(net "PWRGD_PVCCFA_EHV_FIVRA_CPU1_R")
	)
	(segment
		(start 103.673656 -358.452674)
		(end 103.244396 -358.452674)
		(width 0.12954)
		(layer "F.Cu")
		(net "PWRGD_PVCCFA_EHV_FIVRA_CPU1_R")
	)
	(via
		(at 103.110284 -357.87457)
		(size 0.6604)
		(drill 0.3302)
		(layers "F.Cu" "B.Cu")
		(net "PWRGD_PVCCFA_EHV_FIVRA_CPU1_R")
	)
	(via
		(at 103.877872 -358.248458)
		(size 0.508)
		(drill 0.254)
		(layers "F.Cu" "B.Cu")
		(net "PWRGD_PVCCFA_EHV_FIVRA_CPU1_R")
	)
	(segment
		(start 101.19614 -359.788714)
		(end 100.706936 -359.788714)
		(width 0.12954)
		(layer "B.Cu")
		(net "PWRGD_PVCCFA_EHV_FIVRA_CPU1_R")
	)
	(segment
		(start 103.110284 -357.87457)
		(end 101.19614 -359.788714)
		(width 0.12954)
		(layer "B.Cu")
		(net "PWRGD_PVCCFA_EHV_FIVRA_CPU1_R")
	)
	(segment
		(start 100.706936 -358.899714)
		(end 100.706936 -359.788714)
		(width 0.12954)
		(layer "B.Cu")
		(net "PWRGD_PVCCFA_EHV_FIVRA_CPU1_R")
	)
	(segment
		(start 103.503984 -357.87457)
		(end 103.110284 -357.87457)
		(width 0.12954)
		(layer "B.Cu")
		(net "PWRGD_PVCCFA_EHV_FIVRA_CPU1_R")
	)
	(segment
		(start 103.877872 -358.248458)
		(end 103.503984 -357.87457)
		(width 0.12954)
		(layer "B.Cu")
		(net "PWRGD_PVCCFA_EHV_FIVRA_CPU1_R")
	)
	(segment
		(start 87.734394 -95.738442)
		(end 87.480394 -95.992442)
		(width 0.12954)
		(layer "F.Cu")
		(net "PWRGD_PVCCFA_EHV_FIVRA_CPU1")
	)
	(segment
		(start 87.480394 -95.992442)
		(end 86.526116 -95.992442)
		(width 0.12954)
		(layer "F.Cu")
		(net "PWRGD_PVCCFA_EHV_FIVRA_CPU1")
	)
	(segment
		(start 175.755554 -119.375428)
		(end 175.355504 -119.775478)
		(width 0.12954)
		(layer "F.Cu")
		(net "PWRGD_PVCCFA_EHV_FIVRA_CPU1")
	)
	(via
		(at 99.292156 -358.899714)
		(size 0.508)
		(drill 0.254)
		(layers "F.Cu" "B.Cu")
		(net "PWRGD_PVCCFA_EHV_FIVRA_CPU1")
	)
	(via
		(at 208.33588 -149.062948)
		(size 0.508)
		(drill 0.254)
		(layers "F.Cu" "B.Cu")
		(net "PWRGD_PVCCFA_EHV_FIVRA_CPU1")
	)
	(via
		(at 115.246658 -131.581144)
		(size 0.508)
		(drill 0.254)
		(layers "F.Cu" "B.Cu")
		(net "PWRGD_PVCCFA_EHV_FIVRA_CPU1")
	)
	(via
		(at 87.734394 -95.738442)
		(size 0.508)
		(drill 0.254)
		(layers "F.Cu" "B.Cu")
		(net "PWRGD_PVCCFA_EHV_FIVRA_CPU1")
	)
	(via
		(at 95.55988 -110.835948)
		(size 0.508)
		(drill 0.254)
		(layers "F.Cu" "B.Cu")
		(net "PWRGD_PVCCFA_EHV_FIVRA_CPU1")
	)
	(via
		(at 173.71822 -394.350748)
		(size 0.508)
		(drill 0.254)
		(layers "F.Cu" "B.Cu")
		(net "PWRGD_PVCCFA_EHV_FIVRA_CPU1")
	)
	(via
		(at 102.84968 -390.997948)
		(size 0.508)
		(drill 0.254)
		(layers "F.Cu" "B.Cu")
		(net "PWRGD_PVCCFA_EHV_FIVRA_CPU1")
	)
	(via
		(at 231.06888 -201.894948)
		(size 0.508)
		(drill 0.254)
		(layers "F.Cu" "B.Cu")
		(net "PWRGD_PVCCFA_EHV_FIVRA_CPU1")
	)
	(via
		(at 175.355504 -119.775478)
		(size 0.4572)
		(drill 0.254)
		(layers "F.Cu" "B.Cu")
		(net "PWRGD_PVCCFA_EHV_FIVRA_CPU1")
	)
	(segment
		(start 99.906836 -358.899714)
		(end 99.292156 -358.899714)
		(width 0.12954)
		(layer "B.Cu")
		(net "PWRGD_PVCCFA_EHV_FIVRA_CPU1")
	)
	(segment
		(start 89.453974 -95.738442)
		(end 87.734394 -95.738442)
		(width 0.127)
		(layer "In2.Cu")
		(net "PWRGD_PVCCFA_EHV_FIVRA_CPU1")
	)
	(segment
		(start 93.90888 -110.835948)
		(end 91.06408 -107.991148)
		(width 0.127)
		(layer "In2.Cu")
		(net "PWRGD_PVCCFA_EHV_FIVRA_CPU1")
	)
	(segment
		(start 95.55988 -110.835948)
		(end 93.90888 -110.835948)
		(width 0.127)
		(layer "In2.Cu")
		(net "PWRGD_PVCCFA_EHV_FIVRA_CPU1")
	)
	(segment
		(start 91.06408 -97.348548)
		(end 89.453974 -95.738442)
		(width 0.127)
		(layer "In2.Cu")
		(net "PWRGD_PVCCFA_EHV_FIVRA_CPU1")
	)
	(segment
		(start 91.06408 -107.991148)
		(end 91.06408 -97.348548)
		(width 0.127)
		(layer "In2.Cu")
		(net "PWRGD_PVCCFA_EHV_FIVRA_CPU1")
	)
	(segment
		(start 228.40188 -240.248948)
		(end 228.40188 -204.561948)
		(width 0.127)
		(layer "In4.Cu")
		(net "PWRGD_PVCCFA_EHV_FIVRA_CPU1")
	)
	(segment
		(start 197.27926 -361.696508)
		(end 211.41182 -347.563948)
		(width 0.127)
		(layer "In4.Cu")
		(net "PWRGD_PVCCFA_EHV_FIVRA_CPU1")
	)
	(segment
		(start 173.71822 -394.350748)
		(end 174.34306 -393.725908)
		(width 0.127)
		(layer "In4.Cu")
		(net "PWRGD_PVCCFA_EHV_FIVRA_CPU1")
	)
	(segment
		(start 221.16288 -247.487948)
		(end 228.40188 -240.248948)
		(width 0.127)
		(layer "In4.Cu")
		(net "PWRGD_PVCCFA_EHV_FIVRA_CPU1")
	)
	(segment
		(start 197.27926 -369.773454)
		(end 197.27926 -361.696508)
		(width 0.127)
		(layer "In4.Cu")
		(net "PWRGD_PVCCFA_EHV_FIVRA_CPU1")
	)
	(segment
		(start 174.34306 -386.425694)
		(end 183.304434 -377.46432)
		(width 0.127)
		(layer "In4.Cu")
		(net "PWRGD_PVCCFA_EHV_FIVRA_CPU1")
	)
	(segment
		(start 189.588394 -377.46432)
		(end 197.27926 -369.773454)
		(width 0.127)
		(layer "In4.Cu")
		(net "PWRGD_PVCCFA_EHV_FIVRA_CPU1")
	)
	(segment
		(start 183.304434 -377.46432)
		(end 189.588394 -377.46432)
		(width 0.127)
		(layer "In4.Cu")
		(net "PWRGD_PVCCFA_EHV_FIVRA_CPU1")
	)
	(segment
		(start 102.84968 -390.997948)
		(end 96.04248 -384.190748)
		(width 0.127)
		(layer "In4.Cu")
		(net "PWRGD_PVCCFA_EHV_FIVRA_CPU1")
	)
	(segment
		(start 96.04248 -362.14939)
		(end 99.292156 -358.899714)
		(width 0.127)
		(layer "In4.Cu")
		(net "PWRGD_PVCCFA_EHV_FIVRA_CPU1")
	)
	(segment
		(start 96.04248 -384.190748)
		(end 96.04248 -362.14939)
		(width 0.127)
		(layer "In4.Cu")
		(net "PWRGD_PVCCFA_EHV_FIVRA_CPU1")
	)
	(segment
		(start 174.34306 -393.725908)
		(end 174.34306 -386.425694)
		(width 0.127)
		(layer "In4.Cu")
		(net "PWRGD_PVCCFA_EHV_FIVRA_CPU1")
	)
	(segment
		(start 228.40188 -204.561948)
		(end 231.06888 -201.894948)
		(width 0.127)
		(layer "In4.Cu")
		(net "PWRGD_PVCCFA_EHV_FIVRA_CPU1")
	)
	(segment
		(start 221.16288 -341.721948)
		(end 221.16288 -247.487948)
		(width 0.127)
		(layer "In4.Cu")
		(net "PWRGD_PVCCFA_EHV_FIVRA_CPU1")
	)
	(segment
		(start 215.32088 -347.563948)
		(end 221.16288 -341.721948)
		(width 0.127)
		(layer "In4.Cu")
		(net "PWRGD_PVCCFA_EHV_FIVRA_CPU1")
	)
	(segment
		(start 211.41182 -347.563948)
		(end 215.32088 -347.563948)
		(width 0.127)
		(layer "In4.Cu")
		(net "PWRGD_PVCCFA_EHV_FIVRA_CPU1")
	)
	(segment
		(start 210.49488 -150.447756)
		(end 209.110072 -149.062948)
		(width 0.127)
		(layer "In11.Cu")
		(net "PWRGD_PVCCFA_EHV_FIVRA_CPU1")
	)
	(segment
		(start 105.08488 -393.233148)
		(end 115.362228 -393.233148)
		(width 0.127)
		(layer "In11.Cu")
		(net "PWRGD_PVCCFA_EHV_FIVRA_CPU1")
	)
	(segment
		(start 231.06888 -201.894948)
		(end 230.94188 -202.021948)
		(width 0.127)
		(layer "In11.Cu")
		(net "PWRGD_PVCCFA_EHV_FIVRA_CPU1")
	)
	(segment
		(start 115.71224 -131.115562)
		(end 115.71224 -130.454908)
		(width 0.127)
		(layer "In11.Cu")
		(net "PWRGD_PVCCFA_EHV_FIVRA_CPU1")
	)
	(segment
		(start 209.110072 -149.062948)
		(end 208.33588 -149.062948)
		(width 0.127)
		(layer "In11.Cu")
		(net "PWRGD_PVCCFA_EHV_FIVRA_CPU1")
	)
	(segment
		(start 211.71408 -159.522668)
		(end 211.71408 -153.411428)
		(width 0.127)
		(layer "In11.Cu")
		(net "PWRGD_PVCCFA_EHV_FIVRA_CPU1")
	)
	(segment
		(start 167.20312 -393.88034)
		(end 173.247812 -393.88034)
		(width 0.127)
		(layer "In11.Cu")
		(net "PWRGD_PVCCFA_EHV_FIVRA_CPU1")
	)
	(segment
		(start 98.20148 -112.944148)
		(end 98.20148 -110.505748)
		(width 0.127)
		(layer "In11.Cu")
		(net "PWRGD_PVCCFA_EHV_FIVRA_CPU1")
	)
	(segment
		(start 173.247812 -393.88034)
		(end 173.71822 -394.350748)
		(width 0.127)
		(layer "In11.Cu")
		(net "PWRGD_PVCCFA_EHV_FIVRA_CPU1")
	)
	(segment
		(start 115.71224 -130.454908)
		(end 98.20148 -112.944148)
		(width 0.127)
		(layer "In11.Cu")
		(net "PWRGD_PVCCFA_EHV_FIVRA_CPU1")
	)
	(segment
		(start 223.929194 -196.279262)
		(end 223.929194 -171.737782)
		(width 0.127)
		(layer "In11.Cu")
		(net "PWRGD_PVCCFA_EHV_FIVRA_CPU1")
	)
	(segment
		(start 210.49488 -152.192228)
		(end 210.49488 -150.447756)
		(width 0.127)
		(layer "In11.Cu")
		(net "PWRGD_PVCCFA_EHV_FIVRA_CPU1")
	)
	(segment
		(start 166.910512 -394.172948)
		(end 167.20312 -393.88034)
		(width 0.127)
		(layer "In11.Cu")
		(net "PWRGD_PVCCFA_EHV_FIVRA_CPU1")
	)
	(segment
		(start 229.67188 -202.021948)
		(end 223.929194 -196.279262)
		(width 0.127)
		(layer "In11.Cu")
		(net "PWRGD_PVCCFA_EHV_FIVRA_CPU1")
	)
	(segment
		(start 223.929194 -171.737782)
		(end 211.71408 -159.522668)
		(width 0.127)
		(layer "In11.Cu")
		(net "PWRGD_PVCCFA_EHV_FIVRA_CPU1")
	)
	(segment
		(start 115.246658 -131.581144)
		(end 115.71224 -131.115562)
		(width 0.127)
		(layer "In11.Cu")
		(net "PWRGD_PVCCFA_EHV_FIVRA_CPU1")
	)
	(segment
		(start 98.20148 -110.505748)
		(end 97.92208 -110.226348)
		(width 0.127)
		(layer "In11.Cu")
		(net "PWRGD_PVCCFA_EHV_FIVRA_CPU1")
	)
	(segment
		(start 97.92208 -110.226348)
		(end 96.16948 -110.226348)
		(width 0.127)
		(layer "In11.Cu")
		(net "PWRGD_PVCCFA_EHV_FIVRA_CPU1")
	)
	(segment
		(start 211.71408 -153.411428)
		(end 210.49488 -152.192228)
		(width 0.127)
		(layer "In11.Cu")
		(net "PWRGD_PVCCFA_EHV_FIVRA_CPU1")
	)
	(segment
		(start 230.94188 -202.021948)
		(end 229.67188 -202.021948)
		(width 0.127)
		(layer "In11.Cu")
		(net "PWRGD_PVCCFA_EHV_FIVRA_CPU1")
	)
	(segment
		(start 115.362228 -393.233148)
		(end 116.302028 -394.172948)
		(width 0.127)
		(layer "In11.Cu")
		(net "PWRGD_PVCCFA_EHV_FIVRA_CPU1")
	)
	(segment
		(start 96.16948 -110.226348)
		(end 95.55988 -110.835948)
		(width 0.127)
		(layer "In11.Cu")
		(net "PWRGD_PVCCFA_EHV_FIVRA_CPU1")
	)
	(segment
		(start 102.84968 -390.997948)
		(end 105.08488 -393.233148)
		(width 0.127)
		(layer "In11.Cu")
		(net "PWRGD_PVCCFA_EHV_FIVRA_CPU1")
	)
	(segment
		(start 116.302028 -394.172948)
		(end 166.910512 -394.172948)
		(width 0.127)
		(layer "In11.Cu")
		(net "PWRGD_PVCCFA_EHV_FIVRA_CPU1")
	)
	(segment
		(start 116.29136 -131.581144)
		(end 116.831364 -132.121148)
		(width 0.127)
		(layer "In13.Cu")
		(net "PWRGD_PVCCFA_EHV_FIVRA_CPU1")
	)
	(segment
		(start 154.815794 -141.722348)
		(end 204.75448 -141.722348)
		(width 0.127)
		(layer "In13.Cu")
		(net "PWRGD_PVCCFA_EHV_FIVRA_CPU1")
	)
	(segment
		(start 208.486756 -149.062948)
		(end 208.33588 -149.062948)
		(width 0.127)
		(layer "In13.Cu")
		(net "PWRGD_PVCCFA_EHV_FIVRA_CPU1")
	)
	(segment
		(start 208.949036 -148.600668)
		(end 208.486756 -149.062948)
		(width 0.127)
		(layer "In13.Cu")
		(net "PWRGD_PVCCFA_EHV_FIVRA_CPU1")
	)
	(segment
		(start 116.831364 -132.121148)
		(end 132.66928 -132.121148)
		(width 0.127)
		(layer "In13.Cu")
		(net "PWRGD_PVCCFA_EHV_FIVRA_CPU1")
	)
	(segment
		(start 146.773646 -133.6802)
		(end 154.815794 -141.722348)
		(width 0.127)
		(layer "In13.Cu")
		(net "PWRGD_PVCCFA_EHV_FIVRA_CPU1")
	)
	(segment
		(start 115.246658 -131.581144)
		(end 116.29136 -131.581144)
		(width 0.127)
		(layer "In13.Cu")
		(net "PWRGD_PVCCFA_EHV_FIVRA_CPU1")
	)
	(segment
		(start 132.66928 -132.121148)
		(end 134.228332 -133.6802)
		(width 0.127)
		(layer "In13.Cu")
		(net "PWRGD_PVCCFA_EHV_FIVRA_CPU1")
	)
	(segment
		(start 204.75448 -141.722348)
		(end 208.949036 -145.916904)
		(width 0.127)
		(layer "In13.Cu")
		(net "PWRGD_PVCCFA_EHV_FIVRA_CPU1")
	)
	(segment
		(start 134.228332 -133.6802)
		(end 146.773646 -133.6802)
		(width 0.127)
		(layer "In13.Cu")
		(net "PWRGD_PVCCFA_EHV_FIVRA_CPU1")
	)
	(segment
		(start 208.949036 -145.916904)
		(end 208.949036 -148.600668)
		(width 0.127)
		(layer "In13.Cu")
		(net "PWRGD_PVCCFA_EHV_FIVRA_CPU1")
	)
	(segment
		(start 175.355504 -119.775478)
		(end 174.955454 -120.175528)
		(width 0.127)
		(layer "In15.Cu")
		(net "PWRGD_PVCCFA_EHV_FIVRA_CPU1")
	)
	(segment
		(start 100.34778 -116.766848)
		(end 95.55988 -111.978948)
		(width 0.127)
		(layer "In15.Cu")
		(net "PWRGD_PVCCFA_EHV_FIVRA_CPU1")
	)
	(segment
		(start 163.355782 -126.751588)
		(end 163.078922 -127.028448)
		(width 0.127)
		(layer "In15.Cu")
		(net "PWRGD_PVCCFA_EHV_FIVRA_CPU1")
	)
	(segment
		(start 156.187648 -127.028448)
		(end 154.979624 -125.820424)
		(width 0.127)
		(layer "In15.Cu")
		(net "PWRGD_PVCCFA_EHV_FIVRA_CPU1")
	)
	(segment
		(start 154.979624 -125.820424)
		(end 150.551896 -125.820424)
		(width 0.127)
		(layer "In15.Cu")
		(net "PWRGD_PVCCFA_EHV_FIVRA_CPU1")
	)
	(segment
		(start 133.838188 -116.766848)
		(end 100.34778 -116.766848)
		(width 0.127)
		(layer "In15.Cu")
		(net "PWRGD_PVCCFA_EHV_FIVRA_CPU1")
	)
	(segment
		(start 167.75938 -123.35256)
		(end 167.75938 -124.298456)
		(width 0.127)
		(layer "In15.Cu")
		(net "PWRGD_PVCCFA_EHV_FIVRA_CPU1")
	)
	(segment
		(start 171.563792 -120.970548)
		(end 171.01566 -121.51868)
		(width 0.127)
		(layer "In15.Cu")
		(net "PWRGD_PVCCFA_EHV_FIVRA_CPU1")
	)
	(segment
		(start 139.925552 -118.30558)
		(end 135.37692 -118.30558)
		(width 0.127)
		(layer "In15.Cu")
		(net "PWRGD_PVCCFA_EHV_FIVRA_CPU1")
	)
	(segment
		(start 171.01566 -121.51868)
		(end 169.59326 -121.51868)
		(width 0.127)
		(layer "In15.Cu")
		(net "PWRGD_PVCCFA_EHV_FIVRA_CPU1")
	)
	(segment
		(start 135.37692 -118.30558)
		(end 133.838188 -116.766848)
		(width 0.127)
		(layer "In15.Cu")
		(net "PWRGD_PVCCFA_EHV_FIVRA_CPU1")
	)
	(segment
		(start 149.3901 -124.658628)
		(end 146.2786 -124.658628)
		(width 0.127)
		(layer "In15.Cu")
		(net "PWRGD_PVCCFA_EHV_FIVRA_CPU1")
	)
	(segment
		(start 95.55988 -111.978948)
		(end 95.55988 -110.835948)
		(width 0.127)
		(layer "In15.Cu")
		(net "PWRGD_PVCCFA_EHV_FIVRA_CPU1")
	)
	(segment
		(start 172.34154 -120.970548)
		(end 171.563792 -120.970548)
		(width 0.127)
		(layer "In15.Cu")
		(net "PWRGD_PVCCFA_EHV_FIVRA_CPU1")
	)
	(segment
		(start 174.955454 -120.175528)
		(end 172.77334 -120.175528)
		(width 0.127)
		(layer "In15.Cu")
		(net "PWRGD_PVCCFA_EHV_FIVRA_CPU1")
	)
	(segment
		(start 165.306248 -126.751588)
		(end 163.355782 -126.751588)
		(width 0.127)
		(layer "In15.Cu")
		(net "PWRGD_PVCCFA_EHV_FIVRA_CPU1")
	)
	(segment
		(start 172.54982 -120.762268)
		(end 172.34154 -120.970548)
		(width 0.127)
		(layer "In15.Cu")
		(net "PWRGD_PVCCFA_EHV_FIVRA_CPU1")
	)
	(segment
		(start 146.2786 -124.658628)
		(end 139.925552 -118.30558)
		(width 0.127)
		(layer "In15.Cu")
		(net "PWRGD_PVCCFA_EHV_FIVRA_CPU1")
	)
	(segment
		(start 150.551896 -125.820424)
		(end 149.3901 -124.658628)
		(width 0.127)
		(layer "In15.Cu")
		(net "PWRGD_PVCCFA_EHV_FIVRA_CPU1")
	)
	(segment
		(start 172.77334 -120.175528)
		(end 172.54982 -120.399048)
		(width 0.127)
		(layer "In15.Cu")
		(net "PWRGD_PVCCFA_EHV_FIVRA_CPU1")
	)
	(segment
		(start 172.54982 -120.399048)
		(end 172.54982 -120.762268)
		(width 0.127)
		(layer "In15.Cu")
		(net "PWRGD_PVCCFA_EHV_FIVRA_CPU1")
	)
	(segment
		(start 163.078922 -127.028448)
		(end 156.187648 -127.028448)
		(width 0.127)
		(layer "In15.Cu")
		(net "PWRGD_PVCCFA_EHV_FIVRA_CPU1")
	)
	(segment
		(start 169.59326 -121.51868)
		(end 167.75938 -123.35256)
		(width 0.127)
		(layer "In15.Cu")
		(net "PWRGD_PVCCFA_EHV_FIVRA_CPU1")
	)
	(segment
		(start 167.75938 -124.298456)
		(end 165.306248 -126.751588)
		(width 0.127)
		(layer "In15.Cu")
		(net "PWRGD_PVCCFA_EHV_FIVRA_CPU1")
	)
	(segment
		(start 351.61347 -358.452674)
		(end 351.18421 -358.452674)
		(width 0.12954)
		(layer "F.Cu")
		(net "PWRGD_PVCCFA_EHV_FIVRA_CPU0_R")
	)
	(segment
		(start 351.817686 -358.248458)
		(end 351.61347 -358.452674)
		(width 0.12954)
		(layer "F.Cu")
		(net "PWRGD_PVCCFA_EHV_FIVRA_CPU0_R")
	)
	(segment
		(start 353.643184 -358.248458)
		(end 351.817686 -358.248458)
		(width 0.12954)
		(layer "F.Cu")
		(net "PWRGD_PVCCFA_EHV_FIVRA_CPU0_R")
	)
	(via
		(at 351.067878 -357.87965)
		(size 0.6604)
		(drill 0.3302)
		(layers "F.Cu" "B.Cu")
		(net "PWRGD_PVCCFA_EHV_FIVRA_CPU0_R")
	)
	(via
		(at 351.817686 -358.248458)
		(size 0.508)
		(drill 0.254)
		(layers "F.Cu" "B.Cu")
		(net "PWRGD_PVCCFA_EHV_FIVRA_CPU0_R")
	)
	(segment
		(start 349.616014 -357.87965)
		(end 348.64675 -358.848914)
		(width 0.12954)
		(layer "B.Cu")
		(net "PWRGD_PVCCFA_EHV_FIVRA_CPU0_R")
	)
	(segment
		(start 348.64675 -359.788714)
		(end 348.64675 -358.848914)
		(width 0.12954)
		(layer "B.Cu")
		(net "PWRGD_PVCCFA_EHV_FIVRA_CPU0_R")
	)
	(segment
		(start 351.448878 -357.87965)
		(end 351.067878 -357.87965)
		(width 0.12954)
		(layer "B.Cu")
		(net "PWRGD_PVCCFA_EHV_FIVRA_CPU0_R")
	)
	(segment
		(start 351.817686 -358.248458)
		(end 351.448878 -357.87965)
		(width 0.12954)
		(layer "B.Cu")
		(net "PWRGD_PVCCFA_EHV_FIVRA_CPU0_R")
	)
	(segment
		(start 351.067878 -357.87965)
		(end 349.616014 -357.87965)
		(width 0.12954)
		(layer "B.Cu")
		(net "PWRGD_PVCCFA_EHV_FIVRA_CPU0_R")
	)
	(segment
		(start 173.355762 -114.575336)
		(end 172.955712 -114.975386)
		(width 0.12954)
		(layer "F.Cu")
		(net "PWRGD_PVCCFA_EHV_FIVRA_CPU0")
	)
	(segment
		(start 87.480394 -92.888308)
		(end 86.526116 -92.888308)
		(width 0.12954)
		(layer "F.Cu")
		(net "PWRGD_PVCCFA_EHV_FIVRA_CPU0")
	)
	(segment
		(start 87.734394 -92.634308)
		(end 87.480394 -92.888308)
		(width 0.12954)
		(layer "F.Cu")
		(net "PWRGD_PVCCFA_EHV_FIVRA_CPU0")
	)
	(via
		(at 179.91074 -164.092128)
		(size 0.508)
		(drill 0.254)
		(layers "F.Cu" "B.Cu")
		(net "PWRGD_PVCCFA_EHV_FIVRA_CPU0")
	)
	(via
		(at 94.92488 -109.565948)
		(size 0.508)
		(drill 0.254)
		(layers "F.Cu" "B.Cu")
		(net "PWRGD_PVCCFA_EHV_FIVRA_CPU0")
	)
	(via
		(at 347.72092 -370.108988)
		(size 0.508)
		(drill 0.254)
		(layers "F.Cu" "B.Cu")
		(net "PWRGD_PVCCFA_EHV_FIVRA_CPU0")
	)
	(via
		(at 172.955712 -114.975386)
		(size 0.4572)
		(drill 0.254)
		(layers "F.Cu" "B.Cu")
		(net "PWRGD_PVCCFA_EHV_FIVRA_CPU0")
	)
	(via
		(at 347.443806 -360.48569)
		(size 0.508)
		(drill 0.254)
		(layers "F.Cu" "B.Cu")
		(net "PWRGD_PVCCFA_EHV_FIVRA_CPU0")
	)
	(via
		(at 87.734394 -92.634308)
		(size 0.508)
		(drill 0.254)
		(layers "F.Cu" "B.Cu")
		(net "PWRGD_PVCCFA_EHV_FIVRA_CPU0")
	)
	(segment
		(start 253.74854 -321.009772)
		(end 255.914398 -323.17563)
		(width 0.12954)
		(layer "B.Cu")
		(net "PWRGD_PVCCFA_EHV_FIVRA_CPU0")
	)
	(segment
		(start 232.46588 -174.793148)
		(end 244.17528 -174.793148)
		(width 0.12954)
		(layer "B.Cu")
		(net "PWRGD_PVCCFA_EHV_FIVRA_CPU0")
	)
	(segment
		(start 225.50628 -167.833548)
		(end 232.46588 -174.793148)
		(width 0.12954)
		(layer "B.Cu")
		(net "PWRGD_PVCCFA_EHV_FIVRA_CPU0")
	)
	(segment
		(start 276.242018 -343.08415)
		(end 276.242018 -367.15319)
		(width 0.12954)
		(layer "B.Cu")
		(net "PWRGD_PVCCFA_EHV_FIVRA_CPU0")
	)
	(segment
		(start 347.84665 -360.082846)
		(end 347.84665 -359.788714)
		(width 0.12954)
		(layer "B.Cu")
		(net "PWRGD_PVCCFA_EHV_FIVRA_CPU0")
	)
	(segment
		(start 179.91074 -164.092128)
		(end 180.47843 -164.092128)
		(width 0.12954)
		(layer "B.Cu")
		(net "PWRGD_PVCCFA_EHV_FIVRA_CPU0")
	)
	(segment
		(start 260.897878 -327.74001)
		(end 276.242018 -343.08415)
		(width 0.12954)
		(layer "B.Cu")
		(net "PWRGD_PVCCFA_EHV_FIVRA_CPU0")
	)
	(segment
		(start 276.242018 -367.15319)
		(end 287.989518 -378.90069)
		(width 0.12954)
		(layer "B.Cu")
		(net "PWRGD_PVCCFA_EHV_FIVRA_CPU0")
	)
	(segment
		(start 244.17528 -174.793148)
		(end 254.413258 -185.031126)
		(width 0.12954)
		(layer "B.Cu")
		(net "PWRGD_PVCCFA_EHV_FIVRA_CPU0")
	)
	(segment
		(start 182.32628 -167.833548)
		(end 225.50628 -167.833548)
		(width 0.12954)
		(layer "B.Cu")
		(net "PWRGD_PVCCFA_EHV_FIVRA_CPU0")
	)
	(segment
		(start 255.914398 -323.17563)
		(end 255.914398 -324.45325)
		(width 0.12954)
		(layer "B.Cu")
		(net "PWRGD_PVCCFA_EHV_FIVRA_CPU0")
	)
	(segment
		(start 338.929218 -378.90069)
		(end 347.72092 -370.108988)
		(width 0.12954)
		(layer "B.Cu")
		(net "PWRGD_PVCCFA_EHV_FIVRA_CPU0")
	)
	(segment
		(start 287.989518 -378.90069)
		(end 338.929218 -378.90069)
		(width 0.12954)
		(layer "B.Cu")
		(net "PWRGD_PVCCFA_EHV_FIVRA_CPU0")
	)
	(segment
		(start 180.47843 -164.092128)
		(end 180.77688 -164.390578)
		(width 0.12954)
		(layer "B.Cu")
		(net "PWRGD_PVCCFA_EHV_FIVRA_CPU0")
	)
	(segment
		(start 254.413258 -185.031126)
		(end 254.413258 -302.826928)
		(width 0.12954)
		(layer "B.Cu")
		(net "PWRGD_PVCCFA_EHV_FIVRA_CPU0")
	)
	(segment
		(start 253.74854 -303.491646)
		(end 253.74854 -321.009772)
		(width 0.12954)
		(layer "B.Cu")
		(net "PWRGD_PVCCFA_EHV_FIVRA_CPU0")
	)
	(segment
		(start 180.77688 -166.284148)
		(end 182.32628 -167.833548)
		(width 0.12954)
		(layer "B.Cu")
		(net "PWRGD_PVCCFA_EHV_FIVRA_CPU0")
	)
	(segment
		(start 180.77688 -164.390578)
		(end 180.77688 -166.284148)
		(width 0.12954)
		(layer "B.Cu")
		(net "PWRGD_PVCCFA_EHV_FIVRA_CPU0")
	)
	(segment
		(start 256.485898 -325.02475)
		(end 259.818378 -325.02475)
		(width 0.12954)
		(layer "B.Cu")
		(net "PWRGD_PVCCFA_EHV_FIVRA_CPU0")
	)
	(segment
		(start 259.818378 -325.02475)
		(end 260.897878 -326.10425)
		(width 0.12954)
		(layer "B.Cu")
		(net "PWRGD_PVCCFA_EHV_FIVRA_CPU0")
	)
	(segment
		(start 254.413258 -302.826928)
		(end 253.74854 -303.491646)
		(width 0.12954)
		(layer "B.Cu")
		(net "PWRGD_PVCCFA_EHV_FIVRA_CPU0")
	)
	(segment
		(start 260.897878 -326.10425)
		(end 260.897878 -327.74001)
		(width 0.12954)
		(layer "B.Cu")
		(net "PWRGD_PVCCFA_EHV_FIVRA_CPU0")
	)
	(segment
		(start 347.443806 -360.48569)
		(end 347.84665 -360.082846)
		(width 0.12954)
		(layer "B.Cu")
		(net "PWRGD_PVCCFA_EHV_FIVRA_CPU0")
	)
	(segment
		(start 255.914398 -324.45325)
		(end 256.485898 -325.02475)
		(width 0.12954)
		(layer "B.Cu")
		(net "PWRGD_PVCCFA_EHV_FIVRA_CPU0")
	)
	(segment
		(start 88.50884 -92.634308)
		(end 87.734394 -92.634308)
		(width 0.127)
		(layer "In2.Cu")
		(net "PWRGD_PVCCFA_EHV_FIVRA_CPU0")
	)
	(segment
		(start 91.49588 -95.621348)
		(end 88.50884 -92.634308)
		(width 0.127)
		(layer "In2.Cu")
		(net "PWRGD_PVCCFA_EHV_FIVRA_CPU0")
	)
	(segment
		(start 94.92488 -109.565948)
		(end 91.49588 -106.136948)
		(width 0.127)
		(layer "In2.Cu")
		(net "PWRGD_PVCCFA_EHV_FIVRA_CPU0")
	)
	(segment
		(start 91.49588 -106.136948)
		(end 91.49588 -95.621348)
		(width 0.127)
		(layer "In2.Cu")
		(net "PWRGD_PVCCFA_EHV_FIVRA_CPU0")
	)
	(segment
		(start 172.15739 -127.96139)
		(end 171.09948 -126.90348)
		(width 0.127)
		(layer "In11.Cu")
		(net "PWRGD_PVCCFA_EHV_FIVRA_CPU0")
	)
	(segment
		(start 171.945808 -118.573042)
		(end 172.361606 -118.573042)
		(width 0.127)
		(layer "In11.Cu")
		(net "PWRGD_PVCCFA_EHV_FIVRA_CPU0")
	)
	(segment
		(start 172.56887 -128.662938)
		(end 172.15739 -128.251458)
		(width 0.127)
		(layer "In11.Cu")
		(net "PWRGD_PVCCFA_EHV_FIVRA_CPU0")
	)
	(segment
		(start 179.35956 -163.540948)
		(end 179.35956 -159.177228)
		(width 0.127)
		(layer "In11.Cu")
		(net "PWRGD_PVCCFA_EHV_FIVRA_CPU0")
	)
	(segment
		(start 171.75226 -121.793)
		(end 171.75226 -118.76659)
		(width 0.127)
		(layer "In11.Cu")
		(net "PWRGD_PVCCFA_EHV_FIVRA_CPU0")
	)
	(segment
		(start 172.55744 -118.377208)
		(end 172.55744 -115.373658)
		(width 0.127)
		(layer "In11.Cu")
		(net "PWRGD_PVCCFA_EHV_FIVRA_CPU0")
	)
	(segment
		(start 171.75226 -118.76659)
		(end 171.945808 -118.573042)
		(width 0.127)
		(layer "In11.Cu")
		(net "PWRGD_PVCCFA_EHV_FIVRA_CPU0")
	)
	(segment
		(start 171.09948 -126.90348)
		(end 171.09948 -123.9012)
		(width 0.127)
		(layer "In11.Cu")
		(net "PWRGD_PVCCFA_EHV_FIVRA_CPU0")
	)
	(segment
		(start 179.91074 -164.092128)
		(end 179.35956 -163.540948)
		(width 0.127)
		(layer "In11.Cu")
		(net "PWRGD_PVCCFA_EHV_FIVRA_CPU0")
	)
	(segment
		(start 172.15739 -128.251458)
		(end 172.15739 -127.96139)
		(width 0.127)
		(layer "In11.Cu")
		(net "PWRGD_PVCCFA_EHV_FIVRA_CPU0")
	)
	(segment
		(start 171.9834 -123.01728)
		(end 171.9834 -122.02414)
		(width 0.127)
		(layer "In11.Cu")
		(net "PWRGD_PVCCFA_EHV_FIVRA_CPU0")
	)
	(segment
		(start 173.07687 -128.662938)
		(end 172.56887 -128.662938)
		(width 0.127)
		(layer "In11.Cu")
		(net "PWRGD_PVCCFA_EHV_FIVRA_CPU0")
	)
	(segment
		(start 173.41088 -153.228548)
		(end 173.41088 -128.996948)
		(width 0.127)
		(layer "In11.Cu")
		(net "PWRGD_PVCCFA_EHV_FIVRA_CPU0")
	)
	(segment
		(start 179.35956 -159.177228)
		(end 173.41088 -153.228548)
		(width 0.127)
		(layer "In11.Cu")
		(net "PWRGD_PVCCFA_EHV_FIVRA_CPU0")
	)
	(segment
		(start 171.09948 -123.9012)
		(end 171.9834 -123.01728)
		(width 0.127)
		(layer "In11.Cu")
		(net "PWRGD_PVCCFA_EHV_FIVRA_CPU0")
	)
	(segment
		(start 173.41088 -128.996948)
		(end 173.07687 -128.662938)
		(width 0.127)
		(layer "In11.Cu")
		(net "PWRGD_PVCCFA_EHV_FIVRA_CPU0")
	)
	(segment
		(start 171.9834 -122.02414)
		(end 171.75226 -121.793)
		(width 0.127)
		(layer "In11.Cu")
		(net "PWRGD_PVCCFA_EHV_FIVRA_CPU0")
	)
	(segment
		(start 172.55744 -115.373658)
		(end 172.955712 -114.975386)
		(width 0.127)
		(layer "In11.Cu")
		(net "PWRGD_PVCCFA_EHV_FIVRA_CPU0")
	)
	(segment
		(start 172.361606 -118.573042)
		(end 172.55744 -118.377208)
		(width 0.127)
		(layer "In11.Cu")
		(net "PWRGD_PVCCFA_EHV_FIVRA_CPU0")
	)
	(segment
		(start 127.828548 -109.25048)
		(end 145.688558 -109.25048)
		(width 0.127)
		(layer "In15.Cu")
		(net "PWRGD_PVCCFA_EHV_FIVRA_CPU0")
	)
	(segment
		(start 151.68753 -115.249452)
		(end 152.35174 -115.249452)
		(width 0.127)
		(layer "In15.Cu")
		(net "PWRGD_PVCCFA_EHV_FIVRA_CPU0")
	)
	(segment
		(start 172.555154 -114.574828)
		(end 172.955712 -114.975386)
		(width 0.127)
		(layer "In15.Cu")
		(net "PWRGD_PVCCFA_EHV_FIVRA_CPU0")
	)
	(segment
		(start 156.95676 -118.765828)
		(end 157.52318 -119.332248)
		(width 0.127)
		(layer "In15.Cu")
		(net "PWRGD_PVCCFA_EHV_FIVRA_CPU0")
	)
	(segment
		(start 111.33328 -109.464348)
		(end 112.43564 -110.566708)
		(width 0.127)
		(layer "In15.Cu")
		(net "PWRGD_PVCCFA_EHV_FIVRA_CPU0")
	)
	(segment
		(start 166.956486 -117.834918)
		(end 168.44518 -116.346224)
		(width 0.127)
		(layer "In15.Cu")
		(net "PWRGD_PVCCFA_EHV_FIVRA_CPU0")
	)
	(segment
		(start 168.44518 -115.553744)
		(end 169.424096 -114.574828)
		(width 0.127)
		(layer "In15.Cu")
		(net "PWRGD_PVCCFA_EHV_FIVRA_CPU0")
	)
	(segment
		(start 154.135836 -117.033548)
		(end 156.48178 -117.033548)
		(width 0.127)
		(layer "In15.Cu")
		(net "PWRGD_PVCCFA_EHV_FIVRA_CPU0")
	)
	(segment
		(start 169.424096 -114.574828)
		(end 172.555154 -114.574828)
		(width 0.127)
		(layer "In15.Cu")
		(net "PWRGD_PVCCFA_EHV_FIVRA_CPU0")
	)
	(segment
		(start 156.95676 -117.508528)
		(end 156.95676 -118.765828)
		(width 0.127)
		(layer "In15.Cu")
		(net "PWRGD_PVCCFA_EHV_FIVRA_CPU0")
	)
	(segment
		(start 101.09708 -109.464348)
		(end 111.33328 -109.464348)
		(width 0.127)
		(layer "In15.Cu")
		(net "PWRGD_PVCCFA_EHV_FIVRA_CPU0")
	)
	(segment
		(start 152.35174 -115.249452)
		(end 154.135836 -117.033548)
		(width 0.127)
		(layer "In15.Cu")
		(net "PWRGD_PVCCFA_EHV_FIVRA_CPU0")
	)
	(segment
		(start 164.666676 -119.332248)
		(end 166.164006 -117.834918)
		(width 0.127)
		(layer "In15.Cu")
		(net "PWRGD_PVCCFA_EHV_FIVRA_CPU0")
	)
	(segment
		(start 166.164006 -117.834918)
		(end 166.956486 -117.834918)
		(width 0.127)
		(layer "In15.Cu")
		(net "PWRGD_PVCCFA_EHV_FIVRA_CPU0")
	)
	(segment
		(start 100.61448 -109.946948)
		(end 101.09708 -109.464348)
		(width 0.127)
		(layer "In15.Cu")
		(net "PWRGD_PVCCFA_EHV_FIVRA_CPU0")
	)
	(segment
		(start 94.92488 -109.565948)
		(end 95.30588 -109.946948)
		(width 0.127)
		(layer "In15.Cu")
		(net "PWRGD_PVCCFA_EHV_FIVRA_CPU0")
	)
	(segment
		(start 347.443806 -361.211114)
		(end 347.443806 -360.48569)
		(width 0.127)
		(layer "In15.Cu")
		(net "PWRGD_PVCCFA_EHV_FIVRA_CPU0")
	)
	(segment
		(start 156.48178 -117.033548)
		(end 156.95676 -117.508528)
		(width 0.127)
		(layer "In15.Cu")
		(net "PWRGD_PVCCFA_EHV_FIVRA_CPU0")
	)
	(segment
		(start 347.72092 -370.108988)
		(end 349.20936 -368.620548)
		(width 0.127)
		(layer "In15.Cu")
		(net "PWRGD_PVCCFA_EHV_FIVRA_CPU0")
	)
	(segment
		(start 126.51232 -110.566708)
		(end 127.828548 -109.25048)
		(width 0.127)
		(layer "In15.Cu")
		(net "PWRGD_PVCCFA_EHV_FIVRA_CPU0")
	)
	(segment
		(start 112.43564 -110.566708)
		(end 126.51232 -110.566708)
		(width 0.127)
		(layer "In15.Cu")
		(net "PWRGD_PVCCFA_EHV_FIVRA_CPU0")
	)
	(segment
		(start 157.52318 -119.332248)
		(end 164.666676 -119.332248)
		(width 0.127)
		(layer "In15.Cu")
		(net "PWRGD_PVCCFA_EHV_FIVRA_CPU0")
	)
	(segment
		(start 95.30588 -109.946948)
		(end 100.61448 -109.946948)
		(width 0.127)
		(layer "In15.Cu")
		(net "PWRGD_PVCCFA_EHV_FIVRA_CPU0")
	)
	(segment
		(start 349.20936 -368.620548)
		(end 349.20936 -362.976668)
		(width 0.127)
		(layer "In15.Cu")
		(net "PWRGD_PVCCFA_EHV_FIVRA_CPU0")
	)
	(segment
		(start 168.44518 -116.346224)
		(end 168.44518 -115.553744)
		(width 0.127)
		(layer "In15.Cu")
		(net "PWRGD_PVCCFA_EHV_FIVRA_CPU0")
	)
	(segment
		(start 349.20936 -362.976668)
		(end 347.443806 -361.211114)
		(width 0.127)
		(layer "In15.Cu")
		(net "PWRGD_PVCCFA_EHV_FIVRA_CPU0")
	)
	(segment
		(start 145.688558 -109.25048)
		(end 151.68753 -115.249452)
		(width 0.127)
		(layer "In15.Cu")
		(net "PWRGD_PVCCFA_EHV_FIVRA_CPU0")
	)
	(segment
		(start 35.819334 -129.74193)
		(end 34.975292 -129.74193)
		(width 0.12954)
		(layer "F.Cu")
		(net "PWRGD_PVCCFA_EHV_CPU1_R")
	)
	(segment
		(start 34.883852 -129.83337)
		(end 34.461196 -129.83337)
		(width 0.12954)
		(layer "F.Cu")
		(net "PWRGD_PVCCFA_EHV_CPU1_R")
	)
	(segment
		(start 34.975292 -129.74193)
		(end 34.883852 -129.83337)
		(width 0.12954)
		(layer "F.Cu")
		(net "PWRGD_PVCCFA_EHV_CPU1_R")
	)
	(segment
		(start 35.897566 -129.663698)
		(end 35.819334 -129.74193)
		(width 0.12954)
		(layer "F.Cu")
		(net "PWRGD_PVCCFA_EHV_CPU1_R")
	)
	(via
		(at 34.398712 -129.619248)
		(size 0.6604)
		(drill 0.3302)
		(layers "F.Cu" "B.Cu")
		(net "PWRGD_PVCCFA_EHV_CPU1_R")
	)
	(via
		(at 35.897566 -129.663698)
		(size 0.508)
		(drill 0.254)
		(layers "F.Cu" "B.Cu")
		(net "PWRGD_PVCCFA_EHV_CPU1_R")
	)
	(segment
		(start 36.556188 -131.77774)
		(end 36.579302 -131.754626)
		(width 0.12954)
		(layer "B.Cu")
		(net "PWRGD_PVCCFA_EHV_CPU1_R")
	)
	(segment
		(start 35.897566 -130.12547)
		(end 35.897566 -129.663698)
		(width 0.12954)
		(layer "B.Cu")
		(net "PWRGD_PVCCFA_EHV_CPU1_R")
	)
	(segment
		(start 36.579302 -130.828034)
		(end 36.556188 -130.80492)
		(width 0.12954)
		(layer "B.Cu")
		(net "PWRGD_PVCCFA_EHV_CPU1_R")
	)
	(segment
		(start 35.462464 -129.663698)
		(end 35.897566 -129.663698)
		(width 0.12954)
		(layer "B.Cu")
		(net "PWRGD_PVCCFA_EHV_CPU1_R")
	)
	(segment
		(start 34.517076 -129.500884)
		(end 35.29965 -129.500884)
		(width 0.12954)
		(layer "B.Cu")
		(net "PWRGD_PVCCFA_EHV_CPU1_R")
	)
	(segment
		(start 34.398712 -129.619248)
		(end 34.517076 -129.500884)
		(width 0.12954)
		(layer "B.Cu")
		(net "PWRGD_PVCCFA_EHV_CPU1_R")
	)
	(segment
		(start 35.29965 -129.500884)
		(end 35.462464 -129.663698)
		(width 0.12954)
		(layer "B.Cu")
		(net "PWRGD_PVCCFA_EHV_CPU1_R")
	)
	(segment
		(start 36.556442 -131.777994)
		(end 36.556442 -132.783834)
		(width 0.12954)
		(layer "B.Cu")
		(net "PWRGD_PVCCFA_EHV_CPU1_R")
	)
	(segment
		(start 36.556188 -130.784092)
		(end 35.897566 -130.12547)
		(width 0.12954)
		(layer "B.Cu")
		(net "PWRGD_PVCCFA_EHV_CPU1_R")
	)
	(segment
		(start 36.556188 -130.80492)
		(end 36.556188 -130.784092)
		(width 0.12954)
		(layer "B.Cu")
		(net "PWRGD_PVCCFA_EHV_CPU1_R")
	)
	(segment
		(start 36.556188 -131.77774)
		(end 36.556442 -131.777994)
		(width 0.12954)
		(layer "B.Cu")
		(net "PWRGD_PVCCFA_EHV_CPU1_R")
	)
	(segment
		(start 36.579302 -131.754626)
		(end 36.579302 -130.828034)
		(width 0.12954)
		(layer "B.Cu")
		(net "PWRGD_PVCCFA_EHV_CPU1_R")
	)
	(segment
		(start 175.755554 -120.975374)
		(end 175.355504 -121.375424)
		(width 0.12954)
		(layer "F.Cu")
		(net "PWRGD_PVCCFA_EHV_CPU1")
	)
	(segment
		(start 83.646518 -95.992442)
		(end 84.626196 -95.992442)
		(width 0.12954)
		(layer "F.Cu")
		(net "PWRGD_PVCCFA_EHV_CPU1")
	)
	(segment
		(start 83.354418 -96.284542)
		(end 83.646518 -95.992442)
		(width 0.12954)
		(layer "F.Cu")
		(net "PWRGD_PVCCFA_EHV_CPU1")
	)
	(via
		(at 83.354418 -96.284542)
		(size 0.508)
		(drill 0.254)
		(layers "F.Cu" "B.Cu")
		(net "PWRGD_PVCCFA_EHV_CPU1")
	)
	(via
		(at 39.049198 -130.782822)
		(size 0.508)
		(drill 0.254)
		(layers "F.Cu" "B.Cu")
		(net "PWRGD_PVCCFA_EHV_CPU1")
	)
	(via
		(at 175.355504 -121.375424)
		(size 0.4572)
		(drill 0.254)
		(layers "F.Cu" "B.Cu")
		(net "PWRGD_PVCCFA_EHV_CPU1")
	)
	(via
		(at 53.22062 -108.252768)
		(size 0.508)
		(drill 0.254)
		(layers "F.Cu" "B.Cu")
		(net "PWRGD_PVCCFA_EHV_CPU1")
	)
	(via
		(at 92.89288 -111.902748)
		(size 0.508)
		(drill 0.254)
		(layers "F.Cu" "B.Cu")
		(net "PWRGD_PVCCFA_EHV_CPU1")
	)
	(segment
		(start 38.307518 -131.524502)
		(end 37.609526 -131.524502)
		(width 0.12954)
		(layer "B.Cu")
		(net "PWRGD_PVCCFA_EHV_CPU1")
	)
	(segment
		(start 39.049198 -130.782822)
		(end 38.307518 -131.524502)
		(width 0.12954)
		(layer "B.Cu")
		(net "PWRGD_PVCCFA_EHV_CPU1")
	)
	(segment
		(start 37.609526 -131.524502)
		(end 37.356288 -131.77774)
		(width 0.12954)
		(layer "B.Cu")
		(net "PWRGD_PVCCFA_EHV_CPU1")
	)
	(segment
		(start 92.89288 -111.902748)
		(end 90.09888 -109.108748)
		(width 0.127)
		(layer "In2.Cu")
		(net "PWRGD_PVCCFA_EHV_CPU1")
	)
	(segment
		(start 90.09888 -98.465894)
		(end 89.116408 -97.483422)
		(width 0.127)
		(layer "In2.Cu")
		(net "PWRGD_PVCCFA_EHV_CPU1")
	)
	(segment
		(start 89.116408 -97.483422)
		(end 85.83168 -97.483422)
		(width 0.127)
		(layer "In2.Cu")
		(net "PWRGD_PVCCFA_EHV_CPU1")
	)
	(segment
		(start 83.662012 -95.976948)
		(end 83.354418 -96.284542)
		(width 0.127)
		(layer "In2.Cu")
		(net "PWRGD_PVCCFA_EHV_CPU1")
	)
	(segment
		(start 90.09888 -109.108748)
		(end 90.09888 -98.465894)
		(width 0.127)
		(layer "In2.Cu")
		(net "PWRGD_PVCCFA_EHV_CPU1")
	)
	(segment
		(start 85.83168 -97.483422)
		(end 84.325206 -95.976948)
		(width 0.127)
		(layer "In2.Cu")
		(net "PWRGD_PVCCFA_EHV_CPU1")
	)
	(segment
		(start 84.325206 -95.976948)
		(end 83.662012 -95.976948)
		(width 0.127)
		(layer "In2.Cu")
		(net "PWRGD_PVCCFA_EHV_CPU1")
	)
	(segment
		(start 78.14056 -101.4984)
		(end 60.615068 -101.4984)
		(width 0.127)
		(layer "In6.Cu")
		(net "PWRGD_PVCCFA_EHV_CPU1")
	)
	(segment
		(start 83.354418 -96.284542)
		(end 78.14056 -101.4984)
		(width 0.127)
		(layer "In6.Cu")
		(net "PWRGD_PVCCFA_EHV_CPU1")
	)
	(segment
		(start 60.615068 -101.4984)
		(end 54.68112 -107.432348)
		(width 0.127)
		(layer "In6.Cu")
		(net "PWRGD_PVCCFA_EHV_CPU1")
	)
	(segment
		(start 54.68112 -107.432348)
		(end 54.04104 -107.432348)
		(width 0.127)
		(layer "In6.Cu")
		(net "PWRGD_PVCCFA_EHV_CPU1")
	)
	(segment
		(start 54.04104 -107.432348)
		(end 53.22062 -108.252768)
		(width 0.127)
		(layer "In6.Cu")
		(net "PWRGD_PVCCFA_EHV_CPU1")
	)
	(segment
		(start 38.71976 -129.466848)
		(end 38.839648 -129.586736)
		(width 0.127)
		(layer "In15.Cu")
		(net "PWRGD_PVCCFA_EHV_CPU1")
	)
	(segment
		(start 53.2638 -108.295948)
		(end 53.2638 -114.684048)
		(width 0.127)
		(layer "In15.Cu")
		(net "PWRGD_PVCCFA_EHV_CPU1")
	)
	(segment
		(start 38.839648 -129.586736)
		(end 39.049198 -130.092958)
		(width 0.127)
		(layer "In15.Cu")
		(net "PWRGD_PVCCFA_EHV_CPU1")
	)
	(segment
		(start 100.783136 -117.813328)
		(end 94.872556 -111.902748)
		(width 0.127)
		(layer "In15.Cu")
		(net "PWRGD_PVCCFA_EHV_CPU1")
	)
	(segment
		(start 174.81042 -122.720608)
		(end 174.24908 -123.281948)
		(width 0.127)
		(layer "In15.Cu")
		(net "PWRGD_PVCCFA_EHV_CPU1")
	)
	(segment
		(start 139.572492 -119.33936)
		(end 134.71652 -119.33936)
		(width 0.127)
		(layer "In15.Cu")
		(net "PWRGD_PVCCFA_EHV_CPU1")
	)
	(segment
		(start 150.2537 -126.832868)
		(end 149.45868 -127.627888)
		(width 0.127)
		(layer "In15.Cu")
		(net "PWRGD_PVCCFA_EHV_CPU1")
	)
	(segment
		(start 39.049198 -130.092958)
		(end 39.049198 -130.782822)
		(width 0.127)
		(layer "In15.Cu")
		(net "PWRGD_PVCCFA_EHV_CPU1")
	)
	(segment
		(start 155.55468 -127.892048)
		(end 154.4955 -126.832868)
		(width 0.127)
		(layer "In15.Cu")
		(net "PWRGD_PVCCFA_EHV_CPU1")
	)
	(segment
		(start 168.76268 -128.539748)
		(end 168.43248 -128.869948)
		(width 0.127)
		(layer "In15.Cu")
		(net "PWRGD_PVCCFA_EHV_CPU1")
	)
	(segment
		(start 168.43248 -128.869948)
		(end 167.49268 -128.869948)
		(width 0.127)
		(layer "In15.Cu")
		(net "PWRGD_PVCCFA_EHV_CPU1")
	)
	(segment
		(start 173.33468 -123.281948)
		(end 168.76268 -127.853948)
		(width 0.127)
		(layer "In15.Cu")
		(net "PWRGD_PVCCFA_EHV_CPU1")
	)
	(segment
		(start 149.45868 -127.627888)
		(end 147.86102 -127.627888)
		(width 0.127)
		(layer "In15.Cu")
		(net "PWRGD_PVCCFA_EHV_CPU1")
	)
	(segment
		(start 53.22062 -108.252768)
		(end 53.2638 -108.295948)
		(width 0.127)
		(layer "In15.Cu")
		(net "PWRGD_PVCCFA_EHV_CPU1")
	)
	(segment
		(start 154.4955 -126.832868)
		(end 150.2537 -126.832868)
		(width 0.127)
		(layer "In15.Cu")
		(net "PWRGD_PVCCFA_EHV_CPU1")
	)
	(segment
		(start 175.355504 -121.375424)
		(end 174.81042 -121.920508)
		(width 0.127)
		(layer "In15.Cu")
		(net "PWRGD_PVCCFA_EHV_CPU1")
	)
	(segment
		(start 147.86102 -127.627888)
		(end 139.572492 -119.33936)
		(width 0.127)
		(layer "In15.Cu")
		(net "PWRGD_PVCCFA_EHV_CPU1")
	)
	(segment
		(start 94.872556 -111.902748)
		(end 92.89288 -111.902748)
		(width 0.127)
		(layer "In15.Cu")
		(net "PWRGD_PVCCFA_EHV_CPU1")
	)
	(segment
		(start 174.24908 -123.281948)
		(end 173.33468 -123.281948)
		(width 0.127)
		(layer "In15.Cu")
		(net "PWRGD_PVCCFA_EHV_CPU1")
	)
	(segment
		(start 40.76192 -126.121668)
		(end 38.71976 -128.163828)
		(width 0.127)
		(layer "In15.Cu")
		(net "PWRGD_PVCCFA_EHV_CPU1")
	)
	(segment
		(start 166.23792 -127.615188)
		(end 163.713922 -127.615188)
		(width 0.127)
		(layer "In15.Cu")
		(net "PWRGD_PVCCFA_EHV_CPU1")
	)
	(segment
		(start 163.713922 -127.615188)
		(end 163.437062 -127.892048)
		(width 0.127)
		(layer "In15.Cu")
		(net "PWRGD_PVCCFA_EHV_CPU1")
	)
	(segment
		(start 38.71976 -128.163828)
		(end 38.71976 -129.466848)
		(width 0.127)
		(layer "In15.Cu")
		(net "PWRGD_PVCCFA_EHV_CPU1")
	)
	(segment
		(start 41.82618 -126.121668)
		(end 40.76192 -126.121668)
		(width 0.127)
		(layer "In15.Cu")
		(net "PWRGD_PVCCFA_EHV_CPU1")
	)
	(segment
		(start 168.76268 -127.853948)
		(end 168.76268 -128.539748)
		(width 0.127)
		(layer "In15.Cu")
		(net "PWRGD_PVCCFA_EHV_CPU1")
	)
	(segment
		(start 167.49268 -128.869948)
		(end 166.23792 -127.615188)
		(width 0.127)
		(layer "In15.Cu")
		(net "PWRGD_PVCCFA_EHV_CPU1")
	)
	(segment
		(start 134.71652 -119.33936)
		(end 133.190488 -117.813328)
		(width 0.127)
		(layer "In15.Cu")
		(net "PWRGD_PVCCFA_EHV_CPU1")
	)
	(segment
		(start 53.2638 -114.684048)
		(end 41.82618 -126.121668)
		(width 0.127)
		(layer "In15.Cu")
		(net "PWRGD_PVCCFA_EHV_CPU1")
	)
	(segment
		(start 163.437062 -127.892048)
		(end 155.55468 -127.892048)
		(width 0.127)
		(layer "In15.Cu")
		(net "PWRGD_PVCCFA_EHV_CPU1")
	)
	(segment
		(start 174.81042 -121.920508)
		(end 174.81042 -122.720608)
		(width 0.127)
		(layer "In15.Cu")
		(net "PWRGD_PVCCFA_EHV_CPU1")
	)
	(segment
		(start 133.190488 -117.813328)
		(end 100.783136 -117.813328)
		(width 0.127)
		(layer "In15.Cu")
		(net "PWRGD_PVCCFA_EHV_CPU1")
	)
	(segment
		(start 429.201326 -136.484106)
		(end 429.071024 -136.614408)
		(width 0.12954)
		(layer "F.Cu")
		(net "PWRGD_PVCCFA_EHV_CPU0_R")
	)
	(segment
		(start 429.071024 -136.614408)
		(end 428.105062 -136.614408)
		(width 0.12954)
		(layer "F.Cu")
		(net "PWRGD_PVCCFA_EHV_CPU0_R")
	)
	(via
		(at 429.201326 -136.484106)
		(size 0.508)
		(drill 0.254)
		(layers "F.Cu" "B.Cu")
		(net "PWRGD_PVCCFA_EHV_CPU0_R")
	)
	(via
		(at 428.080932 -137.094722)
		(size 0.6604)
		(drill 0.3302)
		(layers "F.Cu" "B.Cu")
		(net "PWRGD_PVCCFA_EHV_CPU0_R")
	)
	(segment
		(start 429.201326 -136.484106)
		(end 429.560736 -136.843516)
		(width 0.12954)
		(layer "B.Cu")
		(net "PWRGD_PVCCFA_EHV_CPU0_R")
	)
	(segment
		(start 429.560736 -136.843516)
		(end 429.883316 -136.843516)
		(width 0.12954)
		(layer "B.Cu")
		(net "PWRGD_PVCCFA_EHV_CPU0_R")
	)
	(segment
		(start 428.502318 -137.094722)
		(end 428.080932 -137.094722)
		(width 0.12954)
		(layer "B.Cu")
		(net "PWRGD_PVCCFA_EHV_CPU0_R")
	)
	(segment
		(start 430.200054 -138.558778)
		(end 430.200054 -137.542778)
		(width 0.12954)
		(layer "B.Cu")
		(net "PWRGD_PVCCFA_EHV_CPU0_R")
	)
	(segment
		(start 429.112934 -136.484106)
		(end 428.502318 -137.094722)
		(width 0.12954)
		(layer "B.Cu")
		(net "PWRGD_PVCCFA_EHV_CPU0_R")
	)
	(segment
		(start 429.883316 -136.843516)
		(end 430.200054 -136.526778)
		(width 0.12954)
		(layer "B.Cu")
		(net "PWRGD_PVCCFA_EHV_CPU0_R")
	)
	(segment
		(start 429.201326 -136.484106)
		(end 429.112934 -136.484106)
		(width 0.12954)
		(layer "B.Cu")
		(net "PWRGD_PVCCFA_EHV_CPU0_R")
	)
	(segment
		(start 430.200054 -137.542778)
		(end 430.200054 -136.526778)
		(width 0.12954)
		(layer "B.Cu")
		(net "PWRGD_PVCCFA_EHV_CPU0_R")
	)
	(segment
		(start 175.31588 -131.994148)
		(end 175.62068 -131.994148)
		(width 0.12954)
		(layer "F.Cu")
		(net "PWRGD_PVCCFA_EHV_CPU0")
	)
	(segment
		(start 175.923194 -131.691634)
		(end 175.923194 -121.943114)
		(width 0.12954)
		(layer "F.Cu")
		(net "PWRGD_PVCCFA_EHV_CPU0")
	)
	(segment
		(start 175.923194 -121.943114)
		(end 175.755554 -121.775474)
		(width 0.12954)
		(layer "F.Cu")
		(net "PWRGD_PVCCFA_EHV_CPU0")
	)
	(segment
		(start 175.62068 -131.994148)
		(end 175.923194 -131.691634)
		(width 0.12954)
		(layer "F.Cu")
		(net "PWRGD_PVCCFA_EHV_CPU0")
	)
	(segment
		(start 84.626196 -92.888308)
		(end 83.991196 -92.888308)
		(width 0.12954)
		(layer "F.Cu")
		(net "PWRGD_PVCCFA_EHV_CPU0")
	)
	(via
		(at 175.31588 -131.994148)
		(size 0.508)
		(drill 0.254)
		(layers "F.Cu" "B.Cu")
		(net "PWRGD_PVCCFA_EHV_CPU0")
	)
	(via
		(at 275.77288 -132.695188)
		(size 0.508)
		(drill 0.254)
		(layers "F.Cu" "B.Cu")
		(net "PWRGD_PVCCFA_EHV_CPU0")
	)
	(via
		(at 431.09388 -115.788948)
		(size 0.508)
		(drill 0.254)
		(layers "F.Cu" "B.Cu")
		(net "PWRGD_PVCCFA_EHV_CPU0")
	)
	(via
		(at 98.425 -125.821948)
		(size 0.508)
		(drill 0.254)
		(layers "F.Cu" "B.Cu")
		(net "PWRGD_PVCCFA_EHV_CPU0")
	)
	(via
		(at 83.991196 -92.888308)
		(size 0.508)
		(drill 0.254)
		(layers "F.Cu" "B.Cu")
		(net "PWRGD_PVCCFA_EHV_CPU0")
	)
	(via
		(at 276.92223 -110.600998)
		(size 0.508)
		(drill 0.254)
		(layers "F.Cu" "B.Cu")
		(net "PWRGD_PVCCFA_EHV_CPU0")
	)
	(segment
		(start 433.598828 -115.493292)
		(end 432.693572 -116.398548)
		(width 0.12954)
		(layer "B.Cu")
		(net "PWRGD_PVCCFA_EHV_CPU0")
	)
	(segment
		(start 432.693572 -116.398548)
		(end 431.70348 -116.398548)
		(width 0.12954)
		(layer "B.Cu")
		(net "PWRGD_PVCCFA_EHV_CPU0")
	)
	(segment
		(start 443.23 -120.258332)
		(end 438.46496 -115.493292)
		(width 0.12954)
		(layer "B.Cu")
		(net "PWRGD_PVCCFA_EHV_CPU0")
	)
	(segment
		(start 431.000154 -138.558778)
		(end 431.734722 -138.558778)
		(width 0.12954)
		(layer "B.Cu")
		(net "PWRGD_PVCCFA_EHV_CPU0")
	)
	(segment
		(start 438.46496 -115.493292)
		(end 433.598828 -115.493292)
		(width 0.12954)
		(layer "B.Cu")
		(net "PWRGD_PVCCFA_EHV_CPU0")
	)
	(segment
		(start 443.23 -127.0635)
		(end 443.23 -120.258332)
		(width 0.12954)
		(layer "B.Cu")
		(net "PWRGD_PVCCFA_EHV_CPU0")
	)
	(segment
		(start 431.70348 -116.398548)
		(end 431.09388 -115.788948)
		(width 0.12954)
		(layer "B.Cu")
		(net "PWRGD_PVCCFA_EHV_CPU0")
	)
	(segment
		(start 431.734722 -138.558778)
		(end 443.23 -127.0635)
		(width 0.12954)
		(layer "B.Cu")
		(net "PWRGD_PVCCFA_EHV_CPU0")
	)
	(segment
		(start 276.92223 -110.600998)
		(end 276.92223 -112.58423)
		(width 0.127)
		(layer "In2.Cu")
		(net "PWRGD_PVCCFA_EHV_CPU0")
	)
	(segment
		(start 94.16288 -121.559828)
		(end 94.16288 -111.978948)
		(width 0.127)
		(layer "In2.Cu")
		(net "PWRGD_PVCCFA_EHV_CPU0")
	)
	(segment
		(start 85.15604 -92.888308)
		(end 83.991196 -92.888308)
		(width 0.127)
		(layer "In2.Cu")
		(net "PWRGD_PVCCFA_EHV_CPU0")
	)
	(segment
		(start 89.38768 -97.043748)
		(end 87.33028 -97.043748)
		(width 0.127)
		(layer "In2.Cu")
		(net "PWRGD_PVCCFA_EHV_CPU0")
	)
	(segment
		(start 276.16023 -113.34623)
		(end 276.16023 -132.307838)
		(width 0.127)
		(layer "In2.Cu")
		(net "PWRGD_PVCCFA_EHV_CPU0")
	)
	(segment
		(start 87.33028 -97.043748)
		(end 85.97138 -95.684848)
		(width 0.127)
		(layer "In2.Cu")
		(net "PWRGD_PVCCFA_EHV_CPU0")
	)
	(segment
		(start 90.60688 -108.422948)
		(end 90.60688 -98.262948)
		(width 0.127)
		(layer "In2.Cu")
		(net "PWRGD_PVCCFA_EHV_CPU0")
	)
	(segment
		(start 85.97138 -93.703648)
		(end 85.15604 -92.888308)
		(width 0.127)
		(layer "In2.Cu")
		(net "PWRGD_PVCCFA_EHV_CPU0")
	)
	(segment
		(start 276.92223 -112.58423)
		(end 276.16023 -113.34623)
		(width 0.127)
		(layer "In2.Cu")
		(net "PWRGD_PVCCFA_EHV_CPU0")
	)
	(segment
		(start 98.425 -125.821948)
		(end 94.16288 -121.559828)
		(width 0.127)
		(layer "In2.Cu")
		(net "PWRGD_PVCCFA_EHV_CPU0")
	)
	(segment
		(start 276.16023 -132.307838)
		(end 275.77288 -132.695188)
		(width 0.127)
		(layer "In2.Cu")
		(net "PWRGD_PVCCFA_EHV_CPU0")
	)
	(segment
		(start 90.60688 -98.262948)
		(end 89.38768 -97.043748)
		(width 0.127)
		(layer "In2.Cu")
		(net "PWRGD_PVCCFA_EHV_CPU0")
	)
	(segment
		(start 85.97138 -95.684848)
		(end 85.97138 -93.703648)
		(width 0.127)
		(layer "In2.Cu")
		(net "PWRGD_PVCCFA_EHV_CPU0")
	)
	(segment
		(start 94.16288 -111.978948)
		(end 90.60688 -108.422948)
		(width 0.127)
		(layer "In2.Cu")
		(net "PWRGD_PVCCFA_EHV_CPU0")
	)
	(segment
		(start 276.92223 -109.838998)
		(end 278.303228 -108.458)
		(width 0.127)
		(layer "In4.Cu")
		(net "PWRGD_PVCCFA_EHV_CPU0")
	)
	(segment
		(start 362.12526 -110.076488)
		(end 362.420408 -109.78134)
		(width 0.127)
		(layer "In4.Cu")
		(net "PWRGD_PVCCFA_EHV_CPU0")
	)
	(segment
		(start 431.0888 -115.664488)
		(end 431.09388 -115.664488)
		(width 0.127)
		(layer "In4.Cu")
		(net "PWRGD_PVCCFA_EHV_CPU0")
	)
	(segment
		(start 374.879108 -110.388908)
		(end 380.79172 -110.388908)
		(width 0.127)
		(layer "In4.Cu")
		(net "PWRGD_PVCCFA_EHV_CPU0")
	)
	(segment
		(start 276.92223 -110.600998)
		(end 276.92223 -109.838998)
		(width 0.127)
		(layer "In4.Cu")
		(net "PWRGD_PVCCFA_EHV_CPU0")
	)
	(segment
		(start 412.4325 -115.169188)
		(end 430.5935 -115.169188)
		(width 0.127)
		(layer "In4.Cu")
		(net "PWRGD_PVCCFA_EHV_CPU0")
	)
	(segment
		(start 430.5935 -115.169188)
		(end 431.0888 -115.664488)
		(width 0.127)
		(layer "In4.Cu")
		(net "PWRGD_PVCCFA_EHV_CPU0")
	)
	(segment
		(start 278.303228 -108.458)
		(end 336.767932 -108.458)
		(width 0.127)
		(layer "In4.Cu")
		(net "PWRGD_PVCCFA_EHV_CPU0")
	)
	(segment
		(start 406.68448 -109.421168)
		(end 412.4325 -115.169188)
		(width 0.127)
		(layer "In4.Cu")
		(net "PWRGD_PVCCFA_EHV_CPU0")
	)
	(segment
		(start 362.420408 -109.78134)
		(end 374.27154 -109.78134)
		(width 0.127)
		(layer "In4.Cu")
		(net "PWRGD_PVCCFA_EHV_CPU0")
	)
	(segment
		(start 431.09388 -115.664488)
		(end 431.09388 -115.788948)
		(width 0.127)
		(layer "In4.Cu")
		(net "PWRGD_PVCCFA_EHV_CPU0")
	)
	(segment
		(start 380.79172 -110.388908)
		(end 381.75946 -109.421168)
		(width 0.127)
		(layer "In4.Cu")
		(net "PWRGD_PVCCFA_EHV_CPU0")
	)
	(segment
		(start 336.767932 -108.458)
		(end 338.38642 -110.076488)
		(width 0.127)
		(layer "In4.Cu")
		(net "PWRGD_PVCCFA_EHV_CPU0")
	)
	(segment
		(start 381.75946 -109.421168)
		(end 406.68448 -109.421168)
		(width 0.127)
		(layer "In4.Cu")
		(net "PWRGD_PVCCFA_EHV_CPU0")
	)
	(segment
		(start 374.27154 -109.78134)
		(end 374.879108 -110.388908)
		(width 0.127)
		(layer "In4.Cu")
		(net "PWRGD_PVCCFA_EHV_CPU0")
	)
	(segment
		(start 338.38642 -110.076488)
		(end 362.12526 -110.076488)
		(width 0.127)
		(layer "In4.Cu")
		(net "PWRGD_PVCCFA_EHV_CPU0")
	)
	(segment
		(start 200.71588 -130.571748)
		(end 176.15408 -130.571748)
		(width 0.127)
		(layer "In6.Cu")
		(net "PWRGD_PVCCFA_EHV_CPU0")
	)
	(segment
		(start 149.50948 -129.098548)
		(end 146.69008 -126.279148)
		(width 0.127)
		(layer "In6.Cu")
		(net "PWRGD_PVCCFA_EHV_CPU0")
	)
	(segment
		(start 136.63168 -126.279148)
		(end 135.15848 -124.805948)
		(width 0.127)
		(layer "In6.Cu")
		(net "PWRGD_PVCCFA_EHV_CPU0")
	)
	(segment
		(start 107.654852 -125.123448)
		(end 99.1235 -125.123448)
		(width 0.127)
		(layer "In6.Cu")
		(net "PWRGD_PVCCFA_EHV_CPU0")
	)
	(segment
		(start 151.89708 -128.742948)
		(end 151.54148 -129.098548)
		(width 0.127)
		(layer "In6.Cu")
		(net "PWRGD_PVCCFA_EHV_CPU0")
	)
	(segment
		(start 204.903324 -130.774948)
		(end 204.556868 -131.121404)
		(width 0.127)
		(layer "In6.Cu")
		(net "PWRGD_PVCCFA_EHV_CPU0")
	)
	(segment
		(start 273.918172 -134.549896)
		(end 253.081028 -134.549896)
		(width 0.127)
		(layer "In6.Cu")
		(net "PWRGD_PVCCFA_EHV_CPU0")
	)
	(segment
		(start 214.2998 -132.039868)
		(end 213.763352 -131.50342)
		(width 0.127)
		(layer "In6.Cu")
		(net "PWRGD_PVCCFA_EHV_CPU0")
	)
	(segment
		(start 223.15424 -132.039868)
		(end 214.2998 -132.039868)
		(width 0.127)
		(layer "In6.Cu")
		(net "PWRGD_PVCCFA_EHV_CPU0")
	)
	(segment
		(start 127.48768 -121.757948)
		(end 123.57608 -121.757948)
		(width 0.127)
		(layer "In6.Cu")
		(net "PWRGD_PVCCFA_EHV_CPU0")
	)
	(segment
		(start 241.29238 -129.987548)
		(end 239.78616 -129.987548)
		(width 0.127)
		(layer "In6.Cu")
		(net "PWRGD_PVCCFA_EHV_CPU0")
	)
	(segment
		(start 225.87966 -129.314448)
		(end 223.15424 -132.039868)
		(width 0.127)
		(layer "In6.Cu")
		(net "PWRGD_PVCCFA_EHV_CPU0")
	)
	(segment
		(start 176.15408 -130.571748)
		(end 175.95088 -130.774948)
		(width 0.127)
		(layer "In6.Cu")
		(net "PWRGD_PVCCFA_EHV_CPU0")
	)
	(segment
		(start 123.14428 -121.326148)
		(end 123.14428 -120.513348)
		(width 0.127)
		(layer "In6.Cu")
		(net "PWRGD_PVCCFA_EHV_CPU0")
	)
	(segment
		(start 175.95088 -131.359148)
		(end 175.31588 -131.994148)
		(width 0.127)
		(layer "In6.Cu")
		(net "PWRGD_PVCCFA_EHV_CPU0")
	)
	(segment
		(start 175.31588 -131.994148)
		(end 174.68088 -131.359148)
		(width 0.127)
		(layer "In6.Cu")
		(net "PWRGD_PVCCFA_EHV_CPU0")
	)
	(segment
		(start 166.299134 -130.278886)
		(end 158.182818 -130.278886)
		(width 0.127)
		(layer "In6.Cu")
		(net "PWRGD_PVCCFA_EHV_CPU0")
	)
	(segment
		(start 242.47602 -128.803908)
		(end 241.29238 -129.987548)
		(width 0.127)
		(layer "In6.Cu")
		(net "PWRGD_PVCCFA_EHV_CPU0")
	)
	(segment
		(start 250.57608 -132.044948)
		(end 250.57608 -130.015488)
		(width 0.127)
		(layer "In6.Cu")
		(net "PWRGD_PVCCFA_EHV_CPU0")
	)
	(segment
		(start 201.265536 -131.121404)
		(end 200.71588 -130.571748)
		(width 0.127)
		(layer "In6.Cu")
		(net "PWRGD_PVCCFA_EHV_CPU0")
	)
	(segment
		(start 123.14428 -120.513348)
		(end 121.64568 -119.014748)
		(width 0.127)
		(layer "In6.Cu")
		(net "PWRGD_PVCCFA_EHV_CPU0")
	)
	(segment
		(start 249.3645 -128.803908)
		(end 242.47602 -128.803908)
		(width 0.127)
		(layer "In6.Cu")
		(net "PWRGD_PVCCFA_EHV_CPU0")
	)
	(segment
		(start 130.53568 -124.805948)
		(end 127.48768 -121.757948)
		(width 0.127)
		(layer "In6.Cu")
		(net "PWRGD_PVCCFA_EHV_CPU0")
	)
	(segment
		(start 250.57608 -130.015488)
		(end 249.3645 -128.803908)
		(width 0.127)
		(layer "In6.Cu")
		(net "PWRGD_PVCCFA_EHV_CPU0")
	)
	(segment
		(start 112.26292 -121.88698)
		(end 110.89132 -121.88698)
		(width 0.127)
		(layer "In6.Cu")
		(net "PWRGD_PVCCFA_EHV_CPU0")
	)
	(segment
		(start 166.783512 -129.794508)
		(end 166.299134 -130.278886)
		(width 0.127)
		(layer "In6.Cu")
		(net "PWRGD_PVCCFA_EHV_CPU0")
	)
	(segment
		(start 123.57608 -121.757948)
		(end 123.14428 -121.326148)
		(width 0.127)
		(layer "In6.Cu")
		(net "PWRGD_PVCCFA_EHV_CPU0")
	)
	(segment
		(start 115.135152 -119.014748)
		(end 112.26292 -121.88698)
		(width 0.127)
		(layer "In6.Cu")
		(net "PWRGD_PVCCFA_EHV_CPU0")
	)
	(segment
		(start 253.081028 -134.549896)
		(end 250.57608 -132.044948)
		(width 0.127)
		(layer "In6.Cu")
		(net "PWRGD_PVCCFA_EHV_CPU0")
	)
	(segment
		(start 275.77288 -132.695188)
		(end 273.918172 -134.549896)
		(width 0.127)
		(layer "In6.Cu")
		(net "PWRGD_PVCCFA_EHV_CPU0")
	)
	(segment
		(start 213.763352 -131.50342)
		(end 209.699352 -131.50342)
		(width 0.127)
		(layer "In6.Cu")
		(net "PWRGD_PVCCFA_EHV_CPU0")
	)
	(segment
		(start 239.237266 -129.438654)
		(end 232.224326 -129.438654)
		(width 0.127)
		(layer "In6.Cu")
		(net "PWRGD_PVCCFA_EHV_CPU0")
	)
	(segment
		(start 209.699352 -131.50342)
		(end 209.52968 -131.333748)
		(width 0.127)
		(layer "In6.Cu")
		(net "PWRGD_PVCCFA_EHV_CPU0")
	)
	(segment
		(start 239.78616 -129.987548)
		(end 239.237266 -129.438654)
		(width 0.127)
		(layer "In6.Cu")
		(net "PWRGD_PVCCFA_EHV_CPU0")
	)
	(segment
		(start 146.69008 -126.279148)
		(end 136.63168 -126.279148)
		(width 0.127)
		(layer "In6.Cu")
		(net "PWRGD_PVCCFA_EHV_CPU0")
	)
	(segment
		(start 209.52968 -131.333748)
		(end 207.95488 -131.333748)
		(width 0.127)
		(layer "In6.Cu")
		(net "PWRGD_PVCCFA_EHV_CPU0")
	)
	(segment
		(start 99.1235 -125.123448)
		(end 98.425 -125.821948)
		(width 0.127)
		(layer "In6.Cu")
		(net "PWRGD_PVCCFA_EHV_CPU0")
	)
	(segment
		(start 121.64568 -119.014748)
		(end 115.135152 -119.014748)
		(width 0.127)
		(layer "In6.Cu")
		(net "PWRGD_PVCCFA_EHV_CPU0")
	)
	(segment
		(start 175.95088 -130.774948)
		(end 175.95088 -131.359148)
		(width 0.127)
		(layer "In6.Cu")
		(net "PWRGD_PVCCFA_EHV_CPU0")
	)
	(segment
		(start 232.224326 -129.438654)
		(end 232.10012 -129.314448)
		(width 0.127)
		(layer "In6.Cu")
		(net "PWRGD_PVCCFA_EHV_CPU0")
	)
	(segment
		(start 204.556868 -131.121404)
		(end 201.265536 -131.121404)
		(width 0.127)
		(layer "In6.Cu")
		(net "PWRGD_PVCCFA_EHV_CPU0")
	)
	(segment
		(start 151.54148 -129.098548)
		(end 149.50948 -129.098548)
		(width 0.127)
		(layer "In6.Cu")
		(net "PWRGD_PVCCFA_EHV_CPU0")
	)
	(segment
		(start 174.68088 -131.028948)
		(end 173.44644 -129.794508)
		(width 0.127)
		(layer "In6.Cu")
		(net "PWRGD_PVCCFA_EHV_CPU0")
	)
	(segment
		(start 232.10012 -129.314448)
		(end 225.87966 -129.314448)
		(width 0.127)
		(layer "In6.Cu")
		(net "PWRGD_PVCCFA_EHV_CPU0")
	)
	(segment
		(start 158.182818 -130.278886)
		(end 156.64688 -128.742948)
		(width 0.127)
		(layer "In6.Cu")
		(net "PWRGD_PVCCFA_EHV_CPU0")
	)
	(segment
		(start 173.44644 -129.794508)
		(end 166.783512 -129.794508)
		(width 0.127)
		(layer "In6.Cu")
		(net "PWRGD_PVCCFA_EHV_CPU0")
	)
	(segment
		(start 156.64688 -128.742948)
		(end 151.89708 -128.742948)
		(width 0.127)
		(layer "In6.Cu")
		(net "PWRGD_PVCCFA_EHV_CPU0")
	)
	(segment
		(start 110.89132 -121.88698)
		(end 107.654852 -125.123448)
		(width 0.127)
		(layer "In6.Cu")
		(net "PWRGD_PVCCFA_EHV_CPU0")
	)
	(segment
		(start 135.15848 -124.805948)
		(end 130.53568 -124.805948)
		(width 0.127)
		(layer "In6.Cu")
		(net "PWRGD_PVCCFA_EHV_CPU0")
	)
	(segment
		(start 207.95488 -131.333748)
		(end 207.39608 -130.774948)
		(width 0.127)
		(layer "In6.Cu")
		(net "PWRGD_PVCCFA_EHV_CPU0")
	)
	(segment
		(start 174.68088 -131.359148)
		(end 174.68088 -131.028948)
		(width 0.127)
		(layer "In6.Cu")
		(net "PWRGD_PVCCFA_EHV_CPU0")
	)
	(segment
		(start 207.39608 -130.774948)
		(end 204.903324 -130.774948)
		(width 0.127)
		(layer "In6.Cu")
		(net "PWRGD_PVCCFA_EHV_CPU0")
	)
	(segment
		(start 24.7523 -167.140128)
		(end 24.34844 -167.543988)
		(width 0.12954)
		(layer "F.Cu")
		(net "PWRGD_PVCCD_HV_CPU1_R")
	)
	(segment
		(start 24.34844 -167.543988)
		(end 24.34844 -168.740328)
		(width 0.12954)
		(layer "F.Cu")
		(net "PWRGD_PVCCD_HV_CPU1_R")
	)
	(segment
		(start 25.26284 -166.227252)
		(end 24.984202 -166.227252)
		(width 0.12954)
		(layer "F.Cu")
		(net "PWRGD_PVCCD_HV_CPU1_R")
	)
	(segment
		(start 24.984202 -166.227252)
		(end 24.7523 -166.459154)
		(width 0.12954)
		(layer "F.Cu")
		(net "PWRGD_PVCCD_HV_CPU1_R")
	)
	(segment
		(start 23.484332 -169.604436)
		(end 23.04161 -169.604436)
		(width 0.12954)
		(layer "F.Cu")
		(net "PWRGD_PVCCD_HV_CPU1_R")
	)
	(segment
		(start 24.7523 -166.459154)
		(end 24.7523 -167.140128)
		(width 0.12954)
		(layer "F.Cu")
		(net "PWRGD_PVCCD_HV_CPU1_R")
	)
	(segment
		(start 24.34844 -168.740328)
		(end 23.484332 -169.604436)
		(width 0.12954)
		(layer "F.Cu")
		(net "PWRGD_PVCCD_HV_CPU1_R")
	)
	(via
		(at 24.34844 -167.543988)
		(size 0.508)
		(drill 0.254)
		(layers "F.Cu" "B.Cu")
		(net "PWRGD_PVCCD_HV_CPU1_R")
	)
	(segment
		(start 22.88921 -169.564304)
		(end 22.291548 -168.966642)
		(width 0.12954)
		(layer "B.Cu")
		(net "PWRGD_PVCCD_HV_CPU1_R")
	)
	(segment
		(start 22.291548 -168.966642)
		(end 22.291548 -168.460928)
		(width 0.12954)
		(layer "B.Cu")
		(net "PWRGD_PVCCD_HV_CPU1_R")
	)
	(segment
		(start 24.34844 -167.543988)
		(end 23.454614 -168.437814)
		(width 0.12954)
		(layer "B.Cu")
		(net "PWRGD_PVCCD_HV_CPU1_R")
	)
	(segment
		(start 22.88921 -169.659808)
		(end 22.88921 -169.564304)
		(width 0.12954)
		(layer "B.Cu")
		(net "PWRGD_PVCCD_HV_CPU1_R")
	)
	(segment
		(start 22.291548 -168.460928)
		(end 22.314662 -168.437814)
		(width 0.12954)
		(layer "B.Cu")
		(net "PWRGD_PVCCD_HV_CPU1_R")
	)
	(segment
		(start 23.454614 -168.437814)
		(end 22.314662 -168.437814)
		(width 0.12954)
		(layer "B.Cu")
		(net "PWRGD_PVCCD_HV_CPU1_R")
	)
	(segment
		(start 93.136466 -99.577398)
		(end 92.501466 -99.577398)
		(width 0.12954)
		(layer "F.Cu")
		(net "PWRGD_PVCCD_HV_CPU1")
	)
	(segment
		(start 175.755554 -118.575328)
		(end 175.355504 -118.975378)
		(width 0.12954)
		(layer "F.Cu")
		(net "PWRGD_PVCCD_HV_CPU1")
	)
	(via
		(at 92.501466 -99.577398)
		(size 0.508)
		(drill 0.254)
		(layers "F.Cu" "B.Cu")
		(net "PWRGD_PVCCD_HV_CPU1")
	)
	(via
		(at 175.355504 -118.975378)
		(size 0.4572)
		(drill 0.254)
		(layers "F.Cu" "B.Cu")
		(net "PWRGD_PVCCD_HV_CPU1")
	)
	(via
		(at 20.351242 -168.663874)
		(size 0.508)
		(drill 0.254)
		(layers "F.Cu" "B.Cu")
		(net "PWRGD_PVCCD_HV_CPU1")
	)
	(via
		(at 96.32188 -110.835948)
		(size 0.508)
		(drill 0.254)
		(layers "F.Cu" "B.Cu")
		(net "PWRGD_PVCCD_HV_CPU1")
	)
	(via
		(at 96.32188 -119.624348)
		(size 0.508)
		(drill 0.254)
		(layers "F.Cu" "B.Cu")
		(net "PWRGD_PVCCD_HV_CPU1")
	)
	(segment
		(start 20.351242 -168.663874)
		(end 20.705826 -168.30929)
		(width 0.12954)
		(layer "B.Cu")
		(net "PWRGD_PVCCD_HV_CPU1")
	)
	(segment
		(start 20.965414 -168.30929)
		(end 21.093938 -168.437814)
		(width 0.12954)
		(layer "B.Cu")
		(net "PWRGD_PVCCD_HV_CPU1")
	)
	(segment
		(start 20.705826 -168.30929)
		(end 20.965414 -168.30929)
		(width 0.12954)
		(layer "B.Cu")
		(net "PWRGD_PVCCD_HV_CPU1")
	)
	(segment
		(start 21.093938 -168.437814)
		(end 21.514562 -168.437814)
		(width 0.12954)
		(layer "B.Cu")
		(net "PWRGD_PVCCD_HV_CPU1")
	)
	(segment
		(start 96.32188 -109.946948)
		(end 93.22308 -106.848148)
		(width 0.127)
		(layer "In2.Cu")
		(net "PWRGD_PVCCD_HV_CPU1")
	)
	(segment
		(start 96.32188 -110.835948)
		(end 96.32188 -109.946948)
		(width 0.127)
		(layer "In2.Cu")
		(net "PWRGD_PVCCD_HV_CPU1")
	)
	(segment
		(start 93.03893 -99.577398)
		(end 92.501466 -99.577398)
		(width 0.127)
		(layer "In2.Cu")
		(net "PWRGD_PVCCD_HV_CPU1")
	)
	(segment
		(start 93.22308 -99.761548)
		(end 93.03893 -99.577398)
		(width 0.127)
		(layer "In2.Cu")
		(net "PWRGD_PVCCD_HV_CPU1")
	)
	(segment
		(start 96.32188 -119.624348)
		(end 96.32188 -110.835948)
		(width 0.127)
		(layer "In2.Cu")
		(net "PWRGD_PVCCD_HV_CPU1")
	)
	(segment
		(start 93.22308 -106.848148)
		(end 93.22308 -99.761548)
		(width 0.127)
		(layer "In2.Cu")
		(net "PWRGD_PVCCD_HV_CPU1")
	)
	(segment
		(start 24.84374 -119.385588)
		(end 17.76222 -126.467108)
		(width 0.127)
		(layer "In13.Cu")
		(net "PWRGD_PVCCD_HV_CPU1")
	)
	(segment
		(start 24.2062 -158.688024)
		(end 24.2062 -163.069016)
		(width 0.127)
		(layer "In13.Cu")
		(net "PWRGD_PVCCD_HV_CPU1")
	)
	(segment
		(start 21.180552 -167.834564)
		(end 20.351242 -168.663874)
		(width 0.127)
		(layer "In13.Cu")
		(net "PWRGD_PVCCD_HV_CPU1")
	)
	(segment
		(start 17.76222 -126.467108)
		(end 17.76222 -152.244044)
		(width 0.127)
		(layer "In13.Cu")
		(net "PWRGD_PVCCD_HV_CPU1")
	)
	(segment
		(start 96.32188 -119.624348)
		(end 95.50908 -120.437148)
		(width 0.127)
		(layer "In13.Cu")
		(net "PWRGD_PVCCD_HV_CPU1")
	)
	(segment
		(start 22.63394 -164.641276)
		(end 22.63394 -166.815008)
		(width 0.127)
		(layer "In13.Cu")
		(net "PWRGD_PVCCD_HV_CPU1")
	)
	(segment
		(start 24.2062 -163.069016)
		(end 22.63394 -164.641276)
		(width 0.127)
		(layer "In13.Cu")
		(net "PWRGD_PVCCD_HV_CPU1")
	)
	(segment
		(start 48.49114 -119.385588)
		(end 24.84374 -119.385588)
		(width 0.127)
		(layer "In13.Cu")
		(net "PWRGD_PVCCD_HV_CPU1")
	)
	(segment
		(start 49.5427 -120.437148)
		(end 48.49114 -119.385588)
		(width 0.127)
		(layer "In13.Cu")
		(net "PWRGD_PVCCD_HV_CPU1")
	)
	(segment
		(start 21.614384 -167.834564)
		(end 21.180552 -167.834564)
		(width 0.127)
		(layer "In13.Cu")
		(net "PWRGD_PVCCD_HV_CPU1")
	)
	(segment
		(start 95.50908 -120.437148)
		(end 49.5427 -120.437148)
		(width 0.127)
		(layer "In13.Cu")
		(net "PWRGD_PVCCD_HV_CPU1")
	)
	(segment
		(start 17.76222 -152.244044)
		(end 24.2062 -158.688024)
		(width 0.127)
		(layer "In13.Cu")
		(net "PWRGD_PVCCD_HV_CPU1")
	)
	(segment
		(start 22.63394 -166.815008)
		(end 21.614384 -167.834564)
		(width 0.127)
		(layer "In13.Cu")
		(net "PWRGD_PVCCD_HV_CPU1")
	)
	(segment
		(start 149.35962 -123.396248)
		(end 145.72742 -123.396248)
		(width 0.127)
		(layer "In15.Cu")
		(net "PWRGD_PVCCD_HV_CPU1")
	)
	(segment
		(start 145.72742 -123.396248)
		(end 139.359132 -117.02796)
		(width 0.127)
		(layer "In15.Cu")
		(net "PWRGD_PVCCD_HV_CPU1")
	)
	(segment
		(start 100.50526 -115.654328)
		(end 96.32188 -111.470948)
		(width 0.127)
		(layer "In15.Cu")
		(net "PWRGD_PVCCD_HV_CPU1")
	)
	(segment
		(start 172.33392 -120.170448)
		(end 171.764452 -120.170448)
		(width 0.127)
		(layer "In15.Cu")
		(net "PWRGD_PVCCD_HV_CPU1")
	)
	(segment
		(start 162.899852 -126.596648)
		(end 156.380942 -126.596648)
		(width 0.127)
		(layer "In15.Cu")
		(net "PWRGD_PVCCD_HV_CPU1")
	)
	(segment
		(start 134.86638 -117.02796)
		(end 133.492748 -115.654328)
		(width 0.127)
		(layer "In15.Cu")
		(net "PWRGD_PVCCD_HV_CPU1")
	)
	(segment
		(start 156.380942 -126.596648)
		(end 155.112974 -125.32868)
		(width 0.127)
		(layer "In15.Cu")
		(net "PWRGD_PVCCD_HV_CPU1")
	)
	(segment
		(start 172.72 -119.375428)
		(end 172.55744 -119.537988)
		(width 0.127)
		(layer "In15.Cu")
		(net "PWRGD_PVCCD_HV_CPU1")
	)
	(segment
		(start 172.55744 -119.946928)
		(end 172.33392 -120.170448)
		(width 0.127)
		(layer "In15.Cu")
		(net "PWRGD_PVCCD_HV_CPU1")
	)
	(segment
		(start 175.355504 -118.975378)
		(end 174.955454 -119.375428)
		(width 0.127)
		(layer "In15.Cu")
		(net "PWRGD_PVCCD_HV_CPU1")
	)
	(segment
		(start 167.32758 -124.119132)
		(end 165.126924 -126.319788)
		(width 0.127)
		(layer "In15.Cu")
		(net "PWRGD_PVCCD_HV_CPU1")
	)
	(segment
		(start 96.32188 -111.470948)
		(end 96.32188 -110.835948)
		(width 0.127)
		(layer "In15.Cu")
		(net "PWRGD_PVCCD_HV_CPU1")
	)
	(segment
		(start 151.292052 -125.32868)
		(end 149.35962 -123.396248)
		(width 0.127)
		(layer "In15.Cu")
		(net "PWRGD_PVCCD_HV_CPU1")
	)
	(segment
		(start 170.75658 -121.17832)
		(end 169.19702 -121.17832)
		(width 0.127)
		(layer "In15.Cu")
		(net "PWRGD_PVCCD_HV_CPU1")
	)
	(segment
		(start 169.19702 -121.17832)
		(end 167.32758 -123.04776)
		(width 0.127)
		(layer "In15.Cu")
		(net "PWRGD_PVCCD_HV_CPU1")
	)
	(segment
		(start 139.359132 -117.02796)
		(end 134.86638 -117.02796)
		(width 0.127)
		(layer "In15.Cu")
		(net "PWRGD_PVCCD_HV_CPU1")
	)
	(segment
		(start 165.126924 -126.319788)
		(end 163.176712 -126.319788)
		(width 0.127)
		(layer "In15.Cu")
		(net "PWRGD_PVCCD_HV_CPU1")
	)
	(segment
		(start 172.55744 -119.537988)
		(end 172.55744 -119.946928)
		(width 0.127)
		(layer "In15.Cu")
		(net "PWRGD_PVCCD_HV_CPU1")
	)
	(segment
		(start 167.32758 -123.04776)
		(end 167.32758 -124.119132)
		(width 0.127)
		(layer "In15.Cu")
		(net "PWRGD_PVCCD_HV_CPU1")
	)
	(segment
		(start 163.176712 -126.319788)
		(end 162.899852 -126.596648)
		(width 0.127)
		(layer "In15.Cu")
		(net "PWRGD_PVCCD_HV_CPU1")
	)
	(segment
		(start 133.492748 -115.654328)
		(end 100.50526 -115.654328)
		(width 0.127)
		(layer "In15.Cu")
		(net "PWRGD_PVCCD_HV_CPU1")
	)
	(segment
		(start 174.955454 -119.375428)
		(end 172.72 -119.375428)
		(width 0.127)
		(layer "In15.Cu")
		(net "PWRGD_PVCCD_HV_CPU1")
	)
	(segment
		(start 155.112974 -125.32868)
		(end 151.292052 -125.32868)
		(width 0.127)
		(layer "In15.Cu")
		(net "PWRGD_PVCCD_HV_CPU1")
	)
	(segment
		(start 171.764452 -120.170448)
		(end 170.75658 -121.17832)
		(width 0.127)
		(layer "In15.Cu")
		(net "PWRGD_PVCCD_HV_CPU1")
	)
	(segment
		(start 436.842916 -120.614186)
		(end 436.397908 -120.614186)
		(width 0.12954)
		(layer "F.Cu")
		(net "PWRGD_PVCCD_HV_CPU0_R")
	)
	(segment
		(start 436.281068 -120.497346)
		(end 435.790594 -120.497346)
		(width 0.12954)
		(layer "F.Cu")
		(net "PWRGD_PVCCD_HV_CPU0_R")
	)
	(segment
		(start 436.397908 -120.614186)
		(end 436.281068 -120.497346)
		(width 0.12954)
		(layer "F.Cu")
		(net "PWRGD_PVCCD_HV_CPU0_R")
	)
	(segment
		(start 435.790594 -120.497346)
		(end 435.414928 -120.873012)
		(width 0.12954)
		(layer "F.Cu")
		(net "PWRGD_PVCCD_HV_CPU0_R")
	)
	(segment
		(start 435.414928 -120.873012)
		(end 435.414928 -121.361454)
		(width 0.12954)
		(layer "F.Cu")
		(net "PWRGD_PVCCD_HV_CPU0_R")
	)
	(segment
		(start 435.187852 -121.58853)
		(end 434.901086 -121.58853)
		(width 0.12954)
		(layer "F.Cu")
		(net "PWRGD_PVCCD_HV_CPU0_R")
	)
	(segment
		(start 435.414928 -121.361454)
		(end 435.187852 -121.58853)
		(width 0.12954)
		(layer "F.Cu")
		(net "PWRGD_PVCCD_HV_CPU0_R")
	)
	(via
		(at 436.571644 -118.749318)
		(size 0.6604)
		(drill 0.3302)
		(layers "F.Cu" "B.Cu")
		(net "PWRGD_PVCCD_HV_CPU0_R")
	)
	(via
		(at 435.790594 -120.497346)
		(size 0.508)
		(drill 0.254)
		(layers "F.Cu" "B.Cu")
		(net "PWRGD_PVCCD_HV_CPU0_R")
	)
	(segment
		(start 436.571644 -119.952008)
		(end 436.571644 -118.749318)
		(width 0.12954)
		(layer "B.Cu")
		(net "PWRGD_PVCCD_HV_CPU0_R")
	)
	(segment
		(start 435.790594 -120.497346)
		(end 436.024782 -120.497346)
		(width 0.12954)
		(layer "B.Cu")
		(net "PWRGD_PVCCD_HV_CPU0_R")
	)
	(segment
		(start 436.368444 -120.841008)
		(end 436.571644 -120.841008)
		(width 0.12954)
		(layer "B.Cu")
		(net "PWRGD_PVCCD_HV_CPU0_R")
	)
	(segment
		(start 436.024782 -120.497346)
		(end 436.368444 -120.841008)
		(width 0.12954)
		(layer "B.Cu")
		(net "PWRGD_PVCCD_HV_CPU0_R")
	)
	(segment
		(start 436.571644 -119.952008)
		(end 436.571644 -120.841008)
		(width 0.12954)
		(layer "B.Cu")
		(net "PWRGD_PVCCD_HV_CPU0_R")
	)
	(segment
		(start 99.986846 -102.693216)
		(end 99.351846 -102.693216)
		(width 0.12954)
		(layer "F.Cu")
		(net "PWRGD_PVCCD_HV_CPU0")
	)
	(segment
		(start 174.155608 -113.77549)
		(end 173.755558 -114.17554)
		(width 0.12954)
		(layer "F.Cu")
		(net "PWRGD_PVCCD_HV_CPU0")
	)
	(via
		(at 437.18988 -116.423948)
		(size 0.508)
		(drill 0.254)
		(layers "F.Cu" "B.Cu")
		(net "PWRGD_PVCCD_HV_CPU0")
	)
	(via
		(at 99.351846 -102.693216)
		(size 0.508)
		(drill 0.254)
		(layers "F.Cu" "B.Cu")
		(net "PWRGD_PVCCD_HV_CPU0")
	)
	(via
		(at 168.405556 -125.44044)
		(size 0.508)
		(drill 0.254)
		(layers "F.Cu" "B.Cu")
		(net "PWRGD_PVCCD_HV_CPU0")
	)
	(via
		(at 98.73488 -109.438948)
		(size 0.508)
		(drill 0.254)
		(layers "F.Cu" "B.Cu")
		(net "PWRGD_PVCCD_HV_CPU0")
	)
	(via
		(at 173.755558 -114.17554)
		(size 0.4572)
		(drill 0.254)
		(layers "F.Cu" "B.Cu")
		(net "PWRGD_PVCCD_HV_CPU0")
	)
	(segment
		(start 438.74182 -121.222008)
		(end 438.173368 -121.222008)
		(width 0.12954)
		(layer "B.Cu")
		(net "PWRGD_PVCCD_HV_CPU0")
	)
	(segment
		(start 437.792368 -120.841008)
		(end 437.371744 -120.841008)
		(width 0.12954)
		(layer "B.Cu")
		(net "PWRGD_PVCCD_HV_CPU0")
	)
	(segment
		(start 437.18988 -116.474748)
		(end 439.12028 -118.405148)
		(width 0.12954)
		(layer "B.Cu")
		(net "PWRGD_PVCCD_HV_CPU0")
	)
	(segment
		(start 439.12028 -118.405148)
		(end 439.12028 -120.843548)
		(width 0.12954)
		(layer "B.Cu")
		(net "PWRGD_PVCCD_HV_CPU0")
	)
	(segment
		(start 437.18988 -116.423948)
		(end 437.18988 -116.474748)
		(width 0.12954)
		(layer "B.Cu")
		(net "PWRGD_PVCCD_HV_CPU0")
	)
	(segment
		(start 439.12028 -120.843548)
		(end 438.74182 -121.222008)
		(width 0.12954)
		(layer "B.Cu")
		(net "PWRGD_PVCCD_HV_CPU0")
	)
	(segment
		(start 438.173368 -121.222008)
		(end 437.792368 -120.841008)
		(width 0.12954)
		(layer "B.Cu")
		(net "PWRGD_PVCCD_HV_CPU0")
	)
	(segment
		(start 98.935286 -102.693216)
		(end 99.351846 -102.693216)
		(width 0.127)
		(layer "In2.Cu")
		(net "PWRGD_PVCCD_HV_CPU0")
	)
	(segment
		(start 98.73488 -102.893622)
		(end 98.935286 -102.693216)
		(width 0.127)
		(layer "In2.Cu")
		(net "PWRGD_PVCCD_HV_CPU0")
	)
	(segment
		(start 98.73488 -109.438948)
		(end 98.73488 -102.893622)
		(width 0.127)
		(layer "In2.Cu")
		(net "PWRGD_PVCCD_HV_CPU0")
	)
	(segment
		(start 169.58945 -113.768378)
		(end 173.348396 -113.768378)
		(width 0.127)
		(layer "In11.Cu")
		(net "PWRGD_PVCCD_HV_CPU0")
	)
	(segment
		(start 168.9735 -124.872496)
		(end 168.9735 -114.384328)
		(width 0.127)
		(layer "In11.Cu")
		(net "PWRGD_PVCCD_HV_CPU0")
	)
	(segment
		(start 168.9735 -114.384328)
		(end 169.58945 -113.768378)
		(width 0.127)
		(layer "In11.Cu")
		(net "PWRGD_PVCCD_HV_CPU0")
	)
	(segment
		(start 173.348396 -113.768378)
		(end 173.755558 -114.17554)
		(width 0.127)
		(layer "In11.Cu")
		(net "PWRGD_PVCCD_HV_CPU0")
	)
	(segment
		(start 168.405556 -125.44044)
		(end 168.9735 -124.872496)
		(width 0.127)
		(layer "In11.Cu")
		(net "PWRGD_PVCCD_HV_CPU0")
	)
	(segment
		(start 416.97656 -123.535948)
		(end 425.96816 -114.544348)
		(width 0.127)
		(layer "In13.Cu")
		(net "PWRGD_PVCCD_HV_CPU0")
	)
	(segment
		(start 216.31656 -122.951748)
		(end 224.24644 -115.021868)
		(width 0.127)
		(layer "In13.Cu")
		(net "PWRGD_PVCCD_HV_CPU0")
	)
	(segment
		(start 177.42408 -126.101348)
		(end 180.34508 -126.101348)
		(width 0.127)
		(layer "In13.Cu")
		(net "PWRGD_PVCCD_HV_CPU0")
	)
	(segment
		(start 181.08168 -125.364748)
		(end 186.99988 -125.364748)
		(width 0.127)
		(layer "In13.Cu")
		(net "PWRGD_PVCCD_HV_CPU0")
	)
	(segment
		(start 192.03924 -124.856748)
		(end 193.183002 -126.00051)
		(width 0.127)
		(layer "In13.Cu")
		(net "PWRGD_PVCCD_HV_CPU0")
	)
	(segment
		(start 224.24644 -115.021868)
		(end 239.9538 -115.021868)
		(width 0.127)
		(layer "In13.Cu")
		(net "PWRGD_PVCCD_HV_CPU0")
	)
	(segment
		(start 437.18988 -115.230148)
		(end 437.18988 -116.423948)
		(width 0.127)
		(layer "In13.Cu")
		(net "PWRGD_PVCCD_HV_CPU0")
	)
	(segment
		(start 180.34508 -126.101348)
		(end 181.08168 -125.364748)
		(width 0.127)
		(layer "In13.Cu")
		(net "PWRGD_PVCCD_HV_CPU0")
	)
	(segment
		(start 425.96816 -114.544348)
		(end 436.50408 -114.544348)
		(width 0.127)
		(layer "In13.Cu")
		(net "PWRGD_PVCCD_HV_CPU0")
	)
	(segment
		(start 436.50408 -114.544348)
		(end 437.18988 -115.230148)
		(width 0.127)
		(layer "In13.Cu")
		(net "PWRGD_PVCCD_HV_CPU0")
	)
	(segment
		(start 193.183002 -126.00051)
		(end 199.744838 -126.00051)
		(width 0.127)
		(layer "In13.Cu")
		(net "PWRGD_PVCCD_HV_CPU0")
	)
	(segment
		(start 239.9538 -115.021868)
		(end 242.64112 -117.709188)
		(width 0.127)
		(layer "In13.Cu")
		(net "PWRGD_PVCCD_HV_CPU0")
	)
	(segment
		(start 186.99988 -125.364748)
		(end 187.50788 -124.856748)
		(width 0.127)
		(layer "In13.Cu")
		(net "PWRGD_PVCCD_HV_CPU0")
	)
	(segment
		(start 187.50788 -124.856748)
		(end 192.03924 -124.856748)
		(width 0.127)
		(layer "In13.Cu")
		(net "PWRGD_PVCCD_HV_CPU0")
	)
	(segment
		(start 252.3236 -123.535948)
		(end 416.97656 -123.535948)
		(width 0.127)
		(layer "In13.Cu")
		(net "PWRGD_PVCCD_HV_CPU0")
	)
	(segment
		(start 246.49684 -117.709188)
		(end 252.3236 -123.535948)
		(width 0.127)
		(layer "In13.Cu")
		(net "PWRGD_PVCCD_HV_CPU0")
	)
	(segment
		(start 176.763172 -125.44044)
		(end 177.42408 -126.101348)
		(width 0.127)
		(layer "In13.Cu")
		(net "PWRGD_PVCCD_HV_CPU0")
	)
	(segment
		(start 242.64112 -117.709188)
		(end 246.49684 -117.709188)
		(width 0.127)
		(layer "In13.Cu")
		(net "PWRGD_PVCCD_HV_CPU0")
	)
	(segment
		(start 199.744838 -126.00051)
		(end 202.7936 -122.951748)
		(width 0.127)
		(layer "In13.Cu")
		(net "PWRGD_PVCCD_HV_CPU0")
	)
	(segment
		(start 202.7936 -122.951748)
		(end 216.31656 -122.951748)
		(width 0.127)
		(layer "In13.Cu")
		(net "PWRGD_PVCCD_HV_CPU0")
	)
	(segment
		(start 168.405556 -125.44044)
		(end 176.763172 -125.44044)
		(width 0.127)
		(layer "In13.Cu")
		(net "PWRGD_PVCCD_HV_CPU0")
	)
	(segment
		(start 127.98552 -107.330748)
		(end 129.420874 -108.766102)
		(width 0.127)
		(layer "In15.Cu")
		(net "PWRGD_PVCCD_HV_CPU0")
	)
	(segment
		(start 173.268386 -113.688368)
		(end 173.755558 -114.17554)
		(width 0.127)
		(layer "In15.Cu")
		(net "PWRGD_PVCCD_HV_CPU0")
	)
	(segment
		(start 157.53334 -117.833648)
		(end 157.87624 -118.176548)
		(width 0.127)
		(layer "In15.Cu")
		(net "PWRGD_PVCCD_HV_CPU0")
	)
	(segment
		(start 111.63808 -109.007148)
		(end 112.75568 -110.124748)
		(width 0.127)
		(layer "In15.Cu")
		(net "PWRGD_PVCCD_HV_CPU0")
	)
	(segment
		(start 165.812724 -116.753132)
		(end 166.117016 -116.753132)
		(width 0.127)
		(layer "In15.Cu")
		(net "PWRGD_PVCCD_HV_CPU0")
	)
	(segment
		(start 100.56368 -109.007148)
		(end 111.63808 -109.007148)
		(width 0.127)
		(layer "In15.Cu")
		(net "PWRGD_PVCCD_HV_CPU0")
	)
	(segment
		(start 152.768808 -113.337848)
		(end 155.070048 -115.639088)
		(width 0.127)
		(layer "In15.Cu")
		(net "PWRGD_PVCCD_HV_CPU0")
	)
	(segment
		(start 171.248832 -113.688368)
		(end 173.268386 -113.688368)
		(width 0.127)
		(layer "In15.Cu")
		(net "PWRGD_PVCCD_HV_CPU0")
	)
	(segment
		(start 112.75568 -110.124748)
		(end 124.36348 -110.124748)
		(width 0.127)
		(layer "In15.Cu")
		(net "PWRGD_PVCCD_HV_CPU0")
	)
	(segment
		(start 166.117016 -116.753132)
		(end 168.646348 -114.2238)
		(width 0.127)
		(layer "In15.Cu")
		(net "PWRGD_PVCCD_HV_CPU0")
	)
	(segment
		(start 170.7134 -114.2238)
		(end 171.248832 -113.688368)
		(width 0.127)
		(layer "In15.Cu")
		(net "PWRGD_PVCCD_HV_CPU0")
	)
	(segment
		(start 124.36348 -110.124748)
		(end 127.15748 -107.330748)
		(width 0.127)
		(layer "In15.Cu")
		(net "PWRGD_PVCCD_HV_CPU0")
	)
	(segment
		(start 168.646348 -114.2238)
		(end 170.7134 -114.2238)
		(width 0.127)
		(layer "In15.Cu")
		(net "PWRGD_PVCCD_HV_CPU0")
	)
	(segment
		(start 127.15748 -107.330748)
		(end 127.98552 -107.330748)
		(width 0.127)
		(layer "In15.Cu")
		(net "PWRGD_PVCCD_HV_CPU0")
	)
	(segment
		(start 157.87624 -118.176548)
		(end 164.389308 -118.176548)
		(width 0.127)
		(layer "In15.Cu")
		(net "PWRGD_PVCCD_HV_CPU0")
	)
	(segment
		(start 157.53334 -116.987828)
		(end 157.53334 -117.833648)
		(width 0.127)
		(layer "In15.Cu")
		(net "PWRGD_PVCCD_HV_CPU0")
	)
	(segment
		(start 145.84807 -108.766102)
		(end 150.419816 -113.337848)
		(width 0.127)
		(layer "In15.Cu")
		(net "PWRGD_PVCCD_HV_CPU0")
	)
	(segment
		(start 150.419816 -113.337848)
		(end 152.768808 -113.337848)
		(width 0.127)
		(layer "In15.Cu")
		(net "PWRGD_PVCCD_HV_CPU0")
	)
	(segment
		(start 156.1846 -115.639088)
		(end 157.53334 -116.987828)
		(width 0.127)
		(layer "In15.Cu")
		(net "PWRGD_PVCCD_HV_CPU0")
	)
	(segment
		(start 164.389308 -118.176548)
		(end 165.812724 -116.753132)
		(width 0.127)
		(layer "In15.Cu")
		(net "PWRGD_PVCCD_HV_CPU0")
	)
	(segment
		(start 98.73488 -109.438948)
		(end 100.13188 -109.438948)
		(width 0.127)
		(layer "In15.Cu")
		(net "PWRGD_PVCCD_HV_CPU0")
	)
	(segment
		(start 100.13188 -109.438948)
		(end 100.56368 -109.007148)
		(width 0.127)
		(layer "In15.Cu")
		(net "PWRGD_PVCCD_HV_CPU0")
	)
	(segment
		(start 129.420874 -108.766102)
		(end 145.84807 -108.766102)
		(width 0.127)
		(layer "In15.Cu")
		(net "PWRGD_PVCCD_HV_CPU0")
	)
	(segment
		(start 155.070048 -115.639088)
		(end 156.1846 -115.639088)
		(width 0.127)
		(layer "In15.Cu")
		(net "PWRGD_PVCCD_HV_CPU0")
	)
	(segment
		(start 145.346928 -13.600176)
		(end 145.346928 -11.14298)
		(width 0.12954)
		(layer "F.Cu")
		(net "PWRGD_PS_PWROK_R")
	)
	(segment
		(start 145.346928 -11.14298)
		(end 145.59026 -10.899648)
		(width 0.12954)
		(layer "F.Cu")
		(net "PWRGD_PS_PWROK_R")
	)
	(via
		(at 145.59026 -10.899648)
		(size 0.508)
		(drill 0.254)
		(layers "F.Cu" "B.Cu")
		(net "PWRGD_PS_PWROK_R")
	)
	(segment
		(start 145.59026 -10.899648)
		(end 145.59026 -12.953238)
		(width 0.12954)
		(layer "B.Cu")
		(net "PWRGD_PS_PWROK_R")
	)
	(segment
		(start 145.59026 -12.953238)
		(end 145.18132 -13.362178)
		(width 0.12954)
		(layer "B.Cu")
		(net "PWRGD_PS_PWROK_R")
	)
	(segment
		(start 175.755554 -116.975382)
		(end 175.355504 -117.375432)
		(width 0.12954)
		(layer "F.Cu")
		(net "PWRGD_PS_PWROK_PLD_ISO_R")
	)
	(segment
		(start 172.77588 -129.866898)
		(end 172.77588 -129.250948)
		(width 0.12954)
		(layer "F.Cu")
		(net "PWRGD_PS_PWROK_PLD_ISO_R")
	)
	(via
		(at 175.355504 -117.375432)
		(size 0.4572)
		(drill 0.254)
		(layers "F.Cu" "B.Cu")
		(net "PWRGD_PS_PWROK_PLD_ISO_R")
	)
	(via
		(at 172.77588 -129.250948)
		(size 0.508)
		(drill 0.254)
		(layers "F.Cu" "B.Cu")
		(net "PWRGD_PS_PWROK_PLD_ISO_R")
	)
	(segment
		(start 174.958248 -117.772688)
		(end 174.958248 -118.34368)
		(width 0.127)
		(layer "In2.Cu")
		(net "PWRGD_PS_PWROK_PLD_ISO_R")
	)
	(segment
		(start 174.15002 -121.539508)
		(end 173.89348 -121.796048)
		(width 0.127)
		(layer "In2.Cu")
		(net "PWRGD_PS_PWROK_PLD_ISO_R")
	)
	(segment
		(start 174.15002 -118.656608)
		(end 174.15002 -121.539508)
		(width 0.127)
		(layer "In2.Cu")
		(net "PWRGD_PS_PWROK_PLD_ISO_R")
	)
	(segment
		(start 173.89348 -121.796048)
		(end 173.63186 -121.796048)
		(width 0.127)
		(layer "In2.Cu")
		(net "PWRGD_PS_PWROK_PLD_ISO_R")
	)
	(segment
		(start 174.22876 -118.577868)
		(end 174.15002 -118.656608)
		(width 0.127)
		(layer "In2.Cu")
		(net "PWRGD_PS_PWROK_PLD_ISO_R")
	)
	(segment
		(start 173.63186 -121.796048)
		(end 172.0342 -123.393708)
		(width 0.127)
		(layer "In2.Cu")
		(net "PWRGD_PS_PWROK_PLD_ISO_R")
	)
	(segment
		(start 174.958248 -118.34368)
		(end 174.72406 -118.577868)
		(width 0.127)
		(layer "In2.Cu")
		(net "PWRGD_PS_PWROK_PLD_ISO_R")
	)
	(segment
		(start 172.0342 -128.509268)
		(end 172.77588 -129.250948)
		(width 0.127)
		(layer "In2.Cu")
		(net "PWRGD_PS_PWROK_PLD_ISO_R")
	)
	(segment
		(start 172.0342 -123.393708)
		(end 172.0342 -128.509268)
		(width 0.127)
		(layer "In2.Cu")
		(net "PWRGD_PS_PWROK_PLD_ISO_R")
	)
	(segment
		(start 174.72406 -118.577868)
		(end 174.22876 -118.577868)
		(width 0.127)
		(layer "In2.Cu")
		(net "PWRGD_PS_PWROK_PLD_ISO_R")
	)
	(segment
		(start 175.355504 -117.375432)
		(end 174.958248 -117.772688)
		(width 0.127)
		(layer "In2.Cu")
		(net "PWRGD_PS_PWROK_PLD_ISO_R")
	)
	(segment
		(start 150.93696 -131.282948)
		(end 150.241 -131.282948)
		(width 0.12954)
		(layer "F.Cu")
		(net "PWRGD_PS_PWROK_PLD")
	)
	(segment
		(start 172.77588 -133.295898)
		(end 173.63059 -134.150608)
		(width 0.12954)
		(layer "F.Cu")
		(net "PWRGD_PS_PWROK_PLD")
	)
	(segment
		(start 102.58425 -92.87256)
		(end 101.89845 -92.87256)
		(width 0.12954)
		(layer "F.Cu")
		(net "PWRGD_PS_PWROK_PLD")
	)
	(segment
		(start 155.956 -135.473948)
		(end 151.765 -131.282948)
		(width 0.12954)
		(layer "F.Cu")
		(net "PWRGD_PS_PWROK_PLD")
	)
	(segment
		(start 173.63059 -134.987792)
		(end 173.144434 -135.473948)
		(width 0.12954)
		(layer "F.Cu")
		(net "PWRGD_PS_PWROK_PLD")
	)
	(segment
		(start 151.765 -131.282948)
		(end 150.93696 -131.282948)
		(width 0.12954)
		(layer "F.Cu")
		(net "PWRGD_PS_PWROK_PLD")
	)
	(segment
		(start 173.63059 -134.150608)
		(end 173.63059 -134.987792)
		(width 0.12954)
		(layer "F.Cu")
		(net "PWRGD_PS_PWROK_PLD")
	)
	(segment
		(start 173.144434 -135.473948)
		(end 155.956 -135.473948)
		(width 0.12954)
		(layer "F.Cu")
		(net "PWRGD_PS_PWROK_PLD")
	)
	(via
		(at 102.58425 -92.87256)
		(size 0.508)
		(drill 0.254)
		(layers "F.Cu" "B.Cu")
		(net "PWRGD_PS_PWROK_PLD")
	)
	(via
		(at 150.241 -131.282948)
		(size 0.508)
		(drill 0.254)
		(layers "F.Cu" "B.Cu")
		(net "PWRGD_PS_PWROK_PLD")
	)
	(via
		(at 102.235 -125.821948)
		(size 0.508)
		(drill 0.254)
		(layers "F.Cu" "B.Cu")
		(net "PWRGD_PS_PWROK_PLD")
	)
	(segment
		(start 102.235 -125.821948)
		(end 102.235 -112.683544)
		(width 0.127)
		(layer "In2.Cu")
		(net "PWRGD_PS_PWROK_PLD")
	)
	(segment
		(start 103.40848 -93.69679)
		(end 102.58425 -92.87256)
		(width 0.127)
		(layer "In2.Cu")
		(net "PWRGD_PS_PWROK_PLD")
	)
	(segment
		(start 101.32568 -101.768148)
		(end 103.40848 -99.685348)
		(width 0.127)
		(layer "In2.Cu")
		(net "PWRGD_PS_PWROK_PLD")
	)
	(segment
		(start 101.32568 -111.774224)
		(end 101.32568 -101.768148)
		(width 0.127)
		(layer "In2.Cu")
		(net "PWRGD_PS_PWROK_PLD")
	)
	(segment
		(start 103.40848 -99.685348)
		(end 103.40848 -93.69679)
		(width 0.127)
		(layer "In2.Cu")
		(net "PWRGD_PS_PWROK_PLD")
	)
	(segment
		(start 102.235 -112.683544)
		(end 101.32568 -111.774224)
		(width 0.127)
		(layer "In2.Cu")
		(net "PWRGD_PS_PWROK_PLD")
	)
	(segment
		(start 123.39701 -122.189748)
		(end 122.71248 -121.505218)
		(width 0.127)
		(layer "In6.Cu")
		(net "PWRGD_PS_PWROK_PLD")
	)
	(segment
		(start 112.18164 -122.62866)
		(end 110.79226 -122.62866)
		(width 0.127)
		(layer "In6.Cu")
		(net "PWRGD_PS_PWROK_PLD")
	)
	(segment
		(start 134.97941 -125.237748)
		(end 130.35661 -125.237748)
		(width 0.127)
		(layer "In6.Cu")
		(net "PWRGD_PS_PWROK_PLD")
	)
	(segment
		(start 110.79226 -122.62866)
		(end 107.598972 -125.821948)
		(width 0.127)
		(layer "In6.Cu")
		(net "PWRGD_PS_PWROK_PLD")
	)
	(segment
		(start 122.71248 -120.692418)
		(end 121.46661 -119.446548)
		(width 0.127)
		(layer "In6.Cu")
		(net "PWRGD_PS_PWROK_PLD")
	)
	(segment
		(start 115.363752 -119.446548)
		(end 112.18164 -122.62866)
		(width 0.127)
		(layer "In6.Cu")
		(net "PWRGD_PS_PWROK_PLD")
	)
	(segment
		(start 150.241 -130.440938)
		(end 146.51101 -126.710948)
		(width 0.127)
		(layer "In6.Cu")
		(net "PWRGD_PS_PWROK_PLD")
	)
	(segment
		(start 136.45261 -126.710948)
		(end 134.97941 -125.237748)
		(width 0.127)
		(layer "In6.Cu")
		(net "PWRGD_PS_PWROK_PLD")
	)
	(segment
		(start 130.35661 -125.237748)
		(end 127.30861 -122.189748)
		(width 0.127)
		(layer "In6.Cu")
		(net "PWRGD_PS_PWROK_PLD")
	)
	(segment
		(start 122.71248 -121.505218)
		(end 122.71248 -120.692418)
		(width 0.127)
		(layer "In6.Cu")
		(net "PWRGD_PS_PWROK_PLD")
	)
	(segment
		(start 146.51101 -126.710948)
		(end 136.45261 -126.710948)
		(width 0.127)
		(layer "In6.Cu")
		(net "PWRGD_PS_PWROK_PLD")
	)
	(segment
		(start 121.46661 -119.446548)
		(end 115.363752 -119.446548)
		(width 0.127)
		(layer "In6.Cu")
		(net "PWRGD_PS_PWROK_PLD")
	)
	(segment
		(start 127.30861 -122.189748)
		(end 123.39701 -122.189748)
		(width 0.127)
		(layer "In6.Cu")
		(net "PWRGD_PS_PWROK_PLD")
	)
	(segment
		(start 107.598972 -125.821948)
		(end 102.235 -125.821948)
		(width 0.127)
		(layer "In6.Cu")
		(net "PWRGD_PS_PWROK_PLD")
	)
	(segment
		(start 150.241 -131.282948)
		(end 150.241 -130.440938)
		(width 0.127)
		(layer "In6.Cu")
		(net "PWRGD_PS_PWROK_PLD")
	)
	(segment
		(start 170.36288 -132.552948)
		(end 170.36288 -133.157976)
		(width 0.12954)
		(layer "F.Cu")
		(net "PWRGD_PS_PWROK")
	)
	(segment
		(start 28.4861 -47.335948)
		(end 29.4259 -47.335948)
		(width 0.12954)
		(layer "F.Cu")
		(net "PWRGD_PS_PWROK")
	)
	(segment
		(start 170.500802 -133.295898)
		(end 171.50588 -133.295898)
		(width 0.12954)
		(layer "F.Cu")
		(net "PWRGD_PS_PWROK")
	)
	(segment
		(start 170.36288 -133.157976)
		(end 170.500802 -133.295898)
		(width 0.12954)
		(layer "F.Cu")
		(net "PWRGD_PS_PWROK")
	)
	(via
		(at 29.4259 -47.335948)
		(size 0.508)
		(drill 0.254)
		(layers "F.Cu" "B.Cu")
		(net "PWRGD_PS_PWROK")
	)
	(via
		(at 146.6342 -16.937228)
		(size 0.508)
		(drill 0.254)
		(layers "F.Cu" "B.Cu")
		(net "PWRGD_PS_PWROK")
	)
	(via
		(at 155.12288 -110.835948)
		(size 0.508)
		(drill 0.254)
		(layers "F.Cu" "B.Cu")
		(net "PWRGD_PS_PWROK")
	)
	(via
		(at 170.36288 -132.552948)
		(size 0.508)
		(drill 0.254)
		(layers "F.Cu" "B.Cu")
		(net "PWRGD_PS_PWROK")
	)
	(segment
		(start 145.18132 -16.032988)
		(end 145.18132 -14.162278)
		(width 0.12954)
		(layer "B.Cu")
		(net "PWRGD_PS_PWROK")
	)
	(segment
		(start 146.6342 -16.937228)
		(end 146.08556 -16.937228)
		(width 0.12954)
		(layer "B.Cu")
		(net "PWRGD_PS_PWROK")
	)
	(segment
		(start 146.08556 -16.937228)
		(end 145.18132 -16.032988)
		(width 0.12954)
		(layer "B.Cu")
		(net "PWRGD_PS_PWROK")
	)
	(segment
		(start 147.16506 -16.937228)
		(end 146.6342 -16.937228)
		(width 0.127)
		(layer "In2.Cu")
		(net "PWRGD_PS_PWROK")
	)
	(segment
		(start 145.34642 -70.699884)
		(end 147.876006 -68.170298)
		(width 0.127)
		(layer "In2.Cu")
		(net "PWRGD_PS_PWROK")
	)
	(segment
		(start 145.57248 -44.667424)
		(end 146.57832 -43.661584)
		(width 0.127)
		(layer "In2.Cu")
		(net "PWRGD_PS_PWROK")
	)
	(segment
		(start 147.88896 -34.793428)
		(end 147.88896 -17.661128)
		(width 0.127)
		(layer "In2.Cu")
		(net "PWRGD_PS_PWROK")
	)
	(segment
		(start 146.57832 -36.104068)
		(end 147.88896 -34.793428)
		(width 0.127)
		(layer "In2.Cu")
		(net "PWRGD_PS_PWROK")
	)
	(segment
		(start 145.34642 -80.3275)
		(end 145.34642 -70.699884)
		(width 0.127)
		(layer "In2.Cu")
		(net "PWRGD_PS_PWROK")
	)
	(segment
		(start 151.93518 -107.258104)
		(end 151.93518 -96.945196)
		(width 0.127)
		(layer "In2.Cu")
		(net "PWRGD_PS_PWROK")
	)
	(segment
		(start 146.57832 -43.661584)
		(end 146.57832 -36.104068)
		(width 0.127)
		(layer "In2.Cu")
		(net "PWRGD_PS_PWROK")
	)
	(segment
		(start 147.88896 -17.661128)
		(end 147.16506 -16.937228)
		(width 0.127)
		(layer "In2.Cu")
		(net "PWRGD_PS_PWROK")
	)
	(segment
		(start 155.12288 -110.445804)
		(end 151.93518 -107.258104)
		(width 0.127)
		(layer "In2.Cu")
		(net "PWRGD_PS_PWROK")
	)
	(segment
		(start 147.45208 -92.462096)
		(end 147.45208 -82.43316)
		(width 0.127)
		(layer "In2.Cu")
		(net "PWRGD_PS_PWROK")
	)
	(segment
		(start 147.45208 -82.43316)
		(end 145.34642 -80.3275)
		(width 0.127)
		(layer "In2.Cu")
		(net "PWRGD_PS_PWROK")
	)
	(segment
		(start 147.876006 -68.170298)
		(end 147.876006 -62.444122)
		(width 0.127)
		(layer "In2.Cu")
		(net "PWRGD_PS_PWROK")
	)
	(segment
		(start 155.12288 -110.835948)
		(end 155.12288 -110.445804)
		(width 0.127)
		(layer "In2.Cu")
		(net "PWRGD_PS_PWROK")
	)
	(segment
		(start 147.876006 -62.444122)
		(end 145.57248 -60.140596)
		(width 0.127)
		(layer "In2.Cu")
		(net "PWRGD_PS_PWROK")
	)
	(segment
		(start 145.57248 -60.140596)
		(end 145.57248 -44.667424)
		(width 0.127)
		(layer "In2.Cu")
		(net "PWRGD_PS_PWROK")
	)
	(segment
		(start 151.93518 -96.945196)
		(end 147.45208 -92.462096)
		(width 0.127)
		(layer "In2.Cu")
		(net "PWRGD_PS_PWROK")
	)
	(segment
		(start 169.85488 -131.35102)
		(end 169.85488 -132.044948)
		(width 0.127)
		(layer "In11.Cu")
		(net "PWRGD_PS_PWROK")
	)
	(segment
		(start 155.12288 -111.089948)
		(end 155.50388 -111.470948)
		(width 0.127)
		(layer "In11.Cu")
		(net "PWRGD_PS_PWROK")
	)
	(segment
		(start 155.12288 -110.835948)
		(end 155.12288 -111.089948)
		(width 0.127)
		(layer "In11.Cu")
		(net "PWRGD_PS_PWROK")
	)
	(segment
		(start 156.90088 -111.470948)
		(end 157.28188 -111.089948)
		(width 0.127)
		(layer "In11.Cu")
		(net "PWRGD_PS_PWROK")
	)
	(segment
		(start 158.93288 -103.342948)
		(end 164.39388 -103.342948)
		(width 0.127)
		(layer "In11.Cu")
		(net "PWRGD_PS_PWROK")
	)
	(segment
		(start 164.39388 -103.342948)
		(end 165.02888 -103.977948)
		(width 0.127)
		(layer "In11.Cu")
		(net "PWRGD_PS_PWROK")
	)
	(segment
		(start 165.02888 -126.52502)
		(end 169.85488 -131.35102)
		(width 0.127)
		(layer "In11.Cu")
		(net "PWRGD_PS_PWROK")
	)
	(segment
		(start 157.28188 -104.993948)
		(end 158.93288 -103.342948)
		(width 0.127)
		(layer "In11.Cu")
		(net "PWRGD_PS_PWROK")
	)
	(segment
		(start 157.28188 -111.089948)
		(end 157.28188 -104.993948)
		(width 0.127)
		(layer "In11.Cu")
		(net "PWRGD_PS_PWROK")
	)
	(segment
		(start 155.50388 -111.470948)
		(end 156.90088 -111.470948)
		(width 0.127)
		(layer "In11.Cu")
		(net "PWRGD_PS_PWROK")
	)
	(segment
		(start 169.85488 -132.044948)
		(end 170.36288 -132.552948)
		(width 0.127)
		(layer "In11.Cu")
		(net "PWRGD_PS_PWROK")
	)
	(segment
		(start 165.02888 -103.977948)
		(end 165.02888 -126.52502)
		(width 0.127)
		(layer "In11.Cu")
		(net "PWRGD_PS_PWROK")
	)
	(segment
		(start 31.868364 -44.893484)
		(end 29.4259 -47.335948)
		(width 0.127)
		(layer "In15.Cu")
		(net "PWRGD_PS_PWROK")
	)
	(segment
		(start 79.74711 -35.944048)
		(end 78.24851 -34.445448)
		(width 0.127)
		(layer "In15.Cu")
		(net "PWRGD_PS_PWROK")
	)
	(segment
		(start 52.959 -34.889948)
		(end 42.955464 -44.893484)
		(width 0.127)
		(layer "In15.Cu")
		(net "PWRGD_PS_PWROK")
	)
	(segment
		(start 137.45464 -28.250388)
		(end 130.90271 -34.802318)
		(width 0.127)
		(layer "In15.Cu")
		(net "PWRGD_PS_PWROK")
	)
	(segment
		(start 146.6088 -16.962628)
		(end 146.1008 -16.962628)
		(width 0.127)
		(layer "In15.Cu")
		(net "PWRGD_PS_PWROK")
	)
	(segment
		(start 64.3636 -35.321748)
		(end 63.9318 -34.889948)
		(width 0.127)
		(layer "In15.Cu")
		(net "PWRGD_PS_PWROK")
	)
	(segment
		(start 138.44524 -28.250388)
		(end 137.45464 -28.250388)
		(width 0.127)
		(layer "In15.Cu")
		(net "PWRGD_PS_PWROK")
	)
	(segment
		(start 63.9318 -34.889948)
		(end 52.959 -34.889948)
		(width 0.127)
		(layer "In15.Cu")
		(net "PWRGD_PS_PWROK")
	)
	(segment
		(start 146.6342 -16.937228)
		(end 146.6088 -16.962628)
		(width 0.127)
		(layer "In15.Cu")
		(net "PWRGD_PS_PWROK")
	)
	(segment
		(start 142.72768 -23.967948)
		(end 138.44524 -28.250388)
		(width 0.127)
		(layer "In15.Cu")
		(net "PWRGD_PS_PWROK")
	)
	(segment
		(start 67.3989 -34.445448)
		(end 66.5226 -35.321748)
		(width 0.127)
		(layer "In15.Cu")
		(net "PWRGD_PS_PWROK")
	)
	(segment
		(start 87.35695 -35.944048)
		(end 79.74711 -35.944048)
		(width 0.127)
		(layer "In15.Cu")
		(net "PWRGD_PS_PWROK")
	)
	(segment
		(start 146.1008 -16.962628)
		(end 142.72768 -20.335748)
		(width 0.127)
		(layer "In15.Cu")
		(net "PWRGD_PS_PWROK")
	)
	(segment
		(start 42.955464 -44.893484)
		(end 31.868364 -44.893484)
		(width 0.127)
		(layer "In15.Cu")
		(net "PWRGD_PS_PWROK")
	)
	(segment
		(start 78.24851 -34.445448)
		(end 67.3989 -34.445448)
		(width 0.127)
		(layer "In15.Cu")
		(net "PWRGD_PS_PWROK")
	)
	(segment
		(start 66.5226 -35.321748)
		(end 64.3636 -35.321748)
		(width 0.127)
		(layer "In15.Cu")
		(net "PWRGD_PS_PWROK")
	)
	(segment
		(start 142.72768 -20.335748)
		(end 142.72768 -23.967948)
		(width 0.127)
		(layer "In15.Cu")
		(net "PWRGD_PS_PWROK")
	)
	(segment
		(start 130.90271 -34.802318)
		(end 88.49868 -34.802318)
		(width 0.127)
		(layer "In15.Cu")
		(net "PWRGD_PS_PWROK")
	)
	(segment
		(start 88.49868 -34.802318)
		(end 87.35695 -35.944048)
		(width 0.127)
		(layer "In15.Cu")
		(net "PWRGD_PS_PWROK")
	)
	(segment
		(start 186.955684 -108.175552)
		(end 187.355734 -107.775502)
		(width 0.12954)
		(layer "F.Cu")
		(net "PWRGD_PLT_AUX_CPU1_LVT3_R")
	)
	(segment
		(start 184.730898 -192.75679)
		(end 183.857138 -193.63055)
		(width 0.12954)
		(layer "F.Cu")
		(net "PWRGD_PLT_AUX_CPU1_LVT3_R")
	)
	(segment
		(start 158.479744 -194.175888)
		(end 157.19044 -194.175888)
		(width 0.12954)
		(layer "F.Cu")
		(net "PWRGD_PLT_AUX_CPU1_LVT3_R")
	)
	(segment
		(start 159.025082 -193.63055)
		(end 158.479744 -194.175888)
		(width 0.12954)
		(layer "F.Cu")
		(net "PWRGD_PLT_AUX_CPU1_LVT3_R")
	)
	(segment
		(start 183.857138 -193.63055)
		(end 159.025082 -193.63055)
		(width 0.12954)
		(layer "F.Cu")
		(net "PWRGD_PLT_AUX_CPU1_LVT3_R")
	)
	(segment
		(start 193.704718 -192.75679)
		(end 184.730898 -192.75679)
		(width 0.12954)
		(layer "F.Cu")
		(net "PWRGD_PLT_AUX_CPU1_LVT3_R")
	)
	(segment
		(start 157.19044 -194.175888)
		(end 156.95676 -193.942208)
		(width 0.12954)
		(layer "F.Cu")
		(net "PWRGD_PLT_AUX_CPU1_LVT3_R")
	)
	(via
		(at 188.16828 -188.407548)
		(size 0.508)
		(drill 0.254)
		(layers "F.Cu" "B.Cu")
		(net "PWRGD_PLT_AUX_CPU1_LVT3_R")
	)
	(via
		(at 193.704718 -192.75679)
		(size 0.508)
		(drill 0.254)
		(layers "F.Cu" "B.Cu")
		(net "PWRGD_PLT_AUX_CPU1_LVT3_R")
	)
	(via
		(at 187.355734 -107.775502)
		(size 0.4572)
		(drill 0.254)
		(layers "F.Cu" "B.Cu")
		(net "PWRGD_PLT_AUX_CPU1_LVT3_R")
	)
	(via
		(at 156.95676 -193.942208)
		(size 0.508)
		(drill 0.254)
		(layers "F.Cu" "B.Cu")
		(net "PWRGD_PLT_AUX_CPU1_LVT3_R")
	)
	(segment
		(start 156.658818 -192.889378)
		(end 156.1465 -192.37706)
		(width 0.12954)
		(layer "B.Cu")
		(net "PWRGD_PLT_AUX_CPU1_LVT3_R")
	)
	(segment
		(start 156.95676 -193.942208)
		(end 156.658818 -193.644266)
		(width 0.12954)
		(layer "B.Cu")
		(net "PWRGD_PLT_AUX_CPU1_LVT3_R")
	)
	(segment
		(start 156.658818 -193.644266)
		(end 156.658818 -192.889378)
		(width 0.12954)
		(layer "B.Cu")
		(net "PWRGD_PLT_AUX_CPU1_LVT3_R")
	)
	(segment
		(start 192.938908 -191.99098)
		(end 192.938908 -188.113924)
		(width 0.127)
		(layer "In2.Cu")
		(net "PWRGD_PLT_AUX_CPU1_LVT3_R")
	)
	(segment
		(start 188.16828 -188.155072)
		(end 188.16828 -188.407548)
		(width 0.127)
		(layer "In2.Cu")
		(net "PWRGD_PLT_AUX_CPU1_LVT3_R")
	)
	(segment
		(start 189.069218 -187.254134)
		(end 188.16828 -188.155072)
		(width 0.127)
		(layer "In2.Cu")
		(net "PWRGD_PLT_AUX_CPU1_LVT3_R")
	)
	(segment
		(start 192.079118 -187.254134)
		(end 189.069218 -187.254134)
		(width 0.127)
		(layer "In2.Cu")
		(net "PWRGD_PLT_AUX_CPU1_LVT3_R")
	)
	(segment
		(start 193.704718 -192.75679)
		(end 192.938908 -191.99098)
		(width 0.127)
		(layer "In2.Cu")
		(net "PWRGD_PLT_AUX_CPU1_LVT3_R")
	)
	(segment
		(start 192.938908 -188.113924)
		(end 192.079118 -187.254134)
		(width 0.127)
		(layer "In2.Cu")
		(net "PWRGD_PLT_AUX_CPU1_LVT3_R")
	)
	(segment
		(start 186.7408 -161.326068)
		(end 185.276998 -159.862266)
		(width 0.127)
		(layer "In11.Cu")
		(net "PWRGD_PLT_AUX_CPU1_LVT3_R")
	)
	(segment
		(start 185.276998 -159.862266)
		(end 185.276998 -152.77084)
		(width 0.127)
		(layer "In11.Cu")
		(net "PWRGD_PLT_AUX_CPU1_LVT3_R")
	)
	(segment
		(start 190.37046 -115.359688)
		(end 190.37046 -110.790228)
		(width 0.127)
		(layer "In11.Cu")
		(net "PWRGD_PLT_AUX_CPU1_LVT3_R")
	)
	(segment
		(start 190.37046 -110.790228)
		(end 187.355734 -107.775502)
		(width 0.127)
		(layer "In11.Cu")
		(net "PWRGD_PLT_AUX_CPU1_LVT3_R")
	)
	(segment
		(start 188.6458 -133.568948)
		(end 188.6458 -127.145288)
		(width 0.127)
		(layer "In11.Cu")
		(net "PWRGD_PLT_AUX_CPU1_LVT3_R")
	)
	(segment
		(start 189.48908 -126.302008)
		(end 189.48908 -116.241068)
		(width 0.127)
		(layer "In11.Cu")
		(net "PWRGD_PLT_AUX_CPU1_LVT3_R")
	)
	(segment
		(start 189.48908 -116.241068)
		(end 190.37046 -115.359688)
		(width 0.127)
		(layer "In11.Cu")
		(net "PWRGD_PLT_AUX_CPU1_LVT3_R")
	)
	(segment
		(start 186.7408 -187.056268)
		(end 186.7408 -161.326068)
		(width 0.127)
		(layer "In11.Cu")
		(net "PWRGD_PLT_AUX_CPU1_LVT3_R")
	)
	(segment
		(start 188.72962 -133.652768)
		(end 188.6458 -133.568948)
		(width 0.127)
		(layer "In11.Cu")
		(net "PWRGD_PLT_AUX_CPU1_LVT3_R")
	)
	(segment
		(start 187.375038 -150.6728)
		(end 187.375038 -144.989804)
		(width 0.127)
		(layer "In11.Cu")
		(net "PWRGD_PLT_AUX_CPU1_LVT3_R")
	)
	(segment
		(start 187.375038 -144.989804)
		(end 188.52134 -143.843502)
		(width 0.127)
		(layer "In11.Cu")
		(net "PWRGD_PLT_AUX_CPU1_LVT3_R")
	)
	(segment
		(start 188.16828 -188.407548)
		(end 188.09208 -188.407548)
		(width 0.127)
		(layer "In11.Cu")
		(net "PWRGD_PLT_AUX_CPU1_LVT3_R")
	)
	(segment
		(start 188.09208 -188.407548)
		(end 186.7408 -187.056268)
		(width 0.127)
		(layer "In11.Cu")
		(net "PWRGD_PLT_AUX_CPU1_LVT3_R")
	)
	(segment
		(start 188.72962 -135.666988)
		(end 188.72962 -133.652768)
		(width 0.127)
		(layer "In11.Cu")
		(net "PWRGD_PLT_AUX_CPU1_LVT3_R")
	)
	(segment
		(start 188.52134 -143.843502)
		(end 188.52134 -135.875268)
		(width 0.127)
		(layer "In11.Cu")
		(net "PWRGD_PLT_AUX_CPU1_LVT3_R")
	)
	(segment
		(start 188.52134 -135.875268)
		(end 188.72962 -135.666988)
		(width 0.127)
		(layer "In11.Cu")
		(net "PWRGD_PLT_AUX_CPU1_LVT3_R")
	)
	(segment
		(start 188.6458 -127.145288)
		(end 189.48908 -126.302008)
		(width 0.127)
		(layer "In11.Cu")
		(net "PWRGD_PLT_AUX_CPU1_LVT3_R")
	)
	(segment
		(start 185.276998 -152.77084)
		(end 187.375038 -150.6728)
		(width 0.127)
		(layer "In11.Cu")
		(net "PWRGD_PLT_AUX_CPU1_LVT3_R")
	)
	(segment
		(start 121.038366 -229.808532)
		(end 121.038366 -229.272846)
		(width 0.12954)
		(layer "F.Cu")
		(net "PWRGD_PLT_AUX_CPU1_LVT3")
	)
	(segment
		(start 121.038112 -229.808786)
		(end 121.038366 -229.808532)
		(width 0.12954)
		(layer "F.Cu")
		(net "PWRGD_PLT_AUX_CPU1_LVT3")
	)
	(via
		(at 121.038366 -229.272846)
		(size 0.4572)
		(drill 0.2032)
		(layers "F.Cu" "B.Cu")
		(net "PWRGD_PLT_AUX_CPU1_LVT3")
	)
	(via
		(at 154.612086 -195.352162)
		(size 0.6604)
		(drill 0.3302)
		(layers "F.Cu" "B.Cu")
		(net "PWRGD_PLT_AUX_CPU1_LVT3")
	)
	(segment
		(start 136.340088 -229.537768)
		(end 136.490202 -229.387654)
		(width 0.0889)
		(layer "B.Cu")
		(net "PWRGD_PLT_AUX_CPU1_LVT3")
	)
	(segment
		(start 156.1465 -193.17716)
		(end 156.1465 -194.15506)
		(width 0.12954)
		(layer "B.Cu")
		(net "PWRGD_PLT_AUX_CPU1_LVT3")
	)
	(segment
		(start 143.620236 -229.13721)
		(end 152.251918 -220.505528)
		(width 0.12954)
		(layer "B.Cu")
		(net "PWRGD_PLT_AUX_CPU1_LVT3")
	)
	(segment
		(start 155.809188 -194.15506)
		(end 156.1465 -194.15506)
		(width 0.12954)
		(layer "B.Cu")
		(net "PWRGD_PLT_AUX_CPU1_LVT3")
	)
	(segment
		(start 124.044964 -229.597204)
		(end 124.059696 -229.588568)
		(width 0.0889)
		(layer "B.Cu")
		(net "PWRGD_PLT_AUX_CPU1_LVT3")
	)
	(segment
		(start 120.842278 -229.592124)
		(end 120.851168 -229.597204)
		(width 0.0889)
		(layer "B.Cu")
		(net "PWRGD_PLT_AUX_CPU1_LVT3")
	)
	(segment
		(start 138.149838 -229.257606)
		(end 138.270234 -229.13721)
		(width 0.12954)
		(layer "B.Cu")
		(net "PWRGD_PLT_AUX_CPU1_LVT3")
	)
	(segment
		(start 125.924564 -229.597204)
		(end 125.939296 -229.588568)
		(width 0.0889)
		(layer "B.Cu")
		(net "PWRGD_PLT_AUX_CPU1_LVT3")
	)
	(segment
		(start 121.225564 -229.597204)
		(end 121.240296 -229.588568)
		(width 0.0889)
		(layer "B.Cu")
		(net "PWRGD_PLT_AUX_CPU1_LVT3")
	)
	(segment
		(start 132.503164 -229.597204)
		(end 132.517896 -229.588568)
		(width 0.0889)
		(layer "B.Cu")
		(net "PWRGD_PLT_AUX_CPU1_LVT3")
	)
	(segment
		(start 128.743964 -229.597204)
		(end 128.754378 -229.591108)
		(width 0.0889)
		(layer "B.Cu")
		(net "PWRGD_PLT_AUX_CPU1_LVT3")
	)
	(segment
		(start 127.804164 -229.597204)
		(end 127.818896 -229.588568)
		(width 0.0889)
		(layer "B.Cu")
		(net "PWRGD_PLT_AUX_CPU1_LVT3")
	)
	(segment
		(start 138.01979 -229.387654)
		(end 138.149838 -229.257606)
		(width 0.0889)
		(layer "B.Cu")
		(net "PWRGD_PLT_AUX_CPU1_LVT3")
	)
	(segment
		(start 121.038366 -229.272846)
		(end 120.725692 -229.272846)
		(width 0.0889)
		(layer "B.Cu")
		(net "PWRGD_PLT_AUX_CPU1_LVT3")
	)
	(segment
		(start 154.612086 -195.352162)
		(end 155.809188 -194.15506)
		(width 0.12954)
		(layer "B.Cu")
		(net "PWRGD_PLT_AUX_CPU1_LVT3")
	)
	(segment
		(start 122.165364 -229.597204)
		(end 122.175778 -229.591108)
		(width 0.0889)
		(layer "B.Cu")
		(net "PWRGD_PLT_AUX_CPU1_LVT3")
	)
	(segment
		(start 130.623564 -229.597204)
		(end 130.638296 -229.588568)
		(width 0.0889)
		(layer "B.Cu")
		(net "PWRGD_PLT_AUX_CPU1_LVT3")
	)
	(segment
		(start 152.251918 -220.505528)
		(end 152.251918 -197.71233)
		(width 0.12954)
		(layer "B.Cu")
		(net "PWRGD_PLT_AUX_CPU1_LVT3")
	)
	(segment
		(start 126.864364 -229.597204)
		(end 126.879096 -229.588568)
		(width 0.0889)
		(layer "B.Cu")
		(net "PWRGD_PLT_AUX_CPU1_LVT3")
	)
	(segment
		(start 129.68351 -229.597204)
		(end 129.693924 -229.591108)
		(width 0.0889)
		(layer "B.Cu")
		(net "PWRGD_PLT_AUX_CPU1_LVT3")
	)
	(segment
		(start 138.270234 -229.13721)
		(end 143.620236 -229.13721)
		(width 0.12954)
		(layer "B.Cu")
		(net "PWRGD_PLT_AUX_CPU1_LVT3")
	)
	(segment
		(start 136.490202 -229.387654)
		(end 138.01979 -229.387654)
		(width 0.0889)
		(layer "B.Cu")
		(net "PWRGD_PLT_AUX_CPU1_LVT3")
	)
	(segment
		(start 152.251918 -197.71233)
		(end 154.612086 -195.352162)
		(width 0.12954)
		(layer "B.Cu")
		(net "PWRGD_PLT_AUX_CPU1_LVT3")
	)
	(segment
		(start 123.10491 -229.597204)
		(end 123.115324 -229.591108)
		(width 0.0889)
		(layer "B.Cu")
		(net "PWRGD_PLT_AUX_CPU1_LVT3")
	)
	(segment
		(start 120.725692 -229.272846)
		(end 120.668288 -229.33025)
		(width 0.0889)
		(layer "B.Cu")
		(net "PWRGD_PLT_AUX_CPU1_LVT3")
	)
	(arc
		(start 133.068568 -229.597204)
		(mid 133.255766 -229.647347)
		(end 133.442964 -229.597204)
		(width 0.0889)
		(layer "B.Cu")
		(net "PWRGD_PLT_AUX_CPU1_LVT3")
	)
	(arc
		(start 130.638296 -229.588568)
		(mid 130.914771 -229.521248)
		(end 131.188968 -229.597204)
		(width 0.0889)
		(layer "B.Cu")
		(net "PWRGD_PLT_AUX_CPU1_LVT3")
	)
	(arc
		(start 132.128768 -229.597204)
		(mid 132.315966 -229.647347)
		(end 132.503164 -229.597204)
		(width 0.0889)
		(layer "B.Cu")
		(net "PWRGD_PLT_AUX_CPU1_LVT3")
	)
	(arc
		(start 128.369568 -229.597204)
		(mid 128.556766 -229.647347)
		(end 128.743964 -229.597204)
		(width 0.0889)
		(layer "B.Cu")
		(net "PWRGD_PLT_AUX_CPU1_LVT3")
	)
	(arc
		(start 127.818896 -229.588568)
		(mid 128.095371 -229.521248)
		(end 128.369568 -229.597204)
		(width 0.0889)
		(layer "B.Cu")
		(net "PWRGD_PLT_AUX_CPU1_LVT3")
	)
	(arc
		(start 125.550168 -229.597204)
		(mid 125.737366 -229.647347)
		(end 125.924564 -229.597204)
		(width 0.0889)
		(layer "B.Cu")
		(net "PWRGD_PLT_AUX_CPU1_LVT3")
	)
	(arc
		(start 123.670568 -229.597204)
		(mid 123.857766 -229.647347)
		(end 124.044964 -229.597204)
		(width 0.0889)
		(layer "B.Cu")
		(net "PWRGD_PLT_AUX_CPU1_LVT3")
	)
	(arc
		(start 124.984764 -229.597204)
		(mid 125.267466 -229.521428)
		(end 125.550168 -229.597204)
		(width 0.0889)
		(layer "B.Cu")
		(net "PWRGD_PLT_AUX_CPU1_LVT3")
	)
	(arc
		(start 129.309114 -229.597204)
		(mid 129.496312 -229.647347)
		(end 129.68351 -229.597204)
		(width 0.0889)
		(layer "B.Cu")
		(net "PWRGD_PLT_AUX_CPU1_LVT3")
	)
	(arc
		(start 122.730514 -229.597204)
		(mid 122.917712 -229.647347)
		(end 123.10491 -229.597204)
		(width 0.0889)
		(layer "B.Cu")
		(net "PWRGD_PLT_AUX_CPU1_LVT3")
	)
	(arc
		(start 135.887968 -229.597204)
		(mid 136.075166 -229.647347)
		(end 136.262364 -229.597204)
		(width 0.0889)
		(layer "B.Cu")
		(net "PWRGD_PLT_AUX_CPU1_LVT3")
	)
	(arc
		(start 124.059696 -229.588568)
		(mid 124.336171 -229.521248)
		(end 124.610368 -229.597204)
		(width 0.0889)
		(layer "B.Cu")
		(net "PWRGD_PLT_AUX_CPU1_LVT3")
	)
	(arc
		(start 124.610368 -229.597204)
		(mid 124.797566 -229.647347)
		(end 124.984764 -229.597204)
		(width 0.0889)
		(layer "B.Cu")
		(net "PWRGD_PLT_AUX_CPU1_LVT3")
	)
	(arc
		(start 120.668288 -229.33025)
		(mid 120.726444 -229.480363)
		(end 120.842278 -229.592124)
		(width 0.0889)
		(layer "B.Cu")
		(net "PWRGD_PLT_AUX_CPU1_LVT3")
	)
	(arc
		(start 120.851168 -229.597204)
		(mid 121.038366 -229.647347)
		(end 121.225564 -229.597204)
		(width 0.0889)
		(layer "B.Cu")
		(net "PWRGD_PLT_AUX_CPU1_LVT3")
	)
	(arc
		(start 132.517896 -229.588568)
		(mid 132.794371 -229.521248)
		(end 133.068568 -229.597204)
		(width 0.0889)
		(layer "B.Cu")
		(net "PWRGD_PLT_AUX_CPU1_LVT3")
	)
	(arc
		(start 123.115324 -229.591108)
		(mid 123.393756 -229.521262)
		(end 123.670568 -229.597204)
		(width 0.0889)
		(layer "B.Cu")
		(net "PWRGD_PLT_AUX_CPU1_LVT3")
	)
	(arc
		(start 131.563364 -229.597204)
		(mid 131.846066 -229.521428)
		(end 132.128768 -229.597204)
		(width 0.0889)
		(layer "B.Cu")
		(net "PWRGD_PLT_AUX_CPU1_LVT3")
	)
	(arc
		(start 133.442964 -229.597204)
		(mid 133.725666 -229.521428)
		(end 134.008368 -229.597204)
		(width 0.0889)
		(layer "B.Cu")
		(net "PWRGD_PLT_AUX_CPU1_LVT3")
	)
	(arc
		(start 135.322564 -229.597204)
		(mid 135.605266 -229.521428)
		(end 135.887968 -229.597204)
		(width 0.0889)
		(layer "B.Cu")
		(net "PWRGD_PLT_AUX_CPU1_LVT3")
	)
	(arc
		(start 121.790968 -229.597204)
		(mid 121.978166 -229.647347)
		(end 122.165364 -229.597204)
		(width 0.0889)
		(layer "B.Cu")
		(net "PWRGD_PLT_AUX_CPU1_LVT3")
	)
	(arc
		(start 136.262364 -229.597204)
		(mid 136.303173 -229.570032)
		(end 136.340088 -229.537768)
		(width 0.0889)
		(layer "B.Cu")
		(net "PWRGD_PLT_AUX_CPU1_LVT3")
	)
	(arc
		(start 134.008368 -229.597204)
		(mid 134.195566 -229.647347)
		(end 134.382764 -229.597204)
		(width 0.0889)
		(layer "B.Cu")
		(net "PWRGD_PLT_AUX_CPU1_LVT3")
	)
	(arc
		(start 126.489968 -229.597204)
		(mid 126.677166 -229.647347)
		(end 126.864364 -229.597204)
		(width 0.0889)
		(layer "B.Cu")
		(net "PWRGD_PLT_AUX_CPU1_LVT3")
	)
	(arc
		(start 129.693924 -229.591108)
		(mid 129.972356 -229.521262)
		(end 130.249168 -229.597204)
		(width 0.0889)
		(layer "B.Cu")
		(net "PWRGD_PLT_AUX_CPU1_LVT3")
	)
	(arc
		(start 134.382764 -229.597204)
		(mid 134.665466 -229.521428)
		(end 134.948168 -229.597204)
		(width 0.0889)
		(layer "B.Cu")
		(net "PWRGD_PLT_AUX_CPU1_LVT3")
	)
	(arc
		(start 128.754378 -229.591108)
		(mid 129.032556 -229.521385)
		(end 129.309114 -229.597204)
		(width 0.0889)
		(layer "B.Cu")
		(net "PWRGD_PLT_AUX_CPU1_LVT3")
	)
	(arc
		(start 121.240296 -229.588568)
		(mid 121.516771 -229.521248)
		(end 121.790968 -229.597204)
		(width 0.0889)
		(layer "B.Cu")
		(net "PWRGD_PLT_AUX_CPU1_LVT3")
	)
	(arc
		(start 134.948168 -229.597204)
		(mid 135.135366 -229.647347)
		(end 135.322564 -229.597204)
		(width 0.0889)
		(layer "B.Cu")
		(net "PWRGD_PLT_AUX_CPU1_LVT3")
	)
	(arc
		(start 131.188968 -229.597204)
		(mid 131.376166 -229.647347)
		(end 131.563364 -229.597204)
		(width 0.0889)
		(layer "B.Cu")
		(net "PWRGD_PLT_AUX_CPU1_LVT3")
	)
	(arc
		(start 122.175778 -229.591108)
		(mid 122.453956 -229.521385)
		(end 122.730514 -229.597204)
		(width 0.0889)
		(layer "B.Cu")
		(net "PWRGD_PLT_AUX_CPU1_LVT3")
	)
	(arc
		(start 126.879096 -229.588568)
		(mid 127.155571 -229.521248)
		(end 127.429768 -229.597204)
		(width 0.0889)
		(layer "B.Cu")
		(net "PWRGD_PLT_AUX_CPU1_LVT3")
	)
	(arc
		(start 125.939296 -229.588568)
		(mid 126.215771 -229.521248)
		(end 126.489968 -229.597204)
		(width 0.0889)
		(layer "B.Cu")
		(net "PWRGD_PLT_AUX_CPU1_LVT3")
	)
	(arc
		(start 130.249168 -229.597204)
		(mid 130.436366 -229.647347)
		(end 130.623564 -229.597204)
		(width 0.0889)
		(layer "B.Cu")
		(net "PWRGD_PLT_AUX_CPU1_LVT3")
	)
	(arc
		(start 127.429768 -229.597204)
		(mid 127.616966 -229.647347)
		(end 127.804164 -229.597204)
		(width 0.0889)
		(layer "B.Cu")
		(net "PWRGD_PLT_AUX_CPU1_LVT3")
	)
	(segment
		(start 186.155584 -108.175552)
		(end 186.555634 -107.775502)
		(width 0.12954)
		(layer "F.Cu")
		(net "PWRGD_PLT_AUX_CPU0_LVT3_R")
	)
	(via
		(at 186.555634 -107.775502)
		(size 0.4572)
		(drill 0.254)
		(layers "F.Cu" "B.Cu")
		(net "PWRGD_PLT_AUX_CPU0_LVT3_R")
	)
	(via
		(at 269.61338 -148.808948)
		(size 0.762)
		(drill 0.254)
		(layers "F.Cu" "B.Cu")
		(net "PWRGD_PLT_AUX_CPU0_LVT3_R")
	)
	(via
		(at 266.81938 -113.553748)
		(size 0.508)
		(drill 0.254)
		(layers "F.Cu" "B.Cu")
		(net "PWRGD_PLT_AUX_CPU0_LVT3_R")
	)
	(segment
		(start 375.596658 -176.94021)
		(end 385.46405 -186.807602)
		(width 0.12954)
		(layer "B.Cu")
		(net "PWRGD_PLT_AUX_CPU0_LVT3_R")
	)
	(segment
		(start 367.942368 -174.5361)
		(end 367.942368 -175.59782)
		(width 0.12954)
		(layer "B.Cu")
		(net "PWRGD_PLT_AUX_CPU0_LVT3_R")
	)
	(segment
		(start 361.731814 -168.325546)
		(end 367.942368 -174.5361)
		(width 0.12954)
		(layer "B.Cu")
		(net "PWRGD_PLT_AUX_CPU0_LVT3_R")
	)
	(segment
		(start 320.033142 -146.550888)
		(end 340.568026 -155.05684)
		(width 0.12954)
		(layer "B.Cu")
		(net "PWRGD_PLT_AUX_CPU0_LVT3_R")
	)
	(segment
		(start 340.568026 -155.05684)
		(end 348.253558 -162.742372)
		(width 0.12954)
		(layer "B.Cu")
		(net "PWRGD_PLT_AUX_CPU0_LVT3_R")
	)
	(segment
		(start 271.138142 -146.550888)
		(end 320.033142 -146.550888)
		(width 0.12954)
		(layer "B.Cu")
		(net "PWRGD_PLT_AUX_CPU0_LVT3_R")
	)
	(segment
		(start 369.284758 -176.94021)
		(end 370.096288 -176.94021)
		(width 0.12954)
		(layer "B.Cu")
		(net "PWRGD_PLT_AUX_CPU0_LVT3_R")
	)
	(segment
		(start 269.61338 -148.07565)
		(end 271.138142 -146.550888)
		(width 0.12954)
		(layer "B.Cu")
		(net "PWRGD_PLT_AUX_CPU0_LVT3_R")
	)
	(segment
		(start 269.61338 -148.808948)
		(end 269.61338 -148.07565)
		(width 0.12954)
		(layer "B.Cu")
		(net "PWRGD_PLT_AUX_CPU0_LVT3_R")
	)
	(segment
		(start 367.942368 -175.59782)
		(end 369.284758 -176.94021)
		(width 0.12954)
		(layer "B.Cu")
		(net "PWRGD_PLT_AUX_CPU0_LVT3_R")
	)
	(segment
		(start 373.174514 -176.25695)
		(end 374.824244 -176.94021)
		(width 0.12954)
		(layer "B.Cu")
		(net "PWRGD_PLT_AUX_CPU0_LVT3_R")
	)
	(segment
		(start 348.253558 -162.742372)
		(end 361.731814 -168.325546)
		(width 0.12954)
		(layer "B.Cu")
		(net "PWRGD_PLT_AUX_CPU0_LVT3_R")
	)
	(segment
		(start 385.46405 -186.807602)
		(end 385.46405 -188.30417)
		(width 0.12954)
		(layer "B.Cu")
		(net "PWRGD_PLT_AUX_CPU0_LVT3_R")
	)
	(segment
		(start 370.096288 -176.94021)
		(end 371.746018 -176.25695)
		(width 0.12954)
		(layer "B.Cu")
		(net "PWRGD_PLT_AUX_CPU0_LVT3_R")
	)
	(segment
		(start 371.746018 -176.25695)
		(end 373.174514 -176.25695)
		(width 0.12954)
		(layer "B.Cu")
		(net "PWRGD_PLT_AUX_CPU0_LVT3_R")
	)
	(segment
		(start 374.824244 -176.94021)
		(end 375.596658 -176.94021)
		(width 0.12954)
		(layer "B.Cu")
		(net "PWRGD_PLT_AUX_CPU0_LVT3_R")
	)
	(segment
		(start 269.61338 -137.823448)
		(end 266.81938 -135.029448)
		(width 0.127)
		(layer "In2.Cu")
		(net "PWRGD_PLT_AUX_CPU0_LVT3_R")
	)
	(segment
		(start 269.61338 -148.808948)
		(end 269.61338 -137.823448)
		(width 0.127)
		(layer "In2.Cu")
		(net "PWRGD_PLT_AUX_CPU0_LVT3_R")
	)
	(segment
		(start 266.81938 -135.029448)
		(end 266.81938 -113.553748)
		(width 0.127)
		(layer "In2.Cu")
		(net "PWRGD_PLT_AUX_CPU0_LVT3_R")
	)
	(segment
		(start 266.14628 -114.226848)
		(end 266.81938 -113.553748)
		(width 0.127)
		(layer "In15.Cu")
		(net "PWRGD_PLT_AUX_CPU0_LVT3_R")
	)
	(segment
		(start 231.823006 -100.391468)
		(end 235.675424 -104.243886)
		(width 0.127)
		(layer "In15.Cu")
		(net "PWRGD_PLT_AUX_CPU0_LVT3_R")
	)
	(segment
		(start 218.7448 -97.63506)
		(end 222.233998 -97.63506)
		(width 0.127)
		(layer "In15.Cu")
		(net "PWRGD_PLT_AUX_CPU0_LVT3_R")
	)
	(segment
		(start 224.990406 -100.391468)
		(end 231.823006 -100.391468)
		(width 0.127)
		(layer "In15.Cu")
		(net "PWRGD_PLT_AUX_CPU0_LVT3_R")
	)
	(segment
		(start 190.42634 -103.370888)
		(end 195.761864 -98.035364)
		(width 0.127)
		(layer "In15.Cu")
		(net "PWRGD_PLT_AUX_CPU0_LVT3_R")
	)
	(segment
		(start 195.761864 -98.035364)
		(end 208.991708 -98.035364)
		(width 0.127)
		(layer "In15.Cu")
		(net "PWRGD_PLT_AUX_CPU0_LVT3_R")
	)
	(segment
		(start 252.01245 -114.226848)
		(end 266.14628 -114.226848)
		(width 0.127)
		(layer "In15.Cu")
		(net "PWRGD_PLT_AUX_CPU0_LVT3_R")
	)
	(segment
		(start 209.793332 -97.23374)
		(end 218.34348 -97.23374)
		(width 0.127)
		(layer "In15.Cu")
		(net "PWRGD_PLT_AUX_CPU0_LVT3_R")
	)
	(segment
		(start 190.42634 -104.685084)
		(end 190.42634 -103.370888)
		(width 0.127)
		(layer "In15.Cu")
		(net "PWRGD_PLT_AUX_CPU0_LVT3_R")
	)
	(segment
		(start 242.029488 -104.243886)
		(end 252.01245 -114.226848)
		(width 0.127)
		(layer "In15.Cu")
		(net "PWRGD_PLT_AUX_CPU0_LVT3_R")
	)
	(segment
		(start 218.34348 -97.23374)
		(end 218.7448 -97.63506)
		(width 0.127)
		(layer "In15.Cu")
		(net "PWRGD_PLT_AUX_CPU0_LVT3_R")
	)
	(segment
		(start 186.555634 -107.775502)
		(end 187.000388 -107.330748)
		(width 0.127)
		(layer "In15.Cu")
		(net "PWRGD_PLT_AUX_CPU0_LVT3_R")
	)
	(segment
		(start 208.991708 -98.035364)
		(end 209.793332 -97.23374)
		(width 0.127)
		(layer "In15.Cu")
		(net "PWRGD_PLT_AUX_CPU0_LVT3_R")
	)
	(segment
		(start 187.000388 -107.330748)
		(end 187.780676 -107.330748)
		(width 0.127)
		(layer "In15.Cu")
		(net "PWRGD_PLT_AUX_CPU0_LVT3_R")
	)
	(segment
		(start 235.675424 -104.243886)
		(end 242.029488 -104.243886)
		(width 0.127)
		(layer "In15.Cu")
		(net "PWRGD_PLT_AUX_CPU0_LVT3_R")
	)
	(segment
		(start 187.780676 -107.330748)
		(end 190.42634 -104.685084)
		(width 0.127)
		(layer "In15.Cu")
		(net "PWRGD_PLT_AUX_CPU0_LVT3_R")
	)
	(segment
		(start 222.233998 -97.63506)
		(end 224.990406 -100.391468)
		(width 0.127)
		(layer "In15.Cu")
		(net "PWRGD_PLT_AUX_CPU0_LVT3_R")
	)
	(segment
		(start 368.978434 -229.808532)
		(end 368.978434 -229.272846)
		(width 0.12954)
		(layer "F.Cu")
		(net "PWRGD_PLT_AUX_CPU0_LVT3")
	)
	(segment
		(start 368.97818 -229.808786)
		(end 368.978434 -229.808532)
		(width 0.12954)
		(layer "F.Cu")
		(net "PWRGD_PLT_AUX_CPU0_LVT3")
	)
	(via
		(at 368.978434 -229.272846)
		(size 0.4572)
		(drill 0.2032)
		(layers "F.Cu" "B.Cu")
		(net "PWRGD_PLT_AUX_CPU0_LVT3")
	)
	(via
		(at 391.3632 -225.809048)
		(size 0.6604)
		(drill 0.3302)
		(layers "F.Cu" "B.Cu")
		(net "PWRGD_PLT_AUX_CPU0_LVT3")
	)
	(segment
		(start 384.546348 -192.139062)
		(end 385.46405 -191.22136)
		(width 0.12954)
		(layer "B.Cu")
		(net "PWRGD_PLT_AUX_CPU0_LVT3")
	)
	(segment
		(start 378.64415 -229.77094)
		(end 378.658882 -229.762304)
		(width 0.0889)
		(layer "B.Cu")
		(net "PWRGD_PLT_AUX_CPU0_LVT3")
	)
	(segment
		(start 369.557046 -229.717092)
		(end 369.635278 -229.762304)
		(width 0.0889)
		(layer "B.Cu")
		(net "PWRGD_PLT_AUX_CPU0_LVT3")
	)
	(segment
		(start 384.814318 -190.571628)
		(end 385.46405 -191.22136)
		(width 0.12954)
		(layer "B.Cu")
		(net "PWRGD_PLT_AUX_CPU0_LVT3")
	)
	(segment
		(start 392.481054 -200.065386)
		(end 386.229098 -193.81343)
		(width 0.12954)
		(layer "B.Cu")
		(net "PWRGD_PLT_AUX_CPU0_LVT3")
	)
	(segment
		(start 379.588522 -229.7684)
		(end 379.598936 -229.762304)
		(width 0.0889)
		(layer "B.Cu")
		(net "PWRGD_PLT_AUX_CPU0_LVT3")
	)
	(segment
		(start 373.949468 -229.7684)
		(end 373.959882 -229.762304)
		(width 0.0889)
		(layer "B.Cu")
		(net "PWRGD_PLT_AUX_CPU0_LVT3")
	)
	(segment
		(start 384.814318 -189.754002)
		(end 384.814318 -190.571628)
		(width 0.12954)
		(layer "B.Cu")
		(net "PWRGD_PLT_AUX_CPU0_LVT3")
	)
	(segment
		(start 387.596888 -229.57536)
		(end 391.3632 -225.809048)
		(width 0.12954)
		(layer "B.Cu")
		(net "PWRGD_PLT_AUX_CPU0_LVT3")
	)
	(segment
		(start 380.528068 -229.7684)
		(end 380.538482 -229.762304)
		(width 0.0889)
		(layer "B.Cu")
		(net "PWRGD_PLT_AUX_CPU0_LVT3")
	)
	(segment
		(start 391.3632 -225.809048)
		(end 392.481054 -224.691194)
		(width 0.12954)
		(layer "B.Cu")
		(net "PWRGD_PLT_AUX_CPU0_LVT3")
	)
	(segment
		(start 370.18595 -229.77094)
		(end 370.200682 -229.762304)
		(width 0.0889)
		(layer "B.Cu")
		(net "PWRGD_PLT_AUX_CPU0_LVT3")
	)
	(segment
		(start 384.973068 -229.57536)
		(end 387.596888 -229.57536)
		(width 0.12954)
		(layer "B.Cu")
		(net "PWRGD_PLT_AUX_CPU0_LVT3")
	)
	(segment
		(start 386.229098 -193.81343)
		(end 385.241038 -193.81343)
		(width 0.12954)
		(layer "B.Cu")
		(net "PWRGD_PLT_AUX_CPU0_LVT3")
	)
	(segment
		(start 381.468122 -229.7684)
		(end 381.478536 -229.762304)
		(width 0.0889)
		(layer "B.Cu")
		(net "PWRGD_PLT_AUX_CPU0_LVT3")
	)
	(segment
		(start 392.481054 -224.691194)
		(end 392.481054 -200.065386)
		(width 0.12954)
		(layer "B.Cu")
		(net "PWRGD_PLT_AUX_CPU0_LVT3")
	)
	(segment
		(start 385.46405 -189.10427)
		(end 384.814318 -189.754002)
		(width 0.12954)
		(layer "B.Cu")
		(net "PWRGD_PLT_AUX_CPU0_LVT3")
	)
	(segment
		(start 385.241038 -193.81343)
		(end 384.546348 -193.11874)
		(width 0.12954)
		(layer "B.Cu")
		(net "PWRGD_PLT_AUX_CPU0_LVT3")
	)
	(segment
		(start 375.82475 -229.77094)
		(end 375.839482 -229.762304)
		(width 0.0889)
		(layer "B.Cu")
		(net "PWRGD_PLT_AUX_CPU0_LVT3")
	)
	(segment
		(start 373.009922 -229.7684)
		(end 373.020336 -229.762304)
		(width 0.0889)
		(layer "B.Cu")
		(net "PWRGD_PLT_AUX_CPU0_LVT3")
	)
	(segment
		(start 384.541776 -229.57536)
		(end 384.973068 -229.57536)
		(width 0.0889)
		(layer "B.Cu")
		(net "PWRGD_PLT_AUX_CPU0_LVT3")
	)
	(segment
		(start 374.88495 -229.77094)
		(end 374.899682 -229.762304)
		(width 0.0889)
		(layer "B.Cu")
		(net "PWRGD_PLT_AUX_CPU0_LVT3")
	)
	(segment
		(start 384.546348 -193.11874)
		(end 384.546348 -192.139062)
		(width 0.12954)
		(layer "B.Cu")
		(net "PWRGD_PLT_AUX_CPU0_LVT3")
	)
	(segment
		(start 376.76455 -229.77094)
		(end 376.779282 -229.762304)
		(width 0.0889)
		(layer "B.Cu")
		(net "PWRGD_PLT_AUX_CPU0_LVT3")
	)
	(segment
		(start 372.06555 -229.77094)
		(end 372.080282 -229.762304)
		(width 0.0889)
		(layer "B.Cu")
		(net "PWRGD_PLT_AUX_CPU0_LVT3")
	)
	(arc
		(start 379.973332 -229.762304)
		(mid 380.249891 -229.838047)
		(end 380.528068 -229.7684)
		(width 0.0889)
		(layer "B.Cu")
		(net "PWRGD_PLT_AUX_CPU0_LVT3")
	)
	(arc
		(start 380.538482 -229.762304)
		(mid 380.72568 -229.712161)
		(end 380.912878 -229.762304)
		(width 0.0889)
		(layer "B.Cu")
		(net "PWRGD_PLT_AUX_CPU0_LVT3")
	)
	(arc
		(start 368.978434 -229.272846)
		(mid 369.253215 -229.513887)
		(end 369.557046 -229.717092)
		(width 0.0889)
		(layer "B.Cu")
		(net "PWRGD_PLT_AUX_CPU0_LVT3")
	)
	(arc
		(start 374.899682 -229.762304)
		(mid 375.08688 -229.712161)
		(end 375.274078 -229.762304)
		(width 0.0889)
		(layer "B.Cu")
		(net "PWRGD_PLT_AUX_CPU0_LVT3")
	)
	(arc
		(start 378.093478 -229.762304)
		(mid 378.367677 -229.838139)
		(end 378.64415 -229.77094)
		(width 0.0889)
		(layer "B.Cu")
		(net "PWRGD_PLT_AUX_CPU0_LVT3")
	)
	(arc
		(start 373.020336 -229.762304)
		(mid 373.207534 -229.712161)
		(end 373.394732 -229.762304)
		(width 0.0889)
		(layer "B.Cu")
		(net "PWRGD_PLT_AUX_CPU0_LVT3")
	)
	(arc
		(start 377.719082 -229.762304)
		(mid 377.90628 -229.712161)
		(end 378.093478 -229.762304)
		(width 0.0889)
		(layer "B.Cu")
		(net "PWRGD_PLT_AUX_CPU0_LVT3")
	)
	(arc
		(start 384.297936 -229.762304)
		(mid 384.426016 -229.676865)
		(end 384.541776 -229.57536)
		(width 0.0889)
		(layer "B.Cu")
		(net "PWRGD_PLT_AUX_CPU0_LVT3")
	)
	(arc
		(start 382.418336 -229.762304)
		(mid 382.605534 -229.712161)
		(end 382.792732 -229.762304)
		(width 0.0889)
		(layer "B.Cu")
		(net "PWRGD_PLT_AUX_CPU0_LVT3")
	)
	(arc
		(start 378.658882 -229.762304)
		(mid 378.84608 -229.712161)
		(end 379.033278 -229.762304)
		(width 0.0889)
		(layer "B.Cu")
		(net "PWRGD_PLT_AUX_CPU0_LVT3")
	)
	(arc
		(start 372.080282 -229.762304)
		(mid 372.26748 -229.712161)
		(end 372.454678 -229.762304)
		(width 0.0889)
		(layer "B.Cu")
		(net "PWRGD_PLT_AUX_CPU0_LVT3")
	)
	(arc
		(start 375.274078 -229.762304)
		(mid 375.548277 -229.838139)
		(end 375.82475 -229.77094)
		(width 0.0889)
		(layer "B.Cu")
		(net "PWRGD_PLT_AUX_CPU0_LVT3")
	)
	(arc
		(start 376.213878 -229.762304)
		(mid 376.488077 -229.838139)
		(end 376.76455 -229.77094)
		(width 0.0889)
		(layer "B.Cu")
		(net "PWRGD_PLT_AUX_CPU0_LVT3")
	)
	(arc
		(start 370.200682 -229.762304)
		(mid 370.38788 -229.712161)
		(end 370.575078 -229.762304)
		(width 0.0889)
		(layer "B.Cu")
		(net "PWRGD_PLT_AUX_CPU0_LVT3")
	)
	(arc
		(start 382.792732 -229.762304)
		(mid 383.075434 -229.83808)
		(end 383.358136 -229.762304)
		(width 0.0889)
		(layer "B.Cu")
		(net "PWRGD_PLT_AUX_CPU0_LVT3")
	)
	(arc
		(start 380.912878 -229.762304)
		(mid 381.189691 -229.838174)
		(end 381.468122 -229.7684)
		(width 0.0889)
		(layer "B.Cu")
		(net "PWRGD_PLT_AUX_CPU0_LVT3")
	)
	(arc
		(start 377.153678 -229.762304)
		(mid 377.43638 -229.83808)
		(end 377.719082 -229.762304)
		(width 0.0889)
		(layer "B.Cu")
		(net "PWRGD_PLT_AUX_CPU0_LVT3")
	)
	(arc
		(start 376.779282 -229.762304)
		(mid 376.96648 -229.712161)
		(end 377.153678 -229.762304)
		(width 0.0889)
		(layer "B.Cu")
		(net "PWRGD_PLT_AUX_CPU0_LVT3")
	)
	(arc
		(start 381.478536 -229.762304)
		(mid 381.665734 -229.712161)
		(end 381.852932 -229.762304)
		(width 0.0889)
		(layer "B.Cu")
		(net "PWRGD_PLT_AUX_CPU0_LVT3")
	)
	(arc
		(start 383.732532 -229.762304)
		(mid 384.015234 -229.83808)
		(end 384.297936 -229.762304)
		(width 0.0889)
		(layer "B.Cu")
		(net "PWRGD_PLT_AUX_CPU0_LVT3")
	)
	(arc
		(start 381.852932 -229.762304)
		(mid 382.135634 -229.83808)
		(end 382.418336 -229.762304)
		(width 0.0889)
		(layer "B.Cu")
		(net "PWRGD_PLT_AUX_CPU0_LVT3")
	)
	(arc
		(start 370.575078 -229.762304)
		(mid 370.85778 -229.83808)
		(end 371.140482 -229.762304)
		(width 0.0889)
		(layer "B.Cu")
		(net "PWRGD_PLT_AUX_CPU0_LVT3")
	)
	(arc
		(start 371.514878 -229.762304)
		(mid 371.789077 -229.838139)
		(end 372.06555 -229.77094)
		(width 0.0889)
		(layer "B.Cu")
		(net "PWRGD_PLT_AUX_CPU0_LVT3")
	)
	(arc
		(start 373.394732 -229.762304)
		(mid 373.671291 -229.838047)
		(end 373.949468 -229.7684)
		(width 0.0889)
		(layer "B.Cu")
		(net "PWRGD_PLT_AUX_CPU0_LVT3")
	)
	(arc
		(start 371.140482 -229.762304)
		(mid 371.32768 -229.712161)
		(end 371.514878 -229.762304)
		(width 0.0889)
		(layer "B.Cu")
		(net "PWRGD_PLT_AUX_CPU0_LVT3")
	)
	(arc
		(start 383.358136 -229.762304)
		(mid 383.545334 -229.712161)
		(end 383.732532 -229.762304)
		(width 0.0889)
		(layer "B.Cu")
		(net "PWRGD_PLT_AUX_CPU0_LVT3")
	)
	(arc
		(start 379.598936 -229.762304)
		(mid 379.786134 -229.712161)
		(end 379.973332 -229.762304)
		(width 0.0889)
		(layer "B.Cu")
		(net "PWRGD_PLT_AUX_CPU0_LVT3")
	)
	(arc
		(start 373.959882 -229.762304)
		(mid 374.14708 -229.712161)
		(end 374.334278 -229.762304)
		(width 0.0889)
		(layer "B.Cu")
		(net "PWRGD_PLT_AUX_CPU0_LVT3")
	)
	(arc
		(start 369.635278 -229.762304)
		(mid 369.909477 -229.838139)
		(end 370.18595 -229.77094)
		(width 0.0889)
		(layer "B.Cu")
		(net "PWRGD_PLT_AUX_CPU0_LVT3")
	)
	(arc
		(start 374.334278 -229.762304)
		(mid 374.608477 -229.838139)
		(end 374.88495 -229.77094)
		(width 0.0889)
		(layer "B.Cu")
		(net "PWRGD_PLT_AUX_CPU0_LVT3")
	)
	(arc
		(start 379.033278 -229.762304)
		(mid 379.310091 -229.838174)
		(end 379.588522 -229.7684)
		(width 0.0889)
		(layer "B.Cu")
		(net "PWRGD_PLT_AUX_CPU0_LVT3")
	)
	(arc
		(start 375.839482 -229.762304)
		(mid 376.02668 -229.712161)
		(end 376.213878 -229.762304)
		(width 0.0889)
		(layer "B.Cu")
		(net "PWRGD_PLT_AUX_CPU0_LVT3")
	)
	(arc
		(start 372.454678 -229.762304)
		(mid 372.731491 -229.838174)
		(end 373.009922 -229.7684)
		(width 0.0889)
		(layer "B.Cu")
		(net "PWRGD_PLT_AUX_CPU0_LVT3")
	)
	(segment
		(start 317.607696 -26.176224)
		(end 317.05804 -25.626568)
		(width 0.12954)
		(layer "F.Cu")
		(net "PWRGD_PCH_PWROK_R")
	)
	(segment
		(start 175.31588 -129.866898)
		(end 175.31588 -129.256028)
		(width 0.12954)
		(layer "F.Cu")
		(net "PWRGD_PCH_PWROK_R")
	)
	(segment
		(start 176.555654 -119.375428)
		(end 176.155604 -119.775478)
		(width 0.12954)
		(layer "F.Cu")
		(net "PWRGD_PCH_PWROK_R")
	)
	(segment
		(start 99.974654 -96.123506)
		(end 99.274122 -96.123506)
		(width 0.12954)
		(layer "F.Cu")
		(net "PWRGD_PCH_PWROK_R")
	)
	(segment
		(start 316.081156 -25.626568)
		(end 315.545978 -25.09139)
		(width 0.12954)
		(layer "F.Cu")
		(net "PWRGD_PCH_PWROK_R")
	)
	(segment
		(start 317.05804 -25.626568)
		(end 316.081156 -25.626568)
		(width 0.12954)
		(layer "F.Cu")
		(net "PWRGD_PCH_PWROK_R")
	)
	(segment
		(start 317.607696 -27.671522)
		(end 317.607696 -26.176224)
		(width 0.12954)
		(layer "F.Cu")
		(net "PWRGD_PCH_PWROK_R")
	)
	(via
		(at 176.155604 -119.775478)
		(size 0.4572)
		(drill 0.254)
		(layers "F.Cu" "B.Cu")
		(net "PWRGD_PCH_PWROK_R")
	)
	(via
		(at 99.03968 -117.185948)
		(size 0.508)
		(drill 0.254)
		(layers "F.Cu" "B.Cu")
		(net "PWRGD_PCH_PWROK_R")
	)
	(via
		(at 317.607696 -27.671522)
		(size 0.508)
		(drill 0.254)
		(layers "F.Cu" "B.Cu")
		(net "PWRGD_PCH_PWROK_R")
	)
	(via
		(at 99.274122 -96.123506)
		(size 0.508)
		(drill 0.254)
		(layers "F.Cu" "B.Cu")
		(net "PWRGD_PCH_PWROK_R")
	)
	(via
		(at 201.32548 -90.134948)
		(size 0.508)
		(drill 0.254)
		(layers "F.Cu" "B.Cu")
		(net "PWRGD_PCH_PWROK_R")
	)
	(via
		(at 175.31588 -129.256028)
		(size 0.508)
		(drill 0.254)
		(layers "F.Cu" "B.Cu")
		(net "PWRGD_PCH_PWROK_R")
	)
	(segment
		(start 175.96104 -122.263408)
		(end 176.5554 -121.669048)
		(width 0.127)
		(layer "In2.Cu")
		(net "PWRGD_PCH_PWROK_R")
	)
	(segment
		(start 176.5554 -121.669048)
		(end 176.5554 -120.175274)
		(width 0.127)
		(layer "In2.Cu")
		(net "PWRGD_PCH_PWROK_R")
	)
	(segment
		(start 174.68088 -124.760228)
		(end 175.96104 -123.480068)
		(width 0.127)
		(layer "In2.Cu")
		(net "PWRGD_PCH_PWROK_R")
	)
	(segment
		(start 100.00488 -113.502948)
		(end 99.03968 -114.468148)
		(width 0.127)
		(layer "In2.Cu")
		(net "PWRGD_PCH_PWROK_R")
	)
	(segment
		(start 174.93996 -129.256028)
		(end 174.68088 -128.996948)
		(width 0.127)
		(layer "In2.Cu")
		(net "PWRGD_PCH_PWROK_R")
	)
	(segment
		(start 99.29368 -96.103948)
		(end 99.64928 -96.103948)
		(width 0.127)
		(layer "In2.Cu")
		(net "PWRGD_PCH_PWROK_R")
	)
	(segment
		(start 99.274122 -96.123506)
		(end 99.29368 -96.103948)
		(width 0.127)
		(layer "In2.Cu")
		(net "PWRGD_PCH_PWROK_R")
	)
	(segment
		(start 176.5554 -120.175274)
		(end 176.155604 -119.775478)
		(width 0.127)
		(layer "In2.Cu")
		(net "PWRGD_PCH_PWROK_R")
	)
	(segment
		(start 100.00488 -96.459548)
		(end 100.00488 -113.502948)
		(width 0.127)
		(layer "In2.Cu")
		(net "PWRGD_PCH_PWROK_R")
	)
	(segment
		(start 174.68088 -128.996948)
		(end 174.68088 -124.760228)
		(width 0.127)
		(layer "In2.Cu")
		(net "PWRGD_PCH_PWROK_R")
	)
	(segment
		(start 99.64928 -96.103948)
		(end 100.00488 -96.459548)
		(width 0.127)
		(layer "In2.Cu")
		(net "PWRGD_PCH_PWROK_R")
	)
	(segment
		(start 175.96104 -123.480068)
		(end 175.96104 -122.263408)
		(width 0.127)
		(layer "In2.Cu")
		(net "PWRGD_PCH_PWROK_R")
	)
	(segment
		(start 99.03968 -114.468148)
		(end 99.03968 -117.185948)
		(width 0.127)
		(layer "In2.Cu")
		(net "PWRGD_PCH_PWROK_R")
	)
	(segment
		(start 175.31588 -129.256028)
		(end 174.93996 -129.256028)
		(width 0.127)
		(layer "In2.Cu")
		(net "PWRGD_PCH_PWROK_R")
	)
	(segment
		(start 189.992 -93.6498)
		(end 194.083432 -89.558368)
		(width 0.127)
		(layer "In13.Cu")
		(net "PWRGD_PCH_PWROK_R")
	)
	(segment
		(start 182.7022 -102.1334)
		(end 183.388 -101.4476)
		(width 0.127)
		(layer "In13.Cu")
		(net "PWRGD_PCH_PWROK_R")
	)
	(segment
		(start 178.31308 -119.146828)
		(end 178.31308 -110.30712)
		(width 0.127)
		(layer "In13.Cu")
		(net "PWRGD_PCH_PWROK_R")
	)
	(segment
		(start 183.388 -100.6094)
		(end 183.8452 -100.1522)
		(width 0.127)
		(layer "In13.Cu")
		(net "PWRGD_PCH_PWROK_R")
	)
	(segment
		(start 176.155604 -119.775478)
		(end 176.553114 -119.377968)
		(width 0.127)
		(layer "In13.Cu")
		(net "PWRGD_PCH_PWROK_R")
	)
	(segment
		(start 176.553114 -119.377968)
		(end 178.08194 -119.377968)
		(width 0.127)
		(layer "In13.Cu")
		(net "PWRGD_PCH_PWROK_R")
	)
	(segment
		(start 178.31308 -110.30712)
		(end 180.3908 -108.2294)
		(width 0.127)
		(layer "In13.Cu")
		(net "PWRGD_PCH_PWROK_R")
	)
	(segment
		(start 201.19848 -89.558368)
		(end 201.32548 -89.685368)
		(width 0.127)
		(layer "In13.Cu")
		(net "PWRGD_PCH_PWROK_R")
	)
	(segment
		(start 178.08194 -119.377968)
		(end 178.31308 -119.146828)
		(width 0.127)
		(layer "In13.Cu")
		(net "PWRGD_PCH_PWROK_R")
	)
	(segment
		(start 183.388 -101.4476)
		(end 183.388 -100.6094)
		(width 0.127)
		(layer "In13.Cu")
		(net "PWRGD_PCH_PWROK_R")
	)
	(segment
		(start 201.32548 -89.685368)
		(end 201.32548 -90.134948)
		(width 0.127)
		(layer "In13.Cu")
		(net "PWRGD_PCH_PWROK_R")
	)
	(segment
		(start 183.8452 -100.1522)
		(end 185.251852 -100.1522)
		(width 0.127)
		(layer "In13.Cu")
		(net "PWRGD_PCH_PWROK_R")
	)
	(segment
		(start 180.3908 -108.2294)
		(end 180.3908 -103.0224)
		(width 0.127)
		(layer "In13.Cu")
		(net "PWRGD_PCH_PWROK_R")
	)
	(segment
		(start 181.2798 -102.1334)
		(end 182.7022 -102.1334)
		(width 0.127)
		(layer "In13.Cu")
		(net "PWRGD_PCH_PWROK_R")
	)
	(segment
		(start 180.3908 -103.0224)
		(end 181.2798 -102.1334)
		(width 0.127)
		(layer "In13.Cu")
		(net "PWRGD_PCH_PWROK_R")
	)
	(segment
		(start 185.683144 -99.720908)
		(end 187.095892 -99.720908)
		(width 0.127)
		(layer "In13.Cu")
		(net "PWRGD_PCH_PWROK_R")
	)
	(segment
		(start 187.095892 -99.720908)
		(end 189.992 -96.8248)
		(width 0.127)
		(layer "In13.Cu")
		(net "PWRGD_PCH_PWROK_R")
	)
	(segment
		(start 189.992 -96.8248)
		(end 189.992 -93.6498)
		(width 0.127)
		(layer "In13.Cu")
		(net "PWRGD_PCH_PWROK_R")
	)
	(segment
		(start 185.251852 -100.1522)
		(end 185.683144 -99.720908)
		(width 0.127)
		(layer "In13.Cu")
		(net "PWRGD_PCH_PWROK_R")
	)
	(segment
		(start 194.083432 -89.558368)
		(end 201.19848 -89.558368)
		(width 0.127)
		(layer "In13.Cu")
		(net "PWRGD_PCH_PWROK_R")
	)
	(segment
		(start 291.82568 -44.516294)
		(end 296.23258 -40.109394)
		(width 0.127)
		(layer "In15.Cu")
		(net "PWRGD_PCH_PWROK_R")
	)
	(segment
		(start 173.308518 -123.942348)
		(end 169.447972 -127.802894)
		(width 0.127)
		(layer "In15.Cu")
		(net "PWRGD_PCH_PWROK_R")
	)
	(segment
		(start 251.03455 -69.004688)
		(end 253.424182 -66.615056)
		(width 0.127)
		(layer "In15.Cu")
		(net "PWRGD_PCH_PWROK_R")
	)
	(segment
		(start 175.95088 -123.104148)
		(end 175.49749 -123.557538)
		(width 0.127)
		(layer "In15.Cu")
		(net "PWRGD_PCH_PWROK_R")
	)
	(segment
		(start 296.23258 -40.109394)
		(end 296.23258 -38.590474)
		(width 0.127)
		(layer "In15.Cu")
		(net "PWRGD_PCH_PWROK_R")
	)
	(segment
		(start 132.9309 -118.321328)
		(end 100.17506 -118.321328)
		(width 0.127)
		(layer "In15.Cu")
		(net "PWRGD_PCH_PWROK_R")
	)
	(segment
		(start 175.75022 -120.180862)
		(end 175.75022 -122.037348)
		(width 0.127)
		(layer "In15.Cu")
		(net "PWRGD_PCH_PWROK_R")
	)
	(segment
		(start 317.5889 -27.671522)
		(end 317.607696 -27.671522)
		(width 0.127)
		(layer "In15.Cu")
		(net "PWRGD_PCH_PWROK_R")
	)
	(segment
		(start 222.81769 -82.565748)
		(end 234.32389 -71.059548)
		(width 0.127)
		(layer "In15.Cu")
		(net "PWRGD_PCH_PWROK_R")
	)
	(segment
		(start 262.237728 -64.861948)
		(end 274.96389 -64.861948)
		(width 0.127)
		(layer "In15.Cu")
		(net "PWRGD_PCH_PWROK_R")
	)
	(segment
		(start 174.57928 -123.942348)
		(end 173.308518 -123.942348)
		(width 0.127)
		(layer "In15.Cu")
		(net "PWRGD_PCH_PWROK_R")
	)
	(segment
		(start 308.08168 -30.319218)
		(end 308.08168 -28.234894)
		(width 0.127)
		(layer "In15.Cu")
		(net "PWRGD_PCH_PWROK_R")
	)
	(segment
		(start 296.23258 -38.590474)
		(end 303.157636 -31.665418)
		(width 0.127)
		(layer "In15.Cu")
		(net "PWRGD_PCH_PWROK_R")
	)
	(segment
		(start 169.447972 -127.802894)
		(end 169.447972 -128.48971)
		(width 0.127)
		(layer "In15.Cu")
		(net "PWRGD_PCH_PWROK_R")
	)
	(segment
		(start 148.10994 -128.842008)
		(end 139.234926 -119.966994)
		(width 0.127)
		(layer "In15.Cu")
		(net "PWRGD_PCH_PWROK_R")
	)
	(segment
		(start 234.32389 -71.059548)
		(end 243.991892 -71.059548)
		(width 0.127)
		(layer "In15.Cu")
		(net "PWRGD_PCH_PWROK_R")
	)
	(segment
		(start 176.155604 -119.775478)
		(end 175.75022 -120.180862)
		(width 0.127)
		(layer "In15.Cu")
		(net "PWRGD_PCH_PWROK_R")
	)
	(segment
		(start 200.89368 -88.776048)
		(end 200.89368 -83.179158)
		(width 0.127)
		(layer "In15.Cu")
		(net "PWRGD_PCH_PWROK_R")
	)
	(segment
		(start 200.89368 -83.179158)
		(end 201.50709 -82.565748)
		(width 0.127)
		(layer "In15.Cu")
		(net "PWRGD_PCH_PWROK_R")
	)
	(segment
		(start 274.96389 -64.861948)
		(end 291.82568 -48.000158)
		(width 0.127)
		(layer "In15.Cu")
		(net "PWRGD_PCH_PWROK_R")
	)
	(segment
		(start 317.060326 -27.142948)
		(end 317.5889 -27.671522)
		(width 0.127)
		(layer "In15.Cu")
		(net "PWRGD_PCH_PWROK_R")
	)
	(segment
		(start 201.50709 -82.565748)
		(end 222.81769 -82.565748)
		(width 0.127)
		(layer "In15.Cu")
		(net "PWRGD_PCH_PWROK_R")
	)
	(segment
		(start 139.234926 -119.966994)
		(end 134.576566 -119.966994)
		(width 0.127)
		(layer "In15.Cu")
		(net "PWRGD_PCH_PWROK_R")
	)
	(segment
		(start 169.447972 -128.48971)
		(end 168.539414 -129.398268)
		(width 0.127)
		(layer "In15.Cu")
		(net "PWRGD_PCH_PWROK_R")
	)
	(segment
		(start 168.539414 -129.398268)
		(end 167.11168 -129.398268)
		(width 0.127)
		(layer "In15.Cu")
		(net "PWRGD_PCH_PWROK_R")
	)
	(segment
		(start 152.6794 -128.842008)
		(end 148.10994 -128.842008)
		(width 0.127)
		(layer "In15.Cu")
		(net "PWRGD_PCH_PWROK_R")
	)
	(segment
		(start 163.66998 -128.633728)
		(end 163.3601 -128.323848)
		(width 0.127)
		(layer "In15.Cu")
		(net "PWRGD_PCH_PWROK_R")
	)
	(segment
		(start 303.157636 -31.665418)
		(end 306.73548 -31.665418)
		(width 0.127)
		(layer "In15.Cu")
		(net "PWRGD_PCH_PWROK_R")
	)
	(segment
		(start 308.08168 -28.234894)
		(end 309.173626 -27.142948)
		(width 0.127)
		(layer "In15.Cu")
		(net "PWRGD_PCH_PWROK_R")
	)
	(segment
		(start 201.32548 -89.207848)
		(end 200.89368 -88.776048)
		(width 0.127)
		(layer "In15.Cu")
		(net "PWRGD_PCH_PWROK_R")
	)
	(segment
		(start 134.576566 -119.966994)
		(end 132.9309 -118.321328)
		(width 0.127)
		(layer "In15.Cu")
		(net "PWRGD_PCH_PWROK_R")
	)
	(segment
		(start 309.173626 -27.142948)
		(end 317.060326 -27.142948)
		(width 0.127)
		(layer "In15.Cu")
		(net "PWRGD_PCH_PWROK_R")
	)
	(segment
		(start 175.49749 -123.557538)
		(end 174.96409 -123.557538)
		(width 0.127)
		(layer "In15.Cu")
		(net "PWRGD_PCH_PWROK_R")
	)
	(segment
		(start 306.73548 -31.665418)
		(end 308.08168 -30.319218)
		(width 0.127)
		(layer "In15.Cu")
		(net "PWRGD_PCH_PWROK_R")
	)
	(segment
		(start 243.991892 -71.059548)
		(end 246.046752 -69.004688)
		(width 0.127)
		(layer "In15.Cu")
		(net "PWRGD_PCH_PWROK_R")
	)
	(segment
		(start 163.3601 -128.323848)
		(end 153.19756 -128.323848)
		(width 0.127)
		(layer "In15.Cu")
		(net "PWRGD_PCH_PWROK_R")
	)
	(segment
		(start 167.11168 -129.398268)
		(end 166.34714 -128.633728)
		(width 0.127)
		(layer "In15.Cu")
		(net "PWRGD_PCH_PWROK_R")
	)
	(segment
		(start 175.75022 -122.037348)
		(end 175.95088 -122.238008)
		(width 0.127)
		(layer "In15.Cu")
		(net "PWRGD_PCH_PWROK_R")
	)
	(segment
		(start 166.34714 -128.633728)
		(end 163.66998 -128.633728)
		(width 0.127)
		(layer "In15.Cu")
		(net "PWRGD_PCH_PWROK_R")
	)
	(segment
		(start 175.95088 -122.238008)
		(end 175.95088 -123.104148)
		(width 0.127)
		(layer "In15.Cu")
		(net "PWRGD_PCH_PWROK_R")
	)
	(segment
		(start 253.424182 -66.615056)
		(end 262.237728 -64.861948)
		(width 0.127)
		(layer "In15.Cu")
		(net "PWRGD_PCH_PWROK_R")
	)
	(segment
		(start 174.96409 -123.557538)
		(end 174.57928 -123.942348)
		(width 0.127)
		(layer "In15.Cu")
		(net "PWRGD_PCH_PWROK_R")
	)
	(segment
		(start 291.82568 -48.000158)
		(end 291.82568 -44.516294)
		(width 0.127)
		(layer "In15.Cu")
		(net "PWRGD_PCH_PWROK_R")
	)
	(segment
		(start 201.32548 -90.134948)
		(end 201.32548 -89.207848)
		(width 0.127)
		(layer "In15.Cu")
		(net "PWRGD_PCH_PWROK_R")
	)
	(segment
		(start 246.046752 -69.004688)
		(end 251.03455 -69.004688)
		(width 0.127)
		(layer "In15.Cu")
		(net "PWRGD_PCH_PWROK_R")
	)
	(segment
		(start 100.17506 -118.321328)
		(end 99.03968 -117.185948)
		(width 0.127)
		(layer "In15.Cu")
		(net "PWRGD_PCH_PWROK_R")
	)
	(segment
		(start 153.19756 -128.323848)
		(end 152.6794 -128.842008)
		(width 0.127)
		(layer "In15.Cu")
		(net "PWRGD_PCH_PWROK_R")
	)
	(segment
		(start 320.745612 -32.241744)
		(end 320.745612 -31.640526)
		(width 0.12954)
		(layer "F.Cu")
		(net "PWRGD_PCH_PWROK")
	)
	(segment
		(start 326.428862 -37.36086)
		(end 325.094854 -37.36086)
		(width 0.12954)
		(layer "F.Cu")
		(net "PWRGD_PCH_PWROK")
	)
	(segment
		(start 321.110356 -32.606488)
		(end 320.745612 -32.241744)
		(width 0.12954)
		(layer "F.Cu")
		(net "PWRGD_PCH_PWROK")
	)
	(segment
		(start 327.768458 -37.991288)
		(end 327.05929 -37.991288)
		(width 0.0889)
		(layer "F.Cu")
		(net "PWRGD_PCH_PWROK")
	)
	(segment
		(start 316.346078 -24.132032)
		(end 316.346078 -25.09139)
		(width 0.12954)
		(layer "F.Cu")
		(net "PWRGD_PCH_PWROK")
	)
	(segment
		(start 321.185032 -29.105606)
		(end 320.621406 -28.54198)
		(width 0.12954)
		(layer "F.Cu")
		(net "PWRGD_PCH_PWROK")
	)
	(segment
		(start 327.05929 -37.991288)
		(end 326.664066 -37.596064)
		(width 0.0889)
		(layer "F.Cu")
		(net "PWRGD_PCH_PWROK")
	)
	(segment
		(start 321.598544 -30.104334)
		(end 321.185032 -29.105606)
		(width 0.12954)
		(layer "F.Cu")
		(net "PWRGD_PCH_PWROK")
	)
	(segment
		(start 321.315588 -30.787594)
		(end 321.598544 -30.104334)
		(width 0.12954)
		(layer "F.Cu")
		(net "PWRGD_PCH_PWROK")
	)
	(segment
		(start 318.784224 -25.925526)
		(end 317.950088 -25.09139)
		(width 0.12954)
		(layer "F.Cu")
		(net "PWRGD_PCH_PWROK")
	)
	(segment
		(start 327.895458 -38.118288)
		(end 327.768458 -37.991288)
		(width 0.0889)
		(layer "F.Cu")
		(net "PWRGD_PCH_PWROK")
	)
	(segment
		(start 316.346078 -25.09139)
		(end 317.781178 -25.09139)
		(width 0.12954)
		(layer "F.Cu")
		(net "PWRGD_PCH_PWROK")
	)
	(segment
		(start 321.110356 -33.376362)
		(end 321.110356 -32.606488)
		(width 0.12954)
		(layer "F.Cu")
		(net "PWRGD_PCH_PWROK")
	)
	(segment
		(start 320.621406 -28.54198)
		(end 319.34658 -28.54198)
		(width 0.12954)
		(layer "F.Cu")
		(net "PWRGD_PCH_PWROK")
	)
	(segment
		(start 326.664066 -37.596064)
		(end 326.428862 -37.36086)
		(width 0.12954)
		(layer "F.Cu")
		(net "PWRGD_PCH_PWROK")
	)
	(segment
		(start 327.895458 -38.465252)
		(end 327.895458 -38.118288)
		(width 0.0889)
		(layer "F.Cu")
		(net "PWRGD_PCH_PWROK")
	)
	(segment
		(start 318.784224 -27.979624)
		(end 318.784224 -25.925526)
		(width 0.12954)
		(layer "F.Cu")
		(net "PWRGD_PCH_PWROK")
	)
	(segment
		(start 320.745612 -31.640526)
		(end 321.315588 -30.787594)
		(width 0.12954)
		(layer "F.Cu")
		(net "PWRGD_PCH_PWROK")
	)
	(segment
		(start 325.094854 -37.36086)
		(end 321.110356 -33.376362)
		(width 0.12954)
		(layer "F.Cu")
		(net "PWRGD_PCH_PWROK")
	)
	(segment
		(start 317.950088 -25.09139)
		(end 317.781178 -25.09139)
		(width 0.12954)
		(layer "F.Cu")
		(net "PWRGD_PCH_PWROK")
	)
	(segment
		(start 319.34658 -28.54198)
		(end 318.784224 -27.979624)
		(width 0.12954)
		(layer "F.Cu")
		(net "PWRGD_PCH_PWROK")
	)
	(via
		(at 317.781178 -25.09139)
		(size 0.762)
		(drill 0.381)
		(layers "F.Cu" "B.Cu")
		(net "PWRGD_PCH_PWROK")
	)
	(segment
		(start 166.57828 -114.976148)
		(end 165.09873 -114.976148)
		(width 0.12954)
		(layer "F.Cu")
		(net "PWRGD_P5V_AUX_R2")
	)
	(segment
		(start 165.09873 -114.976148)
		(end 165.04793 -115.026948)
		(width 0.12954)
		(layer "F.Cu")
		(net "PWRGD_P5V_AUX_R2")
	)
	(segment
		(start 172.555662 -113.77549)
		(end 172.155612 -114.17554)
		(width 0.12954)
		(layer "F.Cu")
		(net "PWRGD_P5V_AUX_R2")
	)
	(segment
		(start 153.789126 -118.051072)
		(end 153.789126 -118.760748)
		(width 0.12954)
		(layer "F.Cu")
		(net "PWRGD_P5V_AUX_R2")
	)
	(via
		(at 153.789126 -118.760748)
		(size 0.508)
		(drill 0.254)
		(layers "F.Cu" "B.Cu")
		(net "PWRGD_P5V_AUX_R2")
	)
	(via
		(at 172.155612 -114.17554)
		(size 0.4572)
		(drill 0.254)
		(layers "F.Cu" "B.Cu")
		(net "PWRGD_P5V_AUX_R2")
	)
	(via
		(at 166.57828 -114.976148)
		(size 0.508)
		(drill 0.254)
		(layers "F.Cu" "B.Cu")
		(net "PWRGD_P5V_AUX_R2")
	)
	(segment
		(start 153.70048 -117.922548)
		(end 153.70048 -118.672102)
		(width 0.127)
		(layer "In4.Cu")
		(net "PWRGD_P5V_AUX_R2")
	)
	(segment
		(start 163.88588 -116.906548)
		(end 154.71648 -116.906548)
		(width 0.127)
		(layer "In4.Cu")
		(net "PWRGD_P5V_AUX_R2")
	)
	(segment
		(start 153.70048 -118.672102)
		(end 153.789126 -118.760748)
		(width 0.127)
		(layer "In4.Cu")
		(net "PWRGD_P5V_AUX_R2")
	)
	(segment
		(start 154.71648 -116.906548)
		(end 153.70048 -117.922548)
		(width 0.127)
		(layer "In4.Cu")
		(net "PWRGD_P5V_AUX_R2")
	)
	(segment
		(start 165.81628 -114.976148)
		(end 163.88588 -116.906548)
		(width 0.127)
		(layer "In4.Cu")
		(net "PWRGD_P5V_AUX_R2")
	)
	(segment
		(start 166.57828 -114.976148)
		(end 165.81628 -114.976148)
		(width 0.127)
		(layer "In4.Cu")
		(net "PWRGD_P5V_AUX_R2")
	)
	(segment
		(start 171.831 -114.5794)
		(end 172.155612 -114.254788)
		(width 0.127)
		(layer "In6.Cu")
		(net "PWRGD_P5V_AUX_R2")
	)
	(segment
		(start 172.155612 -114.254788)
		(end 172.155612 -114.17554)
		(width 0.127)
		(layer "In6.Cu")
		(net "PWRGD_P5V_AUX_R2")
	)
	(segment
		(start 166.975028 -114.5794)
		(end 171.831 -114.5794)
		(width 0.127)
		(layer "In6.Cu")
		(net "PWRGD_P5V_AUX_R2")
	)
	(segment
		(start 166.57828 -114.976148)
		(end 166.975028 -114.5794)
		(width 0.127)
		(layer "In6.Cu")
		(net "PWRGD_P5V_AUX_R2")
	)
	(segment
		(start 153.10993 -121.249948)
		(end 153.10993 -119.980202)
		(width 0.12954)
		(layer "F.Cu")
		(net "PWRGD_P5V_AUX_R1")
	)
	(segment
		(start 152.58288 -119.471948)
		(end 153.04008 -119.471948)
		(width 0.12954)
		(layer "F.Cu")
		(net "PWRGD_P5V_AUX_R1")
	)
	(segment
		(start 152.489154 -119.565674)
		(end 152.58288 -119.471948)
		(width 0.12954)
		(layer "F.Cu")
		(net "PWRGD_P5V_AUX_R1")
	)
	(segment
		(start 153.10993 -119.980202)
		(end 153.13914 -119.950992)
		(width 0.12954)
		(layer "F.Cu")
		(net "PWRGD_P5V_AUX_R1")
	)
	(segment
		(start 152.489154 -119.950992)
		(end 152.489154 -119.565674)
		(width 0.12954)
		(layer "F.Cu")
		(net "PWRGD_P5V_AUX_R1")
	)
	(segment
		(start 153.10993 -122.519948)
		(end 153.10993 -121.249948)
		(width 0.12954)
		(layer "F.Cu")
		(net "PWRGD_P5V_AUX_R1")
	)
	(segment
		(start 153.04008 -119.471948)
		(end 153.13914 -119.571008)
		(width 0.12954)
		(layer "F.Cu")
		(net "PWRGD_P5V_AUX_R1")
	)
	(segment
		(start 153.13914 -119.571008)
		(end 153.13914 -119.950992)
		(width 0.12954)
		(layer "F.Cu")
		(net "PWRGD_P5V_AUX_R1")
	)
	(via
		(at 153.10993 -121.249948)
		(size 0.762)
		(drill 0.381)
		(layers "F.Cu" "B.Cu")
		(net "PWRGD_P5V_AUX_R1")
	)
	(segment
		(start 460.397606 -383.004314)
		(end 460.754476 -383.004314)
		(width 0.12954)
		(layer "F.Cu")
		(net "PWRGD_P5V_AUX_R")
	)
	(segment
		(start 459.547722 -383.228088)
		(end 459.687676 -383.088134)
		(width 0.12954)
		(layer "F.Cu")
		(net "PWRGD_P5V_AUX_R")
	)
	(segment
		(start 459.687676 -383.088134)
		(end 460.313786 -383.088134)
		(width 0.12954)
		(layer "F.Cu")
		(net "PWRGD_P5V_AUX_R")
	)
	(segment
		(start 461.045306 -382.713484)
		(end 460.754476 -383.004314)
		(width 0.12954)
		(layer "F.Cu")
		(net "PWRGD_P5V_AUX_R")
	)
	(segment
		(start 460.313786 -383.088134)
		(end 460.397606 -383.004314)
		(width 0.12954)
		(layer "F.Cu")
		(net "PWRGD_P5V_AUX_R")
	)
	(segment
		(start 459.547722 -383.684272)
		(end 459.547722 -383.228088)
		(width 0.12954)
		(layer "F.Cu")
		(net "PWRGD_P5V_AUX_R")
	)
	(segment
		(start 461.045306 -382.077214)
		(end 461.045306 -382.713484)
		(width 0.12954)
		(layer "F.Cu")
		(net "PWRGD_P5V_AUX_R")
	)
	(via
		(at 460.754476 -383.004314)
		(size 0.508)
		(drill 0.254)
		(layers "F.Cu" "B.Cu")
		(net "PWRGD_P5V_AUX_R")
	)
	(via
		(at 461.773016 -383.545334)
		(size 0.6604)
		(drill 0.3302)
		(layers "F.Cu" "B.Cu")
		(net "PWRGD_P5V_AUX_R")
	)
	(segment
		(start 461.773016 -383.545334)
		(end 461.353916 -383.964434)
		(width 0.12954)
		(layer "B.Cu")
		(net "PWRGD_P5V_AUX_R")
	)
	(segment
		(start 461.353916 -383.964434)
		(end 460.789274 -383.964434)
		(width 0.12954)
		(layer "B.Cu")
		(net "PWRGD_P5V_AUX_R")
	)
	(segment
		(start 460.789274 -383.964434)
		(end 460.475838 -383.650998)
		(width 0.12954)
		(layer "B.Cu")
		(net "PWRGD_P5V_AUX_R")
	)
	(segment
		(start 460.754476 -383.004314)
		(end 461.231996 -383.004314)
		(width 0.12954)
		(layer "B.Cu")
		(net "PWRGD_P5V_AUX_R")
	)
	(segment
		(start 461.231996 -383.004314)
		(end 461.773016 -383.545334)
		(width 0.12954)
		(layer "B.Cu")
		(net "PWRGD_P5V_AUX_R")
	)
	(segment
		(start 153.13914 -117.312948)
		(end 153.13914 -116.530882)
		(width 0.12954)
		(layer "F.Cu")
		(net "PWRGD_P5V_AUX")
	)
	(segment
		(start 153.13914 -118.051072)
		(end 153.13914 -117.312948)
		(width 0.12954)
		(layer "F.Cu")
		(net "PWRGD_P5V_AUX")
	)
	(segment
		(start 461.845406 -382.077214)
		(end 461.845406 -381.404114)
		(width 0.12954)
		(layer "F.Cu")
		(net "PWRGD_P5V_AUX")
	)
	(segment
		(start 153.13914 -116.530882)
		(end 153.16327 -116.506752)
		(width 0.12954)
		(layer "F.Cu")
		(net "PWRGD_P5V_AUX")
	)
	(via
		(at 239.845088 -204.06614)
		(size 0.508)
		(drill 0.254)
		(layers "F.Cu" "B.Cu")
		(net "PWRGD_P5V_AUX")
	)
	(via
		(at 301.68088 -390.235948)
		(size 0.508)
		(drill 0.254)
		(layers "F.Cu" "B.Cu")
		(net "PWRGD_P5V_AUX")
	)
	(via
		(at 205.03388 -125.313948)
		(size 0.508)
		(drill 0.254)
		(layers "F.Cu" "B.Cu")
		(net "PWRGD_P5V_AUX")
	)
	(via
		(at 461.845406 -381.404114)
		(size 0.508)
		(drill 0.254)
		(layers "F.Cu" "B.Cu")
		(net "PWRGD_P5V_AUX")
	)
	(via
		(at 153.13914 -117.312948)
		(size 0.508)
		(drill 0.254)
		(layers "F.Cu" "B.Cu")
		(net "PWRGD_P5V_AUX")
	)
	(segment
		(start 174.85106 -125.471428)
		(end 174.64278 -125.679708)
		(width 0.127)
		(layer "In4.Cu")
		(net "PWRGD_P5V_AUX")
	)
	(segment
		(start 278.788114 -374.116346)
		(end 292.814248 -388.14248)
		(width 0.127)
		(layer "In4.Cu")
		(net "PWRGD_P5V_AUX")
	)
	(segment
		(start 174.64278 -125.679708)
		(end 174.64278 -126.093728)
		(width 0.127)
		(layer "In4.Cu")
		(net "PWRGD_P5V_AUX")
	)
	(segment
		(start 184.282588 -124.455428)
		(end 183.644032 -125.093984)
		(width 0.127)
		(layer "In4.Cu")
		(net "PWRGD_P5V_AUX")
	)
	(segment
		(start 164.906452 -123.28652)
		(end 156.575252 -123.28652)
		(width 0.127)
		(layer "In4.Cu")
		(net "PWRGD_P5V_AUX")
	)
	(segment
		(start 205.03388 -125.313948)
		(end 204.04328 -125.313948)
		(width 0.127)
		(layer "In4.Cu")
		(net "PWRGD_P5V_AUX")
	)
	(segment
		(start 200.75144 -124.384308)
		(end 198.90486 -126.230888)
		(width 0.127)
		(layer "In4.Cu")
		(net "PWRGD_P5V_AUX")
	)
	(segment
		(start 195.4022 -126.670308)
		(end 191.089788 -126.670308)
		(width 0.127)
		(layer "In4.Cu")
		(net "PWRGD_P5V_AUX")
	)
	(segment
		(start 174.26686 -126.469648)
		(end 170.38066 -126.469648)
		(width 0.127)
		(layer "In4.Cu")
		(net "PWRGD_P5V_AUX")
	)
	(segment
		(start 180.222144 -125.093984)
		(end 179.8447 -125.471428)
		(width 0.127)
		(layer "In4.Cu")
		(net "PWRGD_P5V_AUX")
	)
	(segment
		(start 167.603932 -125.984)
		(end 164.906452 -123.28652)
		(width 0.127)
		(layer "In4.Cu")
		(net "PWRGD_P5V_AUX")
	)
	(segment
		(start 301.490888 -390.42594)
		(end 301.68088 -390.235948)
		(width 0.127)
		(layer "In4.Cu")
		(net "PWRGD_P5V_AUX")
	)
	(segment
		(start 174.64278 -126.093728)
		(end 174.26686 -126.469648)
		(width 0.127)
		(layer "In4.Cu")
		(net "PWRGD_P5V_AUX")
	)
	(segment
		(start 292.814248 -388.14248)
		(end 295.67632 -388.14248)
		(width 0.127)
		(layer "In4.Cu")
		(net "PWRGD_P5V_AUX")
	)
	(segment
		(start 153.13914 -119.850408)
		(end 153.13914 -117.312948)
		(width 0.127)
		(layer "In4.Cu")
		(net "PWRGD_P5V_AUX")
	)
	(segment
		(start 295.67632 -388.14248)
		(end 297.95978 -390.42594)
		(width 0.127)
		(layer "In4.Cu")
		(net "PWRGD_P5V_AUX")
	)
	(segment
		(start 246.423434 -327.586594)
		(end 278.788114 -359.951274)
		(width 0.127)
		(layer "In4.Cu")
		(net "PWRGD_P5V_AUX")
	)
	(segment
		(start 170.38066 -126.469648)
		(end 169.895012 -125.984)
		(width 0.127)
		(layer "In4.Cu")
		(net "PWRGD_P5V_AUX")
	)
	(segment
		(start 191.089788 -126.670308)
		(end 188.874908 -124.455428)
		(width 0.127)
		(layer "In4.Cu")
		(net "PWRGD_P5V_AUX")
	)
	(segment
		(start 195.84162 -126.230888)
		(end 195.4022 -126.670308)
		(width 0.127)
		(layer "In4.Cu")
		(net "PWRGD_P5V_AUX")
	)
	(segment
		(start 246.423434 -280.546302)
		(end 246.423434 -327.586594)
		(width 0.127)
		(layer "In4.Cu")
		(net "PWRGD_P5V_AUX")
	)
	(segment
		(start 183.644032 -125.093984)
		(end 180.222144 -125.093984)
		(width 0.127)
		(layer "In4.Cu")
		(net "PWRGD_P5V_AUX")
	)
	(segment
		(start 204.04328 -125.313948)
		(end 203.11364 -124.384308)
		(width 0.127)
		(layer "In4.Cu")
		(net "PWRGD_P5V_AUX")
	)
	(segment
		(start 188.874908 -124.455428)
		(end 184.282588 -124.455428)
		(width 0.127)
		(layer "In4.Cu")
		(net "PWRGD_P5V_AUX")
	)
	(segment
		(start 203.11364 -124.384308)
		(end 200.75144 -124.384308)
		(width 0.127)
		(layer "In4.Cu")
		(net "PWRGD_P5V_AUX")
	)
	(segment
		(start 250.06808 -276.901656)
		(end 246.423434 -280.546302)
		(width 0.127)
		(layer "In4.Cu")
		(net "PWRGD_P5V_AUX")
	)
	(segment
		(start 297.95978 -390.42594)
		(end 301.490888 -390.42594)
		(width 0.127)
		(layer "In4.Cu")
		(net "PWRGD_P5V_AUX")
	)
	(segment
		(start 198.90486 -126.230888)
		(end 195.84162 -126.230888)
		(width 0.127)
		(layer "In4.Cu")
		(net "PWRGD_P5V_AUX")
	)
	(segment
		(start 169.895012 -125.984)
		(end 167.603932 -125.984)
		(width 0.127)
		(layer "In4.Cu")
		(net "PWRGD_P5V_AUX")
	)
	(segment
		(start 179.8447 -125.471428)
		(end 174.85106 -125.471428)
		(width 0.127)
		(layer "In4.Cu")
		(net "PWRGD_P5V_AUX")
	)
	(segment
		(start 156.575252 -123.28652)
		(end 153.13914 -119.850408)
		(width 0.127)
		(layer "In4.Cu")
		(net "PWRGD_P5V_AUX")
	)
	(segment
		(start 278.788114 -359.951274)
		(end 278.788114 -374.116346)
		(width 0.127)
		(layer "In4.Cu")
		(net "PWRGD_P5V_AUX")
	)
	(segment
		(start 239.845088 -204.06614)
		(end 250.06808 -214.289132)
		(width 0.127)
		(layer "In4.Cu")
		(net "PWRGD_P5V_AUX")
	)
	(segment
		(start 250.06808 -214.289132)
		(end 250.06808 -276.901656)
		(width 0.127)
		(layer "In4.Cu")
		(net "PWRGD_P5V_AUX")
	)
	(segment
		(start 443.24016 -376.596148)
		(end 432.225704 -376.596148)
		(width 0.127)
		(layer "In11.Cu")
		(net "PWRGD_P5V_AUX")
	)
	(segment
		(start 432.225704 -376.596148)
		(end 430.234344 -378.587508)
		(width 0.127)
		(layer "In11.Cu")
		(net "PWRGD_P5V_AUX")
	)
	(segment
		(start 423.759376 -380.812548)
		(end 422.61282 -380.812548)
		(width 0.127)
		(layer "In11.Cu")
		(net "PWRGD_P5V_AUX")
	)
	(segment
		(start 461.845406 -378.239274)
		(end 461.03032 -377.424188)
		(width 0.127)
		(layer "In11.Cu")
		(net "PWRGD_P5V_AUX")
	)
	(segment
		(start 425.984416 -378.587508)
		(end 423.759376 -380.812548)
		(width 0.127)
		(layer "In11.Cu")
		(net "PWRGD_P5V_AUX")
	)
	(segment
		(start 239.845088 -204.06614)
		(end 239.845088 -203.915772)
		(width 0.127)
		(layer "In11.Cu")
		(net "PWRGD_P5V_AUX")
	)
	(segment
		(start 355.40188 -384.520948)
		(end 349.68688 -390.235948)
		(width 0.127)
		(layer "In11.Cu")
		(net "PWRGD_P5V_AUX")
	)
	(segment
		(start 430.234344 -378.587508)
		(end 425.984416 -378.587508)
		(width 0.127)
		(layer "In11.Cu")
		(net "PWRGD_P5V_AUX")
	)
	(segment
		(start 205.843632 -135.300974)
		(end 205.843632 -126.1237)
		(width 0.127)
		(layer "In11.Cu")
		(net "PWRGD_P5V_AUX")
	)
	(segment
		(start 349.68688 -390.235948)
		(end 301.68088 -390.235948)
		(width 0.127)
		(layer "In11.Cu")
		(net "PWRGD_P5V_AUX")
	)
	(segment
		(start 230.34498 -171.869354)
		(end 216.597992 -158.122366)
		(width 0.127)
		(layer "In11.Cu")
		(net "PWRGD_P5V_AUX")
	)
	(segment
		(start 461.03032 -377.424188)
		(end 444.0682 -377.424188)
		(width 0.127)
		(layer "In11.Cu")
		(net "PWRGD_P5V_AUX")
	)
	(segment
		(start 230.34498 -194.415664)
		(end 230.34498 -171.869354)
		(width 0.127)
		(layer "In11.Cu")
		(net "PWRGD_P5V_AUX")
	)
	(segment
		(start 216.597992 -158.122366)
		(end 216.597992 -146.055334)
		(width 0.127)
		(layer "In11.Cu")
		(net "PWRGD_P5V_AUX")
	)
	(segment
		(start 239.845088 -203.915772)
		(end 230.34498 -194.415664)
		(width 0.127)
		(layer "In11.Cu")
		(net "PWRGD_P5V_AUX")
	)
	(segment
		(start 216.597992 -146.055334)
		(end 205.843632 -135.300974)
		(width 0.127)
		(layer "In11.Cu")
		(net "PWRGD_P5V_AUX")
	)
	(segment
		(start 461.845406 -381.404114)
		(end 461.845406 -378.239274)
		(width 0.127)
		(layer "In11.Cu")
		(net "PWRGD_P5V_AUX")
	)
	(segment
		(start 422.61282 -380.812548)
		(end 418.90442 -384.520948)
		(width 0.127)
		(layer "In11.Cu")
		(net "PWRGD_P5V_AUX")
	)
	(segment
		(start 444.0682 -377.424188)
		(end 443.24016 -376.596148)
		(width 0.127)
		(layer "In11.Cu")
		(net "PWRGD_P5V_AUX")
	)
	(segment
		(start 418.90442 -384.520948)
		(end 355.40188 -384.520948)
		(width 0.127)
		(layer "In11.Cu")
		(net "PWRGD_P5V_AUX")
	)
	(segment
		(start 205.843632 -126.1237)
		(end 205.03388 -125.313948)
		(width 0.127)
		(layer "In11.Cu")
		(net "PWRGD_P5V_AUX")
	)
	(segment
		(start 423.33926 -49.09566)
		(end 419.65626 -49.09566)
		(width 0.12954)
		(layer "F.Cu")
		(net "PWRGD_P5V")
	)
	(segment
		(start 419.65626 -49.09566)
		(end 418.920168 -49.831752)
		(width 0.12954)
		(layer "F.Cu")
		(net "PWRGD_P5V")
	)
	(segment
		(start 418.920168 -49.831752)
		(end 418.78758 -49.831752)
		(width 0.12954)
		(layer "F.Cu")
		(net "PWRGD_P5V")
	)
	(via
		(at 423.33926 -49.09566)
		(size 0.508)
		(drill 0.254)
		(layers "F.Cu" "B.Cu")
		(net "PWRGD_P5V")
	)
	(segment
		(start 435.10962 -44.59351)
		(end 435.10962 -45.24756)
		(width 0.12954)
		(layer "B.Cu")
		(net "PWRGD_P5V")
	)
	(segment
		(start 423.8752 -48.55972)
		(end 430.55032 -48.55972)
		(width 0.12954)
		(layer "B.Cu")
		(net "PWRGD_P5V")
	)
	(segment
		(start 435.05628 -44.54017)
		(end 434.01234 -44.54017)
		(width 0.12954)
		(layer "B.Cu")
		(net "PWRGD_P5V")
	)
	(segment
		(start 435.05628 -44.54017)
		(end 435.10962 -44.59351)
		(width 0.12954)
		(layer "B.Cu")
		(net "PWRGD_P5V")
	)
	(segment
		(start 434.86832 -45.48886)
		(end 434.86832 -47.03318)
		(width 0.12954)
		(layer "B.Cu")
		(net "PWRGD_P5V")
	)
	(segment
		(start 434.00472 -45.10532)
		(end 434.00472 -44.53255)
		(width 0.12954)
		(layer "B.Cu")
		(net "PWRGD_P5V")
	)
	(segment
		(start 435.10962 -45.24756)
		(end 434.86832 -45.48886)
		(width 0.12954)
		(layer "B.Cu")
		(net "PWRGD_P5V")
	)
	(segment
		(start 434.01234 -44.54017)
		(end 434.00472 -44.53255)
		(width 0.12954)
		(layer "B.Cu")
		(net "PWRGD_P5V")
	)
	(segment
		(start 430.55032 -48.55972)
		(end 434.00472 -45.10532)
		(width 0.12954)
		(layer "B.Cu")
		(net "PWRGD_P5V")
	)
	(segment
		(start 423.33926 -49.09566)
		(end 423.8752 -48.55972)
		(width 0.12954)
		(layer "B.Cu")
		(net "PWRGD_P5V")
	)
	(segment
		(start 160.83788 -133.676898)
		(end 160.81883 -133.695948)
		(width 0.12954)
		(layer "F.Cu")
		(net "PWRGD_P3V3_AUX_R2")
	)
	(segment
		(start 158.75 -133.596888)
		(end 158.23184 -133.078728)
		(width 0.12954)
		(layer "F.Cu")
		(net "PWRGD_P3V3_AUX_R2")
	)
	(segment
		(start 159.17672 -132.839714)
		(end 159.17672 -133.596888)
		(width 0.12954)
		(layer "F.Cu")
		(net "PWRGD_P3V3_AUX_R2")
	)
	(segment
		(start 160.83788 -132.155946)
		(end 160.83788 -133.676898)
		(width 0.12954)
		(layer "F.Cu")
		(net "PWRGD_P3V3_AUX_R2")
	)
	(segment
		(start 159.860488 -132.155946)
		(end 159.17672 -132.839714)
		(width 0.12954)
		(layer "F.Cu")
		(net "PWRGD_P3V3_AUX_R2")
	)
	(segment
		(start 158.23184 -133.078728)
		(end 158.23184 -132.155946)
		(width 0.12954)
		(layer "F.Cu")
		(net "PWRGD_P3V3_AUX_R2")
	)
	(segment
		(start 159.17672 -133.596888)
		(end 158.75 -133.596888)
		(width 0.12954)
		(layer "F.Cu")
		(net "PWRGD_P3V3_AUX_R2")
	)
	(segment
		(start 160.83788 -132.155946)
		(end 159.860488 -132.155946)
		(width 0.12954)
		(layer "F.Cu")
		(net "PWRGD_P3V3_AUX_R2")
	)
	(via
		(at 159.17672 -133.596888)
		(size 0.762)
		(drill 0.381)
		(layers "F.Cu" "B.Cu")
		(net "PWRGD_P3V3_AUX_R2")
	)
	(segment
		(start 174.955708 -113.77549)
		(end 174.555658 -114.17554)
		(width 0.12954)
		(layer "F.Cu")
		(net "PWRGD_P3V3_AUX_PLD")
	)
	(via
		(at 174.555658 -114.17554)
		(size 0.4572)
		(drill 0.254)
		(layers "F.Cu" "B.Cu")
		(net "PWRGD_P3V3_AUX_PLD")
	)
	(via
		(at 168.90746 -115.380008)
		(size 0.6604)
		(drill 0.3302)
		(layers "F.Cu" "B.Cu")
		(net "PWRGD_P3V3_AUX_PLD")
	)
	(segment
		(start 166.93896 -115.380008)
		(end 166.67734 -115.641628)
		(width 0.12954)
		(layer "B.Cu")
		(net "PWRGD_P3V3_AUX_PLD")
	)
	(segment
		(start 168.90746 -115.380008)
		(end 166.93896 -115.380008)
		(width 0.12954)
		(layer "B.Cu")
		(net "PWRGD_P3V3_AUX_PLD")
	)
	(segment
		(start 173.19752 -115.380008)
		(end 168.90746 -115.380008)
		(width 0.12954)
		(layer "B.Cu")
		(net "PWRGD_P3V3_AUX_PLD")
	)
	(segment
		(start 173.35754 -113.980468)
		(end 173.35754 -115.219988)
		(width 0.12954)
		(layer "B.Cu")
		(net "PWRGD_P3V3_AUX_PLD")
	)
	(segment
		(start 166.67734 -115.641628)
		(end 165.402514 -115.641628)
		(width 0.12954)
		(layer "B.Cu")
		(net "PWRGD_P3V3_AUX_PLD")
	)
	(segment
		(start 165.04793 -115.996212)
		(end 165.04793 -116.296948)
		(width 0.12954)
		(layer "B.Cu")
		(net "PWRGD_P3V3_AUX_PLD")
	)
	(segment
		(start 165.402514 -115.641628)
		(end 165.04793 -115.996212)
		(width 0.12954)
		(layer "B.Cu")
		(net "PWRGD_P3V3_AUX_PLD")
	)
	(segment
		(start 173.35754 -115.219988)
		(end 173.19752 -115.380008)
		(width 0.12954)
		(layer "B.Cu")
		(net "PWRGD_P3V3_AUX_PLD")
	)
	(segment
		(start 174.159926 -113.779808)
		(end 173.5582 -113.779808)
		(width 0.12954)
		(layer "B.Cu")
		(net "PWRGD_P3V3_AUX_PLD")
	)
	(segment
		(start 174.555658 -114.17554)
		(end 174.159926 -113.779808)
		(width 0.12954)
		(layer "B.Cu")
		(net "PWRGD_P3V3_AUX_PLD")
	)
	(segment
		(start 173.5582 -113.779808)
		(end 173.35754 -113.980468)
		(width 0.12954)
		(layer "B.Cu")
		(net "PWRGD_P3V3_AUX_PLD")
	)
	(segment
		(start 460.6798 -381.584962)
		(end 460.6798 -381.091948)
		(width 0.12954)
		(layer "F.Cu")
		(net "PWRGD_P3V3_AUX")
	)
	(segment
		(start 460.119476 -382.358646)
		(end 460.528924 -381.949198)
		(width 0.12954)
		(layer "F.Cu")
		(net "PWRGD_P3V3_AUX")
	)
	(segment
		(start 459.047596 -383.350262)
		(end 460.039212 -382.358646)
		(width 0.1016)
		(layer "F.Cu")
		(net "PWRGD_P3V3_AUX")
	)
	(segment
		(start 445.008 -77.866748)
		(end 445.5414 -76.578968)
		(width 0.12954)
		(layer "F.Cu")
		(net "PWRGD_P3V3_AUX")
	)
	(segment
		(start 445.5414 -76.578968)
		(end 445.5414 -75.070462)
		(width 0.12954)
		(layer "F.Cu")
		(net "PWRGD_P3V3_AUX")
	)
	(segment
		(start 159.88792 -130.15595)
		(end 159.88792 -129.250948)
		(width 0.12954)
		(layer "F.Cu")
		(net "PWRGD_P3V3_AUX")
	)
	(segment
		(start 460.528924 -381.949198)
		(end 460.6798 -381.584962)
		(width 0.12954)
		(layer "F.Cu")
		(net "PWRGD_P3V3_AUX")
	)
	(segment
		(start 460.039212 -382.358646)
		(end 460.119476 -382.358646)
		(width 0.1016)
		(layer "F.Cu")
		(net "PWRGD_P3V3_AUX")
	)
	(segment
		(start 445.834262 -74.7776)
		(end 446.068958 -74.7776)
		(width 0.12954)
		(layer "F.Cu")
		(net "PWRGD_P3V3_AUX")
	)
	(segment
		(start 459.047596 -383.684272)
		(end 459.047596 -383.350262)
		(width 0.1016)
		(layer "F.Cu")
		(net "PWRGD_P3V3_AUX")
	)
	(segment
		(start 445.5414 -75.070462)
		(end 445.834262 -74.7776)
		(width 0.12954)
		(layer "F.Cu")
		(net "PWRGD_P3V3_AUX")
	)
	(via
		(at 275.39823 -110.600998)
		(size 0.508)
		(drill 0.254)
		(layers "F.Cu" "B.Cu")
		(net "PWRGD_P3V3_AUX")
	)
	(via
		(at 464.363816 -83.478116)
		(size 0.508)
		(drill 0.254)
		(layers "F.Cu" "B.Cu")
		(net "PWRGD_P3V3_AUX")
	)
	(via
		(at 465.9884 -103.236268)
		(size 0.508)
		(drill 0.254)
		(layers "F.Cu" "B.Cu")
		(net "PWRGD_P3V3_AUX")
	)
	(via
		(at 445.008 -77.866748)
		(size 0.508)
		(drill 0.254)
		(layers "F.Cu" "B.Cu")
		(net "PWRGD_P3V3_AUX")
	)
	(via
		(at 274.88388 -132.679948)
		(size 0.508)
		(drill 0.254)
		(layers "F.Cu" "B.Cu")
		(net "PWRGD_P3V3_AUX")
	)
	(via
		(at 162.76828 -116.307108)
		(size 0.508)
		(drill 0.254)
		(layers "F.Cu" "B.Cu")
		(net "PWRGD_P3V3_AUX")
	)
	(via
		(at 460.119476 -382.358646)
		(size 0.508)
		(drill 0.254)
		(layers "F.Cu" "B.Cu")
		(net "PWRGD_P3V3_AUX")
	)
	(via
		(at 159.88792 -129.250948)
		(size 0.508)
		(drill 0.254)
		(layers "F.Cu" "B.Cu")
		(net "PWRGD_P3V3_AUX")
	)
	(segment
		(start 464.363816 -89.448132)
		(end 464.363816 -83.478116)
		(width 0.12954)
		(layer "B.Cu")
		(net "PWRGD_P3V3_AUX")
	)
	(segment
		(start 465.9884 -103.236268)
		(end 465.3661 -102.613968)
		(width 0.12954)
		(layer "B.Cu")
		(net "PWRGD_P3V3_AUX")
	)
	(segment
		(start 161.23793 -116.104924)
		(end 161.642806 -115.700048)
		(width 0.12954)
		(layer "B.Cu")
		(net "PWRGD_P3V3_AUX")
	)
	(segment
		(start 163.178744 -115.591336)
		(end 162.76828 -116.0018)
		(width 0.12954)
		(layer "B.Cu")
		(net "PWRGD_P3V3_AUX")
	)
	(segment
		(start 161.642806 -115.700048)
		(end 162.16122 -115.700048)
		(width 0.12954)
		(layer "B.Cu")
		(net "PWRGD_P3V3_AUX")
	)
	(segment
		(start 163.825428 -115.591336)
		(end 163.178744 -115.591336)
		(width 0.12954)
		(layer "B.Cu")
		(net "PWRGD_P3V3_AUX")
	)
	(segment
		(start 164.24783 -116.296948)
		(end 164.24783 -116.013738)
		(width 0.12954)
		(layer "B.Cu")
		(net "PWRGD_P3V3_AUX")
	)
	(segment
		(start 162.16122 -115.700048)
		(end 162.76828 -116.307108)
		(width 0.12954)
		(layer "B.Cu")
		(net "PWRGD_P3V3_AUX")
	)
	(segment
		(start 164.24783 -116.013738)
		(end 163.825428 -115.591336)
		(width 0.12954)
		(layer "B.Cu")
		(net "PWRGD_P3V3_AUX")
	)
	(segment
		(start 161.23793 -116.296948)
		(end 161.23793 -116.104924)
		(width 0.12954)
		(layer "B.Cu")
		(net "PWRGD_P3V3_AUX")
	)
	(segment
		(start 162.76828 -116.0018)
		(end 162.76828 -116.307108)
		(width 0.12954)
		(layer "B.Cu")
		(net "PWRGD_P3V3_AUX")
	)
	(segment
		(start 465.3661 -102.613968)
		(end 465.3661 -90.450416)
		(width 0.12954)
		(layer "B.Cu")
		(net "PWRGD_P3V3_AUX")
	)
	(segment
		(start 465.3661 -90.450416)
		(end 464.363816 -89.448132)
		(width 0.12954)
		(layer "B.Cu")
		(net "PWRGD_P3V3_AUX")
	)
	(segment
		(start 466.68436 -331.927708)
		(end 466.68436 -176.754028)
		(width 0.127)
		(layer "In2.Cu")
		(net "PWRGD_P3V3_AUX")
	)
	(segment
		(start 466.68436 -176.754028)
		(end 453.90308 -163.972748)
		(width 0.127)
		(layer "In2.Cu")
		(net "PWRGD_P3V3_AUX")
	)
	(segment
		(start 460.571342 -382.358646)
		(end 460.82204 -382.107948)
		(width 0.127)
		(layer "In2.Cu")
		(net "PWRGD_P3V3_AUX")
	)
	(segment
		(start 462.78292 -381.902208)
		(end 462.78292 -373.134128)
		(width 0.127)
		(layer "In2.Cu")
		(net "PWRGD_P3V3_AUX")
	)
	(segment
		(start 159.88792 -128.422654)
		(end 159.88792 -129.250948)
		(width 0.127)
		(layer "In2.Cu")
		(net "PWRGD_P3V3_AUX")
	)
	(segment
		(start 462.57718 -382.107948)
		(end 462.78292 -381.902208)
		(width 0.127)
		(layer "In2.Cu")
		(net "PWRGD_P3V3_AUX")
	)
	(segment
		(start 445.008 -77.866748)
		(end 443.705996 -79.168752)
		(width 0.127)
		(layer "In2.Cu")
		(net "PWRGD_P3V3_AUX")
	)
	(segment
		(start 462.78292 -373.134128)
		(end 455.14768 -365.498888)
		(width 0.127)
		(layer "In2.Cu")
		(net "PWRGD_P3V3_AUX")
	)
	(segment
		(start 455.14768 -343.464388)
		(end 466.68436 -331.927708)
		(width 0.127)
		(layer "In2.Cu")
		(net "PWRGD_P3V3_AUX")
	)
	(segment
		(start 460.82204 -382.107948)
		(end 462.57718 -382.107948)
		(width 0.127)
		(layer "In2.Cu")
		(net "PWRGD_P3V3_AUX")
	)
	(segment
		(start 274.88388 -132.679948)
		(end 275.39823 -132.165598)
		(width 0.127)
		(layer "In2.Cu")
		(net "PWRGD_P3V3_AUX")
	)
	(segment
		(start 453.90308 -128.834388)
		(end 464.64982 -118.087648)
		(width 0.127)
		(layer "In2.Cu")
		(net "PWRGD_P3V3_AUX")
	)
	(segment
		(start 164.22878 -117.175788)
		(end 164.22878 -124.081794)
		(width 0.127)
		(layer "In2.Cu")
		(net "PWRGD_P3V3_AUX")
	)
	(segment
		(start 453.90308 -163.972748)
		(end 453.90308 -128.834388)
		(width 0.127)
		(layer "In2.Cu")
		(net "PWRGD_P3V3_AUX")
	)
	(segment
		(start 443.705996 -81.099152)
		(end 444.177928 -81.571084)
		(width 0.127)
		(layer "In2.Cu")
		(net "PWRGD_P3V3_AUX")
	)
	(segment
		(start 164.22878 -124.081794)
		(end 159.88792 -128.422654)
		(width 0.127)
		(layer "In2.Cu")
		(net "PWRGD_P3V3_AUX")
	)
	(segment
		(start 455.14768 -365.498888)
		(end 455.14768 -343.464388)
		(width 0.127)
		(layer "In2.Cu")
		(net "PWRGD_P3V3_AUX")
	)
	(segment
		(start 464.64982 -104.574848)
		(end 465.9884 -103.236268)
		(width 0.127)
		(layer "In2.Cu")
		(net "PWRGD_P3V3_AUX")
	)
	(segment
		(start 162.76828 -116.307108)
		(end 163.34994 -116.888768)
		(width 0.127)
		(layer "In2.Cu")
		(net "PWRGD_P3V3_AUX")
	)
	(segment
		(start 444.177928 -81.571084)
		(end 462.456784 -81.571084)
		(width 0.127)
		(layer "In2.Cu")
		(net "PWRGD_P3V3_AUX")
	)
	(segment
		(start 462.456784 -81.571084)
		(end 464.363816 -83.478116)
		(width 0.127)
		(layer "In2.Cu")
		(net "PWRGD_P3V3_AUX")
	)
	(segment
		(start 163.34994 -116.888768)
		(end 163.94176 -116.888768)
		(width 0.127)
		(layer "In2.Cu")
		(net "PWRGD_P3V3_AUX")
	)
	(segment
		(start 163.94176 -116.888768)
		(end 164.22878 -117.175788)
		(width 0.127)
		(layer "In2.Cu")
		(net "PWRGD_P3V3_AUX")
	)
	(segment
		(start 460.119476 -382.358646)
		(end 460.571342 -382.358646)
		(width 0.127)
		(layer "In2.Cu")
		(net "PWRGD_P3V3_AUX")
	)
	(segment
		(start 443.705996 -79.168752)
		(end 443.705996 -81.099152)
		(width 0.127)
		(layer "In2.Cu")
		(net "PWRGD_P3V3_AUX")
	)
	(segment
		(start 464.64982 -118.087648)
		(end 464.64982 -104.574848)
		(width 0.127)
		(layer "In2.Cu")
		(net "PWRGD_P3V3_AUX")
	)
	(segment
		(start 275.39823 -132.165598)
		(end 275.39823 -110.600998)
		(width 0.127)
		(layer "In2.Cu")
		(net "PWRGD_P3V3_AUX")
	)
	(segment
		(start 275.39823 -109.178598)
		(end 277.16988 -107.406948)
		(width 0.127)
		(layer "In4.Cu")
		(net "PWRGD_P3V3_AUX")
	)
	(segment
		(start 381.35052 -107.539028)
		(end 381.6604 -107.229148)
		(width 0.127)
		(layer "In4.Cu")
		(net "PWRGD_P3V3_AUX")
	)
	(segment
		(start 459.48346 -101.763068)
		(end 459.48346 -100.683568)
		(width 0.127)
		(layer "In4.Cu")
		(net "PWRGD_P3V3_AUX")
	)
	(segment
		(start 437.663336 -113.640108)
		(end 446.827656 -104.475788)
		(width 0.127)
		(layer "In4.Cu")
		(net "PWRGD_P3V3_AUX")
	)
	(segment
		(start 365.94034 -107.539028)
		(end 381.35052 -107.539028)
		(width 0.127)
		(layer "In4.Cu")
		(net "PWRGD_P3V3_AUX")
	)
	(segment
		(start 459.48346 -100.683568)
		(end 459.942692 -100.224336)
		(width 0.127)
		(layer "In4.Cu")
		(net "PWRGD_P3V3_AUX")
	)
	(segment
		(start 338.33054 -107.406948)
		(end 339.09508 -108.171488)
		(width 0.127)
		(layer "In4.Cu")
		(net "PWRGD_P3V3_AUX")
	)
	(segment
		(start 275.39823 -110.600998)
		(end 275.39823 -109.178598)
		(width 0.127)
		(layer "In4.Cu")
		(net "PWRGD_P3V3_AUX")
	)
	(segment
		(start 342.71458 -107.229148)
		(end 365.63046 -107.229148)
		(width 0.127)
		(layer "In4.Cu")
		(net "PWRGD_P3V3_AUX")
	)
	(segment
		(start 456.1713 -105.075228)
		(end 459.48346 -101.763068)
		(width 0.127)
		(layer "In4.Cu")
		(net "PWRGD_P3V3_AUX")
	)
	(segment
		(start 459.942692 -87.89924)
		(end 464.363816 -83.478116)
		(width 0.127)
		(layer "In4.Cu")
		(net "PWRGD_P3V3_AUX")
	)
	(segment
		(start 452.12762 -105.075228)
		(end 456.1713 -105.075228)
		(width 0.127)
		(layer "In4.Cu")
		(net "PWRGD_P3V3_AUX")
	)
	(segment
		(start 459.942692 -100.224336)
		(end 459.942692 -87.89924)
		(width 0.127)
		(layer "In4.Cu")
		(net "PWRGD_P3V3_AUX")
	)
	(segment
		(start 277.16988 -107.406948)
		(end 338.33054 -107.406948)
		(width 0.127)
		(layer "In4.Cu")
		(net "PWRGD_P3V3_AUX")
	)
	(segment
		(start 341.77224 -108.171488)
		(end 342.71458 -107.229148)
		(width 0.127)
		(layer "In4.Cu")
		(net "PWRGD_P3V3_AUX")
	)
	(segment
		(start 381.6604 -107.229148)
		(end 408.011884 -107.229148)
		(width 0.127)
		(layer "In4.Cu")
		(net "PWRGD_P3V3_AUX")
	)
	(segment
		(start 408.011884 -107.229148)
		(end 414.422844 -113.640108)
		(width 0.127)
		(layer "In4.Cu")
		(net "PWRGD_P3V3_AUX")
	)
	(segment
		(start 451.52818 -104.475788)
		(end 452.12762 -105.075228)
		(width 0.127)
		(layer "In4.Cu")
		(net "PWRGD_P3V3_AUX")
	)
	(segment
		(start 365.63046 -107.229148)
		(end 365.94034 -107.539028)
		(width 0.127)
		(layer "In4.Cu")
		(net "PWRGD_P3V3_AUX")
	)
	(segment
		(start 414.422844 -113.640108)
		(end 437.663336 -113.640108)
		(width 0.127)
		(layer "In4.Cu")
		(net "PWRGD_P3V3_AUX")
	)
	(segment
		(start 446.827656 -104.475788)
		(end 451.52818 -104.475788)
		(width 0.127)
		(layer "In4.Cu")
		(net "PWRGD_P3V3_AUX")
	)
	(segment
		(start 339.09508 -108.171488)
		(end 341.77224 -108.171488)
		(width 0.127)
		(layer "In4.Cu")
		(net "PWRGD_P3V3_AUX")
	)
	(segment
		(start 217.85834 -131.011168)
		(end 223.571816 -131.011168)
		(width 0.127)
		(layer "In6.Cu")
		(net "PWRGD_P3V3_AUX")
	)
	(segment
		(start 251.2822 -131.511548)
		(end 253.850648 -134.079996)
		(width 0.127)
		(layer "In6.Cu")
		(net "PWRGD_P3V3_AUX")
	)
	(segment
		(start 167.4876 -127.2286)
		(end 169.418508 -127.2286)
		(width 0.127)
		(layer "In6.Cu")
		(net "PWRGD_P3V3_AUX")
	)
	(segment
		(start 207.59928 -130.360928)
		(end 209.30108 -130.360928)
		(width 0.127)
		(layer "In6.Cu")
		(net "PWRGD_P3V3_AUX")
	)
	(segment
		(start 165.56736 -129.14884)
		(end 167.4876 -127.2286)
		(width 0.127)
		(layer "In6.Cu")
		(net "PWRGD_P3V3_AUX")
	)
	(segment
		(start 159.88792 -129.250948)
		(end 160.619948 -128.51892)
		(width 0.127)
		(layer "In6.Cu")
		(net "PWRGD_P3V3_AUX")
	)
	(segment
		(start 196.75602 -130.112008)
		(end 197.88632 -128.981708)
		(width 0.127)
		(layer "In6.Cu")
		(net "PWRGD_P3V3_AUX")
	)
	(segment
		(start 163.5125 -128.51892)
		(end 164.14242 -129.14884)
		(width 0.127)
		(layer "In6.Cu")
		(net "PWRGD_P3V3_AUX")
	)
	(segment
		(start 225.700336 -128.882648)
		(end 232.942892 -128.882648)
		(width 0.127)
		(layer "In6.Cu")
		(net "PWRGD_P3V3_AUX")
	)
	(segment
		(start 169.80916 -126.837948)
		(end 189.0395 -126.837948)
		(width 0.127)
		(layer "In6.Cu")
		(net "PWRGD_P3V3_AUX")
	)
	(segment
		(start 160.619948 -128.51892)
		(end 163.5125 -128.51892)
		(width 0.127)
		(layer "In6.Cu")
		(net "PWRGD_P3V3_AUX")
	)
	(segment
		(start 203.13396 -128.981708)
		(end 204.3684 -130.216148)
		(width 0.127)
		(layer "In6.Cu")
		(net "PWRGD_P3V3_AUX")
	)
	(segment
		(start 204.3684 -130.216148)
		(end 207.4545 -130.216148)
		(width 0.127)
		(layer "In6.Cu")
		(net "PWRGD_P3V3_AUX")
	)
	(segment
		(start 210.195668 -129.46634)
		(end 213.777068 -129.46634)
		(width 0.127)
		(layer "In6.Cu")
		(net "PWRGD_P3V3_AUX")
	)
	(segment
		(start 240.146332 -127.178308)
		(end 241.2492 -127.178308)
		(width 0.127)
		(layer "In6.Cu")
		(net "PWRGD_P3V3_AUX")
	)
	(segment
		(start 214.447628 -130.1369)
		(end 216.984072 -130.1369)
		(width 0.127)
		(layer "In6.Cu")
		(net "PWRGD_P3V3_AUX")
	)
	(segment
		(start 169.418508 -127.2286)
		(end 169.80916 -126.837948)
		(width 0.127)
		(layer "In6.Cu")
		(net "PWRGD_P3V3_AUX")
	)
	(segment
		(start 250.177046 -128.344168)
		(end 251.2822 -129.449322)
		(width 0.127)
		(layer "In6.Cu")
		(net "PWRGD_P3V3_AUX")
	)
	(segment
		(start 216.984072 -130.1369)
		(end 217.85834 -131.011168)
		(width 0.127)
		(layer "In6.Cu")
		(net "PWRGD_P3V3_AUX")
	)
	(segment
		(start 233.067098 -129.006854)
		(end 238.317786 -129.006854)
		(width 0.127)
		(layer "In6.Cu")
		(net "PWRGD_P3V3_AUX")
	)
	(segment
		(start 207.4545 -130.216148)
		(end 207.59928 -130.360928)
		(width 0.127)
		(layer "In6.Cu")
		(net "PWRGD_P3V3_AUX")
	)
	(segment
		(start 242.41506 -128.344168)
		(end 250.177046 -128.344168)
		(width 0.127)
		(layer "In6.Cu")
		(net "PWRGD_P3V3_AUX")
	)
	(segment
		(start 209.30108 -130.360928)
		(end 210.195668 -129.46634)
		(width 0.127)
		(layer "In6.Cu")
		(net "PWRGD_P3V3_AUX")
	)
	(segment
		(start 197.88632 -128.981708)
		(end 203.13396 -128.981708)
		(width 0.127)
		(layer "In6.Cu")
		(net "PWRGD_P3V3_AUX")
	)
	(segment
		(start 232.942892 -128.882648)
		(end 233.067098 -129.006854)
		(width 0.127)
		(layer "In6.Cu")
		(net "PWRGD_P3V3_AUX")
	)
	(segment
		(start 253.850648 -134.079996)
		(end 273.483832 -134.079996)
		(width 0.127)
		(layer "In6.Cu")
		(net "PWRGD_P3V3_AUX")
	)
	(segment
		(start 273.483832 -134.079996)
		(end 274.88388 -132.679948)
		(width 0.127)
		(layer "In6.Cu")
		(net "PWRGD_P3V3_AUX")
	)
	(segment
		(start 251.2822 -129.449322)
		(end 251.2822 -131.511548)
		(width 0.127)
		(layer "In6.Cu")
		(net "PWRGD_P3V3_AUX")
	)
	(segment
		(start 213.777068 -129.46634)
		(end 214.447628 -130.1369)
		(width 0.127)
		(layer "In6.Cu")
		(net "PWRGD_P3V3_AUX")
	)
	(segment
		(start 238.317786 -129.006854)
		(end 240.146332 -127.178308)
		(width 0.127)
		(layer "In6.Cu")
		(net "PWRGD_P3V3_AUX")
	)
	(segment
		(start 241.2492 -127.178308)
		(end 242.41506 -128.344168)
		(width 0.127)
		(layer "In6.Cu")
		(net "PWRGD_P3V3_AUX")
	)
	(segment
		(start 223.571816 -131.011168)
		(end 225.700336 -128.882648)
		(width 0.127)
		(layer "In6.Cu")
		(net "PWRGD_P3V3_AUX")
	)
	(segment
		(start 164.14242 -129.14884)
		(end 165.56736 -129.14884)
		(width 0.127)
		(layer "In6.Cu")
		(net "PWRGD_P3V3_AUX")
	)
	(segment
		(start 192.31356 -130.112008)
		(end 196.75602 -130.112008)
		(width 0.127)
		(layer "In6.Cu")
		(net "PWRGD_P3V3_AUX")
	)
	(segment
		(start 189.0395 -126.837948)
		(end 192.31356 -130.112008)
		(width 0.127)
		(layer "In6.Cu")
		(net "PWRGD_P3V3_AUX")
	)
	(segment
		(start 360.42473 -94.70898)
		(end 303.00422 -94.70898)
		(width 0.12954)
		(layer "F.Cu")
		(net "PWRGD_P3V3")
	)
	(segment
		(start 298.557188 -90.261948)
		(end 298.22648 -90.261948)
		(width 0.12954)
		(layer "F.Cu")
		(net "PWRGD_P3V3")
	)
	(segment
		(start 415.50209 -87.122508)
		(end 413.761174 -85.381592)
		(width 0.12954)
		(layer "F.Cu")
		(net "PWRGD_P3V3")
	)
	(segment
		(start 173.355762 -113.77549)
		(end 172.955712 -114.17554)
		(width 0.12954)
		(layer "F.Cu")
		(net "PWRGD_P3V3")
	)
	(segment
		(start 413.761174 -85.381592)
		(end 369.752118 -85.381592)
		(width 0.12954)
		(layer "F.Cu")
		(net "PWRGD_P3V3")
	)
	(segment
		(start 414.646618 -54.83606)
		(end 417.9062 -54.83606)
		(width 0.12954)
		(layer "F.Cu")
		(net "PWRGD_P3V3")
	)
	(segment
		(start 417.9062 -54.83606)
		(end 418.6936 -54.04866)
		(width 0.12954)
		(layer "F.Cu")
		(net "PWRGD_P3V3")
	)
	(segment
		(start 414.614868 -54.86781)
		(end 414.646618 -54.83606)
		(width 0.12954)
		(layer "F.Cu")
		(net "PWRGD_P3V3")
	)
	(segment
		(start 303.00422 -94.70898)
		(end 298.557188 -90.261948)
		(width 0.12954)
		(layer "F.Cu")
		(net "PWRGD_P3V3")
	)
	(segment
		(start 369.752118 -85.381592)
		(end 360.42473 -94.70898)
		(width 0.12954)
		(layer "F.Cu")
		(net "PWRGD_P3V3")
	)
	(segment
		(start 418.6936 -54.04866)
		(end 418.6936 -52.27447)
		(width 0.12954)
		(layer "F.Cu")
		(net "PWRGD_P3V3")
	)
	(via
		(at 172.955712 -114.17554)
		(size 0.4572)
		(drill 0.254)
		(layers "F.Cu" "B.Cu")
		(net "PWRGD_P3V3")
	)
	(via
		(at 298.22648 -90.261948)
		(size 0.508)
		(drill 0.254)
		(layers "F.Cu" "B.Cu")
		(net "PWRGD_P3V3")
	)
	(via
		(at 414.614868 -54.86781)
		(size 0.508)
		(drill 0.254)
		(layers "F.Cu" "B.Cu")
		(net "PWRGD_P3V3")
	)
	(via
		(at 415.50209 -87.122508)
		(size 0.508)
		(drill 0.254)
		(layers "F.Cu" "B.Cu")
		(net "PWRGD_P3V3")
	)
	(segment
		(start 239.85093 -91.044014)
		(end 245.620794 -85.27415)
		(width 0.127)
		(layer "In13.Cu")
		(net "PWRGD_P3V3")
	)
	(segment
		(start 181.5846 -93.3196)
		(end 185.0136 -93.3196)
		(width 0.127)
		(layer "In13.Cu")
		(net "PWRGD_P3V3")
	)
	(segment
		(start 173.4312 -102.40264)
		(end 173.4312 -98.3488)
		(width 0.127)
		(layer "In13.Cu")
		(net "PWRGD_P3V3")
	)
	(segment
		(start 181.4576 -93.4466)
		(end 181.5846 -93.3196)
		(width 0.127)
		(layer "In13.Cu")
		(net "PWRGD_P3V3")
	)
	(segment
		(start 415.50209 -55.755032)
		(end 414.614868 -54.86781)
		(width 0.127)
		(layer "In13.Cu")
		(net "PWRGD_P3V3")
	)
	(segment
		(start 245.620794 -85.27415)
		(end 293.238682 -85.27415)
		(width 0.127)
		(layer "In13.Cu")
		(net "PWRGD_P3V3")
	)
	(segment
		(start 175.0822 -93.4466)
		(end 181.4576 -93.4466)
		(width 0.127)
		(layer "In13.Cu")
		(net "PWRGD_P3V3")
	)
	(segment
		(start 415.50209 -87.122508)
		(end 415.50209 -55.755032)
		(width 0.127)
		(layer "In13.Cu")
		(net "PWRGD_P3V3")
	)
	(segment
		(start 190.984632 -86.535768)
		(end 216.694004 -86.535768)
		(width 0.127)
		(layer "In13.Cu")
		(net "PWRGD_P3V3")
	)
	(segment
		(start 174.117 -94.4118)
		(end 175.0822 -93.4466)
		(width 0.127)
		(layer "In13.Cu")
		(net "PWRGD_P3V3")
	)
	(segment
		(start 174.1551 -104.745028)
		(end 173.56836 -104.158288)
		(width 0.127)
		(layer "In13.Cu")
		(net "PWRGD_P3V3")
	)
	(segment
		(start 185.0136 -93.3196)
		(end 185.293 -93.0402)
		(width 0.127)
		(layer "In13.Cu")
		(net "PWRGD_P3V3")
	)
	(segment
		(start 173.56836 -102.5398)
		(end 173.4312 -102.40264)
		(width 0.127)
		(layer "In13.Cu")
		(net "PWRGD_P3V3")
	)
	(segment
		(start 185.293 -92.2274)
		(end 190.984632 -86.535768)
		(width 0.127)
		(layer "In13.Cu")
		(net "PWRGD_P3V3")
	)
	(segment
		(start 185.293 -93.0402)
		(end 185.293 -92.2274)
		(width 0.127)
		(layer "In13.Cu")
		(net "PWRGD_P3V3")
	)
	(segment
		(start 172.974 -94.4118)
		(end 174.117 -94.4118)
		(width 0.127)
		(layer "In13.Cu")
		(net "PWRGD_P3V3")
	)
	(segment
		(start 293.238682 -85.27415)
		(end 298.22648 -90.261948)
		(width 0.127)
		(layer "In13.Cu")
		(net "PWRGD_P3V3")
	)
	(segment
		(start 221.20225 -91.044014)
		(end 239.85093 -91.044014)
		(width 0.127)
		(layer "In13.Cu")
		(net "PWRGD_P3V3")
	)
	(segment
		(start 174.1551 -112.976152)
		(end 174.1551 -104.745028)
		(width 0.127)
		(layer "In13.Cu")
		(net "PWRGD_P3V3")
	)
	(segment
		(start 172.212 -97.1296)
		(end 172.212 -95.1738)
		(width 0.127)
		(layer "In13.Cu")
		(net "PWRGD_P3V3")
	)
	(segment
		(start 173.4312 -98.3488)
		(end 172.212 -97.1296)
		(width 0.127)
		(layer "In13.Cu")
		(net "PWRGD_P3V3")
	)
	(segment
		(start 173.56836 -104.158288)
		(end 173.56836 -102.5398)
		(width 0.127)
		(layer "In13.Cu")
		(net "PWRGD_P3V3")
	)
	(segment
		(start 216.694004 -86.535768)
		(end 221.20225 -91.044014)
		(width 0.127)
		(layer "In13.Cu")
		(net "PWRGD_P3V3")
	)
	(segment
		(start 172.212 -95.1738)
		(end 172.974 -94.4118)
		(width 0.127)
		(layer "In13.Cu")
		(net "PWRGD_P3V3")
	)
	(segment
		(start 172.955712 -114.17554)
		(end 174.1551 -112.976152)
		(width 0.127)
		(layer "In13.Cu")
		(net "PWRGD_P3V3")
	)
	(segment
		(start 385.487926 -74.045064)
		(end 385.109974 -74.423016)
		(width 0.12954)
		(layer "F.Cu")
		(net "PWRGD_P1V8_PCH_AUX_R")
	)
	(segment
		(start 385.237482 -73.394824)
		(end 385.487926 -73.645268)
		(width 0.12954)
		(layer "F.Cu")
		(net "PWRGD_P1V8_PCH_AUX_R")
	)
	(segment
		(start 385.237482 -73.394824)
		(end 385.237482 -72.378824)
		(width 0.12954)
		(layer "F.Cu")
		(net "PWRGD_P1V8_PCH_AUX_R")
	)
	(segment
		(start 385.487926 -73.645268)
		(end 385.487926 -74.045064)
		(width 0.12954)
		(layer "F.Cu")
		(net "PWRGD_P1V8_PCH_AUX_R")
	)
	(segment
		(start 385.109974 -74.423016)
		(end 385.109974 -74.694034)
		(width 0.12954)
		(layer "F.Cu")
		(net "PWRGD_P1V8_PCH_AUX_R")
	)
	(via
		(at 385.487926 -74.045064)
		(size 0.508)
		(drill 0.254)
		(layers "F.Cu" "B.Cu")
		(net "PWRGD_P1V8_PCH_AUX_R")
	)
	(segment
		(start 176.555654 -117.775482)
		(end 176.155604 -118.175532)
		(width 0.12954)
		(layer "F.Cu")
		(net "PWRGD_P1V8_PCH_AUX_PLD")
	)
	(segment
		(start 174.04588 -126.564898)
		(end 174.04588 -125.955298)
		(width 0.12954)
		(layer "F.Cu")
		(net "PWRGD_P1V8_PCH_AUX_PLD")
	)
	(via
		(at 174.04588 -125.955298)
		(size 0.508)
		(drill 0.254)
		(layers "F.Cu" "B.Cu")
		(net "PWRGD_P1V8_PCH_AUX_PLD")
	)
	(via
		(at 176.155604 -118.175532)
		(size 0.4572)
		(drill 0.254)
		(layers "F.Cu" "B.Cu")
		(net "PWRGD_P1V8_PCH_AUX_PLD")
	)
	(segment
		(start 175.75276 -118.578376)
		(end 176.155604 -118.175532)
		(width 0.127)
		(layer "In2.Cu")
		(net "PWRGD_P1V8_PCH_AUX_PLD")
	)
	(segment
		(start 174.04588 -123.363228)
		(end 175.75276 -121.656348)
		(width 0.127)
		(layer "In2.Cu")
		(net "PWRGD_P1V8_PCH_AUX_PLD")
	)
	(segment
		(start 175.75276 -121.656348)
		(end 175.75276 -118.578376)
		(width 0.127)
		(layer "In2.Cu")
		(net "PWRGD_P1V8_PCH_AUX_PLD")
	)
	(segment
		(start 174.04588 -125.955298)
		(end 174.04588 -123.363228)
		(width 0.127)
		(layer "In2.Cu")
		(net "PWRGD_P1V8_PCH_AUX_PLD")
	)
	(segment
		(start 386.037582 -71.362824)
		(end 386.037582 -70.433438)
		(width 0.12954)
		(layer "F.Cu")
		(net "PWRGD_P1V8_PCH_AUX")
	)
	(segment
		(start 106.350816 -96.317054)
		(end 107.066842 -96.317054)
		(width 0.12954)
		(layer "F.Cu")
		(net "PWRGD_P1V8_PCH_AUX")
	)
	(segment
		(start 162.63493 -58.511948)
		(end 162.63493 -59.496198)
		(width 0.12954)
		(layer "F.Cu")
		(net "PWRGD_P1V8_PCH_AUX")
	)
	(segment
		(start 386.037582 -72.378824)
		(end 386.037582 -71.362824)
		(width 0.12954)
		(layer "F.Cu")
		(net "PWRGD_P1V8_PCH_AUX")
	)
	(segment
		(start 174.04588 -127.364998)
		(end 174.04588 -127.974598)
		(width 0.12954)
		(layer "F.Cu")
		(net "PWRGD_P1V8_PCH_AUX")
	)
	(via
		(at 174.04588 -127.974598)
		(size 0.508)
		(drill 0.254)
		(layers "F.Cu" "B.Cu")
		(net "PWRGD_P1V8_PCH_AUX")
	)
	(via
		(at 162.63493 -59.496198)
		(size 0.508)
		(drill 0.254)
		(layers "F.Cu" "B.Cu")
		(net "PWRGD_P1V8_PCH_AUX")
	)
	(via
		(at 386.037582 -70.433438)
		(size 0.508)
		(drill 0.254)
		(layers "F.Cu" "B.Cu")
		(net "PWRGD_P1V8_PCH_AUX")
	)
	(via
		(at 106.350816 -96.317054)
		(size 0.508)
		(drill 0.254)
		(layers "F.Cu" "B.Cu")
		(net "PWRGD_P1V8_PCH_AUX")
	)
	(via
		(at 176.50968 -98.754438)
		(size 0.508)
		(drill 0.254)
		(layers "F.Cu" "B.Cu")
		(net "PWRGD_P1V8_PCH_AUX")
	)
	(via
		(at 314.12688 -95.976948)
		(size 0.508)
		(drill 0.254)
		(layers "F.Cu" "B.Cu")
		(net "PWRGD_P1V8_PCH_AUX")
	)
	(segment
		(start 386.037582 -70.433438)
		(end 385.855972 -70.251828)
		(width 0.12954)
		(layer "B.Cu")
		(net "PWRGD_P1V8_PCH_AUX")
	)
	(segment
		(start 314.12688 -95.520002)
		(end 314.12688 -95.976948)
		(width 0.12954)
		(layer "B.Cu")
		(net "PWRGD_P1V8_PCH_AUX")
	)
	(segment
		(start 355.04628 -95.951548)
		(end 330.77785 -95.951548)
		(width 0.12954)
		(layer "B.Cu")
		(net "PWRGD_P1V8_PCH_AUX")
	)
	(segment
		(start 371.55628 -79.441548)
		(end 355.04628 -95.951548)
		(width 0.12954)
		(layer "B.Cu")
		(net "PWRGD_P1V8_PCH_AUX")
	)
	(segment
		(start 375.9708 -70.251828)
		(end 375.11228 -71.110348)
		(width 0.12954)
		(layer "B.Cu")
		(net "PWRGD_P1V8_PCH_AUX")
	)
	(segment
		(start 375.11228 -71.110348)
		(end 372.41988 -71.110348)
		(width 0.12954)
		(layer "B.Cu")
		(net "PWRGD_P1V8_PCH_AUX")
	)
	(segment
		(start 330.77785 -95.951548)
		(end 330.16825 -95.341948)
		(width 0.12954)
		(layer "B.Cu")
		(net "PWRGD_P1V8_PCH_AUX")
	)
	(segment
		(start 385.855972 -70.251828)
		(end 375.9708 -70.251828)
		(width 0.12954)
		(layer "B.Cu")
		(net "PWRGD_P1V8_PCH_AUX")
	)
	(segment
		(start 372.41988 -71.110348)
		(end 371.55628 -71.973948)
		(width 0.12954)
		(layer "B.Cu")
		(net "PWRGD_P1V8_PCH_AUX")
	)
	(segment
		(start 314.304934 -95.341948)
		(end 314.12688 -95.520002)
		(width 0.12954)
		(layer "B.Cu")
		(net "PWRGD_P1V8_PCH_AUX")
	)
	(segment
		(start 371.55628 -71.973948)
		(end 371.55628 -79.441548)
		(width 0.12954)
		(layer "B.Cu")
		(net "PWRGD_P1V8_PCH_AUX")
	)
	(segment
		(start 330.16825 -95.341948)
		(end 314.304934 -95.341948)
		(width 0.12954)
		(layer "B.Cu")
		(net "PWRGD_P1V8_PCH_AUX")
	)
	(segment
		(start 170.2816 -96.484948)
		(end 170.2816 -91.272868)
		(width 0.127)
		(layer "In2.Cu")
		(net "PWRGD_P1V8_PCH_AUX")
	)
	(segment
		(start 171.6786 -97.881948)
		(end 170.2816 -96.484948)
		(width 0.127)
		(layer "In2.Cu")
		(net "PWRGD_P1V8_PCH_AUX")
	)
	(segment
		(start 176.149 -97.881948)
		(end 171.6786 -97.881948)
		(width 0.127)
		(layer "In2.Cu")
		(net "PWRGD_P1V8_PCH_AUX")
	)
	(segment
		(start 176.50968 -98.242628)
		(end 176.149 -97.881948)
		(width 0.127)
		(layer "In2.Cu")
		(net "PWRGD_P1V8_PCH_AUX")
	)
	(segment
		(start 170.2816 -91.272868)
		(end 162.63493 -83.626198)
		(width 0.127)
		(layer "In2.Cu")
		(net "PWRGD_P1V8_PCH_AUX")
	)
	(segment
		(start 162.63493 -83.626198)
		(end 162.63493 -59.496198)
		(width 0.127)
		(layer "In2.Cu")
		(net "PWRGD_P1V8_PCH_AUX")
	)
	(segment
		(start 176.50968 -98.754438)
		(end 176.50968 -98.242628)
		(width 0.127)
		(layer "In2.Cu")
		(net "PWRGD_P1V8_PCH_AUX")
	)
	(segment
		(start 219.112592 -101.897688)
		(end 220.27642 -100.73386)
		(width 0.127)
		(layer "In11.Cu")
		(net "PWRGD_P1V8_PCH_AUX")
	)
	(segment
		(start 184.0484 -93.2942)
		(end 184.8739 -94.1197)
		(width 0.127)
		(layer "In11.Cu")
		(net "PWRGD_P1V8_PCH_AUX")
	)
	(segment
		(start 173.36008 -123.24334)
		(end 172.10278 -124.50064)
		(width 0.127)
		(layer "In11.Cu")
		(net "PWRGD_P1V8_PCH_AUX")
	)
	(segment
		(start 313.66714 -94.706948)
		(end 314.12688 -95.166688)
		(width 0.127)
		(layer "In11.Cu")
		(net "PWRGD_P1V8_PCH_AUX")
	)
	(segment
		(start 174.15256 -117.196108)
		(end 173.36008 -117.988588)
		(width 0.127)
		(layer "In11.Cu")
		(net "PWRGD_P1V8_PCH_AUX")
	)
	(segment
		(start 205.79715 -101.724968)
		(end 207.04556 -100.476558)
		(width 0.127)
		(layer "In11.Cu")
		(net "PWRGD_P1V8_PCH_AUX")
	)
	(segment
		(start 173.5074 -104.43464)
		(end 174.15256 -105.0798)
		(width 0.127)
		(layer "In11.Cu")
		(net "PWRGD_P1V8_PCH_AUX")
	)
	(segment
		(start 185.031888 -94.1197)
		(end 185.196988 -94.2848)
		(width 0.127)
		(layer "In11.Cu")
		(net "PWRGD_P1V8_PCH_AUX")
	)
	(segment
		(start 221.7674 -100.73386)
		(end 222.931228 -101.897688)
		(width 0.127)
		(layer "In11.Cu")
		(net "PWRGD_P1V8_PCH_AUX")
	)
	(segment
		(start 244.783864 -108.168948)
		(end 246.68988 -108.168948)
		(width 0.127)
		(layer "In11.Cu")
		(net "PWRGD_P1V8_PCH_AUX")
	)
	(segment
		(start 174.04588 -127.968248)
		(end 174.04588 -127.974598)
		(width 0.127)
		(layer "In11.Cu")
		(net "PWRGD_P1V8_PCH_AUX")
	)
	(segment
		(start 249.839734 -111.318802)
		(end 263.172194 -111.318802)
		(width 0.127)
		(layer "In11.Cu")
		(net "PWRGD_P1V8_PCH_AUX")
	)
	(segment
		(start 307.186584 -97.754948)
		(end 310.234584 -94.706948)
		(width 0.127)
		(layer "In11.Cu")
		(net "PWRGD_P1V8_PCH_AUX")
	)
	(segment
		(start 310.234584 -94.706948)
		(end 313.66714 -94.706948)
		(width 0.127)
		(layer "In11.Cu")
		(net "PWRGD_P1V8_PCH_AUX")
	)
	(segment
		(start 184.0484 -92.515436)
		(end 184.0484 -93.2942)
		(width 0.127)
		(layer "In11.Cu")
		(net "PWRGD_P1V8_PCH_AUX")
	)
	(segment
		(start 189.38748 -95.17888)
		(end 192.32372 -95.17888)
		(width 0.127)
		(layer "In11.Cu")
		(net "PWRGD_P1V8_PCH_AUX")
	)
	(segment
		(start 196.118988 -98.974148)
		(end 198.234808 -98.974148)
		(width 0.127)
		(layer "In11.Cu")
		(net "PWRGD_P1V8_PCH_AUX")
	)
	(segment
		(start 188.4934 -94.2848)
		(end 189.38748 -95.17888)
		(width 0.127)
		(layer "In11.Cu")
		(net "PWRGD_P1V8_PCH_AUX")
	)
	(segment
		(start 173.36008 -117.988588)
		(end 173.36008 -123.24334)
		(width 0.127)
		(layer "In11.Cu")
		(net "PWRGD_P1V8_PCH_AUX")
	)
	(segment
		(start 276.736048 -97.754948)
		(end 307.186584 -97.754948)
		(width 0.127)
		(layer "In11.Cu")
		(net "PWRGD_P1V8_PCH_AUX")
	)
	(segment
		(start 172.10278 -124.50064)
		(end 172.10278 -126.0221)
		(width 0.127)
		(layer "In11.Cu")
		(net "PWRGD_P1V8_PCH_AUX")
	)
	(segment
		(start 209.76844 -101.897688)
		(end 219.112592 -101.897688)
		(width 0.127)
		(layer "In11.Cu")
		(net "PWRGD_P1V8_PCH_AUX")
	)
	(segment
		(start 222.931228 -101.897688)
		(end 238.512604 -101.897688)
		(width 0.127)
		(layer "In11.Cu")
		(net "PWRGD_P1V8_PCH_AUX")
	)
	(segment
		(start 185.196988 -94.2848)
		(end 188.4934 -94.2848)
		(width 0.127)
		(layer "In11.Cu")
		(net "PWRGD_P1V8_PCH_AUX")
	)
	(segment
		(start 220.27642 -100.73386)
		(end 221.7674 -100.73386)
		(width 0.127)
		(layer "In11.Cu")
		(net "PWRGD_P1V8_PCH_AUX")
	)
	(segment
		(start 314.12688 -95.166688)
		(end 314.12688 -95.976948)
		(width 0.127)
		(layer "In11.Cu")
		(net "PWRGD_P1V8_PCH_AUX")
	)
	(segment
		(start 175.5648 -97.7392)
		(end 172.6946 -97.7392)
		(width 0.127)
		(layer "In11.Cu")
		(net "PWRGD_P1V8_PCH_AUX")
	)
	(segment
		(start 182.363364 -90.8304)
		(end 184.0484 -92.515436)
		(width 0.127)
		(layer "In11.Cu")
		(net "PWRGD_P1V8_PCH_AUX")
	)
	(segment
		(start 246.68988 -108.168948)
		(end 249.839734 -111.318802)
		(width 0.127)
		(layer "In11.Cu")
		(net "PWRGD_P1V8_PCH_AUX")
	)
	(segment
		(start 198.234808 -98.974148)
		(end 200.985628 -101.724968)
		(width 0.127)
		(layer "In11.Cu")
		(net "PWRGD_P1V8_PCH_AUX")
	)
	(segment
		(start 173.801786 -100.594414)
		(end 173.5074 -100.8888)
		(width 0.127)
		(layer "In11.Cu")
		(net "PWRGD_P1V8_PCH_AUX")
	)
	(segment
		(start 176.50968 -98.68408)
		(end 175.5648 -97.7392)
		(width 0.127)
		(layer "In11.Cu")
		(net "PWRGD_P1V8_PCH_AUX")
	)
	(segment
		(start 175.630586 -100.594414)
		(end 173.801786 -100.594414)
		(width 0.127)
		(layer "In11.Cu")
		(net "PWRGD_P1V8_PCH_AUX")
	)
	(segment
		(start 172.7454 -90.8304)
		(end 182.363364 -90.8304)
		(width 0.127)
		(layer "In11.Cu")
		(net "PWRGD_P1V8_PCH_AUX")
	)
	(segment
		(start 208.34731 -100.476558)
		(end 209.76844 -101.897688)
		(width 0.127)
		(layer "In11.Cu")
		(net "PWRGD_P1V8_PCH_AUX")
	)
	(segment
		(start 200.985628 -101.724968)
		(end 205.79715 -101.724968)
		(width 0.127)
		(layer "In11.Cu")
		(net "PWRGD_P1V8_PCH_AUX")
	)
	(segment
		(start 176.3522 -99.8728)
		(end 175.630586 -100.594414)
		(width 0.127)
		(layer "In11.Cu")
		(net "PWRGD_P1V8_PCH_AUX")
	)
	(segment
		(start 176.50968 -98.754438)
		(end 176.50968 -98.68408)
		(width 0.127)
		(layer "In11.Cu")
		(net "PWRGD_P1V8_PCH_AUX")
	)
	(segment
		(start 238.512604 -101.897688)
		(end 244.783864 -108.168948)
		(width 0.127)
		(layer "In11.Cu")
		(net "PWRGD_P1V8_PCH_AUX")
	)
	(segment
		(start 173.5074 -100.8888)
		(end 173.5074 -104.43464)
		(width 0.127)
		(layer "In11.Cu")
		(net "PWRGD_P1V8_PCH_AUX")
	)
	(segment
		(start 172.6946 -97.7392)
		(end 171.5008 -96.5454)
		(width 0.127)
		(layer "In11.Cu")
		(net "PWRGD_P1V8_PCH_AUX")
	)
	(segment
		(start 173.086268 -127.005588)
		(end 173.086268 -127.008636)
		(width 0.127)
		(layer "In11.Cu")
		(net "PWRGD_P1V8_PCH_AUX")
	)
	(segment
		(start 171.5008 -92.075)
		(end 172.7454 -90.8304)
		(width 0.127)
		(layer "In11.Cu")
		(net "PWRGD_P1V8_PCH_AUX")
	)
	(segment
		(start 176.50968 -98.754438)
		(end 176.3522 -98.911918)
		(width 0.127)
		(layer "In11.Cu")
		(net "PWRGD_P1V8_PCH_AUX")
	)
	(segment
		(start 173.086268 -127.008636)
		(end 174.04588 -127.968248)
		(width 0.127)
		(layer "In11.Cu")
		(net "PWRGD_P1V8_PCH_AUX")
	)
	(segment
		(start 172.10278 -126.0221)
		(end 173.086268 -127.005588)
		(width 0.127)
		(layer "In11.Cu")
		(net "PWRGD_P1V8_PCH_AUX")
	)
	(segment
		(start 176.3522 -98.911918)
		(end 176.3522 -99.8728)
		(width 0.127)
		(layer "In11.Cu")
		(net "PWRGD_P1V8_PCH_AUX")
	)
	(segment
		(start 174.15256 -105.0798)
		(end 174.15256 -117.196108)
		(width 0.127)
		(layer "In11.Cu")
		(net "PWRGD_P1V8_PCH_AUX")
	)
	(segment
		(start 171.5008 -96.5454)
		(end 171.5008 -92.075)
		(width 0.127)
		(layer "In11.Cu")
		(net "PWRGD_P1V8_PCH_AUX")
	)
	(segment
		(start 207.04556 -100.476558)
		(end 208.34731 -100.476558)
		(width 0.127)
		(layer "In11.Cu")
		(net "PWRGD_P1V8_PCH_AUX")
	)
	(segment
		(start 192.32372 -95.17888)
		(end 196.118988 -98.974148)
		(width 0.127)
		(layer "In11.Cu")
		(net "PWRGD_P1V8_PCH_AUX")
	)
	(segment
		(start 263.172194 -111.318802)
		(end 276.736048 -97.754948)
		(width 0.127)
		(layer "In11.Cu")
		(net "PWRGD_P1V8_PCH_AUX")
	)
	(segment
		(start 184.8739 -94.1197)
		(end 185.031888 -94.1197)
		(width 0.127)
		(layer "In11.Cu")
		(net "PWRGD_P1V8_PCH_AUX")
	)
	(segment
		(start 126.05131 -91.340178)
		(end 126.05131 -94.355158)
		(width 0.127)
		(layer "In15.Cu")
		(net "PWRGD_P1V8_PCH_AUX")
	)
	(segment
		(start 176.38268 -98.252788)
		(end 175.081438 -98.252788)
		(width 0.127)
		(layer "In15.Cu")
		(net "PWRGD_P1V8_PCH_AUX")
	)
	(segment
		(start 158.952946 -98.669348)
		(end 151.01316 -98.669348)
		(width 0.127)
		(layer "In15.Cu")
		(net "PWRGD_P1V8_PCH_AUX")
	)
	(segment
		(start 140.84808 -88.504268)
		(end 140.84808 -86.170008)
		(width 0.127)
		(layer "In15.Cu")
		(net "PWRGD_P1V8_PCH_AUX")
	)
	(segment
		(start 171.757848 -98.174048)
		(end 171.630848 -98.047048)
		(width 0.127)
		(layer "In15.Cu")
		(net "PWRGD_P1V8_PCH_AUX")
	)
	(segment
		(start 175.081438 -98.252788)
		(end 175.002698 -98.174048)
		(width 0.127)
		(layer "In15.Cu")
		(net "PWRGD_P1V8_PCH_AUX")
	)
	(segment
		(start 107.95508 -96.352868)
		(end 106.38663 -96.352868)
		(width 0.127)
		(layer "In15.Cu")
		(net "PWRGD_P1V8_PCH_AUX")
	)
	(segment
		(start 106.38663 -96.352868)
		(end 106.350816 -96.317054)
		(width 0.127)
		(layer "In15.Cu")
		(net "PWRGD_P1V8_PCH_AUX")
	)
	(segment
		(start 171.630848 -98.047048)
		(end 159.575246 -98.047048)
		(width 0.127)
		(layer "In15.Cu")
		(net "PWRGD_P1V8_PCH_AUX")
	)
	(segment
		(start 121.81332 -95.578168)
		(end 112.17402 -95.578168)
		(width 0.127)
		(layer "In15.Cu")
		(net "PWRGD_P1V8_PCH_AUX")
	)
	(segment
		(start 151.01316 -98.669348)
		(end 140.84808 -88.504268)
		(width 0.127)
		(layer "In15.Cu")
		(net "PWRGD_P1V8_PCH_AUX")
	)
	(segment
		(start 112.17402 -95.578168)
		(end 110.88116 -96.871028)
		(width 0.127)
		(layer "In15.Cu")
		(net "PWRGD_P1V8_PCH_AUX")
	)
	(segment
		(start 108.47324 -96.871028)
		(end 107.95508 -96.352868)
		(width 0.127)
		(layer "In15.Cu")
		(net "PWRGD_P1V8_PCH_AUX")
	)
	(segment
		(start 110.88116 -96.871028)
		(end 108.47324 -96.871028)
		(width 0.127)
		(layer "In15.Cu")
		(net "PWRGD_P1V8_PCH_AUX")
	)
	(segment
		(start 132.54228 -84.800948)
		(end 130.20548 -87.137748)
		(width 0.127)
		(layer "In15.Cu")
		(net "PWRGD_P1V8_PCH_AUX")
	)
	(segment
		(start 139.47902 -84.800948)
		(end 132.54228 -84.800948)
		(width 0.127)
		(layer "In15.Cu")
		(net "PWRGD_P1V8_PCH_AUX")
	)
	(segment
		(start 140.84808 -86.170008)
		(end 139.47902 -84.800948)
		(width 0.127)
		(layer "In15.Cu")
		(net "PWRGD_P1V8_PCH_AUX")
	)
	(segment
		(start 130.20548 -87.137748)
		(end 130.20548 -87.186008)
		(width 0.127)
		(layer "In15.Cu")
		(net "PWRGD_P1V8_PCH_AUX")
	)
	(segment
		(start 130.20548 -87.186008)
		(end 126.05131 -91.340178)
		(width 0.127)
		(layer "In15.Cu")
		(net "PWRGD_P1V8_PCH_AUX")
	)
	(segment
		(start 125.39726 -95.009208)
		(end 122.38228 -95.009208)
		(width 0.127)
		(layer "In15.Cu")
		(net "PWRGD_P1V8_PCH_AUX")
	)
	(segment
		(start 159.575246 -98.047048)
		(end 158.952946 -98.669348)
		(width 0.127)
		(layer "In15.Cu")
		(net "PWRGD_P1V8_PCH_AUX")
	)
	(segment
		(start 122.38228 -95.009208)
		(end 121.81332 -95.578168)
		(width 0.127)
		(layer "In15.Cu")
		(net "PWRGD_P1V8_PCH_AUX")
	)
	(segment
		(start 176.50968 -98.379788)
		(end 176.38268 -98.252788)
		(width 0.127)
		(layer "In15.Cu")
		(net "PWRGD_P1V8_PCH_AUX")
	)
	(segment
		(start 126.05131 -94.355158)
		(end 125.39726 -95.009208)
		(width 0.127)
		(layer "In15.Cu")
		(net "PWRGD_P1V8_PCH_AUX")
	)
	(segment
		(start 176.50968 -98.754438)
		(end 176.50968 -98.379788)
		(width 0.127)
		(layer "In15.Cu")
		(net "PWRGD_P1V8_PCH_AUX")
	)
	(segment
		(start 175.002698 -98.174048)
		(end 171.757848 -98.174048)
		(width 0.127)
		(layer "In15.Cu")
		(net "PWRGD_P1V8_PCH_AUX")
	)
	(segment
		(start 260.00456 -73.292208)
		(end 260.00456 -73.086976)
		(width 0.12954)
		(layer "F.Cu")
		(net "PWRGD_P1V05_PCH_AUX_R")
	)
	(segment
		(start 260.00456 -72.841104)
		(end 260.00456 -73.086976)
		(width 0.12954)
		(layer "F.Cu")
		(net "PWRGD_P1V05_PCH_AUX_R")
	)
	(segment
		(start 257.94208 -76.926948)
		(end 258.58724 -76.281788)
		(width 0.12954)
		(layer "F.Cu")
		(net "PWRGD_P1V05_PCH_AUX_R")
	)
	(segment
		(start 258.58724 -76.281788)
		(end 258.58724 -74.709528)
		(width 0.12954)
		(layer "F.Cu")
		(net "PWRGD_P1V05_PCH_AUX_R")
	)
	(segment
		(start 258.58724 -74.709528)
		(end 260.00456 -73.292208)
		(width 0.12954)
		(layer "F.Cu")
		(net "PWRGD_P1V05_PCH_AUX_R")
	)
	(via
		(at 257.94208 -76.926948)
		(size 0.508)
		(drill 0.254)
		(layers "F.Cu" "B.Cu")
		(net "PWRGD_P1V05_PCH_AUX_R")
	)
	(segment
		(start 257.287268 -76.272136)
		(end 257.287268 -75.72883)
		(width 0.12954)
		(layer "B.Cu")
		(net "PWRGD_P1V05_PCH_AUX_R")
	)
	(segment
		(start 256.271268 -75.72883)
		(end 257.287268 -75.72883)
		(width 0.12954)
		(layer "B.Cu")
		(net "PWRGD_P1V05_PCH_AUX_R")
	)
	(segment
		(start 257.94208 -76.926948)
		(end 257.287268 -76.272136)
		(width 0.12954)
		(layer "B.Cu")
		(net "PWRGD_P1V05_PCH_AUX_R")
	)
	(segment
		(start 257.48488 -77.384148)
		(end 257.94208 -76.926948)
		(width 0.12954)
		(layer "B.Cu")
		(net "PWRGD_P1V05_PCH_AUX_R")
	)
	(segment
		(start 257.48488 -78.177898)
		(end 257.48488 -77.384148)
		(width 0.12954)
		(layer "B.Cu")
		(net "PWRGD_P1V05_PCH_AUX_R")
	)
	(segment
		(start 108.966762 -96.317054)
		(end 109.672374 -96.317054)
		(width 0.12954)
		(layer "F.Cu")
		(net "PWRGD_P1V05_PCH_AUX")
	)
	(segment
		(start 176.555654 -116.975382)
		(end 176.155604 -117.375432)
		(width 0.12954)
		(layer "F.Cu")
		(net "PWRGD_P1V05_PCH_AUX")
	)
	(via
		(at 230.15448 -66.358008)
		(size 0.508)
		(drill 0.254)
		(layers "F.Cu" "B.Cu")
		(net "PWRGD_P1V05_PCH_AUX")
	)
	(via
		(at 176.155604 -117.375432)
		(size 0.4572)
		(drill 0.254)
		(layers "F.Cu" "B.Cu")
		(net "PWRGD_P1V05_PCH_AUX")
	)
	(via
		(at 244.506242 -89.063068)
		(size 0.508)
		(drill 0.254)
		(layers "F.Cu" "B.Cu")
		(net "PWRGD_P1V05_PCH_AUX")
	)
	(via
		(at 108.89488 -111.597948)
		(size 0.508)
		(drill 0.254)
		(layers "F.Cu" "B.Cu")
		(net "PWRGD_P1V05_PCH_AUX")
	)
	(via
		(at 109.672374 -96.317054)
		(size 0.508)
		(drill 0.254)
		(layers "F.Cu" "B.Cu")
		(net "PWRGD_P1V05_PCH_AUX")
	)
	(segment
		(start 234.87634 -68.313808)
		(end 240.7412 -68.313808)
		(width 0.12954)
		(layer "B.Cu")
		(net "PWRGD_P1V05_PCH_AUX")
	)
	(segment
		(start 240.7412 -68.313808)
		(end 241.21364 -68.786248)
		(width 0.12954)
		(layer "B.Cu")
		(net "PWRGD_P1V05_PCH_AUX")
	)
	(segment
		(start 257.287268 -74.168)
		(end 257.287268 -74.92873)
		(width 0.12954)
		(layer "B.Cu")
		(net "PWRGD_P1V05_PCH_AUX")
	)
	(segment
		(start 241.21364 -68.786248)
		(end 251.905516 -68.786248)
		(width 0.12954)
		(layer "B.Cu")
		(net "PWRGD_P1V05_PCH_AUX")
	)
	(segment
		(start 230.15448 -66.358008)
		(end 234.87634 -68.313808)
		(width 0.12954)
		(layer "B.Cu")
		(net "PWRGD_P1V05_PCH_AUX")
	)
	(segment
		(start 251.905516 -68.786248)
		(end 257.287268 -74.168)
		(width 0.12954)
		(layer "B.Cu")
		(net "PWRGD_P1V05_PCH_AUX")
	)
	(segment
		(start 244.1702 -88.727026)
		(end 244.506242 -89.063068)
		(width 0.127)
		(layer "In2.Cu")
		(net "PWRGD_P1V05_PCH_AUX")
	)
	(segment
		(start 231.15016 -66.358008)
		(end 242.41633 -77.624178)
		(width 0.127)
		(layer "In2.Cu")
		(net "PWRGD_P1V05_PCH_AUX")
	)
	(segment
		(start 242.41633 -82.488278)
		(end 244.1702 -84.242148)
		(width 0.127)
		(layer "In2.Cu")
		(net "PWRGD_P1V05_PCH_AUX")
	)
	(segment
		(start 242.41633 -77.624178)
		(end 242.41633 -82.488278)
		(width 0.127)
		(layer "In2.Cu")
		(net "PWRGD_P1V05_PCH_AUX")
	)
	(segment
		(start 244.1702 -84.242148)
		(end 244.1702 -88.727026)
		(width 0.127)
		(layer "In2.Cu")
		(net "PWRGD_P1V05_PCH_AUX")
	)
	(segment
		(start 108.89488 -97.094548)
		(end 109.672374 -96.317054)
		(width 0.127)
		(layer "In2.Cu")
		(net "PWRGD_P1V05_PCH_AUX")
	)
	(segment
		(start 108.89488 -111.597948)
		(end 108.89488 -97.094548)
		(width 0.127)
		(layer "In2.Cu")
		(net "PWRGD_P1V05_PCH_AUX")
	)
	(segment
		(start 230.15448 -66.358008)
		(end 231.15016 -66.358008)
		(width 0.127)
		(layer "In2.Cu")
		(net "PWRGD_P1V05_PCH_AUX")
	)
	(segment
		(start 180.06949 -98.768408)
		(end 180.301392 -98.768408)
		(width 0.127)
		(layer "In13.Cu")
		(net "PWRGD_P1V05_PCH_AUX")
	)
	(segment
		(start 176.7586 -108.1786)
		(end 177.170842 -108.1786)
		(width 0.127)
		(layer "In13.Cu")
		(net "PWRGD_P1V05_PCH_AUX")
	)
	(segment
		(start 178.74488 -100.093018)
		(end 180.06949 -98.768408)
		(width 0.127)
		(layer "In13.Cu")
		(net "PWRGD_P1V05_PCH_AUX")
	)
	(segment
		(start 177.170842 -108.1786)
		(end 177.348642 -108.0008)
		(width 0.127)
		(layer "In13.Cu")
		(net "PWRGD_P1V05_PCH_AUX")
	)
	(segment
		(start 184.020968 -97.569528)
		(end 185.245248 -96.345248)
		(width 0.127)
		(layer "In13.Cu")
		(net "PWRGD_P1V05_PCH_AUX")
	)
	(segment
		(start 176.155604 -117.375432)
		(end 176.55794 -116.973096)
		(width 0.127)
		(layer "In13.Cu")
		(net "PWRGD_P1V05_PCH_AUX")
	)
	(segment
		(start 193.550032 -87.831168)
		(end 215.679274 -87.831168)
		(width 0.127)
		(layer "In13.Cu")
		(net "PWRGD_P1V05_PCH_AUX")
	)
	(segment
		(start 220.52534 -92.677234)
		(end 242.59286 -92.677234)
		(width 0.127)
		(layer "In13.Cu")
		(net "PWRGD_P1V05_PCH_AUX")
	)
	(segment
		(start 176.55794 -104.399588)
		(end 176.55794 -102.418388)
		(width 0.127)
		(layer "In13.Cu")
		(net "PWRGD_P1V05_PCH_AUX")
	)
	(segment
		(start 215.679274 -87.831168)
		(end 220.52534 -92.677234)
		(width 0.127)
		(layer "In13.Cu")
		(net "PWRGD_P1V05_PCH_AUX")
	)
	(segment
		(start 177.348642 -108.0008)
		(end 177.348642 -105.19029)
		(width 0.127)
		(layer "In13.Cu")
		(net "PWRGD_P1V05_PCH_AUX")
	)
	(segment
		(start 185.245248 -94.869)
		(end 185.372248 -94.742)
		(width 0.127)
		(layer "In13.Cu")
		(net "PWRGD_P1V05_PCH_AUX")
	)
	(segment
		(start 185.245248 -96.345248)
		(end 185.245248 -94.869)
		(width 0.127)
		(layer "In13.Cu")
		(net "PWRGD_P1V05_PCH_AUX")
	)
	(segment
		(start 177.348642 -105.19029)
		(end 176.55794 -104.399588)
		(width 0.127)
		(layer "In13.Cu")
		(net "PWRGD_P1V05_PCH_AUX")
	)
	(segment
		(start 178.74488 -100.231448)
		(end 178.74488 -100.093018)
		(width 0.127)
		(layer "In13.Cu")
		(net "PWRGD_P1V05_PCH_AUX")
	)
	(segment
		(start 242.59286 -92.677234)
		(end 244.485922 -90.784172)
		(width 0.127)
		(layer "In13.Cu")
		(net "PWRGD_P1V05_PCH_AUX")
	)
	(segment
		(start 176.55794 -108.37926)
		(end 176.7586 -108.1786)
		(width 0.127)
		(layer "In13.Cu")
		(net "PWRGD_P1V05_PCH_AUX")
	)
	(segment
		(start 186.6392 -94.742)
		(end 193.550032 -87.831168)
		(width 0.127)
		(layer "In13.Cu")
		(net "PWRGD_P1V05_PCH_AUX")
	)
	(segment
		(start 244.485922 -90.784172)
		(end 244.485922 -89.083388)
		(width 0.127)
		(layer "In13.Cu")
		(net "PWRGD_P1V05_PCH_AUX")
	)
	(segment
		(start 181.500272 -97.569528)
		(end 184.020968 -97.569528)
		(width 0.127)
		(layer "In13.Cu")
		(net "PWRGD_P1V05_PCH_AUX")
	)
	(segment
		(start 180.301392 -98.768408)
		(end 181.500272 -97.569528)
		(width 0.127)
		(layer "In13.Cu")
		(net "PWRGD_P1V05_PCH_AUX")
	)
	(segment
		(start 185.372248 -94.742)
		(end 186.6392 -94.742)
		(width 0.127)
		(layer "In13.Cu")
		(net "PWRGD_P1V05_PCH_AUX")
	)
	(segment
		(start 176.55794 -102.418388)
		(end 178.74488 -100.231448)
		(width 0.127)
		(layer "In13.Cu")
		(net "PWRGD_P1V05_PCH_AUX")
	)
	(segment
		(start 244.485922 -89.083388)
		(end 244.506242 -89.063068)
		(width 0.127)
		(layer "In13.Cu")
		(net "PWRGD_P1V05_PCH_AUX")
	)
	(segment
		(start 176.55794 -116.973096)
		(end 176.55794 -108.37926)
		(width 0.127)
		(layer "In13.Cu")
		(net "PWRGD_P1V05_PCH_AUX")
	)
	(segment
		(start 110.08868 -112.791748)
		(end 131.012692 -112.791748)
		(width 0.127)
		(layer "In15.Cu")
		(net "PWRGD_P1V05_PCH_AUX")
	)
	(segment
		(start 145.48612 -114.14506)
		(end 145.98142 -113.64976)
		(width 0.127)
		(layer "In15.Cu")
		(net "PWRGD_P1V05_PCH_AUX")
	)
	(segment
		(start 149.1615 -118.532402)
		(end 151.00808 -120.378982)
		(width 0.127)
		(layer "In15.Cu")
		(net "PWRGD_P1V05_PCH_AUX")
	)
	(segment
		(start 131.97332 -111.83112)
		(end 136.054592 -111.83112)
		(width 0.127)
		(layer "In15.Cu")
		(net "PWRGD_P1V05_PCH_AUX")
	)
	(segment
		(start 136.054592 -111.83112)
		(end 137.54862 -113.325148)
		(width 0.127)
		(layer "In15.Cu")
		(net "PWRGD_P1V05_PCH_AUX")
	)
	(segment
		(start 149.1615 -116.02974)
		(end 149.1615 -118.532402)
		(width 0.127)
		(layer "In15.Cu")
		(net "PWRGD_P1V05_PCH_AUX")
	)
	(segment
		(start 160.097216 -124.9172)
		(end 163.364418 -124.9172)
		(width 0.127)
		(layer "In15.Cu")
		(net "PWRGD_P1V05_PCH_AUX")
	)
	(segment
		(start 146.78152 -113.64976)
		(end 149.1615 -116.02974)
		(width 0.127)
		(layer "In15.Cu")
		(net "PWRGD_P1V05_PCH_AUX")
	)
	(segment
		(start 175.75784 -116.977668)
		(end 176.155604 -117.375432)
		(width 0.127)
		(layer "In15.Cu")
		(net "PWRGD_P1V05_PCH_AUX")
	)
	(segment
		(start 145.98142 -113.64976)
		(end 146.78152 -113.64976)
		(width 0.127)
		(layer "In15.Cu")
		(net "PWRGD_P1V05_PCH_AUX")
	)
	(segment
		(start 164.33927 -123.942348)
		(end 164.366448 -123.942348)
		(width 0.127)
		(layer "In15.Cu")
		(net "PWRGD_P1V05_PCH_AUX")
	)
	(segment
		(start 131.012692 -112.791748)
		(end 131.97332 -111.83112)
		(width 0.127)
		(layer "In15.Cu")
		(net "PWRGD_P1V05_PCH_AUX")
	)
	(segment
		(start 171.75988 -118.377208)
		(end 171.75988 -117.173248)
		(width 0.127)
		(layer "In15.Cu")
		(net "PWRGD_P1V05_PCH_AUX")
	)
	(segment
		(start 163.364418 -124.9172)
		(end 164.33927 -123.942348)
		(width 0.127)
		(layer "In15.Cu")
		(net "PWRGD_P1V05_PCH_AUX")
	)
	(segment
		(start 151.00808 -120.378982)
		(end 152.41016 -120.378982)
		(width 0.127)
		(layer "In15.Cu")
		(net "PWRGD_P1V05_PCH_AUX")
	)
	(segment
		(start 171.95546 -116.977668)
		(end 175.75784 -116.977668)
		(width 0.127)
		(layer "In15.Cu")
		(net "PWRGD_P1V05_PCH_AUX")
	)
	(segment
		(start 170.1038 -119.73052)
		(end 170.406568 -119.73052)
		(width 0.127)
		(layer "In15.Cu")
		(net "PWRGD_P1V05_PCH_AUX")
	)
	(segment
		(start 144.8181 -114.14506)
		(end 145.48612 -114.14506)
		(width 0.127)
		(layer "In15.Cu")
		(net "PWRGD_P1V05_PCH_AUX")
	)
	(segment
		(start 137.54862 -113.325148)
		(end 143.998188 -113.325148)
		(width 0.127)
		(layer "In15.Cu")
		(net "PWRGD_P1V05_PCH_AUX")
	)
	(segment
		(start 159.716216 -125.2982)
		(end 160.097216 -124.9172)
		(width 0.127)
		(layer "In15.Cu")
		(net "PWRGD_P1V05_PCH_AUX")
	)
	(segment
		(start 167.948356 -120.36044)
		(end 169.47388 -120.36044)
		(width 0.127)
		(layer "In15.Cu")
		(net "PWRGD_P1V05_PCH_AUX")
	)
	(segment
		(start 157.329378 -125.2982)
		(end 159.716216 -125.2982)
		(width 0.127)
		(layer "In15.Cu")
		(net "PWRGD_P1V05_PCH_AUX")
	)
	(segment
		(start 171.75988 -117.173248)
		(end 171.95546 -116.977668)
		(width 0.127)
		(layer "In15.Cu")
		(net "PWRGD_P1V05_PCH_AUX")
	)
	(segment
		(start 164.366448 -123.942348)
		(end 167.948356 -120.36044)
		(width 0.127)
		(layer "In15.Cu")
		(net "PWRGD_P1V05_PCH_AUX")
	)
	(segment
		(start 143.998188 -113.325148)
		(end 144.8181 -114.14506)
		(width 0.127)
		(layer "In15.Cu")
		(net "PWRGD_P1V05_PCH_AUX")
	)
	(segment
		(start 169.47388 -120.36044)
		(end 170.1038 -119.73052)
		(width 0.127)
		(layer "In15.Cu")
		(net "PWRGD_P1V05_PCH_AUX")
	)
	(segment
		(start 152.41016 -120.378982)
		(end 157.329378 -125.2982)
		(width 0.127)
		(layer "In15.Cu")
		(net "PWRGD_P1V05_PCH_AUX")
	)
	(segment
		(start 170.406568 -119.73052)
		(end 171.75988 -118.377208)
		(width 0.127)
		(layer "In15.Cu")
		(net "PWRGD_P1V05_PCH_AUX")
	)
	(segment
		(start 108.89488 -111.597948)
		(end 110.08868 -112.791748)
		(width 0.127)
		(layer "In15.Cu")
		(net "PWRGD_P1V05_PCH_AUX")
	)
	(via
		(at 214.69096 -315.562488)
		(size 0.6604)
		(drill 0.3302)
		(layers "F.Cu" "B.Cu")
		(net "PWRGD_FAIL_CPU1_GH_R1")
	)
	(segment
		(start 213.525354 -314.950094)
		(end 213.548722 -314.926726)
		(width 0.12954)
		(layer "B.Cu")
		(net "PWRGD_FAIL_CPU1_GH_R1")
	)
	(segment
		(start 214.055198 -314.926726)
		(end 214.69096 -315.562488)
		(width 0.12954)
		(layer "B.Cu")
		(net "PWRGD_FAIL_CPU1_GH_R1")
	)
	(segment
		(start 214.863426 -315.734954)
		(end 215.840818 -315.734954)
		(width 0.12954)
		(layer "B.Cu")
		(net "PWRGD_FAIL_CPU1_GH_R1")
	)
	(segment
		(start 213.060026 -314.950094)
		(end 211.634578 -314.950094)
		(width 0.12954)
		(layer "B.Cu")
		(net "PWRGD_FAIL_CPU1_GH_R1")
	)
	(segment
		(start 213.548722 -314.926726)
		(end 214.055198 -314.926726)
		(width 0.12954)
		(layer "B.Cu")
		(net "PWRGD_FAIL_CPU1_GH_R1")
	)
	(segment
		(start 215.840818 -316.66561)
		(end 215.840818 -315.734954)
		(width 0.12954)
		(layer "B.Cu")
		(net "PWRGD_FAIL_CPU1_GH_R1")
	)
	(segment
		(start 213.525354 -314.950094)
		(end 213.501986 -314.926726)
		(width 0.12954)
		(layer "B.Cu")
		(net "PWRGD_FAIL_CPU1_GH_R1")
	)
	(segment
		(start 213.501986 -314.926726)
		(end 213.083394 -314.926726)
		(width 0.12954)
		(layer "B.Cu")
		(net "PWRGD_FAIL_CPU1_GH_R1")
	)
	(segment
		(start 213.083394 -314.926726)
		(end 213.060026 -314.950094)
		(width 0.12954)
		(layer "B.Cu")
		(net "PWRGD_FAIL_CPU1_GH_R1")
	)
	(segment
		(start 214.69096 -315.562488)
		(end 214.863426 -315.734954)
		(width 0.12954)
		(layer "B.Cu")
		(net "PWRGD_FAIL_CPU1_GH_R1")
	)
	(segment
		(start 182.155592 -119.375428)
		(end 182.555642 -119.775478)
		(width 0.12954)
		(layer "F.Cu")
		(net "PWRGD_FAIL_CPU1_GH_R")
	)
	(via
		(at 213.576154 -312.369708)
		(size 0.6604)
		(drill 0.3302)
		(layers "F.Cu" "B.Cu")
		(net "PWRGD_FAIL_CPU1_GH_R")
	)
	(via
		(at 193.690748 -189.596776)
		(size 0.508)
		(drill 0.254)
		(layers "F.Cu" "B.Cu")
		(net "PWRGD_FAIL_CPU1_GH_R")
	)
	(via
		(at 182.555642 -119.775478)
		(size 0.4572)
		(drill 0.254)
		(layers "F.Cu" "B.Cu")
		(net "PWRGD_FAIL_CPU1_GH_R")
	)
	(segment
		(start 213.576154 -313.678316)
		(end 213.525354 -313.729116)
		(width 0.12954)
		(layer "B.Cu")
		(net "PWRGD_FAIL_CPU1_GH_R")
	)
	(segment
		(start 193.690748 -189.596776)
		(end 193.690748 -190.308738)
		(width 0.12954)
		(layer "B.Cu")
		(net "PWRGD_FAIL_CPU1_GH_R")
	)
	(segment
		(start 193.148458 -190.851028)
		(end 193.148458 -255.48463)
		(width 0.12954)
		(layer "B.Cu")
		(net "PWRGD_FAIL_CPU1_GH_R")
	)
	(segment
		(start 213.576154 -312.369708)
		(end 213.576154 -313.678316)
		(width 0.12954)
		(layer "B.Cu")
		(net "PWRGD_FAIL_CPU1_GH_R")
	)
	(segment
		(start 212.726778 -257.04673)
		(end 213.576154 -257.896106)
		(width 0.12954)
		(layer "B.Cu")
		(net "PWRGD_FAIL_CPU1_GH_R")
	)
	(segment
		(start 193.690748 -190.308738)
		(end 193.148458 -190.851028)
		(width 0.12954)
		(layer "B.Cu")
		(net "PWRGD_FAIL_CPU1_GH_R")
	)
	(segment
		(start 194.710558 -257.04673)
		(end 212.726778 -257.04673)
		(width 0.12954)
		(layer "B.Cu")
		(net "PWRGD_FAIL_CPU1_GH_R")
	)
	(segment
		(start 193.148458 -255.48463)
		(end 194.710558 -257.04673)
		(width 0.12954)
		(layer "B.Cu")
		(net "PWRGD_FAIL_CPU1_GH_R")
	)
	(segment
		(start 213.525354 -313.729116)
		(end 213.525354 -314.149994)
		(width 0.12954)
		(layer "B.Cu")
		(net "PWRGD_FAIL_CPU1_GH_R")
	)
	(segment
		(start 213.576154 -257.896106)
		(end 213.576154 -312.369708)
		(width 0.12954)
		(layer "B.Cu")
		(net "PWRGD_FAIL_CPU1_GH_R")
	)
	(segment
		(start 200.059036 -148.681948)
		(end 199.228964 -148.338032)
		(width 0.127)
		(layer "In2.Cu")
		(net "PWRGD_FAIL_CPU1_GH_R")
	)
	(segment
		(start 201.9173 -187.236608)
		(end 208.32572 -180.828188)
		(width 0.127)
		(layer "In2.Cu")
		(net "PWRGD_FAIL_CPU1_GH_R")
	)
	(segment
		(start 182.73141 -119.775478)
		(end 182.555642 -119.775478)
		(width 0.127)
		(layer "In2.Cu")
		(net "PWRGD_FAIL_CPU1_GH_R")
	)
	(segment
		(start 183.7563 -120.399048)
		(end 183.53532 -120.178068)
		(width 0.127)
		(layer "In2.Cu")
		(net "PWRGD_FAIL_CPU1_GH_R")
	)
	(segment
		(start 183.134 -120.178068)
		(end 182.73141 -119.775478)
		(width 0.127)
		(layer "In2.Cu")
		(net "PWRGD_FAIL_CPU1_GH_R")
	)
	(segment
		(start 199.228964 -148.338032)
		(end 189.78372 -138.892788)
		(width 0.127)
		(layer "In2.Cu")
		(net "PWRGD_FAIL_CPU1_GH_R")
	)
	(segment
		(start 207.31226 -158.209488)
		(end 201.628248 -158.209488)
		(width 0.127)
		(layer "In2.Cu")
		(net "PWRGD_FAIL_CPU1_GH_R")
	)
	(segment
		(start 208.32572 -180.828188)
		(end 208.32572 -159.222948)
		(width 0.127)
		(layer "In2.Cu")
		(net "PWRGD_FAIL_CPU1_GH_R")
	)
	(segment
		(start 183.53532 -120.178068)
		(end 183.134 -120.178068)
		(width 0.127)
		(layer "In2.Cu")
		(net "PWRGD_FAIL_CPU1_GH_R")
	)
	(segment
		(start 188.65088 -129.675128)
		(end 188.65088 -126.683008)
		(width 0.127)
		(layer "In2.Cu")
		(net "PWRGD_FAIL_CPU1_GH_R")
	)
	(segment
		(start 201.9173 -189.301628)
		(end 201.9173 -187.236608)
		(width 0.127)
		(layer "In2.Cu")
		(net "PWRGD_FAIL_CPU1_GH_R")
	)
	(segment
		(start 200.524618 -153.19121)
		(end 202.16368 -151.552148)
		(width 0.127)
		(layer "In2.Cu")
		(net "PWRGD_FAIL_CPU1_GH_R")
	)
	(segment
		(start 184.577228 -122.609356)
		(end 184.577228 -121.895616)
		(width 0.127)
		(layer "In2.Cu")
		(net "PWRGD_FAIL_CPU1_GH_R")
	)
	(segment
		(start 194.54114 -190.447168)
		(end 200.77176 -190.447168)
		(width 0.127)
		(layer "In2.Cu")
		(net "PWRGD_FAIL_CPU1_GH_R")
	)
	(segment
		(start 183.7563 -121.615708)
		(end 183.7563 -120.399048)
		(width 0.127)
		(layer "In2.Cu")
		(net "PWRGD_FAIL_CPU1_GH_R")
	)
	(segment
		(start 202.16368 -149.748748)
		(end 201.09688 -148.681948)
		(width 0.127)
		(layer "In2.Cu")
		(net "PWRGD_FAIL_CPU1_GH_R")
	)
	(segment
		(start 201.09688 -148.681948)
		(end 200.059036 -148.681948)
		(width 0.127)
		(layer "In2.Cu")
		(net "PWRGD_FAIL_CPU1_GH_R")
	)
	(segment
		(start 193.690748 -189.596776)
		(end 194.54114 -190.447168)
		(width 0.127)
		(layer "In2.Cu")
		(net "PWRGD_FAIL_CPU1_GH_R")
	)
	(segment
		(start 201.628248 -158.209488)
		(end 200.524618 -157.105858)
		(width 0.127)
		(layer "In2.Cu")
		(net "PWRGD_FAIL_CPU1_GH_R")
	)
	(segment
		(start 188.65088 -126.683008)
		(end 184.577228 -122.609356)
		(width 0.127)
		(layer "In2.Cu")
		(net "PWRGD_FAIL_CPU1_GH_R")
	)
	(segment
		(start 184.577228 -121.895616)
		(end 184.45226 -121.770648)
		(width 0.127)
		(layer "In2.Cu")
		(net "PWRGD_FAIL_CPU1_GH_R")
	)
	(segment
		(start 189.78372 -138.892788)
		(end 189.78372 -130.807968)
		(width 0.127)
		(layer "In2.Cu")
		(net "PWRGD_FAIL_CPU1_GH_R")
	)
	(segment
		(start 183.91124 -121.770648)
		(end 183.7563 -121.615708)
		(width 0.127)
		(layer "In2.Cu")
		(net "PWRGD_FAIL_CPU1_GH_R")
	)
	(segment
		(start 208.32572 -159.222948)
		(end 207.31226 -158.209488)
		(width 0.127)
		(layer "In2.Cu")
		(net "PWRGD_FAIL_CPU1_GH_R")
	)
	(segment
		(start 200.77176 -190.447168)
		(end 201.9173 -189.301628)
		(width 0.127)
		(layer "In2.Cu")
		(net "PWRGD_FAIL_CPU1_GH_R")
	)
	(segment
		(start 200.524618 -157.105858)
		(end 200.524618 -153.19121)
		(width 0.127)
		(layer "In2.Cu")
		(net "PWRGD_FAIL_CPU1_GH_R")
	)
	(segment
		(start 189.78372 -130.807968)
		(end 188.65088 -129.675128)
		(width 0.127)
		(layer "In2.Cu")
		(net "PWRGD_FAIL_CPU1_GH_R")
	)
	(segment
		(start 202.16368 -151.552148)
		(end 202.16368 -149.748748)
		(width 0.127)
		(layer "In2.Cu")
		(net "PWRGD_FAIL_CPU1_GH_R")
	)
	(segment
		(start 184.45226 -121.770648)
		(end 183.91124 -121.770648)
		(width 0.127)
		(layer "In2.Cu")
		(net "PWRGD_FAIL_CPU1_GH_R")
	)
	(via
		(at 203.69149 -318.06261)
		(size 0.6604)
		(drill 0.3302)
		(layers "F.Cu" "B.Cu")
		(net "PWRGD_FAIL_CPU1_GH")
	)
	(segment
		(start 196.239384 -318.590168)
		(end 195.82638 -318.590168)
		(width 0.12954)
		(layer "B.Cu")
		(net "PWRGD_FAIL_CPU1_GH")
	)
	(segment
		(start 215.029288 -317.54445)
		(end 215.206834 -317.721996)
		(width 0.12954)
		(layer "B.Cu")
		(net "PWRGD_FAIL_CPU1_GH")
	)
	(segment
		(start 210.984338 -318.167258)
		(end 210.984338 -316.597792)
		(width 0.12954)
		(layer "B.Cu")
		(net "PWRGD_FAIL_CPU1_GH")
	)
	(segment
		(start 201.937112 -319.446148)
		(end 202.307952 -319.446148)
		(width 0.12954)
		(layer "B.Cu")
		(net "PWRGD_FAIL_CPU1_GH")
	)
	(segment
		(start 195.82638 -318.590168)
		(end 194.92976 -319.486788)
		(width 0.12954)
		(layer "B.Cu")
		(net "PWRGD_FAIL_CPU1_GH")
	)
	(segment
		(start 212.907118 -316.42939)
		(end 213.178898 -316.70117)
		(width 0.12954)
		(layer "B.Cu")
		(net "PWRGD_FAIL_CPU1_GH")
	)
	(segment
		(start 208.56829 -318.535812)
		(end 208.56829 -319.514982)
		(width 0.12954)
		(layer "B.Cu")
		(net "PWRGD_FAIL_CPU1_GH")
	)
	(segment
		(start 207.66278 -318.241426)
		(end 207.250284 -317.82893)
		(width 0.12954)
		(layer "B.Cu")
		(net "PWRGD_FAIL_CPU1_GH")
	)
	(segment
		(start 194.385946 -319.486788)
		(end 194.322446 -319.423288)
		(width 0.12954)
		(layer "B.Cu")
		(net "PWRGD_FAIL_CPU1_GH")
	)
	(segment
		(start 215.206834 -317.721996)
		(end 215.206834 -318.426592)
		(width 0.12954)
		(layer "B.Cu")
		(net "PWRGD_FAIL_CPU1_GH")
	)
	(segment
		(start 208.133442 -318.247014)
		(end 208.279492 -318.247014)
		(width 0.12954)
		(layer "B.Cu")
		(net "PWRGD_FAIL_CPU1_GH")
	)
	(segment
		(start 203.92517 -317.82893)
		(end 203.69149 -318.06261)
		(width 0.12954)
		(layer "B.Cu")
		(net "PWRGD_FAIL_CPU1_GH")
	)
	(segment
		(start 215.840818 -318.297052)
		(end 215.711278 -318.426592)
		(width 0.12954)
		(layer "B.Cu")
		(net "PWRGD_FAIL_CPU1_GH")
	)
	(segment
		(start 207.250284 -317.82893)
		(end 203.92517 -317.82893)
		(width 0.12954)
		(layer "B.Cu")
		(net "PWRGD_FAIL_CPU1_GH")
	)
	(segment
		(start 194.322446 -319.423288)
		(end 193.901568 -319.423288)
		(width 0.12954)
		(layer "B.Cu")
		(net "PWRGD_FAIL_CPU1_GH")
	)
	(segment
		(start 201.08799 -318.597026)
		(end 201.937112 -319.446148)
		(width 0.12954)
		(layer "B.Cu")
		(net "PWRGD_FAIL_CPU1_GH")
	)
	(segment
		(start 200.64603 -318.62014)
		(end 200.622916 -318.597026)
		(width 0.12954)
		(layer "B.Cu")
		(net "PWRGD_FAIL_CPU1_GH")
	)
	(segment
		(start 208.279492 -318.247014)
		(end 208.56829 -318.535812)
		(width 0.12954)
		(layer "B.Cu")
		(net "PWRGD_FAIL_CPU1_GH")
	)
	(segment
		(start 200.622916 -318.597026)
		(end 200.337166 -318.597026)
		(width 0.12954)
		(layer "B.Cu")
		(net "PWRGD_FAIL_CPU1_GH")
	)
	(segment
		(start 210.984338 -316.597792)
		(end 211.15274 -316.42939)
		(width 0.12954)
		(layer "B.Cu")
		(net "PWRGD_FAIL_CPU1_GH")
	)
	(segment
		(start 202.307952 -319.446148)
		(end 203.69149 -318.06261)
		(width 0.12954)
		(layer "B.Cu")
		(net "PWRGD_FAIL_CPU1_GH")
	)
	(segment
		(start 208.127854 -318.241426)
		(end 208.133442 -318.247014)
		(width 0.12954)
		(layer "B.Cu")
		(net "PWRGD_FAIL_CPU1_GH")
	)
	(segment
		(start 199.476868 -317.736728)
		(end 197.092824 -317.736728)
		(width 0.12954)
		(layer "B.Cu")
		(net "PWRGD_FAIL_CPU1_GH")
	)
	(segment
		(start 213.665562 -317.54445)
		(end 215.029288 -317.54445)
		(width 0.12954)
		(layer "B.Cu")
		(net "PWRGD_FAIL_CPU1_GH")
	)
	(segment
		(start 213.178898 -316.70117)
		(end 213.178898 -317.057786)
		(width 0.12954)
		(layer "B.Cu")
		(net "PWRGD_FAIL_CPU1_GH")
	)
	(segment
		(start 215.840818 -317.46571)
		(end 215.840818 -318.297052)
		(width 0.12954)
		(layer "B.Cu")
		(net "PWRGD_FAIL_CPU1_GH")
	)
	(segment
		(start 201.064876 -318.62014)
		(end 200.64603 -318.62014)
		(width 0.12954)
		(layer "B.Cu")
		(net "PWRGD_FAIL_CPU1_GH")
	)
	(segment
		(start 194.92976 -319.486788)
		(end 194.385946 -319.486788)
		(width 0.12954)
		(layer "B.Cu")
		(net "PWRGD_FAIL_CPU1_GH")
	)
	(segment
		(start 208.56829 -319.514982)
		(end 208.720436 -319.667128)
		(width 0.12954)
		(layer "B.Cu")
		(net "PWRGD_FAIL_CPU1_GH")
	)
	(segment
		(start 211.15274 -316.42939)
		(end 212.907118 -316.42939)
		(width 0.12954)
		(layer "B.Cu")
		(net "PWRGD_FAIL_CPU1_GH")
	)
	(segment
		(start 215.711278 -318.426592)
		(end 215.206834 -318.426592)
		(width 0.12954)
		(layer "B.Cu")
		(net "PWRGD_FAIL_CPU1_GH")
	)
	(segment
		(start 208.127854 -318.241426)
		(end 207.66278 -318.241426)
		(width 0.12954)
		(layer "B.Cu")
		(net "PWRGD_FAIL_CPU1_GH")
	)
	(segment
		(start 210.589622 -318.561974)
		(end 210.984338 -318.167258)
		(width 0.12954)
		(layer "B.Cu")
		(net "PWRGD_FAIL_CPU1_GH")
	)
	(segment
		(start 197.092824 -317.736728)
		(end 196.239384 -318.590168)
		(width 0.12954)
		(layer "B.Cu")
		(net "PWRGD_FAIL_CPU1_GH")
	)
	(segment
		(start 200.337166 -318.597026)
		(end 199.476868 -317.736728)
		(width 0.12954)
		(layer "B.Cu")
		(net "PWRGD_FAIL_CPU1_GH")
	)
	(segment
		(start 213.178898 -317.057786)
		(end 213.665562 -317.54445)
		(width 0.12954)
		(layer "B.Cu")
		(net "PWRGD_FAIL_CPU1_GH")
	)
	(segment
		(start 201.08799 -318.597026)
		(end 201.064876 -318.62014)
		(width 0.12954)
		(layer "B.Cu")
		(net "PWRGD_FAIL_CPU1_GH")
	)
	(segment
		(start 209.731356 -319.667128)
		(end 210.589622 -318.808862)
		(width 0.12954)
		(layer "B.Cu")
		(net "PWRGD_FAIL_CPU1_GH")
	)
	(segment
		(start 210.589622 -318.808862)
		(end 210.589622 -318.561974)
		(width 0.12954)
		(layer "B.Cu")
		(net "PWRGD_FAIL_CPU1_GH")
	)
	(segment
		(start 208.720436 -319.667128)
		(end 209.731356 -319.667128)
		(width 0.12954)
		(layer "B.Cu")
		(net "PWRGD_FAIL_CPU1_GH")
	)
	(via
		(at 183.8579 -313.916568)
		(size 0.6604)
		(drill 0.3302)
		(layers "F.Cu" "B.Cu")
		(net "PWRGD_FAIL_CPU1_EF_R1")
	)
	(segment
		(start 184.95899 -315.458602)
		(end 184.168542 -315.458602)
		(width 0.12954)
		(layer "B.Cu")
		(net "PWRGD_FAIL_CPU1_EF_R1")
	)
	(segment
		(start 185.955178 -317.40475)
		(end 185.293 -316.742572)
		(width 0.12954)
		(layer "B.Cu")
		(net "PWRGD_FAIL_CPU1_EF_R1")
	)
	(segment
		(start 185.955178 -318.2747)
		(end 185.955178 -317.40475)
		(width 0.12954)
		(layer "B.Cu")
		(net "PWRGD_FAIL_CPU1_EF_R1")
	)
	(segment
		(start 183.8579 -315.14796)
		(end 183.8579 -313.916568)
		(width 0.12954)
		(layer "B.Cu")
		(net "PWRGD_FAIL_CPU1_EF_R1")
	)
	(segment
		(start 186.30392 -318.623442)
		(end 185.955178 -318.2747)
		(width 0.12954)
		(layer "B.Cu")
		(net "PWRGD_FAIL_CPU1_EF_R1")
	)
	(segment
		(start 183.8579 -313.916568)
		(end 184.391554 -313.382914)
		(width 0.12954)
		(layer "B.Cu")
		(net "PWRGD_FAIL_CPU1_EF_R1")
	)
	(segment
		(start 185.293 -316.742572)
		(end 185.293 -315.792612)
		(width 0.12954)
		(layer "B.Cu")
		(net "PWRGD_FAIL_CPU1_EF_R1")
	)
	(segment
		(start 186.45886 -318.623442)
		(end 186.30392 -318.623442)
		(width 0.12954)
		(layer "B.Cu")
		(net "PWRGD_FAIL_CPU1_EF_R1")
	)
	(segment
		(start 184.391554 -313.382914)
		(end 185.691526 -313.382914)
		(width 0.12954)
		(layer "B.Cu")
		(net "PWRGD_FAIL_CPU1_EF_R1")
	)
	(segment
		(start 186.464194 -318.628776)
		(end 186.45886 -318.623442)
		(width 0.12954)
		(layer "B.Cu")
		(net "PWRGD_FAIL_CPU1_EF_R1")
	)
	(segment
		(start 185.293 -315.792612)
		(end 184.95899 -315.458602)
		(width 0.12954)
		(layer "B.Cu")
		(net "PWRGD_FAIL_CPU1_EF_R1")
	)
	(segment
		(start 184.168542 -315.458602)
		(end 183.8579 -315.14796)
		(width 0.12954)
		(layer "B.Cu")
		(net "PWRGD_FAIL_CPU1_EF_R1")
	)
	(segment
		(start 182.155592 -120.175528)
		(end 182.555642 -120.575578)
		(width 0.12954)
		(layer "F.Cu")
		(net "PWRGD_FAIL_CPU1_EF_R")
	)
	(via
		(at 185.645806 -189.695836)
		(size 0.508)
		(drill 0.254)
		(layers "F.Cu" "B.Cu")
		(net "PWRGD_FAIL_CPU1_EF_R")
	)
	(via
		(at 183.651398 -265.50239)
		(size 0.6604)
		(drill 0.3302)
		(layers "F.Cu" "B.Cu")
		(net "PWRGD_FAIL_CPU1_EF_R")
	)
	(via
		(at 182.555642 -120.575578)
		(size 0.4572)
		(drill 0.254)
		(layers "F.Cu" "B.Cu")
		(net "PWRGD_FAIL_CPU1_EF_R")
	)
	(segment
		(start 185.195718 -256.01803)
		(end 183.651398 -257.56235)
		(width 0.12954)
		(layer "B.Cu")
		(net "PWRGD_FAIL_CPU1_EF_R")
	)
	(segment
		(start 183.651398 -194.65925)
		(end 183.651398 -245.79961)
		(width 0.12954)
		(layer "B.Cu")
		(net "PWRGD_FAIL_CPU1_EF_R")
	)
	(segment
		(start 184.464198 -191.55029)
		(end 184.464198 -193.84645)
		(width 0.12954)
		(layer "B.Cu")
		(net "PWRGD_FAIL_CPU1_EF_R")
	)
	(segment
		(start 185.645806 -189.695836)
		(end 185.645806 -190.368682)
		(width 0.12954)
		(layer "B.Cu")
		(net "PWRGD_FAIL_CPU1_EF_R")
	)
	(segment
		(start 183.651398 -257.56235)
		(end 183.651398 -265.50239)
		(width 0.12954)
		(layer "B.Cu")
		(net "PWRGD_FAIL_CPU1_EF_R")
	)
	(segment
		(start 183.651398 -269.60449)
		(end 185.668158 -271.62125)
		(width 0.12954)
		(layer "B.Cu")
		(net "PWRGD_FAIL_CPU1_EF_R")
	)
	(segment
		(start 184.464198 -193.84645)
		(end 183.651398 -194.65925)
		(width 0.12954)
		(layer "B.Cu")
		(net "PWRGD_FAIL_CPU1_EF_R")
	)
	(segment
		(start 185.645806 -190.368682)
		(end 184.464198 -191.55029)
		(width 0.12954)
		(layer "B.Cu")
		(net "PWRGD_FAIL_CPU1_EF_R")
	)
	(segment
		(start 183.651398 -265.50239)
		(end 183.651398 -269.60449)
		(width 0.12954)
		(layer "B.Cu")
		(net "PWRGD_FAIL_CPU1_EF_R")
	)
	(segment
		(start 183.651398 -245.79961)
		(end 185.195718 -247.34393)
		(width 0.12954)
		(layer "B.Cu")
		(net "PWRGD_FAIL_CPU1_EF_R")
	)
	(segment
		(start 185.195718 -247.34393)
		(end 185.195718 -256.01803)
		(width 0.12954)
		(layer "B.Cu")
		(net "PWRGD_FAIL_CPU1_EF_R")
	)
	(segment
		(start 185.668158 -271.62125)
		(end 185.668158 -312.559446)
		(width 0.12954)
		(layer "B.Cu")
		(net "PWRGD_FAIL_CPU1_EF_R")
	)
	(segment
		(start 185.668158 -312.559446)
		(end 185.691526 -312.582814)
		(width 0.12954)
		(layer "B.Cu")
		(net "PWRGD_FAIL_CPU1_EF_R")
	)
	(segment
		(start 180.85816 -151.897588)
		(end 180.85816 -159.512508)
		(width 0.127)
		(layer "In11.Cu")
		(net "PWRGD_FAIL_CPU1_EF_R")
	)
	(segment
		(start 182.9562 -126.284228)
		(end 181.18201 -128.058418)
		(width 0.127)
		(layer "In11.Cu")
		(net "PWRGD_FAIL_CPU1_EF_R")
	)
	(segment
		(start 179.85994 -150.899368)
		(end 180.85816 -151.897588)
		(width 0.127)
		(layer "In11.Cu")
		(net "PWRGD_FAIL_CPU1_EF_R")
	)
	(segment
		(start 182.57012 -161.224468)
		(end 183.36768 -161.224468)
		(width 0.127)
		(layer "In11.Cu")
		(net "PWRGD_FAIL_CPU1_EF_R")
	)
	(segment
		(start 181.18201 -138.770868)
		(end 179.85994 -140.092938)
		(width 0.127)
		(layer "In11.Cu")
		(net "PWRGD_FAIL_CPU1_EF_R")
	)
	(segment
		(start 185.645806 -188.351414)
		(end 185.645806 -189.695836)
		(width 0.127)
		(layer "In11.Cu")
		(net "PWRGD_FAIL_CPU1_EF_R")
	)
	(segment
		(start 179.85994 -140.092938)
		(end 179.85994 -150.899368)
		(width 0.127)
		(layer "In11.Cu")
		(net "PWRGD_FAIL_CPU1_EF_R")
	)
	(segment
		(start 183.36768 -161.224468)
		(end 184.26938 -162.126168)
		(width 0.127)
		(layer "In11.Cu")
		(net "PWRGD_FAIL_CPU1_EF_R")
	)
	(segment
		(start 182.9562 -120.976136)
		(end 182.9562 -126.284228)
		(width 0.127)
		(layer "In11.Cu")
		(net "PWRGD_FAIL_CPU1_EF_R")
	)
	(segment
		(start 184.26938 -162.126168)
		(end 184.26938 -186.974988)
		(width 0.127)
		(layer "In11.Cu")
		(net "PWRGD_FAIL_CPU1_EF_R")
	)
	(segment
		(start 180.85816 -159.512508)
		(end 182.57012 -161.224468)
		(width 0.127)
		(layer "In11.Cu")
		(net "PWRGD_FAIL_CPU1_EF_R")
	)
	(segment
		(start 184.26938 -186.974988)
		(end 185.645806 -188.351414)
		(width 0.127)
		(layer "In11.Cu")
		(net "PWRGD_FAIL_CPU1_EF_R")
	)
	(segment
		(start 181.18201 -128.058418)
		(end 181.18201 -138.770868)
		(width 0.127)
		(layer "In11.Cu")
		(net "PWRGD_FAIL_CPU1_EF_R")
	)
	(segment
		(start 182.555642 -120.575578)
		(end 182.9562 -120.976136)
		(width 0.127)
		(layer "In11.Cu")
		(net "PWRGD_FAIL_CPU1_EF_R")
	)
	(via
		(at 172.385482 -318.619632)
		(size 0.6604)
		(drill 0.3302)
		(layers "F.Cu" "B.Cu")
		(net "PWRGD_FAIL_CPU1_EF")
	)
	(segment
		(start 178.323748 -318.622426)
		(end 178.323748 -318.0969)
		(width 0.12954)
		(layer "B.Cu")
		(net "PWRGD_FAIL_CPU1_EF")
	)
	(segment
		(start 177.847498 -317.62065)
		(end 177.066956 -317.62065)
		(width 0.12954)
		(layer "B.Cu")
		(net "PWRGD_FAIL_CPU1_EF")
	)
	(segment
		(start 163.66109 -318.327786)
		(end 163.671504 -318.3382)
		(width 0.12954)
		(layer "B.Cu")
		(net "PWRGD_FAIL_CPU1_EF")
	)
	(segment
		(start 176.502314 -318.019176)
		(end 176.502314 -318.214248)
		(width 0.12954)
		(layer "B.Cu")
		(net "PWRGD_FAIL_CPU1_EF")
	)
	(segment
		(start 163.671504 -318.363346)
		(end 164.323014 -319.014856)
		(width 0.12954)
		(layer "B.Cu")
		(net "PWRGD_FAIL_CPU1_EF")
	)
	(segment
		(start 163.671504 -318.3382)
		(end 163.671504 -318.363346)
		(width 0.12954)
		(layer "B.Cu")
		(net "PWRGD_FAIL_CPU1_EF")
	)
	(segment
		(start 177.066956 -317.62065)
		(end 176.783238 -317.738252)
		(width 0.12954)
		(layer "B.Cu")
		(net "PWRGD_FAIL_CPU1_EF")
	)
	(segment
		(start 185.503312 -318.171576)
		(end 185.178446 -317.84671)
		(width 0.12954)
		(layer "B.Cu")
		(net "PWRGD_FAIL_CPU1_EF")
	)
	(segment
		(start 170.072558 -317.76289)
		(end 169.264838 -316.95517)
		(width 0.12954)
		(layer "B.Cu")
		(net "PWRGD_FAIL_CPU1_EF")
	)
	(segment
		(start 167.577008 -317.72606)
		(end 167.212518 -317.72606)
		(width 0.12954)
		(layer "B.Cu")
		(net "PWRGD_FAIL_CPU1_EF")
	)
	(segment
		(start 165.191948 -319.014856)
		(end 165.971474 -318.23533)
		(width 0.12954)
		(layer "B.Cu")
		(net "PWRGD_FAIL_CPU1_EF")
	)
	(segment
		(start 167.212518 -317.72606)
		(end 166.703248 -318.23533)
		(width 0.12954)
		(layer "B.Cu")
		(net "PWRGD_FAIL_CPU1_EF")
	)
	(segment
		(start 182.211472 -317.75781)
		(end 184.616598 -317.75781)
		(width 0.12954)
		(layer "B.Cu")
		(net "PWRGD_FAIL_CPU1_EF")
	)
	(segment
		(start 176.502314 -318.214248)
		(end 176.057814 -318.658748)
		(width 0.12954)
		(layer "B.Cu")
		(net "PWRGD_FAIL_CPU1_EF")
	)
	(segment
		(start 180.734208 -318.540384)
		(end 181.428898 -318.540384)
		(width 0.12954)
		(layer "B.Cu")
		(net "PWRGD_FAIL_CPU1_EF")
	)
	(segment
		(start 176.783238 -317.738252)
		(end 176.502314 -318.019176)
		(width 0.12954)
		(layer "B.Cu")
		(net "PWRGD_FAIL_CPU1_EF")
	)
	(segment
		(start 181.428898 -318.540384)
		(end 182.211472 -317.75781)
		(width 0.12954)
		(layer "B.Cu")
		(net "PWRGD_FAIL_CPU1_EF")
	)
	(segment
		(start 185.178446 -317.84671)
		(end 185.178446 -317.428118)
		(width 0.12954)
		(layer "B.Cu")
		(net "PWRGD_FAIL_CPU1_EF")
	)
	(segment
		(start 175.347884 -318.619632)
		(end 172.385482 -318.619632)
		(width 0.12954)
		(layer "B.Cu")
		(net "PWRGD_FAIL_CPU1_EF")
	)
	(segment
		(start 178.631342 -318.622426)
		(end 178.758342 -318.749426)
		(width 0.12954)
		(layer "B.Cu")
		(net "PWRGD_FAIL_CPU1_EF")
	)
	(segment
		(start 178.758342 -318.749426)
		(end 178.758342 -319.500504)
		(width 0.12954)
		(layer "B.Cu")
		(net "PWRGD_FAIL_CPU1_EF")
	)
	(segment
		(start 178.323748 -318.0969)
		(end 177.847498 -317.62065)
		(width 0.12954)
		(layer "B.Cu")
		(net "PWRGD_FAIL_CPU1_EF")
	)
	(segment
		(start 165.971474 -318.23533)
		(end 166.678102 -318.23533)
		(width 0.12954)
		(layer "B.Cu")
		(net "PWRGD_FAIL_CPU1_EF")
	)
	(segment
		(start 164.323014 -319.014856)
		(end 165.191948 -319.014856)
		(width 0.12954)
		(layer "B.Cu")
		(net "PWRGD_FAIL_CPU1_EF")
	)
	(segment
		(start 176.057814 -318.658748)
		(end 175.387 -318.658748)
		(width 0.12954)
		(layer "B.Cu")
		(net "PWRGD_FAIL_CPU1_EF")
	)
	(segment
		(start 169.264838 -316.95517)
		(end 168.347898 -316.95517)
		(width 0.12954)
		(layer "B.Cu")
		(net "PWRGD_FAIL_CPU1_EF")
	)
	(segment
		(start 185.503312 -318.623442)
		(end 185.503312 -318.171576)
		(width 0.12954)
		(layer "B.Cu")
		(net "PWRGD_FAIL_CPU1_EF")
	)
	(segment
		(start 185.178446 -317.428118)
		(end 185.155078 -317.40475)
		(width 0.12954)
		(layer "B.Cu")
		(net "PWRGD_FAIL_CPU1_EF")
	)
	(segment
		(start 175.387 -318.658748)
		(end 175.347884 -318.619632)
		(width 0.12954)
		(layer "B.Cu")
		(net "PWRGD_FAIL_CPU1_EF")
	)
	(segment
		(start 179.056538 -319.7987)
		(end 179.475892 -319.7987)
		(width 0.12954)
		(layer "B.Cu")
		(net "PWRGD_FAIL_CPU1_EF")
	)
	(segment
		(start 166.703248 -318.23533)
		(end 166.678102 -318.23533)
		(width 0.12954)
		(layer "B.Cu")
		(net "PWRGD_FAIL_CPU1_EF")
	)
	(segment
		(start 184.616598 -317.75781)
		(end 185.48223 -318.623442)
		(width 0.12954)
		(layer "B.Cu")
		(net "PWRGD_FAIL_CPU1_EF")
	)
	(segment
		(start 185.48223 -318.623442)
		(end 185.503312 -318.623442)
		(width 0.12954)
		(layer "B.Cu")
		(net "PWRGD_FAIL_CPU1_EF")
	)
	(segment
		(start 178.323748 -318.622426)
		(end 178.631342 -318.622426)
		(width 0.12954)
		(layer "B.Cu")
		(net "PWRGD_FAIL_CPU1_EF")
	)
	(segment
		(start 178.758342 -319.500504)
		(end 179.056538 -319.7987)
		(width 0.12954)
		(layer "B.Cu")
		(net "PWRGD_FAIL_CPU1_EF")
	)
	(segment
		(start 171.395898 -317.76289)
		(end 170.072558 -317.76289)
		(width 0.12954)
		(layer "B.Cu")
		(net "PWRGD_FAIL_CPU1_EF")
	)
	(segment
		(start 172.385482 -318.619632)
		(end 172.25264 -318.619632)
		(width 0.12954)
		(layer "B.Cu")
		(net "PWRGD_FAIL_CPU1_EF")
	)
	(segment
		(start 168.347898 -316.95517)
		(end 167.577008 -317.72606)
		(width 0.12954)
		(layer "B.Cu")
		(net "PWRGD_FAIL_CPU1_EF")
	)
	(segment
		(start 179.475892 -319.7987)
		(end 180.734208 -318.540384)
		(width 0.12954)
		(layer "B.Cu")
		(net "PWRGD_FAIL_CPU1_EF")
	)
	(segment
		(start 163.66109 -318.317372)
		(end 163.66109 -318.327786)
		(width 0.12954)
		(layer "B.Cu")
		(net "PWRGD_FAIL_CPU1_EF")
	)
	(segment
		(start 172.25264 -318.619632)
		(end 171.395898 -317.76289)
		(width 0.12954)
		(layer "B.Cu")
		(net "PWRGD_FAIL_CPU1_EF")
	)
	(via
		(at 40.58412 -315.399928)
		(size 0.6604)
		(drill 0.3302)
		(layers "F.Cu" "B.Cu")
		(net "PWRGD_FAIL_CPU1_CD_R1")
	)
	(segment
		(start 37.309552 -318.748664)
		(end 36.538408 -319.519808)
		(width 0.12954)
		(layer "B.Cu")
		(net "PWRGD_FAIL_CPU1_CD_R1")
	)
	(segment
		(start 39.451026 -314.266834)
		(end 40.58412 -315.399928)
		(width 0.12954)
		(layer "B.Cu")
		(net "PWRGD_FAIL_CPU1_CD_R1")
	)
	(segment
		(start 36.538408 -319.519808)
		(end 36.52901 -319.519808)
		(width 0.12954)
		(layer "B.Cu")
		(net "PWRGD_FAIL_CPU1_CD_R1")
	)
	(segment
		(start 37.672518 -315.27877)
		(end 38.335458 -314.61583)
		(width 0.12954)
		(layer "B.Cu")
		(net "PWRGD_FAIL_CPU1_CD_R1")
	)
	(segment
		(start 40.58412 -315.399928)
		(end 40.58412 -314.414916)
		(width 0.12954)
		(layer "B.Cu")
		(net "PWRGD_FAIL_CPU1_CD_R1")
	)
	(segment
		(start 38.335458 -314.266834)
		(end 39.451026 -314.266834)
		(width 0.12954)
		(layer "B.Cu")
		(net "PWRGD_FAIL_CPU1_CD_R1")
	)
	(segment
		(start 37.547296 -318.252856)
		(end 37.672518 -318.127634)
		(width 0.12954)
		(layer "B.Cu")
		(net "PWRGD_FAIL_CPU1_CD_R1")
	)
	(segment
		(start 37.309552 -318.4906)
		(end 37.309552 -318.748664)
		(width 0.12954)
		(layer "B.Cu")
		(net "PWRGD_FAIL_CPU1_CD_R1")
	)
	(segment
		(start 38.335458 -314.61583)
		(end 38.335458 -314.266834)
		(width 0.12954)
		(layer "B.Cu")
		(net "PWRGD_FAIL_CPU1_CD_R1")
	)
	(segment
		(start 37.547296 -318.252856)
		(end 37.309552 -318.4906)
		(width 0.12954)
		(layer "B.Cu")
		(net "PWRGD_FAIL_CPU1_CD_R1")
	)
	(segment
		(start 37.672518 -318.127634)
		(end 37.672518 -315.27877)
		(width 0.12954)
		(layer "B.Cu")
		(net "PWRGD_FAIL_CPU1_CD_R1")
	)
	(segment
		(start 40.58412 -314.414916)
		(end 40.436038 -314.266834)
		(width 0.12954)
		(layer "B.Cu")
		(net "PWRGD_FAIL_CPU1_CD_R1")
	)
	(segment
		(start 181.355746 -116.975382)
		(end 181.755796 -117.375432)
		(width 0.12954)
		(layer "F.Cu")
		(net "PWRGD_FAIL_CPU1_CD_R")
	)
	(via
		(at 20.918678 -187.401962)
		(size 0.508)
		(drill 0.254)
		(layers "F.Cu" "B.Cu")
		(net "PWRGD_FAIL_CPU1_CD_R")
	)
	(via
		(at 181.755796 -117.375432)
		(size 0.4572)
		(drill 0.254)
		(layers "F.Cu" "B.Cu")
		(net "PWRGD_FAIL_CPU1_CD_R")
	)
	(via
		(at 143.79956 -140.073888)
		(size 0.508)
		(drill 0.254)
		(layers "F.Cu" "B.Cu")
		(net "PWRGD_FAIL_CPU1_CD_R")
	)
	(via
		(at 41.903904 -311.490868)
		(size 0.6604)
		(drill 0.3302)
		(layers "F.Cu" "B.Cu")
		(net "PWRGD_FAIL_CPU1_CD_R")
	)
	(segment
		(start 34.586418 -253.645162)
		(end 38.85311 -257.911854)
		(width 0.12954)
		(layer "B.Cu")
		(net "PWRGD_FAIL_CPU1_CD_R")
	)
	(segment
		(start 23.572978 -191.91859)
		(end 29.917898 -191.91859)
		(width 0.12954)
		(layer "B.Cu")
		(net "PWRGD_FAIL_CPU1_CD_R")
	)
	(segment
		(start 180.75402 -117.772688)
		(end 181.12232 -117.772688)
		(width 0.12954)
		(layer "B.Cu")
		(net "PWRGD_FAIL_CPU1_CD_R")
	)
	(segment
		(start 42.233342 -311.16143)
		(end 41.903904 -311.490868)
		(width 0.12954)
		(layer "B.Cu")
		(net "PWRGD_FAIL_CPU1_CD_R")
	)
	(segment
		(start 180.55844 -117.968268)
		(end 180.75402 -117.772688)
		(width 0.12954)
		(layer "B.Cu")
		(net "PWRGD_FAIL_CPU1_CD_R")
	)
	(segment
		(start 40.436038 -312.958734)
		(end 40.436038 -313.466734)
		(width 0.12954)
		(layer "B.Cu")
		(net "PWRGD_FAIL_CPU1_CD_R")
	)
	(segment
		(start 144.540478 -140.814806)
		(end 176.563782 -140.814806)
		(width 0.12954)
		(layer "B.Cu")
		(net "PWRGD_FAIL_CPU1_CD_R")
	)
	(segment
		(start 180.55844 -121.252488)
		(end 180.55844 -117.968268)
		(width 0.12954)
		(layer "B.Cu")
		(net "PWRGD_FAIL_CPU1_CD_R")
	)
	(segment
		(start 181.519576 -117.375432)
		(end 181.755796 -117.375432)
		(width 0.12954)
		(layer "B.Cu")
		(net "PWRGD_FAIL_CPU1_CD_R")
	)
	(segment
		(start 20.918678 -187.401962)
		(end 20.918678 -189.26429)
		(width 0.12954)
		(layer "B.Cu")
		(net "PWRGD_FAIL_CPU1_CD_R")
	)
	(segment
		(start 41.563036 -257.911854)
		(end 42.233342 -258.58216)
		(width 0.12954)
		(layer "B.Cu")
		(net "PWRGD_FAIL_CPU1_CD_R")
	)
	(segment
		(start 42.233342 -258.58216)
		(end 42.233342 -311.16143)
		(width 0.12954)
		(layer "B.Cu")
		(net "PWRGD_FAIL_CPU1_CD_R")
	)
	(segment
		(start 41.903904 -311.490868)
		(end 40.436038 -312.958734)
		(width 0.12954)
		(layer "B.Cu")
		(net "PWRGD_FAIL_CPU1_CD_R")
	)
	(segment
		(start 182.20944 -126.291848)
		(end 182.20944 -122.903488)
		(width 0.12954)
		(layer "B.Cu")
		(net "PWRGD_FAIL_CPU1_CD_R")
	)
	(segment
		(start 38.85311 -257.911854)
		(end 41.563036 -257.911854)
		(width 0.12954)
		(layer "B.Cu")
		(net "PWRGD_FAIL_CPU1_CD_R")
	)
	(segment
		(start 182.20944 -122.903488)
		(end 180.55844 -121.252488)
		(width 0.12954)
		(layer "B.Cu")
		(net "PWRGD_FAIL_CPU1_CD_R")
	)
	(segment
		(start 182.74284 -126.825248)
		(end 182.20944 -126.291848)
		(width 0.12954)
		(layer "B.Cu")
		(net "PWRGD_FAIL_CPU1_CD_R")
	)
	(segment
		(start 20.918678 -189.26429)
		(end 23.572978 -191.91859)
		(width 0.12954)
		(layer "B.Cu")
		(net "PWRGD_FAIL_CPU1_CD_R")
	)
	(segment
		(start 29.917898 -191.91859)
		(end 34.586418 -196.58711)
		(width 0.12954)
		(layer "B.Cu")
		(net "PWRGD_FAIL_CPU1_CD_R")
	)
	(segment
		(start 181.12232 -117.772688)
		(end 181.519576 -117.375432)
		(width 0.12954)
		(layer "B.Cu")
		(net "PWRGD_FAIL_CPU1_CD_R")
	)
	(segment
		(start 143.79956 -140.073888)
		(end 144.540478 -140.814806)
		(width 0.12954)
		(layer "B.Cu")
		(net "PWRGD_FAIL_CPU1_CD_R")
	)
	(segment
		(start 34.586418 -196.58711)
		(end 34.586418 -253.645162)
		(width 0.12954)
		(layer "B.Cu")
		(net "PWRGD_FAIL_CPU1_CD_R")
	)
	(segment
		(start 182.74284 -134.635748)
		(end 182.74284 -126.825248)
		(width 0.12954)
		(layer "B.Cu")
		(net "PWRGD_FAIL_CPU1_CD_R")
	)
	(segment
		(start 176.563782 -140.814806)
		(end 182.74284 -134.635748)
		(width 0.12954)
		(layer "B.Cu")
		(net "PWRGD_FAIL_CPU1_CD_R")
	)
	(segment
		(start 104.24668 -142.230348)
		(end 138.25728 -142.230348)
		(width 0.127)
		(layer "In6.Cu")
		(net "PWRGD_FAIL_CPU1_CD_R")
	)
	(segment
		(start 20.918678 -187.401962)
		(end 20.918678 -186.858148)
		(width 0.127)
		(layer "In6.Cu")
		(net "PWRGD_FAIL_CPU1_CD_R")
	)
	(segment
		(start 138.25728 -142.230348)
		(end 140.41374 -140.073888)
		(width 0.127)
		(layer "In6.Cu")
		(net "PWRGD_FAIL_CPU1_CD_R")
	)
	(segment
		(start 20.059904 -183.768238)
		(end 18.53311 -183.768238)
		(width 0.127)
		(layer "In6.Cu")
		(net "PWRGD_FAIL_CPU1_CD_R")
	)
	(segment
		(start 17.729708 -168.010586)
		(end 17.729708 -129.07772)
		(width 0.127)
		(layer "In6.Cu")
		(net "PWRGD_FAIL_CPU1_CD_R")
	)
	(segment
		(start 25.15108 -121.656348)
		(end 30.30728 -121.656348)
		(width 0.127)
		(layer "In6.Cu")
		(net "PWRGD_FAIL_CPU1_CD_R")
	)
	(segment
		(start 20.918678 -186.858148)
		(end 21.081238 -186.695588)
		(width 0.127)
		(layer "In6.Cu")
		(net "PWRGD_FAIL_CPU1_CD_R")
	)
	(segment
		(start 22.43074 -186.410854)
		(end 22.43074 -186.139074)
		(width 0.127)
		(layer "In6.Cu")
		(net "PWRGD_FAIL_CPU1_CD_R")
	)
	(segment
		(start 17.729708 -129.07772)
		(end 25.15108 -121.656348)
		(width 0.127)
		(layer "In6.Cu")
		(net "PWRGD_FAIL_CPU1_CD_R")
	)
	(segment
		(start 50.55108 -128.031748)
		(end 90.04808 -128.031748)
		(width 0.127)
		(layer "In6.Cu")
		(net "PWRGD_FAIL_CPU1_CD_R")
	)
	(segment
		(start 31.67888 -120.284748)
		(end 42.80408 -120.284748)
		(width 0.127)
		(layer "In6.Cu")
		(net "PWRGD_FAIL_CPU1_CD_R")
	)
	(segment
		(start 22.43074 -186.139074)
		(end 20.059904 -183.768238)
		(width 0.127)
		(layer "In6.Cu")
		(net "PWRGD_FAIL_CPU1_CD_R")
	)
	(segment
		(start 21.081238 -186.695588)
		(end 22.146006 -186.695588)
		(width 0.127)
		(layer "In6.Cu")
		(net "PWRGD_FAIL_CPU1_CD_R")
	)
	(segment
		(start 30.30728 -121.656348)
		(end 31.67888 -120.284748)
		(width 0.127)
		(layer "In6.Cu")
		(net "PWRGD_FAIL_CPU1_CD_R")
	)
	(segment
		(start 90.04808 -128.031748)
		(end 104.24668 -142.230348)
		(width 0.127)
		(layer "In6.Cu")
		(net "PWRGD_FAIL_CPU1_CD_R")
	)
	(segment
		(start 42.80408 -120.284748)
		(end 50.55108 -128.031748)
		(width 0.127)
		(layer "In6.Cu")
		(net "PWRGD_FAIL_CPU1_CD_R")
	)
	(segment
		(start 17.095978 -182.331106)
		(end 17.095978 -168.644316)
		(width 0.127)
		(layer "In6.Cu")
		(net "PWRGD_FAIL_CPU1_CD_R")
	)
	(segment
		(start 18.53311 -183.768238)
		(end 17.095978 -182.331106)
		(width 0.127)
		(layer "In6.Cu")
		(net "PWRGD_FAIL_CPU1_CD_R")
	)
	(segment
		(start 22.146006 -186.695588)
		(end 22.43074 -186.410854)
		(width 0.127)
		(layer "In6.Cu")
		(net "PWRGD_FAIL_CPU1_CD_R")
	)
	(segment
		(start 140.41374 -140.073888)
		(end 143.79956 -140.073888)
		(width 0.127)
		(layer "In6.Cu")
		(net "PWRGD_FAIL_CPU1_CD_R")
	)
	(segment
		(start 17.095978 -168.644316)
		(end 17.729708 -168.010586)
		(width 0.127)
		(layer "In6.Cu")
		(net "PWRGD_FAIL_CPU1_CD_R")
	)
	(via
		(at 23.52802 -317.91021)
		(size 0.6604)
		(drill 0.3302)
		(layers "F.Cu" "B.Cu")
		(net "PWRGD_FAIL_CPU1_CD")
	)
	(segment
		(start 29.136848 -319.268856)
		(end 27.704796 -319.268856)
		(width 0.12954)
		(layer "B.Cu")
		(net "PWRGD_FAIL_CPU1_CD")
	)
	(segment
		(start 35.72891 -319.519808)
		(end 35.343084 -319.133982)
		(width 0.12954)
		(layer "B.Cu")
		(net "PWRGD_FAIL_CPU1_CD")
	)
	(segment
		(start 20.160996 -319.268856)
		(end 20.160996 -317.551054)
		(width 0.12954)
		(layer "B.Cu")
		(net "PWRGD_FAIL_CPU1_CD")
	)
	(segment
		(start 20.160996 -317.551054)
		(end 19.534632 -316.92469)
		(width 0.12954)
		(layer "B.Cu")
		(net "PWRGD_FAIL_CPU1_CD")
	)
	(segment
		(start 13.21308 -319.268856)
		(end 12.617196 -319.268856)
		(width 0.12954)
		(layer "B.Cu")
		(net "PWRGD_FAIL_CPU1_CD")
	)
	(segment
		(start 31.306516 -318.430148)
		(end 29.975556 -318.430148)
		(width 0.12954)
		(layer "B.Cu")
		(net "PWRGD_FAIL_CPU1_CD")
	)
	(segment
		(start 17.700498 -316.92469)
		(end 16.20774 -318.417448)
		(width 0.12954)
		(layer "B.Cu")
		(net "PWRGD_FAIL_CPU1_CD")
	)
	(segment
		(start 32.804354 -316.93231)
		(end 31.306516 -318.430148)
		(width 0.12954)
		(layer "B.Cu")
		(net "PWRGD_FAIL_CPU1_CD")
	)
	(segment
		(start 15.034768 -318.417448)
		(end 14.495018 -318.957198)
		(width 0.12954)
		(layer "B.Cu")
		(net "PWRGD_FAIL_CPU1_CD")
	)
	(segment
		(start 34.554414 -318.683132)
		(end 34.97326 -318.683132)
		(width 0.12954)
		(layer "B.Cu")
		(net "PWRGD_FAIL_CPU1_CD")
	)
	(segment
		(start 23.030434 -317.91021)
		(end 21.712936 -319.227708)
		(width 0.12954)
		(layer "B.Cu")
		(net "PWRGD_FAIL_CPU1_CD")
	)
	(segment
		(start 29.975556 -318.430148)
		(end 29.136848 -319.268856)
		(width 0.12954)
		(layer "B.Cu")
		(net "PWRGD_FAIL_CPU1_CD")
	)
	(segment
		(start 34.97326 -318.683132)
		(end 35.248596 -318.407796)
		(width 0.12954)
		(layer "B.Cu")
		(net "PWRGD_FAIL_CPU1_CD")
	)
	(segment
		(start 27.704796 -317.363094)
		(end 27.286712 -316.94501)
		(width 0.12954)
		(layer "B.Cu")
		(net "PWRGD_FAIL_CPU1_CD")
	)
	(segment
		(start 35.248596 -318.407796)
		(end 35.248596 -317.251588)
		(width 0.12954)
		(layer "B.Cu")
		(net "PWRGD_FAIL_CPU1_CD")
	)
	(segment
		(start 19.534632 -316.92469)
		(end 17.700498 -316.92469)
		(width 0.12954)
		(layer "B.Cu")
		(net "PWRGD_FAIL_CPU1_CD")
	)
	(segment
		(start 35.343084 -319.133982)
		(end 34.980118 -319.133982)
		(width 0.12954)
		(layer "B.Cu")
		(net "PWRGD_FAIL_CPU1_CD")
	)
	(segment
		(start 14.495018 -318.957198)
		(end 14.231874 -319.066164)
		(width 0.12954)
		(layer "B.Cu")
		(net "PWRGD_FAIL_CPU1_CD")
	)
	(segment
		(start 14.231874 -319.066164)
		(end 13.21308 -319.268856)
		(width 0.12954)
		(layer "B.Cu")
		(net "PWRGD_FAIL_CPU1_CD")
	)
	(segment
		(start 34.980118 -319.133982)
		(end 34.5313 -318.685164)
		(width 0.12954)
		(layer "B.Cu")
		(net "PWRGD_FAIL_CPU1_CD")
	)
	(segment
		(start 35.248596 -317.251588)
		(end 34.929318 -316.93231)
		(width 0.12954)
		(layer "B.Cu")
		(net "PWRGD_FAIL_CPU1_CD")
	)
	(segment
		(start 34.5313 -318.685164)
		(end 34.5313 -318.660018)
		(width 0.12954)
		(layer "B.Cu")
		(net "PWRGD_FAIL_CPU1_CD")
	)
	(segment
		(start 34.5313 -318.660018)
		(end 34.554414 -318.683132)
		(width 0.12954)
		(layer "B.Cu")
		(net "PWRGD_FAIL_CPU1_CD")
	)
	(segment
		(start 20.202144 -319.227708)
		(end 20.160996 -319.268856)
		(width 0.12954)
		(layer "B.Cu")
		(net "PWRGD_FAIL_CPU1_CD")
	)
	(segment
		(start 23.52802 -317.91021)
		(end 23.030434 -317.91021)
		(width 0.12954)
		(layer "B.Cu")
		(net "PWRGD_FAIL_CPU1_CD")
	)
	(segment
		(start 27.286712 -316.94501)
		(end 25.229312 -316.94501)
		(width 0.12954)
		(layer "B.Cu")
		(net "PWRGD_FAIL_CPU1_CD")
	)
	(segment
		(start 24.264112 -317.91021)
		(end 23.52802 -317.91021)
		(width 0.12954)
		(layer "B.Cu")
		(net "PWRGD_FAIL_CPU1_CD")
	)
	(segment
		(start 21.712936 -319.227708)
		(end 20.202144 -319.227708)
		(width 0.12954)
		(layer "B.Cu")
		(net "PWRGD_FAIL_CPU1_CD")
	)
	(segment
		(start 16.20774 -318.417448)
		(end 15.034768 -318.417448)
		(width 0.12954)
		(layer "B.Cu")
		(net "PWRGD_FAIL_CPU1_CD")
	)
	(segment
		(start 25.229312 -316.94501)
		(end 24.264112 -317.91021)
		(width 0.12954)
		(layer "B.Cu")
		(net "PWRGD_FAIL_CPU1_CD")
	)
	(segment
		(start 27.704796 -319.268856)
		(end 27.704796 -317.363094)
		(width 0.12954)
		(layer "B.Cu")
		(net "PWRGD_FAIL_CPU1_CD")
	)
	(segment
		(start 34.929318 -316.93231)
		(end 32.804354 -316.93231)
		(width 0.12954)
		(layer "B.Cu")
		(net "PWRGD_FAIL_CPU1_CD")
	)
	(via
		(at 66.59118 -318.785494)
		(size 0.6604)
		(drill 0.3302)
		(layers "F.Cu" "B.Cu")
		(net "PWRGD_FAIL_CPU1_AB_R1")
	)
	(segment
		(start 68.223638 -318.785494)
		(end 66.59118 -318.785494)
		(width 0.12954)
		(layer "B.Cu")
		(net "PWRGD_FAIL_CPU1_AB_R1")
	)
	(segment
		(start 66.59118 -318.785494)
		(end 65.566798 -318.785494)
		(width 0.12954)
		(layer "B.Cu")
		(net "PWRGD_FAIL_CPU1_AB_R1")
	)
	(segment
		(start 65.566798 -318.785494)
		(end 65.390268 -318.962024)
		(width 0.12954)
		(layer "B.Cu")
		(net "PWRGD_FAIL_CPU1_AB_R1")
	)
	(segment
		(start 69.772022 -318.785494)
		(end 68.223638 -318.785494)
		(width 0.12954)
		(layer "B.Cu")
		(net "PWRGD_FAIL_CPU1_AB_R1")
	)
	(segment
		(start 65.390268 -318.962024)
		(end 65.390268 -317.897256)
		(width 0.12954)
		(layer "B.Cu")
		(net "PWRGD_FAIL_CPU1_AB_R1")
	)
	(segment
		(start 181.355746 -117.775482)
		(end 181.755796 -118.175532)
		(width 0.12954)
		(layer "F.Cu")
		(net "PWRGD_FAIL_CPU1_AB_R")
	)
	(via
		(at 57.63514 -311.896506)
		(size 0.6604)
		(drill 0.3302)
		(layers "F.Cu" "B.Cu")
		(net "PWRGD_FAIL_CPU1_AB_R")
	)
	(via
		(at 21.494242 -188.277246)
		(size 0.508)
		(drill 0.254)
		(layers "F.Cu" "B.Cu")
		(net "PWRGD_FAIL_CPU1_AB_R")
	)
	(via
		(at 143.79956 -140.962888)
		(size 0.508)
		(drill 0.254)
		(layers "F.Cu" "B.Cu")
		(net "PWRGD_FAIL_CPU1_AB_R")
	)
	(via
		(at 181.755796 -118.175532)
		(size 0.4572)
		(drill 0.254)
		(layers "F.Cu" "B.Cu")
		(net "PWRGD_FAIL_CPU1_AB_R")
	)
	(segment
		(start 53.961538 -311.896506)
		(end 57.63514 -311.896506)
		(width 0.12954)
		(layer "B.Cu")
		(net "PWRGD_FAIL_CPU1_AB_R")
	)
	(segment
		(start 182.61838 -125.910848)
		(end 182.61838 -122.710448)
		(width 0.12954)
		(layer "B.Cu")
		(net "PWRGD_FAIL_CPU1_AB_R")
	)
	(segment
		(start 183.0578 -136.372092)
		(end 183.0578 -126.350268)
		(width 0.12954)
		(layer "B.Cu")
		(net "PWRGD_FAIL_CPU1_AB_R")
	)
	(segment
		(start 182.61838 -122.710448)
		(end 181.356 -121.448068)
		(width 0.12954)
		(layer "B.Cu")
		(net "PWRGD_FAIL_CPU1_AB_R")
	)
	(segment
		(start 47.62754 -309.944008)
		(end 48.61052 -310.926988)
		(width 0.12954)
		(layer "B.Cu")
		(net "PWRGD_FAIL_CPU1_AB_R")
	)
	(segment
		(start 57.63514 -311.896506)
		(end 67.744594 -311.896506)
		(width 0.12954)
		(layer "B.Cu")
		(net "PWRGD_FAIL_CPU1_AB_R")
	)
	(segment
		(start 21.494242 -188.277246)
		(end 21.494242 -189.088014)
		(width 0.12954)
		(layer "B.Cu")
		(net "PWRGD_FAIL_CPU1_AB_R")
	)
	(segment
		(start 143.79956 -140.962888)
		(end 144.055338 -141.218666)
		(width 0.12954)
		(layer "B.Cu")
		(net "PWRGD_FAIL_CPU1_AB_R")
	)
	(segment
		(start 23.793958 -191.38773)
		(end 30.349952 -191.38773)
		(width 0.12954)
		(layer "B.Cu")
		(net "PWRGD_FAIL_CPU1_AB_R")
	)
	(segment
		(start 39.084758 -257.3528)
		(end 41.697148 -257.3528)
		(width 0.12954)
		(layer "B.Cu")
		(net "PWRGD_FAIL_CPU1_AB_R")
	)
	(segment
		(start 183.0578 -126.350268)
		(end 182.61838 -125.910848)
		(width 0.12954)
		(layer "B.Cu")
		(net "PWRGD_FAIL_CPU1_AB_R")
	)
	(segment
		(start 50.39868 -309.921148)
		(end 51.98618 -309.921148)
		(width 0.1143)
		(layer "B.Cu")
		(net "PWRGD_FAIL_CPU1_AB_R")
	)
	(segment
		(start 46.22038 -310.015128)
		(end 46.2915 -309.944008)
		(width 0.12954)
		(layer "B.Cu")
		(net "PWRGD_FAIL_CPU1_AB_R")
	)
	(segment
		(start 69.772022 -313.923934)
		(end 69.772022 -317.985394)
		(width 0.12954)
		(layer "B.Cu")
		(net "PWRGD_FAIL_CPU1_AB_R")
	)
	(segment
		(start 67.744594 -311.896506)
		(end 69.772022 -313.923934)
		(width 0.12954)
		(layer "B.Cu")
		(net "PWRGD_FAIL_CPU1_AB_R")
	)
	(segment
		(start 33.780222 -194.09156)
		(end 35.145472 -195.45681)
		(width 0.12954)
		(layer "B.Cu")
		(net "PWRGD_FAIL_CPU1_AB_R")
	)
	(segment
		(start 35.145472 -253.413514)
		(end 39.084758 -257.3528)
		(width 0.12954)
		(layer "B.Cu")
		(net "PWRGD_FAIL_CPU1_AB_R")
	)
	(segment
		(start 41.697148 -257.3528)
		(end 42.792396 -258.448048)
		(width 0.12954)
		(layer "B.Cu")
		(net "PWRGD_FAIL_CPU1_AB_R")
	)
	(segment
		(start 42.792396 -309.032656)
		(end 43.318938 -309.559198)
		(width 0.12954)
		(layer "B.Cu")
		(net "PWRGD_FAIL_CPU1_AB_R")
	)
	(segment
		(start 181.356 -118.575328)
		(end 181.755796 -118.175532)
		(width 0.12954)
		(layer "B.Cu")
		(net "PWRGD_FAIL_CPU1_AB_R")
	)
	(segment
		(start 46.2915 -309.944008)
		(end 47.62754 -309.944008)
		(width 0.12954)
		(layer "B.Cu")
		(net "PWRGD_FAIL_CPU1_AB_R")
	)
	(segment
		(start 181.356 -121.448068)
		(end 181.356 -118.575328)
		(width 0.12954)
		(layer "B.Cu")
		(net "PWRGD_FAIL_CPU1_AB_R")
	)
	(segment
		(start 21.494242 -189.088014)
		(end 23.793958 -191.38773)
		(width 0.12954)
		(layer "B.Cu")
		(net "PWRGD_FAIL_CPU1_AB_R")
	)
	(segment
		(start 35.145472 -195.45681)
		(end 35.145472 -253.413514)
		(width 0.12954)
		(layer "B.Cu")
		(net "PWRGD_FAIL_CPU1_AB_R")
	)
	(segment
		(start 43.737784 -309.559198)
		(end 44.193714 -310.015128)
		(width 0.12954)
		(layer "B.Cu")
		(net "PWRGD_FAIL_CPU1_AB_R")
	)
	(segment
		(start 42.792396 -258.448048)
		(end 42.792396 -309.032656)
		(width 0.12954)
		(layer "B.Cu")
		(net "PWRGD_FAIL_CPU1_AB_R")
	)
	(segment
		(start 48.61052 -310.926988)
		(end 49.39284 -310.926988)
		(width 0.12954)
		(layer "B.Cu")
		(net "PWRGD_FAIL_CPU1_AB_R")
	)
	(segment
		(start 49.39284 -310.926988)
		(end 50.39868 -309.921148)
		(width 0.12954)
		(layer "B.Cu")
		(net "PWRGD_FAIL_CPU1_AB_R")
	)
	(segment
		(start 51.98618 -309.921148)
		(end 53.961538 -311.896506)
		(width 0.12954)
		(layer "B.Cu")
		(net "PWRGD_FAIL_CPU1_AB_R")
	)
	(segment
		(start 44.193714 -310.015128)
		(end 46.22038 -310.015128)
		(width 0.12954)
		(layer "B.Cu")
		(net "PWRGD_FAIL_CPU1_AB_R")
	)
	(segment
		(start 33.053782 -194.09156)
		(end 33.780222 -194.09156)
		(width 0.12954)
		(layer "B.Cu")
		(net "PWRGD_FAIL_CPU1_AB_R")
	)
	(segment
		(start 30.349952 -191.38773)
		(end 33.053782 -194.09156)
		(width 0.12954)
		(layer "B.Cu")
		(net "PWRGD_FAIL_CPU1_AB_R")
	)
	(segment
		(start 43.318938 -309.559198)
		(end 43.737784 -309.559198)
		(width 0.12954)
		(layer "B.Cu")
		(net "PWRGD_FAIL_CPU1_AB_R")
	)
	(segment
		(start 178.211226 -141.218666)
		(end 183.0578 -136.372092)
		(width 0.12954)
		(layer "B.Cu")
		(net "PWRGD_FAIL_CPU1_AB_R")
	)
	(segment
		(start 144.055338 -141.218666)
		(end 178.211226 -141.218666)
		(width 0.12954)
		(layer "B.Cu")
		(net "PWRGD_FAIL_CPU1_AB_R")
	)
	(segment
		(start 18.91411 -182.79872)
		(end 18.91411 -181.84622)
		(width 0.127)
		(layer "In6.Cu")
		(net "PWRGD_FAIL_CPU1_AB_R")
	)
	(segment
		(start 18.42262 -129.278634)
		(end 25.422606 -122.278648)
		(width 0.127)
		(layer "In6.Cu")
		(net "PWRGD_FAIL_CPU1_AB_R")
	)
	(segment
		(start 140.418566 -140.962888)
		(end 143.79956 -140.962888)
		(width 0.127)
		(layer "In6.Cu")
		(net "PWRGD_FAIL_CPU1_AB_R")
	)
	(segment
		(start 23.06955 -186.741816)
		(end 23.06955 -185.707274)
		(width 0.127)
		(layer "In6.Cu")
		(net "PWRGD_FAIL_CPU1_AB_R")
	)
	(segment
		(start 31.961074 -120.879108)
		(end 42.499534 -120.879108)
		(width 0.127)
		(layer "In6.Cu")
		(net "PWRGD_FAIL_CPU1_AB_R")
	)
	(segment
		(start 138.584686 -142.796768)
		(end 140.418566 -140.962888)
		(width 0.127)
		(layer "In6.Cu")
		(net "PWRGD_FAIL_CPU1_AB_R")
	)
	(segment
		(start 19.312128 -183.196738)
		(end 18.91411 -182.79872)
		(width 0.127)
		(layer "In6.Cu")
		(net "PWRGD_FAIL_CPU1_AB_R")
	)
	(segment
		(start 18.0848 -168.476168)
		(end 18.42262 -168.138348)
		(width 0.127)
		(layer "In6.Cu")
		(net "PWRGD_FAIL_CPU1_AB_R")
	)
	(segment
		(start 18.42262 -168.138348)
		(end 18.42262 -129.278634)
		(width 0.127)
		(layer "In6.Cu")
		(net "PWRGD_FAIL_CPU1_AB_R")
	)
	(segment
		(start 20.559014 -183.196738)
		(end 19.312128 -183.196738)
		(width 0.127)
		(layer "In6.Cu")
		(net "PWRGD_FAIL_CPU1_AB_R")
	)
	(segment
		(start 18.91411 -181.84622)
		(end 18.0848 -181.01691)
		(width 0.127)
		(layer "In6.Cu")
		(net "PWRGD_FAIL_CPU1_AB_R")
	)
	(segment
		(start 25.422606 -122.278648)
		(end 30.561534 -122.278648)
		(width 0.127)
		(layer "In6.Cu")
		(net "PWRGD_FAIL_CPU1_AB_R")
	)
	(segment
		(start 104.005634 -142.796768)
		(end 138.584686 -142.796768)
		(width 0.127)
		(layer "In6.Cu")
		(net "PWRGD_FAIL_CPU1_AB_R")
	)
	(segment
		(start 89.784174 -128.575308)
		(end 104.005634 -142.796768)
		(width 0.127)
		(layer "In6.Cu")
		(net "PWRGD_FAIL_CPU1_AB_R")
	)
	(segment
		(start 50.195734 -128.575308)
		(end 89.784174 -128.575308)
		(width 0.127)
		(layer "In6.Cu")
		(net "PWRGD_FAIL_CPU1_AB_R")
	)
	(segment
		(start 30.561534 -122.278648)
		(end 31.961074 -120.879108)
		(width 0.127)
		(layer "In6.Cu")
		(net "PWRGD_FAIL_CPU1_AB_R")
	)
	(segment
		(start 18.0848 -181.01691)
		(end 18.0848 -168.476168)
		(width 0.127)
		(layer "In6.Cu")
		(net "PWRGD_FAIL_CPU1_AB_R")
	)
	(segment
		(start 23.06955 -185.707274)
		(end 20.559014 -183.196738)
		(width 0.127)
		(layer "In6.Cu")
		(net "PWRGD_FAIL_CPU1_AB_R")
	)
	(segment
		(start 21.53412 -188.277246)
		(end 23.06955 -186.741816)
		(width 0.127)
		(layer "In6.Cu")
		(net "PWRGD_FAIL_CPU1_AB_R")
	)
	(segment
		(start 42.499534 -120.879108)
		(end 50.195734 -128.575308)
		(width 0.127)
		(layer "In6.Cu")
		(net "PWRGD_FAIL_CPU1_AB_R")
	)
	(segment
		(start 21.494242 -188.277246)
		(end 21.53412 -188.277246)
		(width 0.127)
		(layer "In6.Cu")
		(net "PWRGD_FAIL_CPU1_AB_R")
	)
	(via
		(at 46.228 -317.947548)
		(size 0.6604)
		(drill 0.3302)
		(layers "F.Cu" "B.Cu")
		(net "PWRGD_FAIL_CPU1_AB")
	)
	(segment
		(start 51.966114 -319.042034)
		(end 51.788568 -319.470786)
		(width 0.12954)
		(layer "B.Cu")
		(net "PWRGD_FAIL_CPU1_AB")
	)
	(segment
		(start 51.731926 -319.754758)
		(end 51.731926 -319.822068)
		(width 0.12954)
		(layer "B.Cu")
		(net "PWRGD_FAIL_CPU1_AB")
	)
	(segment
		(start 52.653438 -318.35471)
		(end 51.966114 -319.042034)
		(width 0.12954)
		(layer "B.Cu")
		(net "PWRGD_FAIL_CPU1_AB")
	)
	(segment
		(start 47.563278 -317.28283)
		(end 50.037238 -317.28283)
		(width 0.12954)
		(layer "B.Cu")
		(net "PWRGD_FAIL_CPU1_AB")
	)
	(segment
		(start 44.294044 -319.488058)
		(end 45.834554 -317.947548)
		(width 0.12954)
		(layer "B.Cu")
		(net "PWRGD_FAIL_CPU1_AB")
	)
	(segment
		(start 50.309018 -317.55461)
		(end 50.309018 -319.241678)
		(width 0.12954)
		(layer "B.Cu")
		(net "PWRGD_FAIL_CPU1_AB")
	)
	(segment
		(start 50.309018 -319.241678)
		(end 50.336196 -319.268856)
		(width 0.12954)
		(layer "B.Cu")
		(net "PWRGD_FAIL_CPU1_AB")
	)
	(segment
		(start 51.788568 -319.470786)
		(end 51.731926 -319.754758)
		(width 0.12954)
		(layer "B.Cu")
		(net "PWRGD_FAIL_CPU1_AB")
	)
	(segment
		(start 51.518566 -320.035428)
		(end 50.725832 -320.035428)
		(width 0.12954)
		(layer "B.Cu")
		(net "PWRGD_FAIL_CPU1_AB")
	)
	(segment
		(start 46.89856 -317.947548)
		(end 47.563278 -317.28283)
		(width 0.12954)
		(layer "B.Cu")
		(net "PWRGD_FAIL_CPU1_AB")
	)
	(segment
		(start 60.83173 -316.208918)
		(end 60.63742 -316.403228)
		(width 0.12954)
		(layer "B.Cu")
		(net "PWRGD_FAIL_CPU1_AB")
	)
	(segment
		(start 57.323736 -317.238888)
		(end 55.21452 -317.238888)
		(width 0.12954)
		(layer "B.Cu")
		(net "PWRGD_FAIL_CPU1_AB")
	)
	(segment
		(start 55.21452 -317.238888)
		(end 54.098698 -318.35471)
		(width 0.12954)
		(layer "B.Cu")
		(net "PWRGD_FAIL_CPU1_AB")
	)
	(segment
		(start 58.852562 -319.41008)
		(end 57.829196 -319.41008)
		(width 0.12954)
		(layer "B.Cu")
		(net "PWRGD_FAIL_CPU1_AB")
	)
	(segment
		(start 54.098698 -318.35471)
		(end 52.653438 -318.35471)
		(width 0.12954)
		(layer "B.Cu")
		(net "PWRGD_FAIL_CPU1_AB")
	)
	(segment
		(start 60.63742 -316.403228)
		(end 60.63742 -316.98057)
		(width 0.12954)
		(layer "B.Cu")
		(net "PWRGD_FAIL_CPU1_AB")
	)
	(segment
		(start 60.63742 -316.98057)
		(end 59.998356 -318.523366)
		(width 0.12954)
		(layer "B.Cu")
		(net "PWRGD_FAIL_CPU1_AB")
	)
	(segment
		(start 46.228 -317.947548)
		(end 46.89856 -317.947548)
		(width 0.12954)
		(layer "B.Cu")
		(net "PWRGD_FAIL_CPU1_AB")
	)
	(segment
		(start 63.312802 -316.61989)
		(end 64.590168 -317.897256)
		(width 0.12954)
		(layer "B.Cu")
		(net "PWRGD_FAIL_CPU1_AB")
	)
	(segment
		(start 57.829196 -319.41008)
		(end 57.829196 -317.744348)
		(width 0.12954)
		(layer "B.Cu")
		(net "PWRGD_FAIL_CPU1_AB")
	)
	(segment
		(start 45.834554 -317.947548)
		(end 46.228 -317.947548)
		(width 0.12954)
		(layer "B.Cu")
		(net "PWRGD_FAIL_CPU1_AB")
	)
	(segment
		(start 50.725832 -320.035428)
		(end 50.336196 -319.645792)
		(width 0.12954)
		(layer "B.Cu")
		(net "PWRGD_FAIL_CPU1_AB")
	)
	(segment
		(start 61.25464 -316.208918)
		(end 61.819536 -316.208918)
		(width 0.12954)
		(layer "B.Cu")
		(net "PWRGD_FAIL_CPU1_AB")
	)
	(segment
		(start 51.731926 -319.822068)
		(end 51.518566 -320.035428)
		(width 0.12954)
		(layer "B.Cu")
		(net "PWRGD_FAIL_CPU1_AB")
	)
	(segment
		(start 42.792396 -319.268856)
		(end 43.011598 -319.488058)
		(width 0.12954)
		(layer "B.Cu")
		(net "PWRGD_FAIL_CPU1_AB")
	)
	(segment
		(start 59.294776 -319.226946)
		(end 58.852562 -319.41008)
		(width 0.12954)
		(layer "B.Cu")
		(net "PWRGD_FAIL_CPU1_AB")
	)
	(segment
		(start 61.25464 -316.208918)
		(end 60.83173 -316.208918)
		(width 0.12954)
		(layer "B.Cu")
		(net "PWRGD_FAIL_CPU1_AB")
	)
	(segment
		(start 43.011598 -319.488058)
		(end 44.294044 -319.488058)
		(width 0.12954)
		(layer "B.Cu")
		(net "PWRGD_FAIL_CPU1_AB")
	)
	(segment
		(start 50.037238 -317.28283)
		(end 50.309018 -317.55461)
		(width 0.12954)
		(layer "B.Cu")
		(net "PWRGD_FAIL_CPU1_AB")
	)
	(segment
		(start 62.230508 -316.61989)
		(end 63.312802 -316.61989)
		(width 0.12954)
		(layer "B.Cu")
		(net "PWRGD_FAIL_CPU1_AB")
	)
	(segment
		(start 59.998356 -318.523366)
		(end 59.294776 -319.226946)
		(width 0.12954)
		(layer "B.Cu")
		(net "PWRGD_FAIL_CPU1_AB")
	)
	(segment
		(start 61.819536 -316.208918)
		(end 62.230508 -316.61989)
		(width 0.12954)
		(layer "B.Cu")
		(net "PWRGD_FAIL_CPU1_AB")
	)
	(segment
		(start 50.336196 -319.645792)
		(end 50.336196 -319.268856)
		(width 0.12954)
		(layer "B.Cu")
		(net "PWRGD_FAIL_CPU1_AB")
	)
	(segment
		(start 57.829196 -317.744348)
		(end 57.323736 -317.238888)
		(width 0.12954)
		(layer "B.Cu")
		(net "PWRGD_FAIL_CPU1_AB")
	)
	(via
		(at 457.87818 -314.838588)
		(size 0.6604)
		(drill 0.3302)
		(layers "F.Cu" "B.Cu")
		(net "PWRGD_FAIL_CPU0_GH_R1")
	)
	(segment
		(start 456.117198 -316.18301)
		(end 455.863198 -316.43701)
		(width 0.12954)
		(layer "B.Cu")
		(net "PWRGD_FAIL_CPU0_GH_R1")
	)
	(segment
		(start 455.863198 -317.726568)
		(end 456.403456 -318.266826)
		(width 0.12954)
		(layer "B.Cu")
		(net "PWRGD_FAIL_CPU0_GH_R1")
	)
	(segment
		(start 458.273658 -314.44311)
		(end 459.19263 -314.44311)
		(width 0.12954)
		(layer "B.Cu")
		(net "PWRGD_FAIL_CPU0_GH_R1")
	)
	(segment
		(start 456.543918 -315.20511)
		(end 456.543918 -316.18301)
		(width 0.12954)
		(layer "B.Cu")
		(net "PWRGD_FAIL_CPU0_GH_R1")
	)
	(segment
		(start 459.19263 -314.44311)
		(end 459.574646 -314.061094)
		(width 0.12954)
		(layer "B.Cu")
		(net "PWRGD_FAIL_CPU0_GH_R1")
	)
	(segment
		(start 457.87818 -314.838588)
		(end 458.273658 -314.44311)
		(width 0.12954)
		(layer "B.Cu")
		(net "PWRGD_FAIL_CPU0_GH_R1")
	)
	(segment
		(start 457.511658 -315.20511)
		(end 457.87818 -314.838588)
		(width 0.12954)
		(layer "B.Cu")
		(net "PWRGD_FAIL_CPU0_GH_R1")
	)
	(segment
		(start 455.863198 -316.43701)
		(end 455.863198 -317.726568)
		(width 0.12954)
		(layer "B.Cu")
		(net "PWRGD_FAIL_CPU0_GH_R1")
	)
	(segment
		(start 456.543918 -315.20511)
		(end 457.511658 -315.20511)
		(width 0.12954)
		(layer "B.Cu")
		(net "PWRGD_FAIL_CPU0_GH_R1")
	)
	(segment
		(start 456.543918 -316.18301)
		(end 456.117198 -316.18301)
		(width 0.12954)
		(layer "B.Cu")
		(net "PWRGD_FAIL_CPU0_GH_R1")
	)
	(segment
		(start 181.355746 -118.575328)
		(end 181.755796 -118.975378)
		(width 0.12954)
		(layer "F.Cu")
		(net "PWRGD_FAIL_CPU0_GH_R")
	)
	(via
		(at 181.755796 -118.975378)
		(size 0.4572)
		(drill 0.254)
		(layers "F.Cu" "B.Cu")
		(net "PWRGD_FAIL_CPU0_GH_R")
	)
	(via
		(at 432.64074 -190.36157)
		(size 0.508)
		(drill 0.254)
		(layers "F.Cu" "B.Cu")
		(net "PWRGD_FAIL_CPU0_GH_R")
	)
	(via
		(at 288.556954 -127.844296)
		(size 0.508)
		(drill 0.254)
		(layers "F.Cu" "B.Cu")
		(net "PWRGD_FAIL_CPU0_GH_R")
	)
	(via
		(at 393.823698 -173.11751)
		(size 0.508)
		(drill 0.254)
		(layers "F.Cu" "B.Cu")
		(net "PWRGD_FAIL_CPU0_GH_R")
	)
	(via
		(at 186.416188 -135.054848)
		(size 0.508)
		(drill 0.254)
		(layers "F.Cu" "B.Cu")
		(net "PWRGD_FAIL_CPU0_GH_R")
	)
	(via
		(at 183.567578 -147.160234)
		(size 0.508)
		(drill 0.254)
		(layers "F.Cu" "B.Cu")
		(net "PWRGD_FAIL_CPU0_GH_R")
	)
	(segment
		(start 310.430926 -132.73405)
		(end 303.064164 -125.367288)
		(width 0.12954)
		(layer "B.Cu")
		(net "PWRGD_FAIL_CPU0_GH_R")
	)
	(segment
		(start 455.916538 -256.82575)
		(end 456.537314 -257.446526)
		(width 0.12954)
		(layer "B.Cu")
		(net "PWRGD_FAIL_CPU0_GH_R")
	)
	(segment
		(start 393.823698 -173.11751)
		(end 390.54405 -173.11751)
		(width 0.12954)
		(layer "B.Cu")
		(net "PWRGD_FAIL_CPU0_GH_R")
	)
	(segment
		(start 320.066924 -132.73405)
		(end 310.430926 -132.73405)
		(width 0.12954)
		(layer "B.Cu")
		(net "PWRGD_FAIL_CPU0_GH_R")
	)
	(segment
		(start 334.990186 -138.915648)
		(end 320.066924 -132.73405)
		(width 0.12954)
		(layer "B.Cu")
		(net "PWRGD_FAIL_CPU0_GH_R")
	)
	(segment
		(start 186.416188 -135.054848)
		(end 184.37352 -133.01218)
		(width 0.12954)
		(layer "B.Cu")
		(net "PWRGD_FAIL_CPU0_GH_R")
	)
	(segment
		(start 183.06796 -122.540268)
		(end 182.15356 -121.625868)
		(width 0.12954)
		(layer "B.Cu")
		(net "PWRGD_FAIL_CPU0_GH_R")
	)
	(segment
		(start 183.06796 -125.042168)
		(end 183.06796 -122.540268)
		(width 0.12954)
		(layer "B.Cu")
		(net "PWRGD_FAIL_CPU0_GH_R")
	)
	(segment
		(start 440.722258 -251.86259)
		(end 445.685418 -256.82575)
		(width 0.12954)
		(layer "B.Cu")
		(net "PWRGD_FAIL_CPU0_GH_R")
	)
	(segment
		(start 456.537314 -257.446526)
		(end 456.537314 -314.398406)
		(width 0.12954)
		(layer "B.Cu")
		(net "PWRGD_FAIL_CPU0_GH_R")
	)
	(segment
		(start 440.722258 -192.94221)
		(end 440.722258 -251.86259)
		(width 0.12954)
		(layer "B.Cu")
		(net "PWRGD_FAIL_CPU0_GH_R")
	)
	(segment
		(start 376.535696 -150.159212)
		(end 357.38689 -150.159212)
		(width 0.12954)
		(layer "B.Cu")
		(net "PWRGD_FAIL_CPU0_GH_R")
	)
	(segment
		(start 438.141618 -190.36157)
		(end 440.722258 -192.94221)
		(width 0.12954)
		(layer "B.Cu")
		(net "PWRGD_FAIL_CPU0_GH_R")
	)
	(segment
		(start 432.64074 -190.36157)
		(end 438.141618 -190.36157)
		(width 0.12954)
		(layer "B.Cu")
		(net "PWRGD_FAIL_CPU0_GH_R")
	)
	(segment
		(start 346.143326 -138.915648)
		(end 334.990186 -138.915648)
		(width 0.12954)
		(layer "B.Cu")
		(net "PWRGD_FAIL_CPU0_GH_R")
	)
	(segment
		(start 184.37352 -133.01218)
		(end 184.37352 -126.347728)
		(width 0.12954)
		(layer "B.Cu")
		(net "PWRGD_FAIL_CPU0_GH_R")
	)
	(segment
		(start 357.38689 -150.159212)
		(end 346.143326 -138.915648)
		(width 0.12954)
		(layer "B.Cu")
		(net "PWRGD_FAIL_CPU0_GH_R")
	)
	(segment
		(start 182.15356 -119.373142)
		(end 181.755796 -118.975378)
		(width 0.12954)
		(layer "B.Cu")
		(net "PWRGD_FAIL_CPU0_GH_R")
	)
	(segment
		(start 390.54405 -173.11751)
		(end 386.637784 -169.211244)
		(width 0.12954)
		(layer "B.Cu")
		(net "PWRGD_FAIL_CPU0_GH_R")
	)
	(segment
		(start 456.537314 -314.398406)
		(end 456.543918 -314.40501)
		(width 0.12954)
		(layer "B.Cu")
		(net "PWRGD_FAIL_CPU0_GH_R")
	)
	(segment
		(start 182.15356 -121.625868)
		(end 182.15356 -119.373142)
		(width 0.12954)
		(layer "B.Cu")
		(net "PWRGD_FAIL_CPU0_GH_R")
	)
	(segment
		(start 382.88976 -162.027362)
		(end 382.88976 -156.513276)
		(width 0.12954)
		(layer "B.Cu")
		(net "PWRGD_FAIL_CPU0_GH_R")
	)
	(segment
		(start 386.637784 -165.775386)
		(end 382.88976 -162.027362)
		(width 0.12954)
		(layer "B.Cu")
		(net "PWRGD_FAIL_CPU0_GH_R")
	)
	(segment
		(start 303.064164 -125.367288)
		(end 290.183316 -125.367288)
		(width 0.12954)
		(layer "B.Cu")
		(net "PWRGD_FAIL_CPU0_GH_R")
	)
	(segment
		(start 445.685418 -256.82575)
		(end 455.916538 -256.82575)
		(width 0.12954)
		(layer "B.Cu")
		(net "PWRGD_FAIL_CPU0_GH_R")
	)
	(segment
		(start 386.637784 -169.211244)
		(end 386.637784 -165.775386)
		(width 0.12954)
		(layer "B.Cu")
		(net "PWRGD_FAIL_CPU0_GH_R")
	)
	(segment
		(start 288.556954 -126.99365)
		(end 288.556954 -127.844296)
		(width 0.12954)
		(layer "B.Cu")
		(net "PWRGD_FAIL_CPU0_GH_R")
	)
	(segment
		(start 184.37352 -126.347728)
		(end 183.06796 -125.042168)
		(width 0.12954)
		(layer "B.Cu")
		(net "PWRGD_FAIL_CPU0_GH_R")
	)
	(segment
		(start 290.183316 -125.367288)
		(end 288.556954 -126.99365)
		(width 0.12954)
		(layer "B.Cu")
		(net "PWRGD_FAIL_CPU0_GH_R")
	)
	(segment
		(start 382.88976 -156.513276)
		(end 376.535696 -150.159212)
		(width 0.12954)
		(layer "B.Cu")
		(net "PWRGD_FAIL_CPU0_GH_R")
	)
	(segment
		(start 396.090902 -187.784994)
		(end 395.609318 -187.30341)
		(width 0.127)
		(layer "In2.Cu")
		(net "PWRGD_FAIL_CPU0_GH_R")
	)
	(segment
		(start 422.329102 -190.36157)
		(end 419.752526 -187.784994)
		(width 0.127)
		(layer "In2.Cu")
		(net "PWRGD_FAIL_CPU0_GH_R")
	)
	(segment
		(start 394.491718 -173.11751)
		(end 393.823698 -173.11751)
		(width 0.127)
		(layer "In2.Cu")
		(net "PWRGD_FAIL_CPU0_GH_R")
	)
	(segment
		(start 432.64074 -190.36157)
		(end 422.329102 -190.36157)
		(width 0.127)
		(layer "In2.Cu")
		(net "PWRGD_FAIL_CPU0_GH_R")
	)
	(segment
		(start 396.418308 -175.0441)
		(end 394.491718 -173.11751)
		(width 0.127)
		(layer "In2.Cu")
		(net "PWRGD_FAIL_CPU0_GH_R")
	)
	(segment
		(start 395.609318 -184.13603)
		(end 396.418308 -183.32704)
		(width 0.127)
		(layer "In2.Cu")
		(net "PWRGD_FAIL_CPU0_GH_R")
	)
	(segment
		(start 395.609318 -187.30341)
		(end 395.609318 -184.13603)
		(width 0.127)
		(layer "In2.Cu")
		(net "PWRGD_FAIL_CPU0_GH_R")
	)
	(segment
		(start 396.418308 -183.32704)
		(end 396.418308 -175.0441)
		(width 0.127)
		(layer "In2.Cu")
		(net "PWRGD_FAIL_CPU0_GH_R")
	)
	(segment
		(start 419.752526 -187.784994)
		(end 396.090902 -187.784994)
		(width 0.127)
		(layer "In2.Cu")
		(net "PWRGD_FAIL_CPU0_GH_R")
	)
	(segment
		(start 185.457592 -145.129758)
		(end 183.567578 -147.019772)
		(width 0.127)
		(layer "In11.Cu")
		(net "PWRGD_FAIL_CPU0_GH_R")
	)
	(segment
		(start 186.71286 -135.637016)
		(end 186.71286 -143.099282)
		(width 0.127)
		(layer "In11.Cu")
		(net "PWRGD_FAIL_CPU0_GH_R")
	)
	(segment
		(start 186.71286 -143.099282)
		(end 185.457592 -144.35455)
		(width 0.127)
		(layer "In11.Cu")
		(net "PWRGD_FAIL_CPU0_GH_R")
	)
	(segment
		(start 185.457592 -144.35455)
		(end 185.457592 -145.129758)
		(width 0.127)
		(layer "In11.Cu")
		(net "PWRGD_FAIL_CPU0_GH_R")
	)
	(segment
		(start 186.416188 -135.340344)
		(end 186.71286 -135.637016)
		(width 0.127)
		(layer "In11.Cu")
		(net "PWRGD_FAIL_CPU0_GH_R")
	)
	(segment
		(start 186.416188 -135.054848)
		(end 186.416188 -135.340344)
		(width 0.127)
		(layer "In11.Cu")
		(net "PWRGD_FAIL_CPU0_GH_R")
	)
	(segment
		(start 183.567578 -147.019772)
		(end 183.567578 -147.160234)
		(width 0.127)
		(layer "In11.Cu")
		(net "PWRGD_FAIL_CPU0_GH_R")
	)
	(segment
		(start 266.183364 -130.224784)
		(end 260.992366 -135.415782)
		(width 0.127)
		(layer "In15.Cu")
		(net "PWRGD_FAIL_CPU0_GH_R")
	)
	(segment
		(start 212.366606 -142.491714)
		(end 187.930028 -142.491714)
		(width 0.127)
		(layer "In15.Cu")
		(net "PWRGD_FAIL_CPU0_GH_R")
	)
	(segment
		(start 288.556954 -127.844296)
		(end 286.176466 -130.224784)
		(width 0.127)
		(layer "In15.Cu")
		(net "PWRGD_FAIL_CPU0_GH_R")
	)
	(segment
		(start 248.025158 -140.17625)
		(end 214.68207 -140.17625)
		(width 0.127)
		(layer "In15.Cu")
		(net "PWRGD_FAIL_CPU0_GH_R")
	)
	(segment
		(start 214.68207 -140.17625)
		(end 212.366606 -142.491714)
		(width 0.127)
		(layer "In15.Cu")
		(net "PWRGD_FAIL_CPU0_GH_R")
	)
	(segment
		(start 184.6453 -145.776442)
		(end 184.066434 -145.776442)
		(width 0.127)
		(layer "In15.Cu")
		(net "PWRGD_FAIL_CPU0_GH_R")
	)
	(segment
		(start 183.567578 -146.275298)
		(end 183.567578 -147.160234)
		(width 0.127)
		(layer "In15.Cu")
		(net "PWRGD_FAIL_CPU0_GH_R")
	)
	(segment
		(start 184.066434 -145.776442)
		(end 183.567578 -146.275298)
		(width 0.127)
		(layer "In15.Cu")
		(net "PWRGD_FAIL_CPU0_GH_R")
	)
	(segment
		(start 260.992366 -135.415782)
		(end 252.785626 -135.415782)
		(width 0.127)
		(layer "In15.Cu")
		(net "PWRGD_FAIL_CPU0_GH_R")
	)
	(segment
		(start 286.176466 -130.224784)
		(end 266.183364 -130.224784)
		(width 0.127)
		(layer "In15.Cu")
		(net "PWRGD_FAIL_CPU0_GH_R")
	)
	(segment
		(start 187.930028 -142.491714)
		(end 184.6453 -145.776442)
		(width 0.127)
		(layer "In15.Cu")
		(net "PWRGD_FAIL_CPU0_GH_R")
	)
	(segment
		(start 252.785626 -135.415782)
		(end 248.025158 -140.17625)
		(width 0.127)
		(layer "In15.Cu")
		(net "PWRGD_FAIL_CPU0_GH_R")
	)
	(via
		(at 446.80378 -317.350648)
		(size 0.6604)
		(drill 0.3302)
		(layers "F.Cu" "B.Cu")
		(net "PWRGD_FAIL_CPU0_GH")
	)
	(segment
		(start 451.202298 -318.492886)
		(end 450.731636 -318.963548)
		(width 0.12954)
		(layer "B.Cu")
		(net "PWRGD_FAIL_CPU0_GH")
	)
	(segment
		(start 453.131682 -318.03467)
		(end 452.673466 -318.492886)
		(width 0.12954)
		(layer "B.Cu")
		(net "PWRGD_FAIL_CPU0_GH")
	)
	(segment
		(start 443.384686 -318.862202)
		(end 444.323978 -317.92291)
		(width 0.12954)
		(layer "B.Cu")
		(net "PWRGD_FAIL_CPU0_GH")
	)
	(segment
		(start 450.731636 -318.963548)
		(end 450.122798 -318.963548)
		(width 0.12954)
		(layer "B.Cu")
		(net "PWRGD_FAIL_CPU0_GH")
	)
	(segment
		(start 456.066398 -318.729868)
		(end 456.066398 -318.894968)
		(width 0.12954)
		(layer "B.Cu")
		(net "PWRGD_FAIL_CPU0_GH")
	)
	(segment
		(start 459.982316 -318.208406)
		(end 458.844396 -318.208406)
		(width 0.12954)
		(layer "B.Cu")
		(net "PWRGD_FAIL_CPU0_GH")
	)
	(segment
		(start 447.60134 -317.92291)
		(end 448.186556 -318.508126)
		(width 0.12954)
		(layer "B.Cu")
		(net "PWRGD_FAIL_CPU0_GH")
	)
	(segment
		(start 450.122798 -318.963548)
		(end 449.667376 -318.508126)
		(width 0.12954)
		(layer "B.Cu")
		(net "PWRGD_FAIL_CPU0_GH")
	)
	(segment
		(start 456.066398 -318.894968)
		(end 456.403456 -319.232026)
		(width 0.12954)
		(layer "B.Cu")
		(net "PWRGD_FAIL_CPU0_GH")
	)
	(segment
		(start 446.231518 -317.92291)
		(end 446.80378 -317.350648)
		(width 0.12954)
		(layer "B.Cu")
		(net "PWRGD_FAIL_CPU0_GH")
	)
	(segment
		(start 456.627738 -319.007744)
		(end 456.403456 -319.232026)
		(width 0.12954)
		(layer "B.Cu")
		(net "PWRGD_FAIL_CPU0_GH")
	)
	(segment
		(start 455.603356 -318.266826)
		(end 455.3712 -318.03467)
		(width 0.12954)
		(layer "B.Cu")
		(net "PWRGD_FAIL_CPU0_GH")
	)
	(segment
		(start 458.571092 -318.48171)
		(end 456.955398 -318.48171)
		(width 0.12954)
		(layer "B.Cu")
		(net "PWRGD_FAIL_CPU0_GH")
	)
	(segment
		(start 455.3712 -318.03467)
		(end 453.131682 -318.03467)
		(width 0.12954)
		(layer "B.Cu")
		(net "PWRGD_FAIL_CPU0_GH")
	)
	(segment
		(start 452.673466 -318.492886)
		(end 451.202298 -318.492886)
		(width 0.12954)
		(layer "B.Cu")
		(net "PWRGD_FAIL_CPU0_GH")
	)
	(segment
		(start 447.376042 -317.92291)
		(end 447.60134 -317.92291)
		(width 0.12954)
		(layer "B.Cu")
		(net "PWRGD_FAIL_CPU0_GH")
	)
	(segment
		(start 440.617356 -318.533526)
		(end 442.086238 -318.533526)
		(width 0.12954)
		(layer "B.Cu")
		(net "PWRGD_FAIL_CPU0_GH")
	)
	(segment
		(start 446.80378 -317.350648)
		(end 447.376042 -317.92291)
		(width 0.12954)
		(layer "B.Cu")
		(net "PWRGD_FAIL_CPU0_GH")
	)
	(segment
		(start 444.323978 -317.92291)
		(end 446.231518 -317.92291)
		(width 0.12954)
		(layer "B.Cu")
		(net "PWRGD_FAIL_CPU0_GH")
	)
	(segment
		(start 442.414914 -318.862202)
		(end 443.384686 -318.862202)
		(width 0.12954)
		(layer "B.Cu")
		(net "PWRGD_FAIL_CPU0_GH")
	)
	(segment
		(start 442.086238 -318.533526)
		(end 442.414914 -318.862202)
		(width 0.12954)
		(layer "B.Cu")
		(net "PWRGD_FAIL_CPU0_GH")
	)
	(segment
		(start 456.955398 -318.48171)
		(end 456.627738 -318.80937)
		(width 0.12954)
		(layer "B.Cu")
		(net "PWRGD_FAIL_CPU0_GH")
	)
	(segment
		(start 456.627738 -318.80937)
		(end 456.627738 -319.007744)
		(width 0.12954)
		(layer "B.Cu")
		(net "PWRGD_FAIL_CPU0_GH")
	)
	(segment
		(start 458.844396 -318.208406)
		(end 458.571092 -318.48171)
		(width 0.12954)
		(layer "B.Cu")
		(net "PWRGD_FAIL_CPU0_GH")
	)
	(segment
		(start 449.667376 -318.508126)
		(end 448.186556 -318.508126)
		(width 0.12954)
		(layer "B.Cu")
		(net "PWRGD_FAIL_CPU0_GH")
	)
	(segment
		(start 455.603356 -318.266826)
		(end 456.066398 -318.729868)
		(width 0.12954)
		(layer "B.Cu")
		(net "PWRGD_FAIL_CPU0_GH")
	)
	(via
		(at 433.089304 -315.476128)
		(size 0.6604)
		(drill 0.3302)
		(layers "F.Cu" "B.Cu")
		(net "PWRGD_FAIL_CPU0_EF_R1")
	)
	(segment
		(start 433.089304 -314.151772)
		(end 433.089304 -315.476128)
		(width 0.12954)
		(layer "B.Cu")
		(net "PWRGD_FAIL_CPU0_EF_R1")
	)
	(segment
		(start 433.035964 -312.222388)
		(end 431.39487 -312.222388)
		(width 0.12954)
		(layer "B.Cu")
		(net "PWRGD_FAIL_CPU0_EF_R1")
	)
	(segment
		(start 431.948844 -313.913266)
		(end 432.850798 -313.913266)
		(width 0.12954)
		(layer "B.Cu")
		(net "PWRGD_FAIL_CPU0_EF_R1")
	)
	(segment
		(start 433.077366 -312.26379)
		(end 433.035964 -312.222388)
		(width 0.12954)
		(layer "B.Cu")
		(net "PWRGD_FAIL_CPU0_EF_R1")
	)
	(segment
		(start 434.089302 -318.306196)
		(end 434.089302 -318.468756)
		(width 0.12954)
		(layer "B.Cu")
		(net "PWRGD_FAIL_CPU0_EF_R1")
	)
	(segment
		(start 431.39487 -312.222388)
		(end 431.266854 -312.350404)
		(width 0.12954)
		(layer "B.Cu")
		(net "PWRGD_FAIL_CPU0_EF_R1")
	)
	(segment
		(start 432.850798 -313.913266)
		(end 433.089304 -314.151772)
		(width 0.12954)
		(layer "B.Cu")
		(net "PWRGD_FAIL_CPU0_EF_R1")
	)
	(segment
		(start 433.089304 -315.476128)
		(end 433.089304 -316.51829)
		(width 0.12954)
		(layer "B.Cu")
		(net "PWRGD_FAIL_CPU0_EF_R1")
	)
	(segment
		(start 431.266854 -313.59729)
		(end 431.58283 -313.913266)
		(width 0.12954)
		(layer "B.Cu")
		(net "PWRGD_FAIL_CPU0_EF_R1")
	)
	(segment
		(start 433.273962 -316.702948)
		(end 433.776882 -317.205868)
		(width 0.12954)
		(layer "B.Cu")
		(net "PWRGD_FAIL_CPU0_EF_R1")
	)
	(segment
		(start 433.089304 -316.51829)
		(end 433.273962 -316.702948)
		(width 0.12954)
		(layer "B.Cu")
		(net "PWRGD_FAIL_CPU0_EF_R1")
	)
	(segment
		(start 431.58283 -313.913266)
		(end 431.948844 -313.913266)
		(width 0.12954)
		(layer "B.Cu")
		(net "PWRGD_FAIL_CPU0_EF_R1")
	)
	(segment
		(start 433.776882 -317.993776)
		(end 434.089302 -318.306196)
		(width 0.12954)
		(layer "B.Cu")
		(net "PWRGD_FAIL_CPU0_EF_R1")
	)
	(segment
		(start 431.266854 -312.350404)
		(end 431.266854 -313.59729)
		(width 0.12954)
		(layer "B.Cu")
		(net "PWRGD_FAIL_CPU0_EF_R1")
	)
	(segment
		(start 433.776882 -317.205868)
		(end 433.776882 -317.993776)
		(width 0.12954)
		(layer "B.Cu")
		(net "PWRGD_FAIL_CPU0_EF_R1")
	)
	(segment
		(start 181.355746 -119.375428)
		(end 181.755796 -119.775478)
		(width 0.12954)
		(layer "F.Cu")
		(net "PWRGD_FAIL_CPU0_EF_R")
	)
	(via
		(at 184.202578 -147.160234)
		(size 0.508)
		(drill 0.254)
		(layers "F.Cu" "B.Cu")
		(net "PWRGD_FAIL_CPU0_EF_R")
	)
	(via
		(at 429.41748 -193.218308)
		(size 0.508)
		(drill 0.254)
		(layers "F.Cu" "B.Cu")
		(net "PWRGD_FAIL_CPU0_EF_R")
	)
	(via
		(at 289.191954 -127.844296)
		(size 0.508)
		(drill 0.254)
		(layers "F.Cu" "B.Cu")
		(net "PWRGD_FAIL_CPU0_EF_R")
	)
	(via
		(at 393.78128 -176.926748)
		(size 0.508)
		(drill 0.254)
		(layers "F.Cu" "B.Cu")
		(net "PWRGD_FAIL_CPU0_EF_R")
	)
	(via
		(at 181.755796 -119.775478)
		(size 0.4572)
		(drill 0.254)
		(layers "F.Cu" "B.Cu")
		(net "PWRGD_FAIL_CPU0_EF_R")
	)
	(via
		(at 187.70092 -135.057388)
		(size 0.508)
		(drill 0.254)
		(layers "F.Cu" "B.Cu")
		(net "PWRGD_FAIL_CPU0_EF_R")
	)
	(segment
		(start 290.375086 -125.83033)
		(end 289.191954 -127.013462)
		(width 0.12954)
		(layer "B.Cu")
		(net "PWRGD_FAIL_CPU0_EF_R")
	)
	(segment
		(start 429.41748 -254.726948)
		(end 430.66208 -255.971548)
		(width 0.12954)
		(layer "B.Cu")
		(net "PWRGD_FAIL_CPU0_EF_R")
	)
	(segment
		(start 382.426718 -156.7053)
		(end 376.343672 -150.622254)
		(width 0.12954)
		(layer "B.Cu")
		(net "PWRGD_FAIL_CPU0_EF_R")
	)
	(segment
		(start 393.78128 -176.92624)
		(end 386.174742 -169.319702)
		(width 0.12954)
		(layer "B.Cu")
		(net "PWRGD_FAIL_CPU0_EF_R")
	)
	(segment
		(start 310.238902 -133.197092)
		(end 302.87214 -125.83033)
		(width 0.12954)
		(layer "B.Cu")
		(net "PWRGD_FAIL_CPU0_EF_R")
	)
	(segment
		(start 357.194866 -150.622254)
		(end 345.951302 -139.37869)
		(width 0.12954)
		(layer "B.Cu")
		(net "PWRGD_FAIL_CPU0_EF_R")
	)
	(segment
		(start 345.951302 -139.37869)
		(end 334.287368 -139.37869)
		(width 0.12954)
		(layer "B.Cu")
		(net "PWRGD_FAIL_CPU0_EF_R")
	)
	(segment
		(start 433.631594 -257.645662)
		(end 433.631594 -311.049924)
		(width 0.12954)
		(layer "B.Cu")
		(net "PWRGD_FAIL_CPU0_EF_R")
	)
	(segment
		(start 433.217828 -311.46369)
		(end 433.077366 -311.46369)
		(width 0.12954)
		(layer "B.Cu")
		(net "PWRGD_FAIL_CPU0_EF_R")
	)
	(segment
		(start 430.66208 -255.971548)
		(end 431.95748 -255.971548)
		(width 0.12954)
		(layer "B.Cu")
		(net "PWRGD_FAIL_CPU0_EF_R")
	)
	(segment
		(start 334.287368 -139.37869)
		(end 319.36436 -133.197092)
		(width 0.12954)
		(layer "B.Cu")
		(net "PWRGD_FAIL_CPU0_EF_R")
	)
	(segment
		(start 386.174742 -165.96741)
		(end 382.426718 -162.219386)
		(width 0.12954)
		(layer "B.Cu")
		(net "PWRGD_FAIL_CPU0_EF_R")
	)
	(segment
		(start 433.631594 -311.049924)
		(end 433.217828 -311.46369)
		(width 0.12954)
		(layer "B.Cu")
		(net "PWRGD_FAIL_CPU0_EF_R")
	)
	(segment
		(start 429.41748 -193.218308)
		(end 429.41748 -254.726948)
		(width 0.12954)
		(layer "B.Cu")
		(net "PWRGD_FAIL_CPU0_EF_R")
	)
	(segment
		(start 376.343672 -150.622254)
		(end 357.194866 -150.622254)
		(width 0.12954)
		(layer "B.Cu")
		(net "PWRGD_FAIL_CPU0_EF_R")
	)
	(segment
		(start 431.95748 -255.971548)
		(end 433.631594 -257.645662)
		(width 0.12954)
		(layer "B.Cu")
		(net "PWRGD_FAIL_CPU0_EF_R")
	)
	(segment
		(start 289.191954 -127.013462)
		(end 289.191954 -127.844296)
		(width 0.12954)
		(layer "B.Cu")
		(net "PWRGD_FAIL_CPU0_EF_R")
	)
	(segment
		(start 393.78128 -176.926748)
		(end 393.78128 -176.92624)
		(width 0.12954)
		(layer "B.Cu")
		(net "PWRGD_FAIL_CPU0_EF_R")
	)
	(segment
		(start 382.426718 -162.219386)
		(end 382.426718 -156.7053)
		(width 0.12954)
		(layer "B.Cu")
		(net "PWRGD_FAIL_CPU0_EF_R")
	)
	(segment
		(start 386.174742 -169.319702)
		(end 386.174742 -165.96741)
		(width 0.12954)
		(layer "B.Cu")
		(net "PWRGD_FAIL_CPU0_EF_R")
	)
	(segment
		(start 319.36436 -133.197092)
		(end 310.238902 -133.197092)
		(width 0.12954)
		(layer "B.Cu")
		(net "PWRGD_FAIL_CPU0_EF_R")
	)
	(segment
		(start 302.87214 -125.83033)
		(end 290.375086 -125.83033)
		(width 0.12954)
		(layer "B.Cu")
		(net "PWRGD_FAIL_CPU0_EF_R")
	)
	(segment
		(start 406.86355 -193.739008)
		(end 405.63419 -192.509648)
		(width 0.127)
		(layer "In2.Cu")
		(net "PWRGD_FAIL_CPU0_EF_R")
	)
	(segment
		(start 392.66368 -178.044348)
		(end 393.78128 -176.926748)
		(width 0.127)
		(layer "In2.Cu")
		(net "PWRGD_FAIL_CPU0_EF_R")
	)
	(segment
		(start 403.199346 -191.303148)
		(end 395.50848 -191.303148)
		(width 0.127)
		(layer "In2.Cu")
		(net "PWRGD_FAIL_CPU0_EF_R")
	)
	(segment
		(start 187.70092 -135.057388)
		(end 187.70092 -127.130302)
		(width 0.127)
		(layer "In2.Cu")
		(net "PWRGD_FAIL_CPU0_EF_R")
	)
	(segment
		(start 403.553168 -190.949326)
		(end 403.199346 -191.303148)
		(width 0.127)
		(layer "In2.Cu")
		(net "PWRGD_FAIL_CPU0_EF_R")
	)
	(segment
		(start 404.697184 -190.949326)
		(end 403.553168 -190.949326)
		(width 0.127)
		(layer "In2.Cu")
		(net "PWRGD_FAIL_CPU0_EF_R")
	)
	(segment
		(start 405.63419 -191.886332)
		(end 404.697184 -190.949326)
		(width 0.127)
		(layer "In2.Cu")
		(net "PWRGD_FAIL_CPU0_EF_R")
	)
	(segment
		(start 405.63419 -192.509648)
		(end 405.63419 -191.886332)
		(width 0.127)
		(layer "In2.Cu")
		(net "PWRGD_FAIL_CPU0_EF_R")
	)
	(segment
		(start 182.15356 -120.408954)
		(end 181.755796 -120.01119)
		(width 0.127)
		(layer "In2.Cu")
		(net "PWRGD_FAIL_CPU0_EF_R")
	)
	(segment
		(start 429.41748 -193.218308)
		(end 428.7647 -193.218308)
		(width 0.127)
		(layer "In2.Cu")
		(net "PWRGD_FAIL_CPU0_EF_R")
	)
	(segment
		(start 395.50848 -191.303148)
		(end 392.66368 -188.458348)
		(width 0.127)
		(layer "In2.Cu")
		(net "PWRGD_FAIL_CPU0_EF_R")
	)
	(segment
		(start 428.244 -193.739008)
		(end 406.86355 -193.739008)
		(width 0.127)
		(layer "In2.Cu")
		(net "PWRGD_FAIL_CPU0_EF_R")
	)
	(segment
		(start 181.755796 -120.01119)
		(end 181.755796 -119.775478)
		(width 0.127)
		(layer "In2.Cu")
		(net "PWRGD_FAIL_CPU0_EF_R")
	)
	(segment
		(start 187.70092 -127.130302)
		(end 182.15356 -121.582942)
		(width 0.127)
		(layer "In2.Cu")
		(net "PWRGD_FAIL_CPU0_EF_R")
	)
	(segment
		(start 392.66368 -188.458348)
		(end 392.66368 -178.044348)
		(width 0.127)
		(layer "In2.Cu")
		(net "PWRGD_FAIL_CPU0_EF_R")
	)
	(segment
		(start 428.7647 -193.218308)
		(end 428.244 -193.739008)
		(width 0.127)
		(layer "In2.Cu")
		(net "PWRGD_FAIL_CPU0_EF_R")
	)
	(segment
		(start 182.15356 -121.582942)
		(end 182.15356 -120.408954)
		(width 0.127)
		(layer "In2.Cu")
		(net "PWRGD_FAIL_CPU0_EF_R")
	)
	(segment
		(start 187.70092 -135.250682)
		(end 187.310014 -135.641588)
		(width 0.127)
		(layer "In11.Cu")
		(net "PWRGD_FAIL_CPU0_EF_R")
	)
	(segment
		(start 187.310014 -143.23441)
		(end 185.985404 -144.55902)
		(width 0.127)
		(layer "In11.Cu")
		(net "PWRGD_FAIL_CPU0_EF_R")
	)
	(segment
		(start 187.70092 -135.057388)
		(end 187.70092 -135.250682)
		(width 0.127)
		(layer "In11.Cu")
		(net "PWRGD_FAIL_CPU0_EF_R")
	)
	(segment
		(start 187.310014 -135.641588)
		(end 187.310014 -143.23441)
		(width 0.127)
		(layer "In11.Cu")
		(net "PWRGD_FAIL_CPU0_EF_R")
	)
	(segment
		(start 185.985404 -145.377408)
		(end 184.202578 -147.160234)
		(width 0.127)
		(layer "In11.Cu")
		(net "PWRGD_FAIL_CPU0_EF_R")
	)
	(segment
		(start 185.985404 -144.55902)
		(end 185.985404 -145.377408)
		(width 0.127)
		(layer "In11.Cu")
		(net "PWRGD_FAIL_CPU0_EF_R")
	)
	(segment
		(start 184.908444 -146.411442)
		(end 184.329578 -146.411442)
		(width 0.127)
		(layer "In15.Cu")
		(net "PWRGD_FAIL_CPU0_EF_R")
	)
	(segment
		(start 248.288302 -140.81125)
		(end 214.945214 -140.81125)
		(width 0.127)
		(layer "In15.Cu")
		(net "PWRGD_FAIL_CPU0_EF_R")
	)
	(segment
		(start 214.945214 -140.81125)
		(end 212.62975 -143.126714)
		(width 0.127)
		(layer "In15.Cu")
		(net "PWRGD_FAIL_CPU0_EF_R")
	)
	(segment
		(start 289.191954 -127.844296)
		(end 289.191954 -128.10744)
		(width 0.127)
		(layer "In15.Cu")
		(net "PWRGD_FAIL_CPU0_EF_R")
	)
	(segment
		(start 289.191954 -128.10744)
		(end 286.43961 -130.859784)
		(width 0.127)
		(layer "In15.Cu")
		(net "PWRGD_FAIL_CPU0_EF_R")
	)
	(segment
		(start 253.04877 -136.050782)
		(end 248.288302 -140.81125)
		(width 0.127)
		(layer "In15.Cu")
		(net "PWRGD_FAIL_CPU0_EF_R")
	)
	(segment
		(start 188.193172 -143.126714)
		(end 184.908444 -146.411442)
		(width 0.127)
		(layer "In15.Cu")
		(net "PWRGD_FAIL_CPU0_EF_R")
	)
	(segment
		(start 286.43961 -130.859784)
		(end 266.446508 -130.859784)
		(width 0.127)
		(layer "In15.Cu")
		(net "PWRGD_FAIL_CPU0_EF_R")
	)
	(segment
		(start 266.446508 -130.859784)
		(end 261.25551 -136.050782)
		(width 0.127)
		(layer "In15.Cu")
		(net "PWRGD_FAIL_CPU0_EF_R")
	)
	(segment
		(start 261.25551 -136.050782)
		(end 253.04877 -136.050782)
		(width 0.127)
		(layer "In15.Cu")
		(net "PWRGD_FAIL_CPU0_EF_R")
	)
	(segment
		(start 212.62975 -143.126714)
		(end 188.193172 -143.126714)
		(width 0.127)
		(layer "In15.Cu")
		(net "PWRGD_FAIL_CPU0_EF_R")
	)
	(segment
		(start 184.329578 -146.411442)
		(end 184.202578 -146.538442)
		(width 0.127)
		(layer "In15.Cu")
		(net "PWRGD_FAIL_CPU0_EF_R")
	)
	(segment
		(start 184.202578 -146.538442)
		(end 184.202578 -147.160234)
		(width 0.127)
		(layer "In15.Cu")
		(net "PWRGD_FAIL_CPU0_EF_R")
	)
	(via
		(at 421.9702 -318.02959)
		(size 0.6604)
		(drill 0.3302)
		(layers "F.Cu" "B.Cu")
		(net "PWRGD_FAIL_CPU0_EF")
	)
	(segment
		(start 433.073302 -318.468756)
		(end 432.806094 -318.468756)
		(width 0.12954)
		(layer "B.Cu")
		(net "PWRGD_FAIL_CPU0_EF")
	)
	(segment
		(start 421.002714 -318.612774)
		(end 420.58336 -319.032128)
		(width 0.12954)
		(layer "B.Cu")
		(net "PWRGD_FAIL_CPU0_EF")
	)
	(segment
		(start 416.231578 -316.97041)
		(end 414.780476 -318.421512)
		(width 0.12954)
		(layer "B.Cu")
		(net "PWRGD_FAIL_CPU0_EF")
	)
	(segment
		(start 418.795454 -319.402968)
		(end 418.399468 -319.006982)
		(width 0.12954)
		(layer "B.Cu")
		(net "PWRGD_FAIL_CPU0_EF")
	)
	(segment
		(start 433.073302 -318.468756)
		(end 433.273962 -318.268096)
		(width 0.12954)
		(layer "B.Cu")
		(net "PWRGD_FAIL_CPU0_EF")
	)
	(segment
		(start 420.58336 -319.529206)
		(end 419.945058 -320.167508)
		(width 0.12954)
		(layer "B.Cu")
		(net "PWRGD_FAIL_CPU0_EF")
	)
	(segment
		(start 420.58336 -319.032128)
		(end 420.58336 -319.529206)
		(width 0.12954)
		(layer "B.Cu")
		(net "PWRGD_FAIL_CPU0_EF")
	)
	(segment
		(start 413.45866 -318.421512)
		(end 413.287464 -318.592708)
		(width 0.12954)
		(layer "B.Cu")
		(net "PWRGD_FAIL_CPU0_EF")
	)
	(segment
		(start 427.7868 -319.240662)
		(end 426.726096 -319.240662)
		(width 0.12954)
		(layer "B.Cu")
		(net "PWRGD_FAIL_CPU0_EF")
	)
	(segment
		(start 421.226234 -318.612774)
		(end 421.002714 -318.612774)
		(width 0.12954)
		(layer "B.Cu")
		(net "PWRGD_FAIL_CPU0_EF")
	)
	(segment
		(start 419.398958 -320.167508)
		(end 418.795454 -319.564004)
		(width 0.12954)
		(layer "B.Cu")
		(net "PWRGD_FAIL_CPU0_EF")
	)
	(segment
		(start 425.99356 -318.508126)
		(end 425.555156 -318.508126)
		(width 0.12954)
		(layer "B.Cu")
		(net "PWRGD_FAIL_CPU0_EF")
	)
	(segment
		(start 433.273962 -318.268096)
		(end 433.273962 -317.503048)
		(width 0.12954)
		(layer "B.Cu")
		(net "PWRGD_FAIL_CPU0_EF")
	)
	(segment
		(start 421.9702 -318.02959)
		(end 421.809418 -318.02959)
		(width 0.12954)
		(layer "B.Cu")
		(net "PWRGD_FAIL_CPU0_EF")
	)
	(segment
		(start 425.07662 -318.02959)
		(end 425.555156 -318.508126)
		(width 0.12954)
		(layer "B.Cu")
		(net "PWRGD_FAIL_CPU0_EF")
	)
	(segment
		(start 429.817276 -318.580008)
		(end 428.447454 -318.580008)
		(width 0.12954)
		(layer "B.Cu")
		(net "PWRGD_FAIL_CPU0_EF")
	)
	(segment
		(start 411.914086 -318.592708)
		(end 411.829504 -318.508126)
		(width 0.12954)
		(layer "B.Cu")
		(net "PWRGD_FAIL_CPU0_EF")
	)
	(segment
		(start 432.806094 -318.468756)
		(end 432.255168 -317.91783)
		(width 0.12954)
		(layer "B.Cu")
		(net "PWRGD_FAIL_CPU0_EF")
	)
	(segment
		(start 428.447454 -318.580008)
		(end 427.7868 -319.240662)
		(width 0.12954)
		(layer "B.Cu")
		(net "PWRGD_FAIL_CPU0_EF")
	)
	(segment
		(start 411.829504 -318.508126)
		(end 410.492956 -318.508126)
		(width 0.12954)
		(layer "B.Cu")
		(net "PWRGD_FAIL_CPU0_EF")
	)
	(segment
		(start 421.809418 -318.02959)
		(end 421.226234 -318.612774)
		(width 0.12954)
		(layer "B.Cu")
		(net "PWRGD_FAIL_CPU0_EF")
	)
	(segment
		(start 418.399468 -319.006982)
		(end 418.399468 -317.259716)
		(width 0.12954)
		(layer "B.Cu")
		(net "PWRGD_FAIL_CPU0_EF")
	)
	(segment
		(start 418.110162 -316.97041)
		(end 416.231578 -316.97041)
		(width 0.12954)
		(layer "B.Cu")
		(net "PWRGD_FAIL_CPU0_EF")
	)
	(segment
		(start 414.780476 -318.421512)
		(end 413.45866 -318.421512)
		(width 0.12954)
		(layer "B.Cu")
		(net "PWRGD_FAIL_CPU0_EF")
	)
	(segment
		(start 413.287464 -318.592708)
		(end 411.914086 -318.592708)
		(width 0.12954)
		(layer "B.Cu")
		(net "PWRGD_FAIL_CPU0_EF")
	)
	(segment
		(start 432.255168 -317.91783)
		(end 430.479454 -317.91783)
		(width 0.12954)
		(layer "B.Cu")
		(net "PWRGD_FAIL_CPU0_EF")
	)
	(segment
		(start 419.945058 -320.167508)
		(end 419.398958 -320.167508)
		(width 0.12954)
		(layer "B.Cu")
		(net "PWRGD_FAIL_CPU0_EF")
	)
	(segment
		(start 418.399468 -317.259716)
		(end 418.110162 -316.97041)
		(width 0.12954)
		(layer "B.Cu")
		(net "PWRGD_FAIL_CPU0_EF")
	)
	(segment
		(start 430.479454 -317.91783)
		(end 429.817276 -318.580008)
		(width 0.12954)
		(layer "B.Cu")
		(net "PWRGD_FAIL_CPU0_EF")
	)
	(segment
		(start 426.726096 -319.240662)
		(end 425.99356 -318.508126)
		(width 0.12954)
		(layer "B.Cu")
		(net "PWRGD_FAIL_CPU0_EF")
	)
	(segment
		(start 421.9702 -318.02959)
		(end 425.07662 -318.02959)
		(width 0.12954)
		(layer "B.Cu")
		(net "PWRGD_FAIL_CPU0_EF")
	)
	(segment
		(start 418.795454 -319.564004)
		(end 418.795454 -319.402968)
		(width 0.12954)
		(layer "B.Cu")
		(net "PWRGD_FAIL_CPU0_EF")
	)
	(via
		(at 284.71368 -316.555628)
		(size 0.6604)
		(drill 0.3302)
		(layers "F.Cu" "B.Cu")
		(net "PWRGD_FAIL_CPU0_CD_R1")
	)
	(segment
		(start 286.275526 -314.633102)
		(end 285.601918 -315.30671)
		(width 0.12954)
		(layer "B.Cu")
		(net "PWRGD_FAIL_CPU0_CD_R1")
	)
	(segment
		(start 285.601918 -315.30671)
		(end 285.601918 -315.66739)
		(width 0.12954)
		(layer "B.Cu")
		(net "PWRGD_FAIL_CPU0_CD_R1")
	)
	(segment
		(start 283.675328 -319.176146)
		(end 284.475428 -318.376046)
		(width 0.12954)
		(layer "B.Cu")
		(net "PWRGD_FAIL_CPU0_CD_R1")
	)
	(segment
		(start 284.475428 -316.79388)
		(end 284.475428 -318.376046)
		(width 0.12954)
		(layer "B.Cu")
		(net "PWRGD_FAIL_CPU0_CD_R1")
	)
	(segment
		(start 286.275526 -314.266834)
		(end 286.275526 -314.633102)
		(width 0.12954)
		(layer "B.Cu")
		(net "PWRGD_FAIL_CPU0_CD_R1")
	)
	(segment
		(start 285.601918 -315.66739)
		(end 284.71368 -316.555628)
		(width 0.12954)
		(layer "B.Cu")
		(net "PWRGD_FAIL_CPU0_CD_R1")
	)
	(segment
		(start 288.376106 -314.266834)
		(end 286.275526 -314.266834)
		(width 0.12954)
		(layer "B.Cu")
		(net "PWRGD_FAIL_CPU0_CD_R1")
	)
	(segment
		(start 284.71368 -316.555628)
		(end 284.475428 -316.79388)
		(width 0.12954)
		(layer "B.Cu")
		(net "PWRGD_FAIL_CPU0_CD_R1")
	)
	(segment
		(start 283.675328 -319.392046)
		(end 283.675328 -319.176146)
		(width 0.12954)
		(layer "B.Cu")
		(net "PWRGD_FAIL_CPU0_CD_R1")
	)
	(segment
		(start 187.06592 -135.057388)
		(end 187.06592 -135.426958)
		(width 0.12954)
		(layer "F.Cu")
		(net "PWRGD_FAIL_CPU0_CD_R")
	)
	(segment
		(start 187.06592 -135.426958)
		(end 185.111644 -137.381234)
		(width 0.12954)
		(layer "F.Cu")
		(net "PWRGD_FAIL_CPU0_CD_R")
	)
	(segment
		(start 184.120536 -150.372572)
		(end 182.94096 -151.552148)
		(width 0.12954)
		(layer "F.Cu")
		(net "PWRGD_FAIL_CPU0_CD_R")
	)
	(segment
		(start 182.94096 -151.552148)
		(end 182.94096 -151.966168)
		(width 0.12954)
		(layer "F.Cu")
		(net "PWRGD_FAIL_CPU0_CD_R")
	)
	(segment
		(start 185.111644 -146.94154)
		(end 184.120536 -147.932648)
		(width 0.12954)
		(layer "F.Cu")
		(net "PWRGD_FAIL_CPU0_CD_R")
	)
	(segment
		(start 184.120536 -147.932648)
		(end 184.120536 -150.372572)
		(width 0.12954)
		(layer "F.Cu")
		(net "PWRGD_FAIL_CPU0_CD_R")
	)
	(segment
		(start 181.355746 -120.175528)
		(end 181.755796 -120.575578)
		(width 0.12954)
		(layer "F.Cu")
		(net "PWRGD_FAIL_CPU0_CD_R")
	)
	(segment
		(start 185.111644 -137.381234)
		(end 185.111644 -146.94154)
		(width 0.12954)
		(layer "F.Cu")
		(net "PWRGD_FAIL_CPU0_CD_R")
	)
	(via
		(at 181.755796 -120.575578)
		(size 0.4572)
		(drill 0.254)
		(layers "F.Cu" "B.Cu")
		(net "PWRGD_FAIL_CPU0_CD_R")
	)
	(via
		(at 187.06592 -135.057388)
		(size 0.508)
		(drill 0.254)
		(layers "F.Cu" "B.Cu")
		(net "PWRGD_FAIL_CPU0_CD_R")
	)
	(via
		(at 185.59526 -166.505128)
		(size 0.508)
		(drill 0.254)
		(layers "F.Cu" "B.Cu")
		(net "PWRGD_FAIL_CPU0_CD_R")
	)
	(via
		(at 182.94096 -151.966168)
		(size 0.508)
		(drill 0.254)
		(layers "F.Cu" "B.Cu")
		(net "PWRGD_FAIL_CPU0_CD_R")
	)
	(segment
		(start 260.22808 -188.629544)
		(end 260.22808 -194.342512)
		(width 0.12954)
		(layer "B.Cu")
		(net "PWRGD_FAIL_CPU0_CD_R")
	)
	(segment
		(start 260.557264 -194.671696)
		(end 260.557264 -252.90907)
		(width 0.12954)
		(layer "B.Cu")
		(net "PWRGD_FAIL_CPU0_CD_R")
	)
	(segment
		(start 275.375878 -260.609588)
		(end 276.6187 -260.609588)
		(width 0.12954)
		(layer "B.Cu")
		(net "PWRGD_FAIL_CPU0_CD_R")
	)
	(segment
		(start 280.13914 -260.668008)
		(end 280.77668 -261.305548)
		(width 0.12954)
		(layer "B.Cu")
		(net "PWRGD_FAIL_CPU0_CD_R")
	)
	(segment
		(start 287.649158 -312.63463)
		(end 288.376106 -313.361578)
		(width 0.12954)
		(layer "B.Cu")
		(net "PWRGD_FAIL_CPU0_CD_R")
	)
	(segment
		(start 285.029402 -312.63463)
		(end 287.649158 -312.63463)
		(width 0.12954)
		(layer "B.Cu")
		(net "PWRGD_FAIL_CPU0_CD_R")
	)
	(segment
		(start 274.987258 -260.220968)
		(end 275.375878 -260.609588)
		(width 0.12954)
		(layer "B.Cu")
		(net "PWRGD_FAIL_CPU0_CD_R")
	)
	(segment
		(start 185.59526 -166.505128)
		(end 186.23915 -167.149018)
		(width 0.12954)
		(layer "B.Cu")
		(net "PWRGD_FAIL_CPU0_CD_R")
	)
	(segment
		(start 245.465854 -173.867318)
		(end 260.22808 -188.629544)
		(width 0.12954)
		(layer "B.Cu")
		(net "PWRGD_FAIL_CPU0_CD_R")
	)
	(segment
		(start 274.306538 -257.13817)
		(end 274.987258 -257.81889)
		(width 0.12954)
		(layer "B.Cu")
		(net "PWRGD_FAIL_CPU0_CD_R")
	)
	(segment
		(start 225.89109 -167.149018)
		(end 232.60939 -173.867318)
		(width 0.12954)
		(layer "B.Cu")
		(net "PWRGD_FAIL_CPU0_CD_R")
	)
	(segment
		(start 284.24632 -275.067268)
		(end 284.49524 -275.316188)
		(width 0.12954)
		(layer "B.Cu")
		(net "PWRGD_FAIL_CPU0_CD_R")
	)
	(segment
		(start 280.77668 -261.305548)
		(end 280.77668 -269.773908)
		(width 0.12954)
		(layer "B.Cu")
		(net "PWRGD_FAIL_CPU0_CD_R")
	)
	(segment
		(start 276.67712 -260.668008)
		(end 280.13914 -260.668008)
		(width 0.12954)
		(layer "B.Cu")
		(net "PWRGD_FAIL_CPU0_CD_R")
	)
	(segment
		(start 186.23915 -167.149018)
		(end 225.89109 -167.149018)
		(width 0.12954)
		(layer "B.Cu")
		(net "PWRGD_FAIL_CPU0_CD_R")
	)
	(segment
		(start 283.22524 -275.067268)
		(end 284.24632 -275.067268)
		(width 0.12954)
		(layer "B.Cu")
		(net "PWRGD_FAIL_CPU0_CD_R")
	)
	(segment
		(start 274.987258 -257.81889)
		(end 274.987258 -260.220968)
		(width 0.12954)
		(layer "B.Cu")
		(net "PWRGD_FAIL_CPU0_CD_R")
	)
	(segment
		(start 264.786364 -257.13817)
		(end 274.306538 -257.13817)
		(width 0.12954)
		(layer "B.Cu")
		(net "PWRGD_FAIL_CPU0_CD_R")
	)
	(segment
		(start 284.49524 -275.316188)
		(end 284.49524 -312.100468)
		(width 0.12954)
		(layer "B.Cu")
		(net "PWRGD_FAIL_CPU0_CD_R")
	)
	(segment
		(start 284.49524 -312.100468)
		(end 285.029402 -312.63463)
		(width 0.12954)
		(layer "B.Cu")
		(net "PWRGD_FAIL_CPU0_CD_R")
	)
	(segment
		(start 281.75712 -270.335248)
		(end 283.09062 -271.668748)
		(width 0.12954)
		(layer "B.Cu")
		(net "PWRGD_FAIL_CPU0_CD_R")
	)
	(segment
		(start 280.77668 -269.773908)
		(end 281.33802 -270.335248)
		(width 0.12954)
		(layer "B.Cu")
		(net "PWRGD_FAIL_CPU0_CD_R")
	)
	(segment
		(start 232.60939 -173.867318)
		(end 245.465854 -173.867318)
		(width 0.12954)
		(layer "B.Cu")
		(net "PWRGD_FAIL_CPU0_CD_R")
	)
	(segment
		(start 288.376106 -313.361578)
		(end 288.376106 -313.466734)
		(width 0.12954)
		(layer "B.Cu")
		(net "PWRGD_FAIL_CPU0_CD_R")
	)
	(segment
		(start 260.22808 -194.342512)
		(end 260.557264 -194.671696)
		(width 0.12954)
		(layer "B.Cu")
		(net "PWRGD_FAIL_CPU0_CD_R")
	)
	(segment
		(start 276.6187 -260.609588)
		(end 276.67712 -260.668008)
		(width 0.12954)
		(layer "B.Cu")
		(net "PWRGD_FAIL_CPU0_CD_R")
	)
	(segment
		(start 260.557264 -252.90907)
		(end 264.786364 -257.13817)
		(width 0.12954)
		(layer "B.Cu")
		(net "PWRGD_FAIL_CPU0_CD_R")
	)
	(segment
		(start 283.09062 -274.932648)
		(end 283.22524 -275.067268)
		(width 0.12954)
		(layer "B.Cu")
		(net "PWRGD_FAIL_CPU0_CD_R")
	)
	(segment
		(start 283.09062 -271.668748)
		(end 283.09062 -274.932648)
		(width 0.12954)
		(layer "B.Cu")
		(net "PWRGD_FAIL_CPU0_CD_R")
	)
	(segment
		(start 281.33802 -270.335248)
		(end 281.75712 -270.335248)
		(width 0.12954)
		(layer "B.Cu")
		(net "PWRGD_FAIL_CPU0_CD_R")
	)
	(segment
		(start 182.8038 -122.837448)
		(end 181.755796 -121.789444)
		(width 0.127)
		(layer "In2.Cu")
		(net "PWRGD_FAIL_CPU0_CD_R")
	)
	(segment
		(start 182.8038 -122.956828)
		(end 182.8038 -122.837448)
		(width 0.127)
		(layer "In2.Cu")
		(net "PWRGD_FAIL_CPU0_CD_R")
	)
	(segment
		(start 181.755796 -121.789444)
		(end 181.755796 -120.575578)
		(width 0.127)
		(layer "In2.Cu")
		(net "PWRGD_FAIL_CPU0_CD_R")
	)
	(segment
		(start 187.26912 -127.422148)
		(end 182.8038 -122.956828)
		(width 0.127)
		(layer "In2.Cu")
		(net "PWRGD_FAIL_CPU0_CD_R")
	)
	(segment
		(start 187.26912 -134.854188)
		(end 187.26912 -127.422148)
		(width 0.127)
		(layer "In2.Cu")
		(net "PWRGD_FAIL_CPU0_CD_R")
	)
	(segment
		(start 187.06592 -135.057388)
		(end 187.26912 -134.854188)
		(width 0.127)
		(layer "In2.Cu")
		(net "PWRGD_FAIL_CPU0_CD_R")
	)
	(segment
		(start 185.59526 -162.070288)
		(end 182.94096 -159.415988)
		(width 0.127)
		(layer "In11.Cu")
		(net "PWRGD_FAIL_CPU0_CD_R")
	)
	(segment
		(start 185.59526 -166.505128)
		(end 185.59526 -162.070288)
		(width 0.127)
		(layer "In11.Cu")
		(net "PWRGD_FAIL_CPU0_CD_R")
	)
	(segment
		(start 182.94096 -159.415988)
		(end 182.94096 -151.966168)
		(width 0.127)
		(layer "In11.Cu")
		(net "PWRGD_FAIL_CPU0_CD_R")
	)
	(via
		(at 280.568654 -316.136274)
		(size 0.6604)
		(drill 0.3302)
		(layers "F.Cu" "B.Cu")
		(net "PWRGD_FAIL_CPU0_CD")
	)
	(segment
		(start 274.83562 -317.876174)
		(end 274.499324 -317.539878)
		(width 0.12954)
		(layer "B.Cu")
		(net "PWRGD_FAIL_CPU0_CD")
	)
	(segment
		(start 260.557264 -319.263776)
		(end 260.767576 -319.474088)
		(width 0.12954)
		(layer "B.Cu")
		(net "PWRGD_FAIL_CPU0_CD")
	)
	(segment
		(start 265.289792 -317.46317)
		(end 266.97178 -317.46317)
		(width 0.12954)
		(layer "B.Cu")
		(net "PWRGD_FAIL_CPU0_CD")
	)
	(segment
		(start 282.981908 -318.54648)
		(end 283.152342 -318.376046)
		(width 0.12954)
		(layer "B.Cu")
		(net "PWRGD_FAIL_CPU0_CD")
	)
	(segment
		(start 260.767576 -319.474088)
		(end 261.1628 -319.474088)
		(width 0.12954)
		(layer "B.Cu")
		(net "PWRGD_FAIL_CPU0_CD")
	)
	(segment
		(start 282.423616 -318.54648)
		(end 282.981908 -318.54648)
		(width 0.12954)
		(layer "B.Cu")
		(net "PWRGD_FAIL_CPU0_CD")
	)
	(segment
		(start 261.25424 -319.565528)
		(end 262.03402 -319.565528)
		(width 0.12954)
		(layer "B.Cu")
		(net "PWRGD_FAIL_CPU0_CD")
	)
	(segment
		(start 266.97178 -317.46317)
		(end 267.336016 -317.827406)
		(width 0.12954)
		(layer "B.Cu")
		(net "PWRGD_FAIL_CPU0_CD")
	)
	(segment
		(start 271.850358 -318.633348)
		(end 267.43152 -318.633348)
		(width 0.12954)
		(layer "B.Cu")
		(net "PWRGD_FAIL_CPU0_CD")
	)
	(segment
		(start 274.83562 -318.586358)
		(end 274.83562 -317.876174)
		(width 0.12954)
		(layer "B.Cu")
		(net "PWRGD_FAIL_CPU0_CD")
	)
	(segment
		(start 280.3017 -317.389002)
		(end 280.3017 -316.403228)
		(width 0.12954)
		(layer "B.Cu")
		(net "PWRGD_FAIL_CPU0_CD")
	)
	(segment
		(start 261.1628 -319.474088)
		(end 261.25424 -319.565528)
		(width 0.12954)
		(layer "B.Cu")
		(net "PWRGD_FAIL_CPU0_CD")
	)
	(segment
		(start 280.3017 -316.403228)
		(end 280.568654 -316.136274)
		(width 0.12954)
		(layer "B.Cu")
		(net "PWRGD_FAIL_CPU0_CD")
	)
	(segment
		(start 280.568654 -316.136274)
		(end 280.893266 -316.136274)
		(width 0.12954)
		(layer "B.Cu")
		(net "PWRGD_FAIL_CPU0_CD")
	)
	(segment
		(start 274.83562 -318.586358)
		(end 279.104344 -318.586358)
		(width 0.12954)
		(layer "B.Cu")
		(net "PWRGD_FAIL_CPU0_CD")
	)
	(segment
		(start 282.423616 -317.666624)
		(end 282.423616 -318.54648)
		(width 0.12954)
		(layer "B.Cu")
		(net "PWRGD_FAIL_CPU0_CD")
	)
	(segment
		(start 264.34669 -318.406272)
		(end 265.289792 -317.46317)
		(width 0.12954)
		(layer "B.Cu")
		(net "PWRGD_FAIL_CPU0_CD")
	)
	(segment
		(start 263.193276 -318.406272)
		(end 264.34669 -318.406272)
		(width 0.12954)
		(layer "B.Cu")
		(net "PWRGD_FAIL_CPU0_CD")
	)
	(segment
		(start 267.43152 -318.633348)
		(end 267.336016 -318.537844)
		(width 0.12954)
		(layer "B.Cu")
		(net "PWRGD_FAIL_CPU0_CD")
	)
	(segment
		(start 267.336016 -317.827406)
		(end 267.336016 -318.537844)
		(width 0.12954)
		(layer "B.Cu")
		(net "PWRGD_FAIL_CPU0_CD")
	)
	(segment
		(start 280.893266 -316.136274)
		(end 282.423616 -317.666624)
		(width 0.12954)
		(layer "B.Cu")
		(net "PWRGD_FAIL_CPU0_CD")
	)
	(segment
		(start 274.499324 -317.539878)
		(end 272.943828 -317.539878)
		(width 0.12954)
		(layer "B.Cu")
		(net "PWRGD_FAIL_CPU0_CD")
	)
	(segment
		(start 279.104344 -318.586358)
		(end 280.3017 -317.389002)
		(width 0.12954)
		(layer "B.Cu")
		(net "PWRGD_FAIL_CPU0_CD")
	)
	(segment
		(start 262.03402 -319.565528)
		(end 263.193276 -318.406272)
		(width 0.12954)
		(layer "B.Cu")
		(net "PWRGD_FAIL_CPU0_CD")
	)
	(segment
		(start 272.943828 -317.539878)
		(end 271.850358 -318.633348)
		(width 0.12954)
		(layer "B.Cu")
		(net "PWRGD_FAIL_CPU0_CD")
	)
	(segment
		(start 283.152342 -318.376046)
		(end 283.675328 -318.376046)
		(width 0.12954)
		(layer "B.Cu")
		(net "PWRGD_FAIL_CPU0_CD")
	)
	(via
		(at 312.039 -315.493908)
		(size 0.6604)
		(drill 0.3302)
		(layers "F.Cu" "B.Cu")
		(net "PWRGD_FAIL_CPU0_AB_R1")
	)
	(segment
		(start 312.592974 -316.66561)
		(end 312.592974 -316.047882)
		(width 0.12954)
		(layer "B.Cu")
		(net "PWRGD_FAIL_CPU0_AB_R1")
	)
	(segment
		(start 310.843422 -314.950094)
		(end 310.843422 -315.927994)
		(width 0.12954)
		(layer "B.Cu")
		(net "PWRGD_FAIL_CPU0_AB_R1")
	)
	(segment
		(start 310.843422 -314.950094)
		(end 308.901846 -314.950094)
		(width 0.12954)
		(layer "B.Cu")
		(net "PWRGD_FAIL_CPU0_AB_R1")
	)
	(segment
		(start 311.76468 -315.493908)
		(end 311.330594 -315.927994)
		(width 0.12954)
		(layer "B.Cu")
		(net "PWRGD_FAIL_CPU0_AB_R1")
	)
	(segment
		(start 311.330594 -315.927994)
		(end 310.843422 -315.927994)
		(width 0.12954)
		(layer "B.Cu")
		(net "PWRGD_FAIL_CPU0_AB_R1")
	)
	(segment
		(start 312.039 -315.493908)
		(end 311.76468 -315.493908)
		(width 0.12954)
		(layer "B.Cu")
		(net "PWRGD_FAIL_CPU0_AB_R1")
	)
	(segment
		(start 312.592974 -316.047882)
		(end 312.039 -315.493908)
		(width 0.12954)
		(layer "B.Cu")
		(net "PWRGD_FAIL_CPU0_AB_R1")
	)
	(segment
		(start 184.955688 -122.175524)
		(end 184.555638 -121.775474)
		(width 0.12954)
		(layer "F.Cu")
		(net "PWRGD_FAIL_CPU0_AB_R")
	)
	(segment
		(start 185.676032 -147.008088)
		(end 184.630314 -148.053806)
		(width 0.12954)
		(layer "F.Cu")
		(net "PWRGD_FAIL_CPU0_AB_R")
	)
	(segment
		(start 185.676032 -138.04519)
		(end 185.676032 -147.008088)
		(width 0.12954)
		(layer "F.Cu")
		(net "PWRGD_FAIL_CPU0_AB_R")
	)
	(segment
		(start 184.630314 -148.053806)
		(end 184.630314 -151.389334)
		(width 0.12954)
		(layer "F.Cu")
		(net "PWRGD_FAIL_CPU0_AB_R")
	)
	(segment
		(start 184.43194 -151.587708)
		(end 183.82488 -151.587708)
		(width 0.12954)
		(layer "F.Cu")
		(net "PWRGD_FAIL_CPU0_AB_R")
	)
	(segment
		(start 183.82488 -151.587708)
		(end 183.7563 -151.656288)
		(width 0.12954)
		(layer "F.Cu")
		(net "PWRGD_FAIL_CPU0_AB_R")
	)
	(segment
		(start 184.981088 -122.175524)
		(end 184.955688 -122.175524)
		(width 0.12954)
		(layer "F.Cu")
		(net "PWRGD_FAIL_CPU0_AB_R")
	)
	(segment
		(start 188.17336 -132.583428)
		(end 188.17336 -135.547862)
		(width 0.12954)
		(layer "F.Cu")
		(net "PWRGD_FAIL_CPU0_AB_R")
	)
	(segment
		(start 188.17336 -135.547862)
		(end 185.676032 -138.04519)
		(width 0.12954)
		(layer "F.Cu")
		(net "PWRGD_FAIL_CPU0_AB_R")
	)
	(segment
		(start 184.630314 -151.389334)
		(end 184.43194 -151.587708)
		(width 0.12954)
		(layer "F.Cu")
		(net "PWRGD_FAIL_CPU0_AB_R")
	)
	(via
		(at 184.981088 -122.175524)
		(size 0.4572)
		(drill 0.254)
		(layers "F.Cu" "B.Cu")
		(net "PWRGD_FAIL_CPU0_AB_R")
	)
	(via
		(at 183.7563 -151.656288)
		(size 0.762)
		(drill 0.254)
		(layers "F.Cu" "B.Cu")
		(net "PWRGD_FAIL_CPU0_AB_R")
	)
	(via
		(at 182.67426 -164.247068)
		(size 0.508)
		(drill 0.254)
		(layers "F.Cu" "B.Cu")
		(net "PWRGD_FAIL_CPU0_AB_R")
	)
	(via
		(at 188.17336 -132.583428)
		(size 0.508)
		(drill 0.254)
		(layers "F.Cu" "B.Cu")
		(net "PWRGD_FAIL_CPU0_AB_R")
	)
	(segment
		(start 284.458918 -270.01597)
		(end 284.598618 -270.15567)
		(width 0.12954)
		(layer "B.Cu")
		(net "PWRGD_FAIL_CPU0_AB_R")
	)
	(segment
		(start 245.770146 -173.133258)
		(end 268.246098 -195.60921)
		(width 0.12954)
		(layer "B.Cu")
		(net "PWRGD_FAIL_CPU0_AB_R")
	)
	(segment
		(start 182.67426 -164.247068)
		(end 184.68848 -164.247068)
		(width 0.12954)
		(layer "B.Cu")
		(net "PWRGD_FAIL_CPU0_AB_R")
	)
	(segment
		(start 284.598618 -274.58797)
		(end 288.022538 -278.01189)
		(width 0.12954)
		(layer "B.Cu")
		(net "PWRGD_FAIL_CPU0_AB_R")
	)
	(segment
		(start 295.736518 -279.31999)
		(end 295.787318 -279.37079)
		(width 0.12954)
		(layer "B.Cu")
		(net "PWRGD_FAIL_CPU0_AB_R")
	)
	(segment
		(start 232.913682 -173.133258)
		(end 245.770146 -173.133258)
		(width 0.12954)
		(layer "B.Cu")
		(net "PWRGD_FAIL_CPU0_AB_R")
	)
	(segment
		(start 289.124898 -278.01189)
		(end 290.514278 -279.40127)
		(width 0.12954)
		(layer "B.Cu")
		(net "PWRGD_FAIL_CPU0_AB_R")
	)
	(segment
		(start 186.85637 -166.414958)
		(end 226.195382 -166.414958)
		(width 0.12954)
		(layer "B.Cu")
		(net "PWRGD_FAIL_CPU0_AB_R")
	)
	(segment
		(start 310.488838 -280.52903)
		(end 310.843422 -280.883614)
		(width 0.12954)
		(layer "B.Cu")
		(net "PWRGD_FAIL_CPU0_AB_R")
	)
	(segment
		(start 277.400258 -259.15493)
		(end 278.764238 -259.15493)
		(width 0.12954)
		(layer "B.Cu")
		(net "PWRGD_FAIL_CPU0_AB_R")
	)
	(segment
		(start 271.184878 -256.34061)
		(end 275.332698 -256.34061)
		(width 0.12954)
		(layer "B.Cu")
		(net "PWRGD_FAIL_CPU0_AB_R")
	)
	(segment
		(start 299.693838 -278.96439)
		(end 303.016158 -278.96439)
		(width 0.12954)
		(layer "B.Cu")
		(net "PWRGD_FAIL_CPU0_AB_R")
	)
	(segment
		(start 268.246098 -195.60921)
		(end 268.246098 -253.40183)
		(width 0.12954)
		(layer "B.Cu")
		(net "PWRGD_FAIL_CPU0_AB_R")
	)
	(segment
		(start 282.304998 -259.94233)
		(end 282.304998 -269.58163)
		(width 0.12954)
		(layer "B.Cu")
		(net "PWRGD_FAIL_CPU0_AB_R")
	)
	(segment
		(start 299.287438 -279.37079)
		(end 299.693838 -278.96439)
		(width 0.12954)
		(layer "B.Cu")
		(net "PWRGD_FAIL_CPU0_AB_R")
	)
	(segment
		(start 282.739338 -270.01597)
		(end 284.458918 -270.01597)
		(width 0.12954)
		(layer "B.Cu")
		(net "PWRGD_FAIL_CPU0_AB_R")
	)
	(segment
		(start 310.843422 -280.883614)
		(end 310.843422 -314.149994)
		(width 0.12954)
		(layer "B.Cu")
		(net "PWRGD_FAIL_CPU0_AB_R")
	)
	(segment
		(start 282.304998 -269.58163)
		(end 282.739338 -270.01597)
		(width 0.12954)
		(layer "B.Cu")
		(net "PWRGD_FAIL_CPU0_AB_R")
	)
	(segment
		(start 184.955688 -122.896884)
		(end 188.13272 -126.073916)
		(width 0.12954)
		(layer "B.Cu")
		(net "PWRGD_FAIL_CPU0_AB_R")
	)
	(segment
		(start 307.654198 -280.52903)
		(end 310.488838 -280.52903)
		(width 0.12954)
		(layer "B.Cu")
		(net "PWRGD_FAIL_CPU0_AB_R")
	)
	(segment
		(start 281.329638 -258.96697)
		(end 282.304998 -259.94233)
		(width 0.12954)
		(layer "B.Cu")
		(net "PWRGD_FAIL_CPU0_AB_R")
	)
	(segment
		(start 288.022538 -278.01189)
		(end 289.124898 -278.01189)
		(width 0.12954)
		(layer "B.Cu")
		(net "PWRGD_FAIL_CPU0_AB_R")
	)
	(segment
		(start 295.787318 -279.37079)
		(end 299.287438 -279.37079)
		(width 0.12954)
		(layer "B.Cu")
		(net "PWRGD_FAIL_CPU0_AB_R")
	)
	(segment
		(start 184.955688 -122.200924)
		(end 184.955688 -122.896884)
		(width 0.12954)
		(layer "B.Cu")
		(net "PWRGD_FAIL_CPU0_AB_R")
	)
	(segment
		(start 292.294818 -278.95931)
		(end 293.036498 -278.95931)
		(width 0.12954)
		(layer "B.Cu")
		(net "PWRGD_FAIL_CPU0_AB_R")
	)
	(segment
		(start 290.514278 -279.40127)
		(end 291.852858 -279.40127)
		(width 0.12954)
		(layer "B.Cu")
		(net "PWRGD_FAIL_CPU0_AB_R")
	)
	(segment
		(start 188.13272 -126.073916)
		(end 188.13272 -132.542788)
		(width 0.12954)
		(layer "B.Cu")
		(net "PWRGD_FAIL_CPU0_AB_R")
	)
	(segment
		(start 291.852858 -279.40127)
		(end 292.294818 -278.95931)
		(width 0.12954)
		(layer "B.Cu")
		(net "PWRGD_FAIL_CPU0_AB_R")
	)
	(segment
		(start 184.68848 -164.247068)
		(end 186.85637 -166.414958)
		(width 0.12954)
		(layer "B.Cu")
		(net "PWRGD_FAIL_CPU0_AB_R")
	)
	(segment
		(start 184.981088 -122.175524)
		(end 184.955688 -122.200924)
		(width 0.12954)
		(layer "B.Cu")
		(net "PWRGD_FAIL_CPU0_AB_R")
	)
	(segment
		(start 277.059898 -258.06781)
		(end 277.059898 -258.81457)
		(width 0.12954)
		(layer "B.Cu")
		(net "PWRGD_FAIL_CPU0_AB_R")
	)
	(segment
		(start 293.036498 -278.95931)
		(end 293.397178 -279.31999)
		(width 0.12954)
		(layer "B.Cu")
		(net "PWRGD_FAIL_CPU0_AB_R")
	)
	(segment
		(start 226.195382 -166.414958)
		(end 232.913682 -173.133258)
		(width 0.12954)
		(layer "B.Cu")
		(net "PWRGD_FAIL_CPU0_AB_R")
	)
	(segment
		(start 293.397178 -279.31999)
		(end 295.736518 -279.31999)
		(width 0.12954)
		(layer "B.Cu")
		(net "PWRGD_FAIL_CPU0_AB_R")
	)
	(segment
		(start 278.952198 -258.96697)
		(end 281.329638 -258.96697)
		(width 0.12954)
		(layer "B.Cu")
		(net "PWRGD_FAIL_CPU0_AB_R")
	)
	(segment
		(start 303.734978 -279.68321)
		(end 306.808378 -279.68321)
		(width 0.12954)
		(layer "B.Cu")
		(net "PWRGD_FAIL_CPU0_AB_R")
	)
	(segment
		(start 284.598618 -270.15567)
		(end 284.598618 -274.58797)
		(width 0.12954)
		(layer "B.Cu")
		(net "PWRGD_FAIL_CPU0_AB_R")
	)
	(segment
		(start 277.059898 -258.81457)
		(end 277.400258 -259.15493)
		(width 0.12954)
		(layer "B.Cu")
		(net "PWRGD_FAIL_CPU0_AB_R")
	)
	(segment
		(start 303.016158 -278.96439)
		(end 303.734978 -279.68321)
		(width 0.12954)
		(layer "B.Cu")
		(net "PWRGD_FAIL_CPU0_AB_R")
	)
	(segment
		(start 278.764238 -259.15493)
		(end 278.952198 -258.96697)
		(width 0.12954)
		(layer "B.Cu")
		(net "PWRGD_FAIL_CPU0_AB_R")
	)
	(segment
		(start 188.13272 -132.542788)
		(end 188.17336 -132.583428)
		(width 0.12954)
		(layer "B.Cu")
		(net "PWRGD_FAIL_CPU0_AB_R")
	)
	(segment
		(start 275.332698 -256.34061)
		(end 277.059898 -258.06781)
		(width 0.12954)
		(layer "B.Cu")
		(net "PWRGD_FAIL_CPU0_AB_R")
	)
	(segment
		(start 268.246098 -253.40183)
		(end 271.184878 -256.34061)
		(width 0.12954)
		(layer "B.Cu")
		(net "PWRGD_FAIL_CPU0_AB_R")
	)
	(segment
		(start 306.808378 -279.68321)
		(end 307.654198 -280.52903)
		(width 0.12954)
		(layer "B.Cu")
		(net "PWRGD_FAIL_CPU0_AB_R")
	)
	(segment
		(start 183.7563 -160.373568)
		(end 183.7563 -151.656288)
		(width 0.127)
		(layer "In2.Cu")
		(net "PWRGD_FAIL_CPU0_AB_R")
	)
	(segment
		(start 183.22544 -163.695888)
		(end 183.22544 -160.904428)
		(width 0.127)
		(layer "In2.Cu")
		(net "PWRGD_FAIL_CPU0_AB_R")
	)
	(segment
		(start 183.22544 -160.904428)
		(end 183.7563 -160.373568)
		(width 0.127)
		(layer "In2.Cu")
		(net "PWRGD_FAIL_CPU0_AB_R")
	)
	(segment
		(start 182.67426 -164.247068)
		(end 183.22544 -163.695888)
		(width 0.127)
		(layer "In2.Cu")
		(net "PWRGD_FAIL_CPU0_AB_R")
	)
	(via
		(at 307.28666 -319.893442)
		(size 0.6604)
		(drill 0.3302)
		(layers "F.Cu" "B.Cu")
		(net "PWRGD_FAIL_CPU0_AB")
	)
	(segment
		(start 298.802298 -319.502028)
		(end 297.903646 -318.603376)
		(width 0.12954)
		(layer "B.Cu")
		(net "PWRGD_FAIL_CPU0_AB")
	)
	(segment
		(start 301.97425 -318.441578)
		(end 300.508162 -318.441578)
		(width 0.12954)
		(layer "B.Cu")
		(net "PWRGD_FAIL_CPU0_AB")
	)
	(segment
		(start 292.3286 -319.453768)
		(end 291.804598 -319.97777)
		(width 0.12954)
		(layer "B.Cu")
		(net "PWRGD_FAIL_CPU0_AB")
	)
	(segment
		(start 297.867324 -318.603376)
		(end 297.852846 -318.588898)
		(width 0.12954)
		(layer "B.Cu")
		(net "PWRGD_FAIL_CPU0_AB")
	)
	(segment
		(start 307.28666 -319.893442)
		(end 307.463698 -319.893442)
		(width 0.12954)
		(layer "B.Cu")
		(net "PWRGD_FAIL_CPU0_AB")
	)
	(segment
		(start 297.903646 -318.603376)
		(end 297.867324 -318.603376)
		(width 0.12954)
		(layer "B.Cu")
		(net "PWRGD_FAIL_CPU0_AB")
	)
	(segment
		(start 306.128166 -319.893442)
		(end 305.10607 -318.871346)
		(width 0.12954)
		(layer "B.Cu")
		(net "PWRGD_FAIL_CPU0_AB")
	)
	(segment
		(start 291.804598 -319.97777)
		(end 291.048948 -319.97777)
		(width 0.12954)
		(layer "B.Cu")
		(net "PWRGD_FAIL_CPU0_AB")
	)
	(segment
		(start 296.186352 -317.522352)
		(end 295.395396 -318.313308)
		(width 0.12954)
		(layer "B.Cu")
		(net "PWRGD_FAIL_CPU0_AB")
	)
	(segment
		(start 297.852846 -318.125856)
		(end 297.249342 -317.522352)
		(width 0.12954)
		(layer "B.Cu")
		(net "PWRGD_FAIL_CPU0_AB")
	)
	(segment
		(start 297.852846 -318.588898)
		(end 297.852846 -318.125856)
		(width 0.12954)
		(layer "B.Cu")
		(net "PWRGD_FAIL_CPU0_AB")
	)
	(segment
		(start 300.508162 -318.441578)
		(end 299.447712 -319.502028)
		(width 0.12954)
		(layer "B.Cu")
		(net "PWRGD_FAIL_CPU0_AB")
	)
	(segment
		(start 303.097438 -317.31839)
		(end 301.97425 -318.441578)
		(width 0.12954)
		(layer "B.Cu")
		(net "PWRGD_FAIL_CPU0_AB")
	)
	(segment
		(start 290.540186 -319.469008)
		(end 290.301934 -319.469008)
		(width 0.12954)
		(layer "B.Cu")
		(net "PWRGD_FAIL_CPU0_AB")
	)
	(segment
		(start 312.592974 -317.46571)
		(end 312.592974 -318.669162)
		(width 0.12954)
		(layer "B.Cu")
		(net "PWRGD_FAIL_CPU0_AB")
	)
	(segment
		(start 304.928016 -318.871346)
		(end 304.718466 -318.661796)
		(width 0.12954)
		(layer "B.Cu")
		(net "PWRGD_FAIL_CPU0_AB")
	)
	(segment
		(start 304.718466 -318.661796)
		(end 304.739548 -318.661796)
		(width 0.12954)
		(layer "B.Cu")
		(net "PWRGD_FAIL_CPU0_AB")
	)
	(segment
		(start 295.395396 -318.313308)
		(end 294.901366 -318.313308)
		(width 0.12954)
		(layer "B.Cu")
		(net "PWRGD_FAIL_CPU0_AB")
	)
	(segment
		(start 294.853106 -318.361568)
		(end 292.905434 -318.361568)
		(width 0.12954)
		(layer "B.Cu")
		(net "PWRGD_FAIL_CPU0_AB")
	)
	(segment
		(start 307.28666 -319.893442)
		(end 306.128166 -319.893442)
		(width 0.12954)
		(layer "B.Cu")
		(net "PWRGD_FAIL_CPU0_AB")
	)
	(segment
		(start 297.249342 -317.522352)
		(end 296.186352 -317.522352)
		(width 0.12954)
		(layer "B.Cu")
		(net "PWRGD_FAIL_CPU0_AB")
	)
	(segment
		(start 307.463698 -319.893442)
		(end 308.687978 -318.669162)
		(width 0.12954)
		(layer "B.Cu")
		(net "PWRGD_FAIL_CPU0_AB")
	)
	(segment
		(start 304.888392 -318.512952)
		(end 304.888392 -317.888112)
		(width 0.12954)
		(layer "B.Cu")
		(net "PWRGD_FAIL_CPU0_AB")
	)
	(segment
		(start 304.31867 -317.31839)
		(end 303.097438 -317.31839)
		(width 0.12954)
		(layer "B.Cu")
		(net "PWRGD_FAIL_CPU0_AB")
	)
	(segment
		(start 308.687978 -318.669162)
		(end 312.592974 -318.669162)
		(width 0.12954)
		(layer "B.Cu")
		(net "PWRGD_FAIL_CPU0_AB")
	)
	(segment
		(start 299.447712 -319.502028)
		(end 298.802298 -319.502028)
		(width 0.12954)
		(layer "B.Cu")
		(net "PWRGD_FAIL_CPU0_AB")
	)
	(segment
		(start 304.888392 -317.888112)
		(end 304.31867 -317.31839)
		(width 0.12954)
		(layer "B.Cu")
		(net "PWRGD_FAIL_CPU0_AB")
	)
	(segment
		(start 305.10607 -318.871346)
		(end 304.928016 -318.871346)
		(width 0.12954)
		(layer "B.Cu")
		(net "PWRGD_FAIL_CPU0_AB")
	)
	(segment
		(start 294.901366 -318.313308)
		(end 294.853106 -318.361568)
		(width 0.12954)
		(layer "B.Cu")
		(net "PWRGD_FAIL_CPU0_AB")
	)
	(segment
		(start 291.048948 -319.97777)
		(end 290.540186 -319.469008)
		(width 0.12954)
		(layer "B.Cu")
		(net "PWRGD_FAIL_CPU0_AB")
	)
	(segment
		(start 292.905434 -318.361568)
		(end 292.3286 -318.938402)
		(width 0.12954)
		(layer "B.Cu")
		(net "PWRGD_FAIL_CPU0_AB")
	)
	(segment
		(start 292.3286 -318.938402)
		(end 292.3286 -319.453768)
		(width 0.12954)
		(layer "B.Cu")
		(net "PWRGD_FAIL_CPU0_AB")
	)
	(segment
		(start 304.739548 -318.661796)
		(end 304.888392 -318.512952)
		(width 0.12954)
		(layer "B.Cu")
		(net "PWRGD_FAIL_CPU0_AB")
	)
	(segment
		(start 228.6381 -121.288048)
		(end 229.46614 -121.288048)
		(width 0.12954)
		(layer "F.Cu")
		(net "PWRGD_DSW_PWROK_R3")
	)
	(segment
		(start 292.76294 -115.024408)
		(end 293.6494 -115.910868)
		(width 0.12954)
		(layer "F.Cu")
		(net "PWRGD_DSW_PWROK_R3")
	)
	(segment
		(start 186.621928 -127.851916)
		(end 186.74588 -127.975868)
		(width 0.12954)
		(layer "F.Cu")
		(net "PWRGD_DSW_PWROK_R3")
	)
	(segment
		(start 229.91064 -120.843548)
		(end 229.91064 -115.461288)
		(width 0.12954)
		(layer "F.Cu")
		(net "PWRGD_DSW_PWROK_R3")
	)
	(segment
		(start 221.07144 -124.061728)
		(end 224.08642 -121.046748)
		(width 0.12954)
		(layer "F.Cu")
		(net "PWRGD_DSW_PWROK_R3")
	)
	(segment
		(start 229.91064 -115.461288)
		(end 230.34752 -115.024408)
		(width 0.12954)
		(layer "F.Cu")
		(net "PWRGD_DSW_PWROK_R3")
	)
	(segment
		(start 184.170066 -123.535948)
		(end 183.916066 -123.535948)
		(width 0.12954)
		(layer "F.Cu")
		(net "PWRGD_DSW_PWROK_R3")
	)
	(segment
		(start 224.08642 -121.046748)
		(end 228.3968 -121.046748)
		(width 0.12954)
		(layer "F.Cu")
		(net "PWRGD_DSW_PWROK_R3")
	)
	(segment
		(start 183.916066 -123.535948)
		(end 182.155592 -121.775474)
		(width 0.12954)
		(layer "F.Cu")
		(net "PWRGD_DSW_PWROK_R3")
	)
	(segment
		(start 321.2592 -26.000202)
		(end 320.958464 -26.300938)
		(width 0.12954)
		(layer "F.Cu")
		(net "PWRGD_DSW_PWROK_R3")
	)
	(segment
		(start 185.975498 -125.34138)
		(end 185.975498 -126.4158)
		(width 0.12954)
		(layer "F.Cu")
		(net "PWRGD_DSW_PWROK_R3")
	)
	(segment
		(start 320.596768 -25.067768)
		(end 321.04584 -25.067768)
		(width 0.12954)
		(layer "F.Cu")
		(net "PWRGD_DSW_PWROK_R3")
	)
	(segment
		(start 321.2592 -25.281128)
		(end 321.2592 -26.000202)
		(width 0.12954)
		(layer "F.Cu")
		(net "PWRGD_DSW_PWROK_R3")
	)
	(segment
		(start 185.975498 -125.34138)
		(end 184.170066 -123.535948)
		(width 0.12954)
		(layer "F.Cu")
		(net "PWRGD_DSW_PWROK_R3")
	)
	(segment
		(start 321.04584 -25.067768)
		(end 321.2592 -25.281128)
		(width 0.12954)
		(layer "F.Cu")
		(net "PWRGD_DSW_PWROK_R3")
	)
	(segment
		(start 229.46614 -121.288048)
		(end 229.91064 -120.843548)
		(width 0.12954)
		(layer "F.Cu")
		(net "PWRGD_DSW_PWROK_R3")
	)
	(segment
		(start 318.902588 -23.373588)
		(end 320.596768 -25.067768)
		(width 0.12954)
		(layer "F.Cu")
		(net "PWRGD_DSW_PWROK_R3")
	)
	(segment
		(start 230.34752 -115.024408)
		(end 292.76294 -115.024408)
		(width 0.12954)
		(layer "F.Cu")
		(net "PWRGD_DSW_PWROK_R3")
	)
	(segment
		(start 320.958464 -26.300938)
		(end 320.81216 -26.300938)
		(width 0.12954)
		(layer "F.Cu")
		(net "PWRGD_DSW_PWROK_R3")
	)
	(segment
		(start 228.3968 -121.046748)
		(end 228.6381 -121.288048)
		(width 0.12954)
		(layer "F.Cu")
		(net "PWRGD_DSW_PWROK_R3")
	)
	(segment
		(start 318.14008 -23.373588)
		(end 318.902588 -23.373588)
		(width 0.12954)
		(layer "F.Cu")
		(net "PWRGD_DSW_PWROK_R3")
	)
	(segment
		(start 185.975498 -126.4158)
		(end 186.621928 -127.06223)
		(width 0.12954)
		(layer "F.Cu")
		(net "PWRGD_DSW_PWROK_R3")
	)
	(segment
		(start 221.07144 -125.232668)
		(end 221.07144 -124.061728)
		(width 0.12954)
		(layer "F.Cu")
		(net "PWRGD_DSW_PWROK_R3")
	)
	(segment
		(start 186.621928 -127.06223)
		(end 186.621928 -127.851916)
		(width 0.12954)
		(layer "F.Cu")
		(net "PWRGD_DSW_PWROK_R3")
	)
	(via
		(at 186.74588 -127.975868)
		(size 0.508)
		(drill 0.254)
		(layers "F.Cu" "B.Cu")
		(net "PWRGD_DSW_PWROK_R3")
	)
	(via
		(at 318.14008 -23.373588)
		(size 0.508)
		(drill 0.254)
		(layers "F.Cu" "B.Cu")
		(net "PWRGD_DSW_PWROK_R3")
	)
	(via
		(at 221.07144 -125.232668)
		(size 0.508)
		(drill 0.254)
		(layers "F.Cu" "B.Cu")
		(net "PWRGD_DSW_PWROK_R3")
	)
	(via
		(at 296.02176 -44.8183)
		(size 0.508)
		(drill 0.254)
		(layers "F.Cu" "B.Cu")
		(net "PWRGD_DSW_PWROK_R3")
	)
	(via
		(at 293.6494 -115.910868)
		(size 0.508)
		(drill 0.254)
		(layers "F.Cu" "B.Cu")
		(net "PWRGD_DSW_PWROK_R3")
	)
	(via
		(at 185.975498 -125.34138)
		(size 0.762)
		(drill 0.381)
		(layers "F.Cu" "B.Cu")
		(net "PWRGD_DSW_PWROK_R3")
	)
	(segment
		(start 296.02176 -44.8183)
		(end 294.87622 -43.67276)
		(width 0.12954)
		(layer "B.Cu")
		(net "PWRGD_DSW_PWROK_R3")
	)
	(segment
		(start 294.87622 -36.286948)
		(end 306.92344 -24.239728)
		(width 0.12954)
		(layer "B.Cu")
		(net "PWRGD_DSW_PWROK_R3")
	)
	(segment
		(start 294.87622 -43.67276)
		(end 294.87622 -36.286948)
		(width 0.12954)
		(layer "B.Cu")
		(net "PWRGD_DSW_PWROK_R3")
	)
	(segment
		(start 316.62497 -24.888698)
		(end 318.14008 -23.373588)
		(width 0.12954)
		(layer "B.Cu")
		(net "PWRGD_DSW_PWROK_R3")
	)
	(segment
		(start 313.11088 -24.239728)
		(end 313.75985 -24.888698)
		(width 0.12954)
		(layer "B.Cu")
		(net "PWRGD_DSW_PWROK_R3")
	)
	(segment
		(start 306.92344 -24.239728)
		(end 313.11088 -24.239728)
		(width 0.12954)
		(layer "B.Cu")
		(net "PWRGD_DSW_PWROK_R3")
	)
	(segment
		(start 313.75985 -24.888698)
		(end 316.62497 -24.888698)
		(width 0.12954)
		(layer "B.Cu")
		(net "PWRGD_DSW_PWROK_R3")
	)
	(segment
		(start 292.24986 -107.29722)
		(end 292.24986 -85.072728)
		(width 0.127)
		(layer "In2.Cu")
		(net "PWRGD_DSW_PWROK_R3")
	)
	(segment
		(start 300.79696 -64.353948)
		(end 298.21632 -61.773308)
		(width 0.127)
		(layer "In2.Cu")
		(net "PWRGD_DSW_PWROK_R3")
	)
	(segment
		(start 298.21632 -79.106268)
		(end 298.21632 -77.824076)
		(width 0.127)
		(layer "In2.Cu")
		(net "PWRGD_DSW_PWROK_R3")
	)
	(segment
		(start 293.6494 -108.69676)
		(end 292.24986 -107.29722)
		(width 0.127)
		(layer "In2.Cu")
		(net "PWRGD_DSW_PWROK_R3")
	)
	(segment
		(start 300.79696 -73.538588)
		(end 300.79696 -64.353948)
		(width 0.127)
		(layer "In2.Cu")
		(net "PWRGD_DSW_PWROK_R3")
	)
	(segment
		(start 292.24986 -85.072728)
		(end 298.21632 -79.106268)
		(width 0.127)
		(layer "In2.Cu")
		(net "PWRGD_DSW_PWROK_R3")
	)
	(segment
		(start 298.21632 -77.824076)
		(end 299.421804 -74.913744)
		(width 0.127)
		(layer "In2.Cu")
		(net "PWRGD_DSW_PWROK_R3")
	)
	(segment
		(start 299.421804 -74.913744)
		(end 300.79696 -73.538588)
		(width 0.127)
		(layer "In2.Cu")
		(net "PWRGD_DSW_PWROK_R3")
	)
	(segment
		(start 298.21632 -61.773308)
		(end 298.21632 -58.003948)
		(width 0.127)
		(layer "In2.Cu")
		(net "PWRGD_DSW_PWROK_R3")
	)
	(segment
		(start 293.6494 -115.910868)
		(end 293.6494 -108.69676)
		(width 0.127)
		(layer "In2.Cu")
		(net "PWRGD_DSW_PWROK_R3")
	)
	(segment
		(start 298.21632 -58.003948)
		(end 296.57548 -56.363108)
		(width 0.127)
		(layer "In2.Cu")
		(net "PWRGD_DSW_PWROK_R3")
	)
	(segment
		(start 296.57548 -56.363108)
		(end 296.57548 -45.37202)
		(width 0.127)
		(layer "In2.Cu")
		(net "PWRGD_DSW_PWROK_R3")
	)
	(segment
		(start 296.57548 -45.37202)
		(end 296.02176 -44.8183)
		(width 0.127)
		(layer "In2.Cu")
		(net "PWRGD_DSW_PWROK_R3")
	)
	(segment
		(start 186.74588 -127.975868)
		(end 187.06592 -127.975868)
		(width 0.127)
		(layer "In15.Cu")
		(net "PWRGD_DSW_PWROK_R3")
	)
	(segment
		(start 220.6752 -129.7178)
		(end 221.07144 -129.32156)
		(width 0.127)
		(layer "In15.Cu")
		(net "PWRGD_DSW_PWROK_R3")
	)
	(segment
		(start 192.037208 -132.032756)
		(end 195.086732 -132.032756)
		(width 0.127)
		(layer "In15.Cu")
		(net "PWRGD_DSW_PWROK_R3")
	)
	(segment
		(start 196.229224 -133.175248)
		(end 202.63485 -133.175248)
		(width 0.127)
		(layer "In15.Cu")
		(net "PWRGD_DSW_PWROK_R3")
	)
	(segment
		(start 212.61451 -129.12471)
		(end 213.614 -130.1242)
		(width 0.127)
		(layer "In15.Cu")
		(net "PWRGD_DSW_PWROK_R3")
	)
	(segment
		(start 216.1032 -130.1242)
		(end 217.043 -129.1844)
		(width 0.127)
		(layer "In15.Cu")
		(net "PWRGD_DSW_PWROK_R3")
	)
	(segment
		(start 213.614 -130.1242)
		(end 216.1032 -130.1242)
		(width 0.127)
		(layer "In15.Cu")
		(net "PWRGD_DSW_PWROK_R3")
	)
	(segment
		(start 202.63485 -133.175248)
		(end 205.88097 -129.929128)
		(width 0.127)
		(layer "In15.Cu")
		(net "PWRGD_DSW_PWROK_R3")
	)
	(segment
		(start 191.4144 -131.409948)
		(end 192.037208 -132.032756)
		(width 0.127)
		(layer "In15.Cu")
		(net "PWRGD_DSW_PWROK_R3")
	)
	(segment
		(start 187.06592 -127.975868)
		(end 189.1792 -130.089148)
		(width 0.127)
		(layer "In15.Cu")
		(net "PWRGD_DSW_PWROK_R3")
	)
	(segment
		(start 221.07144 -129.32156)
		(end 221.07144 -125.232668)
		(width 0.127)
		(layer "In15.Cu")
		(net "PWRGD_DSW_PWROK_R3")
	)
	(segment
		(start 208.64322 -129.12471)
		(end 212.61451 -129.12471)
		(width 0.127)
		(layer "In15.Cu")
		(net "PWRGD_DSW_PWROK_R3")
	)
	(segment
		(start 207.995012 -129.772918)
		(end 208.64322 -129.12471)
		(width 0.127)
		(layer "In15.Cu")
		(net "PWRGD_DSW_PWROK_R3")
	)
	(segment
		(start 190.4492 -130.089148)
		(end 191.4144 -131.054348)
		(width 0.127)
		(layer "In15.Cu")
		(net "PWRGD_DSW_PWROK_R3")
	)
	(segment
		(start 206.040736 -129.772918)
		(end 207.995012 -129.772918)
		(width 0.127)
		(layer "In15.Cu")
		(net "PWRGD_DSW_PWROK_R3")
	)
	(segment
		(start 205.884526 -129.929128)
		(end 206.040736 -129.772918)
		(width 0.127)
		(layer "In15.Cu")
		(net "PWRGD_DSW_PWROK_R3")
	)
	(segment
		(start 191.4144 -131.054348)
		(end 191.4144 -131.409948)
		(width 0.127)
		(layer "In15.Cu")
		(net "PWRGD_DSW_PWROK_R3")
	)
	(segment
		(start 195.086732 -132.032756)
		(end 196.229224 -133.175248)
		(width 0.127)
		(layer "In15.Cu")
		(net "PWRGD_DSW_PWROK_R3")
	)
	(segment
		(start 205.88097 -129.929128)
		(end 205.884526 -129.929128)
		(width 0.127)
		(layer "In15.Cu")
		(net "PWRGD_DSW_PWROK_R3")
	)
	(segment
		(start 218.313 -129.1844)
		(end 218.8464 -129.7178)
		(width 0.127)
		(layer "In15.Cu")
		(net "PWRGD_DSW_PWROK_R3")
	)
	(segment
		(start 218.8464 -129.7178)
		(end 220.6752 -129.7178)
		(width 0.127)
		(layer "In15.Cu")
		(net "PWRGD_DSW_PWROK_R3")
	)
	(segment
		(start 217.043 -129.1844)
		(end 218.313 -129.1844)
		(width 0.127)
		(layer "In15.Cu")
		(net "PWRGD_DSW_PWROK_R3")
	)
	(segment
		(start 189.1792 -130.089148)
		(end 190.4492 -130.089148)
		(width 0.127)
		(layer "In15.Cu")
		(net "PWRGD_DSW_PWROK_R3")
	)
	(segment
		(start 214.0204 -127.399034)
		(end 214.0204 -126.7714)
		(width 0.12954)
		(layer "F.Cu")
		(net "PWRGD_DSW_PWROK_R2")
	)
	(segment
		(start 214.9856 -125.8062)
		(end 217.68943 -125.8062)
		(width 0.12954)
		(layer "F.Cu")
		(net "PWRGD_DSW_PWROK_R2")
	)
	(segment
		(start 210.14563 -128.544828)
		(end 211.48548 -128.544828)
		(width 0.12954)
		(layer "F.Cu")
		(net "PWRGD_DSW_PWROK_R2")
	)
	(segment
		(start 212.98662 -128.432814)
		(end 214.0204 -127.399034)
		(width 0.12954)
		(layer "F.Cu")
		(net "PWRGD_DSW_PWROK_R2")
	)
	(segment
		(start 214.0204 -126.7714)
		(end 214.9856 -125.8062)
		(width 0.12954)
		(layer "F.Cu")
		(net "PWRGD_DSW_PWROK_R2")
	)
	(segment
		(start 212.874606 -128.544828)
		(end 212.98662 -128.432814)
		(width 0.12954)
		(layer "F.Cu")
		(net "PWRGD_DSW_PWROK_R2")
	)
	(segment
		(start 211.48548 -128.544828)
		(end 212.874606 -128.544828)
		(width 0.12954)
		(layer "F.Cu")
		(net "PWRGD_DSW_PWROK_R2")
	)
	(via
		(at 211.48548 -128.544828)
		(size 0.762)
		(drill 0.381)
		(layers "F.Cu" "B.Cu")
		(net "PWRGD_DSW_PWROK_R2")
	)
	(segment
		(start 217.637868 -130.273552)
		(end 214.752682 -130.273552)
		(width 0.12954)
		(layer "F.Cu")
		(net "PWRGD_DSW_PWROK_R1")
	)
	(segment
		(start 217.68943 -127.803148)
		(end 217.68943 -126.761748)
		(width 0.12954)
		(layer "F.Cu")
		(net "PWRGD_DSW_PWROK_R1")
	)
	(segment
		(start 217.68943 -129.43205)
		(end 218.0844 -129.82702)
		(width 0.12954)
		(layer "F.Cu")
		(net "PWRGD_DSW_PWROK_R1")
	)
	(segment
		(start 218.48953 -125.961648)
		(end 217.68943 -126.761748)
		(width 0.12954)
		(layer "F.Cu")
		(net "PWRGD_DSW_PWROK_R1")
	)
	(segment
		(start 218.48953 -125.8062)
		(end 218.48953 -125.961648)
		(width 0.12954)
		(layer "F.Cu")
		(net "PWRGD_DSW_PWROK_R1")
	)
	(segment
		(start 217.68943 -128.819148)
		(end 217.68943 -127.803148)
		(width 0.12954)
		(layer "F.Cu")
		(net "PWRGD_DSW_PWROK_R1")
	)
	(segment
		(start 218.0844 -129.82702)
		(end 217.637868 -130.273552)
		(width 0.12954)
		(layer "F.Cu")
		(net "PWRGD_DSW_PWROK_R1")
	)
	(segment
		(start 216.393014 -127.782828)
		(end 217.429334 -128.819148)
		(width 0.12954)
		(layer "F.Cu")
		(net "PWRGD_DSW_PWROK_R1")
	)
	(segment
		(start 214.88654 -127.782828)
		(end 216.393014 -127.782828)
		(width 0.12954)
		(layer "F.Cu")
		(net "PWRGD_DSW_PWROK_R1")
	)
	(segment
		(start 212.82025 -133.565646)
		(end 213.731094 -133.565646)
		(width 0.12954)
		(layer "F.Cu")
		(net "PWRGD_DSW_PWROK_R1")
	)
	(segment
		(start 217.429334 -128.819148)
		(end 217.68943 -128.819148)
		(width 0.12954)
		(layer "F.Cu")
		(net "PWRGD_DSW_PWROK_R1")
	)
	(segment
		(start 217.68943 -128.819148)
		(end 217.68943 -129.43205)
		(width 0.12954)
		(layer "F.Cu")
		(net "PWRGD_DSW_PWROK_R1")
	)
	(via
		(at 216.393014 -127.782828)
		(size 0.762)
		(drill 0.381)
		(layers "F.Cu" "B.Cu")
		(net "PWRGD_DSW_PWROK_R1")
	)
	(via
		(at 218.0844 -129.82702)
		(size 0.508)
		(drill 0.254)
		(layers "F.Cu" "B.Cu")
		(net "PWRGD_DSW_PWROK_R1")
	)
	(via
		(at 213.731094 -133.565646)
		(size 0.508)
		(drill 0.254)
		(layers "F.Cu" "B.Cu")
		(net "PWRGD_DSW_PWROK_R1")
	)
	(segment
		(start 218.0844 -129.82702)
		(end 216.27846 -129.82702)
		(width 0.127)
		(layer "In13.Cu")
		(net "PWRGD_DSW_PWROK_R1")
	)
	(segment
		(start 213.731094 -132.374386)
		(end 213.731094 -133.565646)
		(width 0.127)
		(layer "In13.Cu")
		(net "PWRGD_DSW_PWROK_R1")
	)
	(segment
		(start 216.27846 -129.82702)
		(end 213.731094 -132.374386)
		(width 0.127)
		(layer "In13.Cu")
		(net "PWRGD_DSW_PWROK_R1")
	)
	(segment
		(start 209.34553 -128.544828)
		(end 209.34553 -127.528828)
		(width 0.12954)
		(layer "F.Cu")
		(net "PWRGD_DSW_PWROK")
	)
	(segment
		(start 320.5734 -28.0416)
		(end 321.096132 -28.0416)
		(width 0.12954)
		(layer "F.Cu")
		(net "PWRGD_DSW_PWROK")
	)
	(segment
		(start 329.70216 -34.459164)
		(end 328.628502 -33.385506)
		(width 0.0889)
		(layer "F.Cu")
		(net "PWRGD_DSW_PWROK")
	)
	(segment
		(start 330.06538 -37.951918)
		(end 330.102972 -37.86124)
		(width 0.0889)
		(layer "F.Cu")
		(net "PWRGD_DSW_PWROK")
	)
	(segment
		(start 217.12428 -124.475748)
		(end 217.83548 -125.186948)
		(width 0.12954)
		(layer "F.Cu")
		(net "PWRGD_DSW_PWROK")
	)
	(segment
		(start 209.34553 -127.528828)
		(end 209.34553 -126.512828)
		(width 0.12954)
		(layer "F.Cu")
		(net "PWRGD_DSW_PWROK")
	)
	(segment
		(start 319.8368 -25.0952)
		(end 320.2178 -25.4762)
		(width 0.12954)
		(layer "F.Cu")
		(net "PWRGD_DSW_PWROK")
	)
	(segment
		(start 329.89647 -38.465252)
		(end 329.89647 -38.18382)
		(width 0.0889)
		(layer "F.Cu")
		(net "PWRGD_DSW_PWROK")
	)
	(segment
		(start 220.500702 -103.330248)
		(end 220.500702 -103.980488)
		(width 0.12954)
		(layer "F.Cu")
		(net "PWRGD_DSW_PWROK")
	)
	(segment
		(start 209.34553 -125.477778)
		(end 209.343752 -125.476)
		(width 0.12954)
		(layer "F.Cu")
		(net "PWRGD_DSW_PWROK")
	)
	(segment
		(start 330.228956 -36.504118)
		(end 329.70216 -35.977322)
		(width 0.0889)
		(layer "F.Cu")
		(net "PWRGD_DSW_PWROK")
	)
	(segment
		(start 330.203556 -37.760656)
		(end 330.203556 -37.554408)
		(width 0.0889)
		(layer "F.Cu")
		(net "PWRGD_DSW_PWROK")
	)
	(segment
		(start 210.31708 -124.475748)
		(end 217.12428 -124.475748)
		(width 0.12954)
		(layer "F.Cu")
		(net "PWRGD_DSW_PWROK")
	)
	(segment
		(start 330.203556 -37.554408)
		(end 330.228956 -37.529008)
		(width 0.0889)
		(layer "F.Cu")
		(net "PWRGD_DSW_PWROK")
	)
	(segment
		(start 324.432676 -27.869642)
		(end 324.432676 -26.995628)
		(width 0.12954)
		(layer "F.Cu")
		(net "PWRGD_DSW_PWROK")
	)
	(segment
		(start 321.88912 -27.101038)
		(end 320.81216 -27.101038)
		(width 0.12954)
		(layer "F.Cu")
		(net "PWRGD_DSW_PWROK")
	)
	(segment
		(start 327.937622 -32.079438)
		(end 326.927464 -31.06928)
		(width 0.12954)
		(layer "F.Cu")
		(net "PWRGD_DSW_PWROK")
	)
	(segment
		(start 318.9478 -25.0952)
		(end 319.8368 -25.0952)
		(width 0.12954)
		(layer "F.Cu")
		(net "PWRGD_DSW_PWROK")
	)
	(segment
		(start 330.102972 -37.86124)
		(end 330.203556 -37.760656)
		(width 0.0889)
		(layer "F.Cu")
		(net "PWRGD_DSW_PWROK")
	)
	(segment
		(start 320.2178 -25.4762)
		(end 320.2178 -27.686)
		(width 0.12954)
		(layer "F.Cu")
		(net "PWRGD_DSW_PWROK")
	)
	(segment
		(start 327.937622 -32.69361)
		(end 327.937622 -32.079438)
		(width 0.12954)
		(layer "F.Cu")
		(net "PWRGD_DSW_PWROK")
	)
	(segment
		(start 316.6364 -22.7838)
		(end 318.9478 -25.0952)
		(width 0.12954)
		(layer "F.Cu")
		(net "PWRGD_DSW_PWROK")
	)
	(segment
		(start 315.1378 -22.7838)
		(end 316.6364 -22.7838)
		(width 0.12954)
		(layer "F.Cu")
		(net "PWRGD_DSW_PWROK")
	)
	(segment
		(start 322.423028 -27.111706)
		(end 321.899788 -27.111706)
		(width 0.12954)
		(layer "F.Cu")
		(net "PWRGD_DSW_PWROK")
	)
	(segment
		(start 323.067426 -26.467308)
		(end 322.423028 -27.111706)
		(width 0.12954)
		(layer "F.Cu")
		(net "PWRGD_DSW_PWROK")
	)
	(segment
		(start 330.06538 -38.01491)
		(end 330.06538 -37.951918)
		(width 0.0889)
		(layer "F.Cu")
		(net "PWRGD_DSW_PWROK")
	)
	(segment
		(start 329.89647 -38.18382)
		(end 330.06538 -38.01491)
		(width 0.0889)
		(layer "F.Cu")
		(net "PWRGD_DSW_PWROK")
	)
	(segment
		(start 312.82005 -23.9268)
		(end 312.82005 -23.32355)
		(width 0.12954)
		(layer "F.Cu")
		(net "PWRGD_DSW_PWROK")
	)
	(segment
		(start 328.628502 -33.385506)
		(end 327.937622 -32.69361)
		(width 0.12954)
		(layer "F.Cu")
		(net "PWRGD_DSW_PWROK")
	)
	(segment
		(start 326.927464 -31.06928)
		(end 325.511414 -28.94838)
		(width 0.12954)
		(layer "F.Cu")
		(net "PWRGD_DSW_PWROK")
	)
	(segment
		(start 209.34553 -126.512828)
		(end 209.34553 -125.477778)
		(width 0.12954)
		(layer "F.Cu")
		(net "PWRGD_DSW_PWROK")
	)
	(segment
		(start 320.81216 -27.757628)
		(end 320.81216 -27.101038)
		(width 0.12954)
		(layer "F.Cu")
		(net "PWRGD_DSW_PWROK")
	)
	(segment
		(start 321.096132 -28.0416)
		(end 321.11188 -28.057348)
		(width 0.12954)
		(layer "F.Cu")
		(net "PWRGD_DSW_PWROK")
	)
	(segment
		(start 313.3598 -22.7838)
		(end 315.1378 -22.7838)
		(width 0.12954)
		(layer "F.Cu")
		(net "PWRGD_DSW_PWROK")
	)
	(segment
		(start 325.511414 -28.94838)
		(end 324.432676 -27.869642)
		(width 0.12954)
		(layer "F.Cu")
		(net "PWRGD_DSW_PWROK")
	)
	(segment
		(start 209.343752 -125.449076)
		(end 210.31708 -124.475748)
		(width 0.12954)
		(layer "F.Cu")
		(net "PWRGD_DSW_PWROK")
	)
	(segment
		(start 312.82005 -23.32355)
		(end 313.3598 -22.7838)
		(width 0.12954)
		(layer "F.Cu")
		(net "PWRGD_DSW_PWROK")
	)
	(segment
		(start 321.899788 -27.111706)
		(end 321.88912 -27.101038)
		(width 0.12954)
		(layer "F.Cu")
		(net "PWRGD_DSW_PWROK")
	)
	(segment
		(start 321.096132 -28.0416)
		(end 320.81216 -27.757628)
		(width 0.12954)
		(layer "F.Cu")
		(net "PWRGD_DSW_PWROK")
	)
	(segment
		(start 329.70216 -35.977322)
		(end 329.70216 -34.459164)
		(width 0.0889)
		(layer "F.Cu")
		(net "PWRGD_DSW_PWROK")
	)
	(segment
		(start 324.432676 -26.995628)
		(end 323.904356 -26.467308)
		(width 0.12954)
		(layer "F.Cu")
		(net "PWRGD_DSW_PWROK")
	)
	(segment
		(start 320.2178 -27.686)
		(end 320.5734 -28.0416)
		(width 0.12954)
		(layer "F.Cu")
		(net "PWRGD_DSW_PWROK")
	)
	(segment
		(start 209.343752 -125.476)
		(end 209.343752 -125.449076)
		(width 0.12954)
		(layer "F.Cu")
		(net "PWRGD_DSW_PWROK")
	)
	(segment
		(start 323.904356 -26.467308)
		(end 323.067426 -26.467308)
		(width 0.12954)
		(layer "F.Cu")
		(net "PWRGD_DSW_PWROK")
	)
	(segment
		(start 330.228956 -37.529008)
		(end 330.228956 -36.504118)
		(width 0.0889)
		(layer "F.Cu")
		(net "PWRGD_DSW_PWROK")
	)
	(segment
		(start 312.82005 -24.9936)
		(end 312.82005 -23.9268)
		(width 0.12954)
		(layer "F.Cu")
		(net "PWRGD_DSW_PWROK")
	)
	(via
		(at 315.1378 -22.7838)
		(size 0.762)
		(drill 0.381)
		(layers "F.Cu" "B.Cu")
		(net "PWRGD_DSW_PWROK")
	)
	(via
		(at 321.11188 -28.057348)
		(size 0.508)
		(drill 0.254)
		(layers "F.Cu" "B.Cu")
		(net "PWRGD_DSW_PWROK")
	)
	(via
		(at 217.83548 -125.186948)
		(size 0.508)
		(drill 0.254)
		(layers "F.Cu" "B.Cu")
		(net "PWRGD_DSW_PWROK")
	)
	(via
		(at 220.500702 -103.980488)
		(size 0.508)
		(drill 0.254)
		(layers "F.Cu" "B.Cu")
		(net "PWRGD_DSW_PWROK")
	)
	(via
		(at 200.69048 -90.134948)
		(size 0.508)
		(drill 0.254)
		(layers "F.Cu" "B.Cu")
		(net "PWRGD_DSW_PWROK")
	)
	(segment
		(start 220.500702 -103.980488)
		(end 220.500702 -104.517952)
		(width 0.127)
		(layer "In2.Cu")
		(net "PWRGD_DSW_PWROK")
	)
	(segment
		(start 217.83548 -107.183174)
		(end 217.83548 -125.186948)
		(width 0.127)
		(layer "In2.Cu")
		(net "PWRGD_DSW_PWROK")
	)
	(segment
		(start 220.500702 -104.517952)
		(end 217.83548 -107.183174)
		(width 0.127)
		(layer "In2.Cu")
		(net "PWRGD_DSW_PWROK")
	)
	(segment
		(start 211.786724 -102.479348)
		(end 218.999562 -102.479348)
		(width 0.127)
		(layer "In6.Cu")
		(net "PWRGD_DSW_PWROK")
	)
	(segment
		(start 200.69048 -90.134948)
		(end 200.69048 -94.122748)
		(width 0.127)
		(layer "In6.Cu")
		(net "PWRGD_DSW_PWROK")
	)
	(segment
		(start 218.999562 -102.479348)
		(end 220.500702 -103.980488)
		(width 0.127)
		(layer "In6.Cu")
		(net "PWRGD_DSW_PWROK")
	)
	(segment
		(start 209.221324 -99.913948)
		(end 211.786724 -102.479348)
		(width 0.127)
		(layer "In6.Cu")
		(net "PWRGD_DSW_PWROK")
	)
	(segment
		(start 200.69048 -94.122748)
		(end 206.48168 -99.913948)
		(width 0.127)
		(layer "In6.Cu")
		(net "PWRGD_DSW_PWROK")
	)
	(segment
		(start 206.48168 -99.913948)
		(end 209.221324 -99.913948)
		(width 0.127)
		(layer "In6.Cu")
		(net "PWRGD_DSW_PWROK")
	)
	(segment
		(start 307.61305 -28.092654)
		(end 308.994556 -26.711148)
		(width 0.127)
		(layer "In15.Cu")
		(net "PWRGD_DSW_PWROK")
	)
	(segment
		(start 200.46188 -88.979248)
		(end 200.46188 -83.000088)
		(width 0.127)
		(layer "In15.Cu")
		(net "PWRGD_DSW_PWROK")
	)
	(segment
		(start 262.193532 -64.430148)
		(end 274.78482 -64.430148)
		(width 0.127)
		(layer "In15.Cu")
		(net "PWRGD_DSW_PWROK")
	)
	(segment
		(start 295.521888 -40.208962)
		(end 295.521888 -38.615366)
		(width 0.127)
		(layer "In15.Cu")
		(net "PWRGD_DSW_PWROK")
	)
	(segment
		(start 200.69048 -90.134948)
		(end 200.69048 -89.207848)
		(width 0.127)
		(layer "In15.Cu")
		(net "PWRGD_DSW_PWROK")
	)
	(segment
		(start 291.39388 -44.33697)
		(end 295.521888 -40.208962)
		(width 0.127)
		(layer "In15.Cu")
		(net "PWRGD_DSW_PWROK")
	)
	(segment
		(start 222.63862 -82.133948)
		(end 234.14482 -70.627748)
		(width 0.127)
		(layer "In15.Cu")
		(net "PWRGD_DSW_PWROK")
	)
	(segment
		(start 295.521888 -38.615366)
		(end 298.336208 -35.801046)
		(width 0.127)
		(layer "In15.Cu")
		(net "PWRGD_DSW_PWROK")
	)
	(segment
		(start 234.14482 -70.627748)
		(end 243.812568 -70.627748)
		(width 0.127)
		(layer "In15.Cu")
		(net "PWRGD_DSW_PWROK")
	)
	(segment
		(start 291.39388 -47.821088)
		(end 291.39388 -44.33697)
		(width 0.127)
		(layer "In15.Cu")
		(net "PWRGD_DSW_PWROK")
	)
	(segment
		(start 306.55641 -31.233618)
		(end 307.61305 -30.176978)
		(width 0.127)
		(layer "In15.Cu")
		(net "PWRGD_DSW_PWROK")
	)
	(segment
		(start 302.022256 -31.233618)
		(end 306.55641 -31.233618)
		(width 0.127)
		(layer "In15.Cu")
		(net "PWRGD_DSW_PWROK")
	)
	(segment
		(start 201.32802 -82.133948)
		(end 222.63862 -82.133948)
		(width 0.127)
		(layer "In15.Cu")
		(net "PWRGD_DSW_PWROK")
	)
	(segment
		(start 319.76568 -26.711148)
		(end 321.11188 -28.057348)
		(width 0.127)
		(layer "In15.Cu")
		(net "PWRGD_DSW_PWROK")
	)
	(segment
		(start 307.61305 -30.176978)
		(end 307.61305 -28.092654)
		(width 0.127)
		(layer "In15.Cu")
		(net "PWRGD_DSW_PWROK")
	)
	(segment
		(start 298.336208 -35.801046)
		(end 298.336208 -34.919666)
		(width 0.127)
		(layer "In15.Cu")
		(net "PWRGD_DSW_PWROK")
	)
	(segment
		(start 274.78482 -64.430148)
		(end 291.39388 -47.821088)
		(width 0.127)
		(layer "In15.Cu")
		(net "PWRGD_DSW_PWROK")
	)
	(segment
		(start 308.994556 -26.711148)
		(end 319.76568 -26.711148)
		(width 0.127)
		(layer "In15.Cu")
		(net "PWRGD_DSW_PWROK")
	)
	(segment
		(start 298.336208 -34.919666)
		(end 302.022256 -31.233618)
		(width 0.127)
		(layer "In15.Cu")
		(net "PWRGD_DSW_PWROK")
	)
	(segment
		(start 243.812568 -70.627748)
		(end 246.739918 -67.700398)
		(width 0.127)
		(layer "In15.Cu")
		(net "PWRGD_DSW_PWROK")
	)
	(segment
		(start 246.739918 -67.700398)
		(end 251.72797 -67.700398)
		(width 0.127)
		(layer "In15.Cu")
		(net "PWRGD_DSW_PWROK")
	)
	(segment
		(start 200.69048 -89.207848)
		(end 200.46188 -88.979248)
		(width 0.127)
		(layer "In15.Cu")
		(net "PWRGD_DSW_PWROK")
	)
	(segment
		(start 251.72797 -67.700398)
		(end 253.21133 -66.217038)
		(width 0.127)
		(layer "In15.Cu")
		(net "PWRGD_DSW_PWROK")
	)
	(segment
		(start 253.21133 -66.217038)
		(end 262.193532 -64.430148)
		(width 0.127)
		(layer "In15.Cu")
		(net "PWRGD_DSW_PWROK")
	)
	(segment
		(start 200.46188 -83.000088)
		(end 201.32802 -82.133948)
		(width 0.127)
		(layer "In15.Cu")
		(net "PWRGD_DSW_PWROK")
	)
	(segment
		(start 176.555654 -108.975398)
		(end 176.155604 -108.575348)
		(width 0.12954)
		(layer "F.Cu")
		(net "PWRGD_DRAMPWRGD_CPU1_GH_R_LVC1")
	)
	(via
		(at 203.90866 -110.193328)
		(size 0.508)
		(drill 0.254)
		(layers "F.Cu" "B.Cu")
		(net "PWRGD_DRAMPWRGD_CPU1_GH_R_LVC1")
	)
	(via
		(at 176.155604 -108.575348)
		(size 0.4572)
		(drill 0.254)
		(layers "F.Cu" "B.Cu")
		(net "PWRGD_DRAMPWRGD_CPU1_GH_R_LVC1")
	)
	(segment
		(start 205.434438 -110.0709)
		(end 205.446122 -110.059216)
		(width 0.12954)
		(layer "B.Cu")
		(net "PWRGD_DRAMPWRGD_CPU1_GH_R_LVC1")
	)
	(segment
		(start 205.446122 -110.059216)
		(end 205.446122 -108.890816)
		(width 0.12954)
		(layer "B.Cu")
		(net "PWRGD_DRAMPWRGD_CPU1_GH_R_LVC1")
	)
	(segment
		(start 203.90866 -109.992668)
		(end 205.010512 -108.890816)
		(width 0.12954)
		(layer "B.Cu")
		(net "PWRGD_DRAMPWRGD_CPU1_GH_R_LVC1")
	)
	(segment
		(start 205.010512 -108.890816)
		(end 205.446122 -108.890816)
		(width 0.12954)
		(layer "B.Cu")
		(net "PWRGD_DRAMPWRGD_CPU1_GH_R_LVC1")
	)
	(segment
		(start 203.90866 -110.193328)
		(end 203.90866 -109.992668)
		(width 0.12954)
		(layer "B.Cu")
		(net "PWRGD_DRAMPWRGD_CPU1_GH_R_LVC1")
	)
	(segment
		(start 180.36032 -110.574328)
		(end 178.798728 -110.574328)
		(width 0.127)
		(layer "In2.Cu")
		(net "PWRGD_DRAMPWRGD_CPU1_GH_R_LVC1")
	)
	(segment
		(start 178.798728 -110.574328)
		(end 177.992786 -109.768386)
		(width 0.127)
		(layer "In2.Cu")
		(net "PWRGD_DRAMPWRGD_CPU1_GH_R_LVC1")
	)
	(segment
		(start 189.94882 -108.207048)
		(end 186.7789 -111.376968)
		(width 0.127)
		(layer "In2.Cu")
		(net "PWRGD_DRAMPWRGD_CPU1_GH_R_LVC1")
	)
	(segment
		(start 186.7789 -111.376968)
		(end 180.78196 -111.376968)
		(width 0.127)
		(layer "In2.Cu")
		(net "PWRGD_DRAMPWRGD_CPU1_GH_R_LVC1")
	)
	(segment
		(start 177.992786 -109.768386)
		(end 176.748186 -109.768386)
		(width 0.127)
		(layer "In2.Cu")
		(net "PWRGD_DRAMPWRGD_CPU1_GH_R_LVC1")
	)
	(segment
		(start 203.90866 -110.193328)
		(end 202.50912 -110.193328)
		(width 0.127)
		(layer "In2.Cu")
		(net "PWRGD_DRAMPWRGD_CPU1_GH_R_LVC1")
	)
	(segment
		(start 202.50912 -110.193328)
		(end 201.6633 -109.347508)
		(width 0.127)
		(layer "In2.Cu")
		(net "PWRGD_DRAMPWRGD_CPU1_GH_R_LVC1")
	)
	(segment
		(start 180.55082 -111.145828)
		(end 180.55082 -110.764828)
		(width 0.127)
		(layer "In2.Cu")
		(net "PWRGD_DRAMPWRGD_CPU1_GH_R_LVC1")
	)
	(segment
		(start 176.155604 -108.744004)
		(end 176.155604 -108.575348)
		(width 0.127)
		(layer "In2.Cu")
		(net "PWRGD_DRAMPWRGD_CPU1_GH_R_LVC1")
	)
	(segment
		(start 176.748186 -109.768386)
		(end 176.5554 -109.5756)
		(width 0.127)
		(layer "In2.Cu")
		(net "PWRGD_DRAMPWRGD_CPU1_GH_R_LVC1")
	)
	(segment
		(start 176.5554 -109.5756)
		(end 176.5554 -109.1438)
		(width 0.127)
		(layer "In2.Cu")
		(net "PWRGD_DRAMPWRGD_CPU1_GH_R_LVC1")
	)
	(segment
		(start 199.55764 -109.347508)
		(end 198.41718 -108.207048)
		(width 0.127)
		(layer "In2.Cu")
		(net "PWRGD_DRAMPWRGD_CPU1_GH_R_LVC1")
	)
	(segment
		(start 201.6633 -109.347508)
		(end 199.55764 -109.347508)
		(width 0.127)
		(layer "In2.Cu")
		(net "PWRGD_DRAMPWRGD_CPU1_GH_R_LVC1")
	)
	(segment
		(start 198.41718 -108.207048)
		(end 189.94882 -108.207048)
		(width 0.127)
		(layer "In2.Cu")
		(net "PWRGD_DRAMPWRGD_CPU1_GH_R_LVC1")
	)
	(segment
		(start 180.78196 -111.376968)
		(end 180.55082 -111.145828)
		(width 0.127)
		(layer "In2.Cu")
		(net "PWRGD_DRAMPWRGD_CPU1_GH_R_LVC1")
	)
	(segment
		(start 180.55082 -110.764828)
		(end 180.36032 -110.574328)
		(width 0.127)
		(layer "In2.Cu")
		(net "PWRGD_DRAMPWRGD_CPU1_GH_R_LVC1")
	)
	(segment
		(start 176.5554 -109.1438)
		(end 176.155604 -108.744004)
		(width 0.127)
		(layer "In2.Cu")
		(net "PWRGD_DRAMPWRGD_CPU1_GH_R_LVC1")
	)
	(segment
		(start 121.508266 -250.155964)
		(end 121.508012 -250.15571)
		(width 0.12954)
		(layer "F.Cu")
		(net "PWRGD_DRAMPWRGD_CPU1_GH_LVC1_R")
	)
	(segment
		(start 121.508012 -250.15571)
		(end 121.508012 -249.620024)
		(width 0.12954)
		(layer "F.Cu")
		(net "PWRGD_DRAMPWRGD_CPU1_GH_LVC1_R")
	)
	(via
		(at 147.124166 -244.943122)
		(size 0.6604)
		(drill 0.3302)
		(layers "F.Cu" "B.Cu")
		(net "PWRGD_DRAMPWRGD_CPU1_GH_LVC1_R")
	)
	(via
		(at 121.508012 -249.620024)
		(size 0.4572)
		(drill 0.2032)
		(layers "F.Cu" "B.Cu")
		(net "PWRGD_DRAMPWRGD_CPU1_GH_LVC1_R")
	)
	(segment
		(start 128.824482 -249.304302)
		(end 128.839214 -249.295666)
		(width 0.0889)
		(layer "B.Cu")
		(net "PWRGD_DRAMPWRGD_CPU1_GH_LVC1_R")
	)
	(segment
		(start 137.171938 -249.605546)
		(end 142.461742 -249.605546)
		(width 0.12954)
		(layer "B.Cu")
		(net "PWRGD_DRAMPWRGD_CPU1_GH_LVC1_R")
	)
	(segment
		(start 148.459698 -243.60759)
		(end 153.468578 -243.60759)
		(width 0.12954)
		(layer "B.Cu")
		(net "PWRGD_DRAMPWRGD_CPU1_GH_LVC1_R")
	)
	(segment
		(start 170.189398 -235.607606)
		(end 170.189398 -201.463148)
		(width 0.12954)
		(layer "B.Cu")
		(net "PWRGD_DRAMPWRGD_CPU1_GH_LVC1_R")
	)
	(segment
		(start 124.125482 -249.304302)
		(end 124.140214 -249.295666)
		(width 0.0889)
		(layer "B.Cu")
		(net "PWRGD_DRAMPWRGD_CPU1_GH_LVC1_R")
	)
	(segment
		(start 125.069854 -249.301762)
		(end 125.080268 -249.295666)
		(width 0.0889)
		(layer "B.Cu")
		(net "PWRGD_DRAMPWRGD_CPU1_GH_LVC1_R")
	)
	(segment
		(start 121.508012 -249.620024)
		(end 121.664476 -249.349006)
		(width 0.0889)
		(layer "B.Cu")
		(net "PWRGD_DRAMPWRGD_CPU1_GH_LVC1_R")
	)
	(segment
		(start 136.672828 -250.104656)
		(end 137.171938 -249.605546)
		(width 0.12954)
		(layer "B.Cu")
		(net "PWRGD_DRAMPWRGD_CPU1_GH_LVC1_R")
	)
	(segment
		(start 142.461742 -249.605546)
		(end 147.124166 -244.943122)
		(width 0.12954)
		(layer "B.Cu")
		(net "PWRGD_DRAMPWRGD_CPU1_GH_LVC1_R")
	)
	(segment
		(start 130.704082 -249.304302)
		(end 130.718814 -249.295666)
		(width 0.0889)
		(layer "B.Cu")
		(net "PWRGD_DRAMPWRGD_CPU1_GH_LVC1_R")
	)
	(segment
		(start 153.468578 -243.60759)
		(end 155.350718 -241.72545)
		(width 0.12954)
		(layer "B.Cu")
		(net "PWRGD_DRAMPWRGD_CPU1_GH_LVC1_R")
	)
	(segment
		(start 147.124166 -244.943122)
		(end 148.459698 -243.60759)
		(width 0.12954)
		(layer "B.Cu")
		(net "PWRGD_DRAMPWRGD_CPU1_GH_LVC1_R")
	)
	(segment
		(start 126.944882 -249.304302)
		(end 126.959614 -249.295666)
		(width 0.0889)
		(layer "B.Cu")
		(net "PWRGD_DRAMPWRGD_CPU1_GH_LVC1_R")
	)
	(segment
		(start 160.753044 -241.72545)
		(end 161.614104 -240.86439)
		(width 0.12954)
		(layer "B.Cu")
		(net "PWRGD_DRAMPWRGD_CPU1_GH_LVC1_R")
	)
	(segment
		(start 155.350718 -241.72545)
		(end 160.753044 -241.72545)
		(width 0.12954)
		(layer "B.Cu")
		(net "PWRGD_DRAMPWRGD_CPU1_GH_LVC1_R")
	)
	(segment
		(start 165.727634 -240.06937)
		(end 170.189398 -235.607606)
		(width 0.12954)
		(layer "B.Cu")
		(net "PWRGD_DRAMPWRGD_CPU1_GH_LVC1_R")
	)
	(segment
		(start 126.0094 -249.301762)
		(end 126.019814 -249.295666)
		(width 0.0889)
		(layer "B.Cu")
		(net "PWRGD_DRAMPWRGD_CPU1_GH_LVC1_R")
	)
	(segment
		(start 165.129718 -240.06937)
		(end 165.727634 -240.06937)
		(width 0.12954)
		(layer "B.Cu")
		(net "PWRGD_DRAMPWRGD_CPU1_GH_LVC1_R")
	)
	(segment
		(start 121.664476 -249.349006)
		(end 121.75363 -249.32513)
		(width 0.0889)
		(layer "B.Cu")
		(net "PWRGD_DRAMPWRGD_CPU1_GH_LVC1_R")
	)
	(segment
		(start 122.245882 -249.304302)
		(end 122.260614 -249.295666)
		(width 0.0889)
		(layer "B.Cu")
		(net "PWRGD_DRAMPWRGD_CPU1_GH_LVC1_R")
	)
	(segment
		(start 131.648454 -249.301762)
		(end 131.658868 -249.295666)
		(width 0.0889)
		(layer "B.Cu")
		(net "PWRGD_DRAMPWRGD_CPU1_GH_LVC1_R")
	)
	(segment
		(start 132.315966 -249.371358)
		(end 133.049264 -250.104656)
		(width 0.0889)
		(layer "B.Cu")
		(net "PWRGD_DRAMPWRGD_CPU1_GH_LVC1_R")
	)
	(segment
		(start 164.334698 -240.86439)
		(end 165.129718 -240.06937)
		(width 0.12954)
		(layer "B.Cu")
		(net "PWRGD_DRAMPWRGD_CPU1_GH_LVC1_R")
	)
	(segment
		(start 161.614104 -240.86439)
		(end 164.334698 -240.86439)
		(width 0.12954)
		(layer "B.Cu")
		(net "PWRGD_DRAMPWRGD_CPU1_GH_LVC1_R")
	)
	(segment
		(start 127.884682 -249.304302)
		(end 127.899414 -249.295666)
		(width 0.0889)
		(layer "B.Cu")
		(net "PWRGD_DRAMPWRGD_CPU1_GH_LVC1_R")
	)
	(segment
		(start 170.673268 -200.979278)
		(end 170.673268 -196.413628)
		(width 0.12954)
		(layer "B.Cu")
		(net "PWRGD_DRAMPWRGD_CPU1_GH_LVC1_R")
	)
	(segment
		(start 133.049264 -250.104656)
		(end 136.672828 -250.104656)
		(width 0.12954)
		(layer "B.Cu")
		(net "PWRGD_DRAMPWRGD_CPU1_GH_LVC1_R")
	)
	(segment
		(start 170.189398 -201.463148)
		(end 170.673268 -200.979278)
		(width 0.12954)
		(layer "B.Cu")
		(net "PWRGD_DRAMPWRGD_CPU1_GH_LVC1_R")
	)
	(arc
		(start 126.959614 -249.295666)
		(mid 127.146812 -249.245523)
		(end 127.33401 -249.295666)
		(width 0.0889)
		(layer "B.Cu")
		(net "PWRGD_DRAMPWRGD_CPU1_GH_LVC1_R")
	)
	(arc
		(start 128.839214 -249.295666)
		(mid 129.026412 -249.245523)
		(end 129.21361 -249.295666)
		(width 0.0889)
		(layer "B.Cu")
		(net "PWRGD_DRAMPWRGD_CPU1_GH_LVC1_R")
	)
	(arc
		(start 128.27381 -249.295666)
		(mid 128.548009 -249.371501)
		(end 128.824482 -249.304302)
		(width 0.0889)
		(layer "B.Cu")
		(net "PWRGD_DRAMPWRGD_CPU1_GH_LVC1_R")
	)
	(arc
		(start 125.080268 -249.295666)
		(mid 125.267466 -249.245523)
		(end 125.454664 -249.295666)
		(width 0.0889)
		(layer "B.Cu")
		(net "PWRGD_DRAMPWRGD_CPU1_GH_LVC1_R")
	)
	(arc
		(start 131.09321 -249.295666)
		(mid 131.370023 -249.371536)
		(end 131.648454 -249.301762)
		(width 0.0889)
		(layer "B.Cu")
		(net "PWRGD_DRAMPWRGD_CPU1_GH_LVC1_R")
	)
	(arc
		(start 131.658868 -249.295666)
		(mid 131.846066 -249.245523)
		(end 132.033264 -249.295666)
		(width 0.0889)
		(layer "B.Cu")
		(net "PWRGD_DRAMPWRGD_CPU1_GH_LVC1_R")
	)
	(arc
		(start 132.033264 -249.295666)
		(mid 132.169633 -249.352108)
		(end 132.315966 -249.371358)
		(width 0.0889)
		(layer "B.Cu")
		(net "PWRGD_DRAMPWRGD_CPU1_GH_LVC1_R")
	)
	(arc
		(start 121.75363 -249.32513)
		(mid 122.002135 -249.371117)
		(end 122.245882 -249.304302)
		(width 0.0889)
		(layer "B.Cu")
		(net "PWRGD_DRAMPWRGD_CPU1_GH_LVC1_R")
	)
	(arc
		(start 127.33401 -249.295666)
		(mid 127.608209 -249.371501)
		(end 127.884682 -249.304302)
		(width 0.0889)
		(layer "B.Cu")
		(net "PWRGD_DRAMPWRGD_CPU1_GH_LVC1_R")
	)
	(arc
		(start 123.200414 -249.295666)
		(mid 123.387612 -249.245523)
		(end 123.57481 -249.295666)
		(width 0.0889)
		(layer "B.Cu")
		(net "PWRGD_DRAMPWRGD_CPU1_GH_LVC1_R")
	)
	(arc
		(start 130.15341 -249.295666)
		(mid 130.427609 -249.371501)
		(end 130.704082 -249.304302)
		(width 0.0889)
		(layer "B.Cu")
		(net "PWRGD_DRAMPWRGD_CPU1_GH_LVC1_R")
	)
	(arc
		(start 127.899414 -249.295666)
		(mid 128.086612 -249.245523)
		(end 128.27381 -249.295666)
		(width 0.0889)
		(layer "B.Cu")
		(net "PWRGD_DRAMPWRGD_CPU1_GH_LVC1_R")
	)
	(arc
		(start 126.39421 -249.295666)
		(mid 126.668409 -249.371501)
		(end 126.944882 -249.304302)
		(width 0.0889)
		(layer "B.Cu")
		(net "PWRGD_DRAMPWRGD_CPU1_GH_LVC1_R")
	)
	(arc
		(start 125.454664 -249.295666)
		(mid 125.731223 -249.371409)
		(end 126.0094 -249.301762)
		(width 0.0889)
		(layer "B.Cu")
		(net "PWRGD_DRAMPWRGD_CPU1_GH_LVC1_R")
	)
	(arc
		(start 122.63501 -249.295666)
		(mid 122.917712 -249.371442)
		(end 123.200414 -249.295666)
		(width 0.0889)
		(layer "B.Cu")
		(net "PWRGD_DRAMPWRGD_CPU1_GH_LVC1_R")
	)
	(arc
		(start 129.779014 -249.295666)
		(mid 129.966212 -249.245523)
		(end 130.15341 -249.295666)
		(width 0.0889)
		(layer "B.Cu")
		(net "PWRGD_DRAMPWRGD_CPU1_GH_LVC1_R")
	)
	(arc
		(start 124.140214 -249.295666)
		(mid 124.327412 -249.245523)
		(end 124.51461 -249.295666)
		(width 0.0889)
		(layer "B.Cu")
		(net "PWRGD_DRAMPWRGD_CPU1_GH_LVC1_R")
	)
	(arc
		(start 126.019814 -249.295666)
		(mid 126.207012 -249.245523)
		(end 126.39421 -249.295666)
		(width 0.0889)
		(layer "B.Cu")
		(net "PWRGD_DRAMPWRGD_CPU1_GH_LVC1_R")
	)
	(arc
		(start 123.57481 -249.295666)
		(mid 123.849009 -249.371501)
		(end 124.125482 -249.304302)
		(width 0.0889)
		(layer "B.Cu")
		(net "PWRGD_DRAMPWRGD_CPU1_GH_LVC1_R")
	)
	(arc
		(start 124.51461 -249.295666)
		(mid 124.791423 -249.371536)
		(end 125.069854 -249.301762)
		(width 0.0889)
		(layer "B.Cu")
		(net "PWRGD_DRAMPWRGD_CPU1_GH_LVC1_R")
	)
	(arc
		(start 122.260614 -249.295666)
		(mid 122.447812 -249.245523)
		(end 122.63501 -249.295666)
		(width 0.0889)
		(layer "B.Cu")
		(net "PWRGD_DRAMPWRGD_CPU1_GH_LVC1_R")
	)
	(arc
		(start 130.718814 -249.295666)
		(mid 130.906012 -249.245523)
		(end 131.09321 -249.295666)
		(width 0.0889)
		(layer "B.Cu")
		(net "PWRGD_DRAMPWRGD_CPU1_GH_LVC1_R")
	)
	(arc
		(start 129.21361 -249.295666)
		(mid 129.496312 -249.371442)
		(end 129.779014 -249.295666)
		(width 0.0889)
		(layer "B.Cu")
		(net "PWRGD_DRAMPWRGD_CPU1_GH_LVC1_R")
	)
	(segment
		(start 176.555654 -109.775498)
		(end 176.155604 -109.375448)
		(width 0.12954)
		(layer "F.Cu")
		(net "PWRGD_DRAMPWRGD_CPU1_EF_R_LVC1")
	)
	(via
		(at 176.155604 -109.375448)
		(size 0.4572)
		(drill 0.254)
		(layers "F.Cu" "B.Cu")
		(net "PWRGD_DRAMPWRGD_CPU1_EF_R_LVC1")
	)
	(via
		(at 199.32142 -109.901228)
		(size 0.762)
		(drill 0.254)
		(layers "F.Cu" "B.Cu")
		(net "PWRGD_DRAMPWRGD_CPU1_EF_R_LVC1")
	)
	(segment
		(start 197.40118 -110.470188)
		(end 198.75246 -110.470188)
		(width 0.12954)
		(layer "B.Cu")
		(net "PWRGD_DRAMPWRGD_CPU1_EF_R_LVC1")
	)
	(segment
		(start 199.32142 -109.901228)
		(end 199.353678 -109.86897)
		(width 0.12954)
		(layer "B.Cu")
		(net "PWRGD_DRAMPWRGD_CPU1_EF_R_LVC1")
	)
	(segment
		(start 199.353678 -109.86897)
		(end 200.261728 -109.86897)
		(width 0.12954)
		(layer "B.Cu")
		(net "PWRGD_DRAMPWRGD_CPU1_EF_R_LVC1")
	)
	(segment
		(start 197.037452 -110.10646)
		(end 197.40118 -110.470188)
		(width 0.12954)
		(layer "B.Cu")
		(net "PWRGD_DRAMPWRGD_CPU1_EF_R_LVC1")
	)
	(segment
		(start 197.037452 -109.89691)
		(end 197.037452 -110.10646)
		(width 0.12954)
		(layer "B.Cu")
		(net "PWRGD_DRAMPWRGD_CPU1_EF_R_LVC1")
	)
	(segment
		(start 198.75246 -110.470188)
		(end 199.32142 -109.901228)
		(width 0.12954)
		(layer "B.Cu")
		(net "PWRGD_DRAMPWRGD_CPU1_EF_R_LVC1")
	)
	(segment
		(start 180.32476 -111.376968)
		(end 180.56098 -111.613188)
		(width 0.127)
		(layer "In2.Cu")
		(net "PWRGD_DRAMPWRGD_CPU1_EF_R_LVC1")
	)
	(segment
		(start 199.32142 -109.789468)
		(end 199.32142 -109.901228)
		(width 0.127)
		(layer "In2.Cu")
		(net "PWRGD_DRAMPWRGD_CPU1_EF_R_LVC1")
	)
	(segment
		(start 176.155604 -109.607604)
		(end 176.562766 -110.014766)
		(width 0.127)
		(layer "In2.Cu")
		(net "PWRGD_DRAMPWRGD_CPU1_EF_R_LVC1")
	)
	(segment
		(start 177.929032 -110.568232)
		(end 178.737768 -111.376968)
		(width 0.127)
		(layer "In2.Cu")
		(net "PWRGD_DRAMPWRGD_CPU1_EF_R_LVC1")
	)
	(segment
		(start 180.56098 -111.613188)
		(end 180.56098 -111.948468)
		(width 0.127)
		(layer "In2.Cu")
		(net "PWRGD_DRAMPWRGD_CPU1_EF_R_LVC1")
	)
	(segment
		(start 195.6943 -109.075728)
		(end 198.60768 -109.075728)
		(width 0.127)
		(layer "In2.Cu")
		(net "PWRGD_DRAMPWRGD_CPU1_EF_R_LVC1")
	)
	(segment
		(start 186.466988 -111.648748)
		(end 187.20562 -111.648748)
		(width 0.127)
		(layer "In2.Cu")
		(net "PWRGD_DRAMPWRGD_CPU1_EF_R_LVC1")
	)
	(segment
		(start 189.04966 -109.804708)
		(end 194.96532 -109.804708)
		(width 0.127)
		(layer "In2.Cu")
		(net "PWRGD_DRAMPWRGD_CPU1_EF_R_LVC1")
	)
	(segment
		(start 194.96532 -109.804708)
		(end 195.6943 -109.075728)
		(width 0.127)
		(layer "In2.Cu")
		(net "PWRGD_DRAMPWRGD_CPU1_EF_R_LVC1")
	)
	(segment
		(start 198.60768 -109.075728)
		(end 199.32142 -109.789468)
		(width 0.127)
		(layer "In2.Cu")
		(net "PWRGD_DRAMPWRGD_CPU1_EF_R_LVC1")
	)
	(segment
		(start 176.562766 -110.338108)
		(end 176.79289 -110.568232)
		(width 0.127)
		(layer "In2.Cu")
		(net "PWRGD_DRAMPWRGD_CPU1_EF_R_LVC1")
	)
	(segment
		(start 178.737768 -111.376968)
		(end 180.32476 -111.376968)
		(width 0.127)
		(layer "In2.Cu")
		(net "PWRGD_DRAMPWRGD_CPU1_EF_R_LVC1")
	)
	(segment
		(start 180.56098 -111.948468)
		(end 180.7845 -112.171988)
		(width 0.127)
		(layer "In2.Cu")
		(net "PWRGD_DRAMPWRGD_CPU1_EF_R_LVC1")
	)
	(segment
		(start 187.20562 -111.648748)
		(end 189.04966 -109.804708)
		(width 0.127)
		(layer "In2.Cu")
		(net "PWRGD_DRAMPWRGD_CPU1_EF_R_LVC1")
	)
	(segment
		(start 185.943748 -112.171988)
		(end 186.466988 -111.648748)
		(width 0.127)
		(layer "In2.Cu")
		(net "PWRGD_DRAMPWRGD_CPU1_EF_R_LVC1")
	)
	(segment
		(start 176.79289 -110.568232)
		(end 177.929032 -110.568232)
		(width 0.127)
		(layer "In2.Cu")
		(net "PWRGD_DRAMPWRGD_CPU1_EF_R_LVC1")
	)
	(segment
		(start 176.155604 -109.375448)
		(end 176.155604 -109.607604)
		(width 0.127)
		(layer "In2.Cu")
		(net "PWRGD_DRAMPWRGD_CPU1_EF_R_LVC1")
	)
	(segment
		(start 180.7845 -112.171988)
		(end 185.943748 -112.171988)
		(width 0.127)
		(layer "In2.Cu")
		(net "PWRGD_DRAMPWRGD_CPU1_EF_R_LVC1")
	)
	(segment
		(start 176.562766 -110.014766)
		(end 176.562766 -110.338108)
		(width 0.127)
		(layer "In2.Cu")
		(net "PWRGD_DRAMPWRGD_CPU1_EF_R_LVC1")
	)
	(segment
		(start 121.977912 -249.342148)
		(end 121.977912 -248.806462)
		(width 0.12954)
		(layer "F.Cu")
		(net "PWRGD_DRAMPWRGD_CPU1_EF_LVC1_R")
	)
	(segment
		(start 121.977912 -248.806462)
		(end 121.978166 -248.806208)
		(width 0.12954)
		(layer "F.Cu")
		(net "PWRGD_DRAMPWRGD_CPU1_EF_LVC1_R")
	)
	(via
		(at 121.978166 -248.806208)
		(size 0.4572)
		(drill 0.2032)
		(layers "F.Cu" "B.Cu")
		(net "PWRGD_DRAMPWRGD_CPU1_EF_LVC1_R")
	)
	(via
		(at 143.747998 -246.06377)
		(size 0.6604)
		(drill 0.3302)
		(layers "F.Cu" "B.Cu")
		(net "PWRGD_DRAMPWRGD_CPU1_EF_LVC1_R")
	)
	(segment
		(start 168.742868 -197.705218)
		(end 168.742868 -197.531228)
		(width 0.12954)
		(layer "B.Cu")
		(net "PWRGD_DRAMPWRGD_CPU1_EF_LVC1_R")
	)
	(segment
		(start 133.088126 -249.529346)
		(end 135.993632 -249.529346)
		(width 0.12954)
		(layer "B.Cu")
		(net "PWRGD_DRAMPWRGD_CPU1_EF_LVC1_R")
	)
	(segment
		(start 125.924564 -249.130566)
		(end 125.939296 -249.12193)
		(width 0.0889)
		(layer "B.Cu")
		(net "PWRGD_DRAMPWRGD_CPU1_EF_LVC1_R")
	)
	(segment
		(start 121.978166 -248.806208)
		(end 121.821702 -249.077226)
		(width 0.0889)
		(layer "B.Cu")
		(net "PWRGD_DRAMPWRGD_CPU1_EF_LVC1_R")
	)
	(segment
		(start 143.747998 -246.06377)
		(end 147.314158 -242.49761)
		(width 0.12954)
		(layer "B.Cu")
		(net "PWRGD_DRAMPWRGD_CPU1_EF_LVC1_R")
	)
	(segment
		(start 165.452298 -239.53343)
		(end 166.745158 -238.24057)
		(width 0.12954)
		(layer "B.Cu")
		(net "PWRGD_DRAMPWRGD_CPU1_EF_LVC1_R")
	)
	(segment
		(start 126.864364 -249.130566)
		(end 126.879096 -249.12193)
		(width 0.0889)
		(layer "B.Cu")
		(net "PWRGD_DRAMPWRGD_CPU1_EF_LVC1_R")
	)
	(segment
		(start 153.445718 -242.49761)
		(end 154.809698 -241.13363)
		(width 0.12954)
		(layer "B.Cu")
		(net "PWRGD_DRAMPWRGD_CPU1_EF_LVC1_R")
	)
	(segment
		(start 147.314158 -242.49761)
		(end 153.445718 -242.49761)
		(width 0.12954)
		(layer "B.Cu")
		(net "PWRGD_DRAMPWRGD_CPU1_EF_LVC1_R")
	)
	(segment
		(start 168.109138 -198.338948)
		(end 168.742868 -197.705218)
		(width 0.12954)
		(layer "B.Cu")
		(net "PWRGD_DRAMPWRGD_CPU1_EF_LVC1_R")
	)
	(segment
		(start 140.592302 -249.219466)
		(end 143.747998 -246.06377)
		(width 0.12954)
		(layer "B.Cu")
		(net "PWRGD_DRAMPWRGD_CPU1_EF_LVC1_R")
	)
	(segment
		(start 122.165364 -249.130566)
		(end 122.175778 -249.12447)
		(width 0.0889)
		(layer "B.Cu")
		(net "PWRGD_DRAMPWRGD_CPU1_EF_LVC1_R")
	)
	(segment
		(start 168.215818 -217.58275)
		(end 166.861998 -216.22893)
		(width 0.12954)
		(layer "B.Cu")
		(net "PWRGD_DRAMPWRGD_CPU1_EF_LVC1_R")
	)
	(segment
		(start 128.743964 -249.130566)
		(end 128.754378 -249.12447)
		(width 0.0889)
		(layer "B.Cu")
		(net "PWRGD_DRAMPWRGD_CPU1_EF_LVC1_R")
	)
	(segment
		(start 154.809698 -241.13363)
		(end 160.560258 -241.13363)
		(width 0.12954)
		(layer "B.Cu")
		(net "PWRGD_DRAMPWRGD_CPU1_EF_LVC1_R")
	)
	(segment
		(start 124.044964 -249.130566)
		(end 124.059696 -249.12193)
		(width 0.0889)
		(layer "B.Cu")
		(net "PWRGD_DRAMPWRGD_CPU1_EF_LVC1_R")
	)
	(segment
		(start 164.174678 -240.29797)
		(end 164.939218 -239.53343)
		(width 0.12954)
		(layer "B.Cu")
		(net "PWRGD_DRAMPWRGD_CPU1_EF_LVC1_R")
	)
	(segment
		(start 121.821702 -249.077226)
		(end 121.842784 -249.155204)
		(width 0.0889)
		(layer "B.Cu")
		(net "PWRGD_DRAMPWRGD_CPU1_EF_LVC1_R")
	)
	(segment
		(start 135.993632 -249.529346)
		(end 136.303512 -249.219466)
		(width 0.12954)
		(layer "B.Cu")
		(net "PWRGD_DRAMPWRGD_CPU1_EF_LVC1_R")
	)
	(segment
		(start 161.395918 -240.29797)
		(end 164.174678 -240.29797)
		(width 0.12954)
		(layer "B.Cu")
		(net "PWRGD_DRAMPWRGD_CPU1_EF_LVC1_R")
	)
	(segment
		(start 166.745158 -238.24057)
		(end 166.745158 -229.18547)
		(width 0.12954)
		(layer "B.Cu")
		(net "PWRGD_DRAMPWRGD_CPU1_EF_LVC1_R")
	)
	(segment
		(start 132.739892 -249.181112)
		(end 133.088126 -249.529346)
		(width 0.12954)
		(layer "B.Cu")
		(net "PWRGD_DRAMPWRGD_CPU1_EF_LVC1_R")
	)
	(segment
		(start 127.804164 -249.130566)
		(end 127.818896 -249.12193)
		(width 0.0889)
		(layer "B.Cu")
		(net "PWRGD_DRAMPWRGD_CPU1_EF_LVC1_R")
	)
	(segment
		(start 168.109138 -200.09485)
		(end 168.109138 -198.338948)
		(width 0.12954)
		(layer "B.Cu")
		(net "PWRGD_DRAMPWRGD_CPU1_EF_LVC1_R")
	)
	(segment
		(start 166.745158 -229.18547)
		(end 168.215818 -227.71481)
		(width 0.12954)
		(layer "B.Cu")
		(net "PWRGD_DRAMPWRGD_CPU1_EF_LVC1_R")
	)
	(segment
		(start 130.623564 -249.130566)
		(end 130.638296 -249.12193)
		(width 0.0889)
		(layer "B.Cu")
		(net "PWRGD_DRAMPWRGD_CPU1_EF_LVC1_R")
	)
	(segment
		(start 160.560258 -241.13363)
		(end 161.395918 -240.29797)
		(width 0.12954)
		(layer "B.Cu")
		(net "PWRGD_DRAMPWRGD_CPU1_EF_LVC1_R")
	)
	(segment
		(start 132.315966 -249.181112)
		(end 132.739892 -249.181112)
		(width 0.0889)
		(layer "B.Cu")
		(net "PWRGD_DRAMPWRGD_CPU1_EF_LVC1_R")
	)
	(segment
		(start 129.68351 -249.130566)
		(end 129.693924 -249.12447)
		(width 0.0889)
		(layer "B.Cu")
		(net "PWRGD_DRAMPWRGD_CPU1_EF_LVC1_R")
	)
	(segment
		(start 136.303512 -249.219466)
		(end 140.592302 -249.219466)
		(width 0.12954)
		(layer "B.Cu")
		(net "PWRGD_DRAMPWRGD_CPU1_EF_LVC1_R")
	)
	(segment
		(start 164.939218 -239.53343)
		(end 165.452298 -239.53343)
		(width 0.12954)
		(layer "B.Cu")
		(net "PWRGD_DRAMPWRGD_CPU1_EF_LVC1_R")
	)
	(segment
		(start 166.861998 -201.34199)
		(end 168.109138 -200.09485)
		(width 0.12954)
		(layer "B.Cu")
		(net "PWRGD_DRAMPWRGD_CPU1_EF_LVC1_R")
	)
	(segment
		(start 168.215818 -227.71481)
		(end 168.215818 -217.58275)
		(width 0.12954)
		(layer "B.Cu")
		(net "PWRGD_DRAMPWRGD_CPU1_EF_LVC1_R")
	)
	(segment
		(start 166.861998 -216.22893)
		(end 166.861998 -201.34199)
		(width 0.12954)
		(layer "B.Cu")
		(net "PWRGD_DRAMPWRGD_CPU1_EF_LVC1_R")
	)
	(segment
		(start 123.10491 -249.130566)
		(end 123.115324 -249.12447)
		(width 0.0889)
		(layer "B.Cu")
		(net "PWRGD_DRAMPWRGD_CPU1_EF_LVC1_R")
	)
	(arc
		(start 125.939296 -249.12193)
		(mid 126.215771 -249.05461)
		(end 126.489968 -249.130566)
		(width 0.0889)
		(layer "B.Cu")
		(net "PWRGD_DRAMPWRGD_CPU1_EF_LVC1_R")
	)
	(arc
		(start 129.693924 -249.12447)
		(mid 129.972356 -249.054624)
		(end 130.249168 -249.130566)
		(width 0.0889)
		(layer "B.Cu")
		(net "PWRGD_DRAMPWRGD_CPU1_EF_LVC1_R")
	)
	(arc
		(start 132.128768 -249.130566)
		(mid 132.21904 -249.168165)
		(end 132.315966 -249.181112)
		(width 0.0889)
		(layer "B.Cu")
		(net "PWRGD_DRAMPWRGD_CPU1_EF_LVC1_R")
	)
	(arc
		(start 124.984764 -249.130566)
		(mid 125.267466 -249.05479)
		(end 125.550168 -249.130566)
		(width 0.0889)
		(layer "B.Cu")
		(net "PWRGD_DRAMPWRGD_CPU1_EF_LVC1_R")
	)
	(arc
		(start 126.489968 -249.130566)
		(mid 126.677166 -249.180709)
		(end 126.864364 -249.130566)
		(width 0.0889)
		(layer "B.Cu")
		(net "PWRGD_DRAMPWRGD_CPU1_EF_LVC1_R")
	)
	(arc
		(start 129.309114 -249.130566)
		(mid 129.496312 -249.180709)
		(end 129.68351 -249.130566)
		(width 0.0889)
		(layer "B.Cu")
		(net "PWRGD_DRAMPWRGD_CPU1_EF_LVC1_R")
	)
	(arc
		(start 125.550168 -249.130566)
		(mid 125.737366 -249.180709)
		(end 125.924564 -249.130566)
		(width 0.0889)
		(layer "B.Cu")
		(net "PWRGD_DRAMPWRGD_CPU1_EF_LVC1_R")
	)
	(arc
		(start 124.610368 -249.130566)
		(mid 124.797566 -249.180709)
		(end 124.984764 -249.130566)
		(width 0.0889)
		(layer "B.Cu")
		(net "PWRGD_DRAMPWRGD_CPU1_EF_LVC1_R")
	)
	(arc
		(start 122.730514 -249.130566)
		(mid 122.917712 -249.180709)
		(end 123.10491 -249.130566)
		(width 0.0889)
		(layer "B.Cu")
		(net "PWRGD_DRAMPWRGD_CPU1_EF_LVC1_R")
	)
	(arc
		(start 126.879096 -249.12193)
		(mid 127.155571 -249.05461)
		(end 127.429768 -249.130566)
		(width 0.0889)
		(layer "B.Cu")
		(net "PWRGD_DRAMPWRGD_CPU1_EF_LVC1_R")
	)
	(arc
		(start 123.670568 -249.130566)
		(mid 123.857766 -249.180709)
		(end 124.044964 -249.130566)
		(width 0.0889)
		(layer "B.Cu")
		(net "PWRGD_DRAMPWRGD_CPU1_EF_LVC1_R")
	)
	(arc
		(start 124.059696 -249.12193)
		(mid 124.336171 -249.05461)
		(end 124.610368 -249.130566)
		(width 0.0889)
		(layer "B.Cu")
		(net "PWRGD_DRAMPWRGD_CPU1_EF_LVC1_R")
	)
	(arc
		(start 128.369568 -249.130566)
		(mid 128.556766 -249.180709)
		(end 128.743964 -249.130566)
		(width 0.0889)
		(layer "B.Cu")
		(net "PWRGD_DRAMPWRGD_CPU1_EF_LVC1_R")
	)
	(arc
		(start 127.818896 -249.12193)
		(mid 128.095371 -249.05461)
		(end 128.369568 -249.130566)
		(width 0.0889)
		(layer "B.Cu")
		(net "PWRGD_DRAMPWRGD_CPU1_EF_LVC1_R")
	)
	(arc
		(start 128.754378 -249.12447)
		(mid 129.032556 -249.054747)
		(end 129.309114 -249.130566)
		(width 0.0889)
		(layer "B.Cu")
		(net "PWRGD_DRAMPWRGD_CPU1_EF_LVC1_R")
	)
	(arc
		(start 121.842784 -249.155204)
		(mid 122.00688 -249.179551)
		(end 122.165364 -249.130566)
		(width 0.0889)
		(layer "B.Cu")
		(net "PWRGD_DRAMPWRGD_CPU1_EF_LVC1_R")
	)
	(arc
		(start 127.429768 -249.130566)
		(mid 127.616966 -249.180709)
		(end 127.804164 -249.130566)
		(width 0.0889)
		(layer "B.Cu")
		(net "PWRGD_DRAMPWRGD_CPU1_EF_LVC1_R")
	)
	(arc
		(start 131.563364 -249.130566)
		(mid 131.846066 -249.05479)
		(end 132.128768 -249.130566)
		(width 0.0889)
		(layer "B.Cu")
		(net "PWRGD_DRAMPWRGD_CPU1_EF_LVC1_R")
	)
	(arc
		(start 122.175778 -249.12447)
		(mid 122.453956 -249.054747)
		(end 122.730514 -249.130566)
		(width 0.0889)
		(layer "B.Cu")
		(net "PWRGD_DRAMPWRGD_CPU1_EF_LVC1_R")
	)
	(arc
		(start 130.249168 -249.130566)
		(mid 130.436366 -249.180709)
		(end 130.623564 -249.130566)
		(width 0.0889)
		(layer "B.Cu")
		(net "PWRGD_DRAMPWRGD_CPU1_EF_LVC1_R")
	)
	(arc
		(start 131.188968 -249.130566)
		(mid 131.376166 -249.180709)
		(end 131.563364 -249.130566)
		(width 0.0889)
		(layer "B.Cu")
		(net "PWRGD_DRAMPWRGD_CPU1_EF_LVC1_R")
	)
	(arc
		(start 123.115324 -249.12447)
		(mid 123.393756 -249.054624)
		(end 123.670568 -249.130566)
		(width 0.0889)
		(layer "B.Cu")
		(net "PWRGD_DRAMPWRGD_CPU1_EF_LVC1_R")
	)
	(arc
		(start 130.638296 -249.12193)
		(mid 130.914771 -249.05461)
		(end 131.188968 -249.130566)
		(width 0.0889)
		(layer "B.Cu")
		(net "PWRGD_DRAMPWRGD_CPU1_EF_LVC1_R")
	)
	(segment
		(start 175.20793 -97.116138)
		(end 174.82566 -97.116138)
		(width 0.12954)
		(layer "F.Cu")
		(net "PWRGD_DRAMPWRGD_CPU1_CD_R_LVC1")
	)
	(segment
		(start 175.93945 -100.263198)
		(end 174.87138 -100.263198)
		(width 0.12954)
		(layer "F.Cu")
		(net "PWRGD_DRAMPWRGD_CPU1_CD_R_LVC1")
	)
	(segment
		(start 175.38446 -102.461568)
		(end 176.0982 -101.747828)
		(width 0.12954)
		(layer "F.Cu")
		(net "PWRGD_DRAMPWRGD_CPU1_CD_R_LVC1")
	)
	(segment
		(start 175.3362 -97.244408)
		(end 175.20793 -97.116138)
		(width 0.12954)
		(layer "F.Cu")
		(net "PWRGD_DRAMPWRGD_CPU1_CD_R_LVC1")
	)
	(segment
		(start 175.755554 -104.975406)
		(end 175.38446 -104.604312)
		(width 0.12954)
		(layer "F.Cu")
		(net "PWRGD_DRAMPWRGD_CPU1_CD_R_LVC1")
	)
	(segment
		(start 174.87138 -100.263198)
		(end 175.3362 -99.798378)
		(width 0.12954)
		(layer "F.Cu")
		(net "PWRGD_DRAMPWRGD_CPU1_CD_R_LVC1")
	)
	(segment
		(start 176.0982 -100.421948)
		(end 175.93945 -100.263198)
		(width 0.12954)
		(layer "F.Cu")
		(net "PWRGD_DRAMPWRGD_CPU1_CD_R_LVC1")
	)
	(segment
		(start 175.3362 -99.798378)
		(end 175.3362 -97.244408)
		(width 0.12954)
		(layer "F.Cu")
		(net "PWRGD_DRAMPWRGD_CPU1_CD_R_LVC1")
	)
	(segment
		(start 175.38446 -104.604312)
		(end 175.38446 -102.461568)
		(width 0.12954)
		(layer "F.Cu")
		(net "PWRGD_DRAMPWRGD_CPU1_CD_R_LVC1")
	)
	(segment
		(start 176.0982 -101.747828)
		(end 176.0982 -100.421948)
		(width 0.12954)
		(layer "F.Cu")
		(net "PWRGD_DRAMPWRGD_CPU1_CD_R_LVC1")
	)
	(via
		(at 176.0982 -100.421948)
		(size 0.762)
		(drill 0.381)
		(layers "F.Cu" "B.Cu")
		(net "PWRGD_DRAMPWRGD_CPU1_CD_R_LVC1")
	)
	(segment
		(start 87.315294 -253.383796)
		(end 87.315294 -253.919736)
		(width 0.12954)
		(layer "F.Cu")
		(net "PWRGD_DRAMPWRGD_CPU1_CD_LVC1_R")
	)
	(via
		(at 80.569308 -246.4435)
		(size 0.6604)
		(drill 0.3302)
		(layers "F.Cu" "B.Cu")
		(net "PWRGD_DRAMPWRGD_CPU1_CD_LVC1_R")
	)
	(via
		(at 87.315294 -253.919736)
		(size 0.4572)
		(drill 0.2032)
		(layers "F.Cu" "B.Cu")
		(net "PWRGD_DRAMPWRGD_CPU1_CD_LVC1_R")
	)
	(segment
		(start 85.733382 -252.337824)
		(end 85.733382 -249.51055)
		(width 0.12954)
		(layer "B.Cu")
		(net "PWRGD_DRAMPWRGD_CPU1_CD_LVC1_R")
	)
	(segment
		(start 85.733382 -249.51055)
		(end 83.457288 -247.234456)
		(width 0.12954)
		(layer "B.Cu")
		(net "PWRGD_DRAMPWRGD_CPU1_CD_LVC1_R")
	)
	(segment
		(start 67.82689 -237.978442)
		(end 63.824104 -236.320076)
		(width 0.12954)
		(layer "B.Cu")
		(net "PWRGD_DRAMPWRGD_CPU1_CD_LVC1_R")
	)
	(segment
		(start 60.29706 -233.722672)
		(end 60.29706 -202.443588)
		(width 0.12954)
		(layer "B.Cu")
		(net "PWRGD_DRAMPWRGD_CPU1_CD_LVC1_R")
	)
	(segment
		(start 87.315294 -253.919736)
		(end 85.733382 -252.337824)
		(width 0.12954)
		(layer "B.Cu")
		(net "PWRGD_DRAMPWRGD_CPU1_CD_LVC1_R")
	)
	(segment
		(start 61.772038 -235.19765)
		(end 60.29706 -233.722672)
		(width 0.12954)
		(layer "B.Cu")
		(net "PWRGD_DRAMPWRGD_CPU1_CD_LVC1_R")
	)
	(segment
		(start 83.457288 -247.234456)
		(end 81.360264 -247.234456)
		(width 0.12954)
		(layer "B.Cu")
		(net "PWRGD_DRAMPWRGD_CPU1_CD_LVC1_R")
	)
	(segment
		(start 63.824104 -236.320076)
		(end 63.200534 -235.696506)
		(width 0.12954)
		(layer "B.Cu")
		(net "PWRGD_DRAMPWRGD_CPU1_CD_LVC1_R")
	)
	(segment
		(start 80.569308 -246.4435)
		(end 80.184752 -246.4435)
		(width 0.12954)
		(layer "B.Cu")
		(net "PWRGD_DRAMPWRGD_CPU1_CD_LVC1_R")
	)
	(segment
		(start 60.29706 -202.443588)
		(end 65.364868 -197.37578)
		(width 0.12954)
		(layer "B.Cu")
		(net "PWRGD_DRAMPWRGD_CPU1_CD_LVC1_R")
	)
	(segment
		(start 80.184752 -246.4435)
		(end 73.414636 -239.673384)
		(width 0.12954)
		(layer "B.Cu")
		(net "PWRGD_DRAMPWRGD_CPU1_CD_LVC1_R")
	)
	(segment
		(start 73.414636 -239.673384)
		(end 67.82689 -237.978442)
		(width 0.12954)
		(layer "B.Cu")
		(net "PWRGD_DRAMPWRGD_CPU1_CD_LVC1_R")
	)
	(segment
		(start 61.99632 -235.19765)
		(end 61.772038 -235.19765)
		(width 0.12954)
		(layer "B.Cu")
		(net "PWRGD_DRAMPWRGD_CPU1_CD_LVC1_R")
	)
	(segment
		(start 81.360264 -247.234456)
		(end 80.569308 -246.4435)
		(width 0.12954)
		(layer "B.Cu")
		(net "PWRGD_DRAMPWRGD_CPU1_CD_LVC1_R")
	)
	(segment
		(start 63.200534 -235.696506)
		(end 61.99632 -235.19765)
		(width 0.12954)
		(layer "B.Cu")
		(net "PWRGD_DRAMPWRGD_CPU1_CD_LVC1_R")
	)
	(segment
		(start 65.364868 -197.37578)
		(end 65.364868 -196.032628)
		(width 0.12954)
		(layer "B.Cu")
		(net "PWRGD_DRAMPWRGD_CPU1_CD_LVC1_R")
	)
	(segment
		(start 175.755554 -105.775506)
		(end 175.355504 -105.375456)
		(width 0.12954)
		(layer "F.Cu")
		(net "PWRGD_DRAMPWRGD_CPU1_AB_R_LVC1")
	)
	(via
		(at 158.11246 -102.149148)
		(size 0.508)
		(drill 0.254)
		(layers "F.Cu" "B.Cu")
		(net "PWRGD_DRAMPWRGD_CPU1_AB_R_LVC1")
	)
	(via
		(at 175.355504 -105.375456)
		(size 0.4572)
		(drill 0.254)
		(layers "F.Cu" "B.Cu")
		(net "PWRGD_DRAMPWRGD_CPU1_AB_R_LVC1")
	)
	(segment
		(start 157.600142 -102.661466)
		(end 156.980128 -102.661466)
		(width 0.12954)
		(layer "B.Cu")
		(net "PWRGD_DRAMPWRGD_CPU1_AB_R_LVC1")
	)
	(segment
		(start 156.980128 -102.661466)
		(end 156.980128 -101.637846)
		(width 0.12954)
		(layer "B.Cu")
		(net "PWRGD_DRAMPWRGD_CPU1_AB_R_LVC1")
	)
	(segment
		(start 158.11246 -102.149148)
		(end 157.600142 -102.661466)
		(width 0.12954)
		(layer "B.Cu")
		(net "PWRGD_DRAMPWRGD_CPU1_AB_R_LVC1")
	)
	(segment
		(start 170.12158 -104.173528)
		(end 165.716204 -104.173528)
		(width 0.127)
		(layer "In15.Cu")
		(net "PWRGD_DRAMPWRGD_CPU1_AB_R_LVC1")
	)
	(segment
		(start 170.23588 -104.287828)
		(end 170.12158 -104.173528)
		(width 0.127)
		(layer "In15.Cu")
		(net "PWRGD_DRAMPWRGD_CPU1_AB_R_LVC1")
	)
	(segment
		(start 158.6611 -102.697788)
		(end 158.11246 -102.149148)
		(width 0.127)
		(layer "In15.Cu")
		(net "PWRGD_DRAMPWRGD_CPU1_AB_R_LVC1")
	)
	(segment
		(start 175.355504 -105.375456)
		(end 174.267876 -104.287828)
		(width 0.127)
		(layer "In15.Cu")
		(net "PWRGD_DRAMPWRGD_CPU1_AB_R_LVC1")
	)
	(segment
		(start 164.240464 -102.697788)
		(end 158.6611 -102.697788)
		(width 0.127)
		(layer "In15.Cu")
		(net "PWRGD_DRAMPWRGD_CPU1_AB_R_LVC1")
	)
	(segment
		(start 174.267876 -104.287828)
		(end 170.23588 -104.287828)
		(width 0.127)
		(layer "In15.Cu")
		(net "PWRGD_DRAMPWRGD_CPU1_AB_R_LVC1")
	)
	(segment
		(start 165.716204 -104.173528)
		(end 164.240464 -102.697788)
		(width 0.127)
		(layer "In15.Cu")
		(net "PWRGD_DRAMPWRGD_CPU1_AB_R_LVC1")
	)
	(segment
		(start 84.51977 -248.528078)
		(end 84.856066 -248.528078)
		(width 0.12954)
		(layer "F.Cu")
		(net "PWRGD_DRAMPWRGD_CPU1_AB_LVC1_R")
	)
	(segment
		(start 84.429092 -248.618756)
		(end 84.51977 -248.528078)
		(width 0.12954)
		(layer "F.Cu")
		(net "PWRGD_DRAMPWRGD_CPU1_AB_LVC1_R")
	)
	(segment
		(start 84.146136 -248.618756)
		(end 84.429092 -248.618756)
		(width 0.12954)
		(layer "F.Cu")
		(net "PWRGD_DRAMPWRGD_CPU1_AB_LVC1_R")
	)
	(via
		(at 82.596228 -248.618756)
		(size 0.6604)
		(drill 0.3302)
		(layers "F.Cu" "B.Cu")
		(net "PWRGD_DRAMPWRGD_CPU1_AB_LVC1_R")
	)
	(via
		(at 84.146136 -248.618756)
		(size 0.4572)
		(drill 0.2032)
		(layers "F.Cu" "B.Cu")
		(net "PWRGD_DRAMPWRGD_CPU1_AB_LVC1_R")
	)
	(segment
		(start 62.566296 -236.047788)
		(end 61.905896 -235.77423)
		(width 0.12954)
		(layer "B.Cu")
		(net "PWRGD_DRAMPWRGD_CPU1_AB_LVC1_R")
	)
	(segment
		(start 63.104268 -198.63054)
		(end 63.104268 -196.210428)
		(width 0.12954)
		(layer "B.Cu")
		(net "PWRGD_DRAMPWRGD_CPU1_AB_LVC1_R")
	)
	(segment
		(start 61.905896 -235.77423)
		(end 61.416438 -235.77423)
		(width 0.12954)
		(layer "B.Cu")
		(net "PWRGD_DRAMPWRGD_CPU1_AB_LVC1_R")
	)
	(segment
		(start 63.9064 -236.82071)
		(end 63.339218 -236.82071)
		(width 0.12954)
		(layer "B.Cu")
		(net "PWRGD_DRAMPWRGD_CPU1_AB_LVC1_R")
	)
	(segment
		(start 81.629758 -248.618756)
		(end 73.403714 -240.392712)
		(width 0.12954)
		(layer "B.Cu")
		(net "PWRGD_DRAMPWRGD_CPU1_AB_LVC1_R")
	)
	(segment
		(start 65.923922 -238.43869)
		(end 65.77838 -238.293148)
		(width 0.1016)
		(layer "B.Cu")
		(net "PWRGD_DRAMPWRGD_CPU1_AB_LVC1_R")
	)
	(segment
		(start 73.403714 -240.392712)
		(end 67.975988 -238.74603)
		(width 0.12954)
		(layer "B.Cu")
		(net "PWRGD_DRAMPWRGD_CPU1_AB_LVC1_R")
	)
	(segment
		(start 59.153298 -210.56727)
		(end 59.366658 -210.35391)
		(width 0.12954)
		(layer "B.Cu")
		(net "PWRGD_DRAMPWRGD_CPU1_AB_LVC1_R")
	)
	(segment
		(start 59.366658 -209.30997)
		(end 59.135518 -209.07883)
		(width 0.12954)
		(layer "B.Cu")
		(net "PWRGD_DRAMPWRGD_CPU1_AB_LVC1_R")
	)
	(segment
		(start 59.153298 -219.88399)
		(end 59.280298 -219.75699)
		(width 0.12954)
		(layer "B.Cu")
		(net "PWRGD_DRAMPWRGD_CPU1_AB_LVC1_R")
	)
	(segment
		(start 63.339218 -236.82071)
		(end 62.566296 -236.047788)
		(width 0.12954)
		(layer "B.Cu")
		(net "PWRGD_DRAMPWRGD_CPU1_AB_LVC1_R")
	)
	(segment
		(start 60.852558 -235.21035)
		(end 59.638438 -235.21035)
		(width 0.12954)
		(layer "B.Cu")
		(net "PWRGD_DRAMPWRGD_CPU1_AB_LVC1_R")
	)
	(segment
		(start 60.75172 -200.983088)
		(end 63.104268 -198.63054)
		(width 0.12954)
		(layer "B.Cu")
		(net "PWRGD_DRAMPWRGD_CPU1_AB_LVC1_R")
	)
	(segment
		(start 59.366658 -210.35391)
		(end 59.366658 -209.30997)
		(width 0.12954)
		(layer "B.Cu")
		(net "PWRGD_DRAMPWRGD_CPU1_AB_LVC1_R")
	)
	(segment
		(start 66.93662 -238.74603)
		(end 65.923922 -238.43869)
		(width 0.1016)
		(layer "B.Cu")
		(net "PWRGD_DRAMPWRGD_CPU1_AB_LVC1_R")
	)
	(segment
		(start 82.596228 -248.618756)
		(end 81.629758 -248.618756)
		(width 0.12954)
		(layer "B.Cu")
		(net "PWRGD_DRAMPWRGD_CPU1_AB_LVC1_R")
	)
	(segment
		(start 84.146136 -248.618756)
		(end 82.596228 -248.618756)
		(width 0.12954)
		(layer "B.Cu")
		(net "PWRGD_DRAMPWRGD_CPU1_AB_LVC1_R")
	)
	(segment
		(start 61.416438 -235.77423)
		(end 60.852558 -235.21035)
		(width 0.12954)
		(layer "B.Cu")
		(net "PWRGD_DRAMPWRGD_CPU1_AB_LVC1_R")
	)
	(segment
		(start 59.153298 -234.72521)
		(end 59.153298 -219.88399)
		(width 0.12954)
		(layer "B.Cu")
		(net "PWRGD_DRAMPWRGD_CPU1_AB_LVC1_R")
	)
	(segment
		(start 59.153298 -218.47683)
		(end 59.153298 -210.56727)
		(width 0.12954)
		(layer "B.Cu")
		(net "PWRGD_DRAMPWRGD_CPU1_AB_LVC1_R")
	)
	(segment
		(start 64.588898 -237.103666)
		(end 63.9064 -236.82071)
		(width 0.12954)
		(layer "B.Cu")
		(net "PWRGD_DRAMPWRGD_CPU1_AB_LVC1_R")
	)
	(segment
		(start 59.641486 -200.983088)
		(end 60.75172 -200.983088)
		(width 0.12954)
		(layer "B.Cu")
		(net "PWRGD_DRAMPWRGD_CPU1_AB_LVC1_R")
	)
	(segment
		(start 59.638438 -235.21035)
		(end 59.153298 -234.72521)
		(width 0.12954)
		(layer "B.Cu")
		(net "PWRGD_DRAMPWRGD_CPU1_AB_LVC1_R")
	)
	(segment
		(start 59.135518 -201.489056)
		(end 59.641486 -200.983088)
		(width 0.12954)
		(layer "B.Cu")
		(net "PWRGD_DRAMPWRGD_CPU1_AB_LVC1_R")
	)
	(segment
		(start 59.280298 -219.75699)
		(end 59.280298 -218.60383)
		(width 0.12954)
		(layer "B.Cu")
		(net "PWRGD_DRAMPWRGD_CPU1_AB_LVC1_R")
	)
	(segment
		(start 67.975988 -238.74603)
		(end 67.14236 -238.74603)
		(width 0.12954)
		(layer "B.Cu")
		(net "PWRGD_DRAMPWRGD_CPU1_AB_LVC1_R")
	)
	(segment
		(start 59.280298 -218.60383)
		(end 59.153298 -218.47683)
		(width 0.12954)
		(layer "B.Cu")
		(net "PWRGD_DRAMPWRGD_CPU1_AB_LVC1_R")
	)
	(segment
		(start 65.77838 -238.293148)
		(end 64.588898 -237.103666)
		(width 0.12954)
		(layer "B.Cu")
		(net "PWRGD_DRAMPWRGD_CPU1_AB_LVC1_R")
	)
	(segment
		(start 59.135518 -209.07883)
		(end 59.135518 -201.489056)
		(width 0.12954)
		(layer "B.Cu")
		(net "PWRGD_DRAMPWRGD_CPU1_AB_LVC1_R")
	)
	(segment
		(start 67.14236 -238.74603)
		(end 66.93662 -238.74603)
		(width 0.1016)
		(layer "B.Cu")
		(net "PWRGD_DRAMPWRGD_CPU1_AB_LVC1_R")
	)
	(segment
		(start 175.755554 -106.575352)
		(end 175.355504 -106.175302)
		(width 0.12954)
		(layer "F.Cu")
		(net "PWRGD_DRAMPWRGD_CPU0_GH_R_LVC1")
	)
	(via
		(at 175.355504 -106.175302)
		(size 0.4572)
		(drill 0.254)
		(layers "F.Cu" "B.Cu")
		(net "PWRGD_DRAMPWRGD_CPU0_GH_R_LVC1")
	)
	(via
		(at 181.046374 -106.776774)
		(size 0.6604)
		(drill 0.3302)
		(layers "F.Cu" "B.Cu")
		(net "PWRGD_DRAMPWRGD_CPU0_GH_R_LVC1")
	)
	(segment
		(start 179.98186 -108.18114)
		(end 181.046374 -107.116626)
		(width 0.12954)
		(layer "B.Cu")
		(net "PWRGD_DRAMPWRGD_CPU0_GH_R_LVC1")
	)
	(segment
		(start 180.449982 -105.520236)
		(end 180.52923 -105.440988)
		(width 0.12954)
		(layer "B.Cu")
		(net "PWRGD_DRAMPWRGD_CPU0_GH_R_LVC1")
	)
	(segment
		(start 175.081946 -106.175302)
		(end 174.9552 -106.302048)
		(width 0.12954)
		(layer "B.Cu")
		(net "PWRGD_DRAMPWRGD_CPU0_GH_R_LVC1")
	)
	(segment
		(start 174.9552 -106.302048)
		(end 174.9552 -108.016548)
		(width 0.12954)
		(layer "B.Cu")
		(net "PWRGD_DRAMPWRGD_CPU0_GH_R_LVC1")
	)
	(segment
		(start 181.046374 -106.522774)
		(end 180.41366 -105.89006)
		(width 0.12954)
		(layer "B.Cu")
		(net "PWRGD_DRAMPWRGD_CPU0_GH_R_LVC1")
	)
	(segment
		(start 180.41366 -105.556558)
		(end 180.449982 -105.520236)
		(width 0.12954)
		(layer "B.Cu")
		(net "PWRGD_DRAMPWRGD_CPU0_GH_R_LVC1")
	)
	(segment
		(start 175.355504 -106.175302)
		(end 175.081946 -106.175302)
		(width 0.12954)
		(layer "B.Cu")
		(net "PWRGD_DRAMPWRGD_CPU0_GH_R_LVC1")
	)
	(segment
		(start 174.9552 -108.016548)
		(end 175.119792 -108.18114)
		(width 0.12954)
		(layer "B.Cu")
		(net "PWRGD_DRAMPWRGD_CPU0_GH_R_LVC1")
	)
	(segment
		(start 181.27472 -105.440988)
		(end 181.475888 -105.23982)
		(width 0.12954)
		(layer "B.Cu")
		(net "PWRGD_DRAMPWRGD_CPU0_GH_R_LVC1")
	)
	(segment
		(start 180.52923 -105.440988)
		(end 181.27472 -105.440988)
		(width 0.12954)
		(layer "B.Cu")
		(net "PWRGD_DRAMPWRGD_CPU0_GH_R_LVC1")
	)
	(segment
		(start 180.41366 -105.89006)
		(end 180.41366 -105.556558)
		(width 0.12954)
		(layer "B.Cu")
		(net "PWRGD_DRAMPWRGD_CPU0_GH_R_LVC1")
	)
	(segment
		(start 181.046374 -107.116626)
		(end 181.046374 -106.776774)
		(width 0.12954)
		(layer "B.Cu")
		(net "PWRGD_DRAMPWRGD_CPU0_GH_R_LVC1")
	)
	(segment
		(start 181.046374 -106.776774)
		(end 181.046374 -106.522774)
		(width 0.12954)
		(layer "B.Cu")
		(net "PWRGD_DRAMPWRGD_CPU0_GH_R_LVC1")
	)
	(segment
		(start 181.475888 -105.23982)
		(end 181.475888 -104.716326)
		(width 0.12954)
		(layer "B.Cu")
		(net "PWRGD_DRAMPWRGD_CPU0_GH_R_LVC1")
	)
	(segment
		(start 175.119792 -108.18114)
		(end 179.98186 -108.18114)
		(width 0.12954)
		(layer "B.Cu")
		(net "PWRGD_DRAMPWRGD_CPU0_GH_R_LVC1")
	)
	(segment
		(start 369.44808 -250.15571)
		(end 369.44808 -249.620024)
		(width 0.12954)
		(layer "F.Cu")
		(net "PWRGD_DRAMPWRGD_CPU0_GH_LVC1_R")
	)
	(segment
		(start 369.448334 -250.155964)
		(end 369.44808 -250.15571)
		(width 0.12954)
		(layer "F.Cu")
		(net "PWRGD_DRAMPWRGD_CPU0_GH_LVC1_R")
	)
	(via
		(at 386.818378 -250.645168)
		(size 0.6604)
		(drill 0.3302)
		(layers "F.Cu" "B.Cu")
		(net "PWRGD_DRAMPWRGD_CPU0_GH_LVC1_R")
	)
	(via
		(at 369.44808 -249.620024)
		(size 0.4572)
		(drill 0.2032)
		(layers "F.Cu" "B.Cu")
		(net "PWRGD_DRAMPWRGD_CPU0_GH_LVC1_R")
	)
	(segment
		(start 373.949468 -249.301762)
		(end 373.959882 -249.295666)
		(width 0.0889)
		(layer "B.Cu")
		(net "PWRGD_DRAMPWRGD_CPU0_GH_LVC1_R")
	)
	(segment
		(start 404.867618 -233.475276)
		(end 404.867618 -200.35647)
		(width 0.12954)
		(layer "B.Cu")
		(net "PWRGD_DRAMPWRGD_CPU0_GH_LVC1_R")
	)
	(segment
		(start 404.867618 -200.35647)
		(end 403.635718 -199.12457)
		(width 0.12954)
		(layer "B.Cu")
		(net "PWRGD_DRAMPWRGD_CPU0_GH_LVC1_R")
	)
	(segment
		(start 369.604544 -249.349006)
		(end 369.693698 -249.32513)
		(width 0.0889)
		(layer "B.Cu")
		(net "PWRGD_DRAMPWRGD_CPU0_GH_LVC1_R")
	)
	(segment
		(start 403.635718 -199.12457)
		(end 403.635718 -197.03415)
		(width 0.12954)
		(layer "B.Cu")
		(net "PWRGD_DRAMPWRGD_CPU0_GH_LVC1_R")
	)
	(segment
		(start 380.051056 -249.355102)
		(end 380.323344 -249.62739)
		(width 0.0889)
		(layer "B.Cu")
		(net "PWRGD_DRAMPWRGD_CPU0_GH_LVC1_R")
	)
	(segment
		(start 373.009922 -249.301762)
		(end 373.020336 -249.295666)
		(width 0.0889)
		(layer "B.Cu")
		(net "PWRGD_DRAMPWRGD_CPU0_GH_LVC1_R")
	)
	(segment
		(start 374.88495 -249.304302)
		(end 374.899682 -249.295666)
		(width 0.0889)
		(layer "B.Cu")
		(net "PWRGD_DRAMPWRGD_CPU0_GH_LVC1_R")
	)
	(segment
		(start 387.697726 -250.645168)
		(end 404.867618 -233.475276)
		(width 0.12954)
		(layer "B.Cu")
		(net "PWRGD_DRAMPWRGD_CPU0_GH_LVC1_R")
	)
	(segment
		(start 402.274786 -195.673218)
		(end 402.274786 -191.307212)
		(width 0.12954)
		(layer "B.Cu")
		(net "PWRGD_DRAMPWRGD_CPU0_GH_LVC1_R")
	)
	(segment
		(start 386.818378 -250.645168)
		(end 387.697726 -250.645168)
		(width 0.12954)
		(layer "B.Cu")
		(net "PWRGD_DRAMPWRGD_CPU0_GH_LVC1_R")
	)
	(segment
		(start 372.06555 -249.304302)
		(end 372.080282 -249.295666)
		(width 0.0889)
		(layer "B.Cu")
		(net "PWRGD_DRAMPWRGD_CPU0_GH_LVC1_R")
	)
	(segment
		(start 381.341122 -250.645168)
		(end 386.818378 -250.645168)
		(width 0.12954)
		(layer "B.Cu")
		(net "PWRGD_DRAMPWRGD_CPU0_GH_LVC1_R")
	)
	(segment
		(start 370.18595 -249.304302)
		(end 370.200682 -249.295666)
		(width 0.0889)
		(layer "B.Cu")
		(net "PWRGD_DRAMPWRGD_CPU0_GH_LVC1_R")
	)
	(segment
		(start 375.82475 -249.304302)
		(end 375.839482 -249.295666)
		(width 0.0889)
		(layer "B.Cu")
		(net "PWRGD_DRAMPWRGD_CPU0_GH_LVC1_R")
	)
	(segment
		(start 402.274786 -191.307212)
		(end 402.336 -191.245998)
		(width 0.12954)
		(layer "B.Cu")
		(net "PWRGD_DRAMPWRGD_CPU0_GH_LVC1_R")
	)
	(segment
		(start 403.635718 -197.03415)
		(end 402.274786 -195.673218)
		(width 0.12954)
		(layer "B.Cu")
		(net "PWRGD_DRAMPWRGD_CPU0_GH_LVC1_R")
	)
	(segment
		(start 379.588522 -249.301762)
		(end 379.598936 -249.295666)
		(width 0.0889)
		(layer "B.Cu")
		(net "PWRGD_DRAMPWRGD_CPU0_GH_LVC1_R")
	)
	(segment
		(start 380.323344 -249.62739)
		(end 381.341122 -250.645168)
		(width 0.12954)
		(layer "B.Cu")
		(net "PWRGD_DRAMPWRGD_CPU0_GH_LVC1_R")
	)
	(segment
		(start 376.76455 -249.304302)
		(end 376.779282 -249.295666)
		(width 0.0889)
		(layer "B.Cu")
		(net "PWRGD_DRAMPWRGD_CPU0_GH_LVC1_R")
	)
	(segment
		(start 369.44808 -249.620024)
		(end 369.604544 -249.349006)
		(width 0.0889)
		(layer "B.Cu")
		(net "PWRGD_DRAMPWRGD_CPU0_GH_LVC1_R")
	)
	(segment
		(start 378.64415 -249.304302)
		(end 378.658882 -249.295666)
		(width 0.0889)
		(layer "B.Cu")
		(net "PWRGD_DRAMPWRGD_CPU0_GH_LVC1_R")
	)
	(arc
		(start 376.213878 -249.295666)
		(mid 376.488077 -249.371501)
		(end 376.76455 -249.304302)
		(width 0.0889)
		(layer "B.Cu")
		(net "PWRGD_DRAMPWRGD_CPU0_GH_LVC1_R")
	)
	(arc
		(start 373.959882 -249.295666)
		(mid 374.14708 -249.245523)
		(end 374.334278 -249.295666)
		(width 0.0889)
		(layer "B.Cu")
		(net "PWRGD_DRAMPWRGD_CPU0_GH_LVC1_R")
	)
	(arc
		(start 375.839482 -249.295666)
		(mid 376.02668 -249.245523)
		(end 376.213878 -249.295666)
		(width 0.0889)
		(layer "B.Cu")
		(net "PWRGD_DRAMPWRGD_CPU0_GH_LVC1_R")
	)
	(arc
		(start 374.899682 -249.295666)
		(mid 375.08688 -249.245523)
		(end 375.274078 -249.295666)
		(width 0.0889)
		(layer "B.Cu")
		(net "PWRGD_DRAMPWRGD_CPU0_GH_LVC1_R")
	)
	(arc
		(start 378.093478 -249.295666)
		(mid 378.367677 -249.371501)
		(end 378.64415 -249.304302)
		(width 0.0889)
		(layer "B.Cu")
		(net "PWRGD_DRAMPWRGD_CPU0_GH_LVC1_R")
	)
	(arc
		(start 372.080282 -249.295666)
		(mid 372.26748 -249.245523)
		(end 372.454678 -249.295666)
		(width 0.0889)
		(layer "B.Cu")
		(net "PWRGD_DRAMPWRGD_CPU0_GH_LVC1_R")
	)
	(arc
		(start 375.274078 -249.295666)
		(mid 375.548277 -249.371501)
		(end 375.82475 -249.304302)
		(width 0.0889)
		(layer "B.Cu")
		(net "PWRGD_DRAMPWRGD_CPU0_GH_LVC1_R")
	)
	(arc
		(start 371.140482 -249.295666)
		(mid 371.32768 -249.245523)
		(end 371.514878 -249.295666)
		(width 0.0889)
		(layer "B.Cu")
		(net "PWRGD_DRAMPWRGD_CPU0_GH_LVC1_R")
	)
	(arc
		(start 374.334278 -249.295666)
		(mid 374.608477 -249.371501)
		(end 374.88495 -249.304302)
		(width 0.0889)
		(layer "B.Cu")
		(net "PWRGD_DRAMPWRGD_CPU0_GH_LVC1_R")
	)
	(arc
		(start 379.973332 -249.295666)
		(mid 380.014141 -249.322838)
		(end 380.051056 -249.355102)
		(width 0.0889)
		(layer "B.Cu")
		(net "PWRGD_DRAMPWRGD_CPU0_GH_LVC1_R")
	)
	(arc
		(start 379.033278 -249.295666)
		(mid 379.310091 -249.371536)
		(end 379.588522 -249.301762)
		(width 0.0889)
		(layer "B.Cu")
		(net "PWRGD_DRAMPWRGD_CPU0_GH_LVC1_R")
	)
	(arc
		(start 372.454678 -249.295666)
		(mid 372.731491 -249.371536)
		(end 373.009922 -249.301762)
		(width 0.0889)
		(layer "B.Cu")
		(net "PWRGD_DRAMPWRGD_CPU0_GH_LVC1_R")
	)
	(arc
		(start 379.598936 -249.295666)
		(mid 379.786134 -249.245523)
		(end 379.973332 -249.295666)
		(width 0.0889)
		(layer "B.Cu")
		(net "PWRGD_DRAMPWRGD_CPU0_GH_LVC1_R")
	)
	(arc
		(start 377.153678 -249.295666)
		(mid 377.43638 -249.371442)
		(end 377.719082 -249.295666)
		(width 0.0889)
		(layer "B.Cu")
		(net "PWRGD_DRAMPWRGD_CPU0_GH_LVC1_R")
	)
	(arc
		(start 377.719082 -249.295666)
		(mid 377.90628 -249.245523)
		(end 378.093478 -249.295666)
		(width 0.0889)
		(layer "B.Cu")
		(net "PWRGD_DRAMPWRGD_CPU0_GH_LVC1_R")
	)
	(arc
		(start 373.394732 -249.295666)
		(mid 373.671291 -249.371409)
		(end 373.949468 -249.301762)
		(width 0.0889)
		(layer "B.Cu")
		(net "PWRGD_DRAMPWRGD_CPU0_GH_LVC1_R")
	)
	(arc
		(start 371.514878 -249.295666)
		(mid 371.789077 -249.371501)
		(end 372.06555 -249.304302)
		(width 0.0889)
		(layer "B.Cu")
		(net "PWRGD_DRAMPWRGD_CPU0_GH_LVC1_R")
	)
	(arc
		(start 370.200682 -249.295666)
		(mid 370.38788 -249.245523)
		(end 370.575078 -249.295666)
		(width 0.0889)
		(layer "B.Cu")
		(net "PWRGD_DRAMPWRGD_CPU0_GH_LVC1_R")
	)
	(arc
		(start 376.779282 -249.295666)
		(mid 376.96648 -249.245523)
		(end 377.153678 -249.295666)
		(width 0.0889)
		(layer "B.Cu")
		(net "PWRGD_DRAMPWRGD_CPU0_GH_LVC1_R")
	)
	(arc
		(start 373.020336 -249.295666)
		(mid 373.207534 -249.245523)
		(end 373.394732 -249.295666)
		(width 0.0889)
		(layer "B.Cu")
		(net "PWRGD_DRAMPWRGD_CPU0_GH_LVC1_R")
	)
	(arc
		(start 369.693698 -249.32513)
		(mid 369.942203 -249.371117)
		(end 370.18595 -249.304302)
		(width 0.0889)
		(layer "B.Cu")
		(net "PWRGD_DRAMPWRGD_CPU0_GH_LVC1_R")
	)
	(arc
		(start 370.575078 -249.295666)
		(mid 370.85778 -249.371442)
		(end 371.140482 -249.295666)
		(width 0.0889)
		(layer "B.Cu")
		(net "PWRGD_DRAMPWRGD_CPU0_GH_LVC1_R")
	)
	(arc
		(start 378.658882 -249.295666)
		(mid 378.84608 -249.245523)
		(end 379.033278 -249.295666)
		(width 0.0889)
		(layer "B.Cu")
		(net "PWRGD_DRAMPWRGD_CPU0_GH_LVC1_R")
	)
	(segment
		(start 175.755554 -107.375452)
		(end 175.355504 -106.975402)
		(width 0.12954)
		(layer "F.Cu")
		(net "PWRGD_DRAMPWRGD_CPU0_EF_R_LVC1")
	)
	(via
		(at 176.0982 -106.263948)
		(size 0.6604)
		(drill 0.3302)
		(layers "F.Cu" "B.Cu")
		(net "PWRGD_DRAMPWRGD_CPU0_EF_R_LVC1")
	)
	(via
		(at 175.355504 -106.975402)
		(size 0.4572)
		(drill 0.254)
		(layers "F.Cu" "B.Cu")
		(net "PWRGD_DRAMPWRGD_CPU0_EF_R_LVC1")
	)
	(segment
		(start 176.066958 -106.263948)
		(end 176.0982 -106.263948)
		(width 0.12954)
		(layer "B.Cu")
		(net "PWRGD_DRAMPWRGD_CPU0_EF_R_LVC1")
	)
	(segment
		(start 177.6603 -107.061)
		(end 177.65014 -107.07116)
		(width 0.12954)
		(layer "B.Cu")
		(net "PWRGD_DRAMPWRGD_CPU0_EF_R_LVC1")
	)
	(segment
		(start 177.6603 -106.045)
		(end 177.6603 -107.061)
		(width 0.12954)
		(layer "B.Cu")
		(net "PWRGD_DRAMPWRGD_CPU0_EF_R_LVC1")
	)
	(segment
		(start 177.35169 -107.36961)
		(end 177.65014 -107.07116)
		(width 0.12954)
		(layer "B.Cu")
		(net "PWRGD_DRAMPWRGD_CPU0_EF_R_LVC1")
	)
	(segment
		(start 176.549812 -106.71556)
		(end 176.549812 -107.228386)
		(width 0.12954)
		(layer "B.Cu")
		(net "PWRGD_DRAMPWRGD_CPU0_EF_R_LVC1")
	)
	(segment
		(start 175.355504 -106.975402)
		(end 176.066958 -106.263948)
		(width 0.12954)
		(layer "B.Cu")
		(net "PWRGD_DRAMPWRGD_CPU0_EF_R_LVC1")
	)
	(segment
		(start 176.0982 -106.263948)
		(end 176.549812 -106.71556)
		(width 0.12954)
		(layer "B.Cu")
		(net "PWRGD_DRAMPWRGD_CPU0_EF_R_LVC1")
	)
	(segment
		(start 176.549812 -107.228386)
		(end 176.691036 -107.36961)
		(width 0.12954)
		(layer "B.Cu")
		(net "PWRGD_DRAMPWRGD_CPU0_EF_R_LVC1")
	)
	(segment
		(start 176.691036 -107.36961)
		(end 177.35169 -107.36961)
		(width 0.12954)
		(layer "B.Cu")
		(net "PWRGD_DRAMPWRGD_CPU0_EF_R_LVC1")
	)
	(segment
		(start 369.91798 -248.806462)
		(end 369.918234 -248.806208)
		(width 0.12954)
		(layer "F.Cu")
		(net "PWRGD_DRAMPWRGD_CPU0_EF_LVC1_R")
	)
	(segment
		(start 369.91798 -249.342148)
		(end 369.91798 -248.806462)
		(width 0.12954)
		(layer "F.Cu")
		(net "PWRGD_DRAMPWRGD_CPU0_EF_LVC1_R")
	)
	(via
		(at 388.835138 -248.43105)
		(size 0.6604)
		(drill 0.3302)
		(layers "F.Cu" "B.Cu")
		(net "PWRGD_DRAMPWRGD_CPU0_EF_LVC1_R")
	)
	(via
		(at 369.918234 -248.806208)
		(size 0.4572)
		(drill 0.2032)
		(layers "F.Cu" "B.Cu")
		(net "PWRGD_DRAMPWRGD_CPU0_EF_LVC1_R")
	)
	(segment
		(start 388.835138 -248.43105)
		(end 387.681978 -249.58421)
		(width 0.12954)
		(layer "B.Cu")
		(net "PWRGD_DRAMPWRGD_CPU0_EF_LVC1_R")
	)
	(segment
		(start 371.999764 -249.12193)
		(end 371.985032 -249.130566)
		(width 0.0889)
		(layer "B.Cu")
		(net "PWRGD_DRAMPWRGD_CPU0_EF_LVC1_R")
	)
	(segment
		(start 402.988018 -199.32777)
		(end 402.988018 -197.12813)
		(width 0.12954)
		(layer "B.Cu")
		(net "PWRGD_DRAMPWRGD_CPU0_EF_LVC1_R")
	)
	(segment
		(start 380.72314 -249.181112)
		(end 380.554738 -249.181112)
		(width 0.12954)
		(layer "B.Cu")
		(net "PWRGD_DRAMPWRGD_CPU0_EF_LVC1_R")
	)
	(segment
		(start 385.241292 -250.042934)
		(end 381.584962 -250.042934)
		(width 0.12954)
		(layer "B.Cu")
		(net "PWRGD_DRAMPWRGD_CPU0_EF_LVC1_R")
	)
	(segment
		(start 373.879364 -249.12193)
		(end 373.864632 -249.130566)
		(width 0.0889)
		(layer "B.Cu")
		(net "PWRGD_DRAMPWRGD_CPU0_EF_LVC1_R")
	)
	(segment
		(start 402.988018 -197.12813)
		(end 401.828 -195.968112)
		(width 0.12954)
		(layer "B.Cu")
		(net "PWRGD_DRAMPWRGD_CPU0_EF_LVC1_R")
	)
	(segment
		(start 380.554738 -249.181112)
		(end 380.256034 -249.181112)
		(width 0.0889)
		(layer "B.Cu")
		(net "PWRGD_DRAMPWRGD_CPU0_EF_LVC1_R")
	)
	(segment
		(start 371.055392 -249.12447)
		(end 371.044978 -249.130566)
		(width 0.0889)
		(layer "B.Cu")
		(net "PWRGD_DRAMPWRGD_CPU0_EF_LVC1_R")
	)
	(segment
		(start 404.357078 -200.69683)
		(end 402.988018 -199.32777)
		(width 0.12954)
		(layer "B.Cu")
		(net "PWRGD_DRAMPWRGD_CPU0_EF_LVC1_R")
	)
	(segment
		(start 388.835138 -248.43105)
		(end 404.357078 -232.90911)
		(width 0.12954)
		(layer "B.Cu")
		(net "PWRGD_DRAMPWRGD_CPU0_EF_LVC1_R")
	)
	(segment
		(start 401.828 -195.968112)
		(end 401.828 -193.023998)
		(width 0.12954)
		(layer "B.Cu")
		(net "PWRGD_DRAMPWRGD_CPU0_EF_LVC1_R")
	)
	(segment
		(start 370.115846 -249.12447)
		(end 370.105432 -249.130566)
		(width 0.0889)
		(layer "B.Cu")
		(net "PWRGD_DRAMPWRGD_CPU0_EF_LVC1_R")
	)
	(segment
		(start 369.782852 -249.155204)
		(end 369.76177 -249.077226)
		(width 0.0889)
		(layer "B.Cu")
		(net "PWRGD_DRAMPWRGD_CPU0_EF_LVC1_R")
	)
	(segment
		(start 404.357078 -232.90911)
		(end 404.357078 -200.69683)
		(width 0.12954)
		(layer "B.Cu")
		(net "PWRGD_DRAMPWRGD_CPU0_EF_LVC1_R")
	)
	(segment
		(start 381.584962 -250.042934)
		(end 380.72314 -249.181112)
		(width 0.12954)
		(layer "B.Cu")
		(net "PWRGD_DRAMPWRGD_CPU0_EF_LVC1_R")
	)
	(segment
		(start 374.819164 -249.12193)
		(end 374.804432 -249.130566)
		(width 0.0889)
		(layer "B.Cu")
		(net "PWRGD_DRAMPWRGD_CPU0_EF_LVC1_R")
	)
	(segment
		(start 378.578364 -249.12193)
		(end 378.563632 -249.130566)
		(width 0.0889)
		(layer "B.Cu")
		(net "PWRGD_DRAMPWRGD_CPU0_EF_LVC1_R")
	)
	(segment
		(start 375.758964 -249.12193)
		(end 375.744232 -249.130566)
		(width 0.0889)
		(layer "B.Cu")
		(net "PWRGD_DRAMPWRGD_CPU0_EF_LVC1_R")
	)
	(segment
		(start 369.76177 -249.077226)
		(end 369.918234 -248.806208)
		(width 0.0889)
		(layer "B.Cu")
		(net "PWRGD_DRAMPWRGD_CPU0_EF_LVC1_R")
	)
	(segment
		(start 385.700016 -249.58421)
		(end 385.241292 -250.042934)
		(width 0.12954)
		(layer "B.Cu")
		(net "PWRGD_DRAMPWRGD_CPU0_EF_LVC1_R")
	)
	(segment
		(start 376.694446 -249.12447)
		(end 376.684032 -249.130566)
		(width 0.0889)
		(layer "B.Cu")
		(net "PWRGD_DRAMPWRGD_CPU0_EF_LVC1_R")
	)
	(segment
		(start 387.681978 -249.58421)
		(end 385.700016 -249.58421)
		(width 0.12954)
		(layer "B.Cu")
		(net "PWRGD_DRAMPWRGD_CPU0_EF_LVC1_R")
	)
	(segment
		(start 377.633992 -249.12447)
		(end 377.623578 -249.130566)
		(width 0.0889)
		(layer "B.Cu")
		(net "PWRGD_DRAMPWRGD_CPU0_EF_LVC1_R")
	)
	(arc
		(start 378.563632 -249.130566)
		(mid 378.376434 -249.180709)
		(end 378.189236 -249.130566)
		(width 0.0889)
		(layer "B.Cu")
		(net "PWRGD_DRAMPWRGD_CPU0_EF_LVC1_R")
	)
	(arc
		(start 379.129036 -249.130566)
		(mid 378.854837 -249.054731)
		(end 378.578364 -249.12193)
		(width 0.0889)
		(layer "B.Cu")
		(net "PWRGD_DRAMPWRGD_CPU0_EF_LVC1_R")
	)
	(arc
		(start 373.490236 -249.130566)
		(mid 373.207534 -249.05479)
		(end 372.924832 -249.130566)
		(width 0.0889)
		(layer "B.Cu")
		(net "PWRGD_DRAMPWRGD_CPU0_EF_LVC1_R")
	)
	(arc
		(start 377.623578 -249.130566)
		(mid 377.43638 -249.180709)
		(end 377.249182 -249.130566)
		(width 0.0889)
		(layer "B.Cu")
		(net "PWRGD_DRAMPWRGD_CPU0_EF_LVC1_R")
	)
	(arc
		(start 370.105432 -249.130566)
		(mid 369.946944 -249.179499)
		(end 369.782852 -249.155204)
		(width 0.0889)
		(layer "B.Cu")
		(net "PWRGD_DRAMPWRGD_CPU0_EF_LVC1_R")
	)
	(arc
		(start 380.068836 -249.130566)
		(mid 379.786134 -249.05479)
		(end 379.503432 -249.130566)
		(width 0.0889)
		(layer "B.Cu")
		(net "PWRGD_DRAMPWRGD_CPU0_EF_LVC1_R")
	)
	(arc
		(start 374.804432 -249.130566)
		(mid 374.617234 -249.180709)
		(end 374.430036 -249.130566)
		(width 0.0889)
		(layer "B.Cu")
		(net "PWRGD_DRAMPWRGD_CPU0_EF_LVC1_R")
	)
	(arc
		(start 377.249182 -249.130566)
		(mid 376.972623 -249.054823)
		(end 376.694446 -249.12447)
		(width 0.0889)
		(layer "B.Cu")
		(net "PWRGD_DRAMPWRGD_CPU0_EF_LVC1_R")
	)
	(arc
		(start 371.985032 -249.130566)
		(mid 371.797834 -249.180709)
		(end 371.610636 -249.130566)
		(width 0.0889)
		(layer "B.Cu")
		(net "PWRGD_DRAMPWRGD_CPU0_EF_LVC1_R")
	)
	(arc
		(start 376.309636 -249.130566)
		(mid 376.035437 -249.054731)
		(end 375.758964 -249.12193)
		(width 0.0889)
		(layer "B.Cu")
		(net "PWRGD_DRAMPWRGD_CPU0_EF_LVC1_R")
	)
	(arc
		(start 370.670582 -249.130566)
		(mid 370.394023 -249.054823)
		(end 370.115846 -249.12447)
		(width 0.0889)
		(layer "B.Cu")
		(net "PWRGD_DRAMPWRGD_CPU0_EF_LVC1_R")
	)
	(arc
		(start 375.744232 -249.130566)
		(mid 375.557034 -249.180709)
		(end 375.369836 -249.130566)
		(width 0.0889)
		(layer "B.Cu")
		(net "PWRGD_DRAMPWRGD_CPU0_EF_LVC1_R")
	)
	(arc
		(start 376.684032 -249.130566)
		(mid 376.496834 -249.180709)
		(end 376.309636 -249.130566)
		(width 0.0889)
		(layer "B.Cu")
		(net "PWRGD_DRAMPWRGD_CPU0_EF_LVC1_R")
	)
	(arc
		(start 373.864632 -249.130566)
		(mid 373.677434 -249.180709)
		(end 373.490236 -249.130566)
		(width 0.0889)
		(layer "B.Cu")
		(net "PWRGD_DRAMPWRGD_CPU0_EF_LVC1_R")
	)
	(arc
		(start 371.610636 -249.130566)
		(mid 371.333823 -249.054696)
		(end 371.055392 -249.12447)
		(width 0.0889)
		(layer "B.Cu")
		(net "PWRGD_DRAMPWRGD_CPU0_EF_LVC1_R")
	)
	(arc
		(start 375.369836 -249.130566)
		(mid 375.095637 -249.054731)
		(end 374.819164 -249.12193)
		(width 0.0889)
		(layer "B.Cu")
		(net "PWRGD_DRAMPWRGD_CPU0_EF_LVC1_R")
	)
	(arc
		(start 371.044978 -249.130566)
		(mid 370.85778 -249.180709)
		(end 370.670582 -249.130566)
		(width 0.0889)
		(layer "B.Cu")
		(net "PWRGD_DRAMPWRGD_CPU0_EF_LVC1_R")
	)
	(arc
		(start 372.924832 -249.130566)
		(mid 372.737634 -249.180709)
		(end 372.550436 -249.130566)
		(width 0.0889)
		(layer "B.Cu")
		(net "PWRGD_DRAMPWRGD_CPU0_EF_LVC1_R")
	)
	(arc
		(start 378.189236 -249.130566)
		(mid 377.912423 -249.054696)
		(end 377.633992 -249.12447)
		(width 0.0889)
		(layer "B.Cu")
		(net "PWRGD_DRAMPWRGD_CPU0_EF_LVC1_R")
	)
	(arc
		(start 374.430036 -249.130566)
		(mid 374.155837 -249.054731)
		(end 373.879364 -249.12193)
		(width 0.0889)
		(layer "B.Cu")
		(net "PWRGD_DRAMPWRGD_CPU0_EF_LVC1_R")
	)
	(arc
		(start 372.550436 -249.130566)
		(mid 372.276237 -249.054731)
		(end 371.999764 -249.12193)
		(width 0.0889)
		(layer "B.Cu")
		(net "PWRGD_DRAMPWRGD_CPU0_EF_LVC1_R")
	)
	(arc
		(start 379.503432 -249.130566)
		(mid 379.316234 -249.180709)
		(end 379.129036 -249.130566)
		(width 0.0889)
		(layer "B.Cu")
		(net "PWRGD_DRAMPWRGD_CPU0_EF_LVC1_R")
	)
	(arc
		(start 380.256034 -249.181112)
		(mid 380.159111 -249.168154)
		(end 380.068836 -249.130566)
		(width 0.0889)
		(layer "B.Cu")
		(net "PWRGD_DRAMPWRGD_CPU0_EF_LVC1_R")
	)
	(segment
		(start 174.04334 -98.768408)
		(end 173.5328 -98.768408)
		(width 0.12954)
		(layer "F.Cu")
		(net "PWRGD_DRAMPWRGD_CPU0_CD_R_LVC1")
	)
	(segment
		(start 174.955708 -104.975406)
		(end 174.955708 -102.768908)
		(width 0.12954)
		(layer "F.Cu")
		(net "PWRGD_DRAMPWRGD_CPU0_CD_R_LVC1")
	)
	(segment
		(start 174.014384 -101.827584)
		(end 173.564804 -100.740972)
		(width 0.12954)
		(layer "F.Cu")
		(net "PWRGD_DRAMPWRGD_CPU0_CD_R_LVC1")
	)
	(segment
		(start 173.5328 -98.768408)
		(end 173.26356 -99.037648)
		(width 0.12954)
		(layer "F.Cu")
		(net "PWRGD_DRAMPWRGD_CPU0_CD_R_LVC1")
	)
	(segment
		(start 174.955708 -102.768908)
		(end 174.014384 -101.827584)
		(width 0.12954)
		(layer "F.Cu")
		(net "PWRGD_DRAMPWRGD_CPU0_CD_R_LVC1")
	)
	(segment
		(start 173.564804 -100.740972)
		(end 173.26356 -100.439728)
		(width 0.12954)
		(layer "F.Cu")
		(net "PWRGD_DRAMPWRGD_CPU0_CD_R_LVC1")
	)
	(segment
		(start 173.26356 -100.439728)
		(end 173.26356 -99.931728)
		(width 0.12954)
		(layer "F.Cu")
		(net "PWRGD_DRAMPWRGD_CPU0_CD_R_LVC1")
	)
	(segment
		(start 173.26356 -99.037648)
		(end 173.26356 -99.931728)
		(width 0.12954)
		(layer "F.Cu")
		(net "PWRGD_DRAMPWRGD_CPU0_CD_R_LVC1")
	)
	(via
		(at 173.26356 -99.931728)
		(size 0.762)
		(drill 0.381)
		(layers "F.Cu" "B.Cu")
		(net "PWRGD_DRAMPWRGD_CPU0_CD_R_LVC1")
	)
	(via
		(at 174.04334 -98.768408)
		(size 0.508)
		(drill 0.254)
		(layers "F.Cu" "B.Cu")
		(net "PWRGD_DRAMPWRGD_CPU0_CD_R_LVC1")
	)
	(segment
		(start 174.04334 -97.655888)
		(end 174.777908 -96.92132)
		(width 0.12954)
		(layer "B.Cu")
		(net "PWRGD_DRAMPWRGD_CPU0_CD_R_LVC1")
	)
	(segment
		(start 175.830738 -96.92132)
		(end 174.814738 -96.92132)
		(width 0.12954)
		(layer "B.Cu")
		(net "PWRGD_DRAMPWRGD_CPU0_CD_R_LVC1")
	)
	(segment
		(start 174.777908 -96.92132)
		(end 174.814738 -96.92132)
		(width 0.12954)
		(layer "B.Cu")
		(net "PWRGD_DRAMPWRGD_CPU0_CD_R_LVC1")
	)
	(segment
		(start 174.04334 -98.768408)
		(end 174.04334 -97.655888)
		(width 0.12954)
		(layer "B.Cu")
		(net "PWRGD_DRAMPWRGD_CPU0_CD_R_LVC1")
	)
	(segment
		(start 335.255362 -253.383796)
		(end 335.255362 -253.919736)
		(width 0.12954)
		(layer "F.Cu")
		(net "PWRGD_DRAMPWRGD_CPU0_CD_LVC1_R")
	)
	(via
		(at 329.345798 -246.57177)
		(size 0.6604)
		(drill 0.3302)
		(layers "F.Cu" "B.Cu")
		(net "PWRGD_DRAMPWRGD_CPU0_CD_LVC1_R")
	)
	(via
		(at 335.255362 -253.919736)
		(size 0.4572)
		(drill 0.2032)
		(layers "F.Cu" "B.Cu")
		(net "PWRGD_DRAMPWRGD_CPU0_CD_LVC1_R")
	)
	(segment
		(start 299.730668 -199.202548)
		(end 299.679868 -199.151748)
		(width 0.12954)
		(layer "B.Cu")
		(net "PWRGD_DRAMPWRGD_CPU0_CD_LVC1_R")
	)
	(segment
		(start 330.78547 -246.57177)
		(end 329.345798 -246.57177)
		(width 0.12954)
		(layer "B.Cu")
		(net "PWRGD_DRAMPWRGD_CPU0_CD_LVC1_R")
	)
	(segment
		(start 299.665898 -237.04677)
		(end 299.498258 -236.87913)
		(width 0.12954)
		(layer "B.Cu")
		(net "PWRGD_DRAMPWRGD_CPU0_CD_LVC1_R")
	)
	(segment
		(start 335.255362 -253.919736)
		(end 333.67345 -252.337824)
		(width 0.12954)
		(layer "B.Cu")
		(net "PWRGD_DRAMPWRGD_CPU0_CD_LVC1_R")
	)
	(segment
		(start 301.941738 -241.51463)
		(end 299.665898 -239.23879)
		(width 0.12954)
		(layer "B.Cu")
		(net "PWRGD_DRAMPWRGD_CPU0_CD_LVC1_R")
	)
	(segment
		(start 299.679868 -199.151748)
		(end 299.679868 -198.598028)
		(width 0.12954)
		(layer "B.Cu")
		(net "PWRGD_DRAMPWRGD_CPU0_CD_LVC1_R")
	)
	(segment
		(start 311.271158 -246.57177)
		(end 310.659018 -247.18391)
		(width 0.12954)
		(layer "B.Cu")
		(net "PWRGD_DRAMPWRGD_CPU0_CD_LVC1_R")
	)
	(segment
		(start 329.345798 -246.57177)
		(end 311.271158 -246.57177)
		(width 0.12954)
		(layer "B.Cu")
		(net "PWRGD_DRAMPWRGD_CPU0_CD_LVC1_R")
	)
	(segment
		(start 299.730668 -199.427338)
		(end 299.730668 -199.202548)
		(width 0.12954)
		(layer "B.Cu")
		(net "PWRGD_DRAMPWRGD_CPU0_CD_LVC1_R")
	)
	(segment
		(start 303.257458 -244.25275)
		(end 303.257458 -241.99469)
		(width 0.12954)
		(layer "B.Cu")
		(net "PWRGD_DRAMPWRGD_CPU0_CD_LVC1_R")
	)
	(segment
		(start 299.665898 -239.23879)
		(end 299.665898 -237.04677)
		(width 0.12954)
		(layer "B.Cu")
		(net "PWRGD_DRAMPWRGD_CPU0_CD_LVC1_R")
	)
	(segment
		(start 304.197258 -245.19255)
		(end 303.257458 -244.25275)
		(width 0.12954)
		(layer "B.Cu")
		(net "PWRGD_DRAMPWRGD_CPU0_CD_LVC1_R")
	)
	(segment
		(start 333.67345 -252.337824)
		(end 333.67345 -249.45975)
		(width 0.12954)
		(layer "B.Cu")
		(net "PWRGD_DRAMPWRGD_CPU0_CD_LVC1_R")
	)
	(segment
		(start 333.67345 -249.45975)
		(end 330.78547 -246.57177)
		(width 0.12954)
		(layer "B.Cu")
		(net "PWRGD_DRAMPWRGD_CPU0_CD_LVC1_R")
	)
	(segment
		(start 299.498258 -199.659748)
		(end 299.730668 -199.427338)
		(width 0.12954)
		(layer "B.Cu")
		(net "PWRGD_DRAMPWRGD_CPU0_CD_LVC1_R")
	)
	(segment
		(start 309.282338 -247.18391)
		(end 307.290978 -245.19255)
		(width 0.12954)
		(layer "B.Cu")
		(net "PWRGD_DRAMPWRGD_CPU0_CD_LVC1_R")
	)
	(segment
		(start 310.659018 -247.18391)
		(end 309.282338 -247.18391)
		(width 0.12954)
		(layer "B.Cu")
		(net "PWRGD_DRAMPWRGD_CPU0_CD_LVC1_R")
	)
	(segment
		(start 299.498258 -236.87913)
		(end 299.498258 -199.659748)
		(width 0.12954)
		(layer "B.Cu")
		(net "PWRGD_DRAMPWRGD_CPU0_CD_LVC1_R")
	)
	(segment
		(start 302.777398 -241.51463)
		(end 301.941738 -241.51463)
		(width 0.12954)
		(layer "B.Cu")
		(net "PWRGD_DRAMPWRGD_CPU0_CD_LVC1_R")
	)
	(segment
		(start 303.257458 -241.99469)
		(end 302.777398 -241.51463)
		(width 0.12954)
		(layer "B.Cu")
		(net "PWRGD_DRAMPWRGD_CPU0_CD_LVC1_R")
	)
	(segment
		(start 307.290978 -245.19255)
		(end 304.197258 -245.19255)
		(width 0.12954)
		(layer "B.Cu")
		(net "PWRGD_DRAMPWRGD_CPU0_CD_LVC1_R")
	)
	(segment
		(start 174.955708 -105.775506)
		(end 174.555658 -105.375456)
		(width 0.12954)
		(layer "F.Cu")
		(net "PWRGD_DRAMPWRGD_CPU0_AB_R_LVC1")
	)
	(via
		(at 174.555658 -105.375456)
		(size 0.4572)
		(drill 0.254)
		(layers "F.Cu" "B.Cu")
		(net "PWRGD_DRAMPWRGD_CPU0_AB_R_LVC1")
	)
	(via
		(at 176.49952 -104.71277)
		(size 0.6604)
		(drill 0.3302)
		(layers "F.Cu" "B.Cu")
		(net "PWRGD_DRAMPWRGD_CPU0_AB_R_LVC1")
	)
	(segment
		(start 175.748442 -103.498396)
		(end 175.174402 -103.498396)
		(width 0.12954)
		(layer "B.Cu")
		(net "PWRGD_DRAMPWRGD_CPU0_AB_R_LVC1")
	)
	(segment
		(start 176.49952 -104.249474)
		(end 175.748442 -103.498396)
		(width 0.12954)
		(layer "B.Cu")
		(net "PWRGD_DRAMPWRGD_CPU0_AB_R_LVC1")
	)
	(segment
		(start 176.49952 -104.71277)
		(end 176.49952 -104.249474)
		(width 0.12954)
		(layer "B.Cu")
		(net "PWRGD_DRAMPWRGD_CPU0_AB_R_LVC1")
	)
	(segment
		(start 177.720752 -104.71277)
		(end 176.49952 -104.71277)
		(width 0.12954)
		(layer "B.Cu")
		(net "PWRGD_DRAMPWRGD_CPU0_AB_R_LVC1")
	)
	(segment
		(start 174.555658 -105.375456)
		(end 175.174402 -104.756712)
		(width 0.12954)
		(layer "B.Cu")
		(net "PWRGD_DRAMPWRGD_CPU0_AB_R_LVC1")
	)
	(segment
		(start 175.174402 -104.756712)
		(end 175.174402 -103.498396)
		(width 0.12954)
		(layer "B.Cu")
		(net "PWRGD_DRAMPWRGD_CPU0_AB_R_LVC1")
	)
	(segment
		(start 332.705456 -248.618756)
		(end 332.086204 -248.618756)
		(width 0.12954)
		(layer "F.Cu")
		(net "PWRGD_DRAMPWRGD_CPU0_AB_LVC1_R")
	)
	(segment
		(start 332.796134 -248.528078)
		(end 332.705456 -248.618756)
		(width 0.12954)
		(layer "F.Cu")
		(net "PWRGD_DRAMPWRGD_CPU0_AB_LVC1_R")
	)
	(via
		(at 318.284098 -248.61901)
		(size 0.6604)
		(drill 0.3302)
		(layers "F.Cu" "B.Cu")
		(net "PWRGD_DRAMPWRGD_CPU0_AB_LVC1_R")
	)
	(via
		(at 332.086204 -248.618756)
		(size 0.4572)
		(drill 0.2032)
		(layers "F.Cu" "B.Cu")
		(net "PWRGD_DRAMPWRGD_CPU0_AB_LVC1_R")
	)
	(segment
		(start 303.572418 -249.05843)
		(end 303.572418 -250.31827)
		(width 0.12954)
		(layer "B.Cu")
		(net "PWRGD_DRAMPWRGD_CPU0_AB_LVC1_R")
	)
	(segment
		(start 299.698918 -250.63577)
		(end 299.475398 -250.41225)
		(width 0.12954)
		(layer "B.Cu")
		(net "PWRGD_DRAMPWRGD_CPU0_AB_LVC1_R")
	)
	(segment
		(start 310.516778 -247.83415)
		(end 307.186838 -247.83415)
		(width 0.12954)
		(layer "B.Cu")
		(net "PWRGD_DRAMPWRGD_CPU0_AB_LVC1_R")
	)
	(segment
		(start 307.186838 -247.83415)
		(end 306.798218 -248.22277)
		(width 0.12954)
		(layer "B.Cu")
		(net "PWRGD_DRAMPWRGD_CPU0_AB_LVC1_R")
	)
	(segment
		(start 332.086204 -248.618756)
		(end 320.890646 -248.618756)
		(width 0.12954)
		(layer "B.Cu")
		(net "PWRGD_DRAMPWRGD_CPU0_AB_LVC1_R")
	)
	(segment
		(start 298.400978 -250.09983)
		(end 298.400978 -197.653148)
		(width 0.12954)
		(layer "B.Cu")
		(net "PWRGD_DRAMPWRGD_CPU0_AB_LVC1_R")
	)
	(segment
		(start 298.400978 -197.653148)
		(end 297.876468 -197.128638)
		(width 0.12954)
		(layer "B.Cu")
		(net "PWRGD_DRAMPWRGD_CPU0_AB_LVC1_R")
	)
	(segment
		(start 297.876468 -197.128638)
		(end 297.876468 -196.591428)
		(width 0.12954)
		(layer "B.Cu")
		(net "PWRGD_DRAMPWRGD_CPU0_AB_LVC1_R")
	)
	(segment
		(start 320.890646 -248.618756)
		(end 320.890646 -248.61901)
		(width 0.12954)
		(layer "B.Cu")
		(net "PWRGD_DRAMPWRGD_CPU0_AB_LVC1_R")
	)
	(segment
		(start 315.312298 -248.61901)
		(end 314.850018 -248.15673)
		(width 0.12954)
		(layer "B.Cu")
		(net "PWRGD_DRAMPWRGD_CPU0_AB_LVC1_R")
	)
	(segment
		(start 306.798218 -248.22277)
		(end 304.408078 -248.22277)
		(width 0.12954)
		(layer "B.Cu")
		(net "PWRGD_DRAMPWRGD_CPU0_AB_LVC1_R")
	)
	(segment
		(start 298.713398 -250.41225)
		(end 298.400978 -250.09983)
		(width 0.12954)
		(layer "B.Cu")
		(net "PWRGD_DRAMPWRGD_CPU0_AB_LVC1_R")
	)
	(segment
		(start 318.284098 -248.61901)
		(end 315.312298 -248.61901)
		(width 0.12954)
		(layer "B.Cu")
		(net "PWRGD_DRAMPWRGD_CPU0_AB_LVC1_R")
	)
	(segment
		(start 303.254918 -250.63577)
		(end 299.698918 -250.63577)
		(width 0.12954)
		(layer "B.Cu")
		(net "PWRGD_DRAMPWRGD_CPU0_AB_LVC1_R")
	)
	(segment
		(start 303.572418 -250.31827)
		(end 303.254918 -250.63577)
		(width 0.12954)
		(layer "B.Cu")
		(net "PWRGD_DRAMPWRGD_CPU0_AB_LVC1_R")
	)
	(segment
		(start 310.839358 -248.15673)
		(end 310.516778 -247.83415)
		(width 0.12954)
		(layer "B.Cu")
		(net "PWRGD_DRAMPWRGD_CPU0_AB_LVC1_R")
	)
	(segment
		(start 299.475398 -250.41225)
		(end 298.713398 -250.41225)
		(width 0.12954)
		(layer "B.Cu")
		(net "PWRGD_DRAMPWRGD_CPU0_AB_LVC1_R")
	)
	(segment
		(start 314.850018 -248.15673)
		(end 310.839358 -248.15673)
		(width 0.12954)
		(layer "B.Cu")
		(net "PWRGD_DRAMPWRGD_CPU0_AB_LVC1_R")
	)
	(segment
		(start 320.890646 -248.61901)
		(end 318.284098 -248.61901)
		(width 0.12954)
		(layer "B.Cu")
		(net "PWRGD_DRAMPWRGD_CPU0_AB_LVC1_R")
	)
	(segment
		(start 304.408078 -248.22277)
		(end 303.572418 -249.05843)
		(width 0.12954)
		(layer "B.Cu")
		(net "PWRGD_DRAMPWRGD_CPU0_AB_LVC1_R")
	)
	(segment
		(start 310.68772 -53.480208)
		(end 310.68772 -52.969922)
		(width 0.12954)
		(layer "F.Cu")
		(net "PWRGD_CPUPWRGD_LVC1_R")
	)
	(segment
		(start 310.368696 -52.650898)
		(end 310.007 -52.650898)
		(width 0.12954)
		(layer "F.Cu")
		(net "PWRGD_CPUPWRGD_LVC1_R")
	)
	(segment
		(start 113.21288 -103.449628)
		(end 113.21288 -102.193598)
		(width 0.12954)
		(layer "F.Cu")
		(net "PWRGD_CPUPWRGD_LVC1_R")
	)
	(segment
		(start 310.68772 -52.969922)
		(end 310.368696 -52.650898)
		(width 0.12954)
		(layer "F.Cu")
		(net "PWRGD_CPUPWRGD_LVC1_R")
	)
	(segment
		(start 113.66246 -103.899208)
		(end 113.21288 -103.449628)
		(width 0.12954)
		(layer "F.Cu")
		(net "PWRGD_CPUPWRGD_LVC1_R")
	)
	(via
		(at 310.68772 -53.480208)
		(size 0.508)
		(drill 0.254)
		(layers "F.Cu" "B.Cu")
		(net "PWRGD_CPUPWRGD_LVC1_R")
	)
	(via
		(at 284.095444 -53.071268)
		(size 0.508)
		(drill 0.254)
		(layers "F.Cu" "B.Cu")
		(net "PWRGD_CPUPWRGD_LVC1_R")
	)
	(via
		(at 113.66246 -103.899208)
		(size 0.508)
		(drill 0.254)
		(layers "F.Cu" "B.Cu")
		(net "PWRGD_CPUPWRGD_LVC1_R")
	)
	(segment
		(start 308.02326 -54.831488)
		(end 304.59934 -54.831488)
		(width 0.127)
		(layer "In6.Cu")
		(net "PWRGD_CPUPWRGD_LVC1_R")
	)
	(segment
		(start 309.37454 -53.480208)
		(end 308.02326 -54.831488)
		(width 0.127)
		(layer "In6.Cu")
		(net "PWRGD_CPUPWRGD_LVC1_R")
	)
	(segment
		(start 304.1142 -54.346348)
		(end 295.94048 -54.346348)
		(width 0.127)
		(layer "In6.Cu")
		(net "PWRGD_CPUPWRGD_LVC1_R")
	)
	(segment
		(start 291.232336 -54.828948)
		(end 290.851336 -54.447948)
		(width 0.127)
		(layer "In6.Cu")
		(net "PWRGD_CPUPWRGD_LVC1_R")
	)
	(segment
		(start 310.68772 -53.480208)
		(end 309.37454 -53.480208)
		(width 0.127)
		(layer "In6.Cu")
		(net "PWRGD_CPUPWRGD_LVC1_R")
	)
	(segment
		(start 295.94048 -54.346348)
		(end 295.45788 -54.828948)
		(width 0.127)
		(layer "In6.Cu")
		(net "PWRGD_CPUPWRGD_LVC1_R")
	)
	(segment
		(start 295.45788 -54.828948)
		(end 291.232336 -54.828948)
		(width 0.127)
		(layer "In6.Cu")
		(net "PWRGD_CPUPWRGD_LVC1_R")
	)
	(segment
		(start 304.59934 -54.831488)
		(end 304.1142 -54.346348)
		(width 0.127)
		(layer "In6.Cu")
		(net "PWRGD_CPUPWRGD_LVC1_R")
	)
	(segment
		(start 290.851336 -54.447948)
		(end 285.472124 -54.447948)
		(width 0.127)
		(layer "In6.Cu")
		(net "PWRGD_CPUPWRGD_LVC1_R")
	)
	(segment
		(start 285.472124 -54.447948)
		(end 284.095444 -53.071268)
		(width 0.127)
		(layer "In6.Cu")
		(net "PWRGD_CPUPWRGD_LVC1_R")
	)
	(segment
		(start 115.60048 -100.838508)
		(end 115.19662 -100.434648)
		(width 0.127)
		(layer "In11.Cu")
		(net "PWRGD_CPUPWRGD_LVC1_R")
	)
	(segment
		(start 109.9693 -100.434648)
		(end 108.83646 -101.567488)
		(width 0.127)
		(layer "In11.Cu")
		(net "PWRGD_CPUPWRGD_LVC1_R")
	)
	(segment
		(start 109.75086 -103.899208)
		(end 113.66246 -103.899208)
		(width 0.127)
		(layer "In11.Cu")
		(net "PWRGD_CPUPWRGD_LVC1_R")
	)
	(segment
		(start 282.718764 -54.447948)
		(end 281.23515 -54.447948)
		(width 0.127)
		(layer "In11.Cu")
		(net "PWRGD_CPUPWRGD_LVC1_R")
	)
	(segment
		(start 153.996136 -82.499962)
		(end 150.75535 -85.740748)
		(width 0.127)
		(layer "In11.Cu")
		(net "PWRGD_CPUPWRGD_LVC1_R")
	)
	(segment
		(start 108.83646 -102.984808)
		(end 109.75086 -103.899208)
		(width 0.127)
		(layer "In11.Cu")
		(net "PWRGD_CPUPWRGD_LVC1_R")
	)
	(segment
		(start 254.46355 -63.236348)
		(end 242.99799 -63.236348)
		(width 0.127)
		(layer "In11.Cu")
		(net "PWRGD_CPUPWRGD_LVC1_R")
	)
	(segment
		(start 118.30304 -100.838508)
		(end 115.60048 -100.838508)
		(width 0.127)
		(layer "In11.Cu")
		(net "PWRGD_CPUPWRGD_LVC1_R")
	)
	(segment
		(start 128.87706 -98.682048)
		(end 127.12446 -100.434648)
		(width 0.127)
		(layer "In11.Cu")
		(net "PWRGD_CPUPWRGD_LVC1_R")
	)
	(segment
		(start 274.91055 -60.772548)
		(end 256.92735 -60.772548)
		(width 0.127)
		(layer "In11.Cu")
		(net "PWRGD_CPUPWRGD_LVC1_R")
	)
	(segment
		(start 115.19662 -100.434648)
		(end 109.9693 -100.434648)
		(width 0.127)
		(layer "In11.Cu")
		(net "PWRGD_CPUPWRGD_LVC1_R")
	)
	(segment
		(start 149.53615 -85.740748)
		(end 147.17268 -88.104218)
		(width 0.127)
		(layer "In11.Cu")
		(net "PWRGD_CPUPWRGD_LVC1_R")
	)
	(segment
		(start 281.23515 -54.447948)
		(end 274.91055 -60.772548)
		(width 0.127)
		(layer "In11.Cu")
		(net "PWRGD_CPUPWRGD_LVC1_R")
	)
	(segment
		(start 284.095444 -53.071268)
		(end 282.718764 -54.447948)
		(width 0.127)
		(layer "In11.Cu")
		(net "PWRGD_CPUPWRGD_LVC1_R")
	)
	(segment
		(start 242.99799 -63.236348)
		(end 239.59693 -66.637408)
		(width 0.127)
		(layer "In11.Cu")
		(net "PWRGD_CPUPWRGD_LVC1_R")
	)
	(segment
		(start 256.92735 -60.772548)
		(end 254.46355 -63.236348)
		(width 0.127)
		(layer "In11.Cu")
		(net "PWRGD_CPUPWRGD_LVC1_R")
	)
	(segment
		(start 235.06811 -66.637408)
		(end 219.205556 -82.499962)
		(width 0.127)
		(layer "In11.Cu")
		(net "PWRGD_CPUPWRGD_LVC1_R")
	)
	(segment
		(start 137.50925 -98.682048)
		(end 128.87706 -98.682048)
		(width 0.127)
		(layer "In11.Cu")
		(net "PWRGD_CPUPWRGD_LVC1_R")
	)
	(segment
		(start 127.12446 -100.434648)
		(end 118.7069 -100.434648)
		(width 0.127)
		(layer "In11.Cu")
		(net "PWRGD_CPUPWRGD_LVC1_R")
	)
	(segment
		(start 118.7069 -100.434648)
		(end 118.30304 -100.838508)
		(width 0.127)
		(layer "In11.Cu")
		(net "PWRGD_CPUPWRGD_LVC1_R")
	)
	(segment
		(start 150.75535 -85.740748)
		(end 149.53615 -85.740748)
		(width 0.127)
		(layer "In11.Cu")
		(net "PWRGD_CPUPWRGD_LVC1_R")
	)
	(segment
		(start 108.83646 -101.567488)
		(end 108.83646 -102.984808)
		(width 0.127)
		(layer "In11.Cu")
		(net "PWRGD_CPUPWRGD_LVC1_R")
	)
	(segment
		(start 147.17268 -88.104218)
		(end 147.17268 -89.018618)
		(width 0.127)
		(layer "In11.Cu")
		(net "PWRGD_CPUPWRGD_LVC1_R")
	)
	(segment
		(start 219.205556 -82.499962)
		(end 153.996136 -82.499962)
		(width 0.127)
		(layer "In11.Cu")
		(net "PWRGD_CPUPWRGD_LVC1_R")
	)
	(segment
		(start 147.17268 -89.018618)
		(end 137.50925 -98.682048)
		(width 0.127)
		(layer "In11.Cu")
		(net "PWRGD_CPUPWRGD_LVC1_R")
	)
	(segment
		(start 239.59693 -66.637408)
		(end 235.06811 -66.637408)
		(width 0.127)
		(layer "In11.Cu")
		(net "PWRGD_CPUPWRGD_LVC1_R")
	)
	(segment
		(start 113.919762 -99.067366)
		(end 113.919762 -98.425762)
		(width 0.12954)
		(layer "F.Cu")
		(net "PWRGD_CPUPWRGD_LVC1")
	)
	(segment
		(start 113.21288 -101.393498)
		(end 113.389664 -101.216714)
		(width 0.12954)
		(layer "F.Cu")
		(net "PWRGD_CPUPWRGD_LVC1")
	)
	(segment
		(start 113.389664 -99.597464)
		(end 113.919762 -99.067366)
		(width 0.12954)
		(layer "F.Cu")
		(net "PWRGD_CPUPWRGD_LVC1")
	)
	(segment
		(start 113.389664 -100.153724)
		(end 113.389664 -99.597464)
		(width 0.12954)
		(layer "F.Cu")
		(net "PWRGD_CPUPWRGD_LVC1")
	)
	(segment
		(start 113.389664 -101.216714)
		(end 113.389664 -100.153724)
		(width 0.12954)
		(layer "F.Cu")
		(net "PWRGD_CPUPWRGD_LVC1")
	)
	(via
		(at 113.389664 -100.153724)
		(size 0.762)
		(drill 0.381)
		(layers "F.Cu" "B.Cu")
		(net "PWRGD_CPUPWRGD_LVC1")
	)
	(segment
		(start 309.64124 -54.181248)
		(end 310.007 -53.815488)
		(width 0.12954)
		(layer "F.Cu")
		(net "PWRGD_CPUPWRGD_GTL")
	)
	(segment
		(start 330.25588 -56.438546)
		(end 330.79436 -56.438546)
		(width 0.12954)
		(layer "F.Cu")
		(net "PWRGD_CPUPWRGD_GTL")
	)
	(segment
		(start 310.007 -53.815488)
		(end 310.007 -53.450998)
		(width 0.12954)
		(layer "F.Cu")
		(net "PWRGD_CPUPWRGD_GTL")
	)
	(via
		(at 309.64124 -54.181248)
		(size 0.508)
		(drill 0.254)
		(layers "F.Cu" "B.Cu")
		(net "PWRGD_CPUPWRGD_GTL")
	)
	(via
		(at 330.25588 -56.438546)
		(size 0.4572)
		(drill 0.2032)
		(layers "F.Cu" "B.Cu")
		(net "PWRGD_CPUPWRGD_GTL")
	)
	(segment
		(start 319.63614 -52.240688)
		(end 317.85814 -52.240688)
		(width 0.127)
		(layer "In6.Cu")
		(net "PWRGD_CPUPWRGD_GTL")
	)
	(segment
		(start 326.68972 -52.659788)
		(end 324.14972 -52.659788)
		(width 0.127)
		(layer "In6.Cu")
		(net "PWRGD_CPUPWRGD_GTL")
	)
	(segment
		(start 327.33488 -53.304948)
		(end 326.68972 -52.659788)
		(width 0.127)
		(layer "In6.Cu")
		(net "PWRGD_CPUPWRGD_GTL")
	)
	(segment
		(start 330.25588 -56.438546)
		(end 329.789282 -55.971948)
		(width 0.127)
		(layer "In6.Cu")
		(net "PWRGD_CPUPWRGD_GTL")
	)
	(segment
		(start 329.789282 -55.971948)
		(end 328.35088 -55.971948)
		(width 0.127)
		(layer "In6.Cu")
		(net "PWRGD_CPUPWRGD_GTL")
	)
	(segment
		(start 317.85814 -52.240688)
		(end 316.92088 -53.177948)
		(width 0.127)
		(layer "In6.Cu")
		(net "PWRGD_CPUPWRGD_GTL")
	)
	(segment
		(start 319.90538 -51.971448)
		(end 319.63614 -52.240688)
		(width 0.127)
		(layer "In6.Cu")
		(net "PWRGD_CPUPWRGD_GTL")
	)
	(segment
		(start 316.92088 -53.177948)
		(end 315.26988 -53.177948)
		(width 0.127)
		(layer "In6.Cu")
		(net "PWRGD_CPUPWRGD_GTL")
	)
	(segment
		(start 314.73648 -53.711348)
		(end 313.72048 -53.711348)
		(width 0.127)
		(layer "In6.Cu")
		(net "PWRGD_CPUPWRGD_GTL")
	)
	(segment
		(start 313.5884 -53.843428)
		(end 311.404 -53.843428)
		(width 0.127)
		(layer "In6.Cu")
		(net "PWRGD_CPUPWRGD_GTL")
	)
	(segment
		(start 313.72048 -53.711348)
		(end 313.5884 -53.843428)
		(width 0.127)
		(layer "In6.Cu")
		(net "PWRGD_CPUPWRGD_GTL")
	)
	(segment
		(start 323.77888 -52.288948)
		(end 322.38188 -52.288948)
		(width 0.127)
		(layer "In6.Cu")
		(net "PWRGD_CPUPWRGD_GTL")
	)
	(segment
		(start 328.35088 -55.971948)
		(end 327.33488 -54.955948)
		(width 0.127)
		(layer "In6.Cu")
		(net "PWRGD_CPUPWRGD_GTL")
	)
	(segment
		(start 311.06618 -54.181248)
		(end 309.64124 -54.181248)
		(width 0.127)
		(layer "In6.Cu")
		(net "PWRGD_CPUPWRGD_GTL")
	)
	(segment
		(start 311.404 -53.843428)
		(end 311.06618 -54.181248)
		(width 0.127)
		(layer "In6.Cu")
		(net "PWRGD_CPUPWRGD_GTL")
	)
	(segment
		(start 322.06438 -51.971448)
		(end 319.90538 -51.971448)
		(width 0.127)
		(layer "In6.Cu")
		(net "PWRGD_CPUPWRGD_GTL")
	)
	(segment
		(start 322.38188 -52.288948)
		(end 322.06438 -51.971448)
		(width 0.127)
		(layer "In6.Cu")
		(net "PWRGD_CPUPWRGD_GTL")
	)
	(segment
		(start 324.14972 -52.659788)
		(end 323.77888 -52.288948)
		(width 0.127)
		(layer "In6.Cu")
		(net "PWRGD_CPUPWRGD_GTL")
	)
	(segment
		(start 327.33488 -54.955948)
		(end 327.33488 -53.304948)
		(width 0.127)
		(layer "In6.Cu")
		(net "PWRGD_CPUPWRGD_GTL")
	)
	(segment
		(start 315.26988 -53.177948)
		(end 314.73648 -53.711348)
		(width 0.127)
		(layer "In6.Cu")
		(net "PWRGD_CPUPWRGD_GTL")
	)
	(segment
		(start 184.7088 -100.319078)
		(end 184.96788 -100.059998)
		(width 0.12954)
		(layer "F.Cu")
		(net "PWRGD_CPU1_LVC1_R")
	)
	(segment
		(start 183.7309 -99.184714)
		(end 183.7309 -98.793808)
		(width 0.12954)
		(layer "F.Cu")
		(net "PWRGD_CPU1_LVC1_R")
	)
	(segment
		(start 184.7088 -104.491028)
		(end 184.7088 -100.319078)
		(width 0.12954)
		(layer "F.Cu")
		(net "PWRGD_CPU1_LVC1_R")
	)
	(segment
		(start 183.7309 -98.793808)
		(end 183.7309 -98.356674)
		(width 0.12954)
		(layer "F.Cu")
		(net "PWRGD_CPU1_LVC1_R")
	)
	(segment
		(start 184.555638 -104.64419)
		(end 184.7088 -104.491028)
		(width 0.12954)
		(layer "F.Cu")
		(net "PWRGD_CPU1_LVC1_R")
	)
	(segment
		(start 184.555638 -104.975406)
		(end 184.555638 -104.64419)
		(width 0.12954)
		(layer "F.Cu")
		(net "PWRGD_CPU1_LVC1_R")
	)
	(segment
		(start 184.96788 -100.059998)
		(end 184.606184 -100.059998)
		(width 0.12954)
		(layer "F.Cu")
		(net "PWRGD_CPU1_LVC1_R")
	)
	(segment
		(start 184.567576 -97.519998)
		(end 184.96788 -97.519998)
		(width 0.12954)
		(layer "F.Cu")
		(net "PWRGD_CPU1_LVC1_R")
	)
	(segment
		(start 183.7309 -98.356674)
		(end 184.567576 -97.519998)
		(width 0.12954)
		(layer "F.Cu")
		(net "PWRGD_CPU1_LVC1_R")
	)
	(segment
		(start 184.606184 -100.059998)
		(end 183.7309 -99.184714)
		(width 0.12954)
		(layer "F.Cu")
		(net "PWRGD_CPU1_LVC1_R")
	)
	(via
		(at 183.7309 -98.793808)
		(size 0.762)
		(drill 0.381)
		(layers "F.Cu" "B.Cu")
		(net "PWRGD_CPU1_LVC1_R")
	)
	(segment
		(start 102.242112 -229.2731)
		(end 102.242366 -229.272846)
		(width 0.12954)
		(layer "F.Cu")
		(net "PWRGD_CPU1_LVC1")
	)
	(segment
		(start 102.242112 -229.808786)
		(end 102.242112 -229.2731)
		(width 0.12954)
		(layer "F.Cu")
		(net "PWRGD_CPU1_LVC1")
	)
	(segment
		(start 68.294758 -190.60541)
		(end 67.563238 -189.87389)
		(width 0.12954)
		(layer "F.Cu")
		(net "PWRGD_CPU1_LVC1")
	)
	(segment
		(start 69.056758 -190.60541)
		(end 68.294758 -190.60541)
		(width 0.12954)
		(layer "F.Cu")
		(net "PWRGD_CPU1_LVC1")
	)
	(via
		(at 102.242366 -229.272846)
		(size 0.4572)
		(drill 0.2032)
		(layers "F.Cu" "B.Cu")
		(net "PWRGD_CPU1_LVC1")
	)
	(via
		(at 69.056758 -190.60541)
		(size 0.762)
		(drill 0.381)
		(layers "F.Cu" "B.Cu")
		(net "PWRGD_CPU1_LVC1")
	)
	(via
		(at 67.563238 -189.87389)
		(size 0.508)
		(drill 0.254)
		(layers "F.Cu" "B.Cu")
		(net "PWRGD_CPU1_LVC1")
	)
	(segment
		(start 67.2592 -185.391552)
		(end 67.638676 -184.474866)
		(width 0.12954)
		(layer "B.Cu")
		(net "PWRGD_CPU1_LVC1")
	)
	(segment
		(start 67.2592 -188.345064)
		(end 67.2592 -185.391552)
		(width 0.12954)
		(layer "B.Cu")
		(net "PWRGD_CPU1_LVC1")
	)
	(segment
		(start 68.337684 -183.775858)
		(end 68.337684 -183.703976)
		(width 0.12954)
		(layer "B.Cu")
		(net "PWRGD_CPU1_LVC1")
	)
	(segment
		(start 67.638676 -184.474866)
		(end 68.337684 -183.775858)
		(width 0.12954)
		(layer "B.Cu")
		(net "PWRGD_CPU1_LVC1")
	)
	(segment
		(start 67.563238 -189.87389)
		(end 67.2592 -188.345064)
		(width 0.12954)
		(layer "B.Cu")
		(net "PWRGD_CPU1_LVC1")
	)
	(segment
		(start 98.685096 -228.957124)
		(end 98.678238 -228.95306)
		(width 0.0889)
		(layer "In4.Cu")
		(net "PWRGD_CPU1_LVC1")
	)
	(segment
		(start 87.288878 -222.054928)
		(end 87.288878 -221.77121)
		(width 0.0889)
		(layer "In4.Cu")
		(net "PWRGD_CPU1_LVC1")
	)
	(segment
		(start 96.3295 -228.139752)
		(end 96.32061 -228.134672)
		(width 0.0889)
		(layer "In4.Cu")
		(net "PWRGD_CPU1_LVC1")
	)
	(segment
		(start 88.989662 -225.217482)
		(end 88.989662 -225.194622)
		(width 0.0889)
		(layer "In4.Cu")
		(net "PWRGD_CPU1_LVC1")
	)
	(segment
		(start 95.3897 -226.511866)
		(end 95.38081 -226.506786)
		(width 0.0889)
		(layer "In4.Cu")
		(net "PWRGD_CPU1_LVC1")
	)
	(segment
		(start 75.00493 -196.35597)
		(end 68.52285 -189.87389)
		(width 0.127)
		(layer "In4.Cu")
		(net "PWRGD_CPU1_LVC1")
	)
	(segment
		(start 95.859854 -227.325682)
		(end 95.850964 -227.320602)
		(width 0.0889)
		(layer "In4.Cu")
		(net "PWRGD_CPU1_LVC1")
	)
	(segment
		(start 87.936578 -223.10979)
		(end 87.906606 -223.079818)
		(width 0.0889)
		(layer "In4.Cu")
		(net "PWRGD_CPU1_LVC1")
	)
	(segment
		(start 88.8111 -223.256348)
		(end 88.80221 -223.251268)
		(width 0.0889)
		(layer "In4.Cu")
		(net "PWRGD_CPU1_LVC1")
	)
	(segment
		(start 75.927458 -197.735952)
		(end 75.00493 -196.35597)
		(width 0.127)
		(layer "In4.Cu")
		(net "PWRGD_CPU1_LVC1")
	)
	(segment
		(start 94.066614 -226.506786)
		(end 94.0562 -226.512882)
		(width 0.0889)
		(layer "In4.Cu")
		(net "PWRGD_CPU1_LVC1")
	)
	(segment
		(start 87.342218 -221.49943)
		(end 84.658708 -218.81592)
		(width 0.127)
		(layer "In4.Cu")
		(net "PWRGD_CPU1_LVC1")
	)
	(segment
		(start 96.805496 -228.957124)
		(end 96.790764 -228.948488)
		(width 0.0889)
		(layer "In4.Cu")
		(net "PWRGD_CPU1_LVC1")
	)
	(segment
		(start 87.756238 -222.716852)
		(end 87.756238 -222.62211)
		(width 0.0889)
		(layer "In4.Cu")
		(net "PWRGD_CPU1_LVC1")
	)
	(segment
		(start 84.658708 -218.81592)
		(end 75.927458 -197.735952)
		(width 0.127)
		(layer "In4.Cu")
		(net "PWRGD_CPU1_LVC1")
	)
	(segment
		(start 87.342218 -221.62135)
		(end 87.342218 -221.49943)
		(width 0.127)
		(layer "In4.Cu")
		(net "PWRGD_CPU1_LVC1")
	)
	(segment
		(start 87.288878 -221.77121)
		(end 87.342218 -221.71787)
		(width 0.0889)
		(layer "In4.Cu")
		(net "PWRGD_CPU1_LVC1")
	)
	(segment
		(start 90.399362 -226.027234)
		(end 90.399362 -226.008692)
		(width 0.0889)
		(layer "In4.Cu")
		(net "PWRGD_CPU1_LVC1")
	)
	(segment
		(start 101.886258 -229.177342)
		(end 101.48951 -228.948488)
		(width 0.0889)
		(layer "In4.Cu")
		(net "PWRGD_CPU1_LVC1")
	)
	(segment
		(start 88.520016 -224.399348)
		(end 88.520016 -224.373948)
		(width 0.0889)
		(layer "In4.Cu")
		(net "PWRGD_CPU1_LVC1")
	)
	(segment
		(start 89.287096 -225.701606)
		(end 89.272364 -225.69297)
		(width 0.0889)
		(layer "In4.Cu")
		(net "PWRGD_CPU1_LVC1")
	)
	(segment
		(start 87.566246 -222.379286)
		(end 87.322152 -222.135192)
		(width 0.0889)
		(layer "In4.Cu")
		(net "PWRGD_CPU1_LVC1")
	)
	(segment
		(start 95.850964 -227.320602)
		(end 95.838772 -227.31349)
		(width 0.0889)
		(layer "In4.Cu")
		(net "PWRGD_CPU1_LVC1")
	)
	(segment
		(start 98.678238 -228.95306)
		(end 98.670364 -228.948488)
		(width 0.0889)
		(layer "In4.Cu")
		(net "PWRGD_CPU1_LVC1")
	)
	(segment
		(start 68.52285 -189.87389)
		(end 67.563238 -189.87389)
		(width 0.127)
		(layer "In4.Cu")
		(net "PWRGD_CPU1_LVC1")
	)
	(segment
		(start 95.006414 -226.506786)
		(end 94.991682 -226.515422)
		(width 0.0889)
		(layer "In4.Cu")
		(net "PWRGD_CPU1_LVC1")
	)
	(segment
		(start 88.518238 -223.17583)
		(end 88.09609 -223.17583)
		(width 0.0889)
		(layer "In4.Cu")
		(net "PWRGD_CPU1_LVC1")
	)
	(segment
		(start 99.624896 -228.957124)
		(end 99.610164 -228.948488)
		(width 0.0889)
		(layer "In4.Cu")
		(net "PWRGD_CPU1_LVC1")
	)
	(segment
		(start 100.560378 -228.954584)
		(end 100.549964 -228.948488)
		(width 0.0889)
		(layer "In4.Cu")
		(net "PWRGD_CPU1_LVC1")
	)
	(segment
		(start 88.80221 -223.899984)
		(end 88.8111 -223.894904)
		(width 0.0889)
		(layer "In4.Cu")
		(net "PWRGD_CPU1_LVC1")
	)
	(segment
		(start 90.692224 -226.512882)
		(end 90.68181 -226.506786)
		(width 0.0889)
		(layer "In4.Cu")
		(net "PWRGD_CPU1_LVC1")
	)
	(segment
		(start 96.790764 -228.948488)
		(end 96.784668 -228.944932)
		(width 0.0889)
		(layer "In4.Cu")
		(net "PWRGD_CPU1_LVC1")
	)
	(segment
		(start 96.038416 -227.667058)
		(end 96.038416 -227.64496)
		(width 0.0889)
		(layer "In4.Cu")
		(net "PWRGD_CPU1_LVC1")
	)
	(segment
		(start 87.342218 -221.71787)
		(end 87.342218 -221.62135)
		(width 0.0889)
		(layer "In4.Cu")
		(net "PWRGD_CPU1_LVC1")
	)
	(arc
		(start 96.784668 -228.944932)
		(mid 96.582081 -228.738581)
		(end 96.508062 -228.45903)
		(width 0.0889)
		(layer "In4.Cu")
		(net "PWRGD_CPU1_LVC1")
	)
	(arc
		(start 92.561664 -226.506786)
		(mid 92.374466 -226.456643)
		(end 92.187268 -226.506786)
		(width 0.0889)
		(layer "In4.Cu")
		(net "PWRGD_CPU1_LVC1")
	)
	(arc
		(start 95.838772 -227.31349)
		(mid 95.640544 -227.107642)
		(end 95.568262 -226.831144)
		(width 0.0889)
		(layer "In4.Cu")
		(net "PWRGD_CPU1_LVC1")
	)
	(arc
		(start 92.187268 -226.506786)
		(mid 91.904566 -226.582562)
		(end 91.621864 -226.506786)
		(width 0.0889)
		(layer "In4.Cu")
		(net "PWRGD_CPU1_LVC1")
	)
	(arc
		(start 97.730564 -228.948488)
		(mid 97.543366 -228.898345)
		(end 97.356168 -228.948488)
		(width 0.0889)
		(layer "In4.Cu")
		(net "PWRGD_CPU1_LVC1")
	)
	(arc
		(start 88.520016 -224.373948)
		(mid 88.599386 -224.100214)
		(end 88.80221 -223.899984)
		(width 0.0889)
		(layer "In4.Cu")
		(net "PWRGD_CPU1_LVC1")
	)
	(arc
		(start 90.68181 -226.506786)
		(mid 90.477475 -226.304181)
		(end 90.399362 -226.027234)
		(width 0.0889)
		(layer "In4.Cu")
		(net "PWRGD_CPU1_LVC1")
	)
	(arc
		(start 91.247468 -226.506786)
		(mid 90.970655 -226.582656)
		(end 90.692224 -226.512882)
		(width 0.0889)
		(layer "In4.Cu")
		(net "PWRGD_CPU1_LVC1")
	)
	(arc
		(start 88.802464 -224.8789)
		(mid 88.598129 -224.676295)
		(end 88.520016 -224.399348)
		(width 0.0889)
		(layer "In4.Cu")
		(net "PWRGD_CPU1_LVC1")
	)
	(arc
		(start 94.991682 -226.515422)
		(mid 94.715207 -226.582742)
		(end 94.44101 -226.506786)
		(width 0.0889)
		(layer "In4.Cu")
		(net "PWRGD_CPU1_LVC1")
	)
	(arc
		(start 87.638636 -222.431102)
		(mid 87.600353 -222.408111)
		(end 87.566246 -222.379286)
		(width 0.0889)
		(layer "In4.Cu")
		(net "PWRGD_CPU1_LVC1")
	)
	(arc
		(start 99.610164 -228.948488)
		(mid 99.422966 -228.898345)
		(end 99.235768 -228.948488)
		(width 0.0889)
		(layer "In4.Cu")
		(net "PWRGD_CPU1_LVC1")
	)
	(arc
		(start 90.399362 -226.008692)
		(mid 90.347092 -225.826327)
		(end 90.212164 -225.69297)
		(width 0.0889)
		(layer "In4.Cu")
		(net "PWRGD_CPU1_LVC1")
	)
	(arc
		(start 99.235768 -228.948488)
		(mid 98.961569 -229.024323)
		(end 98.685096 -228.957124)
		(width 0.0889)
		(layer "In4.Cu")
		(net "PWRGD_CPU1_LVC1")
	)
	(arc
		(start 96.508062 -228.45903)
		(mid 96.460383 -228.27613)
		(end 96.3295 -228.139752)
		(width 0.0889)
		(layer "In4.Cu")
		(net "PWRGD_CPU1_LVC1")
	)
	(arc
		(start 93.127068 -226.506786)
		(mid 92.844366 -226.582562)
		(end 92.561664 -226.506786)
		(width 0.0889)
		(layer "In4.Cu")
		(net "PWRGD_CPU1_LVC1")
	)
	(arc
		(start 94.44101 -226.506786)
		(mid 94.253812 -226.456643)
		(end 94.066614 -226.506786)
		(width 0.0889)
		(layer "In4.Cu")
		(net "PWRGD_CPU1_LVC1")
	)
	(arc
		(start 94.0562 -226.512882)
		(mid 93.778022 -226.582605)
		(end 93.501464 -226.506786)
		(width 0.0889)
		(layer "In4.Cu")
		(net "PWRGD_CPU1_LVC1")
	)
	(arc
		(start 87.906606 -223.079818)
		(mid 87.795334 -222.913288)
		(end 87.756238 -222.716852)
		(width 0.0889)
		(layer "In4.Cu")
		(net "PWRGD_CPU1_LVC1")
	)
	(arc
		(start 88.09609 -223.17583)
		(mid 88.009775 -223.158661)
		(end 87.936578 -223.10979)
		(width 0.0889)
		(layer "In4.Cu")
		(net "PWRGD_CPU1_LVC1")
	)
	(arc
		(start 101.48951 -228.948488)
		(mid 101.302312 -228.898345)
		(end 101.115114 -228.948488)
		(width 0.0889)
		(layer "In4.Cu")
		(net "PWRGD_CPU1_LVC1")
	)
	(arc
		(start 89.272364 -225.69297)
		(mid 89.068883 -225.492166)
		(end 88.989662 -225.217482)
		(width 0.0889)
		(layer "In4.Cu")
		(net "PWRGD_CPU1_LVC1")
	)
	(arc
		(start 96.038416 -227.64496)
		(mid 95.990737 -227.46206)
		(end 95.859854 -227.325682)
		(width 0.0889)
		(layer "In4.Cu")
		(net "PWRGD_CPU1_LVC1")
	)
	(arc
		(start 97.356168 -228.948488)
		(mid 97.081969 -229.024323)
		(end 96.805496 -228.957124)
		(width 0.0889)
		(layer "In4.Cu")
		(net "PWRGD_CPU1_LVC1")
	)
	(arc
		(start 96.32061 -228.134672)
		(mid 96.119328 -227.937185)
		(end 96.038416 -227.667058)
		(width 0.0889)
		(layer "In4.Cu")
		(net "PWRGD_CPU1_LVC1")
	)
	(arc
		(start 100.175568 -228.948488)
		(mid 99.901369 -229.024323)
		(end 99.624896 -228.957124)
		(width 0.0889)
		(layer "In4.Cu")
		(net "PWRGD_CPU1_LVC1")
	)
	(arc
		(start 88.80221 -223.251268)
		(mid 88.665143 -223.195042)
		(end 88.518238 -223.17583)
		(width 0.0889)
		(layer "In4.Cu")
		(net "PWRGD_CPU1_LVC1")
	)
	(arc
		(start 89.837768 -225.69297)
		(mid 89.563539 -225.768895)
		(end 89.287096 -225.701606)
		(width 0.0889)
		(layer "In4.Cu")
		(net "PWRGD_CPU1_LVC1")
	)
	(arc
		(start 98.295968 -228.948488)
		(mid 98.013266 -229.024264)
		(end 97.730564 -228.948488)
		(width 0.0889)
		(layer "In4.Cu")
		(net "PWRGD_CPU1_LVC1")
	)
	(arc
		(start 101.115114 -228.948488)
		(mid 100.838555 -229.024231)
		(end 100.560378 -228.954584)
		(width 0.0889)
		(layer "In4.Cu")
		(net "PWRGD_CPU1_LVC1")
	)
	(arc
		(start 95.38081 -226.506786)
		(mid 95.193612 -226.456643)
		(end 95.006414 -226.506786)
		(width 0.0889)
		(layer "In4.Cu")
		(net "PWRGD_CPU1_LVC1")
	)
	(arc
		(start 90.212164 -225.69297)
		(mid 90.024966 -225.642827)
		(end 89.837768 -225.69297)
		(width 0.0889)
		(layer "In4.Cu")
		(net "PWRGD_CPU1_LVC1")
	)
	(arc
		(start 88.989662 -225.194622)
		(mid 88.937392 -225.012257)
		(end 88.802464 -224.8789)
		(width 0.0889)
		(layer "In4.Cu")
		(net "PWRGD_CPU1_LVC1")
	)
	(arc
		(start 95.568262 -226.831144)
		(mid 95.520583 -226.648244)
		(end 95.3897 -226.511866)
		(width 0.0889)
		(layer "In4.Cu")
		(net "PWRGD_CPU1_LVC1")
	)
	(arc
		(start 87.756238 -222.62211)
		(mid 87.724529 -222.509939)
		(end 87.638636 -222.431102)
		(width 0.0889)
		(layer "In4.Cu")
		(net "PWRGD_CPU1_LVC1")
	)
	(arc
		(start 93.501464 -226.506786)
		(mid 93.314266 -226.456643)
		(end 93.127068 -226.506786)
		(width 0.0889)
		(layer "In4.Cu")
		(net "PWRGD_CPU1_LVC1")
	)
	(arc
		(start 88.8111 -223.894904)
		(mid 88.989697 -223.575626)
		(end 88.8111 -223.256348)
		(width 0.0889)
		(layer "In4.Cu")
		(net "PWRGD_CPU1_LVC1")
	)
	(arc
		(start 100.549964 -228.948488)
		(mid 100.362766 -228.898345)
		(end 100.175568 -228.948488)
		(width 0.0889)
		(layer "In4.Cu")
		(net "PWRGD_CPU1_LVC1")
	)
	(arc
		(start 102.242366 -229.272846)
		(mid 102.058031 -229.248519)
		(end 101.886258 -229.177342)
		(width 0.0889)
		(layer "In4.Cu")
		(net "PWRGD_CPU1_LVC1")
	)
	(arc
		(start 91.621864 -226.506786)
		(mid 91.434666 -226.456643)
		(end 91.247468 -226.506786)
		(width 0.0889)
		(layer "In4.Cu")
		(net "PWRGD_CPU1_LVC1")
	)
	(arc
		(start 98.670364 -228.948488)
		(mid 98.483166 -228.898345)
		(end 98.295968 -228.948488)
		(width 0.0889)
		(layer "In4.Cu")
		(net "PWRGD_CPU1_LVC1")
	)
	(arc
		(start 87.322152 -222.135192)
		(mid 87.297492 -222.098381)
		(end 87.288878 -222.054928)
		(width 0.0889)
		(layer "In4.Cu")
		(net "PWRGD_CPU1_LVC1")
	)
	(segment
		(start 184.96788 -99.259898)
		(end 184.96788 -98.643948)
		(width 0.12954)
		(layer "F.Cu")
		(net "PWRGD_CPU1_BUF_R")
	)
	(via
		(at 184.96788 -98.643948)
		(size 0.508)
		(drill 0.254)
		(layers "F.Cu" "B.Cu")
		(net "PWRGD_CPU1_BUF_R")
	)
	(via
		(at 68.4784 -181.811168)
		(size 0.508)
		(drill 0.254)
		(layers "F.Cu" "B.Cu")
		(net "PWRGD_CPU1_BUF_R")
	)
	(segment
		(start 68.4784 -181.811168)
		(end 68.4784 -182.76316)
		(width 0.12954)
		(layer "B.Cu")
		(net "PWRGD_CPU1_BUF_R")
	)
	(segment
		(start 68.4784 -182.76316)
		(end 68.337684 -182.903876)
		(width 0.12954)
		(layer "B.Cu")
		(net "PWRGD_CPU1_BUF_R")
	)
	(segment
		(start 67.320922 -182.903876)
		(end 68.337684 -182.903876)
		(width 0.12954)
		(layer "B.Cu")
		(net "PWRGD_CPU1_BUF_R")
	)
	(segment
		(start 161.94024 -100.736908)
		(end 159.3215 -103.355648)
		(width 0.127)
		(layer "In4.Cu")
		(net "PWRGD_CPU1_BUF_R")
	)
	(segment
		(start 178.37658 -100.736908)
		(end 161.94024 -100.736908)
		(width 0.127)
		(layer "In4.Cu")
		(net "PWRGD_CPU1_BUF_R")
	)
	(segment
		(start 147.70608 -126.736348)
		(end 147.70608 -128.846072)
		(width 0.127)
		(layer "In4.Cu")
		(net "PWRGD_CPU1_BUF_R")
	)
	(segment
		(start 72.30618 -180.279548)
		(end 71.13778 -181.447948)
		(width 0.127)
		(layer "In4.Cu")
		(net "PWRGD_CPU1_BUF_R")
	)
	(segment
		(start 109.676946 -147.391374)
		(end 76.788772 -180.279548)
		(width 0.127)
		(layer "In4.Cu")
		(net "PWRGD_CPU1_BUF_R")
	)
	(segment
		(start 76.788772 -180.279548)
		(end 72.30618 -180.279548)
		(width 0.127)
		(layer "In4.Cu")
		(net "PWRGD_CPU1_BUF_R")
	)
	(segment
		(start 158.28772 -103.355648)
		(end 157.23362 -104.409748)
		(width 0.127)
		(layer "In4.Cu")
		(net "PWRGD_CPU1_BUF_R")
	)
	(segment
		(start 143.424656 -131.545584)
		(end 127.578866 -147.391374)
		(width 0.127)
		(layer "In4.Cu")
		(net "PWRGD_CPU1_BUF_R")
	)
	(segment
		(start 68.4784 -181.625748)
		(end 68.4784 -181.811168)
		(width 0.127)
		(layer "In4.Cu")
		(net "PWRGD_CPU1_BUF_R")
	)
	(segment
		(start 150.35276 -104.409748)
		(end 143.40586 -111.356648)
		(width 0.127)
		(layer "In4.Cu")
		(net "PWRGD_CPU1_BUF_R")
	)
	(segment
		(start 145.006568 -131.545584)
		(end 143.424656 -131.545584)
		(width 0.127)
		(layer "In4.Cu")
		(net "PWRGD_CPU1_BUF_R")
	)
	(segment
		(start 184.28208 -99.329748)
		(end 179.78374 -99.329748)
		(width 0.127)
		(layer "In4.Cu")
		(net "PWRGD_CPU1_BUF_R")
	)
	(segment
		(start 147.70608 -128.846072)
		(end 145.006568 -131.545584)
		(width 0.127)
		(layer "In4.Cu")
		(net "PWRGD_CPU1_BUF_R")
	)
	(segment
		(start 157.23362 -104.409748)
		(end 150.35276 -104.409748)
		(width 0.127)
		(layer "In4.Cu")
		(net "PWRGD_CPU1_BUF_R")
	)
	(segment
		(start 143.40586 -122.436128)
		(end 147.70608 -126.736348)
		(width 0.127)
		(layer "In4.Cu")
		(net "PWRGD_CPU1_BUF_R")
	)
	(segment
		(start 184.96788 -98.643948)
		(end 184.28208 -99.329748)
		(width 0.127)
		(layer "In4.Cu")
		(net "PWRGD_CPU1_BUF_R")
	)
	(segment
		(start 179.78374 -99.329748)
		(end 178.37658 -100.736908)
		(width 0.127)
		(layer "In4.Cu")
		(net "PWRGD_CPU1_BUF_R")
	)
	(segment
		(start 159.3215 -103.355648)
		(end 158.28772 -103.355648)
		(width 0.127)
		(layer "In4.Cu")
		(net "PWRGD_CPU1_BUF_R")
	)
	(segment
		(start 71.13778 -181.447948)
		(end 68.6562 -181.447948)
		(width 0.127)
		(layer "In4.Cu")
		(net "PWRGD_CPU1_BUF_R")
	)
	(segment
		(start 127.578866 -147.391374)
		(end 109.676946 -147.391374)
		(width 0.127)
		(layer "In4.Cu")
		(net "PWRGD_CPU1_BUF_R")
	)
	(segment
		(start 143.40586 -111.356648)
		(end 143.40586 -122.436128)
		(width 0.127)
		(layer "In4.Cu")
		(net "PWRGD_CPU1_BUF_R")
	)
	(segment
		(start 68.6562 -181.447948)
		(end 68.4784 -181.625748)
		(width 0.127)
		(layer "In4.Cu")
		(net "PWRGD_CPU1_BUF_R")
	)
	(segment
		(start 185.28284 -101.359208)
		(end 185.28284 -104.424988)
		(width 0.12954)
		(layer "F.Cu")
		(net "PWRGD_CPU0_LVC1_R")
	)
	(segment
		(start 184.96788 -105.363264)
		(end 184.555638 -105.775506)
		(width 0.12954)
		(layer "F.Cu")
		(net "PWRGD_CPU0_LVC1_R")
	)
	(segment
		(start 186.23788 -100.059998)
		(end 185.28284 -101.015038)
		(width 0.12954)
		(layer "F.Cu")
		(net "PWRGD_CPU0_LVC1_R")
	)
	(segment
		(start 185.28284 -101.015038)
		(end 185.28284 -101.359208)
		(width 0.12954)
		(layer "F.Cu")
		(net "PWRGD_CPU0_LVC1_R")
	)
	(segment
		(start 185.837576 -97.519998)
		(end 185.60288 -97.754694)
		(width 0.12954)
		(layer "F.Cu")
		(net "PWRGD_CPU0_LVC1_R")
	)
	(segment
		(start 185.875676 -100.059998)
		(end 186.23788 -100.059998)
		(width 0.12954)
		(layer "F.Cu")
		(net "PWRGD_CPU0_LVC1_R")
	)
	(segment
		(start 185.60288 -97.754694)
		(end 185.60288 -99.787202)
		(width 0.12954)
		(layer "F.Cu")
		(net "PWRGD_CPU0_LVC1_R")
	)
	(segment
		(start 185.28284 -104.424988)
		(end 184.96788 -104.739948)
		(width 0.12954)
		(layer "F.Cu")
		(net "PWRGD_CPU0_LVC1_R")
	)
	(segment
		(start 186.23788 -97.519998)
		(end 185.837576 -97.519998)
		(width 0.12954)
		(layer "F.Cu")
		(net "PWRGD_CPU0_LVC1_R")
	)
	(segment
		(start 184.96788 -104.739948)
		(end 184.96788 -105.363264)
		(width 0.12954)
		(layer "F.Cu")
		(net "PWRGD_CPU0_LVC1_R")
	)
	(segment
		(start 185.60288 -99.787202)
		(end 185.875676 -100.059998)
		(width 0.12954)
		(layer "F.Cu")
		(net "PWRGD_CPU0_LVC1_R")
	)
	(via
		(at 185.28284 -101.359208)
		(size 0.762)
		(drill 0.381)
		(layers "F.Cu" "B.Cu")
		(net "PWRGD_CPU0_LVC1_R")
	)
	(segment
		(start 350.18218 -229.808786)
		(end 350.18218 -229.2731)
		(width 0.12954)
		(layer "F.Cu")
		(net "PWRGD_CPU0_LVC1")
	)
	(segment
		(start 350.18218 -229.2731)
		(end 350.182434 -229.272846)
		(width 0.12954)
		(layer "F.Cu")
		(net "PWRGD_CPU0_LVC1")
	)
	(via
		(at 330.462636 -199.17791)
		(size 0.508)
		(drill 0.254)
		(layers "F.Cu" "B.Cu")
		(net "PWRGD_CPU0_LVC1")
	)
	(via
		(at 350.182434 -229.272846)
		(size 0.4572)
		(drill 0.2032)
		(layers "F.Cu" "B.Cu")
		(net "PWRGD_CPU0_LVC1")
	)
	(via
		(at 330.689458 -193.02349)
		(size 0.6604)
		(drill 0.3302)
		(layers "F.Cu" "B.Cu")
		(net "PWRGD_CPU0_LVC1")
	)
	(segment
		(start 330.689458 -191.34074)
		(end 330.577698 -191.22898)
		(width 0.12954)
		(layer "B.Cu")
		(net "PWRGD_CPU0_LVC1")
	)
	(segment
		(start 330.971398 -197.48627)
		(end 330.689458 -197.20433)
		(width 0.12954)
		(layer "B.Cu")
		(net "PWRGD_CPU0_LVC1")
	)
	(segment
		(start 330.689458 -193.02349)
		(end 330.689458 -191.34074)
		(width 0.12954)
		(layer "B.Cu")
		(net "PWRGD_CPU0_LVC1")
	)
	(segment
		(start 330.554838 -199.17791)
		(end 330.971398 -198.76135)
		(width 0.12954)
		(layer "B.Cu")
		(net "PWRGD_CPU0_LVC1")
	)
	(segment
		(start 330.462636 -199.17791)
		(end 330.554838 -199.17791)
		(width 0.12954)
		(layer "B.Cu")
		(net "PWRGD_CPU0_LVC1")
	)
	(segment
		(start 330.971398 -198.76135)
		(end 330.971398 -197.48627)
		(width 0.12954)
		(layer "B.Cu")
		(net "PWRGD_CPU0_LVC1")
	)
	(segment
		(start 330.689458 -197.20433)
		(end 330.689458 -193.02349)
		(width 0.12954)
		(layer "B.Cu")
		(net "PWRGD_CPU0_LVC1")
	)
	(segment
		(start 332.68285 -220.478858)
		(end 329.002898 -216.798906)
		(width 0.127)
		(layer "In4.Cu")
		(net "PWRGD_CPU0_LVC1")
	)
	(segment
		(start 350.182434 -229.272846)
		(end 349.749618 -228.84003)
		(width 0.0889)
		(layer "In4.Cu")
		(net "PWRGD_CPU0_LVC1")
	)
	(segment
		(start 339.092032 -224.065084)
		(end 339.07984 -224.057972)
		(width 0.0889)
		(layer "In4.Cu")
		(net "PWRGD_CPU0_LVC1")
	)
	(segment
		(start 342.469216 -227.98659)
		(end 342.232234 -227.736654)
		(width 0.0889)
		(layer "In4.Cu")
		(net "PWRGD_CPU0_LVC1")
	)
	(segment
		(start 349.302578 -228.68255)
		(end 349.302578 -228.35235)
		(width 0.0889)
		(layer "In4.Cu")
		(net "PWRGD_CPU0_LVC1")
	)
	(segment
		(start 329.233276 -199.480424)
		(end 330.160122 -199.480424)
		(width 0.127)
		(layer "In4.Cu")
		(net "PWRGD_CPU0_LVC1")
	)
	(segment
		(start 337.278218 -223.14027)
		(end 336.961226 -223.14027)
		(width 0.0889)
		(layer "In4.Cu")
		(net "PWRGD_CPU0_LVC1")
	)
	(segment
		(start 349.749618 -228.84003)
		(end 349.460058 -228.84003)
		(width 0.0889)
		(layer "In4.Cu")
		(net "PWRGD_CPU0_LVC1")
	)
	(segment
		(start 342.096344 -227.468176)
		(end 342.063578 -227.43541)
		(width 0.0889)
		(layer "In4.Cu")
		(net "PWRGD_CPU0_LVC1")
	)
	(segment
		(start 339.100922 -224.070164)
		(end 339.092032 -224.065084)
		(width 0.0889)
		(layer "In4.Cu")
		(net "PWRGD_CPU0_LVC1")
	)
	(segment
		(start 340.046564 -225.701606)
		(end 340.031832 -225.69297)
		(width 0.0889)
		(layer "In4.Cu")
		(net "PWRGD_CPU0_LVC1")
	)
	(segment
		(start 335.368138 -221.57309)
		(end 334.993488 -221.19844)
		(width 0.0889)
		(layer "In4.Cu")
		(net "PWRGD_CPU0_LVC1")
	)
	(segment
		(start 341.62873 -226.831144)
		(end 341.62873 -226.822508)
		(width 0.0889)
		(layer "In4.Cu")
		(net "PWRGD_CPU0_LVC1")
	)
	(segment
		(start 337.682586 -223.251268)
		(end 337.673696 -223.246188)
		(width 0.0889)
		(layer "In4.Cu")
		(net "PWRGD_CPU0_LVC1")
	)
	(segment
		(start 348.585282 -228.134672)
		(end 348.57055 -228.143308)
		(width 0.0889)
		(layer "In4.Cu")
		(net "PWRGD_CPU0_LVC1")
	)
	(segment
		(start 333.898494 -220.478858)
		(end 332.68285 -220.478858)
		(width 0.127)
		(layer "In4.Cu")
		(net "PWRGD_CPU0_LVC1")
	)
	(segment
		(start 341.159084 -226.027234)
		(end 341.159084 -226.017328)
		(width 0.0889)
		(layer "In4.Cu")
		(net "PWRGD_CPU0_LVC1")
	)
	(segment
		(start 346.705682 -228.134672)
		(end 346.695268 -228.140768)
		(width 0.0889)
		(layer "In4.Cu")
		(net "PWRGD_CPU0_LVC1")
	)
	(segment
		(start 339.570568 -224.88398)
		(end 339.561678 -224.8789)
		(width 0.0889)
		(layer "In4.Cu")
		(net "PWRGD_CPU0_LVC1")
	)
	(segment
		(start 342.893396 -228.10597)
		(end 342.746838 -228.10597)
		(width 0.0889)
		(layer "In4.Cu")
		(net "PWRGD_CPU0_LVC1")
	)
	(segment
		(start 330.160122 -199.480424)
		(end 330.462636 -199.17791)
		(width 0.127)
		(layer "In4.Cu")
		(net "PWRGD_CPU0_LVC1")
	)
	(segment
		(start 334.457802 -221.038166)
		(end 333.898494 -220.478858)
		(width 0.127)
		(layer "In4.Cu")
		(net "PWRGD_CPU0_LVC1")
	)
	(segment
		(start 335.615534 -221.573344)
		(end 335.368646 -221.573344)
		(width 0.0889)
		(layer "In4.Cu")
		(net "PWRGD_CPU0_LVC1")
	)
	(segment
		(start 345.766136 -228.134672)
		(end 345.755722 -228.140768)
		(width 0.0889)
		(layer "In4.Cu")
		(net "PWRGD_CPU0_LVC1")
	)
	(segment
		(start 344.826082 -228.134672)
		(end 344.81135 -228.143308)
		(width 0.0889)
		(layer "In4.Cu")
		(net "PWRGD_CPU0_LVC1")
	)
	(segment
		(start 336.504026 -222.572834)
		(end 336.272632 -222.437198)
		(width 0.0889)
		(layer "In4.Cu")
		(net "PWRGD_CPU0_LVC1")
	)
	(segment
		(start 338.630768 -223.256348)
		(end 338.621878 -223.251268)
		(width 0.0889)
		(layer "In4.Cu")
		(net "PWRGD_CPU0_LVC1")
	)
	(segment
		(start 329.002898 -216.798906)
		(end 329.002898 -199.710802)
		(width 0.127)
		(layer "In4.Cu")
		(net "PWRGD_CPU0_LVC1")
	)
	(segment
		(start 340.980522 -225.69805)
		(end 340.971632 -225.69297)
		(width 0.0889)
		(layer "In4.Cu")
		(net "PWRGD_CPU0_LVC1")
	)
	(segment
		(start 336.804 -223.090232)
		(end 336.715354 -223.001332)
		(width 0.0889)
		(layer "In4.Cu")
		(net "PWRGD_CPU0_LVC1")
	)
	(segment
		(start 336.272632 -222.437198)
		(end 336.266536 -222.433642)
		(width 0.0889)
		(layer "In4.Cu")
		(net "PWRGD_CPU0_LVC1")
	)
	(segment
		(start 349.460058 -228.84003)
		(end 349.302578 -228.68255)
		(width 0.0889)
		(layer "In4.Cu")
		(net "PWRGD_CPU0_LVC1")
	)
	(segment
		(start 349.19793 -228.272086)
		(end 348.959678 -228.134672)
		(width 0.0889)
		(layer "In4.Cu")
		(net "PWRGD_CPU0_LVC1")
	)
	(segment
		(start 343.886282 -228.134672)
		(end 343.87155 -228.143308)
		(width 0.0889)
		(layer "In4.Cu")
		(net "PWRGD_CPU0_LVC1")
	)
	(segment
		(start 334.993488 -221.19844)
		(end 334.618076 -221.19844)
		(width 0.0889)
		(layer "In4.Cu")
		(net "PWRGD_CPU0_LVC1")
	)
	(segment
		(start 334.618076 -221.19844)
		(end 334.457802 -221.038166)
		(width 0.0889)
		(layer "In4.Cu")
		(net "PWRGD_CPU0_LVC1")
	)
	(segment
		(start 339.74913 -225.217482)
		(end 339.74913 -225.203258)
		(width 0.0889)
		(layer "In4.Cu")
		(net "PWRGD_CPU0_LVC1")
	)
	(segment
		(start 341.911432 -227.320602)
		(end 341.905336 -227.317046)
		(width 0.0889)
		(layer "In4.Cu")
		(net "PWRGD_CPU0_LVC1")
	)
	(segment
		(start 343.08288 -228.087174)
		(end 342.982296 -228.100128)
		(width 0.0889)
		(layer "In4.Cu")
		(net "PWRGD_CPU0_LVC1")
	)
	(segment
		(start 335.98993 -221.94774)
		(end 335.98993 -221.939104)
		(width 0.0889)
		(layer "In4.Cu")
		(net "PWRGD_CPU0_LVC1")
	)
	(segment
		(start 329.002898 -199.710802)
		(end 329.233276 -199.480424)
		(width 0.127)
		(layer "In4.Cu")
		(net "PWRGD_CPU0_LVC1")
	)
	(segment
		(start 341.926164 -227.329238)
		(end 341.911432 -227.320602)
		(width 0.0889)
		(layer "In4.Cu")
		(net "PWRGD_CPU0_LVC1")
	)
	(segment
		(start 339.279484 -224.404936)
		(end 339.279484 -224.389442)
		(width 0.0889)
		(layer "In4.Cu")
		(net "PWRGD_CPU0_LVC1")
	)
	(arc
		(start 341.62873 -226.822508)
		(mid 341.57646 -226.640143)
		(end 341.441532 -226.506786)
		(width 0.0889)
		(layer "In4.Cu")
		(net "PWRGD_CPU0_LVC1")
	)
	(arc
		(start 339.279484 -224.389442)
		(mid 339.231805 -224.206542)
		(end 339.100922 -224.070164)
		(width 0.0889)
		(layer "In4.Cu")
		(net "PWRGD_CPU0_LVC1")
	)
	(arc
		(start 347.645482 -228.134672)
		(mid 347.36278 -228.210414)
		(end 347.080078 -228.134672)
		(width 0.0889)
		(layer "In4.Cu")
		(net "PWRGD_CPU0_LVC1")
	)
	(arc
		(start 346.695268 -228.140768)
		(mid 346.41709 -228.21046)
		(end 346.140532 -228.134672)
		(width 0.0889)
		(layer "In4.Cu")
		(net "PWRGD_CPU0_LVC1")
	)
	(arc
		(start 349.302578 -228.35235)
		(mid 349.252888 -228.308783)
		(end 349.19793 -228.272086)
		(width 0.0889)
		(layer "In4.Cu")
		(net "PWRGD_CPU0_LVC1")
	)
	(arc
		(start 336.266536 -222.433642)
		(mid 336.063949 -222.227291)
		(end 335.98993 -221.94774)
		(width 0.0889)
		(layer "In4.Cu")
		(net "PWRGD_CPU0_LVC1")
	)
	(arc
		(start 348.019878 -228.134672)
		(mid 347.83268 -228.084529)
		(end 347.645482 -228.134672)
		(width 0.0889)
		(layer "In4.Cu")
		(net "PWRGD_CPU0_LVC1")
	)
	(arc
		(start 339.561678 -224.8789)
		(mid 339.358855 -224.678669)
		(end 339.279484 -224.404936)
		(width 0.0889)
		(layer "In4.Cu")
		(net "PWRGD_CPU0_LVC1")
	)
	(arc
		(start 341.441532 -226.506786)
		(mid 341.237197 -226.304181)
		(end 341.159084 -226.027234)
		(width 0.0889)
		(layer "In4.Cu")
		(net "PWRGD_CPU0_LVC1")
	)
	(arc
		(start 336.715354 -223.001332)
		(mid 336.648851 -222.901942)
		(end 336.625438 -222.78467)
		(width 0.0889)
		(layer "In4.Cu")
		(net "PWRGD_CPU0_LVC1")
	)
	(arc
		(start 344.81135 -228.143308)
		(mid 344.534909 -228.210474)
		(end 344.260678 -228.134672)
		(width 0.0889)
		(layer "In4.Cu")
		(net "PWRGD_CPU0_LVC1")
	)
	(arc
		(start 342.746838 -228.10597)
		(mid 342.595736 -228.074861)
		(end 342.469216 -227.98659)
		(width 0.0889)
		(layer "In4.Cu")
		(net "PWRGD_CPU0_LVC1")
	)
	(arc
		(start 339.74913 -225.203258)
		(mid 339.701451 -225.020358)
		(end 339.570568 -224.88398)
		(width 0.0889)
		(layer "In4.Cu")
		(net "PWRGD_CPU0_LVC1")
	)
	(arc
		(start 340.031832 -225.69297)
		(mid 339.828351 -225.492166)
		(end 339.74913 -225.217482)
		(width 0.0889)
		(layer "In4.Cu")
		(net "PWRGD_CPU0_LVC1")
	)
	(arc
		(start 338.247482 -223.251268)
		(mid 337.965034 -223.326883)
		(end 337.682586 -223.251268)
		(width 0.0889)
		(layer "In4.Cu")
		(net "PWRGD_CPU0_LVC1")
	)
	(arc
		(start 340.971632 -225.69297)
		(mid 340.784434 -225.642827)
		(end 340.597236 -225.69297)
		(width 0.0889)
		(layer "In4.Cu")
		(net "PWRGD_CPU0_LVC1")
	)
	(arc
		(start 346.140532 -228.134672)
		(mid 345.953334 -228.084529)
		(end 345.766136 -228.134672)
		(width 0.0889)
		(layer "In4.Cu")
		(net "PWRGD_CPU0_LVC1")
	)
	(arc
		(start 342.232234 -227.736654)
		(mid 342.189556 -227.675529)
		(end 342.166702 -227.604574)
		(width 0.0889)
		(layer "In4.Cu")
		(net "PWRGD_CPU0_LVC1")
	)
	(arc
		(start 341.159084 -226.017328)
		(mid 341.111405 -225.834428)
		(end 340.980522 -225.69805)
		(width 0.0889)
		(layer "In4.Cu")
		(net "PWRGD_CPU0_LVC1")
	)
	(arc
		(start 345.200478 -228.134672)
		(mid 345.01328 -228.084529)
		(end 344.826082 -228.134672)
		(width 0.0889)
		(layer "In4.Cu")
		(net "PWRGD_CPU0_LVC1")
	)
	(arc
		(start 342.063578 -227.43541)
		(mid 341.99826 -227.377938)
		(end 341.926164 -227.329238)
		(width 0.0889)
		(layer "In4.Cu")
		(net "PWRGD_CPU0_LVC1")
	)
	(arc
		(start 342.982296 -228.100128)
		(mid 342.93794 -228.10448)
		(end 342.893396 -228.10597)
		(width 0.0889)
		(layer "In4.Cu")
		(net "PWRGD_CPU0_LVC1")
	)
	(arc
		(start 343.320878 -228.134672)
		(mid 343.205796 -228.091311)
		(end 343.08288 -228.087174)
		(width 0.0889)
		(layer "In4.Cu")
		(net "PWRGD_CPU0_LVC1")
	)
	(arc
		(start 342.166702 -227.604574)
		(mid 342.142177 -227.530879)
		(end 342.096344 -227.468176)
		(width 0.0889)
		(layer "In4.Cu")
		(net "PWRGD_CPU0_LVC1")
	)
	(arc
		(start 336.942938 -223.14789)
		(mid 336.867718 -223.13291)
		(end 336.804 -223.090232)
		(width 0.0889)
		(layer "In4.Cu")
		(net "PWRGD_CPU0_LVC1")
	)
	(arc
		(start 348.57055 -228.143308)
		(mid 348.294109 -228.210474)
		(end 348.019878 -228.134672)
		(width 0.0889)
		(layer "In4.Cu")
		(net "PWRGD_CPU0_LVC1")
	)
	(arc
		(start 336.625438 -222.78467)
		(mid 336.592942 -222.662575)
		(end 336.504026 -222.572834)
		(width 0.0889)
		(layer "In4.Cu")
		(net "PWRGD_CPU0_LVC1")
	)
	(arc
		(start 337.673696 -223.246188)
		(mid 337.482923 -223.167226)
		(end 337.278218 -223.14027)
		(width 0.0889)
		(layer "In4.Cu")
		(net "PWRGD_CPU0_LVC1")
	)
	(arc
		(start 338.80933 -223.575626)
		(mid 338.761651 -223.392726)
		(end 338.630768 -223.256348)
		(width 0.0889)
		(layer "In4.Cu")
		(net "PWRGD_CPU0_LVC1")
	)
	(arc
		(start 348.959678 -228.134672)
		(mid 348.77248 -228.084529)
		(end 348.585282 -228.134672)
		(width 0.0889)
		(layer "In4.Cu")
		(net "PWRGD_CPU0_LVC1")
	)
	(arc
		(start 344.260678 -228.134672)
		(mid 344.07348 -228.084529)
		(end 343.886282 -228.134672)
		(width 0.0889)
		(layer "In4.Cu")
		(net "PWRGD_CPU0_LVC1")
	)
	(arc
		(start 338.621878 -223.251268)
		(mid 338.43468 -223.201125)
		(end 338.247482 -223.251268)
		(width 0.0889)
		(layer "In4.Cu")
		(net "PWRGD_CPU0_LVC1")
	)
	(arc
		(start 345.755722 -228.140768)
		(mid 345.47729 -228.210582)
		(end 345.200478 -228.134672)
		(width 0.0889)
		(layer "In4.Cu")
		(net "PWRGD_CPU0_LVC1")
	)
	(arc
		(start 336.961226 -223.14027)
		(mid 336.951311 -223.142242)
		(end 336.942938 -223.14789)
		(width 0.0889)
		(layer "In4.Cu")
		(net "PWRGD_CPU0_LVC1")
	)
	(arc
		(start 335.368646 -221.573344)
		(mid 335.368354 -221.573286)
		(end 335.368138 -221.57309)
		(width 0.0889)
		(layer "In4.Cu")
		(net "PWRGD_CPU0_LVC1")
	)
	(arc
		(start 340.597236 -225.69297)
		(mid 340.323007 -225.768895)
		(end 340.046564 -225.701606)
		(width 0.0889)
		(layer "In4.Cu")
		(net "PWRGD_CPU0_LVC1")
	)
	(arc
		(start 343.87155 -228.143308)
		(mid 343.595109 -228.210474)
		(end 343.320878 -228.134672)
		(width 0.0889)
		(layer "In4.Cu")
		(net "PWRGD_CPU0_LVC1")
	)
	(arc
		(start 347.080078 -228.134672)
		(mid 346.89288 -228.084529)
		(end 346.705682 -228.134672)
		(width 0.0889)
		(layer "In4.Cu")
		(net "PWRGD_CPU0_LVC1")
	)
	(arc
		(start 335.98993 -221.939104)
		(mid 335.877271 -221.679896)
		(end 335.615534 -221.573344)
		(width 0.0889)
		(layer "In4.Cu")
		(net "PWRGD_CPU0_LVC1")
	)
	(arc
		(start 339.07984 -224.057972)
		(mid 338.881612 -223.852124)
		(end 338.80933 -223.575626)
		(width 0.0889)
		(layer "In4.Cu")
		(net "PWRGD_CPU0_LVC1")
	)
	(arc
		(start 341.905336 -227.317046)
		(mid 341.702749 -227.110695)
		(end 341.62873 -226.831144)
		(width 0.0889)
		(layer "In4.Cu")
		(net "PWRGD_CPU0_LVC1")
	)
	(segment
		(start 186.23788 -96.719898)
		(end 186.99988 -96.719898)
		(width 0.12954)
		(layer "F.Cu")
		(net "PWRGD_CPU0_BUF_R")
	)
	(via
		(at 192.98666 -133.482588)
		(size 0.508)
		(drill 0.254)
		(layers "F.Cu" "B.Cu")
		(net "PWRGD_CPU0_BUF_R")
	)
	(via
		(at 268.78788 -148.808948)
		(size 0.508)
		(drill 0.254)
		(layers "F.Cu" "B.Cu")
		(net "PWRGD_CPU0_BUF_R")
	)
	(via
		(at 186.99988 -96.719898)
		(size 0.508)
		(drill 0.254)
		(layers "F.Cu" "B.Cu")
		(net "PWRGD_CPU0_BUF_R")
	)
	(segment
		(start 330.651358 -188.45022)
		(end 330.280518 -188.07938)
		(width 0.12954)
		(layer "B.Cu")
		(net "PWRGD_CPU0_BUF_R")
	)
	(segment
		(start 330.651358 -190.35522)
		(end 330.651358 -188.45022)
		(width 0.12954)
		(layer "B.Cu")
		(net "PWRGD_CPU0_BUF_R")
	)
	(segment
		(start 268.78788 -148.808948)
		(end 268.78788 -156.060648)
		(width 0.12954)
		(layer "B.Cu")
		(net "PWRGD_CPU0_BUF_R")
	)
	(segment
		(start 328.344276 -182.609744)
		(end 329.42403 -182.609744)
		(width 0.12954)
		(layer "B.Cu")
		(net "PWRGD_CPU0_BUF_R")
	)
	(segment
		(start 278.23668 -165.509448)
		(end 311.24398 -165.509448)
		(width 0.12954)
		(layer "B.Cu")
		(net "PWRGD_CPU0_BUF_R")
	)
	(segment
		(start 330.288138 -183.473852)
		(end 330.288138 -186.31154)
		(width 0.12954)
		(layer "B.Cu")
		(net "PWRGD_CPU0_BUF_R")
	)
	(segment
		(start 330.577698 -190.42888)
		(end 330.651358 -190.35522)
		(width 0.12954)
		(layer "B.Cu")
		(net "PWRGD_CPU0_BUF_R")
	)
	(segment
		(start 329.42403 -182.609744)
		(end 330.288138 -183.473852)
		(width 0.12954)
		(layer "B.Cu")
		(net "PWRGD_CPU0_BUF_R")
	)
	(segment
		(start 329.81392 -186.785758)
		(end 329.81392 -187.612782)
		(width 0.12954)
		(layer "B.Cu")
		(net "PWRGD_CPU0_BUF_R")
	)
	(segment
		(start 329.81392 -187.612782)
		(end 330.280518 -188.07938)
		(width 0.12954)
		(layer "B.Cu")
		(net "PWRGD_CPU0_BUF_R")
	)
	(segment
		(start 330.288138 -186.31154)
		(end 329.81392 -186.785758)
		(width 0.12954)
		(layer "B.Cu")
		(net "PWRGD_CPU0_BUF_R")
	)
	(segment
		(start 311.24398 -165.509448)
		(end 328.344276 -182.609744)
		(width 0.12954)
		(layer "B.Cu")
		(net "PWRGD_CPU0_BUF_R")
	)
	(segment
		(start 268.78788 -156.060648)
		(end 278.23668 -165.509448)
		(width 0.12954)
		(layer "B.Cu")
		(net "PWRGD_CPU0_BUF_R")
	)
	(segment
		(start 189.95898 -101.156008)
		(end 188.54293 -99.739958)
		(width 0.127)
		(layer "In11.Cu")
		(net "PWRGD_CPU0_BUF_R")
	)
	(segment
		(start 188.54293 -97.500948)
		(end 187.76188 -96.719898)
		(width 0.127)
		(layer "In11.Cu")
		(net "PWRGD_CPU0_BUF_R")
	)
	(segment
		(start 192.8622 -118.476268)
		(end 191.65062 -117.264688)
		(width 0.127)
		(layer "In11.Cu")
		(net "PWRGD_CPU0_BUF_R")
	)
	(segment
		(start 192.8622 -133.358128)
		(end 192.8622 -118.476268)
		(width 0.127)
		(layer "In11.Cu")
		(net "PWRGD_CPU0_BUF_R")
	)
	(segment
		(start 187.76188 -96.719898)
		(end 186.99988 -96.719898)
		(width 0.127)
		(layer "In11.Cu")
		(net "PWRGD_CPU0_BUF_R")
	)
	(segment
		(start 191.65062 -117.264688)
		(end 191.65062 -109.408468)
		(width 0.127)
		(layer "In11.Cu")
		(net "PWRGD_CPU0_BUF_R")
	)
	(segment
		(start 192.98666 -133.482588)
		(end 192.8622 -133.358128)
		(width 0.127)
		(layer "In11.Cu")
		(net "PWRGD_CPU0_BUF_R")
	)
	(segment
		(start 191.65062 -109.408468)
		(end 189.95898 -107.716828)
		(width 0.127)
		(layer "In11.Cu")
		(net "PWRGD_CPU0_BUF_R")
	)
	(segment
		(start 188.54293 -99.739958)
		(end 188.54293 -97.500948)
		(width 0.127)
		(layer "In11.Cu")
		(net "PWRGD_CPU0_BUF_R")
	)
	(segment
		(start 189.95898 -107.716828)
		(end 189.95898 -101.156008)
		(width 0.127)
		(layer "In11.Cu")
		(net "PWRGD_CPU0_BUF_R")
	)
	(segment
		(start 267.51788 -147.538948)
		(end 268.78788 -148.808948)
		(width 0.127)
		(layer "In13.Cu")
		(net "PWRGD_CPU0_BUF_R")
	)
	(segment
		(start 215.373204 -146.676872)
		(end 242.374928 -146.676872)
		(width 0.127)
		(layer "In13.Cu")
		(net "PWRGD_CPU0_BUF_R")
	)
	(segment
		(start 193.58102 -134.076948)
		(end 196.180456 -134.076948)
		(width 0.127)
		(layer "In13.Cu")
		(net "PWRGD_CPU0_BUF_R")
	)
	(segment
		(start 202.51928 -133.822948)
		(end 215.373204 -146.676872)
		(width 0.127)
		(layer "In13.Cu")
		(net "PWRGD_CPU0_BUF_R")
	)
	(segment
		(start 196.180456 -134.076948)
		(end 196.434456 -133.822948)
		(width 0.127)
		(layer "In13.Cu")
		(net "PWRGD_CPU0_BUF_R")
	)
	(segment
		(start 243.237004 -147.538948)
		(end 267.51788 -147.538948)
		(width 0.127)
		(layer "In13.Cu")
		(net "PWRGD_CPU0_BUF_R")
	)
	(segment
		(start 192.98666 -133.482588)
		(end 193.58102 -134.076948)
		(width 0.127)
		(layer "In13.Cu")
		(net "PWRGD_CPU0_BUF_R")
	)
	(segment
		(start 196.434456 -133.822948)
		(end 202.51928 -133.822948)
		(width 0.127)
		(layer "In13.Cu")
		(net "PWRGD_CPU0_BUF_R")
	)
	(segment
		(start 242.374928 -146.676872)
		(end 243.237004 -147.538948)
		(width 0.127)
		(layer "In13.Cu")
		(net "PWRGD_CPU0_BUF_R")
	)
	(segment
		(start 206.35976 -319.716658)
		(end 208.176114 -319.716658)
		(width 0.12954)
		(layer "F.Cu")
		(net "PWRGD_CHH_CPU1_DIMM2")
	)
	(via
		(at 206.35976 -319.716658)
		(size 0.4572)
		(drill 0.2032)
		(layers "F.Cu" "B.Cu")
		(net "PWRGD_CHH_CPU1_DIMM2")
	)
	(segment
		(start 207.452722 -319.716658)
		(end 208.127854 -319.041526)
		(width 0.12954)
		(layer "B.Cu")
		(net "PWRGD_CHH_CPU1_DIMM2")
	)
	(segment
		(start 206.35976 -319.716658)
		(end 207.452722 -319.716658)
		(width 0.12954)
		(layer "B.Cu")
		(net "PWRGD_CHH_CPU1_DIMM2")
	)
	(segment
		(start 214.615014 -319.716658)
		(end 215.719914 -319.716658)
		(width 0.12954)
		(layer "F.Cu")
		(net "PWRGD_CHH_CPU1_DIMM1")
	)
	(via
		(at 216.374218 -319.226692)
		(size 0.6604)
		(drill 0.3302)
		(layers "F.Cu" "B.Cu")
		(net "PWRGD_CHH_CPU1_DIMM1")
	)
	(via
		(at 214.615014 -319.716658)
		(size 0.4572)
		(drill 0.2032)
		(layers "F.Cu" "B.Cu")
		(net "PWRGD_CHH_CPU1_DIMM1")
	)
	(segment
		(start 214.615014 -319.716658)
		(end 215.10498 -319.226692)
		(width 0.12954)
		(layer "B.Cu")
		(net "PWRGD_CHH_CPU1_DIMM1")
	)
	(segment
		(start 215.10498 -319.226692)
		(end 215.206834 -319.226692)
		(width 0.12954)
		(layer "B.Cu")
		(net "PWRGD_CHH_CPU1_DIMM1")
	)
	(segment
		(start 216.374218 -319.226692)
		(end 215.206834 -319.226692)
		(width 0.12954)
		(layer "B.Cu")
		(net "PWRGD_CHH_CPU1_DIMM1")
	)
	(segment
		(start 455.10831 -319.716658)
		(end 456.116182 -319.716658)
		(width 0.12954)
		(layer "F.Cu")
		(net "PWRGD_CHH_CPU0_DIMM2")
	)
	(segment
		(start 454.24344 -321.188588)
		(end 454.24344 -320.581528)
		(width 0.12954)
		(layer "F.Cu")
		(net "PWRGD_CHH_CPU0_DIMM2")
	)
	(segment
		(start 454.24344 -320.581528)
		(end 455.10831 -319.716658)
		(width 0.12954)
		(layer "F.Cu")
		(net "PWRGD_CHH_CPU0_DIMM2")
	)
	(via
		(at 454.24344 -321.188588)
		(size 0.4572)
		(drill 0.2032)
		(layers "F.Cu" "B.Cu")
		(net "PWRGD_CHH_CPU0_DIMM2")
	)
	(segment
		(start 454.24344 -321.188588)
		(end 454.24344 -320.591942)
		(width 0.12954)
		(layer "B.Cu")
		(net "PWRGD_CHH_CPU0_DIMM2")
	)
	(segment
		(start 454.24344 -320.591942)
		(end 455.603356 -319.232026)
		(width 0.12954)
		(layer "B.Cu")
		(net "PWRGD_CHH_CPU0_DIMM2")
	)
	(segment
		(start 464.80476 -320.352928)
		(end 464.16849 -319.716658)
		(width 0.12954)
		(layer "F.Cu")
		(net "PWRGD_CHH_CPU0_DIMM1")
	)
	(segment
		(start 464.80476 -320.970148)
		(end 464.80476 -320.352928)
		(width 0.12954)
		(layer "F.Cu")
		(net "PWRGD_CHH_CPU0_DIMM1")
	)
	(segment
		(start 464.16849 -319.716658)
		(end 463.659982 -319.716658)
		(width 0.12954)
		(layer "F.Cu")
		(net "PWRGD_CHH_CPU0_DIMM1")
	)
	(via
		(at 464.80476 -320.970148)
		(size 0.4572)
		(drill 0.2032)
		(layers "F.Cu" "B.Cu")
		(net "PWRGD_CHH_CPU0_DIMM1")
	)
	(segment
		(start 459.982316 -319.587118)
		(end 459.982316 -319.008506)
		(width 0.12954)
		(layer "B.Cu")
		(net "PWRGD_CHH_CPU0_DIMM1")
	)
	(segment
		(start 464.80476 -320.970148)
		(end 463.55127 -319.716658)
		(width 0.12954)
		(layer "B.Cu")
		(net "PWRGD_CHH_CPU0_DIMM1")
	)
	(segment
		(start 463.55127 -319.716658)
		(end 460.111856 -319.716658)
		(width 0.12954)
		(layer "B.Cu")
		(net "PWRGD_CHH_CPU0_DIMM1")
	)
	(segment
		(start 460.111856 -319.716658)
		(end 459.982316 -319.587118)
		(width 0.12954)
		(layer "B.Cu")
		(net "PWRGD_CHH_CPU0_DIMM1")
	)
	(segment
		(start 191.262 -320.383408)
		(end 191.92875 -319.716658)
		(width 0.12954)
		(layer "F.Cu")
		(net "PWRGD_CHG_CPU1_DIMM2")
	)
	(segment
		(start 191.92875 -319.716658)
		(end 193.088514 -319.716658)
		(width 0.12954)
		(layer "F.Cu")
		(net "PWRGD_CHG_CPU1_DIMM2")
	)
	(via
		(at 191.262 -320.383408)
		(size 0.4572)
		(drill 0.2032)
		(layers "F.Cu" "B.Cu")
		(net "PWRGD_CHG_CPU1_DIMM2")
	)
	(segment
		(start 191.744092 -319.901316)
		(end 192.62344 -319.901316)
		(width 0.12954)
		(layer "B.Cu")
		(net "PWRGD_CHG_CPU1_DIMM2")
	)
	(segment
		(start 191.262 -320.383408)
		(end 191.744092 -319.901316)
		(width 0.12954)
		(layer "B.Cu")
		(net "PWRGD_CHG_CPU1_DIMM2")
	)
	(segment
		(start 192.62344 -319.901316)
		(end 193.101468 -319.423288)
		(width 0.12954)
		(layer "B.Cu")
		(net "PWRGD_CHG_CPU1_DIMM2")
	)
	(segment
		(start 199.07885 -319.716658)
		(end 200.632314 -319.716658)
		(width 0.12954)
		(layer "F.Cu")
		(net "PWRGD_CHG_CPU1_DIMM1")
	)
	(segment
		(start 198.91502 -319.880488)
		(end 199.07885 -319.716658)
		(width 0.12954)
		(layer "F.Cu")
		(net "PWRGD_CHG_CPU1_DIMM1")
	)
	(via
		(at 198.91502 -319.880488)
		(size 0.4572)
		(drill 0.2032)
		(layers "F.Cu" "B.Cu")
		(net "PWRGD_CHG_CPU1_DIMM1")
	)
	(segment
		(start 199.07885 -319.716658)
		(end 198.91502 -319.880488)
		(width 0.12954)
		(layer "B.Cu")
		(net "PWRGD_CHG_CPU1_DIMM1")
	)
	(segment
		(start 200.07199 -319.716658)
		(end 199.07885 -319.716658)
		(width 0.12954)
		(layer "B.Cu")
		(net "PWRGD_CHG_CPU1_DIMM1")
	)
	(segment
		(start 201.08799 -319.397126)
		(end 200.391522 -319.397126)
		(width 0.12954)
		(layer "B.Cu")
		(net "PWRGD_CHG_CPU1_DIMM1")
	)
	(segment
		(start 200.391522 -319.397126)
		(end 200.07199 -319.716658)
		(width 0.12954)
		(layer "B.Cu")
		(net "PWRGD_CHG_CPU1_DIMM1")
	)
	(segment
		(start 441.028582 -319.716658)
		(end 439.923682 -319.716658)
		(width 0.12954)
		(layer "F.Cu")
		(net "PWRGD_CHG_CPU0_DIMM2")
	)
	(via
		(at 439.923682 -319.716658)
		(size 0.4572)
		(drill 0.2032)
		(layers "F.Cu" "B.Cu")
		(net "PWRGD_CHG_CPU0_DIMM2")
	)
	(via
		(at 441.766198 -319.26149)
		(size 0.6604)
		(drill 0.3302)
		(layers "F.Cu" "B.Cu")
		(net "PWRGD_CHG_CPU0_DIMM2")
	)
	(segment
		(start 441.112148 -319.333626)
		(end 440.617356 -319.333626)
		(width 0.12954)
		(layer "B.Cu")
		(net "PWRGD_CHG_CPU0_DIMM2")
	)
	(segment
		(start 441.184284 -319.26149)
		(end 441.112148 -319.333626)
		(width 0.12954)
		(layer "B.Cu")
		(net "PWRGD_CHG_CPU0_DIMM2")
	)
	(segment
		(start 439.923682 -319.716658)
		(end 440.234324 -319.716658)
		(width 0.12954)
		(layer "B.Cu")
		(net "PWRGD_CHG_CPU0_DIMM2")
	)
	(segment
		(start 440.234324 -319.716658)
		(end 440.617356 -319.333626)
		(width 0.12954)
		(layer "B.Cu")
		(net "PWRGD_CHG_CPU0_DIMM2")
	)
	(segment
		(start 441.766198 -319.26149)
		(end 441.184284 -319.26149)
		(width 0.12954)
		(layer "B.Cu")
		(net "PWRGD_CHG_CPU0_DIMM2")
	)
	(segment
		(start 448.572382 -319.716658)
		(end 447.467482 -319.716658)
		(width 0.12954)
		(layer "F.Cu")
		(net "PWRGD_CHG_CPU0_DIMM1")
	)
	(via
		(at 447.467482 -319.716658)
		(size 0.4572)
		(drill 0.2032)
		(layers "F.Cu" "B.Cu")
		(net "PWRGD_CHG_CPU0_DIMM1")
	)
	(via
		(at 449.335398 -319.23609)
		(size 0.6604)
		(drill 0.3302)
		(layers "F.Cu" "B.Cu")
		(net "PWRGD_CHG_CPU0_DIMM1")
	)
	(segment
		(start 447.875914 -319.308226)
		(end 448.186556 -319.308226)
		(width 0.12954)
		(layer "B.Cu")
		(net "PWRGD_CHG_CPU0_DIMM1")
	)
	(segment
		(start 449.335398 -319.23609)
		(end 448.753484 -319.23609)
		(width 0.12954)
		(layer "B.Cu")
		(net "PWRGD_CHG_CPU0_DIMM1")
	)
	(segment
		(start 447.467482 -319.716658)
		(end 447.875914 -319.308226)
		(width 0.12954)
		(layer "B.Cu")
		(net "PWRGD_CHG_CPU0_DIMM1")
	)
	(segment
		(start 448.753484 -319.23609)
		(end 448.681348 -319.308226)
		(width 0.12954)
		(layer "B.Cu")
		(net "PWRGD_CHG_CPU0_DIMM1")
	)
	(segment
		(start 448.681348 -319.308226)
		(end 448.186556 -319.308226)
		(width 0.12954)
		(layer "B.Cu")
		(net "PWRGD_CHG_CPU0_DIMM1")
	)
	(segment
		(start 177.02149 -319.716658)
		(end 178.000914 -319.716658)
		(width 0.12954)
		(layer "F.Cu")
		(net "PWRGD_CHF_CPU1_DIMM2")
	)
	(segment
		(start 176.3014 -320.436748)
		(end 177.02149 -319.716658)
		(width 0.12954)
		(layer "F.Cu")
		(net "PWRGD_CHF_CPU1_DIMM2")
	)
	(via
		(at 176.3014 -320.436748)
		(size 0.4572)
		(drill 0.2032)
		(layers "F.Cu" "B.Cu")
		(net "PWRGD_CHF_CPU1_DIMM2")
	)
	(segment
		(start 178.323748 -319.422526)
		(end 177.90033 -319.845944)
		(width 0.12954)
		(layer "B.Cu")
		(net "PWRGD_CHF_CPU1_DIMM2")
	)
	(segment
		(start 177.90033 -319.845944)
		(end 176.892204 -319.845944)
		(width 0.12954)
		(layer "B.Cu")
		(net "PWRGD_CHF_CPU1_DIMM2")
	)
	(segment
		(start 176.892204 -319.845944)
		(end 176.3014 -320.436748)
		(width 0.12954)
		(layer "B.Cu")
		(net "PWRGD_CHF_CPU1_DIMM2")
	)
	(segment
		(start 183.8198 -319.716658)
		(end 185.544714 -319.716658)
		(width 0.12954)
		(layer "F.Cu")
		(net "PWRGD_CHF_CPU1_DIMM1")
	)
	(via
		(at 183.8198 -319.716658)
		(size 0.4572)
		(drill 0.2032)
		(layers "F.Cu" "B.Cu")
		(net "PWRGD_CHF_CPU1_DIMM1")
	)
	(segment
		(start 185.061352 -319.400174)
		(end 185.479944 -319.400174)
		(width 0.12954)
		(layer "B.Cu")
		(net "PWRGD_CHF_CPU1_DIMM1")
	)
	(segment
		(start 184.978548 -319.423542)
		(end 185.037984 -319.423542)
		(width 0.12954)
		(layer "B.Cu")
		(net "PWRGD_CHF_CPU1_DIMM1")
	)
	(segment
		(start 183.8198 -319.716658)
		(end 184.685432 -319.716658)
		(width 0.12954)
		(layer "B.Cu")
		(net "PWRGD_CHF_CPU1_DIMM1")
	)
	(segment
		(start 185.037984 -319.423542)
		(end 185.061352 -319.400174)
		(width 0.12954)
		(layer "B.Cu")
		(net "PWRGD_CHF_CPU1_DIMM1")
	)
	(segment
		(start 184.685432 -319.716658)
		(end 184.978548 -319.423542)
		(width 0.12954)
		(layer "B.Cu")
		(net "PWRGD_CHF_CPU1_DIMM1")
	)
	(segment
		(start 185.479944 -319.400174)
		(end 185.503312 -319.423542)
		(width 0.12954)
		(layer "B.Cu")
		(net "PWRGD_CHF_CPU1_DIMM1")
	)
	(segment
		(start 425.940982 -319.716658)
		(end 424.836082 -319.716658)
		(width 0.12954)
		(layer "F.Cu")
		(net "PWRGD_CHF_CPU0_DIMM2")
	)
	(via
		(at 424.836082 -319.716658)
		(size 0.4572)
		(drill 0.2032)
		(layers "F.Cu" "B.Cu")
		(net "PWRGD_CHF_CPU0_DIMM2")
	)
	(via
		(at 427.467268 -319.762886)
		(size 0.6604)
		(drill 0.3302)
		(layers "F.Cu" "B.Cu")
		(net "PWRGD_CHF_CPU0_DIMM2")
	)
	(segment
		(start 424.836082 -319.716658)
		(end 425.244514 -319.308226)
		(width 0.12954)
		(layer "B.Cu")
		(net "PWRGD_CHF_CPU0_DIMM2")
	)
	(segment
		(start 425.244514 -319.308226)
		(end 425.555156 -319.308226)
		(width 0.12954)
		(layer "B.Cu")
		(net "PWRGD_CHF_CPU0_DIMM2")
	)
	(segment
		(start 427.467268 -319.762886)
		(end 426.358304 -319.762886)
		(width 0.12954)
		(layer "B.Cu")
		(net "PWRGD_CHF_CPU0_DIMM2")
	)
	(segment
		(start 426.358304 -319.762886)
		(end 425.903644 -319.308226)
		(width 0.12954)
		(layer "B.Cu")
		(net "PWRGD_CHF_CPU0_DIMM2")
	)
	(segment
		(start 425.903644 -319.308226)
		(end 425.555156 -319.308226)
		(width 0.12954)
		(layer "B.Cu")
		(net "PWRGD_CHF_CPU0_DIMM2")
	)
	(segment
		(start 432.379882 -319.716658)
		(end 433.484782 -319.716658)
		(width 0.12954)
		(layer "F.Cu")
		(net "PWRGD_CHF_CPU0_DIMM1")
	)
	(segment
		(start 431.55362 -320.54292)
		(end 432.379882 -319.716658)
		(width 0.12954)
		(layer "F.Cu")
		(net "PWRGD_CHF_CPU0_DIMM1")
	)
	(segment
		(start 431.55362 -321.033648)
		(end 431.55362 -320.54292)
		(width 0.12954)
		(layer "F.Cu")
		(net "PWRGD_CHF_CPU0_DIMM1")
	)
	(via
		(at 431.55362 -321.033648)
		(size 0.4572)
		(drill 0.2032)
		(layers "F.Cu" "B.Cu")
		(net "PWRGD_CHF_CPU0_DIMM1")
	)
	(segment
		(start 432.68519 -319.47485)
		(end 432.867308 -319.47485)
		(width 0.12954)
		(layer "B.Cu")
		(net "PWRGD_CHF_CPU0_DIMM1")
	)
	(segment
		(start 431.55362 -321.033648)
		(end 431.55362 -320.60642)
		(width 0.12954)
		(layer "B.Cu")
		(net "PWRGD_CHF_CPU0_DIMM1")
	)
	(segment
		(start 432.867308 -319.47485)
		(end 433.073302 -319.268856)
		(width 0.12954)
		(layer "B.Cu")
		(net "PWRGD_CHF_CPU0_DIMM1")
	)
	(segment
		(start 431.55362 -320.60642)
		(end 432.68519 -319.47485)
		(width 0.12954)
		(layer "B.Cu")
		(net "PWRGD_CHF_CPU0_DIMM1")
	)
	(segment
		(start 163.98367 -319.716658)
		(end 164.51326 -320.246248)
		(width 0.12954)
		(layer "F.Cu")
		(net "PWRGD_CHE_CPU1_DIMM2")
	)
	(segment
		(start 162.913314 -319.716658)
		(end 163.98367 -319.716658)
		(width 0.12954)
		(layer "F.Cu")
		(net "PWRGD_CHE_CPU1_DIMM2")
	)
	(via
		(at 164.51326 -320.246248)
		(size 0.4572)
		(drill 0.2032)
		(layers "F.Cu" "B.Cu")
		(net "PWRGD_CHE_CPU1_DIMM2")
	)
	(segment
		(start 164.51326 -320.246248)
		(end 163.66109 -319.394078)
		(width 0.12954)
		(layer "B.Cu")
		(net "PWRGD_CHE_CPU1_DIMM2")
	)
	(segment
		(start 163.66109 -319.394078)
		(end 163.66109 -319.117472)
		(width 0.12954)
		(layer "B.Cu")
		(net "PWRGD_CHE_CPU1_DIMM2")
	)
	(segment
		(start 170.457114 -319.716658)
		(end 168.99763 -319.716658)
		(width 0.12954)
		(layer "F.Cu")
		(net "PWRGD_CHE_CPU1_DIMM1")
	)
	(segment
		(start 168.99763 -319.716658)
		(end 168.81602 -319.898268)
		(width 0.12954)
		(layer "F.Cu")
		(net "PWRGD_CHE_CPU1_DIMM1")
	)
	(via
		(at 168.81602 -319.898268)
		(size 0.4572)
		(drill 0.2032)
		(layers "F.Cu" "B.Cu")
		(net "PWRGD_CHE_CPU1_DIMM1")
	)
	(segment
		(start 168.81602 -319.670938)
		(end 168.81602 -319.898268)
		(width 0.12954)
		(layer "B.Cu")
		(net "PWRGD_CHE_CPU1_DIMM1")
	)
	(segment
		(start 168.635934 -319.393062)
		(end 168.635934 -319.490852)
		(width 0.12954)
		(layer "B.Cu")
		(net "PWRGD_CHE_CPU1_DIMM1")
	)
	(segment
		(start 168.635934 -319.490852)
		(end 168.81602 -319.670938)
		(width 0.12954)
		(layer "B.Cu")
		(net "PWRGD_CHE_CPU1_DIMM1")
	)
	(segment
		(start 167.478202 -318.23533)
		(end 168.635934 -319.393062)
		(width 0.12954)
		(layer "B.Cu")
		(net "PWRGD_CHE_CPU1_DIMM1")
	)
	(segment
		(start 410.853382 -319.716658)
		(end 411.983682 -319.716658)
		(width 0.12954)
		(layer "F.Cu")
		(net "PWRGD_CHE_CPU0_DIMM2")
	)
	(via
		(at 411.664658 -319.08115)
		(size 0.6604)
		(drill 0.3302)
		(layers "F.Cu" "B.Cu")
		(net "PWRGD_CHE_CPU0_DIMM2")
	)
	(via
		(at 411.983682 -319.716658)
		(size 0.4572)
		(drill 0.2032)
		(layers "F.Cu" "B.Cu")
		(net "PWRGD_CHE_CPU0_DIMM2")
	)
	(segment
		(start 411.983682 -319.716658)
		(end 411.983682 -319.400174)
		(width 0.12954)
		(layer "B.Cu")
		(net "PWRGD_CHE_CPU0_DIMM2")
	)
	(segment
		(start 411.983682 -319.400174)
		(end 411.664658 -319.08115)
		(width 0.12954)
		(layer "B.Cu")
		(net "PWRGD_CHE_CPU0_DIMM2")
	)
	(segment
		(start 410.720032 -319.08115)
		(end 410.492956 -319.308226)
		(width 0.12954)
		(layer "B.Cu")
		(net "PWRGD_CHE_CPU0_DIMM2")
	)
	(segment
		(start 411.664658 -319.08115)
		(end 410.720032 -319.08115)
		(width 0.12954)
		(layer "B.Cu")
		(net "PWRGD_CHE_CPU0_DIMM2")
	)
	(segment
		(start 418.397182 -319.716658)
		(end 417.292282 -319.716658)
		(width 0.12954)
		(layer "F.Cu")
		(net "PWRGD_CHE_CPU0_DIMM1")
	)
	(via
		(at 417.757356 -317.478156)
		(size 0.6604)
		(drill 0.3302)
		(layers "F.Cu" "B.Cu")
		(net "PWRGD_CHE_CPU0_DIMM1")
	)
	(via
		(at 417.292282 -319.716658)
		(size 0.4572)
		(drill 0.2032)
		(layers "F.Cu" "B.Cu")
		(net "PWRGD_CHE_CPU0_DIMM1")
	)
	(segment
		(start 417.757356 -318.508634)
		(end 417.995354 -318.746632)
		(width 0.12954)
		(layer "B.Cu")
		(net "PWRGD_CHE_CPU0_DIMM1")
	)
	(segment
		(start 417.605972 -319.402968)
		(end 417.995354 -319.402968)
		(width 0.12954)
		(layer "B.Cu")
		(net "PWRGD_CHE_CPU0_DIMM1")
	)
	(segment
		(start 417.757356 -317.478156)
		(end 417.757356 -318.508634)
		(width 0.12954)
		(layer "B.Cu")
		(net "PWRGD_CHE_CPU0_DIMM1")
	)
	(segment
		(start 417.292282 -319.716658)
		(end 417.605972 -319.402968)
		(width 0.12954)
		(layer "B.Cu")
		(net "PWRGD_CHE_CPU0_DIMM1")
	)
	(segment
		(start 417.995354 -318.746632)
		(end 417.995354 -319.402968)
		(width 0.12954)
		(layer "B.Cu")
		(net "PWRGD_CHE_CPU0_DIMM1")
	)
	(segment
		(start 18.679414 -319.716658)
		(end 19.784314 -319.716658)
		(width 0.12954)
		(layer "F.Cu")
		(net "PWRGD_CHD_CPU1_DIMM2")
	)
	(via
		(at 18.679414 -319.716658)
		(size 0.4572)
		(drill 0.2032)
		(layers "F.Cu" "B.Cu")
		(net "PWRGD_CHD_CPU1_DIMM2")
	)
	(via
		(at 17.748758 -319.81775)
		(size 0.6604)
		(drill 0.3302)
		(layers "F.Cu" "B.Cu")
		(net "PWRGD_CHD_CPU1_DIMM2")
	)
	(segment
		(start 18.32483 -319.716658)
		(end 18.679414 -319.716658)
		(width 0.12954)
		(layer "B.Cu")
		(net "PWRGD_CHD_CPU1_DIMM2")
	)
	(segment
		(start 18.223738 -319.81775)
		(end 18.32483 -319.716658)
		(width 0.12954)
		(layer "B.Cu")
		(net "PWRGD_CHD_CPU1_DIMM2")
	)
	(segment
		(start 19.21891 -319.716658)
		(end 19.360896 -319.574672)
		(width 0.12954)
		(layer "B.Cu")
		(net "PWRGD_CHD_CPU1_DIMM2")
	)
	(segment
		(start 18.679414 -319.716658)
		(end 19.21891 -319.716658)
		(width 0.12954)
		(layer "B.Cu")
		(net "PWRGD_CHD_CPU1_DIMM2")
	)
	(segment
		(start 19.360896 -319.574672)
		(end 19.360896 -319.268856)
		(width 0.12954)
		(layer "B.Cu")
		(net "PWRGD_CHD_CPU1_DIMM2")
	)
	(segment
		(start 17.748758 -319.81775)
		(end 18.223738 -319.81775)
		(width 0.12954)
		(layer "B.Cu")
		(net "PWRGD_CHD_CPU1_DIMM2")
	)
	(segment
		(start 12.240514 -319.716658)
		(end 11.135614 -319.716658)
		(width 0.12954)
		(layer "F.Cu")
		(net "PWRGD_CHD_CPU1_DIMM1")
	)
	(via
		(at 11.135614 -319.716658)
		(size 0.4572)
		(drill 0.2032)
		(layers "F.Cu" "B.Cu")
		(net "PWRGD_CHD_CPU1_DIMM1")
	)
	(via
		(at 10.215118 -319.76695)
		(size 0.6604)
		(drill 0.3302)
		(layers "F.Cu" "B.Cu")
		(net "PWRGD_CHD_CPU1_DIMM1")
	)
	(segment
		(start 10.215118 -319.76695)
		(end 10.730738 -319.76695)
		(width 0.12954)
		(layer "B.Cu")
		(net "PWRGD_CHD_CPU1_DIMM1")
	)
	(segment
		(start 11.817096 -319.617852)
		(end 11.817096 -319.268856)
		(width 0.12954)
		(layer "B.Cu")
		(net "PWRGD_CHD_CPU1_DIMM1")
	)
	(segment
		(start 11.71829 -319.716658)
		(end 11.817096 -319.617852)
		(width 0.12954)
		(layer "B.Cu")
		(net "PWRGD_CHD_CPU1_DIMM1")
	)
	(segment
		(start 10.78103 -319.716658)
		(end 11.135614 -319.716658)
		(width 0.12954)
		(layer "B.Cu")
		(net "PWRGD_CHD_CPU1_DIMM1")
	)
	(segment
		(start 11.135614 -319.716658)
		(end 11.71829 -319.716658)
		(width 0.12954)
		(layer "B.Cu")
		(net "PWRGD_CHD_CPU1_DIMM1")
	)
	(segment
		(start 10.730738 -319.76695)
		(end 10.78103 -319.716658)
		(width 0.12954)
		(layer "B.Cu")
		(net "PWRGD_CHD_CPU1_DIMM1")
	)
	(segment
		(start 266.619482 -319.716658)
		(end 267.724382 -319.716658)
		(width 0.12954)
		(layer "F.Cu")
		(net "PWRGD_CHD_CPU0_DIMM2")
	)
	(via
		(at 268.489938 -319.24371)
		(size 0.6604)
		(drill 0.3302)
		(layers "F.Cu" "B.Cu")
		(net "PWRGD_CHD_CPU0_DIMM2")
	)
	(via
		(at 266.619482 -319.716658)
		(size 0.4572)
		(drill 0.2032)
		(layers "F.Cu" "B.Cu")
		(net "PWRGD_CHD_CPU0_DIMM2")
	)
	(segment
		(start 267.857478 -319.24371)
		(end 267.763244 -319.337944)
		(width 0.12954)
		(layer "B.Cu")
		(net "PWRGD_CHD_CPU0_DIMM2")
	)
	(segment
		(start 268.489938 -319.24371)
		(end 267.857478 -319.24371)
		(width 0.12954)
		(layer "B.Cu")
		(net "PWRGD_CHD_CPU0_DIMM2")
	)
	(segment
		(start 267.763244 -319.337944)
		(end 267.336016 -319.337944)
		(width 0.12954)
		(layer "B.Cu")
		(net "PWRGD_CHD_CPU0_DIMM2")
	)
	(segment
		(start 266.619482 -319.716658)
		(end 266.998196 -319.337944)
		(width 0.12954)
		(layer "B.Cu")
		(net "PWRGD_CHD_CPU0_DIMM2")
	)
	(segment
		(start 266.998196 -319.337944)
		(end 267.336016 -319.337944)
		(width 0.12954)
		(layer "B.Cu")
		(net "PWRGD_CHD_CPU0_DIMM2")
	)
	(segment
		(start 261.40029 -319.716658)
		(end 260.180582 -319.716658)
		(width 0.12954)
		(layer "F.Cu")
		(net "PWRGD_CHD_CPU0_DIMM1")
	)
	(segment
		(start 261.83082 -320.147188)
		(end 261.40029 -319.716658)
		(width 0.12954)
		(layer "F.Cu")
		(net "PWRGD_CHD_CPU0_DIMM1")
	)
	(segment
		(start 261.83082 -320.370708)
		(end 261.83082 -320.147188)
		(width 0.12954)
		(layer "F.Cu")
		(net "PWRGD_CHD_CPU0_DIMM1")
	)
	(via
		(at 261.83082 -320.370708)
		(size 0.4572)
		(drill 0.2032)
		(layers "F.Cu" "B.Cu")
		(net "PWRGD_CHD_CPU0_DIMM1")
	)
	(segment
		(start 261.83082 -320.370708)
		(end 261.83082 -320.231008)
		(width 0.12954)
		(layer "B.Cu")
		(net "PWRGD_CHD_CPU0_DIMM1")
	)
	(segment
		(start 261.83082 -320.231008)
		(end 261.5438 -319.943988)
		(width 0.12954)
		(layer "B.Cu")
		(net "PWRGD_CHD_CPU0_DIMM1")
	)
	(segment
		(start 260.437376 -319.943988)
		(end 259.757164 -319.263776)
		(width 0.12954)
		(layer "B.Cu")
		(net "PWRGD_CHD_CPU0_DIMM1")
	)
	(segment
		(start 261.5438 -319.943988)
		(end 260.437376 -319.943988)
		(width 0.12954)
		(layer "B.Cu")
		(net "PWRGD_CHD_CPU0_DIMM1")
	)
	(segment
		(start 33.767014 -319.716658)
		(end 34.871914 -319.716658)
		(width 0.12954)
		(layer "F.Cu")
		(net "PWRGD_CHC_CPU1_DIMM2")
	)
	(via
		(at 32.836358 -319.81775)
		(size 0.6604)
		(drill 0.3302)
		(layers "F.Cu" "B.Cu")
		(net "PWRGD_CHC_CPU1_DIMM2")
	)
	(via
		(at 33.767014 -319.716658)
		(size 0.4572)
		(drill 0.2032)
		(layers "F.Cu" "B.Cu")
		(net "PWRGD_CHC_CPU1_DIMM2")
	)
	(segment
		(start 34.448496 -319.542922)
		(end 34.448496 -319.633092)
		(width 0.12954)
		(layer "B.Cu")
		(net "PWRGD_CHC_CPU1_DIMM2")
	)
	(segment
		(start 34.448496 -319.633092)
		(end 34.36493 -319.716658)
		(width 0.12954)
		(layer "B.Cu")
		(net "PWRGD_CHC_CPU1_DIMM2")
	)
	(segment
		(start 33.41243 -319.716658)
		(end 33.311338 -319.81775)
		(width 0.12954)
		(layer "B.Cu")
		(net "PWRGD_CHC_CPU1_DIMM2")
	)
	(segment
		(start 33.311338 -319.81775)
		(end 32.836358 -319.81775)
		(width 0.12954)
		(layer "B.Cu")
		(net "PWRGD_CHC_CPU1_DIMM2")
	)
	(segment
		(start 34.36493 -319.716658)
		(end 33.767014 -319.716658)
		(width 0.12954)
		(layer "B.Cu")
		(net "PWRGD_CHC_CPU1_DIMM2")
	)
	(segment
		(start 34.5313 -319.460118)
		(end 34.448496 -319.542922)
		(width 0.12954)
		(layer "B.Cu")
		(net "PWRGD_CHC_CPU1_DIMM2")
	)
	(segment
		(start 33.767014 -319.716658)
		(end 33.41243 -319.716658)
		(width 0.12954)
		(layer "B.Cu")
		(net "PWRGD_CHC_CPU1_DIMM2")
	)
	(segment
		(start 26.223214 -319.716658)
		(end 27.328114 -319.716658)
		(width 0.12954)
		(layer "F.Cu")
		(net "PWRGD_CHC_CPU1_DIMM1")
	)
	(via
		(at 26.223214 -319.716658)
		(size 0.4572)
		(drill 0.2032)
		(layers "F.Cu" "B.Cu")
		(net "PWRGD_CHC_CPU1_DIMM1")
	)
	(via
		(at 25.292558 -319.81775)
		(size 0.6604)
		(drill 0.3302)
		(layers "F.Cu" "B.Cu")
		(net "PWRGD_CHC_CPU1_DIMM1")
	)
	(segment
		(start 25.292558 -319.81775)
		(end 25.767538 -319.81775)
		(width 0.12954)
		(layer "B.Cu")
		(net "PWRGD_CHC_CPU1_DIMM1")
	)
	(segment
		(start 25.86863 -319.716658)
		(end 26.223214 -319.716658)
		(width 0.12954)
		(layer "B.Cu")
		(net "PWRGD_CHC_CPU1_DIMM1")
	)
	(segment
		(start 26.904696 -319.589912)
		(end 26.904696 -319.268856)
		(width 0.12954)
		(layer "B.Cu")
		(net "PWRGD_CHC_CPU1_DIMM1")
	)
	(segment
		(start 25.767538 -319.81775)
		(end 25.86863 -319.716658)
		(width 0.12954)
		(layer "B.Cu")
		(net "PWRGD_CHC_CPU1_DIMM1")
	)
	(segment
		(start 26.223214 -319.716658)
		(end 26.77795 -319.716658)
		(width 0.12954)
		(layer "B.Cu")
		(net "PWRGD_CHC_CPU1_DIMM1")
	)
	(segment
		(start 26.77795 -319.716658)
		(end 26.904696 -319.589912)
		(width 0.12954)
		(layer "B.Cu")
		(net "PWRGD_CHC_CPU1_DIMM1")
	)
	(segment
		(start 281.11196 -322.047108)
		(end 281.11196 -320.700908)
		(width 0.12954)
		(layer "F.Cu")
		(net "PWRGD_CHC_CPU0_DIMM2")
	)
	(segment
		(start 282.09621 -319.716658)
		(end 282.811982 -319.716658)
		(width 0.12954)
		(layer "F.Cu")
		(net "PWRGD_CHC_CPU0_DIMM2")
	)
	(segment
		(start 281.11196 -320.700908)
		(end 282.09621 -319.716658)
		(width 0.12954)
		(layer "F.Cu")
		(net "PWRGD_CHC_CPU0_DIMM2")
	)
	(via
		(at 281.11196 -322.047108)
		(size 0.4572)
		(drill 0.2032)
		(layers "F.Cu" "B.Cu")
		(net "PWRGD_CHC_CPU0_DIMM2")
	)
	(segment
		(start 281.11196 -322.047108)
		(end 281.11196 -320.746628)
		(width 0.12954)
		(layer "B.Cu")
		(net "PWRGD_CHC_CPU0_DIMM2")
	)
	(segment
		(start 282.423616 -319.434972)
		(end 282.423616 -319.34658)
		(width 0.12954)
		(layer "B.Cu")
		(net "PWRGD_CHC_CPU0_DIMM2")
	)
	(segment
		(start 281.11196 -320.746628)
		(end 282.423616 -319.434972)
		(width 0.12954)
		(layer "B.Cu")
		(net "PWRGD_CHC_CPU0_DIMM2")
	)
	(segment
		(start 274.163282 -319.716658)
		(end 275.268182 -319.716658)
		(width 0.12954)
		(layer "F.Cu")
		(net "PWRGD_CHC_CPU0_DIMM1")
	)
	(via
		(at 275.999702 -319.233804)
		(size 0.6604)
		(drill 0.3302)
		(layers "F.Cu" "B.Cu")
		(net "PWRGD_CHC_CPU0_DIMM1")
	)
	(via
		(at 274.163282 -319.716658)
		(size 0.4572)
		(drill 0.2032)
		(layers "F.Cu" "B.Cu")
		(net "PWRGD_CHC_CPU0_DIMM1")
	)
	(segment
		(start 274.163282 -319.716658)
		(end 274.493482 -319.386458)
		(width 0.12954)
		(layer "B.Cu")
		(net "PWRGD_CHC_CPU0_DIMM1")
	)
	(segment
		(start 275.415502 -319.233804)
		(end 275.262848 -319.386458)
		(width 0.12954)
		(layer "B.Cu")
		(net "PWRGD_CHC_CPU0_DIMM1")
	)
	(segment
		(start 275.262848 -319.386458)
		(end 274.83562 -319.386458)
		(width 0.12954)
		(layer "B.Cu")
		(net "PWRGD_CHC_CPU0_DIMM1")
	)
	(segment
		(start 274.493482 -319.386458)
		(end 274.83562 -319.386458)
		(width 0.12954)
		(layer "B.Cu")
		(net "PWRGD_CHC_CPU0_DIMM1")
	)
	(segment
		(start 275.999702 -319.233804)
		(end 275.415502 -319.233804)
		(width 0.12954)
		(layer "B.Cu")
		(net "PWRGD_CHC_CPU0_DIMM1")
	)
	(segment
		(start 48.854614 -319.716658)
		(end 49.959514 -319.716658)
		(width 0.12954)
		(layer "F.Cu")
		(net "PWRGD_CHB_CPU1_DIMM2")
	)
	(via
		(at 47.829978 -320.16065)
		(size 0.6604)
		(drill 0.3302)
		(layers "F.Cu" "B.Cu")
		(net "PWRGD_CHB_CPU1_DIMM2")
	)
	(via
		(at 48.854614 -319.716658)
		(size 0.4572)
		(drill 0.2032)
		(layers "F.Cu" "B.Cu")
		(net "PWRGD_CHB_CPU1_DIMM2")
	)
	(segment
		(start 48.27397 -319.716658)
		(end 48.854614 -319.716658)
		(width 0.12954)
		(layer "B.Cu")
		(net "PWRGD_CHB_CPU1_DIMM2")
	)
	(segment
		(start 49.536096 -319.594992)
		(end 49.536096 -319.268856)
		(width 0.12954)
		(layer "B.Cu")
		(net "PWRGD_CHB_CPU1_DIMM2")
	)
	(segment
		(start 48.854614 -319.716658)
		(end 49.41443 -319.716658)
		(width 0.12954)
		(layer "B.Cu")
		(net "PWRGD_CHB_CPU1_DIMM2")
	)
	(segment
		(start 49.41443 -319.716658)
		(end 49.536096 -319.594992)
		(width 0.12954)
		(layer "B.Cu")
		(net "PWRGD_CHB_CPU1_DIMM2")
	)
	(segment
		(start 47.829978 -320.16065)
		(end 48.27397 -319.716658)
		(width 0.12954)
		(layer "B.Cu")
		(net "PWRGD_CHB_CPU1_DIMM2")
	)
	(segment
		(start 41.310814 -319.716658)
		(end 42.415714 -319.716658)
		(width 0.12954)
		(layer "F.Cu")
		(net "PWRGD_CHB_CPU1_DIMM1")
	)
	(via
		(at 40.380158 -319.81775)
		(size 0.6604)
		(drill 0.3302)
		(layers "F.Cu" "B.Cu")
		(net "PWRGD_CHB_CPU1_DIMM1")
	)
	(via
		(at 41.310814 -319.716658)
		(size 0.4572)
		(drill 0.2032)
		(layers "F.Cu" "B.Cu")
		(net "PWRGD_CHB_CPU1_DIMM1")
	)
	(segment
		(start 41.93667 -319.716658)
		(end 41.310814 -319.716658)
		(width 0.12954)
		(layer "B.Cu")
		(net "PWRGD_CHB_CPU1_DIMM1")
	)
	(segment
		(start 41.310814 -319.716658)
		(end 40.95623 -319.716658)
		(width 0.12954)
		(layer "B.Cu")
		(net "PWRGD_CHB_CPU1_DIMM1")
	)
	(segment
		(start 41.992296 -319.268856)
		(end 41.992296 -319.661032)
		(width 0.12954)
		(layer "B.Cu")
		(net "PWRGD_CHB_CPU1_DIMM1")
	)
	(segment
		(start 40.855138 -319.81775)
		(end 40.380158 -319.81775)
		(width 0.12954)
		(layer "B.Cu")
		(net "PWRGD_CHB_CPU1_DIMM1")
	)
	(segment
		(start 40.95623 -319.716658)
		(end 40.855138 -319.81775)
		(width 0.12954)
		(layer "B.Cu")
		(net "PWRGD_CHB_CPU1_DIMM1")
	)
	(segment
		(start 41.992296 -319.661032)
		(end 41.93667 -319.716658)
		(width 0.12954)
		(layer "B.Cu")
		(net "PWRGD_CHB_CPU1_DIMM1")
	)
	(segment
		(start 296.794682 -319.716658)
		(end 297.899582 -319.716658)
		(width 0.12954)
		(layer "F.Cu")
		(net "PWRGD_CHB_CPU0_DIMM2")
	)
	(via
		(at 296.794682 -319.716658)
		(size 0.4572)
		(drill 0.2032)
		(layers "F.Cu" "B.Cu")
		(net "PWRGD_CHB_CPU0_DIMM2")
	)
	(via
		(at 299.48632 -320.210688)
		(size 0.6604)
		(drill 0.3302)
		(layers "F.Cu" "B.Cu")
		(net "PWRGD_CHB_CPU0_DIMM2")
	)
	(segment
		(start 297.829478 -319.36563)
		(end 297.852846 -319.388998)
		(width 0.12954)
		(layer "B.Cu")
		(net "PWRGD_CHB_CPU0_DIMM2")
	)
	(segment
		(start 296.794682 -319.716658)
		(end 297.107864 -319.403476)
		(width 0.12954)
		(layer "B.Cu")
		(net "PWRGD_CHB_CPU0_DIMM2")
	)
	(segment
		(start 297.107864 -319.403476)
		(end 297.37304 -319.403476)
		(width 0.12954)
		(layer "B.Cu")
		(net "PWRGD_CHB_CPU0_DIMM2")
	)
	(segment
		(start 298.43603 -319.893188)
		(end 299.345858 -319.893188)
		(width 0.12954)
		(layer "B.Cu")
		(net "PWRGD_CHB_CPU0_DIMM2")
	)
	(segment
		(start 299.48632 -320.03365)
		(end 299.48632 -320.210688)
		(width 0.12954)
		(layer "B.Cu")
		(net "PWRGD_CHB_CPU0_DIMM2")
	)
	(segment
		(start 297.867324 -319.403476)
		(end 297.946318 -319.403476)
		(width 0.12954)
		(layer "B.Cu")
		(net "PWRGD_CHB_CPU0_DIMM2")
	)
	(segment
		(start 297.852846 -319.388998)
		(end 297.867324 -319.403476)
		(width 0.12954)
		(layer "B.Cu")
		(net "PWRGD_CHB_CPU0_DIMM2")
	)
	(segment
		(start 297.946318 -319.403476)
		(end 298.43603 -319.893188)
		(width 0.12954)
		(layer "B.Cu")
		(net "PWRGD_CHB_CPU0_DIMM2")
	)
	(segment
		(start 299.345858 -319.893188)
		(end 299.48632 -320.03365)
		(width 0.12954)
		(layer "B.Cu")
		(net "PWRGD_CHB_CPU0_DIMM2")
	)
	(segment
		(start 297.410886 -319.36563)
		(end 297.829478 -319.36563)
		(width 0.12954)
		(layer "B.Cu")
		(net "PWRGD_CHB_CPU0_DIMM2")
	)
	(segment
		(start 297.37304 -319.403476)
		(end 297.410886 -319.36563)
		(width 0.12954)
		(layer "B.Cu")
		(net "PWRGD_CHB_CPU0_DIMM2")
	)
	(segment
		(start 289.250882 -319.716658)
		(end 290.355782 -319.716658)
		(width 0.12954)
		(layer "F.Cu")
		(net "PWRGD_CHB_CPU0_DIMM1")
	)
	(via
		(at 289.250882 -319.716658)
		(size 0.4572)
		(drill 0.2032)
		(layers "F.Cu" "B.Cu")
		(net "PWRGD_CHB_CPU0_DIMM1")
	)
	(via
		(at 290.722558 -316.062614)
		(size 0.6604)
		(drill 0.3302)
		(layers "F.Cu" "B.Cu")
		(net "PWRGD_CHB_CPU0_DIMM1")
	)
	(segment
		(start 290.135056 -316.650116)
		(end 290.722558 -316.062614)
		(width 0.12954)
		(layer "B.Cu")
		(net "PWRGD_CHB_CPU0_DIMM1")
	)
	(segment
		(start 289.73272 -319.23482)
		(end 289.761422 -319.23482)
		(width 0.12954)
		(layer "B.Cu")
		(net "PWRGD_CHB_CPU0_DIMM1")
	)
	(segment
		(start 290.301934 -318.668908)
		(end 290.301934 -318.248284)
		(width 0.12954)
		(layer "B.Cu")
		(net "PWRGD_CHB_CPU0_DIMM1")
	)
	(segment
		(start 289.250882 -319.716658)
		(end 289.73272 -319.23482)
		(width 0.12954)
		(layer "B.Cu")
		(net "PWRGD_CHB_CPU0_DIMM1")
	)
	(segment
		(start 290.301934 -318.694308)
		(end 290.301934 -318.668908)
		(width 0.12954)
		(layer "B.Cu")
		(net "PWRGD_CHB_CPU0_DIMM1")
	)
	(segment
		(start 290.301934 -318.248284)
		(end 290.135056 -318.081406)
		(width 0.12954)
		(layer "B.Cu")
		(net "PWRGD_CHB_CPU0_DIMM1")
	)
	(segment
		(start 290.135056 -318.081406)
		(end 290.135056 -316.650116)
		(width 0.12954)
		(layer "B.Cu")
		(net "PWRGD_CHB_CPU0_DIMM1")
	)
	(segment
		(start 289.761422 -319.23482)
		(end 290.301934 -318.694308)
		(width 0.12954)
		(layer "B.Cu")
		(net "PWRGD_CHB_CPU0_DIMM1")
	)
	(segment
		(start 63.618618 -319.83045)
		(end 63.816738 -320.02857)
		(width 0.12954)
		(layer "F.Cu")
		(net "PWRGD_CHA_CPU1_DIMM2")
	)
	(segment
		(start 63.816738 -320.02857)
		(end 64.174878 -320.02857)
		(width 0.12954)
		(layer "F.Cu")
		(net "PWRGD_CHA_CPU1_DIMM2")
	)
	(segment
		(start 64.48679 -319.716658)
		(end 65.047114 -319.716658)
		(width 0.12954)
		(layer "F.Cu")
		(net "PWRGD_CHA_CPU1_DIMM2")
	)
	(segment
		(start 64.174878 -320.02857)
		(end 64.48679 -319.716658)
		(width 0.12954)
		(layer "F.Cu")
		(net "PWRGD_CHA_CPU1_DIMM2")
	)
	(via
		(at 63.618618 -319.83045)
		(size 0.4572)
		(drill 0.2032)
		(layers "F.Cu" "B.Cu")
		(net "PWRGD_CHA_CPU1_DIMM2")
	)
	(via
		(at 61.02096 -318.150748)
		(size 0.6604)
		(drill 0.3302)
		(layers "F.Cu" "B.Cu")
		(net "PWRGD_CHA_CPU1_DIMM2")
	)
	(segment
		(start 62.58941 -317.96609)
		(end 61.205618 -317.96609)
		(width 0.12954)
		(layer "B.Cu")
		(net "PWRGD_CHA_CPU1_DIMM2")
	)
	(segment
		(start 61.02096 -317.242698)
		(end 61.25464 -317.009018)
		(width 0.12954)
		(layer "B.Cu")
		(net "PWRGD_CHA_CPU1_DIMM2")
	)
	(segment
		(start 61.02096 -318.150748)
		(end 61.02096 -317.242698)
		(width 0.12954)
		(layer "B.Cu")
		(net "PWRGD_CHA_CPU1_DIMM2")
	)
	(segment
		(start 63.613538 -319.82537)
		(end 63.024004 -318.400684)
		(width 0.12954)
		(layer "B.Cu")
		(net "PWRGD_CHA_CPU1_DIMM2")
	)
	(segment
		(start 63.618618 -319.83045)
		(end 63.613538 -319.82537)
		(width 0.12954)
		(layer "B.Cu")
		(net "PWRGD_CHA_CPU1_DIMM2")
	)
	(segment
		(start 61.205618 -317.96609)
		(end 61.02096 -318.150748)
		(width 0.12954)
		(layer "B.Cu")
		(net "PWRGD_CHA_CPU1_DIMM2")
	)
	(segment
		(start 63.024004 -318.400684)
		(end 62.58941 -317.96609)
		(width 0.12954)
		(layer "B.Cu")
		(net "PWRGD_CHA_CPU1_DIMM2")
	)
	(segment
		(start 56.24195 -319.716658)
		(end 57.503314 -319.716658)
		(width 0.12954)
		(layer "F.Cu")
		(net "PWRGD_CHA_CPU1_DIMM1")
	)
	(segment
		(start 55.79364 -320.164968)
		(end 56.24195 -319.716658)
		(width 0.12954)
		(layer "F.Cu")
		(net "PWRGD_CHA_CPU1_DIMM1")
	)
	(via
		(at 55.79364 -320.164968)
		(size 0.4572)
		(drill 0.2032)
		(layers "F.Cu" "B.Cu")
		(net "PWRGD_CHA_CPU1_DIMM1")
	)
	(segment
		(start 56.548528 -319.41008)
		(end 57.029096 -319.41008)
		(width 0.12954)
		(layer "B.Cu")
		(net "PWRGD_CHA_CPU1_DIMM1")
	)
	(segment
		(start 55.79364 -320.164968)
		(end 56.548528 -319.41008)
		(width 0.12954)
		(layer "B.Cu")
		(net "PWRGD_CHA_CPU1_DIMM1")
	)
	(segment
		(start 311.756806 -320.02857)
		(end 312.114946 -320.02857)
		(width 0.12954)
		(layer "F.Cu")
		(net "PWRGD_CHA_CPU0_DIMM2")
	)
	(segment
		(start 312.426858 -319.716658)
		(end 312.987182 -319.716658)
		(width 0.12954)
		(layer "F.Cu")
		(net "PWRGD_CHA_CPU0_DIMM2")
	)
	(segment
		(start 311.632346 -319.523872)
		(end 311.632346 -319.90411)
		(width 0.12954)
		(layer "F.Cu")
		(net "PWRGD_CHA_CPU0_DIMM2")
	)
	(segment
		(start 311.632346 -319.90411)
		(end 311.756806 -320.02857)
		(width 0.12954)
		(layer "F.Cu")
		(net "PWRGD_CHA_CPU0_DIMM2")
	)
	(segment
		(start 312.114946 -320.02857)
		(end 312.426858 -319.716658)
		(width 0.12954)
		(layer "F.Cu")
		(net "PWRGD_CHA_CPU0_DIMM2")
	)
	(via
		(at 311.632346 -319.523872)
		(size 0.4572)
		(drill 0.2032)
		(layers "F.Cu" "B.Cu")
		(net "PWRGD_CHA_CPU0_DIMM2")
	)
	(via
		(at 313.749436 -319.227708)
		(size 0.6604)
		(drill 0.3302)
		(layers "F.Cu" "B.Cu")
		(net "PWRGD_CHA_CPU0_DIMM2")
	)
	(segment
		(start 313.020202 -319.469262)
		(end 312.592974 -319.469262)
		(width 0.12954)
		(layer "B.Cu")
		(net "PWRGD_CHA_CPU0_DIMM2")
	)
	(segment
		(start 311.919874 -319.469262)
		(end 312.592974 -319.469262)
		(width 0.12954)
		(layer "B.Cu")
		(net "PWRGD_CHA_CPU0_DIMM2")
	)
	(segment
		(start 313.749436 -319.227708)
		(end 313.261756 -319.227708)
		(width 0.12954)
		(layer "B.Cu")
		(net "PWRGD_CHA_CPU0_DIMM2")
	)
	(segment
		(start 311.865264 -319.523872)
		(end 311.919874 -319.469262)
		(width 0.12954)
		(layer "B.Cu")
		(net "PWRGD_CHA_CPU0_DIMM2")
	)
	(segment
		(start 311.632346 -319.523872)
		(end 311.865264 -319.523872)
		(width 0.12954)
		(layer "B.Cu")
		(net "PWRGD_CHA_CPU0_DIMM2")
	)
	(segment
		(start 313.261756 -319.227708)
		(end 313.020202 -319.469262)
		(width 0.12954)
		(layer "B.Cu")
		(net "PWRGD_CHA_CPU0_DIMM2")
	)
	(segment
		(start 304.19167 -319.716658)
		(end 305.443382 -319.716658)
		(width 0.12954)
		(layer "F.Cu")
		(net "PWRGD_CHA_CPU0_DIMM1")
	)
	(segment
		(start 303.64938 -320.258948)
		(end 304.19167 -319.716658)
		(width 0.12954)
		(layer "F.Cu")
		(net "PWRGD_CHA_CPU0_DIMM1")
	)
	(segment
		(start 303.64938 -320.751708)
		(end 303.64938 -320.258948)
		(width 0.12954)
		(layer "F.Cu")
		(net "PWRGD_CHA_CPU0_DIMM1")
	)
	(via
		(at 303.64938 -320.751708)
		(size 0.4572)
		(drill 0.2032)
		(layers "F.Cu" "B.Cu")
		(net "PWRGD_CHA_CPU0_DIMM1")
	)
	(segment
		(start 303.64938 -320.241168)
		(end 303.64938 -320.751708)
		(width 0.12954)
		(layer "B.Cu")
		(net "PWRGD_CHA_CPU0_DIMM1")
	)
	(segment
		(start 304.33264 -319.826386)
		(end 304.064162 -319.826386)
		(width 0.12954)
		(layer "B.Cu")
		(net "PWRGD_CHA_CPU0_DIMM1")
	)
	(segment
		(start 304.718466 -319.461896)
		(end 304.69713 -319.461896)
		(width 0.12954)
		(layer "B.Cu")
		(net "PWRGD_CHA_CPU0_DIMM1")
	)
	(segment
		(start 304.064162 -319.826386)
		(end 303.64938 -320.241168)
		(width 0.12954)
		(layer "B.Cu")
		(net "PWRGD_CHA_CPU0_DIMM1")
	)
	(segment
		(start 304.69713 -319.461896)
		(end 304.33264 -319.826386)
		(width 0.12954)
		(layer "B.Cu")
		(net "PWRGD_CHA_CPU0_DIMM1")
	)
	(via
		(at 128.467358 -362.097066)
		(size 0.508)
		(drill 0.254)
		(layers "F.Cu" "B.Cu")
		(net "PVPP_HBM_CPU1_VCC")
	)
	(segment
		(start 119.76862 -359.3211)
		(end 120.16994 -358.91978)
		(width 0.254)
		(layer "F.Cu")
		(net "PVPP_HBM_CPU1_REF")
	)
	(segment
		(start 122.287792 -359.06329)
		(end 121.60123 -359.06329)
		(width 0.254)
		(layer "F.Cu")
		(net "PVPP_HBM_CPU1_REF")
	)
	(segment
		(start 120.090692 -359.643172)
		(end 119.76862 -359.3211)
		(width 0.254)
		(layer "F.Cu")
		(net "PVPP_HBM_CPU1_REF")
	)
	(segment
		(start 120.975374 -359.643172)
		(end 120.090692 -359.643172)
		(width 0.254)
		(layer "F.Cu")
		(net "PVPP_HBM_CPU1_REF")
	)
	(segment
		(start 120.824244 -358.430576)
		(end 121.029984 -358.430576)
		(width 0.254)
		(layer "F.Cu")
		(net "PVPP_HBM_CPU1_REF")
	)
	(segment
		(start 124.314966 -358.460548)
		(end 122.890534 -358.460548)
		(width 0.1778)
		(layer "F.Cu")
		(net "PVPP_HBM_CPU1_REF")
	)
	(segment
		(start 120.33504 -358.91978)
		(end 120.824244 -358.430576)
		(width 0.254)
		(layer "F.Cu")
		(net "PVPP_HBM_CPU1_REF")
	)
	(segment
		(start 121.60123 -359.06329)
		(end 121.029984 -358.492044)
		(width 0.254)
		(layer "F.Cu")
		(net "PVPP_HBM_CPU1_REF")
	)
	(segment
		(start 120.16994 -358.91978)
		(end 120.33504 -358.91978)
		(width 0.254)
		(layer "F.Cu")
		(net "PVPP_HBM_CPU1_REF")
	)
	(segment
		(start 121.029984 -358.492044)
		(end 121.029984 -358.430576)
		(width 0.254)
		(layer "F.Cu")
		(net "PVPP_HBM_CPU1_REF")
	)
	(segment
		(start 122.890534 -358.460548)
		(end 122.287792 -359.06329)
		(width 0.254)
		(layer "F.Cu")
		(net "PVPP_HBM_CPU1_REF")
	)
	(via
		(at 119.76862 -359.3211)
		(size 0.762)
		(drill 0.381)
		(layers "F.Cu" "B.Cu")
		(net "PVPP_HBM_CPU1_REF")
	)
	(segment
		(start 120.066054 -356.71633)
		(end 121.251472 -356.71633)
		(width 0.1778)
		(layer "F.Cu")
		(net "PVPP_HBM_CPU1_FB")
	)
	(segment
		(start 124.314966 -357.660448)
		(end 123.907042 -357.660448)
		(width 0.1778)
		(layer "F.Cu")
		(net "PVPP_HBM_CPU1_FB")
	)
	(segment
		(start 119.02948 -356.714298)
		(end 120.064022 -356.714298)
		(width 0.1778)
		(layer "F.Cu")
		(net "PVPP_HBM_CPU1_FB")
	)
	(segment
		(start 120.064022 -356.714298)
		(end 120.066054 -356.71633)
		(width 0.1778)
		(layer "F.Cu")
		(net "PVPP_HBM_CPU1_FB")
	)
	(segment
		(start 123.225814 -356.97922)
		(end 122.555762 -356.97922)
		(width 0.1778)
		(layer "F.Cu")
		(net "PVPP_HBM_CPU1_FB")
	)
	(segment
		(start 121.251472 -356.71633)
		(end 122.292872 -356.71633)
		(width 0.1778)
		(layer "F.Cu")
		(net "PVPP_HBM_CPU1_FB")
	)
	(segment
		(start 123.907042 -357.660448)
		(end 123.225814 -356.97922)
		(width 0.1778)
		(layer "F.Cu")
		(net "PVPP_HBM_CPU1_FB")
	)
	(segment
		(start 122.555762 -356.97922)
		(end 122.292872 -356.71633)
		(width 0.1778)
		(layer "F.Cu")
		(net "PVPP_HBM_CPU1_FB")
	)
	(via
		(at 123.225814 -356.97922)
		(size 0.508)
		(drill 0.254)
		(layers "F.Cu" "B.Cu")
		(net "PVPP_HBM_CPU1_FB")
	)
	(segment
		(start 122.613674 -359.704386)
		(end 122.821954 -359.496106)
		(width 0.254)
		(layer "F.Cu")
		(net "PVPP_HBM_CPU1_CS")
	)
	(segment
		(start 122.821954 -359.496106)
		(end 123.010676 -359.496106)
		(width 0.254)
		(layer "F.Cu")
		(net "PVPP_HBM_CPU1_CS")
	)
	(segment
		(start 121.984008 -359.643172)
		(end 122.045222 -359.704386)
		(width 0.254)
		(layer "F.Cu")
		(net "PVPP_HBM_CPU1_CS")
	)
	(segment
		(start 123.182634 -359.496106)
		(end 123.010676 -359.496106)
		(width 0.1778)
		(layer "F.Cu")
		(net "PVPP_HBM_CPU1_CS")
	)
	(segment
		(start 122.045222 -359.704386)
		(end 122.613674 -359.704386)
		(width 0.254)
		(layer "F.Cu")
		(net "PVPP_HBM_CPU1_CS")
	)
	(segment
		(start 123.762262 -359.260648)
		(end 123.182634 -359.496106)
		(width 0.1778)
		(layer "F.Cu")
		(net "PVPP_HBM_CPU1_CS")
	)
	(segment
		(start 124.314966 -359.260648)
		(end 123.762262 -359.260648)
		(width 0.1778)
		(layer "F.Cu")
		(net "PVPP_HBM_CPU1_CS")
	)
	(via
		(at 123.010676 -359.496106)
		(size 0.4064)
		(drill 0.2032)
		(layers "F.Cu" "B.Cu")
		(net "PVPP_HBM_CPU1_CS")
	)
	(segment
		(start 115.979448 -270.475456)
		(end 115.979448 -271.011142)
		(width 0.254)
		(layer "F.Cu")
		(net "PVPP_HBM_CPU1")
	)
	(segment
		(start 115.039648 -271.011142)
		(end 115.039394 -271.011396)
		(width 0.254)
		(layer "F.Cu")
		(net "PVPP_HBM_CPU1")
	)
	(segment
		(start 114.099848 -270.475456)
		(end 114.099848 -271.011142)
		(width 0.254)
		(layer "F.Cu")
		(net "PVPP_HBM_CPU1")
	)
	(segment
		(start 114.569494 -269.66164)
		(end 114.569494 -270.19758)
		(width 0.254)
		(layer "F.Cu")
		(net "PVPP_HBM_CPU1")
	)
	(segment
		(start 115.509294 -269.66164)
		(end 115.509294 -270.19758)
		(width 0.254)
		(layer "F.Cu")
		(net "PVPP_HBM_CPU1")
	)
	(segment
		(start 115.039648 -270.475456)
		(end 115.039648 -271.011142)
		(width 0.254)
		(layer "F.Cu")
		(net "PVPP_HBM_CPU1")
	)
	(segment
		(start 114.099848 -271.011142)
		(end 114.099594 -271.011396)
		(width 0.254)
		(layer "F.Cu")
		(net "PVPP_HBM_CPU1")
	)
	(segment
		(start 115.979448 -271.011142)
		(end 115.979194 -271.011396)
		(width 0.254)
		(layer "F.Cu")
		(net "PVPP_HBM_CPU1")
	)
	(via
		(at 126.870206 -368.069114)
		(size 0.508)
		(drill 0.254)
		(layers "F.Cu" "B.Cu")
		(net "PVPP_HBM_CPU1")
	)
	(via
		(at 129.022856 -368.040666)
		(size 0.508)
		(drill 0.254)
		(layers "F.Cu" "B.Cu")
		(net "PVPP_HBM_CPU1")
	)
	(via
		(at 115.979194 -271.011396)
		(size 0.4572)
		(drill 0.2032)
		(layers "F.Cu" "B.Cu")
		(net "PVPP_HBM_CPU1")
	)
	(via
		(at 115.509294 -270.19758)
		(size 0.4572)
		(drill 0.2032)
		(layers "F.Cu" "B.Cu")
		(net "PVPP_HBM_CPU1")
	)
	(via
		(at 116.317268 -262.739886)
		(size 0.4572)
		(drill 0.2032)
		(layers "F.Cu" "B.Cu")
		(net "PVPP_HBM_CPU1")
	)
	(via
		(at 115.039394 -271.011396)
		(size 0.4572)
		(drill 0.2032)
		(layers "F.Cu" "B.Cu")
		(net "PVPP_HBM_CPU1")
	)
	(via
		(at 116.317268 -262.104886)
		(size 0.4572)
		(drill 0.2032)
		(layers "F.Cu" "B.Cu")
		(net "PVPP_HBM_CPU1")
	)
	(via
		(at 124.736606 -368.069114)
		(size 0.508)
		(drill 0.254)
		(layers "F.Cu" "B.Cu")
		(net "PVPP_HBM_CPU1")
	)
	(via
		(at 124.736606 -367.307114)
		(size 0.508)
		(drill 0.254)
		(layers "F.Cu" "B.Cu")
		(net "PVPP_HBM_CPU1")
	)
	(via
		(at 152.8826 -274.234148)
		(size 0.6604)
		(drill 0.3302)
		(layers "F.Cu" "B.Cu")
		(net "PVPP_HBM_CPU1")
	)
	(via
		(at 117.670834 -263.415526)
		(size 0.4572)
		(drill 0.2032)
		(layers "F.Cu" "B.Cu")
		(net "PVPP_HBM_CPU1")
	)
	(via
		(at 114.099594 -271.011396)
		(size 0.4572)
		(drill 0.2032)
		(layers "F.Cu" "B.Cu")
		(net "PVPP_HBM_CPU1")
	)
	(via
		(at 114.569494 -270.19758)
		(size 0.4572)
		(drill 0.2032)
		(layers "F.Cu" "B.Cu")
		(net "PVPP_HBM_CPU1")
	)
	(via
		(at 126.870206 -367.307114)
		(size 0.508)
		(drill 0.254)
		(layers "F.Cu" "B.Cu")
		(net "PVPP_HBM_CPU1")
	)
	(via
		(at 116.502434 -263.415526)
		(size 0.4572)
		(drill 0.2032)
		(layers "F.Cu" "B.Cu")
		(net "PVPP_HBM_CPU1")
	)
	(via
		(at 117.086634 -263.415526)
		(size 0.4572)
		(drill 0.2032)
		(layers "F.Cu" "B.Cu")
		(net "PVPP_HBM_CPU1")
	)
	(via
		(at 121.526046 -367.832132)
		(size 0.508)
		(drill 0.254)
		(layers "F.Cu" "B.Cu")
		(net "PVPP_HBM_CPU1")
	)
	(via
		(at 122.588782 -368.069114)
		(size 0.508)
		(drill 0.254)
		(layers "F.Cu" "B.Cu")
		(net "PVPP_HBM_CPU1")
	)
	(via
		(at 122.588782 -367.307114)
		(size 0.508)
		(drill 0.254)
		(layers "F.Cu" "B.Cu")
		(net "PVPP_HBM_CPU1")
	)
	(via
		(at 129.022856 -367.278666)
		(size 0.508)
		(drill 0.254)
		(layers "F.Cu" "B.Cu")
		(net "PVPP_HBM_CPU1")
	)
	(via
		(at 121.45772 -369.542568)
		(size 0.762)
		(drill 0.381)
		(layers "F.Cu" "B.Cu")
		(net "PVPP_HBM_CPU1")
	)
	(segment
		(start 137.219944 -270.995902)
		(end 137.219944 -271.011396)
		(width 0.0889)
		(layer "B.Cu")
		(net "PVPP_HBM_CPU1")
	)
	(segment
		(start 128.853946 -270.521938)
		(end 128.868678 -270.513302)
		(width 0.0889)
		(layer "B.Cu")
		(net "PVPP_HBM_CPU1")
	)
	(segment
		(start 161.57448 -381.643128)
		(end 121.75998 -381.643128)
		(width 0.381)
		(layer "B.Cu")
		(net "PVPP_HBM_CPU1")
	)
	(segment
		(start 154.73426 -272.273268)
		(end 155.66898 -273.207988)
		(width 0.381)
		(layer "B.Cu")
		(net "PVPP_HBM_CPU1")
	)
	(segment
		(start 121.75998 -381.643128)
		(end 119.8499 -379.733048)
		(width 0.381)
		(layer "B.Cu")
		(net "PVPP_HBM_CPU1")
	)
	(segment
		(start 119.8499 -379.733048)
		(end 119.8499 -368.018568)
		(width 0.381)
		(layer "B.Cu")
		(net "PVPP_HBM_CPU1")
	)
	(segment
		(start 157.38602 -334.894428)
		(end 160.9471 -334.894428)
		(width 0.381)
		(layer "B.Cu")
		(net "PVPP_HBM_CPU1")
	)
	(segment
		(start 118.516146 -270.521938)
		(end 118.530878 -270.513302)
		(width 0.0889)
		(layer "B.Cu")
		(net "PVPP_HBM_CPU1")
	)
	(segment
		(start 119.52478 -361.528868)
		(end 120.01754 -361.528868)
		(width 0.381)
		(layer "B.Cu")
		(net "PVPP_HBM_CPU1")
	)
	(segment
		(start 129.793746 -270.521938)
		(end 129.808478 -270.513302)
		(width 0.0889)
		(layer "B.Cu")
		(net "PVPP_HBM_CPU1")
	)
	(segment
		(start 115.979194 -271.011396)
		(end 116.64696 -270.515842)
		(width 0.0889)
		(layer "B.Cu")
		(net "PVPP_HBM_CPU1")
	)
	(segment
		(start 132.613146 -270.521938)
		(end 132.62356 -270.515842)
		(width 0.0889)
		(layer "B.Cu")
		(net "PVPP_HBM_CPU1")
	)
	(segment
		(start 163.3728 -354.404168)
		(end 163.3728 -379.844808)
		(width 0.381)
		(layer "B.Cu")
		(net "PVPP_HBM_CPU1")
	)
	(segment
		(start 121.335546 -270.521938)
		(end 121.350278 -270.513302)
		(width 0.0889)
		(layer "B.Cu")
		(net "PVPP_HBM_CPU1")
	)
	(segment
		(start 135.432546 -270.521938)
		(end 135.447278 -270.513302)
		(width 0.0889)
		(layer "B.Cu")
		(net "PVPP_HBM_CPU1")
	)
	(segment
		(start 139.373864 -271.259808)
		(end 139.531344 -271.102328)
		(width 0.0889)
		(layer "B.Cu")
		(net "PVPP_HBM_CPU1")
	)
	(segment
		(start 126.974346 -270.521938)
		(end 126.989078 -270.513302)
		(width 0.0889)
		(layer "B.Cu")
		(net "PVPP_HBM_CPU1")
	)
	(segment
		(start 120.458484 -361.087924)
		(end 120.458484 -360.345736)
		(width 0.381)
		(layer "B.Cu")
		(net "PVPP_HBM_CPU1")
	)
	(segment
		(start 134.492746 -270.521938)
		(end 134.507478 -270.513302)
		(width 0.0889)
		(layer "B.Cu")
		(net "PVPP_HBM_CPU1")
	)
	(segment
		(start 151.765 -271.102328)
		(end 152.93594 -272.273268)
		(width 0.381)
		(layer "B.Cu")
		(net "PVPP_HBM_CPU1")
	)
	(segment
		(start 120.395746 -270.521938)
		(end 120.410478 -270.513302)
		(width 0.0889)
		(layer "B.Cu")
		(net "PVPP_HBM_CPU1")
	)
	(segment
		(start 138.332464 -271.327118)
		(end 138.347196 -271.335754)
		(width 0.0889)
		(layer "B.Cu")
		(net "PVPP_HBM_CPU1")
	)
	(segment
		(start 130.733546 -270.521938)
		(end 130.748278 -270.513302)
		(width 0.0889)
		(layer "B.Cu")
		(net "PVPP_HBM_CPU1")
	)
	(segment
		(start 125.094746 -270.521938)
		(end 125.109478 -270.513302)
		(width 0.0889)
		(layer "B.Cu")
		(net "PVPP_HBM_CPU1")
	)
	(segment
		(start 131.673346 -270.521938)
		(end 131.688078 -270.513302)
		(width 0.0889)
		(layer "B.Cu")
		(net "PVPP_HBM_CPU1")
	)
	(segment
		(start 137.398506 -271.330674)
		(end 137.407396 -271.335754)
		(width 0.0889)
		(layer "B.Cu")
		(net "PVPP_HBM_CPU1")
	)
	(segment
		(start 160.9471 -334.894428)
		(end 162.10026 -336.047588)
		(width 0.381)
		(layer "B.Cu")
		(net "PVPP_HBM_CPU1")
	)
	(segment
		(start 123.215146 -270.521938)
		(end 123.229878 -270.513302)
		(width 0.0889)
		(layer "B.Cu")
		(net "PVPP_HBM_CPU1")
	)
	(segment
		(start 118.44274 -362.610908)
		(end 119.52478 -361.528868)
		(width 0.381)
		(layer "B.Cu")
		(net "PVPP_HBM_CPU1")
	)
	(segment
		(start 162.10026 -336.047588)
		(end 162.10026 -353.131628)
		(width 0.381)
		(layer "B.Cu")
		(net "PVPP_HBM_CPU1")
	)
	(segment
		(start 120.01754 -361.528868)
		(end 120.458484 -361.087924)
		(width 0.381)
		(layer "B.Cu")
		(net "PVPP_HBM_CPU1")
	)
	(segment
		(start 126.034546 -270.521938)
		(end 126.049278 -270.513302)
		(width 0.0889)
		(layer "B.Cu")
		(net "PVPP_HBM_CPU1")
	)
	(segment
		(start 119.455946 -270.521938)
		(end 119.470678 -270.513302)
		(width 0.0889)
		(layer "B.Cu")
		(net "PVPP_HBM_CPU1")
	)
	(segment
		(start 162.10026 -353.131628)
		(end 163.3728 -354.404168)
		(width 0.381)
		(layer "B.Cu")
		(net "PVPP_HBM_CPU1")
	)
	(segment
		(start 127.914146 -270.521938)
		(end 127.928878 -270.513302)
		(width 0.0889)
		(layer "B.Cu")
		(net "PVPP_HBM_CPU1")
	)
	(segment
		(start 136.372346 -270.521938)
		(end 136.387078 -270.513302)
		(width 0.0889)
		(layer "B.Cu")
		(net "PVPP_HBM_CPU1")
	)
	(segment
		(start 155.66898 -273.207988)
		(end 155.66898 -333.177388)
		(width 0.381)
		(layer "B.Cu")
		(net "PVPP_HBM_CPU1")
	)
	(segment
		(start 133.552692 -270.521938)
		(end 133.563106 -270.515842)
		(width 0.0889)
		(layer "B.Cu")
		(net "PVPP_HBM_CPU1")
	)
	(segment
		(start 118.44274 -366.611408)
		(end 118.44274 -362.610908)
		(width 0.381)
		(layer "B.Cu")
		(net "PVPP_HBM_CPU1")
	)
	(segment
		(start 124.154946 -270.521938)
		(end 124.169678 -270.513302)
		(width 0.0889)
		(layer "B.Cu")
		(net "PVPP_HBM_CPU1")
	)
	(segment
		(start 118.515892 -270.521938)
		(end 118.516146 -270.521938)
		(width 0.0889)
		(layer "B.Cu")
		(net "PVPP_HBM_CPU1")
	)
	(segment
		(start 155.66898 -333.177388)
		(end 157.38602 -334.894428)
		(width 0.381)
		(layer "B.Cu")
		(net "PVPP_HBM_CPU1")
	)
	(segment
		(start 139.004548 -271.259808)
		(end 139.373864 -271.259808)
		(width 0.0889)
		(layer "B.Cu")
		(net "PVPP_HBM_CPU1")
	)
	(segment
		(start 163.3728 -379.844808)
		(end 161.57448 -381.643128)
		(width 0.381)
		(layer "B.Cu")
		(net "PVPP_HBM_CPU1")
	)
	(segment
		(start 152.93594 -272.273268)
		(end 154.73426 -272.273268)
		(width 0.381)
		(layer "B.Cu")
		(net "PVPP_HBM_CPU1")
	)
	(segment
		(start 139.531344 -271.102328)
		(end 151.765 -271.102328)
		(width 0.381)
		(layer "B.Cu")
		(net "PVPP_HBM_CPU1")
	)
	(segment
		(start 119.8499 -368.018568)
		(end 118.44274 -366.611408)
		(width 0.381)
		(layer "B.Cu")
		(net "PVPP_HBM_CPU1")
	)
	(segment
		(start 117.576092 -270.521938)
		(end 117.586506 -270.515842)
		(width 0.0889)
		(layer "B.Cu")
		(net "PVPP_HBM_CPU1")
	)
	(arc
		(start 124.72035 -270.521938)
		(mid 124.907548 -270.572081)
		(end 125.094746 -270.521938)
		(width 0.0889)
		(layer "B.Cu")
		(net "PVPP_HBM_CPU1")
	)
	(arc
		(start 135.447278 -270.513302)
		(mid 135.723753 -270.445982)
		(end 135.99795 -270.521938)
		(width 0.0889)
		(layer "B.Cu")
		(net "PVPP_HBM_CPU1")
	)
	(arc
		(start 131.688078 -270.513302)
		(mid 131.964553 -270.445982)
		(end 132.23875 -270.521938)
		(width 0.0889)
		(layer "B.Cu")
		(net "PVPP_HBM_CPU1")
	)
	(arc
		(start 138.347196 -271.335754)
		(mid 138.534394 -271.385897)
		(end 138.721592 -271.335754)
		(width 0.0889)
		(layer "B.Cu")
		(net "PVPP_HBM_CPU1")
	)
	(arc
		(start 121.90095 -270.521938)
		(mid 122.088148 -270.572081)
		(end 122.275346 -270.521938)
		(width 0.0889)
		(layer "B.Cu")
		(net "PVPP_HBM_CPU1")
	)
	(arc
		(start 132.62356 -270.515842)
		(mid 132.901738 -270.446119)
		(end 133.178296 -270.521938)
		(width 0.0889)
		(layer "B.Cu")
		(net "PVPP_HBM_CPU1")
	)
	(arc
		(start 130.35915 -270.521938)
		(mid 130.546348 -270.572081)
		(end 130.733546 -270.521938)
		(width 0.0889)
		(layer "B.Cu")
		(net "PVPP_HBM_CPU1")
	)
	(arc
		(start 129.41935 -270.521938)
		(mid 129.606548 -270.572081)
		(end 129.793746 -270.521938)
		(width 0.0889)
		(layer "B.Cu")
		(net "PVPP_HBM_CPU1")
	)
	(arc
		(start 137.781792 -271.335754)
		(mid 138.055991 -271.259919)
		(end 138.332464 -271.327118)
		(width 0.0889)
		(layer "B.Cu")
		(net "PVPP_HBM_CPU1")
	)
	(arc
		(start 122.275346 -270.521938)
		(mid 122.558048 -270.446162)
		(end 122.84075 -270.521938)
		(width 0.0889)
		(layer "B.Cu")
		(net "PVPP_HBM_CPU1")
	)
	(arc
		(start 135.05815 -270.521938)
		(mid 135.245348 -270.572081)
		(end 135.432546 -270.521938)
		(width 0.0889)
		(layer "B.Cu")
		(net "PVPP_HBM_CPU1")
	)
	(arc
		(start 120.02135 -270.521938)
		(mid 120.208548 -270.572081)
		(end 120.395746 -270.521938)
		(width 0.0889)
		(layer "B.Cu")
		(net "PVPP_HBM_CPU1")
	)
	(arc
		(start 134.11835 -270.521938)
		(mid 134.305548 -270.572081)
		(end 134.492746 -270.521938)
		(width 0.0889)
		(layer "B.Cu")
		(net "PVPP_HBM_CPU1")
	)
	(arc
		(start 123.229878 -270.513302)
		(mid 123.506353 -270.445982)
		(end 123.78055 -270.521938)
		(width 0.0889)
		(layer "B.Cu")
		(net "PVPP_HBM_CPU1")
	)
	(arc
		(start 129.808478 -270.513302)
		(mid 130.084953 -270.445982)
		(end 130.35915 -270.521938)
		(width 0.0889)
		(layer "B.Cu")
		(net "PVPP_HBM_CPU1")
	)
	(arc
		(start 125.109478 -270.513302)
		(mid 125.385953 -270.445982)
		(end 125.66015 -270.521938)
		(width 0.0889)
		(layer "B.Cu")
		(net "PVPP_HBM_CPU1")
	)
	(arc
		(start 122.84075 -270.521938)
		(mid 123.027948 -270.572081)
		(end 123.215146 -270.521938)
		(width 0.0889)
		(layer "B.Cu")
		(net "PVPP_HBM_CPU1")
	)
	(arc
		(start 128.47955 -270.521938)
		(mid 128.666748 -270.572081)
		(end 128.853946 -270.521938)
		(width 0.0889)
		(layer "B.Cu")
		(net "PVPP_HBM_CPU1")
	)
	(arc
		(start 136.93775 -270.521938)
		(mid 137.140573 -270.722169)
		(end 137.219944 -270.995902)
		(width 0.0889)
		(layer "B.Cu")
		(net "PVPP_HBM_CPU1")
	)
	(arc
		(start 118.14175 -270.521938)
		(mid 118.328838 -270.572115)
		(end 118.515892 -270.521938)
		(width 0.0889)
		(layer "B.Cu")
		(net "PVPP_HBM_CPU1")
	)
	(arc
		(start 134.507478 -270.513302)
		(mid 134.783953 -270.445982)
		(end 135.05815 -270.521938)
		(width 0.0889)
		(layer "B.Cu")
		(net "PVPP_HBM_CPU1")
	)
	(arc
		(start 131.29895 -270.521938)
		(mid 131.486148 -270.572081)
		(end 131.673346 -270.521938)
		(width 0.0889)
		(layer "B.Cu")
		(net "PVPP_HBM_CPU1")
	)
	(arc
		(start 126.049278 -270.513302)
		(mid 126.325753 -270.445982)
		(end 126.59995 -270.521938)
		(width 0.0889)
		(layer "B.Cu")
		(net "PVPP_HBM_CPU1")
	)
	(arc
		(start 130.748278 -270.513302)
		(mid 131.024753 -270.445982)
		(end 131.29895 -270.521938)
		(width 0.0889)
		(layer "B.Cu")
		(net "PVPP_HBM_CPU1")
	)
	(arc
		(start 123.78055 -270.521938)
		(mid 123.967748 -270.572081)
		(end 124.154946 -270.521938)
		(width 0.0889)
		(layer "B.Cu")
		(net "PVPP_HBM_CPU1")
	)
	(arc
		(start 132.23875 -270.521938)
		(mid 132.425948 -270.572081)
		(end 132.613146 -270.521938)
		(width 0.0889)
		(layer "B.Cu")
		(net "PVPP_HBM_CPU1")
	)
	(arc
		(start 126.59995 -270.521938)
		(mid 126.787148 -270.572081)
		(end 126.974346 -270.521938)
		(width 0.0889)
		(layer "B.Cu")
		(net "PVPP_HBM_CPU1")
	)
	(arc
		(start 136.387078 -270.513302)
		(mid 136.663553 -270.445982)
		(end 136.93775 -270.521938)
		(width 0.0889)
		(layer "B.Cu")
		(net "PVPP_HBM_CPU1")
	)
	(arc
		(start 137.407396 -271.335754)
		(mid 137.594594 -271.385897)
		(end 137.781792 -271.335754)
		(width 0.0889)
		(layer "B.Cu")
		(net "PVPP_HBM_CPU1")
	)
	(arc
		(start 121.350278 -270.513302)
		(mid 121.626753 -270.445982)
		(end 121.90095 -270.521938)
		(width 0.0889)
		(layer "B.Cu")
		(net "PVPP_HBM_CPU1")
	)
	(arc
		(start 135.99795 -270.521938)
		(mid 136.185148 -270.572081)
		(end 136.372346 -270.521938)
		(width 0.0889)
		(layer "B.Cu")
		(net "PVPP_HBM_CPU1")
	)
	(arc
		(start 127.928878 -270.513302)
		(mid 128.205353 -270.445982)
		(end 128.47955 -270.521938)
		(width 0.0889)
		(layer "B.Cu")
		(net "PVPP_HBM_CPU1")
	)
	(arc
		(start 119.08155 -270.521938)
		(mid 119.268748 -270.572081)
		(end 119.455946 -270.521938)
		(width 0.0889)
		(layer "B.Cu")
		(net "PVPP_HBM_CPU1")
	)
	(arc
		(start 124.169678 -270.513302)
		(mid 124.446153 -270.445982)
		(end 124.72035 -270.521938)
		(width 0.0889)
		(layer "B.Cu")
		(net "PVPP_HBM_CPU1")
	)
	(arc
		(start 119.470678 -270.513302)
		(mid 119.747153 -270.445982)
		(end 120.02135 -270.521938)
		(width 0.0889)
		(layer "B.Cu")
		(net "PVPP_HBM_CPU1")
	)
	(arc
		(start 133.563106 -270.515842)
		(mid 133.841538 -270.445996)
		(end 134.11835 -270.521938)
		(width 0.0889)
		(layer "B.Cu")
		(net "PVPP_HBM_CPU1")
	)
	(arc
		(start 127.53975 -270.521938)
		(mid 127.726948 -270.572081)
		(end 127.914146 -270.521938)
		(width 0.0889)
		(layer "B.Cu")
		(net "PVPP_HBM_CPU1")
	)
	(arc
		(start 117.586506 -270.515842)
		(mid 117.864938 -270.445996)
		(end 118.14175 -270.521938)
		(width 0.0889)
		(layer "B.Cu")
		(net "PVPP_HBM_CPU1")
	)
	(arc
		(start 125.66015 -270.521938)
		(mid 125.847348 -270.572081)
		(end 126.034546 -270.521938)
		(width 0.0889)
		(layer "B.Cu")
		(net "PVPP_HBM_CPU1")
	)
	(arc
		(start 133.178296 -270.521938)
		(mid 133.365494 -270.572081)
		(end 133.552692 -270.521938)
		(width 0.0889)
		(layer "B.Cu")
		(net "PVPP_HBM_CPU1")
	)
	(arc
		(start 120.96115 -270.521938)
		(mid 121.148348 -270.572081)
		(end 121.335546 -270.521938)
		(width 0.0889)
		(layer "B.Cu")
		(net "PVPP_HBM_CPU1")
	)
	(arc
		(start 126.989078 -270.513302)
		(mid 127.265553 -270.445982)
		(end 127.53975 -270.521938)
		(width 0.0889)
		(layer "B.Cu")
		(net "PVPP_HBM_CPU1")
	)
	(arc
		(start 117.201696 -270.521938)
		(mid 117.388894 -270.572081)
		(end 117.576092 -270.521938)
		(width 0.0889)
		(layer "B.Cu")
		(net "PVPP_HBM_CPU1")
	)
	(arc
		(start 118.530878 -270.513302)
		(mid 118.807353 -270.445982)
		(end 119.08155 -270.521938)
		(width 0.0889)
		(layer "B.Cu")
		(net "PVPP_HBM_CPU1")
	)
	(arc
		(start 138.721592 -271.335754)
		(mid 138.858064 -271.279131)
		(end 139.004548 -271.259808)
		(width 0.0889)
		(layer "B.Cu")
		(net "PVPP_HBM_CPU1")
	)
	(arc
		(start 116.64696 -270.515842)
		(mid 116.925138 -270.446119)
		(end 117.201696 -270.521938)
		(width 0.0889)
		(layer "B.Cu")
		(net "PVPP_HBM_CPU1")
	)
	(arc
		(start 128.868678 -270.513302)
		(mid 129.145153 -270.445982)
		(end 129.41935 -270.521938)
		(width 0.0889)
		(layer "B.Cu")
		(net "PVPP_HBM_CPU1")
	)
	(arc
		(start 120.410478 -270.513302)
		(mid 120.686953 -270.445982)
		(end 120.96115 -270.521938)
		(width 0.0889)
		(layer "B.Cu")
		(net "PVPP_HBM_CPU1")
	)
	(arc
		(start 137.219944 -271.011396)
		(mid 137.267623 -271.194296)
		(end 137.398506 -271.330674)
		(width 0.0889)
		(layer "B.Cu")
		(net "PVPP_HBM_CPU1")
	)
	(segment
		(start 115.171728 -271.371568)
		(end 115.195858 -271.282414)
		(width 0.0889)
		(layer "In11.Cu")
		(net "PVPP_HBM_CPU1")
	)
	(segment
		(start 115.195858 -271.282414)
		(end 115.039394 -271.011396)
		(width 0.0889)
		(layer "In11.Cu")
		(net "PVPP_HBM_CPU1")
	)
	(via
		(at 376.407172 -362.097066)
		(size 0.508)
		(drill 0.254)
		(layers "F.Cu" "B.Cu")
		(net "PVPP_HBM_CPU0_VCC")
	)
	(segment
		(start 367.727992 -359.803192)
		(end 367.694718 -359.769918)
		(width 0.254)
		(layer "F.Cu")
		(net "PVPP_HBM_CPU0_REF")
	)
	(segment
		(start 369.39601 -359.024428)
		(end 368.969798 -358.598216)
		(width 0.254)
		(layer "F.Cu")
		(net "PVPP_HBM_CPU0_REF")
	)
	(segment
		(start 368.755168 -359.803192)
		(end 367.727992 -359.803192)
		(width 0.254)
		(layer "F.Cu")
		(net "PVPP_HBM_CPU0_REF")
	)
	(segment
		(start 368.915188 -359.643172)
		(end 368.755168 -359.803192)
		(width 0.254)
		(layer "F.Cu")
		(net "PVPP_HBM_CPU0_REF")
	)
	(segment
		(start 372.25478 -358.460548)
		(end 370.882164 -358.460548)
		(width 0.1778)
		(layer "F.Cu")
		(net "PVPP_HBM_CPU0_REF")
	)
	(segment
		(start 368.969798 -358.598216)
		(end 368.969798 -358.494838)
		(width 0.254)
		(layer "F.Cu")
		(net "PVPP_HBM_CPU0_REF")
	)
	(segment
		(start 370.882164 -358.460548)
		(end 370.830348 -358.460548)
		(width 0.254)
		(layer "F.Cu")
		(net "PVPP_HBM_CPU0_REF")
	)
	(segment
		(start 370.830348 -358.460548)
		(end 370.266468 -359.024428)
		(width 0.254)
		(layer "F.Cu")
		(net "PVPP_HBM_CPU0_REF")
	)
	(segment
		(start 370.266468 -359.024428)
		(end 369.39601 -359.024428)
		(width 0.254)
		(layer "F.Cu")
		(net "PVPP_HBM_CPU0_REF")
	)
	(segment
		(start 367.694718 -359.769918)
		(end 368.969798 -358.494838)
		(width 0.254)
		(layer "F.Cu")
		(net "PVPP_HBM_CPU0_REF")
	)
	(segment
		(start 368.969798 -358.494838)
		(end 368.969798 -358.430576)
		(width 0.254)
		(layer "F.Cu")
		(net "PVPP_HBM_CPU0_REF")
	)
	(via
		(at 367.694718 -359.769918)
		(size 0.762)
		(drill 0.381)
		(layers "F.Cu" "B.Cu")
		(net "PVPP_HBM_CPU0_REF")
	)
	(segment
		(start 368.2619 -356.71633)
		(end 368.005868 -356.71633)
		(width 0.254)
		(layer "F.Cu")
		(net "PVPP_HBM_CPU0_FB")
	)
	(segment
		(start 370.232686 -356.72649)
		(end 370.232686 -356.71633)
		(width 0.254)
		(layer "F.Cu")
		(net "PVPP_HBM_CPU0_FB")
	)
	(segment
		(start 369.191286 -356.71633)
		(end 368.946684 -356.71633)
		(width 0.254)
		(layer "F.Cu")
		(net "PVPP_HBM_CPU0_FB")
	)
	(segment
		(start 368.604292 -356.373938)
		(end 368.2619 -356.71633)
		(width 0.254)
		(layer "F.Cu")
		(net "PVPP_HBM_CPU0_FB")
	)
	(segment
		(start 369.191286 -356.71633)
		(end 370.232686 -356.71633)
		(width 0.254)
		(layer "F.Cu")
		(net "PVPP_HBM_CPU0_FB")
	)
	(segment
		(start 372.25478 -357.660448)
		(end 371.798596 -357.660448)
		(width 0.1778)
		(layer "F.Cu")
		(net "PVPP_HBM_CPU0_FB")
	)
	(segment
		(start 368.946684 -356.71633)
		(end 368.604292 -356.373938)
		(width 0.254)
		(layer "F.Cu")
		(net "PVPP_HBM_CPU0_FB")
	)
	(segment
		(start 371.798596 -357.660448)
		(end 371.118638 -356.98049)
		(width 0.254)
		(layer "F.Cu")
		(net "PVPP_HBM_CPU0_FB")
	)
	(segment
		(start 371.118638 -356.98049)
		(end 370.486686 -356.98049)
		(width 0.254)
		(layer "F.Cu")
		(net "PVPP_HBM_CPU0_FB")
	)
	(segment
		(start 366.95888 -356.714298)
		(end 366.960912 -356.71633)
		(width 0.254)
		(layer "F.Cu")
		(net "PVPP_HBM_CPU0_FB")
	)
	(segment
		(start 370.486686 -356.98049)
		(end 370.232686 -356.72649)
		(width 0.254)
		(layer "F.Cu")
		(net "PVPP_HBM_CPU0_FB")
	)
	(segment
		(start 366.960912 -356.71633)
		(end 368.005868 -356.71633)
		(width 0.254)
		(layer "F.Cu")
		(net "PVPP_HBM_CPU0_FB")
	)
	(via
		(at 368.604292 -356.373938)
		(size 0.508)
		(drill 0.254)
		(layers "F.Cu" "B.Cu")
		(net "PVPP_HBM_CPU0_FB")
	)
	(segment
		(start 370.614702 -359.643172)
		(end 369.923822 -359.643172)
		(width 0.254)
		(layer "F.Cu")
		(net "PVPP_HBM_CPU0_CS")
	)
	(segment
		(start 371.225826 -359.494582)
		(end 371.044216 -359.494582)
		(width 0.1778)
		(layer "F.Cu")
		(net "PVPP_HBM_CPU0_CS")
	)
	(segment
		(start 370.763292 -359.494582)
		(end 370.614702 -359.643172)
		(width 0.254)
		(layer "F.Cu")
		(net "PVPP_HBM_CPU0_CS")
	)
	(segment
		(start 371.58295 -359.260648)
		(end 371.225826 -359.494582)
		(width 0.1778)
		(layer "F.Cu")
		(net "PVPP_HBM_CPU0_CS")
	)
	(segment
		(start 371.044216 -359.494582)
		(end 370.763292 -359.494582)
		(width 0.254)
		(layer "F.Cu")
		(net "PVPP_HBM_CPU0_CS")
	)
	(segment
		(start 372.25478 -359.260648)
		(end 371.58295 -359.260648)
		(width 0.1778)
		(layer "F.Cu")
		(net "PVPP_HBM_CPU0_CS")
	)
	(via
		(at 371.044216 -359.494582)
		(size 0.4064)
		(drill 0.2032)
		(layers "F.Cu" "B.Cu")
		(net "PVPP_HBM_CPU0_CS")
	)
	(segment
		(start 363.449362 -269.66164)
		(end 363.449362 -270.19758)
		(width 0.381)
		(layer "F.Cu")
		(net "PVPP_HBM_CPU0")
	)
	(segment
		(start 362.509562 -269.66164)
		(end 362.509562 -270.19758)
		(width 0.381)
		(layer "F.Cu")
		(net "PVPP_HBM_CPU0")
	)
	(segment
		(start 362.979716 -271.011142)
		(end 362.979462 -271.011396)
		(width 0.381)
		(layer "F.Cu")
		(net "PVPP_HBM_CPU0")
	)
	(segment
		(start 363.919516 -270.475456)
		(end 363.919516 -271.011142)
		(width 0.381)
		(layer "F.Cu")
		(net "PVPP_HBM_CPU0")
	)
	(segment
		(start 362.039916 -270.475456)
		(end 362.039916 -271.011142)
		(width 0.381)
		(layer "F.Cu")
		(net "PVPP_HBM_CPU0")
	)
	(segment
		(start 362.039916 -271.011142)
		(end 362.039662 -271.011396)
		(width 0.381)
		(layer "F.Cu")
		(net "PVPP_HBM_CPU0")
	)
	(segment
		(start 363.919516 -271.011142)
		(end 363.919262 -271.011396)
		(width 0.381)
		(layer "F.Cu")
		(net "PVPP_HBM_CPU0")
	)
	(segment
		(start 362.979716 -270.475456)
		(end 362.979716 -271.011142)
		(width 0.381)
		(layer "F.Cu")
		(net "PVPP_HBM_CPU0")
	)
	(via
		(at 362.979462 -271.011396)
		(size 0.4572)
		(drill 0.2032)
		(layers "F.Cu" "B.Cu")
		(net "PVPP_HBM_CPU0")
	)
	(via
		(at 377.048268 -367.933478)
		(size 0.508)
		(drill 0.254)
		(layers "F.Cu" "B.Cu")
		(net "PVPP_HBM_CPU0")
	)
	(via
		(at 362.039662 -271.011396)
		(size 0.4572)
		(drill 0.2032)
		(layers "F.Cu" "B.Cu")
		(net "PVPP_HBM_CPU0")
	)
	(via
		(at 400.49196 -274.386548)
		(size 0.6604)
		(drill 0.3302)
		(layers "F.Cu" "B.Cu")
		(net "PVPP_HBM_CPU0")
	)
	(via
		(at 372.762018 -367.961926)
		(size 0.508)
		(drill 0.254)
		(layers "F.Cu" "B.Cu")
		(net "PVPP_HBM_CPU0")
	)
	(via
		(at 370.614194 -367.961926)
		(size 0.508)
		(drill 0.254)
		(layers "F.Cu" "B.Cu")
		(net "PVPP_HBM_CPU0")
	)
	(via
		(at 365.610902 -263.415526)
		(size 0.4572)
		(drill 0.2032)
		(layers "F.Cu" "B.Cu")
		(net "PVPP_HBM_CPU0")
	)
	(via
		(at 362.509562 -270.19758)
		(size 0.4572)
		(drill 0.2032)
		(layers "F.Cu" "B.Cu")
		(net "PVPP_HBM_CPU0")
	)
	(via
		(at 364.257082 -262.104632)
		(size 0.4572)
		(drill 0.2032)
		(layers "F.Cu" "B.Cu")
		(net "PVPP_HBM_CPU0")
	)
	(via
		(at 364.442502 -263.415526)
		(size 0.4572)
		(drill 0.2032)
		(layers "F.Cu" "B.Cu")
		(net "PVPP_HBM_CPU0")
	)
	(via
		(at 370.614194 -367.199926)
		(size 0.508)
		(drill 0.254)
		(layers "F.Cu" "B.Cu")
		(net "PVPP_HBM_CPU0")
	)
	(via
		(at 369.571524 -367.776252)
		(size 0.508)
		(drill 0.254)
		(layers "F.Cu" "B.Cu")
		(net "PVPP_HBM_CPU0")
	)
	(via
		(at 373.503698 -371.59311)
		(size 0.6604)
		(drill 0.3302)
		(layers "F.Cu" "B.Cu")
		(net "PVPP_HBM_CPU0")
	)
	(via
		(at 374.895618 -367.199926)
		(size 0.508)
		(drill 0.254)
		(layers "F.Cu" "B.Cu")
		(net "PVPP_HBM_CPU0")
	)
	(via
		(at 363.449362 -270.19758)
		(size 0.4572)
		(drill 0.2032)
		(layers "F.Cu" "B.Cu")
		(net "PVPP_HBM_CPU0")
	)
	(via
		(at 372.762018 -367.199926)
		(size 0.508)
		(drill 0.254)
		(layers "F.Cu" "B.Cu")
		(net "PVPP_HBM_CPU0")
	)
	(via
		(at 363.919262 -271.011396)
		(size 0.4572)
		(drill 0.2032)
		(layers "F.Cu" "B.Cu")
		(net "PVPP_HBM_CPU0")
	)
	(via
		(at 364.257082 -262.739632)
		(size 0.4572)
		(drill 0.2032)
		(layers "F.Cu" "B.Cu")
		(net "PVPP_HBM_CPU0")
	)
	(via
		(at 365.026702 -263.415526)
		(size 0.4572)
		(drill 0.2032)
		(layers "F.Cu" "B.Cu")
		(net "PVPP_HBM_CPU0")
	)
	(via
		(at 374.895618 -367.961926)
		(size 0.508)
		(drill 0.254)
		(layers "F.Cu" "B.Cu")
		(net "PVPP_HBM_CPU0")
	)
	(via
		(at 377.048268 -367.171478)
		(size 0.508)
		(drill 0.254)
		(layers "F.Cu" "B.Cu")
		(net "PVPP_HBM_CPU0")
	)
	(segment
		(start 368.335814 -270.521938)
		(end 368.350546 -270.513302)
		(width 0.0889)
		(layer "B.Cu")
		(net "PVPP_HBM_CPU0")
	)
	(segment
		(start 369.34648 -382.808988)
		(end 367.37798 -380.840488)
		(width 0.381)
		(layer "B.Cu")
		(net "PVPP_HBM_CPU0")
	)
	(segment
		(start 380.553214 -270.521938)
		(end 380.563628 -270.515842)
		(width 0.0889)
		(layer "B.Cu")
		(net "PVPP_HBM_CPU0")
	)
	(segment
		(start 368.398552 -360.759248)
		(end 368.398298 -360.758994)
		(width 0.381)
		(layer "B.Cu")
		(net "PVPP_HBM_CPU0")
	)
	(segment
		(start 364.473998 -270.582136)
		(end 364.587028 -270.515842)
		(width 0.0889)
		(layer "B.Cu")
		(net "PVPP_HBM_CPU0")
	)
	(segment
		(start 369.275614 -270.521938)
		(end 369.290346 -270.513302)
		(width 0.0889)
		(layer "B.Cu")
		(net "PVPP_HBM_CPU0")
	)
	(segment
		(start 386.272532 -271.327118)
		(end 386.287264 -271.335754)
		(width 0.0889)
		(layer "B.Cu")
		(net "PVPP_HBM_CPU0")
	)
	(segment
		(start 401.066 -272.466308)
		(end 402.87448 -272.466308)
		(width 0.381)
		(layer "B.Cu")
		(net "PVPP_HBM_CPU0")
	)
	(segment
		(start 376.794014 -270.521938)
		(end 376.808746 -270.513302)
		(width 0.0889)
		(layer "B.Cu")
		(net "PVPP_HBM_CPU0")
	)
	(segment
		(start 379.613414 -270.521938)
		(end 379.628146 -270.513302)
		(width 0.0889)
		(layer "B.Cu")
		(net "PVPP_HBM_CPU0")
	)
	(segment
		(start 374.914414 -270.521938)
		(end 374.929146 -270.513302)
		(width 0.0889)
		(layer "B.Cu")
		(net "PVPP_HBM_CPU0")
	)
	(segment
		(start 384.220212 -270.995902)
		(end 384.220212 -271.011396)
		(width 0.0889)
		(layer "B.Cu")
		(net "PVPP_HBM_CPU0")
	)
	(segment
		(start 367.37798 -362.64215)
		(end 368.398552 -361.621578)
		(width 0.381)
		(layer "B.Cu")
		(net "PVPP_HBM_CPU0")
	)
	(segment
		(start 405.13762 -382.808988)
		(end 369.34648 -382.808988)
		(width 0.381)
		(layer "B.Cu")
		(net "PVPP_HBM_CPU0")
	)
	(segment
		(start 366.456214 -270.521938)
		(end 366.470946 -270.513302)
		(width 0.0889)
		(layer "B.Cu")
		(net "PVPP_HBM_CPU0")
	)
	(segment
		(start 399.71218 -271.112488)
		(end 401.066 -272.466308)
		(width 0.381)
		(layer "B.Cu")
		(net "PVPP_HBM_CPU0")
	)
	(segment
		(start 387.17982 -271.112488)
		(end 399.71218 -271.112488)
		(width 0.381)
		(layer "B.Cu")
		(net "PVPP_HBM_CPU0")
	)
	(segment
		(start 387.0325 -271.259808)
		(end 387.17982 -271.112488)
		(width 0.0889)
		(layer "B.Cu")
		(net "PVPP_HBM_CPU0")
	)
	(segment
		(start 366.45596 -270.521938)
		(end 366.456214 -270.521938)
		(width 0.0889)
		(layer "B.Cu")
		(net "PVPP_HBM_CPU0")
	)
	(segment
		(start 384.398774 -271.330674)
		(end 384.407664 -271.335754)
		(width 0.0889)
		(layer "B.Cu")
		(net "PVPP_HBM_CPU0")
	)
	(segment
		(start 383.372614 -270.521938)
		(end 383.387346 -270.513302)
		(width 0.0889)
		(layer "B.Cu")
		(net "PVPP_HBM_CPU0")
	)
	(segment
		(start 373.974614 -270.521938)
		(end 373.989346 -270.513302)
		(width 0.0889)
		(layer "B.Cu")
		(net "PVPP_HBM_CPU0")
	)
	(segment
		(start 407.22296 -340.609428)
		(end 407.22296 -380.723648)
		(width 0.381)
		(layer "B.Cu")
		(net "PVPP_HBM_CPU0")
	)
	(segment
		(start 368.398552 -361.621578)
		(end 368.398552 -360.759248)
		(width 0.381)
		(layer "B.Cu")
		(net "PVPP_HBM_CPU0")
	)
	(segment
		(start 365.51616 -270.521938)
		(end 365.526574 -270.515842)
		(width 0.0889)
		(layer "B.Cu")
		(net "PVPP_HBM_CPU0")
	)
	(segment
		(start 403.95652 -337.342988)
		(end 407.22296 -340.609428)
		(width 0.381)
		(layer "B.Cu")
		(net "PVPP_HBM_CPU0")
	)
	(segment
		(start 378.673614 -270.521938)
		(end 378.688346 -270.513302)
		(width 0.0889)
		(layer "B.Cu")
		(net "PVPP_HBM_CPU0")
	)
	(segment
		(start 371.155214 -270.521938)
		(end 371.169946 -270.513302)
		(width 0.0889)
		(layer "B.Cu")
		(net "PVPP_HBM_CPU0")
	)
	(segment
		(start 386.944616 -271.259808)
		(end 387.0325 -271.259808)
		(width 0.0889)
		(layer "B.Cu")
		(net "PVPP_HBM_CPU0")
	)
	(segment
		(start 403.95652 -273.548348)
		(end 403.95652 -337.342988)
		(width 0.381)
		(layer "B.Cu")
		(net "PVPP_HBM_CPU0")
	)
	(segment
		(start 368.398298 -360.758994)
		(end 368.398298 -360.335576)
		(width 0.381)
		(layer "B.Cu")
		(net "PVPP_HBM_CPU0")
	)
	(segment
		(start 381.49276 -270.521938)
		(end 381.503174 -270.515842)
		(width 0.0889)
		(layer "B.Cu")
		(net "PVPP_HBM_CPU0")
	)
	(segment
		(start 375.854214 -270.521938)
		(end 375.868946 -270.513302)
		(width 0.0889)
		(layer "B.Cu")
		(net "PVPP_HBM_CPU0")
	)
	(segment
		(start 367.37798 -380.840488)
		(end 367.37798 -362.64215)
		(width 0.381)
		(layer "B.Cu")
		(net "PVPP_HBM_CPU0")
	)
	(segment
		(start 382.432814 -270.521938)
		(end 382.447546 -270.513302)
		(width 0.0889)
		(layer "B.Cu")
		(net "PVPP_HBM_CPU0")
	)
	(segment
		(start 367.396014 -270.521938)
		(end 367.410746 -270.513302)
		(width 0.0889)
		(layer "B.Cu")
		(net "PVPP_HBM_CPU0")
	)
	(segment
		(start 385.332732 -271.327118)
		(end 385.347464 -271.335754)
		(width 0.0889)
		(layer "B.Cu")
		(net "PVPP_HBM_CPU0")
	)
	(segment
		(start 402.87448 -272.466308)
		(end 403.95652 -273.548348)
		(width 0.381)
		(layer "B.Cu")
		(net "PVPP_HBM_CPU0")
	)
	(segment
		(start 407.22296 -380.723648)
		(end 405.13762 -382.808988)
		(width 0.381)
		(layer "B.Cu")
		(net "PVPP_HBM_CPU0")
	)
	(segment
		(start 377.733814 -270.521938)
		(end 377.748546 -270.513302)
		(width 0.0889)
		(layer "B.Cu")
		(net "PVPP_HBM_CPU0")
	)
	(segment
		(start 373.034814 -270.521938)
		(end 373.049546 -270.513302)
		(width 0.0889)
		(layer "B.Cu")
		(net "PVPP_HBM_CPU0")
	)
	(segment
		(start 363.919262 -271.011396)
		(end 364.473998 -270.582136)
		(width 0.0889)
		(layer "B.Cu")
		(net "PVPP_HBM_CPU0")
	)
	(segment
		(start 372.095014 -270.521938)
		(end 372.109746 -270.513302)
		(width 0.0889)
		(layer "B.Cu")
		(net "PVPP_HBM_CPU0")
	)
	(arc
		(start 367.961418 -270.521938)
		(mid 368.148616 -270.572081)
		(end 368.335814 -270.521938)
		(width 0.0889)
		(layer "B.Cu")
		(net "PVPP_HBM_CPU0")
	)
	(arc
		(start 369.290346 -270.513302)
		(mid 369.566821 -270.445982)
		(end 369.841018 -270.521938)
		(width 0.0889)
		(layer "B.Cu")
		(net "PVPP_HBM_CPU0")
	)
	(arc
		(start 369.841018 -270.521938)
		(mid 370.028216 -270.572081)
		(end 370.215414 -270.521938)
		(width 0.0889)
		(layer "B.Cu")
		(net "PVPP_HBM_CPU0")
	)
	(arc
		(start 365.526574 -270.515842)
		(mid 365.805006 -270.445996)
		(end 366.081818 -270.521938)
		(width 0.0889)
		(layer "B.Cu")
		(net "PVPP_HBM_CPU0")
	)
	(arc
		(start 385.72186 -271.335754)
		(mid 385.996059 -271.259919)
		(end 386.272532 -271.327118)
		(width 0.0889)
		(layer "B.Cu")
		(net "PVPP_HBM_CPU0")
	)
	(arc
		(start 382.447546 -270.513302)
		(mid 382.724021 -270.445982)
		(end 382.998218 -270.521938)
		(width 0.0889)
		(layer "B.Cu")
		(net "PVPP_HBM_CPU0")
	)
	(arc
		(start 382.058418 -270.521938)
		(mid 382.245616 -270.572081)
		(end 382.432814 -270.521938)
		(width 0.0889)
		(layer "B.Cu")
		(net "PVPP_HBM_CPU0")
	)
	(arc
		(start 380.178818 -270.521938)
		(mid 380.366016 -270.572081)
		(end 380.553214 -270.521938)
		(width 0.0889)
		(layer "B.Cu")
		(net "PVPP_HBM_CPU0")
	)
	(arc
		(start 372.109746 -270.513302)
		(mid 372.386221 -270.445982)
		(end 372.660418 -270.521938)
		(width 0.0889)
		(layer "B.Cu")
		(net "PVPP_HBM_CPU0")
	)
	(arc
		(start 376.808746 -270.513302)
		(mid 377.085221 -270.445982)
		(end 377.359418 -270.521938)
		(width 0.0889)
		(layer "B.Cu")
		(net "PVPP_HBM_CPU0")
	)
	(arc
		(start 384.407664 -271.335754)
		(mid 384.594862 -271.385897)
		(end 384.78206 -271.335754)
		(width 0.0889)
		(layer "B.Cu")
		(net "PVPP_HBM_CPU0")
	)
	(arc
		(start 368.350546 -270.513302)
		(mid 368.627021 -270.445982)
		(end 368.901218 -270.521938)
		(width 0.0889)
		(layer "B.Cu")
		(net "PVPP_HBM_CPU0")
	)
	(arc
		(start 367.021618 -270.521938)
		(mid 367.208816 -270.572081)
		(end 367.396014 -270.521938)
		(width 0.0889)
		(layer "B.Cu")
		(net "PVPP_HBM_CPU0")
	)
	(arc
		(start 378.299218 -270.521938)
		(mid 378.486416 -270.572081)
		(end 378.673614 -270.521938)
		(width 0.0889)
		(layer "B.Cu")
		(net "PVPP_HBM_CPU0")
	)
	(arc
		(start 374.540018 -270.521938)
		(mid 374.727216 -270.572081)
		(end 374.914414 -270.521938)
		(width 0.0889)
		(layer "B.Cu")
		(net "PVPP_HBM_CPU0")
	)
	(arc
		(start 376.419618 -270.521938)
		(mid 376.606816 -270.572081)
		(end 376.794014 -270.521938)
		(width 0.0889)
		(layer "B.Cu")
		(net "PVPP_HBM_CPU0")
	)
	(arc
		(start 364.587028 -270.515842)
		(mid 364.865206 -270.446119)
		(end 365.141764 -270.521938)
		(width 0.0889)
		(layer "B.Cu")
		(net "PVPP_HBM_CPU0")
	)
	(arc
		(start 375.868946 -270.513302)
		(mid 376.145421 -270.445982)
		(end 376.419618 -270.521938)
		(width 0.0889)
		(layer "B.Cu")
		(net "PVPP_HBM_CPU0")
	)
	(arc
		(start 370.780818 -270.521938)
		(mid 370.968016 -270.572081)
		(end 371.155214 -270.521938)
		(width 0.0889)
		(layer "B.Cu")
		(net "PVPP_HBM_CPU0")
	)
	(arc
		(start 381.503174 -270.515842)
		(mid 381.781606 -270.445996)
		(end 382.058418 -270.521938)
		(width 0.0889)
		(layer "B.Cu")
		(net "PVPP_HBM_CPU0")
	)
	(arc
		(start 380.563628 -270.515842)
		(mid 380.841806 -270.446119)
		(end 381.118364 -270.521938)
		(width 0.0889)
		(layer "B.Cu")
		(net "PVPP_HBM_CPU0")
	)
	(arc
		(start 381.118364 -270.521938)
		(mid 381.305562 -270.572081)
		(end 381.49276 -270.521938)
		(width 0.0889)
		(layer "B.Cu")
		(net "PVPP_HBM_CPU0")
	)
	(arc
		(start 377.748546 -270.513302)
		(mid 378.025021 -270.445982)
		(end 378.299218 -270.521938)
		(width 0.0889)
		(layer "B.Cu")
		(net "PVPP_HBM_CPU0")
	)
	(arc
		(start 382.998218 -270.521938)
		(mid 383.185416 -270.572081)
		(end 383.372614 -270.521938)
		(width 0.0889)
		(layer "B.Cu")
		(net "PVPP_HBM_CPU0")
	)
	(arc
		(start 377.359418 -270.521938)
		(mid 377.546616 -270.572081)
		(end 377.733814 -270.521938)
		(width 0.0889)
		(layer "B.Cu")
		(net "PVPP_HBM_CPU0")
	)
	(arc
		(start 386.287264 -271.335754)
		(mid 386.474462 -271.385897)
		(end 386.66166 -271.335754)
		(width 0.0889)
		(layer "B.Cu")
		(net "PVPP_HBM_CPU0")
	)
	(arc
		(start 371.169946 -270.513302)
		(mid 371.446421 -270.445982)
		(end 371.720618 -270.521938)
		(width 0.0889)
		(layer "B.Cu")
		(net "PVPP_HBM_CPU0")
	)
	(arc
		(start 366.081818 -270.521938)
		(mid 366.268906 -270.572115)
		(end 366.45596 -270.521938)
		(width 0.0889)
		(layer "B.Cu")
		(net "PVPP_HBM_CPU0")
	)
	(arc
		(start 374.929146 -270.513302)
		(mid 375.205621 -270.445982)
		(end 375.479818 -270.521938)
		(width 0.0889)
		(layer "B.Cu")
		(net "PVPP_HBM_CPU0")
	)
	(arc
		(start 378.688346 -270.513302)
		(mid 378.964821 -270.445982)
		(end 379.239018 -270.521938)
		(width 0.0889)
		(layer "B.Cu")
		(net "PVPP_HBM_CPU0")
	)
	(arc
		(start 368.901218 -270.521938)
		(mid 369.088416 -270.572081)
		(end 369.275614 -270.521938)
		(width 0.0889)
		(layer "B.Cu")
		(net "PVPP_HBM_CPU0")
	)
	(arc
		(start 373.049546 -270.513302)
		(mid 373.326021 -270.445982)
		(end 373.600218 -270.521938)
		(width 0.0889)
		(layer "B.Cu")
		(net "PVPP_HBM_CPU0")
	)
	(arc
		(start 379.628146 -270.513302)
		(mid 379.904621 -270.445982)
		(end 380.178818 -270.521938)
		(width 0.0889)
		(layer "B.Cu")
		(net "PVPP_HBM_CPU0")
	)
	(arc
		(start 384.220212 -271.011396)
		(mid 384.267891 -271.194296)
		(end 384.398774 -271.330674)
		(width 0.0889)
		(layer "B.Cu")
		(net "PVPP_HBM_CPU0")
	)
	(arc
		(start 379.239018 -270.521938)
		(mid 379.426216 -270.572081)
		(end 379.613414 -270.521938)
		(width 0.0889)
		(layer "B.Cu")
		(net "PVPP_HBM_CPU0")
	)
	(arc
		(start 385.347464 -271.335754)
		(mid 385.534662 -271.385897)
		(end 385.72186 -271.335754)
		(width 0.0889)
		(layer "B.Cu")
		(net "PVPP_HBM_CPU0")
	)
	(arc
		(start 386.66166 -271.335754)
		(mid 386.798132 -271.279131)
		(end 386.944616 -271.259808)
		(width 0.0889)
		(layer "B.Cu")
		(net "PVPP_HBM_CPU0")
	)
	(arc
		(start 384.78206 -271.335754)
		(mid 385.056259 -271.259919)
		(end 385.332732 -271.327118)
		(width 0.0889)
		(layer "B.Cu")
		(net "PVPP_HBM_CPU0")
	)
	(arc
		(start 375.479818 -270.521938)
		(mid 375.667016 -270.572081)
		(end 375.854214 -270.521938)
		(width 0.0889)
		(layer "B.Cu")
		(net "PVPP_HBM_CPU0")
	)
	(arc
		(start 383.938018 -270.521938)
		(mid 384.140841 -270.722169)
		(end 384.220212 -270.995902)
		(width 0.0889)
		(layer "B.Cu")
		(net "PVPP_HBM_CPU0")
	)
	(arc
		(start 367.410746 -270.513302)
		(mid 367.687221 -270.445982)
		(end 367.961418 -270.521938)
		(width 0.0889)
		(layer "B.Cu")
		(net "PVPP_HBM_CPU0")
	)
	(arc
		(start 373.989346 -270.513302)
		(mid 374.265821 -270.445982)
		(end 374.540018 -270.521938)
		(width 0.0889)
		(layer "B.Cu")
		(net "PVPP_HBM_CPU0")
	)
	(arc
		(start 383.387346 -270.513302)
		(mid 383.663821 -270.445982)
		(end 383.938018 -270.521938)
		(width 0.0889)
		(layer "B.Cu")
		(net "PVPP_HBM_CPU0")
	)
	(arc
		(start 372.660418 -270.521938)
		(mid 372.847616 -270.572081)
		(end 373.034814 -270.521938)
		(width 0.0889)
		(layer "B.Cu")
		(net "PVPP_HBM_CPU0")
	)
	(arc
		(start 371.720618 -270.521938)
		(mid 371.907816 -270.572081)
		(end 372.095014 -270.521938)
		(width 0.0889)
		(layer "B.Cu")
		(net "PVPP_HBM_CPU0")
	)
	(arc
		(start 370.215414 -270.521938)
		(mid 370.498116 -270.446162)
		(end 370.780818 -270.521938)
		(width 0.0889)
		(layer "B.Cu")
		(net "PVPP_HBM_CPU0")
	)
	(arc
		(start 365.141764 -270.521938)
		(mid 365.328962 -270.572081)
		(end 365.51616 -270.521938)
		(width 0.0889)
		(layer "B.Cu")
		(net "PVPP_HBM_CPU0")
	)
	(arc
		(start 373.600218 -270.521938)
		(mid 373.787416 -270.572081)
		(end 373.974614 -270.521938)
		(width 0.0889)
		(layer "B.Cu")
		(net "PVPP_HBM_CPU0")
	)
	(arc
		(start 366.470946 -270.513302)
		(mid 366.747421 -270.445982)
		(end 367.021618 -270.521938)
		(width 0.0889)
		(layer "B.Cu")
		(net "PVPP_HBM_CPU0")
	)
	(segment
		(start 11.7094 -172.920914)
		(end 18.31594 -166.314374)
		(width 0.381)
		(layer "F.Cu")
		(net "PVNN_TERM_CPU1")
	)
	(segment
		(start 133.02488 -93.074998)
		(end 133.01218 -93.087698)
		(width 0.381)
		(layer "F.Cu")
		(net "PVNN_TERM_CPU1")
	)
	(segment
		(start 19.16176 -164.271706)
		(end 19.71421 -163.719256)
		(width 0.381)
		(layer "F.Cu")
		(net "PVNN_TERM_CPU1")
	)
	(segment
		(start 40.207692 -130.053334)
		(end 40.588692 -130.434334)
		(width 0.381)
		(layer "F.Cu")
		(net "PVNN_TERM_CPU1")
	)
	(segment
		(start 223.716088 -223.49714)
		(end 223.060768 -223.49714)
		(width 0.3556)
		(layer "F.Cu")
		(net "PVNN_TERM_CPU1")
	)
	(segment
		(start 179.4002 -188.178948)
		(end 178.816 -188.178948)
		(width 0.381)
		(layer "F.Cu")
		(net "PVNN_TERM_CPU1")
	)
	(segment
		(start 227.303838 -222.09887)
		(end 227.303838 -221.42323)
		(width 0.381)
		(layer "F.Cu")
		(net "PVNN_TERM_CPU1")
	)
	(segment
		(start 216.4588 -189.550548)
		(end 214.7316 -187.823348)
		(width 0.381)
		(layer "F.Cu")
		(net "PVNN_TERM_CPU1")
	)
	(segment
		(start 211.963 -187.823348)
		(end 211.0994 -186.959748)
		(width 0.381)
		(layer "F.Cu")
		(net "PVNN_TERM_CPU1")
	)
	(segment
		(start 194.35953 -349.367348)
		(end 195.20408 -349.367348)
		(width 0.381)
		(layer "F.Cu")
		(net "PVNN_TERM_CPU1")
	)
	(segment
		(start 154.856688 -189.207648)
		(end 152.51684 -189.207648)
		(width 0.381)
		(layer "F.Cu")
		(net "PVNN_TERM_CPU1")
	)
	(segment
		(start 19.707352 -165.758114)
		(end 19.707352 -166.770558)
		(width 0.381)
		(layer "F.Cu")
		(net "PVNN_TERM_CPU1")
	)
	(segment
		(start 207.210406 -256.24663)
		(end 167.804338 -256.24663)
		(width 0.381)
		(layer "F.Cu")
		(net "PVNN_TERM_CPU1")
	)
	(segment
		(start 203.3016 -185.435748)
		(end 194.183 -185.435748)
		(width 0.381)
		(layer "F.Cu")
		(net "PVNN_TERM_CPU1")
	)
	(segment
		(start 133.671818 -95.458026)
		(end 133.671818 -94.972886)
		(width 0.381)
		(layer "F.Cu")
		(net "PVNN_TERM_CPU1")
	)
	(segment
		(start 155.728162 -188.350398)
		(end 155.725368 -188.350398)
		(width 0.381)
		(layer "F.Cu")
		(net "PVNN_TERM_CPU1")
	)
	(segment
		(start 152.51684 -189.207648)
		(end 151.63165 -190.092838)
		(width 0.381)
		(layer "F.Cu")
		(net "PVNN_TERM_CPU1")
	)
	(segment
		(start 99.804474 -356.83063)
		(end 99.999546 -357.025702)
		(width 0.381)
		(layer "F.Cu")
		(net "PVNN_TERM_CPU1")
	)
	(segment
		(start 133.01218 -93.087698)
		(end 133.01218 -93.698568)
		(width 0.381)
		(layer "F.Cu")
		(net "PVNN_TERM_CPU1")
	)
	(segment
		(start 40.588692 -131.516374)
		(end 40.207692 -131.897374)
		(width 0.381)
		(layer "F.Cu")
		(net "PVNN_TERM_CPU1")
	)
	(segment
		(start 133.671818 -94.972886)
		(end 133.01218 -94.313248)
		(width 0.381)
		(layer "F.Cu")
		(net "PVNN_TERM_CPU1")
	)
	(segment
		(start 178.816 -188.178948)
		(end 177.988722 -187.35167)
		(width 0.381)
		(layer "F.Cu")
		(net "PVNN_TERM_CPU1")
	)
	(segment
		(start 15.649194 -186.793378)
		(end 11.7094 -182.853584)
		(width 0.381)
		(layer "F.Cu")
		(net "PVNN_TERM_CPU1")
	)
	(segment
		(start 124.64288 -94.736666)
		(end 125.264418 -95.358204)
		(width 0.381)
		(layer "F.Cu")
		(net "PVNN_TERM_CPU1")
	)
	(segment
		(start 99.808538 -355.048058)
		(end 100.018342 -355.257862)
		(width 0.381)
		(layer "F.Cu")
		(net "PVNN_TERM_CPU1")
	)
	(segment
		(start 218.186 -189.550548)
		(end 216.4588 -189.550548)
		(width 0.381)
		(layer "F.Cu")
		(net "PVNN_TERM_CPU1")
	)
	(segment
		(start 124.64288 -93.690948)
		(end 124.64288 -94.736666)
		(width 0.381)
		(layer "F.Cu")
		(net "PVNN_TERM_CPU1")
	)
	(segment
		(start 193.421 -186.197748)
		(end 181.3814 -186.197748)
		(width 0.381)
		(layer "F.Cu")
		(net "PVNN_TERM_CPU1")
	)
	(segment
		(start 19.71421 -163.719256)
		(end 19.71421 -164.737796)
		(width 0.381)
		(layer "F.Cu")
		(net "PVNN_TERM_CPU1")
	)
	(segment
		(start 99.297236 -357.53167)
		(end 99.618546 -357.53167)
		(width 0.381)
		(layer "F.Cu")
		(net "PVNN_TERM_CPU1")
	)
	(segment
		(start 224.028 -225.288348)
		(end 224.028 -224.150428)
		(width 0.381)
		(layer "F.Cu")
		(net "PVNN_TERM_CPU1")
	)
	(segment
		(start 100.209096 -357.025702)
		(end 99.999546 -357.025702)
		(width 0.381)
		(layer "F.Cu")
		(net "PVNN_TERM_CPU1")
	)
	(segment
		(start 11.7094 -182.853584)
		(end 11.7094 -172.920914)
		(width 0.381)
		(layer "F.Cu")
		(net "PVNN_TERM_CPU1")
	)
	(segment
		(start 227.303838 -221.42323)
		(end 227.303838 -217.794586)
		(width 0.381)
		(layer "F.Cu")
		(net "PVNN_TERM_CPU1")
	)
	(segment
		(start 224.725738 -222.09887)
		(end 224.725738 -221.42323)
		(width 0.381)
		(layer "F.Cu")
		(net "PVNN_TERM_CPU1")
	)
	(segment
		(start 100.018342 -355.257862)
		(end 100.420678 -355.257862)
		(width 0.381)
		(layer "F.Cu")
		(net "PVNN_TERM_CPU1")
	)
	(segment
		(start 132.51688 -102.431088)
		(end 132.909818 -102.824026)
		(width 0.381)
		(layer "F.Cu")
		(net "PVNN_TERM_CPU1")
	)
	(segment
		(start 38.3032 -130.053334)
		(end 40.207692 -130.053334)
		(width 0.381)
		(layer "F.Cu")
		(net "PVNN_TERM_CPU1")
	)
	(segment
		(start 94.607126 -190.092838)
		(end 94.101158 -189.58687)
		(width 0.381)
		(layer "F.Cu")
		(net "PVNN_TERM_CPU1")
	)
	(segment
		(start 194.183 -185.435748)
		(end 193.421 -186.197748)
		(width 0.381)
		(layer "F.Cu")
		(net "PVNN_TERM_CPU1")
	)
	(segment
		(start 181.3814 -186.197748)
		(end 179.4002 -188.178948)
		(width 0.381)
		(layer "F.Cu")
		(net "PVNN_TERM_CPU1")
	)
	(segment
		(start 19.73072 -165.734746)
		(end 19.71421 -165.751256)
		(width 0.381)
		(layer "F.Cu")
		(net "PVNN_TERM_CPU1")
	)
	(segment
		(start 101.046026 -357.862632)
		(end 100.209096 -357.025702)
		(width 0.381)
		(layer "F.Cu")
		(net "PVNN_TERM_CPU1")
	)
	(segment
		(start 99.618546 -357.53167)
		(end 99.999546 -357.15067)
		(width 0.381)
		(layer "F.Cu")
		(net "PVNN_TERM_CPU1")
	)
	(segment
		(start 124.64288 -93.074998)
		(end 124.64288 -93.690948)
		(width 0.381)
		(layer "F.Cu")
		(net "PVNN_TERM_CPU1")
	)
	(segment
		(start 157.301692 -189.20587)
		(end 156.583634 -189.20587)
		(width 0.381)
		(layer "F.Cu")
		(net "PVNN_TERM_CPU1")
	)
	(segment
		(start 99.490276 -356.83063)
		(end 99.804474 -356.83063)
		(width 0.381)
		(layer "F.Cu")
		(net "PVNN_TERM_CPU1")
	)
	(segment
		(start 133.01218 -94.313248)
		(end 133.01218 -93.698568)
		(width 0.381)
		(layer "F.Cu")
		(net "PVNN_TERM_CPU1")
	)
	(segment
		(start 19.73072 -165.255194)
		(end 19.73072 -165.734746)
		(width 0.381)
		(layer "F.Cu")
		(net "PVNN_TERM_CPU1")
	)
	(segment
		(start 223.139 -195.773548)
		(end 218.9734 -191.607948)
		(width 0.381)
		(layer "F.Cu")
		(net "PVNN_TERM_CPU1")
	)
	(segment
		(start 19.71421 -165.238684)
		(end 19.73072 -165.255194)
		(width 0.381)
		(layer "F.Cu")
		(net "PVNN_TERM_CPU1")
	)
	(segment
		(start 223.139 -213.629748)
		(end 223.139 -195.773548)
		(width 0.381)
		(layer "F.Cu")
		(net "PVNN_TERM_CPU1")
	)
	(segment
		(start 159.155892 -187.35167)
		(end 157.301692 -189.20587)
		(width 0.381)
		(layer "F.Cu")
		(net "PVNN_TERM_CPU1")
	)
	(segment
		(start 132.51688 -100.567998)
		(end 132.51688 -101.183948)
		(width 0.381)
		(layer "F.Cu")
		(net "PVNN_TERM_CPU1")
	)
	(segment
		(start 167.804338 -256.24663)
		(end 165.754558 -254.19685)
		(width 0.381)
		(layer "F.Cu")
		(net "PVNN_TERM_CPU1")
	)
	(segment
		(start 155.713938 -188.350398)
		(end 154.856688 -189.207648)
		(width 0.381)
		(layer "F.Cu")
		(net "PVNN_TERM_CPU1")
	)
	(segment
		(start 204.8256 -186.959748)
		(end 203.3016 -185.435748)
		(width 0.381)
		(layer "F.Cu")
		(net "PVNN_TERM_CPU1")
	)
	(segment
		(start 155.725368 -188.350398)
		(end 155.713938 -188.338968)
		(width 0.381)
		(layer "F.Cu")
		(net "PVNN_TERM_CPU1")
	)
	(segment
		(start 156.583634 -189.20587)
		(end 155.728162 -188.350398)
		(width 0.381)
		(layer "F.Cu")
		(net "PVNN_TERM_CPU1")
	)
	(segment
		(start 132.51688 -101.183948)
		(end 132.51688 -102.431088)
		(width 0.381)
		(layer "F.Cu")
		(net "PVNN_TERM_CPU1")
	)
	(segment
		(start 218.9734 -190.337948)
		(end 218.186 -189.550548)
		(width 0.381)
		(layer "F.Cu")
		(net "PVNN_TERM_CPU1")
	)
	(segment
		(start 99.297236 -356.63759)
		(end 99.490276 -356.83063)
		(width 0.381)
		(layer "F.Cu")
		(net "PVNN_TERM_CPU1")
	)
	(segment
		(start 218.9734 -191.607948)
		(end 218.9734 -190.337948)
		(width 0.381)
		(layer "F.Cu")
		(net "PVNN_TERM_CPU1")
	)
	(segment
		(start 18.31594 -166.314374)
		(end 19.16176 -164.271706)
		(width 0.381)
		(layer "F.Cu")
		(net "PVNN_TERM_CPU1")
	)
	(segment
		(start 223.716088 -223.838516)
		(end 223.716088 -223.49714)
		(width 0.381)
		(layer "F.Cu")
		(net "PVNN_TERM_CPU1")
	)
	(segment
		(start 19.71421 -164.737796)
		(end 19.71421 -165.238684)
		(width 0.381)
		(layer "F.Cu")
		(net "PVNN_TERM_CPU1")
	)
	(segment
		(start 177.988722 -187.35167)
		(end 159.155892 -187.35167)
		(width 0.381)
		(layer "F.Cu")
		(net "PVNN_TERM_CPU1")
	)
	(segment
		(start 40.588692 -130.434334)
		(end 40.588692 -131.516374)
		(width 0.381)
		(layer "F.Cu")
		(net "PVNN_TERM_CPU1")
	)
	(segment
		(start 155.713938 -188.338968)
		(end 155.713938 -188.350398)
		(width 0.381)
		(layer "F.Cu")
		(net "PVNN_TERM_CPU1")
	)
	(segment
		(start 40.207692 -131.897374)
		(end 39.594282 -131.897374)
		(width 0.381)
		(layer "F.Cu")
		(net "PVNN_TERM_CPU1")
	)
	(segment
		(start 99.999546 -357.15067)
		(end 99.999546 -357.025702)
		(width 0.381)
		(layer "F.Cu")
		(net "PVNN_TERM_CPU1")
	)
	(segment
		(start 151.63165 -190.092838)
		(end 94.607126 -190.092838)
		(width 0.381)
		(layer "F.Cu")
		(net "PVNN_TERM_CPU1")
	)
	(segment
		(start 214.7316 -187.823348)
		(end 211.963 -187.823348)
		(width 0.381)
		(layer "F.Cu")
		(net "PVNN_TERM_CPU1")
	)
	(segment
		(start 201.42073 -101.145848)
		(end 202.06208 -101.145848)
		(width 0.381)
		(layer "F.Cu")
		(net "PVNN_TERM_CPU1")
	)
	(segment
		(start 227.303838 -217.794586)
		(end 223.139 -213.629748)
		(width 0.381)
		(layer "F.Cu")
		(net "PVNN_TERM_CPU1")
	)
	(segment
		(start 94.101158 -189.58687)
		(end 91.161108 -189.58687)
		(width 0.381)
		(layer "F.Cu")
		(net "PVNN_TERM_CPU1")
	)
	(segment
		(start 224.028 -224.150428)
		(end 223.716088 -223.838516)
		(width 0.381)
		(layer "F.Cu")
		(net "PVNN_TERM_CPU1")
	)
	(segment
		(start 19.71421 -165.751256)
		(end 19.707352 -165.758114)
		(width 0.381)
		(layer "F.Cu")
		(net "PVNN_TERM_CPU1")
	)
	(segment
		(start 211.0994 -186.959748)
		(end 204.8256 -186.959748)
		(width 0.381)
		(layer "F.Cu")
		(net "PVNN_TERM_CPU1")
	)
	(via
		(at 91.161108 -187.89777)
		(size 0.508)
		(drill 0.254)
		(layers "F.Cu" "B.Cu")
		(net "PVNN_TERM_CPU1")
	)
	(via
		(at 78.38567 -159.26435)
		(size 0.508)
		(drill 0.254)
		(layers "F.Cu" "B.Cu")
		(net "PVNN_TERM_CPU1")
	)
	(via
		(at 70.994778 -184.66435)
		(size 0.508)
		(drill 0.254)
		(layers "F.Cu" "B.Cu")
		(net "PVNN_TERM_CPU1")
	)
	(via
		(at 83.082384 -186.94527)
		(size 0.508)
		(drill 0.254)
		(layers "F.Cu" "B.Cu")
		(net "PVNN_TERM_CPU1")
	)
	(via
		(at 77.368908 -184.903872)
		(size 0.508)
		(drill 0.254)
		(layers "F.Cu" "B.Cu")
		(net "PVNN_TERM_CPU1")
	)
	(via
		(at 77.625448 -159.39262)
		(size 0.508)
		(drill 0.254)
		(layers "F.Cu" "B.Cu")
		(net "PVNN_TERM_CPU1")
	)
	(via
		(at 99.297236 -357.53167)
		(size 0.508)
		(drill 0.254)
		(layers "F.Cu" "B.Cu")
		(net "PVNN_TERM_CPU1")
	)
	(via
		(at 74.0664 -179.111148)
		(size 0.508)
		(drill 0.254)
		(layers "F.Cu" "B.Cu")
		(net "PVNN_TERM_CPU1")
	)
	(via
		(at 91.161108 -189.58687)
		(size 0.508)
		(drill 0.254)
		(layers "F.Cu" "B.Cu")
		(net "PVNN_TERM_CPU1")
	)
	(via
		(at 227.303838 -221.42323)
		(size 0.508)
		(drill 0.254)
		(layers "F.Cu" "B.Cu")
		(net "PVNN_TERM_CPU1")
	)
	(via
		(at 91.38666 -185.37809)
		(size 0.508)
		(drill 0.254)
		(layers "F.Cu" "B.Cu")
		(net "PVNN_TERM_CPU1")
	)
	(via
		(at 132.51688 -101.183948)
		(size 0.508)
		(drill 0.254)
		(layers "F.Cu" "B.Cu")
		(net "PVNN_TERM_CPU1")
	)
	(via
		(at 85.457284 -189.607444)
		(size 0.508)
		(drill 0.254)
		(layers "F.Cu" "B.Cu")
		(net "PVNN_TERM_CPU1")
	)
	(via
		(at 51.714908 -192.24117)
		(size 0.508)
		(drill 0.254)
		(layers "F.Cu" "B.Cu")
		(net "PVNN_TERM_CPU1")
	)
	(via
		(at 48.666908 -192.237106)
		(size 0.508)
		(drill 0.254)
		(layers "F.Cu" "B.Cu")
		(net "PVNN_TERM_CPU1")
	)
	(via
		(at 80.616044 -158.294578)
		(size 0.508)
		(drill 0.254)
		(layers "F.Cu" "B.Cu")
		(net "PVNN_TERM_CPU1")
	)
	(via
		(at 75.460098 -183.197246)
		(size 0.508)
		(drill 0.254)
		(layers "F.Cu" "B.Cu")
		(net "PVNN_TERM_CPU1")
	)
	(via
		(at 48.000412 -192.24117)
		(size 0.508)
		(drill 0.254)
		(layers "F.Cu" "B.Cu")
		(net "PVNN_TERM_CPU1")
	)
	(via
		(at 133.01218 -93.698568)
		(size 0.508)
		(drill 0.254)
		(layers "F.Cu" "B.Cu")
		(net "PVNN_TERM_CPU1")
	)
	(via
		(at 195.20408 -349.367348)
		(size 0.508)
		(drill 0.254)
		(layers "F.Cu" "B.Cu")
		(net "PVNN_TERM_CPU1")
	)
	(via
		(at 124.64288 -93.690948)
		(size 0.508)
		(drill 0.254)
		(layers "F.Cu" "B.Cu")
		(net "PVNN_TERM_CPU1")
	)
	(via
		(at 202.06208 -101.145848)
		(size 0.508)
		(drill 0.254)
		(layers "F.Cu" "B.Cu")
		(net "PVNN_TERM_CPU1")
	)
	(via
		(at 99.808538 -355.048058)
		(size 0.508)
		(drill 0.254)
		(layers "F.Cu" "B.Cu")
		(net "PVNN_TERM_CPU1")
	)
	(via
		(at 152.51684 -189.207648)
		(size 0.508)
		(drill 0.254)
		(layers "F.Cu" "B.Cu")
		(net "PVNN_TERM_CPU1")
	)
	(via
		(at 85.876638 -187.00369)
		(size 0.508)
		(drill 0.254)
		(layers "F.Cu" "B.Cu")
		(net "PVNN_TERM_CPU1")
	)
	(via
		(at 77.625448 -158.75762)
		(size 0.508)
		(drill 0.254)
		(layers "F.Cu" "B.Cu")
		(net "PVNN_TERM_CPU1")
	)
	(via
		(at 78.38567 -159.89935)
		(size 0.508)
		(drill 0.254)
		(layers "F.Cu" "B.Cu")
		(net "PVNN_TERM_CPU1")
	)
	(via
		(at 178.816 -188.178948)
		(size 0.508)
		(drill 0.254)
		(layers "F.Cu" "B.Cu")
		(net "PVNN_TERM_CPU1")
	)
	(via
		(at 47.20209 -192.292478)
		(size 0.508)
		(drill 0.254)
		(layers "F.Cu" "B.Cu")
		(net "PVNN_TERM_CPU1")
	)
	(via
		(at 49.682908 -192.237106)
		(size 0.508)
		(drill 0.254)
		(layers "F.Cu" "B.Cu")
		(net "PVNN_TERM_CPU1")
	)
	(via
		(at 38.3032 -130.053334)
		(size 0.508)
		(drill 0.254)
		(layers "F.Cu" "B.Cu")
		(net "PVNN_TERM_CPU1")
	)
	(via
		(at 120.779032 -91.253564)
		(size 0.508)
		(drill 0.254)
		(layers "F.Cu" "B.Cu")
		(net "PVNN_TERM_CPU1")
	)
	(via
		(at 165.754558 -254.19685)
		(size 0.508)
		(drill 0.254)
		(layers "F.Cu" "B.Cu")
		(net "PVNN_TERM_CPU1")
	)
	(via
		(at 67.056 -184.470548)
		(size 0.508)
		(drill 0.254)
		(layers "F.Cu" "B.Cu")
		(net "PVNN_TERM_CPU1")
	)
	(via
		(at 72.208898 -181.86781)
		(size 0.508)
		(drill 0.254)
		(layers "F.Cu" "B.Cu")
		(net "PVNN_TERM_CPU1")
	)
	(via
		(at 73.052178 -191.760348)
		(size 0.508)
		(drill 0.254)
		(layers "F.Cu" "B.Cu")
		(net "PVNN_TERM_CPU1")
	)
	(via
		(at 18.734786 -191.700404)
		(size 0.508)
		(drill 0.254)
		(layers "F.Cu" "B.Cu")
		(net "PVNN_TERM_CPU1")
	)
	(via
		(at 85.122004 -184.994042)
		(size 0.508)
		(drill 0.254)
		(layers "F.Cu" "B.Cu")
		(net "PVNN_TERM_CPU1")
	)
	(via
		(at 155.713938 -188.338968)
		(size 0.508)
		(drill 0.254)
		(layers "F.Cu" "B.Cu")
		(net "PVNN_TERM_CPU1")
	)
	(via
		(at 99.297236 -356.63759)
		(size 0.508)
		(drill 0.254)
		(layers "F.Cu" "B.Cu")
		(net "PVNN_TERM_CPU1")
	)
	(via
		(at 77.625448 -158.12262)
		(size 0.508)
		(drill 0.254)
		(layers "F.Cu" "B.Cu")
		(net "PVNN_TERM_CPU1")
	)
	(via
		(at 18.734786 -192.848484)
		(size 0.508)
		(drill 0.254)
		(layers "F.Cu" "B.Cu")
		(net "PVNN_TERM_CPU1")
	)
	(via
		(at 67.7418 -185.664348)
		(size 0.508)
		(drill 0.254)
		(layers "F.Cu" "B.Cu")
		(net "PVNN_TERM_CPU1")
	)
	(via
		(at 224.725738 -221.42323)
		(size 0.508)
		(drill 0.254)
		(layers "F.Cu" "B.Cu")
		(net "PVNN_TERM_CPU1")
	)
	(via
		(at 55.888382 -192.238376)
		(size 0.508)
		(drill 0.254)
		(layers "F.Cu" "B.Cu")
		(net "PVNN_TERM_CPU1")
	)
	(via
		(at 207.210406 -256.24663)
		(size 0.508)
		(drill 0.254)
		(layers "F.Cu" "B.Cu")
		(net "PVNN_TERM_CPU1")
	)
	(via
		(at 90.410284 -185.1152)
		(size 0.508)
		(drill 0.254)
		(layers "F.Cu" "B.Cu")
		(net "PVNN_TERM_CPU1")
	)
	(via
		(at 68.97878 -189.591188)
		(size 0.508)
		(drill 0.254)
		(layers "F.Cu" "B.Cu")
		(net "PVNN_TERM_CPU1")
	)
	(via
		(at 53.746908 -192.24117)
		(size 0.508)
		(drill 0.254)
		(layers "F.Cu" "B.Cu")
		(net "PVNN_TERM_CPU1")
	)
	(via
		(at 81.167478 -187.00115)
		(size 0.508)
		(drill 0.254)
		(layers "F.Cu" "B.Cu")
		(net "PVNN_TERM_CPU1")
	)
	(via
		(at 17.35201 -194.478656)
		(size 0.508)
		(drill 0.254)
		(layers "F.Cu" "B.Cu")
		(net "PVNN_TERM_CPU1")
	)
	(via
		(at 223.060768 -223.49714)
		(size 0.508)
		(drill 0.254)
		(layers "F.Cu" "B.Cu")
		(net "PVNN_TERM_CPU1")
	)
	(segment
		(start 67.818 -185.664348)
		(end 68.090542 -185.391806)
		(width 0.381)
		(layer "B.Cu")
		(net "PVNN_TERM_CPU1")
	)
	(segment
		(start 18.125186 -192.848484)
		(end 18.734786 -192.848484)
		(width 0.3556)
		(layer "B.Cu")
		(net "PVNN_TERM_CPU1")
	)
	(segment
		(start 48.000412 -192.510156)
		(end 47.650908 -192.85966)
		(width 0.381)
		(layer "B.Cu")
		(net "PVNN_TERM_CPU1")
	)
	(segment
		(start 70.994778 -184.66435)
		(end 70.994778 -185.0009)
		(width 0.381)
		(layer "B.Cu")
		(net "PVNN_TERM_CPU1")
	)
	(segment
		(start 120.1674 -93.767148)
		(end 120.6246 -93.309948)
		(width 0.508)
		(layer "B.Cu")
		(net "PVNN_TERM_CPU1")
	)
	(segment
		(start 71.711058 -182.903876)
		(end 72.655684 -182.903876)
		(width 0.381)
		(layer "B.Cu")
		(net "PVNN_TERM_CPU1")
	)
	(segment
		(start 55.695088 -192.43167)
		(end 55.695088 -192.99174)
		(width 0.381)
		(layer "B.Cu")
		(net "PVNN_TERM_CPU1")
	)
	(segment
		(start 176.360582 -93.979746)
		(end 188.451998 -93.979746)
		(width 0.508)
		(layer "B.Cu")
		(net "PVNN_TERM_CPU1")
	)
	(segment
		(start 217.674698 -226.12985)
		(end 217.674698 -255.56845)
		(width 0.381)
		(layer "B.Cu")
		(net "PVNN_TERM_CPU1")
	)
	(segment
		(start 174.997618 -200.003918)
		(end 175.673258 -199.328278)
		(width 0.381)
		(layer "B.Cu")
		(net "PVNN_TERM_CPU1")
	)
	(segment
		(start 188.451998 -93.979746)
		(end 192.99428 -98.522028)
		(width 0.508)
		(layer "B.Cu")
		(net "PVNN_TERM_CPU1")
	)
	(segment
		(start 67.7418 -185.664348)
		(end 67.818 -185.664348)
		(width 0.381)
		(layer "B.Cu")
		(net "PVNN_TERM_CPU1")
	)
	(segment
		(start 175.464978 -194.63131)
		(end 175.673258 -194.83959)
		(width 0.381)
		(layer "B.Cu")
		(net "PVNN_TERM_CPU1")
	)
	(segment
		(start 71.65848 -182.418228)
		(end 71.65848 -182.851298)
		(width 0.381)
		(layer "B.Cu")
		(net "PVNN_TERM_CPU1")
	)
	(segment
		(start 165.985952 -251.854716)
		(end 165.985952 -251.267214)
		(width 0.381)
		(layer "B.Cu")
		(net "PVNN_TERM_CPU1")
	)
	(segment
		(start 79.182468 -156.2862)
		(end 79.182468 -153.248868)
		(width 0.508)
		(layer "B.Cu")
		(net "PVNN_TERM_CPU1")
	)
	(segment
		(start 90.410284 -184.4167)
		(end 90.410284 -185.1152)
		(width 0.381)
		(layer "B.Cu")
		(net "PVNN_TERM_CPU1")
	)
	(segment
		(start 125.717808 -92.61602)
		(end 124.64288 -93.690948)
		(width 0.508)
		(layer "B.Cu")
		(net "PVNN_TERM_CPU1")
	)
	(segment
		(start 158.550864 -93.979746)
		(end 171.577 -93.979746)
		(width 0.508)
		(layer "B.Cu")
		(net "PVNN_TERM_CPU1")
	)
	(segment
		(start 152.335738 -189.95517)
		(end 152.339802 -189.959234)
		(width 0.381)
		(layer "B.Cu")
		(net "PVNN_TERM_CPU1")
	)
	(segment
		(start 67.056 -183.968898)
		(end 67.320922 -183.703976)
		(width 0.381)
		(layer "B.Cu")
		(net "PVNN_TERM_CPU1")
	)
	(segment
		(start 99.906836 -356.63759)
		(end 99.297236 -356.63759)
		(width 0.381)
		(layer "B.Cu")
		(net "PVNN_TERM_CPU1")
	)
	(segment
		(start 179.168552 -191.001396)
		(end 179.168552 -192.299844)
		(width 0.381)
		(layer "B.Cu")
		(net "PVNN_TERM_CPU1")
	)
	(segment
		(start 139.073128 -88.76665)
		(end 140.525754 -90.219276)
		(width 0.508)
		(layer "B.Cu")
		(net "PVNN_TERM_CPU1")
	)
	(segment
		(start 132.51688 -101.183948)
		(end 132.51688 -94.193868)
		(width 0.508)
		(layer "B.Cu")
		(net "PVNN_TERM_CPU1")
	)
	(segment
		(start 49.682908 -192.85966)
		(end 49.682908 -192.237106)
		(width 0.381)
		(layer "B.Cu")
		(net "PVNN_TERM_CPU1")
	)
	(segment
		(start 18.125186 -191.700404)
		(end 18.734786 -191.700404)
		(width 0.3556)
		(layer "B.Cu")
		(net "PVNN_TERM_CPU1")
	)
	(segment
		(start 83.082384 -187.635642)
		(end 83.082384 -186.94527)
		(width 0.381)
		(layer "B.Cu")
		(net "PVNN_TERM_CPU1")
	)
	(segment
		(start 175.673258 -194.83959)
		(end 175.673258 -198.114158)
		(width 0.381)
		(layer "B.Cu")
		(net "PVNN_TERM_CPU1")
	)
	(segment
		(start 154.995118 -188.94933)
		(end 155.38704 -188.94933)
		(width 0.381)
		(layer "B.Cu")
		(net "PVNN_TERM_CPU1")
	)
	(segment
		(start 78.07452 -157.673548)
		(end 78.07452 -157.394148)
		(width 0.508)
		(layer "B.Cu")
		(net "PVNN_TERM_CPU1")
	)
	(segment
		(start 179.841398 -190.32855)
		(end 179.168552 -191.001396)
		(width 0.381)
		(layer "B.Cu")
		(net "PVNN_TERM_CPU1")
	)
	(segment
		(start 172.225462 -94.628208)
		(end 175.71212 -94.628208)
		(width 0.508)
		(layer "B.Cu")
		(net "PVNN_TERM_CPU1")
	)
	(segment
		(start 81.157318 -187.759086)
		(end 80.763618 -188.152786)
		(width 0.381)
		(layer "B.Cu")
		(net "PVNN_TERM_CPU1")
	)
	(segment
		(start 17.35201 -194.478656)
		(end 17.35201 -193.843656)
		(width 0.381)
		(layer "B.Cu")
		(net "PVNN_TERM_CPU1")
	)
	(segment
		(start 178.145948 -192.299844)
		(end 177.123344 -192.299844)
		(width 0.381)
		(layer "B.Cu")
		(net "PVNN_TERM_CPU1")
	)
	(segment
		(start 178.816 -188.178948)
		(end 179.841398 -189.204346)
		(width 0.381)
		(layer "B.Cu")
		(net "PVNN_TERM_CPU1")
	)
	(segment
		(start 46.634908 -192.85966)
		(end 47.20209 -192.292478)
		(width 0.381)
		(layer "B.Cu")
		(net "PVNN_TERM_CPU1")
	)
	(segment
		(start 223.060768 -223.49714)
		(end 220.307408 -223.49714)
		(width 0.381)
		(layer "B.Cu")
		(net "PVNN_TERM_CPU1")
	)
	(segment
		(start 55.888382 -192.238376)
		(end 55.695088 -192.43167)
		(width 0.381)
		(layer "B.Cu")
		(net "PVNN_TERM_CPU1")
	)
	(segment
		(start 120.1674 -97.323148)
		(end 120.1674 -93.767148)
		(width 0.508)
		(layer "B.Cu")
		(net "PVNN_TERM_CPU1")
	)
	(segment
		(start 71.65848 -182.877968)
		(end 71.65848 -182.851298)
		(width 0.381)
		(layer "B.Cu")
		(net "PVNN_TERM_CPU1")
	)
	(segment
		(start 132.346192 -92.61602)
		(end 125.717808 -92.61602)
		(width 0.508)
		(layer "B.Cu")
		(net "PVNN_TERM_CPU1")
	)
	(segment
		(start 154.4955 -189.448948)
		(end 154.995118 -188.94933)
		(width 0.381)
		(layer "B.Cu")
		(net "PVNN_TERM_CPU1")
	)
	(segment
		(start 93.148658 -187.89777)
		(end 94.209108 -188.95822)
		(width 0.381)
		(layer "B.Cu")
		(net "PVNN_TERM_CPU1")
	)
	(segment
		(start 120.8786 -99.990148)
		(end 120.8786 -98.034348)
		(width 0.508)
		(layer "B.Cu")
		(net "PVNN_TERM_CPU1")
	)
	(segment
		(start 120.6246 -93.309948)
		(end 121.66981 -93.309948)
		(width 0.508)
		(layer "B.Cu")
		(net "PVNN_TERM_CPU1")
	)
	(segment
		(start 151.281638 -189.95517)
		(end 152.335738 -189.95517)
		(width 0.381)
		(layer "B.Cu")
		(net "PVNN_TERM_CPU1")
	)
	(segment
		(start 81.167478 -187.00115)
		(end 81.157318 -187.01131)
		(width 0.381)
		(layer "B.Cu")
		(net "PVNN_TERM_CPU1")
	)
	(segment
		(start 220.307408 -223.49714)
		(end 217.674698 -226.12985)
		(width 0.381)
		(layer "B.Cu")
		(net "PVNN_TERM_CPU1")
	)
	(segment
		(start 175.673258 -199.328278)
		(end 175.673258 -198.114158)
		(width 0.381)
		(layer "B.Cu")
		(net "PVNN_TERM_CPU1")
	)
	(segment
		(start 152.51684 -189.207648)
		(end 152.339802 -189.384686)
		(width 0.381)
		(layer "B.Cu")
		(net "PVNN_TERM_CPU1")
	)
	(segment
		(start 85.257386 -147.17395)
		(end 85.257386 -107.305348)
		(width 0.508)
		(layer "B.Cu")
		(net "PVNN_TERM_CPU1")
	)
	(segment
		(start 38.3032 -130.053334)
		(end 38.891718 -130.053334)
		(width 0.381)
		(layer "B.Cu")
		(net "PVNN_TERM_CPU1")
	)
	(segment
		(start 175.464978 -192.79997)
		(end 175.464978 -194.63131)
		(width 0.381)
		(layer "B.Cu")
		(net "PVNN_TERM_CPU1")
	)
	(segment
		(start 72.208898 -181.86781)
		(end 71.65848 -182.418228)
		(width 0.381)
		(layer "B.Cu")
		(net "PVNN_TERM_CPU1")
	)
	(segment
		(start 79.182468 -153.248868)
		(end 85.257386 -147.17395)
		(width 0.508)
		(layer "B.Cu")
		(net "PVNN_TERM_CPU1")
	)
	(segment
		(start 154.790394 -90.219276)
		(end 158.550864 -93.979746)
		(width 0.508)
		(layer "B.Cu")
		(net "PVNN_TERM_CPU1")
	)
	(segment
		(start 85.122004 -185.603642)
		(end 85.122004 -184.994042)
		(width 0.381)
		(layer "B.Cu")
		(net "PVNN_TERM_CPU1")
	)
	(segment
		(start 74.0664 -179.111148)
		(end 74.235818 -178.94173)
		(width 0.381)
		(layer "B.Cu")
		(net "PVNN_TERM_CPU1")
	)
	(segment
		(start 68.090542 -185.391806)
		(end 68.337684 -185.391806)
		(width 0.381)
		(layer "B.Cu")
		(net "PVNN_TERM_CPU1")
	)
	(segment
		(start 201.6252 -101.145848)
		(end 202.06208 -101.145848)
		(width 0.508)
		(layer "B.Cu")
		(net "PVNN_TERM_CPU1")
	)
	(segment
		(start 98.273108 -189.134496)
		(end 98.273108 -190.305182)
		(width 0.381)
		(layer "B.Cu")
		(net "PVNN_TERM_CPU1")
	)
	(segment
		(start 122.05081 -93.690948)
		(end 124.64288 -93.690948)
		(width 0.508)
		(layer "B.Cu")
		(net "PVNN_TERM_CPU1")
	)
	(segment
		(start 165.754558 -252.08611)
		(end 165.985952 -251.854716)
		(width 0.381)
		(layer "B.Cu")
		(net "PVNN_TERM_CPU1")
	)
	(segment
		(start 67.056 -184.470548)
		(end 67.056 -183.968898)
		(width 0.381)
		(layer "B.Cu")
		(net "PVNN_TERM_CPU1")
	)
	(segment
		(start 120.779032 -91.253564)
		(end 123.265946 -88.76665)
		(width 0.508)
		(layer "B.Cu")
		(net "PVNN_TERM_CPU1")
	)
	(segment
		(start 152.339802 -189.384686)
		(end 152.339802 -189.959234)
		(width 0.381)
		(layer "B.Cu")
		(net "PVNN_TERM_CPU1")
	)
	(segment
		(start 179.168552 -192.299844)
		(end 178.145948 -192.299844)
		(width 0.381)
		(layer "B.Cu")
		(net "PVNN_TERM_CPU1")
	)
	(segment
		(start 154.4955 -190.47206)
		(end 154.4955 -189.448948)
		(width 0.381)
		(layer "B.Cu")
		(net "PVNN_TERM_CPU1")
	)
	(segment
		(start 80.430624 -186.274202)
		(end 80.430624 -186.691524)
		(width 0.381)
		(layer "B.Cu")
		(net "PVNN_TERM_CPU1")
	)
	(segment
		(start 69.342 -188.869066)
		(end 68.97878 -189.232286)
		(width 0.381)
		(layer "B.Cu")
		(net "PVNN_TERM_CPU1")
	)
	(segment
		(start 94.516702 -185.37809)
		(end 98.273108 -189.134496)
		(width 0.381)
		(layer "B.Cu")
		(net "PVNN_TERM_CPU1")
	)
	(segment
		(start 17.017746 -193.843656)
		(end 16.669512 -194.19189)
		(width 0.381)
		(layer "B.Cu")
		(net "PVNN_TERM_CPU1")
	)
	(segment
		(start 165.754558 -254.19685)
		(end 165.754558 -252.08611)
		(width 0.381)
		(layer "B.Cu")
		(net "PVNN_TERM_CPU1")
	)
	(segment
		(start 99.906836 -357.53167)
		(end 99.297236 -357.53167)
		(width 0.381)
		(layer "B.Cu")
		(net "PVNN_TERM_CPU1")
	)
	(segment
		(start 48.000412 -192.24117)
		(end 48.000412 -192.510156)
		(width 0.381)
		(layer "B.Cu")
		(net "PVNN_TERM_CPU1")
	)
	(segment
		(start 15.078202 -193.82486)
		(end 13.931138 -193.82486)
		(width 0.381)
		(layer "B.Cu")
		(net "PVNN_TERM_CPU1")
	)
	(segment
		(start 80.430624 -186.691524)
		(end 80.74025 -187.00115)
		(width 0.381)
		(layer "B.Cu")
		(net "PVNN_TERM_CPU1")
	)
	(segment
		(start 105.988866 -101.626162)
		(end 119.242586 -101.626162)
		(width 0.508)
		(layer "B.Cu")
		(net "PVNN_TERM_CPU1")
	)
	(segment
		(start 73.052178 -191.760348)
		(end 73.052178 -191.383412)
		(width 0.381)
		(layer "B.Cu")
		(net "PVNN_TERM_CPU1")
	)
	(segment
		(start 133.01218 -93.282008)
		(end 132.346192 -92.61602)
		(width 0.508)
		(layer "B.Cu")
		(net "PVNN_TERM_CPU1")
	)
	(segment
		(start 177.123344 -192.299844)
		(end 176.10074 -192.299844)
		(width 0.381)
		(layer "B.Cu")
		(net "PVNN_TERM_CPU1")
	)
	(segment
		(start 155.713938 -188.622432)
		(end 155.38704 -188.94933)
		(width 0.381)
		(layer "B.Cu")
		(net "PVNN_TERM_CPU1")
	)
	(segment
		(start 199.00138 -98.522028)
		(end 201.6252 -101.145848)
		(width 0.508)
		(layer "B.Cu")
		(net "PVNN_TERM_CPU1")
	)
	(segment
		(start 15.445232 -194.19189)
		(end 15.078202 -193.82486)
		(width 0.381)
		(layer "B.Cu")
		(net "PVNN_TERM_CPU1")
	)
	(segment
		(start 16.669512 -194.19189)
		(end 15.445232 -194.19189)
		(width 0.381)
		(layer "B.Cu")
		(net "PVNN_TERM_CPU1")
	)
	(segment
		(start 140.525754 -90.219276)
		(end 154.790394 -90.219276)
		(width 0.508)
		(layer "B.Cu")
		(net "PVNN_TERM_CPU1")
	)
	(segment
		(start 120.8786 -98.034348)
		(end 120.1674 -97.323148)
		(width 0.508)
		(layer "B.Cu")
		(net "PVNN_TERM_CPU1")
	)
	(segment
		(start 94.209108 -188.95822)
		(end 94.209108 -190.305182)
		(width 0.381)
		(layer "B.Cu")
		(net "PVNN_TERM_CPU1")
	)
	(segment
		(start 73.052178 -191.383412)
		(end 73.316084 -191.119506)
		(width 0.381)
		(layer "B.Cu")
		(net "PVNN_TERM_CPU1")
	)
	(segment
		(start 85.457284 -190.305182)
		(end 85.457284 -189.607444)
		(width 0.381)
		(layer "B.Cu")
		(net "PVNN_TERM_CPU1")
	)
	(segment
		(start 17.35201 -193.843656)
		(end 17.017746 -193.843656)
		(width 0.381)
		(layer "B.Cu")
		(net "PVNN_TERM_CPU1")
	)
	(segment
		(start 71.65848 -182.851298)
		(end 71.711058 -182.903876)
		(width 0.381)
		(layer "B.Cu")
		(net "PVNN_TERM_CPU1")
	)
	(segment
		(start 179.841398 -189.204346)
		(end 179.841398 -190.32855)
		(width 0.381)
		(layer "B.Cu")
		(net "PVNN_TERM_CPU1")
	)
	(segment
		(start 68.97878 -189.969902)
		(end 69.404484 -190.395606)
		(width 0.381)
		(layer "B.Cu")
		(net "PVNN_TERM_CPU1")
	)
	(segment
		(start 51.714908 -192.85966)
		(end 51.714908 -192.24117)
		(width 0.381)
		(layer "B.Cu")
		(net "PVNN_TERM_CPU1")
	)
	(segment
		(start 217.674698 -255.56845)
		(end 216.996518 -256.24663)
		(width 0.381)
		(layer "B.Cu")
		(net "PVNN_TERM_CPU1")
	)
	(segment
		(start 77.625448 -158.12262)
		(end 78.07452 -157.673548)
		(width 0.508)
		(layer "B.Cu")
		(net "PVNN_TERM_CPU1")
	)
	(segment
		(start 119.242586 -101.626162)
		(end 120.8786 -99.990148)
		(width 0.508)
		(layer "B.Cu")
		(net "PVNN_TERM_CPU1")
	)
	(segment
		(start 77.368908 -185.526426)
		(end 77.368908 -184.903872)
		(width 0.381)
		(layer "B.Cu")
		(net "PVNN_TERM_CPU1")
	)
	(segment
		(start 175.965104 -192.299844)
		(end 175.464978 -192.79997)
		(width 0.381)
		(layer "B.Cu")
		(net "PVNN_TERM_CPU1")
	)
	(segment
		(start 175.71212 -94.628208)
		(end 176.360582 -93.979746)
		(width 0.508)
		(layer "B.Cu")
		(net "PVNN_TERM_CPU1")
	)
	(segment
		(start 68.97878 -189.232286)
		(end 68.97878 -189.591188)
		(width 0.381)
		(layer "B.Cu")
		(net "PVNN_TERM_CPU1")
	)
	(segment
		(start 102.06228 -105.552748)
		(end 105.988866 -101.626162)
		(width 0.508)
		(layer "B.Cu")
		(net "PVNN_TERM_CPU1")
	)
	(segment
		(start 176.10074 -192.299844)
		(end 175.965104 -192.299844)
		(width 0.381)
		(layer "B.Cu")
		(net "PVNN_TERM_CPU1")
	)
	(segment
		(start 75.460098 -183.855868)
		(end 75.460098 -183.197246)
		(width 0.3048)
		(layer "B.Cu")
		(net "PVNN_TERM_CPU1")
	)
	(segment
		(start 133.01218 -93.698568)
		(end 133.01218 -93.282008)
		(width 0.508)
		(layer "B.Cu")
		(net "PVNN_TERM_CPU1")
	)
	(segment
		(start 48.666908 -192.85966)
		(end 48.666908 -192.237106)
		(width 0.381)
		(layer "B.Cu")
		(net "PVNN_TERM_CPU1")
	)
	(segment
		(start 87.009986 -105.552748)
		(end 102.06228 -105.552748)
		(width 0.508)
		(layer "B.Cu")
		(net "PVNN_TERM_CPU1")
	)
	(segment
		(start 81.446624 -186.274202)
		(end 80.430624 -186.274202)
		(width 0.381)
		(layer "B.Cu")
		(net "PVNN_TERM_CPU1")
	)
	(segment
		(start 132.51688 -94.193868)
		(end 133.01218 -93.698568)
		(width 0.508)
		(layer "B.Cu")
		(net "PVNN_TERM_CPU1")
	)
	(segment
		(start 91.161108 -187.89777)
		(end 93.148658 -187.89777)
		(width 0.381)
		(layer "B.Cu")
		(net "PVNN_TERM_CPU1")
	)
	(segment
		(start 91.38666 -185.37809)
		(end 94.516702 -185.37809)
		(width 0.381)
		(layer "B.Cu")
		(net "PVNN_TERM_CPU1")
	)
	(segment
		(start 53.746908 -192.85966)
		(end 53.746908 -192.24117)
		(width 0.381)
		(layer "B.Cu")
		(net "PVNN_TERM_CPU1")
	)
	(segment
		(start 81.157318 -187.01131)
		(end 81.157318 -187.759086)
		(width 0.381)
		(layer "B.Cu")
		(net "PVNN_TERM_CPU1")
	)
	(segment
		(start 123.265946 -88.76665)
		(end 139.073128 -88.76665)
		(width 0.508)
		(layer "B.Cu")
		(net "PVNN_TERM_CPU1")
	)
	(segment
		(start 78.07452 -157.394148)
		(end 79.182468 -156.2862)
		(width 0.508)
		(layer "B.Cu")
		(net "PVNN_TERM_CPU1")
	)
	(segment
		(start 121.66981 -93.309948)
		(end 122.05081 -93.690948)
		(width 0.508)
		(layer "B.Cu")
		(net "PVNN_TERM_CPU1")
	)
	(segment
		(start 91.161108 -189.58687)
		(end 91.161108 -190.305182)
		(width 0.381)
		(layer "B.Cu")
		(net "PVNN_TERM_CPU1")
	)
	(segment
		(start 38.891718 -130.053334)
		(end 39.126922 -129.81813)
		(width 0.381)
		(layer "B.Cu")
		(net "PVNN_TERM_CPU1")
	)
	(segment
		(start 68.97878 -189.591188)
		(end 68.97878 -189.969902)
		(width 0.381)
		(layer "B.Cu")
		(net "PVNN_TERM_CPU1")
	)
	(segment
		(start 155.713938 -188.338968)
		(end 155.713938 -188.622432)
		(width 0.381)
		(layer "B.Cu")
		(net "PVNN_TERM_CPU1")
	)
	(segment
		(start 80.74025 -187.00115)
		(end 81.167478 -187.00115)
		(width 0.381)
		(layer "B.Cu")
		(net "PVNN_TERM_CPU1")
	)
	(segment
		(start 85.257386 -107.305348)
		(end 87.009986 -105.552748)
		(width 0.508)
		(layer "B.Cu")
		(net "PVNN_TERM_CPU1")
	)
	(segment
		(start 192.99428 -98.522028)
		(end 199.00138 -98.522028)
		(width 0.508)
		(layer "B.Cu")
		(net "PVNN_TERM_CPU1")
	)
	(segment
		(start 70.994778 -185.0009)
		(end 71.385684 -185.391806)
		(width 0.381)
		(layer "B.Cu")
		(net "PVNN_TERM_CPU1")
	)
	(segment
		(start 74.235818 -178.94173)
		(end 74.850498 -178.94173)
		(width 0.381)
		(layer "B.Cu")
		(net "PVNN_TERM_CPU1")
	)
	(segment
		(start 91.161108 -190.305182)
		(end 92.177108 -190.305182)
		(width 0.381)
		(layer "B.Cu")
		(net "PVNN_TERM_CPU1")
	)
	(segment
		(start 216.996518 -256.24663)
		(end 207.210406 -256.24663)
		(width 0.381)
		(layer "B.Cu")
		(net "PVNN_TERM_CPU1")
	)
	(segment
		(start 171.577 -93.979746)
		(end 172.225462 -94.628208)
		(width 0.508)
		(layer "B.Cu")
		(net "PVNN_TERM_CPU1")
	)
	(segment
		(start 120.779032 -91.253564)
		(end 123.216416 -93.690948)
		(width 0.508)
		(layer "In2.Cu")
		(net "PVNN_TERM_CPU1")
	)
	(segment
		(start 123.216416 -93.690948)
		(end 124.64288 -93.690948)
		(width 0.508)
		(layer "In2.Cu")
		(net "PVNN_TERM_CPU1")
	)
	(segment
		(start 226.795838 -220.91523)
		(end 225.233738 -220.91523)
		(width 0.508)
		(layer "In4.Cu")
		(net "PVNN_TERM_CPU1")
	)
	(segment
		(start 195.20408 -349.367348)
		(end 207.385666 -349.367348)
		(width 0.508)
		(layer "In4.Cu")
		(net "PVNN_TERM_CPU1")
	)
	(segment
		(start 225.233738 -220.91523)
		(end 224.725738 -221.42323)
		(width 0.508)
		(layer "In4.Cu")
		(net "PVNN_TERM_CPU1")
	)
	(segment
		(start 220.055694 -226.502214)
		(end 223.060768 -223.49714)
		(width 0.508)
		(layer "In4.Cu")
		(net "PVNN_TERM_CPU1")
	)
	(segment
		(start 220.055694 -341.388446)
		(end 220.055694 -226.502214)
		(width 0.508)
		(layer "In4.Cu")
		(net "PVNN_TERM_CPU1")
	)
	(segment
		(start 224.725738 -221.42323)
		(end 224.725738 -222.49511)
		(width 0.508)
		(layer "In4.Cu")
		(net "PVNN_TERM_CPU1")
	)
	(segment
		(start 210.635088 -346.117926)
		(end 215.326214 -346.117926)
		(width 0.508)
		(layer "In4.Cu")
		(net "PVNN_TERM_CPU1")
	)
	(segment
		(start 215.326214 -346.117926)
		(end 220.055694 -341.388446)
		(width 0.508)
		(layer "In4.Cu")
		(net "PVNN_TERM_CPU1")
	)
	(segment
		(start 207.385666 -349.367348)
		(end 210.635088 -346.117926)
		(width 0.508)
		(layer "In4.Cu")
		(net "PVNN_TERM_CPU1")
	)
	(segment
		(start 224.725738 -222.49511)
		(end 223.723708 -223.49714)
		(width 0.508)
		(layer "In4.Cu")
		(net "PVNN_TERM_CPU1")
	)
	(segment
		(start 223.723708 -223.49714)
		(end 223.060768 -223.49714)
		(width 0.508)
		(layer "In4.Cu")
		(net "PVNN_TERM_CPU1")
	)
	(segment
		(start 227.303838 -221.42323)
		(end 226.795838 -220.91523)
		(width 0.508)
		(layer "In4.Cu")
		(net "PVNN_TERM_CPU1")
	)
	(segment
		(start 98.706178 -356.046532)
		(end 99.297236 -356.63759)
		(width 0.381)
		(layer "In6.Cu")
		(net "PVNN_TERM_CPU1")
	)
	(segment
		(start 99.808538 -355.048058)
		(end 99.087178 -355.048058)
		(width 0.381)
		(layer "In6.Cu")
		(net "PVNN_TERM_CPU1")
	)
	(segment
		(start 184.007506 -365.050324)
		(end 194.21348 -354.84435)
		(width 0.381)
		(layer "In6.Cu")
		(net "PVNN_TERM_CPU1")
	)
	(segment
		(start 130.09499 -368.982244)
		(end 130.867404 -368.20983)
		(width 0.381)
		(layer "In6.Cu")
		(net "PVNN_TERM_CPU1")
	)
	(segment
		(start 194.21348 -354.84435)
		(end 194.21348 -350.357948)
		(width 0.381)
		(layer "In6.Cu")
		(net "PVNN_TERM_CPU1")
	)
	(segment
		(start 106.94289 -362.020104)
		(end 107.741466 -362.020104)
		(width 0.381)
		(layer "In6.Cu")
		(net "PVNN_TERM_CPU1")
	)
	(segment
		(start 109.02188 -363.300518)
		(end 109.02188 -365.661956)
		(width 0.381)
		(layer "In6.Cu")
		(net "PVNN_TERM_CPU1")
	)
	(segment
		(start 107.741466 -362.020104)
		(end 109.02188 -363.300518)
		(width 0.381)
		(layer "In6.Cu")
		(net "PVNN_TERM_CPU1")
	)
	(segment
		(start 100.161344 -353.458272)
		(end 102.29088 -353.458272)
		(width 0.381)
		(layer "In6.Cu")
		(net "PVNN_TERM_CPU1")
	)
	(segment
		(start 133.118606 -363.1565)
		(end 158.142432 -363.1565)
		(width 0.381)
		(layer "In6.Cu")
		(net "PVNN_TERM_CPU1")
	)
	(segment
		(start 130.867404 -365.407702)
		(end 133.118606 -363.1565)
		(width 0.381)
		(layer "In6.Cu")
		(net "PVNN_TERM_CPU1")
	)
	(segment
		(start 109.02188 -365.661956)
		(end 113.049304 -369.68938)
		(width 0.381)
		(layer "In6.Cu")
		(net "PVNN_TERM_CPU1")
	)
	(segment
		(start 102.29088 -353.458272)
		(end 105.61193 -356.779322)
		(width 0.381)
		(layer "In6.Cu")
		(net "PVNN_TERM_CPU1")
	)
	(segment
		(start 99.087178 -355.048058)
		(end 98.706178 -355.429058)
		(width 0.381)
		(layer "In6.Cu")
		(net "PVNN_TERM_CPU1")
	)
	(segment
		(start 99.808538 -353.811078)
		(end 100.161344 -353.458272)
		(width 0.381)
		(layer "In6.Cu")
		(net "PVNN_TERM_CPU1")
	)
	(segment
		(start 99.297236 -356.63759)
		(end 99.297236 -357.53167)
		(width 0.508)
		(layer "In6.Cu")
		(net "PVNN_TERM_CPU1")
	)
	(segment
		(start 105.61193 -356.779322)
		(end 105.61193 -360.689144)
		(width 0.381)
		(layer "In6.Cu")
		(net "PVNN_TERM_CPU1")
	)
	(segment
		(start 161.692082 -366.70615)
		(end 180.010054 -366.70615)
		(width 0.381)
		(layer "In6.Cu")
		(net "PVNN_TERM_CPU1")
	)
	(segment
		(start 120.434862 -368.982244)
		(end 130.09499 -368.982244)
		(width 0.381)
		(layer "In6.Cu")
		(net "PVNN_TERM_CPU1")
	)
	(segment
		(start 194.21348 -350.357948)
		(end 195.20408 -349.367348)
		(width 0.381)
		(layer "In6.Cu")
		(net "PVNN_TERM_CPU1")
	)
	(segment
		(start 180.010054 -366.70615)
		(end 184.007506 -365.050324)
		(width 0.381)
		(layer "In6.Cu")
		(net "PVNN_TERM_CPU1")
	)
	(segment
		(start 119.727726 -369.68938)
		(end 120.434862 -368.982244)
		(width 0.381)
		(layer "In6.Cu")
		(net "PVNN_TERM_CPU1")
	)
	(segment
		(start 158.142432 -363.1565)
		(end 161.692082 -366.70615)
		(width 0.381)
		(layer "In6.Cu")
		(net "PVNN_TERM_CPU1")
	)
	(segment
		(start 98.706178 -355.429058)
		(end 98.706178 -356.046532)
		(width 0.381)
		(layer "In6.Cu")
		(net "PVNN_TERM_CPU1")
	)
	(segment
		(start 105.61193 -360.689144)
		(end 106.94289 -362.020104)
		(width 0.381)
		(layer "In6.Cu")
		(net "PVNN_TERM_CPU1")
	)
	(segment
		(start 99.808538 -355.048058)
		(end 99.808538 -353.811078)
		(width 0.381)
		(layer "In6.Cu")
		(net "PVNN_TERM_CPU1")
	)
	(segment
		(start 130.867404 -368.20983)
		(end 130.867404 -365.407702)
		(width 0.381)
		(layer "In6.Cu")
		(net "PVNN_TERM_CPU1")
	)
	(segment
		(start 113.049304 -369.68938)
		(end 119.727726 -369.68938)
		(width 0.381)
		(layer "In6.Cu")
		(net "PVNN_TERM_CPU1")
	)
	(segment
		(start 37.072316 -130.053334)
		(end 38.3032 -130.053334)
		(width 0.508)
		(layer "In11.Cu")
		(net "PVNN_TERM_CPU1")
	)
	(segment
		(start 36.624006 -137.252456)
		(end 36.624006 -130.501644)
		(width 0.508)
		(layer "In11.Cu")
		(net "PVNN_TERM_CPU1")
	)
	(segment
		(start 82.505042 -145.948908)
		(end 78.389734 -141.8336)
		(width 0.508)
		(layer "In11.Cu")
		(net "PVNN_TERM_CPU1")
	)
	(segment
		(start 82.505042 -156.40558)
		(end 82.505042 -145.948908)
		(width 0.508)
		(layer "In11.Cu")
		(net "PVNN_TERM_CPU1")
	)
	(segment
		(start 77.038454 -138.91641)
		(end 38.28796 -138.91641)
		(width 0.508)
		(layer "In11.Cu")
		(net "PVNN_TERM_CPU1")
	)
	(segment
		(start 78.389734 -141.8336)
		(end 78.389734 -140.26769)
		(width 0.508)
		(layer "In11.Cu")
		(net "PVNN_TERM_CPU1")
	)
	(segment
		(start 78.389734 -140.26769)
		(end 77.038454 -138.91641)
		(width 0.508)
		(layer "In11.Cu")
		(net "PVNN_TERM_CPU1")
	)
	(segment
		(start 36.624006 -130.501644)
		(end 37.072316 -130.053334)
		(width 0.508)
		(layer "In11.Cu")
		(net "PVNN_TERM_CPU1")
	)
	(segment
		(start 38.28796 -138.91641)
		(end 36.624006 -137.252456)
		(width 0.508)
		(layer "In11.Cu")
		(net "PVNN_TERM_CPU1")
	)
	(segment
		(start 80.616044 -158.294578)
		(end 82.505042 -156.40558)
		(width 0.508)
		(layer "In11.Cu")
		(net "PVNN_TERM_CPU1")
	)
	(segment
		(start 211.983828 -38.373558)
		(end 211.087716 -39.26967)
		(width 0.508)
		(layer "F.Cu")
		(net "PVNN_TERM_CPU0")
	)
	(segment
		(start 248.17832 -335.587848)
		(end 248.17832 -324.197472)
		(width 0.508)
		(layer "F.Cu")
		(net "PVNN_TERM_CPU0")
	)
	(segment
		(start 347.990414 -356.478332)
		(end 347.298264 -356.478332)
		(width 0.381)
		(layer "F.Cu")
		(net "PVNN_TERM_CPU0")
	)
	(segment
		(start 216.9668 -35.194748)
		(end 217.660474 -35.888422)
		(width 0.508)
		(layer "F.Cu")
		(net "PVNN_TERM_CPU0")
	)
	(segment
		(start 152.068022 -188.486288)
		(end 152.068022 -161.899854)
		(width 0.508)
		(layer "F.Cu")
		(net "PVNN_TERM_CPU0")
	)
	(segment
		(start 406.524714 -359.579926)
		(end 409.713938 -359.579926)
		(width 0.381)
		(layer "F.Cu")
		(net "PVNN_TERM_CPU0")
	)
	(segment
		(start 395.550898 -159.73044)
		(end 395.550898 -158.916624)
		(width 0.381)
		(layer "F.Cu")
		(net "PVNN_TERM_CPU0")
	)
	(segment
		(start 433.041044 -135.779256)
		(end 432.575462 -136.244838)
		(width 0.381)
		(layer "F.Cu")
		(net "PVNN_TERM_CPU0")
	)
	(segment
		(start 121.860818 -94.972886)
		(end 121.860818 -95.331026)
		(width 0.381)
		(layer "F.Cu")
		(net "PVNN_TERM_CPU0")
	)
	(segment
		(start 204.046328 -42.53738)
		(end 200.56094 -42.53738)
		(width 0.508)
		(layer "F.Cu")
		(net "PVNN_TERM_CPU0")
	)
	(segment
		(start 395.221206 -158.586932)
		(end 395.221206 -157.997652)
		(width 0.381)
		(layer "F.Cu")
		(net "PVNN_TERM_CPU0")
	)
	(segment
		(start 217.660474 -37.510466)
		(end 216.797382 -38.373558)
		(width 0.508)
		(layer "F.Cu")
		(net "PVNN_TERM_CPU0")
	)
	(segment
		(start 216.797382 -38.373558)
		(end 211.983828 -38.373558)
		(width 0.508)
		(layer "F.Cu")
		(net "PVNN_TERM_CPU0")
	)
	(segment
		(start 319.448688 -343.156032)
		(end 306.401978 -343.156032)
		(width 0.508)
		(layer "F.Cu")
		(net "PVNN_TERM_CPU0")
	)
	(segment
		(start 194.552316 -48.546004)
		(end 194.552316 -56.636412)
		(width 0.508)
		(layer "F.Cu")
		(net "PVNN_TERM_CPU0")
	)
	(segment
		(start 164.19195 -23.713948)
		(end 164.215318 -23.69058)
		(width 0.381)
		(layer "F.Cu")
		(net "PVNN_TERM_CPU0")
	)
	(segment
		(start 305.6128 -51.438556)
		(end 306.12588 -51.438556)
		(width 0.508)
		(layer "F.Cu")
		(net "PVNN_TERM_CPU0")
	)
	(segment
		(start 253.73838 -194.61734)
		(end 256.98069 -191.37503)
		(width 0.508)
		(layer "F.Cu")
		(net "PVNN_TERM_CPU0")
	)
	(segment
		(start 394.907262 -159.73044)
		(end 395.550898 -159.73044)
		(width 0.381)
		(layer "F.Cu")
		(net "PVNN_TERM_CPU0")
	)
	(segment
		(start 182.80888 -56.792368)
		(end 182.80888 -55.916068)
		(width 0.508)
		(layer "F.Cu")
		(net "PVNN_TERM_CPU0")
	)
	(segment
		(start 256.98069 -191.37503)
		(end 274.559014 -191.37503)
		(width 0.508)
		(layer "F.Cu")
		(net "PVNN_TERM_CPU0")
	)
	(segment
		(start 120.57888 -93.690948)
		(end 121.05259 -94.164658)
		(width 0.381)
		(layer "F.Cu")
		(net "PVNN_TERM_CPU0")
	)
	(segment
		(start 371.055646 -87.205058)
		(end 370.1034 -88.157304)
		(width 0.508)
		(layer "F.Cu")
		(net "PVNN_TERM_CPU0")
	)
	(segment
		(start 275.497798 -190.436246)
		(end 275.497798 -189.13729)
		(width 0.508)
		(layer "F.Cu")
		(net "PVNN_TERM_CPU0")
	)
	(segment
		(start 164.19195 -23.123144)
		(end 164.19195 -22.664928)
		(width 0.381)
		(layer "F.Cu")
		(net "PVNN_TERM_CPU0")
	)
	(segment
		(start 347.990414 -357.494332)
		(end 347.298264 -357.494332)
		(width 0.381)
		(layer "F.Cu")
		(net "PVNN_TERM_CPU0")
	)
	(segment
		(start 120.57888 -93.074998)
		(end 120.57888 -93.690948)
		(width 0.381)
		(layer "F.Cu")
		(net "PVNN_TERM_CPU0")
	)
	(segment
		(start 440.271916 -124.680726)
		(end 440.393582 -124.802392)
		(width 0.381)
		(layer "F.Cu")
		(net "PVNN_TERM_CPU0")
	)
	(segment
		(start 432.914044 -139.066016)
		(end 432.80584 -138.957812)
		(width 0.381)
		(layer "F.Cu")
		(net "PVNN_TERM_CPU0")
	)
	(segment
		(start 306.401978 -343.156032)
		(end 304.383694 -341.137748)
		(width 0.508)
		(layer "F.Cu")
		(net "PVNN_TERM_CPU0")
	)
	(segment
		(start 128.70688 -94.198948)
		(end 128.70688 -93.690948)
		(width 0.381)
		(layer "F.Cu")
		(net "PVNN_TERM_CPU0")
	)
	(segment
		(start 432.575462 -136.244838)
		(end 432.38928 -136.244838)
		(width 0.381)
		(layer "F.Cu")
		(net "PVNN_TERM_CPU0")
	)
	(segment
		(start 137.597388 -144.5133)
		(end 137.597388 -144.285716)
		(width 0.508)
		(layer "F.Cu")
		(net "PVNN_TERM_CPU0")
	)
	(segment
		(start 88.842088 -178.900836)
		(end 88.842088 -179.267866)
		(width 0.381)
		(layer "F.Cu")
		(net "PVNN_TERM_CPU0")
	)
	(segment
		(start 440.93257 -124.802392)
		(end 441.099194 -124.635768)
		(width 0.381)
		(layer "F.Cu")
		(net "PVNN_TERM_CPU0")
	)
	(segment
		(start 391.963148 -161.07791)
		(end 391.255758 -161.07791)
		(width 0.381)
		(layer "F.Cu")
		(net "PVNN_TERM_CPU0")
	)
	(segment
		(start 128.45288 -102.431088)
		(end 128.845818 -102.824026)
		(width 0.381)
		(layer "F.Cu")
		(net "PVNN_TERM_CPU0")
	)
	(segment
		(start 200.56094 -42.53738)
		(end 194.552316 -48.546004)
		(width 0.508)
		(layer "F.Cu")
		(net "PVNN_TERM_CPU0")
	)
	(segment
		(start 440.280044 -123.656598)
		(end 440.976004 -123.656598)
		(width 0.381)
		(layer "F.Cu")
		(net "PVNN_TERM_CPU0")
	)
	(segment
		(start 164.215318 -23.69058)
		(end 164.215318 -23.146512)
		(width 0.381)
		(layer "F.Cu")
		(net "PVNN_TERM_CPU0")
	)
	(segment
		(start 183.2102 -57.193688)
		(end 182.80888 -56.792368)
		(width 0.508)
		(layer "F.Cu")
		(net "PVNN_TERM_CPU0")
	)
	(segment
		(start 439.662316 -124.680726)
		(end 440.271916 -124.680726)
		(width 0.381)
		(layer "F.Cu")
		(net "PVNN_TERM_CPU0")
	)
	(segment
		(start 138.919204 -148.751036)
		(end 138.919204 -145.835116)
		(width 0.508)
		(layer "F.Cu")
		(net "PVNN_TERM_CPU0")
	)
	(segment
		(start 128.45288 -100.567998)
		(end 128.45288 -101.183948)
		(width 0.381)
		(layer "F.Cu")
		(net "PVNN_TERM_CPU0")
	)
	(segment
		(start 304.383694 -341.137748)
		(end 253.72822 -341.137748)
		(width 0.508)
		(layer "F.Cu")
		(net "PVNN_TERM_CPU0")
	)
	(segment
		(start 433.665884 -139.066016)
		(end 432.914044 -139.066016)
		(width 0.381)
		(layer "F.Cu")
		(net "PVNN_TERM_CPU0")
	)
	(segment
		(start 181.15788 -96.719898)
		(end 181.15788 -96.103948)
		(width 0.381)
		(layer "F.Cu")
		(net "PVNN_TERM_CPU0")
	)
	(segment
		(start 253.562104 -296.739056)
		(end 252.871478 -296.04843)
		(width 0.508)
		(layer "F.Cu")
		(net "PVNN_TERM_CPU0")
	)
	(segment
		(start 207.314038 -39.26967)
		(end 204.046328 -42.53738)
		(width 0.508)
		(layer "F.Cu")
		(net "PVNN_TERM_CPU0")
	)
	(segment
		(start 439.662316 -123.664726)
		(end 440.271916 -123.664726)
		(width 0.381)
		(layer "F.Cu")
		(net "PVNN_TERM_CPU0")
	)
	(segment
		(start 217.660474 -35.888422)
		(end 217.660474 -37.510466)
		(width 0.508)
		(layer "F.Cu")
		(net "PVNN_TERM_CPU0")
	)
	(segment
		(start 211.087716 -39.26967)
		(end 207.314038 -39.26967)
		(width 0.508)
		(layer "F.Cu")
		(net "PVNN_TERM_CPU0")
	)
	(segment
		(start 121.05259 -94.164658)
		(end 121.860818 -94.972886)
		(width 0.381)
		(layer "F.Cu")
		(net "PVNN_TERM_CPU0")
	)
	(segment
		(start 440.271916 -123.664726)
		(end 440.280044 -123.656598)
		(width 0.381)
		(layer "F.Cu")
		(net "PVNN_TERM_CPU0")
	)
	(segment
		(start 129.353818 -95.331026)
		(end 129.353818 -94.845886)
		(width 0.381)
		(layer "F.Cu")
		(net "PVNN_TERM_CPU0")
	)
	(segment
		(start 194.552316 -56.636412)
		(end 193.99504 -57.193688)
		(width 0.508)
		(layer "F.Cu")
		(net "PVNN_TERM_CPU0")
	)
	(segment
		(start 88.61552 -178.674268)
		(end 88.842088 -178.900836)
		(width 0.381)
		(layer "F.Cu")
		(net "PVNN_TERM_CPU0")
	)
	(segment
		(start 370.1034 -88.157304)
		(end 370.1034 -91.557602)
		(width 0.508)
		(layer "F.Cu")
		(net "PVNN_TERM_CPU0")
	)
	(segment
		(start 306.63388 -51.946556)
		(end 306.63388 -52.650898)
		(width 0.508)
		(layer "F.Cu")
		(net "PVNN_TERM_CPU0")
	)
	(segment
		(start 440.393582 -124.802392)
		(end 440.93257 -124.802392)
		(width 0.381)
		(layer "F.Cu")
		(net "PVNN_TERM_CPU0")
	)
	(segment
		(start 348.004892 -355.359462)
		(end 347.298264 -355.359462)
		(width 0.381)
		(layer "F.Cu")
		(net "PVNN_TERM_CPU0")
	)
	(segment
		(start 370.4082 -91.862402)
		(end 370.4082 -92.554298)
		(width 0.3556)
		(layer "F.Cu")
		(net "PVNN_TERM_CPU0")
	)
	(segment
		(start 253.72822 -341.137748)
		(end 248.17832 -335.587848)
		(width 0.508)
		(layer "F.Cu")
		(net "PVNN_TERM_CPU0")
	)
	(segment
		(start 128.70688 -93.074998)
		(end 128.70688 -93.690948)
		(width 0.381)
		(layer "F.Cu")
		(net "PVNN_TERM_CPU0")
	)
	(segment
		(start 129.353818 -94.845886)
		(end 128.70688 -94.198948)
		(width 0.381)
		(layer "F.Cu")
		(net "PVNN_TERM_CPU0")
	)
	(segment
		(start 395.550898 -158.916624)
		(end 395.221206 -158.586932)
		(width 0.381)
		(layer "F.Cu")
		(net "PVNN_TERM_CPU0")
	)
	(segment
		(start 274.559014 -191.37503)
		(end 275.497798 -190.436246)
		(width 0.508)
		(layer "F.Cu")
		(net "PVNN_TERM_CPU0")
	)
	(segment
		(start 164.39388 -24.619966)
		(end 164.19195 -24.418036)
		(width 0.381)
		(layer "F.Cu")
		(net "PVNN_TERM_CPU0")
	)
	(segment
		(start 253.73838 -203.081128)
		(end 253.73838 -194.61734)
		(width 0.508)
		(layer "F.Cu")
		(net "PVNN_TERM_CPU0")
	)
	(segment
		(start 248.17832 -324.197472)
		(end 253.562104 -318.813688)
		(width 0.508)
		(layer "F.Cu")
		(net "PVNN_TERM_CPU0")
	)
	(segment
		(start 193.99504 -57.193688)
		(end 183.2102 -57.193688)
		(width 0.508)
		(layer "F.Cu")
		(net "PVNN_TERM_CPU0")
	)
	(segment
		(start 253.562104 -318.813688)
		(end 253.562104 -296.739056)
		(width 0.508)
		(layer "F.Cu")
		(net "PVNN_TERM_CPU0")
	)
	(segment
		(start 164.19195 -24.418036)
		(end 164.19195 -23.713948)
		(width 0.381)
		(layer "F.Cu")
		(net "PVNN_TERM_CPU0")
	)
	(segment
		(start 306.12588 -51.438556)
		(end 306.63388 -51.946556)
		(width 0.508)
		(layer "F.Cu")
		(net "PVNN_TERM_CPU0")
	)
	(segment
		(start 252.871478 -296.04843)
		(end 252.871478 -203.94803)
		(width 0.508)
		(layer "F.Cu")
		(net "PVNN_TERM_CPU0")
	)
	(segment
		(start 252.871478 -203.94803)
		(end 253.73838 -203.081128)
		(width 0.508)
		(layer "F.Cu")
		(net "PVNN_TERM_CPU0")
	)
	(segment
		(start 138.919204 -145.835116)
		(end 137.597388 -144.5133)
		(width 0.508)
		(layer "F.Cu")
		(net "PVNN_TERM_CPU0")
	)
	(segment
		(start 128.45288 -101.183948)
		(end 128.45288 -102.431088)
		(width 0.381)
		(layer "F.Cu")
		(net "PVNN_TERM_CPU0")
	)
	(segment
		(start 152.068022 -161.899854)
		(end 138.919204 -148.751036)
		(width 0.508)
		(layer "F.Cu")
		(net "PVNN_TERM_CPU0")
	)
	(segment
		(start 306.63388 -52.650898)
		(end 307.77688 -52.650898)
		(width 0.508)
		(layer "F.Cu")
		(net "PVNN_TERM_CPU0")
	)
	(segment
		(start 370.1034 -91.557602)
		(end 370.4082 -91.862402)
		(width 0.508)
		(layer "F.Cu")
		(net "PVNN_TERM_CPU0")
	)
	(segment
		(start 164.19195 -22.664928)
		(end 164.67328 -22.183598)
		(width 0.381)
		(layer "F.Cu")
		(net "PVNN_TERM_CPU0")
	)
	(segment
		(start 394.541248 -161.07791)
		(end 394.541248 -161.75101)
		(width 0.381)
		(layer "F.Cu")
		(net "PVNN_TERM_CPU0")
	)
	(segment
		(start 164.215318 -23.146512)
		(end 164.19195 -23.123144)
		(width 0.381)
		(layer "F.Cu")
		(net "PVNN_TERM_CPU0")
	)
	(via
		(at 409.140152 -192.074546)
		(size 0.508)
		(drill 0.254)
		(layers "F.Cu" "B.Cu")
		(net "PVNN_TERM_CPU0")
	)
	(via
		(at 406.00376 -187.119768)
		(size 0.508)
		(drill 0.254)
		(layers "F.Cu" "B.Cu")
		(net "PVNN_TERM_CPU0")
	)
	(via
		(at 320.925444 -187.947046)
		(size 0.508)
		(drill 0.254)
		(layers "F.Cu" "B.Cu")
		(net "PVNN_TERM_CPU0")
	)
	(via
		(at 318.90208 -189.829948)
		(size 0.508)
		(drill 0.254)
		(layers "F.Cu" "B.Cu")
		(net "PVNN_TERM_CPU0")
	)
	(via
		(at 277.748238 -189.14237)
		(size 0.508)
		(drill 0.254)
		(layers "F.Cu" "B.Cu")
		(net "PVNN_TERM_CPU0")
	)
	(via
		(at 394.541248 -161.75101)
		(size 0.508)
		(drill 0.254)
		(layers "F.Cu" "B.Cu")
		(net "PVNN_TERM_CPU0")
	)
	(via
		(at 371.055646 -87.205058)
		(size 0.508)
		(drill 0.254)
		(layers "F.Cu" "B.Cu")
		(net "PVNN_TERM_CPU0")
	)
	(via
		(at 315.871606 -96.41713)
		(size 0.508)
		(drill 0.254)
		(layers "F.Cu" "B.Cu")
		(net "PVNN_TERM_CPU0")
	)
	(via
		(at 337.44662 -189.916308)
		(size 0.508)
		(drill 0.254)
		(layers "F.Cu" "B.Cu")
		(net "PVNN_TERM_CPU0")
	)
	(via
		(at 373.593614 -183.259222)
		(size 0.508)
		(drill 0.254)
		(layers "F.Cu" "B.Cu")
		(net "PVNN_TERM_CPU0")
	)
	(via
		(at 137.597388 -144.285716)
		(size 0.508)
		(drill 0.254)
		(layers "F.Cu" "B.Cu")
		(net "PVNN_TERM_CPU0")
	)
	(via
		(at 314.71743 -56.911748)
		(size 0.508)
		(drill 0.254)
		(layers "F.Cu" "B.Cu")
		(net "PVNN_TERM_CPU0")
	)
	(via
		(at 323.996304 -185.643266)
		(size 0.508)
		(drill 0.254)
		(layers "F.Cu" "B.Cu")
		(net "PVNN_TERM_CPU0")
	)
	(via
		(at 336.60334 -189.057788)
		(size 0.508)
		(drill 0.254)
		(layers "F.Cu" "B.Cu")
		(net "PVNN_TERM_CPU0")
	)
	(via
		(at 85.261958 -181.66461)
		(size 0.508)
		(drill 0.254)
		(layers "F.Cu" "B.Cu")
		(net "PVNN_TERM_CPU0")
	)
	(via
		(at 440.271916 -123.664726)
		(size 0.508)
		(drill 0.254)
		(layers "F.Cu" "B.Cu")
		(net "PVNN_TERM_CPU0")
	)
	(via
		(at 321.968622 -58.283348)
		(size 0.508)
		(drill 0.254)
		(layers "F.Cu" "B.Cu")
		(net "PVNN_TERM_CPU0")
	)
	(via
		(at 68.6054 -184.724548)
		(size 0.508)
		(drill 0.254)
		(layers "F.Cu" "B.Cu")
		(net "PVNN_TERM_CPU0")
	)
	(via
		(at 307.664358 -189.04331)
		(size 0.508)
		(drill 0.254)
		(layers "F.Cu" "B.Cu")
		(net "PVNN_TERM_CPU0")
	)
	(via
		(at 327.643744 -186.064906)
		(size 0.508)
		(drill 0.254)
		(layers "F.Cu" "B.Cu")
		(net "PVNN_TERM_CPU0")
	)
	(via
		(at 147.41398 -97.45218)
		(size 0.508)
		(drill 0.254)
		(layers "F.Cu" "B.Cu")
		(net "PVNN_TERM_CPU0")
	)
	(via
		(at 405.2824 -187.109608)
		(size 0.508)
		(drill 0.254)
		(layers "F.Cu" "B.Cu")
		(net "PVNN_TERM_CPU0")
	)
	(via
		(at 347.298264 -355.359462)
		(size 0.508)
		(drill 0.254)
		(layers "F.Cu" "B.Cu")
		(net "PVNN_TERM_CPU0")
	)
	(via
		(at 182.80888 -55.916068)
		(size 0.508)
		(drill 0.254)
		(layers "F.Cu" "B.Cu")
		(net "PVNN_TERM_CPU0")
	)
	(via
		(at 364.802928 -87.420704)
		(size 0.508)
		(drill 0.254)
		(layers "F.Cu" "B.Cu")
		(net "PVNN_TERM_CPU0")
	)
	(via
		(at 75.761342 -181.7116)
		(size 0.508)
		(drill 0.254)
		(layers "F.Cu" "B.Cu")
		(net "PVNN_TERM_CPU0")
	)
	(via
		(at 370.887498 -185.37047)
		(size 0.508)
		(drill 0.254)
		(layers "F.Cu" "B.Cu")
		(net "PVNN_TERM_CPU0")
	)
	(via
		(at 282.754578 -189.09157)
		(size 0.508)
		(drill 0.254)
		(layers "F.Cu" "B.Cu")
		(net "PVNN_TERM_CPU0")
	)
	(via
		(at 382.205738 -189.812422)
		(size 0.508)
		(drill 0.254)
		(layers "F.Cu" "B.Cu")
		(net "PVNN_TERM_CPU0")
	)
	(via
		(at 383.448052 -187.611258)
		(size 0.508)
		(drill 0.254)
		(layers "F.Cu" "B.Cu")
		(net "PVNN_TERM_CPU0")
	)
	(via
		(at 88.61552 -178.674268)
		(size 0.508)
		(drill 0.254)
		(layers "F.Cu" "B.Cu")
		(net "PVNN_TERM_CPU0")
	)
	(via
		(at 216.9668 -35.194748)
		(size 0.508)
		(drill 0.254)
		(layers "F.Cu" "B.Cu")
		(net "PVNN_TERM_CPU0")
	)
	(via
		(at 262.355076 -39.41699)
		(size 0.508)
		(drill 0.254)
		(layers "F.Cu" "B.Cu")
		(net "PVNN_TERM_CPU0")
	)
	(via
		(at 366.550448 -360.153966)
		(size 0.508)
		(drill 0.254)
		(layers "F.Cu" "B.Cu")
		(net "PVNN_TERM_CPU0")
	)
	(via
		(at 275.497798 -189.13729)
		(size 0.508)
		(drill 0.254)
		(layers "F.Cu" "B.Cu")
		(net "PVNN_TERM_CPU0")
	)
	(via
		(at 370.259356 -188.371988)
		(size 0.508)
		(drill 0.254)
		(layers "F.Cu" "B.Cu")
		(net "PVNN_TERM_CPU0")
	)
	(via
		(at 440.271916 -124.680726)
		(size 0.508)
		(drill 0.254)
		(layers "F.Cu" "B.Cu")
		(net "PVNN_TERM_CPU0")
	)
	(via
		(at 397.451072 -179.872386)
		(size 0.508)
		(drill 0.254)
		(layers "F.Cu" "B.Cu")
		(net "PVNN_TERM_CPU0")
	)
	(via
		(at 409.713938 -359.579926)
		(size 0.508)
		(drill 0.254)
		(layers "F.Cu" "B.Cu")
		(net "PVNN_TERM_CPU0")
	)
	(via
		(at 311.99328 -192.683892)
		(size 0.508)
		(drill 0.254)
		(layers "F.Cu" "B.Cu")
		(net "PVNN_TERM_CPU0")
	)
	(via
		(at 404.56104 -187.109608)
		(size 0.508)
		(drill 0.254)
		(layers "F.Cu" "B.Cu")
		(net "PVNN_TERM_CPU0")
	)
	(via
		(at 145.193258 -139.223496)
		(size 0.508)
		(drill 0.254)
		(layers "F.Cu" "B.Cu")
		(net "PVNN_TERM_CPU0")
	)
	(via
		(at 319.448688 -343.156032)
		(size 0.508)
		(drill 0.254)
		(layers "F.Cu" "B.Cu")
		(net "PVNN_TERM_CPU0")
	)
	(via
		(at 331.517498 -186.85002)
		(size 0.508)
		(drill 0.254)
		(layers "F.Cu" "B.Cu")
		(net "PVNN_TERM_CPU0")
	)
	(via
		(at 327.79208 -189.626748)
		(size 0.508)
		(drill 0.254)
		(layers "F.Cu" "B.Cu")
		(net "PVNN_TERM_CPU0")
	)
	(via
		(at 121.05259 -94.164658)
		(size 0.508)
		(drill 0.254)
		(layers "F.Cu" "B.Cu")
		(net "PVNN_TERM_CPU0")
	)
	(via
		(at 391.255758 -161.07791)
		(size 0.508)
		(drill 0.254)
		(layers "F.Cu" "B.Cu")
		(net "PVNN_TERM_CPU0")
	)
	(via
		(at 407.108152 -192.074546)
		(size 0.508)
		(drill 0.254)
		(layers "F.Cu" "B.Cu")
		(net "PVNN_TERM_CPU0")
	)
	(via
		(at 410.156152 -192.074546)
		(size 0.508)
		(drill 0.254)
		(layers "F.Cu" "B.Cu")
		(net "PVNN_TERM_CPU0")
	)
	(via
		(at 347.298264 -356.478332)
		(size 0.508)
		(drill 0.254)
		(layers "F.Cu" "B.Cu")
		(net "PVNN_TERM_CPU0")
	)
	(via
		(at 164.39388 -24.619966)
		(size 0.508)
		(drill 0.254)
		(layers "F.Cu" "B.Cu")
		(net "PVNN_TERM_CPU0")
	)
	(via
		(at 433.665884 -139.066016)
		(size 0.508)
		(drill 0.254)
		(layers "F.Cu" "B.Cu")
		(net "PVNN_TERM_CPU0")
	)
	(via
		(at 364.088172 -185.192416)
		(size 0.508)
		(drill 0.254)
		(layers "F.Cu" "B.Cu")
		(net "PVNN_TERM_CPU0")
	)
	(via
		(at 404.09241 -191.971422)
		(size 0.508)
		(drill 0.254)
		(layers "F.Cu" "B.Cu")
		(net "PVNN_TERM_CPU0")
	)
	(via
		(at 315.53404 -192.430908)
		(size 0.508)
		(drill 0.254)
		(layers "F.Cu" "B.Cu")
		(net "PVNN_TERM_CPU0")
	)
	(via
		(at 181.15788 -96.103948)
		(size 0.508)
		(drill 0.254)
		(layers "F.Cu" "B.Cu")
		(net "PVNN_TERM_CPU0")
	)
	(via
		(at 361.338876 -351.358454)
		(size 0.508)
		(drill 0.254)
		(layers "F.Cu" "B.Cu")
		(net "PVNN_TERM_CPU0")
	)
	(via
		(at 305.6128 -51.438556)
		(size 0.508)
		(drill 0.254)
		(layers "F.Cu" "B.Cu")
		(net "PVNN_TERM_CPU0")
	)
	(via
		(at 276.036024 -47.63516)
		(size 0.508)
		(drill 0.254)
		(layers "F.Cu" "B.Cu")
		(net "PVNN_TERM_CPU0")
	)
	(via
		(at 359.923588 -157.840426)
		(size 0.508)
		(drill 0.254)
		(layers "F.Cu" "B.Cu")
		(net "PVNN_TERM_CPU0")
	)
	(via
		(at 152.068022 -188.486288)
		(size 0.508)
		(drill 0.254)
		(layers "F.Cu" "B.Cu")
		(net "PVNN_TERM_CPU0")
	)
	(via
		(at 408.124152 -192.074546)
		(size 0.508)
		(drill 0.254)
		(layers "F.Cu" "B.Cu")
		(net "PVNN_TERM_CPU0")
	)
	(via
		(at 85.208618 -184.23509)
		(size 0.508)
		(drill 0.254)
		(layers "F.Cu" "B.Cu")
		(net "PVNN_TERM_CPU0")
	)
	(via
		(at 347.298264 -357.494332)
		(size 0.508)
		(drill 0.254)
		(layers "F.Cu" "B.Cu")
		(net "PVNN_TERM_CPU0")
	)
	(via
		(at 286.504888 -189.8015)
		(size 0.508)
		(drill 0.254)
		(layers "F.Cu" "B.Cu")
		(net "PVNN_TERM_CPU0")
	)
	(via
		(at 411.172152 -192.074546)
		(size 0.508)
		(drill 0.254)
		(layers "F.Cu" "B.Cu")
		(net "PVNN_TERM_CPU0")
	)
	(via
		(at 128.45288 -101.183948)
		(size 0.508)
		(drill 0.254)
		(layers "F.Cu" "B.Cu")
		(net "PVNN_TERM_CPU0")
	)
	(via
		(at 306.516278 -189.09157)
		(size 0.508)
		(drill 0.254)
		(layers "F.Cu" "B.Cu")
		(net "PVNN_TERM_CPU0")
	)
	(via
		(at 334.01508 -187.924948)
		(size 0.508)
		(drill 0.254)
		(layers "F.Cu" "B.Cu")
		(net "PVNN_TERM_CPU0")
	)
	(via
		(at 69.353684 -186.858148)
		(size 0.508)
		(drill 0.254)
		(layers "F.Cu" "B.Cu")
		(net "PVNN_TERM_CPU0")
	)
	(via
		(at 394.907262 -159.73044)
		(size 0.508)
		(drill 0.254)
		(layers "F.Cu" "B.Cu")
		(net "PVNN_TERM_CPU0")
	)
	(via
		(at 433.041044 -135.779256)
		(size 0.508)
		(drill 0.254)
		(layers "F.Cu" "B.Cu")
		(net "PVNN_TERM_CPU0")
	)
	(via
		(at 128.70688 -93.690948)
		(size 0.508)
		(drill 0.254)
		(layers "F.Cu" "B.Cu")
		(net "PVNN_TERM_CPU0")
	)
	(segment
		(start 320.925444 -187.947046)
		(end 320.600324 -187.947046)
		(width 0.3048)
		(layer "B.Cu")
		(net "PVNN_TERM_CPU0")
	)
	(segment
		(start 440.271916 -127.621792)
		(end 433.041044 -134.852664)
		(width 0.381)
		(layer "B.Cu")
		(net "PVNN_TERM_CPU0")
	)
	(segment
		(start 69.353684 -186.191906)
		(end 69.353684 -186.858148)
		(width 0.381)
		(layer "B.Cu")
		(net "PVNN_TERM_CPU0")
	)
	(segment
		(start 321.037204 -188.56706)
		(end 321.039998 -188.56706)
		(width 0.381)
		(layer "B.Cu")
		(net "PVNN_TERM_CPU0")
	)
	(segment
		(start 370.259356 -188.371988)
		(end 370.031264 -188.60008)
		(width 0.381)
		(layer "B.Cu")
		(net "PVNN_TERM_CPU0")
	)
	(segment
		(start 128.70688 -100.929948)
		(end 128.70688 -93.690948)
		(width 0.508)
		(layer "B.Cu")
		(net "PVNN_TERM_CPU0")
	)
	(segment
		(start 330.345034 -96.748854)
		(end 330.01331 -96.41713)
		(width 0.508)
		(layer "B.Cu")
		(net "PVNN_TERM_CPU0")
	)
	(segment
		(start 377.632214 -190.303658)
		(end 378.62002 -190.303658)
		(width 0.381)
		(layer "B.Cu")
		(net "PVNN_TERM_CPU0")
	)
	(segment
		(start 304.697638 -192.050416)
		(end 304.690526 -192.057528)
		(width 0.381)
		(layer "B.Cu")
		(net "PVNN_TERM_CPU0")
	)
	(segment
		(start 333.653638 -188.28639)
		(end 333.653638 -188.52388)
		(width 0.381)
		(layer "B.Cu")
		(net "PVNN_TERM_CPU0")
	)
	(segment
		(start 315.569092 -192.395856)
		(end 315.569092 -191.615568)
		(width 0.381)
		(layer "B.Cu")
		(net "PVNN_TERM_CPU0")
	)
	(segment
		(start 375.121678 -183.89219)
		(end 377.632214 -186.402726)
		(width 0.381)
		(layer "B.Cu")
		(net "PVNN_TERM_CPU0")
	)
	(segment
		(start 372.375938 -185.37047)
		(end 372.750588 -185.74512)
		(width 0.381)
		(layer "B.Cu")
		(net "PVNN_TERM_CPU0")
	)
	(segment
		(start 310.107838 -57.309512)
		(end 307.937408 -55.139082)
		(width 0.508)
		(layer "B.Cu")
		(net "PVNN_TERM_CPU0")
	)
	(segment
		(start 277.748238 -189.14237)
		(end 277.138384 -189.752224)
		(width 0.381)
		(layer "B.Cu")
		(net "PVNN_TERM_CPU0")
	)
	(segment
		(start 337.605624 -189.916308)
		(end 338.045552 -190.356236)
		(width 0.381)
		(layer "B.Cu")
		(net "PVNN_TERM_CPU0")
	)
	(segment
		(start 317.276988 -191.219328)
		(end 318.05753 -191.219328)
		(width 0.381)
		(layer "B.Cu")
		(net "PVNN_TERM_CPU0")
	)
	(segment
		(start 307.984398 -189.36335)
		(end 307.984398 -190.05042)
		(width 0.381)
		(layer "B.Cu")
		(net "PVNN_TERM_CPU0")
	)
	(segment
		(start 288.522918 -191.81953)
		(end 288.522918 -198.749666)
		(width 0.381)
		(layer "B.Cu")
		(net "PVNN_TERM_CPU0")
	)
	(segment
		(start 405.121618 -192.65138)
		(end 404.09241 -192.65138)
		(width 0.381)
		(layer "B.Cu")
		(net "PVNN_TERM_CPU0")
	)
	(segment
		(start 312.13044 -192.821052)
		(end 312.13044 -193.34226)
		(width 0.381)
		(layer "B.Cu")
		(net "PVNN_TERM_CPU0")
	)
	(segment
		(start 364.088172 -185.192416)
		(end 363.64799 -185.632598)
		(width 0.381)
		(layer "B.Cu")
		(net "PVNN_TERM_CPU0")
	)
	(segment
		(start 377.632214 -186.402726)
		(end 377.632214 -190.303658)
		(width 0.381)
		(layer "B.Cu")
		(net "PVNN_TERM_CPU0")
	)
	(segment
		(start 370.031264 -188.60008)
		(end 370.031264 -189.291976)
		(width 0.381)
		(layer "B.Cu")
		(net "PVNN_TERM_CPU0")
	)
	(segment
		(start 363.64799 -185.632598)
		(end 363.64799 -185.981848)
		(width 0.381)
		(layer "B.Cu")
		(net "PVNN_TERM_CPU0")
	)
	(segment
		(start 286.504888 -189.8015)
		(end 288.522918 -191.81953)
		(width 0.381)
		(layer "B.Cu")
		(net "PVNN_TERM_CPU0")
	)
	(segment
		(start 381.92583 -190.42126)
		(end 382.189482 -190.157608)
		(width 0.381)
		(layer "B.Cu")
		(net "PVNN_TERM_CPU0")
	)
	(segment
		(start 320.376042 -188.41339)
		(end 320.529712 -188.56706)
		(width 0.3048)
		(layer "B.Cu")
		(net "PVNN_TERM_CPU0")
	)
	(segment
		(start 404.09241 -192.65138)
		(end 404.09241 -191.971422)
		(width 0.381)
		(layer "B.Cu")
		(net "PVNN_TERM_CPU0")
	)
	(segment
		(start 282.11272 -190.993268)
		(end 282.11272 -193.310764)
		(width 0.381)
		(layer "B.Cu")
		(net "PVNN_TERM_CPU0")
	)
	(segment
		(start 323.407278 -186.30646)
		(end 323.651118 -186.06262)
		(width 0.381)
		(layer "B.Cu")
		(net "PVNN_TERM_CPU0")
	)
	(segment
		(start 361.338876 -351.868232)
		(end 362.015024 -353.500436)
		(width 0.381)
		(layer "B.Cu")
		(net "PVNN_TERM_CPU0")
	)
	(segment
		(start 276.147784 -193.269616)
		(end 275.157184 -193.269616)
		(width 0.381)
		(layer "B.Cu")
		(net "PVNN_TERM_CPU0")
	)
	(segment
		(start 409.140152 -192.68948)
		(end 409.140152 -192.074546)
		(width 0.381)
		(layer "B.Cu")
		(net "PVNN_TERM_CPU0")
	)
	(segment
		(start 315.53404 -192.430908)
		(end 315.569092 -192.395856)
		(width 0.381)
		(layer "B.Cu")
		(net "PVNN_TERM_CPU0")
	)
	(segment
		(start 364.380018 -355.86543)
		(end 365.169958 -355.86543)
		(width 0.381)
		(layer "B.Cu")
		(net "PVNN_TERM_CPU0")
	)
	(segment
		(start 373.593614 -183.259222)
		(end 375.121678 -183.89219)
		(width 0.381)
		(layer "B.Cu")
		(net "PVNN_TERM_CPU0")
	)
	(segment
		(start 362.015024 -353.500436)
		(end 364.380018 -355.86543)
		(width 0.381)
		(layer "B.Cu")
		(net "PVNN_TERM_CPU0")
	)
	(segment
		(start 381.684276 -189.29096)
		(end 381.613918 -189.29096)
		(width 0.381)
		(layer "B.Cu")
		(net "PVNN_TERM_CPU0")
	)
	(segment
		(start 152.068022 -188.486288)
		(end 151.784304 -188.20257)
		(width 0.381)
		(layer "B.Cu")
		(net "PVNN_TERM_CPU0")
	)
	(segment
		(start 347.298264 -355.359462)
		(end 347.298264 -356.478332)
		(width 0.381)
		(layer "B.Cu")
		(net "PVNN_TERM_CPU0")
	)
	(segment
		(start 396.42034 -178.841654)
		(end 396.42034 -172.052996)
		(width 0.508)
		(layer "B.Cu")
		(net "PVNN_TERM_CPU0")
	)
	(segment
		(start 282.754578 -190.35141)
		(end 282.11272 -190.993268)
		(width 0.381)
		(layer "B.Cu")
		(net "PVNN_TERM_CPU0")
	)
	(segment
		(start 314.71743 -56.276748)
		(end 314.71743 -56.911748)
		(width 0.381)
		(layer "B.Cu")
		(net "PVNN_TERM_CPU0")
	)
	(segment
		(start 333.656178 -188.52642)
		(end 333.653638 -188.52388)
		(width 0.381)
		(layer "B.Cu")
		(net "PVNN_TERM_CPU0")
	)
	(segment
		(start 306.968398 -190.05042)
		(end 307.984398 -190.05042)
		(width 0.381)
		(layer "B.Cu")
		(net "PVNN_TERM_CPU0")
	)
	(segment
		(start 364.802928 -87.420704)
		(end 355.474778 -96.748854)
		(width 0.508)
		(layer "B.Cu")
		(net "PVNN_TERM_CPU0")
	)
	(segment
		(start 127.26416 -93.642688)
		(end 125.969522 -94.937326)
		(width 0.508)
		(layer "B.Cu")
		(net "PVNN_TERM_CPU0")
	)
	(segment
		(start 327.994518 -184.69864)
		(end 328.169778 -184.69864)
		(width 0.381)
		(layer "B.Cu")
		(net "PVNN_TERM_CPU0")
	)
	(segment
		(start 370.031264 -189.291976)
		(end 370.300758 -189.56147)
		(width 0.381)
		(layer "B.Cu")
		(net "PVNN_TERM_CPU0")
	)
	(segment
		(start 382.205738 -189.812422)
		(end 381.684276 -189.29096)
		(width 0.381)
		(layer "B.Cu")
		(net "PVNN_TERM_CPU0")
	)
	(segment
		(start 307.937408 -55.139082)
		(end 307.937408 -54.14137)
		(width 0.508)
		(layer "B.Cu")
		(net "PVNN_TERM_CPU0")
	)
	(segment
		(start 318.90208 -189.829948)
		(end 318.589914 -190.142114)
		(width 0.381)
		(layer "B.Cu")
		(net "PVNN_TERM_CPU0")
	)
	(segment
		(start 292.3286 -255.234948)
		(end 294.3606 -257.266948)
		(width 0.381)
		(layer "B.Cu")
		(net "PVNN_TERM_CPU0")
	)
	(segment
		(start 323.651118 -185.988452)
		(end 323.996304 -185.643266)
		(width 0.381)
		(layer "B.Cu")
		(net "PVNN_TERM_CPU0")
	)
	(segment
		(start 394.541248 -170.173904)
		(end 394.541248 -161.75101)
		(width 0.508)
		(layer "B.Cu")
		(net "PVNN_TERM_CPU0")
	)
	(segment
		(start 365.812578 -357.37165)
		(end 365.294418 -357.88981)
		(width 0.381)
		(layer "B.Cu")
		(net "PVNN_TERM_CPU0")
	)
	(segment
		(start 337.903312 -188.396118)
		(end 337.900772 -188.393578)
		(width 0.381)
		(layer "B.Cu")
		(net "PVNN_TERM_CPU0")
	)
	(segment
		(start 365.812578 -356.50805)
		(end 365.812578 -357.37165)
		(width 0.381)
		(layer "B.Cu")
		(net "PVNN_TERM_CPU0")
	)
	(segment
		(start 290.8046 -249.900948)
		(end 290.8046 -251.272548)
		(width 0.381)
		(layer "B.Cu")
		(net "PVNN_TERM_CPU0")
	)
	(segment
		(start 304.418238 -190.80607)
		(end 304.418238 -191.540384)
		(width 0.381)
		(layer "B.Cu")
		(net "PVNN_TERM_CPU0")
	)
	(segment
		(start 395.698726 -161.3916)
		(end 395.698726 -160.01111)
		(width 0.508)
		(layer "B.Cu")
		(net "PVNN_TERM_CPU0")
	)
	(segment
		(start 320.039492 -187.386214)
		(end 320.039492 -186.840368)
		(width 0.3048)
		(layer "B.Cu")
		(net "PVNN_TERM_CPU0")
	)
	(segment
		(start 392.603228 -159.73044)
		(end 391.255758 -161.07791)
		(width 0.508)
		(layer "B.Cu")
		(net "PVNN_TERM_CPU0")
	)
	(segment
		(start 314.319666 -57.309512)
		(end 310.107838 -57.309512)
		(width 0.508)
		(layer "B.Cu")
		(net "PVNN_TERM_CPU0")
	)
	(segment
		(start 323.996304 -185.643266)
		(end 324.267576 -185.914538)
		(width 0.381)
		(layer "B.Cu")
		(net "PVNN_TERM_CPU0")
	)
	(segment
		(start 336.894932 -188.766196)
		(end 336.894932 -188.393578)
		(width 0.381)
		(layer "B.Cu")
		(net "PVNN_TERM_CPU0")
	)
	(segment
		(start 407.108152 -192.68948)
		(end 407.108152 -192.074546)
		(width 0.381)
		(layer "B.Cu")
		(net "PVNN_TERM_CPU0")
	)
	(segment
		(start 365.169958 -355.86543)
		(end 365.812578 -356.50805)
		(width 0.381)
		(layer "B.Cu")
		(net "PVNN_TERM_CPU0")
	)
	(segment
		(start 315.53404 -193.13906)
		(end 315.53404 -192.430908)
		(width 0.381)
		(layer "B.Cu")
		(net "PVNN_TERM_CPU0")
	)
	(segment
		(start 395.418056 -159.73044)
		(end 394.907262 -159.73044)
		(width 0.508)
		(layer "B.Cu")
		(net "PVNN_TERM_CPU0")
	)
	(segment
		(start 331.517498 -186.85002)
		(end 331.088238 -187.27928)
		(width 0.381)
		(layer "B.Cu")
		(net "PVNN_TERM_CPU0")
	)
	(segment
		(start 330.01331 -96.41713)
		(end 315.871606 -96.41713)
		(width 0.508)
		(layer "B.Cu")
		(net "PVNN_TERM_CPU0")
	)
	(segment
		(start 75.860148 -181.7116)
		(end 76.314808 -181.25694)
		(width 0.381)
		(layer "B.Cu")
		(net "PVNN_TERM_CPU0")
	)
	(segment
		(start 68.6054 -184.724548)
		(end 69.021198 -184.30875)
		(width 0.381)
		(layer "B.Cu")
		(net "PVNN_TERM_CPU0")
	)
	(segment
		(start 69.021198 -184.15635)
		(end 69.353684 -183.823864)
		(width 0.381)
		(layer "B.Cu")
		(net "PVNN_TERM_CPU0")
	)
	(segment
		(start 121.77014 -94.937326)
		(end 121.05259 -94.219776)
		(width 0.508)
		(layer "B.Cu")
		(net "PVNN_TERM_CPU0")
	)
	(segment
		(start 76.314808 -181.25694)
		(end 76.463652 -181.25694)
		(width 0.381)
		(layer "B.Cu")
		(net "PVNN_TERM_CPU0")
	)
	(segment
		(start 373.112538 -188.39434)
		(end 372.638574 -188.39434)
		(width 0.381)
		(layer "B.Cu")
		(net "PVNN_TERM_CPU0")
	)
	(segment
		(start 128.70688 -93.690948)
		(end 128.65862 -93.642688)
		(width 0.508)
		(layer "B.Cu")
		(net "PVNN_TERM_CPU0")
	)
	(segment
		(start 69.353684 -183.823864)
		(end 69.353684 -183.703976)
		(width 0.381)
		(layer "B.Cu")
		(net "PVNN_TERM_CPU0")
	)
	(segment
		(start 365.294418 -358.897936)
		(end 366.550448 -360.153966)
		(width 0.381)
		(layer "B.Cu")
		(net "PVNN_TERM_CPU0")
	)
	(segment
		(start 408.124152 -192.68948)
		(end 408.124152 -192.074546)
		(width 0.381)
		(layer "B.Cu")
		(net "PVNN_TERM_CPU0")
	)
	(segment
		(start 320.529712 -188.56706)
		(end 321.037204 -188.56706)
		(width 0.3048)
		(layer "B.Cu")
		(net "PVNN_TERM_CPU0")
	)
	(segment
		(start 306.516278 -189.09157)
		(end 306.132738 -189.09157)
		(width 0.381)
		(layer "B.Cu")
		(net "PVNN_TERM_CPU0")
	)
	(segment
		(start 334.01508 -187.924948)
		(end 333.653638 -188.28639)
		(width 0.381)
		(layer "B.Cu")
		(net "PVNN_TERM_CPU0")
	)
	(segment
		(start 382.189482 -189.828678)
		(end 382.205738 -189.812422)
		(width 0.381)
		(layer "B.Cu")
		(net "PVNN_TERM_CPU0")
	)
	(segment
		(start 304.690526 -192.057528)
		(end 303.554638 -192.057528)
		(width 0.381)
		(layer "B.Cu")
		(net "PVNN_TERM_CPU0")
	)
	(segment
		(start 347.298264 -356.478332)
		(end 347.298264 -357.494332)
		(width 0.381)
		(layer "B.Cu")
		(net "PVNN_TERM_CPU0")
	)
	(segment
		(start 396.42034 -172.052996)
		(end 394.541248 -170.173904)
		(width 0.508)
		(layer "B.Cu")
		(net "PVNN_TERM_CPU0")
	)
	(segment
		(start 307.937408 -54.14137)
		(end 305.6128 -51.816762)
		(width 0.508)
		(layer "B.Cu")
		(net "PVNN_TERM_CPU0")
	)
	(segment
		(start 365.294418 -357.88981)
		(end 365.294418 -358.897936)
		(width 0.381)
		(layer "B.Cu")
		(net "PVNN_TERM_CPU0")
	)
	(segment
		(start 327.593198 -186.01436)
		(end 327.593198 -185.09996)
		(width 0.381)
		(layer "B.Cu")
		(net "PVNN_TERM_CPU0")
	)
	(segment
		(start 288.522918 -198.749666)
		(end 290.0426 -200.269348)
		(width 0.381)
		(layer "B.Cu")
		(net "PVNN_TERM_CPU0")
	)
	(segment
		(start 296.65295 -257.266948)
		(end 297.54195 -258.155948)
		(width 0.381)
		(layer "B.Cu")
		(net "PVNN_TERM_CPU0")
	)
	(segment
		(start 378.62002 -190.303658)
		(end 378.711968 -190.395606)
		(width 0.381)
		(layer "B.Cu")
		(net "PVNN_TERM_CPU0")
	)
	(segment
		(start 320.035428 -188.41339)
		(end 320.376042 -188.41339)
		(width 0.3048)
		(layer "B.Cu")
		(net "PVNN_TERM_CPU0")
	)
	(segment
		(start 275.157184 -190.443104)
		(end 275.157184 -193.269616)
		(width 0.381)
		(layer "B.Cu")
		(net "PVNN_TERM_CPU0")
	)
	(segment
		(start 370.300758 -189.56147)
		(end 370.873528 -189.56147)
		(width 0.381)
		(layer "B.Cu")
		(net "PVNN_TERM_CPU0")
	)
	(segment
		(start 395.339316 -161.75101)
		(end 395.698726 -161.3916)
		(width 0.508)
		(layer "B.Cu")
		(net "PVNN_TERM_CPU0")
	)
	(segment
		(start 337.44662 -189.916308)
		(end 337.605624 -189.916308)
		(width 0.381)
		(layer "B.Cu")
		(net "PVNN_TERM_CPU0")
	)
	(segment
		(start 307.664358 -189.04331)
		(end 307.984398 -189.36335)
		(width 0.381)
		(layer "B.Cu")
		(net "PVNN_TERM_CPU0")
	)
	(segment
		(start 75.761342 -181.7116)
		(end 75.860148 -181.7116)
		(width 0.381)
		(layer "B.Cu")
		(net "PVNN_TERM_CPU0")
	)
	(segment
		(start 440.271916 -124.680726)
		(end 440.271916 -127.621792)
		(width 0.381)
		(layer "B.Cu")
		(net "PVNN_TERM_CPU0")
	)
	(segment
		(start 324.267576 -186.130438)
		(end 324.423278 -186.28614)
		(width 0.381)
		(layer "B.Cu")
		(net "PVNN_TERM_CPU0")
	)
	(segment
		(start 318.228472 -190.142114)
		(end 318.223138 -190.13678)
		(width 0.381)
		(layer "B.Cu")
		(net "PVNN_TERM_CPU0")
	)
	(segment
		(start 294.3606 -257.266948)
		(end 296.65295 -257.266948)
		(width 0.381)
		(layer "B.Cu")
		(net "PVNN_TERM_CPU0")
	)
	(segment
		(start 318.05753 -191.219328)
		(end 318.154812 -191.122046)
		(width 0.381)
		(layer "B.Cu")
		(net "PVNN_TERM_CPU0")
	)
	(segment
		(start 440.271916 -124.680726)
		(end 440.271916 -123.664726)
		(width 0.381)
		(layer "B.Cu")
		(net "PVNN_TERM_CPU0")
	)
	(segment
		(start 394.541248 -161.75101)
		(end 395.339316 -161.75101)
		(width 0.508)
		(layer "B.Cu")
		(net "PVNN_TERM_CPU0")
	)
	(segment
		(start 290.0426 -249.138948)
		(end 290.8046 -249.900948)
		(width 0.381)
		(layer "B.Cu")
		(net "PVNN_TERM_CPU0")
	)
	(segment
		(start 329.170538 -184.1881)
		(end 328.680318 -184.1881)
		(width 0.381)
		(layer "B.Cu")
		(net "PVNN_TERM_CPU0")
	)
	(segment
		(start 321.037204 -188.56706)
		(end 320.925444 -188.4553)
		(width 0.3048)
		(layer "B.Cu")
		(net "PVNN_TERM_CPU0")
	)
	(segment
		(start 84.62772 -184.496202)
		(end 84.494624 -184.496202)
		(width 0.381)
		(layer "B.Cu")
		(net "PVNN_TERM_CPU0")
	)
	(segment
		(start 318.223138 -191.05372)
		(end 318.154812 -191.122046)
		(width 0.381)
		(layer "B.Cu")
		(net "PVNN_TERM_CPU0")
	)
	(segment
		(start 318.223138 -190.13678)
		(end 318.223138 -191.05372)
		(width 0.381)
		(layer "B.Cu")
		(net "PVNN_TERM_CPU0")
	)
	(segment
		(start 372.638574 -188.39434)
		(end 372.476014 -188.23178)
		(width 0.381)
		(layer "B.Cu")
		(net "PVNN_TERM_CPU0")
	)
	(segment
		(start 151.784304 -188.20257)
		(end 151.459438 -188.20257)
		(width 0.381)
		(layer "B.Cu")
		(net "PVNN_TERM_CPU0")
	)
	(segment
		(start 405.129238 -192.64376)
		(end 405.121618 -192.65138)
		(width 0.381)
		(layer "B.Cu")
		(net "PVNN_TERM_CPU0")
	)
	(segment
		(start 320.600324 -187.947046)
		(end 320.039492 -187.386214)
		(width 0.3048)
		(layer "B.Cu")
		(net "PVNN_TERM_CPU0")
	)
	(segment
		(start 85.208618 -184.23509)
		(end 85.09762 -184.346088)
		(width 0.381)
		(layer "B.Cu")
		(net "PVNN_TERM_CPU0")
	)
	(segment
		(start 370.887498 -185.37047)
		(end 372.375938 -185.37047)
		(width 0.381)
		(layer "B.Cu")
		(net "PVNN_TERM_CPU0")
	)
	(segment
		(start 372.476014 -188.23178)
		(end 371.652038 -188.23178)
		(width 0.381)
		(layer "B.Cu")
		(net "PVNN_TERM_CPU0")
	)
	(segment
		(start 277.138384 -193.269616)
		(end 278.128984 -193.269616)
		(width 0.381)
		(layer "B.Cu")
		(net "PVNN_TERM_CPU0")
	)
	(segment
		(start 348.036388 -357.494332)
		(end 348.291404 -357.239316)
		(width 0.381)
		(layer "B.Cu")
		(net "PVNN_TERM_CPU0")
	)
	(segment
		(start 361.338876 -351.358454)
		(end 361.338876 -351.868232)
		(width 0.381)
		(layer "B.Cu")
		(net "PVNN_TERM_CPU0")
	)
	(segment
		(start 433.041044 -134.852664)
		(end 433.041044 -135.779256)
		(width 0.381)
		(layer "B.Cu")
		(net "PVNN_TERM_CPU0")
	)
	(segment
		(start 411.172152 -192.68948)
		(end 411.172152 -192.074546)
		(width 0.381)
		(layer "B.Cu")
		(net "PVNN_TERM_CPU0")
	)
	(segment
		(start 371.371622 -188.23178)
		(end 370.873528 -188.729874)
		(width 0.381)
		(layer "B.Cu")
		(net "PVNN_TERM_CPU0")
	)
	(segment
		(start 128.45288 -101.183948)
		(end 128.70688 -100.929948)
		(width 0.508)
		(layer "B.Cu")
		(net "PVNN_TERM_CPU0")
	)
	(segment
		(start 282.071572 -193.269616)
		(end 281.100784 -193.269616)
		(width 0.381)
		(layer "B.Cu")
		(net "PVNN_TERM_CPU0")
	)
	(segment
		(start 290.0426 -200.269348)
		(end 290.0426 -249.138948)
		(width 0.381)
		(layer "B.Cu")
		(net "PVNN_TERM_CPU0")
	)
	(segment
		(start 275.497798 -189.13729)
		(end 275.497798 -190.10249)
		(width 0.381)
		(layer "B.Cu")
		(net "PVNN_TERM_CPU0")
	)
	(segment
		(start 323.651118 -186.06262)
		(end 323.651118 -185.988452)
		(width 0.381)
		(layer "B.Cu")
		(net "PVNN_TERM_CPU0")
	)
	(segment
		(start 318.589914 -190.142114)
		(end 318.228472 -190.142114)
		(width 0.381)
		(layer "B.Cu")
		(net "PVNN_TERM_CPU0")
	)
	(segment
		(start 128.65862 -93.642688)
		(end 127.26416 -93.642688)
		(width 0.508)
		(layer "B.Cu")
		(net "PVNN_TERM_CPU0")
	)
	(segment
		(start 322.584572 -58.283348)
		(end 321.968622 -58.283348)
		(width 0.381)
		(layer "B.Cu")
		(net "PVNN_TERM_CPU0")
	)
	(segment
		(start 327.643744 -186.064906)
		(end 327.593198 -186.01436)
		(width 0.381)
		(layer "B.Cu")
		(net "PVNN_TERM_CPU0")
	)
	(segment
		(start 69.021198 -184.30875)
		(end 69.021198 -184.15635)
		(width 0.381)
		(layer "B.Cu")
		(net "PVNN_TERM_CPU0")
	)
	(segment
		(start 348.079314 -356.192836)
		(end 348.079314 -357.027226)
		(width 0.381)
		(layer "B.Cu")
		(net "PVNN_TERM_CPU0")
	)
	(segment
		(start 347.298264 -357.494332)
		(end 348.036388 -357.494332)
		(width 0.381)
		(layer "B.Cu")
		(net "PVNN_TERM_CPU0")
	)
	(segment
		(start 383.172208 -187.335414)
		(end 382.782064 -187.335414)
		(width 0.381)
		(layer "B.Cu")
		(net "PVNN_TERM_CPU0")
	)
	(segment
		(start 337.900772 -188.393578)
		(end 336.894932 -188.393578)
		(width 0.381)
		(layer "B.Cu")
		(net "PVNN_TERM_CPU0")
	)
	(segment
		(start 84.777834 -184.346088)
		(end 84.62772 -184.496202)
		(width 0.381)
		(layer "B.Cu")
		(net "PVNN_TERM_CPU0")
	)
	(segment
		(start 331.088238 -187.27928)
		(end 330.280518 -187.27928)
		(width 0.381)
		(layer "B.Cu")
		(net "PVNN_TERM_CPU0")
	)
	(segment
		(start 327.79208 -189.626748)
		(end 327.79208 -189.191392)
		(width 0.381)
		(layer "B.Cu")
		(net "PVNN_TERM_CPU0")
	)
	(segment
		(start 304.418238 -191.540384)
		(end 304.697638 -191.819784)
		(width 0.381)
		(layer "B.Cu")
		(net "PVNN_TERM_CPU0")
	)
	(segment
		(start 394.907262 -159.73044)
		(end 392.603228 -159.73044)
		(width 0.508)
		(layer "B.Cu")
		(net "PVNN_TERM_CPU0")
	)
	(segment
		(start 328.680318 -184.1881)
		(end 328.169778 -184.69864)
		(width 0.381)
		(layer "B.Cu")
		(net "PVNN_TERM_CPU0")
	)
	(segment
		(start 397.451072 -179.872386)
		(end 396.42034 -178.841654)
		(width 0.508)
		(layer "B.Cu")
		(net "PVNN_TERM_CPU0")
	)
	(segment
		(start 410.156152 -192.68948)
		(end 410.156152 -192.074546)
		(width 0.381)
		(layer "B.Cu")
		(net "PVNN_TERM_CPU0")
	)
	(segment
		(start 85.09762 -184.346088)
		(end 84.777834 -184.346088)
		(width 0.381)
		(layer "B.Cu")
		(net "PVNN_TERM_CPU0")
	)
	(segment
		(start 395.698726 -160.01111)
		(end 395.418056 -159.73044)
		(width 0.508)
		(layer "B.Cu")
		(net "PVNN_TERM_CPU0")
	)
	(segment
		(start 305.6128 -51.816762)
		(end 305.6128 -51.438556)
		(width 0.508)
		(layer "B.Cu")
		(net "PVNN_TERM_CPU0")
	)
	(segment
		(start 125.969522 -94.937326)
		(end 121.77014 -94.937326)
		(width 0.508)
		(layer "B.Cu")
		(net "PVNN_TERM_CPU0")
	)
	(segment
		(start 327.79208 -189.191392)
		(end 327.613518 -189.01283)
		(width 0.381)
		(layer "B.Cu")
		(net "PVNN_TERM_CPU0")
	)
	(segment
		(start 85.892894 -181.66461)
		(end 85.261958 -181.66461)
		(width 0.381)
		(layer "B.Cu")
		(net "PVNN_TERM_CPU0")
	)
	(segment
		(start 327.593198 -185.09996)
		(end 327.994518 -184.69864)
		(width 0.381)
		(layer "B.Cu")
		(net "PVNN_TERM_CPU0")
	)
	(segment
		(start 290.8046 -251.272548)
		(end 292.3286 -252.796548)
		(width 0.381)
		(layer "B.Cu")
		(net "PVNN_TERM_CPU0")
	)
	(segment
		(start 306.132738 -189.09157)
		(end 304.418238 -190.80607)
		(width 0.381)
		(layer "B.Cu")
		(net "PVNN_TERM_CPU0")
	)
	(segment
		(start 355.474778 -96.748854)
		(end 330.345034 -96.748854)
		(width 0.508)
		(layer "B.Cu")
		(net "PVNN_TERM_CPU0")
	)
	(segment
		(start 383.448052 -187.611258)
		(end 383.172208 -187.335414)
		(width 0.381)
		(layer "B.Cu")
		(net "PVNN_TERM_CPU0")
	)
	(segment
		(start 314.71743 -56.911748)
		(end 314.319666 -57.309512)
		(width 0.508)
		(layer "B.Cu")
		(net "PVNN_TERM_CPU0")
	)
	(segment
		(start 348.079314 -357.027226)
		(end 348.291404 -357.239316)
		(width 0.381)
		(layer "B.Cu")
		(net "PVNN_TERM_CPU0")
	)
	(segment
		(start 121.05259 -94.219776)
		(end 121.05259 -94.164658)
		(width 0.508)
		(layer "B.Cu")
		(net "PVNN_TERM_CPU0")
	)
	(segment
		(start 282.754578 -189.09157)
		(end 282.754578 -190.35141)
		(width 0.381)
		(layer "B.Cu")
		(net "PVNN_TERM_CPU0")
	)
	(segment
		(start 370.873528 -188.729874)
		(end 370.873528 -189.56147)
		(width 0.381)
		(layer "B.Cu")
		(net "PVNN_TERM_CPU0")
	)
	(segment
		(start 324.267576 -185.914538)
		(end 324.267576 -186.130438)
		(width 0.381)
		(layer "B.Cu")
		(net "PVNN_TERM_CPU0")
	)
	(segment
		(start 282.11272 -193.310764)
		(end 282.071572 -193.269616)
		(width 0.381)
		(layer "B.Cu")
		(net "PVNN_TERM_CPU0")
	)
	(segment
		(start 382.189482 -190.157608)
		(end 382.189482 -189.828678)
		(width 0.381)
		(layer "B.Cu")
		(net "PVNN_TERM_CPU0")
	)
	(segment
		(start 371.652038 -188.23178)
		(end 371.371622 -188.23178)
		(width 0.381)
		(layer "B.Cu")
		(net "PVNN_TERM_CPU0")
	)
	(segment
		(start 292.3286 -252.796548)
		(end 292.3286 -255.234948)
		(width 0.381)
		(layer "B.Cu")
		(net "PVNN_TERM_CPU0")
	)
	(segment
		(start 320.925444 -188.4553)
		(end 320.925444 -187.947046)
		(width 0.3048)
		(layer "B.Cu")
		(net "PVNN_TERM_CPU0")
	)
	(segment
		(start 336.60334 -189.057788)
		(end 336.894932 -188.766196)
		(width 0.381)
		(layer "B.Cu")
		(net "PVNN_TERM_CPU0")
	)
	(segment
		(start 372.750588 -185.74512)
		(end 373.143018 -185.74512)
		(width 0.381)
		(layer "B.Cu")
		(net "PVNN_TERM_CPU0")
	)
	(segment
		(start 311.99328 -192.683892)
		(end 312.13044 -192.821052)
		(width 0.381)
		(layer "B.Cu")
		(net "PVNN_TERM_CPU0")
	)
	(segment
		(start 304.697638 -191.819784)
		(end 304.697638 -192.050416)
		(width 0.381)
		(layer "B.Cu")
		(net "PVNN_TERM_CPU0")
	)
	(segment
		(start 334.662018 -188.52642)
		(end 333.656178 -188.52642)
		(width 0.381)
		(layer "B.Cu")
		(net "PVNN_TERM_CPU0")
	)
	(segment
		(start 275.497798 -190.10249)
		(end 275.157184 -190.443104)
		(width 0.381)
		(layer "B.Cu")
		(net "PVNN_TERM_CPU0")
	)
	(segment
		(start 277.138384 -189.752224)
		(end 277.138384 -193.269616)
		(width 0.381)
		(layer "B.Cu")
		(net "PVNN_TERM_CPU0")
	)
	(segment
		(start 147.931886 -119.256048)
		(end 147.931886 -110.751874)
		(width 0.508)
		(layer "In2.Cu")
		(net "PVNN_TERM_CPU0")
	)
	(segment
		(start 145.193258 -128.533906)
		(end 146.60372 -127.123444)
		(width 0.508)
		(layer "In2.Cu")
		(net "PVNN_TERM_CPU0")
	)
	(segment
		(start 436.27548 -146.921728)
		(end 445.4906 -146.921728)
		(width 0.381)
		(layer "In2.Cu")
		(net "PVNN_TERM_CPU0")
	)
	(segment
		(start 447.93408 -191.864488)
		(end 435.52364 -191.864488)
		(width 0.381)
		(layer "In2.Cu")
		(net "PVNN_TERM_CPU0")
	)
	(segment
		(start 450.00418 -151.435308)
		(end 450.00418 -165.400228)
		(width 0.381)
		(layer "In2.Cu")
		(net "PVNN_TERM_CPU0")
	)
	(segment
		(start 449.91782 -187.554108)
		(end 449.91782 -189.880748)
		(width 0.381)
		(layer "In2.Cu")
		(net "PVNN_TERM_CPU0")
	)
	(segment
		(start 144.2974 -130.054858)
		(end 145.193258 -129.159)
		(width 0.508)
		(layer "In2.Cu")
		(net "PVNN_TERM_CPU0")
	)
	(segment
		(start 276.036024 -47.63516)
		(end 275.820124 -47.41926)
		(width 0.508)
		(layer "In2.Cu")
		(net "PVNN_TERM_CPU0")
	)
	(segment
		(start 433.665884 -144.312132)
		(end 436.27548 -146.921728)
		(width 0.381)
		(layer "In2.Cu")
		(net "PVNN_TERM_CPU0")
	)
	(segment
		(start 264.98169 -44.29887)
		(end 262.355076 -41.672256)
		(width 0.508)
		(layer "In2.Cu")
		(net "PVNN_TERM_CPU0")
	)
	(segment
		(start 311.402984 -191.191642)
		(end 309.641494 -191.191642)
		(width 0.508)
		(layer "In2.Cu")
		(net "PVNN_TERM_CPU0")
	)
	(segment
		(start 181.15788 -96.103948)
		(end 181.960012 -96.103948)
		(width 0.508)
		(layer "In2.Cu")
		(net "PVNN_TERM_CPU0")
	)
	(segment
		(start 430.23536 -192.347088)
		(end 427.482 -192.347088)
		(width 0.381)
		(layer "In2.Cu")
		(net "PVNN_TERM_CPU0")
	)
	(segment
		(start 275.820124 -47.41926)
		(end 274.973796 -47.41926)
		(width 0.508)
		(layer "In2.Cu")
		(net "PVNN_TERM_CPU0")
	)
	(segment
		(start 145.193258 -139.223496)
		(end 145.193258 -135.820658)
		(width 0.508)
		(layer "In2.Cu")
		(net "PVNN_TERM_CPU0")
	)
	(segment
		(start 182.4228 -95.64116)
		(end 182.4228 -94.839028)
		(width 0.508)
		(layer "In2.Cu")
		(net "PVNN_TERM_CPU0")
	)
	(segment
		(start 450.00418 -165.400228)
		(end 453.96912 -169.365168)
		(width 0.381)
		(layer "In2.Cu")
		(net "PVNN_TERM_CPU0")
	)
	(segment
		(start 277.743158 -189.13729)
		(end 275.497798 -189.13729)
		(width 0.508)
		(layer "In2.Cu")
		(net "PVNN_TERM_CPU0")
	)
	(segment
		(start 175.219106 -58.772552)
		(end 182.057548 -58.772552)
		(width 0.508)
		(layer "In2.Cu")
		(net "PVNN_TERM_CPU0")
	)
	(segment
		(start 147.931886 -110.751874)
		(end 148.34362 -110.34014)
		(width 0.508)
		(layer "In2.Cu")
		(net "PVNN_TERM_CPU0")
	)
	(segment
		(start 311.982358 -192.67297)
		(end 311.982358 -191.771016)
		(width 0.508)
		(layer "In2.Cu")
		(net "PVNN_TERM_CPU0")
	)
	(segment
		(start 183.256428 -94.0054)
		(end 187.0202 -94.0054)
		(width 0.508)
		(layer "In2.Cu")
		(net "PVNN_TERM_CPU0")
	)
	(segment
		(start 309.641494 -191.191642)
		(end 307.664358 -189.214506)
		(width 0.508)
		(layer "In2.Cu")
		(net "PVNN_TERM_CPU0")
	)
	(segment
		(start 435.52364 -191.864488)
		(end 434.467 -192.921128)
		(width 0.381)
		(layer "In2.Cu")
		(net "PVNN_TERM_CPU0")
	)
	(segment
		(start 148.34362 -98.38182)
		(end 147.41398 -97.45218)
		(width 0.508)
		(layer "In2.Cu")
		(net "PVNN_TERM_CPU0")
	)
	(segment
		(start 144.2974 -134.9248)
		(end 144.2974 -130.054858)
		(width 0.508)
		(layer "In2.Cu")
		(net "PVNN_TERM_CPU0")
	)
	(segment
		(start 182.80888 -58.02122)
		(end 182.80888 -55.916068)
		(width 0.508)
		(layer "In2.Cu")
		(net "PVNN_TERM_CPU0")
	)
	(segment
		(start 453.96912 -169.365168)
		(end 453.96912 -183.502808)
		(width 0.381)
		(layer "In2.Cu")
		(net "PVNN_TERM_CPU0")
	)
	(segment
		(start 445.4906 -146.921728)
		(end 450.00418 -151.435308)
		(width 0.381)
		(layer "In2.Cu")
		(net "PVNN_TERM_CPU0")
	)
	(segment
		(start 187.0202 -94.0054)
		(end 187.579 -93.4466)
		(width 0.508)
		(layer "In2.Cu")
		(net "PVNN_TERM_CPU0")
	)
	(segment
		(start 171.43476 -82.740246)
		(end 171.43476 -62.556898)
		(width 0.508)
		(layer "In2.Cu")
		(net "PVNN_TERM_CPU0")
	)
	(segment
		(start 287.75025 -191.046862)
		(end 304.560986 -191.046862)
		(width 0.508)
		(layer "In2.Cu")
		(net "PVNN_TERM_CPU0")
	)
	(segment
		(start 277.748238 -190.094108)
		(end 278.170132 -190.516002)
		(width 0.508)
		(layer "In2.Cu")
		(net "PVNN_TERM_CPU0")
	)
	(segment
		(start 307.664358 -189.04331)
		(end 306.564538 -189.04331)
		(width 0.508)
		(layer "In2.Cu")
		(net "PVNN_TERM_CPU0")
	)
	(segment
		(start 145.193258 -129.159)
		(end 145.193258 -128.533906)
		(width 0.508)
		(layer "In2.Cu")
		(net "PVNN_TERM_CPU0")
	)
	(segment
		(start 426.77588 -193.053208)
		(end 412.150814 -193.053208)
		(width 0.381)
		(layer "In2.Cu")
		(net "PVNN_TERM_CPU0")
	)
	(segment
		(start 449.91782 -189.880748)
		(end 447.93408 -191.864488)
		(width 0.381)
		(layer "In2.Cu")
		(net "PVNN_TERM_CPU0")
	)
	(segment
		(start 187.579 -92.2274)
		(end 186.3852 -91.0336)
		(width 0.508)
		(layer "In2.Cu")
		(net "PVNN_TERM_CPU0")
	)
	(segment
		(start 311.982358 -191.771016)
		(end 311.402984 -191.191642)
		(width 0.508)
		(layer "In2.Cu")
		(net "PVNN_TERM_CPU0")
	)
	(segment
		(start 145.193258 -135.820658)
		(end 144.2974 -134.9248)
		(width 0.508)
		(layer "In2.Cu")
		(net "PVNN_TERM_CPU0")
	)
	(segment
		(start 286.504888 -189.8015)
		(end 287.75025 -191.046862)
		(width 0.508)
		(layer "In2.Cu")
		(net "PVNN_TERM_CPU0")
	)
	(segment
		(start 433.665884 -139.066016)
		(end 433.665884 -144.312132)
		(width 0.381)
		(layer "In2.Cu")
		(net "PVNN_TERM_CPU0")
	)
	(segment
		(start 182.057548 -58.772552)
		(end 182.80888 -58.02122)
		(width 0.508)
		(layer "In2.Cu")
		(net "PVNN_TERM_CPU0")
	)
	(segment
		(start 187.579 -93.4466)
		(end 187.579 -92.2274)
		(width 0.508)
		(layer "In2.Cu")
		(net "PVNN_TERM_CPU0")
	)
	(segment
		(start 146.60372 -120.584214)
		(end 147.931886 -119.256048)
		(width 0.508)
		(layer "In2.Cu")
		(net "PVNN_TERM_CPU0")
	)
	(segment
		(start 171.43476 -62.556898)
		(end 175.219106 -58.772552)
		(width 0.508)
		(layer "In2.Cu")
		(net "PVNN_TERM_CPU0")
	)
	(segment
		(start 306.564538 -189.04331)
		(end 306.516278 -189.09157)
		(width 0.508)
		(layer "In2.Cu")
		(net "PVNN_TERM_CPU0")
	)
	(segment
		(start 277.748238 -189.14237)
		(end 277.743158 -189.13729)
		(width 0.508)
		(layer "In2.Cu")
		(net "PVNN_TERM_CPU0")
	)
	(segment
		(start 278.170132 -190.516002)
		(end 282.29687 -190.516002)
		(width 0.508)
		(layer "In2.Cu")
		(net "PVNN_TERM_CPU0")
	)
	(segment
		(start 186.3852 -91.0336)
		(end 186.3852 -90.5256)
		(width 0.508)
		(layer "In2.Cu")
		(net "PVNN_TERM_CPU0")
	)
	(segment
		(start 262.355076 -41.672256)
		(end 262.355076 -39.41699)
		(width 0.508)
		(layer "In2.Cu")
		(net "PVNN_TERM_CPU0")
	)
	(segment
		(start 181.960012 -96.103948)
		(end 182.4228 -95.64116)
		(width 0.508)
		(layer "In2.Cu")
		(net "PVNN_TERM_CPU0")
	)
	(segment
		(start 311.99328 -192.683892)
		(end 311.982358 -192.67297)
		(width 0.508)
		(layer "In2.Cu")
		(net "PVNN_TERM_CPU0")
	)
	(segment
		(start 430.8094 -192.921128)
		(end 430.23536 -192.347088)
		(width 0.381)
		(layer "In2.Cu")
		(net "PVNN_TERM_CPU0")
	)
	(segment
		(start 412.150814 -193.053208)
		(end 411.172152 -192.074546)
		(width 0.381)
		(layer "In2.Cu")
		(net "PVNN_TERM_CPU0")
	)
	(segment
		(start 453.96912 -183.502808)
		(end 449.91782 -187.554108)
		(width 0.381)
		(layer "In2.Cu")
		(net "PVNN_TERM_CPU0")
	)
	(segment
		(start 304.560986 -191.046862)
		(end 306.516278 -189.09157)
		(width 0.508)
		(layer "In2.Cu")
		(net "PVNN_TERM_CPU0")
	)
	(segment
		(start 271.853406 -44.29887)
		(end 264.98169 -44.29887)
		(width 0.508)
		(layer "In2.Cu")
		(net "PVNN_TERM_CPU0")
	)
	(segment
		(start 282.29687 -190.516002)
		(end 282.754578 -190.058294)
		(width 0.508)
		(layer "In2.Cu")
		(net "PVNN_TERM_CPU0")
	)
	(segment
		(start 182.4228 -94.839028)
		(end 183.256428 -94.0054)
		(width 0.508)
		(layer "In2.Cu")
		(net "PVNN_TERM_CPU0")
	)
	(segment
		(start 282.754578 -190.058294)
		(end 282.754578 -189.09157)
		(width 0.508)
		(layer "In2.Cu")
		(net "PVNN_TERM_CPU0")
	)
	(segment
		(start 307.664358 -189.214506)
		(end 307.664358 -189.04331)
		(width 0.508)
		(layer "In2.Cu")
		(net "PVNN_TERM_CPU0")
	)
	(segment
		(start 175.086264 -86.39175)
		(end 171.43476 -82.740246)
		(width 0.508)
		(layer "In2.Cu")
		(net "PVNN_TERM_CPU0")
	)
	(segment
		(start 434.467 -192.921128)
		(end 430.8094 -192.921128)
		(width 0.381)
		(layer "In2.Cu")
		(net "PVNN_TERM_CPU0")
	)
	(segment
		(start 186.3852 -90.5256)
		(end 182.25135 -86.39175)
		(width 0.508)
		(layer "In2.Cu")
		(net "PVNN_TERM_CPU0")
	)
	(segment
		(start 148.34362 -110.34014)
		(end 148.34362 -98.38182)
		(width 0.508)
		(layer "In2.Cu")
		(net "PVNN_TERM_CPU0")
	)
	(segment
		(start 146.60372 -127.123444)
		(end 146.60372 -120.584214)
		(width 0.508)
		(layer "In2.Cu")
		(net "PVNN_TERM_CPU0")
	)
	(segment
		(start 427.482 -192.347088)
		(end 426.77588 -193.053208)
		(width 0.381)
		(layer "In2.Cu")
		(net "PVNN_TERM_CPU0")
	)
	(segment
		(start 277.748238 -189.14237)
		(end 277.748238 -190.094108)
		(width 0.508)
		(layer "In2.Cu")
		(net "PVNN_TERM_CPU0")
	)
	(segment
		(start 182.25135 -86.39175)
		(end 175.086264 -86.39175)
		(width 0.508)
		(layer "In2.Cu")
		(net "PVNN_TERM_CPU0")
	)
	(segment
		(start 274.973796 -47.41926)
		(end 271.853406 -44.29887)
		(width 0.508)
		(layer "In2.Cu")
		(net "PVNN_TERM_CPU0")
	)
	(segment
		(start 130.337814 -92.566236)
		(end 129.213102 -93.690948)
		(width 0.508)
		(layer "In4.Cu")
		(net "PVNN_TERM_CPU0")
	)
	(segment
		(start 208.46288 -41.029128)
		(end 194.84086 -41.029128)
		(width 0.508)
		(layer "In4.Cu")
		(net "PVNN_TERM_CPU0")
	)
	(segment
		(start 135.81507 -144.285716)
		(end 129.696972 -150.403814)
		(width 0.508)
		(layer "In4.Cu")
		(net "PVNN_TERM_CPU0")
	)
	(segment
		(start 85.261958 -181.66461)
		(end 85.261958 -184.18175)
		(width 0.508)
		(layer "In4.Cu")
		(net "PVNN_TERM_CPU0")
	)
	(segment
		(start 383.448052 -187.611258)
		(end 383.448052 -170.120056)
		(width 0.508)
		(layer "In4.Cu")
		(net "PVNN_TERM_CPU0")
	)
	(segment
		(start 372.726204 -162.659568)
		(end 367.907062 -157.840426)
		(width 0.508)
		(layer "In4.Cu")
		(net "PVNN_TERM_CPU0")
	)
	(segment
		(start 171.510198 -94.681548)
		(end 168.36644 -97.825306)
		(width 0.508)
		(layer "In4.Cu")
		(net "PVNN_TERM_CPU0")
	)
	(segment
		(start 175.01616 -36.871148)
		(end 164.39388 -26.248868)
		(width 0.508)
		(layer "In4.Cu")
		(net "PVNN_TERM_CPU0")
	)
	(segment
		(start 129.213102 -93.690948)
		(end 128.70688 -93.690948)
		(width 0.508)
		(layer "In4.Cu")
		(net "PVNN_TERM_CPU0")
	)
	(segment
		(start 361.338876 -351.358454)
		(end 359.212388 -349.231966)
		(width 0.381)
		(layer "In4.Cu")
		(net "PVNN_TERM_CPU0")
	)
	(segment
		(start 85.261958 -180.432456)
		(end 85.261958 -181.66461)
		(width 0.508)
		(layer "In4.Cu")
		(net "PVNN_TERM_CPU0")
	)
	(segment
		(start 180.203348 -94.681548)
		(end 171.510198 -94.681548)
		(width 0.508)
		(layer "In4.Cu")
		(net "PVNN_TERM_CPU0")
	)
	(segment
		(start 145.193258 -139.223496)
		(end 143.434054 -139.223496)
		(width 0.508)
		(layer "In4.Cu")
		(net "PVNN_TERM_CPU0")
	)
	(segment
		(start 375.987564 -162.659568)
		(end 372.726204 -162.659568)
		(width 0.508)
		(layer "In4.Cu")
		(net "PVNN_TERM_CPU0")
	)
	(segment
		(start 88.61552 -178.674268)
		(end 88.428322 -178.48707)
		(width 0.508)
		(layer "In4.Cu")
		(net "PVNN_TERM_CPU0")
	)
	(segment
		(start 351.007934 -349.231966)
		(end 347.298264 -352.941636)
		(width 0.381)
		(layer "In4.Cu")
		(net "PVNN_TERM_CPU0")
	)
	(segment
		(start 147.41398 -97.45218)
		(end 147.497038 -97.369122)
		(width 0.508)
		(layer "In4.Cu")
		(net "PVNN_TERM_CPU0")
	)
	(segment
		(start 110.828074 -150.403814)
		(end 104.67721 -156.554678)
		(width 0.508)
		(layer "In4.Cu")
		(net "PVNN_TERM_CPU0")
	)
	(segment
		(start 147.497038 -93.990414)
		(end 146.07286 -92.566236)
		(width 0.508)
		(layer "In4.Cu")
		(net "PVNN_TERM_CPU0")
	)
	(segment
		(start 181.15788 -96.103948)
		(end 181.15788 -95.63608)
		(width 0.508)
		(layer "In4.Cu")
		(net "PVNN_TERM_CPU0")
	)
	(segment
		(start 147.787106 -97.825306)
		(end 147.41398 -97.45218)
		(width 0.508)
		(layer "In4.Cu")
		(net "PVNN_TERM_CPU0")
	)
	(segment
		(start 185.15076 -36.871148)
		(end 175.01616 -36.871148)
		(width 0.508)
		(layer "In4.Cu")
		(net "PVNN_TERM_CPU0")
	)
	(segment
		(start 194.84086 -41.029128)
		(end 189.78626 -35.974528)
		(width 0.508)
		(layer "In4.Cu")
		(net "PVNN_TERM_CPU0")
	)
	(segment
		(start 189.78626 -35.974528)
		(end 186.04738 -35.974528)
		(width 0.508)
		(layer "In4.Cu")
		(net "PVNN_TERM_CPU0")
	)
	(segment
		(start 367.907062 -157.840426)
		(end 359.923588 -157.840426)
		(width 0.508)
		(layer "In4.Cu")
		(net "PVNN_TERM_CPU0")
	)
	(segment
		(start 164.39388 -26.248868)
		(end 164.39388 -24.619966)
		(width 0.508)
		(layer "In4.Cu")
		(net "PVNN_TERM_CPU0")
	)
	(segment
		(start 397.451072 -184.967626)
		(end 397.451072 -179.872386)
		(width 0.508)
		(layer "In4.Cu")
		(net "PVNN_TERM_CPU0")
	)
	(segment
		(start 181.15788 -95.63608)
		(end 180.203348 -94.681548)
		(width 0.508)
		(layer "In4.Cu")
		(net "PVNN_TERM_CPU0")
	)
	(segment
		(start 147.497038 -97.369122)
		(end 147.497038 -93.990414)
		(width 0.508)
		(layer "In4.Cu")
		(net "PVNN_TERM_CPU0")
	)
	(segment
		(start 129.696972 -150.403814)
		(end 110.828074 -150.403814)
		(width 0.508)
		(layer "In4.Cu")
		(net "PVNN_TERM_CPU0")
	)
	(segment
		(start 89.19337 -172.152056)
		(end 89.19337 -178.096418)
		(width 0.508)
		(layer "In4.Cu")
		(net "PVNN_TERM_CPU0")
	)
	(segment
		(start 138.371834 -144.285716)
		(end 137.597388 -144.285716)
		(width 0.508)
		(layer "In4.Cu")
		(net "PVNN_TERM_CPU0")
	)
	(segment
		(start 87.207344 -178.48707)
		(end 85.261958 -180.432456)
		(width 0.508)
		(layer "In4.Cu")
		(net "PVNN_TERM_CPU0")
	)
	(segment
		(start 168.36644 -97.825306)
		(end 147.787106 -97.825306)
		(width 0.508)
		(layer "In4.Cu")
		(net "PVNN_TERM_CPU0")
	)
	(segment
		(start 359.212388 -349.231966)
		(end 351.007934 -349.231966)
		(width 0.381)
		(layer "In4.Cu")
		(net "PVNN_TERM_CPU0")
	)
	(segment
		(start 347.298264 -352.941636)
		(end 347.298264 -355.359462)
		(width 0.381)
		(layer "In4.Cu")
		(net "PVNN_TERM_CPU0")
	)
	(segment
		(start 210.06308 -39.428928)
		(end 208.46288 -41.029128)
		(width 0.508)
		(layer "In4.Cu")
		(net "PVNN_TERM_CPU0")
	)
	(segment
		(start 137.597388 -144.285716)
		(end 135.81507 -144.285716)
		(width 0.508)
		(layer "In4.Cu")
		(net "PVNN_TERM_CPU0")
	)
	(segment
		(start 403.011894 -186.87669)
		(end 399.360136 -186.87669)
		(width 0.508)
		(layer "In4.Cu")
		(net "PVNN_TERM_CPU0")
	)
	(segment
		(start 399.360136 -186.87669)
		(end 397.451072 -184.967626)
		(width 0.508)
		(layer "In4.Cu")
		(net "PVNN_TERM_CPU0")
	)
	(segment
		(start 212.73262 -39.428928)
		(end 210.06308 -39.428928)
		(width 0.508)
		(layer "In4.Cu")
		(net "PVNN_TERM_CPU0")
	)
	(segment
		(start 146.07286 -92.566236)
		(end 130.337814 -92.566236)
		(width 0.508)
		(layer "In4.Cu")
		(net "PVNN_TERM_CPU0")
	)
	(segment
		(start 216.9668 -35.194748)
		(end 212.73262 -39.428928)
		(width 0.508)
		(layer "In4.Cu")
		(net "PVNN_TERM_CPU0")
	)
	(segment
		(start 85.261958 -184.18175)
		(end 85.208618 -184.23509)
		(width 0.508)
		(layer "In4.Cu")
		(net "PVNN_TERM_CPU0")
	)
	(segment
		(start 104.67721 -156.554678)
		(end 104.67721 -156.668216)
		(width 0.508)
		(layer "In4.Cu")
		(net "PVNN_TERM_CPU0")
	)
	(segment
		(start 383.448052 -170.120056)
		(end 375.987564 -162.659568)
		(width 0.508)
		(layer "In4.Cu")
		(net "PVNN_TERM_CPU0")
	)
	(segment
		(start 88.428322 -178.48707)
		(end 87.207344 -178.48707)
		(width 0.508)
		(layer "In4.Cu")
		(net "PVNN_TERM_CPU0")
	)
	(segment
		(start 143.434054 -139.223496)
		(end 138.371834 -144.285716)
		(width 0.508)
		(layer "In4.Cu")
		(net "PVNN_TERM_CPU0")
	)
	(segment
		(start 186.04738 -35.974528)
		(end 185.15076 -36.871148)
		(width 0.508)
		(layer "In4.Cu")
		(net "PVNN_TERM_CPU0")
	)
	(segment
		(start 104.67721 -156.668216)
		(end 89.19337 -172.152056)
		(width 0.508)
		(layer "In4.Cu")
		(net "PVNN_TERM_CPU0")
	)
	(segment
		(start 89.19337 -178.096418)
		(end 88.61552 -178.674268)
		(width 0.508)
		(layer "In4.Cu")
		(net "PVNN_TERM_CPU0")
	)
	(segment
		(start 220.391228 -35.194748)
		(end 216.9668 -35.194748)
		(width 0.508)
		(layer "In6.Cu")
		(net "PVNN_TERM_CPU0")
	)
	(segment
		(start 369.030758 -88.082374)
		(end 368.369088 -87.420704)
		(width 0.508)
		(layer "In6.Cu")
		(net "PVNN_TERM_CPU0")
	)
	(segment
		(start 251.780294 -40.119808)
		(end 250.694952 -41.20515)
		(width 0.508)
		(layer "In6.Cu")
		(net "PVNN_TERM_CPU0")
	)
	(segment
		(start 262.038846 -39.10076)
		(end 256.082546 -39.10076)
		(width 0.508)
		(layer "In6.Cu")
		(net "PVNN_TERM_CPU0")
	)
	(segment
		(start 374.9802 -97.284794)
		(end 374.9802 -91.641676)
		(width 0.508)
		(layer "In6.Cu")
		(net "PVNN_TERM_CPU0")
	)
	(segment
		(start 262.355076 -39.41699)
		(end 262.038846 -39.10076)
		(width 0.508)
		(layer "In6.Cu")
		(net "PVNN_TERM_CPU0")
	)
	(segment
		(start 397.434562 -157.20314)
		(end 397.434562 -147.373086)
		(width 0.508)
		(layer "In6.Cu")
		(net "PVNN_TERM_CPU0")
	)
	(segment
		(start 370.259356 -188.371988)
		(end 367.267744 -188.371988)
		(width 0.381)
		(layer "In6.Cu")
		(net "PVNN_TERM_CPU0")
	)
	(segment
		(start 245.757192 -40.119808)
		(end 242.85702 -40.119808)
		(width 0.508)
		(layer "In6.Cu")
		(net "PVNN_TERM_CPU0")
	)
	(segment
		(start 237.51159 -42.493438)
		(end 234.407964 -42.493438)
		(width 0.508)
		(layer "In6.Cu")
		(net "PVNN_TERM_CPU0")
	)
	(segment
		(start 242.85702 -40.119808)
		(end 241.064542 -41.912286)
		(width 0.508)
		(layer "In6.Cu")
		(net "PVNN_TERM_CPU0")
	)
	(segment
		(start 223.507046 -38.310566)
		(end 220.391228 -35.194748)
		(width 0.508)
		(layer "In6.Cu")
		(net "PVNN_TERM_CPU0")
	)
	(segment
		(start 253.95428 -40.119808)
		(end 251.780294 -40.119808)
		(width 0.508)
		(layer "In6.Cu")
		(net "PVNN_TERM_CPU0")
	)
	(segment
		(start 397.434562 -147.373086)
		(end 392.454892 -142.393416)
		(width 0.508)
		(layer "In6.Cu")
		(net "PVNN_TERM_CPU0")
	)
	(segment
		(start 371.53723 -87.205058)
		(end 371.055646 -87.205058)
		(width 0.508)
		(layer "In6.Cu")
		(net "PVNN_TERM_CPU0")
	)
	(segment
		(start 255.314704 -39.868602)
		(end 254.205486 -39.868602)
		(width 0.508)
		(layer "In6.Cu")
		(net "PVNN_TERM_CPU0")
	)
	(segment
		(start 372.036086 -88.697562)
		(end 372.036086 -87.703914)
		(width 0.508)
		(layer "In6.Cu")
		(net "PVNN_TERM_CPU0")
	)
	(segment
		(start 394.907262 -159.73044)
		(end 397.434562 -157.20314)
		(width 0.508)
		(layer "In6.Cu")
		(net "PVNN_TERM_CPU0")
	)
	(segment
		(start 246.842534 -41.20515)
		(end 245.757192 -40.119808)
		(width 0.508)
		(layer "In6.Cu")
		(net "PVNN_TERM_CPU0")
	)
	(segment
		(start 375.769632 -98.074226)
		(end 374.9802 -97.284794)
		(width 0.508)
		(layer "In6.Cu")
		(net "PVNN_TERM_CPU0")
	)
	(segment
		(start 254.205486 -39.868602)
		(end 253.95428 -40.119808)
		(width 0.508)
		(layer "In6.Cu")
		(net "PVNN_TERM_CPU0")
	)
	(segment
		(start 256.082546 -39.10076)
		(end 255.314704 -39.868602)
		(width 0.508)
		(layer "In6.Cu")
		(net "PVNN_TERM_CPU0")
	)
	(segment
		(start 392.454892 -142.393416)
		(end 392.454892 -110.193328)
		(width 0.508)
		(layer "In6.Cu")
		(net "PVNN_TERM_CPU0")
	)
	(segment
		(start 238.092742 -41.912286)
		(end 237.51159 -42.493438)
		(width 0.508)
		(layer "In6.Cu")
		(net "PVNN_TERM_CPU0")
	)
	(segment
		(start 367.267744 -188.371988)
		(end 364.088172 -185.192416)
		(width 0.381)
		(layer "In6.Cu")
		(net "PVNN_TERM_CPU0")
	)
	(segment
		(start 241.064542 -41.912286)
		(end 238.092742 -41.912286)
		(width 0.508)
		(layer "In6.Cu")
		(net "PVNN_TERM_CPU0")
	)
	(segment
		(start 372.036086 -87.703914)
		(end 371.53723 -87.205058)
		(width 0.508)
		(layer "In6.Cu")
		(net "PVNN_TERM_CPU0")
	)
	(segment
		(start 374.9802 -91.641676)
		(end 372.036086 -88.697562)
		(width 0.508)
		(layer "In6.Cu")
		(net "PVNN_TERM_CPU0")
	)
	(segment
		(start 250.694952 -41.20515)
		(end 246.842534 -41.20515)
		(width 0.508)
		(layer "In6.Cu")
		(net "PVNN_TERM_CPU0")
	)
	(segment
		(start 368.369088 -87.420704)
		(end 364.802928 -87.420704)
		(width 0.508)
		(layer "In6.Cu")
		(net "PVNN_TERM_CPU0")
	)
	(segment
		(start 371.055646 -87.205058)
		(end 370.17833 -88.082374)
		(width 0.508)
		(layer "In6.Cu")
		(net "PVNN_TERM_CPU0")
	)
	(segment
		(start 392.454892 -110.193328)
		(end 380.33579 -98.074226)
		(width 0.508)
		(layer "In6.Cu")
		(net "PVNN_TERM_CPU0")
	)
	(segment
		(start 230.225092 -38.310566)
		(end 223.507046 -38.310566)
		(width 0.508)
		(layer "In6.Cu")
		(net "PVNN_TERM_CPU0")
	)
	(segment
		(start 380.33579 -98.074226)
		(end 375.769632 -98.074226)
		(width 0.508)
		(layer "In6.Cu")
		(net "PVNN_TERM_CPU0")
	)
	(segment
		(start 234.407964 -42.493438)
		(end 230.225092 -38.310566)
		(width 0.508)
		(layer "In6.Cu")
		(net "PVNN_TERM_CPU0")
	)
	(segment
		(start 370.17833 -88.082374)
		(end 369.030758 -88.082374)
		(width 0.508)
		(layer "In6.Cu")
		(net "PVNN_TERM_CPU0")
	)
	(segment
		(start 69.021198 -186.525662)
		(end 69.021198 -185.140346)
		(width 0.381)
		(layer "In11.Cu")
		(net "PVNN_TERM_CPU0")
	)
	(segment
		(start 76.37018 -186.872626)
		(end 74.698098 -188.544708)
		(width 0.381)
		(layer "In11.Cu")
		(net "PVNN_TERM_CPU0")
	)
	(segment
		(start 409.713938 -359.579926)
		(end 408.785822 -359.579926)
		(width 0.381)
		(layer "In11.Cu")
		(net "PVNN_TERM_CPU0")
	)
	(segment
		(start 69.269102 -186.94273)
		(end 69.353684 -186.858148)
		(width 0.381)
		(layer "In11.Cu")
		(net "PVNN_TERM_CPU0")
	)
	(segment
		(start 320.473578 -344.56243)
		(end 319.448688 -343.53754)
		(width 0.508)
		(layer "In11.Cu")
		(net "PVNN_TERM_CPU0")
	)
	(segment
		(start 382.216914 -363.836966)
		(end 369.2398 -363.836966)
		(width 0.381)
		(layer "In11.Cu")
		(net "PVNN_TERM_CPU0")
	)
	(segment
		(start 321.968622 -58.283348)
		(end 321.40652 -58.283348)
		(width 0.508)
		(layer "In11.Cu")
		(net "PVNN_TERM_CPU0")
	)
	(segment
		(start 305.6128 -51.438556)
		(end 305.683666 -51.36769)
		(width 0.508)
		(layer "In11.Cu")
		(net "PVNN_TERM_CPU0")
	)
	(segment
		(start 366.550448 -361.147614)
		(end 366.550448 -360.153966)
		(width 0.381)
		(layer "In11.Cu")
		(net "PVNN_TERM_CPU0")
	)
	(segment
		(start 320.519044 -68.863972)
		(end 316.834012 -72.549004)
		(width 0.508)
		(layer "In11.Cu")
		(net "PVNN_TERM_CPU0")
	)
	(segment
		(start 307.240432 -46.68901)
		(end 306.21097 -45.659548)
		(width 0.508)
		(layer "In11.Cu")
		(net "PVNN_TERM_CPU0")
	)
	(segment
		(start 316.834012 -95.454724)
		(end 315.871606 -96.41713)
		(width 0.508)
		(layer "In11.Cu")
		(net "PVNN_TERM_CPU0")
	)
	(segment
		(start 74.698098 -188.544708)
		(end 69.784468 -188.544708)
		(width 0.381)
		(layer "In11.Cu")
		(net "PVNN_TERM_CPU0")
	)
	(segment
		(start 384.900678 -366.52073)
		(end 382.216914 -363.836966)
		(width 0.381)
		(layer "In11.Cu")
		(net "PVNN_TERM_CPU0")
	)
	(segment
		(start 306.21097 -45.659548)
		(end 298.211494 -45.659548)
		(width 0.508)
		(layer "In11.Cu")
		(net "PVNN_TERM_CPU0")
	)
	(segment
		(start 320.473578 -358.33177)
		(end 320.473578 -347.2307)
		(width 0.381)
		(layer "In11.Cu")
		(net "PVNN_TERM_CPU0")
	)
	(segment
		(start 76.37018 -182.320438)
		(end 76.37018 -186.872626)
		(width 0.381)
		(layer "In11.Cu")
		(net "PVNN_TERM_CPU0")
	)
	(segment
		(start 282.754578 -189.09157)
		(end 285.794958 -189.09157)
		(width 0.508)
		(layer "In11.Cu")
		(net "PVNN_TERM_CPU0")
	)
	(segment
		(start 321.40652 -58.283348)
		(end 320.519044 -59.170824)
		(width 0.508)
		(layer "In11.Cu")
		(net "PVNN_TERM_CPU0")
	)
	(segment
		(start 306.759102 -50.703734)
		(end 306.759102 -49.342802)
		(width 0.508)
		(layer "In11.Cu")
		(net "PVNN_TERM_CPU0")
	)
	(segment
		(start 69.784468 -188.544708)
		(end 69.269102 -188.029342)
		(width 0.381)
		(layer "In11.Cu")
		(net "PVNN_TERM_CPU0")
	)
	(segment
		(start 345.418918 -362.78947)
		(end 343.485978 -364.72241)
		(width 0.381)
		(layer "In11.Cu")
		(net "PVNN_TERM_CPU0")
	)
	(segment
		(start 69.269102 -188.029342)
		(end 69.269102 -186.94273)
		(width 0.381)
		(layer "In11.Cu")
		(net "PVNN_TERM_CPU0")
	)
	(segment
		(start 285.794958 -189.09157)
		(end 286.504888 -189.8015)
		(width 0.508)
		(layer "In11.Cu")
		(net "PVNN_TERM_CPU0")
	)
	(segment
		(start 399.047208 -360.580432)
		(end 393.10691 -366.52073)
		(width 0.381)
		(layer "In11.Cu")
		(net "PVNN_TERM_CPU0")
	)
	(segment
		(start 306.759102 -49.342802)
		(end 307.240432 -48.861472)
		(width 0.508)
		(layer "In11.Cu")
		(net "PVNN_TERM_CPU0")
	)
	(segment
		(start 345.418918 -357.238808)
		(end 345.418918 -362.78947)
		(width 0.381)
		(layer "In11.Cu")
		(net "PVNN_TERM_CPU0")
	)
	(segment
		(start 296.235882 -47.63516)
		(end 276.036024 -47.63516)
		(width 0.508)
		(layer "In11.Cu")
		(net "PVNN_TERM_CPU0")
	)
	(segment
		(start 305.683666 -51.36769)
		(end 306.095146 -51.36769)
		(width 0.508)
		(layer "In11.Cu")
		(net "PVNN_TERM_CPU0")
	)
	(segment
		(start 307.240432 -48.861472)
		(end 307.240432 -46.68901)
		(width 0.508)
		(layer "In11.Cu")
		(net "PVNN_TERM_CPU0")
	)
	(segment
		(start 82.685128 -181.7116)
		(end 75.761342 -181.7116)
		(width 0.508)
		(layer "In11.Cu")
		(net "PVNN_TERM_CPU0")
	)
	(segment
		(start 298.211494 -45.659548)
		(end 296.235882 -47.63516)
		(width 0.508)
		(layer "In11.Cu")
		(net "PVNN_TERM_CPU0")
	)
	(segment
		(start 69.021198 -185.140346)
		(end 68.6054 -184.724548)
		(width 0.381)
		(layer "In11.Cu")
		(net "PVNN_TERM_CPU0")
	)
	(segment
		(start 408.785822 -359.579926)
		(end 407.785316 -360.580432)
		(width 0.381)
		(layer "In11.Cu")
		(net "PVNN_TERM_CPU0")
	)
	(segment
		(start 326.864218 -364.72241)
		(end 320.473578 -358.33177)
		(width 0.381)
		(layer "In11.Cu")
		(net "PVNN_TERM_CPU0")
	)
	(segment
		(start 319.448688 -343.53754)
		(end 319.448688 -343.156032)
		(width 0.508)
		(layer "In11.Cu")
		(net "PVNN_TERM_CPU0")
	)
	(segment
		(start 69.353684 -186.858148)
		(end 69.021198 -186.525662)
		(width 0.381)
		(layer "In11.Cu")
		(net "PVNN_TERM_CPU0")
	)
	(segment
		(start 75.761342 -181.7116)
		(end 76.37018 -182.320438)
		(width 0.381)
		(layer "In11.Cu")
		(net "PVNN_TERM_CPU0")
	)
	(segment
		(start 407.785316 -360.580432)
		(end 399.047208 -360.580432)
		(width 0.381)
		(layer "In11.Cu")
		(net "PVNN_TERM_CPU0")
	)
	(segment
		(start 85.208618 -184.23509)
		(end 82.685128 -181.7116)
		(width 0.508)
		(layer "In11.Cu")
		(net "PVNN_TERM_CPU0")
	)
	(segment
		(start 393.10691 -366.52073)
		(end 384.900678 -366.52073)
		(width 0.381)
		(layer "In11.Cu")
		(net "PVNN_TERM_CPU0")
	)
	(segment
		(start 306.095146 -51.36769)
		(end 306.759102 -50.703734)
		(width 0.508)
		(layer "In11.Cu")
		(net "PVNN_TERM_CPU0")
	)
	(segment
		(start 316.834012 -72.549004)
		(end 316.834012 -95.454724)
		(width 0.508)
		(layer "In11.Cu")
		(net "PVNN_TERM_CPU0")
	)
	(segment
		(start 347.298264 -355.359462)
		(end 345.418918 -357.238808)
		(width 0.381)
		(layer "In11.Cu")
		(net "PVNN_TERM_CPU0")
	)
	(segment
		(start 369.2398 -363.836966)
		(end 366.550448 -361.147614)
		(width 0.381)
		(layer "In11.Cu")
		(net "PVNN_TERM_CPU0")
	)
	(segment
		(start 320.519044 -59.170824)
		(end 320.519044 -68.863972)
		(width 0.508)
		(layer "In11.Cu")
		(net "PVNN_TERM_CPU0")
	)
	(segment
		(start 320.473578 -347.2307)
		(end 320.473578 -344.56243)
		(width 0.508)
		(layer "In11.Cu")
		(net "PVNN_TERM_CPU0")
	)
	(segment
		(start 343.485978 -364.72241)
		(end 326.864218 -364.72241)
		(width 0.381)
		(layer "In11.Cu")
		(net "PVNN_TERM_CPU0")
	)
	(segment
		(start 316.145418 -54.797452)
		(end 317.98768 -54.797452)
		(width 0.381)
		(layer "In13.Cu")
		(net "PVNN_TERM_CPU0")
	)
	(segment
		(start 317.98768 -54.797452)
		(end 318.485774 -54.299358)
		(width 0.381)
		(layer "In13.Cu")
		(net "PVNN_TERM_CPU0")
	)
	(segment
		(start 433.665884 -139.066016)
		(end 432.79314 -138.193272)
		(width 0.381)
		(layer "In13.Cu")
		(net "PVNN_TERM_CPU0")
	)
	(segment
		(start 314.71743 -56.911748)
		(end 314.71743 -56.22544)
		(width 0.381)
		(layer "In13.Cu")
		(net "PVNN_TERM_CPU0")
	)
	(segment
		(start 322.231258 -54.299358)
		(end 323.522594 -55.590694)
		(width 0.381)
		(layer "In13.Cu")
		(net "PVNN_TERM_CPU0")
	)
	(segment
		(start 432.79314 -138.193272)
		(end 432.79314 -136.02716)
		(width 0.381)
		(layer "In13.Cu")
		(net "PVNN_TERM_CPU0")
	)
	(segment
		(start 314.71743 -56.22544)
		(end 316.145418 -54.797452)
		(width 0.381)
		(layer "In13.Cu")
		(net "PVNN_TERM_CPU0")
	)
	(segment
		(start 432.79314 -136.02716)
		(end 433.041044 -135.779256)
		(width 0.381)
		(layer "In13.Cu")
		(net "PVNN_TERM_CPU0")
	)
	(segment
		(start 323.522594 -55.590694)
		(end 323.522594 -56.729376)
		(width 0.381)
		(layer "In13.Cu")
		(net "PVNN_TERM_CPU0")
	)
	(segment
		(start 323.522594 -56.729376)
		(end 321.968622 -58.283348)
		(width 0.381)
		(layer "In13.Cu")
		(net "PVNN_TERM_CPU0")
	)
	(segment
		(start 318.485774 -54.299358)
		(end 322.231258 -54.299358)
		(width 0.381)
		(layer "In13.Cu")
		(net "PVNN_TERM_CPU0")
	)
	(via
		(at 23.26894 -183.239156)
		(size 0.508)
		(drill 0.254)
		(layers "F.Cu" "B.Cu")
		(net "PVNN_MAIN_CPU1_VCC")
	)
	(segment
		(start 22.619462 -184.011824)
		(end 22.619462 -184.31256)
		(width 0.381)
		(layer "B.Cu")
		(net "PVNN_MAIN_CPU1_VCC")
	)
	(segment
		(start 22.624542 -183.883554)
		(end 22.624542 -184.006744)
		(width 0.381)
		(layer "B.Cu")
		(net "PVNN_MAIN_CPU1_VCC")
	)
	(segment
		(start 23.26894 -183.239156)
		(end 22.624542 -183.883554)
		(width 0.381)
		(layer "B.Cu")
		(net "PVNN_MAIN_CPU1_VCC")
	)
	(segment
		(start 22.624542 -184.006744)
		(end 22.619462 -184.011824)
		(width 0.381)
		(layer "B.Cu")
		(net "PVNN_MAIN_CPU1_VCC")
	)
	(segment
		(start 25.11933 -177.339244)
		(end 25.11933 -176.850548)
		(width 0.3048)
		(layer "F.Cu")
		(net "PVNN_MAIN_CPU1_REF")
	)
	(segment
		(start 24.05507 -178.403504)
		(end 24.71293 -177.745644)
		(width 0.3048)
		(layer "F.Cu")
		(net "PVNN_MAIN_CPU1_REF")
	)
	(segment
		(start 24.71293 -177.745644)
		(end 25.11933 -177.339244)
		(width 0.3048)
		(layer "F.Cu")
		(net "PVNN_MAIN_CPU1_REF")
	)
	(via
		(at 24.71293 -177.745644)
		(size 0.508)
		(drill 0.254)
		(layers "F.Cu" "B.Cu")
		(net "PVNN_MAIN_CPU1_REF")
	)
	(segment
		(start 24.23287 -180.928264)
		(end 24.05507 -180.928264)
		(width 0.12954)
		(layer "F.Cu")
		(net "PVNN_MAIN_CPU1_MODE")
	)
	(segment
		(start 24.345646 -182.551324)
		(end 24.345646 -181.954932)
		(width 0.12954)
		(layer "F.Cu")
		(net "PVNN_MAIN_CPU1_MODE")
	)
	(segment
		(start 24.345646 -181.954932)
		(end 24.345646 -181.04104)
		(width 0.12954)
		(layer "F.Cu")
		(net "PVNN_MAIN_CPU1_MODE")
	)
	(segment
		(start 24.345646 -181.04104)
		(end 24.23287 -180.928264)
		(width 0.12954)
		(layer "F.Cu")
		(net "PVNN_MAIN_CPU1_MODE")
	)
	(segment
		(start 24.30145 -182.59552)
		(end 24.345646 -182.551324)
		(width 0.12954)
		(layer "F.Cu")
		(net "PVNN_MAIN_CPU1_MODE")
	)
	(via
		(at 24.345646 -181.954932)
		(size 0.508)
		(drill 0.254)
		(layers "F.Cu" "B.Cu")
		(net "PVNN_MAIN_CPU1_MODE")
	)
	(segment
		(start 21.89353 -176.864518)
		(end 21.89353 -178.017424)
		(width 0.254)
		(layer "F.Cu")
		(net "PVNN_MAIN_CPU1_FB")
	)
	(segment
		(start 21.953982 -174.79264)
		(end 21.953982 -174.616618)
		(width 0.254)
		(layer "F.Cu")
		(net "PVNN_MAIN_CPU1_FB")
	)
	(segment
		(start 22.354286 -178.47818)
		(end 22.855174 -178.47818)
		(width 0.254)
		(layer "F.Cu")
		(net "PVNN_MAIN_CPU1_FB")
	)
	(segment
		(start 21.699982 -176.031398)
		(end 21.953982 -175.777398)
		(width 0.254)
		(layer "F.Cu")
		(net "PVNN_MAIN_CPU1_FB")
	)
	(segment
		(start 21.953982 -175.423576)
		(end 21.953982 -174.79264)
		(width 0.254)
		(layer "F.Cu")
		(net "PVNN_MAIN_CPU1_FB")
	)
	(segment
		(start 21.699982 -176.67097)
		(end 21.89353 -176.864518)
		(width 0.254)
		(layer "F.Cu")
		(net "PVNN_MAIN_CPU1_FB")
	)
	(segment
		(start 21.89353 -178.017424)
		(end 22.354286 -178.47818)
		(width 0.254)
		(layer "F.Cu")
		(net "PVNN_MAIN_CPU1_FB")
	)
	(segment
		(start 21.953982 -175.777398)
		(end 21.953982 -175.423576)
		(width 0.254)
		(layer "F.Cu")
		(net "PVNN_MAIN_CPU1_FB")
	)
	(segment
		(start 21.699982 -176.329086)
		(end 21.699982 -176.031398)
		(width 0.254)
		(layer "F.Cu")
		(net "PVNN_MAIN_CPU1_FB")
	)
	(segment
		(start 21.956776 -174.613824)
		(end 21.956776 -174.113952)
		(width 0.254)
		(layer "F.Cu")
		(net "PVNN_MAIN_CPU1_FB")
	)
	(segment
		(start 21.953982 -174.616618)
		(end 21.956776 -174.613824)
		(width 0.254)
		(layer "F.Cu")
		(net "PVNN_MAIN_CPU1_FB")
	)
	(segment
		(start 21.699982 -176.329086)
		(end 21.699982 -176.67097)
		(width 0.254)
		(layer "F.Cu")
		(net "PVNN_MAIN_CPU1_FB")
	)
	(via
		(at 21.953982 -174.79264)
		(size 0.508)
		(drill 0.254)
		(layers "F.Cu" "B.Cu")
		(net "PVNN_MAIN_CPU1_FB")
	)
	(segment
		(start 21.083016 -179.105814)
		(end 20.831556 -178.854354)
		(width 0.12954)
		(layer "F.Cu")
		(net "PVNN_MAIN_CPU1_CS")
	)
	(segment
		(start 22.255226 -179.428394)
		(end 21.405596 -179.428394)
		(width 0.12954)
		(layer "F.Cu")
		(net "PVNN_MAIN_CPU1_CS")
	)
	(segment
		(start 21.405596 -179.428394)
		(end 21.083016 -179.105814)
		(width 0.12954)
		(layer "F.Cu")
		(net "PVNN_MAIN_CPU1_CS")
	)
	(segment
		(start 20.831556 -178.854354)
		(end 20.831556 -178.477418)
		(width 0.12954)
		(layer "F.Cu")
		(net "PVNN_MAIN_CPU1_CS")
	)
	(via
		(at 21.083016 -179.105814)
		(size 0.508)
		(drill 0.254)
		(layers "F.Cu" "B.Cu")
		(net "PVNN_MAIN_CPU1_CS")
	)
	(segment
		(start 105.531666 -228.99497)
		(end 105.531666 -228.459284)
		(width 0.254)
		(layer "F.Cu")
		(net "PVNN_MAIN_CPU1")
	)
	(segment
		(start 107.411266 -228.99497)
		(end 107.411266 -228.459284)
		(width 0.2032)
		(layer "F.Cu")
		(net "PVNN_MAIN_CPU1")
	)
	(segment
		(start 103.652066 -228.99497)
		(end 103.652066 -228.459284)
		(width 0.254)
		(layer "F.Cu")
		(net "PVNN_MAIN_CPU1")
	)
	(segment
		(start 27.98318 -174.11446)
		(end 36.179506 -174.11446)
		(width 0.254)
		(layer "F.Cu")
		(net "PVNN_MAIN_CPU1")
	)
	(segment
		(start 109.290866 -228.99497)
		(end 109.290866 -228.459284)
		(width 0.254)
		(layer "F.Cu")
		(net "PVNN_MAIN_CPU1")
	)
	(segment
		(start 107.411266 -228.459284)
		(end 107.411012 -228.45903)
		(width 0.2032)
		(layer "F.Cu")
		(net "PVNN_MAIN_CPU1")
	)
	(segment
		(start 109.290866 -228.459284)
		(end 109.290612 -228.45903)
		(width 0.254)
		(layer "F.Cu")
		(net "PVNN_MAIN_CPU1")
	)
	(segment
		(start 36.179506 -174.11446)
		(end 36.44138 -174.376334)
		(width 0.254)
		(layer "F.Cu")
		(net "PVNN_MAIN_CPU1")
	)
	(segment
		(start 24.777446 -174.91456)
		(end 25.0444 -174.91456)
		(width 0.254)
		(layer "F.Cu")
		(net "PVNN_MAIN_CPU1")
	)
	(segment
		(start 105.531666 -228.459284)
		(end 105.531412 -228.45903)
		(width 0.254)
		(layer "F.Cu")
		(net "PVNN_MAIN_CPU1")
	)
	(segment
		(start 103.652066 -228.459284)
		(end 103.651812 -228.45903)
		(width 0.254)
		(layer "F.Cu")
		(net "PVNN_MAIN_CPU1")
	)
	(segment
		(start 25.0444 -174.91456)
		(end 25.92324 -175.7934)
		(width 0.254)
		(layer "F.Cu")
		(net "PVNN_MAIN_CPU1")
	)
	(segment
		(start 36.44138 -174.376334)
		(end 36.44138 -174.804578)
		(width 0.254)
		(layer "F.Cu")
		(net "PVNN_MAIN_CPU1")
	)
	(via
		(at 36.259516 -177.497994)
		(size 0.508)
		(drill 0.254)
		(layers "F.Cu" "B.Cu")
		(net "PVNN_MAIN_CPU1")
	)
	(via
		(at 33.10255 -182.225696)
		(size 0.6604)
		(drill 0.3302)
		(layers "F.Cu" "B.Cu")
		(net "PVNN_MAIN_CPU1")
	)
	(via
		(at 35.642804 -183.30164)
		(size 0.508)
		(drill 0.254)
		(layers "F.Cu" "B.Cu")
		(net "PVNN_MAIN_CPU1")
	)
	(via
		(at 40.926004 -183.30164)
		(size 0.508)
		(drill 0.254)
		(layers "F.Cu" "B.Cu")
		(net "PVNN_MAIN_CPU1")
	)
	(via
		(at 40.913812 -179.53609)
		(size 0.508)
		(drill 0.254)
		(layers "F.Cu" "B.Cu")
		(net "PVNN_MAIN_CPU1")
	)
	(via
		(at 103.651812 -228.45903)
		(size 0.4572)
		(drill 0.2032)
		(layers "F.Cu" "B.Cu")
		(net "PVNN_MAIN_CPU1")
	)
	(via
		(at 36.265612 -179.53609)
		(size 0.508)
		(drill 0.254)
		(layers "F.Cu" "B.Cu")
		(net "PVNN_MAIN_CPU1")
	)
	(via
		(at 36.277804 -183.30164)
		(size 0.508)
		(drill 0.254)
		(layers "F.Cu" "B.Cu")
		(net "PVNN_MAIN_CPU1")
	)
	(via
		(at 35.630612 -179.53609)
		(size 0.508)
		(drill 0.254)
		(layers "F.Cu" "B.Cu")
		(net "PVNN_MAIN_CPU1")
	)
	(via
		(at 25.92324 -175.7934)
		(size 0.508)
		(drill 0.254)
		(layers "F.Cu" "B.Cu")
		(net "PVNN_MAIN_CPU1")
	)
	(via
		(at 41.548812 -179.53609)
		(size 0.508)
		(drill 0.254)
		(layers "F.Cu" "B.Cu")
		(net "PVNN_MAIN_CPU1")
	)
	(via
		(at 109.290612 -228.45903)
		(size 0.4572)
		(drill 0.2032)
		(layers "F.Cu" "B.Cu")
		(net "PVNN_MAIN_CPU1")
	)
	(via
		(at 105.531412 -228.45903)
		(size 0.4572)
		(drill 0.2032)
		(layers "F.Cu" "B.Cu")
		(net "PVNN_MAIN_CPU1")
	)
	(via
		(at 35.624516 -177.497994)
		(size 0.508)
		(drill 0.254)
		(layers "F.Cu" "B.Cu")
		(net "PVNN_MAIN_CPU1")
	)
	(via
		(at 107.296458 -235.52277)
		(size 0.4572)
		(drill 0.2032)
		(layers "F.Cu" "B.Cu")
		(net "PVNN_MAIN_CPU1")
	)
	(via
		(at 107.411012 -228.45903)
		(size 0.4572)
		(drill 0.2032)
		(layers "F.Cu" "B.Cu")
		(net "PVNN_MAIN_CPU1")
	)
	(via
		(at 35.67684 -175.464978)
		(size 0.508)
		(drill 0.254)
		(layers "F.Cu" "B.Cu")
		(net "PVNN_MAIN_CPU1")
	)
	(via
		(at 107.931458 -235.52277)
		(size 0.4572)
		(drill 0.2032)
		(layers "F.Cu" "B.Cu")
		(net "PVNN_MAIN_CPU1")
	)
	(via
		(at 36.31184 -175.464978)
		(size 0.508)
		(drill 0.254)
		(layers "F.Cu" "B.Cu")
		(net "PVNN_MAIN_CPU1")
	)
	(via
		(at 33.10255 -177.755296)
		(size 0.6604)
		(drill 0.3302)
		(layers "F.Cu" "B.Cu")
		(net "PVNN_MAIN_CPU1")
	)
	(via
		(at 108.121704 -236.08411)
		(size 0.4572)
		(drill 0.2032)
		(layers "F.Cu" "B.Cu")
		(net "PVNN_MAIN_CPU1")
	)
	(via
		(at 107.486704 -236.08411)
		(size 0.4572)
		(drill 0.2032)
		(layers "F.Cu" "B.Cu")
		(net "PVNN_MAIN_CPU1")
	)
	(via
		(at 41.561004 -183.30164)
		(size 0.508)
		(drill 0.254)
		(layers "F.Cu" "B.Cu")
		(net "PVNN_MAIN_CPU1")
	)
	(via
		(at 33.10255 -179.990496)
		(size 0.6604)
		(drill 0.3302)
		(layers "F.Cu" "B.Cu")
		(net "PVNN_MAIN_CPU1")
	)
	(segment
		(start 23.127716 -179.362862)
		(end 23.127716 -177.66538)
		(width 0.254)
		(layer "In6.Cu")
		(net "PVNN_MAIN_CPU1")
	)
	(segment
		(start 85.503258 -216.19083)
		(end 79.0956 -209.783172)
		(width 0.254)
		(layer "In6.Cu")
		(net "PVNN_MAIN_CPU1")
	)
	(segment
		(start 100.175568 -224.7138)
		(end 100.166678 -224.70872)
		(width 0.0889)
		(layer "In6.Cu")
		(net "PVNN_MAIN_CPU1")
	)
	(segment
		(start 24.999696 -175.7934)
		(end 25.92324 -175.7934)
		(width 0.254)
		(layer "In6.Cu")
		(net "PVNN_MAIN_CPU1")
	)
	(segment
		(start 102.337362 -228.45903)
		(end 102.337362 -228.436932)
		(width 0.0889)
		(layer "In6.Cu")
		(net "PVNN_MAIN_CPU1")
	)
	(segment
		(start 97.638362 -221.956376)
		(end 97.638362 -221.932246)
		(width 0.0889)
		(layer "In6.Cu")
		(net "PVNN_MAIN_CPU1")
	)
	(segment
		(start 85.503258 -216.512902)
		(end 85.503258 -216.19083)
		(width 0.254)
		(layer "In6.Cu")
		(net "PVNN_MAIN_CPU1")
	)
	(segment
		(start 28.612084 -184.84723)
		(end 23.127716 -179.362862)
		(width 0.254)
		(layer "In6.Cu")
		(net "PVNN_MAIN_CPU1")
	)
	(segment
		(start 55.198518 -184.84723)
		(end 28.612084 -184.84723)
		(width 0.254)
		(layer "In6.Cu")
		(net "PVNN_MAIN_CPU1")
	)
	(segment
		(start 57.636156 -187.284868)
		(end 55.198518 -184.84723)
		(width 0.254)
		(layer "In6.Cu")
		(net "PVNN_MAIN_CPU1")
	)
	(segment
		(start 72.925178 -194.886834)
		(end 68.881498 -190.843154)
		(width 0.254)
		(layer "In6.Cu")
		(net "PVNN_MAIN_CPU1")
	)
	(segment
		(start 107.567476 -228.786944)
		(end 107.546394 -228.808026)
		(width 0.0889)
		(layer "In6.Cu")
		(net "PVNN_MAIN_CPU1")
	)
	(segment
		(start 93.986096 -219.82176)
		(end 93.971364 -219.830396)
		(width 0.0889)
		(layer "In6.Cu")
		(net "PVNN_MAIN_CPU1")
	)
	(segment
		(start 85.503258 -216.55405)
		(end 85.503258 -216.512902)
		(width 0.0889)
		(layer "In6.Cu")
		(net "PVNN_MAIN_CPU1")
	)
	(segment
		(start 85.891116 -218.206828)
		(end 85.891116 -217.864182)
		(width 0.0889)
		(layer "In6.Cu")
		(net "PVNN_MAIN_CPU1")
	)
	(segment
		(start 90.226896 -219.82176)
		(end 90.212164 -219.830396)
		(width 0.0889)
		(layer "In6.Cu")
		(net "PVNN_MAIN_CPU1")
	)
	(segment
		(start 103.464614 -228.783388)
		(end 103.449882 -228.774752)
		(width 0.0889)
		(layer "In6.Cu")
		(net "PVNN_MAIN_CPU1")
	)
	(segment
		(start 97.168716 -221.133924)
		(end 97.168716 -221.115382)
		(width 0.0889)
		(layer "In6.Cu")
		(net "PVNN_MAIN_CPU1")
	)
	(segment
		(start 99.71151 -222.275654)
		(end 99.705414 -222.272098)
		(width 0.0889)
		(layer "In6.Cu")
		(net "PVNN_MAIN_CPU1")
	)
	(segment
		(start 98.765614 -222.272098)
		(end 98.750882 -222.263462)
		(width 0.0889)
		(layer "In6.Cu")
		(net "PVNN_MAIN_CPU1")
	)
	(segment
		(start 100.927916 -226.017328)
		(end 100.927916 -226.003104)
		(width 0.0889)
		(layer "In6.Cu")
		(net "PVNN_MAIN_CPU1")
	)
	(segment
		(start 100.175568 -224.065084)
		(end 100.181664 -224.061528)
		(width 0.0889)
		(layer "In6.Cu")
		(net "PVNN_MAIN_CPU1")
	)
	(segment
		(start 107.411012 -228.45903)
		(end 107.567476 -228.730048)
		(width 0.0889)
		(layer "In6.Cu")
		(net "PVNN_MAIN_CPU1")
	)
	(segment
		(start 107.223814 -228.783388)
		(end 107.209082 -228.774752)
		(width 0.0889)
		(layer "In6.Cu")
		(net "PVNN_MAIN_CPU1")
	)
	(segment
		(start 97.356168 -221.458282)
		(end 97.347278 -221.453202)
		(width 0.0889)
		(layer "In6.Cu")
		(net "PVNN_MAIN_CPU1")
	)
	(segment
		(start 85.420708 -216.6366)
		(end 85.503258 -216.55405)
		(width 0.0889)
		(layer "In6.Cu")
		(net "PVNN_MAIN_CPU1")
	)
	(segment
		(start 87.517732 -219.833444)
		(end 85.891116 -218.206828)
		(width 0.0889)
		(layer "In6.Cu")
		(net "PVNN_MAIN_CPU1")
	)
	(segment
		(start 100.166678 -224.070164)
		(end 100.175568 -224.065084)
		(width 0.0889)
		(layer "In6.Cu")
		(net "PVNN_MAIN_CPU1")
	)
	(segment
		(start 96.886268 -220.644212)
		(end 96.877378 -220.639132)
		(width 0.0889)
		(layer "In6.Cu")
		(net "PVNN_MAIN_CPU1")
	)
	(segment
		(start 23.127716 -177.66538)
		(end 24.999696 -175.7934)
		(width 0.254)
		(layer "In6.Cu")
		(net "PVNN_MAIN_CPU1")
	)
	(segment
		(start 100.457762 -225.203258)
		(end 100.457762 -225.187764)
		(width 0.0889)
		(layer "In6.Cu")
		(net "PVNN_MAIN_CPU1")
	)
	(segment
		(start 101.115368 -226.341686)
		(end 101.106478 -226.336606)
		(width 0.0889)
		(layer "In6.Cu")
		(net "PVNN_MAIN_CPU1")
	)
	(segment
		(start 100.175568 -223.085914)
		(end 100.166678 -223.080834)
		(width 0.0889)
		(layer "In6.Cu")
		(net "PVNN_MAIN_CPU1")
	)
	(segment
		(start 85.421216 -217.072972)
		(end 85.420708 -217.072464)
		(width 0.0889)
		(layer "In6.Cu")
		(net "PVNN_MAIN_CPU1")
	)
	(segment
		(start 92.106496 -219.82176)
		(end 92.091764 -219.830396)
		(width 0.0889)
		(layer "In6.Cu")
		(net "PVNN_MAIN_CPU1")
	)
	(segment
		(start 95.865696 -219.82176)
		(end 95.850964 -219.830396)
		(width 0.0889)
		(layer "In6.Cu")
		(net "PVNN_MAIN_CPU1")
	)
	(segment
		(start 101.867716 -227.64496)
		(end 101.867716 -227.644706)
		(width 0.0889)
		(layer "In6.Cu")
		(net "PVNN_MAIN_CPU1")
	)
	(segment
		(start 102.055168 -227.969318)
		(end 102.046278 -227.964238)
		(width 0.0889)
		(layer "In6.Cu")
		(net "PVNN_MAIN_CPU1")
	)
	(segment
		(start 107.567476 -228.730048)
		(end 107.567476 -228.786944)
		(width 0.0889)
		(layer "In6.Cu")
		(net "PVNN_MAIN_CPU1")
	)
	(segment
		(start 68.881498 -190.843154)
		(end 67.632834 -190.843154)
		(width 0.254)
		(layer "In6.Cu")
		(net "PVNN_MAIN_CPU1")
	)
	(segment
		(start 64.074548 -187.284868)
		(end 57.636156 -187.284868)
		(width 0.254)
		(layer "In6.Cu")
		(net "PVNN_MAIN_CPU1")
	)
	(segment
		(start 88.145366 -219.880688)
		(end 87.631778 -219.880688)
		(width 0.0889)
		(layer "In6.Cu")
		(net "PVNN_MAIN_CPU1")
	)
	(segment
		(start 96.422464 -219.833952)
		(end 96.416368 -219.830396)
		(width 0.0889)
		(layer "In6.Cu")
		(net "PVNN_MAIN_CPU1")
	)
	(segment
		(start 106.284014 -228.783388)
		(end 106.269282 -228.774752)
		(width 0.0889)
		(layer "In6.Cu")
		(net "PVNN_MAIN_CPU1")
	)
	(segment
		(start 67.632834 -190.843154)
		(end 64.074548 -187.284868)
		(width 0.254)
		(layer "In6.Cu")
		(net "PVNN_MAIN_CPU1")
	)
	(segment
		(start 101.397816 -226.83978)
		(end 101.397816 -226.821238)
		(width 0.0889)
		(layer "In6.Cu")
		(net "PVNN_MAIN_CPU1")
	)
	(segment
		(start 97.825814 -222.272098)
		(end 97.819464 -222.268288)
		(width 0.0889)
		(layer "In6.Cu")
		(net "PVNN_MAIN_CPU1")
	)
	(segment
		(start 104.404414 -228.783388)
		(end 104.389682 -228.774752)
		(width 0.0889)
		(layer "In6.Cu")
		(net "PVNN_MAIN_CPU1")
	)
	(segment
		(start 85.420708 -217.072464)
		(end 85.420708 -216.6366)
		(width 0.0889)
		(layer "In6.Cu")
		(net "PVNN_MAIN_CPU1")
	)
	(segment
		(start 100.458016 -223.575626)
		(end 100.458016 -223.561402)
		(width 0.0889)
		(layer "In6.Cu")
		(net "PVNN_MAIN_CPU1")
	)
	(segment
		(start 101.591618 -227.159058)
		(end 101.585014 -227.155502)
		(width 0.0889)
		(layer "In6.Cu")
		(net "PVNN_MAIN_CPU1")
	)
	(segment
		(start 99.705414 -222.272098)
		(end 99.690682 -222.263462)
		(width 0.0889)
		(layer "In6.Cu")
		(net "PVNN_MAIN_CPU1")
	)
	(segment
		(start 79.0956 -209.783172)
		(end 72.925178 -194.886834)
		(width 0.254)
		(layer "In6.Cu")
		(net "PVNN_MAIN_CPU1")
	)
	(segment
		(start 100.645214 -225.527616)
		(end 100.636324 -225.522536)
		(width 0.0889)
		(layer "In6.Cu")
		(net "PVNN_MAIN_CPU1")
	)
	(segment
		(start 105.344214 -228.783388)
		(end 105.329482 -228.774752)
		(width 0.0889)
		(layer "In6.Cu")
		(net "PVNN_MAIN_CPU1")
	)
	(arc
		(start 99.14001 -222.272098)
		(mid 98.952812 -222.322241)
		(end 98.765614 -222.272098)
		(width 0.0889)
		(layer "In6.Cu")
		(net "PVNN_MAIN_CPU1")
	)
	(arc
		(start 100.166678 -224.70872)
		(mid 99.988081 -224.389442)
		(end 100.166678 -224.070164)
		(width 0.0889)
		(layer "In6.Cu")
		(net "PVNN_MAIN_CPU1")
	)
	(arc
		(start 90.777568 -219.830396)
		(mid 90.503369 -219.754561)
		(end 90.226896 -219.82176)
		(width 0.0889)
		(layer "In6.Cu")
		(net "PVNN_MAIN_CPU1")
	)
	(arc
		(start 102.337362 -228.436932)
		(mid 102.256451 -228.166804)
		(end 102.055168 -227.969318)
		(width 0.0889)
		(layer "In6.Cu")
		(net "PVNN_MAIN_CPU1")
	)
	(arc
		(start 94.536768 -219.830396)
		(mid 94.262569 -219.754561)
		(end 93.986096 -219.82176)
		(width 0.0889)
		(layer "In6.Cu")
		(net "PVNN_MAIN_CPU1")
	)
	(arc
		(start 96.698816 -220.319854)
		(mid 96.6249 -220.040352)
		(end 96.422464 -219.833952)
		(width 0.0889)
		(layer "In6.Cu")
		(net "PVNN_MAIN_CPU1")
	)
	(arc
		(start 101.397816 -226.821238)
		(mid 101.319705 -226.544289)
		(end 101.115368 -226.341686)
		(width 0.0889)
		(layer "In6.Cu")
		(net "PVNN_MAIN_CPU1")
	)
	(arc
		(start 97.638362 -221.932246)
		(mid 97.558992 -221.658512)
		(end 97.356168 -221.458282)
		(width 0.0889)
		(layer "In6.Cu")
		(net "PVNN_MAIN_CPU1")
	)
	(arc
		(start 100.166678 -223.080834)
		(mid 100.035764 -222.944474)
		(end 99.988116 -222.761556)
		(width 0.0889)
		(layer "In6.Cu")
		(net "PVNN_MAIN_CPU1")
	)
	(arc
		(start 91.151964 -219.830396)
		(mid 90.964766 -219.880539)
		(end 90.777568 -219.830396)
		(width 0.0889)
		(layer "In6.Cu")
		(net "PVNN_MAIN_CPU1")
	)
	(arc
		(start 96.877378 -220.639132)
		(mid 96.746464 -220.502772)
		(end 96.698816 -220.319854)
		(width 0.0889)
		(layer "In6.Cu")
		(net "PVNN_MAIN_CPU1")
	)
	(arc
		(start 93.971364 -219.830396)
		(mid 93.784166 -219.880539)
		(end 93.596968 -219.830396)
		(width 0.0889)
		(layer "In6.Cu")
		(net "PVNN_MAIN_CPU1")
	)
	(arc
		(start 103.83901 -228.783388)
		(mid 103.651812 -228.833531)
		(end 103.464614 -228.783388)
		(width 0.0889)
		(layer "In6.Cu")
		(net "PVNN_MAIN_CPU1")
	)
	(arc
		(start 107.546394 -228.808026)
		(mid 107.382298 -228.832373)
		(end 107.223814 -228.783388)
		(width 0.0889)
		(layer "In6.Cu")
		(net "PVNN_MAIN_CPU1")
	)
	(arc
		(start 105.71861 -228.783388)
		(mid 105.531412 -228.833531)
		(end 105.344214 -228.783388)
		(width 0.0889)
		(layer "In6.Cu")
		(net "PVNN_MAIN_CPU1")
	)
	(arc
		(start 105.329482 -228.774752)
		(mid 105.053007 -228.707432)
		(end 104.77881 -228.783388)
		(width 0.0889)
		(layer "In6.Cu")
		(net "PVNN_MAIN_CPU1")
	)
	(arc
		(start 97.168716 -221.115382)
		(mid 97.088554 -220.843193)
		(end 96.886268 -220.644212)
		(width 0.0889)
		(layer "In6.Cu")
		(net "PVNN_MAIN_CPU1")
	)
	(arc
		(start 98.750882 -222.263462)
		(mid 98.474407 -222.196142)
		(end 98.20021 -222.272098)
		(width 0.0889)
		(layer "In6.Cu")
		(net "PVNN_MAIN_CPU1")
	)
	(arc
		(start 87.631778 -219.880688)
		(mid 87.570055 -219.868411)
		(end 87.517732 -219.833444)
		(width 0.0889)
		(layer "In6.Cu")
		(net "PVNN_MAIN_CPU1")
	)
	(arc
		(start 101.867716 -227.644706)
		(mid 101.793919 -227.36536)
		(end 101.591618 -227.159058)
		(width 0.0889)
		(layer "In6.Cu")
		(net "PVNN_MAIN_CPU1")
	)
	(arc
		(start 104.77881 -228.783388)
		(mid 104.591612 -228.833531)
		(end 104.404414 -228.783388)
		(width 0.0889)
		(layer "In6.Cu")
		(net "PVNN_MAIN_CPU1")
	)
	(arc
		(start 89.272364 -219.830396)
		(mid 89.085166 -219.880539)
		(end 88.897968 -219.830396)
		(width 0.0889)
		(layer "In6.Cu")
		(net "PVNN_MAIN_CPU1")
	)
	(arc
		(start 90.212164 -219.830396)
		(mid 90.024966 -219.880539)
		(end 89.837768 -219.830396)
		(width 0.0889)
		(layer "In6.Cu")
		(net "PVNN_MAIN_CPU1")
	)
	(arc
		(start 98.20021 -222.272098)
		(mid 98.013012 -222.322241)
		(end 97.825814 -222.272098)
		(width 0.0889)
		(layer "In6.Cu")
		(net "PVNN_MAIN_CPU1")
	)
	(arc
		(start 107.209082 -228.774752)
		(mid 106.932607 -228.707432)
		(end 106.65841 -228.783388)
		(width 0.0889)
		(layer "In6.Cu")
		(net "PVNN_MAIN_CPU1")
	)
	(arc
		(start 97.347278 -221.453202)
		(mid 97.216364 -221.316842)
		(end 97.168716 -221.133924)
		(width 0.0889)
		(layer "In6.Cu")
		(net "PVNN_MAIN_CPU1")
	)
	(arc
		(start 102.046278 -227.964238)
		(mid 101.915364 -227.827878)
		(end 101.867716 -227.64496)
		(width 0.0889)
		(layer "In6.Cu")
		(net "PVNN_MAIN_CPU1")
	)
	(arc
		(start 85.608414 -217.388694)
		(mid 85.473481 -217.25534)
		(end 85.421216 -217.072972)
		(width 0.0889)
		(layer "In6.Cu")
		(net "PVNN_MAIN_CPU1")
	)
	(arc
		(start 95.850964 -219.830396)
		(mid 95.663766 -219.880539)
		(end 95.476568 -219.830396)
		(width 0.0889)
		(layer "In6.Cu")
		(net "PVNN_MAIN_CPU1")
	)
	(arc
		(start 85.891116 -217.864182)
		(mid 85.811897 -217.589497)
		(end 85.608414 -217.388694)
		(width 0.0889)
		(layer "In6.Cu")
		(net "PVNN_MAIN_CPU1")
	)
	(arc
		(start 100.927916 -226.003104)
		(mid 100.848697 -225.728419)
		(end 100.645214 -225.527616)
		(width 0.0889)
		(layer "In6.Cu")
		(net "PVNN_MAIN_CPU1")
	)
	(arc
		(start 93.031564 -219.830396)
		(mid 92.844366 -219.880539)
		(end 92.657168 -219.830396)
		(width 0.0889)
		(layer "In6.Cu")
		(net "PVNN_MAIN_CPU1")
	)
	(arc
		(start 97.819464 -222.268288)
		(mid 97.686921 -222.136714)
		(end 97.638362 -221.956376)
		(width 0.0889)
		(layer "In6.Cu")
		(net "PVNN_MAIN_CPU1")
	)
	(arc
		(start 100.181664 -224.061528)
		(mid 100.384077 -223.855115)
		(end 100.458016 -223.575626)
		(width 0.0889)
		(layer "In6.Cu")
		(net "PVNN_MAIN_CPU1")
	)
	(arc
		(start 92.091764 -219.830396)
		(mid 91.904566 -219.880539)
		(end 91.717368 -219.830396)
		(width 0.0889)
		(layer "In6.Cu")
		(net "PVNN_MAIN_CPU1")
	)
	(arc
		(start 106.269282 -228.774752)
		(mid 105.992807 -228.707432)
		(end 105.71861 -228.783388)
		(width 0.0889)
		(layer "In6.Cu")
		(net "PVNN_MAIN_CPU1")
	)
	(arc
		(start 100.457762 -225.187764)
		(mid 100.378392 -224.91403)
		(end 100.175568 -224.7138)
		(width 0.0889)
		(layer "In6.Cu")
		(net "PVNN_MAIN_CPU1")
	)
	(arc
		(start 106.65841 -228.783388)
		(mid 106.471212 -228.833531)
		(end 106.284014 -228.783388)
		(width 0.0889)
		(layer "In6.Cu")
		(net "PVNN_MAIN_CPU1")
	)
	(arc
		(start 100.636324 -225.522536)
		(mid 100.50541 -225.386176)
		(end 100.457762 -225.203258)
		(width 0.0889)
		(layer "In6.Cu")
		(net "PVNN_MAIN_CPU1")
	)
	(arc
		(start 91.717368 -219.830396)
		(mid 91.434666 -219.75462)
		(end 91.151964 -219.830396)
		(width 0.0889)
		(layer "In6.Cu")
		(net "PVNN_MAIN_CPU1")
	)
	(arc
		(start 104.389682 -228.774752)
		(mid 104.113207 -228.707432)
		(end 103.83901 -228.783388)
		(width 0.0889)
		(layer "In6.Cu")
		(net "PVNN_MAIN_CPU1")
	)
	(arc
		(start 101.106478 -226.336606)
		(mid 100.975564 -226.200246)
		(end 100.927916 -226.017328)
		(width 0.0889)
		(layer "In6.Cu")
		(net "PVNN_MAIN_CPU1")
	)
	(arc
		(start 93.596968 -219.830396)
		(mid 93.314266 -219.75462)
		(end 93.031564 -219.830396)
		(width 0.0889)
		(layer "In6.Cu")
		(net "PVNN_MAIN_CPU1")
	)
	(arc
		(start 102.89921 -228.783388)
		(mid 102.524735 -228.783342)
		(end 102.337362 -228.45903)
		(width 0.0889)
		(layer "In6.Cu")
		(net "PVNN_MAIN_CPU1")
	)
	(arc
		(start 100.458016 -223.561402)
		(mid 100.378875 -223.286779)
		(end 100.175568 -223.085914)
		(width 0.0889)
		(layer "In6.Cu")
		(net "PVNN_MAIN_CPU1")
	)
	(arc
		(start 103.449882 -228.774752)
		(mid 103.173407 -228.707432)
		(end 102.89921 -228.783388)
		(width 0.0889)
		(layer "In6.Cu")
		(net "PVNN_MAIN_CPU1")
	)
	(arc
		(start 99.690682 -222.263462)
		(mid 99.414207 -222.196142)
		(end 99.14001 -222.272098)
		(width 0.0889)
		(layer "In6.Cu")
		(net "PVNN_MAIN_CPU1")
	)
	(arc
		(start 88.332564 -219.830396)
		(mid 88.242272 -219.867848)
		(end 88.145366 -219.880688)
		(width 0.0889)
		(layer "In6.Cu")
		(net "PVNN_MAIN_CPU1")
	)
	(arc
		(start 101.585014 -227.155502)
		(mid 101.450081 -227.022148)
		(end 101.397816 -226.83978)
		(width 0.0889)
		(layer "In6.Cu")
		(net "PVNN_MAIN_CPU1")
	)
	(arc
		(start 88.897968 -219.830396)
		(mid 88.615266 -219.75462)
		(end 88.332564 -219.830396)
		(width 0.0889)
		(layer "In6.Cu")
		(net "PVNN_MAIN_CPU1")
	)
	(arc
		(start 94.911164 -219.830396)
		(mid 94.723966 -219.880539)
		(end 94.536768 -219.830396)
		(width 0.0889)
		(layer "In6.Cu")
		(net "PVNN_MAIN_CPU1")
	)
	(arc
		(start 99.988116 -222.761556)
		(mid 99.914125 -222.48199)
		(end 99.71151 -222.275654)
		(width 0.0889)
		(layer "In6.Cu")
		(net "PVNN_MAIN_CPU1")
	)
	(arc
		(start 89.837768 -219.830396)
		(mid 89.555066 -219.75462)
		(end 89.272364 -219.830396)
		(width 0.0889)
		(layer "In6.Cu")
		(net "PVNN_MAIN_CPU1")
	)
	(arc
		(start 95.476568 -219.830396)
		(mid 95.193866 -219.75462)
		(end 94.911164 -219.830396)
		(width 0.0889)
		(layer "In6.Cu")
		(net "PVNN_MAIN_CPU1")
	)
	(arc
		(start 96.416368 -219.830396)
		(mid 96.142169 -219.754561)
		(end 95.865696 -219.82176)
		(width 0.0889)
		(layer "In6.Cu")
		(net "PVNN_MAIN_CPU1")
	)
	(arc
		(start 92.657168 -219.830396)
		(mid 92.382969 -219.754561)
		(end 92.106496 -219.82176)
		(width 0.0889)
		(layer "In6.Cu")
		(net "PVNN_MAIN_CPU1")
	)
	(segment
		(start 433.07889 -184.544208)
		(end 433.07889 -185.21934)
		(width 0.4572)
		(layer "F.Cu")
		(net "PVNN_MAIN_CPU0_VCC")
	)
	(via
		(at 433.07889 -185.21934)
		(size 0.508)
		(drill 0.254)
		(layers "F.Cu" "B.Cu")
		(net "PVNN_MAIN_CPU0_VCC")
	)
	(segment
		(start 434.370988 -178.691286)
		(end 434.370988 -178.690016)
		(width 0.381)
		(layer "F.Cu")
		(net "PVNN_MAIN_CPU0_REF")
	)
	(segment
		(start 433.866798 -179.46243)
		(end 434.10124 -179.227988)
		(width 0.381)
		(layer "F.Cu")
		(net "PVNN_MAIN_CPU0_REF")
	)
	(segment
		(start 434.370988 -178.690016)
		(end 434.46573 -178.595274)
		(width 0.381)
		(layer "F.Cu")
		(net "PVNN_MAIN_CPU0_REF")
	)
	(segment
		(start 434.10124 -179.227988)
		(end 434.10124 -178.959764)
		(width 0.381)
		(layer "F.Cu")
		(net "PVNN_MAIN_CPU0_REF")
	)
	(segment
		(start 434.370734 -178.691032)
		(end 434.370988 -178.691286)
		(width 0.381)
		(layer "F.Cu")
		(net "PVNN_MAIN_CPU0_REF")
	)
	(segment
		(start 434.10124 -178.959764)
		(end 434.369972 -178.691032)
		(width 0.381)
		(layer "F.Cu")
		(net "PVNN_MAIN_CPU0_REF")
	)
	(segment
		(start 434.369972 -178.691032)
		(end 434.370734 -178.691032)
		(width 0.381)
		(layer "F.Cu")
		(net "PVNN_MAIN_CPU0_REF")
	)
	(segment
		(start 434.46573 -178.595274)
		(end 434.46573 -178.069748)
		(width 0.381)
		(layer "F.Cu")
		(net "PVNN_MAIN_CPU0_REF")
	)
	(via
		(at 434.370988 -178.691286)
		(size 0.508)
		(drill 0.254)
		(layers "F.Cu" "B.Cu")
		(net "PVNN_MAIN_CPU0_REF")
	)
	(segment
		(start 434.296312 -182.697882)
		(end 434.296312 -183.258206)
		(width 0.254)
		(layer "F.Cu")
		(net "PVNN_MAIN_CPU0_MODE")
	)
	(segment
		(start 433.866798 -181.976268)
		(end 433.942998 -182.052468)
		(width 0.254)
		(layer "F.Cu")
		(net "PVNN_MAIN_CPU0_MODE")
	)
	(segment
		(start 434.296312 -183.258206)
		(end 434.113178 -183.44134)
		(width 0.254)
		(layer "F.Cu")
		(net "PVNN_MAIN_CPU0_MODE")
	)
	(segment
		(start 434.296312 -182.320438)
		(end 434.296312 -182.697882)
		(width 0.254)
		(layer "F.Cu")
		(net "PVNN_MAIN_CPU0_MODE")
	)
	(segment
		(start 433.942998 -182.052468)
		(end 434.028342 -182.052468)
		(width 0.254)
		(layer "F.Cu")
		(net "PVNN_MAIN_CPU0_MODE")
	)
	(segment
		(start 434.028342 -182.052468)
		(end 434.296312 -182.320438)
		(width 0.254)
		(layer "F.Cu")
		(net "PVNN_MAIN_CPU0_MODE")
	)
	(via
		(at 434.296312 -182.697882)
		(size 0.508)
		(drill 0.254)
		(layers "F.Cu" "B.Cu")
		(net "PVNN_MAIN_CPU0_MODE")
	)
	(segment
		(start 432.666902 -179.526184)
		(end 432.666902 -179.431188)
		(width 0.254)
		(layer "F.Cu")
		(net "PVNN_MAIN_CPU0_FB")
	)
	(segment
		(start 432.13528 -177.269902)
		(end 432.01463 -177.149252)
		(width 0.254)
		(layer "F.Cu")
		(net "PVNN_MAIN_CPU0_FB")
	)
	(segment
		(start 432.01463 -175.69942)
		(end 432.01463 -176.61382)
		(width 0.254)
		(layer "F.Cu")
		(net "PVNN_MAIN_CPU0_FB")
	)
	(segment
		(start 432.01463 -177.149252)
		(end 432.01463 -176.61382)
		(width 0.254)
		(layer "F.Cu")
		(net "PVNN_MAIN_CPU0_FB")
	)
	(segment
		(start 432.666902 -179.431188)
		(end 432.477926 -179.242212)
		(width 0.254)
		(layer "F.Cu")
		(net "PVNN_MAIN_CPU0_FB")
	)
	(segment
		(start 432.01463 -175.69942)
		(end 432.01463 -174.78502)
		(width 0.254)
		(layer "F.Cu")
		(net "PVNN_MAIN_CPU0_FB")
	)
	(segment
		(start 432.477926 -179.242212)
		(end 432.13528 -179.242212)
		(width 0.254)
		(layer "F.Cu")
		(net "PVNN_MAIN_CPU0_FB")
	)
	(segment
		(start 432.13528 -179.242212)
		(end 432.13528 -177.269902)
		(width 0.254)
		(layer "F.Cu")
		(net "PVNN_MAIN_CPU0_FB")
	)
	(via
		(at 432.13528 -179.242212)
		(size 0.508)
		(drill 0.254)
		(layers "F.Cu" "B.Cu")
		(net "PVNN_MAIN_CPU0_FB")
	)
	(segment
		(start 430.886108 -180.221382)
		(end 430.643284 -179.978558)
		(width 0.12954)
		(layer "F.Cu")
		(net "PVNN_MAIN_CPU0_CS")
	)
	(segment
		(start 430.643284 -179.978558)
		(end 430.643284 -179.601622)
		(width 0.12954)
		(layer "F.Cu")
		(net "PVNN_MAIN_CPU0_CS")
	)
	(segment
		(start 432.066954 -180.476398)
		(end 431.141124 -180.476398)
		(width 0.12954)
		(layer "F.Cu")
		(net "PVNN_MAIN_CPU0_CS")
	)
	(segment
		(start 431.141124 -180.476398)
		(end 430.886108 -180.221382)
		(width 0.12954)
		(layer "F.Cu")
		(net "PVNN_MAIN_CPU0_CS")
	)
	(via
		(at 430.886108 -180.221382)
		(size 0.508)
		(drill 0.254)
		(layers "F.Cu" "B.Cu")
		(net "PVNN_MAIN_CPU0_CS")
	)
	(segment
		(start 351.592134 -228.99497)
		(end 351.592134 -228.459284)
		(width 0.381)
		(layer "F.Cu")
		(net "PVNN_MAIN_CPU0")
	)
	(segment
		(start 353.471734 -228.459284)
		(end 353.47148 -228.45903)
		(width 0.381)
		(layer "F.Cu")
		(net "PVNN_MAIN_CPU0")
	)
	(segment
		(start 435.97068 -175.6029)
		(end 435.98592 -175.61814)
		(width 0.254)
		(layer "F.Cu")
		(net "PVNN_MAIN_CPU0")
	)
	(segment
		(start 446.2145 -174.63008)
		(end 438.714388 -174.63008)
		(width 0.254)
		(layer "F.Cu")
		(net "PVNN_MAIN_CPU0")
	)
	(segment
		(start 355.351334 -228.459284)
		(end 355.35108 -228.45903)
		(width 0.381)
		(layer "F.Cu")
		(net "PVNN_MAIN_CPU0")
	)
	(segment
		(start 357.230934 -228.459284)
		(end 357.23068 -228.45903)
		(width 0.381)
		(layer "F.Cu")
		(net "PVNN_MAIN_CPU0")
	)
	(segment
		(start 446.41262 -175.2092)
		(end 446.41262 -174.8282)
		(width 0.254)
		(layer "F.Cu")
		(net "PVNN_MAIN_CPU0")
	)
	(segment
		(start 355.351334 -228.99497)
		(end 355.351334 -228.459284)
		(width 0.381)
		(layer "F.Cu")
		(net "PVNN_MAIN_CPU0")
	)
	(segment
		(start 438.714388 -174.63008)
		(end 438.538874 -174.805594)
		(width 0.254)
		(layer "F.Cu")
		(net "PVNN_MAIN_CPU0")
	)
	(segment
		(start 446.41262 -174.8282)
		(end 446.2145 -174.63008)
		(width 0.254)
		(layer "F.Cu")
		(net "PVNN_MAIN_CPU0")
	)
	(segment
		(start 438.538874 -174.805594)
		(end 438.33542 -174.805594)
		(width 0.254)
		(layer "F.Cu")
		(net "PVNN_MAIN_CPU0")
	)
	(segment
		(start 435.142386 -175.6029)
		(end 435.97068 -175.6029)
		(width 0.254)
		(layer "F.Cu")
		(net "PVNN_MAIN_CPU0")
	)
	(segment
		(start 353.471734 -228.99497)
		(end 353.471734 -228.459284)
		(width 0.381)
		(layer "F.Cu")
		(net "PVNN_MAIN_CPU0")
	)
	(segment
		(start 357.230934 -228.99497)
		(end 357.230934 -228.459284)
		(width 0.381)
		(layer "F.Cu")
		(net "PVNN_MAIN_CPU0")
	)
	(via
		(at 398.156938 -191.89319)
		(size 0.508)
		(drill 0.254)
		(layers "F.Cu" "B.Cu")
		(net "PVNN_MAIN_CPU0")
	)
	(via
		(at 445.063118 -176.018952)
		(size 0.508)
		(drill 0.254)
		(layers "F.Cu" "B.Cu")
		(net "PVNN_MAIN_CPU0")
	)
	(via
		(at 355.426518 -236.083856)
		(size 0.4572)
		(drill 0.2032)
		(layers "F.Cu" "B.Cu")
		(net "PVNN_MAIN_CPU0")
	)
	(via
		(at 445.798448 -176.694592)
		(size 0.508)
		(drill 0.254)
		(layers "F.Cu" "B.Cu")
		(net "PVNN_MAIN_CPU0")
	)
	(via
		(at 435.98592 -175.61814)
		(size 0.508)
		(drill 0.254)
		(layers "F.Cu" "B.Cu")
		(net "PVNN_MAIN_CPU0")
	)
	(via
		(at 446.423288 -183.009032)
		(size 0.508)
		(drill 0.254)
		(layers "F.Cu" "B.Cu")
		(net "PVNN_MAIN_CPU0")
	)
	(via
		(at 445.088264 -180.916326)
		(size 0.508)
		(drill 0.254)
		(layers "F.Cu" "B.Cu")
		(net "PVNN_MAIN_CPU0")
	)
	(via
		(at 445.798448 -178.802792)
		(size 0.508)
		(drill 0.254)
		(layers "F.Cu" "B.Cu")
		(net "PVNN_MAIN_CPU0")
	)
	(via
		(at 446.433448 -176.694592)
		(size 0.508)
		(drill 0.254)
		(layers "F.Cu" "B.Cu")
		(net "PVNN_MAIN_CPU0")
	)
	(via
		(at 355.988112 -235.49737)
		(size 0.4572)
		(drill 0.2032)
		(layers "F.Cu" "B.Cu")
		(net "PVNN_MAIN_CPU0")
	)
	(via
		(at 445.078104 -183.014366)
		(size 0.508)
		(drill 0.254)
		(layers "F.Cu" "B.Cu")
		(net "PVNN_MAIN_CPU0")
	)
	(via
		(at 353.47148 -228.45903)
		(size 0.4572)
		(drill 0.2032)
		(layers "F.Cu" "B.Cu")
		(net "PVNN_MAIN_CPU0")
	)
	(via
		(at 442.83376 -183.337708)
		(size 0.6604)
		(drill 0.3302)
		(layers "F.Cu" "B.Cu")
		(net "PVNN_MAIN_CPU0")
	)
	(via
		(at 399.26768 -193.716148)
		(size 0.508)
		(drill 0.254)
		(layers "F.Cu" "B.Cu")
		(net "PVNN_MAIN_CPU0")
	)
	(via
		(at 357.23068 -228.45903)
		(size 0.4572)
		(drill 0.2032)
		(layers "F.Cu" "B.Cu")
		(net "PVNN_MAIN_CPU0")
	)
	(via
		(at 446.433448 -178.802792)
		(size 0.508)
		(drill 0.254)
		(layers "F.Cu" "B.Cu")
		(net "PVNN_MAIN_CPU0")
	)
	(via
		(at 445.798448 -180.910992)
		(size 0.508)
		(drill 0.254)
		(layers "F.Cu" "B.Cu")
		(net "PVNN_MAIN_CPU0")
	)
	(via
		(at 355.35108 -228.45903)
		(size 0.4572)
		(drill 0.2032)
		(layers "F.Cu" "B.Cu")
		(net "PVNN_MAIN_CPU0")
	)
	(via
		(at 356.061518 -236.083856)
		(size 0.4572)
		(drill 0.2032)
		(layers "F.Cu" "B.Cu")
		(net "PVNN_MAIN_CPU0")
	)
	(via
		(at 445.088264 -176.699926)
		(size 0.508)
		(drill 0.254)
		(layers "F.Cu" "B.Cu")
		(net "PVNN_MAIN_CPU0")
	)
	(via
		(at 446.433448 -180.910992)
		(size 0.508)
		(drill 0.254)
		(layers "F.Cu" "B.Cu")
		(net "PVNN_MAIN_CPU0")
	)
	(via
		(at 445.788288 -183.009032)
		(size 0.508)
		(drill 0.254)
		(layers "F.Cu" "B.Cu")
		(net "PVNN_MAIN_CPU0")
	)
	(via
		(at 398.874996 -193.063622)
		(size 0.508)
		(drill 0.254)
		(layers "F.Cu" "B.Cu")
		(net "PVNN_MAIN_CPU0")
	)
	(via
		(at 445.773302 -176.013618)
		(size 0.508)
		(drill 0.254)
		(layers "F.Cu" "B.Cu")
		(net "PVNN_MAIN_CPU0")
	)
	(via
		(at 398.39646 -192.573148)
		(size 0.508)
		(drill 0.254)
		(layers "F.Cu" "B.Cu")
		(net "PVNN_MAIN_CPU0")
	)
	(via
		(at 355.353112 -235.49737)
		(size 0.4572)
		(drill 0.2032)
		(layers "F.Cu" "B.Cu")
		(net "PVNN_MAIN_CPU0")
	)
	(via
		(at 351.592134 -228.459284)
		(size 0.4572)
		(drill 0.2032)
		(layers "F.Cu" "B.Cu")
		(net "PVNN_MAIN_CPU0")
	)
	(via
		(at 445.088264 -178.808126)
		(size 0.508)
		(drill 0.254)
		(layers "F.Cu" "B.Cu")
		(net "PVNN_MAIN_CPU0")
	)
	(segment
		(start 427.352714 -178.053238)
		(end 427.352714 -180.376576)
		(width 0.254)
		(layer "In11.Cu")
		(net "PVNN_MAIN_CPU0")
	)
	(segment
		(start 349.531178 -224.875344)
		(end 349.525082 -224.8789)
		(width 0.0889)
		(layer "In11.Cu")
		(net "PVNN_MAIN_CPU0")
	)
	(segment
		(start 364.481364 -222.445834)
		(end 364.466632 -222.437198)
		(width 0.0889)
		(layer "In11.Cu")
		(net "PVNN_MAIN_CPU0")
	)
	(segment
		(start 384.297936 -219.995496)
		(end 384.289046 -220.000576)
		(width 0.0889)
		(layer "In11.Cu")
		(net "PVNN_MAIN_CPU0")
	)
	(segment
		(start 350.001332 -224.061528)
		(end 349.995236 -224.065084)
		(width 0.0889)
		(layer "In11.Cu")
		(net "PVNN_MAIN_CPU0")
	)
	(segment
		(start 352.263964 -222.445834)
		(end 352.249232 -222.437198)
		(width 0.0889)
		(layer "In11.Cu")
		(net "PVNN_MAIN_CPU0")
	)
	(segment
		(start 349.995236 -224.065084)
		(end 349.986346 -224.070164)
		(width 0.0889)
		(layer "In11.Cu")
		(net "PVNN_MAIN_CPU0")
	)
	(segment
		(start 386.776976 -216.167716)
		(end 386.294376 -216.650316)
		(width 0.0889)
		(layer "In11.Cu")
		(net "PVNN_MAIN_CPU0")
	)
	(segment
		(start 402.783548 -185.123836)
		(end 389.670544 -198.23684)
		(width 0.254)
		(layer "In11.Cu")
		(net "PVNN_MAIN_CPU0")
	)
	(segment
		(start 385.520184 -217.878406)
		(end 385.520184 -217.888312)
		(width 0.0889)
		(layer "In11.Cu")
		(net "PVNN_MAIN_CPU0")
	)
	(segment
		(start 363.541564 -222.445834)
		(end 363.526832 -222.437198)
		(width 0.0889)
		(layer "In11.Cu")
		(net "PVNN_MAIN_CPU0")
	)
	(segment
		(start 359.782364 -222.445834)
		(end 359.767632 -222.437198)
		(width 0.0889)
		(layer "In11.Cu")
		(net "PVNN_MAIN_CPU0")
	)
	(segment
		(start 431.783998 -174.94123)
		(end 430.566322 -176.158906)
		(width 0.254)
		(layer "In11.Cu")
		(net "PVNN_MAIN_CPU0")
	)
	(segment
		(start 385.990084 -217.064336)
		(end 385.990084 -217.082878)
		(width 0.0889)
		(layer "In11.Cu")
		(net "PVNN_MAIN_CPU0")
	)
	(segment
		(start 383.640584 -221.133924)
		(end 383.640584 -221.14383)
		(width 0.0889)
		(layer "In11.Cu")
		(net "PVNN_MAIN_CPU0")
	)
	(segment
		(start 383.358136 -221.623382)
		(end 383.349246 -221.628462)
		(width 0.0889)
		(layer "In11.Cu")
		(net "PVNN_MAIN_CPU0")
	)
	(segment
		(start 435.295802 -175.61814)
		(end 434.618892 -174.94123)
		(width 0.254)
		(layer "In11.Cu")
		(net "PVNN_MAIN_CPU0")
	)
	(segment
		(start 350.935036 -222.437198)
		(end 350.926146 -222.442278)
		(width 0.0889)
		(layer "In11.Cu")
		(net "PVNN_MAIN_CPU0")
	)
	(segment
		(start 371.059964 -222.445834)
		(end 371.045232 -222.437198)
		(width 0.0889)
		(layer "In11.Cu")
		(net "PVNN_MAIN_CPU0")
	)
	(segment
		(start 377.638564 -222.445834)
		(end 377.623832 -222.437198)
		(width 0.0889)
		(layer "In11.Cu")
		(net "PVNN_MAIN_CPU0")
	)
	(segment
		(start 351.394522 -228.777292)
		(end 351.404936 -228.783388)
		(width 0.0889)
		(layer "In11.Cu")
		(net "PVNN_MAIN_CPU0")
	)
	(segment
		(start 366.360964 -222.445834)
		(end 366.346232 -222.437198)
		(width 0.0889)
		(layer "In11.Cu")
		(net "PVNN_MAIN_CPU0")
	)
	(segment
		(start 354.143564 -222.445834)
		(end 354.128832 -222.437198)
		(width 0.0889)
		(layer "In11.Cu")
		(net "PVNN_MAIN_CPU0")
	)
	(segment
		(start 430.566322 -176.158906)
		(end 429.247046 -176.158906)
		(width 0.254)
		(layer "In11.Cu")
		(net "PVNN_MAIN_CPU0")
	)
	(segment
		(start 360.722164 -222.445834)
		(end 360.707432 -222.437198)
		(width 0.0889)
		(layer "In11.Cu")
		(net "PVNN_MAIN_CPU0")
	)
	(segment
		(start 368.240564 -222.445834)
		(end 368.225832 -222.437198)
		(width 0.0889)
		(layer "In11.Cu")
		(net "PVNN_MAIN_CPU0")
	)
	(segment
		(start 349.337884 -226.821238)
		(end 349.337884 -226.83978)
		(width 0.0889)
		(layer "In11.Cu")
		(net "PVNN_MAIN_CPU0")
	)
	(segment
		(start 384.110484 -220.319854)
		(end 384.110484 -220.338396)
		(width 0.0889)
		(layer "In11.Cu")
		(net "PVNN_MAIN_CPU0")
	)
	(segment
		(start 349.055436 -225.69297)
		(end 349.046546 -225.69805)
		(width 0.0889)
		(layer "In11.Cu")
		(net "PVNN_MAIN_CPU0")
	)
	(segment
		(start 387.297422 -215.913716)
		(end 387.043422 -216.167716)
		(width 0.254)
		(layer "In11.Cu")
		(net "PVNN_MAIN_CPU0")
	)
	(segment
		(start 350.455992 -228.778308)
		(end 350.464882 -228.783388)
		(width 0.0889)
		(layer "In11.Cu")
		(net "PVNN_MAIN_CPU0")
	)
	(segment
		(start 427.352714 -180.376576)
		(end 422.605454 -185.123836)
		(width 0.254)
		(layer "In11.Cu")
		(net "PVNN_MAIN_CPU0")
	)
	(segment
		(start 385.707636 -217.554048)
		(end 385.698746 -217.559128)
		(width 0.0889)
		(layer "In11.Cu")
		(net "PVNN_MAIN_CPU0")
	)
	(segment
		(start 389.670544 -212.739224)
		(end 387.297422 -215.112346)
		(width 0.254)
		(layer "In11.Cu")
		(net "PVNN_MAIN_CPU0")
	)
	(segment
		(start 389.670544 -198.23684)
		(end 389.670544 -212.739224)
		(width 0.254)
		(layer "In11.Cu")
		(net "PVNN_MAIN_CPU0")
	)
	(segment
		(start 434.618892 -174.94123)
		(end 431.783998 -174.94123)
		(width 0.254)
		(layer "In11.Cu")
		(net "PVNN_MAIN_CPU0")
	)
	(segment
		(start 384.580384 -219.497402)
		(end 384.580384 -219.515944)
		(width 0.0889)
		(layer "In11.Cu")
		(net "PVNN_MAIN_CPU0")
	)
	(segment
		(start 371.999764 -222.445834)
		(end 371.985032 -222.437198)
		(width 0.0889)
		(layer "In11.Cu")
		(net "PVNN_MAIN_CPU0")
	)
	(segment
		(start 429.247046 -176.158906)
		(end 427.352714 -178.053238)
		(width 0.254)
		(layer "In11.Cu")
		(net "PVNN_MAIN_CPU0")
	)
	(segment
		(start 350.747584 -222.761556)
		(end 350.747584 -222.780098)
		(width 0.0889)
		(layer "In11.Cu")
		(net "PVNN_MAIN_CPU0")
	)
	(segment
		(start 349.525082 -224.8789)
		(end 349.516192 -224.88398)
		(width 0.0889)
		(layer "In11.Cu")
		(net "PVNN_MAIN_CPU0")
	)
	(segment
		(start 349.525082 -227.155502)
		(end 349.531178 -227.159058)
		(width 0.0889)
		(layer "In11.Cu")
		(net "PVNN_MAIN_CPU0")
	)
	(segment
		(start 387.297422 -215.112346)
		(end 387.297422 -215.913716)
		(width 0.254)
		(layer "In11.Cu")
		(net "PVNN_MAIN_CPU0")
	)
	(segment
		(start 356.962964 -222.445834)
		(end 356.948232 -222.437198)
		(width 0.0889)
		(layer "In11.Cu")
		(net "PVNN_MAIN_CPU0")
	)
	(segment
		(start 386.169916 -216.74455)
		(end 386.168646 -216.745058)
		(width 0.0889)
		(layer "In11.Cu")
		(net "PVNN_MAIN_CPU0")
	)
	(segment
		(start 378.578364 -222.445834)
		(end 378.563632 -222.437198)
		(width 0.0889)
		(layer "In11.Cu")
		(net "PVNN_MAIN_CPU0")
	)
	(segment
		(start 387.043422 -216.167716)
		(end 386.776976 -216.167716)
		(width 0.0889)
		(layer "In11.Cu")
		(net "PVNN_MAIN_CPU0")
	)
	(segment
		(start 384.773678 -219.178124)
		(end 384.767582 -219.18168)
		(width 0.0889)
		(layer "In11.Cu")
		(net "PVNN_MAIN_CPU0")
	)
	(segment
		(start 351.324164 -222.445834)
		(end 351.309432 -222.437198)
		(width 0.0889)
		(layer "In11.Cu")
		(net "PVNN_MAIN_CPU0")
	)
	(segment
		(start 375.758964 -222.445834)
		(end 375.744232 -222.437198)
		(width 0.0889)
		(layer "In11.Cu")
		(net "PVNN_MAIN_CPU0")
	)
	(segment
		(start 385.237736 -218.367864)
		(end 385.228846 -218.372944)
		(width 0.0889)
		(layer "In11.Cu")
		(net "PVNN_MAIN_CPU0")
	)
	(segment
		(start 380.457964 -222.445834)
		(end 380.443232 -222.437198)
		(width 0.0889)
		(layer "In11.Cu")
		(net "PVNN_MAIN_CPU0")
	)
	(segment
		(start 365.421164 -222.445834)
		(end 365.406432 -222.437198)
		(width 0.0889)
		(layer "In11.Cu")
		(net "PVNN_MAIN_CPU0")
	)
	(segment
		(start 383.828036 -220.809566)
		(end 383.819146 -220.814646)
		(width 0.0889)
		(layer "In11.Cu")
		(net "PVNN_MAIN_CPU0")
	)
	(segment
		(start 351.748344 -228.730048)
		(end 351.592134 -228.459284)
		(width 0.0889)
		(layer "In11.Cu")
		(net "PVNN_MAIN_CPU0")
	)
	(segment
		(start 435.98592 -175.61814)
		(end 435.295802 -175.61814)
		(width 0.254)
		(layer "In11.Cu")
		(net "PVNN_MAIN_CPU0")
	)
	(segment
		(start 355.083364 -222.445834)
		(end 355.068632 -222.437198)
		(width 0.0889)
		(layer "In11.Cu")
		(net "PVNN_MAIN_CPU0")
	)
	(segment
		(start 350.465136 -223.251268)
		(end 350.456246 -223.256348)
		(width 0.0889)
		(layer "In11.Cu")
		(net "PVNN_MAIN_CPU0")
	)
	(segment
		(start 372.939564 -222.445834)
		(end 372.924832 -222.437198)
		(width 0.0889)
		(layer "In11.Cu")
		(net "PVNN_MAIN_CPU0")
	)
	(segment
		(start 353.203764 -222.445834)
		(end 353.189032 -222.437198)
		(width 0.0889)
		(layer "In11.Cu")
		(net "PVNN_MAIN_CPU0")
	)
	(segment
		(start 370.120164 -222.445834)
		(end 370.105432 -222.437198)
		(width 0.0889)
		(layer "In11.Cu")
		(net "PVNN_MAIN_CPU0")
	)
	(segment
		(start 351.727262 -228.80828)
		(end 351.748344 -228.730048)
		(width 0.0889)
		(layer "In11.Cu")
		(net "PVNN_MAIN_CPU0")
	)
	(segment
		(start 373.879364 -222.445834)
		(end 373.864632 -222.437198)
		(width 0.0889)
		(layer "In11.Cu")
		(net "PVNN_MAIN_CPU0")
	)
	(segment
		(start 349.986346 -227.964238)
		(end 349.995236 -227.969318)
		(width 0.0889)
		(layer "In11.Cu")
		(net "PVNN_MAIN_CPU0")
	)
	(segment
		(start 349.046546 -226.336606)
		(end 349.055436 -226.341686)
		(width 0.0889)
		(layer "In11.Cu")
		(net "PVNN_MAIN_CPU0")
	)
	(segment
		(start 369.180364 -222.445834)
		(end 369.165632 -222.437198)
		(width 0.0889)
		(layer "In11.Cu")
		(net "PVNN_MAIN_CPU0")
	)
	(segment
		(start 376.698764 -222.445834)
		(end 376.684032 -222.437198)
		(width 0.0889)
		(layer "In11.Cu")
		(net "PVNN_MAIN_CPU0")
	)
	(segment
		(start 379.518164 -222.445834)
		(end 379.503432 -222.437198)
		(width 0.0889)
		(layer "In11.Cu")
		(net "PVNN_MAIN_CPU0")
	)
	(segment
		(start 350.27743 -228.436932)
		(end 350.27743 -228.45903)
		(width 0.0889)
		(layer "In11.Cu")
		(net "PVNN_MAIN_CPU0")
	)
	(segment
		(start 422.605454 -185.123836)
		(end 402.783548 -185.123836)
		(width 0.254)
		(layer "In11.Cu")
		(net "PVNN_MAIN_CPU0")
	)
	(segment
		(start 383.170684 -221.94774)
		(end 383.170684 -221.957646)
		(width 0.0889)
		(layer "In11.Cu")
		(net "PVNN_MAIN_CPU0")
	)
	(segment
		(start 349.33763 -225.203258)
		(end 349.33763 -225.225356)
		(width 0.0889)
		(layer "In11.Cu")
		(net "PVNN_MAIN_CPU0")
	)
	(segment
		(start 356.023164 -222.445834)
		(end 356.008432 -222.437198)
		(width 0.0889)
		(layer "In11.Cu")
		(net "PVNN_MAIN_CPU0")
	)
	(segment
		(start 374.819164 -222.445834)
		(end 374.804432 -222.437198)
		(width 0.0889)
		(layer "In11.Cu")
		(net "PVNN_MAIN_CPU0")
	)
	(arc
		(start 359.393236 -222.437198)
		(mid 359.110534 -222.512974)
		(end 358.827832 -222.437198)
		(width 0.0889)
		(layer "In11.Cu")
		(net "PVNN_MAIN_CPU0")
	)
	(arc
		(start 378.563632 -222.437198)
		(mid 378.376434 -222.387055)
		(end 378.189236 -222.437198)
		(width 0.0889)
		(layer "In11.Cu")
		(net "PVNN_MAIN_CPU0")
	)
	(arc
		(start 355.068632 -222.437198)
		(mid 354.881434 -222.387055)
		(end 354.694236 -222.437198)
		(width 0.0889)
		(layer "In11.Cu")
		(net "PVNN_MAIN_CPU0")
	)
	(arc
		(start 383.640584 -221.14383)
		(mid 383.562473 -221.420779)
		(end 383.358136 -221.623382)
		(width 0.0889)
		(layer "In11.Cu")
		(net "PVNN_MAIN_CPU0")
	)
	(arc
		(start 352.249232 -222.437198)
		(mid 352.062034 -222.387055)
		(end 351.874836 -222.437198)
		(width 0.0889)
		(layer "In11.Cu")
		(net "PVNN_MAIN_CPU0")
	)
	(arc
		(start 376.309636 -222.437198)
		(mid 376.035437 -222.513033)
		(end 375.758964 -222.445834)
		(width 0.0889)
		(layer "In11.Cu")
		(net "PVNN_MAIN_CPU0")
	)
	(arc
		(start 362.212636 -222.437198)
		(mid 361.929934 -222.512974)
		(end 361.647232 -222.437198)
		(width 0.0889)
		(layer "In11.Cu")
		(net "PVNN_MAIN_CPU0")
	)
	(arc
		(start 380.068836 -222.437198)
		(mid 379.794637 -222.513033)
		(end 379.518164 -222.445834)
		(width 0.0889)
		(layer "In11.Cu")
		(net "PVNN_MAIN_CPU0")
	)
	(arc
		(start 350.464882 -228.783388)
		(mid 350.65208 -228.833531)
		(end 350.839278 -228.783388)
		(width 0.0889)
		(layer "In11.Cu")
		(net "PVNN_MAIN_CPU0")
	)
	(arc
		(start 358.453436 -222.437198)
		(mid 358.170734 -222.512974)
		(end 357.888032 -222.437198)
		(width 0.0889)
		(layer "In11.Cu")
		(net "PVNN_MAIN_CPU0")
	)
	(arc
		(start 385.520184 -217.888312)
		(mid 385.442073 -218.165261)
		(end 385.237736 -218.367864)
		(width 0.0889)
		(layer "In11.Cu")
		(net "PVNN_MAIN_CPU0")
	)
	(arc
		(start 377.249436 -222.437198)
		(mid 376.975237 -222.513033)
		(end 376.698764 -222.445834)
		(width 0.0889)
		(layer "In11.Cu")
		(net "PVNN_MAIN_CPU0")
	)
	(arc
		(start 365.032036 -222.437198)
		(mid 364.757837 -222.513033)
		(end 364.481364 -222.445834)
		(width 0.0889)
		(layer "In11.Cu")
		(net "PVNN_MAIN_CPU0")
	)
	(arc
		(start 386.294376 -216.650316)
		(mid 386.238771 -216.69899)
		(end 386.177282 -216.739978)
		(width 0.0889)
		(layer "In11.Cu")
		(net "PVNN_MAIN_CPU0")
	)
	(arc
		(start 350.456246 -223.256348)
		(mid 350.325332 -223.392708)
		(end 350.277684 -223.575626)
		(width 0.0889)
		(layer "In11.Cu")
		(net "PVNN_MAIN_CPU0")
	)
	(arc
		(start 372.924832 -222.437198)
		(mid 372.737634 -222.387055)
		(end 372.550436 -222.437198)
		(width 0.0889)
		(layer "In11.Cu")
		(net "PVNN_MAIN_CPU0")
	)
	(arc
		(start 385.698746 -217.559128)
		(mid 385.567832 -217.695488)
		(end 385.520184 -217.878406)
		(width 0.0889)
		(layer "In11.Cu")
		(net "PVNN_MAIN_CPU0")
	)
	(arc
		(start 368.225832 -222.437198)
		(mid 368.038634 -222.387055)
		(end 367.851436 -222.437198)
		(width 0.0889)
		(layer "In11.Cu")
		(net "PVNN_MAIN_CPU0")
	)
	(arc
		(start 364.466632 -222.437198)
		(mid 364.279434 -222.387055)
		(end 364.092236 -222.437198)
		(width 0.0889)
		(layer "In11.Cu")
		(net "PVNN_MAIN_CPU0")
	)
	(arc
		(start 352.814636 -222.437198)
		(mid 352.540437 -222.513033)
		(end 352.263964 -222.445834)
		(width 0.0889)
		(layer "In11.Cu")
		(net "PVNN_MAIN_CPU0")
	)
	(arc
		(start 381.948436 -222.437198)
		(mid 381.665734 -222.512974)
		(end 381.383032 -222.437198)
		(width 0.0889)
		(layer "In11.Cu")
		(net "PVNN_MAIN_CPU0")
	)
	(arc
		(start 350.277684 -223.575626)
		(mid 350.203768 -223.855128)
		(end 350.001332 -224.061528)
		(width 0.0889)
		(layer "In11.Cu")
		(net "PVNN_MAIN_CPU0")
	)
	(arc
		(start 370.105432 -222.437198)
		(mid 369.918234 -222.387055)
		(end 369.731036 -222.437198)
		(width 0.0889)
		(layer "In11.Cu")
		(net "PVNN_MAIN_CPU0")
	)
	(arc
		(start 365.971836 -222.437198)
		(mid 365.697637 -222.513033)
		(end 365.421164 -222.445834)
		(width 0.0889)
		(layer "In11.Cu")
		(net "PVNN_MAIN_CPU0")
	)
	(arc
		(start 357.513636 -222.437198)
		(mid 357.239437 -222.513033)
		(end 356.962964 -222.445834)
		(width 0.0889)
		(layer "In11.Cu")
		(net "PVNN_MAIN_CPU0")
	)
	(arc
		(start 366.911636 -222.437198)
		(mid 366.637437 -222.513033)
		(end 366.360964 -222.445834)
		(width 0.0889)
		(layer "In11.Cu")
		(net "PVNN_MAIN_CPU0")
	)
	(arc
		(start 356.573836 -222.437198)
		(mid 356.299637 -222.513033)
		(end 356.023164 -222.445834)
		(width 0.0889)
		(layer "In11.Cu")
		(net "PVNN_MAIN_CPU0")
	)
	(arc
		(start 374.430036 -222.437198)
		(mid 374.155837 -222.513033)
		(end 373.879364 -222.445834)
		(width 0.0889)
		(layer "In11.Cu")
		(net "PVNN_MAIN_CPU0")
	)
	(arc
		(start 385.990084 -217.082878)
		(mid 385.909922 -217.355067)
		(end 385.707636 -217.554048)
		(width 0.0889)
		(layer "In11.Cu")
		(net "PVNN_MAIN_CPU0")
	)
	(arc
		(start 386.177282 -216.739978)
		(mid 386.173585 -216.742242)
		(end 386.169916 -216.74455)
		(width 0.0889)
		(layer "In11.Cu")
		(net "PVNN_MAIN_CPU0")
	)
	(arc
		(start 349.055436 -226.341686)
		(mid 349.259771 -226.544291)
		(end 349.337884 -226.821238)
		(width 0.0889)
		(layer "In11.Cu")
		(net "PVNN_MAIN_CPU0")
	)
	(arc
		(start 376.684032 -222.437198)
		(mid 376.496834 -222.387055)
		(end 376.309636 -222.437198)
		(width 0.0889)
		(layer "In11.Cu")
		(net "PVNN_MAIN_CPU0")
	)
	(arc
		(start 374.804432 -222.437198)
		(mid 374.617234 -222.387055)
		(end 374.430036 -222.437198)
		(width 0.0889)
		(layer "In11.Cu")
		(net "PVNN_MAIN_CPU0")
	)
	(arc
		(start 368.791236 -222.437198)
		(mid 368.517037 -222.513033)
		(end 368.240564 -222.445834)
		(width 0.0889)
		(layer "In11.Cu")
		(net "PVNN_MAIN_CPU0")
	)
	(arc
		(start 356.008432 -222.437198)
		(mid 355.821234 -222.387055)
		(end 355.634036 -222.437198)
		(width 0.0889)
		(layer "In11.Cu")
		(net "PVNN_MAIN_CPU0")
	)
	(arc
		(start 354.694236 -222.437198)
		(mid 354.420037 -222.513033)
		(end 354.143564 -222.445834)
		(width 0.0889)
		(layer "In11.Cu")
		(net "PVNN_MAIN_CPU0")
	)
	(arc
		(start 351.404936 -228.783388)
		(mid 351.563276 -228.832451)
		(end 351.727262 -228.80828)
		(width 0.0889)
		(layer "In11.Cu")
		(net "PVNN_MAIN_CPU0")
	)
	(arc
		(start 361.647232 -222.437198)
		(mid 361.460034 -222.387055)
		(end 361.272836 -222.437198)
		(width 0.0889)
		(layer "In11.Cu")
		(net "PVNN_MAIN_CPU0")
	)
	(arc
		(start 385.228846 -218.372944)
		(mid 385.097932 -218.509304)
		(end 385.050284 -218.692222)
		(width 0.0889)
		(layer "In11.Cu")
		(net "PVNN_MAIN_CPU0")
	)
	(arc
		(start 373.864632 -222.437198)
		(mid 373.677434 -222.387055)
		(end 373.490236 -222.437198)
		(width 0.0889)
		(layer "In11.Cu")
		(net "PVNN_MAIN_CPU0")
	)
	(arc
		(start 350.926146 -222.442278)
		(mid 350.795232 -222.578638)
		(end 350.747584 -222.761556)
		(width 0.0889)
		(layer "In11.Cu")
		(net "PVNN_MAIN_CPU0")
	)
	(arc
		(start 384.580384 -219.515944)
		(mid 384.502273 -219.792893)
		(end 384.297936 -219.995496)
		(width 0.0889)
		(layer "In11.Cu")
		(net "PVNN_MAIN_CPU0")
	)
	(arc
		(start 364.092236 -222.437198)
		(mid 363.818037 -222.513033)
		(end 363.541564 -222.445834)
		(width 0.0889)
		(layer "In11.Cu")
		(net "PVNN_MAIN_CPU0")
	)
	(arc
		(start 358.827832 -222.437198)
		(mid 358.640634 -222.387055)
		(end 358.453436 -222.437198)
		(width 0.0889)
		(layer "In11.Cu")
		(net "PVNN_MAIN_CPU0")
	)
	(arc
		(start 357.888032 -222.437198)
		(mid 357.700834 -222.387055)
		(end 357.513636 -222.437198)
		(width 0.0889)
		(layer "In11.Cu")
		(net "PVNN_MAIN_CPU0")
	)
	(arc
		(start 383.349246 -221.628462)
		(mid 383.218332 -221.764822)
		(end 383.170684 -221.94774)
		(width 0.0889)
		(layer "In11.Cu")
		(net "PVNN_MAIN_CPU0")
	)
	(arc
		(start 382.888236 -222.437198)
		(mid 382.605534 -222.512974)
		(end 382.322832 -222.437198)
		(width 0.0889)
		(layer "In11.Cu")
		(net "PVNN_MAIN_CPU0")
	)
	(arc
		(start 353.754436 -222.437198)
		(mid 353.480237 -222.513033)
		(end 353.203764 -222.445834)
		(width 0.0889)
		(layer "In11.Cu")
		(net "PVNN_MAIN_CPU0")
	)
	(arc
		(start 371.045232 -222.437198)
		(mid 370.858034 -222.387055)
		(end 370.670836 -222.437198)
		(width 0.0889)
		(layer "In11.Cu")
		(net "PVNN_MAIN_CPU0")
	)
	(arc
		(start 381.383032 -222.437198)
		(mid 381.195834 -222.387055)
		(end 381.008636 -222.437198)
		(width 0.0889)
		(layer "In11.Cu")
		(net "PVNN_MAIN_CPU0")
	)
	(arc
		(start 383.170684 -221.957646)
		(mid 383.092573 -222.234595)
		(end 382.888236 -222.437198)
		(width 0.0889)
		(layer "In11.Cu")
		(net "PVNN_MAIN_CPU0")
	)
	(arc
		(start 371.985032 -222.437198)
		(mid 371.797834 -222.387055)
		(end 371.610636 -222.437198)
		(width 0.0889)
		(layer "In11.Cu")
		(net "PVNN_MAIN_CPU0")
	)
	(arc
		(start 354.128832 -222.437198)
		(mid 353.941634 -222.387055)
		(end 353.754436 -222.437198)
		(width 0.0889)
		(layer "In11.Cu")
		(net "PVNN_MAIN_CPU0")
	)
	(arc
		(start 367.851436 -222.437198)
		(mid 367.568734 -222.512974)
		(end 367.286032 -222.437198)
		(width 0.0889)
		(layer "In11.Cu")
		(net "PVNN_MAIN_CPU0")
	)
	(arc
		(start 350.839278 -228.783388)
		(mid 351.116091 -228.707518)
		(end 351.394522 -228.777292)
		(width 0.0889)
		(layer "In11.Cu")
		(net "PVNN_MAIN_CPU0")
	)
	(arc
		(start 359.767632 -222.437198)
		(mid 359.580434 -222.387055)
		(end 359.393236 -222.437198)
		(width 0.0889)
		(layer "In11.Cu")
		(net "PVNN_MAIN_CPU0")
	)
	(arc
		(start 349.516192 -224.88398)
		(mid 349.385278 -225.02034)
		(end 349.33763 -225.203258)
		(width 0.0889)
		(layer "In11.Cu")
		(net "PVNN_MAIN_CPU0")
	)
	(arc
		(start 349.33763 -225.225356)
		(mid 349.256719 -225.495484)
		(end 349.055436 -225.69297)
		(width 0.0889)
		(layer "In11.Cu")
		(net "PVNN_MAIN_CPU0")
	)
	(arc
		(start 355.634036 -222.437198)
		(mid 355.359837 -222.513033)
		(end 355.083364 -222.445834)
		(width 0.0889)
		(layer "In11.Cu")
		(net "PVNN_MAIN_CPU0")
	)
	(arc
		(start 362.587032 -222.437198)
		(mid 362.399834 -222.387055)
		(end 362.212636 -222.437198)
		(width 0.0889)
		(layer "In11.Cu")
		(net "PVNN_MAIN_CPU0")
	)
	(arc
		(start 369.165632 -222.437198)
		(mid 368.978434 -222.387055)
		(end 368.791236 -222.437198)
		(width 0.0889)
		(layer "In11.Cu")
		(net "PVNN_MAIN_CPU0")
	)
	(arc
		(start 353.189032 -222.437198)
		(mid 353.001834 -222.387055)
		(end 352.814636 -222.437198)
		(width 0.0889)
		(layer "In11.Cu")
		(net "PVNN_MAIN_CPU0")
	)
	(arc
		(start 378.189236 -222.437198)
		(mid 377.915037 -222.513033)
		(end 377.638564 -222.445834)
		(width 0.0889)
		(layer "In11.Cu")
		(net "PVNN_MAIN_CPU0")
	)
	(arc
		(start 382.322832 -222.437198)
		(mid 382.135634 -222.387055)
		(end 381.948436 -222.437198)
		(width 0.0889)
		(layer "In11.Cu")
		(net "PVNN_MAIN_CPU0")
	)
	(arc
		(start 370.670836 -222.437198)
		(mid 370.396637 -222.513033)
		(end 370.120164 -222.445834)
		(width 0.0889)
		(layer "In11.Cu")
		(net "PVNN_MAIN_CPU0")
	)
	(arc
		(start 385.050284 -218.692222)
		(mid 384.976293 -218.971788)
		(end 384.773678 -219.178124)
		(width 0.0889)
		(layer "In11.Cu")
		(net "PVNN_MAIN_CPU0")
	)
	(arc
		(start 379.503432 -222.437198)
		(mid 379.316234 -222.387055)
		(end 379.129036 -222.437198)
		(width 0.0889)
		(layer "In11.Cu")
		(net "PVNN_MAIN_CPU0")
	)
	(arc
		(start 384.110484 -220.338396)
		(mid 384.030322 -220.610585)
		(end 383.828036 -220.809566)
		(width 0.0889)
		(layer "In11.Cu")
		(net "PVNN_MAIN_CPU0")
	)
	(arc
		(start 384.767582 -219.18168)
		(mid 384.632649 -219.315034)
		(end 384.580384 -219.497402)
		(width 0.0889)
		(layer "In11.Cu")
		(net "PVNN_MAIN_CPU0")
	)
	(arc
		(start 375.369836 -222.437198)
		(mid 375.095637 -222.513033)
		(end 374.819164 -222.445834)
		(width 0.0889)
		(layer "In11.Cu")
		(net "PVNN_MAIN_CPU0")
	)
	(arc
		(start 366.346232 -222.437198)
		(mid 366.159034 -222.387055)
		(end 365.971836 -222.437198)
		(width 0.0889)
		(layer "In11.Cu")
		(net "PVNN_MAIN_CPU0")
	)
	(arc
		(start 349.337884 -226.83978)
		(mid 349.390154 -227.022145)
		(end 349.525082 -227.155502)
		(width 0.0889)
		(layer "In11.Cu")
		(net "PVNN_MAIN_CPU0")
	)
	(arc
		(start 383.819146 -220.814646)
		(mid 383.688232 -220.951006)
		(end 383.640584 -221.133924)
		(width 0.0889)
		(layer "In11.Cu")
		(net "PVNN_MAIN_CPU0")
	)
	(arc
		(start 371.610636 -222.437198)
		(mid 371.336437 -222.513033)
		(end 371.059964 -222.445834)
		(width 0.0889)
		(layer "In11.Cu")
		(net "PVNN_MAIN_CPU0")
	)
	(arc
		(start 380.443232 -222.437198)
		(mid 380.256034 -222.387055)
		(end 380.068836 -222.437198)
		(width 0.0889)
		(layer "In11.Cu")
		(net "PVNN_MAIN_CPU0")
	)
	(arc
		(start 349.807784 -227.64496)
		(mid 349.855463 -227.82786)
		(end 349.986346 -227.964238)
		(width 0.0889)
		(layer "In11.Cu")
		(net "PVNN_MAIN_CPU0")
	)
	(arc
		(start 367.286032 -222.437198)
		(mid 367.098834 -222.387055)
		(end 366.911636 -222.437198)
		(width 0.0889)
		(layer "In11.Cu")
		(net "PVNN_MAIN_CPU0")
	)
	(arc
		(start 386.168646 -216.745058)
		(mid 386.037732 -216.881418)
		(end 385.990084 -217.064336)
		(width 0.0889)
		(layer "In11.Cu")
		(net "PVNN_MAIN_CPU0")
	)
	(arc
		(start 356.948232 -222.437198)
		(mid 356.761034 -222.387055)
		(end 356.573836 -222.437198)
		(width 0.0889)
		(layer "In11.Cu")
		(net "PVNN_MAIN_CPU0")
	)
	(arc
		(start 365.406432 -222.437198)
		(mid 365.219234 -222.387055)
		(end 365.032036 -222.437198)
		(width 0.0889)
		(layer "In11.Cu")
		(net "PVNN_MAIN_CPU0")
	)
	(arc
		(start 363.526832 -222.437198)
		(mid 363.339634 -222.387055)
		(end 363.152436 -222.437198)
		(width 0.0889)
		(layer "In11.Cu")
		(net "PVNN_MAIN_CPU0")
	)
	(arc
		(start 350.27743 -228.45903)
		(mid 350.325109 -228.64193)
		(end 350.455992 -228.778308)
		(width 0.0889)
		(layer "In11.Cu")
		(net "PVNN_MAIN_CPU0")
	)
	(arc
		(start 351.874836 -222.437198)
		(mid 351.600637 -222.513033)
		(end 351.324164 -222.445834)
		(width 0.0889)
		(layer "In11.Cu")
		(net "PVNN_MAIN_CPU0")
	)
	(arc
		(start 379.129036 -222.437198)
		(mid 378.854837 -222.513033)
		(end 378.578364 -222.445834)
		(width 0.0889)
		(layer "In11.Cu")
		(net "PVNN_MAIN_CPU0")
	)
	(arc
		(start 372.550436 -222.437198)
		(mid 372.276237 -222.513033)
		(end 371.999764 -222.445834)
		(width 0.0889)
		(layer "In11.Cu")
		(net "PVNN_MAIN_CPU0")
	)
	(arc
		(start 381.008636 -222.437198)
		(mid 380.734437 -222.513033)
		(end 380.457964 -222.445834)
		(width 0.0889)
		(layer "In11.Cu")
		(net "PVNN_MAIN_CPU0")
	)
	(arc
		(start 360.707432 -222.437198)
		(mid 360.520234 -222.387055)
		(end 360.333036 -222.437198)
		(width 0.0889)
		(layer "In11.Cu")
		(net "PVNN_MAIN_CPU0")
	)
	(arc
		(start 349.986346 -224.070164)
		(mid 349.855432 -224.206524)
		(end 349.807784 -224.389442)
		(width 0.0889)
		(layer "In11.Cu")
		(net "PVNN_MAIN_CPU0")
	)
	(arc
		(start 384.289046 -220.000576)
		(mid 384.158132 -220.136936)
		(end 384.110484 -220.319854)
		(width 0.0889)
		(layer "In11.Cu")
		(net "PVNN_MAIN_CPU0")
	)
	(arc
		(start 349.995236 -227.969318)
		(mid 350.196518 -228.166805)
		(end 350.27743 -228.436932)
		(width 0.0889)
		(layer "In11.Cu")
		(net "PVNN_MAIN_CPU0")
	)
	(arc
		(start 360.333036 -222.437198)
		(mid 360.058837 -222.513033)
		(end 359.782364 -222.445834)
		(width 0.0889)
		(layer "In11.Cu")
		(net "PVNN_MAIN_CPU0")
	)
	(arc
		(start 375.744232 -222.437198)
		(mid 375.557034 -222.387055)
		(end 375.369836 -222.437198)
		(width 0.0889)
		(layer "In11.Cu")
		(net "PVNN_MAIN_CPU0")
	)
	(arc
		(start 349.531178 -227.159058)
		(mid 349.733765 -227.365409)
		(end 349.807784 -227.64496)
		(width 0.0889)
		(layer "In11.Cu")
		(net "PVNN_MAIN_CPU0")
	)
	(arc
		(start 361.272836 -222.437198)
		(mid 360.998637 -222.513033)
		(end 360.722164 -222.445834)
		(width 0.0889)
		(layer "In11.Cu")
		(net "PVNN_MAIN_CPU0")
	)
	(arc
		(start 349.807784 -224.389442)
		(mid 349.733793 -224.669008)
		(end 349.531178 -224.875344)
		(width 0.0889)
		(layer "In11.Cu")
		(net "PVNN_MAIN_CPU0")
	)
	(arc
		(start 363.152436 -222.437198)
		(mid 362.869734 -222.512974)
		(end 362.587032 -222.437198)
		(width 0.0889)
		(layer "In11.Cu")
		(net "PVNN_MAIN_CPU0")
	)
	(arc
		(start 349.046546 -225.69805)
		(mid 348.867949 -226.017328)
		(end 349.046546 -226.336606)
		(width 0.0889)
		(layer "In11.Cu")
		(net "PVNN_MAIN_CPU0")
	)
	(arc
		(start 350.747584 -222.780098)
		(mid 350.667422 -223.052287)
		(end 350.465136 -223.251268)
		(width 0.0889)
		(layer "In11.Cu")
		(net "PVNN_MAIN_CPU0")
	)
	(arc
		(start 373.490236 -222.437198)
		(mid 373.216037 -222.513033)
		(end 372.939564 -222.445834)
		(width 0.0889)
		(layer "In11.Cu")
		(net "PVNN_MAIN_CPU0")
	)
	(arc
		(start 377.623832 -222.437198)
		(mid 377.436634 -222.387055)
		(end 377.249436 -222.437198)
		(width 0.0889)
		(layer "In11.Cu")
		(net "PVNN_MAIN_CPU0")
	)
	(arc
		(start 369.731036 -222.437198)
		(mid 369.456837 -222.513033)
		(end 369.180364 -222.445834)
		(width 0.0889)
		(layer "In11.Cu")
		(net "PVNN_MAIN_CPU0")
	)
	(arc
		(start 351.309432 -222.437198)
		(mid 351.122234 -222.387055)
		(end 350.935036 -222.437198)
		(width 0.0889)
		(layer "In11.Cu")
		(net "PVNN_MAIN_CPU0")
	)
	(segment
		(start 164.44468 -21.154898)
		(end 164.67328 -21.383498)
		(width 0.12954)
		(layer "F.Cu")
		(net "PVCCIO_PECI_BMC")
	)
	(segment
		(start 162.666934 -16.550132)
		(end 162.666934 -20.375372)
		(width 0.12954)
		(layer "F.Cu")
		(net "PVCCIO_PECI_BMC")
	)
	(segment
		(start 162.666934 -20.375372)
		(end 163.420298 -21.128736)
		(width 0.12954)
		(layer "F.Cu")
		(net "PVCCIO_PECI_BMC")
	)
	(segment
		(start 163.420298 -21.128736)
		(end 163.44646 -21.154898)
		(width 0.12954)
		(layer "F.Cu")
		(net "PVCCIO_PECI_BMC")
	)
	(segment
		(start 163.44646 -21.154898)
		(end 164.44468 -21.154898)
		(width 0.12954)
		(layer "F.Cu")
		(net "PVCCIO_PECI_BMC")
	)
	(via
		(at 163.420298 -21.128736)
		(size 0.762)
		(drill 0.381)
		(layers "F.Cu" "B.Cu")
		(net "PVCCIO_PECI_BMC")
	)
	(segment
		(start 113.520474 -356.593648)
		(end 112.89665 -357.217472)
		(width 0.1778)
		(layer "F.Cu")
		(net "PVCCIN_CPU1_VR_FAULT")
	)
	(segment
		(start 113.56594 -356.568248)
		(end 113.54054 -356.593648)
		(width 0.1778)
		(layer "F.Cu")
		(net "PVCCIN_CPU1_VR_FAULT")
	)
	(segment
		(start 113.54054 -356.593648)
		(end 113.520474 -356.593648)
		(width 0.1778)
		(layer "F.Cu")
		(net "PVCCIN_CPU1_VR_FAULT")
	)
	(segment
		(start 112.790986 -357.472488)
		(end 112.015016 -358.248458)
		(width 0.1778)
		(layer "F.Cu")
		(net "PVCCIN_CPU1_VR_FAULT")
	)
	(segment
		(start 112.015016 -358.248458)
		(end 111.453422 -358.248458)
		(width 0.1778)
		(layer "F.Cu")
		(net "PVCCIN_CPU1_VR_FAULT")
	)
	(segment
		(start 112.89665 -357.217472)
		(end 112.790986 -357.472488)
		(width 0.1778)
		(layer "F.Cu")
		(net "PVCCIN_CPU1_VR_FAULT")
	)
	(via
		(at 113.56594 -356.568248)
		(size 0.508)
		(drill 0.254)
		(layers "F.Cu" "B.Cu")
		(net "PVCCIN_CPU1_VR_FAULT")
	)
	(via
		(at 115.26647 -354.76942)
		(size 0.6604)
		(drill 0.3302)
		(layers "F.Cu" "B.Cu")
		(net "PVCCIN_CPU1_VR_FAULT")
	)
	(segment
		(start 115.26647 -354.76942)
		(end 115.26647 -355.925628)
		(width 0.12954)
		(layer "B.Cu")
		(net "PVCCIN_CPU1_VR_FAULT")
	)
	(segment
		(start 113.56594 -356.245414)
		(end 113.56594 -356.568248)
		(width 0.12954)
		(layer "B.Cu")
		(net "PVCCIN_CPU1_VR_FAULT")
	)
	(segment
		(start 115.26647 -355.925628)
		(end 114.845592 -355.925628)
		(width 0.12954)
		(layer "B.Cu")
		(net "PVCCIN_CPU1_VR_FAULT")
	)
	(segment
		(start 114.845592 -355.925628)
		(end 114.759232 -356.011988)
		(width 0.12954)
		(layer "B.Cu")
		(net "PVCCIN_CPU1_VR_FAULT")
	)
	(segment
		(start 114.759232 -356.011988)
		(end 113.799366 -356.011988)
		(width 0.12954)
		(layer "B.Cu")
		(net "PVCCIN_CPU1_VR_FAULT")
	)
	(segment
		(start 113.799366 -356.011988)
		(end 113.56594 -356.245414)
		(width 0.12954)
		(layer "B.Cu")
		(net "PVCCIN_CPU1_VR_FAULT")
	)
	(segment
		(start 119.502174 -338.238338)
		(end 119.166386 -337.90255)
		(width 0.254)
		(layer "F.Cu")
		(net "PVCCIN_CPU1_VREF")
	)
	(segment
		(start 49.2633 -356.555802)
		(end 48.501046 -357.318056)
		(width 0.2286)
		(layer "F.Cu")
		(net "PVCCIN_CPU1_VREF")
	)
	(segment
		(start 95.020638 -338.238338)
		(end 94.680532 -337.898232)
		(width 0.254)
		(layer "F.Cu")
		(net "PVCCIN_CPU1_VREF")
	)
	(segment
		(start 169.27195 -357.73741)
		(end 169.27195 -357.735886)
		(width 0.254)
		(layer "F.Cu")
		(net "PVCCIN_CPU1_VREF")
	)
	(segment
		(start 111.001302 -337.897978)
		(end 110.485682 -337.897978)
		(width 0.254)
		(layer "F.Cu")
		(net "PVCCIN_CPU1_VREF")
	)
	(segment
		(start 169.27195 -357.299006)
		(end 170.034204 -356.536752)
		(width 0.254)
		(layer "F.Cu")
		(net "PVCCIN_CPU1_VREF")
	)
	(segment
		(start 111.453422 -361.75569)
		(end 111.453422 -361.0483)
		(width 0.1778)
		(layer "F.Cu")
		(net "PVCCIN_CPU1_VREF")
	)
	(segment
		(start 169.52595 -357.99141)
		(end 169.27195 -357.73741)
		(width 0.254)
		(layer "F.Cu")
		(net "PVCCIN_CPU1_VREF")
	)
	(segment
		(start 78.593188 -347.332808)
		(end 78.593188 -347.315028)
		(width 0.254)
		(layer "F.Cu")
		(net "PVCCIN_CPU1_VREF")
	)
	(segment
		(start 49.2633 -356.447852)
		(end 49.2633 -356.555802)
		(width 0.2286)
		(layer "F.Cu")
		(net "PVCCIN_CPU1_VREF")
	)
	(segment
		(start 77.982826 -346.616528)
		(end 77.982826 -347.081348)
		(width 0.254)
		(layer "F.Cu")
		(net "PVCCIN_CPU1_VREF")
	)
	(segment
		(start 179.73548 -358.05364)
		(end 179.589938 -358.05364)
		(width 0.254)
		(layer "F.Cu")
		(net "PVCCIN_CPU1_VREF")
	)
	(segment
		(start 135.823198 -347.439234)
		(end 135.490712 -347.106748)
		(width 0.254)
		(layer "F.Cu")
		(net "PVCCIN_CPU1_VREF")
	)
	(segment
		(start 78.593188 -347.315028)
		(end 78.359508 -347.081348)
		(width 0.254)
		(layer "F.Cu")
		(net "PVCCIN_CPU1_VREF")
	)
	(segment
		(start 39.574978 -356.54107)
		(end 39.574978 -356.447852)
		(width 0.254)
		(layer "F.Cu")
		(net "PVCCIN_CPU1_VREF")
	)
	(segment
		(start 86.519512 -341.307928)
		(end 86.084918 -341.307928)
		(width 0.254)
		(layer "F.Cu")
		(net "PVCCIN_CPU1_VREF")
	)
	(segment
		(start 135.022844 -346.700094)
		(end 135.022844 -347.1037)
		(width 0.254)
		(layer "F.Cu")
		(net "PVCCIN_CPU1_VREF")
	)
	(segment
		(start 178.960272 -357.735886)
		(end 178.960272 -357.324406)
		(width 0.2286)
		(layer "F.Cu")
		(net "PVCCIN_CPU1_VREF")
	)
	(segment
		(start 78.68666 -345.816936)
		(end 78.68666 -345.912694)
		(width 0.254)
		(layer "F.Cu")
		(net "PVCCIN_CPU1_VREF")
	)
	(segment
		(start 38.812724 -357.729536)
		(end 38.812724 -357.303324)
		(width 0.254)
		(layer "F.Cu")
		(net "PVCCIN_CPU1_VREF")
	)
	(segment
		(start 111.328708 -336.69478)
		(end 111.328708 -336.61604)
		(width 0.254)
		(layer "F.Cu")
		(net "PVCCIN_CPU1_VREF")
	)
	(segment
		(start 86.847172 -340.026244)
		(end 86.847172 -340.122002)
		(width 0.254)
		(layer "F.Cu")
		(net "PVCCIN_CPU1_VREF")
	)
	(segment
		(start 102.355142 -337.5152)
		(end 102.355142 -337.890612)
		(width 0.254)
		(layer "F.Cu")
		(net "PVCCIN_CPU1_VREF")
	)
	(segment
		(start 111.341662 -338.238338)
		(end 111.001302 -337.897978)
		(width 0.254)
		(layer "F.Cu")
		(net "PVCCIN_CPU1_VREF")
	)
	(segment
		(start 78.699614 -347.439234)
		(end 78.593188 -347.332808)
		(width 0.254)
		(layer "F.Cu")
		(net "PVCCIN_CPU1_VREF")
	)
	(segment
		(start 95.007684 -336.711798)
		(end 94.201996 -337.517486)
		(width 0.254)
		(layer "F.Cu")
		(net "PVCCIN_CPU1_VREF")
	)
	(segment
		(start 78.359508 -347.081348)
		(end 77.982826 -347.081348)
		(width 0.254)
		(layer "F.Cu")
		(net "PVCCIN_CPU1_VREF")
	)
	(segment
		(start 48.501046 -357.318056)
		(end 48.501046 -357.729536)
		(width 0.2286)
		(layer "F.Cu")
		(net "PVCCIN_CPU1_VREF")
	)
	(segment
		(start 112.70361 -364.757208)
		(end 113.348516 -364.757208)
		(width 0.1778)
		(layer "F.Cu")
		(net "PVCCIN_CPU1_VREF")
	)
	(segment
		(start 103.168196 -336.61604)
		(end 103.168196 -336.702146)
		(width 0.254)
		(layer "F.Cu")
		(net "PVCCIN_CPU1_VREF")
	)
	(segment
		(start 78.68666 -345.912694)
		(end 77.982826 -346.616528)
		(width 0.254)
		(layer "F.Cu")
		(net "PVCCIN_CPU1_VREF")
	)
	(segment
		(start 127.662686 -341.648542)
		(end 127.3302 -341.316056)
		(width 0.254)
		(layer "F.Cu")
		(net "PVCCIN_CPU1_VREF")
	)
	(segment
		(start 103.168196 -336.702146)
		(end 102.355142 -337.5152)
		(width 0.254)
		(layer "F.Cu")
		(net "PVCCIN_CPU1_VREF")
	)
	(segment
		(start 119.48922 -336.711798)
		(end 119.48922 -336.61604)
		(width 0.254)
		(layer "F.Cu")
		(net "PVCCIN_CPU1_VREF")
	)
	(segment
		(start 86.860126 -341.648542)
		(end 86.519512 -341.307928)
		(width 0.254)
		(layer "F.Cu")
		(net "PVCCIN_CPU1_VREF")
	)
	(segment
		(start 112.046258 -363.595666)
		(end 112.046258 -362.348526)
		(width 0.1778)
		(layer "F.Cu")
		(net "PVCCIN_CPU1_VREF")
	)
	(segment
		(start 86.847172 -340.122002)
		(end 86.084918 -340.884256)
		(width 0.254)
		(layer "F.Cu")
		(net "PVCCIN_CPU1_VREF")
	)
	(segment
		(start 113.349532 -364.758224)
		(end 114.243612 -364.758224)
		(width 0.1778)
		(layer "F.Cu")
		(net "PVCCIN_CPU1_VREF")
	)
	(segment
		(start 169.27195 -357.735886)
		(end 169.27195 -357.299006)
		(width 0.254)
		(layer "F.Cu")
		(net "PVCCIN_CPU1_VREF")
	)
	(segment
		(start 112.70361 -364.253018)
		(end 112.046258 -363.595666)
		(width 0.1778)
		(layer "F.Cu")
		(net "PVCCIN_CPU1_VREF")
	)
	(segment
		(start 102.841044 -337.890612)
		(end 102.355142 -337.890612)
		(width 0.254)
		(layer "F.Cu")
		(net "PVCCIN_CPU1_VREF")
	)
	(segment
		(start 103.074724 -338.124292)
		(end 102.841044 -337.890612)
		(width 0.254)
		(layer "F.Cu")
		(net "PVCCIN_CPU1_VREF")
	)
	(segment
		(start 170.047158 -357.99141)
		(end 169.52595 -357.99141)
		(width 0.254)
		(layer "F.Cu")
		(net "PVCCIN_CPU1_VREF")
	)
	(segment
		(start 112.70361 -364.757208)
		(end 112.70361 -364.253018)
		(width 0.1778)
		(layer "F.Cu")
		(net "PVCCIN_CPU1_VREF")
	)
	(segment
		(start 126.862332 -340.909402)
		(end 126.862332 -341.316056)
		(width 0.254)
		(layer "F.Cu")
		(net "PVCCIN_CPU1_VREF")
	)
	(segment
		(start 49.144682 -358.0765)
		(end 48.797718 -357.729536)
		(width 0.254)
		(layer "F.Cu")
		(net "PVCCIN_CPU1_VREF")
	)
	(segment
		(start 135.490712 -347.106748)
		(end 135.031988 -347.106748)
		(width 0.254)
		(layer "F.Cu")
		(net "PVCCIN_CPU1_VREF")
	)
	(segment
		(start 39.206424 -357.729536)
		(end 38.812724 -357.729536)
		(width 0.254)
		(layer "F.Cu")
		(net "PVCCIN_CPU1_VREF")
	)
	(segment
		(start 110.485682 -337.537806)
		(end 111.328708 -336.69478)
		(width 0.254)
		(layer "F.Cu")
		(net "PVCCIN_CPU1_VREF")
	)
	(segment
		(start 118.781576 -337.419442)
		(end 119.48922 -336.711798)
		(width 0.254)
		(layer "F.Cu")
		(net "PVCCIN_CPU1_VREF")
	)
	(segment
		(start 179.589938 -358.05364)
		(end 179.272184 -357.735886)
		(width 0.254)
		(layer "F.Cu")
		(net "PVCCIN_CPU1_VREF")
	)
	(segment
		(start 94.680532 -337.898232)
		(end 94.201996 -337.898232)
		(width 0.254)
		(layer "F.Cu")
		(net "PVCCIN_CPU1_VREF")
	)
	(segment
		(start 103.18115 -338.238338)
		(end 103.074724 -338.131912)
		(width 0.254)
		(layer "F.Cu")
		(net "PVCCIN_CPU1_VREF")
	)
	(segment
		(start 127.649732 -340.026244)
		(end 127.649732 -340.122002)
		(width 0.254)
		(layer "F.Cu")
		(net "PVCCIN_CPU1_VREF")
	)
	(segment
		(start 38.812724 -357.303324)
		(end 39.574978 -356.54107)
		(width 0.254)
		(layer "F.Cu")
		(net "PVCCIN_CPU1_VREF")
	)
	(segment
		(start 127.649732 -340.122002)
		(end 126.862332 -340.909402)
		(width 0.254)
		(layer "F.Cu")
		(net "PVCCIN_CPU1_VREF")
	)
	(segment
		(start 178.960272 -357.324406)
		(end 179.722526 -356.562152)
		(width 0.2286)
		(layer "F.Cu")
		(net "PVCCIN_CPU1_VREF")
	)
	(segment
		(start 113.348516 -364.757208)
		(end 113.349532 -364.758224)
		(width 0.1778)
		(layer "F.Cu")
		(net "PVCCIN_CPU1_VREF")
	)
	(segment
		(start 179.272184 -357.735886)
		(end 178.960272 -357.735886)
		(width 0.254)
		(layer "F.Cu")
		(net "PVCCIN_CPU1_VREF")
	)
	(segment
		(start 135.031988 -347.106748)
		(end 135.02894 -347.109796)
		(width 0.254)
		(layer "F.Cu")
		(net "PVCCIN_CPU1_VREF")
	)
	(segment
		(start 135.022844 -347.1037)
		(end 135.02894 -347.109796)
		(width 0.254)
		(layer "F.Cu")
		(net "PVCCIN_CPU1_VREF")
	)
	(segment
		(start 118.781576 -337.90255)
		(end 118.781576 -337.419442)
		(width 0.254)
		(layer "F.Cu")
		(net "PVCCIN_CPU1_VREF")
	)
	(segment
		(start 103.074724 -338.131912)
		(end 103.074724 -338.124292)
		(width 0.254)
		(layer "F.Cu")
		(net "PVCCIN_CPU1_VREF")
	)
	(segment
		(start 112.046258 -362.348526)
		(end 111.453422 -361.75569)
		(width 0.1778)
		(layer "F.Cu")
		(net "PVCCIN_CPU1_VREF")
	)
	(segment
		(start 86.084918 -340.884256)
		(end 86.084918 -341.307928)
		(width 0.254)
		(layer "F.Cu")
		(net "PVCCIN_CPU1_VREF")
	)
	(segment
		(start 135.810244 -345.912694)
		(end 135.022844 -346.700094)
		(width 0.254)
		(layer "F.Cu")
		(net "PVCCIN_CPU1_VREF")
	)
	(segment
		(start 94.201996 -337.517486)
		(end 94.201996 -337.898232)
		(width 0.254)
		(layer "F.Cu")
		(net "PVCCIN_CPU1_VREF")
	)
	(segment
		(start 179.722526 -356.562152)
		(end 179.722526 -356.454202)
		(width 0.2286)
		(layer "F.Cu")
		(net "PVCCIN_CPU1_VREF")
	)
	(segment
		(start 39.461948 -357.98506)
		(end 39.206424 -357.729536)
		(width 0.254)
		(layer "F.Cu")
		(net "PVCCIN_CPU1_VREF")
	)
	(segment
		(start 39.587932 -357.98506)
		(end 39.461948 -357.98506)
		(width 0.254)
		(layer "F.Cu")
		(net "PVCCIN_CPU1_VREF")
	)
	(segment
		(start 127.3302 -341.316056)
		(end 126.862332 -341.316056)
		(width 0.254)
		(layer "F.Cu")
		(net "PVCCIN_CPU1_VREF")
	)
	(segment
		(start 119.166386 -337.90255)
		(end 118.781576 -337.90255)
		(width 0.254)
		(layer "F.Cu")
		(net "PVCCIN_CPU1_VREF")
	)
	(segment
		(start 135.810244 -345.816936)
		(end 135.810244 -345.912694)
		(width 0.254)
		(layer "F.Cu")
		(net "PVCCIN_CPU1_VREF")
	)
	(segment
		(start 110.485682 -337.897978)
		(end 110.485682 -337.537806)
		(width 0.254)
		(layer "F.Cu")
		(net "PVCCIN_CPU1_VREF")
	)
	(segment
		(start 95.007684 -336.61604)
		(end 95.007684 -336.711798)
		(width 0.254)
		(layer "F.Cu")
		(net "PVCCIN_CPU1_VREF")
	)
	(segment
		(start 170.034204 -356.536752)
		(end 170.034204 -356.454202)
		(width 0.254)
		(layer "F.Cu")
		(net "PVCCIN_CPU1_VREF")
	)
	(segment
		(start 48.797718 -357.729536)
		(end 48.501046 -357.729536)
		(width 0.254)
		(layer "F.Cu")
		(net "PVCCIN_CPU1_VREF")
	)
	(segment
		(start 49.261014 -358.0765)
		(end 49.144682 -358.0765)
		(width 0.254)
		(layer "F.Cu")
		(net "PVCCIN_CPU1_VREF")
	)
	(via
		(at 112.70361 -364.757208)
		(size 0.508)
		(drill 0.254)
		(layers "F.Cu" "B.Cu")
		(net "PVCCIN_CPU1_VREF")
	)
	(via
		(at 44.126658 -367.978436)
		(size 0.508)
		(drill 0.254)
		(layers "F.Cu" "B.Cu")
		(net "PVCCIN_CPU1_VREF")
	)
	(via
		(at 107.733084 -366.626394)
		(size 0.508)
		(drill 0.254)
		(layers "F.Cu" "B.Cu")
		(net "PVCCIN_CPU1_VREF")
	)
	(via
		(at 95.020638 -338.238338)
		(size 0.508)
		(drill 0.254)
		(layers "F.Cu" "B.Cu")
		(net "PVCCIN_CPU1_VREF")
	)
	(via
		(at 170.047158 -357.99141)
		(size 0.508)
		(drill 0.254)
		(layers "F.Cu" "B.Cu")
		(net "PVCCIN_CPU1_VREF")
	)
	(via
		(at 103.18115 -338.238338)
		(size 0.508)
		(drill 0.254)
		(layers "F.Cu" "B.Cu")
		(net "PVCCIN_CPU1_VREF")
	)
	(via
		(at 111.341662 -338.238338)
		(size 0.508)
		(drill 0.254)
		(layers "F.Cu" "B.Cu")
		(net "PVCCIN_CPU1_VREF")
	)
	(via
		(at 105.054146 -366.244632)
		(size 0.508)
		(drill 0.254)
		(layers "F.Cu" "B.Cu")
		(net "PVCCIN_CPU1_VREF")
	)
	(via
		(at 119.502174 -338.238338)
		(size 0.508)
		(drill 0.254)
		(layers "F.Cu" "B.Cu")
		(net "PVCCIN_CPU1_VREF")
	)
	(via
		(at 49.261014 -358.0765)
		(size 0.508)
		(drill 0.254)
		(layers "F.Cu" "B.Cu")
		(net "PVCCIN_CPU1_VREF")
	)
	(via
		(at 127.662686 -341.648542)
		(size 0.508)
		(drill 0.254)
		(layers "F.Cu" "B.Cu")
		(net "PVCCIN_CPU1_VREF")
	)
	(via
		(at 78.699614 -347.439234)
		(size 0.508)
		(drill 0.254)
		(layers "F.Cu" "B.Cu")
		(net "PVCCIN_CPU1_VREF")
	)
	(via
		(at 39.587932 -357.98506)
		(size 0.508)
		(drill 0.254)
		(layers "F.Cu" "B.Cu")
		(net "PVCCIN_CPU1_VREF")
	)
	(via
		(at 114.566192 -356.848156)
		(size 0.508)
		(drill 0.254)
		(layers "F.Cu" "B.Cu")
		(net "PVCCIN_CPU1_VREF")
	)
	(via
		(at 179.73548 -358.05364)
		(size 0.508)
		(drill 0.254)
		(layers "F.Cu" "B.Cu")
		(net "PVCCIN_CPU1_VREF")
	)
	(via
		(at 135.823198 -347.439234)
		(size 0.508)
		(drill 0.254)
		(layers "F.Cu" "B.Cu")
		(net "PVCCIN_CPU1_VREF")
	)
	(via
		(at 56.100726 -369.50015)
		(size 0.508)
		(drill 0.254)
		(layers "F.Cu" "B.Cu")
		(net "PVCCIN_CPU1_VREF")
	)
	(via
		(at 86.860126 -341.648542)
		(size 0.508)
		(drill 0.254)
		(layers "F.Cu" "B.Cu")
		(net "PVCCIN_CPU1_VREF")
	)
	(segment
		(start 57.423558 -367.768632)
		(end 52.263802 -367.768632)
		(width 0.254)
		(layer "B.Cu")
		(net "PVCCIN_CPU1_VREF")
	)
	(segment
		(start 59.673998 -370.019072)
		(end 57.423558 -367.768632)
		(width 0.254)
		(layer "B.Cu")
		(net "PVCCIN_CPU1_VREF")
	)
	(segment
		(start 52.263802 -367.768632)
		(end 51.824382 -368.208052)
		(width 0.254)
		(layer "B.Cu")
		(net "PVCCIN_CPU1_VREF")
	)
	(segment
		(start 57.395872 -372.247922)
		(end 55.871618 -370.723668)
		(width 0.254)
		(layer "B.Cu")
		(net "PVCCIN_CPU1_VREF")
	)
	(segment
		(start 44.356274 -368.208052)
		(end 44.126658 -367.978436)
		(width 0.254)
		(layer "B.Cu")
		(net "PVCCIN_CPU1_VREF")
	)
	(segment
		(start 51.824382 -368.208052)
		(end 44.356274 -368.208052)
		(width 0.254)
		(layer "B.Cu")
		(net "PVCCIN_CPU1_VREF")
	)
	(segment
		(start 105.054146 -366.244632)
		(end 105.300018 -366.490504)
		(width 0.254)
		(layer "B.Cu")
		(net "PVCCIN_CPU1_VREF")
	)
	(segment
		(start 107.979718 -368.222276)
		(end 103.954072 -372.247922)
		(width 0.254)
		(layer "B.Cu")
		(net "PVCCIN_CPU1_VREF")
	)
	(segment
		(start 103.954072 -372.247922)
		(end 57.395872 -372.247922)
		(width 0.254)
		(layer "B.Cu")
		(net "PVCCIN_CPU1_VREF")
	)
	(segment
		(start 55.871618 -369.729258)
		(end 56.100726 -369.50015)
		(width 0.254)
		(layer "B.Cu")
		(net "PVCCIN_CPU1_VREF")
	)
	(segment
		(start 55.871618 -370.723668)
		(end 55.871618 -369.729258)
		(width 0.254)
		(layer "B.Cu")
		(net "PVCCIN_CPU1_VREF")
	)
	(segment
		(start 105.300018 -366.490504)
		(end 105.300018 -367.718848)
		(width 0.254)
		(layer "B.Cu")
		(net "PVCCIN_CPU1_VREF")
	)
	(segment
		(start 105.300018 -367.718848)
		(end 102.999794 -370.019072)
		(width 0.254)
		(layer "B.Cu")
		(net "PVCCIN_CPU1_VREF")
	)
	(segment
		(start 102.999794 -370.019072)
		(end 59.673998 -370.019072)
		(width 0.254)
		(layer "B.Cu")
		(net "PVCCIN_CPU1_VREF")
	)
	(segment
		(start 114.566192 -356.848156)
		(end 114.769646 -357.05161)
		(width 0.2032)
		(layer "B.Cu")
		(net "PVCCIN_CPU1_VREF")
	)
	(segment
		(start 114.769646 -357.05161)
		(end 114.769646 -357.436166)
		(width 0.2032)
		(layer "B.Cu")
		(net "PVCCIN_CPU1_VREF")
	)
	(segment
		(start 107.733084 -366.626394)
		(end 107.979718 -366.873028)
		(width 0.254)
		(layer "B.Cu")
		(net "PVCCIN_CPU1_VREF")
	)
	(segment
		(start 107.979718 -366.873028)
		(end 107.979718 -368.222276)
		(width 0.254)
		(layer "B.Cu")
		(net "PVCCIN_CPU1_VREF")
	)
	(segment
		(start 108.749846 -362.564172)
		(end 108.749846 -365.055912)
		(width 0.254)
		(layer "In4.Cu")
		(net "PVCCIN_CPU1_VREF")
	)
	(segment
		(start 105.280206 -365.61014)
		(end 105.280206 -366.018572)
		(width 0.254)
		(layer "In4.Cu")
		(net "PVCCIN_CPU1_VREF")
	)
	(segment
		(start 110.265718 -353.88804)
		(end 109.156246 -353.88804)
		(width 0.254)
		(layer "In4.Cu")
		(net "PVCCIN_CPU1_VREF")
	)
	(segment
		(start 108.749846 -365.055912)
		(end 107.939586 -365.866172)
		(width 0.254)
		(layer "In4.Cu")
		(net "PVCCIN_CPU1_VREF")
	)
	(segment
		(start 109.301026 -356.407212)
		(end 109.301026 -362.012992)
		(width 0.254)
		(layer "In4.Cu")
		(net "PVCCIN_CPU1_VREF")
	)
	(segment
		(start 105.280206 -366.018572)
		(end 105.054146 -366.244632)
		(width 0.254)
		(layer "In4.Cu")
		(net "PVCCIN_CPU1_VREF")
	)
	(segment
		(start 110.898686 -355.767132)
		(end 109.941106 -355.767132)
		(width 0.254)
		(layer "In4.Cu")
		(net "PVCCIN_CPU1_VREF")
	)
	(segment
		(start 107.939586 -365.866172)
		(end 107.939586 -366.419892)
		(width 0.254)
		(layer "In4.Cu")
		(net "PVCCIN_CPU1_VREF")
	)
	(segment
		(start 107.834938 -352.566732)
		(end 102.074472 -352.566732)
		(width 0.254)
		(layer "In4.Cu")
		(net "PVCCIN_CPU1_VREF")
	)
	(segment
		(start 109.156246 -353.88804)
		(end 107.834938 -352.566732)
		(width 0.254)
		(layer "In4.Cu")
		(net "PVCCIN_CPU1_VREF")
	)
	(segment
		(start 100.781866 -362.953554)
		(end 102.802944 -364.974632)
		(width 0.254)
		(layer "In4.Cu")
		(net "PVCCIN_CPU1_VREF")
	)
	(segment
		(start 109.941106 -355.767132)
		(end 109.301026 -356.407212)
		(width 0.254)
		(layer "In4.Cu")
		(net "PVCCIN_CPU1_VREF")
	)
	(segment
		(start 104.644698 -364.974632)
		(end 105.280206 -365.61014)
		(width 0.254)
		(layer "In4.Cu")
		(net "PVCCIN_CPU1_VREF")
	)
	(segment
		(start 102.802944 -364.974632)
		(end 104.644698 -364.974632)
		(width 0.254)
		(layer "In4.Cu")
		(net "PVCCIN_CPU1_VREF")
	)
	(segment
		(start 100.781866 -353.859338)
		(end 100.781866 -362.953554)
		(width 0.254)
		(layer "In4.Cu")
		(net "PVCCIN_CPU1_VREF")
	)
	(segment
		(start 102.074472 -352.566732)
		(end 100.781866 -353.859338)
		(width 0.254)
		(layer "In4.Cu")
		(net "PVCCIN_CPU1_VREF")
	)
	(segment
		(start 109.301026 -362.012992)
		(end 108.749846 -362.564172)
		(width 0.254)
		(layer "In4.Cu")
		(net "PVCCIN_CPU1_VREF")
	)
	(segment
		(start 107.939586 -366.419892)
		(end 107.733084 -366.626394)
		(width 0.254)
		(layer "In4.Cu")
		(net "PVCCIN_CPU1_VREF")
	)
	(segment
		(start 38.168072 -358.62133)
		(end 38.950392 -357.83901)
		(width 0.254)
		(layer "In6.Cu")
		(net "PVCCIN_CPU1_VREF")
	)
	(segment
		(start 39.441882 -357.83901)
		(end 39.587932 -357.98506)
		(width 0.254)
		(layer "In6.Cu")
		(net "PVCCIN_CPU1_VREF")
	)
	(segment
		(start 38.168072 -365.819182)
		(end 38.168072 -358.62133)
		(width 0.254)
		(layer "In6.Cu")
		(net "PVCCIN_CPU1_VREF")
	)
	(segment
		(start 48.709072 -359.836212)
		(end 48.439832 -359.566972)
		(width 0.254)
		(layer "In6.Cu")
		(net "PVCCIN_CPU1_VREF")
	)
	(segment
		(start 43.882564 -368.22253)
		(end 40.57142 -368.22253)
		(width 0.254)
		(layer "In6.Cu")
		(net "PVCCIN_CPU1_VREF")
	)
	(segment
		(start 53.73624 -359.836212)
		(end 48.709072 -359.836212)
		(width 0.254)
		(layer "In6.Cu")
		(net "PVCCIN_CPU1_VREF")
	)
	(segment
		(start 40.57142 -368.22253)
		(end 38.168072 -365.819182)
		(width 0.254)
		(layer "In6.Cu")
		(net "PVCCIN_CPU1_VREF")
	)
	(segment
		(start 55.872126 -369.27155)
		(end 55.872126 -368.173508)
		(width 0.254)
		(layer "In6.Cu")
		(net "PVCCIN_CPU1_VREF")
	)
	(segment
		(start 48.439832 -358.491282)
		(end 49.010062 -357.921052)
		(width 0.254)
		(layer "In6.Cu")
		(net "PVCCIN_CPU1_VREF")
	)
	(segment
		(start 54.667658 -366.96904)
		(end 54.667658 -360.76763)
		(width 0.254)
		(layer "In6.Cu")
		(net "PVCCIN_CPU1_VREF")
	)
	(segment
		(start 55.872126 -368.173508)
		(end 54.667658 -366.96904)
		(width 0.254)
		(layer "In6.Cu")
		(net "PVCCIN_CPU1_VREF")
	)
	(segment
		(start 56.100726 -369.50015)
		(end 55.872126 -369.27155)
		(width 0.254)
		(layer "In6.Cu")
		(net "PVCCIN_CPU1_VREF")
	)
	(segment
		(start 44.126658 -367.978436)
		(end 43.882564 -368.22253)
		(width 0.254)
		(layer "In6.Cu")
		(net "PVCCIN_CPU1_VREF")
	)
	(segment
		(start 38.950392 -357.83901)
		(end 39.441882 -357.83901)
		(width 0.254)
		(layer "In6.Cu")
		(net "PVCCIN_CPU1_VREF")
	)
	(segment
		(start 54.667658 -360.76763)
		(end 53.73624 -359.836212)
		(width 0.254)
		(layer "In6.Cu")
		(net "PVCCIN_CPU1_VREF")
	)
	(segment
		(start 49.010062 -357.921052)
		(end 49.105566 -357.921052)
		(width 0.254)
		(layer "In6.Cu")
		(net "PVCCIN_CPU1_VREF")
	)
	(segment
		(start 49.105566 -357.921052)
		(end 49.261014 -358.0765)
		(width 0.254)
		(layer "In6.Cu")
		(net "PVCCIN_CPU1_VREF")
	)
	(segment
		(start 48.439832 -359.566972)
		(end 48.439832 -358.491282)
		(width 0.254)
		(layer "In6.Cu")
		(net "PVCCIN_CPU1_VREF")
	)
	(segment
		(start 109.7788 -353.118928)
		(end 109.5502 -353.347528)
		(width 0.254)
		(layer "In11.Cu")
		(net "PVCCIN_CPU1_VREF")
	)
	(segment
		(start 114.125756 -349.759778)
		(end 117.472968 -346.412566)
		(width 0.254)
		(layer "In11.Cu")
		(net "PVCCIN_CPU1_VREF")
	)
	(segment
		(start 106.886248 -347.467428)
		(end 108.044488 -346.309188)
		(width 0.254)
		(layer "In11.Cu")
		(net "PVCCIN_CPU1_VREF")
	)
	(segment
		(start 88.056212 -344.309446)
		(end 87.004398 -343.257632)
		(width 0.254)
		(layer "In11.Cu")
		(net "PVCCIN_CPU1_VREF")
	)
	(segment
		(start 100.23094 -342.298782)
		(end 93.65361 -342.298782)
		(width 0.254)
		(layer "In11.Cu")
		(net "PVCCIN_CPU1_VREF")
	)
	(segment
		(start 131.5212 -363.40796)
		(end 136.494774 -358.434386)
		(width 0.254)
		(layer "In11.Cu")
		(net "PVCCIN_CPU1_VREF")
	)
	(segment
		(start 119.011954 -340.546436)
		(end 119.639588 -339.918802)
		(width 0.254)
		(layer "In11.Cu")
		(net "PVCCIN_CPU1_VREF")
	)
	(segment
		(start 175.634904 -359.18521)
		(end 176.273968 -358.546146)
		(width 0.254)
		(layer "In11.Cu")
		(net "PVCCIN_CPU1_VREF")
	)
	(segment
		(start 178.703986 -358.546146)
		(end 179.196492 -358.05364)
		(width 0.254)
		(layer "In11.Cu")
		(net "PVCCIN_CPU1_VREF")
	)
	(segment
		(start 110.780576 -354.833428)
		(end 108.881164 -354.833428)
		(width 0.254)
		(layer "In11.Cu")
		(net "PVCCIN_CPU1_VREF")
	)
	(segment
		(start 84.752434 -349.635064)
		(end 79.448406 -349.635064)
		(width 0.254)
		(layer "In11.Cu")
		(net "PVCCIN_CPU1_VREF")
	)
	(segment
		(start 113.779808 -348.004638)
		(end 117.031008 -344.753438)
		(width 0.254)
		(layer "In11.Cu")
		(net "PVCCIN_CPU1_VREF")
	)
	(segment
		(start 108.68914 -345.665806)
		(end 108.68914 -343.299288)
		(width 0.254)
		(layer "In11.Cu")
		(net "PVCCIN_CPU1_VREF")
	)
	(segment
		(start 108.847128 -363.388656)
		(end 108.847128 -365.966756)
		(width 0.254)
		(layer "In11.Cu")
		(net "PVCCIN_CPU1_VREF")
	)
	(segment
		(start 111.504476 -338.401152)
		(end 111.341662 -338.238338)
		(width 0.254)
		(layer "In11.Cu")
		(net "PVCCIN_CPU1_VREF")
	)
	(segment
		(start 107.421426 -354.33)
		(end 105.759758 -355.991668)
		(width 0.254)
		(layer "In11.Cu")
		(net "PVCCIN_CPU1_VREF")
	)
	(segment
		(start 87.697818 -346.68968)
		(end 84.752434 -349.635064)
		(width 0.254)
		(layer "In11.Cu")
		(net "PVCCIN_CPU1_VREF")
	)
	(segment
		(start 112.801654 -352.138996)
		(end 121.340372 -352.138996)
		(width 0.254)
		(layer "In11.Cu")
		(net "PVCCIN_CPU1_VREF")
	)
	(segment
		(start 107.8992 -350.683068)
		(end 107.8992 -349.15856)
		(width 0.254)
		(layer "In11.Cu")
		(net "PVCCIN_CPU1_VREF")
	)
	(segment
		(start 127.917194 -341.90305)
		(end 127.662686 -341.648542)
		(width 0.254)
		(layer "In11.Cu")
		(net "PVCCIN_CPU1_VREF")
	)
	(segment
		(start 110.823756 -350.675956)
		(end 111.740188 -349.759778)
		(width 0.254)
		(layer "In11.Cu")
		(net "PVCCIN_CPU1_VREF")
	)
	(segment
		(start 108.68914 -343.299288)
		(end 105.967276 -340.577424)
		(width 0.254)
		(layer "In11.Cu")
		(net "PVCCIN_CPU1_VREF")
	)
	(segment
		(start 119.639588 -338.375752)
		(end 119.502174 -338.238338)
		(width 0.254)
		(layer "In11.Cu")
		(net "PVCCIN_CPU1_VREF")
	)
	(segment
		(start 111.215424 -348.004638)
		(end 113.779808 -348.004638)
		(width 0.254)
		(layer "In11.Cu")
		(net "PVCCIN_CPU1_VREF")
	)
	(segment
		(start 78.699614 -348.886272)
		(end 78.699614 -347.439234)
		(width 0.254)
		(layer "In11.Cu")
		(net "PVCCIN_CPU1_VREF")
	)
	(segment
		(start 132.940298 -347.748352)
		(end 133.765544 -348.573598)
		(width 0.254)
		(layer "In11.Cu")
		(net "PVCCIN_CPU1_VREF")
	)
	(segment
		(start 108.044488 -346.309188)
		(end 108.04525 -346.309696)
		(width 0.254)
		(layer "In11.Cu")
		(net "PVCCIN_CPU1_VREF")
	)
	(segment
		(start 117.472968 -346.412566)
		(end 125.07214 -346.412566)
		(width 0.254)
		(layer "In11.Cu")
		(net "PVCCIN_CPU1_VREF")
	)
	(segment
		(start 136.078468 -347.694504)
		(end 135.823198 -347.439234)
		(width 0.254)
		(layer "In11.Cu")
		(net "PVCCIN_CPU1_VREF")
	)
	(segment
		(start 110.336076 -346.721684)
		(end 110.336076 -340.831678)
		(width 0.254)
		(layer "In11.Cu")
		(net "PVCCIN_CPU1_VREF")
	)
	(segment
		(start 98.402902 -349.535496)
		(end 98.402902 -347.428566)
		(width 0.254)
		(layer "In11.Cu")
		(net "PVCCIN_CPU1_VREF")
	)
	(segment
		(start 175.243744 -359.575608)
		(end 175.634396 -359.184956)
		(width 0.254)
		(layer "In11.Cu")
		(net "PVCCIN_CPU1_VREF")
	)
	(segment
		(start 173.863508 -359.575608)
		(end 175.243744 -359.575608)
		(width 0.254)
		(layer "In11.Cu")
		(net "PVCCIN_CPU1_VREF")
	)
	(segment
		(start 117.031008 -344.753438)
		(end 117.031008 -342.527128)
		(width 0.254)
		(layer "In11.Cu")
		(net "PVCCIN_CPU1_VREF")
	)
	(segment
		(start 111.740188 -349.759778)
		(end 114.125756 -349.759778)
		(width 0.254)
		(layer "In11.Cu")
		(net "PVCCIN_CPU1_VREF")
	)
	(segment
		(start 105.828338 -350.41459)
		(end 105.828338 -348.843854)
		(width 0.254)
		(layer "In11.Cu")
		(net "PVCCIN_CPU1_VREF")
	)
	(segment
		(start 79.448406 -349.635064)
		(end 78.699614 -348.886272)
		(width 0.254)
		(layer "In11.Cu")
		(net "PVCCIN_CPU1_VREF")
	)
	(segment
		(start 87.004398 -343.257632)
		(end 87.004398 -341.792814)
		(width 0.254)
		(layer "In11.Cu")
		(net "PVCCIN_CPU1_VREF")
	)
	(segment
		(start 125.07214 -346.412566)
		(end 127.917194 -343.567512)
		(width 0.254)
		(layer "In11.Cu")
		(net "PVCCIN_CPU1_VREF")
	)
	(segment
		(start 107.434126 -361.975654)
		(end 108.847128 -363.388656)
		(width 0.254)
		(layer "In11.Cu")
		(net "PVCCIN_CPU1_VREF")
	)
	(segment
		(start 127.917194 -343.567512)
		(end 127.917194 -341.90305)
		(width 0.254)
		(layer "In11.Cu")
		(net "PVCCIN_CPU1_VREF")
	)
	(segment
		(start 93.65361 -342.298782)
		(end 91.642946 -344.309446)
		(width 0.254)
		(layer "In11.Cu")
		(net "PVCCIN_CPU1_VREF")
	)
	(segment
		(start 117.780562 -358.872028)
		(end 117.780562 -362.603796)
		(width 0.254)
		(layer "In11.Cu")
		(net "PVCCIN_CPU1_VREF")
	)
	(segment
		(start 106.886248 -350.63684)
		(end 106.886248 -347.467428)
		(width 0.254)
		(layer "In11.Cu")
		(net "PVCCIN_CPU1_VREF")
	)
	(segment
		(start 136.078468 -348.153228)
		(end 136.078468 -347.694504)
		(width 0.254)
		(layer "In11.Cu")
		(net "PVCCIN_CPU1_VREF")
	)
	(segment
		(start 104.445816 -340.577424)
		(end 103.29545 -339.427058)
		(width 0.254)
		(layer "In11.Cu")
		(net "PVCCIN_CPU1_VREF")
	)
	(segment
		(start 87.004398 -341.792814)
		(end 86.860126 -341.648542)
		(width 0.254)
		(layer "In11.Cu")
		(net "PVCCIN_CPU1_VREF")
	)
	(segment
		(start 108.847128 -365.966756)
		(end 109.96422 -367.083848)
		(width 0.254)
		(layer "In11.Cu")
		(net "PVCCIN_CPU1_VREF")
	)
	(segment
		(start 103.29545 -339.427058)
		(end 103.29545 -338.352638)
		(width 0.254)
		(layer "In11.Cu")
		(net "PVCCIN_CPU1_VREF")
	)
	(segment
		(start 102.782624 -345.79814)
		(end 102.782624 -342.624664)
		(width 0.254)
		(layer "In11.Cu")
		(net "PVCCIN_CPU1_VREF")
	)
	(segment
		(start 95.546926 -340.115652)
		(end 95.130874 -339.6996)
		(width 0.254)
		(layer "In11.Cu")
		(net "PVCCIN_CPU1_VREF")
	)
	(segment
		(start 110.336076 -340.831678)
		(end 111.504476 -339.663278)
		(width 0.254)
		(layer "In11.Cu")
		(net "PVCCIN_CPU1_VREF")
	)
	(segment
		(start 117.780562 -362.603796)
		(end 118.915942 -363.739176)
		(width 0.254)
		(layer "In11.Cu")
		(net "PVCCIN_CPU1_VREF")
	)
	(segment
		(start 108.90504 -350.315022)
		(end 111.215424 -348.004638)
		(width 0.254)
		(layer "In11.Cu")
		(net "PVCCIN_CPU1_VREF")
	)
	(segment
		(start 135.658098 -348.573598)
		(end 136.078468 -348.153228)
		(width 0.254)
		(layer "In11.Cu")
		(net "PVCCIN_CPU1_VREF")
	)
	(segment
		(start 119.639588 -339.918802)
		(end 119.639588 -338.375752)
		(width 0.254)
		(layer "In11.Cu")
		(net "PVCCIN_CPU1_VREF")
	)
	(segment
		(start 107.434126 -356.280466)
		(end 107.434126 -361.975654)
		(width 0.254)
		(layer "In11.Cu")
		(net "PVCCIN_CPU1_VREF")
	)
	(segment
		(start 179.196492 -358.05364)
		(end 179.73548 -358.05364)
		(width 0.254)
		(layer "In11.Cu")
		(net "PVCCIN_CPU1_VREF")
	)
	(segment
		(start 98.402902 -347.428566)
		(end 97.664016 -346.68968)
		(width 0.254)
		(layer "In11.Cu")
		(net "PVCCIN_CPU1_VREF")
	)
	(segment
		(start 111.504476 -339.663278)
		(end 111.504476 -338.401152)
		(width 0.254)
		(layer "In11.Cu")
		(net "PVCCIN_CPU1_VREF")
	)
	(segment
		(start 120.489472 -363.739176)
		(end 120.820688 -363.40796)
		(width 0.254)
		(layer "In11.Cu")
		(net "PVCCIN_CPU1_VREF")
	)
	(segment
		(start 103.552498 -353.347528)
		(end 101.300026 -351.095056)
		(width 0.254)
		(layer "In11.Cu")
		(net "PVCCIN_CPU1_VREF")
	)
	(segment
		(start 175.634396 -359.184956)
		(end 175.634904 -359.18521)
		(width 0.254)
		(layer "In11.Cu")
		(net "PVCCIN_CPU1_VREF")
	)
	(segment
		(start 133.765544 -348.573598)
		(end 135.658098 -348.573598)
		(width 0.254)
		(layer "In11.Cu")
		(net "PVCCIN_CPU1_VREF")
	)
	(segment
		(start 102.782624 -342.624664)
		(end 100.273612 -340.115652)
		(width 0.254)
		(layer "In11.Cu")
		(net "PVCCIN_CPU1_VREF")
	)
	(segment
		(start 118.915942 -363.739176)
		(end 120.489472 -363.739176)
		(width 0.254)
		(layer "In11.Cu")
		(net "PVCCIN_CPU1_VREF")
	)
	(segment
		(start 132.938266 -364.572296)
		(end 136.974072 -360.53649)
		(width 0.254)
		(layer "In11.Cu")
		(net "PVCCIN_CPU1_VREF")
	)
	(segment
		(start 97.664016 -346.68968)
		(end 87.697818 -346.68968)
		(width 0.254)
		(layer "In11.Cu")
		(net "PVCCIN_CPU1_VREF")
	)
	(segment
		(start 101.300026 -343.367868)
		(end 100.23094 -342.298782)
		(width 0.254)
		(layer "In11.Cu")
		(net "PVCCIN_CPU1_VREF")
	)
	(segment
		(start 108.90504 -350.769428)
		(end 108.90504 -350.315022)
		(width 0.254)
		(layer "In11.Cu")
		(net "PVCCIN_CPU1_VREF")
	)
	(segment
		(start 104.859074 -355.991668)
		(end 98.402902 -349.535496)
		(width 0.254)
		(layer "In11.Cu")
		(net "PVCCIN_CPU1_VREF")
	)
	(segment
		(start 121.628916 -364.572296)
		(end 132.938266 -364.572296)
		(width 0.254)
		(layer "In11.Cu")
		(net "PVCCIN_CPU1_VREF")
	)
	(segment
		(start 176.273968 -358.546146)
		(end 178.703986 -358.546146)
		(width 0.254)
		(layer "In11.Cu")
		(net "PVCCIN_CPU1_VREF")
	)
	(segment
		(start 107.8992 -349.15856)
		(end 110.336076 -346.721684)
		(width 0.254)
		(layer "In11.Cu")
		(net "PVCCIN_CPU1_VREF")
	)
	(segment
		(start 136.494774 -358.434386)
		(end 169.065194 -358.434386)
		(width 0.254)
		(layer "In11.Cu")
		(net "PVCCIN_CPU1_VREF")
	)
	(segment
		(start 169.50817 -357.99141)
		(end 170.047158 -357.99141)
		(width 0.254)
		(layer "In11.Cu")
		(net "PVCCIN_CPU1_VREF")
	)
	(segment
		(start 172.902626 -360.53649)
		(end 173.863508 -359.575608)
		(width 0.254)
		(layer "In11.Cu")
		(net "PVCCIN_CPU1_VREF")
	)
	(segment
		(start 109.96422 -367.083848)
		(end 119.117364 -367.083848)
		(width 0.254)
		(layer "In11.Cu")
		(net "PVCCIN_CPU1_VREF")
	)
	(segment
		(start 105.759758 -355.991668)
		(end 104.859074 -355.991668)
		(width 0.254)
		(layer "In11.Cu")
		(net "PVCCIN_CPU1_VREF")
	)
	(segment
		(start 103.29545 -338.352638)
		(end 103.18115 -338.238338)
		(width 0.254)
		(layer "In11.Cu")
		(net "PVCCIN_CPU1_VREF")
	)
	(segment
		(start 169.065194 -358.434386)
		(end 169.50817 -357.99141)
		(width 0.254)
		(layer "In11.Cu")
		(net "PVCCIN_CPU1_VREF")
	)
	(segment
		(start 105.828338 -348.843854)
		(end 102.782624 -345.79814)
		(width 0.254)
		(layer "In11.Cu")
		(net "PVCCIN_CPU1_VREF")
	)
	(segment
		(start 95.130874 -338.348574)
		(end 95.020638 -338.238338)
		(width 0.254)
		(layer "In11.Cu")
		(net "PVCCIN_CPU1_VREF")
	)
	(segment
		(start 114.968782 -356.060248)
		(end 117.780562 -358.872028)
		(width 0.254)
		(layer "In11.Cu")
		(net "PVCCIN_CPU1_VREF")
	)
	(segment
		(start 121.340372 -352.138996)
		(end 125.731016 -347.748352)
		(width 0.254)
		(layer "In11.Cu")
		(net "PVCCIN_CPU1_VREF")
	)
	(segment
		(start 125.731016 -347.748352)
		(end 132.940298 -347.748352)
		(width 0.254)
		(layer "In11.Cu")
		(net "PVCCIN_CPU1_VREF")
	)
	(segment
		(start 110.5662 -354.33)
		(end 107.421426 -354.33)
		(width 0.254)
		(layer "In11.Cu")
		(net "PVCCIN_CPU1_VREF")
	)
	(segment
		(start 120.820688 -363.40796)
		(end 131.5212 -363.40796)
		(width 0.254)
		(layer "In11.Cu")
		(net "PVCCIN_CPU1_VREF")
	)
	(segment
		(start 119.117364 -367.083848)
		(end 121.628916 -364.572296)
		(width 0.254)
		(layer "In11.Cu")
		(net "PVCCIN_CPU1_VREF")
	)
	(segment
		(start 117.031008 -342.527128)
		(end 119.011954 -340.546182)
		(width 0.254)
		(layer "In11.Cu")
		(net "PVCCIN_CPU1_VREF")
	)
	(segment
		(start 95.130874 -339.6996)
		(end 95.130874 -338.348574)
		(width 0.254)
		(layer "In11.Cu")
		(net "PVCCIN_CPU1_VREF")
	)
	(segment
		(start 108.04525 -346.309696)
		(end 108.68914 -345.665806)
		(width 0.254)
		(layer "In11.Cu")
		(net "PVCCIN_CPU1_VREF")
	)
	(segment
		(start 91.642946 -344.309446)
		(end 88.056212 -344.309446)
		(width 0.254)
		(layer "In11.Cu")
		(net "PVCCIN_CPU1_VREF")
	)
	(segment
		(start 108.881164 -354.833428)
		(end 107.434126 -356.280466)
		(width 0.254)
		(layer "In11.Cu")
		(net "PVCCIN_CPU1_VREF")
	)
	(segment
		(start 101.300026 -351.095056)
		(end 101.300026 -343.367868)
		(width 0.254)
		(layer "In11.Cu")
		(net "PVCCIN_CPU1_VREF")
	)
	(segment
		(start 119.011954 -340.546182)
		(end 119.011954 -340.546436)
		(width 0.254)
		(layer "In11.Cu")
		(net "PVCCIN_CPU1_VREF")
	)
	(segment
		(start 109.5502 -353.347528)
		(end 103.552498 -353.347528)
		(width 0.254)
		(layer "In11.Cu")
		(net "PVCCIN_CPU1_VREF")
	)
	(segment
		(start 100.273612 -340.115652)
		(end 95.546926 -340.115652)
		(width 0.254)
		(layer "In11.Cu")
		(net "PVCCIN_CPU1_VREF")
	)
	(segment
		(start 136.974072 -360.53649)
		(end 172.902626 -360.53649)
		(width 0.254)
		(layer "In11.Cu")
		(net "PVCCIN_CPU1_VREF")
	)
	(segment
		(start 105.967276 -340.577424)
		(end 104.445816 -340.577424)
		(width 0.254)
		(layer "In11.Cu")
		(net "PVCCIN_CPU1_VREF")
	)
	(segment
		(start 135.017002 -345.845638)
		(end 135.400288 -345.462352)
		(width 0.254)
		(layer "F.Cu")
		(net "PVCCIN_CPU1_VOS8")
	)
	(segment
		(start 135.400288 -345.462352)
		(end 135.400288 -345.192096)
		(width 0.254)
		(layer "F.Cu")
		(net "PVCCIN_CPU1_VOS8")
	)
	(via
		(at 135.017002 -345.845638)
		(size 0.508)
		(drill 0.254)
		(layers "F.Cu" "B.Cu")
		(net "PVCCIN_CPU1_VOS8")
	)
	(segment
		(start 135.017002 -345.510866)
		(end 134.743698 -345.237562)
		(width 0.2286)
		(layer "B.Cu")
		(net "PVCCIN_CPU1_VOS8")
	)
	(segment
		(start 134.522464 -345.237562)
		(end 134.347966 -345.063064)
		(width 0.2286)
		(layer "B.Cu")
		(net "PVCCIN_CPU1_VOS8")
	)
	(segment
		(start 135.017002 -345.845638)
		(end 135.017002 -345.510866)
		(width 0.2286)
		(layer "B.Cu")
		(net "PVCCIN_CPU1_VOS8")
	)
	(segment
		(start 134.743698 -345.237562)
		(end 134.522464 -345.237562)
		(width 0.2286)
		(layer "B.Cu")
		(net "PVCCIN_CPU1_VOS8")
	)
	(segment
		(start 78.276704 -345.192096)
		(end 78.276704 -345.462352)
		(width 0.254)
		(layer "F.Cu")
		(net "PVCCIN_CPU1_VOS7")
	)
	(segment
		(start 78.276704 -345.462352)
		(end 77.893418 -345.845638)
		(width 0.254)
		(layer "F.Cu")
		(net "PVCCIN_CPU1_VOS7")
	)
	(via
		(at 77.893418 -345.845638)
		(size 0.508)
		(drill 0.254)
		(layers "F.Cu" "B.Cu")
		(net "PVCCIN_CPU1_VOS7")
	)
	(segment
		(start 77.893418 -345.845638)
		(end 77.893418 -345.580462)
		(width 0.2032)
		(layer "B.Cu")
		(net "PVCCIN_CPU1_VOS7")
	)
	(segment
		(start 77.893418 -345.580462)
		(end 77.74305 -345.430094)
		(width 0.2032)
		(layer "B.Cu")
		(net "PVCCIN_CPU1_VOS7")
	)
	(segment
		(start 77.74305 -345.430094)
		(end 76.809854 -345.430094)
		(width 0.2032)
		(layer "B.Cu")
		(net "PVCCIN_CPU1_VOS7")
	)
	(segment
		(start 86.05393 -340.054946)
		(end 86.437216 -339.67166)
		(width 0.254)
		(layer "F.Cu")
		(net "PVCCIN_CPU1_VOS6")
	)
	(segment
		(start 86.437216 -339.67166)
		(end 86.437216 -339.401404)
		(width 0.254)
		(layer "F.Cu")
		(net "PVCCIN_CPU1_VOS6")
	)
	(via
		(at 86.05393 -340.054946)
		(size 0.508)
		(drill 0.254)
		(layers "F.Cu" "B.Cu")
		(net "PVCCIN_CPU1_VOS6")
	)
	(segment
		(start 85.818726 -339.819742)
		(end 85.625686 -339.819742)
		(width 0.2286)
		(layer "B.Cu")
		(net "PVCCIN_CPU1_VOS6")
	)
	(segment
		(start 85.625686 -339.819742)
		(end 85.389466 -339.583522)
		(width 0.2286)
		(layer "B.Cu")
		(net "PVCCIN_CPU1_VOS6")
	)
	(segment
		(start 86.05393 -340.054946)
		(end 85.818726 -339.819742)
		(width 0.2286)
		(layer "B.Cu")
		(net "PVCCIN_CPU1_VOS6")
	)
	(segment
		(start 127.239776 -339.67166)
		(end 127.239776 -339.401404)
		(width 0.254)
		(layer "F.Cu")
		(net "PVCCIN_CPU1_VOS5")
	)
	(segment
		(start 126.85649 -340.054946)
		(end 127.239776 -339.67166)
		(width 0.254)
		(layer "F.Cu")
		(net "PVCCIN_CPU1_VOS5")
	)
	(via
		(at 126.85649 -340.054946)
		(size 0.508)
		(drill 0.254)
		(layers "F.Cu" "B.Cu")
		(net "PVCCIN_CPU1_VOS5")
	)
	(segment
		(start 126.85649 -339.72627)
		(end 126.85649 -340.054946)
		(width 0.2286)
		(layer "B.Cu")
		(net "PVCCIN_CPU1_VOS5")
	)
	(segment
		(start 126.065026 -339.202522)
		(end 126.332742 -339.202522)
		(width 0.2286)
		(layer "B.Cu")
		(net "PVCCIN_CPU1_VOS5")
	)
	(segment
		(start 126.332742 -339.202522)
		(end 126.85649 -339.72627)
		(width 0.2286)
		(layer "B.Cu")
		(net "PVCCIN_CPU1_VOS5")
	)
	(segment
		(start 119.079264 -336.261456)
		(end 119.079264 -335.9912)
		(width 0.254)
		(layer "F.Cu")
		(net "PVCCIN_CPU1_VOS4")
	)
	(segment
		(start 118.695978 -336.644742)
		(end 119.079264 -336.261456)
		(width 0.254)
		(layer "F.Cu")
		(net "PVCCIN_CPU1_VOS4")
	)
	(via
		(at 118.695978 -336.644742)
		(size 0.508)
		(drill 0.254)
		(layers "F.Cu" "B.Cu")
		(net "PVCCIN_CPU1_VOS4")
	)
	(segment
		(start 118.695978 -336.644742)
		(end 118.695978 -336.343498)
		(width 0.2032)
		(layer "B.Cu")
		(net "PVCCIN_CPU1_VOS4")
	)
	(segment
		(start 118.695978 -336.343498)
		(end 118.144798 -335.792318)
		(width 0.2032)
		(layer "B.Cu")
		(net "PVCCIN_CPU1_VOS4")
	)
	(segment
		(start 118.144798 -335.792318)
		(end 117.904514 -335.792318)
		(width 0.2032)
		(layer "B.Cu")
		(net "PVCCIN_CPU1_VOS4")
	)
	(segment
		(start 110.918752 -336.261456)
		(end 110.918752 -335.9912)
		(width 0.254)
		(layer "F.Cu")
		(net "PVCCIN_CPU1_VOS3")
	)
	(segment
		(start 110.535466 -336.644742)
		(end 110.918752 -336.261456)
		(width 0.254)
		(layer "F.Cu")
		(net "PVCCIN_CPU1_VOS3")
	)
	(via
		(at 110.535466 -336.644742)
		(size 0.508)
		(drill 0.254)
		(layers "F.Cu" "B.Cu")
		(net "PVCCIN_CPU1_VOS3")
	)
	(segment
		(start 110.535466 -336.644742)
		(end 110.535466 -336.206338)
		(width 0.254)
		(layer "B.Cu")
		(net "PVCCIN_CPU1_VOS3")
	)
	(segment
		(start 110.115096 -335.785968)
		(end 109.658912 -335.785968)
		(width 0.254)
		(layer "B.Cu")
		(net "PVCCIN_CPU1_VOS3")
	)
	(segment
		(start 110.535466 -336.206338)
		(end 110.115096 -335.785968)
		(width 0.254)
		(layer "B.Cu")
		(net "PVCCIN_CPU1_VOS3")
	)
	(segment
		(start 102.75824 -336.261456)
		(end 102.75824 -335.9912)
		(width 0.254)
		(layer "F.Cu")
		(net "PVCCIN_CPU1_VOS2")
	)
	(segment
		(start 102.374954 -336.644742)
		(end 102.75824 -336.261456)
		(width 0.254)
		(layer "F.Cu")
		(net "PVCCIN_CPU1_VOS2")
	)
	(via
		(at 102.374954 -336.644742)
		(size 0.508)
		(drill 0.254)
		(layers "F.Cu" "B.Cu")
		(net "PVCCIN_CPU1_VOS2")
	)
	(segment
		(start 102.088442 -336.042762)
		(end 101.967792 -336.042762)
		(width 0.2286)
		(layer "B.Cu")
		(net "PVCCIN_CPU1_VOS2")
	)
	(segment
		(start 102.374954 -336.329274)
		(end 102.088442 -336.042762)
		(width 0.2286)
		(layer "B.Cu")
		(net "PVCCIN_CPU1_VOS2")
	)
	(segment
		(start 102.374954 -336.644742)
		(end 102.374954 -336.329274)
		(width 0.2286)
		(layer "B.Cu")
		(net "PVCCIN_CPU1_VOS2")
	)
	(segment
		(start 101.967792 -336.042762)
		(end 101.717348 -335.792318)
		(width 0.2286)
		(layer "B.Cu")
		(net "PVCCIN_CPU1_VOS2")
	)
	(segment
		(start 94.214442 -336.644742)
		(end 94.597728 -336.261456)
		(width 0.254)
		(layer "F.Cu")
		(net "PVCCIN_CPU1_VOS1")
	)
	(segment
		(start 94.597728 -336.261456)
		(end 94.597728 -335.9912)
		(width 0.254)
		(layer "F.Cu")
		(net "PVCCIN_CPU1_VOS1")
	)
	(via
		(at 94.214442 -336.644742)
		(size 0.508)
		(drill 0.254)
		(layers "F.Cu" "B.Cu")
		(net "PVCCIN_CPU1_VOS1")
	)
	(segment
		(start 94.214442 -336.156554)
		(end 93.936312 -335.878424)
		(width 0.254)
		(layer "B.Cu")
		(net "PVCCIN_CPU1_VOS1")
	)
	(segment
		(start 94.214442 -336.644742)
		(end 94.214442 -336.156554)
		(width 0.254)
		(layer "B.Cu")
		(net "PVCCIN_CPU1_VOS1")
	)
	(segment
		(start 93.936312 -335.878424)
		(end 93.571314 -335.878424)
		(width 0.254)
		(layer "B.Cu")
		(net "PVCCIN_CPU1_VOS1")
	)
	(segment
		(start 112.7379 -361.544616)
		(end 113.176558 -361.544616)
		(width 0.1778)
		(layer "F.Cu")
		(net "PVCCIN_CPU1_VIN_CSNIN")
	)
	(segment
		(start 114.306604 -361.024678)
		(end 114.306604 -360.83875)
		(width 0.1778)
		(layer "F.Cu")
		(net "PVCCIN_CPU1_VIN_CSNIN")
	)
	(segment
		(start 113.542826 -361.178348)
		(end 114.152934 -361.178348)
		(width 0.1778)
		(layer "F.Cu")
		(net "PVCCIN_CPU1_VIN_CSNIN")
	)
	(segment
		(start 112.386618 -360.711496)
		(end 112.386618 -361.193334)
		(width 0.1778)
		(layer "F.Cu")
		(net "PVCCIN_CPU1_VIN_CSNIN")
	)
	(segment
		(start 114.152934 -361.178348)
		(end 114.306604 -361.024678)
		(width 0.1778)
		(layer "F.Cu")
		(net "PVCCIN_CPU1_VIN_CSNIN")
	)
	(segment
		(start 111.453422 -360.248454)
		(end 111.923576 -360.248454)
		(width 0.1778)
		(layer "F.Cu")
		(net "PVCCIN_CPU1_VIN_CSNIN")
	)
	(segment
		(start 113.176558 -361.544616)
		(end 113.542826 -361.178348)
		(width 0.1778)
		(layer "F.Cu")
		(net "PVCCIN_CPU1_VIN_CSNIN")
	)
	(segment
		(start 111.923576 -360.248454)
		(end 112.386618 -360.711496)
		(width 0.1778)
		(layer "F.Cu")
		(net "PVCCIN_CPU1_VIN_CSNIN")
	)
	(segment
		(start 112.386618 -361.193334)
		(end 112.7379 -361.544616)
		(width 0.1778)
		(layer "F.Cu")
		(net "PVCCIN_CPU1_VIN_CSNIN")
	)
	(via
		(at 112.7379 -361.544616)
		(size 0.762)
		(drill 0.254)
		(layers "F.Cu" "B.Cu")
		(net "PVCCIN_CPU1_VIN_CSNIN")
	)
	(segment
		(start 112.8649 -361.544616)
		(end 112.7379 -361.544616)
		(width 0.254)
		(layer "B.Cu")
		(net "PVCCIN_CPU1_VIN_CSNIN")
	)
	(segment
		(start 113.32337 -361.703366)
		(end 113.02365 -361.703366)
		(width 0.254)
		(layer "B.Cu")
		(net "PVCCIN_CPU1_VIN_CSNIN")
	)
	(segment
		(start 113.02365 -361.703366)
		(end 112.8649 -361.544616)
		(width 0.254)
		(layer "B.Cu")
		(net "PVCCIN_CPU1_VIN_CSNIN")
	)
	(segment
		(start 112.6109 -361.417616)
		(end 112.359948 -361.417616)
		(width 0.254)
		(layer "B.Cu")
		(net "PVCCIN_CPU1_VIN_CSNIN")
	)
	(segment
		(start 112.359948 -361.417616)
		(end 112.021366 -361.079034)
		(width 0.254)
		(layer "B.Cu")
		(net "PVCCIN_CPU1_VIN_CSNIN")
	)
	(segment
		(start 112.021366 -361.079034)
		(end 112.021366 -360.847386)
		(width 0.254)
		(layer "B.Cu")
		(net "PVCCIN_CPU1_VIN_CSNIN")
	)
	(segment
		(start 112.7379 -361.544616)
		(end 112.6109 -361.417616)
		(width 0.254)
		(layer "B.Cu")
		(net "PVCCIN_CPU1_VIN_CSNIN")
	)
	(segment
		(start 113.38433 -361.764326)
		(end 113.32337 -361.703366)
		(width 0.254)
		(layer "B.Cu")
		(net "PVCCIN_CPU1_VIN_CSNIN")
	)
	(segment
		(start 137.610342 -346.528898)
		(end 137.610342 -345.816936)
		(width 0.2286)
		(layer "F.Cu")
		(net "PVCCIN_CPU1_VDD8")
	)
	(segment
		(start 134.225538 -344.993214)
		(end 134.310882 -344.993214)
		(width 0.2032)
		(layer "F.Cu")
		(net "PVCCIN_CPU1_VDD8")
	)
	(segment
		(start 134.225538 -344.377264)
		(end 134.225538 -344.993214)
		(width 0.2032)
		(layer "F.Cu")
		(net "PVCCIN_CPU1_VDD8")
	)
	(segment
		(start 135.012176 -344.29192)
		(end 135.400288 -344.29192)
		(width 0.2032)
		(layer "F.Cu")
		(net "PVCCIN_CPU1_VDD8")
	)
	(segment
		(start 137.53465 -346.60459)
		(end 137.610342 -346.528898)
		(width 0.2286)
		(layer "F.Cu")
		(net "PVCCIN_CPU1_VDD8")
	)
	(segment
		(start 134.310882 -344.993214)
		(end 135.012176 -344.29192)
		(width 0.2032)
		(layer "F.Cu")
		(net "PVCCIN_CPU1_VDD8")
	)
	(via
		(at 137.53465 -346.60459)
		(size 0.508)
		(drill 0.254)
		(layers "F.Cu" "B.Cu")
		(net "PVCCIN_CPU1_VDD8")
	)
	(via
		(at 135.976106 -345.774772)
		(size 0.6604)
		(drill 0.3302)
		(layers "F.Cu" "B.Cu")
		(net "PVCCIN_CPU1_VDD8")
	)
	(via
		(at 134.225538 -344.377264)
		(size 0.508)
		(drill 0.254)
		(layers "F.Cu" "B.Cu")
		(net "PVCCIN_CPU1_VDD8")
	)
	(segment
		(start 137.53465 -346.60459)
		(end 137.043922 -346.113862)
		(width 0.2286)
		(layer "B.Cu")
		(net "PVCCIN_CPU1_VDD8")
	)
	(segment
		(start 136.315196 -346.113862)
		(end 135.976106 -345.774772)
		(width 0.2286)
		(layer "B.Cu")
		(net "PVCCIN_CPU1_VDD8")
	)
	(segment
		(start 137.043922 -346.113862)
		(end 136.315196 -346.113862)
		(width 0.2286)
		(layer "B.Cu")
		(net "PVCCIN_CPU1_VDD8")
	)
	(segment
		(start 135.976106 -345.774772)
		(end 135.489442 -345.288108)
		(width 0.2286)
		(layer "B.Cu")
		(net "PVCCIN_CPU1_VDD8")
	)
	(segment
		(start 135.440166 -344.377264)
		(end 135.489442 -344.327988)
		(width 0.2286)
		(layer "B.Cu")
		(net "PVCCIN_CPU1_VDD8")
	)
	(segment
		(start 135.489442 -345.288108)
		(end 135.489442 -344.327988)
		(width 0.2286)
		(layer "B.Cu")
		(net "PVCCIN_CPU1_VDD8")
	)
	(segment
		(start 134.225538 -344.377264)
		(end 135.440166 -344.377264)
		(width 0.2286)
		(layer "B.Cu")
		(net "PVCCIN_CPU1_VDD8")
	)
	(segment
		(start 77.23759 -345.002612)
		(end 77.107542 -345.002612)
		(width 0.2286)
		(layer "F.Cu")
		(net "PVCCIN_CPU1_VDD7")
	)
	(segment
		(start 78.276704 -344.29192)
		(end 77.948282 -344.29192)
		(width 0.2286)
		(layer "F.Cu")
		(net "PVCCIN_CPU1_VDD7")
	)
	(segment
		(start 80.486758 -346.528898)
		(end 80.411066 -346.60459)
		(width 0.2286)
		(layer "F.Cu")
		(net "PVCCIN_CPU1_VDD7")
	)
	(segment
		(start 77.145642 -344.964512)
		(end 77.107542 -345.002612)
		(width 0.2032)
		(layer "F.Cu")
		(net "PVCCIN_CPU1_VDD7")
	)
	(segment
		(start 80.486758 -345.816936)
		(end 80.486758 -346.528898)
		(width 0.2286)
		(layer "F.Cu")
		(net "PVCCIN_CPU1_VDD7")
	)
	(segment
		(start 77.948282 -344.29192)
		(end 77.23759 -345.002612)
		(width 0.2286)
		(layer "F.Cu")
		(net "PVCCIN_CPU1_VDD7")
	)
	(segment
		(start 77.145642 -344.386662)
		(end 77.145642 -344.964512)
		(width 0.2032)
		(layer "F.Cu")
		(net "PVCCIN_CPU1_VDD7")
	)
	(via
		(at 80.411066 -346.60459)
		(size 0.508)
		(drill 0.254)
		(layers "F.Cu" "B.Cu")
		(net "PVCCIN_CPU1_VDD7")
	)
	(via
		(at 78.894432 -345.742006)
		(size 0.6604)
		(drill 0.3302)
		(layers "F.Cu" "B.Cu")
		(net "PVCCIN_CPU1_VDD7")
	)
	(via
		(at 77.145642 -344.386662)
		(size 0.508)
		(drill 0.254)
		(layers "F.Cu" "B.Cu")
		(net "PVCCIN_CPU1_VDD7")
	)
	(segment
		(start 77.767688 -344.327988)
		(end 77.776578 -344.327988)
		(width 0.2286)
		(layer "B.Cu")
		(net "PVCCIN_CPU1_VDD7")
	)
	(segment
		(start 77.776578 -344.336878)
		(end 77.776578 -344.327988)
		(width 0.2286)
		(layer "B.Cu")
		(net "PVCCIN_CPU1_VDD7")
	)
	(segment
		(start 77.869542 -344.717116)
		(end 77.869542 -344.429842)
		(width 0.2286)
		(layer "B.Cu")
		(net "PVCCIN_CPU1_VDD7")
	)
	(segment
		(start 80.411066 -346.60459)
		(end 79.935578 -346.129102)
		(width 0.2286)
		(layer "B.Cu")
		(net "PVCCIN_CPU1_VDD7")
	)
	(segment
		(start 79.281528 -346.129102)
		(end 78.894432 -345.742006)
		(width 0.2286)
		(layer "B.Cu")
		(net "PVCCIN_CPU1_VDD7")
	)
	(segment
		(start 77.869542 -344.429842)
		(end 77.776578 -344.336878)
		(width 0.2286)
		(layer "B.Cu")
		(net "PVCCIN_CPU1_VDD7")
	)
	(segment
		(start 77.145642 -344.386662)
		(end 77.709014 -344.386662)
		(width 0.2286)
		(layer "B.Cu")
		(net "PVCCIN_CPU1_VDD7")
	)
	(segment
		(start 79.935578 -346.129102)
		(end 79.281528 -346.129102)
		(width 0.2286)
		(layer "B.Cu")
		(net "PVCCIN_CPU1_VDD7")
	)
	(segment
		(start 78.894432 -345.742006)
		(end 77.869542 -344.717116)
		(width 0.2286)
		(layer "B.Cu")
		(net "PVCCIN_CPU1_VDD7")
	)
	(segment
		(start 77.709014 -344.386662)
		(end 77.767688 -344.327988)
		(width 0.2286)
		(layer "B.Cu")
		(net "PVCCIN_CPU1_VDD7")
	)
	(segment
		(start 85.990176 -338.501228)
		(end 85.262466 -339.228938)
		(width 0.2032)
		(layer "F.Cu")
		(net "PVCCIN_CPU1_VDD6")
	)
	(segment
		(start 88.571578 -340.813898)
		(end 88.64727 -340.738206)
		(width 0.2286)
		(layer "F.Cu")
		(net "PVCCIN_CPU1_VDD6")
	)
	(segment
		(start 85.083142 -338.671662)
		(end 85.083142 -339.157564)
		(width 0.2032)
		(layer "F.Cu")
		(net "PVCCIN_CPU1_VDD6")
	)
	(segment
		(start 85.262466 -339.336888)
		(end 85.260942 -339.338412)
		(width 0.2286)
		(layer "F.Cu")
		(net "PVCCIN_CPU1_VDD6")
	)
	(segment
		(start 86.437216 -338.501228)
		(end 85.990176 -338.501228)
		(width 0.2032)
		(layer "F.Cu")
		(net "PVCCIN_CPU1_VDD6")
	)
	(segment
		(start 85.262466 -339.228938)
		(end 85.262466 -339.336888)
		(width 0.2032)
		(layer "F.Cu")
		(net "PVCCIN_CPU1_VDD6")
	)
	(segment
		(start 88.64727 -340.738206)
		(end 88.64727 -340.026244)
		(width 0.2286)
		(layer "F.Cu")
		(net "PVCCIN_CPU1_VDD6")
	)
	(segment
		(start 85.083142 -339.157564)
		(end 85.262466 -339.336888)
		(width 0.2032)
		(layer "F.Cu")
		(net "PVCCIN_CPU1_VDD6")
	)
	(via
		(at 88.571578 -340.813898)
		(size 0.508)
		(drill 0.254)
		(layers "F.Cu" "B.Cu")
		(net "PVCCIN_CPU1_VDD6")
	)
	(via
		(at 85.083142 -338.671662)
		(size 0.508)
		(drill 0.254)
		(layers "F.Cu" "B.Cu")
		(net "PVCCIN_CPU1_VDD6")
	)
	(via
		(at 86.941406 -339.894672)
		(size 0.6604)
		(drill 0.3302)
		(layers "F.Cu" "B.Cu")
		(net "PVCCIN_CPU1_VDD6")
	)
	(segment
		(start 88.571578 -340.813898)
		(end 87.953342 -340.195662)
		(width 0.2286)
		(layer "B.Cu")
		(net "PVCCIN_CPU1_VDD6")
	)
	(segment
		(start 87.242396 -340.195662)
		(end 86.941406 -339.894672)
		(width 0.2286)
		(layer "B.Cu")
		(net "PVCCIN_CPU1_VDD6")
	)
	(segment
		(start 85.083142 -338.671662)
		(end 85.177376 -338.671662)
		(width 0.2286)
		(layer "B.Cu")
		(net "PVCCIN_CPU1_VDD6")
	)
	(segment
		(start 86.941406 -339.894672)
		(end 85.9282 -338.881466)
		(width 0.2286)
		(layer "B.Cu")
		(net "PVCCIN_CPU1_VDD6")
	)
	(segment
		(start 87.953342 -340.195662)
		(end 87.242396 -340.195662)
		(width 0.2286)
		(layer "B.Cu")
		(net "PVCCIN_CPU1_VDD6")
	)
	(segment
		(start 85.9282 -338.881466)
		(end 85.9282 -338.537296)
		(width 0.2286)
		(layer "B.Cu")
		(net "PVCCIN_CPU1_VDD6")
	)
	(segment
		(start 85.177376 -338.671662)
		(end 85.311742 -338.537296)
		(width 0.2286)
		(layer "B.Cu")
		(net "PVCCIN_CPU1_VDD6")
	)
	(segment
		(start 85.311742 -338.537296)
		(end 85.9282 -338.537296)
		(width 0.2286)
		(layer "B.Cu")
		(net "PVCCIN_CPU1_VDD6")
	)
	(segment
		(start 126.851664 -338.501228)
		(end 127.239776 -338.501228)
		(width 0.2032)
		(layer "F.Cu")
		(net "PVCCIN_CPU1_VDD5")
	)
	(segment
		(start 126.065026 -339.202522)
		(end 126.15037 -339.202522)
		(width 0.2032)
		(layer "F.Cu")
		(net "PVCCIN_CPU1_VDD5")
	)
	(segment
		(start 129.374138 -340.813898)
		(end 129.44983 -340.738206)
		(width 0.2286)
		(layer "F.Cu")
		(net "PVCCIN_CPU1_VDD5")
	)
	(segment
		(start 126.15037 -339.202522)
		(end 126.851664 -338.501228)
		(width 0.2032)
		(layer "F.Cu")
		(net "PVCCIN_CPU1_VDD5")
	)
	(segment
		(start 126.065026 -338.592922)
		(end 126.065026 -339.202522)
		(width 0.2032)
		(layer "F.Cu")
		(net "PVCCIN_CPU1_VDD5")
	)
	(segment
		(start 129.44983 -340.738206)
		(end 129.44983 -340.026244)
		(width 0.2286)
		(layer "F.Cu")
		(net "PVCCIN_CPU1_VDD5")
	)
	(via
		(at 129.374138 -340.813898)
		(size 0.508)
		(drill 0.254)
		(layers "F.Cu" "B.Cu")
		(net "PVCCIN_CPU1_VDD5")
	)
	(via
		(at 127.817372 -339.800692)
		(size 0.6604)
		(drill 0.3302)
		(layers "F.Cu" "B.Cu")
		(net "PVCCIN_CPU1_VDD5")
	)
	(via
		(at 126.065026 -338.592922)
		(size 0.508)
		(drill 0.254)
		(layers "F.Cu" "B.Cu")
		(net "PVCCIN_CPU1_VDD5")
	)
	(segment
		(start 129.374138 -340.813898)
		(end 128.755902 -340.195662)
		(width 0.2286)
		(layer "B.Cu")
		(net "PVCCIN_CPU1_VDD5")
	)
	(segment
		(start 128.212342 -340.195662)
		(end 127.817372 -339.800692)
		(width 0.2286)
		(layer "B.Cu")
		(net "PVCCIN_CPU1_VDD5")
	)
	(segment
		(start 127.817372 -339.800692)
		(end 127.257302 -339.240622)
		(width 0.2286)
		(layer "B.Cu")
		(net "PVCCIN_CPU1_VDD5")
	)
	(segment
		(start 128.755902 -340.195662)
		(end 128.212342 -340.195662)
		(width 0.2286)
		(layer "B.Cu")
		(net "PVCCIN_CPU1_VDD5")
	)
	(segment
		(start 126.065026 -338.592922)
		(end 126.159006 -338.498942)
		(width 0.2286)
		(layer "B.Cu")
		(net "PVCCIN_CPU1_VDD5")
	)
	(segment
		(start 127.257302 -339.240622)
		(end 127.257302 -338.498942)
		(width 0.2286)
		(layer "B.Cu")
		(net "PVCCIN_CPU1_VDD5")
	)
	(segment
		(start 126.159006 -338.498942)
		(end 127.257302 -338.498942)
		(width 0.2286)
		(layer "B.Cu")
		(net "PVCCIN_CPU1_VDD5")
	)
	(segment
		(start 118.691152 -335.091024)
		(end 119.079264 -335.091024)
		(width 0.2032)
		(layer "F.Cu")
		(net "PVCCIN_CPU1_VDD4")
	)
	(segment
		(start 121.289318 -337.328002)
		(end 121.289318 -336.61604)
		(width 0.2286)
		(layer "F.Cu")
		(net "PVCCIN_CPU1_VDD4")
	)
	(segment
		(start 121.213626 -337.403694)
		(end 121.289318 -337.328002)
		(width 0.2286)
		(layer "F.Cu")
		(net "PVCCIN_CPU1_VDD4")
	)
	(segment
		(start 117.989858 -335.792318)
		(end 118.691152 -335.091024)
		(width 0.2032)
		(layer "F.Cu")
		(net "PVCCIN_CPU1_VDD4")
	)
	(segment
		(start 117.904514 -335.792318)
		(end 117.989858 -335.792318)
		(width 0.2032)
		(layer "F.Cu")
		(net "PVCCIN_CPU1_VDD4")
	)
	(segment
		(start 117.904514 -335.176368)
		(end 117.904514 -335.792318)
		(width 0.2032)
		(layer "F.Cu")
		(net "PVCCIN_CPU1_VDD4")
	)
	(via
		(at 117.904514 -335.176368)
		(size 0.508)
		(drill 0.254)
		(layers "F.Cu" "B.Cu")
		(net "PVCCIN_CPU1_VDD4")
	)
	(via
		(at 121.213626 -337.403694)
		(size 0.508)
		(drill 0.254)
		(layers "F.Cu" "B.Cu")
		(net "PVCCIN_CPU1_VDD4")
	)
	(via
		(at 119.77243 -336.55635)
		(size 0.6604)
		(drill 0.3302)
		(layers "F.Cu" "B.Cu")
		(net "PVCCIN_CPU1_VDD4")
	)
	(segment
		(start 117.904514 -335.176368)
		(end 117.987318 -335.093564)
		(width 0.2286)
		(layer "B.Cu")
		(net "PVCCIN_CPU1_VDD4")
	)
	(segment
		(start 120.744234 -336.934302)
		(end 120.150382 -336.934302)
		(width 0.2286)
		(layer "B.Cu")
		(net "PVCCIN_CPU1_VDD4")
	)
	(segment
		(start 119.07266 -335.85658)
		(end 119.07266 -335.093564)
		(width 0.2286)
		(layer "B.Cu")
		(net "PVCCIN_CPU1_VDD4")
	)
	(segment
		(start 120.150382 -336.934302)
		(end 119.77243 -336.55635)
		(width 0.2286)
		(layer "B.Cu")
		(net "PVCCIN_CPU1_VDD4")
	)
	(segment
		(start 119.77243 -336.55635)
		(end 119.07266 -335.85658)
		(width 0.2286)
		(layer "B.Cu")
		(net "PVCCIN_CPU1_VDD4")
	)
	(segment
		(start 121.213626 -337.403694)
		(end 120.744234 -336.934302)
		(width 0.2286)
		(layer "B.Cu")
		(net "PVCCIN_CPU1_VDD4")
	)
	(segment
		(start 117.987318 -335.093564)
		(end 119.07266 -335.093564)
		(width 0.2286)
		(layer "B.Cu")
		(net "PVCCIN_CPU1_VDD4")
	)
	(segment
		(start 109.744002 -335.176368)
		(end 109.744002 -335.792318)
		(width 0.2032)
		(layer "F.Cu")
		(net "PVCCIN_CPU1_VDD3")
	)
	(segment
		(start 109.744002 -335.792318)
		(end 109.829346 -335.792318)
		(width 0.2032)
		(layer "F.Cu")
		(net "PVCCIN_CPU1_VDD3")
	)
	(segment
		(start 113.053114 -337.403694)
		(end 113.128806 -337.328002)
		(width 0.2286)
		(layer "F.Cu")
		(net "PVCCIN_CPU1_VDD3")
	)
	(segment
		(start 109.829346 -335.792318)
		(end 110.53064 -335.091024)
		(width 0.2032)
		(layer "F.Cu")
		(net "PVCCIN_CPU1_VDD3")
	)
	(segment
		(start 110.53064 -335.091024)
		(end 110.918752 -335.091024)
		(width 0.2032)
		(layer "F.Cu")
		(net "PVCCIN_CPU1_VDD3")
	)
	(segment
		(start 113.128806 -337.328002)
		(end 113.128806 -336.61604)
		(width 0.2286)
		(layer "F.Cu")
		(net "PVCCIN_CPU1_VDD3")
	)
	(via
		(at 111.532416 -336.49539)
		(size 0.6604)
		(drill 0.3302)
		(layers "F.Cu" "B.Cu")
		(net "PVCCIN_CPU1_VDD3")
	)
	(via
		(at 109.744002 -335.176368)
		(size 0.508)
		(drill 0.254)
		(layers "F.Cu" "B.Cu")
		(net "PVCCIN_CPU1_VDD3")
	)
	(via
		(at 113.053114 -337.403694)
		(size 0.508)
		(drill 0.254)
		(layers "F.Cu" "B.Cu")
		(net "PVCCIN_CPU1_VDD3")
	)
	(segment
		(start 109.744002 -335.176368)
		(end 109.817154 -335.103216)
		(width 0.2286)
		(layer "B.Cu")
		(net "PVCCIN_CPU1_VDD3")
	)
	(segment
		(start 111.532416 -336.49539)
		(end 110.922054 -335.885028)
		(width 0.2286)
		(layer "B.Cu")
		(net "PVCCIN_CPU1_VDD3")
	)
	(segment
		(start 110.922054 -335.885028)
		(end 110.922054 -335.103216)
		(width 0.2286)
		(layer "B.Cu")
		(net "PVCCIN_CPU1_VDD3")
	)
	(segment
		(start 109.817154 -335.103216)
		(end 110.922054 -335.103216)
		(width 0.2286)
		(layer "B.Cu")
		(net "PVCCIN_CPU1_VDD3")
	)
	(segment
		(start 113.053114 -337.403694)
		(end 112.434878 -336.785458)
		(width 0.2286)
		(layer "B.Cu")
		(net "PVCCIN_CPU1_VDD3")
	)
	(segment
		(start 112.434878 -336.785458)
		(end 111.822484 -336.785458)
		(width 0.2286)
		(layer "B.Cu")
		(net "PVCCIN_CPU1_VDD3")
	)
	(segment
		(start 111.822484 -336.785458)
		(end 111.532416 -336.49539)
		(width 0.2286)
		(layer "B.Cu")
		(net "PVCCIN_CPU1_VDD3")
	)
	(segment
		(start 102.370128 -335.091024)
		(end 101.668834 -335.792318)
		(width 0.2032)
		(layer "F.Cu")
		(net "PVCCIN_CPU1_VDD2")
	)
	(segment
		(start 101.668834 -335.792318)
		(end 101.58349 -335.792318)
		(width 0.2032)
		(layer "F.Cu")
		(net "PVCCIN_CPU1_VDD2")
	)
	(segment
		(start 102.75824 -335.091024)
		(end 102.370128 -335.091024)
		(width 0.2032)
		(layer "F.Cu")
		(net "PVCCIN_CPU1_VDD2")
	)
	(segment
		(start 104.968294 -337.328002)
		(end 104.968294 -336.61604)
		(width 0.2286)
		(layer "F.Cu")
		(net "PVCCIN_CPU1_VDD2")
	)
	(segment
		(start 101.58349 -335.176368)
		(end 101.58349 -335.792318)
		(width 0.2032)
		(layer "F.Cu")
		(net "PVCCIN_CPU1_VDD2")
	)
	(segment
		(start 104.892602 -337.403694)
		(end 104.968294 -337.328002)
		(width 0.2286)
		(layer "F.Cu")
		(net "PVCCIN_CPU1_VDD2")
	)
	(via
		(at 101.58349 -335.176368)
		(size 0.508)
		(drill 0.254)
		(layers "F.Cu" "B.Cu")
		(net "PVCCIN_CPU1_VDD2")
	)
	(via
		(at 103.718106 -336.785458)
		(size 0.6604)
		(drill 0.3302)
		(layers "F.Cu" "B.Cu")
		(net "PVCCIN_CPU1_VDD2")
	)
	(via
		(at 104.892602 -337.403694)
		(size 0.508)
		(drill 0.254)
		(layers "F.Cu" "B.Cu")
		(net "PVCCIN_CPU1_VDD2")
	)
	(segment
		(start 101.58349 -335.176368)
		(end 101.652324 -335.245202)
		(width 0.2286)
		(layer "B.Cu")
		(net "PVCCIN_CPU1_VDD2")
	)
	(segment
		(start 103.718106 -336.785458)
		(end 103.644192 -336.785458)
		(width 0.2286)
		(layer "B.Cu")
		(net "PVCCIN_CPU1_VDD2")
	)
	(segment
		(start 103.644192 -336.785458)
		(end 102.909624 -336.05089)
		(width 0.2286)
		(layer "B.Cu")
		(net "PVCCIN_CPU1_VDD2")
	)
	(segment
		(start 104.892602 -337.403694)
		(end 104.274366 -336.785458)
		(width 0.2286)
		(layer "B.Cu")
		(net "PVCCIN_CPU1_VDD2")
	)
	(segment
		(start 104.274366 -336.785458)
		(end 103.718106 -336.785458)
		(width 0.2286)
		(layer "B.Cu")
		(net "PVCCIN_CPU1_VDD2")
	)
	(segment
		(start 102.909624 -336.05089)
		(end 102.909624 -335.245202)
		(width 0.2286)
		(layer "B.Cu")
		(net "PVCCIN_CPU1_VDD2")
	)
	(segment
		(start 101.652324 -335.245202)
		(end 102.909624 -335.245202)
		(width 0.2286)
		(layer "B.Cu")
		(net "PVCCIN_CPU1_VDD2")
	)
	(segment
		(start 94.597728 -335.091024)
		(end 94.19336 -335.091024)
		(width 0.2032)
		(layer "F.Cu")
		(net "PVCCIN_CPU1_VDD1")
	)
	(segment
		(start 93.492066 -335.792318)
		(end 93.422978 -335.792318)
		(width 0.2032)
		(layer "F.Cu")
		(net "PVCCIN_CPU1_VDD1")
	)
	(segment
		(start 96.807782 -337.328002)
		(end 96.807782 -336.61604)
		(width 0.2286)
		(layer "F.Cu")
		(net "PVCCIN_CPU1_VDD1")
	)
	(segment
		(start 96.73209 -337.403694)
		(end 96.807782 -337.328002)
		(width 0.2286)
		(layer "F.Cu")
		(net "PVCCIN_CPU1_VDD1")
	)
	(segment
		(start 94.19336 -335.091024)
		(end 93.492066 -335.792318)
		(width 0.2032)
		(layer "F.Cu")
		(net "PVCCIN_CPU1_VDD1")
	)
	(segment
		(start 93.422978 -335.176368)
		(end 93.422978 -335.792318)
		(width 0.2032)
		(layer "F.Cu")
		(net "PVCCIN_CPU1_VDD1")
	)
	(via
		(at 95.25762 -336.603594)
		(size 0.6604)
		(drill 0.3302)
		(layers "F.Cu" "B.Cu")
		(net "PVCCIN_CPU1_VDD1")
	)
	(via
		(at 93.422978 -335.176368)
		(size 0.508)
		(drill 0.254)
		(layers "F.Cu" "B.Cu")
		(net "PVCCIN_CPU1_VDD1")
	)
	(via
		(at 96.73209 -337.403694)
		(size 0.508)
		(drill 0.254)
		(layers "F.Cu" "B.Cu")
		(net "PVCCIN_CPU1_VDD1")
	)
	(segment
		(start 93.422978 -335.176368)
		(end 93.446854 -335.152492)
		(width 0.2286)
		(layer "B.Cu")
		(net "PVCCIN_CPU1_VDD1")
	)
	(segment
		(start 95.25762 -336.603594)
		(end 94.698058 -336.044032)
		(width 0.2286)
		(layer "B.Cu")
		(net "PVCCIN_CPU1_VDD1")
	)
	(segment
		(start 95.611188 -336.957162)
		(end 95.25762 -336.603594)
		(width 0.2286)
		(layer "B.Cu")
		(net "PVCCIN_CPU1_VDD1")
	)
	(segment
		(start 94.698058 -336.044032)
		(end 94.698058 -335.253838)
		(width 0.2286)
		(layer "B.Cu")
		(net "PVCCIN_CPU1_VDD1")
	)
	(segment
		(start 93.446854 -335.152492)
		(end 94.596712 -335.152492)
		(width 0.2286)
		(layer "B.Cu")
		(net "PVCCIN_CPU1_VDD1")
	)
	(segment
		(start 94.698058 -335.253838)
		(end 94.596712 -335.152492)
		(width 0.2286)
		(layer "B.Cu")
		(net "PVCCIN_CPU1_VDD1")
	)
	(segment
		(start 96.285558 -336.957162)
		(end 95.611188 -336.957162)
		(width 0.2286)
		(layer "B.Cu")
		(net "PVCCIN_CPU1_VDD1")
	)
	(segment
		(start 96.73209 -337.403694)
		(end 96.285558 -336.957162)
		(width 0.2286)
		(layer "B.Cu")
		(net "PVCCIN_CPU1_VDD1")
	)
	(segment
		(start 114.306604 -362.618528)
		(end 114.306604 -361.72775)
		(width 0.1778)
		(layer "F.Cu")
		(net "PVCCIN_CPU1_VCC")
	)
	(segment
		(start 111.453422 -360.648504)
		(end 111.80826 -360.648504)
		(width 0.1778)
		(layer "F.Cu")
		(net "PVCCIN_CPU1_VCC")
	)
	(segment
		(start 112.00257 -361.822238)
		(end 113.104676 -362.924344)
		(width 0.1778)
		(layer "F.Cu")
		(net "PVCCIN_CPU1_VCC")
	)
	(segment
		(start 113.104676 -362.924344)
		(end 113.104676 -363.32541)
		(width 0.1778)
		(layer "F.Cu")
		(net "PVCCIN_CPU1_VCC")
	)
	(segment
		(start 114.306604 -363.505242)
		(end 114.30381 -363.508036)
		(width 0.1778)
		(layer "F.Cu")
		(net "PVCCIN_CPU1_VCC")
	)
	(segment
		(start 113.287302 -363.508036)
		(end 113.104676 -363.32541)
		(width 0.1778)
		(layer "F.Cu")
		(net "PVCCIN_CPU1_VCC")
	)
	(segment
		(start 112.00257 -360.842814)
		(end 112.00257 -361.822238)
		(width 0.1778)
		(layer "F.Cu")
		(net "PVCCIN_CPU1_VCC")
	)
	(segment
		(start 114.30381 -363.508036)
		(end 113.287302 -363.508036)
		(width 0.1778)
		(layer "F.Cu")
		(net "PVCCIN_CPU1_VCC")
	)
	(segment
		(start 114.306604 -362.618528)
		(end 114.306604 -363.505242)
		(width 0.1778)
		(layer "F.Cu")
		(net "PVCCIN_CPU1_VCC")
	)
	(segment
		(start 111.80826 -360.648504)
		(end 112.00257 -360.842814)
		(width 0.1778)
		(layer "F.Cu")
		(net "PVCCIN_CPU1_VCC")
	)
	(via
		(at 113.104676 -363.32541)
		(size 0.762)
		(drill 0.254)
		(layers "F.Cu" "B.Cu")
		(net "PVCCIN_CPU1_VCC")
	)
	(segment
		(start 113.104676 -363.32541)
		(end 113.104676 -362.983526)
		(width 0.4572)
		(layer "B.Cu")
		(net "PVCCIN_CPU1_VCC")
	)
	(segment
		(start 113.104676 -362.983526)
		(end 113.38433 -362.703872)
		(width 0.4572)
		(layer "B.Cu")
		(net "PVCCIN_CPU1_VCC")
	)
	(segment
		(start 138.06043 -346.8624)
		(end 138.06043 -345.816936)
		(width 0.1778)
		(layer "F.Cu")
		(net "PVCCIN_CPU1_PWM8")
	)
	(segment
		(start 137.908538 -347.228922)
		(end 138.06043 -346.8624)
		(width 0.1778)
		(layer "F.Cu")
		(net "PVCCIN_CPU1_PWM8")
	)
	(segment
		(start 109.178344 -363.374686)
		(end 109.178344 -361.723432)
		(width 0.1778)
		(layer "F.Cu")
		(net "PVCCIN_CPU1_PWM8")
	)
	(segment
		(start 110.209838 -364.40618)
		(end 109.178344 -363.374686)
		(width 0.1778)
		(layer "F.Cu")
		(net "PVCCIN_CPU1_PWM8")
	)
	(via
		(at 137.908538 -347.228922)
		(size 0.508)
		(drill 0.254)
		(layers "F.Cu" "B.Cu")
		(net "PVCCIN_CPU1_PWM8")
	)
	(via
		(at 110.209838 -364.40618)
		(size 0.762)
		(drill 0.254)
		(layers "F.Cu" "B.Cu")
		(net "PVCCIN_CPU1_PWM8")
	)
	(segment
		(start 115.22964 -361.066588)
		(end 113.864898 -362.43133)
		(width 0.2032)
		(layer "In2.Cu")
		(net "PVCCIN_CPU1_PWM8")
	)
	(segment
		(start 123.418854 -349.663512)
		(end 120.616218 -352.466148)
		(width 0.2032)
		(layer "In2.Cu")
		(net "PVCCIN_CPU1_PWM8")
	)
	(segment
		(start 111.71682 -363.362748)
		(end 111.353346 -363.362748)
		(width 0.2032)
		(layer "In2.Cu")
		(net "PVCCIN_CPU1_PWM8")
	)
	(segment
		(start 120.616218 -352.466148)
		(end 116.763546 -352.466148)
		(width 0.2032)
		(layer "In2.Cu")
		(net "PVCCIN_CPU1_PWM8")
	)
	(segment
		(start 115.22964 -357.708962)
		(end 115.22964 -361.066588)
		(width 0.2032)
		(layer "In2.Cu")
		(net "PVCCIN_CPU1_PWM8")
	)
	(segment
		(start 115.50396 -357.434642)
		(end 115.22964 -357.708962)
		(width 0.2032)
		(layer "In2.Cu")
		(net "PVCCIN_CPU1_PWM8")
	)
	(segment
		(start 112.648238 -362.43133)
		(end 111.71682 -363.362748)
		(width 0.2032)
		(layer "In2.Cu")
		(net "PVCCIN_CPU1_PWM8")
	)
	(segment
		(start 135.088122 -349.663512)
		(end 123.418854 -349.663512)
		(width 0.2032)
		(layer "In2.Cu")
		(net "PVCCIN_CPU1_PWM8")
	)
	(segment
		(start 137.908538 -347.228922)
		(end 137.522712 -347.228922)
		(width 0.2032)
		(layer "In2.Cu")
		(net "PVCCIN_CPU1_PWM8")
	)
	(segment
		(start 116.763546 -352.466148)
		(end 115.50396 -353.725734)
		(width 0.2032)
		(layer "In2.Cu")
		(net "PVCCIN_CPU1_PWM8")
	)
	(segment
		(start 113.864898 -362.43133)
		(end 112.648238 -362.43133)
		(width 0.2032)
		(layer "In2.Cu")
		(net "PVCCIN_CPU1_PWM8")
	)
	(segment
		(start 110.309914 -364.40618)
		(end 110.209838 -364.40618)
		(width 0.2032)
		(layer "In2.Cu")
		(net "PVCCIN_CPU1_PWM8")
	)
	(segment
		(start 111.353346 -363.362748)
		(end 110.309914 -364.40618)
		(width 0.2032)
		(layer "In2.Cu")
		(net "PVCCIN_CPU1_PWM8")
	)
	(segment
		(start 137.522712 -347.228922)
		(end 135.088122 -349.663512)
		(width 0.2032)
		(layer "In2.Cu")
		(net "PVCCIN_CPU1_PWM8")
	)
	(segment
		(start 115.50396 -353.725734)
		(end 115.50396 -357.434642)
		(width 0.2032)
		(layer "In2.Cu")
		(net "PVCCIN_CPU1_PWM8")
	)
	(segment
		(start 80.936846 -346.8624)
		(end 80.784954 -347.228922)
		(width 0.1778)
		(layer "F.Cu")
		(net "PVCCIN_CPU1_PWM7")
	)
	(segment
		(start 108.97616 -364.877858)
		(end 108.97616 -363.885734)
		(width 0.1778)
		(layer "F.Cu")
		(net "PVCCIN_CPU1_PWM7")
	)
	(segment
		(start 110.224316 -365.513366)
		(end 109.611668 -365.513366)
		(width 0.1778)
		(layer "F.Cu")
		(net "PVCCIN_CPU1_PWM7")
	)
	(segment
		(start 109.611668 -365.513366)
		(end 109.293914 -365.195612)
		(width 0.1778)
		(layer "F.Cu")
		(net "PVCCIN_CPU1_PWM7")
	)
	(segment
		(start 109.293914 -365.195612)
		(end 108.97616 -364.877858)
		(width 0.1778)
		(layer "F.Cu")
		(net "PVCCIN_CPU1_PWM7")
	)
	(segment
		(start 80.936846 -345.816936)
		(end 80.936846 -346.8624)
		(width 0.1778)
		(layer "F.Cu")
		(net "PVCCIN_CPU1_PWM7")
	)
	(segment
		(start 108.778294 -363.687868)
		(end 108.778294 -361.723432)
		(width 0.1778)
		(layer "F.Cu")
		(net "PVCCIN_CPU1_PWM7")
	)
	(segment
		(start 108.97616 -363.885734)
		(end 108.778294 -363.687868)
		(width 0.1778)
		(layer "F.Cu")
		(net "PVCCIN_CPU1_PWM7")
	)
	(via
		(at 109.293914 -365.195612)
		(size 0.762)
		(drill 0.381)
		(layers "F.Cu" "B.Cu")
		(net "PVCCIN_CPU1_PWM7")
	)
	(via
		(at 110.224316 -365.513366)
		(size 0.508)
		(drill 0.254)
		(layers "F.Cu" "B.Cu")
		(net "PVCCIN_CPU1_PWM7")
	)
	(via
		(at 80.784954 -347.228922)
		(size 0.508)
		(drill 0.254)
		(layers "F.Cu" "B.Cu")
		(net "PVCCIN_CPU1_PWM7")
	)
	(segment
		(start 81.199482 -347.64345)
		(end 80.784954 -347.228922)
		(width 0.2032)
		(layer "In2.Cu")
		(net "PVCCIN_CPU1_PWM7")
	)
	(segment
		(start 101.813868 -364.98657)
		(end 97.455736 -360.628438)
		(width 0.2032)
		(layer "In2.Cu")
		(net "PVCCIN_CPU1_PWM7")
	)
	(segment
		(start 105.452418 -367.86439)
		(end 102.574598 -364.98657)
		(width 0.2032)
		(layer "In2.Cu")
		(net "PVCCIN_CPU1_PWM7")
	)
	(segment
		(start 109.160818 -367.86439)
		(end 105.452418 -367.86439)
		(width 0.2032)
		(layer "In2.Cu")
		(net "PVCCIN_CPU1_PWM7")
	)
	(segment
		(start 110.224316 -366.800892)
		(end 109.160818 -367.86439)
		(width 0.2032)
		(layer "In2.Cu")
		(net "PVCCIN_CPU1_PWM7")
	)
	(segment
		(start 86.200488 -347.64345)
		(end 81.199482 -347.64345)
		(width 0.2032)
		(layer "In2.Cu")
		(net "PVCCIN_CPU1_PWM7")
	)
	(segment
		(start 97.455736 -360.628438)
		(end 97.455736 -355.137466)
		(width 0.2032)
		(layer "In2.Cu")
		(net "PVCCIN_CPU1_PWM7")
	)
	(segment
		(start 98.666046 -348.78264)
		(end 97.158556 -347.27515)
		(width 0.2032)
		(layer "In2.Cu")
		(net "PVCCIN_CPU1_PWM7")
	)
	(segment
		(start 86.568788 -347.27515)
		(end 86.200488 -347.64345)
		(width 0.2032)
		(layer "In2.Cu")
		(net "PVCCIN_CPU1_PWM7")
	)
	(segment
		(start 110.224316 -365.513366)
		(end 110.224316 -366.800892)
		(width 0.2032)
		(layer "In2.Cu")
		(net "PVCCIN_CPU1_PWM7")
	)
	(segment
		(start 97.158556 -347.27515)
		(end 86.568788 -347.27515)
		(width 0.2032)
		(layer "In2.Cu")
		(net "PVCCIN_CPU1_PWM7")
	)
	(segment
		(start 98.666046 -353.927156)
		(end 98.666046 -348.78264)
		(width 0.2032)
		(layer "In2.Cu")
		(net "PVCCIN_CPU1_PWM7")
	)
	(segment
		(start 102.574598 -364.98657)
		(end 101.813868 -364.98657)
		(width 0.2032)
		(layer "In2.Cu")
		(net "PVCCIN_CPU1_PWM7")
	)
	(segment
		(start 97.455736 -355.137466)
		(end 98.666046 -353.927156)
		(width 0.2032)
		(layer "In2.Cu")
		(net "PVCCIN_CPU1_PWM7")
	)
	(segment
		(start 89.097358 -341.071708)
		(end 89.097358 -340.026244)
		(width 0.1778)
		(layer "F.Cu")
		(net "PVCCIN_CPU1_PWM6")
	)
	(segment
		(start 108.55706 -363.985302)
		(end 108.378498 -363.80674)
		(width 0.1778)
		(layer "F.Cu")
		(net "PVCCIN_CPU1_PWM6")
	)
	(segment
		(start 108.55706 -364.630462)
		(end 108.55706 -363.985302)
		(width 0.1778)
		(layer "F.Cu")
		(net "PVCCIN_CPU1_PWM6")
	)
	(segment
		(start 88.945466 -341.43823)
		(end 89.097358 -341.071708)
		(width 0.1778)
		(layer "F.Cu")
		(net "PVCCIN_CPU1_PWM6")
	)
	(segment
		(start 108.378498 -363.80674)
		(end 108.378498 -361.723432)
		(width 0.1778)
		(layer "F.Cu")
		(net "PVCCIN_CPU1_PWM6")
	)
	(segment
		(start 107.367832 -365.14024)
		(end 108.047282 -365.14024)
		(width 0.1778)
		(layer "F.Cu")
		(net "PVCCIN_CPU1_PWM6")
	)
	(segment
		(start 108.047282 -365.14024)
		(end 108.55706 -364.630462)
		(width 0.1778)
		(layer "F.Cu")
		(net "PVCCIN_CPU1_PWM6")
	)
	(via
		(at 88.945466 -341.43823)
		(size 0.508)
		(drill 0.254)
		(layers "F.Cu" "B.Cu")
		(net "PVCCIN_CPU1_PWM6")
	)
	(via
		(at 107.367832 -365.14024)
		(size 0.762)
		(drill 0.254)
		(layers "F.Cu" "B.Cu")
		(net "PVCCIN_CPU1_PWM6")
	)
	(segment
		(start 90.625168 -343.117932)
		(end 88.945466 -341.43823)
		(width 0.2032)
		(layer "In2.Cu")
		(net "PVCCIN_CPU1_PWM6")
	)
	(segment
		(start 107.367832 -365.14024)
		(end 107.201462 -365.30661)
		(width 0.2032)
		(layer "In2.Cu")
		(net "PVCCIN_CPU1_PWM6")
	)
	(segment
		(start 100.21189 -362.307378)
		(end 100.21189 -361.674918)
		(width 0.2032)
		(layer "In2.Cu")
		(net "PVCCIN_CPU1_PWM6")
	)
	(segment
		(start 98.23958 -360.279188)
		(end 98.23958 -355.39553)
		(width 0.2032)
		(layer "In2.Cu")
		(net "PVCCIN_CPU1_PWM6")
	)
	(segment
		(start 102.151942 -364.24743)
		(end 100.21189 -362.307378)
		(width 0.2032)
		(layer "In2.Cu")
		(net "PVCCIN_CPU1_PWM6")
	)
	(segment
		(start 99.377246 -354.257864)
		(end 99.377246 -348.487746)
		(width 0.2032)
		(layer "In2.Cu")
		(net "PVCCIN_CPU1_PWM6")
	)
	(segment
		(start 99.377246 -348.487746)
		(end 94.007432 -343.117932)
		(width 0.2032)
		(layer "In2.Cu")
		(net "PVCCIN_CPU1_PWM6")
	)
	(segment
		(start 98.23958 -355.39553)
		(end 99.377246 -354.257864)
		(width 0.2032)
		(layer "In2.Cu")
		(net "PVCCIN_CPU1_PWM6")
	)
	(segment
		(start 104.164384 -365.30661)
		(end 103.105204 -364.24743)
		(width 0.2032)
		(layer "In2.Cu")
		(net "PVCCIN_CPU1_PWM6")
	)
	(segment
		(start 107.201462 -365.30661)
		(end 104.164384 -365.30661)
		(width 0.2032)
		(layer "In2.Cu")
		(net "PVCCIN_CPU1_PWM6")
	)
	(segment
		(start 99.83216 -361.295188)
		(end 99.25558 -361.295188)
		(width 0.2032)
		(layer "In2.Cu")
		(net "PVCCIN_CPU1_PWM6")
	)
	(segment
		(start 103.105204 -364.24743)
		(end 102.151942 -364.24743)
		(width 0.2032)
		(layer "In2.Cu")
		(net "PVCCIN_CPU1_PWM6")
	)
	(segment
		(start 100.21189 -361.674918)
		(end 99.83216 -361.295188)
		(width 0.2032)
		(layer "In2.Cu")
		(net "PVCCIN_CPU1_PWM6")
	)
	(segment
		(start 99.25558 -361.295188)
		(end 98.23958 -360.279188)
		(width 0.2032)
		(layer "In2.Cu")
		(net "PVCCIN_CPU1_PWM6")
	)
	(segment
		(start 94.007432 -343.117932)
		(end 90.625168 -343.117932)
		(width 0.2032)
		(layer "In2.Cu")
		(net "PVCCIN_CPU1_PWM6")
	)
	(segment
		(start 129.748026 -341.43823)
		(end 129.899918 -341.071708)
		(width 0.1778)
		(layer "F.Cu")
		(net "PVCCIN_CPU1_PWM5")
	)
	(segment
		(start 107.95762 -364.310168)
		(end 107.978448 -364.28934)
		(width 0.1778)
		(layer "F.Cu")
		(net "PVCCIN_CPU1_PWM5")
	)
	(segment
		(start 129.899918 -341.071708)
		(end 129.899918 -340.026244)
		(width 0.1778)
		(layer "F.Cu")
		(net "PVCCIN_CPU1_PWM5")
	)
	(segment
		(start 107.978448 -364.28934)
		(end 107.978448 -361.723432)
		(width 0.1778)
		(layer "F.Cu")
		(net "PVCCIN_CPU1_PWM5")
	)
	(via
		(at 129.748026 -341.43823)
		(size 0.508)
		(drill 0.254)
		(layers "F.Cu" "B.Cu")
		(net "PVCCIN_CPU1_PWM5")
	)
	(via
		(at 107.95762 -364.310168)
		(size 0.508)
		(drill 0.254)
		(layers "F.Cu" "B.Cu")
		(net "PVCCIN_CPU1_PWM5")
	)
	(segment
		(start 127.151892 -343.73185)
		(end 130.067558 -343.73185)
		(width 0.2032)
		(layer "In2.Cu")
		(net "PVCCIN_CPU1_PWM5")
	)
	(segment
		(start 114.6937 -349.836994)
		(end 117.111018 -347.419676)
		(width 0.2032)
		(layer "In2.Cu")
		(net "PVCCIN_CPU1_PWM5")
	)
	(segment
		(start 114.6937 -355.224842)
		(end 114.6937 -349.836994)
		(width 0.2032)
		(layer "In2.Cu")
		(net "PVCCIN_CPU1_PWM5")
	)
	(segment
		(start 130.639058 -343.16035)
		(end 130.639058 -342.329262)
		(width 0.2032)
		(layer "In2.Cu")
		(net "PVCCIN_CPU1_PWM5")
	)
	(segment
		(start 130.067558 -343.73185)
		(end 130.639058 -343.16035)
		(width 0.2032)
		(layer "In2.Cu")
		(net "PVCCIN_CPU1_PWM5")
	)
	(segment
		(start 111.450374 -360.817414)
		(end 111.450374 -357.462074)
		(width 0.2032)
		(layer "In2.Cu")
		(net "PVCCIN_CPU1_PWM5")
	)
	(segment
		(start 111.450374 -357.462074)
		(end 113.2078 -355.704648)
		(width 0.2032)
		(layer "In2.Cu")
		(net "PVCCIN_CPU1_PWM5")
	)
	(segment
		(start 130.639058 -342.329262)
		(end 129.748026 -341.43823)
		(width 0.2032)
		(layer "In2.Cu")
		(net "PVCCIN_CPU1_PWM5")
	)
	(segment
		(start 123.464066 -347.419676)
		(end 127.151892 -343.73185)
		(width 0.2032)
		(layer "In2.Cu")
		(net "PVCCIN_CPU1_PWM5")
	)
	(segment
		(start 107.95762 -364.310168)
		(end 111.450374 -360.817414)
		(width 0.2032)
		(layer "In2.Cu")
		(net "PVCCIN_CPU1_PWM5")
	)
	(segment
		(start 117.111018 -347.419676)
		(end 123.464066 -347.419676)
		(width 0.2032)
		(layer "In2.Cu")
		(net "PVCCIN_CPU1_PWM5")
	)
	(segment
		(start 114.213894 -355.704648)
		(end 114.6937 -355.224842)
		(width 0.2032)
		(layer "In2.Cu")
		(net "PVCCIN_CPU1_PWM5")
	)
	(segment
		(start 113.2078 -355.704648)
		(end 114.213894 -355.704648)
		(width 0.2032)
		(layer "In2.Cu")
		(net "PVCCIN_CPU1_PWM5")
	)
	(segment
		(start 121.739406 -337.661504)
		(end 121.739406 -336.61604)
		(width 0.1778)
		(layer "F.Cu")
		(net "PVCCIN_CPU1_PWM4")
	)
	(segment
		(start 106.502708 -364.4138)
		(end 107.578398 -363.33811)
		(width 0.1778)
		(layer "F.Cu")
		(net "PVCCIN_CPU1_PWM4")
	)
	(segment
		(start 107.578398 -363.33811)
		(end 107.578398 -361.723432)
		(width 0.1778)
		(layer "F.Cu")
		(net "PVCCIN_CPU1_PWM4")
	)
	(segment
		(start 121.587514 -338.028026)
		(end 121.739406 -337.661504)
		(width 0.1778)
		(layer "F.Cu")
		(net "PVCCIN_CPU1_PWM4")
	)
	(via
		(at 106.502708 -364.4138)
		(size 0.508)
		(drill 0.254)
		(layers "F.Cu" "B.Cu")
		(net "PVCCIN_CPU1_PWM4")
	)
	(via
		(at 121.587514 -338.028026)
		(size 0.508)
		(drill 0.254)
		(layers "F.Cu" "B.Cu")
		(net "PVCCIN_CPU1_PWM4")
	)
	(segment
		(start 109.483652 -361.018836)
		(end 107.51566 -362.986828)
		(width 0.2032)
		(layer "In2.Cu")
		(net "PVCCIN_CPU1_PWM4")
	)
	(segment
		(start 117.67312 -344.594434)
		(end 111.960406 -350.307148)
		(width 0.2032)
		(layer "In2.Cu")
		(net "PVCCIN_CPU1_PWM4")
	)
	(segment
		(start 110.16742 -351.947734)
		(end 109.483652 -352.631502)
		(width 0.2032)
		(layer "In2.Cu")
		(net "PVCCIN_CPU1_PWM4")
	)
	(segment
		(start 110.8202 -350.307148)
		(end 110.16742 -350.959928)
		(width 0.2032)
		(layer "In2.Cu")
		(net "PVCCIN_CPU1_PWM4")
	)
	(segment
		(start 106.600752 -364.4138)
		(end 106.502708 -364.4138)
		(width 0.2032)
		(layer "In2.Cu")
		(net "PVCCIN_CPU1_PWM4")
	)
	(segment
		(start 117.67312 -342.499442)
		(end 117.67312 -344.594434)
		(width 0.2032)
		(layer "In2.Cu")
		(net "PVCCIN_CPU1_PWM4")
	)
	(segment
		(start 111.960406 -350.307148)
		(end 110.8202 -350.307148)
		(width 0.2032)
		(layer "In2.Cu")
		(net "PVCCIN_CPU1_PWM4")
	)
	(segment
		(start 109.483652 -352.631502)
		(end 109.483652 -361.018836)
		(width 0.2032)
		(layer "In2.Cu")
		(net "PVCCIN_CPU1_PWM4")
	)
	(segment
		(start 121.587514 -338.028026)
		(end 122.345958 -338.78647)
		(width 0.2032)
		(layer "In2.Cu")
		(net "PVCCIN_CPU1_PWM4")
	)
	(segment
		(start 121.630948 -340.37524)
		(end 119.797322 -340.37524)
		(width 0.2032)
		(layer "In2.Cu")
		(net "PVCCIN_CPU1_PWM4")
	)
	(segment
		(start 107.51566 -363.498892)
		(end 106.600752 -364.4138)
		(width 0.2032)
		(layer "In2.Cu")
		(net "PVCCIN_CPU1_PWM4")
	)
	(segment
		(start 122.345958 -339.66023)
		(end 121.630948 -340.37524)
		(width 0.2032)
		(layer "In2.Cu")
		(net "PVCCIN_CPU1_PWM4")
	)
	(segment
		(start 119.797322 -340.37524)
		(end 117.67312 -342.499442)
		(width 0.2032)
		(layer "In2.Cu")
		(net "PVCCIN_CPU1_PWM4")
	)
	(segment
		(start 107.51566 -362.986828)
		(end 107.51566 -363.498892)
		(width 0.2032)
		(layer "In2.Cu")
		(net "PVCCIN_CPU1_PWM4")
	)
	(segment
		(start 122.345958 -338.78647)
		(end 122.345958 -339.66023)
		(width 0.2032)
		(layer "In2.Cu")
		(net "PVCCIN_CPU1_PWM4")
	)
	(segment
		(start 110.16742 -350.959928)
		(end 110.16742 -351.947734)
		(width 0.2032)
		(layer "In2.Cu")
		(net "PVCCIN_CPU1_PWM4")
	)
	(segment
		(start 113.484152 -337.890358)
		(end 113.578894 -337.413854)
		(width 0.1778)
		(layer "F.Cu")
		(net "PVCCIN_CPU1_PWM3")
	)
	(segment
		(start 107.178348 -362.614718)
		(end 107.178348 -361.723432)
		(width 0.1778)
		(layer "F.Cu")
		(net "PVCCIN_CPU1_PWM3")
	)
	(segment
		(start 113.427002 -338.028026)
		(end 113.484152 -337.890358)
		(width 0.1778)
		(layer "F.Cu")
		(net "PVCCIN_CPU1_PWM3")
	)
	(segment
		(start 113.578894 -337.413854)
		(end 113.578894 -336.61604)
		(width 0.1778)
		(layer "F.Cu")
		(net "PVCCIN_CPU1_PWM3")
	)
	(segment
		(start 106.644694 -363.148372)
		(end 107.178348 -362.614718)
		(width 0.1778)
		(layer "F.Cu")
		(net "PVCCIN_CPU1_PWM3")
	)
	(via
		(at 106.644694 -363.148372)
		(size 0.508)
		(drill 0.254)
		(layers "F.Cu" "B.Cu")
		(net "PVCCIN_CPU1_PWM3")
	)
	(via
		(at 113.427002 -338.028026)
		(size 0.508)
		(drill 0.254)
		(layers "F.Cu" "B.Cu")
		(net "PVCCIN_CPU1_PWM3")
	)
	(segment
		(start 107.484926 -355.313234)
		(end 105.54208 -353.370388)
		(width 0.2032)
		(layer "In2.Cu")
		(net "PVCCIN_CPU1_PWM3")
	)
	(segment
		(start 107.484926 -361.963716)
		(end 107.484926 -355.313234)
		(width 0.2032)
		(layer "In2.Cu")
		(net "PVCCIN_CPU1_PWM3")
	)
	(segment
		(start 103.389938 -350.23171)
		(end 114.11712 -339.504528)
		(width 0.2032)
		(layer "In2.Cu")
		(net "PVCCIN_CPU1_PWM3")
	)
	(segment
		(start 105.54208 -353.370388)
		(end 104.59974 -353.370388)
		(width 0.2032)
		(layer "In2.Cu")
		(net "PVCCIN_CPU1_PWM3")
	)
	(segment
		(start 106.644694 -363.148372)
		(end 106.644694 -362.803948)
		(width 0.2032)
		(layer "In2.Cu")
		(net "PVCCIN_CPU1_PWM3")
	)
	(segment
		(start 114.11712 -338.718144)
		(end 113.427002 -338.028026)
		(width 0.2032)
		(layer "In2.Cu")
		(net "PVCCIN_CPU1_PWM3")
	)
	(segment
		(start 104.59974 -353.370388)
		(end 103.389938 -352.160586)
		(width 0.2032)
		(layer "In2.Cu")
		(net "PVCCIN_CPU1_PWM3")
	)
	(segment
		(start 103.389938 -352.160586)
		(end 103.389938 -350.23171)
		(width 0.2032)
		(layer "In2.Cu")
		(net "PVCCIN_CPU1_PWM3")
	)
	(segment
		(start 106.644694 -362.803948)
		(end 107.484926 -361.963716)
		(width 0.2032)
		(layer "In2.Cu")
		(net "PVCCIN_CPU1_PWM3")
	)
	(segment
		(start 114.11712 -339.504528)
		(end 114.11712 -338.718144)
		(width 0.2032)
		(layer "In2.Cu")
		(net "PVCCIN_CPU1_PWM3")
	)
	(segment
		(start 106.778298 -362.15447)
		(end 106.778298 -361.723432)
		(width 0.1778)
		(layer "F.Cu")
		(net "PVCCIN_CPU1_PWM2")
	)
	(segment
		(start 104.753664 -363.63783)
		(end 105.294938 -363.63783)
		(width 0.1778)
		(layer "F.Cu")
		(net "PVCCIN_CPU1_PWM2")
	)
	(segment
		(start 105.294938 -363.63783)
		(end 106.778298 -362.15447)
		(width 0.1778)
		(layer "F.Cu")
		(net "PVCCIN_CPU1_PWM2")
	)
	(segment
		(start 105.418382 -337.661504)
		(end 105.418382 -336.61604)
		(width 0.1778)
		(layer "F.Cu")
		(net "PVCCIN_CPU1_PWM2")
	)
	(segment
		(start 105.26649 -338.028026)
		(end 105.418382 -337.661504)
		(width 0.1778)
		(layer "F.Cu")
		(net "PVCCIN_CPU1_PWM2")
	)
	(via
		(at 105.26649 -338.028026)
		(size 0.508)
		(drill 0.254)
		(layers "F.Cu" "B.Cu")
		(net "PVCCIN_CPU1_PWM2")
	)
	(via
		(at 104.753664 -363.63783)
		(size 0.508)
		(drill 0.254)
		(layers "F.Cu" "B.Cu")
		(net "PVCCIN_CPU1_PWM2")
	)
	(segment
		(start 103.097838 -348.12097)
		(end 103.097838 -342.92159)
		(width 0.2032)
		(layer "In2.Cu")
		(net "PVCCIN_CPU1_PWM2")
	)
	(segment
		(start 105.5497 -360.561382)
		(end 105.5497 -356.33406)
		(width 0.2032)
		(layer "In2.Cu")
		(net "PVCCIN_CPU1_PWM2")
	)
	(segment
		(start 106.209338 -338.55787)
		(end 105.679494 -338.028026)
		(width 0.2032)
		(layer "In2.Cu")
		(net "PVCCIN_CPU1_PWM2")
	)
	(segment
		(start 105.03408 -361.077002)
		(end 105.5497 -360.561382)
		(width 0.2032)
		(layer "In2.Cu")
		(net "PVCCIN_CPU1_PWM2")
	)
	(segment
		(start 105.679494 -338.028026)
		(end 105.26649 -338.028026)
		(width 0.2032)
		(layer "In2.Cu")
		(net "PVCCIN_CPU1_PWM2")
	)
	(segment
		(start 102.132638 -352.916998)
		(end 102.132638 -349.08617)
		(width 0.2032)
		(layer "In2.Cu")
		(net "PVCCIN_CPU1_PWM2")
	)
	(segment
		(start 105.03408 -363.357414)
		(end 105.03408 -361.077002)
		(width 0.2032)
		(layer "In2.Cu")
		(net "PVCCIN_CPU1_PWM2")
	)
	(segment
		(start 103.097838 -342.92159)
		(end 106.209338 -339.81009)
		(width 0.2032)
		(layer "In2.Cu")
		(net "PVCCIN_CPU1_PWM2")
	)
	(segment
		(start 106.209338 -339.81009)
		(end 106.209338 -338.55787)
		(width 0.2032)
		(layer "In2.Cu")
		(net "PVCCIN_CPU1_PWM2")
	)
	(segment
		(start 104.753664 -363.63783)
		(end 105.03408 -363.357414)
		(width 0.2032)
		(layer "In2.Cu")
		(net "PVCCIN_CPU1_PWM2")
	)
	(segment
		(start 105.5497 -356.33406)
		(end 102.132638 -352.916998)
		(width 0.2032)
		(layer "In2.Cu")
		(net "PVCCIN_CPU1_PWM2")
	)
	(segment
		(start 102.132638 -349.08617)
		(end 103.097838 -348.12097)
		(width 0.2032)
		(layer "In2.Cu")
		(net "PVCCIN_CPU1_PWM2")
	)
	(segment
		(start 105.899204 -362.323634)
		(end 106.172508 -362.323634)
		(width 0.12954)
		(layer "F.Cu")
		(net "PVCCIN_CPU1_PWM1")
	)
	(segment
		(start 106.378502 -362.11764)
		(end 106.378502 -361.723432)
		(width 0.12954)
		(layer "F.Cu")
		(net "PVCCIN_CPU1_PWM1")
	)
	(segment
		(start 106.172508 -362.323634)
		(end 106.378502 -362.11764)
		(width 0.12954)
		(layer "F.Cu")
		(net "PVCCIN_CPU1_PWM1")
	)
	(segment
		(start 97.105978 -338.028026)
		(end 97.25787 -337.661504)
		(width 0.1778)
		(layer "F.Cu")
		(net "PVCCIN_CPU1_PWM1")
	)
	(segment
		(start 97.25787 -337.661504)
		(end 97.25787 -336.61604)
		(width 0.1778)
		(layer "F.Cu")
		(net "PVCCIN_CPU1_PWM1")
	)
	(via
		(at 97.105978 -338.028026)
		(size 0.508)
		(drill 0.254)
		(layers "F.Cu" "B.Cu")
		(net "PVCCIN_CPU1_PWM1")
	)
	(via
		(at 105.899204 -362.323634)
		(size 0.508)
		(drill 0.254)
		(layers "F.Cu" "B.Cu")
		(net "PVCCIN_CPU1_PWM1")
	)
	(segment
		(start 101.2444 -360.982514)
		(end 100.710238 -360.448352)
		(width 0.2032)
		(layer "In2.Cu")
		(net "PVCCIN_CPU1_PWM1")
	)
	(segment
		(start 102.555294 -363.444536)
		(end 101.2444 -362.133642)
		(width 0.2032)
		(layer "In2.Cu")
		(net "PVCCIN_CPU1_PWM1")
	)
	(segment
		(start 100.710238 -360.448352)
		(end 100.710238 -348.522036)
		(width 0.2032)
		(layer "In2.Cu")
		(net "PVCCIN_CPU1_PWM1")
	)
	(segment
		(start 104.428798 -364.53445)
		(end 103.338884 -363.444536)
		(width 0.2032)
		(layer "In2.Cu")
		(net "PVCCIN_CPU1_PWM1")
	)
	(segment
		(start 101.617018 -341.965788)
		(end 97.679256 -338.028026)
		(width 0.2032)
		(layer "In2.Cu")
		(net "PVCCIN_CPU1_PWM1")
	)
	(segment
		(start 97.679256 -338.028026)
		(end 97.105978 -338.028026)
		(width 0.2032)
		(layer "In2.Cu")
		(net "PVCCIN_CPU1_PWM1")
	)
	(segment
		(start 103.338884 -363.444536)
		(end 102.555294 -363.444536)
		(width 0.2032)
		(layer "In2.Cu")
		(net "PVCCIN_CPU1_PWM1")
	)
	(segment
		(start 105.899204 -362.323634)
		(end 105.75036 -362.472478)
		(width 0.2032)
		(layer "In2.Cu")
		(net "PVCCIN_CPU1_PWM1")
	)
	(segment
		(start 105.75036 -363.896148)
		(end 105.112058 -364.53445)
		(width 0.2032)
		(layer "In2.Cu")
		(net "PVCCIN_CPU1_PWM1")
	)
	(segment
		(start 100.710238 -348.522036)
		(end 101.617018 -347.615256)
		(width 0.2032)
		(layer "In2.Cu")
		(net "PVCCIN_CPU1_PWM1")
	)
	(segment
		(start 105.75036 -362.472478)
		(end 105.75036 -363.896148)
		(width 0.2032)
		(layer "In2.Cu")
		(net "PVCCIN_CPU1_PWM1")
	)
	(segment
		(start 101.617018 -347.615256)
		(end 101.617018 -341.965788)
		(width 0.2032)
		(layer "In2.Cu")
		(net "PVCCIN_CPU1_PWM1")
	)
	(segment
		(start 101.2444 -362.133642)
		(end 101.2444 -360.982514)
		(width 0.2032)
		(layer "In2.Cu")
		(net "PVCCIN_CPU1_PWM1")
	)
	(segment
		(start 105.112058 -364.53445)
		(end 104.428798 -364.53445)
		(width 0.2032)
		(layer "In2.Cu")
		(net "PVCCIN_CPU1_PWM1")
	)
	(segment
		(start 77.145642 -343.742264)
		(end 77.145642 -343.170002)
		(width 0.2032)
		(layer "F.Cu")
		(net "PVCCIN_CPU1_PVCC")
	)
	(segment
		(start 144.14373 -343.713308)
		(end 144.14373 -344.232738)
		(width 0.381)
		(layer "F.Cu")
		(net "PVCCIN_CPU1_PVCC")
	)
	(segment
		(start 109.744002 -334.541368)
		(end 109.744002 -333.925418)
		(width 0.2032)
		(layer "F.Cu")
		(net "PVCCIN_CPU1_PVCC")
	)
	(segment
		(start 109.744002 -333.925418)
		(end 109.835442 -333.925418)
		(width 0.2032)
		(layer "F.Cu")
		(net "PVCCIN_CPU1_PVCC")
	)
	(segment
		(start 143.89354 -343.463118)
		(end 144.14373 -343.713308)
		(width 0.381)
		(layer "F.Cu")
		(net "PVCCIN_CPU1_PVCC")
	)
	(segment
		(start 117.904514 -333.925418)
		(end 117.995954 -333.925418)
		(width 0.2032)
		(layer "F.Cu")
		(net "PVCCIN_CPU1_PVCC")
	)
	(segment
		(start 126.156466 -337.335622)
		(end 126.872238 -338.051394)
		(width 0.2032)
		(layer "F.Cu")
		(net "PVCCIN_CPU1_PVCC")
	)
	(segment
		(start 93.394276 -334.541368)
		(end 93.400118 -334.535526)
		(width 0.2032)
		(layer "F.Cu")
		(net "PVCCIN_CPU1_PVCC")
	)
	(segment
		(start 93.400118 -334.535526)
		(end 93.400118 -333.925418)
		(width 0.2032)
		(layer "F.Cu")
		(net "PVCCIN_CPU1_PVCC")
	)
	(segment
		(start 126.872238 -338.051394)
		(end 127.239776 -338.051394)
		(width 0.2032)
		(layer "F.Cu")
		(net "PVCCIN_CPU1_PVCC")
	)
	(segment
		(start 102.75824 -334.64119)
		(end 102.390702 -334.64119)
		(width 0.2032)
		(layer "F.Cu")
		(net "PVCCIN_CPU1_PVCC")
	)
	(segment
		(start 77.230986 -343.126314)
		(end 77.101954 -343.126314)
		(width 0.2286)
		(layer "F.Cu")
		(net "PVCCIN_CPU1_PVCC")
	)
	(segment
		(start 93.466666 -333.925418)
		(end 93.400118 -333.925418)
		(width 0.2032)
		(layer "F.Cu")
		(net "PVCCIN_CPU1_PVCC")
	)
	(segment
		(start 118.711726 -334.64119)
		(end 119.079264 -334.64119)
		(width 0.2032)
		(layer "F.Cu")
		(net "PVCCIN_CPU1_PVCC")
	)
	(segment
		(start 85.353906 -337.335622)
		(end 85.262466 -337.335622)
		(width 0.2032)
		(layer "F.Cu")
		(net "PVCCIN_CPU1_PVCC")
	)
	(segment
		(start 117.904514 -334.541368)
		(end 117.904514 -333.925418)
		(width 0.2032)
		(layer "F.Cu")
		(net "PVCCIN_CPU1_PVCC")
	)
	(segment
		(start 109.835442 -333.925418)
		(end 110.551214 -334.64119)
		(width 0.2032)
		(layer "F.Cu")
		(net "PVCCIN_CPU1_PVCC")
	)
	(segment
		(start 134.316978 -343.126314)
		(end 134.225538 -343.126314)
		(width 0.2032)
		(layer "F.Cu")
		(net "PVCCIN_CPU1_PVCC")
	)
	(segment
		(start 85.262466 -337.951572)
		(end 85.262466 -337.335622)
		(width 0.2032)
		(layer "F.Cu")
		(net "PVCCIN_CPU1_PVCC")
	)
	(segment
		(start 135.400288 -343.842086)
		(end 135.03275 -343.842086)
		(width 0.2032)
		(layer "F.Cu")
		(net "PVCCIN_CPU1_PVCC")
	)
	(segment
		(start 126.065026 -337.335622)
		(end 126.156466 -337.335622)
		(width 0.2032)
		(layer "F.Cu")
		(net "PVCCIN_CPU1_PVCC")
	)
	(segment
		(start 77.145642 -343.170002)
		(end 77.101954 -343.126314)
		(width 0.2032)
		(layer "F.Cu")
		(net "PVCCIN_CPU1_PVCC")
	)
	(segment
		(start 126.065026 -337.945222)
		(end 126.065026 -337.335622)
		(width 0.2032)
		(layer "F.Cu")
		(net "PVCCIN_CPU1_PVCC")
	)
	(segment
		(start 94.182438 -334.64119)
		(end 93.466666 -333.925418)
		(width 0.2032)
		(layer "F.Cu")
		(net "PVCCIN_CPU1_PVCC")
	)
	(segment
		(start 102.390702 -334.64119)
		(end 101.67493 -333.925418)
		(width 0.2032)
		(layer "F.Cu")
		(net "PVCCIN_CPU1_PVCC")
	)
	(segment
		(start 86.069678 -338.051394)
		(end 85.353906 -337.335622)
		(width 0.2032)
		(layer "F.Cu")
		(net "PVCCIN_CPU1_PVCC")
	)
	(segment
		(start 110.551214 -334.64119)
		(end 110.918752 -334.64119)
		(width 0.2032)
		(layer "F.Cu")
		(net "PVCCIN_CPU1_PVCC")
	)
	(segment
		(start 144.14373 -344.232738)
		(end 144.14373 -345.129358)
		(width 0.381)
		(layer "F.Cu")
		(net "PVCCIN_CPU1_PVCC")
	)
	(segment
		(start 101.58349 -334.541368)
		(end 101.58349 -333.925418)
		(width 0.2032)
		(layer "F.Cu")
		(net "PVCCIN_CPU1_PVCC")
	)
	(segment
		(start 77.946758 -343.842086)
		(end 77.230986 -343.126314)
		(width 0.2286)
		(layer "F.Cu")
		(net "PVCCIN_CPU1_PVCC")
	)
	(segment
		(start 86.437216 -338.051394)
		(end 86.069678 -338.051394)
		(width 0.2032)
		(layer "F.Cu")
		(net "PVCCIN_CPU1_PVCC")
	)
	(segment
		(start 117.995954 -333.925418)
		(end 118.711726 -334.64119)
		(width 0.2032)
		(layer "F.Cu")
		(net "PVCCIN_CPU1_PVCC")
	)
	(segment
		(start 101.67493 -333.925418)
		(end 101.58349 -333.925418)
		(width 0.2032)
		(layer "F.Cu")
		(net "PVCCIN_CPU1_PVCC")
	)
	(segment
		(start 78.276704 -343.842086)
		(end 77.946758 -343.842086)
		(width 0.2286)
		(layer "F.Cu")
		(net "PVCCIN_CPU1_PVCC")
	)
	(segment
		(start 134.225538 -343.126314)
		(end 134.225538 -343.742264)
		(width 0.254)
		(layer "F.Cu")
		(net "PVCCIN_CPU1_PVCC")
	)
	(segment
		(start 135.03275 -343.842086)
		(end 134.316978 -343.126314)
		(width 0.2032)
		(layer "F.Cu")
		(net "PVCCIN_CPU1_PVCC")
	)
	(segment
		(start 94.597728 -334.64119)
		(end 94.182438 -334.64119)
		(width 0.2032)
		(layer "F.Cu")
		(net "PVCCIN_CPU1_PVCC")
	)
	(via
		(at 85.262466 -337.951572)
		(size 0.508)
		(drill 0.254)
		(layers "F.Cu" "B.Cu")
		(net "PVCCIN_CPU1_PVCC")
	)
	(via
		(at 101.58349 -334.541368)
		(size 0.508)
		(drill 0.254)
		(layers "F.Cu" "B.Cu")
		(net "PVCCIN_CPU1_PVCC")
	)
	(via
		(at 109.744002 -334.541368)
		(size 0.508)
		(drill 0.254)
		(layers "F.Cu" "B.Cu")
		(net "PVCCIN_CPU1_PVCC")
	)
	(via
		(at 77.145642 -343.742264)
		(size 0.508)
		(drill 0.254)
		(layers "F.Cu" "B.Cu")
		(net "PVCCIN_CPU1_PVCC")
	)
	(via
		(at 126.065026 -337.945222)
		(size 0.508)
		(drill 0.254)
		(layers "F.Cu" "B.Cu")
		(net "PVCCIN_CPU1_PVCC")
	)
	(via
		(at 117.904514 -334.541368)
		(size 0.508)
		(drill 0.254)
		(layers "F.Cu" "B.Cu")
		(net "PVCCIN_CPU1_PVCC")
	)
	(via
		(at 134.225538 -343.742264)
		(size 0.508)
		(drill 0.254)
		(layers "F.Cu" "B.Cu")
		(net "PVCCIN_CPU1_PVCC")
	)
	(via
		(at 143.89354 -343.463118)
		(size 0.508)
		(drill 0.254)
		(layers "F.Cu" "B.Cu")
		(net "PVCCIN_CPU1_PVCC")
	)
	(via
		(at 93.394276 -334.541368)
		(size 0.508)
		(drill 0.254)
		(layers "F.Cu" "B.Cu")
		(net "PVCCIN_CPU1_PVCC")
	)
	(segment
		(start 77.145642 -343.698576)
		(end 77.31633 -343.527888)
		(width 0.508)
		(layer "B.Cu")
		(net "PVCCIN_CPU1_PVCC")
	)
	(segment
		(start 93.394276 -334.541368)
		(end 93.422978 -334.541368)
		(width 0.508)
		(layer "B.Cu")
		(net "PVCCIN_CPU1_PVCC")
	)
	(segment
		(start 93.611954 -334.352392)
		(end 94.596712 -334.352392)
		(width 0.508)
		(layer "B.Cu")
		(net "PVCCIN_CPU1_PVCC")
	)
	(segment
		(start 118.152418 -334.293464)
		(end 119.07266 -334.293464)
		(width 0.508)
		(layer "B.Cu")
		(net "PVCCIN_CPU1_PVCC")
	)
	(segment
		(start 77.145642 -343.742264)
		(end 77.145642 -343.698576)
		(width 0.508)
		(layer "B.Cu")
		(net "PVCCIN_CPU1_PVCC")
	)
	(segment
		(start 93.422978 -334.541368)
		(end 93.611954 -334.352392)
		(width 0.508)
		(layer "B.Cu")
		(net "PVCCIN_CPU1_PVCC")
	)
	(segment
		(start 126.065026 -337.945222)
		(end 126.071376 -337.945222)
		(width 0.508)
		(layer "B.Cu")
		(net "PVCCIN_CPU1_PVCC")
	)
	(segment
		(start 117.904514 -334.541368)
		(end 118.152418 -334.293464)
		(width 0.508)
		(layer "B.Cu")
		(net "PVCCIN_CPU1_PVCC")
	)
	(segment
		(start 85.262466 -337.951572)
		(end 85.476842 -337.737196)
		(width 0.508)
		(layer "B.Cu")
		(net "PVCCIN_CPU1_PVCC")
	)
	(segment
		(start 134.439914 -343.527888)
		(end 135.489442 -343.527888)
		(width 0.508)
		(layer "B.Cu")
		(net "PVCCIN_CPU1_PVCC")
	)
	(segment
		(start 101.679756 -334.445102)
		(end 102.909624 -334.445102)
		(width 0.508)
		(layer "B.Cu")
		(net "PVCCIN_CPU1_PVCC")
	)
	(segment
		(start 101.58349 -334.541368)
		(end 101.679756 -334.445102)
		(width 0.508)
		(layer "B.Cu")
		(net "PVCCIN_CPU1_PVCC")
	)
	(segment
		(start 109.982254 -334.303116)
		(end 110.922054 -334.303116)
		(width 0.508)
		(layer "B.Cu")
		(net "PVCCIN_CPU1_PVCC")
	)
	(segment
		(start 126.071376 -337.945222)
		(end 126.317756 -337.698842)
		(width 0.508)
		(layer "B.Cu")
		(net "PVCCIN_CPU1_PVCC")
	)
	(segment
		(start 126.317756 -337.698842)
		(end 127.257302 -337.698842)
		(width 0.508)
		(layer "B.Cu")
		(net "PVCCIN_CPU1_PVCC")
	)
	(segment
		(start 134.225538 -343.742264)
		(end 134.439914 -343.527888)
		(width 0.508)
		(layer "B.Cu")
		(net "PVCCIN_CPU1_PVCC")
	)
	(segment
		(start 85.476842 -337.737196)
		(end 85.9282 -337.737196)
		(width 0.508)
		(layer "B.Cu")
		(net "PVCCIN_CPU1_PVCC")
	)
	(segment
		(start 77.31633 -343.527888)
		(end 77.776578 -343.527888)
		(width 0.508)
		(layer "B.Cu")
		(net "PVCCIN_CPU1_PVCC")
	)
	(segment
		(start 109.744002 -334.541368)
		(end 109.982254 -334.303116)
		(width 0.508)
		(layer "B.Cu")
		(net "PVCCIN_CPU1_PVCC")
	)
	(segment
		(start 102.628446 -334.956912)
		(end 105.19664 -334.956912)
		(width 0.508)
		(layer "In4.Cu")
		(net "PVCCIN_CPU1_PVCC")
	)
	(segment
		(start 77.145642 -343.742264)
		(end 77.812138 -343.742264)
		(width 0.508)
		(layer "In4.Cu")
		(net "PVCCIN_CPU1_PVCC")
	)
	(segment
		(start 109.744002 -334.541368)
		(end 110.328202 -334.541368)
		(width 0.508)
		(layer "In4.Cu")
		(net "PVCCIN_CPU1_PVCC")
	)
	(segment
		(start 101.58349 -334.541368)
		(end 102.212902 -334.541368)
		(width 0.508)
		(layer "In4.Cu")
		(net "PVCCIN_CPU1_PVCC")
	)
	(segment
		(start 129.948432 -340.212172)
		(end 128.652524 -340.212172)
		(width 0.4064)
		(layer "In4.Cu")
		(net "PVCCIN_CPU1_PVCC")
	)
	(segment
		(start 134.225538 -343.742264)
		(end 133.478524 -343.742264)
		(width 0.4064)
		(layer "In4.Cu")
		(net "PVCCIN_CPU1_PVCC")
	)
	(segment
		(start 84.256626 -341.009986)
		(end 84.512912 -340.390734)
		(width 0.508)
		(layer "In4.Cu")
		(net "PVCCIN_CPU1_PVCC")
	)
	(segment
		(start 119.871744 -336.462624)
		(end 121.01068 -336.462624)
		(width 0.4064)
		(layer "In4.Cu")
		(net "PVCCIN_CPU1_PVCC")
	)
	(segment
		(start 126.138686 -339.384132)
		(end 126.600966 -338.921852)
		(width 0.4064)
		(layer "In4.Cu")
		(net "PVCCIN_CPU1_PVCC")
	)
	(segment
		(start 77.812138 -343.742264)
		(end 78.25994 -344.190066)
		(width 0.508)
		(layer "In4.Cu")
		(net "PVCCIN_CPU1_PVCC")
	)
	(segment
		(start 121.01068 -336.462624)
		(end 121.772172 -336.778092)
		(width 0.4064)
		(layer "In4.Cu")
		(net "PVCCIN_CPU1_PVCC")
	)
	(segment
		(start 94.006162 -335.738724)
		(end 92.958412 -336.17281)
		(width 0.508)
		(layer "In4.Cu")
		(net "PVCCIN_CPU1_PVCC")
	)
	(segment
		(start 124.378212 -339.384132)
		(end 126.138686 -339.384132)
		(width 0.4064)
		(layer "In4.Cu")
		(net "PVCCIN_CPU1_PVCC")
	)
	(segment
		(start 134.883398 -343.681812)
		(end 134.28599 -343.681812)
		(width 0.508)
		(layer "In4.Cu")
		(net "PVCCIN_CPU1_PVCC")
	)
	(segment
		(start 134.28599 -343.681812)
		(end 134.225538 -343.742264)
		(width 0.508)
		(layer "In4.Cu")
		(net "PVCCIN_CPU1_PVCC")
	)
	(segment
		(start 121.772172 -336.778092)
		(end 124.378212 -339.384132)
		(width 0.4064)
		(layer "In4.Cu")
		(net "PVCCIN_CPU1_PVCC")
	)
	(segment
		(start 113.759742 -334.541368)
		(end 117.904514 -334.541368)
		(width 0.508)
		(layer "In4.Cu")
		(net "PVCCIN_CPU1_PVCC")
	)
	(segment
		(start 113.265712 -335.035398)
		(end 113.759742 -334.541368)
		(width 0.508)
		(layer "In4.Cu")
		(net "PVCCIN_CPU1_PVCC")
	)
	(segment
		(start 117.904514 -334.541368)
		(end 118.658386 -334.541368)
		(width 0.4064)
		(layer "In4.Cu")
		(net "PVCCIN_CPU1_PVCC")
	)
	(segment
		(start 135.353298 -344.151712)
		(end 134.883398 -343.681812)
		(width 0.508)
		(layer "In4.Cu")
		(net "PVCCIN_CPU1_PVCC")
	)
	(segment
		(start 86.213696 -338.445602)
		(end 86.548976 -338.445602)
		(width 0.508)
		(layer "In4.Cu")
		(net "PVCCIN_CPU1_PVCC")
	)
	(segment
		(start 94.709488 -335.035398)
		(end 94.006162 -335.738724)
		(width 0.508)
		(layer "In4.Cu")
		(net "PVCCIN_CPU1_PVCC")
	)
	(segment
		(start 119.473472 -336.064352)
		(end 119.871744 -336.462624)
		(width 0.4064)
		(layer "In4.Cu")
		(net "PVCCIN_CPU1_PVCC")
	)
	(segment
		(start 128.652524 -340.212172)
		(end 128.194308 -340.022434)
		(width 0.4064)
		(layer "In4.Cu")
		(net "PVCCIN_CPU1_PVCC")
	)
	(segment
		(start 84.512912 -340.390734)
		(end 85.00491 -339.654388)
		(width 0.508)
		(layer "In4.Cu")
		(net "PVCCIN_CPU1_PVCC")
	)
	(segment
		(start 138.512804 -343.463118)
		(end 137.82421 -344.151712)
		(width 0.508)
		(layer "In4.Cu")
		(net "PVCCIN_CPU1_PVCC")
	)
	(segment
		(start 94.215458 -334.541368)
		(end 94.709488 -335.035398)
		(width 0.508)
		(layer "In4.Cu")
		(net "PVCCIN_CPU1_PVCC")
	)
	(segment
		(start 97.422462 -334.541368)
		(end 101.58349 -334.541368)
		(width 0.508)
		(layer "In4.Cu")
		(net "PVCCIN_CPU1_PVCC")
	)
	(segment
		(start 89.532968 -337.691984)
		(end 88.741504 -338.483448)
		(width 0.508)
		(layer "In4.Cu")
		(net "PVCCIN_CPU1_PVCC")
	)
	(segment
		(start 84.256626 -342.770206)
		(end 84.256626 -341.009986)
		(width 0.508)
		(layer "In4.Cu")
		(net "PVCCIN_CPU1_PVCC")
	)
	(segment
		(start 118.658386 -334.541368)
		(end 119.267986 -335.150968)
		(width 0.4064)
		(layer "In4.Cu")
		(net "PVCCIN_CPU1_PVCC")
	)
	(segment
		(start 102.212902 -334.541368)
		(end 102.628446 -334.956912)
		(width 0.508)
		(layer "In4.Cu")
		(net "PVCCIN_CPU1_PVCC")
	)
	(segment
		(start 94.709488 -335.035398)
		(end 96.928432 -335.035398)
		(width 0.508)
		(layer "In4.Cu")
		(net "PVCCIN_CPU1_PVCC")
	)
	(segment
		(start 83.486498 -343.540334)
		(end 84.256626 -342.770206)
		(width 0.508)
		(layer "In4.Cu")
		(net "PVCCIN_CPU1_PVCC")
	)
	(segment
		(start 143.89354 -343.463118)
		(end 138.512804 -343.463118)
		(width 0.508)
		(layer "In4.Cu")
		(net "PVCCIN_CPU1_PVCC")
	)
	(segment
		(start 92.958412 -336.17281)
		(end 91.439238 -337.691984)
		(width 0.508)
		(layer "In4.Cu")
		(net "PVCCIN_CPU1_PVCC")
	)
	(segment
		(start 128.194308 -340.022434)
		(end 127.093726 -338.921852)
		(width 0.4064)
		(layer "In4.Cu")
		(net "PVCCIN_CPU1_PVCC")
	)
	(segment
		(start 91.439238 -337.691984)
		(end 89.532968 -337.691984)
		(width 0.508)
		(layer "In4.Cu")
		(net "PVCCIN_CPU1_PVCC")
	)
	(segment
		(start 88.741504 -338.483448)
		(end 86.586822 -338.483448)
		(width 0.508)
		(layer "In4.Cu")
		(net "PVCCIN_CPU1_PVCC")
	)
	(segment
		(start 105.19664 -334.956912)
		(end 105.612184 -334.541368)
		(width 0.508)
		(layer "In4.Cu")
		(net "PVCCIN_CPU1_PVCC")
	)
	(segment
		(start 110.822232 -335.035398)
		(end 113.265712 -335.035398)
		(width 0.508)
		(layer "In4.Cu")
		(net "PVCCIN_CPU1_PVCC")
	)
	(segment
		(start 126.065026 -337.945222)
		(end 126.585726 -337.945222)
		(width 0.508)
		(layer "In4.Cu")
		(net "PVCCIN_CPU1_PVCC")
	)
	(segment
		(start 105.612184 -334.541368)
		(end 109.744002 -334.541368)
		(width 0.508)
		(layer "In4.Cu")
		(net "PVCCIN_CPU1_PVCC")
	)
	(segment
		(start 81.308448 -343.540334)
		(end 83.486498 -343.540334)
		(width 0.508)
		(layer "In4.Cu")
		(net "PVCCIN_CPU1_PVCC")
	)
	(segment
		(start 137.82421 -344.151712)
		(end 135.353298 -344.151712)
		(width 0.508)
		(layer "In4.Cu")
		(net "PVCCIN_CPU1_PVCC")
	)
	(segment
		(start 126.585726 -337.945222)
		(end 127.093726 -338.453222)
		(width 0.508)
		(layer "In4.Cu")
		(net "PVCCIN_CPU1_PVCC")
	)
	(segment
		(start 96.928432 -335.035398)
		(end 97.422462 -334.541368)
		(width 0.508)
		(layer "In4.Cu")
		(net "PVCCIN_CPU1_PVCC")
	)
	(segment
		(start 85.00491 -339.654388)
		(end 86.213696 -338.445602)
		(width 0.508)
		(layer "In4.Cu")
		(net "PVCCIN_CPU1_PVCC")
	)
	(segment
		(start 133.478524 -343.742264)
		(end 129.948432 -340.212172)
		(width 0.4064)
		(layer "In4.Cu")
		(net "PVCCIN_CPU1_PVCC")
	)
	(segment
		(start 126.600966 -338.921852)
		(end 127.093726 -338.921852)
		(width 0.4064)
		(layer "In4.Cu")
		(net "PVCCIN_CPU1_PVCC")
	)
	(segment
		(start 119.267986 -335.56829)
		(end 119.473472 -336.064352)
		(width 0.4064)
		(layer "In4.Cu")
		(net "PVCCIN_CPU1_PVCC")
	)
	(segment
		(start 78.25994 -344.190066)
		(end 80.658716 -344.190066)
		(width 0.508)
		(layer "In4.Cu")
		(net "PVCCIN_CPU1_PVCC")
	)
	(segment
		(start 119.267986 -335.150968)
		(end 119.267986 -335.56829)
		(width 0.4064)
		(layer "In4.Cu")
		(net "PVCCIN_CPU1_PVCC")
	)
	(segment
		(start 80.658716 -344.190066)
		(end 81.308448 -343.540334)
		(width 0.508)
		(layer "In4.Cu")
		(net "PVCCIN_CPU1_PVCC")
	)
	(segment
		(start 110.328202 -334.541368)
		(end 110.822232 -335.035398)
		(width 0.508)
		(layer "In4.Cu")
		(net "PVCCIN_CPU1_PVCC")
	)
	(segment
		(start 86.586822 -338.483448)
		(end 86.548976 -338.445602)
		(width 0.508)
		(layer "In4.Cu")
		(net "PVCCIN_CPU1_PVCC")
	)
	(segment
		(start 86.054946 -337.951572)
		(end 86.548976 -338.445602)
		(width 0.508)
		(layer "In4.Cu")
		(net "PVCCIN_CPU1_PVCC")
	)
	(segment
		(start 93.394276 -334.541368)
		(end 94.215458 -334.541368)
		(width 0.508)
		(layer "In4.Cu")
		(net "PVCCIN_CPU1_PVCC")
	)
	(segment
		(start 85.262466 -337.951572)
		(end 86.054946 -337.951572)
		(width 0.508)
		(layer "In4.Cu")
		(net "PVCCIN_CPU1_PVCC")
	)
	(segment
		(start 127.093726 -338.453222)
		(end 127.093726 -338.921852)
		(width 0.508)
		(layer "In4.Cu")
		(net "PVCCIN_CPU1_PVCC")
	)
	(segment
		(start 102.048818 -359.46334)
		(end 102.216712 -359.631234)
		(width 0.1778)
		(layer "F.Cu")
		(net "PVCCIN_CPU1_PIN_ALERT")
	)
	(segment
		(start 105.206038 -358.605328)
		(end 105.249218 -358.648508)
		(width 0.1778)
		(layer "F.Cu")
		(net "PVCCIN_CPU1_PIN_ALERT")
	)
	(segment
		(start 102.216712 -359.631234)
		(end 103.165148 -359.631234)
		(width 0.1778)
		(layer "F.Cu")
		(net "PVCCIN_CPU1_PIN_ALERT")
	)
	(segment
		(start 101.11359 -359.012236)
		(end 101.597714 -359.012236)
		(width 0.1778)
		(layer "F.Cu")
		(net "PVCCIN_CPU1_PIN_ALERT")
	)
	(segment
		(start 104.191054 -358.605328)
		(end 105.206038 -358.605328)
		(width 0.1778)
		(layer "F.Cu")
		(net "PVCCIN_CPU1_PIN_ALERT")
	)
	(segment
		(start 103.165148 -359.631234)
		(end 104.191054 -358.605328)
		(width 0.1778)
		(layer "F.Cu")
		(net "PVCCIN_CPU1_PIN_ALERT")
	)
	(segment
		(start 101.597714 -359.012236)
		(end 102.048818 -359.46334)
		(width 0.1778)
		(layer "F.Cu")
		(net "PVCCIN_CPU1_PIN_ALERT")
	)
	(segment
		(start 105.249218 -358.648508)
		(end 105.70337 -358.648508)
		(width 0.1778)
		(layer "F.Cu")
		(net "PVCCIN_CPU1_PIN_ALERT")
	)
	(segment
		(start 101.0666 -359.059226)
		(end 101.11359 -359.012236)
		(width 0.1778)
		(layer "F.Cu")
		(net "PVCCIN_CPU1_PIN_ALERT")
	)
	(via
		(at 102.048818 -359.46334)
		(size 0.4064)
		(drill 0.2032)
		(layers "F.Cu" "B.Cu")
		(net "PVCCIN_CPU1_PIN_ALERT")
	)
	(segment
		(start 136.71042 -346.140786)
		(end 136.71042 -345.816936)
		(width 0.12954)
		(layer "F.Cu")
		(net "PVCCIN_CPU1_LSET8")
	)
	(segment
		(start 136.337802 -346.59443)
		(end 136.653016 -346.279216)
		(width 0.12954)
		(layer "F.Cu")
		(net "PVCCIN_CPU1_LSET8")
	)
	(segment
		(start 136.337802 -347.832172)
		(end 136.337802 -346.59443)
		(width 0.12954)
		(layer "F.Cu")
		(net "PVCCIN_CPU1_LSET8")
	)
	(segment
		(start 136.653016 -346.279216)
		(end 136.71042 -346.140786)
		(width 0.12954)
		(layer "F.Cu")
		(net "PVCCIN_CPU1_LSET8")
	)
	(segment
		(start 136.108948 -348.061026)
		(end 136.337802 -347.832172)
		(width 0.12954)
		(layer "F.Cu")
		(net "PVCCIN_CPU1_LSET8")
	)
	(segment
		(start 79.214218 -347.879162)
		(end 79.266034 -347.930978)
		(width 0.12954)
		(layer "F.Cu")
		(net "PVCCIN_CPU1_LSET7")
	)
	(segment
		(start 79.586836 -346.140786)
		(end 79.529432 -346.279216)
		(width 0.12954)
		(layer "F.Cu")
		(net "PVCCIN_CPU1_LSET7")
	)
	(segment
		(start 79.214218 -346.59443)
		(end 79.214218 -347.879162)
		(width 0.12954)
		(layer "F.Cu")
		(net "PVCCIN_CPU1_LSET7")
	)
	(segment
		(start 79.529432 -346.279216)
		(end 79.214218 -346.59443)
		(width 0.12954)
		(layer "F.Cu")
		(net "PVCCIN_CPU1_LSET7")
	)
	(segment
		(start 79.586836 -345.816936)
		(end 79.586836 -346.140786)
		(width 0.12954)
		(layer "F.Cu")
		(net "PVCCIN_CPU1_LSET7")
	)
	(segment
		(start 87.145876 -342.270334)
		(end 87.37473 -342.04148)
		(width 0.12954)
		(layer "F.Cu")
		(net "PVCCIN_CPU1_LSET6")
	)
	(segment
		(start 87.37473 -342.04148)
		(end 87.37473 -340.803738)
		(width 0.12954)
		(layer "F.Cu")
		(net "PVCCIN_CPU1_LSET6")
	)
	(segment
		(start 87.689944 -340.488524)
		(end 87.747348 -340.350094)
		(width 0.12954)
		(layer "F.Cu")
		(net "PVCCIN_CPU1_LSET6")
	)
	(segment
		(start 87.747348 -340.350094)
		(end 87.747348 -340.026244)
		(width 0.12954)
		(layer "F.Cu")
		(net "PVCCIN_CPU1_LSET6")
	)
	(segment
		(start 87.37473 -340.803738)
		(end 87.689944 -340.488524)
		(width 0.12954)
		(layer "F.Cu")
		(net "PVCCIN_CPU1_LSET6")
	)
	(segment
		(start 128.549908 -340.350094)
		(end 128.549908 -340.026244)
		(width 0.12954)
		(layer "F.Cu")
		(net "PVCCIN_CPU1_LSET5")
	)
	(segment
		(start 128.492504 -340.488524)
		(end 128.549908 -340.350094)
		(width 0.12954)
		(layer "F.Cu")
		(net "PVCCIN_CPU1_LSET5")
	)
	(segment
		(start 128.17729 -342.04148)
		(end 128.17729 -340.803738)
		(width 0.12954)
		(layer "F.Cu")
		(net "PVCCIN_CPU1_LSET5")
	)
	(segment
		(start 128.17729 -340.803738)
		(end 128.492504 -340.488524)
		(width 0.12954)
		(layer "F.Cu")
		(net "PVCCIN_CPU1_LSET5")
	)
	(segment
		(start 127.948436 -342.270334)
		(end 128.17729 -342.04148)
		(width 0.12954)
		(layer "F.Cu")
		(net "PVCCIN_CPU1_LSET5")
	)
	(segment
		(start 120.016778 -338.631276)
		(end 120.016778 -337.393534)
		(width 0.12954)
		(layer "F.Cu")
		(net "PVCCIN_CPU1_LSET4")
	)
	(segment
		(start 120.389396 -336.93989)
		(end 120.389396 -336.61604)
		(width 0.12954)
		(layer "F.Cu")
		(net "PVCCIN_CPU1_LSET4")
	)
	(segment
		(start 120.331992 -337.07832)
		(end 120.389396 -336.93989)
		(width 0.12954)
		(layer "F.Cu")
		(net "PVCCIN_CPU1_LSET4")
	)
	(segment
		(start 119.787924 -338.86013)
		(end 120.016778 -338.631276)
		(width 0.12954)
		(layer "F.Cu")
		(net "PVCCIN_CPU1_LSET4")
	)
	(segment
		(start 120.016778 -337.393534)
		(end 120.331992 -337.07832)
		(width 0.12954)
		(layer "F.Cu")
		(net "PVCCIN_CPU1_LSET4")
	)
	(segment
		(start 111.856266 -338.631276)
		(end 111.856266 -337.393534)
		(width 0.12954)
		(layer "F.Cu")
		(net "PVCCIN_CPU1_LSET3")
	)
	(segment
		(start 111.627412 -338.86013)
		(end 111.856266 -338.631276)
		(width 0.12954)
		(layer "F.Cu")
		(net "PVCCIN_CPU1_LSET3")
	)
	(segment
		(start 111.856266 -337.393534)
		(end 112.17148 -337.07832)
		(width 0.12954)
		(layer "F.Cu")
		(net "PVCCIN_CPU1_LSET3")
	)
	(segment
		(start 112.228884 -336.93989)
		(end 112.228884 -336.61604)
		(width 0.12954)
		(layer "F.Cu")
		(net "PVCCIN_CPU1_LSET3")
	)
	(segment
		(start 112.17148 -337.07832)
		(end 112.228884 -336.93989)
		(width 0.12954)
		(layer "F.Cu")
		(net "PVCCIN_CPU1_LSET3")
	)
	(segment
		(start 103.695754 -337.393534)
		(end 104.010968 -337.07832)
		(width 0.12954)
		(layer "F.Cu")
		(net "PVCCIN_CPU1_LSET2")
	)
	(segment
		(start 104.068372 -336.93989)
		(end 104.068372 -336.61604)
		(width 0.12954)
		(layer "F.Cu")
		(net "PVCCIN_CPU1_LSET2")
	)
	(segment
		(start 103.695754 -338.678012)
		(end 103.695754 -337.393534)
		(width 0.12954)
		(layer "F.Cu")
		(net "PVCCIN_CPU1_LSET2")
	)
	(segment
		(start 104.010968 -337.07832)
		(end 104.068372 -336.93989)
		(width 0.12954)
		(layer "F.Cu")
		(net "PVCCIN_CPU1_LSET2")
	)
	(segment
		(start 103.877872 -338.86013)
		(end 103.695754 -338.678012)
		(width 0.12954)
		(layer "F.Cu")
		(net "PVCCIN_CPU1_LSET2")
	)
	(segment
		(start 95.850456 -337.07832)
		(end 95.90786 -336.93989)
		(width 0.12954)
		(layer "F.Cu")
		(net "PVCCIN_CPU1_LSET1")
	)
	(segment
		(start 95.90786 -336.93989)
		(end 95.90786 -336.61604)
		(width 0.12954)
		(layer "F.Cu")
		(net "PVCCIN_CPU1_LSET1")
	)
	(segment
		(start 95.535242 -337.393534)
		(end 95.850456 -337.07832)
		(width 0.12954)
		(layer "F.Cu")
		(net "PVCCIN_CPU1_LSET1")
	)
	(segment
		(start 95.535242 -338.631276)
		(end 95.535242 -337.393534)
		(width 0.12954)
		(layer "F.Cu")
		(net "PVCCIN_CPU1_LSET1")
	)
	(segment
		(start 95.306388 -338.86013)
		(end 95.535242 -338.631276)
		(width 0.12954)
		(layer "F.Cu")
		(net "PVCCIN_CPU1_LSET1")
	)
	(segment
		(start 136.260332 -346.1512)
		(end 136.260332 -345.816936)
		(width 0.254)
		(layer "F.Cu")
		(net "PVCCIN_CPU1_IMON8")
	)
	(segment
		(start 109.978444 -355.165152)
		(end 109.978444 -355.97338)
		(width 0.1778)
		(layer "F.Cu")
		(net "PVCCIN_CPU1_IMON8")
	)
	(segment
		(start 112.735868 -352.832924)
		(end 112.310672 -352.832924)
		(width 0.1778)
		(layer "F.Cu")
		(net "PVCCIN_CPU1_IMON8")
	)
	(segment
		(start 135.823198 -346.66301)
		(end 135.823198 -346.588334)
		(width 0.254)
		(layer "F.Cu")
		(net "PVCCIN_CPU1_IMON8")
	)
	(segment
		(start 112.310672 -352.832924)
		(end 109.978444 -355.165152)
		(width 0.1778)
		(layer "F.Cu")
		(net "PVCCIN_CPU1_IMON8")
	)
	(segment
		(start 135.823198 -346.588334)
		(end 136.260332 -346.1512)
		(width 0.254)
		(layer "F.Cu")
		(net "PVCCIN_CPU1_IMON8")
	)
	(via
		(at 112.735868 -352.832924)
		(size 0.508)
		(drill 0.254)
		(layers "F.Cu" "B.Cu")
		(net "PVCCIN_CPU1_IMON8")
	)
	(via
		(at 135.823198 -346.66301)
		(size 0.508)
		(drill 0.254)
		(layers "F.Cu" "B.Cu")
		(net "PVCCIN_CPU1_IMON8")
	)
	(segment
		(start 133.605016 -348.960948)
		(end 132.77977 -348.135702)
		(width 0.254)
		(layer "In11.Cu")
		(net "PVCCIN_CPU1_IMON8")
	)
	(segment
		(start 136.465818 -347.30563)
		(end 136.465818 -348.313756)
		(width 0.254)
		(layer "In11.Cu")
		(net "PVCCIN_CPU1_IMON8")
	)
	(segment
		(start 136.465818 -348.313756)
		(end 135.818626 -348.960948)
		(width 0.254)
		(layer "In11.Cu")
		(net "PVCCIN_CPU1_IMON8")
	)
	(segment
		(start 135.818626 -348.960948)
		(end 133.605016 -348.960948)
		(width 0.254)
		(layer "In11.Cu")
		(net "PVCCIN_CPU1_IMON8")
	)
	(segment
		(start 113.042446 -352.526346)
		(end 112.735868 -352.832924)
		(width 0.254)
		(layer "In11.Cu")
		(net "PVCCIN_CPU1_IMON8")
	)
	(segment
		(start 135.823198 -346.66301)
		(end 136.465818 -347.30563)
		(width 0.254)
		(layer "In11.Cu")
		(net "PVCCIN_CPU1_IMON8")
	)
	(segment
		(start 132.77977 -348.135702)
		(end 125.891544 -348.135702)
		(width 0.254)
		(layer "In11.Cu")
		(net "PVCCIN_CPU1_IMON8")
	)
	(segment
		(start 121.5009 -352.526346)
		(end 113.042446 -352.526346)
		(width 0.254)
		(layer "In11.Cu")
		(net "PVCCIN_CPU1_IMON8")
	)
	(segment
		(start 125.891544 -348.135702)
		(end 121.5009 -352.526346)
		(width 0.254)
		(layer "In11.Cu")
		(net "PVCCIN_CPU1_IMON8")
	)
	(segment
		(start 109.578394 -354.772722)
		(end 109.578394 -355.97338)
		(width 0.1778)
		(layer "F.Cu")
		(net "PVCCIN_CPU1_IMON7")
	)
	(segment
		(start 78.699614 -346.588334)
		(end 78.699614 -346.66301)
		(width 0.254)
		(layer "F.Cu")
		(net "PVCCIN_CPU1_IMON7")
	)
	(segment
		(start 79.136748 -345.816936)
		(end 79.136748 -346.1512)
		(width 0.254)
		(layer "F.Cu")
		(net "PVCCIN_CPU1_IMON7")
	)
	(segment
		(start 110.862618 -353.488498)
		(end 109.578394 -354.772722)
		(width 0.1778)
		(layer "F.Cu")
		(net "PVCCIN_CPU1_IMON7")
	)
	(segment
		(start 79.136748 -346.1512)
		(end 78.699614 -346.588334)
		(width 0.254)
		(layer "F.Cu")
		(net "PVCCIN_CPU1_IMON7")
	)
	(via
		(at 110.862618 -353.488498)
		(size 0.508)
		(drill 0.254)
		(layers "F.Cu" "B.Cu")
		(net "PVCCIN_CPU1_IMON7")
	)
	(via
		(at 78.699614 -346.66301)
		(size 0.508)
		(drill 0.254)
		(layers "F.Cu" "B.Cu")
		(net "PVCCIN_CPU1_IMON7")
	)
	(segment
		(start 105.019856 -355.604064)
		(end 105.589832 -355.604064)
		(width 0.254)
		(layer "In11.Cu")
		(net "PVCCIN_CPU1_IMON7")
	)
	(segment
		(start 79.087218 -348.273116)
		(end 79.087218 -348.72549)
		(width 0.254)
		(layer "In11.Cu")
		(net "PVCCIN_CPU1_IMON7")
	)
	(segment
		(start 79.209138 -348.151196)
		(end 79.087218 -348.273116)
		(width 0.254)
		(layer "In11.Cu")
		(net "PVCCIN_CPU1_IMON7")
	)
	(segment
		(start 107.285282 -353.908614)
		(end 110.442502 -353.908614)
		(width 0.254)
		(layer "In11.Cu")
		(net "PVCCIN_CPU1_IMON7")
	)
	(segment
		(start 98.790506 -347.267784)
		(end 98.790506 -349.374714)
		(width 0.254)
		(layer "In11.Cu")
		(net "PVCCIN_CPU1_IMON7")
	)
	(segment
		(start 78.699614 -346.66301)
		(end 79.209138 -347.172534)
		(width 0.254)
		(layer "In11.Cu")
		(net "PVCCIN_CPU1_IMON7")
	)
	(segment
		(start 79.087218 -348.72549)
		(end 79.609188 -349.24746)
		(width 0.254)
		(layer "In11.Cu")
		(net "PVCCIN_CPU1_IMON7")
	)
	(segment
		(start 79.609188 -349.24746)
		(end 84.591652 -349.24746)
		(width 0.254)
		(layer "In11.Cu")
		(net "PVCCIN_CPU1_IMON7")
	)
	(segment
		(start 79.209138 -347.172534)
		(end 79.209138 -348.151196)
		(width 0.254)
		(layer "In11.Cu")
		(net "PVCCIN_CPU1_IMON7")
	)
	(segment
		(start 87.537036 -346.302076)
		(end 97.824798 -346.302076)
		(width 0.254)
		(layer "In11.Cu")
		(net "PVCCIN_CPU1_IMON7")
	)
	(segment
		(start 98.790506 -349.374714)
		(end 105.019856 -355.604064)
		(width 0.254)
		(layer "In11.Cu")
		(net "PVCCIN_CPU1_IMON7")
	)
	(segment
		(start 97.824798 -346.302076)
		(end 98.790506 -347.267784)
		(width 0.254)
		(layer "In11.Cu")
		(net "PVCCIN_CPU1_IMON7")
	)
	(segment
		(start 105.589832 -355.604064)
		(end 107.285282 -353.908614)
		(width 0.254)
		(layer "In11.Cu")
		(net "PVCCIN_CPU1_IMON7")
	)
	(segment
		(start 110.442502 -353.908614)
		(end 110.862618 -353.488498)
		(width 0.254)
		(layer "In11.Cu")
		(net "PVCCIN_CPU1_IMON7")
	)
	(segment
		(start 84.591652 -349.24746)
		(end 87.537036 -346.302076)
		(width 0.254)
		(layer "In11.Cu")
		(net "PVCCIN_CPU1_IMON7")
	)
	(segment
		(start 109.178344 -354.123244)
		(end 109.178344 -355.97338)
		(width 0.1778)
		(layer "F.Cu")
		(net "PVCCIN_CPU1_IMON6")
	)
	(segment
		(start 87.29726 -340.360508)
		(end 87.29726 -340.026244)
		(width 0.254)
		(layer "F.Cu")
		(net "PVCCIN_CPU1_IMON6")
	)
	(segment
		(start 109.789722 -353.511866)
		(end 109.178344 -354.123244)
		(width 0.1778)
		(layer "F.Cu")
		(net "PVCCIN_CPU1_IMON6")
	)
	(segment
		(start 109.789722 -353.482656)
		(end 109.789722 -353.511866)
		(width 0.1778)
		(layer "F.Cu")
		(net "PVCCIN_CPU1_IMON6")
	)
	(segment
		(start 86.860126 -340.872318)
		(end 86.860126 -340.797642)
		(width 0.254)
		(layer "F.Cu")
		(net "PVCCIN_CPU1_IMON6")
	)
	(segment
		(start 110.94212 -352.396298)
		(end 110.87608 -352.396298)
		(width 0.1778)
		(layer "F.Cu")
		(net "PVCCIN_CPU1_IMON6")
	)
	(segment
		(start 86.860126 -340.797642)
		(end 87.29726 -340.360508)
		(width 0.254)
		(layer "F.Cu")
		(net "PVCCIN_CPU1_IMON6")
	)
	(segment
		(start 110.87608 -352.396298)
		(end 109.789722 -353.482656)
		(width 0.1778)
		(layer "F.Cu")
		(net "PVCCIN_CPU1_IMON6")
	)
	(via
		(at 110.94212 -352.396298)
		(size 0.508)
		(drill 0.254)
		(layers "F.Cu" "B.Cu")
		(net "PVCCIN_CPU1_IMON6")
	)
	(via
		(at 86.860126 -340.872318)
		(size 0.508)
		(drill 0.254)
		(layers "F.Cu" "B.Cu")
		(net "PVCCIN_CPU1_IMON6")
	)
	(via
		(at 109.789722 -353.511866)
		(size 0.762)
		(drill 0.381)
		(layers "F.Cu" "B.Cu")
		(net "PVCCIN_CPU1_IMON6")
	)
	(segment
		(start 101.681026 -350.937068)
		(end 101.681026 -343.20988)
		(width 0.254)
		(layer "In11.Cu")
		(net "PVCCIN_CPU1_IMON6")
	)
	(segment
		(start 110.94212 -352.396298)
		(end 109.769656 -352.396298)
		(width 0.254)
		(layer "In11.Cu")
		(net "PVCCIN_CPU1_IMON6")
	)
	(segment
		(start 91.484958 -343.928446)
		(end 88.2142 -343.928446)
		(width 0.254)
		(layer "In11.Cu")
		(net "PVCCIN_CPU1_IMON6")
	)
	(segment
		(start 100.388928 -341.917782)
		(end 93.495622 -341.917782)
		(width 0.254)
		(layer "In11.Cu")
		(net "PVCCIN_CPU1_IMON6")
	)
	(segment
		(start 103.700326 -352.956368)
		(end 101.681026 -350.937068)
		(width 0.254)
		(layer "In11.Cu")
		(net "PVCCIN_CPU1_IMON6")
	)
	(segment
		(start 109.209586 -352.956368)
		(end 103.700326 -352.956368)
		(width 0.254)
		(layer "In11.Cu")
		(net "PVCCIN_CPU1_IMON6")
	)
	(segment
		(start 87.441278 -341.45347)
		(end 86.860126 -340.872318)
		(width 0.254)
		(layer "In11.Cu")
		(net "PVCCIN_CPU1_IMON6")
	)
	(segment
		(start 87.441278 -343.155524)
		(end 87.441278 -341.45347)
		(width 0.254)
		(layer "In11.Cu")
		(net "PVCCIN_CPU1_IMON6")
	)
	(segment
		(start 101.681026 -343.20988)
		(end 100.388928 -341.917782)
		(width 0.254)
		(layer "In11.Cu")
		(net "PVCCIN_CPU1_IMON6")
	)
	(segment
		(start 93.495622 -341.917782)
		(end 91.484958 -343.928446)
		(width 0.254)
		(layer "In11.Cu")
		(net "PVCCIN_CPU1_IMON6")
	)
	(segment
		(start 88.2142 -343.928446)
		(end 87.441278 -343.155524)
		(width 0.254)
		(layer "In11.Cu")
		(net "PVCCIN_CPU1_IMON6")
	)
	(segment
		(start 109.769656 -352.396298)
		(end 109.209586 -352.956368)
		(width 0.254)
		(layer "In11.Cu")
		(net "PVCCIN_CPU1_IMON6")
	)
	(segment
		(start 111.51362 -351.457768)
		(end 110.60303 -351.457768)
		(width 0.1778)
		(layer "F.Cu")
		(net "PVCCIN_CPU1_IMON5")
	)
	(segment
		(start 127.662686 -340.797642)
		(end 128.09982 -340.360508)
		(width 0.254)
		(layer "F.Cu")
		(net "PVCCIN_CPU1_IMON5")
	)
	(segment
		(start 110.60303 -351.457768)
		(end 108.778294 -353.282504)
		(width 0.1778)
		(layer "F.Cu")
		(net "PVCCIN_CPU1_IMON5")
	)
	(segment
		(start 127.662686 -340.872318)
		(end 127.662686 -340.797642)
		(width 0.254)
		(layer "F.Cu")
		(net "PVCCIN_CPU1_IMON5")
	)
	(segment
		(start 108.778294 -353.282504)
		(end 108.778294 -355.97338)
		(width 0.1778)
		(layer "F.Cu")
		(net "PVCCIN_CPU1_IMON5")
	)
	(segment
		(start 128.09982 -340.360508)
		(end 128.09982 -340.026244)
		(width 0.254)
		(layer "F.Cu")
		(net "PVCCIN_CPU1_IMON5")
	)
	(via
		(at 111.51362 -351.457768)
		(size 0.508)
		(drill 0.254)
		(layers "F.Cu" "B.Cu")
		(net "PVCCIN_CPU1_IMON5")
	)
	(via
		(at 127.662686 -340.872318)
		(size 0.508)
		(drill 0.254)
		(layers "F.Cu" "B.Cu")
		(net "PVCCIN_CPU1_IMON5")
	)
	(segment
		(start 111.904526 -350.156272)
		(end 114.290094 -350.156272)
		(width 0.254)
		(layer "In11.Cu")
		(net "PVCCIN_CPU1_IMON5")
	)
	(segment
		(start 117.6528 -346.793566)
		(end 125.251972 -346.793566)
		(width 0.254)
		(layer "In11.Cu")
		(net "PVCCIN_CPU1_IMON5")
	)
	(segment
		(start 128.313688 -341.52332)
		(end 127.662686 -340.872318)
		(width 0.254)
		(layer "In11.Cu")
		(net "PVCCIN_CPU1_IMON5")
	)
	(segment
		(start 114.290094 -350.156272)
		(end 117.6528 -346.793566)
		(width 0.254)
		(layer "In11.Cu")
		(net "PVCCIN_CPU1_IMON5")
	)
	(segment
		(start 128.313688 -343.73185)
		(end 128.313688 -341.52332)
		(width 0.254)
		(layer "In11.Cu")
		(net "PVCCIN_CPU1_IMON5")
	)
	(segment
		(start 111.51362 -350.547178)
		(end 111.904526 -350.156272)
		(width 0.254)
		(layer "In11.Cu")
		(net "PVCCIN_CPU1_IMON5")
	)
	(segment
		(start 125.251972 -346.793566)
		(end 128.313688 -343.73185)
		(width 0.254)
		(layer "In11.Cu")
		(net "PVCCIN_CPU1_IMON5")
	)
	(segment
		(start 111.51362 -351.457768)
		(end 111.51362 -350.547178)
		(width 0.254)
		(layer "In11.Cu")
		(net "PVCCIN_CPU1_IMON5")
	)
	(segment
		(start 108.378498 -352.42373)
		(end 108.378498 -355.97338)
		(width 0.1778)
		(layer "F.Cu")
		(net "PVCCIN_CPU1_IMON4")
	)
	(segment
		(start 119.502174 -337.387438)
		(end 119.939308 -336.950304)
		(width 0.254)
		(layer "F.Cu")
		(net "PVCCIN_CPU1_IMON4")
	)
	(segment
		(start 119.939308 -336.950304)
		(end 119.939308 -336.61604)
		(width 0.254)
		(layer "F.Cu")
		(net "PVCCIN_CPU1_IMON4")
	)
	(segment
		(start 119.502174 -337.462114)
		(end 119.502174 -337.387438)
		(width 0.254)
		(layer "F.Cu")
		(net "PVCCIN_CPU1_IMON4")
	)
	(segment
		(start 109.30128 -351.500948)
		(end 108.378498 -352.42373)
		(width 0.1778)
		(layer "F.Cu")
		(net "PVCCIN_CPU1_IMON4")
	)
	(via
		(at 109.30128 -351.500948)
		(size 0.762)
		(drill 0.254)
		(layers "F.Cu" "B.Cu")
		(net "PVCCIN_CPU1_IMON4")
	)
	(via
		(at 119.502174 -337.462114)
		(size 0.508)
		(drill 0.254)
		(layers "F.Cu" "B.Cu")
		(net "PVCCIN_CPU1_IMON4")
	)
	(segment
		(start 117.41912 -342.68791)
		(end 117.41912 -344.91422)
		(width 0.254)
		(layer "In11.Cu")
		(net "PVCCIN_CPU1_IMON4")
	)
	(segment
		(start 111.376206 -348.39275)
		(end 109.30128 -350.467676)
		(width 0.254)
		(layer "In11.Cu")
		(net "PVCCIN_CPU1_IMON4")
	)
	(segment
		(start 119.623078 -337.462114)
		(end 120.027446 -337.866482)
		(width 0.254)
		(layer "In11.Cu")
		(net "PVCCIN_CPU1_IMON4")
	)
	(segment
		(start 119.502174 -337.462114)
		(end 119.623078 -337.462114)
		(width 0.254)
		(layer "In11.Cu")
		(net "PVCCIN_CPU1_IMON4")
	)
	(segment
		(start 120.027446 -337.866482)
		(end 120.027446 -340.079584)
		(width 0.254)
		(layer "In11.Cu")
		(net "PVCCIN_CPU1_IMON4")
	)
	(segment
		(start 109.30128 -350.467676)
		(end 109.30128 -351.500948)
		(width 0.254)
		(layer "In11.Cu")
		(net "PVCCIN_CPU1_IMON4")
	)
	(segment
		(start 117.41912 -344.91422)
		(end 113.94059 -348.39275)
		(width 0.254)
		(layer "In11.Cu")
		(net "PVCCIN_CPU1_IMON4")
	)
	(segment
		(start 120.027446 -340.079584)
		(end 117.41912 -342.68791)
		(width 0.254)
		(layer "In11.Cu")
		(net "PVCCIN_CPU1_IMON4")
	)
	(segment
		(start 113.94059 -348.39275)
		(end 111.376206 -348.39275)
		(width 0.254)
		(layer "In11.Cu")
		(net "PVCCIN_CPU1_IMON4")
	)
	(segment
		(start 108.28528 -351.500948)
		(end 108.28528 -351.50298)
		(width 0.1778)
		(layer "F.Cu")
		(net "PVCCIN_CPU1_IMON3")
	)
	(segment
		(start 111.341662 -337.387438)
		(end 111.778796 -336.950304)
		(width 0.254)
		(layer "F.Cu")
		(net "PVCCIN_CPU1_IMON3")
	)
	(segment
		(start 107.978448 -351.809812)
		(end 107.978448 -355.97338)
		(width 0.1778)
		(layer "F.Cu")
		(net "PVCCIN_CPU1_IMON3")
	)
	(segment
		(start 108.28528 -351.50298)
		(end 107.978448 -351.809812)
		(width 0.1778)
		(layer "F.Cu")
		(net "PVCCIN_CPU1_IMON3")
	)
	(segment
		(start 111.341662 -337.462114)
		(end 111.341662 -337.387438)
		(width 0.254)
		(layer "F.Cu")
		(net "PVCCIN_CPU1_IMON3")
	)
	(segment
		(start 111.778796 -336.950304)
		(end 111.778796 -336.61604)
		(width 0.254)
		(layer "F.Cu")
		(net "PVCCIN_CPU1_IMON3")
	)
	(via
		(at 108.28528 -351.500948)
		(size 0.508)
		(drill 0.254)
		(layers "F.Cu" "B.Cu")
		(net "PVCCIN_CPU1_IMON3")
	)
	(via
		(at 111.341662 -337.462114)
		(size 0.508)
		(drill 0.254)
		(layers "F.Cu" "B.Cu")
		(net "PVCCIN_CPU1_IMON3")
	)
	(segment
		(start 111.937292 -339.775546)
		(end 110.721394 -340.991444)
		(width 0.254)
		(layer "In11.Cu")
		(net "PVCCIN_CPU1_IMON3")
	)
	(segment
		(start 111.341662 -337.462114)
		(end 111.937292 -338.057744)
		(width 0.254)
		(layer "In11.Cu")
		(net "PVCCIN_CPU1_IMON3")
	)
	(segment
		(start 110.721394 -346.88145)
		(end 108.28528 -349.317564)
		(width 0.254)
		(layer "In11.Cu")
		(net "PVCCIN_CPU1_IMON3")
	)
	(segment
		(start 111.937292 -338.057744)
		(end 111.937292 -339.775546)
		(width 0.254)
		(layer "In11.Cu")
		(net "PVCCIN_CPU1_IMON3")
	)
	(segment
		(start 110.721394 -340.991444)
		(end 110.721394 -346.88145)
		(width 0.254)
		(layer "In11.Cu")
		(net "PVCCIN_CPU1_IMON3")
	)
	(segment
		(start 108.28528 -349.317564)
		(end 108.28528 -351.500948)
		(width 0.254)
		(layer "In11.Cu")
		(net "PVCCIN_CPU1_IMON3")
	)
	(segment
		(start 103.18115 -337.387438)
		(end 103.618284 -336.950304)
		(width 0.254)
		(layer "F.Cu")
		(net "PVCCIN_CPU1_IMON2")
	)
	(segment
		(start 103.18115 -337.462114)
		(end 103.18115 -337.387438)
		(width 0.254)
		(layer "F.Cu")
		(net "PVCCIN_CPU1_IMON2")
	)
	(segment
		(start 103.618284 -336.950304)
		(end 103.618284 -336.61604)
		(width 0.254)
		(layer "F.Cu")
		(net "PVCCIN_CPU1_IMON2")
	)
	(segment
		(start 107.26928 -351.500948)
		(end 107.578398 -351.810066)
		(width 0.1778)
		(layer "F.Cu")
		(net "PVCCIN_CPU1_IMON2")
	)
	(segment
		(start 107.578398 -351.810066)
		(end 107.578398 -355.97338)
		(width 0.1778)
		(layer "F.Cu")
		(net "PVCCIN_CPU1_IMON2")
	)
	(via
		(at 103.18115 -337.462114)
		(size 0.508)
		(drill 0.254)
		(layers "F.Cu" "B.Cu")
		(net "PVCCIN_CPU1_IMON2")
	)
	(via
		(at 107.26928 -351.500948)
		(size 0.508)
		(drill 0.254)
		(layers "F.Cu" "B.Cu")
		(net "PVCCIN_CPU1_IMON2")
	)
	(segment
		(start 103.831644 -339.424264)
		(end 103.831644 -338.112608)
		(width 0.254)
		(layer "In11.Cu")
		(net "PVCCIN_CPU1_IMON2")
	)
	(segment
		(start 108.31449 -346.580968)
		(end 108.31449 -346.579444)
		(width 0.254)
		(layer "In11.Cu")
		(net "PVCCIN_CPU1_IMON2")
	)
	(segment
		(start 109.07014 -343.1413)
		(end 106.125264 -340.196424)
		(width 0.254)
		(layer "In11.Cu")
		(net "PVCCIN_CPU1_IMON2")
	)
	(segment
		(start 109.07014 -345.823794)
		(end 109.07014 -343.1413)
		(width 0.254)
		(layer "In11.Cu")
		(net "PVCCIN_CPU1_IMON2")
	)
	(segment
		(start 107.26928 -347.626178)
		(end 108.31449 -346.580968)
		(width 0.254)
		(layer "In11.Cu")
		(net "PVCCIN_CPU1_IMON2")
	)
	(segment
		(start 108.31449 -346.579444)
		(end 109.07014 -345.823794)
		(width 0.254)
		(layer "In11.Cu")
		(net "PVCCIN_CPU1_IMON2")
	)
	(segment
		(start 104.603804 -340.196424)
		(end 103.831644 -339.424264)
		(width 0.254)
		(layer "In11.Cu")
		(net "PVCCIN_CPU1_IMON2")
	)
	(segment
		(start 106.125264 -340.196424)
		(end 104.603804 -340.196424)
		(width 0.254)
		(layer "In11.Cu")
		(net "PVCCIN_CPU1_IMON2")
	)
	(segment
		(start 107.26928 -351.500948)
		(end 107.26928 -347.626178)
		(width 0.254)
		(layer "In11.Cu")
		(net "PVCCIN_CPU1_IMON2")
	)
	(segment
		(start 103.831644 -338.112608)
		(end 103.18115 -337.462114)
		(width 0.254)
		(layer "In11.Cu")
		(net "PVCCIN_CPU1_IMON2")
	)
	(segment
		(start 95.020638 -337.387438)
		(end 95.457772 -336.950304)
		(width 0.254)
		(layer "F.Cu")
		(net "PVCCIN_CPU1_IMON1")
	)
	(segment
		(start 95.457772 -336.950304)
		(end 95.457772 -336.61604)
		(width 0.254)
		(layer "F.Cu")
		(net "PVCCIN_CPU1_IMON1")
	)
	(segment
		(start 107.178348 -352.426016)
		(end 107.178348 -355.97338)
		(width 0.1778)
		(layer "F.Cu")
		(net "PVCCIN_CPU1_IMON1")
	)
	(segment
		(start 95.020638 -337.462114)
		(end 95.020638 -337.387438)
		(width 0.254)
		(layer "F.Cu")
		(net "PVCCIN_CPU1_IMON1")
	)
	(segment
		(start 106.25328 -351.500948)
		(end 107.178348 -352.426016)
		(width 0.1778)
		(layer "F.Cu")
		(net "PVCCIN_CPU1_IMON1")
	)
	(via
		(at 106.25328 -351.500948)
		(size 0.508)
		(drill 0.254)
		(layers "F.Cu" "B.Cu")
		(net "PVCCIN_CPU1_IMON1")
	)
	(via
		(at 95.020638 -337.462114)
		(size 0.508)
		(drill 0.254)
		(layers "F.Cu" "B.Cu")
		(net "PVCCIN_CPU1_IMON1")
	)
	(segment
		(start 103.183182 -342.458548)
		(end 100.439728 -339.715094)
		(width 0.254)
		(layer "In11.Cu")
		(net "PVCCIN_CPU1_IMON1")
	)
	(segment
		(start 95.825818 -339.715094)
		(end 95.571818 -339.461094)
		(width 0.254)
		(layer "In11.Cu")
		(net "PVCCIN_CPU1_IMON1")
	)
	(segment
		(start 103.183182 -345.632024)
		(end 103.183182 -342.458548)
		(width 0.254)
		(layer "In11.Cu")
		(net "PVCCIN_CPU1_IMON1")
	)
	(segment
		(start 95.571818 -339.461094)
		(end 95.571818 -338.013294)
		(width 0.254)
		(layer "In11.Cu")
		(net "PVCCIN_CPU1_IMON1")
	)
	(segment
		(start 106.25328 -348.702122)
		(end 103.183182 -345.632024)
		(width 0.254)
		(layer "In11.Cu")
		(net "PVCCIN_CPU1_IMON1")
	)
	(segment
		(start 106.25328 -351.500948)
		(end 106.25328 -348.702122)
		(width 0.254)
		(layer "In11.Cu")
		(net "PVCCIN_CPU1_IMON1")
	)
	(segment
		(start 95.571818 -338.013294)
		(end 95.020638 -337.462114)
		(width 0.254)
		(layer "In11.Cu")
		(net "PVCCIN_CPU1_IMON1")
	)
	(segment
		(start 100.439728 -339.715094)
		(end 95.825818 -339.715094)
		(width 0.254)
		(layer "In11.Cu")
		(net "PVCCIN_CPU1_IMON1")
	)
	(segment
		(start 104.371648 -360.184446)
		(end 105.10774 -359.448354)
		(width 0.1778)
		(layer "F.Cu")
		(net "PVCCIN_CPU1_EN_R")
	)
	(segment
		(start 104.371648 -360.216958)
		(end 104.371648 -360.184446)
		(width 0.1778)
		(layer "F.Cu")
		(net "PVCCIN_CPU1_EN_R")
	)
	(segment
		(start 105.10774 -359.448354)
		(end 105.70337 -359.448354)
		(width 0.1778)
		(layer "F.Cu")
		(net "PVCCIN_CPU1_EN_R")
	)
	(via
		(at 104.371648 -360.216958)
		(size 0.508)
		(drill 0.254)
		(layers "F.Cu" "B.Cu")
		(net "PVCCIN_CPU1_EN_R")
	)
	(via
		(at 105.627424 -360.751882)
		(size 0.6604)
		(drill 0.3302)
		(layers "F.Cu" "B.Cu")
		(net "PVCCIN_CPU1_EN_R")
	)
	(segment
		(start 105.627424 -360.751882)
		(end 105.881424 -360.497882)
		(width 0.254)
		(layer "B.Cu")
		(net "PVCCIN_CPU1_EN_R")
	)
	(segment
		(start 105.881424 -360.497882)
		(end 105.881424 -359.47985)
		(width 0.254)
		(layer "B.Cu")
		(net "PVCCIN_CPU1_EN_R")
	)
	(segment
		(start 104.409748 -360.216958)
		(end 104.944672 -360.751882)
		(width 0.254)
		(layer "B.Cu")
		(net "PVCCIN_CPU1_EN_R")
	)
	(segment
		(start 104.371648 -360.216958)
		(end 104.409748 -360.216958)
		(width 0.254)
		(layer "B.Cu")
		(net "PVCCIN_CPU1_EN_R")
	)
	(segment
		(start 104.944672 -360.751882)
		(end 105.627424 -360.751882)
		(width 0.254)
		(layer "B.Cu")
		(net "PVCCIN_CPU1_EN_R")
	)
	(segment
		(start 105.881424 -358.640126)
		(end 105.696258 -358.45496)
		(width 0.254)
		(layer "B.Cu")
		(net "PVCCIN_CPU1_EN_R")
	)
	(segment
		(start 105.881424 -359.47985)
		(end 105.881424 -358.640126)
		(width 0.254)
		(layer "B.Cu")
		(net "PVCCIN_CPU1_EN_R")
	)
	(segment
		(start 113.213642 -360.61142)
		(end 113.644934 -360.61142)
		(width 0.1778)
		(layer "F.Cu")
		(net "PVCCIN_CPU1_CSPIN")
	)
	(segment
		(start 112.170718 -359.848404)
		(end 112.933734 -360.61142)
		(width 0.1778)
		(layer "F.Cu")
		(net "PVCCIN_CPU1_CSPIN")
	)
	(segment
		(start 113.644934 -360.61142)
		(end 114.306604 -359.94975)
		(width 0.1778)
		(layer "F.Cu")
		(net "PVCCIN_CPU1_CSPIN")
	)
	(segment
		(start 112.933734 -360.61142)
		(end 113.213642 -360.61142)
		(width 0.1778)
		(layer "F.Cu")
		(net "PVCCIN_CPU1_CSPIN")
	)
	(segment
		(start 111.453422 -359.848404)
		(end 112.170718 -359.848404)
		(width 0.1778)
		(layer "F.Cu")
		(net "PVCCIN_CPU1_CSPIN")
	)
	(via
		(at 113.213642 -360.61142)
		(size 0.508)
		(drill 0.254)
		(layers "F.Cu" "B.Cu")
		(net "PVCCIN_CPU1_CSPIN")
	)
	(segment
		(start 111.767366 -359.47985)
		(end 111.266986 -359.47985)
		(width 0.254)
		(layer "B.Cu")
		(net "PVCCIN_CPU1_CSPIN")
	)
	(segment
		(start 112.797336 -360.50982)
		(end 111.767366 -359.47985)
		(width 0.254)
		(layer "B.Cu")
		(net "PVCCIN_CPU1_CSPIN")
	)
	(segment
		(start 113.112042 -360.50982)
		(end 112.797336 -360.50982)
		(width 0.254)
		(layer "B.Cu")
		(net "PVCCIN_CPU1_CSPIN")
	)
	(segment
		(start 113.315242 -360.61142)
		(end 113.213642 -360.61142)
		(width 0.254)
		(layer "B.Cu")
		(net "PVCCIN_CPU1_CSPIN")
	)
	(segment
		(start 113.521998 -360.818176)
		(end 113.315242 -360.61142)
		(width 0.254)
		(layer "B.Cu")
		(net "PVCCIN_CPU1_CSPIN")
	)
	(segment
		(start 113.213642 -360.61142)
		(end 113.112042 -360.50982)
		(width 0.254)
		(layer "B.Cu")
		(net "PVCCIN_CPU1_CSPIN")
	)
	(segment
		(start 114.374676 -360.818176)
		(end 113.521998 -360.818176)
		(width 0.254)
		(layer "B.Cu")
		(net "PVCCIN_CPU1_CSPIN")
	)
	(segment
		(start 136.854438 -346.850462)
		(end 136.854692 -346.850208)
		(width 0.254)
		(layer "F.Cu")
		(net "PVCCIN_CPU1_ATSEN")
	)
	(segment
		(start 88.197182 -340.321392)
		(end 88.197182 -340.026244)
		(width 0.254)
		(layer "F.Cu")
		(net "PVCCIN_CPU1_ATSEN")
	)
	(segment
		(start 96.357694 -336.911188)
		(end 96.357694 -336.61604)
		(width 0.254)
		(layer "F.Cu")
		(net "PVCCIN_CPU1_ATSEN")
	)
	(segment
		(start 79.730854 -346.850462)
		(end 79.715614 -346.850462)
		(width 0.254)
		(layer "F.Cu")
		(net "PVCCIN_CPU1_ATSEN")
	)
	(segment
		(start 112.372902 -337.649566)
		(end 112.373156 -337.649312)
		(width 0.254)
		(layer "F.Cu")
		(net "PVCCIN_CPU1_ATSEN")
	)
	(segment
		(start 120.518174 -337.649566)
		(end 120.533414 -337.649566)
		(width 0.254)
		(layer "F.Cu")
		(net "PVCCIN_CPU1_ATSEN")
	)
	(segment
		(start 137.160254 -346.112084)
		(end 137.160254 -345.816936)
		(width 0.254)
		(layer "F.Cu")
		(net "PVCCIN_CPU1_ATSEN")
	)
	(segment
		(start 112.990376 -358.576626)
		(end 112.518698 -359.048304)
		(width 0.1778)
		(layer "F.Cu")
		(net "PVCCIN_CPU1_ATSEN")
	)
	(segment
		(start 96.051878 -337.649566)
		(end 96.052132 -337.649312)
		(width 0.254)
		(layer "F.Cu")
		(net "PVCCIN_CPU1_ATSEN")
	)
	(segment
		(start 112.678718 -336.911188)
		(end 112.678718 -336.61604)
		(width 0.254)
		(layer "F.Cu")
		(net "PVCCIN_CPU1_ATSEN")
	)
	(segment
		(start 114.306604 -357.91775)
		(end 113.647728 -358.576626)
		(width 0.12954)
		(layer "F.Cu")
		(net "PVCCIN_CPU1_ATSEN")
	)
	(segment
		(start 87.89162 -341.059516)
		(end 88.197182 -340.321392)
		(width 0.254)
		(layer "F.Cu")
		(net "PVCCIN_CPU1_ATSEN")
	)
	(segment
		(start 79.731108 -346.850208)
		(end 79.730854 -346.850462)
		(width 0.254)
		(layer "F.Cu")
		(net "PVCCIN_CPU1_ATSEN")
	)
	(segment
		(start 112.518698 -359.048304)
		(end 111.453422 -359.048304)
		(width 0.1778)
		(layer "F.Cu")
		(net "PVCCIN_CPU1_ATSEN")
	)
	(segment
		(start 87.876126 -341.05977)
		(end 87.891366 -341.05977)
		(width 0.254)
		(layer "F.Cu")
		(net "PVCCIN_CPU1_ATSEN")
	)
	(segment
		(start 80.03667 -346.112084)
		(end 79.731108 -346.850208)
		(width 0.254)
		(layer "F.Cu")
		(net "PVCCIN_CPU1_ATSEN")
	)
	(segment
		(start 128.678686 -341.05977)
		(end 128.693926 -341.05977)
		(width 0.254)
		(layer "F.Cu")
		(net "PVCCIN_CPU1_ATSEN")
	)
	(segment
		(start 120.83923 -336.911188)
		(end 120.83923 -336.61604)
		(width 0.254)
		(layer "F.Cu")
		(net "PVCCIN_CPU1_ATSEN")
	)
	(segment
		(start 80.03667 -345.816936)
		(end 80.03667 -346.112084)
		(width 0.254)
		(layer "F.Cu")
		(net "PVCCIN_CPU1_ATSEN")
	)
	(segment
		(start 104.518206 -336.911188)
		(end 104.518206 -336.61604)
		(width 0.254)
		(layer "F.Cu")
		(net "PVCCIN_CPU1_ATSEN")
	)
	(segment
		(start 128.69418 -341.059516)
		(end 128.999742 -340.321392)
		(width 0.254)
		(layer "F.Cu")
		(net "PVCCIN_CPU1_ATSEN")
	)
	(segment
		(start 120.533668 -337.649312)
		(end 120.83923 -336.911188)
		(width 0.254)
		(layer "F.Cu")
		(net "PVCCIN_CPU1_ATSEN")
	)
	(segment
		(start 128.999742 -340.321392)
		(end 128.999742 -340.026244)
		(width 0.254)
		(layer "F.Cu")
		(net "PVCCIN_CPU1_ATSEN")
	)
	(segment
		(start 96.052132 -337.649312)
		(end 96.357694 -336.911188)
		(width 0.254)
		(layer "F.Cu")
		(net "PVCCIN_CPU1_ATSEN")
	)
	(segment
		(start 128.693926 -341.05977)
		(end 128.69418 -341.059516)
		(width 0.254)
		(layer "F.Cu")
		(net "PVCCIN_CPU1_ATSEN")
	)
	(segment
		(start 112.357662 -337.649566)
		(end 112.372902 -337.649566)
		(width 0.254)
		(layer "F.Cu")
		(net "PVCCIN_CPU1_ATSEN")
	)
	(segment
		(start 136.854692 -346.850208)
		(end 137.160254 -346.112084)
		(width 0.254)
		(layer "F.Cu")
		(net "PVCCIN_CPU1_ATSEN")
	)
	(segment
		(start 113.08842 -358.576626)
		(end 112.990376 -358.576626)
		(width 0.1778)
		(layer "F.Cu")
		(net "PVCCIN_CPU1_ATSEN")
	)
	(segment
		(start 113.647728 -358.576626)
		(end 113.08842 -358.576626)
		(width 0.12954)
		(layer "F.Cu")
		(net "PVCCIN_CPU1_ATSEN")
	)
	(segment
		(start 104.21239 -337.649566)
		(end 104.212644 -337.649312)
		(width 0.254)
		(layer "F.Cu")
		(net "PVCCIN_CPU1_ATSEN")
	)
	(segment
		(start 120.533414 -337.649566)
		(end 120.533668 -337.649312)
		(width 0.254)
		(layer "F.Cu")
		(net "PVCCIN_CPU1_ATSEN")
	)
	(segment
		(start 104.212644 -337.649312)
		(end 104.518206 -336.911188)
		(width 0.254)
		(layer "F.Cu")
		(net "PVCCIN_CPU1_ATSEN")
	)
	(segment
		(start 87.891366 -341.05977)
		(end 87.89162 -341.059516)
		(width 0.254)
		(layer "F.Cu")
		(net "PVCCIN_CPU1_ATSEN")
	)
	(segment
		(start 136.839198 -346.850462)
		(end 136.854438 -346.850462)
		(width 0.254)
		(layer "F.Cu")
		(net "PVCCIN_CPU1_ATSEN")
	)
	(segment
		(start 96.036638 -337.649566)
		(end 96.051878 -337.649566)
		(width 0.254)
		(layer "F.Cu")
		(net "PVCCIN_CPU1_ATSEN")
	)
	(segment
		(start 104.19715 -337.649566)
		(end 104.21239 -337.649566)
		(width 0.254)
		(layer "F.Cu")
		(net "PVCCIN_CPU1_ATSEN")
	)
	(segment
		(start 112.373156 -337.649312)
		(end 112.678718 -336.911188)
		(width 0.254)
		(layer "F.Cu")
		(net "PVCCIN_CPU1_ATSEN")
	)
	(via
		(at 104.19715 -337.649566)
		(size 0.508)
		(drill 0.254)
		(layers "F.Cu" "B.Cu")
		(net "PVCCIN_CPU1_ATSEN")
	)
	(via
		(at 112.357662 -337.649566)
		(size 0.508)
		(drill 0.254)
		(layers "F.Cu" "B.Cu")
		(net "PVCCIN_CPU1_ATSEN")
	)
	(via
		(at 96.036638 -337.649566)
		(size 0.508)
		(drill 0.254)
		(layers "F.Cu" "B.Cu")
		(net "PVCCIN_CPU1_ATSEN")
	)
	(via
		(at 79.715614 -346.850462)
		(size 0.508)
		(drill 0.254)
		(layers "F.Cu" "B.Cu")
		(net "PVCCIN_CPU1_ATSEN")
	)
	(via
		(at 120.518174 -337.649566)
		(size 0.508)
		(drill 0.254)
		(layers "F.Cu" "B.Cu")
		(net "PVCCIN_CPU1_ATSEN")
	)
	(via
		(at 113.08842 -358.576626)
		(size 0.508)
		(drill 0.254)
		(layers "F.Cu" "B.Cu")
		(net "PVCCIN_CPU1_ATSEN")
	)
	(via
		(at 128.678686 -341.05977)
		(size 0.508)
		(drill 0.254)
		(layers "F.Cu" "B.Cu")
		(net "PVCCIN_CPU1_ATSEN")
	)
	(via
		(at 136.839198 -346.850462)
		(size 0.508)
		(drill 0.254)
		(layers "F.Cu" "B.Cu")
		(net "PVCCIN_CPU1_ATSEN")
	)
	(via
		(at 87.876126 -341.05977)
		(size 0.508)
		(drill 0.254)
		(layers "F.Cu" "B.Cu")
		(net "PVCCIN_CPU1_ATSEN")
	)
	(segment
		(start 113.08842 -358.576626)
		(end 114.282982 -358.576626)
		(width 0.254)
		(layer "B.Cu")
		(net "PVCCIN_CPU1_ATSEN")
	)
	(segment
		(start 114.282982 -358.576626)
		(end 114.293396 -358.566212)
		(width 0.254)
		(layer "B.Cu")
		(net "PVCCIN_CPU1_ATSEN")
	)
	(segment
		(start 127.55753 -343.530174)
		(end 128.180338 -342.907366)
		(width 0.254)
		(layer "In4.Cu")
		(net "PVCCIN_CPU1_ATSEN")
	)
	(segment
		(start 87.876126 -341.05977)
		(end 87.876126 -342.483694)
		(width 0.254)
		(layer "In4.Cu")
		(net "PVCCIN_CPU1_ATSEN")
	)
	(segment
		(start 119.32666 -340.1441)
		(end 120.070118 -339.400642)
		(width 0.254)
		(layer "In4.Cu")
		(net "PVCCIN_CPU1_ATSEN")
	)
	(segment
		(start 128.678686 -343.455498)
		(end 130.27025 -345.047062)
		(width 0.254)
		(layer "In4.Cu")
		(net "PVCCIN_CPU1_ATSEN")
	)
	(segment
		(start 115.7351 -357.043228)
		(end 115.7351 -352.9965)
		(width 0.254)
		(layer "In4.Cu")
		(net "PVCCIN_CPU1_ATSEN")
	)
	(segment
		(start 112.103662 -337.754722)
		(end 112.357662 -337.649566)
		(width 0.254)
		(layer "In4.Cu")
		(net "PVCCIN_CPU1_ATSEN")
	)
	(segment
		(start 115.7351 -352.9965)
		(end 116.570252 -352.161348)
		(width 0.254)
		(layer "In4.Cu")
		(net "PVCCIN_CPU1_ATSEN")
	)
	(segment
		(start 103.071676 -340.130384)
		(end 103.752904 -339.449156)
		(width 0.254)
		(layer "In4.Cu")
		(net "PVCCIN_CPU1_ATSEN")
	)
	(segment
		(start 112.357662 -339.188044)
		(end 113.313718 -340.1441)
		(width 0.254)
		(layer "In4.Cu")
		(net "PVCCIN_CPU1_ATSEN")
	)
	(segment
		(start 113.08842 -358.576626)
		(end 113.218722 -358.706928)
		(width 0.254)
		(layer "In4.Cu")
		(net "PVCCIN_CPU1_ATSEN")
	)
	(segment
		(start 80.01 -345.684348)
		(end 80.560164 -345.684348)
		(width 0.254)
		(layer "In4.Cu")
		(net "PVCCIN_CPU1_ATSEN")
	)
	(segment
		(start 128.180338 -342.907366)
		(end 128.180338 -341.409274)
		(width 0.254)
		(layer "In4.Cu")
		(net "PVCCIN_CPU1_ATSEN")
	)
	(segment
		(start 105.139744 -340.130638)
		(end 111.08182 -340.130638)
		(width 0.254)
		(layer "In4.Cu")
		(net "PVCCIN_CPU1_ATSEN")
	)
	(segment
		(start 96.036638 -339.188044)
		(end 96.978978 -340.130384)
		(width 0.254)
		(layer "In4.Cu")
		(net "PVCCIN_CPU1_ATSEN")
	)
	(segment
		(start 120.518174 -339.188044)
		(end 122.211338 -340.881208)
		(width 0.254)
		(layer "In4.Cu")
		(net "PVCCIN_CPU1_ATSEN")
	)
	(segment
		(start 113.313718 -340.1441)
		(end 119.32666 -340.1441)
		(width 0.254)
		(layer "In4.Cu")
		(net "PVCCIN_CPU1_ATSEN")
	)
	(segment
		(start 85.839554 -347.60281)
		(end 86.557866 -346.884498)
		(width 0.254)
		(layer "In4.Cu")
		(net "PVCCIN_CPU1_ATSEN")
	)
	(segment
		(start 116.570252 -352.161348)
		(end 122.886724 -352.161348)
		(width 0.254)
		(layer "In4.Cu")
		(net "PVCCIN_CPU1_ATSEN")
	)
	(segment
		(start 96.036638 -337.649566)
		(end 96.036638 -339.188044)
		(width 0.254)
		(layer "In4.Cu")
		(net "PVCCIN_CPU1_ATSEN")
	)
	(segment
		(start 113.218722 -358.706928)
		(end 114.0714 -358.706928)
		(width 0.254)
		(layer "In4.Cu")
		(net "PVCCIN_CPU1_ATSEN")
	)
	(segment
		(start 95.604584 -337.884516)
		(end 95.699834 -337.789266)
		(width 0.254)
		(layer "In4.Cu")
		(net "PVCCIN_CPU1_ATSEN")
	)
	(segment
		(start 82.718402 -347.60281)
		(end 85.839554 -347.60281)
		(width 0.254)
		(layer "In4.Cu")
		(net "PVCCIN_CPU1_ATSEN")
	)
	(segment
		(start 111.08182 -340.130638)
		(end 111.942118 -339.27034)
		(width 0.254)
		(layer "In4.Cu")
		(net "PVCCIN_CPU1_ATSEN")
	)
	(segment
		(start 120.264174 -337.754722)
		(end 120.518174 -337.649566)
		(width 0.254)
		(layer "In4.Cu")
		(net "PVCCIN_CPU1_ATSEN")
	)
	(segment
		(start 128.180338 -341.409274)
		(end 128.424686 -341.164926)
		(width 0.254)
		(layer "In4.Cu")
		(net "PVCCIN_CPU1_ATSEN")
	)
	(segment
		(start 103.752904 -339.449156)
		(end 103.752904 -337.944968)
		(width 0.254)
		(layer "In4.Cu")
		(net "PVCCIN_CPU1_ATSEN")
	)
	(segment
		(start 123.139454 -340.881208)
		(end 125.78842 -343.530174)
		(width 0.254)
		(layer "In4.Cu")
		(net "PVCCIN_CPU1_ATSEN")
	)
	(segment
		(start 134.557008 -349.673926)
		(end 136.363456 -348.925642)
		(width 0.254)
		(layer "In4.Cu")
		(net "PVCCIN_CPU1_ATSEN")
	)
	(segment
		(start 80.560164 -345.684348)
		(end 80.969612 -345.85402)
		(width 0.254)
		(layer "In4.Cu")
		(net "PVCCIN_CPU1_ATSEN")
	)
	(segment
		(start 96.978978 -340.130384)
		(end 103.071676 -340.130384)
		(width 0.254)
		(layer "In4.Cu")
		(net "PVCCIN_CPU1_ATSEN")
	)
	(segment
		(start 103.752904 -337.944968)
		(end 103.94315 -337.754722)
		(width 0.254)
		(layer "In4.Cu")
		(net "PVCCIN_CPU1_ATSEN")
	)
	(segment
		(start 95.604584 -340.571328)
		(end 95.604584 -337.884516)
		(width 0.254)
		(layer "In4.Cu")
		(net "PVCCIN_CPU1_ATSEN")
	)
	(segment
		(start 128.678686 -341.05977)
		(end 128.678686 -343.455498)
		(width 0.254)
		(layer "In4.Cu")
		(net "PVCCIN_CPU1_ATSEN")
	)
	(segment
		(start 112.357662 -337.649566)
		(end 112.357662 -339.188044)
		(width 0.254)
		(layer "In4.Cu")
		(net "PVCCIN_CPU1_ATSEN")
	)
	(segment
		(start 136.363456 -348.925642)
		(end 136.839198 -348.4499)
		(width 0.254)
		(layer "In4.Cu")
		(net "PVCCIN_CPU1_ATSEN")
	)
	(segment
		(start 104.19715 -337.649566)
		(end 104.19715 -339.188044)
		(width 0.254)
		(layer "In4.Cu")
		(net "PVCCIN_CPU1_ATSEN")
	)
	(segment
		(start 88.6333 -343.240868)
		(end 92.935044 -343.240868)
		(width 0.254)
		(layer "In4.Cu")
		(net "PVCCIN_CPU1_ATSEN")
	)
	(segment
		(start 79.715614 -345.978734)
		(end 80.01 -345.684348)
		(width 0.254)
		(layer "In4.Cu")
		(net "PVCCIN_CPU1_ATSEN")
	)
	(segment
		(start 128.424686 -341.164926)
		(end 128.678686 -341.05977)
		(width 0.254)
		(layer "In4.Cu")
		(net "PVCCIN_CPU1_ATSEN")
	)
	(segment
		(start 125.78842 -343.530174)
		(end 127.55753 -343.530174)
		(width 0.254)
		(layer "In4.Cu")
		(net "PVCCIN_CPU1_ATSEN")
	)
	(segment
		(start 79.715614 -346.850462)
		(end 79.715614 -345.978734)
		(width 0.254)
		(layer "In4.Cu")
		(net "PVCCIN_CPU1_ATSEN")
	)
	(segment
		(start 114.0714 -358.706928)
		(end 115.7351 -357.043228)
		(width 0.254)
		(layer "In4.Cu")
		(net "PVCCIN_CPU1_ATSEN")
	)
	(segment
		(start 111.942118 -337.916266)
		(end 112.103662 -337.754722)
		(width 0.254)
		(layer "In4.Cu")
		(net "PVCCIN_CPU1_ATSEN")
	)
	(segment
		(start 120.070118 -339.400642)
		(end 120.070118 -337.948778)
		(width 0.254)
		(layer "In4.Cu")
		(net "PVCCIN_CPU1_ATSEN")
	)
	(segment
		(start 95.699834 -337.789266)
		(end 96.036638 -337.649566)
		(width 0.254)
		(layer "In4.Cu")
		(net "PVCCIN_CPU1_ATSEN")
	)
	(segment
		(start 103.94315 -337.754722)
		(end 104.19715 -337.649566)
		(width 0.254)
		(layer "In4.Cu")
		(net "PVCCIN_CPU1_ATSEN")
	)
	(segment
		(start 111.942118 -339.27034)
		(end 111.942118 -337.916266)
		(width 0.254)
		(layer "In4.Cu")
		(net "PVCCIN_CPU1_ATSEN")
	)
	(segment
		(start 120.070118 -337.948778)
		(end 120.264174 -337.754722)
		(width 0.254)
		(layer "In4.Cu")
		(net "PVCCIN_CPU1_ATSEN")
	)
	(segment
		(start 125.374146 -349.673926)
		(end 134.557008 -349.673926)
		(width 0.254)
		(layer "In4.Cu")
		(net "PVCCIN_CPU1_ATSEN")
	)
	(segment
		(start 86.557866 -346.884498)
		(end 86.557866 -343.789508)
		(width 0.254)
		(layer "In4.Cu")
		(net "PVCCIN_CPU1_ATSEN")
	)
	(segment
		(start 86.557866 -343.789508)
		(end 87.461598 -342.885776)
		(width 0.254)
		(layer "In4.Cu")
		(net "PVCCIN_CPU1_ATSEN")
	)
	(segment
		(start 136.839198 -348.4499)
		(end 136.839198 -346.850462)
		(width 0.254)
		(layer "In4.Cu")
		(net "PVCCIN_CPU1_ATSEN")
	)
	(segment
		(start 136.839198 -346.432378)
		(end 136.839198 -346.850462)
		(width 0.254)
		(layer "In4.Cu")
		(net "PVCCIN_CPU1_ATSEN")
	)
	(segment
		(start 120.518174 -337.649566)
		(end 120.518174 -339.188044)
		(width 0.254)
		(layer "In4.Cu")
		(net "PVCCIN_CPU1_ATSEN")
	)
	(segment
		(start 87.876126 -342.483694)
		(end 88.6333 -343.240868)
		(width 0.254)
		(layer "In4.Cu")
		(net "PVCCIN_CPU1_ATSEN")
	)
	(segment
		(start 130.27025 -345.047062)
		(end 135.453882 -345.047062)
		(width 0.254)
		(layer "In4.Cu")
		(net "PVCCIN_CPU1_ATSEN")
	)
	(segment
		(start 80.969612 -345.85402)
		(end 82.718402 -347.60281)
		(width 0.254)
		(layer "In4.Cu")
		(net "PVCCIN_CPU1_ATSEN")
	)
	(segment
		(start 135.453882 -345.047062)
		(end 136.839198 -346.432378)
		(width 0.254)
		(layer "In4.Cu")
		(net "PVCCIN_CPU1_ATSEN")
	)
	(segment
		(start 122.886724 -352.161348)
		(end 125.374146 -349.673926)
		(width 0.254)
		(layer "In4.Cu")
		(net "PVCCIN_CPU1_ATSEN")
	)
	(segment
		(start 122.211338 -340.881208)
		(end 123.139454 -340.881208)
		(width 0.254)
		(layer "In4.Cu")
		(net "PVCCIN_CPU1_ATSEN")
	)
	(segment
		(start 87.461598 -342.885776)
		(end 87.461598 -341.474298)
		(width 0.254)
		(layer "In4.Cu")
		(net "PVCCIN_CPU1_ATSEN")
	)
	(segment
		(start 87.461598 -341.474298)
		(end 87.876126 -341.05977)
		(width 0.254)
		(layer "In4.Cu")
		(net "PVCCIN_CPU1_ATSEN")
	)
	(segment
		(start 104.19715 -339.188044)
		(end 105.139744 -340.130638)
		(width 0.254)
		(layer "In4.Cu")
		(net "PVCCIN_CPU1_ATSEN")
	)
	(segment
		(start 92.935044 -343.240868)
		(end 95.604584 -340.571328)
		(width 0.254)
		(layer "In4.Cu")
		(net "PVCCIN_CPU1_ATSEN")
	)
	(segment
		(start 113.34242 -357.561388)
		(end 112.2553 -358.648508)
		(width 0.1778)
		(layer "F.Cu")
		(net "PVCCIN_CPU1_ADDR")
	)
	(segment
		(start 112.2553 -358.648508)
		(end 111.453422 -358.648508)
		(width 0.1778)
		(layer "F.Cu")
		(net "PVCCIN_CPU1_ADDR")
	)
	(via
		(at 113.34242 -357.561388)
		(size 0.508)
		(drill 0.254)
		(layers "F.Cu" "B.Cu")
		(net "PVCCIN_CPU1_ADDR")
	)
	(via
		(at 112.51438 -357.335328)
		(size 0.6604)
		(drill 0.3302)
		(layers "F.Cu" "B.Cu")
		(net "PVCCIN_CPU1_ADDR")
	)
	(segment
		(start 113.844324 -357.561388)
		(end 113.969546 -357.436166)
		(width 0.12954)
		(layer "B.Cu")
		(net "PVCCIN_CPU1_ADDR")
	)
	(segment
		(start 113.11636 -357.335328)
		(end 113.34242 -357.561388)
		(width 0.12954)
		(layer "B.Cu")
		(net "PVCCIN_CPU1_ADDR")
	)
	(segment
		(start 111.264446 -357.578406)
		(end 111.507524 -357.335328)
		(width 0.12954)
		(layer "B.Cu")
		(net "PVCCIN_CPU1_ADDR")
	)
	(segment
		(start 111.507524 -357.335328)
		(end 112.51438 -357.335328)
		(width 0.12954)
		(layer "B.Cu")
		(net "PVCCIN_CPU1_ADDR")
	)
	(segment
		(start 112.51438 -357.335328)
		(end 113.11636 -357.335328)
		(width 0.12954)
		(layer "B.Cu")
		(net "PVCCIN_CPU1_ADDR")
	)
	(segment
		(start 113.34242 -357.561388)
		(end 113.844324 -357.561388)
		(width 0.12954)
		(layer "B.Cu")
		(net "PVCCIN_CPU1_ADDR")
	)
	(segment
		(start 106.581448 -288.381186)
		(end 106.581448 -288.917126)
		(width 0.2032)
		(layer "F.Cu")
		(net "PVCCIN_CPU1")
	)
	(segment
		(start 109.400594 -288.381186)
		(end 109.400594 -288.993326)
		(width 0.254)
		(layer "F.Cu")
		(net "PVCCIN_CPU1")
	)
	(segment
		(start 109.290866 -239.853724)
		(end 109.29112 -239.85347)
		(width 0.2032)
		(layer "F.Cu")
		(net "PVCCIN_CPU1")
	)
	(segment
		(start 97.58553 -314.727082)
		(end 98.525838 -315.66739)
		(width 0.508)
		(layer "F.Cu")
		(net "PVCCIN_CPU1")
	)
	(segment
		(start 112.110266 -242.017042)
		(end 112.110266 -241.48161)
		(width 0.2032)
		(layer "F.Cu")
		(net "PVCCIN_CPU1")
	)
	(segment
		(start 112.220248 -268.84757)
		(end 112.220248 -269.38351)
		(width 0.2032)
		(layer "F.Cu")
		(net "PVCCIN_CPU1")
	)
	(segment
		(start 115.979448 -281.869896)
		(end 115.979448 -282.405582)
		(width 0.2032)
		(layer "F.Cu")
		(net "PVCCIN_CPU1")
	)
	(segment
		(start 113.989866 -242.017042)
		(end 113.989866 -241.48161)
		(width 0.2032)
		(layer "F.Cu")
		(net "PVCCIN_CPU1")
	)
	(segment
		(start 108.930694 -284.311598)
		(end 108.930694 -284.847538)
		(width 0.2032)
		(layer "F.Cu")
		(net "PVCCIN_CPU1")
	)
	(segment
		(start 113.159794 -276.986492)
		(end 113.159794 -277.522432)
		(width 0.2032)
		(layer "F.Cu")
		(net "PVCCIN_CPU1")
	)
	(segment
		(start 115.979448 -286.7533)
		(end 115.979448 -287.288986)
		(width 0.2032)
		(layer "F.Cu")
		(net "PVCCIN_CPU1")
	)
	(segment
		(start 122.356118 -316.607698)
		(end 123.296426 -315.66739)
		(width 0.508)
		(layer "F.Cu")
		(net "PVCCIN_CPU1")
	)
	(segment
		(start 110.810294 -268.56944)
		(end 110.810548 -268.569694)
		(width 0.2032)
		(layer "F.Cu")
		(net "PVCCIN_CPU1")
	)
	(segment
		(start 111.750094 -272.917158)
		(end 111.750094 -273.453098)
		(width 0.2032)
		(layer "F.Cu")
		(net "PVCCIN_CPU1")
	)
	(segment
		(start 111.170466 -239.853724)
		(end 111.17072 -239.85347)
		(width 0.2032)
		(layer "F.Cu")
		(net "PVCCIN_CPU1")
	)
	(segment
		(start 112.220248 -276.986492)
		(end 112.220248 -277.522432)
		(width 0.2032)
		(layer "F.Cu")
		(net "PVCCIN_CPU1")
	)
	(segment
		(start 115.039648 -283.497782)
		(end 115.039648 -284.033722)
		(width 0.2032)
		(layer "F.Cu")
		(net "PVCCIN_CPU1")
	)
	(segment
		(start 108.461048 -288.381186)
		(end 108.461048 -288.942526)
		(width 0.2032)
		(layer "F.Cu")
		(net "PVCCIN_CPU1")
	)
	(segment
		(start 113.629694 -277.800562)
		(end 113.629694 -278.336502)
		(width 0.254)
		(layer "F.Cu")
		(net "PVCCIN_CPU1")
	)
	(segment
		(start 106.111294 -287.567116)
		(end 106.111294 -288.103056)
		(width 0.2032)
		(layer "F.Cu")
		(net "PVCCIN_CPU1")
	)
	(segment
		(start 107.990894 -289.195002)
		(end 107.990894 -289.807142)
		(width 0.2032)
		(layer "F.Cu")
		(net "PVCCIN_CPU1")
	)
	(segment
		(start 112.220248 -283.497782)
		(end 112.220248 -284.033722)
		(width 0.2032)
		(layer "F.Cu")
		(net "PVCCIN_CPU1")
	)
	(segment
		(start 116.919248 -286.7533)
		(end 116.919248 -287.28924)
		(width 0.2032)
		(layer "F.Cu")
		(net "PVCCIN_CPU1")
	)
	(segment
		(start 109.400594 -262.872474)
		(end 109.400848 -262.872728)
		(width 0.2032)
		(layer "F.Cu")
		(net "PVCCIN_CPU1")
	)
	(segment
		(start 110.810294 -268.033754)
		(end 110.810294 -268.56944)
		(width 0.2032)
		(layer "F.Cu")
		(net "PVCCIN_CPU1")
	)
	(segment
		(start 109.760512 -241.203226)
		(end 109.760512 -240.667794)
		(width 0.2032)
		(layer "F.Cu")
		(net "PVCCIN_CPU1")
	)
	(segment
		(start 115.509294 -285.939484)
		(end 115.509294 -286.475424)
		(width 0.2032)
		(layer "F.Cu")
		(net "PVCCIN_CPU1")
	)
	(segment
		(start 118.328694 -289.195002)
		(end 118.328694 -289.807142)
		(width 0.2032)
		(layer "F.Cu")
		(net "PVCCIN_CPU1")
	)
	(segment
		(start 117.098826 -315.66739)
		(end 118.039134 -314.727082)
		(width 0.508)
		(layer "F.Cu")
		(net "PVCCIN_CPU1")
	)
	(segment
		(start 111.280448 -265.592306)
		(end 111.280448 -266.128246)
		(width 0.2032)
		(layer "F.Cu")
		(net "PVCCIN_CPU1")
	)
	(segment
		(start 115.509294 -287.567116)
		(end 115.509294 -288.103056)
		(width 0.2032)
		(layer "F.Cu")
		(net "PVCCIN_CPU1")
	)
	(segment
		(start 111.280448 -288.381186)
		(end 111.280448 -288.993326)
		(width 0.2032)
		(layer "F.Cu")
		(net "PVCCIN_CPU1")
	)
	(segment
		(start 105.641648 -285.125414)
		(end 105.641648 -285.661354)
		(width 0.2032)
		(layer "F.Cu")
		(net "PVCCIN_CPU1")
	)
	(segment
		(start 115.509294 -284.311598)
		(end 115.509294 -284.847538)
		(width 0.2032)
		(layer "F.Cu")
		(net "PVCCIN_CPU1")
	)
	(segment
		(start 111.280448 -286.7533)
		(end 111.280448 -287.28924)
		(width 0.2032)
		(layer "F.Cu")
		(net "PVCCIN_CPU1")
	)
	(segment
		(start 113.159794 -273.730974)
		(end 113.159794 -274.266914)
		(width 0.2032)
		(layer "F.Cu")
		(net "PVCCIN_CPU1")
	)
	(segment
		(start 110.810548 -263.150858)
		(end 110.810548 -263.686798)
		(width 0.2032)
		(layer "F.Cu")
		(net "PVCCIN_CPU1")
	)
	(segment
		(start 107.990894 -286.47517)
		(end 107.991148 -286.475424)
		(width 0.2032)
		(layer "F.Cu")
		(net "PVCCIN_CPU1")
	)
	(segment
		(start 107.990894 -281.591766)
		(end 107.991148 -281.59202)
		(width 0.2032)
		(layer "F.Cu")
		(net "PVCCIN_CPU1")
	)
	(segment
		(start 115.979448 -288.381186)
		(end 115.979448 -288.917126)
		(width 0.2032)
		(layer "F.Cu")
		(net "PVCCIN_CPU1")
	)
	(segment
		(start 116.449094 -281.05608)
		(end 116.449094 -281.59202)
		(width 0.2032)
		(layer "F.Cu")
		(net "PVCCIN_CPU1")
	)
	(segment
		(start 107.990894 -283.219652)
		(end 107.991148 -283.219906)
		(width 0.2032)
		(layer "F.Cu")
		(net "PVCCIN_CPU1")
	)
	(segment
		(start 123.296426 -315.66739)
		(end 124.236734 -314.727082)
		(width 0.508)
		(layer "F.Cu")
		(net "PVCCIN_CPU1")
	)
	(segment
		(start 112.689894 -266.405868)
		(end 112.689894 -266.941808)
		(width 0.2032)
		(layer "F.Cu")
		(net "PVCCIN_CPU1")
	)
	(segment
		(start 103.78313 -316.607698)
		(end 104.723438 -315.66739)
		(width 0.508)
		(layer "F.Cu")
		(net "PVCCIN_CPU1")
	)
	(segment
		(start 112.579912 -239.57534)
		(end 112.579912 -239.040162)
		(width 0.2032)
		(layer "F.Cu")
		(net "PVCCIN_CPU1")
	)
	(segment
		(start 111.280448 -281.869896)
		(end 111.280448 -282.405836)
		(width 0.2032)
		(layer "F.Cu")
		(net "PVCCIN_CPU1")
	)
	(segment
		(start 112.579912 -241.203226)
		(end 112.579912 -240.667794)
		(width 0.2032)
		(layer "F.Cu")
		(net "PVCCIN_CPU1")
	)
	(segment
		(start 109.760512 -240.667794)
		(end 109.760766 -240.66754)
		(width 0.2032)
		(layer "F.Cu")
		(net "PVCCIN_CPU1")
	)
	(segment
		(start 110.810294 -273.452844)
		(end 110.810548 -273.453098)
		(width 0.2032)
		(layer "F.Cu")
		(net "PVCCIN_CPU1")
	)
	(segment
		(start 108.461048 -280.242264)
		(end 108.461048 -280.778204)
		(width 0.2032)
		(layer "F.Cu")
		(net "PVCCIN_CPU1")
	)
	(segment
		(start 110.810294 -266.941554)
		(end 110.810548 -266.941808)
		(width 0.2032)
		(layer "F.Cu")
		(net "PVCCIN_CPU1")
	)
	(segment
		(start 112.220248 -262.336534)
		(end 112.220248 -262.872474)
		(width 0.2032)
		(layer "F.Cu")
		(net "PVCCIN_CPU1")
	)
	(segment
		(start 114.569494 -282.683966)
		(end 114.569494 -283.219906)
		(width 0.2032)
		(layer "F.Cu")
		(net "PVCCIN_CPU1")
	)
	(segment
		(start 111.280448 -261.244842)
		(end 111.280702 -261.245096)
		(width 0.2032)
		(layer "F.Cu")
		(net "PVCCIN_CPU1")
	)
	(segment
		(start 111.750094 -269.66164)
		(end 111.750094 -270.19758)
		(width 0.2032)
		(layer "F.Cu")
		(net "PVCCIN_CPU1")
	)
	(segment
		(start 113.159794 -278.614378)
		(end 113.159794 -279.150318)
		(width 0.2032)
		(layer "F.Cu")
		(net "PVCCIN_CPU1")
	)
	(segment
		(start 111.280448 -270.475456)
		(end 111.280448 -271.011396)
		(width 0.2032)
		(layer "F.Cu")
		(net "PVCCIN_CPU1")
	)
	(segment
		(start 111.750094 -274.54479)
		(end 111.750094 -275.08073)
		(width 0.2032)
		(layer "F.Cu")
		(net "PVCCIN_CPU1")
	)
	(segment
		(start 110.810294 -263.150604)
		(end 110.810548 -263.150858)
		(width 0.2032)
		(layer "F.Cu")
		(net "PVCCIN_CPU1")
	)
	(segment
		(start 97.58553 -316.607698)
		(end 98.525838 -315.66739)
		(width 0.508)
		(layer "F.Cu")
		(net "PVCCIN_CPU1")
	)
	(segment
		(start 111.280448 -285.125414)
		(end 111.280448 -285.661354)
		(width 0.2032)
		(layer "F.Cu")
		(net "PVCCIN_CPU1")
	)
	(segment
		(start 114.099848 -277.522178)
		(end 114.099594 -277.522432)
		(width 0.2032)
		(layer "F.Cu")
		(net "PVCCIN_CPU1")
	)
	(segment
		(start 116.158518 -316.607698)
		(end 117.098826 -315.66739)
		(width 0.508)
		(layer "F.Cu")
		(net "PVCCIN_CPU1")
	)
	(segment
		(start 109.760512 -239.57534)
		(end 109.760512 -239.040162)
		(width 0.254)
		(layer "F.Cu")
		(net "PVCCIN_CPU1")
	)
	(segment
		(start 110.810294 -283.219652)
		(end 110.810548 -283.219906)
		(width 0.2032)
		(layer "F.Cu")
		(net "PVCCIN_CPU1")
	)
	(segment
		(start 117.388894 -289.195002)
		(end 117.388894 -289.807142)
		(width 0.2032)
		(layer "F.Cu")
		(net "PVCCIN_CPU1")
	)
	(segment
		(start 111.280448 -260.708902)
		(end 111.280448 -261.244842)
		(width 0.2032)
		(layer "F.Cu")
		(net "PVCCIN_CPU1")
	)
	(segment
		(start 112.220248 -263.96442)
		(end 112.220248 -264.50036)
		(width 0.2032)
		(layer "F.Cu")
		(net "PVCCIN_CPU1")
	)
	(segment
		(start 114.459766 -239.039908)
		(end 114.46002 -239.039654)
		(width 0.2032)
		(layer "F.Cu")
		(net "PVCCIN_CPU1")
	)
	(segment
		(start 118.328694 -287.567116)
		(end 118.328694 -288.103056)
		(width 0.2032)
		(layer "F.Cu")
		(net "PVCCIN_CPU1")
	)
	(segment
		(start 116.919248 -281.869896)
		(end 116.919248 -282.405836)
		(width 0.2032)
		(layer "F.Cu")
		(net "PVCCIN_CPU1")
	)
	(segment
		(start 113.159794 -263.96442)
		(end 113.159794 -264.50036)
		(width 0.2032)
		(layer "F.Cu")
		(net "PVCCIN_CPU1")
	)
	(segment
		(start 115.039648 -280.242264)
		(end 115.039648 -280.778204)
		(width 0.2032)
		(layer "F.Cu")
		(net "PVCCIN_CPU1")
	)
	(segment
		(start 107.051094 -284.311598)
		(end 107.051094 -284.847538)
		(width 0.2032)
		(layer "F.Cu")
		(net "PVCCIN_CPU1")
	)
	(segment
		(start 110.810294 -284.311598)
		(end 110.810294 -284.847284)
		(width 0.2032)
		(layer "F.Cu")
		(net "PVCCIN_CPU1")
	)
	(segment
		(start 114.459766 -241.203226)
		(end 114.459766 -240.667794)
		(width 0.2032)
		(layer "F.Cu")
		(net "PVCCIN_CPU1")
	)
	(segment
		(start 112.110266 -241.48161)
		(end 112.11052 -241.481356)
		(width 0.2032)
		(layer "F.Cu")
		(net "PVCCIN_CPU1")
	)
	(segment
		(start 108.930694 -287.567116)
		(end 108.930694 -288.103056)
		(width 0.2032)
		(layer "F.Cu")
		(net "PVCCIN_CPU1")
	)
	(segment
		(start 111.170466 -242.017042)
		(end 111.170466 -241.48161)
		(width 0.2032)
		(layer "F.Cu")
		(net "PVCCIN_CPU1")
	)
	(segment
		(start 110.340648 -263.96442)
		(end 110.340648 -264.50036)
		(width 0.2032)
		(layer "F.Cu")
		(net "PVCCIN_CPU1")
	)
	(segment
		(start 112.689894 -261.522718)
		(end 112.689894 -262.058658)
		(width 0.2032)
		(layer "F.Cu")
		(net "PVCCIN_CPU1")
	)
	(segment
		(start 112.579912 -240.667794)
		(end 112.580166 -240.66754)
		(width 0.2032)
		(layer "F.Cu")
		(net "PVCCIN_CPU1")
	)
	(segment
		(start 112.689894 -263.150604)
		(end 112.690148 -263.150858)
		(width 0.2032)
		(layer "F.Cu")
		(net "PVCCIN_CPU1")
	)
	(segment
		(start 109.760512 -239.040162)
		(end 109.76102 -239.039654)
		(width 0.254)
		(layer "F.Cu")
		(net "PVCCIN_CPU1")
	)
	(segment
		(start 116.919248 -283.497782)
		(end 116.919248 -284.033722)
		(width 0.2032)
		(layer "F.Cu")
		(net "PVCCIN_CPU1")
	)
	(segment
		(start 112.220248 -272.103342)
		(end 112.220248 -272.639282)
		(width 0.2032)
		(layer "F.Cu")
		(net "PVCCIN_CPU1")
	)
	(segment
		(start 109.400594 -261.244842)
		(end 109.400848 -261.245096)
		(width 0.2032)
		(layer "F.Cu")
		(net "PVCCIN_CPU1")
	)
	(segment
		(start 111.280448 -268.84757)
		(end 111.280448 -269.38351)
		(width 0.2032)
		(layer "F.Cu")
		(net "PVCCIN_CPU1")
	)
	(segment
		(start 112.689894 -264.778236)
		(end 112.689894 -265.314176)
		(width 0.2032)
		(layer "F.Cu")
		(net "PVCCIN_CPU1")
	)
	(segment
		(start 109.400594 -262.336534)
		(end 109.400594 -262.872474)
		(width 0.2032)
		(layer "F.Cu")
		(net "PVCCIN_CPU1")
	)
	(segment
		(start 112.220248 -281.869896)
		(end 112.220248 -282.405836)
		(width 0.2032)
		(layer "F.Cu")
		(net "PVCCIN_CPU1")
	)
	(segment
		(start 112.689894 -269.66164)
		(end 112.689894 -270.19758)
		(width 0.2032)
		(layer "F.Cu")
		(net "PVCCIN_CPU1")
	)
	(segment
		(start 118.328694 -285.939484)
		(end 118.328694 -286.475424)
		(width 0.2032)
		(layer "F.Cu")
		(net "PVCCIN_CPU1")
	)
	(segment
		(start 110.810294 -287.567116)
		(end 110.810294 -288.103056)
		(width 0.2032)
		(layer "F.Cu")
		(net "PVCCIN_CPU1")
	)
	(segment
		(start 115.979448 -285.125414)
		(end 115.979448 -285.6611)
		(width 0.2032)
		(layer "F.Cu")
		(net "PVCCIN_CPU1")
	)
	(segment
		(start 111.280448 -265.592052)
		(end 111.280448 -265.592306)
		(width 0.2032)
		(layer "F.Cu")
		(net "PVCCIN_CPU1")
	)
	(segment
		(start 112.689894 -268.033754)
		(end 112.689894 -268.569694)
		(width 0.2032)
		(layer "F.Cu")
		(net "PVCCIN_CPU1")
	)
	(segment
		(start 109.870494 -285.939484)
		(end 109.870494 -286.475424)
		(width 0.2032)
		(layer "F.Cu")
		(net "PVCCIN_CPU1")
	)
	(segment
		(start 114.099848 -262.336534)
		(end 114.099848 -262.872474)
		(width 0.2032)
		(layer "F.Cu")
		(net "PVCCIN_CPU1")
	)
	(segment
		(start 111.170466 -240.389156)
		(end 111.170466 -239.853724)
		(width 0.2032)
		(layer "F.Cu")
		(net "PVCCIN_CPU1")
	)
	(segment
		(start 110.810294 -271.289272)
		(end 110.810294 -271.824958)
		(width 0.2032)
		(layer "F.Cu")
		(net "PVCCIN_CPU1")
	)
	(segment
		(start 114.459766 -240.667794)
		(end 114.46002 -240.66754)
		(width 0.2032)
		(layer "F.Cu")
		(net "PVCCIN_CPU1")
	)
	(segment
		(start 111.170466 -241.48161)
		(end 111.17072 -241.481356)
		(width 0.2032)
		(layer "F.Cu")
		(net "PVCCIN_CPU1")
	)
	(segment
		(start 116.449094 -289.195002)
		(end 116.449094 -289.807142)
		(width 0.2032)
		(layer "F.Cu")
		(net "PVCCIN_CPU1")
	)
	(segment
		(start 109.400594 -263.96442)
		(end 109.400594 -264.50036)
		(width 0.2032)
		(layer "F.Cu")
		(net "PVCCIN_CPU1")
	)
	(segment
		(start 109.870494 -287.567116)
		(end 109.870494 -288.103056)
		(width 0.2032)
		(layer "F.Cu")
		(net "PVCCIN_CPU1")
	)
	(segment
		(start 109.870494 -261.522718)
		(end 109.870494 -262.058658)
		(width 0.2032)
		(layer "F.Cu")
		(net "PVCCIN_CPU1")
	)
	(segment
		(start 113.159794 -283.497782)
		(end 113.159794 -284.033722)
		(width 0.2032)
		(layer "F.Cu")
		(net "PVCCIN_CPU1")
	)
	(segment
		(start 111.750094 -287.567116)
		(end 111.750094 -288.103056)
		(width 0.2032)
		(layer "F.Cu")
		(net "PVCCIN_CPU1")
	)
	(segment
		(start 113.159794 -266.127992)
		(end 113.15954 -266.128246)
		(width 0.2032)
		(layer "F.Cu")
		(net "PVCCIN_CPU1")
	)
	(segment
		(start 110.810294 -285.939484)
		(end 110.810294 -286.47517)
		(width 0.2032)
		(layer "F.Cu")
		(net "PVCCIN_CPU1")
	)
	(segment
		(start 112.689894 -287.567116)
		(end 112.689894 -288.103056)
		(width 0.2032)
		(layer "F.Cu")
		(net "PVCCIN_CPU1")
	)
	(segment
		(start 114.569494 -285.939484)
		(end 114.569494 -286.475424)
		(width 0.2032)
		(layer "F.Cu")
		(net "PVCCIN_CPU1")
	)
	(segment
		(start 107.990894 -281.05608)
		(end 107.990894 -281.591766)
		(width 0.2032)
		(layer "F.Cu")
		(net "PVCCIN_CPU1")
	)
	(segment
		(start 110.700566 -239.57534)
		(end 110.700566 -239.039908)
		(width 0.2032)
		(layer "F.Cu")
		(net "PVCCIN_CPU1")
	)
	(segment
		(start 112.220248 -265.592306)
		(end 112.220248 -266.128246)
		(width 0.2032)
		(layer "F.Cu")
		(net "PVCCIN_CPU1")
	)
	(segment
		(start 112.689894 -285.939484)
		(end 112.689894 -286.475424)
		(width 0.2032)
		(layer "F.Cu")
		(net "PVCCIN_CPU1")
	)
	(segment
		(start 108.461048 -285.125414)
		(end 108.461048 -285.661354)
		(width 0.2032)
		(layer "F.Cu")
		(net "PVCCIN_CPU1")
	)
	(segment
		(start 122.356118 -314.727082)
		(end 123.296426 -315.66739)
		(width 0.508)
		(layer "F.Cu")
		(net "PVCCIN_CPU1")
	)
	(segment
		(start 111.750094 -282.683966)
		(end 111.750094 -283.219906)
		(width 0.2032)
		(layer "F.Cu")
		(net "PVCCIN_CPU1")
	)
	(segment
		(start 115.979448 -283.497782)
		(end 115.979448 -284.033468)
		(width 0.2032)
		(layer "F.Cu")
		(net "PVCCIN_CPU1")
	)
	(segment
		(start 109.400594 -280.242264)
		(end 109.400594 -280.778204)
		(width 0.2032)
		(layer "F.Cu")
		(net "PVCCIN_CPU1")
	)
	(segment
		(start 110.340648 -278.614378)
		(end 110.340648 -279.150318)
		(width 0.254)
		(layer "F.Cu")
		(net "PVCCIN_CPU1")
	)
	(segment
		(start 118.798848 -288.381186)
		(end 118.798848 -288.917126)
		(width 0.2032)
		(layer "F.Cu")
		(net "PVCCIN_CPU1")
	)
	(segment
		(start 107.990894 -284.847284)
		(end 107.991148 -284.847538)
		(width 0.2032)
		(layer "F.Cu")
		(net "PVCCIN_CPU1")
	)
	(segment
		(start 111.750094 -279.428194)
		(end 111.750094 -279.964134)
		(width 0.2032)
		(layer "F.Cu")
		(net "PVCCIN_CPU1")
	)
	(segment
		(start 111.280448 -272.103342)
		(end 111.280448 -272.639282)
		(width 0.2032)
		(layer "F.Cu")
		(net "PVCCIN_CPU1")
	)
	(segment
		(start 109.400594 -286.7533)
		(end 109.400594 -287.28924)
		(width 0.2032)
		(layer "F.Cu")
		(net "PVCCIN_CPU1")
	)
	(segment
		(start 113.159794 -280.242264)
		(end 113.159794 -280.778204)
		(width 0.2032)
		(layer "F.Cu")
		(net "PVCCIN_CPU1")
	)
	(segment
		(start 105.641648 -288.381186)
		(end 105.641648 -288.917126)
		(width 0.2032)
		(layer "F.Cu")
		(net "PVCCIN_CPU1")
	)
	(segment
		(start 115.039648 -288.381186)
		(end 115.039648 -288.993326)
		(width 0.2032)
		(layer "F.Cu")
		(net "PVCCIN_CPU1")
	)
	(segment
		(start 112.220248 -267.219938)
		(end 112.220248 -267.755878)
		(width 0.2032)
		(layer "F.Cu")
		(net "PVCCIN_CPU1")
	)
	(segment
		(start 114.569494 -281.05608)
		(end 114.569494 -281.59202)
		(width 0.2032)
		(layer "F.Cu")
		(net "PVCCIN_CPU1")
	)
	(segment
		(start 106.581448 -286.7533)
		(end 106.581448 -287.28924)
		(width 0.2032)
		(layer "F.Cu")
		(net "PVCCIN_CPU1")
	)
	(segment
		(start 106.111294 -284.311598)
		(end 106.111294 -284.847538)
		(width 0.2032)
		(layer "F.Cu")
		(net "PVCCIN_CPU1")
	)
	(segment
		(start 114.099848 -288.381186)
		(end 114.099848 -288.993326)
		(width 0.2032)
		(layer "F.Cu")
		(net "PVCCIN_CPU1")
	)
	(segment
		(start 114.099848 -286.7533)
		(end 114.099848 -287.28924)
		(width 0.2032)
		(layer "F.Cu")
		(net "PVCCIN_CPU1")
	)
	(segment
		(start 116.919248 -285.125414)
		(end 116.919248 -285.661354)
		(width 0.2032)
		(layer "F.Cu")
		(net "PVCCIN_CPU1")
	)
	(segment
		(start 113.629694 -276.172676)
		(end 113.629694 -276.708616)
		(width 0.2032)
		(layer "F.Cu")
		(net "PVCCIN_CPU1")
	)
	(segment
		(start 113.159794 -272.103342)
		(end 113.159794 -272.639282)
		(width 0.2032)
		(layer "F.Cu")
		(net "PVCCIN_CPU1")
	)
	(segment
		(start 112.689894 -274.54479)
		(end 112.689894 -275.08073)
		(width 0.2032)
		(layer "F.Cu")
		(net "PVCCIN_CPU1")
	)
	(segment
		(start 114.099848 -278.614378)
		(end 114.099848 -279.150318)
		(width 0.2032)
		(layer "F.Cu")
		(net "PVCCIN_CPU1")
	)
	(segment
		(start 110.810294 -276.172676)
		(end 110.810294 -276.708362)
		(width 0.2032)
		(layer "F.Cu")
		(net "PVCCIN_CPU1")
	)
	(segment
		(start 114.099848 -262.872474)
		(end 114.100102 -262.872728)
		(width 0.2032)
		(layer "F.Cu")
		(net "PVCCIN_CPU1")
	)
	(segment
		(start 110.810294 -272.917158)
		(end 110.810294 -273.452844)
		(width 0.2032)
		(layer "F.Cu")
		(net "PVCCIN_CPU1")
	)
	(segment
		(start 112.689894 -277.800562)
		(end 112.689894 -278.336502)
		(width 0.2032)
		(layer "F.Cu")
		(net "PVCCIN_CPU1")
	)
	(segment
		(start 112.220248 -275.35886)
		(end 112.220248 -275.8948)
		(width 0.2032)
		(layer "F.Cu")
		(net "PVCCIN_CPU1")
	)
	(segment
		(start 113.989866 -239.853724)
		(end 113.99012 -239.85347)
		(width 0.2032)
		(layer "F.Cu")
		(net "PVCCIN_CPU1")
	)
	(segment
		(start 111.280448 -280.242264)
		(end 111.280448 -280.778204)
		(width 0.2032)
		(layer "F.Cu")
		(net "PVCCIN_CPU1")
	)
	(segment
		(start 98.525838 -315.66739)
		(end 99.466146 -314.727082)
		(width 0.508)
		(layer "F.Cu")
		(net "PVCCIN_CPU1")
	)
	(segment
		(start 108.930694 -281.05608)
		(end 108.930694 -281.59202)
		(width 0.2032)
		(layer "F.Cu")
		(net "PVCCIN_CPU1")
	)
	(segment
		(start 112.220248 -286.7533)
		(end 112.220248 -287.28924)
		(width 0.2032)
		(layer "F.Cu")
		(net "PVCCIN_CPU1")
	)
	(segment
		(start 109.400594 -278.614378)
		(end 109.400594 -279.150318)
		(width 0.2032)
		(layer "F.Cu")
		(net "PVCCIN_CPU1")
	)
	(segment
		(start 108.930694 -289.195002)
		(end 108.930694 -289.807142)
		(width 0.2032)
		(layer "F.Cu")
		(net "PVCCIN_CPU1")
	)
	(segment
		(start 111.640112 -240.667794)
		(end 111.640366 -240.66754)
		(width 0.2032)
		(layer "F.Cu")
		(net "PVCCIN_CPU1")
	)
	(segment
		(start 115.509294 -282.683966)
		(end 115.509294 -283.219906)
		(width 0.2032)
		(layer "F.Cu")
		(net "PVCCIN_CPU1")
	)
	(segment
		(start 113.159794 -281.869896)
		(end 113.159794 -282.405836)
		(width 0.2032)
		(layer "F.Cu")
		(net "PVCCIN_CPU1")
	)
	(segment
		(start 113.159794 -262.336534)
		(end 113.159794 -262.872474)
		(width 0.2032)
		(layer "F.Cu")
		(net "PVCCIN_CPU1")
	)
	(segment
		(start 112.110266 -239.853724)
		(end 112.11052 -239.85347)
		(width 0.2032)
		(layer "F.Cu")
		(net "PVCCIN_CPU1")
	)
	(segment
		(start 106.581448 -285.125414)
		(end 106.581448 -285.661354)
		(width 0.2032)
		(layer "F.Cu")
		(net "PVCCIN_CPU1")
	)
	(segment
		(start 117.859048 -283.497782)
		(end 117.859048 -284.033468)
		(width 0.2032)
		(layer "F.Cu")
		(net "PVCCIN_CPU1")
	)
	(segment
		(start 108.461048 -283.497782)
		(end 108.461048 -284.033722)
		(width 0.2032)
		(layer "F.Cu")
		(net "PVCCIN_CPU1")
	)
	(segment
		(start 109.960918 -314.727082)
		(end 110.901226 -315.66739)
		(width 0.508)
		(layer "F.Cu")
		(net "PVCCIN_CPU1")
	)
	(segment
		(start 108.930694 -285.939484)
		(end 108.930694 -286.475424)
		(width 0.2032)
		(layer "F.Cu")
		(net "PVCCIN_CPU1")
	)
	(segment
		(start 112.220248 -265.592052)
		(end 112.220248 -265.592306)
		(width 0.2032)
		(layer "F.Cu")
		(net "PVCCIN_CPU1")
	)
	(segment
		(start 117.859048 -288.381186)
		(end 117.859048 -288.917126)
		(width 0.2032)
		(layer "F.Cu")
		(net "PVCCIN_CPU1")
	)
	(segment
		(start 113.159794 -285.125414)
		(end 113.159794 -285.661354)
		(width 0.2032)
		(layer "F.Cu")
		(net "PVCCIN_CPU1")
	)
	(segment
		(start 110.810294 -266.405868)
		(end 110.810294 -266.941554)
		(width 0.2032)
		(layer "F.Cu")
		(net "PVCCIN_CPU1")
	)
	(segment
		(start 114.569494 -279.428194)
		(end 114.569494 -279.964134)
		(width 0.2032)
		(layer "F.Cu")
		(net "PVCCIN_CPU1")
	)
	(segment
		(start 114.099848 -276.986492)
		(end 114.099848 -277.522178)
		(width 0.2032)
		(layer "F.Cu")
		(net "PVCCIN_CPU1")
	)
	(segment
		(start 110.810294 -279.428194)
		(end 110.810294 -279.96388)
		(width 0.2032)
		(layer "F.Cu")
		(net "PVCCIN_CPU1")
	)
	(segment
		(start 107.051094 -285.939484)
		(end 107.051094 -286.475424)
		(width 0.2032)
		(layer "F.Cu")
		(net "PVCCIN_CPU1")
	)
	(segment
		(start 109.400594 -283.497782)
		(end 109.400594 -284.033722)
		(width 0.2032)
		(layer "F.Cu")
		(net "PVCCIN_CPU1")
	)
	(segment
		(start 112.220248 -288.381186)
		(end 112.220248 -288.993326)
		(width 0.2032)
		(layer "F.Cu")
		(net "PVCCIN_CPU1")
	)
	(segment
		(start 110.810294 -276.708362)
		(end 110.810548 -276.708616)
		(width 0.2032)
		(layer "F.Cu")
		(net "PVCCIN_CPU1")
	)
	(segment
		(start 110.700566 -239.039908)
		(end 110.70082 -239.039654)
		(width 0.2032)
		(layer "F.Cu")
		(net "PVCCIN_CPU1")
	)
	(segment
		(start 117.388894 -282.683966)
		(end 117.388894 -283.219906)
		(width 0.2032)
		(layer "F.Cu")
		(net "PVCCIN_CPU1")
	)
	(segment
		(start 110.810294 -282.683966)
		(end 110.810294 -283.219652)
		(width 0.2032)
		(layer "F.Cu")
		(net "PVCCIN_CPU1")
	)
	(segment
		(start 117.098826 -315.66739)
		(end 118.039134 -316.607698)
		(width 0.508)
		(layer "F.Cu")
		(net "PVCCIN_CPU1")
	)
	(segment
		(start 109.870494 -263.150604)
		(end 109.870748 -263.150858)
		(width 0.2032)
		(layer "F.Cu")
		(net "PVCCIN_CPU1")
	)
	(segment
		(start 112.689894 -282.683966)
		(end 112.689894 -283.219906)
		(width 0.2032)
		(layer "F.Cu")
		(net "PVCCIN_CPU1")
	)
	(segment
		(start 111.280448 -263.96442)
		(end 111.280448 -264.50036)
		(width 0.2032)
		(layer "F.Cu")
		(net "PVCCIN_CPU1")
	)
	(segment
		(start 110.810294 -281.591766)
		(end 110.810548 -281.59202)
		(width 0.2032)
		(layer "F.Cu")
		(net "PVCCIN_CPU1")
	)
	(segment
		(start 106.111294 -285.939484)
		(end 106.111294 -286.475424)
		(width 0.2032)
		(layer "F.Cu")
		(net "PVCCIN_CPU1")
	)
	(segment
		(start 105.641648 -286.7533)
		(end 105.641648 -287.28924)
		(width 0.2032)
		(layer "F.Cu")
		(net "PVCCIN_CPU1")
	)
	(segment
		(start 107.990894 -285.939484)
		(end 107.990894 -286.47517)
		(width 0.2032)
		(layer "F.Cu")
		(net "PVCCIN_CPU1")
	)
	(segment
		(start 111.280448 -273.730974)
		(end 111.280448 -274.266914)
		(width 0.2032)
		(layer "F.Cu")
		(net "PVCCIN_CPU1")
	)
	(segment
		(start 113.050066 -242.017042)
		(end 113.050066 -241.481356)
		(width 0.2032)
		(layer "F.Cu")
		(net "PVCCIN_CPU1")
	)
	(segment
		(start 112.220248 -278.614378)
		(end 112.220248 -279.150318)
		(width 0.2032)
		(layer "F.Cu")
		(net "PVCCIN_CPU1")
	)
	(segment
		(start 112.689894 -276.172676)
		(end 112.689894 -276.708616)
		(width 0.2032)
		(layer "F.Cu")
		(net "PVCCIN_CPU1")
	)
	(segment
		(start 111.750094 -262.058658)
		(end 111.750348 -262.058912)
		(width 0.2032)
		(layer "F.Cu")
		(net "PVCCIN_CPU1")
	)
	(segment
		(start 117.388894 -287.567116)
		(end 117.388894 -288.103056)
		(width 0.2032)
		(layer "F.Cu")
		(net "PVCCIN_CPU1")
	)
	(segment
		(start 107.990894 -282.683966)
		(end 107.990894 -283.219652)
		(width 0.2032)
		(layer "F.Cu")
		(net "PVCCIN_CPU1")
	)
	(segment
		(start 108.461048 -286.7533)
		(end 108.461048 -287.28924)
		(width 0.2032)
		(layer "F.Cu")
		(net "PVCCIN_CPU1")
	)
	(segment
		(start 112.110266 -240.389156)
		(end 112.110266 -239.853724)
		(width 0.2032)
		(layer "F.Cu")
		(net "PVCCIN_CPU1")
	)
	(segment
		(start 117.388894 -284.311598)
		(end 117.388894 -284.847538)
		(width 0.2032)
		(layer "F.Cu")
		(net "PVCCIN_CPU1")
	)
	(segment
		(start 110.810294 -264.778236)
		(end 110.810294 -265.314176)
		(width 0.2032)
		(layer "F.Cu")
		(net "PVCCIN_CPU1")
	)
	(segment
		(start 115.039648 -286.7533)
		(end 115.039648 -287.28924)
		(width 0.2032)
		(layer "F.Cu")
		(net "PVCCIN_CPU1")
	)
	(segment
		(start 109.400594 -285.125414)
		(end 109.400594 -285.661354)
		(width 0.2032)
		(layer "F.Cu")
		(net "PVCCIN_CPU1")
	)
	(segment
		(start 113.159794 -268.84757)
		(end 113.159794 -269.38351)
		(width 0.2032)
		(layer "F.Cu")
		(net "PVCCIN_CPU1")
	)
	(segment
		(start 108.930694 -282.683966)
		(end 108.930694 -283.219906)
		(width 0.2032)
		(layer "F.Cu")
		(net "PVCCIN_CPU1")
	)
	(segment
		(start 109.870494 -281.05608)
		(end 109.870494 -281.59202)
		(width 0.2032)
		(layer "F.Cu")
		(net "PVCCIN_CPU1")
	)
	(segment
		(start 111.640112 -241.203226)
		(end 111.640112 -240.667794)
		(width 0.2032)
		(layer "F.Cu")
		(net "PVCCIN_CPU1")
	)
	(segment
		(start 107.990894 -284.311598)
		(end 107.990894 -284.847284)
		(width 0.2032)
		(layer "F.Cu")
		(net "PVCCIN_CPU1")
	)
	(segment
		(start 114.569494 -262.058658)
		(end 114.569748 -262.058912)
		(width 0.2032)
		(layer "F.Cu")
		(net "PVCCIN_CPU1")
	)
	(segment
		(start 115.979448 -287.288986)
		(end 115.979194 -287.28924)
		(width 0.2032)
		(layer "F.Cu")
		(net "PVCCIN_CPU1")
	)
	(segment
		(start 111.750094 -261.522718)
		(end 111.750094 -262.058658)
		(width 0.2032)
		(layer "F.Cu")
		(net "PVCCIN_CPU1")
	)
	(segment
		(start 112.220248 -262.872474)
		(end 112.220502 -262.872728)
		(width 0.2032)
		(layer "F.Cu")
		(net "PVCCIN_CPU1")
	)
	(segment
		(start 111.280448 -283.497782)
		(end 111.280448 -284.033722)
		(width 0.2032)
		(layer "F.Cu")
		(net "PVCCIN_CPU1")
	)
	(segment
		(start 112.579912 -239.040162)
		(end 112.58042 -239.039654)
		(width 0.2032)
		(layer "F.Cu")
		(net "PVCCIN_CPU1")
	)
	(segment
		(start 113.159794 -270.475456)
		(end 113.159794 -271.011396)
		(width 0.2032)
		(layer "F.Cu")
		(net "PVCCIN_CPU1")
	)
	(segment
		(start 114.099848 -283.497782)
		(end 114.099848 -284.033722)
		(width 0.2032)
		(layer "F.Cu")
		(net "PVCCIN_CPU1")
	)
	(segment
		(start 110.810294 -281.05608)
		(end 110.810294 -281.591766)
		(width 0.2032)
		(layer "F.Cu")
		(net "PVCCIN_CPU1")
	)
	(segment
		(start 112.220248 -261.244842)
		(end 112.220502 -261.245096)
		(width 0.2032)
		(layer "F.Cu")
		(net "PVCCIN_CPU1")
	)
	(segment
		(start 111.280448 -267.219938)
		(end 111.280448 -267.755878)
		(width 0.2032)
		(layer "F.Cu")
		(net "PVCCIN_CPU1")
	)
	(segment
		(start 111.750094 -264.778236)
		(end 111.750094 -265.314176)
		(width 0.2032)
		(layer "F.Cu")
		(net "PVCCIN_CPU1")
	)
	(segment
		(start 103.78313 -314.727082)
		(end 104.723438 -315.66739)
		(width 0.508)
		(layer "F.Cu")
		(net "PVCCIN_CPU1")
	)
	(segment
		(start 113.989866 -241.48161)
		(end 113.99012 -241.481356)
		(width 0.2032)
		(layer "F.Cu")
		(net "PVCCIN_CPU1")
	)
	(segment
		(start 115.979448 -282.405582)
		(end 115.979194 -282.405836)
		(width 0.2032)
		(layer "F.Cu")
		(net "PVCCIN_CPU1")
	)
	(segment
		(start 114.099848 -261.244842)
		(end 114.100102 -261.245096)
		(width 0.2032)
		(layer "F.Cu")
		(net "PVCCIN_CPU1")
	)
	(segment
		(start 118.798848 -286.7533)
		(end 118.798848 -287.28924)
		(width 0.2032)
		(layer "F.Cu")
		(net "PVCCIN_CPU1")
	)
	(segment
		(start 110.810294 -279.96388)
		(end 110.810548 -279.964134)
		(width 0.2032)
		(layer "F.Cu")
		(net "PVCCIN_CPU1")
	)
	(segment
		(start 111.280448 -262.336534)
		(end 111.280448 -262.872474)
		(width 0.2032)
		(layer "F.Cu")
		(net "PVCCIN_CPU1")
	)
	(segment
		(start 112.689894 -262.058658)
		(end 112.690148 -262.058912)
		(width 0.2032)
		(layer "F.Cu")
		(net "PVCCIN_CPU1")
	)
	(segment
		(start 114.569494 -259.894832)
		(end 114.569494 -260.430772)
		(width 0.2032)
		(layer "F.Cu")
		(net "PVCCIN_CPU1")
	)
	(segment
		(start 111.750094 -281.05608)
		(end 111.750094 -281.59202)
		(width 0.2032)
		(layer "F.Cu")
		(net "PVCCIN_CPU1")
	)
	(segment
		(start 111.280448 -278.614378)
		(end 111.280448 -279.150318)
		(width 0.2032)
		(layer "F.Cu")
		(net "PVCCIN_CPU1")
	)
	(segment
		(start 117.859048 -285.125414)
		(end 117.859048 -285.661354)
		(width 0.2032)
		(layer "F.Cu")
		(net "PVCCIN_CPU1")
	)
	(segment
		(start 112.220248 -273.730974)
		(end 112.220248 -274.266914)
		(width 0.2032)
		(layer "F.Cu")
		(net "PVCCIN_CPU1")
	)
	(segment
		(start 112.220248 -270.475456)
		(end 112.220248 -271.011396)
		(width 0.2032)
		(layer "F.Cu")
		(net "PVCCIN_CPU1")
	)
	(segment
		(start 114.099848 -281.869896)
		(end 114.099848 -282.405836)
		(width 0.2032)
		(layer "F.Cu")
		(net "PVCCIN_CPU1")
	)
	(segment
		(start 111.750094 -263.150604)
		(end 111.750348 -263.150858)
		(width 0.2032)
		(layer "F.Cu")
		(net "PVCCIN_CPU1")
	)
	(segment
		(start 106.581448 -283.497782)
		(end 106.581448 -284.033722)
		(width 0.254)
		(layer "F.Cu")
		(net "PVCCIN_CPU1")
	)
	(segment
		(start 111.280448 -262.872474)
		(end 111.280702 -262.872728)
		(width 0.2032)
		(layer "F.Cu")
		(net "PVCCIN_CPU1")
	)
	(segment
		(start 112.220248 -260.708902)
		(end 112.220248 -261.244842)
		(width 0.2032)
		(layer "F.Cu")
		(net "PVCCIN_CPU1")
	)
	(segment
		(start 110.810294 -261.522718)
		(end 110.810294 -262.058404)
		(width 0.2032)
		(layer "F.Cu")
		(net "PVCCIN_CPU1")
	)
	(segment
		(start 110.810294 -269.66164)
		(end 110.810294 -270.197326)
		(width 0.2032)
		(layer "F.Cu")
		(net "PVCCIN_CPU1")
	)
	(segment
		(start 113.159794 -265.592306)
		(end 113.159794 -266.127992)
		(width 0.2032)
		(layer "F.Cu")
		(net "PVCCIN_CPU1")
	)
	(segment
		(start 115.509294 -289.195002)
		(end 115.509294 -289.807142)
		(width 0.2032)
		(layer "F.Cu")
		(net "PVCCIN_CPU1")
	)
	(segment
		(start 108.461048 -281.869896)
		(end 108.461048 -282.405836)
		(width 0.2032)
		(layer "F.Cu")
		(net "PVCCIN_CPU1")
	)
	(segment
		(start 113.159794 -262.872474)
		(end 113.160048 -262.872728)
		(width 0.2032)
		(layer "F.Cu")
		(net "PVCCIN_CPU1")
	)
	(segment
		(start 109.400594 -281.869896)
		(end 109.400594 -282.405836)
		(width 0.2032)
		(layer "F.Cu")
		(net "PVCCIN_CPU1")
	)
	(segment
		(start 115.039648 -281.869896)
		(end 115.039648 -282.405836)
		(width 0.2032)
		(layer "F.Cu")
		(net "PVCCIN_CPU1")
	)
	(segment
		(start 110.810294 -284.847284)
		(end 110.810548 -284.847538)
		(width 0.2032)
		(layer "F.Cu")
		(net "PVCCIN_CPU1")
	)
	(segment
		(start 111.750094 -276.172676)
		(end 111.750094 -276.708616)
		(width 0.2032)
		(layer "F.Cu")
		(net "PVCCIN_CPU1")
	)
	(segment
		(start 119.268494 -287.567116)
		(end 119.268494 -288.103056)
		(width 0.2032)
		(layer "F.Cu")
		(net "PVCCIN_CPU1")
	)
	(segment
		(start 113.159794 -267.219938)
		(end 113.159794 -267.755878)
		(width 0.2032)
		(layer "F.Cu")
		(net "PVCCIN_CPU1")
	)
	(segment
		(start 110.810294 -275.080476)
		(end 110.810548 -275.08073)
		(width 0.2032)
		(layer "F.Cu")
		(net "PVCCIN_CPU1")
	)
	(segment
		(start 115.039648 -285.125414)
		(end 115.039648 -285.661354)
		(width 0.2032)
		(layer "F.Cu")
		(net "PVCCIN_CPU1")
	)
	(segment
		(start 114.459766 -239.57534)
		(end 114.459766 -239.039908)
		(width 0.2032)
		(layer "F.Cu")
		(net "PVCCIN_CPU1")
	)
	(segment
		(start 114.099848 -263.96442)
		(end 114.099848 -264.500106)
		(width 0.2032)
		(layer "F.Cu")
		(net "PVCCIN_CPU1")
	)
	(segment
		(start 112.689894 -271.289272)
		(end 112.689894 -271.825212)
		(width 0.2032)
		(layer "F.Cu")
		(net "PVCCIN_CPU1")
	)
	(segment
		(start 112.689894 -279.428194)
		(end 112.689894 -279.964134)
		(width 0.2032)
		(layer "F.Cu")
		(net "PVCCIN_CPU1")
	)
	(segment
		(start 110.810294 -274.54479)
		(end 110.810294 -275.080476)
		(width 0.2032)
		(layer "F.Cu")
		(net "PVCCIN_CPU1")
	)
	(segment
		(start 109.870494 -262.058658)
		(end 109.870748 -262.058912)
		(width 0.2032)
		(layer "F.Cu")
		(net "PVCCIN_CPU1")
	)
	(segment
		(start 115.979448 -285.6611)
		(end 115.979194 -285.661354)
		(width 0.2032)
		(layer "F.Cu")
		(net "PVCCIN_CPU1")
	)
	(segment
		(start 115.979448 -284.033468)
		(end 115.979194 -284.033722)
		(width 0.2032)
		(layer "F.Cu")
		(net "PVCCIN_CPU1")
	)
	(segment
		(start 111.750094 -284.311598)
		(end 111.750094 -284.847538)
		(width 0.2032)
		(layer "F.Cu")
		(net "PVCCIN_CPU1")
	)
	(segment
		(start 113.159794 -286.7533)
		(end 113.159794 -287.28924)
		(width 0.2032)
		(layer "F.Cu")
		(net "PVCCIN_CPU1")
	)
	(segment
		(start 112.220248 -280.242264)
		(end 112.220248 -280.778204)
		(width 0.2032)
		(layer "F.Cu")
		(net "PVCCIN_CPU1")
	)
	(segment
		(start 112.690148 -263.150858)
		(end 112.690148 -263.686798)
		(width 0.2032)
		(layer "F.Cu")
		(net "PVCCIN_CPU1")
	)
	(segment
		(start 114.099848 -264.500106)
		(end 114.099594 -264.50036)
		(width 0.2032)
		(layer "F.Cu")
		(net "PVCCIN_CPU1")
	)
	(segment
		(start 111.640112 -239.57534)
		(end 111.640112 -239.040162)
		(width 0.2032)
		(layer "F.Cu")
		(net "PVCCIN_CPU1")
	)
	(segment
		(start 107.990894 -288.102802)
		(end 107.991148 -288.103056)
		(width 0.2032)
		(layer "F.Cu")
		(net "PVCCIN_CPU1")
	)
	(segment
		(start 113.050066 -240.389156)
		(end 113.050066 -239.85347)
		(width 0.2032)
		(layer "F.Cu")
		(net "PVCCIN_CPU1")
	)
	(segment
		(start 113.159794 -265.592306)
		(end 113.159794 -265.592052)
		(width 0.2032)
		(layer "F.Cu")
		(net "PVCCIN_CPU1")
	)
	(segment
		(start 110.340648 -265.592306)
		(end 110.340648 -266.128246)
		(width 0.254)
		(layer "F.Cu")
		(net "PVCCIN_CPU1")
	)
	(segment
		(start 114.569494 -261.522718)
		(end 114.569494 -262.058658)
		(width 0.2032)
		(layer "F.Cu")
		(net "PVCCIN_CPU1")
	)
	(segment
		(start 109.870748 -263.150858)
		(end 109.870748 -263.686798)
		(width 0.2032)
		(layer "F.Cu")
		(net "PVCCIN_CPU1")
	)
	(segment
		(start 113.629694 -264.778236)
		(end 113.629694 -265.314176)
		(width 0.2032)
		(layer "F.Cu")
		(net "PVCCIN_CPU1")
	)
	(segment
		(start 115.979448 -280.242264)
		(end 115.979448 -280.778204)
		(width 0.2032)
		(layer "F.Cu")
		(net "PVCCIN_CPU1")
	)
	(segment
		(start 107.990894 -287.567116)
		(end 107.990894 -288.102802)
		(width 0.2032)
		(layer "F.Cu")
		(net "PVCCIN_CPU1")
	)
	(segment
		(start 114.099848 -280.242264)
		(end 114.099848 -280.778204)
		(width 0.2032)
		(layer "F.Cu")
		(net "PVCCIN_CPU1")
	)
	(segment
		(start 114.569494 -284.311598)
		(end 114.569494 -284.847538)
		(width 0.2032)
		(layer "F.Cu")
		(net "PVCCIN_CPU1")
	)
	(segment
		(start 113.159794 -260.708902)
		(end 113.159794 -261.245096)
		(width 0.2032)
		(layer "F.Cu")
		(net "PVCCIN_CPU1")
	)
	(segment
		(start 110.810294 -270.197326)
		(end 110.810548 -270.19758)
		(width 0.2032)
		(layer "F.Cu")
		(net "PVCCIN_CPU1")
	)
	(segment
		(start 104.723438 -315.66739)
		(end 105.663746 -316.607698)
		(width 0.508)
		(layer "F.Cu")
		(net "PVCCIN_CPU1")
	)
	(segment
		(start 113.159794 -275.35886)
		(end 113.159794 -275.8948)
		(width 0.2032)
		(layer "F.Cu")
		(net "PVCCIN_CPU1")
	)
	(segment
		(start 110.901226 -315.66739)
		(end 111.841534 -314.727082)
		(width 0.508)
		(layer "F.Cu")
		(net "PVCCIN_CPU1")
	)
	(segment
		(start 107.051094 -289.195002)
		(end 107.051094 -289.807142)
		(width 0.2032)
		(layer "F.Cu")
		(net "PVCCIN_CPU1")
	)
	(segment
		(start 117.388894 -285.939484)
		(end 117.388894 -286.475424)
		(width 0.2032)
		(layer "F.Cu")
		(net "PVCCIN_CPU1")
	)
	(segment
		(start 113.989866 -240.389156)
		(end 113.989866 -239.853724)
		(width 0.2032)
		(layer "F.Cu")
		(net "PVCCIN_CPU1")
	)
	(segment
		(start 114.569494 -287.567116)
		(end 114.569494 -288.103056)
		(width 0.2032)
		(layer "F.Cu")
		(net "PVCCIN_CPU1")
	)
	(segment
		(start 106.111294 -289.195002)
		(end 106.111294 -289.807142)
		(width 0.2032)
		(layer "F.Cu")
		(net "PVCCIN_CPU1")
	)
	(segment
		(start 109.870494 -264.778236)
		(end 109.870494 -265.314176)
		(width 0.2032)
		(layer "F.Cu")
		(net "PVCCIN_CPU1")
	)
	(segment
		(start 112.689894 -272.917158)
		(end 112.689894 -273.453098)
		(width 0.2032)
		(layer "F.Cu")
		(net "PVCCIN_CPU1")
	)
	(segment
		(start 111.750348 -263.150858)
		(end 111.750348 -263.686798)
		(width 0.2032)
		(layer "F.Cu")
		(net "PVCCIN_CPU1")
	)
	(segment
		(start 114.569494 -263.150604)
		(end 114.569748 -263.150858)
		(width 0.2032)
		(layer "F.Cu")
		(net "PVCCIN_CPU1")
	)
	(segment
		(start 108.930694 -279.428194)
		(end 108.930694 -279.964134)
		(width 0.2032)
		(layer "F.Cu")
		(net "PVCCIN_CPU1")
	)
	(segment
		(start 104.723438 -315.66739)
		(end 105.663746 -314.727082)
		(width 0.508)
		(layer "F.Cu")
		(net "PVCCIN_CPU1")
	)
	(segment
		(start 110.810294 -271.824958)
		(end 110.810548 -271.825212)
		(width 0.2032)
		(layer "F.Cu")
		(net "PVCCIN_CPU1")
	)
	(segment
		(start 117.859048 -286.7533)
		(end 117.859048 -287.28924)
		(width 0.2032)
		(layer "F.Cu")
		(net "PVCCIN_CPU1")
	)
	(segment
		(start 115.509294 -279.428194)
		(end 115.509294 -279.964134)
		(width 0.2032)
		(layer "F.Cu")
		(net "PVCCIN_CPU1")
	)
	(segment
		(start 111.750094 -271.289272)
		(end 111.750094 -271.825212)
		(width 0.2032)
		(layer "F.Cu")
		(net "PVCCIN_CPU1")
	)
	(segment
		(start 112.689894 -284.311598)
		(end 112.689894 -284.847538)
		(width 0.2032)
		(layer "F.Cu")
		(net "PVCCIN_CPU1")
	)
	(segment
		(start 105.171494 -289.195002)
		(end 105.171494 -289.807142)
		(width 0.2032)
		(layer "F.Cu")
		(net "PVCCIN_CPU1")
	)
	(segment
		(start 107.051094 -287.567116)
		(end 107.051094 -288.103056)
		(width 0.2032)
		(layer "F.Cu")
		(net "PVCCIN_CPU1")
	)
	(segment
		(start 111.640112 -239.040162)
		(end 111.64062 -239.039654)
		(width 0.2032)
		(layer "F.Cu")
		(net "PVCCIN_CPU1")
	)
	(segment
		(start 109.870494 -284.311598)
		(end 109.870494 -284.847538)
		(width 0.2032)
		(layer "F.Cu")
		(net "PVCCIN_CPU1")
	)
	(segment
		(start 114.569748 -263.150858)
		(end 114.569748 -263.686798)
		(width 0.2032)
		(layer "F.Cu")
		(net "PVCCIN_CPU1")
	)
	(segment
		(start 123.296426 -315.66739)
		(end 124.236734 -316.607698)
		(width 0.508)
		(layer "F.Cu")
		(net "PVCCIN_CPU1")
	)
	(segment
		(start 114.099848 -260.708902)
		(end 114.099848 -261.244842)
		(width 0.2032)
		(layer "F.Cu")
		(net "PVCCIN_CPU1")
	)
	(segment
		(start 111.750094 -277.800562)
		(end 111.750094 -278.336502)
		(width 0.2032)
		(layer "F.Cu")
		(net "PVCCIN_CPU1")
	)
	(segment
		(start 109.400594 -260.708902)
		(end 109.400594 -261.244842)
		(width 0.2032)
		(layer "F.Cu")
		(net "PVCCIN_CPU1")
	)
	(segment
		(start 109.960918 -316.607698)
		(end 110.901226 -315.66739)
		(width 0.508)
		(layer "F.Cu")
		(net "PVCCIN_CPU1")
	)
	(segment
		(start 109.870494 -279.428194)
		(end 109.870494 -279.964134)
		(width 0.2032)
		(layer "F.Cu")
		(net "PVCCIN_CPU1")
	)
	(segment
		(start 112.220248 -285.125414)
		(end 112.220248 -285.661354)
		(width 0.2032)
		(layer "F.Cu")
		(net "PVCCIN_CPU1")
	)
	(segment
		(start 111.750094 -268.033754)
		(end 111.750094 -268.569694)
		(width 0.2032)
		(layer "F.Cu")
		(net "PVCCIN_CPU1")
	)
	(segment
		(start 110.901226 -315.66739)
		(end 111.841534 -316.607698)
		(width 0.508)
		(layer "F.Cu")
		(net "PVCCIN_CPU1")
	)
	(segment
		(start 110.340648 -265.592052)
		(end 110.340648 -265.592306)
		(width 0.254)
		(layer "F.Cu")
		(net "PVCCIN_CPU1")
	)
	(segment
		(start 117.859048 -284.033468)
		(end 117.858794 -284.033722)
		(width 0.2032)
		(layer "F.Cu")
		(net "PVCCIN_CPU1")
	)
	(segment
		(start 111.750094 -285.939484)
		(end 111.750094 -286.475424)
		(width 0.2032)
		(layer "F.Cu")
		(net "PVCCIN_CPU1")
	)
	(segment
		(start 116.158518 -314.727082)
		(end 117.098826 -315.66739)
		(width 0.508)
		(layer "F.Cu")
		(net "PVCCIN_CPU1")
	)
	(segment
		(start 116.919248 -288.381186)
		(end 116.919248 -288.917126)
		(width 0.2032)
		(layer "F.Cu")
		(net "PVCCIN_CPU1")
	)
	(segment
		(start 109.290866 -240.389156)
		(end 109.290866 -239.853724)
		(width 0.2032)
		(layer "F.Cu")
		(net "PVCCIN_CPU1")
	)
	(segment
		(start 111.280448 -276.986492)
		(end 111.280448 -277.522432)
		(width 0.2032)
		(layer "F.Cu")
		(net "PVCCIN_CPU1")
	)
	(segment
		(start 113.159794 -288.381186)
		(end 113.159794 -288.993326)
		(width 0.2032)
		(layer "F.Cu")
		(net "PVCCIN_CPU1")
	)
	(segment
		(start 112.689894 -281.05608)
		(end 112.689894 -281.59202)
		(width 0.2032)
		(layer "F.Cu")
		(net "PVCCIN_CPU1")
	)
	(segment
		(start 111.750094 -266.405868)
		(end 111.750094 -266.941808)
		(width 0.2032)
		(layer "F.Cu")
		(net "PVCCIN_CPU1")
	)
	(segment
		(start 115.509294 -281.05608)
		(end 115.509294 -281.59202)
		(width 0.2032)
		(layer "F.Cu")
		(net "PVCCIN_CPU1")
	)
	(segment
		(start 110.810294 -262.058404)
		(end 110.810802 -262.058912)
		(width 0.2032)
		(layer "F.Cu")
		(net "PVCCIN_CPU1")
	)
	(segment
		(start 109.870494 -282.683966)
		(end 109.870494 -283.219906)
		(width 0.2032)
		(layer "F.Cu")
		(net "PVCCIN_CPU1")
	)
	(segment
		(start 110.810294 -286.47517)
		(end 110.810548 -286.475424)
		(width 0.2032)
		(layer "F.Cu")
		(net "PVCCIN_CPU1")
	)
	(segment
		(start 110.810294 -277.800562)
		(end 110.810294 -278.336502)
		(width 0.2032)
		(layer "F.Cu")
		(net "PVCCIN_CPU1")
	)
	(segment
		(start 111.280448 -275.35886)
		(end 111.280448 -275.8948)
		(width 0.2032)
		(layer "F.Cu")
		(net "PVCCIN_CPU1")
	)
	(segment
		(start 114.099848 -285.125414)
		(end 114.099848 -285.661354)
		(width 0.2032)
		(layer "F.Cu")
		(net "PVCCIN_CPU1")
	)
	(segment
		(start 98.525838 -315.66739)
		(end 99.466146 -316.607698)
		(width 0.508)
		(layer "F.Cu")
		(net "PVCCIN_CPU1")
	)
	(segment
		(start 114.569494 -260.430772)
		(end 114.569748 -260.431026)
		(width 0.2032)
		(layer "F.Cu")
		(net "PVCCIN_CPU1")
	)
	(via
		(at 111.750348 -263.686798)
		(size 0.4572)
		(drill 0.2032)
		(layers "F.Cu" "B.Cu")
		(net "PVCCIN_CPU1")
	)
	(via
		(at 112.220248 -272.639282)
		(size 0.4572)
		(drill 0.2032)
		(layers "F.Cu" "B.Cu")
		(net "PVCCIN_CPU1")
	)
	(via
		(at 94.31782 -319.198498)
		(size 0.508)
		(drill 0.254)
		(layers "F.Cu" "B.Cu")
		(net "PVCCIN_CPU1")
	)
	(via
		(at 114.46002 -247.178576)
		(size 0.4572)
		(drill 0.2032)
		(layers "F.Cu" "B.Cu")
		(net "PVCCIN_CPU1")
	)
	(via
		(at 118.922292 -317.925958)
		(size 0.508)
		(drill 0.254)
		(layers "F.Cu" "B.Cu")
		(net "PVCCIN_CPU1")
	)
	(via
		(at 112.580166 -242.295172)
		(size 0.4572)
		(drill 0.2032)
		(layers "F.Cu" "B.Cu")
		(net "PVCCIN_CPU1")
	)
	(via
		(at 95.59163 -321.150742)
		(size 0.508)
		(drill 0.254)
		(layers "F.Cu" "B.Cu")
		(net "PVCCIN_CPU1")
	)
	(via
		(at 109.870748 -255.547876)
		(size 0.4572)
		(drill 0.2032)
		(layers "F.Cu" "B.Cu")
		(net "PVCCIN_CPU1")
	)
	(via
		(at 110.70082 -240.66754)
		(size 0.4572)
		(drill 0.2032)
		(layers "F.Cu" "B.Cu")
		(net "PVCCIN_CPU1")
	)
	(via
		(at 109.870494 -286.475424)
		(size 0.4572)
		(drill 0.2032)
		(layers "F.Cu" "B.Cu")
		(net "PVCCIN_CPU1")
	)
	(via
		(at 137.4394 -330.945236)
		(size 0.508)
		(drill 0.254)
		(layers "F.Cu" "B.Cu")
		(net "PVCCIN_CPU1")
	)
	(via
		(at 124.167392 -320.529458)
		(size 0.508)
		(drill 0.254)
		(layers "F.Cu" "B.Cu")
		(net "PVCCIN_CPU1")
	)
	(via
		(at 99.041712 -317.882778)
		(size 0.508)
		(drill 0.254)
		(layers "F.Cu" "B.Cu")
		(net "PVCCIN_CPU1")
	)
	(via
		(at 107.842812 -318.558418)
		(size 0.508)
		(drill 0.254)
		(layers "F.Cu" "B.Cu")
		(net "PVCCIN_CPU1")
	)
	(via
		(at 115.509294 -279.964134)
		(size 0.4572)
		(drill 0.2032)
		(layers "F.Cu" "B.Cu")
		(net "PVCCIN_CPU1")
	)
	(via
		(at 110.70082 -247.178576)
		(size 0.4572)
		(drill 0.2032)
		(layers "F.Cu" "B.Cu")
		(net "PVCCIN_CPU1")
	)
	(via
		(at 127.0381 -324.638416)
		(size 0.508)
		(drill 0.254)
		(layers "F.Cu" "B.Cu")
		(net "PVCCIN_CPU1")
	)
	(via
		(at 112.580166 -247.178576)
		(size 0.4572)
		(drill 0.2032)
		(layers "F.Cu" "B.Cu")
		(net "PVCCIN_CPU1")
	)
	(via
		(at 117.201696 -246.66956)
		(size 0.4572)
		(drill 0.2032)
		(layers "F.Cu" "B.Cu")
		(net "PVCCIN_CPU1")
	)
	(via
		(at 112.580166 -243.923058)
		(size 0.4572)
		(drill 0.2032)
		(layers "F.Cu" "B.Cu")
		(net "PVCCIN_CPU1")
	)
	(via
		(at 83.32851 -330.008992)
		(size 0.508)
		(drill 0.254)
		(layers "F.Cu" "B.Cu")
		(net "PVCCIN_CPU1")
	)
	(via
		(at 107.991148 -284.847538)
		(size 0.4572)
		(drill 0.2032)
		(layers "F.Cu" "B.Cu")
		(net "PVCCIN_CPU1")
	)
	(via
		(at 98.96729 -321.858132)
		(size 0.508)
		(drill 0.254)
		(layers "F.Cu" "B.Cu")
		(net "PVCCIN_CPU1")
	)
	(via
		(at 107.991148 -283.219906)
		(size 0.4572)
		(drill 0.2032)
		(layers "F.Cu" "B.Cu")
		(net "PVCCIN_CPU1")
	)
	(via
		(at 95.018352 -317.229998)
		(size 0.508)
		(drill 0.254)
		(layers "F.Cu" "B.Cu")
		(net "PVCCIN_CPU1")
	)
	(via
		(at 112.592104 -292.95598)
		(size 0.508)
		(drill 0.254)
		(layers "F.Cu" "B.Cu")
		(net "PVCCIN_CPU1")
	)
	(via
		(at 118.328694 -288.103056)
		(size 0.4572)
		(drill 0.2032)
		(layers "F.Cu" "B.Cu")
		(net "PVCCIN_CPU1")
	)
	(via
		(at 114.099848 -280.778204)
		(size 0.4572)
		(drill 0.2032)
		(layers "F.Cu" "B.Cu")
		(net "PVCCIN_CPU1")
	)
	(via
		(at 83.316572 -327.994518)
		(size 0.508)
		(drill 0.254)
		(layers "F.Cu" "B.Cu")
		(net "PVCCIN_CPU1")
	)
	(via
		(at 94.365572 -317.890398)
		(size 0.508)
		(drill 0.254)
		(layers "F.Cu" "B.Cu")
		(net "PVCCIN_CPU1")
	)
	(via
		(at 114.569494 -288.103056)
		(size 0.4572)
		(drill 0.2032)
		(layers "F.Cu" "B.Cu")
		(net "PVCCIN_CPU1")
	)
	(via
		(at 85.389466 -341.059262)
		(size 0.508)
		(drill 0.254)
		(layers "F.Cu" "B.Cu")
		(net "PVCCIN_CPU1")
	)
	(via
		(at 128.325372 -324.364096)
		(size 0.508)
		(drill 0.254)
		(layers "F.Cu" "B.Cu")
		(net "PVCCIN_CPU1")
	)
	(via
		(at 132.348732 -324.019418)
		(size 0.508)
		(drill 0.254)
		(layers "F.Cu" "B.Cu")
		(net "PVCCIN_CPU1")
	)
	(via
		(at 103.764842 -320.515742)
		(size 0.508)
		(drill 0.254)
		(layers "F.Cu" "B.Cu")
		(net "PVCCIN_CPU1")
	)
	(via
		(at 115.164362 -250.672346)
		(size 0.4572)
		(drill 0.2032)
		(layers "F.Cu" "B.Cu")
		(net "PVCCIN_CPU1")
	)
	(via
		(at 112.11052 -247.992392)
		(size 0.4572)
		(drill 0.2032)
		(layers "F.Cu" "B.Cu")
		(net "PVCCIN_CPU1")
	)
	(via
		(at 111.640366 -240.66754)
		(size 0.4572)
		(drill 0.2032)
		(layers "F.Cu" "B.Cu")
		(net "PVCCIN_CPU1")
	)
	(via
		(at 138.08964 -330.945236)
		(size 0.508)
		(drill 0.254)
		(layers "F.Cu" "B.Cu")
		(net "PVCCIN_CPU1")
	)
	(via
		(at 111.280448 -277.522432)
		(size 0.4572)
		(drill 0.2032)
		(layers "F.Cu" "B.Cu")
		(net "PVCCIN_CPU1")
	)
	(via
		(at 118.937532 -317.273178)
		(size 0.508)
		(drill 0.254)
		(layers "F.Cu" "B.Cu")
		(net "PVCCIN_CPU1")
	)
	(via
		(at 118.846092 -320.547238)
		(size 0.508)
		(drill 0.254)
		(layers "F.Cu" "B.Cu")
		(net "PVCCIN_CPU1")
	)
	(via
		(at 106.111294 -288.103056)
		(size 0.4572)
		(drill 0.2032)
		(layers "F.Cu" "B.Cu")
		(net "PVCCIN_CPU1")
	)
	(via
		(at 82.724752 -327.702418)
		(size 0.508)
		(drill 0.254)
		(layers "F.Cu" "B.Cu")
		(net "PVCCIN_CPU1")
	)
	(via
		(at 115.429792 -317.875158)
		(size 0.508)
		(drill 0.254)
		(layers "F.Cu" "B.Cu")
		(net "PVCCIN_CPU1")
	)
	(via
		(at 137.21334 -329.078336)
		(size 0.508)
		(drill 0.254)
		(layers "F.Cu" "B.Cu")
		(net "PVCCIN_CPU1")
	)
	(via
		(at 113.050066 -247.992392)
		(size 0.4572)
		(drill 0.2032)
		(layers "F.Cu" "B.Cu")
		(net "PVCCIN_CPU1")
	)
	(via
		(at 127.6985 -321.852036)
		(size 0.508)
		(drill 0.254)
		(layers "F.Cu" "B.Cu")
		(net "PVCCIN_CPU1")
	)
	(via
		(at 117.859048 -285.661354)
		(size 0.4572)
		(drill 0.2032)
		(layers "F.Cu" "B.Cu")
		(net "PVCCIN_CPU1")
	)
	(via
		(at 127.035052 -322.487798)
		(size 0.508)
		(drill 0.254)
		(layers "F.Cu" "B.Cu")
		(net "PVCCIN_CPU1")
	)
	(via
		(at 113.159794 -279.150318)
		(size 0.4572)
		(drill 0.2032)
		(layers "F.Cu" "B.Cu")
		(net "PVCCIN_CPU1")
	)
	(via
		(at 87.40521 -325.175372)
		(size 0.508)
		(drill 0.254)
		(layers "F.Cu" "B.Cu")
		(net "PVCCIN_CPU1")
	)
	(via
		(at 115.164362 -257.098546)
		(size 0.4572)
		(drill 0.2032)
		(layers "F.Cu" "B.Cu")
		(net "PVCCIN_CPU1")
	)
	(via
		(at 90.182192 -324.46976)
		(size 0.508)
		(drill 0.254)
		(layers "F.Cu" "B.Cu")
		(net "PVCCIN_CPU1")
	)
	(via
		(at 119.544592 -318.578738)
		(size 0.508)
		(drill 0.254)
		(layers "F.Cu" "B.Cu")
		(net "PVCCIN_CPU1")
	)
	(via
		(at 114.807492 -317.229998)
		(size 0.508)
		(drill 0.254)
		(layers "F.Cu" "B.Cu")
		(net "PVCCIN_CPU1")
	)
	(via
		(at 135.91794 -329.078336)
		(size 0.508)
		(drill 0.254)
		(layers "F.Cu" "B.Cu")
		(net "PVCCIN_CPU1")
	)
	(via
		(at 91.47048 -324.524116)
		(size 0.508)
		(drill 0.254)
		(layers "F.Cu" "B.Cu")
		(net "PVCCIN_CPU1")
	)
	(via
		(at 134.72414 -327.978516)
		(size 0.508)
		(drill 0.254)
		(layers "F.Cu" "B.Cu")
		(net "PVCCIN_CPU1")
	)
	(via
		(at 112.031272 -317.898018)
		(size 0.508)
		(drill 0.254)
		(layers "F.Cu" "B.Cu")
		(net "PVCCIN_CPU1")
	)
	(via
		(at 108.461048 -284.033722)
		(size 0.4572)
		(drill 0.2032)
		(layers "F.Cu" "B.Cu")
		(net "PVCCIN_CPU1")
	)
	(via
		(at 110.70082 -245.550944)
		(size 0.4572)
		(drill 0.2032)
		(layers "F.Cu" "B.Cu")
		(net "PVCCIN_CPU1")
	)
	(via
		(at 110.70082 -248.806462)
		(size 0.4572)
		(drill 0.2032)
		(layers "F.Cu" "B.Cu")
		(net "PVCCIN_CPU1")
	)
	(via
		(at 110.70082 -242.295172)
		(size 0.4572)
		(drill 0.2032)
		(layers "F.Cu" "B.Cu")
		(net "PVCCIN_CPU1")
	)
	(via
		(at 109.760766 -248.806462)
		(size 0.4572)
		(drill 0.2032)
		(layers "F.Cu" "B.Cu")
		(net "PVCCIN_CPU1")
	)
	(via
		(at 112.689894 -284.847538)
		(size 0.4572)
		(drill 0.2032)
		(layers "F.Cu" "B.Cu")
		(net "PVCCIN_CPU1")
	)
	(via
		(at 106.581448 -287.28924)
		(size 0.4572)
		(drill 0.2032)
		(layers "F.Cu" "B.Cu")
		(net "PVCCIN_CPU1")
	)
	(via
		(at 113.159794 -274.266914)
		(size 0.4572)
		(drill 0.2032)
		(layers "F.Cu" "B.Cu")
		(net "PVCCIN_CPU1")
	)
	(via
		(at 115.164362 -243.661946)
		(size 0.4572)
		(drill 0.2032)
		(layers "F.Cu" "B.Cu")
		(net "PVCCIN_CPU1")
	)
	(via
		(at 107.51439 -263.368536)
		(size 0.4572)
		(drill 0.2032)
		(layers "F.Cu" "B.Cu")
		(net "PVCCIN_CPU1")
	)
	(via
		(at 110.810548 -283.219906)
		(size 0.4572)
		(drill 0.2032)
		(layers "F.Cu" "B.Cu")
		(net "PVCCIN_CPU1")
	)
	(via
		(at 109.870494 -281.59202)
		(size 0.4572)
		(drill 0.2032)
		(layers "F.Cu" "B.Cu")
		(net "PVCCIN_CPU1")
	)
	(via
		(at 110.810548 -284.847538)
		(size 0.4572)
		(drill 0.2032)
		(layers "F.Cu" "B.Cu")
		(net "PVCCIN_CPU1")
	)
	(via
		(at 128.340612 -321.194938)
		(size 0.508)
		(drill 0.254)
		(layers "F.Cu" "B.Cu")
		(net "PVCCIN_CPU1")
	)
	(via
		(at 109.288072 -247.992392)
		(size 0.4572)
		(drill 0.2032)
		(layers "F.Cu" "B.Cu")
		(net "PVCCIN_CPU1")
	)
	(via
		(at 94.95409 -321.158362)
		(size 0.508)
		(drill 0.254)
		(layers "F.Cu" "B.Cu")
		(net "PVCCIN_CPU1")
	)
	(via
		(at 83.331812 -327.341738)
		(size 0.508)
		(drill 0.254)
		(layers "F.Cu" "B.Cu")
		(net "PVCCIN_CPU1")
	)
	(via
		(at 87.443056 -324.47357)
		(size 0.508)
		(drill 0.254)
		(layers "F.Cu" "B.Cu")
		(net "PVCCIN_CPU1")
	)
	(via
		(at 116.01196 -321.199256)
		(size 0.508)
		(drill 0.254)
		(layers "F.Cu" "B.Cu")
		(net "PVCCIN_CPU1")
	)
	(via
		(at 113.159794 -271.011396)
		(size 0.4572)
		(drill 0.2032)
		(layers "F.Cu" "B.Cu")
		(net "PVCCIN_CPU1")
	)
	(via
		(at 109.400594 -280.778204)
		(size 0.4572)
		(drill 0.2032)
		(layers "F.Cu" "B.Cu")
		(net "PVCCIN_CPU1")
	)
	(via
		(at 119.684292 -295.03878)
		(size 0.508)
		(drill 0.254)
		(layers "F.Cu" "B.Cu")
		(net "PVCCIN_CPU1")
	)
	(via
		(at 123.530614 -321.139312)
		(size 0.508)
		(drill 0.254)
		(layers "F.Cu" "B.Cu")
		(net "PVCCIN_CPU1")
	)
	(via
		(at 111.95685 -321.873372)
		(size 0.508)
		(drill 0.254)
		(layers "F.Cu" "B.Cu")
		(net "PVCCIN_CPU1")
	)
	(via
		(at 110.810802 -260.431026)
		(size 0.4572)
		(drill 0.2032)
		(layers "F.Cu" "B.Cu")
		(net "PVCCIN_CPU1")
	)
	(via
		(at 134.305294 -289.807142)
		(size 0.4572)
		(drill 0.2032)
		(layers "F.Cu" "B.Cu")
		(net "PVCCIN_CPU1")
	)
	(via
		(at 106.50093 -319.240154)
		(size 0.508)
		(drill 0.254)
		(layers "F.Cu" "B.Cu")
		(net "PVCCIN_CPU1")
	)
	(via
		(at 112.592104 -297.197526)
		(size 0.508)
		(drill 0.254)
		(layers "F.Cu" "B.Cu")
		(net "PVCCIN_CPU1")
	)
	(via
		(at 113.050066 -246.36476)
		(size 0.4572)
		(drill 0.2032)
		(layers "F.Cu" "B.Cu")
		(net "PVCCIN_CPU1")
	)
	(via
		(at 112.220248 -266.128246)
		(size 0.4572)
		(drill 0.2032)
		(layers "F.Cu" "B.Cu")
		(net "PVCCIN_CPU1")
	)
	(via
		(at 128.325372 -323.632576)
		(size 0.508)
		(drill 0.254)
		(layers "F.Cu" "B.Cu")
		(net "PVCCIN_CPU1")
	)
	(via
		(at 111.280448 -264.50036)
		(size 0.4572)
		(drill 0.2032)
		(layers "F.Cu" "B.Cu")
		(net "PVCCIN_CPU1")
	)
	(via
		(at 114.569748 -255.547876)
		(size 0.4572)
		(drill 0.2032)
		(layers "F.Cu" "B.Cu")
		(net "PVCCIN_CPU1")
	)
	(via
		(at 119.516398 -321.158362)
		(size 0.508)
		(drill 0.254)
		(layers "F.Cu" "B.Cu")
		(net "PVCCIN_CPU1")
	)
	(via
		(at 95.003112 -317.882778)
		(size 0.508)
		(drill 0.254)
		(layers "F.Cu" "B.Cu")
		(net "PVCCIN_CPU1")
	)
	(via
		(at 115.21059 -239.328452)
		(size 0.4572)
		(drill 0.2032)
		(layers "F.Cu" "B.Cu")
		(net "PVCCIN_CPU1")
	)
	(via
		(at 108.68025 -242.334542)
		(size 0.4572)
		(drill 0.2032)
		(layers "F.Cu" "B.Cu")
		(net "PVCCIN_CPU1")
	)
	(via
		(at 107.78363 -321.873372)
		(size 0.508)
		(drill 0.254)
		(layers "F.Cu" "B.Cu")
		(net "PVCCIN_CPU1")
	)
	(via
		(at 114.099594 -264.50036)
		(size 0.4572)
		(drill 0.2032)
		(layers "F.Cu" "B.Cu")
		(net "PVCCIN_CPU1")
	)
	(via
		(at 112.220248 -275.8948)
		(size 0.4572)
		(drill 0.2032)
		(layers "F.Cu" "B.Cu")
		(net "PVCCIN_CPU1")
	)
	(via
		(at 108.68025 -239.83442)
		(size 0.4572)
		(drill 0.2032)
		(layers "F.Cu" "B.Cu")
		(net "PVCCIN_CPU1")
	)
	(via
		(at 111.280448 -267.755878)
		(size 0.4572)
		(drill 0.2032)
		(layers "F.Cu" "B.Cu")
		(net "PVCCIN_CPU1")
	)
	(via
		(at 82.094832 -327.054718)
		(size 0.508)
		(drill 0.254)
		(layers "F.Cu" "B.Cu")
		(net "PVCCIN_CPU1")
	)
	(via
		(at 123.527566 -320.502534)
		(size 0.508)
		(drill 0.254)
		(layers "F.Cu" "B.Cu")
		(net "PVCCIN_CPU1")
	)
	(via
		(at 90.903552 -320.547238)
		(size 0.508)
		(drill 0.254)
		(layers "F.Cu" "B.Cu")
		(net "PVCCIN_CPU1")
	)
	(via
		(at 111.280448 -269.38351)
		(size 0.4572)
		(drill 0.2032)
		(layers "F.Cu" "B.Cu")
		(net "PVCCIN_CPU1")
	)
	(via
		(at 86.805516 -323.21119)
		(size 0.508)
		(drill 0.254)
		(layers "F.Cu" "B.Cu")
		(net "PVCCIN_CPU1")
	)
	(via
		(at 108.68025 -261.951216)
		(size 0.4572)
		(drill 0.2032)
		(layers "F.Cu" "B.Cu")
		(net "PVCCIN_CPU1")
	)
	(via
		(at 108.930694 -281.59202)
		(size 0.4572)
		(drill 0.2032)
		(layers "F.Cu" "B.Cu")
		(net "PVCCIN_CPU1")
	)
	(via
		(at 114.569748 -258.803394)
		(size 0.4572)
		(drill 0.2032)
		(layers "F.Cu" "B.Cu")
		(net "PVCCIN_CPU1")
	)
	(via
		(at 107.17784 -297.077638)
		(size 0.508)
		(drill 0.254)
		(layers "F.Cu" "B.Cu")
		(net "PVCCIN_CPU1")
	)
	(via
		(at 105.641648 -285.661354)
		(size 0.4572)
		(drill 0.2032)
		(layers "F.Cu" "B.Cu")
		(net "PVCCIN_CPU1")
	)
	(via
		(at 134.721092 -327.293478)
		(size 0.508)
		(drill 0.254)
		(layers "F.Cu" "B.Cu")
		(net "PVCCIN_CPU1")
	)
	(via
		(at 109.29112 -244.736874)
		(size 0.4572)
		(drill 0.2032)
		(layers "F.Cu" "B.Cu")
		(net "PVCCIN_CPU1")
	)
	(via
		(at 106.588052 -317.237618)
		(size 0.508)
		(drill 0.254)
		(layers "F.Cu" "B.Cu")
		(net "PVCCIN_CPU1")
	)
	(via
		(at 136.562592 -327.669398)
		(size 0.508)
		(drill 0.254)
		(layers "F.Cu" "B.Cu")
		(net "PVCCIN_CPU1")
	)
	(via
		(at 122.890026 -319.875154)
		(size 0.508)
		(drill 0.254)
		(layers "F.Cu" "B.Cu")
		(net "PVCCIN_CPU1")
	)
	(via
		(at 98.965258 -320.502534)
		(size 0.508)
		(drill 0.254)
		(layers "F.Cu" "B.Cu")
		(net "PVCCIN_CPU1")
	)
	(via
		(at 110.700312 -319.198498)
		(size 0.508)
		(drill 0.254)
		(layers "F.Cu" "B.Cu")
		(net "PVCCIN_CPU1")
	)
	(via
		(at 86.805516 -324.48119)
		(size 0.508)
		(drill 0.254)
		(layers "F.Cu" "B.Cu")
		(net "PVCCIN_CPU1")
	)
	(via
		(at 99.689412 -317.898018)
		(size 0.508)
		(drill 0.254)
		(layers "F.Cu" "B.Cu")
		(net "PVCCIN_CPU1")
	)
	(via
		(at 135.269732 -327.651618)
		(size 0.508)
		(drill 0.254)
		(layers "F.Cu" "B.Cu")
		(net "PVCCIN_CPU1")
	)
	(via
		(at 86.113112 -323.821298)
		(size 0.508)
		(drill 0.254)
		(layers "F.Cu" "B.Cu")
		(net "PVCCIN_CPU1")
	)
	(via
		(at 112.220248 -285.661354)
		(size 0.4572)
		(drill 0.2032)
		(layers "F.Cu" "B.Cu")
		(net "PVCCIN_CPU1")
	)
	(via
		(at 112.689894 -275.08073)
		(size 0.4572)
		(drill 0.2032)
		(layers "F.Cu" "B.Cu")
		(net "PVCCIN_CPU1")
	)
	(via
		(at 128.371092 -319.881758)
		(size 0.508)
		(drill 0.254)
		(layers "F.Cu" "B.Cu")
		(net "PVCCIN_CPU1")
	)
	(via
		(at 114.717068 -320.510154)
		(size 0.508)
		(drill 0.254)
		(layers "F.Cu" "B.Cu")
		(net "PVCCIN_CPU1")
	)
	(via
		(at 118.798848 -288.917126)
		(size 0.4572)
		(drill 0.2032)
		(layers "F.Cu" "B.Cu")
		(net "PVCCIN_CPU1")
	)
	(via
		(at 107.17784 -292.95598)
		(size 0.508)
		(drill 0.254)
		(layers "F.Cu" "B.Cu")
		(net "PVCCIN_CPU1")
	)
	(via
		(at 113.227104 -292.95598)
		(size 0.508)
		(drill 0.254)
		(layers "F.Cu" "B.Cu")
		(net "PVCCIN_CPU1")
	)
	(via
		(at 115.509294 -284.847538)
		(size 0.4572)
		(drill 0.2032)
		(layers "F.Cu" "B.Cu")
		(net "PVCCIN_CPU1")
	)
	(via
		(at 134.7343 -329.441556)
		(size 0.508)
		(drill 0.254)
		(layers "F.Cu" "B.Cu")
		(net "PVCCIN_CPU1")
	)
	(via
		(at 111.340392 -319.251584)
		(size 0.508)
		(drill 0.254)
		(layers "F.Cu" "B.Cu")
		(net "PVCCIN_CPU1")
	)
	(via
		(at 120.222772 -317.280798)
		(size 0.508)
		(drill 0.254)
		(layers "F.Cu" "B.Cu")
		(net "PVCCIN_CPU1")
	)
	(via
		(at 117.201696 -242.98148)
		(size 0.4572)
		(drill 0.2032)
		(layers "F.Cu" "B.Cu")
		(net "PVCCIN_CPU1")
	)
	(via
		(at 112.689894 -271.825212)
		(size 0.4572)
		(drill 0.2032)
		(layers "F.Cu" "B.Cu")
		(net "PVCCIN_CPU1")
	)
	(via
		(at 134.759192 -325.977758)
		(size 0.508)
		(drill 0.254)
		(layers "F.Cu" "B.Cu")
		(net "PVCCIN_CPU1")
	)
	(via
		(at 95.666052 -317.245238)
		(size 0.508)
		(drill 0.254)
		(layers "F.Cu" "B.Cu")
		(net "PVCCIN_CPU1")
	)
	(via
		(at 94.304612 -319.851278)
		(size 0.508)
		(drill 0.254)
		(layers "F.Cu" "B.Cu")
		(net "PVCCIN_CPU1")
	)
	(via
		(at 124.16536 -321.214496)
		(size 0.508)
		(drill 0.254)
		(layers "F.Cu" "B.Cu")
		(net "PVCCIN_CPU1")
	)
	(via
		(at 90.179144 -323.197982)
		(size 0.508)
		(drill 0.254)
		(layers "F.Cu" "B.Cu")
		(net "PVCCIN_CPU1")
	)
	(via
		(at 108.68025 -239.25022)
		(size 0.4572)
		(drill 0.2032)
		(layers "F.Cu" "B.Cu")
		(net "PVCCIN_CPU1")
	)
	(via
		(at 82.686652 -328.405998)
		(size 0.508)
		(drill 0.254)
		(layers "F.Cu" "B.Cu")
		(net "PVCCIN_CPU1")
	)
	(via
		(at 90.179144 -322.562982)
		(size 0.508)
		(drill 0.254)
		(layers "F.Cu" "B.Cu")
		(net "PVCCIN_CPU1")
	)
	(via
		(at 106.54284 -297.077638)
		(size 0.508)
		(drill 0.254)
		(layers "F.Cu" "B.Cu")
		(net "PVCCIN_CPU1")
	)
	(via
		(at 95.57639 -321.873372)
		(size 0.508)
		(drill 0.254)
		(layers "F.Cu" "B.Cu")
		(net "PVCCIN_CPU1")
	)
	(via
		(at 103.171752 -317.898018)
		(size 0.508)
		(drill 0.254)
		(layers "F.Cu" "B.Cu")
		(net "PVCCIN_CPU1")
	)
	(via
		(at 112.220502 -254.733806)
		(size 0.4572)
		(drill 0.2032)
		(layers "F.Cu" "B.Cu")
		(net "PVCCIN_CPU1")
	)
	(via
		(at 90.888312 -321.200018)
		(size 0.508)
		(drill 0.254)
		(layers "F.Cu" "B.Cu")
		(net "PVCCIN_CPU1")
	)
	(via
		(at 114.46002 -243.923058)
		(size 0.4572)
		(drill 0.2032)
		(layers "F.Cu" "B.Cu")
		(net "PVCCIN_CPU1")
	)
	(via
		(at 108.930694 -288.103056)
		(size 0.4572)
		(drill 0.2032)
		(layers "F.Cu" "B.Cu")
		(net "PVCCIN_CPU1")
	)
	(via
		(at 77.228954 -346.825062)
		(size 0.508)
		(drill 0.254)
		(layers "F.Cu" "B.Cu")
		(net "PVCCIN_CPU1")
	)
	(via
		(at 111.64062 -239.039654)
		(size 0.4572)
		(drill 0.2032)
		(layers "F.Cu" "B.Cu")
		(net "PVCCIN_CPU1")
	)
	(via
		(at 107.99699 -242.98148)
		(size 0.4572)
		(drill 0.2032)
		(layers "F.Cu" "B.Cu")
		(net "PVCCIN_CPU1")
	)
	(via
		(at 116.013992 -320.514218)
		(size 0.508)
		(drill 0.254)
		(layers "F.Cu" "B.Cu")
		(net "PVCCIN_CPU1")
	)
	(via
		(at 114.46002 -248.806462)
		(size 0.4572)
		(drill 0.2032)
		(layers "F.Cu" "B.Cu")
		(net "PVCCIN_CPU1")
	)
	(via
		(at 114.792252 -317.882778)
		(size 0.508)
		(drill 0.254)
		(layers "F.Cu" "B.Cu")
		(net "PVCCIN_CPU1")
	)
	(via
		(at 114.100102 -262.872728)
		(size 0.4572)
		(drill 0.2032)
		(layers "F.Cu" "B.Cu")
		(net "PVCCIN_CPU1")
	)
	(via
		(at 113.160048 -254.733806)
		(size 0.4572)
		(drill 0.2032)
		(layers "F.Cu" "B.Cu")
		(net "PVCCIN_CPU1")
	)
	(via
		(at 111.750094 -288.103056)
		(size 0.4572)
		(drill 0.2032)
		(layers "F.Cu" "B.Cu")
		(net "PVCCIN_CPU1")
	)
	(via
		(at 111.750094 -265.314176)
		(size 0.4572)
		(drill 0.2032)
		(layers "F.Cu" "B.Cu")
		(net "PVCCIN_CPU1")
	)
	(via
		(at 91.520772 -321.875658)
		(size 0.508)
		(drill 0.254)
		(layers "F.Cu" "B.Cu")
		(net "PVCCIN_CPU1")
	)
	(via
		(at 115.039648 -280.778204)
		(size 0.4572)
		(drill 0.2032)
		(layers "F.Cu" "B.Cu")
		(net "PVCCIN_CPU1")
	)
	(via
		(at 135.27278 -329.802236)
		(size 0.508)
		(drill 0.254)
		(layers "F.Cu" "B.Cu")
		(net "PVCCIN_CPU1")
	)
	(via
		(at 82.686652 -329.040998)
		(size 0.508)
		(drill 0.254)
		(layers "F.Cu" "B.Cu")
		(net "PVCCIN_CPU1")
	)
	(via
		(at 113.050066 -249.620278)
		(size 0.4572)
		(drill 0.2032)
		(layers "F.Cu" "B.Cu")
		(net "PVCCIN_CPU1")
	)
	(via
		(at 109.870494 -288.103056)
		(size 0.4572)
		(drill 0.2032)
		(layers "F.Cu" "B.Cu")
		(net "PVCCIN_CPU1")
	)
	(via
		(at 112.220248 -269.38351)
		(size 0.4572)
		(drill 0.2032)
		(layers "F.Cu" "B.Cu")
		(net "PVCCIN_CPU1")
	)
	(via
		(at 109.870494 -265.314176)
		(size 0.4572)
		(drill 0.2032)
		(layers "F.Cu" "B.Cu")
		(net "PVCCIN_CPU1")
	)
	(via
		(at 127.0381 -323.906896)
		(size 0.508)
		(drill 0.254)
		(layers "F.Cu" "B.Cu")
		(net "PVCCIN_CPU1")
	)
	(via
		(at 98.327718 -319.875154)
		(size 0.508)
		(drill 0.254)
		(layers "F.Cu" "B.Cu")
		(net "PVCCIN_CPU1")
	)
	(via
		(at 112.11052 -243.109242)
		(size 0.4572)
		(drill 0.2032)
		(layers "F.Cu" "B.Cu")
		(net "PVCCIN_CPU1")
	)
	(via
		(at 119.516398 -319.888362)
		(size 0.508)
		(drill 0.254)
		(layers "F.Cu" "B.Cu")
		(net "PVCCIN_CPU1")
	)
	(via
		(at 83.354672 -325.365618)
		(size 0.508)
		(drill 0.254)
		(layers "F.Cu" "B.Cu")
		(net "PVCCIN_CPU1")
	)
	(via
		(at 111.750094 -266.941808)
		(size 0.4572)
		(drill 0.2032)
		(layers "F.Cu" "B.Cu")
		(net "PVCCIN_CPU1")
	)
	(via
		(at 113.159794 -277.522432)
		(size 0.4572)
		(drill 0.2032)
		(layers "F.Cu" "B.Cu")
		(net "PVCCIN_CPU1")
	)
	(via
		(at 111.280448 -288.993326)
		(size 0.4572)
		(drill 0.2032)
		(layers "F.Cu" "B.Cu")
		(net "PVCCIN_CPU1")
	)
	(via
		(at 109.400594 -285.661354)
		(size 0.4572)
		(drill 0.2032)
		(layers "F.Cu" "B.Cu")
		(net "PVCCIN_CPU1")
	)
	(via
		(at 110.810548 -271.825212)
		(size 0.4572)
		(drill 0.2032)
		(layers "F.Cu" "B.Cu")
		(net "PVCCIN_CPU1")
	)
	(via
		(at 131.699 -325.133716)
		(size 0.508)
		(drill 0.254)
		(layers "F.Cu" "B.Cu")
		(net "PVCCIN_CPU1")
	)
	(via
		(at 119.736616 -254.02032)
		(size 0.4572)
		(drill 0.2032)
		(layers "F.Cu" "B.Cu")
		(net "PVCCIN_CPU1")
	)
	(via
		(at 106.73207 -246.6594)
		(size 0.4572)
		(drill 0.2032)
		(layers "F.Cu" "B.Cu")
		(net "PVCCIN_CPU1")
	)
	(via
		(at 107.990894 -289.807142)
		(size 0.4572)
		(drill 0.2032)
		(layers "F.Cu" "B.Cu")
		(net "PVCCIN_CPU1")
	)
	(via
		(at 110.810548 -273.453098)
		(size 0.4572)
		(drill 0.2032)
		(layers "F.Cu" "B.Cu")
		(net "PVCCIN_CPU1")
	)
	(via
		(at 110.761272 -317.237618)
		(size 0.508)
		(drill 0.254)
		(layers "F.Cu" "B.Cu")
		(net "PVCCIN_CPU1")
	)
	(via
		(at 113.050066 -244.736874)
		(size 0.4572)
		(drill 0.2032)
		(layers "F.Cu" "B.Cu")
		(net "PVCCIN_CPU1")
	)
	(via
		(at 122.893074 -321.146932)
		(size 0.508)
		(drill 0.254)
		(layers "F.Cu" "B.Cu")
		(net "PVCCIN_CPU1")
	)
	(via
		(at 127.0381 -323.175376)
		(size 0.508)
		(drill 0.254)
		(layers "F.Cu" "B.Cu")
		(net "PVCCIN_CPU1")
	)
	(via
		(at 112.220248 -274.266914)
		(size 0.4572)
		(drill 0.2032)
		(layers "F.Cu" "B.Cu")
		(net "PVCCIN_CPU1")
	)
	(via
		(at 95.59163 -319.880742)
		(size 0.508)
		(drill 0.254)
		(layers "F.Cu" "B.Cu")
		(net "PVCCIN_CPU1")
	)
	(via
		(at 116.919248 -284.033722)
		(size 0.4572)
		(drill 0.2032)
		(layers "F.Cu" "B.Cu")
		(net "PVCCIN_CPU1")
	)
	(via
		(at 107.17784 -295.03878)
		(size 0.508)
		(drill 0.254)
		(layers "F.Cu" "B.Cu")
		(net "PVCCIN_CPU1")
	)
	(via
		(at 113.862104 -297.197526)
		(size 0.508)
		(drill 0.254)
		(layers "F.Cu" "B.Cu")
		(net "PVCCIN_CPU1")
	)
	(via
		(at 116.434616 -254.02032)
		(size 0.4572)
		(drill 0.2032)
		(layers "F.Cu" "B.Cu")
		(net "PVCCIN_CPU1")
	)
	(via
		(at 102.46106 -321.214496)
		(size 0.508)
		(drill 0.254)
		(layers "F.Cu" "B.Cu")
		(net "PVCCIN_CPU1")
	)
	(via
		(at 115.039648 -285.661354)
		(size 0.4572)
		(drill 0.2032)
		(layers "F.Cu" "B.Cu")
		(net "PVCCIN_CPU1")
	)
	(via
		(at 111.640366 -243.923058)
		(size 0.4572)
		(drill 0.2032)
		(layers "F.Cu" "B.Cu")
		(net "PVCCIN_CPU1")
	)
	(via
		(at 106.111294 -286.475424)
		(size 0.4572)
		(drill 0.2032)
		(layers "F.Cu" "B.Cu")
		(net "PVCCIN_CPU1")
	)
	(via
		(at 81.426812 -327.710038)
		(size 0.508)
		(drill 0.254)
		(layers "F.Cu" "B.Cu")
		(net "PVCCIN_CPU1")
	)
	(via
		(at 103.764842 -321.150742)
		(size 0.508)
		(drill 0.254)
		(layers "F.Cu" "B.Cu")
		(net "PVCCIN_CPU1")
	)
	(via
		(at 102.549452 -317.252858)
		(size 0.508)
		(drill 0.254)
		(layers "F.Cu" "B.Cu")
		(net "PVCCIN_CPU1")
	)
	(via
		(at 112.690148 -253.91999)
		(size 0.4572)
		(drill 0.2032)
		(layers "F.Cu" "B.Cu")
		(net "PVCCIN_CPU1")
	)
	(via
		(at 111.280702 -261.245096)
		(size 0.4572)
		(drill 0.2032)
		(layers "F.Cu" "B.Cu")
		(net "PVCCIN_CPU1")
	)
	(via
		(at 115.164362 -250.088146)
		(size 0.4572)
		(drill 0.2032)
		(layers "F.Cu" "B.Cu")
		(net "PVCCIN_CPU1")
	)
	(via
		(at 117.201696 -250.33732)
		(size 0.4572)
		(drill 0.2032)
		(layers "F.Cu" "B.Cu")
		(net "PVCCIN_CPU1")
	)
	(via
		(at 111.280448 -275.8948)
		(size 0.4572)
		(drill 0.2032)
		(layers "F.Cu" "B.Cu")
		(net "PVCCIN_CPU1")
	)
	(via
		(at 112.580166 -248.806462)
		(size 0.4572)
		(drill 0.2032)
		(layers "F.Cu" "B.Cu")
		(net "PVCCIN_CPU1")
	)
	(via
		(at 127.690372 -324.356476)
		(size 0.508)
		(drill 0.254)
		(layers "F.Cu" "B.Cu")
		(net "PVCCIN_CPU1")
	)
	(via
		(at 108.68025 -253.370334)
		(size 0.4572)
		(drill 0.2032)
		(layers "F.Cu" "B.Cu")
		(net "PVCCIN_CPU1")
	)
	(via
		(at 118.876572 -319.234058)
		(size 0.508)
		(drill 0.254)
		(layers "F.Cu" "B.Cu")
		(net "PVCCIN_CPU1")
	)
	(via
		(at 108.930694 -286.475424)
		(size 0.4572)
		(drill 0.2032)
		(layers "F.Cu" "B.Cu")
		(net "PVCCIN_CPU1")
	)
	(via
		(at 106.09199 -242.98148)
		(size 0.4572)
		(drill 0.2032)
		(layers "F.Cu" "B.Cu")
		(net "PVCCIN_CPU1")
	)
	(via
		(at 115.979194 -282.405836)
		(size 0.4572)
		(drill 0.2032)
		(layers "F.Cu" "B.Cu")
		(net "PVCCIN_CPU1")
	)
	(via
		(at 86.143592 -322.508118)
		(size 0.508)
		(drill 0.254)
		(layers "F.Cu" "B.Cu")
		(net "PVCCIN_CPU1")
	)
	(via
		(at 115.164362 -247.167146)
		(size 0.4572)
		(drill 0.2032)
		(layers "F.Cu" "B.Cu")
		(net "PVCCIN_CPU1")
	)
	(via
		(at 112.220248 -264.50036)
		(size 0.4572)
		(drill 0.2032)
		(layers "F.Cu" "B.Cu")
		(net "PVCCIN_CPU1")
	)
	(via
		(at 101.294184 -295.03878)
		(size 0.508)
		(drill 0.254)
		(layers "F.Cu" "B.Cu")
		(net "PVCCIN_CPU1")
	)
	(via
		(at 109.400594 -284.033722)
		(size 0.4572)
		(drill 0.2032)
		(layers "F.Cu" "B.Cu")
		(net "PVCCIN_CPU1")
	)
	(via
		(at 112.689894 -266.941808)
		(size 0.4572)
		(drill 0.2032)
		(layers "F.Cu" "B.Cu")
		(net "PVCCIN_CPU1")
	)
	(via
		(at 123.527566 -319.867534)
		(size 0.508)
		(drill 0.254)
		(layers "F.Cu" "B.Cu")
		(net "PVCCIN_CPU1")
	)
	(via
		(at 90.81389 -325.175372)
		(size 0.508)
		(drill 0.254)
		(layers "F.Cu" "B.Cu")
		(net "PVCCIN_CPU1")
	)
	(via
		(at 82.732372 -327.047098)
		(size 0.508)
		(drill 0.254)
		(layers "F.Cu" "B.Cu")
		(net "PVCCIN_CPU1")
	)
	(via
		(at 102.473252 -319.866518)
		(size 0.508)
		(drill 0.254)
		(layers "F.Cu" "B.Cu")
		(net "PVCCIN_CPU1")
	)
	(via
		(at 115.039648 -282.405836)
		(size 0.4572)
		(drill 0.2032)
		(layers "F.Cu" "B.Cu")
		(net "PVCCIN_CPU1")
	)
	(via
		(at 109.400848 -262.872728)
		(size 0.4572)
		(drill 0.2032)
		(layers "F.Cu" "B.Cu")
		(net "PVCCIN_CPU1")
	)
	(via
		(at 115.164362 -254.177546)
		(size 0.4572)
		(drill 0.2032)
		(layers "F.Cu" "B.Cu")
		(net "PVCCIN_CPU1")
	)
	(via
		(at 118.798848 -287.28924)
		(size 0.4572)
		(drill 0.2032)
		(layers "F.Cu" "B.Cu")
		(net "PVCCIN_CPU1")
	)
	(via
		(at 105.641648 -288.917126)
		(size 0.4572)
		(drill 0.2032)
		(layers "F.Cu" "B.Cu")
		(net "PVCCIN_CPU1")
	)
	(via
		(at 114.569494 -279.964134)
		(size 0.4572)
		(drill 0.2032)
		(layers "F.Cu" "B.Cu")
		(net "PVCCIN_CPU1")
	)
	(via
		(at 90.179144 -323.832982)
		(size 0.508)
		(drill 0.254)
		(layers "F.Cu" "B.Cu")
		(net "PVCCIN_CPU1")
	)
	(via
		(at 113.862104 -292.95598)
		(size 0.508)
		(drill 0.254)
		(layers "F.Cu" "B.Cu")
		(net "PVCCIN_CPU1")
	)
	(via
		(at 116.016532 -319.851278)
		(size 0.508)
		(drill 0.254)
		(layers "F.Cu" "B.Cu")
		(net "PVCCIN_CPU1")
	)
	(via
		(at 116.919248 -287.28924)
		(size 0.4572)
		(drill 0.2032)
		(layers "F.Cu" "B.Cu")
		(net "PVCCIN_CPU1")
	)
	(via
		(at 111.280702 -259.61721)
		(size 0.4572)
		(drill 0.2032)
		(layers "F.Cu" "B.Cu")
		(net "PVCCIN_CPU1")
	)
	(via
		(at 110.810548 -275.08073)
		(size 0.4572)
		(drill 0.2032)
		(layers "F.Cu" "B.Cu")
		(net "PVCCIN_CPU1")
	)
	(via
		(at 112.220248 -271.011396)
		(size 0.4572)
		(drill 0.2032)
		(layers "F.Cu" "B.Cu")
		(net "PVCCIN_CPU1")
	)
	(via
		(at 124.215652 -318.566038)
		(size 0.508)
		(drill 0.254)
		(layers "F.Cu" "B.Cu")
		(net "PVCCIN_CPU1")
	)
	(via
		(at 107.797092 -319.858898)
		(size 0.508)
		(drill 0.254)
		(layers "F.Cu" "B.Cu")
		(net "PVCCIN_CPU1")
	)
	(via
		(at 112.220502 -261.245096)
		(size 0.4572)
		(drill 0.2032)
		(layers "F.Cu" "B.Cu")
		(net "PVCCIN_CPU1")
	)
	(via
		(at 98.965258 -319.232534)
		(size 0.508)
		(drill 0.254)
		(layers "F.Cu" "B.Cu")
		(net "PVCCIN_CPU1")
	)
	(via
		(at 135.904732 -327.661778)
		(size 0.508)
		(drill 0.254)
		(layers "F.Cu" "B.Cu")
		(net "PVCCIN_CPU1")
	)
	(via
		(at 108.461048 -287.28924)
		(size 0.4572)
		(drill 0.2032)
		(layers "F.Cu" "B.Cu")
		(net "PVCCIN_CPU1")
	)
	(via
		(at 114.569748 -263.686798)
		(size 0.4572)
		(drill 0.2032)
		(layers "F.Cu" "B.Cu")
		(net "PVCCIN_CPU1")
	)
	(via
		(at 111.17072 -241.481356)
		(size 0.4572)
		(drill 0.2032)
		(layers "F.Cu" "B.Cu")
		(net "PVCCIN_CPU1")
	)
	(via
		(at 82.049112 -329.048618)
		(size 0.508)
		(drill 0.254)
		(layers "F.Cu" "B.Cu")
		(net "PVCCIN_CPU1")
	)
	(via
		(at 109.400848 -254.733806)
		(size 0.4572)
		(drill 0.2032)
		(layers "F.Cu" "B.Cu")
		(net "PVCCIN_CPU1")
	)
	(via
		(at 109.29112 -241.481356)
		(size 0.4572)
		(drill 0.2032)
		(layers "F.Cu" "B.Cu")
		(net "PVCCIN_CPU1")
	)
	(via
		(at 113.159794 -256.361692)
		(size 0.4572)
		(drill 0.2032)
		(layers "F.Cu" "B.Cu")
		(net "PVCCIN_CPU1")
	)
	(via
		(at 115.979194 -287.28924)
		(size 0.4572)
		(drill 0.2032)
		(layers "F.Cu" "B.Cu")
		(net "PVCCIN_CPU1")
	)
	(via
		(at 95.588582 -319.243964)
		(size 0.508)
		(drill 0.254)
		(layers "F.Cu" "B.Cu")
		(net "PVCCIN_CPU1")
	)
	(via
		(at 110.810802 -257.175508)
		(size 0.4572)
		(drill 0.2032)
		(layers "F.Cu" "B.Cu")
		(net "PVCCIN_CPU1")
	)
	(via
		(at 102.488492 -319.213738)
		(size 0.508)
		(drill 0.254)
		(layers "F.Cu" "B.Cu")
		(net "PVCCIN_CPU1")
	)
	(via
		(at 135.245094 -289.807142)
		(size 0.4572)
		(drill 0.2032)
		(layers "F.Cu" "B.Cu")
		(net "PVCCIN_CPU1")
	)
	(via
		(at 114.099848 -285.661354)
		(size 0.4572)
		(drill 0.2032)
		(layers "F.Cu" "B.Cu")
		(net "PVCCIN_CPU1")
	)
	(via
		(at 115.354608 -319.867534)
		(size 0.508)
		(drill 0.254)
		(layers "F.Cu" "B.Cu")
		(net "PVCCIN_CPU1")
	)
	(via
		(at 107.36199 -254.01524)
		(size 0.4572)
		(drill 0.2032)
		(layers "F.Cu" "B.Cu")
		(net "PVCCIN_CPU1")
	)
	(via
		(at 135.27278 -329.070716)
		(size 0.508)
		(drill 0.254)
		(layers "F.Cu" "B.Cu")
		(net "PVCCIN_CPU1")
	)
	(via
		(at 112.689894 -265.314176)
		(size 0.4572)
		(drill 0.2032)
		(layers "F.Cu" "B.Cu")
		(net "PVCCIN_CPU1")
	)
	(via
		(at 111.280448 -287.28924)
		(size 0.4572)
		(drill 0.2032)
		(layers "F.Cu" "B.Cu")
		(net "PVCCIN_CPU1")
	)
	(via
		(at 117.859048 -288.917126)
		(size 0.4572)
		(drill 0.2032)
		(layers "F.Cu" "B.Cu")
		(net "PVCCIN_CPU1")
	)
	(via
		(at 112.220248 -288.993326)
		(size 0.4572)
		(drill 0.2032)
		(layers "F.Cu" "B.Cu")
		(net "PVCCIN_CPU1")
	)
	(via
		(at 135.27278 -328.339196)
		(size 0.508)
		(drill 0.254)
		(layers "F.Cu" "B.Cu")
		(net "PVCCIN_CPU1")
	)
	(via
		(at 112.58042 -239.039654)
		(size 0.4572)
		(drill 0.2032)
		(layers "F.Cu" "B.Cu")
		(net "PVCCIN_CPU1")
	)
	(via
		(at 108.68025 -257.670808)
		(size 0.4572)
		(drill 0.2032)
		(layers "F.Cu" "B.Cu")
		(net "PVCCIN_CPU1")
	)
	(via
		(at 117.201696 -254.02032)
		(size 0.4572)
		(drill 0.2032)
		(layers "F.Cu" "B.Cu")
		(net "PVCCIN_CPU1")
	)
	(via
		(at 115.164362 -243.077746)
		(size 0.4572)
		(drill 0.2032)
		(layers "F.Cu" "B.Cu")
		(net "PVCCIN_CPU1")
	)
	(via
		(at 111.750348 -257.175508)
		(size 0.4572)
		(drill 0.2032)
		(layers "F.Cu" "B.Cu")
		(net "PVCCIN_CPU1")
	)
	(via
		(at 116.434616 -246.6594)
		(size 0.4572)
		(drill 0.2032)
		(layers "F.Cu" "B.Cu")
		(net "PVCCIN_CPU1")
	)
	(via
		(at 82.049112 -329.683618)
		(size 0.508)
		(drill 0.254)
		(layers "F.Cu" "B.Cu")
		(net "PVCCIN_CPU1")
	)
	(via
		(at 131.0513 -323.632576)
		(size 0.508)
		(drill 0.254)
		(layers "F.Cu" "B.Cu")
		(net "PVCCIN_CPU1")
	)
	(via
		(at 115.039648 -288.993326)
		(size 0.4572)
		(drill 0.2032)
		(layers "F.Cu" "B.Cu")
		(net "PVCCIN_CPU1")
	)
	(via
		(at 111.17072 -249.620278)
		(size 0.4572)
		(drill 0.2032)
		(layers "F.Cu" "B.Cu")
		(net "PVCCIN_CPU1")
	)
	(via
		(at 104.56799 -242.98148)
		(size 0.4572)
		(drill 0.2032)
		(layers "F.Cu" "B.Cu")
		(net "PVCCIN_CPU1")
	)
	(via
		(at 114.099848 -282.405836)
		(size 0.4572)
		(drill 0.2032)
		(layers "F.Cu" "B.Cu")
		(net "PVCCIN_CPU1")
	)
	(via
		(at 119.268494 -288.103056)
		(size 0.4572)
		(drill 0.2032)
		(layers "F.Cu" "B.Cu")
		(net "PVCCIN_CPU1")
	)
	(via
		(at 110.70082 -239.039654)
		(size 0.4572)
		(drill 0.2032)
		(layers "F.Cu" "B.Cu")
		(net "PVCCIN_CPU1")
	)
	(via
		(at 120.153938 -321.150742)
		(size 0.508)
		(drill 0.254)
		(layers "F.Cu" "B.Cu")
		(net "PVCCIN_CPU1")
	)
	(via
		(at 117.16893 -257.68554)
		(size 0.4572)
		(drill 0.2032)
		(layers "F.Cu" "B.Cu")
		(net "PVCCIN_CPU1")
	)
	(via
		(at 109.400594 -279.150318)
		(size 0.4572)
		(drill 0.2032)
		(layers "F.Cu" "B.Cu")
		(net "PVCCIN_CPU1")
	)
	(via
		(at 112.220248 -267.755878)
		(size 0.4572)
		(drill 0.2032)
		(layers "F.Cu" "B.Cu")
		(net "PVCCIN_CPU1")
	)
	(via
		(at 114.569494 -281.59202)
		(size 0.4572)
		(drill 0.2032)
		(layers "F.Cu" "B.Cu")
		(net "PVCCIN_CPU1")
	)
	(via
		(at 95.59163 -320.515742)
		(size 0.508)
		(drill 0.254)
		(layers "F.Cu" "B.Cu")
		(net "PVCCIN_CPU1")
	)
	(via
		(at 81.388712 -328.413618)
		(size 0.508)
		(drill 0.254)
		(layers "F.Cu" "B.Cu")
		(net "PVCCIN_CPU1")
	)
	(via
		(at 111.17072 -239.85347)
		(size 0.4572)
		(drill 0.2032)
		(layers "F.Cu" "B.Cu")
		(net "PVCCIN_CPU1")
	)
	(via
		(at 120.319292 -292.95598)
		(size 0.508)
		(drill 0.254)
		(layers "F.Cu" "B.Cu")
		(net "PVCCIN_CPU1")
	)
	(via
		(at 108.930694 -279.964134)
		(size 0.4572)
		(drill 0.2032)
		(layers "F.Cu" "B.Cu")
		(net "PVCCIN_CPU1")
	)
	(via
		(at 90.17635 -325.182992)
		(size 0.508)
		(drill 0.254)
		(layers "F.Cu" "B.Cu")
		(net "PVCCIN_CPU1")
	)
	(via
		(at 116.00307 -321.865752)
		(size 0.508)
		(drill 0.254)
		(layers "F.Cu" "B.Cu")
		(net "PVCCIN_CPU1")
	)
	(via
		(at 110.810548 -276.708616)
		(size 0.4572)
		(drill 0.2032)
		(layers "F.Cu" "B.Cu")
		(net "PVCCIN_CPU1")
	)
	(via
		(at 115.509294 -281.59202)
		(size 0.4572)
		(drill 0.2032)
		(layers "F.Cu" "B.Cu")
		(net "PVCCIN_CPU1")
	)
	(via
		(at 103.761794 -319.243964)
		(size 0.508)
		(drill 0.254)
		(layers "F.Cu" "B.Cu")
		(net "PVCCIN_CPU1")
	)
	(via
		(at 104.16159 -254.02032)
		(size 0.4572)
		(drill 0.2032)
		(layers "F.Cu" "B.Cu")
		(net "PVCCIN_CPU1")
	)
	(via
		(at 103.127302 -320.523362)
		(size 0.508)
		(drill 0.254)
		(layers "F.Cu" "B.Cu")
		(net "PVCCIN_CPU1")
	)
	(via
		(at 86.128352 -323.160898)
		(size 0.508)
		(drill 0.254)
		(layers "F.Cu" "B.Cu")
		(net "PVCCIN_CPU1")
	)
	(via
		(at 112.220248 -287.28924)
		(size 0.4572)
		(drill 0.2032)
		(layers "F.Cu" "B.Cu")
		(net "PVCCIN_CPU1")
	)
	(via
		(at 120.192292 -318.593978)
		(size 0.508)
		(drill 0.254)
		(layers "F.Cu" "B.Cu")
		(net "PVCCIN_CPU1")
	)
	(via
		(at 114.46002 -239.039654)
		(size 0.4572)
		(drill 0.2032)
		(layers "F.Cu" "B.Cu")
		(net "PVCCIN_CPU1")
	)
	(via
		(at 107.858052 -317.898018)
		(size 0.508)
		(drill 0.254)
		(layers "F.Cu" "B.Cu")
		(net "PVCCIN_CPU1")
	)
	(via
		(at 111.750348 -262.058912)
		(size 0.4572)
		(drill 0.2032)
		(layers "F.Cu" "B.Cu")
		(net "PVCCIN_CPU1")
	)
	(via
		(at 111.280702 -256.361692)
		(size 0.4572)
		(drill 0.2032)
		(layers "F.Cu" "B.Cu")
		(net "PVCCIN_CPU1")
	)
	(via
		(at 111.34344 -321.158362)
		(size 0.508)
		(drill 0.254)
		(layers "F.Cu" "B.Cu")
		(net "PVCCIN_CPU1")
	)
	(via
		(at 109.400594 -288.993326)
		(size 0.4572)
		(drill 0.2032)
		(layers "F.Cu" "B.Cu")
		(net "PVCCIN_CPU1")
	)
	(via
		(at 122.87123 -321.873372)
		(size 0.508)
		(drill 0.254)
		(layers "F.Cu" "B.Cu")
		(net "PVCCIN_CPU1")
	)
	(via
		(at 111.750094 -279.964134)
		(size 0.4572)
		(drill 0.2032)
		(layers "F.Cu" "B.Cu")
		(net "PVCCIN_CPU1")
	)
	(via
		(at 115.979194 -285.661354)
		(size 0.4572)
		(drill 0.2032)
		(layers "F.Cu" "B.Cu")
		(net "PVCCIN_CPU1")
	)
	(via
		(at 112.11052 -244.736874)
		(size 0.4572)
		(drill 0.2032)
		(layers "F.Cu" "B.Cu")
		(net "PVCCIN_CPU1")
	)
	(via
		(at 112.689894 -286.475424)
		(size 0.4572)
		(drill 0.2032)
		(layers "F.Cu" "B.Cu")
		(net "PVCCIN_CPU1")
	)
	(via
		(at 116.434616 -250.33732)
		(size 0.4572)
		(drill 0.2032)
		(layers "F.Cu" "B.Cu")
		(net "PVCCIN_CPU1")
	)
	(via
		(at 111.280448 -272.639282)
		(size 0.4572)
		(drill 0.2032)
		(layers "F.Cu" "B.Cu")
		(net "PVCCIN_CPU1")
	)
	(via
		(at 122.945652 -317.898018)
		(size 0.508)
		(drill 0.254)
		(layers "F.Cu" "B.Cu")
		(net "PVCCIN_CPU1")
	)
	(via
		(at 127.050292 -321.827398)
		(size 0.508)
		(drill 0.254)
		(layers "F.Cu" "B.Cu")
		(net "PVCCIN_CPU1")
	)
	(via
		(at 131.69646 -324.364096)
		(size 0.508)
		(drill 0.254)
		(layers "F.Cu" "B.Cu")
		(net "PVCCIN_CPU1")
	)
	(via
		(at 137.21334 -329.809856)
		(size 0.508)
		(drill 0.254)
		(layers "F.Cu" "B.Cu")
		(net "PVCCIN_CPU1")
	)
	(via
		(at 115.039648 -287.28924)
		(size 0.4572)
		(drill 0.2032)
		(layers "F.Cu" "B.Cu")
		(net "PVCCIN_CPU1")
	)
	(via
		(at 110.340648 -266.128246)
		(size 0.4572)
		(drill 0.2032)
		(layers "F.Cu" "B.Cu")
		(net "PVCCIN_CPU1")
	)
	(via
		(at 107.051094 -288.103056)
		(size 0.4572)
		(drill 0.2032)
		(layers "F.Cu" "B.Cu")
		(net "PVCCIN_CPU1")
	)
	(via
		(at 103.127302 -321.158362)
		(size 0.508)
		(drill 0.254)
		(layers "F.Cu" "B.Cu")
		(net "PVCCIN_CPU1")
	)
	(via
		(at 111.750094 -278.336502)
		(size 0.4572)
		(drill 0.2032)
		(layers "F.Cu" "B.Cu")
		(net "PVCCIN_CPU1")
	)
	(via
		(at 110.810548 -263.686798)
		(size 0.4572)
		(drill 0.2032)
		(layers "F.Cu" "B.Cu")
		(net "PVCCIN_CPU1")
	)
	(via
		(at 119.101616 -250.33732)
		(size 0.4572)
		(drill 0.2032)
		(layers "F.Cu" "B.Cu")
		(net "PVCCIN_CPU1")
	)
	(via
		(at 87.443056 -323.83857)
		(size 0.508)
		(drill 0.254)
		(layers "F.Cu" "B.Cu")
		(net "PVCCIN_CPU1")
	)
	(via
		(at 107.195112 -318.543178)
		(size 0.508)
		(drill 0.254)
		(layers "F.Cu" "B.Cu")
		(net "PVCCIN_CPU1")
	)
	(via
		(at 111.750094 -273.453098)
		(size 0.4572)
		(drill 0.2032)
		(layers "F.Cu" "B.Cu")
		(net "PVCCIN_CPU1")
	)
	(via
		(at 119.736616 -250.33732)
		(size 0.4572)
		(drill 0.2032)
		(layers "F.Cu" "B.Cu")
		(net "PVCCIN_CPU1")
	)
	(via
		(at 116.062252 -318.550798)
		(size 0.508)
		(drill 0.254)
		(layers "F.Cu" "B.Cu")
		(net "PVCCIN_CPU1")
	)
	(via
		(at 86.76767 -325.182992)
		(size 0.508)
		(drill 0.254)
		(layers "F.Cu" "B.Cu")
		(net "PVCCIN_CPU1")
	)
	(via
		(at 114.100102 -259.61721)
		(size 0.4572)
		(drill 0.2032)
		(layers "F.Cu" "B.Cu")
		(net "PVCCIN_CPU1")
	)
	(via
		(at 109.870748 -258.803394)
		(size 0.4572)
		(drill 0.2032)
		(layers "F.Cu" "B.Cu")
		(net "PVCCIN_CPU1")
	)
	(via
		(at 107.13593 -321.858132)
		(size 0.508)
		(drill 0.254)
		(layers "F.Cu" "B.Cu")
		(net "PVCCIN_CPU1")
	)
	(via
		(at 86.11489 -325.175372)
		(size 0.508)
		(drill 0.254)
		(layers "F.Cu" "B.Cu")
		(net "PVCCIN_CPU1")
	)
	(via
		(at 107.991148 -286.475424)
		(size 0.4572)
		(drill 0.2032)
		(layers "F.Cu" "B.Cu")
		(net "PVCCIN_CPU1")
	)
	(via
		(at 94.95409 -319.888362)
		(size 0.508)
		(drill 0.254)
		(layers "F.Cu" "B.Cu")
		(net "PVCCIN_CPU1")
	)
	(via
		(at 112.580166 -245.550944)
		(size 0.4572)
		(drill 0.2032)
		(layers "F.Cu" "B.Cu")
		(net "PVCCIN_CPU1")
	)
	(via
		(at 106.49839 -321.865752)
		(size 0.508)
		(drill 0.254)
		(layers "F.Cu" "B.Cu")
		(net "PVCCIN_CPU1")
	)
	(via
		(at 111.17072 -244.736874)
		(size 0.4572)
		(drill 0.2032)
		(layers "F.Cu" "B.Cu")
		(net "PVCCIN_CPU1")
	)
	(via
		(at 113.159794 -259.61721)
		(size 0.4572)
		(drill 0.2032)
		(layers "F.Cu" "B.Cu")
		(net "PVCCIN_CPU1")
	)
	(via
		(at 112.689894 -273.453098)
		(size 0.4572)
		(drill 0.2032)
		(layers "F.Cu" "B.Cu")
		(net "PVCCIN_CPU1")
	)
	(via
		(at 116.092732 -317.237618)
		(size 0.508)
		(drill 0.254)
		(layers "F.Cu" "B.Cu")
		(net "PVCCIN_CPU1")
	)
	(via
		(at 109.760766 -240.66754)
		(size 0.4572)
		(drill 0.2032)
		(layers "F.Cu" "B.Cu")
		(net "PVCCIN_CPU1")
	)
	(via
		(at 110.810802 -262.058912)
		(size 0.4572)
		(drill 0.2032)
		(layers "F.Cu" "B.Cu")
		(net "PVCCIN_CPU1")
	)
	(via
		(at 128.355852 -320.534538)
		(size 0.508)
		(drill 0.254)
		(layers "F.Cu" "B.Cu")
		(net "PVCCIN_CPU1")
	)
	(via
		(at 124.230892 -317.905638)
		(size 0.508)
		(drill 0.254)
		(layers "F.Cu" "B.Cu")
		(net "PVCCIN_CPU1")
	)
	(via
		(at 108.461048 -280.778204)
		(size 0.4572)
		(drill 0.2032)
		(layers "F.Cu" "B.Cu")
		(net "PVCCIN_CPU1")
	)
	(via
		(at 114.100102 -257.989324)
		(size 0.4572)
		(drill 0.2032)
		(layers "F.Cu" "B.Cu")
		(net "PVCCIN_CPU1")
	)
	(via
		(at 119.559832 -317.918338)
		(size 0.508)
		(drill 0.254)
		(layers "F.Cu" "B.Cu")
		(net "PVCCIN_CPU1")
	)
	(via
		(at 115.445032 -317.222378)
		(size 0.508)
		(drill 0.254)
		(layers "F.Cu" "B.Cu")
		(net "PVCCIN_CPU1")
	)
	(via
		(at 120.319292 -295.03878)
		(size 0.508)
		(drill 0.254)
		(layers "F.Cu" "B.Cu")
		(net "PVCCIN_CPU1")
	)
	(via
		(at 127.725932 -319.851278)
		(size 0.508)
		(drill 0.254)
		(layers "F.Cu" "B.Cu")
		(net "PVCCIN_CPU1")
	)
	(via
		(at 107.36199 -242.98148)
		(size 0.4572)
		(drill 0.2032)
		(layers "F.Cu" "B.Cu")
		(net "PVCCIN_CPU1")
	)
	(via
		(at 120.153938 -320.515742)
		(size 0.508)
		(drill 0.254)
		(layers "F.Cu" "B.Cu")
		(net "PVCCIN_CPU1")
	)
	(via
		(at 127.042672 -320.498978)
		(size 0.508)
		(drill 0.254)
		(layers "F.Cu" "B.Cu")
		(net "PVCCIN_CPU1")
	)
	(via
		(at 131.69646 -323.632576)
		(size 0.508)
		(drill 0.254)
		(layers "F.Cu" "B.Cu")
		(net "PVCCIN_CPU1")
	)
	(via
		(at 119.101616 -254.02032)
		(size 0.4572)
		(drill 0.2032)
		(layers "F.Cu" "B.Cu")
		(net "PVCCIN_CPU1")
	)
	(via
		(at 108.461048 -288.942526)
		(size 0.4572)
		(drill 0.2032)
		(layers "F.Cu" "B.Cu")
		(net "PVCCIN_CPU1")
	)
	(via
		(at 90.819732 -324.46214)
		(size 0.508)
		(drill 0.254)
		(layers "F.Cu" "B.Cu")
		(net "PVCCIN_CPU1")
	)
	(via
		(at 117.858794 -284.033722)
		(size 0.4572)
		(drill 0.2032)
		(layers "F.Cu" "B.Cu")
		(net "PVCCIN_CPU1")
	)
	(via
		(at 106.71683 -250.3297)
		(size 0.4572)
		(drill 0.2032)
		(layers "F.Cu" "B.Cu")
		(net "PVCCIN_CPU1")
	)
	(via
		(at 103.764842 -319.880742)
		(size 0.508)
		(drill 0.254)
		(layers "F.Cu" "B.Cu")
		(net "PVCCIN_CPU1")
	)
	(via
		(at 112.689894 -276.708616)
		(size 0.4572)
		(drill 0.2032)
		(layers "F.Cu" "B.Cu")
		(net "PVCCIN_CPU1")
	)
	(via
		(at 111.280448 -279.150318)
		(size 0.4572)
		(drill 0.2032)
		(layers "F.Cu" "B.Cu")
		(net "PVCCIN_CPU1")
	)
	(via
		(at 105.171494 -289.807142)
		(size 0.4572)
		(drill 0.2032)
		(layers "F.Cu" "B.Cu")
		(net "PVCCIN_CPU1")
	)
	(via
		(at 112.580166 -240.66754)
		(size 0.4572)
		(drill 0.2032)
		(layers "F.Cu" "B.Cu")
		(net "PVCCIN_CPU1")
	)
	(via
		(at 107.79252 -321.206876)
		(size 0.508)
		(drill 0.254)
		(layers "F.Cu" "B.Cu")
		(net "PVCCIN_CPU1")
	)
	(via
		(at 111.280448 -284.033722)
		(size 0.4572)
		(drill 0.2032)
		(layers "F.Cu" "B.Cu")
		(net "PVCCIN_CPU1")
	)
	(via
		(at 113.99012 -241.481356)
		(size 0.4572)
		(drill 0.2032)
		(layers "F.Cu" "B.Cu")
		(net "PVCCIN_CPU1")
	)
	(via
		(at 111.17072 -246.36476)
		(size 0.4572)
		(drill 0.2032)
		(layers "F.Cu" "B.Cu")
		(net "PVCCIN_CPU1")
	)
	(via
		(at 122.960892 -317.245238)
		(size 0.508)
		(drill 0.254)
		(layers "F.Cu" "B.Cu")
		(net "PVCCIN_CPU1")
	)
	(via
		(at 135.284972 -326.991218)
		(size 0.508)
		(drill 0.254)
		(layers "F.Cu" "B.Cu")
		(net "PVCCIN_CPU1")
	)
	(via
		(at 113.227104 -295.03878)
		(size 0.508)
		(drill 0.254)
		(layers "F.Cu" "B.Cu")
		(net "PVCCIN_CPU1")
	)
	(via
		(at 113.99012 -247.992392)
		(size 0.4572)
		(drill 0.2032)
		(layers "F.Cu" "B.Cu")
		(net "PVCCIN_CPU1")
	)
	(via
		(at 120.13311 -321.908932)
		(size 0.508)
		(drill 0.254)
		(layers "F.Cu" "B.Cu")
		(net "PVCCIN_CPU1")
	)
	(via
		(at 110.810294 -265.314176)
		(size 0.4572)
		(drill 0.2032)
		(layers "F.Cu" "B.Cu")
		(net "PVCCIN_CPU1")
	)
	(via
		(at 90.266012 -320.554858)
		(size 0.508)
		(drill 0.254)
		(layers "F.Cu" "B.Cu")
		(net "PVCCIN_CPU1")
	)
	(via
		(at 99.704652 -317.245238)
		(size 0.508)
		(drill 0.254)
		(layers "F.Cu" "B.Cu")
		(net "PVCCIN_CPU1")
	)
	(via
		(at 110.340648 -264.50036)
		(size 0.4572)
		(drill 0.2032)
		(layers "F.Cu" "B.Cu")
		(net "PVCCIN_CPU1")
	)
	(via
		(at 114.717068 -319.240154)
		(size 0.508)
		(drill 0.254)
		(layers "F.Cu" "B.Cu")
		(net "PVCCIN_CPU1")
	)
	(via
		(at 108.68025 -249.710194)
		(size 0.4572)
		(drill 0.2032)
		(layers "F.Cu" "B.Cu")
		(net "PVCCIN_CPU1")
	)
	(via
		(at 106.557572 -318.550798)
		(size 0.508)
		(drill 0.254)
		(layers "F.Cu" "B.Cu")
		(net "PVCCIN_CPU1")
	)
	(via
		(at 123.50877 -321.865752)
		(size 0.508)
		(drill 0.254)
		(layers "F.Cu" "B.Cu")
		(net "PVCCIN_CPU1")
	)
	(via
		(at 115.509294 -286.475424)
		(size 0.4572)
		(drill 0.2032)
		(layers "F.Cu" "B.Cu")
		(net "PVCCIN_CPU1")
	)
	(via
		(at 112.220248 -280.778204)
		(size 0.4572)
		(drill 0.2032)
		(layers "F.Cu" "B.Cu")
		(net "PVCCIN_CPU1")
	)
	(via
		(at 112.11052 -239.85347)
		(size 0.4572)
		(drill 0.2032)
		(layers "F.Cu" "B.Cu")
		(net "PVCCIN_CPU1")
	)
	(via
		(at 103.127302 -319.888362)
		(size 0.508)
		(drill 0.254)
		(layers "F.Cu" "B.Cu")
		(net "PVCCIN_CPU1")
	)
	(via
		(at 112.689894 -268.569694)
		(size 0.4572)
		(drill 0.2032)
		(layers "F.Cu" "B.Cu")
		(net "PVCCIN_CPU1")
	)
	(via
		(at 108.68025 -250.294394)
		(size 0.4572)
		(drill 0.2032)
		(layers "F.Cu" "B.Cu")
		(net "PVCCIN_CPU1")
	)
	(via
		(at 115.164362 -257.682746)
		(size 0.4572)
		(drill 0.2032)
		(layers "F.Cu" "B.Cu")
		(net "PVCCIN_CPU1")
	)
	(via
		(at 114.100102 -254.733806)
		(size 0.4572)
		(drill 0.2032)
		(layers "F.Cu" "B.Cu")
		(net "PVCCIN_CPU1")
	)
	(via
		(at 111.280702 -262.872728)
		(size 0.4572)
		(drill 0.2032)
		(layers "F.Cu" "B.Cu")
		(net "PVCCIN_CPU1")
	)
	(via
		(at 105.45699 -242.98148)
		(size 0.4572)
		(drill 0.2032)
		(layers "F.Cu" "B.Cu")
		(net "PVCCIN_CPU1")
	)
	(via
		(at 95.650812 -317.898018)
		(size 0.508)
		(drill 0.254)
		(layers "F.Cu" "B.Cu")
		(net "PVCCIN_CPU1")
	)
	(via
		(at 114.099848 -279.150318)
		(size 0.4572)
		(drill 0.2032)
		(layers "F.Cu" "B.Cu")
		(net "PVCCIN_CPU1")
	)
	(via
		(at 108.68025 -260.782816)
		(size 0.4572)
		(drill 0.2032)
		(layers "F.Cu" "B.Cu")
		(net "PVCCIN_CPU1")
	)
	(via
		(at 110.67288 -321.199256)
		(size 0.508)
		(drill 0.254)
		(layers "F.Cu" "B.Cu")
		(net "PVCCIN_CPU1")
	)
	(via
		(at 107.991148 -288.103056)
		(size 0.4572)
		(drill 0.2032)
		(layers "F.Cu" "B.Cu")
		(net "PVCCIN_CPU1")
	)
	(via
		(at 111.750094 -268.569694)
		(size 0.4572)
		(drill 0.2032)
		(layers "F.Cu" "B.Cu")
		(net "PVCCIN_CPU1")
	)
	(via
		(at 111.750348 -260.431026)
		(size 0.4572)
		(drill 0.2032)
		(layers "F.Cu" "B.Cu")
		(net "PVCCIN_CPU1")
	)
	(via
		(at 116.919248 -285.661354)
		(size 0.4572)
		(drill 0.2032)
		(layers "F.Cu" "B.Cu")
		(net "PVCCIN_CPU1")
	)
	(via
		(at 81.388712 -329.048618)
		(size 0.508)
		(drill 0.254)
		(layers "F.Cu" "B.Cu")
		(net "PVCCIN_CPU1")
	)
	(via
		(at 122.890026 -319.240154)
		(size 0.508)
		(drill 0.254)
		(layers "F.Cu" "B.Cu")
		(net "PVCCIN_CPU1")
	)
	(via
		(at 114.569748 -253.91999)
		(size 0.4572)
		(drill 0.2032)
		(layers "F.Cu" "B.Cu")
		(net "PVCCIN_CPU1")
	)
	(via
		(at 113.159794 -261.245096)
		(size 0.4572)
		(drill 0.2032)
		(layers "F.Cu" "B.Cu")
		(net "PVCCIN_CPU1")
	)
	(via
		(at 114.46002 -242.295172)
		(size 0.4572)
		(drill 0.2032)
		(layers "F.Cu" "B.Cu")
		(net "PVCCIN_CPU1")
	)
	(via
		(at 91.475052 -323.176138)
		(size 0.508)
		(drill 0.254)
		(layers "F.Cu" "B.Cu")
		(net "PVCCIN_CPU1")
	)
	(via
		(at 110.810294 -278.336502)
		(size 0.4572)
		(drill 0.2032)
		(layers "F.Cu" "B.Cu")
		(net "PVCCIN_CPU1")
	)
	(via
		(at 107.44581 -257.67538)
		(size 0.4572)
		(drill 0.2032)
		(layers "F.Cu" "B.Cu")
		(net "PVCCIN_CPU1")
	)
	(via
		(at 136.5631 -328.346816)
		(size 0.508)
		(drill 0.254)
		(layers "F.Cu" "B.Cu")
		(net "PVCCIN_CPU1")
	)
	(via
		(at 108.461048 -282.405836)
		(size 0.4572)
		(drill 0.2032)
		(layers "F.Cu" "B.Cu")
		(net "PVCCIN_CPU1")
	)
	(via
		(at 117.904514 -337.259422)
		(size 0.508)
		(drill 0.254)
		(layers "F.Cu" "B.Cu")
		(net "PVCCIN_CPU1")
	)
	(via
		(at 106.111294 -289.807142)
		(size 0.4572)
		(drill 0.2032)
		(layers "F.Cu" "B.Cu")
		(net "PVCCIN_CPU1")
	)
	(via
		(at 102.518972 -318.566038)
		(size 0.508)
		(drill 0.254)
		(layers "F.Cu" "B.Cu")
		(net "PVCCIN_CPU1")
	)
	(via
		(at 111.17072 -243.109242)
		(size 0.4572)
		(drill 0.2032)
		(layers "F.Cu" "B.Cu")
		(net "PVCCIN_CPU1")
	)
	(via
		(at 87.440008 -322.566792)
		(size 0.508)
		(drill 0.254)
		(layers "F.Cu" "B.Cu")
		(net "PVCCIN_CPU1")
	)
	(via
		(at 94.95409 -320.523362)
		(size 0.508)
		(drill 0.254)
		(layers "F.Cu" "B.Cu")
		(net "PVCCIN_CPU1")
	)
	(via
		(at 120.153938 -319.880742)
		(size 0.508)
		(drill 0.254)
		(layers "F.Cu" "B.Cu")
		(net "PVCCIN_CPU1")
	)
	(via
		(at 114.569748 -260.431026)
		(size 0.4572)
		(drill 0.2032)
		(layers "F.Cu" "B.Cu")
		(net "PVCCIN_CPU1")
	)
	(via
		(at 111.750094 -281.59202)
		(size 0.4572)
		(drill 0.2032)
		(layers "F.Cu" "B.Cu")
		(net "PVCCIN_CPU1")
	)
	(via
		(at 113.159794 -280.778204)
		(size 0.4572)
		(drill 0.2032)
		(layers "F.Cu" "B.Cu")
		(net "PVCCIN_CPU1")
	)
	(via
		(at 106.78287 -257.67538)
		(size 0.4572)
		(drill 0.2032)
		(layers "F.Cu" "B.Cu")
		(net "PVCCIN_CPU1")
	)
	(via
		(at 115.979448 -280.778204)
		(size 0.4572)
		(drill 0.2032)
		(layers "F.Cu" "B.Cu")
		(net "PVCCIN_CPU1")
	)
	(via
		(at 132.348732 -324.682358)
		(size 0.508)
		(drill 0.254)
		(layers "F.Cu" "B.Cu")
		(net "PVCCIN_CPU1")
	)
	(via
		(at 98.965258 -319.867534)
		(size 0.508)
		(drill 0.254)
		(layers "F.Cu" "B.Cu")
		(net "PVCCIN_CPU1")
	)
	(via
		(at 111.17072 -247.992392)
		(size 0.4572)
		(drill 0.2032)
		(layers "F.Cu" "B.Cu")
		(net "PVCCIN_CPU1")
	)
	(via
		(at 110.810548 -281.59202)
		(size 0.4572)
		(drill 0.2032)
		(layers "F.Cu" "B.Cu")
		(net "PVCCIN_CPU1")
	)
	(via
		(at 101.294184 -292.87978)
		(size 0.508)
		(drill 0.254)
		(layers "F.Cu" "B.Cu")
		(net "PVCCIN_CPU1")
	)
	(via
		(at 103.186992 -317.245238)
		(size 0.508)
		(drill 0.254)
		(layers "F.Cu" "B.Cu")
		(net "PVCCIN_CPU1")
	)
	(via
		(at 115.357656 -321.139312)
		(size 0.508)
		(drill 0.254)
		(layers "F.Cu" "B.Cu")
		(net "PVCCIN_CPU1")
	)
	(via
		(at 113.99012 -249.620278)
		(size 0.4572)
		(drill 0.2032)
		(layers "F.Cu" "B.Cu")
		(net "PVCCIN_CPU1")
	)
	(via
		(at 110.810548 -286.475424)
		(size 0.4572)
		(drill 0.2032)
		(layers "F.Cu" "B.Cu")
		(net "PVCCIN_CPU1")
	)
	(via
		(at 107.051094 -286.475424)
		(size 0.4572)
		(drill 0.2032)
		(layers "F.Cu" "B.Cu")
		(net "PVCCIN_CPU1")
	)
	(via
		(at 107.36199 -250.33732)
		(size 0.4572)
		(drill 0.2032)
		(layers "F.Cu" "B.Cu")
		(net "PVCCIN_CPU1")
	)
	(via
		(at 113.227104 -297.197526)
		(size 0.508)
		(drill 0.254)
		(layers "F.Cu" "B.Cu")
		(net "PVCCIN_CPU1")
	)
	(via
		(at 114.099848 -287.28924)
		(size 0.4572)
		(drill 0.2032)
		(layers "F.Cu" "B.Cu")
		(net "PVCCIN_CPU1")
	)
	(via
		(at 103.98379 -242.98148)
		(size 0.4572)
		(drill 0.2032)
		(layers "F.Cu" "B.Cu")
		(net "PVCCIN_CPU1")
	)
	(via
		(at 112.11052 -249.620278)
		(size 0.4572)
		(drill 0.2032)
		(layers "F.Cu" "B.Cu")
		(net "PVCCIN_CPU1")
	)
	(via
		(at 111.280702 -254.733806)
		(size 0.4572)
		(drill 0.2032)
		(layers "F.Cu" "B.Cu")
		(net "PVCCIN_CPU1")
	)
	(via
		(at 128.32588 -325.133716)
		(size 0.508)
		(drill 0.254)
		(layers "F.Cu" "B.Cu")
		(net "PVCCIN_CPU1")
	)
	(via
		(at 102.534212 -317.905638)
		(size 0.508)
		(drill 0.254)
		(layers "F.Cu" "B.Cu")
		(net "PVCCIN_CPU1")
	)
	(via
		(at 94.350332 -318.550798)
		(size 0.508)
		(drill 0.254)
		(layers "F.Cu" "B.Cu")
		(net "PVCCIN_CPU1")
	)
	(via
		(at 107.991148 -281.59202)
		(size 0.4572)
		(drill 0.2032)
		(layers "F.Cu" "B.Cu")
		(net "PVCCIN_CPU1")
	)
	(via
		(at 111.280448 -282.405836)
		(size 0.4572)
		(drill 0.2032)
		(layers "F.Cu" "B.Cu")
		(net "PVCCIN_CPU1")
	)
	(via
		(at 134.728712 -326.630538)
		(size 0.508)
		(drill 0.254)
		(layers "F.Cu" "B.Cu")
		(net "PVCCIN_CPU1")
	)
	(via
		(at 109.760766 -243.923058)
		(size 0.4572)
		(drill 0.2032)
		(layers "F.Cu" "B.Cu")
		(net "PVCCIN_CPU1")
	)
	(via
		(at 115.414552 -318.535558)
		(size 0.508)
		(drill 0.254)
		(layers "F.Cu" "B.Cu")
		(net "PVCCIN_CPU1")
	)
	(via
		(at 112.689894 -278.336502)
		(size 0.4572)
		(drill 0.2032)
		(layers "F.Cu" "B.Cu")
		(net "PVCCIN_CPU1")
	)
	(via
		(at 86.11616 -324.508876)
		(size 0.508)
		(drill 0.254)
		(layers "F.Cu" "B.Cu")
		(net "PVCCIN_CPU1")
	)
	(via
		(at 135.927592 -326.998838)
		(size 0.508)
		(drill 0.254)
		(layers "F.Cu" "B.Cu")
		(net "PVCCIN_CPU1")
	)
	(via
		(at 111.280448 -274.266914)
		(size 0.4572)
		(drill 0.2032)
		(layers "F.Cu" "B.Cu")
		(net "PVCCIN_CPU1")
	)
	(via
		(at 82.686652 -329.675998)
		(size 0.508)
		(drill 0.254)
		(layers "F.Cu" "B.Cu")
		(net "PVCCIN_CPU1")
	)
	(via
		(at 101.618542 -337.223862)
		(size 0.508)
		(drill 0.254)
		(layers "F.Cu" "B.Cu")
		(net "PVCCIN_CPU1")
	)
	(via
		(at 113.629694 -265.314176)
		(size 0.4572)
		(drill 0.2032)
		(layers "F.Cu" "B.Cu")
		(net "PVCCIN_CPU1")
	)
	(via
		(at 111.640366 -242.295172)
		(size 0.4572)
		(drill 0.2032)
		(layers "F.Cu" "B.Cu")
		(net "PVCCIN_CPU1")
	)
	(via
		(at 111.750348 -258.803394)
		(size 0.4572)
		(drill 0.2032)
		(layers "F.Cu" "B.Cu")
		(net "PVCCIN_CPU1")
	)
	(via
		(at 106.50093 -319.875154)
		(size 0.508)
		(drill 0.254)
		(layers "F.Cu" "B.Cu")
		(net "PVCCIN_CPU1")
	)
	(via
		(at 112.220502 -257.989324)
		(size 0.4572)
		(drill 0.2032)
		(layers "F.Cu" "B.Cu")
		(net "PVCCIN_CPU1")
	)
	(via
		(at 118.84914 -321.234816)
		(size 0.508)
		(drill 0.254)
		(layers "F.Cu" "B.Cu")
		(net "PVCCIN_CPU1")
	)
	(via
		(at 107.13847 -320.502534)
		(size 0.508)
		(drill 0.254)
		(layers "F.Cu" "B.Cu")
		(net "PVCCIN_CPU1")
	)
	(via
		(at 137.21334 -328.346816)
		(size 0.508)
		(drill 0.254)
		(layers "F.Cu" "B.Cu")
		(net "PVCCIN_CPU1")
	)
	(via
		(at 112.220248 -279.150318)
		(size 0.4572)
		(drill 0.2032)
		(layers "F.Cu" "B.Cu")
		(net "PVCCIN_CPU1")
	)
	(via
		(at 113.159794 -272.639282)
		(size 0.4572)
		(drill 0.2032)
		(layers "F.Cu" "B.Cu")
		(net "PVCCIN_CPU1")
	)
	(via
		(at 99.056952 -317.229998)
		(size 0.508)
		(drill 0.254)
		(layers "F.Cu" "B.Cu")
		(net "PVCCIN_CPU1")
	)
	(via
		(at 107.051094 -289.807142)
		(size 0.4572)
		(drill 0.2032)
		(layers "F.Cu" "B.Cu")
		(net "PVCCIN_CPU1")
	)
	(via
		(at 101.294184 -297.19778)
		(size 0.508)
		(drill 0.254)
		(layers "F.Cu" "B.Cu")
		(net "PVCCIN_CPU1")
	)
	(via
		(at 90.816684 -323.825362)
		(size 0.508)
		(drill 0.254)
		(layers "F.Cu" "B.Cu")
		(net "PVCCIN_CPU1")
	)
	(via
		(at 127.050292 -321.174618)
		(size 0.508)
		(drill 0.254)
		(layers "F.Cu" "B.Cu")
		(net "PVCCIN_CPU1")
	)
	(via
		(at 108.930694 -289.807142)
		(size 0.4572)
		(drill 0.2032)
		(layers "F.Cu" "B.Cu")
		(net "PVCCIN_CPU1")
	)
	(via
		(at 108.68025 -246.117618)
		(size 0.4572)
		(drill 0.2032)
		(layers "F.Cu" "B.Cu")
		(net "PVCCIN_CPU1")
	)
	(via
		(at 109.760766 -242.295172)
		(size 0.4572)
		(drill 0.2032)
		(layers "F.Cu" "B.Cu")
		(net "PVCCIN_CPU1")
	)
	(via
		(at 91.490292 -322.523358)
		(size 0.508)
		(drill 0.254)
		(layers "F.Cu" "B.Cu")
		(net "PVCCIN_CPU1")
	)
	(via
		(at 115.354608 -319.232534)
		(size 0.508)
		(drill 0.254)
		(layers "F.Cu" "B.Cu")
		(net "PVCCIN_CPU1")
	)
	(via
		(at 107.210352 -317.882778)
		(size 0.508)
		(drill 0.254)
		(layers "F.Cu" "B.Cu")
		(net "PVCCIN_CPU1")
	)
	(via
		(at 109.400594 -282.405836)
		(size 0.4572)
		(drill 0.2032)
		(layers "F.Cu" "B.Cu")
		(net "PVCCIN_CPU1")
	)
	(via
		(at 117.859048 -287.28924)
		(size 0.4572)
		(drill 0.2032)
		(layers "F.Cu" "B.Cu")
		(net "PVCCIN_CPU1")
	)
	(via
		(at 112.690148 -255.547876)
		(size 0.4572)
		(drill 0.2032)
		(layers "F.Cu" "B.Cu")
		(net "PVCCIN_CPU1")
	)
	(via
		(at 94.987872 -318.543178)
		(size 0.508)
		(drill 0.254)
		(layers "F.Cu" "B.Cu")
		(net "PVCCIN_CPU1")
	)
	(via
		(at 116.077492 -317.890398)
		(size 0.508)
		(drill 0.254)
		(layers "F.Cu" "B.Cu")
		(net "PVCCIN_CPU1")
	)
	(via
		(at 116.434616 -257.69316)
		(size 0.4572)
		(drill 0.2032)
		(layers "F.Cu" "B.Cu")
		(net "PVCCIN_CPU1")
	)
	(via
		(at 106.581448 -284.033722)
		(size 0.4572)
		(drill 0.2032)
		(layers "F.Cu" "B.Cu")
		(net "PVCCIN_CPU1")
	)
	(via
		(at 99.643692 -319.206118)
		(size 0.508)
		(drill 0.254)
		(layers "F.Cu" "B.Cu")
		(net "PVCCIN_CPU1")
	)
	(via
		(at 115.509294 -288.103056)
		(size 0.4572)
		(drill 0.2032)
		(layers "F.Cu" "B.Cu")
		(net "PVCCIN_CPU1")
	)
	(via
		(at 109.887512 -337.27263)
		(size 0.508)
		(drill 0.254)
		(layers "F.Cu" "B.Cu")
		(net "PVCCIN_CPU1")
	)
	(via
		(at 108.68025 -242.918742)
		(size 0.4572)
		(drill 0.2032)
		(layers "F.Cu" "B.Cu")
		(net "PVCCIN_CPU1")
	)
	(via
		(at 111.750094 -275.08073)
		(size 0.4572)
		(drill 0.2032)
		(layers "F.Cu" "B.Cu")
		(net "PVCCIN_CPU1")
	)
	(via
		(at 131.05384 -325.133716)
		(size 0.508)
		(drill 0.254)
		(layers "F.Cu" "B.Cu")
		(net "PVCCIN_CPU1")
	)
	(via
		(at 108.68025 -257.086608)
		(size 0.4572)
		(drill 0.2032)
		(layers "F.Cu" "B.Cu")
		(net "PVCCIN_CPU1")
	)
	(via
		(at 111.750094 -270.19758)
		(size 0.4572)
		(drill 0.2032)
		(layers "F.Cu" "B.Cu")
		(net "PVCCIN_CPU1")
	)
	(via
		(at 107.51439 -262.200136)
		(size 0.4572)
		(drill 0.2032)
		(layers "F.Cu" "B.Cu")
		(net "PVCCIN_CPU1")
	)
	(via
		(at 81.388712 -329.683618)
		(size 0.508)
		(drill 0.254)
		(layers "F.Cu" "B.Cu")
		(net "PVCCIN_CPU1")
	)
	(via
		(at 115.979448 -288.917126)
		(size 0.4572)
		(drill 0.2032)
		(layers "F.Cu" "B.Cu")
		(net "PVCCIN_CPU1")
	)
	(via
		(at 112.592104 -295.03878)
		(size 0.508)
		(drill 0.254)
		(layers "F.Cu" "B.Cu")
		(net "PVCCIN_CPU1")
	)
	(via
		(at 108.68025 -246.701818)
		(size 0.4572)
		(drill 0.2032)
		(layers "F.Cu" "B.Cu")
		(net "PVCCIN_CPU1")
	)
	(via
		(at 99.674172 -318.558418)
		(size 0.508)
		(drill 0.254)
		(layers "F.Cu" "B.Cu")
		(net "PVCCIN_CPU1")
	)
	(via
		(at 112.690148 -257.175508)
		(size 0.4572)
		(drill 0.2032)
		(layers "F.Cu" "B.Cu")
		(net "PVCCIN_CPU1")
	)
	(via
		(at 107.812332 -319.206118)
		(size 0.508)
		(drill 0.254)
		(layers "F.Cu" "B.Cu")
		(net "PVCCIN_CPU1")
	)
	(via
		(at 127.710692 -320.504058)
		(size 0.508)
		(drill 0.254)
		(layers "F.Cu" "B.Cu")
		(net "PVCCIN_CPU1")
	)
	(via
		(at 98.968306 -321.139312)
		(size 0.508)
		(drill 0.254)
		(layers "F.Cu" "B.Cu")
		(net "PVCCIN_CPU1")
	)
	(via
		(at 114.099848 -288.993326)
		(size 0.4572)
		(drill 0.2032)
		(layers "F.Cu" "B.Cu")
		(net "PVCCIN_CPU1")
	)
	(via
		(at 112.689894 -279.964134)
		(size 0.4572)
		(drill 0.2032)
		(layers "F.Cu" "B.Cu")
		(net "PVCCIN_CPU1")
	)
	(via
		(at 108.930694 -284.847538)
		(size 0.4572)
		(drill 0.2032)
		(layers "F.Cu" "B.Cu")
		(net "PVCCIN_CPU1")
	)
	(via
		(at 114.71783 -321.858132)
		(size 0.508)
		(drill 0.254)
		(layers "F.Cu" "B.Cu")
		(net "PVCCIN_CPU1")
	)
	(via
		(at 99.61499 -321.873372)
		(size 0.508)
		(drill 0.254)
		(layers "F.Cu" "B.Cu")
		(net "PVCCIN_CPU1")
	)
	(via
		(at 103.834692 -317.260478)
		(size 0.508)
		(drill 0.254)
		(layers "F.Cu" "B.Cu")
		(net "PVCCIN_CPU1")
	)
	(via
		(at 127.690372 -323.624956)
		(size 0.508)
		(drill 0.254)
		(layers "F.Cu" "B.Cu")
		(net "PVCCIN_CPU1")
	)
	(via
		(at 111.750094 -284.847538)
		(size 0.4572)
		(drill 0.2032)
		(layers "F.Cu" "B.Cu")
		(net "PVCCIN_CPU1")
	)
	(via
		(at 107.794552 -320.521838)
		(size 0.508)
		(drill 0.254)
		(layers "F.Cu" "B.Cu")
		(net "PVCCIN_CPU1")
	)
	(via
		(at 111.640366 -248.806462)
		(size 0.4572)
		(drill 0.2032)
		(layers "F.Cu" "B.Cu")
		(net "PVCCIN_CPU1")
	)
	(via
		(at 124.246132 -317.252858)
		(size 0.508)
		(drill 0.254)
		(layers "F.Cu" "B.Cu")
		(net "PVCCIN_CPU1")
	)
	(via
		(at 111.750348 -255.547876)
		(size 0.4572)
		(drill 0.2032)
		(layers "F.Cu" "B.Cu")
		(net "PVCCIN_CPU1")
	)
	(via
		(at 111.368332 -318.543178)
		(size 0.508)
		(drill 0.254)
		(layers "F.Cu" "B.Cu")
		(net "PVCCIN_CPU1")
	)
	(via
		(at 111.398812 -317.229998)
		(size 0.508)
		(drill 0.254)
		(layers "F.Cu" "B.Cu")
		(net "PVCCIN_CPU1")
	)
	(via
		(at 114.569494 -284.847538)
		(size 0.4572)
		(drill 0.2032)
		(layers "F.Cu" "B.Cu")
		(net "PVCCIN_CPU1")
	)
	(via
		(at 110.70082 -243.923058)
		(size 0.4572)
		(drill 0.2032)
		(layers "F.Cu" "B.Cu")
		(net "PVCCIN_CPU1")
	)
	(via
		(at 112.220248 -284.033722)
		(size 0.4572)
		(drill 0.2032)
		(layers "F.Cu" "B.Cu")
		(net "PVCCIN_CPU1")
	)
	(via
		(at 91.551252 -320.562478)
		(size 0.508)
		(drill 0.254)
		(layers "F.Cu" "B.Cu")
		(net "PVCCIN_CPU1")
	)
	(via
		(at 90.250772 -321.207638)
		(size 0.508)
		(drill 0.254)
		(layers "F.Cu" "B.Cu")
		(net "PVCCIN_CPU1")
	)
	(via
		(at 110.685072 -319.851278)
		(size 0.508)
		(drill 0.254)
		(layers "F.Cu" "B.Cu")
		(net "PVCCIN_CPU1")
	)
	(via
		(at 90.873072 -321.860418)
		(size 0.508)
		(drill 0.254)
		(layers "F.Cu" "B.Cu")
		(net "PVCCIN_CPU1")
	)
	(via
		(at 107.13847 -319.867534)
		(size 0.508)
		(drill 0.254)
		(layers "F.Cu" "B.Cu")
		(net "PVCCIN_CPU1")
	)
	(via
		(at 109.29112 -243.109242)
		(size 0.4572)
		(drill 0.2032)
		(layers "F.Cu" "B.Cu")
		(net "PVCCIN_CPU1")
	)
	(via
		(at 91.472512 -323.839078)
		(size 0.508)
		(drill 0.254)
		(layers "F.Cu" "B.Cu")
		(net "PVCCIN_CPU1")
	)
	(via
		(at 111.280448 -285.661354)
		(size 0.4572)
		(drill 0.2032)
		(layers "F.Cu" "B.Cu")
		(net "PVCCIN_CPU1")
	)
	(via
		(at 113.862104 -295.03878)
		(size 0.508)
		(drill 0.254)
		(layers "F.Cu" "B.Cu")
		(net "PVCCIN_CPU1")
	)
	(via
		(at 126.065026 -340.681056)
		(size 0.508)
		(drill 0.254)
		(layers "F.Cu" "B.Cu")
		(net "PVCCIN_CPU1")
	)
	(via
		(at 109.870494 -283.219906)
		(size 0.4572)
		(drill 0.2032)
		(layers "F.Cu" "B.Cu")
		(net "PVCCIN_CPU1")
	)
	(via
		(at 113.99012 -239.85347)
		(size 0.4572)
		(drill 0.2032)
		(layers "F.Cu" "B.Cu")
		(net "PVCCIN_CPU1")
	)
	(via
		(at 109.870494 -279.964134)
		(size 0.4572)
		(drill 0.2032)
		(layers "F.Cu" "B.Cu")
		(net "PVCCIN_CPU1")
	)
	(via
		(at 127.695452 -321.164458)
		(size 0.508)
		(drill 0.254)
		(layers "F.Cu" "B.Cu")
		(net "PVCCIN_CPU1")
	)
	(via
		(at 120.319292 -297.19778)
		(size 0.508)
		(drill 0.254)
		(layers "F.Cu" "B.Cu")
		(net "PVCCIN_CPU1")
	)
	(via
		(at 117.388894 -284.847538)
		(size 0.4572)
		(drill 0.2032)
		(layers "F.Cu" "B.Cu")
		(net "PVCCIN_CPU1")
	)
	(via
		(at 120.207532 -317.933578)
		(size 0.508)
		(drill 0.254)
		(layers "F.Cu" "B.Cu")
		(net "PVCCIN_CPU1")
	)
	(via
		(at 124.185172 -319.213738)
		(size 0.508)
		(drill 0.254)
		(layers "F.Cu" "B.Cu")
		(net "PVCCIN_CPU1")
	)
	(via
		(at 122.930412 -318.558418)
		(size 0.508)
		(drill 0.254)
		(layers "F.Cu" "B.Cu")
		(net "PVCCIN_CPU1")
	)
	(via
		(at 98.327718 -319.240154)
		(size 0.508)
		(drill 0.254)
		(layers "F.Cu" "B.Cu")
		(net "PVCCIN_CPU1")
	)
	(via
		(at 94.29242 -321.199256)
		(size 0.508)
		(drill 0.254)
		(layers "F.Cu" "B.Cu")
		(net "PVCCIN_CPU1")
	)
	(via
		(at 135.91794 -329.809856)
		(size 0.508)
		(drill 0.254)
		(layers "F.Cu" "B.Cu")
		(net "PVCCIN_CPU1")
	)
	(via
		(at 113.050066 -243.109242)
		(size 0.4572)
		(drill 0.2032)
		(layers "F.Cu" "B.Cu")
		(net "PVCCIN_CPU1")
	)
	(via
		(at 106.503978 -321.146932)
		(size 0.508)
		(drill 0.254)
		(layers "F.Cu" "B.Cu")
		(net "PVCCIN_CPU1")
	)
	(via
		(at 122.890026 -320.510154)
		(size 0.508)
		(drill 0.254)
		(layers "F.Cu" "B.Cu")
		(net "PVCCIN_CPU1")
	)
	(via
		(at 98.419412 -317.237618)
		(size 0.508)
		(drill 0.254)
		(layers "F.Cu" "B.Cu")
		(net "PVCCIN_CPU1")
	)
	(via
		(at 108.461048 -285.661354)
		(size 0.4572)
		(drill 0.2032)
		(layers "F.Cu" "B.Cu")
		(net "PVCCIN_CPU1")
	)
	(via
		(at 107.36199 -246.6594)
		(size 0.4572)
		(drill 0.2032)
		(layers "F.Cu" "B.Cu")
		(net "PVCCIN_CPU1")
	)
	(via
		(at 99.62388 -321.206876)
		(size 0.508)
		(drill 0.254)
		(layers "F.Cu" "B.Cu")
		(net "PVCCIN_CPU1")
	)
	(via
		(at 131.695952 -322.955158)
		(size 0.508)
		(drill 0.254)
		(layers "F.Cu" "B.Cu")
		(net "PVCCIN_CPU1")
	)
	(via
		(at 111.34344 -320.523362)
		(size 0.508)
		(drill 0.254)
		(layers "F.Cu" "B.Cu")
		(net "PVCCIN_CPU1")
	)
	(via
		(at 124.15647 -321.880992)
		(size 0.508)
		(drill 0.254)
		(layers "F.Cu" "B.Cu")
		(net "PVCCIN_CPU1")
	)
	(via
		(at 108.930694 -283.219906)
		(size 0.4572)
		(drill 0.2032)
		(layers "F.Cu" "B.Cu")
		(net "PVCCIN_CPU1")
	)
	(via
		(at 114.46002 -240.66754)
		(size 0.4572)
		(drill 0.2032)
		(layers "F.Cu" "B.Cu")
		(net "PVCCIN_CPU1")
	)
	(via
		(at 112.689894 -270.19758)
		(size 0.4572)
		(drill 0.2032)
		(layers "F.Cu" "B.Cu")
		(net "PVCCIN_CPU1")
	)
	(via
		(at 112.689894 -281.59202)
		(size 0.4572)
		(drill 0.2032)
		(layers "F.Cu" "B.Cu")
		(net "PVCCIN_CPU1")
	)
	(via
		(at 119.684292 -292.95598)
		(size 0.508)
		(drill 0.254)
		(layers "F.Cu" "B.Cu")
		(net "PVCCIN_CPU1")
	)
	(via
		(at 115.039648 -284.033722)
		(size 0.4572)
		(drill 0.2032)
		(layers "F.Cu" "B.Cu")
		(net "PVCCIN_CPU1")
	)
	(via
		(at 83.32978 -329.342496)
		(size 0.508)
		(drill 0.254)
		(layers "F.Cu" "B.Cu")
		(net "PVCCIN_CPU1")
	)
	(via
		(at 103.124254 -319.251584)
		(size 0.508)
		(drill 0.254)
		(layers "F.Cu" "B.Cu")
		(net "PVCCIN_CPU1")
	)
	(via
		(at 117.388894 -288.103056)
		(size 0.4572)
		(drill 0.2032)
		(layers "F.Cu" "B.Cu")
		(net "PVCCIN_CPU1")
	)
	(via
		(at 110.810294 -288.103056)
		(size 0.4572)
		(drill 0.2032)
		(layers "F.Cu" "B.Cu")
		(net "PVCCIN_CPU1")
	)
	(via
		(at 114.720116 -321.146932)
		(size 0.508)
		(drill 0.254)
		(layers "F.Cu" "B.Cu")
		(net "PVCCIN_CPU1")
	)
	(via
		(at 128.34366 -321.882516)
		(size 0.508)
		(drill 0.254)
		(layers "F.Cu" "B.Cu")
		(net "PVCCIN_CPU1")
	)
	(via
		(at 109.400848 -256.361692)
		(size 0.4572)
		(drill 0.2032)
		(layers "F.Cu" "B.Cu")
		(net "PVCCIN_CPU1")
	)
	(via
		(at 135.91794 -328.346816)
		(size 0.508)
		(drill 0.254)
		(layers "F.Cu" "B.Cu")
		(net "PVCCIN_CPU1")
	)
	(via
		(at 119.516398 -320.523362)
		(size 0.508)
		(drill 0.254)
		(layers "F.Cu" "B.Cu")
		(net "PVCCIN_CPU1")
	)
	(via
		(at 111.280448 -280.778204)
		(size 0.4572)
		(drill 0.2032)
		(layers "F.Cu" "B.Cu")
		(net "PVCCIN_CPU1")
	)
	(via
		(at 109.76102 -239.039654)
		(size 0.4572)
		(drill 0.2032)
		(layers "F.Cu" "B.Cu")
		(net "PVCCIN_CPU1")
	)
	(via
		(at 94.29115 -321.865752)
		(size 0.508)
		(drill 0.254)
		(layers "F.Cu" "B.Cu")
		(net "PVCCIN_CPU1")
	)
	(via
		(at 106.73461 -254.01016)
		(size 0.4572)
		(drill 0.2032)
		(layers "F.Cu" "B.Cu")
		(net "PVCCIN_CPU1")
	)
	(via
		(at 132.33908 -325.367396)
		(size 0.508)
		(drill 0.254)
		(layers "F.Cu" "B.Cu")
		(net "PVCCIN_CPU1")
	)
	(via
		(at 98.32975 -321.865752)
		(size 0.508)
		(drill 0.254)
		(layers "F.Cu" "B.Cu")
		(net "PVCCIN_CPU1")
	)
	(via
		(at 86.802468 -322.574412)
		(size 0.508)
		(drill 0.254)
		(layers "F.Cu" "B.Cu")
		(net "PVCCIN_CPU1")
	)
	(via
		(at 118.907052 -318.586358)
		(size 0.508)
		(drill 0.254)
		(layers "F.Cu" "B.Cu")
		(net "PVCCIN_CPU1")
	)
	(via
		(at 113.050066 -241.481356)
		(size 0.4572)
		(drill 0.2032)
		(layers "F.Cu" "B.Cu")
		(net "PVCCIN_CPU1")
	)
	(via
		(at 123.567952 -318.550798)
		(size 0.508)
		(drill 0.254)
		(layers "F.Cu" "B.Cu")
		(net "PVCCIN_CPU1")
	)
	(via
		(at 107.051094 -284.847538)
		(size 0.4572)
		(drill 0.2032)
		(layers "F.Cu" "B.Cu")
		(net "PVCCIN_CPU1")
	)
	(via
		(at 98.404172 -317.890398)
		(size 0.508)
		(drill 0.254)
		(layers "F.Cu" "B.Cu")
		(net "PVCCIN_CPU1")
	)
	(via
		(at 112.689894 -283.219906)
		(size 0.4572)
		(drill 0.2032)
		(layers "F.Cu" "B.Cu")
		(net "PVCCIN_CPU1")
	)
	(via
		(at 109.870748 -253.91999)
		(size 0.4572)
		(drill 0.2032)
		(layers "F.Cu" "B.Cu")
		(net "PVCCIN_CPU1")
	)
	(via
		(at 114.777012 -318.543178)
		(size 0.508)
		(drill 0.254)
		(layers "F.Cu" "B.Cu")
		(net "PVCCIN_CPU1")
	)
	(via
		(at 109.760766 -247.178576)
		(size 0.4572)
		(drill 0.2032)
		(layers "F.Cu" "B.Cu")
		(net "PVCCIN_CPU1")
	)
	(via
		(at 113.159794 -275.8948)
		(size 0.4572)
		(drill 0.2032)
		(layers "F.Cu" "B.Cu")
		(net "PVCCIN_CPU1")
	)
	(via
		(at 111.640366 -247.178576)
		(size 0.4572)
		(drill 0.2032)
		(layers "F.Cu" "B.Cu")
		(net "PVCCIN_CPU1")
	)
	(via
		(at 117.388894 -289.807142)
		(size 0.4572)
		(drill 0.2032)
		(layers "F.Cu" "B.Cu")
		(net "PVCCIN_CPU1")
	)
	(via
		(at 111.280448 -266.128246)
		(size 0.4572)
		(drill 0.2032)
		(layers "F.Cu" "B.Cu")
		(net "PVCCIN_CPU1")
	)
	(via
		(at 108.68025 -262.535416)
		(size 0.4572)
		(drill 0.2032)
		(layers "F.Cu" "B.Cu")
		(net "PVCCIN_CPU1")
	)
	(via
		(at 123.527566 -319.232534)
		(size 0.508)
		(drill 0.254)
		(layers "F.Cu" "B.Cu")
		(net "PVCCIN_CPU1")
	)
	(via
		(at 112.689894 -288.103056)
		(size 0.4572)
		(drill 0.2032)
		(layers "F.Cu" "B.Cu")
		(net "PVCCIN_CPU1")
	)
	(via
		(at 132.363972 -323.366638)
		(size 0.508)
		(drill 0.254)
		(layers "F.Cu" "B.Cu")
		(net "PVCCIN_CPU1")
	)
	(via
		(at 111.750348 -253.91999)
		(size 0.4572)
		(drill 0.2032)
		(layers "F.Cu" "B.Cu")
		(net "PVCCIN_CPU1")
	)
	(via
		(at 115.164362 -253.593346)
		(size 0.4572)
		(drill 0.2032)
		(layers "F.Cu" "B.Cu")
		(net "PVCCIN_CPU1")
	)
	(via
		(at 112.220248 -277.522432)
		(size 0.4572)
		(drill 0.2032)
		(layers "F.Cu" "B.Cu")
		(net "PVCCIN_CPU1")
	)
	(via
		(at 134.7343 -328.710036)
		(size 0.508)
		(drill 0.254)
		(layers "F.Cu" "B.Cu")
		(net "PVCCIN_CPU1")
	)
	(via
		(at 98.330766 -321.146932)
		(size 0.508)
		(drill 0.254)
		(layers "F.Cu" "B.Cu")
		(net "PVCCIN_CPU1")
	)
	(via
		(at 111.280448 -271.011396)
		(size 0.4572)
		(drill 0.2032)
		(layers "F.Cu" "B.Cu")
		(net "PVCCIN_CPU1")
	)
	(via
		(at 119.684292 -297.19778)
		(size 0.508)
		(drill 0.254)
		(layers "F.Cu" "B.Cu")
		(net "PVCCIN_CPU1")
	)
	(via
		(at 99.625912 -320.521838)
		(size 0.508)
		(drill 0.254)
		(layers "F.Cu" "B.Cu")
		(net "PVCCIN_CPU1")
	)
	(via
		(at 109.29112 -249.620278)
		(size 0.4572)
		(drill 0.2032)
		(layers "F.Cu" "B.Cu")
		(net "PVCCIN_CPU1")
	)
	(via
		(at 103.819452 -317.913258)
		(size 0.508)
		(drill 0.254)
		(layers "F.Cu" "B.Cu")
		(net "PVCCIN_CPU1")
	)
	(via
		(at 115.164362 -246.582946)
		(size 0.4572)
		(drill 0.2032)
		(layers "F.Cu" "B.Cu")
		(net "PVCCIN_CPU1")
	)
	(via
		(at 113.99012 -246.36476)
		(size 0.4572)
		(drill 0.2032)
		(layers "F.Cu" "B.Cu")
		(net "PVCCIN_CPU1")
	)
	(via
		(at 87.441532 -321.847718)
		(size 0.508)
		(drill 0.254)
		(layers "F.Cu" "B.Cu")
		(net "PVCCIN_CPU1")
	)
	(via
		(at 112.220502 -256.361692)
		(size 0.4572)
		(drill 0.2032)
		(layers "F.Cu" "B.Cu")
		(net "PVCCIN_CPU1")
	)
	(via
		(at 112.11052 -241.481356)
		(size 0.4572)
		(drill 0.2032)
		(layers "F.Cu" "B.Cu")
		(net "PVCCIN_CPU1")
	)
	(via
		(at 112.690148 -260.431026)
		(size 0.4572)
		(drill 0.2032)
		(layers "F.Cu" "B.Cu")
		(net "PVCCIN_CPU1")
	)
	(via
		(at 82.049112 -328.413618)
		(size 0.508)
		(drill 0.254)
		(layers "F.Cu" "B.Cu")
		(net "PVCCIN_CPU1")
	)
	(via
		(at 128.325372 -322.947538)
		(size 0.508)
		(drill 0.254)
		(layers "F.Cu" "B.Cu")
		(net "PVCCIN_CPU1")
	)
	(via
		(at 109.870748 -260.431026)
		(size 0.4572)
		(drill 0.2032)
		(layers "F.Cu" "B.Cu")
		(net "PVCCIN_CPU1")
	)
	(via
		(at 131.038092 -322.947538)
		(size 0.508)
		(drill 0.254)
		(layers "F.Cu" "B.Cu")
		(net "PVCCIN_CPU1")
	)
	(via
		(at 86.803992 -321.855338)
		(size 0.508)
		(drill 0.254)
		(layers "F.Cu" "B.Cu")
		(net "PVCCIN_CPU1")
	)
	(via
		(at 109.29112 -239.85347)
		(size 0.4572)
		(drill 0.2032)
		(layers "F.Cu" "B.Cu")
		(net "PVCCIN_CPU1")
	)
	(via
		(at 136.5631 -329.078336)
		(size 0.508)
		(drill 0.254)
		(layers "F.Cu" "B.Cu")
		(net "PVCCIN_CPU1")
	)
	(via
		(at 112.220502 -259.61721)
		(size 0.4572)
		(drill 0.2032)
		(layers "F.Cu" "B.Cu")
		(net "PVCCIN_CPU1")
	)
	(via
		(at 118.84787 -321.901312)
		(size 0.508)
		(drill 0.254)
		(layers "F.Cu" "B.Cu")
		(net "PVCCIN_CPU1")
	)
	(via
		(at 106.572812 -317.890398)
		(size 0.508)
		(drill 0.254)
		(layers "F.Cu" "B.Cu")
		(net "PVCCIN_CPU1")
	)
	(via
		(at 113.160048 -262.872728)
		(size 0.4572)
		(drill 0.2032)
		(layers "F.Cu" "B.Cu")
		(net "PVCCIN_CPU1")
	)
	(via
		(at 127.690372 -322.939918)
		(size 0.508)
		(drill 0.254)
		(layers "F.Cu" "B.Cu")
		(net "PVCCIN_CPU1")
	)
	(via
		(at 94.92869 -321.858132)
		(size 0.508)
		(drill 0.254)
		(layers "F.Cu" "B.Cu")
		(net "PVCCIN_CPU1")
	)
	(via
		(at 114.569494 -283.219906)
		(size 0.4572)
		(drill 0.2032)
		(layers "F.Cu" "B.Cu")
		(net "PVCCIN_CPU1")
	)
	(via
		(at 103.09733 -321.873372)
		(size 0.508)
		(drill 0.254)
		(layers "F.Cu" "B.Cu")
		(net "PVCCIN_CPU1")
	)
	(via
		(at 94.380812 -317.237618)
		(size 0.508)
		(drill 0.254)
		(layers "F.Cu" "B.Cu")
		(net "PVCCIN_CPU1")
	)
	(via
		(at 112.690148 -262.058912)
		(size 0.4572)
		(drill 0.2032)
		(layers "F.Cu" "B.Cu")
		(net "PVCCIN_CPU1")
	)
	(via
		(at 95.635572 -318.558418)
		(size 0.508)
		(drill 0.254)
		(layers "F.Cu" "B.Cu")
		(net "PVCCIN_CPU1")
	)
	(via
		(at 113.159794 -282.405836)
		(size 0.4572)
		(drill 0.2032)
		(layers "F.Cu" "B.Cu")
		(net "PVCCIN_CPU1")
	)
	(via
		(at 112.690148 -263.686798)
		(size 0.4572)
		(drill 0.2032)
		(layers "F.Cu" "B.Cu")
		(net "PVCCIN_CPU1")
	)
	(via
		(at 110.669832 -320.511678)
		(size 0.508)
		(drill 0.254)
		(layers "F.Cu" "B.Cu")
		(net "PVCCIN_CPU1")
	)
	(via
		(at 113.159794 -267.755878)
		(size 0.4572)
		(drill 0.2032)
		(layers "F.Cu" "B.Cu")
		(net "PVCCIN_CPU1")
	)
	(via
		(at 119.736616 -242.98148)
		(size 0.4572)
		(drill 0.2032)
		(layers "F.Cu" "B.Cu")
		(net "PVCCIN_CPU1")
	)
	(via
		(at 109.400848 -259.61721)
		(size 0.4572)
		(drill 0.2032)
		(layers "F.Cu" "B.Cu")
		(net "PVCCIN_CPU1")
	)
	(via
		(at 116.434616 -242.98148)
		(size 0.4572)
		(drill 0.2032)
		(layers "F.Cu" "B.Cu")
		(net "PVCCIN_CPU1")
	)
	(via
		(at 114.099594 -277.522432)
		(size 0.4572)
		(drill 0.2032)
		(layers "F.Cu" "B.Cu")
		(net "PVCCIN_CPU1")
	)
	(via
		(at 107.873292 -317.245238)
		(size 0.508)
		(drill 0.254)
		(layers "F.Cu" "B.Cu")
		(net "PVCCIN_CPU1")
	)
	(via
		(at 93.571314 -337.352894)
		(size 0.508)
		(drill 0.254)
		(layers "F.Cu" "B.Cu")
		(net "PVCCIN_CPU1")
	)
	(via
		(at 111.98098 -321.150742)
		(size 0.508)
		(drill 0.254)
		(layers "F.Cu" "B.Cu")
		(net "PVCCIN_CPU1")
	)
	(via
		(at 110.810802 -255.547876)
		(size 0.4572)
		(drill 0.2032)
		(layers "F.Cu" "B.Cu")
		(net "PVCCIN_CPU1")
	)
	(via
		(at 90.816684 -323.190362)
		(size 0.508)
		(drill 0.254)
		(layers "F.Cu" "B.Cu")
		(net "PVCCIN_CPU1")
	)
	(via
		(at 109.400848 -257.989324)
		(size 0.4572)
		(drill 0.2032)
		(layers "F.Cu" "B.Cu")
		(net "PVCCIN_CPU1")
	)
	(via
		(at 112.690148 -258.803394)
		(size 0.4572)
		(drill 0.2032)
		(layers "F.Cu" "B.Cu")
		(net "PVCCIN_CPU1")
	)
	(via
		(at 90.816684 -322.555362)
		(size 0.508)
		(drill 0.254)
		(layers "F.Cu" "B.Cu")
		(net "PVCCIN_CPU1")
	)
	(via
		(at 114.569748 -257.175508)
		(size 0.4572)
		(drill 0.2032)
		(layers "F.Cu" "B.Cu")
		(net "PVCCIN_CPU1")
	)
	(via
		(at 109.760766 -245.550944)
		(size 0.4572)
		(drill 0.2032)
		(layers "F.Cu" "B.Cu")
		(net "PVCCIN_CPU1")
	)
	(via
		(at 109.870748 -257.175508)
		(size 0.4572)
		(drill 0.2032)
		(layers "F.Cu" "B.Cu")
		(net "PVCCIN_CPU1")
	)
	(via
		(at 107.141518 -321.139312)
		(size 0.508)
		(drill 0.254)
		(layers "F.Cu" "B.Cu")
		(net "PVCCIN_CPU1")
	)
	(via
		(at 104.74071 -250.34494)
		(size 0.4572)
		(drill 0.2032)
		(layers "F.Cu" "B.Cu")
		(net "PVCCIN_CPU1")
	)
	(via
		(at 118.328694 -289.807142)
		(size 0.4572)
		(drill 0.2032)
		(layers "F.Cu" "B.Cu")
		(net "PVCCIN_CPU1")
	)
	(via
		(at 111.98098 -319.880742)
		(size 0.508)
		(drill 0.254)
		(layers "F.Cu" "B.Cu")
		(net "PVCCIN_CPU1")
	)
	(via
		(at 107.13847 -319.232534)
		(size 0.508)
		(drill 0.254)
		(layers "F.Cu" "B.Cu")
		(net "PVCCIN_CPU1")
	)
	(via
		(at 111.34344 -319.888362)
		(size 0.508)
		(drill 0.254)
		(layers "F.Cu" "B.Cu")
		(net "PVCCIN_CPU1")
	)
	(via
		(at 115.21059 -238.744252)
		(size 0.4572)
		(drill 0.2032)
		(layers "F.Cu" "B.Cu")
		(net "PVCCIN_CPU1")
	)
	(via
		(at 106.50093 -320.510154)
		(size 0.508)
		(drill 0.254)
		(layers "F.Cu" "B.Cu")
		(net "PVCCIN_CPU1")
	)
	(via
		(at 90.235532 -321.868038)
		(size 0.508)
		(drill 0.254)
		(layers "F.Cu" "B.Cu")
		(net "PVCCIN_CPU1")
	)
	(via
		(at 98.327718 -320.510154)
		(size 0.508)
		(drill 0.254)
		(layers "F.Cu" "B.Cu")
		(net "PVCCIN_CPU1")
	)
	(via
		(at 115.509294 -283.219906)
		(size 0.4572)
		(drill 0.2032)
		(layers "F.Cu" "B.Cu")
		(net "PVCCIN_CPU1")
	)
	(via
		(at 113.629694 -278.336502)
		(size 0.4572)
		(drill 0.2032)
		(layers "F.Cu" "B.Cu")
		(net "PVCCIN_CPU1")
	)
	(via
		(at 116.919248 -282.405836)
		(size 0.4572)
		(drill 0.2032)
		(layers "F.Cu" "B.Cu")
		(net "PVCCIN_CPU1")
	)
	(via
		(at 112.220502 -262.872728)
		(size 0.4572)
		(drill 0.2032)
		(layers "F.Cu" "B.Cu")
		(net "PVCCIN_CPU1")
	)
	(via
		(at 102.458012 -320.526918)
		(size 0.508)
		(drill 0.254)
		(layers "F.Cu" "B.Cu")
		(net "PVCCIN_CPU1")
	)
	(via
		(at 109.870494 -284.847538)
		(size 0.4572)
		(drill 0.2032)
		(layers "F.Cu" "B.Cu")
		(net "PVCCIN_CPU1")
	)
	(via
		(at 114.099848 -284.033722)
		(size 0.4572)
		(drill 0.2032)
		(layers "F.Cu" "B.Cu")
		(net "PVCCIN_CPU1")
	)
	(via
		(at 114.100102 -261.245096)
		(size 0.4572)
		(drill 0.2032)
		(layers "F.Cu" "B.Cu")
		(net "PVCCIN_CPU1")
	)
	(via
		(at 77.126338 -332.227174)
		(size 0.508)
		(drill 0.254)
		(layers "F.Cu" "B.Cu")
		(net "PVCCIN_CPU1")
	)
	(via
		(at 106.111294 -284.847538)
		(size 0.4572)
		(drill 0.2032)
		(layers "F.Cu" "B.Cu")
		(net "PVCCIN_CPU1")
	)
	(via
		(at 113.159794 -284.033722)
		(size 0.4572)
		(drill 0.2032)
		(layers "F.Cu" "B.Cu")
		(net "PVCCIN_CPU1")
	)
	(via
		(at 98.388932 -318.550798)
		(size 0.508)
		(drill 0.254)
		(layers "F.Cu" "B.Cu")
		(net "PVCCIN_CPU1")
	)
	(via
		(at 113.629694 -276.708616)
		(size 0.4572)
		(drill 0.2032)
		(layers "F.Cu" "B.Cu")
		(net "PVCCIN_CPU1")
	)
	(via
		(at 110.810802 -253.91999)
		(size 0.4572)
		(drill 0.2032)
		(layers "F.Cu" "B.Cu")
		(net "PVCCIN_CPU1")
	)
	(via
		(at 113.99012 -244.736874)
		(size 0.4572)
		(drill 0.2032)
		(layers "F.Cu" "B.Cu")
		(net "PVCCIN_CPU1")
	)
	(via
		(at 113.050066 -239.85347)
		(size 0.4572)
		(drill 0.2032)
		(layers "F.Cu" "B.Cu")
		(net "PVCCIN_CPU1")
	)
	(via
		(at 119.101616 -242.98148)
		(size 0.4572)
		(drill 0.2032)
		(layers "F.Cu" "B.Cu")
		(net "PVCCIN_CPU1")
	)
	(via
		(at 111.383572 -317.882778)
		(size 0.508)
		(drill 0.254)
		(layers "F.Cu" "B.Cu")
		(net "PVCCIN_CPU1")
	)
	(via
		(at 115.354608 -320.502534)
		(size 0.508)
		(drill 0.254)
		(layers "F.Cu" "B.Cu")
		(net "PVCCIN_CPU1")
	)
	(via
		(at 114.569494 -286.475424)
		(size 0.4572)
		(drill 0.2032)
		(layers "F.Cu" "B.Cu")
		(net "PVCCIN_CPU1")
	)
	(via
		(at 82.087212 -327.710038)
		(size 0.508)
		(drill 0.254)
		(layers "F.Cu" "B.Cu")
		(net "PVCCIN_CPU1")
	)
	(via
		(at 83.339432 -326.681338)
		(size 0.508)
		(drill 0.254)
		(layers "F.Cu" "B.Cu")
		(net "PVCCIN_CPU1")
	)
	(via
		(at 113.159794 -269.38351)
		(size 0.4572)
		(drill 0.2032)
		(layers "F.Cu" "B.Cu")
		(net "PVCCIN_CPU1")
	)
	(via
		(at 112.11052 -246.36476)
		(size 0.4572)
		(drill 0.2032)
		(layers "F.Cu" "B.Cu")
		(net "PVCCIN_CPU1")
	)
	(via
		(at 123.583192 -317.890398)
		(size 0.508)
		(drill 0.254)
		(layers "F.Cu" "B.Cu")
		(net "PVCCIN_CPU1")
	)
	(via
		(at 102.45979 -321.880992)
		(size 0.508)
		(drill 0.254)
		(layers "F.Cu" "B.Cu")
		(net "PVCCIN_CPU1")
	)
	(via
		(at 136.79424 -330.945236)
		(size 0.508)
		(drill 0.254)
		(layers "F.Cu" "B.Cu")
		(net "PVCCIN_CPU1")
	)
	(via
		(at 83.347052 -326.026018)
		(size 0.508)
		(drill 0.254)
		(layers "F.Cu" "B.Cu")
		(net "PVCCIN_CPU1")
	)
	(via
		(at 113.159794 -264.50036)
		(size 0.4572)
		(drill 0.2032)
		(layers "F.Cu" "B.Cu")
		(net "PVCCIN_CPU1")
	)
	(via
		(at 109.400848 -261.245096)
		(size 0.4572)
		(drill 0.2032)
		(layers "F.Cu" "B.Cu")
		(net "PVCCIN_CPU1")
	)
	(via
		(at 111.750094 -286.475424)
		(size 0.4572)
		(drill 0.2032)
		(layers "F.Cu" "B.Cu")
		(net "PVCCIN_CPU1")
	)
	(via
		(at 99.628452 -319.858898)
		(size 0.508)
		(drill 0.254)
		(layers "F.Cu" "B.Cu")
		(net "PVCCIN_CPU1")
	)
	(via
		(at 106.54284 -295.03878)
		(size 0.508)
		(drill 0.254)
		(layers "F.Cu" "B.Cu")
		(net "PVCCIN_CPU1")
	)
	(via
		(at 110.810548 -266.941808)
		(size 0.4572)
		(drill 0.2032)
		(layers "F.Cu" "B.Cu")
		(net "PVCCIN_CPU1")
	)
	(via
		(at 105.641648 -287.28924)
		(size 0.4572)
		(drill 0.2032)
		(layers "F.Cu" "B.Cu")
		(net "PVCCIN_CPU1")
	)
	(via
		(at 110.810802 -258.803394)
		(size 0.4572)
		(drill 0.2032)
		(layers "F.Cu" "B.Cu")
		(net "PVCCIN_CPU1")
	)
	(via
		(at 127.057912 -319.846198)
		(size 0.508)
		(drill 0.254)
		(layers "F.Cu" "B.Cu")
		(net "PVCCIN_CPU1")
	)
	(via
		(at 115.35537 -321.850512)
		(size 0.508)
		(drill 0.254)
		(layers "F.Cu" "B.Cu")
		(net "PVCCIN_CPU1")
	)
	(via
		(at 113.15954 -266.128246)
		(size 0.4572)
		(drill 0.2032)
		(layers "F.Cu" "B.Cu")
		(net "PVCCIN_CPU1")
	)
	(via
		(at 118.861332 -319.886838)
		(size 0.508)
		(drill 0.254)
		(layers "F.Cu" "B.Cu")
		(net "PVCCIN_CPU1")
	)
	(via
		(at 106.54284 -292.95598)
		(size 0.508)
		(drill 0.254)
		(layers "F.Cu" "B.Cu")
		(net "PVCCIN_CPU1")
	)
	(via
		(at 110.340648 -279.150318)
		(size 0.4572)
		(drill 0.2032)
		(layers "F.Cu" "B.Cu")
		(net "PVCCIN_CPU1")
	)
	(via
		(at 111.30915 -321.858132)
		(size 0.508)
		(drill 0.254)
		(layers "F.Cu" "B.Cu")
		(net "PVCCIN_CPU1")
	)
	(via
		(at 103.156512 -318.558418)
		(size 0.508)
		(drill 0.254)
		(layers "F.Cu" "B.Cu")
		(net "PVCCIN_CPU1")
	)
	(via
		(at 114.100102 -256.361692)
		(size 0.4572)
		(drill 0.2032)
		(layers "F.Cu" "B.Cu")
		(net "PVCCIN_CPU1")
	)
	(via
		(at 113.159794 -288.993326)
		(size 0.4572)
		(drill 0.2032)
		(layers "F.Cu" "B.Cu")
		(net "PVCCIN_CPU1")
	)
	(via
		(at 119.575072 -317.265558)
		(size 0.508)
		(drill 0.254)
		(layers "F.Cu" "B.Cu")
		(net "PVCCIN_CPU1")
	)
	(via
		(at 111.640366 -245.550944)
		(size 0.4572)
		(drill 0.2032)
		(layers "F.Cu" "B.Cu")
		(net "PVCCIN_CPU1")
	)
	(via
		(at 114.46002 -245.550944)
		(size 0.4572)
		(drill 0.2032)
		(layers "F.Cu" "B.Cu")
		(net "PVCCIN_CPU1")
	)
	(via
		(at 110.810548 -279.964134)
		(size 0.4572)
		(drill 0.2032)
		(layers "F.Cu" "B.Cu")
		(net "PVCCIN_CPU1")
	)
	(via
		(at 110.810548 -268.569694)
		(size 0.4572)
		(drill 0.2032)
		(layers "F.Cu" "B.Cu")
		(net "PVCCIN_CPU1")
	)
	(via
		(at 103.804212 -318.573658)
		(size 0.508)
		(drill 0.254)
		(layers "F.Cu" "B.Cu")
		(net "PVCCIN_CPU1")
	)
	(via
		(at 111.750094 -271.825212)
		(size 0.4572)
		(drill 0.2032)
		(layers "F.Cu" "B.Cu")
		(net "PVCCIN_CPU1")
	)
	(via
		(at 136.14908 -330.937616)
		(size 0.508)
		(drill 0.254)
		(layers "F.Cu" "B.Cu")
		(net "PVCCIN_CPU1")
	)
	(via
		(at 114.569748 -262.058912)
		(size 0.4572)
		(drill 0.2032)
		(layers "F.Cu" "B.Cu")
		(net "PVCCIN_CPU1")
	)
	(via
		(at 119.48541 -321.893692)
		(size 0.508)
		(drill 0.254)
		(layers "F.Cu" "B.Cu")
		(net "PVCCIN_CPU1")
	)
	(via
		(at 113.159794 -285.661354)
		(size 0.4572)
		(drill 0.2032)
		(layers "F.Cu" "B.Cu")
		(net "PVCCIN_CPU1")
	)
	(via
		(at 120.15089 -319.243964)
		(size 0.508)
		(drill 0.254)
		(layers "F.Cu" "B.Cu")
		(net "PVCCIN_CPU1")
	)
	(via
		(at 99.026472 -318.543178)
		(size 0.508)
		(drill 0.254)
		(layers "F.Cu" "B.Cu")
		(net "PVCCIN_CPU1")
	)
	(via
		(at 112.046512 -317.245238)
		(size 0.508)
		(drill 0.254)
		(layers "F.Cu" "B.Cu")
		(net "PVCCIN_CPU1")
	)
	(via
		(at 106.581448 -288.917126)
		(size 0.4572)
		(drill 0.2032)
		(layers "F.Cu" "B.Cu")
		(net "PVCCIN_CPU1")
	)
	(via
		(at 111.977932 -319.243964)
		(size 0.508)
		(drill 0.254)
		(layers "F.Cu" "B.Cu")
		(net "PVCCIN_CPU1")
	)
	(via
		(at 94.289372 -320.511678)
		(size 0.508)
		(drill 0.254)
		(layers "F.Cu" "B.Cu")
		(net "PVCCIN_CPU1")
	)
	(via
		(at 109.400594 -287.28924)
		(size 0.4572)
		(drill 0.2032)
		(layers "F.Cu" "B.Cu")
		(net "PVCCIN_CPU1")
	)
	(via
		(at 112.220248 -282.405836)
		(size 0.4572)
		(drill 0.2032)
		(layers "F.Cu" "B.Cu")
		(net "PVCCIN_CPU1")
	)
	(via
		(at 117.388894 -286.475424)
		(size 0.4572)
		(drill 0.2032)
		(layers "F.Cu" "B.Cu")
		(net "PVCCIN_CPU1")
	)
	(via
		(at 107.51439 -262.784336)
		(size 0.4572)
		(drill 0.2032)
		(layers "F.Cu" "B.Cu")
		(net "PVCCIN_CPU1")
	)
	(via
		(at 91.536012 -321.215258)
		(size 0.508)
		(drill 0.254)
		(layers "F.Cu" "B.Cu")
		(net "PVCCIN_CPU1")
	)
	(via
		(at 116.031772 -319.198498)
		(size 0.508)
		(drill 0.254)
		(layers "F.Cu" "B.Cu")
		(net "PVCCIN_CPU1")
	)
	(via
		(at 109.400594 -264.50036)
		(size 0.4572)
		(drill 0.2032)
		(layers "F.Cu" "B.Cu")
		(net "PVCCIN_CPU1")
	)
	(via
		(at 127.68072 -325.133716)
		(size 0.508)
		(drill 0.254)
		(layers "F.Cu" "B.Cu")
		(net "PVCCIN_CPU1")
	)
	(via
		(at 113.99012 -243.109242)
		(size 0.4572)
		(drill 0.2032)
		(layers "F.Cu" "B.Cu")
		(net "PVCCIN_CPU1")
	)
	(via
		(at 83.326732 -328.654918)
		(size 0.508)
		(drill 0.254)
		(layers "F.Cu" "B.Cu")
		(net "PVCCIN_CPU1")
	)
	(via
		(at 106.581448 -285.661354)
		(size 0.4572)
		(drill 0.2032)
		(layers "F.Cu" "B.Cu")
		(net "PVCCIN_CPU1")
	)
	(via
		(at 116.449094 -281.59202)
		(size 0.4572)
		(drill 0.2032)
		(layers "F.Cu" "B.Cu")
		(net "PVCCIN_CPU1")
	)
	(via
		(at 111.750094 -276.708616)
		(size 0.4572)
		(drill 0.2032)
		(layers "F.Cu" "B.Cu")
		(net "PVCCIN_CPU1")
	)
	(via
		(at 134.347966 -346.509848)
		(size 0.508)
		(drill 0.254)
		(layers "F.Cu" "B.Cu")
		(net "PVCCIN_CPU1")
	)
	(via
		(at 119.51335 -319.251584)
		(size 0.508)
		(drill 0.254)
		(layers "F.Cu" "B.Cu")
		(net "PVCCIN_CPU1")
	)
	(via
		(at 110.810548 -270.19758)
		(size 0.4572)
		(drill 0.2032)
		(layers "F.Cu" "B.Cu")
		(net "PVCCIN_CPU1")
	)
	(via
		(at 87.443056 -323.20357)
		(size 0.508)
		(drill 0.254)
		(layers "F.Cu" "B.Cu")
		(net "PVCCIN_CPU1")
	)
	(via
		(at 118.328694 -286.475424)
		(size 0.4572)
		(drill 0.2032)
		(layers "F.Cu" "B.Cu")
		(net "PVCCIN_CPU1")
	)
	(via
		(at 117.388894 -283.219906)
		(size 0.4572)
		(drill 0.2032)
		(layers "F.Cu" "B.Cu")
		(net "PVCCIN_CPU1")
	)
	(via
		(at 108.68025 -261.367016)
		(size 0.4572)
		(drill 0.2032)
		(layers "F.Cu" "B.Cu")
		(net "PVCCIN_CPU1")
	)
	(via
		(at 116.919248 -288.917126)
		(size 0.4572)
		(drill 0.2032)
		(layers "F.Cu" "B.Cu")
		(net "PVCCIN_CPU1")
	)
	(via
		(at 110.746032 -317.890398)
		(size 0.508)
		(drill 0.254)
		(layers "F.Cu" "B.Cu")
		(net "PVCCIN_CPU1")
	)
	(via
		(at 86.805516 -323.84619)
		(size 0.508)
		(drill 0.254)
		(layers "F.Cu" "B.Cu")
		(net "PVCCIN_CPU1")
	)
	(via
		(at 136.5631 -329.809856)
		(size 0.508)
		(drill 0.254)
		(layers "F.Cu" "B.Cu")
		(net "PVCCIN_CPU1")
	)
	(via
		(at 113.160048 -257.989324)
		(size 0.4572)
		(drill 0.2032)
		(layers "F.Cu" "B.Cu")
		(net "PVCCIN_CPU1")
	)
	(via
		(at 104.15651 -250.34494)
		(size 0.4572)
		(drill 0.2032)
		(layers "F.Cu" "B.Cu")
		(net "PVCCIN_CPU1")
	)
	(via
		(at 111.280702 -257.989324)
		(size 0.4572)
		(drill 0.2032)
		(layers "F.Cu" "B.Cu")
		(net "PVCCIN_CPU1")
	)
	(via
		(at 131.0513 -324.364096)
		(size 0.508)
		(drill 0.254)
		(layers "F.Cu" "B.Cu")
		(net "PVCCIN_CPU1")
	)
	(via
		(at 111.750094 -283.219906)
		(size 0.4572)
		(drill 0.2032)
		(layers "F.Cu" "B.Cu")
		(net "PVCCIN_CPU1")
	)
	(via
		(at 104.74579 -254.02032)
		(size 0.4572)
		(drill 0.2032)
		(layers "F.Cu" "B.Cu")
		(net "PVCCIN_CPU1")
	)
	(via
		(at 112.016032 -318.558418)
		(size 0.508)
		(drill 0.254)
		(layers "F.Cu" "B.Cu")
		(net "PVCCIN_CPU1")
	)
	(via
		(at 115.979194 -284.033722)
		(size 0.4572)
		(drill 0.2032)
		(layers "F.Cu" "B.Cu")
		(net "PVCCIN_CPU1")
	)
	(via
		(at 114.717068 -319.875154)
		(size 0.508)
		(drill 0.254)
		(layers "F.Cu" "B.Cu")
		(net "PVCCIN_CPU1")
	)
	(via
		(at 94.951042 -319.251584)
		(size 0.508)
		(drill 0.254)
		(layers "F.Cu" "B.Cu")
		(net "PVCCIN_CPU1")
	)
	(via
		(at 124.169932 -319.866518)
		(size 0.508)
		(drill 0.254)
		(layers "F.Cu" "B.Cu")
		(net "PVCCIN_CPU1")
	)
	(via
		(at 109.870748 -263.686798)
		(size 0.4572)
		(drill 0.2032)
		(layers "F.Cu" "B.Cu")
		(net "PVCCIN_CPU1")
	)
	(via
		(at 135.300212 -326.338438)
		(size 0.508)
		(drill 0.254)
		(layers "F.Cu" "B.Cu")
		(net "PVCCIN_CPU1")
	)
	(via
		(at 107.225592 -317.229998)
		(size 0.508)
		(drill 0.254)
		(layers "F.Cu" "B.Cu")
		(net "PVCCIN_CPU1")
	)
	(via
		(at 110.730792 -318.550798)
		(size 0.508)
		(drill 0.254)
		(layers "F.Cu" "B.Cu")
		(net "PVCCIN_CPU1")
	)
	(via
		(at 109.29112 -246.36476)
		(size 0.4572)
		(drill 0.2032)
		(layers "F.Cu" "B.Cu")
		(net "PVCCIN_CPU1")
	)
	(via
		(at 82.739992 -326.386698)
		(size 0.508)
		(drill 0.254)
		(layers "F.Cu" "B.Cu")
		(net "PVCCIN_CPU1")
	)
	(via
		(at 115.509294 -289.807142)
		(size 0.4572)
		(drill 0.2032)
		(layers "F.Cu" "B.Cu")
		(net "PVCCIN_CPU1")
	)
	(via
		(at 115.21059 -239.912652)
		(size 0.4572)
		(drill 0.2032)
		(layers "F.Cu" "B.Cu")
		(net "PVCCIN_CPU1")
	)
	(via
		(at 111.98098 -320.515742)
		(size 0.508)
		(drill 0.254)
		(layers "F.Cu" "B.Cu")
		(net "PVCCIN_CPU1")
	)
	(via
		(at 113.159794 -287.28924)
		(size 0.4572)
		(drill 0.2032)
		(layers "F.Cu" "B.Cu")
		(net "PVCCIN_CPU1")
	)
	(via
		(at 103.74503 -321.888612)
		(size 0.508)
		(drill 0.254)
		(layers "F.Cu" "B.Cu")
		(net "PVCCIN_CPU1")
	)
	(via
		(at 109.870748 -262.058912)
		(size 0.4572)
		(drill 0.2032)
		(layers "F.Cu" "B.Cu")
		(net "PVCCIN_CPU1")
	)
	(via
		(at 116.449094 -289.807142)
		(size 0.4572)
		(drill 0.2032)
		(layers "F.Cu" "B.Cu")
		(net "PVCCIN_CPU1")
	)
	(via
		(at 108.68025 -253.954534)
		(size 0.4572)
		(drill 0.2032)
		(layers "F.Cu" "B.Cu")
		(net "PVCCIN_CPU1")
	)
	(via
		(at 110.67161 -321.865752)
		(size 0.508)
		(drill 0.254)
		(layers "F.Cu" "B.Cu")
		(net "PVCCIN_CPU1")
	)
	(via
		(at 123.598432 -317.237618)
		(size 0.508)
		(drill 0.254)
		(layers "F.Cu" "B.Cu")
		(net "PVCCIN_CPU1")
	)
	(segment
		(start 116.158518 -314.727082)
		(end 117.098826 -315.66739)
		(width 0.508)
		(layer "B.Cu")
		(net "PVCCIN_CPU1")
	)
	(segment
		(start 109.887512 -336.814668)
		(end 109.658912 -336.586068)
		(width 0.381)
		(layer "B.Cu")
		(net "PVCCIN_CPU1")
	)
	(segment
		(start 122.356118 -314.727082)
		(end 123.296426 -315.66739)
		(width 0.508)
		(layer "B.Cu")
		(net "PVCCIN_CPU1")
	)
	(segment
		(start 101.643942 -337.195922)
		(end 101.717348 -337.122516)
		(width 0.254)
		(layer "B.Cu")
		(net "PVCCIN_CPU1")
	)
	(segment
		(start 77.228954 -346.649294)
		(end 77.228954 -346.825062)
		(width 0.254)
		(layer "B.Cu")
		(net "PVCCIN_CPU1")
	)
	(segment
		(start 76.413106 -332.227174)
		(end 77.126338 -332.227174)
		(width 0.381)
		(layer "B.Cu")
		(net "PVCCIN_CPU1")
	)
	(segment
		(start 98.525838 -315.66739)
		(end 99.466146 -316.607698)
		(width 0.508)
		(layer "B.Cu")
		(net "PVCCIN_CPU1")
	)
	(segment
		(start 116.158518 -316.607698)
		(end 117.098826 -315.66739)
		(width 0.508)
		(layer "B.Cu")
		(net "PVCCIN_CPU1")
	)
	(segment
		(start 104.723438 -315.66739)
		(end 105.663746 -316.607698)
		(width 0.508)
		(layer "B.Cu")
		(net "PVCCIN_CPU1")
	)
	(segment
		(start 101.643942 -337.198462)
		(end 101.643942 -337.195922)
		(width 0.254)
		(layer "B.Cu")
		(net "PVCCIN_CPU1")
	)
	(segment
		(start 117.098826 -315.66739)
		(end 118.039134 -314.727082)
		(width 0.508)
		(layer "B.Cu")
		(net "PVCCIN_CPU1")
	)
	(segment
		(start 104.723438 -315.66739)
		(end 105.663746 -314.727082)
		(width 0.508)
		(layer "B.Cu")
		(net "PVCCIN_CPU1")
	)
	(segment
		(start 97.58553 -314.727082)
		(end 98.525838 -315.66739)
		(width 0.508)
		(layer "B.Cu")
		(net "PVCCIN_CPU1")
	)
	(segment
		(start 93.571314 -336.678524)
		(end 93.571314 -337.352894)
		(width 0.254)
		(layer "B.Cu")
		(net "PVCCIN_CPU1")
	)
	(segment
		(start 123.296426 -315.66739)
		(end 124.236734 -314.727082)
		(width 0.508)
		(layer "B.Cu")
		(net "PVCCIN_CPU1")
	)
	(segment
		(start 97.58553 -316.607698)
		(end 98.525838 -315.66739)
		(width 0.508)
		(layer "B.Cu")
		(net "PVCCIN_CPU1")
	)
	(segment
		(start 101.717348 -337.122516)
		(end 101.717348 -336.592418)
		(width 0.254)
		(layer "B.Cu")
		(net "PVCCIN_CPU1")
	)
	(segment
		(start 134.347966 -345.863164)
		(end 134.347966 -346.509848)
		(width 0.254)
		(layer "B.Cu")
		(net "PVCCIN_CPU1")
	)
	(segment
		(start 109.887512 -337.27263)
		(end 109.887512 -336.814668)
		(width 0.381)
		(layer "B.Cu")
		(net "PVCCIN_CPU1")
	)
	(segment
		(start 109.960918 -314.727082)
		(end 110.901226 -315.66739)
		(width 0.508)
		(layer "B.Cu")
		(net "PVCCIN_CPU1")
	)
	(segment
		(start 109.960918 -316.607698)
		(end 110.901226 -315.66739)
		(width 0.508)
		(layer "B.Cu")
		(net "PVCCIN_CPU1")
	)
	(segment
		(start 98.525838 -315.66739)
		(end 99.466146 -314.727082)
		(width 0.508)
		(layer "B.Cu")
		(net "PVCCIN_CPU1")
	)
	(segment
		(start 101.618542 -337.223862)
		(end 101.643942 -337.198462)
		(width 0.254)
		(layer "B.Cu")
		(net "PVCCIN_CPU1")
	)
	(segment
		(start 110.901226 -315.66739)
		(end 111.841534 -316.607698)
		(width 0.508)
		(layer "B.Cu")
		(net "PVCCIN_CPU1")
	)
	(segment
		(start 117.904514 -336.592418)
		(end 117.904514 -337.259422)
		(width 0.254)
		(layer "B.Cu")
		(net "PVCCIN_CPU1")
	)
	(segment
		(start 103.78313 -316.607698)
		(end 104.723438 -315.66739)
		(width 0.508)
		(layer "B.Cu")
		(net "PVCCIN_CPU1")
	)
	(segment
		(start 126.065026 -340.002622)
		(end 126.065026 -340.681056)
		(width 0.254)
		(layer "B.Cu")
		(net "PVCCIN_CPU1")
	)
	(segment
		(start 123.296426 -315.66739)
		(end 124.236734 -316.607698)
		(width 0.508)
		(layer "B.Cu")
		(net "PVCCIN_CPU1")
	)
	(segment
		(start 103.78313 -314.727082)
		(end 104.723438 -315.66739)
		(width 0.508)
		(layer "B.Cu")
		(net "PVCCIN_CPU1")
	)
	(segment
		(start 76.809854 -346.230194)
		(end 77.228954 -346.649294)
		(width 0.254)
		(layer "B.Cu")
		(net "PVCCIN_CPU1")
	)
	(segment
		(start 85.389466 -340.383622)
		(end 85.389466 -341.059262)
		(width 0.254)
		(layer "B.Cu")
		(net "PVCCIN_CPU1")
	)
	(segment
		(start 110.901226 -315.66739)
		(end 111.841534 -314.727082)
		(width 0.508)
		(layer "B.Cu")
		(net "PVCCIN_CPU1")
	)
	(segment
		(start 117.098826 -315.66739)
		(end 118.039134 -316.607698)
		(width 0.508)
		(layer "B.Cu")
		(net "PVCCIN_CPU1")
	)
	(segment
		(start 122.356118 -316.607698)
		(end 123.296426 -315.66739)
		(width 0.508)
		(layer "B.Cu")
		(net "PVCCIN_CPU1")
	)
	(segment
		(start 93.514418 -326.332342)
		(end 94.385384 -327.203308)
		(width 0.381)
		(layer "In2.Cu")
		(net "PVCCIN_CPU1")
	)
	(segment
		(start 94.385384 -327.203308)
		(end 94.385384 -328.152252)
		(width 0.381)
		(layer "In2.Cu")
		(net "PVCCIN_CPU1")
	)
	(segment
		(start 94.385638 -331.84973)
		(end 94.385638 -335.27619)
		(width 0.381)
		(layer "In2.Cu")
		(net "PVCCIN_CPU1")
	)
	(segment
		(start 77.1652 -342.476328)
		(end 76.59878 -342.476328)
		(width 0.381)
		(layer "In2.Cu")
		(net "PVCCIN_CPU1")
	)
	(segment
		(start 77.844142 -341.797386)
		(end 77.1652 -342.476328)
		(width 0.381)
		(layer "In2.Cu")
		(net "PVCCIN_CPU1")
	)
	(segment
		(start 118.86946 -335.212944)
		(end 117.904514 -336.17789)
		(width 0.381)
		(layer "In2.Cu")
		(net "PVCCIN_CPU1")
	)
	(segment
		(start 81.388712 -329.683618)
		(end 77.844142 -333.228188)
		(width 0.381)
		(layer "In2.Cu")
		(net "PVCCIN_CPU1")
	)
	(segment
		(start 101.653594 -336.020918)
		(end 102.45979 -335.214722)
		(width 0.381)
		(layer "In2.Cu")
		(net "PVCCIN_CPU1")
	)
	(segment
		(start 86.11489 -325.175372)
		(end 85.47608 -325.814182)
		(width 0.381)
		(layer "In2.Cu")
		(net "PVCCIN_CPU1")
	)
	(segment
		(start 111.95685 -321.873372)
		(end 111.95685 -322.566538)
		(width 0.381)
		(layer "In2.Cu")
		(net "PVCCIN_CPU1")
	)
	(segment
		(start 109.887512 -336.18424)
		(end 109.887512 -337.27263)
		(width 0.381)
		(layer "In2.Cu")
		(net "PVCCIN_CPU1")
	)
	(segment
		(start 135.190738 -336.32267)
		(end 135.190738 -344.59291)
		(width 0.381)
		(layer "In2.Cu")
		(net "PVCCIN_CPU1")
	)
	(segment
		(start 134.009638 -345.77401)
		(end 134.009638 -346.17152)
		(width 0.381)
		(layer "In2.Cu")
		(net "PVCCIN_CPU1")
	)
	(segment
		(start 126.983998 -334.293464)
		(end 127.177292 -334.10017)
		(width 0.381)
		(layer "In2.Cu")
		(net "PVCCIN_CPU1")
	)
	(segment
		(start 110.743492 -328.526648)
		(end 110.743492 -335.32826)
		(width 0.381)
		(layer "In2.Cu")
		(net "PVCCIN_CPU1")
	)
	(segment
		(start 101.653594 -337.18881)
		(end 101.653594 -336.020918)
		(width 0.381)
		(layer "In2.Cu")
		(net "PVCCIN_CPU1")
	)
	(segment
		(start 93.514418 -322.642484)
		(end 93.514418 -326.332342)
		(width 0.381)
		(layer "In2.Cu")
		(net "PVCCIN_CPU1")
	)
	(segment
		(start 111.42726 -323.096128)
		(end 111.42726 -327.84288)
		(width 0.381)
		(layer "In2.Cu")
		(net "PVCCIN_CPU1")
	)
	(segment
		(start 134.49808 -335.630012)
		(end 135.190738 -336.32267)
		(width 0.381)
		(layer "In2.Cu")
		(net "PVCCIN_CPU1")
	)
	(segment
		(start 86.241636 -338.793074)
		(end 85.057742 -339.976968)
		(width 0.381)
		(layer "In2.Cu")
		(net "PVCCIN_CPU1")
	)
	(segment
		(start 86.241636 -331.232002)
		(end 86.241636 -338.793074)
		(width 0.381)
		(layer "In2.Cu")
		(net "PVCCIN_CPU1")
	)
	(segment
		(start 126.983998 -336.961988)
		(end 126.983998 -334.293464)
		(width 0.381)
		(layer "In2.Cu")
		(net "PVCCIN_CPU1")
	)
	(segment
		(start 118.869206 -328.152252)
		(end 118.86946 -331.84973)
		(width 0.381)
		(layer "In2.Cu")
		(net "PVCCIN_CPU1")
	)
	(segment
		(start 126.065026 -340.681056)
		(end 125.764798 -340.380828)
		(width 0.381)
		(layer "In2.Cu")
		(net "PVCCIN_CPU1")
	)
	(segment
		(start 118.358666 -322.390516)
		(end 118.358666 -327.141078)
		(width 0.381)
		(layer "In2.Cu")
		(net "PVCCIN_CPU1")
	)
	(segment
		(start 125.764798 -339.907118)
		(end 127.12192 -338.549996)
		(width 0.381)
		(layer "In2.Cu")
		(net "PVCCIN_CPU1")
	)
	(segment
		(start 94.29115 -321.865752)
		(end 93.514418 -322.642484)
		(width 0.381)
		(layer "In2.Cu")
		(net "PVCCIN_CPU1")
	)
	(segment
		(start 127.177038 -329.58913)
		(end 127.0381 -329.450192)
		(width 0.381)
		(layer "In2.Cu")
		(net "PVCCIN_CPU1")
	)
	(segment
		(start 118.84787 -321.901312)
		(end 118.358666 -322.390516)
		(width 0.381)
		(layer "In2.Cu")
		(net "PVCCIN_CPU1")
	)
	(segment
		(start 118.869206 -327.651618)
		(end 118.869206 -328.152252)
		(width 0.381)
		(layer "In2.Cu")
		(net "PVCCIN_CPU1")
	)
	(segment
		(start 102.45979 -335.214722)
		(end 102.45979 -321.880992)
		(width 0.381)
		(layer "In2.Cu")
		(net "PVCCIN_CPU1")
	)
	(segment
		(start 127.12192 -337.09991)
		(end 126.983998 -336.961988)
		(width 0.381)
		(layer "In2.Cu")
		(net "PVCCIN_CPU1")
	)
	(segment
		(start 94.385638 -335.27619)
		(end 93.313758 -336.34807)
		(width 0.381)
		(layer "In2.Cu")
		(net "PVCCIN_CPU1")
	)
	(segment
		(start 125.764798 -340.380828)
		(end 125.764798 -339.907118)
		(width 0.381)
		(layer "In2.Cu")
		(net "PVCCIN_CPU1")
	)
	(segment
		(start 76.0222 -345.618308)
		(end 77.228954 -346.825062)
		(width 0.381)
		(layer "In2.Cu")
		(net "PVCCIN_CPU1")
	)
	(segment
		(start 101.618542 -337.223862)
		(end 101.653594 -337.18881)
		(width 0.381)
		(layer "In2.Cu")
		(net "PVCCIN_CPU1")
	)
	(segment
		(start 134.009638 -346.17152)
		(end 134.347966 -346.509848)
		(width 0.381)
		(layer "In2.Cu")
		(net "PVCCIN_CPU1")
	)
	(segment
		(start 127.177038 -334.099916)
		(end 127.177038 -329.58913)
		(width 0.381)
		(layer "In2.Cu")
		(net "PVCCIN_CPU1")
	)
	(segment
		(start 77.844142 -333.228188)
		(end 77.844142 -341.797386)
		(width 0.381)
		(layer "In2.Cu")
		(net "PVCCIN_CPU1")
	)
	(segment
		(start 85.057742 -339.976968)
		(end 85.057742 -340.727538)
		(width 0.381)
		(layer "In2.Cu")
		(net "PVCCIN_CPU1")
	)
	(segment
		(start 94.385384 -328.152252)
		(end 94.385638 -331.84973)
		(width 0.381)
		(layer "In2.Cu")
		(net "PVCCIN_CPU1")
	)
	(segment
		(start 85.057742 -340.727538)
		(end 85.389466 -341.059262)
		(width 0.381)
		(layer "In2.Cu")
		(net "PVCCIN_CPU1")
	)
	(segment
		(start 127.177292 -334.10017)
		(end 127.177038 -334.099916)
		(width 0.381)
		(layer "In2.Cu")
		(net "PVCCIN_CPU1")
	)
	(segment
		(start 127.0381 -329.450192)
		(end 127.0381 -324.638416)
		(width 0.381)
		(layer "In2.Cu")
		(net "PVCCIN_CPU1")
	)
	(segment
		(start 111.42726 -327.84288)
		(end 110.743492 -328.526648)
		(width 0.381)
		(layer "In2.Cu")
		(net "PVCCIN_CPU1")
	)
	(segment
		(start 117.904514 -336.17789)
		(end 117.904514 -337.259422)
		(width 0.381)
		(layer "In2.Cu")
		(net "PVCCIN_CPU1")
	)
	(segment
		(start 76.59878 -342.476328)
		(end 76.0222 -343.052908)
		(width 0.381)
		(layer "In2.Cu")
		(net "PVCCIN_CPU1")
	)
	(segment
		(start 135.190738 -344.59291)
		(end 134.009638 -345.77401)
		(width 0.381)
		(layer "In2.Cu")
		(net "PVCCIN_CPU1")
	)
	(segment
		(start 118.358666 -327.141078)
		(end 118.869206 -327.651618)
		(width 0.381)
		(layer "In2.Cu")
		(net "PVCCIN_CPU1")
	)
	(segment
		(start 127.12192 -338.549996)
		(end 127.12192 -337.09991)
		(width 0.381)
		(layer "In2.Cu")
		(net "PVCCIN_CPU1")
	)
	(segment
		(start 134.7343 -329.441556)
		(end 134.49808 -329.677776)
		(width 0.381)
		(layer "In2.Cu")
		(net "PVCCIN_CPU1")
	)
	(segment
		(start 118.86946 -331.84973)
		(end 118.86946 -335.212944)
		(width 0.381)
		(layer "In2.Cu")
		(net "PVCCIN_CPU1")
	)
	(segment
		(start 93.313758 -337.095338)
		(end 93.571314 -337.352894)
		(width 0.381)
		(layer "In2.Cu")
		(net "PVCCIN_CPU1")
	)
	(segment
		(start 76.0222 -343.052908)
		(end 76.0222 -345.618308)
		(width 0.381)
		(layer "In2.Cu")
		(net "PVCCIN_CPU1")
	)
	(segment
		(start 85.47608 -330.466446)
		(end 86.241636 -331.232002)
		(width 0.381)
		(layer "In2.Cu")
		(net "PVCCIN_CPU1")
	)
	(segment
		(start 85.47608 -325.814182)
		(end 85.47608 -330.466446)
		(width 0.381)
		(layer "In2.Cu")
		(net "PVCCIN_CPU1")
	)
	(segment
		(start 93.313758 -336.34807)
		(end 93.313758 -337.095338)
		(width 0.381)
		(layer "In2.Cu")
		(net "PVCCIN_CPU1")
	)
	(segment
		(start 134.49808 -329.677776)
		(end 134.49808 -335.630012)
		(width 0.381)
		(layer "In2.Cu")
		(net "PVCCIN_CPU1")
	)
	(segment
		(start 110.743492 -335.32826)
		(end 109.887512 -336.18424)
		(width 0.381)
		(layer "In2.Cu")
		(net "PVCCIN_CPU1")
	)
	(segment
		(start 111.95685 -322.566538)
		(end 111.42726 -323.096128)
		(width 0.381)
		(layer "In2.Cu")
		(net "PVCCIN_CPU1")
	)
	(segment
		(start 117.098826 -315.66739)
		(end 117.814598 -314.951618)
		(width 0.508)
		(layer "In4.Cu")
		(net "PVCCIN_CPU1")
	)
	(segment
		(start 122.580654 -314.951618)
		(end 123.296426 -315.66739)
		(width 0.508)
		(layer "In4.Cu")
		(net "PVCCIN_CPU1")
	)
	(segment
		(start 116.383054 -314.951618)
		(end 117.098826 -315.66739)
		(width 0.508)
		(layer "In4.Cu")
		(net "PVCCIN_CPU1")
	)
	(segment
		(start 116.383054 -316.383162)
		(end 117.098826 -315.66739)
		(width 0.508)
		(layer "In4.Cu")
		(net "PVCCIN_CPU1")
	)
	(segment
		(start 97.810066 -316.383162)
		(end 98.525838 -315.66739)
		(width 0.508)
		(layer "In4.Cu")
		(net "PVCCIN_CPU1")
	)
	(segment
		(start 104.723438 -315.66739)
		(end 105.43921 -316.383162)
		(width 0.508)
		(layer "In4.Cu")
		(net "PVCCIN_CPU1")
	)
	(segment
		(start 122.580654 -316.383162)
		(end 123.296426 -315.66739)
		(width 0.508)
		(layer "In4.Cu")
		(net "PVCCIN_CPU1")
	)
	(segment
		(start 110.185454 -316.383162)
		(end 110.901226 -315.66739)
		(width 0.508)
		(layer "In4.Cu")
		(net "PVCCIN_CPU1")
	)
	(segment
		(start 110.901226 -315.66739)
		(end 111.616998 -316.383162)
		(width 0.508)
		(layer "In4.Cu")
		(net "PVCCIN_CPU1")
	)
	(segment
		(start 117.098826 -315.66739)
		(end 117.814598 -316.383162)
		(width 0.508)
		(layer "In4.Cu")
		(net "PVCCIN_CPU1")
	)
	(segment
		(start 110.185454 -314.951618)
		(end 110.901226 -315.66739)
		(width 0.508)
		(layer "In4.Cu")
		(net "PVCCIN_CPU1")
	)
	(segment
		(start 98.525838 -315.66739)
		(end 99.24161 -314.951618)
		(width 0.508)
		(layer "In4.Cu")
		(net "PVCCIN_CPU1")
	)
	(segment
		(start 123.296426 -315.66739)
		(end 124.012198 -314.951618)
		(width 0.508)
		(layer "In4.Cu")
		(net "PVCCIN_CPU1")
	)
	(segment
		(start 110.901226 -315.66739)
		(end 111.616998 -314.951618)
		(width 0.508)
		(layer "In4.Cu")
		(net "PVCCIN_CPU1")
	)
	(segment
		(start 97.810066 -314.951618)
		(end 98.525838 -315.66739)
		(width 0.508)
		(layer "In4.Cu")
		(net "PVCCIN_CPU1")
	)
	(segment
		(start 104.723438 -315.66739)
		(end 105.43921 -314.951618)
		(width 0.508)
		(layer "In4.Cu")
		(net "PVCCIN_CPU1")
	)
	(segment
		(start 98.525838 -315.66739)
		(end 99.24161 -316.383162)
		(width 0.508)
		(layer "In4.Cu")
		(net "PVCCIN_CPU1")
	)
	(segment
		(start 104.007666 -316.383162)
		(end 104.723438 -315.66739)
		(width 0.508)
		(layer "In4.Cu")
		(net "PVCCIN_CPU1")
	)
	(segment
		(start 123.296426 -315.66739)
		(end 124.012198 -316.383162)
		(width 0.508)
		(layer "In4.Cu")
		(net "PVCCIN_CPU1")
	)
	(segment
		(start 104.007666 -314.951618)
		(end 104.723438 -315.66739)
		(width 0.508)
		(layer "In4.Cu")
		(net "PVCCIN_CPU1")
	)
	(segment
		(start 360.836464 -357.217472)
		(end 360.7308 -357.472488)
		(width 0.1778)
		(layer "F.Cu")
		(net "PVCCIN_CPU0_VR_FAULT")
	)
	(segment
		(start 360.7308 -357.472488)
		(end 359.95483 -358.248458)
		(width 0.1778)
		(layer "F.Cu")
		(net "PVCCIN_CPU0_VR_FAULT")
	)
	(segment
		(start 359.95483 -358.248458)
		(end 359.393236 -358.248458)
		(width 0.1778)
		(layer "F.Cu")
		(net "PVCCIN_CPU0_VR_FAULT")
	)
	(segment
		(start 361.507024 -356.546912)
		(end 360.836464 -357.217472)
		(width 0.1778)
		(layer "F.Cu")
		(net "PVCCIN_CPU0_VR_FAULT")
	)
	(via
		(at 361.507024 -356.546912)
		(size 0.508)
		(drill 0.254)
		(layers "F.Cu" "B.Cu")
		(net "PVCCIN_CPU0_VR_FAULT")
	)
	(segment
		(start 361.507024 -356.546912)
		(end 361.52709 -356.546912)
		(width 0.12954)
		(layer "B.Cu")
		(net "PVCCIN_CPU0_VR_FAULT")
	)
	(segment
		(start 362.88726 -356.085902)
		(end 362.89615 -356.094792)
		(width 0.12954)
		(layer "B.Cu")
		(net "PVCCIN_CPU0_VR_FAULT")
	)
	(segment
		(start 361.9881 -356.085902)
		(end 362.88726 -356.085902)
		(width 0.12954)
		(layer "B.Cu")
		(net "PVCCIN_CPU0_VR_FAULT")
	)
	(segment
		(start 361.52709 -356.546912)
		(end 361.9881 -356.085902)
		(width 0.12954)
		(layer "B.Cu")
		(net "PVCCIN_CPU0_VR_FAULT")
	)
	(segment
		(start 375.477024 -341.648542)
		(end 375.144538 -341.316056)
		(width 0.254)
		(layer "F.Cu")
		(net "PVCCIN_CPU0_VREF")
	)
	(segment
		(start 423.096436 -366.26927)
		(end 423.096436 -365.85779)
		(width 0.2286)
		(layer "F.Cu")
		(net "PVCCIN_CPU0_VREF")
	)
	(segment
		(start 374.802146 -341.023448)
		(end 374.802146 -341.316056)
		(width 0.254)
		(layer "F.Cu")
		(net "PVCCIN_CPU0_VREF")
	)
	(segment
		(start 334.786986 -340.026244)
		(end 334.786986 -340.129876)
		(width 0.254)
		(layer "F.Cu")
		(net "PVCCIN_CPU0_VREF")
	)
	(segment
		(start 286.795972 -365.751364)
		(end 286.795972 -365.675418)
		(width 0.254)
		(layer "F.Cu")
		(net "PVCCIN_CPU0_VREF")
	)
	(segment
		(start 296.497248 -367.274856)
		(end 296.351706 -367.274856)
		(width 0.254)
		(layer "F.Cu")
		(net "PVCCIN_CPU0_VREF")
	)
	(segment
		(start 342.620346 -337.898232)
		(end 342.14181 -337.898232)
		(width 0.254)
		(layer "F.Cu")
		(net "PVCCIN_CPU0_VREF")
	)
	(segment
		(start 423.408348 -366.26927)
		(end 423.096436 -366.26927)
		(width 0.254)
		(layer "F.Cu")
		(net "PVCCIN_CPU0_VREF")
	)
	(segment
		(start 342.960452 -338.238338)
		(end 342.620346 -337.898232)
		(width 0.254)
		(layer "F.Cu")
		(net "PVCCIN_CPU0_VREF")
	)
	(segment
		(start 374.948958 -340.76259)
		(end 374.948958 -340.876636)
		(width 0.254)
		(layer "F.Cu")
		(net "PVCCIN_CPU0_VREF")
	)
	(segment
		(start 413.907732 -366.26927)
		(end 413.408114 -366.26927)
		(width 0.254)
		(layer "F.Cu")
		(net "PVCCIN_CPU0_VREF")
	)
	(segment
		(start 382.968754 -347.109796)
		(end 382.968754 -346.693998)
		(width 0.254)
		(layer "F.Cu")
		(net "PVCCIN_CPU0_VREF")
	)
	(segment
		(start 367.429034 -336.711798)
		(end 366.72139 -337.419442)
		(width 0.254)
		(layer "F.Cu")
		(net "PVCCIN_CPU0_VREF")
	)
	(segment
		(start 375.589546 -340.122002)
		(end 374.948958 -340.76259)
		(width 0.254)
		(layer "F.Cu")
		(net "PVCCIN_CPU0_VREF")
	)
	(segment
		(start 350.773238 -337.890612)
		(end 350.294956 -337.890612)
		(width 0.254)
		(layer "F.Cu")
		(net "PVCCIN_CPU0_VREF")
	)
	(segment
		(start 360.77906 -364.890304)
		(end 360.615484 -364.726728)
		(width 0.1778)
		(layer "F.Cu")
		(net "PVCCIN_CPU0_VREF")
	)
	(segment
		(start 360.615484 -364.225078)
		(end 359.986072 -363.595666)
		(width 0.1778)
		(layer "F.Cu")
		(net "PVCCIN_CPU0_VREF")
	)
	(segment
		(start 366.72139 -337.419442)
		(end 366.72139 -337.90255)
		(width 0.254)
		(layer "F.Cu")
		(net "PVCCIN_CPU0_VREF")
	)
	(segment
		(start 296.351706 -367.274856)
		(end 296.170604 -367.093754)
		(width 0.254)
		(layer "F.Cu")
		(net "PVCCIN_CPU0_VREF")
	)
	(segment
		(start 350.294956 -337.474814)
		(end 350.294956 -337.890612)
		(width 0.254)
		(layer "F.Cu")
		(net "PVCCIN_CPU0_VREF")
	)
	(segment
		(start 367.1062 -337.90255)
		(end 366.72139 -337.90255)
		(width 0.254)
		(layer "F.Cu")
		(net "PVCCIN_CPU0_VREF")
	)
	(segment
		(start 361.573826 -364.890304)
		(end 360.77906 -364.890304)
		(width 0.1778)
		(layer "F.Cu")
		(net "PVCCIN_CPU0_VREF")
	)
	(segment
		(start 359.986072 -363.595666)
		(end 359.986072 -362.348526)
		(width 0.1778)
		(layer "F.Cu")
		(net "PVCCIN_CPU0_VREF")
	)
	(segment
		(start 414.170368 -365.07674)
		(end 414.170368 -364.987586)
		(width 0.254)
		(layer "F.Cu")
		(net "PVCCIN_CPU0_VREF")
	)
	(segment
		(start 286.454342 -366.957102)
		(end 286.033718 -366.957102)
		(width 0.254)
		(layer "F.Cu")
		(net "PVCCIN_CPU0_VREF")
	)
	(segment
		(start 342.947498 -336.718656)
		(end 342.14181 -337.524344)
		(width 0.254)
		(layer "F.Cu")
		(net "PVCCIN_CPU0_VREF")
	)
	(segment
		(start 374.948958 -340.876636)
		(end 374.802146 -341.023448)
		(width 0.254)
		(layer "F.Cu")
		(net "PVCCIN_CPU0_VREF")
	)
	(segment
		(start 375.144538 -341.316056)
		(end 374.802146 -341.316056)
		(width 0.254)
		(layer "F.Cu")
		(net "PVCCIN_CPU0_VREF")
	)
	(segment
		(start 367.441988 -338.238338)
		(end 367.1062 -337.90255)
		(width 0.254)
		(layer "F.Cu")
		(net "PVCCIN_CPU0_VREF")
	)
	(segment
		(start 383.750058 -345.912694)
		(end 383.750058 -345.816936)
		(width 0.254)
		(layer "F.Cu")
		(net "PVCCIN_CPU0_VREF")
	)
	(segment
		(start 351.10801 -336.61604)
		(end 351.10801 -336.66176)
		(width 0.254)
		(layer "F.Cu")
		(net "PVCCIN_CPU0_VREF")
	)
	(segment
		(start 351.120964 -338.238338)
		(end 350.773238 -337.890612)
		(width 0.254)
		(layer "F.Cu")
		(net "PVCCIN_CPU0_VREF")
	)
	(segment
		(start 296.484294 -365.783368)
		(end 296.484294 -365.675418)
		(width 0.2286)
		(layer "F.Cu")
		(net "PVCCIN_CPU0_VREF")
	)
	(segment
		(start 360.615484 -364.726728)
		(end 360.615484 -364.225078)
		(width 0.1778)
		(layer "F.Cu")
		(net "PVCCIN_CPU0_VREF")
	)
	(segment
		(start 358.425496 -337.562952)
		(end 358.425496 -337.897978)
		(width 0.254)
		(layer "F.Cu")
		(net "PVCCIN_CPU0_VREF")
	)
	(segment
		(start 359.281476 -338.238338)
		(end 358.941116 -337.897978)
		(width 0.254)
		(layer "F.Cu")
		(net "PVCCIN_CPU0_VREF")
	)
	(segment
		(start 383.763012 -347.439234)
		(end 383.433574 -347.109796)
		(width 0.254)
		(layer "F.Cu")
		(net "PVCCIN_CPU0_VREF")
	)
	(segment
		(start 359.268522 -336.61604)
		(end 359.268522 -336.719926)
		(width 0.254)
		(layer "F.Cu")
		(net "PVCCIN_CPU0_VREF")
	)
	(segment
		(start 334.459326 -341.307928)
		(end 334.024732 -341.307928)
		(width 0.254)
		(layer "F.Cu")
		(net "PVCCIN_CPU0_VREF")
	)
	(segment
		(start 375.589546 -340.026244)
		(end 375.589546 -340.122002)
		(width 0.254)
		(layer "F.Cu")
		(net "PVCCIN_CPU0_VREF")
	)
	(segment
		(start 342.14181 -337.524344)
		(end 342.14181 -337.898232)
		(width 0.254)
		(layer "F.Cu")
		(net "PVCCIN_CPU0_VREF")
	)
	(segment
		(start 342.947498 -336.61604)
		(end 342.947498 -336.718656)
		(width 0.254)
		(layer "F.Cu")
		(net "PVCCIN_CPU0_VREF")
	)
	(segment
		(start 382.968754 -346.693998)
		(end 383.750058 -345.912694)
		(width 0.254)
		(layer "F.Cu")
		(net "PVCCIN_CPU0_VREF")
	)
	(segment
		(start 358.941116 -337.897978)
		(end 358.425496 -337.897978)
		(width 0.254)
		(layer "F.Cu")
		(net "PVCCIN_CPU0_VREF")
	)
	(segment
		(start 359.393236 -361.75569)
		(end 359.393236 -361.0483)
		(width 0.1778)
		(layer "F.Cu")
		(net "PVCCIN_CPU0_VREF")
	)
	(segment
		(start 325.95312 -347.141292)
		(end 325.95312 -346.671646)
		(width 0.254)
		(layer "F.Cu")
		(net "PVCCIN_CPU0_VREF")
	)
	(segment
		(start 326.312022 -347.141292)
		(end 325.95312 -347.141292)
		(width 0.254)
		(layer "F.Cu")
		(net "PVCCIN_CPU0_VREF")
	)
	(segment
		(start 286.709866 -367.212626)
		(end 286.454342 -366.957102)
		(width 0.254)
		(layer "F.Cu")
		(net "PVCCIN_CPU0_VREF")
	)
	(segment
		(start 295.72204 -366.545622)
		(end 296.484294 -365.783368)
		(width 0.2286)
		(layer "F.Cu")
		(net "PVCCIN_CPU0_VREF")
	)
	(segment
		(start 423.85869 -365.095536)
		(end 423.85869 -364.987586)
		(width 0.2286)
		(layer "F.Cu")
		(net "PVCCIN_CPU0_VREF")
	)
	(segment
		(start 296.170604 -367.093754)
		(end 295.858692 -367.093754)
		(width 0.254)
		(layer "F.Cu")
		(net "PVCCIN_CPU0_VREF")
	)
	(segment
		(start 325.95312 -346.671646)
		(end 326.656954 -345.967812)
		(width 0.254)
		(layer "F.Cu")
		(net "PVCCIN_CPU0_VREF")
	)
	(segment
		(start 414.183322 -366.54486)
		(end 413.907732 -366.26927)
		(width 0.254)
		(layer "F.Cu")
		(net "PVCCIN_CPU0_VREF")
	)
	(segment
		(start 413.408114 -366.26927)
		(end 413.408114 -365.838994)
		(width 0.254)
		(layer "F.Cu")
		(net "PVCCIN_CPU0_VREF")
	)
	(segment
		(start 423.096436 -365.85779)
		(end 423.85869 -365.095536)
		(width 0.2286)
		(layer "F.Cu")
		(net "PVCCIN_CPU0_VREF")
	)
	(segment
		(start 423.871644 -366.587024)
		(end 423.726102 -366.587024)
		(width 0.254)
		(layer "F.Cu")
		(net "PVCCIN_CPU0_VREF")
	)
	(segment
		(start 375.6025 -341.648542)
		(end 375.477024 -341.648542)
		(width 0.254)
		(layer "F.Cu")
		(net "PVCCIN_CPU0_VREF")
	)
	(segment
		(start 367.429034 -336.61604)
		(end 367.429034 -336.711798)
		(width 0.254)
		(layer "F.Cu")
		(net "PVCCIN_CPU0_VREF")
	)
	(segment
		(start 286.033718 -366.513618)
		(end 286.795972 -365.751364)
		(width 0.254)
		(layer "F.Cu")
		(net "PVCCIN_CPU0_VREF")
	)
	(segment
		(start 413.408114 -365.838994)
		(end 414.170368 -365.07674)
		(width 0.254)
		(layer "F.Cu")
		(net "PVCCIN_CPU0_VREF")
	)
	(segment
		(start 326.669908 -347.499178)
		(end 326.312022 -347.141292)
		(width 0.254)
		(layer "F.Cu")
		(net "PVCCIN_CPU0_VREF")
	)
	(segment
		(start 334.786986 -340.129876)
		(end 334.024732 -340.89213)
		(width 0.254)
		(layer "F.Cu")
		(net "PVCCIN_CPU0_VREF")
	)
	(segment
		(start 383.433574 -347.109796)
		(end 382.968754 -347.109796)
		(width 0.254)
		(layer "F.Cu")
		(net "PVCCIN_CPU0_VREF")
	)
	(segment
		(start 359.986072 -362.348526)
		(end 359.393236 -361.75569)
		(width 0.1778)
		(layer "F.Cu")
		(net "PVCCIN_CPU0_VREF")
	)
	(segment
		(start 334.024732 -340.89213)
		(end 334.024732 -341.307928)
		(width 0.254)
		(layer "F.Cu")
		(net "PVCCIN_CPU0_VREF")
	)
	(segment
		(start 295.858692 -367.093754)
		(end 295.72204 -366.957102)
		(width 0.254)
		(layer "F.Cu")
		(net "PVCCIN_CPU0_VREF")
	)
	(segment
		(start 334.79994 -341.648542)
		(end 334.459326 -341.307928)
		(width 0.254)
		(layer "F.Cu")
		(net "PVCCIN_CPU0_VREF")
	)
	(segment
		(start 286.808926 -367.212626)
		(end 286.709866 -367.212626)
		(width 0.254)
		(layer "F.Cu")
		(net "PVCCIN_CPU0_VREF")
	)
	(segment
		(start 423.726102 -366.587024)
		(end 423.408348 -366.26927)
		(width 0.254)
		(layer "F.Cu")
		(net "PVCCIN_CPU0_VREF")
	)
	(segment
		(start 351.10801 -336.66176)
		(end 350.294956 -337.474814)
		(width 0.254)
		(layer "F.Cu")
		(net "PVCCIN_CPU0_VREF")
	)
	(segment
		(start 359.268522 -336.719926)
		(end 358.425496 -337.562952)
		(width 0.254)
		(layer "F.Cu")
		(net "PVCCIN_CPU0_VREF")
	)
	(segment
		(start 362.546646 -364.887764)
		(end 361.576366 -364.887764)
		(width 0.1778)
		(layer "F.Cu")
		(net "PVCCIN_CPU0_VREF")
	)
	(segment
		(start 286.033718 -366.957102)
		(end 286.033718 -366.513618)
		(width 0.254)
		(layer "F.Cu")
		(net "PVCCIN_CPU0_VREF")
	)
	(segment
		(start 361.576366 -364.887764)
		(end 361.573826 -364.890304)
		(width 0.1778)
		(layer "F.Cu")
		(net "PVCCIN_CPU0_VREF")
	)
	(segment
		(start 295.72204 -366.957102)
		(end 295.72204 -366.545622)
		(width 0.2286)
		(layer "F.Cu")
		(net "PVCCIN_CPU0_VREF")
	)
	(segment
		(start 326.656954 -345.967812)
		(end 326.656954 -345.87688)
		(width 0.254)
		(layer "F.Cu")
		(net "PVCCIN_CPU0_VREF")
	)
	(via
		(at 286.808926 -367.212626)
		(size 0.508)
		(drill 0.254)
		(layers "F.Cu" "B.Cu")
		(net "PVCCIN_CPU0_VREF")
	)
	(via
		(at 414.183322 -366.54486)
		(size 0.508)
		(drill 0.254)
		(layers "F.Cu" "B.Cu")
		(net "PVCCIN_CPU0_VREF")
	)
	(via
		(at 296.497248 -367.274856)
		(size 0.508)
		(drill 0.254)
		(layers "F.Cu" "B.Cu")
		(net "PVCCIN_CPU0_VREF")
	)
	(via
		(at 359.281476 -338.238338)
		(size 0.508)
		(drill 0.254)
		(layers "F.Cu" "B.Cu")
		(net "PVCCIN_CPU0_VREF")
	)
	(via
		(at 326.669908 -347.499178)
		(size 0.508)
		(drill 0.254)
		(layers "F.Cu" "B.Cu")
		(net "PVCCIN_CPU0_VREF")
	)
	(via
		(at 367.441988 -338.238338)
		(size 0.508)
		(drill 0.254)
		(layers "F.Cu" "B.Cu")
		(net "PVCCIN_CPU0_VREF")
	)
	(via
		(at 352.86188 -367.463832)
		(size 0.508)
		(drill 0.254)
		(layers "F.Cu" "B.Cu")
		(net "PVCCIN_CPU0_VREF")
	)
	(via
		(at 351.120964 -338.238338)
		(size 0.508)
		(drill 0.254)
		(layers "F.Cu" "B.Cu")
		(net "PVCCIN_CPU0_VREF")
	)
	(via
		(at 383.763012 -347.439234)
		(size 0.508)
		(drill 0.254)
		(layers "F.Cu" "B.Cu")
		(net "PVCCIN_CPU0_VREF")
	)
	(via
		(at 360.615484 -364.726728)
		(size 0.508)
		(drill 0.254)
		(layers "F.Cu" "B.Cu")
		(net "PVCCIN_CPU0_VREF")
	)
	(via
		(at 342.960452 -338.238338)
		(size 0.508)
		(drill 0.254)
		(layers "F.Cu" "B.Cu")
		(net "PVCCIN_CPU0_VREF")
	)
	(via
		(at 423.871644 -366.587024)
		(size 0.508)
		(drill 0.254)
		(layers "F.Cu" "B.Cu")
		(net "PVCCIN_CPU0_VREF")
	)
	(via
		(at 362.425488 -357.075994)
		(size 0.508)
		(drill 0.254)
		(layers "F.Cu" "B.Cu")
		(net "PVCCIN_CPU0_VREF")
	)
	(via
		(at 355.672898 -366.956594)
		(size 0.508)
		(drill 0.254)
		(layers "F.Cu" "B.Cu")
		(net "PVCCIN_CPU0_VREF")
	)
	(via
		(at 375.6025 -341.648542)
		(size 0.508)
		(drill 0.254)
		(layers "F.Cu" "B.Cu")
		(net "PVCCIN_CPU0_VREF")
	)
	(via
		(at 334.79994 -341.648542)
		(size 0.508)
		(drill 0.254)
		(layers "F.Cu" "B.Cu")
		(net "PVCCIN_CPU0_VREF")
	)
	(segment
		(start 362.96346 -357.330502)
		(end 362.96346 -357.690166)
		(width 0.2032)
		(layer "B.Cu")
		(net "PVCCIN_CPU0_VREF")
	)
	(segment
		(start 362.708952 -357.075994)
		(end 362.96346 -357.330502)
		(width 0.2032)
		(layer "B.Cu")
		(net "PVCCIN_CPU0_VREF")
	)
	(segment
		(start 362.425488 -357.075994)
		(end 362.708952 -357.075994)
		(width 0.2032)
		(layer "B.Cu")
		(net "PVCCIN_CPU0_VREF")
	)
	(segment
		(start 353.08794 -367.237772)
		(end 352.86188 -367.463832)
		(width 0.254)
		(layer "In4.Cu")
		(net "PVCCIN_CPU0_VREF")
	)
	(segment
		(start 357.24084 -362.012992)
		(end 356.77094 -362.482892)
		(width 0.254)
		(layer "In4.Cu")
		(net "PVCCIN_CPU0_VREF")
	)
	(segment
		(start 357.115872 -353.750372)
		(end 355.932232 -352.566732)
		(width 0.254)
		(layer "In4.Cu")
		(net "PVCCIN_CPU0_VREF")
	)
	(segment
		(start 352.82378 -364.974632)
		(end 353.08794 -365.238792)
		(width 0.254)
		(layer "In4.Cu")
		(net "PVCCIN_CPU0_VREF")
	)
	(segment
		(start 357.24084 -356.407212)
		(end 357.24084 -362.012992)
		(width 0.254)
		(layer "In4.Cu")
		(net "PVCCIN_CPU0_VREF")
	)
	(segment
		(start 348.74962 -362.726986)
		(end 350.997266 -364.974632)
		(width 0.254)
		(layer "In4.Cu")
		(net "PVCCIN_CPU0_VREF")
	)
	(segment
		(start 353.08794 -365.238792)
		(end 353.08794 -367.237772)
		(width 0.254)
		(layer "In4.Cu")
		(net "PVCCIN_CPU0_VREF")
	)
	(segment
		(start 356.77094 -364.885224)
		(end 355.90226 -365.753904)
		(width 0.254)
		(layer "In4.Cu")
		(net "PVCCIN_CPU0_VREF")
	)
	(segment
		(start 358.0892 -353.750372)
		(end 357.115872 -353.750372)
		(width 0.254)
		(layer "In4.Cu")
		(net "PVCCIN_CPU0_VREF")
	)
	(segment
		(start 356.77094 -362.482892)
		(end 356.77094 -364.885224)
		(width 0.254)
		(layer "In4.Cu")
		(net "PVCCIN_CPU0_VREF")
	)
	(segment
		(start 355.90226 -366.727232)
		(end 355.672898 -366.956594)
		(width 0.254)
		(layer "In4.Cu")
		(net "PVCCIN_CPU0_VREF")
	)
	(segment
		(start 350.014286 -352.566732)
		(end 348.74962 -353.831398)
		(width 0.254)
		(layer "In4.Cu")
		(net "PVCCIN_CPU0_VREF")
	)
	(segment
		(start 355.932232 -352.566732)
		(end 350.014286 -352.566732)
		(width 0.254)
		(layer "In4.Cu")
		(net "PVCCIN_CPU0_VREF")
	)
	(segment
		(start 357.878126 -355.769926)
		(end 357.24084 -356.407212)
		(width 0.254)
		(layer "In4.Cu")
		(net "PVCCIN_CPU0_VREF")
	)
	(segment
		(start 358.835706 -355.769926)
		(end 357.878126 -355.769926)
		(width 0.254)
		(layer "In4.Cu")
		(net "PVCCIN_CPU0_VREF")
	)
	(segment
		(start 348.74962 -353.831398)
		(end 348.74962 -362.726986)
		(width 0.254)
		(layer "In4.Cu")
		(net "PVCCIN_CPU0_VREF")
	)
	(segment
		(start 355.90226 -365.753904)
		(end 355.90226 -366.727232)
		(width 0.254)
		(layer "In4.Cu")
		(net "PVCCIN_CPU0_VREF")
	)
	(segment
		(start 350.997266 -364.974632)
		(end 352.82378 -364.974632)
		(width 0.254)
		(layer "In4.Cu")
		(net "PVCCIN_CPU0_VREF")
	)
	(segment
		(start 373.349774 -355.150674)
		(end 374.516904 -356.317804)
		(width 0.254)
		(layer "In6.Cu")
		(net "PVCCIN_CPU0_VREF")
	)
	(segment
		(start 379.057916 -356.317804)
		(end 392.253724 -369.513612)
		(width 0.254)
		(layer "In6.Cu")
		(net "PVCCIN_CPU0_VREF")
	)
	(segment
		(start 425.62145 -377.31827)
		(end 375.192036 -377.31827)
		(width 0.254)
		(layer "In6.Cu")
		(net "PVCCIN_CPU0_VREF")
	)
	(segment
		(start 366.319054 -356.308406)
		(end 368.217704 -354.409756)
		(width 0.254)
		(layer "In6.Cu")
		(net "PVCCIN_CPU0_VREF")
	)
	(segment
		(start 374.516904 -356.317804)
		(end 379.057916 -356.317804)
		(width 0.254)
		(layer "In6.Cu")
		(net "PVCCIN_CPU0_VREF")
	)
	(segment
		(start 422.993058 -367.029238)
		(end 422.993058 -368.102642)
		(width 0.254)
		(layer "In6.Cu")
		(net "PVCCIN_CPU0_VREF")
	)
	(segment
		(start 422.993058 -368.102642)
		(end 423.974768 -369.084352)
		(width 0.254)
		(layer "In6.Cu")
		(net "PVCCIN_CPU0_VREF")
	)
	(segment
		(start 371.886734 -355.150674)
		(end 373.349774 -355.150674)
		(width 0.254)
		(layer "In6.Cu")
		(net "PVCCIN_CPU0_VREF")
	)
	(segment
		(start 371.145816 -354.409756)
		(end 371.886734 -355.150674)
		(width 0.254)
		(layer "In6.Cu")
		(net "PVCCIN_CPU0_VREF")
	)
	(segment
		(start 355.51364 -361.872276)
		(end 355.51364 -355.993446)
		(width 0.254)
		(layer "In6.Cu")
		(net "PVCCIN_CPU0_VREF")
	)
	(segment
		(start 427.817788 -369.084352)
		(end 428.655988 -369.922552)
		(width 0.254)
		(layer "In6.Cu")
		(net "PVCCIN_CPU0_VREF")
	)
	(segment
		(start 368.217704 -354.409756)
		(end 371.145816 -354.409756)
		(width 0.254)
		(layer "In6.Cu")
		(net "PVCCIN_CPU0_VREF")
	)
	(segment
		(start 428.655988 -374.283732)
		(end 425.62145 -377.31827)
		(width 0.254)
		(layer "In6.Cu")
		(net "PVCCIN_CPU0_VREF")
	)
	(segment
		(start 428.655988 -369.922552)
		(end 428.655988 -374.283732)
		(width 0.254)
		(layer "In6.Cu")
		(net "PVCCIN_CPU0_VREF")
	)
	(segment
		(start 375.192036 -377.31827)
		(end 365.517176 -367.64341)
		(width 0.254)
		(layer "In6.Cu")
		(net "PVCCIN_CPU0_VREF")
	)
	(segment
		(start 423.974768 -369.084352)
		(end 427.817788 -369.084352)
		(width 0.254)
		(layer "In6.Cu")
		(net "PVCCIN_CPU0_VREF")
	)
	(segment
		(start 356.860348 -363.218984)
		(end 355.51364 -361.872276)
		(width 0.254)
		(layer "In6.Cu")
		(net "PVCCIN_CPU0_VREF")
	)
	(segment
		(start 413.795464 -366.54486)
		(end 414.183322 -366.54486)
		(width 0.254)
		(layer "In6.Cu")
		(net "PVCCIN_CPU0_VREF")
	)
	(segment
		(start 356.874318 -354.632768)
		(end 358.37368 -354.632768)
		(width 0.254)
		(layer "In6.Cu")
		(net "PVCCIN_CPU0_VREF")
	)
	(segment
		(start 365.517176 -367.64341)
		(end 358.119934 -367.64341)
		(width 0.254)
		(layer "In6.Cu")
		(net "PVCCIN_CPU0_VREF")
	)
	(segment
		(start 392.253724 -369.513612)
		(end 410.826712 -369.513612)
		(width 0.254)
		(layer "In6.Cu")
		(net "PVCCIN_CPU0_VREF")
	)
	(segment
		(start 355.51364 -355.993446)
		(end 356.874318 -354.632768)
		(width 0.254)
		(layer "In6.Cu")
		(net "PVCCIN_CPU0_VREF")
	)
	(segment
		(start 356.860348 -366.383824)
		(end 356.860348 -363.218984)
		(width 0.254)
		(layer "In6.Cu")
		(net "PVCCIN_CPU0_VREF")
	)
	(segment
		(start 423.871644 -366.587024)
		(end 423.435272 -366.587024)
		(width 0.254)
		(layer "In6.Cu")
		(net "PVCCIN_CPU0_VREF")
	)
	(segment
		(start 423.435272 -366.587024)
		(end 422.993058 -367.029238)
		(width 0.254)
		(layer "In6.Cu")
		(net "PVCCIN_CPU0_VREF")
	)
	(segment
		(start 410.826712 -369.513612)
		(end 413.795464 -366.54486)
		(width 0.254)
		(layer "In6.Cu")
		(net "PVCCIN_CPU0_VREF")
	)
	(segment
		(start 358.119934 -367.64341)
		(end 356.860348 -366.383824)
		(width 0.254)
		(layer "In6.Cu")
		(net "PVCCIN_CPU0_VREF")
	)
	(segment
		(start 362.29544 -356.308406)
		(end 366.319054 -356.308406)
		(width 0.254)
		(layer "In6.Cu")
		(net "PVCCIN_CPU0_VREF")
	)
	(segment
		(start 365.416592 -341.926672)
		(end 367.718086 -339.625178)
		(width 0.254)
		(layer "In11.Cu")
		(net "PVCCIN_CPU0_VREF")
	)
	(segment
		(start 343.229438 -338.507324)
		(end 342.960452 -338.238338)
		(width 0.254)
		(layer "In11.Cu")
		(net "PVCCIN_CPU0_VREF")
	)
	(segment
		(start 353.16922 -368.137948)
		(end 347.783658 -373.52351)
		(width 0.254)
		(layer "In11.Cu")
		(net "PVCCIN_CPU0_VREF")
	)
	(segment
		(start 343.989406 -341.045546)
		(end 343.229438 -340.285578)
		(width 0.254)
		(layer "In11.Cu")
		(net "PVCCIN_CPU0_VREF")
	)
	(segment
		(start 355.844094 -350.494346)
		(end 355.844094 -349.280988)
		(width 0.254)
		(layer "In11.Cu")
		(net "PVCCIN_CPU0_VREF")
	)
	(segment
		(start 361.678728 -350.084136)
		(end 365.509556 -346.253308)
		(width 0.254)
		(layer "In11.Cu")
		(net "PVCCIN_CPU0_VREF")
	)
	(segment
		(start 353.67468 -348.833694)
		(end 353.147122 -348.306136)
		(width 0.254)
		(layer "In11.Cu")
		(net "PVCCIN_CPU0_VREF")
	)
	(segment
		(start 305.964844 -377.484386)
		(end 288.479992 -377.484386)
		(width 0.254)
		(layer "In11.Cu")
		(net "PVCCIN_CPU0_VREF")
	)
	(segment
		(start 359.408476 -340.334092)
		(end 359.408476 -338.365338)
		(width 0.254)
		(layer "In11.Cu")
		(net "PVCCIN_CPU0_VREF")
	)
	(segment
		(start 367.79073 -352.262948)
		(end 372.455948 -347.59773)
		(width 0.254)
		(layer "In11.Cu")
		(net "PVCCIN_CPU0_VREF")
	)
	(segment
		(start 359.166668 -350.084136)
		(end 361.678728 -350.084136)
		(width 0.254)
		(layer "In11.Cu")
		(net "PVCCIN_CPU0_VREF")
	)
	(segment
		(start 340.00694 -371.104668)
		(end 345.06408 -366.047528)
		(width 0.254)
		(layer "In11.Cu")
		(net "PVCCIN_CPU0_VREF")
	)
	(segment
		(start 365.416592 -344.395806)
		(end 365.416592 -341.926672)
		(width 0.254)
		(layer "In11.Cu")
		(net "PVCCIN_CPU0_VREF")
	)
	(segment
		(start 356.866444 -350.442276)
		(end 358.3178 -348.99092)
		(width 0.254)
		(layer "In11.Cu")
		(net "PVCCIN_CPU0_VREF")
	)
	(segment
		(start 383.178304 -348.567756)
		(end 383.763012 -347.983048)
		(width 0.254)
		(layer "In11.Cu")
		(net "PVCCIN_CPU0_VREF")
	)
	(segment
		(start 351.919032 -353.29368)
		(end 344.866468 -346.241116)
		(width 0.254)
		(layer "In11.Cu")
		(net "PVCCIN_CPU0_VREF")
	)
	(segment
		(start 350.479106 -345.431364)
		(end 350.479106 -341.079074)
		(width 0.254)
		(layer "In11.Cu")
		(net "PVCCIN_CPU0_VREF")
	)
	(segment
		(start 344.866468 -346.241116)
		(end 344.318844 -346.241116)
		(width 0.254)
		(layer "In11.Cu")
		(net "PVCCIN_CPU0_VREF")
	)
	(segment
		(start 335.815178 -344.11158)
		(end 334.997552 -343.293954)
		(width 0.254)
		(layer "In11.Cu")
		(net "PVCCIN_CPU0_VREF")
	)
	(segment
		(start 350.492822 -348.306136)
		(end 348.962472 -346.775786)
		(width 0.254)
		(layer "In11.Cu")
		(net "PVCCIN_CPU0_VREF")
	)
	(segment
		(start 345.06408 -366.047528)
		(end 347.194632 -366.047528)
		(width 0.254)
		(layer "In11.Cu")
		(net "PVCCIN_CPU0_VREF")
	)
	(segment
		(start 347.738192 -366.591088)
		(end 355.307392 -366.591088)
		(width 0.254)
		(layer "In11.Cu")
		(net "PVCCIN_CPU0_VREF")
	)
	(segment
		(start 375.8057 -341.851742)
		(end 375.6025 -341.648542)
		(width 0.254)
		(layer "In11.Cu")
		(net "PVCCIN_CPU0_VREF")
	)
	(segment
		(start 334.997552 -341.846154)
		(end 334.79994 -341.648542)
		(width 0.254)
		(layer "In11.Cu")
		(net "PVCCIN_CPU0_VREF")
	)
	(segment
		(start 354.76688 -350.284034)
		(end 354.76688 -346.724986)
		(width 0.254)
		(layer "In11.Cu")
		(net "PVCCIN_CPU0_VREF")
	)
	(segment
		(start 355.844094 -349.280988)
		(end 357.874316 -347.250766)
		(width 0.254)
		(layer "In11.Cu")
		(net "PVCCIN_CPU0_VREF")
	)
	(segment
		(start 344.318844 -346.241116)
		(end 342.189308 -344.11158)
		(width 0.254)
		(layer "In11.Cu")
		(net "PVCCIN_CPU0_VREF")
	)
	(segment
		(start 348.962472 -346.775786)
		(end 348.962472 -342.14562)
		(width 0.254)
		(layer "In11.Cu")
		(net "PVCCIN_CPU0_VREF")
	)
	(segment
		(start 342.189308 -344.11158)
		(end 335.815178 -344.11158)
		(width 0.254)
		(layer "In11.Cu")
		(net "PVCCIN_CPU0_VREF")
	)
	(segment
		(start 348.962472 -342.14562)
		(end 347.862398 -341.045546)
		(width 0.254)
		(layer "In11.Cu")
		(net "PVCCIN_CPU0_VREF")
	)
	(segment
		(start 357.874316 -341.868252)
		(end 359.408476 -340.334092)
		(width 0.254)
		(layer "In11.Cu")
		(net "PVCCIN_CPU0_VREF")
	)
	(segment
		(start 334.997552 -343.293954)
		(end 334.997552 -341.846154)
		(width 0.254)
		(layer "In11.Cu")
		(net "PVCCIN_CPU0_VREF")
	)
	(segment
		(start 351.374964 -340.183216)
		(end 351.374964 -338.492338)
		(width 0.254)
		(layer "In11.Cu")
		(net "PVCCIN_CPU0_VREF")
	)
	(segment
		(start 357.71836 -353.29368)
		(end 351.919032 -353.29368)
		(width 0.254)
		(layer "In11.Cu")
		(net "PVCCIN_CPU0_VREF")
	)
	(segment
		(start 367.718086 -339.625178)
		(end 367.718086 -338.514436)
		(width 0.254)
		(layer "In11.Cu")
		(net "PVCCIN_CPU0_VREF")
	)
	(segment
		(start 355.307392 -366.591088)
		(end 355.672898 -366.956594)
		(width 0.254)
		(layer "In11.Cu")
		(net "PVCCIN_CPU0_VREF")
	)
	(segment
		(start 359.408476 -338.365338)
		(end 359.281476 -338.238338)
		(width 0.254)
		(layer "In11.Cu")
		(net "PVCCIN_CPU0_VREF")
	)
	(segment
		(start 358.3178 -348.99092)
		(end 360.821478 -348.99092)
		(width 0.254)
		(layer "In11.Cu")
		(net "PVCCIN_CPU0_VREF")
	)
	(segment
		(start 299.0977 -371.104668)
		(end 340.00694 -371.104668)
		(width 0.254)
		(layer "In11.Cu")
		(net "PVCCIN_CPU0_VREF")
	)
	(segment
		(start 360.821478 -348.99092)
		(end 365.416592 -344.395806)
		(width 0.254)
		(layer "In11.Cu")
		(net "PVCCIN_CPU0_VREF")
	)
	(segment
		(start 352.86188 -367.463832)
		(end 353.16922 -367.771172)
		(width 0.254)
		(layer "In11.Cu")
		(net "PVCCIN_CPU0_VREF")
	)
	(segment
		(start 361.376976 -352.262948)
		(end 367.79073 -352.262948)
		(width 0.254)
		(layer "In11.Cu")
		(net "PVCCIN_CPU0_VREF")
	)
	(segment
		(start 286.351726 -367.212626)
		(end 286.808926 -367.212626)
		(width 0.254)
		(layer "In11.Cu")
		(net "PVCCIN_CPU0_VREF")
	)
	(segment
		(start 351.500948 -346.453206)
		(end 350.479106 -345.431364)
		(width 0.254)
		(layer "In11.Cu")
		(net "PVCCIN_CPU0_VREF")
	)
	(segment
		(start 354.4951 -346.453206)
		(end 351.500948 -346.453206)
		(width 0.254)
		(layer "In11.Cu")
		(net "PVCCIN_CPU0_VREF")
	)
	(segment
		(start 347.194632 -366.047528)
		(end 347.738192 -366.591088)
		(width 0.254)
		(layer "In11.Cu")
		(net "PVCCIN_CPU0_VREF")
	)
	(segment
		(start 309.92572 -373.52351)
		(end 305.964844 -377.484386)
		(width 0.254)
		(layer "In11.Cu")
		(net "PVCCIN_CPU0_VREF")
	)
	(segment
		(start 365.509556 -346.253308)
		(end 374.553734 -346.253308)
		(width 0.254)
		(layer "In11.Cu")
		(net "PVCCIN_CPU0_VREF")
	)
	(segment
		(start 374.553734 -346.253308)
		(end 375.8057 -345.001342)
		(width 0.254)
		(layer "In11.Cu")
		(net "PVCCIN_CPU0_VREF")
	)
	(segment
		(start 353.147122 -348.306136)
		(end 350.492822 -348.306136)
		(width 0.254)
		(layer "In11.Cu")
		(net "PVCCIN_CPU0_VREF")
	)
	(segment
		(start 383.763012 -347.983048)
		(end 383.763012 -347.439234)
		(width 0.254)
		(layer "In11.Cu")
		(net "PVCCIN_CPU0_VREF")
	)
	(segment
		(start 288.479992 -377.484386)
		(end 284.178502 -373.182896)
		(width 0.254)
		(layer "In11.Cu")
		(net "PVCCIN_CPU0_VREF")
	)
	(segment
		(start 380.452884 -348.567756)
		(end 383.178304 -348.567756)
		(width 0.254)
		(layer "In11.Cu")
		(net "PVCCIN_CPU0_VREF")
	)
	(segment
		(start 343.229438 -340.285578)
		(end 343.229438 -338.507324)
		(width 0.254)
		(layer "In11.Cu")
		(net "PVCCIN_CPU0_VREF")
	)
	(segment
		(start 296.497248 -367.274856)
		(end 296.497248 -368.504216)
		(width 0.254)
		(layer "In11.Cu")
		(net "PVCCIN_CPU0_VREF")
	)
	(segment
		(start 284.178502 -373.182896)
		(end 284.178502 -369.38585)
		(width 0.254)
		(layer "In11.Cu")
		(net "PVCCIN_CPU0_VREF")
	)
	(segment
		(start 357.874316 -347.250766)
		(end 357.874316 -341.868252)
		(width 0.254)
		(layer "In11.Cu")
		(net "PVCCIN_CPU0_VREF")
	)
	(segment
		(start 284.178502 -369.38585)
		(end 286.351726 -367.212626)
		(width 0.254)
		(layer "In11.Cu")
		(net "PVCCIN_CPU0_VREF")
	)
	(segment
		(start 353.16922 -367.771172)
		(end 353.16922 -368.137948)
		(width 0.254)
		(layer "In11.Cu")
		(net "PVCCIN_CPU0_VREF")
	)
	(segment
		(start 353.67468 -350.281748)
		(end 353.67468 -348.833694)
		(width 0.254)
		(layer "In11.Cu")
		(net "PVCCIN_CPU0_VREF")
	)
	(segment
		(start 375.8057 -345.001342)
		(end 375.8057 -341.851742)
		(width 0.254)
		(layer "In11.Cu")
		(net "PVCCIN_CPU0_VREF")
	)
	(segment
		(start 347.862398 -341.045546)
		(end 343.989406 -341.045546)
		(width 0.254)
		(layer "In11.Cu")
		(net "PVCCIN_CPU0_VREF")
	)
	(segment
		(start 372.455948 -347.59773)
		(end 379.482858 -347.59773)
		(width 0.254)
		(layer "In11.Cu")
		(net "PVCCIN_CPU0_VREF")
	)
	(segment
		(start 296.497248 -368.504216)
		(end 299.0977 -371.104668)
		(width 0.254)
		(layer "In11.Cu")
		(net "PVCCIN_CPU0_VREF")
	)
	(segment
		(start 379.482858 -347.59773)
		(end 380.452884 -348.567756)
		(width 0.254)
		(layer "In11.Cu")
		(net "PVCCIN_CPU0_VREF")
	)
	(segment
		(start 367.718086 -338.514436)
		(end 367.441988 -338.238338)
		(width 0.254)
		(layer "In11.Cu")
		(net "PVCCIN_CPU0_VREF")
	)
	(segment
		(start 350.479106 -341.079074)
		(end 351.374964 -340.183216)
		(width 0.254)
		(layer "In11.Cu")
		(net "PVCCIN_CPU0_VREF")
	)
	(segment
		(start 351.374964 -338.492338)
		(end 351.120964 -338.238338)
		(width 0.254)
		(layer "In11.Cu")
		(net "PVCCIN_CPU0_VREF")
	)
	(segment
		(start 347.783658 -373.52351)
		(end 309.92572 -373.52351)
		(width 0.254)
		(layer "In11.Cu")
		(net "PVCCIN_CPU0_VREF")
	)
	(segment
		(start 354.76688 -346.724986)
		(end 354.4951 -346.453206)
		(width 0.254)
		(layer "In11.Cu")
		(net "PVCCIN_CPU0_VREF")
	)
	(segment
		(start 331.60208 -349.418148)
		(end 328.588878 -349.418148)
		(width 0.254)
		(layer "In15.Cu")
		(net "PVCCIN_CPU0_VREF")
	)
	(segment
		(start 334.79994 -341.648542)
		(end 334.79994 -346.220288)
		(width 0.254)
		(layer "In15.Cu")
		(net "PVCCIN_CPU0_VREF")
	)
	(segment
		(start 334.79994 -346.220288)
		(end 331.60208 -349.418148)
		(width 0.254)
		(layer "In15.Cu")
		(net "PVCCIN_CPU0_VREF")
	)
	(segment
		(start 328.588878 -349.418148)
		(end 326.669908 -347.499178)
		(width 0.254)
		(layer "In15.Cu")
		(net "PVCCIN_CPU0_VREF")
	)
	(segment
		(start 383.340102 -345.462352)
		(end 383.340102 -345.192096)
		(width 0.2286)
		(layer "F.Cu")
		(net "PVCCIN_CPU0_VOS8")
	)
	(segment
		(start 382.956816 -345.845638)
		(end 383.340102 -345.462352)
		(width 0.2286)
		(layer "F.Cu")
		(net "PVCCIN_CPU0_VOS8")
	)
	(via
		(at 382.956816 -345.845638)
		(size 0.508)
		(drill 0.254)
		(layers "F.Cu" "B.Cu")
		(net "PVCCIN_CPU0_VOS8")
	)
	(segment
		(start 382.956816 -345.410028)
		(end 382.609852 -345.063064)
		(width 0.2286)
		(layer "B.Cu")
		(net "PVCCIN_CPU0_VOS8")
	)
	(segment
		(start 382.956816 -345.845638)
		(end 382.956816 -345.410028)
		(width 0.2286)
		(layer "B.Cu")
		(net "PVCCIN_CPU0_VOS8")
	)
	(segment
		(start 382.609852 -345.063064)
		(end 382.28778 -345.063064)
		(width 0.2286)
		(layer "B.Cu")
		(net "PVCCIN_CPU0_VOS8")
	)
	(segment
		(start 326.246998 -345.522296)
		(end 326.246998 -345.25204)
		(width 0.254)
		(layer "F.Cu")
		(net "PVCCIN_CPU0_VOS7")
	)
	(segment
		(start 325.863712 -345.905582)
		(end 326.246998 -345.522296)
		(width 0.254)
		(layer "F.Cu")
		(net "PVCCIN_CPU0_VOS7")
	)
	(via
		(at 325.863712 -345.905582)
		(size 0.508)
		(drill 0.254)
		(layers "F.Cu" "B.Cu")
		(net "PVCCIN_CPU0_VOS7")
	)
	(segment
		(start 325.332344 -345.374214)
		(end 325.168768 -345.374214)
		(width 0.254)
		(layer "B.Cu")
		(net "PVCCIN_CPU0_VOS7")
	)
	(segment
		(start 325.863712 -345.905582)
		(end 325.332344 -345.374214)
		(width 0.254)
		(layer "B.Cu")
		(net "PVCCIN_CPU0_VOS7")
	)
	(segment
		(start 334.37703 -339.67166)
		(end 334.37703 -339.401404)
		(width 0.254)
		(layer "F.Cu")
		(net "PVCCIN_CPU0_VOS6")
	)
	(segment
		(start 333.993744 -340.054946)
		(end 334.37703 -339.67166)
		(width 0.254)
		(layer "F.Cu")
		(net "PVCCIN_CPU0_VOS6")
	)
	(via
		(at 333.993744 -340.054946)
		(size 0.508)
		(drill 0.254)
		(layers "F.Cu" "B.Cu")
		(net "PVCCIN_CPU0_VOS6")
	)
	(segment
		(start 333.537814 -339.792056)
		(end 333.32928 -339.583522)
		(width 0.2286)
		(layer "B.Cu")
		(net "PVCCIN_CPU0_VOS6")
	)
	(segment
		(start 333.730854 -339.792056)
		(end 333.537814 -339.792056)
		(width 0.2286)
		(layer "B.Cu")
		(net "PVCCIN_CPU0_VOS6")
	)
	(segment
		(start 333.993744 -340.054946)
		(end 333.730854 -339.792056)
		(width 0.2286)
		(layer "B.Cu")
		(net "PVCCIN_CPU0_VOS6")
	)
	(segment
		(start 374.796304 -340.054946)
		(end 375.17959 -339.67166)
		(width 0.2286)
		(layer "F.Cu")
		(net "PVCCIN_CPU0_VOS5")
	)
	(segment
		(start 375.17959 -339.67166)
		(end 375.17959 -339.401404)
		(width 0.2286)
		(layer "F.Cu")
		(net "PVCCIN_CPU0_VOS5")
	)
	(via
		(at 374.796304 -340.054946)
		(size 0.508)
		(drill 0.254)
		(layers "F.Cu" "B.Cu")
		(net "PVCCIN_CPU0_VOS5")
	)
	(segment
		(start 374.796304 -340.054946)
		(end 374.796304 -339.72881)
		(width 0.2286)
		(layer "B.Cu")
		(net "PVCCIN_CPU0_VOS5")
	)
	(segment
		(start 374.796304 -339.72881)
		(end 374.270016 -339.202522)
		(width 0.2286)
		(layer "B.Cu")
		(net "PVCCIN_CPU0_VOS5")
	)
	(segment
		(start 374.270016 -339.202522)
		(end 374.00484 -339.202522)
		(width 0.2286)
		(layer "B.Cu")
		(net "PVCCIN_CPU0_VOS5")
	)
	(segment
		(start 367.019078 -336.261456)
		(end 367.019078 -335.9912)
		(width 0.2286)
		(layer "F.Cu")
		(net "PVCCIN_CPU0_VOS4")
	)
	(segment
		(start 366.635792 -336.644742)
		(end 367.019078 -336.261456)
		(width 0.2286)
		(layer "F.Cu")
		(net "PVCCIN_CPU0_VOS4")
	)
	(via
		(at 366.635792 -336.644742)
		(size 0.508)
		(drill 0.254)
		(layers "F.Cu" "B.Cu")
		(net "PVCCIN_CPU0_VOS4")
	)
	(segment
		(start 366.635792 -336.644742)
		(end 366.635792 -337.20151)
		(width 0.2032)
		(layer "B.Cu")
		(net "PVCCIN_CPU0_VOS4")
	)
	(segment
		(start 366.850422 -337.41614)
		(end 366.850422 -337.899248)
		(width 0.2032)
		(layer "B.Cu")
		(net "PVCCIN_CPU0_VOS4")
	)
	(segment
		(start 366.635792 -337.20151)
		(end 366.850422 -337.41614)
		(width 0.2032)
		(layer "B.Cu")
		(net "PVCCIN_CPU0_VOS4")
	)
	(segment
		(start 358.47528 -336.644742)
		(end 358.858566 -336.261456)
		(width 0.2286)
		(layer "F.Cu")
		(net "PVCCIN_CPU0_VOS3")
	)
	(segment
		(start 358.858566 -336.261456)
		(end 358.858566 -335.9912)
		(width 0.2286)
		(layer "F.Cu")
		(net "PVCCIN_CPU0_VOS3")
	)
	(via
		(at 358.47528 -336.644742)
		(size 0.508)
		(drill 0.254)
		(layers "F.Cu" "B.Cu")
		(net "PVCCIN_CPU0_VOS3")
	)
	(segment
		(start 358.47528 -336.644742)
		(end 358.47528 -337.592162)
		(width 0.2286)
		(layer "B.Cu")
		(net "PVCCIN_CPU0_VOS3")
	)
	(segment
		(start 358.728264 -337.845146)
		(end 358.728264 -337.860386)
		(width 0.2286)
		(layer "B.Cu")
		(net "PVCCIN_CPU0_VOS3")
	)
	(segment
		(start 358.47528 -337.592162)
		(end 358.728264 -337.845146)
		(width 0.2286)
		(layer "B.Cu")
		(net "PVCCIN_CPU0_VOS3")
	)
	(segment
		(start 350.314768 -336.644742)
		(end 350.698054 -336.261456)
		(width 0.2286)
		(layer "F.Cu")
		(net "PVCCIN_CPU0_VOS2")
	)
	(segment
		(start 350.698054 -336.261456)
		(end 350.698054 -335.9912)
		(width 0.2286)
		(layer "F.Cu")
		(net "PVCCIN_CPU0_VOS2")
	)
	(via
		(at 350.314768 -336.644742)
		(size 0.508)
		(drill 0.254)
		(layers "F.Cu" "B.Cu")
		(net "PVCCIN_CPU0_VOS2")
	)
	(segment
		(start 350.314768 -337.14182)
		(end 350.558862 -337.385914)
		(width 0.2286)
		(layer "B.Cu")
		(net "PVCCIN_CPU0_VOS2")
	)
	(segment
		(start 350.314768 -336.644742)
		(end 350.314768 -337.14182)
		(width 0.2286)
		(layer "B.Cu")
		(net "PVCCIN_CPU0_VOS2")
	)
	(segment
		(start 350.558862 -337.385914)
		(end 350.558862 -337.853782)
		(width 0.2286)
		(layer "B.Cu")
		(net "PVCCIN_CPU0_VOS2")
	)
	(segment
		(start 342.537542 -336.332576)
		(end 342.537542 -335.9912)
		(width 0.2286)
		(layer "F.Cu")
		(net "PVCCIN_CPU0_VOS1")
	)
	(segment
		(start 342.238838 -336.63128)
		(end 342.537542 -336.332576)
		(width 0.2286)
		(layer "F.Cu")
		(net "PVCCIN_CPU0_VOS1")
	)
	(via
		(at 342.238838 -336.63128)
		(size 0.508)
		(drill 0.254)
		(layers "F.Cu" "B.Cu")
		(net "PVCCIN_CPU0_VOS1")
	)
	(segment
		(start 342.238838 -336.63128)
		(end 342.238838 -336.508344)
		(width 0.2286)
		(layer "B.Cu")
		(net "PVCCIN_CPU0_VOS1")
	)
	(segment
		(start 342.238838 -336.508344)
		(end 341.88019 -336.149696)
		(width 0.2286)
		(layer "B.Cu")
		(net "PVCCIN_CPU0_VOS1")
	)
	(segment
		(start 341.7824 -336.149696)
		(end 341.511128 -335.878424)
		(width 0.2286)
		(layer "B.Cu")
		(net "PVCCIN_CPU0_VOS1")
	)
	(segment
		(start 341.88019 -336.149696)
		(end 341.7824 -336.149696)
		(width 0.2286)
		(layer "B.Cu")
		(net "PVCCIN_CPU0_VOS1")
	)
	(segment
		(start 362.246418 -360.83875)
		(end 362.246418 -361.024678)
		(width 0.1778)
		(layer "F.Cu")
		(net "PVCCIN_CPU0_VIN_CSNIN")
	)
	(segment
		(start 361.116372 -361.544616)
		(end 360.677714 -361.544616)
		(width 0.1778)
		(layer "F.Cu")
		(net "PVCCIN_CPU0_VIN_CSNIN")
	)
	(segment
		(start 360.326432 -361.193334)
		(end 360.326432 -360.711496)
		(width 0.1778)
		(layer "F.Cu")
		(net "PVCCIN_CPU0_VIN_CSNIN")
	)
	(segment
		(start 362.246418 -361.024678)
		(end 362.092748 -361.178348)
		(width 0.1778)
		(layer "F.Cu")
		(net "PVCCIN_CPU0_VIN_CSNIN")
	)
	(segment
		(start 360.677714 -361.544616)
		(end 360.326432 -361.193334)
		(width 0.1778)
		(layer "F.Cu")
		(net "PVCCIN_CPU0_VIN_CSNIN")
	)
	(segment
		(start 360.326432 -360.711496)
		(end 359.86339 -360.248454)
		(width 0.1778)
		(layer "F.Cu")
		(net "PVCCIN_CPU0_VIN_CSNIN")
	)
	(segment
		(start 361.48264 -361.178348)
		(end 361.116372 -361.544616)
		(width 0.1778)
		(layer "F.Cu")
		(net "PVCCIN_CPU0_VIN_CSNIN")
	)
	(segment
		(start 362.092748 -361.178348)
		(end 361.48264 -361.178348)
		(width 0.1778)
		(layer "F.Cu")
		(net "PVCCIN_CPU0_VIN_CSNIN")
	)
	(segment
		(start 359.86339 -360.248454)
		(end 359.393236 -360.248454)
		(width 0.1778)
		(layer "F.Cu")
		(net "PVCCIN_CPU0_VIN_CSNIN")
	)
	(via
		(at 360.677714 -361.544616)
		(size 0.762)
		(drill 0.254)
		(layers "F.Cu" "B.Cu")
		(net "PVCCIN_CPU0_VIN_CSNIN")
	)
	(segment
		(start 361.235244 -361.703366)
		(end 360.836464 -361.703366)
		(width 0.254)
		(layer "B.Cu")
		(net "PVCCIN_CPU0_VIN_CSNIN")
	)
	(segment
		(start 360.65841 -361.544616)
		(end 359.96118 -360.847386)
		(width 0.254)
		(layer "B.Cu")
		(net "PVCCIN_CPU0_VIN_CSNIN")
	)
	(segment
		(start 361.291124 -361.759246)
		(end 361.235244 -361.703366)
		(width 0.254)
		(layer "B.Cu")
		(net "PVCCIN_CPU0_VIN_CSNIN")
	)
	(segment
		(start 360.677714 -361.544616)
		(end 360.65841 -361.544616)
		(width 0.254)
		(layer "B.Cu")
		(net "PVCCIN_CPU0_VIN_CSNIN")
	)
	(segment
		(start 360.836464 -361.703366)
		(end 360.677714 -361.544616)
		(width 0.254)
		(layer "B.Cu")
		(net "PVCCIN_CPU0_VIN_CSNIN")
	)
	(segment
		(start 382.165352 -344.377264)
		(end 382.165352 -344.993214)
		(width 0.2032)
		(layer "F.Cu")
		(net "PVCCIN_CPU0_VDD8")
	)
	(segment
		(start 385.474464 -346.60459)
		(end 385.550156 -346.528898)
		(width 0.2286)
		(layer "F.Cu")
		(net "PVCCIN_CPU0_VDD8")
	)
	(segment
		(start 385.550156 -346.528898)
		(end 385.550156 -345.816936)
		(width 0.2286)
		(layer "F.Cu")
		(net "PVCCIN_CPU0_VDD8")
	)
	(segment
		(start 382.165352 -344.993214)
		(end 382.250696 -344.993214)
		(width 0.2032)
		(layer "F.Cu")
		(net "PVCCIN_CPU0_VDD8")
	)
	(segment
		(start 382.250696 -344.993214)
		(end 382.95199 -344.29192)
		(width 0.2032)
		(layer "F.Cu")
		(net "PVCCIN_CPU0_VDD8")
	)
	(segment
		(start 382.95199 -344.29192)
		(end 383.340102 -344.29192)
		(width 0.2032)
		(layer "F.Cu")
		(net "PVCCIN_CPU0_VDD8")
	)
	(via
		(at 382.165352 -344.377264)
		(size 0.508)
		(drill 0.254)
		(layers "F.Cu" "B.Cu")
		(net "PVCCIN_CPU0_VDD8")
	)
	(via
		(at 385.474464 -346.60459)
		(size 0.508)
		(drill 0.254)
		(layers "F.Cu" "B.Cu")
		(net "PVCCIN_CPU0_VDD8")
	)
	(via
		(at 383.884678 -345.74353)
		(size 0.6604)
		(drill 0.3302)
		(layers "F.Cu" "B.Cu")
		(net "PVCCIN_CPU0_VDD8")
	)
	(segment
		(start 382.165352 -344.377264)
		(end 383.37998 -344.377264)
		(width 0.2286)
		(layer "B.Cu")
		(net "PVCCIN_CPU0_VDD8")
	)
	(segment
		(start 385.474464 -346.60459)
		(end 385.01193 -346.142056)
		(width 0.2286)
		(layer "B.Cu")
		(net "PVCCIN_CPU0_VDD8")
	)
	(segment
		(start 383.884678 -345.74353)
		(end 383.429256 -345.288108)
		(width 0.2286)
		(layer "B.Cu")
		(net "PVCCIN_CPU0_VDD8")
	)
	(segment
		(start 383.37998 -344.377264)
		(end 383.429256 -344.327988)
		(width 0.2286)
		(layer "B.Cu")
		(net "PVCCIN_CPU0_VDD8")
	)
	(segment
		(start 384.283204 -346.142056)
		(end 383.884678 -345.74353)
		(width 0.2286)
		(layer "B.Cu")
		(net "PVCCIN_CPU0_VDD8")
	)
	(segment
		(start 383.429256 -345.288108)
		(end 383.429256 -344.327988)
		(width 0.2286)
		(layer "B.Cu")
		(net "PVCCIN_CPU0_VDD8")
	)
	(segment
		(start 385.01193 -346.142056)
		(end 384.283204 -346.142056)
		(width 0.2286)
		(layer "B.Cu")
		(net "PVCCIN_CPU0_VDD8")
	)
	(segment
		(start 328.38136 -346.664534)
		(end 328.457052 -346.588842)
		(width 0.2286)
		(layer "F.Cu")
		(net "PVCCIN_CPU0_VDD7")
	)
	(segment
		(start 324.950836 -344.446606)
		(end 324.950836 -344.935556)
		(width 0.2286)
		(layer "F.Cu")
		(net "PVCCIN_CPU0_VDD7")
	)
	(segment
		(start 325.757032 -344.351864)
		(end 325.077836 -345.03106)
		(width 0.2286)
		(layer "F.Cu")
		(net "PVCCIN_CPU0_VDD7")
	)
	(segment
		(start 328.457052 -346.588842)
		(end 328.457052 -345.87688)
		(width 0.2286)
		(layer "F.Cu")
		(net "PVCCIN_CPU0_VDD7")
	)
	(segment
		(start 325.077836 -345.03106)
		(end 325.077836 -345.062556)
		(width 0.2286)
		(layer "F.Cu")
		(net "PVCCIN_CPU0_VDD7")
	)
	(segment
		(start 326.246998 -344.351864)
		(end 325.757032 -344.351864)
		(width 0.2286)
		(layer "F.Cu")
		(net "PVCCIN_CPU0_VDD7")
	)
	(segment
		(start 324.950836 -344.935556)
		(end 325.077836 -345.062556)
		(width 0.2286)
		(layer "F.Cu")
		(net "PVCCIN_CPU0_VDD7")
	)
	(via
		(at 324.950836 -344.446606)
		(size 0.508)
		(drill 0.254)
		(layers "F.Cu" "B.Cu")
		(net "PVCCIN_CPU0_VDD7")
	)
	(via
		(at 328.38136 -346.664534)
		(size 0.508)
		(drill 0.254)
		(layers "F.Cu" "B.Cu")
		(net "PVCCIN_CPU0_VDD7")
	)
	(via
		(at 327.152 -345.986354)
		(size 0.6604)
		(drill 0.3302)
		(layers "F.Cu" "B.Cu")
		(net "PVCCIN_CPU0_VDD7")
	)
	(segment
		(start 325.069454 -344.327988)
		(end 325.707502 -344.327988)
		(width 0.2032)
		(layer "B.Cu")
		(net "PVCCIN_CPU0_VDD7")
	)
	(segment
		(start 325.707502 -344.327988)
		(end 325.707502 -344.743278)
		(width 0.2286)
		(layer "B.Cu")
		(net "PVCCIN_CPU0_VDD7")
	)
	(segment
		(start 326.950578 -345.986354)
		(end 327.152 -345.986354)
		(width 0.2286)
		(layer "B.Cu")
		(net "PVCCIN_CPU0_VDD7")
	)
	(segment
		(start 328.068178 -346.321888)
		(end 328.068178 -346.351352)
		(width 0.2286)
		(layer "B.Cu")
		(net "PVCCIN_CPU0_VDD7")
	)
	(segment
		(start 328.068178 -346.351352)
		(end 328.38136 -346.664534)
		(width 0.2286)
		(layer "B.Cu")
		(net "PVCCIN_CPU0_VDD7")
	)
	(segment
		(start 327.654666 -346.321888)
		(end 328.068178 -346.321888)
		(width 0.2286)
		(layer "B.Cu")
		(net "PVCCIN_CPU0_VDD7")
	)
	(segment
		(start 327.319132 -345.986354)
		(end 327.654666 -346.321888)
		(width 0.2286)
		(layer "B.Cu")
		(net "PVCCIN_CPU0_VDD7")
	)
	(segment
		(start 327.152 -345.986354)
		(end 327.319132 -345.986354)
		(width 0.2286)
		(layer "B.Cu")
		(net "PVCCIN_CPU0_VDD7")
	)
	(segment
		(start 325.707502 -344.743278)
		(end 326.950578 -345.986354)
		(width 0.2286)
		(layer "B.Cu")
		(net "PVCCIN_CPU0_VDD7")
	)
	(segment
		(start 324.950836 -344.446606)
		(end 325.069454 -344.327988)
		(width 0.2032)
		(layer "B.Cu")
		(net "PVCCIN_CPU0_VDD7")
	)
	(segment
		(start 333.20228 -338.586572)
		(end 333.20228 -339.202522)
		(width 0.2032)
		(layer "F.Cu")
		(net "PVCCIN_CPU0_VDD6")
	)
	(segment
		(start 334.37703 -338.501228)
		(end 333.982314 -338.501228)
		(width 0.2032)
		(layer "F.Cu")
		(net "PVCCIN_CPU0_VDD6")
	)
	(segment
		(start 336.511392 -340.813898)
		(end 336.587084 -340.738206)
		(width 0.2286)
		(layer "F.Cu")
		(net "PVCCIN_CPU0_VDD6")
	)
	(segment
		(start 333.28102 -339.202522)
		(end 333.20228 -339.202522)
		(width 0.2032)
		(layer "F.Cu")
		(net "PVCCIN_CPU0_VDD6")
	)
	(segment
		(start 336.587084 -340.738206)
		(end 336.587084 -340.026244)
		(width 0.2286)
		(layer "F.Cu")
		(net "PVCCIN_CPU0_VDD6")
	)
	(segment
		(start 333.982314 -338.501228)
		(end 333.28102 -339.202522)
		(width 0.2032)
		(layer "F.Cu")
		(net "PVCCIN_CPU0_VDD6")
	)
	(via
		(at 333.20228 -338.586572)
		(size 0.508)
		(drill 0.254)
		(layers "F.Cu" "B.Cu")
		(net "PVCCIN_CPU0_VDD6")
	)
	(via
		(at 336.511392 -340.813898)
		(size 0.508)
		(drill 0.254)
		(layers "F.Cu" "B.Cu")
		(net "PVCCIN_CPU0_VDD6")
	)
	(via
		(at 335.479644 -340.195662)
		(size 0.6604)
		(drill 0.3302)
		(layers "F.Cu" "B.Cu")
		(net "PVCCIN_CPU0_VDD6")
	)
	(segment
		(start 333.251556 -338.537296)
		(end 333.868014 -338.537296)
		(width 0.2032)
		(layer "B.Cu")
		(net "PVCCIN_CPU0_VDD6")
	)
	(segment
		(start 335.815178 -340.531196)
		(end 335.479644 -340.195662)
		(width 0.2286)
		(layer "B.Cu")
		(net "PVCCIN_CPU0_VDD6")
	)
	(segment
		(start 333.20228 -338.586572)
		(end 333.251556 -338.537296)
		(width 0.2032)
		(layer "B.Cu")
		(net "PVCCIN_CPU0_VDD6")
	)
	(segment
		(start 333.868014 -338.952586)
		(end 333.868014 -338.537296)
		(width 0.2286)
		(layer "B.Cu")
		(net "PVCCIN_CPU0_VDD6")
	)
	(segment
		(start 336.22869 -340.531196)
		(end 335.815178 -340.531196)
		(width 0.2286)
		(layer "B.Cu")
		(net "PVCCIN_CPU0_VDD6")
	)
	(segment
		(start 336.511392 -340.813898)
		(end 336.22869 -340.531196)
		(width 0.2286)
		(layer "B.Cu")
		(net "PVCCIN_CPU0_VDD6")
	)
	(segment
		(start 335.479644 -340.195662)
		(end 335.11109 -340.195662)
		(width 0.2286)
		(layer "B.Cu")
		(net "PVCCIN_CPU0_VDD6")
	)
	(segment
		(start 335.11109 -340.195662)
		(end 333.868014 -338.952586)
		(width 0.2286)
		(layer "B.Cu")
		(net "PVCCIN_CPU0_VDD6")
	)
	(segment
		(start 377.389644 -340.738206)
		(end 377.389644 -340.026244)
		(width 0.2286)
		(layer "F.Cu")
		(net "PVCCIN_CPU0_VDD5")
	)
	(segment
		(start 374.791478 -338.501228)
		(end 375.17959 -338.501228)
		(width 0.2032)
		(layer "F.Cu")
		(net "PVCCIN_CPU0_VDD5")
	)
	(segment
		(start 374.090184 -339.202522)
		(end 374.791478 -338.501228)
		(width 0.2032)
		(layer "F.Cu")
		(net "PVCCIN_CPU0_VDD5")
	)
	(segment
		(start 374.00484 -338.592922)
		(end 374.00484 -339.202522)
		(width 0.2032)
		(layer "F.Cu")
		(net "PVCCIN_CPU0_VDD5")
	)
	(segment
		(start 374.00484 -339.202522)
		(end 374.090184 -339.202522)
		(width 0.2032)
		(layer "F.Cu")
		(net "PVCCIN_CPU0_VDD5")
	)
	(segment
		(start 377.313952 -340.813898)
		(end 377.389644 -340.738206)
		(width 0.2286)
		(layer "F.Cu")
		(net "PVCCIN_CPU0_VDD5")
	)
	(via
		(at 374.00484 -338.592922)
		(size 0.508)
		(drill 0.254)
		(layers "F.Cu" "B.Cu")
		(net "PVCCIN_CPU0_VDD5")
	)
	(via
		(at 377.313952 -340.813898)
		(size 0.508)
		(drill 0.254)
		(layers "F.Cu" "B.Cu")
		(net "PVCCIN_CPU0_VDD5")
	)
	(via
		(at 376.00128 -340.044786)
		(size 0.6604)
		(drill 0.3302)
		(layers "F.Cu" "B.Cu")
		(net "PVCCIN_CPU0_VDD5")
	)
	(segment
		(start 374.09882 -338.498942)
		(end 375.197116 -338.498942)
		(width 0.2286)
		(layer "B.Cu")
		(net "PVCCIN_CPU0_VDD5")
	)
	(segment
		(start 376.37593 -340.419436)
		(end 376.00128 -340.044786)
		(width 0.2286)
		(layer "B.Cu")
		(net "PVCCIN_CPU0_VDD5")
	)
	(segment
		(start 374.00484 -338.592922)
		(end 374.09882 -338.498942)
		(width 0.2286)
		(layer "B.Cu")
		(net "PVCCIN_CPU0_VDD5")
	)
	(segment
		(start 377.313952 -340.813898)
		(end 376.91949 -340.419436)
		(width 0.2286)
		(layer "B.Cu")
		(net "PVCCIN_CPU0_VDD5")
	)
	(segment
		(start 375.197116 -339.240622)
		(end 375.197116 -338.498942)
		(width 0.2286)
		(layer "B.Cu")
		(net "PVCCIN_CPU0_VDD5")
	)
	(segment
		(start 376.00128 -340.044786)
		(end 375.197116 -339.240622)
		(width 0.2286)
		(layer "B.Cu")
		(net "PVCCIN_CPU0_VDD5")
	)
	(segment
		(start 376.91949 -340.419436)
		(end 376.37593 -340.419436)
		(width 0.2286)
		(layer "B.Cu")
		(net "PVCCIN_CPU0_VDD5")
	)
	(segment
		(start 369.15344 -337.403694)
		(end 369.229132 -337.328002)
		(width 0.2286)
		(layer "F.Cu")
		(net "PVCCIN_CPU0_VDD4")
	)
	(segment
		(start 369.229132 -337.328002)
		(end 369.229132 -336.61604)
		(width 0.2286)
		(layer "F.Cu")
		(net "PVCCIN_CPU0_VDD4")
	)
	(segment
		(start 366.630966 -335.091024)
		(end 367.019078 -335.091024)
		(width 0.2032)
		(layer "F.Cu")
		(net "PVCCIN_CPU0_VDD4")
	)
	(segment
		(start 365.844328 -335.176368)
		(end 365.844328 -335.792318)
		(width 0.2032)
		(layer "F.Cu")
		(net "PVCCIN_CPU0_VDD4")
	)
	(segment
		(start 365.844328 -335.792318)
		(end 365.929672 -335.792318)
		(width 0.2032)
		(layer "F.Cu")
		(net "PVCCIN_CPU0_VDD4")
	)
	(segment
		(start 365.929672 -335.792318)
		(end 366.630966 -335.091024)
		(width 0.2032)
		(layer "F.Cu")
		(net "PVCCIN_CPU0_VDD4")
	)
	(via
		(at 367.940844 -336.65033)
		(size 0.6604)
		(drill 0.3302)
		(layers "F.Cu" "B.Cu")
		(net "PVCCIN_CPU0_VDD4")
	)
	(via
		(at 369.15344 -337.403694)
		(size 0.508)
		(drill 0.254)
		(layers "F.Cu" "B.Cu")
		(net "PVCCIN_CPU0_VDD4")
	)
	(via
		(at 365.844328 -335.176368)
		(size 0.508)
		(drill 0.254)
		(layers "F.Cu" "B.Cu")
		(net "PVCCIN_CPU0_VDD4")
	)
	(segment
		(start 368.783362 -337.033616)
		(end 369.15344 -337.403694)
		(width 0.2286)
		(layer "B.Cu")
		(net "PVCCIN_CPU0_VDD4")
	)
	(segment
		(start 368.32413 -337.033616)
		(end 368.783362 -337.033616)
		(width 0.2286)
		(layer "B.Cu")
		(net "PVCCIN_CPU0_VDD4")
	)
	(segment
		(start 365.927132 -335.093564)
		(end 367.012474 -335.093564)
		(width 0.2286)
		(layer "B.Cu")
		(net "PVCCIN_CPU0_VDD4")
	)
	(segment
		(start 365.844328 -335.176368)
		(end 365.927132 -335.093564)
		(width 0.2286)
		(layer "B.Cu")
		(net "PVCCIN_CPU0_VDD4")
	)
	(segment
		(start 367.012474 -335.093564)
		(end 367.012474 -335.72196)
		(width 0.2286)
		(layer "B.Cu")
		(net "PVCCIN_CPU0_VDD4")
	)
	(segment
		(start 367.940844 -336.65033)
		(end 368.32413 -337.033616)
		(width 0.2286)
		(layer "B.Cu")
		(net "PVCCIN_CPU0_VDD4")
	)
	(segment
		(start 367.012474 -335.72196)
		(end 367.940844 -336.65033)
		(width 0.2286)
		(layer "B.Cu")
		(net "PVCCIN_CPU0_VDD4")
	)
	(segment
		(start 357.76916 -335.792318)
		(end 358.470454 -335.091024)
		(width 0.2032)
		(layer "F.Cu")
		(net "PVCCIN_CPU0_VDD3")
	)
	(segment
		(start 361.06862 -337.328002)
		(end 361.06862 -336.61604)
		(width 0.2286)
		(layer "F.Cu")
		(net "PVCCIN_CPU0_VDD3")
	)
	(segment
		(start 358.470454 -335.091024)
		(end 358.858566 -335.091024)
		(width 0.2032)
		(layer "F.Cu")
		(net "PVCCIN_CPU0_VDD3")
	)
	(segment
		(start 360.992928 -337.403694)
		(end 361.06862 -337.328002)
		(width 0.2286)
		(layer "F.Cu")
		(net "PVCCIN_CPU0_VDD3")
	)
	(segment
		(start 357.683816 -335.792318)
		(end 357.76916 -335.792318)
		(width 0.2032)
		(layer "F.Cu")
		(net "PVCCIN_CPU0_VDD3")
	)
	(segment
		(start 357.683816 -335.176368)
		(end 357.683816 -335.792318)
		(width 0.2032)
		(layer "F.Cu")
		(net "PVCCIN_CPU0_VDD3")
	)
	(via
		(at 360.992928 -337.403694)
		(size 0.508)
		(drill 0.254)
		(layers "F.Cu" "B.Cu")
		(net "PVCCIN_CPU0_VDD3")
	)
	(via
		(at 357.683816 -335.176368)
		(size 0.508)
		(drill 0.254)
		(layers "F.Cu" "B.Cu")
		(net "PVCCIN_CPU0_VDD3")
	)
	(via
		(at 360.17962 -336.785458)
		(size 0.6604)
		(drill 0.3302)
		(layers "F.Cu" "B.Cu")
		(net "PVCCIN_CPU0_VDD3")
	)
	(segment
		(start 359.079038 -335.320386)
		(end 359.079038 -336.102198)
		(width 0.2286)
		(layer "B.Cu")
		(net "PVCCIN_CPU0_VDD3")
	)
	(segment
		(start 360.17962 -336.785458)
		(end 360.374692 -336.785458)
		(width 0.2286)
		(layer "B.Cu")
		(net "PVCCIN_CPU0_VDD3")
	)
	(segment
		(start 359.762298 -336.785458)
		(end 360.17962 -336.785458)
		(width 0.2286)
		(layer "B.Cu")
		(net "PVCCIN_CPU0_VDD3")
	)
	(segment
		(start 360.374692 -336.785458)
		(end 360.992928 -337.403694)
		(width 0.2286)
		(layer "B.Cu")
		(net "PVCCIN_CPU0_VDD3")
	)
	(segment
		(start 357.756968 -335.103216)
		(end 358.861868 -335.103216)
		(width 0.2286)
		(layer "B.Cu")
		(net "PVCCIN_CPU0_VDD3")
	)
	(segment
		(start 358.861868 -335.103216)
		(end 359.079038 -335.320386)
		(width 0.2286)
		(layer "B.Cu")
		(net "PVCCIN_CPU0_VDD3")
	)
	(segment
		(start 357.683816 -335.176368)
		(end 357.756968 -335.103216)
		(width 0.2286)
		(layer "B.Cu")
		(net "PVCCIN_CPU0_VDD3")
	)
	(segment
		(start 359.079038 -336.102198)
		(end 359.762298 -336.785458)
		(width 0.2286)
		(layer "B.Cu")
		(net "PVCCIN_CPU0_VDD3")
	)
	(segment
		(start 349.608648 -335.792318)
		(end 349.523304 -335.792318)
		(width 0.2032)
		(layer "F.Cu")
		(net "PVCCIN_CPU0_VDD2")
	)
	(segment
		(start 352.832416 -337.403694)
		(end 352.908108 -337.328002)
		(width 0.2286)
		(layer "F.Cu")
		(net "PVCCIN_CPU0_VDD2")
	)
	(segment
		(start 350.309942 -335.091024)
		(end 349.608648 -335.792318)
		(width 0.2032)
		(layer "F.Cu")
		(net "PVCCIN_CPU0_VDD2")
	)
	(segment
		(start 349.523304 -335.176368)
		(end 349.523304 -335.792318)
		(width 0.2032)
		(layer "F.Cu")
		(net "PVCCIN_CPU0_VDD2")
	)
	(segment
		(start 350.698054 -335.091024)
		(end 350.309942 -335.091024)
		(width 0.2032)
		(layer "F.Cu")
		(net "PVCCIN_CPU0_VDD2")
	)
	(segment
		(start 352.908108 -337.328002)
		(end 352.908108 -336.61604)
		(width 0.2286)
		(layer "F.Cu")
		(net "PVCCIN_CPU0_VDD2")
	)
	(via
		(at 351.698052 -336.681064)
		(size 0.6604)
		(drill 0.3302)
		(layers "F.Cu" "B.Cu")
		(net "PVCCIN_CPU0_VDD2")
	)
	(via
		(at 349.523304 -335.176368)
		(size 0.508)
		(drill 0.254)
		(layers "F.Cu" "B.Cu")
		(net "PVCCIN_CPU0_VDD2")
	)
	(via
		(at 352.832416 -337.403694)
		(size 0.508)
		(drill 0.254)
		(layers "F.Cu" "B.Cu")
		(net "PVCCIN_CPU0_VDD2")
	)
	(segment
		(start 352.485198 -337.056476)
		(end 352.832416 -337.403694)
		(width 0.2286)
		(layer "B.Cu")
		(net "PVCCIN_CPU0_VDD2")
	)
	(segment
		(start 352.073464 -337.056476)
		(end 352.485198 -337.056476)
		(width 0.2286)
		(layer "B.Cu")
		(net "PVCCIN_CPU0_VDD2")
	)
	(segment
		(start 350.849438 -335.245202)
		(end 350.849438 -335.83245)
		(width 0.2286)
		(layer "B.Cu")
		(net "PVCCIN_CPU0_VDD2")
	)
	(segment
		(start 350.849438 -335.83245)
		(end 351.698052 -336.681064)
		(width 0.2286)
		(layer "B.Cu")
		(net "PVCCIN_CPU0_VDD2")
	)
	(segment
		(start 351.698052 -336.681064)
		(end 352.073464 -337.056476)
		(width 0.2286)
		(layer "B.Cu")
		(net "PVCCIN_CPU0_VDD2")
	)
	(segment
		(start 349.523304 -335.176368)
		(end 349.592138 -335.245202)
		(width 0.2286)
		(layer "B.Cu")
		(net "PVCCIN_CPU0_VDD2")
	)
	(segment
		(start 349.592138 -335.245202)
		(end 350.849438 -335.245202)
		(width 0.2286)
		(layer "B.Cu")
		(net "PVCCIN_CPU0_VDD2")
	)
	(segment
		(start 341.362792 -335.176368)
		(end 341.362792 -335.792318)
		(width 0.2032)
		(layer "F.Cu")
		(net "PVCCIN_CPU0_VDD1")
	)
	(segment
		(start 342.139778 -335.091024)
		(end 341.438484 -335.792318)
		(width 0.2032)
		(layer "F.Cu")
		(net "PVCCIN_CPU0_VDD1")
	)
	(segment
		(start 344.671904 -337.403694)
		(end 344.747596 -337.328002)
		(width 0.2286)
		(layer "F.Cu")
		(net "PVCCIN_CPU0_VDD1")
	)
	(segment
		(start 344.747596 -337.328002)
		(end 344.747596 -336.61604)
		(width 0.2286)
		(layer "F.Cu")
		(net "PVCCIN_CPU0_VDD1")
	)
	(segment
		(start 341.438484 -335.792318)
		(end 341.362792 -335.792318)
		(width 0.2032)
		(layer "F.Cu")
		(net "PVCCIN_CPU0_VDD1")
	)
	(segment
		(start 342.537542 -335.091024)
		(end 342.139778 -335.091024)
		(width 0.2032)
		(layer "F.Cu")
		(net "PVCCIN_CPU0_VDD1")
	)
	(via
		(at 343.294716 -336.700876)
		(size 0.6604)
		(drill 0.3302)
		(layers "F.Cu" "B.Cu")
		(net "PVCCIN_CPU0_VDD1")
	)
	(via
		(at 344.671904 -337.403694)
		(size 0.508)
		(drill 0.254)
		(layers "F.Cu" "B.Cu")
		(net "PVCCIN_CPU0_VDD1")
	)
	(via
		(at 341.362792 -335.176368)
		(size 0.508)
		(drill 0.254)
		(layers "F.Cu" "B.Cu")
		(net "PVCCIN_CPU0_VDD1")
	)
	(segment
		(start 343.294716 -336.700876)
		(end 342.536526 -335.942686)
		(width 0.2286)
		(layer "B.Cu")
		(net "PVCCIN_CPU0_VDD1")
	)
	(segment
		(start 344.671904 -337.403694)
		(end 344.053668 -336.785458)
		(width 0.2286)
		(layer "B.Cu")
		(net "PVCCIN_CPU0_VDD1")
	)
	(segment
		(start 342.536526 -335.942686)
		(end 342.536526 -335.152492)
		(width 0.2286)
		(layer "B.Cu")
		(net "PVCCIN_CPU0_VDD1")
	)
	(segment
		(start 344.053668 -336.785458)
		(end 343.379298 -336.785458)
		(width 0.2286)
		(layer "B.Cu")
		(net "PVCCIN_CPU0_VDD1")
	)
	(segment
		(start 341.386668 -335.152492)
		(end 342.536526 -335.152492)
		(width 0.2286)
		(layer "B.Cu")
		(net "PVCCIN_CPU0_VDD1")
	)
	(segment
		(start 341.362792 -335.176368)
		(end 341.386668 -335.152492)
		(width 0.2286)
		(layer "B.Cu")
		(net "PVCCIN_CPU0_VDD1")
	)
	(segment
		(start 343.379298 -336.785458)
		(end 343.294716 -336.700876)
		(width 0.2286)
		(layer "B.Cu")
		(net "PVCCIN_CPU0_VDD1")
	)
	(segment
		(start 359.748074 -360.648504)
		(end 359.942384 -360.842814)
		(width 0.1778)
		(layer "F.Cu")
		(net "PVCCIN_CPU0_VCC")
	)
	(segment
		(start 359.393236 -360.648504)
		(end 359.748074 -360.648504)
		(width 0.1778)
		(layer "F.Cu")
		(net "PVCCIN_CPU0_VCC")
	)
	(segment
		(start 359.942384 -361.729274)
		(end 360.579416 -362.366306)
		(width 0.1778)
		(layer "F.Cu")
		(net "PVCCIN_CPU0_VCC")
	)
	(segment
		(start 362.246418 -362.618528)
		(end 362.246418 -363.504988)
		(width 0.1778)
		(layer "F.Cu")
		(net "PVCCIN_CPU0_VCC")
	)
	(segment
		(start 362.246418 -361.72775)
		(end 362.246418 -362.618528)
		(width 0.1778)
		(layer "F.Cu")
		(net "PVCCIN_CPU0_VCC")
	)
	(segment
		(start 360.579416 -362.366306)
		(end 360.579416 -362.860336)
		(width 0.1778)
		(layer "F.Cu")
		(net "PVCCIN_CPU0_VCC")
	)
	(segment
		(start 362.246418 -363.504988)
		(end 362.25353 -363.5121)
		(width 0.1778)
		(layer "F.Cu")
		(net "PVCCIN_CPU0_VCC")
	)
	(segment
		(start 362.25353 -363.5121)
		(end 361.23118 -363.5121)
		(width 0.1778)
		(layer "F.Cu")
		(net "PVCCIN_CPU0_VCC")
	)
	(segment
		(start 361.23118 -363.5121)
		(end 361.04449 -363.32541)
		(width 0.1778)
		(layer "F.Cu")
		(net "PVCCIN_CPU0_VCC")
	)
	(segment
		(start 359.942384 -360.842814)
		(end 359.942384 -361.729274)
		(width 0.1778)
		(layer "F.Cu")
		(net "PVCCIN_CPU0_VCC")
	)
	(segment
		(start 360.579416 -362.860336)
		(end 361.04449 -363.32541)
		(width 0.1778)
		(layer "F.Cu")
		(net "PVCCIN_CPU0_VCC")
	)
	(via
		(at 361.04449 -363.32541)
		(size 0.762)
		(drill 0.254)
		(layers "F.Cu" "B.Cu")
		(net "PVCCIN_CPU0_VCC")
	)
	(segment
		(start 361.04449 -362.945426)
		(end 361.291124 -362.698792)
		(width 0.254)
		(layer "B.Cu")
		(net "PVCCIN_CPU0_VCC")
	)
	(segment
		(start 361.04449 -363.32541)
		(end 361.04449 -362.945426)
		(width 0.254)
		(layer "B.Cu")
		(net "PVCCIN_CPU0_VCC")
	)
	(segment
		(start 385.848352 -347.228922)
		(end 386.000244 -346.8624)
		(width 0.1778)
		(layer "F.Cu")
		(net "PVCCIN_CPU0_PWM8")
	)
	(segment
		(start 357.118158 -363.374686)
		(end 357.118158 -361.723432)
		(width 0.1778)
		(layer "F.Cu")
		(net "PVCCIN_CPU0_PWM8")
	)
	(segment
		(start 358.149652 -364.40618)
		(end 357.118158 -363.374686)
		(width 0.1778)
		(layer "F.Cu")
		(net "PVCCIN_CPU0_PWM8")
	)
	(segment
		(start 386.000244 -346.8624)
		(end 386.000244 -345.816936)
		(width 0.1778)
		(layer "F.Cu")
		(net "PVCCIN_CPU0_PWM8")
	)
	(via
		(at 385.848352 -347.228922)
		(size 0.508)
		(drill 0.254)
		(layers "F.Cu" "B.Cu")
		(net "PVCCIN_CPU0_PWM8")
	)
	(via
		(at 358.149652 -364.40618)
		(size 0.762)
		(drill 0.254)
		(layers "F.Cu" "B.Cu")
		(net "PVCCIN_CPU0_PWM8")
	)
	(segment
		(start 366.262158 -356.057962)
		(end 364.713266 -356.057962)
		(width 0.2032)
		(layer "In2.Cu")
		(net "PVCCIN_CPU0_PWM8")
	)
	(segment
		(start 384.809492 -349.649796)
		(end 372.670324 -349.649796)
		(width 0.2032)
		(layer "In2.Cu")
		(net "PVCCIN_CPU0_PWM8")
	)
	(segment
		(start 386.325618 -348.13367)
		(end 384.809492 -349.649796)
		(width 0.2032)
		(layer "In2.Cu")
		(net "PVCCIN_CPU0_PWM8")
	)
	(segment
		(start 359.3465 -363.347508)
		(end 358.287828 -364.40618)
		(width 0.2032)
		(layer "In2.Cu")
		(net "PVCCIN_CPU0_PWM8")
	)
	(segment
		(start 362.388658 -358.38257)
		(end 362.388658 -361.67695)
		(width 0.2032)
		(layer "In2.Cu")
		(net "PVCCIN_CPU0_PWM8")
	)
	(segment
		(start 372.670324 -349.649796)
		(end 366.262158 -356.057962)
		(width 0.2032)
		(layer "In2.Cu")
		(net "PVCCIN_CPU0_PWM8")
	)
	(segment
		(start 362.388658 -361.67695)
		(end 361.65028 -362.415328)
		(width 0.2032)
		(layer "In2.Cu")
		(net "PVCCIN_CPU0_PWM8")
	)
	(segment
		(start 359.844086 -363.347508)
		(end 359.3465 -363.347508)
		(width 0.2032)
		(layer "In2.Cu")
		(net "PVCCIN_CPU0_PWM8")
	)
	(segment
		(start 358.287828 -364.40618)
		(end 358.149652 -364.40618)
		(width 0.2032)
		(layer "In2.Cu")
		(net "PVCCIN_CPU0_PWM8")
	)
	(segment
		(start 360.232706 -362.958888)
		(end 359.844086 -363.347508)
		(width 0.2032)
		(layer "In2.Cu")
		(net "PVCCIN_CPU0_PWM8")
	)
	(segment
		(start 361.65028 -362.415328)
		(end 360.57078 -362.415328)
		(width 0.2032)
		(layer "In2.Cu")
		(net "PVCCIN_CPU0_PWM8")
	)
	(segment
		(start 360.57078 -362.415328)
		(end 360.232706 -362.753402)
		(width 0.2032)
		(layer "In2.Cu")
		(net "PVCCIN_CPU0_PWM8")
	)
	(segment
		(start 364.713266 -356.057962)
		(end 362.388658 -358.38257)
		(width 0.2032)
		(layer "In2.Cu")
		(net "PVCCIN_CPU0_PWM8")
	)
	(segment
		(start 385.848352 -347.228922)
		(end 386.325618 -347.706188)
		(width 0.2032)
		(layer "In2.Cu")
		(net "PVCCIN_CPU0_PWM8")
	)
	(segment
		(start 386.325618 -347.706188)
		(end 386.325618 -348.13367)
		(width 0.2032)
		(layer "In2.Cu")
		(net "PVCCIN_CPU0_PWM8")
	)
	(segment
		(start 360.232706 -362.753402)
		(end 360.232706 -362.958888)
		(width 0.2032)
		(layer "In2.Cu")
		(net "PVCCIN_CPU0_PWM8")
	)
	(segment
		(start 358.261158 -365.789718)
		(end 357.827834 -365.789718)
		(width 0.1778)
		(layer "F.Cu")
		(net "PVCCIN_CPU0_PWM7")
	)
	(segment
		(start 328.90714 -346.922344)
		(end 328.90714 -345.87688)
		(width 0.1778)
		(layer "F.Cu")
		(net "PVCCIN_CPU0_PWM7")
	)
	(segment
		(start 328.755248 -347.288866)
		(end 328.90714 -346.922344)
		(width 0.1778)
		(layer "F.Cu")
		(net "PVCCIN_CPU0_PWM7")
	)
	(segment
		(start 356.915974 -363.885734)
		(end 356.718108 -363.687868)
		(width 0.1778)
		(layer "F.Cu")
		(net "PVCCIN_CPU0_PWM7")
	)
	(segment
		(start 356.915974 -364.877858)
		(end 356.915974 -363.885734)
		(width 0.1778)
		(layer "F.Cu")
		(net "PVCCIN_CPU0_PWM7")
	)
	(segment
		(start 356.718108 -363.687868)
		(end 356.718108 -361.723432)
		(width 0.1778)
		(layer "F.Cu")
		(net "PVCCIN_CPU0_PWM7")
	)
	(segment
		(start 357.827834 -365.789718)
		(end 356.915974 -364.877858)
		(width 0.1778)
		(layer "F.Cu")
		(net "PVCCIN_CPU0_PWM7")
	)
	(via
		(at 358.261158 -365.789718)
		(size 0.762)
		(drill 0.254)
		(layers "F.Cu" "B.Cu")
		(net "PVCCIN_CPU0_PWM7")
	)
	(via
		(at 328.755248 -347.288866)
		(size 0.508)
		(drill 0.254)
		(layers "F.Cu" "B.Cu")
		(net "PVCCIN_CPU0_PWM7")
	)
	(segment
		(start 344.855038 -348.87789)
		(end 343.165938 -347.18879)
		(width 0.2032)
		(layer "In2.Cu")
		(net "PVCCIN_CPU0_PWM7")
	)
	(segment
		(start 345.2114 -363.207808)
		(end 345.2114 -362.308648)
		(width 0.2032)
		(layer "In2.Cu")
		(net "PVCCIN_CPU0_PWM7")
	)
	(segment
		(start 343.165938 -347.18879)
		(end 334.075786 -347.18879)
		(width 0.2032)
		(layer "In2.Cu")
		(net "PVCCIN_CPU0_PWM7")
	)
	(segment
		(start 345.62796 -361.892088)
		(end 345.62796 -354.30587)
		(width 0.2032)
		(layer "In2.Cu")
		(net "PVCCIN_CPU0_PWM7")
	)
	(segment
		(start 345.2114 -362.308648)
		(end 345.62796 -361.892088)
		(width 0.2032)
		(layer "In2.Cu")
		(net "PVCCIN_CPU0_PWM7")
	)
	(segment
		(start 357.939848 -366.085628)
		(end 355.185726 -366.085628)
		(width 0.2032)
		(layer "In2.Cu")
		(net "PVCCIN_CPU0_PWM7")
	)
	(segment
		(start 329.386184 -347.288866)
		(end 328.755248 -347.288866)
		(width 0.2032)
		(layer "In2.Cu")
		(net "PVCCIN_CPU0_PWM7")
	)
	(segment
		(start 334.075786 -347.18879)
		(end 333.492348 -347.772228)
		(width 0.2032)
		(layer "In2.Cu")
		(net "PVCCIN_CPU0_PWM7")
	)
	(segment
		(start 344.855038 -353.532948)
		(end 344.855038 -348.87789)
		(width 0.2032)
		(layer "In2.Cu")
		(net "PVCCIN_CPU0_PWM7")
	)
	(segment
		(start 355.185726 -366.085628)
		(end 354.825046 -366.446308)
		(width 0.2032)
		(layer "In2.Cu")
		(net "PVCCIN_CPU0_PWM7")
	)
	(segment
		(start 358.261158 -365.789718)
		(end 358.235758 -365.789718)
		(width 0.2032)
		(layer "In2.Cu")
		(net "PVCCIN_CPU0_PWM7")
	)
	(segment
		(start 348.4499 -366.446308)
		(end 345.2114 -363.207808)
		(width 0.2032)
		(layer "In2.Cu")
		(net "PVCCIN_CPU0_PWM7")
	)
	(segment
		(start 358.235758 -365.789718)
		(end 357.939848 -366.085628)
		(width 0.2032)
		(layer "In2.Cu")
		(net "PVCCIN_CPU0_PWM7")
	)
	(segment
		(start 329.869546 -347.772228)
		(end 329.386184 -347.288866)
		(width 0.2032)
		(layer "In2.Cu")
		(net "PVCCIN_CPU0_PWM7")
	)
	(segment
		(start 345.62796 -354.30587)
		(end 344.855038 -353.532948)
		(width 0.2032)
		(layer "In2.Cu")
		(net "PVCCIN_CPU0_PWM7")
	)
	(segment
		(start 354.825046 -366.446308)
		(end 348.4499 -366.446308)
		(width 0.2032)
		(layer "In2.Cu")
		(net "PVCCIN_CPU0_PWM7")
	)
	(segment
		(start 333.492348 -347.772228)
		(end 329.869546 -347.772228)
		(width 0.2032)
		(layer "In2.Cu")
		(net "PVCCIN_CPU0_PWM7")
	)
	(segment
		(start 356.5525 -364.693708)
		(end 356.5525 -364.040928)
		(width 0.1778)
		(layer "F.Cu")
		(net "PVCCIN_CPU0_PWM6")
	)
	(segment
		(start 356.5525 -364.040928)
		(end 356.318312 -363.80674)
		(width 0.1778)
		(layer "F.Cu")
		(net "PVCCIN_CPU0_PWM6")
	)
	(segment
		(start 336.88528 -341.43823)
		(end 337.037172 -341.071708)
		(width 0.1778)
		(layer "F.Cu")
		(net "PVCCIN_CPU0_PWM6")
	)
	(segment
		(start 356.029768 -365.21644)
		(end 356.5525 -364.693708)
		(width 0.1778)
		(layer "F.Cu")
		(net "PVCCIN_CPU0_PWM6")
	)
	(segment
		(start 356.318312 -363.80674)
		(end 356.318312 -361.723432)
		(width 0.1778)
		(layer "F.Cu")
		(net "PVCCIN_CPU0_PWM6")
	)
	(segment
		(start 337.037172 -341.071708)
		(end 337.037172 -340.026244)
		(width 0.1778)
		(layer "F.Cu")
		(net "PVCCIN_CPU0_PWM6")
	)
	(segment
		(start 355.236526 -365.21644)
		(end 356.029768 -365.21644)
		(width 0.1778)
		(layer "F.Cu")
		(net "PVCCIN_CPU0_PWM6")
	)
	(via
		(at 355.236526 -365.21644)
		(size 0.762)
		(drill 0.254)
		(layers "F.Cu" "B.Cu")
		(net "PVCCIN_CPU0_PWM6")
	)
	(via
		(at 336.88528 -341.43823)
		(size 0.508)
		(drill 0.254)
		(layers "F.Cu" "B.Cu")
		(net "PVCCIN_CPU0_PWM6")
	)
	(segment
		(start 340.78418 -343.628472)
		(end 339.075522 -343.628472)
		(width 0.2032)
		(layer "In2.Cu")
		(net "PVCCIN_CPU0_PWM6")
	)
	(segment
		(start 345.571318 -348.41561)
		(end 340.78418 -343.628472)
		(width 0.2032)
		(layer "In2.Cu")
		(net "PVCCIN_CPU0_PWM6")
	)
	(segment
		(start 350.78162 -365.293148)
		(end 346.39758 -360.909108)
		(width 0.2032)
		(layer "In2.Cu")
		(net "PVCCIN_CPU0_PWM6")
	)
	(segment
		(start 339.075522 -343.628472)
		(end 336.88528 -341.43823)
		(width 0.2032)
		(layer "In2.Cu")
		(net "PVCCIN_CPU0_PWM6")
	)
	(segment
		(start 355.231446 -365.21644)
		(end 355.154738 -365.293148)
		(width 0.2032)
		(layer "In2.Cu")
		(net "PVCCIN_CPU0_PWM6")
	)
	(segment
		(start 355.236526 -365.21644)
		(end 355.231446 -365.21644)
		(width 0.2032)
		(layer "In2.Cu")
		(net "PVCCIN_CPU0_PWM6")
	)
	(segment
		(start 355.154738 -365.293148)
		(end 350.78162 -365.293148)
		(width 0.2032)
		(layer "In2.Cu")
		(net "PVCCIN_CPU0_PWM6")
	)
	(segment
		(start 346.39758 -360.909108)
		(end 346.39758 -353.92995)
		(width 0.2032)
		(layer "In2.Cu")
		(net "PVCCIN_CPU0_PWM6")
	)
	(segment
		(start 346.39758 -353.92995)
		(end 345.571318 -353.103688)
		(width 0.2032)
		(layer "In2.Cu")
		(net "PVCCIN_CPU0_PWM6")
	)
	(segment
		(start 345.571318 -353.103688)
		(end 345.571318 -348.41561)
		(width 0.2032)
		(layer "In2.Cu")
		(net "PVCCIN_CPU0_PWM6")
	)
	(segment
		(start 377.839732 -341.071708)
		(end 377.839732 -340.026244)
		(width 0.1778)
		(layer "F.Cu")
		(net "PVCCIN_CPU0_PWM5")
	)
	(segment
		(start 355.948234 -364.386368)
		(end 355.948234 -361.753404)
		(width 0.1778)
		(layer "F.Cu")
		(net "PVCCIN_CPU0_PWM5")
	)
	(segment
		(start 355.948234 -361.753404)
		(end 355.918262 -361.723432)
		(width 0.1778)
		(layer "F.Cu")
		(net "PVCCIN_CPU0_PWM5")
	)
	(segment
		(start 377.68784 -341.43823)
		(end 377.839732 -341.071708)
		(width 0.1778)
		(layer "F.Cu")
		(net "PVCCIN_CPU0_PWM5")
	)
	(via
		(at 355.948234 -364.386368)
		(size 0.508)
		(drill 0.254)
		(layers "F.Cu" "B.Cu")
		(net "PVCCIN_CPU0_PWM5")
	)
	(via
		(at 377.68784 -341.43823)
		(size 0.508)
		(drill 0.254)
		(layers "F.Cu" "B.Cu")
		(net "PVCCIN_CPU0_PWM5")
	)
	(segment
		(start 362.757466 -355.666548)
		(end 363.099604 -355.32441)
		(width 0.2032)
		(layer "In2.Cu")
		(net "PVCCIN_CPU0_PWM5")
	)
	(segment
		(start 358.012492 -358.06507)
		(end 358.718612 -358.06507)
		(width 0.2032)
		(layer "In2.Cu")
		(net "PVCCIN_CPU0_PWM5")
	)
	(segment
		(start 361.334812 -355.666548)
		(end 362.757466 -355.666548)
		(width 0.2032)
		(layer "In2.Cu")
		(net "PVCCIN_CPU0_PWM5")
	)
	(segment
		(start 357.356918 -358.720644)
		(end 358.012492 -358.06507)
		(width 0.2032)
		(layer "In2.Cu")
		(net "PVCCIN_CPU0_PWM5")
	)
	(segment
		(start 355.948234 -364.244128)
		(end 357.356918 -362.835444)
		(width 0.2032)
		(layer "In2.Cu")
		(net "PVCCIN_CPU0_PWM5")
	)
	(segment
		(start 363.099604 -354.006404)
		(end 364.71606 -352.389948)
		(width 0.2032)
		(layer "In2.Cu")
		(net "PVCCIN_CPU0_PWM5")
	)
	(segment
		(start 360.962956 -355.820726)
		(end 361.334812 -355.666548)
		(width 0.2032)
		(layer "In2.Cu")
		(net "PVCCIN_CPU0_PWM5")
	)
	(segment
		(start 357.356918 -362.835444)
		(end 357.356918 -358.720644)
		(width 0.2032)
		(layer "In2.Cu")
		(net "PVCCIN_CPU0_PWM5")
	)
	(segment
		(start 364.71606 -352.389948)
		(end 368.046 -352.389948)
		(width 0.2032)
		(layer "In2.Cu")
		(net "PVCCIN_CPU0_PWM5")
	)
	(segment
		(start 363.099604 -355.32441)
		(end 363.099604 -354.006404)
		(width 0.2032)
		(layer "In2.Cu")
		(net "PVCCIN_CPU0_PWM5")
	)
	(segment
		(start 355.948234 -364.386368)
		(end 355.948234 -364.244128)
		(width 0.2032)
		(layer "In2.Cu")
		(net "PVCCIN_CPU0_PWM5")
	)
	(segment
		(start 358.718612 -358.06507)
		(end 360.962956 -355.820726)
		(width 0.2032)
		(layer "In2.Cu")
		(net "PVCCIN_CPU0_PWM5")
	)
	(segment
		(start 373.016272 -347.419676)
		(end 374.306592 -347.419676)
		(width 0.2032)
		(layer "In2.Cu")
		(net "PVCCIN_CPU0_PWM5")
	)
	(segment
		(start 378.568458 -343.15781)
		(end 378.568458 -342.318848)
		(width 0.2032)
		(layer "In2.Cu")
		(net "PVCCIN_CPU0_PWM5")
	)
	(segment
		(start 368.046 -352.389948)
		(end 373.016272 -347.419676)
		(width 0.2032)
		(layer "In2.Cu")
		(net "PVCCIN_CPU0_PWM5")
	)
	(segment
		(start 378.568458 -342.318848)
		(end 377.68784 -341.43823)
		(width 0.2032)
		(layer "In2.Cu")
		(net "PVCCIN_CPU0_PWM5")
	)
	(segment
		(start 374.306592 -347.419676)
		(end 378.568458 -343.15781)
		(width 0.2032)
		(layer "In2.Cu")
		(net "PVCCIN_CPU0_PWM5")
	)
	(segment
		(start 369.67922 -337.661504)
		(end 369.67922 -336.61604)
		(width 0.1778)
		(layer "F.Cu")
		(net "PVCCIN_CPU0_PWM4")
	)
	(segment
		(start 369.527328 -338.028026)
		(end 369.67922 -337.661504)
		(width 0.1778)
		(layer "F.Cu")
		(net "PVCCIN_CPU0_PWM4")
	)
	(segment
		(start 354.442522 -364.4138)
		(end 355.518212 -363.33811)
		(width 0.1778)
		(layer "F.Cu")
		(net "PVCCIN_CPU0_PWM4")
	)
	(segment
		(start 355.518212 -363.33811)
		(end 355.518212 -361.723432)
		(width 0.1778)
		(layer "F.Cu")
		(net "PVCCIN_CPU0_PWM4")
	)
	(via
		(at 369.527328 -338.028026)
		(size 0.508)
		(drill 0.254)
		(layers "F.Cu" "B.Cu")
		(net "PVCCIN_CPU0_PWM4")
	)
	(via
		(at 354.442522 -364.4138)
		(size 0.508)
		(drill 0.254)
		(layers "F.Cu" "B.Cu")
		(net "PVCCIN_CPU0_PWM4")
	)
	(segment
		(start 370.308378 -338.809076)
		(end 370.308378 -339.73135)
		(width 0.2032)
		(layer "In2.Cu")
		(net "PVCCIN_CPU0_PWM4")
	)
	(segment
		(start 354.653342 -364.4138)
		(end 354.442522 -364.4138)
		(width 0.2032)
		(layer "In2.Cu")
		(net "PVCCIN_CPU0_PWM4")
	)
	(segment
		(start 369.551458 -340.48827)
		(end 368.385598 -340.48827)
		(width 0.2032)
		(layer "In2.Cu")
		(net "PVCCIN_CPU0_PWM4")
	)
	(segment
		(start 355.703378 -363.363764)
		(end 354.653342 -364.4138)
		(width 0.2032)
		(layer "In2.Cu")
		(net "PVCCIN_CPU0_PWM4")
	)
	(segment
		(start 365.612934 -345.930474)
		(end 361.74426 -349.799148)
		(width 0.2032)
		(layer "In2.Cu")
		(net "PVCCIN_CPU0_PWM4")
	)
	(segment
		(start 369.527328 -338.028026)
		(end 370.308378 -338.809076)
		(width 0.2032)
		(layer "In2.Cu")
		(net "PVCCIN_CPU0_PWM4")
	)
	(segment
		(start 357.73868 -352.339148)
		(end 357.73868 -354.871528)
		(width 0.2032)
		(layer "In2.Cu")
		(net "PVCCIN_CPU0_PWM4")
	)
	(segment
		(start 368.385598 -340.48827)
		(end 365.612934 -343.260934)
		(width 0.2032)
		(layer "In2.Cu")
		(net "PVCCIN_CPU0_PWM4")
	)
	(segment
		(start 358.17048 -350.942148)
		(end 358.17048 -351.907348)
		(width 0.2032)
		(layer "In2.Cu")
		(net "PVCCIN_CPU0_PWM4")
	)
	(segment
		(start 359.31348 -349.799148)
		(end 358.17048 -350.942148)
		(width 0.2032)
		(layer "In2.Cu")
		(net "PVCCIN_CPU0_PWM4")
	)
	(segment
		(start 358.17048 -351.907348)
		(end 357.73868 -352.339148)
		(width 0.2032)
		(layer "In2.Cu")
		(net "PVCCIN_CPU0_PWM4")
	)
	(segment
		(start 357.73868 -354.871528)
		(end 355.703378 -356.90683)
		(width 0.2032)
		(layer "In2.Cu")
		(net "PVCCIN_CPU0_PWM4")
	)
	(segment
		(start 361.74426 -349.799148)
		(end 359.31348 -349.799148)
		(width 0.2032)
		(layer "In2.Cu")
		(net "PVCCIN_CPU0_PWM4")
	)
	(segment
		(start 365.612934 -343.260934)
		(end 365.612934 -345.930474)
		(width 0.2032)
		(layer "In2.Cu")
		(net "PVCCIN_CPU0_PWM4")
	)
	(segment
		(start 355.703378 -356.90683)
		(end 355.703378 -363.363764)
		(width 0.2032)
		(layer "In2.Cu")
		(net "PVCCIN_CPU0_PWM4")
	)
	(segment
		(start 370.308378 -339.73135)
		(end 369.551458 -340.48827)
		(width 0.2032)
		(layer "In2.Cu")
		(net "PVCCIN_CPU0_PWM4")
	)
	(segment
		(start 361.518708 -337.401916)
		(end 361.518708 -336.61604)
		(width 0.1778)
		(layer "F.Cu")
		(net "PVCCIN_CPU0_PWM3")
	)
	(segment
		(start 354.560378 -363.277658)
		(end 355.118162 -362.719874)
		(width 0.1778)
		(layer "F.Cu")
		(net "PVCCIN_CPU0_PWM3")
	)
	(segment
		(start 361.419394 -337.901026)
		(end 361.518708 -337.401916)
		(width 0.1778)
		(layer "F.Cu")
		(net "PVCCIN_CPU0_PWM3")
	)
	(segment
		(start 361.366816 -338.028026)
		(end 361.419394 -337.901026)
		(width 0.1778)
		(layer "F.Cu")
		(net "PVCCIN_CPU0_PWM3")
	)
	(segment
		(start 355.118162 -362.719874)
		(end 355.118162 -361.723432)
		(width 0.1778)
		(layer "F.Cu")
		(net "PVCCIN_CPU0_PWM3")
	)
	(via
		(at 361.366816 -338.028026)
		(size 0.508)
		(drill 0.254)
		(layers "F.Cu" "B.Cu")
		(net "PVCCIN_CPU0_PWM3")
	)
	(via
		(at 354.560378 -363.277658)
		(size 0.762)
		(drill 0.254)
		(layers "F.Cu" "B.Cu")
		(net "PVCCIN_CPU0_PWM3")
	)
	(segment
		(start 354.126038 -354.021136)
		(end 354.126038 -361.183174)
		(width 0.2032)
		(layer "In2.Cu")
		(net "PVCCIN_CPU0_PWM3")
	)
	(segment
		(start 351.38868 -352.231452)
		(end 352.025458 -352.86823)
		(width 0.2032)
		(layer "In2.Cu")
		(net "PVCCIN_CPU0_PWM3")
	)
	(segment
		(start 357.903018 -343.86901)
		(end 357.903018 -344.120216)
		(width 0.2032)
		(layer "In2.Cu")
		(net "PVCCIN_CPU0_PWM3")
	)
	(segment
		(start 351.38868 -350.634554)
		(end 351.38868 -352.231452)
		(width 0.2032)
		(layer "In2.Cu")
		(net "PVCCIN_CPU0_PWM3")
	)
	(segment
		(start 361.366816 -338.028026)
		(end 362.256578 -338.917788)
		(width 0.2032)
		(layer "In2.Cu")
		(net "PVCCIN_CPU0_PWM3")
	)
	(segment
		(start 352.025458 -352.86823)
		(end 352.973132 -352.86823)
		(width 0.2032)
		(layer "In2.Cu")
		(net "PVCCIN_CPU0_PWM3")
	)
	(segment
		(start 354.93706 -361.994196)
		(end 354.93706 -362.900976)
		(width 0.2032)
		(layer "In2.Cu")
		(net "PVCCIN_CPU0_PWM3")
	)
	(segment
		(start 362.256578 -338.917788)
		(end 362.256578 -339.51545)
		(width 0.2032)
		(layer "In2.Cu")
		(net "PVCCIN_CPU0_PWM3")
	)
	(segment
		(start 352.973132 -352.86823)
		(end 354.126038 -354.021136)
		(width 0.2032)
		(layer "In2.Cu")
		(net "PVCCIN_CPU0_PWM3")
	)
	(segment
		(start 354.93706 -362.900976)
		(end 354.560378 -363.277658)
		(width 0.2032)
		(layer "In2.Cu")
		(net "PVCCIN_CPU0_PWM3")
	)
	(segment
		(start 354.126038 -361.183174)
		(end 354.93706 -361.994196)
		(width 0.2032)
		(layer "In2.Cu")
		(net "PVCCIN_CPU0_PWM3")
	)
	(segment
		(start 357.903018 -344.120216)
		(end 351.38868 -350.634554)
		(width 0.2032)
		(layer "In2.Cu")
		(net "PVCCIN_CPU0_PWM3")
	)
	(segment
		(start 362.256578 -339.51545)
		(end 357.903018 -343.86901)
		(width 0.2032)
		(layer "In2.Cu")
		(net "PVCCIN_CPU0_PWM3")
	)
	(segment
		(start 353.358196 -337.661504)
		(end 353.358196 -336.61604)
		(width 0.1778)
		(layer "F.Cu")
		(net "PVCCIN_CPU0_PWM2")
	)
	(segment
		(start 352.723958 -363.66831)
		(end 353.325176 -363.66831)
		(width 0.1778)
		(layer "F.Cu")
		(net "PVCCIN_CPU0_PWM2")
	)
	(segment
		(start 353.325176 -363.66831)
		(end 354.718112 -362.275374)
		(width 0.1778)
		(layer "F.Cu")
		(net "PVCCIN_CPU0_PWM2")
	)
	(segment
		(start 354.718112 -362.275374)
		(end 354.718112 -361.723432)
		(width 0.1778)
		(layer "F.Cu")
		(net "PVCCIN_CPU0_PWM2")
	)
	(segment
		(start 353.206304 -338.028026)
		(end 353.358196 -337.661504)
		(width 0.1778)
		(layer "F.Cu")
		(net "PVCCIN_CPU0_PWM2")
	)
	(segment
		(start 352.693478 -363.63783)
		(end 352.723958 -363.66831)
		(width 0.1778)
		(layer "F.Cu")
		(net "PVCCIN_CPU0_PWM2")
	)
	(via
		(at 353.206304 -338.028026)
		(size 0.508)
		(drill 0.254)
		(layers "F.Cu" "B.Cu")
		(net "PVCCIN_CPU0_PWM2")
	)
	(via
		(at 352.693478 -363.63783)
		(size 0.508)
		(drill 0.254)
		(layers "F.Cu" "B.Cu")
		(net "PVCCIN_CPU0_PWM2")
	)
	(segment
		(start 352.693478 -362.561886)
		(end 352.2091 -362.077508)
		(width 0.2032)
		(layer "In2.Cu")
		(net "PVCCIN_CPU0_PWM2")
	)
	(segment
		(start 350.666558 -340.567772)
		(end 353.206304 -338.028026)
		(width 0.2032)
		(layer "In2.Cu")
		(net "PVCCIN_CPU0_PWM2")
	)
	(segment
		(start 350.666558 -358.487726)
		(end 350.666558 -340.567772)
		(width 0.2032)
		(layer "In2.Cu")
		(net "PVCCIN_CPU0_PWM2")
	)
	(segment
		(start 352.693478 -363.63783)
		(end 352.693478 -362.561886)
		(width 0.2032)
		(layer "In2.Cu")
		(net "PVCCIN_CPU0_PWM2")
	)
	(segment
		(start 352.2091 -361.338368)
		(end 351.34296 -360.472228)
		(width 0.2032)
		(layer "In2.Cu")
		(net "PVCCIN_CPU0_PWM2")
	)
	(segment
		(start 351.34296 -359.164128)
		(end 350.666558 -358.487726)
		(width 0.2032)
		(layer "In2.Cu")
		(net "PVCCIN_CPU0_PWM2")
	)
	(segment
		(start 351.34296 -360.472228)
		(end 351.34296 -359.164128)
		(width 0.2032)
		(layer "In2.Cu")
		(net "PVCCIN_CPU0_PWM2")
	)
	(segment
		(start 352.2091 -362.077508)
		(end 352.2091 -361.338368)
		(width 0.2032)
		(layer "In2.Cu")
		(net "PVCCIN_CPU0_PWM2")
	)
	(segment
		(start 345.197684 -337.661504)
		(end 345.197684 -336.61604)
		(width 0.1778)
		(layer "F.Cu")
		(net "PVCCIN_CPU0_PWM1")
	)
	(segment
		(start 345.045792 -338.028026)
		(end 345.197684 -337.661504)
		(width 0.1778)
		(layer "F.Cu")
		(net "PVCCIN_CPU0_PWM1")
	)
	(segment
		(start 354.318316 -361.974892)
		(end 354.318316 -361.723432)
		(width 0.1778)
		(layer "F.Cu")
		(net "PVCCIN_CPU0_PWM1")
	)
	(segment
		(start 353.98202 -362.346748)
		(end 353.98202 -362.311188)
		(width 0.1778)
		(layer "F.Cu")
		(net "PVCCIN_CPU0_PWM1")
	)
	(segment
		(start 353.98202 -362.311188)
		(end 354.318316 -361.974892)
		(width 0.1778)
		(layer "F.Cu")
		(net "PVCCIN_CPU0_PWM1")
	)
	(via
		(at 345.045792 -338.028026)
		(size 0.508)
		(drill 0.254)
		(layers "F.Cu" "B.Cu")
		(net "PVCCIN_CPU0_PWM1")
	)
	(via
		(at 353.98202 -362.346748)
		(size 0.508)
		(drill 0.254)
		(layers "F.Cu" "B.Cu")
		(net "PVCCIN_CPU0_PWM1")
	)
	(segment
		(start 346.343478 -347.44025)
		(end 343.623138 -344.71991)
		(width 0.2032)
		(layer "In2.Cu")
		(net "PVCCIN_CPU0_PWM1")
	)
	(segment
		(start 346.239338 -338.838286)
		(end 345.429078 -338.028026)
		(width 0.2032)
		(layer "In2.Cu")
		(net "PVCCIN_CPU0_PWM1")
	)
	(segment
		(start 353.64674 -362.682028)
		(end 353.64674 -363.921802)
		(width 0.2032)
		(layer "In2.Cu")
		(net "PVCCIN_CPU0_PWM1")
	)
	(segment
		(start 349.1738 -354.782628)
		(end 346.343478 -351.952306)
		(width 0.2032)
		(layer "In2.Cu")
		(net "PVCCIN_CPU0_PWM1")
	)
	(segment
		(start 351.054416 -364.51921)
		(end 348.8817 -362.346494)
		(width 0.2032)
		(layer "In2.Cu")
		(net "PVCCIN_CPU0_PWM1")
	)
	(segment
		(start 353.64674 -363.921802)
		(end 353.049332 -364.51921)
		(width 0.2032)
		(layer "In2.Cu")
		(net "PVCCIN_CPU0_PWM1")
	)
	(segment
		(start 348.8817 -361.625388)
		(end 349.1738 -361.333288)
		(width 0.2032)
		(layer "In2.Cu")
		(net "PVCCIN_CPU0_PWM1")
	)
	(segment
		(start 353.98202 -362.346748)
		(end 353.64674 -362.682028)
		(width 0.2032)
		(layer "In2.Cu")
		(net "PVCCIN_CPU0_PWM1")
	)
	(segment
		(start 343.623138 -342.82253)
		(end 346.239338 -340.20633)
		(width 0.2032)
		(layer "In2.Cu")
		(net "PVCCIN_CPU0_PWM1")
	)
	(segment
		(start 353.049332 -364.51921)
		(end 351.054416 -364.51921)
		(width 0.2032)
		(layer "In2.Cu")
		(net "PVCCIN_CPU0_PWM1")
	)
	(segment
		(start 348.8817 -362.346494)
		(end 348.8817 -361.625388)
		(width 0.2032)
		(layer "In2.Cu")
		(net "PVCCIN_CPU0_PWM1")
	)
	(segment
		(start 345.429078 -338.028026)
		(end 345.045792 -338.028026)
		(width 0.2032)
		(layer "In2.Cu")
		(net "PVCCIN_CPU0_PWM1")
	)
	(segment
		(start 343.623138 -344.71991)
		(end 343.623138 -342.82253)
		(width 0.2032)
		(layer "In2.Cu")
		(net "PVCCIN_CPU0_PWM1")
	)
	(segment
		(start 346.239338 -340.20633)
		(end 346.239338 -338.838286)
		(width 0.2032)
		(layer "In2.Cu")
		(net "PVCCIN_CPU0_PWM1")
	)
	(segment
		(start 349.1738 -361.333288)
		(end 349.1738 -354.782628)
		(width 0.2032)
		(layer "In2.Cu")
		(net "PVCCIN_CPU0_PWM1")
	)
	(segment
		(start 346.343478 -351.952306)
		(end 346.343478 -347.44025)
		(width 0.2032)
		(layer "In2.Cu")
		(net "PVCCIN_CPU0_PWM1")
	)
	(segment
		(start 382.256792 -343.126314)
		(end 382.165352 -343.126314)
		(width 0.2032)
		(layer "F.Cu")
		(net "PVCCIN_CPU0_PVCC")
	)
	(segment
		(start 341.339932 -334.518508)
		(end 341.339932 -333.925418)
		(width 0.2032)
		(layer "F.Cu")
		(net "PVCCIN_CPU0_PVCC")
	)
	(segment
		(start 357.683816 -333.925418)
		(end 357.775256 -333.925418)
		(width 0.2032)
		(layer "F.Cu")
		(net "PVCCIN_CPU0_PVCC")
	)
	(segment
		(start 333.20228 -337.951572)
		(end 333.20228 -337.335622)
		(width 0.2032)
		(layer "F.Cu")
		(net "PVCCIN_CPU0_PVCC")
	)
	(segment
		(start 349.614744 -333.925418)
		(end 349.523304 -333.925418)
		(width 0.2032)
		(layer "F.Cu")
		(net "PVCCIN_CPU0_PVCC")
	)
	(segment
		(start 334.009492 -338.051394)
		(end 333.29372 -337.335622)
		(width 0.2032)
		(layer "F.Cu")
		(net "PVCCIN_CPU0_PVCC")
	)
	(segment
		(start 342.537542 -334.64119)
		(end 342.170004 -334.64119)
		(width 0.2032)
		(layer "F.Cu")
		(net "PVCCIN_CPU0_PVCC")
	)
	(segment
		(start 383.340102 -343.842086)
		(end 382.972564 -343.842086)
		(width 0.2032)
		(layer "F.Cu")
		(net "PVCCIN_CPU0_PVCC")
	)
	(segment
		(start 350.698054 -334.64119)
		(end 350.330516 -334.64119)
		(width 0.2032)
		(layer "F.Cu")
		(net "PVCCIN_CPU0_PVCC")
	)
	(segment
		(start 365.844328 -334.541368)
		(end 365.844328 -333.925418)
		(width 0.2032)
		(layer "F.Cu")
		(net "PVCCIN_CPU0_PVCC")
	)
	(segment
		(start 349.523304 -334.541368)
		(end 349.523304 -333.925418)
		(width 0.2032)
		(layer "F.Cu")
		(net "PVCCIN_CPU0_PVCC")
	)
	(segment
		(start 374.00484 -337.335622)
		(end 374.09628 -337.335622)
		(width 0.2032)
		(layer "F.Cu")
		(net "PVCCIN_CPU0_PVCC")
	)
	(segment
		(start 382.972564 -343.842086)
		(end 382.256792 -343.126314)
		(width 0.2032)
		(layer "F.Cu")
		(net "PVCCIN_CPU0_PVCC")
	)
	(segment
		(start 341.454232 -333.925418)
		(end 341.339932 -333.925418)
		(width 0.2032)
		(layer "F.Cu")
		(net "PVCCIN_CPU0_PVCC")
	)
	(segment
		(start 365.844328 -333.925418)
		(end 365.935768 -333.925418)
		(width 0.2032)
		(layer "F.Cu")
		(net "PVCCIN_CPU0_PVCC")
	)
	(segment
		(start 334.37703 -338.051394)
		(end 334.009492 -338.051394)
		(width 0.2032)
		(layer "F.Cu")
		(net "PVCCIN_CPU0_PVCC")
	)
	(segment
		(start 341.362792 -334.541368)
		(end 341.339932 -334.518508)
		(width 0.2032)
		(layer "F.Cu")
		(net "PVCCIN_CPU0_PVCC")
	)
	(segment
		(start 358.491028 -334.64119)
		(end 358.858566 -334.64119)
		(width 0.2032)
		(layer "F.Cu")
		(net "PVCCIN_CPU0_PVCC")
	)
	(segment
		(start 357.683816 -334.541368)
		(end 357.683816 -333.925418)
		(width 0.2032)
		(layer "F.Cu")
		(net "PVCCIN_CPU0_PVCC")
	)
	(segment
		(start 365.935768 -333.925418)
		(end 366.65154 -334.64119)
		(width 0.2032)
		(layer "F.Cu")
		(net "PVCCIN_CPU0_PVCC")
	)
	(segment
		(start 357.775256 -333.925418)
		(end 358.491028 -334.64119)
		(width 0.2032)
		(layer "F.Cu")
		(net "PVCCIN_CPU0_PVCC")
	)
	(segment
		(start 350.330516 -334.64119)
		(end 349.614744 -333.925418)
		(width 0.2032)
		(layer "F.Cu")
		(net "PVCCIN_CPU0_PVCC")
	)
	(segment
		(start 374.812052 -338.051394)
		(end 375.17959 -338.051394)
		(width 0.2032)
		(layer "F.Cu")
		(net "PVCCIN_CPU0_PVCC")
	)
	(segment
		(start 325.880476 -343.90203)
		(end 326.246998 -343.90203)
		(width 0.2286)
		(layer "F.Cu")
		(net "PVCCIN_CPU0_PVCC")
	)
	(segment
		(start 374.00484 -337.945222)
		(end 374.00484 -337.335622)
		(width 0.2032)
		(layer "F.Cu")
		(net "PVCCIN_CPU0_PVCC")
	)
	(segment
		(start 333.29372 -337.335622)
		(end 333.20228 -337.335622)
		(width 0.2032)
		(layer "F.Cu")
		(net "PVCCIN_CPU0_PVCC")
	)
	(segment
		(start 325.072248 -343.186258)
		(end 325.164704 -343.186258)
		(width 0.2286)
		(layer "F.Cu")
		(net "PVCCIN_CPU0_PVCC")
	)
	(segment
		(start 366.65154 -334.64119)
		(end 367.019078 -334.64119)
		(width 0.2032)
		(layer "F.Cu")
		(net "PVCCIN_CPU0_PVCC")
	)
	(segment
		(start 342.170004 -334.64119)
		(end 341.454232 -333.925418)
		(width 0.2032)
		(layer "F.Cu")
		(net "PVCCIN_CPU0_PVCC")
	)
	(segment
		(start 374.09628 -337.335622)
		(end 374.812052 -338.051394)
		(width 0.2032)
		(layer "F.Cu")
		(net "PVCCIN_CPU0_PVCC")
	)
	(segment
		(start 382.165352 -343.742264)
		(end 382.165352 -343.126314)
		(width 0.2032)
		(layer "F.Cu")
		(net "PVCCIN_CPU0_PVCC")
	)
	(segment
		(start 325.072248 -343.802208)
		(end 325.072248 -343.186258)
		(width 0.381)
		(layer "F.Cu")
		(net "PVCCIN_CPU0_PVCC")
	)
	(segment
		(start 325.164704 -343.186258)
		(end 325.880476 -343.90203)
		(width 0.2286)
		(layer "F.Cu")
		(net "PVCCIN_CPU0_PVCC")
	)
	(via
		(at 357.683816 -334.541368)
		(size 0.508)
		(drill 0.254)
		(layers "F.Cu" "B.Cu")
		(net "PVCCIN_CPU0_PVCC")
	)
	(via
		(at 341.362792 -334.541368)
		(size 0.508)
		(drill 0.254)
		(layers "F.Cu" "B.Cu")
		(net "PVCCIN_CPU0_PVCC")
	)
	(via
		(at 382.165352 -343.742264)
		(size 0.508)
		(drill 0.254)
		(layers "F.Cu" "B.Cu")
		(net "PVCCIN_CPU0_PVCC")
	)
	(via
		(at 365.844328 -334.541368)
		(size 0.508)
		(drill 0.254)
		(layers "F.Cu" "B.Cu")
		(net "PVCCIN_CPU0_PVCC")
	)
	(via
		(at 374.00484 -337.945222)
		(size 0.508)
		(drill 0.254)
		(layers "F.Cu" "B.Cu")
		(net "PVCCIN_CPU0_PVCC")
	)
	(via
		(at 333.20228 -337.951572)
		(size 0.508)
		(drill 0.254)
		(layers "F.Cu" "B.Cu")
		(net "PVCCIN_CPU0_PVCC")
	)
	(via
		(at 349.523304 -334.541368)
		(size 0.508)
		(drill 0.254)
		(layers "F.Cu" "B.Cu")
		(net "PVCCIN_CPU0_PVCC")
	)
	(via
		(at 325.072248 -343.802208)
		(size 0.508)
		(drill 0.254)
		(layers "F.Cu" "B.Cu")
		(net "PVCCIN_CPU0_PVCC")
	)
	(via
		(at 323.2277 -342.372188)
		(size 0.6604)
		(drill 0.3302)
		(layers "F.Cu" "B.Cu")
		(net "PVCCIN_CPU0_PVCC")
	)
	(segment
		(start 325.072248 -343.802208)
		(end 324.797928 -343.527888)
		(width 0.4572)
		(layer "B.Cu")
		(net "PVCCIN_CPU0_PVCC")
	)
	(segment
		(start 366.092232 -334.293464)
		(end 367.012474 -334.293464)
		(width 0.4572)
		(layer "B.Cu")
		(net "PVCCIN_CPU0_PVCC")
	)
	(segment
		(start 365.844328 -334.541368)
		(end 366.092232 -334.293464)
		(width 0.4572)
		(layer "B.Cu")
		(net "PVCCIN_CPU0_PVCC")
	)
	(segment
		(start 374.01119 -337.945222)
		(end 374.25757 -337.698842)
		(width 0.4572)
		(layer "B.Cu")
		(net "PVCCIN_CPU0_PVCC")
	)
	(segment
		(start 374.00484 -337.945222)
		(end 374.01119 -337.945222)
		(width 0.4572)
		(layer "B.Cu")
		(net "PVCCIN_CPU0_PVCC")
	)
	(segment
		(start 323.175884 -343.527888)
		(end 324.067424 -343.527888)
		(width 0.4572)
		(layer "B.Cu")
		(net "PVCCIN_CPU0_PVCC")
	)
	(segment
		(start 325.707502 -343.527888)
		(end 325.256144 -343.527888)
		(width 0.4572)
		(layer "B.Cu")
		(net "PVCCIN_CPU0_PVCC")
	)
	(segment
		(start 325.256144 -343.527888)
		(end 325.256144 -343.618312)
		(width 0.4572)
		(layer "B.Cu")
		(net "PVCCIN_CPU0_PVCC")
	)
	(segment
		(start 341.362792 -334.541368)
		(end 341.551768 -334.352392)
		(width 0.4572)
		(layer "B.Cu")
		(net "PVCCIN_CPU0_PVCC")
	)
	(segment
		(start 349.523304 -334.541368)
		(end 349.61957 -334.445102)
		(width 0.4572)
		(layer "B.Cu")
		(net "PVCCIN_CPU0_PVCC")
	)
	(segment
		(start 382.379728 -343.527888)
		(end 383.429256 -343.527888)
		(width 0.4572)
		(layer "B.Cu")
		(net "PVCCIN_CPU0_PVCC")
	)
	(segment
		(start 323.175884 -342.424004)
		(end 323.175884 -343.527888)
		(width 0.4572)
		(layer "B.Cu")
		(net "PVCCIN_CPU0_PVCC")
	)
	(segment
		(start 323.2277 -342.372188)
		(end 323.175884 -342.424004)
		(width 0.4572)
		(layer "B.Cu")
		(net "PVCCIN_CPU0_PVCC")
	)
	(segment
		(start 382.165352 -343.742264)
		(end 382.379728 -343.527888)
		(width 0.4572)
		(layer "B.Cu")
		(net "PVCCIN_CPU0_PVCC")
	)
	(segment
		(start 333.20228 -337.951572)
		(end 333.416656 -337.737196)
		(width 0.4572)
		(layer "B.Cu")
		(net "PVCCIN_CPU0_PVCC")
	)
	(segment
		(start 357.922068 -334.303116)
		(end 358.861868 -334.303116)
		(width 0.4572)
		(layer "B.Cu")
		(net "PVCCIN_CPU0_PVCC")
	)
	(segment
		(start 333.416656 -337.737196)
		(end 333.868014 -337.737196)
		(width 0.4572)
		(layer "B.Cu")
		(net "PVCCIN_CPU0_PVCC")
	)
	(segment
		(start 357.683816 -334.541368)
		(end 357.922068 -334.303116)
		(width 0.4572)
		(layer "B.Cu")
		(net "PVCCIN_CPU0_PVCC")
	)
	(segment
		(start 374.25757 -337.698842)
		(end 375.197116 -337.698842)
		(width 0.4572)
		(layer "B.Cu")
		(net "PVCCIN_CPU0_PVCC")
	)
	(segment
		(start 349.61957 -334.445102)
		(end 350.849438 -334.445102)
		(width 0.4572)
		(layer "B.Cu")
		(net "PVCCIN_CPU0_PVCC")
	)
	(segment
		(start 341.551768 -334.352392)
		(end 342.536526 -334.352392)
		(width 0.4572)
		(layer "B.Cu")
		(net "PVCCIN_CPU0_PVCC")
	)
	(segment
		(start 324.797928 -343.527888)
		(end 324.067424 -343.527888)
		(width 0.4572)
		(layer "B.Cu")
		(net "PVCCIN_CPU0_PVCC")
	)
	(segment
		(start 325.256144 -343.618312)
		(end 325.072248 -343.802208)
		(width 0.4572)
		(layer "B.Cu")
		(net "PVCCIN_CPU0_PVCC")
	)
	(segment
		(start 367.142522 -335.08569)
		(end 367.142522 -335.781396)
		(width 0.4064)
		(layer "In4.Cu")
		(net "PVCCIN_CPU0_PVCC")
	)
	(segment
		(start 325.88454 -343.802208)
		(end 326.272398 -344.190066)
		(width 0.508)
		(layer "In4.Cu")
		(net "PVCCIN_CPU0_PVCC")
	)
	(segment
		(start 361.205526 -335.035398)
		(end 361.75315 -334.487774)
		(width 0.508)
		(layer "In4.Cu")
		(net "PVCCIN_CPU0_PVCC")
	)
	(segment
		(start 333.393288 -339.20176)
		(end 333.972662 -338.96173)
		(width 0.508)
		(layer "In4.Cu")
		(net "PVCCIN_CPU0_PVCC")
	)
	(segment
		(start 345.194636 -334.781144)
		(end 345.645486 -334.330294)
		(width 0.508)
		(layer "In4.Cu")
		(net "PVCCIN_CPU0_PVCC")
	)
	(segment
		(start 334.526636 -338.483448)
		(end 336.682334 -338.483448)
		(width 0.508)
		(layer "In4.Cu")
		(net "PVCCIN_CPU0_PVCC")
	)
	(segment
		(start 365.790734 -334.487774)
		(end 365.844328 -334.541368)
		(width 0.508)
		(layer "In4.Cu")
		(net "PVCCIN_CPU0_PVCC")
	)
	(segment
		(start 350.57334 -334.961992)
		(end 353.131374 -334.961992)
		(width 0.508)
		(layer "In4.Cu")
		(net "PVCCIN_CPU0_PVCC")
	)
	(segment
		(start 332.91907 -339.675978)
		(end 333.393288 -339.20176)
		(width 0.508)
		(layer "In4.Cu")
		(net "PVCCIN_CPU0_PVCC")
	)
	(segment
		(start 382.165352 -343.742264)
		(end 381.418338 -343.742264)
		(width 0.4064)
		(layer "In4.Cu")
		(net "PVCCIN_CPU0_PVCC")
	)
	(segment
		(start 342.649302 -335.035398)
		(end 344.580972 -335.035398)
		(width 0.508)
		(layer "In4.Cu")
		(net "PVCCIN_CPU0_PVCC")
	)
	(segment
		(start 342.155272 -334.541368)
		(end 342.649302 -335.035398)
		(width 0.508)
		(layer "In4.Cu")
		(net "PVCCIN_CPU0_PVCC")
	)
	(segment
		(start 334.48879 -338.445602)
		(end 334.526636 -338.483448)
		(width 0.508)
		(layer "In4.Cu")
		(net "PVCCIN_CPU0_PVCC")
	)
	(segment
		(start 326.272398 -344.190066)
		(end 328.941176 -344.190066)
		(width 0.508)
		(layer "In4.Cu")
		(net "PVCCIN_CPU0_PVCC")
	)
	(segment
		(start 333.972662 -338.96173)
		(end 334.48879 -338.445602)
		(width 0.508)
		(layer "In4.Cu")
		(net "PVCCIN_CPU0_PVCC")
	)
	(segment
		(start 374.00484 -337.945222)
		(end 374.530112 -337.945222)
		(width 0.508)
		(layer "In4.Cu")
		(net "PVCCIN_CPU0_PVCC")
	)
	(segment
		(start 374.326404 -339.198712)
		(end 374.52427 -339.000846)
		(width 0.4064)
		(layer "In4.Cu")
		(net "PVCCIN_CPU0_PVCC")
	)
	(segment
		(start 374.530112 -337.945222)
		(end 374.98147 -338.39658)
		(width 0.508)
		(layer "In4.Cu")
		(net "PVCCIN_CPU0_PVCC")
	)
	(segment
		(start 337.473798 -337.691984)
		(end 339.561932 -337.691984)
		(width 0.508)
		(layer "In4.Cu")
		(net "PVCCIN_CPU0_PVCC")
	)
	(segment
		(start 336.682334 -338.483448)
		(end 337.473798 -337.691984)
		(width 0.508)
		(layer "In4.Cu")
		(net "PVCCIN_CPU0_PVCC")
	)
	(segment
		(start 358.762046 -335.035398)
		(end 361.205526 -335.035398)
		(width 0.508)
		(layer "In4.Cu")
		(net "PVCCIN_CPU0_PVCC")
	)
	(segment
		(start 332.37932 -340.48319)
		(end 332.91907 -339.675978)
		(width 0.508)
		(layer "In4.Cu")
		(net "PVCCIN_CPU0_PVCC")
	)
	(segment
		(start 350.152716 -334.541368)
		(end 350.57334 -334.961992)
		(width 0.508)
		(layer "In4.Cu")
		(net "PVCCIN_CPU0_PVCC")
	)
	(segment
		(start 377.866402 -340.190328)
		(end 376.3264 -340.190328)
		(width 0.4064)
		(layer "In4.Cu")
		(net "PVCCIN_CPU0_PVCC")
	)
	(segment
		(start 328.941176 -344.190066)
		(end 329.590908 -343.540334)
		(width 0.508)
		(layer "In4.Cu")
		(net "PVCCIN_CPU0_PVCC")
	)
	(segment
		(start 331.81036 -343.540334)
		(end 332.37932 -342.971374)
		(width 0.508)
		(layer "In4.Cu")
		(net "PVCCIN_CPU0_PVCC")
	)
	(segment
		(start 374.98147 -338.39658)
		(end 374.98147 -339.000846)
		(width 0.508)
		(layer "In4.Cu")
		(net "PVCCIN_CPU0_PVCC")
	)
	(segment
		(start 353.551998 -334.541368)
		(end 357.683816 -334.541368)
		(width 0.508)
		(layer "In4.Cu")
		(net "PVCCIN_CPU0_PVCC")
	)
	(segment
		(start 358.268016 -334.541368)
		(end 358.762046 -335.035398)
		(width 0.508)
		(layer "In4.Cu")
		(net "PVCCIN_CPU0_PVCC")
	)
	(segment
		(start 376.3264 -340.190328)
		(end 375.136918 -339.000846)
		(width 0.4064)
		(layer "In4.Cu")
		(net "PVCCIN_CPU0_PVCC")
	)
	(segment
		(start 325.072248 -343.802208)
		(end 325.88454 -343.802208)
		(width 0.508)
		(layer "In4.Cu")
		(net "PVCCIN_CPU0_PVCC")
	)
	(segment
		(start 367.628932 -336.267806)
		(end 368.350292 -336.56651)
		(width 0.4064)
		(layer "In4.Cu")
		(net "PVCCIN_CPU0_PVCC")
	)
	(segment
		(start 369.489228 -336.56651)
		(end 372.12143 -339.198712)
		(width 0.4064)
		(layer "In4.Cu")
		(net "PVCCIN_CPU0_PVCC")
	)
	(segment
		(start 349.31223 -334.330294)
		(end 349.523304 -334.541368)
		(width 0.508)
		(layer "In4.Cu")
		(net "PVCCIN_CPU0_PVCC")
	)
	(segment
		(start 365.844328 -334.541368)
		(end 366.5982 -334.541368)
		(width 0.4064)
		(layer "In4.Cu")
		(net "PVCCIN_CPU0_PVCC")
	)
	(segment
		(start 339.561932 -337.691984)
		(end 341.357204 -335.896712)
		(width 0.508)
		(layer "In4.Cu")
		(net "PVCCIN_CPU0_PVCC")
	)
	(segment
		(start 345.645486 -334.330294)
		(end 349.31223 -334.330294)
		(width 0.508)
		(layer "In4.Cu")
		(net "PVCCIN_CPU0_PVCC")
	)
	(segment
		(start 349.523304 -334.541368)
		(end 350.152716 -334.541368)
		(width 0.508)
		(layer "In4.Cu")
		(net "PVCCIN_CPU0_PVCC")
	)
	(segment
		(start 375.136918 -339.000846)
		(end 374.98147 -339.000846)
		(width 0.4064)
		(layer "In4.Cu")
		(net "PVCCIN_CPU0_PVCC")
	)
	(segment
		(start 344.580972 -335.035398)
		(end 345.194636 -334.781144)
		(width 0.508)
		(layer "In4.Cu")
		(net "PVCCIN_CPU0_PVCC")
	)
	(segment
		(start 333.99476 -337.951572)
		(end 334.48879 -338.445602)
		(width 0.508)
		(layer "In4.Cu")
		(net "PVCCIN_CPU0_PVCC")
	)
	(segment
		(start 333.20228 -337.951572)
		(end 333.99476 -337.951572)
		(width 0.508)
		(layer "In4.Cu")
		(net "PVCCIN_CPU0_PVCC")
	)
	(segment
		(start 372.12143 -339.198712)
		(end 374.326404 -339.198712)
		(width 0.4064)
		(layer "In4.Cu")
		(net "PVCCIN_CPU0_PVCC")
	)
	(segment
		(start 332.37932 -342.971374)
		(end 332.37932 -340.48319)
		(width 0.508)
		(layer "In4.Cu")
		(net "PVCCIN_CPU0_PVCC")
	)
	(segment
		(start 368.350292 -336.56651)
		(end 369.489228 -336.56651)
		(width 0.4064)
		(layer "In4.Cu")
		(net "PVCCIN_CPU0_PVCC")
	)
	(segment
		(start 341.357204 -335.896712)
		(end 342.092788 -335.591912)
		(width 0.508)
		(layer "In4.Cu")
		(net "PVCCIN_CPU0_PVCC")
	)
	(segment
		(start 366.5982 -334.541368)
		(end 367.142522 -335.08569)
		(width 0.4064)
		(layer "In4.Cu")
		(net "PVCCIN_CPU0_PVCC")
	)
	(segment
		(start 361.75315 -334.487774)
		(end 365.790734 -334.487774)
		(width 0.508)
		(layer "In4.Cu")
		(net "PVCCIN_CPU0_PVCC")
	)
	(segment
		(start 329.590908 -343.540334)
		(end 331.81036 -343.540334)
		(width 0.508)
		(layer "In4.Cu")
		(net "PVCCIN_CPU0_PVCC")
	)
	(segment
		(start 367.142522 -335.781396)
		(end 367.628932 -336.267806)
		(width 0.4064)
		(layer "In4.Cu")
		(net "PVCCIN_CPU0_PVCC")
	)
	(segment
		(start 341.362792 -334.541368)
		(end 342.155272 -334.541368)
		(width 0.508)
		(layer "In4.Cu")
		(net "PVCCIN_CPU0_PVCC")
	)
	(segment
		(start 342.092788 -335.591912)
		(end 342.649302 -335.035398)
		(width 0.508)
		(layer "In4.Cu")
		(net "PVCCIN_CPU0_PVCC")
	)
	(segment
		(start 357.683816 -334.541368)
		(end 358.268016 -334.541368)
		(width 0.508)
		(layer "In4.Cu")
		(net "PVCCIN_CPU0_PVCC")
	)
	(segment
		(start 374.52427 -339.000846)
		(end 374.98147 -339.000846)
		(width 0.4064)
		(layer "In4.Cu")
		(net "PVCCIN_CPU0_PVCC")
	)
	(segment
		(start 353.131374 -334.961992)
		(end 353.551998 -334.541368)
		(width 0.508)
		(layer "In4.Cu")
		(net "PVCCIN_CPU0_PVCC")
	)
	(segment
		(start 381.418338 -343.742264)
		(end 377.866402 -340.190328)
		(width 0.4064)
		(layer "In4.Cu")
		(net "PVCCIN_CPU0_PVCC")
	)
	(segment
		(start 351.80397 -358.959658)
		(end 352.11512 -358.648508)
		(width 0.1778)
		(layer "F.Cu")
		(net "PVCCIN_CPU0_PIN_ALERT")
	)
	(segment
		(start 352.11512 -358.648508)
		(end 353.643184 -358.648508)
		(width 0.1778)
		(layer "F.Cu")
		(net "PVCCIN_CPU0_PIN_ALERT")
	)
	(segment
		(start 349.420434 -358.906826)
		(end 349.473266 -358.959658)
		(width 0.1778)
		(layer "F.Cu")
		(net "PVCCIN_CPU0_PIN_ALERT")
	)
	(segment
		(start 349.006414 -359.799636)
		(end 349.006414 -358.906826)
		(width 0.254)
		(layer "F.Cu")
		(net "PVCCIN_CPU0_PIN_ALERT")
	)
	(segment
		(start 348.793054 -360.012996)
		(end 349.006414 -359.799636)
		(width 0.254)
		(layer "F.Cu")
		(net "PVCCIN_CPU0_PIN_ALERT")
	)
	(segment
		(start 349.473266 -358.959658)
		(end 351.80397 -358.959658)
		(width 0.1778)
		(layer "F.Cu")
		(net "PVCCIN_CPU0_PIN_ALERT")
	)
	(segment
		(start 349.006414 -358.906826)
		(end 349.420434 -358.906826)
		(width 0.1778)
		(layer "F.Cu")
		(net "PVCCIN_CPU0_PIN_ALERT")
	)
	(segment
		(start 384.650234 -345.816936)
		(end 384.650234 -346.140786)
		(width 0.12954)
		(layer "F.Cu")
		(net "PVCCIN_CPU0_LSET8")
	)
	(segment
		(start 384.277616 -346.59443)
		(end 384.277616 -346.916756)
		(width 0.12954)
		(layer "F.Cu")
		(net "PVCCIN_CPU0_LSET8")
	)
	(segment
		(start 384.277616 -346.916756)
		(end 384.277616 -347.933772)
		(width 0.12954)
		(layer "F.Cu")
		(net "PVCCIN_CPU0_LSET8")
	)
	(segment
		(start 384.59283 -346.279216)
		(end 384.277616 -346.59443)
		(width 0.12954)
		(layer "F.Cu")
		(net "PVCCIN_CPU0_LSET8")
	)
	(segment
		(start 384.277616 -347.933772)
		(end 384.251962 -347.959426)
		(width 0.12954)
		(layer "F.Cu")
		(net "PVCCIN_CPU0_LSET8")
	)
	(segment
		(start 384.650234 -346.140786)
		(end 384.59283 -346.279216)
		(width 0.12954)
		(layer "F.Cu")
		(net "PVCCIN_CPU0_LSET8")
	)
	(via
		(at 384.277616 -346.916756)
		(size 0.4064)
		(drill 0.2032)
		(layers "F.Cu" "B.Cu")
		(net "PVCCIN_CPU0_LSET8")
	)
	(segment
		(start 327.16216 -347.916754)
		(end 327.16216 -346.961206)
		(width 0.12954)
		(layer "F.Cu")
		(net "PVCCIN_CPU0_LSET7")
	)
	(segment
		(start 327.499726 -346.33916)
		(end 327.55713 -346.20073)
		(width 0.12954)
		(layer "F.Cu")
		(net "PVCCIN_CPU0_LSET7")
	)
	(segment
		(start 327.16216 -346.676726)
		(end 327.499726 -346.33916)
		(width 0.12954)
		(layer "F.Cu")
		(net "PVCCIN_CPU0_LSET7")
	)
	(segment
		(start 327.55713 -346.20073)
		(end 327.55713 -345.87688)
		(width 0.12954)
		(layer "F.Cu")
		(net "PVCCIN_CPU0_LSET7")
	)
	(segment
		(start 327.16216 -346.961206)
		(end 327.16216 -346.676726)
		(width 0.12954)
		(layer "F.Cu")
		(net "PVCCIN_CPU0_LSET7")
	)
	(segment
		(start 327.236328 -347.990922)
		(end 327.16216 -347.916754)
		(width 0.12954)
		(layer "F.Cu")
		(net "PVCCIN_CPU0_LSET7")
	)
	(via
		(at 327.16216 -346.961206)
		(size 0.4064)
		(drill 0.2032)
		(layers "F.Cu" "B.Cu")
		(net "PVCCIN_CPU0_LSET7")
	)
	(segment
		(start 335.08569 -342.270334)
		(end 335.314544 -342.04148)
		(width 0.12954)
		(layer "F.Cu")
		(net "PVCCIN_CPU0_LSET6")
	)
	(segment
		(start 335.314544 -340.803738)
		(end 335.629758 -340.488524)
		(width 0.12954)
		(layer "F.Cu")
		(net "PVCCIN_CPU0_LSET6")
	)
	(segment
		(start 335.687162 -340.350094)
		(end 335.687162 -340.026244)
		(width 0.12954)
		(layer "F.Cu")
		(net "PVCCIN_CPU0_LSET6")
	)
	(segment
		(start 335.314544 -341.209376)
		(end 335.314544 -340.803738)
		(width 0.12954)
		(layer "F.Cu")
		(net "PVCCIN_CPU0_LSET6")
	)
	(segment
		(start 335.629758 -340.488524)
		(end 335.687162 -340.350094)
		(width 0.12954)
		(layer "F.Cu")
		(net "PVCCIN_CPU0_LSET6")
	)
	(segment
		(start 335.314544 -342.04148)
		(end 335.314544 -341.209376)
		(width 0.12954)
		(layer "F.Cu")
		(net "PVCCIN_CPU0_LSET6")
	)
	(via
		(at 335.314544 -341.209376)
		(size 0.4064)
		(drill 0.2032)
		(layers "F.Cu" "B.Cu")
		(net "PVCCIN_CPU0_LSET6")
	)
	(segment
		(start 376.432318 -340.488524)
		(end 376.489722 -340.350094)
		(width 0.12954)
		(layer "F.Cu")
		(net "PVCCIN_CPU0_LSET5")
	)
	(segment
		(start 376.117104 -342.04148)
		(end 376.117104 -340.803738)
		(width 0.12954)
		(layer "F.Cu")
		(net "PVCCIN_CPU0_LSET5")
	)
	(segment
		(start 376.117104 -340.803738)
		(end 376.432318 -340.488524)
		(width 0.12954)
		(layer "F.Cu")
		(net "PVCCIN_CPU0_LSET5")
	)
	(segment
		(start 376.489722 -340.350094)
		(end 376.489722 -340.026244)
		(width 0.12954)
		(layer "F.Cu")
		(net "PVCCIN_CPU0_LSET5")
	)
	(segment
		(start 375.88825 -342.270334)
		(end 376.117104 -342.04148)
		(width 0.12954)
		(layer "F.Cu")
		(net "PVCCIN_CPU0_LSET5")
	)
	(segment
		(start 367.956592 -337.393534)
		(end 368.271806 -337.07832)
		(width 0.12954)
		(layer "F.Cu")
		(net "PVCCIN_CPU0_LSET4")
	)
	(segment
		(start 367.956592 -338.631276)
		(end 367.956592 -337.393534)
		(width 0.12954)
		(layer "F.Cu")
		(net "PVCCIN_CPU0_LSET4")
	)
	(segment
		(start 368.271806 -337.07832)
		(end 368.32921 -336.93989)
		(width 0.12954)
		(layer "F.Cu")
		(net "PVCCIN_CPU0_LSET4")
	)
	(segment
		(start 367.727738 -338.86013)
		(end 367.956592 -338.631276)
		(width 0.12954)
		(layer "F.Cu")
		(net "PVCCIN_CPU0_LSET4")
	)
	(segment
		(start 368.32921 -336.93989)
		(end 368.32921 -336.61604)
		(width 0.12954)
		(layer "F.Cu")
		(net "PVCCIN_CPU0_LSET4")
	)
	(segment
		(start 359.79608 -338.631276)
		(end 359.79608 -337.393534)
		(width 0.12954)
		(layer "F.Cu")
		(net "PVCCIN_CPU0_LSET3")
	)
	(segment
		(start 359.79608 -337.393534)
		(end 360.111294 -337.07832)
		(width 0.12954)
		(layer "F.Cu")
		(net "PVCCIN_CPU0_LSET3")
	)
	(segment
		(start 360.168698 -336.93989)
		(end 360.168698 -336.61604)
		(width 0.12954)
		(layer "F.Cu")
		(net "PVCCIN_CPU0_LSET3")
	)
	(segment
		(start 359.567226 -338.86013)
		(end 359.79608 -338.631276)
		(width 0.12954)
		(layer "F.Cu")
		(net "PVCCIN_CPU0_LSET3")
	)
	(segment
		(start 360.111294 -337.07832)
		(end 360.168698 -336.93989)
		(width 0.12954)
		(layer "F.Cu")
		(net "PVCCIN_CPU0_LSET3")
	)
	(segment
		(start 351.635568 -337.393534)
		(end 351.950782 -337.07832)
		(width 0.12954)
		(layer "F.Cu")
		(net "PVCCIN_CPU0_LSET2")
	)
	(segment
		(start 351.635568 -338.678012)
		(end 351.635568 -337.393534)
		(width 0.12954)
		(layer "F.Cu")
		(net "PVCCIN_CPU0_LSET2")
	)
	(segment
		(start 351.817686 -338.86013)
		(end 351.635568 -338.678012)
		(width 0.12954)
		(layer "F.Cu")
		(net "PVCCIN_CPU0_LSET2")
	)
	(segment
		(start 352.008186 -336.93989)
		(end 352.008186 -336.61604)
		(width 0.12954)
		(layer "F.Cu")
		(net "PVCCIN_CPU0_LSET2")
	)
	(segment
		(start 351.950782 -337.07832)
		(end 352.008186 -336.93989)
		(width 0.12954)
		(layer "F.Cu")
		(net "PVCCIN_CPU0_LSET2")
	)
	(segment
		(start 343.246202 -338.86013)
		(end 343.475056 -338.631276)
		(width 0.12954)
		(layer "F.Cu")
		(net "PVCCIN_CPU0_LSET1")
	)
	(segment
		(start 343.475056 -338.631276)
		(end 343.475056 -337.393534)
		(width 0.12954)
		(layer "F.Cu")
		(net "PVCCIN_CPU0_LSET1")
	)
	(segment
		(start 343.847674 -336.93989)
		(end 343.847674 -336.61604)
		(width 0.12954)
		(layer "F.Cu")
		(net "PVCCIN_CPU0_LSET1")
	)
	(segment
		(start 343.475056 -337.393534)
		(end 343.79027 -337.07832)
		(width 0.12954)
		(layer "F.Cu")
		(net "PVCCIN_CPU0_LSET1")
	)
	(segment
		(start 343.79027 -337.07832)
		(end 343.847674 -336.93989)
		(width 0.12954)
		(layer "F.Cu")
		(net "PVCCIN_CPU0_LSET1")
	)
	(segment
		(start 383.763012 -346.66301)
		(end 383.763012 -346.588334)
		(width 0.254)
		(layer "F.Cu")
		(net "PVCCIN_CPU0_IMON8")
	)
	(segment
		(start 357.918258 -355.126544)
		(end 357.918258 -355.97338)
		(width 0.1778)
		(layer "F.Cu")
		(net "PVCCIN_CPU0_IMON8")
	)
	(segment
		(start 383.763012 -346.588334)
		(end 384.200146 -346.1512)
		(width 0.254)
		(layer "F.Cu")
		(net "PVCCIN_CPU0_IMON8")
	)
	(segment
		(start 360.42346 -352.621342)
		(end 357.918258 -355.126544)
		(width 0.1778)
		(layer "F.Cu")
		(net "PVCCIN_CPU0_IMON8")
	)
	(segment
		(start 384.200146 -346.1512)
		(end 384.200146 -345.816936)
		(width 0.254)
		(layer "F.Cu")
		(net "PVCCIN_CPU0_IMON8")
	)
	(segment
		(start 360.42346 -352.412808)
		(end 360.42346 -352.621342)
		(width 0.1778)
		(layer "F.Cu")
		(net "PVCCIN_CPU0_IMON8")
	)
	(via
		(at 360.42346 -352.412808)
		(size 0.508)
		(drill 0.254)
		(layers "F.Cu" "B.Cu")
		(net "PVCCIN_CPU0_IMON8")
	)
	(via
		(at 383.763012 -346.66301)
		(size 0.508)
		(drill 0.254)
		(layers "F.Cu" "B.Cu")
		(net "PVCCIN_CPU0_IMON8")
	)
	(segment
		(start 367.897918 -352.694748)
		(end 372.613936 -347.97873)
		(width 0.254)
		(layer "In11.Cu")
		(net "PVCCIN_CPU0_IMON8")
	)
	(segment
		(start 384.308096 -347.977206)
		(end 384.308096 -347.208094)
		(width 0.254)
		(layer "In11.Cu")
		(net "PVCCIN_CPU0_IMON8")
	)
	(segment
		(start 372.613936 -347.97873)
		(end 379.32487 -347.97873)
		(width 0.254)
		(layer "In11.Cu")
		(net "PVCCIN_CPU0_IMON8")
	)
	(segment
		(start 384.308096 -347.208094)
		(end 383.763012 -346.66301)
		(width 0.254)
		(layer "In11.Cu")
		(net "PVCCIN_CPU0_IMON8")
	)
	(segment
		(start 383.336546 -348.948756)
		(end 384.308096 -347.977206)
		(width 0.254)
		(layer "In11.Cu")
		(net "PVCCIN_CPU0_IMON8")
	)
	(segment
		(start 380.294896 -348.948756)
		(end 383.336546 -348.948756)
		(width 0.254)
		(layer "In11.Cu")
		(net "PVCCIN_CPU0_IMON8")
	)
	(segment
		(start 379.32487 -347.97873)
		(end 380.294896 -348.948756)
		(width 0.254)
		(layer "In11.Cu")
		(net "PVCCIN_CPU0_IMON8")
	)
	(segment
		(start 360.7054 -352.694748)
		(end 367.897918 -352.694748)
		(width 0.254)
		(layer "In11.Cu")
		(net "PVCCIN_CPU0_IMON8")
	)
	(segment
		(start 360.42346 -352.412808)
		(end 360.7054 -352.694748)
		(width 0.254)
		(layer "In11.Cu")
		(net "PVCCIN_CPU0_IMON8")
	)
	(segment
		(start 357.518208 -354.772722)
		(end 357.518208 -355.97338)
		(width 0.1778)
		(layer "F.Cu")
		(net "PVCCIN_CPU0_IMON7")
	)
	(segment
		(start 358.802432 -353.488498)
		(end 357.518208 -354.772722)
		(width 0.1778)
		(layer "F.Cu")
		(net "PVCCIN_CPU0_IMON7")
	)
	(segment
		(start 326.669908 -346.722954)
		(end 326.669908 -346.648278)
		(width 0.254)
		(layer "F.Cu")
		(net "PVCCIN_CPU0_IMON7")
	)
	(segment
		(start 326.669908 -346.648278)
		(end 327.107042 -346.211144)
		(width 0.254)
		(layer "F.Cu")
		(net "PVCCIN_CPU0_IMON7")
	)
	(segment
		(start 327.107042 -346.211144)
		(end 327.107042 -345.87688)
		(width 0.254)
		(layer "F.Cu")
		(net "PVCCIN_CPU0_IMON7")
	)
	(via
		(at 326.669908 -346.722954)
		(size 0.508)
		(drill 0.254)
		(layers "F.Cu" "B.Cu")
		(net "PVCCIN_CPU0_IMON7")
	)
	(via
		(at 358.802432 -353.488498)
		(size 0.508)
		(drill 0.254)
		(layers "F.Cu" "B.Cu")
		(net "PVCCIN_CPU0_IMON7")
	)
	(segment
		(start 328.3077 -349.309944)
		(end 332.232254 -349.309944)
		(width 0.254)
		(layer "In11.Cu")
		(net "PVCCIN_CPU0_IMON7")
	)
	(segment
		(start 328.0664 -348.119446)
		(end 328.0664 -349.068644)
		(width 0.254)
		(layer "In11.Cu")
		(net "PVCCIN_CPU0_IMON7")
	)
	(segment
		(start 343.827354 -347.508322)
		(end 344.646504 -347.508322)
		(width 0.254)
		(layer "In11.Cu")
		(net "PVCCIN_CPU0_IMON7")
	)
	(segment
		(start 328.0664 -349.068644)
		(end 328.3077 -349.309944)
		(width 0.254)
		(layer "In11.Cu")
		(net "PVCCIN_CPU0_IMON7")
	)
	(segment
		(start 344.646504 -347.508322)
		(end 352.11893 -354.980748)
		(width 0.254)
		(layer "In11.Cu")
		(net "PVCCIN_CPU0_IMON7")
	)
	(segment
		(start 353.652328 -355.615748)
		(end 356.675182 -355.615748)
		(width 0.254)
		(layer "In11.Cu")
		(net "PVCCIN_CPU0_IMON7")
	)
	(segment
		(start 326.669908 -346.722954)
		(end 328.0664 -348.119446)
		(width 0.254)
		(layer "In11.Cu")
		(net "PVCCIN_CPU0_IMON7")
	)
	(segment
		(start 332.232254 -349.309944)
		(end 334.805274 -346.736924)
		(width 0.254)
		(layer "In11.Cu")
		(net "PVCCIN_CPU0_IMON7")
	)
	(segment
		(start 356.675182 -355.615748)
		(end 358.802432 -353.488498)
		(width 0.254)
		(layer "In11.Cu")
		(net "PVCCIN_CPU0_IMON7")
	)
	(segment
		(start 334.805274 -346.736924)
		(end 343.055956 -346.736924)
		(width 0.254)
		(layer "In11.Cu")
		(net "PVCCIN_CPU0_IMON7")
	)
	(segment
		(start 343.055956 -346.736924)
		(end 343.827354 -347.508322)
		(width 0.254)
		(layer "In11.Cu")
		(net "PVCCIN_CPU0_IMON7")
	)
	(segment
		(start 352.11893 -354.980748)
		(end 353.652328 -355.615748)
		(width 0.254)
		(layer "In11.Cu")
		(net "PVCCIN_CPU0_IMON7")
	)
	(segment
		(start 357.118158 -354.123244)
		(end 357.118158 -355.97338)
		(width 0.1778)
		(layer "F.Cu")
		(net "PVCCIN_CPU0_IMON6")
	)
	(segment
		(start 358.892094 -352.396298)
		(end 358.815894 -352.396298)
		(width 0.1778)
		(layer "F.Cu")
		(net "PVCCIN_CPU0_IMON6")
	)
	(segment
		(start 357.729536 -353.482656)
		(end 357.729536 -353.511866)
		(width 0.1778)
		(layer "F.Cu")
		(net "PVCCIN_CPU0_IMON6")
	)
	(segment
		(start 334.79994 -340.797642)
		(end 335.237074 -340.360508)
		(width 0.254)
		(layer "F.Cu")
		(net "PVCCIN_CPU0_IMON6")
	)
	(segment
		(start 334.79994 -340.872318)
		(end 334.79994 -340.797642)
		(width 0.254)
		(layer "F.Cu")
		(net "PVCCIN_CPU0_IMON6")
	)
	(segment
		(start 358.815894 -352.396298)
		(end 357.729536 -353.482656)
		(width 0.1778)
		(layer "F.Cu")
		(net "PVCCIN_CPU0_IMON6")
	)
	(segment
		(start 335.237074 -340.360508)
		(end 335.237074 -340.026244)
		(width 0.254)
		(layer "F.Cu")
		(net "PVCCIN_CPU0_IMON6")
	)
	(segment
		(start 357.729536 -353.511866)
		(end 357.118158 -354.123244)
		(width 0.1778)
		(layer "F.Cu")
		(net "PVCCIN_CPU0_IMON6")
	)
	(via
		(at 334.79994 -340.872318)
		(size 0.508)
		(drill 0.254)
		(layers "F.Cu" "B.Cu")
		(net "PVCCIN_CPU0_IMON6")
	)
	(via
		(at 357.729536 -353.511866)
		(size 0.762)
		(drill 0.381)
		(layers "F.Cu" "B.Cu")
		(net "PVCCIN_CPU0_IMON6")
	)
	(via
		(at 358.892094 -352.396298)
		(size 0.508)
		(drill 0.254)
		(layers "F.Cu" "B.Cu")
		(net "PVCCIN_CPU0_IMON6")
	)
	(segment
		(start 352.076258 -352.911918)
		(end 345.024456 -345.860116)
		(width 0.254)
		(layer "In11.Cu")
		(net "PVCCIN_CPU0_IMON6")
	)
	(segment
		(start 357.82123 -352.396298)
		(end 357.30561 -352.911918)
		(width 0.254)
		(layer "In11.Cu")
		(net "PVCCIN_CPU0_IMON6")
	)
	(segment
		(start 335.973166 -343.73058)
		(end 335.378552 -343.135966)
		(width 0.254)
		(layer "In11.Cu")
		(net "PVCCIN_CPU0_IMON6")
	)
	(segment
		(start 345.024456 -345.860116)
		(end 344.476832 -345.860116)
		(width 0.254)
		(layer "In11.Cu")
		(net "PVCCIN_CPU0_IMON6")
	)
	(segment
		(start 342.347296 -343.73058)
		(end 335.973166 -343.73058)
		(width 0.254)
		(layer "In11.Cu")
		(net "PVCCIN_CPU0_IMON6")
	)
	(segment
		(start 358.892094 -352.396298)
		(end 357.82123 -352.396298)
		(width 0.254)
		(layer "In11.Cu")
		(net "PVCCIN_CPU0_IMON6")
	)
	(segment
		(start 335.378552 -343.135966)
		(end 335.378552 -341.45093)
		(width 0.254)
		(layer "In11.Cu")
		(net "PVCCIN_CPU0_IMON6")
	)
	(segment
		(start 335.378552 -341.45093)
		(end 334.79994 -340.872318)
		(width 0.254)
		(layer "In11.Cu")
		(net "PVCCIN_CPU0_IMON6")
	)
	(segment
		(start 344.476832 -345.860116)
		(end 342.347296 -343.73058)
		(width 0.254)
		(layer "In11.Cu")
		(net "PVCCIN_CPU0_IMON6")
	)
	(segment
		(start 357.30561 -352.911918)
		(end 352.076258 -352.911918)
		(width 0.254)
		(layer "In11.Cu")
		(net "PVCCIN_CPU0_IMON6")
	)
	(segment
		(start 359.453434 -351.457768)
		(end 358.542844 -351.457768)
		(width 0.1778)
		(layer "F.Cu")
		(net "PVCCIN_CPU0_IMON5")
	)
	(segment
		(start 375.6025 -340.872318)
		(end 375.6025 -340.797642)
		(width 0.254)
		(layer "F.Cu")
		(net "PVCCIN_CPU0_IMON5")
	)
	(segment
		(start 356.718108 -353.282504)
		(end 356.718108 -355.97338)
		(width 0.1778)
		(layer "F.Cu")
		(net "PVCCIN_CPU0_IMON5")
	)
	(segment
		(start 375.6025 -340.797642)
		(end 376.039634 -340.360508)
		(width 0.254)
		(layer "F.Cu")
		(net "PVCCIN_CPU0_IMON5")
	)
	(segment
		(start 358.542844 -351.457768)
		(end 356.718108 -353.282504)
		(width 0.1778)
		(layer "F.Cu")
		(net "PVCCIN_CPU0_IMON5")
	)
	(segment
		(start 376.039634 -340.360508)
		(end 376.039634 -340.026244)
		(width 0.254)
		(layer "F.Cu")
		(net "PVCCIN_CPU0_IMON5")
	)
	(via
		(at 359.453434 -351.457768)
		(size 0.508)
		(drill 0.254)
		(layers "F.Cu" "B.Cu")
		(net "PVCCIN_CPU0_IMON5")
	)
	(via
		(at 375.6025 -340.872318)
		(size 0.508)
		(drill 0.254)
		(layers "F.Cu" "B.Cu")
		(net "PVCCIN_CPU0_IMON5")
	)
	(segment
		(start 365.667798 -346.634308)
		(end 374.711722 -346.634308)
		(width 0.254)
		(layer "In11.Cu")
		(net "PVCCIN_CPU0_IMON5")
	)
	(segment
		(start 359.453434 -351.060258)
		(end 360.044238 -350.469454)
		(width 0.254)
		(layer "In11.Cu")
		(net "PVCCIN_CPU0_IMON5")
	)
	(segment
		(start 361.832652 -350.469454)
		(end 365.667798 -346.634308)
		(width 0.254)
		(layer "In11.Cu")
		(net "PVCCIN_CPU0_IMON5")
	)
	(segment
		(start 360.044238 -350.469454)
		(end 361.832652 -350.469454)
		(width 0.254)
		(layer "In11.Cu")
		(net "PVCCIN_CPU0_IMON5")
	)
	(segment
		(start 374.711722 -346.634308)
		(end 376.1867 -345.15933)
		(width 0.254)
		(layer "In11.Cu")
		(net "PVCCIN_CPU0_IMON5")
	)
	(segment
		(start 376.1867 -345.15933)
		(end 376.1867 -341.456518)
		(width 0.254)
		(layer "In11.Cu")
		(net "PVCCIN_CPU0_IMON5")
	)
	(segment
		(start 376.1867 -341.456518)
		(end 375.6025 -340.872318)
		(width 0.254)
		(layer "In11.Cu")
		(net "PVCCIN_CPU0_IMON5")
	)
	(segment
		(start 359.453434 -351.457768)
		(end 359.453434 -351.060258)
		(width 0.254)
		(layer "In11.Cu")
		(net "PVCCIN_CPU0_IMON5")
	)
	(segment
		(start 357.241094 -351.500948)
		(end 356.318312 -352.42373)
		(width 0.1778)
		(layer "F.Cu")
		(net "PVCCIN_CPU0_IMON4")
	)
	(segment
		(start 367.441988 -337.462114)
		(end 367.441988 -337.387438)
		(width 0.254)
		(layer "F.Cu")
		(net "PVCCIN_CPU0_IMON4")
	)
	(segment
		(start 367.441988 -337.387438)
		(end 367.879122 -336.950304)
		(width 0.254)
		(layer "F.Cu")
		(net "PVCCIN_CPU0_IMON4")
	)
	(segment
		(start 356.318312 -352.42373)
		(end 356.318312 -355.97338)
		(width 0.1778)
		(layer "F.Cu")
		(net "PVCCIN_CPU0_IMON4")
	)
	(segment
		(start 367.879122 -336.950304)
		(end 367.879122 -336.61604)
		(width 0.254)
		(layer "F.Cu")
		(net "PVCCIN_CPU0_IMON4")
	)
	(via
		(at 357.241094 -351.500948)
		(size 0.762)
		(drill 0.254)
		(layers "F.Cu" "B.Cu")
		(net "PVCCIN_CPU0_IMON4")
	)
	(via
		(at 367.441988 -337.462114)
		(size 0.508)
		(drill 0.254)
		(layers "F.Cu" "B.Cu")
		(net "PVCCIN_CPU0_IMON4")
	)
	(segment
		(start 365.797592 -344.554048)
		(end 365.797592 -342.08466)
		(width 0.254)
		(layer "In11.Cu")
		(net "PVCCIN_CPU0_IMON4")
	)
	(segment
		(start 357.250746 -351.491296)
		(end 357.250746 -350.609408)
		(width 0.254)
		(layer "In11.Cu")
		(net "PVCCIN_CPU0_IMON4")
	)
	(segment
		(start 360.97972 -349.37192)
		(end 365.797592 -344.554048)
		(width 0.254)
		(layer "In11.Cu")
		(net "PVCCIN_CPU0_IMON4")
	)
	(segment
		(start 368.099086 -339.783166)
		(end 368.099086 -338.119212)
		(width 0.254)
		(layer "In11.Cu")
		(net "PVCCIN_CPU0_IMON4")
	)
	(segment
		(start 368.099086 -338.119212)
		(end 367.441988 -337.462114)
		(width 0.254)
		(layer "In11.Cu")
		(net "PVCCIN_CPU0_IMON4")
	)
	(segment
		(start 365.797592 -342.08466)
		(end 368.099086 -339.783166)
		(width 0.254)
		(layer "In11.Cu")
		(net "PVCCIN_CPU0_IMON4")
	)
	(segment
		(start 358.488234 -349.37192)
		(end 360.97972 -349.37192)
		(width 0.254)
		(layer "In11.Cu")
		(net "PVCCIN_CPU0_IMON4")
	)
	(segment
		(start 357.241094 -351.500948)
		(end 357.250746 -351.491296)
		(width 0.254)
		(layer "In11.Cu")
		(net "PVCCIN_CPU0_IMON4")
	)
	(segment
		(start 357.250746 -350.609408)
		(end 358.488234 -349.37192)
		(width 0.254)
		(layer "In11.Cu")
		(net "PVCCIN_CPU0_IMON4")
	)
	(segment
		(start 359.281476 -337.387438)
		(end 359.71861 -336.950304)
		(width 0.254)
		(layer "F.Cu")
		(net "PVCCIN_CPU0_IMON3")
	)
	(segment
		(start 355.918262 -351.809812)
		(end 355.918262 -355.97338)
		(width 0.1778)
		(layer "F.Cu")
		(net "PVCCIN_CPU0_IMON3")
	)
	(segment
		(start 356.02037 -351.707704)
		(end 355.918262 -351.809812)
		(width 0.1778)
		(layer "F.Cu")
		(net "PVCCIN_CPU0_IMON3")
	)
	(segment
		(start 359.71861 -336.950304)
		(end 359.71861 -336.61604)
		(width 0.254)
		(layer "F.Cu")
		(net "PVCCIN_CPU0_IMON3")
	)
	(segment
		(start 359.281476 -337.462114)
		(end 359.281476 -337.387438)
		(width 0.254)
		(layer "F.Cu")
		(net "PVCCIN_CPU0_IMON3")
	)
	(via
		(at 356.02037 -351.707704)
		(size 0.508)
		(drill 0.254)
		(layers "F.Cu" "B.Cu")
		(net "PVCCIN_CPU0_IMON3")
	)
	(via
		(at 359.281476 -337.462114)
		(size 0.508)
		(drill 0.254)
		(layers "F.Cu" "B.Cu")
		(net "PVCCIN_CPU0_IMON3")
	)
	(segment
		(start 359.789476 -340.49208)
		(end 358.255316 -342.02624)
		(width 0.254)
		(layer "In11.Cu")
		(net "PVCCIN_CPU0_IMON3")
	)
	(segment
		(start 359.281476 -337.462114)
		(end 359.789476 -337.970114)
		(width 0.254)
		(layer "In11.Cu")
		(net "PVCCIN_CPU0_IMON3")
	)
	(segment
		(start 356.2096 -351.518474)
		(end 356.02037 -351.707704)
		(width 0.254)
		(layer "In11.Cu")
		(net "PVCCIN_CPU0_IMON3")
	)
	(segment
		(start 356.225094 -351.454974)
		(end 356.2096 -351.470468)
		(width 0.254)
		(layer "In11.Cu")
		(net "PVCCIN_CPU0_IMON3")
	)
	(segment
		(start 358.255316 -347.408754)
		(end 356.225094 -349.438976)
		(width 0.254)
		(layer "In11.Cu")
		(net "PVCCIN_CPU0_IMON3")
	)
	(segment
		(start 356.2096 -351.470468)
		(end 356.2096 -351.518474)
		(width 0.254)
		(layer "In11.Cu")
		(net "PVCCIN_CPU0_IMON3")
	)
	(segment
		(start 359.789476 -337.970114)
		(end 359.789476 -340.49208)
		(width 0.254)
		(layer "In11.Cu")
		(net "PVCCIN_CPU0_IMON3")
	)
	(segment
		(start 356.225094 -349.438976)
		(end 356.225094 -351.454974)
		(width 0.254)
		(layer "In11.Cu")
		(net "PVCCIN_CPU0_IMON3")
	)
	(segment
		(start 358.255316 -342.02624)
		(end 358.255316 -347.408754)
		(width 0.254)
		(layer "In11.Cu")
		(net "PVCCIN_CPU0_IMON3")
	)
	(segment
		(start 351.120964 -337.387438)
		(end 351.558098 -336.950304)
		(width 0.254)
		(layer "F.Cu")
		(net "PVCCIN_CPU0_IMON2")
	)
	(segment
		(start 351.558098 -336.950304)
		(end 351.558098 -336.61604)
		(width 0.254)
		(layer "F.Cu")
		(net "PVCCIN_CPU0_IMON2")
	)
	(segment
		(start 355.518212 -351.810066)
		(end 355.518212 -355.97338)
		(width 0.1778)
		(layer "F.Cu")
		(net "PVCCIN_CPU0_IMON2")
	)
	(segment
		(start 355.26472 -351.556574)
		(end 355.518212 -351.810066)
		(width 0.1778)
		(layer "F.Cu")
		(net "PVCCIN_CPU0_IMON2")
	)
	(segment
		(start 351.120964 -337.462114)
		(end 351.120964 -337.387438)
		(width 0.254)
		(layer "F.Cu")
		(net "PVCCIN_CPU0_IMON2")
	)
	(segment
		(start 355.26472 -350.667828)
		(end 355.26472 -351.556574)
		(width 0.1778)
		(layer "F.Cu")
		(net "PVCCIN_CPU0_IMON2")
	)
	(via
		(at 351.120964 -337.462114)
		(size 0.508)
		(drill 0.254)
		(layers "F.Cu" "B.Cu")
		(net "PVCCIN_CPU0_IMON2")
	)
	(via
		(at 355.26472 -350.667828)
		(size 0.508)
		(drill 0.254)
		(layers "F.Cu" "B.Cu")
		(net "PVCCIN_CPU0_IMON2")
	)
	(segment
		(start 354.653342 -346.072206)
		(end 351.65919 -346.072206)
		(width 0.254)
		(layer "In11.Cu")
		(net "PVCCIN_CPU0_IMON2")
	)
	(segment
		(start 355.26472 -346.683584)
		(end 354.653342 -346.072206)
		(width 0.254)
		(layer "In11.Cu")
		(net "PVCCIN_CPU0_IMON2")
	)
	(segment
		(start 351.755964 -338.097114)
		(end 351.120964 -337.462114)
		(width 0.254)
		(layer "In11.Cu")
		(net "PVCCIN_CPU0_IMON2")
	)
	(segment
		(start 350.860106 -341.237062)
		(end 351.755964 -340.341204)
		(width 0.254)
		(layer "In11.Cu")
		(net "PVCCIN_CPU0_IMON2")
	)
	(segment
		(start 351.65919 -346.072206)
		(end 350.860106 -345.273122)
		(width 0.254)
		(layer "In11.Cu")
		(net "PVCCIN_CPU0_IMON2")
	)
	(segment
		(start 355.26472 -350.667828)
		(end 355.26472 -346.683584)
		(width 0.254)
		(layer "In11.Cu")
		(net "PVCCIN_CPU0_IMON2")
	)
	(segment
		(start 351.755964 -340.341204)
		(end 351.755964 -338.097114)
		(width 0.254)
		(layer "In11.Cu")
		(net "PVCCIN_CPU0_IMON2")
	)
	(segment
		(start 350.860106 -345.273122)
		(end 350.860106 -341.237062)
		(width 0.254)
		(layer "In11.Cu")
		(net "PVCCIN_CPU0_IMON2")
	)
	(segment
		(start 342.960452 -337.462114)
		(end 342.960452 -337.387438)
		(width 0.254)
		(layer "F.Cu")
		(net "PVCCIN_CPU0_IMON1")
	)
	(segment
		(start 354.662994 -351.970848)
		(end 355.118162 -352.426016)
		(width 0.1778)
		(layer "F.Cu")
		(net "PVCCIN_CPU0_IMON1")
	)
	(segment
		(start 355.118162 -352.426016)
		(end 355.118162 -355.97338)
		(width 0.1778)
		(layer "F.Cu")
		(net "PVCCIN_CPU0_IMON1")
	)
	(segment
		(start 342.960452 -337.387438)
		(end 343.397586 -336.950304)
		(width 0.254)
		(layer "F.Cu")
		(net "PVCCIN_CPU0_IMON1")
	)
	(segment
		(start 343.397586 -336.950304)
		(end 343.397586 -336.61604)
		(width 0.254)
		(layer "F.Cu")
		(net "PVCCIN_CPU0_IMON1")
	)
	(via
		(at 342.960452 -337.462114)
		(size 0.508)
		(drill 0.254)
		(layers "F.Cu" "B.Cu")
		(net "PVCCIN_CPU0_IMON1")
	)
	(via
		(at 354.662994 -351.970848)
		(size 0.508)
		(drill 0.254)
		(layers "F.Cu" "B.Cu")
		(net "PVCCIN_CPU0_IMON1")
	)
	(segment
		(start 344.147394 -340.664546)
		(end 343.610438 -340.12759)
		(width 0.254)
		(layer "In11.Cu")
		(net "PVCCIN_CPU0_IMON1")
	)
	(segment
		(start 354.2538 -348.873572)
		(end 353.305364 -347.925136)
		(width 0.254)
		(layer "In11.Cu")
		(net "PVCCIN_CPU0_IMON1")
	)
	(segment
		(start 343.610438 -340.12759)
		(end 343.610438 -338.1121)
		(width 0.254)
		(layer "In11.Cu")
		(net "PVCCIN_CPU0_IMON1")
	)
	(segment
		(start 350.65081 -347.925136)
		(end 349.343472 -346.617798)
		(width 0.254)
		(layer "In11.Cu")
		(net "PVCCIN_CPU0_IMON1")
	)
	(segment
		(start 349.343472 -341.987632)
		(end 348.020386 -340.664546)
		(width 0.254)
		(layer "In11.Cu")
		(net "PVCCIN_CPU0_IMON1")
	)
	(segment
		(start 349.343472 -346.617798)
		(end 349.343472 -341.987632)
		(width 0.254)
		(layer "In11.Cu")
		(net "PVCCIN_CPU0_IMON1")
	)
	(segment
		(start 353.305364 -347.925136)
		(end 350.65081 -347.925136)
		(width 0.254)
		(layer "In11.Cu")
		(net "PVCCIN_CPU0_IMON1")
	)
	(segment
		(start 354.2538 -351.104454)
		(end 354.2538 -348.873572)
		(width 0.254)
		(layer "In11.Cu")
		(net "PVCCIN_CPU0_IMON1")
	)
	(segment
		(start 343.610438 -338.1121)
		(end 342.960452 -337.462114)
		(width 0.254)
		(layer "In11.Cu")
		(net "PVCCIN_CPU0_IMON1")
	)
	(segment
		(start 348.020386 -340.664546)
		(end 344.147394 -340.664546)
		(width 0.254)
		(layer "In11.Cu")
		(net "PVCCIN_CPU0_IMON1")
	)
	(segment
		(start 354.662994 -351.970848)
		(end 354.662994 -351.513648)
		(width 0.254)
		(layer "In11.Cu")
		(net "PVCCIN_CPU0_IMON1")
	)
	(segment
		(start 354.662994 -351.513648)
		(end 354.2538 -351.104454)
		(width 0.254)
		(layer "In11.Cu")
		(net "PVCCIN_CPU0_IMON1")
	)
	(segment
		(start 353.217734 -359.448354)
		(end 353.643184 -359.448354)
		(width 0.12954)
		(layer "F.Cu")
		(net "PVCCIN_CPU0_EN_R")
	)
	(segment
		(start 352.41738 -360.248708)
		(end 353.217734 -359.448354)
		(width 0.12954)
		(layer "F.Cu")
		(net "PVCCIN_CPU0_EN_R")
	)
	(via
		(at 352.41738 -360.248708)
		(size 0.508)
		(drill 0.254)
		(layers "F.Cu" "B.Cu")
		(net "PVCCIN_CPU0_EN_R")
	)
	(via
		(at 353.6696 -360.63555)
		(size 0.6604)
		(drill 0.3302)
		(layers "F.Cu" "B.Cu")
		(net "PVCCIN_CPU0_EN_R")
	)
	(segment
		(start 351.921572 -360.248708)
		(end 351.66808 -359.995216)
		(width 0.12954)
		(layer "B.Cu")
		(net "PVCCIN_CPU0_EN_R")
	)
	(segment
		(start 353.299522 -360.63555)
		(end 352.91268 -360.248708)
		(width 0.12954)
		(layer "B.Cu")
		(net "PVCCIN_CPU0_EN_R")
	)
	(segment
		(start 353.821238 -359.47985)
		(end 353.821238 -360.483912)
		(width 0.12954)
		(layer "B.Cu")
		(net "PVCCIN_CPU0_EN_R")
	)
	(segment
		(start 352.91268 -360.248708)
		(end 352.41738 -360.248708)
		(width 0.12954)
		(layer "B.Cu")
		(net "PVCCIN_CPU0_EN_R")
	)
	(segment
		(start 353.6696 -360.63555)
		(end 353.299522 -360.63555)
		(width 0.12954)
		(layer "B.Cu")
		(net "PVCCIN_CPU0_EN_R")
	)
	(segment
		(start 353.821238 -360.483912)
		(end 353.6696 -360.63555)
		(width 0.12954)
		(layer "B.Cu")
		(net "PVCCIN_CPU0_EN_R")
	)
	(segment
		(start 352.41738 -360.248708)
		(end 351.921572 -360.248708)
		(width 0.12954)
		(layer "B.Cu")
		(net "PVCCIN_CPU0_EN_R")
	)
	(segment
		(start 360.110532 -359.848404)
		(end 360.873548 -360.61142)
		(width 0.1778)
		(layer "F.Cu")
		(net "PVCCIN_CPU0_CSPIN")
	)
	(segment
		(start 359.393236 -359.848404)
		(end 360.110532 -359.848404)
		(width 0.1778)
		(layer "F.Cu")
		(net "PVCCIN_CPU0_CSPIN")
	)
	(segment
		(start 361.584748 -360.61142)
		(end 362.246418 -359.94975)
		(width 0.1778)
		(layer "F.Cu")
		(net "PVCCIN_CPU0_CSPIN")
	)
	(segment
		(start 360.873548 -360.61142)
		(end 361.153456 -360.61142)
		(width 0.1778)
		(layer "F.Cu")
		(net "PVCCIN_CPU0_CSPIN")
	)
	(segment
		(start 361.153456 -360.61142)
		(end 361.584748 -360.61142)
		(width 0.1778)
		(layer "F.Cu")
		(net "PVCCIN_CPU0_CSPIN")
	)
	(via
		(at 361.153456 -360.61142)
		(size 0.508)
		(drill 0.254)
		(layers "F.Cu" "B.Cu")
		(net "PVCCIN_CPU0_CSPIN")
	)
	(segment
		(start 361.153456 -360.61142)
		(end 361.360212 -360.818176)
		(width 0.254)
		(layer "B.Cu")
		(net "PVCCIN_CPU0_CSPIN")
	)
	(segment
		(start 359.579164 -359.47985)
		(end 360.710734 -360.61142)
		(width 0.254)
		(layer "B.Cu")
		(net "PVCCIN_CPU0_CSPIN")
	)
	(segment
		(start 361.360212 -360.818176)
		(end 362.31449 -360.818176)
		(width 0.254)
		(layer "B.Cu")
		(net "PVCCIN_CPU0_CSPIN")
	)
	(segment
		(start 360.710734 -360.61142)
		(end 361.153456 -360.61142)
		(width 0.254)
		(layer "B.Cu")
		(net "PVCCIN_CPU0_CSPIN")
	)
	(segment
		(start 359.2068 -359.47985)
		(end 359.579164 -359.47985)
		(width 0.254)
		(layer "B.Cu")
		(net "PVCCIN_CPU0_CSPIN")
	)
	(segment
		(start 335.831434 -341.059516)
		(end 336.136996 -340.321392)
		(width 0.254)
		(layer "F.Cu")
		(net "PVCCIN_CPU0_ATSEN")
	)
	(segment
		(start 360.618532 -336.911188)
		(end 360.618532 -336.61604)
		(width 0.254)
		(layer "F.Cu")
		(net "PVCCIN_CPU0_ATSEN")
	)
	(segment
		(start 343.991946 -337.649312)
		(end 344.297508 -336.911188)
		(width 0.254)
		(layer "F.Cu")
		(net "PVCCIN_CPU0_ATSEN")
	)
	(segment
		(start 384.794252 -346.850462)
		(end 384.794506 -346.850208)
		(width 0.254)
		(layer "F.Cu")
		(net "PVCCIN_CPU0_ATSEN")
	)
	(segment
		(start 368.473482 -337.649312)
		(end 368.779044 -336.911188)
		(width 0.254)
		(layer "F.Cu")
		(net "PVCCIN_CPU0_ATSEN")
	)
	(segment
		(start 360.297476 -337.649566)
		(end 360.312716 -337.649566)
		(width 0.254)
		(layer "F.Cu")
		(net "PVCCIN_CPU0_ATSEN")
	)
	(segment
		(start 343.976452 -337.649566)
		(end 343.991692 -337.649566)
		(width 0.254)
		(layer "F.Cu")
		(net "PVCCIN_CPU0_ATSEN")
	)
	(segment
		(start 361.028234 -358.576626)
		(end 360.93019 -358.576626)
		(width 0.1778)
		(layer "F.Cu")
		(net "PVCCIN_CPU0_ATSEN")
	)
	(segment
		(start 376.633994 -341.059516)
		(end 376.939556 -340.321392)
		(width 0.254)
		(layer "F.Cu")
		(net "PVCCIN_CPU0_ATSEN")
	)
	(segment
		(start 368.473228 -337.649566)
		(end 368.473482 -337.649312)
		(width 0.254)
		(layer "F.Cu")
		(net "PVCCIN_CPU0_ATSEN")
	)
	(segment
		(start 384.779012 -346.850462)
		(end 384.794252 -346.850462)
		(width 0.254)
		(layer "F.Cu")
		(net "PVCCIN_CPU0_ATSEN")
	)
	(segment
		(start 360.93019 -358.576626)
		(end 360.458512 -359.048304)
		(width 0.1778)
		(layer "F.Cu")
		(net "PVCCIN_CPU0_ATSEN")
	)
	(segment
		(start 376.63374 -341.05977)
		(end 376.633994 -341.059516)
		(width 0.254)
		(layer "F.Cu")
		(net "PVCCIN_CPU0_ATSEN")
	)
	(segment
		(start 335.83118 -341.05977)
		(end 335.831434 -341.059516)
		(width 0.254)
		(layer "F.Cu")
		(net "PVCCIN_CPU0_ATSEN")
	)
	(segment
		(start 327.701148 -346.910406)
		(end 327.701402 -346.910152)
		(width 0.254)
		(layer "F.Cu")
		(net "PVCCIN_CPU0_ATSEN")
	)
	(segment
		(start 360.31297 -337.649312)
		(end 360.618532 -336.911188)
		(width 0.254)
		(layer "F.Cu")
		(net "PVCCIN_CPU0_ATSEN")
	)
	(segment
		(start 352.45802 -336.911188)
		(end 352.45802 -336.61604)
		(width 0.254)
		(layer "F.Cu")
		(net "PVCCIN_CPU0_ATSEN")
	)
	(segment
		(start 335.81594 -341.05977)
		(end 335.83118 -341.05977)
		(width 0.254)
		(layer "F.Cu")
		(net "PVCCIN_CPU0_ATSEN")
	)
	(segment
		(start 368.457988 -337.649566)
		(end 368.473228 -337.649566)
		(width 0.254)
		(layer "F.Cu")
		(net "PVCCIN_CPU0_ATSEN")
	)
	(segment
		(start 352.136964 -337.649566)
		(end 352.152204 -337.649566)
		(width 0.254)
		(layer "F.Cu")
		(net "PVCCIN_CPU0_ATSEN")
	)
	(segment
		(start 368.779044 -336.911188)
		(end 368.779044 -336.61604)
		(width 0.254)
		(layer "F.Cu")
		(net "PVCCIN_CPU0_ATSEN")
	)
	(segment
		(start 362.246418 -357.91775)
		(end 361.587542 -358.576626)
		(width 0.12954)
		(layer "F.Cu")
		(net "PVCCIN_CPU0_ATSEN")
	)
	(segment
		(start 361.587542 -358.576626)
		(end 361.028234 -358.576626)
		(width 0.12954)
		(layer "F.Cu")
		(net "PVCCIN_CPU0_ATSEN")
	)
	(segment
		(start 344.297508 -336.911188)
		(end 344.297508 -336.61604)
		(width 0.254)
		(layer "F.Cu")
		(net "PVCCIN_CPU0_ATSEN")
	)
	(segment
		(start 328.006964 -346.172028)
		(end 328.006964 -345.87688)
		(width 0.254)
		(layer "F.Cu")
		(net "PVCCIN_CPU0_ATSEN")
	)
	(segment
		(start 336.136996 -340.321392)
		(end 336.136996 -340.026244)
		(width 0.254)
		(layer "F.Cu")
		(net "PVCCIN_CPU0_ATSEN")
	)
	(segment
		(start 327.685908 -346.910406)
		(end 327.701148 -346.910406)
		(width 0.254)
		(layer "F.Cu")
		(net "PVCCIN_CPU0_ATSEN")
	)
	(segment
		(start 384.794506 -346.850208)
		(end 385.100068 -346.112084)
		(width 0.254)
		(layer "F.Cu")
		(net "PVCCIN_CPU0_ATSEN")
	)
	(segment
		(start 327.701402 -346.910152)
		(end 328.006964 -346.172028)
		(width 0.254)
		(layer "F.Cu")
		(net "PVCCIN_CPU0_ATSEN")
	)
	(segment
		(start 360.312716 -337.649566)
		(end 360.31297 -337.649312)
		(width 0.254)
		(layer "F.Cu")
		(net "PVCCIN_CPU0_ATSEN")
	)
	(segment
		(start 352.152458 -337.649312)
		(end 352.45802 -336.911188)
		(width 0.254)
		(layer "F.Cu")
		(net "PVCCIN_CPU0_ATSEN")
	)
	(segment
		(start 360.458512 -359.048304)
		(end 359.393236 -359.048304)
		(width 0.1778)
		(layer "F.Cu")
		(net "PVCCIN_CPU0_ATSEN")
	)
	(segment
		(start 385.100068 -346.112084)
		(end 385.100068 -345.816936)
		(width 0.254)
		(layer "F.Cu")
		(net "PVCCIN_CPU0_ATSEN")
	)
	(segment
		(start 343.991692 -337.649566)
		(end 343.991946 -337.649312)
		(width 0.254)
		(layer "F.Cu")
		(net "PVCCIN_CPU0_ATSEN")
	)
	(segment
		(start 376.939556 -340.321392)
		(end 376.939556 -340.026244)
		(width 0.254)
		(layer "F.Cu")
		(net "PVCCIN_CPU0_ATSEN")
	)
	(segment
		(start 376.6185 -341.05977)
		(end 376.63374 -341.05977)
		(width 0.254)
		(layer "F.Cu")
		(net "PVCCIN_CPU0_ATSEN")
	)
	(segment
		(start 352.152204 -337.649566)
		(end 352.152458 -337.649312)
		(width 0.254)
		(layer "F.Cu")
		(net "PVCCIN_CPU0_ATSEN")
	)
	(via
		(at 361.028234 -358.576626)
		(size 0.508)
		(drill 0.254)
		(layers "F.Cu" "B.Cu")
		(net "PVCCIN_CPU0_ATSEN")
	)
	(via
		(at 368.457988 -337.649566)
		(size 0.508)
		(drill 0.254)
		(layers "F.Cu" "B.Cu")
		(net "PVCCIN_CPU0_ATSEN")
	)
	(via
		(at 352.136964 -337.649566)
		(size 0.508)
		(drill 0.254)
		(layers "F.Cu" "B.Cu")
		(net "PVCCIN_CPU0_ATSEN")
	)
	(via
		(at 327.685908 -346.910406)
		(size 0.508)
		(drill 0.254)
		(layers "F.Cu" "B.Cu")
		(net "PVCCIN_CPU0_ATSEN")
	)
	(via
		(at 384.779012 -346.850462)
		(size 0.508)
		(drill 0.254)
		(layers "F.Cu" "B.Cu")
		(net "PVCCIN_CPU0_ATSEN")
	)
	(via
		(at 376.6185 -341.05977)
		(size 0.508)
		(drill 0.254)
		(layers "F.Cu" "B.Cu")
		(net "PVCCIN_CPU0_ATSEN")
	)
	(via
		(at 343.976452 -337.649566)
		(size 0.508)
		(drill 0.254)
		(layers "F.Cu" "B.Cu")
		(net "PVCCIN_CPU0_ATSEN")
	)
	(via
		(at 335.81594 -341.05977)
		(size 0.508)
		(drill 0.254)
		(layers "F.Cu" "B.Cu")
		(net "PVCCIN_CPU0_ATSEN")
	)
	(via
		(at 360.297476 -337.649566)
		(size 0.508)
		(drill 0.254)
		(layers "F.Cu" "B.Cu")
		(net "PVCCIN_CPU0_ATSEN")
	)
	(segment
		(start 361.028234 -358.576626)
		(end 361.648248 -358.576626)
		(width 0.254)
		(layer "B.Cu")
		(net "PVCCIN_CPU0_ATSEN")
	)
	(segment
		(start 361.747054 -358.675432)
		(end 362.229654 -358.675432)
		(width 0.254)
		(layer "B.Cu")
		(net "PVCCIN_CPU0_ATSEN")
	)
	(segment
		(start 361.648248 -358.576626)
		(end 361.747054 -358.675432)
		(width 0.254)
		(layer "B.Cu")
		(net "PVCCIN_CPU0_ATSEN")
	)
	(segment
		(start 351.882964 -337.754722)
		(end 352.136964 -337.649566)
		(width 0.254)
		(layer "In4.Cu")
		(net "PVCCIN_CPU0_ATSEN")
	)
	(segment
		(start 344.918792 -340.130384)
		(end 351.01149 -340.130384)
		(width 0.254)
		(layer "In4.Cu")
		(net "PVCCIN_CPU0_ATSEN")
	)
	(segment
		(start 343.976452 -339.188044)
		(end 344.918792 -340.130384)
		(width 0.254)
		(layer "In4.Cu")
		(net "PVCCIN_CPU0_ATSEN")
	)
	(segment
		(start 335.81594 -341.05977)
		(end 335.937098 -341.180928)
		(width 0.254)
		(layer "In4.Cu")
		(net "PVCCIN_CPU0_ATSEN")
	)
	(segment
		(start 334.392524 -343.894664)
		(end 335.393538 -342.89365)
		(width 0.254)
		(layer "In4.Cu")
		(net "PVCCIN_CPU0_ATSEN")
	)
	(segment
		(start 343.639648 -337.789266)
		(end 343.976452 -337.649566)
		(width 0.254)
		(layer "In4.Cu")
		(net "PVCCIN_CPU0_ATSEN")
	)
	(segment
		(start 335.937098 -342.604852)
		(end 336.573114 -343.240868)
		(width 0.254)
		(layer "In4.Cu")
		(net "PVCCIN_CPU0_ATSEN")
	)
	(segment
		(start 367.266474 -340.1441)
		(end 368.009932 -339.400642)
		(width 0.254)
		(layer "In4.Cu")
		(net "PVCCIN_CPU0_ATSEN")
	)
	(segment
		(start 352.136964 -337.649566)
		(end 352.136964 -339.188044)
		(width 0.254)
		(layer "In4.Cu")
		(net "PVCCIN_CPU0_ATSEN")
	)
	(segment
		(start 335.393538 -342.89365)
		(end 335.393538 -341.31377)
		(width 0.254)
		(layer "In4.Cu")
		(net "PVCCIN_CPU0_ATSEN")
	)
	(segment
		(start 335.647538 -341.05977)
		(end 335.81594 -341.05977)
		(width 0.254)
		(layer "In4.Cu")
		(net "PVCCIN_CPU0_ATSEN")
	)
	(segment
		(start 353.079558 -340.130638)
		(end 359.021634 -340.130638)
		(width 0.254)
		(layer "In4.Cu")
		(net "PVCCIN_CPU0_ATSEN")
	)
	(segment
		(start 368.457988 -337.649566)
		(end 368.457988 -339.188044)
		(width 0.254)
		(layer "In4.Cu")
		(net "PVCCIN_CPU0_ATSEN")
	)
	(segment
		(start 336.573114 -343.240868)
		(end 340.874858 -343.240868)
		(width 0.254)
		(layer "In4.Cu")
		(net "PVCCIN_CPU0_ATSEN")
	)
	(segment
		(start 383.393696 -345.047062)
		(end 384.779012 -346.432378)
		(width 0.254)
		(layer "In4.Cu")
		(net "PVCCIN_CPU0_ATSEN")
	)
	(segment
		(start 362.184696 -358.576626)
		(end 361.028234 -358.576626)
		(width 0.254)
		(layer "In4.Cu")
		(net "PVCCIN_CPU0_ATSEN")
	)
	(segment
		(start 352.136964 -339.188044)
		(end 353.079558 -340.130638)
		(width 0.254)
		(layer "In4.Cu")
		(net "PVCCIN_CPU0_ATSEN")
	)
	(segment
		(start 373.728234 -343.530174)
		(end 375.497344 -343.530174)
		(width 0.254)
		(layer "In4.Cu")
		(net "PVCCIN_CPU0_ATSEN")
	)
	(segment
		(start 332.560168 -349.189548)
		(end 334.392524 -347.357192)
		(width 0.254)
		(layer "In4.Cu")
		(net "PVCCIN_CPU0_ATSEN")
	)
	(segment
		(start 351.692718 -337.944968)
		(end 351.882964 -337.754722)
		(width 0.254)
		(layer "In4.Cu")
		(net "PVCCIN_CPU0_ATSEN")
	)
	(segment
		(start 376.3645 -341.164926)
		(end 376.6185 -341.05977)
		(width 0.254)
		(layer "In4.Cu")
		(net "PVCCIN_CPU0_ATSEN")
	)
	(segment
		(start 376.6185 -343.455498)
		(end 378.210064 -345.047062)
		(width 0.254)
		(layer "In4.Cu")
		(net "PVCCIN_CPU0_ATSEN")
	)
	(segment
		(start 368.457988 -339.188044)
		(end 370.151152 -340.881208)
		(width 0.254)
		(layer "In4.Cu")
		(net "PVCCIN_CPU0_ATSEN")
	)
	(segment
		(start 364.652052 -356.10927)
		(end 362.184696 -358.576626)
		(width 0.254)
		(layer "In4.Cu")
		(net "PVCCIN_CPU0_ATSEN")
	)
	(segment
		(start 366.047782 -356.10927)
		(end 364.652052 -356.10927)
		(width 0.254)
		(layer "In4.Cu")
		(net "PVCCIN_CPU0_ATSEN")
	)
	(segment
		(start 359.021634 -340.130638)
		(end 359.881932 -339.27034)
		(width 0.254)
		(layer "In4.Cu")
		(net "PVCCIN_CPU0_ATSEN")
	)
	(segment
		(start 368.203988 -337.754722)
		(end 368.457988 -337.649566)
		(width 0.254)
		(layer "In4.Cu")
		(net "PVCCIN_CPU0_ATSEN")
	)
	(segment
		(start 376.120152 -342.907366)
		(end 376.120152 -341.409274)
		(width 0.254)
		(layer "In4.Cu")
		(net "PVCCIN_CPU0_ATSEN")
	)
	(segment
		(start 376.6185 -341.05977)
		(end 376.6185 -343.455498)
		(width 0.254)
		(layer "In4.Cu")
		(net "PVCCIN_CPU0_ATSEN")
	)
	(segment
		(start 360.043476 -337.754722)
		(end 360.297476 -337.649566)
		(width 0.254)
		(layer "In4.Cu")
		(net "PVCCIN_CPU0_ATSEN")
	)
	(segment
		(start 368.009932 -339.400642)
		(end 368.009932 -337.948778)
		(width 0.254)
		(layer "In4.Cu")
		(net "PVCCIN_CPU0_ATSEN")
	)
	(segment
		(start 343.544398 -340.571328)
		(end 343.544398 -337.884516)
		(width 0.254)
		(layer "In4.Cu")
		(net "PVCCIN_CPU0_ATSEN")
	)
	(segment
		(start 335.937098 -341.180928)
		(end 335.937098 -342.604852)
		(width 0.254)
		(layer "In4.Cu")
		(net "PVCCIN_CPU0_ATSEN")
	)
	(segment
		(start 351.692718 -339.449156)
		(end 351.692718 -337.944968)
		(width 0.254)
		(layer "In4.Cu")
		(net "PVCCIN_CPU0_ATSEN")
	)
	(segment
		(start 359.881932 -337.916266)
		(end 360.043476 -337.754722)
		(width 0.254)
		(layer "In4.Cu")
		(net "PVCCIN_CPU0_ATSEN")
	)
	(segment
		(start 343.544398 -337.884516)
		(end 343.639648 -337.789266)
		(width 0.254)
		(layer "In4.Cu")
		(net "PVCCIN_CPU0_ATSEN")
	)
	(segment
		(start 368.009932 -337.948778)
		(end 368.203988 -337.754722)
		(width 0.254)
		(layer "In4.Cu")
		(net "PVCCIN_CPU0_ATSEN")
	)
	(segment
		(start 371.079268 -340.881208)
		(end 373.728234 -343.530174)
		(width 0.254)
		(layer "In4.Cu")
		(net "PVCCIN_CPU0_ATSEN")
	)
	(segment
		(start 335.393538 -341.31377)
		(end 335.647538 -341.05977)
		(width 0.254)
		(layer "In4.Cu")
		(net "PVCCIN_CPU0_ATSEN")
	)
	(segment
		(start 370.151152 -340.881208)
		(end 371.079268 -340.881208)
		(width 0.254)
		(layer "In4.Cu")
		(net "PVCCIN_CPU0_ATSEN")
	)
	(segment
		(start 360.297476 -339.188044)
		(end 361.253532 -340.1441)
		(width 0.254)
		(layer "In4.Cu")
		(net "PVCCIN_CPU0_ATSEN")
	)
	(segment
		(start 328.19848 -349.189548)
		(end 332.560168 -349.189548)
		(width 0.254)
		(layer "In4.Cu")
		(net "PVCCIN_CPU0_ATSEN")
	)
	(segment
		(start 384.779012 -346.432378)
		(end 384.779012 -346.850462)
		(width 0.254)
		(layer "In4.Cu")
		(net "PVCCIN_CPU0_ATSEN")
	)
	(segment
		(start 359.881932 -339.27034)
		(end 359.881932 -337.916266)
		(width 0.254)
		(layer "In4.Cu")
		(net "PVCCIN_CPU0_ATSEN")
	)
	(segment
		(start 340.874858 -343.240868)
		(end 343.544398 -340.571328)
		(width 0.254)
		(layer "In4.Cu")
		(net "PVCCIN_CPU0_ATSEN")
	)
	(segment
		(start 384.779012 -348.026736)
		(end 383.580894 -349.224854)
		(width 0.254)
		(layer "In4.Cu")
		(net "PVCCIN_CPU0_ATSEN")
	)
	(segment
		(start 382.680718 -349.597726)
		(end 372.559326 -349.597726)
		(width 0.254)
		(layer "In4.Cu")
		(net "PVCCIN_CPU0_ATSEN")
	)
	(segment
		(start 383.580894 -349.224854)
		(end 382.680718 -349.597726)
		(width 0.254)
		(layer "In4.Cu")
		(net "PVCCIN_CPU0_ATSEN")
	)
	(segment
		(start 375.497344 -343.530174)
		(end 376.120152 -342.907366)
		(width 0.254)
		(layer "In4.Cu")
		(net "PVCCIN_CPU0_ATSEN")
	)
	(segment
		(start 376.120152 -341.409274)
		(end 376.3645 -341.164926)
		(width 0.254)
		(layer "In4.Cu")
		(net "PVCCIN_CPU0_ATSEN")
	)
	(segment
		(start 384.779012 -346.850462)
		(end 384.779012 -348.026736)
		(width 0.254)
		(layer "In4.Cu")
		(net "PVCCIN_CPU0_ATSEN")
	)
	(segment
		(start 378.210064 -345.047062)
		(end 383.393696 -345.047062)
		(width 0.254)
		(layer "In4.Cu")
		(net "PVCCIN_CPU0_ATSEN")
	)
	(segment
		(start 327.685908 -346.910406)
		(end 327.685908 -348.676976)
		(width 0.254)
		(layer "In4.Cu")
		(net "PVCCIN_CPU0_ATSEN")
	)
	(segment
		(start 360.297476 -337.649566)
		(end 360.297476 -339.188044)
		(width 0.254)
		(layer "In4.Cu")
		(net "PVCCIN_CPU0_ATSEN")
	)
	(segment
		(start 334.392524 -347.357192)
		(end 334.392524 -343.894664)
		(width 0.254)
		(layer "In4.Cu")
		(net "PVCCIN_CPU0_ATSEN")
	)
	(segment
		(start 361.253532 -340.1441)
		(end 367.266474 -340.1441)
		(width 0.254)
		(layer "In4.Cu")
		(net "PVCCIN_CPU0_ATSEN")
	)
	(segment
		(start 351.01149 -340.130384)
		(end 351.692718 -339.449156)
		(width 0.254)
		(layer "In4.Cu")
		(net "PVCCIN_CPU0_ATSEN")
	)
	(segment
		(start 343.976452 -337.649566)
		(end 343.976452 -339.188044)
		(width 0.254)
		(layer "In4.Cu")
		(net "PVCCIN_CPU0_ATSEN")
	)
	(segment
		(start 327.685908 -348.676976)
		(end 328.19848 -349.189548)
		(width 0.254)
		(layer "In4.Cu")
		(net "PVCCIN_CPU0_ATSEN")
	)
	(segment
		(start 372.559326 -349.597726)
		(end 366.047782 -356.10927)
		(width 0.254)
		(layer "In4.Cu")
		(net "PVCCIN_CPU0_ATSEN")
	)
	(segment
		(start 360.195114 -358.648508)
		(end 359.393236 -358.648508)
		(width 0.1778)
		(layer "F.Cu")
		(net "PVCCIN_CPU0_ADDR")
	)
	(segment
		(start 361.282234 -357.561388)
		(end 360.195114 -358.648508)
		(width 0.1778)
		(layer "F.Cu")
		(net "PVCCIN_CPU0_ADDR")
	)
	(via
		(at 361.282234 -357.561388)
		(size 0.508)
		(drill 0.254)
		(layers "F.Cu" "B.Cu")
		(net "PVCCIN_CPU0_ADDR")
	)
	(via
		(at 360.39298 -357.312468)
		(size 0.6604)
		(drill 0.3302)
		(layers "F.Cu" "B.Cu")
		(net "PVCCIN_CPU0_ADDR")
	)
	(segment
		(start 361.780582 -357.561388)
		(end 361.282234 -357.561388)
		(width 0.12954)
		(layer "B.Cu")
		(net "PVCCIN_CPU0_ADDR")
	)
	(segment
		(start 361.282234 -357.561388)
		(end 361.033314 -357.312468)
		(width 0.12954)
		(layer "B.Cu")
		(net "PVCCIN_CPU0_ADDR")
	)
	(segment
		(start 359.470198 -357.312468)
		(end 359.20426 -357.578406)
		(width 0.12954)
		(layer "B.Cu")
		(net "PVCCIN_CPU0_ADDR")
	)
	(segment
		(start 362.16336 -357.690166)
		(end 361.90936 -357.690166)
		(width 0.12954)
		(layer "B.Cu")
		(net "PVCCIN_CPU0_ADDR")
	)
	(segment
		(start 360.39298 -357.312468)
		(end 359.470198 -357.312468)
		(width 0.12954)
		(layer "B.Cu")
		(net "PVCCIN_CPU0_ADDR")
	)
	(segment
		(start 361.033314 -357.312468)
		(end 360.39298 -357.312468)
		(width 0.12954)
		(layer "B.Cu")
		(net "PVCCIN_CPU0_ADDR")
	)
	(segment
		(start 361.90936 -357.690166)
		(end 361.780582 -357.561388)
		(width 0.12954)
		(layer "B.Cu")
		(net "PVCCIN_CPU0_ADDR")
	)
	(segment
		(start 357.230934 -246.900446)
		(end 357.230934 -246.364506)
		(width 0.2032)
		(layer "F.Cu")
		(net "PVCCIN_CPU0")
	)
	(segment
		(start 360.990134 -246.900446)
		(end 360.990134 -246.36476)
		(width 0.2032)
		(layer "F.Cu")
		(net "PVCCIN_CPU0")
	)
	(segment
		(start 357.810562 -253.383796)
		(end 357.810562 -253.919736)
		(width 0.2032)
		(layer "F.Cu")
		(net "PVCCIN_CPU0")
	)
	(segment
		(start 355.930962 -289.195002)
		(end 355.930962 -289.807142)
		(width 0.2032)
		(layer "F.Cu")
		(net "PVCCIN_CPU0")
	)
	(segment
		(start 356.870762 -284.311598)
		(end 356.870762 -284.847538)
		(width 0.2032)
		(layer "F.Cu")
		(net "PVCCIN_CPU0")
	)
	(segment
		(start 357.340662 -285.125414)
		(end 357.340662 -285.661354)
		(width 0.2032)
		(layer "F.Cu")
		(net "PVCCIN_CPU0")
	)
	(segment
		(start 359.220516 -280.242264)
		(end 359.220516 -280.778204)
		(width 0.2032)
		(layer "F.Cu")
		(net "PVCCIN_CPU0")
	)
	(segment
		(start 359.220516 -263.96442)
		(end 359.220516 -264.50036)
		(width 0.2032)
		(layer "F.Cu")
		(net "PVCCIN_CPU0")
	)
	(segment
		(start 361.099862 -257.45313)
		(end 361.099862 -257.98907)
		(width 0.2032)
		(layer "F.Cu")
		(net "PVCCIN_CPU0")
	)
	(segment
		(start 360.990134 -249.620278)
		(end 360.98988 -249.620024)
		(width 0.2032)
		(layer "F.Cu")
		(net "PVCCIN_CPU0")
	)
	(segment
		(start 357.340662 -254.197612)
		(end 357.340662 -254.733552)
		(width 0.2032)
		(layer "F.Cu")
		(net "PVCCIN_CPU0")
	)
	(segment
		(start 361.099862 -267.219938)
		(end 361.099862 -267.755878)
		(width 0.2032)
		(layer "F.Cu")
		(net "PVCCIN_CPU0")
	)
	(segment
		(start 363.919516 -281.869896)
		(end 363.919516 -282.405582)
		(width 0.2032)
		(layer "F.Cu")
		(net "PVCCIN_CPU0")
	)
	(segment
		(start 360.629962 -287.567116)
		(end 360.629962 -288.103056)
		(width 0.2032)
		(layer "F.Cu")
		(net "PVCCIN_CPU0")
	)
	(segment
		(start 359.690162 -271.289272)
		(end 359.690162 -271.825212)
		(width 0.2032)
		(layer "F.Cu")
		(net "PVCCIN_CPU0")
	)
	(segment
		(start 360.990134 -250.155964)
		(end 360.990134 -249.620278)
		(width 0.2032)
		(layer "F.Cu")
		(net "PVCCIN_CPU0")
	)
	(segment
		(start 357.70058 -247.714262)
		(end 357.70058 -247.178322)
		(width 0.2032)
		(layer "F.Cu")
		(net "PVCCIN_CPU0")
	)
	(segment
		(start 355.930962 -281.591766)
		(end 355.931216 -281.59202)
		(width 0.2032)
		(layer "F.Cu")
		(net "PVCCIN_CPU0")
	)
	(segment
		(start 362.509562 -255.011682)
		(end 362.509562 -255.547622)
		(width 0.2032)
		(layer "F.Cu")
		(net "PVCCIN_CPU0")
	)
	(segment
		(start 362.399834 -247.714262)
		(end 362.399834 -247.178322)
		(width 0.2032)
		(layer "F.Cu")
		(net "PVCCIN_CPU0")
	)
	(segment
		(start 361.099862 -255.825498)
		(end 361.099862 -256.361438)
		(width 0.2032)
		(layer "F.Cu")
		(net "PVCCIN_CPU0")
	)
	(segment
		(start 353.581716 -286.7533)
		(end 353.581716 -287.28924)
		(width 0.2032)
		(layer "F.Cu")
		(net "PVCCIN_CPU0")
	)
	(segment
		(start 346.465652 -315.66739)
		(end 347.40596 -314.727082)
		(width 0.508)
		(layer "F.Cu")
		(net "PVCCIN_CPU0")
	)
	(segment
		(start 359.110534 -250.155964)
		(end 359.110534 -249.620024)
		(width 0.2032)
		(layer "F.Cu")
		(net "PVCCIN_CPU0")
	)
	(segment
		(start 360.629962 -261.522718)
		(end 360.629962 -262.058658)
		(width 0.2032)
		(layer "F.Cu")
		(net "PVCCIN_CPU0")
	)
	(segment
		(start 358.280716 -263.96442)
		(end 358.280716 -264.50036)
		(width 0.2032)
		(layer "F.Cu")
		(net "PVCCIN_CPU0")
	)
	(segment
		(start 363.449362 -279.428194)
		(end 363.449362 -279.964134)
		(width 0.2032)
		(layer "F.Cu")
		(net "PVCCIN_CPU0")
	)
	(segment
		(start 362.509562 -284.311598)
		(end 362.509562 -284.847538)
		(width 0.2032)
		(layer "F.Cu")
		(net "PVCCIN_CPU0")
	)
	(segment
		(start 359.690162 -284.311598)
		(end 359.690162 -284.847538)
		(width 0.2032)
		(layer "F.Cu")
		(net "PVCCIN_CPU0")
	)
	(segment
		(start 359.220516 -262.336534)
		(end 359.220516 -262.872474)
		(width 0.2032)
		(layer "F.Cu")
		(net "PVCCIN_CPU0")
	)
	(segment
		(start 357.230934 -243.644928)
		(end 357.230934 -243.108988)
		(width 0.2032)
		(layer "F.Cu")
		(net "PVCCIN_CPU0")
	)
	(segment
		(start 360.160316 -259.081016)
		(end 360.160316 -259.616956)
		(width 0.2032)
		(layer "F.Cu")
		(net "PVCCIN_CPU0")
	)
	(segment
		(start 359.58018 -241.203226)
		(end 359.58018 -240.667286)
		(width 0.2032)
		(layer "F.Cu")
		(net "PVCCIN_CPU0")
	)
	(segment
		(start 356.870762 -282.683966)
		(end 356.870762 -283.219906)
		(width 0.2032)
		(layer "F.Cu")
		(net "PVCCIN_CPU0")
	)
	(segment
		(start 346.465652 -315.66739)
		(end 347.40596 -316.607698)
		(width 0.508)
		(layer "F.Cu")
		(net "PVCCIN_CPU0")
	)
	(segment
		(start 360.050334 -250.155964)
		(end 360.050334 -249.620024)
		(width 0.2032)
		(layer "F.Cu")
		(net "PVCCIN_CPU0")
	)
	(segment
		(start 361.099862 -276.986492)
		(end 361.099862 -277.522432)
		(width 0.2032)
		(layer "F.Cu")
		(net "PVCCIN_CPU0")
	)
	(segment
		(start 359.58018 -244.458744)
		(end 359.58018 -243.922804)
		(width 0.2032)
		(layer "F.Cu")
		(net "PVCCIN_CPU0")
	)
	(segment
		(start 361.099862 -265.592052)
		(end 361.099862 -265.592306)
		(width 0.2032)
		(layer "F.Cu")
		(net "PVCCIN_CPU0")
	)
	(segment
		(start 360.51998 -239.039654)
		(end 360.520234 -239.0394)
		(width 0.2032)
		(layer "F.Cu")
		(net "PVCCIN_CPU0")
	)
	(segment
		(start 358.640634 -249.342148)
		(end 358.640634 -248.806208)
		(width 0.2032)
		(layer "F.Cu")
		(net "PVCCIN_CPU0")
	)
	(segment
		(start 360.990134 -240.389156)
		(end 360.990134 -239.85347)
		(width 0.2032)
		(layer "F.Cu")
		(net "PVCCIN_CPU0")
	)
	(segment
		(start 358.640634 -241.203226)
		(end 358.640634 -240.667286)
		(width 0.2032)
		(layer "F.Cu")
		(net "PVCCIN_CPU0")
	)
	(segment
		(start 357.340662 -262.336534)
		(end 357.340662 -262.872474)
		(width 0.2032)
		(layer "F.Cu")
		(net "PVCCIN_CPU0")
	)
	(segment
		(start 360.629962 -268.033754)
		(end 360.629962 -268.569694)
		(width 0.2032)
		(layer "F.Cu")
		(net "PVCCIN_CPU0")
	)
	(segment
		(start 362.039916 -260.708648)
		(end 362.039916 -260.708902)
		(width 0.2032)
		(layer "F.Cu")
		(net "PVCCIN_CPU0")
	)
	(segment
		(start 357.810562 -287.567116)
		(end 357.810562 -288.103056)
		(width 0.2032)
		(layer "F.Cu")
		(net "PVCCIN_CPU0")
	)
	(segment
		(start 358.750362 -272.917158)
		(end 358.750362 -273.452844)
		(width 0.2032)
		(layer "F.Cu")
		(net "PVCCIN_CPU0")
	)
	(segment
		(start 362.039916 -280.242264)
		(end 362.039916 -280.778204)
		(width 0.2032)
		(layer "F.Cu")
		(net "PVCCIN_CPU0")
	)
	(segment
		(start 360.160316 -257.45313)
		(end 360.160316 -257.98907)
		(width 0.2032)
		(layer "F.Cu")
		(net "PVCCIN_CPU0")
	)
	(segment
		(start 358.750362 -260.430518)
		(end 358.750616 -260.430772)
		(width 0.2032)
		(layer "F.Cu")
		(net "PVCCIN_CPU0")
	)
	(segment
		(start 371.23624 -315.66739)
		(end 372.176548 -316.607698)
		(width 0.508)
		(layer "F.Cu")
		(net "PVCCIN_CPU0")
	)
	(segment
		(start 359.220516 -281.869896)
		(end 359.220516 -282.405836)
		(width 0.2032)
		(layer "F.Cu")
		(net "PVCCIN_CPU0")
	)
	(segment
		(start 360.160316 -278.614378)
		(end 360.160316 -279.150318)
		(width 0.2032)
		(layer "F.Cu")
		(net "PVCCIN_CPU0")
	)
	(segment
		(start 358.750362 -258.802886)
		(end 358.750616 -258.80314)
		(width 0.2032)
		(layer "F.Cu")
		(net "PVCCIN_CPU0")
	)
	(segment
		(start 361.099862 -259.081016)
		(end 361.099862 -259.616956)
		(width 0.2032)
		(layer "F.Cu")
		(net "PVCCIN_CPU0")
	)
	(segment
		(start 354.521516 -283.497782)
		(end 354.521516 -284.033722)
		(width 0.254)
		(layer "F.Cu")
		(net "PVCCIN_CPU0")
	)
	(segment
		(start 360.51998 -242.830858)
		(end 360.51998 -242.294918)
		(width 0.2032)
		(layer "F.Cu")
		(net "PVCCIN_CPU0")
	)
	(segment
		(start 363.449362 -285.939484)
		(end 363.449362 -286.475424)
		(width 0.2032)
		(layer "F.Cu")
		(net "PVCCIN_CPU0")
	)
	(segment
		(start 360.629962 -258.2672)
		(end 360.629962 -258.80314)
		(width 0.2032)
		(layer "F.Cu")
		(net "PVCCIN_CPU0")
	)
	(segment
		(start 362.509562 -253.383796)
		(end 362.509562 -253.919736)
		(width 0.2032)
		(layer "F.Cu")
		(net "PVCCIN_CPU0")
	)
	(segment
		(start 362.509562 -287.567116)
		(end 362.509562 -288.103056)
		(width 0.2032)
		(layer "F.Cu")
		(net "PVCCIN_CPU0")
	)
	(segment
		(start 359.690162 -281.05608)
		(end 359.690162 -281.59202)
		(width 0.2032)
		(layer "F.Cu")
		(net "PVCCIN_CPU0")
	)
	(segment
		(start 360.990134 -241.481356)
		(end 360.98988 -241.481102)
		(width 0.2032)
		(layer "F.Cu")
		(net "PVCCIN_CPU0")
	)
	(segment
		(start 360.160316 -254.197612)
		(end 360.160316 -254.733552)
		(width 0.2032)
		(layer "F.Cu")
		(net "PVCCIN_CPU0")
	)
	(segment
		(start 362.039916 -260.708902)
		(end 362.039916 -261.244842)
		(width 0.2032)
		(layer "F.Cu")
		(net "PVCCIN_CPU0")
	)
	(segment
		(start 360.160316 -268.84757)
		(end 360.160316 -269.38351)
		(width 0.2032)
		(layer "F.Cu")
		(net "PVCCIN_CPU0")
	)
	(segment
		(start 358.750362 -262.058404)
		(end 358.750616 -262.058658)
		(width 0.2032)
		(layer "F.Cu")
		(net "PVCCIN_CPU0")
	)
	(segment
		(start 358.750362 -258.2672)
		(end 358.750362 -258.802886)
		(width 0.2032)
		(layer "F.Cu")
		(net "PVCCIN_CPU0")
	)
	(segment
		(start 361.099862 -260.708902)
		(end 361.099862 -261.244842)
		(width 0.2032)
		(layer "F.Cu")
		(net "PVCCIN_CPU0")
	)
	(segment
		(start 357.810562 -282.683966)
		(end 357.810562 -283.219906)
		(width 0.2032)
		(layer "F.Cu")
		(net "PVCCIN_CPU0")
	)
	(segment
		(start 357.340662 -283.497782)
		(end 357.340662 -284.033722)
		(width 0.2032)
		(layer "F.Cu")
		(net "PVCCIN_CPU0")
	)
	(segment
		(start 362.399834 -245.55069)
		(end 362.399834 -246.08663)
		(width 0.2032)
		(layer "F.Cu")
		(net "PVCCIN_CPU0")
	)
	(segment
		(start 360.629962 -259.894832)
		(end 360.629962 -260.430772)
		(width 0.2032)
		(layer "F.Cu")
		(net "PVCCIN_CPU0")
	)
	(segment
		(start 362.979716 -283.497782)
		(end 362.979716 -284.033722)
		(width 0.2032)
		(layer "F.Cu")
		(net "PVCCIN_CPU0")
	)
	(segment
		(start 358.750362 -257.175)
		(end 358.750616 -257.175254)
		(width 0.2032)
		(layer "F.Cu")
		(net "PVCCIN_CPU0")
	)
	(segment
		(start 365.03864 -315.66739)
		(end 365.978948 -316.607698)
		(width 0.508)
		(layer "F.Cu")
		(net "PVCCIN_CPU0")
	)
	(segment
		(start 356.870762 -281.05608)
		(end 356.870762 -281.59202)
		(width 0.2032)
		(layer "F.Cu")
		(net "PVCCIN_CPU0")
	)
	(segment
		(start 361.099862 -272.103342)
		(end 361.099862 -272.639282)
		(width 0.2032)
		(layer "F.Cu")
		(net "PVCCIN_CPU0")
	)
	(segment
		(start 355.930962 -281.05608)
		(end 355.930962 -281.591766)
		(width 0.2032)
		(layer "F.Cu")
		(net "PVCCIN_CPU0")
	)
	(segment
		(start 365.799116 -286.7533)
		(end 365.799116 -287.28924)
		(width 0.2032)
		(layer "F.Cu")
		(net "PVCCIN_CPU0")
	)
	(segment
		(start 358.640634 -244.458744)
		(end 358.640634 -243.922804)
		(width 0.2032)
		(layer "F.Cu")
		(net "PVCCIN_CPU0")
	)
	(segment
		(start 362.399834 -239.57534)
		(end 362.399834 -239.0394)
		(width 0.2032)
		(layer "F.Cu")
		(net "PVCCIN_CPU0")
	)
	(segment
		(start 361.099862 -270.475456)
		(end 361.099862 -271.011396)
		(width 0.2032)
		(layer "F.Cu")
		(net "PVCCIN_CPU0")
	)
	(segment
		(start 361.099862 -286.7533)
		(end 361.099862 -287.28924)
		(width 0.2032)
		(layer "F.Cu")
		(net "PVCCIN_CPU0")
	)
	(segment
		(start 364.859316 -286.7533)
		(end 364.859316 -287.28924)
		(width 0.2032)
		(layer "F.Cu")
		(net "PVCCIN_CPU0")
	)
	(segment
		(start 359.220516 -278.614378)
		(end 359.220516 -279.150318)
		(width 0.2032)
		(layer "F.Cu")
		(net "PVCCIN_CPU0")
	)
	(segment
		(start 359.690162 -255.011682)
		(end 359.690162 -255.547622)
		(width 0.2032)
		(layer "F.Cu")
		(net "PVCCIN_CPU0")
	)
	(segment
		(start 358.750362 -269.66164)
		(end 358.750362 -270.197326)
		(width 0.2032)
		(layer "F.Cu")
		(net "PVCCIN_CPU0")
	)
	(segment
		(start 360.160316 -260.708648)
		(end 360.160316 -260.708902)
		(width 0.2032)
		(layer "F.Cu")
		(net "PVCCIN_CPU0")
	)
	(segment
		(start 360.050334 -245.27256)
		(end 360.050334 -244.73662)
		(width 0.2032)
		(layer "F.Cu")
		(net "PVCCIN_CPU0")
	)
	(segment
		(start 371.23624 -315.66739)
		(end 372.176548 -314.727082)
		(width 0.508)
		(layer "F.Cu")
		(net "PVCCIN_CPU0")
	)
	(segment
		(start 356.870762 -285.939484)
		(end 356.870762 -286.475424)
		(width 0.2032)
		(layer "F.Cu")
		(net "PVCCIN_CPU0")
	)
	(segment
		(start 358.640634 -246.08663)
		(end 358.640634 -245.55069)
		(width 0.2032)
		(layer "F.Cu")
		(net "PVCCIN_CPU0")
	)
	(segment
		(start 360.160316 -260.708902)
		(end 360.160316 -261.244842)
		(width 0.2032)
		(layer "F.Cu")
		(net "PVCCIN_CPU0")
	)
	(segment
		(start 359.110534 -248.528078)
		(end 359.110534 -247.992138)
		(width 0.2032)
		(layer "F.Cu")
		(net "PVCCIN_CPU0")
	)
	(segment
		(start 358.750362 -276.708362)
		(end 358.750616 -276.708616)
		(width 0.2032)
		(layer "F.Cu")
		(net "PVCCIN_CPU0")
	)
	(segment
		(start 360.629962 -279.428194)
		(end 360.629962 -279.964134)
		(width 0.2032)
		(layer "F.Cu")
		(net "PVCCIN_CPU0")
	)
	(segment
		(start 365.328962 -282.683966)
		(end 365.328962 -283.219906)
		(width 0.2032)
		(layer "F.Cu")
		(net "PVCCIN_CPU0")
	)
	(segment
		(start 357.340662 -259.081016)
		(end 357.340662 -259.616956)
		(width 0.2032)
		(layer "F.Cu")
		(net "PVCCIN_CPU0")
	)
	(segment
		(start 359.690162 -266.405868)
		(end 359.690162 -266.941808)
		(width 0.2032)
		(layer "F.Cu")
		(net "PVCCIN_CPU0")
	)
	(segment
		(start 362.979716 -286.7533)
		(end 362.979716 -287.28924)
		(width 0.2032)
		(layer "F.Cu")
		(net "PVCCIN_CPU0")
	)
	(segment
		(start 360.160316 -283.497782)
		(end 360.160316 -284.033722)
		(width 0.2032)
		(layer "F.Cu")
		(net "PVCCIN_CPU0")
	)
	(segment
		(start 359.690162 -279.428194)
		(end 359.690162 -279.964134)
		(width 0.2032)
		(layer "F.Cu")
		(net "PVCCIN_CPU0")
	)
	(segment
		(start 359.220516 -272.103342)
		(end 359.220516 -272.639282)
		(width 0.2032)
		(layer "F.Cu")
		(net "PVCCIN_CPU0")
	)
	(segment
		(start 360.990134 -243.644928)
		(end 360.990134 -243.109242)
		(width 0.2032)
		(layer "F.Cu")
		(net "PVCCIN_CPU0")
	)
	(segment
		(start 360.51998 -244.458744)
		(end 360.51998 -243.922804)
		(width 0.2032)
		(layer "F.Cu")
		(net "PVCCIN_CPU0")
	)
	(segment
		(start 362.039916 -259.081016)
		(end 362.039916 -259.616956)
		(width 0.2032)
		(layer "F.Cu")
		(net "PVCCIN_CPU0")
	)
	(segment
		(start 351.722944 -316.607698)
		(end 352.663252 -315.66739)
		(width 0.508)
		(layer "F.Cu")
		(net "PVCCIN_CPU0")
	)
	(segment
		(start 359.690162 -277.800562)
		(end 359.690162 -278.336502)
		(width 0.2032)
		(layer "F.Cu")
		(net "PVCCIN_CPU0")
	)
	(segment
		(start 358.750362 -274.54479)
		(end 358.750362 -275.080476)
		(width 0.2032)
		(layer "F.Cu")
		(net "PVCCIN_CPU0")
	)
	(segment
		(start 361.099862 -263.96442)
		(end 361.099862 -264.50036)
		(width 0.2032)
		(layer "F.Cu")
		(net "PVCCIN_CPU0")
	)
	(segment
		(start 358.750362 -253.919482)
		(end 358.750616 -253.919736)
		(width 0.2032)
		(layer "F.Cu")
		(net "PVCCIN_CPU0")
	)
	(segment
		(start 357.230934 -245.27256)
		(end 357.230934 -244.73662)
		(width 0.2032)
		(layer "F.Cu")
		(net "PVCCIN_CPU0")
	)
	(segment
		(start 364.859316 -288.381186)
		(end 364.859316 -288.917126)
		(width 0.2032)
		(layer "F.Cu")
		(net "PVCCIN_CPU0")
	)
	(segment
		(start 362.399834 -244.458744)
		(end 362.399834 -243.922804)
		(width 0.2032)
		(layer "F.Cu")
		(net "PVCCIN_CPU0")
	)
	(segment
		(start 361.099862 -288.381186)
		(end 361.099862 -288.993326)
		(width 0.2032)
		(layer "F.Cu")
		(net "PVCCIN_CPU0")
	)
	(segment
		(start 362.509562 -258.2672)
		(end 362.509562 -258.80314)
		(width 0.2032)
		(layer "F.Cu")
		(net "PVCCIN_CPU0")
	)
	(segment
		(start 364.859316 -283.497782)
		(end 364.859316 -284.033722)
		(width 0.2032)
		(layer "F.Cu")
		(net "PVCCIN_CPU0")
	)
	(segment
		(start 360.160316 -262.336534)
		(end 360.160316 -262.872474)
		(width 0.2032)
		(layer "F.Cu")
		(net "PVCCIN_CPU0")
	)
	(segment
		(start 361.929934 -248.528078)
		(end 361.929934 -247.992138)
		(width 0.2032)
		(layer "F.Cu")
		(net "PVCCIN_CPU0")
	)
	(segment
		(start 355.930962 -287.567116)
		(end 355.930962 -288.102802)
		(width 0.2032)
		(layer "F.Cu")
		(net "PVCCIN_CPU0")
	)
	(segment
		(start 360.160316 -276.986492)
		(end 360.160316 -277.522432)
		(width 0.2032)
		(layer "F.Cu")
		(net "PVCCIN_CPU0")
	)
	(segment
		(start 362.509562 -285.939484)
		(end 362.509562 -286.475424)
		(width 0.2032)
		(layer "F.Cu")
		(net "PVCCIN_CPU0")
	)
	(segment
		(start 356.401116 -288.381186)
		(end 356.401116 -288.942526)
		(width 0.2032)
		(layer "F.Cu")
		(net "PVCCIN_CPU0")
	)
	(segment
		(start 345.525344 -316.607698)
		(end 346.465652 -315.66739)
		(width 0.508)
		(layer "F.Cu")
		(net "PVCCIN_CPU0")
	)
	(segment
		(start 365.328962 -285.939484)
		(end 365.328962 -286.475424)
		(width 0.2032)
		(layer "F.Cu")
		(net "PVCCIN_CPU0")
	)
	(segment
		(start 360.160316 -281.869896)
		(end 360.160316 -282.405836)
		(width 0.2032)
		(layer "F.Cu")
		(net "PVCCIN_CPU0")
	)
	(segment
		(start 363.919516 -284.033468)
		(end 363.919262 -284.033722)
		(width 0.2032)
		(layer "F.Cu")
		(net "PVCCIN_CPU0")
	)
	(segment
		(start 357.340662 -278.614378)
		(end 357.340662 -279.150318)
		(width 0.2032)
		(layer "F.Cu")
		(net "PVCCIN_CPU0")
	)
	(segment
		(start 358.750362 -255.547368)
		(end 358.750616 -255.547622)
		(width 0.2032)
		(layer "F.Cu")
		(net "PVCCIN_CPU0")
	)
	(segment
		(start 358.750362 -287.567116)
		(end 358.750362 -288.103056)
		(width 0.2032)
		(layer "F.Cu")
		(net "PVCCIN_CPU0")
	)
	(segment
		(start 362.509562 -279.428194)
		(end 362.509562 -279.964134)
		(width 0.2032)
		(layer "F.Cu")
		(net "PVCCIN_CPU0")
	)
	(segment
		(start 361.929934 -246.900446)
		(end 361.929934 -246.364506)
		(width 0.2032)
		(layer "F.Cu")
		(net "PVCCIN_CPU0")
	)
	(segment
		(start 360.160316 -270.475456)
		(end 360.160316 -271.011396)
		(width 0.2032)
		(layer "F.Cu")
		(net "PVCCIN_CPU0")
	)
	(segment
		(start 363.449362 -287.567116)
		(end 363.449362 -288.103056)
		(width 0.2032)
		(layer "F.Cu")
		(net "PVCCIN_CPU0")
	)
	(segment
		(start 360.160316 -272.103342)
		(end 360.160316 -272.639282)
		(width 0.2032)
		(layer "F.Cu")
		(net "PVCCIN_CPU0")
	)
	(segment
		(start 358.750362 -270.197326)
		(end 358.750616 -270.19758)
		(width 0.2032)
		(layer "F.Cu")
		(net "PVCCIN_CPU0")
	)
	(segment
		(start 362.039916 -254.197612)
		(end 362.039916 -254.733552)
		(width 0.2032)
		(layer "F.Cu")
		(net "PVCCIN_CPU0")
	)
	(segment
		(start 360.160316 -286.7533)
		(end 360.160316 -287.28924)
		(width 0.2032)
		(layer "F.Cu")
		(net "PVCCIN_CPU0")
	)
	(segment
		(start 358.750362 -273.452844)
		(end 358.750616 -273.453098)
		(width 0.2032)
		(layer "F.Cu")
		(net "PVCCIN_CPU0")
	)
	(segment
		(start 360.990134 -239.85347)
		(end 360.98988 -239.853216)
		(width 0.2032)
		(layer "F.Cu")
		(net "PVCCIN_CPU0")
	)
	(segment
		(start 360.160316 -273.730974)
		(end 360.160316 -274.266914)
		(width 0.2032)
		(layer "F.Cu")
		(net "PVCCIN_CPU0")
	)
	(segment
		(start 359.690162 -285.939484)
		(end 359.690162 -286.475424)
		(width 0.2032)
		(layer "F.Cu")
		(net "PVCCIN_CPU0")
	)
	(segment
		(start 359.220516 -286.7533)
		(end 359.220516 -287.28924)
		(width 0.2032)
		(layer "F.Cu")
		(net "PVCCIN_CPU0")
	)
	(segment
		(start 359.58018 -247.714262)
		(end 359.58018 -247.178322)
		(width 0.2032)
		(layer "F.Cu")
		(net "PVCCIN_CPU0")
	)
	(segment
		(start 357.340662 -280.242264)
		(end 357.340662 -280.778204)
		(width 0.2032)
		(layer "F.Cu")
		(net "PVCCIN_CPU0")
	)
	(segment
		(start 356.401116 -286.7533)
		(end 356.401116 -287.28924)
		(width 0.2032)
		(layer "F.Cu")
		(net "PVCCIN_CPU0")
	)
	(segment
		(start 363.919516 -286.7533)
		(end 363.919516 -287.288986)
		(width 0.2032)
		(layer "F.Cu")
		(net "PVCCIN_CPU0")
	)
	(segment
		(start 362.039916 -262.336534)
		(end 362.039916 -262.872474)
		(width 0.2032)
		(layer "F.Cu")
		(net "PVCCIN_CPU0")
	)
	(segment
		(start 361.099862 -281.869896)
		(end 361.099862 -282.405836)
		(width 0.2032)
		(layer "F.Cu")
		(net "PVCCIN_CPU0")
	)
	(segment
		(start 360.51998 -241.203226)
		(end 360.51998 -240.667286)
		(width 0.2032)
		(layer "F.Cu")
		(net "PVCCIN_CPU0")
	)
	(segment
		(start 352.663252 -315.66739)
		(end 353.60356 -314.727082)
		(width 0.508)
		(layer "F.Cu")
		(net "PVCCIN_CPU0")
	)
	(segment
		(start 357.340662 -281.869896)
		(end 357.340662 -282.405836)
		(width 0.2032)
		(layer "F.Cu")
		(net "PVCCIN_CPU0")
	)
	(segment
		(start 361.929934 -240.389156)
		(end 361.929934 -239.853216)
		(width 0.2032)
		(layer "F.Cu")
		(net "PVCCIN_CPU0")
	)
	(segment
		(start 365.799116 -285.125414)
		(end 365.799116 -285.661354)
		(width 0.2032)
		(layer "F.Cu")
		(net "PVCCIN_CPU0")
	)
	(segment
		(start 358.750362 -282.683966)
		(end 358.750362 -283.219652)
		(width 0.2032)
		(layer "F.Cu")
		(net "PVCCIN_CPU0")
	)
	(segment
		(start 360.990134 -245.27256)
		(end 360.990134 -244.736874)
		(width 0.2032)
		(layer "F.Cu")
		(net "PVCCIN_CPU0")
	)
	(segment
		(start 357.340662 -288.381186)
		(end 357.340662 -288.993326)
		(width 0.254)
		(layer "F.Cu")
		(net "PVCCIN_CPU0")
	)
	(segment
		(start 361.099862 -265.592306)
		(end 361.099862 -266.128246)
		(width 0.2032)
		(layer "F.Cu")
		(net "PVCCIN_CPU0")
	)
	(segment
		(start 357.230934 -248.528078)
		(end 357.230934 -247.995186)
		(width 0.2032)
		(layer "F.Cu")
		(net "PVCCIN_CPU0")
	)
	(segment
		(start 355.930962 -285.939484)
		(end 355.930962 -286.47517)
		(width 0.2032)
		(layer "F.Cu")
		(net "PVCCIN_CPU0")
	)
	(segment
		(start 361.569762 -276.172676)
		(end 361.569762 -276.708616)
		(width 0.2032)
		(layer "F.Cu")
		(net "PVCCIN_CPU0")
	)
	(segment
		(start 355.930962 -284.311598)
		(end 355.930962 -284.847284)
		(width 0.2032)
		(layer "F.Cu")
		(net "PVCCIN_CPU0")
	)
	(segment
		(start 359.220516 -285.125414)
		(end 359.220516 -285.661354)
		(width 0.2032)
		(layer "F.Cu")
		(net "PVCCIN_CPU0")
	)
	(segment
		(start 360.160316 -280.242264)
		(end 360.160316 -280.778204)
		(width 0.2032)
		(layer "F.Cu")
		(net "PVCCIN_CPU0")
	)
	(segment
		(start 360.050334 -240.389156)
		(end 360.050334 -239.853216)
		(width 0.2032)
		(layer "F.Cu")
		(net "PVCCIN_CPU0")
	)
	(segment
		(start 360.629962 -281.05608)
		(end 360.629962 -281.59202)
		(width 0.2032)
		(layer "F.Cu")
		(net "PVCCIN_CPU0")
	)
	(segment
		(start 358.84104 -315.66739)
		(end 359.781348 -314.727082)
		(width 0.508)
		(layer "F.Cu")
		(net "PVCCIN_CPU0")
	)
	(segment
		(start 359.58018 -242.830858)
		(end 359.58018 -242.294918)
		(width 0.2032)
		(layer "F.Cu")
		(net "PVCCIN_CPU0")
	)
	(segment
		(start 362.509562 -256.639314)
		(end 362.509562 -257.175254)
		(width 0.2032)
		(layer "F.Cu")
		(net "PVCCIN_CPU0")
	)
	(segment
		(start 360.160316 -255.825498)
		(end 360.160316 -256.361438)
		(width 0.2032)
		(layer "F.Cu")
		(net "PVCCIN_CPU0")
	)
	(segment
		(start 361.929934 -250.155964)
		(end 361.929934 -249.620024)
		(width 0.2032)
		(layer "F.Cu")
		(net "PVCCIN_CPU0")
	)
	(segment
		(start 360.160316 -285.125414)
		(end 360.160316 -285.661354)
		(width 0.2032)
		(layer "F.Cu")
		(net "PVCCIN_CPU0")
	)
	(segment
		(start 359.690162 -282.683966)
		(end 359.690162 -283.219906)
		(width 0.2032)
		(layer "F.Cu")
		(net "PVCCIN_CPU0")
	)
	(segment
		(start 360.629962 -255.011682)
		(end 360.629962 -255.547622)
		(width 0.2032)
		(layer "F.Cu")
		(net "PVCCIN_CPU0")
	)
	(segment
		(start 357.230934 -247.995186)
		(end 357.227886 -247.992138)
		(width 0.2032)
		(layer "F.Cu")
		(net "PVCCIN_CPU0")
	)
	(segment
		(start 361.099862 -260.708648)
		(end 361.099862 -260.708902)
		(width 0.2032)
		(layer "F.Cu")
		(net "PVCCIN_CPU0")
	)
	(segment
		(start 362.039916 -264.500106)
		(end 362.039662 -264.50036)
		(width 0.2032)
		(layer "F.Cu")
		(net "PVCCIN_CPU0")
	)
	(segment
		(start 360.050334 -242.017042)
		(end 360.050334 -241.481102)
		(width 0.2032)
		(layer "F.Cu")
		(net "PVCCIN_CPU0")
	)
	(segment
		(start 358.750362 -256.639314)
		(end 358.750362 -257.175)
		(width 0.2032)
		(layer "F.Cu")
		(net "PVCCIN_CPU0")
	)
	(segment
		(start 360.160316 -265.592052)
		(end 360.160316 -265.592306)
		(width 0.2032)
		(layer "F.Cu")
		(net "PVCCIN_CPU0")
	)
	(segment
		(start 362.979716 -288.381186)
		(end 362.979716 -288.993326)
		(width 0.2032)
		(layer "F.Cu")
		(net "PVCCIN_CPU0")
	)
	(segment
		(start 359.690162 -268.033754)
		(end 359.690162 -268.569694)
		(width 0.2032)
		(layer "F.Cu")
		(net "PVCCIN_CPU0")
	)
	(segment
		(start 358.750362 -261.522718)
		(end 358.750362 -262.058404)
		(width 0.2032)
		(layer "F.Cu")
		(net "PVCCIN_CPU0")
	)
	(segment
		(start 363.449362 -282.683966)
		(end 363.449362 -283.219906)
		(width 0.2032)
		(layer "F.Cu")
		(net "PVCCIN_CPU0")
	)
	(segment
		(start 362.039916 -285.125414)
		(end 362.039916 -285.661354)
		(width 0.2032)
		(layer "F.Cu")
		(net "PVCCIN_CPU0")
	)
	(segment
		(start 366.268762 -285.939484)
		(end 366.268762 -286.475424)
		(width 0.2032)
		(layer "F.Cu")
		(net "PVCCIN_CPU0")
	)
	(segment
		(start 358.750362 -268.56944)
		(end 358.750616 -268.569694)
		(width 0.2032)
		(layer "F.Cu")
		(net "PVCCIN_CPU0")
	)
	(segment
		(start 361.099862 -262.336534)
		(end 361.099862 -262.872474)
		(width 0.2032)
		(layer "F.Cu")
		(net "PVCCIN_CPU0")
	)
	(segment
		(start 357.70058 -242.830858)
		(end 357.70058 -242.294918)
		(width 0.2032)
		(layer "F.Cu")
		(net "PVCCIN_CPU0")
	)
	(segment
		(start 364.389162 -281.05608)
		(end 364.389162 -281.59202)
		(width 0.2032)
		(layer "F.Cu")
		(net "PVCCIN_CPU0")
	)
	(segment
		(start 358.750362 -271.289272)
		(end 358.750362 -271.824958)
		(width 0.2032)
		(layer "F.Cu")
		(net "PVCCIN_CPU0")
	)
	(segment
		(start 354.991162 -289.195002)
		(end 354.991162 -289.807142)
		(width 0.2032)
		(layer "F.Cu")
		(net "PVCCIN_CPU0")
	)
	(segment
		(start 358.750362 -281.591766)
		(end 358.750616 -281.59202)
		(width 0.2032)
		(layer "F.Cu")
		(net "PVCCIN_CPU0")
	)
	(segment
		(start 366.738916 -288.381186)
		(end 366.738916 -288.917126)
		(width 0.2032)
		(layer "F.Cu")
		(net "PVCCIN_CPU0")
	)
	(segment
		(start 357.340662 -260.708648)
		(end 357.340662 -260.708902)
		(width 0.2032)
		(layer "F.Cu")
		(net "PVCCIN_CPU0")
	)
	(segment
		(start 356.401116 -280.242264)
		(end 356.401116 -280.778204)
		(width 0.2032)
		(layer "F.Cu")
		(net "PVCCIN_CPU0")
	)
	(segment
		(start 360.629962 -269.66164)
		(end 360.629962 -270.19758)
		(width 0.2032)
		(layer "F.Cu")
		(net "PVCCIN_CPU0")
	)
	(segment
		(start 362.979716 -281.869896)
		(end 362.979716 -282.405836)
		(width 0.2032)
		(layer "F.Cu")
		(net "PVCCIN_CPU0")
	)
	(segment
		(start 359.220516 -254.197612)
		(end 359.220516 -254.733552)
		(width 0.2032)
		(layer "F.Cu")
		(net "PVCCIN_CPU0")
	)
	(segment
		(start 358.750362 -281.05608)
		(end 358.750362 -281.591766)
		(width 0.2032)
		(layer "F.Cu")
		(net "PVCCIN_CPU0")
	)
	(segment
		(start 363.919516 -287.288986)
		(end 363.919262 -287.28924)
		(width 0.2032)
		(layer "F.Cu")
		(net "PVCCIN_CPU0")
	)
	(segment
		(start 358.750362 -266.405868)
		(end 358.750362 -266.941554)
		(width 0.2032)
		(layer "F.Cu")
		(net "PVCCIN_CPU0")
	)
	(segment
		(start 362.039916 -278.614378)
		(end 362.039916 -279.150318)
		(width 0.2032)
		(layer "F.Cu")
		(net "PVCCIN_CPU0")
	)
	(segment
		(start 357.900732 -316.607698)
		(end 358.84104 -315.66739)
		(width 0.508)
		(layer "F.Cu")
		(net "PVCCIN_CPU0")
	)
	(segment
		(start 364.098332 -316.607698)
		(end 365.03864 -315.66739)
		(width 0.508)
		(layer "F.Cu")
		(net "PVCCIN_CPU0")
	)
	(segment
		(start 359.110534 -246.900446)
		(end 359.110534 -246.364506)
		(width 0.2032)
		(layer "F.Cu")
		(net "PVCCIN_CPU0")
	)
	(segment
		(start 358.750362 -284.847284)
		(end 358.750616 -284.847538)
		(width 0.2032)
		(layer "F.Cu")
		(net "PVCCIN_CPU0")
	)
	(segment
		(start 360.990134 -247.992392)
		(end 360.98988 -247.992138)
		(width 0.2032)
		(layer "F.Cu")
		(net "PVCCIN_CPU0")
	)
	(segment
		(start 364.098332 -314.727082)
		(end 365.03864 -315.66739)
		(width 0.508)
		(layer "F.Cu")
		(net "PVCCIN_CPU0")
	)
	(segment
		(start 360.629962 -282.683966)
		(end 360.629962 -283.219906)
		(width 0.2032)
		(layer "F.Cu")
		(net "PVCCIN_CPU0")
	)
	(segment
		(start 365.03864 -315.66739)
		(end 365.978948 -314.727082)
		(width 0.508)
		(layer "F.Cu")
		(net "PVCCIN_CPU0")
	)
	(segment
		(start 364.859316 -285.125414)
		(end 364.859316 -285.661354)
		(width 0.2032)
		(layer "F.Cu")
		(net "PVCCIN_CPU0")
	)
	(segment
		(start 357.810562 -281.05608)
		(end 357.810562 -281.59202)
		(width 0.2032)
		(layer "F.Cu")
		(net "PVCCIN_CPU0")
	)
	(segment
		(start 353.581716 -288.381186)
		(end 353.581716 -288.917126)
		(width 0.2032)
		(layer "F.Cu")
		(net "PVCCIN_CPU0")
	)
	(segment
		(start 359.690162 -263.150604)
		(end 359.690162 -263.686544)
		(width 0.2032)
		(layer "F.Cu")
		(net "PVCCIN_CPU0")
	)
	(segment
		(start 357.810562 -263.150604)
		(end 357.810562 -263.686544)
		(width 0.2032)
		(layer "F.Cu")
		(net "PVCCIN_CPU0")
	)
	(segment
		(start 370.295932 -314.727082)
		(end 371.23624 -315.66739)
		(width 0.508)
		(layer "F.Cu")
		(net "PVCCIN_CPU0")
	)
	(segment
		(start 359.690162 -269.66164)
		(end 359.690162 -270.19758)
		(width 0.2032)
		(layer "F.Cu")
		(net "PVCCIN_CPU0")
	)
	(segment
		(start 361.569762 -264.778236)
		(end 361.569762 -265.314176)
		(width 0.2032)
		(layer "F.Cu")
		(net "PVCCIN_CPU0")
	)
	(segment
		(start 356.401116 -285.125414)
		(end 356.401116 -285.661354)
		(width 0.2032)
		(layer "F.Cu")
		(net "PVCCIN_CPU0")
	)
	(segment
		(start 365.328962 -289.195002)
		(end 365.328962 -289.807142)
		(width 0.2032)
		(layer "F.Cu")
		(net "PVCCIN_CPU0")
	)
	(segment
		(start 366.738916 -286.7533)
		(end 366.738916 -287.28924)
		(width 0.2032)
		(layer "F.Cu")
		(net "PVCCIN_CPU0")
	)
	(segment
		(start 357.810562 -264.778236)
		(end 357.810562 -265.314176)
		(width 0.2032)
		(layer "F.Cu")
		(net "PVCCIN_CPU0")
	)
	(segment
		(start 359.220516 -268.84757)
		(end 359.220516 -269.38351)
		(width 0.2032)
		(layer "F.Cu")
		(net "PVCCIN_CPU0")
	)
	(segment
		(start 362.509562 -282.683966)
		(end 362.509562 -283.219906)
		(width 0.2032)
		(layer "F.Cu")
		(net "PVCCIN_CPU0")
	)
	(segment
		(start 359.110534 -243.644928)
		(end 359.110534 -243.108988)
		(width 0.2032)
		(layer "F.Cu")
		(net "PVCCIN_CPU0")
	)
	(segment
		(start 359.220516 -259.081016)
		(end 359.220516 -259.616956)
		(width 0.2032)
		(layer "F.Cu")
		(net "PVCCIN_CPU0")
	)
	(segment
		(start 359.220516 -283.497782)
		(end 359.220516 -284.033722)
		(width 0.2032)
		(layer "F.Cu")
		(net "PVCCIN_CPU0")
	)
	(segment
		(start 362.509562 -281.05608)
		(end 362.509562 -281.59202)
		(width 0.2032)
		(layer "F.Cu")
		(net "PVCCIN_CPU0")
	)
	(segment
		(start 367.208562 -287.567116)
		(end 367.208562 -288.103056)
		(width 0.2032)
		(layer "F.Cu")
		(net "PVCCIN_CPU0")
	)
	(segment
		(start 360.050334 -243.644928)
		(end 360.050334 -243.108988)
		(width 0.2032)
		(layer "F.Cu")
		(net "PVCCIN_CPU0")
	)
	(segment
		(start 358.750362 -268.033754)
		(end 358.750362 -268.56944)
		(width 0.2032)
		(layer "F.Cu")
		(net "PVCCIN_CPU0")
	)
	(segment
		(start 363.919516 -283.497782)
		(end 363.919516 -284.033468)
		(width 0.2032)
		(layer "F.Cu")
		(net "PVCCIN_CPU0")
	)
	(segment
		(start 361.929934 -245.27256)
		(end 361.929934 -244.73662)
		(width 0.2032)
		(layer "F.Cu")
		(net "PVCCIN_CPU0")
	)
	(segment
		(start 359.690162 -276.172676)
		(end 359.690162 -276.708616)
		(width 0.2032)
		(layer "F.Cu")
		(net "PVCCIN_CPU0")
	)
	(segment
		(start 355.930962 -288.102802)
		(end 355.931216 -288.103056)
		(width 0.2032)
		(layer "F.Cu")
		(net "PVCCIN_CPU0")
	)
	(segment
		(start 358.280716 -265.592306)
		(end 358.280716 -266.128246)
		(width 0.254)
		(layer "F.Cu")
		(net "PVCCIN_CPU0")
	)
	(segment
		(start 356.870762 -287.567116)
		(end 356.870762 -288.103056)
		(width 0.2032)
		(layer "F.Cu")
		(net "PVCCIN_CPU0")
	)
	(segment
		(start 358.750362 -253.383796)
		(end 358.750362 -253.919482)
		(width 0.2032)
		(layer "F.Cu")
		(net "PVCCIN_CPU0")
	)
	(segment
		(start 357.70058 -239.039654)
		(end 357.700834 -239.0394)
		(width 0.2032)
		(layer "F.Cu")
		(net "PVCCIN_CPU0")
	)
	(segment
		(start 365.799116 -284.033468)
		(end 365.798862 -284.033722)
		(width 0.2032)
		(layer "F.Cu")
		(net "PVCCIN_CPU0")
	)
	(segment
		(start 354.991162 -284.311598)
		(end 354.991162 -284.847538)
		(width 0.2032)
		(layer "F.Cu")
		(net "PVCCIN_CPU0")
	)
	(segment
		(start 360.629962 -271.289272)
		(end 360.629962 -271.825212)
		(width 0.2032)
		(layer "F.Cu")
		(net "PVCCIN_CPU0")
	)
	(segment
		(start 361.099862 -273.730974)
		(end 361.099862 -274.266914)
		(width 0.2032)
		(layer "F.Cu")
		(net "PVCCIN_CPU0")
	)
	(segment
		(start 357.900732 -314.727082)
		(end 358.84104 -315.66739)
		(width 0.508)
		(layer "F.Cu")
		(net "PVCCIN_CPU0")
	)
	(segment
		(start 366.268762 -287.567116)
		(end 366.268762 -288.103056)
		(width 0.2032)
		(layer "F.Cu")
		(net "PVCCIN_CPU0")
	)
	(segment
		(start 359.220516 -265.592052)
		(end 359.220516 -265.592306)
		(width 0.2032)
		(layer "F.Cu")
		(net "PVCCIN_CPU0")
	)
	(segment
		(start 353.581716 -285.125414)
		(end 353.581716 -285.661354)
		(width 0.2032)
		(layer "F.Cu")
		(net "PVCCIN_CPU0")
	)
	(segment
		(start 357.70058 -239.57534)
		(end 357.70058 -239.039654)
		(width 0.2032)
		(layer "F.Cu")
		(net "PVCCIN_CPU0")
	)
	(segment
		(start 363.449362 -289.195002)
		(end 363.449362 -289.807142)
		(width 0.2032)
		(layer "F.Cu")
		(net "PVCCIN_CPU0")
	)
	(segment
		(start 361.099862 -285.125414)
		(end 361.099862 -285.661354)
		(width 0.2032)
		(layer "F.Cu")
		(net "PVCCIN_CPU0")
	)
	(segment
		(start 355.930962 -283.219652)
		(end 355.931216 -283.219906)
		(width 0.2032)
		(layer "F.Cu")
		(net "PVCCIN_CPU0")
	)
	(segment
		(start 345.525344 -314.727082)
		(end 346.465652 -315.66739)
		(width 0.508)
		(layer "F.Cu")
		(net "PVCCIN_CPU0")
	)
	(segment
		(start 357.340662 -257.45313)
		(end 357.340662 -257.98907)
		(width 0.2032)
		(layer "F.Cu")
		(net "PVCCIN_CPU0")
	)
	(segment
		(start 363.919516 -280.242264)
		(end 363.919516 -280.778204)
		(width 0.2032)
		(layer "F.Cu")
		(net "PVCCIN_CPU0")
	)
	(segment
		(start 363.919516 -288.381186)
		(end 363.919516 -288.917126)
		(width 0.2032)
		(layer "F.Cu")
		(net "PVCCIN_CPU0")
	)
	(segment
		(start 363.919516 -282.405582)
		(end 363.919262 -282.405836)
		(width 0.2032)
		(layer "F.Cu")
		(net "PVCCIN_CPU0")
	)
	(segment
		(start 359.690162 -253.383796)
		(end 359.690162 -253.919736)
		(width 0.2032)
		(layer "F.Cu")
		(net "PVCCIN_CPU0")
	)
	(segment
		(start 362.509562 -259.894832)
		(end 362.509562 -260.430772)
		(width 0.2032)
		(layer "F.Cu")
		(net "PVCCIN_CPU0")
	)
	(segment
		(start 362.039916 -263.96442)
		(end 362.039916 -264.500106)
		(width 0.2032)
		(layer "F.Cu")
		(net "PVCCIN_CPU0")
	)
	(segment
		(start 361.099862 -283.497782)
		(end 361.099862 -284.033722)
		(width 0.2032)
		(layer "F.Cu")
		(net "PVCCIN_CPU0")
	)
	(segment
		(start 357.230934 -250.155964)
		(end 357.230934 -249.620024)
		(width 0.2032)
		(layer "F.Cu")
		(net "PVCCIN_CPU0")
	)
	(segment
		(start 362.039916 -283.497782)
		(end 362.039916 -284.033722)
		(width 0.2032)
		(layer "F.Cu")
		(net "PVCCIN_CPU0")
	)
	(segment
		(start 359.690162 -258.2672)
		(end 359.690162 -258.80314)
		(width 0.2032)
		(layer "F.Cu")
		(net "PVCCIN_CPU0")
	)
	(segment
		(start 358.640634 -242.830858)
		(end 358.640634 -242.294918)
		(width 0.2032)
		(layer "F.Cu")
		(net "PVCCIN_CPU0")
	)
	(segment
		(start 358.750362 -279.428194)
		(end 358.750362 -279.96388)
		(width 0.2032)
		(layer "F.Cu")
		(net "PVCCIN_CPU0")
	)
	(segment
		(start 360.629962 -285.939484)
		(end 360.629962 -286.475424)
		(width 0.2032)
		(layer "F.Cu")
		(net "PVCCIN_CPU0")
	)
	(segment
		(start 355.930962 -282.683966)
		(end 355.930962 -283.219652)
		(width 0.2032)
		(layer "F.Cu")
		(net "PVCCIN_CPU0")
	)
	(segment
		(start 362.399834 -242.830858)
		(end 362.399834 -242.294918)
		(width 0.2032)
		(layer "F.Cu")
		(net "PVCCIN_CPU0")
	)
	(segment
		(start 359.220516 -260.708902)
		(end 359.220516 -261.244842)
		(width 0.2032)
		(layer "F.Cu")
		(net "PVCCIN_CPU0")
	)
	(segment
		(start 358.640634 -247.714262)
		(end 358.640634 -247.178322)
		(width 0.2032)
		(layer "F.Cu")
		(net "PVCCIN_CPU0")
	)
	(segment
		(start 357.810562 -259.894832)
		(end 357.810562 -260.430772)
		(width 0.2032)
		(layer "F.Cu")
		(net "PVCCIN_CPU0")
	)
	(segment
		(start 362.039916 -257.45313)
		(end 362.039916 -257.98907)
		(width 0.2032)
		(layer "F.Cu")
		(net "PVCCIN_CPU0")
	)
	(segment
		(start 358.750362 -285.939484)
		(end 358.750362 -286.47517)
		(width 0.2032)
		(layer "F.Cu")
		(net "PVCCIN_CPU0")
	)
	(segment
		(start 362.399834 -240.667286)
		(end 362.399834 -241.203226)
		(width 0.2032)
		(layer "F.Cu")
		(net "PVCCIN_CPU0")
	)
	(segment
		(start 357.70058 -244.458744)
		(end 357.70058 -243.922804)
		(width 0.2032)
		(layer "F.Cu")
		(net "PVCCIN_CPU0")
	)
	(segment
		(start 360.050334 -246.900446)
		(end 360.050334 -246.364506)
		(width 0.2032)
		(layer "F.Cu")
		(net "PVCCIN_CPU0")
	)
	(segment
		(start 358.750362 -255.011682)
		(end 358.750362 -255.547368)
		(width 0.2032)
		(layer "F.Cu")
		(net "PVCCIN_CPU0")
	)
	(segment
		(start 358.750362 -271.824958)
		(end 358.750616 -271.825212)
		(width 0.2032)
		(layer "F.Cu")
		(net "PVCCIN_CPU0")
	)
	(segment
		(start 354.051362 -284.311598)
		(end 354.051362 -284.847538)
		(width 0.2032)
		(layer "F.Cu")
		(net "PVCCIN_CPU0")
	)
	(segment
		(start 370.295932 -316.607698)
		(end 371.23624 -315.66739)
		(width 0.508)
		(layer "F.Cu")
		(net "PVCCIN_CPU0")
	)
	(segment
		(start 359.220516 -257.45313)
		(end 359.220516 -257.98907)
		(width 0.2032)
		(layer "F.Cu")
		(net "PVCCIN_CPU0")
	)
	(segment
		(start 362.039916 -276.986492)
		(end 362.039916 -277.522178)
		(width 0.2032)
		(layer "F.Cu")
		(net "PVCCIN_CPU0")
	)
	(segment
		(start 360.990134 -244.736874)
		(end 360.98988 -244.73662)
		(width 0.2032)
		(layer "F.Cu")
		(net "PVCCIN_CPU0")
	)
	(segment
		(start 361.099862 -278.614378)
		(end 361.099862 -279.150318)
		(width 0.2032)
		(layer "F.Cu")
		(net "PVCCIN_CPU0")
	)
	(segment
		(start 365.328962 -287.567116)
		(end 365.328962 -288.103056)
		(width 0.2032)
		(layer "F.Cu")
		(net "PVCCIN_CPU0")
	)
	(segment
		(start 355.930962 -286.47517)
		(end 355.931216 -286.475424)
		(width 0.2032)
		(layer "F.Cu")
		(net "PVCCIN_CPU0")
	)
	(segment
		(start 365.328962 -284.311598)
		(end 365.328962 -284.847538)
		(width 0.2032)
		(layer "F.Cu")
		(net "PVCCIN_CPU0")
	)
	(segment
		(start 357.810562 -279.428194)
		(end 357.810562 -279.964134)
		(width 0.2032)
		(layer "F.Cu")
		(net "PVCCIN_CPU0")
	)
	(segment
		(start 359.110534 -240.389156)
		(end 359.110534 -239.853216)
		(width 0.2032)
		(layer "F.Cu")
		(net "PVCCIN_CPU0")
	)
	(segment
		(start 354.521516 -285.125414)
		(end 354.521516 -285.661354)
		(width 0.2032)
		(layer "F.Cu")
		(net "PVCCIN_CPU0")
	)
	(segment
		(start 358.750362 -277.800562)
		(end 358.750362 -278.336502)
		(width 0.2032)
		(layer "F.Cu")
		(net "PVCCIN_CPU0")
	)
	(segment
		(start 362.509562 -263.150604)
		(end 362.509562 -263.686544)
		(width 0.2032)
		(layer "F.Cu")
		(net "PVCCIN_CPU0")
	)
	(segment
		(start 354.051362 -289.195002)
		(end 354.051362 -289.807142)
		(width 0.2032)
		(layer "F.Cu")
		(net "PVCCIN_CPU0")
	)
	(segment
		(start 360.51998 -246.08663)
		(end 360.51998 -245.55069)
		(width 0.2032)
		(layer "F.Cu")
		(net "PVCCIN_CPU0")
	)
	(segment
		(start 357.810562 -261.522718)
		(end 357.810562 -262.058658)
		(width 0.2032)
		(layer "F.Cu")
		(net "PVCCIN_CPU0")
	)
	(segment
		(start 359.58018 -239.57534)
		(end 359.58018 -239.039654)
		(width 0.2032)
		(layer "F.Cu")
		(net "PVCCIN_CPU0")
	)
	(segment
		(start 358.750362 -266.941554)
		(end 358.750616 -266.941808)
		(width 0.2032)
		(layer "F.Cu")
		(net "PVCCIN_CPU0")
	)
	(segment
		(start 357.230934 -242.017042)
		(end 357.230934 -241.481102)
		(width 0.2032)
		(layer "F.Cu")
		(net "PVCCIN_CPU0")
	)
	(segment
		(start 358.750362 -275.080476)
		(end 358.750616 -275.08073)
		(width 0.2032)
		(layer "F.Cu")
		(net "PVCCIN_CPU0")
	)
	(segment
		(start 354.991162 -287.567116)
		(end 354.991162 -288.103056)
		(width 0.2032)
		(layer "F.Cu")
		(net "PVCCIN_CPU0")
	)
	(segment
		(start 362.039916 -277.522178)
		(end 362.039662 -277.522432)
		(width 0.2032)
		(layer "F.Cu")
		(net "PVCCIN_CPU0")
	)
	(segment
		(start 360.160316 -288.381186)
		(end 360.160316 -288.993326)
		(width 0.2032)
		(layer "F.Cu")
		(net "PVCCIN_CPU0")
	)
	(segment
		(start 359.220516 -265.592306)
		(end 359.220516 -266.128246)
		(width 0.2032)
		(layer "F.Cu")
		(net "PVCCIN_CPU0")
	)
	(segment
		(start 365.799116 -283.497782)
		(end 365.799116 -284.033468)
		(width 0.2032)
		(layer "F.Cu")
		(net "PVCCIN_CPU0")
	)
	(segment
		(start 358.280716 -278.614378)
		(end 358.280716 -279.150318)
		(width 0.254)
		(layer "F.Cu")
		(net "PVCCIN_CPU0")
	)
	(segment
		(start 360.629962 -276.172676)
		(end 360.629962 -276.708616)
		(width 0.2032)
		(layer "F.Cu")
		(net "PVCCIN_CPU0")
	)
	(segment
		(start 359.220516 -260.708648)
		(end 359.220516 -260.708902)
		(width 0.2032)
		(layer "F.Cu")
		(net "PVCCIN_CPU0")
	)
	(segment
		(start 360.990134 -248.528078)
		(end 360.990134 -247.992392)
		(width 0.2032)
		(layer "F.Cu")
		(net "PVCCIN_CPU0")
	)
	(segment
		(start 359.690162 -272.917158)
		(end 359.690162 -273.453098)
		(width 0.2032)
		(layer "F.Cu")
		(net "PVCCIN_CPU0")
	)
	(segment
		(start 360.990134 -243.109242)
		(end 360.98988 -243.108988)
		(width 0.2032)
		(layer "F.Cu")
		(net "PVCCIN_CPU0")
	)
	(segment
		(start 357.810562 -256.639314)
		(end 357.810562 -257.175254)
		(width 0.2032)
		(layer "F.Cu")
		(net "PVCCIN_CPU0")
	)
	(segment
		(start 357.810562 -285.939484)
		(end 357.810562 -286.475424)
		(width 0.2032)
		(layer "F.Cu")
		(net "PVCCIN_CPU0")
	)
	(segment
		(start 359.690162 -264.778236)
		(end 359.690162 -265.314176)
		(width 0.2032)
		(layer "F.Cu")
		(net "PVCCIN_CPU0")
	)
	(segment
		(start 359.58018 -249.342148)
		(end 359.58018 -248.806208)
		(width 0.2032)
		(layer "F.Cu")
		(net "PVCCIN_CPU0")
	)
	(segment
		(start 360.990134 -246.36476)
		(end 360.98988 -246.364506)
		(width 0.2032)
		(layer "F.Cu")
		(net "PVCCIN_CPU0")
	)
	(segment
		(start 360.050334 -248.528078)
		(end 360.050334 -247.992138)
		(width 0.2032)
		(layer "F.Cu")
		(net "PVCCIN_CPU0")
	)
	(segment
		(start 358.750362 -286.47517)
		(end 358.750616 -286.475424)
		(width 0.2032)
		(layer "F.Cu")
		(net "PVCCIN_CPU0")
	)
	(segment
		(start 360.629962 -284.311598)
		(end 360.629962 -284.847538)
		(width 0.2032)
		(layer "F.Cu")
		(net "PVCCIN_CPU0")
	)
	(segment
		(start 362.039916 -286.7533)
		(end 362.039916 -287.28924)
		(width 0.2032)
		(layer "F.Cu")
		(net "PVCCIN_CPU0")
	)
	(segment
		(start 360.160316 -263.96442)
		(end 360.160316 -264.50036)
		(width 0.2032)
		(layer "F.Cu")
		(net "PVCCIN_CPU0")
	)
	(segment
		(start 360.629962 -256.639314)
		(end 360.629962 -257.175254)
		(width 0.2032)
		(layer "F.Cu")
		(net "PVCCIN_CPU0")
	)
	(segment
		(start 357.810562 -258.2672)
		(end 357.810562 -258.80314)
		(width 0.2032)
		(layer "F.Cu")
		(net "PVCCIN_CPU0")
	)
	(segment
		(start 357.340662 -260.708902)
		(end 357.340662 -261.244842)
		(width 0.2032)
		(layer "F.Cu")
		(net "PVCCIN_CPU0")
	)
	(segment
		(start 360.629962 -272.917158)
		(end 360.629962 -273.453098)
		(width 0.2032)
		(layer "F.Cu")
		(net "PVCCIN_CPU0")
	)
	(segment
		(start 360.51998 -249.342148)
		(end 360.51998 -248.806208)
		(width 0.2032)
		(layer "F.Cu")
		(net "PVCCIN_CPU0")
	)
	(segment
		(start 359.220516 -276.986492)
		(end 359.220516 -277.522432)
		(width 0.2032)
		(layer "F.Cu")
		(net "PVCCIN_CPU0")
	)
	(segment
		(start 361.099862 -280.242264)
		(end 361.099862 -280.778204)
		(width 0.2032)
		(layer "F.Cu")
		(net "PVCCIN_CPU0")
	)
	(segment
		(start 359.220516 -288.381186)
		(end 359.220516 -288.993326)
		(width 0.2032)
		(layer "F.Cu")
		(net "PVCCIN_CPU0")
	)
	(segment
		(start 356.401116 -283.497782)
		(end 356.401116 -284.033722)
		(width 0.2032)
		(layer "F.Cu")
		(net "PVCCIN_CPU0")
	)
	(segment
		(start 358.750362 -283.219652)
		(end 358.750616 -283.219906)
		(width 0.2032)
		(layer "F.Cu")
		(net "PVCCIN_CPU0")
	)
	(segment
		(start 357.810562 -284.311598)
		(end 357.810562 -284.847538)
		(width 0.2032)
		(layer "F.Cu")
		(net "PVCCIN_CPU0")
	)
	(segment
		(start 361.099862 -275.35886)
		(end 361.099862 -275.8948)
		(width 0.2032)
		(layer "F.Cu")
		(net "PVCCIN_CPU0")
	)
	(segment
		(start 359.690162 -256.639314)
		(end 359.690162 -257.175254)
		(width 0.2032)
		(layer "F.Cu")
		(net "PVCCIN_CPU0")
	)
	(segment
		(start 359.690162 -259.894832)
		(end 359.690162 -260.430772)
		(width 0.2032)
		(layer "F.Cu")
		(net "PVCCIN_CPU0")
	)
	(segment
		(start 360.629962 -274.54479)
		(end 360.629962 -275.08073)
		(width 0.2032)
		(layer "F.Cu")
		(net "PVCCIN_CPU0")
	)
	(segment
		(start 361.929934 -242.017042)
		(end 361.929934 -241.481102)
		(width 0.2032)
		(layer "F.Cu")
		(net "PVCCIN_CPU0")
	)
	(segment
		(start 352.663252 -315.66739)
		(end 353.60356 -316.607698)
		(width 0.508)
		(layer "F.Cu")
		(net "PVCCIN_CPU0")
	)
	(segment
		(start 360.160316 -265.592306)
		(end 360.160316 -266.128246)
		(width 0.2032)
		(layer "F.Cu")
		(net "PVCCIN_CPU0")
	)
	(segment
		(start 358.640634 -239.57534)
		(end 358.640634 -239.0394)
		(width 0.2032)
		(layer "F.Cu")
		(net "PVCCIN_CPU0")
	)
	(segment
		(start 358.280716 -265.592052)
		(end 358.280716 -265.592306)
		(width 0.254)
		(layer "F.Cu")
		(net "PVCCIN_CPU0")
	)
	(segment
		(start 357.810562 -255.011682)
		(end 357.810562 -255.547622)
		(width 0.2032)
		(layer "F.Cu")
		(net "PVCCIN_CPU0")
	)
	(segment
		(start 351.722944 -314.727082)
		(end 352.663252 -315.66739)
		(width 0.508)
		(layer "F.Cu")
		(net "PVCCIN_CPU0")
	)
	(segment
		(start 359.690162 -287.567116)
		(end 359.690162 -288.103056)
		(width 0.2032)
		(layer "F.Cu")
		(net "PVCCIN_CPU0")
	)
	(segment
		(start 358.750362 -284.311598)
		(end 358.750362 -284.847284)
		(width 0.2032)
		(layer "F.Cu")
		(net "PVCCIN_CPU0")
	)
	(segment
		(start 358.84104 -315.66739)
		(end 359.781348 -316.607698)
		(width 0.508)
		(layer "F.Cu")
		(net "PVCCIN_CPU0")
	)
	(segment
		(start 359.58018 -239.039654)
		(end 359.580434 -239.0394)
		(width 0.2032)
		(layer "F.Cu")
		(net "PVCCIN_CPU0")
	)
	(segment
		(start 356.870762 -279.428194)
		(end 356.870762 -279.964134)
		(width 0.2032)
		(layer "F.Cu")
		(net "PVCCIN_CPU0")
	)
	(segment
		(start 360.629962 -253.383796)
		(end 360.629962 -253.919736)
		(width 0.2032)
		(layer "F.Cu")
		(net "PVCCIN_CPU0")
	)
	(segment
		(start 359.220516 -275.35886)
		(end 359.220516 -275.8948)
		(width 0.2032)
		(layer "F.Cu")
		(net "PVCCIN_CPU0")
	)
	(segment
		(start 360.629962 -264.778236)
		(end 360.629962 -265.314176)
		(width 0.2032)
		(layer "F.Cu")
		(net "PVCCIN_CPU0")
	)
	(segment
		(start 360.629962 -266.405868)
		(end 360.629962 -266.941808)
		(width 0.2032)
		(layer "F.Cu")
		(net "PVCCIN_CPU0")
	)
	(segment
		(start 359.220516 -270.475456)
		(end 359.220516 -271.011396)
		(width 0.2032)
		(layer "F.Cu")
		(net "PVCCIN_CPU0")
	)
	(segment
		(start 360.51998 -247.714262)
		(end 360.51998 -247.178322)
		(width 0.2032)
		(layer "F.Cu")
		(net "PVCCIN_CPU0")
	)
	(segment
		(start 366.268762 -289.195002)
		(end 366.268762 -289.807142)
		(width 0.2032)
		(layer "F.Cu")
		(net "PVCCIN_CPU0")
	)
	(segment
		(start 357.70058 -249.342148)
		(end 357.70058 -248.806208)
		(width 0.2032)
		(layer "F.Cu")
		(net "PVCCIN_CPU0")
	)
	(segment
		(start 364.859316 -281.869896)
		(end 364.859316 -282.405836)
		(width 0.2032)
		(layer "F.Cu")
		(net "PVCCIN_CPU0")
	)
	(segment
		(start 359.690162 -274.54479)
		(end 359.690162 -275.08073)
		(width 0.2032)
		(layer "F.Cu")
		(net "PVCCIN_CPU0")
	)
	(segment
		(start 358.750362 -264.778236)
		(end 358.750362 -265.314176)
		(width 0.2032)
		(layer "F.Cu")
		(net "PVCCIN_CPU0")
	)
	(segment
		(start 360.160316 -275.35886)
		(end 360.160316 -275.8948)
		(width 0.2032)
		(layer "F.Cu")
		(net "PVCCIN_CPU0")
	)
	(segment
		(start 359.220516 -255.825498)
		(end 359.220516 -256.361438)
		(width 0.2032)
		(layer "F.Cu")
		(net "PVCCIN_CPU0")
	)
	(segment
		(start 359.220516 -267.219938)
		(end 359.220516 -267.755878)
		(width 0.2032)
		(layer "F.Cu")
		(net "PVCCIN_CPU0")
	)
	(segment
		(start 361.099862 -268.84757)
		(end 361.099862 -269.38351)
		(width 0.2032)
		(layer "F.Cu")
		(net "PVCCIN_CPU0")
	)
	(segment
		(start 363.449362 -281.05608)
		(end 363.449362 -281.59202)
		(width 0.2032)
		(layer "F.Cu")
		(net "PVCCIN_CPU0")
	)
	(segment
		(start 354.521516 -286.7533)
		(end 354.521516 -287.28924)
		(width 0.2032)
		(layer "F.Cu")
		(net "PVCCIN_CPU0")
	)
	(segment
		(start 359.110534 -245.27256)
		(end 359.110534 -244.73662)
		(width 0.2032)
		(layer "F.Cu")
		(net "PVCCIN_CPU0")
	)
	(segment
		(start 355.930962 -284.847284)
		(end 355.931216 -284.847538)
		(width 0.2032)
		(layer "F.Cu")
		(net "PVCCIN_CPU0")
	)
	(segment
		(start 357.340662 -286.7533)
		(end 357.340662 -287.28924)
		(width 0.2032)
		(layer "F.Cu")
		(net "PVCCIN_CPU0")
	)
	(segment
		(start 363.919516 -285.6611)
		(end 363.919262 -285.661354)
		(width 0.2032)
		(layer "F.Cu")
		(net "PVCCIN_CPU0")
	)
	(segment
		(start 357.340662 -255.825498)
		(end 357.340662 -256.361438)
		(width 0.2032)
		(layer "F.Cu")
		(net "PVCCIN_CPU0")
	)
	(segment
		(start 362.979716 -285.125414)
		(end 362.979716 -285.661354)
		(width 0.2032)
		(layer "F.Cu")
		(net "PVCCIN_CPU0")
	)
	(segment
		(start 365.799116 -288.381186)
		(end 365.799116 -288.917126)
		(width 0.2032)
		(layer "F.Cu")
		(net "PVCCIN_CPU0")
	)
	(segment
		(start 362.039916 -255.825498)
		(end 362.039916 -256.361438)
		(width 0.2032)
		(layer "F.Cu")
		(net "PVCCIN_CPU0")
	)
	(segment
		(start 358.750362 -276.172676)
		(end 358.750362 -276.708362)
		(width 0.2032)
		(layer "F.Cu")
		(net "PVCCIN_CPU0")
	)
	(segment
		(start 358.750362 -263.150604)
		(end 358.750362 -263.686544)
		(width 0.2032)
		(layer "F.Cu")
		(net "PVCCIN_CPU0")
	)
	(segment
		(start 362.509562 -261.522718)
		(end 362.509562 -262.058658)
		(width 0.2032)
		(layer "F.Cu")
		(net "PVCCIN_CPU0")
	)
	(segment
		(start 360.160316 -267.219938)
		(end 360.160316 -267.755878)
		(width 0.2032)
		(layer "F.Cu")
		(net "PVCCIN_CPU0")
	)
	(segment
		(start 362.399834 -248.806208)
		(end 362.399834 -249.342148)
		(width 0.2032)
		(layer "F.Cu")
		(net "PVCCIN_CPU0")
	)
	(segment
		(start 360.629962 -263.150604)
		(end 360.629962 -263.686544)
		(width 0.2032)
		(layer "F.Cu")
		(net "PVCCIN_CPU0")
	)
	(segment
		(start 362.979716 -280.242264)
		(end 362.979716 -280.778204)
		(width 0.2032)
		(layer "F.Cu")
		(net "PVCCIN_CPU0")
	)
	(segment
		(start 357.70058 -246.08663)
		(end 357.70058 -245.55069)
		(width 0.2032)
		(layer "F.Cu")
		(net "PVCCIN_CPU0")
	)
	(segment
		(start 354.051362 -287.567116)
		(end 354.051362 -288.103056)
		(width 0.2032)
		(layer "F.Cu")
		(net "PVCCIN_CPU0")
	)
	(segment
		(start 354.051362 -285.939484)
		(end 354.051362 -286.475424)
		(width 0.2032)
		(layer "F.Cu")
		(net "PVCCIN_CPU0")
	)
	(segment
		(start 363.449362 -284.311598)
		(end 363.449362 -284.847538)
		(width 0.2032)
		(layer "F.Cu")
		(net "PVCCIN_CPU0")
	)
	(segment
		(start 360.629962 -277.800562)
		(end 360.629962 -278.336502)
		(width 0.2032)
		(layer "F.Cu")
		(net "PVCCIN_CPU0")
	)
	(segment
		(start 360.51998 -239.57534)
		(end 360.51998 -239.039654)
		(width 0.2032)
		(layer "F.Cu")
		(net "PVCCIN_CPU0")
	)
	(segment
		(start 362.039916 -281.869896)
		(end 362.039916 -282.405836)
		(width 0.2032)
		(layer "F.Cu")
		(net "PVCCIN_CPU0")
	)
	(segment
		(start 364.389162 -289.195002)
		(end 364.389162 -289.807142)
		(width 0.2032)
		(layer "F.Cu")
		(net "PVCCIN_CPU0")
	)
	(segment
		(start 359.690162 -261.522718)
		(end 359.690162 -262.058658)
		(width 0.2032)
		(layer "F.Cu")
		(net "PVCCIN_CPU0")
	)
	(segment
		(start 362.039916 -288.381186)
		(end 362.039916 -288.993326)
		(width 0.2032)
		(layer "F.Cu")
		(net "PVCCIN_CPU0")
	)
	(segment
		(start 356.870762 -289.195002)
		(end 356.870762 -289.807142)
		(width 0.2032)
		(layer "F.Cu")
		(net "PVCCIN_CPU0")
	)
	(segment
		(start 354.991162 -285.939484)
		(end 354.991162 -286.475424)
		(width 0.2032)
		(layer "F.Cu")
		(net "PVCCIN_CPU0")
	)
	(segment
		(start 353.111562 -289.195002)
		(end 353.111562 -289.807142)
		(width 0.2032)
		(layer "F.Cu")
		(net "PVCCIN_CPU0")
	)
	(segment
		(start 354.521516 -288.381186)
		(end 354.521516 -288.917126)
		(width 0.2032)
		(layer "F.Cu")
		(net "PVCCIN_CPU0")
	)
	(segment
		(start 363.919516 -285.125414)
		(end 363.919516 -285.6611)
		(width 0.2032)
		(layer "F.Cu")
		(net "PVCCIN_CPU0")
	)
	(segment
		(start 357.70058 -241.203226)
		(end 357.70058 -240.667286)
		(width 0.2032)
		(layer "F.Cu")
		(net "PVCCIN_CPU0")
	)
	(segment
		(start 357.230934 -240.389156)
		(end 357.230934 -239.853216)
		(width 0.2032)
		(layer "F.Cu")
		(net "PVCCIN_CPU0")
	)
	(segment
		(start 358.750362 -259.894832)
		(end 358.750362 -260.430518)
		(width 0.2032)
		(layer "F.Cu")
		(net "PVCCIN_CPU0")
	)
	(segment
		(start 356.401116 -281.869896)
		(end 356.401116 -282.405836)
		(width 0.2032)
		(layer "F.Cu")
		(net "PVCCIN_CPU0")
	)
	(segment
		(start 357.340662 -263.96442)
		(end 357.340662 -264.50036)
		(width 0.2032)
		(layer "F.Cu")
		(net "PVCCIN_CPU0")
	)
	(segment
		(start 360.990134 -242.017042)
		(end 360.990134 -241.481356)
		(width 0.2032)
		(layer "F.Cu")
		(net "PVCCIN_CPU0")
	)
	(segment
		(start 361.929934 -243.108988)
		(end 361.929934 -243.644928)
		(width 0.2032)
		(layer "F.Cu")
		(net "PVCCIN_CPU0")
	)
	(segment
		(start 361.569762 -277.800562)
		(end 361.569762 -278.336502)
		(width 0.254)
		(layer "F.Cu")
		(net "PVCCIN_CPU0")
	)
	(segment
		(start 359.220516 -273.730974)
		(end 359.220516 -274.266914)
		(width 0.2032)
		(layer "F.Cu")
		(net "PVCCIN_CPU0")
	)
	(segment
		(start 358.750362 -279.96388)
		(end 358.750616 -279.964134)
		(width 0.2032)
		(layer "F.Cu")
		(net "PVCCIN_CPU0")
	)
	(segment
		(start 361.099862 -254.197612)
		(end 361.099862 -254.733552)
		(width 0.2032)
		(layer "F.Cu")
		(net "PVCCIN_CPU0")
	)
	(segment
		(start 359.110534 -242.017042)
		(end 359.110534 -241.481102)
		(width 0.2032)
		(layer "F.Cu")
		(net "PVCCIN_CPU0")
	)
	(segment
		(start 359.58018 -246.08663)
		(end 359.58018 -245.55069)
		(width 0.2032)
		(layer "F.Cu")
		(net "PVCCIN_CPU0")
	)
	(via
		(at 355.301804 -246.659146)
		(size 0.4572)
		(drill 0.2032)
		(layers "F.Cu" "B.Cu")
		(net "PVCCIN_CPU0")
	)
	(via
		(at 353.581716 -285.661354)
		(size 0.4572)
		(drill 0.2032)
		(layers "F.Cu" "B.Cu")
		(net "PVCCIN_CPU0")
	)
	(via
		(at 355.081332 -321.139312)
		(size 0.508)
		(drill 0.254)
		(layers "F.Cu" "B.Cu")
		(net "PVCCIN_CPU0")
	)
	(via
		(at 360.629962 -275.08073)
		(size 0.4572)
		(drill 0.2032)
		(layers "F.Cu" "B.Cu")
		(net "PVCCIN_CPU0")
	)
	(via
		(at 359.220516 -262.872474)
		(size 0.4572)
		(drill 0.2032)
		(layers "F.Cu" "B.Cu")
		(net "PVCCIN_CPU0")
	)
	(via
		(at 383.844546 -327.661778)
		(size 0.508)
		(drill 0.254)
		(layers "F.Cu" "B.Cu")
		(net "PVCCIN_CPU0")
	)
	(via
		(at 363.449362 -289.807142)
		(size 0.4572)
		(drill 0.2032)
		(layers "F.Cu" "B.Cu")
		(net "PVCCIN_CPU0")
	)
	(via
		(at 354.604574 -292.955726)
		(size 0.508)
		(drill 0.254)
		(layers "F.Cu" "B.Cu")
		(net "PVCCIN_CPU0")
	)
	(via
		(at 355.931216 -284.847538)
		(size 0.4572)
		(drill 0.2032)
		(layers "F.Cu" "B.Cu")
		(net "PVCCIN_CPU0")
	)
	(via
		(at 375.665746 -319.851278)
		(size 0.508)
		(drill 0.254)
		(layers "F.Cu" "B.Cu")
		(net "PVCCIN_CPU0")
	)
	(via
		(at 354.440744 -320.510154)
		(size 0.508)
		(drill 0.254)
		(layers "F.Cu" "B.Cu")
		(net "PVCCIN_CPU0")
	)
	(via
		(at 342.232234 -321.199256)
		(size 0.508)
		(drill 0.254)
		(layers "F.Cu" "B.Cu")
		(net "PVCCIN_CPU0")
	)
	(via
		(at 354.031804 -242.981226)
		(size 0.4572)
		(drill 0.2032)
		(layers "F.Cu" "B.Cu")
		(net "PVCCIN_CPU0")
	)
	(via
		(at 359.220516 -267.755878)
		(size 0.4572)
		(drill 0.2032)
		(layers "F.Cu" "B.Cu")
		(net "PVCCIN_CPU0")
	)
	(via
		(at 358.750616 -253.919736)
		(size 0.4572)
		(drill 0.2032)
		(layers "F.Cu" "B.Cu")
		(net "PVCCIN_CPU0")
	)
	(via
		(at 364.37443 -257.692906)
		(size 0.4572)
		(drill 0.2032)
		(layers "F.Cu" "B.Cu")
		(net "PVCCIN_CPU0")
	)
	(via
		(at 362.399834 -242.294918)
		(size 0.4572)
		(drill 0.2032)
		(layers "F.Cu" "B.Cu")
		(net "PVCCIN_CPU0")
	)
	(via
		(at 385.153154 -328.346816)
		(size 0.508)
		(drill 0.254)
		(layers "F.Cu" "B.Cu")
		(net "PVCCIN_CPU0")
	)
	(via
		(at 334.068166 -323.160898)
		(size 0.508)
		(drill 0.254)
		(layers "F.Cu" "B.Cu")
		(net "PVCCIN_CPU0")
	)
	(via
		(at 361.929934 -249.620024)
		(size 0.4572)
		(drill 0.2032)
		(layers "F.Cu" "B.Cu")
		(net "PVCCIN_CPU0")
	)
	(via
		(at 359.220516 -271.011396)
		(size 0.4572)
		(drill 0.2032)
		(layers "F.Cu" "B.Cu")
		(net "PVCCIN_CPU0")
	)
	(via
		(at 359.690162 -268.569694)
		(size 0.4572)
		(drill 0.2032)
		(layers "F.Cu" "B.Cu")
		(net "PVCCIN_CPU0")
	)
	(via
		(at 357.810562 -255.547622)
		(size 0.4572)
		(drill 0.2032)
		(layers "F.Cu" "B.Cu")
		(net "PVCCIN_CPU0")
	)
	(via
		(at 351.037144 -321.873372)
		(size 0.508)
		(drill 0.254)
		(layers "F.Cu" "B.Cu")
		(net "PVCCIN_CPU0")
	)
	(via
		(at 351.067116 -321.158362)
		(size 0.508)
		(drill 0.254)
		(layers "F.Cu" "B.Cu")
		(net "PVCCIN_CPU0")
	)
	(via
		(at 375.650506 -320.504058)
		(size 0.508)
		(drill 0.254)
		(layers "F.Cu" "B.Cu")
		(net "PVCCIN_CPU0")
	)
	(via
		(at 359.896664 -321.873372)
		(size 0.508)
		(drill 0.254)
		(layers "F.Cu" "B.Cu")
		(net "PVCCIN_CPU0")
	)
	(via
		(at 376.283474 -321.882516)
		(size 0.508)
		(drill 0.254)
		(layers "F.Cu" "B.Cu")
		(net "PVCCIN_CPU0")
	)
	(via
		(at 362.65993 -321.146932)
		(size 0.508)
		(drill 0.254)
		(layers "F.Cu" "B.Cu")
		(net "PVCCIN_CPU0")
	)
	(via
		(at 360.160316 -284.033722)
		(size 0.4572)
		(drill 0.2032)
		(layers "F.Cu" "B.Cu")
		(net "PVCCIN_CPU0")
	)
	(via
		(at 360.51998 -245.55069)
		(size 0.4572)
		(drill 0.2032)
		(layers "F.Cu" "B.Cu")
		(net "PVCCIN_CPU0")
	)
	(via
		(at 362.656882 -319.875154)
		(size 0.508)
		(drill 0.254)
		(layers "F.Cu" "B.Cu")
		(net "PVCCIN_CPU0")
	)
	(via
		(at 358.750616 -271.825212)
		(size 0.4572)
		(drill 0.2032)
		(layers "F.Cu" "B.Cu")
		(net "PVCCIN_CPU0")
	)
	(via
		(at 361.929934 -243.108988)
		(size 0.4572)
		(drill 0.2032)
		(layers "F.Cu" "B.Cu")
		(net "PVCCIN_CPU0")
	)
	(via
		(at 358.280716 -264.50036)
		(size 0.4572)
		(drill 0.2032)
		(layers "F.Cu" "B.Cu")
		(net "PVCCIN_CPU0")
	)
	(via
		(at 357.810562 -286.475424)
		(size 0.4572)
		(drill 0.2032)
		(layers "F.Cu" "B.Cu")
		(net "PVCCIN_CPU0")
	)
	(via
		(at 362.039916 -287.28924)
		(size 0.4572)
		(drill 0.2032)
		(layers "F.Cu" "B.Cu")
		(net "PVCCIN_CPU0")
	)
	(via
		(at 361.099862 -284.033722)
		(size 0.4572)
		(drill 0.2032)
		(layers "F.Cu" "B.Cu")
		(net "PVCCIN_CPU0")
	)
	(via
		(at 382.674114 -329.441556)
		(size 0.508)
		(drill 0.254)
		(layers "F.Cu" "B.Cu")
		(net "PVCCIN_CPU0")
	)
	(via
		(at 356.620064 -261.366762)
		(size 0.4572)
		(drill 0.2032)
		(layers "F.Cu" "B.Cu")
		(net "PVCCIN_CPU0")
	)
	(via
		(at 359.220516 -284.033722)
		(size 0.4572)
		(drill 0.2032)
		(layers "F.Cu" "B.Cu")
		(net "PVCCIN_CPU0")
	)
	(via
		(at 359.690162 -270.19758)
		(size 0.4572)
		(drill 0.2032)
		(layers "F.Cu" "B.Cu")
		(net "PVCCIN_CPU0")
	)
	(via
		(at 365.328962 -288.103056)
		(size 0.4572)
		(drill 0.2032)
		(layers "F.Cu" "B.Cu")
		(net "PVCCIN_CPU0")
	)
	(via
		(at 356.401116 -282.405836)
		(size 0.4572)
		(drill 0.2032)
		(layers "F.Cu" "B.Cu")
		(net "PVCCIN_CPU0")
	)
	(via
		(at 355.078284 -320.502534)
		(size 0.508)
		(drill 0.254)
		(layers "F.Cu" "B.Cu")
		(net "PVCCIN_CPU0")
	)
	(via
		(at 360.98988 -239.853216)
		(size 0.4572)
		(drill 0.2032)
		(layers "F.Cu" "B.Cu")
		(net "PVCCIN_CPU0")
	)
	(via
		(at 360.51998 -247.178322)
		(size 0.4572)
		(drill 0.2032)
		(layers "F.Cu" "B.Cu")
		(net "PVCCIN_CPU0")
	)
	(via
		(at 356.870762 -283.219906)
		(size 0.4572)
		(drill 0.2032)
		(layers "F.Cu" "B.Cu")
		(net "PVCCIN_CPU0")
	)
	(via
		(at 359.220516 -259.616956)
		(size 0.4572)
		(drill 0.2032)
		(layers "F.Cu" "B.Cu")
		(net "PVCCIN_CPU0")
	)
	(via
		(at 334.74533 -323.84619)
		(size 0.508)
		(drill 0.254)
		(layers "F.Cu" "B.Cu")
		(net "PVCCIN_CPU0")
	)
	(via
		(at 383.857754 -328.346816)
		(size 0.508)
		(drill 0.254)
		(layers "F.Cu" "B.Cu")
		(net "PVCCIN_CPU0")
	)
	(via
		(at 362.657644 -321.858132)
		(size 0.508)
		(drill 0.254)
		(layers "F.Cu" "B.Cu")
		(net "PVCCIN_CPU0")
	)
	(via
		(at 360.160316 -259.616956)
		(size 0.4572)
		(drill 0.2032)
		(layers "F.Cu" "B.Cu")
		(net "PVCCIN_CPU0")
	)
	(via
		(at 329.988926 -329.683618)
		(size 0.508)
		(drill 0.254)
		(layers "F.Cu" "B.Cu")
		(net "PVCCIN_CPU0")
	)
	(via
		(at 354.051362 -288.103056)
		(size 0.4572)
		(drill 0.2032)
		(layers "F.Cu" "B.Cu")
		(net "PVCCIN_CPU0")
	)
	(via
		(at 360.160316 -267.755878)
		(size 0.4572)
		(drill 0.2032)
		(layers "F.Cu" "B.Cu")
		(net "PVCCIN_CPU0")
	)
	(via
		(at 357.70058 -240.667286)
		(size 0.4572)
		(drill 0.2032)
		(layers "F.Cu" "B.Cu")
		(net "PVCCIN_CPU0")
	)
	(via
		(at 342.230964 -321.865752)
		(size 0.508)
		(drill 0.254)
		(layers "F.Cu" "B.Cu")
		(net "PVCCIN_CPU0")
	)
	(via
		(at 359.690162 -263.686544)
		(size 0.4572)
		(drill 0.2032)
		(layers "F.Cu" "B.Cu")
		(net "PVCCIN_CPU0")
	)
	(via
		(at 360.629962 -284.847538)
		(size 0.4572)
		(drill 0.2032)
		(layers "F.Cu" "B.Cu")
		(net "PVCCIN_CPU0")
	)
	(via
		(at 353.396804 -242.981226)
		(size 0.4572)
		(drill 0.2032)
		(layers "F.Cu" "B.Cu")
		(net "PVCCIN_CPU0")
	)
	(via
		(at 330.629514 -330.312776)
		(size 0.508)
		(drill 0.254)
		(layers "F.Cu" "B.Cu")
		(net "PVCCIN_CPU0")
	)
	(via
		(at 330.664566 -327.702418)
		(size 0.508)
		(drill 0.254)
		(layers "F.Cu" "B.Cu")
		(net "PVCCIN_CPU0")
	)
	(via
		(at 335.38287 -324.47357)
		(size 0.508)
		(drill 0.254)
		(layers "F.Cu" "B.Cu")
		(net "PVCCIN_CPU0")
	)
	(via
		(at 331.284326 -326.026018)
		(size 0.508)
		(drill 0.254)
		(layers "F.Cu" "B.Cu")
		(net "PVCCIN_CPU0")
	)
	(via
		(at 342.893904 -319.888362)
		(size 0.508)
		(drill 0.254)
		(layers "F.Cu" "B.Cu")
		(net "PVCCIN_CPU0")
	)
	(via
		(at 363.104176 -250.672092)
		(size 0.4572)
		(drill 0.2032)
		(layers "F.Cu" "B.Cu")
		(net "PVCCIN_CPU0")
	)
	(via
		(at 363.295184 -321.850512)
		(size 0.508)
		(drill 0.254)
		(layers "F.Cu" "B.Cu")
		(net "PVCCIN_CPU0")
	)
	(via
		(at 362.039916 -261.244842)
		(size 0.4572)
		(drill 0.2032)
		(layers "F.Cu" "B.Cu")
		(net "PVCCIN_CPU0")
	)
	(via
		(at 366.098328 -337.259422)
		(size 0.508)
		(drill 0.254)
		(layers "F.Cu" "B.Cu")
		(net "PVCCIN_CPU0")
	)
	(via
		(at 372.124986 -319.213738)
		(size 0.508)
		(drill 0.254)
		(layers "F.Cu" "B.Cu")
		(net "PVCCIN_CPU0")
	)
	(via
		(at 358.609646 -320.511678)
		(size 0.508)
		(drill 0.254)
		(layers "F.Cu" "B.Cu")
		(net "PVCCIN_CPU0")
	)
	(via
		(at 343.528396 -319.243964)
		(size 0.508)
		(drill 0.254)
		(layers "F.Cu" "B.Cu")
		(net "PVCCIN_CPU0")
	)
	(via
		(at 342.893904 -320.523362)
		(size 0.508)
		(drill 0.254)
		(layers "F.Cu" "B.Cu")
		(net "PVCCIN_CPU0")
	)
	(via
		(at 368.210846 -295.038526)
		(size 0.508)
		(drill 0.254)
		(layers "F.Cu" "B.Cu")
		(net "PVCCIN_CPU0")
	)
	(via
		(at 342.229186 -320.511678)
		(size 0.508)
		(drill 0.254)
		(layers "F.Cu" "B.Cu")
		(net "PVCCIN_CPU0")
	)
	(via
		(at 364.37443 -246.659146)
		(size 0.4572)
		(drill 0.2032)
		(layers "F.Cu" "B.Cu")
		(net "PVCCIN_CPU0")
	)
	(via
		(at 374.974866 -322.487798)
		(size 0.508)
		(drill 0.254)
		(layers "F.Cu" "B.Cu")
		(net "PVCCIN_CPU0")
	)
	(via
		(at 365.14151 -254.020066)
		(size 0.4572)
		(drill 0.2032)
		(layers "F.Cu" "B.Cu")
		(net "PVCCIN_CPU0")
	)
	(via
		(at 368.248946 -292.955726)
		(size 0.508)
		(drill 0.254)
		(layers "F.Cu" "B.Cu")
		(net "PVCCIN_CPU0")
	)
	(via
		(at 357.230934 -246.364506)
		(size 0.4572)
		(drill 0.2032)
		(layers "F.Cu" "B.Cu")
		(net "PVCCIN_CPU0")
	)
	(via
		(at 356.620064 -253.95428)
		(size 0.4572)
		(drill 0.2032)
		(layers "F.Cu" "B.Cu")
		(net "PVCCIN_CPU0")
	)
	(via
		(at 355.301804 -242.981226)
		(size 0.4572)
		(drill 0.2032)
		(layers "F.Cu" "B.Cu")
		(net "PVCCIN_CPU0")
	)
	(via
		(at 342.890856 -319.251584)
		(size 0.508)
		(drill 0.254)
		(layers "F.Cu" "B.Cu")
		(net "PVCCIN_CPU0")
	)
	(via
		(at 329.990704 -331.037692)
		(size 0.508)
		(drill 0.254)
		(layers "F.Cu" "B.Cu")
		(net "PVCCIN_CPU0")
	)
	(via
		(at 358.750616 -275.08073)
		(size 0.4572)
		(drill 0.2032)
		(layers "F.Cu" "B.Cu")
		(net "PVCCIN_CPU0")
	)
	(via
		(at 362.979716 -287.28924)
		(size 0.4572)
		(drill 0.2032)
		(layers "F.Cu" "B.Cu")
		(net "PVCCIN_CPU0")
	)
	(via
		(at 361.099862 -274.266914)
		(size 0.4572)
		(drill 0.2032)
		(layers "F.Cu" "B.Cu")
		(net "PVCCIN_CPU0")
	)
	(via
		(at 357.70058 -247.178322)
		(size 0.4572)
		(drill 0.2032)
		(layers "F.Cu" "B.Cu")
		(net "PVCCIN_CPU0")
	)
	(via
		(at 364.859316 -285.661354)
		(size 0.4572)
		(drill 0.2032)
		(layers "F.Cu" "B.Cu")
		(net "PVCCIN_CPU0")
	)
	(via
		(at 357.810562 -284.847538)
		(size 0.4572)
		(drill 0.2032)
		(layers "F.Cu" "B.Cu")
		(net "PVCCIN_CPU0")
	)
	(via
		(at 360.050334 -246.364506)
		(size 0.4572)
		(drill 0.2032)
		(layers "F.Cu" "B.Cu")
		(net "PVCCIN_CPU0")
	)
	(via
		(at 362.509562 -258.80314)
		(size 0.4572)
		(drill 0.2032)
		(layers "F.Cu" "B.Cu")
		(net "PVCCIN_CPU0")
	)
	(via
		(at 355.301804 -254.014986)
		(size 0.4572)
		(drill 0.2032)
		(layers "F.Cu" "B.Cu")
		(net "PVCCIN_CPU0")
	)
	(via
		(at 356.870762 -288.103056)
		(size 0.4572)
		(drill 0.2032)
		(layers "F.Cu" "B.Cu")
		(net "PVCCIN_CPU0")
	)
	(via
		(at 372.107206 -320.529458)
		(size 0.508)
		(drill 0.254)
		(layers "F.Cu" "B.Cu")
		(net "PVCCIN_CPU0")
	)
	(via
		(at 349.234252 -297.197526)
		(size 0.508)
		(drill 0.254)
		(layers "F.Cu" "B.Cu")
		(net "PVCCIN_CPU0")
	)
	(via
		(at 334.742282 -322.574412)
		(size 0.508)
		(drill 0.254)
		(layers "F.Cu" "B.Cu")
		(net "PVCCIN_CPU0")
	)
	(via
		(at 361.099862 -266.128246)
		(size 0.4572)
		(drill 0.2032)
		(layers "F.Cu" "B.Cu")
		(net "PVCCIN_CPU0")
	)
	(via
		(at 363.150404 -239.912398)
		(size 0.4572)
		(drill 0.2032)
		(layers "F.Cu" "B.Cu")
		(net "PVCCIN_CPU0")
	)
	(via
		(at 359.220516 -285.661354)
		(size 0.4572)
		(drill 0.2032)
		(layers "F.Cu" "B.Cu")
		(net "PVCCIN_CPU0")
	)
	(via
		(at 346.267532 -319.875154)
		(size 0.508)
		(drill 0.254)
		(layers "F.Cu" "B.Cu")
		(net "PVCCIN_CPU0")
	)
	(via
		(at 360.629962 -257.175254)
		(size 0.4572)
		(drill 0.2032)
		(layers "F.Cu" "B.Cu")
		(net "PVCCIN_CPU0")
	)
	(via
		(at 363.449362 -279.964134)
		(size 0.4572)
		(drill 0.2032)
		(layers "F.Cu" "B.Cu")
		(net "PVCCIN_CPU0")
	)
	(via
		(at 359.220516 -277.522432)
		(size 0.4572)
		(drill 0.2032)
		(layers "F.Cu" "B.Cu")
		(net "PVCCIN_CPU0")
	)
	(via
		(at 331.291946 -325.365618)
		(size 0.508)
		(drill 0.254)
		(layers "F.Cu" "B.Cu")
		(net "PVCCIN_CPU0")
	)
	(via
		(at 350.428306 -319.213738)
		(size 0.508)
		(drill 0.254)
		(layers "F.Cu" "B.Cu")
		(net "PVCCIN_CPU0")
	)
	(via
		(at 384.502406 -327.669398)
		(size 0.508)
		(drill 0.254)
		(layers "F.Cu" "B.Cu")
		(net "PVCCIN_CPU0")
	)
	(via
		(at 374.997726 -319.846198)
		(size 0.508)
		(drill 0.254)
		(layers "F.Cu" "B.Cu")
		(net "PVCCIN_CPU0")
	)
	(via
		(at 358.640634 -239.0394)
		(size 0.4572)
		(drill 0.2032)
		(layers "F.Cu" "B.Cu")
		(net "PVCCIN_CPU0")
	)
	(via
		(at 352.685604 -254.020066)
		(size 0.4572)
		(drill 0.2032)
		(layers "F.Cu" "B.Cu")
		(net "PVCCIN_CPU0")
	)
	(via
		(at 362.039916 -282.405836)
		(size 0.4572)
		(drill 0.2032)
		(layers "F.Cu" "B.Cu")
		(net "PVCCIN_CPU0")
	)
	(via
		(at 365.328962 -283.219906)
		(size 0.4572)
		(drill 0.2032)
		(layers "F.Cu" "B.Cu")
		(net "PVCCIN_CPU0")
	)
	(via
		(at 361.099862 -271.011396)
		(size 0.4572)
		(drill 0.2032)
		(layers "F.Cu" "B.Cu")
		(net "PVCCIN_CPU0")
	)
	(via
		(at 346.90812 -321.139312)
		(size 0.508)
		(drill 0.254)
		(layers "F.Cu" "B.Cu")
		(net "PVCCIN_CPU0")
	)
	(via
		(at 359.690162 -255.547622)
		(size 0.4572)
		(drill 0.2032)
		(layers "F.Cu" "B.Cu")
		(net "PVCCIN_CPU0")
	)
	(via
		(at 342.893904 -321.158362)
		(size 0.508)
		(drill 0.254)
		(layers "F.Cu" "B.Cu")
		(net "PVCCIN_CPU0")
	)
	(via
		(at 363.104176 -254.177292)
		(size 0.4572)
		(drill 0.2032)
		(layers "F.Cu" "B.Cu")
		(net "PVCCIN_CPU0")
	)
	(via
		(at 383.224786 -326.991218)
		(size 0.508)
		(drill 0.254)
		(layers "F.Cu" "B.Cu")
		(net "PVCCIN_CPU0")
	)
	(via
		(at 362.361226 -292.955726)
		(size 0.508)
		(drill 0.254)
		(layers "F.Cu" "B.Cu")
		(net "PVCCIN_CPU0")
	)
	(via
		(at 383.212594 -328.339196)
		(size 0.508)
		(drill 0.254)
		(layers "F.Cu" "B.Cu")
		(net "PVCCIN_CPU0")
	)
	(via
		(at 358.750616 -273.453098)
		(size 0.4572)
		(drill 0.2032)
		(layers "F.Cu" "B.Cu")
		(net "PVCCIN_CPU0")
	)
	(via
		(at 361.569762 -276.708616)
		(size 0.4572)
		(drill 0.2032)
		(layers "F.Cu" "B.Cu")
		(net "PVCCIN_CPU0")
	)
	(via
		(at 360.629962 -281.59202)
		(size 0.4572)
		(drill 0.2032)
		(layers "F.Cu" "B.Cu")
		(net "PVCCIN_CPU0")
	)
	(via
		(at 366.268762 -288.103056)
		(size 0.4572)
		(drill 0.2032)
		(layers "F.Cu" "B.Cu")
		(net "PVCCIN_CPU0")
	)
	(via
		(at 338.756498 -322.555362)
		(size 0.508)
		(drill 0.254)
		(layers "F.Cu" "B.Cu")
		(net "PVCCIN_CPU0")
	)
	(via
		(at 361.099862 -264.50036)
		(size 0.4572)
		(drill 0.2032)
		(layers "F.Cu" "B.Cu")
		(net "PVCCIN_CPU0")
	)
	(via
		(at 360.050334 -243.108988)
		(size 0.4572)
		(drill 0.2032)
		(layers "F.Cu" "B.Cu")
		(net "PVCCIN_CPU0")
	)
	(via
		(at 360.160316 -266.128246)
		(size 0.4572)
		(drill 0.2032)
		(layers "F.Cu" "B.Cu")
		(net "PVCCIN_CPU0")
	)
	(via
		(at 379.636274 -323.632576)
		(size 0.508)
		(drill 0.254)
		(layers "F.Cu" "B.Cu")
		(net "PVCCIN_CPU0")
	)
	(via
		(at 363.449362 -286.475424)
		(size 0.4572)
		(drill 0.2032)
		(layers "F.Cu" "B.Cu")
		(net "PVCCIN_CPU0")
	)
	(via
		(at 365.328962 -289.807142)
		(size 0.4572)
		(drill 0.2032)
		(layers "F.Cu" "B.Cu")
		(net "PVCCIN_CPU0")
	)
	(via
		(at 357.810562 -265.314176)
		(size 0.4572)
		(drill 0.2032)
		(layers "F.Cu" "B.Cu")
		(net "PVCCIN_CPU0")
	)
	(via
		(at 360.629962 -288.103056)
		(size 0.4572)
		(drill 0.2032)
		(layers "F.Cu" "B.Cu")
		(net "PVCCIN_CPU0")
	)
	(via
		(at 366.785906 -320.547238)
		(size 0.508)
		(drill 0.254)
		(layers "F.Cu" "B.Cu")
		(net "PVCCIN_CPU0")
	)
	(via
		(at 359.220516 -280.778204)
		(size 0.4572)
		(drill 0.2032)
		(layers "F.Cu" "B.Cu")
		(net "PVCCIN_CPU0")
	)
	(via
		(at 365.799116 -285.661354)
		(size 0.4572)
		(drill 0.2032)
		(layers "F.Cu" "B.Cu")
		(net "PVCCIN_CPU0")
	)
	(via
		(at 359.690162 -283.219906)
		(size 0.4572)
		(drill 0.2032)
		(layers "F.Cu" "B.Cu")
		(net "PVCCIN_CPU0")
	)
	(via
		(at 357.340662 -261.244842)
		(size 0.4572)
		(drill 0.2032)
		(layers "F.Cu" "B.Cu")
		(net "PVCCIN_CPU0")
	)
	(via
		(at 356.620064 -239.249966)
		(size 0.4572)
		(drill 0.2032)
		(layers "F.Cu" "B.Cu")
		(net "PVCCIN_CPU0")
	)
	(via
		(at 355.931216 -283.219906)
		(size 0.4572)
		(drill 0.2032)
		(layers "F.Cu" "B.Cu")
		(net "PVCCIN_CPU0")
	)
	(via
		(at 363.104176 -253.593092)
		(size 0.4572)
		(drill 0.2032)
		(layers "F.Cu" "B.Cu")
		(net "PVCCIN_CPU0")
	)
	(via
		(at 359.580434 -239.0394)
		(size 0.4572)
		(drill 0.2032)
		(layers "F.Cu" "B.Cu")
		(net "PVCCIN_CPU0")
	)
	(via
		(at 362.509562 -263.686544)
		(size 0.4572)
		(drill 0.2032)
		(layers "F.Cu" "B.Cu")
		(net "PVCCIN_CPU0")
	)
	(via
		(at 353.111562 -289.807142)
		(size 0.4572)
		(drill 0.2032)
		(layers "F.Cu" "B.Cu")
		(net "PVCCIN_CPU0")
	)
	(via
		(at 363.104176 -243.077492)
		(size 0.4572)
		(drill 0.2032)
		(layers "F.Cu" "B.Cu")
		(net "PVCCIN_CPU0")
	)
	(via
		(at 357.810562 -260.430772)
		(size 0.4572)
		(drill 0.2032)
		(layers "F.Cu" "B.Cu")
		(net "PVCCIN_CPU0")
	)
	(via
		(at 357.810562 -258.80314)
		(size 0.4572)
		(drill 0.2032)
		(layers "F.Cu" "B.Cu")
		(net "PVCCIN_CPU0")
	)
	(via
		(at 356.620064 -257.670554)
		(size 0.4572)
		(drill 0.2032)
		(layers "F.Cu" "B.Cu")
		(net "PVCCIN_CPU0")
	)
	(via
		(at 357.340662 -282.405836)
		(size 0.4572)
		(drill 0.2032)
		(layers "F.Cu" "B.Cu")
		(net "PVCCIN_CPU0")
	)
	(via
		(at 354.051362 -286.475424)
		(size 0.4572)
		(drill 0.2032)
		(layers "F.Cu" "B.Cu")
		(net "PVCCIN_CPU0")
	)
	(via
		(at 361.099862 -279.150318)
		(size 0.4572)
		(drill 0.2032)
		(layers "F.Cu" "B.Cu")
		(net "PVCCIN_CPU0")
	)
	(via
		(at 365.14151 -246.669306)
		(size 0.4572)
		(drill 0.2032)
		(layers "F.Cu" "B.Cu")
		(net "PVCCIN_CPU0")
	)
	(via
		(at 363.104176 -257.682492)
		(size 0.4572)
		(drill 0.2032)
		(layers "F.Cu" "B.Cu")
		(net "PVCCIN_CPU0")
	)
	(via
		(at 351.701608 -319.243964)
		(size 0.508)
		(drill 0.254)
		(layers "F.Cu" "B.Cu")
		(net "PVCCIN_CPU0")
	)
	(via
		(at 329.330304 -331.037692)
		(size 0.508)
		(drill 0.254)
		(layers "F.Cu" "B.Cu")
		(net "PVCCIN_CPU0")
	)
	(via
		(at 360.629962 -265.314176)
		(size 0.4572)
		(drill 0.2032)
		(layers "F.Cu" "B.Cu")
		(net "PVCCIN_CPU0")
	)
	(via
		(at 360.629962 -276.708616)
		(size 0.4572)
		(drill 0.2032)
		(layers "F.Cu" "B.Cu")
		(net "PVCCIN_CPU0")
	)
	(via
		(at 355.303074 -295.038526)
		(size 0.508)
		(drill 0.254)
		(layers "F.Cu" "B.Cu")
		(net "PVCCIN_CPU0")
	)
	(via
		(at 355.385624 -257.675126)
		(size 0.4572)
		(drill 0.2032)
		(layers "F.Cu" "B.Cu")
		(net "PVCCIN_CPU0")
	)
	(via
		(at 359.220516 -264.50036)
		(size 0.4572)
		(drill 0.2032)
		(layers "F.Cu" "B.Cu")
		(net "PVCCIN_CPU0")
	)
	(via
		(at 357.340662 -280.778204)
		(size 0.4572)
		(drill 0.2032)
		(layers "F.Cu" "B.Cu")
		(net "PVCCIN_CPU0")
	)
	(via
		(at 354.656644 -250.329446)
		(size 0.4572)
		(drill 0.2032)
		(layers "F.Cu" "B.Cu")
		(net "PVCCIN_CPU0")
	)
	(via
		(at 376.265186 -324.364096)
		(size 0.508)
		(drill 0.254)
		(layers "F.Cu" "B.Cu")
		(net "PVCCIN_CPU0")
	)
	(via
		(at 363.104176 -246.582692)
		(size 0.4572)
		(drill 0.2032)
		(layers "F.Cu" "B.Cu")
		(net "PVCCIN_CPU0")
	)
	(via
		(at 359.690162 -257.175254)
		(size 0.4572)
		(drill 0.2032)
		(layers "F.Cu" "B.Cu")
		(net "PVCCIN_CPU0")
	)
	(via
		(at 359.220516 -274.266914)
		(size 0.4572)
		(drill 0.2032)
		(layers "F.Cu" "B.Cu")
		(net "PVCCIN_CPU0")
	)
	(via
		(at 360.98988 -246.364506)
		(size 0.4572)
		(drill 0.2032)
		(layers "F.Cu" "B.Cu")
		(net "PVCCIN_CPU0")
	)
	(via
		(at 331.267054 -329.342496)
		(size 0.508)
		(drill 0.254)
		(layers "F.Cu" "B.Cu")
		(net "PVCCIN_CPU0")
	)
	(via
		(at 367.456212 -321.158362)
		(size 0.508)
		(drill 0.254)
		(layers "F.Cu" "B.Cu")
		(net "PVCCIN_CPU0")
	)
	(via
		(at 374.990106 -321.174618)
		(size 0.508)
		(drill 0.254)
		(layers "F.Cu" "B.Cu")
		(net "PVCCIN_CPU0")
	)
	(via
		(at 358.611424 -321.865752)
		(size 0.508)
		(drill 0.254)
		(layers "F.Cu" "B.Cu")
		(net "PVCCIN_CPU0")
	)
	(via
		(at 354.443792 -321.146932)
		(size 0.508)
		(drill 0.254)
		(layers "F.Cu" "B.Cu")
		(net "PVCCIN_CPU0")
	)
	(via
		(at 360.98988 -247.992138)
		(size 0.4572)
		(drill 0.2032)
		(layers "F.Cu" "B.Cu")
		(net "PVCCIN_CPU0")
	)
	(via
		(at 334.083406 -322.508118)
		(size 0.508)
		(drill 0.254)
		(layers "F.Cu" "B.Cu")
		(net "PVCCIN_CPU0")
	)
	(via
		(at 331.265784 -330.008992)
		(size 0.508)
		(drill 0.254)
		(layers "F.Cu" "B.Cu")
		(net "PVCCIN_CPU0")
	)
	(via
		(at 346.27058 -321.146932)
		(size 0.508)
		(drill 0.254)
		(layers "F.Cu" "B.Cu")
		(net "PVCCIN_CPU0")
	)
	(via
		(at 364.37443 -242.981226)
		(size 0.4572)
		(drill 0.2032)
		(layers "F.Cu" "B.Cu")
		(net "PVCCIN_CPU0")
	)
	(via
		(at 364.859316 -282.405836)
		(size 0.4572)
		(drill 0.2032)
		(layers "F.Cu" "B.Cu")
		(net "PVCCIN_CPU0")
	)
	(via
		(at 347.554804 -321.873372)
		(size 0.508)
		(drill 0.254)
		(layers "F.Cu" "B.Cu")
		(net "PVCCIN_CPU0")
	)
	(via
		(at 360.160316 -274.266914)
		(size 0.4572)
		(drill 0.2032)
		(layers "F.Cu" "B.Cu")
		(net "PVCCIN_CPU0")
	)
	(via
		(at 359.110534 -247.992138)
		(size 0.4572)
		(drill 0.2032)
		(layers "F.Cu" "B.Cu")
		(net "PVCCIN_CPU0")
	)
	(via
		(at 339.475826 -321.215258)
		(size 0.508)
		(drill 0.254)
		(layers "F.Cu" "B.Cu")
		(net "PVCCIN_CPU0")
	)
	(via
		(at 360.51998 -240.667286)
		(size 0.4572)
		(drill 0.2032)
		(layers "F.Cu" "B.Cu")
		(net "PVCCIN_CPU0")
	)
	(via
		(at 357.700834 -239.0394)
		(size 0.4572)
		(drill 0.2032)
		(layers "F.Cu" "B.Cu")
		(net "PVCCIN_CPU0")
	)
	(via
		(at 359.690162 -271.825212)
		(size 0.4572)
		(drill 0.2032)
		(layers "F.Cu" "B.Cu")
		(net "PVCCIN_CPU0")
	)
	(via
		(at 368.072924 -321.908932)
		(size 0.508)
		(drill 0.254)
		(layers "F.Cu" "B.Cu")
		(net "PVCCIN_CPU0")
	)
	(via
		(at 371.46738 -319.232534)
		(size 0.508)
		(drill 0.254)
		(layers "F.Cu" "B.Cu")
		(net "PVCCIN_CPU0")
	)
	(via
		(at 331.253846 -327.994518)
		(size 0.508)
		(drill 0.254)
		(layers "F.Cu" "B.Cu")
		(net "PVCCIN_CPU0")
	)
	(via
		(at 359.917746 -319.243964)
		(size 0.508)
		(drill 0.254)
		(layers "F.Cu" "B.Cu")
		(net "PVCCIN_CPU0")
	)
	(via
		(at 363.919516 -288.917126)
		(size 0.4572)
		(drill 0.2032)
		(layers "F.Cu" "B.Cu")
		(net "PVCCIN_CPU0")
	)
	(via
		(at 360.160316 -279.150318)
		(size 0.4572)
		(drill 0.2032)
		(layers "F.Cu" "B.Cu")
		(net "PVCCIN_CPU0")
	)
	(via
		(at 362.509562 -257.175254)
		(size 0.4572)
		(drill 0.2032)
		(layers "F.Cu" "B.Cu")
		(net "PVCCIN_CPU0")
	)
	(via
		(at 359.690162 -284.847538)
		(size 0.4572)
		(drill 0.2032)
		(layers "F.Cu" "B.Cu")
		(net "PVCCIN_CPU0")
	)
	(via
		(at 355.454204 -262.784082)
		(size 0.4572)
		(drill 0.2032)
		(layers "F.Cu" "B.Cu")
		(net "PVCCIN_CPU0")
	)
	(via
		(at 359.220516 -279.150318)
		(size 0.4572)
		(drill 0.2032)
		(layers "F.Cu" "B.Cu")
		(net "PVCCIN_CPU0")
	)
	(via
		(at 364.37443 -254.020066)
		(size 0.4572)
		(drill 0.2032)
		(layers "F.Cu" "B.Cu")
		(net "PVCCIN_CPU0")
	)
	(via
		(at 366.738916 -288.917126)
		(size 0.4572)
		(drill 0.2032)
		(layers "F.Cu" "B.Cu")
		(net "PVCCIN_CPU0")
	)
	(via
		(at 353.703636 -239.292638)
		(size 0.4572)
		(drill 0.2032)
		(layers "F.Cu" "B.Cu")
		(net "PVCCIN_CPU0")
	)
	(via
		(at 378.991114 -323.632576)
		(size 0.508)
		(drill 0.254)
		(layers "F.Cu" "B.Cu")
		(net "PVCCIN_CPU0")
	)
	(via
		(at 347.563694 -321.206876)
		(size 0.508)
		(drill 0.254)
		(layers "F.Cu" "B.Cu")
		(net "PVCCIN_CPU0")
	)
	(via
		(at 355.930962 -289.807142)
		(size 0.4572)
		(drill 0.2032)
		(layers "F.Cu" "B.Cu")
		(net "PVCCIN_CPU0")
	)
	(via
		(at 367.04143 -250.337066)
		(size 0.4572)
		(drill 0.2032)
		(layers "F.Cu" "B.Cu")
		(net "PVCCIN_CPU0")
	)
	(via
		(at 362.979716 -288.993326)
		(size 0.4572)
		(drill 0.2032)
		(layers "F.Cu" "B.Cu")
		(net "PVCCIN_CPU0")
	)
	(via
		(at 384.502914 -329.078336)
		(size 0.508)
		(drill 0.254)
		(layers "F.Cu" "B.Cu")
		(net "PVCCIN_CPU0")
	)
	(via
		(at 355.931216 -288.103056)
		(size 0.4572)
		(drill 0.2032)
		(layers "F.Cu" "B.Cu")
		(net "PVCCIN_CPU0")
	)
	(via
		(at 371.448584 -321.865752)
		(size 0.508)
		(drill 0.254)
		(layers "F.Cu" "B.Cu")
		(net "PVCCIN_CPU0")
	)
	(via
		(at 365.328962 -284.847538)
		(size 0.4572)
		(drill 0.2032)
		(layers "F.Cu" "B.Cu")
		(net "PVCCIN_CPU0")
	)
	(via
		(at 354.521516 -285.661354)
		(size 0.4572)
		(drill 0.2032)
		(layers "F.Cu" "B.Cu")
		(net "PVCCIN_CPU0")
	)
	(via
		(at 354.991162 -284.847538)
		(size 0.4572)
		(drill 0.2032)
		(layers "F.Cu" "B.Cu")
		(net "PVCCIN_CPU0")
	)
	(via
		(at 385.153154 -329.078336)
		(size 0.508)
		(drill 0.254)
		(layers "F.Cu" "B.Cu")
		(net "PVCCIN_CPU0")
	)
	(via
		(at 351.704656 -321.150742)
		(size 0.508)
		(drill 0.254)
		(layers "F.Cu" "B.Cu")
		(net "PVCCIN_CPU0")
	)
	(via
		(at 362.509562 -255.547622)
		(size 0.4572)
		(drill 0.2032)
		(layers "F.Cu" "B.Cu")
		(net "PVCCIN_CPU0")
	)
	(via
		(at 360.98988 -244.73662)
		(size 0.4572)
		(drill 0.2032)
		(layers "F.Cu" "B.Cu")
		(net "PVCCIN_CPU0")
	)
	(via
		(at 346.267532 -320.510154)
		(size 0.508)
		(drill 0.254)
		(layers "F.Cu" "B.Cu")
		(net "PVCCIN_CPU0")
	)
	(via
		(at 358.640634 -245.55069)
		(size 0.4572)
		(drill 0.2032)
		(layers "F.Cu" "B.Cu")
		(net "PVCCIN_CPU0")
	)
	(via
		(at 360.160316 -269.38351)
		(size 0.4572)
		(drill 0.2032)
		(layers "F.Cu" "B.Cu")
		(net "PVCCIN_CPU0")
	)
	(via
		(at 368.093752 -320.515742)
		(size 0.508)
		(drill 0.254)
		(layers "F.Cu" "B.Cu")
		(net "PVCCIN_CPU0")
	)
	(via
		(at 356.401116 -285.661354)
		(size 0.4572)
		(drill 0.2032)
		(layers "F.Cu" "B.Cu")
		(net "PVCCIN_CPU0")
	)
	(via
		(at 379.636274 -324.364096)
		(size 0.508)
		(drill 0.254)
		(layers "F.Cu" "B.Cu")
		(net "PVCCIN_CPU0")
	)
	(via
		(at 338.175346 -321.868038)
		(size 0.508)
		(drill 0.254)
		(layers "F.Cu" "B.Cu")
		(net "PVCCIN_CPU0")
	)
	(via
		(at 338.756498 -323.825362)
		(size 0.508)
		(drill 0.254)
		(layers "F.Cu" "B.Cu")
		(net "PVCCIN_CPU0")
	)
	(via
		(at 371.46738 -320.502534)
		(size 0.508)
		(drill 0.254)
		(layers "F.Cu" "B.Cu")
		(net "PVCCIN_CPU0")
	)
	(via
		(at 367.575846 -295.038526)
		(size 0.508)
		(drill 0.254)
		(layers "F.Cu" "B.Cu")
		(net "PVCCIN_CPU0")
	)
	(via
		(at 372.109746 -319.866518)
		(size 0.508)
		(drill 0.254)
		(layers "F.Cu" "B.Cu")
		(net "PVCCIN_CPU0")
	)
	(via
		(at 384.502914 -329.809856)
		(size 0.508)
		(drill 0.254)
		(layers "F.Cu" "B.Cu")
		(net "PVCCIN_CPU0")
	)
	(via
		(at 355.078284 -319.232534)
		(size 0.508)
		(drill 0.254)
		(layers "F.Cu" "B.Cu")
		(net "PVCCIN_CPU0")
	)
	(via
		(at 362.399834 -240.667286)
		(size 0.4572)
		(drill 0.2032)
		(layers "F.Cu" "B.Cu")
		(net "PVCCIN_CPU0")
	)
	(via
		(at 359.58018 -248.806208)
		(size 0.4572)
		(drill 0.2032)
		(layers "F.Cu" "B.Cu")
		(net "PVCCIN_CPU0")
	)
	(via
		(at 357.230934 -243.108988)
		(size 0.4572)
		(drill 0.2032)
		(layers "F.Cu" "B.Cu")
		(net "PVCCIN_CPU0")
	)
	(via
		(at 361.099862 -267.755878)
		(size 0.4572)
		(drill 0.2032)
		(layers "F.Cu" "B.Cu")
		(net "PVCCIN_CPU0")
	)
	(via
		(at 366.268762 -286.475424)
		(size 0.4572)
		(drill 0.2032)
		(layers "F.Cu" "B.Cu")
		(net "PVCCIN_CPU0")
	)
	(via
		(at 347.565726 -320.521838)
		(size 0.508)
		(drill 0.254)
		(layers "F.Cu" "B.Cu")
		(net "PVCCIN_CPU0")
	)
	(via
		(at 372.105174 -321.214496)
		(size 0.508)
		(drill 0.254)
		(layers "F.Cu" "B.Cu")
		(net "PVCCIN_CPU0")
	)
	(via
		(at 359.220516 -257.98907)
		(size 0.4572)
		(drill 0.2032)
		(layers "F.Cu" "B.Cu")
		(net "PVCCIN_CPU0")
	)
	(via
		(at 335.38287 -323.20357)
		(size 0.508)
		(drill 0.254)
		(layers "F.Cu" "B.Cu")
		(net "PVCCIN_CPU0")
	)
	(via
		(at 362.509562 -283.219906)
		(size 0.4572)
		(drill 0.2032)
		(layers "F.Cu" "B.Cu")
		(net "PVCCIN_CPU0")
	)
	(via
		(at 355.752146 -319.206118)
		(size 0.508)
		(drill 0.254)
		(layers "F.Cu" "B.Cu")
		(net "PVCCIN_CPU0")
	)
	(via
		(at 334.74533 -324.48119)
		(size 0.508)
		(drill 0.254)
		(layers "F.Cu" "B.Cu")
		(net "PVCCIN_CPU0")
	)
	(via
		(at 334.054704 -325.175372)
		(size 0.508)
		(drill 0.254)
		(layers "F.Cu" "B.Cu")
		(net "PVCCIN_CPU0")
	)
	(via
		(at 360.050334 -244.73662)
		(size 0.4572)
		(drill 0.2032)
		(layers "F.Cu" "B.Cu")
		(net "PVCCIN_CPU0")
	)
	(via
		(at 370.811044 -321.873372)
		(size 0.508)
		(drill 0.254)
		(layers "F.Cu" "B.Cu")
		(net "PVCCIN_CPU0")
	)
	(via
		(at 356.870762 -286.475424)
		(size 0.4572)
		(drill 0.2032)
		(layers "F.Cu" "B.Cu")
		(net "PVCCIN_CPU0")
	)
	(via
		(at 359.920794 -320.515742)
		(size 0.508)
		(drill 0.254)
		(layers "F.Cu" "B.Cu")
		(net "PVCCIN_CPU0")
	)
	(via
		(at 359.283254 -319.888362)
		(size 0.508)
		(drill 0.254)
		(layers "F.Cu" "B.Cu")
		(net "PVCCIN_CPU0")
	)
	(via
		(at 335.379822 -322.566792)
		(size 0.508)
		(drill 0.254)
		(layers "F.Cu" "B.Cu")
		(net "PVCCIN_CPU0")
	)
	(via
		(at 361.099862 -285.661354)
		(size 0.4572)
		(drill 0.2032)
		(layers "F.Cu" "B.Cu")
		(net "PVCCIN_CPU0")
	)
	(via
		(at 358.750362 -288.103056)
		(size 0.4572)
		(drill 0.2032)
		(layers "F.Cu" "B.Cu")
		(net "PVCCIN_CPU0")
	)
	(via
		(at 330.679806 -326.386698)
		(size 0.508)
		(drill 0.254)
		(layers "F.Cu" "B.Cu")
		(net "PVCCIN_CPU0")
	)
	(via
		(at 359.690162 -273.453098)
		(size 0.4572)
		(drill 0.2032)
		(layers "F.Cu" "B.Cu")
		(net "PVCCIN_CPU0")
	)
	(via
		(at 356.620064 -242.918488)
		(size 0.4572)
		(drill 0.2032)
		(layers "F.Cu" "B.Cu")
		(net "PVCCIN_CPU0")
	)
	(via
		(at 346.905072 -319.867534)
		(size 0.508)
		(drill 0.254)
		(layers "F.Cu" "B.Cu")
		(net "PVCCIN_CPU0")
	)
	(via
		(at 354.521516 -288.917126)
		(size 0.4572)
		(drill 0.2032)
		(layers "F.Cu" "B.Cu")
		(net "PVCCIN_CPU0")
	)
	(via
		(at 338.116164 -325.182992)
		(size 0.508)
		(drill 0.254)
		(layers "F.Cu" "B.Cu")
		(net "PVCCIN_CPU0")
	)
	(via
		(at 346.267532 -319.240154)
		(size 0.508)
		(drill 0.254)
		(layers "F.Cu" "B.Cu")
		(net "PVCCIN_CPU0")
	)
	(via
		(at 361.099862 -288.993326)
		(size 0.4572)
		(drill 0.2032)
		(layers "F.Cu" "B.Cu")
		(net "PVCCIN_CPU0")
	)
	(via
		(at 366.788954 -321.234816)
		(size 0.508)
		(drill 0.254)
		(layers "F.Cu" "B.Cu")
		(net "PVCCIN_CPU0")
	)
	(via
		(at 359.220516 -269.38351)
		(size 0.4572)
		(drill 0.2032)
		(layers "F.Cu" "B.Cu")
		(net "PVCCIN_CPU0")
	)
	(via
		(at 362.509562 -281.59202)
		(size 0.4572)
		(drill 0.2032)
		(layers "F.Cu" "B.Cu")
		(net "PVCCIN_CPU0")
	)
	(via
		(at 361.726226 -297.07078)
		(size 0.508)
		(drill 0.254)
		(layers "F.Cu" "B.Cu")
		(net "PVCCIN_CPU0")
	)
	(via
		(at 360.160316 -264.50036)
		(size 0.4572)
		(drill 0.2032)
		(layers "F.Cu" "B.Cu")
		(net "PVCCIN_CPU0")
	)
	(via
		(at 358.750616 -283.219906)
		(size 0.4572)
		(drill 0.2032)
		(layers "F.Cu" "B.Cu")
		(net "PVCCIN_CPU0")
	)
	(via
		(at 352.680524 -250.344686)
		(size 0.4572)
		(drill 0.2032)
		(layers "F.Cu" "B.Cu")
		(net "PVCCIN_CPU0")
	)
	(via
		(at 359.58018 -240.667286)
		(size 0.4572)
		(drill 0.2032)
		(layers "F.Cu" "B.Cu")
		(net "PVCCIN_CPU0")
	)
	(via
		(at 357.810562 -279.964134)
		(size 0.4572)
		(drill 0.2032)
		(layers "F.Cu" "B.Cu")
		(net "PVCCIN_CPU0")
	)
	(via
		(at 362.039916 -280.778204)
		(size 0.4572)
		(drill 0.2032)
		(layers "F.Cu" "B.Cu")
		(net "PVCCIN_CPU0")
	)
	(via
		(at 376.295666 -320.534538)
		(size 0.508)
		(drill 0.254)
		(layers "F.Cu" "B.Cu")
		(net "PVCCIN_CPU0")
	)
	(via
		(at 368.090704 -319.243964)
		(size 0.508)
		(drill 0.254)
		(layers "F.Cu" "B.Cu")
		(net "PVCCIN_CPU0")
	)
	(via
		(at 355.732334 -321.206876)
		(size 0.508)
		(drill 0.254)
		(layers "F.Cu" "B.Cu")
		(net "PVCCIN_CPU0")
	)
	(via
		(at 382.660906 -327.293478)
		(size 0.508)
		(drill 0.254)
		(layers "F.Cu" "B.Cu")
		(net "PVCCIN_CPU0")
	)
	(via
		(at 376.310906 -319.881758)
		(size 0.508)
		(drill 0.254)
		(layers "F.Cu" "B.Cu")
		(net "PVCCIN_CPU0")
	)
	(via
		(at 358.640634 -243.922804)
		(size 0.4572)
		(drill 0.2032)
		(layers "F.Cu" "B.Cu")
		(net "PVCCIN_CPU0")
	)
	(via
		(at 358.750616 -276.708616)
		(size 0.4572)
		(drill 0.2032)
		(layers "F.Cu" "B.Cu")
		(net "PVCCIN_CPU0")
	)
	(via
		(at 375.630186 -323.624956)
		(size 0.508)
		(drill 0.254)
		(layers "F.Cu" "B.Cu")
		(net "PVCCIN_CPU0")
	)
	(via
		(at 362.509562 -284.847538)
		(size 0.4572)
		(drill 0.2032)
		(layers "F.Cu" "B.Cu")
		(net "PVCCIN_CPU0")
	)
	(via
		(at 355.734366 -320.521838)
		(size 0.508)
		(drill 0.254)
		(layers "F.Cu" "B.Cu")
		(net "PVCCIN_CPU0")
	)
	(via
		(at 363.104176 -257.098292)
		(size 0.4572)
		(drill 0.2032)
		(layers "F.Cu" "B.Cu")
		(net "PVCCIN_CPU0")
	)
	(via
		(at 355.931216 -281.59202)
		(size 0.4572)
		(drill 0.2032)
		(layers "F.Cu" "B.Cu")
		(net "PVCCIN_CPU0")
	)
	(via
		(at 360.629962 -266.941808)
		(size 0.4572)
		(drill 0.2032)
		(layers "F.Cu" "B.Cu")
		(net "PVCCIN_CPU0")
	)
	(via
		(at 360.629962 -278.336502)
		(size 0.4572)
		(drill 0.2032)
		(layers "F.Cu" "B.Cu")
		(net "PVCCIN_CPU0")
	)
	(via
		(at 355.723444 -321.873372)
		(size 0.508)
		(drill 0.254)
		(layers "F.Cu" "B.Cu")
		(net "PVCCIN_CPU0")
	)
	(via
		(at 363.294422 -320.502534)
		(size 0.508)
		(drill 0.254)
		(layers "F.Cu" "B.Cu")
		(net "PVCCIN_CPU0")
	)
	(via
		(at 363.449362 -283.219906)
		(size 0.4572)
		(drill 0.2032)
		(layers "F.Cu" "B.Cu")
		(net "PVCCIN_CPU0")
	)
	(via
		(at 362.039916 -284.033722)
		(size 0.4572)
		(drill 0.2032)
		(layers "F.Cu" "B.Cu")
		(net "PVCCIN_CPU0")
	)
	(via
		(at 361.099862 -272.639282)
		(size 0.4572)
		(drill 0.2032)
		(layers "F.Cu" "B.Cu")
		(net "PVCCIN_CPU0")
	)
	(via
		(at 330.626466 -329.040998)
		(size 0.508)
		(drill 0.254)
		(layers "F.Cu" "B.Cu")
		(net "PVCCIN_CPU0")
	)
	(via
		(at 330.034646 -327.054718)
		(size 0.508)
		(drill 0.254)
		(layers "F.Cu" "B.Cu")
		(net "PVCCIN_CPU0")
	)
	(via
		(at 338.190586 -321.207638)
		(size 0.508)
		(drill 0.254)
		(layers "F.Cu" "B.Cu")
		(net "PVCCIN_CPU0")
	)
	(via
		(at 339.460586 -321.875658)
		(size 0.508)
		(drill 0.254)
		(layers "F.Cu" "B.Cu")
		(net "PVCCIN_CPU0")
	)
	(via
		(at 357.340662 -288.993326)
		(size 0.4572)
		(drill 0.2032)
		(layers "F.Cu" "B.Cu")
		(net "PVCCIN_CPU0")
	)
	(via
		(at 371.470428 -321.139312)
		(size 0.508)
		(drill 0.254)
		(layers "F.Cu" "B.Cu")
		(net "PVCCIN_CPU0")
	)
	(via
		(at 343.531444 -319.880742)
		(size 0.508)
		(drill 0.254)
		(layers "F.Cu" "B.Cu")
		(net "PVCCIN_CPU0")
	)
	(via
		(at 361.929934 -239.853216)
		(size 0.4572)
		(drill 0.2032)
		(layers "F.Cu" "B.Cu")
		(net "PVCCIN_CPU0")
	)
	(via
		(at 356.401116 -288.942526)
		(size 0.4572)
		(drill 0.2032)
		(layers "F.Cu" "B.Cu")
		(net "PVCCIN_CPU0")
	)
	(via
		(at 360.160316 -280.778204)
		(size 0.4572)
		(drill 0.2032)
		(layers "F.Cu" "B.Cu")
		(net "PVCCIN_CPU0")
	)
	(via
		(at 359.58018 -247.178322)
		(size 0.4572)
		(drill 0.2032)
		(layers "F.Cu" "B.Cu")
		(net "PVCCIN_CPU0")
	)
	(via
		(at 380.278894 -325.367396)
		(size 0.508)
		(drill 0.254)
		(layers "F.Cu" "B.Cu")
		(net "PVCCIN_CPU0")
	)
	(via
		(at 382.245362 -289.807142)
		(size 0.4572)
		(drill 0.2032)
		(layers "F.Cu" "B.Cu")
		(net "PVCCIN_CPU0")
	)
	(via
		(at 360.050334 -241.481102)
		(size 0.4572)
		(drill 0.2032)
		(layers "F.Cu" "B.Cu")
		(net "PVCCIN_CPU0")
	)
	(via
		(at 341.511128 -337.352894)
		(size 0.508)
		(drill 0.254)
		(layers "F.Cu" "B.Cu")
		(net "PVCCIN_CPU0")
	)
	(via
		(at 358.280716 -266.128246)
		(size 0.4572)
		(drill 0.2032)
		(layers "F.Cu" "B.Cu")
		(net "PVCCIN_CPU0")
	)
	(via
		(at 374.982486 -320.498978)
		(size 0.508)
		(drill 0.254)
		(layers "F.Cu" "B.Cu")
		(net "PVCCIN_CPU0")
	)
	(via
		(at 383.240026 -326.338438)
		(size 0.508)
		(drill 0.254)
		(layers "F.Cu" "B.Cu")
		(net "PVCCIN_CPU0")
	)
	(via
		(at 356.620064 -257.086354)
		(size 0.4572)
		(drill 0.2032)
		(layers "F.Cu" "B.Cu")
		(net "PVCCIN_CPU0")
	)
	(via
		(at 338.122006 -324.46976)
		(size 0.508)
		(drill 0.254)
		(layers "F.Cu" "B.Cu")
		(net "PVCCIN_CPU0")
	)
	(via
		(at 363.942884 -321.865752)
		(size 0.508)
		(drill 0.254)
		(layers "F.Cu" "B.Cu")
		(net "PVCCIN_CPU0")
	)
	(via
		(at 354.521516 -287.28924)
		(size 0.4572)
		(drill 0.2032)
		(layers "F.Cu" "B.Cu")
		(net "PVCCIN_CPU0")
	)
	(via
		(at 368.210846 -297.197526)
		(size 0.508)
		(drill 0.254)
		(layers "F.Cu" "B.Cu")
		(net "PVCCIN_CPU0")
	)
	(via
		(at 379.635766 -322.955158)
		(size 0.508)
		(drill 0.254)
		(layers "F.Cu" "B.Cu")
		(net "PVCCIN_CPU0")
	)
	(via
		(at 382.699006 -325.977758)
		(size 0.508)
		(drill 0.254)
		(layers "F.Cu" "B.Cu")
		(net "PVCCIN_CPU0")
	)
	(via
		(at 338.812886 -321.860418)
		(size 0.508)
		(drill 0.254)
		(layers "F.Cu" "B.Cu")
		(net "PVCCIN_CPU0")
	)
	(via
		(at 351.704656 -319.880742)
		(size 0.508)
		(drill 0.254)
		(layers "F.Cu" "B.Cu")
		(net "PVCCIN_CPU0")
	)
	(via
		(at 357.70058 -245.55069)
		(size 0.4572)
		(drill 0.2032)
		(layers "F.Cu" "B.Cu")
		(net "PVCCIN_CPU0")
	)
	(via
		(at 363.150404 -239.328198)
		(size 0.4572)
		(drill 0.2032)
		(layers "F.Cu" "B.Cu")
		(net "PVCCIN_CPU0")
	)
	(via
		(at 371.46738 -319.867534)
		(size 0.508)
		(drill 0.254)
		(layers "F.Cu" "B.Cu")
		(net "PVCCIN_CPU0")
	)
	(via
		(at 329.328526 -328.413618)
		(size 0.508)
		(drill 0.254)
		(layers "F.Cu" "B.Cu")
		(net "PVCCIN_CPU0")
	)
	(via
		(at 359.248964 -321.858132)
		(size 0.508)
		(drill 0.254)
		(layers "F.Cu" "B.Cu")
		(net "PVCCIN_CPU0")
	)
	(via
		(at 356.401116 -280.778204)
		(size 0.4572)
		(drill 0.2032)
		(layers "F.Cu" "B.Cu")
		(net "PVCCIN_CPU0")
	)
	(via
		(at 374.977914 -324.638416)
		(size 0.508)
		(drill 0.254)
		(layers "F.Cu" "B.Cu")
		(net "PVCCIN_CPU0")
	)
	(via
		(at 359.220516 -254.733552)
		(size 0.4572)
		(drill 0.2032)
		(layers "F.Cu" "B.Cu")
		(net "PVCCIN_CPU0")
	)
	(via
		(at 359.690162 -253.919736)
		(size 0.4572)
		(drill 0.2032)
		(layers "F.Cu" "B.Cu")
		(net "PVCCIN_CPU0")
	)
	(via
		(at 364.389162 -289.807142)
		(size 0.4572)
		(drill 0.2032)
		(layers "F.Cu" "B.Cu")
		(net "PVCCIN_CPU0")
	)
	(via
		(at 361.099862 -262.872474)
		(size 0.4572)
		(drill 0.2032)
		(layers "F.Cu" "B.Cu")
		(net "PVCCIN_CPU0")
	)
	(via
		(at 363.104176 -243.661692)
		(size 0.4572)
		(drill 0.2032)
		(layers "F.Cu" "B.Cu")
		(net "PVCCIN_CPU0")
	)
	(via
		(at 365.328962 -286.475424)
		(size 0.4572)
		(drill 0.2032)
		(layers "F.Cu" "B.Cu")
		(net "PVCCIN_CPU0")
	)
	(via
		(at 367.613946 -292.955726)
		(size 0.508)
		(drill 0.254)
		(layers "F.Cu" "B.Cu")
		(net "PVCCIN_CPU0")
	)
	(via
		(at 359.110534 -239.853216)
		(size 0.4572)
		(drill 0.2032)
		(layers "F.Cu" "B.Cu")
		(net "PVCCIN_CPU0")
	)
	(via
		(at 360.51998 -242.294918)
		(size 0.4572)
		(drill 0.2032)
		(layers "F.Cu" "B.Cu")
		(net "PVCCIN_CPU0")
	)
	(via
		(at 359.110534 -246.364506)
		(size 0.4572)
		(drill 0.2032)
		(layers "F.Cu" "B.Cu")
		(net "PVCCIN_CPU0")
	)
	(via
		(at 343.531444 -320.515742)
		(size 0.508)
		(drill 0.254)
		(layers "F.Cu" "B.Cu")
		(net "PVCCIN_CPU0")
	)
	(via
		(at 329.988926 -328.413618)
		(size 0.508)
		(drill 0.254)
		(layers "F.Cu" "B.Cu")
		(net "PVCCIN_CPU0")
	)
	(via
		(at 374.977914 -323.906896)
		(size 0.508)
		(drill 0.254)
		(layers "F.Cu" "B.Cu")
		(net "PVCCIN_CPU0")
	)
	(via
		(at 359.690162 -262.058658)
		(size 0.4572)
		(drill 0.2032)
		(layers "F.Cu" "B.Cu")
		(net "PVCCIN_CPU0")
	)
	(via
		(at 346.905072 -320.502534)
		(size 0.508)
		(drill 0.254)
		(layers "F.Cu" "B.Cu")
		(net "PVCCIN_CPU0")
	)
	(via
		(at 333.4131 -341.013288)
		(size 0.508)
		(drill 0.254)
		(layers "F.Cu" "B.Cu")
		(net "PVCCIN_CPU0")
	)
	(via
		(at 366.816386 -319.234058)
		(size 0.508)
		(drill 0.254)
		(layers "F.Cu" "B.Cu")
		(net "PVCCIN_CPU0")
	)
	(via
		(at 357.70058 -242.294918)
		(size 0.4572)
		(drill 0.2032)
		(layers "F.Cu" "B.Cu")
		(net "PVCCIN_CPU0")
	)
	(via
		(at 362.039916 -259.616956)
		(size 0.4572)
		(drill 0.2032)
		(layers "F.Cu" "B.Cu")
		(net "PVCCIN_CPU0")
	)
	(via
		(at 330.628244 -331.030072)
		(size 0.508)
		(drill 0.254)
		(layers "F.Cu" "B.Cu")
		(net "PVCCIN_CPU0")
	)
	(via
		(at 363.919262 -285.661354)
		(size 0.4572)
		(drill 0.2032)
		(layers "F.Cu" "B.Cu")
		(net "PVCCIN_CPU0")
	)
	(via
		(at 347.568266 -319.858898)
		(size 0.508)
		(drill 0.254)
		(layers "F.Cu" "B.Cu")
		(net "PVCCIN_CPU0")
	)
	(via
		(at 356.620064 -246.117364)
		(size 0.4572)
		(drill 0.2032)
		(layers "F.Cu" "B.Cu")
		(net "PVCCIN_CPU0")
	)
	(via
		(at 368.093752 -321.150742)
		(size 0.508)
		(drill 0.254)
		(layers "F.Cu" "B.Cu")
		(net "PVCCIN_CPU0")
	)
	(via
		(at 360.160316 -275.8948)
		(size 0.4572)
		(drill 0.2032)
		(layers "F.Cu" "B.Cu")
		(net "PVCCIN_CPU0")
	)
	(via
		(at 363.919262 -282.405836)
		(size 0.4572)
		(drill 0.2032)
		(layers "F.Cu" "B.Cu")
		(net "PVCCIN_CPU0")
	)
	(via
		(at 358.750616 -279.964134)
		(size 0.4572)
		(drill 0.2032)
		(layers "F.Cu" "B.Cu")
		(net "PVCCIN_CPU0")
	)
	(via
		(at 356.870762 -281.59202)
		(size 0.4572)
		(drill 0.2032)
		(layers "F.Cu" "B.Cu")
		(net "PVCCIN_CPU0")
	)
	(via
		(at 351.704656 -320.515742)
		(size 0.508)
		(drill 0.254)
		(layers "F.Cu" "B.Cu")
		(net "PVCCIN_CPU0")
	)
	(via
		(at 365.799116 -287.28924)
		(size 0.4572)
		(drill 0.2032)
		(layers "F.Cu" "B.Cu")
		(net "PVCCIN_CPU0")
	)
	(via
		(at 363.919262 -284.033722)
		(size 0.4572)
		(drill 0.2032)
		(layers "F.Cu" "B.Cu")
		(net "PVCCIN_CPU0")
	)
	(via
		(at 362.039916 -262.872474)
		(size 0.4572)
		(drill 0.2032)
		(layers "F.Cu" "B.Cu")
		(net "PVCCIN_CPU0")
	)
	(via
		(at 367.04143 -242.981226)
		(size 0.4572)
		(drill 0.2032)
		(layers "F.Cu" "B.Cu")
		(net "PVCCIN_CPU0")
	)
	(via
		(at 358.750616 -260.430772)
		(size 0.4572)
		(drill 0.2032)
		(layers "F.Cu" "B.Cu")
		(net "PVCCIN_CPU0")
	)
	(via
		(at 363.29747 -321.139312)
		(size 0.508)
		(drill 0.254)
		(layers "F.Cu" "B.Cu")
		(net "PVCCIN_CPU0")
	)
	(via
		(at 357.230934 -244.73662)
		(size 0.4572)
		(drill 0.2032)
		(layers "F.Cu" "B.Cu")
		(net "PVCCIN_CPU0")
	)
	(via
		(at 361.726226 -295.02608)
		(size 0.508)
		(drill 0.254)
		(layers "F.Cu" "B.Cu")
		(net "PVCCIN_CPU0")
	)
	(via
		(at 358.280716 -279.150318)
		(size 0.4572)
		(drill 0.2032)
		(layers "F.Cu" "B.Cu")
		(net "PVCCIN_CPU0")
	)
	(via
		(at 370.82984 -320.510154)
		(size 0.508)
		(drill 0.254)
		(layers "F.Cu" "B.Cu")
		(net "PVCCIN_CPU0")
	)
	(via
		(at 360.51998 -248.806208)
		(size 0.4572)
		(drill 0.2032)
		(layers "F.Cu" "B.Cu")
		(net "PVCCIN_CPU0")
	)
	(via
		(at 357.810562 -257.175254)
		(size 0.4572)
		(drill 0.2032)
		(layers "F.Cu" "B.Cu")
		(net "PVCCIN_CPU0")
	)
	(via
		(at 346.269564 -321.865752)
		(size 0.508)
		(drill 0.254)
		(layers "F.Cu" "B.Cu")
		(net "PVCCIN_CPU0")
	)
	(via
		(at 339.430106 -322.523358)
		(size 0.508)
		(drill 0.254)
		(layers "F.Cu" "B.Cu")
		(net "PVCCIN_CPU0")
	)
	(via
		(at 334.74533 -323.21119)
		(size 0.508)
		(drill 0.254)
		(layers "F.Cu" "B.Cu")
		(net "PVCCIN_CPU0")
	)
	(via
		(at 359.690162 -260.430772)
		(size 0.4572)
		(drill 0.2032)
		(layers "F.Cu" "B.Cu")
		(net "PVCCIN_CPU0")
	)
	(via
		(at 358.750616 -281.59202)
		(size 0.4572)
		(drill 0.2032)
		(layers "F.Cu" "B.Cu")
		(net "PVCCIN_CPU0")
	)
	(via
		(at 361.099862 -282.405836)
		(size 0.4572)
		(drill 0.2032)
		(layers "F.Cu" "B.Cu")
		(net "PVCCIN_CPU0")
	)
	(via
		(at 338.843366 -320.547238)
		(size 0.508)
		(drill 0.254)
		(layers "F.Cu" "B.Cu")
		(net "PVCCIN_CPU0")
	)
	(via
		(at 357.340662 -285.661354)
		(size 0.4572)
		(drill 0.2032)
		(layers "F.Cu" "B.Cu")
		(net "PVCCIN_CPU0")
	)
	(via
		(at 360.160316 -262.872474)
		(size 0.4572)
		(drill 0.2032)
		(layers "F.Cu" "B.Cu")
		(net "PVCCIN_CPU0")
	)
	(via
		(at 354.440744 -319.875154)
		(size 0.508)
		(drill 0.254)
		(layers "F.Cu" "B.Cu")
		(net "PVCCIN_CPU0")
	)
	(via
		(at 338.828126 -321.200018)
		(size 0.508)
		(drill 0.254)
		(layers "F.Cu" "B.Cu")
		(net "PVCCIN_CPU0")
	)
	(via
		(at 383.857754 -329.809856)
		(size 0.508)
		(drill 0.254)
		(layers "F.Cu" "B.Cu")
		(net "PVCCIN_CPU0")
	)
	(via
		(at 356.620064 -249.70994)
		(size 0.4572)
		(drill 0.2032)
		(layers "F.Cu" "B.Cu")
		(net "PVCCIN_CPU0")
	)
	(via
		(at 359.283254 -320.523362)
		(size 0.508)
		(drill 0.254)
		(layers "F.Cu" "B.Cu")
		(net "PVCCIN_CPU0")
	)
	(via
		(at 359.920794 -321.150742)
		(size 0.508)
		(drill 0.254)
		(layers "F.Cu" "B.Cu")
		(net "PVCCIN_CPU0")
	)
	(via
		(at 359.110534 -244.73662)
		(size 0.4572)
		(drill 0.2032)
		(layers "F.Cu" "B.Cu")
		(net "PVCCIN_CPU0")
	)
	(via
		(at 356.870762 -289.807142)
		(size 0.4572)
		(drill 0.2032)
		(layers "F.Cu" "B.Cu")
		(net "PVCCIN_CPU0")
	)
	(via
		(at 355.931216 -286.475424)
		(size 0.4572)
		(drill 0.2032)
		(layers "F.Cu" "B.Cu")
		(net "PVCCIN_CPU0")
	)
	(via
		(at 359.280206 -319.251584)
		(size 0.508)
		(drill 0.254)
		(layers "F.Cu" "B.Cu")
		(net "PVCCIN_CPU0")
	)
	(via
		(at 360.629962 -270.19758)
		(size 0.4572)
		(drill 0.2032)
		(layers "F.Cu" "B.Cu")
		(net "PVCCIN_CPU0")
	)
	(via
		(at 362.656882 -319.240154)
		(size 0.508)
		(drill 0.254)
		(layers "F.Cu" "B.Cu")
		(net "PVCCIN_CPU0")
	)
	(via
		(at 358.750616 -257.175254)
		(size 0.4572)
		(drill 0.2032)
		(layers "F.Cu" "B.Cu")
		(net "PVCCIN_CPU0")
	)
	(via
		(at 356.620064 -242.334288)
		(size 0.4572)
		(drill 0.2032)
		(layers "F.Cu" "B.Cu")
		(net "PVCCIN_CPU0")
	)
	(via
		(at 370.82984 -319.240154)
		(size 0.508)
		(drill 0.254)
		(layers "F.Cu" "B.Cu")
		(net "PVCCIN_CPU0")
	)
	(via
		(at 356.620064 -246.701564)
		(size 0.4572)
		(drill 0.2032)
		(layers "F.Cu" "B.Cu")
		(net "PVCCIN_CPU0")
	)
	(via
		(at 339.491066 -320.562478)
		(size 0.508)
		(drill 0.254)
		(layers "F.Cu" "B.Cu")
		(net "PVCCIN_CPU0")
	)
	(via
		(at 352.096324 -250.344686)
		(size 0.4572)
		(drill 0.2032)
		(layers "F.Cu" "B.Cu")
		(net "PVCCIN_CPU0")
	)
	(via
		(at 357.810562 -253.919736)
		(size 0.4572)
		(drill 0.2032)
		(layers "F.Cu" "B.Cu")
		(net "PVCCIN_CPU0")
	)
	(via
		(at 338.118958 -322.562982)
		(size 0.508)
		(drill 0.254)
		(layers "F.Cu" "B.Cu")
		(net "PVCCIN_CPU0")
	)
	(via
		(at 359.690162 -279.964134)
		(size 0.4572)
		(drill 0.2032)
		(layers "F.Cu" "B.Cu")
		(net "PVCCIN_CPU0")
	)
	(via
		(at 354.051362 -289.807142)
		(size 0.4572)
		(drill 0.2032)
		(layers "F.Cu" "B.Cu")
		(net "PVCCIN_CPU0")
	)
	(via
		(at 375.635266 -321.164458)
		(size 0.508)
		(drill 0.254)
		(layers "F.Cu" "B.Cu")
		(net "PVCCIN_CPU0")
	)
	(via
		(at 362.509562 -286.475424)
		(size 0.4572)
		(drill 0.2032)
		(layers "F.Cu" "B.Cu")
		(net "PVCCIN_CPU0")
	)
	(via
		(at 378.977906 -322.947538)
		(size 0.508)
		(drill 0.254)
		(layers "F.Cu" "B.Cu")
		(net "PVCCIN_CPU0")
	)
	(via
		(at 358.640634 -248.806208)
		(size 0.4572)
		(drill 0.2032)
		(layers "F.Cu" "B.Cu")
		(net "PVCCIN_CPU0")
	)
	(via
		(at 359.110534 -243.108988)
		(size 0.4572)
		(drill 0.2032)
		(layers "F.Cu" "B.Cu")
		(net "PVCCIN_CPU0")
	)
	(via
		(at 357.340662 -284.033722)
		(size 0.4572)
		(drill 0.2032)
		(layers "F.Cu" "B.Cu")
		(net "PVCCIN_CPU0")
	)
	(via
		(at 359.110534 -241.481102)
		(size 0.4572)
		(drill 0.2032)
		(layers "F.Cu" "B.Cu")
		(net "PVCCIN_CPU0")
	)
	(via
		(at 350.399604 -321.880992)
		(size 0.508)
		(drill 0.254)
		(layers "F.Cu" "B.Cu")
		(net "PVCCIN_CPU0")
	)
	(via
		(at 364.859316 -288.917126)
		(size 0.4572)
		(drill 0.2032)
		(layers "F.Cu" "B.Cu")
		(net "PVCCIN_CPU0")
	)
	(via
		(at 342.868504 -321.858132)
		(size 0.508)
		(drill 0.254)
		(layers "F.Cu" "B.Cu")
		(net "PVCCIN_CPU0")
	)
	(via
		(at 363.953806 -320.514218)
		(size 0.508)
		(drill 0.254)
		(layers "F.Cu" "B.Cu")
		(net "PVCCIN_CPU0")
	)
	(via
		(at 357.340662 -279.150318)
		(size 0.4572)
		(drill 0.2032)
		(layers "F.Cu" "B.Cu")
		(net "PVCCIN_CPU0")
	)
	(via
		(at 383.212594 -329.070716)
		(size 0.508)
		(drill 0.254)
		(layers "F.Cu" "B.Cu")
		(net "PVCCIN_CPU0")
	)
	(via
		(at 358.750616 -258.80314)
		(size 0.4572)
		(drill 0.2032)
		(layers "F.Cu" "B.Cu")
		(net "PVCCIN_CPU0")
	)
	(via
		(at 359.690162 -278.336502)
		(size 0.4572)
		(drill 0.2032)
		(layers "F.Cu" "B.Cu")
		(net "PVCCIN_CPU0")
	)
	(via
		(at 349.234252 -295.038526)
		(size 0.508)
		(drill 0.254)
		(layers "F.Cu" "B.Cu")
		(net "PVCCIN_CPU0")
	)
	(via
		(at 334.707484 -325.182992)
		(size 0.508)
		(drill 0.254)
		(layers "F.Cu" "B.Cu")
		(net "PVCCIN_CPU0")
	)
	(via
		(at 358.640634 -240.667286)
		(size 0.4572)
		(drill 0.2032)
		(layers "F.Cu" "B.Cu")
		(net "PVCCIN_CPU0")
	)
	(via
		(at 338.118958 -323.197982)
		(size 0.508)
		(drill 0.254)
		(layers "F.Cu" "B.Cu")
		(net "PVCCIN_CPU0")
	)
	(via
		(at 375.630186 -324.356476)
		(size 0.508)
		(drill 0.254)
		(layers "F.Cu" "B.Cu")
		(net "PVCCIN_CPU0")
	)
	(via
		(at 367.67643 -250.337066)
		(size 0.4572)
		(drill 0.2032)
		(layers "F.Cu" "B.Cu")
		(net "PVCCIN_CPU0")
	)
	(via
		(at 354.287836 -239.292638)
		(size 0.4572)
		(drill 0.2032)
		(layers "F.Cu" "B.Cu")
		(net "PVCCIN_CPU0")
	)
	(via
		(at 357.227886 -247.992138)
		(size 0.4572)
		(drill 0.2032)
		(layers "F.Cu" "B.Cu")
		(net "PVCCIN_CPU0")
	)
	(via
		(at 363.449362 -281.59202)
		(size 0.4572)
		(drill 0.2032)
		(layers "F.Cu" "B.Cu")
		(net "PVCCIN_CPU0")
	)
	(via
		(at 361.569762 -278.336502)
		(size 0.4572)
		(drill 0.2032)
		(layers "F.Cu" "B.Cu")
		(net "PVCCIN_CPU0")
	)
	(via
		(at 329.328526 -329.683618)
		(size 0.508)
		(drill 0.254)
		(layers "F.Cu" "B.Cu")
		(net "PVCCIN_CPU0")
	)
	(via
		(at 330.027026 -327.710038)
		(size 0.508)
		(drill 0.254)
		(layers "F.Cu" "B.Cu")
		(net "PVCCIN_CPU0")
	)
	(via
		(at 361.099862 -280.778204)
		(size 0.4572)
		(drill 0.2032)
		(layers "F.Cu" "B.Cu")
		(net "PVCCIN_CPU0")
	)
	(via
		(at 362.399834 -247.178322)
		(size 0.4572)
		(drill 0.2032)
		(layers "F.Cu" "B.Cu")
		(net "PVCCIN_CPU0")
	)
	(via
		(at 378.993654 -325.133716)
		(size 0.508)
		(drill 0.254)
		(layers "F.Cu" "B.Cu")
		(net "PVCCIN_CPU0")
	)
	(via
		(at 363.294422 -319.232534)
		(size 0.508)
		(drill 0.254)
		(layers "F.Cu" "B.Cu")
		(net "PVCCIN_CPU0")
	)
	(via
		(at 365.798862 -284.033722)
		(size 0.4572)
		(drill 0.2032)
		(layers "F.Cu" "B.Cu")
		(net "PVCCIN_CPU0")
	)
	(via
		(at 359.220516 -272.639282)
		(size 0.4572)
		(drill 0.2032)
		(layers "F.Cu" "B.Cu")
		(net "PVCCIN_CPU0")
	)
	(via
		(at 360.629962 -283.219906)
		(size 0.4572)
		(drill 0.2032)
		(layers "F.Cu" "B.Cu")
		(net "PVCCIN_CPU0")
	)
	(via
		(at 376.280426 -321.194938)
		(size 0.508)
		(drill 0.254)
		(layers "F.Cu" "B.Cu")
		(net "PVCCIN_CPU0")
	)
	(via
		(at 362.039662 -277.522432)
		(size 0.4572)
		(drill 0.2032)
		(layers "F.Cu" "B.Cu")
		(net "PVCCIN_CPU0")
	)
	(via
		(at 363.919516 -280.778204)
		(size 0.4572)
		(drill 0.2032)
		(layers "F.Cu" "B.Cu")
		(net "PVCCIN_CPU0")
	)
	(via
		(at 380.288546 -324.682358)
		(size 0.508)
		(drill 0.254)
		(layers "F.Cu" "B.Cu")
		(net "PVCCIN_CPU0")
	)
	(via
		(at 325.066152 -331.226668)
		(size 0.508)
		(drill 0.254)
		(layers "F.Cu" "B.Cu")
		(net "PVCCIN_CPU0")
	)
	(via
		(at 362.509562 -279.964134)
		(size 0.4572)
		(drill 0.2032)
		(layers "F.Cu" "B.Cu")
		(net "PVCCIN_CPU0")
	)
	(via
		(at 330.672186 -327.047098)
		(size 0.508)
		(drill 0.254)
		(layers "F.Cu" "B.Cu")
		(net "PVCCIN_CPU0")
	)
	(via
		(at 357.810562 -262.058658)
		(size 0.4572)
		(drill 0.2032)
		(layers "F.Cu" "B.Cu")
		(net "PVCCIN_CPU0")
	)
	(via
		(at 359.283254 -321.158362)
		(size 0.508)
		(drill 0.254)
		(layers "F.Cu" "B.Cu")
		(net "PVCCIN_CPU0")
	)
	(via
		(at 380.288546 -324.019418)
		(size 0.508)
		(drill 0.254)
		(layers "F.Cu" "B.Cu")
		(net "PVCCIN_CPU0")
	)
	(via
		(at 361.099862 -277.522432)
		(size 0.4572)
		(drill 0.2032)
		(layers "F.Cu" "B.Cu")
		(net "PVCCIN_CPU0")
	)
	(via
		(at 346.907104 -321.858132)
		(size 0.508)
		(drill 0.254)
		(layers "F.Cu" "B.Cu")
		(net "PVCCIN_CPU0")
	)
	(via
		(at 360.629962 -286.475424)
		(size 0.4572)
		(drill 0.2032)
		(layers "F.Cu" "B.Cu")
		(net "PVCCIN_CPU0")
	)
	(via
		(at 354.440744 -319.240154)
		(size 0.508)
		(drill 0.254)
		(layers "F.Cu" "B.Cu")
		(net "PVCCIN_CPU0")
	)
	(via
		(at 351.067116 -319.888362)
		(size 0.508)
		(drill 0.254)
		(layers "F.Cu" "B.Cu")
		(net "PVCCIN_CPU0")
	)
	(via
		(at 362.039916 -257.98907)
		(size 0.4572)
		(drill 0.2032)
		(layers "F.Cu" "B.Cu")
		(net "PVCCIN_CPU0")
	)
	(via
		(at 357.340662 -254.733552)
		(size 0.4572)
		(drill 0.2032)
		(layers "F.Cu" "B.Cu")
		(net "PVCCIN_CPU0")
	)
	(via
		(at 356.620064 -253.37008)
		(size 0.4572)
		(drill 0.2032)
		(layers "F.Cu" "B.Cu")
		(net "PVCCIN_CPU0")
	)
	(via
		(at 362.399834 -239.0394)
		(size 0.4572)
		(drill 0.2032)
		(layers "F.Cu" "B.Cu")
		(net "PVCCIN_CPU0")
	)
	(via
		(at 334.743806 -321.855338)
		(size 0.508)
		(drill 0.254)
		(layers "F.Cu" "B.Cu")
		(net "PVCCIN_CPU0")
	)
	(via
		(at 349.812356 -337.223862)
		(size 0.508)
		(drill 0.254)
		(layers "F.Cu" "B.Cu")
		(net "PVCCIN_CPU0")
	)
	(via
		(at 357.810562 -281.59202)
		(size 0.4572)
		(drill 0.2032)
		(layers "F.Cu" "B.Cu")
		(net "PVCCIN_CPU0")
	)
	(via
		(at 354.722684 -257.675126)
		(size 0.4572)
		(drill 0.2032)
		(layers "F.Cu" "B.Cu")
		(net "PVCCIN_CPU0")
	)
	(via
		(at 361.099862 -254.733552)
		(size 0.4572)
		(drill 0.2032)
		(layers "F.Cu" "B.Cu")
		(net "PVCCIN_CPU0")
	)
	(via
		(at 356.401116 -287.28924)
		(size 0.4572)
		(drill 0.2032)
		(layers "F.Cu" "B.Cu")
		(net "PVCCIN_CPU0")
	)
	(via
		(at 359.220516 -261.244842)
		(size 0.4572)
		(drill 0.2032)
		(layers "F.Cu" "B.Cu")
		(net "PVCCIN_CPU0")
	)
	(via
		(at 360.98988 -249.620024)
		(size 0.4572)
		(drill 0.2032)
		(layers "F.Cu" "B.Cu")
		(net "PVCCIN_CPU0")
	)
	(via
		(at 356.870762 -279.964134)
		(size 0.4572)
		(drill 0.2032)
		(layers "F.Cu" "B.Cu")
		(net "PVCCIN_CPU0")
	)
	(via
		(at 364.859316 -287.28924)
		(size 0.4572)
		(drill 0.2032)
		(layers "F.Cu" "B.Cu")
		(net "PVCCIN_CPU0")
	)
	(via
		(at 375.620534 -325.133716)
		(size 0.508)
		(drill 0.254)
		(layers "F.Cu" "B.Cu")
		(net "PVCCIN_CPU0")
	)
	(via
		(at 362.509562 -288.103056)
		(size 0.4572)
		(drill 0.2032)
		(layers "F.Cu" "B.Cu")
		(net "PVCCIN_CPU0")
	)
	(via
		(at 363.971586 -319.198498)
		(size 0.508)
		(drill 0.254)
		(layers "F.Cu" "B.Cu")
		(net "PVCCIN_CPU0")
	)
	(via
		(at 355.301804 -250.337066)
		(size 0.4572)
		(drill 0.2032)
		(layers "F.Cu" "B.Cu")
		(net "PVCCIN_CPU0")
	)
	(via
		(at 358.624886 -319.851278)
		(size 0.508)
		(drill 0.254)
		(layers "F.Cu" "B.Cu")
		(net "PVCCIN_CPU0")
	)
	(via
		(at 357.230934 -239.853216)
		(size 0.4572)
		(drill 0.2032)
		(layers "F.Cu" "B.Cu")
		(net "PVCCIN_CPU0")
	)
	(via
		(at 359.220516 -256.361438)
		(size 0.4572)
		(drill 0.2032)
		(layers "F.Cu" "B.Cu")
		(net "PVCCIN_CPU0")
	)
	(via
		(at 359.58018 -242.294918)
		(size 0.4572)
		(drill 0.2032)
		(layers "F.Cu" "B.Cu")
		(net "PVCCIN_CPU0")
	)
	(via
		(at 358.640634 -247.178322)
		(size 0.4572)
		(drill 0.2032)
		(layers "F.Cu" "B.Cu")
		(net "PVCCIN_CPU0")
	)
	(via
		(at 359.690162 -258.80314)
		(size 0.4572)
		(drill 0.2032)
		(layers "F.Cu" "B.Cu")
		(net "PVCCIN_CPU0")
	)
	(via
		(at 383.212594 -329.802236)
		(size 0.508)
		(drill 0.254)
		(layers "F.Cu" "B.Cu")
		(net "PVCCIN_CPU0")
	)
	(via
		(at 358.750616 -268.569694)
		(size 0.4572)
		(drill 0.2032)
		(layers "F.Cu" "B.Cu")
		(net "PVCCIN_CPU0")
	)
	(via
		(at 357.230934 -249.620024)
		(size 0.4572)
		(drill 0.2032)
		(layers "F.Cu" "B.Cu")
		(net "PVCCIN_CPU0")
	)
	(via
		(at 363.104176 -247.166892)
		(size 0.4572)
		(drill 0.2032)
		(layers "F.Cu" "B.Cu")
		(net "PVCCIN_CPU0")
	)
	(via
		(at 339.412326 -323.839078)
		(size 0.508)
		(drill 0.254)
		(layers "F.Cu" "B.Cu")
		(net "PVCCIN_CPU0")
	)
	(via
		(at 370.832888 -321.146932)
		(size 0.508)
		(drill 0.254)
		(layers "F.Cu" "B.Cu")
		(net "PVCCIN_CPU0")
	)
	(via
		(at 357.810562 -288.103056)
		(size 0.4572)
		(drill 0.2032)
		(layers "F.Cu" "B.Cu")
		(net "PVCCIN_CPU0")
	)
	(via
		(at 358.750362 -263.686544)
		(size 0.4572)
		(drill 0.2032)
		(layers "F.Cu" "B.Cu")
		(net "PVCCIN_CPU0")
	)
	(via
		(at 361.929934 -247.992138)
		(size 0.4572)
		(drill 0.2032)
		(layers "F.Cu" "B.Cu")
		(net "PVCCIN_CPU0")
	)
	(via
		(at 331.276706 -326.681338)
		(size 0.508)
		(drill 0.254)
		(layers "F.Cu" "B.Cu")
		(net "PVCCIN_CPU0")
	)
	(via
		(at 347.583506 -319.206118)
		(size 0.508)
		(drill 0.254)
		(layers "F.Cu" "B.Cu")
		(net "PVCCIN_CPU0")
	)
	(via
		(at 354.051362 -284.847538)
		(size 0.4572)
		(drill 0.2032)
		(layers "F.Cu" "B.Cu")
		(net "PVCCIN_CPU0")
	)
	(via
		(at 367.039144 -257.695446)
		(size 0.4572)
		(drill 0.2032)
		(layers "F.Cu" "B.Cu")
		(net "PVCCIN_CPU0")
	)
	(via
		(at 358.750616 -270.19758)
		(size 0.4572)
		(drill 0.2032)
		(layers "F.Cu" "B.Cu")
		(net "PVCCIN_CPU0")
	)
	(via
		(at 362.361226 -297.07078)
		(size 0.508)
		(drill 0.254)
		(layers "F.Cu" "B.Cu")
		(net "PVCCIN_CPU0")
	)
	(via
		(at 358.640126 -319.198498)
		(size 0.508)
		(drill 0.254)
		(layers "F.Cu" "B.Cu")
		(net "PVCCIN_CPU0")
	)
	(via
		(at 360.160316 -287.28924)
		(size 0.4572)
		(drill 0.2032)
		(layers "F.Cu" "B.Cu")
		(net "PVCCIN_CPU0")
	)
	(via
		(at 367.425224 -321.893692)
		(size 0.508)
		(drill 0.254)
		(layers "F.Cu" "B.Cu")
		(net "PVCCIN_CPU0")
	)
	(via
		(at 330.626466 -328.405998)
		(size 0.508)
		(drill 0.254)
		(layers "F.Cu" "B.Cu")
		(net "PVCCIN_CPU0")
	)
	(via
		(at 359.690162 -276.708616)
		(size 0.4572)
		(drill 0.2032)
		(layers "F.Cu" "B.Cu")
		(net "PVCCIN_CPU0")
	)
	(via
		(at 360.629962 -268.569694)
		(size 0.4572)
		(drill 0.2032)
		(layers "F.Cu" "B.Cu")
		(net "PVCCIN_CPU0")
	)
	(via
		(at 355.454204 -262.199882)
		(size 0.4572)
		(drill 0.2032)
		(layers "F.Cu" "B.Cu")
		(net "PVCCIN_CPU0")
	)
	(via
		(at 362.509562 -260.430772)
		(size 0.4572)
		(drill 0.2032)
		(layers "F.Cu" "B.Cu")
		(net "PVCCIN_CPU0")
	)
	(via
		(at 376.265694 -325.133716)
		(size 0.508)
		(drill 0.254)
		(layers "F.Cu" "B.Cu")
		(net "PVCCIN_CPU0")
	)
	(via
		(at 362.039916 -256.361438)
		(size 0.4572)
		(drill 0.2032)
		(layers "F.Cu" "B.Cu")
		(net "PVCCIN_CPU0")
	)
	(via
		(at 363.449362 -288.103056)
		(size 0.4572)
		(drill 0.2032)
		(layers "F.Cu" "B.Cu")
		(net "PVCCIN_CPU0")
	)
	(via
		(at 358.640634 -242.294918)
		(size 0.4572)
		(drill 0.2032)
		(layers "F.Cu" "B.Cu")
		(net "PVCCIN_CPU0")
	)
	(via
		(at 338.118958 -323.832982)
		(size 0.508)
		(drill 0.254)
		(layers "F.Cu" "B.Cu")
		(net "PVCCIN_CPU0")
	)
	(via
		(at 355.303074 -297.197526)
		(size 0.508)
		(drill 0.254)
		(layers "F.Cu" "B.Cu")
		(net "PVCCIN_CPU0")
	)
	(via
		(at 362.039916 -285.661354)
		(size 0.4572)
		(drill 0.2032)
		(layers "F.Cu" "B.Cu")
		(net "PVCCIN_CPU0")
	)
	(via
		(at 361.929934 -241.481102)
		(size 0.4572)
		(drill 0.2032)
		(layers "F.Cu" "B.Cu")
		(net "PVCCIN_CPU0")
	)
	(via
		(at 360.629962 -271.825212)
		(size 0.4572)
		(drill 0.2032)
		(layers "F.Cu" "B.Cu")
		(net "PVCCIN_CPU0")
	)
	(via
		(at 357.340662 -264.50036)
		(size 0.4572)
		(drill 0.2032)
		(layers "F.Cu" "B.Cu")
		(net "PVCCIN_CPU0")
	)
	(via
		(at 363.951774 -321.199256)
		(size 0.508)
		(drill 0.254)
		(layers "F.Cu" "B.Cu")
		(net "PVCCIN_CPU0")
	)
	(via
		(at 357.230934 -241.481102)
		(size 0.4572)
		(drill 0.2032)
		(layers "F.Cu" "B.Cu")
		(net "PVCCIN_CPU0")
	)
	(via
		(at 361.099862 -256.361438)
		(size 0.4572)
		(drill 0.2032)
		(layers "F.Cu" "B.Cu")
		(net "PVCCIN_CPU0")
	)
	(via
		(at 360.160316 -254.733552)
		(size 0.4572)
		(drill 0.2032)
		(layers "F.Cu" "B.Cu")
		(net "PVCCIN_CPU0")
	)
	(via
		(at 354.991162 -286.475424)
		(size 0.4572)
		(drill 0.2032)
		(layers "F.Cu" "B.Cu")
		(net "PVCCIN_CPU0")
	)
	(via
		(at 360.160316 -272.639282)
		(size 0.4572)
		(drill 0.2032)
		(layers "F.Cu" "B.Cu")
		(net "PVCCIN_CPU0")
	)
	(via
		(at 362.509562 -262.058658)
		(size 0.4572)
		(drill 0.2032)
		(layers "F.Cu" "B.Cu")
		(net "PVCCIN_CPU0")
	)
	(via
		(at 351.923604 -242.981226)
		(size 0.4572)
		(drill 0.2032)
		(layers "F.Cu" "B.Cu")
		(net "PVCCIN_CPU0")
	)
	(via
		(at 360.629962 -255.547622)
		(size 0.4572)
		(drill 0.2032)
		(layers "F.Cu" "B.Cu")
		(net "PVCCIN_CPU0")
	)
	(via
		(at 364.859316 -284.033722)
		(size 0.4572)
		(drill 0.2032)
		(layers "F.Cu" "B.Cu")
		(net "PVCCIN_CPU0")
	)
	(via
		(at 362.979716 -280.778204)
		(size 0.4572)
		(drill 0.2032)
		(layers "F.Cu" "B.Cu")
		(net "PVCCIN_CPU0")
	)
	(via
		(at 351.064068 -319.251584)
		(size 0.508)
		(drill 0.254)
		(layers "F.Cu" "B.Cu")
		(net "PVCCIN_CPU0")
	)
	(via
		(at 362.039916 -279.150318)
		(size 0.4572)
		(drill 0.2032)
		(layers "F.Cu" "B.Cu")
		(net "PVCCIN_CPU0")
	)
	(via
		(at 343.531444 -321.150742)
		(size 0.508)
		(drill 0.254)
		(layers "F.Cu" "B.Cu")
		(net "PVCCIN_CPU0")
	)
	(via
		(at 364.37443 -250.337066)
		(size 0.4572)
		(drill 0.2032)
		(layers "F.Cu" "B.Cu")
		(net "PVCCIN_CPU0")
	)
	(via
		(at 374.977914 -323.175376)
		(size 0.508)
		(drill 0.254)
		(layers "F.Cu" "B.Cu")
		(net "PVCCIN_CPU0")
	)
	(via
		(at 359.58018 -245.55069)
		(size 0.4572)
		(drill 0.2032)
		(layers "F.Cu" "B.Cu")
		(net "PVCCIN_CPU0")
	)
	(via
		(at 335.381346 -321.847718)
		(size 0.508)
		(drill 0.254)
		(layers "F.Cu" "B.Cu")
		(net "PVCCIN_CPU0")
	)
	(via
		(at 357.340662 -262.872474)
		(size 0.4572)
		(drill 0.2032)
		(layers "F.Cu" "B.Cu")
		(net "PVCCIN_CPU0")
	)
	(via
		(at 382.41478 -346.509848)
		(size 0.508)
		(drill 0.254)
		(layers "F.Cu" "B.Cu")
		(net "PVCCIN_CPU0")
	)
	(via
		(at 359.220516 -266.128246)
		(size 0.4572)
		(drill 0.2032)
		(layers "F.Cu" "B.Cu")
		(net "PVCCIN_CPU0")
	)
	(via
		(at 354.991162 -289.807142)
		(size 0.4572)
		(drill 0.2032)
		(layers "F.Cu" "B.Cu")
		(net "PVCCIN_CPU0")
	)
	(via
		(at 359.690162 -288.103056)
		(size 0.4572)
		(drill 0.2032)
		(layers "F.Cu" "B.Cu")
		(net "PVCCIN_CPU0")
	)
	(via
		(at 353.581716 -287.28924)
		(size 0.4572)
		(drill 0.2032)
		(layers "F.Cu" "B.Cu")
		(net "PVCCIN_CPU0")
	)
	(via
		(at 362.039662 -264.50036)
		(size 0.4572)
		(drill 0.2032)
		(layers "F.Cu" "B.Cu")
		(net "PVCCIN_CPU0")
	)
	(via
		(at 351.067116 -320.523362)
		(size 0.508)
		(drill 0.254)
		(layers "F.Cu" "B.Cu")
		(net "PVCCIN_CPU0")
	)
	(via
		(at 331.269086 -327.341738)
		(size 0.508)
		(drill 0.254)
		(layers "F.Cu" "B.Cu")
		(net "PVCCIN_CPU0")
	)
	(via
		(at 365.14151 -242.981226)
		(size 0.4572)
		(drill 0.2032)
		(layers "F.Cu" "B.Cu")
		(net "PVCCIN_CPU0")
	)
	(via
		(at 385.153154 -329.809856)
		(size 0.508)
		(drill 0.254)
		(layers "F.Cu" "B.Cu")
		(net "PVCCIN_CPU0")
	)
	(via
		(at 352.507804 -242.981226)
		(size 0.4572)
		(drill 0.2032)
		(layers "F.Cu" "B.Cu")
		(net "PVCCIN_CPU0")
	)
	(via
		(at 357.70058 -248.806208)
		(size 0.4572)
		(drill 0.2032)
		(layers "F.Cu" "B.Cu")
		(net "PVCCIN_CPU0")
	)
	(via
		(at 359.110534 -249.620024)
		(size 0.4572)
		(drill 0.2032)
		(layers "F.Cu" "B.Cu")
		(net "PVCCIN_CPU0")
	)
	(via
		(at 360.629962 -253.919736)
		(size 0.4572)
		(drill 0.2032)
		(layers "F.Cu" "B.Cu")
		(net "PVCCIN_CPU0")
	)
	(via
		(at 367.67643 -254.020066)
		(size 0.4572)
		(drill 0.2032)
		(layers "F.Cu" "B.Cu")
		(net "PVCCIN_CPU0")
	)
	(via
		(at 363.104176 -250.087892)
		(size 0.4572)
		(drill 0.2032)
		(layers "F.Cu" "B.Cu")
		(net "PVCCIN_CPU0")
	)
	(via
		(at 357.340662 -259.616956)
		(size 0.4572)
		(drill 0.2032)
		(layers "F.Cu" "B.Cu")
		(net "PVCCIN_CPU0")
	)
	(via
		(at 361.569762 -265.314176)
		(size 0.4572)
		(drill 0.2032)
		(layers "F.Cu" "B.Cu")
		(net "PVCCIN_CPU0")
	)
	(via
		(at 354.604574 -295.038526)
		(size 0.508)
		(drill 0.254)
		(layers "F.Cu" "B.Cu")
		(net "PVCCIN_CPU0")
	)
	(via
		(at 358.750616 -262.058658)
		(size 0.4572)
		(drill 0.2032)
		(layers "F.Cu" "B.Cu")
		(net "PVCCIN_CPU0")
	)
	(via
		(at 359.920794 -319.880742)
		(size 0.508)
		(drill 0.254)
		(layers "F.Cu" "B.Cu")
		(net "PVCCIN_CPU0")
	)
	(via
		(at 367.208562 -288.103056)
		(size 0.4572)
		(drill 0.2032)
		(layers "F.Cu" "B.Cu")
		(net "PVCCIN_CPU0")
	)
	(via
		(at 358.750616 -284.847538)
		(size 0.4572)
		(drill 0.2032)
		(layers "F.Cu" "B.Cu")
		(net "PVCCIN_CPU0")
	)
	(via
		(at 360.629962 -260.430772)
		(size 0.4572)
		(drill 0.2032)
		(layers "F.Cu" "B.Cu")
		(net "PVCCIN_CPU0")
	)
	(via
		(at 366.801146 -319.886838)
		(size 0.508)
		(drill 0.254)
		(layers "F.Cu" "B.Cu")
		(net "PVCCIN_CPU0")
	)
	(via
		(at 355.303074 -292.955726)
		(size 0.508)
		(drill 0.254)
		(layers "F.Cu" "B.Cu")
		(net "PVCCIN_CPU0")
	)
	(via
		(at 357.810562 -283.219906)
		(size 0.4572)
		(drill 0.2032)
		(layers "F.Cu" "B.Cu")
		(net "PVCCIN_CPU0")
	)
	(via
		(at 382.674114 -328.710036)
		(size 0.508)
		(drill 0.254)
		(layers "F.Cu" "B.Cu")
		(net "PVCCIN_CPU0")
	)
	(via
		(at 357.70058 -243.922804)
		(size 0.4572)
		(drill 0.2032)
		(layers "F.Cu" "B.Cu")
		(net "PVCCIN_CPU0")
	)
	(via
		(at 370.82984 -319.875154)
		(size 0.508)
		(drill 0.254)
		(layers "F.Cu" "B.Cu")
		(net "PVCCIN_CPU0")
	)
	(via
		(at 350.397826 -320.526918)
		(size 0.508)
		(drill 0.254)
		(layers "F.Cu" "B.Cu")
		(net "PVCCIN_CPU0")
	)
	(via
		(at 383.209546 -327.651618)
		(size 0.508)
		(drill 0.254)
		(layers "F.Cu" "B.Cu")
		(net "PVCCIN_CPU0")
	)
	(via
		(at 360.160316 -261.244842)
		(size 0.4572)
		(drill 0.2032)
		(layers "F.Cu" "B.Cu")
		(net "PVCCIN_CPU0")
	)
	(via
		(at 324.330314 -346.174314)
		(size 0.508)
		(drill 0.254)
		(layers "F.Cu" "B.Cu")
		(net "PVCCIN_CPU0")
	)
	(via
		(at 329.991974 -330.320396)
		(size 0.508)
		(drill 0.254)
		(layers "F.Cu" "B.Cu")
		(net "PVCCIN_CPU0")
	)
	(via
		(at 362.979716 -282.405836)
		(size 0.4572)
		(drill 0.2032)
		(layers "F.Cu" "B.Cu")
		(net "PVCCIN_CPU0")
	)
	(via
		(at 356.401116 -284.033722)
		(size 0.4572)
		(drill 0.2032)
		(layers "F.Cu" "B.Cu")
		(net "PVCCIN_CPU0")
	)
	(via
		(at 342.234266 -319.198498)
		(size 0.508)
		(drill 0.254)
		(layers "F.Cu" "B.Cu")
		(net "PVCCIN_CPU0")
	)
	(via
		(at 359.58018 -243.922804)
		(size 0.4572)
		(drill 0.2032)
		(layers "F.Cu" "B.Cu")
		(net "PVCCIN_CPU0")
	)
	(via
		(at 362.509562 -253.919736)
		(size 0.4572)
		(drill 0.2032)
		(layers "F.Cu" "B.Cu")
		(net "PVCCIN_CPU0")
	)
	(via
		(at 355.454204 -263.368282)
		(size 0.4572)
		(drill 0.2032)
		(layers "F.Cu" "B.Cu")
		(net "PVCCIN_CPU0")
	)
	(via
		(at 329.331574 -330.320396)
		(size 0.508)
		(drill 0.254)
		(layers "F.Cu" "B.Cu")
		(net "PVCCIN_CPU0")
	)
	(via
		(at 331.264006 -328.654918)
		(size 0.508)
		(drill 0.254)
		(layers "F.Cu" "B.Cu")
		(net "PVCCIN_CPU0")
	)
	(via
		(at 329.366626 -327.710038)
		(size 0.508)
		(drill 0.254)
		(layers "F.Cu" "B.Cu")
		(net "PVCCIN_CPU0")
	)
	(via
		(at 360.629962 -273.453098)
		(size 0.4572)
		(drill 0.2032)
		(layers "F.Cu" "B.Cu")
		(net "PVCCIN_CPU0")
	)
	(via
		(at 366.268762 -289.807142)
		(size 0.4572)
		(drill 0.2032)
		(layers "F.Cu" "B.Cu")
		(net "PVCCIN_CPU0")
	)
	(via
		(at 339.414866 -323.176138)
		(size 0.508)
		(drill 0.254)
		(layers "F.Cu" "B.Cu")
		(net "PVCCIN_CPU0")
	)
	(via
		(at 380.303786 -323.366638)
		(size 0.508)
		(drill 0.254)
		(layers "F.Cu" "B.Cu")
		(net "PVCCIN_CPU0")
	)
	(via
		(at 357.810562 -263.686544)
		(size 0.4572)
		(drill 0.2032)
		(layers "F.Cu" "B.Cu")
		(net "PVCCIN_CPU0")
	)
	(via
		(at 360.050334 -249.620024)
		(size 0.4572)
		(drill 0.2032)
		(layers "F.Cu" "B.Cu")
		(net "PVCCIN_CPU0")
	)
	(via
		(at 365.14151 -250.337066)
		(size 0.4572)
		(drill 0.2032)
		(layers "F.Cu" "B.Cu")
		(net "PVCCIN_CPU0")
	)
	(via
		(at 378.991114 -324.364096)
		(size 0.508)
		(drill 0.254)
		(layers "F.Cu" "B.Cu")
		(net "PVCCIN_CPU0")
	)
	(via
		(at 362.361226 -295.02608)
		(size 0.508)
		(drill 0.254)
		(layers "F.Cu" "B.Cu")
		(net "PVCCIN_CPU0")
	)
	(via
		(at 367.575846 -297.197526)
		(size 0.508)
		(drill 0.254)
		(layers "F.Cu" "B.Cu")
		(net "PVCCIN_CPU0")
	)
	(via
		(at 335.345024 -325.175372)
		(size 0.508)
		(drill 0.254)
		(layers "F.Cu" "B.Cu")
		(net "PVCCIN_CPU0")
	)
	(via
		(at 360.160316 -288.993326)
		(size 0.4572)
		(drill 0.2032)
		(layers "F.Cu" "B.Cu")
		(net "PVCCIN_CPU0")
	)
	(via
		(at 354.521516 -284.033722)
		(size 0.4572)
		(drill 0.2032)
		(layers "F.Cu" "B.Cu")
		(net "PVCCIN_CPU0")
	)
	(via
		(at 362.979716 -284.033722)
		(size 0.4572)
		(drill 0.2032)
		(layers "F.Cu" "B.Cu")
		(net "PVCCIN_CPU0")
	)
	(via
		(at 357.340662 -256.361438)
		(size 0.4572)
		(drill 0.2032)
		(layers "F.Cu" "B.Cu")
		(net "PVCCIN_CPU0")
	)
	(via
		(at 357.340662 -257.98907)
		(size 0.4572)
		(drill 0.2032)
		(layers "F.Cu" "B.Cu")
		(net "PVCCIN_CPU0")
	)
	(via
		(at 361.099862 -257.98907)
		(size 0.4572)
		(drill 0.2032)
		(layers "F.Cu" "B.Cu")
		(net "PVCCIN_CPU0")
	)
	(via
		(at 349.211138 -292.879526)
		(size 0.4572)
		(drill 0.2032)
		(layers "F.Cu" "B.Cu")
		(net "PVCCIN_CPU0")
	)
	(via
		(at 360.050334 -247.992138)
		(size 0.4572)
		(drill 0.2032)
		(layers "F.Cu" "B.Cu")
		(net "PVCCIN_CPU0")
	)
	(via
		(at 354.604574 -297.197526)
		(size 0.508)
		(drill 0.254)
		(layers "F.Cu" "B.Cu")
		(net "PVCCIN_CPU0")
	)
	(via
		(at 360.160316 -271.011396)
		(size 0.4572)
		(drill 0.2032)
		(layers "F.Cu" "B.Cu")
		(net "PVCCIN_CPU0")
	)
	(via
		(at 335.38287 -323.83857)
		(size 0.508)
		(drill 0.254)
		(layers "F.Cu" "B.Cu")
		(net "PVCCIN_CPU0")
	)
	(via
		(at 361.099862 -269.38351)
		(size 0.4572)
		(drill 0.2032)
		(layers "F.Cu" "B.Cu")
		(net "PVCCIN_CPU0")
	)
	(via
		(at 382.663954 -327.978516)
		(size 0.508)
		(drill 0.254)
		(layers "F.Cu" "B.Cu")
		(net "PVCCIN_CPU0")
	)
	(via
		(at 383.857754 -329.078336)
		(size 0.508)
		(drill 0.254)
		(layers "F.Cu" "B.Cu")
		(net "PVCCIN_CPU0")
	)
	(via
		(at 362.399834 -245.55069)
		(size 0.4572)
		(drill 0.2032)
		(layers "F.Cu" "B.Cu")
		(net "PVCCIN_CPU0")
	)
	(via
		(at 360.160316 -277.522432)
		(size 0.4572)
		(drill 0.2032)
		(layers "F.Cu" "B.Cu")
		(net "PVCCIN_CPU0")
	)
	(via
		(at 350.413066 -319.866518)
		(size 0.508)
		(drill 0.254)
		(layers "F.Cu" "B.Cu")
		(net "PVCCIN_CPU0")
	)
	(via
		(at 358.750616 -266.941808)
		(size 0.4572)
		(drill 0.2032)
		(layers "F.Cu" "B.Cu")
		(net "PVCCIN_CPU0")
	)
	(via
		(at 361.099862 -275.8948)
		(size 0.4572)
		(drill 0.2032)
		(layers "F.Cu" "B.Cu")
		(net "PVCCIN_CPU0")
	)
	(via
		(at 362.039916 -254.733552)
		(size 0.4572)
		(drill 0.2032)
		(layers "F.Cu" "B.Cu")
		(net "PVCCIN_CPU0")
	)
	(via
		(at 354.438204 -321.865752)
		(size 0.508)
		(drill 0.254)
		(layers "F.Cu" "B.Cu")
		(net "PVCCIN_CPU0")
	)
	(via
		(at 362.399834 -243.922804)
		(size 0.4572)
		(drill 0.2032)
		(layers "F.Cu" "B.Cu")
		(net "PVCCIN_CPU0")
	)
	(via
		(at 357.878126 -337.22183)
		(size 0.508)
		(drill 0.254)
		(layers "F.Cu" "B.Cu")
		(net "PVCCIN_CPU0")
	)
	(via
		(at 374.384824 -340.631272)
		(size 0.508)
		(drill 0.254)
		(layers "F.Cu" "B.Cu")
		(net "PVCCIN_CPU0")
	)
	(via
		(at 355.936804 -242.981226)
		(size 0.4572)
		(drill 0.2032)
		(layers "F.Cu" "B.Cu")
		(net "PVCCIN_CPU0")
	)
	(via
		(at 384.502914 -328.346816)
		(size 0.508)
		(drill 0.254)
		(layers "F.Cu" "B.Cu")
		(net "PVCCIN_CPU0")
	)
	(via
		(at 383.867406 -326.998838)
		(size 0.508)
		(drill 0.254)
		(layers "F.Cu" "B.Cu")
		(net "PVCCIN_CPU0")
	)
	(via
		(at 359.690162 -275.08073)
		(size 0.4572)
		(drill 0.2032)
		(layers "F.Cu" "B.Cu")
		(net "PVCCIN_CPU0")
	)
	(via
		(at 366.787684 -321.901312)
		(size 0.508)
		(drill 0.254)
		(layers "F.Cu" "B.Cu")
		(net "PVCCIN_CPU0")
	)
	(via
		(at 342.244426 -319.851278)
		(size 0.508)
		(drill 0.254)
		(layers "F.Cu" "B.Cu")
		(net "PVCCIN_CPU0")
	)
	(via
		(at 382.668526 -326.630538)
		(size 0.508)
		(drill 0.254)
		(layers "F.Cu" "B.Cu")
		(net "PVCCIN_CPU0")
	)
	(via
		(at 334.052926 -323.821298)
		(size 0.508)
		(drill 0.254)
		(layers "F.Cu" "B.Cu")
		(net "PVCCIN_CPU0")
	)
	(via
		(at 338.205826 -320.554858)
		(size 0.508)
		(drill 0.254)
		(layers "F.Cu" "B.Cu")
		(net "PVCCIN_CPU0")
	)
	(via
		(at 361.726226 -292.955726)
		(size 0.508)
		(drill 0.254)
		(layers "F.Cu" "B.Cu")
		(net "PVCCIN_CPU0")
	)
	(via
		(at 358.750616 -286.475424)
		(size 0.4572)
		(drill 0.2032)
		(layers "F.Cu" "B.Cu")
		(net "PVCCIN_CPU0")
	)
	(via
		(at 360.050334 -239.853216)
		(size 0.4572)
		(drill 0.2032)
		(layers "F.Cu" "B.Cu")
		(net "PVCCIN_CPU0")
	)
	(via
		(at 375.638314 -321.852036)
		(size 0.508)
		(drill 0.254)
		(layers "F.Cu" "B.Cu")
		(net "PVCCIN_CPU0")
	)
	(via
		(at 361.929934 -244.73662)
		(size 0.4572)
		(drill 0.2032)
		(layers "F.Cu" "B.Cu")
		(net "PVCCIN_CPU0")
	)
	(via
		(at 363.294422 -319.867534)
		(size 0.508)
		(drill 0.254)
		(layers "F.Cu" "B.Cu")
		(net "PVCCIN_CPU0")
	)
	(via
		(at 360.160316 -256.361438)
		(size 0.4572)
		(drill 0.2032)
		(layers "F.Cu" "B.Cu")
		(net "PVCCIN_CPU0")
	)
	(via
		(at 360.51998 -243.922804)
		(size 0.4572)
		(drill 0.2032)
		(layers "F.Cu" "B.Cu")
		(net "PVCCIN_CPU0")
	)
	(via
		(at 363.150404 -238.743998)
		(size 0.4572)
		(drill 0.2032)
		(layers "F.Cu" "B.Cu")
		(net "PVCCIN_CPU0")
	)
	(via
		(at 358.750362 -278.336502)
		(size 0.4572)
		(drill 0.2032)
		(layers "F.Cu" "B.Cu")
		(net "PVCCIN_CPU0")
	)
	(via
		(at 339.410294 -324.524116)
		(size 0.508)
		(drill 0.254)
		(layers "F.Cu" "B.Cu")
		(net "PVCCIN_CPU0")
	)
	(via
		(at 365.108744 -257.685286)
		(size 0.4572)
		(drill 0.2032)
		(layers "F.Cu" "B.Cu")
		(net "PVCCIN_CPU0")
	)
	(via
		(at 359.220516 -288.993326)
		(size 0.4572)
		(drill 0.2032)
		(layers "F.Cu" "B.Cu")
		(net "PVCCIN_CPU0")
	)
	(via
		(at 362.399834 -248.806208)
		(size 0.4572)
		(drill 0.2032)
		(layers "F.Cu" "B.Cu")
		(net "PVCCIN_CPU0")
	)
	(via
		(at 354.671884 -246.659146)
		(size 0.4572)
		(drill 0.2032)
		(layers "F.Cu" "B.Cu")
		(net "PVCCIN_CPU0")
	)
	(via
		(at 355.736906 -319.858898)
		(size 0.508)
		(drill 0.254)
		(layers "F.Cu" "B.Cu")
		(net "PVCCIN_CPU0")
	)
	(via
		(at 353.581716 -288.917126)
		(size 0.4572)
		(drill 0.2032)
		(layers "F.Cu" "B.Cu")
		(net "PVCCIN_CPU0")
	)
	(via
		(at 334.055974 -324.508876)
		(size 0.508)
		(drill 0.254)
		(layers "F.Cu" "B.Cu")
		(net "PVCCIN_CPU0")
	)
	(via
		(at 351.684844 -321.888612)
		(size 0.508)
		(drill 0.254)
		(layers "F.Cu" "B.Cu")
		(net "PVCCIN_CPU0")
	)
	(via
		(at 360.520234 -239.0394)
		(size 0.4572)
		(drill 0.2032)
		(layers "F.Cu" "B.Cu")
		(net "PVCCIN_CPU0")
	)
	(via
		(at 359.220516 -275.8948)
		(size 0.4572)
		(drill 0.2032)
		(layers "F.Cu" "B.Cu")
		(net "PVCCIN_CPU0")
	)
	(via
		(at 355.078284 -319.867534)
		(size 0.508)
		(drill 0.254)
		(layers "F.Cu" "B.Cu")
		(net "PVCCIN_CPU0")
	)
	(via
		(at 361.099862 -259.616956)
		(size 0.4572)
		(drill 0.2032)
		(layers "F.Cu" "B.Cu")
		(net "PVCCIN_CPU0")
	)
	(via
		(at 359.690162 -286.475424)
		(size 0.4572)
		(drill 0.2032)
		(layers "F.Cu" "B.Cu")
		(net "PVCCIN_CPU0")
	)
	(via
		(at 358.750362 -265.314176)
		(size 0.4572)
		(drill 0.2032)
		(layers "F.Cu" "B.Cu")
		(net "PVCCIN_CPU0")
	)
	(via
		(at 356.620064 -239.834166)
		(size 0.4572)
		(drill 0.2032)
		(layers "F.Cu" "B.Cu")
		(net "PVCCIN_CPU0")
	)
	(via
		(at 343.516204 -321.873372)
		(size 0.508)
		(drill 0.254)
		(layers "F.Cu" "B.Cu")
		(net "PVCCIN_CPU0")
	)
	(via
		(at 367.456212 -319.888362)
		(size 0.508)
		(drill 0.254)
		(layers "F.Cu" "B.Cu")
		(net "PVCCIN_CPU0")
	)
	(via
		(at 366.738916 -287.28924)
		(size 0.4572)
		(drill 0.2032)
		(layers "F.Cu" "B.Cu")
		(net "PVCCIN_CPU0")
	)
	(via
		(at 358.750616 -255.547622)
		(size 0.4572)
		(drill 0.2032)
		(layers "F.Cu" "B.Cu")
		(net "PVCCIN_CPU0")
	)
	(via
		(at 338.759546 -324.46214)
		(size 0.508)
		(drill 0.254)
		(layers "F.Cu" "B.Cu")
		(net "PVCCIN_CPU0")
	)
	(via
		(at 359.690162 -266.941808)
		(size 0.4572)
		(drill 0.2032)
		(layers "F.Cu" "B.Cu")
		(net "PVCCIN_CPU0")
	)
	(via
		(at 376.265186 -323.632576)
		(size 0.508)
		(drill 0.254)
		(layers "F.Cu" "B.Cu")
		(net "PVCCIN_CPU0")
	)
	(via
		(at 364.389162 -281.59202)
		(size 0.4572)
		(drill 0.2032)
		(layers "F.Cu" "B.Cu")
		(net "PVCCIN_CPU0")
	)
	(via
		(at 368.093752 -319.880742)
		(size 0.508)
		(drill 0.254)
		(layers "F.Cu" "B.Cu")
		(net "PVCCIN_CPU0")
	)
	(via
		(at 360.629962 -263.686544)
		(size 0.4572)
		(drill 0.2032)
		(layers "F.Cu" "B.Cu")
		(net "PVCCIN_CPU0")
	)
	(via
		(at 357.340662 -287.28924)
		(size 0.4572)
		(drill 0.2032)
		(layers "F.Cu" "B.Cu")
		(net "PVCCIN_CPU0")
	)
	(via
		(at 360.629962 -258.80314)
		(size 0.4572)
		(drill 0.2032)
		(layers "F.Cu" "B.Cu")
		(net "PVCCIN_CPU0")
	)
	(via
		(at 367.453164 -319.251584)
		(size 0.508)
		(drill 0.254)
		(layers "F.Cu" "B.Cu")
		(net "PVCCIN_CPU0")
	)
	(via
		(at 360.629962 -279.964134)
		(size 0.4572)
		(drill 0.2032)
		(layers "F.Cu" "B.Cu")
		(net "PVCCIN_CPU0")
	)
	(via
		(at 354.674424 -254.009906)
		(size 0.4572)
		(drill 0.2032)
		(layers "F.Cu" "B.Cu")
		(net "PVCCIN_CPU0")
	)
	(via
		(at 346.905072 -319.232534)
		(size 0.508)
		(drill 0.254)
		(layers "F.Cu" "B.Cu")
		(net "PVCCIN_CPU0")
	)
	(via
		(at 362.039916 -288.993326)
		(size 0.4572)
		(drill 0.2032)
		(layers "F.Cu" "B.Cu")
		(net "PVCCIN_CPU0")
	)
	(via
		(at 362.656882 -320.510154)
		(size 0.508)
		(drill 0.254)
		(layers "F.Cu" "B.Cu")
		(net "PVCCIN_CPU0")
	)
	(via
		(at 361.099862 -261.244842)
		(size 0.4572)
		(drill 0.2032)
		(layers "F.Cu" "B.Cu")
		(net "PVCCIN_CPU0")
	)
	(via
		(at 359.690162 -265.314176)
		(size 0.4572)
		(drill 0.2032)
		(layers "F.Cu" "B.Cu")
		(net "PVCCIN_CPU0")
	)
	(via
		(at 329.988926 -329.048618)
		(size 0.508)
		(drill 0.254)
		(layers "F.Cu" "B.Cu")
		(net "PVCCIN_CPU0")
	)
	(via
		(at 360.98988 -243.108988)
		(size 0.4572)
		(drill 0.2032)
		(layers "F.Cu" "B.Cu")
		(net "PVCCIN_CPU0")
	)
	(via
		(at 356.870762 -284.847538)
		(size 0.4572)
		(drill 0.2032)
		(layers "F.Cu" "B.Cu")
		(net "PVCCIN_CPU0")
	)
	(via
		(at 362.979716 -285.661354)
		(size 0.4572)
		(drill 0.2032)
		(layers "F.Cu" "B.Cu")
		(net "PVCCIN_CPU0")
	)
	(via
		(at 360.98988 -241.481102)
		(size 0.4572)
		(drill 0.2032)
		(layers "F.Cu" "B.Cu")
		(net "PVCCIN_CPU0")
	)
	(via
		(at 359.220516 -287.28924)
		(size 0.4572)
		(drill 0.2032)
		(layers "F.Cu" "B.Cu")
		(net "PVCCIN_CPU0")
	)
	(via
		(at 356.620064 -262.535162)
		(size 0.4572)
		(drill 0.2032)
		(layers "F.Cu" "B.Cu")
		(net "PVCCIN_CPU0")
	)
	(via
		(at 360.160316 -285.661354)
		(size 0.4572)
		(drill 0.2032)
		(layers "F.Cu" "B.Cu")
		(net "PVCCIN_CPU0")
	)
	(via
		(at 374.990106 -321.827398)
		(size 0.508)
		(drill 0.254)
		(layers "F.Cu" "B.Cu")
		(net "PVCCIN_CPU0")
	)
	(via
		(at 367.456212 -320.523362)
		(size 0.508)
		(drill 0.254)
		(layers "F.Cu" "B.Cu")
		(net "PVCCIN_CPU0")
	)
	(via
		(at 352.101404 -254.020066)
		(size 0.4572)
		(drill 0.2032)
		(layers "F.Cu" "B.Cu")
		(net "PVCCIN_CPU0")
	)
	(via
		(at 365.799116 -288.917126)
		(size 0.4572)
		(drill 0.2032)
		(layers "F.Cu" "B.Cu")
		(net "PVCCIN_CPU0")
	)
	(via
		(at 356.620064 -250.29414)
		(size 0.4572)
		(drill 0.2032)
		(layers "F.Cu" "B.Cu")
		(net "PVCCIN_CPU0")
	)
	(via
		(at 367.04143 -254.020066)
		(size 0.4572)
		(drill 0.2032)
		(layers "F.Cu" "B.Cu")
		(net "PVCCIN_CPU0")
	)
	(via
		(at 338.756498 -323.190362)
		(size 0.508)
		(drill 0.254)
		(layers "F.Cu" "B.Cu")
		(net "PVCCIN_CPU0")
	)
	(via
		(at 330.626466 -329.675998)
		(size 0.508)
		(drill 0.254)
		(layers "F.Cu" "B.Cu")
		(net "PVCCIN_CPU0")
	)
	(via
		(at 367.62563 -257.692906)
		(size 0.4572)
		(drill 0.2032)
		(layers "F.Cu" "B.Cu")
		(net "PVCCIN_CPU0")
	)
	(via
		(at 363.449362 -284.847538)
		(size 0.4572)
		(drill 0.2032)
		(layers "F.Cu" "B.Cu")
		(net "PVCCIN_CPU0")
	)
	(via
		(at 361.929934 -246.364506)
		(size 0.4572)
		(drill 0.2032)
		(layers "F.Cu" "B.Cu")
		(net "PVCCIN_CPU0")
	)
	(via
		(at 383.185162 -289.807142)
		(size 0.4572)
		(drill 0.2032)
		(layers "F.Cu" "B.Cu")
		(net "PVCCIN_CPU0")
	)
	(via
		(at 358.612694 -321.199256)
		(size 0.508)
		(drill 0.254)
		(layers "F.Cu" "B.Cu")
		(net "PVCCIN_CPU0")
	)
	(via
		(at 338.753704 -325.175372)
		(size 0.508)
		(drill 0.254)
		(layers "F.Cu" "B.Cu")
		(net "PVCCIN_CPU0")
	)
	(via
		(at 360.160316 -282.405836)
		(size 0.4572)
		(drill 0.2032)
		(layers "F.Cu" "B.Cu")
		(net "PVCCIN_CPU0")
	)
	(via
		(at 375.630186 -322.939918)
		(size 0.508)
		(drill 0.254)
		(layers "F.Cu" "B.Cu")
		(net "PVCCIN_CPU0")
	)
	(via
		(at 361.099862 -287.28924)
		(size 0.4572)
		(drill 0.2032)
		(layers "F.Cu" "B.Cu")
		(net "PVCCIN_CPU0")
	)
	(via
		(at 355.075744 -321.858132)
		(size 0.508)
		(drill 0.254)
		(layers "F.Cu" "B.Cu")
		(net "PVCCIN_CPU0")
	)
	(via
		(at 376.265186 -322.947538)
		(size 0.508)
		(drill 0.254)
		(layers "F.Cu" "B.Cu")
		(net "PVCCIN_CPU0")
	)
	(via
		(at 360.160316 -257.98907)
		(size 0.4572)
		(drill 0.2032)
		(layers "F.Cu" "B.Cu")
		(net "PVCCIN_CPU0")
	)
	(via
		(at 379.638814 -325.133716)
		(size 0.508)
		(drill 0.254)
		(layers "F.Cu" "B.Cu")
		(net "PVCCIN_CPU0")
	)
	(via
		(at 356.620064 -261.950962)
		(size 0.4572)
		(drill 0.2032)
		(layers "F.Cu" "B.Cu")
		(net "PVCCIN_CPU0")
	)
	(via
		(at 360.629962 -262.058658)
		(size 0.4572)
		(drill 0.2032)
		(layers "F.Cu" "B.Cu")
		(net "PVCCIN_CPU0")
	)
	(via
		(at 363.919262 -287.28924)
		(size 0.4572)
		(drill 0.2032)
		(layers "F.Cu" "B.Cu")
		(net "PVCCIN_CPU0")
	)
	(via
		(at 363.956346 -319.851278)
		(size 0.508)
		(drill 0.254)
		(layers "F.Cu" "B.Cu")
		(net "PVCCIN_CPU0")
	)
	(via
		(at 372.096284 -321.880992)
		(size 0.508)
		(drill 0.254)
		(layers "F.Cu" "B.Cu")
		(net "PVCCIN_CPU0")
	)
	(via
		(at 329.328526 -329.048618)
		(size 0.508)
		(drill 0.254)
		(layers "F.Cu" "B.Cu")
		(net "PVCCIN_CPU0")
	)
	(via
		(at 359.220516 -282.405836)
		(size 0.4572)
		(drill 0.2032)
		(layers "F.Cu" "B.Cu")
		(net "PVCCIN_CPU0")
	)
	(via
		(at 367.67643 -242.981226)
		(size 0.4572)
		(drill 0.2032)
		(layers "F.Cu" "B.Cu")
		(net "PVCCIN_CPU0")
	)
	(via
		(at 354.991162 -288.103056)
		(size 0.4572)
		(drill 0.2032)
		(layers "F.Cu" "B.Cu")
		(net "PVCCIN_CPU0")
	)
	(via
		(at 350.400874 -321.214496)
		(size 0.508)
		(drill 0.254)
		(layers "F.Cu" "B.Cu")
		(net "PVCCIN_CPU0")
	)
	(via
		(at 356.620064 -260.782562)
		(size 0.4572)
		(drill 0.2032)
		(layers "F.Cu" "B.Cu")
		(net "PVCCIN_CPU0")
	)
	(via
		(at 359.690162 -281.59202)
		(size 0.4572)
		(drill 0.2032)
		(layers "F.Cu" "B.Cu")
		(net "PVCCIN_CPU0")
	)
	(segment
		(start 357.928164 -337.845146)
		(end 357.928164 -337.860386)
		(width 0.254)
		(layer "B.Cu")
		(net "PVCCIN_CPU0")
	)
	(segment
		(start 370.295932 -314.727082)
		(end 371.23624 -315.66739)
		(width 0.508)
		(layer "B.Cu")
		(net "PVCCIN_CPU0")
	)
	(segment
		(start 352.663252 -315.66739)
		(end 353.60356 -316.607698)
		(width 0.508)
		(layer "B.Cu")
		(net "PVCCIN_CPU0")
	)
	(segment
		(start 366.098328 -337.823302)
		(end 366.050322 -337.871308)
		(width 0.254)
		(layer "B.Cu")
		(net "PVCCIN_CPU0")
	)
	(segment
		(start 358.84104 -315.66739)
		(end 359.781348 -316.607698)
		(width 0.508)
		(layer "B.Cu")
		(net "PVCCIN_CPU0")
	)
	(segment
		(start 371.23624 -315.66739)
		(end 372.176548 -314.727082)
		(width 0.508)
		(layer "B.Cu")
		(net "PVCCIN_CPU0")
	)
	(segment
		(start 366.098328 -337.259422)
		(end 366.098328 -337.823302)
		(width 0.254)
		(layer "B.Cu")
		(net "PVCCIN_CPU0")
	)
	(segment
		(start 351.722944 -316.607698)
		(end 352.663252 -315.66739)
		(width 0.508)
		(layer "B.Cu")
		(net "PVCCIN_CPU0")
	)
	(segment
		(start 374.384824 -340.631272)
		(end 374.189498 -340.435946)
		(width 0.254)
		(layer "B.Cu")
		(net "PVCCIN_CPU0")
	)
	(segment
		(start 371.23624 -315.66739)
		(end 372.176548 -316.607698)
		(width 0.508)
		(layer "B.Cu")
		(net "PVCCIN_CPU0")
	)
	(segment
		(start 351.722944 -314.727082)
		(end 352.663252 -315.66739)
		(width 0.508)
		(layer "B.Cu")
		(net "PVCCIN_CPU0")
	)
	(segment
		(start 333.4131 -340.467442)
		(end 333.32928 -340.383622)
		(width 0.254)
		(layer "B.Cu")
		(net "PVCCIN_CPU0")
	)
	(segment
		(start 382.28778 -346.382848)
		(end 382.28778 -345.863164)
		(width 0.254)
		(layer "B.Cu")
		(net "PVCCIN_CPU0")
	)
	(segment
		(start 346.465652 -315.66739)
		(end 347.40596 -314.727082)
		(width 0.508)
		(layer "B.Cu")
		(net "PVCCIN_CPU0")
	)
	(segment
		(start 352.663252 -315.66739)
		(end 353.60356 -314.727082)
		(width 0.508)
		(layer "B.Cu")
		(net "PVCCIN_CPU0")
	)
	(segment
		(start 374.189498 -340.435946)
		(end 374.189498 -340.18728)
		(width 0.254)
		(layer "B.Cu")
		(net "PVCCIN_CPU0")
	)
	(segment
		(start 325.168768 -346.174314)
		(end 324.330314 -346.174314)
		(width 0.381)
		(layer "B.Cu")
		(net "PVCCIN_CPU0")
	)
	(segment
		(start 346.465652 -315.66739)
		(end 347.40596 -316.607698)
		(width 0.508)
		(layer "B.Cu")
		(net "PVCCIN_CPU0")
	)
	(segment
		(start 349.812356 -337.223862)
		(end 349.812356 -337.800188)
		(width 0.254)
		(layer "B.Cu")
		(net "PVCCIN_CPU0")
	)
	(segment
		(start 374.189498 -340.18728)
		(end 374.00484 -340.002622)
		(width 0.254)
		(layer "B.Cu")
		(net "PVCCIN_CPU0")
	)
	(segment
		(start 324.35292 -331.226668)
		(end 325.066152 -331.226668)
		(width 0.381)
		(layer "B.Cu")
		(net "PVCCIN_CPU0")
	)
	(segment
		(start 358.84104 -315.66739)
		(end 359.781348 -314.727082)
		(width 0.508)
		(layer "B.Cu")
		(net "PVCCIN_CPU0")
	)
	(segment
		(start 364.098332 -314.727082)
		(end 365.03864 -315.66739)
		(width 0.508)
		(layer "B.Cu")
		(net "PVCCIN_CPU0")
	)
	(segment
		(start 341.511128 -336.678524)
		(end 341.511128 -337.352894)
		(width 0.254)
		(layer "B.Cu")
		(net "PVCCIN_CPU0")
	)
	(segment
		(start 364.098332 -316.607698)
		(end 365.03864 -315.66739)
		(width 0.508)
		(layer "B.Cu")
		(net "PVCCIN_CPU0")
	)
	(segment
		(start 370.295932 -316.607698)
		(end 371.23624 -315.66739)
		(width 0.508)
		(layer "B.Cu")
		(net "PVCCIN_CPU0")
	)
	(segment
		(start 357.900732 -314.727082)
		(end 358.84104 -315.66739)
		(width 0.508)
		(layer "B.Cu")
		(net "PVCCIN_CPU0")
	)
	(segment
		(start 365.03864 -315.66739)
		(end 365.978948 -314.727082)
		(width 0.508)
		(layer "B.Cu")
		(net "PVCCIN_CPU0")
	)
	(segment
		(start 357.900732 -316.607698)
		(end 358.84104 -315.66739)
		(width 0.508)
		(layer "B.Cu")
		(net "PVCCIN_CPU0")
	)
	(segment
		(start 357.878126 -337.795108)
		(end 357.928164 -337.845146)
		(width 0.254)
		(layer "B.Cu")
		(net "PVCCIN_CPU0")
	)
	(segment
		(start 382.41478 -346.509848)
		(end 382.28778 -346.382848)
		(width 0.254)
		(layer "B.Cu")
		(net "PVCCIN_CPU0")
	)
	(segment
		(start 333.4131 -341.013288)
		(end 333.4131 -340.467442)
		(width 0.254)
		(layer "B.Cu")
		(net "PVCCIN_CPU0")
	)
	(segment
		(start 365.03864 -315.66739)
		(end 365.978948 -316.607698)
		(width 0.508)
		(layer "B.Cu")
		(net "PVCCIN_CPU0")
	)
	(segment
		(start 345.525344 -316.607698)
		(end 346.465652 -315.66739)
		(width 0.508)
		(layer "B.Cu")
		(net "PVCCIN_CPU0")
	)
	(segment
		(start 349.812356 -337.800188)
		(end 349.758762 -337.853782)
		(width 0.254)
		(layer "B.Cu")
		(net "PVCCIN_CPU0")
	)
	(segment
		(start 345.525344 -314.727082)
		(end 346.465652 -315.66739)
		(width 0.508)
		(layer "B.Cu")
		(net "PVCCIN_CPU0")
	)
	(segment
		(start 366.050322 -337.871308)
		(end 366.050322 -337.899248)
		(width 0.254)
		(layer "B.Cu")
		(net "PVCCIN_CPU0")
	)
	(segment
		(start 357.878126 -337.22183)
		(end 357.878126 -337.795108)
		(width 0.254)
		(layer "B.Cu")
		(net "PVCCIN_CPU0")
	)
	(segment
		(start 358.510078 -333.46771)
		(end 358.510078 -328.777092)
		(width 0.381)
		(layer "In2.Cu")
		(net "PVCCIN_CPU0")
	)
	(segment
		(start 374.977914 -328.797666)
		(end 374.977914 -324.638416)
		(width 0.381)
		(layer "In2.Cu")
		(net "PVCCIN_CPU0")
	)
	(segment
		(start 342.383618 -334.22971)
		(end 342.230964 -334.077056)
		(width 0.381)
		(layer "In2.Cu")
		(net "PVCCIN_CPU0")
	)
	(segment
		(start 374.336056 -340.631272)
		(end 374.148604 -340.44382)
		(width 0.381)
		(layer "In2.Cu")
		(net "PVCCIN_CPU0")
	)
	(segment
		(start 366.848898 -333.75981)
		(end 366.635538 -333.54645)
		(width 0.381)
		(layer "In2.Cu")
		(net "PVCCIN_CPU0")
	)
	(segment
		(start 366.452658 -322.236338)
		(end 366.787684 -321.901312)
		(width 0.381)
		(layer "In2.Cu")
		(net "PVCCIN_CPU0")
	)
	(segment
		(start 375.230898 -330.98613)
		(end 375.230898 -329.05065)
		(width 0.381)
		(layer "In2.Cu")
		(net "PVCCIN_CPU0")
	)
	(segment
		(start 374.384824 -340.631272)
		(end 374.336056 -340.631272)
		(width 0.381)
		(layer "In2.Cu")
		(net "PVCCIN_CPU0")
	)
	(segment
		(start 349.812356 -337.223862)
		(end 349.61576 -337.027266)
		(width 0.381)
		(layer "In2.Cu")
		(net "PVCCIN_CPU0")
	)
	(segment
		(start 374.148604 -339.795358)
		(end 375.180098 -338.763864)
		(width 0.381)
		(layer "In2.Cu")
		(net "PVCCIN_CPU0")
	)
	(segment
		(start 381.92456 -346.146628)
		(end 381.92456 -345.51239)
		(width 0.381)
		(layer "In2.Cu")
		(net "PVCCIN_CPU0")
	)
	(segment
		(start 334.18145 -330.760578)
		(end 333.673958 -330.253086)
		(width 0.381)
		(layer "In2.Cu")
		(net "PVCCIN_CPU0")
	)
	(segment
		(start 366.848898 -335.566512)
		(end 366.848898 -333.75981)
		(width 0.381)
		(layer "In2.Cu")
		(net "PVCCIN_CPU0")
	)
	(segment
		(start 342.230964 -334.077056)
		(end 342.230964 -321.865752)
		(width 0.381)
		(layer "In2.Cu")
		(net "PVCCIN_CPU0")
	)
	(segment
		(start 349.61576 -336.33283)
		(end 350.582738 -335.365852)
		(width 0.381)
		(layer "In2.Cu")
		(net "PVCCIN_CPU0")
	)
	(segment
		(start 366.635538 -333.54645)
		(end 366.635538 -327.595992)
		(width 0.381)
		(layer "In2.Cu")
		(net "PVCCIN_CPU0")
	)
	(segment
		(start 341.244682 -336.53476)
		(end 342.383618 -335.395824)
		(width 0.381)
		(layer "In2.Cu")
		(net "PVCCIN_CPU0")
	)
	(segment
		(start 366.635538 -327.595992)
		(end 366.452658 -327.413112)
		(width 0.381)
		(layer "In2.Cu")
		(net "PVCCIN_CPU0")
	)
	(segment
		(start 374.844818 -331.37221)
		(end 375.230898 -330.98613)
		(width 0.381)
		(layer "In2.Cu")
		(net "PVCCIN_CPU0")
	)
	(segment
		(start 365.974884 -337.135978)
		(end 365.974884 -336.440526)
		(width 0.381)
		(layer "In2.Cu")
		(net "PVCCIN_CPU0")
	)
	(segment
		(start 358.510078 -328.777092)
		(end 357.001064 -327.268078)
		(width 0.381)
		(layer "In2.Cu")
		(net "PVCCIN_CPU0")
	)
	(segment
		(start 383.346198 -344.090752)
		(end 383.346198 -342.63965)
		(width 0.381)
		(layer "In2.Cu")
		(net "PVCCIN_CPU0")
	)
	(segment
		(start 341.244682 -337.069176)
		(end 341.244682 -336.53476)
		(width 0.381)
		(layer "In2.Cu")
		(net "PVCCIN_CPU0")
	)
	(segment
		(start 366.098328 -337.259422)
		(end 365.974884 -337.135978)
		(width 0.381)
		(layer "In2.Cu")
		(net "PVCCIN_CPU0")
	)
	(segment
		(start 350.399604 -333.53375)
		(end 350.399604 -321.880992)
		(width 0.381)
		(layer "In2.Cu")
		(net "PVCCIN_CPU0")
	)
	(segment
		(start 375.180098 -337.01355)
		(end 374.844818 -336.67827)
		(width 0.381)
		(layer "In2.Cu")
		(net "PVCCIN_CPU0")
	)
	(segment
		(start 350.582738 -333.716884)
		(end 350.399604 -333.53375)
		(width 0.381)
		(layer "In2.Cu")
		(net "PVCCIN_CPU0")
	)
	(segment
		(start 358.688386 -335.429352)
		(end 358.688386 -333.646018)
		(width 0.381)
		(layer "In2.Cu")
		(net "PVCCIN_CPU0")
	)
	(segment
		(start 382.433068 -329.682602)
		(end 382.674114 -329.441556)
		(width 0.381)
		(layer "In2.Cu")
		(net "PVCCIN_CPU0")
	)
	(segment
		(start 374.844818 -336.67827)
		(end 374.844818 -331.37221)
		(width 0.381)
		(layer "In2.Cu")
		(net "PVCCIN_CPU0")
	)
	(segment
		(start 365.974884 -336.440526)
		(end 366.848898 -335.566512)
		(width 0.381)
		(layer "In2.Cu")
		(net "PVCCIN_CPU0")
	)
	(segment
		(start 357.827326 -336.290412)
		(end 358.688386 -335.429352)
		(width 0.381)
		(layer "In2.Cu")
		(net "PVCCIN_CPU0")
	)
	(segment
		(start 334.18145 -338.759546)
		(end 334.18145 -330.760578)
		(width 0.381)
		(layer "In2.Cu")
		(net "PVCCIN_CPU0")
	)
	(segment
		(start 357.001064 -327.268078)
		(end 357.001064 -323.150992)
		(width 0.381)
		(layer "In2.Cu")
		(net "PVCCIN_CPU0")
	)
	(segment
		(start 383.043938 -336.320384)
		(end 382.433068 -335.709514)
		(width 0.381)
		(layer "In2.Cu")
		(net "PVCCIN_CPU0")
	)
	(segment
		(start 341.511128 -337.352894)
		(end 341.511128 -337.335622)
		(width 0.381)
		(layer "In2.Cu")
		(net "PVCCIN_CPU0")
	)
	(segment
		(start 383.043938 -342.33739)
		(end 383.043938 -336.320384)
		(width 0.381)
		(layer "In2.Cu")
		(net "PVCCIN_CPU0")
	)
	(segment
		(start 333.4131 -341.013288)
		(end 332.997556 -340.597744)
		(width 0.381)
		(layer "In2.Cu")
		(net "PVCCIN_CPU0")
	)
	(segment
		(start 375.180098 -338.763864)
		(end 375.180098 -337.01355)
		(width 0.381)
		(layer "In2.Cu")
		(net "PVCCIN_CPU0")
	)
	(segment
		(start 375.230898 -329.05065)
		(end 374.977914 -328.797666)
		(width 0.381)
		(layer "In2.Cu")
		(net "PVCCIN_CPU0")
	)
	(segment
		(start 341.511128 -337.335622)
		(end 341.244682 -337.069176)
		(width 0.381)
		(layer "In2.Cu")
		(net "PVCCIN_CPU0")
	)
	(segment
		(start 333.673958 -330.253086)
		(end 333.673958 -325.556118)
		(width 0.381)
		(layer "In2.Cu")
		(net "PVCCIN_CPU0")
	)
	(segment
		(start 358.688386 -333.646018)
		(end 358.510078 -333.46771)
		(width 0.381)
		(layer "In2.Cu")
		(net "PVCCIN_CPU0")
	)
	(segment
		(start 357.878126 -337.22183)
		(end 357.827326 -337.17103)
		(width 0.381)
		(layer "In2.Cu")
		(net "PVCCIN_CPU0")
	)
	(segment
		(start 383.346198 -342.63965)
		(end 383.043938 -342.33739)
		(width 0.381)
		(layer "In2.Cu")
		(net "PVCCIN_CPU0")
	)
	(segment
		(start 349.61576 -337.027266)
		(end 349.61576 -336.33283)
		(width 0.381)
		(layer "In2.Cu")
		(net "PVCCIN_CPU0")
	)
	(segment
		(start 357.827326 -337.17103)
		(end 357.827326 -336.290412)
		(width 0.381)
		(layer "In2.Cu")
		(net "PVCCIN_CPU0")
	)
	(segment
		(start 382.433068 -335.709514)
		(end 382.433068 -329.682602)
		(width 0.381)
		(layer "In2.Cu")
		(net "PVCCIN_CPU0")
	)
	(segment
		(start 366.452658 -327.413112)
		(end 366.452658 -322.236338)
		(width 0.381)
		(layer "In2.Cu")
		(net "PVCCIN_CPU0")
	)
	(segment
		(start 357.001064 -323.150992)
		(end 355.723444 -321.873372)
		(width 0.381)
		(layer "In2.Cu")
		(net "PVCCIN_CPU0")
	)
	(segment
		(start 374.148604 -340.44382)
		(end 374.148604 -339.795358)
		(width 0.381)
		(layer "In2.Cu")
		(net "PVCCIN_CPU0")
	)
	(segment
		(start 382.41478 -346.509848)
		(end 382.28778 -346.509848)
		(width 0.381)
		(layer "In2.Cu")
		(net "PVCCIN_CPU0")
	)
	(segment
		(start 332.997556 -339.94344)
		(end 334.18145 -338.759546)
		(width 0.381)
		(layer "In2.Cu")
		(net "PVCCIN_CPU0")
	)
	(segment
		(start 333.673958 -325.556118)
		(end 334.054704 -325.175372)
		(width 0.381)
		(layer "In2.Cu")
		(net "PVCCIN_CPU0")
	)
	(segment
		(start 350.582738 -335.365852)
		(end 350.582738 -333.716884)
		(width 0.381)
		(layer "In2.Cu")
		(net "PVCCIN_CPU0")
	)
	(segment
		(start 342.383618 -335.395824)
		(end 342.383618 -334.22971)
		(width 0.381)
		(layer "In2.Cu")
		(net "PVCCIN_CPU0")
	)
	(segment
		(start 332.997556 -340.597744)
		(end 332.997556 -339.94344)
		(width 0.381)
		(layer "In2.Cu")
		(net "PVCCIN_CPU0")
	)
	(segment
		(start 381.92456 -345.51239)
		(end 383.346198 -344.090752)
		(width 0.381)
		(layer "In2.Cu")
		(net "PVCCIN_CPU0")
	)
	(segment
		(start 382.28778 -346.509848)
		(end 381.92456 -346.146628)
		(width 0.381)
		(layer "In2.Cu")
		(net "PVCCIN_CPU0")
	)
	(segment
		(start 352.663252 -315.66739)
		(end 353.379024 -314.951618)
		(width 0.508)
		(layer "In4.Cu")
		(net "PVCCIN_CPU0")
	)
	(segment
		(start 345.74988 -314.951618)
		(end 346.465652 -315.66739)
		(width 0.508)
		(layer "In4.Cu")
		(net "PVCCIN_CPU0")
	)
	(segment
		(start 365.03864 -315.66739)
		(end 365.754412 -316.383162)
		(width 0.508)
		(layer "In4.Cu")
		(net "PVCCIN_CPU0")
	)
	(segment
		(start 358.125268 -314.951618)
		(end 358.84104 -315.66739)
		(width 0.508)
		(layer "In4.Cu")
		(net "PVCCIN_CPU0")
	)
	(segment
		(start 371.23624 -315.66739)
		(end 371.952012 -316.383162)
		(width 0.508)
		(layer "In4.Cu")
		(net "PVCCIN_CPU0")
	)
	(segment
		(start 346.465652 -315.66739)
		(end 347.181424 -316.383162)
		(width 0.508)
		(layer "In4.Cu")
		(net "PVCCIN_CPU0")
	)
	(segment
		(start 352.663252 -315.66739)
		(end 353.379024 -316.383162)
		(width 0.508)
		(layer "In4.Cu")
		(net "PVCCIN_CPU0")
	)
	(segment
		(start 346.465652 -315.66739)
		(end 347.181424 -314.951618)
		(width 0.508)
		(layer "In4.Cu")
		(net "PVCCIN_CPU0")
	)
	(segment
		(start 358.84104 -315.66739)
		(end 359.556812 -316.383162)
		(width 0.508)
		(layer "In4.Cu")
		(net "PVCCIN_CPU0")
	)
	(segment
		(start 345.74988 -316.383162)
		(end 346.465652 -315.66739)
		(width 0.508)
		(layer "In4.Cu")
		(net "PVCCIN_CPU0")
	)
	(segment
		(start 371.23624 -315.66739)
		(end 371.952012 -314.951618)
		(width 0.508)
		(layer "In4.Cu")
		(net "PVCCIN_CPU0")
	)
	(segment
		(start 364.322868 -316.383162)
		(end 365.03864 -315.66739)
		(width 0.508)
		(layer "In4.Cu")
		(net "PVCCIN_CPU0")
	)
	(segment
		(start 370.520468 -316.383162)
		(end 371.23624 -315.66739)
		(width 0.508)
		(layer "In4.Cu")
		(net "PVCCIN_CPU0")
	)
	(segment
		(start 370.520468 -314.951618)
		(end 371.23624 -315.66739)
		(width 0.508)
		(layer "In4.Cu")
		(net "PVCCIN_CPU0")
	)
	(segment
		(start 351.94748 -316.383162)
		(end 352.663252 -315.66739)
		(width 0.508)
		(layer "In4.Cu")
		(net "PVCCIN_CPU0")
	)
	(segment
		(start 358.125268 -316.383162)
		(end 358.84104 -315.66739)
		(width 0.508)
		(layer "In4.Cu")
		(net "PVCCIN_CPU0")
	)
	(segment
		(start 364.322868 -314.951618)
		(end 365.03864 -315.66739)
		(width 0.508)
		(layer "In4.Cu")
		(net "PVCCIN_CPU0")
	)
	(segment
		(start 358.84104 -315.66739)
		(end 359.556812 -314.951618)
		(width 0.508)
		(layer "In4.Cu")
		(net "PVCCIN_CPU0")
	)
	(segment
		(start 365.03864 -315.66739)
		(end 365.754412 -314.951618)
		(width 0.508)
		(layer "In4.Cu")
		(net "PVCCIN_CPU0")
	)
	(segment
		(start 351.94748 -314.951618)
		(end 352.663252 -315.66739)
		(width 0.508)
		(layer "In4.Cu")
		(net "PVCCIN_CPU0")
	)
	(segment
		(start 322.33108 -338.036916)
		(end 322.33108 -345.328748)
		(width 0.381)
		(layer "In11.Cu")
		(net "PVCCIN_CPU0")
	)
	(segment
		(start 329.330304 -331.037692)
		(end 322.33108 -338.036916)
		(width 0.381)
		(layer "In11.Cu")
		(net "PVCCIN_CPU0")
	)
	(segment
		(start 323.176646 -346.174314)
		(end 324.330314 -346.174314)
		(width 0.381)
		(layer "In11.Cu")
		(net "PVCCIN_CPU0")
	)
	(segment
		(start 322.33108 -345.328748)
		(end 323.176646 -346.174314)
		(width 0.381)
		(layer "In11.Cu")
		(net "PVCCIN_CPU0")
	)
	(segment
		(start 28.0924 -131.55295)
		(end 28.094178 -131.554728)
		(width 0.254)
		(layer "F.Cu")
		(net "PVCCINFAON_CPU1_VR_FAULT")
	)
	(segment
		(start 28.594812 -131.329176)
		(end 29.290518 -130.63347)
		(width 0.1778)
		(layer "F.Cu")
		(net "PVCCINFAON_CPU1_VR_FAULT")
	)
	(segment
		(start 28.36926 -131.554728)
		(end 28.594812 -131.329176)
		(width 0.1778)
		(layer "F.Cu")
		(net "PVCCINFAON_CPU1_VR_FAULT")
	)
	(segment
		(start 29.290518 -130.63347)
		(end 29.661104 -130.63347)
		(width 0.1778)
		(layer "F.Cu")
		(net "PVCCINFAON_CPU1_VR_FAULT")
	)
	(segment
		(start 27.43835 -131.55295)
		(end 28.0924 -131.55295)
		(width 0.254)
		(layer "F.Cu")
		(net "PVCCINFAON_CPU1_VR_FAULT")
	)
	(segment
		(start 28.094178 -131.554728)
		(end 28.36926 -131.554728)
		(width 0.1778)
		(layer "F.Cu")
		(net "PVCCINFAON_CPU1_VR_FAULT")
	)
	(via
		(at 28.594812 -131.329176)
		(size 0.4064)
		(drill 0.2032)
		(layers "F.Cu" "B.Cu")
		(net "PVCCINFAON_CPU1_VR_FAULT")
	)
	(segment
		(start 49.894998 -173.380908)
		(end 50.765964 -173.380908)
		(width 0.254)
		(layer "F.Cu")
		(net "PVCCINFAON_CPU1_VREF")
	)
	(segment
		(start 50.717704 -154.160474)
		(end 50.717704 -153.644854)
		(width 0.254)
		(layer "F.Cu")
		(net "PVCCINFAON_CPU1_VREF")
	)
	(segment
		(start 50.377344 -154.500834)
		(end 50.717704 -154.160474)
		(width 0.254)
		(layer "F.Cu")
		(net "PVCCINFAON_CPU1_VREF")
	)
	(segment
		(start 51.895756 -154.48788)
		(end 51.05273 -153.644854)
		(width 0.254)
		(layer "F.Cu")
		(net "PVCCINFAON_CPU1_VREF")
	)
	(segment
		(start 51.999642 -145.85188)
		(end 51.895756 -145.85188)
		(width 0.254)
		(layer "F.Cu")
		(net "PVCCINFAON_CPU1_VREF")
	)
	(segment
		(start 49.106328 -172.26153)
		(end 49.106328 -172.362622)
		(width 0.254)
		(layer "F.Cu")
		(net "PVCCINFAON_CPU1_VREF")
	)
	(segment
		(start 51.895756 -145.85188)
		(end 51.05273 -145.008854)
		(width 0.254)
		(layer "F.Cu")
		(net "PVCCINFAON_CPU1_VREF")
	)
	(segment
		(start 51.05273 -153.644854)
		(end 50.717704 -153.644854)
		(width 0.254)
		(layer "F.Cu")
		(net "PVCCINFAON_CPU1_VREF")
	)
	(segment
		(start 49.562004 -173.047914)
		(end 49.894998 -173.380908)
		(width 0.254)
		(layer "F.Cu")
		(net "PVCCINFAON_CPU1_VREF")
	)
	(segment
		(start 49.106328 -172.362622)
		(end 49.562004 -172.818298)
		(width 0.254)
		(layer "F.Cu")
		(net "PVCCINFAON_CPU1_VREF")
	)
	(segment
		(start 51.999642 -154.48788)
		(end 51.895756 -154.48788)
		(width 0.254)
		(layer "F.Cu")
		(net "PVCCINFAON_CPU1_VREF")
	)
	(segment
		(start 51.05273 -145.008854)
		(end 50.717704 -145.008854)
		(width 0.254)
		(layer "F.Cu")
		(net "PVCCINFAON_CPU1_VREF")
	)
	(segment
		(start 50.377344 -145.864834)
		(end 50.717704 -145.524474)
		(width 0.254)
		(layer "F.Cu")
		(net "PVCCINFAON_CPU1_VREF")
	)
	(segment
		(start 49.562004 -172.818298)
		(end 49.562004 -173.047914)
		(width 0.254)
		(layer "F.Cu")
		(net "PVCCINFAON_CPU1_VREF")
	)
	(segment
		(start 50.717704 -145.524474)
		(end 50.717704 -145.008854)
		(width 0.254)
		(layer "F.Cu")
		(net "PVCCINFAON_CPU1_VREF")
	)
	(via
		(at 49.106328 -172.26153)
		(size 0.508)
		(drill 0.254)
		(layers "F.Cu" "B.Cu")
		(net "PVCCINFAON_CPU1_VREF")
	)
	(via
		(at 50.377344 -145.864834)
		(size 0.508)
		(drill 0.254)
		(layers "F.Cu" "B.Cu")
		(net "PVCCINFAON_CPU1_VREF")
	)
	(via
		(at 50.377344 -154.500834)
		(size 0.508)
		(drill 0.254)
		(layers "F.Cu" "B.Cu")
		(net "PVCCINFAON_CPU1_VREF")
	)
	(via
		(at 29.568394 -126.417578)
		(size 0.508)
		(drill 0.254)
		(layers "F.Cu" "B.Cu")
		(net "PVCCINFAON_CPU1_VREF")
	)
	(via
		(at 26.819098 -132.264658)
		(size 0.508)
		(drill 0.254)
		(layers "F.Cu" "B.Cu")
		(net "PVCCINFAON_CPU1_VREF")
	)
	(segment
		(start 26.819098 -132.264658)
		(end 26.63825 -132.08381)
		(width 0.254)
		(layer "B.Cu")
		(net "PVCCINFAON_CPU1_VREF")
	)
	(segment
		(start 26.63825 -132.08381)
		(end 26.63825 -131.55295)
		(width 0.254)
		(layer "B.Cu")
		(net "PVCCINFAON_CPU1_VREF")
	)
	(segment
		(start 37.978334 -150.733506)
		(end 46.17466 -158.929832)
		(width 0.254)
		(layer "In4.Cu")
		(net "PVCCINFAON_CPU1_VREF")
	)
	(segment
		(start 46.17466 -158.929832)
		(end 46.17466 -170.249596)
		(width 0.254)
		(layer "In4.Cu")
		(net "PVCCINFAON_CPU1_VREF")
	)
	(segment
		(start 32.204152 -134.35965)
		(end 34.557208 -134.35965)
		(width 0.254)
		(layer "In4.Cu")
		(net "PVCCINFAON_CPU1_VREF")
	)
	(segment
		(start 46.17466 -170.249596)
		(end 46.933612 -171.008548)
		(width 0.254)
		(layer "In4.Cu")
		(net "PVCCINFAON_CPU1_VREF")
	)
	(segment
		(start 46.933612 -171.008548)
		(end 48.799496 -171.008548)
		(width 0.254)
		(layer "In4.Cu")
		(net "PVCCINFAON_CPU1_VREF")
	)
	(segment
		(start 31.406846 -135.156956)
		(end 32.204152 -134.35965)
		(width 0.254)
		(layer "In4.Cu")
		(net "PVCCINFAON_CPU1_VREF")
	)
	(segment
		(start 34.557208 -134.35965)
		(end 37.978334 -137.780776)
		(width 0.254)
		(layer "In4.Cu")
		(net "PVCCINFAON_CPU1_VREF")
	)
	(segment
		(start 37.978334 -137.780776)
		(end 37.978334 -150.733506)
		(width 0.254)
		(layer "In4.Cu")
		(net "PVCCINFAON_CPU1_VREF")
	)
	(segment
		(start 28.429712 -135.156956)
		(end 31.406846 -135.156956)
		(width 0.254)
		(layer "In4.Cu")
		(net "PVCCINFAON_CPU1_VREF")
	)
	(segment
		(start 48.799496 -171.008548)
		(end 49.1744 -171.383452)
		(width 0.254)
		(layer "In4.Cu")
		(net "PVCCINFAON_CPU1_VREF")
	)
	(segment
		(start 49.1744 -171.383452)
		(end 49.1744 -172.193458)
		(width 0.254)
		(layer "In4.Cu")
		(net "PVCCINFAON_CPU1_VREF")
	)
	(segment
		(start 49.1744 -172.193458)
		(end 49.106328 -172.26153)
		(width 0.254)
		(layer "In4.Cu")
		(net "PVCCINFAON_CPU1_VREF")
	)
	(segment
		(start 49.25695 -155.119578)
		(end 49.875694 -154.500834)
		(width 0.254)
		(layer "In6.Cu")
		(net "PVCCINFAON_CPU1_VREF")
	)
	(segment
		(start 32.00146 -134.607808)
		(end 32.00146 -138.090656)
		(width 0.254)
		(layer "In6.Cu")
		(net "PVCCINFAON_CPU1_VREF")
	)
	(segment
		(start 32.498792 -138.587988)
		(end 33.772348 -138.587988)
		(width 0.254)
		(layer "In6.Cu")
		(net "PVCCINFAON_CPU1_VREF")
	)
	(segment
		(start 41.318434 -155.119578)
		(end 49.25695 -155.119578)
		(width 0.254)
		(layer "In6.Cu")
		(net "PVCCINFAON_CPU1_VREF")
	)
	(segment
		(start 35.46348 -140.27912)
		(end 35.46348 -149.264624)
		(width 0.254)
		(layer "In6.Cu")
		(net "PVCCINFAON_CPU1_VREF")
	)
	(segment
		(start 50.377344 -145.770092)
		(end 50.377344 -145.864834)
		(width 0.254)
		(layer "In6.Cu")
		(net "PVCCINFAON_CPU1_VREF")
	)
	(segment
		(start 37.459666 -137.894568)
		(end 42.571162 -143.006064)
		(width 0.254)
		(layer "In6.Cu")
		(net "PVCCINFAON_CPU1_VREF")
	)
	(segment
		(start 35.46348 -149.264624)
		(end 41.318434 -155.119578)
		(width 0.254)
		(layer "In6.Cu")
		(net "PVCCINFAON_CPU1_VREF")
	)
	(segment
		(start 47.613316 -143.006064)
		(end 50.377344 -145.770092)
		(width 0.254)
		(layer "In6.Cu")
		(net "PVCCINFAON_CPU1_VREF")
	)
	(segment
		(start 32.00146 -138.090656)
		(end 32.498792 -138.587988)
		(width 0.254)
		(layer "In6.Cu")
		(net "PVCCINFAON_CPU1_VREF")
	)
	(segment
		(start 49.875694 -154.500834)
		(end 50.377344 -154.500834)
		(width 0.254)
		(layer "In6.Cu")
		(net "PVCCINFAON_CPU1_VREF")
	)
	(segment
		(start 33.772348 -138.587988)
		(end 35.46348 -140.27912)
		(width 0.254)
		(layer "In6.Cu")
		(net "PVCCINFAON_CPU1_VREF")
	)
	(segment
		(start 42.571162 -143.006064)
		(end 47.613316 -143.006064)
		(width 0.254)
		(layer "In6.Cu")
		(net "PVCCINFAON_CPU1_VREF")
	)
	(segment
		(start 37.459666 -137.889234)
		(end 37.459666 -137.894568)
		(width 0.254)
		(layer "In6.Cu")
		(net "PVCCINFAON_CPU1_VREF")
	)
	(segment
		(start 33.8074 -134.236968)
		(end 37.459666 -137.889234)
		(width 0.254)
		(layer "In6.Cu")
		(net "PVCCINFAON_CPU1_VREF")
	)
	(segment
		(start 28.312618 -128.364996)
		(end 28.784042 -128.364996)
		(width 0.1778)
		(layer "F.Cu")
		(net "PVCCINFAON_CPU1_VIN_CSNIN")
	)
	(segment
		(start 27.43835 -128.364996)
		(end 28.057856 -128.364996)
		(width 0.254)
		(layer "F.Cu")
		(net "PVCCINFAON_CPU1_VIN_CSNIN")
	)
	(segment
		(start 28.784042 -128.364996)
		(end 29.05252 -128.633474)
		(width 0.1778)
		(layer "F.Cu")
		(net "PVCCINFAON_CPU1_VIN_CSNIN")
	)
	(segment
		(start 29.05252 -128.633474)
		(end 29.661104 -128.633474)
		(width 0.1778)
		(layer "F.Cu")
		(net "PVCCINFAON_CPU1_VIN_CSNIN")
	)
	(segment
		(start 28.057856 -128.364996)
		(end 28.312618 -128.364996)
		(width 0.254)
		(layer "F.Cu")
		(net "PVCCINFAON_CPU1_VIN_CSNIN")
	)
	(via
		(at 28.057856 -128.364996)
		(size 0.508)
		(drill 0.254)
		(layers "F.Cu" "B.Cu")
		(net "PVCCINFAON_CPU1_VIN_CSNIN")
	)
	(via
		(at 28.59786 -127.824992)
		(size 0.6604)
		(drill 0.3302)
		(layers "F.Cu" "B.Cu")
		(net "PVCCINFAON_CPU1_VIN_CSNIN")
	)
	(segment
		(start 28.057856 -128.364996)
		(end 27.43835 -128.364996)
		(width 0.254)
		(layer "B.Cu")
		(net "PVCCINFAON_CPU1_VIN_CSNIN")
	)
	(segment
		(start 29.755846 -127.416052)
		(end 29.0068 -127.416052)
		(width 0.254)
		(layer "B.Cu")
		(net "PVCCINFAON_CPU1_VIN_CSNIN")
	)
	(segment
		(start 28.59786 -127.824992)
		(end 28.057856 -128.364996)
		(width 0.254)
		(layer "B.Cu")
		(net "PVCCINFAON_CPU1_VIN_CSNIN")
	)
	(segment
		(start 29.0068 -127.416052)
		(end 28.59786 -127.824992)
		(width 0.254)
		(layer "B.Cu")
		(net "PVCCINFAON_CPU1_VIN_CSNIN")
	)
	(segment
		(start 53.439314 -144.267174)
		(end 52.823364 -144.267174)
		(width 0.2286)
		(layer "F.Cu")
		(net "PVCCINFAON_CPU1_VDD2")
	)
	(segment
		(start 52.823364 -144.352518)
		(end 53.524658 -145.053812)
		(width 0.2032)
		(layer "F.Cu")
		(net "PVCCINFAON_CPU1_VDD2")
	)
	(segment
		(start 51.28768 -147.651978)
		(end 51.999642 -147.651978)
		(width 0.2286)
		(layer "F.Cu")
		(net "PVCCINFAON_CPU1_VDD2")
	)
	(segment
		(start 53.524658 -145.053812)
		(end 53.524658 -145.441924)
		(width 0.2032)
		(layer "F.Cu")
		(net "PVCCINFAON_CPU1_VDD2")
	)
	(segment
		(start 51.211988 -147.576286)
		(end 51.28768 -147.651978)
		(width 0.2286)
		(layer "F.Cu")
		(net "PVCCINFAON_CPU1_VDD2")
	)
	(segment
		(start 52.823364 -144.267174)
		(end 52.823364 -144.352518)
		(width 0.2032)
		(layer "F.Cu")
		(net "PVCCINFAON_CPU1_VDD2")
	)
	(via
		(at 53.439314 -144.267174)
		(size 0.508)
		(drill 0.254)
		(layers "F.Cu" "B.Cu")
		(net "PVCCINFAON_CPU1_VDD2")
	)
	(via
		(at 51.211988 -147.576286)
		(size 0.508)
		(drill 0.254)
		(layers "F.Cu" "B.Cu")
		(net "PVCCINFAON_CPU1_VDD2")
	)
	(via
		(at 52.133754 -146.558508)
		(size 0.6604)
		(drill 0.3302)
		(layers "F.Cu" "B.Cu")
		(net "PVCCINFAON_CPU1_VDD2")
	)
	(segment
		(start 53.439314 -144.267174)
		(end 53.512466 -144.340326)
		(width 0.254)
		(layer "B.Cu")
		(net "PVCCINFAON_CPU1_VDD2")
	)
	(segment
		(start 52.133754 -146.558508)
		(end 52.133754 -146.3929)
		(width 0.254)
		(layer "B.Cu")
		(net "PVCCINFAON_CPU1_VDD2")
	)
	(segment
		(start 53.512466 -144.340326)
		(end 53.512466 -145.445226)
		(width 0.254)
		(layer "B.Cu")
		(net "PVCCINFAON_CPU1_VDD2")
	)
	(segment
		(start 52.133754 -146.3929)
		(end 52.745386 -145.781268)
		(width 0.254)
		(layer "B.Cu")
		(net "PVCCINFAON_CPU1_VDD2")
	)
	(segment
		(start 52.745386 -145.781268)
		(end 53.176424 -145.781268)
		(width 0.254)
		(layer "B.Cu")
		(net "PVCCINFAON_CPU1_VDD2")
	)
	(segment
		(start 53.176424 -145.781268)
		(end 53.512466 -145.445226)
		(width 0.254)
		(layer "B.Cu")
		(net "PVCCINFAON_CPU1_VDD2")
	)
	(segment
		(start 52.133754 -146.65452)
		(end 52.133754 -146.558508)
		(width 0.254)
		(layer "B.Cu")
		(net "PVCCINFAON_CPU1_VDD2")
	)
	(segment
		(start 51.211988 -147.576286)
		(end 52.133754 -146.65452)
		(width 0.254)
		(layer "B.Cu")
		(net "PVCCINFAON_CPU1_VDD2")
	)
	(segment
		(start 52.823364 -152.988518)
		(end 52.823364 -152.903174)
		(width 0.2032)
		(layer "F.Cu")
		(net "PVCCINFAON_CPU1_VDD1")
	)
	(segment
		(start 53.524658 -153.689812)
		(end 52.823364 -152.988518)
		(width 0.2032)
		(layer "F.Cu")
		(net "PVCCINFAON_CPU1_VDD1")
	)
	(segment
		(start 53.524658 -154.077924)
		(end 53.524658 -153.689812)
		(width 0.2032)
		(layer "F.Cu")
		(net "PVCCINFAON_CPU1_VDD1")
	)
	(segment
		(start 51.999642 -156.287978)
		(end 51.28768 -156.287978)
		(width 0.2286)
		(layer "F.Cu")
		(net "PVCCINFAON_CPU1_VDD1")
	)
	(segment
		(start 51.28768 -156.287978)
		(end 51.211988 -156.212286)
		(width 0.2286)
		(layer "F.Cu")
		(net "PVCCINFAON_CPU1_VDD1")
	)
	(segment
		(start 53.439314 -152.903174)
		(end 52.823364 -152.903174)
		(width 0.2286)
		(layer "F.Cu")
		(net "PVCCINFAON_CPU1_VDD1")
	)
	(via
		(at 53.439314 -152.903174)
		(size 0.508)
		(drill 0.254)
		(layers "F.Cu" "B.Cu")
		(net "PVCCINFAON_CPU1_VDD1")
	)
	(via
		(at 51.211988 -156.212286)
		(size 0.508)
		(drill 0.254)
		(layers "F.Cu" "B.Cu")
		(net "PVCCINFAON_CPU1_VDD1")
	)
	(via
		(at 52.133754 -155.194508)
		(size 0.6604)
		(drill 0.3302)
		(layers "F.Cu" "B.Cu")
		(net "PVCCINFAON_CPU1_VDD1")
	)
	(segment
		(start 51.211988 -156.212286)
		(end 52.133754 -155.29052)
		(width 0.254)
		(layer "B.Cu")
		(net "PVCCINFAON_CPU1_VDD1")
	)
	(segment
		(start 52.133754 -155.194508)
		(end 52.133754 -155.0289)
		(width 0.254)
		(layer "B.Cu")
		(net "PVCCINFAON_CPU1_VDD1")
	)
	(segment
		(start 52.133754 -155.29052)
		(end 52.133754 -155.194508)
		(width 0.254)
		(layer "B.Cu")
		(net "PVCCINFAON_CPU1_VDD1")
	)
	(segment
		(start 53.439314 -152.903174)
		(end 53.512466 -152.976326)
		(width 0.254)
		(layer "B.Cu")
		(net "PVCCINFAON_CPU1_VDD1")
	)
	(segment
		(start 52.133754 -155.0289)
		(end 52.717446 -154.445208)
		(width 0.254)
		(layer "B.Cu")
		(net "PVCCINFAON_CPU1_VDD1")
	)
	(segment
		(start 53.512466 -152.976326)
		(end 53.512466 -154.081226)
		(width 0.254)
		(layer "B.Cu")
		(net "PVCCINFAON_CPU1_VDD1")
	)
	(segment
		(start 52.717446 -154.445208)
		(end 53.148484 -154.445208)
		(width 0.254)
		(layer "B.Cu")
		(net "PVCCINFAON_CPU1_VDD1")
	)
	(segment
		(start 53.148484 -154.445208)
		(end 53.512466 -154.081226)
		(width 0.254)
		(layer "B.Cu")
		(net "PVCCINFAON_CPU1_VDD1")
	)
	(segment
		(start 28.115006 -126.053088)
		(end 27.43835 -125.376432)
		(width 0.254)
		(layer "F.Cu")
		(net "PVCCINFAON_CPU1_VCC")
	)
	(segment
		(start 29.248862 -128.233424)
		(end 29.661104 -128.233424)
		(width 0.1778)
		(layer "F.Cu")
		(net "PVCCINFAON_CPU1_VCC")
	)
	(segment
		(start 28.115006 -126.560834)
		(end 28.115006 -126.053088)
		(width 0.254)
		(layer "F.Cu")
		(net "PVCCINFAON_CPU1_VCC")
	)
	(segment
		(start 27.61488 -127.525526)
		(end 27.99588 -127.525526)
		(width 0.254)
		(layer "F.Cu")
		(net "PVCCINFAON_CPU1_VCC")
	)
	(segment
		(start 27.43835 -125.376432)
		(end 27.43073 -125.368812)
		(width 0.254)
		(layer "F.Cu")
		(net "PVCCINFAON_CPU1_VCC")
	)
	(segment
		(start 27.43835 -126.332996)
		(end 27.43835 -125.376432)
		(width 0.254)
		(layer "F.Cu")
		(net "PVCCINFAON_CPU1_VCC")
	)
	(segment
		(start 28.540964 -127.525526)
		(end 29.248862 -128.233424)
		(width 0.1778)
		(layer "F.Cu")
		(net "PVCCINFAON_CPU1_VCC")
	)
	(segment
		(start 27.99588 -127.525526)
		(end 28.540964 -127.525526)
		(width 0.1778)
		(layer "F.Cu")
		(net "PVCCINFAON_CPU1_VCC")
	)
	(segment
		(start 27.43835 -127.348996)
		(end 27.61488 -127.525526)
		(width 0.254)
		(layer "F.Cu")
		(net "PVCCINFAON_CPU1_VCC")
	)
	(segment
		(start 27.43835 -126.332996)
		(end 27.43835 -127.348996)
		(width 0.254)
		(layer "F.Cu")
		(net "PVCCINFAON_CPU1_VCC")
	)
	(via
		(at 28.115006 -126.560834)
		(size 0.508)
		(drill 0.254)
		(layers "F.Cu" "B.Cu")
		(net "PVCCINFAON_CPU1_VCC")
	)
	(segment
		(start 28.115006 -126.019052)
		(end 27.43835 -125.342396)
		(width 0.254)
		(layer "B.Cu")
		(net "PVCCINFAON_CPU1_VCC")
	)
	(segment
		(start 28.115006 -126.560834)
		(end 28.115006 -126.019052)
		(width 0.254)
		(layer "B.Cu")
		(net "PVCCINFAON_CPU1_VCC")
	)
	(segment
		(start 35.428174 -129.433574)
		(end 34.461196 -129.433574)
		(width 0.1778)
		(layer "F.Cu")
		(net "PVCCINFAON_CPU1_PIN_ALERT")
	)
	(segment
		(start 35.931348 -128.9304)
		(end 35.428174 -129.433574)
		(width 0.1778)
		(layer "F.Cu")
		(net "PVCCINFAON_CPU1_PIN_ALERT")
	)
	(via
		(at 36.73856 -129.59842)
		(size 0.7112)
		(drill 0.3556)
		(layers "F.Cu" "B.Cu")
		(net "PVCCINFAON_CPU1_PIN_ALERT")
	)
	(via
		(at 35.931348 -128.9304)
		(size 0.508)
		(drill 0.254)
		(layers "F.Cu" "B.Cu")
		(net "PVCCINFAON_CPU1_PIN_ALERT")
	)
	(segment
		(start 36.73856 -129.59842)
		(end 36.73856 -128.76784)
		(width 0.254)
		(layer "B.Cu")
		(net "PVCCINFAON_CPU1_PIN_ALERT")
	)
	(segment
		(start 36.568888 -128.598168)
		(end 36.568888 -128.4097)
		(width 0.254)
		(layer "B.Cu")
		(net "PVCCINFAON_CPU1_PIN_ALERT")
	)
	(segment
		(start 36.73856 -129.59842)
		(end 36.599368 -129.59842)
		(width 0.254)
		(layer "B.Cu")
		(net "PVCCINFAON_CPU1_PIN_ALERT")
	)
	(segment
		(start 36.73856 -128.76784)
		(end 36.568888 -128.598168)
		(width 0.254)
		(layer "B.Cu")
		(net "PVCCINFAON_CPU1_PIN_ALERT")
	)
	(segment
		(start 36.599368 -129.59842)
		(end 35.931348 -128.9304)
		(width 0.254)
		(layer "B.Cu")
		(net "PVCCINFAON_CPU1_PIN_ALERT")
	)
	(segment
		(start 51.999642 -146.752056)
		(end 51.675792 -146.752056)
		(width 0.12954)
		(layer "F.Cu")
		(net "PVCCINFAON_CPU1_LSET2")
	)
	(segment
		(start 49.984406 -146.379438)
		(end 49.755552 -146.150584)
		(width 0.12954)
		(layer "F.Cu")
		(net "PVCCINFAON_CPU1_LSET2")
	)
	(segment
		(start 51.222148 -146.379438)
		(end 49.984406 -146.379438)
		(width 0.12954)
		(layer "F.Cu")
		(net "PVCCINFAON_CPU1_LSET2")
	)
	(segment
		(start 51.675792 -146.752056)
		(end 51.537362 -146.694652)
		(width 0.12954)
		(layer "F.Cu")
		(net "PVCCINFAON_CPU1_LSET2")
	)
	(segment
		(start 51.537362 -146.694652)
		(end 51.222148 -146.379438)
		(width 0.12954)
		(layer "F.Cu")
		(net "PVCCINFAON_CPU1_LSET2")
	)
	(segment
		(start 51.999642 -155.388056)
		(end 51.675792 -155.388056)
		(width 0.12954)
		(layer "F.Cu")
		(net "PVCCINFAON_CPU1_LSET1")
	)
	(segment
		(start 49.984406 -155.015438)
		(end 49.755552 -154.786584)
		(width 0.12954)
		(layer "F.Cu")
		(net "PVCCINFAON_CPU1_LSET1")
	)
	(segment
		(start 51.222148 -155.015438)
		(end 49.984406 -155.015438)
		(width 0.12954)
		(layer "F.Cu")
		(net "PVCCINFAON_CPU1_LSET1")
	)
	(segment
		(start 51.675792 -155.388056)
		(end 51.537362 -155.330652)
		(width 0.12954)
		(layer "F.Cu")
		(net "PVCCINFAON_CPU1_LSET1")
	)
	(segment
		(start 51.537362 -155.330652)
		(end 51.222148 -155.015438)
		(width 0.12954)
		(layer "F.Cu")
		(net "PVCCINFAON_CPU1_LSET1")
	)
	(segment
		(start 36.149534 -127.71374)
		(end 35.89655 -127.966724)
		(width 0.12954)
		(layer "F.Cu")
		(net "PVCCINFAON_CPU1_EN_R")
	)
	(segment
		(start 34.749232 -128.633474)
		(end 34.461196 -128.633474)
		(width 0.12954)
		(layer "F.Cu")
		(net "PVCCINFAON_CPU1_EN_R")
	)
	(segment
		(start 35.89655 -127.966724)
		(end 35.415982 -127.966724)
		(width 0.12954)
		(layer "F.Cu")
		(net "PVCCINFAON_CPU1_EN_R")
	)
	(segment
		(start 35.415982 -127.966724)
		(end 34.749232 -128.633474)
		(width 0.12954)
		(layer "F.Cu")
		(net "PVCCINFAON_CPU1_EN_R")
	)
	(segment
		(start 36.556188 -127.71374)
		(end 36.149534 -127.71374)
		(width 0.12954)
		(layer "F.Cu")
		(net "PVCCINFAON_CPU1_EN_R")
	)
	(via
		(at 34.968688 -127.534924)
		(size 0.6604)
		(drill 0.3302)
		(layers "F.Cu" "B.Cu")
		(net "PVCCINFAON_CPU1_EN_R")
	)
	(via
		(at 35.89655 -127.966724)
		(size 0.508)
		(drill 0.254)
		(layers "F.Cu" "B.Cu")
		(net "PVCCINFAON_CPU1_EN_R")
	)
	(segment
		(start 35.400488 -127.966724)
		(end 35.89655 -127.966724)
		(width 0.12954)
		(layer "B.Cu")
		(net "PVCCINFAON_CPU1_EN_R")
	)
	(segment
		(start 36.018724 -127.966724)
		(end 36.568888 -127.41656)
		(width 0.12954)
		(layer "B.Cu")
		(net "PVCCINFAON_CPU1_EN_R")
	)
	(segment
		(start 34.968688 -127.534924)
		(end 35.400488 -127.966724)
		(width 0.12954)
		(layer "B.Cu")
		(net "PVCCINFAON_CPU1_EN_R")
	)
	(segment
		(start 35.89655 -127.966724)
		(end 36.018724 -127.966724)
		(width 0.12954)
		(layer "B.Cu")
		(net "PVCCINFAON_CPU1_EN_R")
	)
	(segment
		(start 29.661104 -129.033524)
		(end 28.609036 -129.033524)
		(width 0.1778)
		(layer "F.Cu")
		(net "PVCCINFAON_CPU1_CSPIN")
	)
	(segment
		(start 28.609036 -129.033524)
		(end 28.56992 -128.994408)
		(width 0.1778)
		(layer "F.Cu")
		(net "PVCCINFAON_CPU1_CSPIN")
	)
	(segment
		(start 28.56992 -128.979168)
		(end 27.840178 -128.979168)
		(width 0.1778)
		(layer "F.Cu")
		(net "PVCCINFAON_CPU1_CSPIN")
	)
	(segment
		(start 28.56992 -128.994408)
		(end 28.56992 -128.979168)
		(width 0.1778)
		(layer "F.Cu")
		(net "PVCCINFAON_CPU1_CSPIN")
	)
	(segment
		(start 27.840178 -128.979168)
		(end 27.43835 -129.380996)
		(width 0.254)
		(layer "F.Cu")
		(net "PVCCINFAON_CPU1_CSPIN")
	)
	(via
		(at 28.56992 -128.979168)
		(size 0.508)
		(drill 0.254)
		(layers "F.Cu" "B.Cu")
		(net "PVCCINFAON_CPU1_CSPIN")
	)
	(segment
		(start 28.56992 -128.994408)
		(end 28.56992 -128.979168)
		(width 0.254)
		(layer "B.Cu")
		(net "PVCCINFAON_CPU1_CSPIN")
	)
	(segment
		(start 28.56992 -128.979168)
		(end 28.5496 -128.979168)
		(width 0.254)
		(layer "B.Cu")
		(net "PVCCINFAON_CPU1_CSPIN")
	)
	(segment
		(start 28.57627 -129.000758)
		(end 28.56992 -128.994408)
		(width 0.254)
		(layer "B.Cu")
		(net "PVCCINFAON_CPU1_CSPIN")
	)
	(segment
		(start 28.495244 -129.033524)
		(end 27.785822 -129.033524)
		(width 0.254)
		(layer "B.Cu")
		(net "PVCCINFAON_CPU1_CSPIN")
	)
	(segment
		(start 27.785822 -129.033524)
		(end 27.43835 -129.380996)
		(width 0.254)
		(layer "B.Cu")
		(net "PVCCINFAON_CPU1_CSPIN")
	)
	(segment
		(start 29.763466 -129.000758)
		(end 28.57627 -129.000758)
		(width 0.254)
		(layer "B.Cu")
		(net "PVCCINFAON_CPU1_CSPIN")
	)
	(segment
		(start 28.5496 -128.979168)
		(end 28.495244 -129.033524)
		(width 0.254)
		(layer "B.Cu")
		(net "PVCCINFAON_CPU1_CSPIN")
	)
	(segment
		(start 51.999642 -155.83789)
		(end 51.704494 -155.83789)
		(width 0.254)
		(layer "F.Cu")
		(net "PVCCINFAON_CPU1_ATSEN")
	)
	(segment
		(start 25.342342 -130.442716)
		(end 25.168606 -130.26898)
		(width 0.254)
		(layer "F.Cu")
		(net "PVCCINFAON_CPU1_ATSEN")
	)
	(segment
		(start 50.96637 -155.532328)
		(end 50.966116 -155.532074)
		(width 0.254)
		(layer "F.Cu")
		(net "PVCCINFAON_CPU1_ATSEN")
	)
	(segment
		(start 27.43835 -130.396996)
		(end 27.585416 -130.24993)
		(width 0.1778)
		(layer "F.Cu")
		(net "PVCCINFAON_CPU1_ATSEN")
	)
	(segment
		(start 27.43835 -130.396996)
		(end 27.43835 -130.489452)
		(width 0.254)
		(layer "F.Cu")
		(net "PVCCINFAON_CPU1_ATSEN")
	)
	(segment
		(start 26.963878 -130.963924)
		(end 25.342342 -130.963924)
		(width 0.254)
		(layer "F.Cu")
		(net "PVCCINFAON_CPU1_ATSEN")
	)
	(segment
		(start 50.966116 -155.532074)
		(end 50.966116 -155.516834)
		(width 0.254)
		(layer "F.Cu")
		(net "PVCCINFAON_CPU1_ATSEN")
	)
	(segment
		(start 51.704494 -155.83789)
		(end 50.96637 -155.532328)
		(width 0.254)
		(layer "F.Cu")
		(net "PVCCINFAON_CPU1_ATSEN")
	)
	(segment
		(start 25.342342 -130.963924)
		(end 25.342342 -130.442716)
		(width 0.254)
		(layer "F.Cu")
		(net "PVCCINFAON_CPU1_ATSEN")
	)
	(segment
		(start 50.966116 -146.880834)
		(end 50.966116 -146.896074)
		(width 0.254)
		(layer "F.Cu")
		(net "PVCCINFAON_CPU1_ATSEN")
	)
	(segment
		(start 29.14015 -129.83337)
		(end 29.661104 -129.83337)
		(width 0.1778)
		(layer "F.Cu")
		(net "PVCCINFAON_CPU1_ATSEN")
	)
	(segment
		(start 27.43835 -130.489452)
		(end 26.963878 -130.963924)
		(width 0.254)
		(layer "F.Cu")
		(net "PVCCINFAON_CPU1_ATSEN")
	)
	(segment
		(start 27.585416 -130.24993)
		(end 28.72359 -130.24993)
		(width 0.1778)
		(layer "F.Cu")
		(net "PVCCINFAON_CPU1_ATSEN")
	)
	(segment
		(start 28.72359 -130.24993)
		(end 29.14015 -129.83337)
		(width 0.1778)
		(layer "F.Cu")
		(net "PVCCINFAON_CPU1_ATSEN")
	)
	(segment
		(start 50.966116 -146.896074)
		(end 50.96637 -146.896328)
		(width 0.254)
		(layer "F.Cu")
		(net "PVCCINFAON_CPU1_ATSEN")
	)
	(segment
		(start 50.96637 -146.896328)
		(end 51.704494 -147.20189)
		(width 0.254)
		(layer "F.Cu")
		(net "PVCCINFAON_CPU1_ATSEN")
	)
	(segment
		(start 51.704494 -147.20189)
		(end 51.999642 -147.20189)
		(width 0.254)
		(layer "F.Cu")
		(net "PVCCINFAON_CPU1_ATSEN")
	)
	(via
		(at 25.342342 -130.963924)
		(size 0.508)
		(drill 0.254)
		(layers "F.Cu" "B.Cu")
		(net "PVCCINFAON_CPU1_ATSEN")
	)
	(via
		(at 50.966116 -155.516834)
		(size 0.508)
		(drill 0.254)
		(layers "F.Cu" "B.Cu")
		(net "PVCCINFAON_CPU1_ATSEN")
	)
	(via
		(at 50.966116 -146.880834)
		(size 0.508)
		(drill 0.254)
		(layers "F.Cu" "B.Cu")
		(net "PVCCINFAON_CPU1_ATSEN")
	)
	(segment
		(start 39.046912 -153.967942)
		(end 39.046912 -147.947126)
		(width 0.254)
		(layer "In13.Cu")
		(net "PVCCINFAON_CPU1_ATSEN")
	)
	(segment
		(start 35.700462 -133.891528)
		(end 39.046912 -137.237978)
		(width 0.254)
		(layer "In13.Cu")
		(net "PVCCINFAON_CPU1_ATSEN")
	)
	(segment
		(start 40.595804 -155.516834)
		(end 39.046912 -153.967942)
		(width 0.254)
		(layer "In13.Cu")
		(net "PVCCINFAON_CPU1_ATSEN")
	)
	(segment
		(start 27.708098 -132.71754)
		(end 28.31973 -133.329172)
		(width 0.254)
		(layer "In13.Cu")
		(net "PVCCINFAON_CPU1_ATSEN")
	)
	(segment
		(start 31.773368 -133.891528)
		(end 35.700462 -133.891528)
		(width 0.254)
		(layer "In13.Cu")
		(net "PVCCINFAON_CPU1_ATSEN")
	)
	(segment
		(start 50.966116 -155.516834)
		(end 40.595804 -155.516834)
		(width 0.254)
		(layer "In13.Cu")
		(net "PVCCINFAON_CPU1_ATSEN")
	)
	(segment
		(start 49.3268 -146.880834)
		(end 48.346106 -147.861528)
		(width 0.254)
		(layer "In13.Cu")
		(net "PVCCINFAON_CPU1_ATSEN")
	)
	(segment
		(start 25.342342 -130.963924)
		(end 26.975562 -130.963924)
		(width 0.254)
		(layer "In13.Cu")
		(net "PVCCINFAON_CPU1_ATSEN")
	)
	(segment
		(start 48.346106 -147.861528)
		(end 39.13251 -147.861528)
		(width 0.254)
		(layer "In13.Cu")
		(net "PVCCINFAON_CPU1_ATSEN")
	)
	(segment
		(start 39.13251 -147.861528)
		(end 39.046912 -147.947126)
		(width 0.254)
		(layer "In13.Cu")
		(net "PVCCINFAON_CPU1_ATSEN")
	)
	(segment
		(start 31.211012 -133.329172)
		(end 31.773368 -133.891528)
		(width 0.254)
		(layer "In13.Cu")
		(net "PVCCINFAON_CPU1_ATSEN")
	)
	(segment
		(start 39.046912 -137.237978)
		(end 39.046912 -147.947126)
		(width 0.254)
		(layer "In13.Cu")
		(net "PVCCINFAON_CPU1_ATSEN")
	)
	(segment
		(start 27.708098 -131.69646)
		(end 27.708098 -132.71754)
		(width 0.254)
		(layer "In13.Cu")
		(net "PVCCINFAON_CPU1_ATSEN")
	)
	(segment
		(start 50.966116 -146.880834)
		(end 49.3268 -146.880834)
		(width 0.254)
		(layer "In13.Cu")
		(net "PVCCINFAON_CPU1_ATSEN")
	)
	(segment
		(start 26.975562 -130.963924)
		(end 27.708098 -131.69646)
		(width 0.254)
		(layer "In13.Cu")
		(net "PVCCINFAON_CPU1_ATSEN")
	)
	(segment
		(start 28.31973 -133.329172)
		(end 31.211012 -133.329172)
		(width 0.254)
		(layer "In13.Cu")
		(net "PVCCINFAON_CPU1_ATSEN")
	)
	(segment
		(start 31.527496 -125.954282)
		(end 31.846266 -126.273052)
		(width 0.1524)
		(layer "F.Cu")
		(net "PVCCINFAON_CPU1_APWM2")
	)
	(segment
		(start 31.846266 -126.273052)
		(end 32.14878 -126.273052)
		(width 0.1524)
		(layer "F.Cu")
		(net "PVCCINFAON_CPU1_APWM2")
	)
	(segment
		(start 32.661098 -126.78537)
		(end 32.661098 -127.233426)
		(width 0.1524)
		(layer "F.Cu")
		(net "PVCCINFAON_CPU1_APWM2")
	)
	(segment
		(start 50.587656 -147.950174)
		(end 50.714656 -148.002752)
		(width 0.1778)
		(layer "F.Cu")
		(net "PVCCINFAON_CPU1_APWM2")
	)
	(segment
		(start 50.714656 -148.002752)
		(end 51.213766 -148.102066)
		(width 0.1778)
		(layer "F.Cu")
		(net "PVCCINFAON_CPU1_APWM2")
	)
	(segment
		(start 51.213766 -148.102066)
		(end 51.999642 -148.102066)
		(width 0.1778)
		(layer "F.Cu")
		(net "PVCCINFAON_CPU1_APWM2")
	)
	(segment
		(start 32.14878 -126.273052)
		(end 32.661098 -126.78537)
		(width 0.1524)
		(layer "F.Cu")
		(net "PVCCINFAON_CPU1_APWM2")
	)
	(via
		(at 50.587656 -147.950174)
		(size 0.508)
		(drill 0.254)
		(layers "F.Cu" "B.Cu")
		(net "PVCCINFAON_CPU1_APWM2")
	)
	(via
		(at 31.527496 -125.954282)
		(size 0.508)
		(drill 0.254)
		(layers "F.Cu" "B.Cu")
		(net "PVCCINFAON_CPU1_APWM2")
	)
	(segment
		(start 29.93517 -124.889768)
		(end 30.999684 -125.954282)
		(width 0.254)
		(layer "In2.Cu")
		(net "PVCCINFAON_CPU1_APWM2")
	)
	(segment
		(start 28.882594 -124.889768)
		(end 29.93517 -124.889768)
		(width 0.254)
		(layer "In2.Cu")
		(net "PVCCINFAON_CPU1_APWM2")
	)
	(segment
		(start 38.61562 -147.020534)
		(end 38.61562 -144.142968)
		(width 0.254)
		(layer "In2.Cu")
		(net "PVCCINFAON_CPU1_APWM2")
	)
	(segment
		(start 50.587656 -148.284438)
		(end 49.903126 -148.968968)
		(width 0.254)
		(layer "In2.Cu")
		(net "PVCCINFAON_CPU1_APWM2")
	)
	(segment
		(start 40.564054 -148.968968)
		(end 38.61562 -147.020534)
		(width 0.254)
		(layer "In2.Cu")
		(net "PVCCINFAON_CPU1_APWM2")
	)
	(segment
		(start 44.451778 -138.30681)
		(end 44.451778 -124.898658)
		(width 0.254)
		(layer "In2.Cu")
		(net "PVCCINFAON_CPU1_APWM2")
	)
	(segment
		(start 30.928564 -120.329452)
		(end 28.306268 -122.951748)
		(width 0.254)
		(layer "In2.Cu")
		(net "PVCCINFAON_CPU1_APWM2")
	)
	(segment
		(start 39.882572 -120.329452)
		(end 30.928564 -120.329452)
		(width 0.254)
		(layer "In2.Cu")
		(net "PVCCINFAON_CPU1_APWM2")
	)
	(segment
		(start 50.587656 -147.950174)
		(end 50.587656 -148.284438)
		(width 0.254)
		(layer "In2.Cu")
		(net "PVCCINFAON_CPU1_APWM2")
	)
	(segment
		(start 28.306268 -122.951748)
		(end 28.306268 -124.313442)
		(width 0.254)
		(layer "In2.Cu")
		(net "PVCCINFAON_CPU1_APWM2")
	)
	(segment
		(start 49.903126 -148.968968)
		(end 40.564054 -148.968968)
		(width 0.254)
		(layer "In2.Cu")
		(net "PVCCINFAON_CPU1_APWM2")
	)
	(segment
		(start 30.999684 -125.954282)
		(end 31.527496 -125.954282)
		(width 0.254)
		(layer "In2.Cu")
		(net "PVCCINFAON_CPU1_APWM2")
	)
	(segment
		(start 44.451778 -124.898658)
		(end 39.882572 -120.329452)
		(width 0.254)
		(layer "In2.Cu")
		(net "PVCCINFAON_CPU1_APWM2")
	)
	(segment
		(start 38.61562 -144.142968)
		(end 44.451778 -138.30681)
		(width 0.254)
		(layer "In2.Cu")
		(net "PVCCINFAON_CPU1_APWM2")
	)
	(segment
		(start 28.306268 -124.313442)
		(end 28.882594 -124.889768)
		(width 0.254)
		(layer "In2.Cu")
		(net "PVCCINFAON_CPU1_APWM2")
	)
	(segment
		(start 33.061148 -126.586996)
		(end 33.061148 -127.233426)
		(width 0.1524)
		(layer "F.Cu")
		(net "PVCCINFAON_CPU1_APWM1")
	)
	(segment
		(start 31.753302 -124.924566)
		(end 32.30245 -125.473714)
		(width 0.1524)
		(layer "F.Cu")
		(net "PVCCINFAON_CPU1_APWM1")
	)
	(segment
		(start 51.999642 -156.738066)
		(end 51.213766 -156.738066)
		(width 0.1778)
		(layer "F.Cu")
		(net "PVCCINFAON_CPU1_APWM1")
	)
	(segment
		(start 32.30245 -125.828298)
		(end 33.061148 -126.586996)
		(width 0.1524)
		(layer "F.Cu")
		(net "PVCCINFAON_CPU1_APWM1")
	)
	(segment
		(start 51.213766 -156.738066)
		(end 50.714656 -156.638752)
		(width 0.1778)
		(layer "F.Cu")
		(net "PVCCINFAON_CPU1_APWM1")
	)
	(segment
		(start 50.714656 -156.638752)
		(end 50.587656 -156.586174)
		(width 0.1778)
		(layer "F.Cu")
		(net "PVCCINFAON_CPU1_APWM1")
	)
	(segment
		(start 32.30245 -125.473714)
		(end 32.30245 -125.828298)
		(width 0.1524)
		(layer "F.Cu")
		(net "PVCCINFAON_CPU1_APWM1")
	)
	(via
		(at 31.753302 -124.924566)
		(size 0.508)
		(drill 0.254)
		(layers "F.Cu" "B.Cu")
		(net "PVCCINFAON_CPU1_APWM1")
	)
	(via
		(at 50.587656 -156.586174)
		(size 0.508)
		(drill 0.254)
		(layers "F.Cu" "B.Cu")
		(net "PVCCINFAON_CPU1_APWM1")
	)
	(segment
		(start 37.7317 -152.798526)
		(end 37.7317 -143.883888)
		(width 0.254)
		(layer "In2.Cu")
		(net "PVCCINFAON_CPU1_APWM1")
	)
	(segment
		(start 43.689778 -137.92581)
		(end 43.689778 -125.21438)
		(width 0.254)
		(layer "In2.Cu")
		(net "PVCCINFAON_CPU1_APWM1")
	)
	(segment
		(start 50.587656 -157.022292)
		(end 50.00498 -157.604968)
		(width 0.254)
		(layer "In2.Cu")
		(net "PVCCINFAON_CPU1_APWM1")
	)
	(segment
		(start 37.7317 -143.883888)
		(end 43.689778 -137.92581)
		(width 0.254)
		(layer "In2.Cu")
		(net "PVCCINFAON_CPU1_APWM1")
	)
	(segment
		(start 42.538142 -157.604968)
		(end 37.7317 -152.798526)
		(width 0.254)
		(layer "In2.Cu")
		(net "PVCCINFAON_CPU1_APWM1")
	)
	(segment
		(start 43.689778 -125.21438)
		(end 39.56685 -121.091452)
		(width 0.254)
		(layer "In2.Cu")
		(net "PVCCINFAON_CPU1_APWM1")
	)
	(segment
		(start 50.00498 -157.604968)
		(end 42.538142 -157.604968)
		(width 0.254)
		(layer "In2.Cu")
		(net "PVCCINFAON_CPU1_APWM1")
	)
	(segment
		(start 31.97606 -121.091452)
		(end 30.843982 -122.22353)
		(width 0.254)
		(layer "In2.Cu")
		(net "PVCCINFAON_CPU1_APWM1")
	)
	(segment
		(start 30.843982 -124.015246)
		(end 31.753302 -124.924566)
		(width 0.254)
		(layer "In2.Cu")
		(net "PVCCINFAON_CPU1_APWM1")
	)
	(segment
		(start 50.587656 -156.586174)
		(end 50.587656 -157.022292)
		(width 0.254)
		(layer "In2.Cu")
		(net "PVCCINFAON_CPU1_APWM1")
	)
	(segment
		(start 30.843982 -122.22353)
		(end 30.843982 -124.015246)
		(width 0.254)
		(layer "In2.Cu")
		(net "PVCCINFAON_CPU1_APWM1")
	)
	(segment
		(start 39.56685 -121.091452)
		(end 31.97606 -121.091452)
		(width 0.254)
		(layer "In2.Cu")
		(net "PVCCINFAON_CPU1_APWM1")
	)
	(segment
		(start 27.96921 -130.894836)
		(end 28.562046 -130.894836)
		(width 0.1778)
		(layer "F.Cu")
		(net "PVCCINFAON_CPU1_ADDR")
	)
	(segment
		(start 28.562046 -130.894836)
		(end 29.223462 -130.23342)
		(width 0.1778)
		(layer "F.Cu")
		(net "PVCCINFAON_CPU1_ADDR")
	)
	(segment
		(start 27.95524 -130.880866)
		(end 27.96921 -130.894836)
		(width 0.1778)
		(layer "F.Cu")
		(net "PVCCINFAON_CPU1_ADDR")
	)
	(segment
		(start 29.223462 -130.23342)
		(end 29.661104 -130.23342)
		(width 0.1778)
		(layer "F.Cu")
		(net "PVCCINFAON_CPU1_ADDR")
	)
	(via
		(at 27.708098 -132.74548)
		(size 0.7112)
		(drill 0.3556)
		(layers "F.Cu" "B.Cu")
		(net "PVCCINFAON_CPU1_ADDR")
	)
	(via
		(at 27.95524 -130.880866)
		(size 0.508)
		(drill 0.254)
		(layers "F.Cu" "B.Cu")
		(net "PVCCINFAON_CPU1_ADDR")
	)
	(segment
		(start 27.708098 -131.822698)
		(end 27.43835 -131.55295)
		(width 0.254)
		(layer "B.Cu")
		(net "PVCCINFAON_CPU1_ADDR")
	)
	(segment
		(start 27.753818 -130.396996)
		(end 27.43835 -130.396996)
		(width 0.254)
		(layer "B.Cu")
		(net "PVCCINFAON_CPU1_ADDR")
	)
	(segment
		(start 27.95524 -130.880866)
		(end 27.94 -130.865626)
		(width 0.254)
		(layer "B.Cu")
		(net "PVCCINFAON_CPU1_ADDR")
	)
	(segment
		(start 27.708098 -132.74548)
		(end 27.708098 -131.822698)
		(width 0.254)
		(layer "B.Cu")
		(net "PVCCINFAON_CPU1_ADDR")
	)
	(segment
		(start 27.94 -130.865626)
		(end 27.94 -130.583178)
		(width 0.254)
		(layer "B.Cu")
		(net "PVCCINFAON_CPU1_ADDR")
	)
	(segment
		(start 27.94 -130.583178)
		(end 27.753818 -130.396996)
		(width 0.254)
		(layer "B.Cu")
		(net "PVCCINFAON_CPU1_ADDR")
	)
	(segment
		(start 27.43835 -131.55295)
		(end 27.43835 -130.396996)
		(width 0.254)
		(layer "B.Cu")
		(net "PVCCINFAON_CPU1_ADDR")
	)
	(segment
		(start 32.71774 -135.677148)
		(end 32.39262 -135.352028)
		(width 0.1778)
		(layer "F.Cu")
		(net "PVCCINFAON_CPU1_ACSP2")
	)
	(segment
		(start 51.665378 -146.301968)
		(end 51.999642 -146.301968)
		(width 0.254)
		(layer "F.Cu")
		(net "PVCCINFAON_CPU1_ACSP2")
	)
	(segment
		(start 32.661098 -132.78231)
		(end 32.661098 -132.033518)
		(width 0.1778)
		(layer "F.Cu")
		(net "PVCCINFAON_CPU1_ACSP2")
	)
	(segment
		(start 51.228244 -145.864834)
		(end 51.665378 -146.301968)
		(width 0.254)
		(layer "F.Cu")
		(net "PVCCINFAON_CPU1_ACSP2")
	)
	(segment
		(start 32.39262 -133.050788)
		(end 32.661098 -132.78231)
		(width 0.1778)
		(layer "F.Cu")
		(net "PVCCINFAON_CPU1_ACSP2")
	)
	(segment
		(start 33.4391 -135.677148)
		(end 32.71774 -135.677148)
		(width 0.1778)
		(layer "F.Cu")
		(net "PVCCINFAON_CPU1_ACSP2")
	)
	(segment
		(start 33.82264 -135.128508)
		(end 33.82264 -135.293608)
		(width 0.1778)
		(layer "F.Cu")
		(net "PVCCINFAON_CPU1_ACSP2")
	)
	(segment
		(start 51.153568 -145.864834)
		(end 51.228244 -145.864834)
		(width 0.254)
		(layer "F.Cu")
		(net "PVCCINFAON_CPU1_ACSP2")
	)
	(segment
		(start 33.82264 -135.293608)
		(end 33.4391 -135.677148)
		(width 0.1778)
		(layer "F.Cu")
		(net "PVCCINFAON_CPU1_ACSP2")
	)
	(segment
		(start 32.39262 -135.352028)
		(end 32.39262 -133.050788)
		(width 0.1778)
		(layer "F.Cu")
		(net "PVCCINFAON_CPU1_ACSP2")
	)
	(via
		(at 51.153568 -145.864834)
		(size 0.508)
		(drill 0.254)
		(layers "F.Cu" "B.Cu")
		(net "PVCCINFAON_CPU1_ACSP2")
	)
	(via
		(at 33.82264 -135.128508)
		(size 0.762)
		(drill 0.254)
		(layers "F.Cu" "B.Cu")
		(net "PVCCINFAON_CPU1_ACSP2")
	)
	(segment
		(start 50.6222 -146.421348)
		(end 50.1396 -146.421348)
		(width 0.254)
		(layer "In6.Cu")
		(net "PVCCINFAON_CPU1_ACSP2")
	)
	(segment
		(start 47.455328 -143.387064)
		(end 42.413174 -143.387064)
		(width 0.254)
		(layer "In6.Cu")
		(net "PVCCINFAON_CPU1_ACSP2")
	)
	(segment
		(start 49.7586 -146.040348)
		(end 49.7586 -145.690336)
		(width 0.254)
		(layer "In6.Cu")
		(net "PVCCINFAON_CPU1_ACSP2")
	)
	(segment
		(start 51.153568 -145.864834)
		(end 51.153568 -145.88998)
		(width 0.254)
		(layer "In6.Cu")
		(net "PVCCINFAON_CPU1_ACSP2")
	)
	(segment
		(start 51.153568 -145.88998)
		(end 50.6222 -146.421348)
		(width 0.254)
		(layer "In6.Cu")
		(net "PVCCINFAON_CPU1_ACSP2")
	)
	(segment
		(start 50.1396 -146.421348)
		(end 49.7586 -146.040348)
		(width 0.254)
		(layer "In6.Cu")
		(net "PVCCINFAON_CPU1_ACSP2")
	)
	(segment
		(start 42.413174 -143.387064)
		(end 34.154618 -135.128508)
		(width 0.254)
		(layer "In6.Cu")
		(net "PVCCINFAON_CPU1_ACSP2")
	)
	(segment
		(start 49.7586 -145.690336)
		(end 47.455328 -143.387064)
		(width 0.254)
		(layer "In6.Cu")
		(net "PVCCINFAON_CPU1_ACSP2")
	)
	(segment
		(start 34.154618 -135.128508)
		(end 33.82264 -135.128508)
		(width 0.254)
		(layer "In6.Cu")
		(net "PVCCINFAON_CPU1_ACSP2")
	)
	(segment
		(start 51.228244 -154.500834)
		(end 51.153568 -154.500834)
		(width 0.254)
		(layer "F.Cu")
		(net "PVCCINFAON_CPU1_ACSP1")
	)
	(segment
		(start 32.91586 -134.478268)
		(end 32.91586 -133.137148)
		(width 0.1778)
		(layer "F.Cu")
		(net "PVCCINFAON_CPU1_ACSP1")
	)
	(segment
		(start 33.061148 -134.623556)
		(end 32.91586 -134.478268)
		(width 0.1778)
		(layer "F.Cu")
		(net "PVCCINFAON_CPU1_ACSP1")
	)
	(segment
		(start 32.959548 -135.113268)
		(end 33.061148 -135.011668)
		(width 0.1778)
		(layer "F.Cu")
		(net "PVCCINFAON_CPU1_ACSP1")
	)
	(segment
		(start 51.999642 -154.937968)
		(end 51.665378 -154.937968)
		(width 0.254)
		(layer "F.Cu")
		(net "PVCCINFAON_CPU1_ACSP1")
	)
	(segment
		(start 32.91586 -133.137148)
		(end 33.061148 -132.99186)
		(width 0.1778)
		(layer "F.Cu")
		(net "PVCCINFAON_CPU1_ACSP1")
	)
	(segment
		(start 33.061148 -135.011668)
		(end 33.061148 -134.623556)
		(width 0.1778)
		(layer "F.Cu")
		(net "PVCCINFAON_CPU1_ACSP1")
	)
	(segment
		(start 33.061148 -132.99186)
		(end 33.061148 -132.033518)
		(width 0.1778)
		(layer "F.Cu")
		(net "PVCCINFAON_CPU1_ACSP1")
	)
	(segment
		(start 51.665378 -154.937968)
		(end 51.228244 -154.500834)
		(width 0.254)
		(layer "F.Cu")
		(net "PVCCINFAON_CPU1_ACSP1")
	)
	(via
		(at 51.153568 -154.500834)
		(size 0.508)
		(drill 0.254)
		(layers "F.Cu" "B.Cu")
		(net "PVCCINFAON_CPU1_ACSP1")
	)
	(via
		(at 32.959548 -135.113268)
		(size 0.508)
		(drill 0.254)
		(layers "F.Cu" "B.Cu")
		(net "PVCCINFAON_CPU1_ACSP1")
	)
	(segment
		(start 49.08804 -154.711908)
		(end 41.487344 -154.711908)
		(width 0.254)
		(layer "In6.Cu")
		(net "PVCCINFAON_CPU1_ACSP1")
	)
	(segment
		(start 32.38246 -137.932668)
		(end 32.38246 -135.690356)
		(width 0.254)
		(layer "In6.Cu")
		(net "PVCCINFAON_CPU1_ACSP1")
	)
	(segment
		(start 49.8602 -153.939748)
		(end 49.08804 -154.711908)
		(width 0.254)
		(layer "In6.Cu")
		(net "PVCCINFAON_CPU1_ACSP1")
	)
	(segment
		(start 32.65678 -138.206988)
		(end 32.38246 -137.932668)
		(width 0.254)
		(layer "In6.Cu")
		(net "PVCCINFAON_CPU1_ACSP1")
	)
	(segment
		(start 41.487344 -154.711908)
		(end 35.84448 -149.069044)
		(width 0.254)
		(layer "In6.Cu")
		(net "PVCCINFAON_CPU1_ACSP1")
	)
	(segment
		(start 35.84448 -149.069044)
		(end 35.84448 -140.121132)
		(width 0.254)
		(layer "In6.Cu")
		(net "PVCCINFAON_CPU1_ACSP1")
	)
	(segment
		(start 51.153568 -154.500834)
		(end 50.592482 -153.939748)
		(width 0.254)
		(layer "In6.Cu")
		(net "PVCCINFAON_CPU1_ACSP1")
	)
	(segment
		(start 33.930336 -138.206988)
		(end 32.65678 -138.206988)
		(width 0.254)
		(layer "In6.Cu")
		(net "PVCCINFAON_CPU1_ACSP1")
	)
	(segment
		(start 50.592482 -153.939748)
		(end 49.8602 -153.939748)
		(width 0.254)
		(layer "In6.Cu")
		(net "PVCCINFAON_CPU1_ACSP1")
	)
	(segment
		(start 32.38246 -135.690356)
		(end 32.959548 -135.113268)
		(width 0.254)
		(layer "In6.Cu")
		(net "PVCCINFAON_CPU1_ACSP1")
	)
	(segment
		(start 35.84448 -140.121132)
		(end 33.930336 -138.206988)
		(width 0.254)
		(layer "In6.Cu")
		(net "PVCCINFAON_CPU1_ACSP1")
	)
	(segment
		(start 121.148094 -269.66164)
		(end 121.148348 -270.167862)
		(width 0.254)
		(layer "F.Cu")
		(net "PVCCINFAON_CPU1")
	)
	(segment
		(start 69.923406 -160.499806)
		(end 70.939406 -159.483806)
		(width 0.508)
		(layer "F.Cu")
		(net "PVCCINFAON_CPU1")
	)
	(segment
		(start 116.809266 -218.692476)
		(end 116.809012 -218.692222)
		(width 0.254)
		(layer "F.Cu")
		(net "PVCCINFAON_CPU1")
	)
	(segment
		(start 126.207266 -222.48368)
		(end 126.207266 -221.947994)
		(width 0.254)
		(layer "F.Cu")
		(net "PVCCINFAON_CPU1")
	)
	(segment
		(start 120.568466 -222.48368)
		(end 120.568466 -221.947994)
		(width 0.254)
		(layer "F.Cu")
		(net "PVCCINFAON_CPU1")
	)
	(segment
		(start 68.983098 -149.168612)
		(end 69.923406 -148.228304)
		(width 0.508)
		(layer "F.Cu")
		(net "PVCCINFAON_CPU1")
	)
	(segment
		(start 121.148348 -270.167862)
		(end 121.148348 -270.19758)
		(width 0.254)
		(layer "F.Cu")
		(net "PVCCINFAON_CPU1")
	)
	(segment
		(start 126.207266 -225.739198)
		(end 126.207266 -225.203512)
		(width 0.254)
		(layer "F.Cu")
		(net "PVCCINFAON_CPU1")
	)
	(segment
		(start 69.923406 -160.499806)
		(end 69.153786 -161.269426)
		(width 0.508)
		(layer "F.Cu")
		(net "PVCCINFAON_CPU1")
	)
	(segment
		(start 103.652066 -225.739198)
		(end 103.652066 -225.203512)
		(width 0.254)
		(layer "F.Cu")
		(net "PVCCINFAON_CPU1")
	)
	(segment
		(start 116.809266 -215.972644)
		(end 116.809012 -215.97239)
		(width 0.254)
		(layer "F.Cu")
		(net "PVCCINFAON_CPU1")
	)
	(segment
		(start 120.568466 -221.947994)
		(end 120.568212 -221.94774)
		(width 0.254)
		(layer "F.Cu")
		(net "PVCCINFAON_CPU1")
	)
	(segment
		(start 120.568466 -215.972644)
		(end 120.568466 -215.437212)
		(width 0.254)
		(layer "F.Cu")
		(net "PVCCINFAON_CPU1")
	)
	(segment
		(start 122.448066 -221.947994)
		(end 122.447812 -221.94774)
		(width 0.254)
		(layer "F.Cu")
		(net "PVCCINFAON_CPU1")
	)
	(segment
		(start 118.688612 -215.436958)
		(end 118.688612 -215.436704)
		(width 0.254)
		(layer "F.Cu")
		(net "PVCCINFAON_CPU1")
	)
	(segment
		(start 120.568466 -219.228162)
		(end 120.568466 -218.692476)
		(width 0.254)
		(layer "F.Cu")
		(net "PVCCINFAON_CPU1")
	)
	(segment
		(start 119.268748 -270.167862)
		(end 119.268748 -270.19758)
		(width 0.254)
		(layer "F.Cu")
		(net "PVCCINFAON_CPU1")
	)
	(segment
		(start 122.448066 -218.692476)
		(end 122.447812 -218.692222)
		(width 0.254)
		(layer "F.Cu")
		(net "PVCCINFAON_CPU1")
	)
	(segment
		(start 69.923406 -148.228304)
		(end 70.863714 -147.287996)
		(width 0.508)
		(layer "F.Cu")
		(net "PVCCINFAON_CPU1")
	)
	(segment
		(start 120.208548 -270.167862)
		(end 120.208548 -270.19758)
		(width 0.254)
		(layer "F.Cu")
		(net "PVCCINFAON_CPU1")
	)
	(segment
		(start 121.148094 -264.778236)
		(end 121.148094 -265.313922)
		(width 0.254)
		(layer "F.Cu")
		(net "PVCCINFAON_CPU1")
	)
	(segment
		(start 116.809266 -219.228162)
		(end 116.809266 -218.692476)
		(width 0.254)
		(layer "F.Cu")
		(net "PVCCINFAON_CPU1")
	)
	(segment
		(start 121.148094 -265.313922)
		(end 121.148348 -265.314176)
		(width 0.254)
		(layer "F.Cu")
		(net "PVCCINFAON_CPU1")
	)
	(segment
		(start 105.641648 -264.500106)
		(end 105.641394 -264.50036)
		(width 0.381)
		(layer "F.Cu")
		(net "PVCCINFAON_CPU1")
	)
	(segment
		(start 114.929666 -225.203512)
		(end 114.929412 -225.203258)
		(width 0.254)
		(layer "F.Cu")
		(net "PVCCINFAON_CPU1")
	)
	(segment
		(start 121.618248 -268.84757)
		(end 121.618248 -269.38351)
		(width 0.254)
		(layer "F.Cu")
		(net "PVCCINFAON_CPU1")
	)
	(segment
		(start 116.809266 -228.99497)
		(end 116.809012 -228.994716)
		(width 0.254)
		(layer "F.Cu")
		(net "PVCCINFAON_CPU1")
	)
	(segment
		(start 120.568466 -225.739198)
		(end 120.568466 -225.203512)
		(width 0.254)
		(layer "F.Cu")
		(net "PVCCINFAON_CPU1")
	)
	(segment
		(start 68.983098 -153.424382)
		(end 69.923406 -154.36469)
		(width 0.508)
		(layer "F.Cu")
		(net "PVCCINFAON_CPU1")
	)
	(segment
		(start 120.208294 -266.941554)
		(end 120.208548 -266.941808)
		(width 0.254)
		(layer "F.Cu")
		(net "PVCCINFAON_CPU1")
	)
	(segment
		(start 107.521248 -263.96442)
		(end 107.521248 -264.50036)
		(width 0.381)
		(layer "F.Cu")
		(net "PVCCINFAON_CPU1")
	)
	(segment
		(start 118.798848 -267.219938)
		(end 118.798848 -267.755878)
		(width 0.254)
		(layer "F.Cu")
		(net "PVCCINFAON_CPU1")
	)
	(segment
		(start 118.688866 -218.692476)
		(end 118.688612 -218.692222)
		(width 0.254)
		(layer "F.Cu")
		(net "PVCCINFAON_CPU1")
	)
	(segment
		(start 109.290866 -225.739198)
		(end 109.290866 -225.203512)
		(width 0.254)
		(layer "F.Cu")
		(net "PVCCINFAON_CPU1")
	)
	(segment
		(start 114.929666 -228.99497)
		(end 114.929412 -228.994716)
		(width 0.254)
		(layer "F.Cu")
		(net "PVCCINFAON_CPU1")
	)
	(segment
		(start 126.207266 -221.947994)
		(end 126.207012 -221.94774)
		(width 0.254)
		(layer "F.Cu")
		(net "PVCCINFAON_CPU1")
	)
	(segment
		(start 118.688866 -219.228162)
		(end 118.688866 -218.692476)
		(width 0.254)
		(layer "F.Cu")
		(net "PVCCINFAON_CPU1")
	)
	(segment
		(start 120.568466 -215.437212)
		(end 120.568212 -215.436958)
		(width 0.254)
		(layer "F.Cu")
		(net "PVCCINFAON_CPU1")
	)
	(segment
		(start 106.581448 -263.96442)
		(end 106.581448 -264.500106)
		(width 0.381)
		(layer "F.Cu")
		(net "PVCCINFAON_CPU1")
	)
	(segment
		(start 116.809266 -221.947994)
		(end 116.809012 -221.94774)
		(width 0.254)
		(layer "F.Cu")
		(net "PVCCINFAON_CPU1")
	)
	(segment
		(start 126.207266 -215.972644)
		(end 126.207266 -215.437212)
		(width 0.254)
		(layer "F.Cu")
		(net "PVCCINFAON_CPU1")
	)
	(segment
		(start 68.983098 -147.287996)
		(end 69.923406 -148.228304)
		(width 0.508)
		(layer "F.Cu")
		(net "PVCCINFAON_CPU1")
	)
	(segment
		(start 68.983098 -155.304998)
		(end 69.923406 -154.36469)
		(width 0.508)
		(layer "F.Cu")
		(net "PVCCINFAON_CPU1")
	)
	(segment
		(start 72.88403 -143.769588)
		(end 72.258428 -143.769588)
		(width 0.3556)
		(layer "F.Cu")
		(net "PVCCINFAON_CPU1")
	)
	(segment
		(start 122.087894 -268.033754)
		(end 122.087894 -268.569694)
		(width 0.254)
		(layer "F.Cu")
		(net "PVCCINFAON_CPU1")
	)
	(segment
		(start 118.688866 -225.739198)
		(end 118.688866 -225.203512)
		(width 0.254)
		(layer "F.Cu")
		(net "PVCCINFAON_CPU1")
	)
	(segment
		(start 118.688866 -215.437212)
		(end 118.688612 -215.436958)
		(width 0.254)
		(layer "F.Cu")
		(net "PVCCINFAON_CPU1")
	)
	(segment
		(start 122.448066 -225.739198)
		(end 122.448066 -225.203512)
		(width 0.254)
		(layer "F.Cu")
		(net "PVCCINFAON_CPU1")
	)
	(segment
		(start 121.148094 -268.56944)
		(end 121.148348 -268.569694)
		(width 0.254)
		(layer "F.Cu")
		(net "PVCCINFAON_CPU1")
	)
	(segment
		(start 103.181912 -227.645214)
		(end 103.182166 -227.64496)
		(width 0.254)
		(layer "F.Cu")
		(net "PVCCINFAON_CPU1")
	)
	(segment
		(start 105.531666 -225.203512)
		(end 105.531412 -225.203258)
		(width 0.254)
		(layer "F.Cu")
		(net "PVCCINFAON_CPU1")
	)
	(segment
		(start 122.447812 -215.436958)
		(end 122.447812 -215.436704)
		(width 0.254)
		(layer "F.Cu")
		(net "PVCCINFAON_CPU1")
	)
	(segment
		(start 107.990894 -264.778236)
		(end 107.990894 -265.313922)
		(width 0.254)
		(layer "F.Cu")
		(net "PVCCINFAON_CPU1")
	)
	(segment
		(start 126.207266 -218.692476)
		(end 126.207012 -218.692222)
		(width 0.254)
		(layer "F.Cu")
		(net "PVCCINFAON_CPU1")
	)
	(segment
		(start 124.327666 -218.692476)
		(end 124.327412 -218.692222)
		(width 0.254)
		(layer "F.Cu")
		(net "PVCCINFAON_CPU1")
	)
	(segment
		(start 121.618248 -267.219938)
		(end 121.618248 -267.755878)
		(width 0.254)
		(layer "F.Cu")
		(net "PVCCINFAON_CPU1")
	)
	(segment
		(start 120.568212 -215.436958)
		(end 120.568212 -215.436704)
		(width 0.254)
		(layer "F.Cu")
		(net "PVCCINFAON_CPU1")
	)
	(segment
		(start 124.327666 -225.739198)
		(end 124.327666 -225.203512)
		(width 0.254)
		(layer "F.Cu")
		(net "PVCCINFAON_CPU1")
	)
	(segment
		(start 126.207266 -225.203512)
		(end 126.207012 -225.203258)
		(width 0.254)
		(layer "F.Cu")
		(net "PVCCINFAON_CPU1")
	)
	(segment
		(start 120.568466 -225.203512)
		(end 120.568212 -225.203258)
		(width 0.254)
		(layer "F.Cu")
		(net "PVCCINFAON_CPU1")
	)
	(segment
		(start 119.268494 -266.405868)
		(end 119.268494 -266.941808)
		(width 0.254)
		(layer "F.Cu")
		(net "PVCCINFAON_CPU1")
	)
	(segment
		(start 126.207012 -215.436958)
		(end 126.207012 -215.436704)
		(width 0.254)
		(layer "F.Cu")
		(net "PVCCINFAON_CPU1")
	)
	(segment
		(start 126.207266 -219.228162)
		(end 126.207266 -218.692476)
		(width 0.254)
		(layer "F.Cu")
		(net "PVCCINFAON_CPU1")
	)
	(segment
		(start 69.923406 -160.499806)
		(end 70.939406 -161.515806)
		(width 0.508)
		(layer "F.Cu")
		(net "PVCCINFAON_CPU1")
	)
	(segment
		(start 116.809266 -225.739198)
		(end 116.809266 -225.203512)
		(width 0.254)
		(layer "F.Cu")
		(net "PVCCINFAON_CPU1")
	)
	(segment
		(start 122.448066 -215.437212)
		(end 122.447812 -215.436958)
		(width 0.254)
		(layer "F.Cu")
		(net "PVCCINFAON_CPU1")
	)
	(segment
		(start 109.290866 -225.203512)
		(end 109.290612 -225.203258)
		(width 0.254)
		(layer "F.Cu")
		(net "PVCCINFAON_CPU1")
	)
	(segment
		(start 118.688866 -215.972644)
		(end 118.688866 -215.437212)
		(width 0.254)
		(layer "F.Cu")
		(net "PVCCINFAON_CPU1")
	)
	(segment
		(start 124.327666 -215.437212)
		(end 124.327412 -215.436958)
		(width 0.254)
		(layer "F.Cu")
		(net "PVCCINFAON_CPU1")
	)
	(segment
		(start 107.411266 -225.739198)
		(end 107.411266 -225.203512)
		(width 0.254)
		(layer "F.Cu")
		(net "PVCCINFAON_CPU1")
	)
	(segment
		(start 121.148094 -266.405868)
		(end 121.148094 -266.941808)
		(width 0.254)
		(layer "F.Cu")
		(net "PVCCINFAON_CPU1")
	)
	(segment
		(start 121.618248 -266.127992)
		(end 121.617994 -266.128246)
		(width 0.254)
		(layer "F.Cu")
		(net "PVCCINFAON_CPU1")
	)
	(segment
		(start 124.327412 -215.436958)
		(end 124.327412 -215.436704)
		(width 0.254)
		(layer "F.Cu")
		(net "PVCCINFAON_CPU1")
	)
	(segment
		(start 68.907406 -159.483806)
		(end 69.923406 -160.499806)
		(width 0.508)
		(layer "F.Cu")
		(net "PVCCINFAON_CPU1")
	)
	(segment
		(start 69.153786 -161.269426)
		(end 68.97878 -161.46272)
		(width 0.508)
		(layer "F.Cu")
		(net "PVCCINFAON_CPU1")
	)
	(segment
		(start 120.568466 -218.692476)
		(end 120.568212 -218.692222)
		(width 0.254)
		(layer "F.Cu")
		(net "PVCCINFAON_CPU1")
	)
	(segment
		(start 118.688866 -228.99497)
		(end 118.688612 -228.994716)
		(width 0.254)
		(layer "F.Cu")
		(net "PVCCINFAON_CPU1")
	)
	(segment
		(start 116.809012 -215.97239)
		(end 116.809012 -215.436704)
		(width 0.254)
		(layer "F.Cu")
		(net "PVCCINFAON_CPU1")
	)
	(segment
		(start 122.087894 -269.66164)
		(end 122.088148 -270.167862)
		(width 0.254)
		(layer "F.Cu")
		(net "PVCCINFAON_CPU1")
	)
	(segment
		(start 122.557794 -267.220192)
		(end 122.557794 -267.755878)
		(width 0.254)
		(layer "F.Cu")
		(net "PVCCINFAON_CPU1")
	)
	(segment
		(start 69.923406 -154.36469)
		(end 70.863714 -153.424382)
		(width 0.508)
		(layer "F.Cu")
		(net "PVCCINFAON_CPU1")
	)
	(segment
		(start 120.208294 -266.405868)
		(end 120.208294 -266.941554)
		(width 0.254)
		(layer "F.Cu")
		(net "PVCCINFAON_CPU1")
	)
	(segment
		(start 122.448066 -222.48368)
		(end 122.448066 -221.947994)
		(width 0.254)
		(layer "F.Cu")
		(net "PVCCINFAON_CPU1")
	)
	(segment
		(start 118.688866 -225.203512)
		(end 118.688612 -225.203258)
		(width 0.254)
		(layer "F.Cu")
		(net "PVCCINFAON_CPU1")
	)
	(segment
		(start 113.050066 -225.203512)
		(end 113.049812 -225.203258)
		(width 0.254)
		(layer "F.Cu")
		(net "PVCCINFAON_CPU1")
	)
	(segment
		(start 69.923406 -154.36469)
		(end 70.863714 -155.304998)
		(width 0.508)
		(layer "F.Cu")
		(net "PVCCINFAON_CPU1")
	)
	(segment
		(start 124.327666 -221.947994)
		(end 124.327412 -221.94774)
		(width 0.254)
		(layer "F.Cu")
		(net "PVCCINFAON_CPU1")
	)
	(segment
		(start 124.327666 -222.48368)
		(end 124.327666 -221.947994)
		(width 0.254)
		(layer "F.Cu")
		(net "PVCCINFAON_CPU1")
	)
	(segment
		(start 122.558048 -267.219938)
		(end 122.557794 -267.220192)
		(width 0.254)
		(layer "F.Cu")
		(net "PVCCINFAON_CPU1")
	)
	(segment
		(start 118.688866 -221.947994)
		(end 118.688612 -221.94774)
		(width 0.254)
		(layer "F.Cu")
		(net "PVCCINFAON_CPU1")
	)
	(segment
		(start 119.268494 -269.66164)
		(end 119.268748 -270.167862)
		(width 0.254)
		(layer "F.Cu")
		(net "PVCCINFAON_CPU1")
	)
	(segment
		(start 105.641648 -263.96442)
		(end 105.641648 -264.500106)
		(width 0.381)
		(layer "F.Cu")
		(net "PVCCINFAON_CPU1")
	)
	(segment
		(start 104.701848 -263.96442)
		(end 104.701848 -264.500106)
		(width 0.381)
		(layer "F.Cu")
		(net "PVCCINFAON_CPU1")
	)
	(segment
		(start 122.448066 -225.203512)
		(end 122.447812 -225.203258)
		(width 0.254)
		(layer "F.Cu")
		(net "PVCCINFAON_CPU1")
	)
	(segment
		(start 122.448066 -215.972644)
		(end 122.448066 -215.437212)
		(width 0.254)
		(layer "F.Cu")
		(net "PVCCINFAON_CPU1")
	)
	(segment
		(start 103.181912 -228.1809)
		(end 103.181912 -227.645214)
		(width 0.254)
		(layer "F.Cu")
		(net "PVCCINFAON_CPU1")
	)
	(segment
		(start 122.448066 -230.622602)
		(end 122.447812 -230.622348)
		(width 0.254)
		(layer "F.Cu")
		(net "PVCCINFAON_CPU1")
	)
	(segment
		(start 120.208294 -269.66164)
		(end 120.208548 -270.167862)
		(width 0.254)
		(layer "F.Cu")
		(net "PVCCINFAON_CPU1")
	)
	(segment
		(start 104.701848 -264.500106)
		(end 104.701594 -264.50036)
		(width 0.381)
		(layer "F.Cu")
		(net "PVCCINFAON_CPU1")
	)
	(segment
		(start 124.327666 -219.228162)
		(end 124.327666 -218.692476)
		(width 0.254)
		(layer "F.Cu")
		(net "PVCCINFAON_CPU1")
	)
	(segment
		(start 124.327666 -225.203512)
		(end 124.327412 -225.203258)
		(width 0.254)
		(layer "F.Cu")
		(net "PVCCINFAON_CPU1")
	)
	(segment
		(start 120.678448 -267.219938)
		(end 120.678448 -267.755878)
		(width 0.254)
		(layer "F.Cu")
		(net "PVCCINFAON_CPU1")
	)
	(segment
		(start 116.809266 -222.48368)
		(end 116.809266 -221.947994)
		(width 0.254)
		(layer "F.Cu")
		(net "PVCCINFAON_CPU1")
	)
	(segment
		(start 114.929412 -228.994716)
		(end 114.929412 -228.45903)
		(width 0.254)
		(layer "F.Cu")
		(net "PVCCINFAON_CPU1")
	)
	(segment
		(start 103.652066 -225.203512)
		(end 103.651812 -225.203258)
		(width 0.254)
		(layer "F.Cu")
		(net "PVCCINFAON_CPU1")
	)
	(segment
		(start 118.798848 -268.84757)
		(end 118.798848 -269.38351)
		(width 0.254)
		(layer "F.Cu")
		(net "PVCCINFAON_CPU1")
	)
	(segment
		(start 122.448066 -219.228162)
		(end 122.448066 -218.692476)
		(width 0.254)
		(layer "F.Cu")
		(net "PVCCINFAON_CPU1")
	)
	(segment
		(start 121.618248 -265.592306)
		(end 121.618248 -266.127992)
		(width 0.254)
		(layer "F.Cu")
		(net "PVCCINFAON_CPU1")
	)
	(segment
		(start 122.447812 -230.622348)
		(end 122.447812 -230.086662)
		(width 0.254)
		(layer "F.Cu")
		(net "PVCCINFAON_CPU1")
	)
	(segment
		(start 106.581448 -264.500106)
		(end 106.581194 -264.50036)
		(width 0.381)
		(layer "F.Cu")
		(net "PVCCINFAON_CPU1")
	)
	(segment
		(start 119.738648 -268.84757)
		(end 119.738648 -269.38351)
		(width 0.254)
		(layer "F.Cu")
		(net "PVCCINFAON_CPU1")
	)
	(segment
		(start 107.411266 -225.203512)
		(end 107.411012 -225.203258)
		(width 0.254)
		(layer "F.Cu")
		(net "PVCCINFAON_CPU1")
	)
	(segment
		(start 116.809012 -228.994716)
		(end 116.809012 -228.45903)
		(width 0.254)
		(layer "F.Cu")
		(net "PVCCINFAON_CPU1")
	)
	(segment
		(start 105.531666 -225.739198)
		(end 105.531666 -225.203512)
		(width 0.254)
		(layer "F.Cu")
		(net "PVCCINFAON_CPU1")
	)
	(segment
		(start 124.327666 -215.972644)
		(end 124.327666 -215.437212)
		(width 0.254)
		(layer "F.Cu")
		(net "PVCCINFAON_CPU1")
	)
	(segment
		(start 114.929666 -225.739198)
		(end 114.929666 -225.203512)
		(width 0.254)
		(layer "F.Cu")
		(net "PVCCINFAON_CPU1")
	)
	(segment
		(start 118.688612 -228.994716)
		(end 118.688612 -228.45903)
		(width 0.254)
		(layer "F.Cu")
		(net "PVCCINFAON_CPU1")
	)
	(segment
		(start 121.148094 -268.033754)
		(end 121.148094 -268.56944)
		(width 0.254)
		(layer "F.Cu")
		(net "PVCCINFAON_CPU1")
	)
	(segment
		(start 69.923406 -148.228304)
		(end 70.863714 -149.168612)
		(width 0.508)
		(layer "F.Cu")
		(net "PVCCINFAON_CPU1")
	)
	(segment
		(start 113.050066 -225.739198)
		(end 113.050066 -225.203512)
		(width 0.254)
		(layer "F.Cu")
		(net "PVCCINFAON_CPU1")
	)
	(segment
		(start 122.088148 -270.167862)
		(end 122.088148 -270.19758)
		(width 0.254)
		(layer "F.Cu")
		(net "PVCCINFAON_CPU1")
	)
	(segment
		(start 120.208294 -268.033754)
		(end 120.208294 -268.569694)
		(width 0.254)
		(layer "F.Cu")
		(net "PVCCINFAON_CPU1")
	)
	(segment
		(start 126.207266 -215.437212)
		(end 126.207012 -215.436958)
		(width 0.254)
		(layer "F.Cu")
		(net "PVCCINFAON_CPU1")
	)
	(segment
		(start 116.809266 -225.203512)
		(end 116.809012 -225.203258)
		(width 0.254)
		(layer "F.Cu")
		(net "PVCCINFAON_CPU1")
	)
	(segment
		(start 118.688866 -222.48368)
		(end 118.688866 -221.947994)
		(width 0.254)
		(layer "F.Cu")
		(net "PVCCINFAON_CPU1")
	)
	(segment
		(start 107.990894 -265.313922)
		(end 107.991148 -265.314176)
		(width 0.254)
		(layer "F.Cu")
		(net "PVCCINFAON_CPU1")
	)
	(segment
		(start 119.268494 -268.033754)
		(end 119.268494 -268.569694)
		(width 0.254)
		(layer "F.Cu")
		(net "PVCCINFAON_CPU1")
	)
	(via
		(at 65.24117 -145.28673)
		(size 0.508)
		(drill 0.254)
		(layers "F.Cu" "B.Cu")
		(net "PVCCINFAON_CPU1")
	)
	(via
		(at 68.31711 -150.39721)
		(size 0.508)
		(drill 0.254)
		(layers "F.Cu" "B.Cu")
		(net "PVCCINFAON_CPU1")
	)
	(via
		(at 104.701594 -264.50036)
		(size 0.4572)
		(drill 0.2032)
		(layers "F.Cu" "B.Cu")
		(net "PVCCINFAON_CPU1")
	)
	(via
		(at 64.780922 -160.22828)
		(size 0.508)
		(drill 0.254)
		(layers "F.Cu" "B.Cu")
		(net "PVCCINFAON_CPU1")
	)
	(via
		(at 121.148348 -270.19758)
		(size 0.4572)
		(drill 0.2032)
		(layers "F.Cu" "B.Cu")
		(net "PVCCINFAON_CPU1")
	)
	(via
		(at 68.33235 -149.74951)
		(size 0.508)
		(drill 0.254)
		(layers "F.Cu" "B.Cu")
		(net "PVCCINFAON_CPU1")
	)
	(via
		(at 67.04711 -150.39721)
		(size 0.508)
		(drill 0.254)
		(layers "F.Cu" "B.Cu")
		(net "PVCCINFAON_CPU1")
	)
	(via
		(at 118.728744 -235.102908)
		(size 0.6604)
		(drill 0.3302)
		(layers "F.Cu" "B.Cu")
		(net "PVCCINFAON_CPU1")
	)
	(via
		(at 119.516144 -235.800646)
		(size 0.4572)
		(drill 0.2032)
		(layers "F.Cu" "B.Cu")
		(net "PVCCINFAON_CPU1")
	)
	(via
		(at 75.352656 -156.624782)
		(size 0.6604)
		(drill 0.3302)
		(layers "F.Cu" "B.Cu")
		(net "PVCCINFAON_CPU1")
	)
	(via
		(at 67.68973 -155.20797)
		(size 0.508)
		(drill 0.254)
		(layers "F.Cu" "B.Cu")
		(net "PVCCINFAON_CPU1")
	)
	(via
		(at 66.41973 -151.03475)
		(size 0.508)
		(drill 0.254)
		(layers "F.Cu" "B.Cu")
		(net "PVCCINFAON_CPU1")
	)
	(via
		(at 120.568212 -225.203258)
		(size 0.4572)
		(drill 0.2032)
		(layers "F.Cu" "B.Cu")
		(net "PVCCINFAON_CPU1")
	)
	(via
		(at 117.763544 -235.800646)
		(size 0.4572)
		(drill 0.2032)
		(layers "F.Cu" "B.Cu")
		(net "PVCCINFAON_CPU1")
	)
	(via
		(at 114.929412 -225.203258)
		(size 0.4572)
		(drill 0.2032)
		(layers "F.Cu" "B.Cu")
		(net "PVCCINFAON_CPU1")
	)
	(via
		(at 107.411012 -225.203258)
		(size 0.4572)
		(drill 0.2032)
		(layers "F.Cu" "B.Cu")
		(net "PVCCINFAON_CPU1")
	)
	(via
		(at 75.444096 -153.297382)
		(size 0.6604)
		(drill 0.3302)
		(layers "F.Cu" "B.Cu")
		(net "PVCCINFAON_CPU1")
	)
	(via
		(at 66.42735 -153.28773)
		(size 0.508)
		(drill 0.254)
		(layers "F.Cu" "B.Cu")
		(net "PVCCINFAON_CPU1")
	)
	(via
		(at 122.447812 -215.436704)
		(size 0.4572)
		(drill 0.2032)
		(layers "F.Cu" "B.Cu")
		(net "PVCCINFAON_CPU1")
	)
	(via
		(at 67.03949 -151.68245)
		(size 0.508)
		(drill 0.254)
		(layers "F.Cu" "B.Cu")
		(net "PVCCINFAON_CPU1")
	)
	(via
		(at 66.41211 -150.39721)
		(size 0.508)
		(drill 0.254)
		(layers "F.Cu" "B.Cu")
		(net "PVCCINFAON_CPU1")
	)
	(via
		(at 126.207012 -218.692222)
		(size 0.4572)
		(drill 0.2032)
		(layers "F.Cu" "B.Cu")
		(net "PVCCINFAON_CPU1")
	)
	(via
		(at 67.70497 -144.00149)
		(size 0.508)
		(drill 0.254)
		(layers "F.Cu" "B.Cu")
		(net "PVCCINFAON_CPU1")
	)
	(via
		(at 65.441322 -151.59228)
		(size 0.508)
		(drill 0.254)
		(layers "F.Cu" "B.Cu")
		(net "PVCCINFAON_CPU1")
	)
	(via
		(at 120.208548 -266.941808)
		(size 0.4572)
		(drill 0.2032)
		(layers "F.Cu" "B.Cu")
		(net "PVCCINFAON_CPU1")
	)
	(via
		(at 116.809012 -228.45903)
		(size 0.4572)
		(drill 0.2032)
		(layers "F.Cu" "B.Cu")
		(net "PVCCINFAON_CPU1")
	)
	(via
		(at 122.447812 -225.203258)
		(size 0.4572)
		(drill 0.2032)
		(layers "F.Cu" "B.Cu")
		(net "PVCCINFAON_CPU1")
	)
	(via
		(at 67.04711 -159.03321)
		(size 0.508)
		(drill 0.254)
		(layers "F.Cu" "B.Cu")
		(net "PVCCINFAON_CPU1")
	)
	(via
		(at 64.61379 -154.63647)
		(size 0.508)
		(drill 0.254)
		(layers "F.Cu" "B.Cu")
		(net "PVCCINFAON_CPU1")
	)
	(via
		(at 124.327412 -215.436704)
		(size 0.4572)
		(drill 0.2032)
		(layers "F.Cu" "B.Cu")
		(net "PVCCINFAON_CPU1")
	)
	(via
		(at 66.43497 -144.00149)
		(size 0.508)
		(drill 0.254)
		(layers "F.Cu" "B.Cu")
		(net "PVCCINFAON_CPU1")
	)
	(via
		(at 68.33997 -145.92427)
		(size 0.508)
		(drill 0.254)
		(layers "F.Cu" "B.Cu")
		(net "PVCCINFAON_CPU1")
	)
	(via
		(at 66.41973 -157.74797)
		(size 0.508)
		(drill 0.254)
		(layers "F.Cu" "B.Cu")
		(net "PVCCINFAON_CPU1")
	)
	(via
		(at 67.68973 -151.03475)
		(size 0.508)
		(drill 0.254)
		(layers "F.Cu" "B.Cu")
		(net "PVCCINFAON_CPU1")
	)
	(via
		(at 122.447812 -218.692222)
		(size 0.4572)
		(drill 0.2032)
		(layers "F.Cu" "B.Cu")
		(net "PVCCINFAON_CPU1")
	)
	(via
		(at 118.798848 -269.38351)
		(size 0.4572)
		(drill 0.2032)
		(layers "F.Cu" "B.Cu")
		(net "PVCCINFAON_CPU1")
	)
	(via
		(at 65.441322 -159.56788)
		(size 0.508)
		(drill 0.254)
		(layers "F.Cu" "B.Cu")
		(net "PVCCINFAON_CPU1")
	)
	(via
		(at 67.05473 -157.74797)
		(size 0.508)
		(drill 0.254)
		(layers "F.Cu" "B.Cu")
		(net "PVCCINFAON_CPU1")
	)
	(via
		(at 116.809012 -215.436704)
		(size 0.4572)
		(drill 0.2032)
		(layers "F.Cu" "B.Cu")
		(net "PVCCINFAON_CPU1")
	)
	(via
		(at 107.991148 -265.314176)
		(size 0.4572)
		(drill 0.2032)
		(layers "F.Cu" "B.Cu")
		(net "PVCCINFAON_CPU1")
	)
	(via
		(at 106.581194 -264.50036)
		(size 0.4572)
		(drill 0.2032)
		(layers "F.Cu" "B.Cu")
		(net "PVCCINFAON_CPU1")
	)
	(via
		(at 64.60617 -149.66569)
		(size 0.508)
		(drill 0.254)
		(layers "F.Cu" "B.Cu")
		(net "PVCCINFAON_CPU1")
	)
	(via
		(at 67.06235 -153.92273)
		(size 0.508)
		(drill 0.254)
		(layers "F.Cu" "B.Cu")
		(net "PVCCINFAON_CPU1")
	)
	(via
		(at 67.68211 -150.39721)
		(size 0.508)
		(drill 0.254)
		(layers "F.Cu" "B.Cu")
		(net "PVCCINFAON_CPU1")
	)
	(via
		(at 120.208294 -268.569694)
		(size 0.4572)
		(drill 0.2032)
		(layers "F.Cu" "B.Cu")
		(net "PVCCINFAON_CPU1")
	)
	(via
		(at 119.738648 -269.38351)
		(size 0.4572)
		(drill 0.2032)
		(layers "F.Cu" "B.Cu")
		(net "PVCCINFAON_CPU1")
	)
	(via
		(at 68.33235 -145.28673)
		(size 0.508)
		(drill 0.254)
		(layers "F.Cu" "B.Cu")
		(net "PVCCINFAON_CPU1")
	)
	(via
		(at 120.98655 -261.49173)
		(size 0.4572)
		(drill 0.2032)
		(layers "F.Cu" "B.Cu")
		(net "PVCCINFAON_CPU1")
	)
	(via
		(at 68.30949 -151.68245)
		(size 0.508)
		(drill 0.254)
		(layers "F.Cu" "B.Cu")
		(net "PVCCINFAON_CPU1")
	)
	(via
		(at 65.24879 -146.00047)
		(size 0.508)
		(drill 0.254)
		(layers "F.Cu" "B.Cu")
		(net "PVCCINFAON_CPU1")
	)
	(via
		(at 67.68973 -157.74797)
		(size 0.508)
		(drill 0.254)
		(layers "F.Cu" "B.Cu")
		(net "PVCCINFAON_CPU1")
	)
	(via
		(at 122.447812 -230.086662)
		(size 0.4572)
		(drill 0.2032)
		(layers "F.Cu" "B.Cu")
		(net "PVCCINFAON_CPU1")
	)
	(via
		(at 66.42735 -145.28673)
		(size 0.508)
		(drill 0.254)
		(layers "F.Cu" "B.Cu")
		(net "PVCCINFAON_CPU1")
	)
	(via
		(at 68.33235 -158.38551)
		(size 0.508)
		(drill 0.254)
		(layers "F.Cu" "B.Cu")
		(net "PVCCINFAON_CPU1")
	)
	(via
		(at 116.595144 -235.800646)
		(size 0.4572)
		(drill 0.2032)
		(layers "F.Cu" "B.Cu")
		(net "PVCCINFAON_CPU1")
	)
	(via
		(at 63.97117 -149.66569)
		(size 0.508)
		(drill 0.254)
		(layers "F.Cu" "B.Cu")
		(net "PVCCINFAON_CPU1")
	)
	(via
		(at 126.207012 -215.436704)
		(size 0.4572)
		(drill 0.2032)
		(layers "F.Cu" "B.Cu")
		(net "PVCCINFAON_CPU1")
	)
	(via
		(at 66.43497 -145.92427)
		(size 0.508)
		(drill 0.254)
		(layers "F.Cu" "B.Cu")
		(net "PVCCINFAON_CPU1")
	)
	(via
		(at 120.678448 -267.755878)
		(size 0.4572)
		(drill 0.2032)
		(layers "F.Cu" "B.Cu")
		(net "PVCCINFAON_CPU1")
	)
	(via
		(at 121.618248 -267.755878)
		(size 0.4572)
		(drill 0.2032)
		(layers "F.Cu" "B.Cu")
		(net "PVCCINFAON_CPU1")
	)
	(via
		(at 66.42735 -153.92273)
		(size 0.508)
		(drill 0.254)
		(layers "F.Cu" "B.Cu")
		(net "PVCCINFAON_CPU1")
	)
	(via
		(at 113.049812 -225.203258)
		(size 0.4572)
		(drill 0.2032)
		(layers "F.Cu" "B.Cu")
		(net "PVCCINFAON_CPU1")
	)
	(via
		(at 66.41211 -159.03321)
		(size 0.508)
		(drill 0.254)
		(layers "F.Cu" "B.Cu")
		(net "PVCCINFAON_CPU1")
	)
	(via
		(at 65.24117 -153.92273)
		(size 0.508)
		(drill 0.254)
		(layers "F.Cu" "B.Cu")
		(net "PVCCINFAON_CPU1")
	)
	(via
		(at 124.327412 -225.203258)
		(size 0.4572)
		(drill 0.2032)
		(layers "F.Cu" "B.Cu")
		(net "PVCCINFAON_CPU1")
	)
	(via
		(at 120.98655 -262.07593)
		(size 0.4572)
		(drill 0.2032)
		(layers "F.Cu" "B.Cu")
		(net "PVCCINFAON_CPU1")
	)
	(via
		(at 67.69735 -149.74951)
		(size 0.508)
		(drill 0.254)
		(layers "F.Cu" "B.Cu")
		(net "PVCCINFAON_CPU1")
	)
	(via
		(at 116.809012 -218.692222)
		(size 0.4572)
		(drill 0.2032)
		(layers "F.Cu" "B.Cu")
		(net "PVCCINFAON_CPU1")
	)
	(via
		(at 67.06235 -158.38551)
		(size 0.508)
		(drill 0.254)
		(layers "F.Cu" "B.Cu")
		(net "PVCCINFAON_CPU1")
	)
	(via
		(at 122.087894 -268.569694)
		(size 0.4572)
		(drill 0.2032)
		(layers "F.Cu" "B.Cu")
		(net "PVCCINFAON_CPU1")
	)
	(via
		(at 65.441322 -150.93188)
		(size 0.508)
		(drill 0.254)
		(layers "F.Cu" "B.Cu")
		(net "PVCCINFAON_CPU1")
	)
	(via
		(at 66.42735 -149.74951)
		(size 0.508)
		(drill 0.254)
		(layers "F.Cu" "B.Cu")
		(net "PVCCINFAON_CPU1")
	)
	(via
		(at 67.70497 -154.56027)
		(size 0.508)
		(drill 0.254)
		(layers "F.Cu" "B.Cu")
		(net "PVCCINFAON_CPU1")
	)
	(via
		(at 118.688612 -228.45903)
		(size 0.4572)
		(drill 0.2032)
		(layers "F.Cu" "B.Cu")
		(net "PVCCINFAON_CPU1")
	)
	(via
		(at 124.327412 -218.692222)
		(size 0.4572)
		(drill 0.2032)
		(layers "F.Cu" "B.Cu")
		(net "PVCCINFAON_CPU1")
	)
	(via
		(at 68.31711 -159.03321)
		(size 0.508)
		(drill 0.254)
		(layers "F.Cu" "B.Cu")
		(net "PVCCINFAON_CPU1")
	)
	(via
		(at 64.780922 -150.93188)
		(size 0.508)
		(drill 0.254)
		(layers "F.Cu" "B.Cu")
		(net "PVCCINFAON_CPU1")
	)
	(via
		(at 122.447812 -221.94774)
		(size 0.4572)
		(drill 0.2032)
		(layers "F.Cu" "B.Cu")
		(net "PVCCINFAON_CPU1")
	)
	(via
		(at 67.69735 -153.28773)
		(size 0.508)
		(drill 0.254)
		(layers "F.Cu" "B.Cu")
		(net "PVCCINFAON_CPU1")
	)
	(via
		(at 120.568212 -221.94774)
		(size 0.4572)
		(drill 0.2032)
		(layers "F.Cu" "B.Cu")
		(net "PVCCINFAON_CPU1")
	)
	(via
		(at 63.97879 -146.00047)
		(size 0.508)
		(drill 0.254)
		(layers "F.Cu" "B.Cu")
		(net "PVCCINFAON_CPU1")
	)
	(via
		(at 103.182166 -227.64496)
		(size 0.4572)
		(drill 0.2032)
		(layers "F.Cu" "B.Cu")
		(net "PVCCINFAON_CPU1")
	)
	(via
		(at 67.06235 -153.28773)
		(size 0.508)
		(drill 0.254)
		(layers "F.Cu" "B.Cu")
		(net "PVCCINFAON_CPU1")
	)
	(via
		(at 64.780922 -159.56788)
		(size 0.508)
		(drill 0.254)
		(layers "F.Cu" "B.Cu")
		(net "PVCCINFAON_CPU1")
	)
	(via
		(at 67.05473 -151.03475)
		(size 0.508)
		(drill 0.254)
		(layers "F.Cu" "B.Cu")
		(net "PVCCINFAON_CPU1")
	)
	(via
		(at 118.688612 -218.692222)
		(size 0.4572)
		(drill 0.2032)
		(layers "F.Cu" "B.Cu")
		(net "PVCCINFAON_CPU1")
	)
	(via
		(at 121.148094 -266.941808)
		(size 0.4572)
		(drill 0.2032)
		(layers "F.Cu" "B.Cu")
		(net "PVCCINFAON_CPU1")
	)
	(via
		(at 67.06997 -144.00149)
		(size 0.508)
		(drill 0.254)
		(layers "F.Cu" "B.Cu")
		(net "PVCCINFAON_CPU1")
	)
	(via
		(at 105.531412 -225.203258)
		(size 0.4572)
		(drill 0.2032)
		(layers "F.Cu" "B.Cu")
		(net "PVCCINFAON_CPU1")
	)
	(via
		(at 65.441322 -160.22828)
		(size 0.508)
		(drill 0.254)
		(layers "F.Cu" "B.Cu")
		(net "PVCCINFAON_CPU1")
	)
	(via
		(at 114.929412 -228.45903)
		(size 0.4572)
		(drill 0.2032)
		(layers "F.Cu" "B.Cu")
		(net "PVCCINFAON_CPU1")
	)
	(via
		(at 63.4492 -143.068548)
		(size 0.508)
		(drill 0.254)
		(layers "F.Cu" "B.Cu")
		(net "PVCCINFAON_CPU1")
	)
	(via
		(at 67.68973 -144.64919)
		(size 0.508)
		(drill 0.254)
		(layers "F.Cu" "B.Cu")
		(net "PVCCINFAON_CPU1")
	)
	(via
		(at 109.290612 -225.203258)
		(size 0.4572)
		(drill 0.2032)
		(layers "F.Cu" "B.Cu")
		(net "PVCCINFAON_CPU1")
	)
	(via
		(at 119.268494 -266.941808)
		(size 0.4572)
		(drill 0.2032)
		(layers "F.Cu" "B.Cu")
		(net "PVCCINFAON_CPU1")
	)
	(via
		(at 117.179344 -235.800646)
		(size 0.4572)
		(drill 0.2032)
		(layers "F.Cu" "B.Cu")
		(net "PVCCINFAON_CPU1")
	)
	(via
		(at 66.43497 -154.56027)
		(size 0.508)
		(drill 0.254)
		(layers "F.Cu" "B.Cu")
		(net "PVCCINFAON_CPU1")
	)
	(via
		(at 64.780922 -151.59228)
		(size 0.508)
		(drill 0.254)
		(layers "F.Cu" "B.Cu")
		(net "PVCCINFAON_CPU1")
	)
	(via
		(at 68.33235 -153.92273)
		(size 0.508)
		(drill 0.254)
		(layers "F.Cu" "B.Cu")
		(net "PVCCINFAON_CPU1")
	)
	(via
		(at 120.568212 -218.692222)
		(size 0.4572)
		(drill 0.2032)
		(layers "F.Cu" "B.Cu")
		(net "PVCCINFAON_CPU1")
	)
	(via
		(at 119.268748 -270.19758)
		(size 0.4572)
		(drill 0.2032)
		(layers "F.Cu" "B.Cu")
		(net "PVCCINFAON_CPU1")
	)
	(via
		(at 118.688612 -225.203258)
		(size 0.4572)
		(drill 0.2032)
		(layers "F.Cu" "B.Cu")
		(net "PVCCINFAON_CPU1")
	)
	(via
		(at 68.33235 -153.28773)
		(size 0.508)
		(drill 0.254)
		(layers "F.Cu" "B.Cu")
		(net "PVCCINFAON_CPU1")
	)
	(via
		(at 64.61379 -146.00047)
		(size 0.508)
		(drill 0.254)
		(layers "F.Cu" "B.Cu")
		(net "PVCCINFAON_CPU1")
	)
	(via
		(at 67.06235 -149.74951)
		(size 0.508)
		(drill 0.254)
		(layers "F.Cu" "B.Cu")
		(net "PVCCINFAON_CPU1")
	)
	(via
		(at 121.148348 -265.314176)
		(size 0.4572)
		(drill 0.2032)
		(layers "F.Cu" "B.Cu")
		(net "PVCCINFAON_CPU1")
	)
	(via
		(at 67.05473 -155.20797)
		(size 0.508)
		(drill 0.254)
		(layers "F.Cu" "B.Cu")
		(net "PVCCINFAON_CPU1")
	)
	(via
		(at 119.563896 -261.322058)
		(size 0.4572)
		(drill 0.2032)
		(layers "F.Cu" "B.Cu")
		(net "PVCCINFAON_CPU1")
	)
	(via
		(at 67.69735 -145.28673)
		(size 0.508)
		(drill 0.254)
		(layers "F.Cu" "B.Cu")
		(net "PVCCINFAON_CPU1")
	)
	(via
		(at 68.32473 -157.74797)
		(size 0.508)
		(drill 0.254)
		(layers "F.Cu" "B.Cu")
		(net "PVCCINFAON_CPU1")
	)
	(via
		(at 67.06997 -154.56027)
		(size 0.508)
		(drill 0.254)
		(layers "F.Cu" "B.Cu")
		(net "PVCCINFAON_CPU1")
	)
	(via
		(at 67.06997 -145.92427)
		(size 0.508)
		(drill 0.254)
		(layers "F.Cu" "B.Cu")
		(net "PVCCINFAON_CPU1")
	)
	(via
		(at 67.67449 -151.68245)
		(size 0.508)
		(drill 0.254)
		(layers "F.Cu" "B.Cu")
		(net "PVCCINFAON_CPU1")
	)
	(via
		(at 67.05473 -144.64919)
		(size 0.508)
		(drill 0.254)
		(layers "F.Cu" "B.Cu")
		(net "PVCCINFAON_CPU1")
	)
	(via
		(at 121.617994 -266.128246)
		(size 0.4572)
		(drill 0.2032)
		(layers "F.Cu" "B.Cu")
		(net "PVCCINFAON_CPU1")
	)
	(via
		(at 118.931944 -235.800646)
		(size 0.4572)
		(drill 0.2032)
		(layers "F.Cu" "B.Cu")
		(net "PVCCINFAON_CPU1")
	)
	(via
		(at 126.207012 -221.94774)
		(size 0.4572)
		(drill 0.2032)
		(layers "F.Cu" "B.Cu")
		(net "PVCCINFAON_CPU1")
	)
	(via
		(at 65.24117 -149.66569)
		(size 0.508)
		(drill 0.254)
		(layers "F.Cu" "B.Cu")
		(net "PVCCINFAON_CPU1")
	)
	(via
		(at 65.24879 -154.63647)
		(size 0.508)
		(drill 0.254)
		(layers "F.Cu" "B.Cu")
		(net "PVCCINFAON_CPU1")
	)
	(via
		(at 72.258428 -143.769588)
		(size 0.508)
		(drill 0.254)
		(layers "F.Cu" "B.Cu")
		(net "PVCCINFAON_CPU1")
	)
	(via
		(at 66.40449 -151.68245)
		(size 0.508)
		(drill 0.254)
		(layers "F.Cu" "B.Cu")
		(net "PVCCINFAON_CPU1")
	)
	(via
		(at 119.268494 -268.569694)
		(size 0.4572)
		(drill 0.2032)
		(layers "F.Cu" "B.Cu")
		(net "PVCCINFAON_CPU1")
	)
	(via
		(at 64.60617 -158.30931)
		(size 0.508)
		(drill 0.254)
		(layers "F.Cu" "B.Cu")
		(net "PVCCINFAON_CPU1")
	)
	(via
		(at 63.97879 -154.63647)
		(size 0.508)
		(drill 0.254)
		(layers "F.Cu" "B.Cu")
		(net "PVCCINFAON_CPU1")
	)
	(via
		(at 118.347744 -235.800646)
		(size 0.4572)
		(drill 0.2032)
		(layers "F.Cu" "B.Cu")
		(net "PVCCINFAON_CPU1")
	)
	(via
		(at 122.088148 -270.19758)
		(size 0.4572)
		(drill 0.2032)
		(layers "F.Cu" "B.Cu")
		(net "PVCCINFAON_CPU1")
	)
	(via
		(at 67.68211 -159.03321)
		(size 0.508)
		(drill 0.254)
		(layers "F.Cu" "B.Cu")
		(net "PVCCINFAON_CPU1")
	)
	(via
		(at 120.568212 -215.436704)
		(size 0.4572)
		(drill 0.2032)
		(layers "F.Cu" "B.Cu")
		(net "PVCCINFAON_CPU1")
	)
	(via
		(at 105.641394 -264.50036)
		(size 0.4572)
		(drill 0.2032)
		(layers "F.Cu" "B.Cu")
		(net "PVCCINFAON_CPU1")
	)
	(via
		(at 67.69735 -158.38551)
		(size 0.508)
		(drill 0.254)
		(layers "F.Cu" "B.Cu")
		(net "PVCCINFAON_CPU1")
	)
	(via
		(at 66.41973 -155.20797)
		(size 0.508)
		(drill 0.254)
		(layers "F.Cu" "B.Cu")
		(net "PVCCINFAON_CPU1")
	)
	(via
		(at 118.798848 -267.755878)
		(size 0.4572)
		(drill 0.2032)
		(layers "F.Cu" "B.Cu")
		(net "PVCCINFAON_CPU1")
	)
	(via
		(at 103.651812 -225.203258)
		(size 0.4572)
		(drill 0.2032)
		(layers "F.Cu" "B.Cu")
		(net "PVCCINFAON_CPU1")
	)
	(via
		(at 66.41973 -144.64919)
		(size 0.508)
		(drill 0.254)
		(layers "F.Cu" "B.Cu")
		(net "PVCCINFAON_CPU1")
	)
	(via
		(at 107.521248 -264.50036)
		(size 0.4572)
		(drill 0.2032)
		(layers "F.Cu" "B.Cu")
		(net "PVCCINFAON_CPU1")
	)
	(via
		(at 67.69735 -153.92273)
		(size 0.508)
		(drill 0.254)
		(layers "F.Cu" "B.Cu")
		(net "PVCCINFAON_CPU1")
	)
	(via
		(at 122.557794 -267.755878)
		(size 0.4572)
		(drill 0.2032)
		(layers "F.Cu" "B.Cu")
		(net "PVCCINFAON_CPU1")
	)
	(via
		(at 67.70497 -145.92427)
		(size 0.508)
		(drill 0.254)
		(layers "F.Cu" "B.Cu")
		(net "PVCCINFAON_CPU1")
	)
	(via
		(at 116.809012 -225.203258)
		(size 0.4572)
		(drill 0.2032)
		(layers "F.Cu" "B.Cu")
		(net "PVCCINFAON_CPU1")
	)
	(via
		(at 51.393852 -153.097484)
		(size 0.508)
		(drill 0.254)
		(layers "F.Cu" "B.Cu")
		(net "PVCCINFAON_CPU1")
	)
	(via
		(at 118.688612 -221.94774)
		(size 0.4572)
		(drill 0.2032)
		(layers "F.Cu" "B.Cu")
		(net "PVCCINFAON_CPU1")
	)
	(via
		(at 68.33997 -154.56027)
		(size 0.508)
		(drill 0.254)
		(layers "F.Cu" "B.Cu")
		(net "PVCCINFAON_CPU1")
	)
	(via
		(at 118.688612 -215.436704)
		(size 0.4572)
		(drill 0.2032)
		(layers "F.Cu" "B.Cu")
		(net "PVCCINFAON_CPU1")
	)
	(via
		(at 126.207012 -225.203258)
		(size 0.4572)
		(drill 0.2032)
		(layers "F.Cu" "B.Cu")
		(net "PVCCINFAON_CPU1")
	)
	(via
		(at 68.32473 -155.20797)
		(size 0.508)
		(drill 0.254)
		(layers "F.Cu" "B.Cu")
		(net "PVCCINFAON_CPU1")
	)
	(via
		(at 116.809012 -221.94774)
		(size 0.4572)
		(drill 0.2032)
		(layers "F.Cu" "B.Cu")
		(net "PVCCINFAON_CPU1")
	)
	(via
		(at 120.98655 -260.90753)
		(size 0.4572)
		(drill 0.2032)
		(layers "F.Cu" "B.Cu")
		(net "PVCCINFAON_CPU1")
	)
	(via
		(at 121.148348 -268.569694)
		(size 0.4572)
		(drill 0.2032)
		(layers "F.Cu" "B.Cu")
		(net "PVCCINFAON_CPU1")
	)
	(via
		(at 65.24117 -153.28773)
		(size 0.508)
		(drill 0.254)
		(layers "F.Cu" "B.Cu")
		(net "PVCCINFAON_CPU1")
	)
	(via
		(at 121.618248 -269.38351)
		(size 0.4572)
		(drill 0.2032)
		(layers "F.Cu" "B.Cu")
		(net "PVCCINFAON_CPU1")
	)
	(via
		(at 68.32473 -144.64919)
		(size 0.508)
		(drill 0.254)
		(layers "F.Cu" "B.Cu")
		(net "PVCCINFAON_CPU1")
	)
	(via
		(at 63.97117 -158.30931)
		(size 0.508)
		(drill 0.254)
		(layers "F.Cu" "B.Cu")
		(net "PVCCINFAON_CPU1")
	)
	(via
		(at 65.24117 -158.30931)
		(size 0.508)
		(drill 0.254)
		(layers "F.Cu" "B.Cu")
		(net "PVCCINFAON_CPU1")
	)
	(via
		(at 67.06235 -145.28673)
		(size 0.508)
		(drill 0.254)
		(layers "F.Cu" "B.Cu")
		(net "PVCCINFAON_CPU1")
	)
	(via
		(at 51.393852 -144.461484)
		(size 0.508)
		(drill 0.254)
		(layers "F.Cu" "B.Cu")
		(net "PVCCINFAON_CPU1")
	)
	(via
		(at 124.327412 -221.94774)
		(size 0.4572)
		(drill 0.2032)
		(layers "F.Cu" "B.Cu")
		(net "PVCCINFAON_CPU1")
	)
	(via
		(at 68.33997 -144.00149)
		(size 0.508)
		(drill 0.254)
		(layers "F.Cu" "B.Cu")
		(net "PVCCINFAON_CPU1")
	)
	(via
		(at 120.208548 -270.19758)
		(size 0.4572)
		(drill 0.2032)
		(layers "F.Cu" "B.Cu")
		(net "PVCCINFAON_CPU1")
	)
	(via
		(at 66.42735 -158.38551)
		(size 0.508)
		(drill 0.254)
		(layers "F.Cu" "B.Cu")
		(net "PVCCINFAON_CPU1")
	)
	(via
		(at 68.32473 -151.03475)
		(size 0.508)
		(drill 0.254)
		(layers "F.Cu" "B.Cu")
		(net "PVCCINFAON_CPU1")
	)
	(segment
		(start 68.983098 -155.304998)
		(end 69.923406 -154.36469)
		(width 0.508)
		(layer "B.Cu")
		(net "PVCCINFAON_CPU1")
	)
	(segment
		(start 68.983098 -149.168612)
		(end 69.923406 -148.228304)
		(width 0.508)
		(layer "B.Cu")
		(net "PVCCINFAON_CPU1")
	)
	(segment
		(start 51.444652 -153.046684)
		(end 51.515264 -153.046684)
		(width 0.254)
		(layer "B.Cu")
		(net "PVCCINFAON_CPU1")
	)
	(segment
		(start 51.393852 -144.461484)
		(end 51.55311 -144.302226)
		(width 0.254)
		(layer "B.Cu")
		(net "PVCCINFAON_CPU1")
	)
	(segment
		(start 69.923406 -160.499806)
		(end 70.863714 -161.440114)
		(width 0.508)
		(layer "B.Cu")
		(net "PVCCINFAON_CPU1")
	)
	(segment
		(start 69.169026 -161.254186)
		(end 69.923406 -160.499806)
		(width 0.508)
		(layer "B.Cu")
		(net "PVCCINFAON_CPU1")
	)
	(segment
		(start 69.923406 -154.36469)
		(end 70.863714 -155.304998)
		(width 0.508)
		(layer "B.Cu")
		(net "PVCCINFAON_CPU1")
	)
	(segment
		(start 68.983098 -159.559498)
		(end 69.923406 -160.499806)
		(width 0.508)
		(layer "B.Cu")
		(net "PVCCINFAON_CPU1")
	)
	(segment
		(start 69.923406 -160.499806)
		(end 70.863714 -159.559498)
		(width 0.508)
		(layer "B.Cu")
		(net "PVCCINFAON_CPU1")
	)
	(segment
		(start 51.55311 -144.302226)
		(end 51.55311 -143.759428)
		(width 0.254)
		(layer "B.Cu")
		(net "PVCCINFAON_CPU1")
	)
	(segment
		(start 69.00672 -161.45256)
		(end 69.169026 -161.254186)
		(width 0.508)
		(layer "B.Cu")
		(net "PVCCINFAON_CPU1")
	)
	(segment
		(start 69.923406 -148.228304)
		(end 70.863714 -149.168612)
		(width 0.508)
		(layer "B.Cu")
		(net "PVCCINFAON_CPU1")
	)
	(segment
		(start 68.983098 -147.287996)
		(end 69.923406 -148.228304)
		(width 0.508)
		(layer "B.Cu")
		(net "PVCCINFAON_CPU1")
	)
	(segment
		(start 69.923406 -154.36469)
		(end 70.863714 -153.424382)
		(width 0.508)
		(layer "B.Cu")
		(net "PVCCINFAON_CPU1")
	)
	(segment
		(start 51.393852 -153.097484)
		(end 51.444652 -153.046684)
		(width 0.254)
		(layer "B.Cu")
		(net "PVCCINFAON_CPU1")
	)
	(segment
		(start 68.983098 -153.424382)
		(end 69.923406 -154.36469)
		(width 0.508)
		(layer "B.Cu")
		(net "PVCCINFAON_CPU1")
	)
	(segment
		(start 51.515264 -153.046684)
		(end 51.958494 -152.603454)
		(width 0.254)
		(layer "B.Cu")
		(net "PVCCINFAON_CPU1")
	)
	(segment
		(start 69.923406 -148.228304)
		(end 70.863714 -147.287996)
		(width 0.508)
		(layer "B.Cu")
		(net "PVCCINFAON_CPU1")
	)
	(segment
		(start 53.269388 -153.685748)
		(end 59.1312 -153.685748)
		(width 0.381)
		(layer "In2.Cu")
		(net "PVCCINFAON_CPU1")
	)
	(segment
		(start 59.954922 -146.00047)
		(end 59.1058 -145.151348)
		(width 0.381)
		(layer "In2.Cu")
		(net "PVCCINFAON_CPU1")
	)
	(segment
		(start 51.393852 -153.097484)
		(end 51.489864 -153.097484)
		(width 0.381)
		(layer "In2.Cu")
		(net "PVCCINFAON_CPU1")
	)
	(segment
		(start 52.298346 -144.19199)
		(end 51.759358 -144.19199)
		(width 0.381)
		(layer "In2.Cu")
		(net "PVCCINFAON_CPU1")
	)
	(segment
		(start 63.975234 -154.63647)
		(end 63.97879 -154.63647)
		(width 0.381)
		(layer "In2.Cu")
		(net "PVCCINFAON_CPU1")
	)
	(segment
		(start 59.1312 -153.685748)
		(end 60.0456 -154.600148)
		(width 0.381)
		(layer "In2.Cu")
		(net "PVCCINFAON_CPU1")
	)
	(segment
		(start 51.489864 -144.461484)
		(end 51.393852 -144.461484)
		(width 0.381)
		(layer "In2.Cu")
		(net "PVCCINFAON_CPU1")
	)
	(segment
		(start 63.97879 -146.00047)
		(end 59.954922 -146.00047)
		(width 0.381)
		(layer "In2.Cu")
		(net "PVCCINFAON_CPU1")
	)
	(segment
		(start 52.354988 -152.771348)
		(end 53.269388 -153.685748)
		(width 0.381)
		(layer "In2.Cu")
		(net "PVCCINFAON_CPU1")
	)
	(segment
		(start 51.816 -152.771348)
		(end 52.354988 -152.771348)
		(width 0.381)
		(layer "In2.Cu")
		(net "PVCCINFAON_CPU1")
	)
	(segment
		(start 53.257704 -145.151348)
		(end 52.298346 -144.19199)
		(width 0.381)
		(layer "In2.Cu")
		(net "PVCCINFAON_CPU1")
	)
	(segment
		(start 59.1058 -145.151348)
		(end 53.257704 -145.151348)
		(width 0.381)
		(layer "In2.Cu")
		(net "PVCCINFAON_CPU1")
	)
	(segment
		(start 51.489864 -153.097484)
		(end 51.816 -152.771348)
		(width 0.381)
		(layer "In2.Cu")
		(net "PVCCINFAON_CPU1")
	)
	(segment
		(start 51.759358 -144.19199)
		(end 51.489864 -144.461484)
		(width 0.381)
		(layer "In2.Cu")
		(net "PVCCINFAON_CPU1")
	)
	(segment
		(start 63.938912 -154.600148)
		(end 63.975234 -154.63647)
		(width 0.381)
		(layer "In2.Cu")
		(net "PVCCINFAON_CPU1")
	)
	(segment
		(start 60.0456 -154.600148)
		(end 63.938912 -154.600148)
		(width 0.381)
		(layer "In2.Cu")
		(net "PVCCINFAON_CPU1")
	)
	(segment
		(start 69.207634 -161.215578)
		(end 69.923406 -160.499806)
		(width 0.508)
		(layer "In15.Cu")
		(net "PVCCINFAON_CPU1")
	)
	(segment
		(start 69.923406 -160.499806)
		(end 70.639178 -161.215578)
		(width 0.508)
		(layer "In15.Cu")
		(net "PVCCINFAON_CPU1")
	)
	(segment
		(start 69.207634 -153.648918)
		(end 69.923406 -154.36469)
		(width 0.508)
		(layer "In15.Cu")
		(net "PVCCINFAON_CPU1")
	)
	(segment
		(start 69.207634 -147.512532)
		(end 69.923406 -148.228304)
		(width 0.508)
		(layer "In15.Cu")
		(net "PVCCINFAON_CPU1")
	)
	(segment
		(start 69.923406 -154.36469)
		(end 70.639178 -153.648918)
		(width 0.508)
		(layer "In15.Cu")
		(net "PVCCINFAON_CPU1")
	)
	(segment
		(start 69.923406 -148.228304)
		(end 70.639178 -147.512532)
		(width 0.508)
		(layer "In15.Cu")
		(net "PVCCINFAON_CPU1")
	)
	(segment
		(start 69.207634 -148.944076)
		(end 69.923406 -148.228304)
		(width 0.508)
		(layer "In15.Cu")
		(net "PVCCINFAON_CPU1")
	)
	(segment
		(start 69.923406 -154.36469)
		(end 70.639178 -155.080462)
		(width 0.508)
		(layer "In15.Cu")
		(net "PVCCINFAON_CPU1")
	)
	(segment
		(start 69.923406 -160.499806)
		(end 70.639178 -159.784034)
		(width 0.508)
		(layer "In15.Cu")
		(net "PVCCINFAON_CPU1")
	)
	(segment
		(start 69.207634 -155.080462)
		(end 69.923406 -154.36469)
		(width 0.508)
		(layer "In15.Cu")
		(net "PVCCINFAON_CPU1")
	)
	(segment
		(start 69.207634 -159.784034)
		(end 69.923406 -160.499806)
		(width 0.508)
		(layer "In15.Cu")
		(net "PVCCINFAON_CPU1")
	)
	(segment
		(start 69.923406 -148.228304)
		(end 70.639178 -148.944076)
		(width 0.508)
		(layer "In15.Cu")
		(net "PVCCINFAON_CPU1")
	)
	(segment
		(start 422.22039 -138.128502)
		(end 422.934384 -137.414508)
		(width 0.1778)
		(layer "F.Cu")
		(net "PVCCINFAON_CPU0_VR_FAULT")
	)
	(segment
		(start 421.736266 -138.333988)
		(end 421.738044 -138.335766)
		(width 0.254)
		(layer "F.Cu")
		(net "PVCCINFAON_CPU0_VR_FAULT")
	)
	(segment
		(start 421.738044 -138.335766)
		(end 422.013126 -138.335766)
		(width 0.1778)
		(layer "F.Cu")
		(net "PVCCINFAON_CPU0_VR_FAULT")
	)
	(segment
		(start 422.013126 -138.335766)
		(end 422.22039 -138.128502)
		(width 0.1778)
		(layer "F.Cu")
		(net "PVCCINFAON_CPU0_VR_FAULT")
	)
	(segment
		(start 421.082216 -138.333988)
		(end 421.736266 -138.333988)
		(width 0.254)
		(layer "F.Cu")
		(net "PVCCINFAON_CPU0_VR_FAULT")
	)
	(segment
		(start 422.934384 -137.414508)
		(end 423.30497 -137.414508)
		(width 0.1778)
		(layer "F.Cu")
		(net "PVCCINFAON_CPU0_VR_FAULT")
	)
	(via
		(at 422.22039 -138.128502)
		(size 0.4064)
		(drill 0.2032)
		(layers "F.Cu" "B.Cu")
		(net "PVCCINFAON_CPU0_VR_FAULT")
	)
	(segment
		(start 419.856412 -182.290974)
		(end 419.013386 -181.447948)
		(width 0.254)
		(layer "F.Cu")
		(net "PVCCINFAON_CPU0_VREF")
	)
	(segment
		(start 420.398702 -172.93209)
		(end 420.191438 -173.139354)
		(width 0.254)
		(layer "F.Cu")
		(net "PVCCINFAON_CPU0_VREF")
	)
	(segment
		(start 421.573452 -153.91892)
		(end 421.906446 -154.251914)
		(width 0.254)
		(layer "F.Cu")
		(net "PVCCINFAON_CPU0_VREF")
	)
	(segment
		(start 422.521634 -154.898598)
		(end 422.40454 -154.781504)
		(width 0.254)
		(layer "F.Cu")
		(net "PVCCINFAON_CPU0_VREF")
	)
	(segment
		(start 420.191438 -173.139354)
		(end 420.191438 -173.654974)
		(width 0.254)
		(layer "F.Cu")
		(net "PVCCINFAON_CPU0_VREF")
	)
	(segment
		(start 420.191438 -181.775354)
		(end 420.191438 -182.290974)
		(width 0.254)
		(layer "F.Cu")
		(net "PVCCINFAON_CPU0_VREF")
	)
	(segment
		(start 419.013386 -181.447948)
		(end 418.9095 -181.447948)
		(width 0.254)
		(layer "F.Cu")
		(net "PVCCINFAON_CPU0_VREF")
	)
	(segment
		(start 421.906446 -154.251914)
		(end 422.109138 -154.251914)
		(width 0.254)
		(layer "F.Cu")
		(net "PVCCINFAON_CPU0_VREF")
	)
	(segment
		(start 420.905178 -153.91892)
		(end 421.573452 -153.91892)
		(width 0.254)
		(layer "F.Cu")
		(net "PVCCINFAON_CPU0_VREF")
	)
	(segment
		(start 419.013386 -172.811948)
		(end 418.9095 -172.811948)
		(width 0.254)
		(layer "F.Cu")
		(net "PVCCINFAON_CPU0_VREF")
	)
	(segment
		(start 422.40454 -154.701748)
		(end 422.109138 -154.406346)
		(width 0.254)
		(layer "F.Cu")
		(net "PVCCINFAON_CPU0_VREF")
	)
	(segment
		(start 419.856412 -173.654974)
		(end 419.013386 -172.811948)
		(width 0.254)
		(layer "F.Cu")
		(net "PVCCINFAON_CPU0_VREF")
	)
	(segment
		(start 420.191438 -182.290974)
		(end 419.856412 -182.290974)
		(width 0.254)
		(layer "F.Cu")
		(net "PVCCINFAON_CPU0_VREF")
	)
	(segment
		(start 420.191438 -173.654974)
		(end 419.856412 -173.654974)
		(width 0.254)
		(layer "F.Cu")
		(net "PVCCINFAON_CPU0_VREF")
	)
	(segment
		(start 420.531798 -181.434994)
		(end 420.191438 -181.775354)
		(width 0.254)
		(layer "F.Cu")
		(net "PVCCINFAON_CPU0_VREF")
	)
	(segment
		(start 422.109138 -154.406346)
		(end 422.109138 -154.251914)
		(width 0.254)
		(layer "F.Cu")
		(net "PVCCINFAON_CPU0_VREF")
	)
	(segment
		(start 422.40454 -154.781504)
		(end 422.40454 -154.701748)
		(width 0.254)
		(layer "F.Cu")
		(net "PVCCINFAON_CPU0_VREF")
	)
	(via
		(at 423.11066 -132.947918)
		(size 0.508)
		(drill 0.254)
		(layers "F.Cu" "B.Cu")
		(net "PVCCINFAON_CPU0_VREF")
	)
	(via
		(at 420.531798 -181.434994)
		(size 0.508)
		(drill 0.254)
		(layers "F.Cu" "B.Cu")
		(net "PVCCINFAON_CPU0_VREF")
	)
	(via
		(at 419.92042 -139.527788)
		(size 0.508)
		(drill 0.254)
		(layers "F.Cu" "B.Cu")
		(net "PVCCINFAON_CPU0_VREF")
	)
	(via
		(at 420.398702 -172.93209)
		(size 0.508)
		(drill 0.254)
		(layers "F.Cu" "B.Cu")
		(net "PVCCINFAON_CPU0_VREF")
	)
	(via
		(at 422.521634 -154.898598)
		(size 0.508)
		(drill 0.254)
		(layers "F.Cu" "B.Cu")
		(net "PVCCINFAON_CPU0_VREF")
	)
	(segment
		(start 419.92042 -139.527788)
		(end 420.282116 -139.166092)
		(width 0.254)
		(layer "B.Cu")
		(net "PVCCINFAON_CPU0_VREF")
	)
	(segment
		(start 420.282116 -139.166092)
		(end 420.282116 -138.333988)
		(width 0.254)
		(layer "B.Cu")
		(net "PVCCINFAON_CPU0_VREF")
	)
	(segment
		(start 426.4406 -153.50998)
		(end 425.288202 -154.662378)
		(width 0.254)
		(layer "In4.Cu")
		(net "PVCCINFAON_CPU0_VREF")
	)
	(segment
		(start 425.96308 -139.233148)
		(end 425.96308 -140.020548)
		(width 0.254)
		(layer "In4.Cu")
		(net "PVCCINFAON_CPU0_VREF")
	)
	(segment
		(start 437.65216 -160.363916)
		(end 437.65216 -166.36492)
		(width 0.254)
		(layer "In4.Cu")
		(net "PVCCINFAON_CPU0_VREF")
	)
	(segment
		(start 421.259508 -139.13612)
		(end 421.259508 -144.923256)
		(width 0.254)
		(layer "In4.Cu")
		(net "PVCCINFAON_CPU0_VREF")
	)
	(segment
		(start 422.757854 -154.662378)
		(end 422.521634 -154.898598)
		(width 0.254)
		(layer "In4.Cu")
		(net "PVCCINFAON_CPU0_VREF")
	)
	(segment
		(start 433.86502 -156.576776)
		(end 437.65216 -160.363916)
		(width 0.254)
		(layer "In4.Cu")
		(net "PVCCINFAON_CPU0_VREF")
	)
	(segment
		(start 421.259508 -144.923256)
		(end 422.6814 -146.345148)
		(width 0.254)
		(layer "In4.Cu")
		(net "PVCCINFAON_CPU0_VREF")
	)
	(segment
		(start 429.803052 -174.214028)
		(end 426.33138 -174.214028)
		(width 0.254)
		(layer "In4.Cu")
		(net "PVCCINFAON_CPU0_VREF")
	)
	(segment
		(start 431.261012 -144.897348)
		(end 433.86502 -147.501356)
		(width 0.254)
		(layer "In4.Cu")
		(net "PVCCINFAON_CPU0_VREF")
	)
	(segment
		(start 425.288202 -154.662378)
		(end 422.757854 -154.662378)
		(width 0.254)
		(layer "In4.Cu")
		(net "PVCCINFAON_CPU0_VREF")
	)
	(segment
		(start 425.12488 -143.226536)
		(end 426.795692 -144.897348)
		(width 0.254)
		(layer "In4.Cu")
		(net "PVCCINFAON_CPU0_VREF")
	)
	(segment
		(start 437.65216 -166.36492)
		(end 429.803052 -174.214028)
		(width 0.254)
		(layer "In4.Cu")
		(net "PVCCINFAON_CPU0_VREF")
	)
	(segment
		(start 421.614854 -172.400214)
		(end 421.07104 -172.944028)
		(width 0.254)
		(layer "In4.Cu")
		(net "PVCCINFAON_CPU0_VREF")
	)
	(segment
		(start 421.07104 -172.944028)
		(end 420.41064 -172.944028)
		(width 0.254)
		(layer "In4.Cu")
		(net "PVCCINFAON_CPU0_VREF")
	)
	(segment
		(start 425.0436 -146.345148)
		(end 426.4406 -147.742148)
		(width 0.254)
		(layer "In4.Cu")
		(net "PVCCINFAON_CPU0_VREF")
	)
	(segment
		(start 425.12488 -140.858748)
		(end 425.12488 -143.226536)
		(width 0.254)
		(layer "In4.Cu")
		(net "PVCCINFAON_CPU0_VREF")
	)
	(segment
		(start 426.795692 -144.897348)
		(end 431.261012 -144.897348)
		(width 0.254)
		(layer "In4.Cu")
		(net "PVCCINFAON_CPU0_VREF")
	)
	(segment
		(start 422.6814 -146.345148)
		(end 425.0436 -146.345148)
		(width 0.254)
		(layer "In4.Cu")
		(net "PVCCINFAON_CPU0_VREF")
	)
	(segment
		(start 426.4406 -147.742148)
		(end 426.4406 -153.50998)
		(width 0.254)
		(layer "In4.Cu")
		(net "PVCCINFAON_CPU0_VREF")
	)
	(segment
		(start 433.86502 -147.501356)
		(end 433.86502 -156.576776)
		(width 0.254)
		(layer "In4.Cu")
		(net "PVCCINFAON_CPU0_VREF")
	)
	(segment
		(start 426.33138 -174.214028)
		(end 424.517566 -172.400214)
		(width 0.254)
		(layer "In4.Cu")
		(net "PVCCINFAON_CPU0_VREF")
	)
	(segment
		(start 420.41064 -172.944028)
		(end 420.398702 -172.93209)
		(width 0.254)
		(layer "In4.Cu")
		(net "PVCCINFAON_CPU0_VREF")
	)
	(segment
		(start 424.517566 -172.400214)
		(end 421.614854 -172.400214)
		(width 0.254)
		(layer "In4.Cu")
		(net "PVCCINFAON_CPU0_VREF")
	)
	(segment
		(start 425.96308 -140.020548)
		(end 425.12488 -140.858748)
		(width 0.254)
		(layer "In4.Cu")
		(net "PVCCINFAON_CPU0_VREF")
	)
	(segment
		(start 438.82564 -167.77462)
		(end 436.341012 -170.259248)
		(width 0.254)
		(layer "In6.Cu")
		(net "PVCCINFAON_CPU0_VREF")
	)
	(segment
		(start 435.73954 -170.259248)
		(end 432.179984 -173.818804)
		(width 0.254)
		(layer "In6.Cu")
		(net "PVCCINFAON_CPU0_VREF")
	)
	(segment
		(start 432.179984 -173.818804)
		(end 432.179984 -174.420276)
		(width 0.254)
		(layer "In6.Cu")
		(net "PVCCINFAON_CPU0_VREF")
	)
	(segment
		(start 438.82564 -161.047176)
		(end 438.82564 -167.77462)
		(width 0.254)
		(layer "In6.Cu")
		(net "PVCCINFAON_CPU0_VREF")
	)
	(segment
		(start 434.16728 -156.388816)
		(end 438.82564 -161.047176)
		(width 0.254)
		(layer "In6.Cu")
		(net "PVCCINFAON_CPU0_VREF")
	)
	(segment
		(start 425.891452 -180.708808)
		(end 421.257984 -180.708808)
		(width 0.254)
		(layer "In6.Cu")
		(net "PVCCINFAON_CPU0_VREF")
	)
	(segment
		(start 434.16728 -147.772628)
		(end 434.16728 -156.388816)
		(width 0.254)
		(layer "In6.Cu")
		(net "PVCCINFAON_CPU0_VREF")
	)
	(segment
		(start 432.179984 -174.420276)
		(end 425.891452 -180.708808)
		(width 0.254)
		(layer "In6.Cu")
		(net "PVCCINFAON_CPU0_VREF")
	)
	(segment
		(start 428.3964 -142.001748)
		(end 434.16728 -147.772628)
		(width 0.254)
		(layer "In6.Cu")
		(net "PVCCINFAON_CPU0_VREF")
	)
	(segment
		(start 426.036486 -142.001748)
		(end 428.3964 -142.001748)
		(width 0.254)
		(layer "In6.Cu")
		(net "PVCCINFAON_CPU0_VREF")
	)
	(segment
		(start 425.57192 -141.537182)
		(end 426.036486 -142.001748)
		(width 0.254)
		(layer "In6.Cu")
		(net "PVCCINFAON_CPU0_VREF")
	)
	(segment
		(start 421.257984 -180.708808)
		(end 420.531798 -181.434994)
		(width 0.254)
		(layer "In6.Cu")
		(net "PVCCINFAON_CPU0_VREF")
	)
	(segment
		(start 436.341012 -170.259248)
		(end 435.73954 -170.259248)
		(width 0.254)
		(layer "In6.Cu")
		(net "PVCCINFAON_CPU0_VREF")
	)
	(segment
		(start 421.082216 -135.146034)
		(end 421.701722 -135.146034)
		(width 0.254)
		(layer "F.Cu")
		(net "PVCCINFAON_CPU0_VIN_CSNIN")
	)
	(segment
		(start 422.519602 -135.414512)
		(end 423.30497 -135.414512)
		(width 0.1778)
		(layer "F.Cu")
		(net "PVCCINFAON_CPU0_VIN_CSNIN")
	)
	(segment
		(start 421.956484 -135.146034)
		(end 422.251124 -135.146034)
		(width 0.1778)
		(layer "F.Cu")
		(net "PVCCINFAON_CPU0_VIN_CSNIN")
	)
	(segment
		(start 422.251124 -135.146034)
		(end 422.519602 -135.414512)
		(width 0.1778)
		(layer "F.Cu")
		(net "PVCCINFAON_CPU0_VIN_CSNIN")
	)
	(segment
		(start 421.701722 -135.146034)
		(end 421.956484 -135.146034)
		(width 0.254)
		(layer "F.Cu")
		(net "PVCCINFAON_CPU0_VIN_CSNIN")
	)
	(via
		(at 421.701722 -135.146034)
		(size 0.508)
		(drill 0.254)
		(layers "F.Cu" "B.Cu")
		(net "PVCCINFAON_CPU0_VIN_CSNIN")
	)
	(via
		(at 421.20185 -133.90753)
		(size 0.6604)
		(drill 0.3302)
		(layers "F.Cu" "B.Cu")
		(net "PVCCINFAON_CPU0_VIN_CSNIN")
	)
	(segment
		(start 421.082216 -135.146034)
		(end 421.701722 -135.146034)
		(width 0.254)
		(layer "B.Cu")
		(net "PVCCINFAON_CPU0_VIN_CSNIN")
	)
	(segment
		(start 421.20185 -133.90753)
		(end 421.409114 -133.700266)
		(width 0.254)
		(layer "B.Cu")
		(net "PVCCINFAON_CPU0_VIN_CSNIN")
	)
	(segment
		(start 421.409114 -133.700266)
		(end 422.401238 -133.700266)
		(width 0.254)
		(layer "B.Cu")
		(net "PVCCINFAON_CPU0_VIN_CSNIN")
	)
	(segment
		(start 423.257472 -134.05485)
		(end 423.399712 -134.19709)
		(width 0.254)
		(layer "B.Cu")
		(net "PVCCINFAON_CPU0_VIN_CSNIN")
	)
	(segment
		(start 421.701722 -135.146034)
		(end 421.20185 -133.938772)
		(width 0.254)
		(layer "B.Cu")
		(net "PVCCINFAON_CPU0_VIN_CSNIN")
	)
	(segment
		(start 421.20185 -133.938772)
		(end 421.20185 -133.90753)
		(width 0.254)
		(layer "B.Cu")
		(net "PVCCINFAON_CPU0_VIN_CSNIN")
	)
	(segment
		(start 422.401238 -133.700266)
		(end 423.257472 -134.05485)
		(width 0.254)
		(layer "B.Cu")
		(net "PVCCINFAON_CPU0_VIN_CSNIN")
	)
	(segment
		(start 417.469828 -183.032654)
		(end 418.085778 -183.032654)
		(width 0.2286)
		(layer "F.Cu")
		(net "PVCCINFAON_CPU0_VDD2")
	)
	(segment
		(start 419.697154 -179.723542)
		(end 419.621462 -179.64785)
		(width 0.2286)
		(layer "F.Cu")
		(net "PVCCINFAON_CPU0_VDD2")
	)
	(segment
		(start 419.621462 -179.64785)
		(end 418.9095 -179.64785)
		(width 0.2286)
		(layer "F.Cu")
		(net "PVCCINFAON_CPU0_VDD2")
	)
	(segment
		(start 418.085778 -183.032654)
		(end 418.085778 -182.94731)
		(width 0.2032)
		(layer "F.Cu")
		(net "PVCCINFAON_CPU0_VDD2")
	)
	(segment
		(start 418.085778 -182.94731)
		(end 417.384484 -182.246016)
		(width 0.2032)
		(layer "F.Cu")
		(net "PVCCINFAON_CPU0_VDD2")
	)
	(segment
		(start 417.384484 -182.246016)
		(end 417.384484 -181.857904)
		(width 0.2032)
		(layer "F.Cu")
		(net "PVCCINFAON_CPU0_VDD2")
	)
	(via
		(at 418.96157 -180.808376)
		(size 0.6604)
		(drill 0.3302)
		(layers "F.Cu" "B.Cu")
		(net "PVCCINFAON_CPU0_VDD2")
	)
	(via
		(at 417.469828 -183.032654)
		(size 0.508)
		(drill 0.254)
		(layers "F.Cu" "B.Cu")
		(net "PVCCINFAON_CPU0_VDD2")
	)
	(via
		(at 419.697154 -179.723542)
		(size 0.508)
		(drill 0.254)
		(layers "F.Cu" "B.Cu")
		(net "PVCCINFAON_CPU0_VDD2")
	)
	(segment
		(start 418.96157 -181.07152)
		(end 418.96157 -180.808376)
		(width 0.2286)
		(layer "B.Cu")
		(net "PVCCINFAON_CPU0_VDD2")
	)
	(segment
		(start 417.396676 -182.959502)
		(end 417.396676 -181.854602)
		(width 0.2286)
		(layer "B.Cu")
		(net "PVCCINFAON_CPU0_VDD2")
	)
	(segment
		(start 418.96157 -180.459126)
		(end 419.697154 -179.723542)
		(width 0.2286)
		(layer "B.Cu")
		(net "PVCCINFAON_CPU0_VDD2")
	)
	(segment
		(start 417.469828 -183.032654)
		(end 417.396676 -182.959502)
		(width 0.2286)
		(layer "B.Cu")
		(net "PVCCINFAON_CPU0_VDD2")
	)
	(segment
		(start 418.395658 -181.637432)
		(end 418.96157 -181.07152)
		(width 0.2286)
		(layer "B.Cu")
		(net "PVCCINFAON_CPU0_VDD2")
	)
	(segment
		(start 418.96157 -180.808376)
		(end 418.96157 -180.459126)
		(width 0.2286)
		(layer "B.Cu")
		(net "PVCCINFAON_CPU0_VDD2")
	)
	(segment
		(start 417.396676 -181.854602)
		(end 417.613846 -181.637432)
		(width 0.2286)
		(layer "B.Cu")
		(net "PVCCINFAON_CPU0_VDD2")
	)
	(segment
		(start 417.613846 -181.637432)
		(end 418.395658 -181.637432)
		(width 0.2286)
		(layer "B.Cu")
		(net "PVCCINFAON_CPU0_VDD2")
	)
	(segment
		(start 417.469828 -174.396654)
		(end 418.085778 -174.396654)
		(width 0.2286)
		(layer "F.Cu")
		(net "PVCCINFAON_CPU0_VDD1")
	)
	(segment
		(start 419.621462 -171.01185)
		(end 418.9095 -171.01185)
		(width 0.2286)
		(layer "F.Cu")
		(net "PVCCINFAON_CPU0_VDD1")
	)
	(segment
		(start 418.085778 -174.31131)
		(end 417.384484 -173.610016)
		(width 0.2032)
		(layer "F.Cu")
		(net "PVCCINFAON_CPU0_VDD1")
	)
	(segment
		(start 418.085778 -174.396654)
		(end 418.085778 -174.31131)
		(width 0.2032)
		(layer "F.Cu")
		(net "PVCCINFAON_CPU0_VDD1")
	)
	(segment
		(start 417.384484 -173.610016)
		(end 417.384484 -173.221904)
		(width 0.2032)
		(layer "F.Cu")
		(net "PVCCINFAON_CPU0_VDD1")
	)
	(segment
		(start 419.697154 -171.087542)
		(end 419.621462 -171.01185)
		(width 0.2286)
		(layer "F.Cu")
		(net "PVCCINFAON_CPU0_VDD1")
	)
	(via
		(at 418.775388 -172.621702)
		(size 0.6604)
		(drill 0.3302)
		(layers "F.Cu" "B.Cu")
		(net "PVCCINFAON_CPU0_VDD1")
	)
	(via
		(at 417.469828 -174.396654)
		(size 0.508)
		(drill 0.254)
		(layers "F.Cu" "B.Cu")
		(net "PVCCINFAON_CPU0_VDD1")
	)
	(via
		(at 419.697154 -171.087542)
		(size 0.508)
		(drill 0.254)
		(layers "F.Cu" "B.Cu")
		(net "PVCCINFAON_CPU0_VDD1")
	)
	(segment
		(start 419.078918 -171.705778)
		(end 419.078918 -172.318172)
		(width 0.2286)
		(layer "B.Cu")
		(net "PVCCINFAON_CPU0_VDD1")
	)
	(segment
		(start 417.469828 -174.396654)
		(end 417.396676 -174.323502)
		(width 0.2286)
		(layer "B.Cu")
		(net "PVCCINFAON_CPU0_VDD1")
	)
	(segment
		(start 418.395658 -173.001432)
		(end 417.613846 -173.001432)
		(width 0.2286)
		(layer "B.Cu")
		(net "PVCCINFAON_CPU0_VDD1")
	)
	(segment
		(start 419.078918 -172.318172)
		(end 418.775388 -172.621702)
		(width 0.2286)
		(layer "B.Cu")
		(net "PVCCINFAON_CPU0_VDD1")
	)
	(segment
		(start 417.613846 -173.001432)
		(end 417.396676 -173.218602)
		(width 0.2286)
		(layer "B.Cu")
		(net "PVCCINFAON_CPU0_VDD1")
	)
	(segment
		(start 417.396676 -174.323502)
		(end 417.396676 -173.218602)
		(width 0.2286)
		(layer "B.Cu")
		(net "PVCCINFAON_CPU0_VDD1")
	)
	(segment
		(start 419.697154 -171.087542)
		(end 419.078918 -171.705778)
		(width 0.2286)
		(layer "B.Cu")
		(net "PVCCINFAON_CPU0_VDD1")
	)
	(segment
		(start 418.775388 -172.621702)
		(end 418.395658 -173.001432)
		(width 0.2286)
		(layer "B.Cu")
		(net "PVCCINFAON_CPU0_VDD1")
	)
	(segment
		(start 422.739312 -135.014462)
		(end 423.30497 -135.014462)
		(width 0.1778)
		(layer "F.Cu")
		(net "PVCCINFAON_CPU0_VCC")
	)
	(segment
		(start 421.082216 -134.130034)
		(end 421.082216 -133.114034)
		(width 0.254)
		(layer "F.Cu")
		(net "PVCCINFAON_CPU0_VCC")
	)
	(segment
		(start 421.082216 -134.130034)
		(end 421.258746 -134.306564)
		(width 0.254)
		(layer "F.Cu")
		(net "PVCCINFAON_CPU0_VCC")
	)
	(segment
		(start 421.082216 -132.229606)
		(end 421.06977 -132.21716)
		(width 0.254)
		(layer "F.Cu")
		(net "PVCCINFAON_CPU0_VCC")
	)
	(segment
		(start 422.031414 -134.306564)
		(end 422.739312 -135.014462)
		(width 0.1778)
		(layer "F.Cu")
		(net "PVCCINFAON_CPU0_VCC")
	)
	(segment
		(start 421.258746 -134.306564)
		(end 421.639746 -134.306564)
		(width 0.254)
		(layer "F.Cu")
		(net "PVCCINFAON_CPU0_VCC")
	)
	(segment
		(start 421.639746 -134.306564)
		(end 422.031414 -134.306564)
		(width 0.1778)
		(layer "F.Cu")
		(net "PVCCINFAON_CPU0_VCC")
	)
	(segment
		(start 421.06977 -132.21716)
		(end 421.06977 -131.54914)
		(width 0.254)
		(layer "F.Cu")
		(net "PVCCINFAON_CPU0_VCC")
	)
	(segment
		(start 421.082216 -133.114034)
		(end 421.082216 -132.229606)
		(width 0.254)
		(layer "F.Cu")
		(net "PVCCINFAON_CPU0_VCC")
	)
	(via
		(at 421.06977 -131.54914)
		(size 0.508)
		(drill 0.254)
		(layers "F.Cu" "B.Cu")
		(net "PVCCINFAON_CPU0_VCC")
	)
	(segment
		(start 421.06977 -131.549394)
		(end 421.098472 -131.578096)
		(width 0.381)
		(layer "B.Cu")
		(net "PVCCINFAON_CPU0_VCC")
	)
	(segment
		(start 421.06977 -131.54914)
		(end 421.06977 -131.549394)
		(width 0.381)
		(layer "B.Cu")
		(net "PVCCINFAON_CPU0_VCC")
	)
	(segment
		(start 421.098472 -131.578096)
		(end 421.098472 -132.632704)
		(width 0.381)
		(layer "B.Cu")
		(net "PVCCINFAON_CPU0_VCC")
	)
	(segment
		(start 428.695104 -136.214612)
		(end 428.105062 -136.214612)
		(width 0.1778)
		(layer "F.Cu")
		(net "PVCCINFAON_CPU0_PIN_ALERT")
	)
	(segment
		(start 429.016922 -135.892794)
		(end 428.695104 -136.214612)
		(width 0.1778)
		(layer "F.Cu")
		(net "PVCCINFAON_CPU0_PIN_ALERT")
	)
	(segment
		(start 429.62703 -135.892794)
		(end 429.016922 -135.892794)
		(width 0.1778)
		(layer "F.Cu")
		(net "PVCCINFAON_CPU0_PIN_ALERT")
	)
	(via
		(at 428.184564 -135.892794)
		(size 0.6604)
		(drill 0.3302)
		(layers "F.Cu" "B.Cu")
		(net "PVCCINFAON_CPU0_PIN_ALERT")
	)
	(via
		(at 429.62703 -135.892794)
		(size 0.508)
		(drill 0.254)
		(layers "F.Cu" "B.Cu")
		(net "PVCCINFAON_CPU0_PIN_ALERT")
	)
	(segment
		(start 428.184564 -135.892794)
		(end 429.62703 -135.892794)
		(width 0.12954)
		(layer "B.Cu")
		(net "PVCCINFAON_CPU0_PIN_ALERT")
	)
	(segment
		(start 429.62703 -135.892794)
		(end 429.953166 -135.757666)
		(width 0.1778)
		(layer "B.Cu")
		(net "PVCCINFAON_CPU0_PIN_ALERT")
	)
	(segment
		(start 429.953166 -135.757666)
		(end 430.200054 -135.510778)
		(width 0.1778)
		(layer "B.Cu")
		(net "PVCCINFAON_CPU0_PIN_ALERT")
	)
	(segment
		(start 419.686994 -180.92039)
		(end 419.37178 -180.605176)
		(width 0.12954)
		(layer "F.Cu")
		(net "PVCCINFAON_CPU0_LSET2")
	)
	(segment
		(start 419.37178 -180.605176)
		(end 419.23335 -180.547772)
		(width 0.12954)
		(layer "F.Cu")
		(net "PVCCINFAON_CPU0_LSET2")
	)
	(segment
		(start 421.15359 -181.149244)
		(end 420.924736 -180.92039)
		(width 0.12954)
		(layer "F.Cu")
		(net "PVCCINFAON_CPU0_LSET2")
	)
	(segment
		(start 420.924736 -180.92039)
		(end 419.686994 -180.92039)
		(width 0.12954)
		(layer "F.Cu")
		(net "PVCCINFAON_CPU0_LSET2")
	)
	(segment
		(start 419.23335 -180.547772)
		(end 418.9095 -180.547772)
		(width 0.12954)
		(layer "F.Cu")
		(net "PVCCINFAON_CPU0_LSET2")
	)
	(segment
		(start 419.51148 -172.027088)
		(end 419.768782 -172.28439)
		(width 0.12954)
		(layer "F.Cu")
		(net "PVCCINFAON_CPU0_LSET1")
	)
	(segment
		(start 419.768782 -172.28439)
		(end 420.924736 -172.28439)
		(width 0.12954)
		(layer "F.Cu")
		(net "PVCCINFAON_CPU0_LSET1")
	)
	(segment
		(start 419.23335 -171.911772)
		(end 419.51148 -172.027088)
		(width 0.12954)
		(layer "F.Cu")
		(net "PVCCINFAON_CPU0_LSET1")
	)
	(segment
		(start 420.924736 -172.28439)
		(end 421.15359 -172.513244)
		(width 0.12954)
		(layer "F.Cu")
		(net "PVCCINFAON_CPU0_LSET1")
	)
	(segment
		(start 418.9095 -171.911772)
		(end 419.23335 -171.911772)
		(width 0.12954)
		(layer "F.Cu")
		(net "PVCCINFAON_CPU0_LSET1")
	)
	(segment
		(start 429.213264 -134.747762)
		(end 428.546514 -135.414512)
		(width 0.12954)
		(layer "F.Cu")
		(net "PVCCINFAON_CPU0_EN_R")
	)
	(segment
		(start 430.200054 -134.494778)
		(end 429.7934 -134.494778)
		(width 0.12954)
		(layer "F.Cu")
		(net "PVCCINFAON_CPU0_EN_R")
	)
	(segment
		(start 428.546514 -135.414512)
		(end 428.105062 -135.414512)
		(width 0.12954)
		(layer "F.Cu")
		(net "PVCCINFAON_CPU0_EN_R")
	)
	(segment
		(start 429.7934 -134.494778)
		(end 429.540416 -134.747762)
		(width 0.12954)
		(layer "F.Cu")
		(net "PVCCINFAON_CPU0_EN_R")
	)
	(segment
		(start 429.540416 -134.747762)
		(end 429.213264 -134.747762)
		(width 0.12954)
		(layer "F.Cu")
		(net "PVCCINFAON_CPU0_EN_R")
	)
	(via
		(at 428.540164 -134.575296)
		(size 0.6604)
		(drill 0.3302)
		(layers "F.Cu" "B.Cu")
		(net "PVCCINFAON_CPU0_EN_R")
	)
	(via
		(at 429.540416 -134.747762)
		(size 0.508)
		(drill 0.254)
		(layers "F.Cu" "B.Cu")
		(net "PVCCINFAON_CPU0_EN_R")
	)
	(segment
		(start 428.989744 -134.575296)
		(end 429.16221 -134.747762)
		(width 0.12954)
		(layer "B.Cu")
		(net "PVCCINFAON_CPU0_EN_R")
	)
	(segment
		(start 429.7934 -134.494778)
		(end 430.200054 -134.494778)
		(width 0.12954)
		(layer "B.Cu")
		(net "PVCCINFAON_CPU0_EN_R")
	)
	(segment
		(start 429.16221 -134.747762)
		(end 429.540416 -134.747762)
		(width 0.12954)
		(layer "B.Cu")
		(net "PVCCINFAON_CPU0_EN_R")
	)
	(segment
		(start 429.540416 -134.747762)
		(end 429.7934 -134.494778)
		(width 0.12954)
		(layer "B.Cu")
		(net "PVCCINFAON_CPU0_EN_R")
	)
	(segment
		(start 428.540164 -134.575296)
		(end 428.989744 -134.575296)
		(width 0.12954)
		(layer "B.Cu")
		(net "PVCCINFAON_CPU0_EN_R")
	)
	(segment
		(start 421.429688 -135.814562)
		(end 421.082216 -136.162034)
		(width 0.254)
		(layer "F.Cu")
		(net "PVCCINFAON_CPU0_CSPIN")
	)
	(segment
		(start 423.30497 -135.814562)
		(end 422.115488 -135.814562)
		(width 0.1778)
		(layer "F.Cu")
		(net "PVCCINFAON_CPU0_CSPIN")
	)
	(segment
		(start 422.115488 -135.814562)
		(end 421.429688 -135.814562)
		(width 0.1778)
		(layer "F.Cu")
		(net "PVCCINFAON_CPU0_CSPIN")
	)
	(via
		(at 422.115488 -135.814562)
		(size 0.508)
		(drill 0.254)
		(layers "F.Cu" "B.Cu")
		(net "PVCCINFAON_CPU0_CSPIN")
	)
	(via
		(at 422.266618 -134.696454)
		(size 0.6604)
		(drill 0.3302)
		(layers "F.Cu" "B.Cu")
		(net "PVCCINFAON_CPU0_CSPIN")
	)
	(segment
		(start 423.283888 -135.769096)
		(end 423.283888 -135.713724)
		(width 0.254)
		(layer "B.Cu")
		(net "PVCCINFAON_CPU0_CSPIN")
	)
	(segment
		(start 422.266618 -135.663432)
		(end 422.115488 -135.814562)
		(width 0.254)
		(layer "B.Cu")
		(net "PVCCINFAON_CPU0_CSPIN")
	)
	(segment
		(start 421.082216 -136.162034)
		(end 421.429688 -135.814562)
		(width 0.254)
		(layer "B.Cu")
		(net "PVCCINFAON_CPU0_CSPIN")
	)
	(segment
		(start 422.266618 -134.696454)
		(end 422.266618 -135.663432)
		(width 0.254)
		(layer "B.Cu")
		(net "PVCCINFAON_CPU0_CSPIN")
	)
	(segment
		(start 421.429688 -135.814562)
		(end 422.115488 -135.814562)
		(width 0.254)
		(layer "B.Cu")
		(net "PVCCINFAON_CPU0_CSPIN")
	)
	(segment
		(start 423.283888 -135.713724)
		(end 422.266618 -134.696454)
		(width 0.254)
		(layer "B.Cu")
		(net "PVCCINFAON_CPU0_CSPIN")
	)
	(segment
		(start 419.943026 -171.782994)
		(end 419.943026 -171.767754)
		(width 0.254)
		(layer "F.Cu")
		(net "PVCCINFAON_CPU0_ATSEN")
	)
	(segment
		(start 423.30497 -136.614408)
		(end 422.784016 -136.614408)
		(width 0.1778)
		(layer "F.Cu")
		(net "PVCCINFAON_CPU0_ATSEN")
	)
	(segment
		(start 419.204648 -180.097938)
		(end 418.9095 -180.097938)
		(width 0.254)
		(layer "F.Cu")
		(net "PVCCINFAON_CPU0_ATSEN")
	)
	(segment
		(start 419.942772 -171.7675)
		(end 419.204648 -171.461938)
		(width 0.254)
		(layer "F.Cu")
		(net "PVCCINFAON_CPU0_ATSEN")
	)
	(segment
		(start 422.367456 -137.030968)
		(end 421.229282 -137.030968)
		(width 0.1778)
		(layer "F.Cu")
		(net "PVCCINFAON_CPU0_ATSEN")
	)
	(segment
		(start 419.943026 -171.767754)
		(end 419.942772 -171.7675)
		(width 0.254)
		(layer "F.Cu")
		(net "PVCCINFAON_CPU0_ATSEN")
	)
	(segment
		(start 418.919914 -139.48664)
		(end 417.96462 -139.48664)
		(width 0.254)
		(layer "F.Cu")
		(net "PVCCINFAON_CPU0_ATSEN")
	)
	(segment
		(start 419.942772 -180.4035)
		(end 419.204648 -180.097938)
		(width 0.254)
		(layer "F.Cu")
		(net "PVCCINFAON_CPU0_ATSEN")
	)
	(segment
		(start 417.96462 -138.687048)
		(end 418.96538 -137.686288)
		(width 0.254)
		(layer "F.Cu")
		(net "PVCCINFAON_CPU0_ATSEN")
	)
	(segment
		(start 422.784016 -136.614408)
		(end 422.367456 -137.030968)
		(width 0.1778)
		(layer "F.Cu")
		(net "PVCCINFAON_CPU0_ATSEN")
	)
	(segment
		(start 421.082216 -137.222738)
		(end 421.082216 -137.178034)
		(width 0.254)
		(layer "F.Cu")
		(net "PVCCINFAON_CPU0_ATSEN")
	)
	(segment
		(start 421.229282 -137.030968)
		(end 421.082216 -137.178034)
		(width 0.1778)
		(layer "F.Cu")
		(net "PVCCINFAON_CPU0_ATSEN")
	)
	(segment
		(start 419.204648 -171.461938)
		(end 418.9095 -171.461938)
		(width 0.254)
		(layer "F.Cu")
		(net "PVCCINFAON_CPU0_ATSEN")
	)
	(segment
		(start 419.943026 -180.418994)
		(end 419.943026 -180.403754)
		(width 0.254)
		(layer "F.Cu")
		(net "PVCCINFAON_CPU0_ATSEN")
	)
	(segment
		(start 418.96538 -137.686288)
		(end 420.618666 -137.686288)
		(width 0.254)
		(layer "F.Cu")
		(net "PVCCINFAON_CPU0_ATSEN")
	)
	(segment
		(start 419.943026 -180.403754)
		(end 419.942772 -180.4035)
		(width 0.254)
		(layer "F.Cu")
		(net "PVCCINFAON_CPU0_ATSEN")
	)
	(segment
		(start 420.618666 -137.686288)
		(end 421.082216 -137.222738)
		(width 0.254)
		(layer "F.Cu")
		(net "PVCCINFAON_CPU0_ATSEN")
	)
	(segment
		(start 417.96462 -139.48664)
		(end 417.96462 -138.687048)
		(width 0.254)
		(layer "F.Cu")
		(net "PVCCINFAON_CPU0_ATSEN")
	)
	(via
		(at 417.96462 -139.48664)
		(size 0.508)
		(drill 0.254)
		(layers "F.Cu" "B.Cu")
		(net "PVCCINFAON_CPU0_ATSEN")
	)
	(via
		(at 419.943026 -180.418994)
		(size 0.508)
		(drill 0.254)
		(layers "F.Cu" "B.Cu")
		(net "PVCCINFAON_CPU0_ATSEN")
	)
	(via
		(at 419.943026 -171.782994)
		(size 0.508)
		(drill 0.254)
		(layers "F.Cu" "B.Cu")
		(net "PVCCINFAON_CPU0_ATSEN")
	)
	(segment
		(start 417.903406 -145.351754)
		(end 425.853606 -145.351754)
		(width 0.254)
		(layer "In11.Cu")
		(net "PVCCINFAON_CPU0_ATSEN")
	)
	(segment
		(start 425.853606 -145.351754)
		(end 426.847 -146.345148)
		(width 0.254)
		(layer "In11.Cu")
		(net "PVCCINFAON_CPU0_ATSEN")
	)
	(segment
		(start 416.306 -141.14526)
		(end 416.306 -143.754348)
		(width 0.254)
		(layer "In11.Cu")
		(net "PVCCINFAON_CPU0_ATSEN")
	)
	(segment
		(start 424.62196 -161.628328)
		(end 424.62196 -171.401994)
		(width 0.254)
		(layer "In11.Cu")
		(net "PVCCINFAON_CPU0_ATSEN")
	)
	(segment
		(start 425.781978 -155.682188)
		(end 425.781978 -160.46831)
		(width 0.254)
		(layer "In11.Cu")
		(net "PVCCINFAON_CPU0_ATSEN")
	)
	(segment
		(start 424.62196 -171.401994)
		(end 424.24096 -171.782994)
		(width 0.254)
		(layer "In11.Cu")
		(net "PVCCINFAON_CPU0_ATSEN")
	)
	(segment
		(start 426.847 -146.345148)
		(end 426.847 -154.617166)
		(width 0.254)
		(layer "In11.Cu")
		(net "PVCCINFAON_CPU0_ATSEN")
	)
	(segment
		(start 425.781978 -160.46831)
		(end 424.62196 -161.628328)
		(width 0.254)
		(layer "In11.Cu")
		(net "PVCCINFAON_CPU0_ATSEN")
	)
	(segment
		(start 419.943026 -180.418994)
		(end 419.96106 -180.437028)
		(width 0.254)
		(layer "In11.Cu")
		(net "PVCCINFAON_CPU0_ATSEN")
	)
	(segment
		(start 423.49674 -180.437028)
		(end 424.65752 -179.276248)
		(width 0.254)
		(layer "In11.Cu")
		(net "PVCCINFAON_CPU0_ATSEN")
	)
	(segment
		(start 419.943026 -171.782994)
		(end 424.24096 -171.782994)
		(width 0.254)
		(layer "In11.Cu")
		(net "PVCCINFAON_CPU0_ATSEN")
	)
	(segment
		(start 424.65752 -179.276248)
		(end 424.65752 -172.202348)
		(width 0.254)
		(layer "In11.Cu")
		(net "PVCCINFAON_CPU0_ATSEN")
	)
	(segment
		(start 417.96462 -139.48664)
		(end 416.306 -141.14526)
		(width 0.254)
		(layer "In11.Cu")
		(net "PVCCINFAON_CPU0_ATSEN")
	)
	(segment
		(start 426.847 -154.617166)
		(end 425.781978 -155.682188)
		(width 0.254)
		(layer "In11.Cu")
		(net "PVCCINFAON_CPU0_ATSEN")
	)
	(segment
		(start 424.65752 -172.202348)
		(end 424.24096 -171.785788)
		(width 0.254)
		(layer "In11.Cu")
		(net "PVCCINFAON_CPU0_ATSEN")
	)
	(segment
		(start 416.306 -143.754348)
		(end 417.903406 -145.351754)
		(width 0.254)
		(layer "In11.Cu")
		(net "PVCCINFAON_CPU0_ATSEN")
	)
	(segment
		(start 419.96106 -180.437028)
		(end 423.49674 -180.437028)
		(width 0.254)
		(layer "In11.Cu")
		(net "PVCCINFAON_CPU0_ATSEN")
	)
	(segment
		(start 424.24096 -171.785788)
		(end 424.24096 -171.782994)
		(width 0.254)
		(layer "In11.Cu")
		(net "PVCCINFAON_CPU0_ATSEN")
	)
	(segment
		(start 420.321486 -179.349654)
		(end 420.194486 -179.297076)
		(width 0.1778)
		(layer "F.Cu")
		(net "PVCCINFAON_CPU0_APWM2")
	)
	(segment
		(start 426.304964 -133.613652)
		(end 426.304964 -134.014464)
		(width 0.1524)
		(layer "F.Cu")
		(net "PVCCINFAON_CPU0_APWM2")
	)
	(segment
		(start 420.194486 -179.297076)
		(end 419.695376 -179.197762)
		(width 0.1778)
		(layer "F.Cu")
		(net "PVCCINFAON_CPU0_APWM2")
	)
	(segment
		(start 425.8564 -133.071108)
		(end 425.8564 -133.165088)
		(width 0.1524)
		(layer "F.Cu")
		(net "PVCCINFAON_CPU0_APWM2")
	)
	(segment
		(start 419.695376 -179.197762)
		(end 418.9095 -179.197762)
		(width 0.1778)
		(layer "F.Cu")
		(net "PVCCINFAON_CPU0_APWM2")
	)
	(segment
		(start 425.8564 -133.165088)
		(end 426.304964 -133.613652)
		(width 0.1524)
		(layer "F.Cu")
		(net "PVCCINFAON_CPU0_APWM2")
	)
	(via
		(at 420.321486 -179.349654)
		(size 0.508)
		(drill 0.254)
		(layers "F.Cu" "B.Cu")
		(net "PVCCINFAON_CPU0_APWM2")
	)
	(via
		(at 425.8564 -133.071108)
		(size 0.508)
		(drill 0.254)
		(layers "F.Cu" "B.Cu")
		(net "PVCCINFAON_CPU0_APWM2")
	)
	(segment
		(start 431.53076 -147.112228)
		(end 430.20742 -145.788888)
		(width 0.254)
		(layer "In2.Cu")
		(net "PVCCINFAON_CPU0_APWM2")
	)
	(segment
		(start 426.36186 -133.576568)
		(end 425.8564 -133.071108)
		(width 0.254)
		(layer "In2.Cu")
		(net "PVCCINFAON_CPU0_APWM2")
	)
	(segment
		(start 421.266112 -178.405028)
		(end 423.044112 -178.405028)
		(width 0.254)
		(layer "In2.Cu")
		(net "PVCCINFAON_CPU0_APWM2")
	)
	(segment
		(start 424.4594 -160.020508)
		(end 426.43298 -158.046928)
		(width 0.254)
		(layer "In2.Cu")
		(net "PVCCINFAON_CPU0_APWM2")
	)
	(segment
		(start 421.62476 -144.661128)
		(end 421.62476 -140.646404)
		(width 0.254)
		(layer "In2.Cu")
		(net "PVCCINFAON_CPU0_APWM2")
	)
	(segment
		(start 426.43298 -158.046928)
		(end 426.43298 -155.064968)
		(width 0.254)
		(layer "In2.Cu")
		(net "PVCCINFAON_CPU0_APWM2")
	)
	(segment
		(start 422.75252 -145.788888)
		(end 421.62476 -144.661128)
		(width 0.254)
		(layer "In2.Cu")
		(net "PVCCINFAON_CPU0_APWM2")
	)
	(segment
		(start 426.43298 -155.064968)
		(end 431.53076 -149.967188)
		(width 0.254)
		(layer "In2.Cu")
		(net "PVCCINFAON_CPU0_APWM2")
	)
	(segment
		(start 427.96206 -138.580876)
		(end 427.96206 -134.181088)
		(width 0.254)
		(layer "In2.Cu")
		(net "PVCCINFAON_CPU0_APWM2")
	)
	(segment
		(start 427.35754 -133.576568)
		(end 426.36186 -133.576568)
		(width 0.254)
		(layer "In2.Cu")
		(net "PVCCINFAON_CPU0_APWM2")
	)
	(segment
		(start 431.53076 -149.967188)
		(end 431.53076 -147.112228)
		(width 0.254)
		(layer "In2.Cu")
		(net "PVCCINFAON_CPU0_APWM2")
	)
	(segment
		(start 427.96206 -134.181088)
		(end 427.35754 -133.576568)
		(width 0.254)
		(layer "In2.Cu")
		(net "PVCCINFAON_CPU0_APWM2")
	)
	(segment
		(start 430.20742 -145.788888)
		(end 422.75252 -145.788888)
		(width 0.254)
		(layer "In2.Cu")
		(net "PVCCINFAON_CPU0_APWM2")
	)
	(segment
		(start 423.044112 -178.405028)
		(end 424.4594 -176.98974)
		(width 0.254)
		(layer "In2.Cu")
		(net "PVCCINFAON_CPU0_APWM2")
	)
	(segment
		(start 427.777148 -138.765788)
		(end 427.96206 -138.580876)
		(width 0.254)
		(layer "In2.Cu")
		(net "PVCCINFAON_CPU0_APWM2")
	)
	(segment
		(start 421.62476 -140.646404)
		(end 423.505376 -138.765788)
		(width 0.254)
		(layer "In2.Cu")
		(net "PVCCINFAON_CPU0_APWM2")
	)
	(segment
		(start 420.321486 -179.349654)
		(end 421.266112 -178.405028)
		(width 0.254)
		(layer "In2.Cu")
		(net "PVCCINFAON_CPU0_APWM2")
	)
	(segment
		(start 423.505376 -138.765788)
		(end 427.777148 -138.765788)
		(width 0.254)
		(layer "In2.Cu")
		(net "PVCCINFAON_CPU0_APWM2")
	)
	(segment
		(start 424.4594 -176.98974)
		(end 424.4594 -160.020508)
		(width 0.254)
		(layer "In2.Cu")
		(net "PVCCINFAON_CPU0_APWM2")
	)
	(segment
		(start 427.660308 -130.730498)
		(end 427.660308 -131.8514)
		(width 0.1524)
		(layer "F.Cu")
		(net "PVCCINFAON_CPU0_APWM1")
	)
	(segment
		(start 419.695376 -170.561762)
		(end 418.9095 -170.561762)
		(width 0.1778)
		(layer "F.Cu")
		(net "PVCCINFAON_CPU0_APWM1")
	)
	(segment
		(start 420.321486 -170.713654)
		(end 420.194486 -170.661076)
		(width 0.1778)
		(layer "F.Cu")
		(net "PVCCINFAON_CPU0_APWM1")
	)
	(segment
		(start 427.660308 -131.8514)
		(end 426.705014 -132.806694)
		(width 0.1524)
		(layer "F.Cu")
		(net "PVCCINFAON_CPU0_APWM1")
	)
	(segment
		(start 426.705014 -132.806694)
		(end 426.705014 -134.014464)
		(width 0.1524)
		(layer "F.Cu")
		(net "PVCCINFAON_CPU0_APWM1")
	)
	(segment
		(start 420.194486 -170.661076)
		(end 419.695376 -170.561762)
		(width 0.1778)
		(layer "F.Cu")
		(net "PVCCINFAON_CPU0_APWM1")
	)
	(via
		(at 420.321486 -170.713654)
		(size 0.508)
		(drill 0.254)
		(layers "F.Cu" "B.Cu")
		(net "PVCCINFAON_CPU0_APWM1")
	)
	(via
		(at 427.660308 -130.730498)
		(size 0.508)
		(drill 0.254)
		(layers "F.Cu" "B.Cu")
		(net "PVCCINFAON_CPU0_APWM1")
	)
	(segment
		(start 421.06596 -169.845228)
		(end 422.967912 -169.845228)
		(width 0.254)
		(layer "In2.Cu")
		(net "PVCCINFAON_CPU0_APWM1")
	)
	(segment
		(start 420.8399 -138.295888)
		(end 420.65702 -138.113008)
		(width 0.254)
		(layer "In2.Cu")
		(net "PVCCINFAON_CPU0_APWM1")
	)
	(segment
		(start 430.7459 -147.437348)
		(end 429.8823 -146.573748)
		(width 0.254)
		(layer "In2.Cu")
		(net "PVCCINFAON_CPU0_APWM1")
	)
	(segment
		(start 425.67098 -157.698948)
		(end 425.67098 -154.683968)
		(width 0.254)
		(layer "In2.Cu")
		(net "PVCCINFAON_CPU0_APWM1")
	)
	(segment
		(start 423.310812 -169.50182)
		(end 423.51198 -169.300652)
		(width 0.254)
		(layer "In2.Cu")
		(net "PVCCINFAON_CPU0_APWM1")
	)
	(segment
		(start 424.93438 -133.297168)
		(end 424.93438 -132.705348)
		(width 0.254)
		(layer "In2.Cu")
		(net "PVCCINFAON_CPU0_APWM1")
	)
	(segment
		(start 420.8399 -144.986248)
		(end 420.8399 -138.295888)
		(width 0.254)
		(layer "In2.Cu")
		(net "PVCCINFAON_CPU0_APWM1")
	)
	(segment
		(start 425.67098 -154.683968)
		(end 430.7459 -149.609048)
		(width 0.254)
		(layer "In2.Cu")
		(net "PVCCINFAON_CPU0_APWM1")
	)
	(segment
		(start 420.81196 -170.22318)
		(end 420.81196 -170.099228)
		(width 0.254)
		(layer "In2.Cu")
		(net "PVCCINFAON_CPU0_APWM1")
	)
	(segment
		(start 424.93438 -132.705348)
		(end 425.46778 -132.171948)
		(width 0.254)
		(layer "In2.Cu")
		(net "PVCCINFAON_CPU0_APWM1")
	)
	(segment
		(start 420.321486 -170.713654)
		(end 420.81196 -170.22318)
		(width 0.254)
		(layer "In2.Cu")
		(net "PVCCINFAON_CPU0_APWM1")
	)
	(segment
		(start 423.51198 -169.300652)
		(end 423.51198 -159.857948)
		(width 0.254)
		(layer "In2.Cu")
		(net "PVCCINFAON_CPU0_APWM1")
	)
	(segment
		(start 420.65702 -138.113008)
		(end 420.65702 -134.569708)
		(width 0.254)
		(layer "In2.Cu")
		(net "PVCCINFAON_CPU0_APWM1")
	)
	(segment
		(start 423.51198 -159.857948)
		(end 425.67098 -157.698948)
		(width 0.254)
		(layer "In2.Cu")
		(net "PVCCINFAON_CPU0_APWM1")
	)
	(segment
		(start 421.21582 -134.010908)
		(end 424.22064 -134.010908)
		(width 0.254)
		(layer "In2.Cu")
		(net "PVCCINFAON_CPU0_APWM1")
	)
	(segment
		(start 425.46778 -132.171948)
		(end 427.06036 -132.171948)
		(width 0.254)
		(layer "In2.Cu")
		(net "PVCCINFAON_CPU0_APWM1")
	)
	(segment
		(start 427.06036 -132.171948)
		(end 427.660308 -131.572)
		(width 0.254)
		(layer "In2.Cu")
		(net "PVCCINFAON_CPU0_APWM1")
	)
	(segment
		(start 420.65702 -134.569708)
		(end 421.21582 -134.010908)
		(width 0.254)
		(layer "In2.Cu")
		(net "PVCCINFAON_CPU0_APWM1")
	)
	(segment
		(start 424.22064 -134.010908)
		(end 424.93438 -133.297168)
		(width 0.254)
		(layer "In2.Cu")
		(net "PVCCINFAON_CPU0_APWM1")
	)
	(segment
		(start 423.310812 -169.502328)
		(end 423.310812 -169.50182)
		(width 0.254)
		(layer "In2.Cu")
		(net "PVCCINFAON_CPU0_APWM1")
	)
	(segment
		(start 430.7459 -149.609048)
		(end 430.7459 -147.437348)
		(width 0.254)
		(layer "In2.Cu")
		(net "PVCCINFAON_CPU0_APWM1")
	)
	(segment
		(start 422.967912 -169.845228)
		(end 423.310812 -169.502328)
		(width 0.254)
		(layer "In2.Cu")
		(net "PVCCINFAON_CPU0_APWM1")
	)
	(segment
		(start 429.8823 -146.573748)
		(end 422.4274 -146.573748)
		(width 0.254)
		(layer "In2.Cu")
		(net "PVCCINFAON_CPU0_APWM1")
	)
	(segment
		(start 420.81196 -170.099228)
		(end 421.06596 -169.845228)
		(width 0.254)
		(layer "In2.Cu")
		(net "PVCCINFAON_CPU0_APWM1")
	)
	(segment
		(start 427.660308 -131.572)
		(end 427.660308 -130.730498)
		(width 0.254)
		(layer "In2.Cu")
		(net "PVCCINFAON_CPU0_APWM1")
	)
	(segment
		(start 422.4274 -146.573748)
		(end 420.8399 -144.986248)
		(width 0.254)
		(layer "In2.Cu")
		(net "PVCCINFAON_CPU0_APWM1")
	)
	(segment
		(start 422.867328 -137.014458)
		(end 423.30497 -137.014458)
		(width 0.1778)
		(layer "F.Cu")
		(net "PVCCINFAON_CPU0_ADDR")
	)
	(segment
		(start 422.157398 -137.724388)
		(end 422.867328 -137.014458)
		(width 0.1778)
		(layer "F.Cu")
		(net "PVCCINFAON_CPU0_ADDR")
	)
	(segment
		(start 421.57396 -137.724388)
		(end 422.157398 -137.724388)
		(width 0.1778)
		(layer "F.Cu")
		(net "PVCCINFAON_CPU0_ADDR")
	)
	(via
		(at 421.57396 -137.724388)
		(size 0.508)
		(drill 0.254)
		(layers "F.Cu" "B.Cu")
		(net "PVCCINFAON_CPU0_ADDR")
	)
	(via
		(at 421.2463 -139.5857)
		(size 0.7112)
		(drill 0.3556)
		(layers "F.Cu" "B.Cu")
		(net "PVCCINFAON_CPU0_ADDR")
	)
	(segment
		(start 421.296592 -137.178034)
		(end 421.082216 -137.178034)
		(width 0.254)
		(layer "B.Cu")
		(net "PVCCINFAON_CPU0_ADDR")
	)
	(segment
		(start 421.04564 -138.297412)
		(end 421.04564 -137.21461)
		(width 0.254)
		(layer "B.Cu")
		(net "PVCCINFAON_CPU0_ADDR")
	)
	(segment
		(start 421.082216 -139.421616)
		(end 421.082216 -138.333988)
		(width 0.254)
		(layer "B.Cu")
		(net "PVCCINFAON_CPU0_ADDR")
	)
	(segment
		(start 421.082216 -138.333988)
		(end 421.04564 -138.297412)
		(width 0.254)
		(layer "B.Cu")
		(net "PVCCINFAON_CPU0_ADDR")
	)
	(segment
		(start 421.57396 -137.724388)
		(end 421.57396 -137.455402)
		(width 0.254)
		(layer "B.Cu")
		(net "PVCCINFAON_CPU0_ADDR")
	)
	(segment
		(start 421.04564 -137.21461)
		(end 421.082216 -137.178034)
		(width 0.254)
		(layer "B.Cu")
		(net "PVCCINFAON_CPU0_ADDR")
	)
	(segment
		(start 421.2463 -139.5857)
		(end 421.082216 -139.421616)
		(width 0.254)
		(layer "B.Cu")
		(net "PVCCINFAON_CPU0_ADDR")
	)
	(segment
		(start 421.57396 -137.455402)
		(end 421.296592 -137.178034)
		(width 0.254)
		(layer "B.Cu")
		(net "PVCCINFAON_CPU0_ADDR")
	)
	(segment
		(start 426.304964 -139.571984)
		(end 426.304964 -138.814556)
		(width 0.1778)
		(layer "F.Cu")
		(net "PVCCINFAON_CPU0_ACSP2")
	)
	(segment
		(start 419.680898 -181.434994)
		(end 419.243764 -180.99786)
		(width 0.254)
		(layer "F.Cu")
		(net "PVCCINFAON_CPU0_ACSP2")
	)
	(segment
		(start 426.43044 -141.415008)
		(end 426.17898 -141.163548)
		(width 0.1778)
		(layer "F.Cu")
		(net "PVCCINFAON_CPU0_ACSP2")
	)
	(segment
		(start 426.17898 -141.163548)
		(end 426.17898 -139.697968)
		(width 0.1778)
		(layer "F.Cu")
		(net "PVCCINFAON_CPU0_ACSP2")
	)
	(segment
		(start 419.243764 -180.99786)
		(end 418.9095 -180.99786)
		(width 0.254)
		(layer "F.Cu")
		(net "PVCCINFAON_CPU0_ACSP2")
	)
	(segment
		(start 419.755574 -181.434994)
		(end 419.680898 -181.434994)
		(width 0.254)
		(layer "F.Cu")
		(net "PVCCINFAON_CPU0_ACSP2")
	)
	(segment
		(start 426.17898 -139.697968)
		(end 426.304964 -139.571984)
		(width 0.1778)
		(layer "F.Cu")
		(net "PVCCINFAON_CPU0_ACSP2")
	)
	(via
		(at 419.755574 -181.434994)
		(size 0.508)
		(drill 0.254)
		(layers "F.Cu" "B.Cu")
		(net "PVCCINFAON_CPU0_ACSP2")
	)
	(via
		(at 426.43044 -141.415008)
		(size 0.508)
		(drill 0.254)
		(layers "F.Cu" "B.Cu")
		(net "PVCCINFAON_CPU0_ACSP2")
	)
	(segment
		(start 426.43044 -141.415008)
		(end 428.366936 -141.415008)
		(width 0.254)
		(layer "In6.Cu")
		(net "PVCCINFAON_CPU0_ACSP2")
	)
	(segment
		(start 435.897528 -170.640248)
		(end 432.560984 -173.976792)
		(width 0.254)
		(layer "In6.Cu")
		(net "PVCCINFAON_CPU0_ACSP2")
	)
	(segment
		(start 426.04944 -181.089808)
		(end 421.8051 -181.089808)
		(width 0.254)
		(layer "In6.Cu")
		(net "PVCCINFAON_CPU0_ACSP2")
	)
	(segment
		(start 420.279068 -181.958488)
		(end 419.755574 -181.434994)
		(width 0.254)
		(layer "In6.Cu")
		(net "PVCCINFAON_CPU0_ACSP2")
	)
	(segment
		(start 439.20664 -167.932608)
		(end 436.499 -170.640248)
		(width 0.254)
		(layer "In6.Cu")
		(net "PVCCINFAON_CPU0_ACSP2")
	)
	(segment
		(start 420.93642 -181.958488)
		(end 420.279068 -181.958488)
		(width 0.254)
		(layer "In6.Cu")
		(net "PVCCINFAON_CPU0_ACSP2")
	)
	(segment
		(start 439.20664 -160.889188)
		(end 439.20664 -167.932608)
		(width 0.254)
		(layer "In6.Cu")
		(net "PVCCINFAON_CPU0_ACSP2")
	)
	(segment
		(start 432.560984 -173.976792)
		(end 432.560984 -174.578264)
		(width 0.254)
		(layer "In6.Cu")
		(net "PVCCINFAON_CPU0_ACSP2")
	)
	(segment
		(start 434.561234 -147.609306)
		(end 434.561234 -156.243782)
		(width 0.254)
		(layer "In6.Cu")
		(net "PVCCINFAON_CPU0_ACSP2")
	)
	(segment
		(start 434.561234 -156.243782)
		(end 439.20664 -160.889188)
		(width 0.254)
		(layer "In6.Cu")
		(net "PVCCINFAON_CPU0_ACSP2")
	)
	(segment
		(start 421.8051 -181.089808)
		(end 420.93642 -181.958488)
		(width 0.254)
		(layer "In6.Cu")
		(net "PVCCINFAON_CPU0_ACSP2")
	)
	(segment
		(start 428.366936 -141.415008)
		(end 434.561234 -147.609306)
		(width 0.254)
		(layer "In6.Cu")
		(net "PVCCINFAON_CPU0_ACSP2")
	)
	(segment
		(start 436.499 -170.640248)
		(end 435.897528 -170.640248)
		(width 0.254)
		(layer "In6.Cu")
		(net "PVCCINFAON_CPU0_ACSP2")
	)
	(segment
		(start 432.560984 -174.578264)
		(end 426.04944 -181.089808)
		(width 0.254)
		(layer "In6.Cu")
		(net "PVCCINFAON_CPU0_ACSP2")
	)
	(segment
		(start 426.705014 -138.814556)
		(end 426.705014 -140.264388)
		(width 0.1778)
		(layer "F.Cu")
		(net "PVCCINFAON_CPU0_ACSP1")
	)
	(segment
		(start 419.755574 -172.798994)
		(end 419.31844 -172.36186)
		(width 0.254)
		(layer "F.Cu")
		(net "PVCCINFAON_CPU0_ACSP1")
	)
	(segment
		(start 419.31844 -172.36186)
		(end 418.9095 -172.36186)
		(width 0.254)
		(layer "F.Cu")
		(net "PVCCINFAON_CPU0_ACSP1")
	)
	(via
		(at 426.705014 -140.264388)
		(size 0.508)
		(drill 0.254)
		(layers "F.Cu" "B.Cu")
		(net "PVCCINFAON_CPU0_ACSP1")
	)
	(via
		(at 419.755574 -172.798994)
		(size 0.508)
		(drill 0.254)
		(layers "F.Cu" "B.Cu")
		(net "PVCCINFAON_CPU0_ACSP1")
	)
	(segment
		(start 420.98976 -173.564296)
		(end 421.772842 -172.781214)
		(width 0.254)
		(layer "In4.Cu")
		(net "PVCCINFAON_CPU0_ACSP1")
	)
	(segment
		(start 426.95368 -144.516348)
		(end 425.50588 -143.068548)
		(width 0.254)
		(layer "In4.Cu")
		(net "PVCCINFAON_CPU0_ACSP1")
	)
	(segment
		(start 419.82898 -173.360588)
		(end 420.032688 -173.564296)
		(width 0.254)
		(layer "In4.Cu")
		(net "PVCCINFAON_CPU0_ACSP1")
	)
	(segment
		(start 438.03316 -160.205674)
		(end 434.24602 -156.418534)
		(width 0.254)
		(layer "In4.Cu")
		(net "PVCCINFAON_CPU0_ACSP1")
	)
	(segment
		(start 426.173392 -174.595028)
		(end 429.96104 -174.595028)
		(width 0.254)
		(layer "In4.Cu")
		(net "PVCCINFAON_CPU0_ACSP1")
	)
	(segment
		(start 421.772842 -172.781214)
		(end 424.359578 -172.781214)
		(width 0.254)
		(layer "In4.Cu")
		(net "PVCCINFAON_CPU0_ACSP1")
	)
	(segment
		(start 434.24602 -156.418534)
		(end 434.24602 -147.343368)
		(width 0.254)
		(layer "In4.Cu")
		(net "PVCCINFAON_CPU0_ACSP1")
	)
	(segment
		(start 424.359578 -172.781214)
		(end 426.173392 -174.595028)
		(width 0.254)
		(layer "In4.Cu")
		(net "PVCCINFAON_CPU0_ACSP1")
	)
	(segment
		(start 420.032688 -173.564296)
		(end 420.98976 -173.564296)
		(width 0.254)
		(layer "In4.Cu")
		(net "PVCCINFAON_CPU0_ACSP1")
	)
	(segment
		(start 426.27804 -140.264388)
		(end 426.705014 -140.264388)
		(width 0.254)
		(layer "In4.Cu")
		(net "PVCCINFAON_CPU0_ACSP1")
	)
	(segment
		(start 419.755574 -172.798994)
		(end 419.82898 -172.8724)
		(width 0.254)
		(layer "In4.Cu")
		(net "PVCCINFAON_CPU0_ACSP1")
	)
	(segment
		(start 429.96104 -174.595028)
		(end 438.03316 -166.522908)
		(width 0.254)
		(layer "In4.Cu")
		(net "PVCCINFAON_CPU0_ACSP1")
	)
	(segment
		(start 425.50588 -141.036548)
		(end 426.27804 -140.264388)
		(width 0.254)
		(layer "In4.Cu")
		(net "PVCCINFAON_CPU0_ACSP1")
	)
	(segment
		(start 419.82898 -172.8724)
		(end 419.82898 -173.360588)
		(width 0.254)
		(layer "In4.Cu")
		(net "PVCCINFAON_CPU0_ACSP1")
	)
	(segment
		(start 431.419 -144.516348)
		(end 426.95368 -144.516348)
		(width 0.254)
		(layer "In4.Cu")
		(net "PVCCINFAON_CPU0_ACSP1")
	)
	(segment
		(start 434.24602 -147.343368)
		(end 431.419 -144.516348)
		(width 0.254)
		(layer "In4.Cu")
		(net "PVCCINFAON_CPU0_ACSP1")
	)
	(segment
		(start 425.50588 -143.068548)
		(end 425.50588 -141.036548)
		(width 0.254)
		(layer "In4.Cu")
		(net "PVCCINFAON_CPU0_ACSP1")
	)
	(segment
		(start 438.03316 -166.522908)
		(end 438.03316 -160.205674)
		(width 0.254)
		(layer "In4.Cu")
		(net "PVCCINFAON_CPU0_ACSP1")
	)
	(segment
		(start 368.508534 -221.947994)
		(end 368.50828 -221.94774)
		(width 0.254)
		(layer "F.Cu")
		(net "PVCCINFAON_CPU0")
	)
	(segment
		(start 366.628934 -225.739198)
		(end 366.628934 -225.203512)
		(width 0.254)
		(layer "F.Cu")
		(net "PVCCINFAON_CPU0")
	)
	(segment
		(start 370.388134 -218.692476)
		(end 370.38788 -218.692222)
		(width 0.254)
		(layer "F.Cu")
		(net "PVCCINFAON_CPU0")
	)
	(segment
		(start 364.749334 -222.48368)
		(end 364.749334 -221.947994)
		(width 0.254)
		(layer "F.Cu")
		(net "PVCCINFAON_CPU0")
	)
	(segment
		(start 357.230934 -225.203512)
		(end 357.23068 -225.203258)
		(width 0.254)
		(layer "F.Cu")
		(net "PVCCINFAON_CPU0")
	)
	(segment
		(start 362.869734 -228.99497)
		(end 362.86948 -228.994716)
		(width 0.254)
		(layer "F.Cu")
		(net "PVCCINFAON_CPU0")
	)
	(segment
		(start 369.558316 -265.592306)
		(end 369.558316 -266.127992)
		(width 0.254)
		(layer "F.Cu")
		(net "PVCCINFAON_CPU0")
	)
	(segment
		(start 400.558 -170.983148)
		(end 401.498308 -170.04284)
		(width 0.508)
		(layer "F.Cu")
		(net "PVCCINFAON_CPU0")
	)
	(segment
		(start 400.558 -177.206148)
		(end 401.498308 -178.146456)
		(width 0.508)
		(layer "F.Cu")
		(net "PVCCINFAON_CPU0")
	)
	(segment
		(start 355.931216 -264.77849)
		(end 355.931216 -265.314176)
		(width 0.254)
		(layer "F.Cu")
		(net "PVCCINFAON_CPU0")
	)
	(segment
		(start 368.148362 -266.941554)
		(end 368.148616 -266.941808)
		(width 0.254)
		(layer "F.Cu")
		(net "PVCCINFAON_CPU0")
	)
	(segment
		(start 370.027962 -268.033754)
		(end 370.027962 -268.569694)
		(width 0.254)
		(layer "F.Cu")
		(net "PVCCINFAON_CPU0")
	)
	(segment
		(start 364.74908 -228.994716)
		(end 364.74908 -228.45903)
		(width 0.254)
		(layer "F.Cu")
		(net "PVCCINFAON_CPU0")
	)
	(segment
		(start 372.267734 -225.203512)
		(end 372.26748 -225.203258)
		(width 0.254)
		(layer "F.Cu")
		(net "PVCCINFAON_CPU0")
	)
	(segment
		(start 399.617692 -182.48884)
		(end 400.558 -183.429148)
		(width 0.508)
		(layer "F.Cu")
		(net "PVCCINFAON_CPU0")
	)
	(segment
		(start 369.088416 -270.167862)
		(end 369.088416 -270.19758)
		(width 0.254)
		(layer "F.Cu")
		(net "PVCCINFAON_CPU0")
	)
	(segment
		(start 364.749334 -219.228162)
		(end 364.749334 -218.692476)
		(width 0.254)
		(layer "F.Cu")
		(net "PVCCINFAON_CPU0")
	)
	(segment
		(start 370.028216 -270.167862)
		(end 370.028216 -270.19758)
		(width 0.254)
		(layer "F.Cu")
		(net "PVCCINFAON_CPU0")
	)
	(segment
		(start 366.738916 -268.84757)
		(end 366.738916 -269.38351)
		(width 0.254)
		(layer "F.Cu")
		(net "PVCCINFAON_CPU0")
	)
	(segment
		(start 370.388134 -225.203512)
		(end 370.38788 -225.203258)
		(width 0.254)
		(layer "F.Cu")
		(net "PVCCINFAON_CPU0")
	)
	(segment
		(start 369.088162 -268.033754)
		(end 369.088162 -268.56944)
		(width 0.254)
		(layer "F.Cu")
		(net "PVCCINFAON_CPU0")
	)
	(segment
		(start 353.471734 -225.203512)
		(end 353.47148 -225.203258)
		(width 0.254)
		(layer "F.Cu")
		(net "PVCCINFAON_CPU0")
	)
	(segment
		(start 364.749334 -218.692476)
		(end 364.74908 -218.692222)
		(width 0.254)
		(layer "F.Cu")
		(net "PVCCINFAON_CPU0")
	)
	(segment
		(start 370.388134 -230.622602)
		(end 370.388134 -230.086916)
		(width 0.254)
		(layer "F.Cu")
		(net "PVCCINFAON_CPU0")
	)
	(segment
		(start 372.267734 -219.228162)
		(end 372.267734 -218.692476)
		(width 0.254)
		(layer "F.Cu")
		(net "PVCCINFAON_CPU0")
	)
	(segment
		(start 368.508534 -225.203512)
		(end 368.50828 -225.203258)
		(width 0.254)
		(layer "F.Cu")
		(net "PVCCINFAON_CPU0")
	)
	(segment
		(start 353.581716 -264.500106)
		(end 353.581462 -264.50036)
		(width 0.381)
		(layer "F.Cu")
		(net "PVCCINFAON_CPU0")
	)
	(segment
		(start 360.990134 -225.739198)
		(end 360.990134 -225.203512)
		(width 0.254)
		(layer "F.Cu")
		(net "PVCCINFAON_CPU0")
	)
	(segment
		(start 351.592134 -225.203512)
		(end 351.59188 -225.203258)
		(width 0.254)
		(layer "F.Cu")
		(net "PVCCINFAON_CPU0")
	)
	(segment
		(start 366.628934 -228.99497)
		(end 366.62868 -228.994716)
		(width 0.254)
		(layer "F.Cu")
		(net "PVCCINFAON_CPU0")
	)
	(segment
		(start 369.088162 -264.778236)
		(end 369.088162 -265.313922)
		(width 0.254)
		(layer "F.Cu")
		(net "PVCCINFAON_CPU0")
	)
	(segment
		(start 400.558 -177.206148)
		(end 401.498308 -176.26584)
		(width 0.508)
		(layer "F.Cu")
		(net "PVCCINFAON_CPU0")
	)
	(segment
		(start 370.388134 -221.947994)
		(end 370.38788 -221.94774)
		(width 0.254)
		(layer "F.Cu")
		(net "PVCCINFAON_CPU0")
	)
	(segment
		(start 366.628934 -222.48368)
		(end 366.628934 -221.947994)
		(width 0.254)
		(layer "F.Cu")
		(net "PVCCINFAON_CPU0")
	)
	(segment
		(start 366.628934 -215.972644)
		(end 366.628934 -215.437212)
		(width 0.254)
		(layer "F.Cu")
		(net "PVCCINFAON_CPU0")
	)
	(segment
		(start 400.558 -183.429148)
		(end 401.498308 -184.369456)
		(width 0.508)
		(layer "F.Cu")
		(net "PVCCINFAON_CPU0")
	)
	(segment
		(start 372.267734 -225.739198)
		(end 372.267734 -225.203512)
		(width 0.254)
		(layer "F.Cu")
		(net "PVCCINFAON_CPU0")
	)
	(segment
		(start 368.508534 -225.739198)
		(end 368.508534 -225.203512)
		(width 0.254)
		(layer "F.Cu")
		(net "PVCCINFAON_CPU0")
	)
	(segment
		(start 368.618516 -267.219938)
		(end 368.618516 -267.755878)
		(width 0.254)
		(layer "F.Cu")
		(net "PVCCINFAON_CPU0")
	)
	(segment
		(start 367.208816 -270.167862)
		(end 367.208816 -270.19758)
		(width 0.254)
		(layer "F.Cu")
		(net "PVCCINFAON_CPU0")
	)
	(segment
		(start 354.521516 -264.500106)
		(end 354.521262 -264.50036)
		(width 0.381)
		(layer "F.Cu")
		(net "PVCCINFAON_CPU0")
	)
	(segment
		(start 372.26748 -215.436958)
		(end 372.26748 -215.436704)
		(width 0.254)
		(layer "F.Cu")
		(net "PVCCINFAON_CPU0")
	)
	(segment
		(start 355.461316 -263.96442)
		(end 355.461316 -264.50036)
		(width 0.381)
		(layer "F.Cu")
		(net "PVCCINFAON_CPU0")
	)
	(segment
		(start 364.749334 -215.972644)
		(end 364.74908 -215.97239)
		(width 0.254)
		(layer "F.Cu")
		(net "PVCCINFAON_CPU0")
	)
	(segment
		(start 368.148616 -270.167862)
		(end 368.148616 -270.19758)
		(width 0.254)
		(layer "F.Cu")
		(net "PVCCINFAON_CPU0")
	)
	(segment
		(start 366.628934 -218.692476)
		(end 366.62868 -218.692222)
		(width 0.254)
		(layer "F.Cu")
		(net "PVCCINFAON_CPU0")
	)
	(segment
		(start 370.38788 -215.436958)
		(end 370.38788 -215.436704)
		(width 0.254)
		(layer "F.Cu")
		(net "PVCCINFAON_CPU0")
	)
	(segment
		(start 374.14708 -215.436958)
		(end 374.14708 -215.436704)
		(width 0.254)
		(layer "F.Cu")
		(net "PVCCINFAON_CPU0")
	)
	(segment
		(start 370.027962 -269.66164)
		(end 370.028216 -270.167862)
		(width 0.254)
		(layer "F.Cu")
		(net "PVCCINFAON_CPU0")
	)
	(segment
		(start 369.088162 -266.405868)
		(end 369.088162 -266.941808)
		(width 0.254)
		(layer "F.Cu")
		(net "PVCCINFAON_CPU0")
	)
	(segment
		(start 372.267734 -215.972644)
		(end 372.267734 -215.437212)
		(width 0.254)
		(layer "F.Cu")
		(net "PVCCINFAON_CPU0")
	)
	(segment
		(start 399.617692 -184.369456)
		(end 400.558 -183.429148)
		(width 0.508)
		(layer "F.Cu")
		(net "PVCCINFAON_CPU0")
	)
	(segment
		(start 370.388134 -215.972644)
		(end 370.388134 -215.437212)
		(width 0.254)
		(layer "F.Cu")
		(net "PVCCINFAON_CPU0")
	)
	(segment
		(start 374.147334 -219.228162)
		(end 374.147334 -218.692476)
		(width 0.254)
		(layer "F.Cu")
		(net "PVCCINFAON_CPU0")
	)
	(segment
		(start 370.388134 -215.437212)
		(end 370.38788 -215.436958)
		(width 0.254)
		(layer "F.Cu")
		(net "PVCCINFAON_CPU0")
	)
	(segment
		(start 355.351334 -225.203512)
		(end 355.35108 -225.203258)
		(width 0.254)
		(layer "F.Cu")
		(net "PVCCINFAON_CPU0")
	)
	(segment
		(start 362.869734 -225.203512)
		(end 362.86948 -225.203258)
		(width 0.254)
		(layer "F.Cu")
		(net "PVCCINFAON_CPU0")
	)
	(segment
		(start 374.147334 -215.972644)
		(end 374.147334 -215.437212)
		(width 0.254)
		(layer "F.Cu")
		(net "PVCCINFAON_CPU0")
	)
	(segment
		(start 368.148362 -266.405868)
		(end 368.148362 -266.941554)
		(width 0.254)
		(layer "F.Cu")
		(net "PVCCINFAON_CPU0")
	)
	(segment
		(start 370.388134 -230.086916)
		(end 370.38788 -230.086662)
		(width 0.254)
		(layer "F.Cu")
		(net "PVCCINFAON_CPU0")
	)
	(segment
		(start 360.990134 -225.203512)
		(end 360.98988 -225.203258)
		(width 0.254)
		(layer "F.Cu")
		(net "PVCCINFAON_CPU0")
	)
	(segment
		(start 367.208562 -269.66164)
		(end 367.208816 -270.167862)
		(width 0.254)
		(layer "F.Cu")
		(net "PVCCINFAON_CPU0")
	)
	(segment
		(start 351.592134 -225.739198)
		(end 351.592134 -225.203512)
		(width 0.254)
		(layer "F.Cu")
		(net "PVCCINFAON_CPU0")
	)
	(segment
		(start 370.388134 -225.739198)
		(end 370.388134 -225.203512)
		(width 0.254)
		(layer "F.Cu")
		(net "PVCCINFAON_CPU0")
	)
	(segment
		(start 355.351334 -225.739198)
		(end 355.351334 -225.203512)
		(width 0.254)
		(layer "F.Cu")
		(net "PVCCINFAON_CPU0")
	)
	(segment
		(start 370.498116 -267.219938)
		(end 370.497862 -267.220192)
		(width 0.18034)
		(layer "F.Cu")
		(net "PVCCINFAON_CPU0")
	)
	(segment
		(start 366.738916 -267.219938)
		(end 366.738916 -267.755878)
		(width 0.254)
		(layer "F.Cu")
		(net "PVCCINFAON_CPU0")
	)
	(segment
		(start 362.869734 -225.739198)
		(end 362.869734 -225.203512)
		(width 0.254)
		(layer "F.Cu")
		(net "PVCCINFAON_CPU0")
	)
	(segment
		(start 368.508534 -218.692476)
		(end 368.50828 -218.692222)
		(width 0.254)
		(layer "F.Cu")
		(net "PVCCINFAON_CPU0")
	)
	(segment
		(start 354.521516 -263.96442)
		(end 354.521516 -264.500106)
		(width 0.381)
		(layer "F.Cu")
		(net "PVCCINFAON_CPU0")
	)
	(segment
		(start 367.678716 -268.84757)
		(end 367.678716 -269.38351)
		(width 0.254)
		(layer "F.Cu")
		(net "PVCCINFAON_CPU0")
	)
	(segment
		(start 351.12198 -227.645214)
		(end 351.122234 -227.64496)
		(width 0.381)
		(layer "F.Cu")
		(net "PVCCINFAON_CPU0")
	)
	(segment
		(start 367.208562 -268.033754)
		(end 367.208562 -268.569694)
		(width 0.254)
		(layer "F.Cu")
		(net "PVCCINFAON_CPU0")
	)
	(segment
		(start 400.558 -183.429148)
		(end 401.498308 -182.48884)
		(width 0.508)
		(layer "F.Cu")
		(net "PVCCINFAON_CPU0")
	)
	(segment
		(start 374.147334 -222.48368)
		(end 374.147334 -221.947994)
		(width 0.254)
		(layer "F.Cu")
		(net "PVCCINFAON_CPU0")
	)
	(segment
		(start 372.267734 -218.692476)
		(end 372.26748 -218.692222)
		(width 0.254)
		(layer "F.Cu")
		(net "PVCCINFAON_CPU0")
	)
	(segment
		(start 374.147334 -215.437212)
		(end 374.14708 -215.436958)
		(width 0.254)
		(layer "F.Cu")
		(net "PVCCINFAON_CPU0")
	)
	(segment
		(start 364.749334 -228.99497)
		(end 364.74908 -228.994716)
		(width 0.254)
		(layer "F.Cu")
		(net "PVCCINFAON_CPU0")
	)
	(segment
		(start 372.267734 -215.437212)
		(end 372.26748 -215.436958)
		(width 0.254)
		(layer "F.Cu")
		(net "PVCCINFAON_CPU0")
	)
	(segment
		(start 369.558316 -268.84757)
		(end 369.558316 -269.38351)
		(width 0.254)
		(layer "F.Cu")
		(net "PVCCINFAON_CPU0")
	)
	(segment
		(start 368.508534 -219.228162)
		(end 368.508534 -218.692476)
		(width 0.254)
		(layer "F.Cu")
		(net "PVCCINFAON_CPU0")
	)
	(segment
		(start 357.230934 -225.739198)
		(end 357.230934 -225.203512)
		(width 0.254)
		(layer "F.Cu")
		(net "PVCCINFAON_CPU0")
	)
	(segment
		(start 372.267734 -221.947994)
		(end 372.26748 -221.94774)
		(width 0.254)
		(layer "F.Cu")
		(net "PVCCINFAON_CPU0")
	)
	(segment
		(start 368.148362 -269.66164)
		(end 368.148616 -270.167862)
		(width 0.254)
		(layer "F.Cu")
		(net "PVCCINFAON_CPU0")
	)
	(segment
		(start 364.74908 -215.97239)
		(end 364.74908 -215.436704)
		(width 0.254)
		(layer "F.Cu")
		(net "PVCCINFAON_CPU0")
	)
	(segment
		(start 351.12198 -228.1809)
		(end 351.12198 -227.645214)
		(width 0.381)
		(layer "F.Cu")
		(net "PVCCINFAON_CPU0")
	)
	(segment
		(start 367.208562 -266.405868)
		(end 367.208562 -266.941808)
		(width 0.254)
		(layer "F.Cu")
		(net "PVCCINFAON_CPU0")
	)
	(segment
		(start 399.617692 -170.04284)
		(end 400.558 -170.983148)
		(width 0.508)
		(layer "F.Cu")
		(net "PVCCINFAON_CPU0")
	)
	(segment
		(start 369.088162 -265.313922)
		(end 369.088416 -265.314176)
		(width 0.254)
		(layer "F.Cu")
		(net "PVCCINFAON_CPU0")
	)
	(segment
		(start 364.749334 -225.203512)
		(end 364.74908 -225.203258)
		(width 0.254)
		(layer "F.Cu")
		(net "PVCCINFAON_CPU0")
	)
	(segment
		(start 366.628934 -219.228162)
		(end 366.628934 -218.692476)
		(width 0.254)
		(layer "F.Cu")
		(net "PVCCINFAON_CPU0")
	)
	(segment
		(start 366.62868 -228.994716)
		(end 366.62868 -228.45903)
		(width 0.254)
		(layer "F.Cu")
		(net "PVCCINFAON_CPU0")
	)
	(segment
		(start 374.147334 -218.692476)
		(end 374.14708 -218.692222)
		(width 0.254)
		(layer "F.Cu")
		(net "PVCCINFAON_CPU0")
	)
	(segment
		(start 352.641916 -263.96442)
		(end 352.641916 -264.500106)
		(width 0.381)
		(layer "F.Cu")
		(net "PVCCINFAON_CPU0")
	)
	(segment
		(start 353.471734 -225.739198)
		(end 353.471734 -225.203512)
		(width 0.254)
		(layer "F.Cu")
		(net "PVCCINFAON_CPU0")
	)
	(segment
		(start 374.147334 -221.947994)
		(end 374.14708 -221.94774)
		(width 0.254)
		(layer "F.Cu")
		(net "PVCCINFAON_CPU0")
	)
	(segment
		(start 366.62868 -215.436958)
		(end 366.62868 -215.436704)
		(width 0.254)
		(layer "F.Cu")
		(net "PVCCINFAON_CPU0")
	)
	(segment
		(start 369.558316 -266.127992)
		(end 369.558062 -266.128246)
		(width 0.254)
		(layer "F.Cu")
		(net "PVCCINFAON_CPU0")
	)
	(segment
		(start 355.930962 -264.778236)
		(end 355.931216 -264.77849)
		(width 0.254)
		(layer "F.Cu")
		(net "PVCCINFAON_CPU0")
	)
	(segment
		(start 374.147334 -225.739198)
		(end 374.147334 -225.203512)
		(width 0.254)
		(layer "F.Cu")
		(net "PVCCINFAON_CPU0")
	)
	(segment
		(start 369.088162 -268.56944)
		(end 369.088416 -268.569694)
		(width 0.254)
		(layer "F.Cu")
		(net "PVCCINFAON_CPU0")
	)
	(segment
		(start 368.508534 -222.48368)
		(end 368.508534 -221.947994)
		(width 0.254)
		(layer "F.Cu")
		(net "PVCCINFAON_CPU0")
	)
	(segment
		(start 368.508534 -215.437212)
		(end 368.50828 -215.436958)
		(width 0.254)
		(layer "F.Cu")
		(net "PVCCINFAON_CPU0")
	)
	(segment
		(start 366.628934 -215.437212)
		(end 366.62868 -215.436958)
		(width 0.254)
		(layer "F.Cu")
		(net "PVCCINFAON_CPU0")
	)
	(segment
		(start 368.148362 -268.033754)
		(end 368.148362 -268.569694)
		(width 0.254)
		(layer "F.Cu")
		(net "PVCCINFAON_CPU0")
	)
	(segment
		(start 370.388134 -222.48368)
		(end 370.388134 -221.947994)
		(width 0.254)
		(layer "F.Cu")
		(net "PVCCINFAON_CPU0")
	)
	(segment
		(start 353.581716 -263.96442)
		(end 353.581716 -264.500106)
		(width 0.381)
		(layer "F.Cu")
		(net "PVCCINFAON_CPU0")
	)
	(segment
		(start 372.267734 -222.48368)
		(end 372.267734 -221.947994)
		(width 0.254)
		(layer "F.Cu")
		(net "PVCCINFAON_CPU0")
	)
	(segment
		(start 366.628934 -221.947994)
		(end 366.62868 -221.94774)
		(width 0.254)
		(layer "F.Cu")
		(net "PVCCINFAON_CPU0")
	)
	(segment
		(start 368.50828 -215.436958)
		(end 368.50828 -215.436704)
		(width 0.254)
		(layer "F.Cu")
		(net "PVCCINFAON_CPU0")
	)
	(segment
		(start 364.749334 -221.947994)
		(end 364.74908 -221.94774)
		(width 0.254)
		(layer "F.Cu")
		(net "PVCCINFAON_CPU0")
	)
	(segment
		(start 370.388134 -219.228162)
		(end 370.388134 -218.692476)
		(width 0.254)
		(layer "F.Cu")
		(net "PVCCINFAON_CPU0")
	)
	(segment
		(start 399.617692 -178.146456)
		(end 400.558 -177.206148)
		(width 0.508)
		(layer "F.Cu")
		(net "PVCCINFAON_CPU0")
	)
	(segment
		(start 399.617692 -171.923456)
		(end 400.558 -170.983148)
		(width 0.508)
		(layer "F.Cu")
		(net "PVCCINFAON_CPU0")
	)
	(segment
		(start 369.088162 -269.66164)
		(end 369.088416 -270.167862)
		(width 0.254)
		(layer "F.Cu")
		(net "PVCCINFAON_CPU0")
	)
	(segment
		(start 400.558 -170.983148)
		(end 401.498308 -171.923456)
		(width 0.508)
		(layer "F.Cu")
		(net "PVCCINFAON_CPU0")
	)
	(segment
		(start 399.617692 -176.26584)
		(end 400.558 -177.206148)
		(width 0.508)
		(layer "F.Cu")
		(net "PVCCINFAON_CPU0")
	)
	(segment
		(start 362.86948 -228.994716)
		(end 362.86948 -228.45903)
		(width 0.254)
		(layer "F.Cu")
		(net "PVCCINFAON_CPU0")
	)
	(segment
		(start 366.628934 -225.203512)
		(end 366.62868 -225.203258)
		(width 0.254)
		(layer "F.Cu")
		(net "PVCCINFAON_CPU0")
	)
	(segment
		(start 368.508534 -215.972644)
		(end 368.508534 -215.437212)
		(width 0.254)
		(layer "F.Cu")
		(net "PVCCINFAON_CPU0")
	)
	(segment
		(start 364.749334 -225.739198)
		(end 364.749334 -225.203512)
		(width 0.254)
		(layer "F.Cu")
		(net "PVCCINFAON_CPU0")
	)
	(segment
		(start 370.497862 -267.220192)
		(end 370.497862 -267.755878)
		(width 0.18034)
		(layer "F.Cu")
		(net "PVCCINFAON_CPU0")
	)
	(segment
		(start 369.558316 -267.219938)
		(end 369.558316 -267.755878)
		(width 0.254)
		(layer "F.Cu")
		(net "PVCCINFAON_CPU0")
	)
	(segment
		(start 374.147334 -225.203512)
		(end 374.14708 -225.203258)
		(width 0.254)
		(layer "F.Cu")
		(net "PVCCINFAON_CPU0")
	)
	(segment
		(start 352.641916 -264.500106)
		(end 352.641662 -264.50036)
		(width 0.381)
		(layer "F.Cu")
		(net "PVCCINFAON_CPU0")
	)
	(via
		(at 405.474932 -182.584598)
		(size 0.508)
		(drill 0.254)
		(layers "F.Cu" "B.Cu")
		(net "PVCCINFAON_CPU0")
	)
	(via
		(at 354.521262 -264.50036)
		(size 0.4572)
		(drill 0.2032)
		(layers "F.Cu" "B.Cu")
		(net "PVCCINFAON_CPU0")
	)
	(via
		(at 366.104678 -214.79129)
		(size 0.6604)
		(drill 0.3302)
		(layers "F.Cu" "B.Cu")
		(net "PVCCINFAON_CPU0")
	)
	(via
		(at 403.569932 -177.616358)
		(size 0.508)
		(drill 0.254)
		(layers "F.Cu" "B.Cu")
		(net "PVCCINFAON_CPU0")
	)
	(via
		(at 369.088162 -266.941808)
		(size 0.4572)
		(drill 0.2032)
		(layers "F.Cu" "B.Cu")
		(net "PVCCINFAON_CPU0")
	)
	(via
		(at 405.467312 -176.968658)
		(size 0.508)
		(drill 0.254)
		(layers "F.Cu" "B.Cu")
		(net "PVCCINFAON_CPU0")
	)
	(via
		(at 366.62868 -228.45903)
		(size 0.4572)
		(drill 0.2032)
		(layers "F.Cu" "B.Cu")
		(net "PVCCINFAON_CPU0")
	)
	(via
		(at 351.122234 -227.64496)
		(size 0.4572)
		(drill 0.2032)
		(layers "F.Cu" "B.Cu")
		(net "PVCCINFAON_CPU0")
	)
	(via
		(at 404.832312 -176.968658)
		(size 0.508)
		(drill 0.254)
		(layers "F.Cu" "B.Cu")
		(net "PVCCINFAON_CPU0")
	)
	(via
		(at 406.109932 -177.616358)
		(size 0.508)
		(drill 0.254)
		(layers "F.Cu" "B.Cu")
		(net "PVCCINFAON_CPU0")
	)
	(via
		(at 405.495252 -172.670978)
		(size 0.508)
		(drill 0.254)
		(layers "F.Cu" "B.Cu")
		(net "PVCCINFAON_CPU0")
	)
	(via
		(at 370.028216 -270.19758)
		(size 0.4572)
		(drill 0.2032)
		(layers "F.Cu" "B.Cu")
		(net "PVCCINFAON_CPU0")
	)
	(via
		(at 406.132792 -167.684958)
		(size 0.508)
		(drill 0.254)
		(layers "F.Cu" "B.Cu")
		(net "PVCCINFAON_CPU0")
	)
	(via
		(at 367.678716 -269.38351)
		(size 0.4572)
		(drill 0.2032)
		(layers "F.Cu" "B.Cu")
		(net "PVCCINFAON_CPU0")
	)
	(via
		(at 369.457478 -214.79129)
		(size 0.6604)
		(drill 0.3302)
		(layers "F.Cu" "B.Cu")
		(net "PVCCINFAON_CPU0")
	)
	(via
		(at 364.74908 -215.436704)
		(size 0.4572)
		(drill 0.2032)
		(layers "F.Cu" "B.Cu")
		(net "PVCCINFAON_CPU0")
	)
	(via
		(at 404.204932 -182.584598)
		(size 0.508)
		(drill 0.254)
		(layers "F.Cu" "B.Cu")
		(net "PVCCINFAON_CPU0")
	)
	(via
		(at 405.474932 -177.616358)
		(size 0.508)
		(drill 0.254)
		(layers "F.Cu" "B.Cu")
		(net "PVCCINFAON_CPU0")
	)
	(via
		(at 406.117552 -175.641508)
		(size 0.508)
		(drill 0.254)
		(layers "F.Cu" "B.Cu")
		(net "PVCCINFAON_CPU0")
	)
	(via
		(at 364.74908 -218.692222)
		(size 0.4572)
		(drill 0.2032)
		(layers "F.Cu" "B.Cu")
		(net "PVCCINFAON_CPU0")
	)
	(via
		(at 372.26748 -215.436704)
		(size 0.4572)
		(drill 0.2032)
		(layers "F.Cu" "B.Cu")
		(net "PVCCINFAON_CPU0")
	)
	(via
		(at 374.14708 -221.94774)
		(size 0.4572)
		(drill 0.2032)
		(layers "F.Cu" "B.Cu")
		(net "PVCCINFAON_CPU0")
	)
	(via
		(at 406.14854 -183.896508)
		(size 0.508)
		(drill 0.254)
		(layers "F.Cu" "B.Cu")
		(net "PVCCINFAON_CPU0")
	)
	(via
		(at 362.86948 -225.203258)
		(size 0.4572)
		(drill 0.2032)
		(layers "F.Cu" "B.Cu")
		(net "PVCCINFAON_CPU0")
	)
	(via
		(at 360.98988 -225.203258)
		(size 0.4572)
		(drill 0.2032)
		(layers "F.Cu" "B.Cu")
		(net "PVCCINFAON_CPU0")
	)
	(via
		(at 367.208562 -266.941808)
		(size 0.4572)
		(drill 0.2032)
		(layers "F.Cu" "B.Cu")
		(net "PVCCINFAON_CPU0")
	)
	(via
		(at 368.926364 -260.907276)
		(size 0.4572)
		(drill 0.2032)
		(layers "F.Cu" "B.Cu")
		(net "PVCCINFAON_CPU0")
	)
	(via
		(at 404.860252 -168.332658)
		(size 0.508)
		(drill 0.254)
		(layers "F.Cu" "B.Cu")
		(net "PVCCINFAON_CPU0")
	)
	(via
		(at 404.225252 -168.332658)
		(size 0.508)
		(drill 0.254)
		(layers "F.Cu" "B.Cu")
		(net "PVCCINFAON_CPU0")
	)
	(via
		(at 404.862792 -167.684958)
		(size 0.508)
		(drill 0.254)
		(layers "F.Cu" "B.Cu")
		(net "PVCCINFAON_CPU0")
	)
	(via
		(at 405.497792 -167.684958)
		(size 0.508)
		(drill 0.254)
		(layers "F.Cu" "B.Cu")
		(net "PVCCINFAON_CPU0")
	)
	(via
		(at 366.62868 -225.203258)
		(size 0.4572)
		(drill 0.2032)
		(layers "F.Cu" "B.Cu")
		(net "PVCCINFAON_CPU0")
	)
	(via
		(at 364.74908 -221.94774)
		(size 0.4572)
		(drill 0.2032)
		(layers "F.Cu" "B.Cu")
		(net "PVCCINFAON_CPU0")
	)
	(via
		(at 366.997996 -235.085382)
		(size 0.6604)
		(drill 0.3302)
		(layers "F.Cu" "B.Cu")
		(net "PVCCINFAON_CPU0")
	)
	(via
		(at 355.931216 -265.314176)
		(size 0.4572)
		(drill 0.2032)
		(layers "F.Cu" "B.Cu")
		(net "PVCCINFAON_CPU0")
	)
	(via
		(at 404.839932 -182.584598)
		(size 0.508)
		(drill 0.254)
		(layers "F.Cu" "B.Cu")
		(net "PVCCINFAON_CPU0")
	)
	(via
		(at 405.482552 -176.320958)
		(size 0.508)
		(drill 0.254)
		(layers "F.Cu" "B.Cu")
		(net "PVCCINFAON_CPU0")
	)
	(via
		(at 404.197312 -176.968658)
		(size 0.508)
		(drill 0.254)
		(layers "F.Cu" "B.Cu")
		(net "PVCCINFAON_CPU0")
	)
	(via
		(at 366.738916 -269.38351)
		(size 0.4572)
		(drill 0.2032)
		(layers "F.Cu" "B.Cu")
		(net "PVCCINFAON_CPU0")
	)
	(via
		(at 372.26748 -218.692222)
		(size 0.4572)
		(drill 0.2032)
		(layers "F.Cu" "B.Cu")
		(net "PVCCINFAON_CPU0")
	)
	(via
		(at 406.1079 -183.248808)
		(size 0.508)
		(drill 0.254)
		(layers "F.Cu" "B.Cu")
		(net "PVCCINFAON_CPU0")
	)
	(via
		(at 405.495252 -168.332658)
		(size 0.508)
		(drill 0.254)
		(layers "F.Cu" "B.Cu")
		(net "PVCCINFAON_CPU0")
	)
	(via
		(at 372.26748 -221.94774)
		(size 0.4572)
		(drill 0.2032)
		(layers "F.Cu" "B.Cu")
		(net "PVCCINFAON_CPU0")
	)
	(via
		(at 355.461316 -264.50036)
		(size 0.4572)
		(drill 0.2032)
		(layers "F.Cu" "B.Cu")
		(net "PVCCINFAON_CPU0")
	)
	(via
		(at 368.148362 -268.569694)
		(size 0.4572)
		(drill 0.2032)
		(layers "F.Cu" "B.Cu")
		(net "PVCCINFAON_CPU0")
	)
	(via
		(at 404.862792 -167.049958)
		(size 0.508)
		(drill 0.254)
		(layers "F.Cu" "B.Cu")
		(net "PVCCINFAON_CPU0")
	)
	(via
		(at 352.641662 -264.50036)
		(size 0.4572)
		(drill 0.2032)
		(layers "F.Cu" "B.Cu")
		(net "PVCCINFAON_CPU0")
	)
	(via
		(at 367.208562 -268.569694)
		(size 0.4572)
		(drill 0.2032)
		(layers "F.Cu" "B.Cu")
		(net "PVCCINFAON_CPU0")
	)
	(via
		(at 368.148616 -270.19758)
		(size 0.4572)
		(drill 0.2032)
		(layers "F.Cu" "B.Cu")
		(net "PVCCINFAON_CPU0")
	)
	(via
		(at 367.521236 -261.337806)
		(size 0.4572)
		(drill 0.2032)
		(layers "F.Cu" "B.Cu")
		(net "PVCCINFAON_CPU0")
	)
	(via
		(at 406.132792 -167.049958)
		(size 0.508)
		(drill 0.254)
		(layers "F.Cu" "B.Cu")
		(net "PVCCINFAON_CPU0")
	)
	(via
		(at 405.467312 -181.947058)
		(size 0.508)
		(drill 0.254)
		(layers "F.Cu" "B.Cu")
		(net "PVCCINFAON_CPU0")
	)
	(via
		(at 357.23068 -225.203258)
		(size 0.4572)
		(drill 0.2032)
		(layers "F.Cu" "B.Cu")
		(net "PVCCINFAON_CPU0")
	)
	(via
		(at 405.480012 -173.318678)
		(size 0.508)
		(drill 0.254)
		(layers "F.Cu" "B.Cu")
		(net "PVCCINFAON_CPU0")
	)
	(via
		(at 374.14708 -225.203258)
		(size 0.4572)
		(drill 0.2032)
		(layers "F.Cu" "B.Cu")
		(net "PVCCINFAON_CPU0")
	)
	(via
		(at 369.558316 -269.38351)
		(size 0.4572)
		(drill 0.2032)
		(layers "F.Cu" "B.Cu")
		(net "PVCCINFAON_CPU0")
	)
	(via
		(at 404.832312 -181.947058)
		(size 0.508)
		(drill 0.254)
		(layers "F.Cu" "B.Cu")
		(net "PVCCINFAON_CPU0")
	)
	(via
		(at 404.227792 -167.684958)
		(size 0.508)
		(drill 0.254)
		(layers "F.Cu" "B.Cu")
		(net "PVCCINFAON_CPU0")
	)
	(via
		(at 351.59188 -225.203258)
		(size 0.4572)
		(drill 0.2032)
		(layers "F.Cu" "B.Cu")
		(net "PVCCINFAON_CPU0")
	)
	(via
		(at 406.102312 -176.968658)
		(size 0.508)
		(drill 0.254)
		(layers "F.Cu" "B.Cu")
		(net "PVCCINFAON_CPU0")
	)
	(via
		(at 370.38788 -225.203258)
		(size 0.4572)
		(drill 0.2032)
		(layers "F.Cu" "B.Cu")
		(net "PVCCINFAON_CPU0")
	)
	(via
		(at 405.487632 -173.956218)
		(size 0.508)
		(drill 0.254)
		(layers "F.Cu" "B.Cu")
		(net "PVCCINFAON_CPU0")
	)
	(via
		(at 368.50828 -215.436704)
		(size 0.4572)
		(drill 0.2032)
		(layers "F.Cu" "B.Cu")
		(net "PVCCINFAON_CPU0")
	)
	(via
		(at 404.212552 -181.299358)
		(size 0.508)
		(drill 0.254)
		(layers "F.Cu" "B.Cu")
		(net "PVCCINFAON_CPU0")
	)
	(via
		(at 403.597872 -168.970198)
		(size 0.508)
		(drill 0.254)
		(layers "F.Cu" "B.Cu")
		(net "PVCCINFAON_CPU0")
	)
	(via
		(at 403.592792 -167.049958)
		(size 0.508)
		(drill 0.254)
		(layers "F.Cu" "B.Cu")
		(net "PVCCINFAON_CPU0")
	)
	(via
		(at 368.926364 -262.075676)
		(size 0.4572)
		(drill 0.2032)
		(layers "F.Cu" "B.Cu")
		(net "PVCCINFAON_CPU0")
	)
	(via
		(at 368.148616 -266.941808)
		(size 0.4572)
		(drill 0.2032)
		(layers "F.Cu" "B.Cu")
		(net "PVCCINFAON_CPU0")
	)
	(via
		(at 405.497792 -167.049958)
		(size 0.508)
		(drill 0.254)
		(layers "F.Cu" "B.Cu")
		(net "PVCCINFAON_CPU0")
	)
	(via
		(at 406.122632 -173.956218)
		(size 0.508)
		(drill 0.254)
		(layers "F.Cu" "B.Cu")
		(net "PVCCINFAON_CPU0")
	)
	(via
		(at 404.847552 -176.320958)
		(size 0.508)
		(drill 0.254)
		(layers "F.Cu" "B.Cu")
		(net "PVCCINFAON_CPU0")
	)
	(via
		(at 405.502872 -168.970198)
		(size 0.508)
		(drill 0.254)
		(layers "F.Cu" "B.Cu")
		(net "PVCCINFAON_CPU0")
	)
	(via
		(at 368.50828 -218.692222)
		(size 0.4572)
		(drill 0.2032)
		(layers "F.Cu" "B.Cu")
		(net "PVCCINFAON_CPU0")
	)
	(via
		(at 364.86338 -235.107988)
		(size 0.6604)
		(drill 0.3302)
		(layers "F.Cu" "B.Cu")
		(net "PVCCINFAON_CPU0")
	)
	(via
		(at 403.575012 -173.318678)
		(size 0.508)
		(drill 0.254)
		(layers "F.Cu" "B.Cu")
		(net "PVCCINFAON_CPU0")
	)
	(via
		(at 353.47148 -225.203258)
		(size 0.4572)
		(drill 0.2032)
		(layers "F.Cu" "B.Cu")
		(net "PVCCINFAON_CPU0")
	)
	(via
		(at 406.117552 -174.981108)
		(size 0.508)
		(drill 0.254)
		(layers "F.Cu" "B.Cu")
		(net "PVCCINFAON_CPU0")
	)
	(via
		(at 366.62868 -218.692222)
		(size 0.4572)
		(drill 0.2032)
		(layers "F.Cu" "B.Cu")
		(net "PVCCINFAON_CPU0")
	)
	(via
		(at 404.852632 -173.956218)
		(size 0.508)
		(drill 0.254)
		(layers "F.Cu" "B.Cu")
		(net "PVCCINFAON_CPU0")
	)
	(via
		(at 403.569932 -182.584598)
		(size 0.508)
		(drill 0.254)
		(layers "F.Cu" "B.Cu")
		(net "PVCCINFAON_CPU0")
	)
	(via
		(at 403.590252 -172.670978)
		(size 0.508)
		(drill 0.254)
		(layers "F.Cu" "B.Cu")
		(net "PVCCINFAON_CPU0")
	)
	(via
		(at 369.558062 -266.128246)
		(size 0.4572)
		(drill 0.2032)
		(layers "F.Cu" "B.Cu")
		(net "PVCCINFAON_CPU0")
	)
	(via
		(at 404.232872 -168.970198)
		(size 0.508)
		(drill 0.254)
		(layers "F.Cu" "B.Cu")
		(net "PVCCINFAON_CPU0")
	)
	(via
		(at 406.115012 -173.318678)
		(size 0.508)
		(drill 0.254)
		(layers "F.Cu" "B.Cu")
		(net "PVCCINFAON_CPU0")
	)
	(via
		(at 368.50828 -225.203258)
		(size 0.4572)
		(drill 0.2032)
		(layers "F.Cu" "B.Cu")
		(net "PVCCINFAON_CPU0")
	)
	(via
		(at 405.482552 -181.299358)
		(size 0.508)
		(drill 0.254)
		(layers "F.Cu" "B.Cu")
		(net "PVCCINFAON_CPU0")
	)
	(via
		(at 404.210012 -173.318678)
		(size 0.508)
		(drill 0.254)
		(layers "F.Cu" "B.Cu")
		(net "PVCCINFAON_CPU0")
	)
	(via
		(at 370.497862 -267.755878)
		(size 0.4572)
		(drill 0.2032)
		(layers "F.Cu" "B.Cu")
		(net "PVCCINFAON_CPU0")
	)
	(via
		(at 403.592792 -167.684958)
		(size 0.508)
		(drill 0.254)
		(layers "F.Cu" "B.Cu")
		(net "PVCCINFAON_CPU0")
	)
	(via
		(at 404.197312 -181.947058)
		(size 0.508)
		(drill 0.254)
		(layers "F.Cu" "B.Cu")
		(net "PVCCINFAON_CPU0")
	)
	(via
		(at 370.38788 -218.692222)
		(size 0.4572)
		(drill 0.2032)
		(layers "F.Cu" "B.Cu")
		(net "PVCCINFAON_CPU0")
	)
	(via
		(at 364.534958 -235.800392)
		(size 0.4572)
		(drill 0.2032)
		(layers "F.Cu" "B.Cu")
		(net "PVCCINFAON_CPU0")
	)
	(via
		(at 419.51529 -182.838344)
		(size 0.508)
		(drill 0.254)
		(layers "F.Cu" "B.Cu")
		(net "PVCCINFAON_CPU0")
	)
	(via
		(at 366.287558 -235.800392)
		(size 0.4572)
		(drill 0.2032)
		(layers "F.Cu" "B.Cu")
		(net "PVCCINFAON_CPU0")
	)
	(via
		(at 365.703358 -235.800392)
		(size 0.4572)
		(drill 0.2032)
		(layers "F.Cu" "B.Cu")
		(net "PVCCINFAON_CPU0")
	)
	(via
		(at 368.926364 -261.491476)
		(size 0.4572)
		(drill 0.2032)
		(layers "F.Cu" "B.Cu")
		(net "PVCCINFAON_CPU0")
	)
	(via
		(at 367.455958 -235.800392)
		(size 0.4572)
		(drill 0.2032)
		(layers "F.Cu" "B.Cu")
		(net "PVCCINFAON_CPU0")
	)
	(via
		(at 368.50828 -221.94774)
		(size 0.4572)
		(drill 0.2032)
		(layers "F.Cu" "B.Cu")
		(net "PVCCINFAON_CPU0")
	)
	(via
		(at 404.204932 -177.616358)
		(size 0.508)
		(drill 0.254)
		(layers "F.Cu" "B.Cu")
		(net "PVCCINFAON_CPU0")
	)
	(via
		(at 404.217632 -173.956218)
		(size 0.508)
		(drill 0.254)
		(layers "F.Cu" "B.Cu")
		(net "PVCCINFAON_CPU0")
	)
	(via
		(at 355.35108 -225.203258)
		(size 0.4572)
		(drill 0.2032)
		(layers "F.Cu" "B.Cu")
		(net "PVCCINFAON_CPU0")
	)
	(via
		(at 369.088416 -265.314176)
		(size 0.4572)
		(drill 0.2032)
		(layers "F.Cu" "B.Cu")
		(net "PVCCINFAON_CPU0")
	)
	(via
		(at 403.562312 -181.947058)
		(size 0.508)
		(drill 0.254)
		(layers "F.Cu" "B.Cu")
		(net "PVCCINFAON_CPU0")
	)
	(via
		(at 406.117552 -176.320958)
		(size 0.508)
		(drill 0.254)
		(layers "F.Cu" "B.Cu")
		(net "PVCCINFAON_CPU0")
	)
	(via
		(at 369.088416 -270.19758)
		(size 0.4572)
		(drill 0.2032)
		(layers "F.Cu" "B.Cu")
		(net "PVCCINFAON_CPU0")
	)
	(via
		(at 366.62868 -221.94774)
		(size 0.4572)
		(drill 0.2032)
		(layers "F.Cu" "B.Cu")
		(net "PVCCINFAON_CPU0")
	)
	(via
		(at 404.845012 -173.318678)
		(size 0.508)
		(drill 0.254)
		(layers "F.Cu" "B.Cu")
		(net "PVCCINFAON_CPU0")
	)
	(via
		(at 365.119158 -235.800392)
		(size 0.4572)
		(drill 0.2032)
		(layers "F.Cu" "B.Cu")
		(net "PVCCINFAON_CPU0")
	)
	(via
		(at 370.027962 -268.569694)
		(size 0.4572)
		(drill 0.2032)
		(layers "F.Cu" "B.Cu")
		(net "PVCCINFAON_CPU0")
	)
	(via
		(at 403.577552 -176.320958)
		(size 0.508)
		(drill 0.254)
		(layers "F.Cu" "B.Cu")
		(net "PVCCINFAON_CPU0")
	)
	(via
		(at 406.109932 -182.584598)
		(size 0.508)
		(drill 0.254)
		(layers "F.Cu" "B.Cu")
		(net "PVCCINFAON_CPU0")
	)
	(via
		(at 406.137872 -168.970198)
		(size 0.508)
		(drill 0.254)
		(layers "F.Cu" "B.Cu")
		(net "PVCCINFAON_CPU0")
	)
	(via
		(at 369.088416 -268.569694)
		(size 0.4572)
		(drill 0.2032)
		(layers "F.Cu" "B.Cu")
		(net "PVCCINFAON_CPU0")
	)
	(via
		(at 362.86948 -228.45903)
		(size 0.4572)
		(drill 0.2032)
		(layers "F.Cu" "B.Cu")
		(net "PVCCINFAON_CPU0")
	)
	(via
		(at 404.867872 -168.970198)
		(size 0.508)
		(drill 0.254)
		(layers "F.Cu" "B.Cu")
		(net "PVCCINFAON_CPU0")
	)
	(via
		(at 374.14708 -218.692222)
		(size 0.4572)
		(drill 0.2032)
		(layers "F.Cu" "B.Cu")
		(net "PVCCINFAON_CPU0")
	)
	(via
		(at 369.558316 -267.755878)
		(size 0.4572)
		(drill 0.2032)
		(layers "F.Cu" "B.Cu")
		(net "PVCCINFAON_CPU0")
	)
	(via
		(at 404.847552 -181.299358)
		(size 0.508)
		(drill 0.254)
		(layers "F.Cu" "B.Cu")
		(net "PVCCINFAON_CPU0")
	)
	(via
		(at 353.581462 -264.50036)
		(size 0.4572)
		(drill 0.2032)
		(layers "F.Cu" "B.Cu")
		(net "PVCCINFAON_CPU0")
	)
	(via
		(at 405.457152 -175.641508)
		(size 0.508)
		(drill 0.254)
		(layers "F.Cu" "B.Cu")
		(net "PVCCINFAON_CPU0")
	)
	(via
		(at 406.102312 -181.947058)
		(size 0.508)
		(drill 0.254)
		(layers "F.Cu" "B.Cu")
		(net "PVCCINFAON_CPU0")
	)
	(via
		(at 404.212552 -176.320958)
		(size 0.508)
		(drill 0.254)
		(layers "F.Cu" "B.Cu")
		(net "PVCCINFAON_CPU0")
	)
	(via
		(at 406.130252 -168.332658)
		(size 0.508)
		(drill 0.254)
		(layers "F.Cu" "B.Cu")
		(net "PVCCINFAON_CPU0")
	)
	(via
		(at 405.4475 -183.248808)
		(size 0.508)
		(drill 0.254)
		(layers "F.Cu" "B.Cu")
		(net "PVCCINFAON_CPU0")
	)
	(via
		(at 404.839932 -177.616358)
		(size 0.508)
		(drill 0.254)
		(layers "F.Cu" "B.Cu")
		(net "PVCCINFAON_CPU0")
	)
	(via
		(at 366.62868 -215.436704)
		(size 0.4572)
		(drill 0.2032)
		(layers "F.Cu" "B.Cu")
		(net "PVCCINFAON_CPU0")
	)
	(via
		(at 366.738916 -267.755878)
		(size 0.4572)
		(drill 0.2032)
		(layers "F.Cu" "B.Cu")
		(net "PVCCINFAON_CPU0")
	)
	(via
		(at 403.590252 -168.332658)
		(size 0.508)
		(drill 0.254)
		(layers "F.Cu" "B.Cu")
		(net "PVCCINFAON_CPU0")
	)
	(via
		(at 403.577552 -181.299358)
		(size 0.508)
		(drill 0.254)
		(layers "F.Cu" "B.Cu")
		(net "PVCCINFAON_CPU0")
	)
	(via
		(at 370.38788 -215.436704)
		(size 0.4572)
		(drill 0.2032)
		(layers "F.Cu" "B.Cu")
		(net "PVCCINFAON_CPU0")
	)
	(via
		(at 367.208816 -270.19758)
		(size 0.4572)
		(drill 0.2032)
		(layers "F.Cu" "B.Cu")
		(net "PVCCINFAON_CPU0")
	)
	(via
		(at 403.582632 -173.956218)
		(size 0.508)
		(drill 0.254)
		(layers "F.Cu" "B.Cu")
		(net "PVCCINFAON_CPU0")
	)
	(via
		(at 370.38788 -230.086662)
		(size 0.4572)
		(drill 0.2032)
		(layers "F.Cu" "B.Cu")
		(net "PVCCINFAON_CPU0")
	)
	(via
		(at 364.74908 -228.45903)
		(size 0.4572)
		(drill 0.2032)
		(layers "F.Cu" "B.Cu")
		(net "PVCCINFAON_CPU0")
	)
	(via
		(at 404.227792 -167.049958)
		(size 0.508)
		(drill 0.254)
		(layers "F.Cu" "B.Cu")
		(net "PVCCINFAON_CPU0")
	)
	(via
		(at 366.871758 -235.800392)
		(size 0.4572)
		(drill 0.2032)
		(layers "F.Cu" "B.Cu")
		(net "PVCCINFAON_CPU0")
	)
	(via
		(at 404.860252 -172.670978)
		(size 0.508)
		(drill 0.254)
		(layers "F.Cu" "B.Cu")
		(net "PVCCINFAON_CPU0")
	)
	(via
		(at 404.225252 -172.670978)
		(size 0.508)
		(drill 0.254)
		(layers "F.Cu" "B.Cu")
		(net "PVCCINFAON_CPU0")
	)
	(via
		(at 370.38788 -221.94774)
		(size 0.4572)
		(drill 0.2032)
		(layers "F.Cu" "B.Cu")
		(net "PVCCINFAON_CPU0")
	)
	(via
		(at 374.14708 -215.436704)
		(size 0.4572)
		(drill 0.2032)
		(layers "F.Cu" "B.Cu")
		(net "PVCCINFAON_CPU0")
	)
	(via
		(at 364.74908 -225.203258)
		(size 0.4572)
		(drill 0.2032)
		(layers "F.Cu" "B.Cu")
		(net "PVCCINFAON_CPU0")
	)
	(via
		(at 419.51529 -174.202344)
		(size 0.508)
		(drill 0.254)
		(layers "F.Cu" "B.Cu")
		(net "PVCCINFAON_CPU0")
	)
	(via
		(at 405.457152 -174.981108)
		(size 0.508)
		(drill 0.254)
		(layers "F.Cu" "B.Cu")
		(net "PVCCINFAON_CPU0")
	)
	(via
		(at 406.117552 -181.299358)
		(size 0.508)
		(drill 0.254)
		(layers "F.Cu" "B.Cu")
		(net "PVCCINFAON_CPU0")
	)
	(via
		(at 403.562312 -176.968658)
		(size 0.508)
		(drill 0.254)
		(layers "F.Cu" "B.Cu")
		(net "PVCCINFAON_CPU0")
	)
	(via
		(at 368.618516 -267.755878)
		(size 0.4572)
		(drill 0.2032)
		(layers "F.Cu" "B.Cu")
		(net "PVCCINFAON_CPU0")
	)
	(via
		(at 406.130252 -172.670978)
		(size 0.508)
		(drill 0.254)
		(layers "F.Cu" "B.Cu")
		(net "PVCCINFAON_CPU0")
	)
	(via
		(at 372.26748 -225.203258)
		(size 0.4572)
		(drill 0.2032)
		(layers "F.Cu" "B.Cu")
		(net "PVCCINFAON_CPU0")
	)
	(segment
		(start 400.558 -183.429148)
		(end 401.498308 -184.369456)
		(width 0.508)
		(layer "B.Cu")
		(net "PVCCINFAON_CPU0")
	)
	(segment
		(start 400.558 -177.206148)
		(end 401.498308 -176.26584)
		(width 0.508)
		(layer "B.Cu")
		(net "PVCCINFAON_CPU0")
	)
	(segment
		(start 399.617692 -176.26584)
		(end 400.558 -177.206148)
		(width 0.508)
		(layer "B.Cu")
		(net "PVCCINFAON_CPU0")
	)
	(segment
		(start 419.46449 -174.253144)
		(end 419.374066 -174.253144)
		(width 0.254)
		(layer "B.Cu")
		(net "PVCCINFAON_CPU0")
	)
	(segment
		(start 399.617692 -178.146456)
		(end 400.558 -177.206148)
		(width 0.508)
		(layer "B.Cu")
		(net "PVCCINFAON_CPU0")
	)
	(segment
		(start 419.51529 -182.838344)
		(end 419.46449 -182.889144)
		(width 0.254)
		(layer "B.Cu")
		(net "PVCCINFAON_CPU0")
	)
	(segment
		(start 399.617692 -170.04284)
		(end 400.558 -170.983148)
		(width 0.508)
		(layer "B.Cu")
		(net "PVCCINFAON_CPU0")
	)
	(segment
		(start 419.46449 -182.889144)
		(end 419.408864 -182.889144)
		(width 0.254)
		(layer "B.Cu")
		(net "PVCCINFAON_CPU0")
	)
	(segment
		(start 399.617692 -182.48884)
		(end 400.558 -183.429148)
		(width 0.508)
		(layer "B.Cu")
		(net "PVCCINFAON_CPU0")
	)
	(segment
		(start 419.408864 -182.889144)
		(end 418.970714 -183.327294)
		(width 0.254)
		(layer "B.Cu")
		(net "PVCCINFAON_CPU0")
	)
	(segment
		(start 419.374066 -174.253144)
		(end 418.940742 -174.686468)
		(width 0.254)
		(layer "B.Cu")
		(net "PVCCINFAON_CPU0")
	)
	(segment
		(start 419.51529 -174.202344)
		(end 419.46449 -174.253144)
		(width 0.254)
		(layer "B.Cu")
		(net "PVCCINFAON_CPU0")
	)
	(segment
		(start 400.558 -170.983148)
		(end 401.498308 -170.04284)
		(width 0.508)
		(layer "B.Cu")
		(net "PVCCINFAON_CPU0")
	)
	(segment
		(start 400.558 -170.983148)
		(end 401.498308 -171.923456)
		(width 0.508)
		(layer "B.Cu")
		(net "PVCCINFAON_CPU0")
	)
	(segment
		(start 400.558 -177.206148)
		(end 401.498308 -178.146456)
		(width 0.508)
		(layer "B.Cu")
		(net "PVCCINFAON_CPU0")
	)
	(segment
		(start 400.558 -183.429148)
		(end 401.498308 -182.48884)
		(width 0.508)
		(layer "B.Cu")
		(net "PVCCINFAON_CPU0")
	)
	(segment
		(start 400.558 -183.429148)
		(end 399.617692 -184.369456)
		(width 0.508)
		(layer "B.Cu")
		(net "PVCCINFAON_CPU0")
	)
	(segment
		(start 374.14708 -218.692222)
		(end 374.14708 -218.201748)
		(width 0.381)
		(layer "B.Cu")
		(net "PVCCINFAON_CPU0")
	)
	(segment
		(start 399.617692 -171.923456)
		(end 400.558 -170.983148)
		(width 0.508)
		(layer "B.Cu")
		(net "PVCCINFAON_CPU0")
	)
	(segment
		(start 418.71392 -174.341028)
		(end 417.96716 -173.594268)
		(width 0.381)
		(layer "In2.Cu")
		(net "PVCCINFAON_CPU0")
	)
	(segment
		(start 351.59188 -225.203258)
		(end 351.59188 -226.129088)
		(width 0.254)
		(layer "In2.Cu")
		(net "PVCCINFAON_CPU0")
	)
	(segment
		(start 360.98988 -225.203258)
		(end 360.98988 -226.129088)
		(width 0.254)
		(layer "In2.Cu")
		(net "PVCCINFAON_CPU0")
	)
	(segment
		(start 419.51529 -174.202344)
		(end 419.376606 -174.341028)
		(width 0.381)
		(layer "In2.Cu")
		(net "PVCCINFAON_CPU0")
	)
	(segment
		(start 417.96716 -173.594268)
		(end 413.77362 -173.594268)
		(width 0.381)
		(layer "In2.Cu")
		(net "PVCCINFAON_CPU0")
	)
	(segment
		(start 368.657632 -225.203258)
		(end 368.50828 -225.203258)
		(width 0.381)
		(layer "In2.Cu")
		(net "PVCCINFAON_CPU0")
	)
	(segment
		(start 355.35108 -225.203258)
		(end 355.35108 -226.129088)
		(width 0.254)
		(layer "In2.Cu")
		(net "PVCCINFAON_CPU0")
	)
	(segment
		(start 357.23068 -225.203258)
		(end 357.23068 -226.129088)
		(width 0.254)
		(layer "In2.Cu")
		(net "PVCCINFAON_CPU0")
	)
	(segment
		(start 413.77362 -173.594268)
		(end 412.85033 -172.670978)
		(width 0.381)
		(layer "In2.Cu")
		(net "PVCCINFAON_CPU0")
	)
	(segment
		(start 417.96462 -182.230268)
		(end 413.76854 -182.230268)
		(width 0.381)
		(layer "In2.Cu")
		(net "PVCCINFAON_CPU0")
	)
	(segment
		(start 419.376606 -174.341028)
		(end 418.71392 -174.341028)
		(width 0.381)
		(layer "In2.Cu")
		(net "PVCCINFAON_CPU0")
	)
	(segment
		(start 368.895884 -225.44151)
		(end 368.657632 -225.203258)
		(width 0.381)
		(layer "In2.Cu")
		(net "PVCCINFAON_CPU0")
	)
	(segment
		(start 419.495986 -182.857648)
		(end 418.592 -182.857648)
		(width 0.381)
		(layer "In2.Cu")
		(net "PVCCINFAON_CPU0")
	)
	(segment
		(start 412.83763 -181.299358)
		(end 406.117552 -181.299358)
		(width 0.381)
		(layer "In2.Cu")
		(net "PVCCINFAON_CPU0")
	)
	(segment
		(start 366.62868 -225.203258)
		(end 366.62868 -226.129088)
		(width 0.254)
		(layer "In2.Cu")
		(net "PVCCINFAON_CPU0")
	)
	(segment
		(start 419.51529 -182.838344)
		(end 419.495986 -182.857648)
		(width 0.381)
		(layer "In2.Cu")
		(net "PVCCINFAON_CPU0")
	)
	(segment
		(start 412.85033 -172.670978)
		(end 406.130252 -172.670978)
		(width 0.381)
		(layer "In2.Cu")
		(net "PVCCINFAON_CPU0")
	)
	(segment
		(start 364.74908 -225.203258)
		(end 364.74908 -226.129088)
		(width 0.254)
		(layer "In2.Cu")
		(net "PVCCINFAON_CPU0")
	)
	(segment
		(start 413.76854 -182.230268)
		(end 412.83763 -181.299358)
		(width 0.381)
		(layer "In2.Cu")
		(net "PVCCINFAON_CPU0")
	)
	(segment
		(start 353.47148 -225.203258)
		(end 353.47148 -226.129088)
		(width 0.254)
		(layer "In2.Cu")
		(net "PVCCINFAON_CPU0")
	)
	(segment
		(start 362.86948 -225.203258)
		(end 362.86948 -226.129088)
		(width 0.254)
		(layer "In2.Cu")
		(net "PVCCINFAON_CPU0")
	)
	(segment
		(start 418.592 -182.857648)
		(end 417.96462 -182.230268)
		(width 0.381)
		(layer "In2.Cu")
		(net "PVCCINFAON_CPU0")
	)
	(segment
		(start 399.842228 -182.713376)
		(end 400.558 -183.429148)
		(width 0.508)
		(layer "In15.Cu")
		(net "PVCCINFAON_CPU0")
	)
	(segment
		(start 399.842228 -171.69892)
		(end 400.558 -170.983148)
		(width 0.508)
		(layer "In15.Cu")
		(net "PVCCINFAON_CPU0")
	)
	(segment
		(start 400.558 -183.429148)
		(end 401.273772 -184.14492)
		(width 0.508)
		(layer "In15.Cu")
		(net "PVCCINFAON_CPU0")
	)
	(segment
		(start 400.558 -183.429148)
		(end 401.273772 -182.713376)
		(width 0.508)
		(layer "In15.Cu")
		(net "PVCCINFAON_CPU0")
	)
	(segment
		(start 400.558 -177.206148)
		(end 401.273772 -176.490376)
		(width 0.508)
		(layer "In15.Cu")
		(net "PVCCINFAON_CPU0")
	)
	(segment
		(start 399.842228 -176.490376)
		(end 400.558 -177.206148)
		(width 0.508)
		(layer "In15.Cu")
		(net "PVCCINFAON_CPU0")
	)
	(segment
		(start 353.71659 -225.203258)
		(end 353.47148 -225.203258)
		(width 0.254)
		(layer "In15.Cu")
		(net "PVCCINFAON_CPU0")
	)
	(segment
		(start 399.842228 -184.14492)
		(end 400.558 -183.429148)
		(width 0.508)
		(layer "In15.Cu")
		(net "PVCCINFAON_CPU0")
	)
	(segment
		(start 400.558 -170.983148)
		(end 401.273772 -171.69892)
		(width 0.508)
		(layer "In15.Cu")
		(net "PVCCINFAON_CPU0")
	)
	(segment
		(start 399.842228 -177.92192)
		(end 400.558 -177.206148)
		(width 0.508)
		(layer "In15.Cu")
		(net "PVCCINFAON_CPU0")
	)
	(segment
		(start 400.558 -170.983148)
		(end 401.273772 -170.267376)
		(width 0.508)
		(layer "In15.Cu")
		(net "PVCCINFAON_CPU0")
	)
	(segment
		(start 354.0125 -225.499168)
		(end 353.71659 -225.203258)
		(width 0.254)
		(layer "In15.Cu")
		(net "PVCCINFAON_CPU0")
	)
	(segment
		(start 400.558 -177.206148)
		(end 401.273772 -177.92192)
		(width 0.508)
		(layer "In15.Cu")
		(net "PVCCINFAON_CPU0")
	)
	(segment
		(start 399.842228 -170.267376)
		(end 400.558 -170.983148)
		(width 0.508)
		(layer "In15.Cu")
		(net "PVCCINFAON_CPU0")
	)
	(segment
		(start 38.781736 -356.476554)
		(end 39.165022 -356.093268)
		(width 0.2286)
		(layer "F.Cu")
		(net "PVCCFA_EHV_FIVRA_CPU1_VOS4")
	)
	(segment
		(start 39.165022 -356.093268)
		(end 39.165022 -355.823012)
		(width 0.2286)
		(layer "F.Cu")
		(net "PVCCFA_EHV_FIVRA_CPU1_VOS4")
	)
	(via
		(at 38.781736 -356.476554)
		(size 0.508)
		(drill 0.254)
		(layers "F.Cu" "B.Cu")
		(net "PVCCFA_EHV_FIVRA_CPU1_VOS4")
	)
	(segment
		(start 38.781736 -357.291386)
		(end 38.49751 -357.575612)
		(width 0.2286)
		(layer "B.Cu")
		(net "PVCCFA_EHV_FIVRA_CPU1_VOS4")
	)
	(segment
		(start 38.781736 -356.476554)
		(end 38.781736 -357.291386)
		(width 0.2286)
		(layer "B.Cu")
		(net "PVCCFA_EHV_FIVRA_CPU1_VOS4")
	)
	(segment
		(start 178.929284 -356.482904)
		(end 179.31257 -356.099618)
		(width 0.2286)
		(layer "F.Cu")
		(net "PVCCFA_EHV_FIVRA_CPU1_VOS3")
	)
	(segment
		(start 179.31257 -356.099618)
		(end 179.31257 -355.829362)
		(width 0.2286)
		(layer "F.Cu")
		(net "PVCCFA_EHV_FIVRA_CPU1_VOS3")
	)
	(via
		(at 178.929284 -356.482904)
		(size 0.508)
		(drill 0.254)
		(layers "F.Cu" "B.Cu")
		(net "PVCCFA_EHV_FIVRA_CPU1_VOS3")
	)
	(segment
		(start 178.49469 -356.24135)
		(end 178.26482 -356.01148)
		(width 0.2032)
		(layer "B.Cu")
		(net "PVCCFA_EHV_FIVRA_CPU1_VOS3")
	)
	(segment
		(start 178.68773 -356.24135)
		(end 178.49469 -356.24135)
		(width 0.2032)
		(layer "B.Cu")
		(net "PVCCFA_EHV_FIVRA_CPU1_VOS3")
	)
	(segment
		(start 178.929284 -356.482904)
		(end 178.68773 -356.24135)
		(width 0.2032)
		(layer "B.Cu")
		(net "PVCCFA_EHV_FIVRA_CPU1_VOS3")
	)
	(segment
		(start 48.470058 -356.476554)
		(end 48.853344 -356.093268)
		(width 0.2286)
		(layer "F.Cu")
		(net "PVCCFA_EHV_FIVRA_CPU1_VOS2")
	)
	(segment
		(start 48.853344 -356.093268)
		(end 48.853344 -355.823012)
		(width 0.2286)
		(layer "F.Cu")
		(net "PVCCFA_EHV_FIVRA_CPU1_VOS2")
	)
	(via
		(at 48.470058 -356.476554)
		(size 0.508)
		(drill 0.254)
		(layers "F.Cu" "B.Cu")
		(net "PVCCFA_EHV_FIVRA_CPU1_VOS2")
	)
	(segment
		(start 48.470058 -357.035354)
		(end 48.506634 -357.07193)
		(width 0.2032)
		(layer "B.Cu")
		(net "PVCCFA_EHV_FIVRA_CPU1_VOS2")
	)
	(segment
		(start 48.470058 -356.476554)
		(end 48.470058 -357.035354)
		(width 0.2032)
		(layer "B.Cu")
		(net "PVCCFA_EHV_FIVRA_CPU1_VOS2")
	)
	(segment
		(start 48.506634 -357.07193)
		(end 48.506634 -357.52913)
		(width 0.2032)
		(layer "B.Cu")
		(net "PVCCFA_EHV_FIVRA_CPU1_VOS2")
	)
	(segment
		(start 169.240962 -356.482904)
		(end 169.624248 -356.099618)
		(width 0.2286)
		(layer "F.Cu")
		(net "PVCCFA_EHV_FIVRA_CPU1_VOS1")
	)
	(segment
		(start 169.624248 -356.099618)
		(end 169.624248 -355.829362)
		(width 0.2286)
		(layer "F.Cu")
		(net "PVCCFA_EHV_FIVRA_CPU1_VOS1")
	)
	(via
		(at 169.240962 -356.482904)
		(size 0.508)
		(drill 0.254)
		(layers "F.Cu" "B.Cu")
		(net "PVCCFA_EHV_FIVRA_CPU1_VOS1")
	)
	(segment
		(start 168.803066 -356.045008)
		(end 168.156636 -356.045008)
		(width 0.2286)
		(layer "B.Cu")
		(net "PVCCFA_EHV_FIVRA_CPU1_VOS1")
	)
	(segment
		(start 169.240962 -356.482904)
		(end 168.803066 -356.045008)
		(width 0.2286)
		(layer "B.Cu")
		(net "PVCCFA_EHV_FIVRA_CPU1_VOS1")
	)
	(segment
		(start 168.156636 -356.045008)
		(end 168.133268 -356.02164)
		(width 0.2286)
		(layer "B.Cu")
		(net "PVCCFA_EHV_FIVRA_CPU1_VOS1")
	)
	(segment
		(start 38.063424 -355.62413)
		(end 38.764718 -354.922836)
		(width 0.2032)
		(layer "F.Cu")
		(net "PVCCFA_EHV_FIVRA_CPU1_VDD4")
	)
	(segment
		(start 41.213278 -357.274876)
		(end 41.375076 -356.879398)
		(width 0.2286)
		(layer "F.Cu")
		(net "PVCCFA_EHV_FIVRA_CPU1_VDD4")
	)
	(segment
		(start 37.990272 -355.01453)
		(end 37.990272 -355.62413)
		(width 0.2032)
		(layer "F.Cu")
		(net "PVCCFA_EHV_FIVRA_CPU1_VDD4")
	)
	(segment
		(start 38.764718 -354.922836)
		(end 39.165022 -354.922836)
		(width 0.2032)
		(layer "F.Cu")
		(net "PVCCFA_EHV_FIVRA_CPU1_VDD4")
	)
	(segment
		(start 41.375076 -356.879398)
		(end 41.375076 -356.447852)
		(width 0.2286)
		(layer "F.Cu")
		(net "PVCCFA_EHV_FIVRA_CPU1_VDD4")
	)
	(segment
		(start 37.990272 -355.62413)
		(end 38.063424 -355.62413)
		(width 0.2032)
		(layer "F.Cu")
		(net "PVCCFA_EHV_FIVRA_CPU1_VDD4")
	)
	(via
		(at 40.535098 -356.596696)
		(size 0.6604)
		(drill 0.3302)
		(layers "F.Cu" "B.Cu")
		(net "PVCCFA_EHV_FIVRA_CPU1_VDD4")
	)
	(via
		(at 41.213278 -357.274876)
		(size 0.508)
		(drill 0.254)
		(layers "F.Cu" "B.Cu")
		(net "PVCCFA_EHV_FIVRA_CPU1_VDD4")
	)
	(via
		(at 37.990272 -355.01453)
		(size 0.508)
		(drill 0.254)
		(layers "F.Cu" "B.Cu")
		(net "PVCCFA_EHV_FIVRA_CPU1_VDD4")
	)
	(segment
		(start 39.062406 -355.792024)
		(end 39.062406 -354.965254)
		(width 0.2286)
		(layer "B.Cu")
		(net "PVCCFA_EHV_FIVRA_CPU1_VDD4")
	)
	(segment
		(start 40.535098 -356.596696)
		(end 39.867078 -356.596696)
		(width 0.2286)
		(layer "B.Cu")
		(net "PVCCFA_EHV_FIVRA_CPU1_VDD4")
	)
	(segment
		(start 37.990272 -355.01453)
		(end 38.039548 -354.965254)
		(width 0.254)
		(layer "B.Cu")
		(net "PVCCFA_EHV_FIVRA_CPU1_VDD4")
	)
	(segment
		(start 38.039548 -354.965254)
		(end 39.062406 -354.965254)
		(width 0.254)
		(layer "B.Cu")
		(net "PVCCFA_EHV_FIVRA_CPU1_VDD4")
	)
	(segment
		(start 39.867078 -356.596696)
		(end 39.062406 -355.792024)
		(width 0.2286)
		(layer "B.Cu")
		(net "PVCCFA_EHV_FIVRA_CPU1_VDD4")
	)
	(segment
		(start 41.213278 -357.274876)
		(end 40.535098 -356.596696)
		(width 0.2286)
		(layer "B.Cu")
		(net "PVCCFA_EHV_FIVRA_CPU1_VDD4")
	)
	(segment
		(start 181.360826 -357.281226)
		(end 181.522624 -356.884478)
		(width 0.2286)
		(layer "F.Cu")
		(net "PVCCFA_EHV_FIVRA_CPU1_VDD3")
	)
	(segment
		(start 178.13782 -355.01453)
		(end 178.13782 -355.63048)
		(width 0.2032)
		(layer "F.Cu")
		(net "PVCCFA_EHV_FIVRA_CPU1_VDD3")
	)
	(segment
		(start 181.522624 -356.884478)
		(end 181.522624 -356.454202)
		(width 0.2286)
		(layer "F.Cu")
		(net "PVCCFA_EHV_FIVRA_CPU1_VDD3")
	)
	(segment
		(start 178.223164 -355.63048)
		(end 178.924458 -354.929186)
		(width 0.2032)
		(layer "F.Cu")
		(net "PVCCFA_EHV_FIVRA_CPU1_VDD3")
	)
	(segment
		(start 178.13782 -355.63048)
		(end 178.223164 -355.63048)
		(width 0.2032)
		(layer "F.Cu")
		(net "PVCCFA_EHV_FIVRA_CPU1_VDD3")
	)
	(segment
		(start 178.924458 -354.929186)
		(end 179.31257 -354.929186)
		(width 0.2032)
		(layer "F.Cu")
		(net "PVCCFA_EHV_FIVRA_CPU1_VDD3")
	)
	(via
		(at 181.360826 -357.281226)
		(size 0.508)
		(drill 0.254)
		(layers "F.Cu" "B.Cu")
		(net "PVCCFA_EHV_FIVRA_CPU1_VDD3")
	)
	(via
		(at 179.864004 -356.446074)
		(size 0.6604)
		(drill 0.3302)
		(layers "F.Cu" "B.Cu")
		(net "PVCCFA_EHV_FIVRA_CPU1_VDD3")
	)
	(via
		(at 178.13782 -355.01453)
		(size 0.508)
		(drill 0.254)
		(layers "F.Cu" "B.Cu")
		(net "PVCCFA_EHV_FIVRA_CPU1_VDD3")
	)
	(segment
		(start 178.187096 -354.965254)
		(end 178.803554 -354.965254)
		(width 0.2286)
		(layer "B.Cu")
		(net "PVCCFA_EHV_FIVRA_CPU1_VDD3")
	)
	(segment
		(start 180.21173 -356.7938)
		(end 179.864004 -356.446074)
		(width 0.2286)
		(layer "B.Cu")
		(net "PVCCFA_EHV_FIVRA_CPU1_VDD3")
	)
	(segment
		(start 178.13782 -355.01453)
		(end 178.187096 -354.965254)
		(width 0.2286)
		(layer "B.Cu")
		(net "PVCCFA_EHV_FIVRA_CPU1_VDD3")
	)
	(segment
		(start 178.803554 -355.385624)
		(end 178.803554 -354.965254)
		(width 0.2286)
		(layer "B.Cu")
		(net "PVCCFA_EHV_FIVRA_CPU1_VDD3")
	)
	(segment
		(start 181.360826 -357.281226)
		(end 180.8734 -356.7938)
		(width 0.2286)
		(layer "B.Cu")
		(net "PVCCFA_EHV_FIVRA_CPU1_VDD3")
	)
	(segment
		(start 180.8734 -356.7938)
		(end 180.21173 -356.7938)
		(width 0.2286)
		(layer "B.Cu")
		(net "PVCCFA_EHV_FIVRA_CPU1_VDD3")
	)
	(segment
		(start 179.864004 -356.446074)
		(end 178.803554 -355.385624)
		(width 0.2286)
		(layer "B.Cu")
		(net "PVCCFA_EHV_FIVRA_CPU1_VDD3")
	)
	(segment
		(start 47.763938 -355.62413)
		(end 48.465232 -354.922836)
		(width 0.2032)
		(layer "F.Cu")
		(net "PVCCFA_EHV_FIVRA_CPU1_VDD2")
	)
	(segment
		(start 50.924968 -357.298244)
		(end 51.063398 -356.99573)
		(width 0.2286)
		(layer "F.Cu")
		(net "PVCCFA_EHV_FIVRA_CPU1_VDD2")
	)
	(segment
		(start 47.678594 -355.00818)
		(end 47.678594 -355.62413)
		(width 0.2032)
		(layer "F.Cu")
		(net "PVCCFA_EHV_FIVRA_CPU1_VDD2")
	)
	(segment
		(start 48.465232 -354.922836)
		(end 48.853344 -354.922836)
		(width 0.2032)
		(layer "F.Cu")
		(net "PVCCFA_EHV_FIVRA_CPU1_VDD2")
	)
	(segment
		(start 51.063398 -356.99573)
		(end 51.063398 -356.447852)
		(width 0.2286)
		(layer "F.Cu")
		(net "PVCCFA_EHV_FIVRA_CPU1_VDD2")
	)
	(segment
		(start 47.678594 -355.62413)
		(end 47.763938 -355.62413)
		(width 0.2032)
		(layer "F.Cu")
		(net "PVCCFA_EHV_FIVRA_CPU1_VDD2")
	)
	(via
		(at 50.924968 -357.298244)
		(size 0.508)
		(drill 0.254)
		(layers "F.Cu" "B.Cu")
		(net "PVCCFA_EHV_FIVRA_CPU1_VDD2")
	)
	(via
		(at 50.15484 -356.78745)
		(size 0.6604)
		(drill 0.3302)
		(layers "F.Cu" "B.Cu")
		(net "PVCCFA_EHV_FIVRA_CPU1_VDD2")
	)
	(via
		(at 47.678594 -355.00818)
		(size 0.508)
		(drill 0.254)
		(layers "F.Cu" "B.Cu")
		(net "PVCCFA_EHV_FIVRA_CPU1_VDD2")
	)
	(segment
		(start 47.72787 -354.958904)
		(end 48.344328 -354.958904)
		(width 0.2286)
		(layer "B.Cu")
		(net "PVCCFA_EHV_FIVRA_CPU1_VDD2")
	)
	(segment
		(start 50.414174 -356.78745)
		(end 50.924968 -357.298244)
		(width 0.2286)
		(layer "B.Cu")
		(net "PVCCFA_EHV_FIVRA_CPU1_VDD2")
	)
	(segment
		(start 48.344328 -355.379274)
		(end 49.752504 -356.78745)
		(width 0.2286)
		(layer "B.Cu")
		(net "PVCCFA_EHV_FIVRA_CPU1_VDD2")
	)
	(segment
		(start 47.678594 -355.00818)
		(end 47.72787 -354.958904)
		(width 0.2286)
		(layer "B.Cu")
		(net "PVCCFA_EHV_FIVRA_CPU1_VDD2")
	)
	(segment
		(start 50.15484 -356.78745)
		(end 50.414174 -356.78745)
		(width 0.2286)
		(layer "B.Cu")
		(net "PVCCFA_EHV_FIVRA_CPU1_VDD2")
	)
	(segment
		(start 49.752504 -356.78745)
		(end 50.15484 -356.78745)
		(width 0.2286)
		(layer "B.Cu")
		(net "PVCCFA_EHV_FIVRA_CPU1_VDD2")
	)
	(segment
		(start 48.344328 -354.958904)
		(end 48.344328 -355.379274)
		(width 0.2286)
		(layer "B.Cu")
		(net "PVCCFA_EHV_FIVRA_CPU1_VDD2")
	)
	(segment
		(start 169.264584 -354.929186)
		(end 168.56329 -355.63048)
		(width 0.2032)
		(layer "F.Cu")
		(net "PVCCFA_EHV_FIVRA_CPU1_VDD1")
	)
	(segment
		(start 171.672504 -357.281226)
		(end 171.834302 -356.896162)
		(width 0.2286)
		(layer "F.Cu")
		(net "PVCCFA_EHV_FIVRA_CPU1_VDD1")
	)
	(segment
		(start 171.834302 -356.896162)
		(end 171.834302 -356.454202)
		(width 0.2286)
		(layer "F.Cu")
		(net "PVCCFA_EHV_FIVRA_CPU1_VDD1")
	)
	(segment
		(start 168.449498 -355.02088)
		(end 168.449498 -355.63048)
		(width 0.2286)
		(layer "F.Cu")
		(net "PVCCFA_EHV_FIVRA_CPU1_VDD1")
	)
	(segment
		(start 169.624248 -354.929186)
		(end 169.264584 -354.929186)
		(width 0.2032)
		(layer "F.Cu")
		(net "PVCCFA_EHV_FIVRA_CPU1_VDD1")
	)
	(segment
		(start 168.56329 -355.63048)
		(end 168.449498 -355.63048)
		(width 0.2032)
		(layer "F.Cu")
		(net "PVCCFA_EHV_FIVRA_CPU1_VDD1")
	)
	(via
		(at 170.884342 -356.650544)
		(size 0.6604)
		(drill 0.3302)
		(layers "F.Cu" "B.Cu")
		(net "PVCCFA_EHV_FIVRA_CPU1_VDD1")
	)
	(via
		(at 171.672504 -357.281226)
		(size 0.508)
		(drill 0.254)
		(layers "F.Cu" "B.Cu")
		(net "PVCCFA_EHV_FIVRA_CPU1_VDD1")
	)
	(via
		(at 168.449498 -355.02088)
		(size 0.508)
		(drill 0.254)
		(layers "F.Cu" "B.Cu")
		(net "PVCCFA_EHV_FIVRA_CPU1_VDD1")
	)
	(segment
		(start 170.373802 -356.650544)
		(end 170.884342 -356.650544)
		(width 0.2286)
		(layer "B.Cu")
		(net "PVCCFA_EHV_FIVRA_CPU1_VDD1")
	)
	(segment
		(start 170.884342 -356.650544)
		(end 171.033948 -356.80015)
		(width 0.2286)
		(layer "B.Cu")
		(net "PVCCFA_EHV_FIVRA_CPU1_VDD1")
	)
	(segment
		(start 171.191428 -356.80015)
		(end 171.672504 -357.281226)
		(width 0.2286)
		(layer "B.Cu")
		(net "PVCCFA_EHV_FIVRA_CPU1_VDD1")
	)
	(segment
		(start 171.033948 -356.80015)
		(end 171.191428 -356.80015)
		(width 0.2286)
		(layer "B.Cu")
		(net "PVCCFA_EHV_FIVRA_CPU1_VDD1")
	)
	(segment
		(start 169.521632 -354.971604)
		(end 169.521632 -355.798374)
		(width 0.2286)
		(layer "B.Cu")
		(net "PVCCFA_EHV_FIVRA_CPU1_VDD1")
	)
	(segment
		(start 168.498774 -354.971604)
		(end 169.521632 -354.971604)
		(width 0.254)
		(layer "B.Cu")
		(net "PVCCFA_EHV_FIVRA_CPU1_VDD1")
	)
	(segment
		(start 169.521632 -355.798374)
		(end 170.373802 -356.650544)
		(width 0.2286)
		(layer "B.Cu")
		(net "PVCCFA_EHV_FIVRA_CPU1_VDD1")
	)
	(segment
		(start 168.449498 -355.02088)
		(end 168.498774 -354.971604)
		(width 0.254)
		(layer "B.Cu")
		(net "PVCCFA_EHV_FIVRA_CPU1_VDD1")
	)
	(segment
		(start 41.656 -357.850948)
		(end 41.825164 -357.51643)
		(width 0.1524)
		(layer "F.Cu")
		(net "PVCCFA_EHV_FIVRA_CPU1_PWM4")
	)
	(segment
		(start 109.578394 -362.83519)
		(end 109.578394 -361.723432)
		(width 0.1778)
		(layer "F.Cu")
		(net "PVCCFA_EHV_FIVRA_CPU1_PWM4")
	)
	(segment
		(start 110.118906 -363.375702)
		(end 109.578394 -362.83519)
		(width 0.1778)
		(layer "F.Cu")
		(net "PVCCFA_EHV_FIVRA_CPU1_PWM4")
	)
	(segment
		(start 41.825164 -357.51643)
		(end 41.825164 -356.447852)
		(width 0.1524)
		(layer "F.Cu")
		(net "PVCCFA_EHV_FIVRA_CPU1_PWM4")
	)
	(via
		(at 110.118906 -363.375702)
		(size 0.508)
		(drill 0.254)
		(layers "F.Cu" "B.Cu")
		(net "PVCCFA_EHV_FIVRA_CPU1_PWM4")
	)
	(via
		(at 55.775098 -365.608108)
		(size 0.508)
		(drill 0.254)
		(layers "F.Cu" "B.Cu")
		(net "PVCCFA_EHV_FIVRA_CPU1_PWM4")
	)
	(via
		(at 41.656 -357.850948)
		(size 0.508)
		(drill 0.254)
		(layers "F.Cu" "B.Cu")
		(net "PVCCFA_EHV_FIVRA_CPU1_PWM4")
	)
	(via
		(at 59.222132 -366.261904)
		(size 0.6604)
		(drill 0.3302)
		(layers "F.Cu" "B.Cu")
		(net "PVCCFA_EHV_FIVRA_CPU1_PWM4")
	)
	(segment
		(start 102.823264 -365.705644)
		(end 102.823264 -366.324896)
		(width 0.254)
		(layer "B.Cu")
		(net "PVCCFA_EHV_FIVRA_CPU1_PWM4")
	)
	(segment
		(start 59.222132 -366.261904)
		(end 58.568336 -365.608108)
		(width 0.254)
		(layer "B.Cu")
		(net "PVCCFA_EHV_FIVRA_CPU1_PWM4")
	)
	(segment
		(start 107.677458 -362.959142)
		(end 106.869738 -363.766862)
		(width 0.254)
		(layer "B.Cu")
		(net "PVCCFA_EHV_FIVRA_CPU1_PWM4")
	)
	(segment
		(start 106.102658 -363.766862)
		(end 105.47477 -364.39475)
		(width 0.254)
		(layer "B.Cu")
		(net "PVCCFA_EHV_FIVRA_CPU1_PWM4")
	)
	(segment
		(start 106.869738 -363.766862)
		(end 106.102658 -363.766862)
		(width 0.254)
		(layer "B.Cu")
		(net "PVCCFA_EHV_FIVRA_CPU1_PWM4")
	)
	(segment
		(start 104.134158 -364.39475)
		(end 102.823264 -365.705644)
		(width 0.254)
		(layer "B.Cu")
		(net "PVCCFA_EHV_FIVRA_CPU1_PWM4")
	)
	(segment
		(start 58.568336 -365.608108)
		(end 55.775098 -365.608108)
		(width 0.254)
		(layer "B.Cu")
		(net "PVCCFA_EHV_FIVRA_CPU1_PWM4")
	)
	(segment
		(start 109.702346 -362.959142)
		(end 107.677458 -362.959142)
		(width 0.254)
		(layer "B.Cu")
		(net "PVCCFA_EHV_FIVRA_CPU1_PWM4")
	)
	(segment
		(start 102.823264 -366.324896)
		(end 101.58603 -367.56213)
		(width 0.254)
		(layer "B.Cu")
		(net "PVCCFA_EHV_FIVRA_CPU1_PWM4")
	)
	(segment
		(start 105.47477 -364.39475)
		(end 104.134158 -364.39475)
		(width 0.254)
		(layer "B.Cu")
		(net "PVCCFA_EHV_FIVRA_CPU1_PWM4")
	)
	(segment
		(start 101.58603 -367.56213)
		(end 60.522358 -367.56213)
		(width 0.254)
		(layer "B.Cu")
		(net "PVCCFA_EHV_FIVRA_CPU1_PWM4")
	)
	(segment
		(start 60.522358 -367.56213)
		(end 59.222132 -366.261904)
		(width 0.254)
		(layer "B.Cu")
		(net "PVCCFA_EHV_FIVRA_CPU1_PWM4")
	)
	(segment
		(start 110.118906 -363.375702)
		(end 109.702346 -362.959142)
		(width 0.254)
		(layer "B.Cu")
		(net "PVCCFA_EHV_FIVRA_CPU1_PWM4")
	)
	(segment
		(start 55.273194 -365.608108)
		(end 55.775098 -365.608108)
		(width 0.254)
		(layer "In2.Cu")
		(net "PVCCFA_EHV_FIVRA_CPU1_PWM4")
	)
	(segment
		(start 42.148506 -358.343454)
		(end 47.082202 -358.343454)
		(width 0.254)
		(layer "In2.Cu")
		(net "PVCCFA_EHV_FIVRA_CPU1_PWM4")
	)
	(segment
		(start 54.251098 -364.586012)
		(end 55.273194 -365.608108)
		(width 0.254)
		(layer "In2.Cu")
		(net "PVCCFA_EHV_FIVRA_CPU1_PWM4")
	)
	(segment
		(start 48.975518 -360.23677)
		(end 52.937664 -360.23677)
		(width 0.254)
		(layer "In2.Cu")
		(net "PVCCFA_EHV_FIVRA_CPU1_PWM4")
	)
	(segment
		(start 52.937664 -360.23677)
		(end 54.251098 -361.550204)
		(width 0.254)
		(layer "In2.Cu")
		(net "PVCCFA_EHV_FIVRA_CPU1_PWM4")
	)
	(segment
		(start 54.251098 -361.550204)
		(end 54.251098 -364.586012)
		(width 0.254)
		(layer "In2.Cu")
		(net "PVCCFA_EHV_FIVRA_CPU1_PWM4")
	)
	(segment
		(start 41.656 -357.850948)
		(end 42.148506 -358.343454)
		(width 0.254)
		(layer "In2.Cu")
		(net "PVCCFA_EHV_FIVRA_CPU1_PWM4")
	)
	(segment
		(start 47.082202 -358.343454)
		(end 48.975518 -360.23677)
		(width 0.254)
		(layer "In2.Cu")
		(net "PVCCFA_EHV_FIVRA_CPU1_PWM4")
	)
	(segment
		(start 181.803548 -357.857298)
		(end 181.972712 -357.448866)
		(width 0.1524)
		(layer "F.Cu")
		(net "PVCCFA_EHV_FIVRA_CPU1_PWM3")
	)
	(segment
		(start 181.972712 -357.448866)
		(end 181.972712 -356.454202)
		(width 0.1524)
		(layer "F.Cu")
		(net "PVCCFA_EHV_FIVRA_CPU1_PWM3")
	)
	(segment
		(start 109.978444 -362.534708)
		(end 109.978444 -361.723432)
		(width 0.1778)
		(layer "F.Cu")
		(net "PVCCFA_EHV_FIVRA_CPU1_PWM3")
	)
	(segment
		(start 111.073946 -363.63021)
		(end 109.978444 -362.534708)
		(width 0.1778)
		(layer "F.Cu")
		(net "PVCCFA_EHV_FIVRA_CPU1_PWM3")
	)
	(segment
		(start 111.073946 -364.940596)
		(end 111.073946 -363.63021)
		(width 0.1778)
		(layer "F.Cu")
		(net "PVCCFA_EHV_FIVRA_CPU1_PWM3")
	)
	(via
		(at 181.803548 -357.857298)
		(size 0.508)
		(drill 0.254)
		(layers "F.Cu" "B.Cu")
		(net "PVCCFA_EHV_FIVRA_CPU1_PWM3")
	)
	(via
		(at 111.073946 -364.940596)
		(size 0.508)
		(drill 0.254)
		(layers "F.Cu" "B.Cu")
		(net "PVCCFA_EHV_FIVRA_CPU1_PWM3")
	)
	(segment
		(start 130.423412 -364.524544)
		(end 134.56031 -360.387646)
		(width 0.254)
		(layer "In6.Cu")
		(net "PVCCFA_EHV_FIVRA_CPU1_PWM3")
	)
	(segment
		(start 121.42089 -364.524544)
		(end 130.423412 -364.524544)
		(width 0.254)
		(layer "In6.Cu")
		(net "PVCCFA_EHV_FIVRA_CPU1_PWM3")
	)
	(segment
		(start 111.073946 -364.940596)
		(end 113.05413 -366.92078)
		(width 0.254)
		(layer "In6.Cu")
		(net "PVCCFA_EHV_FIVRA_CPU1_PWM3")
	)
	(segment
		(start 162.300666 -365.88065)
		(end 179.844954 -365.88065)
		(width 0.254)
		(layer "In6.Cu")
		(net "PVCCFA_EHV_FIVRA_CPU1_PWM3")
	)
	(segment
		(start 184.688988 -359.140506)
		(end 183.40578 -357.857298)
		(width 0.254)
		(layer "In6.Cu")
		(net "PVCCFA_EHV_FIVRA_CPU1_PWM3")
	)
	(segment
		(start 119.024654 -366.92078)
		(end 121.42089 -364.524544)
		(width 0.254)
		(layer "In6.Cu")
		(net "PVCCFA_EHV_FIVRA_CPU1_PWM3")
	)
	(segment
		(start 179.844954 -365.88065)
		(end 183.539638 -364.3503)
		(width 0.254)
		(layer "In6.Cu")
		(net "PVCCFA_EHV_FIVRA_CPU1_PWM3")
	)
	(segment
		(start 183.40578 -357.857298)
		(end 181.803548 -357.857298)
		(width 0.254)
		(layer "In6.Cu")
		(net "PVCCFA_EHV_FIVRA_CPU1_PWM3")
	)
	(segment
		(start 156.807662 -360.387646)
		(end 162.300666 -365.88065)
		(width 0.254)
		(layer "In6.Cu")
		(net "PVCCFA_EHV_FIVRA_CPU1_PWM3")
	)
	(segment
		(start 184.688988 -363.20095)
		(end 184.688988 -359.140506)
		(width 0.254)
		(layer "In6.Cu")
		(net "PVCCFA_EHV_FIVRA_CPU1_PWM3")
	)
	(segment
		(start 183.539638 -364.3503)
		(end 184.688988 -363.20095)
		(width 0.254)
		(layer "In6.Cu")
		(net "PVCCFA_EHV_FIVRA_CPU1_PWM3")
	)
	(segment
		(start 134.56031 -360.387646)
		(end 156.807662 -360.387646)
		(width 0.254)
		(layer "In6.Cu")
		(net "PVCCFA_EHV_FIVRA_CPU1_PWM3")
	)
	(segment
		(start 113.05413 -366.92078)
		(end 119.024654 -366.92078)
		(width 0.254)
		(layer "In6.Cu")
		(net "PVCCFA_EHV_FIVRA_CPU1_PWM3")
	)
	(segment
		(start 111.5187 -363.948472)
		(end 111.5187 -363.412278)
		(width 0.1778)
		(layer "F.Cu")
		(net "PVCCFA_EHV_FIVRA_CPU1_PWM2")
	)
	(segment
		(start 51.002438 -358.03967)
		(end 51.256692 -357.785162)
		(width 0.1524)
		(layer "F.Cu")
		(net "PVCCFA_EHV_FIVRA_CPU1_PWM2")
	)
	(segment
		(start 51.513486 -357.165402)
		(end 51.513486 -356.447852)
		(width 0.1524)
		(layer "F.Cu")
		(net "PVCCFA_EHV_FIVRA_CPU1_PWM2")
	)
	(segment
		(start 51.256692 -357.785162)
		(end 51.513486 -357.165402)
		(width 0.1524)
		(layer "F.Cu")
		(net "PVCCFA_EHV_FIVRA_CPU1_PWM2")
	)
	(segment
		(start 111.801656 -364.231428)
		(end 111.5187 -363.948472)
		(width 0.1778)
		(layer "F.Cu")
		(net "PVCCFA_EHV_FIVRA_CPU1_PWM2")
	)
	(segment
		(start 110.378494 -362.272072)
		(end 110.378494 -361.723432)
		(width 0.1778)
		(layer "F.Cu")
		(net "PVCCFA_EHV_FIVRA_CPU1_PWM2")
	)
	(segment
		(start 111.5187 -363.412278)
		(end 110.378494 -362.272072)
		(width 0.1778)
		(layer "F.Cu")
		(net "PVCCFA_EHV_FIVRA_CPU1_PWM2")
	)
	(via
		(at 57.09412 -366.624108)
		(size 0.6604)
		(drill 0.3302)
		(layers "F.Cu" "B.Cu")
		(net "PVCCFA_EHV_FIVRA_CPU1_PWM2")
	)
	(via
		(at 51.002438 -358.03967)
		(size 0.508)
		(drill 0.254)
		(layers "F.Cu" "B.Cu")
		(net "PVCCFA_EHV_FIVRA_CPU1_PWM2")
	)
	(via
		(at 55.775098 -366.624108)
		(size 0.508)
		(drill 0.254)
		(layers "F.Cu" "B.Cu")
		(net "PVCCFA_EHV_FIVRA_CPU1_PWM2")
	)
	(via
		(at 111.801656 -364.231428)
		(size 0.508)
		(drill 0.254)
		(layers "F.Cu" "B.Cu")
		(net "PVCCFA_EHV_FIVRA_CPU1_PWM2")
	)
	(segment
		(start 111.801656 -364.231428)
		(end 111.801656 -365.807752)
		(width 0.254)
		(layer "B.Cu")
		(net "PVCCFA_EHV_FIVRA_CPU1_PWM2")
	)
	(segment
		(start 111.106458 -366.50295)
		(end 109.892338 -366.50295)
		(width 0.254)
		(layer "B.Cu")
		(net "PVCCFA_EHV_FIVRA_CPU1_PWM2")
	)
	(segment
		(start 59.924442 -368.34953)
		(end 58.19902 -366.624108)
		(width 0.254)
		(layer "B.Cu")
		(net "PVCCFA_EHV_FIVRA_CPU1_PWM2")
	)
	(segment
		(start 109.102398 -365.71301)
		(end 106.780838 -365.71301)
		(width 0.254)
		(layer "B.Cu")
		(net "PVCCFA_EHV_FIVRA_CPU1_PWM2")
	)
	(segment
		(start 104.61498 -365.267748)
		(end 103.633778 -366.24895)
		(width 0.254)
		(layer "B.Cu")
		(net "PVCCFA_EHV_FIVRA_CPU1_PWM2")
	)
	(segment
		(start 58.19902 -366.624108)
		(end 57.09412 -366.624108)
		(width 0.254)
		(layer "B.Cu")
		(net "PVCCFA_EHV_FIVRA_CPU1_PWM2")
	)
	(segment
		(start 57.09412 -366.624108)
		(end 55.775098 -366.624108)
		(width 0.254)
		(layer "B.Cu")
		(net "PVCCFA_EHV_FIVRA_CPU1_PWM2")
	)
	(segment
		(start 106.780838 -365.71301)
		(end 106.558334 -365.490506)
		(width 0.254)
		(layer "B.Cu")
		(net "PVCCFA_EHV_FIVRA_CPU1_PWM2")
	)
	(segment
		(start 103.633778 -366.24895)
		(end 103.633778 -366.96777)
		(width 0.254)
		(layer "B.Cu")
		(net "PVCCFA_EHV_FIVRA_CPU1_PWM2")
	)
	(segment
		(start 111.801656 -365.807752)
		(end 111.106458 -366.50295)
		(width 0.254)
		(layer "B.Cu")
		(net "PVCCFA_EHV_FIVRA_CPU1_PWM2")
	)
	(segment
		(start 106.020616 -365.267748)
		(end 104.61498 -365.267748)
		(width 0.254)
		(layer "B.Cu")
		(net "PVCCFA_EHV_FIVRA_CPU1_PWM2")
	)
	(segment
		(start 102.252018 -368.34953)
		(end 59.924442 -368.34953)
		(width 0.254)
		(layer "B.Cu")
		(net "PVCCFA_EHV_FIVRA_CPU1_PWM2")
	)
	(segment
		(start 106.558334 -365.490506)
		(end 106.020616 -365.267748)
		(width 0.254)
		(layer "B.Cu")
		(net "PVCCFA_EHV_FIVRA_CPU1_PWM2")
	)
	(segment
		(start 103.633778 -366.96777)
		(end 102.252018 -368.34953)
		(width 0.254)
		(layer "B.Cu")
		(net "PVCCFA_EHV_FIVRA_CPU1_PWM2")
	)
	(segment
		(start 109.892338 -366.50295)
		(end 109.102398 -365.71301)
		(width 0.254)
		(layer "B.Cu")
		(net "PVCCFA_EHV_FIVRA_CPU1_PWM2")
	)
	(segment
		(start 55.775098 -366.624108)
		(end 56.016398 -366.624108)
		(width 0.254)
		(layer "In2.Cu")
		(net "PVCCFA_EHV_FIVRA_CPU1_PWM2")
	)
	(segment
		(start 56.664098 -365.7854)
		(end 56.664098 -364.223808)
		(width 0.254)
		(layer "In2.Cu")
		(net "PVCCFA_EHV_FIVRA_CPU1_PWM2")
	)
	(segment
		(start 56.529224 -366.111282)
		(end 56.664098 -365.7854)
		(width 0.254)
		(layer "In2.Cu")
		(net "PVCCFA_EHV_FIVRA_CPU1_PWM2")
	)
	(segment
		(start 56.664098 -364.223808)
		(end 55.775098 -363.334808)
		(width 0.254)
		(layer "In2.Cu")
		(net "PVCCFA_EHV_FIVRA_CPU1_PWM2")
	)
	(segment
		(start 56.016398 -366.624108)
		(end 56.529224 -366.111282)
		(width 0.254)
		(layer "In2.Cu")
		(net "PVCCFA_EHV_FIVRA_CPU1_PWM2")
	)
	(segment
		(start 52.896262 -358.03967)
		(end 51.002438 -358.03967)
		(width 0.254)
		(layer "In2.Cu")
		(net "PVCCFA_EHV_FIVRA_CPU1_PWM2")
	)
	(segment
		(start 55.775098 -363.334808)
		(end 55.775098 -360.918506)
		(width 0.254)
		(layer "In2.Cu")
		(net "PVCCFA_EHV_FIVRA_CPU1_PWM2")
	)
	(segment
		(start 55.775098 -360.918506)
		(end 52.896262 -358.03967)
		(width 0.254)
		(layer "In2.Cu")
		(net "PVCCFA_EHV_FIVRA_CPU1_PWM2")
	)
	(segment
		(start 172.115226 -357.857298)
		(end 172.28439 -357.448866)
		(width 0.1524)
		(layer "F.Cu")
		(net "PVCCFA_EHV_FIVRA_CPU1_PWM1")
	)
	(segment
		(start 111.119412 -362.43006)
		(end 110.77829 -362.088938)
		(width 0.1778)
		(layer "F.Cu")
		(net "PVCCFA_EHV_FIVRA_CPU1_PWM1")
	)
	(segment
		(start 110.77829 -362.088938)
		(end 110.77829 -361.723432)
		(width 0.1778)
		(layer "F.Cu")
		(net "PVCCFA_EHV_FIVRA_CPU1_PWM1")
	)
	(segment
		(start 111.41583 -362.43006)
		(end 111.119412 -362.43006)
		(width 0.1778)
		(layer "F.Cu")
		(net "PVCCFA_EHV_FIVRA_CPU1_PWM1")
	)
	(segment
		(start 172.28439 -357.448866)
		(end 172.28439 -356.454202)
		(width 0.1524)
		(layer "F.Cu")
		(net "PVCCFA_EHV_FIVRA_CPU1_PWM1")
	)
	(via
		(at 111.41583 -362.43006)
		(size 0.508)
		(drill 0.254)
		(layers "F.Cu" "B.Cu")
		(net "PVCCFA_EHV_FIVRA_CPU1_PWM1")
	)
	(via
		(at 172.115226 -357.857298)
		(size 0.508)
		(drill 0.254)
		(layers "F.Cu" "B.Cu")
		(net "PVCCFA_EHV_FIVRA_CPU1_PWM1")
	)
	(segment
		(start 172.427646 -357.857298)
		(end 172.115226 -357.857298)
		(width 0.254)
		(layer "In6.Cu")
		(net "PVCCFA_EHV_FIVRA_CPU1_PWM1")
	)
	(segment
		(start 172.750734 -359.603802)
		(end 172.750734 -358.180386)
		(width 0.254)
		(layer "In6.Cu")
		(net "PVCCFA_EHV_FIVRA_CPU1_PWM1")
	)
	(segment
		(start 134.194804 -359.50525)
		(end 157.52445 -359.50525)
		(width 0.254)
		(layer "In6.Cu")
		(net "PVCCFA_EHV_FIVRA_CPU1_PWM1")
	)
	(segment
		(start 117.988588 -364.94974)
		(end 119.29618 -363.642148)
		(width 0.254)
		(layer "In6.Cu")
		(net "PVCCFA_EHV_FIVRA_CPU1_PWM1")
	)
	(segment
		(start 112.718088 -364.000542)
		(end 113.195862 -364.000542)
		(width 0.254)
		(layer "In6.Cu")
		(net "PVCCFA_EHV_FIVRA_CPU1_PWM1")
	)
	(segment
		(start 171.50969 -360.844846)
		(end 172.750734 -359.603802)
		(width 0.254)
		(layer "In6.Cu")
		(net "PVCCFA_EHV_FIVRA_CPU1_PWM1")
	)
	(segment
		(start 157.52445 -359.50525)
		(end 158.864046 -360.844846)
		(width 0.254)
		(layer "In6.Cu")
		(net "PVCCFA_EHV_FIVRA_CPU1_PWM1")
	)
	(segment
		(start 119.29618 -363.642148)
		(end 130.057906 -363.642148)
		(width 0.254)
		(layer "In6.Cu")
		(net "PVCCFA_EHV_FIVRA_CPU1_PWM1")
	)
	(segment
		(start 114.14506 -364.94974)
		(end 117.988588 -364.94974)
		(width 0.254)
		(layer "In6.Cu")
		(net "PVCCFA_EHV_FIVRA_CPU1_PWM1")
	)
	(segment
		(start 111.41583 -362.43006)
		(end 111.41583 -362.698284)
		(width 0.254)
		(layer "In6.Cu")
		(net "PVCCFA_EHV_FIVRA_CPU1_PWM1")
	)
	(segment
		(start 130.057906 -363.642148)
		(end 134.194804 -359.50525)
		(width 0.254)
		(layer "In6.Cu")
		(net "PVCCFA_EHV_FIVRA_CPU1_PWM1")
	)
	(segment
		(start 111.41583 -362.698284)
		(end 112.718088 -364.000542)
		(width 0.254)
		(layer "In6.Cu")
		(net "PVCCFA_EHV_FIVRA_CPU1_PWM1")
	)
	(segment
		(start 113.195862 -364.000542)
		(end 114.14506 -364.94974)
		(width 0.254)
		(layer "In6.Cu")
		(net "PVCCFA_EHV_FIVRA_CPU1_PWM1")
	)
	(segment
		(start 158.864046 -360.844846)
		(end 171.50969 -360.844846)
		(width 0.254)
		(layer "In6.Cu")
		(net "PVCCFA_EHV_FIVRA_CPU1_PWM1")
	)
	(segment
		(start 172.750734 -358.180386)
		(end 172.427646 -357.857298)
		(width 0.254)
		(layer "In6.Cu")
		(net "PVCCFA_EHV_FIVRA_CPU1_PWM1")
	)
	(segment
		(start 47.678594 -354.37318)
		(end 47.678594 -353.75723)
		(width 0.2032)
		(layer "F.Cu")
		(net "PVCCFA_EHV_FIVRA_CPU1_PVCC2")
	)
	(segment
		(start 38.078156 -353.75723)
		(end 37.990272 -353.75723)
		(width 0.2032)
		(layer "F.Cu")
		(net "PVCCFA_EHV_FIVRA_CPU1_PVCC2")
	)
	(segment
		(start 37.990272 -354.36683)
		(end 37.664644 -354.36683)
		(width 0.2032)
		(layer "F.Cu")
		(net "PVCCFA_EHV_FIVRA_CPU1_PVCC2")
	)
	(segment
		(start 37.005768 -353.75723)
		(end 37.990272 -353.75723)
		(width 0.2032)
		(layer "F.Cu")
		(net "PVCCFA_EHV_FIVRA_CPU1_PVCC2")
	)
	(segment
		(start 37.664644 -354.36683)
		(end 37.377624 -354.65385)
		(width 0.2032)
		(layer "F.Cu")
		(net "PVCCFA_EHV_FIVRA_CPU1_PVCC2")
	)
	(segment
		(start 37.005768 -353.75723)
		(end 37.005768 -354.65385)
		(width 0.2032)
		(layer "F.Cu")
		(net "PVCCFA_EHV_FIVRA_CPU1_PVCC2")
	)
	(segment
		(start 48.853344 -354.473002)
		(end 48.48225 -354.473002)
		(width 0.2032)
		(layer "F.Cu")
		(net "PVCCFA_EHV_FIVRA_CPU1_PVCC2")
	)
	(segment
		(start 48.48225 -354.473002)
		(end 47.766478 -353.75723)
		(width 0.2032)
		(layer "F.Cu")
		(net "PVCCFA_EHV_FIVRA_CPU1_PVCC2")
	)
	(segment
		(start 39.165022 -354.473002)
		(end 38.793928 -354.473002)
		(width 0.2032)
		(layer "F.Cu")
		(net "PVCCFA_EHV_FIVRA_CPU1_PVCC2")
	)
	(segment
		(start 47.766478 -353.75723)
		(end 47.678594 -353.75723)
		(width 0.2032)
		(layer "F.Cu")
		(net "PVCCFA_EHV_FIVRA_CPU1_PVCC2")
	)
	(segment
		(start 38.793928 -354.473002)
		(end 38.078156 -353.75723)
		(width 0.2032)
		(layer "F.Cu")
		(net "PVCCFA_EHV_FIVRA_CPU1_PVCC2")
	)
	(segment
		(start 37.377624 -354.65385)
		(end 37.005768 -354.65385)
		(width 0.2032)
		(layer "F.Cu")
		(net "PVCCFA_EHV_FIVRA_CPU1_PVCC2")
	)
	(via
		(at 47.678594 -354.37318)
		(size 0.508)
		(drill 0.254)
		(layers "F.Cu" "B.Cu")
		(net "PVCCFA_EHV_FIVRA_CPU1_PVCC2")
	)
	(via
		(at 37.990272 -354.36683)
		(size 0.508)
		(drill 0.254)
		(layers "F.Cu" "B.Cu")
		(net "PVCCFA_EHV_FIVRA_CPU1_PVCC2")
	)
	(segment
		(start 38.191948 -354.165154)
		(end 39.062406 -354.165154)
		(width 0.254)
		(layer "B.Cu")
		(net "PVCCFA_EHV_FIVRA_CPU1_PVCC2")
	)
	(segment
		(start 37.990272 -354.36683)
		(end 38.191948 -354.165154)
		(width 0.254)
		(layer "B.Cu")
		(net "PVCCFA_EHV_FIVRA_CPU1_PVCC2")
	)
	(segment
		(start 47.678594 -354.37318)
		(end 47.89297 -354.158804)
		(width 0.254)
		(layer "B.Cu")
		(net "PVCCFA_EHV_FIVRA_CPU1_PVCC2")
	)
	(segment
		(start 47.89297 -354.158804)
		(end 48.344328 -354.158804)
		(width 0.254)
		(layer "B.Cu")
		(net "PVCCFA_EHV_FIVRA_CPU1_PVCC2")
	)
	(segment
		(start 45.080174 -353.56419)
		(end 46.869604 -353.56419)
		(width 0.381)
		(layer "In4.Cu")
		(net "PVCCFA_EHV_FIVRA_CPU1_PVCC2")
	)
	(segment
		(start 38.832282 -354.36683)
		(end 39.266368 -354.800916)
		(width 0.381)
		(layer "In4.Cu")
		(net "PVCCFA_EHV_FIVRA_CPU1_PVCC2")
	)
	(segment
		(start 44.409106 -354.235258)
		(end 45.080174 -353.56419)
		(width 0.381)
		(layer "In4.Cu")
		(net "PVCCFA_EHV_FIVRA_CPU1_PVCC2")
	)
	(segment
		(start 41.461182 -354.800916)
		(end 42.02684 -354.235258)
		(width 0.381)
		(layer "In4.Cu")
		(net "PVCCFA_EHV_FIVRA_CPU1_PVCC2")
	)
	(segment
		(start 42.02684 -354.235258)
		(end 44.409106 -354.235258)
		(width 0.381)
		(layer "In4.Cu")
		(net "PVCCFA_EHV_FIVRA_CPU1_PVCC2")
	)
	(segment
		(start 37.990272 -354.36683)
		(end 38.832282 -354.36683)
		(width 0.381)
		(layer "In4.Cu")
		(net "PVCCFA_EHV_FIVRA_CPU1_PVCC2")
	)
	(segment
		(start 46.869604 -353.56419)
		(end 47.678594 -354.37318)
		(width 0.381)
		(layer "In4.Cu")
		(net "PVCCFA_EHV_FIVRA_CPU1_PVCC2")
	)
	(segment
		(start 39.266368 -354.800916)
		(end 41.461182 -354.800916)
		(width 0.381)
		(layer "In4.Cu")
		(net "PVCCFA_EHV_FIVRA_CPU1_PVCC2")
	)
	(segment
		(start 168.09085 -354.37318)
		(end 167.80383 -354.6602)
		(width 0.254)
		(layer "F.Cu")
		(net "PVCCFA_EHV_FIVRA_CPU1_PVCC1")
	)
	(segment
		(start 167.80383 -354.6602)
		(end 167.464994 -354.6602)
		(width 0.254)
		(layer "F.Cu")
		(net "PVCCFA_EHV_FIVRA_CPU1_PVCC1")
	)
	(segment
		(start 178.225704 -353.76358)
		(end 178.13782 -353.76358)
		(width 0.2032)
		(layer "F.Cu")
		(net "PVCCFA_EHV_FIVRA_CPU1_PVCC1")
	)
	(segment
		(start 178.13782 -354.37953)
		(end 178.13782 -353.76358)
		(width 0.2032)
		(layer "F.Cu")
		(net "PVCCFA_EHV_FIVRA_CPU1_PVCC1")
	)
	(segment
		(start 167.464994 -354.6602)
		(end 167.464994 -353.76358)
		(width 0.254)
		(layer "F.Cu")
		(net "PVCCFA_EHV_FIVRA_CPU1_PVCC1")
	)
	(segment
		(start 178.941476 -354.479352)
		(end 178.225704 -353.76358)
		(width 0.2032)
		(layer "F.Cu")
		(net "PVCCFA_EHV_FIVRA_CPU1_PVCC1")
	)
	(segment
		(start 169.253154 -354.479352)
		(end 168.537382 -353.76358)
		(width 0.2032)
		(layer "F.Cu")
		(net "PVCCFA_EHV_FIVRA_CPU1_PVCC1")
	)
	(segment
		(start 169.624248 -354.479352)
		(end 169.253154 -354.479352)
		(width 0.2032)
		(layer "F.Cu")
		(net "PVCCFA_EHV_FIVRA_CPU1_PVCC1")
	)
	(segment
		(start 167.464994 -353.76358)
		(end 168.449498 -353.76358)
		(width 0.254)
		(layer "F.Cu")
		(net "PVCCFA_EHV_FIVRA_CPU1_PVCC1")
	)
	(segment
		(start 168.449498 -354.37318)
		(end 168.09085 -354.37318)
		(width 0.254)
		(layer "F.Cu")
		(net "PVCCFA_EHV_FIVRA_CPU1_PVCC1")
	)
	(segment
		(start 168.537382 -353.76358)
		(end 168.449498 -353.76358)
		(width 0.2032)
		(layer "F.Cu")
		(net "PVCCFA_EHV_FIVRA_CPU1_PVCC1")
	)
	(segment
		(start 179.31257 -354.479352)
		(end 178.941476 -354.479352)
		(width 0.2032)
		(layer "F.Cu")
		(net "PVCCFA_EHV_FIVRA_CPU1_PVCC1")
	)
	(via
		(at 178.13782 -354.37953)
		(size 0.508)
		(drill 0.254)
		(layers "F.Cu" "B.Cu")
		(net "PVCCFA_EHV_FIVRA_CPU1_PVCC1")
	)
	(via
		(at 168.449498 -354.37318)
		(size 0.508)
		(drill 0.254)
		(layers "F.Cu" "B.Cu")
		(net "PVCCFA_EHV_FIVRA_CPU1_PVCC1")
	)
	(segment
		(start 178.352196 -354.165154)
		(end 178.803554 -354.165154)
		(width 0.254)
		(layer "B.Cu")
		(net "PVCCFA_EHV_FIVRA_CPU1_PVCC1")
	)
	(segment
		(start 168.651174 -354.171504)
		(end 169.521632 -354.171504)
		(width 0.254)
		(layer "B.Cu")
		(net "PVCCFA_EHV_FIVRA_CPU1_PVCC1")
	)
	(segment
		(start 178.13782 -354.37953)
		(end 178.352196 -354.165154)
		(width 0.254)
		(layer "B.Cu")
		(net "PVCCFA_EHV_FIVRA_CPU1_PVCC1")
	)
	(segment
		(start 168.449498 -354.37318)
		(end 168.651174 -354.171504)
		(width 0.254)
		(layer "B.Cu")
		(net "PVCCFA_EHV_FIVRA_CPU1_PVCC1")
	)
	(segment
		(start 169.725594 -354.807266)
		(end 171.874942 -354.807266)
		(width 0.381)
		(layer "In4.Cu")
		(net "PVCCFA_EHV_FIVRA_CPU1_PVCC1")
	)
	(segment
		(start 169.291508 -354.37318)
		(end 169.725594 -354.807266)
		(width 0.381)
		(layer "In4.Cu")
		(net "PVCCFA_EHV_FIVRA_CPU1_PVCC1")
	)
	(segment
		(start 174.98314 -353.63531)
		(end 177.3936 -353.63531)
		(width 0.381)
		(layer "In4.Cu")
		(net "PVCCFA_EHV_FIVRA_CPU1_PVCC1")
	)
	(segment
		(start 177.3936 -353.63531)
		(end 178.13782 -354.37953)
		(width 0.381)
		(layer "In4.Cu")
		(net "PVCCFA_EHV_FIVRA_CPU1_PVCC1")
	)
	(segment
		(start 171.874942 -354.807266)
		(end 172.541438 -354.14077)
		(width 0.381)
		(layer "In4.Cu")
		(net "PVCCFA_EHV_FIVRA_CPU1_PVCC1")
	)
	(segment
		(start 174.47768 -354.14077)
		(end 174.98314 -353.63531)
		(width 0.381)
		(layer "In4.Cu")
		(net "PVCCFA_EHV_FIVRA_CPU1_PVCC1")
	)
	(segment
		(start 172.541438 -354.14077)
		(end 174.47768 -354.14077)
		(width 0.381)
		(layer "In4.Cu")
		(net "PVCCFA_EHV_FIVRA_CPU1_PVCC1")
	)
	(segment
		(start 168.449498 -354.37318)
		(end 169.291508 -354.37318)
		(width 0.381)
		(layer "In4.Cu")
		(net "PVCCFA_EHV_FIVRA_CPU1_PVCC1")
	)
	(segment
		(start 37.92982 -359.67162)
		(end 39.48938 -359.67162)
		(width 0.12954)
		(layer "F.Cu")
		(net "PVCCFA_EHV_FIVRA_CPU1_LSET4")
	)
	(segment
		(start 40.102536 -358.463088)
		(end 39.873682 -358.691942)
		(width 0.12954)
		(layer "F.Cu")
		(net "PVCCFA_EHV_FIVRA_CPU1_LSET4")
	)
	(segment
		(start 40.475154 -356.91572)
		(end 40.102536 -357.288338)
		(width 0.12954)
		(layer "F.Cu")
		(net "PVCCFA_EHV_FIVRA_CPU1_LSET4")
	)
	(segment
		(start 40.475154 -356.447852)
		(end 40.475154 -356.91572)
		(width 0.12954)
		(layer "F.Cu")
		(net "PVCCFA_EHV_FIVRA_CPU1_LSET4")
	)
	(segment
		(start 37.5412 -359.283)
		(end 37.92982 -359.67162)
		(width 0.12954)
		(layer "F.Cu")
		(net "PVCCFA_EHV_FIVRA_CPU1_LSET4")
	)
	(segment
		(start 40.102536 -357.288338)
		(end 40.102536 -358.463088)
		(width 0.12954)
		(layer "F.Cu")
		(net "PVCCFA_EHV_FIVRA_CPU1_LSET4")
	)
	(segment
		(start 39.48938 -359.67162)
		(end 39.873682 -359.287318)
		(width 0.12954)
		(layer "F.Cu")
		(net "PVCCFA_EHV_FIVRA_CPU1_LSET4")
	)
	(segment
		(start 39.873682 -359.287318)
		(end 39.873682 -358.691942)
		(width 0.12954)
		(layer "F.Cu")
		(net "PVCCFA_EHV_FIVRA_CPU1_LSET4")
	)
	(via
		(at 37.5412 -359.283)
		(size 0.762)
		(drill 0.381)
		(layers "F.Cu" "B.Cu")
		(net "PVCCFA_EHV_FIVRA_CPU1_LSET4")
	)
	(segment
		(start 180.250084 -358.469438)
		(end 180.250084 -357.26116)
		(width 0.12954)
		(layer "F.Cu")
		(net "PVCCFA_EHV_FIVRA_CPU1_LSET3")
	)
	(segment
		(start 180.622702 -356.888542)
		(end 180.622702 -356.454202)
		(width 0.12954)
		(layer "F.Cu")
		(net "PVCCFA_EHV_FIVRA_CPU1_LSET3")
	)
	(segment
		(start 180.250084 -357.26116)
		(end 180.622702 -356.888542)
		(width 0.12954)
		(layer "F.Cu")
		(net "PVCCFA_EHV_FIVRA_CPU1_LSET3")
	)
	(segment
		(start 180.02123 -358.698292)
		(end 180.250084 -358.469438)
		(width 0.12954)
		(layer "F.Cu")
		(net "PVCCFA_EHV_FIVRA_CPU1_LSET3")
	)
	(segment
		(start 49.83734 -357.246428)
		(end 50.163476 -356.920292)
		(width 0.12954)
		(layer "F.Cu")
		(net "PVCCFA_EHV_FIVRA_CPU1_LSET2")
	)
	(segment
		(start 49.562004 -358.691942)
		(end 49.83734 -358.416606)
		(width 0.12954)
		(layer "F.Cu")
		(net "PVCCFA_EHV_FIVRA_CPU1_LSET2")
	)
	(segment
		(start 50.163476 -356.920292)
		(end 50.163476 -356.447852)
		(width 0.12954)
		(layer "F.Cu")
		(net "PVCCFA_EHV_FIVRA_CPU1_LSET2")
	)
	(segment
		(start 49.83734 -358.416606)
		(end 49.83734 -357.246428)
		(width 0.12954)
		(layer "F.Cu")
		(net "PVCCFA_EHV_FIVRA_CPU1_LSET2")
	)
	(segment
		(start 170.561762 -358.469438)
		(end 170.561762 -357.299768)
		(width 0.12954)
		(layer "F.Cu")
		(net "PVCCFA_EHV_FIVRA_CPU1_LSET1")
	)
	(segment
		(start 170.93438 -356.92715)
		(end 170.93438 -356.454202)
		(width 0.12954)
		(layer "F.Cu")
		(net "PVCCFA_EHV_FIVRA_CPU1_LSET1")
	)
	(segment
		(start 169.418 -359.791)
		(end 170.332908 -358.876092)
		(width 0.12954)
		(layer "F.Cu")
		(net "PVCCFA_EHV_FIVRA_CPU1_LSET1")
	)
	(segment
		(start 168.148 -359.791)
		(end 169.418 -359.791)
		(width 0.12954)
		(layer "F.Cu")
		(net "PVCCFA_EHV_FIVRA_CPU1_LSET1")
	)
	(segment
		(start 170.332908 -358.698292)
		(end 170.561762 -358.469438)
		(width 0.12954)
		(layer "F.Cu")
		(net "PVCCFA_EHV_FIVRA_CPU1_LSET1")
	)
	(segment
		(start 170.561762 -357.299768)
		(end 170.93438 -356.92715)
		(width 0.12954)
		(layer "F.Cu")
		(net "PVCCFA_EHV_FIVRA_CPU1_LSET1")
	)
	(segment
		(start 170.332908 -358.876092)
		(end 170.332908 -358.698292)
		(width 0.12954)
		(layer "F.Cu")
		(net "PVCCFA_EHV_FIVRA_CPU1_LSET1")
	)
	(via
		(at 168.148 -359.791)
		(size 0.762)
		(drill 0.381)
		(layers "F.Cu" "B.Cu")
		(net "PVCCFA_EHV_FIVRA_CPU1_LSET1")
	)
	(segment
		(start 39.587932 -357.293926)
		(end 40.025066 -356.856792)
		(width 0.254)
		(layer "F.Cu")
		(net "PVCCFA_EHV_FIVRA_CPU1_IMON4")
	)
	(segment
		(start 40.025066 -356.856792)
		(end 40.025066 -356.447852)
		(width 0.254)
		(layer "F.Cu")
		(net "PVCCFA_EHV_FIVRA_CPU1_IMON4")
	)
	(segment
		(start 111.570516 -354.14204)
		(end 110.378494 -355.334062)
		(width 0.1778)
		(layer "F.Cu")
		(net "PVCCFA_EHV_FIVRA_CPU1_IMON4")
	)
	(segment
		(start 110.378494 -355.334062)
		(end 110.378494 -355.97338)
		(width 0.1778)
		(layer "F.Cu")
		(net "PVCCFA_EHV_FIVRA_CPU1_IMON4")
	)
	(segment
		(start 112.107726 -354.14204)
		(end 111.570516 -354.14204)
		(width 0.1778)
		(layer "F.Cu")
		(net "PVCCFA_EHV_FIVRA_CPU1_IMON4")
	)
	(via
		(at 39.587932 -357.293926)
		(size 0.508)
		(drill 0.254)
		(layers "F.Cu" "B.Cu")
		(net "PVCCFA_EHV_FIVRA_CPU1_IMON4")
	)
	(via
		(at 105.917746 -366.244632)
		(size 0.762)
		(drill 0.254)
		(layers "F.Cu" "B.Cu")
		(net "PVCCFA_EHV_FIVRA_CPU1_IMON4")
	)
	(via
		(at 112.107726 -354.14204)
		(size 0.508)
		(drill 0.254)
		(layers "F.Cu" "B.Cu")
		(net "PVCCFA_EHV_FIVRA_CPU1_IMON4")
	)
	(via
		(at 44.126658 -368.842036)
		(size 0.508)
		(drill 0.254)
		(layers "F.Cu" "B.Cu")
		(net "PVCCFA_EHV_FIVRA_CPU1_IMON4")
	)
	(segment
		(start 105.917746 -366.244632)
		(end 105.693718 -366.46866)
		(width 0.254)
		(layer "B.Cu")
		(net "PVCCFA_EHV_FIVRA_CPU1_IMON4")
	)
	(segment
		(start 59.41695 -370.419122)
		(end 57.215278 -368.21745)
		(width 0.254)
		(layer "B.Cu")
		(net "PVCCFA_EHV_FIVRA_CPU1_IMON4")
	)
	(segment
		(start 105.693718 -367.947956)
		(end 103.222552 -370.419122)
		(width 0.254)
		(layer "B.Cu")
		(net "PVCCFA_EHV_FIVRA_CPU1_IMON4")
	)
	(segment
		(start 52.053998 -368.608102)
		(end 44.360592 -368.608102)
		(width 0.254)
		(layer "B.Cu")
		(net "PVCCFA_EHV_FIVRA_CPU1_IMON4")
	)
	(segment
		(start 105.693718 -366.46866)
		(end 105.693718 -367.947956)
		(width 0.254)
		(layer "B.Cu")
		(net "PVCCFA_EHV_FIVRA_CPU1_IMON4")
	)
	(segment
		(start 107.77728 -355.615748)
		(end 107.77728 -356.104698)
		(width 0.254)
		(layer "B.Cu")
		(net "PVCCFA_EHV_FIVRA_CPU1_IMON4")
	)
	(segment
		(start 44.360592 -368.608102)
		(end 44.126658 -368.842036)
		(width 0.254)
		(layer "B.Cu")
		(net "PVCCFA_EHV_FIVRA_CPU1_IMON4")
	)
	(segment
		(start 52.44465 -368.21745)
		(end 52.053998 -368.608102)
		(width 0.254)
		(layer "B.Cu")
		(net "PVCCFA_EHV_FIVRA_CPU1_IMON4")
	)
	(segment
		(start 111.705898 -354.543868)
		(end 108.84916 -354.543868)
		(width 0.254)
		(layer "B.Cu")
		(net "PVCCFA_EHV_FIVRA_CPU1_IMON4")
	)
	(segment
		(start 103.222552 -370.419122)
		(end 59.41695 -370.419122)
		(width 0.254)
		(layer "B.Cu")
		(net "PVCCFA_EHV_FIVRA_CPU1_IMON4")
	)
	(segment
		(start 112.107726 -354.14204)
		(end 111.705898 -354.543868)
		(width 0.254)
		(layer "B.Cu")
		(net "PVCCFA_EHV_FIVRA_CPU1_IMON4")
	)
	(segment
		(start 108.84916 -354.543868)
		(end 107.77728 -355.615748)
		(width 0.254)
		(layer "B.Cu")
		(net "PVCCFA_EHV_FIVRA_CPU1_IMON4")
	)
	(segment
		(start 57.215278 -368.21745)
		(end 52.44465 -368.21745)
		(width 0.254)
		(layer "B.Cu")
		(net "PVCCFA_EHV_FIVRA_CPU1_IMON4")
	)
	(segment
		(start 111.980726 -354.26904)
		(end 108.998258 -354.26904)
		(width 0.254)
		(layer "In4.Cu")
		(net "PVCCFA_EHV_FIVRA_CPU1_IMON4")
	)
	(segment
		(start 107.67695 -352.947732)
		(end 102.232714 -352.947732)
		(width 0.254)
		(layer "In4.Cu")
		(net "PVCCFA_EHV_FIVRA_CPU1_IMON4")
	)
	(segment
		(start 108.998258 -354.26904)
		(end 107.67695 -352.947732)
		(width 0.254)
		(layer "In4.Cu")
		(net "PVCCFA_EHV_FIVRA_CPU1_IMON4")
	)
	(segment
		(start 102.961186 -364.593632)
		(end 104.802686 -364.593632)
		(width 0.254)
		(layer "In4.Cu")
		(net "PVCCFA_EHV_FIVRA_CPU1_IMON4")
	)
	(segment
		(start 101.162866 -354.01758)
		(end 101.162866 -362.795312)
		(width 0.254)
		(layer "In4.Cu")
		(net "PVCCFA_EHV_FIVRA_CPU1_IMON4")
	)
	(segment
		(start 105.661206 -365.452152)
		(end 105.661206 -365.988092)
		(width 0.254)
		(layer "In4.Cu")
		(net "PVCCFA_EHV_FIVRA_CPU1_IMON4")
	)
	(segment
		(start 112.107726 -354.14204)
		(end 111.980726 -354.26904)
		(width 0.254)
		(layer "In4.Cu")
		(net "PVCCFA_EHV_FIVRA_CPU1_IMON4")
	)
	(segment
		(start 101.162866 -362.795312)
		(end 102.961186 -364.593632)
		(width 0.254)
		(layer "In4.Cu")
		(net "PVCCFA_EHV_FIVRA_CPU1_IMON4")
	)
	(segment
		(start 102.232714 -352.947732)
		(end 101.162866 -354.01758)
		(width 0.254)
		(layer "In4.Cu")
		(net "PVCCFA_EHV_FIVRA_CPU1_IMON4")
	)
	(segment
		(start 104.802686 -364.593632)
		(end 105.661206 -365.452152)
		(width 0.254)
		(layer "In4.Cu")
		(net "PVCCFA_EHV_FIVRA_CPU1_IMON4")
	)
	(segment
		(start 105.661206 -365.988092)
		(end 105.917746 -366.244632)
		(width 0.254)
		(layer "In4.Cu")
		(net "PVCCFA_EHV_FIVRA_CPU1_IMON4")
	)
	(segment
		(start 39.428928 -357.45293)
		(end 39.587932 -357.293926)
		(width 0.254)
		(layer "In6.Cu")
		(net "PVCCFA_EHV_FIVRA_CPU1_IMON4")
	)
	(segment
		(start 43.903392 -368.61877)
		(end 40.410384 -368.61877)
		(width 0.254)
		(layer "In6.Cu")
		(net "PVCCFA_EHV_FIVRA_CPU1_IMON4")
	)
	(segment
		(start 37.774118 -365.982504)
		(end 37.774118 -358.35209)
		(width 0.254)
		(layer "In6.Cu")
		(net "PVCCFA_EHV_FIVRA_CPU1_IMON4")
	)
	(segment
		(start 38.673278 -357.45293)
		(end 39.428928 -357.45293)
		(width 0.254)
		(layer "In6.Cu")
		(net "PVCCFA_EHV_FIVRA_CPU1_IMON4")
	)
	(segment
		(start 44.126658 -368.842036)
		(end 43.903392 -368.61877)
		(width 0.254)
		(layer "In6.Cu")
		(net "PVCCFA_EHV_FIVRA_CPU1_IMON4")
	)
	(segment
		(start 37.774118 -358.35209)
		(end 38.673278 -357.45293)
		(width 0.254)
		(layer "In6.Cu")
		(net "PVCCFA_EHV_FIVRA_CPU1_IMON4")
	)
	(segment
		(start 40.410384 -368.61877)
		(end 37.774118 -365.982504)
		(width 0.254)
		(layer "In6.Cu")
		(net "PVCCFA_EHV_FIVRA_CPU1_IMON4")
	)
	(segment
		(start 111.605314 -355.159564)
		(end 111.225838 -355.159564)
		(width 0.1778)
		(layer "F.Cu")
		(net "PVCCFA_EHV_FIVRA_CPU1_IMON3")
	)
	(segment
		(start 179.73548 -357.300276)
		(end 180.172614 -356.863142)
		(width 0.2286)
		(layer "F.Cu")
		(net "PVCCFA_EHV_FIVRA_CPU1_IMON3")
	)
	(segment
		(start 111.225838 -355.159564)
		(end 110.77829 -355.607112)
		(width 0.1778)
		(layer "F.Cu")
		(net "PVCCFA_EHV_FIVRA_CPU1_IMON3")
	)
	(segment
		(start 180.172614 -356.863142)
		(end 180.172614 -356.454202)
		(width 0.2286)
		(layer "F.Cu")
		(net "PVCCFA_EHV_FIVRA_CPU1_IMON3")
	)
	(segment
		(start 110.77829 -355.607112)
		(end 110.77829 -355.97338)
		(width 0.1778)
		(layer "F.Cu")
		(net "PVCCFA_EHV_FIVRA_CPU1_IMON3")
	)
	(via
		(at 179.73548 -357.300276)
		(size 0.508)
		(drill 0.254)
		(layers "F.Cu" "B.Cu")
		(net "PVCCFA_EHV_FIVRA_CPU1_IMON3")
	)
	(via
		(at 111.605314 -355.159564)
		(size 0.508)
		(drill 0.254)
		(layers "F.Cu" "B.Cu")
		(net "PVCCFA_EHV_FIVRA_CPU1_IMON3")
	)
	(via
		(at 110.63478 -355.184964)
		(size 0.6604)
		(drill 0.3302)
		(layers "F.Cu" "B.Cu")
		(net "PVCCFA_EHV_FIVRA_CPU1_IMON3")
	)
	(segment
		(start 110.63478 -355.184964)
		(end 109.915198 -355.184964)
		(width 0.254)
		(layer "B.Cu")
		(net "PVCCFA_EHV_FIVRA_CPU1_IMON3")
	)
	(segment
		(start 110.63478 -355.184964)
		(end 111.579914 -355.184964)
		(width 0.254)
		(layer "B.Cu")
		(net "PVCCFA_EHV_FIVRA_CPU1_IMON3")
	)
	(segment
		(start 111.579914 -355.184964)
		(end 111.605314 -355.159564)
		(width 0.254)
		(layer "B.Cu")
		(net "PVCCFA_EHV_FIVRA_CPU1_IMON3")
	)
	(segment
		(start 109.915198 -355.184964)
		(end 109.45114 -355.649022)
		(width 0.254)
		(layer "B.Cu")
		(net "PVCCFA_EHV_FIVRA_CPU1_IMON3")
	)
	(segment
		(start 109.45114 -355.649022)
		(end 109.45114 -356.107238)
		(width 0.254)
		(layer "B.Cu")
		(net "PVCCFA_EHV_FIVRA_CPU1_IMON3")
	)
	(segment
		(start 172.744638 -360.15549)
		(end 173.70552 -359.194608)
		(width 0.254)
		(layer "In11.Cu")
		(net "PVCCFA_EHV_FIVRA_CPU1_IMON3")
	)
	(segment
		(start 175.365156 -358.914192)
		(end 176.115472 -358.163876)
		(width 0.254)
		(layer "In11.Cu")
		(net "PVCCFA_EHV_FIVRA_CPU1_IMON3")
	)
	(segment
		(start 109.008672 -355.244908)
		(end 107.815126 -356.438454)
		(width 0.254)
		(layer "In11.Cu")
		(net "PVCCFA_EHV_FIVRA_CPU1_IMON3")
	)
	(segment
		(start 107.815126 -361.740958)
		(end 109.228128 -363.15396)
		(width 0.254)
		(layer "In11.Cu")
		(net "PVCCFA_EHV_FIVRA_CPU1_IMON3")
	)
	(segment
		(start 175.365156 -358.915208)
		(end 175.365156 -358.914192)
		(width 0.254)
		(layer "In11.Cu")
		(net "PVCCFA_EHV_FIVRA_CPU1_IMON3")
	)
	(segment
		(start 111.51997 -355.244908)
		(end 109.008672 -355.244908)
		(width 0.254)
		(layer "In11.Cu")
		(net "PVCCFA_EHV_FIVRA_CPU1_IMON3")
	)
	(segment
		(start 110.122208 -366.702848)
		(end 118.903496 -366.702848)
		(width 0.254)
		(layer "In11.Cu")
		(net "PVCCFA_EHV_FIVRA_CPU1_IMON3")
	)
	(segment
		(start 178.518312 -358.163876)
		(end 179.381912 -357.300276)
		(width 0.254)
		(layer "In11.Cu")
		(net "PVCCFA_EHV_FIVRA_CPU1_IMON3")
	)
	(segment
		(start 121.464324 -364.14202)
		(end 132.706872 -364.14202)
		(width 0.254)
		(layer "In11.Cu")
		(net "PVCCFA_EHV_FIVRA_CPU1_IMON3")
	)
	(segment
		(start 118.903496 -366.702848)
		(end 121.464324 -364.14202)
		(width 0.254)
		(layer "In11.Cu")
		(net "PVCCFA_EHV_FIVRA_CPU1_IMON3")
	)
	(segment
		(start 111.605314 -355.159564)
		(end 111.51997 -355.244908)
		(width 0.254)
		(layer "In11.Cu")
		(net "PVCCFA_EHV_FIVRA_CPU1_IMON3")
	)
	(segment
		(start 136.693402 -360.15549)
		(end 172.744638 -360.15549)
		(width 0.254)
		(layer "In11.Cu")
		(net "PVCCFA_EHV_FIVRA_CPU1_IMON3")
	)
	(segment
		(start 173.70552 -359.194608)
		(end 175.085756 -359.194608)
		(width 0.254)
		(layer "In11.Cu")
		(net "PVCCFA_EHV_FIVRA_CPU1_IMON3")
	)
	(segment
		(start 132.706872 -364.14202)
		(end 136.693402 -360.15549)
		(width 0.254)
		(layer "In11.Cu")
		(net "PVCCFA_EHV_FIVRA_CPU1_IMON3")
	)
	(segment
		(start 109.228128 -363.15396)
		(end 109.228128 -365.808768)
		(width 0.254)
		(layer "In11.Cu")
		(net "PVCCFA_EHV_FIVRA_CPU1_IMON3")
	)
	(segment
		(start 176.115472 -358.163876)
		(end 178.518312 -358.163876)
		(width 0.254)
		(layer "In11.Cu")
		(net "PVCCFA_EHV_FIVRA_CPU1_IMON3")
	)
	(segment
		(start 107.815126 -356.438454)
		(end 107.815126 -361.740958)
		(width 0.254)
		(layer "In11.Cu")
		(net "PVCCFA_EHV_FIVRA_CPU1_IMON3")
	)
	(segment
		(start 175.085756 -359.194608)
		(end 175.365156 -358.915208)
		(width 0.254)
		(layer "In11.Cu")
		(net "PVCCFA_EHV_FIVRA_CPU1_IMON3")
	)
	(segment
		(start 179.381912 -357.300276)
		(end 179.73548 -357.300276)
		(width 0.254)
		(layer "In11.Cu")
		(net "PVCCFA_EHV_FIVRA_CPU1_IMON3")
	)
	(segment
		(start 109.228128 -365.808768)
		(end 110.122208 -366.702848)
		(width 0.254)
		(layer "In11.Cu")
		(net "PVCCFA_EHV_FIVRA_CPU1_IMON3")
	)
	(segment
		(start 111.453422 -356.236016)
		(end 111.453422 -356.648512)
		(width 0.1778)
		(layer "F.Cu")
		(net "PVCCFA_EHV_FIVRA_CPU1_IMON2")
	)
	(segment
		(start 49.261014 -357.385366)
		(end 49.713388 -356.932992)
		(width 0.2286)
		(layer "F.Cu")
		(net "PVCCFA_EHV_FIVRA_CPU1_IMON2")
	)
	(segment
		(start 49.713388 -356.932992)
		(end 49.713388 -356.447852)
		(width 0.2286)
		(layer "F.Cu")
		(net "PVCCFA_EHV_FIVRA_CPU1_IMON2")
	)
	(segment
		(start 111.368332 -356.150926)
		(end 111.453422 -356.236016)
		(width 0.1778)
		(layer "F.Cu")
		(net "PVCCFA_EHV_FIVRA_CPU1_IMON2")
	)
	(via
		(at 49.261014 -357.385366)
		(size 0.508)
		(drill 0.254)
		(layers "F.Cu" "B.Cu")
		(net "PVCCFA_EHV_FIVRA_CPU1_IMON2")
	)
	(via
		(at 55.237126 -369.50015)
		(size 0.508)
		(drill 0.254)
		(layers "F.Cu" "B.Cu")
		(net "PVCCFA_EHV_FIVRA_CPU1_IMON2")
	)
	(via
		(at 108.596684 -366.626394)
		(size 0.508)
		(drill 0.254)
		(layers "F.Cu" "B.Cu")
		(net "PVCCFA_EHV_FIVRA_CPU1_IMON2")
	)
	(via
		(at 111.368332 -356.150926)
		(size 0.508)
		(drill 0.254)
		(layers "F.Cu" "B.Cu")
		(net "PVCCFA_EHV_FIVRA_CPU1_IMON2")
	)
	(segment
		(start 55.477918 -369.740942)
		(end 55.237126 -369.50015)
		(width 0.254)
		(layer "B.Cu")
		(net "PVCCFA_EHV_FIVRA_CPU1_IMON2")
	)
	(segment
		(start 108.375958 -366.84712)
		(end 108.375958 -368.371882)
		(width 0.254)
		(layer "B.Cu")
		(net "PVCCFA_EHV_FIVRA_CPU1_IMON2")
	)
	(segment
		(start 55.477918 -370.901722)
		(end 55.477918 -369.740942)
		(width 0.254)
		(layer "B.Cu")
		(net "PVCCFA_EHV_FIVRA_CPU1_IMON2")
	)
	(segment
		(start 104.111298 -372.636542)
		(end 57.212738 -372.636542)
		(width 0.254)
		(layer "B.Cu")
		(net "PVCCFA_EHV_FIVRA_CPU1_IMON2")
	)
	(segment
		(start 57.212738 -372.636542)
		(end 55.477918 -370.901722)
		(width 0.254)
		(layer "B.Cu")
		(net "PVCCFA_EHV_FIVRA_CPU1_IMON2")
	)
	(segment
		(start 108.375958 -368.371882)
		(end 104.111298 -372.636542)
		(width 0.254)
		(layer "B.Cu")
		(net "PVCCFA_EHV_FIVRA_CPU1_IMON2")
	)
	(segment
		(start 108.596684 -366.626394)
		(end 108.375958 -366.84712)
		(width 0.254)
		(layer "B.Cu")
		(net "PVCCFA_EHV_FIVRA_CPU1_IMON2")
	)
	(segment
		(start 108.38561 -365.959136)
		(end 109.130846 -365.2139)
		(width 0.254)
		(layer "In4.Cu")
		(net "PVCCFA_EHV_FIVRA_CPU1_IMON2")
	)
	(segment
		(start 109.130846 -362.72216)
		(end 109.682026 -362.17098)
		(width 0.254)
		(layer "In4.Cu")
		(net "PVCCFA_EHV_FIVRA_CPU1_IMON2")
	)
	(segment
		(start 108.596684 -366.626394)
		(end 108.38561 -366.41532)
		(width 0.254)
		(layer "In4.Cu")
		(net "PVCCFA_EHV_FIVRA_CPU1_IMON2")
	)
	(segment
		(start 108.38561 -366.41532)
		(end 108.38561 -365.959136)
		(width 0.254)
		(layer "In4.Cu")
		(net "PVCCFA_EHV_FIVRA_CPU1_IMON2")
	)
	(segment
		(start 109.682026 -362.17098)
		(end 109.682026 -356.5652)
		(width 0.254)
		(layer "In4.Cu")
		(net "PVCCFA_EHV_FIVRA_CPU1_IMON2")
	)
	(segment
		(start 109.130846 -365.2139)
		(end 109.130846 -362.72216)
		(width 0.254)
		(layer "In4.Cu")
		(net "PVCCFA_EHV_FIVRA_CPU1_IMON2")
	)
	(segment
		(start 110.0963 -356.150926)
		(end 111.368332 -356.150926)
		(width 0.254)
		(layer "In4.Cu")
		(net "PVCCFA_EHV_FIVRA_CPU1_IMON2")
	)
	(segment
		(start 109.682026 -356.5652)
		(end 110.0963 -356.150926)
		(width 0.254)
		(layer "In4.Cu")
		(net "PVCCFA_EHV_FIVRA_CPU1_IMON2")
	)
	(segment
		(start 55.480712 -368.330988)
		(end 54.286658 -367.136934)
		(width 0.254)
		(layer "In6.Cu")
		(net "PVCCFA_EHV_FIVRA_CPU1_IMON2")
	)
	(segment
		(start 55.237126 -369.50015)
		(end 55.480712 -369.256564)
		(width 0.254)
		(layer "In6.Cu")
		(net "PVCCFA_EHV_FIVRA_CPU1_IMON2")
	)
	(segment
		(start 48.048418 -359.74909)
		(end 48.048418 -358.32923)
		(width 0.254)
		(layer "In6.Cu")
		(net "PVCCFA_EHV_FIVRA_CPU1_IMON2")
	)
	(segment
		(start 55.480712 -369.256564)
		(end 55.480712 -368.330988)
		(width 0.254)
		(layer "In6.Cu")
		(net "PVCCFA_EHV_FIVRA_CPU1_IMON2")
	)
	(segment
		(start 48.048418 -358.32923)
		(end 48.848518 -357.52913)
		(width 0.254)
		(layer "In6.Cu")
		(net "PVCCFA_EHV_FIVRA_CPU1_IMON2")
	)
	(segment
		(start 54.286658 -360.94035)
		(end 53.573934 -360.227626)
		(width 0.254)
		(layer "In6.Cu")
		(net "PVCCFA_EHV_FIVRA_CPU1_IMON2")
	)
	(segment
		(start 49.11725 -357.52913)
		(end 49.261014 -357.385366)
		(width 0.254)
		(layer "In6.Cu")
		(net "PVCCFA_EHV_FIVRA_CPU1_IMON2")
	)
	(segment
		(start 48.848518 -357.52913)
		(end 49.11725 -357.52913)
		(width 0.254)
		(layer "In6.Cu")
		(net "PVCCFA_EHV_FIVRA_CPU1_IMON2")
	)
	(segment
		(start 54.286658 -367.136934)
		(end 54.286658 -360.94035)
		(width 0.254)
		(layer "In6.Cu")
		(net "PVCCFA_EHV_FIVRA_CPU1_IMON2")
	)
	(segment
		(start 48.526954 -360.227626)
		(end 48.048418 -359.74909)
		(width 0.254)
		(layer "In6.Cu")
		(net "PVCCFA_EHV_FIVRA_CPU1_IMON2")
	)
	(segment
		(start 53.573934 -360.227626)
		(end 48.526954 -360.227626)
		(width 0.254)
		(layer "In6.Cu")
		(net "PVCCFA_EHV_FIVRA_CPU1_IMON2")
	)
	(segment
		(start 111.798354 -357.048308)
		(end 111.453422 -357.048308)
		(width 0.1778)
		(layer "F.Cu")
		(net "PVCCFA_EHV_FIVRA_CPU1_IMON1")
	)
	(segment
		(start 112.00384 -356.040182)
		(end 112.00384 -356.776782)
		(width 0.1778)
		(layer "F.Cu")
		(net "PVCCFA_EHV_FIVRA_CPU1_IMON1")
	)
	(segment
		(start 112.00384 -356.776782)
		(end 111.957104 -356.889558)
		(width 0.1778)
		(layer "F.Cu")
		(net "PVCCFA_EHV_FIVRA_CPU1_IMON1")
	)
	(segment
		(start 112.629696 -355.058726)
		(end 112.629696 -355.414326)
		(width 0.1778)
		(layer "F.Cu")
		(net "PVCCFA_EHV_FIVRA_CPU1_IMON1")
	)
	(segment
		(start 170.047158 -357.300276)
		(end 170.484292 -356.863142)
		(width 0.254)
		(layer "F.Cu")
		(net "PVCCFA_EHV_FIVRA_CPU1_IMON1")
	)
	(segment
		(start 111.957104 -356.889558)
		(end 111.798354 -357.048308)
		(width 0.1778)
		(layer "F.Cu")
		(net "PVCCFA_EHV_FIVRA_CPU1_IMON1")
	)
	(segment
		(start 170.484292 -356.863142)
		(end 170.484292 -356.454202)
		(width 0.254)
		(layer "F.Cu")
		(net "PVCCFA_EHV_FIVRA_CPU1_IMON1")
	)
	(segment
		(start 112.629696 -355.414326)
		(end 112.00384 -356.040182)
		(width 0.1778)
		(layer "F.Cu")
		(net "PVCCFA_EHV_FIVRA_CPU1_IMON1")
	)
	(via
		(at 170.047158 -357.300276)
		(size 0.508)
		(drill 0.254)
		(layers "F.Cu" "B.Cu")
		(net "PVCCFA_EHV_FIVRA_CPU1_IMON1")
	)
	(via
		(at 112.629696 -355.058726)
		(size 0.508)
		(drill 0.254)
		(layers "F.Cu" "B.Cu")
		(net "PVCCFA_EHV_FIVRA_CPU1_IMON1")
	)
	(segment
		(start 120.357138 -363.320076)
		(end 119.11457 -363.320076)
		(width 0.254)
		(layer "In11.Cu")
		(net "PVCCFA_EHV_FIVRA_CPU1_IMON1")
	)
	(segment
		(start 118.178834 -362.38434)
		(end 118.178834 -358.706928)
		(width 0.254)
		(layer "In11.Cu")
		(net "PVCCFA_EHV_FIVRA_CPU1_IMON1")
	)
	(segment
		(start 170.047158 -357.300276)
		(end 169.63136 -357.300276)
		(width 0.254)
		(layer "In11.Cu")
		(net "PVCCFA_EHV_FIVRA_CPU1_IMON1")
	)
	(segment
		(start 169.63136 -357.300276)
		(end 168.87825 -358.053386)
		(width 0.254)
		(layer "In11.Cu")
		(net "PVCCFA_EHV_FIVRA_CPU1_IMON1")
	)
	(segment
		(start 131.389628 -362.98886)
		(end 120.688354 -362.98886)
		(width 0.254)
		(layer "In11.Cu")
		(net "PVCCFA_EHV_FIVRA_CPU1_IMON1")
	)
	(segment
		(start 119.11457 -363.320076)
		(end 118.178834 -362.38434)
		(width 0.254)
		(layer "In11.Cu")
		(net "PVCCFA_EHV_FIVRA_CPU1_IMON1")
	)
	(segment
		(start 115.151154 -355.679248)
		(end 113.250218 -355.679248)
		(width 0.254)
		(layer "In11.Cu")
		(net "PVCCFA_EHV_FIVRA_CPU1_IMON1")
	)
	(segment
		(start 113.250218 -355.679248)
		(end 112.629696 -355.058726)
		(width 0.254)
		(layer "In11.Cu")
		(net "PVCCFA_EHV_FIVRA_CPU1_IMON1")
	)
	(segment
		(start 120.688354 -362.98886)
		(end 120.357138 -363.320076)
		(width 0.254)
		(layer "In11.Cu")
		(net "PVCCFA_EHV_FIVRA_CPU1_IMON1")
	)
	(segment
		(start 118.178834 -358.706928)
		(end 115.151154 -355.679248)
		(width 0.254)
		(layer "In11.Cu")
		(net "PVCCFA_EHV_FIVRA_CPU1_IMON1")
	)
	(segment
		(start 168.87825 -358.053386)
		(end 136.325102 -358.053386)
		(width 0.254)
		(layer "In11.Cu")
		(net "PVCCFA_EHV_FIVRA_CPU1_IMON1")
	)
	(segment
		(start 136.325102 -358.053386)
		(end 131.389628 -362.98886)
		(width 0.254)
		(layer "In11.Cu")
		(net "PVCCFA_EHV_FIVRA_CPU1_IMON1")
	)
	(segment
		(start 104.13492 -354.845112)
		(end 104.13238 -354.847652)
		(width 0.12954)
		(layer "F.Cu")
		(net "PVCCFA_EHV_FIVRA_CPU1_EN_R")
	)
	(segment
		(start 105.386886 -354.497132)
		(end 105.386886 -354.897436)
		(width 0.12954)
		(layer "F.Cu")
		(net "PVCCFA_EHV_FIVRA_CPU1_EN_R")
	)
	(segment
		(start 105.386886 -354.897436)
		(end 105.70337 -355.21392)
		(width 0.12954)
		(layer "F.Cu")
		(net "PVCCFA_EHV_FIVRA_CPU1_EN_R")
	)
	(segment
		(start 104.13238 -354.847652)
		(end 103.227124 -354.847652)
		(width 0.12954)
		(layer "F.Cu")
		(net "PVCCFA_EHV_FIVRA_CPU1_EN_R")
	)
	(segment
		(start 104.13492 -354.845112)
		(end 105.038906 -354.845112)
		(width 0.12954)
		(layer "F.Cu")
		(net "PVCCFA_EHV_FIVRA_CPU1_EN_R")
	)
	(segment
		(start 105.038906 -354.845112)
		(end 105.386886 -354.497132)
		(width 0.12954)
		(layer "F.Cu")
		(net "PVCCFA_EHV_FIVRA_CPU1_EN_R")
	)
	(segment
		(start 105.70337 -355.21392)
		(end 105.70337 -356.648512)
		(width 0.12954)
		(layer "F.Cu")
		(net "PVCCFA_EHV_FIVRA_CPU1_EN_R")
	)
	(via
		(at 105.386886 -354.497132)
		(size 0.508)
		(drill 0.254)
		(layers "F.Cu" "B.Cu")
		(net "PVCCFA_EHV_FIVRA_CPU1_EN_R")
	)
	(segment
		(start 112.409478 -359.448354)
		(end 112.561878 -359.600754)
		(width 0.1778)
		(layer "F.Cu")
		(net "PVCCFA_EHV_FIVRA_CPU1_BTSEN")
	)
	(segment
		(start 50.61331 -356.897178)
		(end 50.61331 -356.447852)
		(width 0.1778)
		(layer "F.Cu")
		(net "PVCCFA_EHV_FIVRA_CPU1_BTSEN")
	)
	(segment
		(start 113.6396 -359.600754)
		(end 113.116106 -359.600754)
		(width 0.254)
		(layer "F.Cu")
		(net "PVCCFA_EHV_FIVRA_CPU1_BTSEN")
	)
	(segment
		(start 40.603932 -357.219504)
		(end 40.924988 -356.898448)
		(width 0.1778)
		(layer "F.Cu")
		(net "PVCCFA_EHV_FIVRA_CPU1_BTSEN")
	)
	(segment
		(start 171.384214 -356.904544)
		(end 171.384214 -356.454202)
		(width 0.1778)
		(layer "F.Cu")
		(net "PVCCFA_EHV_FIVRA_CPU1_BTSEN")
	)
	(segment
		(start 180.75148 -357.984044)
		(end 180.75148 -357.2256)
		(width 0.1778)
		(layer "F.Cu")
		(net "PVCCFA_EHV_FIVRA_CPU1_BTSEN")
	)
	(segment
		(start 112.561878 -359.600754)
		(end 113.116106 -359.600754)
		(width 0.1778)
		(layer "F.Cu")
		(net "PVCCFA_EHV_FIVRA_CPU1_BTSEN")
	)
	(segment
		(start 114.306604 -358.93375)
		(end 113.6396 -359.600754)
		(width 0.254)
		(layer "F.Cu")
		(net "PVCCFA_EHV_FIVRA_CPU1_BTSEN")
	)
	(segment
		(start 171.063158 -357.2256)
		(end 171.384214 -356.904544)
		(width 0.1778)
		(layer "F.Cu")
		(net "PVCCFA_EHV_FIVRA_CPU1_BTSEN")
	)
	(segment
		(start 113.116106 -359.600754)
		(end 113.116106 -359.595674)
		(width 0.254)
		(layer "F.Cu")
		(net "PVCCFA_EHV_FIVRA_CPU1_BTSEN")
	)
	(segment
		(start 171.063158 -357.984044)
		(end 171.063158 -357.2256)
		(width 0.1778)
		(layer "F.Cu")
		(net "PVCCFA_EHV_FIVRA_CPU1_BTSEN")
	)
	(segment
		(start 50.292254 -357.218234)
		(end 50.61331 -356.897178)
		(width 0.1778)
		(layer "F.Cu")
		(net "PVCCFA_EHV_FIVRA_CPU1_BTSEN")
	)
	(segment
		(start 50.292254 -357.977694)
		(end 50.292254 -357.218234)
		(width 0.1778)
		(layer "F.Cu")
		(net "PVCCFA_EHV_FIVRA_CPU1_BTSEN")
	)
	(segment
		(start 40.603932 -357.977694)
		(end 40.603932 -357.219504)
		(width 0.1778)
		(layer "F.Cu")
		(net "PVCCFA_EHV_FIVRA_CPU1_BTSEN")
	)
	(segment
		(start 181.072536 -356.904544)
		(end 181.072536 -356.454202)
		(width 0.1778)
		(layer "F.Cu")
		(net "PVCCFA_EHV_FIVRA_CPU1_BTSEN")
	)
	(segment
		(start 111.453422 -359.448354)
		(end 112.409478 -359.448354)
		(width 0.1778)
		(layer "F.Cu")
		(net "PVCCFA_EHV_FIVRA_CPU1_BTSEN")
	)
	(segment
		(start 180.75148 -357.2256)
		(end 181.072536 -356.904544)
		(width 0.1778)
		(layer "F.Cu")
		(net "PVCCFA_EHV_FIVRA_CPU1_BTSEN")
	)
	(segment
		(start 40.924988 -356.898448)
		(end 40.924988 -356.447852)
		(width 0.1778)
		(layer "F.Cu")
		(net "PVCCFA_EHV_FIVRA_CPU1_BTSEN")
	)
	(via
		(at 171.063158 -357.984044)
		(size 0.508)
		(drill 0.254)
		(layers "F.Cu" "B.Cu")
		(net "PVCCFA_EHV_FIVRA_CPU1_BTSEN")
	)
	(via
		(at 113.116106 -359.595674)
		(size 0.762)
		(drill 0.254)
		(layers "F.Cu" "B.Cu")
		(net "PVCCFA_EHV_FIVRA_CPU1_BTSEN")
	)
	(via
		(at 100.792788 -365.59236)
		(size 0.508)
		(drill 0.254)
		(layers "F.Cu" "B.Cu")
		(net "PVCCFA_EHV_FIVRA_CPU1_BTSEN")
	)
	(via
		(at 55.775098 -364.592108)
		(size 0.508)
		(drill 0.254)
		(layers "F.Cu" "B.Cu")
		(net "PVCCFA_EHV_FIVRA_CPU1_BTSEN")
	)
	(via
		(at 180.75148 -357.984044)
		(size 0.508)
		(drill 0.254)
		(layers "F.Cu" "B.Cu")
		(net "PVCCFA_EHV_FIVRA_CPU1_BTSEN")
	)
	(via
		(at 40.603932 -357.977694)
		(size 0.508)
		(drill 0.254)
		(layers "F.Cu" "B.Cu")
		(net "PVCCFA_EHV_FIVRA_CPU1_BTSEN")
	)
	(via
		(at 50.292254 -357.977694)
		(size 0.508)
		(drill 0.254)
		(layers "F.Cu" "B.Cu")
		(net "PVCCFA_EHV_FIVRA_CPU1_BTSEN")
	)
	(segment
		(start 100.792788 -365.59236)
		(end 99.704398 -366.68075)
		(width 0.254)
		(layer "B.Cu")
		(net "PVCCFA_EHV_FIVRA_CPU1_BTSEN")
	)
	(segment
		(start 112.338358 -359.27919)
		(end 111.890556 -358.831388)
		(width 0.254)
		(layer "B.Cu")
		(net "PVCCFA_EHV_FIVRA_CPU1_BTSEN")
	)
	(segment
		(start 99.704398 -366.68075)
		(end 61.119258 -366.68075)
		(width 0.254)
		(layer "B.Cu")
		(net "PVCCFA_EHV_FIVRA_CPU1_BTSEN")
	)
	(segment
		(start 113.014506 -359.600754)
		(end 112.692942 -359.27919)
		(width 0.254)
		(layer "B.Cu")
		(net "PVCCFA_EHV_FIVRA_CPU1_BTSEN")
	)
	(segment
		(start 113.111026 -359.600754)
		(end 113.014506 -359.600754)
		(width 0.254)
		(layer "B.Cu")
		(net "PVCCFA_EHV_FIVRA_CPU1_BTSEN")
	)
	(segment
		(start 61.119258 -366.68075)
		(end 59.030616 -364.592108)
		(width 0.254)
		(layer "B.Cu")
		(net "PVCCFA_EHV_FIVRA_CPU1_BTSEN")
	)
	(segment
		(start 112.692942 -359.27919)
		(end 112.338358 -359.27919)
		(width 0.254)
		(layer "B.Cu")
		(net "PVCCFA_EHV_FIVRA_CPU1_BTSEN")
	)
	(segment
		(start 59.030616 -364.592108)
		(end 55.775098 -364.592108)
		(width 0.254)
		(layer "B.Cu")
		(net "PVCCFA_EHV_FIVRA_CPU1_BTSEN")
	)
	(segment
		(start 113.116106 -359.595674)
		(end 113.111026 -359.600754)
		(width 0.254)
		(layer "B.Cu")
		(net "PVCCFA_EHV_FIVRA_CPU1_BTSEN")
	)
	(segment
		(start 111.890556 -358.831388)
		(end 111.890556 -358.522016)
		(width 0.254)
		(layer "B.Cu")
		(net "PVCCFA_EHV_FIVRA_CPU1_BTSEN")
	)
	(segment
		(start 55.013098 -361.234482)
		(end 53.144166 -359.36555)
		(width 0.254)
		(layer "In2.Cu")
		(net "PVCCFA_EHV_FIVRA_CPU1_BTSEN")
	)
	(segment
		(start 53.144166 -359.36555)
		(end 50.778918 -359.36555)
		(width 0.254)
		(layer "In2.Cu")
		(net "PVCCFA_EHV_FIVRA_CPU1_BTSEN")
	)
	(segment
		(start 55.775098 -364.592108)
		(end 55.013098 -363.830108)
		(width 0.254)
		(layer "In2.Cu")
		(net "PVCCFA_EHV_FIVRA_CPU1_BTSEN")
	)
	(segment
		(start 50.778918 -359.36555)
		(end 50.292254 -358.878886)
		(width 0.254)
		(layer "In2.Cu")
		(net "PVCCFA_EHV_FIVRA_CPU1_BTSEN")
	)
	(segment
		(start 50.292254 -358.878886)
		(end 50.292254 -357.977694)
		(width 0.254)
		(layer "In2.Cu")
		(net "PVCCFA_EHV_FIVRA_CPU1_BTSEN")
	)
	(segment
		(start 55.013098 -363.830108)
		(end 55.013098 -361.234482)
		(width 0.254)
		(layer "In2.Cu")
		(net "PVCCFA_EHV_FIVRA_CPU1_BTSEN")
	)
	(segment
		(start 49.408588 -359.69829)
		(end 48.561498 -359.69829)
		(width 0.254)
		(layer "In4.Cu")
		(net "PVCCFA_EHV_FIVRA_CPU1_BTSEN")
	)
	(segment
		(start 114.34064 -360.163872)
		(end 113.780316 -359.603548)
		(width 0.254)
		(layer "In4.Cu")
		(net "PVCCFA_EHV_FIVRA_CPU1_BTSEN")
	)
	(segment
		(start 46.024038 -358.46385)
		(end 45.343318 -359.14457)
		(width 0.254)
		(layer "In4.Cu")
		(net "PVCCFA_EHV_FIVRA_CPU1_BTSEN")
	)
	(segment
		(start 178.78806 -359.92435)
		(end 178.23434 -359.37063)
		(width 0.254)
		(layer "In4.Cu")
		(net "PVCCFA_EHV_FIVRA_CPU1_BTSEN")
	)
	(segment
		(start 111.233712 -367.525808)
		(end 113.81232 -364.9472)
		(width 0.254)
		(layer "In4.Cu")
		(net "PVCCFA_EHV_FIVRA_CPU1_BTSEN")
	)
	(segment
		(start 100.792788 -366.557306)
		(end 101.76129 -367.525808)
		(width 0.254)
		(layer "In4.Cu")
		(net "PVCCFA_EHV_FIVRA_CPU1_BTSEN")
	)
	(segment
		(start 48.205898 -359.34269)
		(end 48.205898 -358.87787)
		(width 0.254)
		(layer "In4.Cu")
		(net "PVCCFA_EHV_FIVRA_CPU1_BTSEN")
	)
	(segment
		(start 50.292254 -358.814624)
		(end 49.408588 -359.69829)
		(width 0.254)
		(layer "In4.Cu")
		(net "PVCCFA_EHV_FIVRA_CPU1_BTSEN")
	)
	(segment
		(start 178.23434 -358.88549)
		(end 177.94478 -358.59593)
		(width 0.254)
		(layer "In4.Cu")
		(net "PVCCFA_EHV_FIVRA_CPU1_BTSEN")
	)
	(segment
		(start 179.648104 -359.92435)
		(end 178.78806 -359.92435)
		(width 0.254)
		(layer "In4.Cu")
		(net "PVCCFA_EHV_FIVRA_CPU1_BTSEN")
	)
	(segment
		(start 113.780316 -359.603548)
		(end 113.121186 -359.603548)
		(width 0.254)
		(layer "In4.Cu")
		(net "PVCCFA_EHV_FIVRA_CPU1_BTSEN")
	)
	(segment
		(start 114.34064 -363.22762)
		(end 114.34064 -360.163872)
		(width 0.254)
		(layer "In4.Cu")
		(net "PVCCFA_EHV_FIVRA_CPU1_BTSEN")
	)
	(segment
		(start 113.116106 -359.598468)
		(end 113.116106 -359.595674)
		(width 0.254)
		(layer "In4.Cu")
		(net "PVCCFA_EHV_FIVRA_CPU1_BTSEN")
	)
	(segment
		(start 178.23434 -359.37063)
		(end 178.23434 -358.88549)
		(width 0.254)
		(layer "In4.Cu")
		(net "PVCCFA_EHV_FIVRA_CPU1_BTSEN")
	)
	(segment
		(start 177.94478 -358.59593)
		(end 175.75276 -358.59593)
		(width 0.254)
		(layer "In4.Cu")
		(net "PVCCFA_EHV_FIVRA_CPU1_BTSEN")
	)
	(segment
		(start 180.75148 -357.984044)
		(end 180.75148 -358.820974)
		(width 0.254)
		(layer "In4.Cu")
		(net "PVCCFA_EHV_FIVRA_CPU1_BTSEN")
	)
	(segment
		(start 50.292254 -357.977694)
		(end 50.292254 -358.814624)
		(width 0.254)
		(layer "In4.Cu")
		(net "PVCCFA_EHV_FIVRA_CPU1_BTSEN")
	)
	(segment
		(start 48.205898 -358.87787)
		(end 47.791878 -358.46385)
		(width 0.254)
		(layer "In4.Cu")
		(net "PVCCFA_EHV_FIVRA_CPU1_BTSEN")
	)
	(segment
		(start 45.343318 -359.14457)
		(end 40.996616 -359.14457)
		(width 0.254)
		(layer "In4.Cu")
		(net "PVCCFA_EHV_FIVRA_CPU1_BTSEN")
	)
	(segment
		(start 100.792788 -365.59236)
		(end 100.792788 -366.557306)
		(width 0.254)
		(layer "In4.Cu")
		(net "PVCCFA_EHV_FIVRA_CPU1_BTSEN")
	)
	(segment
		(start 47.791878 -358.46385)
		(end 46.024038 -358.46385)
		(width 0.254)
		(layer "In4.Cu")
		(net "PVCCFA_EHV_FIVRA_CPU1_BTSEN")
	)
	(segment
		(start 113.81232 -363.75594)
		(end 114.34064 -363.22762)
		(width 0.254)
		(layer "In4.Cu")
		(net "PVCCFA_EHV_FIVRA_CPU1_BTSEN")
	)
	(segment
		(start 171.063158 -358.758236)
		(end 171.063158 -357.984044)
		(width 0.254)
		(layer "In4.Cu")
		(net "PVCCFA_EHV_FIVRA_CPU1_BTSEN")
	)
	(segment
		(start 113.121186 -359.603548)
		(end 113.116106 -359.598468)
		(width 0.254)
		(layer "In4.Cu")
		(net "PVCCFA_EHV_FIVRA_CPU1_BTSEN")
	)
	(segment
		(start 180.75148 -358.820974)
		(end 179.648104 -359.92435)
		(width 0.254)
		(layer "In4.Cu")
		(net "PVCCFA_EHV_FIVRA_CPU1_BTSEN")
	)
	(segment
		(start 40.996616 -359.14457)
		(end 40.603932 -358.751886)
		(width 0.254)
		(layer "In4.Cu")
		(net "PVCCFA_EHV_FIVRA_CPU1_BTSEN")
	)
	(segment
		(start 113.81232 -364.9472)
		(end 113.81232 -363.75594)
		(width 0.254)
		(layer "In4.Cu")
		(net "PVCCFA_EHV_FIVRA_CPU1_BTSEN")
	)
	(segment
		(start 171.416472 -359.11155)
		(end 171.063158 -358.758236)
		(width 0.254)
		(layer "In4.Cu")
		(net "PVCCFA_EHV_FIVRA_CPU1_BTSEN")
	)
	(segment
		(start 101.76129 -367.525808)
		(end 111.233712 -367.525808)
		(width 0.254)
		(layer "In4.Cu")
		(net "PVCCFA_EHV_FIVRA_CPU1_BTSEN")
	)
	(segment
		(start 175.23714 -359.11155)
		(end 171.416472 -359.11155)
		(width 0.254)
		(layer "In4.Cu")
		(net "PVCCFA_EHV_FIVRA_CPU1_BTSEN")
	)
	(segment
		(start 40.603932 -358.751886)
		(end 40.603932 -357.977694)
		(width 0.254)
		(layer "In4.Cu")
		(net "PVCCFA_EHV_FIVRA_CPU1_BTSEN")
	)
	(segment
		(start 175.75276 -358.59593)
		(end 175.23714 -359.11155)
		(width 0.254)
		(layer "In4.Cu")
		(net "PVCCFA_EHV_FIVRA_CPU1_BTSEN")
	)
	(segment
		(start 48.561498 -359.69829)
		(end 48.205898 -359.34269)
		(width 0.254)
		(layer "In4.Cu")
		(net "PVCCFA_EHV_FIVRA_CPU1_BTSEN")
	)
	(segment
		(start 135.08228 -358.74325)
		(end 164.69868 -358.74325)
		(width 0.254)
		(layer "In6.Cu")
		(net "PVCCFA_EHV_FIVRA_CPU1_BTSEN")
	)
	(segment
		(start 170.500548 -360.082846)
		(end 171.063158 -359.520236)
		(width 0.254)
		(layer "In6.Cu")
		(net "PVCCFA_EHV_FIVRA_CPU1_BTSEN")
	)
	(segment
		(start 126.299214 -356.046532)
		(end 132.385562 -356.046532)
		(width 0.254)
		(layer "In6.Cu")
		(net "PVCCFA_EHV_FIVRA_CPU1_BTSEN")
	)
	(segment
		(start 117.81028 -357.817928)
		(end 119.029988 -356.59822)
		(width 0.254)
		(layer "In6.Cu")
		(net "PVCCFA_EHV_FIVRA_CPU1_BTSEN")
	)
	(segment
		(start 132.385562 -356.046532)
		(end 135.08228 -358.74325)
		(width 0.254)
		(layer "In6.Cu")
		(net "PVCCFA_EHV_FIVRA_CPU1_BTSEN")
	)
	(segment
		(start 115.19916 -358.539796)
		(end 115.19916 -357.688388)
		(width 0.254)
		(layer "In6.Cu")
		(net "PVCCFA_EHV_FIVRA_CPU1_BTSEN")
	)
	(segment
		(start 166.038276 -360.082846)
		(end 170.500548 -360.082846)
		(width 0.254)
		(layer "In6.Cu")
		(net "PVCCFA_EHV_FIVRA_CPU1_BTSEN")
	)
	(segment
		(start 113.116106 -359.600754)
		(end 113.217706 -359.702354)
		(width 0.254)
		(layer "In6.Cu")
		(net "PVCCFA_EHV_FIVRA_CPU1_BTSEN")
	)
	(segment
		(start 115.56238 -357.325168)
		(end 115.95862 -357.325168)
		(width 0.254)
		(layer "In6.Cu")
		(net "PVCCFA_EHV_FIVRA_CPU1_BTSEN")
	)
	(segment
		(start 171.063158 -359.520236)
		(end 171.063158 -357.984044)
		(width 0.254)
		(layer "In6.Cu")
		(net "PVCCFA_EHV_FIVRA_CPU1_BTSEN")
	)
	(segment
		(start 164.69868 -358.74325)
		(end 166.038276 -360.082846)
		(width 0.254)
		(layer "In6.Cu")
		(net "PVCCFA_EHV_FIVRA_CPU1_BTSEN")
	)
	(segment
		(start 119.029988 -356.59822)
		(end 121.003314 -356.59822)
		(width 0.254)
		(layer "In6.Cu")
		(net "PVCCFA_EHV_FIVRA_CPU1_BTSEN")
	)
	(segment
		(start 122.667776 -354.933758)
		(end 125.18644 -354.933758)
		(width 0.254)
		(layer "In6.Cu")
		(net "PVCCFA_EHV_FIVRA_CPU1_BTSEN")
	)
	(segment
		(start 121.003314 -356.59822)
		(end 122.667776 -354.933758)
		(width 0.254)
		(layer "In6.Cu")
		(net "PVCCFA_EHV_FIVRA_CPU1_BTSEN")
	)
	(segment
		(start 116.45138 -357.817928)
		(end 117.81028 -357.817928)
		(width 0.254)
		(layer "In6.Cu")
		(net "PVCCFA_EHV_FIVRA_CPU1_BTSEN")
	)
	(segment
		(start 125.18644 -354.933758)
		(end 126.299214 -356.046532)
		(width 0.254)
		(layer "In6.Cu")
		(net "PVCCFA_EHV_FIVRA_CPU1_BTSEN")
	)
	(segment
		(start 115.95862 -357.325168)
		(end 116.45138 -357.817928)
		(width 0.254)
		(layer "In6.Cu")
		(net "PVCCFA_EHV_FIVRA_CPU1_BTSEN")
	)
	(segment
		(start 113.116106 -359.595674)
		(end 113.116106 -359.600754)
		(width 0.254)
		(layer "In6.Cu")
		(net "PVCCFA_EHV_FIVRA_CPU1_BTSEN")
	)
	(segment
		(start 115.19916 -357.688388)
		(end 115.56238 -357.325168)
		(width 0.254)
		(layer "In6.Cu")
		(net "PVCCFA_EHV_FIVRA_CPU1_BTSEN")
	)
	(segment
		(start 113.217706 -359.702354)
		(end 114.036602 -359.702354)
		(width 0.254)
		(layer "In6.Cu")
		(net "PVCCFA_EHV_FIVRA_CPU1_BTSEN")
	)
	(segment
		(start 114.036602 -359.702354)
		(end 115.19916 -358.539796)
		(width 0.254)
		(layer "In6.Cu")
		(net "PVCCFA_EHV_FIVRA_CPU1_BTSEN")
	)
	(segment
		(start 96.133666 -222.48368)
		(end 96.133666 -221.947994)
		(width 0.254)
		(layer "F.Cu")
		(net "PVCCFA_EHV_FIVRA_CPU1")
	)
	(segment
		(start 129.966466 -219.228162)
		(end 129.966466 -218.692476)
		(width 0.254)
		(layer "F.Cu")
		(net "PVCCFA_EHV_FIVRA_CPU1")
	)
	(segment
		(start 99.532694 -287.567116)
		(end 99.532694 -288.102802)
		(width 0.254)
		(layer "F.Cu")
		(net "PVCCFA_EHV_FIVRA_CPU1")
	)
	(segment
		(start 52.894738 -337.477608)
		(end 52.894738 -338.417916)
		(width 0.508)
		(layer "F.Cu")
		(net "PVCCFA_EHV_FIVRA_CPU1")
	)
	(segment
		(start 98.013266 -218.692476)
		(end 98.013012 -218.692222)
		(width 0.254)
		(layer "F.Cu")
		(net "PVCCFA_EHV_FIVRA_CPU1")
	)
	(segment
		(start 101.772466 -225.739198)
		(end 101.772466 -225.203512)
		(width 0.254)
		(layer "F.Cu")
		(net "PVCCFA_EHV_FIVRA_CPU1")
	)
	(segment
		(start 89.194894 -285.939484)
		(end 89.194894 -286.47517)
		(width 0.254)
		(layer "F.Cu")
		(net "PVCCFA_EHV_FIVRA_CPU1")
	)
	(segment
		(start 128.086866 -225.739198)
		(end 128.086866 -225.203512)
		(width 0.254)
		(layer "F.Cu")
		(net "PVCCFA_EHV_FIVRA_CPU1")
	)
	(segment
		(start 94.254066 -219.228162)
		(end 94.254066 -218.692476)
		(width 0.254)
		(layer "F.Cu")
		(net "PVCCFA_EHV_FIVRA_CPU1")
	)
	(segment
		(start 128.086866 -218.692476)
		(end 128.086612 -218.692222)
		(width 0.254)
		(layer "F.Cu")
		(net "PVCCFA_EHV_FIVRA_CPU1")
	)
	(segment
		(start 103.291894 -288.102802)
		(end 103.292148 -288.103056)
		(width 0.254)
		(layer "F.Cu")
		(net "PVCCFA_EHV_FIVRA_CPU1")
	)
	(segment
		(start 99.892866 -218.692476)
		(end 99.892612 -218.692222)
		(width 0.254)
		(layer "F.Cu")
		(net "PVCCFA_EHV_FIVRA_CPU1")
	)
	(segment
		(start 123.967494 -288.102802)
		(end 123.967748 -288.103056)
		(width 0.254)
		(layer "F.Cu")
		(net "PVCCFA_EHV_FIVRA_CPU1")
	)
	(segment
		(start 127.726694 -284.311598)
		(end 127.726948 -284.847538)
		(width 0.254)
		(layer "F.Cu")
		(net "PVCCFA_EHV_FIVRA_CPU1")
	)
	(segment
		(start 92.374466 -225.203512)
		(end 92.374212 -225.203258)
		(width 0.2032)
		(layer "F.Cu")
		(net "PVCCFA_EHV_FIVRA_CPU1")
	)
	(segment
		(start 129.606294 -279.428194)
		(end 129.606294 -279.96388)
		(width 0.254)
		(layer "F.Cu")
		(net "PVCCFA_EHV_FIVRA_CPU1")
	)
	(segment
		(start 88.725248 -280.242264)
		(end 88.725248 -280.77795)
		(width 0.254)
		(layer "F.Cu")
		(net "PVCCFA_EHV_FIVRA_CPU1")
	)
	(segment
		(start 89.194894 -286.47517)
		(end 89.195148 -286.475424)
		(width 0.254)
		(layer "F.Cu")
		(net "PVCCFA_EHV_FIVRA_CPU1")
	)
	(segment
		(start 96.133666 -218.692476)
		(end 96.133412 -218.692222)
		(width 0.254)
		(layer "F.Cu")
		(net "PVCCFA_EHV_FIVRA_CPU1")
	)
	(segment
		(start 128.086866 -225.203512)
		(end 128.086612 -225.203258)
		(width 0.254)
		(layer "F.Cu")
		(net "PVCCFA_EHV_FIVRA_CPU1")
	)
	(segment
		(start 177.156364 -337.483958)
		(end 177.156364 -338.424266)
		(width 0.508)
		(layer "F.Cu")
		(net "PVCCFA_EHV_FIVRA_CPU1")
	)
	(segment
		(start 97.183448 -278.614378)
		(end 97.183448 -279.150064)
		(width 0.254)
		(layer "F.Cu")
		(net "PVCCFA_EHV_FIVRA_CPU1")
	)
	(segment
		(start 102.821994 -277.522178)
		(end 102.821994 -277.522432)
		(width 0.254)
		(layer "F.Cu")
		(net "PVCCFA_EHV_FIVRA_CPU1")
	)
	(segment
		(start 93.893894 -284.847284)
		(end 93.894148 -284.847538)
		(width 0.254)
		(layer "F.Cu")
		(net "PVCCFA_EHV_FIVRA_CPU1")
	)
	(segment
		(start 133.365494 -287.567116)
		(end 133.365494 -288.102802)
		(width 0.254)
		(layer "F.Cu")
		(net "PVCCFA_EHV_FIVRA_CPU1")
	)
	(segment
		(start 99.892866 -222.48368)
		(end 99.892866 -221.947994)
		(width 0.254)
		(layer "F.Cu")
		(net "PVCCFA_EHV_FIVRA_CPU1")
	)
	(segment
		(start 89.664794 -283.497782)
		(end 89.664794 -284.033722)
		(width 0.254)
		(layer "F.Cu")
		(net "PVCCFA_EHV_FIVRA_CPU1")
	)
	(segment
		(start 97.653094 -287.567116)
		(end 97.653094 -288.102802)
		(width 0.254)
		(layer "F.Cu")
		(net "PVCCFA_EHV_FIVRA_CPU1")
	)
	(segment
		(start 90.494866 -221.947994)
		(end 90.494612 -221.94774)
		(width 0.254)
		(layer "F.Cu")
		(net "PVCCFA_EHV_FIVRA_CPU1")
	)
	(segment
		(start 129.966466 -222.48368)
		(end 129.966466 -221.947994)
		(width 0.254)
		(layer "F.Cu")
		(net "PVCCFA_EHV_FIVRA_CPU1")
	)
	(segment
		(start 101.772466 -225.203512)
		(end 101.772212 -225.203258)
		(width 0.254)
		(layer "F.Cu")
		(net "PVCCFA_EHV_FIVRA_CPU1")
	)
	(segment
		(start 96.713294 -277.800562)
		(end 96.713294 -278.336248)
		(width 0.254)
		(layer "F.Cu")
		(net "PVCCFA_EHV_FIVRA_CPU1")
	)
	(segment
		(start 129.606294 -288.102802)
		(end 129.606548 -288.103056)
		(width 0.254)
		(layer "F.Cu")
		(net "PVCCFA_EHV_FIVRA_CPU1")
	)
	(segment
		(start 99.892866 -221.947994)
		(end 99.892612 -221.94774)
		(width 0.254)
		(layer "F.Cu")
		(net "PVCCFA_EHV_FIVRA_CPU1")
	)
	(segment
		(start 91.544648 -280.242264)
		(end 91.544902 -280.242518)
		(width 0.254)
		(layer "F.Cu")
		(net "PVCCFA_EHV_FIVRA_CPU1")
	)
	(segment
		(start 133.365494 -284.311598)
		(end 133.365748 -284.847538)
		(width 0.254)
		(layer "F.Cu")
		(net "PVCCFA_EHV_FIVRA_CPU1")
	)
	(segment
		(start 129.966466 -225.739198)
		(end 129.966466 -225.203512)
		(width 0.254)
		(layer "F.Cu")
		(net "PVCCFA_EHV_FIVRA_CPU1")
	)
	(segment
		(start 129.966466 -215.972644)
		(end 129.966466 -215.437212)
		(width 0.254)
		(layer "F.Cu")
		(net "PVCCFA_EHV_FIVRA_CPU1")
	)
	(segment
		(start 92.014294 -288.102802)
		(end 92.014548 -288.103056)
		(width 0.254)
		(layer "F.Cu")
		(net "PVCCFA_EHV_FIVRA_CPU1")
	)
	(segment
		(start 99.892866 -225.739198)
		(end 99.892866 -225.203512)
		(width 0.254)
		(layer "F.Cu")
		(net "PVCCFA_EHV_FIVRA_CPU1")
	)
	(segment
		(start 99.892866 -219.228162)
		(end 99.892866 -218.692476)
		(width 0.254)
		(layer "F.Cu")
		(net "PVCCFA_EHV_FIVRA_CPU1")
	)
	(segment
		(start 95.773494 -284.847284)
		(end 95.773748 -284.847538)
		(width 0.254)
		(layer "F.Cu")
		(net "PVCCFA_EHV_FIVRA_CPU1")
	)
	(segment
		(start 170.965622 -337.477608)
		(end 171.90593 -337.477608)
		(width 0.508)
		(layer "F.Cu")
		(net "PVCCFA_EHV_FIVRA_CPU1")
	)
	(segment
		(start 120.208294 -284.311598)
		(end 120.208548 -284.847538)
		(width 0.254)
		(layer "F.Cu")
		(net "PVCCFA_EHV_FIVRA_CPU1")
	)
	(segment
		(start 40.506396 -337.471258)
		(end 40.506396 -338.411566)
		(width 0.508)
		(layer "F.Cu")
		(net "PVCCFA_EHV_FIVRA_CPU1")
	)
	(segment
		(start 182.413656 -337.483958)
		(end 183.353964 -337.483958)
		(width 0.508)
		(layer "F.Cu")
		(net "PVCCFA_EHV_FIVRA_CPU1")
	)
	(segment
		(start 88.725248 -280.77795)
		(end 88.724994 -280.778204)
		(width 0.254)
		(layer "F.Cu")
		(net "PVCCFA_EHV_FIVRA_CPU1")
	)
	(segment
		(start 122.087894 -279.96388)
		(end 122.088148 -279.964134)
		(width 0.254)
		(layer "F.Cu")
		(net "PVCCFA_EHV_FIVRA_CPU1")
	)
	(segment
		(start 97.183448 -279.150064)
		(end 97.183194 -279.150318)
		(width 0.254)
		(layer "F.Cu")
		(net "PVCCFA_EHV_FIVRA_CPU1")
	)
	(segment
		(start 52.894738 -337.477608)
		(end 53.835046 -337.477608)
		(width 0.508)
		(layer "F.Cu")
		(net "PVCCFA_EHV_FIVRA_CPU1")
	)
	(segment
		(start 131.846066 -225.739198)
		(end 131.846066 -225.203512)
		(width 0.254)
		(layer "F.Cu")
		(net "PVCCFA_EHV_FIVRA_CPU1")
	)
	(segment
		(start 96.133666 -225.739198)
		(end 96.133666 -225.203512)
		(width 0.254)
		(layer "F.Cu")
		(net "PVCCFA_EHV_FIVRA_CPU1")
	)
	(segment
		(start 127.726694 -288.102802)
		(end 127.726948 -288.103056)
		(width 0.254)
		(layer "F.Cu")
		(net "PVCCFA_EHV_FIVRA_CPU1")
	)
	(segment
		(start 93.893894 -284.311598)
		(end 93.893894 -284.847284)
		(width 0.254)
		(layer "F.Cu")
		(net "PVCCFA_EHV_FIVRA_CPU1")
	)
	(segment
		(start 128.086612 -215.436958)
		(end 128.086612 -215.436704)
		(width 0.254)
		(layer "F.Cu")
		(net "PVCCFA_EHV_FIVRA_CPU1")
	)
	(segment
		(start 128.086866 -221.947994)
		(end 128.086612 -221.94774)
		(width 0.254)
		(layer "F.Cu")
		(net "PVCCFA_EHV_FIVRA_CPU1")
	)
	(segment
		(start 95.773494 -288.102802)
		(end 95.773748 -288.103056)
		(width 0.254)
		(layer "F.Cu")
		(net "PVCCFA_EHV_FIVRA_CPU1")
	)
	(segment
		(start 122.087894 -287.567116)
		(end 122.087894 -288.102802)
		(width 0.254)
		(layer "F.Cu")
		(net "PVCCFA_EHV_FIVRA_CPU1")
	)
	(segment
		(start 105.641648 -273.730974)
		(end 105.641648 -274.26666)
		(width 0.254)
		(layer "F.Cu")
		(net "PVCCFA_EHV_FIVRA_CPU1")
	)
	(segment
		(start 128.086866 -222.48368)
		(end 128.086866 -221.947994)
		(width 0.254)
		(layer "F.Cu")
		(net "PVCCFA_EHV_FIVRA_CPU1")
	)
	(segment
		(start 85.905594 -284.033722)
		(end 85.905594 -283.497782)
		(width 0.254)
		(layer "F.Cu")
		(net "PVCCFA_EHV_FIVRA_CPU1")
	)
	(segment
		(start 125.847094 -287.567116)
		(end 125.847094 -288.102802)
		(width 0.254)
		(layer "F.Cu")
		(net "PVCCFA_EHV_FIVRA_CPU1")
	)
	(segment
		(start 129.966212 -215.436958)
		(end 129.966212 -215.436704)
		(width 0.254)
		(layer "F.Cu")
		(net "PVCCFA_EHV_FIVRA_CPU1")
	)
	(segment
		(start 129.606294 -287.567116)
		(end 129.606294 -288.102802)
		(width 0.254)
		(layer "F.Cu")
		(net "PVCCFA_EHV_FIVRA_CPU1")
	)
	(segment
		(start 176.216056 -337.483958)
		(end 177.156364 -337.483958)
		(width 0.508)
		(layer "F.Cu")
		(net "PVCCFA_EHV_FIVRA_CPU1")
	)
	(segment
		(start 90.494866 -219.228162)
		(end 90.494866 -218.692476)
		(width 0.254)
		(layer "F.Cu")
		(net "PVCCFA_EHV_FIVRA_CPU1")
	)
	(segment
		(start 97.653094 -284.311598)
		(end 97.653094 -284.847284)
		(width 0.254)
		(layer "F.Cu")
		(net "PVCCFA_EHV_FIVRA_CPU1")
	)
	(segment
		(start 118.328694 -274.54479)
		(end 118.328948 -274.545044)
		(width 0.254)
		(layer "F.Cu")
		(net "PVCCFA_EHV_FIVRA_CPU1")
	)
	(segment
		(start 120.208294 -278.336248)
		(end 120.208548 -278.336502)
		(width 0.254)
		(layer "F.Cu")
		(net "PVCCFA_EHV_FIVRA_CPU1")
	)
	(segment
		(start 106.111294 -277.800562)
		(end 106.111294 -278.336248)
		(width 0.254)
		(layer "F.Cu")
		(net "PVCCFA_EHV_FIVRA_CPU1")
	)
	(segment
		(start 177.156364 -337.483958)
		(end 178.096672 -337.483958)
		(width 0.508)
		(layer "F.Cu")
		(net "PVCCFA_EHV_FIVRA_CPU1")
	)
	(segment
		(start 46.697138 -337.477608)
		(end 47.637446 -337.477608)
		(width 0.508)
		(layer "F.Cu")
		(net "PVCCFA_EHV_FIVRA_CPU1")
	)
	(segment
		(start 129.606294 -279.96388)
		(end 129.606548 -279.964134)
		(width 0.254)
		(layer "F.Cu")
		(net "PVCCFA_EHV_FIVRA_CPU1")
	)
	(segment
		(start 92.374466 -219.228162)
		(end 92.374466 -218.692476)
		(width 0.254)
		(layer "F.Cu")
		(net "PVCCFA_EHV_FIVRA_CPU1")
	)
	(segment
		(start 92.014294 -284.311598)
		(end 92.014294 -284.847538)
		(width 0.254)
		(layer "F.Cu")
		(net "PVCCFA_EHV_FIVRA_CPU1")
	)
	(segment
		(start 125.847094 -288.102802)
		(end 125.847348 -288.103056)
		(width 0.254)
		(layer "F.Cu")
		(net "PVCCFA_EHV_FIVRA_CPU1")
	)
	(segment
		(start 131.485894 -284.311598)
		(end 131.486148 -284.847538)
		(width 0.254)
		(layer "F.Cu")
		(net "PVCCFA_EHV_FIVRA_CPU1")
	)
	(segment
		(start 170.025314 -337.477608)
		(end 170.965622 -337.477608)
		(width 0.508)
		(layer "F.Cu")
		(net "PVCCFA_EHV_FIVRA_CPU1")
	)
	(segment
		(start 98.013266 -225.203512)
		(end 98.013012 -225.203258)
		(width 0.254)
		(layer "F.Cu")
		(net "PVCCFA_EHV_FIVRA_CPU1")
	)
	(segment
		(start 137.594594 -283.497782)
		(end 137.594594 -284.033722)
		(width 0.254)
		(layer "F.Cu")
		(net "PVCCFA_EHV_FIVRA_CPU1")
	)
	(segment
		(start 117.389148 -274.545044)
		(end 117.389148 -275.08073)
		(width 0.254)
		(layer "F.Cu")
		(net "PVCCFA_EHV_FIVRA_CPU1")
	)
	(segment
		(start 96.713294 -278.336248)
		(end 96.713548 -278.336502)
		(width 0.254)
		(layer "F.Cu")
		(net "PVCCFA_EHV_FIVRA_CPU1")
	)
	(segment
		(start 127.726694 -282.683966)
		(end 127.726948 -283.219906)
		(width 0.254)
		(layer "F.Cu")
		(net "PVCCFA_EHV_FIVRA_CPU1")
	)
	(segment
		(start 98.013266 -225.739198)
		(end 98.013266 -225.203512)
		(width 0.254)
		(layer "F.Cu")
		(net "PVCCFA_EHV_FIVRA_CPU1")
	)
	(segment
		(start 95.773494 -287.567116)
		(end 95.773494 -288.102802)
		(width 0.254)
		(layer "F.Cu")
		(net "PVCCFA_EHV_FIVRA_CPU1")
	)
	(segment
		(start 123.967494 -287.567116)
		(end 123.967494 -288.102802)
		(width 0.254)
		(layer "F.Cu")
		(net "PVCCFA_EHV_FIVRA_CPU1")
	)
	(segment
		(start 94.254066 -218.692476)
		(end 94.253812 -218.692222)
		(width 0.254)
		(layer "F.Cu")
		(net "PVCCFA_EHV_FIVRA_CPU1")
	)
	(segment
		(start 46.697138 -337.477608)
		(end 46.697138 -338.417916)
		(width 0.508)
		(layer "F.Cu")
		(net "PVCCFA_EHV_FIVRA_CPU1")
	)
	(segment
		(start 134.775448 -280.77795)
		(end 134.775194 -280.778204)
		(width 0.254)
		(layer "F.Cu")
		(net "PVCCFA_EHV_FIVRA_CPU1")
	)
	(segment
		(start 183.353964 -337.483958)
		(end 183.353964 -338.424266)
		(width 0.508)
		(layer "F.Cu")
		(net "PVCCFA_EHV_FIVRA_CPU1")
	)
	(segment
		(start 88.255094 -287.567116)
		(end 88.255094 -288.103056)
		(width 0.1778)
		(layer "F.Cu")
		(net "PVCCFA_EHV_FIVRA_CPU1")
	)
	(segment
		(start 134.775448 -280.242264)
		(end 134.775448 -280.77795)
		(width 0.254)
		(layer "F.Cu")
		(net "PVCCFA_EHV_FIVRA_CPU1")
	)
	(segment
		(start 93.893894 -287.567116)
		(end 93.893894 -288.102802)
		(width 0.254)
		(layer "F.Cu")
		(net "PVCCFA_EHV_FIVRA_CPU1")
	)
	(segment
		(start 92.374466 -225.739198)
		(end 92.374466 -225.203512)
		(width 0.2032)
		(layer "F.Cu")
		(net "PVCCFA_EHV_FIVRA_CPU1")
	)
	(segment
		(start 118.798848 -278.614378)
		(end 118.798594 -279.150318)
		(width 0.254)
		(layer "F.Cu")
		(net "PVCCFA_EHV_FIVRA_CPU1")
	)
	(segment
		(start 129.966466 -225.203512)
		(end 129.966212 -225.203258)
		(width 0.254)
		(layer "F.Cu")
		(net "PVCCFA_EHV_FIVRA_CPU1")
	)
	(segment
		(start 97.653094 -284.847284)
		(end 97.653348 -284.847538)
		(width 0.254)
		(layer "F.Cu")
		(net "PVCCFA_EHV_FIVRA_CPU1")
	)
	(segment
		(start 90.494866 -218.692476)
		(end 90.494612 -218.692222)
		(width 0.254)
		(layer "F.Cu")
		(net "PVCCFA_EHV_FIVRA_CPU1")
	)
	(segment
		(start 123.967494 -284.311598)
		(end 123.967748 -284.847538)
		(width 0.254)
		(layer "F.Cu")
		(net "PVCCFA_EHV_FIVRA_CPU1")
	)
	(segment
		(start 90.134694 -287.567116)
		(end 90.134694 -288.103056)
		(width 0.254)
		(layer "F.Cu")
		(net "PVCCFA_EHV_FIVRA_CPU1")
	)
	(segment
		(start 134.305294 -279.428194)
		(end 134.305294 -279.96388)
		(width 0.254)
		(layer "F.Cu")
		(net "PVCCFA_EHV_FIVRA_CPU1")
	)
	(segment
		(start 122.087894 -288.102802)
		(end 122.088148 -288.103056)
		(width 0.254)
		(layer "F.Cu")
		(net "PVCCFA_EHV_FIVRA_CPU1")
	)
	(segment
		(start 90.134694 -284.311598)
		(end 90.134694 -284.847538)
		(width 0.254)
		(layer "F.Cu")
		(net "PVCCFA_EHV_FIVRA_CPU1")
	)
	(segment
		(start 128.086866 -215.437212)
		(end 128.086612 -215.436958)
		(width 0.254)
		(layer "F.Cu")
		(net "PVCCFA_EHV_FIVRA_CPU1")
	)
	(segment
		(start 96.133666 -219.228162)
		(end 96.133666 -218.692476)
		(width 0.254)
		(layer "F.Cu")
		(net "PVCCFA_EHV_FIVRA_CPU1")
	)
	(segment
		(start 99.532694 -288.102802)
		(end 99.532948 -288.103056)
		(width 0.254)
		(layer "F.Cu")
		(net "PVCCFA_EHV_FIVRA_CPU1")
	)
	(segment
		(start 92.374466 -222.48368)
		(end 92.374466 -221.947994)
		(width 0.254)
		(layer "F.Cu")
		(net "PVCCFA_EHV_FIVRA_CPU1")
	)
	(segment
		(start 107.051348 -279.428448)
		(end 107.051348 -279.964134)
		(width 0.254)
		(layer "F.Cu")
		(net "PVCCFA_EHV_FIVRA_CPU1")
	)
	(segment
		(start 123.967494 -282.683966)
		(end 123.967748 -283.219906)
		(width 0.254)
		(layer "F.Cu")
		(net "PVCCFA_EHV_FIVRA_CPU1")
	)
	(segment
		(start 119.268748 -274.545044)
		(end 119.268748 -275.08073)
		(width 0.254)
		(layer "F.Cu")
		(net "PVCCFA_EHV_FIVRA_CPU1")
	)
	(segment
		(start 93.893894 -279.428194)
		(end 93.893894 -279.964134)
		(width 0.254)
		(layer "F.Cu")
		(net "PVCCFA_EHV_FIVRA_CPU1")
	)
	(segment
		(start 107.051094 -279.428194)
		(end 107.051348 -279.428448)
		(width 0.254)
		(layer "F.Cu")
		(net "PVCCFA_EHV_FIVRA_CPU1")
	)
	(segment
		(start 99.892866 -225.203512)
		(end 99.892612 -225.203258)
		(width 0.254)
		(layer "F.Cu")
		(net "PVCCFA_EHV_FIVRA_CPU1")
	)
	(segment
		(start 93.424248 -280.242264)
		(end 93.424248 -280.77795)
		(width 0.254)
		(layer "F.Cu")
		(net "PVCCFA_EHV_FIVRA_CPU1")
	)
	(segment
		(start 91.544902 -280.77795)
		(end 91.544648 -280.778204)
		(width 0.254)
		(layer "F.Cu")
		(net "PVCCFA_EHV_FIVRA_CPU1")
	)
	(segment
		(start 93.424248 -280.77795)
		(end 93.423994 -280.778204)
		(width 0.254)
		(layer "F.Cu")
		(net "PVCCFA_EHV_FIVRA_CPU1")
	)
	(segment
		(start 94.254066 -225.203512)
		(end 94.253812 -225.203258)
		(width 0.254)
		(layer "F.Cu")
		(net "PVCCFA_EHV_FIVRA_CPU1")
	)
	(segment
		(start 100.002848 -280.242264)
		(end 100.002848 -280.77795)
		(width 0.254)
		(layer "F.Cu")
		(net "PVCCFA_EHV_FIVRA_CPU1")
	)
	(segment
		(start 98.013266 -221.947994)
		(end 98.013012 -221.94774)
		(width 0.254)
		(layer "F.Cu")
		(net "PVCCFA_EHV_FIVRA_CPU1")
	)
	(segment
		(start 133.725666 -219.228162)
		(end 133.725666 -218.692222)
		(width 0.254)
		(layer "F.Cu")
		(net "PVCCFA_EHV_FIVRA_CPU1")
	)
	(segment
		(start 131.846066 -218.692476)
		(end 131.845812 -218.692222)
		(width 0.254)
		(layer "F.Cu")
		(net "PVCCFA_EHV_FIVRA_CPU1")
	)
	(segment
		(start 133.365494 -279.428194)
		(end 133.365494 -279.96388)
		(width 0.254)
		(layer "F.Cu")
		(net "PVCCFA_EHV_FIVRA_CPU1")
	)
	(segment
		(start 122.087894 -279.428194)
		(end 122.087894 -279.96388)
		(width 0.254)
		(layer "F.Cu")
		(net "PVCCFA_EHV_FIVRA_CPU1")
	)
	(segment
		(start 98.013266 -219.228162)
		(end 98.013266 -218.692476)
		(width 0.254)
		(layer "F.Cu")
		(net "PVCCFA_EHV_FIVRA_CPU1")
	)
	(segment
		(start 122.087894 -284.311598)
		(end 122.088148 -284.847538)
		(width 0.254)
		(layer "F.Cu")
		(net "PVCCFA_EHV_FIVRA_CPU1")
	)
	(segment
		(start 123.967494 -278.336248)
		(end 123.967748 -278.336502)
		(width 0.254)
		(layer "F.Cu")
		(net "PVCCFA_EHV_FIVRA_CPU1")
	)
	(segment
		(start 107.521248 -278.614378)
		(end 107.521248 -279.150064)
		(width 0.254)
		(layer "F.Cu")
		(net "PVCCFA_EHV_FIVRA_CPU1")
	)
	(segment
		(start 183.353964 -337.483958)
		(end 184.294272 -337.483958)
		(width 0.508)
		(layer "F.Cu")
		(net "PVCCFA_EHV_FIVRA_CPU1")
	)
	(segment
		(start 133.725666 -225.739198)
		(end 133.725666 -225.203258)
		(width 0.254)
		(layer "F.Cu")
		(net "PVCCFA_EHV_FIVRA_CPU1")
	)
	(segment
		(start 115.039648 -275.35886)
		(end 115.039648 -275.894546)
		(width 0.254)
		(layer "F.Cu")
		(net "PVCCFA_EHV_FIVRA_CPU1")
	)
	(segment
		(start 93.893894 -288.102802)
		(end 93.894148 -288.103056)
		(width 0.254)
		(layer "F.Cu")
		(net "PVCCFA_EHV_FIVRA_CPU1")
	)
	(segment
		(start 132.895848 -278.614378)
		(end 132.895848 -279.150318)
		(width 0.254)
		(layer "F.Cu")
		(net "PVCCFA_EHV_FIVRA_CPU1")
	)
	(segment
		(start 129.966466 -221.947994)
		(end 129.966212 -221.94774)
		(width 0.254)
		(layer "F.Cu")
		(net "PVCCFA_EHV_FIVRA_CPU1")
	)
	(segment
		(start 115.039648 -275.894546)
		(end 115.039394 -275.8948)
		(width 0.254)
		(layer "F.Cu")
		(net "PVCCFA_EHV_FIVRA_CPU1")
	)
	(segment
		(start 133.365494 -279.96388)
		(end 133.365748 -279.964134)
		(width 0.254)
		(layer "F.Cu")
		(net "PVCCFA_EHV_FIVRA_CPU1")
	)
	(segment
		(start 127.726694 -287.567116)
		(end 127.726694 -288.102802)
		(width 0.254)
		(layer "F.Cu")
		(net "PVCCFA_EHV_FIVRA_CPU1")
	)
	(segment
		(start 99.532694 -279.428194)
		(end 99.532948 -279.964134)
		(width 0.254)
		(layer "F.Cu")
		(net "PVCCFA_EHV_FIVRA_CPU1")
	)
	(segment
		(start 101.412294 -287.567116)
		(end 101.412294 -288.102802)
		(width 0.254)
		(layer "F.Cu")
		(net "PVCCFA_EHV_FIVRA_CPU1")
	)
	(segment
		(start 131.846066 -219.228162)
		(end 131.846066 -218.692476)
		(width 0.254)
		(layer "F.Cu")
		(net "PVCCFA_EHV_FIVRA_CPU1")
	)
	(segment
		(start 97.653094 -288.102802)
		(end 97.653348 -288.103056)
		(width 0.254)
		(layer "F.Cu")
		(net "PVCCFA_EHV_FIVRA_CPU1")
	)
	(segment
		(start 99.532694 -284.847284)
		(end 99.532948 -284.847538)
		(width 0.254)
		(layer "F.Cu")
		(net "PVCCFA_EHV_FIVRA_CPU1")
	)
	(segment
		(start 117.388894 -274.54479)
		(end 117.389148 -274.545044)
		(width 0.254)
		(layer "F.Cu")
		(net "PVCCFA_EHV_FIVRA_CPU1")
	)
	(segment
		(start 94.254066 -225.739198)
		(end 94.254066 -225.203512)
		(width 0.254)
		(layer "F.Cu")
		(net "PVCCFA_EHV_FIVRA_CPU1")
	)
	(segment
		(start 129.966466 -215.437212)
		(end 129.966212 -215.436958)
		(width 0.254)
		(layer "F.Cu")
		(net "PVCCFA_EHV_FIVRA_CPU1")
	)
	(segment
		(start 39.566088 -337.471258)
		(end 40.506396 -337.471258)
		(width 0.508)
		(layer "F.Cu")
		(net "PVCCFA_EHV_FIVRA_CPU1")
	)
	(segment
		(start 133.725666 -222.48368)
		(end 133.725666 -221.94774)
		(width 0.254)
		(layer "F.Cu")
		(net "PVCCFA_EHV_FIVRA_CPU1")
	)
	(segment
		(start 106.111294 -278.336248)
		(end 106.111548 -278.336502)
		(width 0.254)
		(layer "F.Cu")
		(net "PVCCFA_EHV_FIVRA_CPU1")
	)
	(segment
		(start 107.521248 -273.730974)
		(end 107.521248 -274.26666)
		(width 0.254)
		(layer "F.Cu")
		(net "PVCCFA_EHV_FIVRA_CPU1")
	)
	(segment
		(start 51.95443 -337.477608)
		(end 52.894738 -337.477608)
		(width 0.508)
		(layer "F.Cu")
		(net "PVCCFA_EHV_FIVRA_CPU1")
	)
	(segment
		(start 131.846066 -221.947994)
		(end 131.845812 -221.94774)
		(width 0.254)
		(layer "F.Cu")
		(net "PVCCFA_EHV_FIVRA_CPU1")
	)
	(segment
		(start 94.254066 -222.48368)
		(end 94.254066 -221.947994)
		(width 0.254)
		(layer "F.Cu")
		(net "PVCCFA_EHV_FIVRA_CPU1")
	)
	(segment
		(start 120.208294 -277.800562)
		(end 120.208294 -278.336248)
		(width 0.254)
		(layer "F.Cu")
		(net "PVCCFA_EHV_FIVRA_CPU1")
	)
	(segment
		(start 92.374466 -218.692476)
		(end 92.374212 -218.692222)
		(width 0.254)
		(layer "F.Cu")
		(net "PVCCFA_EHV_FIVRA_CPU1")
	)
	(segment
		(start 131.846066 -225.203512)
		(end 131.845812 -225.203258)
		(width 0.254)
		(layer "F.Cu")
		(net "PVCCFA_EHV_FIVRA_CPU1")
	)
	(segment
		(start 135.714994 -283.497782)
		(end 135.714994 -284.033722)
		(width 0.254)
		(layer "F.Cu")
		(net "PVCCFA_EHV_FIVRA_CPU1")
	)
	(segment
		(start 128.086866 -215.972644)
		(end 128.086866 -215.437212)
		(width 0.254)
		(layer "F.Cu")
		(net "PVCCFA_EHV_FIVRA_CPU1")
	)
	(segment
		(start 129.966466 -218.692476)
		(end 129.966212 -218.692222)
		(width 0.254)
		(layer "F.Cu")
		(net "PVCCFA_EHV_FIVRA_CPU1")
	)
	(segment
		(start 98.013266 -222.48368)
		(end 98.013266 -221.947994)
		(width 0.254)
		(layer "F.Cu")
		(net "PVCCFA_EHV_FIVRA_CPU1")
	)
	(segment
		(start 105.641648 -274.26666)
		(end 105.641394 -274.266914)
		(width 0.254)
		(layer "F.Cu")
		(net "PVCCFA_EHV_FIVRA_CPU1")
	)
	(segment
		(start 100.002848 -280.77795)
		(end 100.002594 -280.778204)
		(width 0.254)
		(layer "F.Cu")
		(net "PVCCFA_EHV_FIVRA_CPU1")
	)
	(segment
		(start 99.532694 -284.311598)
		(end 99.532694 -284.847284)
		(width 0.254)
		(layer "F.Cu")
		(net "PVCCFA_EHV_FIVRA_CPU1")
	)
	(segment
		(start 131.846066 -222.48368)
		(end 131.846066 -221.947994)
		(width 0.254)
		(layer "F.Cu")
		(net "PVCCFA_EHV_FIVRA_CPU1")
	)
	(segment
		(start 131.485894 -287.567116)
		(end 131.485894 -288.102802)
		(width 0.254)
		(layer "F.Cu")
		(net "PVCCFA_EHV_FIVRA_CPU1")
	)
	(segment
		(start 102.822248 -276.986492)
		(end 102.822248 -277.521924)
		(width 0.254)
		(layer "F.Cu")
		(net "PVCCFA_EHV_FIVRA_CPU1")
	)
	(segment
		(start 103.291894 -287.567116)
		(end 103.291894 -288.102802)
		(width 0.254)
		(layer "F.Cu")
		(net "PVCCFA_EHV_FIVRA_CPU1")
	)
	(segment
		(start 128.086866 -219.228162)
		(end 128.086866 -218.692476)
		(width 0.254)
		(layer "F.Cu")
		(net "PVCCFA_EHV_FIVRA_CPU1")
	)
	(segment
		(start 131.485894 -288.102802)
		(end 131.486148 -288.103056)
		(width 0.254)
		(layer "F.Cu")
		(net "PVCCFA_EHV_FIVRA_CPU1")
	)
	(segment
		(start 134.305294 -279.96388)
		(end 134.305548 -279.964134)
		(width 0.254)
		(layer "F.Cu")
		(net "PVCCFA_EHV_FIVRA_CPU1")
	)
	(segment
		(start 40.506396 -337.471258)
		(end 41.446704 -337.471258)
		(width 0.508)
		(layer "F.Cu")
		(net "PVCCFA_EHV_FIVRA_CPU1")
	)
	(segment
		(start 133.835648 -283.497782)
		(end 133.835648 -284.033468)
		(width 0.254)
		(layer "F.Cu")
		(net "PVCCFA_EHV_FIVRA_CPU1")
	)
	(segment
		(start 135.605266 -225.739198)
		(end 135.605266 -225.203258)
		(width 0.254)
		(layer "F.Cu")
		(net "PVCCFA_EHV_FIVRA_CPU1")
	)
	(segment
		(start 131.846066 -215.436958)
		(end 131.845812 -215.436704)
		(width 0.381)
		(layer "F.Cu")
		(net "PVCCFA_EHV_FIVRA_CPU1")
	)
	(segment
		(start 96.133666 -225.203512)
		(end 96.133412 -225.203258)
		(width 0.254)
		(layer "F.Cu")
		(net "PVCCFA_EHV_FIVRA_CPU1")
	)
	(segment
		(start 118.328948 -274.545044)
		(end 118.328948 -275.08073)
		(width 0.254)
		(layer "F.Cu")
		(net "PVCCFA_EHV_FIVRA_CPU1")
	)
	(segment
		(start 92.374466 -221.947994)
		(end 92.374212 -221.94774)
		(width 0.254)
		(layer "F.Cu")
		(net "PVCCFA_EHV_FIVRA_CPU1")
	)
	(segment
		(start 91.074494 -279.96388)
		(end 91.074748 -279.964134)
		(width 0.254)
		(layer "F.Cu")
		(net "PVCCFA_EHV_FIVRA_CPU1")
	)
	(segment
		(start 88.615266 -222.48368)
		(end 88.615266 -221.94774)
		(width 0.254)
		(layer "F.Cu")
		(net "PVCCFA_EHV_FIVRA_CPU1")
	)
	(segment
		(start 133.835648 -284.033468)
		(end 133.835394 -284.033722)
		(width 0.254)
		(layer "F.Cu")
		(net "PVCCFA_EHV_FIVRA_CPU1")
	)
	(segment
		(start 85.905594 -287.28924)
		(end 85.905594 -286.7533)
		(width 0.254)
		(layer "F.Cu")
		(net "PVCCFA_EHV_FIVRA_CPU1")
	)
	(segment
		(start 101.412294 -288.102802)
		(end 101.412548 -288.103056)
		(width 0.254)
		(layer "F.Cu")
		(net "PVCCFA_EHV_FIVRA_CPU1")
	)
	(segment
		(start 95.773494 -284.311598)
		(end 95.773494 -284.847284)
		(width 0.254)
		(layer "F.Cu")
		(net "PVCCFA_EHV_FIVRA_CPU1")
	)
	(segment
		(start 91.544902 -280.242518)
		(end 91.544902 -280.77795)
		(width 0.254)
		(layer "F.Cu")
		(net "PVCCFA_EHV_FIVRA_CPU1")
	)
	(segment
		(start 94.254066 -221.947994)
		(end 94.253812 -221.94774)
		(width 0.254)
		(layer "F.Cu")
		(net "PVCCFA_EHV_FIVRA_CPU1")
	)
	(segment
		(start 88.615266 -219.228162)
		(end 88.615266 -218.692222)
		(width 0.254)
		(layer "F.Cu")
		(net "PVCCFA_EHV_FIVRA_CPU1")
	)
	(segment
		(start 133.365494 -288.102802)
		(end 133.365748 -288.103056)
		(width 0.254)
		(layer "F.Cu")
		(net "PVCCFA_EHV_FIVRA_CPU1")
	)
	(segment
		(start 122.087894 -276.172676)
		(end 122.088148 -276.708616)
		(width 0.254)
		(layer "F.Cu")
		(net "PVCCFA_EHV_FIVRA_CPU1")
	)
	(segment
		(start 119.268494 -274.54479)
		(end 119.268748 -274.545044)
		(width 0.254)
		(layer "F.Cu")
		(net "PVCCFA_EHV_FIVRA_CPU1")
	)
	(segment
		(start 96.133666 -221.947994)
		(end 96.133412 -221.94774)
		(width 0.254)
		(layer "F.Cu")
		(net "PVCCFA_EHV_FIVRA_CPU1")
	)
	(segment
		(start 170.965622 -337.477608)
		(end 170.965622 -338.417916)
		(width 0.508)
		(layer "F.Cu")
		(net "PVCCFA_EHV_FIVRA_CPU1")
	)
	(segment
		(start 129.606294 -284.311598)
		(end 129.606548 -284.847538)
		(width 0.254)
		(layer "F.Cu")
		(net "PVCCFA_EHV_FIVRA_CPU1")
	)
	(segment
		(start 117.388894 -279.428194)
		(end 117.389148 -279.964134)
		(width 0.254)
		(layer "F.Cu")
		(net "PVCCFA_EHV_FIVRA_CPU1")
	)
	(segment
		(start 92.014294 -287.567116)
		(end 92.014294 -288.102802)
		(width 0.254)
		(layer "F.Cu")
		(net "PVCCFA_EHV_FIVRA_CPU1")
	)
	(segment
		(start 91.074494 -279.428194)
		(end 91.074494 -279.96388)
		(width 0.254)
		(layer "F.Cu")
		(net "PVCCFA_EHV_FIVRA_CPU1")
	)
	(segment
		(start 107.521248 -274.26666)
		(end 107.520994 -274.266914)
		(width 0.254)
		(layer "F.Cu")
		(net "PVCCFA_EHV_FIVRA_CPU1")
	)
	(segment
		(start 90.494866 -222.48368)
		(end 90.494866 -221.947994)
		(width 0.254)
		(layer "F.Cu")
		(net "PVCCFA_EHV_FIVRA_CPU1")
	)
	(segment
		(start 107.521248 -279.150064)
		(end 107.520994 -279.150318)
		(width 0.254)
		(layer "F.Cu")
		(net "PVCCFA_EHV_FIVRA_CPU1")
	)
	(segment
		(start 45.75683 -337.477608)
		(end 46.697138 -337.477608)
		(width 0.508)
		(layer "F.Cu")
		(net "PVCCFA_EHV_FIVRA_CPU1")
	)
	(segment
		(start 123.967494 -277.800562)
		(end 123.967494 -278.336248)
		(width 0.254)
		(layer "F.Cu")
		(net "PVCCFA_EHV_FIVRA_CPU1")
	)
	(segment
		(start 131.846066 -215.972644)
		(end 131.846066 -215.436958)
		(width 0.381)
		(layer "F.Cu")
		(net "PVCCFA_EHV_FIVRA_CPU1")
	)
	(segment
		(start 102.822248 -277.521924)
		(end 102.821994 -277.522178)
		(width 0.254)
		(layer "F.Cu")
		(net "PVCCFA_EHV_FIVRA_CPU1")
	)
	(via
		(at 101.412548 -275.08073)
		(size 0.4572)
		(drill 0.2032)
		(layers "F.Cu" "B.Cu")
		(net "PVCCFA_EHV_FIVRA_CPU1")
	)
	(via
		(at 94.253812 -218.692222)
		(size 0.4572)
		(drill 0.2032)
		(layers "F.Cu" "B.Cu")
		(net "PVCCFA_EHV_FIVRA_CPU1")
	)
	(via
		(at 117.389148 -279.964134)
		(size 0.4572)
		(drill 0.2032)
		(layers "F.Cu" "B.Cu")
		(net "PVCCFA_EHV_FIVRA_CPU1")
	)
	(via
		(at 39.084758 -341.473282)
		(size 0.508)
		(drill 0.254)
		(layers "F.Cu" "B.Cu")
		(net "PVCCFA_EHV_FIVRA_CPU1")
	)
	(via
		(at 115.039394 -275.8948)
		(size 0.4572)
		(drill 0.2032)
		(layers "F.Cu" "B.Cu")
		(net "PVCCFA_EHV_FIVRA_CPU1")
	)
	(via
		(at 88.724994 -280.778204)
		(size 0.4572)
		(drill 0.2032)
		(layers "F.Cu" "B.Cu")
		(net "PVCCFA_EHV_FIVRA_CPU1")
	)
	(via
		(at 163.664138 -254.79629)
		(size 0.4572)
		(drill 0.2032)
		(layers "F.Cu" "B.Cu")
		(net "PVCCFA_EHV_FIVRA_CPU1")
	)
	(via
		(at 123.967748 -284.847538)
		(size 0.4572)
		(drill 0.2032)
		(layers "F.Cu" "B.Cu")
		(net "PVCCFA_EHV_FIVRA_CPU1")
	)
	(via
		(at 53.740558 -342.743282)
		(size 0.508)
		(drill 0.254)
		(layers "F.Cu" "B.Cu")
		(net "PVCCFA_EHV_FIVRA_CPU1")
	)
	(via
		(at 39.069518 -338.808822)
		(size 0.508)
		(drill 0.254)
		(layers "F.Cu" "B.Cu")
		(net "PVCCFA_EHV_FIVRA_CPU1")
	)
	(via
		(at 183.655716 -338.809584)
		(size 0.508)
		(drill 0.254)
		(layers "F.Cu" "B.Cu")
		(net "PVCCFA_EHV_FIVRA_CPU1")
	)
	(via
		(at 184.938416 -342.619584)
		(size 0.508)
		(drill 0.254)
		(layers "F.Cu" "B.Cu")
		(net "PVCCFA_EHV_FIVRA_CPU1")
	)
	(via
		(at 90.134694 -288.103056)
		(size 0.4572)
		(drill 0.2032)
		(layers "F.Cu" "B.Cu")
		(net "PVCCFA_EHV_FIVRA_CPU1")
	)
	(via
		(at 175.15967 -340.079584)
		(size 0.508)
		(drill 0.254)
		(layers "F.Cu" "B.Cu")
		(net "PVCCFA_EHV_FIVRA_CPU1")
	)
	(via
		(at 184.303416 -338.809584)
		(size 0.508)
		(drill 0.254)
		(layers "F.Cu" "B.Cu")
		(net "PVCCFA_EHV_FIVRA_CPU1")
	)
	(via
		(at 94.253812 -225.203258)
		(size 0.4572)
		(drill 0.2032)
		(layers "F.Cu" "B.Cu")
		(net "PVCCFA_EHV_FIVRA_CPU1")
	)
	(via
		(at 48.762158 -342.108282)
		(size 0.508)
		(drill 0.254)
		(layers "F.Cu" "B.Cu")
		(net "PVCCFA_EHV_FIVRA_CPU1")
	)
	(via
		(at 131.486148 -284.847538)
		(size 0.4572)
		(drill 0.2032)
		(layers "F.Cu" "B.Cu")
		(net "PVCCFA_EHV_FIVRA_CPU1")
	)
	(via
		(at 53.080158 -340.838282)
		(size 0.508)
		(drill 0.254)
		(layers "F.Cu" "B.Cu")
		(net "PVCCFA_EHV_FIVRA_CPU1")
	)
	(via
		(at 64.739774 -253.9111)
		(size 0.4572)
		(drill 0.2032)
		(layers "F.Cu" "B.Cu")
		(net "PVCCFA_EHV_FIVRA_CPU1")
	)
	(via
		(at 162.643058 -254.79629)
		(size 0.4572)
		(drill 0.2032)
		(layers "F.Cu" "B.Cu")
		(net "PVCCFA_EHV_FIVRA_CPU1")
	)
	(via
		(at 178.584098 -341.984584)
		(size 0.508)
		(drill 0.254)
		(layers "F.Cu" "B.Cu")
		(net "PVCCFA_EHV_FIVRA_CPU1")
	)
	(via
		(at 44.063158 -340.838282)
		(size 0.508)
		(drill 0.254)
		(layers "F.Cu" "B.Cu")
		(net "PVCCFA_EHV_FIVRA_CPU1")
	)
	(via
		(at 92.374212 -221.94774)
		(size 0.4572)
		(drill 0.2032)
		(layers "F.Cu" "B.Cu")
		(net "PVCCFA_EHV_FIVRA_CPU1")
	)
	(via
		(at 123.967748 -278.336502)
		(size 0.4572)
		(drill 0.2032)
		(layers "F.Cu" "B.Cu")
		(net "PVCCFA_EHV_FIVRA_CPU1")
	)
	(via
		(at 179.866798 -341.984584)
		(size 0.508)
		(drill 0.254)
		(layers "F.Cu" "B.Cu")
		(net "PVCCFA_EHV_FIVRA_CPU1")
	)
	(via
		(at 183.655716 -342.619584)
		(size 0.508)
		(drill 0.254)
		(layers "F.Cu" "B.Cu")
		(net "PVCCFA_EHV_FIVRA_CPU1")
	)
	(via
		(at 178.584098 -338.809584)
		(size 0.508)
		(drill 0.254)
		(layers "F.Cu" "B.Cu")
		(net "PVCCFA_EHV_FIVRA_CPU1")
	)
	(via
		(at 38.424358 -341.473282)
		(size 0.508)
		(drill 0.254)
		(layers "F.Cu" "B.Cu")
		(net "PVCCFA_EHV_FIVRA_CPU1")
	)
	(via
		(at 179.866798 -340.079584)
		(size 0.508)
		(drill 0.254)
		(layers "F.Cu" "B.Cu")
		(net "PVCCFA_EHV_FIVRA_CPU1")
	)
	(via
		(at 43.410378 -340.165182)
		(size 0.508)
		(drill 0.254)
		(layers "F.Cu" "B.Cu")
		(net "PVCCFA_EHV_FIVRA_CPU1")
	)
	(via
		(at 184.303416 -339.444584)
		(size 0.508)
		(drill 0.254)
		(layers "F.Cu" "B.Cu")
		(net "PVCCFA_EHV_FIVRA_CPU1")
	)
	(via
		(at 48.101758 -342.108282)
		(size 0.508)
		(drill 0.254)
		(layers "F.Cu" "B.Cu")
		(net "PVCCFA_EHV_FIVRA_CPU1")
	)
	(via
		(at 99.892612 -218.692222)
		(size 0.4572)
		(drill 0.2032)
		(layers "F.Cu" "B.Cu")
		(net "PVCCFA_EHV_FIVRA_CPU1")
	)
	(via
		(at 105.908094 -261.32917)
		(size 0.4572)
		(drill 0.2032)
		(layers "F.Cu" "B.Cu")
		(net "PVCCFA_EHV_FIVRA_CPU1")
	)
	(via
		(at 179.219098 -338.809584)
		(size 0.508)
		(drill 0.254)
		(layers "F.Cu" "B.Cu")
		(net "PVCCFA_EHV_FIVRA_CPU1")
	)
	(via
		(at 44.070778 -340.165182)
		(size 0.508)
		(drill 0.254)
		(layers "F.Cu" "B.Cu")
		(net "PVCCFA_EHV_FIVRA_CPU1")
	)
	(via
		(at 178.584098 -339.444584)
		(size 0.508)
		(drill 0.254)
		(layers "F.Cu" "B.Cu")
		(net "PVCCFA_EHV_FIVRA_CPU1")
	)
	(via
		(at 95.773748 -288.103056)
		(size 0.4572)
		(drill 0.2032)
		(layers "F.Cu" "B.Cu")
		(net "PVCCFA_EHV_FIVRA_CPU1")
	)
	(via
		(at 133.725666 -221.94774)
		(size 0.4572)
		(drill 0.2032)
		(layers "F.Cu" "B.Cu")
		(net "PVCCFA_EHV_FIVRA_CPU1")
	)
	(via
		(at 178.584098 -340.714584)
		(size 0.508)
		(drill 0.254)
		(layers "F.Cu" "B.Cu")
		(net "PVCCFA_EHV_FIVRA_CPU1")
	)
	(via
		(at 102.821994 -277.522432)
		(size 0.4572)
		(drill 0.2032)
		(layers "F.Cu" "B.Cu")
		(net "PVCCFA_EHV_FIVRA_CPU1")
	)
	(via
		(at 53.080158 -341.473282)
		(size 0.508)
		(drill 0.254)
		(layers "F.Cu" "B.Cu")
		(net "PVCCFA_EHV_FIVRA_CPU1")
	)
	(via
		(at 179.219098 -342.619584)
		(size 0.508)
		(drill 0.254)
		(layers "F.Cu" "B.Cu")
		(net "PVCCFA_EHV_FIVRA_CPU1")
	)
	(via
		(at 53.080158 -342.743282)
		(size 0.508)
		(drill 0.254)
		(layers "F.Cu" "B.Cu")
		(net "PVCCFA_EHV_FIVRA_CPU1")
	)
	(via
		(at 92.374212 -225.203258)
		(size 0.4572)
		(drill 0.2032)
		(layers "F.Cu" "B.Cu")
		(net "PVCCFA_EHV_FIVRA_CPU1")
	)
	(via
		(at 117.64772 -261.32917)
		(size 0.4572)
		(drill 0.2032)
		(layers "F.Cu" "B.Cu")
		(net "PVCCFA_EHV_FIVRA_CPU1")
	)
	(via
		(at 133.365748 -288.103056)
		(size 0.4572)
		(drill 0.2032)
		(layers "F.Cu" "B.Cu")
		(net "PVCCFA_EHV_FIVRA_CPU1")
	)
	(via
		(at 43.402758 -340.838282)
		(size 0.508)
		(drill 0.254)
		(layers "F.Cu" "B.Cu")
		(net "PVCCFA_EHV_FIVRA_CPU1")
	)
	(via
		(at 88.615266 -221.94774)
		(size 0.4572)
		(drill 0.2032)
		(layers "F.Cu" "B.Cu")
		(net "PVCCFA_EHV_FIVRA_CPU1")
	)
	(via
		(at 119.268748 -275.08073)
		(size 0.4572)
		(drill 0.2032)
		(layers "F.Cu" "B.Cu")
		(net "PVCCFA_EHV_FIVRA_CPU1")
	)
	(via
		(at 39.745158 -342.108282)
		(size 0.508)
		(drill 0.254)
		(layers "F.Cu" "B.Cu")
		(net "PVCCFA_EHV_FIVRA_CPU1")
	)
	(via
		(at 184.303416 -341.349584)
		(size 0.508)
		(drill 0.254)
		(layers "F.Cu" "B.Cu")
		(net "PVCCFA_EHV_FIVRA_CPU1")
	)
	(via
		(at 117.01272 -261.32917)
		(size 0.4572)
		(drill 0.2032)
		(layers "F.Cu" "B.Cu")
		(net "PVCCFA_EHV_FIVRA_CPU1")
	)
	(via
		(at 48.101758 -339.441282)
		(size 0.508)
		(drill 0.254)
		(layers "F.Cu" "B.Cu")
		(net "PVCCFA_EHV_FIVRA_CPU1")
	)
	(via
		(at 173.87697 -341.984584)
		(size 0.508)
		(drill 0.254)
		(layers "F.Cu" "B.Cu")
		(net "PVCCFA_EHV_FIVRA_CPU1")
	)
	(via
		(at 94.253812 -221.94774)
		(size 0.4572)
		(drill 0.2032)
		(layers "F.Cu" "B.Cu")
		(net "PVCCFA_EHV_FIVRA_CPU1")
	)
	(via
		(at 59.408314 -254.649478)
		(size 0.4572)
		(drill 0.2032)
		(layers "F.Cu" "B.Cu")
		(net "PVCCFA_EHV_FIVRA_CPU1")
	)
	(via
		(at 128.086612 -225.203258)
		(size 0.4572)
		(drill 0.2032)
		(layers "F.Cu" "B.Cu")
		(net "PVCCFA_EHV_FIVRA_CPU1")
	)
	(via
		(at 137.594594 -284.033722)
		(size 0.4572)
		(drill 0.2032)
		(layers "F.Cu" "B.Cu")
		(net "PVCCFA_EHV_FIVRA_CPU1")
	)
	(via
		(at 39.084758 -340.838282)
		(size 0.508)
		(drill 0.254)
		(layers "F.Cu" "B.Cu")
		(net "PVCCFA_EHV_FIVRA_CPU1")
	)
	(via
		(at 97.183194 -279.150318)
		(size 0.4572)
		(drill 0.2032)
		(layers "F.Cu" "B.Cu")
		(net "PVCCFA_EHV_FIVRA_CPU1")
	)
	(via
		(at 118.328948 -275.08073)
		(size 0.4572)
		(drill 0.2032)
		(layers "F.Cu" "B.Cu")
		(net "PVCCFA_EHV_FIVRA_CPU1")
	)
	(via
		(at 85.905594 -287.28924)
		(size 0.4572)
		(drill 0.2032)
		(layers "F.Cu" "B.Cu")
		(net "PVCCFA_EHV_FIVRA_CPU1")
	)
	(via
		(at 178.26482 -357.460804)
		(size 0.508)
		(drill 0.254)
		(layers "F.Cu" "B.Cu")
		(net "PVCCFA_EHV_FIVRA_CPU1")
	)
	(via
		(at 44.723558 -339.441282)
		(size 0.508)
		(drill 0.254)
		(layers "F.Cu" "B.Cu")
		(net "PVCCFA_EHV_FIVRA_CPU1")
	)
	(via
		(at 174.52467 -341.984584)
		(size 0.508)
		(drill 0.254)
		(layers "F.Cu" "B.Cu")
		(net "PVCCFA_EHV_FIVRA_CPU1")
	)
	(via
		(at 48.762158 -340.838282)
		(size 0.508)
		(drill 0.254)
		(layers "F.Cu" "B.Cu")
		(net "PVCCFA_EHV_FIVRA_CPU1")
	)
	(via
		(at 92.014548 -288.103056)
		(size 0.4572)
		(drill 0.2032)
		(layers "F.Cu" "B.Cu")
		(net "PVCCFA_EHV_FIVRA_CPU1")
	)
	(via
		(at 169.541698 -338.809584)
		(size 0.508)
		(drill 0.254)
		(layers "F.Cu" "B.Cu")
		(net "PVCCFA_EHV_FIVRA_CPU1")
	)
	(via
		(at 96.713548 -278.336502)
		(size 0.4572)
		(drill 0.2032)
		(layers "F.Cu" "B.Cu")
		(net "PVCCFA_EHV_FIVRA_CPU1")
	)
	(via
		(at 184.303416 -340.079584)
		(size 0.508)
		(drill 0.254)
		(layers "F.Cu" "B.Cu")
		(net "PVCCFA_EHV_FIVRA_CPU1")
	)
	(via
		(at 135.605266 -225.203258)
		(size 0.4572)
		(drill 0.2032)
		(layers "F.Cu" "B.Cu")
		(net "PVCCFA_EHV_FIVRA_CPU1")
	)
	(via
		(at 49.422558 -341.473282)
		(size 0.508)
		(drill 0.254)
		(layers "F.Cu" "B.Cu")
		(net "PVCCFA_EHV_FIVRA_CPU1")
	)
	(via
		(at 53.080158 -339.441282)
		(size 0.508)
		(drill 0.254)
		(layers "F.Cu" "B.Cu")
		(net "PVCCFA_EHV_FIVRA_CPU1")
	)
	(via
		(at 133.725666 -225.203258)
		(size 0.4572)
		(drill 0.2032)
		(layers "F.Cu" "B.Cu")
		(net "PVCCFA_EHV_FIVRA_CPU1")
	)
	(via
		(at 169.541698 -339.444584)
		(size 0.508)
		(drill 0.254)
		(layers "F.Cu" "B.Cu")
		(net "PVCCFA_EHV_FIVRA_CPU1")
	)
	(via
		(at 175.15967 -341.349584)
		(size 0.508)
		(drill 0.254)
		(layers "F.Cu" "B.Cu")
		(net "PVCCFA_EHV_FIVRA_CPU1")
	)
	(via
		(at 170.189398 -341.349584)
		(size 0.508)
		(drill 0.254)
		(layers "F.Cu" "B.Cu")
		(net "PVCCFA_EHV_FIVRA_CPU1")
	)
	(via
		(at 53.748178 -340.172802)
		(size 0.508)
		(drill 0.254)
		(layers "F.Cu" "B.Cu")
		(net "PVCCFA_EHV_FIVRA_CPU1")
	)
	(via
		(at 183.655716 -340.079584)
		(size 0.508)
		(drill 0.254)
		(layers "F.Cu" "B.Cu")
		(net "PVCCFA_EHV_FIVRA_CPU1")
	)
	(via
		(at 53.740558 -338.780882)
		(size 0.508)
		(drill 0.254)
		(layers "F.Cu" "B.Cu")
		(net "PVCCFA_EHV_FIVRA_CPU1")
	)
	(via
		(at 123.967748 -283.219906)
		(size 0.4572)
		(drill 0.2032)
		(layers "F.Cu" "B.Cu")
		(net "PVCCFA_EHV_FIVRA_CPU1")
	)
	(via
		(at 122.088148 -284.847538)
		(size 0.4572)
		(drill 0.2032)
		(layers "F.Cu" "B.Cu")
		(net "PVCCFA_EHV_FIVRA_CPU1")
	)
	(via
		(at 133.365748 -279.964134)
		(size 0.4572)
		(drill 0.2032)
		(layers "F.Cu" "B.Cu")
		(net "PVCCFA_EHV_FIVRA_CPU1")
	)
	(via
		(at 173.87697 -342.619584)
		(size 0.508)
		(drill 0.254)
		(layers "F.Cu" "B.Cu")
		(net "PVCCFA_EHV_FIVRA_CPU1")
	)
	(via
		(at 49.422558 -340.838282)
		(size 0.508)
		(drill 0.254)
		(layers "F.Cu" "B.Cu")
		(net "PVCCFA_EHV_FIVRA_CPU1")
	)
	(via
		(at 175.15967 -339.444584)
		(size 0.508)
		(drill 0.254)
		(layers "F.Cu" "B.Cu")
		(net "PVCCFA_EHV_FIVRA_CPU1")
	)
	(via
		(at 174.52467 -341.349584)
		(size 0.508)
		(drill 0.254)
		(layers "F.Cu" "B.Cu")
		(net "PVCCFA_EHV_FIVRA_CPU1")
	)
	(via
		(at 44.063158 -339.441282)
		(size 0.508)
		(drill 0.254)
		(layers "F.Cu" "B.Cu")
		(net "PVCCFA_EHV_FIVRA_CPU1")
	)
	(via
		(at 98.013012 -225.203258)
		(size 0.4572)
		(drill 0.2032)
		(layers "F.Cu" "B.Cu")
		(net "PVCCFA_EHV_FIVRA_CPU1")
	)
	(via
		(at 178.584098 -342.619584)
		(size 0.508)
		(drill 0.254)
		(layers "F.Cu" "B.Cu")
		(net "PVCCFA_EHV_FIVRA_CPU1")
	)
	(via
		(at 36.852098 -341.16645)
		(size 0.6604)
		(drill 0.3302)
		(layers "F.Cu" "B.Cu")
		(net "PVCCFA_EHV_FIVRA_CPU1")
	)
	(via
		(at 100.002594 -280.778204)
		(size 0.4572)
		(drill 0.2032)
		(layers "F.Cu" "B.Cu")
		(net "PVCCFA_EHV_FIVRA_CPU1")
	)
	(via
		(at 48.101758 -340.838282)
		(size 0.508)
		(drill 0.254)
		(layers "F.Cu" "B.Cu")
		(net "PVCCFA_EHV_FIVRA_CPU1")
	)
	(via
		(at 49.414938 -340.172802)
		(size 0.508)
		(drill 0.254)
		(layers "F.Cu" "B.Cu")
		(net "PVCCFA_EHV_FIVRA_CPU1")
	)
	(via
		(at 53.740558 -341.473282)
		(size 0.508)
		(drill 0.254)
		(layers "F.Cu" "B.Cu")
		(net "PVCCFA_EHV_FIVRA_CPU1")
	)
	(via
		(at 174.52467 -339.444584)
		(size 0.508)
		(drill 0.254)
		(layers "F.Cu" "B.Cu")
		(net "PVCCFA_EHV_FIVRA_CPU1")
	)
	(via
		(at 122.088148 -276.708616)
		(size 0.4572)
		(drill 0.2032)
		(layers "F.Cu" "B.Cu")
		(net "PVCCFA_EHV_FIVRA_CPU1")
	)
	(via
		(at 53.080158 -338.780882)
		(size 0.508)
		(drill 0.254)
		(layers "F.Cu" "B.Cu")
		(net "PVCCFA_EHV_FIVRA_CPU1")
	)
	(via
		(at 179.866798 -338.809584)
		(size 0.508)
		(drill 0.254)
		(layers "F.Cu" "B.Cu")
		(net "PVCCFA_EHV_FIVRA_CPU1")
	)
	(via
		(at 49.422558 -342.743282)
		(size 0.508)
		(drill 0.254)
		(layers "F.Cu" "B.Cu")
		(net "PVCCFA_EHV_FIVRA_CPU1")
	)
	(via
		(at 43.402758 -342.108282)
		(size 0.508)
		(drill 0.254)
		(layers "F.Cu" "B.Cu")
		(net "PVCCFA_EHV_FIVRA_CPU1")
	)
	(via
		(at 39.084758 -340.152482)
		(size 0.508)
		(drill 0.254)
		(layers "F.Cu" "B.Cu")
		(net "PVCCFA_EHV_FIVRA_CPU1")
	)
	(via
		(at 56.740298 -339.42147)
		(size 0.6604)
		(drill 0.3302)
		(layers "F.Cu" "B.Cu")
		(net "PVCCFA_EHV_FIVRA_CPU1")
	)
	(via
		(at 44.731178 -340.165182)
		(size 0.508)
		(drill 0.254)
		(layers "F.Cu" "B.Cu")
		(net "PVCCFA_EHV_FIVRA_CPU1")
	)
	(via
		(at 133.365748 -284.847538)
		(size 0.4572)
		(drill 0.2032)
		(layers "F.Cu" "B.Cu")
		(net "PVCCFA_EHV_FIVRA_CPU1")
	)
	(via
		(at 122.088148 -279.964134)
		(size 0.4572)
		(drill 0.2032)
		(layers "F.Cu" "B.Cu")
		(net "PVCCFA_EHV_FIVRA_CPU1")
	)
	(via
		(at 132.895848 -279.150318)
		(size 0.4572)
		(drill 0.2032)
		(layers "F.Cu" "B.Cu")
		(net "PVCCFA_EHV_FIVRA_CPU1")
	)
	(via
		(at 183.655716 -340.714584)
		(size 0.508)
		(drill 0.254)
		(layers "F.Cu" "B.Cu")
		(net "PVCCFA_EHV_FIVRA_CPU1")
	)
	(via
		(at 165.127178 -254.71755)
		(size 0.4572)
		(drill 0.2032)
		(layers "F.Cu" "B.Cu")
		(net "PVCCFA_EHV_FIVRA_CPU1")
	)
	(via
		(at 175.15967 -340.714584)
		(size 0.508)
		(drill 0.254)
		(layers "F.Cu" "B.Cu")
		(net "PVCCFA_EHV_FIVRA_CPU1")
	)
	(via
		(at 170.189398 -338.809584)
		(size 0.508)
		(drill 0.254)
		(layers "F.Cu" "B.Cu")
		(net "PVCCFA_EHV_FIVRA_CPU1")
	)
	(via
		(at 49.422558 -339.441282)
		(size 0.508)
		(drill 0.254)
		(layers "F.Cu" "B.Cu")
		(net "PVCCFA_EHV_FIVRA_CPU1")
	)
	(via
		(at 102.943406 -239.309656)
		(size 0.4572)
		(drill 0.2032)
		(layers "F.Cu" "B.Cu")
		(net "PVCCFA_EHV_FIVRA_CPU1")
	)
	(via
		(at 162.678618 -254.18669)
		(size 0.4572)
		(drill 0.2032)
		(layers "F.Cu" "B.Cu")
		(net "PVCCFA_EHV_FIVRA_CPU1")
	)
	(via
		(at 39.084758 -342.108282)
		(size 0.508)
		(drill 0.254)
		(layers "F.Cu" "B.Cu")
		(net "PVCCFA_EHV_FIVRA_CPU1")
	)
	(via
		(at 129.606548 -284.847538)
		(size 0.4572)
		(drill 0.2032)
		(layers "F.Cu" "B.Cu")
		(net "PVCCFA_EHV_FIVRA_CPU1")
	)
	(via
		(at 88.255094 -288.103056)
		(size 0.4572)
		(drill 0.2032)
		(layers "F.Cu" "B.Cu")
		(net "PVCCFA_EHV_FIVRA_CPU1")
	)
	(via
		(at 131.845812 -215.436704)
		(size 0.4572)
		(drill 0.2032)
		(layers "F.Cu" "B.Cu")
		(net "PVCCFA_EHV_FIVRA_CPU1")
	)
	(via
		(at 173.87697 -339.444584)
		(size 0.508)
		(drill 0.254)
		(layers "F.Cu" "B.Cu")
		(net "PVCCFA_EHV_FIVRA_CPU1")
	)
	(via
		(at 93.423994 -280.778204)
		(size 0.4572)
		(drill 0.2032)
		(layers "F.Cu" "B.Cu")
		(net "PVCCFA_EHV_FIVRA_CPU1")
	)
	(via
		(at 169.541698 -340.714584)
		(size 0.508)
		(drill 0.254)
		(layers "F.Cu" "B.Cu")
		(net "PVCCFA_EHV_FIVRA_CPU1")
	)
	(via
		(at 179.866798 -341.349584)
		(size 0.508)
		(drill 0.254)
		(layers "F.Cu" "B.Cu")
		(net "PVCCFA_EHV_FIVRA_CPU1")
	)
	(via
		(at 133.835394 -284.033722)
		(size 0.4572)
		(drill 0.2032)
		(layers "F.Cu" "B.Cu")
		(net "PVCCFA_EHV_FIVRA_CPU1")
	)
	(via
		(at 38.424358 -342.108282)
		(size 0.508)
		(drill 0.254)
		(layers "F.Cu" "B.Cu")
		(net "PVCCFA_EHV_FIVRA_CPU1")
	)
	(via
		(at 39.729918 -338.796122)
		(size 0.508)
		(drill 0.254)
		(layers "F.Cu" "B.Cu")
		(net "PVCCFA_EHV_FIVRA_CPU1")
	)
	(via
		(at 179.219098 -339.444584)
		(size 0.508)
		(drill 0.254)
		(layers "F.Cu" "B.Cu")
		(net "PVCCFA_EHV_FIVRA_CPU1")
	)
	(via
		(at 118.28272 -261.32917)
		(size 0.4572)
		(drill 0.2032)
		(layers "F.Cu" "B.Cu")
		(net "PVCCFA_EHV_FIVRA_CPU1")
	)
	(via
		(at 179.219098 -340.079584)
		(size 0.508)
		(drill 0.254)
		(layers "F.Cu" "B.Cu")
		(net "PVCCFA_EHV_FIVRA_CPU1")
	)
	(via
		(at 90.134694 -284.847538)
		(size 0.4572)
		(drill 0.2032)
		(layers "F.Cu" "B.Cu")
		(net "PVCCFA_EHV_FIVRA_CPU1")
	)
	(via
		(at 90.494612 -221.94774)
		(size 0.4572)
		(drill 0.2032)
		(layers "F.Cu" "B.Cu")
		(net "PVCCFA_EHV_FIVRA_CPU1")
	)
	(via
		(at 122.088148 -288.103056)
		(size 0.4572)
		(drill 0.2032)
		(layers "F.Cu" "B.Cu")
		(net "PVCCFA_EHV_FIVRA_CPU1")
	)
	(via
		(at 129.966212 -221.94774)
		(size 0.4572)
		(drill 0.2032)
		(layers "F.Cu" "B.Cu")
		(net "PVCCFA_EHV_FIVRA_CPU1")
	)
	(via
		(at 93.894148 -284.847538)
		(size 0.4572)
		(drill 0.2032)
		(layers "F.Cu" "B.Cu")
		(net "PVCCFA_EHV_FIVRA_CPU1")
	)
	(via
		(at 49.422558 -342.108282)
		(size 0.508)
		(drill 0.254)
		(layers "F.Cu" "B.Cu")
		(net "PVCCFA_EHV_FIVRA_CPU1")
	)
	(via
		(at 179.219098 -341.984584)
		(size 0.508)
		(drill 0.254)
		(layers "F.Cu" "B.Cu")
		(net "PVCCFA_EHV_FIVRA_CPU1")
	)
	(via
		(at 99.892612 -225.203258)
		(size 0.4572)
		(drill 0.2032)
		(layers "F.Cu" "B.Cu")
		(net "PVCCFA_EHV_FIVRA_CPU1")
	)
	(via
		(at 183.655716 -341.349584)
		(size 0.508)
		(drill 0.254)
		(layers "F.Cu" "B.Cu")
		(net "PVCCFA_EHV_FIVRA_CPU1")
	)
	(via
		(at 65.420494 -253.900432)
		(size 0.4572)
		(drill 0.2032)
		(layers "F.Cu" "B.Cu")
		(net "PVCCFA_EHV_FIVRA_CPU1")
	)
	(via
		(at 129.966212 -218.692222)
		(size 0.4572)
		(drill 0.2032)
		(layers "F.Cu" "B.Cu")
		(net "PVCCFA_EHV_FIVRA_CPU1")
	)
	(via
		(at 175.15967 -338.809584)
		(size 0.508)
		(drill 0.254)
		(layers "F.Cu" "B.Cu")
		(net "PVCCFA_EHV_FIVRA_CPU1")
	)
	(via
		(at 44.723558 -342.743282)
		(size 0.508)
		(drill 0.254)
		(layers "F.Cu" "B.Cu")
		(net "PVCCFA_EHV_FIVRA_CPU1")
	)
	(via
		(at 127.726948 -284.847538)
		(size 0.4572)
		(drill 0.2032)
		(layers "F.Cu" "B.Cu")
		(net "PVCCFA_EHV_FIVRA_CPU1")
	)
	(via
		(at 107.520994 -274.266914)
		(size 0.4572)
		(drill 0.2032)
		(layers "F.Cu" "B.Cu")
		(net "PVCCFA_EHV_FIVRA_CPU1")
	)
	(via
		(at 91.074748 -279.964134)
		(size 0.4572)
		(drill 0.2032)
		(layers "F.Cu" "B.Cu")
		(net "PVCCFA_EHV_FIVRA_CPU1")
	)
	(via
		(at 48.762158 -338.780882)
		(size 0.508)
		(drill 0.254)
		(layers "F.Cu" "B.Cu")
		(net "PVCCFA_EHV_FIVRA_CPU1")
	)
	(via
		(at 107.051348 -279.964134)
		(size 0.4572)
		(drill 0.2032)
		(layers "F.Cu" "B.Cu")
		(net "PVCCFA_EHV_FIVRA_CPU1")
	)
	(via
		(at 38.424358 -340.838282)
		(size 0.508)
		(drill 0.254)
		(layers "F.Cu" "B.Cu")
		(net "PVCCFA_EHV_FIVRA_CPU1")
	)
	(via
		(at 179.866798 -340.714584)
		(size 0.508)
		(drill 0.254)
		(layers "F.Cu" "B.Cu")
		(net "PVCCFA_EHV_FIVRA_CPU1")
	)
	(via
		(at 184.938416 -338.809584)
		(size 0.508)
		(drill 0.254)
		(layers "F.Cu" "B.Cu")
		(net "PVCCFA_EHV_FIVRA_CPU1")
	)
	(via
		(at 43.402758 -338.780882)
		(size 0.508)
		(drill 0.254)
		(layers "F.Cu" "B.Cu")
		(net "PVCCFA_EHV_FIVRA_CPU1")
	)
	(via
		(at 53.080158 -342.108282)
		(size 0.508)
		(drill 0.254)
		(layers "F.Cu" "B.Cu")
		(net "PVCCFA_EHV_FIVRA_CPU1")
	)
	(via
		(at 174.52467 -340.079584)
		(size 0.508)
		(drill 0.254)
		(layers "F.Cu" "B.Cu")
		(net "PVCCFA_EHV_FIVRA_CPU1")
	)
	(via
		(at 123.967748 -288.103056)
		(size 0.4572)
		(drill 0.2032)
		(layers "F.Cu" "B.Cu")
		(net "PVCCFA_EHV_FIVRA_CPU1")
	)
	(via
		(at 37.415978 -356.80523)
		(size 0.508)
		(drill 0.254)
		(layers "F.Cu" "B.Cu")
		(net "PVCCFA_EHV_FIVRA_CPU1")
	)
	(via
		(at 39.745158 -341.473282)
		(size 0.508)
		(drill 0.254)
		(layers "F.Cu" "B.Cu")
		(net "PVCCFA_EHV_FIVRA_CPU1")
	)
	(via
		(at 58.138314 -254.649478)
		(size 0.4572)
		(drill 0.2032)
		(layers "F.Cu" "B.Cu")
		(net "PVCCFA_EHV_FIVRA_CPU1")
	)
	(via
		(at 39.745158 -342.743282)
		(size 0.508)
		(drill 0.254)
		(layers "F.Cu" "B.Cu")
		(net "PVCCFA_EHV_FIVRA_CPU1")
	)
	(via
		(at 97.653348 -288.103056)
		(size 0.4572)
		(drill 0.2032)
		(layers "F.Cu" "B.Cu")
		(net "PVCCFA_EHV_FIVRA_CPU1")
	)
	(via
		(at 92.374212 -218.692222)
		(size 0.4572)
		(drill 0.2032)
		(layers "F.Cu" "B.Cu")
		(net "PVCCFA_EHV_FIVRA_CPU1")
	)
	(via
		(at 103.292148 -288.103056)
		(size 0.4572)
		(drill 0.2032)
		(layers "F.Cu" "B.Cu")
		(net "PVCCFA_EHV_FIVRA_CPU1")
	)
	(via
		(at 44.723558 -338.780882)
		(size 0.508)
		(drill 0.254)
		(layers "F.Cu" "B.Cu")
		(net "PVCCFA_EHV_FIVRA_CPU1")
	)
	(via
		(at 103.527606 -239.309656)
		(size 0.4572)
		(drill 0.2032)
		(layers "F.Cu" "B.Cu")
		(net "PVCCFA_EHV_FIVRA_CPU1")
	)
	(via
		(at 184.938416 -340.714584)
		(size 0.508)
		(drill 0.254)
		(layers "F.Cu" "B.Cu")
		(net "PVCCFA_EHV_FIVRA_CPU1")
	)
	(via
		(at 170.189398 -340.079584)
		(size 0.508)
		(drill 0.254)
		(layers "F.Cu" "B.Cu")
		(net "PVCCFA_EHV_FIVRA_CPU1")
	)
	(via
		(at 174.52467 -342.619584)
		(size 0.508)
		(drill 0.254)
		(layers "F.Cu" "B.Cu")
		(net "PVCCFA_EHV_FIVRA_CPU1")
	)
	(via
		(at 104.638094 -261.32917)
		(size 0.4572)
		(drill 0.2032)
		(layers "F.Cu" "B.Cu")
		(net "PVCCFA_EHV_FIVRA_CPU1")
	)
	(via
		(at 169.541698 -341.984584)
		(size 0.508)
		(drill 0.254)
		(layers "F.Cu" "B.Cu")
		(net "PVCCFA_EHV_FIVRA_CPU1")
	)
	(via
		(at 119.7737 -239.306608)
		(size 0.4572)
		(drill 0.2032)
		(layers "F.Cu" "B.Cu")
		(net "PVCCFA_EHV_FIVRA_CPU1")
	)
	(via
		(at 174.52467 -338.809584)
		(size 0.508)
		(drill 0.254)
		(layers "F.Cu" "B.Cu")
		(net "PVCCFA_EHV_FIVRA_CPU1")
	)
	(via
		(at 89.195148 -286.475424)
		(size 0.4572)
		(drill 0.2032)
		(layers "F.Cu" "B.Cu")
		(net "PVCCFA_EHV_FIVRA_CPU1")
	)
	(via
		(at 135.714994 -284.033722)
		(size 0.4572)
		(drill 0.2032)
		(layers "F.Cu" "B.Cu")
		(net "PVCCFA_EHV_FIVRA_CPU1")
	)
	(via
		(at 49.422558 -338.780882)
		(size 0.508)
		(drill 0.254)
		(layers "F.Cu" "B.Cu")
		(net "PVCCFA_EHV_FIVRA_CPU1")
	)
	(via
		(at 96.133412 -218.692222)
		(size 0.4572)
		(drill 0.2032)
		(layers "F.Cu" "B.Cu")
		(net "PVCCFA_EHV_FIVRA_CPU1")
	)
	(via
		(at 53.740558 -342.108282)
		(size 0.508)
		(drill 0.254)
		(layers "F.Cu" "B.Cu")
		(net "PVCCFA_EHV_FIVRA_CPU1")
	)
	(via
		(at 125.847348 -288.103056)
		(size 0.4572)
		(drill 0.2032)
		(layers "F.Cu" "B.Cu")
		(net "PVCCFA_EHV_FIVRA_CPU1")
	)
	(via
		(at 170.189398 -339.444584)
		(size 0.508)
		(drill 0.254)
		(layers "F.Cu" "B.Cu")
		(net "PVCCFA_EHV_FIVRA_CPU1")
	)
	(via
		(at 129.606548 -288.103056)
		(size 0.4572)
		(drill 0.2032)
		(layers "F.Cu" "B.Cu")
		(net "PVCCFA_EHV_FIVRA_CPU1")
	)
	(via
		(at 129.966212 -215.436704)
		(size 0.4572)
		(drill 0.2032)
		(layers "F.Cu" "B.Cu")
		(net "PVCCFA_EHV_FIVRA_CPU1")
	)
	(via
		(at 164.451538 -254.72771)
		(size 0.4572)
		(drill 0.2032)
		(layers "F.Cu" "B.Cu")
		(net "PVCCFA_EHV_FIVRA_CPU1")
	)
	(via
		(at 158.94812 -254.050292)
		(size 0.4572)
		(drill 0.2032)
		(layers "F.Cu" "B.Cu")
		(net "PVCCFA_EHV_FIVRA_CPU1")
	)
	(via
		(at 168.906698 -342.619584)
		(size 0.508)
		(drill 0.254)
		(layers "F.Cu" "B.Cu")
		(net "PVCCFA_EHV_FIVRA_CPU1")
	)
	(via
		(at 39.069518 -339.443822)
		(size 0.508)
		(drill 0.254)
		(layers "F.Cu" "B.Cu")
		(net "PVCCFA_EHV_FIVRA_CPU1")
	)
	(via
		(at 56.806338 -341.35187)
		(size 0.6604)
		(drill 0.3302)
		(layers "F.Cu" "B.Cu")
		(net "PVCCFA_EHV_FIVRA_CPU1")
	)
	(via
		(at 60.043314 -254.649478)
		(size 0.4572)
		(drill 0.2032)
		(layers "F.Cu" "B.Cu")
		(net "PVCCFA_EHV_FIVRA_CPU1")
	)
	(via
		(at 93.893894 -279.964134)
		(size 0.4572)
		(drill 0.2032)
		(layers "F.Cu" "B.Cu")
		(net "PVCCFA_EHV_FIVRA_CPU1")
	)
	(via
		(at 179.866798 -342.619584)
		(size 0.508)
		(drill 0.254)
		(layers "F.Cu" "B.Cu")
		(net "PVCCFA_EHV_FIVRA_CPU1")
	)
	(via
		(at 46.377098 -341.36203)
		(size 0.6604)
		(drill 0.3302)
		(layers "F.Cu" "B.Cu")
		(net "PVCCFA_EHV_FIVRA_CPU1")
	)
	(via
		(at 44.723558 -340.838282)
		(size 0.508)
		(drill 0.254)
		(layers "F.Cu" "B.Cu")
		(net "PVCCFA_EHV_FIVRA_CPU1")
	)
	(via
		(at 129.966212 -225.203258)
		(size 0.4572)
		(drill 0.2032)
		(layers "F.Cu" "B.Cu")
		(net "PVCCFA_EHV_FIVRA_CPU1")
	)
	(via
		(at 179.866798 -339.444584)
		(size 0.508)
		(drill 0.254)
		(layers "F.Cu" "B.Cu")
		(net "PVCCFA_EHV_FIVRA_CPU1")
	)
	(via
		(at 169.541698 -341.349584)
		(size 0.508)
		(drill 0.254)
		(layers "F.Cu" "B.Cu")
		(net "PVCCFA_EHV_FIVRA_CPU1")
	)
	(via
		(at 168.576498 -357.448866)
		(size 0.508)
		(drill 0.254)
		(layers "F.Cu" "B.Cu")
		(net "PVCCFA_EHV_FIVRA_CPU1")
	)
	(via
		(at 178.584098 -341.349584)
		(size 0.508)
		(drill 0.254)
		(layers "F.Cu" "B.Cu")
		(net "PVCCFA_EHV_FIVRA_CPU1")
	)
	(via
		(at 179.219098 -341.349584)
		(size 0.508)
		(drill 0.254)
		(layers "F.Cu" "B.Cu")
		(net "PVCCFA_EHV_FIVRA_CPU1")
	)
	(via
		(at 99.532948 -284.847538)
		(size 0.4572)
		(drill 0.2032)
		(layers "F.Cu" "B.Cu")
		(net "PVCCFA_EHV_FIVRA_CPU1")
	)
	(via
		(at 48.101758 -341.473282)
		(size 0.508)
		(drill 0.254)
		(layers "F.Cu" "B.Cu")
		(net "PVCCFA_EHV_FIVRA_CPU1")
	)
	(via
		(at 48.101758 -338.780882)
		(size 0.508)
		(drill 0.254)
		(layers "F.Cu" "B.Cu")
		(net "PVCCFA_EHV_FIVRA_CPU1")
	)
	(via
		(at 104.111806 -239.309656)
		(size 0.4572)
		(drill 0.2032)
		(layers "F.Cu" "B.Cu")
		(net "PVCCFA_EHV_FIVRA_CPU1")
	)
	(via
		(at 54.400958 -338.780882)
		(size 0.508)
		(drill 0.254)
		(layers "F.Cu" "B.Cu")
		(net "PVCCFA_EHV_FIVRA_CPU1")
	)
	(via
		(at 178.584098 -340.079584)
		(size 0.508)
		(drill 0.254)
		(layers "F.Cu" "B.Cu")
		(net "PVCCFA_EHV_FIVRA_CPU1")
	)
	(via
		(at 107.178094 -261.32917)
		(size 0.4572)
		(drill 0.2032)
		(layers "F.Cu" "B.Cu")
		(net "PVCCFA_EHV_FIVRA_CPU1")
	)
	(via
		(at 117.389148 -275.08073)
		(size 0.4572)
		(drill 0.2032)
		(layers "F.Cu" "B.Cu")
		(net "PVCCFA_EHV_FIVRA_CPU1")
	)
	(via
		(at 48.762158 -342.743282)
		(size 0.508)
		(drill 0.254)
		(layers "F.Cu" "B.Cu")
		(net "PVCCFA_EHV_FIVRA_CPU1")
	)
	(via
		(at 184.938416 -339.444584)
		(size 0.508)
		(drill 0.254)
		(layers "F.Cu" "B.Cu")
		(net "PVCCFA_EHV_FIVRA_CPU1")
	)
	(via
		(at 99.532948 -279.964134)
		(size 0.4572)
		(drill 0.2032)
		(layers "F.Cu" "B.Cu")
		(net "PVCCFA_EHV_FIVRA_CPU1")
	)
	(via
		(at 39.745158 -340.838282)
		(size 0.508)
		(drill 0.254)
		(layers "F.Cu" "B.Cu")
		(net "PVCCFA_EHV_FIVRA_CPU1")
	)
	(via
		(at 53.740558 -339.441282)
		(size 0.508)
		(drill 0.254)
		(layers "F.Cu" "B.Cu")
		(net "PVCCFA_EHV_FIVRA_CPU1")
	)
	(via
		(at 99.532948 -288.103056)
		(size 0.4572)
		(drill 0.2032)
		(layers "F.Cu" "B.Cu")
		(net "PVCCFA_EHV_FIVRA_CPU1")
	)
	(via
		(at 105.273094 -261.32917)
		(size 0.4572)
		(drill 0.2032)
		(layers "F.Cu" "B.Cu")
		(net "PVCCFA_EHV_FIVRA_CPU1")
	)
	(via
		(at 105.641394 -274.266914)
		(size 0.4572)
		(drill 0.2032)
		(layers "F.Cu" "B.Cu")
		(net "PVCCFA_EHV_FIVRA_CPU1")
	)
	(via
		(at 120.358154 -239.330484)
		(size 0.4572)
		(drill 0.2032)
		(layers "F.Cu" "B.Cu")
		(net "PVCCFA_EHV_FIVRA_CPU1")
	)
	(via
		(at 184.303416 -340.714584)
		(size 0.508)
		(drill 0.254)
		(layers "F.Cu" "B.Cu")
		(net "PVCCFA_EHV_FIVRA_CPU1")
	)
	(via
		(at 96.133412 -225.203258)
		(size 0.4572)
		(drill 0.2032)
		(layers "F.Cu" "B.Cu")
		(net "PVCCFA_EHV_FIVRA_CPU1")
	)
	(via
		(at 184.303416 -342.619584)
		(size 0.508)
		(drill 0.254)
		(layers "F.Cu" "B.Cu")
		(net "PVCCFA_EHV_FIVRA_CPU1")
	)
	(via
		(at 131.845812 -218.692222)
		(size 0.4572)
		(drill 0.2032)
		(layers "F.Cu" "B.Cu")
		(net "PVCCFA_EHV_FIVRA_CPU1")
	)
	(via
		(at 44.723558 -342.108282)
		(size 0.508)
		(drill 0.254)
		(layers "F.Cu" "B.Cu")
		(net "PVCCFA_EHV_FIVRA_CPU1")
	)
	(via
		(at 158.330138 -253.91491)
		(size 0.4572)
		(drill 0.2032)
		(layers "F.Cu" "B.Cu")
		(net "PVCCFA_EHV_FIVRA_CPU1")
	)
	(via
		(at 127.726948 -283.219906)
		(size 0.4572)
		(drill 0.2032)
		(layers "F.Cu" "B.Cu")
		(net "PVCCFA_EHV_FIVRA_CPU1")
	)
	(via
		(at 44.063158 -342.108282)
		(size 0.508)
		(drill 0.254)
		(layers "F.Cu" "B.Cu")
		(net "PVCCFA_EHV_FIVRA_CPU1")
	)
	(via
		(at 89.664794 -284.033722)
		(size 0.4572)
		(drill 0.2032)
		(layers "F.Cu" "B.Cu")
		(net "PVCCFA_EHV_FIVRA_CPU1")
	)
	(via
		(at 96.133412 -221.94774)
		(size 0.4572)
		(drill 0.2032)
		(layers "F.Cu" "B.Cu")
		(net "PVCCFA_EHV_FIVRA_CPU1")
	)
	(via
		(at 169.541698 -342.619584)
		(size 0.508)
		(drill 0.254)
		(layers "F.Cu" "B.Cu")
		(net "PVCCFA_EHV_FIVRA_CPU1")
	)
	(via
		(at 85.905594 -284.033722)
		(size 0.4572)
		(drill 0.2032)
		(layers "F.Cu" "B.Cu")
		(net "PVCCFA_EHV_FIVRA_CPU1")
	)
	(via
		(at 54.400958 -341.473282)
		(size 0.508)
		(drill 0.254)
		(layers "F.Cu" "B.Cu")
		(net "PVCCFA_EHV_FIVRA_CPU1")
	)
	(via
		(at 170.189398 -342.619584)
		(size 0.508)
		(drill 0.254)
		(layers "F.Cu" "B.Cu")
		(net "PVCCFA_EHV_FIVRA_CPU1")
	)
	(via
		(at 38.409118 -338.808822)
		(size 0.508)
		(drill 0.254)
		(layers "F.Cu" "B.Cu")
		(net "PVCCFA_EHV_FIVRA_CPU1")
	)
	(via
		(at 119.189754 -239.330484)
		(size 0.4572)
		(drill 0.2032)
		(layers "F.Cu" "B.Cu")
		(net "PVCCFA_EHV_FIVRA_CPU1")
	)
	(via
		(at 131.845812 -225.203258)
		(size 0.4572)
		(drill 0.2032)
		(layers "F.Cu" "B.Cu")
		(net "PVCCFA_EHV_FIVRA_CPU1")
	)
	(via
		(at 184.303416 -341.984584)
		(size 0.508)
		(drill 0.254)
		(layers "F.Cu" "B.Cu")
		(net "PVCCFA_EHV_FIVRA_CPU1")
	)
	(via
		(at 129.606548 -279.964134)
		(size 0.4572)
		(drill 0.2032)
		(layers "F.Cu" "B.Cu")
		(net "PVCCFA_EHV_FIVRA_CPU1")
	)
	(via
		(at 95.773748 -284.847538)
		(size 0.4572)
		(drill 0.2032)
		(layers "F.Cu" "B.Cu")
		(net "PVCCFA_EHV_FIVRA_CPU1")
	)
	(via
		(at 168.906698 -339.444584)
		(size 0.508)
		(drill 0.254)
		(layers "F.Cu" "B.Cu")
		(net "PVCCFA_EHV_FIVRA_CPU1")
	)
	(via
		(at 173.87697 -338.809584)
		(size 0.508)
		(drill 0.254)
		(layers "F.Cu" "B.Cu")
		(net "PVCCFA_EHV_FIVRA_CPU1")
	)
	(via
		(at 169.541698 -340.079584)
		(size 0.508)
		(drill 0.254)
		(layers "F.Cu" "B.Cu")
		(net "PVCCFA_EHV_FIVRA_CPU1")
	)
	(via
		(at 54.400958 -340.838282)
		(size 0.508)
		(drill 0.254)
		(layers "F.Cu" "B.Cu")
		(net "PVCCFA_EHV_FIVRA_CPU1")
	)
	(via
		(at 175.15967 -341.984584)
		(size 0.508)
		(drill 0.254)
		(layers "F.Cu" "B.Cu")
		(net "PVCCFA_EHV_FIVRA_CPU1")
	)
	(via
		(at 54.400958 -339.441282)
		(size 0.508)
		(drill 0.254)
		(layers "F.Cu" "B.Cu")
		(net "PVCCFA_EHV_FIVRA_CPU1")
	)
	(via
		(at 173.87697 -340.714584)
		(size 0.508)
		(drill 0.254)
		(layers "F.Cu" "B.Cu")
		(net "PVCCFA_EHV_FIVRA_CPU1")
	)
	(via
		(at 48.094138 -340.172802)
		(size 0.508)
		(drill 0.254)
		(layers "F.Cu" "B.Cu")
		(net "PVCCFA_EHV_FIVRA_CPU1")
	)
	(via
		(at 43.402758 -339.441282)
		(size 0.508)
		(drill 0.254)
		(layers "F.Cu" "B.Cu")
		(net "PVCCFA_EHV_FIVRA_CPU1")
	)
	(via
		(at 38.424358 -342.743282)
		(size 0.508)
		(drill 0.254)
		(layers "F.Cu" "B.Cu")
		(net "PVCCFA_EHV_FIVRA_CPU1")
	)
	(via
		(at 61.092334 -254.10033)
		(size 0.4572)
		(drill 0.2032)
		(layers "F.Cu" "B.Cu")
		(net "PVCCFA_EHV_FIVRA_CPU1")
	)
	(via
		(at 93.894148 -288.103056)
		(size 0.4572)
		(drill 0.2032)
		(layers "F.Cu" "B.Cu")
		(net "PVCCFA_EHV_FIVRA_CPU1")
	)
	(via
		(at 101.412548 -288.103056)
		(size 0.4572)
		(drill 0.2032)
		(layers "F.Cu" "B.Cu")
		(net "PVCCFA_EHV_FIVRA_CPU1")
	)
	(via
		(at 47.805594 -357.299514)
		(size 0.508)
		(drill 0.254)
		(layers "F.Cu" "B.Cu")
		(net "PVCCFA_EHV_FIVRA_CPU1")
	)
	(via
		(at 106.111548 -278.336502)
		(size 0.4572)
		(drill 0.2032)
		(layers "F.Cu" "B.Cu")
		(net "PVCCFA_EHV_FIVRA_CPU1")
	)
	(via
		(at 44.063158 -342.743282)
		(size 0.508)
		(drill 0.254)
		(layers "F.Cu" "B.Cu")
		(net "PVCCFA_EHV_FIVRA_CPU1")
	)
	(via
		(at 99.892612 -221.94774)
		(size 0.4572)
		(drill 0.2032)
		(layers "F.Cu" "B.Cu")
		(net "PVCCFA_EHV_FIVRA_CPU1")
	)
	(via
		(at 43.402758 -341.473282)
		(size 0.508)
		(drill 0.254)
		(layers "F.Cu" "B.Cu")
		(net "PVCCFA_EHV_FIVRA_CPU1")
	)
	(via
		(at 48.762158 -339.441282)
		(size 0.508)
		(drill 0.254)
		(layers "F.Cu" "B.Cu")
		(net "PVCCFA_EHV_FIVRA_CPU1")
	)
	(via
		(at 38.424358 -340.152482)
		(size 0.508)
		(drill 0.254)
		(layers "F.Cu" "B.Cu")
		(net "PVCCFA_EHV_FIVRA_CPU1")
	)
	(via
		(at 44.063158 -341.473282)
		(size 0.508)
		(drill 0.254)
		(layers "F.Cu" "B.Cu")
		(net "PVCCFA_EHV_FIVRA_CPU1")
	)
	(via
		(at 101.772212 -225.203258)
		(size 0.4572)
		(drill 0.2032)
		(layers "F.Cu" "B.Cu")
		(net "PVCCFA_EHV_FIVRA_CPU1")
	)
	(via
		(at 164.438838 -254.03429)
		(size 0.4572)
		(drill 0.2032)
		(layers "F.Cu" "B.Cu")
		(net "PVCCFA_EHV_FIVRA_CPU1")
	)
	(via
		(at 118.798594 -279.150318)
		(size 0.4572)
		(drill 0.2032)
		(layers "F.Cu" "B.Cu")
		(net "PVCCFA_EHV_FIVRA_CPU1")
	)
	(via
		(at 133.725666 -218.692222)
		(size 0.4572)
		(drill 0.2032)
		(layers "F.Cu" "B.Cu")
		(net "PVCCFA_EHV_FIVRA_CPU1")
	)
	(via
		(at 38.409118 -339.443822)
		(size 0.508)
		(drill 0.254)
		(layers "F.Cu" "B.Cu")
		(net "PVCCFA_EHV_FIVRA_CPU1")
	)
	(via
		(at 131.845812 -221.94774)
		(size 0.4572)
		(drill 0.2032)
		(layers "F.Cu" "B.Cu")
		(net "PVCCFA_EHV_FIVRA_CPU1")
	)
	(via
		(at 60.411614 -254.110998)
		(size 0.4572)
		(drill 0.2032)
		(layers "F.Cu" "B.Cu")
		(net "PVCCFA_EHV_FIVRA_CPU1")
	)
	(via
		(at 168.906698 -340.714584)
		(size 0.508)
		(drill 0.254)
		(layers "F.Cu" "B.Cu")
		(net "PVCCFA_EHV_FIVRA_CPU1")
	)
	(via
		(at 173.87697 -341.349584)
		(size 0.508)
		(drill 0.254)
		(layers "F.Cu" "B.Cu")
		(net "PVCCFA_EHV_FIVRA_CPU1")
	)
	(via
		(at 131.486148 -288.103056)
		(size 0.4572)
		(drill 0.2032)
		(layers "F.Cu" "B.Cu")
		(net "PVCCFA_EHV_FIVRA_CPU1")
	)
	(via
		(at 116.37772 -261.32917)
		(size 0.4572)
		(drill 0.2032)
		(layers "F.Cu" "B.Cu")
		(net "PVCCFA_EHV_FIVRA_CPU1")
	)
	(via
		(at 48.101758 -342.743282)
		(size 0.508)
		(drill 0.254)
		(layers "F.Cu" "B.Cu")
		(net "PVCCFA_EHV_FIVRA_CPU1")
	)
	(via
		(at 120.208548 -278.336502)
		(size 0.4572)
		(drill 0.2032)
		(layers "F.Cu" "B.Cu")
		(net "PVCCFA_EHV_FIVRA_CPU1")
	)
	(via
		(at 183.655716 -341.984584)
		(size 0.508)
		(drill 0.254)
		(layers "F.Cu" "B.Cu")
		(net "PVCCFA_EHV_FIVRA_CPU1")
	)
	(via
		(at 128.086612 -218.692222)
		(size 0.4572)
		(drill 0.2032)
		(layers "F.Cu" "B.Cu")
		(net "PVCCFA_EHV_FIVRA_CPU1")
	)
	(via
		(at 170.189398 -340.714584)
		(size 0.508)
		(drill 0.254)
		(layers "F.Cu" "B.Cu")
		(net "PVCCFA_EHV_FIVRA_CPU1")
	)
	(via
		(at 53.087778 -340.172802)
		(size 0.508)
		(drill 0.254)
		(layers "F.Cu" "B.Cu")
		(net "PVCCFA_EHV_FIVRA_CPU1")
	)
	(via
		(at 44.723558 -341.473282)
		(size 0.508)
		(drill 0.254)
		(layers "F.Cu" "B.Cu")
		(net "PVCCFA_EHV_FIVRA_CPU1")
	)
	(via
		(at 128.086612 -215.436704)
		(size 0.4572)
		(drill 0.2032)
		(layers "F.Cu" "B.Cu")
		(net "PVCCFA_EHV_FIVRA_CPU1")
	)
	(via
		(at 168.906698 -341.349584)
		(size 0.508)
		(drill 0.254)
		(layers "F.Cu" "B.Cu")
		(net "PVCCFA_EHV_FIVRA_CPU1")
	)
	(via
		(at 128.086612 -221.94774)
		(size 0.4572)
		(drill 0.2032)
		(layers "F.Cu" "B.Cu")
		(net "PVCCFA_EHV_FIVRA_CPU1")
	)
	(via
		(at 39.084758 -342.743282)
		(size 0.508)
		(drill 0.254)
		(layers "F.Cu" "B.Cu")
		(net "PVCCFA_EHV_FIVRA_CPU1")
	)
	(via
		(at 184.938416 -341.349584)
		(size 0.508)
		(drill 0.254)
		(layers "F.Cu" "B.Cu")
		(net "PVCCFA_EHV_FIVRA_CPU1")
	)
	(via
		(at 107.520994 -279.150318)
		(size 0.4572)
		(drill 0.2032)
		(layers "F.Cu" "B.Cu")
		(net "PVCCFA_EHV_FIVRA_CPU1")
	)
	(via
		(at 88.615266 -218.692222)
		(size 0.4572)
		(drill 0.2032)
		(layers "F.Cu" "B.Cu")
		(net "PVCCFA_EHV_FIVRA_CPU1")
	)
	(via
		(at 44.063158 -338.780882)
		(size 0.508)
		(drill 0.254)
		(layers "F.Cu" "B.Cu")
		(net "PVCCFA_EHV_FIVRA_CPU1")
	)
	(via
		(at 39.729918 -339.431122)
		(size 0.508)
		(drill 0.254)
		(layers "F.Cu" "B.Cu")
		(net "PVCCFA_EHV_FIVRA_CPU1")
	)
	(via
		(at 134.305548 -279.964134)
		(size 0.4572)
		(drill 0.2032)
		(layers "F.Cu" "B.Cu")
		(net "PVCCFA_EHV_FIVRA_CPU1")
	)
	(via
		(at 54.408578 -340.172802)
		(size 0.508)
		(drill 0.254)
		(layers "F.Cu" "B.Cu")
		(net "PVCCFA_EHV_FIVRA_CPU1")
	)
	(via
		(at 175.15967 -342.619584)
		(size 0.508)
		(drill 0.254)
		(layers "F.Cu" "B.Cu")
		(net "PVCCFA_EHV_FIVRA_CPU1")
	)
	(via
		(at 54.400958 -342.108282)
		(size 0.508)
		(drill 0.254)
		(layers "F.Cu" "B.Cu")
		(net "PVCCFA_EHV_FIVRA_CPU1")
	)
	(via
		(at 184.938416 -340.079584)
		(size 0.508)
		(drill 0.254)
		(layers "F.Cu" "B.Cu")
		(net "PVCCFA_EHV_FIVRA_CPU1")
	)
	(via
		(at 173.87697 -340.079584)
		(size 0.508)
		(drill 0.254)
		(layers "F.Cu" "B.Cu")
		(net "PVCCFA_EHV_FIVRA_CPU1")
	)
	(via
		(at 168.906698 -340.079584)
		(size 0.508)
		(drill 0.254)
		(layers "F.Cu" "B.Cu")
		(net "PVCCFA_EHV_FIVRA_CPU1")
	)
	(via
		(at 43.402758 -342.743282)
		(size 0.508)
		(drill 0.254)
		(layers "F.Cu" "B.Cu")
		(net "PVCCFA_EHV_FIVRA_CPU1")
	)
	(via
		(at 183.655716 -339.444584)
		(size 0.508)
		(drill 0.254)
		(layers "F.Cu" "B.Cu")
		(net "PVCCFA_EHV_FIVRA_CPU1")
	)
	(via
		(at 170.189398 -341.984584)
		(size 0.508)
		(drill 0.254)
		(layers "F.Cu" "B.Cu")
		(net "PVCCFA_EHV_FIVRA_CPU1")
	)
	(via
		(at 39.745158 -340.152482)
		(size 0.508)
		(drill 0.254)
		(layers "F.Cu" "B.Cu")
		(net "PVCCFA_EHV_FIVRA_CPU1")
	)
	(via
		(at 48.754538 -340.172802)
		(size 0.508)
		(drill 0.254)
		(layers "F.Cu" "B.Cu")
		(net "PVCCFA_EHV_FIVRA_CPU1")
	)
	(via
		(at 54.400958 -342.743282)
		(size 0.508)
		(drill 0.254)
		(layers "F.Cu" "B.Cu")
		(net "PVCCFA_EHV_FIVRA_CPU1")
	)
	(via
		(at 134.775194 -280.778204)
		(size 0.4572)
		(drill 0.2032)
		(layers "F.Cu" "B.Cu")
		(net "PVCCFA_EHV_FIVRA_CPU1")
	)
	(via
		(at 179.219098 -340.714584)
		(size 0.508)
		(drill 0.254)
		(layers "F.Cu" "B.Cu")
		(net "PVCCFA_EHV_FIVRA_CPU1")
	)
	(via
		(at 168.906698 -341.984584)
		(size 0.508)
		(drill 0.254)
		(layers "F.Cu" "B.Cu")
		(net "PVCCFA_EHV_FIVRA_CPU1")
	)
	(via
		(at 98.013012 -218.692222)
		(size 0.4572)
		(drill 0.2032)
		(layers "F.Cu" "B.Cu")
		(net "PVCCFA_EHV_FIVRA_CPU1")
	)
	(via
		(at 168.906698 -338.809584)
		(size 0.508)
		(drill 0.254)
		(layers "F.Cu" "B.Cu")
		(net "PVCCFA_EHV_FIVRA_CPU1")
	)
	(via
		(at 92.014294 -284.847538)
		(size 0.4572)
		(drill 0.2032)
		(layers "F.Cu" "B.Cu")
		(net "PVCCFA_EHV_FIVRA_CPU1")
	)
	(via
		(at 127.726948 -288.103056)
		(size 0.4572)
		(drill 0.2032)
		(layers "F.Cu" "B.Cu")
		(net "PVCCFA_EHV_FIVRA_CPU1")
	)
	(via
		(at 90.494612 -218.692222)
		(size 0.4572)
		(drill 0.2032)
		(layers "F.Cu" "B.Cu")
		(net "PVCCFA_EHV_FIVRA_CPU1")
	)
	(via
		(at 120.208548 -284.847538)
		(size 0.4572)
		(drill 0.2032)
		(layers "F.Cu" "B.Cu")
		(net "PVCCFA_EHV_FIVRA_CPU1")
	)
	(via
		(at 98.013012 -221.94774)
		(size 0.4572)
		(drill 0.2032)
		(layers "F.Cu" "B.Cu")
		(net "PVCCFA_EHV_FIVRA_CPU1")
	)
	(via
		(at 48.762158 -341.473282)
		(size 0.508)
		(drill 0.254)
		(layers "F.Cu" "B.Cu")
		(net "PVCCFA_EHV_FIVRA_CPU1")
	)
	(via
		(at 106.543094 -261.32917)
		(size 0.4572)
		(drill 0.2032)
		(layers "F.Cu" "B.Cu")
		(net "PVCCFA_EHV_FIVRA_CPU1")
	)
	(via
		(at 53.740558 -340.838282)
		(size 0.508)
		(drill 0.254)
		(layers "F.Cu" "B.Cu")
		(net "PVCCFA_EHV_FIVRA_CPU1")
	)
	(via
		(at 91.544648 -280.778204)
		(size 0.4572)
		(drill 0.2032)
		(layers "F.Cu" "B.Cu")
		(net "PVCCFA_EHV_FIVRA_CPU1")
	)
	(via
		(at 184.938416 -341.984584)
		(size 0.508)
		(drill 0.254)
		(layers "F.Cu" "B.Cu")
		(net "PVCCFA_EHV_FIVRA_CPU1")
	)
	(via
		(at 58.773314 -254.649478)
		(size 0.4572)
		(drill 0.2032)
		(layers "F.Cu" "B.Cu")
		(net "PVCCFA_EHV_FIVRA_CPU1")
	)
	(via
		(at 97.653348 -284.847538)
		(size 0.4572)
		(drill 0.2032)
		(layers "F.Cu" "B.Cu")
		(net "PVCCFA_EHV_FIVRA_CPU1")
	)
	(via
		(at 174.52467 -340.714584)
		(size 0.508)
		(drill 0.254)
		(layers "F.Cu" "B.Cu")
		(net "PVCCFA_EHV_FIVRA_CPU1")
	)
	(arc
		(start 101.412294 -274.54479)
		(mid 101.412357 -274.81276)
		(end 101.412548 -275.08073)
		(width 0.254)
		(layer "F.Cu")
		(net "PVCCFA_EHV_FIVRA_CPU1")
	)
	(segment
		(start 37.415978 -357.29418)
		(end 37.415978 -356.80523)
		(width 0.381)
		(layer "B.Cu")
		(net "PVCCFA_EHV_FIVRA_CPU1")
	)
	(segment
		(start 48.506634 -358.32923)
		(end 48.368204 -358.1908)
		(width 0.254)
		(layer "B.Cu")
		(net "PVCCFA_EHV_FIVRA_CPU1")
	)
	(segment
		(start 178.26482 -356.81158)
		(end 178.26482 -357.460804)
		(width 0.254)
		(layer "B.Cu")
		(net "PVCCFA_EHV_FIVRA_CPU1")
	)
	(segment
		(start 46.697138 -337.477608)
		(end 46.697138 -338.417916)
		(width 0.508)
		(layer "B.Cu")
		(net "PVCCFA_EHV_FIVRA_CPU1")
	)
	(segment
		(start 170.965622 -337.477608)
		(end 171.90593 -337.477608)
		(width 0.508)
		(layer "B.Cu")
		(net "PVCCFA_EHV_FIVRA_CPU1")
	)
	(segment
		(start 46.697138 -337.477608)
		(end 47.637446 -337.477608)
		(width 0.508)
		(layer "B.Cu")
		(net "PVCCFA_EHV_FIVRA_CPU1")
	)
	(segment
		(start 170.025314 -337.477608)
		(end 170.965622 -337.477608)
		(width 0.508)
		(layer "B.Cu")
		(net "PVCCFA_EHV_FIVRA_CPU1")
	)
	(segment
		(start 52.894738 -337.477608)
		(end 52.894738 -338.417916)
		(width 0.508)
		(layer "B.Cu")
		(net "PVCCFA_EHV_FIVRA_CPU1")
	)
	(segment
		(start 168.576498 -357.26497)
		(end 168.576498 -357.448866)
		(width 0.381)
		(layer "B.Cu")
		(net "PVCCFA_EHV_FIVRA_CPU1")
	)
	(segment
		(start 177.156364 -337.483958)
		(end 178.096672 -337.483958)
		(width 0.508)
		(layer "B.Cu")
		(net "PVCCFA_EHV_FIVRA_CPU1")
	)
	(segment
		(start 52.894738 -337.477608)
		(end 53.835046 -337.477608)
		(width 0.508)
		(layer "B.Cu")
		(net "PVCCFA_EHV_FIVRA_CPU1")
	)
	(segment
		(start 47.805594 -357.713534)
		(end 47.805594 -357.299514)
		(width 0.254)
		(layer "B.Cu")
		(net "PVCCFA_EHV_FIVRA_CPU1")
	)
	(segment
		(start 48.28286 -358.1908)
		(end 47.805594 -357.713534)
		(width 0.254)
		(layer "B.Cu")
		(net "PVCCFA_EHV_FIVRA_CPU1")
	)
	(segment
		(start 45.75683 -337.477608)
		(end 46.697138 -337.477608)
		(width 0.508)
		(layer "B.Cu")
		(net "PVCCFA_EHV_FIVRA_CPU1")
	)
	(segment
		(start 170.965622 -337.477608)
		(end 170.965622 -338.417916)
		(width 0.508)
		(layer "B.Cu")
		(net "PVCCFA_EHV_FIVRA_CPU1")
	)
	(segment
		(start 40.506396 -337.471258)
		(end 41.446704 -337.471258)
		(width 0.508)
		(layer "B.Cu")
		(net "PVCCFA_EHV_FIVRA_CPU1")
	)
	(segment
		(start 37.69741 -357.575612)
		(end 37.415978 -357.29418)
		(width 0.381)
		(layer "B.Cu")
		(net "PVCCFA_EHV_FIVRA_CPU1")
	)
	(segment
		(start 183.353964 -337.483958)
		(end 184.294272 -337.483958)
		(width 0.508)
		(layer "B.Cu")
		(net "PVCCFA_EHV_FIVRA_CPU1")
	)
	(segment
		(start 48.368204 -358.1908)
		(end 48.28286 -358.1908)
		(width 0.254)
		(layer "B.Cu")
		(net "PVCCFA_EHV_FIVRA_CPU1")
	)
	(segment
		(start 177.156364 -337.483958)
		(end 177.156364 -338.424266)
		(width 0.508)
		(layer "B.Cu")
		(net "PVCCFA_EHV_FIVRA_CPU1")
	)
	(segment
		(start 51.95443 -337.477608)
		(end 52.894738 -337.477608)
		(width 0.508)
		(layer "B.Cu")
		(net "PVCCFA_EHV_FIVRA_CPU1")
	)
	(segment
		(start 176.216056 -337.483958)
		(end 177.156364 -337.483958)
		(width 0.508)
		(layer "B.Cu")
		(net "PVCCFA_EHV_FIVRA_CPU1")
	)
	(segment
		(start 168.133268 -356.82174)
		(end 168.576498 -357.26497)
		(width 0.381)
		(layer "B.Cu")
		(net "PVCCFA_EHV_FIVRA_CPU1")
	)
	(segment
		(start 40.506396 -337.471258)
		(end 40.506396 -338.411566)
		(width 0.508)
		(layer "B.Cu")
		(net "PVCCFA_EHV_FIVRA_CPU1")
	)
	(segment
		(start 182.413656 -337.483958)
		(end 183.353964 -337.483958)
		(width 0.508)
		(layer "B.Cu")
		(net "PVCCFA_EHV_FIVRA_CPU1")
	)
	(segment
		(start 39.566088 -337.471258)
		(end 40.506396 -337.471258)
		(width 0.508)
		(layer "B.Cu")
		(net "PVCCFA_EHV_FIVRA_CPU1")
	)
	(segment
		(start 183.353964 -337.483958)
		(end 183.353964 -338.424266)
		(width 0.508)
		(layer "B.Cu")
		(net "PVCCFA_EHV_FIVRA_CPU1")
	)
	(segment
		(start 37.415978 -356.80523)
		(end 37.030406 -356.419658)
		(width 0.381)
		(layer "In2.Cu")
		(net "PVCCFA_EHV_FIVRA_CPU1")
	)
	(segment
		(start 179.4256 -354.955602)
		(end 179.4256 -353.103434)
		(width 0.381)
		(layer "In2.Cu")
		(net "PVCCFA_EHV_FIVRA_CPU1")
	)
	(segment
		(start 90.134694 -284.847538)
		(end 89.770204 -284.483048)
		(width 0.254)
		(layer "In2.Cu")
		(net "PVCCFA_EHV_FIVRA_CPU1")
	)
	(segment
		(start 47.51832 -357.01224)
		(end 47.51832 -356.319074)
		(width 0.381)
		(layer "In2.Cu")
		(net "PVCCFA_EHV_FIVRA_CPU1")
	)
	(segment
		(start 178.991514 -347.803216)
		(end 178.584098 -347.3958)
		(width 0.381)
		(layer "In2.Cu")
		(net "PVCCFA_EHV_FIVRA_CPU1")
	)
	(segment
		(start 120.208548 -284.847538)
		(end 120.208548 -284.037786)
		(width 0.254)
		(layer "In2.Cu")
		(net "PVCCFA_EHV_FIVRA_CPU1")
	)
	(segment
		(start 131.486148 -284.847538)
		(end 131.486148 -284.037786)
		(width 0.254)
		(layer "In2.Cu")
		(net "PVCCFA_EHV_FIVRA_CPU1")
	)
	(segment
		(start 47.591218 -346.855796)
		(end 47.591218 -343.253822)
		(width 0.381)
		(layer "In2.Cu")
		(net "PVCCFA_EHV_FIVRA_CPU1")
	)
	(segment
		(start 37.030406 -356.419658)
		(end 37.030406 -344.137234)
		(width 0.381)
		(layer "In2.Cu")
		(net "PVCCFA_EHV_FIVRA_CPU1")
	)
	(segment
		(start 48.878998 -353.35591)
		(end 48.564038 -353.04095)
		(width 0.381)
		(layer "In2.Cu")
		(net "PVCCFA_EHV_FIVRA_CPU1")
	)
	(segment
		(start 127.726948 -284.847538)
		(end 127.726948 -284.037786)
		(width 0.254)
		(layer "In2.Cu")
		(net "PVCCFA_EHV_FIVRA_CPU1")
	)
	(segment
		(start 48.878998 -354.958396)
		(end 48.878998 -353.35591)
		(width 0.381)
		(layer "In2.Cu")
		(net "PVCCFA_EHV_FIVRA_CPU1")
	)
	(segment
		(start 167.4876 -356.359968)
		(end 168.576498 -357.448866)
		(width 0.381)
		(layer "In2.Cu")
		(net "PVCCFA_EHV_FIVRA_CPU1")
	)
	(segment
		(start 178.991514 -352.669348)
		(end 178.991514 -347.803216)
		(width 0.381)
		(layer "In2.Cu")
		(net "PVCCFA_EHV_FIVRA_CPU1")
	)
	(segment
		(start 168.906698 -345.464892)
		(end 167.4876 -346.88399)
		(width 0.381)
		(layer "In2.Cu")
		(net "PVCCFA_EHV_FIVRA_CPU1")
	)
	(segment
		(start 179.4256 -353.103434)
		(end 178.991514 -352.669348)
		(width 0.381)
		(layer "In2.Cu")
		(net "PVCCFA_EHV_FIVRA_CPU1")
	)
	(segment
		(start 88.649048 -221.301564)
		(end 88.649048 -221.913958)
		(width 0.254)
		(layer "In2.Cu")
		(net "PVCCFA_EHV_FIVRA_CPU1")
	)
	(segment
		(start 168.906698 -342.619584)
		(end 168.906698 -345.464892)
		(width 0.381)
		(layer "In2.Cu")
		(net "PVCCFA_EHV_FIVRA_CPU1")
	)
	(segment
		(start 167.4876 -346.88399)
		(end 167.4876 -356.359968)
		(width 0.381)
		(layer "In2.Cu")
		(net "PVCCFA_EHV_FIVRA_CPU1")
	)
	(segment
		(start 88.649048 -221.913958)
		(end 88.615266 -221.94774)
		(width 0.254)
		(layer "In2.Cu")
		(net "PVCCFA_EHV_FIVRA_CPU1")
	)
	(segment
		(start 178.584098 -347.3958)
		(end 178.584098 -342.619584)
		(width 0.381)
		(layer "In2.Cu")
		(net "PVCCFA_EHV_FIVRA_CPU1")
	)
	(segment
		(start 177.9016 -356.479602)
		(end 179.4256 -354.955602)
		(width 0.381)
		(layer "In2.Cu")
		(net "PVCCFA_EHV_FIVRA_CPU1")
	)
	(segment
		(start 37.030406 -344.137234)
		(end 38.424358 -342.743282)
		(width 0.381)
		(layer "In2.Cu")
		(net "PVCCFA_EHV_FIVRA_CPU1")
	)
	(segment
		(start 95.773748 -284.847538)
		(end 95.773748 -284.037786)
		(width 0.254)
		(layer "In2.Cu")
		(net "PVCCFA_EHV_FIVRA_CPU1")
	)
	(segment
		(start 123.967748 -284.847538)
		(end 123.967748 -284.037786)
		(width 0.254)
		(layer "In2.Cu")
		(net "PVCCFA_EHV_FIVRA_CPU1")
	)
	(segment
		(start 47.805594 -357.299514)
		(end 47.51832 -357.01224)
		(width 0.381)
		(layer "In2.Cu")
		(net "PVCCFA_EHV_FIVRA_CPU1")
	)
	(segment
		(start 93.894148 -284.847538)
		(end 93.894148 -284.037786)
		(width 0.254)
		(layer "In2.Cu")
		(net "PVCCFA_EHV_FIVRA_CPU1")
	)
	(segment
		(start 99.532948 -284.847538)
		(end 99.532948 -284.037786)
		(width 0.254)
		(layer "In2.Cu")
		(net "PVCCFA_EHV_FIVRA_CPU1")
	)
	(segment
		(start 47.51832 -356.319074)
		(end 48.878998 -354.958396)
		(width 0.381)
		(layer "In2.Cu")
		(net "PVCCFA_EHV_FIVRA_CPU1")
	)
	(segment
		(start 97.653348 -284.847538)
		(end 97.653348 -284.037786)
		(width 0.254)
		(layer "In2.Cu")
		(net "PVCCFA_EHV_FIVRA_CPU1")
	)
	(segment
		(start 48.564038 -353.04095)
		(end 48.564038 -347.828616)
		(width 0.381)
		(layer "In2.Cu")
		(net "PVCCFA_EHV_FIVRA_CPU1")
	)
	(segment
		(start 47.591218 -343.253822)
		(end 48.101758 -342.743282)
		(width 0.381)
		(layer "In2.Cu")
		(net "PVCCFA_EHV_FIVRA_CPU1")
	)
	(segment
		(start 92.014294 -284.847538)
		(end 92.014294 -284.037786)
		(width 0.254)
		(layer "In2.Cu")
		(net "PVCCFA_EHV_FIVRA_CPU1")
	)
	(segment
		(start 88.516968 -286.080962)
		(end 88.91143 -286.475424)
		(width 0.254)
		(layer "In2.Cu")
		(net "PVCCFA_EHV_FIVRA_CPU1")
	)
	(segment
		(start 133.365748 -284.847538)
		(end 133.365748 -284.037786)
		(width 0.254)
		(layer "In2.Cu")
		(net "PVCCFA_EHV_FIVRA_CPU1")
	)
	(segment
		(start 178.26482 -357.460804)
		(end 177.9016 -357.097584)
		(width 0.381)
		(layer "In2.Cu")
		(net "PVCCFA_EHV_FIVRA_CPU1")
	)
	(segment
		(start 88.91143 -286.475424)
		(end 89.195148 -286.475424)
		(width 0.254)
		(layer "In2.Cu")
		(net "PVCCFA_EHV_FIVRA_CPU1")
	)
	(segment
		(start 177.9016 -357.097584)
		(end 177.9016 -356.479602)
		(width 0.381)
		(layer "In2.Cu")
		(net "PVCCFA_EHV_FIVRA_CPU1")
	)
	(segment
		(start 129.606548 -284.847538)
		(end 129.606548 -284.037786)
		(width 0.254)
		(layer "In2.Cu")
		(net "PVCCFA_EHV_FIVRA_CPU1")
	)
	(segment
		(start 48.564038 -347.828616)
		(end 47.591218 -346.855796)
		(width 0.381)
		(layer "In2.Cu")
		(net "PVCCFA_EHV_FIVRA_CPU1")
	)
	(segment
		(start 122.088148 -284.847538)
		(end 122.088148 -284.037786)
		(width 0.254)
		(layer "In2.Cu")
		(net "PVCCFA_EHV_FIVRA_CPU1")
	)
	(segment
		(start 95.773748 -288.103056)
		(end 95.773748 -287.22955)
		(width 0.254)
		(layer "In4.Cu")
		(net "PVCCFA_EHV_FIVRA_CPU1")
	)
	(segment
		(start 97.653348 -288.103056)
		(end 97.653348 -287.22955)
		(width 0.254)
		(layer "In4.Cu")
		(net "PVCCFA_EHV_FIVRA_CPU1")
	)
	(segment
		(start 125.847348 -288.103056)
		(end 125.847348 -287.22955)
		(width 0.254)
		(layer "In4.Cu")
		(net "PVCCFA_EHV_FIVRA_CPU1")
	)
	(segment
		(start 123.967748 -288.103056)
		(end 123.967748 -287.22955)
		(width 0.254)
		(layer "In4.Cu")
		(net "PVCCFA_EHV_FIVRA_CPU1")
	)
	(segment
		(start 99.532948 -288.103056)
		(end 99.532948 -287.22955)
		(width 0.254)
		(layer "In4.Cu")
		(net "PVCCFA_EHV_FIVRA_CPU1")
	)
	(segment
		(start 131.486148 -288.103056)
		(end 131.486148 -287.22955)
		(width 0.254)
		(layer "In4.Cu")
		(net "PVCCFA_EHV_FIVRA_CPU1")
	)
	(segment
		(start 92.014548 -288.103056)
		(end 92.014548 -287.22955)
		(width 0.254)
		(layer "In4.Cu")
		(net "PVCCFA_EHV_FIVRA_CPU1")
	)
	(segment
		(start 127.726948 -288.103056)
		(end 127.726948 -287.22955)
		(width 0.254)
		(layer "In4.Cu")
		(net "PVCCFA_EHV_FIVRA_CPU1")
	)
	(segment
		(start 90.134694 -288.103056)
		(end 90.134694 -287.22955)
		(width 0.254)
		(layer "In4.Cu")
		(net "PVCCFA_EHV_FIVRA_CPU1")
	)
	(segment
		(start 122.088148 -288.103056)
		(end 122.088148 -287.22955)
		(width 0.254)
		(layer "In4.Cu")
		(net "PVCCFA_EHV_FIVRA_CPU1")
	)
	(segment
		(start 133.365748 -288.103056)
		(end 133.365748 -287.22955)
		(width 0.254)
		(layer "In4.Cu")
		(net "PVCCFA_EHV_FIVRA_CPU1")
	)
	(segment
		(start 93.894148 -288.103056)
		(end 93.894148 -287.22955)
		(width 0.254)
		(layer "In4.Cu")
		(net "PVCCFA_EHV_FIVRA_CPU1")
	)
	(segment
		(start 101.412548 -288.103056)
		(end 101.412548 -287.22955)
		(width 0.254)
		(layer "In4.Cu")
		(net "PVCCFA_EHV_FIVRA_CPU1")
	)
	(segment
		(start 129.606548 -288.103056)
		(end 129.606548 -287.22955)
		(width 0.254)
		(layer "In4.Cu")
		(net "PVCCFA_EHV_FIVRA_CPU1")
	)
	(segment
		(start 103.292148 -288.103056)
		(end 103.292148 -287.22955)
		(width 0.254)
		(layer "In4.Cu")
		(net "PVCCFA_EHV_FIVRA_CPU1")
	)
	(segment
		(start 286.386016 -365.320834)
		(end 286.386016 -365.050578)
		(width 0.2286)
		(layer "F.Cu")
		(net "PVCCFA_EHV_FIVRA_CPU0_VOS4")
	)
	(segment
		(start 286.00273 -365.70412)
		(end 286.386016 -365.320834)
		(width 0.2286)
		(layer "F.Cu")
		(net "PVCCFA_EHV_FIVRA_CPU0_VOS4")
	)
	(via
		(at 286.00273 -365.70412)
		(size 0.508)
		(drill 0.254)
		(layers "F.Cu" "B.Cu")
		(net "PVCCFA_EHV_FIVRA_CPU0_VOS4")
	)
	(segment
		(start 284.94863 -365.276384)
		(end 284.925262 -365.253016)
		(width 0.2286)
		(layer "B.Cu")
		(net "PVCCFA_EHV_FIVRA_CPU0_VOS4")
	)
	(segment
		(start 285.574994 -365.276384)
		(end 284.94863 -365.276384)
		(width 0.2286)
		(layer "B.Cu")
		(net "PVCCFA_EHV_FIVRA_CPU0_VOS4")
	)
	(segment
		(start 286.00273 -365.70412)
		(end 285.574994 -365.276384)
		(width 0.2286)
		(layer "B.Cu")
		(net "PVCCFA_EHV_FIVRA_CPU0_VOS4")
	)
	(segment
		(start 423.448734 -364.633002)
		(end 423.448734 -364.362746)
		(width 0.2286)
		(layer "F.Cu")
		(net "PVCCFA_EHV_FIVRA_CPU0_VOS3")
	)
	(segment
		(start 423.065448 -365.016288)
		(end 423.448734 -364.633002)
		(width 0.2286)
		(layer "F.Cu")
		(net "PVCCFA_EHV_FIVRA_CPU0_VOS3")
	)
	(via
		(at 423.065448 -365.016288)
		(size 0.508)
		(drill 0.254)
		(layers "F.Cu" "B.Cu")
		(net "PVCCFA_EHV_FIVRA_CPU0_VOS3")
	)
	(segment
		(start 423.065448 -365.595408)
		(end 423.079164 -365.609124)
		(width 0.2032)
		(layer "B.Cu")
		(net "PVCCFA_EHV_FIVRA_CPU0_VOS3")
	)
	(segment
		(start 423.079164 -365.609124)
		(end 423.079164 -366.066324)
		(width 0.2032)
		(layer "B.Cu")
		(net "PVCCFA_EHV_FIVRA_CPU0_VOS3")
	)
	(segment
		(start 423.065448 -365.016288)
		(end 423.065448 -365.595408)
		(width 0.2032)
		(layer "B.Cu")
		(net "PVCCFA_EHV_FIVRA_CPU0_VOS3")
	)
	(segment
		(start 296.074338 -365.320834)
		(end 296.074338 -365.050578)
		(width 0.2286)
		(layer "F.Cu")
		(net "PVCCFA_EHV_FIVRA_CPU0_VOS2")
	)
	(segment
		(start 295.691052 -365.70412)
		(end 296.074338 -365.320834)
		(width 0.2286)
		(layer "F.Cu")
		(net "PVCCFA_EHV_FIVRA_CPU0_VOS2")
	)
	(via
		(at 295.691052 -365.70412)
		(size 0.508)
		(drill 0.254)
		(layers "F.Cu" "B.Cu")
		(net "PVCCFA_EHV_FIVRA_CPU0_VOS2")
	)
	(segment
		(start 295.694608 -366.302036)
		(end 295.699688 -366.307116)
		(width 0.2032)
		(layer "B.Cu")
		(net "PVCCFA_EHV_FIVRA_CPU0_VOS2")
	)
	(segment
		(start 295.691052 -365.70412)
		(end 295.691052 -366.28832)
		(width 0.2032)
		(layer "B.Cu")
		(net "PVCCFA_EHV_FIVRA_CPU0_VOS2")
	)
	(segment
		(start 295.694608 -366.291876)
		(end 295.694608 -366.302036)
		(width 0.2032)
		(layer "B.Cu")
		(net "PVCCFA_EHV_FIVRA_CPU0_VOS2")
	)
	(segment
		(start 295.691052 -366.28832)
		(end 295.694608 -366.291876)
		(width 0.2032)
		(layer "B.Cu")
		(net "PVCCFA_EHV_FIVRA_CPU0_VOS2")
	)
	(segment
		(start 295.699688 -366.307116)
		(end 295.699688 -366.764316)
		(width 0.2032)
		(layer "B.Cu")
		(net "PVCCFA_EHV_FIVRA_CPU0_VOS2")
	)
	(segment
		(start 413.760412 -364.633002)
		(end 413.760412 -364.362746)
		(width 0.2286)
		(layer "F.Cu")
		(net "PVCCFA_EHV_FIVRA_CPU0_VOS1")
	)
	(segment
		(start 413.377126 -365.016288)
		(end 413.760412 -364.633002)
		(width 0.2286)
		(layer "F.Cu")
		(net "PVCCFA_EHV_FIVRA_CPU0_VOS1")
	)
	(via
		(at 413.377126 -365.016288)
		(size 0.508)
		(drill 0.254)
		(layers "F.Cu" "B.Cu")
		(net "PVCCFA_EHV_FIVRA_CPU0_VOS1")
	)
	(segment
		(start 413.377126 -365.016288)
		(end 413.309816 -364.948978)
		(width 0.2286)
		(layer "B.Cu")
		(net "PVCCFA_EHV_FIVRA_CPU0_VOS1")
	)
	(segment
		(start 413.309816 -364.948978)
		(end 412.556198 -364.948978)
		(width 0.2286)
		(layer "B.Cu")
		(net "PVCCFA_EHV_FIVRA_CPU0_VOS1")
	)
	(segment
		(start 412.522162 -364.983014)
		(end 412.007558 -364.983014)
		(width 0.2286)
		(layer "B.Cu")
		(net "PVCCFA_EHV_FIVRA_CPU0_VOS1")
	)
	(segment
		(start 412.556198 -364.948978)
		(end 412.522162 -364.983014)
		(width 0.2286)
		(layer "B.Cu")
		(net "PVCCFA_EHV_FIVRA_CPU0_VOS1")
	)
	(segment
		(start 288.434272 -366.502442)
		(end 288.59607 -366.340644)
		(width 0.2286)
		(layer "F.Cu")
		(net "PVCCFA_EHV_FIVRA_CPU0_VDD4")
	)
	(segment
		(start 285.284418 -364.851696)
		(end 285.985712 -364.150402)
		(width 0.2032)
		(layer "F.Cu")
		(net "PVCCFA_EHV_FIVRA_CPU0_VDD4")
	)
	(segment
		(start 285.211266 -364.851696)
		(end 285.284418 -364.851696)
		(width 0.2032)
		(layer "F.Cu")
		(net "PVCCFA_EHV_FIVRA_CPU0_VDD4")
	)
	(segment
		(start 285.211266 -364.242096)
		(end 285.211266 -364.851696)
		(width 0.2286)
		(layer "F.Cu")
		(net "PVCCFA_EHV_FIVRA_CPU0_VDD4")
	)
	(segment
		(start 288.59607 -366.340644)
		(end 288.59607 -365.675418)
		(width 0.2286)
		(layer "F.Cu")
		(net "PVCCFA_EHV_FIVRA_CPU0_VDD4")
	)
	(segment
		(start 285.985712 -364.150402)
		(end 286.386016 -364.150402)
		(width 0.2032)
		(layer "F.Cu")
		(net "PVCCFA_EHV_FIVRA_CPU0_VDD4")
	)
	(via
		(at 288.434272 -366.502442)
		(size 0.508)
		(drill 0.254)
		(layers "F.Cu" "B.Cu")
		(net "PVCCFA_EHV_FIVRA_CPU0_VDD4")
	)
	(via
		(at 285.211266 -364.242096)
		(size 0.508)
		(drill 0.254)
		(layers "F.Cu" "B.Cu")
		(net "PVCCFA_EHV_FIVRA_CPU0_VDD4")
	)
	(via
		(at 287.457134 -365.755936)
		(size 0.6604)
		(drill 0.3302)
		(layers "F.Cu" "B.Cu")
		(net "PVCCFA_EHV_FIVRA_CPU0_VDD4")
	)
	(segment
		(start 286.213296 -364.242096)
		(end 286.262572 -364.19282)
		(width 0.254)
		(layer "B.Cu")
		(net "PVCCFA_EHV_FIVRA_CPU0_VDD4")
	)
	(segment
		(start 286.2834 -364.19282)
		(end 286.2834 -365.01959)
		(width 0.2286)
		(layer "B.Cu")
		(net "PVCCFA_EHV_FIVRA_CPU0_VDD4")
	)
	(segment
		(start 287.457134 -365.755936)
		(end 287.722564 -366.021366)
		(width 0.2286)
		(layer "B.Cu")
		(net "PVCCFA_EHV_FIVRA_CPU0_VDD4")
	)
	(segment
		(start 285.211266 -364.242096)
		(end 286.213296 -364.242096)
		(width 0.254)
		(layer "B.Cu")
		(net "PVCCFA_EHV_FIVRA_CPU0_VDD4")
	)
	(segment
		(start 286.262572 -364.19282)
		(end 286.2834 -364.19282)
		(width 0.254)
		(layer "B.Cu")
		(net "PVCCFA_EHV_FIVRA_CPU0_VDD4")
	)
	(segment
		(start 287.722564 -366.021366)
		(end 287.953196 -366.021366)
		(width 0.2286)
		(layer "B.Cu")
		(net "PVCCFA_EHV_FIVRA_CPU0_VDD4")
	)
	(segment
		(start 287.019746 -365.755936)
		(end 287.457134 -365.755936)
		(width 0.2286)
		(layer "B.Cu")
		(net "PVCCFA_EHV_FIVRA_CPU0_VDD4")
	)
	(segment
		(start 286.2834 -365.01959)
		(end 287.019746 -365.755936)
		(width 0.2286)
		(layer "B.Cu")
		(net "PVCCFA_EHV_FIVRA_CPU0_VDD4")
	)
	(segment
		(start 287.953196 -366.021366)
		(end 288.434272 -366.502442)
		(width 0.2286)
		(layer "B.Cu")
		(net "PVCCFA_EHV_FIVRA_CPU0_VDD4")
	)
	(segment
		(start 425.49699 -365.81461)
		(end 425.658788 -365.409988)
		(width 0.2286)
		(layer "F.Cu")
		(net "PVCCFA_EHV_FIVRA_CPU0_VDD3")
	)
	(segment
		(start 422.273984 -363.547914)
		(end 422.273984 -364.163864)
		(width 0.2032)
		(layer "F.Cu")
		(net "PVCCFA_EHV_FIVRA_CPU0_VDD3")
	)
	(segment
		(start 422.359328 -364.163864)
		(end 423.060622 -363.46257)
		(width 0.2032)
		(layer "F.Cu")
		(net "PVCCFA_EHV_FIVRA_CPU0_VDD3")
	)
	(segment
		(start 423.060622 -363.46257)
		(end 423.448734 -363.46257)
		(width 0.2032)
		(layer "F.Cu")
		(net "PVCCFA_EHV_FIVRA_CPU0_VDD3")
	)
	(segment
		(start 425.658788 -365.409988)
		(end 425.658788 -364.987586)
		(width 0.2286)
		(layer "F.Cu")
		(net "PVCCFA_EHV_FIVRA_CPU0_VDD3")
	)
	(segment
		(start 422.273984 -364.163864)
		(end 422.359328 -364.163864)
		(width 0.2032)
		(layer "F.Cu")
		(net "PVCCFA_EHV_FIVRA_CPU0_VDD3")
	)
	(via
		(at 422.273984 -363.547914)
		(size 0.508)
		(drill 0.254)
		(layers "F.Cu" "B.Cu")
		(net "PVCCFA_EHV_FIVRA_CPU0_VDD3")
	)
	(via
		(at 425.49699 -365.81461)
		(size 0.508)
		(drill 0.254)
		(layers "F.Cu" "B.Cu")
		(net "PVCCFA_EHV_FIVRA_CPU0_VDD3")
	)
	(via
		(at 424.65498 -365.327184)
		(size 0.6604)
		(drill 0.3302)
		(layers "F.Cu" "B.Cu")
		(net "PVCCFA_EHV_FIVRA_CPU0_VDD3")
	)
	(segment
		(start 422.273984 -363.547914)
		(end 422.32326 -363.498638)
		(width 0.2286)
		(layer "B.Cu")
		(net "PVCCFA_EHV_FIVRA_CPU0_VDD3")
	)
	(segment
		(start 425.009564 -365.327184)
		(end 425.49699 -365.81461)
		(width 0.2286)
		(layer "B.Cu")
		(net "PVCCFA_EHV_FIVRA_CPU0_VDD3")
	)
	(segment
		(start 424.65498 -365.327184)
		(end 425.009564 -365.327184)
		(width 0.2286)
		(layer "B.Cu")
		(net "PVCCFA_EHV_FIVRA_CPU0_VDD3")
	)
	(segment
		(start 422.939718 -363.498638)
		(end 422.939718 -363.919008)
		(width 0.2286)
		(layer "B.Cu")
		(net "PVCCFA_EHV_FIVRA_CPU0_VDD3")
	)
	(segment
		(start 422.939718 -363.919008)
		(end 424.347894 -365.327184)
		(width 0.2286)
		(layer "B.Cu")
		(net "PVCCFA_EHV_FIVRA_CPU0_VDD3")
	)
	(segment
		(start 422.32326 -363.498638)
		(end 422.939718 -363.498638)
		(width 0.2286)
		(layer "B.Cu")
		(net "PVCCFA_EHV_FIVRA_CPU0_VDD3")
	)
	(segment
		(start 424.347894 -365.327184)
		(end 424.65498 -365.327184)
		(width 0.2286)
		(layer "B.Cu")
		(net "PVCCFA_EHV_FIVRA_CPU0_VDD3")
	)
	(segment
		(start 294.984932 -364.851696)
		(end 295.686226 -364.150402)
		(width 0.2032)
		(layer "F.Cu")
		(net "PVCCFA_EHV_FIVRA_CPU0_VDD2")
	)
	(segment
		(start 298.122594 -366.502442)
		(end 298.284392 -366.340644)
		(width 0.2286)
		(layer "F.Cu")
		(net "PVCCFA_EHV_FIVRA_CPU0_VDD2")
	)
	(segment
		(start 298.284392 -366.340644)
		(end 298.284392 -365.675418)
		(width 0.2286)
		(layer "F.Cu")
		(net "PVCCFA_EHV_FIVRA_CPU0_VDD2")
	)
	(segment
		(start 295.686226 -364.150402)
		(end 296.074338 -364.150402)
		(width 0.2032)
		(layer "F.Cu")
		(net "PVCCFA_EHV_FIVRA_CPU0_VDD2")
	)
	(segment
		(start 294.899588 -364.235746)
		(end 294.899588 -364.851696)
		(width 0.2032)
		(layer "F.Cu")
		(net "PVCCFA_EHV_FIVRA_CPU0_VDD2")
	)
	(segment
		(start 294.899588 -364.851696)
		(end 294.984932 -364.851696)
		(width 0.2032)
		(layer "F.Cu")
		(net "PVCCFA_EHV_FIVRA_CPU0_VDD2")
	)
	(via
		(at 298.122594 -366.502442)
		(size 0.508)
		(drill 0.254)
		(layers "F.Cu" "B.Cu")
		(net "PVCCFA_EHV_FIVRA_CPU0_VDD2")
	)
	(via
		(at 297.35018 -365.66729)
		(size 0.6604)
		(drill 0.3302)
		(layers "F.Cu" "B.Cu")
		(net "PVCCFA_EHV_FIVRA_CPU0_VDD2")
	)
	(via
		(at 294.899588 -364.235746)
		(size 0.508)
		(drill 0.254)
		(layers "F.Cu" "B.Cu")
		(net "PVCCFA_EHV_FIVRA_CPU0_VDD2")
	)
	(segment
		(start 295.565322 -364.18647)
		(end 295.565322 -364.60684)
		(width 0.2286)
		(layer "B.Cu")
		(net "PVCCFA_EHV_FIVRA_CPU0_VDD2")
	)
	(segment
		(start 296.625772 -365.66729)
		(end 297.35018 -365.66729)
		(width 0.2286)
		(layer "B.Cu")
		(net "PVCCFA_EHV_FIVRA_CPU0_VDD2")
	)
	(segment
		(start 295.565322 -364.60684)
		(end 296.625772 -365.66729)
		(width 0.2286)
		(layer "B.Cu")
		(net "PVCCFA_EHV_FIVRA_CPU0_VDD2")
	)
	(segment
		(start 294.948864 -364.18647)
		(end 295.565322 -364.18647)
		(width 0.2286)
		(layer "B.Cu")
		(net "PVCCFA_EHV_FIVRA_CPU0_VDD2")
	)
	(segment
		(start 294.899588 -364.235746)
		(end 294.948864 -364.18647)
		(width 0.2286)
		(layer "B.Cu")
		(net "PVCCFA_EHV_FIVRA_CPU0_VDD2")
	)
	(segment
		(start 297.35018 -365.66729)
		(end 297.696382 -365.66729)
		(width 0.2286)
		(layer "B.Cu")
		(net "PVCCFA_EHV_FIVRA_CPU0_VDD2")
	)
	(segment
		(start 298.122594 -366.093502)
		(end 298.122594 -366.502442)
		(width 0.2286)
		(layer "B.Cu")
		(net "PVCCFA_EHV_FIVRA_CPU0_VDD2")
	)
	(segment
		(start 297.696382 -365.66729)
		(end 298.122594 -366.093502)
		(width 0.2286)
		(layer "B.Cu")
		(net "PVCCFA_EHV_FIVRA_CPU0_VDD2")
	)
	(segment
		(start 415.808668 -365.81461)
		(end 415.970466 -365.404146)
		(width 0.2286)
		(layer "F.Cu")
		(net "PVCCFA_EHV_FIVRA_CPU0_VDD1")
	)
	(segment
		(start 412.585662 -363.554264)
		(end 412.585662 -364.163864)
		(width 0.2286)
		(layer "F.Cu")
		(net "PVCCFA_EHV_FIVRA_CPU0_VDD1")
	)
	(segment
		(start 412.585662 -364.163864)
		(end 412.658814 -364.163864)
		(width 0.2032)
		(layer "F.Cu")
		(net "PVCCFA_EHV_FIVRA_CPU0_VDD1")
	)
	(segment
		(start 415.970466 -365.404146)
		(end 415.970466 -364.987586)
		(width 0.2286)
		(layer "F.Cu")
		(net "PVCCFA_EHV_FIVRA_CPU0_VDD1")
	)
	(segment
		(start 413.360108 -363.46257)
		(end 413.760412 -363.46257)
		(width 0.2032)
		(layer "F.Cu")
		(net "PVCCFA_EHV_FIVRA_CPU0_VDD1")
	)
	(segment
		(start 412.658814 -364.163864)
		(end 413.360108 -363.46257)
		(width 0.2032)
		(layer "F.Cu")
		(net "PVCCFA_EHV_FIVRA_CPU0_VDD1")
	)
	(via
		(at 412.585662 -363.554264)
		(size 0.508)
		(drill 0.254)
		(layers "F.Cu" "B.Cu")
		(net "PVCCFA_EHV_FIVRA_CPU0_VDD1")
	)
	(via
		(at 415.808668 -365.81461)
		(size 0.508)
		(drill 0.254)
		(layers "F.Cu" "B.Cu")
		(net "PVCCFA_EHV_FIVRA_CPU0_VDD1")
	)
	(via
		(at 415.5948 -364.962948)
		(size 0.6604)
		(drill 0.3302)
		(layers "F.Cu" "B.Cu")
		(net "PVCCFA_EHV_FIVRA_CPU0_VDD1")
	)
	(segment
		(start 413.641286 -363.502194)
		(end 413.6644 -363.525308)
		(width 0.254)
		(layer "B.Cu")
		(net "PVCCFA_EHV_FIVRA_CPU0_VDD1")
	)
	(segment
		(start 413.6644 -364.338362)
		(end 414.288986 -364.962948)
		(width 0.2286)
		(layer "B.Cu")
		(net "PVCCFA_EHV_FIVRA_CPU0_VDD1")
	)
	(segment
		(start 412.585662 -363.554264)
		(end 413.108394 -363.554264)
		(width 0.254)
		(layer "B.Cu")
		(net "PVCCFA_EHV_FIVRA_CPU0_VDD1")
	)
	(segment
		(start 414.288986 -364.962948)
		(end 415.5948 -364.962948)
		(width 0.2286)
		(layer "B.Cu")
		(net "PVCCFA_EHV_FIVRA_CPU0_VDD1")
	)
	(segment
		(start 413.160464 -363.502194)
		(end 413.641286 -363.502194)
		(width 0.254)
		(layer "B.Cu")
		(net "PVCCFA_EHV_FIVRA_CPU0_VDD1")
	)
	(segment
		(start 413.6644 -363.525308)
		(end 413.6644 -364.338362)
		(width 0.2286)
		(layer "B.Cu")
		(net "PVCCFA_EHV_FIVRA_CPU0_VDD1")
	)
	(segment
		(start 413.108394 -363.554264)
		(end 413.160464 -363.502194)
		(width 0.254)
		(layer "B.Cu")
		(net "PVCCFA_EHV_FIVRA_CPU0_VDD1")
	)
	(segment
		(start 415.5948 -364.962948)
		(end 415.5948 -365.600742)
		(width 0.2286)
		(layer "B.Cu")
		(net "PVCCFA_EHV_FIVRA_CPU0_VDD1")
	)
	(segment
		(start 415.5948 -365.600742)
		(end 415.808668 -365.81461)
		(width 0.2286)
		(layer "B.Cu")
		(net "PVCCFA_EHV_FIVRA_CPU0_VDD1")
	)
	(segment
		(start 288.876994 -367.078514)
		(end 289.046158 -366.669828)
		(width 0.1524)
		(layer "F.Cu")
		(net "PVCCFA_EHV_FIVRA_CPU0_PWM4")
	)
	(segment
		(start 357.518208 -362.83519)
		(end 357.518208 -361.723432)
		(width 0.1778)
		(layer "F.Cu")
		(net "PVCCFA_EHV_FIVRA_CPU0_PWM4")
	)
	(segment
		(start 358.05872 -363.375702)
		(end 357.518208 -362.83519)
		(width 0.1778)
		(layer "F.Cu")
		(net "PVCCFA_EHV_FIVRA_CPU0_PWM4")
	)
	(segment
		(start 289.046158 -366.669828)
		(end 289.046158 -365.675418)
		(width 0.1524)
		(layer "F.Cu")
		(net "PVCCFA_EHV_FIVRA_CPU0_PWM4")
	)
	(via
		(at 346.6592 -368.104674)
		(size 0.508)
		(drill 0.254)
		(layers "F.Cu" "B.Cu")
		(net "PVCCFA_EHV_FIVRA_CPU0_PWM4")
	)
	(via
		(at 358.05872 -363.375702)
		(size 0.508)
		(drill 0.254)
		(layers "F.Cu" "B.Cu")
		(net "PVCCFA_EHV_FIVRA_CPU0_PWM4")
	)
	(via
		(at 288.876994 -367.078514)
		(size 0.508)
		(drill 0.254)
		(layers "F.Cu" "B.Cu")
		(net "PVCCFA_EHV_FIVRA_CPU0_PWM4")
	)
	(segment
		(start 347.561154 -366.943894)
		(end 346.6592 -367.845848)
		(width 0.254)
		(layer "B.Cu")
		(net "PVCCFA_EHV_FIVRA_CPU0_PWM4")
	)
	(segment
		(start 352.50374 -368.559588)
		(end 350.888046 -366.943894)
		(width 0.254)
		(layer "B.Cu")
		(net "PVCCFA_EHV_FIVRA_CPU0_PWM4")
	)
	(segment
		(start 350.888046 -366.943894)
		(end 347.561154 -366.943894)
		(width 0.254)
		(layer "B.Cu")
		(net "PVCCFA_EHV_FIVRA_CPU0_PWM4")
	)
	(segment
		(start 358.05872 -363.375702)
		(end 357.750872 -363.375702)
		(width 0.254)
		(layer "B.Cu")
		(net "PVCCFA_EHV_FIVRA_CPU0_PWM4")
	)
	(segment
		(start 346.6592 -367.845848)
		(end 346.6592 -368.104674)
		(width 0.254)
		(layer "B.Cu")
		(net "PVCCFA_EHV_FIVRA_CPU0_PWM4")
	)
	(segment
		(start 357.12908 -363.997494)
		(end 357.12908 -367.459768)
		(width 0.254)
		(layer "B.Cu")
		(net "PVCCFA_EHV_FIVRA_CPU0_PWM4")
	)
	(segment
		(start 357.750872 -363.375702)
		(end 357.12908 -363.997494)
		(width 0.254)
		(layer "B.Cu")
		(net "PVCCFA_EHV_FIVRA_CPU0_PWM4")
	)
	(segment
		(start 356.02926 -368.559588)
		(end 352.50374 -368.559588)
		(width 0.254)
		(layer "B.Cu")
		(net "PVCCFA_EHV_FIVRA_CPU0_PWM4")
	)
	(segment
		(start 357.12908 -367.459768)
		(end 356.02926 -368.559588)
		(width 0.254)
		(layer "B.Cu")
		(net "PVCCFA_EHV_FIVRA_CPU0_PWM4")
	)
	(segment
		(start 302.793654 -370.846858)
		(end 330.48829 -370.846858)
		(width 0.254)
		(layer "In6.Cu")
		(net "PVCCFA_EHV_FIVRA_CPU0_PWM4")
	)
	(segment
		(start 295.570656 -369.279424)
		(end 301.22622 -369.279424)
		(width 0.254)
		(layer "In6.Cu")
		(net "PVCCFA_EHV_FIVRA_CPU0_PWM4")
	)
	(segment
		(start 288.876994 -367.078514)
		(end 289.413442 -367.614962)
		(width 0.254)
		(layer "In6.Cu")
		(net "PVCCFA_EHV_FIVRA_CPU0_PWM4")
	)
	(segment
		(start 294.468804 -367.614962)
		(end 295.030906 -368.177064)
		(width 0.254)
		(layer "In6.Cu")
		(net "PVCCFA_EHV_FIVRA_CPU0_PWM4")
	)
	(segment
		(start 330.48829 -370.846858)
		(end 333.230474 -368.104674)
		(width 0.254)
		(layer "In6.Cu")
		(net "PVCCFA_EHV_FIVRA_CPU0_PWM4")
	)
	(segment
		(start 295.030906 -368.177064)
		(end 295.030906 -368.739674)
		(width 0.254)
		(layer "In6.Cu")
		(net "PVCCFA_EHV_FIVRA_CPU0_PWM4")
	)
	(segment
		(start 295.030906 -368.739674)
		(end 295.570656 -369.279424)
		(width 0.254)
		(layer "In6.Cu")
		(net "PVCCFA_EHV_FIVRA_CPU0_PWM4")
	)
	(segment
		(start 289.413442 -367.614962)
		(end 294.468804 -367.614962)
		(width 0.254)
		(layer "In6.Cu")
		(net "PVCCFA_EHV_FIVRA_CPU0_PWM4")
	)
	(segment
		(start 301.22622 -369.279424)
		(end 302.793654 -370.846858)
		(width 0.254)
		(layer "In6.Cu")
		(net "PVCCFA_EHV_FIVRA_CPU0_PWM4")
	)
	(segment
		(start 333.230474 -368.104674)
		(end 346.6592 -368.104674)
		(width 0.254)
		(layer "In6.Cu")
		(net "PVCCFA_EHV_FIVRA_CPU0_PWM4")
	)
	(segment
		(start 357.918258 -362.534708)
		(end 357.918258 -361.723432)
		(width 0.1778)
		(layer "F.Cu")
		(net "PVCCFA_EHV_FIVRA_CPU0_PWM3")
	)
	(segment
		(start 426.108876 -365.98225)
		(end 426.108876 -364.987586)
		(width 0.1524)
		(layer "F.Cu")
		(net "PVCCFA_EHV_FIVRA_CPU0_PWM3")
	)
	(segment
		(start 425.939712 -366.390682)
		(end 426.108876 -365.98225)
		(width 0.1524)
		(layer "F.Cu")
		(net "PVCCFA_EHV_FIVRA_CPU0_PWM3")
	)
	(segment
		(start 359.01376 -363.63021)
		(end 357.918258 -362.534708)
		(width 0.1778)
		(layer "F.Cu")
		(net "PVCCFA_EHV_FIVRA_CPU0_PWM3")
	)
	(segment
		(start 359.01376 -364.940596)
		(end 359.01376 -363.63021)
		(width 0.1778)
		(layer "F.Cu")
		(net "PVCCFA_EHV_FIVRA_CPU0_PWM3")
	)
	(via
		(at 359.01376 -364.940596)
		(size 0.508)
		(drill 0.254)
		(layers "F.Cu" "B.Cu")
		(net "PVCCFA_EHV_FIVRA_CPU0_PWM3")
	)
	(via
		(at 425.939712 -366.390682)
		(size 0.508)
		(drill 0.254)
		(layers "F.Cu" "B.Cu")
		(net "PVCCFA_EHV_FIVRA_CPU0_PWM3")
	)
	(segment
		(start 428.718472 -369.169442)
		(end 428.718472 -371.759226)
		(width 0.254)
		(layer "In11.Cu")
		(net "PVCCFA_EHV_FIVRA_CPU0_PWM3")
	)
	(segment
		(start 359.949242 -366.623346)
		(end 359.949242 -365.49711)
		(width 0.254)
		(layer "In11.Cu")
		(net "PVCCFA_EHV_FIVRA_CPU0_PWM3")
	)
	(segment
		(start 359.185972 -365.112808)
		(end 359.01376 -364.940596)
		(width 0.254)
		(layer "In11.Cu")
		(net "PVCCFA_EHV_FIVRA_CPU0_PWM3")
	)
	(segment
		(start 359.56494 -365.112808)
		(end 359.185972 -365.112808)
		(width 0.254)
		(layer "In11.Cu")
		(net "PVCCFA_EHV_FIVRA_CPU0_PWM3")
	)
	(segment
		(start 370.348256 -377.02236)
		(end 359.949242 -366.623346)
		(width 0.254)
		(layer "In11.Cu")
		(net "PVCCFA_EHV_FIVRA_CPU0_PWM3")
	)
	(segment
		(start 359.949242 -365.49711)
		(end 359.56494 -365.112808)
		(width 0.254)
		(layer "In11.Cu")
		(net "PVCCFA_EHV_FIVRA_CPU0_PWM3")
	)
	(segment
		(start 428.718472 -371.759226)
		(end 423.455338 -377.02236)
		(width 0.254)
		(layer "In11.Cu")
		(net "PVCCFA_EHV_FIVRA_CPU0_PWM3")
	)
	(segment
		(start 423.455338 -377.02236)
		(end 370.348256 -377.02236)
		(width 0.254)
		(layer "In11.Cu")
		(net "PVCCFA_EHV_FIVRA_CPU0_PWM3")
	)
	(segment
		(start 425.939712 -366.390682)
		(end 428.718472 -369.169442)
		(width 0.254)
		(layer "In11.Cu")
		(net "PVCCFA_EHV_FIVRA_CPU0_PWM3")
	)
	(segment
		(start 359.458514 -363.948472)
		(end 359.458514 -363.412278)
		(width 0.1778)
		(layer "F.Cu")
		(net "PVCCFA_EHV_FIVRA_CPU0_PWM2")
	)
	(segment
		(start 298.565316 -367.078514)
		(end 298.73448 -366.670082)
		(width 0.1524)
		(layer "F.Cu")
		(net "PVCCFA_EHV_FIVRA_CPU0_PWM2")
	)
	(segment
		(start 358.318308 -362.272072)
		(end 358.318308 -361.723432)
		(width 0.1778)
		(layer "F.Cu")
		(net "PVCCFA_EHV_FIVRA_CPU0_PWM2")
	)
	(segment
		(start 359.733088 -364.223046)
		(end 359.458514 -363.948472)
		(width 0.1778)
		(layer "F.Cu")
		(net "PVCCFA_EHV_FIVRA_CPU0_PWM2")
	)
	(segment
		(start 359.458514 -363.412278)
		(end 358.318308 -362.272072)
		(width 0.1778)
		(layer "F.Cu")
		(net "PVCCFA_EHV_FIVRA_CPU0_PWM2")
	)
	(segment
		(start 298.73448 -366.670082)
		(end 298.73448 -365.675418)
		(width 0.1524)
		(layer "F.Cu")
		(net "PVCCFA_EHV_FIVRA_CPU0_PWM2")
	)
	(via
		(at 359.733088 -364.223046)
		(size 0.762)
		(drill 0.254)
		(layers "F.Cu" "B.Cu")
		(net "PVCCFA_EHV_FIVRA_CPU0_PWM2")
	)
	(via
		(at 347.685868 -368.112294)
		(size 0.508)
		(drill 0.254)
		(layers "F.Cu" "B.Cu")
		(net "PVCCFA_EHV_FIVRA_CPU0_PWM2")
	)
	(via
		(at 298.565316 -367.078514)
		(size 0.508)
		(drill 0.254)
		(layers "F.Cu" "B.Cu")
		(net "PVCCFA_EHV_FIVRA_CPU0_PWM2")
	)
	(segment
		(start 350.799146 -368.112294)
		(end 347.685868 -368.112294)
		(width 0.254)
		(layer "B.Cu")
		(net "PVCCFA_EHV_FIVRA_CPU0_PWM2")
	)
	(segment
		(start 359.733088 -364.223046)
		(end 359.82656 -364.316518)
		(width 0.254)
		(layer "B.Cu")
		(net "PVCCFA_EHV_FIVRA_CPU0_PWM2")
	)
	(segment
		(start 359.82656 -368.087656)
		(end 357.885238 -370.028978)
		(width 0.254)
		(layer "B.Cu")
		(net "PVCCFA_EHV_FIVRA_CPU0_PWM2")
	)
	(segment
		(start 352.71583 -370.028978)
		(end 350.799146 -368.112294)
		(width 0.254)
		(layer "B.Cu")
		(net "PVCCFA_EHV_FIVRA_CPU0_PWM2")
	)
	(segment
		(start 359.82656 -364.316518)
		(end 359.82656 -368.087656)
		(width 0.254)
		(layer "B.Cu")
		(net "PVCCFA_EHV_FIVRA_CPU0_PWM2")
	)
	(segment
		(start 357.885238 -370.028978)
		(end 352.71583 -370.028978)
		(width 0.254)
		(layer "B.Cu")
		(net "PVCCFA_EHV_FIVRA_CPU0_PWM2")
	)
	(segment
		(start 298.980606 -367.493804)
		(end 330.790804 -367.493804)
		(width 0.254)
		(layer "In6.Cu")
		(net "PVCCFA_EHV_FIVRA_CPU0_PWM2")
	)
	(segment
		(start 347.685868 -367.445036)
		(end 347.685868 -368.112294)
		(width 0.254)
		(layer "In6.Cu")
		(net "PVCCFA_EHV_FIVRA_CPU0_PWM2")
	)
	(segment
		(start 330.790804 -367.493804)
		(end 332.13802 -366.146588)
		(width 0.254)
		(layer "In6.Cu")
		(net "PVCCFA_EHV_FIVRA_CPU0_PWM2")
	)
	(segment
		(start 332.13802 -366.146588)
		(end 346.38742 -366.146588)
		(width 0.254)
		(layer "In6.Cu")
		(net "PVCCFA_EHV_FIVRA_CPU0_PWM2")
	)
	(segment
		(start 298.565316 -367.078514)
		(end 298.980606 -367.493804)
		(width 0.254)
		(layer "In6.Cu")
		(net "PVCCFA_EHV_FIVRA_CPU0_PWM2")
	)
	(segment
		(start 346.38742 -366.146588)
		(end 347.685868 -367.445036)
		(width 0.254)
		(layer "In6.Cu")
		(net "PVCCFA_EHV_FIVRA_CPU0_PWM2")
	)
	(segment
		(start 416.25139 -366.390682)
		(end 416.420554 -365.98225)
		(width 0.1524)
		(layer "F.Cu")
		(net "PVCCFA_EHV_FIVRA_CPU0_PWM1")
	)
	(segment
		(start 359.355644 -362.43006)
		(end 359.059226 -362.43006)
		(width 0.1778)
		(layer "F.Cu")
		(net "PVCCFA_EHV_FIVRA_CPU0_PWM1")
	)
	(segment
		(start 416.420554 -365.98225)
		(end 416.420554 -364.987586)
		(width 0.1524)
		(layer "F.Cu")
		(net "PVCCFA_EHV_FIVRA_CPU0_PWM1")
	)
	(segment
		(start 358.718104 -362.088938)
		(end 358.718104 -361.723432)
		(width 0.1778)
		(layer "F.Cu")
		(net "PVCCFA_EHV_FIVRA_CPU0_PWM1")
	)
	(segment
		(start 359.059226 -362.43006)
		(end 358.718104 -362.088938)
		(width 0.1778)
		(layer "F.Cu")
		(net "PVCCFA_EHV_FIVRA_CPU0_PWM1")
	)
	(via
		(at 359.355644 -362.43006)
		(size 0.508)
		(drill 0.254)
		(layers "F.Cu" "B.Cu")
		(net "PVCCFA_EHV_FIVRA_CPU0_PWM1")
	)
	(via
		(at 416.25139 -366.390682)
		(size 0.508)
		(drill 0.254)
		(layers "F.Cu" "B.Cu")
		(net "PVCCFA_EHV_FIVRA_CPU0_PWM1")
	)
	(segment
		(start 364.19028 -365.317532)
		(end 364.19028 -366.442752)
		(width 0.254)
		(layer "In11.Cu")
		(net "PVCCFA_EHV_FIVRA_CPU0_PWM1")
	)
	(segment
		(start 373.68607 -375.938542)
		(end 409.693364 -375.938542)
		(width 0.254)
		(layer "In11.Cu")
		(net "PVCCFA_EHV_FIVRA_CPU0_PWM1")
	)
	(segment
		(start 362.863384 -362.674154)
		(end 363.65688 -363.861604)
		(width 0.254)
		(layer "In11.Cu")
		(net "PVCCFA_EHV_FIVRA_CPU0_PWM1")
	)
	(segment
		(start 409.693364 -375.938542)
		(end 410.770324 -374.861582)
		(width 0.254)
		(layer "In11.Cu")
		(net "PVCCFA_EHV_FIVRA_CPU0_PWM1")
	)
	(segment
		(start 411.91942 -368.429032)
		(end 416.240976 -368.429032)
		(width 0.254)
		(layer "In11.Cu")
		(net "PVCCFA_EHV_FIVRA_CPU0_PWM1")
	)
	(segment
		(start 416.754818 -366.89411)
		(end 416.25139 -366.390682)
		(width 0.254)
		(layer "In11.Cu")
		(net "PVCCFA_EHV_FIVRA_CPU0_PWM1")
	)
	(segment
		(start 363.65688 -363.861604)
		(end 363.65688 -364.784132)
		(width 0.254)
		(layer "In11.Cu")
		(net "PVCCFA_EHV_FIVRA_CPU0_PWM1")
	)
	(segment
		(start 359.355644 -362.43006)
		(end 359.3592 -362.433616)
		(width 0.254)
		(layer "In11.Cu")
		(net "PVCCFA_EHV_FIVRA_CPU0_PWM1")
	)
	(segment
		(start 364.19028 -366.442752)
		(end 373.68607 -375.938542)
		(width 0.254)
		(layer "In11.Cu")
		(net "PVCCFA_EHV_FIVRA_CPU0_PWM1")
	)
	(segment
		(start 361.647486 -362.433616)
		(end 361.828842 -362.25226)
		(width 0.254)
		(layer "In11.Cu")
		(net "PVCCFA_EHV_FIVRA_CPU0_PWM1")
	)
	(segment
		(start 416.754818 -367.91519)
		(end 416.754818 -366.89411)
		(width 0.254)
		(layer "In11.Cu")
		(net "PVCCFA_EHV_FIVRA_CPU0_PWM1")
	)
	(segment
		(start 410.770324 -369.578128)
		(end 411.91942 -368.429032)
		(width 0.254)
		(layer "In11.Cu")
		(net "PVCCFA_EHV_FIVRA_CPU0_PWM1")
	)
	(segment
		(start 416.240976 -368.429032)
		(end 416.754818 -367.91519)
		(width 0.254)
		(layer "In11.Cu")
		(net "PVCCFA_EHV_FIVRA_CPU0_PWM1")
	)
	(segment
		(start 362.44149 -362.25226)
		(end 362.863384 -362.674154)
		(width 0.254)
		(layer "In11.Cu")
		(net "PVCCFA_EHV_FIVRA_CPU0_PWM1")
	)
	(segment
		(start 359.3592 -362.433616)
		(end 361.647486 -362.433616)
		(width 0.254)
		(layer "In11.Cu")
		(net "PVCCFA_EHV_FIVRA_CPU0_PWM1")
	)
	(segment
		(start 363.65688 -364.784132)
		(end 364.19028 -365.317532)
		(width 0.254)
		(layer "In11.Cu")
		(net "PVCCFA_EHV_FIVRA_CPU0_PWM1")
	)
	(segment
		(start 410.770324 -374.861582)
		(end 410.770324 -369.578128)
		(width 0.254)
		(layer "In11.Cu")
		(net "PVCCFA_EHV_FIVRA_CPU0_PWM1")
	)
	(segment
		(start 361.828842 -362.25226)
		(end 362.44149 -362.25226)
		(width 0.254)
		(layer "In11.Cu")
		(net "PVCCFA_EHV_FIVRA_CPU0_PWM1")
	)
	(segment
		(start 286.014922 -363.700568)
		(end 286.386016 -363.700568)
		(width 0.2032)
		(layer "F.Cu")
		(net "PVCCFA_EHV_FIVRA_CPU0_PVCC2")
	)
	(segment
		(start 285.211266 -363.594396)
		(end 284.805374 -363.594396)
		(width 0.254)
		(layer "F.Cu")
		(net "PVCCFA_EHV_FIVRA_CPU0_PVCC2")
	)
	(segment
		(start 285.29915 -362.984796)
		(end 286.014922 -363.700568)
		(width 0.2032)
		(layer "F.Cu")
		(net "PVCCFA_EHV_FIVRA_CPU0_PVCC2")
	)
	(segment
		(start 294.899588 -363.600746)
		(end 294.899588 -362.984796)
		(width 0.2032)
		(layer "F.Cu")
		(net "PVCCFA_EHV_FIVRA_CPU0_PVCC2")
	)
	(segment
		(start 284.805374 -363.594396)
		(end 284.518354 -363.881416)
		(width 0.254)
		(layer "F.Cu")
		(net "PVCCFA_EHV_FIVRA_CPU0_PVCC2")
	)
	(segment
		(start 295.703244 -363.700568)
		(end 296.074338 -363.700568)
		(width 0.2032)
		(layer "F.Cu")
		(net "PVCCFA_EHV_FIVRA_CPU0_PVCC2")
	)
	(segment
		(start 284.226762 -363.881416)
		(end 284.226762 -362.984796)
		(width 0.254)
		(layer "F.Cu")
		(net "PVCCFA_EHV_FIVRA_CPU0_PVCC2")
	)
	(segment
		(start 294.987472 -362.984796)
		(end 295.703244 -363.700568)
		(width 0.2032)
		(layer "F.Cu")
		(net "PVCCFA_EHV_FIVRA_CPU0_PVCC2")
	)
	(segment
		(start 294.899588 -362.984796)
		(end 294.987472 -362.984796)
		(width 0.2032)
		(layer "F.Cu")
		(net "PVCCFA_EHV_FIVRA_CPU0_PVCC2")
	)
	(segment
		(start 285.211266 -362.984796)
		(end 285.29915 -362.984796)
		(width 0.2032)
		(layer "F.Cu")
		(net "PVCCFA_EHV_FIVRA_CPU0_PVCC2")
	)
	(segment
		(start 284.226762 -362.984796)
		(end 285.211266 -362.984796)
		(width 0.254)
		(layer "F.Cu")
		(net "PVCCFA_EHV_FIVRA_CPU0_PVCC2")
	)
	(segment
		(start 284.518354 -363.881416)
		(end 284.226762 -363.881416)
		(width 0.254)
		(layer "F.Cu")
		(net "PVCCFA_EHV_FIVRA_CPU0_PVCC2")
	)
	(via
		(at 294.899588 -363.600746)
		(size 0.508)
		(drill 0.254)
		(layers "F.Cu" "B.Cu")
		(net "PVCCFA_EHV_FIVRA_CPU0_PVCC2")
	)
	(via
		(at 285.211266 -363.594396)
		(size 0.508)
		(drill 0.254)
		(layers "F.Cu" "B.Cu")
		(net "PVCCFA_EHV_FIVRA_CPU0_PVCC2")
	)
	(segment
		(start 294.899588 -363.600746)
		(end 295.113964 -363.38637)
		(width 0.254)
		(layer "B.Cu")
		(net "PVCCFA_EHV_FIVRA_CPU0_PVCC2")
	)
	(segment
		(start 285.389574 -363.416088)
		(end 286.260032 -363.416088)
		(width 0.254)
		(layer "B.Cu")
		(net "PVCCFA_EHV_FIVRA_CPU0_PVCC2")
	)
	(segment
		(start 286.260032 -363.416088)
		(end 286.2834 -363.39272)
		(width 0.254)
		(layer "B.Cu")
		(net "PVCCFA_EHV_FIVRA_CPU0_PVCC2")
	)
	(segment
		(start 285.211266 -363.594396)
		(end 285.389574 -363.416088)
		(width 0.254)
		(layer "B.Cu")
		(net "PVCCFA_EHV_FIVRA_CPU0_PVCC2")
	)
	(segment
		(start 295.113964 -363.38637)
		(end 295.565322 -363.38637)
		(width 0.254)
		(layer "B.Cu")
		(net "PVCCFA_EHV_FIVRA_CPU0_PVCC2")
	)
	(segment
		(start 286.487362 -364.028482)
		(end 288.647632 -364.028482)
		(width 0.381)
		(layer "In4.Cu")
		(net "PVCCFA_EHV_FIVRA_CPU0_PVCC2")
	)
	(segment
		(start 291.606478 -363.486446)
		(end 292.329616 -362.763308)
		(width 0.381)
		(layer "In4.Cu")
		(net "PVCCFA_EHV_FIVRA_CPU0_PVCC2")
	)
	(segment
		(start 289.189668 -363.486446)
		(end 291.606478 -363.486446)
		(width 0.381)
		(layer "In4.Cu")
		(net "PVCCFA_EHV_FIVRA_CPU0_PVCC2")
	)
	(segment
		(start 292.329616 -362.763308)
		(end 294.06215 -362.763308)
		(width 0.381)
		(layer "In4.Cu")
		(net "PVCCFA_EHV_FIVRA_CPU0_PVCC2")
	)
	(segment
		(start 288.647632 -364.028482)
		(end 289.189668 -363.486446)
		(width 0.381)
		(layer "In4.Cu")
		(net "PVCCFA_EHV_FIVRA_CPU0_PVCC2")
	)
	(segment
		(start 294.06215 -362.763308)
		(end 294.899588 -363.600746)
		(width 0.381)
		(layer "In4.Cu")
		(net "PVCCFA_EHV_FIVRA_CPU0_PVCC2")
	)
	(segment
		(start 286.053276 -363.594396)
		(end 286.487362 -364.028482)
		(width 0.381)
		(layer "In4.Cu")
		(net "PVCCFA_EHV_FIVRA_CPU0_PVCC2")
	)
	(segment
		(start 285.211266 -363.594396)
		(end 286.053276 -363.594396)
		(width 0.381)
		(layer "In4.Cu")
		(net "PVCCFA_EHV_FIVRA_CPU0_PVCC2")
	)
	(segment
		(start 411.601158 -362.296964)
		(end 411.601158 -363.193584)
		(width 0.254)
		(layer "F.Cu")
		(net "PVCCFA_EHV_FIVRA_CPU0_PVCC1")
	)
	(segment
		(start 411.91815 -363.193584)
		(end 411.601158 -363.193584)
		(width 0.254)
		(layer "F.Cu")
		(net "PVCCFA_EHV_FIVRA_CPU0_PVCC1")
	)
	(segment
		(start 422.361868 -362.296964)
		(end 423.07764 -363.012736)
		(width 0.2032)
		(layer "F.Cu")
		(net "PVCCFA_EHV_FIVRA_CPU0_PVCC1")
	)
	(segment
		(start 422.273984 -362.296964)
		(end 422.361868 -362.296964)
		(width 0.2032)
		(layer "F.Cu")
		(net "PVCCFA_EHV_FIVRA_CPU0_PVCC1")
	)
	(segment
		(start 422.273984 -362.912914)
		(end 422.273984 -362.296964)
		(width 0.2032)
		(layer "F.Cu")
		(net "PVCCFA_EHV_FIVRA_CPU0_PVCC1")
	)
	(segment
		(start 412.585662 -362.906564)
		(end 412.20517 -362.906564)
		(width 0.254)
		(layer "F.Cu")
		(net "PVCCFA_EHV_FIVRA_CPU0_PVCC1")
	)
	(segment
		(start 412.673546 -362.296964)
		(end 413.389318 -363.012736)
		(width 0.2032)
		(layer "F.Cu")
		(net "PVCCFA_EHV_FIVRA_CPU0_PVCC1")
	)
	(segment
		(start 412.20517 -362.906564)
		(end 411.91815 -363.193584)
		(width 0.254)
		(layer "F.Cu")
		(net "PVCCFA_EHV_FIVRA_CPU0_PVCC1")
	)
	(segment
		(start 412.585662 -362.296964)
		(end 412.673546 -362.296964)
		(width 0.2032)
		(layer "F.Cu")
		(net "PVCCFA_EHV_FIVRA_CPU0_PVCC1")
	)
	(segment
		(start 423.07764 -363.012736)
		(end 423.448734 -363.012736)
		(width 0.2032)
		(layer "F.Cu")
		(net "PVCCFA_EHV_FIVRA_CPU0_PVCC1")
	)
	(segment
		(start 413.389318 -363.012736)
		(end 413.760412 -363.012736)
		(width 0.2032)
		(layer "F.Cu")
		(net "PVCCFA_EHV_FIVRA_CPU0_PVCC1")
	)
	(segment
		(start 411.601158 -362.296964)
		(end 412.585662 -362.296964)
		(width 0.254)
		(layer "F.Cu")
		(net "PVCCFA_EHV_FIVRA_CPU0_PVCC1")
	)
	(via
		(at 412.585662 -362.906564)
		(size 0.508)
		(drill 0.254)
		(layers "F.Cu" "B.Cu")
		(net "PVCCFA_EHV_FIVRA_CPU0_PVCC1")
	)
	(via
		(at 422.273984 -362.912914)
		(size 0.508)
		(drill 0.254)
		(layers "F.Cu" "B.Cu")
		(net "PVCCFA_EHV_FIVRA_CPU0_PVCC1")
	)
	(segment
		(start 412.585662 -362.906564)
		(end 412.766764 -362.725208)
		(width 0.254)
		(layer "B.Cu")
		(net "PVCCFA_EHV_FIVRA_CPU0_PVCC1")
	)
	(segment
		(start 422.48836 -362.698538)
		(end 422.939718 -362.698538)
		(width 0.254)
		(layer "B.Cu")
		(net "PVCCFA_EHV_FIVRA_CPU0_PVCC1")
	)
	(segment
		(start 422.273984 -362.912914)
		(end 422.48836 -362.698538)
		(width 0.254)
		(layer "B.Cu")
		(net "PVCCFA_EHV_FIVRA_CPU0_PVCC1")
	)
	(segment
		(start 412.766764 -362.725208)
		(end 413.6644 -362.725208)
		(width 0.254)
		(layer "B.Cu")
		(net "PVCCFA_EHV_FIVRA_CPU0_PVCC1")
	)
	(segment
		(start 413.543496 -362.906564)
		(end 413.97428 -363.337348)
		(width 0.381)
		(layer "In4.Cu")
		(net "PVCCFA_EHV_FIVRA_CPU0_PVCC1")
	)
	(segment
		(start 416.03168 -363.337348)
		(end 416.48888 -362.880148)
		(width 0.381)
		(layer "In4.Cu")
		(net "PVCCFA_EHV_FIVRA_CPU0_PVCC1")
	)
	(segment
		(start 419.71468 -362.118148)
		(end 421.479218 -362.118148)
		(width 0.381)
		(layer "In4.Cu")
		(net "PVCCFA_EHV_FIVRA_CPU0_PVCC1")
	)
	(segment
		(start 416.48888 -362.880148)
		(end 418.95268 -362.880148)
		(width 0.381)
		(layer "In4.Cu")
		(net "PVCCFA_EHV_FIVRA_CPU0_PVCC1")
	)
	(segment
		(start 421.479218 -362.118148)
		(end 422.273984 -362.912914)
		(width 0.381)
		(layer "In4.Cu")
		(net "PVCCFA_EHV_FIVRA_CPU0_PVCC1")
	)
	(segment
		(start 412.585662 -362.906564)
		(end 413.543496 -362.906564)
		(width 0.381)
		(layer "In4.Cu")
		(net "PVCCFA_EHV_FIVRA_CPU0_PVCC1")
	)
	(segment
		(start 413.97428 -363.337348)
		(end 416.03168 -363.337348)
		(width 0.381)
		(layer "In4.Cu")
		(net "PVCCFA_EHV_FIVRA_CPU0_PVCC1")
	)
	(segment
		(start 418.95268 -362.880148)
		(end 419.71468 -362.118148)
		(width 0.381)
		(layer "In4.Cu")
		(net "PVCCFA_EHV_FIVRA_CPU0_PVCC1")
	)
	(segment
		(start 287.32353 -366.498632)
		(end 287.696148 -366.126014)
		(width 0.12954)
		(layer "F.Cu")
		(net "PVCCFA_EHV_FIVRA_CPU0_LSET4")
	)
	(segment
		(start 287.094676 -367.919508)
		(end 287.32353 -367.690654)
		(width 0.12954)
		(layer "F.Cu")
		(net "PVCCFA_EHV_FIVRA_CPU0_LSET4")
	)
	(segment
		(start 287.696148 -366.126014)
		(end 287.696148 -365.675418)
		(width 0.12954)
		(layer "F.Cu")
		(net "PVCCFA_EHV_FIVRA_CPU0_LSET4")
	)
	(segment
		(start 287.32353 -367.690654)
		(end 287.32353 -366.498632)
		(width 0.12954)
		(layer "F.Cu")
		(net "PVCCFA_EHV_FIVRA_CPU0_LSET4")
	)
	(segment
		(start 424.758866 -364.987586)
		(end 424.758866 -365.450882)
		(width 0.12954)
		(layer "F.Cu")
		(net "PVCCFA_EHV_FIVRA_CPU0_LSET3")
	)
	(segment
		(start 424.386248 -365.8235)
		(end 424.386248 -367.002822)
		(width 0.12954)
		(layer "F.Cu")
		(net "PVCCFA_EHV_FIVRA_CPU0_LSET3")
	)
	(segment
		(start 424.758866 -365.450882)
		(end 424.386248 -365.8235)
		(width 0.12954)
		(layer "F.Cu")
		(net "PVCCFA_EHV_FIVRA_CPU0_LSET3")
	)
	(segment
		(start 424.386248 -367.002822)
		(end 424.157394 -367.231676)
		(width 0.12954)
		(layer "F.Cu")
		(net "PVCCFA_EHV_FIVRA_CPU0_LSET3")
	)
	(segment
		(start 296.782998 -367.919508)
		(end 297.011852 -367.690654)
		(width 0.12954)
		(layer "F.Cu")
		(net "PVCCFA_EHV_FIVRA_CPU0_LSET2")
	)
	(segment
		(start 297.011852 -367.690654)
		(end 297.011852 -366.498632)
		(width 0.12954)
		(layer "F.Cu")
		(net "PVCCFA_EHV_FIVRA_CPU0_LSET2")
	)
	(segment
		(start 297.38447 -366.126014)
		(end 297.38447 -365.675418)
		(width 0.12954)
		(layer "F.Cu")
		(net "PVCCFA_EHV_FIVRA_CPU0_LSET2")
	)
	(segment
		(start 297.011852 -366.498632)
		(end 297.38447 -366.126014)
		(width 0.12954)
		(layer "F.Cu")
		(net "PVCCFA_EHV_FIVRA_CPU0_LSET2")
	)
	(segment
		(start 414.697926 -367.002822)
		(end 414.697926 -365.808768)
		(width 0.12954)
		(layer "F.Cu")
		(net "PVCCFA_EHV_FIVRA_CPU0_LSET1")
	)
	(segment
		(start 415.070544 -365.43615)
		(end 415.070544 -364.987586)
		(width 0.12954)
		(layer "F.Cu")
		(net "PVCCFA_EHV_FIVRA_CPU0_LSET1")
	)
	(segment
		(start 414.469072 -367.231676)
		(end 414.697926 -367.002822)
		(width 0.12954)
		(layer "F.Cu")
		(net "PVCCFA_EHV_FIVRA_CPU0_LSET1")
	)
	(segment
		(start 414.697926 -365.808768)
		(end 415.070544 -365.43615)
		(width 0.12954)
		(layer "F.Cu")
		(net "PVCCFA_EHV_FIVRA_CPU0_LSET1")
	)
	(segment
		(start 358.318308 -355.204014)
		(end 358.318308 -355.97338)
		(width 0.1778)
		(layer "F.Cu")
		(net "PVCCFA_EHV_FIVRA_CPU0_IMON4")
	)
	(segment
		(start 286.808926 -366.521492)
		(end 287.24606 -366.084358)
		(width 0.254)
		(layer "F.Cu")
		(net "PVCCFA_EHV_FIVRA_CPU0_IMON4")
	)
	(segment
		(start 359.992168 -354.14204)
		(end 359.380282 -354.14204)
		(width 0.1778)
		(layer "F.Cu")
		(net "PVCCFA_EHV_FIVRA_CPU0_IMON4")
	)
	(segment
		(start 287.24606 -366.084358)
		(end 287.24606 -365.675418)
		(width 0.254)
		(layer "F.Cu")
		(net "PVCCFA_EHV_FIVRA_CPU0_IMON4")
	)
	(segment
		(start 360.43997 -353.694238)
		(end 359.992168 -354.14204)
		(width 0.1778)
		(layer "F.Cu")
		(net "PVCCFA_EHV_FIVRA_CPU0_IMON4")
	)
	(segment
		(start 359.380282 -354.14204)
		(end 358.318308 -355.204014)
		(width 0.1778)
		(layer "F.Cu")
		(net "PVCCFA_EHV_FIVRA_CPU0_IMON4")
	)
	(via
		(at 360.43997 -353.694238)
		(size 0.508)
		(drill 0.254)
		(layers "F.Cu" "B.Cu")
		(net "PVCCFA_EHV_FIVRA_CPU0_IMON4")
	)
	(via
		(at 353.72548 -367.463832)
		(size 0.508)
		(drill 0.254)
		(layers "F.Cu" "B.Cu")
		(net "PVCCFA_EHV_FIVRA_CPU0_IMON4")
	)
	(via
		(at 286.808926 -366.521492)
		(size 0.508)
		(drill 0.254)
		(layers "F.Cu" "B.Cu")
		(net "PVCCFA_EHV_FIVRA_CPU0_IMON4")
	)
	(segment
		(start 286.79267 -366.505236)
		(end 286.209232 -366.505236)
		(width 0.254)
		(layer "B.Cu")
		(net "PVCCFA_EHV_FIVRA_CPU0_IMON4")
	)
	(segment
		(start 286.0294 -366.685068)
		(end 286.0294 -366.955578)
		(width 0.254)
		(layer "B.Cu")
		(net "PVCCFA_EHV_FIVRA_CPU0_IMON4")
	)
	(segment
		(start 286.808926 -366.521492)
		(end 286.79267 -366.505236)
		(width 0.254)
		(layer "B.Cu")
		(net "PVCCFA_EHV_FIVRA_CPU0_IMON4")
	)
	(segment
		(start 286.209232 -366.505236)
		(end 286.0294 -366.685068)
		(width 0.254)
		(layer "B.Cu")
		(net "PVCCFA_EHV_FIVRA_CPU0_IMON4")
	)
	(segment
		(start 350.172528 -352.947732)
		(end 349.13062 -353.98964)
		(width 0.254)
		(layer "In4.Cu")
		(net "PVCCFA_EHV_FIVRA_CPU0_IMON4")
	)
	(segment
		(start 355.774244 -352.947732)
		(end 350.172528 -352.947732)
		(width 0.254)
		(layer "In4.Cu")
		(net "PVCCFA_EHV_FIVRA_CPU0_IMON4")
	)
	(segment
		(start 351.155508 -364.593632)
		(end 352.981768 -364.593632)
		(width 0.254)
		(layer "In4.Cu")
		(net "PVCCFA_EHV_FIVRA_CPU0_IMON4")
	)
	(segment
		(start 353.46894 -365.080804)
		(end 353.46894 -367.207292)
		(width 0.254)
		(layer "In4.Cu")
		(net "PVCCFA_EHV_FIVRA_CPU0_IMON4")
	)
	(segment
		(start 356.968552 -354.14204)
		(end 355.774244 -352.947732)
		(width 0.254)
		(layer "In4.Cu")
		(net "PVCCFA_EHV_FIVRA_CPU0_IMON4")
	)
	(segment
		(start 352.981768 -364.593632)
		(end 353.46894 -365.080804)
		(width 0.254)
		(layer "In4.Cu")
		(net "PVCCFA_EHV_FIVRA_CPU0_IMON4")
	)
	(segment
		(start 349.13062 -362.568744)
		(end 351.155508 -364.593632)
		(width 0.254)
		(layer "In4.Cu")
		(net "PVCCFA_EHV_FIVRA_CPU0_IMON4")
	)
	(segment
		(start 360.43997 -353.694238)
		(end 359.992168 -354.14204)
		(width 0.254)
		(layer "In4.Cu")
		(net "PVCCFA_EHV_FIVRA_CPU0_IMON4")
	)
	(segment
		(start 353.46894 -367.207292)
		(end 353.72548 -367.463832)
		(width 0.254)
		(layer "In4.Cu")
		(net "PVCCFA_EHV_FIVRA_CPU0_IMON4")
	)
	(segment
		(start 359.992168 -354.14204)
		(end 356.968552 -354.14204)
		(width 0.254)
		(layer "In4.Cu")
		(net "PVCCFA_EHV_FIVRA_CPU0_IMON4")
	)
	(segment
		(start 349.13062 -353.98964)
		(end 349.13062 -362.568744)
		(width 0.254)
		(layer "In4.Cu")
		(net "PVCCFA_EHV_FIVRA_CPU0_IMON4")
	)
	(segment
		(start 306.123086 -377.865386)
		(end 288.322004 -377.865386)
		(width 0.254)
		(layer "In11.Cu")
		(net "PVCCFA_EHV_FIVRA_CPU0_IMON4")
	)
	(segment
		(start 353.72548 -367.463832)
		(end 353.72548 -368.120676)
		(width 0.254)
		(layer "In11.Cu")
		(net "PVCCFA_EHV_FIVRA_CPU0_IMON4")
	)
	(segment
		(start 283.797502 -373.340884)
		(end 283.797502 -369.227608)
		(width 0.254)
		(layer "In11.Cu")
		(net "PVCCFA_EHV_FIVRA_CPU0_IMON4")
	)
	(segment
		(start 283.797502 -369.227608)
		(end 286.256222 -366.768888)
		(width 0.254)
		(layer "In11.Cu")
		(net "PVCCFA_EHV_FIVRA_CPU0_IMON4")
	)
	(segment
		(start 353.72548 -368.120676)
		(end 347.941646 -373.90451)
		(width 0.254)
		(layer "In11.Cu")
		(net "PVCCFA_EHV_FIVRA_CPU0_IMON4")
	)
	(segment
		(start 286.56153 -366.768888)
		(end 286.808926 -366.521492)
		(width 0.254)
		(layer "In11.Cu")
		(net "PVCCFA_EHV_FIVRA_CPU0_IMON4")
	)
	(segment
		(start 288.322004 -377.865386)
		(end 283.797502 -373.340884)
		(width 0.254)
		(layer "In11.Cu")
		(net "PVCCFA_EHV_FIVRA_CPU0_IMON4")
	)
	(segment
		(start 310.083962 -373.90451)
		(end 306.123086 -377.865386)
		(width 0.254)
		(layer "In11.Cu")
		(net "PVCCFA_EHV_FIVRA_CPU0_IMON4")
	)
	(segment
		(start 347.941646 -373.90451)
		(end 310.083962 -373.90451)
		(width 0.254)
		(layer "In11.Cu")
		(net "PVCCFA_EHV_FIVRA_CPU0_IMON4")
	)
	(segment
		(start 286.256222 -366.768888)
		(end 286.56153 -366.768888)
		(width 0.254)
		(layer "In11.Cu")
		(net "PVCCFA_EHV_FIVRA_CPU0_IMON4")
	)
	(segment
		(start 359.56748 -354.749608)
		(end 358.718104 -355.598984)
		(width 0.1778)
		(layer "F.Cu")
		(net "PVCCFA_EHV_FIVRA_CPU0_IMON3")
	)
	(segment
		(start 423.871644 -365.83366)
		(end 424.308778 -365.396526)
		(width 0.2286)
		(layer "F.Cu")
		(net "PVCCFA_EHV_FIVRA_CPU0_IMON3")
	)
	(segment
		(start 424.308778 -365.396526)
		(end 424.308778 -364.987586)
		(width 0.2286)
		(layer "F.Cu")
		(net "PVCCFA_EHV_FIVRA_CPU0_IMON3")
	)
	(segment
		(start 358.718104 -355.598984)
		(end 358.718104 -355.97338)
		(width 0.1778)
		(layer "F.Cu")
		(net "PVCCFA_EHV_FIVRA_CPU0_IMON3")
	)
	(via
		(at 359.56748 -354.749608)
		(size 0.508)
		(drill 0.254)
		(layers "F.Cu" "B.Cu")
		(net "PVCCFA_EHV_FIVRA_CPU0_IMON3")
	)
	(via
		(at 423.871644 -365.83366)
		(size 0.508)
		(drill 0.254)
		(layers "F.Cu" "B.Cu")
		(net "PVCCFA_EHV_FIVRA_CPU0_IMON3")
	)
	(segment
		(start 358.340914 -355.128068)
		(end 357.368602 -356.10038)
		(width 0.254)
		(layer "B.Cu")
		(net "PVCCFA_EHV_FIVRA_CPU0_IMON3")
	)
	(segment
		(start 359.56748 -354.749608)
		(end 359.18902 -355.128068)
		(width 0.254)
		(layer "B.Cu")
		(net "PVCCFA_EHV_FIVRA_CPU0_IMON3")
	)
	(segment
		(start 359.18902 -355.128068)
		(end 358.340914 -355.128068)
		(width 0.254)
		(layer "B.Cu")
		(net "PVCCFA_EHV_FIVRA_CPU0_IMON3")
	)
	(segment
		(start 365.675164 -367.26241)
		(end 358.411018 -367.26241)
		(width 0.254)
		(layer "In6.Cu")
		(net "PVCCFA_EHV_FIVRA_CPU0_IMON3")
	)
	(segment
		(start 423.636694 -366.06861)
		(end 423.414698 -366.06861)
		(width 0.254)
		(layer "In6.Cu")
		(net "PVCCFA_EHV_FIVRA_CPU0_IMON3")
	)
	(segment
		(start 357.241348 -366.09274)
		(end 357.241348 -363.060996)
		(width 0.254)
		(layer "In6.Cu")
		(net "PVCCFA_EHV_FIVRA_CPU0_IMON3")
	)
	(segment
		(start 355.89464 -361.714288)
		(end 355.89464 -356.151434)
		(width 0.254)
		(layer "In6.Cu")
		(net "PVCCFA_EHV_FIVRA_CPU0_IMON3")
	)
	(segment
		(start 357.241348 -363.060996)
		(end 355.89464 -361.714288)
		(width 0.254)
		(layer "In6.Cu")
		(net "PVCCFA_EHV_FIVRA_CPU0_IMON3")
	)
	(segment
		(start 428.274988 -374.125744)
		(end 425.463462 -376.93727)
		(width 0.254)
		(layer "In6.Cu")
		(net "PVCCFA_EHV_FIVRA_CPU0_IMON3")
	)
	(segment
		(start 359.21696 -355.100128)
		(end 359.56748 -354.749608)
		(width 0.254)
		(layer "In6.Cu")
		(net "PVCCFA_EHV_FIVRA_CPU0_IMON3")
	)
	(segment
		(start 427.6598 -369.465352)
		(end 428.274988 -370.08054)
		(width 0.254)
		(layer "In6.Cu")
		(net "PVCCFA_EHV_FIVRA_CPU0_IMON3")
	)
	(segment
		(start 428.274988 -370.08054)
		(end 428.274988 -374.125744)
		(width 0.254)
		(layer "In6.Cu")
		(net "PVCCFA_EHV_FIVRA_CPU0_IMON3")
	)
	(segment
		(start 423.81678 -369.465352)
		(end 427.6598 -369.465352)
		(width 0.254)
		(layer "In6.Cu")
		(net "PVCCFA_EHV_FIVRA_CPU0_IMON3")
	)
	(segment
		(start 355.89464 -356.151434)
		(end 356.945946 -355.100128)
		(width 0.254)
		(layer "In6.Cu")
		(net "PVCCFA_EHV_FIVRA_CPU0_IMON3")
	)
	(segment
		(start 375.350024 -376.93727)
		(end 365.675164 -367.26241)
		(width 0.254)
		(layer "In6.Cu")
		(net "PVCCFA_EHV_FIVRA_CPU0_IMON3")
	)
	(segment
		(start 356.945946 -355.100128)
		(end 359.21696 -355.100128)
		(width 0.254)
		(layer "In6.Cu")
		(net "PVCCFA_EHV_FIVRA_CPU0_IMON3")
	)
	(segment
		(start 423.871644 -365.83366)
		(end 423.636694 -366.06861)
		(width 0.254)
		(layer "In6.Cu")
		(net "PVCCFA_EHV_FIVRA_CPU0_IMON3")
	)
	(segment
		(start 358.411018 -367.26241)
		(end 357.241348 -366.09274)
		(width 0.254)
		(layer "In6.Cu")
		(net "PVCCFA_EHV_FIVRA_CPU0_IMON3")
	)
	(segment
		(start 422.612058 -368.26063)
		(end 423.81678 -369.465352)
		(width 0.254)
		(layer "In6.Cu")
		(net "PVCCFA_EHV_FIVRA_CPU0_IMON3")
	)
	(segment
		(start 423.414698 -366.06861)
		(end 422.612058 -366.87125)
		(width 0.254)
		(layer "In6.Cu")
		(net "PVCCFA_EHV_FIVRA_CPU0_IMON3")
	)
	(segment
		(start 422.612058 -366.87125)
		(end 422.612058 -368.26063)
		(width 0.254)
		(layer "In6.Cu")
		(net "PVCCFA_EHV_FIVRA_CPU0_IMON3")
	)
	(segment
		(start 425.463462 -376.93727)
		(end 375.350024 -376.93727)
		(width 0.254)
		(layer "In6.Cu")
		(net "PVCCFA_EHV_FIVRA_CPU0_IMON3")
	)
	(segment
		(start 359.247948 -356.156514)
		(end 359.393236 -356.301802)
		(width 0.1778)
		(layer "F.Cu")
		(net "PVCCFA_EHV_FIVRA_CPU0_IMON2")
	)
	(segment
		(start 296.934382 -366.084358)
		(end 296.934382 -365.675418)
		(width 0.2286)
		(layer "F.Cu")
		(net "PVCCFA_EHV_FIVRA_CPU0_IMON2")
	)
	(segment
		(start 296.497248 -366.521492)
		(end 296.934382 -366.084358)
		(width 0.2286)
		(layer "F.Cu")
		(net "PVCCFA_EHV_FIVRA_CPU0_IMON2")
	)
	(segment
		(start 359.393236 -356.301802)
		(end 359.393236 -356.648512)
		(width 0.1778)
		(layer "F.Cu")
		(net "PVCCFA_EHV_FIVRA_CPU0_IMON2")
	)
	(via
		(at 356.536498 -366.956594)
		(size 0.508)
		(drill 0.254)
		(layers "F.Cu" "B.Cu")
		(net "PVCCFA_EHV_FIVRA_CPU0_IMON2")
	)
	(via
		(at 359.247948 -356.156514)
		(size 0.508)
		(drill 0.254)
		(layers "F.Cu" "B.Cu")
		(net "PVCCFA_EHV_FIVRA_CPU0_IMON2")
	)
	(via
		(at 296.497248 -366.521492)
		(size 0.508)
		(drill 0.254)
		(layers "F.Cu" "B.Cu")
		(net "PVCCFA_EHV_FIVRA_CPU0_IMON2")
	)
	(segment
		(start 356.536498 -366.956594)
		(end 356.28326 -366.703356)
		(width 0.254)
		(layer "In4.Cu")
		(net "PVCCFA_EHV_FIVRA_CPU0_IMON2")
	)
	(segment
		(start 357.62184 -356.5652)
		(end 358.030526 -356.156514)
		(width 0.254)
		(layer "In4.Cu")
		(net "PVCCFA_EHV_FIVRA_CPU0_IMON2")
	)
	(segment
		(start 357.15194 -365.043212)
		(end 357.15194 -362.64088)
		(width 0.254)
		(layer "In4.Cu")
		(net "PVCCFA_EHV_FIVRA_CPU0_IMON2")
	)
	(segment
		(start 356.28326 -366.703356)
		(end 356.28326 -365.911892)
		(width 0.254)
		(layer "In4.Cu")
		(net "PVCCFA_EHV_FIVRA_CPU0_IMON2")
	)
	(segment
		(start 357.15194 -362.64088)
		(end 357.62184 -362.17098)
		(width 0.254)
		(layer "In4.Cu")
		(net "PVCCFA_EHV_FIVRA_CPU0_IMON2")
	)
	(segment
		(start 356.28326 -365.911892)
		(end 357.15194 -365.043212)
		(width 0.254)
		(layer "In4.Cu")
		(net "PVCCFA_EHV_FIVRA_CPU0_IMON2")
	)
	(segment
		(start 358.030526 -356.156514)
		(end 359.247948 -356.156514)
		(width 0.254)
		(layer "In4.Cu")
		(net "PVCCFA_EHV_FIVRA_CPU0_IMON2")
	)
	(segment
		(start 357.62184 -362.17098)
		(end 357.62184 -356.5652)
		(width 0.254)
		(layer "In4.Cu")
		(net "PVCCFA_EHV_FIVRA_CPU0_IMON2")
	)
	(segment
		(start 355.754432 -366.174528)
		(end 356.536498 -366.956594)
		(width 0.254)
		(layer "In11.Cu")
		(net "PVCCFA_EHV_FIVRA_CPU0_IMON2")
	)
	(segment
		(start 296.497248 -366.521492)
		(end 296.589704 -366.521492)
		(width 0.254)
		(layer "In11.Cu")
		(net "PVCCFA_EHV_FIVRA_CPU0_IMON2")
	)
	(segment
		(start 347.86062 -366.174528)
		(end 355.754432 -366.174528)
		(width 0.254)
		(layer "In11.Cu")
		(net "PVCCFA_EHV_FIVRA_CPU0_IMON2")
	)
	(segment
		(start 297.007788 -368.407696)
		(end 299.2882 -370.688108)
		(width 0.254)
		(layer "In11.Cu")
		(net "PVCCFA_EHV_FIVRA_CPU0_IMON2")
	)
	(segment
		(start 347.35262 -365.666528)
		(end 347.86062 -366.174528)
		(width 0.254)
		(layer "In11.Cu")
		(net "PVCCFA_EHV_FIVRA_CPU0_IMON2")
	)
	(segment
		(start 299.2882 -370.688108)
		(end 339.83422 -370.688108)
		(width 0.254)
		(layer "In11.Cu")
		(net "PVCCFA_EHV_FIVRA_CPU0_IMON2")
	)
	(segment
		(start 344.8558 -365.666528)
		(end 347.35262 -365.666528)
		(width 0.254)
		(layer "In11.Cu")
		(net "PVCCFA_EHV_FIVRA_CPU0_IMON2")
	)
	(segment
		(start 297.007788 -366.939576)
		(end 297.007788 -368.407696)
		(width 0.254)
		(layer "In11.Cu")
		(net "PVCCFA_EHV_FIVRA_CPU0_IMON2")
	)
	(segment
		(start 296.589704 -366.521492)
		(end 297.007788 -366.939576)
		(width 0.254)
		(layer "In11.Cu")
		(net "PVCCFA_EHV_FIVRA_CPU0_IMON2")
	)
	(segment
		(start 339.83422 -370.688108)
		(end 344.8558 -365.666528)
		(width 0.254)
		(layer "In11.Cu")
		(net "PVCCFA_EHV_FIVRA_CPU0_IMON2")
	)
	(segment
		(start 360.67873 -354.962968)
		(end 359.943654 -355.698044)
		(width 0.1778)
		(layer "F.Cu")
		(net "PVCCFA_EHV_FIVRA_CPU0_IMON1")
	)
	(segment
		(start 359.738168 -357.048308)
		(end 359.393236 -357.048308)
		(width 0.1778)
		(layer "F.Cu")
		(net "PVCCFA_EHV_FIVRA_CPU0_IMON1")
	)
	(segment
		(start 359.943654 -355.698044)
		(end 359.943654 -356.776782)
		(width 0.1778)
		(layer "F.Cu")
		(net "PVCCFA_EHV_FIVRA_CPU0_IMON1")
	)
	(segment
		(start 359.896918 -356.889558)
		(end 359.738168 -357.048308)
		(width 0.1778)
		(layer "F.Cu")
		(net "PVCCFA_EHV_FIVRA_CPU0_IMON1")
	)
	(segment
		(start 359.943654 -356.776782)
		(end 359.896918 -356.889558)
		(width 0.1778)
		(layer "F.Cu")
		(net "PVCCFA_EHV_FIVRA_CPU0_IMON1")
	)
	(segment
		(start 414.183322 -365.83366)
		(end 414.620456 -365.396526)
		(width 0.254)
		(layer "F.Cu")
		(net "PVCCFA_EHV_FIVRA_CPU0_IMON1")
	)
	(segment
		(start 414.620456 -365.396526)
		(end 414.620456 -364.987586)
		(width 0.254)
		(layer "F.Cu")
		(net "PVCCFA_EHV_FIVRA_CPU0_IMON1")
	)
	(via
		(at 360.67873 -354.962968)
		(size 0.508)
		(drill 0.254)
		(layers "F.Cu" "B.Cu")
		(net "PVCCFA_EHV_FIVRA_CPU0_IMON1")
	)
	(via
		(at 414.183322 -365.83366)
		(size 0.508)
		(drill 0.254)
		(layers "F.Cu" "B.Cu")
		(net "PVCCFA_EHV_FIVRA_CPU0_IMON1")
	)
	(segment
		(start 374.682766 -355.903022)
		(end 373.549418 -354.769674)
		(width 0.254)
		(layer "In6.Cu")
		(net "PVCCFA_EHV_FIVRA_CPU0_IMON1")
	)
	(segment
		(start 373.549418 -354.769674)
		(end 372.044722 -354.769674)
		(width 0.254)
		(layer "In6.Cu")
		(net "PVCCFA_EHV_FIVRA_CPU0_IMON1")
	)
	(segment
		(start 366.166146 -355.922326)
		(end 362.282994 -355.922326)
		(width 0.254)
		(layer "In6.Cu")
		(net "PVCCFA_EHV_FIVRA_CPU0_IMON1")
	)
	(segment
		(start 371.303804 -354.028756)
		(end 368.059716 -354.028756)
		(width 0.254)
		(layer "In6.Cu")
		(net "PVCCFA_EHV_FIVRA_CPU0_IMON1")
	)
	(segment
		(start 414.183322 -365.83366)
		(end 413.815022 -365.986314)
		(width 0.254)
		(layer "In6.Cu")
		(net "PVCCFA_EHV_FIVRA_CPU0_IMON1")
	)
	(segment
		(start 413.815022 -365.986314)
		(end 410.668724 -369.132612)
		(width 0.254)
		(layer "In6.Cu")
		(net "PVCCFA_EHV_FIVRA_CPU0_IMON1")
	)
	(segment
		(start 360.868468 -355.336856)
		(end 360.67873 -355.147118)
		(width 0.254)
		(layer "In6.Cu")
		(net "PVCCFA_EHV_FIVRA_CPU0_IMON1")
	)
	(segment
		(start 368.059716 -354.028756)
		(end 366.166146 -355.922326)
		(width 0.254)
		(layer "In6.Cu")
		(net "PVCCFA_EHV_FIVRA_CPU0_IMON1")
	)
	(segment
		(start 392.411712 -369.132612)
		(end 379.182122 -355.903022)
		(width 0.254)
		(layer "In6.Cu")
		(net "PVCCFA_EHV_FIVRA_CPU0_IMON1")
	)
	(segment
		(start 410.668724 -369.132612)
		(end 392.411712 -369.132612)
		(width 0.254)
		(layer "In6.Cu")
		(net "PVCCFA_EHV_FIVRA_CPU0_IMON1")
	)
	(segment
		(start 360.67873 -355.147118)
		(end 360.67873 -354.962968)
		(width 0.254)
		(layer "In6.Cu")
		(net "PVCCFA_EHV_FIVRA_CPU0_IMON1")
	)
	(segment
		(start 372.044722 -354.769674)
		(end 371.303804 -354.028756)
		(width 0.254)
		(layer "In6.Cu")
		(net "PVCCFA_EHV_FIVRA_CPU0_IMON1")
	)
	(segment
		(start 362.282994 -355.922326)
		(end 360.868468 -355.336856)
		(width 0.254)
		(layer "In6.Cu")
		(net "PVCCFA_EHV_FIVRA_CPU0_IMON1")
	)
	(segment
		(start 379.182122 -355.903022)
		(end 374.682766 -355.903022)
		(width 0.254)
		(layer "In6.Cu")
		(net "PVCCFA_EHV_FIVRA_CPU0_IMON1")
	)
	(segment
		(start 353.643184 -356.648512)
		(end 353.643184 -354.89769)
		(width 0.1778)
		(layer "F.Cu")
		(net "PVCCFA_EHV_FIVRA_CPU0_EN_R")
	)
	(segment
		(start 353.643184 -354.89769)
		(end 353.190302 -354.444808)
		(width 0.1778)
		(layer "F.Cu")
		(net "PVCCFA_EHV_FIVRA_CPU0_EN_R")
	)
	(segment
		(start 352.739198 -354.895912)
		(end 352.089974 -354.895912)
		(width 0.1778)
		(layer "F.Cu")
		(net "PVCCFA_EHV_FIVRA_CPU0_EN_R")
	)
	(segment
		(start 351.202498 -354.883212)
		(end 351.215198 -354.895912)
		(width 0.1778)
		(layer "F.Cu")
		(net "PVCCFA_EHV_FIVRA_CPU0_EN_R")
	)
	(segment
		(start 351.116138 -354.883212)
		(end 351.202498 -354.883212)
		(width 0.1778)
		(layer "F.Cu")
		(net "PVCCFA_EHV_FIVRA_CPU0_EN_R")
	)
	(segment
		(start 351.215198 -354.895912)
		(end 352.089974 -354.895912)
		(width 0.1778)
		(layer "F.Cu")
		(net "PVCCFA_EHV_FIVRA_CPU0_EN_R")
	)
	(segment
		(start 353.190302 -354.444808)
		(end 352.739198 -354.895912)
		(width 0.1778)
		(layer "F.Cu")
		(net "PVCCFA_EHV_FIVRA_CPU0_EN_R")
	)
	(via
		(at 353.190302 -354.444808)
		(size 0.508)
		(drill 0.254)
		(layers "F.Cu" "B.Cu")
		(net "PVCCFA_EHV_FIVRA_CPU0_EN_R")
	)
	(segment
		(start 297.834304 -366.126014)
		(end 297.834304 -365.675418)
		(width 0.1778)
		(layer "F.Cu")
		(net "PVCCFA_EHV_FIVRA_CPU0_BTSEN")
	)
	(segment
		(start 415.199322 -365.759238)
		(end 415.520378 -365.438182)
		(width 0.1778)
		(layer "F.Cu")
		(net "PVCCFA_EHV_FIVRA_CPU0_BTSEN")
	)
	(segment
		(start 297.520868 -367.1951)
		(end 297.520868 -366.43945)
		(width 0.1778)
		(layer "F.Cu")
		(net "PVCCFA_EHV_FIVRA_CPU0_BTSEN")
	)
	(segment
		(start 361.05592 -359.600754)
		(end 361.05592 -359.595674)
		(width 0.254)
		(layer "F.Cu")
		(net "PVCCFA_EHV_FIVRA_CPU0_BTSEN")
	)
	(segment
		(start 360.349292 -359.448354)
		(end 360.501692 -359.600754)
		(width 0.1778)
		(layer "F.Cu")
		(net "PVCCFA_EHV_FIVRA_CPU0_BTSEN")
	)
	(segment
		(start 424.887644 -366.517428)
		(end 424.887644 -365.758984)
		(width 0.1778)
		(layer "F.Cu")
		(net "PVCCFA_EHV_FIVRA_CPU0_BTSEN")
	)
	(segment
		(start 425.2087 -365.437928)
		(end 425.2087 -364.987586)
		(width 0.1778)
		(layer "F.Cu")
		(net "PVCCFA_EHV_FIVRA_CPU0_BTSEN")
	)
	(segment
		(start 288.145982 -366.126014)
		(end 288.145982 -365.675418)
		(width 0.1778)
		(layer "F.Cu")
		(net "PVCCFA_EHV_FIVRA_CPU0_BTSEN")
	)
	(segment
		(start 360.501692 -359.600754)
		(end 361.05592 -359.600754)
		(width 0.1778)
		(layer "F.Cu")
		(net "PVCCFA_EHV_FIVRA_CPU0_BTSEN")
	)
	(segment
		(start 297.520868 -366.43945)
		(end 297.834304 -366.126014)
		(width 0.1778)
		(layer "F.Cu")
		(net "PVCCFA_EHV_FIVRA_CPU0_BTSEN")
	)
	(segment
		(start 361.05592 -359.600754)
		(end 361.579414 -359.600754)
		(width 0.254)
		(layer "F.Cu")
		(net "PVCCFA_EHV_FIVRA_CPU0_BTSEN")
	)
	(segment
		(start 415.520378 -365.438182)
		(end 415.520378 -364.987586)
		(width 0.1778)
		(layer "F.Cu")
		(net "PVCCFA_EHV_FIVRA_CPU0_BTSEN")
	)
	(segment
		(start 287.824926 -367.20526)
		(end 287.824926 -366.44707)
		(width 0.1778)
		(layer "F.Cu")
		(net "PVCCFA_EHV_FIVRA_CPU0_BTSEN")
	)
	(segment
		(start 287.824926 -366.44707)
		(end 288.145982 -366.126014)
		(width 0.1778)
		(layer "F.Cu")
		(net "PVCCFA_EHV_FIVRA_CPU0_BTSEN")
	)
	(segment
		(start 415.199322 -366.517428)
		(end 415.199322 -365.759238)
		(width 0.1778)
		(layer "F.Cu")
		(net "PVCCFA_EHV_FIVRA_CPU0_BTSEN")
	)
	(segment
		(start 359.393236 -359.448354)
		(end 360.349292 -359.448354)
		(width 0.1778)
		(layer "F.Cu")
		(net "PVCCFA_EHV_FIVRA_CPU0_BTSEN")
	)
	(segment
		(start 424.887644 -365.758984)
		(end 425.2087 -365.437928)
		(width 0.1778)
		(layer "F.Cu")
		(net "PVCCFA_EHV_FIVRA_CPU0_BTSEN")
	)
	(segment
		(start 361.579414 -359.600754)
		(end 362.246418 -358.93375)
		(width 0.254)
		(layer "F.Cu")
		(net "PVCCFA_EHV_FIVRA_CPU0_BTSEN")
	)
	(via
		(at 424.887644 -366.517428)
		(size 0.508)
		(drill 0.254)
		(layers "F.Cu" "B.Cu")
		(net "PVCCFA_EHV_FIVRA_CPU0_BTSEN")
	)
	(via
		(at 361.05592 -359.595674)
		(size 0.762)
		(drill 0.254)
		(layers "F.Cu" "B.Cu")
		(net "PVCCFA_EHV_FIVRA_CPU0_BTSEN")
	)
	(via
		(at 415.199322 -366.517428)
		(size 0.508)
		(drill 0.254)
		(layers "F.Cu" "B.Cu")
		(net "PVCCFA_EHV_FIVRA_CPU0_BTSEN")
	)
	(via
		(at 287.824926 -367.20526)
		(size 0.508)
		(drill 0.254)
		(layers "F.Cu" "B.Cu")
		(net "PVCCFA_EHV_FIVRA_CPU0_BTSEN")
	)
	(via
		(at 346.05214 -367.099088)
		(size 0.508)
		(drill 0.254)
		(layers "F.Cu" "B.Cu")
		(net "PVCCFA_EHV_FIVRA_CPU0_BTSEN")
	)
	(via
		(at 297.520868 -367.1951)
		(size 0.508)
		(drill 0.254)
		(layers "F.Cu" "B.Cu")
		(net "PVCCFA_EHV_FIVRA_CPU0_BTSEN")
	)
	(segment
		(start 359.982262 -358.522016)
		(end 359.83037 -358.522016)
		(width 0.254)
		(layer "B.Cu")
		(net "PVCCFA_EHV_FIVRA_CPU0_BTSEN")
	)
	(segment
		(start 361.05592 -359.595674)
		(end 359.982262 -358.522016)
		(width 0.254)
		(layer "B.Cu")
		(net "PVCCFA_EHV_FIVRA_CPU0_BTSEN")
	)
	(segment
		(start 363.082078 -360.819446)
		(end 361.858306 -359.595674)
		(width 0.254)
		(layer "In4.Cu")
		(net "PVCCFA_EHV_FIVRA_CPU0_BTSEN")
	)
	(segment
		(start 415.199322 -367.17097)
		(end 415.199322 -366.517428)
		(width 0.254)
		(layer "In4.Cu")
		(net "PVCCFA_EHV_FIVRA_CPU0_BTSEN")
	)
	(segment
		(start 288.161222 -368.315748)
		(end 287.824926 -367.979452)
		(width 0.254)
		(layer "In4.Cu")
		(net "PVCCFA_EHV_FIVRA_CPU0_BTSEN")
	)
	(segment
		(start 363.77372 -363.90326)
		(end 363.082078 -363.211618)
		(width 0.254)
		(layer "In4.Cu")
		(net "PVCCFA_EHV_FIVRA_CPU0_BTSEN")
	)
	(segment
		(start 361.858306 -359.595674)
		(end 361.05592 -359.595674)
		(width 0.254)
		(layer "In4.Cu")
		(net "PVCCFA_EHV_FIVRA_CPU0_BTSEN")
	)
	(segment
		(start 415.7853 -367.756948)
		(end 415.199322 -367.17097)
		(width 0.254)
		(layer "In4.Cu")
		(net "PVCCFA_EHV_FIVRA_CPU0_BTSEN")
	)
	(segment
		(start 295.057068 -368.633248)
		(end 295.057068 -368.092228)
		(width 0.254)
		(layer "In4.Cu")
		(net "PVCCFA_EHV_FIVRA_CPU0_BTSEN")
	)
	(segment
		(start 350.855026 -366.301274)
		(end 354.28174 -369.727988)
		(width 0.254)
		(layer "In4.Cu")
		(net "PVCCFA_EHV_FIVRA_CPU0_BTSEN")
	)
	(segment
		(start 297.520868 -367.1951)
		(end 297.320208 -367.39576)
		(width 0.254)
		(layer "In4.Cu")
		(net "PVCCFA_EHV_FIVRA_CPU0_BTSEN")
	)
	(segment
		(start 424.2435 -368.203988)
		(end 423.27068 -368.203988)
		(width 0.254)
		(layer "In4.Cu")
		(net "PVCCFA_EHV_FIVRA_CPU0_BTSEN")
	)
	(segment
		(start 424.887644 -366.517428)
		(end 424.887644 -367.559844)
		(width 0.254)
		(layer "In4.Cu")
		(net "PVCCFA_EHV_FIVRA_CPU0_BTSEN")
	)
	(segment
		(start 424.887644 -367.559844)
		(end 424.2435 -368.203988)
		(width 0.254)
		(layer "In4.Cu")
		(net "PVCCFA_EHV_FIVRA_CPU0_BTSEN")
	)
	(segment
		(start 419.14572 -367.121948)
		(end 418.51072 -367.756948)
		(width 0.254)
		(layer "In4.Cu")
		(net "PVCCFA_EHV_FIVRA_CPU0_BTSEN")
	)
	(segment
		(start 423.27068 -368.203988)
		(end 422.18864 -367.121948)
		(width 0.254)
		(layer "In4.Cu")
		(net "PVCCFA_EHV_FIVRA_CPU0_BTSEN")
	)
	(segment
		(start 293.990268 -367.673128)
		(end 293.347648 -368.315748)
		(width 0.254)
		(layer "In4.Cu")
		(net "PVCCFA_EHV_FIVRA_CPU0_BTSEN")
	)
	(segment
		(start 360.67746 -369.727988)
		(end 363.77372 -366.631728)
		(width 0.254)
		(layer "In4.Cu")
		(net "PVCCFA_EHV_FIVRA_CPU0_BTSEN")
	)
	(segment
		(start 296.194988 -368.932968)
		(end 295.356788 -368.932968)
		(width 0.254)
		(layer "In4.Cu")
		(net "PVCCFA_EHV_FIVRA_CPU0_BTSEN")
	)
	(segment
		(start 346.05214 -367.099088)
		(end 346.849954 -366.301274)
		(width 0.254)
		(layer "In4.Cu")
		(net "PVCCFA_EHV_FIVRA_CPU0_BTSEN")
	)
	(segment
		(start 293.347648 -368.315748)
		(end 288.161222 -368.315748)
		(width 0.254)
		(layer "In4.Cu")
		(net "PVCCFA_EHV_FIVRA_CPU0_BTSEN")
	)
	(segment
		(start 287.824926 -367.979452)
		(end 287.824926 -367.20526)
		(width 0.254)
		(layer "In4.Cu")
		(net "PVCCFA_EHV_FIVRA_CPU0_BTSEN")
	)
	(segment
		(start 422.18864 -367.121948)
		(end 419.14572 -367.121948)
		(width 0.254)
		(layer "In4.Cu")
		(net "PVCCFA_EHV_FIVRA_CPU0_BTSEN")
	)
	(segment
		(start 295.057068 -368.092228)
		(end 294.637968 -367.673128)
		(width 0.254)
		(layer "In4.Cu")
		(net "PVCCFA_EHV_FIVRA_CPU0_BTSEN")
	)
	(segment
		(start 297.320208 -367.807748)
		(end 296.194988 -368.932968)
		(width 0.254)
		(layer "In4.Cu")
		(net "PVCCFA_EHV_FIVRA_CPU0_BTSEN")
	)
	(segment
		(start 297.320208 -367.39576)
		(end 297.320208 -367.807748)
		(width 0.254)
		(layer "In4.Cu")
		(net "PVCCFA_EHV_FIVRA_CPU0_BTSEN")
	)
	(segment
		(start 295.356788 -368.932968)
		(end 295.057068 -368.633248)
		(width 0.254)
		(layer "In4.Cu")
		(net "PVCCFA_EHV_FIVRA_CPU0_BTSEN")
	)
	(segment
		(start 363.77372 -366.631728)
		(end 363.77372 -363.90326)
		(width 0.254)
		(layer "In4.Cu")
		(net "PVCCFA_EHV_FIVRA_CPU0_BTSEN")
	)
	(segment
		(start 418.51072 -367.756948)
		(end 415.7853 -367.756948)
		(width 0.254)
		(layer "In4.Cu")
		(net "PVCCFA_EHV_FIVRA_CPU0_BTSEN")
	)
	(segment
		(start 363.082078 -363.211618)
		(end 363.082078 -360.819446)
		(width 0.254)
		(layer "In4.Cu")
		(net "PVCCFA_EHV_FIVRA_CPU0_BTSEN")
	)
	(segment
		(start 294.637968 -367.673128)
		(end 293.990268 -367.673128)
		(width 0.254)
		(layer "In4.Cu")
		(net "PVCCFA_EHV_FIVRA_CPU0_BTSEN")
	)
	(segment
		(start 354.28174 -369.727988)
		(end 360.67746 -369.727988)
		(width 0.254)
		(layer "In4.Cu")
		(net "PVCCFA_EHV_FIVRA_CPU0_BTSEN")
	)
	(segment
		(start 346.849954 -366.301274)
		(end 350.855026 -366.301274)
		(width 0.254)
		(layer "In4.Cu")
		(net "PVCCFA_EHV_FIVRA_CPU0_BTSEN")
	)
	(segment
		(start 368.434874 -363.30255)
		(end 368.110516 -362.978192)
		(width 0.254)
		(layer "In6.Cu")
		(net "PVCCFA_EHV_FIVRA_CPU0_BTSEN")
	)
	(segment
		(start 363.0041 -363.200696)
		(end 363.0041 -361.195112)
		(width 0.254)
		(layer "In6.Cu")
		(net "PVCCFA_EHV_FIVRA_CPU0_BTSEN")
	)
	(segment
		(start 364.7313 -363.993176)
		(end 363.79658 -363.993176)
		(width 0.254)
		(layer "In6.Cu")
		(net "PVCCFA_EHV_FIVRA_CPU0_BTSEN")
	)
	(segment
		(start 332.77302 -367.099088)
		(end 331.5589 -368.313208)
		(width 0.254)
		(layer "In6.Cu")
		(net "PVCCFA_EHV_FIVRA_CPU0_BTSEN")
	)
	(segment
		(start 346.05214 -367.099088)
		(end 332.77302 -367.099088)
		(width 0.254)
		(layer "In6.Cu")
		(net "PVCCFA_EHV_FIVRA_CPU0_BTSEN")
	)
	(segment
		(start 390.166098 -370.27739)
		(end 383.191258 -363.30255)
		(width 0.254)
		(layer "In6.Cu")
		(net "PVCCFA_EHV_FIVRA_CPU0_BTSEN")
	)
	(segment
		(start 365.746284 -362.978192)
		(end 364.7313 -363.993176)
		(width 0.254)
		(layer "In6.Cu")
		(net "PVCCFA_EHV_FIVRA_CPU0_BTSEN")
	)
	(segment
		(start 363.79658 -363.993176)
		(end 363.0041 -363.200696)
		(width 0.254)
		(layer "In6.Cu")
		(net "PVCCFA_EHV_FIVRA_CPU0_BTSEN")
	)
	(segment
		(start 297.520868 -367.813336)
		(end 297.520868 -367.1951)
		(width 0.254)
		(layer "In6.Cu")
		(net "PVCCFA_EHV_FIVRA_CPU0_BTSEN")
	)
	(segment
		(start 331.5589 -368.313208)
		(end 298.02074 -368.313208)
		(width 0.254)
		(layer "In6.Cu")
		(net "PVCCFA_EHV_FIVRA_CPU0_BTSEN")
	)
	(segment
		(start 298.02074 -368.313208)
		(end 297.520868 -367.813336)
		(width 0.254)
		(layer "In6.Cu")
		(net "PVCCFA_EHV_FIVRA_CPU0_BTSEN")
	)
	(segment
		(start 361.404662 -359.595674)
		(end 361.05592 -359.595674)
		(width 0.254)
		(layer "In6.Cu")
		(net "PVCCFA_EHV_FIVRA_CPU0_BTSEN")
	)
	(segment
		(start 368.110516 -362.978192)
		(end 365.746284 -362.978192)
		(width 0.254)
		(layer "In6.Cu")
		(net "PVCCFA_EHV_FIVRA_CPU0_BTSEN")
	)
	(segment
		(start 413.757618 -368.27841)
		(end 413.155638 -368.27841)
		(width 0.254)
		(layer "In6.Cu")
		(net "PVCCFA_EHV_FIVRA_CPU0_BTSEN")
	)
	(segment
		(start 411.156658 -370.27739)
		(end 390.166098 -370.27739)
		(width 0.254)
		(layer "In6.Cu")
		(net "PVCCFA_EHV_FIVRA_CPU0_BTSEN")
	)
	(segment
		(start 415.199322 -366.836706)
		(end 413.757618 -368.27841)
		(width 0.254)
		(layer "In6.Cu")
		(net "PVCCFA_EHV_FIVRA_CPU0_BTSEN")
	)
	(segment
		(start 415.199322 -366.517428)
		(end 415.199322 -366.836706)
		(width 0.254)
		(layer "In6.Cu")
		(net "PVCCFA_EHV_FIVRA_CPU0_BTSEN")
	)
	(segment
		(start 363.0041 -361.195112)
		(end 361.404662 -359.595674)
		(width 0.254)
		(layer "In6.Cu")
		(net "PVCCFA_EHV_FIVRA_CPU0_BTSEN")
	)
	(segment
		(start 383.191258 -363.30255)
		(end 368.434874 -363.30255)
		(width 0.254)
		(layer "In6.Cu")
		(net "PVCCFA_EHV_FIVRA_CPU0_BTSEN")
	)
	(segment
		(start 413.155638 -368.27841)
		(end 411.156658 -370.27739)
		(width 0.254)
		(layer "In6.Cu")
		(net "PVCCFA_EHV_FIVRA_CPU0_BTSEN")
	)
	(segment
		(start 342.194134 -225.203512)
		(end 342.19388 -225.203258)
		(width 0.254)
		(layer "F.Cu")
		(net "PVCCFA_EHV_FIVRA_CPU0")
	)
	(segment
		(start 339.954362 -287.567116)
		(end 339.954362 -288.102802)
		(width 0.254)
		(layer "F.Cu")
		(net "PVCCFA_EHV_FIVRA_CPU0")
	)
	(segment
		(start 342.194134 -225.739198)
		(end 342.194134 -225.203512)
		(width 0.254)
		(layer "F.Cu")
		(net "PVCCFA_EHV_FIVRA_CPU0")
	)
	(segment
		(start 371.907562 -287.567116)
		(end 371.907562 -288.102802)
		(width 0.254)
		(layer "F.Cu")
		(net "PVCCFA_EHV_FIVRA_CPU0")
	)
	(segment
		(start 379.786134 -225.203512)
		(end 379.78588 -225.203258)
		(width 0.254)
		(layer "F.Cu")
		(net "PVCCFA_EHV_FIVRA_CPU0")
	)
	(segment
		(start 365.328962 -274.54479)
		(end 365.329216 -274.545044)
		(width 0.254)
		(layer "F.Cu")
		(net "PVCCFA_EHV_FIVRA_CPU0")
	)
	(segment
		(start 368.148362 -278.336248)
		(end 368.148616 -278.336502)
		(width 0.254)
		(layer "F.Cu")
		(net "PVCCFA_EHV_FIVRA_CPU0")
	)
	(segment
		(start 345.953334 -225.203512)
		(end 345.95308 -225.203258)
		(width 0.254)
		(layer "F.Cu")
		(net "PVCCFA_EHV_FIVRA_CPU0")
	)
	(segment
		(start 381.305562 -279.96388)
		(end 381.305816 -279.964134)
		(width 0.254)
		(layer "F.Cu")
		(net "PVCCFA_EHV_FIVRA_CPU0")
	)
	(segment
		(start 345.593162 -287.567116)
		(end 345.593162 -288.102802)
		(width 0.254)
		(layer "F.Cu")
		(net "PVCCFA_EHV_FIVRA_CPU0")
	)
	(segment
		(start 351.231962 -287.567116)
		(end 351.231962 -288.102802)
		(width 0.254)
		(layer "F.Cu")
		(net "PVCCFA_EHV_FIVRA_CPU0")
	)
	(segment
		(start 336.555334 -221.947994)
		(end 336.55508 -221.94774)
		(width 0.254)
		(layer "F.Cu")
		(net "PVCCFA_EHV_FIVRA_CPU0")
	)
	(segment
		(start 341.833962 -284.847284)
		(end 341.834216 -284.847538)
		(width 0.254)
		(layer "F.Cu")
		(net "PVCCFA_EHV_FIVRA_CPU0")
	)
	(segment
		(start 299.6946 -346.700348)
		(end 299.6946 -347.640656)
		(width 0.508)
		(layer "F.Cu")
		(net "PVCCFA_EHV_FIVRA_CPU0")
	)
	(segment
		(start 371.907562 -282.683966)
		(end 371.907816 -283.219906)
		(width 0.254)
		(layer "F.Cu")
		(net "PVCCFA_EHV_FIVRA_CPU0")
	)
	(segment
		(start 381.665734 -225.739198)
		(end 381.665734 -225.203258)
		(width 0.254)
		(layer "F.Cu")
		(net "PVCCFA_EHV_FIVRA_CPU0")
	)
	(segment
		(start 342.194134 -222.48368)
		(end 342.194134 -221.947994)
		(width 0.254)
		(layer "F.Cu")
		(net "PVCCFA_EHV_FIVRA_CPU0")
	)
	(segment
		(start 287.2994 -346.700348)
		(end 287.2994 -347.640656)
		(width 0.508)
		(layer "F.Cu")
		(net "PVCCFA_EHV_FIVRA_CPU0")
	)
	(segment
		(start 370.027962 -276.172676)
		(end 370.028216 -276.708616)
		(width 0.254)
		(layer "F.Cu")
		(net "PVCCFA_EHV_FIVRA_CPU0")
	)
	(segment
		(start 345.123516 -278.614378)
		(end 345.123516 -279.150064)
		(width 0.254)
		(layer "F.Cu")
		(net "PVCCFA_EHV_FIVRA_CPU0")
	)
	(segment
		(start 349.712534 -225.203512)
		(end 349.71228 -225.203258)
		(width 0.254)
		(layer "F.Cu")
		(net "PVCCFA_EHV_FIVRA_CPU0")
	)
	(segment
		(start 336.195162 -287.567116)
		(end 336.195416 -287.56737)
		(width 0.254)
		(layer "F.Cu")
		(net "PVCCFA_EHV_FIVRA_CPU0")
	)
	(segment
		(start 350.762316 -277.521924)
		(end 350.762062 -277.522178)
		(width 0.254)
		(layer "F.Cu")
		(net "PVCCFA_EHV_FIVRA_CPU0")
	)
	(segment
		(start 379.786134 -215.436958)
		(end 379.78588 -215.436704)
		(width 0.381)
		(layer "F.Cu")
		(net "PVCCFA_EHV_FIVRA_CPU0")
	)
	(segment
		(start 377.906534 -221.947994)
		(end 377.90628 -221.94774)
		(width 0.254)
		(layer "F.Cu")
		(net "PVCCFA_EHV_FIVRA_CPU0")
	)
	(segment
		(start 379.786134 -215.972644)
		(end 379.786134 -215.436958)
		(width 0.381)
		(layer "F.Cu")
		(net "PVCCFA_EHV_FIVRA_CPU0")
	)
	(segment
		(start 341.833962 -279.428194)
		(end 341.833962 -279.964134)
		(width 0.254)
		(layer "F.Cu")
		(net "PVCCFA_EHV_FIVRA_CPU0")
	)
	(segment
		(start 376.02668 -215.436958)
		(end 376.02668 -215.436704)
		(width 0.254)
		(layer "F.Cu")
		(net "PVCCFA_EHV_FIVRA_CPU0")
	)
	(segment
		(start 376.026934 -215.972644)
		(end 376.026934 -215.437212)
		(width 0.254)
		(layer "F.Cu")
		(net "PVCCFA_EHV_FIVRA_CPU0")
	)
	(segment
		(start 299.6946 -346.700348)
		(end 300.634908 -346.700348)
		(width 0.508)
		(layer "F.Cu")
		(net "PVCCFA_EHV_FIVRA_CPU0")
	)
	(segment
		(start 336.665316 -280.77795)
		(end 336.665062 -280.778204)
		(width 0.254)
		(layer "F.Cu")
		(net "PVCCFA_EHV_FIVRA_CPU0")
	)
	(segment
		(start 381.305562 -287.567116)
		(end 381.305562 -288.102802)
		(width 0.254)
		(layer "F.Cu")
		(net "PVCCFA_EHV_FIVRA_CPU0")
	)
	(segment
		(start 336.665316 -280.242264)
		(end 336.665316 -280.77795)
		(width 0.254)
		(layer "F.Cu")
		(net "PVCCFA_EHV_FIVRA_CPU0")
	)
	(segment
		(start 343.713562 -284.311598)
		(end 343.713562 -284.847284)
		(width 0.254)
		(layer "F.Cu")
		(net "PVCCFA_EHV_FIVRA_CPU0")
	)
	(segment
		(start 375.666762 -284.311598)
		(end 375.667016 -284.847538)
		(width 0.254)
		(layer "F.Cu")
		(net "PVCCFA_EHV_FIVRA_CPU0")
	)
	(segment
		(start 362.979716 -275.894546)
		(end 362.979462 -275.8948)
		(width 0.254)
		(layer "F.Cu")
		(net "PVCCFA_EHV_FIVRA_CPU0")
	)
	(segment
		(start 377.906534 -215.437212)
		(end 377.90628 -215.436958)
		(width 0.254)
		(layer "F.Cu")
		(net "PVCCFA_EHV_FIVRA_CPU0")
	)
	(segment
		(start 344.073734 -225.203512)
		(end 344.07348 -225.203258)
		(width 0.254)
		(layer "F.Cu")
		(net "PVCCFA_EHV_FIVRA_CPU0")
	)
	(segment
		(start 383.545334 -225.739198)
		(end 383.545334 -225.203258)
		(width 0.254)
		(layer "F.Cu")
		(net "PVCCFA_EHV_FIVRA_CPU0")
	)
	(segment
		(start 341.833962 -284.311598)
		(end 341.833962 -284.847284)
		(width 0.254)
		(layer "F.Cu")
		(net "PVCCFA_EHV_FIVRA_CPU0")
	)
	(segment
		(start 370.027962 -288.102802)
		(end 370.028216 -288.103056)
		(width 0.254)
		(layer "F.Cu")
		(net "PVCCFA_EHV_FIVRA_CPU0")
	)
	(segment
		(start 367.208562 -274.54479)
		(end 367.208816 -274.545044)
		(width 0.254)
		(layer "F.Cu")
		(net "PVCCFA_EHV_FIVRA_CPU0")
	)
	(segment
		(start 340.314534 -218.692476)
		(end 340.31428 -218.692222)
		(width 0.254)
		(layer "F.Cu")
		(net "PVCCFA_EHV_FIVRA_CPU0")
	)
	(segment
		(start 338.074762 -287.567116)
		(end 338.074762 -288.103056)
		(width 0.254)
		(layer "F.Cu")
		(net "PVCCFA_EHV_FIVRA_CPU0")
	)
	(segment
		(start 336.195416 -288.102802)
		(end 336.195162 -288.103056)
		(width 0.254)
		(layer "F.Cu")
		(net "PVCCFA_EHV_FIVRA_CPU0")
	)
	(segment
		(start 347.832934 -225.203512)
		(end 347.83268 -225.203258)
		(width 0.254)
		(layer "F.Cu")
		(net "PVCCFA_EHV_FIVRA_CPU0")
	)
	(segment
		(start 421.292528 -346.017342)
		(end 421.292528 -346.95765)
		(width 0.508)
		(layer "F.Cu")
		(net "PVCCFA_EHV_FIVRA_CPU0")
	)
	(segment
		(start 370.027962 -279.96388)
		(end 370.028216 -279.964134)
		(width 0.254)
		(layer "F.Cu")
		(net "PVCCFA_EHV_FIVRA_CPU0")
	)
	(segment
		(start 377.906534 -222.48368)
		(end 377.906534 -221.947994)
		(width 0.254)
		(layer "F.Cu")
		(net "PVCCFA_EHV_FIVRA_CPU0")
	)
	(segment
		(start 345.953334 -222.48368)
		(end 345.953334 -221.947994)
		(width 0.254)
		(layer "F.Cu")
		(net "PVCCFA_EHV_FIVRA_CPU0")
	)
	(segment
		(start 376.026934 -225.739198)
		(end 376.026934 -225.203512)
		(width 0.254)
		(layer "F.Cu")
		(net "PVCCFA_EHV_FIVRA_CPU0")
	)
	(segment
		(start 339.48497 -280.242518)
		(end 339.48497 -280.77795)
		(width 0.254)
		(layer "F.Cu")
		(net "PVCCFA_EHV_FIVRA_CPU0")
	)
	(segment
		(start 345.953334 -225.739198)
		(end 345.953334 -225.203512)
		(width 0.254)
		(layer "F.Cu")
		(net "PVCCFA_EHV_FIVRA_CPU0")
	)
	(segment
		(start 376.026934 -218.692476)
		(end 376.02668 -218.692222)
		(width 0.254)
		(layer "F.Cu")
		(net "PVCCFA_EHV_FIVRA_CPU0")
	)
	(segment
		(start 338.434934 -221.947994)
		(end 338.43468 -221.94774)
		(width 0.254)
		(layer "F.Cu")
		(net "PVCCFA_EHV_FIVRA_CPU0")
	)
	(segment
		(start 366.268762 -274.54479)
		(end 366.269016 -274.545044)
		(width 0.254)
		(layer "F.Cu")
		(net "PVCCFA_EHV_FIVRA_CPU0")
	)
	(segment
		(start 343.713562 -284.847284)
		(end 343.713816 -284.847538)
		(width 0.254)
		(layer "F.Cu")
		(net "PVCCFA_EHV_FIVRA_CPU0")
	)
	(segment
		(start 344.653362 -278.336248)
		(end 344.653616 -278.336502)
		(width 0.381)
		(layer "F.Cu")
		(net "PVCCFA_EHV_FIVRA_CPU0")
	)
	(segment
		(start 380.835916 -278.614378)
		(end 380.835916 -279.150318)
		(width 0.254)
		(layer "F.Cu")
		(net "PVCCFA_EHV_FIVRA_CPU0")
	)
	(segment
		(start 293.497 -346.700348)
		(end 294.437308 -346.700348)
		(width 0.508)
		(layer "F.Cu")
		(net "PVCCFA_EHV_FIVRA_CPU0")
	)
	(segment
		(start 427.490128 -346.017342)
		(end 428.430436 -346.017342)
		(width 0.508)
		(layer "F.Cu")
		(net "PVCCFA_EHV_FIVRA_CPU0")
	)
	(segment
		(start 371.907562 -278.336248)
		(end 371.907816 -278.336502)
		(width 0.254)
		(layer "F.Cu")
		(net "PVCCFA_EHV_FIVRA_CPU0")
	)
	(segment
		(start 336.555334 -222.48368)
		(end 336.555334 -221.947994)
		(width 0.254)
		(layer "F.Cu")
		(net "PVCCFA_EHV_FIVRA_CPU0")
	)
	(segment
		(start 337.604862 -283.497782)
		(end 337.604862 -284.033722)
		(width 0.254)
		(layer "F.Cu")
		(net "PVCCFA_EHV_FIVRA_CPU0")
	)
	(segment
		(start 342.194134 -218.692476)
		(end 342.19388 -218.692222)
		(width 0.254)
		(layer "F.Cu")
		(net "PVCCFA_EHV_FIVRA_CPU0")
	)
	(segment
		(start 339.954362 -284.311598)
		(end 339.954362 -284.847538)
		(width 0.254)
		(layer "F.Cu")
		(net "PVCCFA_EHV_FIVRA_CPU0")
	)
	(segment
		(start 354.991162 -279.428194)
		(end 354.991162 -279.96388)
		(width 0.254)
		(layer "F.Cu")
		(net "PVCCFA_EHV_FIVRA_CPU0")
	)
	(segment
		(start 379.786134 -219.228162)
		(end 379.786134 -218.692476)
		(width 0.254)
		(layer "F.Cu")
		(net "PVCCFA_EHV_FIVRA_CPU0")
	)
	(segment
		(start 298.754292 -346.700348)
		(end 299.6946 -346.700348)
		(width 0.508)
		(layer "F.Cu")
		(net "PVCCFA_EHV_FIVRA_CPU0")
	)
	(segment
		(start 338.434934 -218.692476)
		(end 338.43468 -218.692222)
		(width 0.254)
		(layer "F.Cu")
		(net "PVCCFA_EHV_FIVRA_CPU0")
	)
	(segment
		(start 337.134962 -286.47517)
		(end 337.135216 -286.475424)
		(width 0.254)
		(layer "F.Cu")
		(net "PVCCFA_EHV_FIVRA_CPU0")
	)
	(segment
		(start 381.305562 -284.311598)
		(end 381.305816 -284.847538)
		(width 0.254)
		(layer "F.Cu")
		(net "PVCCFA_EHV_FIVRA_CPU0")
	)
	(segment
		(start 344.653362 -277.800562)
		(end 344.653362 -278.336248)
		(width 0.381)
		(layer "F.Cu")
		(net "PVCCFA_EHV_FIVRA_CPU0")
	)
	(segment
		(start 340.314534 -222.48368)
		(end 340.314534 -221.947994)
		(width 0.254)
		(layer "F.Cu")
		(net "PVCCFA_EHV_FIVRA_CPU0")
	)
	(segment
		(start 382.245362 -279.96388)
		(end 382.245616 -279.964134)
		(width 0.254)
		(layer "F.Cu")
		(net "PVCCFA_EHV_FIVRA_CPU0")
	)
	(segment
		(start 338.434934 -219.228162)
		(end 338.434934 -218.692476)
		(width 0.254)
		(layer "F.Cu")
		(net "PVCCFA_EHV_FIVRA_CPU0")
	)
	(segment
		(start 340.314534 -219.228162)
		(end 340.314534 -218.692476)
		(width 0.254)
		(layer "F.Cu")
		(net "PVCCFA_EHV_FIVRA_CPU0")
	)
	(segment
		(start 366.269016 -274.545044)
		(end 366.269016 -275.08073)
		(width 0.254)
		(layer "F.Cu")
		(net "PVCCFA_EHV_FIVRA_CPU0")
	)
	(segment
		(start 344.073734 -225.739198)
		(end 344.073734 -225.203512)
		(width 0.254)
		(layer "F.Cu")
		(net "PVCCFA_EHV_FIVRA_CPU0")
	)
	(segment
		(start 342.194134 -219.228162)
		(end 342.194134 -218.692476)
		(width 0.254)
		(layer "F.Cu")
		(net "PVCCFA_EHV_FIVRA_CPU0")
	)
	(segment
		(start 362.979716 -275.35886)
		(end 362.979716 -275.894546)
		(width 0.254)
		(layer "F.Cu")
		(net "PVCCFA_EHV_FIVRA_CPU0")
	)
	(segment
		(start 287.2994 -346.700348)
		(end 288.239708 -346.700348)
		(width 0.508)
		(layer "F.Cu")
		(net "PVCCFA_EHV_FIVRA_CPU0")
	)
	(segment
		(start 338.434934 -222.48368)
		(end 338.434934 -221.947994)
		(width 0.254)
		(layer "F.Cu")
		(net "PVCCFA_EHV_FIVRA_CPU0")
	)
	(segment
		(start 377.906534 -225.203512)
		(end 377.90628 -225.203258)
		(width 0.254)
		(layer "F.Cu")
		(net "PVCCFA_EHV_FIVRA_CPU0")
	)
	(segment
		(start 292.556692 -346.700348)
		(end 293.497 -346.700348)
		(width 0.508)
		(layer "F.Cu")
		(net "PVCCFA_EHV_FIVRA_CPU0")
	)
	(segment
		(start 354.051362 -278.336248)
		(end 354.051616 -278.336502)
		(width 0.254)
		(layer "F.Cu")
		(net "PVCCFA_EHV_FIVRA_CPU0")
	)
	(segment
		(start 353.581716 -273.730974)
		(end 353.581716 -274.26666)
		(width 0.254)
		(layer "F.Cu")
		(net "PVCCFA_EHV_FIVRA_CPU0")
	)
	(segment
		(start 333.845662 -284.033722)
		(end 333.845662 -283.497782)
		(width 0.254)
		(layer "F.Cu")
		(net "PVCCFA_EHV_FIVRA_CPU0")
	)
	(segment
		(start 339.954362 -288.102802)
		(end 339.954616 -288.103056)
		(width 0.254)
		(layer "F.Cu")
		(net "PVCCFA_EHV_FIVRA_CPU0")
	)
	(segment
		(start 376.026934 -219.228162)
		(end 376.026934 -218.692476)
		(width 0.254)
		(layer "F.Cu")
		(net "PVCCFA_EHV_FIVRA_CPU0")
	)
	(segment
		(start 355.461316 -274.26666)
		(end 355.461062 -274.266914)
		(width 0.254)
		(layer "F.Cu")
		(net "PVCCFA_EHV_FIVRA_CPU0")
	)
	(segment
		(start 347.832934 -218.692476)
		(end 347.83268 -218.692222)
		(width 0.254)
		(layer "F.Cu")
		(net "PVCCFA_EHV_FIVRA_CPU0")
	)
	(segment
		(start 343.713562 -287.567116)
		(end 343.713562 -288.102802)
		(width 0.254)
		(layer "F.Cu")
		(net "PVCCFA_EHV_FIVRA_CPU0")
	)
	(segment
		(start 379.425962 -287.567116)
		(end 379.425962 -288.102802)
		(width 0.254)
		(layer "F.Cu")
		(net "PVCCFA_EHV_FIVRA_CPU0")
	)
	(segment
		(start 342.194134 -221.947994)
		(end 342.19388 -221.94774)
		(width 0.254)
		(layer "F.Cu")
		(net "PVCCFA_EHV_FIVRA_CPU0")
	)
	(segment
		(start 339.48497 -280.77795)
		(end 339.484716 -280.778204)
		(width 0.254)
		(layer "F.Cu")
		(net "PVCCFA_EHV_FIVRA_CPU0")
	)
	(segment
		(start 373.787162 -288.102802)
		(end 373.787416 -288.103056)
		(width 0.254)
		(layer "F.Cu")
		(net "PVCCFA_EHV_FIVRA_CPU0")
	)
	(segment
		(start 371.907562 -277.800562)
		(end 371.907562 -278.336248)
		(width 0.254)
		(layer "F.Cu")
		(net "PVCCFA_EHV_FIVRA_CPU0")
	)
	(segment
		(start 339.014562 -279.428194)
		(end 339.014562 -279.96388)
		(width 0.254)
		(layer "F.Cu")
		(net "PVCCFA_EHV_FIVRA_CPU0")
	)
	(segment
		(start 415.101786 -346.010992)
		(end 416.042094 -346.010992)
		(width 0.508)
		(layer "F.Cu")
		(net "PVCCFA_EHV_FIVRA_CPU0")
	)
	(segment
		(start 427.490128 -346.017342)
		(end 427.490128 -346.95765)
		(width 0.508)
		(layer "F.Cu")
		(net "PVCCFA_EHV_FIVRA_CPU0")
	)
	(segment
		(start 365.329216 -274.545044)
		(end 365.329216 -275.08073)
		(width 0.254)
		(layer "F.Cu")
		(net "PVCCFA_EHV_FIVRA_CPU0")
	)
	(segment
		(start 349.352362 -288.102802)
		(end 349.352616 -288.103056)
		(width 0.254)
		(layer "F.Cu")
		(net "PVCCFA_EHV_FIVRA_CPU0")
	)
	(segment
		(start 368.148362 -284.311598)
		(end 368.148616 -284.847538)
		(width 0.254)
		(layer "F.Cu")
		(net "PVCCFA_EHV_FIVRA_CPU0")
	)
	(segment
		(start 341.833962 -287.567116)
		(end 341.833962 -288.102802)
		(width 0.254)
		(layer "F.Cu")
		(net "PVCCFA_EHV_FIVRA_CPU0")
	)
	(segment
		(start 339.014562 -279.96388)
		(end 339.014816 -279.964134)
		(width 0.254)
		(layer "F.Cu")
		(net "PVCCFA_EHV_FIVRA_CPU0")
	)
	(segment
		(start 340.314534 -225.739198)
		(end 340.314534 -225.203512)
		(width 0.2032)
		(layer "F.Cu")
		(net "PVCCFA_EHV_FIVRA_CPU0")
	)
	(segment
		(start 382.715516 -280.77795)
		(end 382.715262 -280.778204)
		(width 0.254)
		(layer "F.Cu")
		(net "PVCCFA_EHV_FIVRA_CPU0")
	)
	(segment
		(start 375.666762 -287.567116)
		(end 375.666762 -288.102802)
		(width 0.254)
		(layer "F.Cu")
		(net "PVCCFA_EHV_FIVRA_CPU0")
	)
	(segment
		(start 375.666762 -282.683966)
		(end 375.667016 -283.219906)
		(width 0.254)
		(layer "F.Cu")
		(net "PVCCFA_EHV_FIVRA_CPU0")
	)
	(segment
		(start 293.497 -346.700348)
		(end 293.497 -347.640656)
		(width 0.508)
		(layer "F.Cu")
		(net "PVCCFA_EHV_FIVRA_CPU0")
	)
	(segment
		(start 345.123516 -279.150064)
		(end 345.123262 -279.150318)
		(width 0.254)
		(layer "F.Cu")
		(net "PVCCFA_EHV_FIVRA_CPU0")
	)
	(segment
		(start 351.231962 -288.102802)
		(end 351.232216 -288.103056)
		(width 0.254)
		(layer "F.Cu")
		(net "PVCCFA_EHV_FIVRA_CPU0")
	)
	(segment
		(start 349.352362 -287.567116)
		(end 349.352362 -288.102802)
		(width 0.254)
		(layer "F.Cu")
		(net "PVCCFA_EHV_FIVRA_CPU0")
	)
	(segment
		(start 414.161478 -346.010992)
		(end 415.101786 -346.010992)
		(width 0.508)
		(layer "F.Cu")
		(net "PVCCFA_EHV_FIVRA_CPU0")
	)
	(segment
		(start 353.581716 -274.26666)
		(end 353.581462 -274.266914)
		(width 0.254)
		(layer "F.Cu")
		(net "PVCCFA_EHV_FIVRA_CPU0")
	)
	(segment
		(start 379.425962 -284.311598)
		(end 379.426216 -284.847538)
		(width 0.254)
		(layer "F.Cu")
		(net "PVCCFA_EHV_FIVRA_CPU0")
	)
	(segment
		(start 377.90628 -215.436958)
		(end 377.90628 -215.436704)
		(width 0.254)
		(layer "F.Cu")
		(net "PVCCFA_EHV_FIVRA_CPU0")
	)
	(segment
		(start 377.906534 -219.228162)
		(end 377.906534 -218.692476)
		(width 0.254)
		(layer "F.Cu")
		(net "PVCCFA_EHV_FIVRA_CPU0")
	)
	(segment
		(start 385.56184 -283.52496)
		(end 385.56184 -284.006544)
		(width 0.254)
		(layer "F.Cu")
		(net "PVCCFA_EHV_FIVRA_CPU0")
	)
	(segment
		(start 336.195416 -287.56737)
		(end 336.195416 -288.102802)
		(width 0.254)
		(layer "F.Cu")
		(net "PVCCFA_EHV_FIVRA_CPU0")
	)
	(segment
		(start 286.359092 -346.700348)
		(end 287.2994 -346.700348)
		(width 0.508)
		(layer "F.Cu")
		(net "PVCCFA_EHV_FIVRA_CPU0")
	)
	(segment
		(start 381.775716 -283.497782)
		(end 381.775716 -284.033468)
		(width 0.254)
		(layer "F.Cu")
		(net "PVCCFA_EHV_FIVRA_CPU0")
	)
	(segment
		(start 370.027962 -287.567116)
		(end 370.027962 -288.102802)
		(width 0.254)
		(layer "F.Cu")
		(net "PVCCFA_EHV_FIVRA_CPU0")
	)
	(segment
		(start 344.073734 -221.947994)
		(end 344.07348 -221.94774)
		(width 0.254)
		(layer "F.Cu")
		(net "PVCCFA_EHV_FIVRA_CPU0")
	)
	(segment
		(start 340.314534 -225.203512)
		(end 340.31428 -225.203258)
		(width 0.2032)
		(layer "F.Cu")
		(net "PVCCFA_EHV_FIVRA_CPU0")
	)
	(segment
		(start 339.484716 -280.242264)
		(end 339.48497 -280.242518)
		(width 0.254)
		(layer "F.Cu")
		(net "PVCCFA_EHV_FIVRA_CPU0")
	)
	(segment
		(start 377.546362 -287.567116)
		(end 377.546362 -288.102802)
		(width 0.254)
		(layer "F.Cu")
		(net "PVCCFA_EHV_FIVRA_CPU0")
	)
	(segment
		(start 355.461316 -278.614378)
		(end 355.461316 -279.150064)
		(width 0.254)
		(layer "F.Cu")
		(net "PVCCFA_EHV_FIVRA_CPU0")
	)
	(segment
		(start 347.832934 -225.739198)
		(end 347.832934 -225.203512)
		(width 0.254)
		(layer "F.Cu")
		(net "PVCCFA_EHV_FIVRA_CPU0")
	)
	(segment
		(start 376.026934 -221.947994)
		(end 376.02668 -221.94774)
		(width 0.254)
		(layer "F.Cu")
		(net "PVCCFA_EHV_FIVRA_CPU0")
	)
	(segment
		(start 383.655062 -283.497782)
		(end 383.655062 -284.033722)
		(width 0.254)
		(layer "F.Cu")
		(net "PVCCFA_EHV_FIVRA_CPU0")
	)
	(segment
		(start 370.027962 -284.311598)
		(end 370.028216 -284.847538)
		(width 0.254)
		(layer "F.Cu")
		(net "PVCCFA_EHV_FIVRA_CPU0")
	)
	(segment
		(start 338.074762 -284.311598)
		(end 338.074762 -284.847538)
		(width 0.254)
		(layer "F.Cu")
		(net "PVCCFA_EHV_FIVRA_CPU0")
	)
	(segment
		(start 381.665734 -219.228162)
		(end 381.665734 -218.692222)
		(width 0.254)
		(layer "F.Cu")
		(net "PVCCFA_EHV_FIVRA_CPU0")
	)
	(segment
		(start 355.461316 -279.150064)
		(end 355.461062 -279.150318)
		(width 0.254)
		(layer "F.Cu")
		(net "PVCCFA_EHV_FIVRA_CPU0")
	)
	(segment
		(start 341.364316 -280.77795)
		(end 341.364062 -280.778204)
		(width 0.254)
		(layer "F.Cu")
		(net "PVCCFA_EHV_FIVRA_CPU0")
	)
	(segment
		(start 347.942916 -280.77795)
		(end 347.942662 -280.778204)
		(width 0.254)
		(layer "F.Cu")
		(net "PVCCFA_EHV_FIVRA_CPU0")
	)
	(segment
		(start 368.148362 -277.800562)
		(end 368.148362 -278.336248)
		(width 0.254)
		(layer "F.Cu")
		(net "PVCCFA_EHV_FIVRA_CPU0")
	)
	(segment
		(start 377.546362 -288.102802)
		(end 377.546616 -288.103056)
		(width 0.254)
		(layer "F.Cu")
		(net "PVCCFA_EHV_FIVRA_CPU0")
	)
	(segment
		(start 377.906534 -215.972644)
		(end 377.906534 -215.437212)
		(width 0.254)
		(layer "F.Cu")
		(net "PVCCFA_EHV_FIVRA_CPU0")
	)
	(segment
		(start 344.073734 -222.48368)
		(end 344.073734 -221.947994)
		(width 0.254)
		(layer "F.Cu")
		(net "PVCCFA_EHV_FIVRA_CPU0")
	)
	(segment
		(start 381.775716 -284.033468)
		(end 381.775462 -284.033722)
		(width 0.254)
		(layer "F.Cu")
		(net "PVCCFA_EHV_FIVRA_CPU0")
	)
	(segment
		(start 370.027962 -279.428194)
		(end 370.027962 -279.96388)
		(width 0.254)
		(layer "F.Cu")
		(net "PVCCFA_EHV_FIVRA_CPU0")
	)
	(segment
		(start 421.292528 -346.017342)
		(end 422.232836 -346.017342)
		(width 0.508)
		(layer "F.Cu")
		(net "PVCCFA_EHV_FIVRA_CPU0")
	)
	(segment
		(start 350.762316 -276.986492)
		(end 350.762316 -277.521924)
		(width 0.254)
		(layer "F.Cu")
		(net "PVCCFA_EHV_FIVRA_CPU0")
	)
	(segment
		(start 375.666762 -288.102802)
		(end 375.667016 -288.103056)
		(width 0.254)
		(layer "F.Cu")
		(net "PVCCFA_EHV_FIVRA_CPU0")
	)
	(segment
		(start 336.555334 -219.228162)
		(end 336.555334 -218.692222)
		(width 0.254)
		(layer "F.Cu")
		(net "PVCCFA_EHV_FIVRA_CPU0")
	)
	(segment
		(start 379.786134 -222.48368)
		(end 379.786134 -221.947994)
		(width 0.254)
		(layer "F.Cu")
		(net "PVCCFA_EHV_FIVRA_CPU0")
	)
	(segment
		(start 373.787162 -287.567116)
		(end 373.787162 -288.102802)
		(width 0.254)
		(layer "F.Cu")
		(net "PVCCFA_EHV_FIVRA_CPU0")
	)
	(segment
		(start 377.906534 -218.692476)
		(end 377.90628 -218.692222)
		(width 0.254)
		(layer "F.Cu")
		(net "PVCCFA_EHV_FIVRA_CPU0")
	)
	(segment
		(start 345.953334 -218.692476)
		(end 345.95308 -218.692222)
		(width 0.254)
		(layer "F.Cu")
		(net "PVCCFA_EHV_FIVRA_CPU0")
	)
	(segment
		(start 347.832934 -219.228162)
		(end 347.832934 -218.692476)
		(width 0.254)
		(layer "F.Cu")
		(net "PVCCFA_EHV_FIVRA_CPU0")
	)
	(segment
		(start 377.546362 -284.311598)
		(end 377.546616 -284.847538)
		(width 0.254)
		(layer "F.Cu")
		(net "PVCCFA_EHV_FIVRA_CPU0")
	)
	(segment
		(start 366.738916 -278.614378)
		(end 366.738662 -279.150318)
		(width 0.254)
		(layer "F.Cu")
		(net "PVCCFA_EHV_FIVRA_CPU0")
	)
	(segment
		(start 347.472762 -288.102802)
		(end 347.473016 -288.103056)
		(width 0.254)
		(layer "F.Cu")
		(net "PVCCFA_EHV_FIVRA_CPU0")
	)
	(segment
		(start 347.942916 -280.242264)
		(end 347.942916 -280.77795)
		(width 0.254)
		(layer "F.Cu")
		(net "PVCCFA_EHV_FIVRA_CPU0")
	)
	(segment
		(start 381.305562 -288.102802)
		(end 381.305816 -288.103056)
		(width 0.254)
		(layer "F.Cu")
		(net "PVCCFA_EHV_FIVRA_CPU0")
	)
	(segment
		(start 347.472762 -279.428194)
		(end 347.473016 -279.964134)
		(width 0.254)
		(layer "F.Cu")
		(net "PVCCFA_EHV_FIVRA_CPU0")
	)
	(segment
		(start 415.101786 -346.010992)
		(end 415.101786 -346.9513)
		(width 0.508)
		(layer "F.Cu")
		(net "PVCCFA_EHV_FIVRA_CPU0")
	)
	(segment
		(start 355.461316 -273.730974)
		(end 355.461316 -274.26666)
		(width 0.254)
		(layer "F.Cu")
		(net "PVCCFA_EHV_FIVRA_CPU0")
	)
	(segment
		(start 354.051362 -277.800562)
		(end 354.051362 -278.336248)
		(width 0.254)
		(layer "F.Cu")
		(net "PVCCFA_EHV_FIVRA_CPU0")
	)
	(segment
		(start 377.546362 -279.96388)
		(end 377.546616 -279.964134)
		(width 0.254)
		(layer "F.Cu")
		(net "PVCCFA_EHV_FIVRA_CPU0")
	)
	(segment
		(start 382.245362 -279.428194)
		(end 382.245362 -279.96388)
		(width 0.254)
		(layer "F.Cu")
		(net "PVCCFA_EHV_FIVRA_CPU0")
	)
	(segment
		(start 376.026934 -215.437212)
		(end 376.02668 -215.436958)
		(width 0.254)
		(layer "F.Cu")
		(net "PVCCFA_EHV_FIVRA_CPU0")
	)
	(segment
		(start 347.472762 -287.567116)
		(end 347.472762 -288.102802)
		(width 0.254)
		(layer "F.Cu")
		(net "PVCCFA_EHV_FIVRA_CPU0")
	)
	(segment
		(start 379.786134 -218.692476)
		(end 379.78588 -218.692222)
		(width 0.254)
		(layer "F.Cu")
		(net "PVCCFA_EHV_FIVRA_CPU0")
	)
	(segment
		(start 341.364316 -280.242264)
		(end 341.364316 -280.77795)
		(width 0.254)
		(layer "F.Cu")
		(net "PVCCFA_EHV_FIVRA_CPU0")
	)
	(segment
		(start 344.073734 -219.228162)
		(end 344.073734 -218.692476)
		(width 0.254)
		(layer "F.Cu")
		(net "PVCCFA_EHV_FIVRA_CPU0")
	)
	(segment
		(start 350.762062 -277.522178)
		(end 350.762062 -277.522432)
		(width 0.254)
		(layer "F.Cu")
		(net "PVCCFA_EHV_FIVRA_CPU0")
	)
	(segment
		(start 426.54982 -346.017342)
		(end 427.490128 -346.017342)
		(width 0.508)
		(layer "F.Cu")
		(net "PVCCFA_EHV_FIVRA_CPU0")
	)
	(segment
		(start 379.786134 -225.739198)
		(end 379.786134 -225.203512)
		(width 0.254)
		(layer "F.Cu")
		(net "PVCCFA_EHV_FIVRA_CPU0")
	)
	(segment
		(start 367.208816 -274.545044)
		(end 367.208816 -275.08073)
		(width 0.254)
		(layer "F.Cu")
		(net "PVCCFA_EHV_FIVRA_CPU0")
	)
	(segment
		(start 344.073734 -218.692476)
		(end 344.07348 -218.692222)
		(width 0.254)
		(layer "F.Cu")
		(net "PVCCFA_EHV_FIVRA_CPU0")
	)
	(segment
		(start 376.026934 -222.48368)
		(end 376.026934 -221.947994)
		(width 0.254)
		(layer "F.Cu")
		(net "PVCCFA_EHV_FIVRA_CPU0")
	)
	(segment
		(start 371.907562 -284.311598)
		(end 371.907816 -284.847538)
		(width 0.254)
		(layer "F.Cu")
		(net "PVCCFA_EHV_FIVRA_CPU0")
	)
	(segment
		(start 379.425962 -288.102802)
		(end 379.426216 -288.103056)
		(width 0.254)
		(layer "F.Cu")
		(net "PVCCFA_EHV_FIVRA_CPU0")
	)
	(segment
		(start 345.593162 -288.102802)
		(end 345.593416 -288.103056)
		(width 0.254)
		(layer "F.Cu")
		(net "PVCCFA_EHV_FIVRA_CPU0")
	)
	(segment
		(start 347.472762 -284.311598)
		(end 347.472762 -284.847284)
		(width 0.254)
		(layer "F.Cu")
		(net "PVCCFA_EHV_FIVRA_CPU0")
	)
	(segment
		(start 347.472762 -284.847284)
		(end 347.473016 -284.847538)
		(width 0.254)
		(layer "F.Cu")
		(net "PVCCFA_EHV_FIVRA_CPU0")
	)
	(segment
		(start 347.832934 -221.947994)
		(end 347.83268 -221.94774)
		(width 0.254)
		(layer "F.Cu")
		(net "PVCCFA_EHV_FIVRA_CPU0")
	)
	(segment
		(start 333.845662 -287.28924)
		(end 333.845662 -286.7533)
		(width 0.254)
		(layer "F.Cu")
		(net "PVCCFA_EHV_FIVRA_CPU0")
	)
	(segment
		(start 343.713562 -288.102802)
		(end 343.713816 -288.103056)
		(width 0.254)
		(layer "F.Cu")
		(net "PVCCFA_EHV_FIVRA_CPU0")
	)
	(segment
		(start 345.593162 -284.847284)
		(end 345.593416 -284.847538)
		(width 0.254)
		(layer "F.Cu")
		(net "PVCCFA_EHV_FIVRA_CPU0")
	)
	(segment
		(start 385.534662 -283.497782)
		(end 385.56184 -283.52496)
		(width 0.254)
		(layer "F.Cu")
		(net "PVCCFA_EHV_FIVRA_CPU0")
	)
	(segment
		(start 345.593162 -284.311598)
		(end 345.593162 -284.847284)
		(width 0.254)
		(layer "F.Cu")
		(net "PVCCFA_EHV_FIVRA_CPU0")
	)
	(segment
		(start 382.715516 -280.242264)
		(end 382.715516 -280.77795)
		(width 0.254)
		(layer "F.Cu")
		(net "PVCCFA_EHV_FIVRA_CPU0")
	)
	(segment
		(start 420.35222 -346.017342)
		(end 421.292528 -346.017342)
		(width 0.508)
		(layer "F.Cu")
		(net "PVCCFA_EHV_FIVRA_CPU0")
	)
	(segment
		(start 341.833962 -288.102802)
		(end 341.834216 -288.103056)
		(width 0.254)
		(layer "F.Cu")
		(net "PVCCFA_EHV_FIVRA_CPU0")
	)
	(segment
		(start 371.907562 -288.102802)
		(end 371.907816 -288.103056)
		(width 0.254)
		(layer "F.Cu")
		(net "PVCCFA_EHV_FIVRA_CPU0")
	)
	(segment
		(start 377.546362 -279.428194)
		(end 377.546362 -279.96388)
		(width 0.254)
		(layer "F.Cu")
		(net "PVCCFA_EHV_FIVRA_CPU0")
	)
	(segment
		(start 381.665734 -222.48368)
		(end 381.665734 -221.94774)
		(width 0.254)
		(layer "F.Cu")
		(net "PVCCFA_EHV_FIVRA_CPU0")
	)
	(segment
		(start 377.906534 -225.739198)
		(end 377.906534 -225.203512)
		(width 0.254)
		(layer "F.Cu")
		(net "PVCCFA_EHV_FIVRA_CPU0")
	)
	(segment
		(start 345.953334 -221.947994)
		(end 345.95308 -221.94774)
		(width 0.254)
		(layer "F.Cu")
		(net "PVCCFA_EHV_FIVRA_CPU0")
	)
	(segment
		(start 365.328962 -279.428194)
		(end 365.329216 -279.964134)
		(width 0.254)
		(layer "F.Cu")
		(net "PVCCFA_EHV_FIVRA_CPU0")
	)
	(segment
		(start 381.305562 -279.428194)
		(end 381.305562 -279.96388)
		(width 0.254)
		(layer "F.Cu")
		(net "PVCCFA_EHV_FIVRA_CPU0")
	)
	(segment
		(start 337.134962 -285.939484)
		(end 337.134962 -286.47517)
		(width 0.254)
		(layer "F.Cu")
		(net "PVCCFA_EHV_FIVRA_CPU0")
	)
	(segment
		(start 376.026934 -225.203512)
		(end 376.02668 -225.203258)
		(width 0.254)
		(layer "F.Cu")
		(net "PVCCFA_EHV_FIVRA_CPU0")
	)
	(segment
		(start 349.712534 -225.739198)
		(end 349.712534 -225.203512)
		(width 0.254)
		(layer "F.Cu")
		(net "PVCCFA_EHV_FIVRA_CPU0")
	)
	(segment
		(start 379.786134 -221.947994)
		(end 379.78588 -221.94774)
		(width 0.254)
		(layer "F.Cu")
		(net "PVCCFA_EHV_FIVRA_CPU0")
	)
	(segment
		(start 354.991162 -279.96388)
		(end 354.991416 -279.964134)
		(width 0.254)
		(layer "F.Cu")
		(net "PVCCFA_EHV_FIVRA_CPU0")
	)
	(segment
		(start 345.953334 -219.228162)
		(end 345.953334 -218.692476)
		(width 0.254)
		(layer "F.Cu")
		(net "PVCCFA_EHV_FIVRA_CPU0")
	)
	(segment
		(start 385.56184 -284.006544)
		(end 385.534662 -284.033722)
		(width 0.254)
		(layer "F.Cu")
		(net "PVCCFA_EHV_FIVRA_CPU0")
	)
	(segment
		(start 347.832934 -222.48368)
		(end 347.832934 -221.947994)
		(width 0.254)
		(layer "F.Cu")
		(net "PVCCFA_EHV_FIVRA_CPU0")
	)
	(segment
		(start 340.314534 -221.947994)
		(end 340.31428 -221.94774)
		(width 0.254)
		(layer "F.Cu")
		(net "PVCCFA_EHV_FIVRA_CPU0")
	)
	(via
		(at 414.325562 -349.247968)
		(size 0.508)
		(drill 0.254)
		(layers "F.Cu" "B.Cu")
		(net "PVCCFA_EHV_FIVRA_CPU0")
	)
	(via
		(at 428.983648 -347.342968)
		(size 0.508)
		(drill 0.254)
		(layers "F.Cu" "B.Cu")
		(net "PVCCFA_EHV_FIVRA_CPU0")
	)
	(via
		(at 368.148616 -278.336502)
		(size 0.4572)
		(drill 0.2032)
		(layers "F.Cu" "B.Cu")
		(net "PVCCFA_EHV_FIVRA_CPU0")
	)
	(via
		(at 295.026588 -366.68202)
		(size 0.508)
		(drill 0.254)
		(layers "F.Cu" "B.Cu")
		(net "PVCCFA_EHV_FIVRA_CPU0")
	)
	(via
		(at 379.426216 -288.103056)
		(size 0.4572)
		(drill 0.2032)
		(layers "F.Cu" "B.Cu")
		(net "PVCCFA_EHV_FIVRA_CPU0")
	)
	(via
		(at 423.355262 -349.882968)
		(size 0.508)
		(drill 0.254)
		(layers "F.Cu" "B.Cu")
		(net "PVCCFA_EHV_FIVRA_CPU0")
	)
	(via
		(at 422.720262 -347.977968)
		(size 0.508)
		(drill 0.254)
		(layers "F.Cu" "B.Cu")
		(net "PVCCFA_EHV_FIVRA_CPU0")
	)
	(via
		(at 347.473016 -284.847538)
		(size 0.4572)
		(drill 0.2032)
		(layers "F.Cu" "B.Cu")
		(net "PVCCFA_EHV_FIVRA_CPU0")
	)
	(via
		(at 301.065438 -349.3008)
		(size 0.508)
		(drill 0.254)
		(layers "F.Cu" "B.Cu")
		(net "PVCCFA_EHV_FIVRA_CPU0")
	)
	(via
		(at 296.628566 -349.3008)
		(size 0.508)
		(drill 0.254)
		(layers "F.Cu" "B.Cu")
		(net "PVCCFA_EHV_FIVRA_CPU0")
	)
	(via
		(at 286.303466 -348.6658)
		(size 0.508)
		(drill 0.254)
		(layers "F.Cu" "B.Cu")
		(net "PVCCFA_EHV_FIVRA_CPU0")
	)
	(via
		(at 339.014816 -279.964134)
		(size 0.4572)
		(drill 0.2032)
		(layers "F.Cu" "B.Cu")
		(net "PVCCFA_EHV_FIVRA_CPU0")
	)
	(via
		(at 410.583126 -254.79629)
		(size 0.4572)
		(drill 0.2032)
		(layers "F.Cu" "B.Cu")
		(net "PVCCFA_EHV_FIVRA_CPU0")
	)
	(via
		(at 286.303466 -350.5708)
		(size 0.508)
		(drill 0.254)
		(layers "F.Cu" "B.Cu")
		(net "PVCCFA_EHV_FIVRA_CPU0")
	)
	(via
		(at 295.345866 -351.8408)
		(size 0.508)
		(drill 0.254)
		(layers "F.Cu" "B.Cu")
		(net "PVCCFA_EHV_FIVRA_CPU0")
	)
	(via
		(at 419.295834 -349.247968)
		(size 0.508)
		(drill 0.254)
		(layers "F.Cu" "B.Cu")
		(net "PVCCFA_EHV_FIVRA_CPU0")
	)
	(via
		(at 414.325562 -347.977968)
		(size 0.508)
		(drill 0.254)
		(layers "F.Cu" "B.Cu")
		(net "PVCCFA_EHV_FIVRA_CPU0")
	)
	(via
		(at 428.983648 -347.977968)
		(size 0.508)
		(drill 0.254)
		(layers "F.Cu" "B.Cu")
		(net "PVCCFA_EHV_FIVRA_CPU0")
	)
	(via
		(at 338.074762 -284.847538)
		(size 0.4572)
		(drill 0.2032)
		(layers "F.Cu" "B.Cu")
		(net "PVCCFA_EHV_FIVRA_CPU0")
	)
	(via
		(at 419.295834 -350.517968)
		(size 0.508)
		(drill 0.254)
		(layers "F.Cu" "B.Cu")
		(net "PVCCFA_EHV_FIVRA_CPU0")
	)
	(via
		(at 286.951166 -348.6658)
		(size 0.508)
		(drill 0.254)
		(layers "F.Cu" "B.Cu")
		(net "PVCCFA_EHV_FIVRA_CPU0")
	)
	(via
		(at 383.655062 -284.033722)
		(size 0.4572)
		(drill 0.2032)
		(layers "F.Cu" "B.Cu")
		(net "PVCCFA_EHV_FIVRA_CPU0")
	)
	(via
		(at 411.604206 -254.79629)
		(size 0.4572)
		(drill 0.2032)
		(layers "F.Cu" "B.Cu")
		(net "PVCCFA_EHV_FIVRA_CPU0")
	)
	(via
		(at 291.921438 -351.2058)
		(size 0.508)
		(drill 0.254)
		(layers "F.Cu" "B.Cu")
		(net "PVCCFA_EHV_FIVRA_CPU0")
	)
	(via
		(at 376.02668 -225.203258)
		(size 0.4572)
		(drill 0.2032)
		(layers "F.Cu" "B.Cu")
		(net "PVCCFA_EHV_FIVRA_CPU0")
	)
	(via
		(at 301.700438 -350.5708)
		(size 0.508)
		(drill 0.254)
		(layers "F.Cu" "B.Cu")
		(net "PVCCFA_EHV_FIVRA_CPU0")
	)
	(via
		(at 339.954362 -284.847538)
		(size 0.4572)
		(drill 0.2032)
		(layers "F.Cu" "B.Cu")
		(net "PVCCFA_EHV_FIVRA_CPU0")
	)
	(via
		(at 422.720262 -348.612968)
		(size 0.508)
		(drill 0.254)
		(layers "F.Cu" "B.Cu")
		(net "PVCCFA_EHV_FIVRA_CPU0")
	)
	(via
		(at 345.95308 -221.94774)
		(size 0.4572)
		(drill 0.2032)
		(layers "F.Cu" "B.Cu")
		(net "PVCCFA_EHV_FIVRA_CPU0")
	)
	(via
		(at 291.921438 -349.9358)
		(size 0.508)
		(drill 0.254)
		(layers "F.Cu" "B.Cu")
		(net "PVCCFA_EHV_FIVRA_CPU0")
	)
	(via
		(at 286.951166 -351.8408)
		(size 0.508)
		(drill 0.254)
		(layers "F.Cu" "B.Cu")
		(net "PVCCFA_EHV_FIVRA_CPU0")
	)
	(via
		(at 303.489868 -348.915228)
		(size 0.6604)
		(drill 0.3302)
		(layers "F.Cu" "B.Cu")
		(net "PVCCFA_EHV_FIVRA_CPU0")
	)
	(via
		(at 353.847908 -261.328916)
		(size 0.4572)
		(drill 0.2032)
		(layers "F.Cu" "B.Cu")
		(net "PVCCFA_EHV_FIVRA_CPU0")
	)
	(via
		(at 428.983648 -349.882968)
		(size 0.508)
		(drill 0.254)
		(layers "F.Cu" "B.Cu")
		(net "PVCCFA_EHV_FIVRA_CPU0")
	)
	(via
		(at 379.426216 -284.847538)
		(size 0.4572)
		(drill 0.2032)
		(layers "F.Cu" "B.Cu")
		(net "PVCCFA_EHV_FIVRA_CPU0")
	)
	(via
		(at 418.013134 -347.342968)
		(size 0.508)
		(drill 0.254)
		(layers "F.Cu" "B.Cu")
		(net "PVCCFA_EHV_FIVRA_CPU0")
	)
	(via
		(at 295.980866 -351.8408)
		(size 0.508)
		(drill 0.254)
		(layers "F.Cu" "B.Cu")
		(net "PVCCFA_EHV_FIVRA_CPU0")
	)
	(via
		(at 365.329216 -275.08073)
		(size 0.4572)
		(drill 0.2032)
		(layers "F.Cu" "B.Cu")
		(net "PVCCFA_EHV_FIVRA_CPU0")
	)
	(via
		(at 342.19388 -225.203258)
		(size 0.4572)
		(drill 0.2032)
		(layers "F.Cu" "B.Cu")
		(net "PVCCFA_EHV_FIVRA_CPU0")
	)
	(via
		(at 306.078382 -254.649478)
		(size 0.4572)
		(drill 0.2032)
		(layers "F.Cu" "B.Cu")
		(net "PVCCFA_EHV_FIVRA_CPU0")
	)
	(via
		(at 313.360562 -253.900432)
		(size 0.4572)
		(drill 0.2032)
		(layers "F.Cu" "B.Cu")
		(net "PVCCFA_EHV_FIVRA_CPU0")
	)
	(via
		(at 414.325562 -349.882968)
		(size 0.508)
		(drill 0.254)
		(layers "F.Cu" "B.Cu")
		(net "PVCCFA_EHV_FIVRA_CPU0")
	)
	(via
		(at 290.638738 -348.0308)
		(size 0.508)
		(drill 0.254)
		(layers "F.Cu" "B.Cu")
		(net "PVCCFA_EHV_FIVRA_CPU0")
	)
	(via
		(at 295.980866 -350.5708)
		(size 0.508)
		(drill 0.254)
		(layers "F.Cu" "B.Cu")
		(net "PVCCFA_EHV_FIVRA_CPU0")
	)
	(via
		(at 433.31384 -349.870268)
		(size 0.762)
		(drill 0.381)
		(layers "F.Cu" "B.Cu")
		(net "PVCCFA_EHV_FIVRA_CPU0")
	)
	(via
		(at 428.335948 -349.882968)
		(size 0.508)
		(drill 0.254)
		(layers "F.Cu" "B.Cu")
		(net "PVCCFA_EHV_FIVRA_CPU0")
	)
	(via
		(at 366.269016 -275.08073)
		(size 0.4572)
		(drill 0.2032)
		(layers "F.Cu" "B.Cu")
		(net "PVCCFA_EHV_FIVRA_CPU0")
	)
	(via
		(at 339.484716 -280.778204)
		(size 0.4572)
		(drill 0.2032)
		(layers "F.Cu" "B.Cu")
		(net "PVCCFA_EHV_FIVRA_CPU0")
	)
	(via
		(at 349.352616 -288.103056)
		(size 0.4572)
		(drill 0.2032)
		(layers "F.Cu" "B.Cu")
		(net "PVCCFA_EHV_FIVRA_CPU0")
	)
	(via
		(at 413.677862 -349.247968)
		(size 0.508)
		(drill 0.254)
		(layers "F.Cu" "B.Cu")
		(net "PVCCFA_EHV_FIVRA_CPU0")
	)
	(via
		(at 406.270206 -253.91491)
		(size 0.4572)
		(drill 0.2032)
		(layers "F.Cu" "B.Cu")
		(net "PVCCFA_EHV_FIVRA_CPU0")
	)
	(via
		(at 285.668466 -348.0308)
		(size 0.508)
		(drill 0.254)
		(layers "F.Cu" "B.Cu")
		(net "PVCCFA_EHV_FIVRA_CPU0")
	)
	(via
		(at 306.713382 -254.649478)
		(size 0.4572)
		(drill 0.2032)
		(layers "F.Cu" "B.Cu")
		(net "PVCCFA_EHV_FIVRA_CPU0")
	)
	(via
		(at 418.013134 -351.152968)
		(size 0.508)
		(drill 0.254)
		(layers "F.Cu" "B.Cu")
		(net "PVCCFA_EHV_FIVRA_CPU0")
	)
	(via
		(at 432.515518 -349.07855)
		(size 0.6604)
		(drill 0.3302)
		(layers "F.Cu" "B.Cu")
		(net "PVCCFA_EHV_FIVRA_CPU0")
	)
	(via
		(at 424.002962 -351.152968)
		(size 0.508)
		(drill 0.254)
		(layers "F.Cu" "B.Cu")
		(net "PVCCFA_EHV_FIVRA_CPU0")
	)
	(via
		(at 295.345866 -349.3008)
		(size 0.508)
		(drill 0.254)
		(layers "F.Cu" "B.Cu")
		(net "PVCCFA_EHV_FIVRA_CPU0")
	)
	(via
		(at 344.07348 -218.692222)
		(size 0.4572)
		(drill 0.2032)
		(layers "F.Cu" "B.Cu")
		(net "PVCCFA_EHV_FIVRA_CPU0")
	)
	(via
		(at 379.78588 -218.692222)
		(size 0.4572)
		(drill 0.2032)
		(layers "F.Cu" "B.Cu")
		(net "PVCCFA_EHV_FIVRA_CPU0")
	)
	(via
		(at 290.638738 -349.9358)
		(size 0.508)
		(drill 0.254)
		(layers "F.Cu" "B.Cu")
		(net "PVCCFA_EHV_FIVRA_CPU0")
	)
	(via
		(at 418.013134 -350.517968)
		(size 0.508)
		(drill 0.254)
		(layers "F.Cu" "B.Cu")
		(net "PVCCFA_EHV_FIVRA_CPU0")
	)
	(via
		(at 429.618648 -351.152968)
		(size 0.508)
		(drill 0.254)
		(layers "F.Cu" "B.Cu")
		(net "PVCCFA_EHV_FIVRA_CPU0")
	)
	(via
		(at 373.787416 -288.103056)
		(size 0.4572)
		(drill 0.2032)
		(layers "F.Cu" "B.Cu")
		(net "PVCCFA_EHV_FIVRA_CPU0")
	)
	(via
		(at 300.417738 -349.3008)
		(size 0.508)
		(drill 0.254)
		(layers "F.Cu" "B.Cu")
		(net "PVCCFA_EHV_FIVRA_CPU0")
	)
	(via
		(at 285.668466 -351.8408)
		(size 0.508)
		(drill 0.254)
		(layers "F.Cu" "B.Cu")
		(net "PVCCFA_EHV_FIVRA_CPU0")
	)
	(via
		(at 340.31428 -218.692222)
		(size 0.4572)
		(drill 0.2032)
		(layers "F.Cu" "B.Cu")
		(net "PVCCFA_EHV_FIVRA_CPU0")
	)
	(via
		(at 347.942662 -280.778204)
		(size 0.4572)
		(drill 0.2032)
		(layers "F.Cu" "B.Cu")
		(net "PVCCFA_EHV_FIVRA_CPU0")
	)
	(via
		(at 418.013134 -349.247968)
		(size 0.508)
		(drill 0.254)
		(layers "F.Cu" "B.Cu")
		(net "PVCCFA_EHV_FIVRA_CPU0")
	)
	(via
		(at 295.980866 -351.2058)
		(size 0.508)
		(drill 0.254)
		(layers "F.Cu" "B.Cu")
		(net "PVCCFA_EHV_FIVRA_CPU0")
	)
	(via
		(at 413.677862 -351.152968)
		(size 0.508)
		(drill 0.254)
		(layers "F.Cu" "B.Cu")
		(net "PVCCFA_EHV_FIVRA_CPU0")
	)
	(via
		(at 424.002962 -349.882968)
		(size 0.508)
		(drill 0.254)
		(layers "F.Cu" "B.Cu")
		(net "PVCCFA_EHV_FIVRA_CPU0")
	)
	(via
		(at 301.700438 -348.0308)
		(size 0.508)
		(drill 0.254)
		(layers "F.Cu" "B.Cu")
		(net "PVCCFA_EHV_FIVRA_CPU0")
	)
	(via
		(at 341.364062 -280.778204)
		(size 0.4572)
		(drill 0.2032)
		(layers "F.Cu" "B.Cu")
		(net "PVCCFA_EHV_FIVRA_CPU0")
	)
	(via
		(at 429.618648 -349.247968)
		(size 0.508)
		(drill 0.254)
		(layers "F.Cu" "B.Cu")
		(net "PVCCFA_EHV_FIVRA_CPU0")
	)
	(via
		(at 368.148616 -284.847538)
		(size 0.4572)
		(drill 0.2032)
		(layers "F.Cu" "B.Cu")
		(net "PVCCFA_EHV_FIVRA_CPU0")
	)
	(via
		(at 295.980866 -349.9358)
		(size 0.508)
		(drill 0.254)
		(layers "F.Cu" "B.Cu")
		(net "PVCCFA_EHV_FIVRA_CPU0")
	)
	(via
		(at 414.325562 -348.612968)
		(size 0.508)
		(drill 0.254)
		(layers "F.Cu" "B.Cu")
		(net "PVCCFA_EHV_FIVRA_CPU0")
	)
	(via
		(at 412.378906 -254.03429)
		(size 0.4572)
		(drill 0.2032)
		(layers "F.Cu" "B.Cu")
		(net "PVCCFA_EHV_FIVRA_CPU0")
	)
	(via
		(at 291.286438 -350.5708)
		(size 0.508)
		(drill 0.254)
		(layers "F.Cu" "B.Cu")
		(net "PVCCFA_EHV_FIVRA_CPU0")
	)
	(via
		(at 352.05162 -239.309402)
		(size 0.4572)
		(drill 0.2032)
		(layers "F.Cu" "B.Cu")
		(net "PVCCFA_EHV_FIVRA_CPU0")
	)
	(via
		(at 301.065438 -350.5708)
		(size 0.508)
		(drill 0.254)
		(layers "F.Cu" "B.Cu")
		(net "PVCCFA_EHV_FIVRA_CPU0")
	)
	(via
		(at 429.618648 -350.517968)
		(size 0.508)
		(drill 0.254)
		(layers "F.Cu" "B.Cu")
		(net "PVCCFA_EHV_FIVRA_CPU0")
	)
	(via
		(at 286.303466 -351.8408)
		(size 0.508)
		(drill 0.254)
		(layers "F.Cu" "B.Cu")
		(net "PVCCFA_EHV_FIVRA_CPU0")
	)
	(via
		(at 381.665734 -221.94774)
		(size 0.4572)
		(drill 0.2032)
		(layers "F.Cu" "B.Cu")
		(net "PVCCFA_EHV_FIVRA_CPU0")
	)
	(via
		(at 413.042862 -349.247968)
		(size 0.508)
		(drill 0.254)
		(layers "F.Cu" "B.Cu")
		(net "PVCCFA_EHV_FIVRA_CPU0")
	)
	(via
		(at 300.417738 -349.9358)
		(size 0.508)
		(drill 0.254)
		(layers "F.Cu" "B.Cu")
		(net "PVCCFA_EHV_FIVRA_CPU0")
	)
	(via
		(at 423.355262 -347.342968)
		(size 0.508)
		(drill 0.254)
		(layers "F.Cu" "B.Cu")
		(net "PVCCFA_EHV_FIVRA_CPU0")
	)
	(via
		(at 295.345866 -350.5708)
		(size 0.508)
		(drill 0.254)
		(layers "F.Cu" "B.Cu")
		(net "PVCCFA_EHV_FIVRA_CPU0")
	)
	(via
		(at 366.738662 -279.150318)
		(size 0.4572)
		(drill 0.2032)
		(layers "F.Cu" "B.Cu")
		(net "PVCCFA_EHV_FIVRA_CPU0")
	)
	(via
		(at 337.604862 -284.033722)
		(size 0.4572)
		(drill 0.2032)
		(layers "F.Cu" "B.Cu")
		(net "PVCCFA_EHV_FIVRA_CPU0")
	)
	(via
		(at 375.667016 -284.847538)
		(size 0.4572)
		(drill 0.2032)
		(layers "F.Cu" "B.Cu")
		(net "PVCCFA_EHV_FIVRA_CPU0")
	)
	(via
		(at 291.286438 -348.0308)
		(size 0.508)
		(drill 0.254)
		(layers "F.Cu" "B.Cu")
		(net "PVCCFA_EHV_FIVRA_CPU0")
	)
	(via
		(at 286.951166 -349.9358)
		(size 0.508)
		(drill 0.254)
		(layers "F.Cu" "B.Cu")
		(net "PVCCFA_EHV_FIVRA_CPU0")
	)
	(via
		(at 379.78588 -215.436704)
		(size 0.4572)
		(drill 0.2032)
		(layers "F.Cu" "B.Cu")
		(net "PVCCFA_EHV_FIVRA_CPU0")
	)
	(via
		(at 428.983648 -351.152968)
		(size 0.508)
		(drill 0.254)
		(layers "F.Cu" "B.Cu")
		(net "PVCCFA_EHV_FIVRA_CPU0")
	)
	(via
		(at 301.065438 -348.0308)
		(size 0.508)
		(drill 0.254)
		(layers "F.Cu" "B.Cu")
		(net "PVCCFA_EHV_FIVRA_CPU0")
	)
	(via
		(at 383.545334 -225.203258)
		(size 0.4572)
		(drill 0.2032)
		(layers "F.Cu" "B.Cu")
		(net "PVCCFA_EHV_FIVRA_CPU0")
	)
	(via
		(at 333.845662 -284.033722)
		(size 0.4572)
		(drill 0.2032)
		(layers "F.Cu" "B.Cu")
		(net "PVCCFA_EHV_FIVRA_CPU0")
	)
	(via
		(at 349.71228 -225.203258)
		(size 0.4572)
		(drill 0.2032)
		(layers "F.Cu" "B.Cu")
		(net "PVCCFA_EHV_FIVRA_CPU0")
	)
	(via
		(at 382.715262 -280.778204)
		(size 0.4572)
		(drill 0.2032)
		(layers "F.Cu" "B.Cu")
		(net "PVCCFA_EHV_FIVRA_CPU0")
	)
	(via
		(at 285.668466 -349.3008)
		(size 0.508)
		(drill 0.254)
		(layers "F.Cu" "B.Cu")
		(net "PVCCFA_EHV_FIVRA_CPU0")
	)
	(via
		(at 343.713816 -288.103056)
		(size 0.4572)
		(drill 0.2032)
		(layers "F.Cu" "B.Cu")
		(net "PVCCFA_EHV_FIVRA_CPU0")
	)
	(via
		(at 413.677862 -349.882968)
		(size 0.508)
		(drill 0.254)
		(layers "F.Cu" "B.Cu")
		(net "PVCCFA_EHV_FIVRA_CPU0")
	)
	(via
		(at 424.002962 -350.517968)
		(size 0.508)
		(drill 0.254)
		(layers "F.Cu" "B.Cu")
		(net "PVCCFA_EHV_FIVRA_CPU0")
	)
	(via
		(at 423.355262 -351.152968)
		(size 0.508)
		(drill 0.254)
		(layers "F.Cu" "B.Cu")
		(net "PVCCFA_EHV_FIVRA_CPU0")
	)
	(via
		(at 300.417738 -351.2058)
		(size 0.508)
		(drill 0.254)
		(layers "F.Cu" "B.Cu")
		(net "PVCCFA_EHV_FIVRA_CPU0")
	)
	(via
		(at 419.295834 -351.152968)
		(size 0.508)
		(drill 0.254)
		(layers "F.Cu" "B.Cu")
		(net "PVCCFA_EHV_FIVRA_CPU0")
	)
	(via
		(at 354.482908 -261.328916)
		(size 0.4572)
		(drill 0.2032)
		(layers "F.Cu" "B.Cu")
		(net "PVCCFA_EHV_FIVRA_CPU0")
	)
	(via
		(at 368.297968 -239.31753)
		(size 0.4572)
		(drill 0.2032)
		(layers "F.Cu" "B.Cu")
		(net "PVCCFA_EHV_FIVRA_CPU0")
	)
	(via
		(at 376.02668 -218.692222)
		(size 0.4572)
		(drill 0.2032)
		(layers "F.Cu" "B.Cu")
		(net "PVCCFA_EHV_FIVRA_CPU0")
	)
	(via
		(at 291.286438 -348.6658)
		(size 0.508)
		(drill 0.254)
		(layers "F.Cu" "B.Cu")
		(net "PVCCFA_EHV_FIVRA_CPU0")
	)
	(via
		(at 301.700438 -348.6658)
		(size 0.508)
		(drill 0.254)
		(layers "F.Cu" "B.Cu")
		(net "PVCCFA_EHV_FIVRA_CPU0")
	)
	(via
		(at 413.677862 -347.977968)
		(size 0.508)
		(drill 0.254)
		(layers "F.Cu" "B.Cu")
		(net "PVCCFA_EHV_FIVRA_CPU0")
	)
	(via
		(at 370.028216 -276.708616)
		(size 0.4572)
		(drill 0.2032)
		(layers "F.Cu" "B.Cu")
		(net "PVCCFA_EHV_FIVRA_CPU0")
	)
	(via
		(at 413.042862 -347.342968)
		(size 0.508)
		(drill 0.254)
		(layers "F.Cu" "B.Cu")
		(net "PVCCFA_EHV_FIVRA_CPU0")
	)
	(via
		(at 422.720262 -351.152968)
		(size 0.508)
		(drill 0.254)
		(layers "F.Cu" "B.Cu")
		(net "PVCCFA_EHV_FIVRA_CPU0")
	)
	(via
		(at 309.032402 -254.10033)
		(size 0.4572)
		(drill 0.2032)
		(layers "F.Cu" "B.Cu")
		(net "PVCCFA_EHV_FIVRA_CPU0")
	)
	(via
		(at 419.295834 -347.342968)
		(size 0.508)
		(drill 0.254)
		(layers "F.Cu" "B.Cu")
		(net "PVCCFA_EHV_FIVRA_CPU0")
	)
	(via
		(at 285.668466 -348.6658)
		(size 0.508)
		(drill 0.254)
		(layers "F.Cu" "B.Cu")
		(net "PVCCFA_EHV_FIVRA_CPU0")
	)
	(via
		(at 345.593416 -284.847538)
		(size 0.4572)
		(drill 0.2032)
		(layers "F.Cu" "B.Cu")
		(net "PVCCFA_EHV_FIVRA_CPU0")
	)
	(via
		(at 381.665734 -218.692222)
		(size 0.4572)
		(drill 0.2032)
		(layers "F.Cu" "B.Cu")
		(net "PVCCFA_EHV_FIVRA_CPU0")
	)
	(via
		(at 347.83268 -218.692222)
		(size 0.4572)
		(drill 0.2032)
		(layers "F.Cu" "B.Cu")
		(net "PVCCFA_EHV_FIVRA_CPU0")
	)
	(via
		(at 291.286438 -351.8408)
		(size 0.508)
		(drill 0.254)
		(layers "F.Cu" "B.Cu")
		(net "PVCCFA_EHV_FIVRA_CPU0")
	)
	(via
		(at 365.329216 -279.964134)
		(size 0.4572)
		(drill 0.2032)
		(layers "F.Cu" "B.Cu")
		(net "PVCCFA_EHV_FIVRA_CPU0")
	)
	(via
		(at 307.348382 -254.649478)
		(size 0.4572)
		(drill 0.2032)
		(layers "F.Cu" "B.Cu")
		(net "PVCCFA_EHV_FIVRA_CPU0")
	)
	(via
		(at 377.90628 -215.436704)
		(size 0.4572)
		(drill 0.2032)
		(layers "F.Cu" "B.Cu")
		(net "PVCCFA_EHV_FIVRA_CPU0")
	)
	(via
		(at 381.665734 -225.203258)
		(size 0.4572)
		(drill 0.2032)
		(layers "F.Cu" "B.Cu")
		(net "PVCCFA_EHV_FIVRA_CPU0")
	)
	(via
		(at 422.720262 -349.247968)
		(size 0.508)
		(drill 0.254)
		(layers "F.Cu" "B.Cu")
		(net "PVCCFA_EHV_FIVRA_CPU0")
	)
	(via
		(at 413.677862 -347.342968)
		(size 0.508)
		(drill 0.254)
		(layers "F.Cu" "B.Cu")
		(net "PVCCFA_EHV_FIVRA_CPU0")
	)
	(via
		(at 414.325562 -350.517968)
		(size 0.508)
		(drill 0.254)
		(layers "F.Cu" "B.Cu")
		(net "PVCCFA_EHV_FIVRA_CPU0")
	)
	(via
		(at 412.712662 -365.98225)
		(size 0.508)
		(drill 0.254)
		(layers "F.Cu" "B.Cu")
		(net "PVCCFA_EHV_FIVRA_CPU0")
	)
	(via
		(at 355.461062 -279.150318)
		(size 0.4572)
		(drill 0.2032)
		(layers "F.Cu" "B.Cu")
		(net "PVCCFA_EHV_FIVRA_CPU0")
	)
	(via
		(at 371.907816 -284.847538)
		(size 0.4572)
		(drill 0.2032)
		(layers "F.Cu" "B.Cu")
		(net "PVCCFA_EHV_FIVRA_CPU0")
	)
	(via
		(at 340.31428 -225.203258)
		(size 0.4572)
		(drill 0.2032)
		(layers "F.Cu" "B.Cu")
		(net "PVCCFA_EHV_FIVRA_CPU0")
	)
	(via
		(at 291.286438 -349.3008)
		(size 0.508)
		(drill 0.254)
		(layers "F.Cu" "B.Cu")
		(net "PVCCFA_EHV_FIVRA_CPU0")
	)
	(via
		(at 341.833962 -279.964134)
		(size 0.4572)
		(drill 0.2032)
		(layers "F.Cu" "B.Cu")
		(net "PVCCFA_EHV_FIVRA_CPU0")
	)
	(via
		(at 345.123262 -279.150318)
		(size 0.4572)
		(drill 0.2032)
		(layers "F.Cu" "B.Cu")
		(net "PVCCFA_EHV_FIVRA_CPU0")
	)
	(via
		(at 418.013134 -347.977968)
		(size 0.508)
		(drill 0.254)
		(layers "F.Cu" "B.Cu")
		(net "PVCCFA_EHV_FIVRA_CPU0")
	)
	(via
		(at 429.618648 -347.977968)
		(size 0.508)
		(drill 0.254)
		(layers "F.Cu" "B.Cu")
		(net "PVCCFA_EHV_FIVRA_CPU0")
	)
	(via
		(at 362.979462 -275.8948)
		(size 0.4572)
		(drill 0.2032)
		(layers "F.Cu" "B.Cu")
		(net "PVCCFA_EHV_FIVRA_CPU0")
	)
	(via
		(at 296.628566 -348.0308)
		(size 0.508)
		(drill 0.254)
		(layers "F.Cu" "B.Cu")
		(net "PVCCFA_EHV_FIVRA_CPU0")
	)
	(via
		(at 432.34102 -351.973388)
		(size 0.762)
		(drill 0.381)
		(layers "F.Cu" "B.Cu")
		(net "PVCCFA_EHV_FIVRA_CPU0")
	)
	(via
		(at 382.245616 -279.964134)
		(size 0.4572)
		(drill 0.2032)
		(layers "F.Cu" "B.Cu")
		(net "PVCCFA_EHV_FIVRA_CPU0")
	)
	(via
		(at 413.677862 -350.517968)
		(size 0.508)
		(drill 0.254)
		(layers "F.Cu" "B.Cu")
		(net "PVCCFA_EHV_FIVRA_CPU0")
	)
	(via
		(at 355.117908 -261.328916)
		(size 0.4572)
		(drill 0.2032)
		(layers "F.Cu" "B.Cu")
		(net "PVCCFA_EHV_FIVRA_CPU0")
	)
	(via
		(at 291.921438 -351.8408)
		(size 0.508)
		(drill 0.254)
		(layers "F.Cu" "B.Cu")
		(net "PVCCFA_EHV_FIVRA_CPU0")
	)
	(via
		(at 428.983648 -348.612968)
		(size 0.508)
		(drill 0.254)
		(layers "F.Cu" "B.Cu")
		(net "PVCCFA_EHV_FIVRA_CPU0")
	)
	(via
		(at 290.638738 -348.6658)
		(size 0.508)
		(drill 0.254)
		(layers "F.Cu" "B.Cu")
		(net "PVCCFA_EHV_FIVRA_CPU0")
	)
	(via
		(at 364.952534 -261.328916)
		(size 0.4572)
		(drill 0.2032)
		(layers "F.Cu" "B.Cu")
		(net "PVCCFA_EHV_FIVRA_CPU0")
	)
	(via
		(at 428.335948 -347.342968)
		(size 0.508)
		(drill 0.254)
		(layers "F.Cu" "B.Cu")
		(net "PVCCFA_EHV_FIVRA_CPU0")
	)
	(via
		(at 418.013134 -348.612968)
		(size 0.508)
		(drill 0.254)
		(layers "F.Cu" "B.Cu")
		(net "PVCCFA_EHV_FIVRA_CPU0")
	)
	(via
		(at 296.628566 -351.2058)
		(size 0.508)
		(drill 0.254)
		(layers "F.Cu" "B.Cu")
		(net "PVCCFA_EHV_FIVRA_CPU0")
	)
	(via
		(at 375.667016 -283.219906)
		(size 0.4572)
		(drill 0.2032)
		(layers "F.Cu" "B.Cu")
		(net "PVCCFA_EHV_FIVRA_CPU0")
	)
	(via
		(at 414.325562 -347.342968)
		(size 0.508)
		(drill 0.254)
		(layers "F.Cu" "B.Cu")
		(net "PVCCFA_EHV_FIVRA_CPU0")
	)
	(via
		(at 286.951166 -351.2058)
		(size 0.508)
		(drill 0.254)
		(layers "F.Cu" "B.Cu")
		(net "PVCCFA_EHV_FIVRA_CPU0")
	)
	(via
		(at 344.07348 -225.203258)
		(size 0.4572)
		(drill 0.2032)
		(layers "F.Cu" "B.Cu")
		(net "PVCCFA_EHV_FIVRA_CPU0")
	)
	(via
		(at 413.042862 -351.152968)
		(size 0.508)
		(drill 0.254)
		(layers "F.Cu" "B.Cu")
		(net "PVCCFA_EHV_FIVRA_CPU0")
	)
	(via
		(at 286.951166 -350.5708)
		(size 0.508)
		(drill 0.254)
		(layers "F.Cu" "B.Cu")
		(net "PVCCFA_EHV_FIVRA_CPU0")
	)
	(via
		(at 413.677862 -348.612968)
		(size 0.508)
		(drill 0.254)
		(layers "F.Cu" "B.Cu")
		(net "PVCCFA_EHV_FIVRA_CPU0")
	)
	(via
		(at 300.417738 -348.6658)
		(size 0.508)
		(drill 0.254)
		(layers "F.Cu" "B.Cu")
		(net "PVCCFA_EHV_FIVRA_CPU0")
	)
	(via
		(at 385.534662 -284.033722)
		(size 0.4572)
		(drill 0.2032)
		(layers "F.Cu" "B.Cu")
		(net "PVCCFA_EHV_FIVRA_CPU0")
	)
	(via
		(at 290.638738 -350.5708)
		(size 0.508)
		(drill 0.254)
		(layers "F.Cu" "B.Cu")
		(net "PVCCFA_EHV_FIVRA_CPU0")
	)
	(via
		(at 291.921438 -348.0308)
		(size 0.508)
		(drill 0.254)
		(layers "F.Cu" "B.Cu")
		(net "PVCCFA_EHV_FIVRA_CPU0")
	)
	(via
		(at 296.628566 -350.5708)
		(size 0.508)
		(drill 0.254)
		(layers "F.Cu" "B.Cu")
		(net "PVCCFA_EHV_FIVRA_CPU0")
	)
	(via
		(at 339.954616 -288.103056)
		(size 0.4572)
		(drill 0.2032)
		(layers "F.Cu" "B.Cu")
		(net "PVCCFA_EHV_FIVRA_CPU0")
	)
	(via
		(at 370.028216 -284.847538)
		(size 0.4572)
		(drill 0.2032)
		(layers "F.Cu" "B.Cu")
		(net "PVCCFA_EHV_FIVRA_CPU0")
	)
	(via
		(at 301.700438 -349.9358)
		(size 0.508)
		(drill 0.254)
		(layers "F.Cu" "B.Cu")
		(net "PVCCFA_EHV_FIVRA_CPU0")
	)
	(via
		(at 301.065438 -348.6658)
		(size 0.508)
		(drill 0.254)
		(layers "F.Cu" "B.Cu")
		(net "PVCCFA_EHV_FIVRA_CPU0")
	)
	(via
		(at 418.660834 -347.342968)
		(size 0.508)
		(drill 0.254)
		(layers "F.Cu" "B.Cu")
		(net "PVCCFA_EHV_FIVRA_CPU0")
	)
	(via
		(at 291.921438 -350.5708)
		(size 0.508)
		(drill 0.254)
		(layers "F.Cu" "B.Cu")
		(net "PVCCFA_EHV_FIVRA_CPU0")
	)
	(via
		(at 338.43468 -221.94774)
		(size 0.4572)
		(drill 0.2032)
		(layers "F.Cu" "B.Cu")
		(net "PVCCFA_EHV_FIVRA_CPU0")
	)
	(via
		(at 301.065438 -351.2058)
		(size 0.508)
		(drill 0.254)
		(layers "F.Cu" "B.Cu")
		(net "PVCCFA_EHV_FIVRA_CPU0")
	)
	(via
		(at 336.195162 -288.103056)
		(size 0.4572)
		(drill 0.2032)
		(layers "F.Cu" "B.Cu")
		(net "PVCCFA_EHV_FIVRA_CPU0")
	)
	(via
		(at 336.665062 -280.778204)
		(size 0.4572)
		(drill 0.2032)
		(layers "F.Cu" "B.Cu")
		(net "PVCCFA_EHV_FIVRA_CPU0")
	)
	(via
		(at 286.951166 -348.0308)
		(size 0.508)
		(drill 0.254)
		(layers "F.Cu" "B.Cu")
		(net "PVCCFA_EHV_FIVRA_CPU0")
	)
	(via
		(at 345.95308 -218.692222)
		(size 0.4572)
		(drill 0.2032)
		(layers "F.Cu" "B.Cu")
		(net "PVCCFA_EHV_FIVRA_CPU0")
	)
	(via
		(at 377.546616 -288.103056)
		(size 0.4572)
		(drill 0.2032)
		(layers "F.Cu" "B.Cu")
		(net "PVCCFA_EHV_FIVRA_CPU0")
	)
	(via
		(at 343.713816 -284.847538)
		(size 0.4572)
		(drill 0.2032)
		(layers "F.Cu" "B.Cu")
		(net "PVCCFA_EHV_FIVRA_CPU0")
	)
	(via
		(at 291.921438 -348.6658)
		(size 0.508)
		(drill 0.254)
		(layers "F.Cu" "B.Cu")
		(net "PVCCFA_EHV_FIVRA_CPU0")
	)
	(via
		(at 367.713768 -239.31753)
		(size 0.4572)
		(drill 0.2032)
		(layers "F.Cu" "B.Cu")
		(net "PVCCFA_EHV_FIVRA_CPU0")
	)
	(via
		(at 379.78588 -225.203258)
		(size 0.4572)
		(drill 0.2032)
		(layers "F.Cu" "B.Cu")
		(net "PVCCFA_EHV_FIVRA_CPU0")
	)
	(via
		(at 376.02668 -221.94774)
		(size 0.4572)
		(drill 0.2032)
		(layers "F.Cu" "B.Cu")
		(net "PVCCFA_EHV_FIVRA_CPU0")
	)
	(via
		(at 344.07348 -221.94774)
		(size 0.4572)
		(drill 0.2032)
		(layers "F.Cu" "B.Cu")
		(net "PVCCFA_EHV_FIVRA_CPU0")
	)
	(via
		(at 422.720262 -347.342968)
		(size 0.508)
		(drill 0.254)
		(layers "F.Cu" "B.Cu")
		(net "PVCCFA_EHV_FIVRA_CPU0")
	)
	(via
		(at 352.577908 -261.328916)
		(size 0.4572)
		(drill 0.2032)
		(layers "F.Cu" "B.Cu")
		(net "PVCCFA_EHV_FIVRA_CPU0")
	)
	(via
		(at 429.618648 -349.882968)
		(size 0.508)
		(drill 0.254)
		(layers "F.Cu" "B.Cu")
		(net "PVCCFA_EHV_FIVRA_CPU0")
	)
	(via
		(at 353.212908 -261.328916)
		(size 0.4572)
		(drill 0.2032)
		(layers "F.Cu" "B.Cu")
		(net "PVCCFA_EHV_FIVRA_CPU0")
	)
	(via
		(at 350.762062 -277.522432)
		(size 0.4572)
		(drill 0.2032)
		(layers "F.Cu" "B.Cu")
		(net "PVCCFA_EHV_FIVRA_CPU0")
	)
	(via
		(at 295.345866 -349.9358)
		(size 0.508)
		(drill 0.254)
		(layers "F.Cu" "B.Cu")
		(net "PVCCFA_EHV_FIVRA_CPU0")
	)
	(via
		(at 367.208816 -275.08073)
		(size 0.4572)
		(drill 0.2032)
		(layers "F.Cu" "B.Cu")
		(net "PVCCFA_EHV_FIVRA_CPU0")
	)
	(via
		(at 413.042862 -348.612968)
		(size 0.508)
		(drill 0.254)
		(layers "F.Cu" "B.Cu")
		(net "PVCCFA_EHV_FIVRA_CPU0")
	)
	(via
		(at 367.129568 -239.31753)
		(size 0.4572)
		(drill 0.2032)
		(layers "F.Cu" "B.Cu")
		(net "PVCCFA_EHV_FIVRA_CPU0")
	)
	(via
		(at 344.653616 -278.336502)
		(size 0.4572)
		(drill 0.2032)
		(layers "F.Cu" "B.Cu")
		(net "PVCCFA_EHV_FIVRA_CPU0")
	)
	(via
		(at 413.042862 -350.517968)
		(size 0.508)
		(drill 0.254)
		(layers "F.Cu" "B.Cu")
		(net "PVCCFA_EHV_FIVRA_CPU0")
	)
	(via
		(at 350.88322 -239.309402)
		(size 0.4572)
		(drill 0.2032)
		(layers "F.Cu" "B.Cu")
		(net "PVCCFA_EHV_FIVRA_CPU0")
	)
	(via
		(at 336.555334 -218.692222)
		(size 0.4572)
		(drill 0.2032)
		(layers "F.Cu" "B.Cu")
		(net "PVCCFA_EHV_FIVRA_CPU0")
	)
	(via
		(at 419.295834 -349.882968)
		(size 0.508)
		(drill 0.254)
		(layers "F.Cu" "B.Cu")
		(net "PVCCFA_EHV_FIVRA_CPU0")
	)
	(via
		(at 285.338266 -366.670082)
		(size 0.508)
		(drill 0.254)
		(layers "F.Cu" "B.Cu")
		(net "PVCCFA_EHV_FIVRA_CPU0")
	)
	(via
		(at 424.002962 -347.342968)
		(size 0.508)
		(drill 0.254)
		(layers "F.Cu" "B.Cu")
		(net "PVCCFA_EHV_FIVRA_CPU0")
	)
	(via
		(at 428.983648 -350.517968)
		(size 0.508)
		(drill 0.254)
		(layers "F.Cu" "B.Cu")
		(net "PVCCFA_EHV_FIVRA_CPU0")
	)
	(via
		(at 342.19388 -221.94774)
		(size 0.4572)
		(drill 0.2032)
		(layers "F.Cu" "B.Cu")
		(net "PVCCFA_EHV_FIVRA_CPU0")
	)
	(via
		(at 353.581462 -274.266914)
		(size 0.4572)
		(drill 0.2032)
		(layers "F.Cu" "B.Cu")
		(net "PVCCFA_EHV_FIVRA_CPU0")
	)
	(via
		(at 413.067246 -254.71755)
		(size 0.4572)
		(drill 0.2032)
		(layers "F.Cu" "B.Cu")
		(net "PVCCFA_EHV_FIVRA_CPU0")
	)
	(via
		(at 381.305816 -279.964134)
		(size 0.4572)
		(drill 0.2032)
		(layers "F.Cu" "B.Cu")
		(net "PVCCFA_EHV_FIVRA_CPU0")
	)
	(via
		(at 355.461062 -274.266914)
		(size 0.4572)
		(drill 0.2032)
		(layers "F.Cu" "B.Cu")
		(net "PVCCFA_EHV_FIVRA_CPU0")
	)
	(via
		(at 423.355262 -349.247968)
		(size 0.508)
		(drill 0.254)
		(layers "F.Cu" "B.Cu")
		(net "PVCCFA_EHV_FIVRA_CPU0")
	)
	(via
		(at 422.720262 -350.517968)
		(size 0.508)
		(drill 0.254)
		(layers "F.Cu" "B.Cu")
		(net "PVCCFA_EHV_FIVRA_CPU0")
	)
	(via
		(at 291.286438 -349.9358)
		(size 0.508)
		(drill 0.254)
		(layers "F.Cu" "B.Cu")
		(net "PVCCFA_EHV_FIVRA_CPU0")
	)
	(via
		(at 424.002962 -349.247968)
		(size 0.508)
		(drill 0.254)
		(layers "F.Cu" "B.Cu")
		(net "PVCCFA_EHV_FIVRA_CPU0")
	)
	(via
		(at 423.355262 -347.977968)
		(size 0.508)
		(drill 0.254)
		(layers "F.Cu" "B.Cu")
		(net "PVCCFA_EHV_FIVRA_CPU0")
	)
	(via
		(at 413.042862 -347.977968)
		(size 0.508)
		(drill 0.254)
		(layers "F.Cu" "B.Cu")
		(net "PVCCFA_EHV_FIVRA_CPU0")
	)
	(via
		(at 364.317534 -261.328916)
		(size 0.4572)
		(drill 0.2032)
		(layers "F.Cu" "B.Cu")
		(net "PVCCFA_EHV_FIVRA_CPU0")
	)
	(via
		(at 295.980866 -349.3008)
		(size 0.508)
		(drill 0.254)
		(layers "F.Cu" "B.Cu")
		(net "PVCCFA_EHV_FIVRA_CPU0")
	)
	(via
		(at 286.303466 -349.3008)
		(size 0.508)
		(drill 0.254)
		(layers "F.Cu" "B.Cu")
		(net "PVCCFA_EHV_FIVRA_CPU0")
	)
	(via
		(at 291.921438 -349.3008)
		(size 0.508)
		(drill 0.254)
		(layers "F.Cu" "B.Cu")
		(net "PVCCFA_EHV_FIVRA_CPU0")
	)
	(via
		(at 312.679842 -253.9111)
		(size 0.4572)
		(drill 0.2032)
		(layers "F.Cu" "B.Cu")
		(net "PVCCFA_EHV_FIVRA_CPU0")
	)
	(via
		(at 296.628566 -348.6658)
		(size 0.508)
		(drill 0.254)
		(layers "F.Cu" "B.Cu")
		(net "PVCCFA_EHV_FIVRA_CPU0")
	)
	(via
		(at 345.593416 -288.103056)
		(size 0.4572)
		(drill 0.2032)
		(layers "F.Cu" "B.Cu")
		(net "PVCCFA_EHV_FIVRA_CPU0")
	)
	(via
		(at 412.391606 -254.72771)
		(size 0.4572)
		(drill 0.2032)
		(layers "F.Cu" "B.Cu")
		(net "PVCCFA_EHV_FIVRA_CPU0")
	)
	(via
		(at 377.90628 -218.692222)
		(size 0.4572)
		(drill 0.2032)
		(layers "F.Cu" "B.Cu")
		(net "PVCCFA_EHV_FIVRA_CPU0")
	)
	(via
		(at 429.618648 -347.342968)
		(size 0.508)
		(drill 0.254)
		(layers "F.Cu" "B.Cu")
		(net "PVCCFA_EHV_FIVRA_CPU0")
	)
	(via
		(at 418.660834 -349.247968)
		(size 0.508)
		(drill 0.254)
		(layers "F.Cu" "B.Cu")
		(net "PVCCFA_EHV_FIVRA_CPU0")
	)
	(via
		(at 340.31428 -221.94774)
		(size 0.4572)
		(drill 0.2032)
		(layers "F.Cu" "B.Cu")
		(net "PVCCFA_EHV_FIVRA_CPU0")
	)
	(via
		(at 341.834216 -284.847538)
		(size 0.4572)
		(drill 0.2032)
		(layers "F.Cu" "B.Cu")
		(net "PVCCFA_EHV_FIVRA_CPU0")
	)
	(via
		(at 333.845662 -287.28924)
		(size 0.4572)
		(drill 0.2032)
		(layers "F.Cu" "B.Cu")
		(net "PVCCFA_EHV_FIVRA_CPU0")
	)
	(via
		(at 286.303466 -351.2058)
		(size 0.508)
		(drill 0.254)
		(layers "F.Cu" "B.Cu")
		(net "PVCCFA_EHV_FIVRA_CPU0")
	)
	(via
		(at 424.002962 -348.612968)
		(size 0.508)
		(drill 0.254)
		(layers "F.Cu" "B.Cu")
		(net "PVCCFA_EHV_FIVRA_CPU0")
	)
	(via
		(at 418.660834 -350.517968)
		(size 0.508)
		(drill 0.254)
		(layers "F.Cu" "B.Cu")
		(net "PVCCFA_EHV_FIVRA_CPU0")
	)
	(via
		(at 290.638738 -351.2058)
		(size 0.508)
		(drill 0.254)
		(layers "F.Cu" "B.Cu")
		(net "PVCCFA_EHV_FIVRA_CPU0")
	)
	(via
		(at 296.628566 -351.8408)
		(size 0.508)
		(drill 0.254)
		(layers "F.Cu" "B.Cu")
		(net "PVCCFA_EHV_FIVRA_CPU0")
	)
	(via
		(at 419.295834 -347.977968)
		(size 0.508)
		(drill 0.254)
		(layers "F.Cu" "B.Cu")
		(net "PVCCFA_EHV_FIVRA_CPU0")
	)
	(via
		(at 370.028216 -279.964134)
		(size 0.4572)
		(drill 0.2032)
		(layers "F.Cu" "B.Cu")
		(net "PVCCFA_EHV_FIVRA_CPU0")
	)
	(via
		(at 307.983382 -254.649478)
		(size 0.4572)
		(drill 0.2032)
		(layers "F.Cu" "B.Cu")
		(net "PVCCFA_EHV_FIVRA_CPU0")
	)
	(via
		(at 428.335948 -348.612968)
		(size 0.508)
		(drill 0.254)
		(layers "F.Cu" "B.Cu")
		(net "PVCCFA_EHV_FIVRA_CPU0")
	)
	(via
		(at 370.028216 -288.103056)
		(size 0.4572)
		(drill 0.2032)
		(layers "F.Cu" "B.Cu")
		(net "PVCCFA_EHV_FIVRA_CPU0")
	)
	(via
		(at 371.907816 -283.219906)
		(size 0.4572)
		(drill 0.2032)
		(layers "F.Cu" "B.Cu")
		(net "PVCCFA_EHV_FIVRA_CPU0")
	)
	(via
		(at 422.400984 -365.994188)
		(size 0.508)
		(drill 0.254)
		(layers "F.Cu" "B.Cu")
		(net "PVCCFA_EHV_FIVRA_CPU0")
	)
	(via
		(at 422.720262 -349.882968)
		(size 0.508)
		(drill 0.254)
		(layers "F.Cu" "B.Cu")
		(net "PVCCFA_EHV_FIVRA_CPU0")
	)
	(via
		(at 428.335948 -347.977968)
		(size 0.508)
		(drill 0.254)
		(layers "F.Cu" "B.Cu")
		(net "PVCCFA_EHV_FIVRA_CPU0")
	)
	(via
		(at 341.834216 -288.103056)
		(size 0.4572)
		(drill 0.2032)
		(layers "F.Cu" "B.Cu")
		(net "PVCCFA_EHV_FIVRA_CPU0")
	)
	(via
		(at 375.667016 -288.103056)
		(size 0.4572)
		(drill 0.2032)
		(layers "F.Cu" "B.Cu")
		(net "PVCCFA_EHV_FIVRA_CPU0")
	)
	(via
		(at 342.19388 -218.692222)
		(size 0.4572)
		(drill 0.2032)
		(layers "F.Cu" "B.Cu")
		(net "PVCCFA_EHV_FIVRA_CPU0")
	)
	(via
		(at 300.417738 -348.0308)
		(size 0.508)
		(drill 0.254)
		(layers "F.Cu" "B.Cu")
		(net "PVCCFA_EHV_FIVRA_CPU0")
	)
	(via
		(at 414.325562 -351.152968)
		(size 0.508)
		(drill 0.254)
		(layers "F.Cu" "B.Cu")
		(net "PVCCFA_EHV_FIVRA_CPU0")
	)
	(via
		(at 347.83268 -225.203258)
		(size 0.4572)
		(drill 0.2032)
		(layers "F.Cu" "B.Cu")
		(net "PVCCFA_EHV_FIVRA_CPU0")
	)
	(via
		(at 286.951166 -349.3008)
		(size 0.508)
		(drill 0.254)
		(layers "F.Cu" "B.Cu")
		(net "PVCCFA_EHV_FIVRA_CPU0")
	)
	(via
		(at 295.345866 -348.6658)
		(size 0.508)
		(drill 0.254)
		(layers "F.Cu" "B.Cu")
		(net "PVCCFA_EHV_FIVRA_CPU0")
	)
	(via
		(at 428.335948 -351.152968)
		(size 0.508)
		(drill 0.254)
		(layers "F.Cu" "B.Cu")
		(net "PVCCFA_EHV_FIVRA_CPU0")
	)
	(via
		(at 428.335948 -349.247968)
		(size 0.508)
		(drill 0.254)
		(layers "F.Cu" "B.Cu")
		(net "PVCCFA_EHV_FIVRA_CPU0")
	)
	(via
		(at 301.065438 -349.9358)
		(size 0.508)
		(drill 0.254)
		(layers "F.Cu" "B.Cu")
		(net "PVCCFA_EHV_FIVRA_CPU0")
	)
	(via
		(at 338.43468 -218.692222)
		(size 0.4572)
		(drill 0.2032)
		(layers "F.Cu" "B.Cu")
		(net "PVCCFA_EHV_FIVRA_CPU0")
	)
	(via
		(at 303.388268 -350.675448)
		(size 0.6604)
		(drill 0.3302)
		(layers "F.Cu" "B.Cu")
		(net "PVCCFA_EHV_FIVRA_CPU0")
	)
	(via
		(at 290.638738 -351.8408)
		(size 0.508)
		(drill 0.254)
		(layers "F.Cu" "B.Cu")
		(net "PVCCFA_EHV_FIVRA_CPU0")
	)
	(via
		(at 365.587534 -261.328916)
		(size 0.4572)
		(drill 0.2032)
		(layers "F.Cu" "B.Cu")
		(net "PVCCFA_EHV_FIVRA_CPU0")
	)
	(via
		(at 377.90628 -225.203258)
		(size 0.4572)
		(drill 0.2032)
		(layers "F.Cu" "B.Cu")
		(net "PVCCFA_EHV_FIVRA_CPU0")
	)
	(via
		(at 354.051616 -278.336502)
		(size 0.4572)
		(drill 0.2032)
		(layers "F.Cu" "B.Cu")
		(net "PVCCFA_EHV_FIVRA_CPU0")
	)
	(via
		(at 345.95308 -225.203258)
		(size 0.4572)
		(drill 0.2032)
		(layers "F.Cu" "B.Cu")
		(net "PVCCFA_EHV_FIVRA_CPU0")
	)
	(via
		(at 301.065438 -351.8408)
		(size 0.508)
		(drill 0.254)
		(layers "F.Cu" "B.Cu")
		(net "PVCCFA_EHV_FIVRA_CPU0")
	)
	(via
		(at 424.002962 -347.977968)
		(size 0.508)
		(drill 0.254)
		(layers "F.Cu" "B.Cu")
		(net "PVCCFA_EHV_FIVRA_CPU0")
	)
	(via
		(at 429.618648 -348.612968)
		(size 0.508)
		(drill 0.254)
		(layers "F.Cu" "B.Cu")
		(net "PVCCFA_EHV_FIVRA_CPU0")
	)
	(via
		(at 428.335948 -350.517968)
		(size 0.508)
		(drill 0.254)
		(layers "F.Cu" "B.Cu")
		(net "PVCCFA_EHV_FIVRA_CPU0")
	)
	(via
		(at 295.980866 -348.6658)
		(size 0.508)
		(drill 0.254)
		(layers "F.Cu" "B.Cu")
		(net "PVCCFA_EHV_FIVRA_CPU0")
	)
	(via
		(at 286.303466 -349.9358)
		(size 0.508)
		(drill 0.254)
		(layers "F.Cu" "B.Cu")
		(net "PVCCFA_EHV_FIVRA_CPU0")
	)
	(via
		(at 381.305816 -288.103056)
		(size 0.4572)
		(drill 0.2032)
		(layers "F.Cu" "B.Cu")
		(net "PVCCFA_EHV_FIVRA_CPU0")
	)
	(via
		(at 418.660834 -351.152968)
		(size 0.508)
		(drill 0.254)
		(layers "F.Cu" "B.Cu")
		(net "PVCCFA_EHV_FIVRA_CPU0")
	)
	(via
		(at 338.074762 -288.103056)
		(size 0.4572)
		(drill 0.2032)
		(layers "F.Cu" "B.Cu")
		(net "PVCCFA_EHV_FIVRA_CPU0")
	)
	(via
		(at 290.638738 -349.3008)
		(size 0.508)
		(drill 0.254)
		(layers "F.Cu" "B.Cu")
		(net "PVCCFA_EHV_FIVRA_CPU0")
	)
	(via
		(at 380.835916 -279.150318)
		(size 0.4572)
		(drill 0.2032)
		(layers "F.Cu" "B.Cu")
		(net "PVCCFA_EHV_FIVRA_CPU0")
	)
	(via
		(at 285.668466 -351.2058)
		(size 0.508)
		(drill 0.254)
		(layers "F.Cu" "B.Cu")
		(net "PVCCFA_EHV_FIVRA_CPU0")
	)
	(via
		(at 301.700438 -349.3008)
		(size 0.508)
		(drill 0.254)
		(layers "F.Cu" "B.Cu")
		(net "PVCCFA_EHV_FIVRA_CPU0")
	)
	(via
		(at 423.355262 -348.612968)
		(size 0.508)
		(drill 0.254)
		(layers "F.Cu" "B.Cu")
		(net "PVCCFA_EHV_FIVRA_CPU0")
	)
	(via
		(at 301.700438 -351.2058)
		(size 0.508)
		(drill 0.254)
		(layers "F.Cu" "B.Cu")
		(net "PVCCFA_EHV_FIVRA_CPU0")
	)
	(via
		(at 351.232216 -288.103056)
		(size 0.4572)
		(drill 0.2032)
		(layers "F.Cu" "B.Cu")
		(net "PVCCFA_EHV_FIVRA_CPU0")
	)
	(via
		(at 406.888188 -254.050292)
		(size 0.4572)
		(drill 0.2032)
		(layers "F.Cu" "B.Cu")
		(net "PVCCFA_EHV_FIVRA_CPU0")
	)
	(via
		(at 285.668466 -350.5708)
		(size 0.508)
		(drill 0.254)
		(layers "F.Cu" "B.Cu")
		(net "PVCCFA_EHV_FIVRA_CPU0")
	)
	(via
		(at 432.413918 -346.60713)
		(size 0.6604)
		(drill 0.3302)
		(layers "F.Cu" "B.Cu")
		(net "PVCCFA_EHV_FIVRA_CPU0")
	)
	(via
		(at 377.546616 -284.847538)
		(size 0.4572)
		(drill 0.2032)
		(layers "F.Cu" "B.Cu")
		(net "PVCCFA_EHV_FIVRA_CPU0")
	)
	(via
		(at 371.907816 -288.103056)
		(size 0.4572)
		(drill 0.2032)
		(layers "F.Cu" "B.Cu")
		(net "PVCCFA_EHV_FIVRA_CPU0")
	)
	(via
		(at 347.473016 -279.964134)
		(size 0.4572)
		(drill 0.2032)
		(layers "F.Cu" "B.Cu")
		(net "PVCCFA_EHV_FIVRA_CPU0")
	)
	(via
		(at 295.345866 -351.2058)
		(size 0.508)
		(drill 0.254)
		(layers "F.Cu" "B.Cu")
		(net "PVCCFA_EHV_FIVRA_CPU0")
	)
	(via
		(at 347.83268 -221.94774)
		(size 0.4572)
		(drill 0.2032)
		(layers "F.Cu" "B.Cu")
		(net "PVCCFA_EHV_FIVRA_CPU0")
	)
	(via
		(at 410.618686 -254.18669)
		(size 0.4572)
		(drill 0.2032)
		(layers "F.Cu" "B.Cu")
		(net "PVCCFA_EHV_FIVRA_CPU0")
	)
	(via
		(at 371.907816 -278.336502)
		(size 0.4572)
		(drill 0.2032)
		(layers "F.Cu" "B.Cu")
		(net "PVCCFA_EHV_FIVRA_CPU0")
	)
	(via
		(at 337.135216 -286.475424)
		(size 0.4572)
		(drill 0.2032)
		(layers "F.Cu" "B.Cu")
		(net "PVCCFA_EHV_FIVRA_CPU0")
	)
	(via
		(at 381.775462 -284.033722)
		(size 0.4572)
		(drill 0.2032)
		(layers "F.Cu" "B.Cu")
		(net "PVCCFA_EHV_FIVRA_CPU0")
	)
	(via
		(at 295.980866 -348.0308)
		(size 0.508)
		(drill 0.254)
		(layers "F.Cu" "B.Cu")
		(net "PVCCFA_EHV_FIVRA_CPU0")
	)
	(via
		(at 349.352616 -275.08073)
		(size 0.4572)
		(drill 0.2032)
		(layers "F.Cu" "B.Cu")
		(net "PVCCFA_EHV_FIVRA_CPU0")
	)
	(via
		(at 300.417738 -351.8408)
		(size 0.508)
		(drill 0.254)
		(layers "F.Cu" "B.Cu")
		(net "PVCCFA_EHV_FIVRA_CPU0")
	)
	(via
		(at 418.013134 -349.882968)
		(size 0.508)
		(drill 0.254)
		(layers "F.Cu" "B.Cu")
		(net "PVCCFA_EHV_FIVRA_CPU0")
	)
	(via
		(at 376.02668 -215.436704)
		(size 0.4572)
		(drill 0.2032)
		(layers "F.Cu" "B.Cu")
		(net "PVCCFA_EHV_FIVRA_CPU0")
	)
	(via
		(at 379.78588 -221.94774)
		(size 0.4572)
		(drill 0.2032)
		(layers "F.Cu" "B.Cu")
		(net "PVCCFA_EHV_FIVRA_CPU0")
	)
	(via
		(at 308.351682 -254.110998)
		(size 0.4572)
		(drill 0.2032)
		(layers "F.Cu" "B.Cu")
		(net "PVCCFA_EHV_FIVRA_CPU0")
	)
	(via
		(at 295.345866 -348.0308)
		(size 0.508)
		(drill 0.254)
		(layers "F.Cu" "B.Cu")
		(net "PVCCFA_EHV_FIVRA_CPU0")
	)
	(via
		(at 428.983648 -349.247968)
		(size 0.508)
		(drill 0.254)
		(layers "F.Cu" "B.Cu")
		(net "PVCCFA_EHV_FIVRA_CPU0")
	)
	(via
		(at 336.55508 -221.94774)
		(size 0.4572)
		(drill 0.2032)
		(layers "F.Cu" "B.Cu")
		(net "PVCCFA_EHV_FIVRA_CPU0")
	)
	(via
		(at 377.90628 -221.94774)
		(size 0.4572)
		(drill 0.2032)
		(layers "F.Cu" "B.Cu")
		(net "PVCCFA_EHV_FIVRA_CPU0")
	)
	(via
		(at 418.660834 -348.612968)
		(size 0.508)
		(drill 0.254)
		(layers "F.Cu" "B.Cu")
		(net "PVCCFA_EHV_FIVRA_CPU0")
	)
	(via
		(at 286.303466 -348.0308)
		(size 0.508)
		(drill 0.254)
		(layers "F.Cu" "B.Cu")
		(net "PVCCFA_EHV_FIVRA_CPU0")
	)
	(via
		(at 418.660834 -347.977968)
		(size 0.508)
		(drill 0.254)
		(layers "F.Cu" "B.Cu")
		(net "PVCCFA_EHV_FIVRA_CPU0")
	)
	(via
		(at 366.222534 -261.328916)
		(size 0.4572)
		(drill 0.2032)
		(layers "F.Cu" "B.Cu")
		(net "PVCCFA_EHV_FIVRA_CPU0")
	)
	(via
		(at 354.991416 -279.964134)
		(size 0.4572)
		(drill 0.2032)
		(layers "F.Cu" "B.Cu")
		(net "PVCCFA_EHV_FIVRA_CPU0")
	)
	(via
		(at 291.286438 -351.2058)
		(size 0.508)
		(drill 0.254)
		(layers "F.Cu" "B.Cu")
		(net "PVCCFA_EHV_FIVRA_CPU0")
	)
	(via
		(at 296.628566 -349.9358)
		(size 0.508)
		(drill 0.254)
		(layers "F.Cu" "B.Cu")
		(net "PVCCFA_EHV_FIVRA_CPU0")
	)
	(via
		(at 413.042862 -349.882968)
		(size 0.508)
		(drill 0.254)
		(layers "F.Cu" "B.Cu")
		(net "PVCCFA_EHV_FIVRA_CPU0")
	)
	(via
		(at 419.295834 -348.612968)
		(size 0.508)
		(drill 0.254)
		(layers "F.Cu" "B.Cu")
		(net "PVCCFA_EHV_FIVRA_CPU0")
	)
	(via
		(at 381.305816 -284.847538)
		(size 0.4572)
		(drill 0.2032)
		(layers "F.Cu" "B.Cu")
		(net "PVCCFA_EHV_FIVRA_CPU0")
	)
	(via
		(at 351.46742 -239.309402)
		(size 0.4572)
		(drill 0.2032)
		(layers "F.Cu" "B.Cu")
		(net "PVCCFA_EHV_FIVRA_CPU0")
	)
	(via
		(at 418.660834 -349.882968)
		(size 0.508)
		(drill 0.254)
		(layers "F.Cu" "B.Cu")
		(net "PVCCFA_EHV_FIVRA_CPU0")
	)
	(via
		(at 285.668466 -349.9358)
		(size 0.508)
		(drill 0.254)
		(layers "F.Cu" "B.Cu")
		(net "PVCCFA_EHV_FIVRA_CPU0")
	)
	(via
		(at 347.473016 -288.103056)
		(size 0.4572)
		(drill 0.2032)
		(layers "F.Cu" "B.Cu")
		(net "PVCCFA_EHV_FIVRA_CPU0")
	)
	(via
		(at 423.355262 -350.517968)
		(size 0.508)
		(drill 0.254)
		(layers "F.Cu" "B.Cu")
		(net "PVCCFA_EHV_FIVRA_CPU0")
	)
	(via
		(at 377.546616 -279.964134)
		(size 0.4572)
		(drill 0.2032)
		(layers "F.Cu" "B.Cu")
		(net "PVCCFA_EHV_FIVRA_CPU0")
	)
	(via
		(at 300.417738 -350.5708)
		(size 0.508)
		(drill 0.254)
		(layers "F.Cu" "B.Cu")
		(net "PVCCFA_EHV_FIVRA_CPU0")
	)
	(via
		(at 301.700438 -351.8408)
		(size 0.508)
		(drill 0.254)
		(layers "F.Cu" "B.Cu")
		(net "PVCCFA_EHV_FIVRA_CPU0")
	)
	(arc
		(start 349.352362 -274.54479)
		(mid 349.352425 -274.81276)
		(end 349.352616 -275.08073)
		(width 0.254)
		(layer "F.Cu")
		(net "PVCCFA_EHV_FIVRA_CPU0")
	)
	(segment
		(start 295.699688 -367.564416)
		(end 295.684448 -367.549176)
		(width 0.254)
		(layer "B.Cu")
		(net "PVCCFA_EHV_FIVRA_CPU0")
	)
	(segment
		(start 423.079164 -366.866424)
		(end 422.90492 -366.69218)
		(width 0.254)
		(layer "B.Cu")
		(net "PVCCFA_EHV_FIVRA_CPU0")
	)
	(segment
		(start 421.292528 -346.017342)
		(end 421.292528 -346.95765)
		(width 0.508)
		(layer "B.Cu")
		(net "PVCCFA_EHV_FIVRA_CPU0")
	)
	(segment
		(start 412.206694 -365.98225)
		(end 412.712662 -365.98225)
		(width 0.381)
		(layer "B.Cu")
		(net "PVCCFA_EHV_FIVRA_CPU0")
	)
	(segment
		(start 286.359092 -346.700348)
		(end 287.2994 -346.700348)
		(width 0.508)
		(layer "B.Cu")
		(net "PVCCFA_EHV_FIVRA_CPU0")
	)
	(segment
		(start 299.6946 -346.700348)
		(end 300.634908 -346.700348)
		(width 0.508)
		(layer "B.Cu")
		(net "PVCCFA_EHV_FIVRA_CPU0")
	)
	(segment
		(start 414.161478 -346.010992)
		(end 415.101786 -346.010992)
		(width 0.508)
		(layer "B.Cu")
		(net "PVCCFA_EHV_FIVRA_CPU0")
	)
	(segment
		(start 427.490128 -346.017342)
		(end 428.430436 -346.017342)
		(width 0.508)
		(layer "B.Cu")
		(net "PVCCFA_EHV_FIVRA_CPU0")
	)
	(segment
		(start 293.497 -346.700348)
		(end 294.437308 -346.700348)
		(width 0.508)
		(layer "B.Cu")
		(net "PVCCFA_EHV_FIVRA_CPU0")
	)
	(segment
		(start 295.684448 -367.549176)
		(end 295.618408 -367.549176)
		(width 0.254)
		(layer "B.Cu")
		(net "PVCCFA_EHV_FIVRA_CPU0")
	)
	(segment
		(start 420.35222 -346.017342)
		(end 421.292528 -346.017342)
		(width 0.508)
		(layer "B.Cu")
		(net "PVCCFA_EHV_FIVRA_CPU0")
	)
	(segment
		(start 426.54982 -346.017342)
		(end 427.490128 -346.017342)
		(width 0.508)
		(layer "B.Cu")
		(net "PVCCFA_EHV_FIVRA_CPU0")
	)
	(segment
		(start 285.338266 -366.46612)
		(end 285.338266 -366.670082)
		(width 0.381)
		(layer "B.Cu")
		(net "PVCCFA_EHV_FIVRA_CPU0")
	)
	(segment
		(start 422.90492 -366.69218)
		(end 422.84396 -366.69218)
		(width 0.254)
		(layer "B.Cu")
		(net "PVCCFA_EHV_FIVRA_CPU0")
	)
	(segment
		(start 415.101786 -346.010992)
		(end 416.042094 -346.010992)
		(width 0.508)
		(layer "B.Cu")
		(net "PVCCFA_EHV_FIVRA_CPU0")
	)
	(segment
		(start 295.026588 -366.957356)
		(end 295.026588 -366.68202)
		(width 0.254)
		(layer "B.Cu")
		(net "PVCCFA_EHV_FIVRA_CPU0")
	)
	(segment
		(start 298.754292 -346.700348)
		(end 299.6946 -346.700348)
		(width 0.508)
		(layer "B.Cu")
		(net "PVCCFA_EHV_FIVRA_CPU0")
	)
	(segment
		(start 284.925262 -366.053116)
		(end 285.338266 -366.46612)
		(width 0.381)
		(layer "B.Cu")
		(net "PVCCFA_EHV_FIVRA_CPU0")
	)
	(segment
		(start 415.101786 -346.010992)
		(end 415.101786 -346.9513)
		(width 0.508)
		(layer "B.Cu")
		(net "PVCCFA_EHV_FIVRA_CPU0")
	)
	(segment
		(start 299.6946 -346.700348)
		(end 299.6946 -347.640656)
		(width 0.508)
		(layer "B.Cu")
		(net "PVCCFA_EHV_FIVRA_CPU0")
	)
	(segment
		(start 422.84396 -366.69218)
		(end 422.400984 -366.249204)
		(width 0.254)
		(layer "B.Cu")
		(net "PVCCFA_EHV_FIVRA_CPU0")
	)
	(segment
		(start 421.292528 -346.017342)
		(end 422.232836 -346.017342)
		(width 0.508)
		(layer "B.Cu")
		(net "PVCCFA_EHV_FIVRA_CPU0")
	)
	(segment
		(start 422.400984 -366.249204)
		(end 422.400984 -365.994188)
		(width 0.254)
		(layer "B.Cu")
		(net "PVCCFA_EHV_FIVRA_CPU0")
	)
	(segment
		(start 427.490128 -346.017342)
		(end 427.490128 -346.95765)
		(width 0.508)
		(layer "B.Cu")
		(net "PVCCFA_EHV_FIVRA_CPU0")
	)
	(segment
		(start 412.007558 -365.783114)
		(end 412.206694 -365.98225)
		(width 0.381)
		(layer "B.Cu")
		(net "PVCCFA_EHV_FIVRA_CPU0")
	)
	(segment
		(start 287.2994 -346.700348)
		(end 288.239708 -346.700348)
		(width 0.508)
		(layer "B.Cu")
		(net "PVCCFA_EHV_FIVRA_CPU0")
	)
	(segment
		(start 295.618408 -367.549176)
		(end 295.026588 -366.957356)
		(width 0.254)
		(layer "B.Cu")
		(net "PVCCFA_EHV_FIVRA_CPU0")
	)
	(segment
		(start 293.497 -346.700348)
		(end 293.497 -347.640656)
		(width 0.508)
		(layer "B.Cu")
		(net "PVCCFA_EHV_FIVRA_CPU0")
	)
	(segment
		(start 292.556692 -346.700348)
		(end 293.497 -346.700348)
		(width 0.508)
		(layer "B.Cu")
		(net "PVCCFA_EHV_FIVRA_CPU0")
	)
	(segment
		(start 287.2994 -346.700348)
		(end 287.2994 -347.640656)
		(width 0.508)
		(layer "B.Cu")
		(net "PVCCFA_EHV_FIVRA_CPU0")
	)
	(segment
		(start 336.851498 -286.475424)
		(end 337.135216 -286.475424)
		(width 0.254)
		(layer "In2.Cu")
		(net "PVCCFA_EHV_FIVRA_CPU0")
	)
	(segment
		(start 336.457036 -286.080962)
		(end 336.851498 -286.475424)
		(width 0.254)
		(layer "In2.Cu")
		(net "PVCCFA_EHV_FIVRA_CPU0")
	)
	(segment
		(start 295.024048 -356.259384)
		(end 295.024048 -352.162618)
		(width 0.381)
		(layer "In2.Cu")
		(net "PVCCFA_EHV_FIVRA_CPU0")
	)
	(segment
		(start 286.080708 -358.80929)
		(end 285.668466 -358.397048)
		(width 0.381)
		(layer "In2.Cu")
		(net "PVCCFA_EHV_FIVRA_CPU0")
	)
	(segment
		(start 370.028216 -284.847538)
		(end 370.028216 -284.037786)
		(width 0.254)
		(layer "In2.Cu")
		(net "PVCCFA_EHV_FIVRA_CPU0")
	)
	(segment
		(start 296.111168 -362.430568)
		(end 295.798748 -362.118148)
		(width 0.381)
		(layer "In2.Cu")
		(net "PVCCFA_EHV_FIVRA_CPU0")
	)
	(segment
		(start 295.798748 -362.118148)
		(end 295.798748 -357.034084)
		(width 0.381)
		(layer "In2.Cu")
		(net "PVCCFA_EHV_FIVRA_CPU0")
	)
	(segment
		(start 294.653208 -365.551974)
		(end 296.111168 -364.094014)
		(width 0.381)
		(layer "In2.Cu")
		(net "PVCCFA_EHV_FIVRA_CPU0")
	)
	(segment
		(start 296.111168 -364.094014)
		(end 296.111168 -362.430568)
		(width 0.381)
		(layer "In2.Cu")
		(net "PVCCFA_EHV_FIVRA_CPU0")
	)
	(segment
		(start 284.988508 -366.320324)
		(end 284.988508 -365.669068)
		(width 0.381)
		(layer "In2.Cu")
		(net "PVCCFA_EHV_FIVRA_CPU0")
	)
	(segment
		(start 339.954362 -284.847538)
		(end 339.954362 -284.037786)
		(width 0.254)
		(layer "In2.Cu")
		(net "PVCCFA_EHV_FIVRA_CPU0")
	)
	(segment
		(start 375.667016 -284.847538)
		(end 375.667016 -284.037786)
		(width 0.254)
		(layer "In2.Cu")
		(net "PVCCFA_EHV_FIVRA_CPU0")
	)
	(segment
		(start 368.148616 -284.847538)
		(end 368.148616 -284.037786)
		(width 0.254)
		(layer "In2.Cu")
		(net "PVCCFA_EHV_FIVRA_CPU0")
	)
	(segment
		(start 285.668466 -358.397048)
		(end 285.668466 -351.8408)
		(width 0.381)
		(layer "In2.Cu")
		(net "PVCCFA_EHV_FIVRA_CPU0")
	)
	(segment
		(start 286.080708 -362.301028)
		(end 286.080708 -358.80929)
		(width 0.381)
		(layer "In2.Cu")
		(net "PVCCFA_EHV_FIVRA_CPU0")
	)
	(segment
		(start 379.426216 -284.847538)
		(end 379.426216 -284.037786)
		(width 0.254)
		(layer "In2.Cu")
		(net "PVCCFA_EHV_FIVRA_CPU0")
	)
	(segment
		(start 343.713816 -284.847538)
		(end 343.713816 -284.037786)
		(width 0.254)
		(layer "In2.Cu")
		(net "PVCCFA_EHV_FIVRA_CPU0")
	)
	(segment
		(start 294.653208 -366.30864)
		(end 294.653208 -365.551974)
		(width 0.381)
		(layer "In2.Cu")
		(net "PVCCFA_EHV_FIVRA_CPU0")
	)
	(segment
		(start 286.377888 -362.598208)
		(end 286.080708 -362.301028)
		(width 0.381)
		(layer "In2.Cu")
		(net "PVCCFA_EHV_FIVRA_CPU0")
	)
	(segment
		(start 381.305816 -284.847538)
		(end 381.305816 -284.037786)
		(width 0.254)
		(layer "In2.Cu")
		(net "PVCCFA_EHV_FIVRA_CPU0")
	)
	(segment
		(start 295.026588 -366.68202)
		(end 294.653208 -366.30864)
		(width 0.381)
		(layer "In2.Cu")
		(net "PVCCFA_EHV_FIVRA_CPU0")
	)
	(segment
		(start 371.907816 -284.847538)
		(end 371.907816 -284.037786)
		(width 0.254)
		(layer "In2.Cu")
		(net "PVCCFA_EHV_FIVRA_CPU0")
	)
	(segment
		(start 377.546616 -284.847538)
		(end 377.546616 -284.037786)
		(width 0.254)
		(layer "In2.Cu")
		(net "PVCCFA_EHV_FIVRA_CPU0")
	)
	(segment
		(start 284.988508 -365.669068)
		(end 286.377888 -364.279688)
		(width 0.381)
		(layer "In2.Cu")
		(net "PVCCFA_EHV_FIVRA_CPU0")
	)
	(segment
		(start 341.834216 -284.847538)
		(end 341.834216 -284.037786)
		(width 0.254)
		(layer "In2.Cu")
		(net "PVCCFA_EHV_FIVRA_CPU0")
	)
	(segment
		(start 345.593416 -284.847538)
		(end 345.593416 -284.037786)
		(width 0.254)
		(layer "In2.Cu")
		(net "PVCCFA_EHV_FIVRA_CPU0")
	)
	(segment
		(start 295.024048 -352.162618)
		(end 295.345866 -351.8408)
		(width 0.381)
		(layer "In2.Cu")
		(net "PVCCFA_EHV_FIVRA_CPU0")
	)
	(segment
		(start 347.473016 -284.847538)
		(end 347.473016 -284.037786)
		(width 0.254)
		(layer "In2.Cu")
		(net "PVCCFA_EHV_FIVRA_CPU0")
	)
	(segment
		(start 285.338266 -366.670082)
		(end 284.988508 -366.320324)
		(width 0.381)
		(layer "In2.Cu")
		(net "PVCCFA_EHV_FIVRA_CPU0")
	)
	(segment
		(start 295.798748 -357.034084)
		(end 295.024048 -356.259384)
		(width 0.381)
		(layer "In2.Cu")
		(net "PVCCFA_EHV_FIVRA_CPU0")
	)
	(segment
		(start 286.377888 -364.279688)
		(end 286.377888 -362.598208)
		(width 0.381)
		(layer "In2.Cu")
		(net "PVCCFA_EHV_FIVRA_CPU0")
	)
	(segment
		(start 338.074762 -284.847538)
		(end 337.710272 -284.483048)
		(width 0.254)
		(layer "In2.Cu")
		(net "PVCCFA_EHV_FIVRA_CPU0")
	)
	(segment
		(start 371.907816 -288.103056)
		(end 371.907816 -287.22955)
		(width 0.254)
		(layer "In4.Cu")
		(net "PVCCFA_EHV_FIVRA_CPU0")
	)
	(segment
		(start 373.787416 -288.103056)
		(end 373.787416 -287.22955)
		(width 0.254)
		(layer "In4.Cu")
		(net "PVCCFA_EHV_FIVRA_CPU0")
	)
	(segment
		(start 345.593416 -288.103056)
		(end 345.593416 -287.22955)
		(width 0.254)
		(layer "In4.Cu")
		(net "PVCCFA_EHV_FIVRA_CPU0")
	)
	(segment
		(start 347.473016 -288.103056)
		(end 347.473016 -287.22955)
		(width 0.254)
		(layer "In4.Cu")
		(net "PVCCFA_EHV_FIVRA_CPU0")
	)
	(segment
		(start 341.834216 -288.103056)
		(end 341.834216 -287.22955)
		(width 0.254)
		(layer "In4.Cu")
		(net "PVCCFA_EHV_FIVRA_CPU0")
	)
	(segment
		(start 351.232216 -288.103056)
		(end 351.232216 -287.22955)
		(width 0.254)
		(layer "In4.Cu")
		(net "PVCCFA_EHV_FIVRA_CPU0")
	)
	(segment
		(start 375.667016 -288.103056)
		(end 375.667016 -287.22955)
		(width 0.254)
		(layer "In4.Cu")
		(net "PVCCFA_EHV_FIVRA_CPU0")
	)
	(segment
		(start 349.352616 -288.103056)
		(end 349.352616 -287.22955)
		(width 0.254)
		(layer "In4.Cu")
		(net "PVCCFA_EHV_FIVRA_CPU0")
	)
	(segment
		(start 381.305816 -288.103056)
		(end 381.305816 -287.22955)
		(width 0.254)
		(layer "In4.Cu")
		(net "PVCCFA_EHV_FIVRA_CPU0")
	)
	(segment
		(start 377.546616 -288.103056)
		(end 377.546616 -287.22955)
		(width 0.254)
		(layer "In4.Cu")
		(net "PVCCFA_EHV_FIVRA_CPU0")
	)
	(segment
		(start 339.954616 -288.103056)
		(end 339.954616 -287.22955)
		(width 0.254)
		(layer "In4.Cu")
		(net "PVCCFA_EHV_FIVRA_CPU0")
	)
	(segment
		(start 338.074762 -288.103056)
		(end 338.074762 -287.22955)
		(width 0.254)
		(layer "In4.Cu")
		(net "PVCCFA_EHV_FIVRA_CPU0")
	)
	(segment
		(start 379.426216 -288.103056)
		(end 379.426216 -287.22955)
		(width 0.254)
		(layer "In4.Cu")
		(net "PVCCFA_EHV_FIVRA_CPU0")
	)
	(segment
		(start 370.028216 -288.103056)
		(end 370.028216 -287.22955)
		(width 0.254)
		(layer "In4.Cu")
		(net "PVCCFA_EHV_FIVRA_CPU0")
	)
	(segment
		(start 343.713816 -288.103056)
		(end 343.713816 -287.22955)
		(width 0.254)
		(layer "In4.Cu")
		(net "PVCCFA_EHV_FIVRA_CPU0")
	)
	(segment
		(start 411.550358 -352.645472)
		(end 413.042862 -351.152968)
		(width 0.381)
		(layer "In15.Cu")
		(net "PVCCFA_EHV_FIVRA_CPU0")
	)
	(segment
		(start 412.712662 -365.98225)
		(end 412.526226 -365.98225)
		(width 0.381)
		(layer "In15.Cu")
		(net "PVCCFA_EHV_FIVRA_CPU0")
	)
	(segment
		(start 423.181018 -363.714284)
		(end 423.181018 -355.690932)
		(width 0.381)
		(layer "In15.Cu")
		(net "PVCCFA_EHV_FIVRA_CPU0")
	)
	(segment
		(start 412.526226 -365.98225)
		(end 411.550358 -365.006382)
		(width 0.381)
		(layer "In15.Cu")
		(net "PVCCFA_EHV_FIVRA_CPU0")
	)
	(segment
		(start 423.181018 -355.690932)
		(end 422.72331 -355.233224)
		(width 0.381)
		(layer "In15.Cu")
		(net "PVCCFA_EHV_FIVRA_CPU0")
	)
	(segment
		(start 422.400984 -364.494318)
		(end 423.181018 -363.714284)
		(width 0.381)
		(layer "In15.Cu")
		(net "PVCCFA_EHV_FIVRA_CPU0")
	)
	(segment
		(start 422.72331 -351.156016)
		(end 422.720262 -351.152968)
		(width 0.381)
		(layer "In15.Cu")
		(net "PVCCFA_EHV_FIVRA_CPU0")
	)
	(segment
		(start 422.72331 -355.233224)
		(end 422.72331 -351.156016)
		(width 0.381)
		(layer "In15.Cu")
		(net "PVCCFA_EHV_FIVRA_CPU0")
	)
	(segment
		(start 411.550358 -365.006382)
		(end 411.550358 -352.645472)
		(width 0.381)
		(layer "In15.Cu")
		(net "PVCCFA_EHV_FIVRA_CPU0")
	)
	(segment
		(start 422.400984 -365.994188)
		(end 422.400984 -364.494318)
		(width 0.381)
		(layer "In15.Cu")
		(net "PVCCFA_EHV_FIVRA_CPU0")
	)
	(segment
		(start 50.58283 -170.176698)
		(end 50.605944 -170.199812)
		(width 0.254)
		(layer "F.Cu")
		(net "PVCCFA_EHV_CPU1_VDD1")
	)
	(segment
		(start 51.132994 -170.199812)
		(end 51.10988 -170.176698)
		(width 0.254)
		(layer "F.Cu")
		(net "PVCCFA_EHV_CPU1_VDD1")
	)
	(segment
		(start 52.094384 -170.976798)
		(end 51.317398 -170.199812)
		(width 0.254)
		(layer "F.Cu")
		(net "PVCCFA_EHV_CPU1_VDD1")
	)
	(segment
		(start 50.605944 -170.199812)
		(end 51.086766 -170.199812)
		(width 0.254)
		(layer "F.Cu")
		(net "PVCCFA_EHV_CPU1_VDD1")
	)
	(segment
		(start 52.15128 -170.976798)
		(end 52.15128 -171.189142)
		(width 0.254)
		(layer "F.Cu")
		(net "PVCCFA_EHV_CPU1_VDD1")
	)
	(segment
		(start 52.15128 -170.976798)
		(end 52.094384 -170.976798)
		(width 0.254)
		(layer "F.Cu")
		(net "PVCCFA_EHV_CPU1_VDD1")
	)
	(segment
		(start 51.086766 -170.199812)
		(end 51.10988 -170.176698)
		(width 0.254)
		(layer "F.Cu")
		(net "PVCCFA_EHV_CPU1_VDD1")
	)
	(segment
		(start 51.317398 -170.199812)
		(end 51.132994 -170.199812)
		(width 0.254)
		(layer "F.Cu")
		(net "PVCCFA_EHV_CPU1_VDD1")
	)
	(segment
		(start 52.15128 -171.189142)
		(end 52.830984 -171.868846)
		(width 0.254)
		(layer "F.Cu")
		(net "PVCCFA_EHV_CPU1_VDD1")
	)
	(segment
		(start 52.830984 -171.868846)
		(end 52.830984 -172.305726)
		(width 0.254)
		(layer "F.Cu")
		(net "PVCCFA_EHV_CPU1_VDD1")
	)
	(segment
		(start 50.41773 -170.049698)
		(end 50.54473 -170.176698)
		(width 0.254)
		(layer "F.Cu")
		(net "PVCCFA_EHV_CPU1_VDD1")
	)
	(segment
		(start 50.54473 -170.176698)
		(end 50.58283 -170.176698)
		(width 0.254)
		(layer "F.Cu")
		(net "PVCCFA_EHV_CPU1_VDD1")
	)
	(via
		(at 50.41773 -170.049698)
		(size 0.508)
		(drill 0.254)
		(layers "F.Cu" "B.Cu")
		(net "PVCCFA_EHV_CPU1_VDD1")
	)
	(via
		(at 49.04994 -170.757088)
		(size 0.6604)
		(drill 0.3302)
		(layers "F.Cu" "B.Cu")
		(net "PVCCFA_EHV_CPU1_VDD1")
	)
	(segment
		(start 48.18634 -170.757088)
		(end 49.04994 -170.757088)
		(width 0.381)
		(layer "B.Cu")
		(net "PVCCFA_EHV_CPU1_VDD1")
	)
	(segment
		(start 48.75403 -172.989748)
		(end 48.36668 -172.989748)
		(width 0.381)
		(layer "B.Cu")
		(net "PVCCFA_EHV_CPU1_VDD1")
	)
	(segment
		(start 49.22901 -170.757088)
		(end 49.9364 -170.049698)
		(width 0.381)
		(layer "B.Cu")
		(net "PVCCFA_EHV_CPU1_VDD1")
	)
	(segment
		(start 49.9364 -170.049698)
		(end 50.41773 -170.049698)
		(width 0.381)
		(layer "B.Cu")
		(net "PVCCFA_EHV_CPU1_VDD1")
	)
	(segment
		(start 50.8508 -170.095418)
		(end 51.14544 -170.095418)
		(width 0.381)
		(layer "B.Cu")
		(net "PVCCFA_EHV_CPU1_VDD1")
	)
	(segment
		(start 50.80508 -170.049698)
		(end 50.8508 -170.095418)
		(width 0.381)
		(layer "B.Cu")
		(net "PVCCFA_EHV_CPU1_VDD1")
	)
	(segment
		(start 49.04994 -170.757088)
		(end 49.22901 -170.757088)
		(width 0.381)
		(layer "B.Cu")
		(net "PVCCFA_EHV_CPU1_VDD1")
	)
	(segment
		(start 48.36668 -172.989748)
		(end 47.752 -172.375068)
		(width 0.381)
		(layer "B.Cu")
		(net "PVCCFA_EHV_CPU1_VDD1")
	)
	(segment
		(start 47.752 -172.375068)
		(end 47.752 -171.191428)
		(width 0.381)
		(layer "B.Cu")
		(net "PVCCFA_EHV_CPU1_VDD1")
	)
	(segment
		(start 47.752 -171.191428)
		(end 48.18634 -170.757088)
		(width 0.381)
		(layer "B.Cu")
		(net "PVCCFA_EHV_CPU1_VDD1")
	)
	(segment
		(start 50.41773 -170.049698)
		(end 50.80508 -170.049698)
		(width 0.381)
		(layer "B.Cu")
		(net "PVCCFA_EHV_CPU1_VDD1")
	)
	(segment
		(start 53.974492 -162.346386)
		(end 54.690264 -161.630614)
		(width 0.2286)
		(layer "F.Cu")
		(net "PVCCFA_EHV_CPU1_PVCC")
	)
	(segment
		(start 54.690264 -161.630614)
		(end 54.690264 -161.539174)
		(width 0.2286)
		(layer "F.Cu")
		(net "PVCCFA_EHV_CPU1_PVCC")
	)
	(segment
		(start 54.690264 -144.358614)
		(end 53.974492 -145.074386)
		(width 0.2286)
		(layer "F.Cu")
		(net "PVCCFA_EHV_CPU1_PVCC")
	)
	(segment
		(start 53.974492 -153.703782)
		(end 54.690264 -152.98801)
		(width 0.2286)
		(layer "F.Cu")
		(net "PVCCFA_EHV_CPU1_PVCC")
	)
	(segment
		(start 53.974492 -154.077924)
		(end 53.974492 -153.703782)
		(width 0.2286)
		(layer "F.Cu")
		(net "PVCCFA_EHV_CPU1_PVCC")
	)
	(segment
		(start 54.690264 -144.267174)
		(end 54.690264 -144.358614)
		(width 0.2286)
		(layer "F.Cu")
		(net "PVCCFA_EHV_CPU1_PVCC")
	)
	(segment
		(start 54.41696 -144.267174)
		(end 54.690264 -144.267174)
		(width 0.254)
		(layer "F.Cu")
		(net "PVCCFA_EHV_CPU1_PVCC")
	)
	(segment
		(start 54.074314 -152.903174)
		(end 54.690264 -152.903174)
		(width 0.254)
		(layer "F.Cu")
		(net "PVCCFA_EHV_CPU1_PVCC")
	)
	(segment
		(start 54.074314 -143.924528)
		(end 54.41696 -144.267174)
		(width 0.254)
		(layer "F.Cu")
		(net "PVCCFA_EHV_CPU1_PVCC")
	)
	(segment
		(start 54.690264 -152.98801)
		(end 54.690264 -152.903174)
		(width 0.2286)
		(layer "F.Cu")
		(net "PVCCFA_EHV_CPU1_PVCC")
	)
	(segment
		(start 54.074314 -161.539174)
		(end 54.690264 -161.539174)
		(width 0.254)
		(layer "F.Cu")
		(net "PVCCFA_EHV_CPU1_PVCC")
	)
	(segment
		(start 53.974492 -162.713924)
		(end 53.974492 -162.346386)
		(width 0.2286)
		(layer "F.Cu")
		(net "PVCCFA_EHV_CPU1_PVCC")
	)
	(segment
		(start 53.974492 -145.074386)
		(end 53.974492 -145.441924)
		(width 0.2286)
		(layer "F.Cu")
		(net "PVCCFA_EHV_CPU1_PVCC")
	)
	(via
		(at 54.074314 -152.903174)
		(size 0.508)
		(drill 0.254)
		(layers "F.Cu" "B.Cu")
		(net "PVCCFA_EHV_CPU1_PVCC")
	)
	(via
		(at 54.074314 -143.924528)
		(size 0.508)
		(drill 0.254)
		(layers "F.Cu" "B.Cu")
		(net "PVCCFA_EHV_CPU1_PVCC")
	)
	(via
		(at 50.39868 -170.856148)
		(size 0.508)
		(drill 0.254)
		(layers "F.Cu" "B.Cu")
		(net "PVCCFA_EHV_CPU1_PVCC")
	)
	(via
		(at 54.074314 -161.539174)
		(size 0.508)
		(drill 0.254)
		(layers "F.Cu" "B.Cu")
		(net "PVCCFA_EHV_CPU1_PVCC")
	)
	(segment
		(start 54.312566 -144.505426)
		(end 54.312566 -145.445226)
		(width 0.254)
		(layer "B.Cu")
		(net "PVCCFA_EHV_CPU1_PVCC")
	)
	(segment
		(start 53.14188 -171.941998)
		(end 52.15128 -171.941998)
		(width 0.381)
		(layer "B.Cu")
		(net "PVCCFA_EHV_CPU1_PVCC")
	)
	(segment
		(start 51.061366 -170.979592)
		(end 51.14544 -170.895518)
		(width 0.381)
		(layer "B.Cu")
		(net "PVCCFA_EHV_CPU1_PVCC")
	)
	(segment
		(start 50.39868 -170.856148)
		(end 50.522124 -170.979592)
		(width 0.381)
		(layer "B.Cu")
		(net "PVCCFA_EHV_CPU1_PVCC")
	)
	(segment
		(start 50.522124 -170.979592)
		(end 51.061366 -170.979592)
		(width 0.381)
		(layer "B.Cu")
		(net "PVCCFA_EHV_CPU1_PVCC")
	)
	(segment
		(start 54.074314 -161.539174)
		(end 54.312566 -161.777426)
		(width 0.254)
		(layer "B.Cu")
		(net "PVCCFA_EHV_CPU1_PVCC")
	)
	(segment
		(start 54.312566 -153.141426)
		(end 54.312566 -154.081226)
		(width 0.254)
		(layer "B.Cu")
		(net "PVCCFA_EHV_CPU1_PVCC")
	)
	(segment
		(start 52.128166 -171.918884)
		(end 51.883056 -171.918884)
		(width 0.381)
		(layer "B.Cu")
		(net "PVCCFA_EHV_CPU1_PVCC")
	)
	(segment
		(start 52.15128 -171.941998)
		(end 52.128166 -171.918884)
		(width 0.381)
		(layer "B.Cu")
		(net "PVCCFA_EHV_CPU1_PVCC")
	)
	(segment
		(start 54.074314 -143.924528)
		(end 54.074314 -144.267174)
		(width 0.254)
		(layer "B.Cu")
		(net "PVCCFA_EHV_CPU1_PVCC")
	)
	(segment
		(start 51.883056 -171.918884)
		(end 51.14544 -171.181268)
		(width 0.381)
		(layer "B.Cu")
		(net "PVCCFA_EHV_CPU1_PVCC")
	)
	(segment
		(start 54.074314 -144.267174)
		(end 54.312566 -144.505426)
		(width 0.254)
		(layer "B.Cu")
		(net "PVCCFA_EHV_CPU1_PVCC")
	)
	(segment
		(start 54.312566 -161.777426)
		(end 54.312566 -162.717226)
		(width 0.254)
		(layer "B.Cu")
		(net "PVCCFA_EHV_CPU1_PVCC")
	)
	(segment
		(start 51.14544 -171.181268)
		(end 51.14544 -170.895518)
		(width 0.381)
		(layer "B.Cu")
		(net "PVCCFA_EHV_CPU1_PVCC")
	)
	(segment
		(start 54.074314 -152.903174)
		(end 54.312566 -153.141426)
		(width 0.254)
		(layer "B.Cu")
		(net "PVCCFA_EHV_CPU1_PVCC")
	)
	(segment
		(start 53.5686 -147.716748)
		(end 54.074314 -148.222462)
		(width 0.4572)
		(layer "In6.Cu")
		(net "PVCCFA_EHV_CPU1_PVCC")
	)
	(segment
		(start 49.7332 -170.703748)
		(end 49.9364 -170.906948)
		(width 0.381)
		(layer "In6.Cu")
		(net "PVCCFA_EHV_CPU1_PVCC")
	)
	(segment
		(start 49.9364 -170.906948)
		(end 50.34788 -170.906948)
		(width 0.381)
		(layer "In6.Cu")
		(net "PVCCFA_EHV_CPU1_PVCC")
	)
	(segment
		(start 54.074314 -152.903174)
		(end 54.074314 -153.840434)
		(width 0.4572)
		(layer "In6.Cu")
		(net "PVCCFA_EHV_CPU1_PVCC")
	)
	(segment
		(start 54.074314 -161.539174)
		(end 54.0512 -161.562288)
		(width 0.381)
		(layer "In6.Cu")
		(net "PVCCFA_EHV_CPU1_PVCC")
	)
	(segment
		(start 54.0512 -162.347148)
		(end 53.7718 -162.626548)
		(width 0.381)
		(layer "In6.Cu")
		(net "PVCCFA_EHV_CPU1_PVCC")
	)
	(segment
		(start 54.074314 -143.924528)
		(end 54.074314 -144.823434)
		(width 0.4572)
		(layer "In6.Cu")
		(net "PVCCFA_EHV_CPU1_PVCC")
	)
	(segment
		(start 50.3682 -168.722548)
		(end 49.7332 -169.357548)
		(width 0.381)
		(layer "In6.Cu")
		(net "PVCCFA_EHV_CPU1_PVCC")
	)
	(segment
		(start 53.6448 -156.581348)
		(end 54.074314 -157.010862)
		(width 0.4572)
		(layer "In6.Cu")
		(net "PVCCFA_EHV_CPU1_PVCC")
	)
	(segment
		(start 54.074314 -144.823434)
		(end 53.5686 -145.329148)
		(width 0.4572)
		(layer "In6.Cu")
		(net "PVCCFA_EHV_CPU1_PVCC")
	)
	(segment
		(start 54.074314 -148.222462)
		(end 54.074314 -152.903174)
		(width 0.4572)
		(layer "In6.Cu")
		(net "PVCCFA_EHV_CPU1_PVCC")
	)
	(segment
		(start 54.074314 -153.840434)
		(end 53.6448 -154.269948)
		(width 0.4572)
		(layer "In6.Cu")
		(net "PVCCFA_EHV_CPU1_PVCC")
	)
	(segment
		(start 52.0954 -165.293548)
		(end 50.3682 -167.020748)
		(width 0.381)
		(layer "In6.Cu")
		(net "PVCCFA_EHV_CPU1_PVCC")
	)
	(segment
		(start 53.5686 -145.329148)
		(end 53.5686 -147.716748)
		(width 0.4572)
		(layer "In6.Cu")
		(net "PVCCFA_EHV_CPU1_PVCC")
	)
	(segment
		(start 49.7332 -169.357548)
		(end 49.7332 -170.703748)
		(width 0.381)
		(layer "In6.Cu")
		(net "PVCCFA_EHV_CPU1_PVCC")
	)
	(segment
		(start 54.074314 -157.010862)
		(end 54.074314 -161.539174)
		(width 0.4572)
		(layer "In6.Cu")
		(net "PVCCFA_EHV_CPU1_PVCC")
	)
	(segment
		(start 50.34788 -170.906948)
		(end 50.39868 -170.856148)
		(width 0.381)
		(layer "In6.Cu")
		(net "PVCCFA_EHV_CPU1_PVCC")
	)
	(segment
		(start 54.0512 -161.562288)
		(end 54.0512 -162.347148)
		(width 0.381)
		(layer "In6.Cu")
		(net "PVCCFA_EHV_CPU1_PVCC")
	)
	(segment
		(start 53.7718 -162.626548)
		(end 53.0606 -162.626548)
		(width 0.381)
		(layer "In6.Cu")
		(net "PVCCFA_EHV_CPU1_PVCC")
	)
	(segment
		(start 53.0606 -162.626548)
		(end 52.0954 -163.591748)
		(width 0.381)
		(layer "In6.Cu")
		(net "PVCCFA_EHV_CPU1_PVCC")
	)
	(segment
		(start 53.6448 -154.269948)
		(end 53.6448 -156.581348)
		(width 0.4572)
		(layer "In6.Cu")
		(net "PVCCFA_EHV_CPU1_PVCC")
	)
	(segment
		(start 50.3682 -167.020748)
		(end 50.3682 -168.722548)
		(width 0.381)
		(layer "In6.Cu")
		(net "PVCCFA_EHV_CPU1_PVCC")
	)
	(segment
		(start 52.0954 -163.591748)
		(end 52.0954 -165.293548)
		(width 0.381)
		(layer "In6.Cu")
		(net "PVCCFA_EHV_CPU1_PVCC")
	)
	(segment
		(start 52.330858 -172.305726)
		(end 52.330858 -171.954952)
		(width 0.254)
		(layer "F.Cu")
		(net "PVCCFA_EHV_CPU1_NC1")
	)
	(segment
		(start 52.330858 -171.954952)
		(end 51.352704 -170.976798)
		(width 0.254)
		(layer "F.Cu")
		(net "PVCCFA_EHV_CPU1_NC1")
	)
	(segment
		(start 51.352704 -170.976798)
		(end 51.10988 -170.976798)
		(width 0.254)
		(layer "F.Cu")
		(net "PVCCFA_EHV_CPU1_NC1")
	)
	(segment
		(start 53.712364 -171.129198)
		(end 53.330856 -171.510706)
		(width 0.254)
		(layer "F.Cu")
		(net "PVCCFA_EHV_CPU1_LSET1")
	)
	(segment
		(start 53.330856 -171.510706)
		(end 53.330856 -172.305726)
		(width 0.254)
		(layer "F.Cu")
		(net "PVCCFA_EHV_CPU1_LSET1")
	)
	(segment
		(start 36.556188 -135.072882)
		(end 36.556188 -133.81482)
		(width 0.254)
		(layer "F.Cu")
		(net "PVCCFA_EHV_CPU1_EN_R")
	)
	(segment
		(start 35.265614 -131.75615)
		(end 34.943034 -131.43357)
		(width 0.12954)
		(layer "F.Cu")
		(net "PVCCFA_EHV_CPU1_EN_R")
	)
	(segment
		(start 35.518598 -131.75615)
		(end 35.265614 -131.75615)
		(width 0.12954)
		(layer "F.Cu")
		(net "PVCCFA_EHV_CPU1_EN_R")
	)
	(segment
		(start 36.556188 -133.81482)
		(end 36.556188 -132.79374)
		(width 0.254)
		(layer "F.Cu")
		(net "PVCCFA_EHV_CPU1_EN_R")
	)
	(segment
		(start 36.556188 -132.79374)
		(end 35.518598 -131.75615)
		(width 0.254)
		(layer "F.Cu")
		(net "PVCCFA_EHV_CPU1_EN_R")
	)
	(segment
		(start 34.943034 -131.43357)
		(end 34.461196 -131.43357)
		(width 0.12954)
		(layer "F.Cu")
		(net "PVCCFA_EHV_CPU1_EN_R")
	)
	(via
		(at 36.556188 -135.072882)
		(size 0.762)
		(drill 0.381)
		(layers "F.Cu" "B.Cu")
		(net "PVCCFA_EHV_CPU1_EN_R")
	)
	(segment
		(start 29.034994 -129.433574)
		(end 29.661104 -129.433574)
		(width 0.1778)
		(layer "F.Cu")
		(net "PVCCFA_EHV_CPU1_BTSEN")
	)
	(segment
		(start 50.804572 -172.082968)
		(end 51.108102 -172.082968)
		(width 0.254)
		(layer "F.Cu")
		(net "PVCCFA_EHV_CPU1_BTSEN")
	)
	(segment
		(start 28.570682 -129.701798)
		(end 28.76677 -129.701798)
		(width 0.254)
		(layer "F.Cu")
		(net "PVCCFA_EHV_CPU1_BTSEN")
	)
	(segment
		(start 28.76677 -129.701798)
		(end 29.034994 -129.433574)
		(width 0.254)
		(layer "F.Cu")
		(net "PVCCFA_EHV_CPU1_BTSEN")
	)
	(segment
		(start 51.108102 -172.082968)
		(end 51.33086 -172.305726)
		(width 0.254)
		(layer "F.Cu")
		(net "PVCCFA_EHV_CPU1_BTSEN")
	)
	(via
		(at 28.570682 -129.701798)
		(size 0.508)
		(drill 0.254)
		(layers "F.Cu" "B.Cu")
		(net "PVCCFA_EHV_CPU1_BTSEN")
	)
	(via
		(at 25.36952 -133.6802)
		(size 0.508)
		(drill 0.254)
		(layers "F.Cu" "B.Cu")
		(net "PVCCFA_EHV_CPU1_BTSEN")
	)
	(via
		(at 50.804572 -172.082968)
		(size 0.508)
		(drill 0.254)
		(layers "F.Cu" "B.Cu")
		(net "PVCCFA_EHV_CPU1_BTSEN")
	)
	(segment
		(start 28.574238 -129.705354)
		(end 28.574238 -130.477006)
		(width 0.254)
		(layer "B.Cu")
		(net "PVCCFA_EHV_CPU1_BTSEN")
	)
	(segment
		(start 25.36952 -133.6802)
		(end 25.4889 -133.79958)
		(width 0.254)
		(layer "B.Cu")
		(net "PVCCFA_EHV_CPU1_BTSEN")
	)
	(segment
		(start 28.570682 -129.701798)
		(end 28.574238 -129.705354)
		(width 0.254)
		(layer "B.Cu")
		(net "PVCCFA_EHV_CPU1_BTSEN")
	)
	(segment
		(start 29.167582 -129.701798)
		(end 28.570682 -129.701798)
		(width 0.254)
		(layer "B.Cu")
		(net "PVCCFA_EHV_CPU1_BTSEN")
	)
	(segment
		(start 29.763466 -131.831842)
		(end 29.763466 -130.297682)
		(width 0.254)
		(layer "B.Cu")
		(net "PVCCFA_EHV_CPU1_BTSEN")
	)
	(segment
		(start 25.4889 -133.79958)
		(end 27.795728 -133.79958)
		(width 0.254)
		(layer "B.Cu")
		(net "PVCCFA_EHV_CPU1_BTSEN")
	)
	(segment
		(start 29.763466 -130.297682)
		(end 29.167582 -129.701798)
		(width 0.254)
		(layer "B.Cu")
		(net "PVCCFA_EHV_CPU1_BTSEN")
	)
	(segment
		(start 27.795728 -133.79958)
		(end 29.763466 -131.831842)
		(width 0.254)
		(layer "B.Cu")
		(net "PVCCFA_EHV_CPU1_BTSEN")
	)
	(segment
		(start 47.60722 -173.228508)
		(end 50.28184 -173.228508)
		(width 0.254)
		(layer "In13.Cu")
		(net "PVCCFA_EHV_CPU1_BTSEN")
	)
	(segment
		(start 29.85262 -137.505948)
		(end 31.0007 -137.505948)
		(width 0.254)
		(layer "In13.Cu")
		(net "PVCCFA_EHV_CPU1_BTSEN")
	)
	(segment
		(start 37.846 -168.344088)
		(end 43.46956 -173.967648)
		(width 0.254)
		(layer "In13.Cu")
		(net "PVCCFA_EHV_CPU1_BTSEN")
	)
	(segment
		(start 25.36952 -133.6802)
		(end 26.026872 -133.6802)
		(width 0.254)
		(layer "In13.Cu")
		(net "PVCCFA_EHV_CPU1_BTSEN")
	)
	(segment
		(start 50.28184 -173.228508)
		(end 50.804572 -172.705776)
		(width 0.254)
		(layer "In13.Cu")
		(net "PVCCFA_EHV_CPU1_BTSEN")
	)
	(segment
		(start 31.0007 -137.505948)
		(end 37.846 -144.351248)
		(width 0.254)
		(layer "In13.Cu")
		(net "PVCCFA_EHV_CPU1_BTSEN")
	)
	(segment
		(start 50.804572 -172.705776)
		(end 50.804572 -172.082968)
		(width 0.254)
		(layer "In13.Cu")
		(net "PVCCFA_EHV_CPU1_BTSEN")
	)
	(segment
		(start 26.026872 -133.6802)
		(end 29.85262 -137.505948)
		(width 0.254)
		(layer "In13.Cu")
		(net "PVCCFA_EHV_CPU1_BTSEN")
	)
	(segment
		(start 37.846 -144.351248)
		(end 37.846 -168.344088)
		(width 0.254)
		(layer "In13.Cu")
		(net "PVCCFA_EHV_CPU1_BTSEN")
	)
	(segment
		(start 43.46956 -173.967648)
		(end 46.86808 -173.967648)
		(width 0.254)
		(layer "In13.Cu")
		(net "PVCCFA_EHV_CPU1_BTSEN")
	)
	(segment
		(start 46.86808 -173.967648)
		(end 47.60722 -173.228508)
		(width 0.254)
		(layer "In13.Cu")
		(net "PVCCFA_EHV_CPU1_BTSEN")
	)
	(segment
		(start 49.9999 -174.880778)
		(end 50.765964 -174.880778)
		(width 0.1524)
		(layer "F.Cu")
		(net "PVCCFA_EHV_CPU1_BPWM1")
	)
	(segment
		(start 30.261052 -126.797562)
		(end 30.261052 -127.233426)
		(width 0.1524)
		(layer "F.Cu")
		(net "PVCCFA_EHV_CPU1_BPWM1")
	)
	(segment
		(start 30.753558 -126.305056)
		(end 30.261052 -126.797562)
		(width 0.1524)
		(layer "F.Cu")
		(net "PVCCFA_EHV_CPU1_BPWM1")
	)
	(segment
		(start 49.475898 -174.663608)
		(end 49.9999 -174.880778)
		(width 0.1524)
		(layer "F.Cu")
		(net "PVCCFA_EHV_CPU1_BPWM1")
	)
	(segment
		(start 31.76778 -123.630944)
		(end 30.753558 -124.645166)
		(width 0.1524)
		(layer "F.Cu")
		(net "PVCCFA_EHV_CPU1_BPWM1")
	)
	(segment
		(start 49.325784 -174.513494)
		(end 49.475898 -174.663608)
		(width 0.1524)
		(layer "F.Cu")
		(net "PVCCFA_EHV_CPU1_BPWM1")
	)
	(segment
		(start 30.753558 -124.645166)
		(end 30.753558 -126.305056)
		(width 0.1524)
		(layer "F.Cu")
		(net "PVCCFA_EHV_CPU1_BPWM1")
	)
	(via
		(at 49.325784 -174.513494)
		(size 0.508)
		(drill 0.254)
		(layers "F.Cu" "B.Cu")
		(net "PVCCFA_EHV_CPU1_BPWM1")
	)
	(via
		(at 31.76778 -123.630944)
		(size 0.508)
		(drill 0.254)
		(layers "F.Cu" "B.Cu")
		(net "PVCCFA_EHV_CPU1_BPWM1")
	)
	(segment
		(start 42.91584 -125.518418)
		(end 40.266874 -122.869452)
		(width 0.254)
		(layer "In2.Cu")
		(net "PVCCFA_EHV_CPU1_BPWM1")
	)
	(segment
		(start 36.942522 -143.595344)
		(end 42.91584 -137.622026)
		(width 0.254)
		(layer "In2.Cu")
		(net "PVCCFA_EHV_CPU1_BPWM1")
	)
	(segment
		(start 35.7251 -169.512488)
		(end 35.7251 -155.938728)
		(width 0.254)
		(layer "In2.Cu")
		(net "PVCCFA_EHV_CPU1_BPWM1")
	)
	(segment
		(start 40.726106 -174.513494)
		(end 35.7251 -169.512488)
		(width 0.254)
		(layer "In2.Cu")
		(net "PVCCFA_EHV_CPU1_BPWM1")
	)
	(segment
		(start 40.266874 -122.869452)
		(end 32.529272 -122.869452)
		(width 0.254)
		(layer "In2.Cu")
		(net "PVCCFA_EHV_CPU1_BPWM1")
	)
	(segment
		(start 36.942522 -154.721306)
		(end 36.942522 -143.595344)
		(width 0.254)
		(layer "In2.Cu")
		(net "PVCCFA_EHV_CPU1_BPWM1")
	)
	(segment
		(start 49.325784 -174.513494)
		(end 40.726106 -174.513494)
		(width 0.254)
		(layer "In2.Cu")
		(net "PVCCFA_EHV_CPU1_BPWM1")
	)
	(segment
		(start 42.91584 -137.622026)
		(end 42.91584 -125.518418)
		(width 0.254)
		(layer "In2.Cu")
		(net "PVCCFA_EHV_CPU1_BPWM1")
	)
	(segment
		(start 32.529272 -122.869452)
		(end 31.76778 -123.630944)
		(width 0.254)
		(layer "In2.Cu")
		(net "PVCCFA_EHV_CPU1_BPWM1")
	)
	(segment
		(start 35.7251 -155.938728)
		(end 36.942522 -154.721306)
		(width 0.254)
		(layer "In2.Cu")
		(net "PVCCFA_EHV_CPU1_BPWM1")
	)
	(segment
		(start 30.137608 -134.33044)
		(end 30.137608 -132.458714)
		(width 0.254)
		(layer "F.Cu")
		(net "PVCCFA_EHV_CPU1_BCSP1")
	)
	(segment
		(start 50.35804 -172.880782)
		(end 50.765964 -172.880782)
		(width 0.254)
		(layer "F.Cu")
		(net "PVCCFA_EHV_CPU1_BCSP1")
	)
	(segment
		(start 49.796446 -172.319188)
		(end 50.35804 -172.880782)
		(width 0.254)
		(layer "F.Cu")
		(net "PVCCFA_EHV_CPU1_BCSP1")
	)
	(segment
		(start 49.796446 -172.26153)
		(end 49.796446 -172.319188)
		(width 0.254)
		(layer "F.Cu")
		(net "PVCCFA_EHV_CPU1_BCSP1")
	)
	(segment
		(start 30.137608 -132.458714)
		(end 30.261052 -132.33527)
		(width 0.254)
		(layer "F.Cu")
		(net "PVCCFA_EHV_CPU1_BCSP1")
	)
	(segment
		(start 30.261052 -132.33527)
		(end 30.261052 -132.033518)
		(width 0.1778)
		(layer "F.Cu")
		(net "PVCCFA_EHV_CPU1_BCSP1")
	)
	(via
		(at 30.137608 -134.33044)
		(size 0.508)
		(drill 0.254)
		(layers "F.Cu" "B.Cu")
		(net "PVCCFA_EHV_CPU1_BCSP1")
	)
	(via
		(at 49.796446 -172.26153)
		(size 0.508)
		(drill 0.254)
		(layers "F.Cu" "B.Cu")
		(net "PVCCFA_EHV_CPU1_BCSP1")
	)
	(segment
		(start 46.55566 -170.091608)
		(end 47.0916 -170.627548)
		(width 0.254)
		(layer "In4.Cu")
		(net "PVCCFA_EHV_CPU1_BCSP1")
	)
	(segment
		(start 49.5554 -172.020484)
		(end 49.796446 -172.26153)
		(width 0.254)
		(layer "In4.Cu")
		(net "PVCCFA_EHV_CPU1_BCSP1")
	)
	(segment
		(start 48.960532 -170.627548)
		(end 49.5554 -171.222416)
		(width 0.254)
		(layer "In4.Cu")
		(net "PVCCFA_EHV_CPU1_BCSP1")
	)
	(segment
		(start 38.359334 -137.618724)
		(end 38.359334 -150.575518)
		(width 0.254)
		(layer "In4.Cu")
		(net "PVCCFA_EHV_CPU1_BCSP1")
	)
	(segment
		(start 38.359334 -150.575518)
		(end 46.55566 -158.771844)
		(width 0.254)
		(layer "In4.Cu")
		(net "PVCCFA_EHV_CPU1_BCSP1")
	)
	(segment
		(start 47.0916 -170.627548)
		(end 48.960532 -170.627548)
		(width 0.254)
		(layer "In4.Cu")
		(net "PVCCFA_EHV_CPU1_BCSP1")
	)
	(segment
		(start 30.137608 -134.33044)
		(end 30.489398 -133.97865)
		(width 0.254)
		(layer "In4.Cu")
		(net "PVCCFA_EHV_CPU1_BCSP1")
	)
	(segment
		(start 34.71926 -133.97865)
		(end 38.359334 -137.618724)
		(width 0.254)
		(layer "In4.Cu")
		(net "PVCCFA_EHV_CPU1_BCSP1")
	)
	(segment
		(start 49.5554 -171.222416)
		(end 49.5554 -172.020484)
		(width 0.254)
		(layer "In4.Cu")
		(net "PVCCFA_EHV_CPU1_BCSP1")
	)
	(segment
		(start 30.489398 -133.97865)
		(end 34.71926 -133.97865)
		(width 0.254)
		(layer "In4.Cu")
		(net "PVCCFA_EHV_CPU1_BCSP1")
	)
	(segment
		(start 46.55566 -158.771844)
		(end 46.55566 -170.091608)
		(width 0.254)
		(layer "In4.Cu")
		(net "PVCCFA_EHV_CPU1_BCSP1")
	)
	(segment
		(start 98.013012 -215.436958)
		(end 98.013012 -215.436704)
		(width 0.254)
		(layer "F.Cu")
		(net "PVCCFA_EHV_CPU1")
	)
	(segment
		(start 101.882448 -263.96442)
		(end 101.882448 -264.500106)
		(width 0.254)
		(layer "F.Cu")
		(net "PVCCFA_EHV_CPU1")
	)
	(segment
		(start 96.133666 -215.437212)
		(end 96.133412 -215.436958)
		(width 0.254)
		(layer "F.Cu")
		(net "PVCCFA_EHV_CPU1")
	)
	(segment
		(start 90.494612 -215.436958)
		(end 90.494612 -215.436704)
		(width 0.254)
		(layer "F.Cu")
		(net "PVCCFA_EHV_CPU1")
	)
	(segment
		(start 94.254066 -215.437212)
		(end 94.253812 -215.436958)
		(width 0.254)
		(layer "F.Cu")
		(net "PVCCFA_EHV_CPU1")
	)
	(segment
		(start 94.254066 -215.972644)
		(end 94.254066 -215.437212)
		(width 0.254)
		(layer "F.Cu")
		(net "PVCCFA_EHV_CPU1")
	)
	(segment
		(start 99.892866 -215.437212)
		(end 99.892612 -215.436958)
		(width 0.2032)
		(layer "F.Cu")
		(net "PVCCFA_EHV_CPU1")
	)
	(segment
		(start 99.892612 -215.436958)
		(end 99.892612 -215.436704)
		(width 0.2032)
		(layer "F.Cu")
		(net "PVCCFA_EHV_CPU1")
	)
	(segment
		(start 96.133412 -215.436958)
		(end 96.133412 -215.436704)
		(width 0.254)
		(layer "F.Cu")
		(net "PVCCFA_EHV_CPU1")
	)
	(segment
		(start 90.494866 -215.972644)
		(end 90.494866 -215.437212)
		(width 0.254)
		(layer "F.Cu")
		(net "PVCCFA_EHV_CPU1")
	)
	(segment
		(start 101.412294 -264.778236)
		(end 101.412294 -265.313922)
		(width 0.254)
		(layer "F.Cu")
		(net "PVCCFA_EHV_CPU1")
	)
	(segment
		(start 68.644008 -177.905156)
		(end 69.584316 -178.845464)
		(width 0.508)
		(layer "F.Cu")
		(net "PVCCFA_EHV_CPU1")
	)
	(segment
		(start 67.7037 -176.964848)
		(end 68.644008 -177.905156)
		(width 0.508)
		(layer "F.Cu")
		(net "PVCCFA_EHV_CPU1")
	)
	(segment
		(start 68.644008 -177.905156)
		(end 69.584316 -176.964848)
		(width 0.508)
		(layer "F.Cu")
		(net "PVCCFA_EHV_CPU1")
	)
	(segment
		(start 92.374212 -215.436958)
		(end 92.374212 -215.436704)
		(width 0.254)
		(layer "F.Cu")
		(net "PVCCFA_EHV_CPU1")
	)
	(segment
		(start 94.253812 -215.436958)
		(end 94.253812 -215.436704)
		(width 0.254)
		(layer "F.Cu")
		(net "PVCCFA_EHV_CPU1")
	)
	(segment
		(start 102.822248 -263.96442)
		(end 102.822248 -264.500106)
		(width 0.254)
		(layer "F.Cu")
		(net "PVCCFA_EHV_CPU1")
	)
	(segment
		(start 92.374466 -215.972644)
		(end 92.374466 -215.437212)
		(width 0.254)
		(layer "F.Cu")
		(net "PVCCFA_EHV_CPU1")
	)
	(segment
		(start 96.133666 -215.972644)
		(end 96.133666 -215.437212)
		(width 0.254)
		(layer "F.Cu")
		(net "PVCCFA_EHV_CPU1")
	)
	(segment
		(start 92.374466 -215.437212)
		(end 92.374212 -215.436958)
		(width 0.254)
		(layer "F.Cu")
		(net "PVCCFA_EHV_CPU1")
	)
	(segment
		(start 90.494866 -215.437212)
		(end 90.494612 -215.436958)
		(width 0.254)
		(layer "F.Cu")
		(net "PVCCFA_EHV_CPU1")
	)
	(segment
		(start 101.412294 -265.313922)
		(end 101.412548 -265.314176)
		(width 0.254)
		(layer "F.Cu")
		(net "PVCCFA_EHV_CPU1")
	)
	(segment
		(start 101.882448 -264.500106)
		(end 101.882194 -264.50036)
		(width 0.254)
		(layer "F.Cu")
		(net "PVCCFA_EHV_CPU1")
	)
	(segment
		(start 98.013266 -215.972644)
		(end 98.013266 -215.437212)
		(width 0.254)
		(layer "F.Cu")
		(net "PVCCFA_EHV_CPU1")
	)
	(segment
		(start 102.352094 -265.313922)
		(end 102.352348 -265.314176)
		(width 0.254)
		(layer "F.Cu")
		(net "PVCCFA_EHV_CPU1")
	)
	(segment
		(start 102.352094 -264.778236)
		(end 102.352094 -265.313922)
		(width 0.254)
		(layer "F.Cu")
		(net "PVCCFA_EHV_CPU1")
	)
	(segment
		(start 98.013266 -215.437212)
		(end 98.013012 -215.436958)
		(width 0.254)
		(layer "F.Cu")
		(net "PVCCFA_EHV_CPU1")
	)
	(segment
		(start 67.7037 -178.845464)
		(end 68.644008 -177.905156)
		(width 0.508)
		(layer "F.Cu")
		(net "PVCCFA_EHV_CPU1")
	)
	(segment
		(start 99.892866 -215.972644)
		(end 99.892866 -215.437212)
		(width 0.2032)
		(layer "F.Cu")
		(net "PVCCFA_EHV_CPU1")
	)
	(segment
		(start 102.822248 -264.500106)
		(end 102.821994 -264.50036)
		(width 0.254)
		(layer "F.Cu")
		(net "PVCCFA_EHV_CPU1")
	)
	(via
		(at 65.884806 -177.502058)
		(size 0.508)
		(drill 0.254)
		(layers "F.Cu" "B.Cu")
		(net "PVCCFA_EHV_CPU1")
	)
	(via
		(at 65.130426 -171.594018)
		(size 0.508)
		(drill 0.254)
		(layers "F.Cu" "B.Cu")
		(net "PVCCFA_EHV_CPU1")
	)
	(via
		(at 65.138046 -172.231558)
		(size 0.508)
		(drill 0.254)
		(layers "F.Cu" "B.Cu")
		(net "PVCCFA_EHV_CPU1")
	)
	(via
		(at 65.790826 -171.594018)
		(size 0.508)
		(drill 0.254)
		(layers "F.Cu" "B.Cu")
		(net "PVCCFA_EHV_CPU1")
	)
	(via
		(at 65.232026 -176.216818)
		(size 0.508)
		(drill 0.254)
		(layers "F.Cu" "B.Cu")
		(net "PVCCFA_EHV_CPU1")
	)
	(via
		(at 92.374212 -215.436704)
		(size 0.4572)
		(drill 0.2032)
		(layers "F.Cu" "B.Cu")
		(net "PVCCFA_EHV_CPU1")
	)
	(via
		(at 64.579246 -176.854358)
		(size 0.508)
		(drill 0.254)
		(layers "F.Cu" "B.Cu")
		(net "PVCCFA_EHV_CPU1")
	)
	(via
		(at 63.817246 -172.231558)
		(size 0.508)
		(drill 0.254)
		(layers "F.Cu" "B.Cu")
		(net "PVCCFA_EHV_CPU1")
	)
	(via
		(at 65.798446 -172.231558)
		(size 0.508)
		(drill 0.254)
		(layers "F.Cu" "B.Cu")
		(net "PVCCFA_EHV_CPU1")
	)
	(via
		(at 65.224406 -177.502058)
		(size 0.508)
		(drill 0.254)
		(layers "F.Cu" "B.Cu")
		(net "PVCCFA_EHV_CPU1")
	)
	(via
		(at 63.243206 -177.502058)
		(size 0.508)
		(drill 0.254)
		(layers "F.Cu" "B.Cu")
		(net "PVCCFA_EHV_CPU1")
	)
	(via
		(at 94.253812 -215.436704)
		(size 0.4572)
		(drill 0.2032)
		(layers "F.Cu" "B.Cu")
		(net "PVCCFA_EHV_CPU1")
	)
	(via
		(at 63.0682 -178.780948)
		(size 0.508)
		(drill 0.254)
		(layers "F.Cu" "B.Cu")
		(net "PVCCFA_EHV_CPU1")
	)
	(via
		(at 101.538024 -206.66075)
		(size 0.6604)
		(drill 0.3302)
		(layers "F.Cu" "B.Cu")
		(net "PVCCFA_EHV_CPU1")
	)
	(via
		(at 102.352348 -265.314176)
		(size 0.4572)
		(drill 0.2032)
		(layers "F.Cu" "B.Cu")
		(net "PVCCFA_EHV_CPU1")
	)
	(via
		(at 103.98379 -257.69316)
		(size 0.4572)
		(drill 0.2032)
		(layers "F.Cu" "B.Cu")
		(net "PVCCFA_EHV_CPU1")
	)
	(via
		(at 63.250826 -176.216818)
		(size 0.508)
		(drill 0.254)
		(layers "F.Cu" "B.Cu")
		(net "PVCCFA_EHV_CPU1")
	)
	(via
		(at 63.809626 -171.594018)
		(size 0.508)
		(drill 0.254)
		(layers "F.Cu" "B.Cu")
		(net "PVCCFA_EHV_CPU1")
	)
	(via
		(at 101.882194 -264.50036)
		(size 0.4572)
		(drill 0.2032)
		(layers "F.Cu" "B.Cu")
		(net "PVCCFA_EHV_CPU1")
	)
	(via
		(at 103.214424 -206.66075)
		(size 0.6604)
		(drill 0.3302)
		(layers "F.Cu" "B.Cu")
		(net "PVCCFA_EHV_CPU1")
	)
	(via
		(at 63.903606 -177.502058)
		(size 0.508)
		(drill 0.254)
		(layers "F.Cu" "B.Cu")
		(net "PVCCFA_EHV_CPU1")
	)
	(via
		(at 104.890824 -206.66075)
		(size 0.6604)
		(drill 0.3302)
		(layers "F.Cu" "B.Cu")
		(net "PVCCFA_EHV_CPU1")
	)
	(via
		(at 64.470026 -171.594018)
		(size 0.508)
		(drill 0.254)
		(layers "F.Cu" "B.Cu")
		(net "PVCCFA_EHV_CPU1")
	)
	(via
		(at 64.571626 -176.216818)
		(size 0.508)
		(drill 0.254)
		(layers "F.Cu" "B.Cu")
		(net "PVCCFA_EHV_CPU1")
	)
	(via
		(at 104.890824 -204.98435)
		(size 0.6604)
		(drill 0.3302)
		(layers "F.Cu" "B.Cu")
		(net "PVCCFA_EHV_CPU1")
	)
	(via
		(at 96.133412 -215.436704)
		(size 0.4572)
		(drill 0.2032)
		(layers "F.Cu" "B.Cu")
		(net "PVCCFA_EHV_CPU1")
	)
	(via
		(at 101.538024 -204.98435)
		(size 0.6604)
		(drill 0.3302)
		(layers "F.Cu" "B.Cu")
		(net "PVCCFA_EHV_CPU1")
	)
	(via
		(at 99.861624 -206.66075)
		(size 0.6604)
		(drill 0.3302)
		(layers "F.Cu" "B.Cu")
		(net "PVCCFA_EHV_CPU1")
	)
	(via
		(at 65.892426 -176.216818)
		(size 0.508)
		(drill 0.254)
		(layers "F.Cu" "B.Cu")
		(net "PVCCFA_EHV_CPU1")
	)
	(via
		(at 64.477646 -172.231558)
		(size 0.508)
		(drill 0.254)
		(layers "F.Cu" "B.Cu")
		(net "PVCCFA_EHV_CPU1")
	)
	(via
		(at 102.821994 -264.50036)
		(size 0.4572)
		(drill 0.2032)
		(layers "F.Cu" "B.Cu")
		(net "PVCCFA_EHV_CPU1")
	)
	(via
		(at 104.56799 -257.69316)
		(size 0.4572)
		(drill 0.2032)
		(layers "F.Cu" "B.Cu")
		(net "PVCCFA_EHV_CPU1")
	)
	(via
		(at 63.911226 -176.216818)
		(size 0.508)
		(drill 0.254)
		(layers "F.Cu" "B.Cu")
		(net "PVCCFA_EHV_CPU1")
	)
	(via
		(at 64.564006 -177.502058)
		(size 0.508)
		(drill 0.254)
		(layers "F.Cu" "B.Cu")
		(net "PVCCFA_EHV_CPU1")
	)
	(via
		(at 65.900046 -176.854358)
		(size 0.508)
		(drill 0.254)
		(layers "F.Cu" "B.Cu")
		(net "PVCCFA_EHV_CPU1")
	)
	(via
		(at 103.214424 -204.98435)
		(size 0.6604)
		(drill 0.3302)
		(layers "F.Cu" "B.Cu")
		(net "PVCCFA_EHV_CPU1")
	)
	(via
		(at 101.412548 -265.314176)
		(size 0.4572)
		(drill 0.2032)
		(layers "F.Cu" "B.Cu")
		(net "PVCCFA_EHV_CPU1")
	)
	(via
		(at 90.494612 -215.436704)
		(size 0.4572)
		(drill 0.2032)
		(layers "F.Cu" "B.Cu")
		(net "PVCCFA_EHV_CPU1")
	)
	(via
		(at 63.918846 -176.854358)
		(size 0.508)
		(drill 0.254)
		(layers "F.Cu" "B.Cu")
		(net "PVCCFA_EHV_CPU1")
	)
	(via
		(at 98.013012 -215.436704)
		(size 0.4572)
		(drill 0.2032)
		(layers "F.Cu" "B.Cu")
		(net "PVCCFA_EHV_CPU1")
	)
	(via
		(at 103.39959 -257.69316)
		(size 0.4572)
		(drill 0.2032)
		(layers "F.Cu" "B.Cu")
		(net "PVCCFA_EHV_CPU1")
	)
	(via
		(at 99.892612 -215.436704)
		(size 0.4572)
		(drill 0.2032)
		(layers "F.Cu" "B.Cu")
		(net "PVCCFA_EHV_CPU1")
	)
	(via
		(at 65.239646 -176.854358)
		(size 0.508)
		(drill 0.254)
		(layers "F.Cu" "B.Cu")
		(net "PVCCFA_EHV_CPU1")
	)
	(via
		(at 99.861624 -204.98435)
		(size 0.6604)
		(drill 0.3302)
		(layers "F.Cu" "B.Cu")
		(net "PVCCFA_EHV_CPU1")
	)
	(via
		(at 63.156846 -172.231558)
		(size 0.508)
		(drill 0.254)
		(layers "F.Cu" "B.Cu")
		(net "PVCCFA_EHV_CPU1")
	)
	(segment
		(start 68.644008 -176.964848)
		(end 68.644008 -177.905156)
		(width 0.508)
		(layer "B.Cu")
		(net "PVCCFA_EHV_CPU1")
	)
	(segment
		(start 67.7037 -176.964848)
		(end 68.644008 -177.905156)
		(width 0.508)
		(layer "B.Cu")
		(net "PVCCFA_EHV_CPU1")
	)
	(segment
		(start 68.644008 -177.905156)
		(end 67.7037 -177.905156)
		(width 0.508)
		(layer "B.Cu")
		(net "PVCCFA_EHV_CPU1")
	)
	(segment
		(start 68.644008 -177.905156)
		(end 69.35978 -177.189384)
		(width 0.508)
		(layer "In13.Cu")
		(net "PVCCFA_EHV_CPU1")
	)
	(segment
		(start 67.928236 -177.189384)
		(end 68.644008 -177.905156)
		(width 0.508)
		(layer "In13.Cu")
		(net "PVCCFA_EHV_CPU1")
	)
	(segment
		(start 68.644008 -177.905156)
		(end 69.35978 -178.620928)
		(width 0.508)
		(layer "In13.Cu")
		(net "PVCCFA_EHV_CPU1")
	)
	(segment
		(start 67.928236 -178.620928)
		(end 68.644008 -177.905156)
		(width 0.508)
		(layer "In13.Cu")
		(net "PVCCFA_EHV_CPU1")
	)
	(segment
		(start 418.840158 -155.611576)
		(end 418.840158 -154.994102)
		(width 0.254)
		(layer "F.Cu")
		(net "PVCCFA_EHV_CPU0_VDD1")
	)
	(segment
		(start 419.784784 -157.032198)
		(end 418.984684 -156.232098)
		(width 0.254)
		(layer "F.Cu")
		(net "PVCCFA_EHV_CPU0_VDD1")
	)
	(segment
		(start 418.984684 -156.232098)
		(end 418.90188 -156.232098)
		(width 0.254)
		(layer "F.Cu")
		(net "PVCCFA_EHV_CPU0_VDD1")
	)
	(segment
		(start 419.91788 -157.648148)
		(end 419.91788 -157.032198)
		(width 0.254)
		(layer "F.Cu")
		(net "PVCCFA_EHV_CPU0_VDD1")
	)
	(segment
		(start 418.90188 -155.673298)
		(end 418.840158 -155.611576)
		(width 0.254)
		(layer "F.Cu")
		(net "PVCCFA_EHV_CPU0_VDD1")
	)
	(segment
		(start 419.91788 -157.032198)
		(end 419.784784 -157.032198)
		(width 0.254)
		(layer "F.Cu")
		(net "PVCCFA_EHV_CPU0_VDD1")
	)
	(segment
		(start 418.90188 -156.232098)
		(end 418.90188 -155.673298)
		(width 0.254)
		(layer "F.Cu")
		(net "PVCCFA_EHV_CPU0_VDD1")
	)
	(via
		(at 419.91788 -157.648148)
		(size 0.508)
		(drill 0.254)
		(layers "F.Cu" "B.Cu")
		(net "PVCCFA_EHV_CPU0_VDD1")
	)
	(via
		(at 423.982388 -153.54046)
		(size 0.508)
		(drill 0.254)
		(layers "F.Cu" "B.Cu")
		(net "PVCCFA_EHV_CPU0_VDD1")
	)
	(segment
		(start 423.26052 -154.262328)
		(end 422.91635 -154.262328)
		(width 0.4572)
		(layer "B.Cu")
		(net "PVCCFA_EHV_CPU0_VDD1")
	)
	(segment
		(start 419.91788 -157.032198)
		(end 419.91788 -157.648148)
		(width 0.381)
		(layer "B.Cu")
		(net "PVCCFA_EHV_CPU0_VDD1")
	)
	(segment
		(start 423.982388 -153.54046)
		(end 423.26052 -154.262328)
		(width 0.4572)
		(layer "B.Cu")
		(net "PVCCFA_EHV_CPU0_VDD1")
	)
	(segment
		(start 423.52976 -153.993088)
		(end 423.52976 -155.364688)
		(width 0.4572)
		(layer "In2.Cu")
		(net "PVCCFA_EHV_CPU0_VDD1")
	)
	(segment
		(start 423.52976 -155.364688)
		(end 422.97858 -155.915868)
		(width 0.4572)
		(layer "In2.Cu")
		(net "PVCCFA_EHV_CPU0_VDD1")
	)
	(segment
		(start 422.97858 -155.915868)
		(end 421.65016 -155.915868)
		(width 0.4572)
		(layer "In2.Cu")
		(net "PVCCFA_EHV_CPU0_VDD1")
	)
	(segment
		(start 423.982388 -153.54046)
		(end 423.52976 -153.993088)
		(width 0.4572)
		(layer "In2.Cu")
		(net "PVCCFA_EHV_CPU0_VDD1")
	)
	(segment
		(start 421.65016 -155.915868)
		(end 419.91788 -157.648148)
		(width 0.4572)
		(layer "In2.Cu")
		(net "PVCCFA_EHV_CPU0_VDD1")
	)
	(segment
		(start 416.834828 -174.396654)
		(end 416.218878 -174.396654)
		(width 0.254)
		(layer "F.Cu")
		(net "PVCCFA_EHV_CPU0_PVCC")
	)
	(segment
		(start 416.93465 -164.953442)
		(end 416.93465 -164.585904)
		(width 0.2286)
		(layer "F.Cu")
		(net "PVCCFA_EHV_CPU0_PVCC")
	)
	(segment
		(start 416.218878 -182.941214)
		(end 416.93465 -182.225442)
		(width 0.2286)
		(layer "F.Cu")
		(net "PVCCFA_EHV_CPU0_PVCC")
	)
	(segment
		(start 416.218878 -183.032654)
		(end 416.218878 -182.941214)
		(width 0.2286)
		(layer "F.Cu")
		(net "PVCCFA_EHV_CPU0_PVCC")
	)
	(segment
		(start 422.152064 -155.699714)
		(end 423.754296 -155.699714)
		(width 0.381)
		(layer "F.Cu")
		(net "PVCCFA_EHV_CPU0_PVCC")
	)
	(segment
		(start 423.754296 -155.699714)
		(end 424.026838 -155.972256)
		(width 0.381)
		(layer "F.Cu")
		(net "PVCCFA_EHV_CPU0_PVCC")
	)
	(segment
		(start 416.218878 -165.669214)
		(end 416.93465 -164.953442)
		(width 0.2286)
		(layer "F.Cu")
		(net "PVCCFA_EHV_CPU0_PVCC")
	)
	(segment
		(start 416.218878 -174.305214)
		(end 416.93465 -173.589442)
		(width 0.2286)
		(layer "F.Cu")
		(net "PVCCFA_EHV_CPU0_PVCC")
	)
	(segment
		(start 421.92448 -155.927298)
		(end 422.152064 -155.699714)
		(width 0.381)
		(layer "F.Cu")
		(net "PVCCFA_EHV_CPU0_PVCC")
	)
	(segment
		(start 416.93465 -182.225442)
		(end 416.93465 -181.857904)
		(width 0.2286)
		(layer "F.Cu")
		(net "PVCCFA_EHV_CPU0_PVCC")
	)
	(segment
		(start 416.834828 -183.032654)
		(end 416.218878 -183.032654)
		(width 0.254)
		(layer "F.Cu")
		(net "PVCCFA_EHV_CPU0_PVCC")
	)
	(segment
		(start 416.218878 -165.760654)
		(end 416.218878 -165.669214)
		(width 0.2286)
		(layer "F.Cu")
		(net "PVCCFA_EHV_CPU0_PVCC")
	)
	(segment
		(start 416.834828 -165.760654)
		(end 416.218878 -165.760654)
		(width 0.254)
		(layer "F.Cu")
		(net "PVCCFA_EHV_CPU0_PVCC")
	)
	(segment
		(start 416.218878 -174.396654)
		(end 416.218878 -174.305214)
		(width 0.2286)
		(layer "F.Cu")
		(net "PVCCFA_EHV_CPU0_PVCC")
	)
	(segment
		(start 416.93465 -173.589442)
		(end 416.93465 -173.221904)
		(width 0.2286)
		(layer "F.Cu")
		(net "PVCCFA_EHV_CPU0_PVCC")
	)
	(via
		(at 424.026838 -155.972256)
		(size 0.508)
		(drill 0.254)
		(layers "F.Cu" "B.Cu")
		(net "PVCCFA_EHV_CPU0_PVCC")
	)
	(via
		(at 416.834828 -165.760654)
		(size 0.508)
		(drill 0.254)
		(layers "F.Cu" "B.Cu")
		(net "PVCCFA_EHV_CPU0_PVCC")
	)
	(via
		(at 416.834828 -183.032654)
		(size 0.508)
		(drill 0.254)
		(layers "F.Cu" "B.Cu")
		(net "PVCCFA_EHV_CPU0_PVCC")
	)
	(via
		(at 416.233102 -183.563768)
		(size 0.6604)
		(drill 0.3302)
		(layers "F.Cu" "B.Cu")
		(net "PVCCFA_EHV_CPU0_PVCC")
	)
	(via
		(at 416.834828 -174.396654)
		(size 0.508)
		(drill 0.254)
		(layers "F.Cu" "B.Cu")
		(net "PVCCFA_EHV_CPU0_PVCC")
	)
	(segment
		(start 416.834828 -183.032654)
		(end 416.834828 -183.441594)
		(width 0.4572)
		(layer "B.Cu")
		(net "PVCCFA_EHV_CPU0_PVCC")
	)
	(segment
		(start 424.020996 -155.978098)
		(end 424.026838 -155.972256)
		(width 0.381)
		(layer "B.Cu")
		(net "PVCCFA_EHV_CPU0_PVCC")
	)
	(segment
		(start 419.91788 -156.232098)
		(end 421.064944 -156.232098)
		(width 0.381)
		(layer "B.Cu")
		(net "PVCCFA_EHV_CPU0_PVCC")
	)
	(segment
		(start 421.064944 -156.232098)
		(end 421.318944 -155.978098)
		(width 0.381)
		(layer "B.Cu")
		(net "PVCCFA_EHV_CPU0_PVCC")
	)
	(segment
		(start 416.596576 -182.264558)
		(end 416.061906 -182.799228)
		(width 0.4572)
		(layer "B.Cu")
		(net "PVCCFA_EHV_CPU0_PVCC")
	)
	(segment
		(start 416.834828 -174.396654)
		(end 416.596576 -174.158402)
		(width 0.4572)
		(layer "B.Cu")
		(net "PVCCFA_EHV_CPU0_PVCC")
	)
	(segment
		(start 416.834828 -165.760654)
		(end 416.596576 -165.522402)
		(width 0.4572)
		(layer "B.Cu")
		(net "PVCCFA_EHV_CPU0_PVCC")
	)
	(segment
		(start 421.92448 -155.978098)
		(end 424.020996 -155.978098)
		(width 0.381)
		(layer "B.Cu")
		(net "PVCCFA_EHV_CPU0_PVCC")
	)
	(segment
		(start 416.061906 -183.392572)
		(end 416.233102 -183.563768)
		(width 0.4572)
		(layer "B.Cu")
		(net "PVCCFA_EHV_CPU0_PVCC")
	)
	(segment
		(start 416.596576 -165.522402)
		(end 416.596576 -164.582602)
		(width 0.4572)
		(layer "B.Cu")
		(net "PVCCFA_EHV_CPU0_PVCC")
	)
	(segment
		(start 416.596576 -174.158402)
		(end 416.596576 -173.218602)
		(width 0.4572)
		(layer "B.Cu")
		(net "PVCCFA_EHV_CPU0_PVCC")
	)
	(segment
		(start 416.834828 -183.441594)
		(end 416.712654 -183.563768)
		(width 0.4572)
		(layer "B.Cu")
		(net "PVCCFA_EHV_CPU0_PVCC")
	)
	(segment
		(start 416.712654 -183.563768)
		(end 416.233102 -183.563768)
		(width 0.4572)
		(layer "B.Cu")
		(net "PVCCFA_EHV_CPU0_PVCC")
	)
	(segment
		(start 416.061906 -182.799228)
		(end 416.061906 -183.392572)
		(width 0.4572)
		(layer "B.Cu")
		(net "PVCCFA_EHV_CPU0_PVCC")
	)
	(segment
		(start 416.596576 -181.854602)
		(end 416.596576 -182.264558)
		(width 0.4572)
		(layer "B.Cu")
		(net "PVCCFA_EHV_CPU0_PVCC")
	)
	(segment
		(start 421.318944 -155.978098)
		(end 421.92448 -155.978098)
		(width 0.381)
		(layer "B.Cu")
		(net "PVCCFA_EHV_CPU0_PVCC")
	)
	(segment
		(start 417.09848 -158.158688)
		(end 417.09848 -161.907982)
		(width 0.254)
		(layer "In11.Cu")
		(net "PVCCFA_EHV_CPU0_PVCC")
	)
	(segment
		(start 416.8648 -165.730682)
		(end 416.834828 -165.760654)
		(width 0.254)
		(layer "In11.Cu")
		(net "PVCCFA_EHV_CPU0_PVCC")
	)
	(segment
		(start 416.834828 -179.098956)
		(end 417.20008 -179.464208)
		(width 0.254)
		(layer "In11.Cu")
		(net "PVCCFA_EHV_CPU0_PVCC")
	)
	(segment
		(start 417.33978 -164.480748)
		(end 416.8648 -164.955728)
		(width 0.254)
		(layer "In11.Cu")
		(net "PVCCFA_EHV_CPU0_PVCC")
	)
	(segment
		(start 417.33724 -173.548802)
		(end 416.834828 -174.051214)
		(width 0.254)
		(layer "In11.Cu")
		(net "PVCCFA_EHV_CPU0_PVCC")
	)
	(segment
		(start 423.88663 -155.832048)
		(end 422.17467 -155.832048)
		(width 0.254)
		(layer "In11.Cu")
		(net "PVCCFA_EHV_CPU0_PVCC")
	)
	(segment
		(start 417.20008 -179.464208)
		(end 417.20008 -181.998874)
		(width 0.254)
		(layer "In11.Cu")
		(net "PVCCFA_EHV_CPU0_PVCC")
	)
	(segment
		(start 417.33978 -162.149282)
		(end 417.33978 -164.480748)
		(width 0.254)
		(layer "In11.Cu")
		(net "PVCCFA_EHV_CPU0_PVCC")
	)
	(segment
		(start 416.834828 -174.396654)
		(end 416.834828 -179.098956)
		(width 0.254)
		(layer "In11.Cu")
		(net "PVCCFA_EHV_CPU0_PVCC")
	)
	(segment
		(start 422.17467 -155.832048)
		(end 421.80129 -156.205428)
		(width 0.254)
		(layer "In11.Cu")
		(net "PVCCFA_EHV_CPU0_PVCC")
	)
	(segment
		(start 421.80129 -156.205428)
		(end 419.05174 -156.205428)
		(width 0.254)
		(layer "In11.Cu")
		(net "PVCCFA_EHV_CPU0_PVCC")
	)
	(segment
		(start 417.20008 -181.998874)
		(end 416.834828 -182.364126)
		(width 0.254)
		(layer "In11.Cu")
		(net "PVCCFA_EHV_CPU0_PVCC")
	)
	(segment
		(start 416.834828 -170.391836)
		(end 417.33724 -170.894248)
		(width 0.254)
		(layer "In11.Cu")
		(net "PVCCFA_EHV_CPU0_PVCC")
	)
	(segment
		(start 424.026838 -155.972256)
		(end 423.88663 -155.832048)
		(width 0.254)
		(layer "In11.Cu")
		(net "PVCCFA_EHV_CPU0_PVCC")
	)
	(segment
		(start 417.09848 -161.907982)
		(end 417.33978 -162.149282)
		(width 0.254)
		(layer "In11.Cu")
		(net "PVCCFA_EHV_CPU0_PVCC")
	)
	(segment
		(start 417.33724 -170.894248)
		(end 417.33724 -173.548802)
		(width 0.254)
		(layer "In11.Cu")
		(net "PVCCFA_EHV_CPU0_PVCC")
	)
	(segment
		(start 419.05174 -156.205428)
		(end 417.09848 -158.158688)
		(width 0.254)
		(layer "In11.Cu")
		(net "PVCCFA_EHV_CPU0_PVCC")
	)
	(segment
		(start 416.834828 -182.364126)
		(end 416.834828 -183.032654)
		(width 0.254)
		(layer "In11.Cu")
		(net "PVCCFA_EHV_CPU0_PVCC")
	)
	(segment
		(start 416.834828 -174.051214)
		(end 416.834828 -174.396654)
		(width 0.254)
		(layer "In11.Cu")
		(net "PVCCFA_EHV_CPU0_PVCC")
	)
	(segment
		(start 416.834828 -165.760654)
		(end 416.834828 -170.391836)
		(width 0.254)
		(layer "In11.Cu")
		(net "PVCCFA_EHV_CPU0_PVCC")
	)
	(segment
		(start 416.8648 -164.955728)
		(end 416.8648 -165.730682)
		(width 0.254)
		(layer "In11.Cu")
		(net "PVCCFA_EHV_CPU0_PVCC")
	)
	(segment
		(start 419.340284 -155.654502)
		(end 419.340284 -154.994102)
		(width 0.254)
		(layer "F.Cu")
		(net "PVCCFA_EHV_CPU0_NC1")
	)
	(segment
		(start 419.91788 -156.232098)
		(end 419.340284 -155.654502)
		(width 0.254)
		(layer "F.Cu")
		(net "PVCCFA_EHV_CPU0_NC1")
	)
	(segment
		(start 418.340286 -155.353766)
		(end 418.194744 -155.499308)
		(width 0.254)
		(layer "F.Cu")
		(net "PVCCFA_EHV_CPU0_LSET1")
	)
	(segment
		(start 417.9062 -155.499308)
		(end 417.90112 -155.499308)
		(width 0.254)
		(layer "F.Cu")
		(net "PVCCFA_EHV_CPU0_LSET1")
	)
	(segment
		(start 417.892992 -156.104844)
		(end 417.958778 -156.17063)
		(width 0.254)
		(layer "F.Cu")
		(net "PVCCFA_EHV_CPU0_LSET1")
	)
	(segment
		(start 418.194744 -155.499308)
		(end 417.9062 -155.499308)
		(width 0.254)
		(layer "F.Cu")
		(net "PVCCFA_EHV_CPU0_LSET1")
	)
	(segment
		(start 417.90112 -155.499308)
		(end 417.892992 -155.507436)
		(width 0.254)
		(layer "F.Cu")
		(net "PVCCFA_EHV_CPU0_LSET1")
	)
	(segment
		(start 418.340286 -154.994102)
		(end 418.340286 -155.353766)
		(width 0.254)
		(layer "F.Cu")
		(net "PVCCFA_EHV_CPU0_LSET1")
	)
	(segment
		(start 417.892992 -155.507436)
		(end 417.892992 -156.104844)
		(width 0.254)
		(layer "F.Cu")
		(net "PVCCFA_EHV_CPU0_LSET1")
	)
	(via
		(at 417.9062 -155.499308)
		(size 0.508)
		(drill 0.254)
		(layers "F.Cu" "B.Cu")
		(net "PVCCFA_EHV_CPU0_LSET1")
	)
	(segment
		(start 429.856646 -139.574778)
		(end 430.200054 -139.574778)
		(width 0.254)
		(layer "F.Cu")
		(net "PVCCFA_EHV_CPU0_EN_R")
	)
	(segment
		(start 428.861474 -138.579606)
		(end 429.856646 -139.574778)
		(width 0.254)
		(layer "F.Cu")
		(net "PVCCFA_EHV_CPU0_EN_R")
	)
	(segment
		(start 430.200054 -141.330426)
		(end 430.200054 -140.595858)
		(width 0.254)
		(layer "F.Cu")
		(net "PVCCFA_EHV_CPU0_EN_R")
	)
	(segment
		(start 428.496476 -138.214608)
		(end 428.861474 -138.579606)
		(width 0.12954)
		(layer "F.Cu")
		(net "PVCCFA_EHV_CPU0_EN_R")
	)
	(segment
		(start 430.200054 -139.574778)
		(end 430.200054 -140.595858)
		(width 0.254)
		(layer "F.Cu")
		(net "PVCCFA_EHV_CPU0_EN_R")
	)
	(segment
		(start 431.442368 -142.57274)
		(end 430.200054 -141.330426)
		(width 0.254)
		(layer "F.Cu")
		(net "PVCCFA_EHV_CPU0_EN_R")
	)
	(segment
		(start 428.105062 -138.214608)
		(end 428.496476 -138.214608)
		(width 0.12954)
		(layer "F.Cu")
		(net "PVCCFA_EHV_CPU0_EN_R")
	)
	(via
		(at 431.442368 -142.57274)
		(size 0.762)
		(drill 0.381)
		(layers "F.Cu" "B.Cu")
		(net "PVCCFA_EHV_CPU0_EN_R")
	)
	(segment
		(start 422.214548 -136.482836)
		(end 422.252648 -136.482836)
		(width 0.254)
		(layer "F.Cu")
		(net "PVCCFA_EHV_CPU0_BTSEN")
	)
	(segment
		(start 420.56304 -155.21686)
		(end 420.340282 -154.994102)
		(width 0.254)
		(layer "F.Cu")
		(net "PVCCFA_EHV_CPU0_BTSEN")
	)
	(segment
		(start 422.252648 -136.482836)
		(end 422.520872 -136.214612)
		(width 0.254)
		(layer "F.Cu")
		(net "PVCCFA_EHV_CPU0_BTSEN")
	)
	(segment
		(start 420.86657 -155.21686)
		(end 420.56304 -155.21686)
		(width 0.254)
		(layer "F.Cu")
		(net "PVCCFA_EHV_CPU0_BTSEN")
	)
	(segment
		(start 422.520872 -136.214612)
		(end 423.30497 -136.214612)
		(width 0.1778)
		(layer "F.Cu")
		(net "PVCCFA_EHV_CPU0_BTSEN")
	)
	(via
		(at 422.214548 -136.482836)
		(size 0.508)
		(drill 0.254)
		(layers "F.Cu" "B.Cu")
		(net "PVCCFA_EHV_CPU0_BTSEN")
	)
	(via
		(at 423.37736 -138.260328)
		(size 0.6604)
		(drill 0.3302)
		(layers "F.Cu" "B.Cu")
		(net "PVCCFA_EHV_CPU0_BTSEN")
	)
	(via
		(at 420.86657 -155.21686)
		(size 0.508)
		(drill 0.254)
		(layers "F.Cu" "B.Cu")
		(net "PVCCFA_EHV_CPU0_BTSEN")
	)
	(segment
		(start 423.407332 -138.230356)
		(end 423.37736 -138.260328)
		(width 0.254)
		(layer "B.Cu")
		(net "PVCCFA_EHV_CPU0_BTSEN")
	)
	(segment
		(start 423.37736 -138.260328)
		(end 422.375076 -137.258044)
		(width 0.254)
		(layer "B.Cu")
		(net "PVCCFA_EHV_CPU0_BTSEN")
	)
	(segment
		(start 422.375076 -137.258044)
		(end 422.218104 -137.258044)
		(width 0.254)
		(layer "B.Cu")
		(net "PVCCFA_EHV_CPU0_BTSEN")
	)
	(segment
		(start 423.407332 -137.07872)
		(end 423.407332 -138.230356)
		(width 0.254)
		(layer "B.Cu")
		(net "PVCCFA_EHV_CPU0_BTSEN")
	)
	(segment
		(start 422.214548 -136.482836)
		(end 422.218104 -136.486392)
		(width 0.254)
		(layer "B.Cu")
		(net "PVCCFA_EHV_CPU0_BTSEN")
	)
	(segment
		(start 422.218104 -136.486392)
		(end 422.218104 -137.258044)
		(width 0.254)
		(layer "B.Cu")
		(net "PVCCFA_EHV_CPU0_BTSEN")
	)
	(segment
		(start 421.64 -152.212548)
		(end 422.1734 -152.212548)
		(width 0.254)
		(layer "In15.Cu")
		(net "PVCCFA_EHV_CPU0_BTSEN")
	)
	(segment
		(start 422.5544 -148.859748)
		(end 419.7096 -148.859748)
		(width 0.254)
		(layer "In15.Cu")
		(net "PVCCFA_EHV_CPU0_BTSEN")
	)
	(segment
		(start 423.164 -149.469348)
		(end 422.5544 -148.859748)
		(width 0.254)
		(layer "In15.Cu")
		(net "PVCCFA_EHV_CPU0_BTSEN")
	)
	(segment
		(start 422.89476 -137.163048)
		(end 422.214548 -136.482836)
		(width 0.254)
		(layer "In15.Cu")
		(net "PVCCFA_EHV_CPU0_BTSEN")
	)
	(segment
		(start 420.86657 -152.985978)
		(end 421.64 -152.212548)
		(width 0.254)
		(layer "In15.Cu")
		(net "PVCCFA_EHV_CPU0_BTSEN")
	)
	(segment
		(start 416.0266 -142.027148)
		(end 417.5506 -140.503148)
		(width 0.254)
		(layer "In15.Cu")
		(net "PVCCFA_EHV_CPU0_BTSEN")
	)
	(segment
		(start 420.86657 -155.21686)
		(end 420.86657 -152.985978)
		(width 0.254)
		(layer "In15.Cu")
		(net "PVCCFA_EHV_CPU0_BTSEN")
	)
	(segment
		(start 421.49268 -140.503148)
		(end 422.89476 -139.101068)
		(width 0.254)
		(layer "In15.Cu")
		(net "PVCCFA_EHV_CPU0_BTSEN")
	)
	(segment
		(start 422.1734 -152.212548)
		(end 423.164 -151.221948)
		(width 0.254)
		(layer "In15.Cu")
		(net "PVCCFA_EHV_CPU0_BTSEN")
	)
	(segment
		(start 422.89476 -139.101068)
		(end 422.89476 -137.163048)
		(width 0.254)
		(layer "In15.Cu")
		(net "PVCCFA_EHV_CPU0_BTSEN")
	)
	(segment
		(start 419.7096 -148.859748)
		(end 416.0266 -145.176748)
		(width 0.254)
		(layer "In15.Cu")
		(net "PVCCFA_EHV_CPU0_BTSEN")
	)
	(segment
		(start 423.164 -151.221948)
		(end 423.164 -149.469348)
		(width 0.254)
		(layer "In15.Cu")
		(net "PVCCFA_EHV_CPU0_BTSEN")
	)
	(segment
		(start 417.5506 -140.503148)
		(end 421.49268 -140.503148)
		(width 0.254)
		(layer "In15.Cu")
		(net "PVCCFA_EHV_CPU0_BTSEN")
	)
	(segment
		(start 416.0266 -145.176748)
		(end 416.0266 -142.027148)
		(width 0.254)
		(layer "In15.Cu")
		(net "PVCCFA_EHV_CPU0_BTSEN")
	)
	(segment
		(start 422.706038 -152.956514)
		(end 422.454324 -152.7048)
		(width 0.1524)
		(layer "F.Cu")
		(net "PVCCFA_EHV_CPU0_BPWM1")
	)
	(segment
		(start 421.764714 -152.41905)
		(end 420.905178 -152.41905)
		(width 0.1524)
		(layer "F.Cu")
		(net "PVCCFA_EHV_CPU0_BPWM1")
	)
	(segment
		(start 425.618656 -130.505708)
		(end 424.42892 -131.695444)
		(width 0.1524)
		(layer "F.Cu")
		(net "PVCCFA_EHV_CPU0_BPWM1")
	)
	(segment
		(start 423.904918 -133.635496)
		(end 423.904918 -134.014464)
		(width 0.1524)
		(layer "F.Cu")
		(net "PVCCFA_EHV_CPU0_BPWM1")
	)
	(segment
		(start 422.454324 -152.7048)
		(end 421.764714 -152.41905)
		(width 0.1524)
		(layer "F.Cu")
		(net "PVCCFA_EHV_CPU0_BPWM1")
	)
	(segment
		(start 424.42892 -131.695444)
		(end 424.42892 -133.111494)
		(width 0.1524)
		(layer "F.Cu")
		(net "PVCCFA_EHV_CPU0_BPWM1")
	)
	(segment
		(start 424.42892 -133.111494)
		(end 423.904918 -133.635496)
		(width 0.1524)
		(layer "F.Cu")
		(net "PVCCFA_EHV_CPU0_BPWM1")
	)
	(via
		(at 425.618656 -130.505708)
		(size 0.508)
		(drill 0.254)
		(layers "F.Cu" "B.Cu")
		(net "PVCCFA_EHV_CPU0_BPWM1")
	)
	(via
		(at 422.706038 -152.956514)
		(size 0.508)
		(drill 0.254)
		(layers "F.Cu" "B.Cu")
		(net "PVCCFA_EHV_CPU0_BPWM1")
	)
	(segment
		(start 417.6776 -149.215348)
		(end 422.4782 -149.215348)
		(width 0.254)
		(layer "In2.Cu")
		(net "PVCCFA_EHV_CPU0_BPWM1")
	)
	(segment
		(start 422.4782 -149.215348)
		(end 423.164 -149.901148)
		(width 0.254)
		(layer "In2.Cu")
		(net "PVCCFA_EHV_CPU0_BPWM1")
	)
	(segment
		(start 418.367972 -130.419348)
		(end 415.51098 -133.27634)
		(width 0.254)
		(layer "In2.Cu")
		(net "PVCCFA_EHV_CPU0_BPWM1")
	)
	(segment
		(start 425.618656 -130.505708)
		(end 425.532296 -130.419348)
		(width 0.254)
		(layer "In2.Cu")
		(net "PVCCFA_EHV_CPU0_BPWM1")
	)
	(segment
		(start 415.51098 -147.048728)
		(end 417.6776 -149.215348)
		(width 0.254)
		(layer "In2.Cu")
		(net "PVCCFA_EHV_CPU0_BPWM1")
	)
	(segment
		(start 415.51098 -133.27634)
		(end 415.51098 -147.048728)
		(width 0.254)
		(layer "In2.Cu")
		(net "PVCCFA_EHV_CPU0_BPWM1")
	)
	(segment
		(start 423.164 -152.498552)
		(end 422.706038 -152.956514)
		(width 0.254)
		(layer "In2.Cu")
		(net "PVCCFA_EHV_CPU0_BPWM1")
	)
	(segment
		(start 423.164 -149.901148)
		(end 423.164 -152.498552)
		(width 0.254)
		(layer "In2.Cu")
		(net "PVCCFA_EHV_CPU0_BPWM1")
	)
	(segment
		(start 425.532296 -130.419348)
		(end 418.367972 -130.419348)
		(width 0.254)
		(layer "In2.Cu")
		(net "PVCCFA_EHV_CPU0_BPWM1")
	)
	(segment
		(start 421.831516 -154.898598)
		(end 421.351964 -154.419046)
		(width 0.254)
		(layer "F.Cu")
		(net "PVCCFA_EHV_CPU0_BCSP1")
	)
	(segment
		(start 421.351964 -154.419046)
		(end 420.905178 -154.419046)
		(width 0.254)
		(layer "F.Cu")
		(net "PVCCFA_EHV_CPU0_BCSP1")
	)
	(segment
		(start 423.904918 -139.33805)
		(end 423.904918 -138.814556)
		(width 0.1778)
		(layer "F.Cu")
		(net "PVCCFA_EHV_CPU0_BCSP1")
	)
	(segment
		(start 423.904918 -139.697968)
		(end 423.904918 -139.33805)
		(width 0.254)
		(layer "F.Cu")
		(net "PVCCFA_EHV_CPU0_BCSP1")
	)
	(via
		(at 421.831516 -154.898598)
		(size 0.508)
		(drill 0.254)
		(layers "F.Cu" "B.Cu")
		(net "PVCCFA_EHV_CPU0_BCSP1")
	)
	(via
		(at 423.904918 -139.697968)
		(size 0.508)
		(drill 0.254)
		(layers "F.Cu" "B.Cu")
		(net "PVCCFA_EHV_CPU0_BCSP1")
	)
	(segment
		(start 422.839388 -145.964148)
		(end 425.201588 -145.964148)
		(width 0.254)
		(layer "In4.Cu")
		(net "PVCCFA_EHV_CPU0_BCSP1")
	)
	(segment
		(start 423.904918 -139.697968)
		(end 423.803318 -139.799568)
		(width 0.254)
		(layer "In4.Cu")
		(net "PVCCFA_EHV_CPU0_BCSP1")
	)
	(segment
		(start 421.640508 -140.15212)
		(end 421.640508 -144.765268)
		(width 0.254)
		(layer "In4.Cu")
		(net "PVCCFA_EHV_CPU0_BCSP1")
	)
	(segment
		(start 425.201588 -145.964148)
		(end 426.8216 -147.58416)
		(width 0.254)
		(layer "In4.Cu")
		(net "PVCCFA_EHV_CPU0_BCSP1")
	)
	(segment
		(start 426.8216 -147.58416)
		(end 426.8216 -153.667968)
		(width 0.254)
		(layer "In4.Cu")
		(net "PVCCFA_EHV_CPU0_BCSP1")
	)
	(segment
		(start 422.99636 -155.407868)
		(end 422.102026 -155.407868)
		(width 0.254)
		(layer "In4.Cu")
		(net "PVCCFA_EHV_CPU0_BCSP1")
	)
	(segment
		(start 423.803318 -139.799568)
		(end 421.99306 -139.799568)
		(width 0.254)
		(layer "In4.Cu")
		(net "PVCCFA_EHV_CPU0_BCSP1")
	)
	(segment
		(start 425.44619 -155.043378)
		(end 423.36085 -155.043378)
		(width 0.254)
		(layer "In4.Cu")
		(net "PVCCFA_EHV_CPU0_BCSP1")
	)
	(segment
		(start 426.8216 -153.667968)
		(end 425.44619 -155.043378)
		(width 0.254)
		(layer "In4.Cu")
		(net "PVCCFA_EHV_CPU0_BCSP1")
	)
	(segment
		(start 421.640508 -144.765268)
		(end 422.839388 -145.964148)
		(width 0.254)
		(layer "In4.Cu")
		(net "PVCCFA_EHV_CPU0_BCSP1")
	)
	(segment
		(start 421.831516 -155.137358)
		(end 421.831516 -154.898598)
		(width 0.254)
		(layer "In4.Cu")
		(net "PVCCFA_EHV_CPU0_BCSP1")
	)
	(segment
		(start 423.36085 -155.043378)
		(end 422.99636 -155.407868)
		(width 0.254)
		(layer "In4.Cu")
		(net "PVCCFA_EHV_CPU0_BCSP1")
	)
	(segment
		(start 422.102026 -155.407868)
		(end 421.831516 -155.137358)
		(width 0.254)
		(layer "In4.Cu")
		(net "PVCCFA_EHV_CPU0_BCSP1")
	)
	(segment
		(start 421.99306 -139.799568)
		(end 421.640508 -140.15212)
		(width 0.254)
		(layer "In4.Cu")
		(net "PVCCFA_EHV_CPU0_BCSP1")
	)
	(segment
		(start 344.073734 -215.972644)
		(end 344.073734 -215.437212)
		(width 0.254)
		(layer "F.Cu")
		(net "PVCCFA_EHV_CPU0")
	)
	(segment
		(start 342.194134 -215.437212)
		(end 342.19388 -215.436958)
		(width 0.254)
		(layer "F.Cu")
		(net "PVCCFA_EHV_CPU0")
	)
	(segment
		(start 350.762316 -264.500106)
		(end 350.762062 -264.50036)
		(width 0.254)
		(layer "F.Cu")
		(net "PVCCFA_EHV_CPU0")
	)
	(segment
		(start 350.292162 -265.313922)
		(end 350.292416 -265.314176)
		(width 0.254)
		(layer "F.Cu")
		(net "PVCCFA_EHV_CPU0")
	)
	(segment
		(start 338.434934 -215.437212)
		(end 338.43468 -215.436958)
		(width 0.254)
		(layer "F.Cu")
		(net "PVCCFA_EHV_CPU0")
	)
	(segment
		(start 399.617692 -153.279856)
		(end 400.558 -152.339548)
		(width 0.508)
		(layer "F.Cu")
		(net "PVCCFA_EHV_CPU0")
	)
	(segment
		(start 344.07348 -215.436958)
		(end 344.07348 -215.436704)
		(width 0.254)
		(layer "F.Cu")
		(net "PVCCFA_EHV_CPU0")
	)
	(segment
		(start 349.822516 -263.96442)
		(end 349.822516 -264.500106)
		(width 0.254)
		(layer "F.Cu")
		(net "PVCCFA_EHV_CPU0")
	)
	(segment
		(start 349.352362 -264.778236)
		(end 349.352362 -265.313922)
		(width 0.254)
		(layer "F.Cu")
		(net "PVCCFA_EHV_CPU0")
	)
	(segment
		(start 349.822516 -264.500106)
		(end 349.822262 -264.50036)
		(width 0.254)
		(layer "F.Cu")
		(net "PVCCFA_EHV_CPU0")
	)
	(segment
		(start 345.953334 -215.972644)
		(end 345.953334 -215.437212)
		(width 0.254)
		(layer "F.Cu")
		(net "PVCCFA_EHV_CPU0")
	)
	(segment
		(start 347.83268 -215.436958)
		(end 347.83268 -215.436704)
		(width 0.2032)
		(layer "F.Cu")
		(net "PVCCFA_EHV_CPU0")
	)
	(segment
		(start 400.558 -152.339548)
		(end 401.498308 -153.279856)
		(width 0.508)
		(layer "F.Cu")
		(net "PVCCFA_EHV_CPU0")
	)
	(segment
		(start 340.314534 -215.437212)
		(end 340.31428 -215.436958)
		(width 0.254)
		(layer "F.Cu")
		(net "PVCCFA_EHV_CPU0")
	)
	(segment
		(start 349.352362 -265.313922)
		(end 349.352616 -265.314176)
		(width 0.254)
		(layer "F.Cu")
		(net "PVCCFA_EHV_CPU0")
	)
	(segment
		(start 342.19388 -215.436958)
		(end 342.19388 -215.436704)
		(width 0.254)
		(layer "F.Cu")
		(net "PVCCFA_EHV_CPU0")
	)
	(segment
		(start 400.558 -152.339548)
		(end 401.498308 -151.39924)
		(width 0.508)
		(layer "F.Cu")
		(net "PVCCFA_EHV_CPU0")
	)
	(segment
		(start 399.617692 -151.39924)
		(end 400.558 -152.339548)
		(width 0.508)
		(layer "F.Cu")
		(net "PVCCFA_EHV_CPU0")
	)
	(segment
		(start 344.073734 -215.437212)
		(end 344.07348 -215.436958)
		(width 0.254)
		(layer "F.Cu")
		(net "PVCCFA_EHV_CPU0")
	)
	(segment
		(start 340.31428 -215.436958)
		(end 340.31428 -215.436704)
		(width 0.254)
		(layer "F.Cu")
		(net "PVCCFA_EHV_CPU0")
	)
	(segment
		(start 350.762316 -263.96442)
		(end 350.762316 -264.500106)
		(width 0.254)
		(layer "F.Cu")
		(net "PVCCFA_EHV_CPU0")
	)
	(segment
		(start 347.832934 -215.972644)
		(end 347.832934 -215.437212)
		(width 0.2032)
		(layer "F.Cu")
		(net "PVCCFA_EHV_CPU0")
	)
	(segment
		(start 340.314534 -215.972644)
		(end 340.314534 -215.437212)
		(width 0.254)
		(layer "F.Cu")
		(net "PVCCFA_EHV_CPU0")
	)
	(segment
		(start 345.953334 -215.437212)
		(end 345.95308 -215.436958)
		(width 0.254)
		(layer "F.Cu")
		(net "PVCCFA_EHV_CPU0")
	)
	(segment
		(start 345.95308 -215.436958)
		(end 345.95308 -215.436704)
		(width 0.254)
		(layer "F.Cu")
		(net "PVCCFA_EHV_CPU0")
	)
	(segment
		(start 350.292162 -264.778236)
		(end 350.292162 -265.313922)
		(width 0.254)
		(layer "F.Cu")
		(net "PVCCFA_EHV_CPU0")
	)
	(segment
		(start 338.43468 -215.436958)
		(end 338.43468 -215.436704)
		(width 0.254)
		(layer "F.Cu")
		(net "PVCCFA_EHV_CPU0")
	)
	(segment
		(start 338.434934 -215.972644)
		(end 338.434934 -215.437212)
		(width 0.254)
		(layer "F.Cu")
		(net "PVCCFA_EHV_CPU0")
	)
	(segment
		(start 347.832934 -215.437212)
		(end 347.83268 -215.436958)
		(width 0.2032)
		(layer "F.Cu")
		(net "PVCCFA_EHV_CPU0")
	)
	(segment
		(start 342.194134 -215.972644)
		(end 342.194134 -215.437212)
		(width 0.254)
		(layer "F.Cu")
		(net "PVCCFA_EHV_CPU0")
	)
	(via
		(at 407.52522 -156.261054)
		(size 0.508)
		(drill 0.254)
		(layers "F.Cu" "B.Cu")
		(net "PVCCFA_EHV_CPU0")
	)
	(via
		(at 340.31428 -215.436704)
		(size 0.4572)
		(drill 0.2032)
		(layers "F.Cu" "B.Cu")
		(net "PVCCFA_EHV_CPU0")
	)
	(via
		(at 402.088096 -155.24607)
		(size 0.508)
		(drill 0.254)
		(layers "F.Cu" "B.Cu")
		(net "PVCCFA_EHV_CPU0")
	)
	(via
		(at 404.069296 -155.24607)
		(size 0.508)
		(drill 0.254)
		(layers "F.Cu" "B.Cu")
		(net "PVCCFA_EHV_CPU0")
	)
	(via
		(at 402.103336 -154.59837)
		(size 0.508)
		(drill 0.254)
		(layers "F.Cu" "B.Cu")
		(net "PVCCFA_EHV_CPU0")
	)
	(via
		(at 404.744936 -151.793702)
		(size 0.508)
		(drill 0.254)
		(layers "F.Cu" "B.Cu")
		(net "PVCCFA_EHV_CPU0")
	)
	(via
		(at 404.752556 -150.508462)
		(size 0.508)
		(drill 0.254)
		(layers "F.Cu" "B.Cu")
		(net "PVCCFA_EHV_CPU0")
	)
	(via
		(at 349.352616 -265.314176)
		(size 0.4572)
		(drill 0.2032)
		(layers "F.Cu" "B.Cu")
		(net "PVCCFA_EHV_CPU0")
	)
	(via
		(at 347.801438 -204.98435)
		(size 0.6604)
		(drill 0.3302)
		(layers "F.Cu" "B.Cu")
		(net "PVCCFA_EHV_CPU0")
	)
	(via
		(at 404.744936 -154.59837)
		(size 0.508)
		(drill 0.254)
		(layers "F.Cu" "B.Cu")
		(net "PVCCFA_EHV_CPU0")
	)
	(via
		(at 408.2288 -148.326348)
		(size 0.508)
		(drill 0.254)
		(layers "F.Cu" "B.Cu")
		(net "PVCCFA_EHV_CPU0")
	)
	(via
		(at 402.763736 -151.793702)
		(size 0.508)
		(drill 0.254)
		(layers "F.Cu" "B.Cu")
		(net "PVCCFA_EHV_CPU0")
	)
	(via
		(at 351.923604 -257.692906)
		(size 0.4572)
		(drill 0.2032)
		(layers "F.Cu" "B.Cu")
		(net "PVCCFA_EHV_CPU0")
	)
	(via
		(at 402.748496 -155.24607)
		(size 0.508)
		(drill 0.254)
		(layers "F.Cu" "B.Cu")
		(net "PVCCFA_EHV_CPU0")
	)
	(via
		(at 349.477838 -206.66075)
		(size 0.6604)
		(drill 0.3302)
		(layers "F.Cu" "B.Cu")
		(net "PVCCFA_EHV_CPU0")
	)
	(via
		(at 403.408896 -155.24607)
		(size 0.508)
		(drill 0.254)
		(layers "F.Cu" "B.Cu")
		(net "PVCCFA_EHV_CPU0")
	)
	(via
		(at 402.756116 -155.88361)
		(size 0.508)
		(drill 0.254)
		(layers "F.Cu" "B.Cu")
		(net "PVCCFA_EHV_CPU0")
	)
	(via
		(at 403.424136 -154.59837)
		(size 0.508)
		(drill 0.254)
		(layers "F.Cu" "B.Cu")
		(net "PVCCFA_EHV_CPU0")
	)
	(via
		(at 352.830638 -206.66075)
		(size 0.6604)
		(drill 0.3302)
		(layers "F.Cu" "B.Cu")
		(net "PVCCFA_EHV_CPU0")
	)
	(via
		(at 403.416516 -151.156162)
		(size 0.508)
		(drill 0.254)
		(layers "F.Cu" "B.Cu")
		(net "PVCCFA_EHV_CPU0")
	)
	(via
		(at 402.756116 -151.156162)
		(size 0.508)
		(drill 0.254)
		(layers "F.Cu" "B.Cu")
		(net "PVCCFA_EHV_CPU0")
	)
	(via
		(at 404.084536 -154.59837)
		(size 0.508)
		(drill 0.254)
		(layers "F.Cu" "B.Cu")
		(net "PVCCFA_EHV_CPU0")
	)
	(via
		(at 338.43468 -215.436704)
		(size 0.4572)
		(drill 0.2032)
		(layers "F.Cu" "B.Cu")
		(net "PVCCFA_EHV_CPU0")
	)
	(via
		(at 344.07348 -215.436704)
		(size 0.4572)
		(drill 0.2032)
		(layers "F.Cu" "B.Cu")
		(net "PVCCFA_EHV_CPU0")
	)
	(via
		(at 402.095716 -155.88361)
		(size 0.508)
		(drill 0.254)
		(layers "F.Cu" "B.Cu")
		(net "PVCCFA_EHV_CPU0")
	)
	(via
		(at 406.86482 -156.261054)
		(size 0.508)
		(drill 0.254)
		(layers "F.Cu" "B.Cu")
		(net "PVCCFA_EHV_CPU0")
	)
	(via
		(at 402.095716 -151.156162)
		(size 0.508)
		(drill 0.254)
		(layers "F.Cu" "B.Cu")
		(net "PVCCFA_EHV_CPU0")
	)
	(via
		(at 349.822262 -264.50036)
		(size 0.4572)
		(drill 0.2032)
		(layers "F.Cu" "B.Cu")
		(net "PVCCFA_EHV_CPU0")
	)
	(via
		(at 350.292416 -265.314176)
		(size 0.4572)
		(drill 0.2032)
		(layers "F.Cu" "B.Cu")
		(net "PVCCFA_EHV_CPU0")
	)
	(via
		(at 342.19388 -215.436704)
		(size 0.4572)
		(drill 0.2032)
		(layers "F.Cu" "B.Cu")
		(net "PVCCFA_EHV_CPU0")
	)
	(via
		(at 402.103336 -151.793702)
		(size 0.508)
		(drill 0.254)
		(layers "F.Cu" "B.Cu")
		(net "PVCCFA_EHV_CPU0")
	)
	(via
		(at 350.762062 -264.50036)
		(size 0.4572)
		(drill 0.2032)
		(layers "F.Cu" "B.Cu")
		(net "PVCCFA_EHV_CPU0")
	)
	(via
		(at 404.737316 -151.156162)
		(size 0.508)
		(drill 0.254)
		(layers "F.Cu" "B.Cu")
		(net "PVCCFA_EHV_CPU0")
	)
	(via
		(at 347.83268 -215.436704)
		(size 0.4572)
		(drill 0.2032)
		(layers "F.Cu" "B.Cu")
		(net "PVCCFA_EHV_CPU0")
	)
	(via
		(at 352.507804 -257.692906)
		(size 0.4572)
		(drill 0.2032)
		(layers "F.Cu" "B.Cu")
		(net "PVCCFA_EHV_CPU0")
	)
	(via
		(at 403.431756 -150.508462)
		(size 0.508)
		(drill 0.254)
		(layers "F.Cu" "B.Cu")
		(net "PVCCFA_EHV_CPU0")
	)
	(via
		(at 345.95308 -215.436704)
		(size 0.4572)
		(drill 0.2032)
		(layers "F.Cu" "B.Cu")
		(net "PVCCFA_EHV_CPU0")
	)
	(via
		(at 406.86482 -150.03399)
		(size 0.508)
		(drill 0.254)
		(layers "F.Cu" "B.Cu")
		(net "PVCCFA_EHV_CPU0")
	)
	(via
		(at 402.771356 -150.508462)
		(size 0.508)
		(drill 0.254)
		(layers "F.Cu" "B.Cu")
		(net "PVCCFA_EHV_CPU0")
	)
	(via
		(at 404.737316 -155.88361)
		(size 0.508)
		(drill 0.254)
		(layers "F.Cu" "B.Cu")
		(net "PVCCFA_EHV_CPU0")
	)
	(via
		(at 402.110956 -150.508462)
		(size 0.508)
		(drill 0.254)
		(layers "F.Cu" "B.Cu")
		(net "PVCCFA_EHV_CPU0")
	)
	(via
		(at 402.763736 -154.59837)
		(size 0.508)
		(drill 0.254)
		(layers "F.Cu" "B.Cu")
		(net "PVCCFA_EHV_CPU0")
	)
	(via
		(at 404.076916 -151.156162)
		(size 0.508)
		(drill 0.254)
		(layers "F.Cu" "B.Cu")
		(net "PVCCFA_EHV_CPU0")
	)
	(via
		(at 407.52522 -150.03399)
		(size 0.508)
		(drill 0.254)
		(layers "F.Cu" "B.Cu")
		(net "PVCCFA_EHV_CPU0")
	)
	(via
		(at 404.076916 -155.88361)
		(size 0.508)
		(drill 0.254)
		(layers "F.Cu" "B.Cu")
		(net "PVCCFA_EHV_CPU0")
	)
	(via
		(at 403.424136 -151.793702)
		(size 0.508)
		(drill 0.254)
		(layers "F.Cu" "B.Cu")
		(net "PVCCFA_EHV_CPU0")
	)
	(via
		(at 351.339404 -257.692906)
		(size 0.4572)
		(drill 0.2032)
		(layers "F.Cu" "B.Cu")
		(net "PVCCFA_EHV_CPU0")
	)
	(via
		(at 404.729696 -155.24607)
		(size 0.508)
		(drill 0.254)
		(layers "F.Cu" "B.Cu")
		(net "PVCCFA_EHV_CPU0")
	)
	(via
		(at 404.084536 -151.793702)
		(size 0.508)
		(drill 0.254)
		(layers "F.Cu" "B.Cu")
		(net "PVCCFA_EHV_CPU0")
	)
	(via
		(at 403.416516 -155.88361)
		(size 0.508)
		(drill 0.254)
		(layers "F.Cu" "B.Cu")
		(net "PVCCFA_EHV_CPU0")
	)
	(via
		(at 404.092156 -150.508462)
		(size 0.508)
		(drill 0.254)
		(layers "F.Cu" "B.Cu")
		(net "PVCCFA_EHV_CPU0")
	)
	(via
		(at 351.154238 -204.98435)
		(size 0.6604)
		(drill 0.3302)
		(layers "F.Cu" "B.Cu")
		(net "PVCCFA_EHV_CPU0")
	)
	(segment
		(start 400.558 -152.339548)
		(end 401.498308 -153.279856)
		(width 0.508)
		(layer "B.Cu")
		(net "PVCCFA_EHV_CPU0")
	)
	(segment
		(start 400.558 -152.339548)
		(end 401.498308 -151.39924)
		(width 0.508)
		(layer "B.Cu")
		(net "PVCCFA_EHV_CPU0")
	)
	(segment
		(start 399.617692 -151.39924)
		(end 400.558 -152.339548)
		(width 0.508)
		(layer "B.Cu")
		(net "PVCCFA_EHV_CPU0")
	)
	(segment
		(start 399.617692 -153.279856)
		(end 400.558 -152.339548)
		(width 0.508)
		(layer "B.Cu")
		(net "PVCCFA_EHV_CPU0")
	)
	(segment
		(start 400.558 -152.339548)
		(end 401.273772 -151.623776)
		(width 0.508)
		(layer "In13.Cu")
		(net "PVCCFA_EHV_CPU0")
	)
	(segment
		(start 400.558 -152.339548)
		(end 401.273772 -153.05532)
		(width 0.508)
		(layer "In13.Cu")
		(net "PVCCFA_EHV_CPU0")
	)
	(segment
		(start 399.842228 -153.05532)
		(end 400.558 -152.339548)
		(width 0.508)
		(layer "In13.Cu")
		(net "PVCCFA_EHV_CPU0")
	)
	(segment
		(start 399.842228 -151.623776)
		(end 400.558 -152.339548)
		(width 0.508)
		(layer "In13.Cu")
		(net "PVCCFA_EHV_CPU0")
	)
	(segment
		(start 50.377344 -163.136834)
		(end 50.717704 -162.796474)
		(width 0.254)
		(layer "F.Cu")
		(net "PVCCD_HV_CPU1_VREF")
	)
	(segment
		(start 33.46196 -162.586162)
		(end 32.337502 -162.586162)
		(width 0.254)
		(layer "F.Cu")
		(net "PVCCD_HV_CPU1_VREF")
	)
	(segment
		(start 51.05273 -162.280854)
		(end 50.717704 -162.280854)
		(width 0.254)
		(layer "F.Cu")
		(net "PVCCD_HV_CPU1_VREF")
	)
	(segment
		(start 51.895756 -163.12388)
		(end 51.05273 -162.280854)
		(width 0.254)
		(layer "F.Cu")
		(net "PVCCD_HV_CPU1_VREF")
	)
	(segment
		(start 50.717704 -162.796474)
		(end 50.717704 -162.280854)
		(width 0.254)
		(layer "F.Cu")
		(net "PVCCD_HV_CPU1_VREF")
	)
	(segment
		(start 51.999642 -163.12388)
		(end 51.895756 -163.12388)
		(width 0.254)
		(layer "F.Cu")
		(net "PVCCD_HV_CPU1_VREF")
	)
	(via
		(at 33.46196 -162.586162)
		(size 0.508)
		(drill 0.254)
		(layers "F.Cu" "B.Cu")
		(net "PVCCD_HV_CPU1_VREF")
	)
	(via
		(at 50.377344 -163.136834)
		(size 0.508)
		(drill 0.254)
		(layers "F.Cu" "B.Cu")
		(net "PVCCD_HV_CPU1_VREF")
	)
	(via
		(at 29.976826 -167.988234)
		(size 0.508)
		(drill 0.254)
		(layers "F.Cu" "B.Cu")
		(net "PVCCD_HV_CPU1_VREF")
	)
	(segment
		(start 34.855404 -163.590224)
		(end 35.5981 -164.33292)
		(width 0.254)
		(layer "In6.Cu")
		(net "PVCCD_HV_CPU1_VREF")
	)
	(segment
		(start 49.433988 -163.540948)
		(end 49.838102 -163.136834)
		(width 0.254)
		(layer "In6.Cu")
		(net "PVCCD_HV_CPU1_VREF")
	)
	(segment
		(start 42.829988 -160.492948)
		(end 45.181012 -160.492948)
		(width 0.254)
		(layer "In6.Cu")
		(net "PVCCD_HV_CPU1_VREF")
	)
	(segment
		(start 49.838102 -163.136834)
		(end 50.377344 -163.136834)
		(width 0.254)
		(layer "In6.Cu")
		(net "PVCCD_HV_CPU1_VREF")
	)
	(segment
		(start 33.952942 -162.09518)
		(end 34.395156 -162.09518)
		(width 0.254)
		(layer "In6.Cu")
		(net "PVCCD_HV_CPU1_VREF")
	)
	(segment
		(start 45.181012 -160.492948)
		(end 48.229012 -163.540948)
		(width 0.254)
		(layer "In6.Cu")
		(net "PVCCD_HV_CPU1_VREF")
	)
	(segment
		(start 35.5981 -164.33292)
		(end 38.990016 -164.33292)
		(width 0.254)
		(layer "In6.Cu")
		(net "PVCCD_HV_CPU1_VREF")
	)
	(segment
		(start 34.855404 -162.555428)
		(end 34.855404 -163.590224)
		(width 0.254)
		(layer "In6.Cu")
		(net "PVCCD_HV_CPU1_VREF")
	)
	(segment
		(start 38.990016 -164.33292)
		(end 42.829988 -160.492948)
		(width 0.254)
		(layer "In6.Cu")
		(net "PVCCD_HV_CPU1_VREF")
	)
	(segment
		(start 34.395156 -162.09518)
		(end 34.855404 -162.555428)
		(width 0.254)
		(layer "In6.Cu")
		(net "PVCCD_HV_CPU1_VREF")
	)
	(segment
		(start 33.46196 -162.586162)
		(end 33.952942 -162.09518)
		(width 0.254)
		(layer "In6.Cu")
		(net "PVCCD_HV_CPU1_VREF")
	)
	(segment
		(start 48.229012 -163.540948)
		(end 49.433988 -163.540948)
		(width 0.254)
		(layer "In6.Cu")
		(net "PVCCD_HV_CPU1_VREF")
	)
	(segment
		(start 53.524658 -162.713924)
		(end 53.524658 -162.325812)
		(width 0.2032)
		(layer "F.Cu")
		(net "PVCCD_HV_CPU1_VDD1")
	)
	(segment
		(start 53.524658 -162.325812)
		(end 52.823364 -161.624518)
		(width 0.2032)
		(layer "F.Cu")
		(net "PVCCD_HV_CPU1_VDD1")
	)
	(segment
		(start 53.439314 -161.539174)
		(end 52.823364 -161.539174)
		(width 0.2286)
		(layer "F.Cu")
		(net "PVCCD_HV_CPU1_VDD1")
	)
	(segment
		(start 52.823364 -161.624518)
		(end 52.823364 -161.539174)
		(width 0.2032)
		(layer "F.Cu")
		(net "PVCCD_HV_CPU1_VDD1")
	)
	(segment
		(start 51.28768 -164.923978)
		(end 51.211988 -164.848286)
		(width 0.2286)
		(layer "F.Cu")
		(net "PVCCD_HV_CPU1_VDD1")
	)
	(segment
		(start 51.999642 -164.923978)
		(end 51.28768 -164.923978)
		(width 0.2286)
		(layer "F.Cu")
		(net "PVCCD_HV_CPU1_VDD1")
	)
	(via
		(at 53.439314 -161.539174)
		(size 0.508)
		(drill 0.254)
		(layers "F.Cu" "B.Cu")
		(net "PVCCD_HV_CPU1_VDD1")
	)
	(via
		(at 52.133754 -163.314126)
		(size 0.6604)
		(drill 0.3302)
		(layers "F.Cu" "B.Cu")
		(net "PVCCD_HV_CPU1_VDD1")
	)
	(via
		(at 51.211988 -164.848286)
		(size 0.508)
		(drill 0.254)
		(layers "F.Cu" "B.Cu")
		(net "PVCCD_HV_CPU1_VDD1")
	)
	(segment
		(start 53.512466 -161.612326)
		(end 53.512466 -162.717226)
		(width 0.254)
		(layer "B.Cu")
		(net "PVCCD_HV_CPU1_VDD1")
	)
	(segment
		(start 51.211988 -164.848286)
		(end 51.830224 -164.23005)
		(width 0.254)
		(layer "B.Cu")
		(net "PVCCD_HV_CPU1_VDD1")
	)
	(segment
		(start 51.830224 -164.23005)
		(end 51.830224 -163.617656)
		(width 0.254)
		(layer "B.Cu")
		(net "PVCCD_HV_CPU1_VDD1")
	)
	(segment
		(start 51.830224 -163.617656)
		(end 52.133754 -163.314126)
		(width 0.254)
		(layer "B.Cu")
		(net "PVCCD_HV_CPU1_VDD1")
	)
	(segment
		(start 52.513484 -162.934396)
		(end 53.295296 -162.934396)
		(width 0.254)
		(layer "B.Cu")
		(net "PVCCD_HV_CPU1_VDD1")
	)
	(segment
		(start 53.295296 -162.934396)
		(end 53.512466 -162.717226)
		(width 0.254)
		(layer "B.Cu")
		(net "PVCCD_HV_CPU1_VDD1")
	)
	(segment
		(start 53.439314 -161.539174)
		(end 53.512466 -161.612326)
		(width 0.254)
		(layer "B.Cu")
		(net "PVCCD_HV_CPU1_VDD1")
	)
	(segment
		(start 52.133754 -163.314126)
		(end 52.513484 -162.934396)
		(width 0.254)
		(layer "B.Cu")
		(net "PVCCD_HV_CPU1_VDD1")
	)
	(segment
		(start 30.375352 -166.227252)
		(end 30.062932 -166.227252)
		(width 0.1778)
		(layer "F.Cu")
		(net "PVCCD_HV_CPU1_VCC")
	)
	(segment
		(start 31.140146 -168.02481)
		(end 31.01848 -167.903144)
		(width 0.1778)
		(layer "F.Cu")
		(net "PVCCD_HV_CPU1_VCC")
	)
	(segment
		(start 31.140146 -170.021504)
		(end 31.13405 -170.0276)
		(width 0.4572)
		(layer "F.Cu")
		(net "PVCCD_HV_CPU1_VCC")
	)
	(segment
		(start 31.140146 -169.04081)
		(end 31.140146 -170.021504)
		(width 0.4572)
		(layer "F.Cu")
		(net "PVCCD_HV_CPU1_VCC")
	)
	(segment
		(start 31.13405 -170.0276)
		(end 31.13405 -170.67022)
		(width 0.4572)
		(layer "F.Cu")
		(net "PVCCD_HV_CPU1_VCC")
	)
	(segment
		(start 30.62859 -166.48049)
		(end 30.375352 -166.227252)
		(width 0.1778)
		(layer "F.Cu")
		(net "PVCCD_HV_CPU1_VCC")
	)
	(segment
		(start 31.01848 -167.903144)
		(end 31.01848 -167.421814)
		(width 0.1778)
		(layer "F.Cu")
		(net "PVCCD_HV_CPU1_VCC")
	)
	(segment
		(start 31.140146 -169.04081)
		(end 31.140146 -168.02481)
		(width 0.4572)
		(layer "F.Cu")
		(net "PVCCD_HV_CPU1_VCC")
	)
	(segment
		(start 31.01848 -167.421814)
		(end 30.62859 -166.48049)
		(width 0.1778)
		(layer "F.Cu")
		(net "PVCCD_HV_CPU1_VCC")
	)
	(via
		(at 31.13405 -170.67022)
		(size 0.508)
		(drill 0.254)
		(layers "F.Cu" "B.Cu")
		(net "PVCCD_HV_CPU1_VCC")
	)
	(segment
		(start 31.13405 -170.67022)
		(end 30.996382 -170.532552)
		(width 0.4572)
		(layer "B.Cu")
		(net "PVCCD_HV_CPU1_VCC")
	)
	(segment
		(start 30.996382 -170.532552)
		(end 30.996382 -169.5958)
		(width 0.4572)
		(layer "B.Cu")
		(net "PVCCD_HV_CPU1_VCC")
	)
	(segment
		(start 24.689054 -164.937948)
		(end 24.02586 -164.937948)
		(width 0.1778)
		(layer "F.Cu")
		(net "PVCCD_HV_CPU1_PIN_ALT")
	)
	(segment
		(start 23.9395 -165.024308)
		(end 23.241 -165.722808)
		(width 0.1778)
		(layer "F.Cu")
		(net "PVCCD_HV_CPU1_PIN_ALT")
	)
	(segment
		(start 25.26284 -165.027102)
		(end 24.778208 -165.027102)
		(width 0.1778)
		(layer "F.Cu")
		(net "PVCCD_HV_CPU1_PIN_ALT")
	)
	(segment
		(start 24.02586 -164.937948)
		(end 23.9395 -165.024308)
		(width 0.1778)
		(layer "F.Cu")
		(net "PVCCD_HV_CPU1_PIN_ALT")
	)
	(segment
		(start 23.241 -166.513002)
		(end 22.986746 -166.767256)
		(width 0.1778)
		(layer "F.Cu")
		(net "PVCCD_HV_CPU1_PIN_ALT")
	)
	(segment
		(start 23.241 -165.722808)
		(end 23.241 -166.513002)
		(width 0.1778)
		(layer "F.Cu")
		(net "PVCCD_HV_CPU1_PIN_ALT")
	)
	(segment
		(start 22.986746 -166.767256)
		(end 22.53361 -166.767256)
		(width 0.1778)
		(layer "F.Cu")
		(net "PVCCD_HV_CPU1_PIN_ALT")
	)
	(segment
		(start 24.778208 -165.027102)
		(end 24.689054 -164.937948)
		(width 0.1778)
		(layer "F.Cu")
		(net "PVCCD_HV_CPU1_PIN_ALT")
	)
	(via
		(at 23.9395 -165.024308)
		(size 0.762)
		(drill 0.381)
		(layers "F.Cu" "B.Cu")
		(net "PVCCD_HV_CPU1_PIN_ALT")
	)
	(segment
		(start 14.421358 -333.79791)
		(end 14.421358 -334.538066)
		(width 0.254)
		(layer "F.Cu")
		(net "PVCCD_HV_CPU1_NVDIMM_ISENSE")
	)
	(segment
		(start 14.804644 -334.921352)
		(end 15.055088 -334.921352)
		(width 0.254)
		(layer "F.Cu")
		(net "PVCCD_HV_CPU1_NVDIMM_ISENSE")
	)
	(segment
		(start 14.421358 -334.538066)
		(end 14.804644 -334.921352)
		(width 0.254)
		(layer "F.Cu")
		(net "PVCCD_HV_CPU1_NVDIMM_ISENSE")
	)
	(via
		(at 14.421358 -333.79791)
		(size 0.508)
		(drill 0.254)
		(layers "F.Cu" "B.Cu")
		(net "PVCCD_HV_CPU1_NVDIMM_ISENSE")
	)
	(via
		(at 33.4264 -164.302694)
		(size 0.508)
		(drill 0.254)
		(layers "F.Cu" "B.Cu")
		(net "PVCCD_HV_CPU1_NVDIMM_ISENSE")
	)
	(segment
		(start 33.4264 -164.302694)
		(end 32.312356 -164.302694)
		(width 0.254)
		(layer "B.Cu")
		(net "PVCCD_HV_CPU1_NVDIMM_ISENSE")
	)
	(segment
		(start 32.312356 -164.302694)
		(end 32.30245 -164.292788)
		(width 0.254)
		(layer "B.Cu")
		(net "PVCCD_HV_CPU1_NVDIMM_ISENSE")
	)
	(segment
		(start 33.9471 -164.302694)
		(end 33.4264 -164.302694)
		(width 0.254)
		(layer "In15.Cu")
		(net "PVCCD_HV_CPU1_NVDIMM_ISENSE")
	)
	(segment
		(start 34.417 -164.772594)
		(end 33.9471 -164.302694)
		(width 0.254)
		(layer "In15.Cu")
		(net "PVCCD_HV_CPU1_NVDIMM_ISENSE")
	)
	(segment
		(start 34.417 -169.479214)
		(end 34.417 -164.772594)
		(width 0.254)
		(layer "In15.Cu")
		(net "PVCCD_HV_CPU1_NVDIMM_ISENSE")
	)
	(segment
		(start 6.056376 -193.586862)
		(end 6.056376 -192.291462)
		(width 0.254)
		(layer "In15.Cu")
		(net "PVCCD_HV_CPU1_NVDIMM_ISENSE")
	)
	(segment
		(start 32.176466 -171.719748)
		(end 34.417 -169.479214)
		(width 0.254)
		(layer "In15.Cu")
		(net "PVCCD_HV_CPU1_NVDIMM_ISENSE")
	)
	(segment
		(start 4.84632 -186.034934)
		(end 19.161506 -171.719748)
		(width 0.254)
		(layer "In15.Cu")
		(net "PVCCD_HV_CPU1_NVDIMM_ISENSE")
	)
	(segment
		(start 4.84632 -329.418188)
		(end 4.84632 -194.796918)
		(width 0.254)
		(layer "In15.Cu")
		(net "PVCCD_HV_CPU1_NVDIMM_ISENSE")
	)
	(segment
		(start 14.421358 -333.79791)
		(end 9.226042 -333.79791)
		(width 0.254)
		(layer "In15.Cu")
		(net "PVCCD_HV_CPU1_NVDIMM_ISENSE")
	)
	(segment
		(start 4.84632 -191.081406)
		(end 4.84632 -186.034934)
		(width 0.254)
		(layer "In15.Cu")
		(net "PVCCD_HV_CPU1_NVDIMM_ISENSE")
	)
	(segment
		(start 9.226042 -333.79791)
		(end 4.84632 -329.418188)
		(width 0.254)
		(layer "In15.Cu")
		(net "PVCCD_HV_CPU1_NVDIMM_ISENSE")
	)
	(segment
		(start 19.161506 -171.719748)
		(end 32.176466 -171.719748)
		(width 0.254)
		(layer "In15.Cu")
		(net "PVCCD_HV_CPU1_NVDIMM_ISENSE")
	)
	(segment
		(start 4.84632 -194.796918)
		(end 6.056376 -193.586862)
		(width 0.254)
		(layer "In15.Cu")
		(net "PVCCD_HV_CPU1_NVDIMM_ISENSE")
	)
	(segment
		(start 6.056376 -192.291462)
		(end 4.84632 -191.081406)
		(width 0.254)
		(layer "In15.Cu")
		(net "PVCCD_HV_CPU1_NVDIMM_ISENSE")
	)
	(segment
		(start 51.222148 -163.651438)
		(end 49.984406 -163.651438)
		(width 0.12954)
		(layer "F.Cu")
		(net "PVCCD_HV_CPU1_LSET1")
	)
	(segment
		(start 51.999642 -164.024056)
		(end 51.675792 -164.024056)
		(width 0.12954)
		(layer "F.Cu")
		(net "PVCCD_HV_CPU1_LSET1")
	)
	(segment
		(start 49.984406 -163.651438)
		(end 49.755552 -163.422584)
		(width 0.12954)
		(layer "F.Cu")
		(net "PVCCD_HV_CPU1_LSET1")
	)
	(segment
		(start 51.675792 -164.024056)
		(end 51.537362 -163.966652)
		(width 0.12954)
		(layer "F.Cu")
		(net "PVCCD_HV_CPU1_LSET1")
	)
	(segment
		(start 51.537362 -163.966652)
		(end 51.222148 -163.651438)
		(width 0.12954)
		(layer "F.Cu")
		(net "PVCCD_HV_CPU1_LSET1")
	)
	(segment
		(start 31.60522 -164.990526)
		(end 31.605474 -164.99078)
		(width 0.1778)
		(layer "F.Cu")
		(net "PVCCD_HV_CPU1_ISYS_R")
	)
	(segment
		(start 31.603188 -164.990526)
		(end 31.60522 -164.990526)
		(width 0.1778)
		(layer "F.Cu")
		(net "PVCCD_HV_CPU1_ISYS_R")
	)
	(segment
		(start 30.062932 -165.027102)
		(end 31.566612 -165.027102)
		(width 0.1778)
		(layer "F.Cu")
		(net "PVCCD_HV_CPU1_ISYS_R")
	)
	(segment
		(start 31.566612 -165.027102)
		(end 31.603188 -164.990526)
		(width 0.1778)
		(layer "F.Cu")
		(net "PVCCD_HV_CPU1_ISYS_R")
	)
	(via
		(at 31.605474 -164.99078)
		(size 0.508)
		(drill 0.254)
		(layers "F.Cu" "B.Cu")
		(net "PVCCD_HV_CPU1_ISYS_R")
	)
	(segment
		(start 31.605474 -164.395912)
		(end 31.50235 -164.292788)
		(width 0.254)
		(layer "B.Cu")
		(net "PVCCD_HV_CPU1_ISYS_R")
	)
	(segment
		(start 31.605474 -164.990526)
		(end 31.605474 -164.395912)
		(width 0.254)
		(layer "B.Cu")
		(net "PVCCD_HV_CPU1_ISYS_R")
	)
	(segment
		(start 31.601664 -164.986716)
		(end 30.243526 -164.423852)
		(width 0.254)
		(layer "B.Cu")
		(net "PVCCD_HV_CPU1_ISYS_R")
	)
	(segment
		(start 31.605474 -164.99078)
		(end 31.605474 -164.990526)
		(width 0.254)
		(layer "B.Cu")
		(net "PVCCD_HV_CPU1_ISYS_R")
	)
	(segment
		(start 31.605474 -164.990526)
		(end 31.601664 -164.986716)
		(width 0.254)
		(layer "B.Cu")
		(net "PVCCD_HV_CPU1_ISYS_R")
	)
	(segment
		(start 30.243526 -164.423852)
		(end 29.986732 -164.167058)
		(width 0.254)
		(layer "B.Cu")
		(net "PVCCD_HV_CPU1_ISYS_R")
	)
	(segment
		(start 31.583122 -165.761162)
		(end 31.791402 -165.761162)
		(width 0.254)
		(layer "F.Cu")
		(net "PVCCD_HV_CPU1_ISENSE_P")
	)
	(segment
		(start 30.895036 -165.427152)
		(end 31.05912 -165.591236)
		(width 0.1778)
		(layer "F.Cu")
		(net "PVCCD_HV_CPU1_ISENSE_P")
	)
	(segment
		(start 31.413196 -165.591236)
		(end 31.583122 -165.761162)
		(width 0.254)
		(layer "F.Cu")
		(net "PVCCD_HV_CPU1_ISENSE_P")
	)
	(segment
		(start 31.05912 -165.591236)
		(end 31.413196 -165.591236)
		(width 0.254)
		(layer "F.Cu")
		(net "PVCCD_HV_CPU1_ISENSE_P")
	)
	(segment
		(start 30.062932 -165.427152)
		(end 30.895036 -165.427152)
		(width 0.1778)
		(layer "F.Cu")
		(net "PVCCD_HV_CPU1_ISENSE_P")
	)
	(via
		(at 33.16478 -165.903148)
		(size 0.6604)
		(drill 0.3302)
		(layers "F.Cu" "B.Cu")
		(net "PVCCD_HV_CPU1_ISENSE_P")
	)
	(via
		(at 31.05912 -165.591236)
		(size 0.508)
		(drill 0.254)
		(layers "F.Cu" "B.Cu")
		(net "PVCCD_HV_CPU1_ISENSE_P")
	)
	(segment
		(start 29.977588 -165.540436)
		(end 30.028388 -165.591236)
		(width 0.254)
		(layer "B.Cu")
		(net "PVCCD_HV_CPU1_ISENSE_P")
	)
	(segment
		(start 34.082482 -166.205408)
		(end 34.446464 -165.841426)
		(width 0.254)
		(layer "B.Cu")
		(net "PVCCD_HV_CPU1_ISENSE_P")
	)
	(segment
		(start 30.028388 -165.591236)
		(end 31.05912 -165.591236)
		(width 0.254)
		(layer "B.Cu")
		(net "PVCCD_HV_CPU1_ISENSE_P")
	)
	(segment
		(start 31.94304 -165.85311)
		(end 32.423862 -165.85311)
		(width 0.254)
		(layer "B.Cu")
		(net "PVCCD_HV_CPU1_ISENSE_P")
	)
	(segment
		(start 31.05912 -165.591236)
		(end 31.681166 -165.591236)
		(width 0.254)
		(layer "B.Cu")
		(net "PVCCD_HV_CPU1_ISENSE_P")
	)
	(segment
		(start 33.46704 -166.205408)
		(end 34.082482 -166.205408)
		(width 0.254)
		(layer "B.Cu")
		(net "PVCCD_HV_CPU1_ISENSE_P")
	)
	(segment
		(start 31.681166 -165.591236)
		(end 31.94304 -165.85311)
		(width 0.254)
		(layer "B.Cu")
		(net "PVCCD_HV_CPU1_ISENSE_P")
	)
	(segment
		(start 32.4739 -165.903148)
		(end 33.16478 -165.903148)
		(width 0.254)
		(layer "B.Cu")
		(net "PVCCD_HV_CPU1_ISENSE_P")
	)
	(segment
		(start 32.423862 -165.85311)
		(end 32.4739 -165.903148)
		(width 0.254)
		(layer "B.Cu")
		(net "PVCCD_HV_CPU1_ISENSE_P")
	)
	(segment
		(start 33.16478 -165.903148)
		(end 33.46704 -166.205408)
		(width 0.254)
		(layer "B.Cu")
		(net "PVCCD_HV_CPU1_ISENSE_P")
	)
	(segment
		(start 31.791402 -166.777162)
		(end 31.565088 -166.777162)
		(width 0.1778)
		(layer "F.Cu")
		(net "PVCCD_HV_CPU1_ISENSE_N")
	)
	(segment
		(start 31.565088 -166.777162)
		(end 31.071566 -166.28364)
		(width 0.1778)
		(layer "F.Cu")
		(net "PVCCD_HV_CPU1_ISENSE_N")
	)
	(segment
		(start 31.071566 -166.28364)
		(end 30.808676 -166.02075)
		(width 0.1778)
		(layer "F.Cu")
		(net "PVCCD_HV_CPU1_ISENSE_N")
	)
	(segment
		(start 30.808676 -166.02075)
		(end 30.34157 -165.827202)
		(width 0.1778)
		(layer "F.Cu")
		(net "PVCCD_HV_CPU1_ISENSE_N")
	)
	(segment
		(start 30.34157 -165.827202)
		(end 30.062932 -165.827202)
		(width 0.1778)
		(layer "F.Cu")
		(net "PVCCD_HV_CPU1_ISENSE_N")
	)
	(via
		(at 31.071566 -166.28364)
		(size 0.508)
		(drill 0.254)
		(layers "F.Cu" "B.Cu")
		(net "PVCCD_HV_CPU1_ISENSE_N")
	)
	(via
		(at 33.15462 -167.175688)
		(size 0.6604)
		(drill 0.3302)
		(layers "F.Cu" "B.Cu")
		(net "PVCCD_HV_CPU1_ISENSE_N")
	)
	(segment
		(start 31.071566 -166.28364)
		(end 30.337506 -167.0177)
		(width 0.254)
		(layer "B.Cu")
		(net "PVCCD_HV_CPU1_ISENSE_N")
	)
	(segment
		(start 30.337506 -167.0177)
		(end 29.977588 -167.0177)
		(width 0.254)
		(layer "B.Cu")
		(net "PVCCD_HV_CPU1_ISENSE_N")
	)
	(segment
		(start 33.15462 -167.175688)
		(end 33.7439 -166.586408)
		(width 0.254)
		(layer "B.Cu")
		(net "PVCCD_HV_CPU1_ISENSE_N")
	)
	(segment
		(start 33.15462 -167.175688)
		(end 32.608774 -166.629842)
		(width 0.254)
		(layer "B.Cu")
		(net "PVCCD_HV_CPU1_ISENSE_N")
	)
	(segment
		(start 31.94304 -166.65321)
		(end 31.441136 -166.65321)
		(width 0.254)
		(layer "B.Cu")
		(net "PVCCD_HV_CPU1_ISENSE_N")
	)
	(segment
		(start 31.441136 -166.65321)
		(end 31.071566 -166.28364)
		(width 0.254)
		(layer "B.Cu")
		(net "PVCCD_HV_CPU1_ISENSE_N")
	)
	(segment
		(start 31.966408 -166.629842)
		(end 31.94304 -166.65321)
		(width 0.254)
		(layer "B.Cu")
		(net "PVCCD_HV_CPU1_ISENSE_N")
	)
	(segment
		(start 33.7439 -166.586408)
		(end 34.299398 -166.586408)
		(width 0.254)
		(layer "B.Cu")
		(net "PVCCD_HV_CPU1_ISENSE_N")
	)
	(segment
		(start 34.299398 -166.586408)
		(end 34.446464 -166.733474)
		(width 0.254)
		(layer "B.Cu")
		(net "PVCCD_HV_CPU1_ISENSE_N")
	)
	(segment
		(start 32.608774 -166.629842)
		(end 31.966408 -166.629842)
		(width 0.254)
		(layer "B.Cu")
		(net "PVCCD_HV_CPU1_ISENSE_N")
	)
	(segment
		(start 30.611572 -162.291776)
		(end 30.611572 -163.577778)
		(width 0.1778)
		(layer "F.Cu")
		(net "PVCCD_HV_CPU1_FAULT")
	)
	(segment
		(start 30.362144 -163.827206)
		(end 30.062932 -163.827206)
		(width 0.1778)
		(layer "F.Cu")
		(net "PVCCD_HV_CPU1_FAULT")
	)
	(segment
		(start 30.8356 -162.067748)
		(end 30.611572 -162.291776)
		(width 0.1778)
		(layer "F.Cu")
		(net "PVCCD_HV_CPU1_FAULT")
	)
	(segment
		(start 30.611572 -163.577778)
		(end 30.362144 -163.827206)
		(width 0.1778)
		(layer "F.Cu")
		(net "PVCCD_HV_CPU1_FAULT")
	)
	(via
		(at 30.8356 -162.067748)
		(size 0.508)
		(drill 0.254)
		(layers "F.Cu" "B.Cu")
		(net "PVCCD_HV_CPU1_FAULT")
	)
	(segment
		(start 30.8356 -162.067748)
		(end 31.764224 -162.996372)
		(width 0.254)
		(layer "B.Cu")
		(net "PVCCD_HV_CPU1_FAULT")
	)
	(segment
		(start 31.764224 -162.996372)
		(end 32.027368 -162.996372)
		(width 0.254)
		(layer "B.Cu")
		(net "PVCCD_HV_CPU1_FAULT")
	)
	(segment
		(start 24.31415 -166.25316)
		(end 24.740108 -165.827202)
		(width 0.12954)
		(layer "F.Cu")
		(net "PVCCD_HV_CPU1_EN_R")
	)
	(segment
		(start 24.740108 -165.827202)
		(end 25.26284 -165.827202)
		(width 0.12954)
		(layer "F.Cu")
		(net "PVCCD_HV_CPU1_EN_R")
	)
	(via
		(at 24.31415 -166.25316)
		(size 0.508)
		(drill 0.254)
		(layers "F.Cu" "B.Cu")
		(net "PVCCD_HV_CPU1_EN_R")
	)
	(segment
		(start 24.059642 -166.25316)
		(end 22.763988 -167.548814)
		(width 0.12954)
		(layer "B.Cu")
		(net "PVCCD_HV_CPU1_EN_R")
	)
	(segment
		(start 22.763988 -167.548814)
		(end 22.314662 -167.548814)
		(width 0.12954)
		(layer "B.Cu")
		(net "PVCCD_HV_CPU1_EN_R")
	)
	(segment
		(start 24.31415 -166.25316)
		(end 24.059642 -166.25316)
		(width 0.12954)
		(layer "B.Cu")
		(net "PVCCD_HV_CPU1_EN_R")
	)
	(segment
		(start 31.537402 -164.05606)
		(end 31.97606 -163.617402)
		(width 0.1778)
		(layer "F.Cu")
		(net "PVCCD_HV_CPU1_ATSEN")
	)
	(segment
		(start 32.523684 -163.617402)
		(end 32.665924 -163.475162)
		(width 0.254)
		(layer "F.Cu")
		(net "PVCCD_HV_CPU1_ATSEN")
	)
	(segment
		(start 51.704494 -164.47389)
		(end 50.96637 -164.168328)
		(width 0.254)
		(layer "F.Cu")
		(net "PVCCD_HV_CPU1_ATSEN")
	)
	(segment
		(start 30.062932 -164.627306)
		(end 30.328108 -164.627306)
		(width 0.1778)
		(layer "F.Cu")
		(net "PVCCD_HV_CPU1_ATSEN")
	)
	(segment
		(start 30.328108 -164.627306)
		(end 30.963362 -164.364162)
		(width 0.1778)
		(layer "F.Cu")
		(net "PVCCD_HV_CPU1_ATSEN")
	)
	(segment
		(start 50.96637 -164.168328)
		(end 50.966116 -164.168074)
		(width 0.254)
		(layer "F.Cu")
		(net "PVCCD_HV_CPU1_ATSEN")
	)
	(segment
		(start 31.97606 -163.617402)
		(end 32.523684 -163.617402)
		(width 0.254)
		(layer "F.Cu")
		(net "PVCCD_HV_CPU1_ATSEN")
	)
	(segment
		(start 30.963362 -164.364162)
		(end 31.537402 -164.364162)
		(width 0.1778)
		(layer "F.Cu")
		(net "PVCCD_HV_CPU1_ATSEN")
	)
	(segment
		(start 51.999642 -164.47389)
		(end 51.704494 -164.47389)
		(width 0.254)
		(layer "F.Cu")
		(net "PVCCD_HV_CPU1_ATSEN")
	)
	(segment
		(start 31.537402 -164.364162)
		(end 31.537402 -164.05606)
		(width 0.1778)
		(layer "F.Cu")
		(net "PVCCD_HV_CPU1_ATSEN")
	)
	(segment
		(start 50.966116 -164.168074)
		(end 50.966116 -164.152834)
		(width 0.254)
		(layer "F.Cu")
		(net "PVCCD_HV_CPU1_ATSEN")
	)
	(via
		(at 31.97606 -163.617402)
		(size 0.508)
		(drill 0.254)
		(layers "F.Cu" "B.Cu")
		(net "PVCCD_HV_CPU1_ATSEN")
	)
	(via
		(at 50.966116 -164.152834)
		(size 0.508)
		(drill 0.254)
		(layers "F.Cu" "B.Cu")
		(net "PVCCD_HV_CPU1_ATSEN")
	)
	(segment
		(start 35.16884 -160.126172)
		(end 34.381186 -159.338518)
		(width 0.254)
		(layer "In11.Cu")
		(net "PVCCD_HV_CPU1_ATSEN")
	)
	(segment
		(start 45.77588 -166.406068)
		(end 36.10356 -166.406068)
		(width 0.254)
		(layer "In11.Cu")
		(net "PVCCD_HV_CPU1_ATSEN")
	)
	(segment
		(start 50.966116 -164.152834)
		(end 48.029114 -164.152834)
		(width 0.254)
		(layer "In11.Cu")
		(net "PVCCD_HV_CPU1_ATSEN")
	)
	(segment
		(start 31.97606 -160.269428)
		(end 31.97606 -163.617402)
		(width 0.254)
		(layer "In11.Cu")
		(net "PVCCD_HV_CPU1_ATSEN")
	)
	(segment
		(start 34.381186 -159.338518)
		(end 32.90697 -159.338518)
		(width 0.254)
		(layer "In11.Cu")
		(net "PVCCD_HV_CPU1_ATSEN")
	)
	(segment
		(start 36.10356 -166.406068)
		(end 35.16884 -165.471348)
		(width 0.254)
		(layer "In11.Cu")
		(net "PVCCD_HV_CPU1_ATSEN")
	)
	(segment
		(start 48.029114 -164.152834)
		(end 45.77588 -166.406068)
		(width 0.254)
		(layer "In11.Cu")
		(net "PVCCD_HV_CPU1_ATSEN")
	)
	(segment
		(start 32.90697 -159.338518)
		(end 31.97606 -160.269428)
		(width 0.254)
		(layer "In11.Cu")
		(net "PVCCD_HV_CPU1_ATSEN")
	)
	(segment
		(start 35.16884 -165.471348)
		(end 35.16884 -160.126172)
		(width 0.254)
		(layer "In11.Cu")
		(net "PVCCD_HV_CPU1_ATSEN")
	)
	(segment
		(start 26.86304 -167.800528)
		(end 27.18943 -168.126918)
		(width 0.254)
		(layer "F.Cu")
		(net "PVCCD_HV_CPU1_APWM1")
	)
	(segment
		(start 51.999642 -165.374066)
		(end 51.213766 -165.374066)
		(width 0.1778)
		(layer "F.Cu")
		(net "PVCCD_HV_CPU1_APWM1")
	)
	(segment
		(start 26.662888 -167.600376)
		(end 26.86304 -167.800528)
		(width 0.1524)
		(layer "F.Cu")
		(net "PVCCD_HV_CPU1_APWM1")
	)
	(segment
		(start 51.213766 -165.374066)
		(end 50.714656 -165.274752)
		(width 0.1778)
		(layer "F.Cu")
		(net "PVCCD_HV_CPU1_APWM1")
	)
	(segment
		(start 26.662888 -167.22725)
		(end 26.662888 -167.600376)
		(width 0.1524)
		(layer "F.Cu")
		(net "PVCCD_HV_CPU1_APWM1")
	)
	(segment
		(start 50.714656 -165.274752)
		(end 50.587656 -165.222174)
		(width 0.1778)
		(layer "F.Cu")
		(net "PVCCD_HV_CPU1_APWM1")
	)
	(via
		(at 50.587656 -165.222174)
		(size 0.508)
		(drill 0.254)
		(layers "F.Cu" "B.Cu")
		(net "PVCCD_HV_CPU1_APWM1")
	)
	(via
		(at 27.18943 -168.126918)
		(size 0.508)
		(drill 0.254)
		(layers "F.Cu" "B.Cu")
		(net "PVCCD_HV_CPU1_APWM1")
	)
	(segment
		(start 41.79824 -170.775122)
		(end 40.076374 -172.496988)
		(width 0.2286)
		(layer "In6.Cu")
		(net "PVCCD_HV_CPU1_APWM1")
	)
	(segment
		(start 28.93949 -172.496988)
		(end 28.072588 -171.630086)
		(width 0.2286)
		(layer "In6.Cu")
		(net "PVCCD_HV_CPU1_APWM1")
	)
	(segment
		(start 49.378362 -166.431468)
		(end 44.833032 -166.431468)
		(width 0.2286)
		(layer "In6.Cu")
		(net "PVCCD_HV_CPU1_APWM1")
	)
	(segment
		(start 41.79824 -169.46626)
		(end 41.79824 -170.775122)
		(width 0.2286)
		(layer "In6.Cu")
		(net "PVCCD_HV_CPU1_APWM1")
	)
	(segment
		(start 27.310334 -170.867832)
		(end 27.310334 -168.247822)
		(width 0.254)
		(layer "In6.Cu")
		(net "PVCCD_HV_CPU1_APWM1")
	)
	(segment
		(start 50.587656 -165.222174)
		(end 49.378362 -166.431468)
		(width 0.2286)
		(layer "In6.Cu")
		(net "PVCCD_HV_CPU1_APWM1")
	)
	(segment
		(start 27.310334 -168.247822)
		(end 27.18943 -168.126918)
		(width 0.254)
		(layer "In6.Cu")
		(net "PVCCD_HV_CPU1_APWM1")
	)
	(segment
		(start 40.076374 -172.496988)
		(end 28.93949 -172.496988)
		(width 0.2286)
		(layer "In6.Cu")
		(net "PVCCD_HV_CPU1_APWM1")
	)
	(segment
		(start 44.833032 -166.431468)
		(end 41.79824 -169.46626)
		(width 0.2286)
		(layer "In6.Cu")
		(net "PVCCD_HV_CPU1_APWM1")
	)
	(segment
		(start 28.072588 -171.630086)
		(end 27.310334 -170.867832)
		(width 0.254)
		(layer "In6.Cu")
		(net "PVCCD_HV_CPU1_APWM1")
	)
	(segment
		(start 31.537402 -162.607244)
		(end 31.537402 -162.586162)
		(width 0.1778)
		(layer "F.Cu")
		(net "PVCCD_HV_CPU1_ADDR")
	)
	(segment
		(start 30.446726 -164.227256)
		(end 31.03118 -163.642802)
		(width 0.1778)
		(layer "F.Cu")
		(net "PVCCD_HV_CPU1_ADDR")
	)
	(segment
		(start 30.062932 -164.227256)
		(end 30.446726 -164.227256)
		(width 0.1778)
		(layer "F.Cu")
		(net "PVCCD_HV_CPU1_ADDR")
	)
	(segment
		(start 31.537402 -161.582862)
		(end 31.560516 -161.605976)
		(width 0.1778)
		(layer "F.Cu")
		(net "PVCCD_HV_CPU1_ADDR")
	)
	(segment
		(start 31.03118 -163.113466)
		(end 31.537402 -162.607244)
		(width 0.1778)
		(layer "F.Cu")
		(net "PVCCD_HV_CPU1_ADDR")
	)
	(segment
		(start 31.03118 -163.642802)
		(end 31.03118 -163.113466)
		(width 0.1778)
		(layer "F.Cu")
		(net "PVCCD_HV_CPU1_ADDR")
	)
	(segment
		(start 31.537402 -160.660588)
		(end 31.90748 -160.29051)
		(width 0.254)
		(layer "F.Cu")
		(net "PVCCD_HV_CPU1_ADDR")
	)
	(segment
		(start 31.560516 -162.563048)
		(end 31.537402 -162.586162)
		(width 0.1778)
		(layer "F.Cu")
		(net "PVCCD_HV_CPU1_ADDR")
	)
	(segment
		(start 31.537402 -161.582862)
		(end 31.537402 -160.660588)
		(width 0.254)
		(layer "F.Cu")
		(net "PVCCD_HV_CPU1_ADDR")
	)
	(segment
		(start 31.560516 -161.605976)
		(end 31.560516 -162.563048)
		(width 0.1778)
		(layer "F.Cu")
		(net "PVCCD_HV_CPU1_ADDR")
	)
	(via
		(at 31.90748 -160.29051)
		(size 0.762)
		(drill 0.381)
		(layers "F.Cu" "B.Cu")
		(net "PVCCD_HV_CPU1_ADDR")
	)
	(segment
		(start 26.662888 -162.427158)
		(end 26.662888 -161.840926)
		(width 0.1778)
		(layer "F.Cu")
		(net "PVCCD_HV_CPU1_ACSP1")
	)
	(segment
		(start 51.228244 -163.136834)
		(end 51.153568 -163.136834)
		(width 0.254)
		(layer "F.Cu")
		(net "PVCCD_HV_CPU1_ACSP1")
	)
	(segment
		(start 51.665378 -163.573968)
		(end 51.228244 -163.136834)
		(width 0.254)
		(layer "F.Cu")
		(net "PVCCD_HV_CPU1_ACSP1")
	)
	(segment
		(start 26.662888 -161.840926)
		(end 25.976326 -161.154364)
		(width 0.1778)
		(layer "F.Cu")
		(net "PVCCD_HV_CPU1_ACSP1")
	)
	(segment
		(start 51.999642 -163.573968)
		(end 51.665378 -163.573968)
		(width 0.254)
		(layer "F.Cu")
		(net "PVCCD_HV_CPU1_ACSP1")
	)
	(via
		(at 25.976326 -161.154364)
		(size 0.508)
		(drill 0.254)
		(layers "F.Cu" "B.Cu")
		(net "PVCCD_HV_CPU1_ACSP1")
	)
	(via
		(at 51.153568 -163.136834)
		(size 0.508)
		(drill 0.254)
		(layers "F.Cu" "B.Cu")
		(net "PVCCD_HV_CPU1_ACSP1")
	)
	(segment
		(start 51.153568 -163.136834)
		(end 50.541682 -162.524948)
		(width 0.254)
		(layer "In6.Cu")
		(net "PVCCD_HV_CPU1_ACSP1")
	)
	(segment
		(start 25.976326 -160.288224)
		(end 25.976326 -161.154364)
		(width 0.254)
		(layer "In6.Cu")
		(net "PVCCD_HV_CPU1_ACSP1")
	)
	(segment
		(start 26.936446 -159.328104)
		(end 25.976326 -160.288224)
		(width 0.254)
		(layer "In6.Cu")
		(net "PVCCD_HV_CPU1_ACSP1")
	)
	(segment
		(start 29.074618 -159.7025)
		(end 28.170632 -159.328104)
		(width 0.254)
		(layer "In6.Cu")
		(net "PVCCD_HV_CPU1_ACSP1")
	)
	(segment
		(start 38.832028 -163.95192)
		(end 35.805618 -163.95192)
		(width 0.254)
		(layer "In6.Cu")
		(net "PVCCD_HV_CPU1_ACSP1")
	)
	(segment
		(start 35.236912 -163.383214)
		(end 35.236912 -160.565338)
		(width 0.254)
		(layer "In6.Cu")
		(net "PVCCD_HV_CPU1_ACSP1")
	)
	(segment
		(start 49.911 -162.524948)
		(end 49.276 -163.159948)
		(width 0.254)
		(layer "In6.Cu")
		(net "PVCCD_HV_CPU1_ACSP1")
	)
	(segment
		(start 48.387 -163.159948)
		(end 45.339 -160.111948)
		(width 0.254)
		(layer "In6.Cu")
		(net "PVCCD_HV_CPU1_ACSP1")
	)
	(segment
		(start 35.805618 -163.95192)
		(end 35.236912 -163.383214)
		(width 0.254)
		(layer "In6.Cu")
		(net "PVCCD_HV_CPU1_ACSP1")
	)
	(segment
		(start 42.672 -160.111948)
		(end 38.832028 -163.95192)
		(width 0.254)
		(layer "In6.Cu")
		(net "PVCCD_HV_CPU1_ACSP1")
	)
	(segment
		(start 34.374074 -159.7025)
		(end 29.074618 -159.7025)
		(width 0.254)
		(layer "In6.Cu")
		(net "PVCCD_HV_CPU1_ACSP1")
	)
	(segment
		(start 50.541682 -162.524948)
		(end 49.911 -162.524948)
		(width 0.254)
		(layer "In6.Cu")
		(net "PVCCD_HV_CPU1_ACSP1")
	)
	(segment
		(start 45.339 -160.111948)
		(end 42.672 -160.111948)
		(width 0.254)
		(layer "In6.Cu")
		(net "PVCCD_HV_CPU1_ACSP1")
	)
	(segment
		(start 49.276 -163.159948)
		(end 48.387 -163.159948)
		(width 0.254)
		(layer "In6.Cu")
		(net "PVCCD_HV_CPU1_ACSP1")
	)
	(segment
		(start 28.170632 -159.328104)
		(end 26.936446 -159.328104)
		(width 0.254)
		(layer "In6.Cu")
		(net "PVCCD_HV_CPU1_ACSP1")
	)
	(segment
		(start 35.236912 -160.565338)
		(end 34.374074 -159.7025)
		(width 0.254)
		(layer "In6.Cu")
		(net "PVCCD_HV_CPU1_ACSP1")
	)
	(segment
		(start 101.772466 -219.228162)
		(end 101.772466 -218.692476)
		(width 0.254)
		(layer "F.Cu")
		(net "PVCCD_HV_CPU1")
	)
	(segment
		(start 102.352094 -258.2672)
		(end 102.352094 -258.802886)
		(width 0.254)
		(layer "F.Cu")
		(net "PVCCD_HV_CPU1")
	)
	(segment
		(start 121.618248 -259.616702)
		(end 121.617994 -259.616956)
		(width 0.254)
		(layer "F.Cu")
		(net "PVCCD_HV_CPU1")
	)
	(segment
		(start 121.618248 -261.244334)
		(end 121.617994 -261.244588)
		(width 0.254)
		(layer "F.Cu")
		(net "PVCCD_HV_CPU1")
	)
	(segment
		(start 65.018158 -191.11595)
		(end 64.276478 -191.85763)
		(width 0.381)
		(layer "F.Cu")
		(net "PVCCD_HV_CPU1")
	)
	(segment
		(start 103.652066 -219.228162)
		(end 103.652066 -218.692476)
		(width 0.254)
		(layer "F.Cu")
		(net "PVCCD_HV_CPU1")
	)
	(segment
		(start 105.531666 -215.972644)
		(end 105.531666 -215.436958)
		(width 0.254)
		(layer "F.Cu")
		(net "PVCCD_HV_CPU1")
	)
	(segment
		(start 107.411266 -215.972644)
		(end 107.411266 -215.437212)
		(width 0.254)
		(layer "F.Cu")
		(net "PVCCD_HV_CPU1")
	)
	(segment
		(start 121.977912 -242.830858)
		(end 121.978166 -242.830604)
		(width 0.254)
		(layer "F.Cu")
		(net "PVCCD_HV_CPU1")
	)
	(segment
		(start 67.7037 -170.829732)
		(end 68.644008 -171.77004)
		(width 0.508)
		(layer "F.Cu")
		(net "PVCCD_HV_CPU1")
	)
	(segment
		(start 107.411266 -221.947994)
		(end 107.411012 -221.94774)
		(width 0.254)
		(layer "F.Cu")
		(net "PVCCD_HV_CPU1")
	)
	(segment
		(start 107.411266 -219.228162)
		(end 107.411266 -218.692476)
		(width 0.254)
		(layer "F.Cu")
		(net "PVCCD_HV_CPU1")
	)
	(segment
		(start 101.772466 -215.972644)
		(end 101.772466 -215.437212)
		(width 0.254)
		(layer "F.Cu")
		(net "PVCCD_HV_CPU1")
	)
	(segment
		(start 107.411266 -218.692476)
		(end 107.411012 -218.692222)
		(width 0.254)
		(layer "F.Cu")
		(net "PVCCD_HV_CPU1")
	)
	(segment
		(start 121.977912 -241.203226)
		(end 121.977912 -240.66754)
		(width 0.254)
		(layer "F.Cu")
		(net "PVCCD_HV_CPU1")
	)
	(segment
		(start 107.411266 -215.437212)
		(end 107.411012 -215.436958)
		(width 0.254)
		(layer "F.Cu")
		(net "PVCCD_HV_CPU1")
	)
	(segment
		(start 69.923406 -166.634922)
		(end 70.863714 -167.57523)
		(width 0.508)
		(layer "F.Cu")
		(net "PVCCD_HV_CPU1")
	)
	(segment
		(start 68.644008 -171.77004)
		(end 69.584316 -170.829732)
		(width 0.508)
		(layer "F.Cu")
		(net "PVCCD_HV_CPU1")
	)
	(segment
		(start 67.017138 -191.11595)
		(end 65.018158 -191.11595)
		(width 0.381)
		(layer "F.Cu")
		(net "PVCCD_HV_CPU1")
	)
	(segment
		(start 105.531666 -222.48368)
		(end 105.531666 -221.947994)
		(width 0.254)
		(layer "F.Cu")
		(net "PVCCD_HV_CPU1")
	)
	(segment
		(start 69.923406 -166.634922)
		(end 70.863714 -165.694614)
		(width 0.508)
		(layer "F.Cu")
		(net "PVCCD_HV_CPU1")
	)
	(segment
		(start 102.242112 -241.203226)
		(end 102.242366 -241.202972)
		(width 0.254)
		(layer "F.Cu")
		(net "PVCCD_HV_CPU1")
	)
	(segment
		(start 121.978166 -242.830604)
		(end 121.978166 -242.294918)
		(width 0.254)
		(layer "F.Cu")
		(net "PVCCD_HV_CPU1")
	)
	(segment
		(start 109.290866 -218.692476)
		(end 109.290612 -218.692222)
		(width 0.2032)
		(layer "F.Cu")
		(net "PVCCD_HV_CPU1")
	)
	(segment
		(start 152.498552 -191.12865)
		(end 150.957788 -192.669414)
		(width 0.381)
		(layer "F.Cu")
		(net "PVCCD_HV_CPU1")
	)
	(segment
		(start 103.651812 -215.436958)
		(end 103.651812 -215.436704)
		(width 0.254)
		(layer "F.Cu")
		(net "PVCCD_HV_CPU1")
	)
	(segment
		(start 102.242366 -241.202972)
		(end 102.242366 -240.667286)
		(width 0.254)
		(layer "F.Cu")
		(net "PVCCD_HV_CPU1")
	)
	(segment
		(start 113.050066 -219.228162)
		(end 113.050066 -218.692476)
		(width 0.254)
		(layer "F.Cu")
		(net "PVCCD_HV_CPU1")
	)
	(segment
		(start 101.772212 -215.436958)
		(end 101.772212 -215.436704)
		(width 0.254)
		(layer "F.Cu")
		(net "PVCCD_HV_CPU1")
	)
	(segment
		(start 105.531666 -221.947994)
		(end 105.531412 -221.94774)
		(width 0.254)
		(layer "F.Cu")
		(net "PVCCD_HV_CPU1")
	)
	(segment
		(start 121.508012 -242.016788)
		(end 121.508012 -241.481102)
		(width 0.254)
		(layer "F.Cu")
		(net "PVCCD_HV_CPU1")
	)
	(segment
		(start 113.050066 -218.692476)
		(end 113.049812 -218.692222)
		(width 0.254)
		(layer "F.Cu")
		(net "PVCCD_HV_CPU1")
	)
	(segment
		(start 103.652066 -218.692476)
		(end 103.651812 -218.692222)
		(width 0.254)
		(layer "F.Cu")
		(net "PVCCD_HV_CPU1")
	)
	(segment
		(start 105.531666 -215.436958)
		(end 105.531412 -215.436704)
		(width 0.254)
		(layer "F.Cu")
		(net "PVCCD_HV_CPU1")
	)
	(segment
		(start 101.77272 -242.016788)
		(end 101.77272 -241.481102)
		(width 0.254)
		(layer "F.Cu")
		(net "PVCCD_HV_CPU1")
	)
	(segment
		(start 102.242366 -242.830858)
		(end 102.242366 -242.294918)
		(width 0.254)
		(layer "F.Cu")
		(net "PVCCD_HV_CPU1")
	)
	(segment
		(start 101.302312 -242.830858)
		(end 101.302566 -242.830858)
		(width 0.254)
		(layer "F.Cu")
		(net "PVCCD_HV_CPU1")
	)
	(segment
		(start 73.633584 -192.41643)
		(end 68.317618 -192.41643)
		(width 0.381)
		(layer "F.Cu")
		(net "PVCCD_HV_CPU1")
	)
	(segment
		(start 121.618248 -260.708902)
		(end 121.618248 -261.244334)
		(width 0.254)
		(layer "F.Cu")
		(net "PVCCD_HV_CPU1")
	)
	(segment
		(start 122.087894 -258.2672)
		(end 122.087894 -258.80314)
		(width 0.254)
		(layer "F.Cu")
		(net "PVCCD_HV_CPU1")
	)
	(segment
		(start 121.508266 -243.644928)
		(end 121.508012 -243.644674)
		(width 0.254)
		(layer "F.Cu")
		(net "PVCCD_HV_CPU1")
	)
	(segment
		(start 121.618248 -259.081016)
		(end 121.618248 -259.616702)
		(width 0.254)
		(layer "F.Cu")
		(net "PVCCD_HV_CPU1")
	)
	(segment
		(start 101.302566 -242.830858)
		(end 101.302566 -242.294918)
		(width 0.254)
		(layer "F.Cu")
		(net "PVCCD_HV_CPU1")
	)
	(segment
		(start 107.411012 -215.436958)
		(end 107.411012 -215.436704)
		(width 0.254)
		(layer "F.Cu")
		(net "PVCCD_HV_CPU1")
	)
	(segment
		(start 102.352094 -258.802886)
		(end 102.35184 -258.80314)
		(width 0.254)
		(layer "F.Cu")
		(net "PVCCD_HV_CPU1")
	)
	(segment
		(start 105.531666 -219.228162)
		(end 105.531666 -218.692476)
		(width 0.254)
		(layer "F.Cu")
		(net "PVCCD_HV_CPU1")
	)
	(segment
		(start 121.618248 -257.45313)
		(end 121.617994 -257.98907)
		(width 0.254)
		(layer "F.Cu")
		(net "PVCCD_HV_CPU1")
	)
	(segment
		(start 103.652066 -215.437212)
		(end 103.651812 -215.436958)
		(width 0.254)
		(layer "F.Cu")
		(net "PVCCD_HV_CPU1")
	)
	(segment
		(start 121.977912 -240.66754)
		(end 121.978166 -240.667286)
		(width 0.254)
		(layer "F.Cu")
		(net "PVCCD_HV_CPU1")
	)
	(segment
		(start 107.411266 -222.48368)
		(end 107.411266 -221.947994)
		(width 0.254)
		(layer "F.Cu")
		(net "PVCCD_HV_CPU1")
	)
	(segment
		(start 74.085704 -192.86855)
		(end 73.633584 -192.41643)
		(width 0.381)
		(layer "F.Cu")
		(net "PVCCD_HV_CPU1")
	)
	(segment
		(start 121.508266 -242.017042)
		(end 121.508012 -242.016788)
		(width 0.254)
		(layer "F.Cu")
		(net "PVCCD_HV_CPU1")
	)
	(segment
		(start 109.290866 -219.228162)
		(end 109.290866 -218.692476)
		(width 0.2032)
		(layer "F.Cu")
		(net "PVCCD_HV_CPU1")
	)
	(segment
		(start 102.242112 -242.830858)
		(end 102.242366 -242.830858)
		(width 0.254)
		(layer "F.Cu")
		(net "PVCCD_HV_CPU1")
	)
	(segment
		(start 168.230296 -191.12865)
		(end 152.498552 -191.12865)
		(width 0.381)
		(layer "F.Cu")
		(net "PVCCD_HV_CPU1")
	)
	(segment
		(start 121.617994 -261.244588)
		(end 121.617994 -261.244842)
		(width 0.254)
		(layer "F.Cu")
		(net "PVCCD_HV_CPU1")
	)
	(segment
		(start 76.295758 -192.86855)
		(end 74.085704 -192.86855)
		(width 0.381)
		(layer "F.Cu")
		(net "PVCCD_HV_CPU1")
	)
	(segment
		(start 68.983098 -167.57523)
		(end 69.923406 -166.634922)
		(width 0.508)
		(layer "F.Cu")
		(net "PVCCD_HV_CPU1")
	)
	(segment
		(start 101.772466 -242.017042)
		(end 101.77272 -242.016788)
		(width 0.254)
		(layer "F.Cu")
		(net "PVCCD_HV_CPU1")
	)
	(segment
		(start 105.531666 -218.692476)
		(end 105.531412 -218.692222)
		(width 0.254)
		(layer "F.Cu")
		(net "PVCCD_HV_CPU1")
	)
	(segment
		(start 93.099636 -193.23939)
		(end 76.666598 -193.23939)
		(width 0.381)
		(layer "F.Cu")
		(net "PVCCD_HV_CPU1")
	)
	(segment
		(start 68.983098 -165.694614)
		(end 69.923406 -166.634922)
		(width 0.508)
		(layer "F.Cu")
		(net "PVCCD_HV_CPU1")
	)
	(segment
		(start 101.882448 -259.081016)
		(end 101.882448 -259.616702)
		(width 0.254)
		(layer "F.Cu")
		(net "PVCCD_HV_CPU1")
	)
	(segment
		(start 73.41743 -162.003486)
		(end 72.791828 -162.003486)
		(width 0.3556)
		(layer "F.Cu")
		(net "PVCCD_HV_CPU1")
	)
	(segment
		(start 103.652066 -215.972644)
		(end 103.652066 -215.437212)
		(width 0.254)
		(layer "F.Cu")
		(net "PVCCD_HV_CPU1")
	)
	(segment
		(start 101.882448 -259.616702)
		(end 101.882194 -259.616956)
		(width 0.254)
		(layer "F.Cu")
		(net "PVCCD_HV_CPU1")
	)
	(segment
		(start 121.508012 -243.644674)
		(end 121.508012 -243.108988)
		(width 0.254)
		(layer "F.Cu")
		(net "PVCCD_HV_CPU1")
	)
	(segment
		(start 170.123612 -193.021966)
		(end 168.230296 -191.12865)
		(width 0.381)
		(layer "F.Cu")
		(net "PVCCD_HV_CPU1")
	)
	(segment
		(start 76.666598 -193.23939)
		(end 76.295758 -192.86855)
		(width 0.381)
		(layer "F.Cu")
		(net "PVCCD_HV_CPU1")
	)
	(segment
		(start 101.772466 -218.692476)
		(end 101.772212 -218.692222)
		(width 0.254)
		(layer "F.Cu")
		(net "PVCCD_HV_CPU1")
	)
	(segment
		(start 114.929666 -219.228162)
		(end 114.929666 -218.692222)
		(width 0.254)
		(layer "F.Cu")
		(net "PVCCD_HV_CPU1")
	)
	(segment
		(start 101.772466 -215.437212)
		(end 101.772212 -215.436958)
		(width 0.254)
		(layer "F.Cu")
		(net "PVCCD_HV_CPU1")
	)
	(segment
		(start 68.644008 -171.77004)
		(end 68.644008 -170.44035)
		(width 0.508)
		(layer "F.Cu")
		(net "PVCCD_HV_CPU1")
	)
	(segment
		(start 150.957788 -192.669414)
		(end 93.669612 -192.669414)
		(width 0.381)
		(layer "F.Cu")
		(net "PVCCD_HV_CPU1")
	)
	(segment
		(start 68.317618 -192.41643)
		(end 67.017138 -191.11595)
		(width 0.381)
		(layer "F.Cu")
		(net "PVCCD_HV_CPU1")
	)
	(segment
		(start 93.669612 -192.669414)
		(end 93.099636 -193.23939)
		(width 0.381)
		(layer "F.Cu")
		(net "PVCCD_HV_CPU1")
	)
	(segment
		(start 73.54443 -161.107882)
		(end 72.791828 -161.107882)
		(width 0.3556)
		(layer "F.Cu")
		(net "PVCCD_HV_CPU1")
	)
	(via
		(at 68.33235 -167.02151)
		(size 0.508)
		(drill 0.254)
		(layers "F.Cu" "B.Cu")
		(net "PVCCD_HV_CPU1")
	)
	(via
		(at 67.06235 -167.02151)
		(size 0.508)
		(drill 0.254)
		(layers "F.Cu" "B.Cu")
		(net "PVCCD_HV_CPU1")
	)
	(via
		(at 113.902744 -213.82609)
		(size 0.6604)
		(drill 0.3302)
		(layers "F.Cu" "B.Cu")
		(net "PVCCD_HV_CPU1")
	)
	(via
		(at 121.508012 -243.108988)
		(size 0.4572)
		(drill 0.2032)
		(layers "F.Cu" "B.Cu")
		(net "PVCCD_HV_CPU1")
	)
	(via
		(at 64.61379 -163.27247)
		(size 0.508)
		(drill 0.254)
		(layers "F.Cu" "B.Cu")
		(net "PVCCD_HV_CPU1")
	)
	(via
		(at 67.68973 -166.38397)
		(size 0.508)
		(drill 0.254)
		(layers "F.Cu" "B.Cu")
		(net "PVCCD_HV_CPU1")
	)
	(via
		(at 65.24117 -162.55873)
		(size 0.508)
		(drill 0.254)
		(layers "F.Cu" "B.Cu")
		(net "PVCCD_HV_CPU1")
	)
	(via
		(at 51.393852 -161.733484)
		(size 0.508)
		(drill 0.254)
		(layers "F.Cu" "B.Cu")
		(net "PVCCD_HV_CPU1")
	)
	(via
		(at 101.772212 -215.436704)
		(size 0.4572)
		(drill 0.2032)
		(layers "F.Cu" "B.Cu")
		(net "PVCCD_HV_CPU1")
	)
	(via
		(at 102.81539 -246.6594)
		(size 0.4572)
		(drill 0.2032)
		(layers "F.Cu" "B.Cu")
		(net "PVCCD_HV_CPU1")
	)
	(via
		(at 107.411012 -215.436704)
		(size 0.4572)
		(drill 0.2032)
		(layers "F.Cu" "B.Cu")
		(net "PVCCD_HV_CPU1")
	)
	(via
		(at 121.617994 -261.244842)
		(size 0.4572)
		(drill 0.2032)
		(layers "F.Cu" "B.Cu")
		(net "PVCCD_HV_CPU1")
	)
	(via
		(at 101.77272 -241.481102)
		(size 0.4572)
		(drill 0.2032)
		(layers "F.Cu" "B.Cu")
		(net "PVCCD_HV_CPU1")
	)
	(via
		(at 107.411012 -218.692222)
		(size 0.4572)
		(drill 0.2032)
		(layers "F.Cu" "B.Cu")
		(net "PVCCD_HV_CPU1")
	)
	(via
		(at 68.33997 -163.19627)
		(size 0.508)
		(drill 0.254)
		(layers "F.Cu" "B.Cu")
		(net "PVCCD_HV_CPU1")
	)
	(via
		(at 66.42735 -167.02151)
		(size 0.508)
		(drill 0.254)
		(layers "F.Cu" "B.Cu")
		(net "PVCCD_HV_CPU1")
	)
	(via
		(at 114.929666 -218.692222)
		(size 0.4572)
		(drill 0.2032)
		(layers "F.Cu" "B.Cu")
		(net "PVCCD_HV_CPU1")
	)
	(via
		(at 67.68211 -167.66921)
		(size 0.508)
		(drill 0.254)
		(layers "F.Cu" "B.Cu")
		(net "PVCCD_HV_CPU1")
	)
	(via
		(at 66.41211 -167.66921)
		(size 0.508)
		(drill 0.254)
		(layers "F.Cu" "B.Cu")
		(net "PVCCD_HV_CPU1")
	)
	(via
		(at 107.411012 -221.94774)
		(size 0.4572)
		(drill 0.2032)
		(layers "F.Cu" "B.Cu")
		(net "PVCCD_HV_CPU1")
	)
	(via
		(at 103.98379 -246.6594)
		(size 0.4572)
		(drill 0.2032)
		(layers "F.Cu" "B.Cu")
		(net "PVCCD_HV_CPU1")
	)
	(via
		(at 65.24117 -161.92373)
		(size 0.508)
		(drill 0.254)
		(layers "F.Cu" "B.Cu")
		(net "PVCCD_HV_CPU1")
	)
	(via
		(at 64.60617 -166.94531)
		(size 0.508)
		(drill 0.254)
		(layers "F.Cu" "B.Cu")
		(net "PVCCD_HV_CPU1")
	)
	(via
		(at 66.43497 -163.19627)
		(size 0.508)
		(drill 0.254)
		(layers "F.Cu" "B.Cu")
		(net "PVCCD_HV_CPU1")
	)
	(via
		(at 102.242366 -240.667286)
		(size 0.4572)
		(drill 0.2032)
		(layers "F.Cu" "B.Cu")
		(net "PVCCD_HV_CPU1")
	)
	(via
		(at 189.112652 -189.617096)
		(size 0.508)
		(drill 0.254)
		(layers "F.Cu" "B.Cu")
		(net "PVCCD_HV_CPU1")
	)
	(via
		(at 66.41973 -163.84397)
		(size 0.508)
		(drill 0.254)
		(layers "F.Cu" "B.Cu")
		(net "PVCCD_HV_CPU1")
	)
	(via
		(at 67.70497 -163.19627)
		(size 0.508)
		(drill 0.254)
		(layers "F.Cu" "B.Cu")
		(net "PVCCD_HV_CPU1")
	)
	(via
		(at 64.276478 -191.85763)
		(size 0.508)
		(drill 0.254)
		(layers "F.Cu" "B.Cu")
		(net "PVCCD_HV_CPU1")
	)
	(via
		(at 119.736616 -246.6594)
		(size 0.4572)
		(drill 0.2032)
		(layers "F.Cu" "B.Cu")
		(net "PVCCD_HV_CPU1")
	)
	(via
		(at 103.651812 -215.436704)
		(size 0.4572)
		(drill 0.2032)
		(layers "F.Cu" "B.Cu")
		(net "PVCCD_HV_CPU1")
	)
	(via
		(at 67.05473 -166.38397)
		(size 0.508)
		(drill 0.254)
		(layers "F.Cu" "B.Cu")
		(net "PVCCD_HV_CPU1")
	)
	(via
		(at 72.791828 -161.107882)
		(size 0.508)
		(drill 0.254)
		(layers "F.Cu" "B.Cu")
		(net "PVCCD_HV_CPU1")
	)
	(via
		(at 67.06997 -163.19627)
		(size 0.508)
		(drill 0.254)
		(layers "F.Cu" "B.Cu")
		(net "PVCCD_HV_CPU1")
	)
	(via
		(at 112.226344 -213.82609)
		(size 0.6604)
		(drill 0.3302)
		(layers "F.Cu" "B.Cu")
		(net "PVCCD_HV_CPU1")
	)
	(via
		(at 67.06235 -162.55873)
		(size 0.508)
		(drill 0.254)
		(layers "F.Cu" "B.Cu")
		(net "PVCCD_HV_CPU1")
	)
	(via
		(at 67.69735 -161.92373)
		(size 0.508)
		(drill 0.254)
		(layers "F.Cu" "B.Cu")
		(net "PVCCD_HV_CPU1")
	)
	(via
		(at 72.791828 -162.003486)
		(size 0.508)
		(drill 0.254)
		(layers "F.Cu" "B.Cu")
		(net "PVCCD_HV_CPU1")
	)
	(via
		(at 66.42735 -161.92373)
		(size 0.508)
		(drill 0.254)
		(layers "F.Cu" "B.Cu")
		(net "PVCCD_HV_CPU1")
	)
	(via
		(at 170.123612 -193.021966)
		(size 0.508)
		(drill 0.254)
		(layers "F.Cu" "B.Cu")
		(net "PVCCD_HV_CPU1")
	)
	(via
		(at 65.441322 -168.86428)
		(size 0.508)
		(drill 0.254)
		(layers "F.Cu" "B.Cu")
		(net "PVCCD_HV_CPU1")
	)
	(via
		(at 120.97639 -247.351804)
		(size 0.4572)
		(drill 0.2032)
		(layers "F.Cu" "B.Cu")
		(net "PVCCD_HV_CPU1")
	)
	(via
		(at 102.242366 -242.294918)
		(size 0.4572)
		(drill 0.2032)
		(layers "F.Cu" "B.Cu")
		(net "PVCCD_HV_CPU1")
	)
	(via
		(at 101.772212 -218.692222)
		(size 0.4572)
		(drill 0.2032)
		(layers "F.Cu" "B.Cu")
		(net "PVCCD_HV_CPU1")
	)
	(via
		(at 105.531412 -218.692222)
		(size 0.4572)
		(drill 0.2032)
		(layers "F.Cu" "B.Cu")
		(net "PVCCD_HV_CPU1")
	)
	(via
		(at 187.352686 -189.047628)
		(size 0.508)
		(drill 0.254)
		(layers "F.Cu" "B.Cu")
		(net "PVCCD_HV_CPU1")
	)
	(via
		(at 120.97639 -246.767604)
		(size 0.4572)
		(drill 0.2032)
		(layers "F.Cu" "B.Cu")
		(net "PVCCD_HV_CPU1")
	)
	(via
		(at 101.302566 -242.294918)
		(size 0.4572)
		(drill 0.2032)
		(layers "F.Cu" "B.Cu")
		(net "PVCCD_HV_CPU1")
	)
	(via
		(at 67.06235 -161.92373)
		(size 0.508)
		(drill 0.254)
		(layers "F.Cu" "B.Cu")
		(net "PVCCD_HV_CPU1")
	)
	(via
		(at 122.087894 -258.80314)
		(size 0.4572)
		(drill 0.2032)
		(layers "F.Cu" "B.Cu")
		(net "PVCCD_HV_CPU1")
	)
	(via
		(at 67.69735 -167.02151)
		(size 0.508)
		(drill 0.254)
		(layers "F.Cu" "B.Cu")
		(net "PVCCD_HV_CPU1")
	)
	(via
		(at 64.780922 -168.20388)
		(size 0.508)
		(drill 0.254)
		(layers "F.Cu" "B.Cu")
		(net "PVCCD_HV_CPU1")
	)
	(via
		(at 105.531412 -221.94774)
		(size 0.4572)
		(drill 0.2032)
		(layers "F.Cu" "B.Cu")
		(net "PVCCD_HV_CPU1")
	)
	(via
		(at 65.441322 -168.20388)
		(size 0.508)
		(drill 0.254)
		(layers "F.Cu" "B.Cu")
		(net "PVCCD_HV_CPU1")
	)
	(via
		(at 120.371616 -246.6594)
		(size 0.4572)
		(drill 0.2032)
		(layers "F.Cu" "B.Cu")
		(net "PVCCD_HV_CPU1")
	)
	(via
		(at 121.617994 -259.616956)
		(size 0.4572)
		(drill 0.2032)
		(layers "F.Cu" "B.Cu")
		(net "PVCCD_HV_CPU1")
	)
	(via
		(at 65.24117 -166.94531)
		(size 0.508)
		(drill 0.254)
		(layers "F.Cu" "B.Cu")
		(net "PVCCD_HV_CPU1")
	)
	(via
		(at 121.978166 -242.294918)
		(size 0.4572)
		(drill 0.2032)
		(layers "F.Cu" "B.Cu")
		(net "PVCCD_HV_CPU1")
	)
	(via
		(at 67.68973 -163.84397)
		(size 0.508)
		(drill 0.254)
		(layers "F.Cu" "B.Cu")
		(net "PVCCD_HV_CPU1")
	)
	(via
		(at 102.352348 -260.430772)
		(size 0.4572)
		(drill 0.2032)
		(layers "F.Cu" "B.Cu")
		(net "PVCCD_HV_CPU1")
	)
	(via
		(at 66.41973 -166.38397)
		(size 0.508)
		(drill 0.254)
		(layers "F.Cu" "B.Cu")
		(net "PVCCD_HV_CPU1")
	)
	(via
		(at 67.69735 -162.55873)
		(size 0.508)
		(drill 0.254)
		(layers "F.Cu" "B.Cu")
		(net "PVCCD_HV_CPU1")
	)
	(via
		(at 68.32473 -166.38397)
		(size 0.508)
		(drill 0.254)
		(layers "F.Cu" "B.Cu")
		(net "PVCCD_HV_CPU1")
	)
	(via
		(at 113.049812 -218.692222)
		(size 0.4572)
		(drill 0.2032)
		(layers "F.Cu" "B.Cu")
		(net "PVCCD_HV_CPU1")
	)
	(via
		(at 63.97117 -166.94531)
		(size 0.508)
		(drill 0.254)
		(layers "F.Cu" "B.Cu")
		(net "PVCCD_HV_CPU1")
	)
	(via
		(at 68.33235 -161.92373)
		(size 0.508)
		(drill 0.254)
		(layers "F.Cu" "B.Cu")
		(net "PVCCD_HV_CPU1")
	)
	(via
		(at 121.978166 -240.667286)
		(size 0.4572)
		(drill 0.2032)
		(layers "F.Cu" "B.Cu")
		(net "PVCCD_HV_CPU1")
	)
	(via
		(at 121.617994 -257.98907)
		(size 0.4572)
		(drill 0.2032)
		(layers "F.Cu" "B.Cu")
		(net "PVCCD_HV_CPU1")
	)
	(via
		(at 28.073858 -192.752726)
		(size 0.508)
		(drill 0.254)
		(layers "F.Cu" "B.Cu")
		(net "PVCCD_HV_CPU1")
	)
	(via
		(at 121.508012 -241.481102)
		(size 0.4572)
		(drill 0.2032)
		(layers "F.Cu" "B.Cu")
		(net "PVCCD_HV_CPU1")
	)
	(via
		(at 102.35184 -258.80314)
		(size 0.4572)
		(drill 0.2032)
		(layers "F.Cu" "B.Cu")
		(net "PVCCD_HV_CPU1")
	)
	(via
		(at 63.97879 -163.27247)
		(size 0.508)
		(drill 0.254)
		(layers "F.Cu" "B.Cu")
		(net "PVCCD_HV_CPU1")
	)
	(via
		(at 67.04711 -167.66921)
		(size 0.508)
		(drill 0.254)
		(layers "F.Cu" "B.Cu")
		(net "PVCCD_HV_CPU1")
	)
	(via
		(at 68.33235 -162.55873)
		(size 0.508)
		(drill 0.254)
		(layers "F.Cu" "B.Cu")
		(net "PVCCD_HV_CPU1")
	)
	(via
		(at 105.531412 -215.436704)
		(size 0.4572)
		(drill 0.2032)
		(layers "F.Cu" "B.Cu")
		(net "PVCCD_HV_CPU1")
	)
	(via
		(at 65.24879 -163.27247)
		(size 0.508)
		(drill 0.254)
		(layers "F.Cu" "B.Cu")
		(net "PVCCD_HV_CPU1")
	)
	(via
		(at 103.651812 -218.692222)
		(size 0.4572)
		(drill 0.2032)
		(layers "F.Cu" "B.Cu")
		(net "PVCCD_HV_CPU1")
	)
	(via
		(at 67.05473 -163.84397)
		(size 0.508)
		(drill 0.254)
		(layers "F.Cu" "B.Cu")
		(net "PVCCD_HV_CPU1")
	)
	(via
		(at 101.882194 -259.616956)
		(size 0.4572)
		(drill 0.2032)
		(layers "F.Cu" "B.Cu")
		(net "PVCCD_HV_CPU1")
	)
	(via
		(at 119.101616 -246.6594)
		(size 0.4572)
		(drill 0.2032)
		(layers "F.Cu" "B.Cu")
		(net "PVCCD_HV_CPU1")
	)
	(via
		(at 101.412548 -260.430772)
		(size 0.4572)
		(drill 0.2032)
		(layers "F.Cu" "B.Cu")
		(net "PVCCD_HV_CPU1")
	)
	(via
		(at 38.322758 -192.524126)
		(size 0.508)
		(drill 0.254)
		(layers "F.Cu" "B.Cu")
		(net "PVCCD_HV_CPU1")
	)
	(via
		(at 66.42735 -162.55873)
		(size 0.508)
		(drill 0.254)
		(layers "F.Cu" "B.Cu")
		(net "PVCCD_HV_CPU1")
	)
	(via
		(at 68.31711 -167.66921)
		(size 0.508)
		(drill 0.254)
		(layers "F.Cu" "B.Cu")
		(net "PVCCD_HV_CPU1")
	)
	(via
		(at 104.56799 -246.6594)
		(size 0.4572)
		(drill 0.2032)
		(layers "F.Cu" "B.Cu")
		(net "PVCCD_HV_CPU1")
	)
	(via
		(at 64.780922 -168.86428)
		(size 0.508)
		(drill 0.254)
		(layers "F.Cu" "B.Cu")
		(net "PVCCD_HV_CPU1")
	)
	(via
		(at 109.290612 -218.692222)
		(size 0.4572)
		(drill 0.2032)
		(layers "F.Cu" "B.Cu")
		(net "PVCCD_HV_CPU1")
	)
	(via
		(at 68.32473 -163.84397)
		(size 0.508)
		(drill 0.254)
		(layers "F.Cu" "B.Cu")
		(net "PVCCD_HV_CPU1")
	)
	(via
		(at 103.39959 -246.6594)
		(size 0.4572)
		(drill 0.2032)
		(layers "F.Cu" "B.Cu")
		(net "PVCCD_HV_CPU1")
	)
	(arc
		(start 101.412294 -259.894832)
		(mid 101.412357 -260.162802)
		(end 101.412548 -260.430772)
		(width 0.254)
		(layer "F.Cu")
		(net "PVCCD_HV_CPU1")
	)
	(arc
		(start 102.352094 -259.894832)
		(mid 102.352157 -260.162802)
		(end 102.352348 -260.430772)
		(width 0.254)
		(layer "F.Cu")
		(net "PVCCD_HV_CPU1")
	)
	(segment
		(start 51.393852 -161.733484)
		(end 51.444652 -161.682684)
		(width 0.254)
		(layer "B.Cu")
		(net "PVCCD_HV_CPU1")
	)
	(segment
		(start 37.599366 -192.524126)
		(end 38.322758 -192.524126)
		(width 0.381)
		(layer "B.Cu")
		(net "PVCCD_HV_CPU1")
	)
	(segment
		(start 69.923406 -166.634922)
		(end 70.863714 -167.57523)
		(width 0.508)
		(layer "B.Cu")
		(net "PVCCD_HV_CPU1")
	)
	(segment
		(start 51.922934 -161.272728)
		(end 51.935634 -161.260028)
		(width 0.254)
		(layer "B.Cu")
		(net "PVCCD_HV_CPU1")
	)
	(segment
		(start 68.644008 -171.77004)
		(end 69.584316 -170.829732)
		(width 0.508)
		(layer "B.Cu")
		(net "PVCCD_HV_CPU1")
	)
	(segment
		(start 169.647108 -192.75171)
		(end 169.506138 -192.61074)
		(width 0.381)
		(layer "B.Cu")
		(net "PVCCD_HV_CPU1")
	)
	(segment
		(start 189.232286 -189.73673)
		(end 189.232286 -193.215006)
		(width 0.381)
		(layer "B.Cu")
		(net "PVCCD_HV_CPU1")
	)
	(segment
		(start 186.813698 -189.586616)
		(end 186.813698 -190.61557)
		(width 0.381)
		(layer "B.Cu")
		(net "PVCCD_HV_CPU1")
	)
	(segment
		(start 187.352686 -189.047628)
		(end 186.813698 -189.586616)
		(width 0.381)
		(layer "B.Cu")
		(net "PVCCD_HV_CPU1")
	)
	(segment
		(start 189.112652 -189.617096)
		(end 189.232286 -189.73673)
		(width 0.381)
		(layer "B.Cu")
		(net "PVCCD_HV_CPU1")
	)
	(segment
		(start 69.923406 -166.634922)
		(end 70.863714 -165.694614)
		(width 0.508)
		(layer "B.Cu")
		(net "PVCCD_HV_CPU1")
	)
	(segment
		(start 170.123612 -193.021966)
		(end 169.853356 -192.75171)
		(width 0.381)
		(layer "B.Cu")
		(net "PVCCD_HV_CPU1")
	)
	(segment
		(start 68.983098 -167.57523)
		(end 69.923406 -166.634922)
		(width 0.508)
		(layer "B.Cu")
		(net "PVCCD_HV_CPU1")
	)
	(segment
		(start 68.644008 -171.77004)
		(end 68.235322 -173.035468)
		(width 0.508)
		(layer "B.Cu")
		(net "PVCCD_HV_CPU1")
	)
	(segment
		(start 64.276478 -191.85763)
		(end 63.616078 -192.51803)
		(width 0.381)
		(layer "B.Cu")
		(net "PVCCD_HV_CPU1")
	)
	(segment
		(start 64.637158 -192.21831)
		(end 64.276478 -191.85763)
		(width 0.381)
		(layer "B.Cu")
		(net "PVCCD_HV_CPU1")
	)
	(segment
		(start 51.444652 -161.682684)
		(end 51.595782 -161.682684)
		(width 0.254)
		(layer "B.Cu")
		(net "PVCCD_HV_CPU1")
	)
	(segment
		(start 63.616078 -192.51803)
		(end 63.616078 -192.53454)
		(width 0.381)
		(layer "B.Cu")
		(net "PVCCD_HV_CPU1")
	)
	(segment
		(start 51.595782 -161.682684)
		(end 51.922934 -161.355532)
		(width 0.254)
		(layer "B.Cu")
		(net "PVCCD_HV_CPU1")
	)
	(segment
		(start 170.824398 -192.62598)
		(end 170.519598 -192.62598)
		(width 0.381)
		(layer "B.Cu")
		(net "PVCCD_HV_CPU1")
	)
	(segment
		(start 169.853356 -192.75171)
		(end 169.647108 -192.75171)
		(width 0.381)
		(layer "B.Cu")
		(net "PVCCD_HV_CPU1")
	)
	(segment
		(start 170.519598 -192.62598)
		(end 170.123612 -193.021966)
		(width 0.381)
		(layer "B.Cu")
		(net "PVCCD_HV_CPU1")
	)
	(segment
		(start 186.813698 -190.61557)
		(end 185.142886 -192.286382)
		(width 0.381)
		(layer "B.Cu")
		(net "PVCCD_HV_CPU1")
	)
	(segment
		(start 28.073858 -192.752726)
		(end 27.375866 -192.752726)
		(width 0.3556)
		(layer "B.Cu")
		(net "PVCCD_HV_CPU1")
	)
	(segment
		(start 185.142886 -192.286382)
		(end 185.142886 -193.199766)
		(width 0.381)
		(layer "B.Cu")
		(net "PVCCD_HV_CPU1")
	)
	(segment
		(start 64.637158 -192.56248)
		(end 64.637158 -192.21831)
		(width 0.381)
		(layer "B.Cu")
		(net "PVCCD_HV_CPU1")
	)
	(segment
		(start 68.983098 -165.694614)
		(end 69.923406 -166.634922)
		(width 0.508)
		(layer "B.Cu")
		(net "PVCCD_HV_CPU1")
	)
	(segment
		(start 51.922934 -161.355532)
		(end 51.922934 -161.272728)
		(width 0.254)
		(layer "B.Cu")
		(net "PVCCD_HV_CPU1")
	)
	(segment
		(start 67.7037 -170.829732)
		(end 68.644008 -171.77004)
		(width 0.508)
		(layer "B.Cu")
		(net "PVCCD_HV_CPU1")
	)
	(segment
		(start 68.644008 -171.77004)
		(end 69.584316 -172.710348)
		(width 0.508)
		(layer "B.Cu")
		(net "PVCCD_HV_CPU1")
	)
	(segment
		(start 170.202352 -192.943226)
		(end 170.123612 -193.021966)
		(width 0.508)
		(layer "In2.Cu")
		(net "PVCCD_HV_CPU1")
	)
	(segment
		(start 59.7408 -162.829748)
		(end 59.1312 -162.220148)
		(width 0.381)
		(layer "In2.Cu")
		(net "PVCCD_HV_CPU1")
	)
	(segment
		(start 187.352686 -190.751968)
		(end 185.93689 -192.167764)
		(width 0.508)
		(layer "In2.Cu")
		(net "PVCCD_HV_CPU1")
	)
	(segment
		(start 63.412878 -163.19627)
		(end 63.3984 -163.210748)
		(width 0.381)
		(layer "In2.Cu")
		(net "PVCCD_HV_CPU1")
	)
	(segment
		(start 52.548536 -161.733484)
		(end 51.393852 -161.733484)
		(width 0.381)
		(layer "In2.Cu")
		(net "PVCCD_HV_CPU1")
	)
	(segment
		(start 187.922154 -189.617096)
		(end 187.352686 -189.047628)
		(width 0.508)
		(layer "In2.Cu")
		(net "PVCCD_HV_CPU1")
	)
	(segment
		(start 63.90259 -163.19627)
		(end 63.412878 -163.19627)
		(width 0.381)
		(layer "In2.Cu")
		(net "PVCCD_HV_CPU1")
	)
	(segment
		(start 172.524166 -192.943226)
		(end 170.202352 -192.943226)
		(width 0.508)
		(layer "In2.Cu")
		(net "PVCCD_HV_CPU1")
	)
	(segment
		(start 63.3984 -163.210748)
		(end 63.0174 -162.829748)
		(width 0.381)
		(layer "In2.Cu")
		(net "PVCCD_HV_CPU1")
	)
	(segment
		(start 63.0174 -162.829748)
		(end 59.7408 -162.829748)
		(width 0.381)
		(layer "In2.Cu")
		(net "PVCCD_HV_CPU1")
	)
	(segment
		(start 189.112652 -189.617096)
		(end 187.922154 -189.617096)
		(width 0.508)
		(layer "In2.Cu")
		(net "PVCCD_HV_CPU1")
	)
	(segment
		(start 63.97879 -163.27247)
		(end 63.90259 -163.19627)
		(width 0.381)
		(layer "In2.Cu")
		(net "PVCCD_HV_CPU1")
	)
	(segment
		(start 185.93689 -192.167764)
		(end 173.299628 -192.167764)
		(width 0.508)
		(layer "In2.Cu")
		(net "PVCCD_HV_CPU1")
	)
	(segment
		(start 53.0352 -162.220148)
		(end 52.548536 -161.733484)
		(width 0.381)
		(layer "In2.Cu")
		(net "PVCCD_HV_CPU1")
	)
	(segment
		(start 173.299628 -192.167764)
		(end 172.524166 -192.943226)
		(width 0.508)
		(layer "In2.Cu")
		(net "PVCCD_HV_CPU1")
	)
	(segment
		(start 187.352686 -189.047628)
		(end 187.352686 -190.751968)
		(width 0.508)
		(layer "In2.Cu")
		(net "PVCCD_HV_CPU1")
	)
	(segment
		(start 59.1312 -162.220148)
		(end 53.0352 -162.220148)
		(width 0.381)
		(layer "In2.Cu")
		(net "PVCCD_HV_CPU1")
	)
	(segment
		(start 28.073858 -192.595246)
		(end 28.073858 -192.752726)
		(width 0.508)
		(layer "In4.Cu")
		(net "PVCCD_HV_CPU1")
	)
	(segment
		(start 43.25874 -191.186562)
		(end 41.921176 -192.524126)
		(width 0.508)
		(layer "In4.Cu")
		(net "PVCCD_HV_CPU1")
	)
	(segment
		(start 60.57773 -168.981628)
		(end 59.8424 -169.716958)
		(width 0.508)
		(layer "In4.Cu")
		(net "PVCCD_HV_CPU1")
	)
	(segment
		(start 36.98367 -191.185038)
		(end 29.484066 -191.185038)
		(width 0.508)
		(layer "In4.Cu")
		(net "PVCCD_HV_CPU1")
	)
	(segment
		(start 59.8424 -169.716958)
		(end 59.8424 -179.451254)
		(width 0.508)
		(layer "In4.Cu")
		(net "PVCCD_HV_CPU1")
	)
	(segment
		(start 38.322758 -192.524126)
		(end 36.98367 -191.185038)
		(width 0.508)
		(layer "In4.Cu")
		(net "PVCCD_HV_CPU1")
	)
	(segment
		(start 61.869574 -168.981628)
		(end 60.57773 -168.981628)
		(width 0.508)
		(layer "In4.Cu")
		(net "PVCCD_HV_CPU1")
	)
	(segment
		(start 29.484066 -191.185038)
		(end 28.073858 -192.595246)
		(width 0.508)
		(layer "In4.Cu")
		(net "PVCCD_HV_CPU1")
	)
	(segment
		(start 41.921176 -192.524126)
		(end 38.322758 -192.524126)
		(width 0.508)
		(layer "In4.Cu")
		(net "PVCCD_HV_CPU1")
	)
	(segment
		(start 56.400446 -182.893208)
		(end 46.297596 -182.893208)
		(width 0.508)
		(layer "In4.Cu")
		(net "PVCCD_HV_CPU1")
	)
	(segment
		(start 46.297596 -182.893208)
		(end 43.25874 -185.932064)
		(width 0.508)
		(layer "In4.Cu")
		(net "PVCCD_HV_CPU1")
	)
	(segment
		(start 64.780922 -168.86428)
		(end 61.986922 -168.86428)
		(width 0.508)
		(layer "In4.Cu")
		(net "PVCCD_HV_CPU1")
	)
	(segment
		(start 59.8424 -179.451254)
		(end 56.400446 -182.893208)
		(width 0.508)
		(layer "In4.Cu")
		(net "PVCCD_HV_CPU1")
	)
	(segment
		(start 43.25874 -185.932064)
		(end 43.25874 -191.186562)
		(width 0.508)
		(layer "In4.Cu")
		(net "PVCCD_HV_CPU1")
	)
	(segment
		(start 61.986922 -168.86428)
		(end 61.869574 -168.981628)
		(width 0.508)
		(layer "In4.Cu")
		(net "PVCCD_HV_CPU1")
	)
	(segment
		(start 69.923406 -166.634922)
		(end 70.639178 -167.350694)
		(width 0.508)
		(layer "In13.Cu")
		(net "PVCCD_HV_CPU1")
	)
	(segment
		(start 67.928236 -171.054268)
		(end 68.644008 -171.77004)
		(width 0.508)
		(layer "In13.Cu")
		(net "PVCCD_HV_CPU1")
	)
	(segment
		(start 68.644008 -171.77004)
		(end 69.35978 -171.054268)
		(width 0.508)
		(layer "In13.Cu")
		(net "PVCCD_HV_CPU1")
	)
	(segment
		(start 69.207634 -165.91915)
		(end 69.923406 -166.634922)
		(width 0.508)
		(layer "In13.Cu")
		(net "PVCCD_HV_CPU1")
	)
	(segment
		(start 69.923406 -166.634922)
		(end 70.639178 -165.91915)
		(width 0.508)
		(layer "In13.Cu")
		(net "PVCCD_HV_CPU1")
	)
	(segment
		(start 68.644008 -171.77004)
		(end 69.35978 -172.485812)
		(width 0.508)
		(layer "In13.Cu")
		(net "PVCCD_HV_CPU1")
	)
	(segment
		(start 69.207634 -167.350694)
		(end 69.923406 -166.634922)
		(width 0.508)
		(layer "In13.Cu")
		(net "PVCCD_HV_CPU1")
	)
	(segment
		(start 419.856412 -165.018974)
		(end 419.013386 -164.175948)
		(width 0.254)
		(layer "F.Cu")
		(net "PVCCD_HV_CPU0_VREF")
	)
	(segment
		(start 419.013386 -164.175948)
		(end 418.9095 -164.175948)
		(width 0.254)
		(layer "F.Cu")
		(net "PVCCD_HV_CPU0_VREF")
	)
	(segment
		(start 420.191438 -164.503354)
		(end 420.191438 -165.018974)
		(width 0.254)
		(layer "F.Cu")
		(net "PVCCD_HV_CPU0_VREF")
	)
	(segment
		(start 420.531798 -164.162994)
		(end 420.191438 -164.503354)
		(width 0.254)
		(layer "F.Cu")
		(net "PVCCD_HV_CPU0_VREF")
	)
	(segment
		(start 427.181518 -125.80366)
		(end 427.826424 -125.80366)
		(width 0.254)
		(layer "F.Cu")
		(net "PVCCD_HV_CPU0_VREF")
	)
	(segment
		(start 420.191438 -165.018974)
		(end 419.856412 -165.018974)
		(width 0.254)
		(layer "F.Cu")
		(net "PVCCD_HV_CPU0_VREF")
	)
	(via
		(at 430.081944 -120.0531)
		(size 0.508)
		(drill 0.254)
		(layers "F.Cu" "B.Cu")
		(net "PVCCD_HV_CPU0_VREF")
	)
	(via
		(at 427.181518 -125.80366)
		(size 0.508)
		(drill 0.254)
		(layers "F.Cu" "B.Cu")
		(net "PVCCD_HV_CPU0_VREF")
	)
	(via
		(at 420.531798 -164.162994)
		(size 0.508)
		(drill 0.254)
		(layers "F.Cu" "B.Cu")
		(net "PVCCD_HV_CPU0_VREF")
	)
	(segment
		(start 416.68954 -143.779748)
		(end 426.257212 -143.779748)
		(width 0.254)
		(layer "In6.Cu")
		(net "PVCCD_HV_CPU0_VREF")
	)
	(segment
		(start 423.037 -163.436808)
		(end 421.250364 -163.436808)
		(width 0.254)
		(layer "In6.Cu")
		(net "PVCCD_HV_CPU0_VREF")
	)
	(segment
		(start 421.230552 -128.895348)
		(end 415.24682 -134.87908)
		(width 0.254)
		(layer "In6.Cu")
		(net "PVCCD_HV_CPU0_VREF")
	)
	(segment
		(start 415.24682 -134.87908)
		(end 415.24682 -142.337028)
		(width 0.254)
		(layer "In6.Cu")
		(net "PVCCD_HV_CPU0_VREF")
	)
	(segment
		(start 428.70628 -146.228816)
		(end 428.70628 -153.69032)
		(width 0.254)
		(layer "In6.Cu")
		(net "PVCCD_HV_CPU0_VREF")
	)
	(segment
		(start 425.15282 -157.24378)
		(end 425.15282 -161.320988)
		(width 0.254)
		(layer "In6.Cu")
		(net "PVCCD_HV_CPU0_VREF")
	)
	(segment
		(start 421.250364 -163.436808)
		(end 420.531798 -164.155374)
		(width 0.254)
		(layer "In6.Cu")
		(net "PVCCD_HV_CPU0_VREF")
	)
	(segment
		(start 428.70628 -153.69032)
		(end 425.15282 -157.24378)
		(width 0.254)
		(layer "In6.Cu")
		(net "PVCCD_HV_CPU0_VREF")
	)
	(segment
		(start 428.7012 -128.895348)
		(end 421.230552 -128.895348)
		(width 0.254)
		(layer "In6.Cu")
		(net "PVCCD_HV_CPU0_VREF")
	)
	(segment
		(start 420.531798 -164.155374)
		(end 420.531798 -164.162994)
		(width 0.254)
		(layer "In6.Cu")
		(net "PVCCD_HV_CPU0_VREF")
	)
	(segment
		(start 426.257212 -143.779748)
		(end 428.70628 -146.228816)
		(width 0.254)
		(layer "In6.Cu")
		(net "PVCCD_HV_CPU0_VREF")
	)
	(segment
		(start 415.24682 -142.337028)
		(end 416.68954 -143.779748)
		(width 0.254)
		(layer "In6.Cu")
		(net "PVCCD_HV_CPU0_VREF")
	)
	(segment
		(start 425.15282 -161.320988)
		(end 423.037 -163.436808)
		(width 0.254)
		(layer "In6.Cu")
		(net "PVCCD_HV_CPU0_VREF")
	)
	(segment
		(start 417.469828 -165.760654)
		(end 418.085778 -165.760654)
		(width 0.2286)
		(layer "F.Cu")
		(net "PVCCD_HV_CPU0_VDD1")
	)
	(segment
		(start 417.384484 -164.974016)
		(end 417.384484 -164.585904)
		(width 0.2032)
		(layer "F.Cu")
		(net "PVCCD_HV_CPU0_VDD1")
	)
	(segment
		(start 418.085778 -165.760654)
		(end 418.085778 -165.67531)
		(width 0.2032)
		(layer "F.Cu")
		(net "PVCCD_HV_CPU0_VDD1")
	)
	(segment
		(start 419.621462 -162.37585)
		(end 418.9095 -162.37585)
		(width 0.2286)
		(layer "F.Cu")
		(net "PVCCD_HV_CPU0_VDD1")
	)
	(segment
		(start 419.697154 -162.451542)
		(end 419.621462 -162.37585)
		(width 0.2286)
		(layer "F.Cu")
		(net "PVCCD_HV_CPU0_VDD1")
	)
	(segment
		(start 418.085778 -165.67531)
		(end 417.384484 -164.974016)
		(width 0.2032)
		(layer "F.Cu")
		(net "PVCCD_HV_CPU0_VDD1")
	)
	(via
		(at 419.697154 -162.451542)
		(size 0.508)
		(drill 0.254)
		(layers "F.Cu" "B.Cu")
		(net "PVCCD_HV_CPU0_VDD1")
	)
	(via
		(at 417.469828 -165.760654)
		(size 0.508)
		(drill 0.254)
		(layers "F.Cu" "B.Cu")
		(net "PVCCD_HV_CPU0_VDD1")
	)
	(via
		(at 418.775388 -163.985702)
		(size 0.6604)
		(drill 0.3302)
		(layers "F.Cu" "B.Cu")
		(net "PVCCD_HV_CPU0_VDD1")
	)
	(segment
		(start 417.469828 -165.760654)
		(end 417.396676 -165.687502)
		(width 0.2286)
		(layer "B.Cu")
		(net "PVCCD_HV_CPU0_VDD1")
	)
	(segment
		(start 419.078918 -163.069778)
		(end 419.078918 -163.682172)
		(width 0.2286)
		(layer "B.Cu")
		(net "PVCCD_HV_CPU0_VDD1")
	)
	(segment
		(start 418.775388 -163.985702)
		(end 418.395658 -164.365432)
		(width 0.2286)
		(layer "B.Cu")
		(net "PVCCD_HV_CPU0_VDD1")
	)
	(segment
		(start 417.396676 -165.687502)
		(end 417.396676 -164.582602)
		(width 0.2286)
		(layer "B.Cu")
		(net "PVCCD_HV_CPU0_VDD1")
	)
	(segment
		(start 417.613846 -164.365432)
		(end 417.396676 -164.582602)
		(width 0.2286)
		(layer "B.Cu")
		(net "PVCCD_HV_CPU0_VDD1")
	)
	(segment
		(start 419.697154 -162.451542)
		(end 419.078918 -163.069778)
		(width 0.2286)
		(layer "B.Cu")
		(net "PVCCD_HV_CPU0_VDD1")
	)
	(segment
		(start 419.078918 -163.682172)
		(end 418.775388 -163.985702)
		(width 0.2286)
		(layer "B.Cu")
		(net "PVCCD_HV_CPU0_VDD1")
	)
	(segment
		(start 418.395658 -164.365432)
		(end 417.613846 -164.365432)
		(width 0.2286)
		(layer "B.Cu")
		(net "PVCCD_HV_CPU0_VDD1")
	)
	(segment
		(start 429.02378 -120.365012)
		(end 429.02378 -120.856248)
		(width 0.1778)
		(layer "F.Cu")
		(net "PVCCD_HV_CPU0_VCC")
	)
	(segment
		(start 429.02378 -118.35511)
		(end 429.03013 -118.34876)
		(width 0.1778)
		(layer "F.Cu")
		(net "PVCCD_HV_CPU0_VCC")
	)
	(segment
		(start 429.03013 -118.34876)
		(end 429.03013 -117.51056)
		(width 0.1778)
		(layer "F.Cu")
		(net "PVCCD_HV_CPU0_VCC")
	)
	(segment
		(start 429.756062 -121.58853)
		(end 430.100994 -121.58853)
		(width 0.1778)
		(layer "F.Cu")
		(net "PVCCD_HV_CPU0_VCC")
	)
	(segment
		(start 429.02378 -120.856248)
		(end 429.756062 -121.58853)
		(width 0.1778)
		(layer "F.Cu")
		(net "PVCCD_HV_CPU0_VCC")
	)
	(segment
		(start 429.02378 -120.365012)
		(end 429.02378 -119.349012)
		(width 0.1778)
		(layer "F.Cu")
		(net "PVCCD_HV_CPU0_VCC")
	)
	(segment
		(start 429.02378 -119.349012)
		(end 429.02378 -118.35511)
		(width 0.1778)
		(layer "F.Cu")
		(net "PVCCD_HV_CPU0_VCC")
	)
	(via
		(at 429.03013 -117.51056)
		(size 0.508)
		(drill 0.254)
		(layers "F.Cu" "B.Cu")
		(net "PVCCD_HV_CPU0_VCC")
	)
	(segment
		(start 429.070008 -117.550438)
		(end 429.070008 -118.6053)
		(width 0.4572)
		(layer "B.Cu")
		(net "PVCCD_HV_CPU0_VCC")
	)
	(segment
		(start 429.03013 -117.51056)
		(end 429.070008 -117.550438)
		(width 0.4572)
		(layer "B.Cu")
		(net "PVCCD_HV_CPU0_VCC")
	)
	(segment
		(start 435.901592 -122.86488)
		(end 435.825392 -122.78868)
		(width 0.1778)
		(layer "F.Cu")
		(net "PVCCD_HV_CPU0_PIN_ALT")
	)
	(segment
		(start 436.842916 -122.648726)
		(end 436.626762 -122.86488)
		(width 0.1778)
		(layer "F.Cu")
		(net "PVCCD_HV_CPU0_PIN_ALT")
	)
	(segment
		(start 435.825392 -122.78868)
		(end 434.901086 -122.78868)
		(width 0.1778)
		(layer "F.Cu")
		(net "PVCCD_HV_CPU0_PIN_ALT")
	)
	(segment
		(start 436.626762 -122.86488)
		(end 435.901592 -122.86488)
		(width 0.1778)
		(layer "F.Cu")
		(net "PVCCD_HV_CPU0_PIN_ALT")
	)
	(via
		(at 435.901592 -122.86488)
		(size 0.508)
		(drill 0.254)
		(layers "F.Cu" "B.Cu")
		(net "PVCCD_HV_CPU0_PIN_ALT")
	)
	(segment
		(start 442.525658 -345.71305)
		(end 440.930538 -344.11793)
		(width 0.254)
		(layer "F.Cu")
		(net "PVCCD_HV_CPU0_NVDIMM_ISENSE")
	)
	(segment
		(start 454.481946 -343.525602)
		(end 452.294498 -345.71305)
		(width 0.254)
		(layer "F.Cu")
		(net "PVCCD_HV_CPU0_NVDIMM_ISENSE")
	)
	(segment
		(start 441.224416 -334.271112)
		(end 442.739526 -334.271112)
		(width 0.254)
		(layer "F.Cu")
		(net "PVCCD_HV_CPU0_NVDIMM_ISENSE")
	)
	(segment
		(start 452.294498 -345.71305)
		(end 442.525658 -345.71305)
		(width 0.254)
		(layer "F.Cu")
		(net "PVCCD_HV_CPU0_NVDIMM_ISENSE")
	)
	(segment
		(start 460.892398 -335.81467)
		(end 454.481946 -342.225122)
		(width 0.254)
		(layer "F.Cu")
		(net "PVCCD_HV_CPU0_NVDIMM_ISENSE")
	)
	(segment
		(start 454.481946 -342.225122)
		(end 454.481946 -343.525602)
		(width 0.254)
		(layer "F.Cu")
		(net "PVCCD_HV_CPU0_NVDIMM_ISENSE")
	)
	(segment
		(start 440.930538 -344.11793)
		(end 440.930538 -334.56499)
		(width 0.254)
		(layer "F.Cu")
		(net "PVCCD_HV_CPU0_NVDIMM_ISENSE")
	)
	(segment
		(start 440.930538 -334.56499)
		(end 441.224416 -334.271112)
		(width 0.254)
		(layer "F.Cu")
		(net "PVCCD_HV_CPU0_NVDIMM_ISENSE")
	)
	(via
		(at 460.892398 -335.81467)
		(size 0.508)
		(drill 0.254)
		(layers "F.Cu" "B.Cu")
		(net "PVCCD_HV_CPU0_NVDIMM_ISENSE")
	)
	(segment
		(start 462.84388 -175.605948)
		(end 462.84388 -186.400948)
		(width 0.254)
		(layer "B.Cu")
		(net "PVCCD_HV_CPU0_NVDIMM_ISENSE")
	)
	(segment
		(start 424.618404 -117.752876)
		(end 428.921164 -113.450116)
		(width 0.254)
		(layer "B.Cu")
		(net "PVCCD_HV_CPU0_NVDIMM_ISENSE")
	)
	(segment
		(start 462.84388 -186.400948)
		(end 466.5599 -190.116968)
		(width 0.254)
		(layer "B.Cu")
		(net "PVCCD_HV_CPU0_NVDIMM_ISENSE")
	)
	(segment
		(start 454.5711 -167.333168)
		(end 462.84388 -175.605948)
		(width 0.254)
		(layer "B.Cu")
		(net "PVCCD_HV_CPU0_NVDIMM_ISENSE")
	)
	(segment
		(start 449.396104 -134.120636)
		(end 454.5711 -139.295632)
		(width 0.254)
		(layer "B.Cu")
		(net "PVCCD_HV_CPU0_NVDIMM_ISENSE")
	)
	(segment
		(start 454.5711 -139.295632)
		(end 454.5711 -167.333168)
		(width 0.254)
		(layer "B.Cu")
		(net "PVCCD_HV_CPU0_NVDIMM_ISENSE")
	)
	(segment
		(start 441.404248 -113.450116)
		(end 449.396104 -121.441972)
		(width 0.254)
		(layer "B.Cu")
		(net "PVCCD_HV_CPU0_NVDIMM_ISENSE")
	)
	(segment
		(start 427.066202 -124.025152)
		(end 425.25315 -124.025152)
		(width 0.254)
		(layer "B.Cu")
		(net "PVCCD_HV_CPU0_NVDIMM_ISENSE")
	)
	(segment
		(start 466.5599 -330.147168)
		(end 460.892398 -335.81467)
		(width 0.254)
		(layer "B.Cu")
		(net "PVCCD_HV_CPU0_NVDIMM_ISENSE")
	)
	(segment
		(start 449.396104 -121.441972)
		(end 449.396104 -134.120636)
		(width 0.254)
		(layer "B.Cu")
		(net "PVCCD_HV_CPU0_NVDIMM_ISENSE")
	)
	(segment
		(start 424.618404 -123.390406)
		(end 424.618404 -117.752876)
		(width 0.254)
		(layer "B.Cu")
		(net "PVCCD_HV_CPU0_NVDIMM_ISENSE")
	)
	(segment
		(start 425.25315 -124.025152)
		(end 424.618404 -123.390406)
		(width 0.254)
		(layer "B.Cu")
		(net "PVCCD_HV_CPU0_NVDIMM_ISENSE")
	)
	(segment
		(start 428.921164 -113.450116)
		(end 441.404248 -113.450116)
		(width 0.254)
		(layer "B.Cu")
		(net "PVCCD_HV_CPU0_NVDIMM_ISENSE")
	)
	(segment
		(start 466.5599 -190.116968)
		(end 466.5599 -330.147168)
		(width 0.254)
		(layer "B.Cu")
		(net "PVCCD_HV_CPU0_NVDIMM_ISENSE")
	)
	(segment
		(start 420.924736 -163.64839)
		(end 420.078916 -163.64839)
		(width 0.12954)
		(layer "F.Cu")
		(net "PVCCD_HV_CPU0_LSET1")
	)
	(segment
		(start 420.078916 -163.64839)
		(end 419.686994 -163.64839)
		(width 0.12954)
		(layer "F.Cu")
		(net "PVCCD_HV_CPU0_LSET1")
	)
	(segment
		(start 421.15359 -163.877244)
		(end 420.924736 -163.64839)
		(width 0.12954)
		(layer "F.Cu")
		(net "PVCCD_HV_CPU0_LSET1")
	)
	(segment
		(start 419.686994 -163.64839)
		(end 419.37178 -163.333176)
		(width 0.12954)
		(layer "F.Cu")
		(net "PVCCD_HV_CPU0_LSET1")
	)
	(segment
		(start 419.37178 -163.333176)
		(end 419.23335 -163.275772)
		(width 0.12954)
		(layer "F.Cu")
		(net "PVCCD_HV_CPU0_LSET1")
	)
	(segment
		(start 419.23335 -163.275772)
		(end 418.9095 -163.275772)
		(width 0.12954)
		(layer "F.Cu")
		(net "PVCCD_HV_CPU0_LSET1")
	)
	(via
		(at 420.078916 -163.64839)
		(size 0.4064)
		(drill 0.2032)
		(layers "F.Cu" "B.Cu")
		(net "PVCCD_HV_CPU0_LSET1")
	)
	(segment
		(start 428.558452 -123.310142)
		(end 429.817784 -122.78868)
		(width 0.1778)
		(layer "F.Cu")
		(net "PVCCD_HV_CPU0_ISYS_R")
	)
	(segment
		(start 428.558452 -123.315984)
		(end 428.558452 -123.310142)
		(width 0.1778)
		(layer "F.Cu")
		(net "PVCCD_HV_CPU0_ISYS_R")
	)
	(segment
		(start 429.817784 -122.78868)
		(end 430.100994 -122.78868)
		(width 0.1778)
		(layer "F.Cu")
		(net "PVCCD_HV_CPU0_ISYS_R")
	)
	(via
		(at 429.036734 -124.025152)
		(size 0.6604)
		(drill 0.3302)
		(layers "F.Cu" "B.Cu")
		(net "PVCCD_HV_CPU0_ISYS_R")
	)
	(via
		(at 428.558452 -123.315984)
		(size 0.508)
		(drill 0.254)
		(layers "F.Cu" "B.Cu")
		(net "PVCCD_HV_CPU0_ISYS_R")
	)
	(segment
		(start 427.866302 -124.025152)
		(end 429.036734 -124.025152)
		(width 0.254)
		(layer "B.Cu")
		(net "PVCCD_HV_CPU0_ISYS_R")
	)
	(segment
		(start 430.177194 -123.849384)
		(end 430.177194 -123.648724)
		(width 0.254)
		(layer "B.Cu")
		(net "PVCCD_HV_CPU0_ISYS_R")
	)
	(segment
		(start 430.177194 -123.488704)
		(end 430.004474 -123.315984)
		(width 0.254)
		(layer "B.Cu")
		(net "PVCCD_HV_CPU0_ISYS_R")
	)
	(segment
		(start 430.004474 -123.315984)
		(end 428.558452 -123.315984)
		(width 0.254)
		(layer "B.Cu")
		(net "PVCCD_HV_CPU0_ISYS_R")
	)
	(segment
		(start 429.036734 -124.025152)
		(end 430.001426 -124.025152)
		(width 0.254)
		(layer "B.Cu")
		(net "PVCCD_HV_CPU0_ISYS_R")
	)
	(segment
		(start 430.001426 -124.025152)
		(end 430.177194 -123.849384)
		(width 0.254)
		(layer "B.Cu")
		(net "PVCCD_HV_CPU0_ISYS_R")
	)
	(segment
		(start 430.177194 -123.648724)
		(end 430.177194 -123.488704)
		(width 0.254)
		(layer "B.Cu")
		(net "PVCCD_HV_CPU0_ISYS_R")
	)
	(segment
		(start 428.626524 -122.62866)
		(end 428.866554 -122.38863)
		(width 0.254)
		(layer "F.Cu")
		(net "PVCCD_HV_CPU0_ISENSE_P")
	)
	(segment
		(start 428.866554 -122.38863)
		(end 429.318166 -122.38863)
		(width 0.254)
		(layer "F.Cu")
		(net "PVCCD_HV_CPU0_ISENSE_P")
	)
	(segment
		(start 429.318166 -122.38863)
		(end 430.100994 -122.38863)
		(width 0.1778)
		(layer "F.Cu")
		(net "PVCCD_HV_CPU0_ISENSE_P")
	)
	(via
		(at 429.318166 -122.38863)
		(size 0.508)
		(drill 0.254)
		(layers "F.Cu" "B.Cu")
		(net "PVCCD_HV_CPU0_ISENSE_P")
	)
	(segment
		(start 430.073054 -122.38863)
		(end 430.180496 -122.281188)
		(width 0.254)
		(layer "B.Cu")
		(net "PVCCD_HV_CPU0_ISENSE_P")
	)
	(segment
		(start 428.164244 -122.485912)
		(end 428.187358 -122.462798)
		(width 0.254)
		(layer "B.Cu")
		(net "PVCCD_HV_CPU0_ISENSE_P")
	)
	(segment
		(start 427.321726 -122.548396)
		(end 427.292262 -122.57786)
		(width 0.254)
		(layer "B.Cu")
		(net "PVCCD_HV_CPU0_ISENSE_P")
	)
	(segment
		(start 429.318166 -122.38863)
		(end 430.073054 -122.38863)
		(width 0.254)
		(layer "B.Cu")
		(net "PVCCD_HV_CPU0_ISENSE_P")
	)
	(segment
		(start 430.180496 -122.281188)
		(end 430.37379 -122.281188)
		(width 0.254)
		(layer "B.Cu")
		(net "PVCCD_HV_CPU0_ISENSE_P")
	)
	(segment
		(start 428.742348 -122.38863)
		(end 429.318166 -122.38863)
		(width 0.254)
		(layer "B.Cu")
		(net "PVCCD_HV_CPU0_ISENSE_P")
	)
	(segment
		(start 428.187358 -122.462798)
		(end 428.66818 -122.462798)
		(width 0.254)
		(layer "B.Cu")
		(net "PVCCD_HV_CPU0_ISENSE_P")
	)
	(segment
		(start 428.10176 -122.548396)
		(end 427.321726 -122.548396)
		(width 0.254)
		(layer "B.Cu")
		(net "PVCCD_HV_CPU0_ISENSE_P")
	)
	(segment
		(start 428.66818 -122.462798)
		(end 428.742348 -122.38863)
		(width 0.254)
		(layer "B.Cu")
		(net "PVCCD_HV_CPU0_ISENSE_P")
	)
	(segment
		(start 428.164244 -122.485912)
		(end 428.10176 -122.548396)
		(width 0.254)
		(layer "B.Cu")
		(net "PVCCD_HV_CPU0_ISENSE_P")
	)
	(segment
		(start 430.100994 -121.98858)
		(end 429.822356 -121.98858)
		(width 0.1778)
		(layer "F.Cu")
		(net "PVCCD_HV_CPU0_ISENSE_N")
	)
	(segment
		(start 429.822356 -121.98858)
		(end 429.429926 -121.82602)
		(width 0.1778)
		(layer "F.Cu")
		(net "PVCCD_HV_CPU0_ISENSE_N")
	)
	(segment
		(start 429.429926 -121.82602)
		(end 429.347122 -121.743216)
		(width 0.1778)
		(layer "F.Cu")
		(net "PVCCD_HV_CPU0_ISENSE_N")
	)
	(segment
		(start 429.347122 -121.743216)
		(end 429.245522 -121.743216)
		(width 0.1778)
		(layer "F.Cu")
		(net "PVCCD_HV_CPU0_ISENSE_N")
	)
	(segment
		(start 428.75708 -121.743216)
		(end 428.626524 -121.61266)
		(width 0.254)
		(layer "F.Cu")
		(net "PVCCD_HV_CPU0_ISENSE_N")
	)
	(segment
		(start 429.245522 -121.743216)
		(end 428.75708 -121.743216)
		(width 0.254)
		(layer "F.Cu")
		(net "PVCCD_HV_CPU0_ISENSE_N")
	)
	(via
		(at 429.245522 -121.743216)
		(size 0.508)
		(drill 0.254)
		(layers "F.Cu" "B.Cu")
		(net "PVCCD_HV_CPU0_ISENSE_N")
	)
	(via
		(at 429.029622 -120.532652)
		(size 0.7112)
		(drill 0.3556)
		(layers "F.Cu" "B.Cu")
		(net "PVCCD_HV_CPU0_ISENSE_N")
	)
	(segment
		(start 429.84801 -121.13641)
		(end 429.63338 -121.13641)
		(width 0.254)
		(layer "B.Cu")
		(net "PVCCD_HV_CPU0_ISENSE_N")
	)
	(segment
		(start 428.164244 -121.685812)
		(end 428.187612 -121.70918)
		(width 0.254)
		(layer "B.Cu")
		(net "PVCCD_HV_CPU0_ISENSE_N")
	)
	(segment
		(start 429.029622 -121.527316)
		(end 429.245522 -121.743216)
		(width 0.254)
		(layer "B.Cu")
		(net "PVCCD_HV_CPU0_ISENSE_N")
	)
	(segment
		(start 429.63338 -121.13641)
		(end 429.029622 -120.532652)
		(width 0.254)
		(layer "B.Cu")
		(net "PVCCD_HV_CPU0_ISENSE_N")
	)
	(segment
		(start 428.187612 -121.70918)
		(end 428.674276 -121.70918)
		(width 0.254)
		(layer "B.Cu")
		(net "PVCCD_HV_CPU0_ISENSE_N")
	)
	(segment
		(start 428.674276 -121.70918)
		(end 428.708312 -121.743216)
		(width 0.254)
		(layer "B.Cu")
		(net "PVCCD_HV_CPU0_ISENSE_N")
	)
	(segment
		(start 429.029622 -120.532652)
		(end 429.029622 -121.527316)
		(width 0.254)
		(layer "B.Cu")
		(net "PVCCD_HV_CPU0_ISENSE_N")
	)
	(segment
		(start 430.186338 -120.798082)
		(end 429.84801 -121.13641)
		(width 0.254)
		(layer "B.Cu")
		(net "PVCCD_HV_CPU0_ISENSE_N")
	)
	(segment
		(start 427.292262 -121.685812)
		(end 428.164244 -121.685812)
		(width 0.254)
		(layer "B.Cu")
		(net "PVCCD_HV_CPU0_ISENSE_N")
	)
	(segment
		(start 428.708312 -121.743216)
		(end 429.245522 -121.743216)
		(width 0.254)
		(layer "B.Cu")
		(net "PVCCD_HV_CPU0_ISENSE_N")
	)
	(segment
		(start 429.552354 -125.394212)
		(end 429.552354 -124.238004)
		(width 0.1778)
		(layer "F.Cu")
		(net "PVCCD_HV_CPU0_FAULT")
	)
	(segment
		(start 429.801782 -123.988576)
		(end 430.100994 -123.988576)
		(width 0.1778)
		(layer "F.Cu")
		(net "PVCCD_HV_CPU0_FAULT")
	)
	(segment
		(start 429.552354 -124.238004)
		(end 429.801782 -123.988576)
		(width 0.1778)
		(layer "F.Cu")
		(net "PVCCD_HV_CPU0_FAULT")
	)
	(via
		(at 429.552354 -125.394212)
		(size 0.508)
		(drill 0.254)
		(layers "F.Cu" "B.Cu")
		(net "PVCCD_HV_CPU0_FAULT")
	)
	(via
		(at 428.387256 -126.38532)
		(size 0.6604)
		(drill 0.3302)
		(layers "F.Cu" "B.Cu")
		(net "PVCCD_HV_CPU0_FAULT")
	)
	(segment
		(start 428.013876 -126.931674)
		(end 428.013876 -127.578866)
		(width 0.254)
		(layer "B.Cu")
		(net "PVCCD_HV_CPU0_FAULT")
	)
	(segment
		(start 428.515018 -126.38532)
		(end 428.387256 -126.38532)
		(width 0.254)
		(layer "B.Cu")
		(net "PVCCD_HV_CPU0_FAULT")
	)
	(segment
		(start 428.387256 -126.38532)
		(end 428.387256 -126.558294)
		(width 0.254)
		(layer "B.Cu")
		(net "PVCCD_HV_CPU0_FAULT")
	)
	(segment
		(start 428.387256 -126.558294)
		(end 428.013876 -126.931674)
		(width 0.254)
		(layer "B.Cu")
		(net "PVCCD_HV_CPU0_FAULT")
	)
	(segment
		(start 429.506126 -125.394212)
		(end 428.515018 -126.38532)
		(width 0.254)
		(layer "B.Cu")
		(net "PVCCD_HV_CPU0_FAULT")
	)
	(segment
		(start 429.552354 -125.394212)
		(end 429.506126 -125.394212)
		(width 0.254)
		(layer "B.Cu")
		(net "PVCCD_HV_CPU0_FAULT")
	)
	(segment
		(start 435.898036 -121.524522)
		(end 435.433978 -121.98858)
		(width 0.12954)
		(layer "F.Cu")
		(net "PVCCD_HV_CPU0_EN_R")
	)
	(segment
		(start 435.433978 -121.98858)
		(end 434.901086 -121.98858)
		(width 0.12954)
		(layer "F.Cu")
		(net "PVCCD_HV_CPU0_EN_R")
	)
	(via
		(at 435.898036 -121.524522)
		(size 0.508)
		(drill 0.254)
		(layers "F.Cu" "B.Cu")
		(net "PVCCD_HV_CPU0_EN_R")
	)
	(via
		(at 435.142132 -121.473722)
		(size 0.6604)
		(drill 0.3302)
		(layers "F.Cu" "B.Cu")
		(net "PVCCD_HV_CPU0_EN_R")
	)
	(segment
		(start 435.898036 -121.562622)
		(end 436.065422 -121.730008)
		(width 0.12954)
		(layer "B.Cu")
		(net "PVCCD_HV_CPU0_EN_R")
	)
	(segment
		(start 435.898036 -121.524522)
		(end 435.898036 -121.562622)
		(width 0.12954)
		(layer "B.Cu")
		(net "PVCCD_HV_CPU0_EN_R")
	)
	(segment
		(start 435.231032 -121.562622)
		(end 435.859936 -121.562622)
		(width 0.12954)
		(layer "B.Cu")
		(net "PVCCD_HV_CPU0_EN_R")
	)
	(segment
		(start 436.065422 -121.730008)
		(end 436.571644 -121.730008)
		(width 0.12954)
		(layer "B.Cu")
		(net "PVCCD_HV_CPU0_EN_R")
	)
	(segment
		(start 435.142132 -121.473722)
		(end 435.231032 -121.562622)
		(width 0.12954)
		(layer "B.Cu")
		(net "PVCCD_HV_CPU0_EN_R")
	)
	(segment
		(start 435.859936 -121.562622)
		(end 435.898036 -121.524522)
		(width 0.12954)
		(layer "B.Cu")
		(net "PVCCD_HV_CPU0_EN_R")
	)
	(segment
		(start 428.626524 -124.333762)
		(end 428.187866 -124.77242)
		(width 0.1778)
		(layer "F.Cu")
		(net "PVCCD_HV_CPU0_ATSEN")
	)
	(segment
		(start 429.255174 -123.39701)
		(end 429.758602 -123.188476)
		(width 0.1778)
		(layer "F.Cu")
		(net "PVCCD_HV_CPU0_ATSEN")
	)
	(segment
		(start 419.943026 -163.131754)
		(end 419.942772 -163.1315)
		(width 0.254)
		(layer "F.Cu")
		(net "PVCCD_HV_CPU0_ATSEN")
	)
	(segment
		(start 428.626524 -124.02566)
		(end 429.255174 -123.39701)
		(width 0.1778)
		(layer "F.Cu")
		(net "PVCCD_HV_CPU0_ATSEN")
	)
	(segment
		(start 428.045626 -124.91466)
		(end 428.187866 -124.77242)
		(width 0.1778)
		(layer "F.Cu")
		(net "PVCCD_HV_CPU0_ATSEN")
	)
	(segment
		(start 428.626524 -124.02566)
		(end 428.626524 -124.333762)
		(width 0.1778)
		(layer "F.Cu")
		(net "PVCCD_HV_CPU0_ATSEN")
	)
	(segment
		(start 419.204648 -162.825938)
		(end 418.9095 -162.825938)
		(width 0.254)
		(layer "F.Cu")
		(net "PVCCD_HV_CPU0_ATSEN")
	)
	(segment
		(start 419.943026 -163.146994)
		(end 419.943026 -163.131754)
		(width 0.254)
		(layer "F.Cu")
		(net "PVCCD_HV_CPU0_ATSEN")
	)
	(segment
		(start 419.942772 -163.1315)
		(end 419.204648 -162.825938)
		(width 0.254)
		(layer "F.Cu")
		(net "PVCCD_HV_CPU0_ATSEN")
	)
	(segment
		(start 427.498002 -124.91466)
		(end 428.045626 -124.91466)
		(width 0.1778)
		(layer "F.Cu")
		(net "PVCCD_HV_CPU0_ATSEN")
	)
	(segment
		(start 429.758602 -123.188476)
		(end 430.100994 -123.188476)
		(width 0.1778)
		(layer "F.Cu")
		(net "PVCCD_HV_CPU0_ATSEN")
	)
	(via
		(at 419.943026 -163.146994)
		(size 0.508)
		(drill 0.254)
		(layers "F.Cu" "B.Cu")
		(net "PVCCD_HV_CPU0_ATSEN")
	)
	(via
		(at 428.187866 -124.77242)
		(size 0.508)
		(drill 0.254)
		(layers "F.Cu" "B.Cu")
		(net "PVCCD_HV_CPU0_ATSEN")
	)
	(segment
		(start 415.544 -144.109948)
		(end 417.576 -146.141948)
		(width 0.254)
		(layer "In11.Cu")
		(net "PVCCD_HV_CPU0_ATSEN")
	)
	(segment
		(start 425.5262 -146.141948)
		(end 426.085 -146.700748)
		(width 0.254)
		(layer "In11.Cu")
		(net "PVCCD_HV_CPU0_ATSEN")
	)
	(segment
		(start 426.085 -154.086306)
		(end 424.997118 -155.174188)
		(width 0.254)
		(layer "In11.Cu")
		(net "PVCCD_HV_CPU0_ATSEN")
	)
	(segment
		(start 417.576 -146.141948)
		(end 425.5262 -146.141948)
		(width 0.254)
		(layer "In11.Cu")
		(net "PVCCD_HV_CPU0_ATSEN")
	)
	(segment
		(start 424.997118 -159.58439)
		(end 421.434514 -163.146994)
		(width 0.254)
		(layer "In11.Cu")
		(net "PVCCD_HV_CPU0_ATSEN")
	)
	(segment
		(start 415.544 -133.898894)
		(end 415.544 -144.109948)
		(width 0.254)
		(layer "In11.Cu")
		(net "PVCCD_HV_CPU0_ATSEN")
	)
	(segment
		(start 428.187866 -124.77242)
		(end 427.670468 -124.255022)
		(width 0.254)
		(layer "In11.Cu")
		(net "PVCCD_HV_CPU0_ATSEN")
	)
	(segment
		(start 426.085 -146.700748)
		(end 426.085 -154.086306)
		(width 0.254)
		(layer "In11.Cu")
		(net "PVCCD_HV_CPU0_ATSEN")
	)
	(segment
		(start 425.187872 -124.255022)
		(end 415.544 -133.898894)
		(width 0.254)
		(layer "In11.Cu")
		(net "PVCCD_HV_CPU0_ATSEN")
	)
	(segment
		(start 427.670468 -124.255022)
		(end 425.187872 -124.255022)
		(width 0.254)
		(layer "In11.Cu")
		(net "PVCCD_HV_CPU0_ATSEN")
	)
	(segment
		(start 421.434514 -163.146994)
		(end 419.943026 -163.146994)
		(width 0.254)
		(layer "In11.Cu")
		(net "PVCCD_HV_CPU0_ATSEN")
	)
	(segment
		(start 424.997118 -155.174188)
		(end 424.997118 -159.58439)
		(width 0.254)
		(layer "In11.Cu")
		(net "PVCCD_HV_CPU0_ATSEN")
	)
	(segment
		(start 420.321486 -162.077654)
		(end 420.194486 -162.025076)
		(width 0.1778)
		(layer "F.Cu")
		(net "PVCCD_HV_CPU0_APWM1")
	)
	(segment
		(start 432.340258 -119.054626)
		(end 433.501038 -120.215406)
		(width 0.1524)
		(layer "F.Cu")
		(net "PVCCD_HV_CPU0_APWM1")
	)
	(segment
		(start 420.194486 -162.025076)
		(end 419.695376 -161.925762)
		(width 0.1778)
		(layer "F.Cu")
		(net "PVCCD_HV_CPU0_APWM1")
	)
	(segment
		(start 419.695376 -161.925762)
		(end 418.9095 -161.925762)
		(width 0.1778)
		(layer "F.Cu")
		(net "PVCCD_HV_CPU0_APWM1")
	)
	(segment
		(start 433.501038 -120.215406)
		(end 433.501038 -120.588532)
		(width 0.1524)
		(layer "F.Cu")
		(net "PVCCD_HV_CPU0_APWM1")
	)
	(via
		(at 432.340258 -119.054626)
		(size 0.508)
		(drill 0.254)
		(layers "F.Cu" "B.Cu")
		(net "PVCCD_HV_CPU0_APWM1")
	)
	(via
		(at 420.321486 -162.077654)
		(size 0.508)
		(drill 0.254)
		(layers "F.Cu" "B.Cu")
		(net "PVCCD_HV_CPU0_APWM1")
	)
	(segment
		(start 432.562 -129.936748)
		(end 431.9524 -129.327148)
		(width 0.254)
		(layer "In2.Cu")
		(net "PVCCD_HV_CPU0_APWM1")
	)
	(segment
		(start 427.6598 -129.327148)
		(end 426.6692 -130.317748)
		(width 0.254)
		(layer "In2.Cu")
		(net "PVCCD_HV_CPU0_APWM1")
	)
	(segment
		(start 434.975 -129.250948)
		(end 433.6542 -129.250948)
		(width 0.254)
		(layer "In2.Cu")
		(net "PVCCD_HV_CPU0_APWM1")
	)
	(segment
		(start 431.9524 -129.327148)
		(end 427.6598 -129.327148)
		(width 0.254)
		(layer "In2.Cu")
		(net "PVCCD_HV_CPU0_APWM1")
	)
	(segment
		(start 433.6542 -129.250948)
		(end 432.9684 -129.936748)
		(width 0.254)
		(layer "In2.Cu")
		(net "PVCCD_HV_CPU0_APWM1")
	)
	(segment
		(start 424.90898 -157.29966)
		(end 420.321486 -161.887154)
		(width 0.254)
		(layer "In2.Cu")
		(net "PVCCD_HV_CPU0_APWM1")
	)
	(segment
		(start 424.73372 -131.562348)
		(end 422.421812 -131.562348)
		(width 0.254)
		(layer "In2.Cu")
		(net "PVCCD_HV_CPU0_APWM1")
	)
	(segment
		(start 420.321486 -161.887154)
		(end 420.321486 -162.077654)
		(width 0.254)
		(layer "In2.Cu")
		(net "PVCCD_HV_CPU0_APWM1")
	)
	(segment
		(start 417.198302 -147.437348)
		(end 423.0878 -147.437348)
		(width 0.254)
		(layer "In2.Cu")
		(net "PVCCD_HV_CPU0_APWM1")
	)
	(segment
		(start 418.748972 -131.562348)
		(end 416.309302 -134.002018)
		(width 0.254)
		(layer "In2.Cu")
		(net "PVCCD_HV_CPU0_APWM1")
	)
	(segment
		(start 432.9684 -129.936748)
		(end 432.562 -129.936748)
		(width 0.254)
		(layer "In2.Cu")
		(net "PVCCD_HV_CPU0_APWM1")
	)
	(segment
		(start 426.6692 -130.317748)
		(end 426.6692 -130.851148)
		(width 0.254)
		(layer "In2.Cu")
		(net "PVCCD_HV_CPU0_APWM1")
	)
	(segment
		(start 433.794662 -117.600222)
		(end 435.483762 -117.600222)
		(width 0.254)
		(layer "In2.Cu")
		(net "PVCCD_HV_CPU0_APWM1")
	)
	(segment
		(start 420.7383 -132.49148)
		(end 419.809168 -131.562348)
		(width 0.254)
		(layer "In2.Cu")
		(net "PVCCD_HV_CPU0_APWM1")
	)
	(segment
		(start 437.13527 -127.090678)
		(end 434.975 -129.250948)
		(width 0.254)
		(layer "In2.Cu")
		(net "PVCCD_HV_CPU0_APWM1")
	)
	(segment
		(start 419.809168 -131.562348)
		(end 418.748972 -131.562348)
		(width 0.254)
		(layer "In2.Cu")
		(net "PVCCD_HV_CPU0_APWM1")
	)
	(segment
		(start 416.309302 -146.548348)
		(end 417.198302 -147.437348)
		(width 0.254)
		(layer "In2.Cu")
		(net "PVCCD_HV_CPU0_APWM1")
	)
	(segment
		(start 435.483762 -117.600222)
		(end 436.31231 -118.42877)
		(width 0.254)
		(layer "In2.Cu")
		(net "PVCCD_HV_CPU0_APWM1")
	)
	(segment
		(start 416.309302 -134.002018)
		(end 416.309302 -146.548348)
		(width 0.254)
		(layer "In2.Cu")
		(net "PVCCD_HV_CPU0_APWM1")
	)
	(segment
		(start 436.31231 -118.42877)
		(end 436.31231 -119.744998)
		(width 0.254)
		(layer "In2.Cu")
		(net "PVCCD_HV_CPU0_APWM1")
	)
	(segment
		(start 426.6692 -130.851148)
		(end 426.12056 -131.399788)
		(width 0.254)
		(layer "In2.Cu")
		(net "PVCCD_HV_CPU0_APWM1")
	)
	(segment
		(start 426.215302 -150.56485)
		(end 426.215302 -152.640792)
		(width 0.254)
		(layer "In2.Cu")
		(net "PVCCD_HV_CPU0_APWM1")
	)
	(segment
		(start 422.421812 -131.562348)
		(end 421.49268 -132.49148)
		(width 0.254)
		(layer "In2.Cu")
		(net "PVCCD_HV_CPU0_APWM1")
	)
	(segment
		(start 436.31231 -119.744998)
		(end 437.13527 -120.567958)
		(width 0.254)
		(layer "In2.Cu")
		(net "PVCCD_HV_CPU0_APWM1")
	)
	(segment
		(start 432.340258 -119.054626)
		(end 433.794662 -117.600222)
		(width 0.254)
		(layer "In2.Cu")
		(net "PVCCD_HV_CPU0_APWM1")
	)
	(segment
		(start 421.49268 -132.49148)
		(end 420.7383 -132.49148)
		(width 0.254)
		(layer "In2.Cu")
		(net "PVCCD_HV_CPU0_APWM1")
	)
	(segment
		(start 424.90898 -153.947114)
		(end 424.90898 -157.29966)
		(width 0.254)
		(layer "In2.Cu")
		(net "PVCCD_HV_CPU0_APWM1")
	)
	(segment
		(start 424.89628 -131.399788)
		(end 424.73372 -131.562348)
		(width 0.254)
		(layer "In2.Cu")
		(net "PVCCD_HV_CPU0_APWM1")
	)
	(segment
		(start 426.215302 -152.640792)
		(end 424.90898 -153.947114)
		(width 0.254)
		(layer "In2.Cu")
		(net "PVCCD_HV_CPU0_APWM1")
	)
	(segment
		(start 423.0878 -147.437348)
		(end 426.215302 -150.56485)
		(width 0.254)
		(layer "In2.Cu")
		(net "PVCCD_HV_CPU0_APWM1")
	)
	(segment
		(start 426.12056 -131.399788)
		(end 424.89628 -131.399788)
		(width 0.254)
		(layer "In2.Cu")
		(net "PVCCD_HV_CPU0_APWM1")
	)
	(segment
		(start 437.13527 -120.567958)
		(end 437.13527 -127.090678)
		(width 0.254)
		(layer "In2.Cu")
		(net "PVCCD_HV_CPU0_APWM1")
	)
	(segment
		(start 428.626524 -125.80366)
		(end 428.626524 -126.81966)
		(width 0.1778)
		(layer "F.Cu")
		(net "PVCCD_HV_CPU0_ADDR")
	)
	(segment
		(start 429.7172 -123.588526)
		(end 430.100994 -123.588526)
		(width 0.1778)
		(layer "F.Cu")
		(net "PVCCD_HV_CPU0_ADDR")
	)
	(segment
		(start 428.626524 -126.81966)
		(end 428.626524 -127.823976)
		(width 0.254)
		(layer "F.Cu")
		(net "PVCCD_HV_CPU0_ADDR")
	)
	(segment
		(start 429.142144 -124.8791)
		(end 429.142144 -124.163582)
		(width 0.1778)
		(layer "F.Cu")
		(net "PVCCD_HV_CPU0_ADDR")
	)
	(segment
		(start 428.626524 -125.39472)
		(end 429.142144 -124.8791)
		(width 0.1778)
		(layer "F.Cu")
		(net "PVCCD_HV_CPU0_ADDR")
	)
	(segment
		(start 428.626524 -125.80366)
		(end 428.626524 -125.39472)
		(width 0.1778)
		(layer "F.Cu")
		(net "PVCCD_HV_CPU0_ADDR")
	)
	(segment
		(start 428.626524 -127.823976)
		(end 428.22749 -128.22301)
		(width 0.254)
		(layer "F.Cu")
		(net "PVCCD_HV_CPU0_ADDR")
	)
	(segment
		(start 429.142144 -124.163582)
		(end 429.7172 -123.588526)
		(width 0.1778)
		(layer "F.Cu")
		(net "PVCCD_HV_CPU0_ADDR")
	)
	(via
		(at 428.22749 -128.22301)
		(size 0.762)
		(drill 0.381)
		(layers "F.Cu" "B.Cu")
		(net "PVCCD_HV_CPU0_ADDR")
	)
	(segment
		(start 419.680898 -164.162994)
		(end 419.243764 -163.72586)
		(width 0.254)
		(layer "F.Cu")
		(net "PVCCD_HV_CPU0_ACSP1")
	)
	(segment
		(start 419.243764 -163.72586)
		(end 418.9095 -163.72586)
		(width 0.254)
		(layer "F.Cu")
		(net "PVCCD_HV_CPU0_ACSP1")
	)
	(segment
		(start 419.755574 -164.162994)
		(end 419.680898 -164.162994)
		(width 0.254)
		(layer "F.Cu")
		(net "PVCCD_HV_CPU0_ACSP1")
	)
	(segment
		(start 433.501038 -126.608586)
		(end 433.501038 -125.388624)
		(width 0.1778)
		(layer "F.Cu")
		(net "PVCCD_HV_CPU0_ACSP1")
	)
	(segment
		(start 433.6288 -126.736348)
		(end 433.501038 -126.608586)
		(width 0.1778)
		(layer "F.Cu")
		(net "PVCCD_HV_CPU0_ACSP1")
	)
	(via
		(at 433.6288 -126.736348)
		(size 0.508)
		(drill 0.254)
		(layers "F.Cu" "B.Cu")
		(net "PVCCD_HV_CPU0_ACSP1")
	)
	(via
		(at 419.755574 -164.162994)
		(size 0.508)
		(drill 0.254)
		(layers "F.Cu" "B.Cu")
		(net "PVCCD_HV_CPU0_ACSP1")
	)
	(segment
		(start 432.056794 -128.740154)
		(end 431.5206 -129.276348)
		(width 0.254)
		(layer "In6.Cu")
		(net "PVCCD_HV_CPU0_ACSP1")
	)
	(segment
		(start 421.79748 -163.817808)
		(end 420.93642 -164.678868)
		(width 0.254)
		(layer "In6.Cu")
		(net "PVCCD_HV_CPU0_ACSP1")
	)
	(segment
		(start 425.53382 -161.478976)
		(end 423.194988 -163.817808)
		(width 0.254)
		(layer "In6.Cu")
		(net "PVCCD_HV_CPU0_ACSP1")
	)
	(segment
		(start 415.62782 -135.037068)
		(end 415.62782 -142.17904)
		(width 0.254)
		(layer "In6.Cu")
		(net "PVCCD_HV_CPU0_ACSP1")
	)
	(segment
		(start 425.53382 -157.401768)
		(end 425.53382 -161.478976)
		(width 0.254)
		(layer "In6.Cu")
		(net "PVCCD_HV_CPU0_ACSP1")
	)
	(segment
		(start 429.08728 -146.070828)
		(end 429.08728 -153.848308)
		(width 0.254)
		(layer "In6.Cu")
		(net "PVCCD_HV_CPU0_ACSP1")
	)
	(segment
		(start 415.62782 -142.17904)
		(end 416.847528 -143.398748)
		(width 0.254)
		(layer "In6.Cu")
		(net "PVCCD_HV_CPU0_ACSP1")
	)
	(segment
		(start 420.271448 -164.678868)
		(end 419.755574 -164.162994)
		(width 0.254)
		(layer "In6.Cu")
		(net "PVCCD_HV_CPU0_ACSP1")
	)
	(segment
		(start 433.6288 -126.736348)
		(end 433.6288 -127.2032)
		(width 0.254)
		(layer "In6.Cu")
		(net "PVCCD_HV_CPU0_ACSP1")
	)
	(segment
		(start 421.38854 -129.276348)
		(end 415.62782 -135.037068)
		(width 0.254)
		(layer "In6.Cu")
		(net "PVCCD_HV_CPU0_ACSP1")
	)
	(segment
		(start 429.08728 -153.848308)
		(end 425.53382 -157.401768)
		(width 0.254)
		(layer "In6.Cu")
		(net "PVCCD_HV_CPU0_ACSP1")
	)
	(segment
		(start 431.5206 -129.276348)
		(end 421.38854 -129.276348)
		(width 0.254)
		(layer "In6.Cu")
		(net "PVCCD_HV_CPU0_ACSP1")
	)
	(segment
		(start 423.194988 -163.817808)
		(end 421.79748 -163.817808)
		(width 0.254)
		(layer "In6.Cu")
		(net "PVCCD_HV_CPU0_ACSP1")
	)
	(segment
		(start 432.403504 -128.740154)
		(end 432.056794 -128.740154)
		(width 0.254)
		(layer "In6.Cu")
		(net "PVCCD_HV_CPU0_ACSP1")
	)
	(segment
		(start 433.6288 -127.2032)
		(end 433.212494 -127.619506)
		(width 0.254)
		(layer "In6.Cu")
		(net "PVCCD_HV_CPU0_ACSP1")
	)
	(segment
		(start 426.4152 -143.398748)
		(end 429.08728 -146.070828)
		(width 0.254)
		(layer "In6.Cu")
		(net "PVCCD_HV_CPU0_ACSP1")
	)
	(segment
		(start 420.93642 -164.678868)
		(end 420.271448 -164.678868)
		(width 0.254)
		(layer "In6.Cu")
		(net "PVCCD_HV_CPU0_ACSP1")
	)
	(segment
		(start 416.847528 -143.398748)
		(end 426.4152 -143.398748)
		(width 0.254)
		(layer "In6.Cu")
		(net "PVCCD_HV_CPU0_ACSP1")
	)
	(segment
		(start 433.212494 -127.619506)
		(end 432.992276 -128.151382)
		(width 0.254)
		(layer "In6.Cu")
		(net "PVCCD_HV_CPU0_ACSP1")
	)
	(segment
		(start 432.992276 -128.151382)
		(end 432.403504 -128.740154)
		(width 0.254)
		(layer "In6.Cu")
		(net "PVCCD_HV_CPU0_ACSP1")
	)
	(segment
		(start 357.230934 -219.228162)
		(end 357.230934 -218.692476)
		(width 0.2032)
		(layer "F.Cu")
		(net "PVCCD_HV_CPU0")
	)
	(segment
		(start 349.712534 -242.017042)
		(end 349.712788 -242.016788)
		(width 0.254)
		(layer "F.Cu")
		(net "PVCCD_HV_CPU0")
	)
	(segment
		(start 349.712534 -218.692476)
		(end 349.71228 -218.692222)
		(width 0.254)
		(layer "F.Cu")
		(net "PVCCD_HV_CPU0")
	)
	(segment
		(start 400.558 -164.785548)
		(end 401.498308 -163.84524)
		(width 0.508)
		(layer "F.Cu")
		(net "PVCCD_HV_CPU0")
	)
	(segment
		(start 353.471734 -221.947994)
		(end 353.47148 -221.94774)
		(width 0.254)
		(layer "F.Cu")
		(net "PVCCD_HV_CPU0")
	)
	(segment
		(start 355.351334 -219.228162)
		(end 355.351334 -218.692476)
		(width 0.254)
		(layer "F.Cu")
		(net "PVCCD_HV_CPU0")
	)
	(segment
		(start 369.44808 -243.644674)
		(end 369.44808 -243.108988)
		(width 0.254)
		(layer "F.Cu")
		(net "PVCCD_HV_CPU0")
	)
	(segment
		(start 353.471734 -218.692476)
		(end 353.47148 -218.692222)
		(width 0.254)
		(layer "F.Cu")
		(net "PVCCD_HV_CPU0")
	)
	(segment
		(start 355.351334 -222.48368)
		(end 355.351334 -221.947994)
		(width 0.254)
		(layer "F.Cu")
		(net "PVCCD_HV_CPU0")
	)
	(segment
		(start 400.558 -158.562548)
		(end 401.498308 -158.562548)
		(width 0.508)
		(layer "F.Cu")
		(net "PVCCD_HV_CPU0")
	)
	(segment
		(start 351.592134 -215.437212)
		(end 351.59188 -215.436958)
		(width 0.254)
		(layer "F.Cu")
		(net "PVCCD_HV_CPU0")
	)
	(segment
		(start 349.71228 -215.436958)
		(end 349.71228 -215.436704)
		(width 0.254)
		(layer "F.Cu")
		(net "PVCCD_HV_CPU0")
	)
	(segment
		(start 369.91798 -242.830858)
		(end 369.918234 -242.830604)
		(width 0.254)
		(layer "F.Cu")
		(net "PVCCD_HV_CPU0")
	)
	(segment
		(start 370.027962 -258.2672)
		(end 370.027962 -258.80314)
		(width 0.254)
		(layer "F.Cu")
		(net "PVCCD_HV_CPU0")
	)
	(segment
		(start 349.712534 -219.228162)
		(end 349.712534 -218.692476)
		(width 0.254)
		(layer "F.Cu")
		(net "PVCCD_HV_CPU0")
	)
	(segment
		(start 357.230934 -218.692476)
		(end 357.23068 -218.692222)
		(width 0.2032)
		(layer "F.Cu")
		(net "PVCCD_HV_CPU0")
	)
	(segment
		(start 351.592134 -218.692476)
		(end 351.59188 -218.692222)
		(width 0.254)
		(layer "F.Cu")
		(net "PVCCD_HV_CPU0")
	)
	(segment
		(start 369.918234 -242.830604)
		(end 369.918234 -242.294918)
		(width 0.254)
		(layer "F.Cu")
		(net "PVCCD_HV_CPU0")
	)
	(segment
		(start 349.712788 -242.016788)
		(end 349.712788 -241.481102)
		(width 0.254)
		(layer "F.Cu")
		(net "PVCCD_HV_CPU0")
	)
	(segment
		(start 360.990134 -218.692476)
		(end 360.98988 -218.692222)
		(width 0.254)
		(layer "F.Cu")
		(net "PVCCD_HV_CPU0")
	)
	(segment
		(start 369.91798 -241.203226)
		(end 369.91798 -240.66754)
		(width 0.254)
		(layer "F.Cu")
		(net "PVCCD_HV_CPU0")
	)
	(segment
		(start 355.351334 -215.972644)
		(end 355.351334 -215.437212)
		(width 0.254)
		(layer "F.Cu")
		(net "PVCCD_HV_CPU0")
	)
	(segment
		(start 399.617692 -163.84524)
		(end 400.558 -164.785548)
		(width 0.508)
		(layer "F.Cu")
		(net "PVCCD_HV_CPU0")
	)
	(segment
		(start 400.558 -164.785548)
		(end 401.498308 -165.725856)
		(width 0.508)
		(layer "F.Cu")
		(net "PVCCD_HV_CPU0")
	)
	(segment
		(start 355.35108 -215.436958)
		(end 355.35108 -215.436704)
		(width 0.254)
		(layer "F.Cu")
		(net "PVCCD_HV_CPU0")
	)
	(segment
		(start 353.471734 -215.436958)
		(end 353.47148 -215.436704)
		(width 0.254)
		(layer "F.Cu")
		(net "PVCCD_HV_CPU0")
	)
	(segment
		(start 362.869734 -219.228162)
		(end 362.869734 -218.692222)
		(width 0.254)
		(layer "F.Cu")
		(net "PVCCD_HV_CPU0")
	)
	(segment
		(start 369.558316 -257.45313)
		(end 369.558062 -257.98907)
		(width 0.254)
		(layer "F.Cu")
		(net "PVCCD_HV_CPU0")
	)
	(segment
		(start 353.471734 -219.228162)
		(end 353.471734 -218.692476)
		(width 0.254)
		(layer "F.Cu")
		(net "PVCCD_HV_CPU0")
	)
	(segment
		(start 349.822516 -259.616702)
		(end 349.822262 -259.616956)
		(width 0.254)
		(layer "F.Cu")
		(net "PVCCD_HV_CPU0")
	)
	(segment
		(start 351.59188 -215.436958)
		(end 351.59188 -215.436704)
		(width 0.254)
		(layer "F.Cu")
		(net "PVCCD_HV_CPU0")
	)
	(segment
		(start 369.558316 -261.244334)
		(end 369.558062 -261.244588)
		(width 0.254)
		(layer "F.Cu")
		(net "PVCCD_HV_CPU0")
	)
	(segment
		(start 355.351334 -215.437212)
		(end 355.35108 -215.436958)
		(width 0.254)
		(layer "F.Cu")
		(net "PVCCD_HV_CPU0")
	)
	(segment
		(start 369.558316 -259.616702)
		(end 369.558062 -259.616956)
		(width 0.254)
		(layer "F.Cu")
		(net "PVCCD_HV_CPU0")
	)
	(segment
		(start 353.471734 -215.972644)
		(end 353.471734 -215.436958)
		(width 0.254)
		(layer "F.Cu")
		(net "PVCCD_HV_CPU0")
	)
	(segment
		(start 369.448334 -242.017042)
		(end 369.44808 -242.016788)
		(width 0.254)
		(layer "F.Cu")
		(net "PVCCD_HV_CPU0")
	)
	(segment
		(start 349.24238 -242.830858)
		(end 349.242634 -242.830858)
		(width 0.254)
		(layer "F.Cu")
		(net "PVCCD_HV_CPU0")
	)
	(segment
		(start 399.617692 -158.562548)
		(end 400.558 -158.562548)
		(width 0.508)
		(layer "F.Cu")
		(net "PVCCD_HV_CPU0")
	)
	(segment
		(start 355.351334 -218.692476)
		(end 355.35108 -218.692222)
		(width 0.254)
		(layer "F.Cu")
		(net "PVCCD_HV_CPU0")
	)
	(segment
		(start 349.822516 -259.081016)
		(end 349.822516 -259.616702)
		(width 0.254)
		(layer "F.Cu")
		(net "PVCCD_HV_CPU0")
	)
	(segment
		(start 369.91798 -240.66754)
		(end 369.918234 -240.667286)
		(width 0.254)
		(layer "F.Cu")
		(net "PVCCD_HV_CPU0")
	)
	(segment
		(start 400.558 -158.562548)
		(end 400.558 -159.502856)
		(width 0.508)
		(layer "F.Cu")
		(net "PVCCD_HV_CPU0")
	)
	(segment
		(start 369.44808 -242.016788)
		(end 369.44808 -241.481102)
		(width 0.254)
		(layer "F.Cu")
		(net "PVCCD_HV_CPU0")
	)
	(segment
		(start 369.558062 -261.244588)
		(end 369.558062 -261.244842)
		(width 0.254)
		(layer "F.Cu")
		(net "PVCCD_HV_CPU0")
	)
	(segment
		(start 369.558316 -259.081016)
		(end 369.558316 -259.616702)
		(width 0.254)
		(layer "F.Cu")
		(net "PVCCD_HV_CPU0")
	)
	(segment
		(start 350.18218 -242.830858)
		(end 350.182434 -242.830858)
		(width 0.254)
		(layer "F.Cu")
		(net "PVCCD_HV_CPU0")
	)
	(segment
		(start 349.242634 -242.830858)
		(end 349.242634 -242.294918)
		(width 0.254)
		(layer "F.Cu")
		(net "PVCCD_HV_CPU0")
	)
	(segment
		(start 399.617692 -165.725856)
		(end 400.558 -164.785548)
		(width 0.508)
		(layer "F.Cu")
		(net "PVCCD_HV_CPU0")
	)
	(segment
		(start 350.292162 -258.802886)
		(end 350.291908 -258.80314)
		(width 0.254)
		(layer "F.Cu")
		(net "PVCCD_HV_CPU0")
	)
	(segment
		(start 350.292162 -258.2672)
		(end 350.292162 -258.802886)
		(width 0.254)
		(layer "F.Cu")
		(net "PVCCD_HV_CPU0")
	)
	(segment
		(start 369.448334 -243.644928)
		(end 369.44808 -243.644674)
		(width 0.254)
		(layer "F.Cu")
		(net "PVCCD_HV_CPU0")
	)
	(segment
		(start 351.592134 -215.972644)
		(end 351.592134 -215.437212)
		(width 0.254)
		(layer "F.Cu")
		(net "PVCCD_HV_CPU0")
	)
	(segment
		(start 349.712534 -215.437212)
		(end 349.71228 -215.436958)
		(width 0.254)
		(layer "F.Cu")
		(net "PVCCD_HV_CPU0")
	)
	(segment
		(start 369.558316 -260.708902)
		(end 369.558316 -261.244334)
		(width 0.254)
		(layer "F.Cu")
		(net "PVCCD_HV_CPU0")
	)
	(segment
		(start 350.182434 -241.202972)
		(end 350.182434 -240.667286)
		(width 0.254)
		(layer "F.Cu")
		(net "PVCCD_HV_CPU0")
	)
	(segment
		(start 355.351334 -221.947994)
		(end 355.35108 -221.94774)
		(width 0.254)
		(layer "F.Cu")
		(net "PVCCD_HV_CPU0")
	)
	(segment
		(start 349.712534 -215.972644)
		(end 349.712534 -215.437212)
		(width 0.254)
		(layer "F.Cu")
		(net "PVCCD_HV_CPU0")
	)
	(segment
		(start 360.990134 -219.228162)
		(end 360.990134 -218.692476)
		(width 0.254)
		(layer "F.Cu")
		(net "PVCCD_HV_CPU0")
	)
	(segment
		(start 351.592134 -219.228162)
		(end 351.592134 -218.692476)
		(width 0.254)
		(layer "F.Cu")
		(net "PVCCD_HV_CPU0")
	)
	(segment
		(start 350.182434 -242.830858)
		(end 350.182434 -242.294918)
		(width 0.254)
		(layer "F.Cu")
		(net "PVCCD_HV_CPU0")
	)
	(segment
		(start 353.471734 -222.48368)
		(end 353.471734 -221.947994)
		(width 0.254)
		(layer "F.Cu")
		(net "PVCCD_HV_CPU0")
	)
	(segment
		(start 350.18218 -241.203226)
		(end 350.182434 -241.202972)
		(width 0.254)
		(layer "F.Cu")
		(net "PVCCD_HV_CPU0")
	)
	(via
		(at 293.614348 -189.533022)
		(size 0.508)
		(drill 0.254)
		(layers "F.Cu" "B.Cu")
		(net "PVCCD_HV_CPU0")
	)
	(via
		(at 353.47148 -218.692222)
		(size 0.4572)
		(drill 0.2032)
		(layers "F.Cu" "B.Cu")
		(net "PVCCD_HV_CPU0")
	)
	(via
		(at 403.580092 -160.334198)
		(size 0.508)
		(drill 0.254)
		(layers "F.Cu" "B.Cu")
		(net "PVCCD_HV_CPU0")
	)
	(via
		(at 404.850092 -164.037518)
		(size 0.508)
		(drill 0.254)
		(layers "F.Cu" "B.Cu")
		(net "PVCCD_HV_CPU0")
	)
	(via
		(at 404.842472 -159.696658)
		(size 0.508)
		(drill 0.254)
		(layers "F.Cu" "B.Cu")
		(net "PVCCD_HV_CPU0")
	)
	(via
		(at 403.587712 -159.048958)
		(size 0.508)
		(drill 0.254)
		(layers "F.Cu" "B.Cu")
		(net "PVCCD_HV_CPU0")
	)
	(via
		(at 403.572472 -165.322758)
		(size 0.508)
		(drill 0.254)
		(layers "F.Cu" "B.Cu")
		(net "PVCCD_HV_CPU0")
	)
	(via
		(at 369.558062 -259.616956)
		(size 0.4572)
		(drill 0.2032)
		(layers "F.Cu" "B.Cu")
		(net "PVCCD_HV_CPU0")
	)
	(via
		(at 404.842472 -165.957758)
		(size 0.508)
		(drill 0.254)
		(layers "F.Cu" "B.Cu")
		(net "PVCCD_HV_CPU0")
	)
	(via
		(at 405.492712 -159.048958)
		(size 0.508)
		(drill 0.254)
		(layers "F.Cu" "B.Cu")
		(net "PVCCD_HV_CPU0")
	)
	(via
		(at 403.572472 -159.696658)
		(size 0.508)
		(drill 0.254)
		(layers "F.Cu" "B.Cu")
		(net "PVCCD_HV_CPU0")
	)
	(via
		(at 405.477472 -165.322758)
		(size 0.508)
		(drill 0.254)
		(layers "F.Cu" "B.Cu")
		(net "PVCCD_HV_CPU0")
	)
	(via
		(at 404.842472 -165.322758)
		(size 0.508)
		(drill 0.254)
		(layers "F.Cu" "B.Cu")
		(net "PVCCD_HV_CPU0")
	)
	(via
		(at 353.47148 -215.436704)
		(size 0.4572)
		(drill 0.2032)
		(layers "F.Cu" "B.Cu")
		(net "PVCCD_HV_CPU0")
	)
	(via
		(at 404.207472 -165.322758)
		(size 0.508)
		(drill 0.254)
		(layers "F.Cu" "B.Cu")
		(net "PVCCD_HV_CPU0")
	)
	(via
		(at 349.712788 -241.481102)
		(size 0.4572)
		(drill 0.2032)
		(layers "F.Cu" "B.Cu")
		(net "PVCCD_HV_CPU0")
	)
	(via
		(at 405.477472 -159.696658)
		(size 0.508)
		(drill 0.254)
		(layers "F.Cu" "B.Cu")
		(net "PVCCD_HV_CPU0")
	)
	(via
		(at 362.869734 -218.692222)
		(size 0.4572)
		(drill 0.2032)
		(layers "F.Cu" "B.Cu")
		(net "PVCCD_HV_CPU0")
	)
	(via
		(at 403.564852 -164.685218)
		(size 0.508)
		(drill 0.254)
		(layers "F.Cu" "B.Cu")
		(net "PVCCD_HV_CPU0")
	)
	(via
		(at 268.02207 -189.192662)
		(size 0.508)
		(drill 0.254)
		(layers "F.Cu" "B.Cu")
		(net "PVCCD_HV_CPU0")
	)
	(via
		(at 403.580092 -164.037518)
		(size 0.508)
		(drill 0.254)
		(layers "F.Cu" "B.Cu")
		(net "PVCCD_HV_CPU0")
	)
	(via
		(at 350.755204 -246.659146)
		(size 0.4572)
		(drill 0.2032)
		(layers "F.Cu" "B.Cu")
		(net "PVCCD_HV_CPU0")
	)
	(via
		(at 353.47148 -221.94774)
		(size 0.4572)
		(drill 0.2032)
		(layers "F.Cu" "B.Cu")
		(net "PVCCD_HV_CPU0")
	)
	(via
		(at 370.027962 -258.80314)
		(size 0.4572)
		(drill 0.2032)
		(layers "F.Cu" "B.Cu")
		(net "PVCCD_HV_CPU0")
	)
	(via
		(at 404.222712 -159.048958)
		(size 0.508)
		(drill 0.254)
		(layers "F.Cu" "B.Cu")
		(net "PVCCD_HV_CPU0")
	)
	(via
		(at 369.44808 -241.481102)
		(size 0.4572)
		(drill 0.2032)
		(layers "F.Cu" "B.Cu")
		(net "PVCCD_HV_CPU0")
	)
	(via
		(at 349.71228 -215.436704)
		(size 0.4572)
		(drill 0.2032)
		(layers "F.Cu" "B.Cu")
		(net "PVCCD_HV_CPU0")
	)
	(via
		(at 351.923604 -246.659146)
		(size 0.4572)
		(drill 0.2032)
		(layers "F.Cu" "B.Cu")
		(net "PVCCD_HV_CPU0")
	)
	(via
		(at 406.120092 -160.334198)
		(size 0.508)
		(drill 0.254)
		(layers "F.Cu" "B.Cu")
		(net "PVCCD_HV_CPU0")
	)
	(via
		(at 355.35108 -218.692222)
		(size 0.4572)
		(drill 0.2032)
		(layers "F.Cu" "B.Cu")
		(net "PVCCD_HV_CPU0")
	)
	(via
		(at 297.94708 -189.476888)
		(size 0.508)
		(drill 0.254)
		(layers "F.Cu" "B.Cu")
		(net "PVCCD_HV_CPU0")
	)
	(via
		(at 406.120092 -164.037518)
		(size 0.508)
		(drill 0.254)
		(layers "F.Cu" "B.Cu")
		(net "PVCCD_HV_CPU0")
	)
	(via
		(at 369.918234 -242.294918)
		(size 0.4572)
		(drill 0.2032)
		(layers "F.Cu" "B.Cu")
		(net "PVCCD_HV_CPU0")
	)
	(via
		(at 404.199852 -164.685218)
		(size 0.508)
		(drill 0.254)
		(layers "F.Cu" "B.Cu")
		(net "PVCCD_HV_CPU0")
	)
	(via
		(at 405.485092 -164.037518)
		(size 0.508)
		(drill 0.254)
		(layers "F.Cu" "B.Cu")
		(net "PVCCD_HV_CPU0")
	)
	(via
		(at 399.180558 -189.77483)
		(size 0.508)
		(drill 0.254)
		(layers "F.Cu" "B.Cu")
		(net "PVCCD_HV_CPU0")
	)
	(via
		(at 331.108304 -167.556434)
		(size 0.508)
		(drill 0.254)
		(layers "F.Cu" "B.Cu")
		(net "PVCCD_HV_CPU0")
	)
	(via
		(at 350.182434 -242.294918)
		(size 0.4572)
		(drill 0.2032)
		(layers "F.Cu" "B.Cu")
		(net "PVCCD_HV_CPU0")
	)
	(via
		(at 405.469852 -164.685218)
		(size 0.508)
		(drill 0.254)
		(layers "F.Cu" "B.Cu")
		(net "PVCCD_HV_CPU0")
	)
	(via
		(at 404.850092 -160.334198)
		(size 0.508)
		(drill 0.254)
		(layers "F.Cu" "B.Cu")
		(net "PVCCD_HV_CPU0")
	)
	(via
		(at 369.558062 -261.244842)
		(size 0.4572)
		(drill 0.2032)
		(layers "F.Cu" "B.Cu")
		(net "PVCCD_HV_CPU0")
	)
	(via
		(at 404.834852 -164.685218)
		(size 0.508)
		(drill 0.254)
		(layers "F.Cu" "B.Cu")
		(net "PVCCD_HV_CPU0")
	)
	(via
		(at 285.23692 -188.293248)
		(size 0.508)
		(drill 0.254)
		(layers "F.Cu" "B.Cu")
		(net "PVCCD_HV_CPU0")
	)
	(via
		(at 406.112472 -159.696658)
		(size 0.508)
		(drill 0.254)
		(layers "F.Cu" "B.Cu")
		(net "PVCCD_HV_CPU0")
	)
	(via
		(at 350.291908 -258.80314)
		(size 0.4572)
		(drill 0.2032)
		(layers "F.Cu" "B.Cu")
		(net "PVCCD_HV_CPU0")
	)
	(via
		(at 351.339404 -246.659146)
		(size 0.4572)
		(drill 0.2032)
		(layers "F.Cu" "B.Cu")
		(net "PVCCD_HV_CPU0")
	)
	(via
		(at 404.215092 -164.037518)
		(size 0.508)
		(drill 0.254)
		(layers "F.Cu" "B.Cu")
		(net "PVCCD_HV_CPU0")
	)
	(via
		(at 368.916204 -247.35155)
		(size 0.4572)
		(drill 0.2032)
		(layers "F.Cu" "B.Cu")
		(net "PVCCD_HV_CPU0")
	)
	(via
		(at 360.98988 -218.692222)
		(size 0.4572)
		(drill 0.2032)
		(layers "F.Cu" "B.Cu")
		(net "PVCCD_HV_CPU0")
	)
	(via
		(at 368.31143 -246.659146)
		(size 0.4572)
		(drill 0.2032)
		(layers "F.Cu" "B.Cu")
		(net "PVCCD_HV_CPU0")
	)
	(via
		(at 355.35108 -215.436704)
		(size 0.4572)
		(drill 0.2032)
		(layers "F.Cu" "B.Cu")
		(net "PVCCD_HV_CPU0")
	)
	(via
		(at 349.71228 -218.692222)
		(size 0.4572)
		(drill 0.2032)
		(layers "F.Cu" "B.Cu")
		(net "PVCCD_HV_CPU0")
	)
	(via
		(at 367.72723 -246.659146)
		(size 0.4572)
		(drill 0.2032)
		(layers "F.Cu" "B.Cu")
		(net "PVCCD_HV_CPU0")
	)
	(via
		(at 349.822262 -259.616956)
		(size 0.4572)
		(drill 0.2032)
		(layers "F.Cu" "B.Cu")
		(net "PVCCD_HV_CPU0")
	)
	(via
		(at 406.127712 -159.048958)
		(size 0.508)
		(drill 0.254)
		(layers "F.Cu" "B.Cu")
		(net "PVCCD_HV_CPU0")
	)
	(via
		(at 350.292416 -260.430772)
		(size 0.4572)
		(drill 0.2032)
		(layers "F.Cu" "B.Cu")
		(net "PVCCD_HV_CPU0")
	)
	(via
		(at 404.207472 -165.957758)
		(size 0.508)
		(drill 0.254)
		(layers "F.Cu" "B.Cu")
		(net "PVCCD_HV_CPU0")
	)
	(via
		(at 433.063142 -191.266826)
		(size 0.508)
		(drill 0.254)
		(layers "F.Cu" "B.Cu")
		(net "PVCCD_HV_CPU0")
	)
	(via
		(at 369.558062 -257.98907)
		(size 0.4572)
		(drill 0.2032)
		(layers "F.Cu" "B.Cu")
		(net "PVCCD_HV_CPU0")
	)
	(via
		(at 355.35108 -221.94774)
		(size 0.4572)
		(drill 0.2032)
		(layers "F.Cu" "B.Cu")
		(net "PVCCD_HV_CPU0")
	)
	(via
		(at 404.207472 -159.696658)
		(size 0.508)
		(drill 0.254)
		(layers "F.Cu" "B.Cu")
		(net "PVCCD_HV_CPU0")
	)
	(via
		(at 352.507804 -246.659146)
		(size 0.4572)
		(drill 0.2032)
		(layers "F.Cu" "B.Cu")
		(net "PVCCD_HV_CPU0")
	)
	(via
		(at 406.104852 -164.685218)
		(size 0.508)
		(drill 0.254)
		(layers "F.Cu" "B.Cu")
		(net "PVCCD_HV_CPU0")
	)
	(via
		(at 349.352616 -260.430772)
		(size 0.4572)
		(drill 0.2032)
		(layers "F.Cu" "B.Cu")
		(net "PVCCD_HV_CPU0")
	)
	(via
		(at 391.467594 -164.129212)
		(size 0.508)
		(drill 0.254)
		(layers "F.Cu" "B.Cu")
		(net "PVCCD_HV_CPU0")
	)
	(via
		(at 406.112472 -165.322758)
		(size 0.508)
		(drill 0.254)
		(layers "F.Cu" "B.Cu")
		(net "PVCCD_HV_CPU0")
	)
	(via
		(at 357.23068 -218.692222)
		(size 0.4572)
		(drill 0.2032)
		(layers "F.Cu" "B.Cu")
		(net "PVCCD_HV_CPU0")
	)
	(via
		(at 349.242634 -242.294918)
		(size 0.4572)
		(drill 0.2032)
		(layers "F.Cu" "B.Cu")
		(net "PVCCD_HV_CPU0")
	)
	(via
		(at 423.338244 -192.319148)
		(size 0.508)
		(drill 0.254)
		(layers "F.Cu" "B.Cu")
		(net "PVCCD_HV_CPU0")
	)
	(via
		(at 368.916204 -246.76735)
		(size 0.4572)
		(drill 0.2032)
		(layers "F.Cu" "B.Cu")
		(net "PVCCD_HV_CPU0")
	)
	(via
		(at 369.44808 -243.108988)
		(size 0.4572)
		(drill 0.2032)
		(layers "F.Cu" "B.Cu")
		(net "PVCCD_HV_CPU0")
	)
	(via
		(at 351.59188 -215.436704)
		(size 0.4572)
		(drill 0.2032)
		(layers "F.Cu" "B.Cu")
		(net "PVCCD_HV_CPU0")
	)
	(via
		(at 367.14303 -246.659146)
		(size 0.4572)
		(drill 0.2032)
		(layers "F.Cu" "B.Cu")
		(net "PVCCD_HV_CPU0")
	)
	(via
		(at 351.59188 -218.692222)
		(size 0.4572)
		(drill 0.2032)
		(layers "F.Cu" "B.Cu")
		(net "PVCCD_HV_CPU0")
	)
	(via
		(at 404.215092 -160.334198)
		(size 0.508)
		(drill 0.254)
		(layers "F.Cu" "B.Cu")
		(net "PVCCD_HV_CPU0")
	)
	(via
		(at 369.918234 -240.667286)
		(size 0.4572)
		(drill 0.2032)
		(layers "F.Cu" "B.Cu")
		(net "PVCCD_HV_CPU0")
	)
	(via
		(at 350.182434 -240.667286)
		(size 0.4572)
		(drill 0.2032)
		(layers "F.Cu" "B.Cu")
		(net "PVCCD_HV_CPU0")
	)
	(via
		(at 403.572472 -165.957758)
		(size 0.508)
		(drill 0.254)
		(layers "F.Cu" "B.Cu")
		(net "PVCCD_HV_CPU0")
	)
	(via
		(at 405.477472 -165.957758)
		(size 0.508)
		(drill 0.254)
		(layers "F.Cu" "B.Cu")
		(net "PVCCD_HV_CPU0")
	)
	(via
		(at 419.51529 -165.566344)
		(size 0.508)
		(drill 0.254)
		(layers "F.Cu" "B.Cu")
		(net "PVCCD_HV_CPU0")
	)
	(via
		(at 405.485092 -160.334198)
		(size 0.508)
		(drill 0.254)
		(layers "F.Cu" "B.Cu")
		(net "PVCCD_HV_CPU0")
	)
	(via
		(at 406.112472 -165.957758)
		(size 0.508)
		(drill 0.254)
		(layers "F.Cu" "B.Cu")
		(net "PVCCD_HV_CPU0")
	)
	(via
		(at 404.857712 -159.048958)
		(size 0.508)
		(drill 0.254)
		(layers "F.Cu" "B.Cu")
		(net "PVCCD_HV_CPU0")
	)
	(arc
		(start 350.292162 -259.894832)
		(mid 350.292225 -260.162802)
		(end 350.292416 -260.430772)
		(width 0.254)
		(layer "F.Cu")
		(net "PVCCD_HV_CPU0")
	)
	(arc
		(start 349.352362 -259.894832)
		(mid 349.352425 -260.162802)
		(end 349.352616 -260.430772)
		(width 0.254)
		(layer "F.Cu")
		(net "PVCCD_HV_CPU0")
	)
	(segment
		(start 299.129958 -192.600326)
		(end 297.94708 -191.417448)
		(width 0.381)
		(layer "B.Cu")
		(net "PVCCD_HV_CPU0")
	)
	(segment
		(start 435.59857 -191.888618)
		(end 435.59857 -193.167254)
		(width 0.381)
		(layer "B.Cu")
		(net "PVCCD_HV_CPU0")
	)
	(segment
		(start 299.129958 -193.27368)
		(end 299.129958 -192.600326)
		(width 0.381)
		(layer "B.Cu")
		(net "PVCCD_HV_CPU0")
	)
	(segment
		(start 285.23692 -191.327278)
		(end 286.478726 -192.569084)
		(width 0.381)
		(layer "B.Cu")
		(net "PVCCD_HV_CPU0")
	)
	(segment
		(start 419.46449 -165.617144)
		(end 419.373812 -165.617144)
		(width 0.381)
		(layer "B.Cu")
		(net "PVCCD_HV_CPU0")
	)
	(segment
		(start 433.063142 -191.266826)
		(end 434.976778 -191.266826)
		(width 0.381)
		(layer "B.Cu")
		(net "PVCCD_HV_CPU0")
	)
	(segment
		(start 399.670778 -190.26505)
		(end 399.670778 -190.37554)
		(width 0.381)
		(layer "B.Cu")
		(net "PVCCD_HV_CPU0")
	)
	(segment
		(start 293.614348 -189.533022)
		(end 293.614348 -191.29629)
		(width 0.381)
		(layer "B.Cu")
		(net "PVCCD_HV_CPU0")
	)
	(segment
		(start 399.180558 -189.77483)
		(end 399.670778 -190.26505)
		(width 0.381)
		(layer "B.Cu")
		(net "PVCCD_HV_CPU0")
	)
	(segment
		(start 399.670778 -190.37554)
		(end 400.686778 -190.37554)
		(width 0.381)
		(layer "B.Cu")
		(net "PVCCD_HV_CPU0")
	)
	(segment
		(start 399.617692 -163.84524)
		(end 400.558 -164.785548)
		(width 0.508)
		(layer "B.Cu")
		(net "PVCCD_HV_CPU0")
	)
	(segment
		(start 400.558 -164.785548)
		(end 401.498308 -165.725856)
		(width 0.508)
		(layer "B.Cu")
		(net "PVCCD_HV_CPU0")
	)
	(segment
		(start 419.51529 -165.566344)
		(end 419.46449 -165.617144)
		(width 0.381)
		(layer "B.Cu")
		(net "PVCCD_HV_CPU0")
	)
	(segment
		(start 297.94708 -191.417448)
		(end 297.94708 -189.476888)
		(width 0.381)
		(layer "B.Cu")
		(net "PVCCD_HV_CPU0")
	)
	(segment
		(start 349.71228 -218.692222)
		(end 349.71228 -218.125548)
		(width 0.381)
		(layer "B.Cu")
		(net "PVCCD_HV_CPU0")
	)
	(segment
		(start 434.976778 -191.266826)
		(end 435.59857 -191.888618)
		(width 0.381)
		(layer "B.Cu")
		(net "PVCCD_HV_CPU0")
	)
	(segment
		(start 399.617692 -158.562548)
		(end 400.558 -158.562548)
		(width 0.508)
		(layer "B.Cu")
		(net "PVCCD_HV_CPU0")
	)
	(segment
		(start 399.617692 -165.725856)
		(end 400.558 -164.785548)
		(width 0.508)
		(layer "B.Cu")
		(net "PVCCD_HV_CPU0")
	)
	(segment
		(start 268.02207 -189.192662)
		(end 268.10589 -189.192662)
		(width 0.381)
		(layer "B.Cu")
		(net "PVCCD_HV_CPU0")
	)
	(segment
		(start 400.558 -164.785548)
		(end 401.498308 -163.84524)
		(width 0.508)
		(layer "B.Cu")
		(net "PVCCD_HV_CPU0")
	)
	(segment
		(start 270.700246 -191.787018)
		(end 270.700246 -193.103246)
		(width 0.381)
		(layer "B.Cu")
		(net "PVCCD_HV_CPU0")
	)
	(segment
		(start 286.478726 -192.569084)
		(end 286.478726 -193.291206)
		(width 0.381)
		(layer "B.Cu")
		(net "PVCCD_HV_CPU0")
	)
	(segment
		(start 400.558 -158.562548)
		(end 401.498308 -158.562548)
		(width 0.508)
		(layer "B.Cu")
		(net "PVCCD_HV_CPU0")
	)
	(segment
		(start 419.373812 -165.617144)
		(end 418.940742 -166.050214)
		(width 0.381)
		(layer "B.Cu")
		(net "PVCCD_HV_CPU0")
	)
	(segment
		(start 293.614348 -191.29629)
		(end 296.183558 -193.8655)
		(width 0.381)
		(layer "B.Cu")
		(net "PVCCD_HV_CPU0")
	)
	(segment
		(start 268.10589 -189.192662)
		(end 270.700246 -191.787018)
		(width 0.381)
		(layer "B.Cu")
		(net "PVCCD_HV_CPU0")
	)
	(segment
		(start 285.23692 -188.293248)
		(end 285.23692 -191.327278)
		(width 0.381)
		(layer "B.Cu")
		(net "PVCCD_HV_CPU0")
	)
	(segment
		(start 400.558 -158.562548)
		(end 400.558 -159.502856)
		(width 0.508)
		(layer "B.Cu")
		(net "PVCCD_HV_CPU0")
	)
	(segment
		(start 423.338244 -192.953386)
		(end 423.338244 -192.319148)
		(width 0.381)
		(layer "B.Cu")
		(net "PVCCD_HV_CPU0")
	)
	(segment
		(start 351.59188 -218.692222)
		(end 351.59188 -218.227148)
		(width 0.381)
		(layer "B.Cu")
		(net "PVCCD_HV_CPU0")
	)
	(segment
		(start 283.82468 -190.470028)
		(end 282.547568 -191.74714)
		(width 0.508)
		(layer "In2.Cu")
		(net "PVCCD_HV_CPU0")
	)
	(segment
		(start 417.91128 -164.958268)
		(end 413.74822 -164.958268)
		(width 0.381)
		(layer "In2.Cu")
		(net "PVCCD_HV_CPU0")
	)
	(segment
		(start 419.51529 -165.566344)
		(end 419.412166 -165.669468)
		(width 0.381)
		(layer "In2.Cu")
		(net "PVCCD_HV_CPU0")
	)
	(segment
		(start 282.547568 -191.74714)
		(end 269.915894 -191.74714)
		(width 0.508)
		(layer "In2.Cu")
		(net "PVCCD_HV_CPU0")
	)
	(segment
		(start 419.412166 -165.669468)
		(end 418.62248 -165.669468)
		(width 0.381)
		(layer "In2.Cu")
		(net "PVCCD_HV_CPU0")
	)
	(segment
		(start 269.915894 -191.74714)
		(end 268.02207 -189.853316)
		(width 0.508)
		(layer "In2.Cu")
		(net "PVCCD_HV_CPU0")
	)
	(segment
		(start 413.74822 -164.958268)
		(end 412.82747 -164.037518)
		(width 0.381)
		(layer "In2.Cu")
		(net "PVCCD_HV_CPU0")
	)
	(segment
		(start 268.02207 -189.853316)
		(end 268.02207 -189.192662)
		(width 0.508)
		(layer "In2.Cu")
		(net "PVCCD_HV_CPU0")
	)
	(segment
		(start 283.82468 -189.705488)
		(end 283.82468 -190.470028)
		(width 0.508)
		(layer "In2.Cu")
		(net "PVCCD_HV_CPU0")
	)
	(segment
		(start 412.82747 -164.037518)
		(end 406.120092 -164.037518)
		(width 0.381)
		(layer "In2.Cu")
		(net "PVCCD_HV_CPU0")
	)
	(segment
		(start 285.23692 -188.293248)
		(end 283.82468 -189.705488)
		(width 0.508)
		(layer "In2.Cu")
		(net "PVCCD_HV_CPU0")
	)
	(segment
		(start 418.62248 -165.669468)
		(end 417.91128 -164.958268)
		(width 0.381)
		(layer "In2.Cu")
		(net "PVCCD_HV_CPU0")
	)
	(segment
		(start 424.58386 -192.319148)
		(end 423.338244 -192.319148)
		(width 0.381)
		(layer "In4.Cu")
		(net "PVCCD_HV_CPU0")
	)
	(segment
		(start 425.055538 -191.84747)
		(end 424.58386 -192.319148)
		(width 0.381)
		(layer "In4.Cu")
		(net "PVCCD_HV_CPU0")
	)
	(segment
		(start 395.04874 -187.424568)
		(end 397.399002 -189.77483)
		(width 0.381)
		(layer "In4.Cu")
		(net "PVCCD_HV_CPU0")
	)
	(segment
		(start 399.03654 -168.923208)
		(end 395.04874 -172.911008)
		(width 0.381)
		(layer "In4.Cu")
		(net "PVCCD_HV_CPU0")
	)
	(segment
		(start 433.063142 -191.266826)
		(end 432.482498 -191.84747)
		(width 0.381)
		(layer "In4.Cu")
		(net "PVCCD_HV_CPU0")
	)
	(segment
		(start 397.399002 -189.77483)
		(end 399.180558 -189.77483)
		(width 0.381)
		(layer "In4.Cu")
		(net "PVCCD_HV_CPU0")
	)
	(segment
		(start 432.482498 -191.84747)
		(end 425.055538 -191.84747)
		(width 0.381)
		(layer "In4.Cu")
		(net "PVCCD_HV_CPU0")
	)
	(segment
		(start 395.04874 -172.911008)
		(end 395.04874 -187.424568)
		(width 0.381)
		(layer "In4.Cu")
		(net "PVCCD_HV_CPU0")
	)
	(segment
		(start 399.03654 -165.496748)
		(end 399.03654 -168.923208)
		(width 0.381)
		(layer "In4.Cu")
		(net "PVCCD_HV_CPU0")
	)
	(segment
		(start 354.936806 -218.692222)
		(end 355.35108 -218.692222)
		(width 0.381)
		(layer "In6.Cu")
		(net "PVCCD_HV_CPU0")
	)
	(segment
		(start 329.322938 -169.3418)
		(end 317.035688 -169.3418)
		(width 0.508)
		(layer "In11.Cu")
		(net "PVCCD_HV_CPU0")
	)
	(segment
		(start 297.94708 -189.982348)
		(end 297.94708 -189.476888)
		(width 0.508)
		(layer "In11.Cu")
		(net "PVCCD_HV_CPU0")
	)
	(segment
		(start 297.94708 -188.430408)
		(end 297.94708 -189.476888)
		(width 0.508)
		(layer "In11.Cu")
		(net "PVCCD_HV_CPU0")
	)
	(segment
		(start 285.87192 -187.658248)
		(end 285.23692 -188.293248)
		(width 0.508)
		(layer "In11.Cu")
		(net "PVCCD_HV_CPU0")
	)
	(segment
		(start 294.180514 -190.607188)
		(end 297.32224 -190.607188)
		(width 0.508)
		(layer "In11.Cu")
		(net "PVCCD_HV_CPU0")
	)
	(segment
		(start 317.035688 -169.3418)
		(end 297.94708 -188.430408)
		(width 0.508)
		(layer "In11.Cu")
		(net "PVCCD_HV_CPU0")
	)
	(segment
		(start 331.108304 -167.556434)
		(end 329.322938 -169.3418)
		(width 0.508)
		(layer "In11.Cu")
		(net "PVCCD_HV_CPU0")
	)
	(segment
		(start 293.614348 -189.533022)
		(end 293.614348 -190.041022)
		(width 0.508)
		(layer "In11.Cu")
		(net "PVCCD_HV_CPU0")
	)
	(segment
		(start 291.739574 -187.658248)
		(end 285.87192 -187.658248)
		(width 0.508)
		(layer "In11.Cu")
		(net "PVCCD_HV_CPU0")
	)
	(segment
		(start 297.32224 -190.607188)
		(end 297.94708 -189.982348)
		(width 0.508)
		(layer "In11.Cu")
		(net "PVCCD_HV_CPU0")
	)
	(segment
		(start 293.614348 -190.041022)
		(end 294.180514 -190.607188)
		(width 0.508)
		(layer "In11.Cu")
		(net "PVCCD_HV_CPU0")
	)
	(segment
		(start 293.614348 -189.533022)
		(end 291.739574 -187.658248)
		(width 0.508)
		(layer "In11.Cu")
		(net "PVCCD_HV_CPU0")
	)
	(segment
		(start 404.191978 -189.77483)
		(end 406.40508 -187.561728)
		(width 0.381)
		(layer "In13.Cu")
		(net "PVCCD_HV_CPU0")
	)
	(segment
		(start 399.842228 -165.50132)
		(end 400.558 -164.785548)
		(width 0.508)
		(layer "In13.Cu")
		(net "PVCCD_HV_CPU0")
	)
	(segment
		(start 406.40508 -187.561728)
		(end 418.580824 -187.561728)
		(width 0.381)
		(layer "In13.Cu")
		(net "PVCCD_HV_CPU0")
	)
	(segment
		(start 400.558 -158.562548)
		(end 401.498308 -158.562548)
		(width 0.508)
		(layer "In13.Cu")
		(net "PVCCD_HV_CPU0")
	)
	(segment
		(start 399.842228 -164.069776)
		(end 400.558 -164.785548)
		(width 0.508)
		(layer "In13.Cu")
		(net "PVCCD_HV_CPU0")
	)
	(segment
		(start 418.580824 -187.561728)
		(end 423.338244 -192.319148)
		(width 0.381)
		(layer "In13.Cu")
		(net "PVCCD_HV_CPU0")
	)
	(segment
		(start 400.558 -164.785548)
		(end 401.273772 -164.069776)
		(width 0.508)
		(layer "In13.Cu")
		(net "PVCCD_HV_CPU0")
	)
	(segment
		(start 399.180558 -189.77483)
		(end 404.191978 -189.77483)
		(width 0.381)
		(layer "In13.Cu")
		(net "PVCCD_HV_CPU0")
	)
	(segment
		(start 400.558 -164.785548)
		(end 401.273772 -165.50132)
		(width 0.508)
		(layer "In13.Cu")
		(net "PVCCD_HV_CPU0")
	)
	(segment
		(start 399.617692 -158.562548)
		(end 400.558 -158.562548)
		(width 0.508)
		(layer "In13.Cu")
		(net "PVCCD_HV_CPU0")
	)
	(segment
		(start 400.558 -158.562548)
		(end 400.558 -159.502856)
		(width 0.508)
		(layer "In13.Cu")
		(net "PVCCD_HV_CPU0")
	)
	(segment
		(start 331.108304 -167.556434)
		(end 346.942918 -167.556434)
		(width 0.508)
		(layer "In15.Cu")
		(net "PVCCD_HV_CPU0")
	)
	(segment
		(start 346.942918 -167.556434)
		(end 349.134176 -165.365176)
		(width 0.508)
		(layer "In15.Cu")
		(net "PVCCD_HV_CPU0")
	)
	(segment
		(start 367.657888 -165.365176)
		(end 370.0145 -163.008564)
		(width 0.508)
		(layer "In15.Cu")
		(net "PVCCD_HV_CPU0")
	)
	(segment
		(start 390.346946 -163.008564)
		(end 391.467594 -164.129212)
		(width 0.508)
		(layer "In15.Cu")
		(net "PVCCD_HV_CPU0")
	)
	(segment
		(start 370.0145 -163.008564)
		(end 390.346946 -163.008564)
		(width 0.508)
		(layer "In15.Cu")
		(net "PVCCD_HV_CPU0")
	)
	(segment
		(start 349.134176 -165.365176)
		(end 367.657888 -165.365176)
		(width 0.508)
		(layer "In15.Cu")
		(net "PVCCD_HV_CPU0")
	)
	(segment
		(start 381.605282 -71.134224)
		(end 381.605282 -71.87819)
		(width 0.4572)
		(layer "F.Cu")
		(net "PVCC1_AUX")
	)
	(segment
		(start 380.741936 -71.126858)
		(end 381.597916 -71.126858)
		(width 0.4572)
		(layer "F.Cu")
		(net "PVCC1_AUX")
	)
	(segment
		(start 381.597916 -71.126858)
		(end 381.605282 -71.134224)
		(width 0.4572)
		(layer "F.Cu")
		(net "PVCC1_AUX")
	)
	(segment
		(start 380.741936 -71.126858)
		(end 380.741936 -71.830438)
		(width 0.4572)
		(layer "F.Cu")
		(net "PVCC1_AUX")
	)
	(segment
		(start 381.605282 -71.87819)
		(end 382.086612 -72.35952)
		(width 0.4572)
		(layer "F.Cu")
		(net "PVCC1_AUX")
	)
	(via
		(at 380.741936 -71.830438)
		(size 0.508)
		(drill 0.254)
		(layers "F.Cu" "B.Cu")
		(net "PVCC1_AUX")
	)
	(segment
		(start 103.181912 -229.808786)
		(end 103.181912 -229.2731)
		(width 0.12954)
		(layer "F.Cu")
		(net "PU_TAP_ODT_CPU1_EN")
	)
	(segment
		(start 103.181912 -229.2731)
		(end 103.182166 -229.272846)
		(width 0.12954)
		(layer "F.Cu")
		(net "PU_TAP_ODT_CPU1_EN")
	)
	(via
		(at 103.182166 -229.272846)
		(size 0.4572)
		(drill 0.2032)
		(layers "F.Cu" "B.Cu")
		(net "PU_TAP_ODT_CPU1_EN")
	)
	(via
		(at 68.156074 -187.459366)
		(size 0.508)
		(drill 0.254)
		(layers "F.Cu" "B.Cu")
		(net "PU_TAP_ODT_CPU1_EN")
	)
	(segment
		(start 68.156074 -186.373516)
		(end 68.337684 -186.191906)
		(width 0.12954)
		(layer "B.Cu")
		(net "PU_TAP_ODT_CPU1_EN")
	)
	(segment
		(start 68.156074 -187.459366)
		(end 68.156074 -186.373516)
		(width 0.12954)
		(layer "B.Cu")
		(net "PU_TAP_ODT_CPU1_EN")
	)
	(segment
		(start 76.197968 -197.184264)
		(end 75.040998 -195.452492)
		(width 0.127)
		(layer "In4.Cu")
		(net "PU_TAP_ODT_CPU1_EN")
	)
	(segment
		(start 101.585014 -228.783388)
		(end 101.432106 -228.69525)
		(width 0.0889)
		(layer "In4.Cu")
		(net "PU_TAP_ODT_CPU1_EN")
	)
	(segment
		(start 75.040998 -195.452492)
		(end 73.928478 -192.766696)
		(width 0.127)
		(layer "In4.Cu")
		(net "PU_TAP_ODT_CPU1_EN")
	)
	(segment
		(start 86.846918 -219.87891)
		(end 86.410038 -219.87891)
		(width 0.127)
		(layer "In4.Cu")
		(net "PU_TAP_ODT_CPU1_EN")
	)
	(segment
		(start 95.482664 -226.345242)
		(end 95.476568 -226.341686)
		(width 0.0889)
		(layer "In4.Cu")
		(net "PU_TAP_ODT_CPU1_EN")
	)
	(segment
		(start 87.958168 -221.458282)
		(end 87.949278 -221.453202)
		(width 0.0889)
		(layer "In4.Cu")
		(net "PU_TAP_ODT_CPU1_EN")
	)
	(segment
		(start 69.586094 -188.253878)
		(end 68.791582 -187.459366)
		(width 0.127)
		(layer "In4.Cu")
		(net "PU_TAP_ODT_CPU1_EN")
	)
	(segment
		(start 73.928478 -192.766696)
		(end 73.928478 -190.446406)
		(width 0.127)
		(layer "In4.Cu")
		(net "PU_TAP_ODT_CPU1_EN")
	)
	(segment
		(start 90.307414 -225.527616)
		(end 90.292682 -225.51898)
		(width 0.0889)
		(layer "In4.Cu")
		(net "PU_TAP_ODT_CPU1_EN")
	)
	(segment
		(start 73.928478 -190.446406)
		(end 72.225662 -188.74359)
		(width 0.127)
		(layer "In4.Cu")
		(net "PU_TAP_ODT_CPU1_EN")
	)
	(segment
		(start 70.408546 -188.253878)
		(end 69.586094 -188.253878)
		(width 0.127)
		(layer "In4.Cu")
		(net "PU_TAP_ODT_CPU1_EN")
	)
	(segment
		(start 90.590116 -226.025964)
		(end 90.590116 -226.003104)
		(width 0.0889)
		(layer "In4.Cu")
		(net "PU_TAP_ODT_CPU1_EN")
	)
	(segment
		(start 68.791582 -187.459366)
		(end 68.156074 -187.459366)
		(width 0.127)
		(layer "In4.Cu")
		(net "PU_TAP_ODT_CPU1_EN")
	)
	(segment
		(start 89.180416 -223.575626)
		(end 89.180416 -223.561402)
		(width 0.0889)
		(layer "In4.Cu")
		(net "PU_TAP_ODT_CPU1_EN")
	)
	(segment
		(start 86.410038 -219.87891)
		(end 85.024468 -218.49334)
		(width 0.127)
		(layer "In4.Cu")
		(net "PU_TAP_ODT_CPU1_EN")
	)
	(segment
		(start 88.889078 -224.070164)
		(end 88.897968 -224.065084)
		(width 0.0889)
		(layer "In4.Cu")
		(net "PU_TAP_ODT_CPU1_EN")
	)
	(segment
		(start 96.228916 -227.64496)
		(end 96.228916 -227.635054)
		(width 0.0889)
		(layer "In4.Cu")
		(net "PU_TAP_ODT_CPU1_EN")
	)
	(segment
		(start 87.461598 -220.49359)
		(end 86.846918 -219.87891)
		(width 0.127)
		(layer "In4.Cu")
		(net "PU_TAP_ODT_CPU1_EN")
	)
	(segment
		(start 87.461598 -220.824806)
		(end 87.461598 -220.49359)
		(width 0.127)
		(layer "In4.Cu")
		(net "PU_TAP_ODT_CPU1_EN")
	)
	(segment
		(start 87.770716 -221.133924)
		(end 87.63254 -220.995748)
		(width 0.0889)
		(layer "In4.Cu")
		(net "PU_TAP_ODT_CPU1_EN")
	)
	(segment
		(start 93.986096 -226.33305)
		(end 93.971364 -226.341686)
		(width 0.0889)
		(layer "In4.Cu")
		(net "PU_TAP_ODT_CPU1_EN")
	)
	(segment
		(start 88.434164 -222.275654)
		(end 88.428068 -222.272098)
		(width 0.0889)
		(layer "In4.Cu")
		(net "PU_TAP_ODT_CPU1_EN")
	)
	(segment
		(start 88.897968 -224.7138)
		(end 88.889078 -224.70872)
		(width 0.0889)
		(layer "In4.Cu")
		(net "PU_TAP_ODT_CPU1_EN")
	)
	(segment
		(start 88.428068 -222.272098)
		(end 88.419178 -222.267018)
		(width 0.0889)
		(layer "In4.Cu")
		(net "PU_TAP_ODT_CPU1_EN")
	)
	(segment
		(start 72.225662 -188.74359)
		(end 70.898258 -188.74359)
		(width 0.127)
		(layer "In4.Cu")
		(net "PU_TAP_ODT_CPU1_EN")
	)
	(segment
		(start 85.024468 -218.49334)
		(end 76.197968 -197.184264)
		(width 0.127)
		(layer "In4.Cu")
		(net "PU_TAP_ODT_CPU1_EN")
	)
	(segment
		(start 96.416368 -227.969318)
		(end 96.407478 -227.964238)
		(width 0.0889)
		(layer "In4.Cu")
		(net "PU_TAP_ODT_CPU1_EN")
	)
	(segment
		(start 89.180416 -225.211894)
		(end 89.180416 -225.193352)
		(width 0.0889)
		(layer "In4.Cu")
		(net "PU_TAP_ODT_CPU1_EN")
	)
	(segment
		(start 91.717368 -226.341686)
		(end 91.706954 -226.33559)
		(width 0.0889)
		(layer "In4.Cu")
		(net "PU_TAP_ODT_CPU1_EN")
	)
	(segment
		(start 88.897968 -224.065084)
		(end 88.904064 -224.061528)
		(width 0.0889)
		(layer "In4.Cu")
		(net "PU_TAP_ODT_CPU1_EN")
	)
	(segment
		(start 88.240616 -221.94774)
		(end 88.240616 -221.937834)
		(width 0.0889)
		(layer "In4.Cu")
		(net "PU_TAP_ODT_CPU1_EN")
	)
	(segment
		(start 94.925896 -226.33305)
		(end 94.911164 -226.341686)
		(width 0.0889)
		(layer "In4.Cu")
		(net "PU_TAP_ODT_CPU1_EN")
	)
	(segment
		(start 95.946468 -227.155502)
		(end 95.937578 -227.150422)
		(width 0.0889)
		(layer "In4.Cu")
		(net "PU_TAP_ODT_CPU1_EN")
	)
	(segment
		(start 102.067614 -228.826568)
		(end 101.781102 -228.833426)
		(width 0.0889)
		(layer "In4.Cu")
		(net "PU_TAP_ODT_CPU1_EN")
	)
	(segment
		(start 70.898258 -188.74359)
		(end 70.408546 -188.253878)
		(width 0.127)
		(layer "In4.Cu")
		(net "PU_TAP_ODT_CPU1_EN")
	)
	(segment
		(start 88.71077 -222.770192)
		(end 88.71077 -222.761556)
		(width 0.0889)
		(layer "In4.Cu")
		(net "PU_TAP_ODT_CPU1_EN")
	)
	(segment
		(start 101.304598 -228.47427)
		(end 101.304598 -228.38537)
		(width 0.0889)
		(layer "In4.Cu")
		(net "PU_TAP_ODT_CPU1_EN")
	)
	(segment
		(start 87.63254 -220.995748)
		(end 87.461598 -220.824806)
		(width 0.127)
		(layer "In4.Cu")
		(net "PU_TAP_ODT_CPU1_EN")
	)
	(segment
		(start 100.954078 -228.03485)
		(end 96.663002 -228.03485)
		(width 0.0889)
		(layer "In4.Cu")
		(net "PU_TAP_ODT_CPU1_EN")
	)
	(arc
		(start 89.74201 -225.527616)
		(mid 89.554812 -225.577759)
		(end 89.367614 -225.527616)
		(width 0.0889)
		(layer "In4.Cu")
		(net "PU_TAP_ODT_CPU1_EN")
	)
	(arc
		(start 90.292682 -225.51898)
		(mid 90.016241 -225.451814)
		(end 89.74201 -225.527616)
		(width 0.0889)
		(layer "In4.Cu")
		(net "PU_TAP_ODT_CPU1_EN")
	)
	(arc
		(start 95.937578 -227.150422)
		(mid 95.806664 -227.014062)
		(end 95.759016 -226.831144)
		(width 0.0889)
		(layer "In4.Cu")
		(net "PU_TAP_ODT_CPU1_EN")
	)
	(arc
		(start 96.407478 -227.964238)
		(mid 96.276564 -227.827878)
		(end 96.228916 -227.64496)
		(width 0.0889)
		(layer "In4.Cu")
		(net "PU_TAP_ODT_CPU1_EN")
	)
	(arc
		(start 93.971364 -226.341686)
		(mid 93.784166 -226.391829)
		(end 93.596968 -226.341686)
		(width 0.0889)
		(layer "In4.Cu")
		(net "PU_TAP_ODT_CPU1_EN")
	)
	(arc
		(start 92.091764 -226.341686)
		(mid 91.904566 -226.391829)
		(end 91.717368 -226.341686)
		(width 0.0889)
		(layer "In4.Cu")
		(net "PU_TAP_ODT_CPU1_EN")
	)
	(arc
		(start 89.180416 -223.561402)
		(mid 89.101275 -223.286779)
		(end 88.897968 -223.085914)
		(width 0.0889)
		(layer "In4.Cu")
		(net "PU_TAP_ODT_CPU1_EN")
	)
	(arc
		(start 95.476568 -226.341686)
		(mid 95.202369 -226.265851)
		(end 94.925896 -226.33305)
		(width 0.0889)
		(layer "In4.Cu")
		(net "PU_TAP_ODT_CPU1_EN")
	)
	(arc
		(start 90.777314 -226.341686)
		(mid 90.642381 -226.208332)
		(end 90.590116 -226.025964)
		(width 0.0889)
		(layer "In4.Cu")
		(net "PU_TAP_ODT_CPU1_EN")
	)
	(arc
		(start 93.596968 -226.341686)
		(mid 93.314266 -226.26591)
		(end 93.031564 -226.341686)
		(width 0.0889)
		(layer "In4.Cu")
		(net "PU_TAP_ODT_CPU1_EN")
	)
	(arc
		(start 92.657168 -226.341686)
		(mid 92.374466 -226.26591)
		(end 92.091764 -226.341686)
		(width 0.0889)
		(layer "In4.Cu")
		(net "PU_TAP_ODT_CPU1_EN")
	)
	(arc
		(start 95.759016 -226.831144)
		(mid 95.6851 -226.551642)
		(end 95.482664 -226.345242)
		(width 0.0889)
		(layer "In4.Cu")
		(net "PU_TAP_ODT_CPU1_EN")
	)
	(arc
		(start 88.897968 -223.085914)
		(mid 88.763035 -222.95256)
		(end 88.71077 -222.770192)
		(width 0.0889)
		(layer "In4.Cu")
		(net "PU_TAP_ODT_CPU1_EN")
	)
	(arc
		(start 91.706954 -226.33559)
		(mid 91.428522 -226.265744)
		(end 91.15171 -226.341686)
		(width 0.0889)
		(layer "In4.Cu")
		(net "PU_TAP_ODT_CPU1_EN")
	)
	(arc
		(start 87.949278 -221.453202)
		(mid 87.818364 -221.316842)
		(end 87.770716 -221.133924)
		(width 0.0889)
		(layer "In4.Cu")
		(net "PU_TAP_ODT_CPU1_EN")
	)
	(arc
		(start 89.367614 -225.527616)
		(mid 89.232681 -225.394262)
		(end 89.180416 -225.211894)
		(width 0.0889)
		(layer "In4.Cu")
		(net "PU_TAP_ODT_CPU1_EN")
	)
	(arc
		(start 93.031564 -226.341686)
		(mid 92.844366 -226.391829)
		(end 92.657168 -226.341686)
		(width 0.0889)
		(layer "In4.Cu")
		(net "PU_TAP_ODT_CPU1_EN")
	)
	(arc
		(start 94.536768 -226.341686)
		(mid 94.262569 -226.265851)
		(end 93.986096 -226.33305)
		(width 0.0889)
		(layer "In4.Cu")
		(net "PU_TAP_ODT_CPU1_EN")
	)
	(arc
		(start 96.663002 -228.03485)
		(mid 96.535399 -228.018201)
		(end 96.416368 -227.969318)
		(width 0.0889)
		(layer "In4.Cu")
		(net "PU_TAP_ODT_CPU1_EN")
	)
	(arc
		(start 101.432106 -228.69525)
		(mid 101.338683 -228.601862)
		(end 101.304598 -228.47427)
		(width 0.0889)
		(layer "In4.Cu")
		(net "PU_TAP_ODT_CPU1_EN")
	)
	(arc
		(start 88.904064 -224.061528)
		(mid 89.106477 -223.855115)
		(end 89.180416 -223.575626)
		(width 0.0889)
		(layer "In4.Cu")
		(net "PU_TAP_ODT_CPU1_EN")
	)
	(arc
		(start 91.15171 -226.341686)
		(mid 90.964512 -226.391829)
		(end 90.777314 -226.341686)
		(width 0.0889)
		(layer "In4.Cu")
		(net "PU_TAP_ODT_CPU1_EN")
	)
	(arc
		(start 88.889078 -224.70872)
		(mid 88.710481 -224.389442)
		(end 88.889078 -224.070164)
		(width 0.0889)
		(layer "In4.Cu")
		(net "PU_TAP_ODT_CPU1_EN")
	)
	(arc
		(start 96.228916 -227.635054)
		(mid 96.150805 -227.358105)
		(end 95.946468 -227.155502)
		(width 0.0889)
		(layer "In4.Cu")
		(net "PU_TAP_ODT_CPU1_EN")
	)
	(arc
		(start 103.182166 -229.272846)
		(mid 102.670664 -228.935364)
		(end 102.067614 -228.826568)
		(width 0.0889)
		(layer "In4.Cu")
		(net "PU_TAP_ODT_CPU1_EN")
	)
	(arc
		(start 90.590116 -226.003104)
		(mid 90.510897 -225.728419)
		(end 90.307414 -225.527616)
		(width 0.0889)
		(layer "In4.Cu")
		(net "PU_TAP_ODT_CPU1_EN")
	)
	(arc
		(start 94.911164 -226.341686)
		(mid 94.723966 -226.391829)
		(end 94.536768 -226.341686)
		(width 0.0889)
		(layer "In4.Cu")
		(net "PU_TAP_ODT_CPU1_EN")
	)
	(arc
		(start 88.240616 -221.937834)
		(mid 88.162505 -221.660885)
		(end 87.958168 -221.458282)
		(width 0.0889)
		(layer "In4.Cu")
		(net "PU_TAP_ODT_CPU1_EN")
	)
	(arc
		(start 101.781102 -228.833426)
		(mid 101.679614 -228.821903)
		(end 101.585014 -228.783388)
		(width 0.0889)
		(layer "In4.Cu")
		(net "PU_TAP_ODT_CPU1_EN")
	)
	(arc
		(start 88.71077 -222.761556)
		(mid 88.636779 -222.48199)
		(end 88.434164 -222.275654)
		(width 0.0889)
		(layer "In4.Cu")
		(net "PU_TAP_ODT_CPU1_EN")
	)
	(arc
		(start 101.304598 -228.38537)
		(mid 101.201933 -228.137515)
		(end 100.954078 -228.03485)
		(width 0.0889)
		(layer "In4.Cu")
		(net "PU_TAP_ODT_CPU1_EN")
	)
	(arc
		(start 89.180416 -225.193352)
		(mid 89.102305 -224.916403)
		(end 88.897968 -224.7138)
		(width 0.0889)
		(layer "In4.Cu")
		(net "PU_TAP_ODT_CPU1_EN")
	)
	(arc
		(start 88.419178 -222.267018)
		(mid 88.288264 -222.130658)
		(end 88.240616 -221.94774)
		(width 0.0889)
		(layer "In4.Cu")
		(net "PU_TAP_ODT_CPU1_EN")
	)
	(segment
		(start 323.071998 -194.06743)
		(end 321.621658 -194.06743)
		(width 0.12954)
		(layer "F.Cu")
		(net "PU_TAP_ODT_CPU0_EN")
	)
	(segment
		(start 328.313288 -199.53605)
		(end 328.313288 -199.30872)
		(width 0.12954)
		(layer "F.Cu")
		(net "PU_TAP_ODT_CPU0_EN")
	)
	(segment
		(start 319.701418 -193.76517)
		(end 319.701418 -190.85687)
		(width 0.12954)
		(layer "F.Cu")
		(net "PU_TAP_ODT_CPU0_EN")
	)
	(segment
		(start 320.003678 -194.06743)
		(end 319.701418 -193.76517)
		(width 0.12954)
		(layer "F.Cu")
		(net "PU_TAP_ODT_CPU0_EN")
	)
	(segment
		(start 328.313288 -199.30872)
		(end 323.071998 -194.06743)
		(width 0.12954)
		(layer "F.Cu")
		(net "PU_TAP_ODT_CPU0_EN")
	)
	(segment
		(start 351.12198 -229.808786)
		(end 351.12198 -229.2731)
		(width 0.12954)
		(layer "F.Cu")
		(net "PU_TAP_ODT_CPU0_EN")
	)
	(segment
		(start 351.12198 -229.2731)
		(end 351.122234 -229.272846)
		(width 0.12954)
		(layer "F.Cu")
		(net "PU_TAP_ODT_CPU0_EN")
	)
	(segment
		(start 321.621658 -194.06743)
		(end 320.003678 -194.06743)
		(width 0.12954)
		(layer "F.Cu")
		(net "PU_TAP_ODT_CPU0_EN")
	)
	(via
		(at 328.313288 -199.53605)
		(size 0.508)
		(drill 0.254)
		(layers "F.Cu" "B.Cu")
		(net "PU_TAP_ODT_CPU0_EN")
	)
	(via
		(at 321.621658 -194.06743)
		(size 0.762)
		(drill 0.381)
		(layers "F.Cu" "B.Cu")
		(net "PU_TAP_ODT_CPU0_EN")
	)
	(via
		(at 319.701418 -190.85687)
		(size 0.508)
		(drill 0.254)
		(layers "F.Cu" "B.Cu")
		(net "PU_TAP_ODT_CPU0_EN")
	)
	(via
		(at 351.122234 -229.272846)
		(size 0.4572)
		(drill 0.2032)
		(layers "F.Cu" "B.Cu")
		(net "PU_TAP_ODT_CPU0_EN")
	)
	(segment
		(start 319.436242 -191.122046)
		(end 318.954912 -191.122046)
		(width 0.12954)
		(layer "B.Cu")
		(net "PU_TAP_ODT_CPU0_EN")
	)
	(segment
		(start 319.701418 -190.85687)
		(end 319.436242 -191.122046)
		(width 0.12954)
		(layer "B.Cu")
		(net "PU_TAP_ODT_CPU0_EN")
	)
	(segment
		(start 339.844634 -226.840796)
		(end 339.844634 -226.831144)
		(width 0.0889)
		(layer "In4.Cu")
		(net "PU_TAP_ODT_CPU0_EN")
	)
	(segment
		(start 341.159084 -227.667058)
		(end 341.159084 -227.480114)
		(width 0.0889)
		(layer "In4.Cu")
		(net "PU_TAP_ODT_CPU0_EN")
	)
	(segment
		(start 345.72321 -228.868732)
		(end 345.708732 -228.86035)
		(width 0.0889)
		(layer "In4.Cu")
		(net "PU_TAP_ODT_CPU0_EN")
	)
	(segment
		(start 337.25993 -224.79635)
		(end 337.250278 -224.801938)
		(width 0.0889)
		(layer "In4.Cu")
		(net "PU_TAP_ODT_CPU0_EN")
	)
	(segment
		(start 338.674456 -224.799144)
		(end 338.66963 -224.79635)
		(width 0.0889)
		(layer "In4.Cu")
		(net "PU_TAP_ODT_CPU0_EN")
	)
	(segment
		(start 343.83853 -228.865938)
		(end 343.825068 -228.858064)
		(width 0.0889)
		(layer "In4.Cu")
		(net "PU_TAP_ODT_CPU0_EN")
	)
	(segment
		(start 341.450168 -228.139752)
		(end 341.441278 -228.134672)
		(width 0.0889)
		(layer "In4.Cu")
		(net "PU_TAP_ODT_CPU0_EN")
	)
	(segment
		(start 327.587356 -201.506074)
		(end 327.587356 -200.261982)
		(width 0.127)
		(layer "In4.Cu")
		(net "PU_TAP_ODT_CPU0_EN")
	)
	(segment
		(start 338.19973 -224.79635)
		(end 338.186268 -224.804224)
		(width 0.0889)
		(layer "In4.Cu")
		(net "PU_TAP_ODT_CPU0_EN")
	)
	(segment
		(start 327.587356 -200.261982)
		(end 328.313288 -199.53605)
		(width 0.127)
		(layer "In4.Cu")
		(net "PU_TAP_ODT_CPU0_EN")
	)
	(segment
		(start 328.328782 -216.74201)
		(end 328.328782 -202.2475)
		(width 0.127)
		(layer "In4.Cu")
		(net "PU_TAP_ODT_CPU0_EN")
	)
	(segment
		(start 345.953334 -229.282498)
		(end 345.953334 -229.272846)
		(width 0.0889)
		(layer "In4.Cu")
		(net "PU_TAP_ODT_CPU0_EN")
	)
	(segment
		(start 333.654908 -220.774514)
		(end 332.361286 -220.774514)
		(width 0.127)
		(layer "In4.Cu")
		(net "PU_TAP_ODT_CPU0_EN")
	)
	(segment
		(start 335.162398 -222.13443)
		(end 335.162398 -221.87789)
		(width 0.0889)
		(layer "In4.Cu")
		(net "PU_TAP_ODT_CPU0_EN")
	)
	(segment
		(start 341.911432 -228.948488)
		(end 341.905336 -228.944932)
		(width 0.0889)
		(layer "In4.Cu")
		(net "PU_TAP_ODT_CPU0_EN")
	)
	(segment
		(start 335.615534 -222.78213)
		(end 335.615534 -222.761556)
		(width 0.0889)
		(layer "In4.Cu")
		(net "PU_TAP_ODT_CPU0_EN")
	)
	(segment
		(start 346.65793 -229.679754)
		(end 346.644468 -229.687628)
		(width 0.0889)
		(layer "In4.Cu")
		(net "PU_TAP_ODT_CPU0_EN")
	)
	(segment
		(start 339.146388 -225.61423)
		(end 339.13953 -225.610166)
		(width 0.0889)
		(layer "In4.Cu")
		(net "PU_TAP_ODT_CPU0_EN")
	)
	(segment
		(start 350.41713 -229.679754)
		(end 350.403668 -229.687628)
		(width 0.0889)
		(layer "In4.Cu")
		(net "PU_TAP_ODT_CPU0_EN")
	)
	(segment
		(start 351.317814 -229.611936)
		(end 351.29089 -229.71125)
		(width 0.0889)
		(layer "In4.Cu")
		(net "PU_TAP_ODT_CPU0_EN")
	)
	(segment
		(start 334.412844 -221.53245)
		(end 334.241394 -221.361)
		(width 0.0889)
		(layer "In4.Cu")
		(net "PU_TAP_ODT_CPU0_EN")
	)
	(segment
		(start 334.816958 -221.53245)
		(end 334.412844 -221.53245)
		(width 0.0889)
		(layer "In4.Cu")
		(net "PU_TAP_ODT_CPU0_EN")
	)
	(segment
		(start 351.122234 -229.272846)
		(end 351.317814 -229.611936)
		(width 0.0889)
		(layer "In4.Cu")
		(net "PU_TAP_ODT_CPU0_EN")
	)
	(segment
		(start 332.361286 -220.774514)
		(end 328.328782 -216.74201)
		(width 0.127)
		(layer "In4.Cu")
		(net "PU_TAP_ODT_CPU0_EN")
	)
	(segment
		(start 339.61451 -226.42703)
		(end 339.604858 -226.421442)
		(width 0.0889)
		(layer "In4.Cu")
		(net "PU_TAP_ODT_CPU0_EN")
	)
	(segment
		(start 336.085434 -223.590104)
		(end 336.085434 -223.575626)
		(width 0.0889)
		(layer "In4.Cu")
		(net "PU_TAP_ODT_CPU0_EN")
	)
	(segment
		(start 328.328782 -202.2475)
		(end 327.587356 -201.506074)
		(width 0.127)
		(layer "In4.Cu")
		(net "PU_TAP_ODT_CPU0_EN")
	)
	(segment
		(start 348.53753 -229.679754)
		(end 348.524068 -229.687628)
		(width 0.0889)
		(layer "In4.Cu")
		(net "PU_TAP_ODT_CPU0_EN")
	)
	(segment
		(start 347.59773 -229.679754)
		(end 347.584268 -229.687628)
		(width 0.0889)
		(layer "In4.Cu")
		(net "PU_TAP_ODT_CPU0_EN")
	)
	(segment
		(start 335.162398 -221.87789)
		(end 334.816958 -221.53245)
		(width 0.0889)
		(layer "In4.Cu")
		(net "PU_TAP_ODT_CPU0_EN")
	)
	(segment
		(start 342.89873 -228.865938)
		(end 342.78443 -228.865938)
		(width 0.0889)
		(layer "In4.Cu")
		(net "PU_TAP_ODT_CPU0_EN")
	)
	(segment
		(start 341.921846 -228.954584)
		(end 341.911432 -228.948488)
		(width 0.0889)
		(layer "In4.Cu")
		(net "PU_TAP_ODT_CPU0_EN")
	)
	(segment
		(start 335.38541 -222.357442)
		(end 335.162398 -222.13443)
		(width 0.0889)
		(layer "In4.Cu")
		(net "PU_TAP_ODT_CPU0_EN")
	)
	(segment
		(start 344.77833 -228.865938)
		(end 344.764868 -228.858064)
		(width 0.0889)
		(layer "In4.Cu")
		(net "PU_TAP_ODT_CPU0_EN")
	)
	(segment
		(start 335.860898 -223.175068)
		(end 335.85023 -223.168718)
		(width 0.0889)
		(layer "In4.Cu")
		(net "PU_TAP_ODT_CPU0_EN")
	)
	(segment
		(start 340.549484 -227.238052)
		(end 340.539832 -227.24364)
		(width 0.0889)
		(layer "In4.Cu")
		(net "PU_TAP_ODT_CPU0_EN")
	)
	(segment
		(start 339.13953 -225.610166)
		(end 339.134704 -225.607372)
		(width 0.0889)
		(layer "In4.Cu")
		(net "PU_TAP_ODT_CPU0_EN")
	)
	(segment
		(start 336.330798 -223.988884)
		(end 336.32013 -223.982534)
		(width 0.0889)
		(layer "In4.Cu")
		(net "PU_TAP_ODT_CPU0_EN")
	)
	(segment
		(start 336.790284 -224.79635)
		(end 336.785458 -224.793556)
		(width 0.0889)
		(layer "In4.Cu")
		(net "PU_TAP_ODT_CPU0_EN")
	)
	(segment
		(start 334.241394 -221.361)
		(end 333.654908 -220.774514)
		(width 0.127)
		(layer "In4.Cu")
		(net "PU_TAP_ODT_CPU0_EN")
	)
	(arc
		(start 351.29089 -229.71125)
		(mid 351.085398 -229.741221)
		(end 350.88703 -229.679754)
		(width 0.0889)
		(layer "In4.Cu")
		(net "PU_TAP_ODT_CPU0_EN")
	)
	(arc
		(start 341.62873 -228.45903)
		(mid 341.581051 -228.27613)
		(end 341.450168 -228.139752)
		(width 0.0889)
		(layer "In4.Cu")
		(net "PU_TAP_ODT_CPU0_EN")
	)
	(arc
		(start 346.18803 -229.679754)
		(mid 346.01858 -229.511908)
		(end 345.953334 -229.282498)
		(width 0.0889)
		(layer "In4.Cu")
		(net "PU_TAP_ODT_CPU0_EN")
	)
	(arc
		(start 343.36863 -228.865938)
		(mid 343.13368 -228.928898)
		(end 342.89873 -228.865938)
		(width 0.0889)
		(layer "In4.Cu")
		(net "PU_TAP_ODT_CPU0_EN")
	)
	(arc
		(start 347.584268 -229.687628)
		(mid 347.355015 -229.742872)
		(end 347.12783 -229.679754)
		(width 0.0889)
		(layer "In4.Cu")
		(net "PU_TAP_ODT_CPU0_EN")
	)
	(arc
		(start 350.403668 -229.687628)
		(mid 350.174415 -229.742872)
		(end 349.94723 -229.679754)
		(width 0.0889)
		(layer "In4.Cu")
		(net "PU_TAP_ODT_CPU0_EN")
	)
	(arc
		(start 339.844634 -226.831144)
		(mid 339.783071 -226.598621)
		(end 339.61451 -226.42703)
		(width 0.0889)
		(layer "In4.Cu")
		(net "PU_TAP_ODT_CPU0_EN")
	)
	(arc
		(start 338.90458 -225.203258)
		(mid 338.843017 -224.970735)
		(end 338.674456 -224.799144)
		(width 0.0889)
		(layer "In4.Cu")
		(net "PU_TAP_ODT_CPU0_EN")
	)
	(arc
		(start 349.94723 -229.679754)
		(mid 349.71228 -229.616794)
		(end 349.47733 -229.679754)
		(width 0.0889)
		(layer "In4.Cu")
		(net "PU_TAP_ODT_CPU0_EN")
	)
	(arc
		(start 337.250278 -224.801938)
		(mid 337.019547 -224.859299)
		(end 336.790284 -224.79635)
		(width 0.0889)
		(layer "In4.Cu")
		(net "PU_TAP_ODT_CPU0_EN")
	)
	(arc
		(start 342.78443 -228.865938)
		(mid 342.625061 -228.886921)
		(end 342.476582 -228.948488)
		(width 0.0889)
		(layer "In4.Cu")
		(net "PU_TAP_ODT_CPU0_EN")
	)
	(arc
		(start 341.159084 -227.480114)
		(mid 341.12164 -227.340394)
		(end 341.019384 -227.238052)
		(width 0.0889)
		(layer "In4.Cu")
		(net "PU_TAP_ODT_CPU0_EN")
	)
	(arc
		(start 337.72983 -224.79635)
		(mid 337.49488 -224.73339)
		(end 337.25993 -224.79635)
		(width 0.0889)
		(layer "In4.Cu")
		(net "PU_TAP_ODT_CPU0_EN")
	)
	(arc
		(start 336.785458 -224.793556)
		(mid 336.616902 -224.621962)
		(end 336.555334 -224.389442)
		(width 0.0889)
		(layer "In4.Cu")
		(net "PU_TAP_ODT_CPU0_EN")
	)
	(arc
		(start 338.66963 -224.79635)
		(mid 338.43468 -224.73339)
		(end 338.19973 -224.79635)
		(width 0.0889)
		(layer "In4.Cu")
		(net "PU_TAP_ODT_CPU0_EN")
	)
	(arc
		(start 340.07933 -227.238052)
		(mid 339.90988 -227.070206)
		(end 339.844634 -226.840796)
		(width 0.0889)
		(layer "In4.Cu")
		(net "PU_TAP_ODT_CPU0_EN")
	)
	(arc
		(start 346.644468 -229.687628)
		(mid 346.415215 -229.742872)
		(end 346.18803 -229.679754)
		(width 0.0889)
		(layer "In4.Cu")
		(net "PU_TAP_ODT_CPU0_EN")
	)
	(arc
		(start 345.708732 -228.86035)
		(mid 345.477747 -228.802867)
		(end 345.24823 -228.865938)
		(width 0.0889)
		(layer "In4.Cu")
		(net "PU_TAP_ODT_CPU0_EN")
	)
	(arc
		(start 344.764868 -228.858064)
		(mid 344.535615 -228.80282)
		(end 344.30843 -228.865938)
		(width 0.0889)
		(layer "In4.Cu")
		(net "PU_TAP_ODT_CPU0_EN")
	)
	(arc
		(start 336.085434 -223.575626)
		(mid 336.025479 -223.346016)
		(end 335.860898 -223.175068)
		(width 0.0889)
		(layer "In4.Cu")
		(net "PU_TAP_ODT_CPU0_EN")
	)
	(arc
		(start 339.374734 -226.017328)
		(mid 339.313677 -225.785695)
		(end 339.146388 -225.61423)
		(width 0.0889)
		(layer "In4.Cu")
		(net "PU_TAP_ODT_CPU0_EN")
	)
	(arc
		(start 349.00743 -229.679754)
		(mid 348.77248 -229.616794)
		(end 348.53753 -229.679754)
		(width 0.0889)
		(layer "In4.Cu")
		(net "PU_TAP_ODT_CPU0_EN")
	)
	(arc
		(start 341.019384 -227.238052)
		(mid 340.784434 -227.175092)
		(end 340.549484 -227.238052)
		(width 0.0889)
		(layer "In4.Cu")
		(net "PU_TAP_ODT_CPU0_EN")
	)
	(arc
		(start 342.476582 -228.948488)
		(mid 342.200023 -229.024231)
		(end 341.921846 -228.954584)
		(width 0.0889)
		(layer "In4.Cu")
		(net "PU_TAP_ODT_CPU0_EN")
	)
	(arc
		(start 348.06763 -229.679754)
		(mid 347.83268 -229.616794)
		(end 347.59773 -229.679754)
		(width 0.0889)
		(layer "In4.Cu")
		(net "PU_TAP_ODT_CPU0_EN")
	)
	(arc
		(start 335.85023 -223.168718)
		(mid 335.683342 -223.005501)
		(end 335.615534 -222.78213)
		(width 0.0889)
		(layer "In4.Cu")
		(net "PU_TAP_ODT_CPU0_EN")
	)
	(arc
		(start 336.32013 -223.982534)
		(mid 336.151826 -223.816794)
		(end 336.085434 -223.590104)
		(width 0.0889)
		(layer "In4.Cu")
		(net "PU_TAP_ODT_CPU0_EN")
	)
	(arc
		(start 335.615534 -222.761556)
		(mid 335.553971 -222.529033)
		(end 335.38541 -222.357442)
		(width 0.0889)
		(layer "In4.Cu")
		(net "PU_TAP_ODT_CPU0_EN")
	)
	(arc
		(start 348.524068 -229.687628)
		(mid 348.294815 -229.742872)
		(end 348.06763 -229.679754)
		(width 0.0889)
		(layer "In4.Cu")
		(net "PU_TAP_ODT_CPU0_EN")
	)
	(arc
		(start 345.953334 -229.272846)
		(mid 345.891771 -229.040323)
		(end 345.72321 -228.868732)
		(width 0.0889)
		(layer "In4.Cu")
		(net "PU_TAP_ODT_CPU0_EN")
	)
	(arc
		(start 340.539832 -227.24364)
		(mid 340.308847 -227.301123)
		(end 340.07933 -227.238052)
		(width 0.0889)
		(layer "In4.Cu")
		(net "PU_TAP_ODT_CPU0_EN")
	)
	(arc
		(start 341.905336 -228.944932)
		(mid 341.702749 -228.738581)
		(end 341.62873 -228.45903)
		(width 0.0889)
		(layer "In4.Cu")
		(net "PU_TAP_ODT_CPU0_EN")
	)
	(arc
		(start 338.186268 -224.804224)
		(mid 337.957015 -224.859468)
		(end 337.72983 -224.79635)
		(width 0.0889)
		(layer "In4.Cu")
		(net "PU_TAP_ODT_CPU0_EN")
	)
	(arc
		(start 336.555334 -224.389442)
		(mid 336.495379 -224.159832)
		(end 336.330798 -223.988884)
		(width 0.0889)
		(layer "In4.Cu")
		(net "PU_TAP_ODT_CPU0_EN")
	)
	(arc
		(start 345.24823 -228.865938)
		(mid 345.01328 -228.928898)
		(end 344.77833 -228.865938)
		(width 0.0889)
		(layer "In4.Cu")
		(net "PU_TAP_ODT_CPU0_EN")
	)
	(arc
		(start 350.88703 -229.679754)
		(mid 350.65208 -229.616794)
		(end 350.41713 -229.679754)
		(width 0.0889)
		(layer "In4.Cu")
		(net "PU_TAP_ODT_CPU0_EN")
	)
	(arc
		(start 339.604858 -226.421442)
		(mid 339.436302 -226.249848)
		(end 339.374734 -226.017328)
		(width 0.0889)
		(layer "In4.Cu")
		(net "PU_TAP_ODT_CPU0_EN")
	)
	(arc
		(start 341.441278 -228.134672)
		(mid 341.239996 -227.937185)
		(end 341.159084 -227.667058)
		(width 0.0889)
		(layer "In4.Cu")
		(net "PU_TAP_ODT_CPU0_EN")
	)
	(arc
		(start 347.12783 -229.679754)
		(mid 346.89288 -229.616794)
		(end 346.65793 -229.679754)
		(width 0.0889)
		(layer "In4.Cu")
		(net "PU_TAP_ODT_CPU0_EN")
	)
	(arc
		(start 349.47733 -229.679754)
		(mid 349.24238 -229.742714)
		(end 349.00743 -229.679754)
		(width 0.0889)
		(layer "In4.Cu")
		(net "PU_TAP_ODT_CPU0_EN")
	)
	(arc
		(start 339.134704 -225.607372)
		(mid 338.966148 -225.435778)
		(end 338.90458 -225.203258)
		(width 0.0889)
		(layer "In4.Cu")
		(net "PU_TAP_ODT_CPU0_EN")
	)
	(arc
		(start 343.825068 -228.858064)
		(mid 343.595815 -228.80282)
		(end 343.36863 -228.865938)
		(width 0.0889)
		(layer "In4.Cu")
		(net "PU_TAP_ODT_CPU0_EN")
	)
	(arc
		(start 344.30843 -228.865938)
		(mid 344.07348 -228.928898)
		(end 343.83853 -228.865938)
		(width 0.0889)
		(layer "In4.Cu")
		(net "PU_TAP_ODT_CPU0_EN")
	)
	(segment
		(start 432.456844 -40.592248)
		(end 433.30368 -40.592248)
		(width 0.12954)
		(layer "F.Cu")
		(net "PU_SWAP_OVERRIDE_N")
	)
	(segment
		(start 426.630084 -39.46525)
		(end 427.79188 -38.303454)
		(width 0.12954)
		(layer "F.Cu")
		(net "PU_SWAP_OVERRIDE_N")
	)
	(segment
		(start 426.630084 -39.539926)
		(end 426.630084 -39.46525)
		(width 0.12954)
		(layer "F.Cu")
		(net "PU_SWAP_OVERRIDE_N")
	)
	(segment
		(start 427.79188 -38.303454)
		(end 430.16805 -38.303454)
		(width 0.12954)
		(layer "F.Cu")
		(net "PU_SWAP_OVERRIDE_N")
	)
	(segment
		(start 430.16805 -38.303454)
		(end 432.456844 -40.592248)
		(width 0.12954)
		(layer "F.Cu")
		(net "PU_SWAP_OVERRIDE_N")
	)
	(segment
		(start 433.30368 -40.592248)
		(end 433.834032 -41.1226)
		(width 0.12954)
		(layer "F.Cu")
		(net "PU_SWAP_OVERRIDE_N")
	)
	(segment
		(start 433.834032 -41.1226)
		(end 434.785516 -41.1226)
		(width 0.12954)
		(layer "F.Cu")
		(net "PU_SWAP_OVERRIDE_N")
	)
	(via
		(at 433.30368 -40.592248)
		(size 0.762)
		(drill 0.381)
		(layers "F.Cu" "B.Cu")
		(net "PU_SWAP_OVERRIDE_N")
	)
	(segment
		(start 312.848244 -32.330644)
		(end 312.848244 -32.869886)
		(width 0.12954)
		(layer "F.Cu")
		(net "PU_SMB_SML4_3V3AUX_PCH_SDA")
	)
	(segment
		(start 321.95516 -38.651688)
		(end 322.946776 -39.643304)
		(width 0.12954)
		(layer "F.Cu")
		(net "PU_SMB_SML4_3V3AUX_PCH_SDA")
	)
	(segment
		(start 319.453514 -36.914328)
		(end 321.190874 -38.651688)
		(width 0.12954)
		(layer "F.Cu")
		(net "PU_SMB_SML4_3V3AUX_PCH_SDA")
	)
	(segment
		(start 323.485002 -39.881302)
		(end 325.550784 -41.947084)
		(width 0.0889)
		(layer "F.Cu")
		(net "PU_SMB_SML4_3V3AUX_PCH_SDA")
	)
	(segment
		(start 321.190874 -38.651688)
		(end 321.95516 -38.651688)
		(width 0.12954)
		(layer "F.Cu")
		(net "PU_SMB_SML4_3V3AUX_PCH_SDA")
	)
	(segment
		(start 323.184774 -39.881302)
		(end 323.485002 -39.881302)
		(width 0.0889)
		(layer "F.Cu")
		(net "PU_SMB_SML4_3V3AUX_PCH_SDA")
	)
	(segment
		(start 312.848244 -32.869886)
		(end 313.613292 -32.869886)
		(width 0.12954)
		(layer "F.Cu")
		(net "PU_SMB_SML4_3V3AUX_PCH_SDA")
	)
	(segment
		(start 312.293 -31.7754)
		(end 312.848244 -32.330644)
		(width 0.12954)
		(layer "F.Cu")
		(net "PU_SMB_SML4_3V3AUX_PCH_SDA")
	)
	(segment
		(start 313.613292 -32.869886)
		(end 316.99708 -35.130232)
		(width 0.12954)
		(layer "F.Cu")
		(net "PU_SMB_SML4_3V3AUX_PCH_SDA")
	)
	(segment
		(start 316.99708 -35.130232)
		(end 318.781176 -36.914328)
		(width 0.12954)
		(layer "F.Cu")
		(net "PU_SMB_SML4_3V3AUX_PCH_SDA")
	)
	(segment
		(start 318.781176 -36.914328)
		(end 319.453514 -36.914328)
		(width 0.12954)
		(layer "F.Cu")
		(net "PU_SMB_SML4_3V3AUX_PCH_SDA")
	)
	(segment
		(start 322.946776 -39.643304)
		(end 323.184774 -39.881302)
		(width 0.0889)
		(layer "F.Cu")
		(net "PU_SMB_SML4_3V3AUX_PCH_SDA")
	)
	(segment
		(start 325.550784 -41.947084)
		(end 326.584818 -41.947084)
		(width 0.0889)
		(layer "F.Cu")
		(net "PU_SMB_SML4_3V3AUX_PCH_SDA")
	)
	(via
		(at 312.293 -31.7754)
		(size 0.508)
		(drill 0.254)
		(layers "F.Cu" "B.Cu")
		(net "PU_SMB_SML4_3V3AUX_PCH_SDA")
	)
	(segment
		(start 319.964054 -34.230818)
		(end 325.05142 -39.318184)
		(width 0.12954)
		(layer "F.Cu")
		(net "PU_SMB_SML4_3V3AUX_PCH_SCL")
	)
	(segment
		(start 315.196982 -27.078686)
		(end 313.935364 -27.078686)
		(width 0.12954)
		(layer "F.Cu")
		(net "PU_SMB_SML4_3V3AUX_PCH_SCL")
	)
	(segment
		(start 316.0268 -28.666948)
		(end 316.741556 -29.381704)
		(width 0.12954)
		(layer "F.Cu")
		(net "PU_SMB_SML4_3V3AUX_PCH_SCL")
	)
	(segment
		(start 316.741556 -29.990542)
		(end 318.626998 -31.875984)
		(width 0.12954)
		(layer "F.Cu")
		(net "PU_SMB_SML4_3V3AUX_PCH_SCL")
	)
	(segment
		(start 325.332852 -39.556436)
		(end 325.332852 -39.656258)
		(width 0.0889)
		(layer "F.Cu")
		(net "PU_SMB_SML4_3V3AUX_PCH_SCL")
	)
	(segment
		(start 316.0268 -27.908504)
		(end 315.196982 -27.078686)
		(width 0.12954)
		(layer "F.Cu")
		(net "PU_SMB_SML4_3V3AUX_PCH_SCL")
	)
	(segment
		(start 319.455546 -34.230818)
		(end 319.964054 -34.230818)
		(width 0.12954)
		(layer "F.Cu")
		(net "PU_SMB_SML4_3V3AUX_PCH_SCL")
	)
	(segment
		(start 326.123046 -40.446452)
		(end 326.999854 -40.446452)
		(width 0.0889)
		(layer "F.Cu")
		(net "PU_SMB_SML4_3V3AUX_PCH_SCL")
	)
	(segment
		(start 318.626998 -31.875984)
		(end 318.626998 -33.40227)
		(width 0.12954)
		(layer "F.Cu")
		(net "PU_SMB_SML4_3V3AUX_PCH_SCL")
	)
	(segment
		(start 318.626998 -33.40227)
		(end 319.455546 -34.230818)
		(width 0.12954)
		(layer "F.Cu")
		(net "PU_SMB_SML4_3V3AUX_PCH_SCL")
	)
	(segment
		(start 325.05142 -39.318184)
		(end 325.0946 -39.318184)
		(width 0.12954)
		(layer "F.Cu")
		(net "PU_SMB_SML4_3V3AUX_PCH_SCL")
	)
	(segment
		(start 325.0946 -39.318184)
		(end 325.332852 -39.556436)
		(width 0.0889)
		(layer "F.Cu")
		(net "PU_SMB_SML4_3V3AUX_PCH_SCL")
	)
	(segment
		(start 316.741556 -29.381704)
		(end 316.741556 -29.990542)
		(width 0.12954)
		(layer "F.Cu")
		(net "PU_SMB_SML4_3V3AUX_PCH_SCL")
	)
	(segment
		(start 316.0268 -28.666948)
		(end 316.0268 -27.908504)
		(width 0.12954)
		(layer "F.Cu")
		(net "PU_SMB_SML4_3V3AUX_PCH_SCL")
	)
	(segment
		(start 325.332852 -39.656258)
		(end 326.123046 -40.446452)
		(width 0.0889)
		(layer "F.Cu")
		(net "PU_SMB_SML4_3V3AUX_PCH_SCL")
	)
	(via
		(at 316.0268 -28.666948)
		(size 0.508)
		(drill 0.254)
		(layers "F.Cu" "B.Cu")
		(net "PU_SMB_SML4_3V3AUX_PCH_SCL")
	)
	(segment
		(start 318.932306 -35.099498)
		(end 317.201804 -33.368996)
		(width 0.12954)
		(layer "F.Cu")
		(net "PU_SMB_SML3_3V3AUX_PCH_SDA")
	)
	(segment
		(start 315.44387 -32.30372)
		(end 314.165488 -31.449518)
		(width 0.12954)
		(layer "F.Cu")
		(net "PU_SMB_SML3_3V3AUX_PCH_SDA")
	)
	(segment
		(start 317.201804 -33.368996)
		(end 315.874654 -32.482282)
		(width 0.12954)
		(layer "F.Cu")
		(net "PU_SMB_SML3_3V3AUX_PCH_SDA")
	)
	(segment
		(start 323.828156 -39.027608)
		(end 322.360036 -37.559488)
		(width 0.12954)
		(layer "F.Cu")
		(net "PU_SMB_SML3_3V3AUX_PCH_SDA")
	)
	(segment
		(start 311.667398 -28.951428)
		(end 311.421526 -28.951428)
		(width 0.12954)
		(layer "F.Cu")
		(net "PU_SMB_SML3_3V3AUX_PCH_SDA")
	)
	(segment
		(start 314.165488 -31.449518)
		(end 311.667398 -28.951428)
		(width 0.12954)
		(layer "F.Cu")
		(net "PU_SMB_SML3_3V3AUX_PCH_SDA")
	)
	(segment
		(start 315.874654 -32.482282)
		(end 315.44387 -32.30372)
		(width 0.12954)
		(layer "F.Cu")
		(net "PU_SMB_SML3_3V3AUX_PCH_SDA")
	)
	(segment
		(start 310.769 -28.235148)
		(end 311.1754 -28.235148)
		(width 0.12954)
		(layer "F.Cu")
		(net "PU_SMB_SML3_3V3AUX_PCH_SDA")
	)
	(segment
		(start 319.603628 -35.099498)
		(end 318.932306 -35.099498)
		(width 0.12954)
		(layer "F.Cu")
		(net "PU_SMB_SML3_3V3AUX_PCH_SDA")
	)
	(segment
		(start 322.063618 -37.559488)
		(end 319.603628 -35.099498)
		(width 0.12954)
		(layer "F.Cu")
		(net "PU_SMB_SML3_3V3AUX_PCH_SDA")
	)
	(segment
		(start 311.421526 -28.481274)
		(end 311.421526 -28.951428)
		(width 0.12954)
		(layer "F.Cu")
		(net "PU_SMB_SML3_3V3AUX_PCH_SDA")
	)
	(segment
		(start 325.747126 -40.946578)
		(end 323.828156 -39.027608)
		(width 0.0889)
		(layer "F.Cu")
		(net "PU_SMB_SML3_3V3AUX_PCH_SDA")
	)
	(segment
		(start 311.1754 -28.235148)
		(end 311.421526 -28.481274)
		(width 0.12954)
		(layer "F.Cu")
		(net "PU_SMB_SML3_3V3AUX_PCH_SDA")
	)
	(segment
		(start 322.360036 -37.559488)
		(end 322.063618 -37.559488)
		(width 0.12954)
		(layer "F.Cu")
		(net "PU_SMB_SML3_3V3AUX_PCH_SDA")
	)
	(segment
		(start 326.584818 -40.946578)
		(end 325.747126 -40.946578)
		(width 0.0889)
		(layer "F.Cu")
		(net "PU_SMB_SML3_3V3AUX_PCH_SDA")
	)
	(via
		(at 310.769 -28.235148)
		(size 0.508)
		(drill 0.254)
		(layers "F.Cu" "B.Cu")
		(net "PU_SMB_SML3_3V3AUX_PCH_SDA")
	)
	(segment
		(start 321.282822 -44.113958)
		(end 321.815714 -44.334684)
		(width 0.12954)
		(layer "F.Cu")
		(net "PU_SMB_SML3_3V3AUX_PCH_SCL")
	)
	(segment
		(start 315.7474 -40.685974)
		(end 316.473078 -40.685974)
		(width 0.12954)
		(layer "F.Cu")
		(net "PU_SMB_SML3_3V3AUX_PCH_SCL")
	)
	(segment
		(start 322.482464 -44.614592)
		(end 322.575174 -44.614592)
		(width 0.12954)
		(layer "F.Cu")
		(net "PU_SMB_SML3_3V3AUX_PCH_SCL")
	)
	(segment
		(start 327.481946 -44.448222)
		(end 327.829926 -44.448222)
		(width 0.0889)
		(layer "F.Cu")
		(net "PU_SMB_SML3_3V3AUX_PCH_SCL")
	)
	(segment
		(start 321.822064 -44.341034)
		(end 322.482464 -44.614592)
		(width 0.12954)
		(layer "F.Cu")
		(net "PU_SMB_SML3_3V3AUX_PCH_SCL")
	)
	(segment
		(start 321.273678 -44.113958)
		(end 321.282822 -44.113958)
		(width 0.12954)
		(layer "F.Cu")
		(net "PU_SMB_SML3_3V3AUX_PCH_SCL")
	)
	(segment
		(start 319.191386 -42.873168)
		(end 319.674494 -43.073574)
		(width 0.12954)
		(layer "F.Cu")
		(net "PU_SMB_SML3_3V3AUX_PCH_SCL")
	)
	(segment
		(start 317.89497 -42.107866)
		(end 318.426084 -42.107866)
		(width 0.12954)
		(layer "F.Cu")
		(net "PU_SMB_SML3_3V3AUX_PCH_SCL")
	)
	(segment
		(start 326.82815 -44.749974)
		(end 327.14565 -44.749974)
		(width 0.0889)
		(layer "F.Cu")
		(net "PU_SMB_SML3_3V3AUX_PCH_SCL")
	)
	(segment
		(start 323.182996 -44.638722)
		(end 326.488552 -44.638722)
		(width 0.0889)
		(layer "F.Cu")
		(net "PU_SMB_SML3_3V3AUX_PCH_SCL")
	)
	(segment
		(start 319.674494 -43.073574)
		(end 320.18224 -43.58132)
		(width 0.12954)
		(layer "F.Cu")
		(net "PU_SMB_SML3_3V3AUX_PCH_SCL")
	)
	(segment
		(start 321.815714 -44.334684)
		(end 321.822064 -44.341034)
		(width 0.12954)
		(layer "F.Cu")
		(net "PU_SMB_SML3_3V3AUX_PCH_SCL")
	)
	(segment
		(start 327.14565 -44.749974)
		(end 327.399904 -44.530264)
		(width 0.0889)
		(layer "F.Cu")
		(net "PU_SMB_SML3_3V3AUX_PCH_SCL")
	)
	(segment
		(start 318.426084 -42.107866)
		(end 319.191386 -42.873168)
		(width 0.12954)
		(layer "F.Cu")
		(net "PU_SMB_SML3_3V3AUX_PCH_SCL")
	)
	(segment
		(start 316.473078 -40.685974)
		(end 317.89497 -42.107866)
		(width 0.12954)
		(layer "F.Cu")
		(net "PU_SMB_SML3_3V3AUX_PCH_SCL")
	)
	(segment
		(start 320.499232 -43.793156)
		(end 321.273678 -44.113958)
		(width 0.12954)
		(layer "F.Cu")
		(net "PU_SMB_SML3_3V3AUX_PCH_SCL")
	)
	(segment
		(start 309.922672 -40.143684)
		(end 310.464962 -40.685974)
		(width 0.12954)
		(layer "F.Cu")
		(net "PU_SMB_SML3_3V3AUX_PCH_SCL")
	)
	(segment
		(start 327.399904 -44.530264)
		(end 327.481946 -44.448222)
		(width 0.0889)
		(layer "F.Cu")
		(net "PU_SMB_SML3_3V3AUX_PCH_SCL")
	)
	(segment
		(start 309.922672 -40.122348)
		(end 309.922672 -40.143684)
		(width 0.12954)
		(layer "F.Cu")
		(net "PU_SMB_SML3_3V3AUX_PCH_SCL")
	)
	(segment
		(start 320.18224 -43.58132)
		(end 320.499232 -43.793156)
		(width 0.12954)
		(layer "F.Cu")
		(net "PU_SMB_SML3_3V3AUX_PCH_SCL")
	)
	(segment
		(start 323.158866 -44.614592)
		(end 323.182996 -44.638722)
		(width 0.0889)
		(layer "F.Cu")
		(net "PU_SMB_SML3_3V3AUX_PCH_SCL")
	)
	(segment
		(start 326.488552 -44.638722)
		(end 326.711056 -44.648882)
		(width 0.0889)
		(layer "F.Cu")
		(net "PU_SMB_SML3_3V3AUX_PCH_SCL")
	)
	(segment
		(start 322.575174 -44.614592)
		(end 323.158866 -44.614592)
		(width 0.0889)
		(layer "F.Cu")
		(net "PU_SMB_SML3_3V3AUX_PCH_SCL")
	)
	(segment
		(start 310.464962 -40.685974)
		(end 315.7474 -40.685974)
		(width 0.12954)
		(layer "F.Cu")
		(net "PU_SMB_SML3_3V3AUX_PCH_SCL")
	)
	(segment
		(start 326.711056 -44.648882)
		(end 326.82815 -44.749974)
		(width 0.0889)
		(layer "F.Cu")
		(net "PU_SMB_SML3_3V3AUX_PCH_SCL")
	)
	(via
		(at 315.7474 -40.685974)
		(size 0.508)
		(drill 0.254)
		(layers "F.Cu" "B.Cu")
		(net "PU_SMB_SML3_3V3AUX_PCH_SCL")
	)
	(segment
		(start 313.19978 -36.198048)
		(end 313.617102 -36.198048)
		(width 0.12954)
		(layer "F.Cu")
		(net "PU_SMB_PCH_PLD_3V3AUX_SDA")
	)
	(segment
		(start 323.295264 -41.704514)
		(end 324.53834 -42.94759)
		(width 0.0889)
		(layer "F.Cu")
		(net "PU_SMB_PCH_PLD_3V3AUX_SDA")
	)
	(segment
		(start 313.617102 -36.198048)
		(end 314.462922 -37.043868)
		(width 0.12954)
		(layer "F.Cu")
		(net "PU_SMB_PCH_PLD_3V3AUX_SDA")
	)
	(segment
		(start 324.53834 -42.94759)
		(end 326.584818 -42.94759)
		(width 0.0889)
		(layer "F.Cu")
		(net "PU_SMB_PCH_PLD_3V3AUX_SDA")
	)
	(segment
		(start 314.462922 -37.043868)
		(end 315.2394 -37.043868)
		(width 0.12954)
		(layer "F.Cu")
		(net "PU_SMB_PCH_PLD_3V3AUX_SDA")
	)
	(segment
		(start 318.37757 -38.847268)
		(end 319.19545 -38.847268)
		(width 0.12954)
		(layer "F.Cu")
		(net "PU_SMB_PCH_PLD_3V3AUX_SDA")
	)
	(segment
		(start 322.766944 -41.704514)
		(end 323.295264 -41.704514)
		(width 0.0889)
		(layer "F.Cu")
		(net "PU_SMB_PCH_PLD_3V3AUX_SDA")
	)
	(segment
		(start 322.575174 -41.512744)
		(end 322.766944 -41.704514)
		(width 0.0889)
		(layer "F.Cu")
		(net "PU_SMB_PCH_PLD_3V3AUX_SDA")
	)
	(segment
		(start 321.702176 -40.639746)
		(end 322.575174 -41.512744)
		(width 0.12954)
		(layer "F.Cu")
		(net "PU_SMB_PCH_PLD_3V3AUX_SDA")
	)
	(segment
		(start 312.843672 -35.84194)
		(end 313.19978 -36.198048)
		(width 0.12954)
		(layer "F.Cu")
		(net "PU_SMB_PCH_PLD_3V3AUX_SDA")
	)
	(segment
		(start 319.19545 -38.847268)
		(end 320.14668 -39.798498)
		(width 0.12954)
		(layer "F.Cu")
		(net "PU_SMB_PCH_PLD_3V3AUX_SDA")
	)
	(segment
		(start 316.57417 -37.043868)
		(end 318.37757 -38.847268)
		(width 0.12954)
		(layer "F.Cu")
		(net "PU_SMB_PCH_PLD_3V3AUX_SDA")
	)
	(segment
		(start 320.14668 -39.798498)
		(end 321.473576 -39.798498)
		(width 0.12954)
		(layer "F.Cu")
		(net "PU_SMB_PCH_PLD_3V3AUX_SDA")
	)
	(segment
		(start 321.473576 -39.798498)
		(end 321.702176 -40.027098)
		(width 0.12954)
		(layer "F.Cu")
		(net "PU_SMB_PCH_PLD_3V3AUX_SDA")
	)
	(segment
		(start 321.702176 -40.027098)
		(end 321.702176 -40.639746)
		(width 0.12954)
		(layer "F.Cu")
		(net "PU_SMB_PCH_PLD_3V3AUX_SDA")
	)
	(segment
		(start 315.2394 -37.043868)
		(end 316.57417 -37.043868)
		(width 0.12954)
		(layer "F.Cu")
		(net "PU_SMB_PCH_PLD_3V3AUX_SDA")
	)
	(via
		(at 315.2394 -37.043868)
		(size 0.508)
		(drill 0.254)
		(layers "F.Cu" "B.Cu")
		(net "PU_SMB_PCH_PLD_3V3AUX_SDA")
	)
	(segment
		(start 322.614798 -45.033692)
		(end 322.741544 -44.906946)
		(width 0.0889)
		(layer "F.Cu")
		(net "PU_SMB_PCH_PLD_3V3AUX_SCL")
	)
	(segment
		(start 316.264544 -41.881806)
		(end 316.553088 -41.881806)
		(width 0.12954)
		(layer "F.Cu")
		(net "PU_SMB_PCH_PLD_3V3AUX_SCL")
	)
	(segment
		(start 319.86474 -44.318174)
		(end 320.580258 -45.033692)
		(width 0.12954)
		(layer "F.Cu")
		(net "PU_SMB_PCH_PLD_3V3AUX_SCL")
	)
	(segment
		(start 316.553088 -41.881806)
		(end 317.250572 -42.57929)
		(width 0.12954)
		(layer "F.Cu")
		(net "PU_SMB_PCH_PLD_3V3AUX_SCL")
	)
	(segment
		(start 319.86474 -44.178982)
		(end 319.86474 -44.318174)
		(width 0.12954)
		(layer "F.Cu")
		(net "PU_SMB_PCH_PLD_3V3AUX_SCL")
	)
	(segment
		(start 312.843672 -41.519348)
		(end 313.211972 -41.151048)
		(width 0.12954)
		(layer "F.Cu")
		(net "PU_SMB_PCH_PLD_3V3AUX_SCL")
	)
	(segment
		(start 326.344026 -44.948602)
		(end 326.584818 -44.948602)
		(width 0.0889)
		(layer "F.Cu")
		(net "PU_SMB_PCH_PLD_3V3AUX_SCL")
	)
	(segment
		(start 317.250572 -42.57929)
		(end 318.265048 -42.57929)
		(width 0.12954)
		(layer "F.Cu")
		(net "PU_SMB_PCH_PLD_3V3AUX_SCL")
	)
	(segment
		(start 318.265048 -42.57929)
		(end 319.86474 -44.178982)
		(width 0.12954)
		(layer "F.Cu")
		(net "PU_SMB_PCH_PLD_3V3AUX_SCL")
	)
	(segment
		(start 315.533786 -41.151048)
		(end 316.264544 -41.881806)
		(width 0.12954)
		(layer "F.Cu")
		(net "PU_SMB_PCH_PLD_3V3AUX_SCL")
	)
	(segment
		(start 322.741544 -44.906946)
		(end 326.30237 -44.906946)
		(width 0.0889)
		(layer "F.Cu")
		(net "PU_SMB_PCH_PLD_3V3AUX_SCL")
	)
	(segment
		(start 320.580258 -45.033692)
		(end 322.614798 -45.033692)
		(width 0.12954)
		(layer "F.Cu")
		(net "PU_SMB_PCH_PLD_3V3AUX_SCL")
	)
	(segment
		(start 326.30237 -44.906946)
		(end 326.344026 -44.948602)
		(width 0.0889)
		(layer "F.Cu")
		(net "PU_SMB_PCH_PLD_3V3AUX_SCL")
	)
	(segment
		(start 313.211972 -41.151048)
		(end 315.533786 -41.151048)
		(width 0.12954)
		(layer "F.Cu")
		(net "PU_SMB_PCH_PLD_3V3AUX_SCL")
	)
	(via
		(at 316.553088 -41.881806)
		(size 0.508)
		(drill 0.254)
		(layers "F.Cu" "B.Cu")
		(net "PU_SMB_PCH_PLD_3V3AUX_SCL")
	)
	(segment
		(start 116.449094 -268.56944)
		(end 116.449348 -268.569694)
		(width 0.12954)
		(layer "F.Cu")
		(net "PU_S3M_CPU1_CPLD_STATUS")
	)
	(segment
		(start 116.449094 -268.033754)
		(end 116.449094 -268.56944)
		(width 0.12954)
		(layer "F.Cu")
		(net "PU_S3M_CPU1_CPLD_STATUS")
	)
	(via
		(at 150.28545 -268.37894)
		(size 0.6604)
		(drill 0.3302)
		(layers "F.Cu" "B.Cu")
		(net "PU_S3M_CPU1_CPLD_STATUS")
	)
	(via
		(at 116.449348 -268.569694)
		(size 0.4572)
		(drill 0.2032)
		(layers "F.Cu" "B.Cu")
		(net "PU_S3M_CPU1_CPLD_STATUS")
	)
	(segment
		(start 149.262338 -268.573758)
		(end 149.457156 -268.37894)
		(width 0.12954)
		(layer "B.Cu")
		(net "PU_S3M_CPU1_CPLD_STATUS")
	)
	(segment
		(start 170.778424 -258.403852)
		(end 171.140882 -257.804666)
		(width 0.12954)
		(layer "B.Cu")
		(net "PU_S3M_CPU1_CPLD_STATUS")
	)
	(segment
		(start 120.950736 -268.251432)
		(end 120.96115 -268.245336)
		(width 0.0889)
		(layer "B.Cu")
		(net "PU_S3M_CPU1_CPLD_STATUS")
	)
	(segment
		(start 170.778424 -267.62583)
		(end 170.778424 -258.403852)
		(width 0.12954)
		(layer "B.Cu")
		(net "PU_S3M_CPU1_CPLD_STATUS")
	)
	(segment
		(start 150.55088 -268.11351)
		(end 157.83814 -268.11351)
		(width 0.12954)
		(layer "B.Cu")
		(net "PU_S3M_CPU1_CPLD_STATUS")
	)
	(segment
		(start 138.452352 -268.573758)
		(end 149.262338 -268.573758)
		(width 0.12954)
		(layer "B.Cu")
		(net "PU_S3M_CPU1_CPLD_STATUS")
	)
	(segment
		(start 116.449348 -268.569694)
		(end 116.605812 -268.298676)
		(width 0.0889)
		(layer "B.Cu")
		(net "PU_S3M_CPU1_CPLD_STATUS")
	)
	(segment
		(start 133.552946 -268.245336)
		(end 133.567678 -268.253972)
		(width 0.0889)
		(layer "B.Cu")
		(net "PU_S3M_CPU1_CPLD_STATUS")
	)
	(segment
		(start 134.492746 -268.245336)
		(end 134.507478 -268.253972)
		(width 0.0889)
		(layer "B.Cu")
		(net "PU_S3M_CPU1_CPLD_STATUS")
	)
	(segment
		(start 149.457156 -268.37894)
		(end 150.28545 -268.37894)
		(width 0.12954)
		(layer "B.Cu")
		(net "PU_S3M_CPU1_CPLD_STATUS")
	)
	(segment
		(start 127.914146 -268.245336)
		(end 127.928878 -268.253972)
		(width 0.0889)
		(layer "B.Cu")
		(net "PU_S3M_CPU1_CPLD_STATUS")
	)
	(segment
		(start 165.048438 -269.95501)
		(end 167.926258 -269.95501)
		(width 0.12954)
		(layer "B.Cu")
		(net "PU_S3M_CPU1_CPLD_STATUS")
	)
	(segment
		(start 126.034546 -268.245336)
		(end 126.049278 -268.253972)
		(width 0.0889)
		(layer "B.Cu")
		(net "PU_S3M_CPU1_CPLD_STATUS")
	)
	(segment
		(start 160.290764 -269.89151)
		(end 160.891728 -270.492474)
		(width 0.12954)
		(layer "B.Cu")
		(net "PU_S3M_CPU1_CPLD_STATUS")
	)
	(segment
		(start 178.153822 -256.78892)
		(end 179.688998 -255.253744)
		(width 0.12954)
		(layer "B.Cu")
		(net "PU_S3M_CPU1_CPLD_STATUS")
	)
	(segment
		(start 164.510974 -270.492474)
		(end 165.048438 -269.95501)
		(width 0.12954)
		(layer "B.Cu")
		(net "PU_S3M_CPU1_CPLD_STATUS")
	)
	(segment
		(start 128.853946 -268.245336)
		(end 128.868678 -268.253972)
		(width 0.0889)
		(layer "B.Cu")
		(net "PU_S3M_CPU1_CPLD_STATUS")
	)
	(segment
		(start 179.688998 -255.253744)
		(end 179.688998 -253.779782)
		(width 0.12954)
		(layer "B.Cu")
		(net "PU_S3M_CPU1_CPLD_STATUS")
	)
	(segment
		(start 150.28545 -268.37894)
		(end 150.55088 -268.11351)
		(width 0.12954)
		(layer "B.Cu")
		(net "PU_S3M_CPU1_CPLD_STATUS")
	)
	(segment
		(start 159.61614 -269.89151)
		(end 160.290764 -269.89151)
		(width 0.12954)
		(layer "B.Cu")
		(net "PU_S3M_CPU1_CPLD_STATUS")
	)
	(segment
		(start 168.909238 -268.97203)
		(end 169.432224 -268.97203)
		(width 0.12954)
		(layer "B.Cu")
		(net "PU_S3M_CPU1_CPLD_STATUS")
	)
	(segment
		(start 169.432224 -268.97203)
		(end 170.778424 -267.62583)
		(width 0.12954)
		(layer "B.Cu")
		(net "PU_S3M_CPU1_CPLD_STATUS")
	)
	(segment
		(start 119.070882 -268.251432)
		(end 119.081296 -268.245336)
		(width 0.0889)
		(layer "B.Cu")
		(net "PU_S3M_CPU1_CPLD_STATUS")
	)
	(segment
		(start 160.891728 -270.492474)
		(end 164.510974 -270.492474)
		(width 0.12954)
		(layer "B.Cu")
		(net "PU_S3M_CPU1_CPLD_STATUS")
	)
	(segment
		(start 129.793746 -268.245336)
		(end 129.808478 -268.253972)
		(width 0.0889)
		(layer "B.Cu")
		(net "PU_S3M_CPU1_CPLD_STATUS")
	)
	(segment
		(start 117.576092 -268.245336)
		(end 117.586506 -268.251432)
		(width 0.0889)
		(layer "B.Cu")
		(net "PU_S3M_CPU1_CPLD_STATUS")
	)
	(segment
		(start 124.154946 -268.245336)
		(end 124.169678 -268.253972)
		(width 0.0889)
		(layer "B.Cu")
		(net "PU_S3M_CPU1_CPLD_STATUS")
	)
	(segment
		(start 157.83814 -268.11351)
		(end 159.61614 -269.89151)
		(width 0.12954)
		(layer "B.Cu")
		(net "PU_S3M_CPU1_CPLD_STATUS")
	)
	(segment
		(start 116.605812 -268.298676)
		(end 116.694966 -268.2748)
		(width 0.0889)
		(layer "B.Cu")
		(net "PU_S3M_CPU1_CPLD_STATUS")
	)
	(segment
		(start 130.733546 -268.245336)
		(end 130.748278 -268.253972)
		(width 0.0889)
		(layer "B.Cu")
		(net "PU_S3M_CPU1_CPLD_STATUS")
	)
	(segment
		(start 125.094746 -268.245336)
		(end 125.109478 -268.253972)
		(width 0.0889)
		(layer "B.Cu")
		(net "PU_S3M_CPU1_CPLD_STATUS")
	)
	(segment
		(start 179.688998 -253.779782)
		(end 181.681628 -251.787152)
		(width 0.12954)
		(layer "B.Cu")
		(net "PU_S3M_CPU1_CPLD_STATUS")
	)
	(segment
		(start 123.214892 -268.245336)
		(end 123.225306 -268.251432)
		(width 0.0889)
		(layer "B.Cu")
		(net "PU_S3M_CPU1_CPLD_STATUS")
	)
	(segment
		(start 117.191282 -268.251432)
		(end 117.201696 -268.245336)
		(width 0.0889)
		(layer "B.Cu")
		(net "PU_S3M_CPU1_CPLD_STATUS")
	)
	(segment
		(start 137.59053 -268.571726)
		(end 138.45032 -268.571726)
		(width 0.0889)
		(layer "B.Cu")
		(net "PU_S3M_CPU1_CPLD_STATUS")
	)
	(segment
		(start 181.681628 -193.25082)
		(end 181.530752 -193.099944)
		(width 0.12954)
		(layer "B.Cu")
		(net "PU_S3M_CPU1_CPLD_STATUS")
	)
	(segment
		(start 173.139862 -256.78892)
		(end 178.153822 -256.78892)
		(width 0.12954)
		(layer "B.Cu")
		(net "PU_S3M_CPU1_CPLD_STATUS")
	)
	(segment
		(start 132.613146 -268.245336)
		(end 132.627878 -268.253972)
		(width 0.0889)
		(layer "B.Cu")
		(net "PU_S3M_CPU1_CPLD_STATUS")
	)
	(segment
		(start 181.681628 -251.787152)
		(end 181.681628 -193.25082)
		(width 0.12954)
		(layer "B.Cu")
		(net "PU_S3M_CPU1_CPLD_STATUS")
	)
	(segment
		(start 167.926258 -269.95501)
		(end 168.909238 -268.97203)
		(width 0.12954)
		(layer "B.Cu")
		(net "PU_S3M_CPU1_CPLD_STATUS")
	)
	(segment
		(start 121.890282 -268.251432)
		(end 121.900696 -268.245336)
		(width 0.0889)
		(layer "B.Cu")
		(net "PU_S3M_CPU1_CPLD_STATUS")
	)
	(segment
		(start 138.45032 -268.571726)
		(end 138.452352 -268.573758)
		(width 0.0889)
		(layer "B.Cu")
		(net "PU_S3M_CPU1_CPLD_STATUS")
	)
	(segment
		(start 126.974346 -268.245336)
		(end 126.989078 -268.253972)
		(width 0.0889)
		(layer "B.Cu")
		(net "PU_S3M_CPU1_CPLD_STATUS")
	)
	(segment
		(start 135.432546 -268.245336)
		(end 135.44296 -268.251432)
		(width 0.0889)
		(layer "B.Cu")
		(net "PU_S3M_CPU1_CPLD_STATUS")
	)
	(segment
		(start 171.140882 -257.804666)
		(end 173.139862 -256.78892)
		(width 0.12954)
		(layer "B.Cu")
		(net "PU_S3M_CPU1_CPLD_STATUS")
	)
	(arc
		(start 120.96115 -268.245336)
		(mid 121.148348 -268.195193)
		(end 121.335546 -268.245336)
		(width 0.0889)
		(layer "B.Cu")
		(net "PU_S3M_CPU1_CPLD_STATUS")
	)
	(arc
		(start 134.11835 -268.245336)
		(mid 134.305548 -268.195193)
		(end 134.492746 -268.245336)
		(width 0.0889)
		(layer "B.Cu")
		(net "PU_S3M_CPU1_CPLD_STATUS")
	)
	(arc
		(start 121.335546 -268.245336)
		(mid 121.612105 -268.321079)
		(end 121.890282 -268.251432)
		(width 0.0889)
		(layer "B.Cu")
		(net "PU_S3M_CPU1_CPLD_STATUS")
	)
	(arc
		(start 119.455692 -268.245336)
		(mid 119.738394 -268.321112)
		(end 120.021096 -268.245336)
		(width 0.0889)
		(layer "B.Cu")
		(net "PU_S3M_CPU1_CPLD_STATUS")
	)
	(arc
		(start 127.928878 -268.253972)
		(mid 128.205353 -268.321292)
		(end 128.47955 -268.245336)
		(width 0.0889)
		(layer "B.Cu")
		(net "PU_S3M_CPU1_CPLD_STATUS")
	)
	(arc
		(start 131.673346 -268.245336)
		(mid 131.956048 -268.321112)
		(end 132.23875 -268.245336)
		(width 0.0889)
		(layer "B.Cu")
		(net "PU_S3M_CPU1_CPLD_STATUS")
	)
	(arc
		(start 118.516146 -268.245336)
		(mid 118.792705 -268.321079)
		(end 119.070882 -268.251432)
		(width 0.0889)
		(layer "B.Cu")
		(net "PU_S3M_CPU1_CPLD_STATUS")
	)
	(arc
		(start 117.586506 -268.251432)
		(mid 117.864938 -268.321278)
		(end 118.14175 -268.245336)
		(width 0.0889)
		(layer "B.Cu")
		(net "PU_S3M_CPU1_CPLD_STATUS")
	)
	(arc
		(start 122.840496 -268.245336)
		(mid 123.027694 -268.195193)
		(end 123.214892 -268.245336)
		(width 0.0889)
		(layer "B.Cu")
		(net "PU_S3M_CPU1_CPLD_STATUS")
	)
	(arc
		(start 131.29895 -268.245336)
		(mid 131.486148 -268.195193)
		(end 131.673346 -268.245336)
		(width 0.0889)
		(layer "B.Cu")
		(net "PU_S3M_CPU1_CPLD_STATUS")
	)
	(arc
		(start 123.225306 -268.251432)
		(mid 123.503738 -268.321278)
		(end 123.78055 -268.245336)
		(width 0.0889)
		(layer "B.Cu")
		(net "PU_S3M_CPU1_CPLD_STATUS")
	)
	(arc
		(start 135.44296 -268.251432)
		(mid 135.721138 -268.321155)
		(end 135.997696 -268.245336)
		(width 0.0889)
		(layer "B.Cu")
		(net "PU_S3M_CPU1_CPLD_STATUS")
	)
	(arc
		(start 136.372092 -268.245336)
		(mid 136.959826 -268.488747)
		(end 137.59053 -268.571726)
		(width 0.0889)
		(layer "B.Cu")
		(net "PU_S3M_CPU1_CPLD_STATUS")
	)
	(arc
		(start 135.997696 -268.245336)
		(mid 136.184894 -268.195193)
		(end 136.372092 -268.245336)
		(width 0.0889)
		(layer "B.Cu")
		(net "PU_S3M_CPU1_CPLD_STATUS")
	)
	(arc
		(start 124.169678 -268.253972)
		(mid 124.446153 -268.321292)
		(end 124.72035 -268.245336)
		(width 0.0889)
		(layer "B.Cu")
		(net "PU_S3M_CPU1_CPLD_STATUS")
	)
	(arc
		(start 116.694966 -268.2748)
		(mid 116.94583 -268.320569)
		(end 117.191282 -268.251432)
		(width 0.0889)
		(layer "B.Cu")
		(net "PU_S3M_CPU1_CPLD_STATUS")
	)
	(arc
		(start 119.081296 -268.245336)
		(mid 119.268494 -268.195193)
		(end 119.455692 -268.245336)
		(width 0.0889)
		(layer "B.Cu")
		(net "PU_S3M_CPU1_CPLD_STATUS")
	)
	(arc
		(start 117.201696 -268.245336)
		(mid 117.388894 -268.195193)
		(end 117.576092 -268.245336)
		(width 0.0889)
		(layer "B.Cu")
		(net "PU_S3M_CPU1_CPLD_STATUS")
	)
	(arc
		(start 128.47955 -268.245336)
		(mid 128.666748 -268.195193)
		(end 128.853946 -268.245336)
		(width 0.0889)
		(layer "B.Cu")
		(net "PU_S3M_CPU1_CPLD_STATUS")
	)
	(arc
		(start 132.627878 -268.253972)
		(mid 132.904353 -268.321292)
		(end 133.17855 -268.245336)
		(width 0.0889)
		(layer "B.Cu")
		(net "PU_S3M_CPU1_CPLD_STATUS")
	)
	(arc
		(start 126.049278 -268.253972)
		(mid 126.325753 -268.321292)
		(end 126.59995 -268.245336)
		(width 0.0889)
		(layer "B.Cu")
		(net "PU_S3M_CPU1_CPLD_STATUS")
	)
	(arc
		(start 133.567678 -268.253972)
		(mid 133.844153 -268.321292)
		(end 134.11835 -268.245336)
		(width 0.0889)
		(layer "B.Cu")
		(net "PU_S3M_CPU1_CPLD_STATUS")
	)
	(arc
		(start 130.35915 -268.245336)
		(mid 130.546348 -268.195193)
		(end 130.733546 -268.245336)
		(width 0.0889)
		(layer "B.Cu")
		(net "PU_S3M_CPU1_CPLD_STATUS")
	)
	(arc
		(start 129.808478 -268.253972)
		(mid 130.084953 -268.321292)
		(end 130.35915 -268.245336)
		(width 0.0889)
		(layer "B.Cu")
		(net "PU_S3M_CPU1_CPLD_STATUS")
	)
	(arc
		(start 122.275092 -268.245336)
		(mid 122.557794 -268.321112)
		(end 122.840496 -268.245336)
		(width 0.0889)
		(layer "B.Cu")
		(net "PU_S3M_CPU1_CPLD_STATUS")
	)
	(arc
		(start 120.021096 -268.245336)
		(mid 120.208294 -268.195193)
		(end 120.395492 -268.245336)
		(width 0.0889)
		(layer "B.Cu")
		(net "PU_S3M_CPU1_CPLD_STATUS")
	)
	(arc
		(start 135.05815 -268.245336)
		(mid 135.245348 -268.195193)
		(end 135.432546 -268.245336)
		(width 0.0889)
		(layer "B.Cu")
		(net "PU_S3M_CPU1_CPLD_STATUS")
	)
	(arc
		(start 129.41935 -268.245336)
		(mid 129.606548 -268.195193)
		(end 129.793746 -268.245336)
		(width 0.0889)
		(layer "B.Cu")
		(net "PU_S3M_CPU1_CPLD_STATUS")
	)
	(arc
		(start 124.72035 -268.245336)
		(mid 124.907548 -268.195193)
		(end 125.094746 -268.245336)
		(width 0.0889)
		(layer "B.Cu")
		(net "PU_S3M_CPU1_CPLD_STATUS")
	)
	(arc
		(start 128.868678 -268.253972)
		(mid 129.145153 -268.321292)
		(end 129.41935 -268.245336)
		(width 0.0889)
		(layer "B.Cu")
		(net "PU_S3M_CPU1_CPLD_STATUS")
	)
	(arc
		(start 132.23875 -268.245336)
		(mid 132.425948 -268.195193)
		(end 132.613146 -268.245336)
		(width 0.0889)
		(layer "B.Cu")
		(net "PU_S3M_CPU1_CPLD_STATUS")
	)
	(arc
		(start 133.17855 -268.245336)
		(mid 133.365748 -268.195193)
		(end 133.552946 -268.245336)
		(width 0.0889)
		(layer "B.Cu")
		(net "PU_S3M_CPU1_CPLD_STATUS")
	)
	(arc
		(start 118.14175 -268.245336)
		(mid 118.328948 -268.195193)
		(end 118.516146 -268.245336)
		(width 0.0889)
		(layer "B.Cu")
		(net "PU_S3M_CPU1_CPLD_STATUS")
	)
	(arc
		(start 125.66015 -268.245336)
		(mid 125.847348 -268.195193)
		(end 126.034546 -268.245336)
		(width 0.0889)
		(layer "B.Cu")
		(net "PU_S3M_CPU1_CPLD_STATUS")
	)
	(arc
		(start 125.109478 -268.253972)
		(mid 125.385953 -268.321292)
		(end 125.66015 -268.245336)
		(width 0.0889)
		(layer "B.Cu")
		(net "PU_S3M_CPU1_CPLD_STATUS")
	)
	(arc
		(start 123.78055 -268.245336)
		(mid 123.967748 -268.195193)
		(end 124.154946 -268.245336)
		(width 0.0889)
		(layer "B.Cu")
		(net "PU_S3M_CPU1_CPLD_STATUS")
	)
	(arc
		(start 121.900696 -268.245336)
		(mid 122.087894 -268.195193)
		(end 122.275092 -268.245336)
		(width 0.0889)
		(layer "B.Cu")
		(net "PU_S3M_CPU1_CPLD_STATUS")
	)
	(arc
		(start 120.395492 -268.245336)
		(mid 120.672305 -268.321206)
		(end 120.950736 -268.251432)
		(width 0.0889)
		(layer "B.Cu")
		(net "PU_S3M_CPU1_CPLD_STATUS")
	)
	(arc
		(start 134.507478 -268.253972)
		(mid 134.783953 -268.321292)
		(end 135.05815 -268.245336)
		(width 0.0889)
		(layer "B.Cu")
		(net "PU_S3M_CPU1_CPLD_STATUS")
	)
	(arc
		(start 130.748278 -268.253972)
		(mid 131.024753 -268.321292)
		(end 131.29895 -268.245336)
		(width 0.0889)
		(layer "B.Cu")
		(net "PU_S3M_CPU1_CPLD_STATUS")
	)
	(arc
		(start 127.53975 -268.245336)
		(mid 127.726948 -268.195193)
		(end 127.914146 -268.245336)
		(width 0.0889)
		(layer "B.Cu")
		(net "PU_S3M_CPU1_CPLD_STATUS")
	)
	(arc
		(start 126.59995 -268.245336)
		(mid 126.787148 -268.195193)
		(end 126.974346 -268.245336)
		(width 0.0889)
		(layer "B.Cu")
		(net "PU_S3M_CPU1_CPLD_STATUS")
	)
	(arc
		(start 126.989078 -268.253972)
		(mid 127.265553 -268.321292)
		(end 127.53975 -268.245336)
		(width 0.0889)
		(layer "B.Cu")
		(net "PU_S3M_CPU1_CPLD_STATUS")
	)
	(segment
		(start 116.919248 -267.219938)
		(end 116.919248 -267.755878)
		(width 0.12954)
		(layer "F.Cu")
		(net "PU_S3M_CPU1_CPLD_CONFD")
	)
	(via
		(at 148.864066 -267.989304)
		(size 0.6604)
		(drill 0.3302)
		(layers "F.Cu" "B.Cu")
		(net "PU_S3M_CPU1_CPLD_CONFD")
	)
	(via
		(at 116.919248 -267.755878)
		(size 0.4572)
		(drill 0.2032)
		(layers "F.Cu" "B.Cu")
		(net "PU_S3M_CPU1_CPLD_CONFD")
	)
	(segment
		(start 177.732944 -256.432558)
		(end 179.27193 -254.893572)
		(width 0.12954)
		(layer "B.Cu")
		(net "PU_S3M_CPU1_CPLD_CONFD")
	)
	(segment
		(start 146.455638 -268.201902)
		(end 146.668236 -267.989304)
		(width 0.12954)
		(layer "B.Cu")
		(net "PU_S3M_CPU1_CPLD_CONFD")
	)
	(segment
		(start 148.864066 -267.989304)
		(end 149.19706 -267.65631)
		(width 0.12954)
		(layer "B.Cu")
		(net "PU_S3M_CPU1_CPLD_CONFD")
	)
	(segment
		(start 146.668236 -267.989304)
		(end 148.864066 -267.989304)
		(width 0.12954)
		(layer "B.Cu")
		(net "PU_S3M_CPU1_CPLD_CONFD")
	)
	(segment
		(start 116.762784 -268.026896)
		(end 116.783866 -268.104874)
		(width 0.0889)
		(layer "B.Cu")
		(net "PU_S3M_CPU1_CPLD_CONFD")
	)
	(segment
		(start 173.22419 -256.432558)
		(end 177.732944 -256.432558)
		(width 0.12954)
		(layer "B.Cu")
		(net "PU_S3M_CPU1_CPLD_CONFD")
	)
	(segment
		(start 129.874264 -268.0716)
		(end 129.888996 -268.080236)
		(width 0.0889)
		(layer "B.Cu")
		(net "PU_S3M_CPU1_CPLD_CONFD")
	)
	(segment
		(start 179.27193 -254.893572)
		(end 179.27193 -253.658624)
		(width 0.12954)
		(layer "B.Cu")
		(net "PU_S3M_CPU1_CPLD_CONFD")
	)
	(segment
		(start 124.235464 -268.0716)
		(end 124.250196 -268.080236)
		(width 0.0889)
		(layer "B.Cu")
		(net "PU_S3M_CPU1_CPLD_CONFD")
	)
	(segment
		(start 165.000178 -269.46987)
		(end 167.738298 -269.46987)
		(width 0.12954)
		(layer "B.Cu")
		(net "PU_S3M_CPU1_CPLD_CONFD")
	)
	(segment
		(start 118.986046 -268.080236)
		(end 118.99646 -268.07414)
		(width 0.0889)
		(layer "B.Cu")
		(net "PU_S3M_CPU1_CPLD_CONFD")
	)
	(segment
		(start 169.379138 -268.56055)
		(end 170.473878 -267.46581)
		(width 0.12954)
		(layer "B.Cu")
		(net "PU_S3M_CPU1_CPLD_CONFD")
	)
	(segment
		(start 179.27193 -253.658624)
		(end 181.304692 -251.625862)
		(width 0.12954)
		(layer "B.Cu")
		(net "PU_S3M_CPU1_CPLD_CONFD")
	)
	(segment
		(start 170.473878 -267.46581)
		(end 170.473878 -258.345686)
		(width 0.12954)
		(layer "B.Cu")
		(net "PU_S3M_CPU1_CPLD_CONFD")
	)
	(segment
		(start 159.74314 -269.48511)
		(end 160.623758 -269.48511)
		(width 0.12954)
		(layer "B.Cu")
		(net "PU_S3M_CPU1_CPLD_CONFD")
	)
	(segment
		(start 180.514752 -193.506344)
		(end 180.514752 -193.099944)
		(width 0.12954)
		(layer "B.Cu")
		(net "PU_S3M_CPU1_CPLD_CONFD")
	)
	(segment
		(start 164.537898 -269.00759)
		(end 165.000178 -269.46987)
		(width 0.12954)
		(layer "B.Cu")
		(net "PU_S3M_CPU1_CPLD_CONFD")
	)
	(segment
		(start 138.452352 -268.201902)
		(end 146.455638 -268.201902)
		(width 0.12954)
		(layer "B.Cu")
		(net "PU_S3M_CPU1_CPLD_CONFD")
	)
	(segment
		(start 127.054864 -268.0716)
		(end 127.069596 -268.080236)
		(width 0.0889)
		(layer "B.Cu")
		(net "PU_S3M_CPU1_CPLD_CONFD")
	)
	(segment
		(start 128.934464 -268.0716)
		(end 128.949196 -268.080236)
		(width 0.0889)
		(layer "B.Cu")
		(net "PU_S3M_CPU1_CPLD_CONFD")
	)
	(segment
		(start 117.106446 -268.080236)
		(end 117.11686 -268.07414)
		(width 0.0889)
		(layer "B.Cu")
		(net "PU_S3M_CPU1_CPLD_CONFD")
	)
	(segment
		(start 170.473878 -258.345686)
		(end 170.968162 -257.548126)
		(width 0.12954)
		(layer "B.Cu")
		(net "PU_S3M_CPU1_CPLD_CONFD")
	)
	(segment
		(start 135.513064 -268.0716)
		(end 135.527796 -268.080236)
		(width 0.0889)
		(layer "B.Cu")
		(net "PU_S3M_CPU1_CPLD_CONFD")
	)
	(segment
		(start 168.647618 -268.56055)
		(end 169.379138 -268.56055)
		(width 0.12954)
		(layer "B.Cu")
		(net "PU_S3M_CPU1_CPLD_CONFD")
	)
	(segment
		(start 121.805446 -268.080236)
		(end 121.81586 -268.07414)
		(width 0.0889)
		(layer "B.Cu")
		(net "PU_S3M_CPU1_CPLD_CONFD")
	)
	(segment
		(start 161.101278 -269.00759)
		(end 164.537898 -269.00759)
		(width 0.12954)
		(layer "B.Cu")
		(net "PU_S3M_CPU1_CPLD_CONFD")
	)
	(segment
		(start 119.925592 -268.080236)
		(end 119.936006 -268.07414)
		(width 0.0889)
		(layer "B.Cu")
		(net "PU_S3M_CPU1_CPLD_CONFD")
	)
	(segment
		(start 131.758436 -268.07414)
		(end 131.76885 -268.080236)
		(width 0.0889)
		(layer "B.Cu")
		(net "PU_S3M_CPU1_CPLD_CONFD")
	)
	(segment
		(start 134.573264 -268.0716)
		(end 134.587996 -268.080236)
		(width 0.0889)
		(layer "B.Cu")
		(net "PU_S3M_CPU1_CPLD_CONFD")
	)
	(segment
		(start 127.994664 -268.0716)
		(end 128.009396 -268.080236)
		(width 0.0889)
		(layer "B.Cu")
		(net "PU_S3M_CPU1_CPLD_CONFD")
	)
	(segment
		(start 125.175264 -268.0716)
		(end 125.189996 -268.080236)
		(width 0.0889)
		(layer "B.Cu")
		(net "PU_S3M_CPU1_CPLD_CONFD")
	)
	(segment
		(start 160.623758 -269.48511)
		(end 161.101278 -269.00759)
		(width 0.12954)
		(layer "B.Cu")
		(net "PU_S3M_CPU1_CPLD_CONFD")
	)
	(segment
		(start 157.91434 -267.65631)
		(end 159.74314 -269.48511)
		(width 0.12954)
		(layer "B.Cu")
		(net "PU_S3M_CPU1_CPLD_CONFD")
	)
	(segment
		(start 126.115064 -268.0716)
		(end 126.129796 -268.080236)
		(width 0.0889)
		(layer "B.Cu")
		(net "PU_S3M_CPU1_CPLD_CONFD")
	)
	(segment
		(start 181.304692 -194.296284)
		(end 180.514752 -193.506344)
		(width 0.12954)
		(layer "B.Cu")
		(net "PU_S3M_CPU1_CPLD_CONFD")
	)
	(segment
		(start 138.451336 -268.200886)
		(end 138.452352 -268.201902)
		(width 0.0889)
		(layer "B.Cu")
		(net "PU_S3M_CPU1_CPLD_CONFD")
	)
	(segment
		(start 133.633464 -268.0716)
		(end 133.648196 -268.080236)
		(width 0.0889)
		(layer "B.Cu")
		(net "PU_S3M_CPU1_CPLD_CONFD")
	)
	(segment
		(start 130.814064 -268.0716)
		(end 130.828796 -268.080236)
		(width 0.0889)
		(layer "B.Cu")
		(net "PU_S3M_CPU1_CPLD_CONFD")
	)
	(segment
		(start 136.91616 -268.200886)
		(end 138.451336 -268.200886)
		(width 0.0889)
		(layer "B.Cu")
		(net "PU_S3M_CPU1_CPLD_CONFD")
	)
	(segment
		(start 170.968162 -257.548126)
		(end 173.22419 -256.432558)
		(width 0.12954)
		(layer "B.Cu")
		(net "PU_S3M_CPU1_CPLD_CONFD")
	)
	(segment
		(start 181.304692 -251.625862)
		(end 181.304692 -194.296284)
		(width 0.12954)
		(layer "B.Cu")
		(net "PU_S3M_CPU1_CPLD_CONFD")
	)
	(segment
		(start 149.19706 -267.65631)
		(end 157.91434 -267.65631)
		(width 0.12954)
		(layer "B.Cu")
		(net "PU_S3M_CPU1_CPLD_CONFD")
	)
	(segment
		(start 132.697982 -268.07414)
		(end 132.708396 -268.080236)
		(width 0.0889)
		(layer "B.Cu")
		(net "PU_S3M_CPU1_CPLD_CONFD")
	)
	(segment
		(start 167.738298 -269.46987)
		(end 168.647618 -268.56055)
		(width 0.12954)
		(layer "B.Cu")
		(net "PU_S3M_CPU1_CPLD_CONFD")
	)
	(segment
		(start 118.601236 -268.07414)
		(end 118.61165 -268.080236)
		(width 0.0889)
		(layer "B.Cu")
		(net "PU_S3M_CPU1_CPLD_CONFD")
	)
	(segment
		(start 116.919248 -267.755878)
		(end 116.762784 -268.026896)
		(width 0.0889)
		(layer "B.Cu")
		(net "PU_S3M_CPU1_CPLD_CONFD")
	)
	(arc
		(start 126.504192 -268.080236)
		(mid 126.778391 -268.004401)
		(end 127.054864 -268.0716)
		(width 0.0889)
		(layer "B.Cu")
		(net "PU_S3M_CPU1_CPLD_CONFD")
	)
	(arc
		(start 131.203192 -268.080236)
		(mid 131.480005 -268.004366)
		(end 131.758436 -268.07414)
		(width 0.0889)
		(layer "B.Cu")
		(net "PU_S3M_CPU1_CPLD_CONFD")
	)
	(arc
		(start 128.949196 -268.080236)
		(mid 129.136394 -268.130379)
		(end 129.323592 -268.080236)
		(width 0.0889)
		(layer "B.Cu")
		(net "PU_S3M_CPU1_CPLD_CONFD")
	)
	(arc
		(start 119.936006 -268.07414)
		(mid 120.214438 -268.004294)
		(end 120.49125 -268.080236)
		(width 0.0889)
		(layer "B.Cu")
		(net "PU_S3M_CPU1_CPLD_CONFD")
	)
	(arc
		(start 122.744992 -268.080236)
		(mid 123.027694 -268.00446)
		(end 123.310396 -268.080236)
		(width 0.0889)
		(layer "B.Cu")
		(net "PU_S3M_CPU1_CPLD_CONFD")
	)
	(arc
		(start 133.082792 -268.080236)
		(mid 133.356991 -268.004401)
		(end 133.633464 -268.0716)
		(width 0.0889)
		(layer "B.Cu")
		(net "PU_S3M_CPU1_CPLD_CONFD")
	)
	(arc
		(start 121.81586 -268.07414)
		(mid 122.094038 -268.004417)
		(end 122.370596 -268.080236)
		(width 0.0889)
		(layer "B.Cu")
		(net "PU_S3M_CPU1_CPLD_CONFD")
	)
	(arc
		(start 128.383792 -268.080236)
		(mid 128.657991 -268.004401)
		(end 128.934464 -268.0716)
		(width 0.0889)
		(layer "B.Cu")
		(net "PU_S3M_CPU1_CPLD_CONFD")
	)
	(arc
		(start 124.250196 -268.080236)
		(mid 124.437394 -268.130379)
		(end 124.624592 -268.080236)
		(width 0.0889)
		(layer "B.Cu")
		(net "PU_S3M_CPU1_CPLD_CONFD")
	)
	(arc
		(start 118.61165 -268.080236)
		(mid 118.798848 -268.130379)
		(end 118.986046 -268.080236)
		(width 0.0889)
		(layer "B.Cu")
		(net "PU_S3M_CPU1_CPLD_CONFD")
	)
	(arc
		(start 126.129796 -268.080236)
		(mid 126.316994 -268.130379)
		(end 126.504192 -268.080236)
		(width 0.0889)
		(layer "B.Cu")
		(net "PU_S3M_CPU1_CPLD_CONFD")
	)
	(arc
		(start 125.564392 -268.080236)
		(mid 125.838591 -268.004401)
		(end 126.115064 -268.0716)
		(width 0.0889)
		(layer "B.Cu")
		(net "PU_S3M_CPU1_CPLD_CONFD")
	)
	(arc
		(start 118.99646 -268.07414)
		(mid 119.274638 -268.004417)
		(end 119.551196 -268.080236)
		(width 0.0889)
		(layer "B.Cu")
		(net "PU_S3M_CPU1_CPLD_CONFD")
	)
	(arc
		(start 117.11686 -268.07414)
		(mid 117.395038 -268.004417)
		(end 117.671596 -268.080236)
		(width 0.0889)
		(layer "B.Cu")
		(net "PU_S3M_CPU1_CPLD_CONFD")
	)
	(arc
		(start 133.648196 -268.080236)
		(mid 133.835394 -268.130379)
		(end 134.022592 -268.080236)
		(width 0.0889)
		(layer "B.Cu")
		(net "PU_S3M_CPU1_CPLD_CONFD")
	)
	(arc
		(start 118.045992 -268.080236)
		(mid 118.322805 -268.004366)
		(end 118.601236 -268.07414)
		(width 0.0889)
		(layer "B.Cu")
		(net "PU_S3M_CPU1_CPLD_CONFD")
	)
	(arc
		(start 134.022592 -268.080236)
		(mid 134.296791 -268.004401)
		(end 134.573264 -268.0716)
		(width 0.0889)
		(layer "B.Cu")
		(net "PU_S3M_CPU1_CPLD_CONFD")
	)
	(arc
		(start 135.902192 -268.080236)
		(mid 136.184894 -268.00446)
		(end 136.467596 -268.080236)
		(width 0.0889)
		(layer "B.Cu")
		(net "PU_S3M_CPU1_CPLD_CONFD")
	)
	(arc
		(start 127.443992 -268.080236)
		(mid 127.718191 -268.004401)
		(end 127.994664 -268.0716)
		(width 0.0889)
		(layer "B.Cu")
		(net "PU_S3M_CPU1_CPLD_CONFD")
	)
	(arc
		(start 116.783866 -268.104874)
		(mid 116.947962 -268.129221)
		(end 117.106446 -268.080236)
		(width 0.0889)
		(layer "B.Cu")
		(net "PU_S3M_CPU1_CPLD_CONFD")
	)
	(arc
		(start 129.888996 -268.080236)
		(mid 130.076194 -268.130379)
		(end 130.263392 -268.080236)
		(width 0.0889)
		(layer "B.Cu")
		(net "PU_S3M_CPU1_CPLD_CONFD")
	)
	(arc
		(start 132.143246 -268.080236)
		(mid 132.419805 -268.004493)
		(end 132.697982 -268.07414)
		(width 0.0889)
		(layer "B.Cu")
		(net "PU_S3M_CPU1_CPLD_CONFD")
	)
	(arc
		(start 123.310396 -268.080236)
		(mid 123.497594 -268.130379)
		(end 123.684792 -268.080236)
		(width 0.0889)
		(layer "B.Cu")
		(net "PU_S3M_CPU1_CPLD_CONFD")
	)
	(arc
		(start 120.49125 -268.080236)
		(mid 120.678448 -268.130379)
		(end 120.865646 -268.080236)
		(width 0.0889)
		(layer "B.Cu")
		(net "PU_S3M_CPU1_CPLD_CONFD")
	)
	(arc
		(start 121.43105 -268.080236)
		(mid 121.618248 -268.130379)
		(end 121.805446 -268.080236)
		(width 0.0889)
		(layer "B.Cu")
		(net "PU_S3M_CPU1_CPLD_CONFD")
	)
	(arc
		(start 134.587996 -268.080236)
		(mid 134.775194 -268.130379)
		(end 134.962392 -268.080236)
		(width 0.0889)
		(layer "B.Cu")
		(net "PU_S3M_CPU1_CPLD_CONFD")
	)
	(arc
		(start 122.370596 -268.080236)
		(mid 122.557794 -268.130379)
		(end 122.744992 -268.080236)
		(width 0.0889)
		(layer "B.Cu")
		(net "PU_S3M_CPU1_CPLD_CONFD")
	)
	(arc
		(start 136.467596 -268.080236)
		(mid 136.68391 -268.170182)
		(end 136.91616 -268.200886)
		(width 0.0889)
		(layer "B.Cu")
		(net "PU_S3M_CPU1_CPLD_CONFD")
	)
	(arc
		(start 119.551196 -268.080236)
		(mid 119.738394 -268.130379)
		(end 119.925592 -268.080236)
		(width 0.0889)
		(layer "B.Cu")
		(net "PU_S3M_CPU1_CPLD_CONFD")
	)
	(arc
		(start 134.962392 -268.080236)
		(mid 135.236591 -268.004401)
		(end 135.513064 -268.0716)
		(width 0.0889)
		(layer "B.Cu")
		(net "PU_S3M_CPU1_CPLD_CONFD")
	)
	(arc
		(start 124.624592 -268.080236)
		(mid 124.898791 -268.004401)
		(end 125.175264 -268.0716)
		(width 0.0889)
		(layer "B.Cu")
		(net "PU_S3M_CPU1_CPLD_CONFD")
	)
	(arc
		(start 123.684792 -268.080236)
		(mid 123.958991 -268.004401)
		(end 124.235464 -268.0716)
		(width 0.0889)
		(layer "B.Cu")
		(net "PU_S3M_CPU1_CPLD_CONFD")
	)
	(arc
		(start 135.527796 -268.080236)
		(mid 135.714994 -268.130379)
		(end 135.902192 -268.080236)
		(width 0.0889)
		(layer "B.Cu")
		(net "PU_S3M_CPU1_CPLD_CONFD")
	)
	(arc
		(start 132.708396 -268.080236)
		(mid 132.895594 -268.130379)
		(end 133.082792 -268.080236)
		(width 0.0889)
		(layer "B.Cu")
		(net "PU_S3M_CPU1_CPLD_CONFD")
	)
	(arc
		(start 125.189996 -268.080236)
		(mid 125.377194 -268.130379)
		(end 125.564392 -268.080236)
		(width 0.0889)
		(layer "B.Cu")
		(net "PU_S3M_CPU1_CPLD_CONFD")
	)
	(arc
		(start 117.671596 -268.080236)
		(mid 117.858794 -268.130379)
		(end 118.045992 -268.080236)
		(width 0.0889)
		(layer "B.Cu")
		(net "PU_S3M_CPU1_CPLD_CONFD")
	)
	(arc
		(start 128.009396 -268.080236)
		(mid 128.196594 -268.130379)
		(end 128.383792 -268.080236)
		(width 0.0889)
		(layer "B.Cu")
		(net "PU_S3M_CPU1_CPLD_CONFD")
	)
	(arc
		(start 130.263392 -268.080236)
		(mid 130.537591 -268.004401)
		(end 130.814064 -268.0716)
		(width 0.0889)
		(layer "B.Cu")
		(net "PU_S3M_CPU1_CPLD_CONFD")
	)
	(arc
		(start 129.323592 -268.080236)
		(mid 129.597791 -268.004401)
		(end 129.874264 -268.0716)
		(width 0.0889)
		(layer "B.Cu")
		(net "PU_S3M_CPU1_CPLD_CONFD")
	)
	(arc
		(start 127.069596 -268.080236)
		(mid 127.256794 -268.130379)
		(end 127.443992 -268.080236)
		(width 0.0889)
		(layer "B.Cu")
		(net "PU_S3M_CPU1_CPLD_CONFD")
	)
	(arc
		(start 130.828796 -268.080236)
		(mid 131.015994 -268.130379)
		(end 131.203192 -268.080236)
		(width 0.0889)
		(layer "B.Cu")
		(net "PU_S3M_CPU1_CPLD_CONFD")
	)
	(arc
		(start 120.865646 -268.080236)
		(mid 121.148348 -268.00446)
		(end 121.43105 -268.080236)
		(width 0.0889)
		(layer "B.Cu")
		(net "PU_S3M_CPU1_CPLD_CONFD")
	)
	(arc
		(start 131.76885 -268.080236)
		(mid 131.956048 -268.130379)
		(end 132.143246 -268.080236)
		(width 0.0889)
		(layer "B.Cu")
		(net "PU_S3M_CPU1_CPLD_CONFD")
	)
	(segment
		(start 364.389162 -268.033754)
		(end 364.389416 -268.034008)
		(width 0.12954)
		(layer "F.Cu")
		(net "PU_S3M_CPU0_CPLD_STATUS")
	)
	(segment
		(start 364.389416 -268.034008)
		(end 364.389416 -268.569694)
		(width 0.12954)
		(layer "F.Cu")
		(net "PU_S3M_CPU0_CPLD_STATUS")
	)
	(via
		(at 364.389416 -268.569694)
		(size 0.4572)
		(drill 0.2032)
		(layers "F.Cu" "B.Cu")
		(net "PU_S3M_CPU0_CPLD_STATUS")
	)
	(via
		(at 395.207998 -264.84961)
		(size 0.6604)
		(drill 0.3302)
		(layers "F.Cu" "B.Cu")
		(net "PU_S3M_CPU0_CPLD_STATUS")
	)
	(segment
		(start 376.794014 -268.245336)
		(end 376.808746 -268.253972)
		(width 0.0889)
		(layer "B.Cu")
		(net "PU_S3M_CPU0_CPLD_STATUS")
	)
	(segment
		(start 374.914414 -268.245336)
		(end 374.929146 -268.253972)
		(width 0.0889)
		(layer "B.Cu")
		(net "PU_S3M_CPU0_CPLD_STATUS")
	)
	(segment
		(start 373.974614 -268.245336)
		(end 373.989346 -268.253972)
		(width 0.0889)
		(layer "B.Cu")
		(net "PU_S3M_CPU0_CPLD_STATUS")
	)
	(segment
		(start 405.604218 -247.17121)
		(end 408.159458 -247.17121)
		(width 0.12954)
		(layer "B.Cu")
		(net "PU_S3M_CPU0_CPLD_STATUS")
	)
	(segment
		(start 391.554716 -268.502892)
		(end 395.207998 -264.84961)
		(width 0.12954)
		(layer "B.Cu")
		(net "PU_S3M_CPU0_CPLD_STATUS")
	)
	(segment
		(start 390.531604 -268.502638)
		(end 390.531858 -268.502892)
		(width 0.12954)
		(layer "B.Cu")
		(net "PU_S3M_CPU0_CPLD_STATUS")
	)
	(segment
		(start 404.103078 -248.67235)
		(end 405.604218 -247.17121)
		(width 0.12954)
		(layer "B.Cu")
		(net "PU_S3M_CPU0_CPLD_STATUS")
	)
	(segment
		(start 365.13135 -268.251432)
		(end 365.141764 -268.245336)
		(width 0.0889)
		(layer "B.Cu")
		(net "PU_S3M_CPU0_CPLD_STATUS")
	)
	(segment
		(start 382.432814 -268.245336)
		(end 382.447546 -268.253972)
		(width 0.0889)
		(layer "B.Cu")
		(net "PU_S3M_CPU0_CPLD_STATUS")
	)
	(segment
		(start 412.260034 -245.254526)
		(end 412.695898 -245.69039)
		(width 0.12954)
		(layer "B.Cu")
		(net "PU_S3M_CPU0_CPLD_STATUS")
	)
	(segment
		(start 413.849058 -245.69039)
		(end 414.351978 -245.18747)
		(width 0.12954)
		(layer "B.Cu")
		(net "PU_S3M_CPU0_CPLD_STATUS")
	)
	(segment
		(start 383.372614 -268.245336)
		(end 383.383028 -268.251432)
		(width 0.0889)
		(layer "B.Cu")
		(net "PU_S3M_CPU0_CPLD_STATUS")
	)
	(segment
		(start 414.900618 -194.81927)
		(end 415.271712 -194.448176)
		(width 0.12954)
		(layer "B.Cu")
		(net "PU_S3M_CPU0_CPLD_STATUS")
	)
	(segment
		(start 414.351978 -241.819176)
		(end 414.900618 -241.270536)
		(width 0.12954)
		(layer "B.Cu")
		(net "PU_S3M_CPU0_CPLD_STATUS")
	)
	(segment
		(start 371.15496 -268.245336)
		(end 371.165374 -268.251432)
		(width 0.0889)
		(layer "B.Cu")
		(net "PU_S3M_CPU0_CPLD_STATUS")
	)
	(segment
		(start 410.158438 -246.57177)
		(end 411.475682 -245.254526)
		(width 0.12954)
		(layer "B.Cu")
		(net "PU_S3M_CPU0_CPLD_STATUS")
	)
	(segment
		(start 377.733814 -268.245336)
		(end 377.748546 -268.253972)
		(width 0.0889)
		(layer "B.Cu")
		(net "PU_S3M_CPU0_CPLD_STATUS")
	)
	(segment
		(start 395.207998 -264.84961)
		(end 404.103078 -255.95453)
		(width 0.12954)
		(layer "B.Cu")
		(net "PU_S3M_CPU0_CPLD_STATUS")
	)
	(segment
		(start 364.389416 -268.569694)
		(end 364.54588 -268.298676)
		(width 0.0889)
		(layer "B.Cu")
		(net "PU_S3M_CPU0_CPLD_STATUS")
	)
	(segment
		(start 414.351978 -245.18747)
		(end 414.351978 -241.819176)
		(width 0.12954)
		(layer "B.Cu")
		(net "PU_S3M_CPU0_CPLD_STATUS")
	)
	(segment
		(start 412.695898 -245.69039)
		(end 413.849058 -245.69039)
		(width 0.12954)
		(layer "B.Cu")
		(net "PU_S3M_CPU0_CPLD_STATUS")
	)
	(segment
		(start 373.034814 -268.245336)
		(end 373.049546 -268.253972)
		(width 0.0889)
		(layer "B.Cu")
		(net "PU_S3M_CPU0_CPLD_STATUS")
	)
	(segment
		(start 384.594862 -268.321028)
		(end 384.8227 -268.321028)
		(width 0.0889)
		(layer "B.Cu")
		(net "PU_S3M_CPU0_CPLD_STATUS")
	)
	(segment
		(start 364.54588 -268.298676)
		(end 364.635034 -268.2748)
		(width 0.0889)
		(layer "B.Cu")
		(net "PU_S3M_CPU0_CPLD_STATUS")
	)
	(segment
		(start 375.854214 -268.245336)
		(end 375.868946 -268.253972)
		(width 0.0889)
		(layer "B.Cu")
		(net "PU_S3M_CPU0_CPLD_STATUS")
	)
	(segment
		(start 390.531858 -268.502892)
		(end 391.554716 -268.502892)
		(width 0.12954)
		(layer "B.Cu")
		(net "PU_S3M_CPU0_CPLD_STATUS")
	)
	(segment
		(start 365.51616 -268.245336)
		(end 365.526574 -268.251432)
		(width 0.0889)
		(layer "B.Cu")
		(net "PU_S3M_CPU0_CPLD_STATUS")
	)
	(segment
		(start 369.83035 -268.251432)
		(end 369.840764 -268.245336)
		(width 0.0889)
		(layer "B.Cu")
		(net "PU_S3M_CPU0_CPLD_STATUS")
	)
	(segment
		(start 380.553214 -268.245336)
		(end 380.567946 -268.253972)
		(width 0.0889)
		(layer "B.Cu")
		(net "PU_S3M_CPU0_CPLD_STATUS")
	)
	(segment
		(start 385.00431 -268.502638)
		(end 390.531604 -268.502638)
		(width 0.12954)
		(layer "B.Cu")
		(net "PU_S3M_CPU0_CPLD_STATUS")
	)
	(segment
		(start 404.103078 -255.95453)
		(end 404.103078 -248.67235)
		(width 0.12954)
		(layer "B.Cu")
		(net "PU_S3M_CPU0_CPLD_STATUS")
	)
	(segment
		(start 414.900618 -241.270536)
		(end 414.900618 -194.81927)
		(width 0.12954)
		(layer "B.Cu")
		(net "PU_S3M_CPU0_CPLD_STATUS")
	)
	(segment
		(start 368.890804 -268.251432)
		(end 368.901218 -268.245336)
		(width 0.0889)
		(layer "B.Cu")
		(net "PU_S3M_CPU0_CPLD_STATUS")
	)
	(segment
		(start 372.095014 -268.245336)
		(end 372.109746 -268.253972)
		(width 0.0889)
		(layer "B.Cu")
		(net "PU_S3M_CPU0_CPLD_STATUS")
	)
	(segment
		(start 408.159458 -247.17121)
		(end 408.758898 -246.57177)
		(width 0.12954)
		(layer "B.Cu")
		(net "PU_S3M_CPU0_CPLD_STATUS")
	)
	(segment
		(start 378.673614 -268.245336)
		(end 378.688346 -268.253972)
		(width 0.0889)
		(layer "B.Cu")
		(net "PU_S3M_CPU0_CPLD_STATUS")
	)
	(segment
		(start 384.8227 -268.321028)
		(end 385.00431 -268.502638)
		(width 0.0889)
		(layer "B.Cu")
		(net "PU_S3M_CPU0_CPLD_STATUS")
	)
	(segment
		(start 408.758898 -246.57177)
		(end 410.158438 -246.57177)
		(width 0.12954)
		(layer "B.Cu")
		(net "PU_S3M_CPU0_CPLD_STATUS")
	)
	(segment
		(start 381.493014 -268.245336)
		(end 381.507746 -268.253972)
		(width 0.0889)
		(layer "B.Cu")
		(net "PU_S3M_CPU0_CPLD_STATUS")
	)
	(segment
		(start 367.01095 -268.251432)
		(end 367.021364 -268.245336)
		(width 0.0889)
		(layer "B.Cu")
		(net "PU_S3M_CPU0_CPLD_STATUS")
	)
	(segment
		(start 415.271712 -194.448176)
		(end 415.271712 -193.48958)
		(width 0.12954)
		(layer "B.Cu")
		(net "PU_S3M_CPU0_CPLD_STATUS")
	)
	(segment
		(start 411.475682 -245.254526)
		(end 412.260034 -245.254526)
		(width 0.12954)
		(layer "B.Cu")
		(net "PU_S3M_CPU0_CPLD_STATUS")
	)
	(arc
		(start 376.808746 -268.253972)
		(mid 377.085221 -268.321292)
		(end 377.359418 -268.245336)
		(width 0.0889)
		(layer "B.Cu")
		(net "PU_S3M_CPU0_CPLD_STATUS")
	)
	(arc
		(start 379.613414 -268.245336)
		(mid 379.896116 -268.321112)
		(end 380.178818 -268.245336)
		(width 0.0889)
		(layer "B.Cu")
		(net "PU_S3M_CPU0_CPLD_STATUS")
	)
	(arc
		(start 372.660418 -268.245336)
		(mid 372.847616 -268.195193)
		(end 373.034814 -268.245336)
		(width 0.0889)
		(layer "B.Cu")
		(net "PU_S3M_CPU0_CPLD_STATUS")
	)
	(arc
		(start 370.21516 -268.245336)
		(mid 370.497862 -268.321112)
		(end 370.780564 -268.245336)
		(width 0.0889)
		(layer "B.Cu")
		(net "PU_S3M_CPU0_CPLD_STATUS")
	)
	(arc
		(start 365.141764 -268.245336)
		(mid 365.328962 -268.195193)
		(end 365.51616 -268.245336)
		(width 0.0889)
		(layer "B.Cu")
		(net "PU_S3M_CPU0_CPLD_STATUS")
	)
	(arc
		(start 367.961164 -268.245336)
		(mid 368.148362 -268.195193)
		(end 368.33556 -268.245336)
		(width 0.0889)
		(layer "B.Cu")
		(net "PU_S3M_CPU0_CPLD_STATUS")
	)
	(arc
		(start 369.840764 -268.245336)
		(mid 370.027962 -268.195193)
		(end 370.21516 -268.245336)
		(width 0.0889)
		(layer "B.Cu")
		(net "PU_S3M_CPU0_CPLD_STATUS")
	)
	(arc
		(start 375.479818 -268.245336)
		(mid 375.667016 -268.195193)
		(end 375.854214 -268.245336)
		(width 0.0889)
		(layer "B.Cu")
		(net "PU_S3M_CPU0_CPLD_STATUS")
	)
	(arc
		(start 380.567946 -268.253972)
		(mid 380.844421 -268.321292)
		(end 381.118618 -268.245336)
		(width 0.0889)
		(layer "B.Cu")
		(net "PU_S3M_CPU0_CPLD_STATUS")
	)
	(arc
		(start 383.937764 -268.245336)
		(mid 384.124962 -268.195193)
		(end 384.31216 -268.245336)
		(width 0.0889)
		(layer "B.Cu")
		(net "PU_S3M_CPU0_CPLD_STATUS")
	)
	(arc
		(start 378.688346 -268.253972)
		(mid 378.964821 -268.321292)
		(end 379.239018 -268.245336)
		(width 0.0889)
		(layer "B.Cu")
		(net "PU_S3M_CPU0_CPLD_STATUS")
	)
	(arc
		(start 371.165374 -268.251432)
		(mid 371.443806 -268.321278)
		(end 371.720618 -268.245336)
		(width 0.0889)
		(layer "B.Cu")
		(net "PU_S3M_CPU0_CPLD_STATUS")
	)
	(arc
		(start 381.507746 -268.253972)
		(mid 381.784221 -268.321292)
		(end 382.058418 -268.245336)
		(width 0.0889)
		(layer "B.Cu")
		(net "PU_S3M_CPU0_CPLD_STATUS")
	)
	(arc
		(start 382.998218 -268.245336)
		(mid 383.185416 -268.195193)
		(end 383.372614 -268.245336)
		(width 0.0889)
		(layer "B.Cu")
		(net "PU_S3M_CPU0_CPLD_STATUS")
	)
	(arc
		(start 384.31216 -268.245336)
		(mid 384.448529 -268.301778)
		(end 384.594862 -268.321028)
		(width 0.0889)
		(layer "B.Cu")
		(net "PU_S3M_CPU0_CPLD_STATUS")
	)
	(arc
		(start 374.929146 -268.253972)
		(mid 375.205621 -268.321292)
		(end 375.479818 -268.245336)
		(width 0.0889)
		(layer "B.Cu")
		(net "PU_S3M_CPU0_CPLD_STATUS")
	)
	(arc
		(start 380.178818 -268.245336)
		(mid 380.366016 -268.195193)
		(end 380.553214 -268.245336)
		(width 0.0889)
		(layer "B.Cu")
		(net "PU_S3M_CPU0_CPLD_STATUS")
	)
	(arc
		(start 364.635034 -268.2748)
		(mid 364.885898 -268.320569)
		(end 365.13135 -268.251432)
		(width 0.0889)
		(layer "B.Cu")
		(net "PU_S3M_CPU0_CPLD_STATUS")
	)
	(arc
		(start 382.447546 -268.253972)
		(mid 382.724021 -268.321292)
		(end 382.998218 -268.245336)
		(width 0.0889)
		(layer "B.Cu")
		(net "PU_S3M_CPU0_CPLD_STATUS")
	)
	(arc
		(start 366.456214 -268.245336)
		(mid 366.732773 -268.321079)
		(end 367.01095 -268.251432)
		(width 0.0889)
		(layer "B.Cu")
		(net "PU_S3M_CPU0_CPLD_STATUS")
	)
	(arc
		(start 378.299218 -268.245336)
		(mid 378.486416 -268.195193)
		(end 378.673614 -268.245336)
		(width 0.0889)
		(layer "B.Cu")
		(net "PU_S3M_CPU0_CPLD_STATUS")
	)
	(arc
		(start 383.383028 -268.251432)
		(mid 383.661206 -268.321155)
		(end 383.937764 -268.245336)
		(width 0.0889)
		(layer "B.Cu")
		(net "PU_S3M_CPU0_CPLD_STATUS")
	)
	(arc
		(start 370.780564 -268.245336)
		(mid 370.967762 -268.195193)
		(end 371.15496 -268.245336)
		(width 0.0889)
		(layer "B.Cu")
		(net "PU_S3M_CPU0_CPLD_STATUS")
	)
	(arc
		(start 375.868946 -268.253972)
		(mid 376.145421 -268.321292)
		(end 376.419618 -268.245336)
		(width 0.0889)
		(layer "B.Cu")
		(net "PU_S3M_CPU0_CPLD_STATUS")
	)
	(arc
		(start 367.021364 -268.245336)
		(mid 367.208562 -268.195193)
		(end 367.39576 -268.245336)
		(width 0.0889)
		(layer "B.Cu")
		(net "PU_S3M_CPU0_CPLD_STATUS")
	)
	(arc
		(start 382.058418 -268.245336)
		(mid 382.245616 -268.195193)
		(end 382.432814 -268.245336)
		(width 0.0889)
		(layer "B.Cu")
		(net "PU_S3M_CPU0_CPLD_STATUS")
	)
	(arc
		(start 368.901218 -268.245336)
		(mid 369.088416 -268.195193)
		(end 369.275614 -268.245336)
		(width 0.0889)
		(layer "B.Cu")
		(net "PU_S3M_CPU0_CPLD_STATUS")
	)
	(arc
		(start 377.748546 -268.253972)
		(mid 378.025021 -268.321292)
		(end 378.299218 -268.245336)
		(width 0.0889)
		(layer "B.Cu")
		(net "PU_S3M_CPU0_CPLD_STATUS")
	)
	(arc
		(start 365.526574 -268.251432)
		(mid 365.805006 -268.321278)
		(end 366.081818 -268.245336)
		(width 0.0889)
		(layer "B.Cu")
		(net "PU_S3M_CPU0_CPLD_STATUS")
	)
	(arc
		(start 369.275614 -268.245336)
		(mid 369.552173 -268.321079)
		(end 369.83035 -268.251432)
		(width 0.0889)
		(layer "B.Cu")
		(net "PU_S3M_CPU0_CPLD_STATUS")
	)
	(arc
		(start 367.39576 -268.245336)
		(mid 367.678462 -268.321112)
		(end 367.961164 -268.245336)
		(width 0.0889)
		(layer "B.Cu")
		(net "PU_S3M_CPU0_CPLD_STATUS")
	)
	(arc
		(start 373.600218 -268.245336)
		(mid 373.787416 -268.195193)
		(end 373.974614 -268.245336)
		(width 0.0889)
		(layer "B.Cu")
		(net "PU_S3M_CPU0_CPLD_STATUS")
	)
	(arc
		(start 373.049546 -268.253972)
		(mid 373.326021 -268.321292)
		(end 373.600218 -268.245336)
		(width 0.0889)
		(layer "B.Cu")
		(net "PU_S3M_CPU0_CPLD_STATUS")
	)
	(arc
		(start 377.359418 -268.245336)
		(mid 377.546616 -268.195193)
		(end 377.733814 -268.245336)
		(width 0.0889)
		(layer "B.Cu")
		(net "PU_S3M_CPU0_CPLD_STATUS")
	)
	(arc
		(start 366.081818 -268.245336)
		(mid 366.269016 -268.195193)
		(end 366.456214 -268.245336)
		(width 0.0889)
		(layer "B.Cu")
		(net "PU_S3M_CPU0_CPLD_STATUS")
	)
	(arc
		(start 376.419618 -268.245336)
		(mid 376.606816 -268.195193)
		(end 376.794014 -268.245336)
		(width 0.0889)
		(layer "B.Cu")
		(net "PU_S3M_CPU0_CPLD_STATUS")
	)
	(arc
		(start 373.989346 -268.253972)
		(mid 374.265821 -268.321292)
		(end 374.540018 -268.245336)
		(width 0.0889)
		(layer "B.Cu")
		(net "PU_S3M_CPU0_CPLD_STATUS")
	)
	(arc
		(start 374.540018 -268.245336)
		(mid 374.727216 -268.195193)
		(end 374.914414 -268.245336)
		(width 0.0889)
		(layer "B.Cu")
		(net "PU_S3M_CPU0_CPLD_STATUS")
	)
	(arc
		(start 371.720618 -268.245336)
		(mid 371.907816 -268.195193)
		(end 372.095014 -268.245336)
		(width 0.0889)
		(layer "B.Cu")
		(net "PU_S3M_CPU0_CPLD_STATUS")
	)
	(arc
		(start 368.33556 -268.245336)
		(mid 368.612373 -268.321206)
		(end 368.890804 -268.251432)
		(width 0.0889)
		(layer "B.Cu")
		(net "PU_S3M_CPU0_CPLD_STATUS")
	)
	(arc
		(start 381.118618 -268.245336)
		(mid 381.305816 -268.195193)
		(end 381.493014 -268.245336)
		(width 0.0889)
		(layer "B.Cu")
		(net "PU_S3M_CPU0_CPLD_STATUS")
	)
	(arc
		(start 379.239018 -268.245336)
		(mid 379.426216 -268.195193)
		(end 379.613414 -268.245336)
		(width 0.0889)
		(layer "B.Cu")
		(net "PU_S3M_CPU0_CPLD_STATUS")
	)
	(arc
		(start 372.109746 -268.253972)
		(mid 372.386221 -268.321292)
		(end 372.660418 -268.245336)
		(width 0.0889)
		(layer "B.Cu")
		(net "PU_S3M_CPU0_CPLD_STATUS")
	)
	(segment
		(start 364.859316 -267.219938)
		(end 364.859316 -267.755878)
		(width 0.12954)
		(layer "F.Cu")
		(net "PU_S3M_CPU0_CPLD_CONFD")
	)
	(via
		(at 364.859316 -267.755878)
		(size 0.4572)
		(drill 0.2032)
		(layers "F.Cu" "B.Cu")
		(net "PU_S3M_CPU0_CPLD_CONFD")
	)
	(via
		(at 392.091418 -266.65809)
		(size 0.6604)
		(drill 0.3302)
		(layers "F.Cu" "B.Cu")
		(net "PU_S3M_CPU0_CPLD_CONFD")
	)
	(segment
		(start 390.425432 -267.869416)
		(end 390.880092 -267.869416)
		(width 0.12954)
		(layer "B.Cu")
		(net "PU_S3M_CPU0_CPLD_CONFD")
	)
	(segment
		(start 385.0259 -268.130782)
		(end 385.125214 -268.230096)
		(width 0.0889)
		(layer "B.Cu")
		(net "PU_S3M_CPU0_CPLD_CONFD")
	)
	(segment
		(start 366.926114 -268.080236)
		(end 366.936528 -268.07414)
		(width 0.0889)
		(layer "B.Cu")
		(net "PU_S3M_CPU0_CPLD_CONFD")
	)
	(segment
		(start 374.994932 -268.0716)
		(end 375.009664 -268.080236)
		(width 0.0889)
		(layer "B.Cu")
		(net "PU_S3M_CPU0_CPLD_CONFD")
	)
	(segment
		(start 414.471358 -240.95837)
		(end 414.471358 -193.705226)
		(width 0.12954)
		(layer "B.Cu")
		(net "PU_S3M_CPU0_CPLD_CONFD")
	)
	(segment
		(start 413.048958 -241.85499)
		(end 413.574738 -241.85499)
		(width 0.12954)
		(layer "B.Cu")
		(net "PU_S3M_CPU0_CPLD_CONFD")
	)
	(segment
		(start 367.86566 -268.080236)
		(end 367.876074 -268.07414)
		(width 0.0889)
		(layer "B.Cu")
		(net "PU_S3M_CPU0_CPLD_CONFD")
	)
	(segment
		(start 392.091418 -266.65809)
		(end 403.549358 -255.20015)
		(width 0.12954)
		(layer "B.Cu")
		(net "PU_S3M_CPU0_CPLD_CONFD")
	)
	(segment
		(start 373.115332 -268.0716)
		(end 373.130064 -268.080236)
		(width 0.0889)
		(layer "B.Cu")
		(net "PU_S3M_CPU0_CPLD_CONFD")
	)
	(segment
		(start 382.513332 -268.0716)
		(end 382.528064 -268.080236)
		(width 0.0889)
		(layer "B.Cu")
		(net "PU_S3M_CPU0_CPLD_CONFD")
	)
	(segment
		(start 379.698504 -268.07414)
		(end 379.708918 -268.080236)
		(width 0.0889)
		(layer "B.Cu")
		(net "PU_S3M_CPU0_CPLD_CONFD")
	)
	(segment
		(start 411.029658 -244.66423)
		(end 411.029658 -243.87429)
		(width 0.12954)
		(layer "B.Cu")
		(net "PU_S3M_CPU0_CPLD_CONFD")
	)
	(segment
		(start 378.754132 -268.0716)
		(end 378.768864 -268.080236)
		(width 0.0889)
		(layer "B.Cu")
		(net "PU_S3M_CPU0_CPLD_CONFD")
	)
	(segment
		(start 405.621744 -246.01297)
		(end 408.432508 -246.01297)
		(width 0.12954)
		(layer "B.Cu")
		(net "PU_S3M_CPU0_CPLD_CONFD")
	)
	(segment
		(start 381.573532 -268.0716)
		(end 381.588264 -268.080236)
		(width 0.0889)
		(layer "B.Cu")
		(net "PU_S3M_CPU0_CPLD_CONFD")
	)
	(segment
		(start 390.064752 -268.230096)
		(end 390.425432 -267.869416)
		(width 0.12954)
		(layer "B.Cu")
		(net "PU_S3M_CPU0_CPLD_CONFD")
	)
	(segment
		(start 364.859316 -267.755878)
		(end 364.702852 -268.026896)
		(width 0.0889)
		(layer "B.Cu")
		(net "PU_S3M_CPU0_CPLD_CONFD")
	)
	(segment
		(start 366.541304 -268.07414)
		(end 366.551718 -268.080236)
		(width 0.0889)
		(layer "B.Cu")
		(net "PU_S3M_CPU0_CPLD_CONFD")
	)
	(segment
		(start 403.549358 -255.20015)
		(end 403.549358 -248.085356)
		(width 0.12954)
		(layer "B.Cu")
		(net "PU_S3M_CPU0_CPLD_CONFD")
	)
	(segment
		(start 375.934732 -268.0716)
		(end 375.949464 -268.080236)
		(width 0.0889)
		(layer "B.Cu")
		(net "PU_S3M_CPU0_CPLD_CONFD")
	)
	(segment
		(start 409.143708 -245.30177)
		(end 410.392118 -245.30177)
		(width 0.12954)
		(layer "B.Cu")
		(net "PU_S3M_CPU0_CPLD_CONFD")
	)
	(segment
		(start 384.594862 -268.130782)
		(end 385.0259 -268.130782)
		(width 0.0889)
		(layer "B.Cu")
		(net "PU_S3M_CPU0_CPLD_CONFD")
	)
	(segment
		(start 403.549358 -248.085356)
		(end 405.621744 -246.01297)
		(width 0.12954)
		(layer "B.Cu")
		(net "PU_S3M_CPU0_CPLD_CONFD")
	)
	(segment
		(start 380.63805 -268.07414)
		(end 380.648464 -268.080236)
		(width 0.0889)
		(layer "B.Cu")
		(net "PU_S3M_CPU0_CPLD_CONFD")
	)
	(segment
		(start 408.432508 -246.01297)
		(end 409.143708 -245.30177)
		(width 0.12954)
		(layer "B.Cu")
		(net "PU_S3M_CPU0_CPLD_CONFD")
	)
	(segment
		(start 390.880092 -267.869416)
		(end 392.091418 -266.65809)
		(width 0.12954)
		(layer "B.Cu")
		(net "PU_S3M_CPU0_CPLD_CONFD")
	)
	(segment
		(start 374.055132 -268.0716)
		(end 374.069864 -268.080236)
		(width 0.0889)
		(layer "B.Cu")
		(net "PU_S3M_CPU0_CPLD_CONFD")
	)
	(segment
		(start 385.125214 -268.230096)
		(end 390.064752 -268.230096)
		(width 0.12954)
		(layer "B.Cu")
		(net "PU_S3M_CPU0_CPLD_CONFD")
	)
	(segment
		(start 376.874532 -268.0716)
		(end 376.889264 -268.080236)
		(width 0.0889)
		(layer "B.Cu")
		(net "PU_S3M_CPU0_CPLD_CONFD")
	)
	(segment
		(start 365.046514 -268.080236)
		(end 365.056928 -268.07414)
		(width 0.0889)
		(layer "B.Cu")
		(net "PU_S3M_CPU0_CPLD_CONFD")
	)
	(segment
		(start 383.453132 -268.0716)
		(end 383.467864 -268.080236)
		(width 0.0889)
		(layer "B.Cu")
		(net "PU_S3M_CPU0_CPLD_CONFD")
	)
	(segment
		(start 413.574738 -241.85499)
		(end 414.471358 -240.95837)
		(width 0.12954)
		(layer "B.Cu")
		(net "PU_S3M_CPU0_CPLD_CONFD")
	)
	(segment
		(start 410.392118 -245.30177)
		(end 411.029658 -244.66423)
		(width 0.12954)
		(layer "B.Cu")
		(net "PU_S3M_CPU0_CPLD_CONFD")
	)
	(segment
		(start 414.471358 -193.705226)
		(end 414.255712 -193.48958)
		(width 0.12954)
		(layer "B.Cu")
		(net "PU_S3M_CPU0_CPLD_CONFD")
	)
	(segment
		(start 377.814332 -268.0716)
		(end 377.829064 -268.080236)
		(width 0.0889)
		(layer "B.Cu")
		(net "PU_S3M_CPU0_CPLD_CONFD")
	)
	(segment
		(start 372.175532 -268.0716)
		(end 372.190264 -268.080236)
		(width 0.0889)
		(layer "B.Cu")
		(net "PU_S3M_CPU0_CPLD_CONFD")
	)
	(segment
		(start 369.745514 -268.080236)
		(end 369.755928 -268.07414)
		(width 0.0889)
		(layer "B.Cu")
		(net "PU_S3M_CPU0_CPLD_CONFD")
	)
	(segment
		(start 411.029658 -243.87429)
		(end 413.048958 -241.85499)
		(width 0.12954)
		(layer "B.Cu")
		(net "PU_S3M_CPU0_CPLD_CONFD")
	)
	(segment
		(start 364.702852 -268.026896)
		(end 364.723934 -268.104874)
		(width 0.0889)
		(layer "B.Cu")
		(net "PU_S3M_CPU0_CPLD_CONFD")
	)
	(arc
		(start 372.190264 -268.080236)
		(mid 372.377462 -268.130379)
		(end 372.56466 -268.080236)
		(width 0.0889)
		(layer "B.Cu")
		(net "PU_S3M_CPU0_CPLD_CONFD")
	)
	(arc
		(start 365.98606 -268.080236)
		(mid 366.262873 -268.004366)
		(end 366.541304 -268.07414)
		(width 0.0889)
		(layer "B.Cu")
		(net "PU_S3M_CPU0_CPLD_CONFD")
	)
	(arc
		(start 376.889264 -268.080236)
		(mid 377.076462 -268.130379)
		(end 377.26366 -268.080236)
		(width 0.0889)
		(layer "B.Cu")
		(net "PU_S3M_CPU0_CPLD_CONFD")
	)
	(arc
		(start 380.083314 -268.080236)
		(mid 380.359873 -268.004493)
		(end 380.63805 -268.07414)
		(width 0.0889)
		(layer "B.Cu")
		(net "PU_S3M_CPU0_CPLD_CONFD")
	)
	(arc
		(start 371.62486 -268.080236)
		(mid 371.899059 -268.004401)
		(end 372.175532 -268.0716)
		(width 0.0889)
		(layer "B.Cu")
		(net "PU_S3M_CPU0_CPLD_CONFD")
	)
	(arc
		(start 373.50446 -268.080236)
		(mid 373.778659 -268.004401)
		(end 374.055132 -268.0716)
		(width 0.0889)
		(layer "B.Cu")
		(net "PU_S3M_CPU0_CPLD_CONFD")
	)
	(arc
		(start 368.805714 -268.080236)
		(mid 369.088416 -268.00446)
		(end 369.371118 -268.080236)
		(width 0.0889)
		(layer "B.Cu")
		(net "PU_S3M_CPU0_CPLD_CONFD")
	)
	(arc
		(start 381.02286 -268.080236)
		(mid 381.297059 -268.004401)
		(end 381.573532 -268.0716)
		(width 0.0889)
		(layer "B.Cu")
		(net "PU_S3M_CPU0_CPLD_CONFD")
	)
	(arc
		(start 377.26366 -268.080236)
		(mid 377.537859 -268.004401)
		(end 377.814332 -268.0716)
		(width 0.0889)
		(layer "B.Cu")
		(net "PU_S3M_CPU0_CPLD_CONFD")
	)
	(arc
		(start 375.009664 -268.080236)
		(mid 375.196862 -268.130379)
		(end 375.38406 -268.080236)
		(width 0.0889)
		(layer "B.Cu")
		(net "PU_S3M_CPU0_CPLD_CONFD")
	)
	(arc
		(start 375.949464 -268.080236)
		(mid 376.136662 -268.130379)
		(end 376.32386 -268.080236)
		(width 0.0889)
		(layer "B.Cu")
		(net "PU_S3M_CPU0_CPLD_CONFD")
	)
	(arc
		(start 367.491264 -268.080236)
		(mid 367.678462 -268.130379)
		(end 367.86566 -268.080236)
		(width 0.0889)
		(layer "B.Cu")
		(net "PU_S3M_CPU0_CPLD_CONFD")
	)
	(arc
		(start 372.56466 -268.080236)
		(mid 372.838859 -268.004401)
		(end 373.115332 -268.0716)
		(width 0.0889)
		(layer "B.Cu")
		(net "PU_S3M_CPU0_CPLD_CONFD")
	)
	(arc
		(start 374.44426 -268.080236)
		(mid 374.718459 -268.004401)
		(end 374.994932 -268.0716)
		(width 0.0889)
		(layer "B.Cu")
		(net "PU_S3M_CPU0_CPLD_CONFD")
	)
	(arc
		(start 379.708918 -268.080236)
		(mid 379.896116 -268.130379)
		(end 380.083314 -268.080236)
		(width 0.0889)
		(layer "B.Cu")
		(net "PU_S3M_CPU0_CPLD_CONFD")
	)
	(arc
		(start 370.310664 -268.080236)
		(mid 370.497862 -268.130379)
		(end 370.68506 -268.080236)
		(width 0.0889)
		(layer "B.Cu")
		(net "PU_S3M_CPU0_CPLD_CONFD")
	)
	(arc
		(start 374.069864 -268.080236)
		(mid 374.257062 -268.130379)
		(end 374.44426 -268.080236)
		(width 0.0889)
		(layer "B.Cu")
		(net "PU_S3M_CPU0_CPLD_CONFD")
	)
	(arc
		(start 370.68506 -268.080236)
		(mid 370.967762 -268.00446)
		(end 371.250464 -268.080236)
		(width 0.0889)
		(layer "B.Cu")
		(net "PU_S3M_CPU0_CPLD_CONFD")
	)
	(arc
		(start 381.96266 -268.080236)
		(mid 382.236859 -268.004401)
		(end 382.513332 -268.0716)
		(width 0.0889)
		(layer "B.Cu")
		(net "PU_S3M_CPU0_CPLD_CONFD")
	)
	(arc
		(start 364.723934 -268.104874)
		(mid 364.88803 -268.129221)
		(end 365.046514 -268.080236)
		(width 0.0889)
		(layer "B.Cu")
		(net "PU_S3M_CPU0_CPLD_CONFD")
	)
	(arc
		(start 382.90246 -268.080236)
		(mid 383.176659 -268.004401)
		(end 383.453132 -268.0716)
		(width 0.0889)
		(layer "B.Cu")
		(net "PU_S3M_CPU0_CPLD_CONFD")
	)
	(arc
		(start 377.829064 -268.080236)
		(mid 378.016262 -268.130379)
		(end 378.20346 -268.080236)
		(width 0.0889)
		(layer "B.Cu")
		(net "PU_S3M_CPU0_CPLD_CONFD")
	)
	(arc
		(start 368.431318 -268.080236)
		(mid 368.618516 -268.130379)
		(end 368.805714 -268.080236)
		(width 0.0889)
		(layer "B.Cu")
		(net "PU_S3M_CPU0_CPLD_CONFD")
	)
	(arc
		(start 379.14326 -268.080236)
		(mid 379.420073 -268.004366)
		(end 379.698504 -268.07414)
		(width 0.0889)
		(layer "B.Cu")
		(net "PU_S3M_CPU0_CPLD_CONFD")
	)
	(arc
		(start 365.056928 -268.07414)
		(mid 365.335106 -268.004417)
		(end 365.611664 -268.080236)
		(width 0.0889)
		(layer "B.Cu")
		(net "PU_S3M_CPU0_CPLD_CONFD")
	)
	(arc
		(start 383.84226 -268.080236)
		(mid 384.124962 -268.00446)
		(end 384.407664 -268.080236)
		(width 0.0889)
		(layer "B.Cu")
		(net "PU_S3M_CPU0_CPLD_CONFD")
	)
	(arc
		(start 371.250464 -268.080236)
		(mid 371.437662 -268.130379)
		(end 371.62486 -268.080236)
		(width 0.0889)
		(layer "B.Cu")
		(net "PU_S3M_CPU0_CPLD_CONFD")
	)
	(arc
		(start 375.38406 -268.080236)
		(mid 375.658259 -268.004401)
		(end 375.934732 -268.0716)
		(width 0.0889)
		(layer "B.Cu")
		(net "PU_S3M_CPU0_CPLD_CONFD")
	)
	(arc
		(start 384.407664 -268.080236)
		(mid 384.497936 -268.117835)
		(end 384.594862 -268.130782)
		(width 0.0889)
		(layer "B.Cu")
		(net "PU_S3M_CPU0_CPLD_CONFD")
	)
	(arc
		(start 378.768864 -268.080236)
		(mid 378.956062 -268.130379)
		(end 379.14326 -268.080236)
		(width 0.0889)
		(layer "B.Cu")
		(net "PU_S3M_CPU0_CPLD_CONFD")
	)
	(arc
		(start 365.611664 -268.080236)
		(mid 365.798862 -268.130379)
		(end 365.98606 -268.080236)
		(width 0.0889)
		(layer "B.Cu")
		(net "PU_S3M_CPU0_CPLD_CONFD")
	)
	(arc
		(start 369.755928 -268.07414)
		(mid 370.034106 -268.004417)
		(end 370.310664 -268.080236)
		(width 0.0889)
		(layer "B.Cu")
		(net "PU_S3M_CPU0_CPLD_CONFD")
	)
	(arc
		(start 366.936528 -268.07414)
		(mid 367.214706 -268.004417)
		(end 367.491264 -268.080236)
		(width 0.0889)
		(layer "B.Cu")
		(net "PU_S3M_CPU0_CPLD_CONFD")
	)
	(arc
		(start 378.20346 -268.080236)
		(mid 378.477659 -268.004401)
		(end 378.754132 -268.0716)
		(width 0.0889)
		(layer "B.Cu")
		(net "PU_S3M_CPU0_CPLD_CONFD")
	)
	(arc
		(start 366.551718 -268.080236)
		(mid 366.738916 -268.130379)
		(end 366.926114 -268.080236)
		(width 0.0889)
		(layer "B.Cu")
		(net "PU_S3M_CPU0_CPLD_CONFD")
	)
	(arc
		(start 380.648464 -268.080236)
		(mid 380.835662 -268.130379)
		(end 381.02286 -268.080236)
		(width 0.0889)
		(layer "B.Cu")
		(net "PU_S3M_CPU0_CPLD_CONFD")
	)
	(arc
		(start 382.528064 -268.080236)
		(mid 382.715262 -268.130379)
		(end 382.90246 -268.080236)
		(width 0.0889)
		(layer "B.Cu")
		(net "PU_S3M_CPU0_CPLD_CONFD")
	)
	(arc
		(start 367.876074 -268.07414)
		(mid 368.154506 -268.004294)
		(end 368.431318 -268.080236)
		(width 0.0889)
		(layer "B.Cu")
		(net "PU_S3M_CPU0_CPLD_CONFD")
	)
	(arc
		(start 373.130064 -268.080236)
		(mid 373.317262 -268.130379)
		(end 373.50446 -268.080236)
		(width 0.0889)
		(layer "B.Cu")
		(net "PU_S3M_CPU0_CPLD_CONFD")
	)
	(arc
		(start 369.371118 -268.080236)
		(mid 369.558316 -268.130379)
		(end 369.745514 -268.080236)
		(width 0.0889)
		(layer "B.Cu")
		(net "PU_S3M_CPU0_CPLD_CONFD")
	)
	(arc
		(start 381.588264 -268.080236)
		(mid 381.775462 -268.130379)
		(end 381.96266 -268.080236)
		(width 0.0889)
		(layer "B.Cu")
		(net "PU_S3M_CPU0_CPLD_CONFD")
	)
	(arc
		(start 383.467864 -268.080236)
		(mid 383.655062 -268.130379)
		(end 383.84226 -268.080236)
		(width 0.0889)
		(layer "B.Cu")
		(net "PU_S3M_CPU0_CPLD_CONFD")
	)
	(arc
		(start 376.32386 -268.080236)
		(mid 376.598059 -268.004401)
		(end 376.874532 -268.0716)
		(width 0.0889)
		(layer "B.Cu")
		(net "PU_S3M_CPU0_CPLD_CONFD")
	)
	(segment
		(start 114.402362 -137.028682)
		(end 113.894362 -136.520682)
		(width 0.12954)
		(layer "F.Cu")
		(net "PU_RST_SMB_PCIE0_N")
	)
	(segment
		(start 118.108476 -136.246616)
		(end 117.221508 -136.246616)
		(width 0.12954)
		(layer "F.Cu")
		(net "PU_RST_SMB_PCIE0_N")
	)
	(segment
		(start 116.439442 -137.028682)
		(end 115.54079 -137.028682)
		(width 0.12954)
		(layer "F.Cu")
		(net "PU_RST_SMB_PCIE0_N")
	)
	(segment
		(start 117.221508 -136.246616)
		(end 116.439442 -137.028682)
		(width 0.12954)
		(layer "F.Cu")
		(net "PU_RST_SMB_PCIE0_N")
	)
	(segment
		(start 115.54079 -137.028682)
		(end 114.402362 -137.028682)
		(width 0.12954)
		(layer "F.Cu")
		(net "PU_RST_SMB_PCIE0_N")
	)
	(via
		(at 115.54079 -137.028682)
		(size 0.762)
		(drill 0.381)
		(layers "F.Cu" "B.Cu")
		(net "PU_RST_SMB_PCIE0_N")
	)
	(segment
		(start 172.555662 -111.375444)
		(end 172.155612 -110.975394)
		(width 0.12954)
		(layer "F.Cu")
		(net "PU_RST_DEDI_BUSY_PLD_N")
	)
	(via
		(at 172.155612 -110.975394)
		(size 0.4572)
		(drill 0.254)
		(layers "F.Cu" "B.Cu")
		(net "PU_RST_DEDI_BUSY_PLD_N")
	)
	(via
		(at 158.90748 -113.756948)
		(size 0.508)
		(drill 0.254)
		(layers "F.Cu" "B.Cu")
		(net "PU_RST_DEDI_BUSY_PLD_N")
	)
	(segment
		(start 158.90748 -113.426748)
		(end 158.72968 -113.248948)
		(width 0.12954)
		(layer "B.Cu")
		(net "PU_RST_DEDI_BUSY_PLD_N")
	)
	(segment
		(start 158.72968 -113.248948)
		(end 157.61208 -113.248948)
		(width 0.12954)
		(layer "B.Cu")
		(net "PU_RST_DEDI_BUSY_PLD_N")
	)
	(segment
		(start 157.61208 -113.248948)
		(end 157.42793 -113.433098)
		(width 0.12954)
		(layer "B.Cu")
		(net "PU_RST_DEDI_BUSY_PLD_N")
	)
	(segment
		(start 158.90748 -113.756948)
		(end 158.90748 -113.426748)
		(width 0.12954)
		(layer "B.Cu")
		(net "PU_RST_DEDI_BUSY_PLD_N")
	)
	(segment
		(start 157.42793 -113.433098)
		(end 157.42793 -113.756948)
		(width 0.12954)
		(layer "B.Cu")
		(net "PU_RST_DEDI_BUSY_PLD_N")
	)
	(segment
		(start 171.759118 -111.371888)
		(end 169.144442 -111.371888)
		(width 0.127)
		(layer "In6.Cu")
		(net "PU_RST_DEDI_BUSY_PLD_N")
	)
	(segment
		(start 160.960308 -112.2426)
		(end 160.10128 -113.101628)
		(width 0.127)
		(layer "In6.Cu")
		(net "PU_RST_DEDI_BUSY_PLD_N")
	)
	(segment
		(start 172.155612 -110.975394)
		(end 171.759118 -111.371888)
		(width 0.127)
		(layer "In6.Cu")
		(net "PU_RST_DEDI_BUSY_PLD_N")
	)
	(segment
		(start 159.5628 -113.101628)
		(end 158.90748 -113.756948)
		(width 0.127)
		(layer "In6.Cu")
		(net "PU_RST_DEDI_BUSY_PLD_N")
	)
	(segment
		(start 164.080444 -112.171734)
		(end 164.009578 -112.2426)
		(width 0.127)
		(layer "In6.Cu")
		(net "PU_RST_DEDI_BUSY_PLD_N")
	)
	(segment
		(start 169.144442 -111.371888)
		(end 168.344596 -112.171734)
		(width 0.127)
		(layer "In6.Cu")
		(net "PU_RST_DEDI_BUSY_PLD_N")
	)
	(segment
		(start 160.10128 -113.101628)
		(end 159.5628 -113.101628)
		(width 0.127)
		(layer "In6.Cu")
		(net "PU_RST_DEDI_BUSY_PLD_N")
	)
	(segment
		(start 168.344596 -112.171734)
		(end 164.080444 -112.171734)
		(width 0.127)
		(layer "In6.Cu")
		(net "PU_RST_DEDI_BUSY_PLD_N")
	)
	(segment
		(start 164.009578 -112.2426)
		(end 160.960308 -112.2426)
		(width 0.127)
		(layer "In6.Cu")
		(net "PU_RST_DEDI_BUSY_PLD_N")
	)
	(segment
		(start 221.569026 -109.337348)
		(end 220.69933 -109.337348)
		(width 0.12954)
		(layer "F.Cu")
		(net "PU_PLD_HEARTBEAT_LVC3")
	)
	(segment
		(start 220.69933 -109.337348)
		(end 220.44533 -109.591348)
		(width 0.12954)
		(layer "F.Cu")
		(net "PU_PLD_HEARTBEAT_LVC3")
	)
	(segment
		(start 221.69628 -109.464602)
		(end 221.569026 -109.337348)
		(width 0.12954)
		(layer "F.Cu")
		(net "PU_PLD_HEARTBEAT_LVC3")
	)
	(segment
		(start 220.26626 -111.115348)
		(end 221.213934 -111.115348)
		(width 0.12954)
		(layer "F.Cu")
		(net "PU_PLD_HEARTBEAT_LVC3")
	)
	(segment
		(start 221.213934 -111.115348)
		(end 221.69628 -110.633002)
		(width 0.12954)
		(layer "F.Cu")
		(net "PU_PLD_HEARTBEAT_LVC3")
	)
	(segment
		(start 221.69628 -110.633002)
		(end 221.69628 -109.464602)
		(width 0.12954)
		(layer "F.Cu")
		(net "PU_PLD_HEARTBEAT_LVC3")
	)
	(via
		(at 221.69628 -109.464602)
		(size 0.762)
		(drill 0.381)
		(layers "F.Cu" "B.Cu")
		(net "PU_PLD_HEARTBEAT_LVC3")
	)
	(segment
		(start 119.738648 -274.26666)
		(end 119.738394 -274.266914)
		(width 0.12954)
		(layer "F.Cu")
		(net "PU_PIROM_CPU1_SM_WP")
	)
	(segment
		(start 193.53403 -355.996748)
		(end 193.53403 -357.139748)
		(width 0.12954)
		(layer "F.Cu")
		(net "PU_PIROM_CPU1_SM_WP")
	)
	(segment
		(start 119.738648 -273.730974)
		(end 119.738648 -274.26666)
		(width 0.12954)
		(layer "F.Cu")
		(net "PU_PIROM_CPU1_SM_WP")
	)
	(segment
		(start 192.84188 -357.139748)
		(end 193.53403 -357.139748)
		(width 0.12954)
		(layer "F.Cu")
		(net "PU_PIROM_CPU1_SM_WP")
	)
	(segment
		(start 192.63868 -357.342948)
		(end 192.84188 -357.139748)
		(width 0.12954)
		(layer "F.Cu")
		(net "PU_PIROM_CPU1_SM_WP")
	)
	(via
		(at 192.63868 -357.342948)
		(size 0.508)
		(drill 0.254)
		(layers "F.Cu" "B.Cu")
		(net "PU_PIROM_CPU1_SM_WP")
	)
	(via
		(at 119.738394 -274.266914)
		(size 0.4572)
		(drill 0.2032)
		(layers "F.Cu" "B.Cu")
		(net "PU_PIROM_CPU1_SM_WP")
	)
	(segment
		(start 121.522998 -281.607514)
		(end 121.522998 -281.576526)
		(width 0.0889)
		(layer "In11.Cu")
		(net "PU_PIROM_CPU1_SM_WP")
	)
	(segment
		(start 120.582944 -288.110676)
		(end 120.582944 -288.103056)
		(width 0.0889)
		(layer "In11.Cu")
		(net "PU_PIROM_CPU1_SM_WP")
	)
	(segment
		(start 120.874536 -288.597848)
		(end 120.865646 -288.592768)
		(width 0.0889)
		(layer "In11.Cu")
		(net "PU_PIROM_CPU1_SM_WP")
	)
	(segment
		(start 194.18808 -337.85175)
		(end 188.431678 -332.095348)
		(width 0.127)
		(layer "In11.Cu")
		(net "PU_PIROM_CPU1_SM_WP")
	)
	(segment
		(start 120.583198 -276.72411)
		(end 120.583198 -276.693122)
		(width 0.0889)
		(layer "In11.Cu")
		(net "PU_PIROM_CPU1_SM_WP")
	)
	(segment
		(start 121.805192 -282.730194)
		(end 121.814082 -282.725114)
		(width 0.0889)
		(layer "In11.Cu")
		(net "PU_PIROM_CPU1_SM_WP")
	)
	(segment
		(start 123.0122 -290.718748)
		(end 121.9454 -290.718748)
		(width 0.0889)
		(layer "In11.Cu")
		(net "PU_PIROM_CPU1_SM_WP")
	)
	(segment
		(start 119.894858 -273.995896)
		(end 119.738394 -274.266914)
		(width 0.0889)
		(layer "In11.Cu")
		(net "PU_PIROM_CPU1_SM_WP")
	)
	(segment
		(start 121.335292 -286.799782)
		(end 121.344182 -286.794702)
		(width 0.0889)
		(layer "In11.Cu")
		(net "PU_PIROM_CPU1_SM_WP")
	)
	(segment
		(start 121.814082 -280.458926)
		(end 121.805192 -280.453846)
		(width 0.0889)
		(layer "In11.Cu")
		(net "PU_PIROM_CPU1_SM_WP")
	)
	(segment
		(start 159.958278 -332.095348)
		(end 129.3114 -301.44847)
		(width 0.127)
		(layer "In11.Cu")
		(net "PU_PIROM_CPU1_SM_WP")
	)
	(segment
		(start 121.052844 -287.28924)
		(end 121.052844 -287.279334)
		(width 0.0889)
		(layer "In11.Cu")
		(net "PU_PIROM_CPU1_SM_WP")
	)
	(segment
		(start 119.984012 -273.97202)
		(end 119.894858 -273.995896)
		(width 0.0889)
		(layer "In11.Cu")
		(net "PU_PIROM_CPU1_SM_WP")
	)
	(segment
		(start 120.874282 -273.947636)
		(end 120.865392 -273.942556)
		(width 0.0889)
		(layer "In11.Cu")
		(net "PU_PIROM_CPU1_SM_WP")
	)
	(segment
		(start 192.63868 -357.342948)
		(end 194.18808 -355.793548)
		(width 0.127)
		(layer "In11.Cu")
		(net "PU_PIROM_CPU1_SM_WP")
	)
	(segment
		(start 121.814082 -285.342076)
		(end 121.805192 -285.336996)
		(width 0.0889)
		(layer "In11.Cu")
		(net "PU_PIROM_CPU1_SM_WP")
	)
	(segment
		(start 120.859296 -287.617154)
		(end 120.865392 -287.613598)
		(width 0.0889)
		(layer "In11.Cu")
		(net "PU_PIROM_CPU1_SM_WP")
	)
	(segment
		(start 120.490996 -273.942556)
		(end 120.476264 -273.951192)
		(width 0.0889)
		(layer "In11.Cu")
		(net "PU_PIROM_CPU1_SM_WP")
	)
	(segment
		(start 121.9454 -290.718748)
		(end 121.522744 -290.296092)
		(width 0.0889)
		(layer "In11.Cu")
		(net "PU_PIROM_CPU1_SM_WP")
	)
	(segment
		(start 129.3114 -295.407588)
		(end 124.62256 -290.718748)
		(width 0.127)
		(layer "In11.Cu")
		(net "PU_PIROM_CPU1_SM_WP")
	)
	(segment
		(start 188.431678 -332.095348)
		(end 159.958278 -332.095348)
		(width 0.127)
		(layer "In11.Cu")
		(net "PU_PIROM_CPU1_SM_WP")
	)
	(segment
		(start 121.522744 -290.296092)
		(end 121.522744 -289.645852)
		(width 0.0889)
		(layer "In11.Cu")
		(net "PU_PIROM_CPU1_SM_WP")
	)
	(segment
		(start 121.522998 -284.863032)
		(end 121.522998 -284.832044)
		(width 0.0889)
		(layer "In11.Cu")
		(net "PU_PIROM_CPU1_SM_WP")
	)
	(segment
		(start 121.522744 -286.475424)
		(end 121.522744 -286.4612)
		(width 0.0889)
		(layer "In11.Cu")
		(net "PU_PIROM_CPU1_SM_WP")
	)
	(segment
		(start 121.522744 -283.229812)
		(end 121.522744 -283.201364)
		(width 0.0889)
		(layer "In11.Cu")
		(net "PU_PIROM_CPU1_SM_WP")
	)
	(segment
		(start 120.865392 -274.591272)
		(end 120.874282 -274.586192)
		(width 0.0889)
		(layer "In11.Cu")
		(net "PU_PIROM_CPU1_SM_WP")
	)
	(segment
		(start 121.805192 -281.102562)
		(end 121.814082 -281.097482)
		(width 0.0889)
		(layer "In11.Cu")
		(net "PU_PIROM_CPU1_SM_WP")
	)
	(segment
		(start 121.522744 -278.346408)
		(end 121.522744 -278.327866)
		(width 0.0889)
		(layer "In11.Cu")
		(net "PU_PIROM_CPU1_SM_WP")
	)
	(segment
		(start 124.62256 -290.718748)
		(end 123.0122 -290.718748)
		(width 0.127)
		(layer "In11.Cu")
		(net "PU_PIROM_CPU1_SM_WP")
	)
	(segment
		(start 120.865392 -287.613598)
		(end 120.874282 -287.608518)
		(width 0.0889)
		(layer "In11.Cu")
		(net "PU_PIROM_CPU1_SM_WP")
	)
	(segment
		(start 129.3114 -301.44847)
		(end 129.3114 -295.407588)
		(width 0.127)
		(layer "In11.Cu")
		(net "PU_PIROM_CPU1_SM_WP")
	)
	(segment
		(start 121.052844 -277.536656)
		(end 121.052844 -277.522432)
		(width 0.0889)
		(layer "In11.Cu")
		(net "PU_PIROM_CPU1_SM_WP")
	)
	(segment
		(start 194.18808 -355.793548)
		(end 194.18808 -337.85175)
		(width 0.127)
		(layer "In11.Cu")
		(net "PU_PIROM_CPU1_SM_WP")
	)
	(segment
		(start 120.865392 -276.219158)
		(end 120.874282 -276.214078)
		(width 0.0889)
		(layer "In11.Cu")
		(net "PU_PIROM_CPU1_SM_WP")
	)
	(segment
		(start 121.805192 -285.985712)
		(end 121.814082 -285.980632)
		(width 0.0889)
		(layer "In11.Cu")
		(net "PU_PIROM_CPU1_SM_WP")
	)
	(segment
		(start 121.053098 -289.114738)
		(end 121.053098 -288.917126)
		(width 0.0889)
		(layer "In11.Cu")
		(net "PU_PIROM_CPU1_SM_WP")
	)
	(segment
		(start 121.814082 -278.83104)
		(end 121.805192 -278.82596)
		(width 0.0889)
		(layer "In11.Cu")
		(net "PU_PIROM_CPU1_SM_WP")
	)
	(segment
		(start 121.814082 -283.714444)
		(end 121.805192 -283.709364)
		(width 0.0889)
		(layer "In11.Cu")
		(net "PU_PIROM_CPU1_SM_WP")
	)
	(segment
		(start 121.805192 -279.474676)
		(end 121.814082 -279.469596)
		(width 0.0889)
		(layer "In11.Cu")
		(net "PU_PIROM_CPU1_SM_WP")
	)
	(segment
		(start 120.583198 -275.081492)
		(end 120.583198 -275.065236)
		(width 0.0889)
		(layer "In11.Cu")
		(net "PU_PIROM_CPU1_SM_WP")
	)
	(segment
		(start 120.874282 -275.575522)
		(end 120.865392 -275.570442)
		(width 0.0889)
		(layer "In11.Cu")
		(net "PU_PIROM_CPU1_SM_WP")
	)
	(segment
		(start 121.522998 -279.986232)
		(end 121.522998 -279.94864)
		(width 0.0889)
		(layer "In11.Cu")
		(net "PU_PIROM_CPU1_SM_WP")
	)
	(segment
		(start 121.814082 -282.086558)
		(end 121.805192 -282.081478)
		(width 0.0889)
		(layer "In11.Cu")
		(net "PU_PIROM_CPU1_SM_WP")
	)
	(segment
		(start 121.805192 -284.35808)
		(end 121.814082 -284.353)
		(width 0.0889)
		(layer "In11.Cu")
		(net "PU_PIROM_CPU1_SM_WP")
	)
	(segment
		(start 120.874282 -277.203154)
		(end 120.865392 -277.198074)
		(width 0.0889)
		(layer "In11.Cu")
		(net "PU_PIROM_CPU1_SM_WP")
	)
	(arc
		(start 120.476264 -273.951192)
		(mid 120.23252 -274.018071)
		(end 119.984012 -273.97202)
		(width 0.0889)
		(layer "In11.Cu")
		(net "PU_PIROM_CPU1_SM_WP")
	)
	(arc
		(start 121.805192 -283.709364)
		(mid 121.600857 -283.506759)
		(end 121.522744 -283.229812)
		(width 0.0889)
		(layer "In11.Cu")
		(net "PU_PIROM_CPU1_SM_WP")
	)
	(arc
		(start 120.583198 -276.693122)
		(mid 120.662568 -276.419388)
		(end 120.865392 -276.219158)
		(width 0.0889)
		(layer "In11.Cu")
		(net "PU_PIROM_CPU1_SM_WP")
	)
	(arc
		(start 120.865392 -277.198074)
		(mid 120.662569 -276.997843)
		(end 120.583198 -276.72411)
		(width 0.0889)
		(layer "In11.Cu")
		(net "PU_PIROM_CPU1_SM_WP")
	)
	(arc
		(start 120.582944 -288.103056)
		(mid 120.65686 -287.823554)
		(end 120.859296 -287.617154)
		(width 0.0889)
		(layer "In11.Cu")
		(net "PU_PIROM_CPU1_SM_WP")
	)
	(arc
		(start 121.335546 -278.012144)
		(mid 121.132065 -277.81134)
		(end 121.052844 -277.536656)
		(width 0.0889)
		(layer "In11.Cu")
		(net "PU_PIROM_CPU1_SM_WP")
	)
	(arc
		(start 121.814082 -279.469596)
		(mid 121.992679 -279.150318)
		(end 121.814082 -278.83104)
		(width 0.0889)
		(layer "In11.Cu")
		(net "PU_PIROM_CPU1_SM_WP")
	)
	(arc
		(start 120.874282 -276.214078)
		(mid 121.052879 -275.8948)
		(end 120.874282 -275.575522)
		(width 0.0889)
		(layer "In11.Cu")
		(net "PU_PIROM_CPU1_SM_WP")
	)
	(arc
		(start 120.874282 -287.608518)
		(mid 121.005196 -287.472158)
		(end 121.052844 -287.28924)
		(width 0.0889)
		(layer "In11.Cu")
		(net "PU_PIROM_CPU1_SM_WP")
	)
	(arc
		(start 120.865392 -273.942556)
		(mid 120.678194 -273.892413)
		(end 120.490996 -273.942556)
		(width 0.0889)
		(layer "In11.Cu")
		(net "PU_PIROM_CPU1_SM_WP")
	)
	(arc
		(start 121.522744 -278.327866)
		(mid 121.470474 -278.145501)
		(end 121.335546 -278.012144)
		(width 0.0889)
		(layer "In11.Cu")
		(net "PU_PIROM_CPU1_SM_WP")
	)
	(arc
		(start 121.805192 -282.081478)
		(mid 121.602369 -281.881247)
		(end 121.522998 -281.607514)
		(width 0.0889)
		(layer "In11.Cu")
		(net "PU_PIROM_CPU1_SM_WP")
	)
	(arc
		(start 121.344182 -286.794702)
		(mid 121.475096 -286.658342)
		(end 121.522744 -286.475424)
		(width 0.0889)
		(layer "In11.Cu")
		(net "PU_PIROM_CPU1_SM_WP")
	)
	(arc
		(start 121.805192 -285.336996)
		(mid 121.602369 -285.136765)
		(end 121.522998 -284.863032)
		(width 0.0889)
		(layer "In11.Cu")
		(net "PU_PIROM_CPU1_SM_WP")
	)
	(arc
		(start 121.052844 -277.522432)
		(mid 121.005165 -277.339532)
		(end 120.874282 -277.203154)
		(width 0.0889)
		(layer "In11.Cu")
		(net "PU_PIROM_CPU1_SM_WP")
	)
	(arc
		(start 121.814082 -284.353)
		(mid 121.992679 -284.033722)
		(end 121.814082 -283.714444)
		(width 0.0889)
		(layer "In11.Cu")
		(net "PU_PIROM_CPU1_SM_WP")
	)
	(arc
		(start 121.522998 -279.94864)
		(mid 121.602368 -279.674906)
		(end 121.805192 -279.474676)
		(width 0.0889)
		(layer "In11.Cu")
		(net "PU_PIROM_CPU1_SM_WP")
	)
	(arc
		(start 121.338594 -289.446462)
		(mid 121.164462 -289.307615)
		(end 121.053098 -289.114738)
		(width 0.0889)
		(layer "In11.Cu")
		(net "PU_PIROM_CPU1_SM_WP")
	)
	(arc
		(start 121.522998 -284.832044)
		(mid 121.602368 -284.55831)
		(end 121.805192 -284.35808)
		(width 0.0889)
		(layer "In11.Cu")
		(net "PU_PIROM_CPU1_SM_WP")
	)
	(arc
		(start 121.052844 -287.279334)
		(mid 121.130955 -287.002385)
		(end 121.335292 -286.799782)
		(width 0.0889)
		(layer "In11.Cu")
		(net "PU_PIROM_CPU1_SM_WP")
	)
	(arc
		(start 121.053098 -288.917126)
		(mid 121.005419 -288.734226)
		(end 120.874536 -288.597848)
		(width 0.0889)
		(layer "In11.Cu")
		(net "PU_PIROM_CPU1_SM_WP")
	)
	(arc
		(start 121.805192 -278.82596)
		(mid 121.600857 -278.623355)
		(end 121.522744 -278.346408)
		(width 0.0889)
		(layer "In11.Cu")
		(net "PU_PIROM_CPU1_SM_WP")
	)
	(arc
		(start 121.522744 -286.4612)
		(mid 121.601885 -286.186577)
		(end 121.805192 -285.985712)
		(width 0.0889)
		(layer "In11.Cu")
		(net "PU_PIROM_CPU1_SM_WP")
	)
	(arc
		(start 120.583198 -275.065236)
		(mid 120.662568 -274.791502)
		(end 120.865392 -274.591272)
		(width 0.0889)
		(layer "In11.Cu")
		(net "PU_PIROM_CPU1_SM_WP")
	)
	(arc
		(start 121.814082 -285.980632)
		(mid 121.992679 -285.661354)
		(end 121.814082 -285.342076)
		(width 0.0889)
		(layer "In11.Cu")
		(net "PU_PIROM_CPU1_SM_WP")
	)
	(arc
		(start 120.865646 -288.592768)
		(mid 120.660574 -288.389089)
		(end 120.582944 -288.110676)
		(width 0.0889)
		(layer "In11.Cu")
		(net "PU_PIROM_CPU1_SM_WP")
	)
	(arc
		(start 121.522744 -289.645852)
		(mid 121.447739 -289.530393)
		(end 121.338594 -289.446462)
		(width 0.0889)
		(layer "In11.Cu")
		(net "PU_PIROM_CPU1_SM_WP")
	)
	(arc
		(start 120.865392 -275.570442)
		(mid 120.658791 -275.363768)
		(end 120.583198 -275.081492)
		(width 0.0889)
		(layer "In11.Cu")
		(net "PU_PIROM_CPU1_SM_WP")
	)
	(arc
		(start 121.805192 -280.453846)
		(mid 121.60391 -280.256359)
		(end 121.522998 -279.986232)
		(width 0.0889)
		(layer "In11.Cu")
		(net "PU_PIROM_CPU1_SM_WP")
	)
	(arc
		(start 121.522998 -281.576526)
		(mid 121.602368 -281.302792)
		(end 121.805192 -281.102562)
		(width 0.0889)
		(layer "In11.Cu")
		(net "PU_PIROM_CPU1_SM_WP")
	)
	(arc
		(start 121.814082 -281.097482)
		(mid 121.992679 -280.778204)
		(end 121.814082 -280.458926)
		(width 0.0889)
		(layer "In11.Cu")
		(net "PU_PIROM_CPU1_SM_WP")
	)
	(arc
		(start 120.874282 -274.586192)
		(mid 121.052879 -274.266914)
		(end 120.874282 -273.947636)
		(width 0.0889)
		(layer "In11.Cu")
		(net "PU_PIROM_CPU1_SM_WP")
	)
	(arc
		(start 121.814082 -282.725114)
		(mid 121.992679 -282.405836)
		(end 121.814082 -282.086558)
		(width 0.0889)
		(layer "In11.Cu")
		(net "PU_PIROM_CPU1_SM_WP")
	)
	(arc
		(start 121.522744 -283.201364)
		(mid 121.602906 -282.929175)
		(end 121.805192 -282.730194)
		(width 0.0889)
		(layer "In11.Cu")
		(net "PU_PIROM_CPU1_SM_WP")
	)
	(segment
		(start 192.68948 -354.904548)
		(end 193.53403 -354.904548)
		(width 0.12954)
		(layer "F.Cu")
		(net "PU_PIROM_CPU1_ADDR0")
	)
	(segment
		(start 193.53403 -353.761548)
		(end 193.53403 -354.904548)
		(width 0.12954)
		(layer "F.Cu")
		(net "PU_PIROM_CPU1_ADDR0")
	)
	(segment
		(start 192.53708 -355.056948)
		(end 192.68948 -354.904548)
		(width 0.12954)
		(layer "F.Cu")
		(net "PU_PIROM_CPU1_ADDR0")
	)
	(segment
		(start 119.738648 -272.103342)
		(end 119.738394 -272.639282)
		(width 0.12954)
		(layer "F.Cu")
		(net "PU_PIROM_CPU1_ADDR0")
	)
	(via
		(at 119.738394 -272.639282)
		(size 0.4572)
		(drill 0.2032)
		(layers "F.Cu" "B.Cu")
		(net "PU_PIROM_CPU1_ADDR0")
	)
	(via
		(at 192.53708 -355.056948)
		(size 0.508)
		(drill 0.254)
		(layers "F.Cu" "B.Cu")
		(net "PU_PIROM_CPU1_ADDR0")
	)
	(segment
		(start 120.303798 -287.28924)
		(end 120.303798 -287.280604)
		(width 0.0889)
		(layer "In11.Cu")
		(net "PU_PIROM_CPU1_ADDR0")
	)
	(segment
		(start 120.395746 -281.267662)
		(end 120.410478 -281.276298)
		(width 0.0889)
		(layer "In11.Cu")
		(net "PU_PIROM_CPU1_ADDR0")
	)
	(segment
		(start 119.08155 -275.405088)
		(end 119.07266 -275.400008)
		(width 0.0889)
		(layer "In11.Cu")
		(net "PU_PIROM_CPU1_ADDR0")
	)
	(segment
		(start 120.95226 -284.52826)
		(end 120.96115 -284.52318)
		(width 0.0889)
		(layer "In11.Cu")
		(net "PU_PIROM_CPU1_ADDR0")
	)
	(segment
		(start 123.0122 -291.048948)
		(end 121.8692 -291.048948)
		(width 0.0889)
		(layer "In11.Cu")
		(net "PU_PIROM_CPU1_ADDR0")
	)
	(segment
		(start 119.833898 -273.459956)
		(end 119.833898 -273.453098)
		(width 0.0889)
		(layer "In11.Cu")
		(net "PU_PIROM_CPU1_ADDR0")
	)
	(segment
		(start 119.833644 -289.982148)
		(end 119.833644 -289.64636)
		(width 0.0889)
		(layer "In11.Cu")
		(net "PU_PIROM_CPU1_ADDR0")
	)
	(segment
		(start 120.303544 -282.405836)
		(end 120.303544 -282.390342)
		(width 0.0889)
		(layer "In11.Cu")
		(net "PU_PIROM_CPU1_ADDR0")
	)
	(segment
		(start 120.49125 -279.474676)
		(end 120.48236 -279.469596)
		(width 0.0889)
		(layer "In11.Cu")
		(net "PU_PIROM_CPU1_ADDR0")
	)
	(segment
		(start 192.53708 -355.056948)
		(end 193.83248 -353.761548)
		(width 0.127)
		(layer "In11.Cu")
		(net "PU_PIROM_CPU1_ADDR0")
	)
	(segment
		(start 120.490996 -282.730194)
		(end 120.482106 -282.725114)
		(width 0.0889)
		(layer "In11.Cu")
		(net "PU_PIROM_CPU1_ADDR0")
	)
	(segment
		(start 120.02135 -278.66086)
		(end 120.01246 -278.65578)
		(width 0.0889)
		(layer "In11.Cu")
		(net "PU_PIROM_CPU1_ADDR0")
	)
	(segment
		(start 120.027446 -278.664416)
		(end 120.02135 -278.66086)
		(width 0.0889)
		(layer "In11.Cu")
		(net "PU_PIROM_CPU1_ADDR0")
	)
	(segment
		(start 119.363998 -277.531068)
		(end 119.363998 -277.513796)
		(width 0.0889)
		(layer "In11.Cu")
		(net "PU_PIROM_CPU1_ADDR0")
	)
	(segment
		(start 121.1072 -290.286948)
		(end 120.138444 -290.286948)
		(width 0.0889)
		(layer "In11.Cu")
		(net "PU_PIROM_CPU1_ADDR0")
	)
	(segment
		(start 120.021096 -288.427414)
		(end 120.012206 -288.422334)
		(width 0.0889)
		(layer "In11.Cu")
		(net "PU_PIROM_CPU1_ADDR0")
	)
	(segment
		(start 120.303798 -289.114484)
		(end 120.303798 -288.902902)
		(width 0.0889)
		(layer "In11.Cu")
		(net "PU_PIROM_CPU1_ADDR0")
	)
	(segment
		(start 121.8692 -291.048948)
		(end 121.1072 -290.286948)
		(width 0.0889)
		(layer "In11.Cu")
		(net "PU_PIROM_CPU1_ADDR0")
	)
	(segment
		(start 120.012206 -287.783778)
		(end 120.021096 -287.778698)
		(width 0.0889)
		(layer "In11.Cu")
		(net "PU_PIROM_CPU1_ADDR0")
	)
	(segment
		(start 124.44984 -291.048948)
		(end 123.0122 -291.048948)
		(width 0.127)
		(layer "In11.Cu")
		(net "PU_PIROM_CPU1_ADDR0")
	)
	(segment
		(start 119.60606 -272.999454)
		(end 119.58193 -272.9103)
		(width 0.0889)
		(layer "In11.Cu")
		(net "PU_PIROM_CPU1_ADDR0")
	)
	(segment
		(start 118.655592 -274.617434)
		(end 118.611396 -274.591272)
		(width 0.0889)
		(layer "In11.Cu")
		(net "PU_PIROM_CPU1_ADDR0")
	)
	(segment
		(start 120.02135 -281.916378)
		(end 120.01246 -281.911298)
		(width 0.0889)
		(layer "In11.Cu")
		(net "PU_PIROM_CPU1_ADDR0")
	)
	(segment
		(start 120.773698 -286.475424)
		(end 120.773698 -286.466788)
		(width 0.0889)
		(layer "In11.Cu")
		(net "PU_PIROM_CPU1_ADDR0")
	)
	(segment
		(start 118.424198 -274.27555)
		(end 118.424198 -274.258278)
		(width 0.0889)
		(layer "In11.Cu")
		(net "PU_PIROM_CPU1_ADDR0")
	)
	(segment
		(start 128.9558 -301.59579)
		(end 128.9558 -295.554908)
		(width 0.127)
		(layer "In11.Cu")
		(net "PU_PIROM_CPU1_ADDR0")
	)
	(segment
		(start 119.563388 -276.22627)
		(end 119.551196 -276.219158)
		(width 0.0889)
		(layer "In11.Cu")
		(net "PU_PIROM_CPU1_ADDR0")
	)
	(segment
		(start 120.138444 -290.286948)
		(end 119.833644 -289.982148)
		(width 0.0889)
		(layer "In11.Cu")
		(net "PU_PIROM_CPU1_ADDR0")
	)
	(segment
		(start 119.536464 -273.951192)
		(end 119.562118 -273.936206)
		(width 0.0889)
		(layer "In11.Cu")
		(net "PU_PIROM_CPU1_ADDR0")
	)
	(segment
		(start 128.9558 -295.554908)
		(end 124.44984 -291.048948)
		(width 0.127)
		(layer "In11.Cu")
		(net "PU_PIROM_CPU1_ADDR0")
	)
	(segment
		(start 159.810958 -332.450948)
		(end 128.9558 -301.59579)
		(width 0.127)
		(layer "In11.Cu")
		(net "PU_PIROM_CPU1_ADDR0")
	)
	(segment
		(start 121.243344 -280.793698)
		(end 121.243344 -280.756106)
		(width 0.0889)
		(layer "In11.Cu")
		(net "PU_PIROM_CPU1_ADDR0")
	)
	(segment
		(start 120.01246 -281.272742)
		(end 120.02135 -281.267662)
		(width 0.0889)
		(layer "In11.Cu")
		(net "PU_PIROM_CPU1_ADDR0")
	)
	(segment
		(start 119.833898 -278.336502)
		(end 119.833898 -278.322278)
		(width 0.0889)
		(layer "In11.Cu")
		(net "PU_PIROM_CPU1_ADDR0")
	)
	(segment
		(start 188.284358 -332.450948)
		(end 159.810958 -332.450948)
		(width 0.127)
		(layer "In11.Cu")
		(net "PU_PIROM_CPU1_ADDR0")
	)
	(segment
		(start 120.773698 -283.228542)
		(end 120.773698 -283.205682)
		(width 0.0889)
		(layer "In11.Cu")
		(net "PU_PIROM_CPU1_ADDR0")
	)
	(segment
		(start 119.363998 -275.903436)
		(end 119.363998 -275.876258)
		(width 0.0889)
		(layer "In11.Cu")
		(net "PU_PIROM_CPU1_ADDR0")
	)
	(segment
		(start 120.96115 -285.171896)
		(end 120.95226 -285.166816)
		(width 0.0889)
		(layer "In11.Cu")
		(net "PU_PIROM_CPU1_ADDR0")
	)
	(segment
		(start 119.58193 -272.9103)
		(end 119.738394 -272.639282)
		(width 0.0889)
		(layer "In11.Cu")
		(net "PU_PIROM_CPU1_ADDR0")
	)
	(segment
		(start 193.83248 -337.99907)
		(end 188.284358 -332.450948)
		(width 0.127)
		(layer "In11.Cu")
		(net "PU_PIROM_CPU1_ADDR0")
	)
	(segment
		(start 121.243344 -285.679896)
		(end 121.243344 -285.64586)
		(width 0.0889)
		(layer "In11.Cu")
		(net "PU_PIROM_CPU1_ADDR0")
	)
	(segment
		(start 120.773698 -279.964134)
		(end 120.773698 -279.954228)
		(width 0.0889)
		(layer "In11.Cu")
		(net "PU_PIROM_CPU1_ADDR0")
	)
	(segment
		(start 120.494806 -286.962596)
		(end 120.497092 -286.961326)
		(width 0.0889)
		(layer "In11.Cu")
		(net "PU_PIROM_CPU1_ADDR0")
	)
	(segment
		(start 119.551196 -277.198074)
		(end 119.563388 -277.190962)
		(width 0.0889)
		(layer "In11.Cu")
		(net "PU_PIROM_CPU1_ADDR0")
	)
	(segment
		(start 120.021096 -287.778698)
		(end 120.02389 -287.777174)
		(width 0.0889)
		(layer "In11.Cu")
		(net "PU_PIROM_CPU1_ADDR0")
	)
	(segment
		(start 193.83248 -353.761548)
		(end 193.83248 -337.99907)
		(width 0.127)
		(layer "In11.Cu")
		(net "PU_PIROM_CPU1_ADDR0")
	)
	(segment
		(start 120.96115 -280.288492)
		(end 120.95226 -280.283412)
		(width 0.0889)
		(layer "In11.Cu")
		(net "PU_PIROM_CPU1_ADDR0")
	)
	(segment
		(start 118.894098 -275.08073)
		(end 118.894098 -275.035518)
		(width 0.0889)
		(layer "In11.Cu")
		(net "PU_PIROM_CPU1_ADDR0")
	)
	(segment
		(start 121.243344 -284.049216)
		(end 121.243344 -284.023816)
		(width 0.0889)
		(layer "In11.Cu")
		(net "PU_PIROM_CPU1_ADDR0")
	)
	(segment
		(start 120.490996 -286.964882)
		(end 120.494806 -286.962596)
		(width 0.0889)
		(layer "In11.Cu")
		(net "PU_PIROM_CPU1_ADDR0")
	)
	(segment
		(start 120.02389 -287.777174)
		(end 120.027192 -287.775142)
		(width 0.0889)
		(layer "In11.Cu")
		(net "PU_PIROM_CPU1_ADDR0")
	)
	(arc
		(start 120.303798 -288.902902)
		(mid 120.224579 -288.628217)
		(end 120.021096 -288.427414)
		(width 0.0889)
		(layer "In11.Cu")
		(net "PU_PIROM_CPU1_ADDR0")
	)
	(arc
		(start 120.303798 -279.150318)
		(mid 120.229882 -278.870816)
		(end 120.027446 -278.664416)
		(width 0.0889)
		(layer "In11.Cu")
		(net "PU_PIROM_CPU1_ADDR0")
	)
	(arc
		(start 119.833898 -273.453098)
		(mid 119.773801 -273.199238)
		(end 119.60606 -272.999454)
		(width 0.0889)
		(layer "In11.Cu")
		(net "PU_PIROM_CPU1_ADDR0")
	)
	(arc
		(start 118.424198 -274.258278)
		(mid 118.476468 -274.075913)
		(end 118.611396 -273.942556)
		(width 0.0889)
		(layer "In11.Cu")
		(net "PU_PIROM_CPU1_ADDR0")
	)
	(arc
		(start 120.773698 -279.954228)
		(mid 120.695587 -279.677279)
		(end 120.49125 -279.474676)
		(width 0.0889)
		(layer "In11.Cu")
		(net "PU_PIROM_CPU1_ADDR0")
	)
	(arc
		(start 120.960896 -283.544264)
		(mid 120.825963 -283.41091)
		(end 120.773698 -283.228542)
		(width 0.0889)
		(layer "In11.Cu")
		(net "PU_PIROM_CPU1_ADDR0")
	)
	(arc
		(start 121.243344 -280.756106)
		(mid 121.162433 -280.485978)
		(end 120.96115 -280.288492)
		(width 0.0889)
		(layer "In11.Cu")
		(net "PU_PIROM_CPU1_ADDR0")
	)
	(arc
		(start 120.95226 -285.166816)
		(mid 120.773663 -284.847538)
		(end 120.95226 -284.52826)
		(width 0.0889)
		(layer "In11.Cu")
		(net "PU_PIROM_CPU1_ADDR0")
	)
	(arc
		(start 121.243344 -284.023816)
		(mid 121.165233 -283.746867)
		(end 120.960896 -283.544264)
		(width 0.0889)
		(layer "In11.Cu")
		(net "PU_PIROM_CPU1_ADDR0")
	)
	(arc
		(start 119.562118 -273.936206)
		(mid 119.761156 -273.734121)
		(end 119.833898 -273.459956)
		(width 0.0889)
		(layer "In11.Cu")
		(net "PU_PIROM_CPU1_ADDR0")
	)
	(arc
		(start 118.894098 -275.035518)
		(mid 118.830275 -274.794858)
		(end 118.655592 -274.617434)
		(width 0.0889)
		(layer "In11.Cu")
		(net "PU_PIROM_CPU1_ADDR0")
	)
	(arc
		(start 119.563388 -277.190962)
		(mid 119.833844 -276.708616)
		(end 119.563388 -276.22627)
		(width 0.0889)
		(layer "In11.Cu")
		(net "PU_PIROM_CPU1_ADDR0")
	)
	(arc
		(start 120.01246 -278.65578)
		(mid 119.881546 -278.51942)
		(end 119.833898 -278.336502)
		(width 0.0889)
		(layer "In11.Cu")
		(net "PU_PIROM_CPU1_ADDR0")
	)
	(arc
		(start 119.363998 -275.876258)
		(mid 119.283836 -275.604069)
		(end 119.08155 -275.405088)
		(width 0.0889)
		(layer "In11.Cu")
		(net "PU_PIROM_CPU1_ADDR0")
	)
	(arc
		(start 119.07266 -275.400008)
		(mid 118.941746 -275.263648)
		(end 118.894098 -275.08073)
		(width 0.0889)
		(layer "In11.Cu")
		(net "PU_PIROM_CPU1_ADDR0")
	)
	(arc
		(start 120.027192 -287.775142)
		(mid 120.229779 -287.568791)
		(end 120.303798 -287.28924)
		(width 0.0889)
		(layer "In11.Cu")
		(net "PU_PIROM_CPU1_ADDR0")
	)
	(arc
		(start 120.482106 -282.725114)
		(mid 120.351192 -282.588754)
		(end 120.303544 -282.405836)
		(width 0.0889)
		(layer "In11.Cu")
		(net "PU_PIROM_CPU1_ADDR0")
	)
	(arc
		(start 119.363998 -277.513796)
		(mid 119.416268 -277.331431)
		(end 119.551196 -277.198074)
		(width 0.0889)
		(layer "In11.Cu")
		(net "PU_PIROM_CPU1_ADDR0")
	)
	(arc
		(start 118.985792 -273.942556)
		(mid 119.259991 -274.018391)
		(end 119.536464 -273.951192)
		(width 0.0889)
		(layer "In11.Cu")
		(net "PU_PIROM_CPU1_ADDR0")
	)
	(arc
		(start 120.48236 -279.469596)
		(mid 120.351446 -279.333236)
		(end 120.303798 -279.150318)
		(width 0.0889)
		(layer "In11.Cu")
		(net "PU_PIROM_CPU1_ADDR0")
	)
	(arc
		(start 119.551196 -277.84679)
		(mid 119.416263 -277.713436)
		(end 119.363998 -277.531068)
		(width 0.0889)
		(layer "In11.Cu")
		(net "PU_PIROM_CPU1_ADDR0")
	)
	(arc
		(start 119.833644 -289.64636)
		(mid 119.908715 -289.530618)
		(end 120.018048 -289.446462)
		(width 0.0889)
		(layer "In11.Cu")
		(net "PU_PIROM_CPU1_ADDR0")
	)
	(arc
		(start 120.497092 -286.961326)
		(mid 120.699679 -286.754975)
		(end 120.773698 -286.475424)
		(width 0.0889)
		(layer "In11.Cu")
		(net "PU_PIROM_CPU1_ADDR0")
	)
	(arc
		(start 120.303798 -287.280604)
		(mid 120.356068 -287.098239)
		(end 120.490996 -286.964882)
		(width 0.0889)
		(layer "In11.Cu")
		(net "PU_PIROM_CPU1_ADDR0")
	)
	(arc
		(start 118.611396 -274.591272)
		(mid 118.476463 -274.457918)
		(end 118.424198 -274.27555)
		(width 0.0889)
		(layer "In11.Cu")
		(net "PU_PIROM_CPU1_ADDR0")
	)
	(arc
		(start 120.303544 -282.390342)
		(mid 120.224174 -282.116608)
		(end 120.02135 -281.916378)
		(width 0.0889)
		(layer "In11.Cu")
		(net "PU_PIROM_CPU1_ADDR0")
	)
	(arc
		(start 120.410478 -281.276298)
		(mid 120.686953 -281.343618)
		(end 120.96115 -281.267662)
		(width 0.0889)
		(layer "In11.Cu")
		(net "PU_PIROM_CPU1_ADDR0")
	)
	(arc
		(start 120.773698 -286.466788)
		(mid 120.825968 -286.284423)
		(end 120.960896 -286.151066)
		(width 0.0889)
		(layer "In11.Cu")
		(net "PU_PIROM_CPU1_ADDR0")
	)
	(arc
		(start 119.833898 -278.322278)
		(mid 119.754679 -278.047593)
		(end 119.551196 -277.84679)
		(width 0.0889)
		(layer "In11.Cu")
		(net "PU_PIROM_CPU1_ADDR0")
	)
	(arc
		(start 120.01246 -281.911298)
		(mid 119.833863 -281.59202)
		(end 120.01246 -281.272742)
		(width 0.0889)
		(layer "In11.Cu")
		(net "PU_PIROM_CPU1_ADDR0")
	)
	(arc
		(start 120.96115 -281.267662)
		(mid 121.163973 -281.067431)
		(end 121.243344 -280.793698)
		(width 0.0889)
		(layer "In11.Cu")
		(net "PU_PIROM_CPU1_ADDR0")
	)
	(arc
		(start 121.243344 -285.64586)
		(mid 121.163974 -285.372126)
		(end 120.96115 -285.171896)
		(width 0.0889)
		(layer "In11.Cu")
		(net "PU_PIROM_CPU1_ADDR0")
	)
	(arc
		(start 120.012206 -288.422334)
		(mid 119.833609 -288.103056)
		(end 120.012206 -287.783778)
		(width 0.0889)
		(layer "In11.Cu")
		(net "PU_PIROM_CPU1_ADDR0")
	)
	(arc
		(start 120.960896 -286.151066)
		(mid 121.163182 -285.952085)
		(end 121.243344 -285.679896)
		(width 0.0889)
		(layer "In11.Cu")
		(net "PU_PIROM_CPU1_ADDR0")
	)
	(arc
		(start 120.95226 -280.283412)
		(mid 120.821346 -280.147052)
		(end 120.773698 -279.964134)
		(width 0.0889)
		(layer "In11.Cu")
		(net "PU_PIROM_CPU1_ADDR0")
	)
	(arc
		(start 120.02135 -281.267662)
		(mid 120.208548 -281.217519)
		(end 120.395746 -281.267662)
		(width 0.0889)
		(layer "In11.Cu")
		(net "PU_PIROM_CPU1_ADDR0")
	)
	(arc
		(start 118.611396 -273.942556)
		(mid 118.798594 -273.892413)
		(end 118.985792 -273.942556)
		(width 0.0889)
		(layer "In11.Cu")
		(net "PU_PIROM_CPU1_ADDR0")
	)
	(arc
		(start 119.551196 -276.219158)
		(mid 119.416263 -276.085804)
		(end 119.363998 -275.903436)
		(width 0.0889)
		(layer "In11.Cu")
		(net "PU_PIROM_CPU1_ADDR0")
	)
	(arc
		(start 120.96115 -284.52318)
		(mid 121.163973 -284.322949)
		(end 121.243344 -284.049216)
		(width 0.0889)
		(layer "In11.Cu")
		(net "PU_PIROM_CPU1_ADDR0")
	)
	(arc
		(start 120.018048 -289.446462)
		(mid 120.192349 -289.307532)
		(end 120.303798 -289.114484)
		(width 0.0889)
		(layer "In11.Cu")
		(net "PU_PIROM_CPU1_ADDR0")
	)
	(arc
		(start 120.773698 -283.205682)
		(mid 120.694479 -282.930997)
		(end 120.490996 -282.730194)
		(width 0.0889)
		(layer "In11.Cu")
		(net "PU_PIROM_CPU1_ADDR0")
	)
	(segment
		(start 385.976622 -363.21619)
		(end 384.468878 -363.21619)
		(width 0.12954)
		(layer "F.Cu")
		(net "PU_PIROM_CPU0_SM_WP")
	)
	(segment
		(start 401.459954 -366.437926)
		(end 400.407378 -365.38535)
		(width 0.12954)
		(layer "F.Cu")
		(net "PU_PIROM_CPU0_SM_WP")
	)
	(segment
		(start 388.30758 -365.547148)
		(end 385.976622 -363.21619)
		(width 0.12954)
		(layer "F.Cu")
		(net "PU_PIROM_CPU0_SM_WP")
	)
	(segment
		(start 400.24558 -365.547148)
		(end 388.30758 -365.547148)
		(width 0.12954)
		(layer "F.Cu")
		(net "PU_PIROM_CPU0_SM_WP")
	)
	(segment
		(start 367.678716 -274.26666)
		(end 367.678462 -274.266914)
		(width 0.12954)
		(layer "F.Cu")
		(net "PU_PIROM_CPU0_SM_WP")
	)
	(segment
		(start 367.678716 -273.730974)
		(end 367.678716 -274.26666)
		(width 0.12954)
		(layer "F.Cu")
		(net "PU_PIROM_CPU0_SM_WP")
	)
	(segment
		(start 405.724614 -366.437926)
		(end 405.724614 -365.294926)
		(width 0.12954)
		(layer "F.Cu")
		(net "PU_PIROM_CPU0_SM_WP")
	)
	(segment
		(start 400.407378 -365.38535)
		(end 400.24558 -365.547148)
		(width 0.12954)
		(layer "F.Cu")
		(net "PU_PIROM_CPU0_SM_WP")
	)
	(segment
		(start 405.724614 -366.437926)
		(end 401.459954 -366.437926)
		(width 0.12954)
		(layer "F.Cu")
		(net "PU_PIROM_CPU0_SM_WP")
	)
	(via
		(at 367.678462 -274.266914)
		(size 0.4572)
		(drill 0.2032)
		(layers "F.Cu" "B.Cu")
		(net "PU_PIROM_CPU0_SM_WP")
	)
	(via
		(at 384.468878 -363.21619)
		(size 0.508)
		(drill 0.254)
		(layers "F.Cu" "B.Cu")
		(net "PU_PIROM_CPU0_SM_WP")
	)
	(via
		(at 400.407378 -365.38535)
		(size 0.762)
		(drill 0.381)
		(layers "F.Cu" "B.Cu")
		(net "PU_PIROM_CPU0_SM_WP")
	)
	(segment
		(start 368.81435 -273.947636)
		(end 368.80546 -273.942556)
		(width 0.0889)
		(layer "In11.Cu")
		(net "PU_PIROM_CPU0_SM_WP")
	)
	(segment
		(start 368.81435 -277.203154)
		(end 368.80546 -277.198074)
		(width 0.0889)
		(layer "In11.Cu")
		(net "PU_PIROM_CPU0_SM_WP")
	)
	(segment
		(start 376.844052 -294.951658)
		(end 372.55069 -290.658296)
		(width 0.127)
		(layer "In11.Cu")
		(net "PU_PIROM_CPU0_SM_WP")
	)
	(segment
		(start 370.3828 -290.658296)
		(end 369.890548 -290.658296)
		(width 0.0889)
		(layer "In11.Cu")
		(net "PU_PIROM_CPU0_SM_WP")
	)
	(segment
		(start 369.462812 -278.346408)
		(end 369.462812 -278.327866)
		(width 0.0889)
		(layer "In11.Cu")
		(net "PU_PIROM_CPU0_SM_WP")
	)
	(segment
		(start 368.992912 -287.28924)
		(end 368.992912 -287.279334)
		(width 0.0889)
		(layer "In11.Cu")
		(net "PU_PIROM_CPU0_SM_WP")
	)
	(segment
		(start 368.992912 -277.536656)
		(end 368.992912 -277.522432)
		(width 0.0889)
		(layer "In11.Cu")
		(net "PU_PIROM_CPU0_SM_WP")
	)
	(segment
		(start 372.55069 -290.658296)
		(end 370.3828 -290.658296)
		(width 0.127)
		(layer "In11.Cu")
		(net "PU_PIROM_CPU0_SM_WP")
	)
	(segment
		(start 369.74526 -279.474676)
		(end 369.75415 -279.469596)
		(width 0.0889)
		(layer "In11.Cu")
		(net "PU_PIROM_CPU0_SM_WP")
	)
	(segment
		(start 376.844052 -298.355258)
		(end 376.844052 -294.951658)
		(width 0.127)
		(layer "In11.Cu")
		(net "PU_PIROM_CPU0_SM_WP")
	)
	(segment
		(start 368.80546 -276.219158)
		(end 368.81435 -276.214078)
		(width 0.0889)
		(layer "In11.Cu")
		(net "PU_PIROM_CPU0_SM_WP")
	)
	(segment
		(start 368.80546 -274.591272)
		(end 368.81435 -274.586192)
		(width 0.0889)
		(layer "In11.Cu")
		(net "PU_PIROM_CPU0_SM_WP")
	)
	(segment
		(start 369.75415 -285.342076)
		(end 369.74526 -285.336996)
		(width 0.0889)
		(layer "In11.Cu")
		(net "PU_PIROM_CPU0_SM_WP")
	)
	(segment
		(start 369.462812 -290.23056)
		(end 369.462812 -289.645852)
		(width 0.0889)
		(layer "In11.Cu")
		(net "PU_PIROM_CPU0_SM_WP")
	)
	(segment
		(start 369.462812 -286.475424)
		(end 369.462812 -286.4612)
		(width 0.0889)
		(layer "In11.Cu")
		(net "PU_PIROM_CPU0_SM_WP")
	)
	(segment
		(start 367.92408 -273.97202)
		(end 367.834926 -273.995896)
		(width 0.0889)
		(layer "In11.Cu")
		(net "PU_PIROM_CPU0_SM_WP")
	)
	(segment
		(start 367.834926 -273.995896)
		(end 367.678462 -274.266914)
		(width 0.0889)
		(layer "In11.Cu")
		(net "PU_PIROM_CPU0_SM_WP")
	)
	(segment
		(start 369.75415 -282.086558)
		(end 369.74526 -282.081478)
		(width 0.0889)
		(layer "In11.Cu")
		(net "PU_PIROM_CPU0_SM_WP")
	)
	(segment
		(start 368.799364 -287.617154)
		(end 368.80546 -287.613598)
		(width 0.0889)
		(layer "In11.Cu")
		(net "PU_PIROM_CPU0_SM_WP")
	)
	(segment
		(start 368.814604 -288.597848)
		(end 368.805714 -288.592768)
		(width 0.0889)
		(layer "In11.Cu")
		(net "PU_PIROM_CPU0_SM_WP")
	)
	(segment
		(start 368.523266 -276.72411)
		(end 368.523266 -276.693122)
		(width 0.0889)
		(layer "In11.Cu")
		(net "PU_PIROM_CPU0_SM_WP")
	)
	(segment
		(start 368.81435 -275.575522)
		(end 368.80546 -275.570442)
		(width 0.0889)
		(layer "In11.Cu")
		(net "PU_PIROM_CPU0_SM_WP")
	)
	(segment
		(start 368.993166 -289.114738)
		(end 368.993166 -288.917126)
		(width 0.0889)
		(layer "In11.Cu")
		(net "PU_PIROM_CPU0_SM_WP")
	)
	(segment
		(start 369.75415 -278.83104)
		(end 369.74526 -278.82596)
		(width 0.0889)
		(layer "In11.Cu")
		(net "PU_PIROM_CPU0_SM_WP")
	)
	(segment
		(start 368.431064 -273.942556)
		(end 368.416332 -273.951192)
		(width 0.0889)
		(layer "In11.Cu")
		(net "PU_PIROM_CPU0_SM_WP")
	)
	(segment
		(start 368.523012 -288.110676)
		(end 368.523012 -288.103056)
		(width 0.0889)
		(layer "In11.Cu")
		(net "PU_PIROM_CPU0_SM_WP")
	)
	(segment
		(start 394.517118 -316.028324)
		(end 376.844052 -298.355258)
		(width 0.127)
		(layer "In11.Cu")
		(net "PU_PIROM_CPU0_SM_WP")
	)
	(segment
		(start 369.463066 -279.986232)
		(end 369.463066 -279.94864)
		(width 0.0889)
		(layer "In11.Cu")
		(net "PU_PIROM_CPU0_SM_WP")
	)
	(segment
		(start 369.27536 -286.799782)
		(end 369.28425 -286.794702)
		(width 0.0889)
		(layer "In11.Cu")
		(net "PU_PIROM_CPU0_SM_WP")
	)
	(segment
		(start 369.462812 -283.229812)
		(end 369.462812 -283.201364)
		(width 0.0889)
		(layer "In11.Cu")
		(net "PU_PIROM_CPU0_SM_WP")
	)
	(segment
		(start 369.74526 -282.730194)
		(end 369.75415 -282.725114)
		(width 0.0889)
		(layer "In11.Cu")
		(net "PU_PIROM_CPU0_SM_WP")
	)
	(segment
		(start 369.74526 -284.35808)
		(end 369.75415 -284.353)
		(width 0.0889)
		(layer "In11.Cu")
		(net "PU_PIROM_CPU0_SM_WP")
	)
	(segment
		(start 394.517118 -353.16795)
		(end 394.517118 -316.028324)
		(width 0.127)
		(layer "In11.Cu")
		(net "PU_PIROM_CPU0_SM_WP")
	)
	(segment
		(start 384.468878 -363.21619)
		(end 394.517118 -353.16795)
		(width 0.127)
		(layer "In11.Cu")
		(net "PU_PIROM_CPU0_SM_WP")
	)
	(segment
		(start 369.75415 -280.458926)
		(end 369.74526 -280.453846)
		(width 0.0889)
		(layer "In11.Cu")
		(net "PU_PIROM_CPU0_SM_WP")
	)
	(segment
		(start 369.74526 -285.985712)
		(end 369.75415 -285.980632)
		(width 0.0889)
		(layer "In11.Cu")
		(net "PU_PIROM_CPU0_SM_WP")
	)
	(segment
		(start 368.80546 -287.613598)
		(end 368.81435 -287.608518)
		(width 0.0889)
		(layer "In11.Cu")
		(net "PU_PIROM_CPU0_SM_WP")
	)
	(segment
		(start 369.74526 -281.102562)
		(end 369.75415 -281.097482)
		(width 0.0889)
		(layer "In11.Cu")
		(net "PU_PIROM_CPU0_SM_WP")
	)
	(segment
		(start 369.463066 -281.607514)
		(end 369.463066 -281.576526)
		(width 0.0889)
		(layer "In11.Cu")
		(net "PU_PIROM_CPU0_SM_WP")
	)
	(segment
		(start 368.523266 -275.081492)
		(end 368.523266 -275.065236)
		(width 0.0889)
		(layer "In11.Cu")
		(net "PU_PIROM_CPU0_SM_WP")
	)
	(segment
		(start 369.890548 -290.658296)
		(end 369.462812 -290.23056)
		(width 0.0889)
		(layer "In11.Cu")
		(net "PU_PIROM_CPU0_SM_WP")
	)
	(segment
		(start 369.463066 -284.863032)
		(end 369.463066 -284.832044)
		(width 0.0889)
		(layer "In11.Cu")
		(net "PU_PIROM_CPU0_SM_WP")
	)
	(segment
		(start 369.75415 -283.714444)
		(end 369.74526 -283.709364)
		(width 0.0889)
		(layer "In11.Cu")
		(net "PU_PIROM_CPU0_SM_WP")
	)
	(arc
		(start 369.275614 -278.012144)
		(mid 369.072133 -277.81134)
		(end 368.992912 -277.536656)
		(width 0.0889)
		(layer "In11.Cu")
		(net "PU_PIROM_CPU0_SM_WP")
	)
	(arc
		(start 368.993166 -288.917126)
		(mid 368.945487 -288.734226)
		(end 368.814604 -288.597848)
		(width 0.0889)
		(layer "In11.Cu")
		(net "PU_PIROM_CPU0_SM_WP")
	)
	(arc
		(start 368.81435 -274.586192)
		(mid 368.992947 -274.266914)
		(end 368.81435 -273.947636)
		(width 0.0889)
		(layer "In11.Cu")
		(net "PU_PIROM_CPU0_SM_WP")
	)
	(arc
		(start 368.80546 -273.942556)
		(mid 368.618262 -273.892413)
		(end 368.431064 -273.942556)
		(width 0.0889)
		(layer "In11.Cu")
		(net "PU_PIROM_CPU0_SM_WP")
	)
	(arc
		(start 368.805714 -288.592768)
		(mid 368.600642 -288.389089)
		(end 368.523012 -288.110676)
		(width 0.0889)
		(layer "In11.Cu")
		(net "PU_PIROM_CPU0_SM_WP")
	)
	(arc
		(start 368.523266 -276.693122)
		(mid 368.602636 -276.419388)
		(end 368.80546 -276.219158)
		(width 0.0889)
		(layer "In11.Cu")
		(net "PU_PIROM_CPU0_SM_WP")
	)
	(arc
		(start 369.278662 -289.446462)
		(mid 369.10453 -289.307615)
		(end 368.993166 -289.114738)
		(width 0.0889)
		(layer "In11.Cu")
		(net "PU_PIROM_CPU0_SM_WP")
	)
	(arc
		(start 369.462812 -286.4612)
		(mid 369.541953 -286.186577)
		(end 369.74526 -285.985712)
		(width 0.0889)
		(layer "In11.Cu")
		(net "PU_PIROM_CPU0_SM_WP")
	)
	(arc
		(start 369.75415 -285.980632)
		(mid 369.932747 -285.661354)
		(end 369.75415 -285.342076)
		(width 0.0889)
		(layer "In11.Cu")
		(net "PU_PIROM_CPU0_SM_WP")
	)
	(arc
		(start 369.28425 -286.794702)
		(mid 369.415164 -286.658342)
		(end 369.462812 -286.475424)
		(width 0.0889)
		(layer "In11.Cu")
		(net "PU_PIROM_CPU0_SM_WP")
	)
	(arc
		(start 368.81435 -287.608518)
		(mid 368.945264 -287.472158)
		(end 368.992912 -287.28924)
		(width 0.0889)
		(layer "In11.Cu")
		(net "PU_PIROM_CPU0_SM_WP")
	)
	(arc
		(start 368.992912 -287.279334)
		(mid 369.071023 -287.002385)
		(end 369.27536 -286.799782)
		(width 0.0889)
		(layer "In11.Cu")
		(net "PU_PIROM_CPU0_SM_WP")
	)
	(arc
		(start 369.463066 -281.576526)
		(mid 369.542436 -281.302792)
		(end 369.74526 -281.102562)
		(width 0.0889)
		(layer "In11.Cu")
		(net "PU_PIROM_CPU0_SM_WP")
	)
	(arc
		(start 368.81435 -276.214078)
		(mid 368.992947 -275.8948)
		(end 368.81435 -275.575522)
		(width 0.0889)
		(layer "In11.Cu")
		(net "PU_PIROM_CPU0_SM_WP")
	)
	(arc
		(start 368.992912 -277.522432)
		(mid 368.945233 -277.339532)
		(end 368.81435 -277.203154)
		(width 0.0889)
		(layer "In11.Cu")
		(net "PU_PIROM_CPU0_SM_WP")
	)
	(arc
		(start 368.80546 -277.198074)
		(mid 368.602637 -276.997843)
		(end 368.523266 -276.72411)
		(width 0.0889)
		(layer "In11.Cu")
		(net "PU_PIROM_CPU0_SM_WP")
	)
	(arc
		(start 368.416332 -273.951192)
		(mid 368.172588 -274.018071)
		(end 367.92408 -273.97202)
		(width 0.0889)
		(layer "In11.Cu")
		(net "PU_PIROM_CPU0_SM_WP")
	)
	(arc
		(start 369.74526 -278.82596)
		(mid 369.540925 -278.623355)
		(end 369.462812 -278.346408)
		(width 0.0889)
		(layer "In11.Cu")
		(net "PU_PIROM_CPU0_SM_WP")
	)
	(arc
		(start 369.462812 -289.645852)
		(mid 369.387807 -289.530393)
		(end 369.278662 -289.446462)
		(width 0.0889)
		(layer "In11.Cu")
		(net "PU_PIROM_CPU0_SM_WP")
	)
	(arc
		(start 368.523012 -288.103056)
		(mid 368.596928 -287.823554)
		(end 368.799364 -287.617154)
		(width 0.0889)
		(layer "In11.Cu")
		(net "PU_PIROM_CPU0_SM_WP")
	)
	(arc
		(start 369.463066 -284.832044)
		(mid 369.542436 -284.55831)
		(end 369.74526 -284.35808)
		(width 0.0889)
		(layer "In11.Cu")
		(net "PU_PIROM_CPU0_SM_WP")
	)
	(arc
		(start 369.75415 -281.097482)
		(mid 369.932747 -280.778204)
		(end 369.75415 -280.458926)
		(width 0.0889)
		(layer "In11.Cu")
		(net "PU_PIROM_CPU0_SM_WP")
	)
	(arc
		(start 369.75415 -282.725114)
		(mid 369.932747 -282.405836)
		(end 369.75415 -282.086558)
		(width 0.0889)
		(layer "In11.Cu")
		(net "PU_PIROM_CPU0_SM_WP")
	)
	(arc
		(start 369.75415 -284.353)
		(mid 369.932747 -284.033722)
		(end 369.75415 -283.714444)
		(width 0.0889)
		(layer "In11.Cu")
		(net "PU_PIROM_CPU0_SM_WP")
	)
	(arc
		(start 369.74526 -280.453846)
		(mid 369.543978 -280.256359)
		(end 369.463066 -279.986232)
		(width 0.0889)
		(layer "In11.Cu")
		(net "PU_PIROM_CPU0_SM_WP")
	)
	(arc
		(start 369.462812 -278.327866)
		(mid 369.410542 -278.145501)
		(end 369.275614 -278.012144)
		(width 0.0889)
		(layer "In11.Cu")
		(net "PU_PIROM_CPU0_SM_WP")
	)
	(arc
		(start 369.74526 -283.709364)
		(mid 369.540925 -283.506759)
		(end 369.462812 -283.229812)
		(width 0.0889)
		(layer "In11.Cu")
		(net "PU_PIROM_CPU0_SM_WP")
	)
	(arc
		(start 368.523266 -275.065236)
		(mid 368.602636 -274.791502)
		(end 368.80546 -274.591272)
		(width 0.0889)
		(layer "In11.Cu")
		(net "PU_PIROM_CPU0_SM_WP")
	)
	(arc
		(start 369.463066 -279.94864)
		(mid 369.542436 -279.674906)
		(end 369.74526 -279.474676)
		(width 0.0889)
		(layer "In11.Cu")
		(net "PU_PIROM_CPU0_SM_WP")
	)
	(arc
		(start 369.74526 -285.336996)
		(mid 369.542437 -285.136765)
		(end 369.463066 -284.863032)
		(width 0.0889)
		(layer "In11.Cu")
		(net "PU_PIROM_CPU0_SM_WP")
	)
	(arc
		(start 368.80546 -275.570442)
		(mid 368.598859 -275.363768)
		(end 368.523266 -275.081492)
		(width 0.0889)
		(layer "In11.Cu")
		(net "PU_PIROM_CPU0_SM_WP")
	)
	(arc
		(start 369.74526 -282.081478)
		(mid 369.542437 -281.881247)
		(end 369.463066 -281.607514)
		(width 0.0889)
		(layer "In11.Cu")
		(net "PU_PIROM_CPU0_SM_WP")
	)
	(arc
		(start 369.462812 -283.201364)
		(mid 369.542974 -282.929175)
		(end 369.74526 -282.730194)
		(width 0.0889)
		(layer "In11.Cu")
		(net "PU_PIROM_CPU0_SM_WP")
	)
	(arc
		(start 369.75415 -279.469596)
		(mid 369.932747 -279.150318)
		(end 369.75415 -278.83104)
		(width 0.0889)
		(layer "In11.Cu")
		(net "PU_PIROM_CPU0_SM_WP")
	)
	(segment
		(start 309.15483 -50.491898)
		(end 309.15483 -49.494948)
		(width 0.12954)
		(layer "F.Cu")
		(net "PU_PCH_VRALERT_N")
	)
	(segment
		(start 315.854334 -49.444148)
		(end 313.57062 -49.444148)
		(width 0.12954)
		(layer "F.Cu")
		(net "PU_PCH_VRALERT_N")
	)
	(segment
		(start 320.028316 -49.799748)
		(end 319.74409 -49.515522)
		(width 0.12954)
		(layer "F.Cu")
		(net "PU_PCH_VRALERT_N")
	)
	(segment
		(start 313.57062 -49.444148)
		(end 313.01182 -48.885348)
		(width 0.12954)
		(layer "F.Cu")
		(net "PU_PCH_VRALERT_N")
	)
	(segment
		(start 310.254142 -50.764948)
		(end 309.42788 -50.764948)
		(width 0.12954)
		(layer "F.Cu")
		(net "PU_PCH_VRALERT_N")
	)
	(segment
		(start 311.51576 -49.774348)
		(end 311.244742 -49.774348)
		(width 0.12954)
		(layer "F.Cu")
		(net "PU_PCH_VRALERT_N")
	)
	(segment
		(start 326.3011 -49.196244)
		(end 325.365872 -49.196244)
		(width 0.0889)
		(layer "F.Cu")
		(net "PU_PCH_VRALERT_N")
	)
	(segment
		(start 322.840604 -49.712118)
		(end 322.663566 -49.712118)
		(width 0.12954)
		(layer "F.Cu")
		(net "PU_PCH_VRALERT_N")
	)
	(segment
		(start 326.406256 -49.227232)
		(end 326.3011 -49.196244)
		(width 0.0889)
		(layer "F.Cu")
		(net "PU_PCH_VRALERT_N")
	)
	(segment
		(start 322.575936 -49.799748)
		(end 320.028316 -49.799748)
		(width 0.12954)
		(layer "F.Cu")
		(net "PU_PCH_VRALERT_N")
	)
	(segment
		(start 322.663566 -49.712118)
		(end 322.575936 -49.799748)
		(width 0.12954)
		(layer "F.Cu")
		(net "PU_PCH_VRALERT_N")
	)
	(segment
		(start 319.74409 -49.515522)
		(end 315.925708 -49.515522)
		(width 0.12954)
		(layer "F.Cu")
		(net "PU_PCH_VRALERT_N")
	)
	(segment
		(start 313.01182 -48.885348)
		(end 312.40476 -48.885348)
		(width 0.12954)
		(layer "F.Cu")
		(net "PU_PCH_VRALERT_N")
	)
	(segment
		(start 327.133458 -48.950372)
		(end 326.718422 -49.227232)
		(width 0.0889)
		(layer "F.Cu")
		(net "PU_PCH_VRALERT_N")
	)
	(segment
		(start 327.41489 -48.950372)
		(end 327.133458 -48.950372)
		(width 0.0889)
		(layer "F.Cu")
		(net "PU_PCH_VRALERT_N")
	)
	(segment
		(start 326.718422 -49.227232)
		(end 326.406256 -49.227232)
		(width 0.0889)
		(layer "F.Cu")
		(net "PU_PCH_VRALERT_N")
	)
	(segment
		(start 312.40476 -48.885348)
		(end 311.51576 -49.774348)
		(width 0.12954)
		(layer "F.Cu")
		(net "PU_PCH_VRALERT_N")
	)
	(segment
		(start 309.42788 -50.764948)
		(end 309.15483 -50.491898)
		(width 0.12954)
		(layer "F.Cu")
		(net "PU_PCH_VRALERT_N")
	)
	(segment
		(start 311.244742 -49.774348)
		(end 310.254142 -50.764948)
		(width 0.12954)
		(layer "F.Cu")
		(net "PU_PCH_VRALERT_N")
	)
	(segment
		(start 325.365872 -49.196244)
		(end 324.849998 -49.712118)
		(width 0.0889)
		(layer "F.Cu")
		(net "PU_PCH_VRALERT_N")
	)
	(segment
		(start 315.925708 -49.515522)
		(end 315.854334 -49.444148)
		(width 0.12954)
		(layer "F.Cu")
		(net "PU_PCH_VRALERT_N")
	)
	(segment
		(start 324.849998 -49.712118)
		(end 322.840604 -49.712118)
		(width 0.0889)
		(layer "F.Cu")
		(net "PU_PCH_VRALERT_N")
	)
	(via
		(at 309.42788 -50.764948)
		(size 0.762)
		(drill 0.381)
		(layers "F.Cu" "B.Cu")
		(net "PU_PCH_VRALERT_N")
	)
	(segment
		(start 323.845936 -57.949084)
		(end 322.495672 -59.299348)
		(width 0.12954)
		(layer "F.Cu")
		(net "PU_PCH_PMCALERT_N")
	)
	(segment
		(start 327.829672 -55.453788)
		(end 327.446894 -55.453788)
		(width 0.0889)
		(layer "F.Cu")
		(net "PU_PCH_PMCALERT_N")
	)
	(segment
		(start 325.240904 -56.433466)
		(end 324.991222 -56.683148)
		(width 0.0889)
		(layer "F.Cu")
		(net "PU_PCH_PMCALERT_N")
	)
	(segment
		(start 324.991222 -56.683148)
		(end 324.771766 -56.683148)
		(width 0.0889)
		(layer "F.Cu")
		(net "PU_PCH_PMCALERT_N")
	)
	(segment
		(start 325.240904 -56.052466)
		(end 325.240904 -56.433466)
		(width 0.0889)
		(layer "F.Cu")
		(net "PU_PCH_PMCALERT_N")
	)
	(segment
		(start 327.829926 -55.453534)
		(end 327.829672 -55.453788)
		(width 0.0889)
		(layer "F.Cu")
		(net "PU_PCH_PMCALERT_N")
	)
	(segment
		(start 327.142856 -55.757826)
		(end 326.883014 -55.757826)
		(width 0.0889)
		(layer "F.Cu")
		(net "PU_PCH_PMCALERT_N")
	)
	(segment
		(start 326.744076 -55.66537)
		(end 325.628 -55.66537)
		(width 0.0889)
		(layer "F.Cu")
		(net "PU_PCH_PMCALERT_N")
	)
	(segment
		(start 324.123812 -57.331102)
		(end 323.845936 -57.608978)
		(width 0.12954)
		(layer "F.Cu")
		(net "PU_PCH_PMCALERT_N")
	)
	(segment
		(start 325.628 -55.66537)
		(end 325.240904 -56.052466)
		(width 0.0889)
		(layer "F.Cu")
		(net "PU_PCH_PMCALERT_N")
	)
	(segment
		(start 324.525894 -56.92902)
		(end 324.525894 -57.32399)
		(width 0.12954)
		(layer "F.Cu")
		(net "PU_PCH_PMCALERT_N")
	)
	(segment
		(start 326.883014 -55.757826)
		(end 326.744076 -55.66537)
		(width 0.0889)
		(layer "F.Cu")
		(net "PU_PCH_PMCALERT_N")
	)
	(segment
		(start 324.771766 -56.683148)
		(end 324.604126 -56.850788)
		(width 0.0889)
		(layer "F.Cu")
		(net "PU_PCH_PMCALERT_N")
	)
	(segment
		(start 324.525894 -57.32399)
		(end 324.518782 -57.331102)
		(width 0.12954)
		(layer "F.Cu")
		(net "PU_PCH_PMCALERT_N")
	)
	(segment
		(start 324.604126 -56.850788)
		(end 324.525894 -56.92902)
		(width 0.12954)
		(layer "F.Cu")
		(net "PU_PCH_PMCALERT_N")
	)
	(segment
		(start 323.845936 -57.608978)
		(end 323.845936 -57.949084)
		(width 0.12954)
		(layer "F.Cu")
		(net "PU_PCH_PMCALERT_N")
	)
	(segment
		(start 324.518782 -57.331102)
		(end 324.123812 -57.331102)
		(width 0.12954)
		(layer "F.Cu")
		(net "PU_PCH_PMCALERT_N")
	)
	(segment
		(start 327.446894 -55.453788)
		(end 327.142856 -55.757826)
		(width 0.0889)
		(layer "F.Cu")
		(net "PU_PCH_PMCALERT_N")
	)
	(via
		(at 324.525894 -57.32399)
		(size 0.508)
		(drill 0.254)
		(layers "F.Cu" "B.Cu")
		(net "PU_PCH_PMCALERT_N")
	)
	(segment
		(start 320.955162 -43.524424)
		(end 322.575174 -44.195492)
		(width 0.12954)
		(layer "F.Cu")
		(net "PU_PCH_PLD_3V3AUX_ALERT_N")
	)
	(segment
		(start 322.575174 -44.195492)
		(end 322.575682 -44.195746)
		(width 0.0889)
		(layer "F.Cu")
		(net "PU_PCH_PLD_3V3AUX_ALERT_N")
	)
	(segment
		(start 323.700648 -44.41952)
		(end 323.812662 -44.441872)
		(width 0.0889)
		(layer "F.Cu")
		(net "PU_PCH_PLD_3V3AUX_ALERT_N")
	)
	(segment
		(start 326.993504 -44.441872)
		(end 326.999854 -44.448222)
		(width 0.0889)
		(layer "F.Cu")
		(net "PU_PCH_PLD_3V3AUX_ALERT_N")
	)
	(segment
		(start 316.842902 -40.147748)
		(end 318.260222 -41.565068)
		(width 0.12954)
		(layer "F.Cu")
		(net "PU_PCH_PLD_3V3AUX_ALERT_N")
	)
	(segment
		(start 319.553336 -42.533062)
		(end 319.834768 -42.649648)
		(width 0.12954)
		(layer "F.Cu")
		(net "PU_PCH_PLD_3V3AUX_ALERT_N")
	)
	(segment
		(start 323.812662 -44.441872)
		(end 326.993504 -44.441872)
		(width 0.0889)
		(layer "F.Cu")
		(net "PU_PCH_PLD_3V3AUX_ALERT_N")
	)
	(segment
		(start 320.540126 -43.109388)
		(end 320.955162 -43.524424)
		(width 0.12954)
		(layer "F.Cu")
		(net "PU_PCH_PLD_3V3AUX_ALERT_N")
	)
	(segment
		(start 316.103 -40.147748)
		(end 316.842902 -40.147748)
		(width 0.12954)
		(layer "F.Cu")
		(net "PU_PCH_PLD_3V3AUX_ALERT_N")
	)
	(segment
		(start 318.260222 -41.565068)
		(end 318.585342 -41.565068)
		(width 0.12954)
		(layer "F.Cu")
		(net "PU_PCH_PLD_3V3AUX_ALERT_N")
	)
	(segment
		(start 318.585342 -41.565068)
		(end 319.553336 -42.533062)
		(width 0.12954)
		(layer "F.Cu")
		(net "PU_PCH_PLD_3V3AUX_ALERT_N")
	)
	(segment
		(start 322.575682 -44.195746)
		(end 323.700648 -44.41952)
		(width 0.0889)
		(layer "F.Cu")
		(net "PU_PCH_PLD_3V3AUX_ALERT_N")
	)
	(segment
		(start 315.8236 -39.868348)
		(end 316.103 -40.147748)
		(width 0.12954)
		(layer "F.Cu")
		(net "PU_PCH_PLD_3V3AUX_ALERT_N")
	)
	(segment
		(start 312.843672 -39.868348)
		(end 315.8236 -39.868348)
		(width 0.12954)
		(layer "F.Cu")
		(net "PU_PCH_PLD_3V3AUX_ALERT_N")
	)
	(segment
		(start 320.253868 -42.823384)
		(end 320.540126 -43.109388)
		(width 0.12954)
		(layer "F.Cu")
		(net "PU_PCH_PLD_3V3AUX_ALERT_N")
	)
	(segment
		(start 319.834768 -42.649648)
		(end 320.253868 -42.823384)
		(width 0.12954)
		(layer "F.Cu")
		(net "PU_PCH_PLD_3V3AUX_ALERT_N")
	)
	(via
		(at 320.540126 -43.109388)
		(size 0.762)
		(drill 0.381)
		(layers "F.Cu" "B.Cu")
		(net "PU_PCH_PLD_3V3AUX_ALERT_N")
	)
	(segment
		(start 465.906104 -48.940212)
		(end 466.27542 -48.940212)
		(width 0.12954)
		(layer "F.Cu")
		(net "PU_OCP_SFF_WAKE_OE")
	)
	(segment
		(start 464.84032 -47.874428)
		(end 465.906104 -48.940212)
		(width 0.12954)
		(layer "F.Cu")
		(net "PU_OCP_SFF_WAKE_OE")
	)
	(segment
		(start 463.285586 -46.319694)
		(end 464.84032 -47.874428)
		(width 0.12954)
		(layer "F.Cu")
		(net "PU_OCP_SFF_WAKE_OE")
	)
	(segment
		(start 463.06359 -46.319694)
		(end 463.285586 -46.319694)
		(width 0.12954)
		(layer "F.Cu")
		(net "PU_OCP_SFF_WAKE_OE")
	)
	(via
		(at 464.84032 -47.874428)
		(size 0.762)
		(drill 0.381)
		(layers "F.Cu" "B.Cu")
		(net "PU_OCP_SFF_WAKE_OE")
	)
	(segment
		(start 336.712814 -29.53893)
		(end 337.730084 -28.52166)
		(width 0.127)
		(layer "F.Cu")
		(net "PU_OC6_USB_N")
	)
	(segment
		(start 336.751422 -30.228794)
		(end 336.712814 -30.190186)
		(width 0.127)
		(layer "F.Cu")
		(net "PU_OC6_USB_N")
	)
	(segment
		(start 336.916014 -37.618924)
		(end 336.916014 -36.697412)
		(width 0.0889)
		(layer "F.Cu")
		(net "PU_OC6_USB_N")
	)
	(segment
		(start 336.712814 -30.190186)
		(end 336.712814 -29.53893)
		(width 0.127)
		(layer "F.Cu")
		(net "PU_OC6_USB_N")
	)
	(segment
		(start 336.899758 -37.63518)
		(end 336.916014 -37.618924)
		(width 0.0889)
		(layer "F.Cu")
		(net "PU_OC6_USB_N")
	)
	(segment
		(start 337.730084 -28.52166)
		(end 337.730084 -28.078176)
		(width 0.127)
		(layer "F.Cu")
		(net "PU_OC6_USB_N")
	)
	(segment
		(start 336.751422 -36.53282)
		(end 336.751422 -30.228794)
		(width 0.127)
		(layer "F.Cu")
		(net "PU_OC6_USB_N")
	)
	(segment
		(start 336.85353 -36.634928)
		(end 336.751422 -36.53282)
		(width 0.127)
		(layer "F.Cu")
		(net "PU_OC6_USB_N")
	)
	(segment
		(start 336.916014 -36.697412)
		(end 336.85353 -36.634928)
		(width 0.0889)
		(layer "F.Cu")
		(net "PU_OC6_USB_N")
	)
	(via
		(at 336.712814 -30.190186)
		(size 0.762)
		(drill 0.381)
		(layers "F.Cu" "B.Cu")
		(net "PU_OC6_USB_N")
	)
	(segment
		(start 338.368894 -32.675068)
		(end 338.368894 -32.417512)
		(width 0.127)
		(layer "F.Cu")
		(net "PU_OC5_USB_N")
	)
	(segment
		(start 338.422742 -29.866082)
		(end 339.483446 -28.805378)
		(width 0.127)
		(layer "F.Cu")
		(net "PU_OC5_USB_N")
	)
	(segment
		(start 339.483446 -28.805378)
		(end 339.483446 -28.32608)
		(width 0.127)
		(layer "F.Cu")
		(net "PU_OC5_USB_N")
	)
	(segment
		(start 338.224622 -32.27324)
		(end 338.224622 -31.816548)
		(width 0.127)
		(layer "F.Cu")
		(net "PU_OC5_USB_N")
	)
	(segment
		(start 338.422742 -31.021782)
		(end 338.422742 -29.866082)
		(width 0.127)
		(layer "F.Cu")
		(net "PU_OC5_USB_N")
	)
	(segment
		(start 337.900264 -37.63518)
		(end 337.900264 -36.207954)
		(width 0.0889)
		(layer "F.Cu")
		(net "PU_OC5_USB_N")
	)
	(segment
		(start 338.224622 -31.816548)
		(end 338.224622 -31.219902)
		(width 0.127)
		(layer "F.Cu")
		(net "PU_OC5_USB_N")
	)
	(segment
		(start 337.900264 -36.207954)
		(end 337.626706 -35.934396)
		(width 0.0889)
		(layer "F.Cu")
		(net "PU_OC5_USB_N")
	)
	(segment
		(start 338.224622 -31.219902)
		(end 338.422742 -31.021782)
		(width 0.127)
		(layer "F.Cu")
		(net "PU_OC5_USB_N")
	)
	(segment
		(start 338.368894 -32.79013)
		(end 338.368894 -32.675068)
		(width 0.0889)
		(layer "F.Cu")
		(net "PU_OC5_USB_N")
	)
	(segment
		(start 337.626706 -35.934396)
		(end 337.626706 -33.532318)
		(width 0.0889)
		(layer "F.Cu")
		(net "PU_OC5_USB_N")
	)
	(segment
		(start 338.368894 -32.417512)
		(end 338.224622 -32.27324)
		(width 0.127)
		(layer "F.Cu")
		(net "PU_OC5_USB_N")
	)
	(segment
		(start 337.626706 -33.532318)
		(end 338.368894 -32.79013)
		(width 0.0889)
		(layer "F.Cu")
		(net "PU_OC5_USB_N")
	)
	(via
		(at 338.224622 -31.816548)
		(size 0.762)
		(drill 0.381)
		(layers "F.Cu" "B.Cu")
		(net "PU_OC5_USB_N")
	)
	(segment
		(start 338.90077 -37.63518)
		(end 338.95538 -37.58057)
		(width 0.0889)
		(layer "F.Cu")
		(net "PU_OC4_USB_N")
	)
	(segment
		(start 341.651082 -24.617172)
		(end 341.101172 -25.167082)
		(width 0.127)
		(layer "F.Cu")
		(net "PU_OC4_USB_N")
	)
	(segment
		(start 338.95538 -37.58057)
		(end 338.95538 -36.506658)
		(width 0.0889)
		(layer "F.Cu")
		(net "PU_OC4_USB_N")
	)
	(segment
		(start 341.101172 -25.167082)
		(end 341.101172 -28.316682)
		(width 0.127)
		(layer "F.Cu")
		(net "PU_OC4_USB_N")
	)
	(segment
		(start 339.49005 -31.06928)
		(end 339.783674 -30.775656)
		(width 0.127)
		(layer "F.Cu")
		(net "PU_OC4_USB_N")
	)
	(segment
		(start 341.052658 -28.433776)
		(end 341.052658 -29.356812)
		(width 0.127)
		(layer "F.Cu")
		(net "PU_OC4_USB_N")
	)
	(segment
		(start 339.49005 -33.199578)
		(end 339.49005 -31.06928)
		(width 0.127)
		(layer "F.Cu")
		(net "PU_OC4_USB_N")
	)
	(segment
		(start 339.090508 -36.37153)
		(end 339.090508 -33.59912)
		(width 0.0889)
		(layer "F.Cu")
		(net "PU_OC4_USB_N")
	)
	(segment
		(start 339.889592 -30.519878)
		(end 339.783674 -30.775656)
		(width 0.127)
		(layer "F.Cu")
		(net "PU_OC4_USB_N")
	)
	(segment
		(start 341.052658 -29.356812)
		(end 339.889592 -30.519878)
		(width 0.127)
		(layer "F.Cu")
		(net "PU_OC4_USB_N")
	)
	(segment
		(start 341.101172 -28.316682)
		(end 341.052658 -28.433776)
		(width 0.127)
		(layer "F.Cu")
		(net "PU_OC4_USB_N")
	)
	(segment
		(start 338.95538 -36.506658)
		(end 339.090508 -36.37153)
		(width 0.0889)
		(layer "F.Cu")
		(net "PU_OC4_USB_N")
	)
	(segment
		(start 339.090508 -33.59912)
		(end 339.49005 -33.199578)
		(width 0.0889)
		(layer "F.Cu")
		(net "PU_OC4_USB_N")
	)
	(via
		(at 339.783674 -30.775656)
		(size 0.762)
		(drill 0.381)
		(layers "F.Cu" "B.Cu")
		(net "PU_OC4_USB_N")
	)
	(segment
		(start 341.099902 -32.147002)
		(end 341.441786 -31.805118)
		(width 0.0889)
		(layer "F.Cu")
		(net "PU_OC3_USB_N")
	)
	(segment
		(start 341.441786 -31.805118)
		(end 341.760556 -31.486348)
		(width 0.127)
		(layer "F.Cu")
		(net "PU_OC3_USB_N")
	)
	(segment
		(start 341.099902 -33.005268)
		(end 341.099902 -32.147002)
		(width 0.0889)
		(layer "F.Cu")
		(net "PU_OC3_USB_N")
	)
	(segment
		(start 342.158828 -30.630622)
		(end 342.482678 -30.306772)
		(width 0.127)
		(layer "F.Cu")
		(net "PU_OC3_USB_N")
	)
	(segment
		(start 341.760556 -31.028894)
		(end 342.158828 -30.630622)
		(width 0.127)
		(layer "F.Cu")
		(net "PU_OC3_USB_N")
	)
	(segment
		(start 342.53805 -28.585414)
		(end 342.803734 -28.31973)
		(width 0.127)
		(layer "F.Cu")
		(net "PU_OC3_USB_N")
	)
	(segment
		(start 341.760556 -31.486348)
		(end 341.760556 -31.028894)
		(width 0.127)
		(layer "F.Cu")
		(net "PU_OC3_USB_N")
	)
	(segment
		(start 339.901276 -34.203894)
		(end 341.099902 -33.005268)
		(width 0.0889)
		(layer "F.Cu")
		(net "PU_OC3_USB_N")
	)
	(segment
		(start 342.803734 -28.31973)
		(end 342.803734 -27.888438)
		(width 0.127)
		(layer "F.Cu")
		(net "PU_OC3_USB_N")
	)
	(segment
		(start 342.482678 -30.306772)
		(end 342.482678 -28.719272)
		(width 0.127)
		(layer "F.Cu")
		(net "PU_OC3_USB_N")
	)
	(segment
		(start 339.901276 -37.63518)
		(end 339.901276 -34.203894)
		(width 0.0889)
		(layer "F.Cu")
		(net "PU_OC3_USB_N")
	)
	(segment
		(start 342.482678 -28.719272)
		(end 342.53805 -28.585414)
		(width 0.127)
		(layer "F.Cu")
		(net "PU_OC3_USB_N")
	)
	(via
		(at 342.158828 -30.630622)
		(size 0.762)
		(drill 0.381)
		(layers "F.Cu" "B.Cu")
		(net "PU_OC3_USB_N")
	)
	(segment
		(start 169.917872 -119.776748)
		(end 170.554396 -119.776748)
		(width 0.12954)
		(layer "F.Cu")
		(net "PU_MAIN_FPGA_CONFIG_DONE")
	)
	(segment
		(start 166.57828 -120.056148)
		(end 166.763192 -120.24106)
		(width 0.12954)
		(layer "F.Cu")
		(net "PU_MAIN_FPGA_CONFIG_DONE")
	)
	(segment
		(start 169.45356 -120.24106)
		(end 169.917872 -119.776748)
		(width 0.12954)
		(layer "F.Cu")
		(net "PU_MAIN_FPGA_CONFIG_DONE")
	)
	(segment
		(start 170.554396 -119.776748)
		(end 170.955716 -119.375428)
		(width 0.12954)
		(layer "F.Cu")
		(net "PU_MAIN_FPGA_CONFIG_DONE")
	)
	(segment
		(start 165.25748 -121.376948)
		(end 165.04793 -121.376948)
		(width 0.12954)
		(layer "F.Cu")
		(net "PU_MAIN_FPGA_CONFIG_DONE")
	)
	(segment
		(start 166.57828 -120.056148)
		(end 165.25748 -121.376948)
		(width 0.12954)
		(layer "F.Cu")
		(net "PU_MAIN_FPGA_CONFIG_DONE")
	)
	(segment
		(start 166.763192 -120.24106)
		(end 169.45356 -120.24106)
		(width 0.12954)
		(layer "F.Cu")
		(net "PU_MAIN_FPGA_CONFIG_DONE")
	)
	(via
		(at 166.57828 -120.056148)
		(size 0.762)
		(drill 0.381)
		(layers "F.Cu" "B.Cu")
		(net "PU_MAIN_FPGA_CONFIG_DONE")
	)
	(segment
		(start 327.41489 -45.949108)
		(end 327.043542 -45.949108)
		(width 0.0889)
		(layer "F.Cu")
		(net "PU_LPC_PME_N")
	)
	(segment
		(start 314.98159 -43.719496)
		(end 314.69584 -43.433746)
		(width 0.12954)
		(layer "F.Cu")
		(net "PU_LPC_PME_N")
	)
	(segment
		(start 327.043542 -45.949108)
		(end 326.805798 -46.186852)
		(width 0.0889)
		(layer "F.Cu")
		(net "PU_LPC_PME_N")
	)
	(segment
		(start 323.492622 -45.583348)
		(end 323.180964 -45.895006)
		(width 0.0889)
		(layer "F.Cu")
		(net "PU_LPC_PME_N")
	)
	(segment
		(start 313.672728 -43.932348)
		(end 312.843672 -43.932348)
		(width 0.12954)
		(layer "F.Cu")
		(net "PU_LPC_PME_N")
	)
	(segment
		(start 318.562482 -44.94276)
		(end 318.562482 -44.820332)
		(width 0.12954)
		(layer "F.Cu")
		(net "PU_LPC_PME_N")
	)
	(segment
		(start 318.985392 -45.36567)
		(end 318.562482 -44.94276)
		(width 0.12954)
		(layer "F.Cu")
		(net "PU_LPC_PME_N")
	)
	(segment
		(start 314.17133 -43.433746)
		(end 313.672728 -43.932348)
		(width 0.12954)
		(layer "F.Cu")
		(net "PU_LPC_PME_N")
	)
	(segment
		(start 326.805798 -46.186852)
		(end 326.716136 -46.225714)
		(width 0.0889)
		(layer "F.Cu")
		(net "PU_LPC_PME_N")
	)
	(segment
		(start 317.461646 -43.719496)
		(end 314.98159 -43.719496)
		(width 0.12954)
		(layer "F.Cu")
		(net "PU_LPC_PME_N")
	)
	(segment
		(start 318.562482 -44.820332)
		(end 317.461646 -43.719496)
		(width 0.12954)
		(layer "F.Cu")
		(net "PU_LPC_PME_N")
	)
	(segment
		(start 325.074026 -45.583348)
		(end 323.492622 -45.583348)
		(width 0.0889)
		(layer "F.Cu")
		(net "PU_LPC_PME_N")
	)
	(segment
		(start 326.288654 -46.185836)
		(end 325.676514 -46.185836)
		(width 0.0889)
		(layer "F.Cu")
		(net "PU_LPC_PME_N")
	)
	(segment
		(start 325.676514 -46.185836)
		(end 325.074026 -45.583348)
		(width 0.0889)
		(layer "F.Cu")
		(net "PU_LPC_PME_N")
	)
	(segment
		(start 319.514728 -45.895006)
		(end 318.985392 -45.36567)
		(width 0.12954)
		(layer "F.Cu")
		(net "PU_LPC_PME_N")
	)
	(segment
		(start 322.575174 -45.895006)
		(end 319.514728 -45.895006)
		(width 0.12954)
		(layer "F.Cu")
		(net "PU_LPC_PME_N")
	)
	(segment
		(start 326.423782 -46.225714)
		(end 326.288654 -46.185836)
		(width 0.0889)
		(layer "F.Cu")
		(net "PU_LPC_PME_N")
	)
	(segment
		(start 314.69584 -43.433746)
		(end 314.17133 -43.433746)
		(width 0.12954)
		(layer "F.Cu")
		(net "PU_LPC_PME_N")
	)
	(segment
		(start 323.180964 -45.895006)
		(end 322.575174 -45.895006)
		(width 0.0889)
		(layer "F.Cu")
		(net "PU_LPC_PME_N")
	)
	(segment
		(start 326.716136 -46.225714)
		(end 326.423782 -46.225714)
		(width 0.0889)
		(layer "F.Cu")
		(net "PU_LPC_PME_N")
	)
	(via
		(at 318.985392 -45.36567)
		(size 0.762)
		(drill 0.381)
		(layers "F.Cu" "B.Cu")
		(net "PU_LPC_PME_N")
	)
	(segment
		(start 329.165966 -42.341546)
		(end 328.625708 -42.341546)
		(width 0.12954)
		(layer "F.Cu")
		(net "PU_LAN_WAKE_N")
	)
	(segment
		(start 309.122572 -39.106348)
		(end 308.46141 -39.106348)
		(width 0.12954)
		(layer "F.Cu")
		(net "PU_LAN_WAKE_N")
	)
	(via
		(at 308.46141 -39.106348)
		(size 0.508)
		(drill 0.254)
		(layers "F.Cu" "B.Cu")
		(net "PU_LAN_WAKE_N")
	)
	(via
		(at 328.625708 -42.341546)
		(size 0.4572)
		(drill 0.2032)
		(layers "F.Cu" "B.Cu")
		(net "PU_LAN_WAKE_N")
	)
	(segment
		(start 310.61279 -41.003728)
		(end 314.90158 -41.003728)
		(width 0.127)
		(layer "In6.Cu")
		(net "PU_LAN_WAKE_N")
	)
	(segment
		(start 314.90158 -41.003728)
		(end 315.1378 -41.239948)
		(width 0.127)
		(layer "In6.Cu")
		(net "PU_LAN_WAKE_N")
	)
	(segment
		(start 320.64452 -41.239948)
		(end 321.08902 -41.684448)
		(width 0.127)
		(layer "In6.Cu")
		(net "PU_LAN_WAKE_N")
	)
	(segment
		(start 321.08902 -41.684448)
		(end 327.96861 -41.684448)
		(width 0.127)
		(layer "In6.Cu")
		(net "PU_LAN_WAKE_N")
	)
	(segment
		(start 308.71541 -39.106348)
		(end 310.61279 -41.003728)
		(width 0.127)
		(layer "In6.Cu")
		(net "PU_LAN_WAKE_N")
	)
	(segment
		(start 308.46141 -39.106348)
		(end 308.71541 -39.106348)
		(width 0.127)
		(layer "In6.Cu")
		(net "PU_LAN_WAKE_N")
	)
	(segment
		(start 327.96861 -41.684448)
		(end 328.625708 -42.341546)
		(width 0.127)
		(layer "In6.Cu")
		(net "PU_LAN_WAKE_N")
	)
	(segment
		(start 315.1378 -41.239948)
		(end 320.64452 -41.239948)
		(width 0.127)
		(layer "In6.Cu")
		(net "PU_LAN_WAKE_N")
	)
	(segment
		(start 367.227358 -93.363034)
		(end 368.243358 -93.363034)
		(width 0.12954)
		(layer "F.Cu")
		(net "PU_GTL2014_BMC_JTAG_DIR_1")
	)
	(segment
		(start 368.243358 -93.363034)
		(end 368.243358 -94.243906)
		(width 0.12954)
		(layer "F.Cu")
		(net "PU_GTL2014_BMC_JTAG_DIR_1")
	)
	(segment
		(start 368.243358 -94.243906)
		(end 369.7224 -95.722948)
		(width 0.12954)
		(layer "F.Cu")
		(net "PU_GTL2014_BMC_JTAG_DIR_1")
	)
	(segment
		(start 369.7224 -95.722948)
		(end 369.7224 -96.264984)
		(width 0.12954)
		(layer "F.Cu")
		(net "PU_GTL2014_BMC_JTAG_DIR_1")
	)
	(via
		(at 368.243358 -94.243906)
		(size 0.508)
		(drill 0.254)
		(layers "F.Cu" "B.Cu")
		(net "PU_GTL2014_BMC_JTAG_DIR_1")
	)
	(segment
		(start 415.894774 -33.49371)
		(end 415.73196 -33.330896)
		(width 0.12954)
		(layer "F.Cu")
		(net "PU_FLASH_SECURITY_STRAP")
	)
	(segment
		(start 414.716468 -32.925258)
		(end 413.920432 -32.925258)
		(width 0.12954)
		(layer "F.Cu")
		(net "PU_FLASH_SECURITY_STRAP")
	)
	(segment
		(start 415.122106 -33.330896)
		(end 414.716468 -32.925258)
		(width 0.12954)
		(layer "F.Cu")
		(net "PU_FLASH_SECURITY_STRAP")
	)
	(segment
		(start 415.73196 -33.330896)
		(end 415.122106 -33.330896)
		(width 0.12954)
		(layer "F.Cu")
		(net "PU_FLASH_SECURITY_STRAP")
	)
	(segment
		(start 426.630084 -34.459926)
		(end 425.663868 -33.49371)
		(width 0.12954)
		(layer "F.Cu")
		(net "PU_FLASH_SECURITY_STRAP")
	)
	(segment
		(start 425.663868 -33.49371)
		(end 415.894774 -33.49371)
		(width 0.12954)
		(layer "F.Cu")
		(net "PU_FLASH_SECURITY_STRAP")
	)
	(via
		(at 415.122106 -33.330896)
		(size 0.762)
		(drill 0.381)
		(layers "F.Cu" "B.Cu")
		(net "PU_FLASH_SECURITY_STRAP")
	)
	(segment
		(start 433.25161 -43.600624)
		(end 433.58943 -43.262804)
		(width 0.12954)
		(layer "F.Cu")
		(net "PU_ESPI_ENABLE_STRAP")
	)
	(segment
		(start 433.58943 -43.262804)
		(end 434.77307 -43.262804)
		(width 0.12954)
		(layer "F.Cu")
		(net "PU_ESPI_ENABLE_STRAP")
	)
	(segment
		(start 432.9684 -43.600624)
		(end 433.25161 -43.600624)
		(width 0.12954)
		(layer "F.Cu")
		(net "PU_ESPI_ENABLE_STRAP")
	)
	(segment
		(start 427.649386 -43.600624)
		(end 432.9684 -43.600624)
		(width 0.12954)
		(layer "F.Cu")
		(net "PU_ESPI_ENABLE_STRAP")
	)
	(segment
		(start 426.630084 -44.619926)
		(end 427.649386 -43.600624)
		(width 0.12954)
		(layer "F.Cu")
		(net "PU_ESPI_ENABLE_STRAP")
	)
	(via
		(at 432.9684 -43.600624)
		(size 0.762)
		(drill 0.381)
		(layers "F.Cu" "B.Cu")
		(net "PU_ESPI_ENABLE_STRAP")
	)
	(segment
		(start 117.389148 -272.917412)
		(end 117.389148 -273.453098)
		(width 0.12954)
		(layer "F.Cu")
		(net "PU_CPU1_UPI3_AC_COUPLING")
	)
	(segment
		(start 117.388894 -272.917158)
		(end 117.389148 -272.917412)
		(width 0.12954)
		(layer "F.Cu")
		(net "PU_CPU1_UPI3_AC_COUPLING")
	)
	(via
		(at 117.389148 -273.453098)
		(size 0.4572)
		(drill 0.2032)
		(layers "F.Cu" "B.Cu")
		(net "PU_CPU1_UPI3_AC_COUPLING")
	)
	(via
		(at 154.928316 -266.093702)
		(size 0.6604)
		(drill 0.3302)
		(layers "F.Cu" "B.Cu")
		(net "PU_CPU1_UPI3_AC_COUPLING")
	)
	(segment
		(start 179.564538 -250.69165)
		(end 179.69484 -250.561348)
		(width 0.12954)
		(layer "B.Cu")
		(net "PU_CPU1_UPI3_AC_COUPLING")
	)
	(segment
		(start 114.367818 -268.885416)
		(end 114.38255 -268.894052)
		(width 0.0889)
		(layer "B.Cu")
		(net "PU_CPU1_UPI3_AC_COUPLING")
	)
	(segment
		(start 167.951404 -267.46581)
		(end 168.896538 -266.520676)
		(width 0.12954)
		(layer "B.Cu")
		(net "PU_CPU1_UPI3_AC_COUPLING")
	)
	(segment
		(start 179.250848 -252.0823)
		(end 179.250848 -251.41936)
		(width 0.12954)
		(layer "B.Cu")
		(net "PU_CPU1_UPI3_AC_COUPLING")
	)
	(segment
		(start 154.928316 -266.093702)
		(end 154.991308 -266.03071)
		(width 0.12954)
		(layer "B.Cu")
		(net "PU_CPU1_UPI3_AC_COUPLING")
	)
	(segment
		(start 134.492746 -267.266166)
		(end 134.498334 -267.262864)
		(width 0.0889)
		(layer "B.Cu")
		(net "PU_CPU1_UPI3_AC_COUPLING")
	)
	(segment
		(start 179.69484 -250.561348)
		(end 179.69484 -194.176904)
		(width 0.12954)
		(layer "B.Cu")
		(net "PU_CPU1_UPI3_AC_COUPLING")
	)
	(segment
		(start 164.342064 -267.46581)
		(end 167.951404 -267.46581)
		(width 0.12954)
		(layer "B.Cu")
		(net "PU_CPU1_UPI3_AC_COUPLING")
	)
	(segment
		(start 135.432546 -267.26642)
		(end 135.449818 -267.256514)
		(width 0.0889)
		(layer "B.Cu")
		(net "PU_CPU1_UPI3_AC_COUPLING")
	)
	(segment
		(start 170.317668 -256.729992)
		(end 173.275498 -255.26365)
		(width 0.12954)
		(layer "B.Cu")
		(net "PU_CPU1_UPI3_AC_COUPLING")
	)
	(segment
		(start 116.267992 -274.752816)
		(end 116.261896 -274.756372)
		(width 0.0889)
		(layer "B.Cu")
		(net "PU_CPU1_UPI3_AC_COUPLING")
	)
	(segment
		(start 161.370518 -267.25753)
		(end 164.133784 -267.25753)
		(width 0.12954)
		(layer "B.Cu")
		(net "PU_CPU1_UPI3_AC_COUPLING")
	)
	(segment
		(start 113.825782 -273.13382)
		(end 113.816892 -273.12874)
		(width 0.0889)
		(layer "B.Cu")
		(net "PU_CPU1_UPI3_AC_COUPLING")
	)
	(segment
		(start 130.733546 -267.266166)
		(end 130.748278 -267.25753)
		(width 0.0889)
		(layer "B.Cu")
		(net "PU_CPU1_UPI3_AC_COUPLING")
	)
	(segment
		(start 138.598656 -267.190474)
		(end 138.938254 -266.850876)
		(width 0.0889)
		(layer "B.Cu")
		(net "PU_CPU1_UPI3_AC_COUPLING")
	)
	(segment
		(start 179.564538 -251.10567)
		(end 179.564538 -250.69165)
		(width 0.12954)
		(layer "B.Cu")
		(net "PU_CPU1_UPI3_AC_COUPLING")
	)
	(segment
		(start 113.355882 -270.692118)
		(end 113.346992 -270.687038)
		(width 0.0889)
		(layer "B.Cu")
		(net "PU_CPU1_UPI3_AC_COUPLING")
	)
	(segment
		(start 121.890536 -267.26007)
		(end 121.90095 -267.266166)
		(width 0.0889)
		(layer "B.Cu")
		(net "PU_CPU1_UPI3_AC_COUPLING")
	)
	(segment
		(start 138.534394 -267.190474)
		(end 138.598656 -267.190474)
		(width 0.0889)
		(layer "B.Cu")
		(net "PU_CPU1_UPI3_AC_COUPLING")
	)
	(segment
		(start 154.991308 -266.03071)
		(end 158.165038 -266.03071)
		(width 0.12954)
		(layer "B.Cu")
		(net "PU_CPU1_UPI3_AC_COUPLING")
	)
	(segment
		(start 118.141242 -267.266166)
		(end 118.149624 -267.270992)
		(width 0.0889)
		(layer "B.Cu")
		(net "PU_CPU1_UPI3_AC_COUPLING")
	)
	(segment
		(start 116.261896 -274.756372)
		(end 116.251482 -274.762468)
		(width 0.0889)
		(layer "B.Cu")
		(net "PU_CPU1_UPI3_AC_COUPLING")
	)
	(segment
		(start 113.81105 -268.897608)
		(end 113.817146 -268.894052)
		(width 0.0889)
		(layer "B.Cu")
		(net "PU_CPU1_UPI3_AC_COUPLING")
	)
	(segment
		(start 133.552692 -267.266166)
		(end 133.563106 -267.26007)
		(width 0.0889)
		(layer "B.Cu")
		(net "PU_CPU1_UPI3_AC_COUPLING")
	)
	(segment
		(start 117.076474 -273.453098)
		(end 117.010942 -273.51863)
		(width 0.0889)
		(layer "B.Cu")
		(net "PU_CPU1_UPI3_AC_COUPLING")
	)
	(segment
		(start 138.938254 -266.850876)
		(end 139.24788 -266.54125)
		(width 0.12954)
		(layer "B.Cu")
		(net "PU_CPU1_UPI3_AC_COUPLING")
	)
	(segment
		(start 117.389148 -273.453098)
		(end 117.076474 -273.453098)
		(width 0.0889)
		(layer "B.Cu")
		(net "PU_CPU1_UPI3_AC_COUPLING")
	)
	(segment
		(start 114.771678 -274.765008)
		(end 114.756946 -274.756372)
		(width 0.0889)
		(layer "B.Cu")
		(net "PU_CPU1_UPI3_AC_COUPLING")
	)
	(segment
		(start 126.034292 -267.266166)
		(end 126.044706 -267.26007)
		(width 0.0889)
		(layer "B.Cu")
		(net "PU_CPU1_UPI3_AC_COUPLING")
	)
	(segment
		(start 128.853946 -267.266166)
		(end 128.868678 -267.25753)
		(width 0.0889)
		(layer "B.Cu")
		(net "PU_CPU1_UPI3_AC_COUPLING")
	)
	(segment
		(start 115.226592 -268.080236)
		(end 115.235482 -268.075156)
		(width 0.0889)
		(layer "B.Cu")
		(net "PU_CPU1_UPI3_AC_COUPLING")
	)
	(segment
		(start 113.346992 -269.707868)
		(end 113.361978 -269.699232)
		(width 0.0889)
		(layer "B.Cu")
		(net "PU_CPU1_UPI3_AC_COUPLING")
	)
	(segment
		(start 179.168552 -193.650616)
		(end 179.168552 -193.099944)
		(width 0.12954)
		(layer "B.Cu")
		(net "PU_CPU1_UPI3_AC_COUPLING")
	)
	(segment
		(start 139.24788 -266.54125)
		(end 154.480768 -266.54125)
		(width 0.12954)
		(layer "B.Cu")
		(net "PU_CPU1_UPI3_AC_COUPLING")
	)
	(segment
		(start 116.73205 -273.942556)
		(end 116.72316 -273.947636)
		(width 0.0889)
		(layer "B.Cu")
		(net "PU_CPU1_UPI3_AC_COUPLING")
	)
	(segment
		(start 125.094746 -267.266166)
		(end 125.10516 -267.26007)
		(width 0.0889)
		(layer "B.Cu")
		(net "PU_CPU1_UPI3_AC_COUPLING")
	)
	(segment
		(start 113.064544 -270.207486)
		(end 113.064544 -270.179038)
		(width 0.0889)
		(layer "B.Cu")
		(net "PU_CPU1_UPI3_AC_COUPLING")
	)
	(segment
		(start 179.69484 -194.176904)
		(end 179.168552 -193.650616)
		(width 0.12954)
		(layer "B.Cu")
		(net "PU_CPU1_UPI3_AC_COUPLING")
	)
	(segment
		(start 113.534444 -272.649188)
		(end 113.534444 -272.62074)
		(width 0.0889)
		(layer "B.Cu")
		(net "PU_CPU1_UPI3_AC_COUPLING")
	)
	(segment
		(start 114.944398 -268.569694)
		(end 114.944398 -268.5542)
		(width 0.0889)
		(layer "B.Cu")
		(net "PU_CPU1_UPI3_AC_COUPLING")
	)
	(segment
		(start 119.066564 -267.25753)
		(end 119.081296 -267.266166)
		(width 0.0889)
		(layer "B.Cu")
		(net "PU_CPU1_UPI3_AC_COUPLING")
	)
	(segment
		(start 113.816892 -272.14957)
		(end 113.825782 -272.14449)
		(width 0.0889)
		(layer "B.Cu")
		(net "PU_CPU1_UPI3_AC_COUPLING")
	)
	(segment
		(start 124.154946 -267.266166)
		(end 124.169678 -267.25753)
		(width 0.0889)
		(layer "B.Cu")
		(net "PU_CPU1_UPI3_AC_COUPLING")
	)
	(segment
		(start 113.816892 -273.777456)
		(end 113.825782 -273.772376)
		(width 0.0889)
		(layer "B.Cu")
		(net "PU_CPU1_UPI3_AC_COUPLING")
	)
	(segment
		(start 113.534444 -271.021302)
		(end 113.534444 -271.011396)
		(width 0.0889)
		(layer "B.Cu")
		(net "PU_CPU1_UPI3_AC_COUPLING")
	)
	(segment
		(start 168.896538 -258.151122)
		(end 170.317668 -256.729992)
		(width 0.12954)
		(layer "B.Cu")
		(net "PU_CPU1_UPI3_AC_COUPLING")
	)
	(segment
		(start 116.261642 -267.266166)
		(end 116.270024 -267.270992)
		(width 0.0889)
		(layer "B.Cu")
		(net "PU_CPU1_UPI3_AC_COUPLING")
	)
	(segment
		(start 120.950482 -267.26007)
		(end 120.960896 -267.266166)
		(width 0.0889)
		(layer "B.Cu")
		(net "PU_CPU1_UPI3_AC_COUPLING")
	)
	(segment
		(start 159.760158 -267.62583)
		(end 161.002218 -267.62583)
		(width 0.12954)
		(layer "B.Cu")
		(net "PU_CPU1_UPI3_AC_COUPLING")
	)
	(segment
		(start 122.275346 -267.266166)
		(end 122.290078 -267.25753)
		(width 0.0889)
		(layer "B.Cu")
		(net "PU_CPU1_UPI3_AC_COUPLING")
	)
	(segment
		(start 127.914146 -267.266166)
		(end 127.928878 -267.25753)
		(width 0.0889)
		(layer "B.Cu")
		(net "PU_CPU1_UPI3_AC_COUPLING")
	)
	(segment
		(start 115.414044 -267.755878)
		(end 115.414044 -267.741654)
		(width 0.0889)
		(layer "B.Cu")
		(net "PU_CPU1_UPI3_AC_COUPLING")
	)
	(segment
		(start 113.825782 -271.505934)
		(end 113.816892 -271.500854)
		(width 0.0889)
		(layer "B.Cu")
		(net "PU_CPU1_UPI3_AC_COUPLING")
	)
	(segment
		(start 161.002218 -267.62583)
		(end 161.370518 -267.25753)
		(width 0.12954)
		(layer "B.Cu")
		(net "PU_CPU1_UPI3_AC_COUPLING")
	)
	(segment
		(start 168.896538 -266.520676)
		(end 168.896538 -258.151122)
		(width 0.12954)
		(layer "B.Cu")
		(net "PU_CPU1_UPI3_AC_COUPLING")
	)
	(segment
		(start 179.250848 -251.41936)
		(end 179.564538 -251.10567)
		(width 0.12954)
		(layer "B.Cu")
		(net "PU_CPU1_UPI3_AC_COUPLING")
	)
	(segment
		(start 176.933352 -255.26365)
		(end 178.119278 -254.077724)
		(width 0.12954)
		(layer "B.Cu")
		(net "PU_CPU1_UPI3_AC_COUPLING")
	)
	(segment
		(start 117.191536 -267.26007)
		(end 117.20195 -267.266166)
		(width 0.0889)
		(layer "B.Cu")
		(net "PU_CPU1_UPI3_AC_COUPLING")
	)
	(segment
		(start 154.480768 -266.54125)
		(end 154.928316 -266.093702)
		(width 0.12954)
		(layer "B.Cu")
		(net "PU_CPU1_UPI3_AC_COUPLING")
	)
	(segment
		(start 164.133784 -267.25753)
		(end 164.342064 -267.46581)
		(width 0.12954)
		(layer "B.Cu")
		(net "PU_CPU1_UPI3_AC_COUPLING")
	)
	(segment
		(start 119.455692 -267.266166)
		(end 119.466106 -267.26007)
		(width 0.0889)
		(layer "B.Cu")
		(net "PU_CPU1_UPI3_AC_COUPLING")
	)
	(segment
		(start 113.827306 -274.762468)
		(end 113.816892 -274.756372)
		(width 0.0889)
		(layer "B.Cu")
		(net "PU_CPU1_UPI3_AC_COUPLING")
	)
	(segment
		(start 129.793746 -267.266166)
		(end 129.808478 -267.25753)
		(width 0.0889)
		(layer "B.Cu")
		(net "PU_CPU1_UPI3_AC_COUPLING")
	)
	(segment
		(start 173.275498 -255.26365)
		(end 176.933352 -255.26365)
		(width 0.12954)
		(layer "B.Cu")
		(net "PU_CPU1_UPI3_AC_COUPLING")
	)
	(segment
		(start 113.534444 -274.27682)
		(end 113.534444 -274.257008)
		(width 0.0889)
		(layer "B.Cu")
		(net "PU_CPU1_UPI3_AC_COUPLING")
	)
	(segment
		(start 126.974346 -267.266166)
		(end 126.989078 -267.25753)
		(width 0.0889)
		(layer "B.Cu")
		(net "PU_CPU1_UPI3_AC_COUPLING")
	)
	(segment
		(start 132.228082 -267.26007)
		(end 132.238496 -267.266166)
		(width 0.0889)
		(layer "B.Cu")
		(net "PU_CPU1_UPI3_AC_COUPLING")
	)
	(segment
		(start 114.756946 -268.894052)
		(end 114.765836 -268.888972)
		(width 0.0889)
		(layer "B.Cu")
		(net "PU_CPU1_UPI3_AC_COUPLING")
	)
	(segment
		(start 158.165038 -266.03071)
		(end 159.760158 -267.62583)
		(width 0.12954)
		(layer "B.Cu")
		(net "PU_CPU1_UPI3_AC_COUPLING")
	)
	(segment
		(start 123.215146 -267.266166)
		(end 123.229878 -267.25753)
		(width 0.0889)
		(layer "B.Cu")
		(net "PU_CPU1_UPI3_AC_COUPLING")
	)
	(segment
		(start 178.119278 -253.21387)
		(end 179.250848 -252.0823)
		(width 0.12954)
		(layer "B.Cu")
		(net "PU_CPU1_UPI3_AC_COUPLING")
	)
	(segment
		(start 178.119278 -254.077724)
		(end 178.119278 -253.21387)
		(width 0.12954)
		(layer "B.Cu")
		(net "PU_CPU1_UPI3_AC_COUPLING")
	)
	(arc
		(start 118.149624 -267.270992)
		(mid 118.333386 -267.316392)
		(end 118.515892 -267.266166)
		(width 0.0889)
		(layer "B.Cu")
		(net "PU_CPU1_UPI3_AC_COUPLING")
	)
	(arc
		(start 137.877296 -267.266166)
		(mid 138.064494 -267.316309)
		(end 138.251692 -267.266166)
		(width 0.0889)
		(layer "B.Cu")
		(net "PU_CPU1_UPI3_AC_COUPLING")
	)
	(arc
		(start 119.081296 -267.266166)
		(mid 119.268494 -267.316309)
		(end 119.455692 -267.266166)
		(width 0.0889)
		(layer "B.Cu")
		(net "PU_CPU1_UPI3_AC_COUPLING")
	)
	(arc
		(start 113.816892 -273.12874)
		(mid 113.612557 -272.926135)
		(end 113.534444 -272.649188)
		(width 0.0889)
		(layer "B.Cu")
		(net "PU_CPU1_UPI3_AC_COUPLING")
	)
	(arc
		(start 114.756946 -274.756372)
		(mid 114.569748 -274.706229)
		(end 114.38255 -274.756372)
		(width 0.0889)
		(layer "B.Cu")
		(net "PU_CPU1_UPI3_AC_COUPLING")
	)
	(arc
		(start 116.270024 -267.270992)
		(mid 116.453786 -267.316392)
		(end 116.636292 -267.266166)
		(width 0.0889)
		(layer "B.Cu")
		(net "PU_CPU1_UPI3_AC_COUPLING")
	)
	(arc
		(start 115.235482 -268.075156)
		(mid 115.366396 -267.938796)
		(end 115.414044 -267.755878)
		(width 0.0889)
		(layer "B.Cu")
		(net "PU_CPU1_UPI3_AC_COUPLING")
	)
	(arc
		(start 113.825782 -273.772376)
		(mid 114.004379 -273.453098)
		(end 113.825782 -273.13382)
		(width 0.0889)
		(layer "B.Cu")
		(net "PU_CPU1_UPI3_AC_COUPLING")
	)
	(arc
		(start 132.612892 -267.266166)
		(mid 132.895594 -267.190424)
		(end 133.178296 -267.266166)
		(width 0.0889)
		(layer "B.Cu")
		(net "PU_CPU1_UPI3_AC_COUPLING")
	)
	(arc
		(start 115.414044 -267.741654)
		(mid 115.493263 -267.466969)
		(end 115.696746 -267.266166)
		(width 0.0889)
		(layer "B.Cu")
		(net "PU_CPU1_UPI3_AC_COUPLING")
	)
	(arc
		(start 125.659896 -267.266166)
		(mid 125.847094 -267.316309)
		(end 126.034292 -267.266166)
		(width 0.0889)
		(layer "B.Cu")
		(net "PU_CPU1_UPI3_AC_COUPLING")
	)
	(arc
		(start 123.78055 -267.266166)
		(mid 123.967748 -267.316309)
		(end 124.154946 -267.266166)
		(width 0.0889)
		(layer "B.Cu")
		(net "PU_CPU1_UPI3_AC_COUPLING")
	)
	(arc
		(start 128.47955 -267.266166)
		(mid 128.666748 -267.316309)
		(end 128.853946 -267.266166)
		(width 0.0889)
		(layer "B.Cu")
		(net "PU_CPU1_UPI3_AC_COUPLING")
	)
	(arc
		(start 138.251692 -267.266166)
		(mid 138.388058 -267.209688)
		(end 138.534394 -267.190474)
		(width 0.0889)
		(layer "B.Cu")
		(net "PU_CPU1_UPI3_AC_COUPLING")
	)
	(arc
		(start 134.498334 -267.262864)
		(mid 134.778723 -267.190456)
		(end 135.05815 -267.26642)
		(width 0.0889)
		(layer "B.Cu")
		(net "PU_CPU1_UPI3_AC_COUPLING")
	)
	(arc
		(start 113.346992 -270.687038)
		(mid 113.142657 -270.484433)
		(end 113.064544 -270.207486)
		(width 0.0889)
		(layer "B.Cu")
		(net "PU_CPU1_UPI3_AC_COUPLING")
	)
	(arc
		(start 133.178296 -267.266166)
		(mid 133.365494 -267.316309)
		(end 133.552692 -267.266166)
		(width 0.0889)
		(layer "B.Cu")
		(net "PU_CPU1_UPI3_AC_COUPLING")
	)
	(arc
		(start 126.989078 -267.25753)
		(mid 127.265519 -267.190364)
		(end 127.53975 -267.266166)
		(width 0.0889)
		(layer "B.Cu")
		(net "PU_CPU1_UPI3_AC_COUPLING")
	)
	(arc
		(start 113.817146 -268.894052)
		(mid 114.091345 -268.818217)
		(end 114.367818 -268.885416)
		(width 0.0889)
		(layer "B.Cu")
		(net "PU_CPU1_UPI3_AC_COUPLING")
	)
	(arc
		(start 116.251482 -274.762468)
		(mid 115.973304 -274.832191)
		(end 115.696746 -274.756372)
		(width 0.0889)
		(layer "B.Cu")
		(net "PU_CPU1_UPI3_AC_COUPLING")
	)
	(arc
		(start 113.816892 -271.500854)
		(mid 113.612557 -271.298249)
		(end 113.534444 -271.021302)
		(width 0.0889)
		(layer "B.Cu")
		(net "PU_CPU1_UPI3_AC_COUPLING")
	)
	(arc
		(start 121.90095 -267.266166)
		(mid 122.088148 -267.316309)
		(end 122.275346 -267.266166)
		(width 0.0889)
		(layer "B.Cu")
		(net "PU_CPU1_UPI3_AC_COUPLING")
	)
	(arc
		(start 113.361978 -269.699232)
		(mid 113.488701 -269.563451)
		(end 113.534698 -269.38351)
		(width 0.0889)
		(layer "B.Cu")
		(net "PU_CPU1_UPI3_AC_COUPLING")
	)
	(arc
		(start 120.960896 -267.266166)
		(mid 121.148094 -267.316309)
		(end 121.335292 -267.266166)
		(width 0.0889)
		(layer "B.Cu")
		(net "PU_CPU1_UPI3_AC_COUPLING")
	)
	(arc
		(start 115.696746 -274.756372)
		(mid 115.509548 -274.706229)
		(end 115.32235 -274.756372)
		(width 0.0889)
		(layer "B.Cu")
		(net "PU_CPU1_UPI3_AC_COUPLING")
	)
	(arc
		(start 116.544598 -274.266914)
		(mid 116.470607 -274.54648)
		(end 116.267992 -274.752816)
		(width 0.0889)
		(layer "B.Cu")
		(net "PU_CPU1_UPI3_AC_COUPLING")
	)
	(arc
		(start 114.944398 -268.5542)
		(mid 115.023768 -268.280466)
		(end 115.226592 -268.080236)
		(width 0.0889)
		(layer "B.Cu")
		(net "PU_CPU1_UPI3_AC_COUPLING")
	)
	(arc
		(start 113.534444 -272.62074)
		(mid 113.614606 -272.348551)
		(end 113.816892 -272.14957)
		(width 0.0889)
		(layer "B.Cu")
		(net "PU_CPU1_UPI3_AC_COUPLING")
	)
	(arc
		(start 116.636292 -267.266166)
		(mid 116.913105 -267.19033)
		(end 117.191536 -267.26007)
		(width 0.0889)
		(layer "B.Cu")
		(net "PU_CPU1_UPI3_AC_COUPLING")
	)
	(arc
		(start 136.372092 -267.266166)
		(mid 136.654794 -267.190424)
		(end 136.937496 -267.266166)
		(width 0.0889)
		(layer "B.Cu")
		(net "PU_CPU1_UPI3_AC_COUPLING")
	)
	(arc
		(start 115.696746 -267.266166)
		(mid 115.979194 -267.190551)
		(end 116.261642 -267.266166)
		(width 0.0889)
		(layer "B.Cu")
		(net "PU_CPU1_UPI3_AC_COUPLING")
	)
	(arc
		(start 130.35915 -267.266166)
		(mid 130.546348 -267.316309)
		(end 130.733546 -267.266166)
		(width 0.0889)
		(layer "B.Cu")
		(net "PU_CPU1_UPI3_AC_COUPLING")
	)
	(arc
		(start 123.229878 -267.25753)
		(mid 123.506319 -267.190364)
		(end 123.78055 -267.266166)
		(width 0.0889)
		(layer "B.Cu")
		(net "PU_CPU1_UPI3_AC_COUPLING")
	)
	(arc
		(start 135.449818 -267.256514)
		(mid 135.724998 -267.190562)
		(end 135.997696 -267.266166)
		(width 0.0889)
		(layer "B.Cu")
		(net "PU_CPU1_UPI3_AC_COUPLING")
	)
	(arc
		(start 132.238496 -267.266166)
		(mid 132.425694 -267.316309)
		(end 132.612892 -267.266166)
		(width 0.0889)
		(layer "B.Cu")
		(net "PU_CPU1_UPI3_AC_COUPLING")
	)
	(arc
		(start 114.38255 -268.894052)
		(mid 114.569748 -268.944195)
		(end 114.756946 -268.894052)
		(width 0.0889)
		(layer "B.Cu")
		(net "PU_CPU1_UPI3_AC_COUPLING")
	)
	(arc
		(start 124.72035 -267.266166)
		(mid 124.907548 -267.316309)
		(end 125.094746 -267.266166)
		(width 0.0889)
		(layer "B.Cu")
		(net "PU_CPU1_UPI3_AC_COUPLING")
	)
	(arc
		(start 113.825782 -272.14449)
		(mid 114.004379 -271.825212)
		(end 113.825782 -271.505934)
		(width 0.0889)
		(layer "B.Cu")
		(net "PU_CPU1_UPI3_AC_COUPLING")
	)
	(arc
		(start 119.466106 -267.26007)
		(mid 119.744538 -267.190256)
		(end 120.02135 -267.266166)
		(width 0.0889)
		(layer "B.Cu")
		(net "PU_CPU1_UPI3_AC_COUPLING")
	)
	(arc
		(start 131.673346 -267.266166)
		(mid 131.949905 -267.190457)
		(end 132.228082 -267.26007)
		(width 0.0889)
		(layer "B.Cu")
		(net "PU_CPU1_UPI3_AC_COUPLING")
	)
	(arc
		(start 135.05815 -267.26642)
		(mid 135.245348 -267.316563)
		(end 135.432546 -267.26642)
		(width 0.0889)
		(layer "B.Cu")
		(net "PU_CPU1_UPI3_AC_COUPLING")
	)
	(arc
		(start 115.32235 -274.756372)
		(mid 115.048151 -274.832207)
		(end 114.771678 -274.765008)
		(width 0.0889)
		(layer "B.Cu")
		(net "PU_CPU1_UPI3_AC_COUPLING")
	)
	(arc
		(start 121.335292 -267.266166)
		(mid 121.612105 -267.19033)
		(end 121.890536 -267.26007)
		(width 0.0889)
		(layer "B.Cu")
		(net "PU_CPU1_UPI3_AC_COUPLING")
	)
	(arc
		(start 118.515892 -267.266166)
		(mid 118.790121 -267.190241)
		(end 119.066564 -267.25753)
		(width 0.0889)
		(layer "B.Cu")
		(net "PU_CPU1_UPI3_AC_COUPLING")
	)
	(arc
		(start 113.534444 -271.011396)
		(mid 113.486765 -270.828496)
		(end 113.355882 -270.692118)
		(width 0.0889)
		(layer "B.Cu")
		(net "PU_CPU1_UPI3_AC_COUPLING")
	)
	(arc
		(start 114.765836 -268.888972)
		(mid 114.89675 -268.752612)
		(end 114.944398 -268.569694)
		(width 0.0889)
		(layer "B.Cu")
		(net "PU_CPU1_UPI3_AC_COUPLING")
	)
	(arc
		(start 113.534444 -274.257008)
		(mid 113.612555 -273.980059)
		(end 113.816892 -273.777456)
		(width 0.0889)
		(layer "B.Cu")
		(net "PU_CPU1_UPI3_AC_COUPLING")
	)
	(arc
		(start 127.928878 -267.25753)
		(mid 128.205319 -267.190364)
		(end 128.47955 -267.266166)
		(width 0.0889)
		(layer "B.Cu")
		(net "PU_CPU1_UPI3_AC_COUPLING")
	)
	(arc
		(start 113.064544 -270.179038)
		(mid 113.144706 -269.906849)
		(end 113.346992 -269.707868)
		(width 0.0889)
		(layer "B.Cu")
		(net "PU_CPU1_UPI3_AC_COUPLING")
	)
	(arc
		(start 113.534698 -269.38351)
		(mid 113.608614 -269.104008)
		(end 113.81105 -268.897608)
		(width 0.0889)
		(layer "B.Cu")
		(net "PU_CPU1_UPI3_AC_COUPLING")
	)
	(arc
		(start 117.576346 -267.266166)
		(mid 117.858794 -267.190551)
		(end 118.141242 -267.266166)
		(width 0.0889)
		(layer "B.Cu")
		(net "PU_CPU1_UPI3_AC_COUPLING")
	)
	(arc
		(start 130.748278 -267.25753)
		(mid 131.024719 -267.190364)
		(end 131.29895 -267.266166)
		(width 0.0889)
		(layer "B.Cu")
		(net "PU_CPU1_UPI3_AC_COUPLING")
	)
	(arc
		(start 131.29895 -267.266166)
		(mid 131.486148 -267.316309)
		(end 131.673346 -267.266166)
		(width 0.0889)
		(layer "B.Cu")
		(net "PU_CPU1_UPI3_AC_COUPLING")
	)
	(arc
		(start 114.38255 -274.756372)
		(mid 114.105737 -274.832242)
		(end 113.827306 -274.762468)
		(width 0.0889)
		(layer "B.Cu")
		(net "PU_CPU1_UPI3_AC_COUPLING")
	)
	(arc
		(start 129.808478 -267.25753)
		(mid 130.084919 -267.190364)
		(end 130.35915 -267.266166)
		(width 0.0889)
		(layer "B.Cu")
		(net "PU_CPU1_UPI3_AC_COUPLING")
	)
	(arc
		(start 126.044706 -267.26007)
		(mid 126.323138 -267.190256)
		(end 126.59995 -267.266166)
		(width 0.0889)
		(layer "B.Cu")
		(net "PU_CPU1_UPI3_AC_COUPLING")
	)
	(arc
		(start 126.59995 -267.266166)
		(mid 126.787148 -267.316309)
		(end 126.974346 -267.266166)
		(width 0.0889)
		(layer "B.Cu")
		(net "PU_CPU1_UPI3_AC_COUPLING")
	)
	(arc
		(start 134.11835 -267.266166)
		(mid 134.305548 -267.316309)
		(end 134.492746 -267.266166)
		(width 0.0889)
		(layer "B.Cu")
		(net "PU_CPU1_UPI3_AC_COUPLING")
	)
	(arc
		(start 129.41935 -267.266166)
		(mid 129.606548 -267.316309)
		(end 129.793746 -267.266166)
		(width 0.0889)
		(layer "B.Cu")
		(net "PU_CPU1_UPI3_AC_COUPLING")
	)
	(arc
		(start 116.72316 -273.947636)
		(mid 116.592246 -274.083996)
		(end 116.544598 -274.266914)
		(width 0.0889)
		(layer "B.Cu")
		(net "PU_CPU1_UPI3_AC_COUPLING")
	)
	(arc
		(start 135.997696 -267.266166)
		(mid 136.184894 -267.316309)
		(end 136.372092 -267.266166)
		(width 0.0889)
		(layer "B.Cu")
		(net "PU_CPU1_UPI3_AC_COUPLING")
	)
	(arc
		(start 120.02135 -267.266166)
		(mid 120.208548 -267.316309)
		(end 120.395746 -267.266166)
		(width 0.0889)
		(layer "B.Cu")
		(net "PU_CPU1_UPI3_AC_COUPLING")
	)
	(arc
		(start 137.311892 -267.266166)
		(mid 137.594594 -267.190424)
		(end 137.877296 -267.266166)
		(width 0.0889)
		(layer "B.Cu")
		(net "PU_CPU1_UPI3_AC_COUPLING")
	)
	(arc
		(start 122.290078 -267.25753)
		(mid 122.566519 -267.190364)
		(end 122.84075 -267.266166)
		(width 0.0889)
		(layer "B.Cu")
		(net "PU_CPU1_UPI3_AC_COUPLING")
	)
	(arc
		(start 117.010942 -273.51863)
		(mid 116.921768 -273.763672)
		(end 116.73205 -273.942556)
		(width 0.0889)
		(layer "B.Cu")
		(net "PU_CPU1_UPI3_AC_COUPLING")
	)
	(arc
		(start 127.53975 -267.266166)
		(mid 127.726948 -267.316309)
		(end 127.914146 -267.266166)
		(width 0.0889)
		(layer "B.Cu")
		(net "PU_CPU1_UPI3_AC_COUPLING")
	)
	(arc
		(start 113.816892 -274.756372)
		(mid 113.612557 -274.553767)
		(end 113.534444 -274.27682)
		(width 0.0889)
		(layer "B.Cu")
		(net "PU_CPU1_UPI3_AC_COUPLING")
	)
	(arc
		(start 122.84075 -267.266166)
		(mid 123.027948 -267.316309)
		(end 123.215146 -267.266166)
		(width 0.0889)
		(layer "B.Cu")
		(net "PU_CPU1_UPI3_AC_COUPLING")
	)
	(arc
		(start 136.937496 -267.266166)
		(mid 137.124694 -267.316309)
		(end 137.311892 -267.266166)
		(width 0.0889)
		(layer "B.Cu")
		(net "PU_CPU1_UPI3_AC_COUPLING")
	)
	(arc
		(start 128.868678 -267.25753)
		(mid 129.145119 -267.190364)
		(end 129.41935 -267.266166)
		(width 0.0889)
		(layer "B.Cu")
		(net "PU_CPU1_UPI3_AC_COUPLING")
	)
	(arc
		(start 120.395746 -267.266166)
		(mid 120.672305 -267.190457)
		(end 120.950482 -267.26007)
		(width 0.0889)
		(layer "B.Cu")
		(net "PU_CPU1_UPI3_AC_COUPLING")
	)
	(arc
		(start 125.10516 -267.26007)
		(mid 125.383338 -267.190378)
		(end 125.659896 -267.266166)
		(width 0.0889)
		(layer "B.Cu")
		(net "PU_CPU1_UPI3_AC_COUPLING")
	)
	(arc
		(start 133.563106 -267.26007)
		(mid 133.841538 -267.190256)
		(end 134.11835 -267.266166)
		(width 0.0889)
		(layer "B.Cu")
		(net "PU_CPU1_UPI3_AC_COUPLING")
	)
	(arc
		(start 117.20195 -267.266166)
		(mid 117.389148 -267.316309)
		(end 117.576346 -267.266166)
		(width 0.0889)
		(layer "B.Cu")
		(net "PU_CPU1_UPI3_AC_COUPLING")
	)
	(arc
		(start 124.169678 -267.25753)
		(mid 124.446119 -267.190364)
		(end 124.72035 -267.266166)
		(width 0.0889)
		(layer "B.Cu")
		(net "PU_CPU1_UPI3_AC_COUPLING")
	)
	(segment
		(start 104.231694 -268.033754)
		(end 104.231948 -268.034008)
		(width 0.12954)
		(layer "F.Cu")
		(net "PU_CPU1_UPI2_AC_COUPLING")
	)
	(segment
		(start 104.231948 -268.034008)
		(end 104.231948 -268.569694)
		(width 0.12954)
		(layer "F.Cu")
		(net "PU_CPU1_UPI2_AC_COUPLING")
	)
	(via
		(at 71.566786 -256.555494)
		(size 0.6604)
		(drill 0.3302)
		(layers "F.Cu" "B.Cu")
		(net "PU_CPU1_UPI2_AC_COUPLING")
	)
	(via
		(at 104.231948 -268.569694)
		(size 0.4572)
		(drill 0.2032)
		(layers "F.Cu" "B.Cu")
		(net "PU_CPU1_UPI2_AC_COUPLING")
	)
	(segment
		(start 98.218498 -266.941808)
		(end 98.218498 -266.949428)
		(width 0.0889)
		(layer "B.Cu")
		(net "PU_CPU1_UPI2_AC_COUPLING")
	)
	(segment
		(start 100.674678 -266.626086)
		(end 100.659946 -266.61745)
		(width 0.0889)
		(layer "B.Cu")
		(net "PU_CPU1_UPI2_AC_COUPLING")
	)
	(segment
		(start 95.116396 -267.43152)
		(end 95.101664 -267.440156)
		(width 0.0889)
		(layer "B.Cu")
		(net "PU_CPU1_UPI2_AC_COUPLING")
	)
	(segment
		(start 98.40595 -266.61745)
		(end 98.40595 -266.617704)
		(width 0.0889)
		(layer "B.Cu")
		(net "PU_CPU1_UPI2_AC_COUPLING")
	)
	(segment
		(start 102.587044 -267.348716)
		(end 102.573582 -267.35659)
		(width 0.0889)
		(layer "B.Cu")
		(net "PU_CPU1_UPI2_AC_COUPLING")
	)
	(segment
		(start 72.84974 -261.347712)
		(end 72.84974 -259.899658)
		(width 0.12954)
		(layer "B.Cu")
		(net "PU_CPU1_UPI2_AC_COUPLING")
	)
	(segment
		(start 53.746908 -195.61048)
		(end 53.746908 -193.65976)
		(width 0.12954)
		(layer "B.Cu")
		(net "PU_CPU1_UPI2_AC_COUPLING")
	)
	(segment
		(start 92.296996 -267.43152)
		(end 92.282264 -267.440156)
		(width 0.0889)
		(layer "B.Cu")
		(net "PU_CPU1_UPI2_AC_COUPLING")
	)
	(segment
		(start 86.373208 -267.660374)
		(end 86.230968 -267.802614)
		(width 0.12954)
		(layer "B.Cu")
		(net "PU_CPU1_UPI2_AC_COUPLING")
	)
	(segment
		(start 62.404498 -245.85041)
		(end 61.462158 -245.85041)
		(width 0.12954)
		(layer "B.Cu")
		(net "PU_CPU1_UPI2_AC_COUPLING")
	)
	(segment
		(start 54.756558 -245.43385)
		(end 53.854858 -245.43385)
		(width 0.12954)
		(layer "B.Cu")
		(net "PU_CPU1_UPI2_AC_COUPLING")
	)
	(segment
		(start 96.99625 -267.43152)
		(end 96.985836 -267.437616)
		(width 0.0889)
		(layer "B.Cu")
		(net "PU_CPU1_UPI2_AC_COUPLING")
	)
	(segment
		(start 71.566786 -256.555494)
		(end 71.566786 -247.94464)
		(width 0.12954)
		(layer "B.Cu")
		(net "PU_CPU1_UPI2_AC_COUPLING")
	)
	(segment
		(start 53.555138 -241.09045)
		(end 51.581558 -239.11687)
		(width 0.12954)
		(layer "B.Cu")
		(net "PU_CPU1_UPI2_AC_COUPLING")
	)
	(segment
		(start 87.315294 -267.507212)
		(end 86.52637 -267.507212)
		(width 0.0889)
		(layer "B.Cu")
		(net "PU_CPU1_UPI2_AC_COUPLING")
	)
	(segment
		(start 52.808378 -196.54901)
		(end 53.746908 -195.61048)
		(width 0.12954)
		(layer "B.Cu")
		(net "PU_CPU1_UPI2_AC_COUPLING")
	)
	(segment
		(start 98.40595 -266.617704)
		(end 98.391726 -266.625832)
		(width 0.0889)
		(layer "B.Cu")
		(net "PU_CPU1_UPI2_AC_COUPLING")
	)
	(segment
		(start 71.566786 -258.616704)
		(end 71.566786 -256.555494)
		(width 0.12954)
		(layer "B.Cu")
		(net "PU_CPU1_UPI2_AC_COUPLING")
	)
	(segment
		(start 103.291894 -267.755878)
		(end 103.291894 -267.742416)
		(width 0.0889)
		(layer "B.Cu")
		(net "PU_CPU1_UPI2_AC_COUPLING")
	)
	(segment
		(start 60.054998 -244.44325)
		(end 59.066938 -244.44325)
		(width 0.12954)
		(layer "B.Cu")
		(net "PU_CPU1_UPI2_AC_COUPLING")
	)
	(segment
		(start 98.795078 -266.626086)
		(end 98.780346 -266.61745)
		(width 0.0889)
		(layer "B.Cu")
		(net "PU_CPU1_UPI2_AC_COUPLING")
	)
	(segment
		(start 69.980556 -246.35841)
		(end 62.912498 -246.35841)
		(width 0.12954)
		(layer "B.Cu")
		(net "PU_CPU1_UPI2_AC_COUPLING")
	)
	(segment
		(start 55.523638 -244.66677)
		(end 54.756558 -245.43385)
		(width 0.12954)
		(layer "B.Cu")
		(net "PU_CPU1_UPI2_AC_COUPLING")
	)
	(segment
		(start 52.808378 -197.47611)
		(end 52.808378 -196.54901)
		(width 0.12954)
		(layer "B.Cu")
		(net "PU_CPU1_UPI2_AC_COUPLING")
	)
	(segment
		(start 59.066938 -244.44325)
		(end 58.843418 -244.66677)
		(width 0.12954)
		(layer "B.Cu")
		(net "PU_CPU1_UPI2_AC_COUPLING")
	)
	(segment
		(start 96.056196 -267.43152)
		(end 96.041464 -267.440156)
		(width 0.0889)
		(layer "B.Cu")
		(net "PU_CPU1_UPI2_AC_COUPLING")
	)
	(segment
		(start 53.854858 -245.43385)
		(end 53.555138 -245.13413)
		(width 0.12954)
		(layer "B.Cu")
		(net "PU_CPU1_UPI2_AC_COUPLING")
	)
	(segment
		(start 58.843418 -244.66677)
		(end 55.523638 -244.66677)
		(width 0.12954)
		(layer "B.Cu")
		(net "PU_CPU1_UPI2_AC_COUPLING")
	)
	(segment
		(start 89.862406 -267.437616)
		(end 89.851992 -267.43152)
		(width 0.0889)
		(layer "B.Cu")
		(net "PU_CPU1_UPI2_AC_COUPLING")
	)
	(segment
		(start 93.236796 -267.43152)
		(end 93.222064 -267.440156)
		(width 0.0889)
		(layer "B.Cu")
		(net "PU_CPU1_UPI2_AC_COUPLING")
	)
	(segment
		(start 62.912498 -246.35841)
		(end 62.404498 -245.85041)
		(width 0.12954)
		(layer "B.Cu")
		(net "PU_CPU1_UPI2_AC_COUPLING")
	)
	(segment
		(start 71.566786 -247.94464)
		(end 69.980556 -246.35841)
		(width 0.12954)
		(layer "B.Cu")
		(net "PU_CPU1_UPI2_AC_COUPLING")
	)
	(segment
		(start 99.734878 -266.626086)
		(end 99.720146 -266.61745)
		(width 0.0889)
		(layer "B.Cu")
		(net "PU_CPU1_UPI2_AC_COUPLING")
	)
	(segment
		(start 72.84974 -259.899658)
		(end 71.566786 -258.616704)
		(width 0.12954)
		(layer "B.Cu")
		(net "PU_CPU1_UPI2_AC_COUPLING")
	)
	(segment
		(start 101.742748 -266.700254)
		(end 101.599746 -266.61745)
		(width 0.0889)
		(layer "B.Cu")
		(net "PU_CPU1_UPI2_AC_COUPLING")
	)
	(segment
		(start 51.581558 -198.70293)
		(end 52.808378 -197.47611)
		(width 0.12954)
		(layer "B.Cu")
		(net "PU_CPU1_UPI2_AC_COUPLING")
	)
	(segment
		(start 97.38106 -267.437616)
		(end 97.370646 -267.43152)
		(width 0.0889)
		(layer "B.Cu")
		(net "PU_CPU1_UPI2_AC_COUPLING")
	)
	(segment
		(start 51.581558 -239.11687)
		(end 51.581558 -198.70293)
		(width 0.12954)
		(layer "B.Cu")
		(net "PU_CPU1_UPI2_AC_COUPLING")
	)
	(segment
		(start 101.882448 -266.95146)
		(end 101.882448 -266.941808)
		(width 0.0889)
		(layer "B.Cu")
		(net "PU_CPU1_UPI2_AC_COUPLING")
	)
	(segment
		(start 86.230968 -267.802614)
		(end 79.304642 -267.802614)
		(width 0.12954)
		(layer "B.Cu")
		(net "PU_CPU1_UPI2_AC_COUPLING")
	)
	(segment
		(start 94.176596 -267.43152)
		(end 94.161864 -267.440156)
		(width 0.0889)
		(layer "B.Cu")
		(net "PU_CPU1_UPI2_AC_COUPLING")
	)
	(segment
		(start 61.462158 -245.85041)
		(end 60.054998 -244.44325)
		(width 0.12954)
		(layer "B.Cu")
		(net "PU_CPU1_UPI2_AC_COUPLING")
	)
	(segment
		(start 79.304642 -267.802614)
		(end 72.84974 -261.347712)
		(width 0.12954)
		(layer "B.Cu")
		(net "PU_CPU1_UPI2_AC_COUPLING")
	)
	(segment
		(start 53.555138 -245.13413)
		(end 53.555138 -241.09045)
		(width 0.12954)
		(layer "B.Cu")
		(net "PU_CPU1_UPI2_AC_COUPLING")
	)
	(segment
		(start 104.231948 -268.569694)
		(end 103.522018 -268.159992)
		(width 0.0889)
		(layer "B.Cu")
		(net "PU_CPU1_UPI2_AC_COUPLING")
	)
	(segment
		(start 90.80246 -267.437616)
		(end 90.792046 -267.43152)
		(width 0.0889)
		(layer "B.Cu")
		(net "PU_CPU1_UPI2_AC_COUPLING")
	)
	(segment
		(start 86.52637 -267.507212)
		(end 86.373208 -267.660374)
		(width 0.0889)
		(layer "B.Cu")
		(net "PU_CPU1_UPI2_AC_COUPLING")
	)
	(arc
		(start 89.851992 -267.43152)
		(mid 89.664794 -267.381377)
		(end 89.477596 -267.43152)
		(width 0.0889)
		(layer "B.Cu")
		(net "PU_CPU1_UPI2_AC_COUPLING")
	)
	(arc
		(start 92.282264 -267.440156)
		(mid 92.005823 -267.507322)
		(end 91.731592 -267.43152)
		(width 0.0889)
		(layer "B.Cu")
		(net "PU_CPU1_UPI2_AC_COUPLING")
	)
	(arc
		(start 99.720146 -266.61745)
		(mid 99.532948 -266.567307)
		(end 99.34575 -266.61745)
		(width 0.0889)
		(layer "B.Cu")
		(net "PU_CPU1_UPI2_AC_COUPLING")
	)
	(arc
		(start 102.573582 -267.35659)
		(mid 102.344329 -267.411834)
		(end 102.117144 -267.348716)
		(width 0.0889)
		(layer "B.Cu")
		(net "PU_CPU1_UPI2_AC_COUPLING")
	)
	(arc
		(start 97.935796 -267.43152)
		(mid 97.659237 -267.507229)
		(end 97.38106 -267.437616)
		(width 0.0889)
		(layer "B.Cu")
		(net "PU_CPU1_UPI2_AC_COUPLING")
	)
	(arc
		(start 91.357196 -267.43152)
		(mid 91.080637 -267.507229)
		(end 90.80246 -267.437616)
		(width 0.0889)
		(layer "B.Cu")
		(net "PU_CPU1_UPI2_AC_COUPLING")
	)
	(arc
		(start 87.972392 -267.43152)
		(mid 87.785194 -267.381377)
		(end 87.597996 -267.43152)
		(width 0.0889)
		(layer "B.Cu")
		(net "PU_CPU1_UPI2_AC_COUPLING")
	)
	(arc
		(start 101.599746 -266.61745)
		(mid 101.412548 -266.567307)
		(end 101.22535 -266.61745)
		(width 0.0889)
		(layer "B.Cu")
		(net "PU_CPU1_UPI2_AC_COUPLING")
	)
	(arc
		(start 88.912192 -267.43152)
		(mid 88.724994 -267.381377)
		(end 88.537796 -267.43152)
		(width 0.0889)
		(layer "B.Cu")
		(net "PU_CPU1_UPI2_AC_COUPLING")
	)
	(arc
		(start 89.477596 -267.43152)
		(mid 89.194894 -267.507262)
		(end 88.912192 -267.43152)
		(width 0.0889)
		(layer "B.Cu")
		(net "PU_CPU1_UPI2_AC_COUPLING")
	)
	(arc
		(start 93.611192 -267.43152)
		(mid 93.423994 -267.381377)
		(end 93.236796 -267.43152)
		(width 0.0889)
		(layer "B.Cu")
		(net "PU_CPU1_UPI2_AC_COUPLING")
	)
	(arc
		(start 93.222064 -267.440156)
		(mid 92.945623 -267.507322)
		(end 92.671392 -267.43152)
		(width 0.0889)
		(layer "B.Cu")
		(net "PU_CPU1_UPI2_AC_COUPLING")
	)
	(arc
		(start 98.391726 -266.625832)
		(mid 98.264683 -266.761648)
		(end 98.218498 -266.941808)
		(width 0.0889)
		(layer "B.Cu")
		(net "PU_CPU1_UPI2_AC_COUPLING")
	)
	(arc
		(start 102.117144 -267.348716)
		(mid 101.947694 -267.18087)
		(end 101.882448 -266.95146)
		(width 0.0889)
		(layer "B.Cu")
		(net "PU_CPU1_UPI2_AC_COUPLING")
	)
	(arc
		(start 92.671392 -267.43152)
		(mid 92.484194 -267.381377)
		(end 92.296996 -267.43152)
		(width 0.0889)
		(layer "B.Cu")
		(net "PU_CPU1_UPI2_AC_COUPLING")
	)
	(arc
		(start 88.537796 -267.43152)
		(mid 88.255094 -267.507262)
		(end 87.972392 -267.43152)
		(width 0.0889)
		(layer "B.Cu")
		(net "PU_CPU1_UPI2_AC_COUPLING")
	)
	(arc
		(start 95.101664 -267.440156)
		(mid 94.825223 -267.507322)
		(end 94.550992 -267.43152)
		(width 0.0889)
		(layer "B.Cu")
		(net "PU_CPU1_UPI2_AC_COUPLING")
	)
	(arc
		(start 90.792046 -267.43152)
		(mid 90.604848 -267.381377)
		(end 90.41765 -267.43152)
		(width 0.0889)
		(layer "B.Cu")
		(net "PU_CPU1_UPI2_AC_COUPLING")
	)
	(arc
		(start 97.370646 -267.43152)
		(mid 97.183448 -267.381377)
		(end 96.99625 -267.43152)
		(width 0.0889)
		(layer "B.Cu")
		(net "PU_CPU1_UPI2_AC_COUPLING")
	)
	(arc
		(start 87.597996 -267.43152)
		(mid 87.46163 -267.487998)
		(end 87.315294 -267.507212)
		(width 0.0889)
		(layer "B.Cu")
		(net "PU_CPU1_UPI2_AC_COUPLING")
	)
	(arc
		(start 94.161864 -267.440156)
		(mid 93.885423 -267.507322)
		(end 93.611192 -267.43152)
		(width 0.0889)
		(layer "B.Cu")
		(net "PU_CPU1_UPI2_AC_COUPLING")
	)
	(arc
		(start 94.550992 -267.43152)
		(mid 94.363794 -267.381377)
		(end 94.176596 -267.43152)
		(width 0.0889)
		(layer "B.Cu")
		(net "PU_CPU1_UPI2_AC_COUPLING")
	)
	(arc
		(start 98.780346 -266.61745)
		(mid 98.593148 -266.567307)
		(end 98.40595 -266.61745)
		(width 0.0889)
		(layer "B.Cu")
		(net "PU_CPU1_UPI2_AC_COUPLING")
	)
	(arc
		(start 95.490792 -267.43152)
		(mid 95.303594 -267.381377)
		(end 95.116396 -267.43152)
		(width 0.0889)
		(layer "B.Cu")
		(net "PU_CPU1_UPI2_AC_COUPLING")
	)
	(arc
		(start 90.41765 -267.43152)
		(mid 90.140837 -267.507356)
		(end 89.862406 -267.437616)
		(width 0.0889)
		(layer "B.Cu")
		(net "PU_CPU1_UPI2_AC_COUPLING")
	)
	(arc
		(start 103.291894 -267.742416)
		(mid 103.225671 -267.514979)
		(end 103.056944 -267.348716)
		(width 0.0889)
		(layer "B.Cu")
		(net "PU_CPU1_UPI2_AC_COUPLING")
	)
	(arc
		(start 96.985836 -267.437616)
		(mid 96.707404 -267.50743)
		(end 96.430592 -267.43152)
		(width 0.0889)
		(layer "B.Cu")
		(net "PU_CPU1_UPI2_AC_COUPLING")
	)
	(arc
		(start 101.22535 -266.61745)
		(mid 100.951151 -266.693285)
		(end 100.674678 -266.626086)
		(width 0.0889)
		(layer "B.Cu")
		(net "PU_CPU1_UPI2_AC_COUPLING")
	)
	(arc
		(start 91.731592 -267.43152)
		(mid 91.544394 -267.381377)
		(end 91.357196 -267.43152)
		(width 0.0889)
		(layer "B.Cu")
		(net "PU_CPU1_UPI2_AC_COUPLING")
	)
	(arc
		(start 100.659946 -266.61745)
		(mid 100.472748 -266.567307)
		(end 100.28555 -266.61745)
		(width 0.0889)
		(layer "B.Cu")
		(net "PU_CPU1_UPI2_AC_COUPLING")
	)
	(arc
		(start 103.522018 -268.159992)
		(mid 103.353462 -267.988398)
		(end 103.291894 -267.755878)
		(width 0.0889)
		(layer "B.Cu")
		(net "PU_CPU1_UPI2_AC_COUPLING")
	)
	(arc
		(start 98.218498 -266.949428)
		(mid 98.140869 -267.227841)
		(end 97.935796 -267.43152)
		(width 0.0889)
		(layer "B.Cu")
		(net "PU_CPU1_UPI2_AC_COUPLING")
	)
	(arc
		(start 100.28555 -266.61745)
		(mid 100.011351 -266.693285)
		(end 99.734878 -266.626086)
		(width 0.0889)
		(layer "B.Cu")
		(net "PU_CPU1_UPI2_AC_COUPLING")
	)
	(arc
		(start 96.430592 -267.43152)
		(mid 96.243394 -267.381377)
		(end 96.056196 -267.43152)
		(width 0.0889)
		(layer "B.Cu")
		(net "PU_CPU1_UPI2_AC_COUPLING")
	)
	(arc
		(start 103.056944 -267.348716)
		(mid 102.821994 -267.28579)
		(end 102.587044 -267.348716)
		(width 0.0889)
		(layer "B.Cu")
		(net "PU_CPU1_UPI2_AC_COUPLING")
	)
	(arc
		(start 99.34575 -266.61745)
		(mid 99.071551 -266.693285)
		(end 98.795078 -266.626086)
		(width 0.0889)
		(layer "B.Cu")
		(net "PU_CPU1_UPI2_AC_COUPLING")
	)
	(arc
		(start 96.041464 -267.440156)
		(mid 95.765023 -267.507322)
		(end 95.490792 -267.43152)
		(width 0.0889)
		(layer "B.Cu")
		(net "PU_CPU1_UPI2_AC_COUPLING")
	)
	(arc
		(start 101.882448 -266.941808)
		(mid 101.844951 -266.802318)
		(end 101.742748 -266.700254)
		(width 0.0889)
		(layer "B.Cu")
		(net "PU_CPU1_UPI2_AC_COUPLING")
	)
	(segment
		(start 121.508012 -228.994716)
		(end 121.508012 -228.45903)
		(width 0.12954)
		(layer "F.Cu")
		(net "PU_CPU1_UPI1_AC_COUPLING")
	)
	(segment
		(start 121.508266 -228.99497)
		(end 121.508012 -228.994716)
		(width 0.12954)
		(layer "F.Cu")
		(net "PU_CPU1_UPI1_AC_COUPLING")
	)
	(via
		(at 121.508012 -228.45903)
		(size 0.4572)
		(drill 0.2032)
		(layers "F.Cu" "B.Cu")
		(net "PU_CPU1_UPI1_AC_COUPLING")
	)
	(via
		(at 147.611338 -223.537018)
		(size 0.6604)
		(drill 0.3302)
		(layers "F.Cu" "B.Cu")
		(net "PU_CPU1_UPI1_AC_COUPLING")
	)
	(segment
		(start 136.810242 -228.724206)
		(end 136.935718 -228.59873)
		(width 0.0889)
		(layer "B.Cu")
		(net "PU_CPU1_UPI1_AC_COUPLING")
	)
	(segment
		(start 137.794238 -228.59873)
		(end 138.234674 -228.158294)
		(width 0.12954)
		(layer "B.Cu")
		(net "PU_CPU1_UPI1_AC_COUPLING")
	)
	(segment
		(start 124.125482 -228.774752)
		(end 124.140214 -228.783388)
		(width 0.0889)
		(layer "B.Cu")
		(net "PU_CPU1_UPI1_AC_COUPLING")
	)
	(segment
		(start 128.824482 -228.774752)
		(end 128.839214 -228.783388)
		(width 0.0889)
		(layer "B.Cu")
		(net "PU_CPU1_UPI1_AC_COUPLING")
	)
	(segment
		(start 132.588254 -228.777292)
		(end 132.598668 -228.783388)
		(width 0.0889)
		(layer "B.Cu")
		(net "PU_CPU1_UPI1_AC_COUPLING")
	)
	(segment
		(start 151.266398 -219.881958)
		(end 151.266398 -197.276212)
		(width 0.12954)
		(layer "B.Cu")
		(net "PU_CPU1_UPI1_AC_COUPLING")
	)
	(segment
		(start 130.704082 -228.774752)
		(end 130.718814 -228.783388)
		(width 0.0889)
		(layer "B.Cu")
		(net "PU_CPU1_UPI1_AC_COUPLING")
	)
	(segment
		(start 125.065282 -228.774752)
		(end 125.080014 -228.783388)
		(width 0.0889)
		(layer "B.Cu")
		(net "PU_CPU1_UPI1_AC_COUPLING")
	)
	(segment
		(start 142.990062 -228.158294)
		(end 147.611338 -223.537018)
		(width 0.12954)
		(layer "B.Cu")
		(net "PU_CPU1_UPI1_AC_COUPLING")
	)
	(segment
		(start 136.935718 -228.59873)
		(end 137.273538 -228.59873)
		(width 0.0889)
		(layer "B.Cu")
		(net "PU_CPU1_UPI1_AC_COUPLING")
	)
	(segment
		(start 126.009654 -228.777292)
		(end 126.020068 -228.783388)
		(width 0.0889)
		(layer "B.Cu")
		(net "PU_CPU1_UPI1_AC_COUPLING")
	)
	(segment
		(start 121.508012 -228.45903)
		(end 121.664476 -228.730048)
		(width 0.0889)
		(layer "B.Cu")
		(net "PU_CPU1_UPI1_AC_COUPLING")
	)
	(segment
		(start 138.234674 -228.158294)
		(end 142.990062 -228.158294)
		(width 0.12954)
		(layer "B.Cu")
		(net "PU_CPU1_UPI1_AC_COUPLING")
	)
	(segment
		(start 121.664476 -228.730048)
		(end 121.75363 -228.753924)
		(width 0.0889)
		(layer "B.Cu")
		(net "PU_CPU1_UPI1_AC_COUPLING")
	)
	(segment
		(start 126.9492 -228.777292)
		(end 126.959614 -228.783388)
		(width 0.0889)
		(layer "B.Cu")
		(net "PU_CPU1_UPI1_AC_COUPLING")
	)
	(segment
		(start 137.273538 -228.59873)
		(end 137.794238 -228.59873)
		(width 0.12954)
		(layer "B.Cu")
		(net "PU_CPU1_UPI1_AC_COUPLING")
	)
	(segment
		(start 131.643882 -228.774752)
		(end 131.658614 -228.783388)
		(width 0.0889)
		(layer "B.Cu")
		(net "PU_CPU1_UPI1_AC_COUPLING")
	)
	(segment
		(start 122.245882 -228.774752)
		(end 122.260614 -228.783388)
		(width 0.0889)
		(layer "B.Cu")
		(net "PU_CPU1_UPI1_AC_COUPLING")
	)
	(segment
		(start 155.1305 -190.00597)
		(end 155.38704 -189.74943)
		(width 0.12954)
		(layer "B.Cu")
		(net "PU_CPU1_UPI1_AC_COUPLING")
	)
	(segment
		(start 151.266398 -197.276212)
		(end 155.1305 -193.41211)
		(width 0.12954)
		(layer "B.Cu")
		(net "PU_CPU1_UPI1_AC_COUPLING")
	)
	(segment
		(start 147.611338 -223.537018)
		(end 151.266398 -219.881958)
		(width 0.12954)
		(layer "B.Cu")
		(net "PU_CPU1_UPI1_AC_COUPLING")
	)
	(segment
		(start 135.407654 -228.777292)
		(end 135.418068 -228.783388)
		(width 0.0889)
		(layer "B.Cu")
		(net "PU_CPU1_UPI1_AC_COUPLING")
	)
	(segment
		(start 134.4676 -228.777292)
		(end 134.478014 -228.783388)
		(width 0.0889)
		(layer "B.Cu")
		(net "PU_CPU1_UPI1_AC_COUPLING")
	)
	(segment
		(start 155.1305 -193.41211)
		(end 155.1305 -190.00597)
		(width 0.12954)
		(layer "B.Cu")
		(net "PU_CPU1_UPI1_AC_COUPLING")
	)
	(segment
		(start 127.884682 -228.774752)
		(end 127.899414 -228.783388)
		(width 0.0889)
		(layer "B.Cu")
		(net "PU_CPU1_UPI1_AC_COUPLING")
	)
	(arc
		(start 133.912864 -228.783388)
		(mid 134.189423 -228.707645)
		(end 134.4676 -228.777292)
		(width 0.0889)
		(layer "B.Cu")
		(net "PU_CPU1_UPI1_AC_COUPLING")
	)
	(arc
		(start 136.732264 -228.783388)
		(mid 136.773194 -228.756355)
		(end 136.810242 -228.724206)
		(width 0.0889)
		(layer "B.Cu")
		(net "PU_CPU1_UPI1_AC_COUPLING")
	)
	(arc
		(start 132.598668 -228.783388)
		(mid 132.785866 -228.833531)
		(end 132.973064 -228.783388)
		(width 0.0889)
		(layer "B.Cu")
		(net "PU_CPU1_UPI1_AC_COUPLING")
	)
	(arc
		(start 135.792464 -228.783388)
		(mid 136.075166 -228.707612)
		(end 136.357868 -228.783388)
		(width 0.0889)
		(layer "B.Cu")
		(net "PU_CPU1_UPI1_AC_COUPLING")
	)
	(arc
		(start 124.140214 -228.783388)
		(mid 124.327412 -228.833531)
		(end 124.51461 -228.783388)
		(width 0.0889)
		(layer "B.Cu")
		(net "PU_CPU1_UPI1_AC_COUPLING")
	)
	(arc
		(start 128.839214 -228.783388)
		(mid 129.026412 -228.833531)
		(end 129.21361 -228.783388)
		(width 0.0889)
		(layer "B.Cu")
		(net "PU_CPU1_UPI1_AC_COUPLING")
	)
	(arc
		(start 130.718814 -228.783388)
		(mid 130.906012 -228.833531)
		(end 131.09321 -228.783388)
		(width 0.0889)
		(layer "B.Cu")
		(net "PU_CPU1_UPI1_AC_COUPLING")
	)
	(arc
		(start 133.538468 -228.783388)
		(mid 133.725666 -228.833531)
		(end 133.912864 -228.783388)
		(width 0.0889)
		(layer "B.Cu")
		(net "PU_CPU1_UPI1_AC_COUPLING")
	)
	(arc
		(start 130.15341 -228.783388)
		(mid 130.427609 -228.707553)
		(end 130.704082 -228.774752)
		(width 0.0889)
		(layer "B.Cu")
		(net "PU_CPU1_UPI1_AC_COUPLING")
	)
	(arc
		(start 121.75363 -228.753924)
		(mid 122.002135 -228.707937)
		(end 122.245882 -228.774752)
		(width 0.0889)
		(layer "B.Cu")
		(net "PU_CPU1_UPI1_AC_COUPLING")
	)
	(arc
		(start 136.357868 -228.783388)
		(mid 136.545066 -228.833531)
		(end 136.732264 -228.783388)
		(width 0.0889)
		(layer "B.Cu")
		(net "PU_CPU1_UPI1_AC_COUPLING")
	)
	(arc
		(start 125.45441 -228.783388)
		(mid 125.731223 -228.707518)
		(end 126.009654 -228.777292)
		(width 0.0889)
		(layer "B.Cu")
		(net "PU_CPU1_UPI1_AC_COUPLING")
	)
	(arc
		(start 123.200414 -228.783388)
		(mid 123.387612 -228.833531)
		(end 123.57481 -228.783388)
		(width 0.0889)
		(layer "B.Cu")
		(net "PU_CPU1_UPI1_AC_COUPLING")
	)
	(arc
		(start 125.080014 -228.783388)
		(mid 125.267212 -228.833531)
		(end 125.45441 -228.783388)
		(width 0.0889)
		(layer "B.Cu")
		(net "PU_CPU1_UPI1_AC_COUPLING")
	)
	(arc
		(start 127.33401 -228.783388)
		(mid 127.608209 -228.707553)
		(end 127.884682 -228.774752)
		(width 0.0889)
		(layer "B.Cu")
		(net "PU_CPU1_UPI1_AC_COUPLING")
	)
	(arc
		(start 131.658614 -228.783388)
		(mid 131.845812 -228.833531)
		(end 132.03301 -228.783388)
		(width 0.0889)
		(layer "B.Cu")
		(net "PU_CPU1_UPI1_AC_COUPLING")
	)
	(arc
		(start 135.418068 -228.783388)
		(mid 135.605266 -228.833531)
		(end 135.792464 -228.783388)
		(width 0.0889)
		(layer "B.Cu")
		(net "PU_CPU1_UPI1_AC_COUPLING")
	)
	(arc
		(start 131.09321 -228.783388)
		(mid 131.367409 -228.707553)
		(end 131.643882 -228.774752)
		(width 0.0889)
		(layer "B.Cu")
		(net "PU_CPU1_UPI1_AC_COUPLING")
	)
	(arc
		(start 129.779014 -228.783388)
		(mid 129.966212 -228.833531)
		(end 130.15341 -228.783388)
		(width 0.0889)
		(layer "B.Cu")
		(net "PU_CPU1_UPI1_AC_COUPLING")
	)
	(arc
		(start 122.260614 -228.783388)
		(mid 122.447812 -228.833531)
		(end 122.63501 -228.783388)
		(width 0.0889)
		(layer "B.Cu")
		(net "PU_CPU1_UPI1_AC_COUPLING")
	)
	(arc
		(start 134.85241 -228.783388)
		(mid 135.129223 -228.707518)
		(end 135.407654 -228.777292)
		(width 0.0889)
		(layer "B.Cu")
		(net "PU_CPU1_UPI1_AC_COUPLING")
	)
	(arc
		(start 129.21361 -228.783388)
		(mid 129.496312 -228.707612)
		(end 129.779014 -228.783388)
		(width 0.0889)
		(layer "B.Cu")
		(net "PU_CPU1_UPI1_AC_COUPLING")
	)
	(arc
		(start 123.57481 -228.783388)
		(mid 123.849009 -228.707553)
		(end 124.125482 -228.774752)
		(width 0.0889)
		(layer "B.Cu")
		(net "PU_CPU1_UPI1_AC_COUPLING")
	)
	(arc
		(start 122.63501 -228.783388)
		(mid 122.917712 -228.707612)
		(end 123.200414 -228.783388)
		(width 0.0889)
		(layer "B.Cu")
		(net "PU_CPU1_UPI1_AC_COUPLING")
	)
	(arc
		(start 126.020068 -228.783388)
		(mid 126.207266 -228.833531)
		(end 126.394464 -228.783388)
		(width 0.0889)
		(layer "B.Cu")
		(net "PU_CPU1_UPI1_AC_COUPLING")
	)
	(arc
		(start 127.899414 -228.783388)
		(mid 128.086612 -228.833531)
		(end 128.27381 -228.783388)
		(width 0.0889)
		(layer "B.Cu")
		(net "PU_CPU1_UPI1_AC_COUPLING")
	)
	(arc
		(start 132.03301 -228.783388)
		(mid 132.309823 -228.707518)
		(end 132.588254 -228.777292)
		(width 0.0889)
		(layer "B.Cu")
		(net "PU_CPU1_UPI1_AC_COUPLING")
	)
	(arc
		(start 128.27381 -228.783388)
		(mid 128.548009 -228.707553)
		(end 128.824482 -228.774752)
		(width 0.0889)
		(layer "B.Cu")
		(net "PU_CPU1_UPI1_AC_COUPLING")
	)
	(arc
		(start 132.973064 -228.783388)
		(mid 133.255766 -228.707612)
		(end 133.538468 -228.783388)
		(width 0.0889)
		(layer "B.Cu")
		(net "PU_CPU1_UPI1_AC_COUPLING")
	)
	(arc
		(start 126.959614 -228.783388)
		(mid 127.146812 -228.833531)
		(end 127.33401 -228.783388)
		(width 0.0889)
		(layer "B.Cu")
		(net "PU_CPU1_UPI1_AC_COUPLING")
	)
	(arc
		(start 134.478014 -228.783388)
		(mid 134.665212 -228.833531)
		(end 134.85241 -228.783388)
		(width 0.0889)
		(layer "B.Cu")
		(net "PU_CPU1_UPI1_AC_COUPLING")
	)
	(arc
		(start 124.51461 -228.783388)
		(mid 124.788809 -228.707553)
		(end 125.065282 -228.774752)
		(width 0.0889)
		(layer "B.Cu")
		(net "PU_CPU1_UPI1_AC_COUPLING")
	)
	(arc
		(start 126.394464 -228.783388)
		(mid 126.671023 -228.707645)
		(end 126.9492 -228.777292)
		(width 0.0889)
		(layer "B.Cu")
		(net "PU_CPU1_UPI1_AC_COUPLING")
	)
	(segment
		(start 103.652066 -232.250488)
		(end 103.652066 -231.714802)
		(width 0.12954)
		(layer "F.Cu")
		(net "PU_CPU1_UPI0_AC_COUPLING")
	)
	(segment
		(start 103.652066 -231.714802)
		(end 103.651812 -231.714548)
		(width 0.12954)
		(layer "F.Cu")
		(net "PU_CPU1_UPI0_AC_COUPLING")
	)
	(via
		(at 77.871066 -188.152786)
		(size 0.6604)
		(drill 0.3302)
		(layers "F.Cu" "B.Cu")
		(net "PU_CPU1_UPI0_AC_COUPLING")
	)
	(via
		(at 103.651812 -231.714548)
		(size 0.4572)
		(drill 0.2032)
		(layers "F.Cu" "B.Cu")
		(net "PU_CPU1_UPI0_AC_COUPLING")
	)
	(via
		(at 78.916276 -228.04374)
		(size 0.6604)
		(drill 0.3302)
		(layers "F.Cu" "B.Cu")
		(net "PU_CPU1_UPI0_AC_COUPLING")
	)
	(segment
		(start 74.856848 -223.984312)
		(end 74.856848 -204.119734)
		(width 0.12954)
		(layer "B.Cu")
		(net "PU_CPU1_UPI0_AC_COUPLING")
	)
	(segment
		(start 77.871066 -188.152786)
		(end 77.368908 -186.940698)
		(width 0.12954)
		(layer "B.Cu")
		(net "PU_CPU1_UPI0_AC_COUPLING")
	)
	(segment
		(start 102.617016 -230.922576)
		(end 102.617016 -230.900478)
		(width 0.0889)
		(layer "B.Cu")
		(net "PU_CPU1_UPI0_AC_COUPLING")
	)
	(segment
		(start 103.495348 -231.44353)
		(end 103.406448 -231.419908)
		(width 0.0889)
		(layer "B.Cu")
		(net "PU_CPU1_UPI0_AC_COUPLING")
	)
	(segment
		(start 83.699858 -230.013256)
		(end 83.488784 -230.22433)
		(width 0.12954)
		(layer "B.Cu")
		(net "PU_CPU1_UPI0_AC_COUPLING")
	)
	(segment
		(start 95.946214 -229.762304)
		(end 95.931482 -229.77094)
		(width 0.0889)
		(layer "B.Cu")
		(net "PU_CPU1_UPI0_AC_COUPLING")
	)
	(segment
		(start 102.438454 -230.5812)
		(end 102.429564 -230.57612)
		(width 0.0889)
		(layer "B.Cu")
		(net "PU_CPU1_UPI0_AC_COUPLING")
	)
	(segment
		(start 90.307668 -229.762304)
		(end 90.297254 -229.7684)
		(width 0.0889)
		(layer "B.Cu")
		(net "PU_CPU1_UPI0_AC_COUPLING")
	)
	(segment
		(start 102.429564 -230.57612)
		(end 102.423468 -230.572564)
		(width 0.0889)
		(layer "B.Cu")
		(net "PU_CPU1_UPI0_AC_COUPLING")
	)
	(segment
		(start 78.916276 -228.04374)
		(end 74.856848 -223.984312)
		(width 0.12954)
		(layer "B.Cu")
		(net "PU_CPU1_UPI0_AC_COUPLING")
	)
	(segment
		(start 98.765614 -229.762304)
		(end 98.750882 -229.77094)
		(width 0.0889)
		(layer "B.Cu")
		(net "PU_CPU1_UPI0_AC_COUPLING")
	)
	(segment
		(start 81.096866 -230.22433)
		(end 78.916276 -228.04374)
		(width 0.12954)
		(layer "B.Cu")
		(net "PU_CPU1_UPI0_AC_COUPLING")
	)
	(segment
		(start 89.367614 -229.762304)
		(end 89.352882 -229.77094)
		(width 0.0889)
		(layer "B.Cu")
		(net "PU_CPU1_UPI0_AC_COUPLING")
	)
	(segment
		(start 100.645214 -229.762304)
		(end 100.630482 -229.77094)
		(width 0.0889)
		(layer "B.Cu")
		(net "PU_CPU1_UPI0_AC_COUPLING")
	)
	(segment
		(start 85.743034 -230.013256)
		(end 83.699858 -230.013256)
		(width 0.12954)
		(layer "B.Cu")
		(net "PU_CPU1_UPI0_AC_COUPLING")
	)
	(segment
		(start 101.9683 -229.767384)
		(end 101.95941 -229.762304)
		(width 0.0889)
		(layer "B.Cu")
		(net "PU_CPU1_UPI0_AC_COUPLING")
	)
	(segment
		(start 83.488784 -230.22433)
		(end 81.096866 -230.22433)
		(width 0.12954)
		(layer "B.Cu")
		(net "PU_CPU1_UPI0_AC_COUPLING")
	)
	(segment
		(start 91.247214 -229.762304)
		(end 91.2368 -229.7684)
		(width 0.0889)
		(layer "B.Cu")
		(net "PU_CPU1_UPI0_AC_COUPLING")
	)
	(segment
		(start 103.651812 -231.714548)
		(end 103.495348 -231.44353)
		(width 0.0889)
		(layer "B.Cu")
		(net "PU_CPU1_UPI0_AC_COUPLING")
	)
	(segment
		(start 77.368908 -186.940698)
		(end 77.368908 -186.326526)
		(width 0.12954)
		(layer "B.Cu")
		(net "PU_CPU1_UPI0_AC_COUPLING")
	)
	(segment
		(start 76.981558 -201.995024)
		(end 76.981558 -196.863716)
		(width 0.12954)
		(layer "B.Cu")
		(net "PU_CPU1_UPI0_AC_COUPLING")
	)
	(segment
		(start 78.387702 -189.40018)
		(end 77.871066 -188.152786)
		(width 0.12954)
		(layer "B.Cu")
		(net "PU_CPU1_UPI0_AC_COUPLING")
	)
	(segment
		(start 86.133686 -229.622604)
		(end 85.743034 -230.013256)
		(width 0.0889)
		(layer "B.Cu")
		(net "PU_CPU1_UPI0_AC_COUPLING")
	)
	(segment
		(start 76.981558 -196.863716)
		(end 78.387702 -195.457572)
		(width 0.12954)
		(layer "B.Cu")
		(net "PU_CPU1_UPI0_AC_COUPLING")
	)
	(segment
		(start 97.825814 -229.762304)
		(end 97.8154 -229.7684)
		(width 0.0889)
		(layer "B.Cu")
		(net "PU_CPU1_UPI0_AC_COUPLING")
	)
	(segment
		(start 88.145366 -229.837996)
		(end 87.750396 -229.837996)
		(width 0.0889)
		(layer "B.Cu")
		(net "PU_CPU1_UPI0_AC_COUPLING")
	)
	(segment
		(start 87.750396 -229.837996)
		(end 87.535004 -229.622604)
		(width 0.0889)
		(layer "B.Cu")
		(net "PU_CPU1_UPI0_AC_COUPLING")
	)
	(segment
		(start 94.066614 -229.762304)
		(end 94.051882 -229.77094)
		(width 0.0889)
		(layer "B.Cu")
		(net "PU_CPU1_UPI0_AC_COUPLING")
	)
	(segment
		(start 93.126814 -229.762304)
		(end 93.112082 -229.77094)
		(width 0.0889)
		(layer "B.Cu")
		(net "PU_CPU1_UPI0_AC_COUPLING")
	)
	(segment
		(start 92.187014 -229.762304)
		(end 92.172282 -229.77094)
		(width 0.0889)
		(layer "B.Cu")
		(net "PU_CPU1_UPI0_AC_COUPLING")
	)
	(segment
		(start 96.886268 -229.762304)
		(end 96.875854 -229.7684)
		(width 0.0889)
		(layer "B.Cu")
		(net "PU_CPU1_UPI0_AC_COUPLING")
	)
	(segment
		(start 99.705414 -229.762304)
		(end 99.690682 -229.77094)
		(width 0.0889)
		(layer "B.Cu")
		(net "PU_CPU1_UPI0_AC_COUPLING")
	)
	(segment
		(start 87.535004 -229.622604)
		(end 86.133686 -229.622604)
		(width 0.0889)
		(layer "B.Cu")
		(net "PU_CPU1_UPI0_AC_COUPLING")
	)
	(segment
		(start 78.387702 -195.457572)
		(end 78.387702 -189.40018)
		(width 0.12954)
		(layer "B.Cu")
		(net "PU_CPU1_UPI0_AC_COUPLING")
	)
	(segment
		(start 74.856848 -204.119734)
		(end 76.981558 -201.995024)
		(width 0.12954)
		(layer "B.Cu")
		(net "PU_CPU1_UPI0_AC_COUPLING")
	)
	(arc
		(start 100.630482 -229.77094)
		(mid 100.354007 -229.83826)
		(end 100.07981 -229.762304)
		(width 0.0889)
		(layer "B.Cu")
		(net "PU_CPU1_UPI0_AC_COUPLING")
	)
	(arc
		(start 102.146862 -230.086662)
		(mid 102.099183 -229.903762)
		(end 101.9683 -229.767384)
		(width 0.0889)
		(layer "B.Cu")
		(net "PU_CPU1_UPI0_AC_COUPLING")
	)
	(arc
		(start 100.07981 -229.762304)
		(mid 99.892612 -229.712161)
		(end 99.705414 -229.762304)
		(width 0.0889)
		(layer "B.Cu")
		(net "PU_CPU1_UPI0_AC_COUPLING")
	)
	(arc
		(start 90.682064 -229.762304)
		(mid 90.494866 -229.712161)
		(end 90.307668 -229.762304)
		(width 0.0889)
		(layer "B.Cu")
		(net "PU_CPU1_UPI0_AC_COUPLING")
	)
	(arc
		(start 96.875854 -229.7684)
		(mid 96.597422 -229.838246)
		(end 96.32061 -229.762304)
		(width 0.0889)
		(layer "B.Cu")
		(net "PU_CPU1_UPI0_AC_COUPLING")
	)
	(arc
		(start 93.112082 -229.77094)
		(mid 92.835607 -229.83826)
		(end 92.56141 -229.762304)
		(width 0.0889)
		(layer "B.Cu")
		(net "PU_CPU1_UPI0_AC_COUPLING")
	)
	(arc
		(start 96.32061 -229.762304)
		(mid 96.133412 -229.712161)
		(end 95.946214 -229.762304)
		(width 0.0889)
		(layer "B.Cu")
		(net "PU_CPU1_UPI0_AC_COUPLING")
	)
	(arc
		(start 92.172282 -229.77094)
		(mid 91.895807 -229.83826)
		(end 91.62161 -229.762304)
		(width 0.0889)
		(layer "B.Cu")
		(net "PU_CPU1_UPI0_AC_COUPLING")
	)
	(arc
		(start 94.051882 -229.77094)
		(mid 93.775407 -229.83826)
		(end 93.50121 -229.762304)
		(width 0.0889)
		(layer "B.Cu")
		(net "PU_CPU1_UPI0_AC_COUPLING")
	)
	(arc
		(start 93.50121 -229.762304)
		(mid 93.314012 -229.712161)
		(end 93.126814 -229.762304)
		(width 0.0889)
		(layer "B.Cu")
		(net "PU_CPU1_UPI0_AC_COUPLING")
	)
	(arc
		(start 88.427814 -229.762304)
		(mid 88.291572 -229.818738)
		(end 88.145366 -229.837996)
		(width 0.0889)
		(layer "B.Cu")
		(net "PU_CPU1_UPI0_AC_COUPLING")
	)
	(arc
		(start 92.56141 -229.762304)
		(mid 92.374212 -229.712161)
		(end 92.187014 -229.762304)
		(width 0.0889)
		(layer "B.Cu")
		(net "PU_CPU1_UPI0_AC_COUPLING")
	)
	(arc
		(start 88.80221 -229.762304)
		(mid 88.615012 -229.712161)
		(end 88.427814 -229.762304)
		(width 0.0889)
		(layer "B.Cu")
		(net "PU_CPU1_UPI0_AC_COUPLING")
	)
	(arc
		(start 95.38081 -229.762304)
		(mid 95.193612 -229.712161)
		(end 95.006414 -229.762304)
		(width 0.0889)
		(layer "B.Cu")
		(net "PU_CPU1_UPI0_AC_COUPLING")
	)
	(arc
		(start 102.423468 -230.572564)
		(mid 102.220881 -230.366213)
		(end 102.146862 -230.086662)
		(width 0.0889)
		(layer "B.Cu")
		(net "PU_CPU1_UPI0_AC_COUPLING")
	)
	(arc
		(start 95.006414 -229.762304)
		(mid 94.723712 -229.83808)
		(end 94.44101 -229.762304)
		(width 0.0889)
		(layer "B.Cu")
		(net "PU_CPU1_UPI0_AC_COUPLING")
	)
	(arc
		(start 102.617016 -230.900478)
		(mid 102.569337 -230.717578)
		(end 102.438454 -230.5812)
		(width 0.0889)
		(layer "B.Cu")
		(net "PU_CPU1_UPI0_AC_COUPLING")
	)
	(arc
		(start 91.2368 -229.7684)
		(mid 90.958622 -229.838123)
		(end 90.682064 -229.762304)
		(width 0.0889)
		(layer "B.Cu")
		(net "PU_CPU1_UPI0_AC_COUPLING")
	)
	(arc
		(start 91.62161 -229.762304)
		(mid 91.434412 -229.712161)
		(end 91.247214 -229.762304)
		(width 0.0889)
		(layer "B.Cu")
		(net "PU_CPU1_UPI0_AC_COUPLING")
	)
	(arc
		(start 103.406448 -231.419908)
		(mid 103.149309 -231.46519)
		(end 102.89921 -231.39019)
		(width 0.0889)
		(layer "B.Cu")
		(net "PU_CPU1_UPI0_AC_COUPLING")
	)
	(arc
		(start 97.8154 -229.7684)
		(mid 97.537222 -229.838123)
		(end 97.260664 -229.762304)
		(width 0.0889)
		(layer "B.Cu")
		(net "PU_CPU1_UPI0_AC_COUPLING")
	)
	(arc
		(start 94.44101 -229.762304)
		(mid 94.253812 -229.712161)
		(end 94.066614 -229.762304)
		(width 0.0889)
		(layer "B.Cu")
		(net "PU_CPU1_UPI0_AC_COUPLING")
	)
	(arc
		(start 89.352882 -229.77094)
		(mid 89.076407 -229.83826)
		(end 88.80221 -229.762304)
		(width 0.0889)
		(layer "B.Cu")
		(net "PU_CPU1_UPI0_AC_COUPLING")
	)
	(arc
		(start 98.20021 -229.762304)
		(mid 98.013012 -229.712161)
		(end 97.825814 -229.762304)
		(width 0.0889)
		(layer "B.Cu")
		(net "PU_CPU1_UPI0_AC_COUPLING")
	)
	(arc
		(start 101.95941 -229.762304)
		(mid 101.772212 -229.712161)
		(end 101.585014 -229.762304)
		(width 0.0889)
		(layer "B.Cu")
		(net "PU_CPU1_UPI0_AC_COUPLING")
	)
	(arc
		(start 97.260664 -229.762304)
		(mid 97.073466 -229.712161)
		(end 96.886268 -229.762304)
		(width 0.0889)
		(layer "B.Cu")
		(net "PU_CPU1_UPI0_AC_COUPLING")
	)
	(arc
		(start 99.690682 -229.77094)
		(mid 99.414207 -229.83826)
		(end 99.14001 -229.762304)
		(width 0.0889)
		(layer "B.Cu")
		(net "PU_CPU1_UPI0_AC_COUPLING")
	)
	(arc
		(start 95.931482 -229.77094)
		(mid 95.655007 -229.83826)
		(end 95.38081 -229.762304)
		(width 0.0889)
		(layer "B.Cu")
		(net "PU_CPU1_UPI0_AC_COUPLING")
	)
	(arc
		(start 101.01961 -229.762304)
		(mid 100.832412 -229.712161)
		(end 100.645214 -229.762304)
		(width 0.0889)
		(layer "B.Cu")
		(net "PU_CPU1_UPI0_AC_COUPLING")
	)
	(arc
		(start 90.297254 -229.7684)
		(mid 90.018822 -229.838246)
		(end 89.74201 -229.762304)
		(width 0.0889)
		(layer "B.Cu")
		(net "PU_CPU1_UPI0_AC_COUPLING")
	)
	(arc
		(start 99.14001 -229.762304)
		(mid 98.952812 -229.712161)
		(end 98.765614 -229.762304)
		(width 0.0889)
		(layer "B.Cu")
		(net "PU_CPU1_UPI0_AC_COUPLING")
	)
	(arc
		(start 89.74201 -229.762304)
		(mid 89.554812 -229.712161)
		(end 89.367614 -229.762304)
		(width 0.0889)
		(layer "B.Cu")
		(net "PU_CPU1_UPI0_AC_COUPLING")
	)
	(arc
		(start 102.89921 -231.39019)
		(mid 102.697928 -231.192703)
		(end 102.617016 -230.922576)
		(width 0.0889)
		(layer "B.Cu")
		(net "PU_CPU1_UPI0_AC_COUPLING")
	)
	(arc
		(start 101.585014 -229.762304)
		(mid 101.302312 -229.83808)
		(end 101.01961 -229.762304)
		(width 0.0889)
		(layer "B.Cu")
		(net "PU_CPU1_UPI0_AC_COUPLING")
	)
	(arc
		(start 98.750882 -229.77094)
		(mid 98.474407 -229.83826)
		(end 98.20021 -229.762304)
		(width 0.0889)
		(layer "B.Cu")
		(net "PU_CPU1_UPI0_AC_COUPLING")
	)
	(segment
		(start 110.70082 -234.156504)
		(end 110.700566 -234.15625)
		(width 0.12954)
		(layer "F.Cu")
		(net "PU_CPU1_TXT_AGENT")
	)
	(segment
		(start 110.700566 -234.69219)
		(end 110.70082 -234.691936)
		(width 0.12954)
		(layer "F.Cu")
		(net "PU_CPU1_TXT_AGENT")
	)
	(segment
		(start 110.70082 -234.691936)
		(end 110.70082 -234.156504)
		(width 0.12954)
		(layer "F.Cu")
		(net "PU_CPU1_TXT_AGENT")
	)
	(via
		(at 85.210142 -198.75119)
		(size 0.6604)
		(drill 0.3302)
		(layers "F.Cu" "B.Cu")
		(net "PU_CPU1_TXT_AGENT")
	)
	(via
		(at 110.700566 -234.15625)
		(size 0.4572)
		(drill 0.2032)
		(layers "F.Cu" "B.Cu")
		(net "PU_CPU1_TXT_AGENT")
	)
	(segment
		(start 96.416368 -224.065084)
		(end 96.407478 -224.070164)
		(width 0.0889)
		(layer "B.Cu")
		(net "PU_CPU1_TXT_AGENT")
	)
	(segment
		(start 98.679254 -224.070164)
		(end 98.678238 -224.069656)
		(width 0.0889)
		(layer "B.Cu")
		(net "PU_CPU1_TXT_AGENT")
	)
	(segment
		(start 100.737416 -224.404936)
		(end 100.737416 -224.389442)
		(width 0.0889)
		(layer "B.Cu")
		(net "PU_CPU1_TXT_AGENT")
	)
	(segment
		(start 108.5469 -231.39527)
		(end 108.53801 -231.39019)
		(width 0.0889)
		(layer "B.Cu")
		(net "PU_CPU1_TXT_AGENT")
	)
	(segment
		(start 95.946214 -224.8789)
		(end 95.931482 -224.887536)
		(width 0.0889)
		(layer "B.Cu")
		(net "PU_CPU1_TXT_AGENT")
	)
	(segment
		(start 102.9081 -224.88398)
		(end 102.89921 -224.8789)
		(width 0.0889)
		(layer "B.Cu")
		(net "PU_CPU1_TXT_AGENT")
	)
	(segment
		(start 93.040454 -224.070164)
		(end 93.031564 -224.065084)
		(width 0.0889)
		(layer "B.Cu")
		(net "PU_CPU1_TXT_AGENT")
	)
	(segment
		(start 103.556816 -226.027234)
		(end 103.556816 -226.017328)
		(width 0.0889)
		(layer "B.Cu")
		(net "PU_CPU1_TXT_AGENT")
	)
	(segment
		(start 102.438454 -224.070164)
		(end 102.429564 -224.065084)
		(width 0.0889)
		(layer "B.Cu")
		(net "PU_CPU1_TXT_AGENT")
	)
	(segment
		(start 84.265262 -224.140776)
		(end 83.302094 -223.177608)
		(width 0.12954)
		(layer "B.Cu")
		(net "PU_CPU1_TXT_AGENT")
	)
	(segment
		(start 81.279492 -220.384878)
		(end 81.279492 -209.426556)
		(width 0.12954)
		(layer "B.Cu")
		(net "PU_CPU1_TXT_AGENT")
	)
	(segment
		(start 91.339416 -224.404936)
		(end 91.339416 -224.389442)
		(width 0.0889)
		(layer "B.Cu")
		(net "PU_CPU1_TXT_AGENT")
	)
	(segment
		(start 106.845862 -230.086662)
		(end 106.845862 -230.078026)
		(width 0.0889)
		(layer "B.Cu")
		(net "PU_CPU1_TXT_AGENT")
	)
	(segment
		(start 103.378254 -225.69805)
		(end 103.369364 -225.69297)
		(width 0.0889)
		(layer "B.Cu")
		(net "PU_CPU1_TXT_AGENT")
	)
	(segment
		(start 105.263696 -228.957124)
		(end 105.248964 -228.948488)
		(width 0.0889)
		(layer "B.Cu")
		(net "PU_CPU1_TXT_AGENT")
	)
	(segment
		(start 106.376216 -229.282752)
		(end 106.376216 -229.272846)
		(width 0.0889)
		(layer "B.Cu")
		(net "PU_CPU1_TXT_AGENT")
	)
	(segment
		(start 88.347296 -224.07372)
		(end 88.332564 -224.065084)
		(width 0.0889)
		(layer "B.Cu")
		(net "PU_CPU1_TXT_AGENT")
	)
	(segment
		(start 95.95231 -224.875344)
		(end 95.946214 -224.8789)
		(width 0.0889)
		(layer "B.Cu")
		(net "PU_CPU1_TXT_AGENT")
	)
	(segment
		(start 107.612942 -231.398826)
		(end 107.59821 -231.39019)
		(width 0.0889)
		(layer "B.Cu")
		(net "PU_CPU1_TXT_AGENT")
	)
	(segment
		(start 100.175568 -224.065084)
		(end 100.166678 -224.070164)
		(width 0.0889)
		(layer "B.Cu")
		(net "PU_CPU1_TXT_AGENT")
	)
	(segment
		(start 97.83191 -224.875344)
		(end 97.825814 -224.8789)
		(width 0.0889)
		(layer "B.Cu")
		(net "PU_CPU1_TXT_AGENT")
	)
	(segment
		(start 92.657168 -224.065084)
		(end 92.648278 -224.070164)
		(width 0.0889)
		(layer "B.Cu")
		(net "PU_CPU1_TXT_AGENT")
	)
	(segment
		(start 98.678238 -224.069656)
		(end 98.670364 -224.065084)
		(width 0.0889)
		(layer "B.Cu")
		(net "PU_CPU1_TXT_AGENT")
	)
	(segment
		(start 90.777568 -224.065084)
		(end 90.768678 -224.070164)
		(width 0.0889)
		(layer "B.Cu")
		(net "PU_CPU1_TXT_AGENT")
	)
	(segment
		(start 94.536768 -224.065084)
		(end 94.527878 -224.070164)
		(width 0.0889)
		(layer "B.Cu")
		(net "PU_CPU1_TXT_AGENT")
	)
	(segment
		(start 84.070698 -201.83983)
		(end 85.210142 -200.700386)
		(width 0.12954)
		(layer "B.Cu")
		(net "PU_CPU1_TXT_AGENT")
	)
	(segment
		(start 102.055168 -224.065084)
		(end 102.046278 -224.070164)
		(width 0.0889)
		(layer "B.Cu")
		(net "PU_CPU1_TXT_AGENT")
	)
	(segment
		(start 96.799654 -224.070164)
		(end 96.790764 -224.065084)
		(width 0.0889)
		(layer "B.Cu")
		(net "PU_CPU1_TXT_AGENT")
	)
	(segment
		(start 109.017054 -232.209086)
		(end 109.008164 -232.204006)
		(width 0.0889)
		(layer "B.Cu")
		(net "PU_CPU1_TXT_AGENT")
	)
	(segment
		(start 107.315762 -230.922576)
		(end 107.315762 -230.891842)
		(width 0.0889)
		(layer "B.Cu")
		(net "PU_CPU1_TXT_AGENT")
	)
	(segment
		(start 85.210142 -191.352424)
		(end 85.457284 -191.105282)
		(width 0.12954)
		(layer "B.Cu")
		(net "PU_CPU1_TXT_AGENT")
	)
	(segment
		(start 95.098616 -224.404936)
		(end 95.098616 -224.389442)
		(width 0.0889)
		(layer "B.Cu")
		(net "PU_CPU1_TXT_AGENT")
	)
	(segment
		(start 98.857816 -224.404936)
		(end 98.857816 -224.389442)
		(width 0.0889)
		(layer "B.Cu")
		(net "PU_CPU1_TXT_AGENT")
	)
	(segment
		(start 89.459816 -224.404936)
		(end 89.459816 -224.389442)
		(width 0.0889)
		(layer "B.Cu")
		(net "PU_CPU1_TXT_AGENT")
	)
	(segment
		(start 81.279492 -209.426556)
		(end 84.070698 -206.63535)
		(width 0.12954)
		(layer "B.Cu")
		(net "PU_CPU1_TXT_AGENT")
	)
	(segment
		(start 96.978216 -224.404936)
		(end 96.978216 -224.389442)
		(width 0.0889)
		(layer "B.Cu")
		(net "PU_CPU1_TXT_AGENT")
	)
	(segment
		(start 84.070698 -206.63535)
		(end 84.070698 -201.83983)
		(width 0.12954)
		(layer "B.Cu")
		(net "PU_CPU1_TXT_AGENT")
	)
	(segment
		(start 109.008164 -232.204006)
		(end 109.002068 -232.20045)
		(width 0.0889)
		(layer "B.Cu")
		(net "PU_CPU1_TXT_AGENT")
	)
	(segment
		(start 90.31351 -224.875344)
		(end 90.307414 -224.8789)
		(width 0.0889)
		(layer "B.Cu")
		(net "PU_CPU1_TXT_AGENT")
	)
	(segment
		(start 85.210142 -200.700386)
		(end 85.210142 -198.75119)
		(width 0.12954)
		(layer "B.Cu")
		(net "PU_CPU1_TXT_AGENT")
	)
	(segment
		(start 101.585014 -224.8789)
		(end 101.570282 -224.887536)
		(width 0.0889)
		(layer "B.Cu")
		(net "PU_CPU1_TXT_AGENT")
	)
	(segment
		(start 107.128564 -230.57612)
		(end 107.122468 -230.572564)
		(width 0.0889)
		(layer "B.Cu")
		(net "PU_CPU1_TXT_AGENT")
	)
	(segment
		(start 94.920054 -224.070164)
		(end 94.911164 -224.065084)
		(width 0.0889)
		(layer "B.Cu")
		(net "PU_CPU1_TXT_AGENT")
	)
	(segment
		(start 91.160854 -224.070164)
		(end 91.151964 -224.065084)
		(width 0.0889)
		(layer "B.Cu")
		(net "PU_CPU1_TXT_AGENT")
	)
	(segment
		(start 90.307414 -224.8789)
		(end 90.292682 -224.887536)
		(width 0.0889)
		(layer "B.Cu")
		(net "PU_CPU1_TXT_AGENT")
	)
	(segment
		(start 106.197654 -228.953568)
		(end 106.188764 -228.948488)
		(width 0.0889)
		(layer "B.Cu")
		(net "PU_CPU1_TXT_AGENT")
	)
	(segment
		(start 92.187014 -224.8789)
		(end 92.172282 -224.887536)
		(width 0.0889)
		(layer "B.Cu")
		(net "PU_CPU1_TXT_AGENT")
	)
	(segment
		(start 83.302094 -223.177608)
		(end 83.302094 -222.40748)
		(width 0.12954)
		(layer "B.Cu")
		(net "PU_CPU1_TXT_AGENT")
	)
	(segment
		(start 86.078568 -224.065084)
		(end 86.068154 -224.07118)
		(width 0.0889)
		(layer "B.Cu")
		(net "PU_CPU1_TXT_AGENT")
	)
	(segment
		(start 109.665262 -233.3498)
		(end 109.665262 -233.34218)
		(width 0.0889)
		(layer "B.Cu")
		(net "PU_CPU1_TXT_AGENT")
	)
	(segment
		(start 98.295968 -224.065084)
		(end 98.287078 -224.070164)
		(width 0.0889)
		(layer "B.Cu")
		(net "PU_CPU1_TXT_AGENT")
	)
	(segment
		(start 103.086662 -225.217482)
		(end 103.086662 -225.203258)
		(width 0.0889)
		(layer "B.Cu")
		(net "PU_CPU1_TXT_AGENT")
	)
	(segment
		(start 94.07271 -224.875344)
		(end 94.066614 -224.8789)
		(width 0.0889)
		(layer "B.Cu")
		(net "PU_CPU1_TXT_AGENT")
	)
	(segment
		(start 101.59111 -224.875344)
		(end 101.585014 -224.8789)
		(width 0.0889)
		(layer "B.Cu")
		(net "PU_CPU1_TXT_AGENT")
	)
	(segment
		(start 99.705414 -224.8789)
		(end 99.690682 -224.887536)
		(width 0.0889)
		(layer "B.Cu")
		(net "PU_CPU1_TXT_AGENT")
	)
	(segment
		(start 97.825814 -224.8789)
		(end 97.811082 -224.887536)
		(width 0.0889)
		(layer "B.Cu")
		(net "PU_CPU1_TXT_AGENT")
	)
	(segment
		(start 105.248964 -228.948488)
		(end 105.242868 -228.944932)
		(width 0.0889)
		(layer "B.Cu")
		(net "PU_CPU1_TXT_AGENT")
	)
	(segment
		(start 110.544102 -233.885232)
		(end 110.454948 -233.861356)
		(width 0.0889)
		(layer "B.Cu")
		(net "PU_CPU1_TXT_AGENT")
	)
	(segment
		(start 110.700566 -234.15625)
		(end 110.544102 -233.885232)
		(width 0.0889)
		(layer "B.Cu")
		(net "PU_CPU1_TXT_AGENT")
	)
	(segment
		(start 109.4867 -233.022902)
		(end 109.47781 -233.017822)
		(width 0.0889)
		(layer "B.Cu")
		(net "PU_CPU1_TXT_AGENT")
	)
	(segment
		(start 83.302094 -222.40748)
		(end 81.279492 -220.384878)
		(width 0.12954)
		(layer "B.Cu")
		(net "PU_CPU1_TXT_AGENT")
	)
	(segment
		(start 104.318054 -227.325682)
		(end 104.309164 -227.320602)
		(width 0.0889)
		(layer "B.Cu")
		(net "PU_CPU1_TXT_AGENT")
	)
	(segment
		(start 104.026716 -226.84105)
		(end 104.026716 -226.831144)
		(width 0.0889)
		(layer "B.Cu")
		(net "PU_CPU1_TXT_AGENT")
	)
	(segment
		(start 104.496616 -227.667058)
		(end 104.496616 -227.64496)
		(width 0.0889)
		(layer "B.Cu")
		(net "PU_CPU1_TXT_AGENT")
	)
	(segment
		(start 104.7877 -228.139752)
		(end 104.77881 -228.134672)
		(width 0.0889)
		(layer "B.Cu")
		(net "PU_CPU1_TXT_AGENT")
	)
	(segment
		(start 85.210142 -198.75119)
		(end 85.210142 -191.352424)
		(width 0.12954)
		(layer "B.Cu")
		(net "PU_CPU1_TXT_AGENT")
	)
	(segment
		(start 100.558854 -224.070164)
		(end 100.549964 -224.065084)
		(width 0.0889)
		(layer "B.Cu")
		(net "PU_CPU1_TXT_AGENT")
	)
	(segment
		(start 109.195616 -232.543858)
		(end 109.195616 -232.528364)
		(width 0.0889)
		(layer "B.Cu")
		(net "PU_CPU1_TXT_AGENT")
	)
	(segment
		(start 92.19311 -224.875344)
		(end 92.187014 -224.8789)
		(width 0.0889)
		(layer "B.Cu")
		(net "PU_CPU1_TXT_AGENT")
	)
	(segment
		(start 94.066614 -224.8789)
		(end 94.051882 -224.887536)
		(width 0.0889)
		(layer "B.Cu")
		(net "PU_CPU1_TXT_AGENT")
	)
	(segment
		(start 93.219016 -224.404936)
		(end 93.219016 -224.389442)
		(width 0.0889)
		(layer "B.Cu")
		(net "PU_CPU1_TXT_AGENT")
	)
	(segment
		(start 102.617016 -224.404936)
		(end 102.617016 -224.389442)
		(width 0.0889)
		(layer "B.Cu")
		(net "PU_CPU1_TXT_AGENT")
	)
	(segment
		(start 89.281254 -224.070164)
		(end 89.272364 -224.065084)
		(width 0.0889)
		(layer "B.Cu")
		(net "PU_CPU1_TXT_AGENT")
	)
	(segment
		(start 103.848154 -226.511866)
		(end 103.839264 -226.506786)
		(width 0.0889)
		(layer "B.Cu")
		(net "PU_CPU1_TXT_AGENT")
	)
	(segment
		(start 99.71151 -224.875344)
		(end 99.705414 -224.8789)
		(width 0.0889)
		(layer "B.Cu")
		(net "PU_CPU1_TXT_AGENT")
	)
	(segment
		(start 84.85632 -224.140776)
		(end 84.265262 -224.140776)
		(width 0.0889)
		(layer "B.Cu")
		(net "PU_CPU1_TXT_AGENT")
	)
	(arc
		(start 108.725462 -231.714548)
		(mid 108.677783 -231.531648)
		(end 108.5469 -231.39527)
		(width 0.0889)
		(layer "B.Cu")
		(net "PU_CPU1_TXT_AGENT")
	)
	(arc
		(start 88.897968 -224.065084)
		(mid 88.623769 -224.140919)
		(end 88.347296 -224.07372)
		(width 0.0889)
		(layer "B.Cu")
		(net "PU_CPU1_TXT_AGENT")
	)
	(arc
		(start 103.839264 -226.506786)
		(mid 103.634929 -226.304181)
		(end 103.556816 -226.027234)
		(width 0.0889)
		(layer "B.Cu")
		(net "PU_CPU1_TXT_AGENT")
	)
	(arc
		(start 104.496616 -227.64496)
		(mid 104.448937 -227.46206)
		(end 104.318054 -227.325682)
		(width 0.0889)
		(layer "B.Cu")
		(net "PU_CPU1_TXT_AGENT")
	)
	(arc
		(start 104.026716 -226.831144)
		(mid 103.979037 -226.648244)
		(end 103.848154 -226.511866)
		(width 0.0889)
		(layer "B.Cu")
		(net "PU_CPU1_TXT_AGENT")
	)
	(arc
		(start 109.665262 -233.34218)
		(mid 109.617583 -233.15928)
		(end 109.4867 -233.022902)
		(width 0.0889)
		(layer "B.Cu")
		(net "PU_CPU1_TXT_AGENT")
	)
	(arc
		(start 106.658664 -229.762304)
		(mid 106.454329 -229.559699)
		(end 106.376216 -229.282752)
		(width 0.0889)
		(layer "B.Cu")
		(net "PU_CPU1_TXT_AGENT")
	)
	(arc
		(start 87.392764 -224.065084)
		(mid 87.205566 -224.014941)
		(end 87.018368 -224.065084)
		(width 0.0889)
		(layer "B.Cu")
		(net "PU_CPU1_TXT_AGENT")
	)
	(arc
		(start 102.046278 -224.070164)
		(mid 101.915364 -224.206524)
		(end 101.867716 -224.389442)
		(width 0.0889)
		(layer "B.Cu")
		(net "PU_CPU1_TXT_AGENT")
	)
	(arc
		(start 85.138514 -224.065084)
		(mid 85.019883 -224.116604)
		(end 84.892642 -224.13976)
		(width 0.0889)
		(layer "B.Cu")
		(net "PU_CPU1_TXT_AGENT")
	)
	(arc
		(start 89.459816 -224.389442)
		(mid 89.412137 -224.206542)
		(end 89.281254 -224.070164)
		(width 0.0889)
		(layer "B.Cu")
		(net "PU_CPU1_TXT_AGENT")
	)
	(arc
		(start 91.151964 -224.065084)
		(mid 90.964766 -224.014941)
		(end 90.777568 -224.065084)
		(width 0.0889)
		(layer "B.Cu")
		(net "PU_CPU1_TXT_AGENT")
	)
	(arc
		(start 109.947964 -233.831892)
		(mid 109.742892 -233.628213)
		(end 109.665262 -233.3498)
		(width 0.0889)
		(layer "B.Cu")
		(net "PU_CPU1_TXT_AGENT")
	)
	(arc
		(start 92.172282 -224.887536)
		(mid 91.895807 -224.954856)
		(end 91.62161 -224.8789)
		(width 0.0889)
		(layer "B.Cu")
		(net "PU_CPU1_TXT_AGENT")
	)
	(arc
		(start 95.931482 -224.887536)
		(mid 95.655007 -224.954856)
		(end 95.38081 -224.8789)
		(width 0.0889)
		(layer "B.Cu")
		(net "PU_CPU1_TXT_AGENT")
	)
	(arc
		(start 107.315762 -230.891842)
		(mid 107.263492 -230.709477)
		(end 107.128564 -230.57612)
		(width 0.0889)
		(layer "B.Cu")
		(net "PU_CPU1_TXT_AGENT")
	)
	(arc
		(start 84.892642 -224.13976)
		(mid 84.874489 -224.140563)
		(end 84.85632 -224.140776)
		(width 0.0889)
		(layer "B.Cu")
		(net "PU_CPU1_TXT_AGENT")
	)
	(arc
		(start 91.339416 -224.389442)
		(mid 91.291737 -224.206542)
		(end 91.160854 -224.070164)
		(width 0.0889)
		(layer "B.Cu")
		(net "PU_CPU1_TXT_AGENT")
	)
	(arc
		(start 94.911164 -224.065084)
		(mid 94.723966 -224.014941)
		(end 94.536768 -224.065084)
		(width 0.0889)
		(layer "B.Cu")
		(net "PU_CPU1_TXT_AGENT")
	)
	(arc
		(start 109.195616 -232.528364)
		(mid 109.147937 -232.345464)
		(end 109.017054 -232.209086)
		(width 0.0889)
		(layer "B.Cu")
		(net "PU_CPU1_TXT_AGENT")
	)
	(arc
		(start 85.51291 -224.065084)
		(mid 85.325712 -224.014941)
		(end 85.138514 -224.065084)
		(width 0.0889)
		(layer "B.Cu")
		(net "PU_CPU1_TXT_AGENT")
	)
	(arc
		(start 108.163614 -231.39019)
		(mid 107.889385 -231.466115)
		(end 107.612942 -231.398826)
		(width 0.0889)
		(layer "B.Cu")
		(net "PU_CPU1_TXT_AGENT")
	)
	(arc
		(start 100.737416 -224.389442)
		(mid 100.689737 -224.206542)
		(end 100.558854 -224.070164)
		(width 0.0889)
		(layer "B.Cu")
		(net "PU_CPU1_TXT_AGENT")
	)
	(arc
		(start 106.845862 -230.078026)
		(mid 106.793592 -229.895661)
		(end 106.658664 -229.762304)
		(width 0.0889)
		(layer "B.Cu")
		(net "PU_CPU1_TXT_AGENT")
	)
	(arc
		(start 100.549964 -224.065084)
		(mid 100.362766 -224.014941)
		(end 100.175568 -224.065084)
		(width 0.0889)
		(layer "B.Cu")
		(net "PU_CPU1_TXT_AGENT")
	)
	(arc
		(start 93.219016 -224.389442)
		(mid 93.171337 -224.206542)
		(end 93.040454 -224.070164)
		(width 0.0889)
		(layer "B.Cu")
		(net "PU_CPU1_TXT_AGENT")
	)
	(arc
		(start 89.272364 -224.065084)
		(mid 89.085166 -224.014941)
		(end 88.897968 -224.065084)
		(width 0.0889)
		(layer "B.Cu")
		(net "PU_CPU1_TXT_AGENT")
	)
	(arc
		(start 104.77881 -228.134672)
		(mid 104.577528 -227.937185)
		(end 104.496616 -227.667058)
		(width 0.0889)
		(layer "B.Cu")
		(net "PU_CPU1_TXT_AGENT")
	)
	(arc
		(start 101.01961 -224.8789)
		(mid 100.816787 -224.678669)
		(end 100.737416 -224.404936)
		(width 0.0889)
		(layer "B.Cu")
		(net "PU_CPU1_TXT_AGENT")
	)
	(arc
		(start 97.26041 -224.8789)
		(mid 97.057587 -224.678669)
		(end 96.978216 -224.404936)
		(width 0.0889)
		(layer "B.Cu")
		(net "PU_CPU1_TXT_AGENT")
	)
	(arc
		(start 97.811082 -224.887536)
		(mid 97.534607 -224.954856)
		(end 97.26041 -224.8789)
		(width 0.0889)
		(layer "B.Cu")
		(net "PU_CPU1_TXT_AGENT")
	)
	(arc
		(start 96.228916 -224.389442)
		(mid 96.154925 -224.669008)
		(end 95.95231 -224.875344)
		(width 0.0889)
		(layer "B.Cu")
		(net "PU_CPU1_TXT_AGENT")
	)
	(arc
		(start 104.966262 -228.45903)
		(mid 104.918583 -228.27613)
		(end 104.7877 -228.139752)
		(width 0.0889)
		(layer "B.Cu")
		(net "PU_CPU1_TXT_AGENT")
	)
	(arc
		(start 93.031564 -224.065084)
		(mid 92.844366 -224.014941)
		(end 92.657168 -224.065084)
		(width 0.0889)
		(layer "B.Cu")
		(net "PU_CPU1_TXT_AGENT")
	)
	(arc
		(start 98.108516 -224.389442)
		(mid 98.034525 -224.669008)
		(end 97.83191 -224.875344)
		(width 0.0889)
		(layer "B.Cu")
		(net "PU_CPU1_TXT_AGENT")
	)
	(arc
		(start 101.570282 -224.887536)
		(mid 101.293807 -224.954856)
		(end 101.01961 -224.8789)
		(width 0.0889)
		(layer "B.Cu")
		(net "PU_CPU1_TXT_AGENT")
	)
	(arc
		(start 90.768678 -224.070164)
		(mid 90.637764 -224.206524)
		(end 90.590116 -224.389442)
		(width 0.0889)
		(layer "B.Cu")
		(net "PU_CPU1_TXT_AGENT")
	)
	(arc
		(start 104.309164 -227.320602)
		(mid 104.104829 -227.117997)
		(end 104.026716 -226.84105)
		(width 0.0889)
		(layer "B.Cu")
		(net "PU_CPU1_TXT_AGENT")
	)
	(arc
		(start 103.556816 -226.017328)
		(mid 103.509137 -225.834428)
		(end 103.378254 -225.69805)
		(width 0.0889)
		(layer "B.Cu")
		(net "PU_CPU1_TXT_AGENT")
	)
	(arc
		(start 102.429564 -224.065084)
		(mid 102.242366 -224.014941)
		(end 102.055168 -224.065084)
		(width 0.0889)
		(layer "B.Cu")
		(net "PU_CPU1_TXT_AGENT")
	)
	(arc
		(start 98.287078 -224.070164)
		(mid 98.156164 -224.206524)
		(end 98.108516 -224.389442)
		(width 0.0889)
		(layer "B.Cu")
		(net "PU_CPU1_TXT_AGENT")
	)
	(arc
		(start 91.62161 -224.8789)
		(mid 91.418787 -224.678669)
		(end 91.339416 -224.404936)
		(width 0.0889)
		(layer "B.Cu")
		(net "PU_CPU1_TXT_AGENT")
	)
	(arc
		(start 94.527878 -224.070164)
		(mid 94.396964 -224.206524)
		(end 94.349316 -224.389442)
		(width 0.0889)
		(layer "B.Cu")
		(net "PU_CPU1_TXT_AGENT")
	)
	(arc
		(start 103.369364 -225.69297)
		(mid 103.165883 -225.492166)
		(end 103.086662 -225.217482)
		(width 0.0889)
		(layer "B.Cu")
		(net "PU_CPU1_TXT_AGENT")
	)
	(arc
		(start 95.38081 -224.8789)
		(mid 95.177987 -224.678669)
		(end 95.098616 -224.404936)
		(width 0.0889)
		(layer "B.Cu")
		(net "PU_CPU1_TXT_AGENT")
	)
	(arc
		(start 94.051882 -224.887536)
		(mid 93.775407 -224.954856)
		(end 93.50121 -224.8789)
		(width 0.0889)
		(layer "B.Cu")
		(net "PU_CPU1_TXT_AGENT")
	)
	(arc
		(start 109.47781 -233.017822)
		(mid 109.274987 -232.817591)
		(end 109.195616 -232.543858)
		(width 0.0889)
		(layer "B.Cu")
		(net "PU_CPU1_TXT_AGENT")
	)
	(arc
		(start 107.122468 -230.572564)
		(mid 106.919881 -230.366213)
		(end 106.845862 -230.086662)
		(width 0.0889)
		(layer "B.Cu")
		(net "PU_CPU1_TXT_AGENT")
	)
	(arc
		(start 96.407478 -224.070164)
		(mid 96.276564 -224.206524)
		(end 96.228916 -224.389442)
		(width 0.0889)
		(layer "B.Cu")
		(net "PU_CPU1_TXT_AGENT")
	)
	(arc
		(start 103.086662 -225.203258)
		(mid 103.038983 -225.020358)
		(end 102.9081 -224.88398)
		(width 0.0889)
		(layer "B.Cu")
		(net "PU_CPU1_TXT_AGENT")
	)
	(arc
		(start 102.617016 -224.389442)
		(mid 102.569337 -224.206542)
		(end 102.438454 -224.070164)
		(width 0.0889)
		(layer "B.Cu")
		(net "PU_CPU1_TXT_AGENT")
	)
	(arc
		(start 87.018368 -224.065084)
		(mid 86.735666 -224.14086)
		(end 86.452964 -224.065084)
		(width 0.0889)
		(layer "B.Cu")
		(net "PU_CPU1_TXT_AGENT")
	)
	(arc
		(start 86.452964 -224.065084)
		(mid 86.265766 -224.014941)
		(end 86.078568 -224.065084)
		(width 0.0889)
		(layer "B.Cu")
		(net "PU_CPU1_TXT_AGENT")
	)
	(arc
		(start 105.242868 -228.944932)
		(mid 105.040281 -228.738581)
		(end 104.966262 -228.45903)
		(width 0.0889)
		(layer "B.Cu")
		(net "PU_CPU1_TXT_AGENT")
	)
	(arc
		(start 93.50121 -224.8789)
		(mid 93.298387 -224.678669)
		(end 93.219016 -224.404936)
		(width 0.0889)
		(layer "B.Cu")
		(net "PU_CPU1_TXT_AGENT")
	)
	(arc
		(start 98.670364 -224.065084)
		(mid 98.483166 -224.014941)
		(end 98.295968 -224.065084)
		(width 0.0889)
		(layer "B.Cu")
		(net "PU_CPU1_TXT_AGENT")
	)
	(arc
		(start 90.590116 -224.389442)
		(mid 90.516125 -224.669008)
		(end 90.31351 -224.875344)
		(width 0.0889)
		(layer "B.Cu")
		(net "PU_CPU1_TXT_AGENT")
	)
	(arc
		(start 99.14001 -224.8789)
		(mid 98.937187 -224.678669)
		(end 98.857816 -224.404936)
		(width 0.0889)
		(layer "B.Cu")
		(net "PU_CPU1_TXT_AGENT")
	)
	(arc
		(start 95.098616 -224.389442)
		(mid 95.050937 -224.206542)
		(end 94.920054 -224.070164)
		(width 0.0889)
		(layer "B.Cu")
		(net "PU_CPU1_TXT_AGENT")
	)
	(arc
		(start 107.59821 -231.39019)
		(mid 107.396754 -231.192765)
		(end 107.315762 -230.922576)
		(width 0.0889)
		(layer "B.Cu")
		(net "PU_CPU1_TXT_AGENT")
	)
	(arc
		(start 106.188764 -228.948488)
		(mid 106.001566 -228.898345)
		(end 105.814368 -228.948488)
		(width 0.0889)
		(layer "B.Cu")
		(net "PU_CPU1_TXT_AGENT")
	)
	(arc
		(start 106.376216 -229.272846)
		(mid 106.328537 -229.089946)
		(end 106.197654 -228.953568)
		(width 0.0889)
		(layer "B.Cu")
		(net "PU_CPU1_TXT_AGENT")
	)
	(arc
		(start 109.002068 -232.20045)
		(mid 108.799481 -231.994099)
		(end 108.725462 -231.714548)
		(width 0.0889)
		(layer "B.Cu")
		(net "PU_CPU1_TXT_AGENT")
	)
	(arc
		(start 92.648278 -224.070164)
		(mid 92.517364 -224.206524)
		(end 92.469716 -224.389442)
		(width 0.0889)
		(layer "B.Cu")
		(net "PU_CPU1_TXT_AGENT")
	)
	(arc
		(start 102.89921 -224.8789)
		(mid 102.696387 -224.678669)
		(end 102.617016 -224.404936)
		(width 0.0889)
		(layer "B.Cu")
		(net "PU_CPU1_TXT_AGENT")
	)
	(arc
		(start 94.349316 -224.389442)
		(mid 94.275325 -224.669008)
		(end 94.07271 -224.875344)
		(width 0.0889)
		(layer "B.Cu")
		(net "PU_CPU1_TXT_AGENT")
	)
	(arc
		(start 99.690682 -224.887536)
		(mid 99.414207 -224.954856)
		(end 99.14001 -224.8789)
		(width 0.0889)
		(layer "B.Cu")
		(net "PU_CPU1_TXT_AGENT")
	)
	(arc
		(start 86.068154 -224.07118)
		(mid 85.789722 -224.141026)
		(end 85.51291 -224.065084)
		(width 0.0889)
		(layer "B.Cu")
		(net "PU_CPU1_TXT_AGENT")
	)
	(arc
		(start 108.53801 -231.39019)
		(mid 108.350812 -231.340047)
		(end 108.163614 -231.39019)
		(width 0.0889)
		(layer "B.Cu")
		(net "PU_CPU1_TXT_AGENT")
	)
	(arc
		(start 92.469716 -224.389442)
		(mid 92.395725 -224.669008)
		(end 92.19311 -224.875344)
		(width 0.0889)
		(layer "B.Cu")
		(net "PU_CPU1_TXT_AGENT")
	)
	(arc
		(start 98.857816 -224.389442)
		(mid 98.810137 -224.206542)
		(end 98.679254 -224.070164)
		(width 0.0889)
		(layer "B.Cu")
		(net "PU_CPU1_TXT_AGENT")
	)
	(arc
		(start 110.454948 -233.861356)
		(mid 110.197949 -233.906782)
		(end 109.947964 -233.831892)
		(width 0.0889)
		(layer "B.Cu")
		(net "PU_CPU1_TXT_AGENT")
	)
	(arc
		(start 100.166678 -224.070164)
		(mid 100.035764 -224.206524)
		(end 99.988116 -224.389442)
		(width 0.0889)
		(layer "B.Cu")
		(net "PU_CPU1_TXT_AGENT")
	)
	(arc
		(start 88.332564 -224.065084)
		(mid 88.145366 -224.014941)
		(end 87.958168 -224.065084)
		(width 0.0889)
		(layer "B.Cu")
		(net "PU_CPU1_TXT_AGENT")
	)
	(arc
		(start 105.814368 -228.948488)
		(mid 105.540169 -229.024323)
		(end 105.263696 -228.957124)
		(width 0.0889)
		(layer "B.Cu")
		(net "PU_CPU1_TXT_AGENT")
	)
	(arc
		(start 89.74201 -224.8789)
		(mid 89.539187 -224.678669)
		(end 89.459816 -224.404936)
		(width 0.0889)
		(layer "B.Cu")
		(net "PU_CPU1_TXT_AGENT")
	)
	(arc
		(start 87.958168 -224.065084)
		(mid 87.675466 -224.14086)
		(end 87.392764 -224.065084)
		(width 0.0889)
		(layer "B.Cu")
		(net "PU_CPU1_TXT_AGENT")
	)
	(arc
		(start 90.292682 -224.887536)
		(mid 90.016207 -224.954856)
		(end 89.74201 -224.8789)
		(width 0.0889)
		(layer "B.Cu")
		(net "PU_CPU1_TXT_AGENT")
	)
	(arc
		(start 96.978216 -224.389442)
		(mid 96.930537 -224.206542)
		(end 96.799654 -224.070164)
		(width 0.0889)
		(layer "B.Cu")
		(net "PU_CPU1_TXT_AGENT")
	)
	(arc
		(start 99.988116 -224.389442)
		(mid 99.914125 -224.669008)
		(end 99.71151 -224.875344)
		(width 0.0889)
		(layer "B.Cu")
		(net "PU_CPU1_TXT_AGENT")
	)
	(arc
		(start 96.790764 -224.065084)
		(mid 96.603566 -224.014941)
		(end 96.416368 -224.065084)
		(width 0.0889)
		(layer "B.Cu")
		(net "PU_CPU1_TXT_AGENT")
	)
	(arc
		(start 101.867716 -224.389442)
		(mid 101.793725 -224.669008)
		(end 101.59111 -224.875344)
		(width 0.0889)
		(layer "B.Cu")
		(net "PU_CPU1_TXT_AGENT")
	)
	(segment
		(start 120.208548 -264.77849)
		(end 120.208548 -265.314176)
		(width 0.12954)
		(layer "F.Cu")
		(net "PU_CPU1_SOCKET_ID2")
	)
	(segment
		(start 120.208294 -264.778236)
		(end 120.208548 -264.77849)
		(width 0.12954)
		(layer "F.Cu")
		(net "PU_CPU1_SOCKET_ID2")
	)
	(via
		(at 153.312368 -265.636248)
		(size 0.6604)
		(drill 0.3302)
		(layers "F.Cu" "B.Cu")
		(net "PU_CPU1_SOCKET_ID2")
	)
	(via
		(at 120.208548 -265.314176)
		(size 0.4572)
		(drill 0.2032)
		(layers "F.Cu" "B.Cu")
		(net "PU_CPU1_SOCKET_ID2")
	)
	(segment
		(start 136.69772 -265.753596)
		(end 136.869678 -265.925554)
		(width 0.0889)
		(layer "B.Cu")
		(net "PU_CPU1_SOCKET_ID2")
	)
	(segment
		(start 132.693664 -265.81227)
		(end 132.708396 -265.803634)
		(width 0.0889)
		(layer "B.Cu")
		(net "PU_CPU1_SOCKET_ID2")
	)
	(segment
		(start 152.88895 -266.059666)
		(end 153.312368 -265.636248)
		(width 0.12954)
		(layer "B.Cu")
		(net "PU_CPU1_SOCKET_ID2")
	)
	(segment
		(start 135.513064 -265.81227)
		(end 135.527796 -265.803634)
		(width 0.0889)
		(layer "B.Cu")
		(net "PU_CPU1_SOCKET_ID2")
	)
	(segment
		(start 127.994664 -265.81227)
		(end 128.009396 -265.803634)
		(width 0.0889)
		(layer "B.Cu")
		(net "PU_CPU1_SOCKET_ID2")
	)
	(segment
		(start 177.438558 -253.14783)
		(end 178.634898 -251.95149)
		(width 0.12954)
		(layer "B.Cu")
		(net "PU_CPU1_SOCKET_ID2")
	)
	(segment
		(start 131.753864 -265.81227)
		(end 131.768596 -265.803634)
		(width 0.0889)
		(layer "B.Cu")
		(net "PU_CPU1_SOCKET_ID2")
	)
	(segment
		(start 175.050958 -253.14783)
		(end 177.438558 -253.14783)
		(width 0.12954)
		(layer "B.Cu")
		(net "PU_CPU1_SOCKET_ID2")
	)
	(segment
		(start 122.355864 -265.81227)
		(end 122.370596 -265.803634)
		(width 0.0889)
		(layer "B.Cu")
		(net "PU_CPU1_SOCKET_ID2")
	)
	(segment
		(start 124.235464 -265.81227)
		(end 124.250196 -265.803634)
		(width 0.0889)
		(layer "B.Cu")
		(net "PU_CPU1_SOCKET_ID2")
	)
	(segment
		(start 153.312368 -265.636248)
		(end 154.116786 -264.83183)
		(width 0.12954)
		(layer "B.Cu")
		(net "PU_CPU1_SOCKET_ID2")
	)
	(segment
		(start 168.601898 -265.319002)
		(end 168.601898 -258.046728)
		(width 0.12954)
		(layer "B.Cu")
		(net "PU_CPU1_SOCKET_ID2")
	)
	(segment
		(start 136.869678 -265.925554)
		(end 137.829798 -265.925554)
		(width 0.0889)
		(layer "B.Cu")
		(net "PU_CPU1_SOCKET_ID2")
	)
	(segment
		(start 134.573264 -265.81227)
		(end 134.587996 -265.803634)
		(width 0.0889)
		(layer "B.Cu")
		(net "PU_CPU1_SOCKET_ID2")
	)
	(segment
		(start 164.542978 -266.76223)
		(end 165.101778 -266.20343)
		(width 0.12954)
		(layer "B.Cu")
		(net "PU_CPU1_SOCKET_ID2")
	)
	(segment
		(start 126.115064 -265.81227)
		(end 126.129796 -265.803634)
		(width 0.0889)
		(layer "B.Cu")
		(net "PU_CPU1_SOCKET_ID2")
	)
	(segment
		(start 123.295664 -265.81227)
		(end 123.310396 -265.803634)
		(width 0.0889)
		(layer "B.Cu")
		(net "PU_CPU1_SOCKET_ID2")
	)
	(segment
		(start 160.357058 -266.76223)
		(end 164.542978 -266.76223)
		(width 0.12954)
		(layer "B.Cu")
		(net "PU_CPU1_SOCKET_ID2")
	)
	(segment
		(start 154.116786 -264.83183)
		(end 158.426658 -264.83183)
		(width 0.12954)
		(layer "B.Cu")
		(net "PU_CPU1_SOCKET_ID2")
	)
	(segment
		(start 125.175264 -265.81227)
		(end 125.189996 -265.803634)
		(width 0.0889)
		(layer "B.Cu")
		(net "PU_CPU1_SOCKET_ID2")
	)
	(segment
		(start 178.634898 -251.95149)
		(end 178.634898 -193.588894)
		(width 0.12954)
		(layer "B.Cu")
		(net "PU_CPU1_SOCKET_ID2")
	)
	(segment
		(start 168.601898 -258.046728)
		(end 170.376596 -256.27203)
		(width 0.12954)
		(layer "B.Cu")
		(net "PU_CPU1_SOCKET_ID2")
	)
	(segment
		(start 158.426658 -264.83183)
		(end 160.357058 -266.76223)
		(width 0.12954)
		(layer "B.Cu")
		(net "PU_CPU1_SOCKET_ID2")
	)
	(segment
		(start 121.416064 -265.81227)
		(end 121.430796 -265.803634)
		(width 0.0889)
		(layer "B.Cu")
		(net "PU_CPU1_SOCKET_ID2")
	)
	(segment
		(start 129.874264 -265.81227)
		(end 129.888996 -265.803634)
		(width 0.0889)
		(layer "B.Cu")
		(net "PU_CPU1_SOCKET_ID2")
	)
	(segment
		(start 167.71747 -266.20343)
		(end 168.601898 -265.319002)
		(width 0.12954)
		(layer "B.Cu")
		(net "PU_CPU1_SOCKET_ID2")
	)
	(segment
		(start 170.376596 -256.27203)
		(end 175.050958 -253.14783)
		(width 0.12954)
		(layer "B.Cu")
		(net "PU_CPU1_SOCKET_ID2")
	)
	(segment
		(start 138.495278 -266.009628)
		(end 138.545316 -266.059666)
		(width 0.0889)
		(layer "B.Cu")
		(net "PU_CPU1_SOCKET_ID2")
	)
	(segment
		(start 178.634898 -193.588894)
		(end 178.145948 -193.099944)
		(width 0.12954)
		(layer "B.Cu")
		(net "PU_CPU1_SOCKET_ID2")
	)
	(segment
		(start 138.545316 -266.059666)
		(end 152.88895 -266.059666)
		(width 0.12954)
		(layer "B.Cu")
		(net "PU_CPU1_SOCKET_ID2")
	)
	(segment
		(start 130.814064 -265.81227)
		(end 130.828796 -265.803634)
		(width 0.0889)
		(layer "B.Cu")
		(net "PU_CPU1_SOCKET_ID2")
	)
	(segment
		(start 128.934464 -265.81227)
		(end 128.949196 -265.803634)
		(width 0.0889)
		(layer "B.Cu")
		(net "PU_CPU1_SOCKET_ID2")
	)
	(segment
		(start 137.913872 -266.009628)
		(end 138.495278 -266.009628)
		(width 0.0889)
		(layer "B.Cu")
		(net "PU_CPU1_SOCKET_ID2")
	)
	(segment
		(start 135.714994 -265.753596)
		(end 136.69772 -265.753596)
		(width 0.0889)
		(layer "B.Cu")
		(net "PU_CPU1_SOCKET_ID2")
	)
	(segment
		(start 137.829798 -265.925554)
		(end 137.913872 -266.009628)
		(width 0.0889)
		(layer "B.Cu")
		(net "PU_CPU1_SOCKET_ID2")
	)
	(segment
		(start 165.101778 -266.20343)
		(end 167.71747 -266.20343)
		(width 0.12954)
		(layer "B.Cu")
		(net "PU_CPU1_SOCKET_ID2")
	)
	(arc
		(start 128.009396 -265.803634)
		(mid 128.196594 -265.753491)
		(end 128.383792 -265.803634)
		(width 0.0889)
		(layer "B.Cu")
		(net "PU_CPU1_SOCKET_ID2")
	)
	(arc
		(start 132.142992 -265.803634)
		(mid 132.417191 -265.879469)
		(end 132.693664 -265.81227)
		(width 0.0889)
		(layer "B.Cu")
		(net "PU_CPU1_SOCKET_ID2")
	)
	(arc
		(start 130.828796 -265.803634)
		(mid 131.015994 -265.753491)
		(end 131.203192 -265.803634)
		(width 0.0889)
		(layer "B.Cu")
		(net "PU_CPU1_SOCKET_ID2")
	)
	(arc
		(start 134.587996 -265.803634)
		(mid 134.775194 -265.753491)
		(end 134.962392 -265.803634)
		(width 0.0889)
		(layer "B.Cu")
		(net "PU_CPU1_SOCKET_ID2")
	)
	(arc
		(start 131.768596 -265.803634)
		(mid 131.955794 -265.753491)
		(end 132.142992 -265.803634)
		(width 0.0889)
		(layer "B.Cu")
		(net "PU_CPU1_SOCKET_ID2")
	)
	(arc
		(start 127.069596 -265.803634)
		(mid 127.256794 -265.753491)
		(end 127.443992 -265.803634)
		(width 0.0889)
		(layer "B.Cu")
		(net "PU_CPU1_SOCKET_ID2")
	)
	(arc
		(start 129.323592 -265.803634)
		(mid 129.597791 -265.879469)
		(end 129.874264 -265.81227)
		(width 0.0889)
		(layer "B.Cu")
		(net "PU_CPU1_SOCKET_ID2")
	)
	(arc
		(start 124.624592 -265.803634)
		(mid 124.898791 -265.879469)
		(end 125.175264 -265.81227)
		(width 0.0889)
		(layer "B.Cu")
		(net "PU_CPU1_SOCKET_ID2")
	)
	(arc
		(start 126.504192 -265.803634)
		(mid 126.786894 -265.87941)
		(end 127.069596 -265.803634)
		(width 0.0889)
		(layer "B.Cu")
		(net "PU_CPU1_SOCKET_ID2")
	)
	(arc
		(start 128.383792 -265.803634)
		(mid 128.657991 -265.879469)
		(end 128.934464 -265.81227)
		(width 0.0889)
		(layer "B.Cu")
		(net "PU_CPU1_SOCKET_ID2")
	)
	(arc
		(start 124.250196 -265.803634)
		(mid 124.437394 -265.753491)
		(end 124.624592 -265.803634)
		(width 0.0889)
		(layer "B.Cu")
		(net "PU_CPU1_SOCKET_ID2")
	)
	(arc
		(start 123.310396 -265.803634)
		(mid 123.497594 -265.753491)
		(end 123.684792 -265.803634)
		(width 0.0889)
		(layer "B.Cu")
		(net "PU_CPU1_SOCKET_ID2")
	)
	(arc
		(start 130.263392 -265.803634)
		(mid 130.537591 -265.879469)
		(end 130.814064 -265.81227)
		(width 0.0889)
		(layer "B.Cu")
		(net "PU_CPU1_SOCKET_ID2")
	)
	(arc
		(start 132.708396 -265.803634)
		(mid 132.895594 -265.753491)
		(end 133.082792 -265.803634)
		(width 0.0889)
		(layer "B.Cu")
		(net "PU_CPU1_SOCKET_ID2")
	)
	(arc
		(start 125.189996 -265.803634)
		(mid 125.377194 -265.753491)
		(end 125.564392 -265.803634)
		(width 0.0889)
		(layer "B.Cu")
		(net "PU_CPU1_SOCKET_ID2")
	)
	(arc
		(start 120.208548 -265.314176)
		(mid 120.522725 -265.578022)
		(end 120.865392 -265.803634)
		(width 0.0889)
		(layer "B.Cu")
		(net "PU_CPU1_SOCKET_ID2")
	)
	(arc
		(start 134.022592 -265.803634)
		(mid 134.296791 -265.879469)
		(end 134.573264 -265.81227)
		(width 0.0889)
		(layer "B.Cu")
		(net "PU_CPU1_SOCKET_ID2")
	)
	(arc
		(start 133.648196 -265.803634)
		(mid 133.835394 -265.753491)
		(end 134.022592 -265.803634)
		(width 0.0889)
		(layer "B.Cu")
		(net "PU_CPU1_SOCKET_ID2")
	)
	(arc
		(start 126.129796 -265.803634)
		(mid 126.316994 -265.753491)
		(end 126.504192 -265.803634)
		(width 0.0889)
		(layer "B.Cu")
		(net "PU_CPU1_SOCKET_ID2")
	)
	(arc
		(start 120.865392 -265.803634)
		(mid 121.139591 -265.879469)
		(end 121.416064 -265.81227)
		(width 0.0889)
		(layer "B.Cu")
		(net "PU_CPU1_SOCKET_ID2")
	)
	(arc
		(start 133.082792 -265.803634)
		(mid 133.365494 -265.87941)
		(end 133.648196 -265.803634)
		(width 0.0889)
		(layer "B.Cu")
		(net "PU_CPU1_SOCKET_ID2")
	)
	(arc
		(start 131.203192 -265.803634)
		(mid 131.477391 -265.879469)
		(end 131.753864 -265.81227)
		(width 0.0889)
		(layer "B.Cu")
		(net "PU_CPU1_SOCKET_ID2")
	)
	(arc
		(start 121.805192 -265.803634)
		(mid 122.079391 -265.879469)
		(end 122.355864 -265.81227)
		(width 0.0889)
		(layer "B.Cu")
		(net "PU_CPU1_SOCKET_ID2")
	)
	(arc
		(start 135.527796 -265.803634)
		(mid 135.618103 -265.766305)
		(end 135.714994 -265.753596)
		(width 0.0889)
		(layer "B.Cu")
		(net "PU_CPU1_SOCKET_ID2")
	)
	(arc
		(start 134.962392 -265.803634)
		(mid 135.236591 -265.879469)
		(end 135.513064 -265.81227)
		(width 0.0889)
		(layer "B.Cu")
		(net "PU_CPU1_SOCKET_ID2")
	)
	(arc
		(start 121.430796 -265.803634)
		(mid 121.617994 -265.753491)
		(end 121.805192 -265.803634)
		(width 0.0889)
		(layer "B.Cu")
		(net "PU_CPU1_SOCKET_ID2")
	)
	(arc
		(start 125.564392 -265.803634)
		(mid 125.838591 -265.879469)
		(end 126.115064 -265.81227)
		(width 0.0889)
		(layer "B.Cu")
		(net "PU_CPU1_SOCKET_ID2")
	)
	(arc
		(start 127.443992 -265.803634)
		(mid 127.718191 -265.879469)
		(end 127.994664 -265.81227)
		(width 0.0889)
		(layer "B.Cu")
		(net "PU_CPU1_SOCKET_ID2")
	)
	(arc
		(start 128.949196 -265.803634)
		(mid 129.136394 -265.753491)
		(end 129.323592 -265.803634)
		(width 0.0889)
		(layer "B.Cu")
		(net "PU_CPU1_SOCKET_ID2")
	)
	(arc
		(start 122.744992 -265.803634)
		(mid 123.019191 -265.879469)
		(end 123.295664 -265.81227)
		(width 0.0889)
		(layer "B.Cu")
		(net "PU_CPU1_SOCKET_ID2")
	)
	(arc
		(start 123.684792 -265.803634)
		(mid 123.958991 -265.879469)
		(end 124.235464 -265.81227)
		(width 0.0889)
		(layer "B.Cu")
		(net "PU_CPU1_SOCKET_ID2")
	)
	(arc
		(start 129.888996 -265.803634)
		(mid 130.076194 -265.753491)
		(end 130.263392 -265.803634)
		(width 0.0889)
		(layer "B.Cu")
		(net "PU_CPU1_SOCKET_ID2")
	)
	(arc
		(start 122.370596 -265.803634)
		(mid 122.557794 -265.753491)
		(end 122.744992 -265.803634)
		(width 0.0889)
		(layer "B.Cu")
		(net "PU_CPU1_SOCKET_ID2")
	)
	(segment
		(start 122.088148 -264.77849)
		(end 122.088148 -265.314176)
		(width 0.12954)
		(layer "F.Cu")
		(net "PU_CPU1_SOCKET_ID1")
	)
	(segment
		(start 122.087894 -264.778236)
		(end 122.088148 -264.77849)
		(width 0.12954)
		(layer "F.Cu")
		(net "PU_CPU1_SOCKET_ID1")
	)
	(via
		(at 150.896574 -264.851388)
		(size 0.6604)
		(drill 0.3302)
		(layers "F.Cu" "B.Cu")
		(net "PU_CPU1_SOCKET_ID1")
	)
	(via
		(at 122.088148 -265.314176)
		(size 0.4572)
		(drill 0.2032)
		(layers "F.Cu" "B.Cu")
		(net "PU_CPU1_SOCKET_ID1")
	)
	(segment
		(start 136.776206 -265.562842)
		(end 136.948672 -265.735308)
		(width 0.0889)
		(layer "B.Cu")
		(net "PU_CPU1_SOCKET_ID1")
	)
	(segment
		(start 160.032192 -264.48893)
		(end 161.182812 -265.63955)
		(width 0.12954)
		(layer "B.Cu")
		(net "PU_CPU1_SOCKET_ID1")
	)
	(segment
		(start 170.19778 -256.051812)
		(end 175.075596 -252.791976)
		(width 0.12954)
		(layer "B.Cu")
		(net "PU_CPU1_SOCKET_ID1")
	)
	(segment
		(start 126.034546 -265.638534)
		(end 126.04496 -265.632438)
		(width 0.0889)
		(layer "B.Cu")
		(net "PU_CPU1_SOCKET_ID1")
	)
	(segment
		(start 164.618924 -265.80211)
		(end 167.644572 -265.80211)
		(width 0.12954)
		(layer "B.Cu")
		(net "PU_CPU1_SOCKET_ID1")
	)
	(segment
		(start 137.992866 -265.819382)
		(end 138.47572 -265.819382)
		(width 0.0889)
		(layer "B.Cu")
		(net "PU_CPU1_SOCKET_ID1")
	)
	(segment
		(start 149.998176 -265.749786)
		(end 150.896574 -264.851388)
		(width 0.12954)
		(layer "B.Cu")
		(net "PU_CPU1_SOCKET_ID1")
	)
	(segment
		(start 177.186844 -252.11913)
		(end 177.4444 -251.861574)
		(width 0.12954)
		(layer "B.Cu")
		(net "PU_CPU1_SOCKET_ID1")
	)
	(segment
		(start 133.552692 -265.638534)
		(end 133.563106 -265.632438)
		(width 0.0889)
		(layer "B.Cu")
		(net "PU_CPU1_SOCKET_ID1")
	)
	(segment
		(start 125.094746 -265.638534)
		(end 125.109478 -265.629898)
		(width 0.0889)
		(layer "B.Cu")
		(net "PU_CPU1_SOCKET_ID1")
	)
	(segment
		(start 128.853946 -265.638534)
		(end 128.868678 -265.629898)
		(width 0.0889)
		(layer "B.Cu")
		(net "PU_CPU1_SOCKET_ID1")
	)
	(segment
		(start 176.587658 -252.11913)
		(end 177.186844 -252.11913)
		(width 0.12954)
		(layer "B.Cu")
		(net "PU_CPU1_SOCKET_ID1")
	)
	(segment
		(start 150.896574 -264.851388)
		(end 151.259032 -264.48893)
		(width 0.12954)
		(layer "B.Cu")
		(net "PU_CPU1_SOCKET_ID1")
	)
	(segment
		(start 135.714994 -265.562842)
		(end 136.776206 -265.562842)
		(width 0.0889)
		(layer "B.Cu")
		(net "PU_CPU1_SOCKET_ID1")
	)
	(segment
		(start 164.456364 -265.63955)
		(end 164.618924 -265.80211)
		(width 0.12954)
		(layer "B.Cu")
		(net "PU_CPU1_SOCKET_ID1")
	)
	(segment
		(start 138.545316 -265.749786)
		(end 149.998176 -265.749786)
		(width 0.12954)
		(layer "B.Cu")
		(net "PU_CPU1_SOCKET_ID1")
	)
	(segment
		(start 177.4444 -251.861574)
		(end 177.4444 -250.225306)
		(width 0.12954)
		(layer "B.Cu")
		(net "PU_CPU1_SOCKET_ID1")
	)
	(segment
		(start 178.231038 -249.438668)
		(end 178.231038 -194.918838)
		(width 0.12954)
		(layer "B.Cu")
		(net "PU_CPU1_SOCKET_ID1")
	)
	(segment
		(start 138.47572 -265.819382)
		(end 138.545316 -265.749786)
		(width 0.0889)
		(layer "B.Cu")
		(net "PU_CPU1_SOCKET_ID1")
	)
	(segment
		(start 131.673346 -265.638534)
		(end 131.688078 -265.629898)
		(width 0.0889)
		(layer "B.Cu")
		(net "PU_CPU1_SOCKET_ID1")
	)
	(segment
		(start 178.231038 -194.918838)
		(end 177.123344 -193.811144)
		(width 0.12954)
		(layer "B.Cu")
		(net "PU_CPU1_SOCKET_ID1")
	)
	(segment
		(start 151.259032 -264.48893)
		(end 160.032192 -264.48893)
		(width 0.12954)
		(layer "B.Cu")
		(net "PU_CPU1_SOCKET_ID1")
	)
	(segment
		(start 175.914812 -252.791976)
		(end 176.587658 -252.11913)
		(width 0.12954)
		(layer "B.Cu")
		(net "PU_CPU1_SOCKET_ID1")
	)
	(segment
		(start 124.154946 -265.638534)
		(end 124.169678 -265.629898)
		(width 0.0889)
		(layer "B.Cu")
		(net "PU_CPU1_SOCKET_ID1")
	)
	(segment
		(start 126.974092 -265.638534)
		(end 126.984506 -265.632438)
		(width 0.0889)
		(layer "B.Cu")
		(net "PU_CPU1_SOCKET_ID1")
	)
	(segment
		(start 175.075596 -252.791976)
		(end 175.914812 -252.791976)
		(width 0.12954)
		(layer "B.Cu")
		(net "PU_CPU1_SOCKET_ID1")
	)
	(segment
		(start 168.297098 -257.952494)
		(end 170.19778 -256.051812)
		(width 0.12954)
		(layer "B.Cu")
		(net "PU_CPU1_SOCKET_ID1")
	)
	(segment
		(start 127.914146 -265.638534)
		(end 127.928878 -265.629898)
		(width 0.0889)
		(layer "B.Cu")
		(net "PU_CPU1_SOCKET_ID1")
	)
	(segment
		(start 136.948672 -265.735308)
		(end 137.908792 -265.735308)
		(width 0.0889)
		(layer "B.Cu")
		(net "PU_CPU1_SOCKET_ID1")
	)
	(segment
		(start 134.492746 -265.638534)
		(end 134.507478 -265.629898)
		(width 0.0889)
		(layer "B.Cu")
		(net "PU_CPU1_SOCKET_ID1")
	)
	(segment
		(start 130.733546 -265.638534)
		(end 130.748278 -265.629898)
		(width 0.0889)
		(layer "B.Cu")
		(net "PU_CPU1_SOCKET_ID1")
	)
	(segment
		(start 122.443748 -265.409426)
		(end 122.84075 -265.638534)
		(width 0.0889)
		(layer "B.Cu")
		(net "PU_CPU1_SOCKET_ID1")
	)
	(segment
		(start 177.123344 -193.811144)
		(end 177.123344 -193.099944)
		(width 0.12954)
		(layer "B.Cu")
		(net "PU_CPU1_SOCKET_ID1")
	)
	(segment
		(start 167.644572 -265.80211)
		(end 168.297098 -265.149584)
		(width 0.12954)
		(layer "B.Cu")
		(net "PU_CPU1_SOCKET_ID1")
	)
	(segment
		(start 137.908792 -265.735308)
		(end 137.992866 -265.819382)
		(width 0.0889)
		(layer "B.Cu")
		(net "PU_CPU1_SOCKET_ID1")
	)
	(segment
		(start 129.793746 -265.638534)
		(end 129.808478 -265.629898)
		(width 0.0889)
		(layer "B.Cu")
		(net "PU_CPU1_SOCKET_ID1")
	)
	(segment
		(start 177.4444 -250.225306)
		(end 178.231038 -249.438668)
		(width 0.12954)
		(layer "B.Cu")
		(net "PU_CPU1_SOCKET_ID1")
	)
	(segment
		(start 168.297098 -265.149584)
		(end 168.297098 -257.952494)
		(width 0.12954)
		(layer "B.Cu")
		(net "PU_CPU1_SOCKET_ID1")
	)
	(segment
		(start 123.215146 -265.638534)
		(end 123.229878 -265.629898)
		(width 0.0889)
		(layer "B.Cu")
		(net "PU_CPU1_SOCKET_ID1")
	)
	(segment
		(start 161.182812 -265.63955)
		(end 164.456364 -265.63955)
		(width 0.12954)
		(layer "B.Cu")
		(net "PU_CPU1_SOCKET_ID1")
	)
	(segment
		(start 132.613146 -265.638534)
		(end 132.62356 -265.632438)
		(width 0.0889)
		(layer "B.Cu")
		(net "PU_CPU1_SOCKET_ID1")
	)
	(arc
		(start 129.41935 -265.638534)
		(mid 129.606548 -265.688677)
		(end 129.793746 -265.638534)
		(width 0.0889)
		(layer "B.Cu")
		(net "PU_CPU1_SOCKET_ID1")
	)
	(arc
		(start 124.169678 -265.629898)
		(mid 124.446153 -265.562578)
		(end 124.72035 -265.638534)
		(width 0.0889)
		(layer "B.Cu")
		(net "PU_CPU1_SOCKET_ID1")
	)
	(arc
		(start 127.928878 -265.629898)
		(mid 128.205353 -265.562578)
		(end 128.47955 -265.638534)
		(width 0.0889)
		(layer "B.Cu")
		(net "PU_CPU1_SOCKET_ID1")
	)
	(arc
		(start 132.62356 -265.632438)
		(mid 132.901738 -265.562715)
		(end 133.178296 -265.638534)
		(width 0.0889)
		(layer "B.Cu")
		(net "PU_CPU1_SOCKET_ID1")
	)
	(arc
		(start 132.23875 -265.638534)
		(mid 132.425948 -265.688677)
		(end 132.613146 -265.638534)
		(width 0.0889)
		(layer "B.Cu")
		(net "PU_CPU1_SOCKET_ID1")
	)
	(arc
		(start 133.563106 -265.632438)
		(mid 133.841538 -265.562592)
		(end 134.11835 -265.638534)
		(width 0.0889)
		(layer "B.Cu")
		(net "PU_CPU1_SOCKET_ID1")
	)
	(arc
		(start 122.84075 -265.638534)
		(mid 123.027948 -265.688677)
		(end 123.215146 -265.638534)
		(width 0.0889)
		(layer "B.Cu")
		(net "PU_CPU1_SOCKET_ID1")
	)
	(arc
		(start 131.688078 -265.629898)
		(mid 131.964553 -265.562578)
		(end 132.23875 -265.638534)
		(width 0.0889)
		(layer "B.Cu")
		(net "PU_CPU1_SOCKET_ID1")
	)
	(arc
		(start 130.748278 -265.629898)
		(mid 131.024753 -265.562578)
		(end 131.29895 -265.638534)
		(width 0.0889)
		(layer "B.Cu")
		(net "PU_CPU1_SOCKET_ID1")
	)
	(arc
		(start 129.808478 -265.629898)
		(mid 130.084953 -265.562578)
		(end 130.35915 -265.638534)
		(width 0.0889)
		(layer "B.Cu")
		(net "PU_CPU1_SOCKET_ID1")
	)
	(arc
		(start 134.11835 -265.638534)
		(mid 134.305548 -265.688677)
		(end 134.492746 -265.638534)
		(width 0.0889)
		(layer "B.Cu")
		(net "PU_CPU1_SOCKET_ID1")
	)
	(arc
		(start 122.088148 -265.314176)
		(mid 122.272217 -265.3384)
		(end 122.443748 -265.409426)
		(width 0.0889)
		(layer "B.Cu")
		(net "PU_CPU1_SOCKET_ID1")
	)
	(arc
		(start 131.29895 -265.638534)
		(mid 131.486148 -265.688677)
		(end 131.673346 -265.638534)
		(width 0.0889)
		(layer "B.Cu")
		(net "PU_CPU1_SOCKET_ID1")
	)
	(arc
		(start 124.72035 -265.638534)
		(mid 124.907548 -265.688677)
		(end 125.094746 -265.638534)
		(width 0.0889)
		(layer "B.Cu")
		(net "PU_CPU1_SOCKET_ID1")
	)
	(arc
		(start 126.599696 -265.638534)
		(mid 126.786894 -265.688677)
		(end 126.974092 -265.638534)
		(width 0.0889)
		(layer "B.Cu")
		(net "PU_CPU1_SOCKET_ID1")
	)
	(arc
		(start 133.178296 -265.638534)
		(mid 133.365494 -265.688677)
		(end 133.552692 -265.638534)
		(width 0.0889)
		(layer "B.Cu")
		(net "PU_CPU1_SOCKET_ID1")
	)
	(arc
		(start 123.78055 -265.638534)
		(mid 123.967748 -265.688677)
		(end 124.154946 -265.638534)
		(width 0.0889)
		(layer "B.Cu")
		(net "PU_CPU1_SOCKET_ID1")
	)
	(arc
		(start 128.47955 -265.638534)
		(mid 128.666748 -265.688677)
		(end 128.853946 -265.638534)
		(width 0.0889)
		(layer "B.Cu")
		(net "PU_CPU1_SOCKET_ID1")
	)
	(arc
		(start 128.868678 -265.629898)
		(mid 129.145153 -265.562578)
		(end 129.41935 -265.638534)
		(width 0.0889)
		(layer "B.Cu")
		(net "PU_CPU1_SOCKET_ID1")
	)
	(arc
		(start 127.53975 -265.638534)
		(mid 127.726948 -265.688677)
		(end 127.914146 -265.638534)
		(width 0.0889)
		(layer "B.Cu")
		(net "PU_CPU1_SOCKET_ID1")
	)
	(arc
		(start 126.04496 -265.632438)
		(mid 126.323138 -265.562715)
		(end 126.599696 -265.638534)
		(width 0.0889)
		(layer "B.Cu")
		(net "PU_CPU1_SOCKET_ID1")
	)
	(arc
		(start 135.432546 -265.638534)
		(mid 135.568788 -265.5821)
		(end 135.714994 -265.562842)
		(width 0.0889)
		(layer "B.Cu")
		(net "PU_CPU1_SOCKET_ID1")
	)
	(arc
		(start 130.35915 -265.638534)
		(mid 130.546348 -265.688677)
		(end 130.733546 -265.638534)
		(width 0.0889)
		(layer "B.Cu")
		(net "PU_CPU1_SOCKET_ID1")
	)
	(arc
		(start 123.229878 -265.629898)
		(mid 123.506353 -265.562578)
		(end 123.78055 -265.638534)
		(width 0.0889)
		(layer "B.Cu")
		(net "PU_CPU1_SOCKET_ID1")
	)
	(arc
		(start 125.66015 -265.638534)
		(mid 125.847348 -265.688677)
		(end 126.034546 -265.638534)
		(width 0.0889)
		(layer "B.Cu")
		(net "PU_CPU1_SOCKET_ID1")
	)
	(arc
		(start 135.05815 -265.638534)
		(mid 135.245348 -265.688677)
		(end 135.432546 -265.638534)
		(width 0.0889)
		(layer "B.Cu")
		(net "PU_CPU1_SOCKET_ID1")
	)
	(arc
		(start 134.507478 -265.629898)
		(mid 134.783953 -265.562578)
		(end 135.05815 -265.638534)
		(width 0.0889)
		(layer "B.Cu")
		(net "PU_CPU1_SOCKET_ID1")
	)
	(arc
		(start 125.109478 -265.629898)
		(mid 125.385953 -265.562578)
		(end 125.66015 -265.638534)
		(width 0.0889)
		(layer "B.Cu")
		(net "PU_CPU1_SOCKET_ID1")
	)
	(arc
		(start 126.984506 -265.632438)
		(mid 127.262938 -265.562592)
		(end 127.53975 -265.638534)
		(width 0.0889)
		(layer "B.Cu")
		(net "PU_CPU1_SOCKET_ID1")
	)
	(segment
		(start 121.618248 -263.96442)
		(end 121.617994 -263.964674)
		(width 0.12954)
		(layer "F.Cu")
		(net "PU_CPU1_SOCKET_ID0")
	)
	(segment
		(start 121.617994 -263.964674)
		(end 121.617994 -264.50036)
		(width 0.12954)
		(layer "F.Cu")
		(net "PU_CPU1_SOCKET_ID0")
	)
	(via
		(at 121.617994 -264.50036)
		(size 0.4572)
		(drill 0.2032)
		(layers "F.Cu" "B.Cu")
		(net "PU_CPU1_SOCKET_ID0")
	)
	(via
		(at 147.326858 -263.9314)
		(size 0.6604)
		(drill 0.3302)
		(layers "F.Cu" "B.Cu")
		(net "PU_CPU1_SOCKET_ID0")
	)
	(segment
		(start 125.175264 -264.184638)
		(end 125.189996 -264.176002)
		(width 0.0889)
		(layer "B.Cu")
		(net "PU_CPU1_SOCKET_ID0")
	)
	(segment
		(start 127.994664 -264.184638)
		(end 128.009396 -264.176002)
		(width 0.0889)
		(layer "B.Cu")
		(net "PU_CPU1_SOCKET_ID0")
	)
	(segment
		(start 146.119088 -264.061702)
		(end 146.24939 -263.9314)
		(width 0.12954)
		(layer "B.Cu")
		(net "PU_CPU1_SOCKET_ID0")
	)
	(segment
		(start 175.734218 -250.37669)
		(end 175.734218 -201.540618)
		(width 0.12954)
		(layer "B.Cu")
		(net "PU_CPU1_SOCKET_ID0")
	)
	(segment
		(start 174.647098 -251.16155)
		(end 174.949358 -251.16155)
		(width 0.12954)
		(layer "B.Cu")
		(net "PU_CPU1_SOCKET_ID0")
	)
	(segment
		(start 169.518838 -255.75895)
		(end 173.3042 -253.231904)
		(width 0.12954)
		(layer "B.Cu")
		(net "PU_CPU1_SOCKET_ID0")
	)
	(segment
		(start 148.837904 -263.9314)
		(end 149.679914 -263.08939)
		(width 0.12954)
		(layer "B.Cu")
		(net "PU_CPU1_SOCKET_ID0")
	)
	(segment
		(start 164.428932 -263.98601)
		(end 164.563552 -264.12063)
		(width 0.12954)
		(layer "B.Cu")
		(net "PU_CPU1_SOCKET_ID0")
	)
	(segment
		(start 134.573264 -264.184638)
		(end 134.587996 -264.176002)
		(width 0.0889)
		(layer "B.Cu")
		(net "PU_CPU1_SOCKET_ID0")
	)
	(segment
		(start 130.814064 -264.184638)
		(end 130.828796 -264.176002)
		(width 0.0889)
		(layer "B.Cu")
		(net "PU_CPU1_SOCKET_ID0")
	)
	(segment
		(start 174.949358 -251.16155)
		(end 175.734218 -250.37669)
		(width 0.12954)
		(layer "B.Cu")
		(net "PU_CPU1_SOCKET_ID0")
	)
	(segment
		(start 161.040064 -263.98601)
		(end 164.428932 -263.98601)
		(width 0.12954)
		(layer "B.Cu")
		(net "PU_CPU1_SOCKET_ID0")
	)
	(segment
		(start 167.009318 -258.26847)
		(end 169.518838 -255.75895)
		(width 0.12954)
		(layer "B.Cu")
		(net "PU_CPU1_SOCKET_ID0")
	)
	(segment
		(start 173.3042 -253.231904)
		(end 173.882812 -252.149864)
		(width 0.12954)
		(layer "B.Cu")
		(net "PU_CPU1_SOCKET_ID0")
	)
	(segment
		(start 173.882812 -252.149864)
		(end 173.882812 -251.925836)
		(width 0.12954)
		(layer "B.Cu")
		(net "PU_CPU1_SOCKET_ID0")
	)
	(segment
		(start 136.438894 -264.319766)
		(end 136.681972 -264.319766)
		(width 0.0889)
		(layer "B.Cu")
		(net "PU_CPU1_SOCKET_ID0")
	)
	(segment
		(start 165.622478 -264.12063)
		(end 167.009318 -262.73379)
		(width 0.12954)
		(layer "B.Cu")
		(net "PU_CPU1_SOCKET_ID0")
	)
	(segment
		(start 147.326858 -263.9314)
		(end 148.837904 -263.9314)
		(width 0.12954)
		(layer "B.Cu")
		(net "PU_CPU1_SOCKET_ID0")
	)
	(segment
		(start 149.679914 -263.08939)
		(end 160.143444 -263.08939)
		(width 0.12954)
		(layer "B.Cu")
		(net "PU_CPU1_SOCKET_ID0")
	)
	(segment
		(start 124.235464 -264.184638)
		(end 124.250196 -264.176002)
		(width 0.0889)
		(layer "B.Cu")
		(net "PU_CPU1_SOCKET_ID0")
	)
	(segment
		(start 128.934464 -264.184638)
		(end 128.949196 -264.176002)
		(width 0.0889)
		(layer "B.Cu")
		(net "PU_CPU1_SOCKET_ID0")
	)
	(segment
		(start 173.882812 -251.925836)
		(end 174.647098 -251.16155)
		(width 0.12954)
		(layer "B.Cu")
		(net "PU_CPU1_SOCKET_ID0")
	)
	(segment
		(start 133.637782 -264.182098)
		(end 133.648196 -264.176002)
		(width 0.0889)
		(layer "B.Cu")
		(net "PU_CPU1_SOCKET_ID0")
	)
	(segment
		(start 131.753864 -264.184638)
		(end 131.768596 -264.176002)
		(width 0.0889)
		(layer "B.Cu")
		(net "PU_CPU1_SOCKET_ID0")
	)
	(segment
		(start 138.158982 -264.061702)
		(end 146.119088 -264.061702)
		(width 0.12954)
		(layer "B.Cu")
		(net "PU_CPU1_SOCKET_ID0")
	)
	(segment
		(start 127.059182 -264.182098)
		(end 127.069596 -264.176002)
		(width 0.0889)
		(layer "B.Cu")
		(net "PU_CPU1_SOCKET_ID0")
	)
	(segment
		(start 121.617994 -264.50036)
		(end 121.774458 -264.229342)
		(width 0.0889)
		(layer "B.Cu")
		(net "PU_CPU1_SOCKET_ID0")
	)
	(segment
		(start 121.774458 -264.229342)
		(end 121.863612 -264.205466)
		(width 0.0889)
		(layer "B.Cu")
		(net "PU_CPU1_SOCKET_ID0")
	)
	(segment
		(start 167.009318 -262.73379)
		(end 167.009318 -258.26847)
		(width 0.12954)
		(layer "B.Cu")
		(net "PU_CPU1_SOCKET_ID0")
	)
	(segment
		(start 160.143444 -263.08939)
		(end 161.040064 -263.98601)
		(width 0.12954)
		(layer "B.Cu")
		(net "PU_CPU1_SOCKET_ID0")
	)
	(segment
		(start 175.734218 -201.540618)
		(end 174.997618 -200.804018)
		(width 0.12954)
		(layer "B.Cu")
		(net "PU_CPU1_SOCKET_ID0")
	)
	(segment
		(start 164.563552 -264.12063)
		(end 165.622478 -264.12063)
		(width 0.12954)
		(layer "B.Cu")
		(net "PU_CPU1_SOCKET_ID0")
	)
	(segment
		(start 146.24939 -263.9314)
		(end 147.326858 -263.9314)
		(width 0.12954)
		(layer "B.Cu")
		(net "PU_CPU1_SOCKET_ID0")
	)
	(segment
		(start 122.355864 -264.184638)
		(end 122.370596 -264.176002)
		(width 0.0889)
		(layer "B.Cu")
		(net "PU_CPU1_SOCKET_ID0")
	)
	(segment
		(start 137.900918 -264.319766)
		(end 138.158982 -264.061702)
		(width 0.12954)
		(layer "B.Cu")
		(net "PU_CPU1_SOCKET_ID0")
	)
	(segment
		(start 126.119636 -264.182098)
		(end 126.13005 -264.176002)
		(width 0.0889)
		(layer "B.Cu")
		(net "PU_CPU1_SOCKET_ID0")
	)
	(segment
		(start 136.681972 -264.319766)
		(end 137.900918 -264.319766)
		(width 0.12954)
		(layer "B.Cu")
		(net "PU_CPU1_SOCKET_ID0")
	)
	(segment
		(start 132.698236 -264.182098)
		(end 132.70865 -264.176002)
		(width 0.0889)
		(layer "B.Cu")
		(net "PU_CPU1_SOCKET_ID0")
	)
	(arc
		(start 123.310396 -264.176002)
		(mid 123.497594 -264.125859)
		(end 123.684792 -264.176002)
		(width 0.0889)
		(layer "B.Cu")
		(net "PU_CPU1_SOCKET_ID0")
	)
	(arc
		(start 125.564392 -264.176002)
		(mid 125.841205 -264.251872)
		(end 126.119636 -264.182098)
		(width 0.0889)
		(layer "B.Cu")
		(net "PU_CPU1_SOCKET_ID0")
	)
	(arc
		(start 131.203192 -264.176002)
		(mid 131.477391 -264.251837)
		(end 131.753864 -264.184638)
		(width 0.0889)
		(layer "B.Cu")
		(net "PU_CPU1_SOCKET_ID0")
	)
	(arc
		(start 135.527796 -264.176002)
		(mid 135.714994 -264.125859)
		(end 135.902192 -264.176002)
		(width 0.0889)
		(layer "B.Cu")
		(net "PU_CPU1_SOCKET_ID0")
	)
	(arc
		(start 132.142992 -264.176002)
		(mid 132.419805 -264.251872)
		(end 132.698236 -264.182098)
		(width 0.0889)
		(layer "B.Cu")
		(net "PU_CPU1_SOCKET_ID0")
	)
	(arc
		(start 128.009396 -264.176002)
		(mid 128.196594 -264.125859)
		(end 128.383792 -264.176002)
		(width 0.0889)
		(layer "B.Cu")
		(net "PU_CPU1_SOCKET_ID0")
	)
	(arc
		(start 134.022592 -264.176002)
		(mid 134.296791 -264.251837)
		(end 134.573264 -264.184638)
		(width 0.0889)
		(layer "B.Cu")
		(net "PU_CPU1_SOCKET_ID0")
	)
	(arc
		(start 125.189996 -264.176002)
		(mid 125.377194 -264.125859)
		(end 125.564392 -264.176002)
		(width 0.0889)
		(layer "B.Cu")
		(net "PU_CPU1_SOCKET_ID0")
	)
	(arc
		(start 135.902192 -264.176002)
		(mid 136.161077 -264.283231)
		(end 136.438894 -264.319766)
		(width 0.0889)
		(layer "B.Cu")
		(net "PU_CPU1_SOCKET_ID0")
	)
	(arc
		(start 132.70865 -264.176002)
		(mid 132.895848 -264.125859)
		(end 133.083046 -264.176002)
		(width 0.0889)
		(layer "B.Cu")
		(net "PU_CPU1_SOCKET_ID0")
	)
	(arc
		(start 124.250196 -264.176002)
		(mid 124.437394 -264.125859)
		(end 124.624592 -264.176002)
		(width 0.0889)
		(layer "B.Cu")
		(net "PU_CPU1_SOCKET_ID0")
	)
	(arc
		(start 129.323592 -264.176002)
		(mid 129.606294 -264.251778)
		(end 129.888996 -264.176002)
		(width 0.0889)
		(layer "B.Cu")
		(net "PU_CPU1_SOCKET_ID0")
	)
	(arc
		(start 124.624592 -264.176002)
		(mid 124.898791 -264.251837)
		(end 125.175264 -264.184638)
		(width 0.0889)
		(layer "B.Cu")
		(net "PU_CPU1_SOCKET_ID0")
	)
	(arc
		(start 133.083046 -264.176002)
		(mid 133.359605 -264.251745)
		(end 133.637782 -264.182098)
		(width 0.0889)
		(layer "B.Cu")
		(net "PU_CPU1_SOCKET_ID0")
	)
	(arc
		(start 122.370596 -264.176002)
		(mid 122.557794 -264.125859)
		(end 122.744992 -264.176002)
		(width 0.0889)
		(layer "B.Cu")
		(net "PU_CPU1_SOCKET_ID0")
	)
	(arc
		(start 126.13005 -264.176002)
		(mid 126.317248 -264.125859)
		(end 126.504446 -264.176002)
		(width 0.0889)
		(layer "B.Cu")
		(net "PU_CPU1_SOCKET_ID0")
	)
	(arc
		(start 133.648196 -264.176002)
		(mid 133.835394 -264.125859)
		(end 134.022592 -264.176002)
		(width 0.0889)
		(layer "B.Cu")
		(net "PU_CPU1_SOCKET_ID0")
	)
	(arc
		(start 134.962392 -264.176002)
		(mid 135.245094 -264.251778)
		(end 135.527796 -264.176002)
		(width 0.0889)
		(layer "B.Cu")
		(net "PU_CPU1_SOCKET_ID0")
	)
	(arc
		(start 122.744992 -264.176002)
		(mid 123.027694 -264.251778)
		(end 123.310396 -264.176002)
		(width 0.0889)
		(layer "B.Cu")
		(net "PU_CPU1_SOCKET_ID0")
	)
	(arc
		(start 121.863612 -264.205466)
		(mid 122.112117 -264.251453)
		(end 122.355864 -264.184638)
		(width 0.0889)
		(layer "B.Cu")
		(net "PU_CPU1_SOCKET_ID0")
	)
	(arc
		(start 130.263392 -264.176002)
		(mid 130.537591 -264.251837)
		(end 130.814064 -264.184638)
		(width 0.0889)
		(layer "B.Cu")
		(net "PU_CPU1_SOCKET_ID0")
	)
	(arc
		(start 134.587996 -264.176002)
		(mid 134.775194 -264.125859)
		(end 134.962392 -264.176002)
		(width 0.0889)
		(layer "B.Cu")
		(net "PU_CPU1_SOCKET_ID0")
	)
	(arc
		(start 127.069596 -264.176002)
		(mid 127.256794 -264.125859)
		(end 127.443992 -264.176002)
		(width 0.0889)
		(layer "B.Cu")
		(net "PU_CPU1_SOCKET_ID0")
	)
	(arc
		(start 128.949196 -264.176002)
		(mid 129.136394 -264.125859)
		(end 129.323592 -264.176002)
		(width 0.0889)
		(layer "B.Cu")
		(net "PU_CPU1_SOCKET_ID0")
	)
	(arc
		(start 127.443992 -264.176002)
		(mid 127.718191 -264.251837)
		(end 127.994664 -264.184638)
		(width 0.0889)
		(layer "B.Cu")
		(net "PU_CPU1_SOCKET_ID0")
	)
	(arc
		(start 128.383792 -264.176002)
		(mid 128.657991 -264.251837)
		(end 128.934464 -264.184638)
		(width 0.0889)
		(layer "B.Cu")
		(net "PU_CPU1_SOCKET_ID0")
	)
	(arc
		(start 126.504446 -264.176002)
		(mid 126.781005 -264.251745)
		(end 127.059182 -264.182098)
		(width 0.0889)
		(layer "B.Cu")
		(net "PU_CPU1_SOCKET_ID0")
	)
	(arc
		(start 130.828796 -264.176002)
		(mid 131.015994 -264.125859)
		(end 131.203192 -264.176002)
		(width 0.0889)
		(layer "B.Cu")
		(net "PU_CPU1_SOCKET_ID0")
	)
	(arc
		(start 129.888996 -264.176002)
		(mid 130.076194 -264.125859)
		(end 130.263392 -264.176002)
		(width 0.0889)
		(layer "B.Cu")
		(net "PU_CPU1_SOCKET_ID0")
	)
	(arc
		(start 123.684792 -264.176002)
		(mid 123.958991 -264.251837)
		(end 124.235464 -264.184638)
		(width 0.0889)
		(layer "B.Cu")
		(net "PU_CPU1_SOCKET_ID0")
	)
	(arc
		(start 131.768596 -264.176002)
		(mid 131.955794 -264.125859)
		(end 132.142992 -264.176002)
		(width 0.0889)
		(layer "B.Cu")
		(net "PU_CPU1_SOCKET_ID0")
	)
	(segment
		(start 101.772212 -232.250234)
		(end 101.772212 -231.714548)
		(width 0.12954)
		(layer "F.Cu")
		(net "PU_CPU1_SAFE_MODE_BOOT")
	)
	(segment
		(start 101.772466 -232.250488)
		(end 101.772212 -232.250234)
		(width 0.12954)
		(layer "F.Cu")
		(net "PU_CPU1_SAFE_MODE_BOOT")
	)
	(via
		(at 101.772212 -231.714548)
		(size 0.4572)
		(drill 0.2032)
		(layers "F.Cu" "B.Cu")
		(net "PU_CPU1_SAFE_MODE_BOOT")
	)
	(via
		(at 73.608438 -201.04227)
		(size 0.6604)
		(drill 0.3302)
		(layers "F.Cu" "B.Cu")
		(net "PU_CPU1_SAFE_MODE_BOOT")
	)
	(segment
		(start 97.825814 -232.038906)
		(end 97.811082 -232.03027)
		(width 0.0889)
		(layer "B.Cu")
		(net "PU_CPU1_SAFE_MODE_BOOT")
	)
	(segment
		(start 86.265766 -231.963214)
		(end 84.939378 -231.963214)
		(width 0.0889)
		(layer "B.Cu")
		(net "PU_CPU1_SAFE_MODE_BOOT")
	)
	(segment
		(start 70.893178 -224.71761)
		(end 70.893178 -221.8817)
		(width 0.12954)
		(layer "B.Cu")
		(net "PU_CPU1_SAFE_MODE_BOOT")
	)
	(segment
		(start 70.893178 -221.8817)
		(end 69.566536 -220.555058)
		(width 0.12954)
		(layer "B.Cu")
		(net "PU_CPU1_SAFE_MODE_BOOT")
	)
	(segment
		(start 84.328254 -231.963214)
		(end 83.971638 -232.31983)
		(width 0.12954)
		(layer "B.Cu")
		(net "PU_CPU1_SAFE_MODE_BOOT")
	)
	(segment
		(start 69.566536 -220.555058)
		(end 69.566536 -207.281272)
		(width 0.12954)
		(layer "B.Cu")
		(net "PU_CPU1_SAFE_MODE_BOOT")
	)
	(segment
		(start 76.559918 -189.897258)
		(end 75.460098 -187.24245)
		(width 0.12954)
		(layer "B.Cu")
		(net "PU_CPU1_SAFE_MODE_BOOT")
	)
	(segment
		(start 73.608438 -201.04227)
		(end 74.602086 -200.048622)
		(width 0.12954)
		(layer "B.Cu")
		(net "PU_CPU1_SAFE_MODE_BOOT")
	)
	(segment
		(start 99.705414 -232.038906)
		(end 99.690682 -232.03027)
		(width 0.0889)
		(layer "B.Cu")
		(net "PU_CPU1_SAFE_MODE_BOOT")
	)
	(segment
		(start 78.495398 -232.31983)
		(end 70.893178 -224.71761)
		(width 0.12954)
		(layer "B.Cu")
		(net "PU_CPU1_SAFE_MODE_BOOT")
	)
	(segment
		(start 73.054718 -201.59599)
		(end 73.608438 -201.04227)
		(width 0.12954)
		(layer "B.Cu")
		(net "PU_CPU1_SAFE_MODE_BOOT")
	)
	(segment
		(start 91.247214 -232.038906)
		(end 91.232482 -232.03027)
		(width 0.0889)
		(layer "B.Cu")
		(net "PU_CPU1_SAFE_MODE_BOOT")
	)
	(segment
		(start 73.054718 -202.30973)
		(end 73.054718 -201.59599)
		(width 0.12954)
		(layer "B.Cu")
		(net "PU_CPU1_SAFE_MODE_BOOT")
	)
	(segment
		(start 100.645468 -232.038906)
		(end 100.635054 -232.03281)
		(width 0.0889)
		(layer "B.Cu")
		(net "PU_CPU1_SAFE_MODE_BOOT")
	)
	(segment
		(start 74.602086 -194.419982)
		(end 76.559918 -192.46215)
		(width 0.12954)
		(layer "B.Cu")
		(net "PU_CPU1_SAFE_MODE_BOOT")
	)
	(segment
		(start 83.971638 -232.31983)
		(end 78.495398 -232.31983)
		(width 0.12954)
		(layer "B.Cu")
		(net "PU_CPU1_SAFE_MODE_BOOT")
	)
	(segment
		(start 93.126814 -232.038906)
		(end 93.112082 -232.03027)
		(width 0.0889)
		(layer "B.Cu")
		(net "PU_CPU1_SAFE_MODE_BOOT")
	)
	(segment
		(start 74.602086 -200.048622)
		(end 74.602086 -194.419982)
		(width 0.12954)
		(layer "B.Cu")
		(net "PU_CPU1_SAFE_MODE_BOOT")
	)
	(segment
		(start 89.367614 -232.038906)
		(end 89.352882 -232.03027)
		(width 0.0889)
		(layer "B.Cu")
		(net "PU_CPU1_SAFE_MODE_BOOT")
	)
	(segment
		(start 76.559918 -192.46215)
		(end 76.559918 -189.897258)
		(width 0.12954)
		(layer "B.Cu")
		(net "PU_CPU1_SAFE_MODE_BOOT")
	)
	(segment
		(start 96.886014 -232.038906)
		(end 96.871282 -232.03027)
		(width 0.0889)
		(layer "B.Cu")
		(net "PU_CPU1_SAFE_MODE_BOOT")
	)
	(segment
		(start 101.585014 -232.038906)
		(end 101.5746 -232.03281)
		(width 0.0889)
		(layer "B.Cu")
		(net "PU_CPU1_SAFE_MODE_BOOT")
	)
	(segment
		(start 88.427814 -232.038906)
		(end 88.4174 -232.03281)
		(width 0.0889)
		(layer "B.Cu")
		(net "PU_CPU1_SAFE_MODE_BOOT")
	)
	(segment
		(start 94.066868 -232.038906)
		(end 94.056454 -232.03281)
		(width 0.0889)
		(layer "B.Cu")
		(net "PU_CPU1_SAFE_MODE_BOOT")
	)
	(segment
		(start 95.006414 -232.038906)
		(end 94.996 -232.03281)
		(width 0.0889)
		(layer "B.Cu")
		(net "PU_CPU1_SAFE_MODE_BOOT")
	)
	(segment
		(start 101.772212 -231.714548)
		(end 101.928676 -231.985566)
		(width 0.0889)
		(layer "B.Cu")
		(net "PU_CPU1_SAFE_MODE_BOOT")
	)
	(segment
		(start 90.307414 -232.038906)
		(end 90.292682 -232.03027)
		(width 0.0889)
		(layer "B.Cu")
		(net "PU_CPU1_SAFE_MODE_BOOT")
	)
	(segment
		(start 84.939378 -231.963214)
		(end 84.328254 -231.963214)
		(width 0.12954)
		(layer "B.Cu")
		(net "PU_CPU1_SAFE_MODE_BOOT")
	)
	(segment
		(start 70.68566 -206.162148)
		(end 70.68566 -204.678788)
		(width 0.12954)
		(layer "B.Cu")
		(net "PU_CPU1_SAFE_MODE_BOOT")
	)
	(segment
		(start 69.566536 -207.281272)
		(end 70.68566 -206.162148)
		(width 0.12954)
		(layer "B.Cu")
		(net "PU_CPU1_SAFE_MODE_BOOT")
	)
	(segment
		(start 75.460098 -187.24245)
		(end 75.460098 -184.655968)
		(width 0.12954)
		(layer "B.Cu")
		(net "PU_CPU1_SAFE_MODE_BOOT")
	)
	(segment
		(start 101.928676 -231.985566)
		(end 101.907594 -232.063544)
		(width 0.0889)
		(layer "B.Cu")
		(net "PU_CPU1_SAFE_MODE_BOOT")
	)
	(segment
		(start 95.946214 -232.038906)
		(end 95.931482 -232.03027)
		(width 0.0889)
		(layer "B.Cu")
		(net "PU_CPU1_SAFE_MODE_BOOT")
	)
	(segment
		(start 70.68566 -204.678788)
		(end 73.054718 -202.30973)
		(width 0.12954)
		(layer "B.Cu")
		(net "PU_CPU1_SAFE_MODE_BOOT")
	)
	(arc
		(start 89.74201 -232.038906)
		(mid 89.554812 -232.089049)
		(end 89.367614 -232.038906)
		(width 0.0889)
		(layer "B.Cu")
		(net "PU_CPU1_SAFE_MODE_BOOT")
	)
	(arc
		(start 100.07981 -232.038906)
		(mid 99.892612 -232.089049)
		(end 99.705414 -232.038906)
		(width 0.0889)
		(layer "B.Cu")
		(net "PU_CPU1_SAFE_MODE_BOOT")
	)
	(arc
		(start 91.232482 -232.03027)
		(mid 90.956007 -231.96295)
		(end 90.68181 -232.038906)
		(width 0.0889)
		(layer "B.Cu")
		(net "PU_CPU1_SAFE_MODE_BOOT")
	)
	(arc
		(start 96.32061 -232.038906)
		(mid 96.133412 -232.089049)
		(end 95.946214 -232.038906)
		(width 0.0889)
		(layer "B.Cu")
		(net "PU_CPU1_SAFE_MODE_BOOT")
	)
	(arc
		(start 98.765614 -232.038906)
		(mid 98.482912 -231.96313)
		(end 98.20021 -232.038906)
		(width 0.0889)
		(layer "B.Cu")
		(net "PU_CPU1_SAFE_MODE_BOOT")
	)
	(arc
		(start 90.68181 -232.038906)
		(mid 90.494612 -232.089049)
		(end 90.307414 -232.038906)
		(width 0.0889)
		(layer "B.Cu")
		(net "PU_CPU1_SAFE_MODE_BOOT")
	)
	(arc
		(start 92.187014 -232.038906)
		(mid 91.904312 -231.96313)
		(end 91.62161 -232.038906)
		(width 0.0889)
		(layer "B.Cu")
		(net "PU_CPU1_SAFE_MODE_BOOT")
	)
	(arc
		(start 95.38081 -232.038906)
		(mid 95.193612 -232.089049)
		(end 95.006414 -232.038906)
		(width 0.0889)
		(layer "B.Cu")
		(net "PU_CPU1_SAFE_MODE_BOOT")
	)
	(arc
		(start 87.862664 -232.038906)
		(mid 87.675466 -232.089049)
		(end 87.488268 -232.038906)
		(width 0.0889)
		(layer "B.Cu")
		(net "PU_CPU1_SAFE_MODE_BOOT")
	)
	(arc
		(start 94.996 -232.03281)
		(mid 94.717822 -231.963087)
		(end 94.441264 -232.038906)
		(width 0.0889)
		(layer "B.Cu")
		(net "PU_CPU1_SAFE_MODE_BOOT")
	)
	(arc
		(start 87.488268 -232.038906)
		(mid 87.205566 -231.96313)
		(end 86.922864 -232.038906)
		(width 0.0889)
		(layer "B.Cu")
		(net "PU_CPU1_SAFE_MODE_BOOT")
	)
	(arc
		(start 101.5746 -232.03281)
		(mid 101.296422 -231.963087)
		(end 101.019864 -232.038906)
		(width 0.0889)
		(layer "B.Cu")
		(net "PU_CPU1_SAFE_MODE_BOOT")
	)
	(arc
		(start 97.811082 -232.03027)
		(mid 97.534607 -231.96295)
		(end 97.26041 -232.038906)
		(width 0.0889)
		(layer "B.Cu")
		(net "PU_CPU1_SAFE_MODE_BOOT")
	)
	(arc
		(start 101.907594 -232.063544)
		(mid 101.743498 -232.087891)
		(end 101.585014 -232.038906)
		(width 0.0889)
		(layer "B.Cu")
		(net "PU_CPU1_SAFE_MODE_BOOT")
	)
	(arc
		(start 96.871282 -232.03027)
		(mid 96.594807 -231.96295)
		(end 96.32061 -232.038906)
		(width 0.0889)
		(layer "B.Cu")
		(net "PU_CPU1_SAFE_MODE_BOOT")
	)
	(arc
		(start 97.26041 -232.038906)
		(mid 97.073212 -232.089049)
		(end 96.886014 -232.038906)
		(width 0.0889)
		(layer "B.Cu")
		(net "PU_CPU1_SAFE_MODE_BOOT")
	)
	(arc
		(start 100.635054 -232.03281)
		(mid 100.356622 -231.962964)
		(end 100.07981 -232.038906)
		(width 0.0889)
		(layer "B.Cu")
		(net "PU_CPU1_SAFE_MODE_BOOT")
	)
	(arc
		(start 86.548468 -232.038906)
		(mid 86.412099 -231.982464)
		(end 86.265766 -231.963214)
		(width 0.0889)
		(layer "B.Cu")
		(net "PU_CPU1_SAFE_MODE_BOOT")
	)
	(arc
		(start 90.292682 -232.03027)
		(mid 90.016207 -231.96295)
		(end 89.74201 -232.038906)
		(width 0.0889)
		(layer "B.Cu")
		(net "PU_CPU1_SAFE_MODE_BOOT")
	)
	(arc
		(start 92.56141 -232.038906)
		(mid 92.374212 -232.089049)
		(end 92.187014 -232.038906)
		(width 0.0889)
		(layer "B.Cu")
		(net "PU_CPU1_SAFE_MODE_BOOT")
	)
	(arc
		(start 99.14001 -232.038906)
		(mid 98.952812 -232.089049)
		(end 98.765614 -232.038906)
		(width 0.0889)
		(layer "B.Cu")
		(net "PU_CPU1_SAFE_MODE_BOOT")
	)
	(arc
		(start 86.922864 -232.038906)
		(mid 86.735666 -232.089049)
		(end 86.548468 -232.038906)
		(width 0.0889)
		(layer "B.Cu")
		(net "PU_CPU1_SAFE_MODE_BOOT")
	)
	(arc
		(start 101.019864 -232.038906)
		(mid 100.832666 -232.089049)
		(end 100.645468 -232.038906)
		(width 0.0889)
		(layer "B.Cu")
		(net "PU_CPU1_SAFE_MODE_BOOT")
	)
	(arc
		(start 94.056454 -232.03281)
		(mid 93.778022 -231.962964)
		(end 93.50121 -232.038906)
		(width 0.0889)
		(layer "B.Cu")
		(net "PU_CPU1_SAFE_MODE_BOOT")
	)
	(arc
		(start 93.112082 -232.03027)
		(mid 92.835607 -231.96295)
		(end 92.56141 -232.038906)
		(width 0.0889)
		(layer "B.Cu")
		(net "PU_CPU1_SAFE_MODE_BOOT")
	)
	(arc
		(start 88.4174 -232.03281)
		(mid 88.139222 -231.963087)
		(end 87.862664 -232.038906)
		(width 0.0889)
		(layer "B.Cu")
		(net "PU_CPU1_SAFE_MODE_BOOT")
	)
	(arc
		(start 91.62161 -232.038906)
		(mid 91.434412 -232.089049)
		(end 91.247214 -232.038906)
		(width 0.0889)
		(layer "B.Cu")
		(net "PU_CPU1_SAFE_MODE_BOOT")
	)
	(arc
		(start 89.352882 -232.03027)
		(mid 89.076407 -231.96295)
		(end 88.80221 -232.038906)
		(width 0.0889)
		(layer "B.Cu")
		(net "PU_CPU1_SAFE_MODE_BOOT")
	)
	(arc
		(start 88.80221 -232.038906)
		(mid 88.615012 -232.089049)
		(end 88.427814 -232.038906)
		(width 0.0889)
		(layer "B.Cu")
		(net "PU_CPU1_SAFE_MODE_BOOT")
	)
	(arc
		(start 95.931482 -232.03027)
		(mid 95.655007 -231.96295)
		(end 95.38081 -232.038906)
		(width 0.0889)
		(layer "B.Cu")
		(net "PU_CPU1_SAFE_MODE_BOOT")
	)
	(arc
		(start 98.20021 -232.038906)
		(mid 98.013012 -232.089049)
		(end 97.825814 -232.038906)
		(width 0.0889)
		(layer "B.Cu")
		(net "PU_CPU1_SAFE_MODE_BOOT")
	)
	(arc
		(start 99.690682 -232.03027)
		(mid 99.414207 -231.96295)
		(end 99.14001 -232.038906)
		(width 0.0889)
		(layer "B.Cu")
		(net "PU_CPU1_SAFE_MODE_BOOT")
	)
	(arc
		(start 94.441264 -232.038906)
		(mid 94.254066 -232.089049)
		(end 94.066868 -232.038906)
		(width 0.0889)
		(layer "B.Cu")
		(net "PU_CPU1_SAFE_MODE_BOOT")
	)
	(arc
		(start 93.50121 -232.038906)
		(mid 93.314012 -232.089049)
		(end 93.126814 -232.038906)
		(width 0.0889)
		(layer "B.Cu")
		(net "PU_CPU1_SAFE_MODE_BOOT")
	)
	(segment
		(start 122.087894 -263.150604)
		(end 122.087894 -263.68629)
		(width 0.12954)
		(layer "F.Cu")
		(net "PU_CPU1_LEGACY_SKT")
	)
	(segment
		(start 122.087894 -263.68629)
		(end 122.088148 -263.686544)
		(width 0.12954)
		(layer "F.Cu")
		(net "PU_CPU1_LEGACY_SKT")
	)
	(via
		(at 122.088148 -263.686544)
		(size 0.4572)
		(drill 0.2032)
		(layers "F.Cu" "B.Cu")
		(net "PU_CPU1_LEGACY_SKT")
	)
	(via
		(at 141.262354 -263.51611)
		(size 0.6604)
		(drill 0.3302)
		(layers "F.Cu" "B.Cu")
		(net "PU_CPU1_LEGACY_SKT")
	)
	(segment
		(start 146.131534 -263.51611)
		(end 146.840194 -262.80745)
		(width 0.12954)
		(layer "B.Cu")
		(net "PU_CPU1_LEGACY_SKT")
	)
	(segment
		(start 160.560512 -262.80745)
		(end 161.431732 -263.67867)
		(width 0.12954)
		(layer "B.Cu")
		(net "PU_CPU1_LEGACY_SKT")
	)
	(segment
		(start 137.68578 -264.039858)
		(end 137.992612 -263.733026)
		(width 0.12954)
		(layer "B.Cu")
		(net "PU_CPU1_LEGACY_SKT")
	)
	(segment
		(start 121.931684 -263.957562)
		(end 121.952766 -264.03554)
		(width 0.0889)
		(layer "B.Cu")
		(net "PU_CPU1_LEGACY_SKT")
	)
	(segment
		(start 173.018196 -252.993652)
		(end 173.326552 -252.416056)
		(width 0.12954)
		(layer "B.Cu")
		(net "PU_CPU1_LEGACY_SKT")
	)
	(segment
		(start 125.094746 -264.010902)
		(end 125.109478 -264.002266)
		(width 0.0889)
		(layer "B.Cu")
		(net "PU_CPU1_LEGACY_SKT")
	)
	(segment
		(start 130.733546 -264.010902)
		(end 130.748278 -264.002266)
		(width 0.0889)
		(layer "B.Cu")
		(net "PU_CPU1_LEGACY_SKT")
	)
	(segment
		(start 129.793492 -264.010902)
		(end 129.803906 -264.004806)
		(width 0.0889)
		(layer "B.Cu")
		(net "PU_CPU1_LEGACY_SKT")
	)
	(segment
		(start 164.464238 -263.67867)
		(end 165.172898 -262.97001)
		(width 0.12954)
		(layer "B.Cu")
		(net "PU_CPU1_LEGACY_SKT")
	)
	(segment
		(start 122.275346 -264.010902)
		(end 122.28576 -264.004806)
		(width 0.0889)
		(layer "B.Cu")
		(net "PU_CPU1_LEGACY_SKT")
	)
	(segment
		(start 137.992612 -263.733026)
		(end 140.136372 -263.733026)
		(width 0.12954)
		(layer "B.Cu")
		(net "PU_CPU1_LEGACY_SKT")
	)
	(segment
		(start 141.262354 -263.51611)
		(end 146.131534 -263.51611)
		(width 0.12954)
		(layer "B.Cu")
		(net "PU_CPU1_LEGACY_SKT")
	)
	(segment
		(start 166.727378 -258.08559)
		(end 169.397934 -255.415034)
		(width 0.12954)
		(layer "B.Cu")
		(net "PU_CPU1_LEGACY_SKT")
	)
	(segment
		(start 122.088148 -263.686544)
		(end 121.931684 -263.957562)
		(width 0.0889)
		(layer "B.Cu")
		(net "PU_CPU1_LEGACY_SKT")
	)
	(segment
		(start 174.458884 -250.63577)
		(end 174.458884 -198.528432)
		(width 0.12954)
		(layer "B.Cu")
		(net "PU_CPU1_LEGACY_SKT")
	)
	(segment
		(start 174.458884 -198.528432)
		(end 174.873158 -198.114158)
		(width 0.12954)
		(layer "B.Cu")
		(net "PU_CPU1_LEGACY_SKT")
	)
	(segment
		(start 137.66419 -264.061448)
		(end 137.68578 -264.039858)
		(width 0.0889)
		(layer "B.Cu")
		(net "PU_CPU1_LEGACY_SKT")
	)
	(segment
		(start 166.727378 -262.00735)
		(end 166.727378 -258.08559)
		(width 0.12954)
		(layer "B.Cu")
		(net "PU_CPU1_LEGACY_SKT")
	)
	(segment
		(start 140.353288 -263.51611)
		(end 141.262354 -263.51611)
		(width 0.12954)
		(layer "B.Cu")
		(net "PU_CPU1_LEGACY_SKT")
	)
	(segment
		(start 146.840194 -262.80745)
		(end 160.560512 -262.80745)
		(width 0.12954)
		(layer "B.Cu")
		(net "PU_CPU1_LEGACY_SKT")
	)
	(segment
		(start 140.136372 -263.733026)
		(end 140.353288 -263.51611)
		(width 0.12954)
		(layer "B.Cu")
		(net "PU_CPU1_LEGACY_SKT")
	)
	(segment
		(start 165.172898 -262.97001)
		(end 165.764718 -262.97001)
		(width 0.12954)
		(layer "B.Cu")
		(net "PU_CPU1_LEGACY_SKT")
	)
	(segment
		(start 126.974346 -264.010902)
		(end 126.989078 -264.002266)
		(width 0.0889)
		(layer "B.Cu")
		(net "PU_CPU1_LEGACY_SKT")
	)
	(segment
		(start 123.214892 -264.010902)
		(end 123.225306 -264.004806)
		(width 0.0889)
		(layer "B.Cu")
		(net "PU_CPU1_LEGACY_SKT")
	)
	(segment
		(start 173.326552 -251.768102)
		(end 174.458884 -250.63577)
		(width 0.12954)
		(layer "B.Cu")
		(net "PU_CPU1_LEGACY_SKT")
	)
	(segment
		(start 169.397934 -255.415034)
		(end 173.018196 -252.993652)
		(width 0.12954)
		(layer "B.Cu")
		(net "PU_CPU1_LEGACY_SKT")
	)
	(segment
		(start 136.184894 -264.061448)
		(end 137.66419 -264.061448)
		(width 0.0889)
		(layer "B.Cu")
		(net "PU_CPU1_LEGACY_SKT")
	)
	(segment
		(start 131.673346 -264.010902)
		(end 131.688078 -264.002266)
		(width 0.0889)
		(layer "B.Cu")
		(net "PU_CPU1_LEGACY_SKT")
	)
	(segment
		(start 161.431732 -263.67867)
		(end 164.464238 -263.67867)
		(width 0.12954)
		(layer "B.Cu")
		(net "PU_CPU1_LEGACY_SKT")
	)
	(segment
		(start 173.326552 -252.416056)
		(end 173.326552 -251.768102)
		(width 0.12954)
		(layer "B.Cu")
		(net "PU_CPU1_LEGACY_SKT")
	)
	(segment
		(start 133.552946 -264.010902)
		(end 133.567678 -264.002266)
		(width 0.0889)
		(layer "B.Cu")
		(net "PU_CPU1_LEGACY_SKT")
	)
	(segment
		(start 165.764718 -262.97001)
		(end 166.727378 -262.00735)
		(width 0.12954)
		(layer "B.Cu")
		(net "PU_CPU1_LEGACY_SKT")
	)
	(segment
		(start 128.853946 -264.010902)
		(end 128.86436 -264.004806)
		(width 0.0889)
		(layer "B.Cu")
		(net "PU_CPU1_LEGACY_SKT")
	)
	(segment
		(start 134.492746 -264.010902)
		(end 134.50316 -264.004806)
		(width 0.0889)
		(layer "B.Cu")
		(net "PU_CPU1_LEGACY_SKT")
	)
	(segment
		(start 127.914146 -264.010902)
		(end 127.928878 -264.002266)
		(width 0.0889)
		(layer "B.Cu")
		(net "PU_CPU1_LEGACY_SKT")
	)
	(segment
		(start 124.154946 -264.010902)
		(end 124.169678 -264.002266)
		(width 0.0889)
		(layer "B.Cu")
		(net "PU_CPU1_LEGACY_SKT")
	)
	(arc
		(start 134.11835 -264.010902)
		(mid 134.305548 -264.061045)
		(end 134.492746 -264.010902)
		(width 0.0889)
		(layer "B.Cu")
		(net "PU_CPU1_LEGACY_SKT")
	)
	(arc
		(start 122.28576 -264.004806)
		(mid 122.563938 -263.935083)
		(end 122.840496 -264.010902)
		(width 0.0889)
		(layer "B.Cu")
		(net "PU_CPU1_LEGACY_SKT")
	)
	(arc
		(start 135.057896 -264.010902)
		(mid 135.245094 -264.061045)
		(end 135.432292 -264.010902)
		(width 0.0889)
		(layer "B.Cu")
		(net "PU_CPU1_LEGACY_SKT")
	)
	(arc
		(start 124.169678 -264.002266)
		(mid 124.446153 -263.934946)
		(end 124.72035 -264.010902)
		(width 0.0889)
		(layer "B.Cu")
		(net "PU_CPU1_LEGACY_SKT")
	)
	(arc
		(start 125.66015 -264.010902)
		(mid 125.847348 -264.061045)
		(end 126.034546 -264.010902)
		(width 0.0889)
		(layer "B.Cu")
		(net "PU_CPU1_LEGACY_SKT")
	)
	(arc
		(start 133.567678 -264.002266)
		(mid 133.844153 -263.934946)
		(end 134.11835 -264.010902)
		(width 0.0889)
		(layer "B.Cu")
		(net "PU_CPU1_LEGACY_SKT")
	)
	(arc
		(start 126.989078 -264.002266)
		(mid 127.265553 -263.934946)
		(end 127.53975 -264.010902)
		(width 0.0889)
		(layer "B.Cu")
		(net "PU_CPU1_LEGACY_SKT")
	)
	(arc
		(start 130.748278 -264.002266)
		(mid 131.024753 -263.934946)
		(end 131.29895 -264.010902)
		(width 0.0889)
		(layer "B.Cu")
		(net "PU_CPU1_LEGACY_SKT")
	)
	(arc
		(start 133.17855 -264.010902)
		(mid 133.365748 -264.061045)
		(end 133.552946 -264.010902)
		(width 0.0889)
		(layer "B.Cu")
		(net "PU_CPU1_LEGACY_SKT")
	)
	(arc
		(start 131.688078 -264.002266)
		(mid 131.964553 -263.934946)
		(end 132.23875 -264.010902)
		(width 0.0889)
		(layer "B.Cu")
		(net "PU_CPU1_LEGACY_SKT")
	)
	(arc
		(start 127.928878 -264.002266)
		(mid 128.205353 -263.934946)
		(end 128.47955 -264.010902)
		(width 0.0889)
		(layer "B.Cu")
		(net "PU_CPU1_LEGACY_SKT")
	)
	(arc
		(start 126.59995 -264.010902)
		(mid 126.787148 -264.061045)
		(end 126.974346 -264.010902)
		(width 0.0889)
		(layer "B.Cu")
		(net "PU_CPU1_LEGACY_SKT")
	)
	(arc
		(start 135.997696 -264.010902)
		(mid 136.087968 -264.048501)
		(end 136.184894 -264.061448)
		(width 0.0889)
		(layer "B.Cu")
		(net "PU_CPU1_LEGACY_SKT")
	)
	(arc
		(start 132.613146 -264.010902)
		(mid 132.895848 -263.935126)
		(end 133.17855 -264.010902)
		(width 0.0889)
		(layer "B.Cu")
		(net "PU_CPU1_LEGACY_SKT")
	)
	(arc
		(start 131.29895 -264.010902)
		(mid 131.486148 -264.061045)
		(end 131.673346 -264.010902)
		(width 0.0889)
		(layer "B.Cu")
		(net "PU_CPU1_LEGACY_SKT")
	)
	(arc
		(start 127.53975 -264.010902)
		(mid 127.726948 -264.061045)
		(end 127.914146 -264.010902)
		(width 0.0889)
		(layer "B.Cu")
		(net "PU_CPU1_LEGACY_SKT")
	)
	(arc
		(start 121.952766 -264.03554)
		(mid 122.116862 -264.059887)
		(end 122.275346 -264.010902)
		(width 0.0889)
		(layer "B.Cu")
		(net "PU_CPU1_LEGACY_SKT")
	)
	(arc
		(start 123.78055 -264.010902)
		(mid 123.967748 -264.061045)
		(end 124.154946 -264.010902)
		(width 0.0889)
		(layer "B.Cu")
		(net "PU_CPU1_LEGACY_SKT")
	)
	(arc
		(start 122.840496 -264.010902)
		(mid 123.027694 -264.061045)
		(end 123.214892 -264.010902)
		(width 0.0889)
		(layer "B.Cu")
		(net "PU_CPU1_LEGACY_SKT")
	)
	(arc
		(start 126.034546 -264.010902)
		(mid 126.317248 -263.935126)
		(end 126.59995 -264.010902)
		(width 0.0889)
		(layer "B.Cu")
		(net "PU_CPU1_LEGACY_SKT")
	)
	(arc
		(start 129.419096 -264.010902)
		(mid 129.606294 -264.061045)
		(end 129.793492 -264.010902)
		(width 0.0889)
		(layer "B.Cu")
		(net "PU_CPU1_LEGACY_SKT")
	)
	(arc
		(start 128.86436 -264.004806)
		(mid 129.142538 -263.935083)
		(end 129.419096 -264.010902)
		(width 0.0889)
		(layer "B.Cu")
		(net "PU_CPU1_LEGACY_SKT")
	)
	(arc
		(start 123.225306 -264.004806)
		(mid 123.503738 -263.93496)
		(end 123.78055 -264.010902)
		(width 0.0889)
		(layer "B.Cu")
		(net "PU_CPU1_LEGACY_SKT")
	)
	(arc
		(start 134.50316 -264.004806)
		(mid 134.781338 -263.935083)
		(end 135.057896 -264.010902)
		(width 0.0889)
		(layer "B.Cu")
		(net "PU_CPU1_LEGACY_SKT")
	)
	(arc
		(start 124.72035 -264.010902)
		(mid 124.907548 -264.061045)
		(end 125.094746 -264.010902)
		(width 0.0889)
		(layer "B.Cu")
		(net "PU_CPU1_LEGACY_SKT")
	)
	(arc
		(start 130.35915 -264.010902)
		(mid 130.546348 -264.061045)
		(end 130.733546 -264.010902)
		(width 0.0889)
		(layer "B.Cu")
		(net "PU_CPU1_LEGACY_SKT")
	)
	(arc
		(start 135.432292 -264.010902)
		(mid 135.714994 -263.935126)
		(end 135.997696 -264.010902)
		(width 0.0889)
		(layer "B.Cu")
		(net "PU_CPU1_LEGACY_SKT")
	)
	(arc
		(start 132.23875 -264.010902)
		(mid 132.425948 -264.061045)
		(end 132.613146 -264.010902)
		(width 0.0889)
		(layer "B.Cu")
		(net "PU_CPU1_LEGACY_SKT")
	)
	(arc
		(start 125.109478 -264.002266)
		(mid 125.385953 -263.934946)
		(end 125.66015 -264.010902)
		(width 0.0889)
		(layer "B.Cu")
		(net "PU_CPU1_LEGACY_SKT")
	)
	(arc
		(start 128.47955 -264.010902)
		(mid 128.666748 -264.061045)
		(end 128.853946 -264.010902)
		(width 0.0889)
		(layer "B.Cu")
		(net "PU_CPU1_LEGACY_SKT")
	)
	(arc
		(start 129.803906 -264.004806)
		(mid 130.082338 -263.93496)
		(end 130.35915 -264.010902)
		(width 0.0889)
		(layer "B.Cu")
		(net "PU_CPU1_LEGACY_SKT")
	)
	(segment
		(start 101.772466 -227.367084)
		(end 101.772212 -227.36683)
		(width 0.12954)
		(layer "F.Cu")
		(net "PU_CPU1_FRMAGENT")
	)
	(segment
		(start 101.772212 -227.36683)
		(end 101.772212 -226.831144)
		(width 0.12954)
		(layer "F.Cu")
		(net "PU_CPU1_FRMAGENT")
	)
	(via
		(at 80.353916 -206.290164)
		(size 0.6604)
		(drill 0.3302)
		(layers "F.Cu" "B.Cu")
		(net "PU_CPU1_FRMAGENT")
	)
	(via
		(at 101.772212 -226.831144)
		(size 0.4572)
		(drill 0.2032)
		(layers "F.Cu" "B.Cu")
		(net "PU_CPU1_FRMAGENT")
	)
	(segment
		(start 96.886014 -227.155502)
		(end 96.8756 -227.149406)
		(width 0.0889)
		(layer "B.Cu")
		(net "PU_CPU1_FRMAGENT")
	)
	(segment
		(start 78.811628 -207.832452)
		(end 80.353916 -206.290164)
		(width 0.12954)
		(layer "B.Cu")
		(net "PU_CPU1_FRMAGENT")
	)
	(segment
		(start 101.615748 -227.102162)
		(end 101.526848 -227.125784)
		(width 0.0889)
		(layer "B.Cu")
		(net "PU_CPU1_FRMAGENT")
	)
	(segment
		(start 81.543144 -205.100936)
		(end 81.543144 -199.4789)
		(width 0.12954)
		(layer "B.Cu")
		(net "PU_CPU1_FRMAGENT")
	)
	(segment
		(start 78.811628 -222.030036)
		(end 78.811628 -207.832452)
		(width 0.12954)
		(layer "B.Cu")
		(net "PU_CPU1_FRMAGENT")
	)
	(segment
		(start 80.353916 -206.290164)
		(end 81.543144 -205.100936)
		(width 0.12954)
		(layer "B.Cu")
		(net "PU_CPU1_FRMAGENT")
	)
	(segment
		(start 83.5025 -226.720908)
		(end 78.811628 -222.030036)
		(width 0.12954)
		(layer "B.Cu")
		(net "PU_CPU1_FRMAGENT")
	)
	(segment
		(start 95.006414 -227.155502)
		(end 94.991682 -227.146866)
		(width 0.0889)
		(layer "B.Cu")
		(net "PU_CPU1_FRMAGENT")
	)
	(segment
		(start 91.247468 -227.155502)
		(end 91.237054 -227.149406)
		(width 0.0889)
		(layer "B.Cu")
		(net "PU_CPU1_FRMAGENT")
	)
	(segment
		(start 90.307414 -227.155502)
		(end 90.292682 -227.146866)
		(width 0.0889)
		(layer "B.Cu")
		(net "PU_CPU1_FRMAGENT")
	)
	(segment
		(start 91.632278 -227.149406)
		(end 91.621864 -227.155502)
		(width 0.0889)
		(layer "B.Cu")
		(net "PU_CPU1_FRMAGENT")
	)
	(segment
		(start 83.67776 -226.720908)
		(end 83.5025 -226.720908)
		(width 0.12954)
		(layer "B.Cu")
		(net "PU_CPU1_FRMAGENT")
	)
	(segment
		(start 82.405982 -198.616062)
		(end 82.405982 -189.112144)
		(width 0.12954)
		(layer "B.Cu")
		(net "PU_CPU1_FRMAGENT")
	)
	(segment
		(start 89.367614 -227.155502)
		(end 89.352882 -227.146866)
		(width 0.0889)
		(layer "B.Cu")
		(net "PU_CPU1_FRMAGENT")
	)
	(segment
		(start 84.162392 -227.20554)
		(end 83.67776 -226.720908)
		(width 0.0889)
		(layer "B.Cu")
		(net "PU_CPU1_FRMAGENT")
	)
	(segment
		(start 100.645214 -227.155502)
		(end 100.630482 -227.146866)
		(width 0.0889)
		(layer "B.Cu")
		(net "PU_CPU1_FRMAGENT")
	)
	(segment
		(start 98.765868 -227.155502)
		(end 98.755454 -227.149406)
		(width 0.0889)
		(layer "B.Cu")
		(net "PU_CPU1_FRMAGENT")
	)
	(segment
		(start 84.855812 -227.20554)
		(end 84.162392 -227.20554)
		(width 0.0889)
		(layer "B.Cu")
		(net "PU_CPU1_FRMAGENT")
	)
	(segment
		(start 93.126814 -227.155502)
		(end 93.112082 -227.146866)
		(width 0.0889)
		(layer "B.Cu")
		(net "PU_CPU1_FRMAGENT")
	)
	(segment
		(start 88.427814 -227.155502)
		(end 88.4174 -227.149406)
		(width 0.0889)
		(layer "B.Cu")
		(net "PU_CPU1_FRMAGENT")
	)
	(segment
		(start 86.548214 -227.155502)
		(end 86.5378 -227.149406)
		(width 0.0889)
		(layer "B.Cu")
		(net "PU_CPU1_FRMAGENT")
	)
	(segment
		(start 86.933024 -227.149406)
		(end 86.92261 -227.155502)
		(width 0.0889)
		(layer "B.Cu")
		(net "PU_CPU1_FRMAGENT")
	)
	(segment
		(start 101.772212 -226.831144)
		(end 101.615748 -227.102162)
		(width 0.0889)
		(layer "B.Cu")
		(net "PU_CPU1_FRMAGENT")
	)
	(segment
		(start 85.053424 -227.149406)
		(end 85.04301 -227.155502)
		(width 0.0889)
		(layer "B.Cu")
		(net "PU_CPU1_FRMAGENT")
	)
	(segment
		(start 95.946468 -227.155502)
		(end 95.936054 -227.149406)
		(width 0.0889)
		(layer "B.Cu")
		(net "PU_CPU1_FRMAGENT")
	)
	(segment
		(start 81.543144 -199.4789)
		(end 82.405982 -198.616062)
		(width 0.12954)
		(layer "B.Cu")
		(net "PU_CPU1_FRMAGENT")
	)
	(segment
		(start 82.405982 -189.112144)
		(end 83.082384 -188.435742)
		(width 0.12954)
		(layer "B.Cu")
		(net "PU_CPU1_FRMAGENT")
	)
	(segment
		(start 94.066614 -227.155502)
		(end 94.051882 -227.146866)
		(width 0.0889)
		(layer "B.Cu")
		(net "PU_CPU1_FRMAGENT")
	)
	(segment
		(start 99.150678 -227.149406)
		(end 99.140264 -227.155502)
		(width 0.0889)
		(layer "B.Cu")
		(net "PU_CPU1_FRMAGENT")
	)
	(segment
		(start 97.825814 -227.155502)
		(end 97.811082 -227.146866)
		(width 0.0889)
		(layer "B.Cu")
		(net "PU_CPU1_FRMAGENT")
	)
	(arc
		(start 91.237054 -227.149406)
		(mid 90.958622 -227.07956)
		(end 90.68181 -227.155502)
		(width 0.0889)
		(layer "B.Cu")
		(net "PU_CPU1_FRMAGENT")
	)
	(arc
		(start 100.630482 -227.146866)
		(mid 100.354007 -227.079546)
		(end 100.07981 -227.155502)
		(width 0.0889)
		(layer "B.Cu")
		(net "PU_CPU1_FRMAGENT")
	)
	(arc
		(start 98.20021 -227.155502)
		(mid 98.013012 -227.205645)
		(end 97.825814 -227.155502)
		(width 0.0889)
		(layer "B.Cu")
		(net "PU_CPU1_FRMAGENT")
	)
	(arc
		(start 92.56141 -227.155502)
		(mid 92.374212 -227.205645)
		(end 92.187014 -227.155502)
		(width 0.0889)
		(layer "B.Cu")
		(net "PU_CPU1_FRMAGENT")
	)
	(arc
		(start 90.292682 -227.146866)
		(mid 90.016207 -227.079546)
		(end 89.74201 -227.155502)
		(width 0.0889)
		(layer "B.Cu")
		(net "PU_CPU1_FRMAGENT")
	)
	(arc
		(start 94.991682 -227.146866)
		(mid 94.715207 -227.079546)
		(end 94.44101 -227.155502)
		(width 0.0889)
		(layer "B.Cu")
		(net "PU_CPU1_FRMAGENT")
	)
	(arc
		(start 97.26041 -227.155502)
		(mid 97.073212 -227.205645)
		(end 96.886014 -227.155502)
		(width 0.0889)
		(layer "B.Cu")
		(net "PU_CPU1_FRMAGENT")
	)
	(arc
		(start 101.526848 -227.125784)
		(mid 101.269709 -227.080482)
		(end 101.01961 -227.155502)
		(width 0.0889)
		(layer "B.Cu")
		(net "PU_CPU1_FRMAGENT")
	)
	(arc
		(start 96.320864 -227.155502)
		(mid 96.133666 -227.205645)
		(end 95.946468 -227.155502)
		(width 0.0889)
		(layer "B.Cu")
		(net "PU_CPU1_FRMAGENT")
	)
	(arc
		(start 87.488268 -227.155502)
		(mid 87.211455 -227.079632)
		(end 86.933024 -227.149406)
		(width 0.0889)
		(layer "B.Cu")
		(net "PU_CPU1_FRMAGENT")
	)
	(arc
		(start 90.68181 -227.155502)
		(mid 90.494612 -227.205645)
		(end 90.307414 -227.155502)
		(width 0.0889)
		(layer "B.Cu")
		(net "PU_CPU1_FRMAGENT")
	)
	(arc
		(start 101.01961 -227.155502)
		(mid 100.832412 -227.205645)
		(end 100.645214 -227.155502)
		(width 0.0889)
		(layer "B.Cu")
		(net "PU_CPU1_FRMAGENT")
	)
	(arc
		(start 95.38081 -227.155502)
		(mid 95.193612 -227.205645)
		(end 95.006414 -227.155502)
		(width 0.0889)
		(layer "B.Cu")
		(net "PU_CPU1_FRMAGENT")
	)
	(arc
		(start 85.983064 -227.155502)
		(mid 85.795866 -227.205645)
		(end 85.608668 -227.155502)
		(width 0.0889)
		(layer "B.Cu")
		(net "PU_CPU1_FRMAGENT")
	)
	(arc
		(start 94.051882 -227.146866)
		(mid 93.775407 -227.079546)
		(end 93.50121 -227.155502)
		(width 0.0889)
		(layer "B.Cu")
		(net "PU_CPU1_FRMAGENT")
	)
	(arc
		(start 96.8756 -227.149406)
		(mid 96.597422 -227.079683)
		(end 96.320864 -227.155502)
		(width 0.0889)
		(layer "B.Cu")
		(net "PU_CPU1_FRMAGENT")
	)
	(arc
		(start 99.705414 -227.155502)
		(mid 99.428855 -227.079759)
		(end 99.150678 -227.149406)
		(width 0.0889)
		(layer "B.Cu")
		(net "PU_CPU1_FRMAGENT")
	)
	(arc
		(start 98.755454 -227.149406)
		(mid 98.477022 -227.07956)
		(end 98.20021 -227.155502)
		(width 0.0889)
		(layer "B.Cu")
		(net "PU_CPU1_FRMAGENT")
	)
	(arc
		(start 99.140264 -227.155502)
		(mid 98.953066 -227.205645)
		(end 98.765868 -227.155502)
		(width 0.0889)
		(layer "B.Cu")
		(net "PU_CPU1_FRMAGENT")
	)
	(arc
		(start 97.811082 -227.146866)
		(mid 97.534607 -227.079546)
		(end 97.26041 -227.155502)
		(width 0.0889)
		(layer "B.Cu")
		(net "PU_CPU1_FRMAGENT")
	)
	(arc
		(start 86.92261 -227.155502)
		(mid 86.735412 -227.205645)
		(end 86.548214 -227.155502)
		(width 0.0889)
		(layer "B.Cu")
		(net "PU_CPU1_FRMAGENT")
	)
	(arc
		(start 91.621864 -227.155502)
		(mid 91.434666 -227.205645)
		(end 91.247468 -227.155502)
		(width 0.0889)
		(layer "B.Cu")
		(net "PU_CPU1_FRMAGENT")
	)
	(arc
		(start 93.50121 -227.155502)
		(mid 93.314012 -227.205645)
		(end 93.126814 -227.155502)
		(width 0.0889)
		(layer "B.Cu")
		(net "PU_CPU1_FRMAGENT")
	)
	(arc
		(start 100.07981 -227.155502)
		(mid 99.892612 -227.205645)
		(end 99.705414 -227.155502)
		(width 0.0889)
		(layer "B.Cu")
		(net "PU_CPU1_FRMAGENT")
	)
	(arc
		(start 95.936054 -227.149406)
		(mid 95.657622 -227.07956)
		(end 95.38081 -227.155502)
		(width 0.0889)
		(layer "B.Cu")
		(net "PU_CPU1_FRMAGENT")
	)
	(arc
		(start 94.44101 -227.155502)
		(mid 94.253812 -227.205645)
		(end 94.066614 -227.155502)
		(width 0.0889)
		(layer "B.Cu")
		(net "PU_CPU1_FRMAGENT")
	)
	(arc
		(start 85.608668 -227.155502)
		(mid 85.331855 -227.079632)
		(end 85.053424 -227.149406)
		(width 0.0889)
		(layer "B.Cu")
		(net "PU_CPU1_FRMAGENT")
	)
	(arc
		(start 88.80221 -227.155502)
		(mid 88.615012 -227.205645)
		(end 88.427814 -227.155502)
		(width 0.0889)
		(layer "B.Cu")
		(net "PU_CPU1_FRMAGENT")
	)
	(arc
		(start 89.352882 -227.146866)
		(mid 89.076407 -227.079546)
		(end 88.80221 -227.155502)
		(width 0.0889)
		(layer "B.Cu")
		(net "PU_CPU1_FRMAGENT")
	)
	(arc
		(start 88.4174 -227.149406)
		(mid 88.139222 -227.079683)
		(end 87.862664 -227.155502)
		(width 0.0889)
		(layer "B.Cu")
		(net "PU_CPU1_FRMAGENT")
	)
	(arc
		(start 87.862664 -227.155502)
		(mid 87.675466 -227.205645)
		(end 87.488268 -227.155502)
		(width 0.0889)
		(layer "B.Cu")
		(net "PU_CPU1_FRMAGENT")
	)
	(arc
		(start 92.187014 -227.155502)
		(mid 91.910455 -227.079759)
		(end 91.632278 -227.149406)
		(width 0.0889)
		(layer "B.Cu")
		(net "PU_CPU1_FRMAGENT")
	)
	(arc
		(start 89.74201 -227.155502)
		(mid 89.554812 -227.205645)
		(end 89.367614 -227.155502)
		(width 0.0889)
		(layer "B.Cu")
		(net "PU_CPU1_FRMAGENT")
	)
	(arc
		(start 85.04301 -227.155502)
		(mid 84.952703 -227.192831)
		(end 84.855812 -227.20554)
		(width 0.0889)
		(layer "B.Cu")
		(net "PU_CPU1_FRMAGENT")
	)
	(arc
		(start 93.112082 -227.146866)
		(mid 92.835607 -227.079546)
		(end 92.56141 -227.155502)
		(width 0.0889)
		(layer "B.Cu")
		(net "PU_CPU1_FRMAGENT")
	)
	(arc
		(start 86.5378 -227.149406)
		(mid 86.259622 -227.079683)
		(end 85.983064 -227.155502)
		(width 0.0889)
		(layer "B.Cu")
		(net "PU_CPU1_FRMAGENT")
	)
	(segment
		(start 365.329216 -272.917412)
		(end 365.329216 -273.453098)
		(width 0.12954)
		(layer "F.Cu")
		(net "PU_CPU0_UPI3_AC_COUPLING")
	)
	(segment
		(start 365.328962 -272.917158)
		(end 365.329216 -272.917412)
		(width 0.12954)
		(layer "F.Cu")
		(net "PU_CPU0_UPI3_AC_COUPLING")
	)
	(via
		(at 392.261598 -264.69975)
		(size 0.6604)
		(drill 0.3302)
		(layers "F.Cu" "B.Cu")
		(net "PU_CPU0_UPI3_AC_COUPLING")
	)
	(via
		(at 365.329216 -273.453098)
		(size 0.4572)
		(drill 0.2032)
		(layers "F.Cu" "B.Cu")
		(net "PU_CPU0_UPI3_AC_COUPLING")
	)
	(segment
		(start 412.684214 -198.23938)
		(end 411.509718 -197.064884)
		(width 0.12954)
		(layer "B.Cu")
		(net "PU_CPU0_UPI3_AC_COUPLING")
	)
	(segment
		(start 376.794014 -267.266166)
		(end 376.808746 -267.25753)
		(width 0.0889)
		(layer "B.Cu")
		(net "PU_CPU0_UPI3_AC_COUPLING")
	)
	(segment
		(start 412.591758 -239.81791)
		(end 412.591758 -238.72825)
		(width 0.12954)
		(layer "B.Cu")
		(net "PU_CPU0_UPI3_AC_COUPLING")
	)
	(segment
		(start 361.474512 -271.021302)
		(end 361.474512 -271.00149)
		(width 0.0889)
		(layer "B.Cu")
		(net "PU_CPU0_UPI3_AC_COUPLING")
	)
	(segment
		(start 362.884466 -268.569694)
		(end 362.884466 -268.5542)
		(width 0.0889)
		(layer "B.Cu")
		(net "PU_CPU0_UPI3_AC_COUPLING")
	)
	(segment
		(start 367.39576 -267.266166)
		(end 367.406174 -267.26007)
		(width 0.0889)
		(layer "B.Cu")
		(net "PU_CPU0_UPI3_AC_COUPLING")
	)
	(segment
		(start 380.16815 -267.26007)
		(end 380.178564 -267.266166)
		(width 0.0889)
		(layer "B.Cu")
		(net "PU_CPU0_UPI3_AC_COUPLING")
	)
	(segment
		(start 390.214358 -266.74699)
		(end 392.261598 -264.69975)
		(width 0.12954)
		(layer "B.Cu")
		(net "PU_CPU0_UPI3_AC_COUPLING")
	)
	(segment
		(start 365.131604 -267.26007)
		(end 365.142018 -267.266166)
		(width 0.0889)
		(layer "B.Cu")
		(net "PU_CPU0_UPI3_AC_COUPLING")
	)
	(segment
		(start 361.75696 -272.14957)
		(end 361.76585 -272.14449)
		(width 0.0889)
		(layer "B.Cu")
		(net "PU_CPU0_UPI3_AC_COUPLING")
	)
	(segment
		(start 365.016542 -273.453098)
		(end 364.95101 -273.51863)
		(width 0.0889)
		(layer "B.Cu")
		(net "PU_CPU0_UPI3_AC_COUPLING")
	)
	(segment
		(start 361.767374 -274.762468)
		(end 361.75696 -274.756372)
		(width 0.0889)
		(layer "B.Cu")
		(net "PU_CPU0_UPI3_AC_COUPLING")
	)
	(segment
		(start 365.329216 -273.453098)
		(end 365.016542 -273.453098)
		(width 0.0889)
		(layer "B.Cu")
		(net "PU_CPU0_UPI3_AC_COUPLING")
	)
	(segment
		(start 388.766558 -266.74699)
		(end 390.214358 -266.74699)
		(width 0.12954)
		(layer "B.Cu")
		(net "PU_CPU0_UPI3_AC_COUPLING")
	)
	(segment
		(start 411.172152 -195.043044)
		(end 411.172152 -193.48958)
		(width 0.12954)
		(layer "B.Cu")
		(net "PU_CPU0_UPI3_AC_COUPLING")
	)
	(segment
		(start 361.76585 -273.13382)
		(end 361.75696 -273.12874)
		(width 0.0889)
		(layer "B.Cu")
		(net "PU_CPU0_UPI3_AC_COUPLING")
	)
	(segment
		(start 369.830604 -267.26007)
		(end 369.841018 -267.266166)
		(width 0.0889)
		(layer "B.Cu")
		(net "PU_CPU0_UPI3_AC_COUPLING")
	)
	(segment
		(start 412.764478 -238.55553)
		(end 412.764478 -237.43539)
		(width 0.12954)
		(layer "B.Cu")
		(net "PU_CPU0_UPI3_AC_COUPLING")
	)
	(segment
		(start 402.383498 -254.57785)
		(end 402.383498 -245.001288)
		(width 0.12954)
		(layer "B.Cu")
		(net "PU_CPU0_UPI3_AC_COUPLING")
	)
	(segment
		(start 364.20171 -267.266166)
		(end 364.210092 -267.270992)
		(width 0.0889)
		(layer "B.Cu")
		(net "PU_CPU0_UPI3_AC_COUPLING")
	)
	(segment
		(start 412.591758 -238.72825)
		(end 412.764478 -238.55553)
		(width 0.12954)
		(layer "B.Cu")
		(net "PU_CPU0_UPI3_AC_COUPLING")
	)
	(segment
		(start 364.201964 -274.756372)
		(end 364.19155 -274.762468)
		(width 0.0889)
		(layer "B.Cu")
		(net "PU_CPU0_UPI3_AC_COUPLING")
	)
	(segment
		(start 411.509718 -197.064884)
		(end 411.509718 -195.38061)
		(width 0.12954)
		(layer "B.Cu")
		(net "PU_CPU0_UPI3_AC_COUPLING")
	)
	(segment
		(start 411.121098 -241.00917)
		(end 411.392878 -240.73739)
		(width 0.12954)
		(layer "B.Cu")
		(net "PU_CPU0_UPI3_AC_COUPLING")
	)
	(segment
		(start 388.094474 -266.907772)
		(end 388.605776 -266.907772)
		(width 0.12954)
		(layer "B.Cu")
		(net "PU_CPU0_UPI3_AC_COUPLING")
	)
	(segment
		(start 377.733814 -267.266166)
		(end 377.748546 -267.25753)
		(width 0.0889)
		(layer "B.Cu")
		(net "PU_CPU0_UPI3_AC_COUPLING")
	)
	(segment
		(start 362.697014 -268.894052)
		(end 362.705904 -268.888972)
		(width 0.0889)
		(layer "B.Cu")
		(net "PU_CPU0_UPI3_AC_COUPLING")
	)
	(segment
		(start 375.854214 -267.266166)
		(end 375.868946 -267.25753)
		(width 0.0889)
		(layer "B.Cu")
		(net "PU_CPU0_UPI3_AC_COUPLING")
	)
	(segment
		(start 361.75696 -273.777456)
		(end 361.76585 -273.772376)
		(width 0.0889)
		(layer "B.Cu")
		(net "PU_CPU0_UPI3_AC_COUPLING")
	)
	(segment
		(start 362.227114 -269.707868)
		(end 362.230416 -269.70609)
		(width 0.0889)
		(layer "B.Cu")
		(net "PU_CPU0_UPI3_AC_COUPLING")
	)
	(segment
		(start 372.095014 -267.266166)
		(end 372.109746 -267.25753)
		(width 0.0889)
		(layer "B.Cu")
		(net "PU_CPU0_UPI3_AC_COUPLING")
	)
	(segment
		(start 371.155214 -267.266166)
		(end 371.169946 -267.25753)
		(width 0.0889)
		(layer "B.Cu")
		(net "PU_CPU0_UPI3_AC_COUPLING")
	)
	(segment
		(start 412.4833 -234.916472)
		(end 412.4833 -219.901008)
		(width 0.12954)
		(layer "B.Cu")
		(net "PU_CPU0_UPI3_AC_COUPLING")
	)
	(segment
		(start 412.289498 -236.96041)
		(end 412.289498 -236.24159)
		(width 0.12954)
		(layer "B.Cu")
		(net "PU_CPU0_UPI3_AC_COUPLING")
	)
	(segment
		(start 382.432814 -267.266166)
		(end 382.438402 -267.262864)
		(width 0.0889)
		(layer "B.Cu")
		(net "PU_CPU0_UPI3_AC_COUPLING")
	)
	(segment
		(start 361.474512 -272.649188)
		(end 361.474512 -272.62074)
		(width 0.0889)
		(layer "B.Cu")
		(net "PU_CPU0_UPI3_AC_COUPLING")
	)
	(segment
		(start 411.672278 -240.73739)
		(end 412.591758 -239.81791)
		(width 0.12954)
		(layer "B.Cu")
		(net "PU_CPU0_UPI3_AC_COUPLING")
	)
	(segment
		(start 370.215414 -267.266166)
		(end 370.230146 -267.25753)
		(width 0.0889)
		(layer "B.Cu")
		(net "PU_CPU0_UPI3_AC_COUPLING")
	)
	(segment
		(start 362.414566 -269.38351)
		(end 362.414566 -269.368016)
		(width 0.0889)
		(layer "B.Cu")
		(net "PU_CPU0_UPI3_AC_COUPLING")
	)
	(segment
		(start 366.08131 -267.266166)
		(end 366.089692 -267.270992)
		(width 0.0889)
		(layer "B.Cu")
		(net "PU_CPU0_UPI3_AC_COUPLING")
	)
	(segment
		(start 363.16666 -268.080236)
		(end 363.17555 -268.075156)
		(width 0.0889)
		(layer "B.Cu")
		(net "PU_CPU0_UPI3_AC_COUPLING")
	)
	(segment
		(start 412.684214 -219.700094)
		(end 412.684214 -198.23938)
		(width 0.12954)
		(layer "B.Cu")
		(net "PU_CPU0_UPI3_AC_COUPLING")
	)
	(segment
		(start 373.034814 -267.266166)
		(end 373.045228 -267.26007)
		(width 0.0889)
		(layer "B.Cu")
		(net "PU_CPU0_UPI3_AC_COUPLING")
	)
	(segment
		(start 361.76585 -271.505934)
		(end 361.75696 -271.500854)
		(width 0.0889)
		(layer "B.Cu")
		(net "PU_CPU0_UPI3_AC_COUPLING")
	)
	(segment
		(start 402.383498 -245.001288)
		(end 405.489156 -241.89563)
		(width 0.12954)
		(layer "B.Cu")
		(net "PU_CPU0_UPI3_AC_COUPLING")
	)
	(segment
		(start 412.4833 -219.901008)
		(end 412.684214 -219.700094)
		(width 0.12954)
		(layer "B.Cu")
		(net "PU_CPU0_UPI3_AC_COUPLING")
	)
	(segment
		(start 412.56966 -235.002832)
		(end 412.4833 -234.916472)
		(width 0.12954)
		(layer "B.Cu")
		(net "PU_CPU0_UPI3_AC_COUPLING")
	)
	(segment
		(start 381.49276 -267.266166)
		(end 381.503174 -267.26007)
		(width 0.0889)
		(layer "B.Cu")
		(net "PU_CPU0_UPI3_AC_COUPLING")
	)
	(segment
		(start 363.354112 -267.755878)
		(end 363.354112 -267.741654)
		(width 0.0889)
		(layer "B.Cu")
		(net "PU_CPU0_UPI3_AC_COUPLING")
	)
	(segment
		(start 373.97436 -267.266166)
		(end 373.984774 -267.26007)
		(width 0.0889)
		(layer "B.Cu")
		(net "PU_CPU0_UPI3_AC_COUPLING")
	)
	(segment
		(start 387.840728 -266.907772)
		(end 388.094474 -266.907772)
		(width 0.0889)
		(layer "B.Cu")
		(net "PU_CPU0_UPI3_AC_COUPLING")
	)
	(segment
		(start 412.289498 -236.24159)
		(end 412.56966 -235.961428)
		(width 0.12954)
		(layer "B.Cu")
		(net "PU_CPU0_UPI3_AC_COUPLING")
	)
	(segment
		(start 392.261598 -264.69975)
		(end 402.383498 -254.57785)
		(width 0.12954)
		(layer "B.Cu")
		(net "PU_CPU0_UPI3_AC_COUPLING")
	)
	(segment
		(start 362.711746 -274.765008)
		(end 362.697014 -274.756372)
		(width 0.0889)
		(layer "B.Cu")
		(net "PU_CPU0_UPI3_AC_COUPLING")
	)
	(segment
		(start 411.392878 -240.73739)
		(end 411.672278 -240.73739)
		(width 0.12954)
		(layer "B.Cu")
		(net "PU_CPU0_UPI3_AC_COUPLING")
	)
	(segment
		(start 364.20806 -274.752816)
		(end 364.201964 -274.756372)
		(width 0.0889)
		(layer "B.Cu")
		(net "PU_CPU0_UPI3_AC_COUPLING")
	)
	(segment
		(start 364.672118 -273.942556)
		(end 364.663228 -273.947636)
		(width 0.0889)
		(layer "B.Cu")
		(net "PU_CPU0_UPI3_AC_COUPLING")
	)
	(segment
		(start 368.89055 -267.26007)
		(end 368.900964 -267.266166)
		(width 0.0889)
		(layer "B.Cu")
		(net "PU_CPU0_UPI3_AC_COUPLING")
	)
	(segment
		(start 412.764478 -237.43539)
		(end 412.289498 -236.96041)
		(width 0.12954)
		(layer "B.Cu")
		(net "PU_CPU0_UPI3_AC_COUPLING")
	)
	(segment
		(start 374.914414 -267.266166)
		(end 374.929146 -267.25753)
		(width 0.0889)
		(layer "B.Cu")
		(net "PU_CPU0_UPI3_AC_COUPLING")
	)
	(segment
		(start 383.372614 -267.26642)
		(end 383.389886 -267.256514)
		(width 0.0889)
		(layer "B.Cu")
		(net "PU_CPU0_UPI3_AC_COUPLING")
	)
	(segment
		(start 412.56966 -235.961428)
		(end 412.56966 -235.002832)
		(width 0.12954)
		(layer "B.Cu")
		(net "PU_CPU0_UPI3_AC_COUPLING")
	)
	(segment
		(start 409.416758 -241.00917)
		(end 411.121098 -241.00917)
		(width 0.12954)
		(layer "B.Cu")
		(net "PU_CPU0_UPI3_AC_COUPLING")
	)
	(segment
		(start 387.602476 -267.146024)
		(end 387.840728 -266.907772)
		(width 0.0889)
		(layer "B.Cu")
		(net "PU_CPU0_UPI3_AC_COUPLING")
	)
	(segment
		(start 408.530298 -241.89563)
		(end 409.416758 -241.00917)
		(width 0.12954)
		(layer "B.Cu")
		(net "PU_CPU0_UPI3_AC_COUPLING")
	)
	(segment
		(start 384.760724 -267.146024)
		(end 387.602476 -267.146024)
		(width 0.0889)
		(layer "B.Cu")
		(net "PU_CPU0_UPI3_AC_COUPLING")
	)
	(segment
		(start 361.75696 -270.521938)
		(end 361.76585 -270.516858)
		(width 0.0889)
		(layer "B.Cu")
		(net "PU_CPU0_UPI3_AC_COUPLING")
	)
	(segment
		(start 388.605776 -266.907772)
		(end 388.766558 -266.74699)
		(width 0.12954)
		(layer "B.Cu")
		(net "PU_CPU0_UPI3_AC_COUPLING")
	)
	(segment
		(start 367.006632 -267.25753)
		(end 367.021364 -267.266166)
		(width 0.0889)
		(layer "B.Cu")
		(net "PU_CPU0_UPI3_AC_COUPLING")
	)
	(segment
		(start 411.509718 -195.38061)
		(end 411.172152 -195.043044)
		(width 0.12954)
		(layer "B.Cu")
		(net "PU_CPU0_UPI3_AC_COUPLING")
	)
	(segment
		(start 361.474512 -274.27682)
		(end 361.474512 -274.257008)
		(width 0.0889)
		(layer "B.Cu")
		(net "PU_CPU0_UPI3_AC_COUPLING")
	)
	(segment
		(start 405.489156 -241.89563)
		(end 408.530298 -241.89563)
		(width 0.12954)
		(layer "B.Cu")
		(net "PU_CPU0_UPI3_AC_COUPLING")
	)
	(segment
		(start 378.673614 -267.266166)
		(end 378.688346 -267.25753)
		(width 0.0889)
		(layer "B.Cu")
		(net "PU_CPU0_UPI3_AC_COUPLING")
	)
	(segment
		(start 361.944412 -270.19758)
		(end 361.944412 -270.183356)
		(width 0.0889)
		(layer "B.Cu")
		(net "PU_CPU0_UPI3_AC_COUPLING")
	)
	(arc
		(start 381.503174 -267.26007)
		(mid 381.781606 -267.190256)
		(end 382.058418 -267.266166)
		(width 0.0889)
		(layer "B.Cu")
		(net "PU_CPU0_UPI3_AC_COUPLING")
	)
	(arc
		(start 380.55296 -267.266166)
		(mid 380.835662 -267.190424)
		(end 381.118364 -267.266166)
		(width 0.0889)
		(layer "B.Cu")
		(net "PU_CPU0_UPI3_AC_COUPLING")
	)
	(arc
		(start 366.45596 -267.266166)
		(mid 366.730189 -267.190241)
		(end 367.006632 -267.25753)
		(width 0.0889)
		(layer "B.Cu")
		(net "PU_CPU0_UPI3_AC_COUPLING")
	)
	(arc
		(start 362.705904 -268.888972)
		(mid 362.836818 -268.752612)
		(end 362.884466 -268.569694)
		(width 0.0889)
		(layer "B.Cu")
		(net "PU_CPU0_UPI3_AC_COUPLING")
	)
	(arc
		(start 382.058418 -267.266166)
		(mid 382.245616 -267.316309)
		(end 382.432814 -267.266166)
		(width 0.0889)
		(layer "B.Cu")
		(net "PU_CPU0_UPI3_AC_COUPLING")
	)
	(arc
		(start 379.613414 -267.266166)
		(mid 379.889973 -267.190457)
		(end 380.16815 -267.26007)
		(width 0.0889)
		(layer "B.Cu")
		(net "PU_CPU0_UPI3_AC_COUPLING")
	)
	(arc
		(start 374.540018 -267.266166)
		(mid 374.727216 -267.316309)
		(end 374.914414 -267.266166)
		(width 0.0889)
		(layer "B.Cu")
		(net "PU_CPU0_UPI3_AC_COUPLING")
	)
	(arc
		(start 364.484666 -274.266914)
		(mid 364.410675 -274.54648)
		(end 364.20806 -274.752816)
		(width 0.0889)
		(layer "B.Cu")
		(net "PU_CPU0_UPI3_AC_COUPLING")
	)
	(arc
		(start 381.118364 -267.266166)
		(mid 381.305562 -267.316309)
		(end 381.49276 -267.266166)
		(width 0.0889)
		(layer "B.Cu")
		(net "PU_CPU0_UPI3_AC_COUPLING")
	)
	(arc
		(start 362.884466 -268.5542)
		(mid 362.963836 -268.280466)
		(end 363.16666 -268.080236)
		(width 0.0889)
		(layer "B.Cu")
		(net "PU_CPU0_UPI3_AC_COUPLING")
	)
	(arc
		(start 378.299218 -267.266166)
		(mid 378.486416 -267.316309)
		(end 378.673614 -267.266166)
		(width 0.0889)
		(layer "B.Cu")
		(net "PU_CPU0_UPI3_AC_COUPLING")
	)
	(arc
		(start 363.636814 -274.756372)
		(mid 363.449616 -274.706229)
		(end 363.262418 -274.756372)
		(width 0.0889)
		(layer "B.Cu")
		(net "PU_CPU0_UPI3_AC_COUPLING")
	)
	(arc
		(start 373.984774 -267.26007)
		(mid 374.263206 -267.190256)
		(end 374.540018 -267.266166)
		(width 0.0889)
		(layer "B.Cu")
		(net "PU_CPU0_UPI3_AC_COUPLING")
	)
	(arc
		(start 375.479818 -267.266166)
		(mid 375.667016 -267.316309)
		(end 375.854214 -267.266166)
		(width 0.0889)
		(layer "B.Cu")
		(net "PU_CPU0_UPI3_AC_COUPLING")
	)
	(arc
		(start 382.438402 -267.262864)
		(mid 382.718791 -267.190456)
		(end 382.998218 -267.26642)
		(width 0.0889)
		(layer "B.Cu")
		(net "PU_CPU0_UPI3_AC_COUPLING")
	)
	(arc
		(start 376.808746 -267.25753)
		(mid 377.085187 -267.190364)
		(end 377.359418 -267.266166)
		(width 0.0889)
		(layer "B.Cu")
		(net "PU_CPU0_UPI3_AC_COUPLING")
	)
	(arc
		(start 377.748546 -267.25753)
		(mid 378.024987 -267.190364)
		(end 378.299218 -267.266166)
		(width 0.0889)
		(layer "B.Cu")
		(net "PU_CPU0_UPI3_AC_COUPLING")
	)
	(arc
		(start 382.998218 -267.26642)
		(mid 383.185416 -267.316563)
		(end 383.372614 -267.26642)
		(width 0.0889)
		(layer "B.Cu")
		(net "PU_CPU0_UPI3_AC_COUPLING")
	)
	(arc
		(start 361.75696 -271.500854)
		(mid 361.552625 -271.298249)
		(end 361.474512 -271.021302)
		(width 0.0889)
		(layer "B.Cu")
		(net "PU_CPU0_UPI3_AC_COUPLING")
	)
	(arc
		(start 361.76585 -272.14449)
		(mid 361.944447 -271.825212)
		(end 361.76585 -271.505934)
		(width 0.0889)
		(layer "B.Cu")
		(net "PU_CPU0_UPI3_AC_COUPLING")
	)
	(arc
		(start 361.474512 -271.00149)
		(mid 361.552623 -270.724541)
		(end 361.75696 -270.521938)
		(width 0.0889)
		(layer "B.Cu")
		(net "PU_CPU0_UPI3_AC_COUPLING")
	)
	(arc
		(start 364.663228 -273.947636)
		(mid 364.532314 -274.083996)
		(end 364.484666 -274.266914)
		(width 0.0889)
		(layer "B.Cu")
		(net "PU_CPU0_UPI3_AC_COUPLING")
	)
	(arc
		(start 370.780818 -267.266166)
		(mid 370.968016 -267.316309)
		(end 371.155214 -267.266166)
		(width 0.0889)
		(layer "B.Cu")
		(net "PU_CPU0_UPI3_AC_COUPLING")
	)
	(arc
		(start 365.516414 -267.266166)
		(mid 365.798862 -267.190551)
		(end 366.08131 -267.266166)
		(width 0.0889)
		(layer "B.Cu")
		(net "PU_CPU0_UPI3_AC_COUPLING")
	)
	(arc
		(start 367.406174 -267.26007)
		(mid 367.684606 -267.190256)
		(end 367.961418 -267.266166)
		(width 0.0889)
		(layer "B.Cu")
		(net "PU_CPU0_UPI3_AC_COUPLING")
	)
	(arc
		(start 364.57636 -267.266166)
		(mid 364.853173 -267.19033)
		(end 365.131604 -267.26007)
		(width 0.0889)
		(layer "B.Cu")
		(net "PU_CPU0_UPI3_AC_COUPLING")
	)
	(arc
		(start 363.17555 -268.075156)
		(mid 363.306464 -267.938796)
		(end 363.354112 -267.755878)
		(width 0.0889)
		(layer "B.Cu")
		(net "PU_CPU0_UPI3_AC_COUPLING")
	)
	(arc
		(start 373.045228 -267.26007)
		(mid 373.323406 -267.190378)
		(end 373.599964 -267.266166)
		(width 0.0889)
		(layer "B.Cu")
		(net "PU_CPU0_UPI3_AC_COUPLING")
	)
	(arc
		(start 361.474512 -272.62074)
		(mid 361.554674 -272.348551)
		(end 361.75696 -272.14957)
		(width 0.0889)
		(layer "B.Cu")
		(net "PU_CPU0_UPI3_AC_COUPLING")
	)
	(arc
		(start 380.178564 -267.266166)
		(mid 380.365762 -267.316309)
		(end 380.55296 -267.266166)
		(width 0.0889)
		(layer "B.Cu")
		(net "PU_CPU0_UPI3_AC_COUPLING")
	)
	(arc
		(start 374.929146 -267.25753)
		(mid 375.205587 -267.190364)
		(end 375.479818 -267.266166)
		(width 0.0889)
		(layer "B.Cu")
		(net "PU_CPU0_UPI3_AC_COUPLING")
	)
	(arc
		(start 363.636814 -267.266166)
		(mid 363.919262 -267.190551)
		(end 364.20171 -267.266166)
		(width 0.0889)
		(layer "B.Cu")
		(net "PU_CPU0_UPI3_AC_COUPLING")
	)
	(arc
		(start 370.230146 -267.25753)
		(mid 370.506587 -267.190364)
		(end 370.780818 -267.266166)
		(width 0.0889)
		(layer "B.Cu")
		(net "PU_CPU0_UPI3_AC_COUPLING")
	)
	(arc
		(start 373.599964 -267.266166)
		(mid 373.787162 -267.316309)
		(end 373.97436 -267.266166)
		(width 0.0889)
		(layer "B.Cu")
		(net "PU_CPU0_UPI3_AC_COUPLING")
	)
	(arc
		(start 372.660418 -267.266166)
		(mid 372.847616 -267.316309)
		(end 373.034814 -267.266166)
		(width 0.0889)
		(layer "B.Cu")
		(net "PU_CPU0_UPI3_AC_COUPLING")
	)
	(arc
		(start 369.27536 -267.266166)
		(mid 369.552173 -267.19033)
		(end 369.830604 -267.26007)
		(width 0.0889)
		(layer "B.Cu")
		(net "PU_CPU0_UPI3_AC_COUPLING")
	)
	(arc
		(start 375.868946 -267.25753)
		(mid 376.145387 -267.190364)
		(end 376.419618 -267.266166)
		(width 0.0889)
		(layer "B.Cu")
		(net "PU_CPU0_UPI3_AC_COUPLING")
	)
	(arc
		(start 361.75696 -274.756372)
		(mid 361.552625 -274.553767)
		(end 361.474512 -274.27682)
		(width 0.0889)
		(layer "B.Cu")
		(net "PU_CPU0_UPI3_AC_COUPLING")
	)
	(arc
		(start 367.961418 -267.266166)
		(mid 368.148616 -267.316309)
		(end 368.335814 -267.266166)
		(width 0.0889)
		(layer "B.Cu")
		(net "PU_CPU0_UPI3_AC_COUPLING")
	)
	(arc
		(start 362.230416 -269.70609)
		(mid 362.365274 -269.569226)
		(end 362.414566 -269.38351)
		(width 0.0889)
		(layer "B.Cu")
		(net "PU_CPU0_UPI3_AC_COUPLING")
	)
	(arc
		(start 361.76585 -273.772376)
		(mid 361.944447 -273.453098)
		(end 361.76585 -273.13382)
		(width 0.0889)
		(layer "B.Cu")
		(net "PU_CPU0_UPI3_AC_COUPLING")
	)
	(arc
		(start 362.414566 -269.368016)
		(mid 362.494015 -269.09422)
		(end 362.697014 -268.894052)
		(width 0.0889)
		(layer "B.Cu")
		(net "PU_CPU0_UPI3_AC_COUPLING")
	)
	(arc
		(start 361.474512 -274.257008)
		(mid 361.552623 -273.980059)
		(end 361.75696 -273.777456)
		(width 0.0889)
		(layer "B.Cu")
		(net "PU_CPU0_UPI3_AC_COUPLING")
	)
	(arc
		(start 379.239018 -267.266166)
		(mid 379.426216 -267.316309)
		(end 379.613414 -267.266166)
		(width 0.0889)
		(layer "B.Cu")
		(net "PU_CPU0_UPI3_AC_COUPLING")
	)
	(arc
		(start 376.419618 -267.266166)
		(mid 376.606816 -267.316309)
		(end 376.794014 -267.266166)
		(width 0.0889)
		(layer "B.Cu")
		(net "PU_CPU0_UPI3_AC_COUPLING")
	)
	(arc
		(start 364.210092 -267.270992)
		(mid 364.393854 -267.316392)
		(end 364.57636 -267.266166)
		(width 0.0889)
		(layer "B.Cu")
		(net "PU_CPU0_UPI3_AC_COUPLING")
	)
	(arc
		(start 369.841018 -267.266166)
		(mid 370.028216 -267.316309)
		(end 370.215414 -267.266166)
		(width 0.0889)
		(layer "B.Cu")
		(net "PU_CPU0_UPI3_AC_COUPLING")
	)
	(arc
		(start 367.021364 -267.266166)
		(mid 367.208562 -267.316309)
		(end 367.39576 -267.266166)
		(width 0.0889)
		(layer "B.Cu")
		(net "PU_CPU0_UPI3_AC_COUPLING")
	)
	(arc
		(start 377.359418 -267.266166)
		(mid 377.546616 -267.316309)
		(end 377.733814 -267.266166)
		(width 0.0889)
		(layer "B.Cu")
		(net "PU_CPU0_UPI3_AC_COUPLING")
	)
	(arc
		(start 371.169946 -267.25753)
		(mid 371.446387 -267.190364)
		(end 371.720618 -267.266166)
		(width 0.0889)
		(layer "B.Cu")
		(net "PU_CPU0_UPI3_AC_COUPLING")
	)
	(arc
		(start 368.900964 -267.266166)
		(mid 369.088162 -267.316309)
		(end 369.27536 -267.266166)
		(width 0.0889)
		(layer "B.Cu")
		(net "PU_CPU0_UPI3_AC_COUPLING")
	)
	(arc
		(start 368.335814 -267.266166)
		(mid 368.612373 -267.190457)
		(end 368.89055 -267.26007)
		(width 0.0889)
		(layer "B.Cu")
		(net "PU_CPU0_UPI3_AC_COUPLING")
	)
	(arc
		(start 364.95101 -273.51863)
		(mid 364.861836 -273.763672)
		(end 364.672118 -273.942556)
		(width 0.0889)
		(layer "B.Cu")
		(net "PU_CPU0_UPI3_AC_COUPLING")
	)
	(arc
		(start 384.31216 -267.266166)
		(mid 384.528535 -267.176573)
		(end 384.760724 -267.146024)
		(width 0.0889)
		(layer "B.Cu")
		(net "PU_CPU0_UPI3_AC_COUPLING")
	)
	(arc
		(start 383.389886 -267.256514)
		(mid 383.665066 -267.190562)
		(end 383.937764 -267.266166)
		(width 0.0889)
		(layer "B.Cu")
		(net "PU_CPU0_UPI3_AC_COUPLING")
	)
	(arc
		(start 363.354112 -267.741654)
		(mid 363.433331 -267.466969)
		(end 363.636814 -267.266166)
		(width 0.0889)
		(layer "B.Cu")
		(net "PU_CPU0_UPI3_AC_COUPLING")
	)
	(arc
		(start 363.262418 -274.756372)
		(mid 362.988219 -274.832207)
		(end 362.711746 -274.765008)
		(width 0.0889)
		(layer "B.Cu")
		(net "PU_CPU0_UPI3_AC_COUPLING")
	)
	(arc
		(start 361.75696 -273.12874)
		(mid 361.552625 -272.926135)
		(end 361.474512 -272.649188)
		(width 0.0889)
		(layer "B.Cu")
		(net "PU_CPU0_UPI3_AC_COUPLING")
	)
	(arc
		(start 362.322618 -274.756372)
		(mid 362.045805 -274.832242)
		(end 361.767374 -274.762468)
		(width 0.0889)
		(layer "B.Cu")
		(net "PU_CPU0_UPI3_AC_COUPLING")
	)
	(arc
		(start 378.688346 -267.25753)
		(mid 378.964787 -267.190364)
		(end 379.239018 -267.266166)
		(width 0.0889)
		(layer "B.Cu")
		(net "PU_CPU0_UPI3_AC_COUPLING")
	)
	(arc
		(start 361.944412 -270.183356)
		(mid 362.023631 -269.908671)
		(end 362.227114 -269.707868)
		(width 0.0889)
		(layer "B.Cu")
		(net "PU_CPU0_UPI3_AC_COUPLING")
	)
	(arc
		(start 361.76585 -270.516858)
		(mid 361.896764 -270.380498)
		(end 361.944412 -270.19758)
		(width 0.0889)
		(layer "B.Cu")
		(net "PU_CPU0_UPI3_AC_COUPLING")
	)
	(arc
		(start 383.937764 -267.266166)
		(mid 384.124962 -267.316309)
		(end 384.31216 -267.266166)
		(width 0.0889)
		(layer "B.Cu")
		(net "PU_CPU0_UPI3_AC_COUPLING")
	)
	(arc
		(start 372.109746 -267.25753)
		(mid 372.386187 -267.190364)
		(end 372.660418 -267.266166)
		(width 0.0889)
		(layer "B.Cu")
		(net "PU_CPU0_UPI3_AC_COUPLING")
	)
	(arc
		(start 364.19155 -274.762468)
		(mid 363.913372 -274.832191)
		(end 363.636814 -274.756372)
		(width 0.0889)
		(layer "B.Cu")
		(net "PU_CPU0_UPI3_AC_COUPLING")
	)
	(arc
		(start 366.089692 -267.270992)
		(mid 366.273454 -267.316392)
		(end 366.45596 -267.266166)
		(width 0.0889)
		(layer "B.Cu")
		(net "PU_CPU0_UPI3_AC_COUPLING")
	)
	(arc
		(start 371.720618 -267.266166)
		(mid 371.907816 -267.316309)
		(end 372.095014 -267.266166)
		(width 0.0889)
		(layer "B.Cu")
		(net "PU_CPU0_UPI3_AC_COUPLING")
	)
	(arc
		(start 362.697014 -274.756372)
		(mid 362.509816 -274.706229)
		(end 362.322618 -274.756372)
		(width 0.0889)
		(layer "B.Cu")
		(net "PU_CPU0_UPI3_AC_COUPLING")
	)
	(arc
		(start 365.142018 -267.266166)
		(mid 365.329216 -267.316309)
		(end 365.516414 -267.266166)
		(width 0.0889)
		(layer "B.Cu")
		(net "PU_CPU0_UPI3_AC_COUPLING")
	)
	(segment
		(start 352.172016 -268.034008)
		(end 352.172016 -268.569694)
		(width 0.12954)
		(layer "F.Cu")
		(net "PU_CPU0_UPI2_AC_COUPLING")
	)
	(segment
		(start 352.171762 -268.033754)
		(end 352.172016 -268.034008)
		(width 0.12954)
		(layer "F.Cu")
		(net "PU_CPU0_UPI2_AC_COUPLING")
	)
	(via
		(at 324.464426 -269.99819)
		(size 0.6604)
		(drill 0.3302)
		(layers "F.Cu" "B.Cu")
		(net "PU_CPU0_UPI2_AC_COUPLING")
	)
	(via
		(at 352.172016 -268.569694)
		(size 0.4572)
		(drill 0.2032)
		(layers "F.Cu" "B.Cu")
		(net "PU_CPU0_UPI2_AC_COUPLING")
	)
	(segment
		(start 311.286398 -271.83207)
		(end 311.116218 -271.66189)
		(width 0.12954)
		(layer "B.Cu")
		(net "PU_CPU0_UPI2_AC_COUPLING")
	)
	(segment
		(start 350.95815 -267.4366)
		(end 350.94926 -267.43152)
		(width 0.0889)
		(layer "B.Cu")
		(net "PU_CPU0_UPI2_AC_COUPLING")
	)
	(segment
		(start 305.972718 -271.78889)
		(end 304.837338 -270.65351)
		(width 0.12954)
		(layer "B.Cu")
		(net "PU_CPU0_UPI2_AC_COUPLING")
	)
	(segment
		(start 302.749458 -269.95501)
		(end 301.865284 -269.95501)
		(width 0.12954)
		(layer "B.Cu")
		(net "PU_CPU0_UPI2_AC_COUPLING")
	)
	(segment
		(start 295.131998 -264.86993)
		(end 294.535098 -264.86993)
		(width 0.12954)
		(layer "B.Cu")
		(net "PU_CPU0_UPI2_AC_COUPLING")
	)
	(segment
		(start 294.019478 -264.35431)
		(end 292.139878 -264.35431)
		(width 0.12954)
		(layer "B.Cu")
		(net "PU_CPU0_UPI2_AC_COUPLING")
	)
	(segment
		(start 295.909238 -267.79601)
		(end 295.909238 -265.64717)
		(width 0.12954)
		(layer "B.Cu")
		(net "PU_CPU0_UPI2_AC_COUPLING")
	)
	(segment
		(start 333.230728 -266.991338)
		(end 333.064612 -267.157454)
		(width 0.0889)
		(layer "B.Cu")
		(net "PU_CPU0_UPI2_AC_COUPLING")
	)
	(segment
		(start 292.139878 -264.35431)
		(end 290.458398 -262.67283)
		(width 0.12954)
		(layer "B.Cu")
		(net "PU_CPU0_UPI2_AC_COUPLING")
	)
	(segment
		(start 340.237064 -267.43152)
		(end 340.222332 -267.440156)
		(width 0.0889)
		(layer "B.Cu")
		(net "PU_CPU0_UPI2_AC_COUPLING")
	)
	(segment
		(start 349.985584 -267.417804)
		(end 349.957644 -267.406882)
		(width 0.0889)
		(layer "B.Cu")
		(net "PU_CPU0_UPI2_AC_COUPLING")
	)
	(segment
		(start 296.907458 -268.79423)
		(end 295.909238 -267.79601)
		(width 0.12954)
		(layer "B.Cu")
		(net "PU_CPU0_UPI2_AC_COUPLING")
	)
	(segment
		(start 314.557918 -271.83207)
		(end 311.286398 -271.83207)
		(width 0.12954)
		(layer "B.Cu")
		(net "PU_CPU0_UPI2_AC_COUPLING")
	)
	(segment
		(start 338.742528 -267.437616)
		(end 338.732114 -267.43152)
		(width 0.0889)
		(layer "B.Cu")
		(net "PU_CPU0_UPI2_AC_COUPLING")
	)
	(segment
		(start 348.695264 -267.43152)
		(end 348.680532 -267.440156)
		(width 0.0889)
		(layer "B.Cu")
		(net "PU_CPU0_UPI2_AC_COUPLING")
	)
	(segment
		(start 345.321128 -267.437616)
		(end 345.310714 -267.43152)
		(width 0.0889)
		(layer "B.Cu")
		(net "PU_CPU0_UPI2_AC_COUPLING")
	)
	(segment
		(start 318.470026 -269.998444)
		(end 316.391544 -269.998444)
		(width 0.12954)
		(layer "B.Cu")
		(net "PU_CPU0_UPI2_AC_COUPLING")
	)
	(segment
		(start 295.909238 -265.64717)
		(end 295.131998 -264.86993)
		(width 0.12954)
		(layer "B.Cu")
		(net "PU_CPU0_UPI2_AC_COUPLING")
	)
	(segment
		(start 287.26892 -255.406398)
		(end 285.01848 -253.155958)
		(width 0.12954)
		(layer "B.Cu")
		(net "PU_CPU0_UPI2_AC_COUPLING")
	)
	(segment
		(start 333.064612 -267.157454)
		(end 330.683108 -269.538958)
		(width 0.12954)
		(layer "B.Cu")
		(net "PU_CPU0_UPI2_AC_COUPLING")
	)
	(segment
		(start 344.936318 -267.43152)
		(end 344.925904 -267.437616)
		(width 0.0889)
		(layer "B.Cu")
		(net "PU_CPU0_UPI2_AC_COUPLING")
	)
	(segment
		(start 303.447958 -270.65351)
		(end 302.749458 -269.95501)
		(width 0.12954)
		(layer "B.Cu")
		(net "PU_CPU0_UPI2_AC_COUPLING")
	)
	(segment
		(start 342.116664 -267.43152)
		(end 342.101932 -267.440156)
		(width 0.0889)
		(layer "B.Cu")
		(net "PU_CPU0_UPI2_AC_COUPLING")
	)
	(segment
		(start 311.116218 -271.66189)
		(end 307.181758 -271.66189)
		(width 0.12954)
		(layer "B.Cu")
		(net "PU_CPU0_UPI2_AC_COUPLING")
	)
	(segment
		(start 282.884372 -196.112384)
		(end 282.152852 -195.380864)
		(width 0.12954)
		(layer "B.Cu")
		(net "PU_CPU0_UPI2_AC_COUPLING")
	)
	(segment
		(start 290.458398 -262.67283)
		(end 290.458398 -258.191508)
		(width 0.12954)
		(layer "B.Cu")
		(net "PU_CPU0_UPI2_AC_COUPLING")
	)
	(segment
		(start 336.195162 -267.507212)
		(end 334.910938 -267.507212)
		(width 0.0889)
		(layer "B.Cu")
		(net "PU_CPU0_UPI2_AC_COUPLING")
	)
	(segment
		(start 346.815664 -267.43152)
		(end 346.800932 -267.440156)
		(width 0.0889)
		(layer "B.Cu")
		(net "PU_CPU0_UPI2_AC_COUPLING")
	)
	(segment
		(start 316.391544 -269.998444)
		(end 314.557918 -271.83207)
		(width 0.12954)
		(layer "B.Cu")
		(net "PU_CPU0_UPI2_AC_COUPLING")
	)
	(segment
		(start 343.056464 -267.43152)
		(end 343.041732 -267.440156)
		(width 0.0889)
		(layer "B.Cu")
		(net "PU_CPU0_UPI2_AC_COUPLING")
	)
	(segment
		(start 318.470026 -269.99819)
		(end 318.470026 -269.998444)
		(width 0.12954)
		(layer "B.Cu")
		(net "PU_CPU0_UPI2_AC_COUPLING")
	)
	(segment
		(start 290.458398 -258.191508)
		(end 287.673288 -255.406398)
		(width 0.12954)
		(layer "B.Cu")
		(net "PU_CPU0_UPI2_AC_COUPLING")
	)
	(segment
		(start 334.910938 -267.507212)
		(end 334.395064 -266.991338)
		(width 0.0889)
		(layer "B.Cu")
		(net "PU_CPU0_UPI2_AC_COUPLING")
	)
	(segment
		(start 285.01848 -253.155958)
		(end 283.848556 -253.155958)
		(width 0.12954)
		(layer "B.Cu")
		(net "PU_CPU0_UPI2_AC_COUPLING")
	)
	(segment
		(start 324.923658 -269.538958)
		(end 324.464426 -269.99819)
		(width 0.12954)
		(layer "B.Cu")
		(net "PU_CPU0_UPI2_AC_COUPLING")
	)
	(segment
		(start 283.848556 -253.155958)
		(end 282.884372 -252.191774)
		(width 0.12954)
		(layer "B.Cu")
		(net "PU_CPU0_UPI2_AC_COUPLING")
	)
	(segment
		(start 294.535098 -264.86993)
		(end 294.019478 -264.35431)
		(width 0.12954)
		(layer "B.Cu")
		(net "PU_CPU0_UPI2_AC_COUPLING")
	)
	(segment
		(start 347.755464 -267.43152)
		(end 347.740732 -267.440156)
		(width 0.0889)
		(layer "B.Cu")
		(net "PU_CPU0_UPI2_AC_COUPLING")
	)
	(segment
		(start 282.11272 -194.541648)
		(end 282.11272 -194.110864)
		(width 0.12954)
		(layer "B.Cu")
		(net "PU_CPU0_UPI2_AC_COUPLING")
	)
	(segment
		(start 304.837338 -270.65351)
		(end 303.447958 -270.65351)
		(width 0.12954)
		(layer "B.Cu")
		(net "PU_CPU0_UPI2_AC_COUPLING")
	)
	(segment
		(start 307.181758 -271.66189)
		(end 307.054758 -271.78889)
		(width 0.12954)
		(layer "B.Cu")
		(net "PU_CPU0_UPI2_AC_COUPLING")
	)
	(segment
		(start 282.152852 -195.380864)
		(end 282.152852 -194.58178)
		(width 0.12954)
		(layer "B.Cu")
		(net "PU_CPU0_UPI2_AC_COUPLING")
	)
	(segment
		(start 299.576998 -268.79423)
		(end 296.907458 -268.79423)
		(width 0.12954)
		(layer "B.Cu")
		(net "PU_CPU0_UPI2_AC_COUPLING")
	)
	(segment
		(start 324.464426 -269.99819)
		(end 318.470026 -269.99819)
		(width 0.12954)
		(layer "B.Cu")
		(net "PU_CPU0_UPI2_AC_COUPLING")
	)
	(segment
		(start 301.865284 -269.95501)
		(end 301.090838 -269.180564)
		(width 0.12954)
		(layer "B.Cu")
		(net "PU_CPU0_UPI2_AC_COUPLING")
	)
	(segment
		(start 282.884372 -252.191774)
		(end 282.884372 -196.112384)
		(width 0.12954)
		(layer "B.Cu")
		(net "PU_CPU0_UPI2_AC_COUPLING")
	)
	(segment
		(start 350.00946 -267.43152)
		(end 349.985584 -267.417804)
		(width 0.0889)
		(layer "B.Cu")
		(net "PU_CPU0_UPI2_AC_COUPLING")
	)
	(segment
		(start 330.683108 -269.538958)
		(end 324.923658 -269.538958)
		(width 0.12954)
		(layer "B.Cu")
		(net "PU_CPU0_UPI2_AC_COUPLING")
	)
	(segment
		(start 334.395064 -266.991338)
		(end 333.230728 -266.991338)
		(width 0.0889)
		(layer "B.Cu")
		(net "PU_CPU0_UPI2_AC_COUPLING")
	)
	(segment
		(start 282.152852 -194.58178)
		(end 282.11272 -194.541648)
		(width 0.12954)
		(layer "B.Cu")
		(net "PU_CPU0_UPI2_AC_COUPLING")
	)
	(segment
		(start 343.996264 -267.43152)
		(end 343.981532 -267.440156)
		(width 0.0889)
		(layer "B.Cu")
		(net "PU_CPU0_UPI2_AC_COUPLING")
	)
	(segment
		(start 352.172016 -268.569694)
		(end 351.419414 -268.245336)
		(width 0.0889)
		(layer "B.Cu")
		(net "PU_CPU0_UPI2_AC_COUPLING")
	)
	(segment
		(start 337.802474 -267.437616)
		(end 337.79206 -267.43152)
		(width 0.0889)
		(layer "B.Cu")
		(net "PU_CPU0_UPI2_AC_COUPLING")
	)
	(segment
		(start 349.635064 -267.43152)
		(end 349.620332 -267.440156)
		(width 0.0889)
		(layer "B.Cu")
		(net "PU_CPU0_UPI2_AC_COUPLING")
	)
	(segment
		(start 341.176864 -267.43152)
		(end 341.162132 -267.440156)
		(width 0.0889)
		(layer "B.Cu")
		(net "PU_CPU0_UPI2_AC_COUPLING")
	)
	(segment
		(start 351.419414 -268.245336)
		(end 351.413318 -268.24178)
		(width 0.0889)
		(layer "B.Cu")
		(net "PU_CPU0_UPI2_AC_COUPLING")
	)
	(segment
		(start 287.673288 -255.406398)
		(end 287.26892 -255.406398)
		(width 0.12954)
		(layer "B.Cu")
		(net "PU_CPU0_UPI2_AC_COUPLING")
	)
	(segment
		(start 301.090838 -269.180564)
		(end 299.963332 -269.180564)
		(width 0.12954)
		(layer "B.Cu")
		(net "PU_CPU0_UPI2_AC_COUPLING")
	)
	(segment
		(start 299.963332 -269.180564)
		(end 299.576998 -268.79423)
		(width 0.12954)
		(layer "B.Cu")
		(net "PU_CPU0_UPI2_AC_COUPLING")
	)
	(segment
		(start 350.574864 -267.43152)
		(end 350.560132 -267.440156)
		(width 0.0889)
		(layer "B.Cu")
		(net "PU_CPU0_UPI2_AC_COUPLING")
	)
	(segment
		(start 307.054758 -271.78889)
		(end 305.972718 -271.78889)
		(width 0.12954)
		(layer "B.Cu")
		(net "PU_CPU0_UPI2_AC_COUPLING")
	)
	(arc
		(start 349.620332 -267.440156)
		(mid 349.343891 -267.507322)
		(end 349.06966 -267.43152)
		(width 0.0889)
		(layer "B.Cu")
		(net "PU_CPU0_UPI2_AC_COUPLING")
	)
	(arc
		(start 340.61146 -267.43152)
		(mid 340.424262 -267.381377)
		(end 340.237064 -267.43152)
		(width 0.0889)
		(layer "B.Cu")
		(net "PU_CPU0_UPI2_AC_COUPLING")
	)
	(arc
		(start 342.101932 -267.440156)
		(mid 341.825491 -267.507322)
		(end 341.55126 -267.43152)
		(width 0.0889)
		(layer "B.Cu")
		(net "PU_CPU0_UPI2_AC_COUPLING")
	)
	(arc
		(start 338.732114 -267.43152)
		(mid 338.544916 -267.381377)
		(end 338.357718 -267.43152)
		(width 0.0889)
		(layer "B.Cu")
		(net "PU_CPU0_UPI2_AC_COUPLING")
	)
	(arc
		(start 344.925904 -267.437616)
		(mid 344.647472 -267.50743)
		(end 344.37066 -267.43152)
		(width 0.0889)
		(layer "B.Cu")
		(net "PU_CPU0_UPI2_AC_COUPLING")
	)
	(arc
		(start 339.67166 -267.43152)
		(mid 339.484462 -267.381377)
		(end 339.297264 -267.43152)
		(width 0.0889)
		(layer "B.Cu")
		(net "PU_CPU0_UPI2_AC_COUPLING")
	)
	(arc
		(start 343.43086 -267.43152)
		(mid 343.243662 -267.381377)
		(end 343.056464 -267.43152)
		(width 0.0889)
		(layer "B.Cu")
		(net "PU_CPU0_UPI2_AC_COUPLING")
	)
	(arc
		(start 350.94926 -267.43152)
		(mid 350.762062 -267.381377)
		(end 350.574864 -267.43152)
		(width 0.0889)
		(layer "B.Cu")
		(net "PU_CPU0_UPI2_AC_COUPLING")
	)
	(arc
		(start 351.136712 -267.755878)
		(mid 351.089033 -267.572978)
		(end 350.95815 -267.4366)
		(width 0.0889)
		(layer "B.Cu")
		(net "PU_CPU0_UPI2_AC_COUPLING")
	)
	(arc
		(start 339.297264 -267.43152)
		(mid 339.020705 -267.507229)
		(end 338.742528 -267.437616)
		(width 0.0889)
		(layer "B.Cu")
		(net "PU_CPU0_UPI2_AC_COUPLING")
	)
	(arc
		(start 346.25026 -267.43152)
		(mid 346.063062 -267.381377)
		(end 345.875864 -267.43152)
		(width 0.0889)
		(layer "B.Cu")
		(net "PU_CPU0_UPI2_AC_COUPLING")
	)
	(arc
		(start 347.740732 -267.440156)
		(mid 347.464291 -267.507322)
		(end 347.19006 -267.43152)
		(width 0.0889)
		(layer "B.Cu")
		(net "PU_CPU0_UPI2_AC_COUPLING")
	)
	(arc
		(start 336.477864 -267.43152)
		(mid 336.341498 -267.487998)
		(end 336.195162 -267.507212)
		(width 0.0889)
		(layer "B.Cu")
		(net "PU_CPU0_UPI2_AC_COUPLING")
	)
	(arc
		(start 342.49106 -267.43152)
		(mid 342.303862 -267.381377)
		(end 342.116664 -267.43152)
		(width 0.0889)
		(layer "B.Cu")
		(net "PU_CPU0_UPI2_AC_COUPLING")
	)
	(arc
		(start 338.357718 -267.43152)
		(mid 338.080905 -267.507356)
		(end 337.802474 -267.437616)
		(width 0.0889)
		(layer "B.Cu")
		(net "PU_CPU0_UPI2_AC_COUPLING")
	)
	(arc
		(start 343.981532 -267.440156)
		(mid 343.705091 -267.507322)
		(end 343.43086 -267.43152)
		(width 0.0889)
		(layer "B.Cu")
		(net "PU_CPU0_UPI2_AC_COUPLING")
	)
	(arc
		(start 341.162132 -267.440156)
		(mid 340.885691 -267.507322)
		(end 340.61146 -267.43152)
		(width 0.0889)
		(layer "B.Cu")
		(net "PU_CPU0_UPI2_AC_COUPLING")
	)
	(arc
		(start 344.37066 -267.43152)
		(mid 344.183462 -267.381377)
		(end 343.996264 -267.43152)
		(width 0.0889)
		(layer "B.Cu")
		(net "PU_CPU0_UPI2_AC_COUPLING")
	)
	(arc
		(start 340.222332 -267.440156)
		(mid 339.945891 -267.507322)
		(end 339.67166 -267.43152)
		(width 0.0889)
		(layer "B.Cu")
		(net "PU_CPU0_UPI2_AC_COUPLING")
	)
	(arc
		(start 346.800932 -267.440156)
		(mid 346.524491 -267.507322)
		(end 346.25026 -267.43152)
		(width 0.0889)
		(layer "B.Cu")
		(net "PU_CPU0_UPI2_AC_COUPLING")
	)
	(arc
		(start 350.560132 -267.440156)
		(mid 350.283691 -267.507322)
		(end 350.00946 -267.43152)
		(width 0.0889)
		(layer "B.Cu")
		(net "PU_CPU0_UPI2_AC_COUPLING")
	)
	(arc
		(start 351.413318 -268.24178)
		(mid 351.210731 -268.035429)
		(end 351.136712 -267.755878)
		(width 0.0889)
		(layer "B.Cu")
		(net "PU_CPU0_UPI2_AC_COUPLING")
	)
	(arc
		(start 341.55126 -267.43152)
		(mid 341.364062 -267.381377)
		(end 341.176864 -267.43152)
		(width 0.0889)
		(layer "B.Cu")
		(net "PU_CPU0_UPI2_AC_COUPLING")
	)
	(arc
		(start 348.680532 -267.440156)
		(mid 348.404091 -267.507322)
		(end 348.12986 -267.43152)
		(width 0.0889)
		(layer "B.Cu")
		(net "PU_CPU0_UPI2_AC_COUPLING")
	)
	(arc
		(start 348.12986 -267.43152)
		(mid 347.942662 -267.381377)
		(end 347.755464 -267.43152)
		(width 0.0889)
		(layer "B.Cu")
		(net "PU_CPU0_UPI2_AC_COUPLING")
	)
	(arc
		(start 345.310714 -267.43152)
		(mid 345.123516 -267.381377)
		(end 344.936318 -267.43152)
		(width 0.0889)
		(layer "B.Cu")
		(net "PU_CPU0_UPI2_AC_COUPLING")
	)
	(arc
		(start 345.875864 -267.43152)
		(mid 345.599305 -267.507229)
		(end 345.321128 -267.437616)
		(width 0.0889)
		(layer "B.Cu")
		(net "PU_CPU0_UPI2_AC_COUPLING")
	)
	(arc
		(start 347.19006 -267.43152)
		(mid 347.002862 -267.381377)
		(end 346.815664 -267.43152)
		(width 0.0889)
		(layer "B.Cu")
		(net "PU_CPU0_UPI2_AC_COUPLING")
	)
	(arc
		(start 336.85226 -267.43152)
		(mid 336.665062 -267.381377)
		(end 336.477864 -267.43152)
		(width 0.0889)
		(layer "B.Cu")
		(net "PU_CPU0_UPI2_AC_COUPLING")
	)
	(arc
		(start 349.06966 -267.43152)
		(mid 348.882462 -267.381377)
		(end 348.695264 -267.43152)
		(width 0.0889)
		(layer "B.Cu")
		(net "PU_CPU0_UPI2_AC_COUPLING")
	)
	(arc
		(start 343.041732 -267.440156)
		(mid 342.765291 -267.507322)
		(end 342.49106 -267.43152)
		(width 0.0889)
		(layer "B.Cu")
		(net "PU_CPU0_UPI2_AC_COUPLING")
	)
	(arc
		(start 349.957644 -267.406882)
		(mid 349.793548 -267.382535)
		(end 349.635064 -267.43152)
		(width 0.0889)
		(layer "B.Cu")
		(net "PU_CPU0_UPI2_AC_COUPLING")
	)
	(arc
		(start 337.79206 -267.43152)
		(mid 337.604862 -267.381377)
		(end 337.417664 -267.43152)
		(width 0.0889)
		(layer "B.Cu")
		(net "PU_CPU0_UPI2_AC_COUPLING")
	)
	(arc
		(start 337.417664 -267.43152)
		(mid 337.134962 -267.507262)
		(end 336.85226 -267.43152)
		(width 0.0889)
		(layer "B.Cu")
		(net "PU_CPU0_UPI2_AC_COUPLING")
	)
	(segment
		(start 369.44808 -228.994716)
		(end 369.44808 -228.45903)
		(width 0.12954)
		(layer "F.Cu")
		(net "PU_CPU0_UPI1_AC_COUPLING")
	)
	(segment
		(start 369.448334 -228.99497)
		(end 369.44808 -228.994716)
		(width 0.12954)
		(layer "F.Cu")
		(net "PU_CPU0_UPI1_AC_COUPLING")
	)
	(via
		(at 369.44808 -228.45903)
		(size 0.4572)
		(drill 0.2032)
		(layers "F.Cu" "B.Cu")
		(net "PU_CPU0_UPI1_AC_COUPLING")
	)
	(via
		(at 391.268204 -217.31097)
		(size 0.6604)
		(drill 0.3302)
		(layers "F.Cu" "B.Cu")
		(net "PU_CPU0_UPI1_AC_COUPLING")
	)
	(segment
		(start 383.358136 -228.783388)
		(end 383.347722 -228.777292)
		(width 0.0889)
		(layer "B.Cu")
		(net "PU_CPU0_UPI1_AC_COUPLING")
	)
	(segment
		(start 380.538736 -228.783388)
		(end 380.528322 -228.777292)
		(width 0.0889)
		(layer "B.Cu")
		(net "PU_CPU0_UPI1_AC_COUPLING")
	)
	(segment
		(start 374.899682 -228.783388)
		(end 374.889268 -228.777292)
		(width 0.0889)
		(layer "B.Cu")
		(net "PU_CPU0_UPI1_AC_COUPLING")
	)
	(segment
		(start 391.268204 -224.199958)
		(end 386.800852 -228.66731)
		(width 0.12954)
		(layer "B.Cu")
		(net "PU_CPU0_UPI1_AC_COUPLING")
	)
	(segment
		(start 391.268204 -217.31097)
		(end 391.268204 -224.199958)
		(width 0.12954)
		(layer "B.Cu")
		(net "PU_CPU0_UPI1_AC_COUPLING")
	)
	(segment
		(start 372.080282 -228.783388)
		(end 372.06555 -228.774752)
		(width 0.0889)
		(layer "B.Cu")
		(net "PU_CPU0_UPI1_AC_COUPLING")
	)
	(segment
		(start 373.020082 -228.783388)
		(end 373.00535 -228.774752)
		(width 0.0889)
		(layer "B.Cu")
		(net "PU_CPU0_UPI1_AC_COUPLING")
	)
	(segment
		(start 382.418082 -228.783388)
		(end 382.407668 -228.777292)
		(width 0.0889)
		(layer "B.Cu")
		(net "PU_CPU0_UPI1_AC_COUPLING")
	)
	(segment
		(start 370.18595 -228.774752)
		(end 369.44808 -228.45903)
		(width 0.0889)
		(layer "B.Cu")
		(net "PU_CPU0_UPI1_AC_COUPLING")
	)
	(segment
		(start 378.658882 -228.783388)
		(end 378.64415 -228.774752)
		(width 0.0889)
		(layer "B.Cu")
		(net "PU_CPU0_UPI1_AC_COUPLING")
	)
	(segment
		(start 384.78841 -228.66731)
		(end 384.672332 -228.783388)
		(width 0.0889)
		(layer "B.Cu")
		(net "PU_CPU0_UPI1_AC_COUPLING")
	)
	(segment
		(start 384.750818 -195.22567)
		(end 386.09905 -195.22567)
		(width 0.12954)
		(layer "B.Cu")
		(net "PU_CPU0_UPI1_AC_COUPLING")
	)
	(segment
		(start 391.268204 -200.394824)
		(end 391.268204 -217.31097)
		(width 0.12954)
		(layer "B.Cu")
		(net "PU_CPU0_UPI1_AC_COUPLING")
	)
	(segment
		(start 370.200682 -228.783388)
		(end 370.18595 -228.774752)
		(width 0.0889)
		(layer "B.Cu")
		(net "PU_CPU0_UPI1_AC_COUPLING")
	)
	(segment
		(start 373.960136 -228.783388)
		(end 373.949722 -228.777292)
		(width 0.0889)
		(layer "B.Cu")
		(net "PU_CPU0_UPI1_AC_COUPLING")
	)
	(segment
		(start 376.779282 -228.783388)
		(end 376.76455 -228.774752)
		(width 0.0889)
		(layer "B.Cu")
		(net "PU_CPU0_UPI1_AC_COUPLING")
	)
	(segment
		(start 381.92583 -192.400682)
		(end 384.750818 -195.22567)
		(width 0.12954)
		(layer "B.Cu")
		(net "PU_CPU0_UPI1_AC_COUPLING")
	)
	(segment
		(start 381.92583 -191.22136)
		(end 381.92583 -192.400682)
		(width 0.12954)
		(layer "B.Cu")
		(net "PU_CPU0_UPI1_AC_COUPLING")
	)
	(segment
		(start 379.598682 -228.783388)
		(end 379.58395 -228.774752)
		(width 0.0889)
		(layer "B.Cu")
		(net "PU_CPU0_UPI1_AC_COUPLING")
	)
	(segment
		(start 386.800852 -228.66731)
		(end 385.385564 -228.66731)
		(width 0.12954)
		(layer "B.Cu")
		(net "PU_CPU0_UPI1_AC_COUPLING")
	)
	(segment
		(start 375.839482 -228.783388)
		(end 375.82475 -228.774752)
		(width 0.0889)
		(layer "B.Cu")
		(net "PU_CPU0_UPI1_AC_COUPLING")
	)
	(segment
		(start 385.385564 -228.66731)
		(end 384.78841 -228.66731)
		(width 0.0889)
		(layer "B.Cu")
		(net "PU_CPU0_UPI1_AC_COUPLING")
	)
	(segment
		(start 386.09905 -195.22567)
		(end 391.268204 -200.394824)
		(width 0.12954)
		(layer "B.Cu")
		(net "PU_CPU0_UPI1_AC_COUPLING")
	)
	(arc
		(start 370.575078 -228.783388)
		(mid 370.38788 -228.833531)
		(end 370.200682 -228.783388)
		(width 0.0889)
		(layer "B.Cu")
		(net "PU_CPU0_UPI1_AC_COUPLING")
	)
	(arc
		(start 371.140482 -228.783388)
		(mid 370.85778 -228.707612)
		(end 370.575078 -228.783388)
		(width 0.0889)
		(layer "B.Cu")
		(net "PU_CPU0_UPI1_AC_COUPLING")
	)
	(arc
		(start 373.949722 -228.777292)
		(mid 373.67129 -228.707446)
		(end 373.394478 -228.783388)
		(width 0.0889)
		(layer "B.Cu")
		(net "PU_CPU0_UPI1_AC_COUPLING")
	)
	(arc
		(start 377.153678 -228.783388)
		(mid 376.96648 -228.833531)
		(end 376.779282 -228.783388)
		(width 0.0889)
		(layer "B.Cu")
		(net "PU_CPU0_UPI1_AC_COUPLING")
	)
	(arc
		(start 373.00535 -228.774752)
		(mid 372.728875 -228.707432)
		(end 372.454678 -228.783388)
		(width 0.0889)
		(layer "B.Cu")
		(net "PU_CPU0_UPI1_AC_COUPLING")
	)
	(arc
		(start 380.528322 -228.777292)
		(mid 380.24989 -228.707446)
		(end 379.973078 -228.783388)
		(width 0.0889)
		(layer "B.Cu")
		(net "PU_CPU0_UPI1_AC_COUPLING")
	)
	(arc
		(start 378.64415 -228.774752)
		(mid 378.367675 -228.707432)
		(end 378.093478 -228.783388)
		(width 0.0889)
		(layer "B.Cu")
		(net "PU_CPU0_UPI1_AC_COUPLING")
	)
	(arc
		(start 383.347722 -228.777292)
		(mid 383.06929 -228.707446)
		(end 382.792478 -228.783388)
		(width 0.0889)
		(layer "B.Cu")
		(net "PU_CPU0_UPI1_AC_COUPLING")
	)
	(arc
		(start 382.407668 -228.777292)
		(mid 382.12949 -228.707569)
		(end 381.852932 -228.783388)
		(width 0.0889)
		(layer "B.Cu")
		(net "PU_CPU0_UPI1_AC_COUPLING")
	)
	(arc
		(start 381.478536 -228.783388)
		(mid 381.195834 -228.707612)
		(end 380.913132 -228.783388)
		(width 0.0889)
		(layer "B.Cu")
		(net "PU_CPU0_UPI1_AC_COUPLING")
	)
	(arc
		(start 382.792478 -228.783388)
		(mid 382.60528 -228.833531)
		(end 382.418082 -228.783388)
		(width 0.0889)
		(layer "B.Cu")
		(net "PU_CPU0_UPI1_AC_COUPLING")
	)
	(arc
		(start 373.394478 -228.783388)
		(mid 373.20728 -228.833531)
		(end 373.020082 -228.783388)
		(width 0.0889)
		(layer "B.Cu")
		(net "PU_CPU0_UPI1_AC_COUPLING")
	)
	(arc
		(start 372.06555 -228.774752)
		(mid 371.789075 -228.707432)
		(end 371.514878 -228.783388)
		(width 0.0889)
		(layer "B.Cu")
		(net "PU_CPU0_UPI1_AC_COUPLING")
	)
	(arc
		(start 374.334532 -228.783388)
		(mid 374.147334 -228.833531)
		(end 373.960136 -228.783388)
		(width 0.0889)
		(layer "B.Cu")
		(net "PU_CPU0_UPI1_AC_COUPLING")
	)
	(arc
		(start 372.454678 -228.783388)
		(mid 372.26748 -228.833531)
		(end 372.080282 -228.783388)
		(width 0.0889)
		(layer "B.Cu")
		(net "PU_CPU0_UPI1_AC_COUPLING")
	)
	(arc
		(start 380.913132 -228.783388)
		(mid 380.725934 -228.833531)
		(end 380.538736 -228.783388)
		(width 0.0889)
		(layer "B.Cu")
		(net "PU_CPU0_UPI1_AC_COUPLING")
	)
	(arc
		(start 375.274078 -228.783388)
		(mid 375.08688 -228.833531)
		(end 374.899682 -228.783388)
		(width 0.0889)
		(layer "B.Cu")
		(net "PU_CPU0_UPI1_AC_COUPLING")
	)
	(arc
		(start 375.82475 -228.774752)
		(mid 375.548275 -228.707432)
		(end 375.274078 -228.783388)
		(width 0.0889)
		(layer "B.Cu")
		(net "PU_CPU0_UPI1_AC_COUPLING")
	)
	(arc
		(start 378.093478 -228.783388)
		(mid 377.90628 -228.833531)
		(end 377.719082 -228.783388)
		(width 0.0889)
		(layer "B.Cu")
		(net "PU_CPU0_UPI1_AC_COUPLING")
	)
	(arc
		(start 376.213878 -228.783388)
		(mid 376.02668 -228.833531)
		(end 375.839482 -228.783388)
		(width 0.0889)
		(layer "B.Cu")
		(net "PU_CPU0_UPI1_AC_COUPLING")
	)
	(arc
		(start 379.973078 -228.783388)
		(mid 379.78588 -228.833531)
		(end 379.598682 -228.783388)
		(width 0.0889)
		(layer "B.Cu")
		(net "PU_CPU0_UPI1_AC_COUPLING")
	)
	(arc
		(start 379.58395 -228.774752)
		(mid 379.307475 -228.707432)
		(end 379.033278 -228.783388)
		(width 0.0889)
		(layer "B.Cu")
		(net "PU_CPU0_UPI1_AC_COUPLING")
	)
	(arc
		(start 376.76455 -228.774752)
		(mid 376.488075 -228.707432)
		(end 376.213878 -228.783388)
		(width 0.0889)
		(layer "B.Cu")
		(net "PU_CPU0_UPI1_AC_COUPLING")
	)
	(arc
		(start 371.514878 -228.783388)
		(mid 371.32768 -228.833531)
		(end 371.140482 -228.783388)
		(width 0.0889)
		(layer "B.Cu")
		(net "PU_CPU0_UPI1_AC_COUPLING")
	)
	(arc
		(start 381.852932 -228.783388)
		(mid 381.665734 -228.833531)
		(end 381.478536 -228.783388)
		(width 0.0889)
		(layer "B.Cu")
		(net "PU_CPU0_UPI1_AC_COUPLING")
	)
	(arc
		(start 384.672332 -228.783388)
		(mid 384.485134 -228.833531)
		(end 384.297936 -228.783388)
		(width 0.0889)
		(layer "B.Cu")
		(net "PU_CPU0_UPI1_AC_COUPLING")
	)
	(arc
		(start 384.297936 -228.783388)
		(mid 384.015234 -228.707612)
		(end 383.732532 -228.783388)
		(width 0.0889)
		(layer "B.Cu")
		(net "PU_CPU0_UPI1_AC_COUPLING")
	)
	(arc
		(start 374.889268 -228.777292)
		(mid 374.61109 -228.707569)
		(end 374.334532 -228.783388)
		(width 0.0889)
		(layer "B.Cu")
		(net "PU_CPU0_UPI1_AC_COUPLING")
	)
	(arc
		(start 377.719082 -228.783388)
		(mid 377.43638 -228.707612)
		(end 377.153678 -228.783388)
		(width 0.0889)
		(layer "B.Cu")
		(net "PU_CPU0_UPI1_AC_COUPLING")
	)
	(arc
		(start 383.732532 -228.783388)
		(mid 383.545334 -228.833531)
		(end 383.358136 -228.783388)
		(width 0.0889)
		(layer "B.Cu")
		(net "PU_CPU0_UPI1_AC_COUPLING")
	)
	(arc
		(start 379.033278 -228.783388)
		(mid 378.84608 -228.833531)
		(end 378.658882 -228.783388)
		(width 0.0889)
		(layer "B.Cu")
		(net "PU_CPU0_UPI1_AC_COUPLING")
	)
	(segment
		(start 351.592134 -232.250488)
		(end 351.592134 -231.714802)
		(width 0.12954)
		(layer "F.Cu")
		(net "PU_CPU0_UPI0_AC_COUPLING")
	)
	(segment
		(start 351.592134 -231.714802)
		(end 351.59188 -231.714548)
		(width 0.12954)
		(layer "F.Cu")
		(net "PU_CPU0_UPI0_AC_COUPLING")
	)
	(via
		(at 351.59188 -231.714548)
		(size 0.4572)
		(drill 0.2032)
		(layers "F.Cu" "B.Cu")
		(net "PU_CPU0_UPI0_AC_COUPLING")
	)
	(via
		(at 319.758314 -223.905318)
		(size 0.6604)
		(drill 0.3302)
		(layers "F.Cu" "B.Cu")
		(net "PU_CPU0_UPI0_AC_COUPLING")
	)
	(segment
		(start 345.765882 -229.762304)
		(end 345.755468 -229.7684)
		(width 0.0889)
		(layer "B.Cu")
		(net "PU_CPU0_UPI0_AC_COUPLING")
	)
	(segment
		(start 335.475072 -229.622604)
		(end 334.302354 -229.622604)
		(width 0.0889)
		(layer "B.Cu")
		(net "PU_CPU0_UPI0_AC_COUPLING")
	)
	(segment
		(start 334.074008 -229.85095)
		(end 333.733902 -230.191056)
		(width 0.12954)
		(layer "B.Cu")
		(net "PU_CPU0_UPI0_AC_COUPLING")
	)
	(segment
		(start 351.59188 -231.714548)
		(end 351.435416 -231.44353)
		(width 0.0889)
		(layer "B.Cu")
		(net "PU_CPU0_UPI0_AC_COUPLING")
	)
	(segment
		(start 334.302354 -229.622604)
		(end 334.074008 -229.85095)
		(width 0.0889)
		(layer "B.Cu")
		(net "PU_CPU0_UPI0_AC_COUPLING")
	)
	(segment
		(start 315.9633 -197.409562)
		(end 315.9633 -194.36842)
		(width 0.12954)
		(layer "B.Cu")
		(net "PU_CPU0_UPI0_AC_COUPLING")
	)
	(segment
		(start 343.886282 -229.762304)
		(end 343.87155 -229.77094)
		(width 0.0889)
		(layer "B.Cu")
		(net "PU_CPU0_UPI0_AC_COUPLING")
	)
	(segment
		(start 338.247736 -229.762304)
		(end 338.237322 -229.7684)
		(width 0.0889)
		(layer "B.Cu")
		(net "PU_CPU0_UPI0_AC_COUPLING")
	)
	(segment
		(start 341.066882 -229.762304)
		(end 341.05215 -229.77094)
		(width 0.0889)
		(layer "B.Cu")
		(net "PU_CPU0_UPI0_AC_COUPLING")
	)
	(segment
		(start 344.826336 -229.762304)
		(end 344.815922 -229.7684)
		(width 0.0889)
		(layer "B.Cu")
		(net "PU_CPU0_UPI0_AC_COUPLING")
	)
	(segment
		(start 350.369632 -230.57612)
		(end 350.363536 -230.572564)
		(width 0.0889)
		(layer "B.Cu")
		(net "PU_CPU0_UPI0_AC_COUPLING")
	)
	(segment
		(start 316.10554 -197.551802)
		(end 315.9633 -197.409562)
		(width 0.12954)
		(layer "B.Cu")
		(net "PU_CPU0_UPI0_AC_COUPLING")
	)
	(segment
		(start 350.378522 -230.5812)
		(end 350.369632 -230.57612)
		(width 0.0889)
		(layer "B.Cu")
		(net "PU_CPU0_UPI0_AC_COUPLING")
	)
	(segment
		(start 349.908368 -229.767384)
		(end 349.899478 -229.762304)
		(width 0.0889)
		(layer "B.Cu")
		(net "PU_CPU0_UPI0_AC_COUPLING")
	)
	(segment
		(start 350.557084 -230.922576)
		(end 350.557084 -230.900478)
		(width 0.0889)
		(layer "B.Cu")
		(net "PU_CPU0_UPI0_AC_COUPLING")
	)
	(segment
		(start 346.705682 -229.762304)
		(end 346.69095 -229.77094)
		(width 0.0889)
		(layer "B.Cu")
		(net "PU_CPU0_UPI0_AC_COUPLING")
	)
	(segment
		(start 347.645482 -229.762304)
		(end 347.63075 -229.77094)
		(width 0.0889)
		(layer "B.Cu")
		(net "PU_CPU0_UPI0_AC_COUPLING")
	)
	(segment
		(start 333.733902 -230.191056)
		(end 330.412598 -230.191056)
		(width 0.12954)
		(layer "B.Cu")
		(net "PU_CPU0_UPI0_AC_COUPLING")
	)
	(segment
		(start 342.006682 -229.762304)
		(end 341.99195 -229.77094)
		(width 0.0889)
		(layer "B.Cu")
		(net "PU_CPU0_UPI0_AC_COUPLING")
	)
	(segment
		(start 339.187282 -229.762304)
		(end 339.176868 -229.7684)
		(width 0.0889)
		(layer "B.Cu")
		(net "PU_CPU0_UPI0_AC_COUPLING")
	)
	(segment
		(start 329.889612 -229.66807)
		(end 325.521066 -229.66807)
		(width 0.12954)
		(layer "B.Cu")
		(net "PU_CPU0_UPI0_AC_COUPLING")
	)
	(segment
		(start 325.521066 -229.66807)
		(end 319.758314 -223.905318)
		(width 0.12954)
		(layer "B.Cu")
		(net "PU_CPU0_UPI0_AC_COUPLING")
	)
	(segment
		(start 330.412598 -230.191056)
		(end 329.889612 -229.66807)
		(width 0.12954)
		(layer "B.Cu")
		(net "PU_CPU0_UPI0_AC_COUPLING")
	)
	(segment
		(start 319.758314 -223.905318)
		(end 316.10554 -220.252544)
		(width 0.12954)
		(layer "B.Cu")
		(net "PU_CPU0_UPI0_AC_COUPLING")
	)
	(segment
		(start 351.435416 -231.44353)
		(end 351.346516 -231.419908)
		(width 0.0889)
		(layer "B.Cu")
		(net "PU_CPU0_UPI0_AC_COUPLING")
	)
	(segment
		(start 337.307682 -229.762304)
		(end 337.29295 -229.77094)
		(width 0.0889)
		(layer "B.Cu")
		(net "PU_CPU0_UPI0_AC_COUPLING")
	)
	(segment
		(start 348.585282 -229.762304)
		(end 348.57055 -229.77094)
		(width 0.0889)
		(layer "B.Cu")
		(net "PU_CPU0_UPI0_AC_COUPLING")
	)
	(segment
		(start 316.10554 -220.252544)
		(end 316.10554 -197.551802)
		(width 0.12954)
		(layer "B.Cu")
		(net "PU_CPU0_UPI0_AC_COUPLING")
	)
	(segment
		(start 335.690464 -229.837996)
		(end 335.475072 -229.622604)
		(width 0.0889)
		(layer "B.Cu")
		(net "PU_CPU0_UPI0_AC_COUPLING")
	)
	(segment
		(start 315.9633 -194.36842)
		(end 315.53404 -193.93916)
		(width 0.12954)
		(layer "B.Cu")
		(net "PU_CPU0_UPI0_AC_COUPLING")
	)
	(segment
		(start 336.085434 -229.837996)
		(end 335.690464 -229.837996)
		(width 0.0889)
		(layer "B.Cu")
		(net "PU_CPU0_UPI0_AC_COUPLING")
	)
	(segment
		(start 340.127082 -229.762304)
		(end 340.11235 -229.77094)
		(width 0.0889)
		(layer "B.Cu")
		(net "PU_CPU0_UPI0_AC_COUPLING")
	)
	(arc
		(start 338.622132 -229.762304)
		(mid 338.434934 -229.712161)
		(end 338.247736 -229.762304)
		(width 0.0889)
		(layer "B.Cu")
		(net "PU_CPU0_UPI0_AC_COUPLING")
	)
	(arc
		(start 341.441278 -229.762304)
		(mid 341.25408 -229.712161)
		(end 341.066882 -229.762304)
		(width 0.0889)
		(layer "B.Cu")
		(net "PU_CPU0_UPI0_AC_COUPLING")
	)
	(arc
		(start 350.839278 -231.39019)
		(mid 350.637996 -231.192703)
		(end 350.557084 -230.922576)
		(width 0.0889)
		(layer "B.Cu")
		(net "PU_CPU0_UPI0_AC_COUPLING")
	)
	(arc
		(start 348.959678 -229.762304)
		(mid 348.77248 -229.712161)
		(end 348.585282 -229.762304)
		(width 0.0889)
		(layer "B.Cu")
		(net "PU_CPU0_UPI0_AC_COUPLING")
	)
	(arc
		(start 343.87155 -229.77094)
		(mid 343.595075 -229.83826)
		(end 343.320878 -229.762304)
		(width 0.0889)
		(layer "B.Cu")
		(net "PU_CPU0_UPI0_AC_COUPLING")
	)
	(arc
		(start 351.346516 -231.419908)
		(mid 351.089377 -231.46519)
		(end 350.839278 -231.39019)
		(width 0.0889)
		(layer "B.Cu")
		(net "PU_CPU0_UPI0_AC_COUPLING")
	)
	(arc
		(start 341.05215 -229.77094)
		(mid 340.775675 -229.83826)
		(end 340.501478 -229.762304)
		(width 0.0889)
		(layer "B.Cu")
		(net "PU_CPU0_UPI0_AC_COUPLING")
	)
	(arc
		(start 347.080078 -229.762304)
		(mid 346.89288 -229.712161)
		(end 346.705682 -229.762304)
		(width 0.0889)
		(layer "B.Cu")
		(net "PU_CPU0_UPI0_AC_COUPLING")
	)
	(arc
		(start 345.755468 -229.7684)
		(mid 345.47729 -229.838123)
		(end 345.200732 -229.762304)
		(width 0.0889)
		(layer "B.Cu")
		(net "PU_CPU0_UPI0_AC_COUPLING")
	)
	(arc
		(start 338.237322 -229.7684)
		(mid 337.95889 -229.838246)
		(end 337.682078 -229.762304)
		(width 0.0889)
		(layer "B.Cu")
		(net "PU_CPU0_UPI0_AC_COUPLING")
	)
	(arc
		(start 339.176868 -229.7684)
		(mid 338.89869 -229.838123)
		(end 338.622132 -229.762304)
		(width 0.0889)
		(layer "B.Cu")
		(net "PU_CPU0_UPI0_AC_COUPLING")
	)
	(arc
		(start 342.946482 -229.762304)
		(mid 342.66378 -229.83808)
		(end 342.381078 -229.762304)
		(width 0.0889)
		(layer "B.Cu")
		(net "PU_CPU0_UPI0_AC_COUPLING")
	)
	(arc
		(start 343.320878 -229.762304)
		(mid 343.13368 -229.712161)
		(end 342.946482 -229.762304)
		(width 0.0889)
		(layer "B.Cu")
		(net "PU_CPU0_UPI0_AC_COUPLING")
	)
	(arc
		(start 342.381078 -229.762304)
		(mid 342.19388 -229.712161)
		(end 342.006682 -229.762304)
		(width 0.0889)
		(layer "B.Cu")
		(net "PU_CPU0_UPI0_AC_COUPLING")
	)
	(arc
		(start 348.57055 -229.77094)
		(mid 348.294075 -229.83826)
		(end 348.019878 -229.762304)
		(width 0.0889)
		(layer "B.Cu")
		(net "PU_CPU0_UPI0_AC_COUPLING")
	)
	(arc
		(start 349.525082 -229.762304)
		(mid 349.24238 -229.83808)
		(end 348.959678 -229.762304)
		(width 0.0889)
		(layer "B.Cu")
		(net "PU_CPU0_UPI0_AC_COUPLING")
	)
	(arc
		(start 344.260678 -229.762304)
		(mid 344.07348 -229.712161)
		(end 343.886282 -229.762304)
		(width 0.0889)
		(layer "B.Cu")
		(net "PU_CPU0_UPI0_AC_COUPLING")
	)
	(arc
		(start 346.140278 -229.762304)
		(mid 345.95308 -229.712161)
		(end 345.765882 -229.762304)
		(width 0.0889)
		(layer "B.Cu")
		(net "PU_CPU0_UPI0_AC_COUPLING")
	)
	(arc
		(start 350.363536 -230.572564)
		(mid 350.160949 -230.366213)
		(end 350.08693 -230.086662)
		(width 0.0889)
		(layer "B.Cu")
		(net "PU_CPU0_UPI0_AC_COUPLING")
	)
	(arc
		(start 344.815922 -229.7684)
		(mid 344.53749 -229.838246)
		(end 344.260678 -229.762304)
		(width 0.0889)
		(layer "B.Cu")
		(net "PU_CPU0_UPI0_AC_COUPLING")
	)
	(arc
		(start 340.11235 -229.77094)
		(mid 339.835875 -229.83826)
		(end 339.561678 -229.762304)
		(width 0.0889)
		(layer "B.Cu")
		(net "PU_CPU0_UPI0_AC_COUPLING")
	)
	(arc
		(start 340.501478 -229.762304)
		(mid 340.31428 -229.712161)
		(end 340.127082 -229.762304)
		(width 0.0889)
		(layer "B.Cu")
		(net "PU_CPU0_UPI0_AC_COUPLING")
	)
	(arc
		(start 341.99195 -229.77094)
		(mid 341.715475 -229.83826)
		(end 341.441278 -229.762304)
		(width 0.0889)
		(layer "B.Cu")
		(net "PU_CPU0_UPI0_AC_COUPLING")
	)
	(arc
		(start 348.019878 -229.762304)
		(mid 347.83268 -229.712161)
		(end 347.645482 -229.762304)
		(width 0.0889)
		(layer "B.Cu")
		(net "PU_CPU0_UPI0_AC_COUPLING")
	)
	(arc
		(start 336.367882 -229.762304)
		(mid 336.23164 -229.818738)
		(end 336.085434 -229.837996)
		(width 0.0889)
		(layer "B.Cu")
		(net "PU_CPU0_UPI0_AC_COUPLING")
	)
	(arc
		(start 349.899478 -229.762304)
		(mid 349.71228 -229.712161)
		(end 349.525082 -229.762304)
		(width 0.0889)
		(layer "B.Cu")
		(net "PU_CPU0_UPI0_AC_COUPLING")
	)
	(arc
		(start 345.200732 -229.762304)
		(mid 345.013534 -229.712161)
		(end 344.826336 -229.762304)
		(width 0.0889)
		(layer "B.Cu")
		(net "PU_CPU0_UPI0_AC_COUPLING")
	)
	(arc
		(start 337.29295 -229.77094)
		(mid 337.016475 -229.83826)
		(end 336.742278 -229.762304)
		(width 0.0889)
		(layer "B.Cu")
		(net "PU_CPU0_UPI0_AC_COUPLING")
	)
	(arc
		(start 336.742278 -229.762304)
		(mid 336.55508 -229.712161)
		(end 336.367882 -229.762304)
		(width 0.0889)
		(layer "B.Cu")
		(net "PU_CPU0_UPI0_AC_COUPLING")
	)
	(arc
		(start 337.682078 -229.762304)
		(mid 337.49488 -229.712161)
		(end 337.307682 -229.762304)
		(width 0.0889)
		(layer "B.Cu")
		(net "PU_CPU0_UPI0_AC_COUPLING")
	)
	(arc
		(start 339.561678 -229.762304)
		(mid 339.37448 -229.712161)
		(end 339.187282 -229.762304)
		(width 0.0889)
		(layer "B.Cu")
		(net "PU_CPU0_UPI0_AC_COUPLING")
	)
	(arc
		(start 350.557084 -230.900478)
		(mid 350.509405 -230.717578)
		(end 350.378522 -230.5812)
		(width 0.0889)
		(layer "B.Cu")
		(net "PU_CPU0_UPI0_AC_COUPLING")
	)
	(arc
		(start 350.08693 -230.086662)
		(mid 350.039251 -229.903762)
		(end 349.908368 -229.767384)
		(width 0.0889)
		(layer "B.Cu")
		(net "PU_CPU0_UPI0_AC_COUPLING")
	)
	(arc
		(start 346.69095 -229.77094)
		(mid 346.414475 -229.83826)
		(end 346.140278 -229.762304)
		(width 0.0889)
		(layer "B.Cu")
		(net "PU_CPU0_UPI0_AC_COUPLING")
	)
	(arc
		(start 347.63075 -229.77094)
		(mid 347.354275 -229.83826)
		(end 347.080078 -229.762304)
		(width 0.0889)
		(layer "B.Cu")
		(net "PU_CPU0_UPI0_AC_COUPLING")
	)
	(segment
		(start 358.640888 -234.156504)
		(end 358.640634 -234.15625)
		(width 0.12954)
		(layer "F.Cu")
		(net "PU_CPU0_TXT_AGENT")
	)
	(segment
		(start 358.640634 -234.69219)
		(end 358.640888 -234.691936)
		(width 0.12954)
		(layer "F.Cu")
		(net "PU_CPU0_TXT_AGENT")
	)
	(segment
		(start 358.640888 -234.691936)
		(end 358.640888 -234.156504)
		(width 0.12954)
		(layer "F.Cu")
		(net "PU_CPU0_TXT_AGENT")
	)
	(via
		(at 358.640634 -234.15625)
		(size 0.4572)
		(drill 0.2032)
		(layers "F.Cu" "B.Cu")
		(net "PU_CPU0_TXT_AGENT")
	)
	(via
		(at 329.06589 -221.262702)
		(size 0.6604)
		(drill 0.3302)
		(layers "F.Cu" "B.Cu")
		(net "PU_CPU0_TXT_AGENT")
	)
	(segment
		(start 351.02673 -225.217482)
		(end 351.02673 -225.203258)
		(width 0.0889)
		(layer "B.Cu")
		(net "PU_CPU0_TXT_AGENT")
	)
	(segment
		(start 334.018636 -224.065084)
		(end 334.008222 -224.07118)
		(width 0.0889)
		(layer "B.Cu")
		(net "PU_CPU0_TXT_AGENT")
	)
	(segment
		(start 351.318322 -225.69805)
		(end 351.309432 -225.69297)
		(width 0.0889)
		(layer "B.Cu")
		(net "PU_CPU0_TXT_AGENT")
	)
	(segment
		(start 342.006682 -224.8789)
		(end 341.99195 -224.887536)
		(width 0.0889)
		(layer "B.Cu")
		(net "PU_CPU0_TXT_AGENT")
	)
	(segment
		(start 349.525082 -224.8789)
		(end 349.51035 -224.887536)
		(width 0.0889)
		(layer "B.Cu")
		(net "PU_CPU0_TXT_AGENT")
	)
	(segment
		(start 347.645482 -224.8789)
		(end 347.63075 -224.887536)
		(width 0.0889)
		(layer "B.Cu")
		(net "PU_CPU0_TXT_AGENT")
	)
	(segment
		(start 345.771978 -224.875344)
		(end 345.765882 -224.8789)
		(width 0.0889)
		(layer "B.Cu")
		(net "PU_CPU0_TXT_AGENT")
	)
	(segment
		(start 350.378522 -224.070164)
		(end 350.369632 -224.065084)
		(width 0.0889)
		(layer "B.Cu")
		(net "PU_CPU0_TXT_AGENT")
	)
	(segment
		(start 348.498922 -224.070164)
		(end 348.490032 -224.065084)
		(width 0.0889)
		(layer "B.Cu")
		(net "PU_CPU0_TXT_AGENT")
	)
	(segment
		(start 343.886282 -224.8789)
		(end 343.87155 -224.887536)
		(width 0.0889)
		(layer "B.Cu")
		(net "PU_CPU0_TXT_AGENT")
	)
	(segment
		(start 356.957122 -232.209086)
		(end 356.942136 -232.20045)
		(width 0.0889)
		(layer "B.Cu")
		(net "PU_CPU0_TXT_AGENT")
	)
	(segment
		(start 332.796388 -224.140776)
		(end 332.545436 -224.140776)
		(width 0.0889)
		(layer "B.Cu")
		(net "PU_CPU0_TXT_AGENT")
	)
	(segment
		(start 341.159084 -224.404936)
		(end 341.159084 -224.389442)
		(width 0.0889)
		(layer "B.Cu")
		(net "PU_CPU0_TXT_AGENT")
	)
	(segment
		(start 332.012036 -223.607376)
		(end 331.44968 -223.04502)
		(width 0.12954)
		(layer "B.Cu")
		(net "PU_CPU0_TXT_AGENT")
	)
	(segment
		(start 353.667568 -228.139752)
		(end 353.658678 -228.134672)
		(width 0.0889)
		(layer "B.Cu")
		(net "PU_CPU0_TXT_AGENT")
	)
	(segment
		(start 329.06589 -221.262702)
		(end 325.152258 -217.34907)
		(width 0.12954)
		(layer "B.Cu")
		(net "PU_CPU0_TXT_AGENT")
	)
	(segment
		(start 354.316284 -229.282752)
		(end 354.316284 -229.272846)
		(width 0.0889)
		(layer "B.Cu")
		(net "PU_CPU0_TXT_AGENT")
	)
	(segment
		(start 338.247482 -224.8789)
		(end 338.23275 -224.887536)
		(width 0.0889)
		(layer "B.Cu")
		(net "PU_CPU0_TXT_AGENT")
	)
	(segment
		(start 324.423278 -188.721746)
		(end 324.423278 -187.08624)
		(width 0.12954)
		(layer "B.Cu")
		(net "PU_CPU0_TXT_AGENT")
	)
	(segment
		(start 357.60533 -233.3498)
		(end 357.60533 -233.34218)
		(width 0.0889)
		(layer "B.Cu")
		(net "PU_CPU0_TXT_AGENT")
	)
	(segment
		(start 358.48417 -233.885232)
		(end 358.395016 -233.861356)
		(width 0.0889)
		(layer "B.Cu")
		(net "PU_CPU0_TXT_AGENT")
	)
	(segment
		(start 345.765882 -224.8789)
		(end 345.75115 -224.887536)
		(width 0.0889)
		(layer "B.Cu")
		(net "PU_CPU0_TXT_AGENT")
	)
	(segment
		(start 338.717636 -224.065084)
		(end 338.708746 -224.070164)
		(width 0.0889)
		(layer "B.Cu")
		(net "PU_CPU0_TXT_AGENT")
	)
	(segment
		(start 350.848168 -224.88398)
		(end 350.839278 -224.8789)
		(width 0.0889)
		(layer "B.Cu")
		(net "PU_CPU0_TXT_AGENT")
	)
	(segment
		(start 344.918284 -224.404936)
		(end 344.918284 -224.389442)
		(width 0.0889)
		(layer "B.Cu")
		(net "PU_CPU0_TXT_AGENT")
	)
	(segment
		(start 351.788222 -226.511866)
		(end 351.779332 -226.506786)
		(width 0.0889)
		(layer "B.Cu")
		(net "PU_CPU0_TXT_AGENT")
	)
	(segment
		(start 340.597236 -224.065084)
		(end 340.588346 -224.070164)
		(width 0.0889)
		(layer "B.Cu")
		(net "PU_CPU0_TXT_AGENT")
	)
	(segment
		(start 337.221322 -224.070164)
		(end 337.212432 -224.065084)
		(width 0.0889)
		(layer "B.Cu")
		(net "PU_CPU0_TXT_AGENT")
	)
	(segment
		(start 331.44968 -223.04502)
		(end 330.848208 -223.04502)
		(width 0.12954)
		(layer "B.Cu")
		(net "PU_CPU0_TXT_AGENT")
	)
	(segment
		(start 349.995236 -224.065084)
		(end 349.986346 -224.070164)
		(width 0.0889)
		(layer "B.Cu")
		(net "PU_CPU0_TXT_AGENT")
	)
	(segment
		(start 349.531178 -224.875344)
		(end 349.525082 -224.8789)
		(width 0.0889)
		(layer "B.Cu")
		(net "PU_CPU0_TXT_AGENT")
	)
	(segment
		(start 338.253578 -224.875344)
		(end 338.247482 -224.8789)
		(width 0.0889)
		(layer "B.Cu")
		(net "PU_CPU0_TXT_AGENT")
	)
	(segment
		(start 340.133178 -224.875344)
		(end 340.127082 -224.8789)
		(width 0.0889)
		(layer "B.Cu")
		(net "PU_CPU0_TXT_AGENT")
	)
	(segment
		(start 357.135684 -232.543858)
		(end 357.135684 -232.528364)
		(width 0.0889)
		(layer "B.Cu")
		(net "PU_CPU0_TXT_AGENT")
	)
	(segment
		(start 355.068632 -230.57612)
		(end 355.062536 -230.572564)
		(width 0.0889)
		(layer "B.Cu")
		(net "PU_CPU0_TXT_AGENT")
	)
	(segment
		(start 339.100922 -224.070164)
		(end 339.092032 -224.065084)
		(width 0.0889)
		(layer "B.Cu")
		(net "PU_CPU0_TXT_AGENT")
	)
	(segment
		(start 354.78593 -230.086662)
		(end 354.78593 -230.078026)
		(width 0.0889)
		(layer "B.Cu")
		(net "PU_CPU0_TXT_AGENT")
	)
	(segment
		(start 330.848208 -223.04502)
		(end 329.06589 -221.262702)
		(width 0.12954)
		(layer "B.Cu")
		(net "PU_CPU0_TXT_AGENT")
	)
	(segment
		(start 337.399884 -224.404936)
		(end 337.399884 -224.389442)
		(width 0.0889)
		(layer "B.Cu")
		(net "PU_CPU0_TXT_AGENT")
	)
	(segment
		(start 355.25583 -230.922576)
		(end 355.25583 -230.891842)
		(width 0.0889)
		(layer "B.Cu")
		(net "PU_CPU0_TXT_AGENT")
	)
	(segment
		(start 351.496884 -226.027234)
		(end 351.496884 -226.017328)
		(width 0.0889)
		(layer "B.Cu")
		(net "PU_CPU0_TXT_AGENT")
	)
	(segment
		(start 347.651578 -224.875344)
		(end 347.645482 -224.8789)
		(width 0.0889)
		(layer "B.Cu")
		(net "PU_CPU0_TXT_AGENT")
	)
	(segment
		(start 344.356436 -224.065084)
		(end 344.347546 -224.070164)
		(width 0.0889)
		(layer "B.Cu")
		(net "PU_CPU0_TXT_AGENT")
	)
	(segment
		(start 348.677484 -224.404936)
		(end 348.677484 -224.389442)
		(width 0.0889)
		(layer "B.Cu")
		(net "PU_CPU0_TXT_AGENT")
	)
	(segment
		(start 340.127082 -224.8789)
		(end 340.11235 -224.887536)
		(width 0.0889)
		(layer "B.Cu")
		(net "PU_CPU0_TXT_AGENT")
	)
	(segment
		(start 352.436684 -227.667058)
		(end 352.436684 -227.64496)
		(width 0.0889)
		(layer "B.Cu")
		(net "PU_CPU0_TXT_AGENT")
	)
	(segment
		(start 342.860122 -224.070164)
		(end 342.851232 -224.065084)
		(width 0.0889)
		(layer "B.Cu")
		(net "PU_CPU0_TXT_AGENT")
	)
	(segment
		(start 350.557084 -224.404936)
		(end 350.557084 -224.389442)
		(width 0.0889)
		(layer "B.Cu")
		(net "PU_CPU0_TXT_AGENT")
	)
	(segment
		(start 354.137722 -228.953568)
		(end 354.128832 -228.948488)
		(width 0.0889)
		(layer "B.Cu")
		(net "PU_CPU0_TXT_AGENT")
	)
	(segment
		(start 344.739722 -224.070164)
		(end 344.730832 -224.065084)
		(width 0.0889)
		(layer "B.Cu")
		(net "PU_CPU0_TXT_AGENT")
	)
	(segment
		(start 339.279484 -224.404936)
		(end 339.279484 -224.389442)
		(width 0.0889)
		(layer "B.Cu")
		(net "PU_CPU0_TXT_AGENT")
	)
	(segment
		(start 354.128832 -228.948488)
		(end 354.122736 -228.944932)
		(width 0.0889)
		(layer "B.Cu")
		(net "PU_CPU0_TXT_AGENT")
	)
	(segment
		(start 351.966784 -226.84105)
		(end 351.966784 -226.831144)
		(width 0.0889)
		(layer "B.Cu")
		(net "PU_CPU0_TXT_AGENT")
	)
	(segment
		(start 352.258122 -227.325682)
		(end 352.249232 -227.320602)
		(width 0.0889)
		(layer "B.Cu")
		(net "PU_CPU0_TXT_AGENT")
	)
	(segment
		(start 325.152258 -217.34907)
		(end 325.152258 -189.450726)
		(width 0.12954)
		(layer "B.Cu")
		(net "PU_CPU0_TXT_AGENT")
	)
	(segment
		(start 346.236036 -224.065084)
		(end 346.227146 -224.070164)
		(width 0.0889)
		(layer "B.Cu")
		(net "PU_CPU0_TXT_AGENT")
	)
	(segment
		(start 343.892378 -224.875344)
		(end 343.886282 -224.8789)
		(width 0.0889)
		(layer "B.Cu")
		(net "PU_CPU0_TXT_AGENT")
	)
	(segment
		(start 340.980522 -224.070164)
		(end 340.971632 -224.065084)
		(width 0.0889)
		(layer "B.Cu")
		(net "PU_CPU0_TXT_AGENT")
	)
	(segment
		(start 342.012778 -224.875344)
		(end 342.006682 -224.8789)
		(width 0.0889)
		(layer "B.Cu")
		(net "PU_CPU0_TXT_AGENT")
	)
	(segment
		(start 343.038684 -224.404936)
		(end 343.038684 -224.389442)
		(width 0.0889)
		(layer "B.Cu")
		(net "PU_CPU0_TXT_AGENT")
	)
	(segment
		(start 348.115636 -224.065084)
		(end 348.106746 -224.070164)
		(width 0.0889)
		(layer "B.Cu")
		(net "PU_CPU0_TXT_AGENT")
	)
	(segment
		(start 346.619322 -224.070164)
		(end 346.610432 -224.065084)
		(width 0.0889)
		(layer "B.Cu")
		(net "PU_CPU0_TXT_AGENT")
	)
	(segment
		(start 336.287364 -224.07372)
		(end 336.272632 -224.065084)
		(width 0.0889)
		(layer "B.Cu")
		(net "PU_CPU0_TXT_AGENT")
	)
	(segment
		(start 353.284282 -228.134672)
		(end 353.26955 -228.143308)
		(width 0.0889)
		(layer "B.Cu")
		(net "PU_CPU0_TXT_AGENT")
	)
	(segment
		(start 342.476836 -224.065084)
		(end 342.467946 -224.070164)
		(width 0.0889)
		(layer "B.Cu")
		(net "PU_CPU0_TXT_AGENT")
	)
	(segment
		(start 332.545436 -224.140776)
		(end 332.012036 -223.607376)
		(width 0.0889)
		(layer "B.Cu")
		(net "PU_CPU0_TXT_AGENT")
	)
	(segment
		(start 358.640634 -234.15625)
		(end 358.48417 -233.885232)
		(width 0.0889)
		(layer "B.Cu")
		(net "PU_CPU0_TXT_AGENT")
	)
	(segment
		(start 346.797884 -224.404936)
		(end 346.797884 -224.389442)
		(width 0.0889)
		(layer "B.Cu")
		(net "PU_CPU0_TXT_AGENT")
	)
	(segment
		(start 357.426768 -233.022902)
		(end 357.417878 -233.017822)
		(width 0.0889)
		(layer "B.Cu")
		(net "PU_CPU0_TXT_AGENT")
	)
	(segment
		(start 325.152258 -189.450726)
		(end 324.423278 -188.721746)
		(width 0.12954)
		(layer "B.Cu")
		(net "PU_CPU0_TXT_AGENT")
	)
	(arc
		(start 349.807784 -224.389442)
		(mid 349.733793 -224.669008)
		(end 349.531178 -224.875344)
		(width 0.0889)
		(layer "B.Cu")
		(net "PU_CPU0_TXT_AGENT")
	)
	(arc
		(start 337.212432 -224.065084)
		(mid 337.025234 -224.014941)
		(end 336.838036 -224.065084)
		(width 0.0889)
		(layer "B.Cu")
		(net "PU_CPU0_TXT_AGENT")
	)
	(arc
		(start 355.25583 -230.891842)
		(mid 355.20356 -230.709477)
		(end 355.068632 -230.57612)
		(width 0.0889)
		(layer "B.Cu")
		(net "PU_CPU0_TXT_AGENT")
	)
	(arc
		(start 342.851232 -224.065084)
		(mid 342.664034 -224.014941)
		(end 342.476836 -224.065084)
		(width 0.0889)
		(layer "B.Cu")
		(net "PU_CPU0_TXT_AGENT")
	)
	(arc
		(start 344.168984 -224.389442)
		(mid 344.094993 -224.669008)
		(end 343.892378 -224.875344)
		(width 0.0889)
		(layer "B.Cu")
		(net "PU_CPU0_TXT_AGENT")
	)
	(arc
		(start 346.610432 -224.065084)
		(mid 346.423234 -224.014941)
		(end 346.236036 -224.065084)
		(width 0.0889)
		(layer "B.Cu")
		(net "PU_CPU0_TXT_AGENT")
	)
	(arc
		(start 350.557084 -224.389442)
		(mid 350.509405 -224.206542)
		(end 350.378522 -224.070164)
		(width 0.0889)
		(layer "B.Cu")
		(net "PU_CPU0_TXT_AGENT")
	)
	(arc
		(start 356.66553 -231.714548)
		(mid 356.478231 -231.390107)
		(end 356.103682 -231.39019)
		(width 0.0889)
		(layer "B.Cu")
		(net "PU_CPU0_TXT_AGENT")
	)
	(arc
		(start 336.838036 -224.065084)
		(mid 336.563837 -224.140919)
		(end 336.287364 -224.07372)
		(width 0.0889)
		(layer "B.Cu")
		(net "PU_CPU0_TXT_AGENT")
	)
	(arc
		(start 333.452978 -224.065084)
		(mid 333.26578 -224.014941)
		(end 333.078582 -224.065084)
		(width 0.0889)
		(layer "B.Cu")
		(net "PU_CPU0_TXT_AGENT")
	)
	(arc
		(start 341.441278 -224.8789)
		(mid 341.238455 -224.678669)
		(end 341.159084 -224.404936)
		(width 0.0889)
		(layer "B.Cu")
		(net "PU_CPU0_TXT_AGENT")
	)
	(arc
		(start 344.347546 -224.070164)
		(mid 344.216632 -224.206524)
		(end 344.168984 -224.389442)
		(width 0.0889)
		(layer "B.Cu")
		(net "PU_CPU0_TXT_AGENT")
	)
	(arc
		(start 348.677484 -224.389442)
		(mid 348.629805 -224.206542)
		(end 348.498922 -224.070164)
		(width 0.0889)
		(layer "B.Cu")
		(net "PU_CPU0_TXT_AGENT")
	)
	(arc
		(start 339.561678 -224.8789)
		(mid 339.358855 -224.678669)
		(end 339.279484 -224.404936)
		(width 0.0889)
		(layer "B.Cu")
		(net "PU_CPU0_TXT_AGENT")
	)
	(arc
		(start 349.986346 -224.070164)
		(mid 349.855432 -224.206524)
		(end 349.807784 -224.389442)
		(width 0.0889)
		(layer "B.Cu")
		(net "PU_CPU0_TXT_AGENT")
	)
	(arc
		(start 354.78593 -230.078026)
		(mid 354.73366 -229.895661)
		(end 354.598732 -229.762304)
		(width 0.0889)
		(layer "B.Cu")
		(net "PU_CPU0_TXT_AGENT")
	)
	(arc
		(start 352.436684 -227.64496)
		(mid 352.389005 -227.46206)
		(end 352.258122 -227.325682)
		(width 0.0889)
		(layer "B.Cu")
		(net "PU_CPU0_TXT_AGENT")
	)
	(arc
		(start 357.135684 -232.528364)
		(mid 357.088005 -232.345464)
		(end 356.957122 -232.209086)
		(width 0.0889)
		(layer "B.Cu")
		(net "PU_CPU0_TXT_AGENT")
	)
	(arc
		(start 351.496884 -226.017328)
		(mid 351.449205 -225.834428)
		(end 351.318322 -225.69805)
		(width 0.0889)
		(layer "B.Cu")
		(net "PU_CPU0_TXT_AGENT")
	)
	(arc
		(start 353.658678 -228.134672)
		(mid 353.47148 -228.084529)
		(end 353.284282 -228.134672)
		(width 0.0889)
		(layer "B.Cu")
		(net "PU_CPU0_TXT_AGENT")
	)
	(arc
		(start 335.898236 -224.065084)
		(mid 335.615534 -224.14086)
		(end 335.332832 -224.065084)
		(width 0.0889)
		(layer "B.Cu")
		(net "PU_CPU0_TXT_AGENT")
	)
	(arc
		(start 340.11235 -224.887536)
		(mid 339.835875 -224.954856)
		(end 339.561678 -224.8789)
		(width 0.0889)
		(layer "B.Cu")
		(net "PU_CPU0_TXT_AGENT")
	)
	(arc
		(start 338.23275 -224.887536)
		(mid 337.956275 -224.954856)
		(end 337.682078 -224.8789)
		(width 0.0889)
		(layer "B.Cu")
		(net "PU_CPU0_TXT_AGENT")
	)
	(arc
		(start 344.918284 -224.389442)
		(mid 344.870605 -224.206542)
		(end 344.739722 -224.070164)
		(width 0.0889)
		(layer "B.Cu")
		(net "PU_CPU0_TXT_AGENT")
	)
	(arc
		(start 334.393032 -224.065084)
		(mid 334.205834 -224.014941)
		(end 334.018636 -224.065084)
		(width 0.0889)
		(layer "B.Cu")
		(net "PU_CPU0_TXT_AGENT")
	)
	(arc
		(start 351.779332 -226.506786)
		(mid 351.574997 -226.304181)
		(end 351.496884 -226.027234)
		(width 0.0889)
		(layer "B.Cu")
		(net "PU_CPU0_TXT_AGENT")
	)
	(arc
		(start 346.048584 -224.389442)
		(mid 345.974593 -224.669008)
		(end 345.771978 -224.875344)
		(width 0.0889)
		(layer "B.Cu")
		(net "PU_CPU0_TXT_AGENT")
	)
	(arc
		(start 340.409784 -224.389442)
		(mid 340.335793 -224.669008)
		(end 340.133178 -224.875344)
		(width 0.0889)
		(layer "B.Cu")
		(net "PU_CPU0_TXT_AGENT")
	)
	(arc
		(start 338.708746 -224.070164)
		(mid 338.577832 -224.206524)
		(end 338.530184 -224.389442)
		(width 0.0889)
		(layer "B.Cu")
		(net "PU_CPU0_TXT_AGENT")
	)
	(arc
		(start 341.159084 -224.389442)
		(mid 341.111405 -224.206542)
		(end 340.980522 -224.070164)
		(width 0.0889)
		(layer "B.Cu")
		(net "PU_CPU0_TXT_AGENT")
	)
	(arc
		(start 356.942136 -232.20045)
		(mid 356.739549 -231.994099)
		(end 356.66553 -231.714548)
		(width 0.0889)
		(layer "B.Cu")
		(net "PU_CPU0_TXT_AGENT")
	)
	(arc
		(start 353.26955 -228.143308)
		(mid 352.993109 -228.210474)
		(end 352.718878 -228.134672)
		(width 0.0889)
		(layer "B.Cu")
		(net "PU_CPU0_TXT_AGENT")
	)
	(arc
		(start 347.928184 -224.389442)
		(mid 347.854193 -224.669008)
		(end 347.651578 -224.875344)
		(width 0.0889)
		(layer "B.Cu")
		(net "PU_CPU0_TXT_AGENT")
	)
	(arc
		(start 335.332832 -224.065084)
		(mid 335.145634 -224.014941)
		(end 334.958436 -224.065084)
		(width 0.0889)
		(layer "B.Cu")
		(net "PU_CPU0_TXT_AGENT")
	)
	(arc
		(start 351.309432 -225.69297)
		(mid 351.105951 -225.492166)
		(end 351.02673 -225.217482)
		(width 0.0889)
		(layer "B.Cu")
		(net "PU_CPU0_TXT_AGENT")
	)
	(arc
		(start 343.87155 -224.887536)
		(mid 343.595075 -224.954856)
		(end 343.320878 -224.8789)
		(width 0.0889)
		(layer "B.Cu")
		(net "PU_CPU0_TXT_AGENT")
	)
	(arc
		(start 351.966784 -226.831144)
		(mid 351.919105 -226.648244)
		(end 351.788222 -226.511866)
		(width 0.0889)
		(layer "B.Cu")
		(net "PU_CPU0_TXT_AGENT")
	)
	(arc
		(start 337.682078 -224.8789)
		(mid 337.479255 -224.678669)
		(end 337.399884 -224.404936)
		(width 0.0889)
		(layer "B.Cu")
		(net "PU_CPU0_TXT_AGENT")
	)
	(arc
		(start 340.588346 -224.070164)
		(mid 340.457432 -224.206524)
		(end 340.409784 -224.389442)
		(width 0.0889)
		(layer "B.Cu")
		(net "PU_CPU0_TXT_AGENT")
	)
	(arc
		(start 338.530184 -224.389442)
		(mid 338.456193 -224.669008)
		(end 338.253578 -224.875344)
		(width 0.0889)
		(layer "B.Cu")
		(net "PU_CPU0_TXT_AGENT")
	)
	(arc
		(start 348.490032 -224.065084)
		(mid 348.302834 -224.014941)
		(end 348.115636 -224.065084)
		(width 0.0889)
		(layer "B.Cu")
		(net "PU_CPU0_TXT_AGENT")
	)
	(arc
		(start 346.797884 -224.389442)
		(mid 346.750205 -224.206542)
		(end 346.619322 -224.070164)
		(width 0.0889)
		(layer "B.Cu")
		(net "PU_CPU0_TXT_AGENT")
	)
	(arc
		(start 337.399884 -224.389442)
		(mid 337.352205 -224.206542)
		(end 337.221322 -224.070164)
		(width 0.0889)
		(layer "B.Cu")
		(net "PU_CPU0_TXT_AGENT")
	)
	(arc
		(start 333.078582 -224.065084)
		(mid 332.959951 -224.116604)
		(end 332.83271 -224.13976)
		(width 0.0889)
		(layer "B.Cu")
		(net "PU_CPU0_TXT_AGENT")
	)
	(arc
		(start 352.718878 -228.134672)
		(mid 352.517596 -227.937185)
		(end 352.436684 -227.667058)
		(width 0.0889)
		(layer "B.Cu")
		(net "PU_CPU0_TXT_AGENT")
	)
	(arc
		(start 341.99195 -224.887536)
		(mid 341.715475 -224.954856)
		(end 341.441278 -224.8789)
		(width 0.0889)
		(layer "B.Cu")
		(net "PU_CPU0_TXT_AGENT")
	)
	(arc
		(start 349.51035 -224.887536)
		(mid 349.233875 -224.954856)
		(end 348.959678 -224.8789)
		(width 0.0889)
		(layer "B.Cu")
		(net "PU_CPU0_TXT_AGENT")
	)
	(arc
		(start 354.598732 -229.762304)
		(mid 354.394397 -229.559699)
		(end 354.316284 -229.282752)
		(width 0.0889)
		(layer "B.Cu")
		(net "PU_CPU0_TXT_AGENT")
	)
	(arc
		(start 342.467946 -224.070164)
		(mid 342.337032 -224.206524)
		(end 342.289384 -224.389442)
		(width 0.0889)
		(layer "B.Cu")
		(net "PU_CPU0_TXT_AGENT")
	)
	(arc
		(start 357.60533 -233.34218)
		(mid 357.557651 -233.15928)
		(end 357.426768 -233.022902)
		(width 0.0889)
		(layer "B.Cu")
		(net "PU_CPU0_TXT_AGENT")
	)
	(arc
		(start 358.395016 -233.861356)
		(mid 357.863278 -233.816856)
		(end 357.60533 -233.3498)
		(width 0.0889)
		(layer "B.Cu")
		(net "PU_CPU0_TXT_AGENT")
	)
	(arc
		(start 353.84613 -228.45903)
		(mid 353.798451 -228.27613)
		(end 353.667568 -228.139752)
		(width 0.0889)
		(layer "B.Cu")
		(net "PU_CPU0_TXT_AGENT")
	)
	(arc
		(start 340.971632 -224.065084)
		(mid 340.784434 -224.014941)
		(end 340.597236 -224.065084)
		(width 0.0889)
		(layer "B.Cu")
		(net "PU_CPU0_TXT_AGENT")
	)
	(arc
		(start 350.369632 -224.065084)
		(mid 350.182434 -224.014941)
		(end 349.995236 -224.065084)
		(width 0.0889)
		(layer "B.Cu")
		(net "PU_CPU0_TXT_AGENT")
	)
	(arc
		(start 339.279484 -224.389442)
		(mid 339.231805 -224.206542)
		(end 339.100922 -224.070164)
		(width 0.0889)
		(layer "B.Cu")
		(net "PU_CPU0_TXT_AGENT")
	)
	(arc
		(start 339.092032 -224.065084)
		(mid 338.904834 -224.014941)
		(end 338.717636 -224.065084)
		(width 0.0889)
		(layer "B.Cu")
		(net "PU_CPU0_TXT_AGENT")
	)
	(arc
		(start 356.103682 -231.39019)
		(mid 355.547699 -231.395797)
		(end 355.25583 -230.922576)
		(width 0.0889)
		(layer "B.Cu")
		(net "PU_CPU0_TXT_AGENT")
	)
	(arc
		(start 345.200478 -224.8789)
		(mid 344.997655 -224.678669)
		(end 344.918284 -224.404936)
		(width 0.0889)
		(layer "B.Cu")
		(net "PU_CPU0_TXT_AGENT")
	)
	(arc
		(start 348.959678 -224.8789)
		(mid 348.756855 -224.678669)
		(end 348.677484 -224.404936)
		(width 0.0889)
		(layer "B.Cu")
		(net "PU_CPU0_TXT_AGENT")
	)
	(arc
		(start 334.958436 -224.065084)
		(mid 334.675734 -224.14086)
		(end 334.393032 -224.065084)
		(width 0.0889)
		(layer "B.Cu")
		(net "PU_CPU0_TXT_AGENT")
	)
	(arc
		(start 348.106746 -224.070164)
		(mid 347.975832 -224.206524)
		(end 347.928184 -224.389442)
		(width 0.0889)
		(layer "B.Cu")
		(net "PU_CPU0_TXT_AGENT")
	)
	(arc
		(start 347.080078 -224.8789)
		(mid 346.877255 -224.678669)
		(end 346.797884 -224.404936)
		(width 0.0889)
		(layer "B.Cu")
		(net "PU_CPU0_TXT_AGENT")
	)
	(arc
		(start 354.316284 -229.272846)
		(mid 354.268605 -229.089946)
		(end 354.137722 -228.953568)
		(width 0.0889)
		(layer "B.Cu")
		(net "PU_CPU0_TXT_AGENT")
	)
	(arc
		(start 343.320878 -224.8789)
		(mid 343.118055 -224.678669)
		(end 343.038684 -224.404936)
		(width 0.0889)
		(layer "B.Cu")
		(net "PU_CPU0_TXT_AGENT")
	)
	(arc
		(start 350.839278 -224.8789)
		(mid 350.636455 -224.678669)
		(end 350.557084 -224.404936)
		(width 0.0889)
		(layer "B.Cu")
		(net "PU_CPU0_TXT_AGENT")
	)
	(arc
		(start 346.227146 -224.070164)
		(mid 346.096232 -224.206524)
		(end 346.048584 -224.389442)
		(width 0.0889)
		(layer "B.Cu")
		(net "PU_CPU0_TXT_AGENT")
	)
	(arc
		(start 334.008222 -224.07118)
		(mid 333.72979 -224.141026)
		(end 333.452978 -224.065084)
		(width 0.0889)
		(layer "B.Cu")
		(net "PU_CPU0_TXT_AGENT")
	)
	(arc
		(start 343.038684 -224.389442)
		(mid 342.991005 -224.206542)
		(end 342.860122 -224.070164)
		(width 0.0889)
		(layer "B.Cu")
		(net "PU_CPU0_TXT_AGENT")
	)
	(arc
		(start 342.289384 -224.389442)
		(mid 342.215393 -224.669008)
		(end 342.012778 -224.875344)
		(width 0.0889)
		(layer "B.Cu")
		(net "PU_CPU0_TXT_AGENT")
	)
	(arc
		(start 344.730832 -224.065084)
		(mid 344.543634 -224.014941)
		(end 344.356436 -224.065084)
		(width 0.0889)
		(layer "B.Cu")
		(net "PU_CPU0_TXT_AGENT")
	)
	(arc
		(start 354.122736 -228.944932)
		(mid 353.920149 -228.738581)
		(end 353.84613 -228.45903)
		(width 0.0889)
		(layer "B.Cu")
		(net "PU_CPU0_TXT_AGENT")
	)
	(arc
		(start 352.249232 -227.320602)
		(mid 352.044897 -227.117997)
		(end 351.966784 -226.84105)
		(width 0.0889)
		(layer "B.Cu")
		(net "PU_CPU0_TXT_AGENT")
	)
	(arc
		(start 351.02673 -225.203258)
		(mid 350.979051 -225.020358)
		(end 350.848168 -224.88398)
		(width 0.0889)
		(layer "B.Cu")
		(net "PU_CPU0_TXT_AGENT")
	)
	(arc
		(start 336.272632 -224.065084)
		(mid 336.085434 -224.014941)
		(end 335.898236 -224.065084)
		(width 0.0889)
		(layer "B.Cu")
		(net "PU_CPU0_TXT_AGENT")
	)
	(arc
		(start 345.75115 -224.887536)
		(mid 345.474675 -224.954856)
		(end 345.200478 -224.8789)
		(width 0.0889)
		(layer "B.Cu")
		(net "PU_CPU0_TXT_AGENT")
	)
	(arc
		(start 357.417878 -233.017822)
		(mid 357.215055 -232.817591)
		(end 357.135684 -232.543858)
		(width 0.0889)
		(layer "B.Cu")
		(net "PU_CPU0_TXT_AGENT")
	)
	(arc
		(start 332.83271 -224.13976)
		(mid 332.814557 -224.140563)
		(end 332.796388 -224.140776)
		(width 0.0889)
		(layer "B.Cu")
		(net "PU_CPU0_TXT_AGENT")
	)
	(arc
		(start 347.63075 -224.887536)
		(mid 347.354275 -224.954856)
		(end 347.080078 -224.8789)
		(width 0.0889)
		(layer "B.Cu")
		(net "PU_CPU0_TXT_AGENT")
	)
	(arc
		(start 355.062536 -230.572564)
		(mid 354.859949 -230.366213)
		(end 354.78593 -230.086662)
		(width 0.0889)
		(layer "B.Cu")
		(net "PU_CPU0_TXT_AGENT")
	)
	(segment
		(start 368.148616 -264.77849)
		(end 368.148616 -265.314176)
		(width 0.12954)
		(layer "F.Cu")
		(net "PU_CPU0_SOCKET_ID2")
	)
	(segment
		(start 368.148362 -264.778236)
		(end 368.148616 -264.77849)
		(width 0.12954)
		(layer "F.Cu")
		(net "PU_CPU0_SOCKET_ID2")
	)
	(via
		(at 390.213342 -265.826494)
		(size 0.6604)
		(drill 0.3302)
		(layers "F.Cu" "B.Cu")
		(net "PU_CPU0_SOCKET_ID2")
	)
	(via
		(at 368.148616 -265.314176)
		(size 0.4572)
		(drill 0.2032)
		(layers "F.Cu" "B.Cu")
		(net "PU_CPU0_SOCKET_ID2")
	)
	(segment
		(start 377.814332 -265.81227)
		(end 377.829064 -265.803634)
		(width 0.0889)
		(layer "B.Cu")
		(net "PU_CPU0_SOCKET_ID2")
	)
	(segment
		(start 370.295932 -265.81227)
		(end 370.310664 -265.803634)
		(width 0.0889)
		(layer "B.Cu")
		(net "PU_CPU0_SOCKET_ID2")
	)
	(segment
		(start 389.838946 -266.20089)
		(end 390.213342 -265.826494)
		(width 0.12954)
		(layer "B.Cu")
		(net "PU_CPU0_SOCKET_ID2")
	)
	(segment
		(start 369.356132 -265.81227)
		(end 369.370864 -265.803634)
		(width 0.0889)
		(layer "B.Cu")
		(net "PU_CPU0_SOCKET_ID2")
	)
	(segment
		(start 385.021836 -266.20089)
		(end 385.598162 -266.20089)
		(width 0.12954)
		(layer "B.Cu")
		(net "PU_CPU0_SOCKET_ID2")
	)
	(segment
		(start 384.405886 -265.753596)
		(end 384.85318 -266.20089)
		(width 0.0889)
		(layer "B.Cu")
		(net "PU_CPU0_SOCKET_ID2")
	)
	(segment
		(start 380.633732 -265.81227)
		(end 380.648464 -265.803634)
		(width 0.0889)
		(layer "B.Cu")
		(net "PU_CPU0_SOCKET_ID2")
	)
	(segment
		(start 374.055132 -265.81227)
		(end 374.069864 -265.803634)
		(width 0.0889)
		(layer "B.Cu")
		(net "PU_CPU0_SOCKET_ID2")
	)
	(segment
		(start 383.453132 -265.81227)
		(end 383.467864 -265.803634)
		(width 0.0889)
		(layer "B.Cu")
		(net "PU_CPU0_SOCKET_ID2")
	)
	(segment
		(start 383.655062 -265.753596)
		(end 384.405886 -265.753596)
		(width 0.0889)
		(layer "B.Cu")
		(net "PU_CPU0_SOCKET_ID2")
	)
	(segment
		(start 379.693932 -265.81227)
		(end 379.708664 -265.803634)
		(width 0.0889)
		(layer "B.Cu")
		(net "PU_CPU0_SOCKET_ID2")
	)
	(segment
		(start 410.656278 -193.989706)
		(end 410.156152 -193.48958)
		(width 0.12954)
		(layer "B.Cu")
		(net "PU_CPU0_SOCKET_ID2")
	)
	(segment
		(start 371.235732 -265.81227)
		(end 371.250464 -265.803634)
		(width 0.0889)
		(layer "B.Cu")
		(net "PU_CPU0_SOCKET_ID2")
	)
	(segment
		(start 375.934732 -265.81227)
		(end 375.949464 -265.803634)
		(width 0.0889)
		(layer "B.Cu")
		(net "PU_CPU0_SOCKET_ID2")
	)
	(segment
		(start 387.973316 -265.634216)
		(end 388.53999 -266.20089)
		(width 0.12954)
		(layer "B.Cu")
		(net "PU_CPU0_SOCKET_ID2")
	)
	(segment
		(start 411.204918 -195.73875)
		(end 410.656278 -195.19011)
		(width 0.12954)
		(layer "B.Cu")
		(net "PU_CPU0_SOCKET_ID2")
	)
	(segment
		(start 373.115332 -265.81227)
		(end 373.130064 -265.803634)
		(width 0.0889)
		(layer "B.Cu")
		(net "PU_CPU0_SOCKET_ID2")
	)
	(segment
		(start 410.432758 -240.63325)
		(end 411.204918 -239.86109)
		(width 0.12954)
		(layer "B.Cu")
		(net "PU_CPU0_SOCKET_ID2")
	)
	(segment
		(start 401.992338 -244.993668)
		(end 405.481536 -241.50447)
		(width 0.12954)
		(layer "B.Cu")
		(net "PU_CPU0_SOCKET_ID2")
	)
	(segment
		(start 405.481536 -241.50447)
		(end 408.388058 -241.50447)
		(width 0.12954)
		(layer "B.Cu")
		(net "PU_CPU0_SOCKET_ID2")
	)
	(segment
		(start 411.204918 -239.86109)
		(end 411.204918 -195.73875)
		(width 0.12954)
		(layer "B.Cu")
		(net "PU_CPU0_SOCKET_ID2")
	)
	(segment
		(start 384.85318 -266.20089)
		(end 385.021836 -266.20089)
		(width 0.0889)
		(layer "B.Cu")
		(net "PU_CPU0_SOCKET_ID2")
	)
	(segment
		(start 382.513332 -265.81227)
		(end 382.528064 -265.803634)
		(width 0.0889)
		(layer "B.Cu")
		(net "PU_CPU0_SOCKET_ID2")
	)
	(segment
		(start 401.992338 -254.047498)
		(end 401.992338 -244.993668)
		(width 0.12954)
		(layer "B.Cu")
		(net "PU_CPU0_SOCKET_ID2")
	)
	(segment
		(start 390.213342 -265.826494)
		(end 401.992338 -254.047498)
		(width 0.12954)
		(layer "B.Cu")
		(net "PU_CPU0_SOCKET_ID2")
	)
	(segment
		(start 409.259278 -240.63325)
		(end 410.432758 -240.63325)
		(width 0.12954)
		(layer "B.Cu")
		(net "PU_CPU0_SOCKET_ID2")
	)
	(segment
		(start 376.874532 -265.81227)
		(end 376.889264 -265.803634)
		(width 0.0889)
		(layer "B.Cu")
		(net "PU_CPU0_SOCKET_ID2")
	)
	(segment
		(start 410.656278 -195.19011)
		(end 410.656278 -193.989706)
		(width 0.12954)
		(layer "B.Cu")
		(net "PU_CPU0_SOCKET_ID2")
	)
	(segment
		(start 408.388058 -241.50447)
		(end 409.259278 -240.63325)
		(width 0.12954)
		(layer "B.Cu")
		(net "PU_CPU0_SOCKET_ID2")
	)
	(segment
		(start 378.754132 -265.81227)
		(end 378.768864 -265.803634)
		(width 0.0889)
		(layer "B.Cu")
		(net "PU_CPU0_SOCKET_ID2")
	)
	(segment
		(start 386.164836 -265.634216)
		(end 387.973316 -265.634216)
		(width 0.12954)
		(layer "B.Cu")
		(net "PU_CPU0_SOCKET_ID2")
	)
	(segment
		(start 388.53999 -266.20089)
		(end 389.838946 -266.20089)
		(width 0.12954)
		(layer "B.Cu")
		(net "PU_CPU0_SOCKET_ID2")
	)
	(segment
		(start 385.598162 -266.20089)
		(end 386.164836 -265.634216)
		(width 0.12954)
		(layer "B.Cu")
		(net "PU_CPU0_SOCKET_ID2")
	)
	(segment
		(start 372.175532 -265.81227)
		(end 372.190264 -265.803634)
		(width 0.0889)
		(layer "B.Cu")
		(net "PU_CPU0_SOCKET_ID2")
	)
	(arc
		(start 369.74526 -265.803634)
		(mid 370.019459 -265.879469)
		(end 370.295932 -265.81227)
		(width 0.0889)
		(layer "B.Cu")
		(net "PU_CPU0_SOCKET_ID2")
	)
	(arc
		(start 378.20346 -265.803634)
		(mid 378.477659 -265.879469)
		(end 378.754132 -265.81227)
		(width 0.0889)
		(layer "B.Cu")
		(net "PU_CPU0_SOCKET_ID2")
	)
	(arc
		(start 381.96266 -265.803634)
		(mid 382.236859 -265.879469)
		(end 382.513332 -265.81227)
		(width 0.0889)
		(layer "B.Cu")
		(net "PU_CPU0_SOCKET_ID2")
	)
	(arc
		(start 373.130064 -265.803634)
		(mid 373.317262 -265.753491)
		(end 373.50446 -265.803634)
		(width 0.0889)
		(layer "B.Cu")
		(net "PU_CPU0_SOCKET_ID2")
	)
	(arc
		(start 372.56466 -265.803634)
		(mid 372.838859 -265.879469)
		(end 373.115332 -265.81227)
		(width 0.0889)
		(layer "B.Cu")
		(net "PU_CPU0_SOCKET_ID2")
	)
	(arc
		(start 369.370864 -265.803634)
		(mid 369.558062 -265.753491)
		(end 369.74526 -265.803634)
		(width 0.0889)
		(layer "B.Cu")
		(net "PU_CPU0_SOCKET_ID2")
	)
	(arc
		(start 376.889264 -265.803634)
		(mid 377.076462 -265.753491)
		(end 377.26366 -265.803634)
		(width 0.0889)
		(layer "B.Cu")
		(net "PU_CPU0_SOCKET_ID2")
	)
	(arc
		(start 381.588264 -265.803634)
		(mid 381.775462 -265.753491)
		(end 381.96266 -265.803634)
		(width 0.0889)
		(layer "B.Cu")
		(net "PU_CPU0_SOCKET_ID2")
	)
	(arc
		(start 373.50446 -265.803634)
		(mid 373.778659 -265.879469)
		(end 374.055132 -265.81227)
		(width 0.0889)
		(layer "B.Cu")
		(net "PU_CPU0_SOCKET_ID2")
	)
	(arc
		(start 375.38406 -265.803634)
		(mid 375.658259 -265.879469)
		(end 375.934732 -265.81227)
		(width 0.0889)
		(layer "B.Cu")
		(net "PU_CPU0_SOCKET_ID2")
	)
	(arc
		(start 374.44426 -265.803634)
		(mid 374.726962 -265.87941)
		(end 375.009664 -265.803634)
		(width 0.0889)
		(layer "B.Cu")
		(net "PU_CPU0_SOCKET_ID2")
	)
	(arc
		(start 374.069864 -265.803634)
		(mid 374.257062 -265.753491)
		(end 374.44426 -265.803634)
		(width 0.0889)
		(layer "B.Cu")
		(net "PU_CPU0_SOCKET_ID2")
	)
	(arc
		(start 382.90246 -265.803634)
		(mid 383.176659 -265.879469)
		(end 383.453132 -265.81227)
		(width 0.0889)
		(layer "B.Cu")
		(net "PU_CPU0_SOCKET_ID2")
	)
	(arc
		(start 375.009664 -265.803634)
		(mid 375.196862 -265.753491)
		(end 375.38406 -265.803634)
		(width 0.0889)
		(layer "B.Cu")
		(net "PU_CPU0_SOCKET_ID2")
	)
	(arc
		(start 379.708664 -265.803634)
		(mid 379.895862 -265.753491)
		(end 380.08306 -265.803634)
		(width 0.0889)
		(layer "B.Cu")
		(net "PU_CPU0_SOCKET_ID2")
	)
	(arc
		(start 382.528064 -265.803634)
		(mid 382.715262 -265.753491)
		(end 382.90246 -265.803634)
		(width 0.0889)
		(layer "B.Cu")
		(net "PU_CPU0_SOCKET_ID2")
	)
	(arc
		(start 371.62486 -265.803634)
		(mid 371.899059 -265.879469)
		(end 372.175532 -265.81227)
		(width 0.0889)
		(layer "B.Cu")
		(net "PU_CPU0_SOCKET_ID2")
	)
	(arc
		(start 380.648464 -265.803634)
		(mid 380.835662 -265.753491)
		(end 381.02286 -265.803634)
		(width 0.0889)
		(layer "B.Cu")
		(net "PU_CPU0_SOCKET_ID2")
	)
	(arc
		(start 378.768864 -265.803634)
		(mid 378.956062 -265.753491)
		(end 379.14326 -265.803634)
		(width 0.0889)
		(layer "B.Cu")
		(net "PU_CPU0_SOCKET_ID2")
	)
	(arc
		(start 380.08306 -265.803634)
		(mid 380.357259 -265.879469)
		(end 380.633732 -265.81227)
		(width 0.0889)
		(layer "B.Cu")
		(net "PU_CPU0_SOCKET_ID2")
	)
	(arc
		(start 368.80546 -265.803634)
		(mid 369.079659 -265.879469)
		(end 369.356132 -265.81227)
		(width 0.0889)
		(layer "B.Cu")
		(net "PU_CPU0_SOCKET_ID2")
	)
	(arc
		(start 375.949464 -265.803634)
		(mid 376.136662 -265.753491)
		(end 376.32386 -265.803634)
		(width 0.0889)
		(layer "B.Cu")
		(net "PU_CPU0_SOCKET_ID2")
	)
	(arc
		(start 372.190264 -265.803634)
		(mid 372.377462 -265.753491)
		(end 372.56466 -265.803634)
		(width 0.0889)
		(layer "B.Cu")
		(net "PU_CPU0_SOCKET_ID2")
	)
	(arc
		(start 377.829064 -265.803634)
		(mid 378.016262 -265.753491)
		(end 378.20346 -265.803634)
		(width 0.0889)
		(layer "B.Cu")
		(net "PU_CPU0_SOCKET_ID2")
	)
	(arc
		(start 377.26366 -265.803634)
		(mid 377.537859 -265.879469)
		(end 377.814332 -265.81227)
		(width 0.0889)
		(layer "B.Cu")
		(net "PU_CPU0_SOCKET_ID2")
	)
	(arc
		(start 383.467864 -265.803634)
		(mid 383.558171 -265.766305)
		(end 383.655062 -265.753596)
		(width 0.0889)
		(layer "B.Cu")
		(net "PU_CPU0_SOCKET_ID2")
	)
	(arc
		(start 371.250464 -265.803634)
		(mid 371.437662 -265.753491)
		(end 371.62486 -265.803634)
		(width 0.0889)
		(layer "B.Cu")
		(net "PU_CPU0_SOCKET_ID2")
	)
	(arc
		(start 370.68506 -265.803634)
		(mid 370.959259 -265.879469)
		(end 371.235732 -265.81227)
		(width 0.0889)
		(layer "B.Cu")
		(net "PU_CPU0_SOCKET_ID2")
	)
	(arc
		(start 368.148616 -265.314176)
		(mid 368.462793 -265.578022)
		(end 368.80546 -265.803634)
		(width 0.0889)
		(layer "B.Cu")
		(net "PU_CPU0_SOCKET_ID2")
	)
	(arc
		(start 379.14326 -265.803634)
		(mid 379.417459 -265.879469)
		(end 379.693932 -265.81227)
		(width 0.0889)
		(layer "B.Cu")
		(net "PU_CPU0_SOCKET_ID2")
	)
	(arc
		(start 370.310664 -265.803634)
		(mid 370.497862 -265.753491)
		(end 370.68506 -265.803634)
		(width 0.0889)
		(layer "B.Cu")
		(net "PU_CPU0_SOCKET_ID2")
	)
	(arc
		(start 381.02286 -265.803634)
		(mid 381.305562 -265.87941)
		(end 381.588264 -265.803634)
		(width 0.0889)
		(layer "B.Cu")
		(net "PU_CPU0_SOCKET_ID2")
	)
	(arc
		(start 376.32386 -265.803634)
		(mid 376.598059 -265.879469)
		(end 376.874532 -265.81227)
		(width 0.0889)
		(layer "B.Cu")
		(net "PU_CPU0_SOCKET_ID2")
	)
	(segment
		(start 370.028216 -264.77849)
		(end 370.028216 -265.314176)
		(width 0.12954)
		(layer "F.Cu")
		(net "PU_CPU0_SOCKET_ID1")
	)
	(segment
		(start 370.027962 -264.778236)
		(end 370.028216 -264.77849)
		(width 0.12954)
		(layer "F.Cu")
		(net "PU_CPU0_SOCKET_ID1")
	)
	(via
		(at 370.028216 -265.314176)
		(size 0.4572)
		(drill 0.2032)
		(layers "F.Cu" "B.Cu")
		(net "PU_CPU0_SOCKET_ID1")
	)
	(via
		(at 388.738618 -265.489436)
		(size 0.6604)
		(drill 0.3302)
		(layers "F.Cu" "B.Cu")
		(net "PU_CPU0_SOCKET_ID1")
	)
	(segment
		(start 379.628146 -265.629898)
		(end 379.613414 -265.638534)
		(width 0.0889)
		(layer "B.Cu")
		(net "PU_CPU0_SOCKET_ID1")
	)
	(segment
		(start 373.049546 -265.629898)
		(end 373.034814 -265.638534)
		(width 0.0889)
		(layer "B.Cu")
		(net "PU_CPU0_SOCKET_ID1")
	)
	(segment
		(start 401.692618 -253.581916)
		(end 389.785098 -265.489436)
		(width 0.12954)
		(layer "B.Cu")
		(net "PU_CPU0_SOCKET_ID1")
	)
	(segment
		(start 373.985028 -265.632438)
		(end 373.974614 -265.638534)
		(width 0.0889)
		(layer "B.Cu")
		(net "PU_CPU0_SOCKET_ID1")
	)
	(segment
		(start 388.738618 -265.489436)
		(end 388.449312 -265.20013)
		(width 0.12954)
		(layer "B.Cu")
		(net "PU_CPU0_SOCKET_ID1")
	)
	(segment
		(start 410.064458 -240.29543)
		(end 408.992578 -240.29543)
		(width 0.12954)
		(layer "B.Cu")
		(net "PU_CPU0_SOCKET_ID1")
	)
	(segment
		(start 384.66014 -265.557254)
		(end 383.676144 -265.557254)
		(width 0.0889)
		(layer "B.Cu")
		(net "PU_CPU0_SOCKET_ID1")
	)
	(segment
		(start 410.874718 -239.48517)
		(end 410.064458 -240.29543)
		(width 0.12954)
		(layer "B.Cu")
		(net "PU_CPU0_SOCKET_ID1")
	)
	(segment
		(start 380.563628 -265.632438)
		(end 380.553214 -265.638534)
		(width 0.0889)
		(layer "B.Cu")
		(net "PU_CPU0_SOCKET_ID1")
	)
	(segment
		(start 374.924574 -265.632438)
		(end 374.91416 -265.638534)
		(width 0.0889)
		(layer "B.Cu")
		(net "PU_CPU0_SOCKET_ID1")
	)
	(segment
		(start 408.992578 -240.29543)
		(end 408.083258 -241.20475)
		(width 0.12954)
		(layer "B.Cu")
		(net "PU_CPU0_SOCKET_ID1")
	)
	(segment
		(start 378.688346 -265.629898)
		(end 378.673614 -265.638534)
		(width 0.0889)
		(layer "B.Cu")
		(net "PU_CPU0_SOCKET_ID1")
	)
	(segment
		(start 401.692618 -244.894608)
		(end 401.692618 -253.581916)
		(width 0.12954)
		(layer "B.Cu")
		(net "PU_CPU0_SOCKET_ID1")
	)
	(segment
		(start 375.868946 -265.629898)
		(end 375.854214 -265.638534)
		(width 0.0889)
		(layer "B.Cu")
		(net "PU_CPU0_SOCKET_ID1")
	)
	(segment
		(start 370.780818 -265.638534)
		(end 370.383816 -265.409426)
		(width 0.0889)
		(layer "B.Cu")
		(net "PU_CPU0_SOCKET_ID1")
	)
	(segment
		(start 408.083258 -241.20475)
		(end 405.382476 -241.20475)
		(width 0.12954)
		(layer "B.Cu")
		(net "PU_CPU0_SOCKET_ID1")
	)
	(segment
		(start 389.785098 -265.489436)
		(end 388.738618 -265.489436)
		(width 0.12954)
		(layer "B.Cu")
		(net "PU_CPU0_SOCKET_ID1")
	)
	(segment
		(start 388.449312 -265.20013)
		(end 385.876038 -265.20013)
		(width 0.12954)
		(layer "B.Cu")
		(net "PU_CPU0_SOCKET_ID1")
	)
	(segment
		(start 385.876038 -265.20013)
		(end 385.267454 -265.808714)
		(width 0.12954)
		(layer "B.Cu")
		(net "PU_CPU0_SOCKET_ID1")
	)
	(segment
		(start 410.262578 -194.612006)
		(end 410.262578 -195.38061)
		(width 0.12954)
		(layer "B.Cu")
		(net "PU_CPU0_SOCKET_ID1")
	)
	(segment
		(start 385.019296 -265.808714)
		(end 384.9116 -265.808714)
		(width 0.0889)
		(layer "B.Cu")
		(net "PU_CPU0_SOCKET_ID1")
	)
	(segment
		(start 381.503174 -265.632438)
		(end 381.49276 -265.638534)
		(width 0.0889)
		(layer "B.Cu")
		(net "PU_CPU0_SOCKET_ID1")
	)
	(segment
		(start 409.140152 -193.48958)
		(end 410.262578 -194.612006)
		(width 0.12954)
		(layer "B.Cu")
		(net "PU_CPU0_SOCKET_ID1")
	)
	(segment
		(start 372.109746 -265.629898)
		(end 372.095014 -265.638534)
		(width 0.0889)
		(layer "B.Cu")
		(net "PU_CPU0_SOCKET_ID1")
	)
	(segment
		(start 371.169946 -265.629898)
		(end 371.155214 -265.638534)
		(width 0.0889)
		(layer "B.Cu")
		(net "PU_CPU0_SOCKET_ID1")
	)
	(segment
		(start 385.267454 -265.808714)
		(end 385.019296 -265.808714)
		(width 0.12954)
		(layer "B.Cu")
		(net "PU_CPU0_SOCKET_ID1")
	)
	(segment
		(start 377.748546 -265.629898)
		(end 377.733814 -265.638534)
		(width 0.0889)
		(layer "B.Cu")
		(net "PU_CPU0_SOCKET_ID1")
	)
	(segment
		(start 410.262578 -195.38061)
		(end 410.874718 -195.99275)
		(width 0.12954)
		(layer "B.Cu")
		(net "PU_CPU0_SOCKET_ID1")
	)
	(segment
		(start 405.382476 -241.20475)
		(end 401.692618 -244.894608)
		(width 0.12954)
		(layer "B.Cu")
		(net "PU_CPU0_SOCKET_ID1")
	)
	(segment
		(start 410.874718 -195.99275)
		(end 410.874718 -239.48517)
		(width 0.12954)
		(layer "B.Cu")
		(net "PU_CPU0_SOCKET_ID1")
	)
	(segment
		(start 384.9116 -265.808714)
		(end 384.66014 -265.557254)
		(width 0.0889)
		(layer "B.Cu")
		(net "PU_CPU0_SOCKET_ID1")
	)
	(segment
		(start 376.808746 -265.629898)
		(end 376.794014 -265.638534)
		(width 0.0889)
		(layer "B.Cu")
		(net "PU_CPU0_SOCKET_ID1")
	)
	(segment
		(start 382.447546 -265.629898)
		(end 382.432814 -265.638534)
		(width 0.0889)
		(layer "B.Cu")
		(net "PU_CPU0_SOCKET_ID1")
	)
	(arc
		(start 371.720618 -265.638534)
		(mid 371.446419 -265.562699)
		(end 371.169946 -265.629898)
		(width 0.0889)
		(layer "B.Cu")
		(net "PU_CPU0_SOCKET_ID1")
	)
	(arc
		(start 380.553214 -265.638534)
		(mid 380.366016 -265.688677)
		(end 380.178818 -265.638534)
		(width 0.0889)
		(layer "B.Cu")
		(net "PU_CPU0_SOCKET_ID1")
	)
	(arc
		(start 370.383816 -265.409426)
		(mid 370.212283 -265.338405)
		(end 370.028216 -265.314176)
		(width 0.0889)
		(layer "B.Cu")
		(net "PU_CPU0_SOCKET_ID1")
	)
	(arc
		(start 378.299218 -265.638534)
		(mid 378.025019 -265.562699)
		(end 377.748546 -265.629898)
		(width 0.0889)
		(layer "B.Cu")
		(net "PU_CPU0_SOCKET_ID1")
	)
	(arc
		(start 373.974614 -265.638534)
		(mid 373.787416 -265.688677)
		(end 373.600218 -265.638534)
		(width 0.0889)
		(layer "B.Cu")
		(net "PU_CPU0_SOCKET_ID1")
	)
	(arc
		(start 378.673614 -265.638534)
		(mid 378.486416 -265.688677)
		(end 378.299218 -265.638534)
		(width 0.0889)
		(layer "B.Cu")
		(net "PU_CPU0_SOCKET_ID1")
	)
	(arc
		(start 373.034814 -265.638534)
		(mid 372.847616 -265.688677)
		(end 372.660418 -265.638534)
		(width 0.0889)
		(layer "B.Cu")
		(net "PU_CPU0_SOCKET_ID1")
	)
	(arc
		(start 380.178818 -265.638534)
		(mid 379.904619 -265.562699)
		(end 379.628146 -265.629898)
		(width 0.0889)
		(layer "B.Cu")
		(net "PU_CPU0_SOCKET_ID1")
	)
	(arc
		(start 382.058418 -265.638534)
		(mid 381.781605 -265.562664)
		(end 381.503174 -265.632438)
		(width 0.0889)
		(layer "B.Cu")
		(net "PU_CPU0_SOCKET_ID1")
	)
	(arc
		(start 372.660418 -265.638534)
		(mid 372.386219 -265.562699)
		(end 372.109746 -265.629898)
		(width 0.0889)
		(layer "B.Cu")
		(net "PU_CPU0_SOCKET_ID1")
	)
	(arc
		(start 381.118364 -265.638534)
		(mid 380.841805 -265.562791)
		(end 380.563628 -265.632438)
		(width 0.0889)
		(layer "B.Cu")
		(net "PU_CPU0_SOCKET_ID1")
	)
	(arc
		(start 379.239018 -265.638534)
		(mid 378.964819 -265.562699)
		(end 378.688346 -265.629898)
		(width 0.0889)
		(layer "B.Cu")
		(net "PU_CPU0_SOCKET_ID1")
	)
	(arc
		(start 374.91416 -265.638534)
		(mid 374.726962 -265.688677)
		(end 374.539764 -265.638534)
		(width 0.0889)
		(layer "B.Cu")
		(net "PU_CPU0_SOCKET_ID1")
	)
	(arc
		(start 383.372614 -265.638534)
		(mid 383.185416 -265.688677)
		(end 382.998218 -265.638534)
		(width 0.0889)
		(layer "B.Cu")
		(net "PU_CPU0_SOCKET_ID1")
	)
	(arc
		(start 376.794014 -265.638534)
		(mid 376.606816 -265.688677)
		(end 376.419618 -265.638534)
		(width 0.0889)
		(layer "B.Cu")
		(net "PU_CPU0_SOCKET_ID1")
	)
	(arc
		(start 371.155214 -265.638534)
		(mid 370.968016 -265.688677)
		(end 370.780818 -265.638534)
		(width 0.0889)
		(layer "B.Cu")
		(net "PU_CPU0_SOCKET_ID1")
	)
	(arc
		(start 377.359418 -265.638534)
		(mid 377.085219 -265.562699)
		(end 376.808746 -265.629898)
		(width 0.0889)
		(layer "B.Cu")
		(net "PU_CPU0_SOCKET_ID1")
	)
	(arc
		(start 377.733814 -265.638534)
		(mid 377.546616 -265.688677)
		(end 377.359418 -265.638534)
		(width 0.0889)
		(layer "B.Cu")
		(net "PU_CPU0_SOCKET_ID1")
	)
	(arc
		(start 379.613414 -265.638534)
		(mid 379.426216 -265.688677)
		(end 379.239018 -265.638534)
		(width 0.0889)
		(layer "B.Cu")
		(net "PU_CPU0_SOCKET_ID1")
	)
	(arc
		(start 375.854214 -265.638534)
		(mid 375.667016 -265.688677)
		(end 375.479818 -265.638534)
		(width 0.0889)
		(layer "B.Cu")
		(net "PU_CPU0_SOCKET_ID1")
	)
	(arc
		(start 383.676144 -265.557254)
		(mid 383.519038 -265.577936)
		(end 383.372614 -265.638534)
		(width 0.0889)
		(layer "B.Cu")
		(net "PU_CPU0_SOCKET_ID1")
	)
	(arc
		(start 373.600218 -265.638534)
		(mid 373.326019 -265.562699)
		(end 373.049546 -265.629898)
		(width 0.0889)
		(layer "B.Cu")
		(net "PU_CPU0_SOCKET_ID1")
	)
	(arc
		(start 372.095014 -265.638534)
		(mid 371.907816 -265.688677)
		(end 371.720618 -265.638534)
		(width 0.0889)
		(layer "B.Cu")
		(net "PU_CPU0_SOCKET_ID1")
	)
	(arc
		(start 382.998218 -265.638534)
		(mid 382.724019 -265.562699)
		(end 382.447546 -265.629898)
		(width 0.0889)
		(layer "B.Cu")
		(net "PU_CPU0_SOCKET_ID1")
	)
	(arc
		(start 375.479818 -265.638534)
		(mid 375.203005 -265.562664)
		(end 374.924574 -265.632438)
		(width 0.0889)
		(layer "B.Cu")
		(net "PU_CPU0_SOCKET_ID1")
	)
	(arc
		(start 381.49276 -265.638534)
		(mid 381.305562 -265.688677)
		(end 381.118364 -265.638534)
		(width 0.0889)
		(layer "B.Cu")
		(net "PU_CPU0_SOCKET_ID1")
	)
	(arc
		(start 374.539764 -265.638534)
		(mid 374.263205 -265.562791)
		(end 373.985028 -265.632438)
		(width 0.0889)
		(layer "B.Cu")
		(net "PU_CPU0_SOCKET_ID1")
	)
	(arc
		(start 376.419618 -265.638534)
		(mid 376.145419 -265.562699)
		(end 375.868946 -265.629898)
		(width 0.0889)
		(layer "B.Cu")
		(net "PU_CPU0_SOCKET_ID1")
	)
	(arc
		(start 382.432814 -265.638534)
		(mid 382.245616 -265.688677)
		(end 382.058418 -265.638534)
		(width 0.0889)
		(layer "B.Cu")
		(net "PU_CPU0_SOCKET_ID1")
	)
	(segment
		(start 369.558062 -263.964674)
		(end 369.558062 -264.50036)
		(width 0.12954)
		(layer "F.Cu")
		(net "PU_CPU0_SOCKET_ID0")
	)
	(segment
		(start 369.558316 -263.96442)
		(end 369.558062 -263.964674)
		(width 0.12954)
		(layer "F.Cu")
		(net "PU_CPU0_SOCKET_ID0")
	)
	(via
		(at 390.092438 -263.62025)
		(size 0.6604)
		(drill 0.3302)
		(layers "F.Cu" "B.Cu")
		(net "PU_CPU0_SOCKET_ID0")
	)
	(via
		(at 369.558062 -264.50036)
		(size 0.4572)
		(drill 0.2032)
		(layers "F.Cu" "B.Cu")
		(net "PU_CPU0_SOCKET_ID0")
	)
	(segment
		(start 374.99925 -264.182098)
		(end 375.009664 -264.176002)
		(width 0.0889)
		(layer "B.Cu")
		(net "PU_CPU0_SOCKET_ID0")
	)
	(segment
		(start 409.207208 -239.34166)
		(end 409.948888 -239.34166)
		(width 0.12954)
		(layer "B.Cu")
		(net "PU_CPU0_SOCKET_ID0")
	)
	(segment
		(start 372.175532 -264.184638)
		(end 372.190264 -264.176002)
		(width 0.0889)
		(layer "B.Cu")
		(net "PU_CPU0_SOCKET_ID0")
	)
	(segment
		(start 380.638304 -264.182098)
		(end 380.648718 -264.176002)
		(width 0.0889)
		(layer "B.Cu")
		(net "PU_CPU0_SOCKET_ID0")
	)
	(segment
		(start 384.268218 -264.251694)
		(end 384.476498 -264.459974)
		(width 0.0889)
		(layer "B.Cu")
		(net "PU_CPU0_SOCKET_ID0")
	)
	(segment
		(start 390.092438 -263.62025)
		(end 391.255504 -263.62025)
		(width 0.12954)
		(layer "B.Cu")
		(net "PU_CPU0_SOCKET_ID0")
	)
	(segment
		(start 401.324318 -253.551436)
		(end 401.324318 -244.360446)
		(width 0.12954)
		(layer "B.Cu")
		(net "PU_CPU0_SOCKET_ID0")
	)
	(segment
		(start 408.349958 -240.19891)
		(end 409.207208 -239.34166)
		(width 0.12954)
		(layer "B.Cu")
		(net "PU_CPU0_SOCKET_ID0")
	)
	(segment
		(start 369.558062 -264.50036)
		(end 370.310664 -264.176002)
		(width 0.0889)
		(layer "B.Cu")
		(net "PU_CPU0_SOCKET_ID0")
	)
	(segment
		(start 391.255504 -263.62025)
		(end 401.324318 -253.551436)
		(width 0.12954)
		(layer "B.Cu")
		(net "PU_CPU0_SOCKET_ID0")
	)
	(segment
		(start 381.57785 -264.182098)
		(end 381.588264 -264.176002)
		(width 0.0889)
		(layer "B.Cu")
		(net "PU_CPU0_SOCKET_ID0")
	)
	(segment
		(start 373.115332 -264.184638)
		(end 373.130064 -264.176002)
		(width 0.0889)
		(layer "B.Cu")
		(net "PU_CPU0_SOCKET_ID0")
	)
	(segment
		(start 410.476192 -196.193918)
		(end 409.223718 -194.941444)
		(width 0.12954)
		(layer "B.Cu")
		(net "PU_CPU0_SOCKET_ID0")
	)
	(segment
		(start 409.223718 -194.589146)
		(end 408.124152 -193.48958)
		(width 0.12954)
		(layer "B.Cu")
		(net "PU_CPU0_SOCKET_ID0")
	)
	(segment
		(start 384.784092 -264.767568)
		(end 388.94512 -264.767568)
		(width 0.12954)
		(layer "B.Cu")
		(net "PU_CPU0_SOCKET_ID0")
	)
	(segment
		(start 410.476192 -238.814356)
		(end 410.476192 -196.193918)
		(width 0.12954)
		(layer "B.Cu")
		(net "PU_CPU0_SOCKET_ID0")
	)
	(segment
		(start 388.94512 -264.767568)
		(end 390.092438 -263.62025)
		(width 0.12954)
		(layer "B.Cu")
		(net "PU_CPU0_SOCKET_ID0")
	)
	(segment
		(start 384.476498 -264.459974)
		(end 384.784092 -264.767568)
		(width 0.12954)
		(layer "B.Cu")
		(net "PU_CPU0_SOCKET_ID0")
	)
	(segment
		(start 384.124962 -264.251694)
		(end 384.268218 -264.251694)
		(width 0.0889)
		(layer "B.Cu")
		(net "PU_CPU0_SOCKET_ID0")
	)
	(segment
		(start 376.874532 -264.184638)
		(end 376.889264 -264.176002)
		(width 0.0889)
		(layer "B.Cu")
		(net "PU_CPU0_SOCKET_ID0")
	)
	(segment
		(start 375.934732 -264.184638)
		(end 375.949464 -264.176002)
		(width 0.0889)
		(layer "B.Cu")
		(net "PU_CPU0_SOCKET_ID0")
	)
	(segment
		(start 374.059704 -264.182098)
		(end 374.070118 -264.176002)
		(width 0.0889)
		(layer "B.Cu")
		(net "PU_CPU0_SOCKET_ID0")
	)
	(segment
		(start 382.513332 -264.184638)
		(end 382.528064 -264.176002)
		(width 0.0889)
		(layer "B.Cu")
		(net "PU_CPU0_SOCKET_ID0")
	)
	(segment
		(start 378.754132 -264.184638)
		(end 378.768864 -264.176002)
		(width 0.0889)
		(layer "B.Cu")
		(net "PU_CPU0_SOCKET_ID0")
	)
	(segment
		(start 379.693932 -264.184638)
		(end 379.708664 -264.176002)
		(width 0.0889)
		(layer "B.Cu")
		(net "PU_CPU0_SOCKET_ID0")
	)
	(segment
		(start 409.948888 -239.34166)
		(end 410.476192 -238.814356)
		(width 0.12954)
		(layer "B.Cu")
		(net "PU_CPU0_SOCKET_ID0")
	)
	(segment
		(start 405.485854 -240.19891)
		(end 408.349958 -240.19891)
		(width 0.12954)
		(layer "B.Cu")
		(net "PU_CPU0_SOCKET_ID0")
	)
	(segment
		(start 401.324318 -244.360446)
		(end 405.485854 -240.19891)
		(width 0.12954)
		(layer "B.Cu")
		(net "PU_CPU0_SOCKET_ID0")
	)
	(segment
		(start 409.223718 -194.941444)
		(end 409.223718 -194.589146)
		(width 0.12954)
		(layer "B.Cu")
		(net "PU_CPU0_SOCKET_ID0")
	)
	(arc
		(start 372.190264 -264.176002)
		(mid 372.377462 -264.125859)
		(end 372.56466 -264.176002)
		(width 0.0889)
		(layer "B.Cu")
		(net "PU_CPU0_SOCKET_ID0")
	)
	(arc
		(start 381.588264 -264.176002)
		(mid 381.775462 -264.125859)
		(end 381.96266 -264.176002)
		(width 0.0889)
		(layer "B.Cu")
		(net "PU_CPU0_SOCKET_ID0")
	)
	(arc
		(start 381.023114 -264.176002)
		(mid 381.299673 -264.251745)
		(end 381.57785 -264.182098)
		(width 0.0889)
		(layer "B.Cu")
		(net "PU_CPU0_SOCKET_ID0")
	)
	(arc
		(start 375.38406 -264.176002)
		(mid 375.658259 -264.251837)
		(end 375.934732 -264.184638)
		(width 0.0889)
		(layer "B.Cu")
		(net "PU_CPU0_SOCKET_ID0")
	)
	(arc
		(start 383.84226 -264.176002)
		(mid 383.978629 -264.232444)
		(end 384.124962 -264.251694)
		(width 0.0889)
		(layer "B.Cu")
		(net "PU_CPU0_SOCKET_ID0")
	)
	(arc
		(start 370.68506 -264.176002)
		(mid 370.967762 -264.251778)
		(end 371.250464 -264.176002)
		(width 0.0889)
		(layer "B.Cu")
		(net "PU_CPU0_SOCKET_ID0")
	)
	(arc
		(start 371.250464 -264.176002)
		(mid 371.437662 -264.125859)
		(end 371.62486 -264.176002)
		(width 0.0889)
		(layer "B.Cu")
		(net "PU_CPU0_SOCKET_ID0")
	)
	(arc
		(start 374.070118 -264.176002)
		(mid 374.257316 -264.125859)
		(end 374.444514 -264.176002)
		(width 0.0889)
		(layer "B.Cu")
		(net "PU_CPU0_SOCKET_ID0")
	)
	(arc
		(start 372.56466 -264.176002)
		(mid 372.838859 -264.251837)
		(end 373.115332 -264.184638)
		(width 0.0889)
		(layer "B.Cu")
		(net "PU_CPU0_SOCKET_ID0")
	)
	(arc
		(start 381.96266 -264.176002)
		(mid 382.236859 -264.251837)
		(end 382.513332 -264.184638)
		(width 0.0889)
		(layer "B.Cu")
		(net "PU_CPU0_SOCKET_ID0")
	)
	(arc
		(start 373.50446 -264.176002)
		(mid 373.781273 -264.251872)
		(end 374.059704 -264.182098)
		(width 0.0889)
		(layer "B.Cu")
		(net "PU_CPU0_SOCKET_ID0")
	)
	(arc
		(start 382.90246 -264.176002)
		(mid 383.185162 -264.251778)
		(end 383.467864 -264.176002)
		(width 0.0889)
		(layer "B.Cu")
		(net "PU_CPU0_SOCKET_ID0")
	)
	(arc
		(start 378.768864 -264.176002)
		(mid 378.956062 -264.125859)
		(end 379.14326 -264.176002)
		(width 0.0889)
		(layer "B.Cu")
		(net "PU_CPU0_SOCKET_ID0")
	)
	(arc
		(start 382.528064 -264.176002)
		(mid 382.715262 -264.125859)
		(end 382.90246 -264.176002)
		(width 0.0889)
		(layer "B.Cu")
		(net "PU_CPU0_SOCKET_ID0")
	)
	(arc
		(start 378.20346 -264.176002)
		(mid 378.477659 -264.251837)
		(end 378.754132 -264.184638)
		(width 0.0889)
		(layer "B.Cu")
		(net "PU_CPU0_SOCKET_ID0")
	)
	(arc
		(start 383.467864 -264.176002)
		(mid 383.655062 -264.125859)
		(end 383.84226 -264.176002)
		(width 0.0889)
		(layer "B.Cu")
		(net "PU_CPU0_SOCKET_ID0")
	)
	(arc
		(start 377.829064 -264.176002)
		(mid 378.016262 -264.125859)
		(end 378.20346 -264.176002)
		(width 0.0889)
		(layer "B.Cu")
		(net "PU_CPU0_SOCKET_ID0")
	)
	(arc
		(start 375.949464 -264.176002)
		(mid 376.136662 -264.125859)
		(end 376.32386 -264.176002)
		(width 0.0889)
		(layer "B.Cu")
		(net "PU_CPU0_SOCKET_ID0")
	)
	(arc
		(start 376.889264 -264.176002)
		(mid 377.076462 -264.125859)
		(end 377.26366 -264.176002)
		(width 0.0889)
		(layer "B.Cu")
		(net "PU_CPU0_SOCKET_ID0")
	)
	(arc
		(start 370.310664 -264.176002)
		(mid 370.497862 -264.125859)
		(end 370.68506 -264.176002)
		(width 0.0889)
		(layer "B.Cu")
		(net "PU_CPU0_SOCKET_ID0")
	)
	(arc
		(start 371.62486 -264.176002)
		(mid 371.899059 -264.251837)
		(end 372.175532 -264.184638)
		(width 0.0889)
		(layer "B.Cu")
		(net "PU_CPU0_SOCKET_ID0")
	)
	(arc
		(start 375.009664 -264.176002)
		(mid 375.196862 -264.125859)
		(end 375.38406 -264.176002)
		(width 0.0889)
		(layer "B.Cu")
		(net "PU_CPU0_SOCKET_ID0")
	)
	(arc
		(start 377.26366 -264.176002)
		(mid 377.546362 -264.251778)
		(end 377.829064 -264.176002)
		(width 0.0889)
		(layer "B.Cu")
		(net "PU_CPU0_SOCKET_ID0")
	)
	(arc
		(start 376.32386 -264.176002)
		(mid 376.598059 -264.251837)
		(end 376.874532 -264.184638)
		(width 0.0889)
		(layer "B.Cu")
		(net "PU_CPU0_SOCKET_ID0")
	)
	(arc
		(start 373.130064 -264.176002)
		(mid 373.317262 -264.125859)
		(end 373.50446 -264.176002)
		(width 0.0889)
		(layer "B.Cu")
		(net "PU_CPU0_SOCKET_ID0")
	)
	(arc
		(start 380.648718 -264.176002)
		(mid 380.835916 -264.125859)
		(end 381.023114 -264.176002)
		(width 0.0889)
		(layer "B.Cu")
		(net "PU_CPU0_SOCKET_ID0")
	)
	(arc
		(start 379.708664 -264.176002)
		(mid 379.895862 -264.125859)
		(end 380.08306 -264.176002)
		(width 0.0889)
		(layer "B.Cu")
		(net "PU_CPU0_SOCKET_ID0")
	)
	(arc
		(start 380.08306 -264.176002)
		(mid 380.359873 -264.251872)
		(end 380.638304 -264.182098)
		(width 0.0889)
		(layer "B.Cu")
		(net "PU_CPU0_SOCKET_ID0")
	)
	(arc
		(start 374.444514 -264.176002)
		(mid 374.721073 -264.251745)
		(end 374.99925 -264.182098)
		(width 0.0889)
		(layer "B.Cu")
		(net "PU_CPU0_SOCKET_ID0")
	)
	(arc
		(start 379.14326 -264.176002)
		(mid 379.417459 -264.251837)
		(end 379.693932 -264.184638)
		(width 0.0889)
		(layer "B.Cu")
		(net "PU_CPU0_SOCKET_ID0")
	)
	(segment
		(start 349.712534 -232.250488)
		(end 349.71228 -232.250234)
		(width 0.12954)
		(layer "F.Cu")
		(net "PU_CPU0_SAFE_MODE_BOOT")
	)
	(segment
		(start 349.71228 -232.250234)
		(end 349.71228 -231.714548)
		(width 0.12954)
		(layer "F.Cu")
		(net "PU_CPU0_SAFE_MODE_BOOT")
	)
	(via
		(at 321.931538 -231.71531)
		(size 0.6604)
		(drill 0.3302)
		(layers "F.Cu" "B.Cu")
		(net "PU_CPU0_SAFE_MODE_BOOT")
	)
	(via
		(at 349.71228 -231.714548)
		(size 0.4572)
		(drill 0.2032)
		(layers "F.Cu" "B.Cu")
		(net "PU_CPU0_SAFE_MODE_BOOT")
	)
	(segment
		(start 333.658718 -231.892856)
		(end 323.092064 -231.892856)
		(width 0.12954)
		(layer "B.Cu")
		(net "PU_CPU0_SAFE_MODE_BOOT")
	)
	(segment
		(start 348.585536 -232.038906)
		(end 348.575122 -232.03281)
		(width 0.0889)
		(layer "B.Cu")
		(net "PU_CPU0_SAFE_MODE_BOOT")
	)
	(segment
		(start 349.71228 -231.714548)
		(end 348.959932 -232.038906)
		(width 0.0889)
		(layer "B.Cu")
		(net "PU_CPU0_SAFE_MODE_BOOT")
	)
	(segment
		(start 334.410812 -231.97947)
		(end 334.324198 -231.892856)
		(width 0.0889)
		(layer "B.Cu")
		(net "PU_CPU0_SAFE_MODE_BOOT")
	)
	(segment
		(start 312.414158 -196.01307)
		(end 312.480198 -195.94703)
		(width 0.12954)
		(layer "B.Cu")
		(net "PU_CPU0_SAFE_MODE_BOOT")
	)
	(segment
		(start 341.066882 -232.038906)
		(end 341.05215 -232.03027)
		(width 0.0889)
		(layer "B.Cu")
		(net "PU_CPU0_SAFE_MODE_BOOT")
	)
	(segment
		(start 339.187282 -232.038906)
		(end 339.17255 -232.03027)
		(width 0.0889)
		(layer "B.Cu")
		(net "PU_CPU0_SAFE_MODE_BOOT")
	)
	(segment
		(start 344.826082 -232.038906)
		(end 344.81135 -232.03027)
		(width 0.0889)
		(layer "B.Cu")
		(net "PU_CPU0_SAFE_MODE_BOOT")
	)
	(segment
		(start 343.886282 -232.038906)
		(end 343.87155 -232.03027)
		(width 0.0889)
		(layer "B.Cu")
		(net "PU_CPU0_SAFE_MODE_BOOT")
	)
	(segment
		(start 337.307682 -232.038906)
		(end 337.29295 -232.03027)
		(width 0.0889)
		(layer "B.Cu")
		(net "PU_CPU0_SAFE_MODE_BOOT")
	)
	(segment
		(start 347.645482 -232.038906)
		(end 347.63075 -232.03027)
		(width 0.0889)
		(layer "B.Cu")
		(net "PU_CPU0_SAFE_MODE_BOOT")
	)
	(segment
		(start 322.914518 -231.71531)
		(end 321.931538 -231.71531)
		(width 0.12954)
		(layer "B.Cu")
		(net "PU_CPU0_SAFE_MODE_BOOT")
	)
	(segment
		(start 312.414158 -230.24973)
		(end 312.414158 -196.01307)
		(width 0.12954)
		(layer "B.Cu")
		(net "PU_CPU0_SAFE_MODE_BOOT")
	)
	(segment
		(start 342.006936 -232.038906)
		(end 341.996522 -232.03281)
		(width 0.0889)
		(layer "B.Cu")
		(net "PU_CPU0_SAFE_MODE_BOOT")
	)
	(segment
		(start 336.367882 -232.038906)
		(end 336.357468 -232.03281)
		(width 0.0889)
		(layer "B.Cu")
		(net "PU_CPU0_SAFE_MODE_BOOT")
	)
	(segment
		(start 312.480198 -195.94703)
		(end 312.480198 -194.492118)
		(width 0.12954)
		(layer "B.Cu")
		(net "PU_CPU0_SAFE_MODE_BOOT")
	)
	(segment
		(start 334.324198 -231.892856)
		(end 333.658718 -231.892856)
		(width 0.0889)
		(layer "B.Cu")
		(net "PU_CPU0_SAFE_MODE_BOOT")
	)
	(segment
		(start 312.480198 -194.492118)
		(end 312.13044 -194.14236)
		(width 0.12954)
		(layer "B.Cu")
		(net "PU_CPU0_SAFE_MODE_BOOT")
	)
	(segment
		(start 345.765882 -232.038906)
		(end 345.75115 -232.03027)
		(width 0.0889)
		(layer "B.Cu")
		(net "PU_CPU0_SAFE_MODE_BOOT")
	)
	(segment
		(start 321.931538 -231.71531)
		(end 313.879738 -231.71531)
		(width 0.12954)
		(layer "B.Cu")
		(net "PU_CPU0_SAFE_MODE_BOOT")
	)
	(segment
		(start 313.879738 -231.71531)
		(end 312.414158 -230.24973)
		(width 0.12954)
		(layer "B.Cu")
		(net "PU_CPU0_SAFE_MODE_BOOT")
	)
	(segment
		(start 338.247482 -232.038906)
		(end 338.23275 -232.03027)
		(width 0.0889)
		(layer "B.Cu")
		(net "PU_CPU0_SAFE_MODE_BOOT")
	)
	(segment
		(start 323.092064 -231.892856)
		(end 322.914518 -231.71531)
		(width 0.12954)
		(layer "B.Cu")
		(net "PU_CPU0_SAFE_MODE_BOOT")
	)
	(segment
		(start 342.946482 -232.038906)
		(end 342.936068 -232.03281)
		(width 0.0889)
		(layer "B.Cu")
		(net "PU_CPU0_SAFE_MODE_BOOT")
	)
	(arc
		(start 342.936068 -232.03281)
		(mid 342.65789 -231.963087)
		(end 342.381332 -232.038906)
		(width 0.0889)
		(layer "B.Cu")
		(net "PU_CPU0_SAFE_MODE_BOOT")
	)
	(arc
		(start 338.23275 -232.03027)
		(mid 337.956275 -231.96295)
		(end 337.682078 -232.038906)
		(width 0.0889)
		(layer "B.Cu")
		(net "PU_CPU0_SAFE_MODE_BOOT")
	)
	(arc
		(start 338.621878 -232.038906)
		(mid 338.43468 -232.089049)
		(end 338.247482 -232.038906)
		(width 0.0889)
		(layer "B.Cu")
		(net "PU_CPU0_SAFE_MODE_BOOT")
	)
	(arc
		(start 336.742278 -232.038906)
		(mid 336.55508 -232.089049)
		(end 336.367882 -232.038906)
		(width 0.0889)
		(layer "B.Cu")
		(net "PU_CPU0_SAFE_MODE_BOOT")
	)
	(arc
		(start 337.682078 -232.038906)
		(mid 337.49488 -232.089049)
		(end 337.307682 -232.038906)
		(width 0.0889)
		(layer "B.Cu")
		(net "PU_CPU0_SAFE_MODE_BOOT")
	)
	(arc
		(start 343.87155 -232.03027)
		(mid 343.595075 -231.96295)
		(end 343.320878 -232.038906)
		(width 0.0889)
		(layer "B.Cu")
		(net "PU_CPU0_SAFE_MODE_BOOT")
	)
	(arc
		(start 340.127082 -232.038906)
		(mid 339.84438 -231.96313)
		(end 339.561678 -232.038906)
		(width 0.0889)
		(layer "B.Cu")
		(net "PU_CPU0_SAFE_MODE_BOOT")
	)
	(arc
		(start 334.862932 -232.038906)
		(mid 334.675734 -232.089049)
		(end 334.488536 -232.038906)
		(width 0.0889)
		(layer "B.Cu")
		(net "PU_CPU0_SAFE_MODE_BOOT")
	)
	(arc
		(start 341.05215 -232.03027)
		(mid 340.775675 -231.96295)
		(end 340.501478 -232.038906)
		(width 0.0889)
		(layer "B.Cu")
		(net "PU_CPU0_SAFE_MODE_BOOT")
	)
	(arc
		(start 334.488536 -232.038906)
		(mid 334.447727 -232.011734)
		(end 334.410812 -231.97947)
		(width 0.0889)
		(layer "B.Cu")
		(net "PU_CPU0_SAFE_MODE_BOOT")
	)
	(arc
		(start 345.200478 -232.038906)
		(mid 345.01328 -232.089049)
		(end 344.826082 -232.038906)
		(width 0.0889)
		(layer "B.Cu")
		(net "PU_CPU0_SAFE_MODE_BOOT")
	)
	(arc
		(start 341.996522 -232.03281)
		(mid 341.71809 -231.962964)
		(end 341.441278 -232.038906)
		(width 0.0889)
		(layer "B.Cu")
		(net "PU_CPU0_SAFE_MODE_BOOT")
	)
	(arc
		(start 346.140278 -232.038906)
		(mid 345.95308 -232.089049)
		(end 345.765882 -232.038906)
		(width 0.0889)
		(layer "B.Cu")
		(net "PU_CPU0_SAFE_MODE_BOOT")
	)
	(arc
		(start 345.75115 -232.03027)
		(mid 345.474675 -231.96295)
		(end 345.200478 -232.038906)
		(width 0.0889)
		(layer "B.Cu")
		(net "PU_CPU0_SAFE_MODE_BOOT")
	)
	(arc
		(start 347.63075 -232.03027)
		(mid 347.354275 -231.96295)
		(end 347.080078 -232.038906)
		(width 0.0889)
		(layer "B.Cu")
		(net "PU_CPU0_SAFE_MODE_BOOT")
	)
	(arc
		(start 348.959932 -232.038906)
		(mid 348.772734 -232.089049)
		(end 348.585536 -232.038906)
		(width 0.0889)
		(layer "B.Cu")
		(net "PU_CPU0_SAFE_MODE_BOOT")
	)
	(arc
		(start 343.320878 -232.038906)
		(mid 343.13368 -232.089049)
		(end 342.946482 -232.038906)
		(width 0.0889)
		(layer "B.Cu")
		(net "PU_CPU0_SAFE_MODE_BOOT")
	)
	(arc
		(start 335.802732 -232.038906)
		(mid 335.615534 -232.089049)
		(end 335.428336 -232.038906)
		(width 0.0889)
		(layer "B.Cu")
		(net "PU_CPU0_SAFE_MODE_BOOT")
	)
	(arc
		(start 335.428336 -232.038906)
		(mid 335.145634 -231.96313)
		(end 334.862932 -232.038906)
		(width 0.0889)
		(layer "B.Cu")
		(net "PU_CPU0_SAFE_MODE_BOOT")
	)
	(arc
		(start 342.381332 -232.038906)
		(mid 342.194134 -232.089049)
		(end 342.006936 -232.038906)
		(width 0.0889)
		(layer "B.Cu")
		(net "PU_CPU0_SAFE_MODE_BOOT")
	)
	(arc
		(start 344.81135 -232.03027)
		(mid 344.534875 -231.96295)
		(end 344.260678 -232.038906)
		(width 0.0889)
		(layer "B.Cu")
		(net "PU_CPU0_SAFE_MODE_BOOT")
	)
	(arc
		(start 344.260678 -232.038906)
		(mid 344.07348 -232.089049)
		(end 343.886282 -232.038906)
		(width 0.0889)
		(layer "B.Cu")
		(net "PU_CPU0_SAFE_MODE_BOOT")
	)
	(arc
		(start 340.501478 -232.038906)
		(mid 340.31428 -232.089049)
		(end 340.127082 -232.038906)
		(width 0.0889)
		(layer "B.Cu")
		(net "PU_CPU0_SAFE_MODE_BOOT")
	)
	(arc
		(start 336.357468 -232.03281)
		(mid 336.07929 -231.963087)
		(end 335.802732 -232.038906)
		(width 0.0889)
		(layer "B.Cu")
		(net "PU_CPU0_SAFE_MODE_BOOT")
	)
	(arc
		(start 339.17255 -232.03027)
		(mid 338.896075 -231.96295)
		(end 338.621878 -232.038906)
		(width 0.0889)
		(layer "B.Cu")
		(net "PU_CPU0_SAFE_MODE_BOOT")
	)
	(arc
		(start 348.019878 -232.038906)
		(mid 347.83268 -232.089049)
		(end 347.645482 -232.038906)
		(width 0.0889)
		(layer "B.Cu")
		(net "PU_CPU0_SAFE_MODE_BOOT")
	)
	(arc
		(start 339.561678 -232.038906)
		(mid 339.37448 -232.089049)
		(end 339.187282 -232.038906)
		(width 0.0889)
		(layer "B.Cu")
		(net "PU_CPU0_SAFE_MODE_BOOT")
	)
	(arc
		(start 347.080078 -232.038906)
		(mid 346.89288 -232.089049)
		(end 346.705682 -232.038906)
		(width 0.0889)
		(layer "B.Cu")
		(net "PU_CPU0_SAFE_MODE_BOOT")
	)
	(arc
		(start 348.575122 -232.03281)
		(mid 348.29669 -231.962964)
		(end 348.019878 -232.038906)
		(width 0.0889)
		(layer "B.Cu")
		(net "PU_CPU0_SAFE_MODE_BOOT")
	)
	(arc
		(start 337.29295 -232.03027)
		(mid 337.016475 -231.96295)
		(end 336.742278 -232.038906)
		(width 0.0889)
		(layer "B.Cu")
		(net "PU_CPU0_SAFE_MODE_BOOT")
	)
	(arc
		(start 341.441278 -232.038906)
		(mid 341.25408 -232.089049)
		(end 341.066882 -232.038906)
		(width 0.0889)
		(layer "B.Cu")
		(net "PU_CPU0_SAFE_MODE_BOOT")
	)
	(arc
		(start 346.705682 -232.038906)
		(mid 346.42298 -231.96313)
		(end 346.140278 -232.038906)
		(width 0.0889)
		(layer "B.Cu")
		(net "PU_CPU0_SAFE_MODE_BOOT")
	)
	(segment
		(start 370.027962 -263.150604)
		(end 370.027962 -263.68629)
		(width 0.12954)
		(layer "F.Cu")
		(net "PU_CPU0_LEGACY_SKT")
	)
	(segment
		(start 370.027962 -263.68629)
		(end 370.028216 -263.686544)
		(width 0.12954)
		(layer "F.Cu")
		(net "PU_CPU0_LEGACY_SKT")
	)
	(via
		(at 370.028216 -263.686544)
		(size 0.4572)
		(drill 0.2032)
		(layers "F.Cu" "B.Cu")
		(net "PU_CPU0_LEGACY_SKT")
	)
	(via
		(at 392.441938 -261.67715)
		(size 0.6604)
		(drill 0.3302)
		(layers "F.Cu" "B.Cu")
		(net "PU_CPU0_LEGACY_SKT")
	)
	(segment
		(start 379.613414 -264.010902)
		(end 379.628146 -264.002266)
		(width 0.0889)
		(layer "B.Cu")
		(net "PU_CPU0_LEGACY_SKT")
	)
	(segment
		(start 384.915918 -264.183876)
		(end 388.440676 -264.183876)
		(width 0.12954)
		(layer "B.Cu")
		(net "PU_CPU0_LEGACY_SKT")
	)
	(segment
		(start 376.794014 -264.010902)
		(end 376.804428 -264.004806)
		(width 0.0889)
		(layer "B.Cu")
		(net "PU_CPU0_LEGACY_SKT")
	)
	(segment
		(start 409.155138 -195.336922)
		(end 407.938986 -194.12077)
		(width 0.12954)
		(layer "B.Cu")
		(net "PU_CPU0_LEGACY_SKT")
	)
	(segment
		(start 372.095014 -264.010902)
		(end 372.109746 -264.002266)
		(width 0.0889)
		(layer "B.Cu")
		(net "PU_CPU0_LEGACY_SKT")
	)
	(segment
		(start 374.914414 -264.010902)
		(end 374.929146 -264.002266)
		(width 0.0889)
		(layer "B.Cu")
		(net "PU_CPU0_LEGACY_SKT")
	)
	(segment
		(start 392.441938 -261.67715)
		(end 392.799824 -261.67715)
		(width 0.12954)
		(layer "B.Cu")
		(net "PU_CPU0_LEGACY_SKT")
	)
	(segment
		(start 384.36931 -264.061448)
		(end 384.491738 -264.183876)
		(width 0.0889)
		(layer "B.Cu")
		(net "PU_CPU0_LEGACY_SKT")
	)
	(segment
		(start 373.034814 -264.010902)
		(end 373.049546 -264.002266)
		(width 0.0889)
		(layer "B.Cu")
		(net "PU_CPU0_LEGACY_SKT")
	)
	(segment
		(start 371.15496 -264.010902)
		(end 371.165374 -264.004806)
		(width 0.0889)
		(layer "B.Cu")
		(net "PU_CPU0_LEGACY_SKT")
	)
	(segment
		(start 410.194252 -238.661956)
		(end 410.194252 -197.707504)
		(width 0.12954)
		(layer "B.Cu")
		(net "PU_CPU0_LEGACY_SKT")
	)
	(segment
		(start 407.739342 -194.12077)
		(end 407.108152 -193.48958)
		(width 0.12954)
		(layer "B.Cu")
		(net "PU_CPU0_LEGACY_SKT")
	)
	(segment
		(start 410.194252 -197.707504)
		(end 409.155138 -196.66839)
		(width 0.12954)
		(layer "B.Cu")
		(net "PU_CPU0_LEGACY_SKT")
	)
	(segment
		(start 384.491738 -264.183876)
		(end 384.915918 -264.183876)
		(width 0.0889)
		(layer "B.Cu")
		(net "PU_CPU0_LEGACY_SKT")
	)
	(segment
		(start 388.440676 -264.183876)
		(end 389.705342 -262.91921)
		(width 0.12954)
		(layer "B.Cu")
		(net "PU_CPU0_LEGACY_SKT")
	)
	(segment
		(start 381.493014 -264.010902)
		(end 381.507746 -264.002266)
		(width 0.0889)
		(layer "B.Cu")
		(net "PU_CPU0_LEGACY_SKT")
	)
	(segment
		(start 370.028216 -263.686544)
		(end 370.634768 -263.951974)
		(width 0.0889)
		(layer "B.Cu")
		(net "PU_CPU0_LEGACY_SKT")
	)
	(segment
		(start 408.207718 -239.90681)
		(end 409.155138 -238.95939)
		(width 0.12954)
		(layer "B.Cu")
		(net "PU_CPU0_LEGACY_SKT")
	)
	(segment
		(start 405.347678 -239.90681)
		(end 408.207718 -239.90681)
		(width 0.12954)
		(layer "B.Cu")
		(net "PU_CPU0_LEGACY_SKT")
	)
	(segment
		(start 375.854214 -264.010902)
		(end 375.868946 -264.002266)
		(width 0.0889)
		(layer "B.Cu")
		(net "PU_CPU0_LEGACY_SKT")
	)
	(segment
		(start 392.799824 -261.67715)
		(end 400.79168 -253.685294)
		(width 0.12954)
		(layer "B.Cu")
		(net "PU_CPU0_LEGACY_SKT")
	)
	(segment
		(start 382.432814 -264.010902)
		(end 382.443228 -264.004806)
		(width 0.0889)
		(layer "B.Cu")
		(net "PU_CPU0_LEGACY_SKT")
	)
	(segment
		(start 409.896818 -238.95939)
		(end 410.194252 -238.661956)
		(width 0.12954)
		(layer "B.Cu")
		(net "PU_CPU0_LEGACY_SKT")
	)
	(segment
		(start 409.155138 -196.66839)
		(end 409.155138 -195.336922)
		(width 0.12954)
		(layer "B.Cu")
		(net "PU_CPU0_LEGACY_SKT")
	)
	(segment
		(start 391.199878 -262.91921)
		(end 392.441938 -261.67715)
		(width 0.12954)
		(layer "B.Cu")
		(net "PU_CPU0_LEGACY_SKT")
	)
	(segment
		(start 400.79168 -253.685294)
		(end 400.79168 -244.462808)
		(width 0.12954)
		(layer "B.Cu")
		(net "PU_CPU0_LEGACY_SKT")
	)
	(segment
		(start 377.73356 -264.010902)
		(end 377.743974 -264.004806)
		(width 0.0889)
		(layer "B.Cu")
		(net "PU_CPU0_LEGACY_SKT")
	)
	(segment
		(start 384.124962 -264.061448)
		(end 384.36931 -264.061448)
		(width 0.0889)
		(layer "B.Cu")
		(net "PU_CPU0_LEGACY_SKT")
	)
	(segment
		(start 407.938986 -194.12077)
		(end 407.739342 -194.12077)
		(width 0.12954)
		(layer "B.Cu")
		(net "PU_CPU0_LEGACY_SKT")
	)
	(segment
		(start 378.673614 -264.010902)
		(end 378.688346 -264.002266)
		(width 0.0889)
		(layer "B.Cu")
		(net "PU_CPU0_LEGACY_SKT")
	)
	(segment
		(start 409.155138 -238.95939)
		(end 409.896818 -238.95939)
		(width 0.12954)
		(layer "B.Cu")
		(net "PU_CPU0_LEGACY_SKT")
	)
	(segment
		(start 400.79168 -244.462808)
		(end 405.347678 -239.90681)
		(width 0.12954)
		(layer "B.Cu")
		(net "PU_CPU0_LEGACY_SKT")
	)
	(segment
		(start 389.705342 -262.91921)
		(end 391.199878 -262.91921)
		(width 0.12954)
		(layer "B.Cu")
		(net "PU_CPU0_LEGACY_SKT")
	)
	(arc
		(start 383.37236 -264.010902)
		(mid 383.655062 -263.935126)
		(end 383.937764 -264.010902)
		(width 0.0889)
		(layer "B.Cu")
		(net "PU_CPU0_LEGACY_SKT")
	)
	(arc
		(start 381.118618 -264.010902)
		(mid 381.305816 -264.061045)
		(end 381.493014 -264.010902)
		(width 0.0889)
		(layer "B.Cu")
		(net "PU_CPU0_LEGACY_SKT")
	)
	(arc
		(start 378.688346 -264.002266)
		(mid 378.964821 -263.934946)
		(end 379.239018 -264.010902)
		(width 0.0889)
		(layer "B.Cu")
		(net "PU_CPU0_LEGACY_SKT")
	)
	(arc
		(start 371.720618 -264.010902)
		(mid 371.907816 -264.061045)
		(end 372.095014 -264.010902)
		(width 0.0889)
		(layer "B.Cu")
		(net "PU_CPU0_LEGACY_SKT")
	)
	(arc
		(start 377.743974 -264.004806)
		(mid 378.022406 -263.93496)
		(end 378.299218 -264.010902)
		(width 0.0889)
		(layer "B.Cu")
		(net "PU_CPU0_LEGACY_SKT")
	)
	(arc
		(start 374.929146 -264.002266)
		(mid 375.205621 -263.934946)
		(end 375.479818 -264.010902)
		(width 0.0889)
		(layer "B.Cu")
		(net "PU_CPU0_LEGACY_SKT")
	)
	(arc
		(start 380.178818 -264.010902)
		(mid 380.366016 -264.061045)
		(end 380.553214 -264.010902)
		(width 0.0889)
		(layer "B.Cu")
		(net "PU_CPU0_LEGACY_SKT")
	)
	(arc
		(start 382.058418 -264.010902)
		(mid 382.245616 -264.061045)
		(end 382.432814 -264.010902)
		(width 0.0889)
		(layer "B.Cu")
		(net "PU_CPU0_LEGACY_SKT")
	)
	(arc
		(start 373.600218 -264.010902)
		(mid 373.787416 -264.061045)
		(end 373.974614 -264.010902)
		(width 0.0889)
		(layer "B.Cu")
		(net "PU_CPU0_LEGACY_SKT")
	)
	(arc
		(start 381.507746 -264.002266)
		(mid 381.784221 -263.934946)
		(end 382.058418 -264.010902)
		(width 0.0889)
		(layer "B.Cu")
		(net "PU_CPU0_LEGACY_SKT")
	)
	(arc
		(start 376.804428 -264.004806)
		(mid 377.082606 -263.935083)
		(end 377.359164 -264.010902)
		(width 0.0889)
		(layer "B.Cu")
		(net "PU_CPU0_LEGACY_SKT")
	)
	(arc
		(start 374.540018 -264.010902)
		(mid 374.727216 -264.061045)
		(end 374.914414 -264.010902)
		(width 0.0889)
		(layer "B.Cu")
		(net "PU_CPU0_LEGACY_SKT")
	)
	(arc
		(start 373.049546 -264.002266)
		(mid 373.326021 -263.934946)
		(end 373.600218 -264.010902)
		(width 0.0889)
		(layer "B.Cu")
		(net "PU_CPU0_LEGACY_SKT")
	)
	(arc
		(start 377.359164 -264.010902)
		(mid 377.546362 -264.061045)
		(end 377.73356 -264.010902)
		(width 0.0889)
		(layer "B.Cu")
		(net "PU_CPU0_LEGACY_SKT")
	)
	(arc
		(start 372.109746 -264.002266)
		(mid 372.386221 -263.934946)
		(end 372.660418 -264.010902)
		(width 0.0889)
		(layer "B.Cu")
		(net "PU_CPU0_LEGACY_SKT")
	)
	(arc
		(start 376.419618 -264.010902)
		(mid 376.606816 -264.061045)
		(end 376.794014 -264.010902)
		(width 0.0889)
		(layer "B.Cu")
		(net "PU_CPU0_LEGACY_SKT")
	)
	(arc
		(start 383.937764 -264.010902)
		(mid 384.028036 -264.048501)
		(end 384.124962 -264.061448)
		(width 0.0889)
		(layer "B.Cu")
		(net "PU_CPU0_LEGACY_SKT")
	)
	(arc
		(start 382.997964 -264.010902)
		(mid 383.185162 -264.061045)
		(end 383.37236 -264.010902)
		(width 0.0889)
		(layer "B.Cu")
		(net "PU_CPU0_LEGACY_SKT")
	)
	(arc
		(start 372.660418 -264.010902)
		(mid 372.847616 -264.061045)
		(end 373.034814 -264.010902)
		(width 0.0889)
		(layer "B.Cu")
		(net "PU_CPU0_LEGACY_SKT")
	)
	(arc
		(start 379.628146 -264.002266)
		(mid 379.904621 -263.934946)
		(end 380.178818 -264.010902)
		(width 0.0889)
		(layer "B.Cu")
		(net "PU_CPU0_LEGACY_SKT")
	)
	(arc
		(start 379.239018 -264.010902)
		(mid 379.426216 -264.061045)
		(end 379.613414 -264.010902)
		(width 0.0889)
		(layer "B.Cu")
		(net "PU_CPU0_LEGACY_SKT")
	)
	(arc
		(start 370.634768 -263.951974)
		(mid 370.709722 -263.976351)
		(end 370.780564 -264.010902)
		(width 0.0889)
		(layer "B.Cu")
		(net "PU_CPU0_LEGACY_SKT")
	)
	(arc
		(start 373.974614 -264.010902)
		(mid 374.257316 -263.935126)
		(end 374.540018 -264.010902)
		(width 0.0889)
		(layer "B.Cu")
		(net "PU_CPU0_LEGACY_SKT")
	)
	(arc
		(start 378.299218 -264.010902)
		(mid 378.486416 -264.061045)
		(end 378.673614 -264.010902)
		(width 0.0889)
		(layer "B.Cu")
		(net "PU_CPU0_LEGACY_SKT")
	)
	(arc
		(start 382.443228 -264.004806)
		(mid 382.721406 -263.935083)
		(end 382.997964 -264.010902)
		(width 0.0889)
		(layer "B.Cu")
		(net "PU_CPU0_LEGACY_SKT")
	)
	(arc
		(start 370.780564 -264.010902)
		(mid 370.967762 -264.061045)
		(end 371.15496 -264.010902)
		(width 0.0889)
		(layer "B.Cu")
		(net "PU_CPU0_LEGACY_SKT")
	)
	(arc
		(start 380.553214 -264.010902)
		(mid 380.835916 -263.935126)
		(end 381.118618 -264.010902)
		(width 0.0889)
		(layer "B.Cu")
		(net "PU_CPU0_LEGACY_SKT")
	)
	(arc
		(start 375.479818 -264.010902)
		(mid 375.667016 -264.061045)
		(end 375.854214 -264.010902)
		(width 0.0889)
		(layer "B.Cu")
		(net "PU_CPU0_LEGACY_SKT")
	)
	(arc
		(start 371.165374 -264.004806)
		(mid 371.443806 -263.93496)
		(end 371.720618 -264.010902)
		(width 0.0889)
		(layer "B.Cu")
		(net "PU_CPU0_LEGACY_SKT")
	)
	(arc
		(start 375.868946 -264.002266)
		(mid 376.145421 -263.934946)
		(end 376.419618 -264.010902)
		(width 0.0889)
		(layer "B.Cu")
		(net "PU_CPU0_LEGACY_SKT")
	)
	(segment
		(start 349.712534 -227.367084)
		(end 349.71228 -227.36683)
		(width 0.12954)
		(layer "F.Cu")
		(net "PU_CPU0_FRMAGENT")
	)
	(segment
		(start 349.71228 -227.36683)
		(end 349.71228 -226.831144)
		(width 0.12954)
		(layer "F.Cu")
		(net "PU_CPU0_FRMAGENT")
	)
	(via
		(at 322.93814 -220.189044)
		(size 0.6604)
		(drill 0.3302)
		(layers "F.Cu" "B.Cu")
		(net "PU_CPU0_FRMAGENT")
	)
	(via
		(at 349.71228 -226.831144)
		(size 0.4572)
		(drill 0.2032)
		(layers "F.Cu" "B.Cu")
		(net "PU_CPU0_FRMAGENT")
	)
	(segment
		(start 321.039998 -189.528704)
		(end 321.039998 -189.36716)
		(width 0.12954)
		(layer "B.Cu")
		(net "PU_CPU0_FRMAGENT")
	)
	(segment
		(start 349.71228 -226.831144)
		(end 349.555816 -227.102162)
		(width 0.0889)
		(layer "B.Cu")
		(net "PU_CPU0_FRMAGENT")
	)
	(segment
		(start 338.247482 -227.155502)
		(end 338.23275 -227.146866)
		(width 0.0889)
		(layer "B.Cu")
		(net "PU_CPU0_FRMAGENT")
	)
	(segment
		(start 334.873092 -227.149406)
		(end 334.862678 -227.155502)
		(width 0.0889)
		(layer "B.Cu")
		(net "PU_CPU0_FRMAGENT")
	)
	(segment
		(start 346.705936 -227.155502)
		(end 346.695522 -227.149406)
		(width 0.0889)
		(layer "B.Cu")
		(net "PU_CPU0_FRMAGENT")
	)
	(segment
		(start 332.79588 -227.20554)
		(end 332.566518 -227.20554)
		(width 0.0889)
		(layer "B.Cu")
		(net "PU_CPU0_FRMAGENT")
	)
	(segment
		(start 332.566518 -227.20554)
		(end 331.859636 -227.20554)
		(width 0.12954)
		(layer "B.Cu")
		(net "PU_CPU0_FRMAGENT")
	)
	(segment
		(start 322.337938 -219.588842)
		(end 322.337938 -190.826644)
		(width 0.12954)
		(layer "B.Cu")
		(net "PU_CPU0_FRMAGENT")
	)
	(segment
		(start 339.187536 -227.155502)
		(end 339.177122 -227.149406)
		(width 0.0889)
		(layer "B.Cu")
		(net "PU_CPU0_FRMAGENT")
	)
	(segment
		(start 347.090746 -227.149406)
		(end 347.080332 -227.155502)
		(width 0.0889)
		(layer "B.Cu")
		(net "PU_CPU0_FRMAGENT")
	)
	(segment
		(start 348.585282 -227.155502)
		(end 348.57055 -227.146866)
		(width 0.0889)
		(layer "B.Cu")
		(net "PU_CPU0_FRMAGENT")
	)
	(segment
		(start 336.367882 -227.155502)
		(end 336.357468 -227.149406)
		(width 0.0889)
		(layer "B.Cu")
		(net "PU_CPU0_FRMAGENT")
	)
	(segment
		(start 322.93814 -220.189044)
		(end 322.337938 -219.588842)
		(width 0.12954)
		(layer "B.Cu")
		(net "PU_CPU0_FRMAGENT")
	)
	(segment
		(start 330.281026 -225.62693)
		(end 328.376026 -225.62693)
		(width 0.12954)
		(layer "B.Cu")
		(net "PU_CPU0_FRMAGENT")
	)
	(segment
		(start 332.993492 -227.149406)
		(end 332.983078 -227.155502)
		(width 0.0889)
		(layer "B.Cu")
		(net "PU_CPU0_FRMAGENT")
	)
	(segment
		(start 331.859636 -227.20554)
		(end 330.281026 -225.62693)
		(width 0.12954)
		(layer "B.Cu")
		(net "PU_CPU0_FRMAGENT")
	)
	(segment
		(start 322.337938 -190.826644)
		(end 321.039998 -189.528704)
		(width 0.12954)
		(layer "B.Cu")
		(net "PU_CPU0_FRMAGENT")
	)
	(segment
		(start 341.066882 -227.155502)
		(end 341.05215 -227.146866)
		(width 0.0889)
		(layer "B.Cu")
		(net "PU_CPU0_FRMAGENT")
	)
	(segment
		(start 342.006682 -227.155502)
		(end 341.99195 -227.146866)
		(width 0.0889)
		(layer "B.Cu")
		(net "PU_CPU0_FRMAGENT")
	)
	(segment
		(start 328.376026 -225.62693)
		(end 322.93814 -220.189044)
		(width 0.12954)
		(layer "B.Cu")
		(net "PU_CPU0_FRMAGENT")
	)
	(segment
		(start 342.946482 -227.155502)
		(end 342.93175 -227.146866)
		(width 0.0889)
		(layer "B.Cu")
		(net "PU_CPU0_FRMAGENT")
	)
	(segment
		(start 343.886536 -227.155502)
		(end 343.876122 -227.149406)
		(width 0.0889)
		(layer "B.Cu")
		(net "PU_CPU0_FRMAGENT")
	)
	(segment
		(start 344.826082 -227.155502)
		(end 344.815668 -227.149406)
		(width 0.0889)
		(layer "B.Cu")
		(net "PU_CPU0_FRMAGENT")
	)
	(segment
		(start 349.555816 -227.102162)
		(end 349.466916 -227.125784)
		(width 0.0889)
		(layer "B.Cu")
		(net "PU_CPU0_FRMAGENT")
	)
	(segment
		(start 334.488282 -227.155502)
		(end 334.477868 -227.149406)
		(width 0.0889)
		(layer "B.Cu")
		(net "PU_CPU0_FRMAGENT")
	)
	(segment
		(start 339.572346 -227.149406)
		(end 339.561932 -227.155502)
		(width 0.0889)
		(layer "B.Cu")
		(net "PU_CPU0_FRMAGENT")
	)
	(segment
		(start 337.307682 -227.155502)
		(end 337.29295 -227.146866)
		(width 0.0889)
		(layer "B.Cu")
		(net "PU_CPU0_FRMAGENT")
	)
	(segment
		(start 345.765882 -227.155502)
		(end 345.75115 -227.146866)
		(width 0.0889)
		(layer "B.Cu")
		(net "PU_CPU0_FRMAGENT")
	)
	(arc
		(start 340.501478 -227.155502)
		(mid 340.31428 -227.205645)
		(end 340.127082 -227.155502)
		(width 0.0889)
		(layer "B.Cu")
		(net "PU_CPU0_FRMAGENT")
	)
	(arc
		(start 349.466916 -227.125784)
		(mid 349.209777 -227.080482)
		(end 348.959678 -227.155502)
		(width 0.0889)
		(layer "B.Cu")
		(net "PU_CPU0_FRMAGENT")
	)
	(arc
		(start 348.57055 -227.146866)
		(mid 348.294075 -227.079546)
		(end 348.019878 -227.155502)
		(width 0.0889)
		(layer "B.Cu")
		(net "PU_CPU0_FRMAGENT")
	)
	(arc
		(start 339.561932 -227.155502)
		(mid 339.374734 -227.205645)
		(end 339.187536 -227.155502)
		(width 0.0889)
		(layer "B.Cu")
		(net "PU_CPU0_FRMAGENT")
	)
	(arc
		(start 342.93175 -227.146866)
		(mid 342.655275 -227.079546)
		(end 342.381078 -227.155502)
		(width 0.0889)
		(layer "B.Cu")
		(net "PU_CPU0_FRMAGENT")
	)
	(arc
		(start 347.645482 -227.155502)
		(mid 347.368923 -227.079759)
		(end 347.090746 -227.149406)
		(width 0.0889)
		(layer "B.Cu")
		(net "PU_CPU0_FRMAGENT")
	)
	(arc
		(start 335.428336 -227.155502)
		(mid 335.151523 -227.079632)
		(end 334.873092 -227.149406)
		(width 0.0889)
		(layer "B.Cu")
		(net "PU_CPU0_FRMAGENT")
	)
	(arc
		(start 343.876122 -227.149406)
		(mid 343.59769 -227.07956)
		(end 343.320878 -227.155502)
		(width 0.0889)
		(layer "B.Cu")
		(net "PU_CPU0_FRMAGENT")
	)
	(arc
		(start 340.127082 -227.155502)
		(mid 339.850523 -227.079759)
		(end 339.572346 -227.149406)
		(width 0.0889)
		(layer "B.Cu")
		(net "PU_CPU0_FRMAGENT")
	)
	(arc
		(start 338.23275 -227.146866)
		(mid 337.956275 -227.079546)
		(end 337.682078 -227.155502)
		(width 0.0889)
		(layer "B.Cu")
		(net "PU_CPU0_FRMAGENT")
	)
	(arc
		(start 337.29295 -227.146866)
		(mid 337.016475 -227.079546)
		(end 336.742278 -227.155502)
		(width 0.0889)
		(layer "B.Cu")
		(net "PU_CPU0_FRMAGENT")
	)
	(arc
		(start 339.177122 -227.149406)
		(mid 338.89869 -227.07956)
		(end 338.621878 -227.155502)
		(width 0.0889)
		(layer "B.Cu")
		(net "PU_CPU0_FRMAGENT")
	)
	(arc
		(start 343.320878 -227.155502)
		(mid 343.13368 -227.205645)
		(end 342.946482 -227.155502)
		(width 0.0889)
		(layer "B.Cu")
		(net "PU_CPU0_FRMAGENT")
	)
	(arc
		(start 334.477868 -227.149406)
		(mid 334.19969 -227.079683)
		(end 333.923132 -227.155502)
		(width 0.0889)
		(layer "B.Cu")
		(net "PU_CPU0_FRMAGENT")
	)
	(arc
		(start 335.802732 -227.155502)
		(mid 335.615534 -227.205645)
		(end 335.428336 -227.155502)
		(width 0.0889)
		(layer "B.Cu")
		(net "PU_CPU0_FRMAGENT")
	)
	(arc
		(start 336.742278 -227.155502)
		(mid 336.55508 -227.205645)
		(end 336.367882 -227.155502)
		(width 0.0889)
		(layer "B.Cu")
		(net "PU_CPU0_FRMAGENT")
	)
	(arc
		(start 344.260932 -227.155502)
		(mid 344.073734 -227.205645)
		(end 343.886536 -227.155502)
		(width 0.0889)
		(layer "B.Cu")
		(net "PU_CPU0_FRMAGENT")
	)
	(arc
		(start 332.983078 -227.155502)
		(mid 332.892771 -227.192831)
		(end 332.79588 -227.20554)
		(width 0.0889)
		(layer "B.Cu")
		(net "PU_CPU0_FRMAGENT")
	)
	(arc
		(start 338.621878 -227.155502)
		(mid 338.43468 -227.205645)
		(end 338.247482 -227.155502)
		(width 0.0889)
		(layer "B.Cu")
		(net "PU_CPU0_FRMAGENT")
	)
	(arc
		(start 345.200478 -227.155502)
		(mid 345.01328 -227.205645)
		(end 344.826082 -227.155502)
		(width 0.0889)
		(layer "B.Cu")
		(net "PU_CPU0_FRMAGENT")
	)
	(arc
		(start 346.140278 -227.155502)
		(mid 345.95308 -227.205645)
		(end 345.765882 -227.155502)
		(width 0.0889)
		(layer "B.Cu")
		(net "PU_CPU0_FRMAGENT")
	)
	(arc
		(start 341.05215 -227.146866)
		(mid 340.775675 -227.079546)
		(end 340.501478 -227.155502)
		(width 0.0889)
		(layer "B.Cu")
		(net "PU_CPU0_FRMAGENT")
	)
	(arc
		(start 348.019878 -227.155502)
		(mid 347.83268 -227.205645)
		(end 347.645482 -227.155502)
		(width 0.0889)
		(layer "B.Cu")
		(net "PU_CPU0_FRMAGENT")
	)
	(arc
		(start 345.75115 -227.146866)
		(mid 345.474675 -227.079546)
		(end 345.200478 -227.155502)
		(width 0.0889)
		(layer "B.Cu")
		(net "PU_CPU0_FRMAGENT")
	)
	(arc
		(start 337.682078 -227.155502)
		(mid 337.49488 -227.205645)
		(end 337.307682 -227.155502)
		(width 0.0889)
		(layer "B.Cu")
		(net "PU_CPU0_FRMAGENT")
	)
	(arc
		(start 341.441278 -227.155502)
		(mid 341.25408 -227.205645)
		(end 341.066882 -227.155502)
		(width 0.0889)
		(layer "B.Cu")
		(net "PU_CPU0_FRMAGENT")
	)
	(arc
		(start 342.381078 -227.155502)
		(mid 342.19388 -227.205645)
		(end 342.006682 -227.155502)
		(width 0.0889)
		(layer "B.Cu")
		(net "PU_CPU0_FRMAGENT")
	)
	(arc
		(start 347.080332 -227.155502)
		(mid 346.893134 -227.205645)
		(end 346.705936 -227.155502)
		(width 0.0889)
		(layer "B.Cu")
		(net "PU_CPU0_FRMAGENT")
	)
	(arc
		(start 334.862678 -227.155502)
		(mid 334.67548 -227.205645)
		(end 334.488282 -227.155502)
		(width 0.0889)
		(layer "B.Cu")
		(net "PU_CPU0_FRMAGENT")
	)
	(arc
		(start 348.959678 -227.155502)
		(mid 348.77248 -227.205645)
		(end 348.585282 -227.155502)
		(width 0.0889)
		(layer "B.Cu")
		(net "PU_CPU0_FRMAGENT")
	)
	(arc
		(start 333.923132 -227.155502)
		(mid 333.735934 -227.205645)
		(end 333.548736 -227.155502)
		(width 0.0889)
		(layer "B.Cu")
		(net "PU_CPU0_FRMAGENT")
	)
	(arc
		(start 333.548736 -227.155502)
		(mid 333.271923 -227.079632)
		(end 332.993492 -227.149406)
		(width 0.0889)
		(layer "B.Cu")
		(net "PU_CPU0_FRMAGENT")
	)
	(arc
		(start 344.815668 -227.149406)
		(mid 344.53749 -227.079683)
		(end 344.260932 -227.155502)
		(width 0.0889)
		(layer "B.Cu")
		(net "PU_CPU0_FRMAGENT")
	)
	(arc
		(start 336.357468 -227.149406)
		(mid 336.07929 -227.079683)
		(end 335.802732 -227.155502)
		(width 0.0889)
		(layer "B.Cu")
		(net "PU_CPU0_FRMAGENT")
	)
	(arc
		(start 346.695522 -227.149406)
		(mid 346.41709 -227.07956)
		(end 346.140278 -227.155502)
		(width 0.0889)
		(layer "B.Cu")
		(net "PU_CPU0_FRMAGENT")
	)
	(arc
		(start 341.99195 -227.146866)
		(mid 341.715475 -227.079546)
		(end 341.441278 -227.155502)
		(width 0.0889)
		(layer "B.Cu")
		(net "PU_CPU0_FRMAGENT")
	)
	(segment
		(start 252.557788 -100.563172)
		(end 250.88977 -100.563172)
		(width 0.0889)
		(layer "F.Cu")
		(net "PU_CLK_PFT_LOST_N")
	)
	(segment
		(start 250.88977 -100.563172)
		(end 249.841766 -100.997512)
		(width 0.0889)
		(layer "F.Cu")
		(net "PU_CLK_PFT_LOST_N")
	)
	(via
		(at 249.841766 -100.997512)
		(size 0.508)
		(drill 0.254)
		(layers "F.Cu" "B.Cu")
		(net "PU_CLK_PFT_LOST_N")
	)
	(segment
		(start 249.190256 -102.112318)
		(end 246.22125 -102.112318)
		(width 0.12954)
		(layer "B.Cu")
		(net "PU_CLK_PFT_LOST_N")
	)
	(segment
		(start 249.841766 -100.997512)
		(end 249.841766 -101.460808)
		(width 0.12954)
		(layer "B.Cu")
		(net "PU_CLK_PFT_LOST_N")
	)
	(segment
		(start 249.841766 -101.460808)
		(end 249.190256 -102.112318)
		(width 0.12954)
		(layer "B.Cu")
		(net "PU_CLK_PFT_LOST_N")
	)
	(segment
		(start 196.59473 -113.263934)
		(end 195.850764 -113.263934)
		(width 0.12954)
		(layer "F.Cu")
		(net "PU_CLK25M_OSC_FPGA_EN")
	)
	(segment
		(start 197.41388 -113.902998)
		(end 197.233794 -113.902998)
		(width 0.12954)
		(layer "F.Cu")
		(net "PU_CLK25M_OSC_FPGA_EN")
	)
	(segment
		(start 196.845428 -113.514632)
		(end 196.59473 -113.263934)
		(width 0.12954)
		(layer "F.Cu")
		(net "PU_CLK25M_OSC_FPGA_EN")
	)
	(segment
		(start 197.233794 -113.902998)
		(end 196.845428 -113.514632)
		(width 0.12954)
		(layer "F.Cu")
		(net "PU_CLK25M_OSC_FPGA_EN")
	)
	(via
		(at 196.845428 -113.514632)
		(size 0.508)
		(drill 0.254)
		(layers "F.Cu" "B.Cu")
		(net "PU_CLK25M_OSC_FPGA_EN")
	)
	(segment
		(start 254.182626 -105.579672)
		(end 253.29515 -106.467148)
		(width 0.0889)
		(layer "F.Cu")
		(net "PU_CK440_SHFT_LD_N")
	)
	(segment
		(start 254.182626 -102.688136)
		(end 254.182626 -105.579672)
		(width 0.0889)
		(layer "F.Cu")
		(net "PU_CK440_SHFT_LD_N")
	)
	(via
		(at 253.29515 -106.467148)
		(size 0.508)
		(drill 0.254)
		(layers "F.Cu" "B.Cu")
		(net "PU_CK440_SHFT_LD_N")
	)
	(segment
		(start 254.424434 -107.361228)
		(end 254.424434 -106.467148)
		(width 0.12954)
		(layer "B.Cu")
		(net "PU_CK440_SHFT_LD_N")
	)
	(segment
		(start 254.424434 -106.467148)
		(end 253.29515 -106.467148)
		(width 0.12954)
		(layer "B.Cu")
		(net "PU_CK440_SHFT_LD_N")
	)
	(segment
		(start 426.630084 -42.078402)
		(end 426.630084 -42.079926)
		(width 0.12954)
		(layer "F.Cu")
		(net "PU_BIOS_RCVR_BOOT")
	)
	(segment
		(start 427.848268 -40.860218)
		(end 426.630084 -42.078402)
		(width 0.12954)
		(layer "F.Cu")
		(net "PU_BIOS_RCVR_BOOT")
	)
	(segment
		(start 431.694082 -40.860218)
		(end 427.848268 -40.860218)
		(width 0.12954)
		(layer "F.Cu")
		(net "PU_BIOS_RCVR_BOOT")
	)
	(segment
		(start 432.97475 -42.140886)
		(end 431.694082 -40.860218)
		(width 0.12954)
		(layer "F.Cu")
		(net "PU_BIOS_RCVR_BOOT")
	)
	(segment
		(start 434.77307 -42.140886)
		(end 432.97475 -42.140886)
		(width 0.12954)
		(layer "F.Cu")
		(net "PU_BIOS_RCVR_BOOT")
	)
	(via
		(at 432.97475 -42.140886)
		(size 0.762)
		(drill 0.381)
		(layers "F.Cu" "B.Cu")
		(net "PU_BIOS_RCVR_BOOT")
	)
	(segment
		(start 328.717402 -44.66971)
		(end 328.717402 -44.305728)
		(width 0.12954)
		(layer "F.Cu")
		(net "PU_ACPRESENT")
	)
	(segment
		(start 328.717402 -44.305728)
		(end 328.801984 -44.221146)
		(width 0.12954)
		(layer "F.Cu")
		(net "PU_ACPRESENT")
	)
	(segment
		(start 328.801984 -44.221146)
		(end 329.165966 -44.221146)
		(width 0.12954)
		(layer "F.Cu")
		(net "PU_ACPRESENT")
	)
	(via
		(at 317.35522 -37.49548)
		(size 0.6604)
		(drill 0.3302)
		(layers "F.Cu" "B.Cu")
		(net "PU_ACPRESENT")
	)
	(via
		(at 328.717402 -44.66971)
		(size 0.4572)
		(drill 0.2032)
		(layers "F.Cu" "B.Cu")
		(net "PU_ACPRESENT")
	)
	(segment
		(start 316.601856 -33.835848)
		(end 316.601856 -36.3982)
		(width 0.12954)
		(layer "B.Cu")
		(net "PU_ACPRESENT")
	)
	(segment
		(start 317.35522 -37.151564)
		(end 317.35522 -37.49548)
		(width 0.12954)
		(layer "B.Cu")
		(net "PU_ACPRESENT")
	)
	(segment
		(start 323.964554 -42.374058)
		(end 326.098154 -44.507658)
		(width 0.12954)
		(layer "B.Cu")
		(net "PU_ACPRESENT")
	)
	(segment
		(start 323.885814 -42.184066)
		(end 323.964554 -42.374058)
		(width 0.12954)
		(layer "B.Cu")
		(net "PU_ACPRESENT")
	)
	(segment
		(start 328.344022 -44.66971)
		(end 328.717402 -44.66971)
		(width 0.0889)
		(layer "B.Cu")
		(net "PU_ACPRESENT")
	)
	(segment
		(start 327.818496 -44.507658)
		(end 328.18197 -44.507658)
		(width 0.0889)
		(layer "B.Cu")
		(net "PU_ACPRESENT")
	)
	(segment
		(start 322.644516 -41.496488)
		(end 323.198236 -41.496488)
		(width 0.12954)
		(layer "B.Cu")
		(net "PU_ACPRESENT")
	)
	(segment
		(start 323.198236 -41.496488)
		(end 323.885814 -42.184066)
		(width 0.12954)
		(layer "B.Cu")
		(net "PU_ACPRESENT")
	)
	(segment
		(start 316.601856 -36.3982)
		(end 317.35522 -37.151564)
		(width 0.12954)
		(layer "B.Cu")
		(net "PU_ACPRESENT")
	)
	(segment
		(start 312.589672 -29.708348)
		(end 313.000136 -30.118812)
		(width 0.12954)
		(layer "B.Cu")
		(net "PU_ACPRESENT")
	)
	(segment
		(start 319.971166 -40.136318)
		(end 320.78168 -40.946832)
		(width 0.12954)
		(layer "B.Cu")
		(net "PU_ACPRESENT")
	)
	(segment
		(start 321.06616 -41.803828)
		(end 322.337176 -41.803828)
		(width 0.12954)
		(layer "B.Cu")
		(net "PU_ACPRESENT")
	)
	(segment
		(start 320.78168 -41.519348)
		(end 321.06616 -41.803828)
		(width 0.12954)
		(layer "B.Cu")
		(net "PU_ACPRESENT")
	)
	(segment
		(start 322.337176 -41.803828)
		(end 322.644516 -41.496488)
		(width 0.12954)
		(layer "B.Cu")
		(net "PU_ACPRESENT")
	)
	(segment
		(start 317.35522 -37.49548)
		(end 317.699136 -37.49548)
		(width 0.12954)
		(layer "B.Cu")
		(net "PU_ACPRESENT")
	)
	(segment
		(start 320.78168 -40.946832)
		(end 320.78168 -41.519348)
		(width 0.12954)
		(layer "B.Cu")
		(net "PU_ACPRESENT")
	)
	(segment
		(start 317.699136 -37.49548)
		(end 319.971166 -39.76751)
		(width 0.12954)
		(layer "B.Cu")
		(net "PU_ACPRESENT")
	)
	(segment
		(start 319.971166 -39.76751)
		(end 319.971166 -40.136318)
		(width 0.12954)
		(layer "B.Cu")
		(net "PU_ACPRESENT")
	)
	(segment
		(start 326.098154 -44.507658)
		(end 327.818496 -44.507658)
		(width 0.12954)
		(layer "B.Cu")
		(net "PU_ACPRESENT")
	)
	(segment
		(start 313.000136 -30.234128)
		(end 316.601856 -33.835848)
		(width 0.12954)
		(layer "B.Cu")
		(net "PU_ACPRESENT")
	)
	(segment
		(start 328.18197 -44.507658)
		(end 328.344022 -44.66971)
		(width 0.0889)
		(layer "B.Cu")
		(net "PU_ACPRESENT")
	)
	(segment
		(start 313.000136 -30.118812)
		(end 313.000136 -30.234128)
		(width 0.12954)
		(layer "B.Cu")
		(net "PU_ACPRESENT")
	)
	(segment
		(start 116.919248 -274.266914)
		(end 116.919248 -273.730974)
		(width 0.12954)
		(layer "F.Cu")
		(net "PUD_XTAL_CPU1_MODE1")
	)
	(via
		(at 140.546328 -260.72211)
		(size 0.6604)
		(drill 0.3302)
		(layers "F.Cu" "B.Cu")
		(net "PUD_XTAL_CPU1_MODE1")
	)
	(via
		(at 115.509548 -263.686544)
		(size 0.4572)
		(drill 0.2032)
		(layers "F.Cu" "B.Cu")
		(net "PUD_XTAL_CPU1_MODE1")
	)
	(via
		(at 116.919248 -274.266914)
		(size 0.4572)
		(drill 0.2032)
		(layers "F.Cu" "B.Cu")
		(net "PUD_XTAL_CPU1_MODE1")
	)
	(segment
		(start 115.91163 -263.686544)
		(end 116.171472 -263.946386)
		(width 0.12954)
		(layer "B.Cu")
		(net "PUD_XTAL_CPU1_MODE1")
	)
	(segment
		(start 156.892498 -248.83999)
		(end 160.105598 -248.83999)
		(width 0.12954)
		(layer "B.Cu")
		(net "PUD_XTAL_CPU1_MODE1")
	)
	(segment
		(start 125.602492 -262.459978)
		(end 125.612144 -262.465566)
		(width 0.12954)
		(layer "B.Cu")
		(net "PUD_XTAL_CPU1_MODE1")
	)
	(segment
		(start 119.055896 -263.715246)
		(end 120.306338 -263.715246)
		(width 0.12954)
		(layer "B.Cu")
		(net "PUD_XTAL_CPU1_MODE1")
	)
	(segment
		(start 121.162572 -262.859012)
		(end 121.162572 -262.590026)
		(width 0.12954)
		(layer "B.Cu")
		(net "PUD_XTAL_CPU1_MODE1")
	)
	(segment
		(start 128.887982 -262.47344)
		(end 128.901444 -262.465566)
		(width 0.12954)
		(layer "B.Cu")
		(net "PUD_XTAL_CPU1_MODE1")
	)
	(segment
		(start 140.546328 -260.72211)
		(end 145.010378 -260.72211)
		(width 0.12954)
		(layer "B.Cu")
		(net "PUD_XTAL_CPU1_MODE1")
	)
	(segment
		(start 121.350024 -262.402574)
		(end 121.617994 -262.402574)
		(width 0.12954)
		(layer "B.Cu")
		(net "PUD_XTAL_CPU1_MODE1")
	)
	(segment
		(start 165.157658 -249.00763)
		(end 165.522148 -249.00763)
		(width 0.12954)
		(layer "B.Cu")
		(net "PUD_XTAL_CPU1_MODE1")
	)
	(segment
		(start 124.188982 -262.47344)
		(end 124.202444 -262.465566)
		(width 0.12954)
		(layer "B.Cu")
		(net "PUD_XTAL_CPU1_MODE1")
	)
	(segment
		(start 166.786052 -251.267214)
		(end 166.786052 -250.271534)
		(width 0.12954)
		(layer "B.Cu")
		(net "PUD_XTAL_CPU1_MODE1")
	)
	(segment
		(start 127.948182 -262.47344)
		(end 127.961644 -262.465566)
		(width 0.12954)
		(layer "B.Cu")
		(net "PUD_XTAL_CPU1_MODE1")
	)
	(segment
		(start 122.783092 -262.459978)
		(end 122.792744 -262.465566)
		(width 0.12954)
		(layer "B.Cu")
		(net "PUD_XTAL_CPU1_MODE1")
	)
	(segment
		(start 145.010378 -260.72211)
		(end 156.892498 -248.83999)
		(width 0.12954)
		(layer "B.Cu")
		(net "PUD_XTAL_CPU1_MODE1")
	)
	(segment
		(start 134.526782 -262.47344)
		(end 134.540244 -262.465566)
		(width 0.12954)
		(layer "B.Cu")
		(net "PUD_XTAL_CPU1_MODE1")
	)
	(segment
		(start 130.767582 -262.47344)
		(end 130.781044 -262.465566)
		(width 0.12954)
		(layer "B.Cu")
		(net "PUD_XTAL_CPU1_MODE1")
	)
	(segment
		(start 133.586982 -262.47344)
		(end 133.600444 -262.465566)
		(width 0.12954)
		(layer "B.Cu")
		(net "PUD_XTAL_CPU1_MODE1")
	)
	(segment
		(start 160.740598 -248.20499)
		(end 164.355018 -248.20499)
		(width 0.12954)
		(layer "B.Cu")
		(net "PUD_XTAL_CPU1_MODE1")
	)
	(segment
		(start 129.827782 -262.47344)
		(end 129.841244 -262.465566)
		(width 0.12954)
		(layer "B.Cu")
		(net "PUD_XTAL_CPU1_MODE1")
	)
	(segment
		(start 164.355018 -248.20499)
		(end 165.157658 -249.00763)
		(width 0.12954)
		(layer "B.Cu")
		(net "PUD_XTAL_CPU1_MODE1")
	)
	(segment
		(start 160.105598 -248.83999)
		(end 160.740598 -248.20499)
		(width 0.12954)
		(layer "B.Cu")
		(net "PUD_XTAL_CPU1_MODE1")
	)
	(segment
		(start 127.008382 -262.47344)
		(end 127.021844 -262.465566)
		(width 0.12954)
		(layer "B.Cu")
		(net "PUD_XTAL_CPU1_MODE1")
	)
	(segment
		(start 120.306338 -263.715246)
		(end 121.162572 -262.859012)
		(width 0.12954)
		(layer "B.Cu")
		(net "PUD_XTAL_CPU1_MODE1")
	)
	(segment
		(start 132.181092 -262.459978)
		(end 132.190744 -262.465566)
		(width 0.12954)
		(layer "B.Cu")
		(net "PUD_XTAL_CPU1_MODE1")
	)
	(segment
		(start 165.522148 -249.00763)
		(end 166.786052 -250.271534)
		(width 0.12954)
		(layer "B.Cu")
		(net "PUD_XTAL_CPU1_MODE1")
	)
	(segment
		(start 131.711446 -262.471154)
		(end 131.721098 -262.465566)
		(width 0.12954)
		(layer "B.Cu")
		(net "PUD_XTAL_CPU1_MODE1")
	)
	(segment
		(start 136.517126 -262.39089)
		(end 138.185906 -260.72211)
		(width 0.12954)
		(layer "B.Cu")
		(net "PUD_XTAL_CPU1_MODE1")
	)
	(segment
		(start 115.509548 -263.686544)
		(end 115.91163 -263.686544)
		(width 0.12954)
		(layer "B.Cu")
		(net "PUD_XTAL_CPU1_MODE1")
	)
	(segment
		(start 138.185906 -260.72211)
		(end 140.546328 -260.72211)
		(width 0.12954)
		(layer "B.Cu")
		(net "PUD_XTAL_CPU1_MODE1")
	)
	(segment
		(start 121.162572 -262.590026)
		(end 121.350024 -262.402574)
		(width 0.12954)
		(layer "B.Cu")
		(net "PUD_XTAL_CPU1_MODE1")
	)
	(segment
		(start 116.171472 -263.946386)
		(end 118.824756 -263.946386)
		(width 0.12954)
		(layer "B.Cu")
		(net "PUD_XTAL_CPU1_MODE1")
	)
	(segment
		(start 122.313446 -262.471154)
		(end 122.323098 -262.465566)
		(width 0.12954)
		(layer "B.Cu")
		(net "PUD_XTAL_CPU1_MODE1")
	)
	(segment
		(start 125.132846 -262.471154)
		(end 125.142498 -262.465566)
		(width 0.12954)
		(layer "B.Cu")
		(net "PUD_XTAL_CPU1_MODE1")
	)
	(segment
		(start 118.824756 -263.946386)
		(end 119.055896 -263.715246)
		(width 0.12954)
		(layer "B.Cu")
		(net "PUD_XTAL_CPU1_MODE1")
	)
	(arc
		(start 123.732544 -262.465566)
		(mid 123.959731 -262.528584)
		(end 124.188982 -262.47344)
		(width 0.12954)
		(layer "B.Cu")
		(net "PUD_XTAL_CPU1_MODE1")
	)
	(arc
		(start 134.070344 -262.465566)
		(mid 134.297531 -262.528584)
		(end 134.526782 -262.47344)
		(width 0.12954)
		(layer "B.Cu")
		(net "PUD_XTAL_CPU1_MODE1")
	)
	(arc
		(start 127.961644 -262.465566)
		(mid 128.196594 -262.402606)
		(end 128.431544 -262.465566)
		(width 0.12954)
		(layer "B.Cu")
		(net "PUD_XTAL_CPU1_MODE1")
	)
	(arc
		(start 125.142498 -262.465566)
		(mid 125.371761 -262.402641)
		(end 125.602492 -262.459978)
		(width 0.12954)
		(layer "B.Cu")
		(net "PUD_XTAL_CPU1_MODE1")
	)
	(arc
		(start 132.190744 -262.465566)
		(mid 132.425694 -262.528526)
		(end 132.660644 -262.465566)
		(width 0.12954)
		(layer "B.Cu")
		(net "PUD_XTAL_CPU1_MODE1")
	)
	(arc
		(start 131.721098 -262.465566)
		(mid 131.950361 -262.402641)
		(end 132.181092 -262.459978)
		(width 0.12954)
		(layer "B.Cu")
		(net "PUD_XTAL_CPU1_MODE1")
	)
	(arc
		(start 130.781044 -262.465566)
		(mid 131.015994 -262.402606)
		(end 131.250944 -262.465566)
		(width 0.12954)
		(layer "B.Cu")
		(net "PUD_XTAL_CPU1_MODE1")
	)
	(arc
		(start 135.949944 -262.465566)
		(mid 136.184894 -262.528526)
		(end 136.419844 -262.465566)
		(width 0.12954)
		(layer "B.Cu")
		(net "PUD_XTAL_CPU1_MODE1")
	)
	(arc
		(start 124.672344 -262.465566)
		(mid 124.901861 -262.528618)
		(end 125.132846 -262.471154)
		(width 0.12954)
		(layer "B.Cu")
		(net "PUD_XTAL_CPU1_MODE1")
	)
	(arc
		(start 136.419844 -262.465566)
		(mid 136.470939 -262.431423)
		(end 136.517126 -262.39089)
		(width 0.12954)
		(layer "B.Cu")
		(net "PUD_XTAL_CPU1_MODE1")
	)
	(arc
		(start 121.617994 -262.402574)
		(mid 121.739618 -262.418596)
		(end 121.852944 -262.465566)
		(width 0.12954)
		(layer "B.Cu")
		(net "PUD_XTAL_CPU1_MODE1")
	)
	(arc
		(start 125.612144 -262.465566)
		(mid 125.847094 -262.528526)
		(end 126.082044 -262.465566)
		(width 0.12954)
		(layer "B.Cu")
		(net "PUD_XTAL_CPU1_MODE1")
	)
	(arc
		(start 133.130544 -262.465566)
		(mid 133.357731 -262.528584)
		(end 133.586982 -262.47344)
		(width 0.12954)
		(layer "B.Cu")
		(net "PUD_XTAL_CPU1_MODE1")
	)
	(arc
		(start 121.852944 -262.465566)
		(mid 122.082461 -262.528618)
		(end 122.313446 -262.471154)
		(width 0.12954)
		(layer "B.Cu")
		(net "PUD_XTAL_CPU1_MODE1")
	)
	(arc
		(start 129.841244 -262.465566)
		(mid 130.076194 -262.402606)
		(end 130.311144 -262.465566)
		(width 0.12954)
		(layer "B.Cu")
		(net "PUD_XTAL_CPU1_MODE1")
	)
	(arc
		(start 126.551944 -262.465566)
		(mid 126.779131 -262.528584)
		(end 127.008382 -262.47344)
		(width 0.12954)
		(layer "B.Cu")
		(net "PUD_XTAL_CPU1_MODE1")
	)
	(arc
		(start 122.792744 -262.465566)
		(mid 123.027694 -262.528526)
		(end 123.262644 -262.465566)
		(width 0.12954)
		(layer "B.Cu")
		(net "PUD_XTAL_CPU1_MODE1")
	)
	(arc
		(start 126.082044 -262.465566)
		(mid 126.316994 -262.402606)
		(end 126.551944 -262.465566)
		(width 0.12954)
		(layer "B.Cu")
		(net "PUD_XTAL_CPU1_MODE1")
	)
	(arc
		(start 128.901444 -262.465566)
		(mid 129.136394 -262.402606)
		(end 129.371344 -262.465566)
		(width 0.12954)
		(layer "B.Cu")
		(net "PUD_XTAL_CPU1_MODE1")
	)
	(arc
		(start 135.010144 -262.465566)
		(mid 135.245094 -262.528526)
		(end 135.480044 -262.465566)
		(width 0.12954)
		(layer "B.Cu")
		(net "PUD_XTAL_CPU1_MODE1")
	)
	(arc
		(start 135.480044 -262.465566)
		(mid 135.714994 -262.402606)
		(end 135.949944 -262.465566)
		(width 0.12954)
		(layer "B.Cu")
		(net "PUD_XTAL_CPU1_MODE1")
	)
	(arc
		(start 131.250944 -262.465566)
		(mid 131.480461 -262.528618)
		(end 131.711446 -262.471154)
		(width 0.12954)
		(layer "B.Cu")
		(net "PUD_XTAL_CPU1_MODE1")
	)
	(arc
		(start 124.202444 -262.465566)
		(mid 124.437394 -262.402606)
		(end 124.672344 -262.465566)
		(width 0.12954)
		(layer "B.Cu")
		(net "PUD_XTAL_CPU1_MODE1")
	)
	(arc
		(start 127.021844 -262.465566)
		(mid 127.256794 -262.402606)
		(end 127.491744 -262.465566)
		(width 0.12954)
		(layer "B.Cu")
		(net "PUD_XTAL_CPU1_MODE1")
	)
	(arc
		(start 128.431544 -262.465566)
		(mid 128.658731 -262.528584)
		(end 128.887982 -262.47344)
		(width 0.12954)
		(layer "B.Cu")
		(net "PUD_XTAL_CPU1_MODE1")
	)
	(arc
		(start 122.323098 -262.465566)
		(mid 122.552361 -262.402641)
		(end 122.783092 -262.459978)
		(width 0.12954)
		(layer "B.Cu")
		(net "PUD_XTAL_CPU1_MODE1")
	)
	(arc
		(start 127.491744 -262.465566)
		(mid 127.718931 -262.528584)
		(end 127.948182 -262.47344)
		(width 0.12954)
		(layer "B.Cu")
		(net "PUD_XTAL_CPU1_MODE1")
	)
	(arc
		(start 130.311144 -262.465566)
		(mid 130.538331 -262.528584)
		(end 130.767582 -262.47344)
		(width 0.12954)
		(layer "B.Cu")
		(net "PUD_XTAL_CPU1_MODE1")
	)
	(arc
		(start 123.262644 -262.465566)
		(mid 123.497594 -262.402606)
		(end 123.732544 -262.465566)
		(width 0.12954)
		(layer "B.Cu")
		(net "PUD_XTAL_CPU1_MODE1")
	)
	(arc
		(start 134.540244 -262.465566)
		(mid 134.775194 -262.402606)
		(end 135.010144 -262.465566)
		(width 0.12954)
		(layer "B.Cu")
		(net "PUD_XTAL_CPU1_MODE1")
	)
	(arc
		(start 133.600444 -262.465566)
		(mid 133.835394 -262.402606)
		(end 134.070344 -262.465566)
		(width 0.12954)
		(layer "B.Cu")
		(net "PUD_XTAL_CPU1_MODE1")
	)
	(arc
		(start 132.660644 -262.465566)
		(mid 132.895594 -262.402606)
		(end 133.130544 -262.465566)
		(width 0.12954)
		(layer "B.Cu")
		(net "PUD_XTAL_CPU1_MODE1")
	)
	(arc
		(start 129.371344 -262.465566)
		(mid 129.598531 -262.528584)
		(end 129.827782 -262.47344)
		(width 0.12954)
		(layer "B.Cu")
		(net "PUD_XTAL_CPU1_MODE1")
	)
	(segment
		(start 116.919502 -274.26666)
		(end 116.919502 -273.453352)
		(width 0.127)
		(layer "In4.Cu")
		(net "PUD_XTAL_CPU1_MODE1")
	)
	(segment
		(start 116.684298 -264.907522)
		(end 116.679472 -264.904728)
		(width 0.127)
		(layer "In4.Cu")
		(net "PUD_XTAL_CPU1_MODE1")
	)
	(segment
		(start 116.684298 -273.046444)
		(end 116.679472 -273.04365)
		(width 0.127)
		(layer "In4.Cu")
		(net "PUD_XTAL_CPU1_MODE1")
	)
	(segment
		(start 116.449348 -264.500614)
		(end 116.449348 -264.214102)
		(width 0.127)
		(layer "In4.Cu")
		(net "PUD_XTAL_CPU1_MODE1")
	)
	(segment
		(start 116.689378 -268.165834)
		(end 116.679726 -268.160246)
		(width 0.127)
		(layer "In4.Cu")
		(net "PUD_XTAL_CPU1_MODE1")
	)
	(segment
		(start 116.919502 -270.197834)
		(end 116.919502 -270.190214)
		(width 0.127)
		(layer "In4.Cu")
		(net "PUD_XTAL_CPU1_MODE1")
	)
	(segment
		(start 116.684298 -265.721592)
		(end 116.684298 -265.721338)
		(width 0.127)
		(layer "In4.Cu")
		(net "PUD_XTAL_CPU1_MODE1")
	)
	(segment
		(start 116.679472 -270.607536)
		(end 116.684298 -270.604742)
		(width 0.127)
		(layer "In4.Cu")
		(net "PUD_XTAL_CPU1_MODE1")
	)
	(segment
		(start 116.694966 -271.424908)
		(end 116.684298 -271.418558)
		(width 0.127)
		(layer "In4.Cu")
		(net "PUD_XTAL_CPU1_MODE1")
	)
	(segment
		(start 116.700808 -266.54506)
		(end 116.670836 -266.527534)
		(width 0.127)
		(layer "In4.Cu")
		(net "PUD_XTAL_CPU1_MODE1")
	)
	(segment
		(start 116.694966 -264.913872)
		(end 116.684298 -264.907522)
		(width 0.127)
		(layer "In4.Cu")
		(net "PUD_XTAL_CPU1_MODE1")
	)
	(segment
		(start 116.919248 -266.949682)
		(end 116.919248 -266.942062)
		(width 0.127)
		(layer "In4.Cu")
		(net "PUD_XTAL_CPU1_MODE1")
	)
	(segment
		(start 116.694966 -273.052794)
		(end 116.684298 -273.046444)
		(width 0.127)
		(layer "In4.Cu")
		(net "PUD_XTAL_CPU1_MODE1")
	)
	(segment
		(start 116.684298 -268.976856)
		(end 116.684552 -268.976602)
		(width 0.127)
		(layer "In4.Cu")
		(net "PUD_XTAL_CPU1_MODE1")
	)
	(segment
		(start 116.449348 -264.214102)
		(end 115.92179 -263.686544)
		(width 0.127)
		(layer "In4.Cu")
		(net "PUD_XTAL_CPU1_MODE1")
	)
	(segment
		(start 116.679472 -272.235422)
		(end 116.684298 -272.232628)
		(width 0.127)
		(layer "In4.Cu")
		(net "PUD_XTAL_CPU1_MODE1")
	)
	(segment
		(start 115.92179 -263.686544)
		(end 115.509548 -263.686544)
		(width 0.127)
		(layer "In4.Cu")
		(net "PUD_XTAL_CPU1_MODE1")
	)
	(segment
		(start 116.679472 -268.97965)
		(end 116.684298 -268.976856)
		(width 0.127)
		(layer "In4.Cu")
		(net "PUD_XTAL_CPU1_MODE1")
	)
	(segment
		(start 116.919248 -271.833086)
		(end 116.919248 -271.825466)
		(width 0.127)
		(layer "In4.Cu")
		(net "PUD_XTAL_CPU1_MODE1")
	)
	(segment
		(start 116.684298 -271.418558)
		(end 116.679472 -271.415764)
		(width 0.127)
		(layer "In4.Cu")
		(net "PUD_XTAL_CPU1_MODE1")
	)
	(segment
		(start 116.684298 -270.604742)
		(end 116.684552 -270.604488)
		(width 0.127)
		(layer "In4.Cu")
		(net "PUD_XTAL_CPU1_MODE1")
	)
	(segment
		(start 116.449348 -266.1285)
		(end 116.449602 -266.115038)
		(width 0.127)
		(layer "In4.Cu")
		(net "PUD_XTAL_CPU1_MODE1")
	)
	(segment
		(start 116.449602 -267.756132)
		(end 116.449602 -267.74648)
		(width 0.127)
		(layer "In4.Cu")
		(net "PUD_XTAL_CPU1_MODE1")
	)
	(segment
		(start 116.919248 -274.266914)
		(end 116.919502 -274.26666)
		(width 0.127)
		(layer "In4.Cu")
		(net "PUD_XTAL_CPU1_MODE1")
	)
	(arc
		(start 116.919502 -270.190214)
		(mid 116.854599 -269.95942)
		(end 116.684298 -269.790672)
		(width 0.127)
		(layer "In4.Cu")
		(net "PUD_XTAL_CPU1_MODE1")
	)
	(arc
		(start 116.919248 -266.942062)
		(mid 116.861026 -266.715507)
		(end 116.700808 -266.54506)
		(width 0.127)
		(layer "In4.Cu")
		(net "PUD_XTAL_CPU1_MODE1")
	)
	(arc
		(start 116.679726 -268.160246)
		(mid 116.51117 -267.988652)
		(end 116.449602 -267.756132)
		(width 0.127)
		(layer "In4.Cu")
		(net "PUD_XTAL_CPU1_MODE1")
	)
	(arc
		(start 116.684298 -265.721338)
		(mid 116.856448 -265.549419)
		(end 116.919502 -265.31443)
		(width 0.127)
		(layer "In4.Cu")
		(net "PUD_XTAL_CPU1_MODE1")
	)
	(arc
		(start 116.919502 -273.453352)
		(mid 116.859547 -273.223742)
		(end 116.694966 -273.052794)
		(width 0.127)
		(layer "In4.Cu")
		(net "PUD_XTAL_CPU1_MODE1")
	)
	(arc
		(start 116.684552 -268.976602)
		(mid 116.856543 -268.804772)
		(end 116.919502 -268.569948)
		(width 0.127)
		(layer "In4.Cu")
		(net "PUD_XTAL_CPU1_MODE1")
	)
	(arc
		(start 116.679472 -273.04365)
		(mid 116.449354 -272.639536)
		(end 116.679472 -272.235422)
		(width 0.127)
		(layer "In4.Cu")
		(net "PUD_XTAL_CPU1_MODE1")
	)
	(arc
		(start 116.449602 -266.115038)
		(mid 116.515736 -265.88775)
		(end 116.684298 -265.721592)
		(width 0.127)
		(layer "In4.Cu")
		(net "PUD_XTAL_CPU1_MODE1")
	)
	(arc
		(start 116.679472 -271.415764)
		(mid 116.449354 -271.01165)
		(end 116.679472 -270.607536)
		(width 0.127)
		(layer "In4.Cu")
		(net "PUD_XTAL_CPU1_MODE1")
	)
	(arc
		(start 116.919248 -271.825466)
		(mid 116.859366 -271.595921)
		(end 116.694966 -271.424908)
		(width 0.127)
		(layer "In4.Cu")
		(net "PUD_XTAL_CPU1_MODE1")
	)
	(arc
		(start 116.919502 -265.31443)
		(mid 116.859547 -265.08482)
		(end 116.694966 -264.913872)
		(width 0.127)
		(layer "In4.Cu")
		(net "PUD_XTAL_CPU1_MODE1")
	)
	(arc
		(start 116.449602 -267.74648)
		(mid 116.514845 -267.517068)
		(end 116.684298 -267.349224)
		(width 0.127)
		(layer "In4.Cu")
		(net "PUD_XTAL_CPU1_MODE1")
	)
	(arc
		(start 116.919502 -268.569948)
		(mid 116.857939 -268.337425)
		(end 116.689378 -268.165834)
		(width 0.127)
		(layer "In4.Cu")
		(net "PUD_XTAL_CPU1_MODE1")
	)
	(arc
		(start 116.684298 -272.232628)
		(mid 116.854422 -272.063817)
		(end 116.919248 -271.833086)
		(width 0.127)
		(layer "In4.Cu")
		(net "PUD_XTAL_CPU1_MODE1")
	)
	(arc
		(start 116.670836 -266.527534)
		(mid 116.508429 -266.356705)
		(end 116.449348 -266.1285)
		(width 0.127)
		(layer "In4.Cu")
		(net "PUD_XTAL_CPU1_MODE1")
	)
	(arc
		(start 116.684298 -267.349224)
		(mid 116.854422 -267.180413)
		(end 116.919248 -266.949682)
		(width 0.127)
		(layer "In4.Cu")
		(net "PUD_XTAL_CPU1_MODE1")
	)
	(arc
		(start 116.684298 -269.790672)
		(mid 116.512326 -269.61869)
		(end 116.449348 -269.383764)
		(width 0.127)
		(layer "In4.Cu")
		(net "PUD_XTAL_CPU1_MODE1")
	)
	(arc
		(start 116.679472 -264.904728)
		(mid 116.510916 -264.733134)
		(end 116.449348 -264.500614)
		(width 0.127)
		(layer "In4.Cu")
		(net "PUD_XTAL_CPU1_MODE1")
	)
	(arc
		(start 116.449348 -269.383764)
		(mid 116.510911 -269.151241)
		(end 116.679472 -268.97965)
		(width 0.127)
		(layer "In4.Cu")
		(net "PUD_XTAL_CPU1_MODE1")
	)
	(arc
		(start 116.684552 -270.604488)
		(mid 116.856543 -270.432658)
		(end 116.919502 -270.197834)
		(width 0.127)
		(layer "In4.Cu")
		(net "PUD_XTAL_CPU1_MODE1")
	)
	(segment
		(start 192.46088 -349.367348)
		(end 193.55943 -349.367348)
		(width 0.12954)
		(layer "F.Cu")
		(net "PUD_XTAL_CPU1_MODE0")
	)
	(segment
		(start 193.55943 -349.367348)
		(end 193.55943 -350.510348)
		(width 0.12954)
		(layer "F.Cu")
		(net "PUD_XTAL_CPU1_MODE0")
	)
	(segment
		(start 117.859048 -274.266914)
		(end 117.859048 -273.730974)
		(width 0.12954)
		(layer "F.Cu")
		(net "PUD_XTAL_CPU1_MODE0")
	)
	(via
		(at 117.859048 -274.266914)
		(size 0.4572)
		(drill 0.2032)
		(layers "F.Cu" "B.Cu")
		(net "PUD_XTAL_CPU1_MODE0")
	)
	(via
		(at 192.46088 -349.367348)
		(size 0.508)
		(drill 0.254)
		(layers "F.Cu" "B.Cu")
		(net "PUD_XTAL_CPU1_MODE0")
	)
	(segment
		(start 118.62054 -277.862792)
		(end 118.61165 -277.857458)
		(width 0.0889)
		(layer "In11.Cu")
		(net "PUD_XTAL_CPU1_MODE0")
	)
	(segment
		(start 119.738648 -284.85719)
		(end 119.738648 -284.837886)
		(width 0.0889)
		(layer "In11.Cu")
		(net "PUD_XTAL_CPU1_MODE0")
	)
	(segment
		(start 118.424198 -279.150318)
		(end 118.424198 -279.14981)
		(width 0.0889)
		(layer "In11.Cu")
		(net "PUD_XTAL_CPU1_MODE0")
	)
	(segment
		(start 118.424198 -280.78684)
		(end 118.424198 -280.76398)
		(width 0.0889)
		(layer "In11.Cu")
		(net "PUD_XTAL_CPU1_MODE0")
	)
	(segment
		(start 128.2446 -295.849548)
		(end 124.1298 -291.734748)
		(width 0.127)
		(layer "In11.Cu")
		(net "PUD_XTAL_CPU1_MODE0")
	)
	(segment
		(start 119.033544 -288.509964)
		(end 119.028718 -288.50717)
		(width 0.0889)
		(layer "In11.Cu")
		(net "PUD_XTAL_CPU1_MODE0")
	)
	(segment
		(start 193.12128 -348.706948)
		(end 193.12128 -338.29371)
		(width 0.127)
		(layer "In11.Cu")
		(net "PUD_XTAL_CPU1_MODE0")
	)
	(segment
		(start 119.97817 -283.629608)
		(end 119.973344 -283.626814)
		(width 0.0889)
		(layer "In11.Cu")
		(net "PUD_XTAL_CPU1_MODE0")
	)
	(segment
		(start 118.14175 -275.405088)
		(end 118.141496 -275.404834)
		(width 0.0889)
		(layer "In11.Cu")
		(net "PUD_XTAL_CPU1_MODE0")
	)
	(segment
		(start 119.028718 -287.698942)
		(end 119.033544 -287.696148)
		(width 0.0889)
		(layer "In11.Cu")
		(net "PUD_XTAL_CPU1_MODE0")
	)
	(segment
		(start 119.738648 -283.229558)
		(end 119.738648 -283.219906)
		(width 0.0889)
		(layer "In11.Cu")
		(net "PUD_XTAL_CPU1_MODE0")
	)
	(segment
		(start 159.516318 -333.162148)
		(end 128.2446 -301.89043)
		(width 0.127)
		(layer "In11.Cu")
		(net "PUD_XTAL_CPU1_MODE0")
	)
	(segment
		(start 119.97817 -285.25724)
		(end 119.973344 -285.254446)
		(width 0.0889)
		(layer "In11.Cu")
		(net "PUD_XTAL_CPU1_MODE0")
	)
	(segment
		(start 192.46088 -349.367348)
		(end 193.12128 -348.706948)
		(width 0.127)
		(layer "In11.Cu")
		(net "PUD_XTAL_CPU1_MODE0")
	)
	(segment
		(start 118.60276 -277.203154)
		(end 118.61165 -277.198074)
		(width 0.0889)
		(layer "In11.Cu")
		(net "PUD_XTAL_CPU1_MODE0")
	)
	(segment
		(start 118.61165 -276.219158)
		(end 118.611396 -276.218904)
		(width 0.0889)
		(layer "In11.Cu")
		(net "PUD_XTAL_CPU1_MODE0")
	)
	(segment
		(start 119.7102 -290.845748)
		(end 118.798594 -289.934142)
		(width 0.0889)
		(layer "In11.Cu")
		(net "PUD_XTAL_CPU1_MODE0")
	)
	(segment
		(start 121.6406 -291.734748)
		(end 120.7516 -290.845748)
		(width 0.0889)
		(layer "In11.Cu")
		(net "PUD_XTAL_CPU1_MODE0")
	)
	(segment
		(start 119.738648 -286.475424)
		(end 119.738648 -286.465772)
		(width 0.0889)
		(layer "In11.Cu")
		(net "PUD_XTAL_CPU1_MODE0")
	)
	(segment
		(start 120.208294 -285.674816)
		(end 120.208294 -285.661354)
		(width 0.0889)
		(layer "In11.Cu")
		(net "PUD_XTAL_CPU1_MODE0")
	)
	(segment
		(start 124.1298 -291.734748)
		(end 123.0122 -291.734748)
		(width 0.127)
		(layer "In11.Cu")
		(net "PUD_XTAL_CPU1_MODE0")
	)
	(segment
		(start 119.498872 -286.885126)
		(end 119.508524 -286.879538)
		(width 0.0889)
		(layer "In11.Cu")
		(net "PUD_XTAL_CPU1_MODE0")
	)
	(segment
		(start 119.033544 -287.696148)
		(end 119.044212 -287.689798)
		(width 0.0889)
		(layer "In11.Cu")
		(net "PUD_XTAL_CPU1_MODE0")
	)
	(segment
		(start 118.424198 -277.5331)
		(end 118.424198 -277.522432)
		(width 0.0889)
		(layer "In11.Cu")
		(net "PUD_XTAL_CPU1_MODE0")
	)
	(segment
		(start 119.503444 -282.812744)
		(end 119.498618 -282.80995)
		(width 0.0889)
		(layer "In11.Cu")
		(net "PUD_XTAL_CPU1_MODE0")
	)
	(segment
		(start 118.894098 -276.70887)
		(end 118.894098 -276.69871)
		(width 0.0889)
		(layer "In11.Cu")
		(net "PUD_XTAL_CPU1_MODE0")
	)
	(segment
		(start 118.623588 -281.109674)
		(end 118.611396 -281.102562)
		(width 0.0889)
		(layer "In11.Cu")
		(net "PUD_XTAL_CPU1_MODE0")
	)
	(segment
		(start 118.141496 -279.639776)
		(end 118.147592 -279.63622)
		(width 0.0889)
		(layer "In11.Cu")
		(net "PUD_XTAL_CPU1_MODE0")
	)
	(segment
		(start 117.954298 -275.08073)
		(end 117.954298 -274.907756)
		(width 0.0889)
		(layer "In11.Cu")
		(net "PUD_XTAL_CPU1_MODE0")
	)
	(segment
		(start 118.424198 -275.8948)
		(end 118.424198 -275.894292)
		(width 0.0889)
		(layer "In11.Cu")
		(net "PUD_XTAL_CPU1_MODE0")
	)
	(segment
		(start 118.798594 -289.934142)
		(end 118.798594 -289.627056)
		(width 0.0889)
		(layer "In11.Cu")
		(net "PUD_XTAL_CPU1_MODE0")
	)
	(segment
		(start 119.510302 -282.816808)
		(end 119.503444 -282.812744)
		(width 0.0889)
		(layer "In11.Cu")
		(net "PUD_XTAL_CPU1_MODE0")
	)
	(segment
		(start 119.973344 -284.44063)
		(end 119.97817 -284.437836)
		(width 0.0889)
		(layer "In11.Cu")
		(net "PUD_XTAL_CPU1_MODE0")
	)
	(segment
		(start 118.894098 -281.757374)
		(end 118.894098 -281.59202)
		(width 0.0889)
		(layer "In11.Cu")
		(net "PUD_XTAL_CPU1_MODE0")
	)
	(segment
		(start 187.989718 -333.162148)
		(end 159.516318 -333.162148)
		(width 0.127)
		(layer "In11.Cu")
		(net "PUD_XTAL_CPU1_MODE0")
	)
	(segment
		(start 117.954298 -279.964388)
		(end 117.954298 -279.955498)
		(width 0.0889)
		(layer "In11.Cu")
		(net "PUD_XTAL_CPU1_MODE0")
	)
	(segment
		(start 193.12128 -338.29371)
		(end 187.989718 -333.162148)
		(width 0.127)
		(layer "In11.Cu")
		(net "PUD_XTAL_CPU1_MODE0")
	)
	(segment
		(start 120.7516 -290.845748)
		(end 119.7102 -290.845748)
		(width 0.0889)
		(layer "In11.Cu")
		(net "PUD_XTAL_CPU1_MODE0")
	)
	(segment
		(start 117.859048 -274.812506)
		(end 117.859048 -274.266914)
		(width 0.0889)
		(layer "In11.Cu")
		(net "PUD_XTAL_CPU1_MODE0")
	)
	(segment
		(start 119.03837 -282.001722)
		(end 119.033544 -281.998928)
		(width 0.0889)
		(layer "In11.Cu")
		(net "PUD_XTAL_CPU1_MODE0")
	)
	(segment
		(start 128.2446 -301.89043)
		(end 128.2446 -295.849548)
		(width 0.127)
		(layer "In11.Cu")
		(net "PUD_XTAL_CPU1_MODE0")
	)
	(segment
		(start 117.954298 -274.907756)
		(end 117.859048 -274.812506)
		(width 0.0889)
		(layer "In11.Cu")
		(net "PUD_XTAL_CPU1_MODE0")
	)
	(segment
		(start 119.268748 -289.096958)
		(end 119.268748 -288.909506)
		(width 0.0889)
		(layer "In11.Cu")
		(net "PUD_XTAL_CPU1_MODE0")
	)
	(segment
		(start 123.0122 -291.734748)
		(end 121.6406 -291.734748)
		(width 0.0889)
		(layer "In11.Cu")
		(net "PUD_XTAL_CPU1_MODE0")
	)
	(arc
		(start 118.141496 -275.404834)
		(mid 118.004451 -275.267874)
		(end 117.954298 -275.08073)
		(width 0.0889)
		(layer "In11.Cu")
		(net "PUD_XTAL_CPU1_MODE0")
	)
	(arc
		(start 120.208294 -285.661354)
		(mid 120.146731 -285.428831)
		(end 119.97817 -285.25724)
		(width 0.0889)
		(layer "In11.Cu")
		(net "PUD_XTAL_CPU1_MODE0")
	)
	(arc
		(start 118.894098 -278.336502)
		(mid 118.820791 -278.062999)
		(end 118.62054 -277.862792)
		(width 0.0889)
		(layer "In11.Cu")
		(net "PUD_XTAL_CPU1_MODE0")
	)
	(arc
		(start 117.954298 -279.955498)
		(mid 118.006568 -279.773133)
		(end 118.141496 -279.639776)
		(width 0.0889)
		(layer "In11.Cu")
		(net "PUD_XTAL_CPU1_MODE0")
	)
	(arc
		(start 119.738648 -284.837886)
		(mid 119.803891 -284.608474)
		(end 119.973344 -284.44063)
		(width 0.0889)
		(layer "In11.Cu")
		(net "PUD_XTAL_CPU1_MODE0")
	)
	(arc
		(start 119.97817 -284.437836)
		(mid 120.208288 -284.033722)
		(end 119.97817 -283.629608)
		(width 0.0889)
		(layer "In11.Cu")
		(net "PUD_XTAL_CPU1_MODE0")
	)
	(arc
		(start 119.973344 -286.068516)
		(mid 120.142067 -285.90225)
		(end 120.208294 -285.674816)
		(width 0.0889)
		(layer "In11.Cu")
		(net "PUD_XTAL_CPU1_MODE0")
	)
	(arc
		(start 118.424198 -275.894292)
		(mid 118.348518 -275.611846)
		(end 118.14175 -275.405088)
		(width 0.0889)
		(layer "In11.Cu")
		(net "PUD_XTAL_CPU1_MODE0")
	)
	(arc
		(start 118.798594 -289.627056)
		(mid 118.891997 -289.473246)
		(end 119.033544 -289.362134)
		(width 0.0889)
		(layer "In11.Cu")
		(net "PUD_XTAL_CPU1_MODE0")
	)
	(arc
		(start 119.973344 -283.626814)
		(mid 119.803894 -283.458968)
		(end 119.738648 -283.229558)
		(width 0.0889)
		(layer "In11.Cu")
		(net "PUD_XTAL_CPU1_MODE0")
	)
	(arc
		(start 119.738648 -283.219906)
		(mid 119.677591 -282.988273)
		(end 119.510302 -282.816808)
		(width 0.0889)
		(layer "In11.Cu")
		(net "PUD_XTAL_CPU1_MODE0")
	)
	(arc
		(start 118.147592 -279.63622)
		(mid 118.350179 -279.429869)
		(end 118.424198 -279.150318)
		(width 0.0889)
		(layer "In11.Cu")
		(net "PUD_XTAL_CPU1_MODE0")
	)
	(arc
		(start 118.611396 -278.825706)
		(mid 118.81834 -278.618996)
		(end 118.894098 -278.336502)
		(width 0.0889)
		(layer "In11.Cu")
		(net "PUD_XTAL_CPU1_MODE0")
	)
	(arc
		(start 119.033544 -281.998928)
		(mid 118.931446 -281.896837)
		(end 118.894098 -281.757374)
		(width 0.0889)
		(layer "In11.Cu")
		(net "PUD_XTAL_CPU1_MODE0")
	)
	(arc
		(start 118.141496 -280.288492)
		(mid 118.004451 -280.151532)
		(end 117.954298 -279.964388)
		(width 0.0889)
		(layer "In11.Cu")
		(net "PUD_XTAL_CPU1_MODE0")
	)
	(arc
		(start 119.498618 -282.80995)
		(mid 119.330062 -282.638356)
		(end 119.268494 -282.405836)
		(width 0.0889)
		(layer "In11.Cu")
		(net "PUD_XTAL_CPU1_MODE0")
	)
	(arc
		(start 119.268494 -282.405836)
		(mid 119.206931 -282.173313)
		(end 119.03837 -282.001722)
		(width 0.0889)
		(layer "In11.Cu")
		(net "PUD_XTAL_CPU1_MODE0")
	)
	(arc
		(start 119.738648 -286.465772)
		(mid 119.803891 -286.23636)
		(end 119.973344 -286.068516)
		(width 0.0889)
		(layer "In11.Cu")
		(net "PUD_XTAL_CPU1_MODE0")
	)
	(arc
		(start 118.424198 -280.76398)
		(mid 118.344979 -280.489295)
		(end 118.141496 -280.288492)
		(width 0.0889)
		(layer "In11.Cu")
		(net "PUD_XTAL_CPU1_MODE0")
	)
	(arc
		(start 118.424198 -279.14981)
		(mid 118.474362 -278.962672)
		(end 118.611396 -278.825706)
		(width 0.0889)
		(layer "In11.Cu")
		(net "PUD_XTAL_CPU1_MODE0")
	)
	(arc
		(start 118.424198 -277.522432)
		(mid 118.471877 -277.339532)
		(end 118.60276 -277.203154)
		(width 0.0889)
		(layer "In11.Cu")
		(net "PUD_XTAL_CPU1_MODE0")
	)
	(arc
		(start 118.894098 -281.59202)
		(mid 118.821863 -281.315496)
		(end 118.623588 -281.109674)
		(width 0.0889)
		(layer "In11.Cu")
		(net "PUD_XTAL_CPU1_MODE0")
	)
	(arc
		(start 119.508524 -286.879538)
		(mid 119.67708 -286.707944)
		(end 119.738648 -286.475424)
		(width 0.0889)
		(layer "In11.Cu")
		(net "PUD_XTAL_CPU1_MODE0")
	)
	(arc
		(start 119.028718 -288.50717)
		(mid 118.7986 -288.103056)
		(end 119.028718 -287.698942)
		(width 0.0889)
		(layer "In11.Cu")
		(net "PUD_XTAL_CPU1_MODE0")
	)
	(arc
		(start 119.973344 -285.254446)
		(mid 119.803894 -285.0866)
		(end 119.738648 -284.85719)
		(width 0.0889)
		(layer "In11.Cu")
		(net "PUD_XTAL_CPU1_MODE0")
	)
	(arc
		(start 119.268748 -288.909506)
		(mid 119.203845 -288.678712)
		(end 119.033544 -288.509964)
		(width 0.0889)
		(layer "In11.Cu")
		(net "PUD_XTAL_CPU1_MODE0")
	)
	(arc
		(start 118.611396 -281.102562)
		(mid 118.476463 -280.969208)
		(end 118.424198 -280.78684)
		(width 0.0889)
		(layer "In11.Cu")
		(net "PUD_XTAL_CPU1_MODE0")
	)
	(arc
		(start 119.044212 -287.689798)
		(mid 119.208754 -287.518828)
		(end 119.268748 -287.28924)
		(width 0.0889)
		(layer "In11.Cu")
		(net "PUD_XTAL_CPU1_MODE0")
	)
	(arc
		(start 118.894098 -276.69871)
		(mid 118.815987 -276.421761)
		(end 118.61165 -276.219158)
		(width 0.0889)
		(layer "In11.Cu")
		(net "PUD_XTAL_CPU1_MODE0")
	)
	(arc
		(start 118.61165 -277.857458)
		(mid 118.47444 -277.720398)
		(end 118.424198 -277.5331)
		(width 0.0889)
		(layer "In11.Cu")
		(net "PUD_XTAL_CPU1_MODE0")
	)
	(arc
		(start 119.268748 -287.28924)
		(mid 119.330311 -287.056717)
		(end 119.498872 -286.885126)
		(width 0.0889)
		(layer "In11.Cu")
		(net "PUD_XTAL_CPU1_MODE0")
	)
	(arc
		(start 119.033544 -289.362134)
		(mid 119.175258 -289.250937)
		(end 119.268748 -289.096958)
		(width 0.0889)
		(layer "In11.Cu")
		(net "PUD_XTAL_CPU1_MODE0")
	)
	(arc
		(start 118.611396 -276.218904)
		(mid 118.474351 -276.081944)
		(end 118.424198 -275.8948)
		(width 0.0889)
		(layer "In11.Cu")
		(net "PUD_XTAL_CPU1_MODE0")
	)
	(arc
		(start 118.61165 -277.198074)
		(mid 118.81841 -276.991311)
		(end 118.894098 -276.70887)
		(width 0.0889)
		(layer "In11.Cu")
		(net "PUD_XTAL_CPU1_MODE0")
	)
	(segment
		(start 364.859062 -274.26666)
		(end 364.859316 -274.266914)
		(width 0.12954)
		(layer "F.Cu")
		(net "PUD_XTAL_CPU0_MODE1")
	)
	(segment
		(start 364.859316 -273.730974)
		(end 364.859062 -273.731228)
		(width 0.12954)
		(layer "F.Cu")
		(net "PUD_XTAL_CPU0_MODE1")
	)
	(segment
		(start 364.859062 -273.731228)
		(end 364.859062 -274.26666)
		(width 0.12954)
		(layer "F.Cu")
		(net "PUD_XTAL_CPU0_MODE1")
	)
	(via
		(at 363.449616 -263.686544)
		(size 0.4572)
		(drill 0.2032)
		(layers "F.Cu" "B.Cu")
		(net "PUD_XTAL_CPU0_MODE1")
	)
	(via
		(at 364.859316 -274.266914)
		(size 0.4572)
		(drill 0.2032)
		(layers "F.Cu" "B.Cu")
		(net "PUD_XTAL_CPU0_MODE1")
	)
	(via
		(at 390.751822 -258.132834)
		(size 0.6604)
		(drill 0.3302)
		(layers "F.Cu" "B.Cu")
		(net "PUD_XTAL_CPU0_MODE1")
	)
	(segment
		(start 402.916644 -237.77067)
		(end 406.091898 -237.77067)
		(width 0.12954)
		(layer "B.Cu")
		(net "PUD_XTAL_CPU0_MODE1")
	)
	(segment
		(start 363.449616 -263.686544)
		(end 363.920532 -263.686544)
		(width 0.0889)
		(layer "B.Cu")
		(net "PUD_XTAL_CPU0_MODE1")
	)
	(segment
		(start 367.174018 -263.80567)
		(end 367.290858 -263.68883)
		(width 0.0889)
		(layer "B.Cu")
		(net "PUD_XTAL_CPU0_MODE1")
	)
	(segment
		(start 390.751822 -258.132834)
		(end 391.152126 -257.73253)
		(width 0.12954)
		(layer "B.Cu")
		(net "PUD_XTAL_CPU0_MODE1")
	)
	(segment
		(start 368.230658 -263.68883)
		(end 368.644678 -263.27481)
		(width 0.0889)
		(layer "B.Cu")
		(net "PUD_XTAL_CPU0_MODE1")
	)
	(segment
		(start 372.175532 -261.560564)
		(end 372.190264 -261.5692)
		(width 0.0889)
		(layer "B.Cu")
		(net "PUD_XTAL_CPU0_MODE1")
	)
	(segment
		(start 406.909524 -236.953044)
		(end 406.909524 -198.372476)
		(width 0.12954)
		(layer "B.Cu")
		(net "PUD_XTAL_CPU0_MODE1")
	)
	(segment
		(start 368.644678 -262.90143)
		(end 369.471702 -262.074406)
		(width 0.0889)
		(layer "B.Cu")
		(net "PUD_XTAL_CPU0_MODE1")
	)
	(segment
		(start 404.09241 -194.47002)
		(end 404.09241 -193.45148)
		(width 0.12954)
		(layer "B.Cu")
		(net "PUD_XTAL_CPU0_MODE1")
	)
	(segment
		(start 384.487928 -260.780022)
		(end 384.73634 -260.53161)
		(width 0.12954)
		(layer "B.Cu")
		(net "PUD_XTAL_CPU0_MODE1")
	)
	(segment
		(start 391.152126 -257.73253)
		(end 393.513818 -257.73253)
		(width 0.12954)
		(layer "B.Cu")
		(net "PUD_XTAL_CPU0_MODE1")
	)
	(segment
		(start 388.353046 -260.53161)
		(end 390.751822 -258.132834)
		(width 0.12954)
		(layer "B.Cu")
		(net "PUD_XTAL_CPU0_MODE1")
	)
	(segment
		(start 398.624298 -252.62205)
		(end 398.624298 -242.063016)
		(width 0.12954)
		(layer "B.Cu")
		(net "PUD_XTAL_CPU0_MODE1")
	)
	(segment
		(start 404.160482 -193.45148)
		(end 404.09241 -193.45148)
		(width 0.12954)
		(layer "B.Cu")
		(net "PUD_XTAL_CPU0_MODE1")
	)
	(segment
		(start 377.814332 -261.560564)
		(end 377.829064 -261.5692)
		(width 0.0889)
		(layer "B.Cu")
		(net "PUD_XTAL_CPU0_MODE1")
	)
	(segment
		(start 374.994932 -261.560564)
		(end 375.009664 -261.5692)
		(width 0.0889)
		(layer "B.Cu")
		(net "PUD_XTAL_CPU0_MODE1")
	)
	(segment
		(start 406.909524 -198.372476)
		(end 406.244298 -197.70725)
		(width 0.12954)
		(layer "B.Cu")
		(net "PUD_XTAL_CPU0_MODE1")
	)
	(segment
		(start 384.232658 -261.197598)
		(end 384.232658 -261.035292)
		(width 0.0889)
		(layer "B.Cu")
		(net "PUD_XTAL_CPU0_MODE1")
	)
	(segment
		(start 363.920532 -263.686544)
		(end 364.039658 -263.80567)
		(width 0.0889)
		(layer "B.Cu")
		(net "PUD_XTAL_CPU0_MODE1")
	)
	(segment
		(start 368.644678 -263.27481)
		(end 368.644678 -262.90143)
		(width 0.0889)
		(layer "B.Cu")
		(net "PUD_XTAL_CPU0_MODE1")
	)
	(segment
		(start 375.934732 -261.560564)
		(end 375.949464 -261.5692)
		(width 0.0889)
		(layer "B.Cu")
		(net "PUD_XTAL_CPU0_MODE1")
	)
	(segment
		(start 384.73634 -260.53161)
		(end 388.353046 -260.53161)
		(width 0.12954)
		(layer "B.Cu")
		(net "PUD_XTAL_CPU0_MODE1")
	)
	(segment
		(start 379.693932 -261.560564)
		(end 379.708664 -261.5692)
		(width 0.0889)
		(layer "B.Cu")
		(net "PUD_XTAL_CPU0_MODE1")
	)
	(segment
		(start 406.244298 -197.70725)
		(end 406.244298 -195.535296)
		(width 0.12954)
		(layer "B.Cu")
		(net "PUD_XTAL_CPU0_MODE1")
	)
	(segment
		(start 370.295932 -261.560564)
		(end 370.310664 -261.5692)
		(width 0.0889)
		(layer "B.Cu")
		(net "PUD_XTAL_CPU0_MODE1")
	)
	(segment
		(start 398.624298 -242.063016)
		(end 402.916644 -237.77067)
		(width 0.12954)
		(layer "B.Cu")
		(net "PUD_XTAL_CPU0_MODE1")
	)
	(segment
		(start 383.920238 -261.510018)
		(end 384.232658 -261.197598)
		(width 0.0889)
		(layer "B.Cu")
		(net "PUD_XTAL_CPU0_MODE1")
	)
	(segment
		(start 378.754132 -261.560564)
		(end 378.768864 -261.5692)
		(width 0.0889)
		(layer "B.Cu")
		(net "PUD_XTAL_CPU0_MODE1")
	)
	(segment
		(start 406.244298 -195.535296)
		(end 404.160482 -193.45148)
		(width 0.12954)
		(layer "B.Cu")
		(net "PUD_XTAL_CPU0_MODE1")
	)
	(segment
		(start 406.091898 -237.77067)
		(end 406.909524 -236.953044)
		(width 0.12954)
		(layer "B.Cu")
		(net "PUD_XTAL_CPU0_MODE1")
	)
	(segment
		(start 367.290858 -263.68883)
		(end 368.230658 -263.68883)
		(width 0.0889)
		(layer "B.Cu")
		(net "PUD_XTAL_CPU0_MODE1")
	)
	(segment
		(start 393.513818 -257.73253)
		(end 398.624298 -252.62205)
		(width 0.12954)
		(layer "B.Cu")
		(net "PUD_XTAL_CPU0_MODE1")
	)
	(segment
		(start 364.039658 -263.80567)
		(end 367.174018 -263.80567)
		(width 0.0889)
		(layer "B.Cu")
		(net "PUD_XTAL_CPU0_MODE1")
	)
	(segment
		(start 373.115332 -261.560564)
		(end 373.130064 -261.5692)
		(width 0.0889)
		(layer "B.Cu")
		(net "PUD_XTAL_CPU0_MODE1")
	)
	(segment
		(start 384.232658 -261.035292)
		(end 384.487928 -260.780022)
		(width 0.0889)
		(layer "B.Cu")
		(net "PUD_XTAL_CPU0_MODE1")
	)
	(segment
		(start 382.513332 -261.560564)
		(end 382.528064 -261.5692)
		(width 0.0889)
		(layer "B.Cu")
		(net "PUD_XTAL_CPU0_MODE1")
	)
	(segment
		(start 369.471702 -261.817866)
		(end 369.631214 -261.658354)
		(width 0.0889)
		(layer "B.Cu")
		(net "PUD_XTAL_CPU0_MODE1")
	)
	(segment
		(start 376.874532 -261.560564)
		(end 376.889264 -261.5692)
		(width 0.0889)
		(layer "B.Cu")
		(net "PUD_XTAL_CPU0_MODE1")
	)
	(segment
		(start 381.573532 -261.560564)
		(end 381.588264 -261.5692)
		(width 0.0889)
		(layer "B.Cu")
		(net "PUD_XTAL_CPU0_MODE1")
	)
	(segment
		(start 369.471702 -262.074406)
		(end 369.471702 -261.817866)
		(width 0.0889)
		(layer "B.Cu")
		(net "PUD_XTAL_CPU0_MODE1")
	)
	(arc
		(start 373.130064 -261.5692)
		(mid 373.317262 -261.619343)
		(end 373.50446 -261.5692)
		(width 0.0889)
		(layer "B.Cu")
		(net "PUD_XTAL_CPU0_MODE1")
	)
	(arc
		(start 371.250464 -261.5692)
		(mid 371.437662 -261.619343)
		(end 371.62486 -261.5692)
		(width 0.0889)
		(layer "B.Cu")
		(net "PUD_XTAL_CPU0_MODE1")
	)
	(arc
		(start 381.588264 -261.5692)
		(mid 381.775462 -261.619343)
		(end 381.96266 -261.5692)
		(width 0.0889)
		(layer "B.Cu")
		(net "PUD_XTAL_CPU0_MODE1")
	)
	(arc
		(start 370.68506 -261.5692)
		(mid 370.967762 -261.493424)
		(end 371.250464 -261.5692)
		(width 0.0889)
		(layer "B.Cu")
		(net "PUD_XTAL_CPU0_MODE1")
	)
	(arc
		(start 382.528064 -261.5692)
		(mid 382.715262 -261.619343)
		(end 382.90246 -261.5692)
		(width 0.0889)
		(layer "B.Cu")
		(net "PUD_XTAL_CPU0_MODE1")
	)
	(arc
		(start 378.768864 -261.5692)
		(mid 378.956062 -261.619343)
		(end 379.14326 -261.5692)
		(width 0.0889)
		(layer "B.Cu")
		(net "PUD_XTAL_CPU0_MODE1")
	)
	(arc
		(start 379.708664 -261.5692)
		(mid 379.895862 -261.619343)
		(end 380.08306 -261.5692)
		(width 0.0889)
		(layer "B.Cu")
		(net "PUD_XTAL_CPU0_MODE1")
	)
	(arc
		(start 380.648464 -261.5692)
		(mid 380.835662 -261.619343)
		(end 381.02286 -261.5692)
		(width 0.0889)
		(layer "B.Cu")
		(net "PUD_XTAL_CPU0_MODE1")
	)
	(arc
		(start 382.90246 -261.5692)
		(mid 383.185162 -261.493424)
		(end 383.467864 -261.5692)
		(width 0.0889)
		(layer "B.Cu")
		(net "PUD_XTAL_CPU0_MODE1")
	)
	(arc
		(start 383.84226 -261.5692)
		(mid 383.88319 -261.542167)
		(end 383.920238 -261.510018)
		(width 0.0889)
		(layer "B.Cu")
		(net "PUD_XTAL_CPU0_MODE1")
	)
	(arc
		(start 370.310664 -261.5692)
		(mid 370.497862 -261.619343)
		(end 370.68506 -261.5692)
		(width 0.0889)
		(layer "B.Cu")
		(net "PUD_XTAL_CPU0_MODE1")
	)
	(arc
		(start 378.20346 -261.5692)
		(mid 378.477659 -261.493365)
		(end 378.754132 -261.560564)
		(width 0.0889)
		(layer "B.Cu")
		(net "PUD_XTAL_CPU0_MODE1")
	)
	(arc
		(start 372.190264 -261.5692)
		(mid 372.377462 -261.619343)
		(end 372.56466 -261.5692)
		(width 0.0889)
		(layer "B.Cu")
		(net "PUD_XTAL_CPU0_MODE1")
	)
	(arc
		(start 383.467864 -261.5692)
		(mid 383.655062 -261.619343)
		(end 383.84226 -261.5692)
		(width 0.0889)
		(layer "B.Cu")
		(net "PUD_XTAL_CPU0_MODE1")
	)
	(arc
		(start 374.069864 -261.5692)
		(mid 374.257062 -261.619343)
		(end 374.44426 -261.5692)
		(width 0.0889)
		(layer "B.Cu")
		(net "PUD_XTAL_CPU0_MODE1")
	)
	(arc
		(start 375.38406 -261.5692)
		(mid 375.658259 -261.493365)
		(end 375.934732 -261.560564)
		(width 0.0889)
		(layer "B.Cu")
		(net "PUD_XTAL_CPU0_MODE1")
	)
	(arc
		(start 371.62486 -261.5692)
		(mid 371.899059 -261.493365)
		(end 372.175532 -261.560564)
		(width 0.0889)
		(layer "B.Cu")
		(net "PUD_XTAL_CPU0_MODE1")
	)
	(arc
		(start 377.26366 -261.5692)
		(mid 377.537859 -261.493365)
		(end 377.814332 -261.560564)
		(width 0.0889)
		(layer "B.Cu")
		(net "PUD_XTAL_CPU0_MODE1")
	)
	(arc
		(start 381.96266 -261.5692)
		(mid 382.236859 -261.493365)
		(end 382.513332 -261.560564)
		(width 0.0889)
		(layer "B.Cu")
		(net "PUD_XTAL_CPU0_MODE1")
	)
	(arc
		(start 377.829064 -261.5692)
		(mid 378.016262 -261.619343)
		(end 378.20346 -261.5692)
		(width 0.0889)
		(layer "B.Cu")
		(net "PUD_XTAL_CPU0_MODE1")
	)
	(arc
		(start 375.949464 -261.5692)
		(mid 376.136662 -261.619343)
		(end 376.32386 -261.5692)
		(width 0.0889)
		(layer "B.Cu")
		(net "PUD_XTAL_CPU0_MODE1")
	)
	(arc
		(start 372.56466 -261.5692)
		(mid 372.838859 -261.493365)
		(end 373.115332 -261.560564)
		(width 0.0889)
		(layer "B.Cu")
		(net "PUD_XTAL_CPU0_MODE1")
	)
	(arc
		(start 380.08306 -261.5692)
		(mid 380.365762 -261.493424)
		(end 380.648464 -261.5692)
		(width 0.0889)
		(layer "B.Cu")
		(net "PUD_XTAL_CPU0_MODE1")
	)
	(arc
		(start 381.02286 -261.5692)
		(mid 381.297059 -261.493365)
		(end 381.573532 -261.560564)
		(width 0.0889)
		(layer "B.Cu")
		(net "PUD_XTAL_CPU0_MODE1")
	)
	(arc
		(start 374.44426 -261.5692)
		(mid 374.718459 -261.493365)
		(end 374.994932 -261.560564)
		(width 0.0889)
		(layer "B.Cu")
		(net "PUD_XTAL_CPU0_MODE1")
	)
	(arc
		(start 373.50446 -261.5692)
		(mid 373.787162 -261.493424)
		(end 374.069864 -261.5692)
		(width 0.0889)
		(layer "B.Cu")
		(net "PUD_XTAL_CPU0_MODE1")
	)
	(arc
		(start 379.14326 -261.5692)
		(mid 379.417459 -261.493365)
		(end 379.693932 -261.560564)
		(width 0.0889)
		(layer "B.Cu")
		(net "PUD_XTAL_CPU0_MODE1")
	)
	(arc
		(start 376.32386 -261.5692)
		(mid 376.598059 -261.493365)
		(end 376.874532 -261.560564)
		(width 0.0889)
		(layer "B.Cu")
		(net "PUD_XTAL_CPU0_MODE1")
	)
	(arc
		(start 369.631214 -261.658354)
		(mid 369.947378 -261.499545)
		(end 370.295932 -261.560564)
		(width 0.0889)
		(layer "B.Cu")
		(net "PUD_XTAL_CPU0_MODE1")
	)
	(arc
		(start 376.889264 -261.5692)
		(mid 377.076462 -261.619343)
		(end 377.26366 -261.5692)
		(width 0.0889)
		(layer "B.Cu")
		(net "PUD_XTAL_CPU0_MODE1")
	)
	(arc
		(start 375.009664 -261.5692)
		(mid 375.196862 -261.619343)
		(end 375.38406 -261.5692)
		(width 0.0889)
		(layer "B.Cu")
		(net "PUD_XTAL_CPU0_MODE1")
	)
	(segment
		(start 364.624366 -271.418558)
		(end 364.61954 -271.415764)
		(width 0.1016)
		(layer "In4.Cu")
		(net "PUD_XTAL_CPU0_MODE1")
	)
	(segment
		(start 364.61954 -268.97965)
		(end 364.624366 -268.976856)
		(width 0.1016)
		(layer "In4.Cu")
		(net "PUD_XTAL_CPU0_MODE1")
	)
	(segment
		(start 364.629446 -268.165834)
		(end 364.619794 -268.160246)
		(width 0.1016)
		(layer "In4.Cu")
		(net "PUD_XTAL_CPU0_MODE1")
	)
	(segment
		(start 364.624366 -265.721592)
		(end 364.624366 -265.721338)
		(width 0.1016)
		(layer "In4.Cu")
		(net "PUD_XTAL_CPU0_MODE1")
	)
	(segment
		(start 364.38967 -267.756132)
		(end 364.38967 -267.74648)
		(width 0.1016)
		(layer "In4.Cu")
		(net "PUD_XTAL_CPU0_MODE1")
	)
	(segment
		(start 364.389416 -264.500614)
		(end 364.389416 -264.214102)
		(width 0.1016)
		(layer "In4.Cu")
		(net "PUD_XTAL_CPU0_MODE1")
	)
	(segment
		(start 364.61954 -272.235422)
		(end 364.624366 -272.232628)
		(width 0.1016)
		(layer "In4.Cu")
		(net "PUD_XTAL_CPU0_MODE1")
	)
	(segment
		(start 364.640876 -266.54506)
		(end 364.624366 -266.535408)
		(width 0.1016)
		(layer "In4.Cu")
		(net "PUD_XTAL_CPU0_MODE1")
	)
	(segment
		(start 364.624366 -270.604742)
		(end 364.62462 -270.604488)
		(width 0.1016)
		(layer "In4.Cu")
		(net "PUD_XTAL_CPU0_MODE1")
	)
	(segment
		(start 364.61954 -270.607536)
		(end 364.624366 -270.604742)
		(width 0.1016)
		(layer "In4.Cu")
		(net "PUD_XTAL_CPU0_MODE1")
	)
	(segment
		(start 364.389416 -266.1285)
		(end 364.38967 -266.115038)
		(width 0.1016)
		(layer "In4.Cu")
		(net "PUD_XTAL_CPU0_MODE1")
	)
	(segment
		(start 364.389416 -264.214102)
		(end 363.861858 -263.686544)
		(width 0.1016)
		(layer "In4.Cu")
		(net "PUD_XTAL_CPU0_MODE1")
	)
	(segment
		(start 364.85957 -270.197834)
		(end 364.85957 -270.190214)
		(width 0.1016)
		(layer "In4.Cu")
		(net "PUD_XTAL_CPU0_MODE1")
	)
	(segment
		(start 363.861858 -263.686544)
		(end 363.449616 -263.686544)
		(width 0.1016)
		(layer "In4.Cu")
		(net "PUD_XTAL_CPU0_MODE1")
	)
	(segment
		(start 364.624366 -266.535408)
		(end 364.610904 -266.527534)
		(width 0.1016)
		(layer "In4.Cu")
		(net "PUD_XTAL_CPU0_MODE1")
	)
	(segment
		(start 364.635034 -264.913872)
		(end 364.624366 -264.907522)
		(width 0.1016)
		(layer "In4.Cu")
		(net "PUD_XTAL_CPU0_MODE1")
	)
	(segment
		(start 364.85957 -274.26666)
		(end 364.85957 -273.453352)
		(width 0.1016)
		(layer "In4.Cu")
		(net "PUD_XTAL_CPU0_MODE1")
	)
	(segment
		(start 364.859316 -271.833086)
		(end 364.859316 -271.825466)
		(width 0.1016)
		(layer "In4.Cu")
		(net "PUD_XTAL_CPU0_MODE1")
	)
	(segment
		(start 364.624366 -268.976856)
		(end 364.62462 -268.976602)
		(width 0.1016)
		(layer "In4.Cu")
		(net "PUD_XTAL_CPU0_MODE1")
	)
	(segment
		(start 364.635034 -271.424908)
		(end 364.624366 -271.418558)
		(width 0.1016)
		(layer "In4.Cu")
		(net "PUD_XTAL_CPU0_MODE1")
	)
	(segment
		(start 364.624366 -264.907522)
		(end 364.61954 -264.904728)
		(width 0.1016)
		(layer "In4.Cu")
		(net "PUD_XTAL_CPU0_MODE1")
	)
	(segment
		(start 364.624366 -273.046444)
		(end 364.61954 -273.04365)
		(width 0.1016)
		(layer "In4.Cu")
		(net "PUD_XTAL_CPU0_MODE1")
	)
	(segment
		(start 364.859316 -274.266914)
		(end 364.85957 -274.26666)
		(width 0.1016)
		(layer "In4.Cu")
		(net "PUD_XTAL_CPU0_MODE1")
	)
	(segment
		(start 364.859316 -266.949682)
		(end 364.859316 -266.942062)
		(width 0.1016)
		(layer "In4.Cu")
		(net "PUD_XTAL_CPU0_MODE1")
	)
	(segment
		(start 364.635034 -273.052794)
		(end 364.624366 -273.046444)
		(width 0.1016)
		(layer "In4.Cu")
		(net "PUD_XTAL_CPU0_MODE1")
	)
	(arc
		(start 364.389416 -269.383764)
		(mid 364.450979 -269.151241)
		(end 364.61954 -268.97965)
		(width 0.1016)
		(layer "In4.Cu")
		(net "PUD_XTAL_CPU0_MODE1")
	)
	(arc
		(start 364.85957 -270.190214)
		(mid 364.794667 -269.95942)
		(end 364.624366 -269.790672)
		(width 0.1016)
		(layer "In4.Cu")
		(net "PUD_XTAL_CPU0_MODE1")
	)
	(arc
		(start 364.624366 -269.790672)
		(mid 364.452394 -269.61869)
		(end 364.389416 -269.383764)
		(width 0.1016)
		(layer "In4.Cu")
		(net "PUD_XTAL_CPU0_MODE1")
	)
	(arc
		(start 364.624366 -272.232628)
		(mid 364.79449 -272.063817)
		(end 364.859316 -271.833086)
		(width 0.1016)
		(layer "In4.Cu")
		(net "PUD_XTAL_CPU0_MODE1")
	)
	(arc
		(start 364.61954 -264.904728)
		(mid 364.450984 -264.733134)
		(end 364.389416 -264.500614)
		(width 0.1016)
		(layer "In4.Cu")
		(net "PUD_XTAL_CPU0_MODE1")
	)
	(arc
		(start 364.38967 -266.115038)
		(mid 364.455804 -265.88775)
		(end 364.624366 -265.721592)
		(width 0.1016)
		(layer "In4.Cu")
		(net "PUD_XTAL_CPU0_MODE1")
	)
	(arc
		(start 364.859316 -266.942062)
		(mid 364.801094 -266.715507)
		(end 364.640876 -266.54506)
		(width 0.1016)
		(layer "In4.Cu")
		(net "PUD_XTAL_CPU0_MODE1")
	)
	(arc
		(start 364.38967 -267.74648)
		(mid 364.454913 -267.517068)
		(end 364.624366 -267.349224)
		(width 0.1016)
		(layer "In4.Cu")
		(net "PUD_XTAL_CPU0_MODE1")
	)
	(arc
		(start 364.624366 -265.721338)
		(mid 364.796516 -265.549419)
		(end 364.85957 -265.31443)
		(width 0.1016)
		(layer "In4.Cu")
		(net "PUD_XTAL_CPU0_MODE1")
	)
	(arc
		(start 364.624366 -267.349224)
		(mid 364.79449 -267.180413)
		(end 364.859316 -266.949682)
		(width 0.1016)
		(layer "In4.Cu")
		(net "PUD_XTAL_CPU0_MODE1")
	)
	(arc
		(start 364.61954 -271.415764)
		(mid 364.389422 -271.01165)
		(end 364.61954 -270.607536)
		(width 0.1016)
		(layer "In4.Cu")
		(net "PUD_XTAL_CPU0_MODE1")
	)
	(arc
		(start 364.61954 -273.04365)
		(mid 364.389422 -272.639536)
		(end 364.61954 -272.235422)
		(width 0.1016)
		(layer "In4.Cu")
		(net "PUD_XTAL_CPU0_MODE1")
	)
	(arc
		(start 364.85957 -273.453352)
		(mid 364.799615 -273.223742)
		(end 364.635034 -273.052794)
		(width 0.1016)
		(layer "In4.Cu")
		(net "PUD_XTAL_CPU0_MODE1")
	)
	(arc
		(start 364.610904 -266.527534)
		(mid 364.448497 -266.356705)
		(end 364.389416 -266.1285)
		(width 0.1016)
		(layer "In4.Cu")
		(net "PUD_XTAL_CPU0_MODE1")
	)
	(arc
		(start 364.62462 -268.976602)
		(mid 364.796611 -268.804772)
		(end 364.85957 -268.569948)
		(width 0.1016)
		(layer "In4.Cu")
		(net "PUD_XTAL_CPU0_MODE1")
	)
	(arc
		(start 364.619794 -268.160246)
		(mid 364.451238 -267.988652)
		(end 364.38967 -267.756132)
		(width 0.1016)
		(layer "In4.Cu")
		(net "PUD_XTAL_CPU0_MODE1")
	)
	(arc
		(start 364.85957 -265.31443)
		(mid 364.799615 -265.08482)
		(end 364.635034 -264.913872)
		(width 0.1016)
		(layer "In4.Cu")
		(net "PUD_XTAL_CPU0_MODE1")
	)
	(arc
		(start 364.62462 -270.604488)
		(mid 364.796611 -270.432658)
		(end 364.85957 -270.197834)
		(width 0.1016)
		(layer "In4.Cu")
		(net "PUD_XTAL_CPU0_MODE1")
	)
	(arc
		(start 364.85957 -268.569948)
		(mid 364.798007 -268.337425)
		(end 364.629446 -268.165834)
		(width 0.1016)
		(layer "In4.Cu")
		(net "PUD_XTAL_CPU0_MODE1")
	)
	(arc
		(start 364.859316 -271.825466)
		(mid 364.799434 -271.595921)
		(end 364.635034 -271.424908)
		(width 0.1016)
		(layer "In4.Cu")
		(net "PUD_XTAL_CPU0_MODE1")
	)
	(segment
		(start 401.068794 -359.579926)
		(end 400.65071 -359.99801)
		(width 0.12954)
		(layer "F.Cu")
		(net "PUD_XTAL_CPU0_MODE0")
	)
	(segment
		(start 399.239232 -361.409488)
		(end 383.64922 -361.409488)
		(width 0.12954)
		(layer "F.Cu")
		(net "PUD_XTAL_CPU0_MODE0")
	)
	(segment
		(start 365.799116 -274.266914)
		(end 365.799116 -273.730974)
		(width 0.12954)
		(layer "F.Cu")
		(net "PUD_XTAL_CPU0_MODE0")
	)
	(segment
		(start 383.351278 -361.70743)
		(end 382.934718 -361.70743)
		(width 0.12954)
		(layer "F.Cu")
		(net "PUD_XTAL_CPU0_MODE0")
	)
	(segment
		(start 405.724614 -359.579926)
		(end 405.724614 -358.436926)
		(width 0.12954)
		(layer "F.Cu")
		(net "PUD_XTAL_CPU0_MODE0")
	)
	(segment
		(start 400.65071 -359.99801)
		(end 399.239232 -361.409488)
		(width 0.12954)
		(layer "F.Cu")
		(net "PUD_XTAL_CPU0_MODE0")
	)
	(segment
		(start 405.724614 -359.579926)
		(end 401.068794 -359.579926)
		(width 0.12954)
		(layer "F.Cu")
		(net "PUD_XTAL_CPU0_MODE0")
	)
	(segment
		(start 383.64922 -361.409488)
		(end 383.351278 -361.70743)
		(width 0.12954)
		(layer "F.Cu")
		(net "PUD_XTAL_CPU0_MODE0")
	)
	(via
		(at 400.65071 -359.99801)
		(size 0.762)
		(drill 0.381)
		(layers "F.Cu" "B.Cu")
		(net "PUD_XTAL_CPU0_MODE0")
	)
	(via
		(at 365.799116 -274.266914)
		(size 0.4572)
		(drill 0.2032)
		(layers "F.Cu" "B.Cu")
		(net "PUD_XTAL_CPU0_MODE0")
	)
	(via
		(at 382.934718 -361.70743)
		(size 0.508)
		(drill 0.254)
		(layers "F.Cu" "B.Cu")
		(net "PUD_XTAL_CPU0_MODE0")
	)
	(segment
		(start 366.364266 -275.8948)
		(end 366.364266 -275.894292)
		(width 0.0889)
		(layer "In11.Cu")
		(net "PUD_XTAL_CPU0_MODE0")
	)
	(segment
		(start 367.43894 -286.885126)
		(end 367.448592 -286.879538)
		(width 0.0889)
		(layer "In11.Cu")
		(net "PUD_XTAL_CPU0_MODE0")
	)
	(segment
		(start 366.968786 -287.698942)
		(end 366.973612 -287.696148)
		(width 0.0889)
		(layer "In11.Cu")
		(net "PUD_XTAL_CPU0_MODE0")
	)
	(segment
		(start 367.443512 -282.812744)
		(end 367.438686 -282.80995)
		(width 0.0889)
		(layer "In11.Cu")
		(net "PUD_XTAL_CPU0_MODE0")
	)
	(segment
		(start 367.918238 -285.25724)
		(end 367.913412 -285.254446)
		(width 0.0889)
		(layer "In11.Cu")
		(net "PUD_XTAL_CPU0_MODE0")
	)
	(segment
		(start 367.678716 -284.85719)
		(end 367.678716 -284.837886)
		(width 0.0889)
		(layer "In11.Cu")
		(net "PUD_XTAL_CPU0_MODE0")
	)
	(segment
		(start 366.560608 -277.862792)
		(end 366.551718 -277.857458)
		(width 0.0889)
		(layer "In11.Cu")
		(net "PUD_XTAL_CPU0_MODE0")
	)
	(segment
		(start 384.786632 -361.49661)
		(end 393.475718 -352.807524)
		(width 0.127)
		(layer "In11.Cu")
		(net "PUD_XTAL_CPU0_MODE0")
	)
	(segment
		(start 370.3828 -291.699696)
		(end 369.661948 -291.699696)
		(width 0.0889)
		(layer "In11.Cu")
		(net "PUD_XTAL_CPU0_MODE0")
	)
	(segment
		(start 383.145538 -361.49661)
		(end 384.786632 -361.49661)
		(width 0.127)
		(layer "In11.Cu")
		(net "PUD_XTAL_CPU0_MODE0")
	)
	(segment
		(start 368.148362 -285.674816)
		(end 368.148362 -285.661354)
		(width 0.0889)
		(layer "In11.Cu")
		(net "PUD_XTAL_CPU0_MODE0")
	)
	(segment
		(start 365.894366 -275.08073)
		(end 365.894366 -274.362164)
		(width 0.0889)
		(layer "In11.Cu")
		(net "PUD_XTAL_CPU0_MODE0")
	)
	(segment
		(start 369.661948 -291.699696)
		(end 368.7318 -290.769548)
		(width 0.0889)
		(layer "In11.Cu")
		(net "PUD_XTAL_CPU0_MODE0")
	)
	(segment
		(start 366.973612 -287.696148)
		(end 366.98428 -287.689798)
		(width 0.0889)
		(layer "In11.Cu")
		(net "PUD_XTAL_CPU0_MODE0")
	)
	(segment
		(start 368.7318 -290.769548)
		(end 367.5126 -290.769548)
		(width 0.0889)
		(layer "In11.Cu")
		(net "PUD_XTAL_CPU0_MODE0")
	)
	(segment
		(start 372.11889 -291.699696)
		(end 370.3828 -291.699696)
		(width 0.127)
		(layer "In11.Cu")
		(net "PUD_XTAL_CPU0_MODE0")
	)
	(segment
		(start 365.894366 -279.964388)
		(end 365.894366 -279.955498)
		(width 0.0889)
		(layer "In11.Cu")
		(net "PUD_XTAL_CPU0_MODE0")
	)
	(segment
		(start 375.802652 -298.787058)
		(end 375.802652 -295.383458)
		(width 0.127)
		(layer "In11.Cu")
		(net "PUD_XTAL_CPU0_MODE0")
	)
	(segment
		(start 366.738662 -289.99561)
		(end 366.738662 -289.627056)
		(width 0.0889)
		(layer "In11.Cu")
		(net "PUD_XTAL_CPU0_MODE0")
	)
	(segment
		(start 366.542828 -277.203154)
		(end 366.551718 -277.198074)
		(width 0.0889)
		(layer "In11.Cu")
		(net "PUD_XTAL_CPU0_MODE0")
	)
	(segment
		(start 393.475718 -352.807524)
		(end 393.475718 -316.460124)
		(width 0.127)
		(layer "In11.Cu")
		(net "PUD_XTAL_CPU0_MODE0")
	)
	(segment
		(start 382.934718 -361.70743)
		(end 383.145538 -361.49661)
		(width 0.127)
		(layer "In11.Cu")
		(net "PUD_XTAL_CPU0_MODE0")
	)
	(segment
		(start 366.551718 -276.219158)
		(end 366.551464 -276.218904)
		(width 0.0889)
		(layer "In11.Cu")
		(net "PUD_XTAL_CPU0_MODE0")
	)
	(segment
		(start 366.978438 -282.001722)
		(end 366.973612 -281.998928)
		(width 0.0889)
		(layer "In11.Cu")
		(net "PUD_XTAL_CPU0_MODE0")
	)
	(segment
		(start 393.475718 -316.460124)
		(end 375.802652 -298.787058)
		(width 0.127)
		(layer "In11.Cu")
		(net "PUD_XTAL_CPU0_MODE0")
	)
	(segment
		(start 367.208816 -289.096958)
		(end 367.208816 -288.909506)
		(width 0.0889)
		(layer "In11.Cu")
		(net "PUD_XTAL_CPU0_MODE0")
	)
	(segment
		(start 366.834166 -276.70887)
		(end 366.834166 -276.69871)
		(width 0.0889)
		(layer "In11.Cu")
		(net "PUD_XTAL_CPU0_MODE0")
	)
	(segment
		(start 366.364266 -277.5331)
		(end 366.364266 -277.522432)
		(width 0.0889)
		(layer "In11.Cu")
		(net "PUD_XTAL_CPU0_MODE0")
	)
	(segment
		(start 367.45037 -282.816808)
		(end 367.443512 -282.812744)
		(width 0.0889)
		(layer "In11.Cu")
		(net "PUD_XTAL_CPU0_MODE0")
	)
	(segment
		(start 367.918238 -283.629608)
		(end 367.913412 -283.626814)
		(width 0.0889)
		(layer "In11.Cu")
		(net "PUD_XTAL_CPU0_MODE0")
	)
	(segment
		(start 365.894366 -274.362164)
		(end 365.799116 -274.266914)
		(width 0.0889)
		(layer "In11.Cu")
		(net "PUD_XTAL_CPU0_MODE0")
	)
	(segment
		(start 375.802652 -295.383458)
		(end 372.11889 -291.699696)
		(width 0.127)
		(layer "In11.Cu")
		(net "PUD_XTAL_CPU0_MODE0")
	)
	(segment
		(start 367.913412 -284.44063)
		(end 367.918238 -284.437836)
		(width 0.0889)
		(layer "In11.Cu")
		(net "PUD_XTAL_CPU0_MODE0")
	)
	(segment
		(start 367.5126 -290.769548)
		(end 366.738662 -289.99561)
		(width 0.0889)
		(layer "In11.Cu")
		(net "PUD_XTAL_CPU0_MODE0")
	)
	(segment
		(start 366.364266 -279.150318)
		(end 366.364266 -279.14981)
		(width 0.0889)
		(layer "In11.Cu")
		(net "PUD_XTAL_CPU0_MODE0")
	)
	(segment
		(start 366.364266 -280.78684)
		(end 366.364266 -280.76398)
		(width 0.0889)
		(layer "In11.Cu")
		(net "PUD_XTAL_CPU0_MODE0")
	)
	(segment
		(start 367.678716 -286.475424)
		(end 367.678716 -286.465772)
		(width 0.0889)
		(layer "In11.Cu")
		(net "PUD_XTAL_CPU0_MODE0")
	)
	(segment
		(start 367.678716 -283.229558)
		(end 367.678716 -283.219906)
		(width 0.0889)
		(layer "In11.Cu")
		(net "PUD_XTAL_CPU0_MODE0")
	)
	(segment
		(start 366.081564 -279.639776)
		(end 366.08766 -279.63622)
		(width 0.0889)
		(layer "In11.Cu")
		(net "PUD_XTAL_CPU0_MODE0")
	)
	(segment
		(start 366.973612 -288.509964)
		(end 366.968786 -288.50717)
		(width 0.0889)
		(layer "In11.Cu")
		(net "PUD_XTAL_CPU0_MODE0")
	)
	(segment
		(start 366.834166 -281.757374)
		(end 366.834166 -281.59202)
		(width 0.0889)
		(layer "In11.Cu")
		(net "PUD_XTAL_CPU0_MODE0")
	)
	(segment
		(start 366.563656 -281.109674)
		(end 366.551464 -281.102562)
		(width 0.0889)
		(layer "In11.Cu")
		(net "PUD_XTAL_CPU0_MODE0")
	)
	(segment
		(start 366.081818 -275.405088)
		(end 366.081564 -275.404834)
		(width 0.0889)
		(layer "In11.Cu")
		(net "PUD_XTAL_CPU0_MODE0")
	)
	(arc
		(start 367.913412 -283.626814)
		(mid 367.743962 -283.458968)
		(end 367.678716 -283.229558)
		(width 0.0889)
		(layer "In11.Cu")
		(net "PUD_XTAL_CPU0_MODE0")
	)
	(arc
		(start 367.208562 -282.405836)
		(mid 367.146999 -282.173313)
		(end 366.978438 -282.001722)
		(width 0.0889)
		(layer "In11.Cu")
		(net "PUD_XTAL_CPU0_MODE0")
	)
	(arc
		(start 366.973612 -289.362134)
		(mid 367.115326 -289.250937)
		(end 367.208816 -289.096958)
		(width 0.0889)
		(layer "In11.Cu")
		(net "PUD_XTAL_CPU0_MODE0")
	)
	(arc
		(start 368.148362 -285.661354)
		(mid 368.086799 -285.428831)
		(end 367.918238 -285.25724)
		(width 0.0889)
		(layer "In11.Cu")
		(net "PUD_XTAL_CPU0_MODE0")
	)
	(arc
		(start 366.364266 -275.894292)
		(mid 366.288586 -275.611846)
		(end 366.081818 -275.405088)
		(width 0.0889)
		(layer "In11.Cu")
		(net "PUD_XTAL_CPU0_MODE0")
	)
	(arc
		(start 366.98428 -287.689798)
		(mid 367.148822 -287.518828)
		(end 367.208816 -287.28924)
		(width 0.0889)
		(layer "In11.Cu")
		(net "PUD_XTAL_CPU0_MODE0")
	)
	(arc
		(start 367.918238 -284.437836)
		(mid 368.148356 -284.033722)
		(end 367.918238 -283.629608)
		(width 0.0889)
		(layer "In11.Cu")
		(net "PUD_XTAL_CPU0_MODE0")
	)
	(arc
		(start 366.834166 -281.59202)
		(mid 366.761931 -281.315496)
		(end 366.563656 -281.109674)
		(width 0.0889)
		(layer "In11.Cu")
		(net "PUD_XTAL_CPU0_MODE0")
	)
	(arc
		(start 366.551718 -277.857458)
		(mid 366.414508 -277.720398)
		(end 366.364266 -277.5331)
		(width 0.0889)
		(layer "In11.Cu")
		(net "PUD_XTAL_CPU0_MODE0")
	)
	(arc
		(start 366.081564 -280.288492)
		(mid 365.944519 -280.151532)
		(end 365.894366 -279.964388)
		(width 0.0889)
		(layer "In11.Cu")
		(net "PUD_XTAL_CPU0_MODE0")
	)
	(arc
		(start 365.894366 -279.955498)
		(mid 365.946636 -279.773133)
		(end 366.081564 -279.639776)
		(width 0.0889)
		(layer "In11.Cu")
		(net "PUD_XTAL_CPU0_MODE0")
	)
	(arc
		(start 367.438686 -282.80995)
		(mid 367.27013 -282.638356)
		(end 367.208562 -282.405836)
		(width 0.0889)
		(layer "In11.Cu")
		(net "PUD_XTAL_CPU0_MODE0")
	)
	(arc
		(start 366.834166 -276.69871)
		(mid 366.756055 -276.421761)
		(end 366.551718 -276.219158)
		(width 0.0889)
		(layer "In11.Cu")
		(net "PUD_XTAL_CPU0_MODE0")
	)
	(arc
		(start 366.973612 -281.998928)
		(mid 366.871514 -281.896837)
		(end 366.834166 -281.757374)
		(width 0.0889)
		(layer "In11.Cu")
		(net "PUD_XTAL_CPU0_MODE0")
	)
	(arc
		(start 367.208816 -287.28924)
		(mid 367.270379 -287.056717)
		(end 367.43894 -286.885126)
		(width 0.0889)
		(layer "In11.Cu")
		(net "PUD_XTAL_CPU0_MODE0")
	)
	(arc
		(start 366.364266 -277.522432)
		(mid 366.411945 -277.339532)
		(end 366.542828 -277.203154)
		(width 0.0889)
		(layer "In11.Cu")
		(net "PUD_XTAL_CPU0_MODE0")
	)
	(arc
		(start 366.551718 -277.198074)
		(mid 366.758478 -276.991311)
		(end 366.834166 -276.70887)
		(width 0.0889)
		(layer "In11.Cu")
		(net "PUD_XTAL_CPU0_MODE0")
	)
	(arc
		(start 366.551464 -281.102562)
		(mid 366.416531 -280.969208)
		(end 366.364266 -280.78684)
		(width 0.0889)
		(layer "In11.Cu")
		(net "PUD_XTAL_CPU0_MODE0")
	)
	(arc
		(start 367.913412 -285.254446)
		(mid 367.743962 -285.0866)
		(end 367.678716 -284.85719)
		(width 0.0889)
		(layer "In11.Cu")
		(net "PUD_XTAL_CPU0_MODE0")
	)
	(arc
		(start 366.834166 -278.336502)
		(mid 366.760859 -278.062999)
		(end 366.560608 -277.862792)
		(width 0.0889)
		(layer "In11.Cu")
		(net "PUD_XTAL_CPU0_MODE0")
	)
	(arc
		(start 367.678716 -283.219906)
		(mid 367.617659 -282.988273)
		(end 367.45037 -282.816808)
		(width 0.0889)
		(layer "In11.Cu")
		(net "PUD_XTAL_CPU0_MODE0")
	)
	(arc
		(start 367.913412 -286.068516)
		(mid 368.082135 -285.90225)
		(end 368.148362 -285.674816)
		(width 0.0889)
		(layer "In11.Cu")
		(net "PUD_XTAL_CPU0_MODE0")
	)
	(arc
		(start 366.738662 -289.627056)
		(mid 366.832065 -289.473246)
		(end 366.973612 -289.362134)
		(width 0.0889)
		(layer "In11.Cu")
		(net "PUD_XTAL_CPU0_MODE0")
	)
	(arc
		(start 366.081564 -275.404834)
		(mid 365.944519 -275.267874)
		(end 365.894366 -275.08073)
		(width 0.0889)
		(layer "In11.Cu")
		(net "PUD_XTAL_CPU0_MODE0")
	)
	(arc
		(start 366.551464 -276.218904)
		(mid 366.414419 -276.081944)
		(end 366.364266 -275.8948)
		(width 0.0889)
		(layer "In11.Cu")
		(net "PUD_XTAL_CPU0_MODE0")
	)
	(arc
		(start 366.08766 -279.63622)
		(mid 366.290247 -279.429869)
		(end 366.364266 -279.150318)
		(width 0.0889)
		(layer "In11.Cu")
		(net "PUD_XTAL_CPU0_MODE0")
	)
	(arc
		(start 367.208816 -288.909506)
		(mid 367.143913 -288.678712)
		(end 366.973612 -288.509964)
		(width 0.0889)
		(layer "In11.Cu")
		(net "PUD_XTAL_CPU0_MODE0")
	)
	(arc
		(start 367.678716 -286.465772)
		(mid 367.743959 -286.23636)
		(end 367.913412 -286.068516)
		(width 0.0889)
		(layer "In11.Cu")
		(net "PUD_XTAL_CPU0_MODE0")
	)
	(arc
		(start 366.551464 -278.825706)
		(mid 366.758408 -278.618996)
		(end 366.834166 -278.336502)
		(width 0.0889)
		(layer "In11.Cu")
		(net "PUD_XTAL_CPU0_MODE0")
	)
	(arc
		(start 366.364266 -280.76398)
		(mid 366.285047 -280.489295)
		(end 366.081564 -280.288492)
		(width 0.0889)
		(layer "In11.Cu")
		(net "PUD_XTAL_CPU0_MODE0")
	)
	(arc
		(start 366.364266 -279.14981)
		(mid 366.41443 -278.962672)
		(end 366.551464 -278.825706)
		(width 0.0889)
		(layer "In11.Cu")
		(net "PUD_XTAL_CPU0_MODE0")
	)
	(arc
		(start 367.448592 -286.879538)
		(mid 367.617148 -286.707944)
		(end 367.678716 -286.475424)
		(width 0.0889)
		(layer "In11.Cu")
		(net "PUD_XTAL_CPU0_MODE0")
	)
	(arc
		(start 366.968786 -288.50717)
		(mid 366.738668 -288.103056)
		(end 366.968786 -287.698942)
		(width 0.0889)
		(layer "In11.Cu")
		(net "PUD_XTAL_CPU0_MODE0")
	)
	(arc
		(start 367.678716 -284.837886)
		(mid 367.743959 -284.608474)
		(end 367.913412 -284.44063)
		(width 0.0889)
		(layer "In11.Cu")
		(net "PUD_XTAL_CPU0_MODE0")
	)
	(segment
		(start 115.509548 -264.77849)
		(end 115.509548 -265.314176)
		(width 0.12954)
		(layer "F.Cu")
		(net "PUD_PCH_BOOT_MODE_CPU1")
	)
	(segment
		(start 115.509294 -264.778236)
		(end 115.509548 -264.77849)
		(width 0.12954)
		(layer "F.Cu")
		(net "PUD_PCH_BOOT_MODE_CPU1")
	)
	(via
		(at 144.105122 -264.622026)
		(size 0.6604)
		(drill 0.3302)
		(layers "F.Cu" "B.Cu")
		(net "PUD_PCH_BOOT_MODE_CPU1")
	)
	(via
		(at 115.509548 -265.314176)
		(size 0.4572)
		(drill 0.2032)
		(layers "F.Cu" "B.Cu")
		(net "PUD_PCH_BOOT_MODE_CPU1")
	)
	(segment
		(start 120.021096 -264.990072)
		(end 120.02135 -264.989818)
		(width 0.0889)
		(layer "B.Cu")
		(net "PUD_PCH_BOOT_MODE_CPU1")
	)
	(segment
		(start 127.914146 -264.989818)
		(end 127.928878 -264.998454)
		(width 0.0889)
		(layer "B.Cu")
		(net "PUD_PCH_BOOT_MODE_CPU1")
	)
	(segment
		(start 149.663658 -263.559798)
		(end 149.663912 -263.560052)
		(width 0.12954)
		(layer "B.Cu")
		(net "PUD_PCH_BOOT_MODE_CPU1")
	)
	(segment
		(start 137.928604 -265.175492)
		(end 138.975084 -265.175492)
		(width 0.12954)
		(layer "B.Cu")
		(net "PUD_PCH_BOOT_MODE_CPU1")
	)
	(segment
		(start 126.589282 -264.995914)
		(end 126.599696 -264.989818)
		(width 0.0889)
		(layer "B.Cu")
		(net "PUD_PCH_BOOT_MODE_CPU1")
	)
	(segment
		(start 164.651944 -265.15441)
		(end 165.156388 -264.649966)
		(width 0.12954)
		(layer "B.Cu")
		(net "PUD_PCH_BOOT_MODE_CPU1")
	)
	(segment
		(start 116.636546 -265.638534)
		(end 116.651278 -265.629898)
		(width 0.0889)
		(layer "B.Cu")
		(net "PUD_PCH_BOOT_MODE_CPU1")
	)
	(segment
		(start 156.4005 -264.15111)
		(end 160.453324 -264.15111)
		(width 0.12954)
		(layer "B.Cu")
		(net "PUD_PCH_BOOT_MODE_CPU1")
	)
	(segment
		(start 129.793746 -264.989818)
		(end 129.808478 -264.998454)
		(width 0.0889)
		(layer "B.Cu")
		(net "PUD_PCH_BOOT_MODE_CPU1")
	)
	(segment
		(start 124.154946 -264.989818)
		(end 124.169678 -264.998454)
		(width 0.0889)
		(layer "B.Cu")
		(net "PUD_PCH_BOOT_MODE_CPU1")
	)
	(segment
		(start 118.515892 -265.638534)
		(end 118.526306 -265.632438)
		(width 0.0889)
		(layer "B.Cu")
		(net "PUD_PCH_BOOT_MODE_CPU1")
	)
	(segment
		(start 137.530586 -265.175492)
		(end 137.928604 -265.175492)
		(width 0.0889)
		(layer "B.Cu")
		(net "PUD_PCH_BOOT_MODE_CPU1")
	)
	(segment
		(start 144.105122 -264.622026)
		(end 148.601684 -264.622026)
		(width 0.12954)
		(layer "B.Cu")
		(net "PUD_PCH_BOOT_MODE_CPU1")
	)
	(segment
		(start 138.975084 -265.175492)
		(end 139.52855 -264.622026)
		(width 0.12954)
		(layer "B.Cu")
		(net "PUD_PCH_BOOT_MODE_CPU1")
	)
	(segment
		(start 176.10074 -200.180702)
		(end 176.275238 -200.006204)
		(width 0.12954)
		(layer "B.Cu")
		(net "PUD_PCH_BOOT_MODE_CPU1")
	)
	(segment
		(start 176.275238 -200.006204)
		(end 176.275238 -193.274442)
		(width 0.12954)
		(layer "B.Cu")
		(net "PUD_PCH_BOOT_MODE_CPU1")
	)
	(segment
		(start 126.974092 -264.989818)
		(end 126.984506 -264.995914)
		(width 0.0889)
		(layer "B.Cu")
		(net "PUD_PCH_BOOT_MODE_CPU1")
	)
	(segment
		(start 168.015158 -257.835654)
		(end 170.129454 -255.721358)
		(width 0.12954)
		(layer "B.Cu")
		(net "PUD_PCH_BOOT_MODE_CPU1")
	)
	(segment
		(start 167.226996 -264.649966)
		(end 168.015158 -263.861804)
		(width 0.12954)
		(layer "B.Cu")
		(net "PUD_PCH_BOOT_MODE_CPU1")
	)
	(segment
		(start 128.853946 -264.989818)
		(end 128.868678 -264.998454)
		(width 0.0889)
		(layer "B.Cu")
		(net "PUD_PCH_BOOT_MODE_CPU1")
	)
	(segment
		(start 155.809442 -263.560052)
		(end 156.4005 -264.15111)
		(width 0.12954)
		(layer "B.Cu")
		(net "PUD_PCH_BOOT_MODE_CPU1")
	)
	(segment
		(start 148.601684 -264.622026)
		(end 149.243542 -263.980168)
		(width 0.12954)
		(layer "B.Cu")
		(net "PUD_PCH_BOOT_MODE_CPU1")
	)
	(segment
		(start 139.52855 -264.622026)
		(end 144.105122 -264.622026)
		(width 0.12954)
		(layer "B.Cu")
		(net "PUD_PCH_BOOT_MODE_CPU1")
	)
	(segment
		(start 133.167882 -264.995914)
		(end 133.178296 -264.989818)
		(width 0.0889)
		(layer "B.Cu")
		(net "PUD_PCH_BOOT_MODE_CPU1")
	)
	(segment
		(start 168.015158 -263.861804)
		(end 168.015158 -257.835654)
		(width 0.12954)
		(layer "B.Cu")
		(net "PUD_PCH_BOOT_MODE_CPU1")
	)
	(segment
		(start 115.833906 -265.638534)
		(end 116.26215 -265.638534)
		(width 0.0889)
		(layer "B.Cu")
		(net "PUD_PCH_BOOT_MODE_CPU1")
	)
	(segment
		(start 130.733546 -264.989818)
		(end 130.748278 -264.998454)
		(width 0.0889)
		(layer "B.Cu")
		(net "PUD_PCH_BOOT_MODE_CPU1")
	)
	(segment
		(start 135.71474 -265.06551)
		(end 136.848342 -265.06551)
		(width 0.0889)
		(layer "B.Cu")
		(net "PUD_PCH_BOOT_MODE_CPU1")
	)
	(segment
		(start 131.673346 -264.989818)
		(end 131.688078 -264.998454)
		(width 0.0889)
		(layer "B.Cu")
		(net "PUD_PCH_BOOT_MODE_CPU1")
	)
	(segment
		(start 134.492746 -264.989818)
		(end 134.507478 -264.998454)
		(width 0.0889)
		(layer "B.Cu")
		(net "PUD_PCH_BOOT_MODE_CPU1")
	)
	(segment
		(start 160.453324 -264.15111)
		(end 161.456624 -265.15441)
		(width 0.12954)
		(layer "B.Cu")
		(net "PUD_PCH_BOOT_MODE_CPU1")
	)
	(segment
		(start 121.367296 -265.008106)
		(end 121.393712 -265.019536)
		(width 0.0889)
		(layer "B.Cu")
		(net "PUD_PCH_BOOT_MODE_CPU1")
	)
	(segment
		(start 149.243542 -263.979914)
		(end 149.663658 -263.559798)
		(width 0.12954)
		(layer "B.Cu")
		(net "PUD_PCH_BOOT_MODE_CPU1")
	)
	(segment
		(start 161.456624 -265.15441)
		(end 164.651944 -265.15441)
		(width 0.12954)
		(layer "B.Cu")
		(net "PUD_PCH_BOOT_MODE_CPU1")
	)
	(segment
		(start 125.094746 -264.989818)
		(end 125.109478 -264.998454)
		(width 0.0889)
		(layer "B.Cu")
		(net "PUD_PCH_BOOT_MODE_CPU1")
	)
	(segment
		(start 120.395746 -264.989818)
		(end 120.410478 -264.998454)
		(width 0.0889)
		(layer "B.Cu")
		(net "PUD_PCH_BOOT_MODE_CPU1")
	)
	(segment
		(start 165.156388 -264.649966)
		(end 167.226996 -264.649966)
		(width 0.12954)
		(layer "B.Cu")
		(net "PUD_PCH_BOOT_MODE_CPU1")
	)
	(segment
		(start 121.335546 -264.989818)
		(end 121.367296 -265.008106)
		(width 0.0889)
		(layer "B.Cu")
		(net "PUD_PCH_BOOT_MODE_CPU1")
	)
	(segment
		(start 175.377602 -252.21438)
		(end 176.10074 -251.491242)
		(width 0.12954)
		(layer "B.Cu")
		(net "PUD_PCH_BOOT_MODE_CPU1")
	)
	(segment
		(start 137.30605 -264.950956)
		(end 137.530586 -265.175492)
		(width 0.0889)
		(layer "B.Cu")
		(net "PUD_PCH_BOOT_MODE_CPU1")
	)
	(segment
		(start 170.129454 -255.721358)
		(end 175.377602 -252.21438)
		(width 0.12954)
		(layer "B.Cu")
		(net "PUD_PCH_BOOT_MODE_CPU1")
	)
	(segment
		(start 122.275346 -264.989818)
		(end 122.290078 -264.998454)
		(width 0.0889)
		(layer "B.Cu")
		(net "PUD_PCH_BOOT_MODE_CPU1")
	)
	(segment
		(start 149.663912 -263.560052)
		(end 155.809442 -263.560052)
		(width 0.12954)
		(layer "B.Cu")
		(net "PUD_PCH_BOOT_MODE_CPU1")
	)
	(segment
		(start 123.215146 -264.989818)
		(end 123.229878 -264.998454)
		(width 0.0889)
		(layer "B.Cu")
		(net "PUD_PCH_BOOT_MODE_CPU1")
	)
	(segment
		(start 117.576346 -265.638534)
		(end 117.58676 -265.632438)
		(width 0.0889)
		(layer "B.Cu")
		(net "PUD_PCH_BOOT_MODE_CPU1")
	)
	(segment
		(start 133.552692 -264.989818)
		(end 133.563106 -264.995914)
		(width 0.0889)
		(layer "B.Cu")
		(net "PUD_PCH_BOOT_MODE_CPU1")
	)
	(segment
		(start 136.962896 -264.950956)
		(end 137.30605 -264.950956)
		(width 0.0889)
		(layer "B.Cu")
		(net "PUD_PCH_BOOT_MODE_CPU1")
	)
	(segment
		(start 115.509548 -265.314176)
		(end 115.833906 -265.638534)
		(width 0.0889)
		(layer "B.Cu")
		(net "PUD_PCH_BOOT_MODE_CPU1")
	)
	(segment
		(start 149.243542 -263.980168)
		(end 149.243542 -263.979914)
		(width 0.12954)
		(layer "B.Cu")
		(net "PUD_PCH_BOOT_MODE_CPU1")
	)
	(segment
		(start 176.10074 -251.491242)
		(end 176.10074 -200.180702)
		(width 0.12954)
		(layer "B.Cu")
		(net "PUD_PCH_BOOT_MODE_CPU1")
	)
	(segment
		(start 136.848342 -265.06551)
		(end 136.962896 -264.950956)
		(width 0.0889)
		(layer "B.Cu")
		(net "PUD_PCH_BOOT_MODE_CPU1")
	)
	(segment
		(start 176.275238 -193.274442)
		(end 176.10074 -193.099944)
		(width 0.12954)
		(layer "B.Cu")
		(net "PUD_PCH_BOOT_MODE_CPU1")
	)
	(arc
		(start 121.90095 -264.989818)
		(mid 122.088148 -264.939675)
		(end 122.275346 -264.989818)
		(width 0.0889)
		(layer "B.Cu")
		(net "PUD_PCH_BOOT_MODE_CPU1")
	)
	(arc
		(start 119.08155 -265.638534)
		(mid 119.564479 -265.723875)
		(end 119.833898 -265.314176)
		(width 0.0889)
		(layer "B.Cu")
		(net "PUD_PCH_BOOT_MODE_CPU1")
	)
	(arc
		(start 135.432546 -264.989818)
		(mid 135.551177 -265.041338)
		(end 135.678418 -265.064494)
		(width 0.0889)
		(layer "B.Cu")
		(net "PUD_PCH_BOOT_MODE_CPU1")
	)
	(arc
		(start 135.05815 -264.989818)
		(mid 135.245348 -264.939675)
		(end 135.432546 -264.989818)
		(width 0.0889)
		(layer "B.Cu")
		(net "PUD_PCH_BOOT_MODE_CPU1")
	)
	(arc
		(start 122.84075 -264.989818)
		(mid 123.027948 -264.939675)
		(end 123.215146 -264.989818)
		(width 0.0889)
		(layer "B.Cu")
		(net "PUD_PCH_BOOT_MODE_CPU1")
	)
	(arc
		(start 127.928878 -264.998454)
		(mid 128.205353 -265.065774)
		(end 128.47955 -264.989818)
		(width 0.0889)
		(layer "B.Cu")
		(net "PUD_PCH_BOOT_MODE_CPU1")
	)
	(arc
		(start 126.599696 -264.989818)
		(mid 126.786894 -264.939675)
		(end 126.974092 -264.989818)
		(width 0.0889)
		(layer "B.Cu")
		(net "PUD_PCH_BOOT_MODE_CPU1")
	)
	(arc
		(start 127.53975 -264.989818)
		(mid 127.726948 -264.939675)
		(end 127.914146 -264.989818)
		(width 0.0889)
		(layer "B.Cu")
		(net "PUD_PCH_BOOT_MODE_CPU1")
	)
	(arc
		(start 133.563106 -264.995914)
		(mid 133.841538 -265.06576)
		(end 134.11835 -264.989818)
		(width 0.0889)
		(layer "B.Cu")
		(net "PUD_PCH_BOOT_MODE_CPU1")
	)
	(arc
		(start 119.833898 -265.314176)
		(mid 119.884062 -265.127038)
		(end 120.021096 -264.990072)
		(width 0.0889)
		(layer "B.Cu")
		(net "PUD_PCH_BOOT_MODE_CPU1")
	)
	(arc
		(start 129.41935 -264.989818)
		(mid 129.606548 -264.939675)
		(end 129.793746 -264.989818)
		(width 0.0889)
		(layer "B.Cu")
		(net "PUD_PCH_BOOT_MODE_CPU1")
	)
	(arc
		(start 128.47955 -264.989818)
		(mid 128.666748 -264.939675)
		(end 128.853946 -264.989818)
		(width 0.0889)
		(layer "B.Cu")
		(net "PUD_PCH_BOOT_MODE_CPU1")
	)
	(arc
		(start 120.02135 -264.989818)
		(mid 120.208548 -264.939675)
		(end 120.395746 -264.989818)
		(width 0.0889)
		(layer "B.Cu")
		(net "PUD_PCH_BOOT_MODE_CPU1")
	)
	(arc
		(start 124.169678 -264.998454)
		(mid 124.446153 -265.065774)
		(end 124.72035 -264.989818)
		(width 0.0889)
		(layer "B.Cu")
		(net "PUD_PCH_BOOT_MODE_CPU1")
	)
	(arc
		(start 128.868678 -264.998454)
		(mid 129.145153 -265.065774)
		(end 129.41935 -264.989818)
		(width 0.0889)
		(layer "B.Cu")
		(net "PUD_PCH_BOOT_MODE_CPU1")
	)
	(arc
		(start 131.688078 -264.998454)
		(mid 131.964553 -265.065774)
		(end 132.23875 -264.989818)
		(width 0.0889)
		(layer "B.Cu")
		(net "PUD_PCH_BOOT_MODE_CPU1")
	)
	(arc
		(start 120.410478 -264.998454)
		(mid 120.686953 -265.065774)
		(end 120.96115 -264.989818)
		(width 0.0889)
		(layer "B.Cu")
		(net "PUD_PCH_BOOT_MODE_CPU1")
	)
	(arc
		(start 121.393712 -265.019536)
		(mid 121.650851 -265.064838)
		(end 121.90095 -264.989818)
		(width 0.0889)
		(layer "B.Cu")
		(net "PUD_PCH_BOOT_MODE_CPU1")
	)
	(arc
		(start 117.58676 -265.632438)
		(mid 117.864938 -265.562715)
		(end 118.141496 -265.638534)
		(width 0.0889)
		(layer "B.Cu")
		(net "PUD_PCH_BOOT_MODE_CPU1")
	)
	(arc
		(start 125.109478 -264.998454)
		(mid 125.385953 -265.065774)
		(end 125.66015 -264.989818)
		(width 0.0889)
		(layer "B.Cu")
		(net "PUD_PCH_BOOT_MODE_CPU1")
	)
	(arc
		(start 116.651278 -265.629898)
		(mid 116.927753 -265.562578)
		(end 117.20195 -265.638534)
		(width 0.0889)
		(layer "B.Cu")
		(net "PUD_PCH_BOOT_MODE_CPU1")
	)
	(arc
		(start 131.29895 -264.989818)
		(mid 131.486148 -264.939675)
		(end 131.673346 -264.989818)
		(width 0.0889)
		(layer "B.Cu")
		(net "PUD_PCH_BOOT_MODE_CPU1")
	)
	(arc
		(start 129.808478 -264.998454)
		(mid 130.084953 -265.065774)
		(end 130.35915 -264.989818)
		(width 0.0889)
		(layer "B.Cu")
		(net "PUD_PCH_BOOT_MODE_CPU1")
	)
	(arc
		(start 117.20195 -265.638534)
		(mid 117.389148 -265.688677)
		(end 117.576346 -265.638534)
		(width 0.0889)
		(layer "B.Cu")
		(net "PUD_PCH_BOOT_MODE_CPU1")
	)
	(arc
		(start 118.141496 -265.638534)
		(mid 118.328694 -265.688677)
		(end 118.515892 -265.638534)
		(width 0.0889)
		(layer "B.Cu")
		(net "PUD_PCH_BOOT_MODE_CPU1")
	)
	(arc
		(start 123.229878 -264.998454)
		(mid 123.506353 -265.065774)
		(end 123.78055 -264.989818)
		(width 0.0889)
		(layer "B.Cu")
		(net "PUD_PCH_BOOT_MODE_CPU1")
	)
	(arc
		(start 126.984506 -264.995914)
		(mid 127.262938 -265.06576)
		(end 127.53975 -264.989818)
		(width 0.0889)
		(layer "B.Cu")
		(net "PUD_PCH_BOOT_MODE_CPU1")
	)
	(arc
		(start 122.290078 -264.998454)
		(mid 122.566553 -265.065774)
		(end 122.84075 -264.989818)
		(width 0.0889)
		(layer "B.Cu")
		(net "PUD_PCH_BOOT_MODE_CPU1")
	)
	(arc
		(start 123.78055 -264.989818)
		(mid 123.967748 -264.939675)
		(end 124.154946 -264.989818)
		(width 0.0889)
		(layer "B.Cu")
		(net "PUD_PCH_BOOT_MODE_CPU1")
	)
	(arc
		(start 133.178296 -264.989818)
		(mid 133.365494 -264.939675)
		(end 133.552692 -264.989818)
		(width 0.0889)
		(layer "B.Cu")
		(net "PUD_PCH_BOOT_MODE_CPU1")
	)
	(arc
		(start 132.23875 -264.989818)
		(mid 132.425948 -264.939675)
		(end 132.613146 -264.989818)
		(width 0.0889)
		(layer "B.Cu")
		(net "PUD_PCH_BOOT_MODE_CPU1")
	)
	(arc
		(start 116.26215 -265.638534)
		(mid 116.449348 -265.688677)
		(end 116.636546 -265.638534)
		(width 0.0889)
		(layer "B.Cu")
		(net "PUD_PCH_BOOT_MODE_CPU1")
	)
	(arc
		(start 135.678418 -265.064494)
		(mid 135.696571 -265.065297)
		(end 135.71474 -265.06551)
		(width 0.0889)
		(layer "B.Cu")
		(net "PUD_PCH_BOOT_MODE_CPU1")
	)
	(arc
		(start 134.11835 -264.989818)
		(mid 134.305548 -264.939675)
		(end 134.492746 -264.989818)
		(width 0.0889)
		(layer "B.Cu")
		(net "PUD_PCH_BOOT_MODE_CPU1")
	)
	(arc
		(start 132.613146 -264.989818)
		(mid 132.889705 -265.065561)
		(end 133.167882 -264.995914)
		(width 0.0889)
		(layer "B.Cu")
		(net "PUD_PCH_BOOT_MODE_CPU1")
	)
	(arc
		(start 118.526306 -265.632438)
		(mid 118.804738 -265.562592)
		(end 119.08155 -265.638534)
		(width 0.0889)
		(layer "B.Cu")
		(net "PUD_PCH_BOOT_MODE_CPU1")
	)
	(arc
		(start 130.35915 -264.989818)
		(mid 130.546348 -264.939675)
		(end 130.733546 -264.989818)
		(width 0.0889)
		(layer "B.Cu")
		(net "PUD_PCH_BOOT_MODE_CPU1")
	)
	(arc
		(start 124.72035 -264.989818)
		(mid 124.907548 -264.939675)
		(end 125.094746 -264.989818)
		(width 0.0889)
		(layer "B.Cu")
		(net "PUD_PCH_BOOT_MODE_CPU1")
	)
	(arc
		(start 130.748278 -264.998454)
		(mid 131.024753 -265.065774)
		(end 131.29895 -264.989818)
		(width 0.0889)
		(layer "B.Cu")
		(net "PUD_PCH_BOOT_MODE_CPU1")
	)
	(arc
		(start 120.96115 -264.989818)
		(mid 121.148348 -264.939675)
		(end 121.335546 -264.989818)
		(width 0.0889)
		(layer "B.Cu")
		(net "PUD_PCH_BOOT_MODE_CPU1")
	)
	(arc
		(start 125.66015 -264.989818)
		(mid 125.847348 -264.939675)
		(end 126.034546 -264.989818)
		(width 0.0889)
		(layer "B.Cu")
		(net "PUD_PCH_BOOT_MODE_CPU1")
	)
	(arc
		(start 126.034546 -264.989818)
		(mid 126.311105 -265.065561)
		(end 126.589282 -264.995914)
		(width 0.0889)
		(layer "B.Cu")
		(net "PUD_PCH_BOOT_MODE_CPU1")
	)
	(arc
		(start 134.507478 -264.998454)
		(mid 134.783953 -265.065774)
		(end 135.05815 -264.989818)
		(width 0.0889)
		(layer "B.Cu")
		(net "PUD_PCH_BOOT_MODE_CPU1")
	)
	(segment
		(start 363.449616 -264.77849)
		(end 363.449616 -265.314176)
		(width 0.12954)
		(layer "F.Cu")
		(net "PUD_PCH_BOOT_MODE_CPU0")
	)
	(segment
		(start 363.449362 -264.778236)
		(end 363.449616 -264.77849)
		(width 0.12954)
		(layer "F.Cu")
		(net "PUD_PCH_BOOT_MODE_CPU0")
	)
	(via
		(at 363.449616 -265.314176)
		(size 0.4572)
		(drill 0.2032)
		(layers "F.Cu" "B.Cu")
		(net "PUD_PCH_BOOT_MODE_CPU0")
	)
	(via
		(at 386.468112 -261.966456)
		(size 0.6604)
		(drill 0.3302)
		(layers "F.Cu" "B.Cu")
		(net "PUD_PCH_BOOT_MODE_CPU0")
	)
	(segment
		(start 384.982466 -261.966456)
		(end 384.470656 -262.478266)
		(width 0.12954)
		(layer "B.Cu")
		(net "PUD_PCH_BOOT_MODE_CPU0")
	)
	(segment
		(start 391.522458 -258.46405)
		(end 388.606538 -261.37997)
		(width 0.12954)
		(layer "B.Cu")
		(net "PUD_PCH_BOOT_MODE_CPU0")
	)
	(segment
		(start 407.191464 -197.968616)
		(end 407.191464 -237.143544)
		(width 0.12954)
		(layer "B.Cu")
		(net "PUD_PCH_BOOT_MODE_CPU0")
	)
	(segment
		(start 367.387632 -263.91997)
		(end 367.260632 -264.04697)
		(width 0.0889)
		(layer "B.Cu")
		(net "PUD_PCH_BOOT_MODE_CPU0")
	)
	(segment
		(start 406.526238 -195.24091)
		(end 406.526238 -197.30339)
		(width 0.12954)
		(layer "B.Cu")
		(net "PUD_PCH_BOOT_MODE_CPU0")
	)
	(segment
		(start 406.526238 -197.30339)
		(end 407.191464 -197.968616)
		(width 0.12954)
		(layer "B.Cu")
		(net "PUD_PCH_BOOT_MODE_CPU0")
	)
	(segment
		(start 384.470656 -262.478266)
		(end 384.011678 -262.478266)
		(width 0.12954)
		(layer "B.Cu")
		(net "PUD_PCH_BOOT_MODE_CPU0")
	)
	(segment
		(start 388.606538 -261.37997)
		(end 387.054598 -261.37997)
		(width 0.12954)
		(layer "B.Cu")
		(net "PUD_PCH_BOOT_MODE_CPU0")
	)
	(segment
		(start 363.709712 -264.04697)
		(end 363.449616 -264.307066)
		(width 0.0889)
		(layer "B.Cu")
		(net "PUD_PCH_BOOT_MODE_CPU0")
	)
	(segment
		(start 369.415822 -262.478266)
		(end 368.913664 -262.980424)
		(width 0.0889)
		(layer "B.Cu")
		(net "PUD_PCH_BOOT_MODE_CPU0")
	)
	(segment
		(start 406.254204 -238.080804)
		(end 403.120098 -238.080804)
		(width 0.12954)
		(layer "B.Cu")
		(net "PUD_PCH_BOOT_MODE_CPU0")
	)
	(segment
		(start 368.352578 -263.91997)
		(end 367.387632 -263.91997)
		(width 0.0889)
		(layer "B.Cu")
		(net "PUD_PCH_BOOT_MODE_CPU0")
	)
	(segment
		(start 368.913664 -263.358884)
		(end 368.352578 -263.91997)
		(width 0.0889)
		(layer "B.Cu")
		(net "PUD_PCH_BOOT_MODE_CPU0")
	)
	(segment
		(start 407.191464 -237.143544)
		(end 406.254204 -238.080804)
		(width 0.12954)
		(layer "B.Cu")
		(net "PUD_PCH_BOOT_MODE_CPU0")
	)
	(segment
		(start 405.129238 -193.44386)
		(end 405.129238 -193.84391)
		(width 0.12954)
		(layer "B.Cu")
		(net "PUD_PCH_BOOT_MODE_CPU0")
	)
	(segment
		(start 368.913664 -262.980424)
		(end 368.913664 -263.358884)
		(width 0.0889)
		(layer "B.Cu")
		(net "PUD_PCH_BOOT_MODE_CPU0")
	)
	(segment
		(start 384.011678 -262.478266)
		(end 369.415822 -262.478266)
		(width 0.0889)
		(layer "B.Cu")
		(net "PUD_PCH_BOOT_MODE_CPU0")
	)
	(segment
		(start 405.129238 -193.84391)
		(end 406.526238 -195.24091)
		(width 0.12954)
		(layer "B.Cu")
		(net "PUD_PCH_BOOT_MODE_CPU0")
	)
	(segment
		(start 387.054598 -261.37997)
		(end 386.468112 -261.966456)
		(width 0.12954)
		(layer "B.Cu")
		(net "PUD_PCH_BOOT_MODE_CPU0")
	)
	(segment
		(start 363.449616 -264.307066)
		(end 363.449616 -265.314176)
		(width 0.0889)
		(layer "B.Cu")
		(net "PUD_PCH_BOOT_MODE_CPU0")
	)
	(segment
		(start 367.260632 -264.04697)
		(end 363.709712 -264.04697)
		(width 0.0889)
		(layer "B.Cu")
		(net "PUD_PCH_BOOT_MODE_CPU0")
	)
	(segment
		(start 386.468112 -261.966456)
		(end 384.982466 -261.966456)
		(width 0.12954)
		(layer "B.Cu")
		(net "PUD_PCH_BOOT_MODE_CPU0")
	)
	(segment
		(start 399.117058 -253.30023)
		(end 393.953238 -258.46405)
		(width 0.12954)
		(layer "B.Cu")
		(net "PUD_PCH_BOOT_MODE_CPU0")
	)
	(segment
		(start 393.953238 -258.46405)
		(end 391.522458 -258.46405)
		(width 0.12954)
		(layer "B.Cu")
		(net "PUD_PCH_BOOT_MODE_CPU0")
	)
	(segment
		(start 399.117058 -242.083844)
		(end 399.117058 -253.30023)
		(width 0.12954)
		(layer "B.Cu")
		(net "PUD_PCH_BOOT_MODE_CPU0")
	)
	(segment
		(start 403.120098 -238.080804)
		(end 399.117058 -242.083844)
		(width 0.12954)
		(layer "B.Cu")
		(net "PUD_PCH_BOOT_MODE_CPU0")
	)
	(segment
		(start 189.861952 -16.550132)
		(end 189.861952 -17.465802)
		(width 0.12954)
		(layer "F.Cu")
		(net "PRSNT0_N")
	)
	(segment
		(start 189.861698 -17.466056)
		(end 189.861698 -18.142966)
		(width 0.12954)
		(layer "F.Cu")
		(net "PRSNT0_N")
	)
	(segment
		(start 189.861952 -17.465802)
		(end 189.861698 -17.466056)
		(width 0.12954)
		(layer "F.Cu")
		(net "PRSNT0_N")
	)
	(via
		(at 189.861698 -18.142966)
		(size 0.508)
		(drill 0.254)
		(layers "F.Cu" "B.Cu")
		(net "PRSNT0_N")
	)
	(via
		(at 188.71184 -19.340068)
		(size 0.6604)
		(drill 0.3302)
		(layers "F.Cu" "B.Cu")
		(net "PRSNT0_N")
	)
	(segment
		(start 188.71184 -19.340068)
		(end 189.44971 -19.340068)
		(width 0.12954)
		(layer "B.Cu")
		(net "PRSNT0_N")
	)
	(segment
		(start 189.44971 -19.340068)
		(end 189.85103 -18.938748)
		(width 0.12954)
		(layer "B.Cu")
		(net "PRSNT0_N")
	)
	(segment
		(start 188.71184 -19.292824)
		(end 188.71184 -19.340068)
		(width 0.12954)
		(layer "B.Cu")
		(net "PRSNT0_N")
	)
	(segment
		(start 189.861698 -18.142966)
		(end 188.71184 -19.292824)
		(width 0.12954)
		(layer "B.Cu")
		(net "PRSNT0_N")
	)
	(segment
		(start 337.142328 -16.982948)
		(end 337.142328 -18.434558)
		(width 0.381)
		(layer "F.Cu")
		(net "PGPPA_AUX")
	)
	(segment
		(start 336.779108 -16.619728)
		(end 337.142328 -16.982948)
		(width 0.381)
		(layer "F.Cu")
		(net "PGPPA_AUX")
	)
	(segment
		(start 333.183738 -19.225768)
		(end 333.155544 -19.197574)
		(width 0.381)
		(layer "F.Cu")
		(net "PGPPA_AUX")
	)
	(segment
		(start 334.385412 -20.607782)
		(end 334.385412 -19.407886)
		(width 0.381)
		(layer "F.Cu")
		(net "PGPPA_AUX")
	)
	(segment
		(start 334.146398 -19.225768)
		(end 333.183738 -19.225768)
		(width 0.381)
		(layer "F.Cu")
		(net "PGPPA_AUX")
	)
	(segment
		(start 336.779108 -16.619728)
		(end 337.845908 -16.619728)
		(width 0.381)
		(layer "F.Cu")
		(net "PGPPA_AUX")
	)
	(segment
		(start 333.029814 -19.877532)
		(end 333.029814 -19.323304)
		(width 0.381)
		(layer "F.Cu")
		(net "PGPPA_AUX")
	)
	(segment
		(start 332.957678 -19.949668)
		(end 333.029814 -19.877532)
		(width 0.381)
		(layer "F.Cu")
		(net "PGPPA_AUX")
	)
	(segment
		(start 334.385412 -19.407886)
		(end 334.174846 -19.19732)
		(width 0.381)
		(layer "F.Cu")
		(net "PGPPA_AUX")
	)
	(segment
		(start 333.029814 -19.323304)
		(end 333.155544 -19.197574)
		(width 0.381)
		(layer "F.Cu")
		(net "PGPPA_AUX")
	)
	(segment
		(start 334.174846 -19.19732)
		(end 334.146398 -19.225768)
		(width 0.381)
		(layer "F.Cu")
		(net "PGPPA_AUX")
	)
	(segment
		(start 332.124812 -19.838416)
		(end 332.124812 -19.197066)
		(width 0.381)
		(layer "F.Cu")
		(net "PGPPA_AUX")
	)
	(segment
		(start 332.00848 -19.954748)
		(end 332.124812 -19.838416)
		(width 0.381)
		(layer "F.Cu")
		(net "PGPPA_AUX")
	)
	(segment
		(start 331.029056 -18.97761)
		(end 331.056996 -19.00555)
		(width 0.381)
		(layer "F.Cu")
		(net "PGPPA_AUX")
	)
	(segment
		(start 336.018124 -27.256232)
		(end 336.018124 -27.872182)
		(width 0.381)
		(layer "F.Cu")
		(net "PGPPA_AUX")
	)
	(segment
		(start 338.63026 -14.94155)
		(end 338.63026 -15.835376)
		(width 0.12954)
		(layer "F.Cu")
		(net "PGPPA_AUX")
	)
	(segment
		(start 331.056996 -19.00555)
		(end 331.933296 -19.00555)
		(width 0.381)
		(layer "F.Cu")
		(net "PGPPA_AUX")
	)
	(segment
		(start 334.729074 -16.60525)
		(end 334.729074 -17.437608)
		(width 0.3556)
		(layer "F.Cu")
		(net "PGPPA_AUX")
	)
	(segment
		(start 338.63026 -15.835376)
		(end 337.845908 -16.619728)
		(width 0.12954)
		(layer "F.Cu")
		(net "PGPPA_AUX")
	)
	(segment
		(start 331.933296 -19.00555)
		(end 332.124812 -19.197066)
		(width 0.381)
		(layer "F.Cu")
		(net "PGPPA_AUX")
	)
	(segment
		(start 337.792314 -24.612092)
		(end 337.792314 -25.26157)
		(width 0.381)
		(layer "F.Cu")
		(net "PGPPA_AUX")
	)
	(via
		(at 337.792314 -25.26157)
		(size 0.508)
		(drill 0.254)
		(layers "F.Cu" "B.Cu")
		(net "PGPPA_AUX")
	)
	(via
		(at 302.105822 -15.286482)
		(size 0.508)
		(drill 0.254)
		(layers "F.Cu" "B.Cu")
		(net "PGPPA_AUX")
	)
	(via
		(at 289.621468 -25.68829)
		(size 0.508)
		(drill 0.254)
		(layers "F.Cu" "B.Cu")
		(net "PGPPA_AUX")
	)
	(via
		(at 324.31228 -14.768068)
		(size 0.508)
		(drill 0.254)
		(layers "F.Cu" "B.Cu")
		(net "PGPPA_AUX")
	)
	(via
		(at 325.01332 -14.765528)
		(size 0.508)
		(drill 0.254)
		(layers "F.Cu" "B.Cu")
		(net "PGPPA_AUX")
	)
	(via
		(at 325.71944 -14.765528)
		(size 0.508)
		(drill 0.254)
		(layers "F.Cu" "B.Cu")
		(net "PGPPA_AUX")
	)
	(via
		(at 172.16628 -22.723348)
		(size 0.508)
		(drill 0.254)
		(layers "F.Cu" "B.Cu")
		(net "PGPPA_AUX")
	)
	(via
		(at 334.729074 -17.437608)
		(size 0.508)
		(drill 0.254)
		(layers "F.Cu" "B.Cu")
		(net "PGPPA_AUX")
	)
	(via
		(at 338.63026 -14.94155)
		(size 0.508)
		(drill 0.254)
		(layers "F.Cu" "B.Cu")
		(net "PGPPA_AUX")
	)
	(via
		(at 332.957678 -19.949668)
		(size 0.508)
		(drill 0.254)
		(layers "F.Cu" "B.Cu")
		(net "PGPPA_AUX")
	)
	(via
		(at 336.018124 -27.872182)
		(size 0.508)
		(drill 0.254)
		(layers "F.Cu" "B.Cu")
		(net "PGPPA_AUX")
	)
	(via
		(at 332.00848 -19.954748)
		(size 0.508)
		(drill 0.254)
		(layers "F.Cu" "B.Cu")
		(net "PGPPA_AUX")
	)
	(via
		(at 326.441054 -14.762734)
		(size 0.508)
		(drill 0.254)
		(layers "F.Cu" "B.Cu")
		(net "PGPPA_AUX")
	)
	(via
		(at 215.572086 -39.815008)
		(size 0.508)
		(drill 0.254)
		(layers "F.Cu" "B.Cu")
		(net "PGPPA_AUX")
	)
	(segment
		(start 252.984 -42.077894)
		(end 253.798832 -42.892726)
		(width 0.508)
		(layer "B.Cu")
		(net "PGPPA_AUX")
	)
	(segment
		(start 315.07811 -15.259304)
		(end 314.691522 -15.645892)
		(width 0.508)
		(layer "B.Cu")
		(net "PGPPA_AUX")
	)
	(segment
		(start 324.31228 -14.768068)
		(end 323.821044 -15.259304)
		(width 0.508)
		(layer "B.Cu")
		(net "PGPPA_AUX")
	)
	(segment
		(start 246.364506 -45.746416)
		(end 250.033028 -42.077894)
		(width 0.508)
		(layer "B.Cu")
		(net "PGPPA_AUX")
	)
	(segment
		(start 334.789526 -20.98929)
		(end 333.749904 -19.949668)
		(width 0.381)
		(layer "B.Cu")
		(net "PGPPA_AUX")
	)
	(segment
		(start 253.798832 -42.892726)
		(end 262.201152 -42.892726)
		(width 0.508)
		(layer "B.Cu")
		(net "PGPPA_AUX")
	)
	(segment
		(start 222.858584 -40.349932)
		(end 223.874584 -41.365932)
		(width 0.508)
		(layer "B.Cu")
		(net "PGPPA_AUX")
	)
	(segment
		(start 277.639018 -40.301672)
		(end 288.264092 -29.676598)
		(width 0.508)
		(layer "B.Cu")
		(net "PGPPA_AUX")
	)
	(segment
		(start 232.603548 -42.669206)
		(end 233.544872 -42.669206)
		(width 0.508)
		(layer "B.Cu")
		(net "PGPPA_AUX")
	)
	(segment
		(start 172.16628 -22.723348)
		(end 172.29836 -22.723348)
		(width 0.381)
		(layer "B.Cu")
		(net "PGPPA_AUX")
	)
	(segment
		(start 236.622082 -45.746416)
		(end 246.364506 -45.746416)
		(width 0.508)
		(layer "B.Cu")
		(net "PGPPA_AUX")
	)
	(segment
		(start 233.544872 -42.669206)
		(end 236.622082 -45.746416)
		(width 0.508)
		(layer "B.Cu")
		(net "PGPPA_AUX")
	)
	(segment
		(start 172.29836 -22.723348)
		(end 172.53966 -22.964648)
		(width 0.381)
		(layer "B.Cu")
		(net "PGPPA_AUX")
	)
	(segment
		(start 289.31997 -25.68829)
		(end 289.621468 -25.68829)
		(width 0.508)
		(layer "B.Cu")
		(net "PGPPA_AUX")
	)
	(segment
		(start 338.335874 -25.327102)
		(end 338.666328 -24.996648)
		(width 0.381)
		(layer "B.Cu")
		(net "PGPPA_AUX")
	)
	(segment
		(start 323.821044 -15.259304)
		(end 315.07811 -15.259304)
		(width 0.508)
		(layer "B.Cu")
		(net "PGPPA_AUX")
	)
	(segment
		(start 314.691522 -15.645892)
		(end 311.66054 -15.645892)
		(width 0.508)
		(layer "B.Cu")
		(net "PGPPA_AUX")
	)
	(segment
		(start 288.264092 -26.744168)
		(end 289.31997 -25.68829)
		(width 0.508)
		(layer "B.Cu")
		(net "PGPPA_AUX")
	)
	(segment
		(start 335.903824 -20.98929)
		(end 334.789526 -20.98929)
		(width 0.381)
		(layer "B.Cu")
		(net "PGPPA_AUX")
	)
	(segment
		(start 223.874584 -41.365932)
		(end 231.300274 -41.365932)
		(width 0.508)
		(layer "B.Cu")
		(net "PGPPA_AUX")
	)
	(segment
		(start 172.53966 -22.964648)
		(end 173.377352 -22.964648)
		(width 0.381)
		(layer "B.Cu")
		(net "PGPPA_AUX")
	)
	(segment
		(start 274.71878 -44.935648)
		(end 277.639018 -42.01541)
		(width 0.508)
		(layer "B.Cu")
		(net "PGPPA_AUX")
	)
	(segment
		(start 262.201152 -42.892726)
		(end 264.244074 -44.935648)
		(width 0.508)
		(layer "B.Cu")
		(net "PGPPA_AUX")
	)
	(segment
		(start 311.30113 -15.286482)
		(end 302.105822 -15.286482)
		(width 0.508)
		(layer "B.Cu")
		(net "PGPPA_AUX")
	)
	(segment
		(start 288.264092 -29.676598)
		(end 288.264092 -26.744168)
		(width 0.508)
		(layer "B.Cu")
		(net "PGPPA_AUX")
	)
	(segment
		(start 337.857846 -25.327102)
		(end 338.335874 -25.327102)
		(width 0.381)
		(layer "B.Cu")
		(net "PGPPA_AUX")
	)
	(segment
		(start 231.300274 -41.365932)
		(end 232.603548 -42.669206)
		(width 0.508)
		(layer "B.Cu")
		(net "PGPPA_AUX")
	)
	(segment
		(start 250.033028 -42.077894)
		(end 252.984 -42.077894)
		(width 0.508)
		(layer "B.Cu")
		(net "PGPPA_AUX")
	)
	(segment
		(start 337.792314 -25.26157)
		(end 337.857846 -25.327102)
		(width 0.381)
		(layer "B.Cu")
		(net "PGPPA_AUX")
	)
	(segment
		(start 215.572086 -39.815008)
		(end 218.38666 -39.815008)
		(width 0.508)
		(layer "B.Cu")
		(net "PGPPA_AUX")
	)
	(segment
		(start 218.921584 -40.349932)
		(end 222.858584 -40.349932)
		(width 0.508)
		(layer "B.Cu")
		(net "PGPPA_AUX")
	)
	(segment
		(start 277.639018 -42.01541)
		(end 277.639018 -40.301672)
		(width 0.508)
		(layer "B.Cu")
		(net "PGPPA_AUX")
	)
	(segment
		(start 338.666328 -23.751794)
		(end 335.903824 -20.98929)
		(width 0.381)
		(layer "B.Cu")
		(net "PGPPA_AUX")
	)
	(segment
		(start 338.666328 -24.996648)
		(end 338.666328 -23.751794)
		(width 0.381)
		(layer "B.Cu")
		(net "PGPPA_AUX")
	)
	(segment
		(start 218.38666 -39.815008)
		(end 218.921584 -40.349932)
		(width 0.508)
		(layer "B.Cu")
		(net "PGPPA_AUX")
	)
	(segment
		(start 311.66054 -15.645892)
		(end 311.30113 -15.286482)
		(width 0.508)
		(layer "B.Cu")
		(net "PGPPA_AUX")
	)
	(segment
		(start 333.749904 -19.949668)
		(end 332.957678 -19.949668)
		(width 0.381)
		(layer "B.Cu")
		(net "PGPPA_AUX")
	)
	(segment
		(start 264.244074 -44.935648)
		(end 274.71878 -44.935648)
		(width 0.508)
		(layer "B.Cu")
		(net "PGPPA_AUX")
	)
	(segment
		(start 302.105822 -15.286482)
		(end 299.661834 -15.286482)
		(width 0.508)
		(layer "In2.Cu")
		(net "PGPPA_AUX")
	)
	(segment
		(start 291.709348 -16.456914)
		(end 289.621468 -18.544794)
		(width 0.508)
		(layer "In2.Cu")
		(net "PGPPA_AUX")
	)
	(segment
		(start 289.621468 -18.544794)
		(end 289.621468 -25.68829)
		(width 0.508)
		(layer "In2.Cu")
		(net "PGPPA_AUX")
	)
	(segment
		(start 298.491402 -16.456914)
		(end 291.709348 -16.456914)
		(width 0.508)
		(layer "In2.Cu")
		(net "PGPPA_AUX")
	)
	(segment
		(start 299.661834 -15.286482)
		(end 298.491402 -16.456914)
		(width 0.508)
		(layer "In2.Cu")
		(net "PGPPA_AUX")
	)
	(segment
		(start 336.018124 -27.872182)
		(end 336.018124 -27.03576)
		(width 0.508)
		(layer "In6.Cu")
		(net "PGPPA_AUX")
	)
	(segment
		(start 336.018124 -27.03576)
		(end 337.792314 -25.26157)
		(width 0.508)
		(layer "In6.Cu")
		(net "PGPPA_AUX")
	)
	(segment
		(start 181.542944 -20.788884)
		(end 179.60848 -22.723348)
		(width 0.508)
		(layer "In11.Cu")
		(net "PGPPA_AUX")
	)
	(segment
		(start 205.859888 -37.823902)
		(end 205.859888 -35.307778)
		(width 0.508)
		(layer "In11.Cu")
		(net "PGPPA_AUX")
	)
	(segment
		(start 185.208164 -20.788884)
		(end 181.542944 -20.788884)
		(width 0.508)
		(layer "In11.Cu")
		(net "PGPPA_AUX")
	)
	(segment
		(start 207.451452 -39.415466)
		(end 205.859888 -37.823902)
		(width 0.508)
		(layer "In11.Cu")
		(net "PGPPA_AUX")
	)
	(segment
		(start 179.60848 -22.723348)
		(end 172.16628 -22.723348)
		(width 0.508)
		(layer "In11.Cu")
		(net "PGPPA_AUX")
	)
	(segment
		(start 215.572086 -39.815008)
		(end 215.172544 -39.415466)
		(width 0.508)
		(layer "In11.Cu")
		(net "PGPPA_AUX")
	)
	(segment
		(start 193.678302 -23.826978)
		(end 190.072772 -20.221448)
		(width 0.508)
		(layer "In11.Cu")
		(net "PGPPA_AUX")
	)
	(segment
		(start 190.072772 -20.221448)
		(end 185.7756 -20.221448)
		(width 0.508)
		(layer "In11.Cu")
		(net "PGPPA_AUX")
	)
	(segment
		(start 215.172544 -39.415466)
		(end 207.451452 -39.415466)
		(width 0.508)
		(layer "In11.Cu")
		(net "PGPPA_AUX")
	)
	(segment
		(start 203.351638 -32.799528)
		(end 199.11441 -32.799528)
		(width 0.508)
		(layer "In11.Cu")
		(net "PGPPA_AUX")
	)
	(segment
		(start 193.678302 -27.36342)
		(end 193.678302 -23.826978)
		(width 0.508)
		(layer "In11.Cu")
		(net "PGPPA_AUX")
	)
	(segment
		(start 205.859888 -35.307778)
		(end 203.351638 -32.799528)
		(width 0.508)
		(layer "In11.Cu")
		(net "PGPPA_AUX")
	)
	(segment
		(start 185.7756 -20.221448)
		(end 185.208164 -20.788884)
		(width 0.508)
		(layer "In11.Cu")
		(net "PGPPA_AUX")
	)
	(segment
		(start 199.11441 -32.799528)
		(end 193.678302 -27.36342)
		(width 0.508)
		(layer "In11.Cu")
		(net "PGPPA_AUX")
	)
	(segment
		(start 310.21782 -54.864)
		(end 309.436262 -55.645558)
		(width 0.12954)
		(layer "F.Cu")
		(net "PECI_PCH_R")
	)
	(segment
		(start 308.79288 -53.450998)
		(end 308.79288 -54.430168)
		(width 0.12954)
		(layer "F.Cu")
		(net "PECI_PCH_R")
	)
	(segment
		(start 308.79288 -53.450998)
		(end 307.77688 -53.450998)
		(width 0.12954)
		(layer "F.Cu")
		(net "PECI_PCH_R")
	)
	(segment
		(start 309.436262 -55.645558)
		(end 309.01894 -55.645558)
		(width 0.12954)
		(layer "F.Cu")
		(net "PECI_PCH_R")
	)
	(segment
		(start 309.226712 -54.864)
		(end 310.21782 -54.864)
		(width 0.12954)
		(layer "F.Cu")
		(net "PECI_PCH_R")
	)
	(segment
		(start 308.00294 -55.645558)
		(end 309.01894 -55.645558)
		(width 0.12954)
		(layer "F.Cu")
		(net "PECI_PCH_R")
	)
	(segment
		(start 308.79288 -54.430168)
		(end 309.226712 -54.864)
		(width 0.12954)
		(layer "F.Cu")
		(net "PECI_PCH_R")
	)
	(via
		(at 310.21782 -54.864)
		(size 0.762)
		(drill 0.381)
		(layers "F.Cu" "B.Cu")
		(net "PECI_PCH_R")
	)
	(segment
		(start 308.011322 -58.03773)
		(end 308.011322 -57.325006)
		(width 0.12954)
		(layer "F.Cu")
		(net "PECI_PCH_B1")
	)
	(segment
		(start 308.011322 -57.325006)
		(end 308.23916 -57.097168)
		(width 0.12954)
		(layer "F.Cu")
		(net "PECI_PCH_B1")
	)
	(segment
		(start 308.23916 -57.097168)
		(end 308.011322 -56.86933)
		(width 0.12954)
		(layer "F.Cu")
		(net "PECI_PCH_B1")
	)
	(segment
		(start 308.011322 -56.86933)
		(end 308.011322 -56.45404)
		(width 0.12954)
		(layer "F.Cu")
		(net "PECI_PCH_B1")
	)
	(segment
		(start 308.011322 -56.45404)
		(end 308.00294 -56.445658)
		(width 0.12954)
		(layer "F.Cu")
		(net "PECI_PCH_B1")
	)
	(via
		(at 308.23916 -57.097168)
		(size 0.508)
		(drill 0.254)
		(layers "F.Cu" "B.Cu")
		(net "PECI_PCH_B1")
	)
	(segment
		(start 330.25588 -55.498746)
		(end 330.79436 -55.498746)
		(width 0.12954)
		(layer "F.Cu")
		(net "PECI_PCH")
	)
	(segment
		(start 308.79288 -52.034948)
		(end 308.79288 -52.650898)
		(width 0.12954)
		(layer "F.Cu")
		(net "PECI_PCH")
	)
	(via
		(at 330.25588 -55.498746)
		(size 0.4572)
		(drill 0.2032)
		(layers "F.Cu" "B.Cu")
		(net "PECI_PCH")
	)
	(via
		(at 326.325484 -52.646834)
		(size 0.6604)
		(drill 0.3302)
		(layers "F.Cu" "B.Cu")
		(net "PECI_PCH")
	)
	(via
		(at 308.79288 -52.034948)
		(size 0.508)
		(drill 0.254)
		(layers "F.Cu" "B.Cu")
		(net "PECI_PCH")
	)
	(segment
		(start 329.334622 -54.600348)
		(end 328.826622 -54.092348)
		(width 0.12954)
		(layer "B.Cu")
		(net "PECI_PCH")
	)
	(segment
		(start 330.25588 -55.498746)
		(end 330.255372 -55.498238)
		(width 0.12954)
		(layer "B.Cu")
		(net "PECI_PCH")
	)
	(segment
		(start 310.95569 -47.398178)
		(end 308.93766 -49.416208)
		(width 0.12954)
		(layer "B.Cu")
		(net "PECI_PCH")
	)
	(segment
		(start 328.826622 -54.092348)
		(end 328.491342 -54.092348)
		(width 0.12954)
		(layer "B.Cu")
		(net "PECI_PCH")
	)
	(segment
		(start 323.09308 -51.399948)
		(end 322.85432 -51.161188)
		(width 0.12954)
		(layer "B.Cu")
		(net "PECI_PCH")
	)
	(segment
		(start 328.491342 -54.092348)
		(end 327.045828 -52.646834)
		(width 0.12954)
		(layer "B.Cu")
		(net "PECI_PCH")
	)
	(segment
		(start 327.045828 -52.646834)
		(end 326.325484 -52.646834)
		(width 0.12954)
		(layer "B.Cu")
		(net "PECI_PCH")
	)
	(segment
		(start 323.88048 -51.399948)
		(end 323.09308 -51.399948)
		(width 0.12954)
		(layer "B.Cu")
		(net "PECI_PCH")
	)
	(segment
		(start 326.325484 -52.646834)
		(end 325.533766 -52.646834)
		(width 0.12954)
		(layer "B.Cu")
		(net "PECI_PCH")
	)
	(segment
		(start 308.93766 -49.416208)
		(end 308.93766 -51.890168)
		(width 0.12954)
		(layer "B.Cu")
		(net "PECI_PCH")
	)
	(segment
		(start 308.93766 -51.890168)
		(end 308.79288 -52.034948)
		(width 0.12954)
		(layer "B.Cu")
		(net "PECI_PCH")
	)
	(segment
		(start 317.66891 -47.398178)
		(end 310.95569 -47.398178)
		(width 0.12954)
		(layer "B.Cu")
		(net "PECI_PCH")
	)
	(segment
		(start 324.79488 -51.907948)
		(end 324.38848 -51.907948)
		(width 0.12954)
		(layer "B.Cu")
		(net "PECI_PCH")
	)
	(segment
		(start 322.85432 -51.161188)
		(end 321.43192 -51.161188)
		(width 0.12954)
		(layer "B.Cu")
		(net "PECI_PCH")
	)
	(segment
		(start 329.715622 -54.600348)
		(end 329.334622 -54.600348)
		(width 0.12954)
		(layer "B.Cu")
		(net "PECI_PCH")
	)
	(segment
		(start 324.38848 -51.907948)
		(end 323.88048 -51.399948)
		(width 0.12954)
		(layer "B.Cu")
		(net "PECI_PCH")
	)
	(segment
		(start 321.43192 -51.161188)
		(end 317.66891 -47.398178)
		(width 0.12954)
		(layer "B.Cu")
		(net "PECI_PCH")
	)
	(segment
		(start 330.255372 -55.140098)
		(end 329.715622 -54.600348)
		(width 0.12954)
		(layer "B.Cu")
		(net "PECI_PCH")
	)
	(segment
		(start 325.533766 -52.646834)
		(end 324.79488 -51.907948)
		(width 0.12954)
		(layer "B.Cu")
		(net "PECI_PCH")
	)
	(segment
		(start 330.255372 -55.498238)
		(end 330.255372 -55.140098)
		(width 0.12954)
		(layer "B.Cu")
		(net "PECI_PCH")
	)
	(segment
		(start 304.9397 -61.130688)
		(end 304.9397 -60.094368)
		(width 0.12954)
		(layer "F.Cu")
		(net "PECI_MUX_SEL_R")
	)
	(segment
		(start 305.63566 -59.494928)
		(end 306.5399 -59.494928)
		(width 0.12954)
		(layer "F.Cu")
		(net "PECI_MUX_SEL_R")
	)
	(segment
		(start 304.9397 -60.094368)
		(end 304.94986 -60.084208)
		(width 0.12954)
		(layer "F.Cu")
		(net "PECI_MUX_SEL_R")
	)
	(segment
		(start 304.94986 -58.809128)
		(end 305.63566 -59.494928)
		(width 0.12954)
		(layer "F.Cu")
		(net "PECI_MUX_SEL_R")
	)
	(segment
		(start 304.94986 -60.084208)
		(end 304.94986 -58.809128)
		(width 0.12954)
		(layer "F.Cu")
		(net "PECI_MUX_SEL_R")
	)
	(segment
		(start 306.5399 -59.494928)
		(end 306.71135 -59.666378)
		(width 0.12954)
		(layer "F.Cu")
		(net "PECI_MUX_SEL_R")
	)
	(segment
		(start 306.71135 -59.666378)
		(end 306.71135 -60.037726)
		(width 0.12954)
		(layer "F.Cu")
		(net "PECI_MUX_SEL_R")
	)
	(segment
		(start 304.9397 -62.151768)
		(end 304.9397 -61.130688)
		(width 0.12954)
		(layer "F.Cu")
		(net "PECI_MUX_SEL_R")
	)
	(via
		(at 304.94986 -58.809128)
		(size 0.762)
		(drill 0.381)
		(layers "F.Cu" "B.Cu")
		(net "PECI_MUX_SEL_R")
	)
	(segment
		(start 310.725058 -192.43421)
		(end 310.725058 -193.28511)
		(width 0.12954)
		(layer "F.Cu")
		(net "PECI_CPU_GTL")
	)
	(segment
		(start 309.886858 -194.12331)
		(end 300.094142 -194.12331)
		(width 0.12954)
		(layer "F.Cu")
		(net "PECI_CPU_GTL")
	)
	(segment
		(start 308.011322 -60.95619)
		(end 309.030624 -61.975492)
		(width 0.12954)
		(layer "F.Cu")
		(net "PECI_CPU_GTL")
	)
	(segment
		(start 309.647336 -61.975492)
		(end 309.030624 -61.975492)
		(width 0.12954)
		(layer "F.Cu")
		(net "PECI_CPU_GTL")
	)
	(segment
		(start 311.94248 -129.885948)
		(end 319.00368 -129.885948)
		(width 0.12954)
		(layer "F.Cu")
		(net "PECI_CPU_GTL")
	)
	(segment
		(start 310.725058 -193.28511)
		(end 309.886858 -194.12331)
		(width 0.12954)
		(layer "F.Cu")
		(net "PECI_CPU_GTL")
	)
	(segment
		(start 305.95824 -174.097188)
		(end 305.95824 -135.870188)
		(width 0.12954)
		(layer "F.Cu")
		(net "PECI_CPU_GTL")
	)
	(segment
		(start 309.68188 -61.940948)
		(end 309.647336 -61.975492)
		(width 0.12954)
		(layer "F.Cu")
		(net "PECI_CPU_GTL")
	)
	(segment
		(start 300.094142 -194.12331)
		(end 298.7675 -192.796668)
		(width 0.12954)
		(layer "F.Cu")
		(net "PECI_CPU_GTL")
	)
	(segment
		(start 298.7675 -181.287928)
		(end 305.95824 -174.097188)
		(width 0.12954)
		(layer "F.Cu")
		(net "PECI_CPU_GTL")
	)
	(segment
		(start 305.95824 -135.870188)
		(end 311.94248 -129.885948)
		(width 0.12954)
		(layer "F.Cu")
		(net "PECI_CPU_GTL")
	)
	(segment
		(start 298.7675 -192.796668)
		(end 298.7675 -181.287928)
		(width 0.12954)
		(layer "F.Cu")
		(net "PECI_CPU_GTL")
	)
	(segment
		(start 308.011322 -60.037726)
		(end 308.011322 -60.95619)
		(width 0.12954)
		(layer "F.Cu")
		(net "PECI_CPU_GTL")
	)
	(via
		(at 137.62228 -146.08302)
		(size 0.508)
		(drill 0.254)
		(layers "F.Cu" "B.Cu")
		(net "PECI_CPU_GTL")
	)
	(via
		(at 319.00368 -129.885948)
		(size 0.508)
		(drill 0.254)
		(layers "F.Cu" "B.Cu")
		(net "PECI_CPU_GTL")
	)
	(via
		(at 255.51384 -151.049228)
		(size 0.508)
		(drill 0.254)
		(layers "F.Cu" "B.Cu")
		(net "PECI_CPU_GTL")
	)
	(via
		(at 310.725058 -192.43421)
		(size 0.508)
		(drill 0.254)
		(layers "F.Cu" "B.Cu")
		(net "PECI_CPU_GTL")
	)
	(via
		(at 309.68188 -61.940948)
		(size 0.508)
		(drill 0.254)
		(layers "F.Cu" "B.Cu")
		(net "PECI_CPU_GTL")
	)
	(segment
		(start 74.55281 -182.60822)
		(end 74.55281 -181.113938)
		(width 0.12954)
		(layer "B.Cu")
		(net "PECI_CPU_GTL")
	)
	(segment
		(start 75.152758 -190.094616)
		(end 75.152758 -189.652656)
		(width 0.12954)
		(layer "B.Cu")
		(net "PECI_CPU_GTL")
	)
	(segment
		(start 255.51384 -151.049228)
		(end 255.51384 -159.281368)
		(width 0.12954)
		(layer "B.Cu")
		(net "PECI_CPU_GTL")
	)
	(segment
		(start 75.890374 -179.776374)
		(end 76.485242 -179.776374)
		(width 0.12954)
		(layer "B.Cu")
		(net "PECI_CPU_GTL")
	)
	(segment
		(start 308.878478 -188.45149)
		(end 308.878478 -189.99835)
		(width 0.12954)
		(layer "B.Cu")
		(net "PECI_CPU_GTL")
	)
	(segment
		(start 310.725058 -191.84493)
		(end 310.725058 -192.43421)
		(width 0.12954)
		(layer "B.Cu")
		(net "PECI_CPU_GTL")
	)
	(segment
		(start 79.664306 -174.471076)
		(end 108.052362 -146.08302)
		(width 0.12954)
		(layer "B.Cu")
		(net "PECI_CPU_GTL")
	)
	(segment
		(start 75.363324 -190.305182)
		(end 75.152758 -190.094616)
		(width 0.12954)
		(layer "B.Cu")
		(net "PECI_CPU_GTL")
	)
	(segment
		(start 255.51384 -159.281368)
		(end 274.555458 -178.322986)
		(width 0.12954)
		(layer "B.Cu")
		(net "PECI_CPU_GTL")
	)
	(segment
		(start 298.749974 -178.322986)
		(end 308.878478 -188.45149)
		(width 0.12954)
		(layer "B.Cu")
		(net "PECI_CPU_GTL")
	)
	(segment
		(start 310.725058 -192.97142)
		(end 310.567578 -193.1289)
		(width 0.12954)
		(layer "B.Cu")
		(net "PECI_CPU_GTL")
	)
	(segment
		(start 74.198988 -187.349384)
		(end 74.198988 -182.962042)
		(width 0.12954)
		(layer "B.Cu")
		(net "PECI_CPU_GTL")
	)
	(segment
		(start 274.555458 -178.322986)
		(end 298.749974 -178.322986)
		(width 0.12954)
		(layer "B.Cu")
		(net "PECI_CPU_GTL")
	)
	(segment
		(start 79.664306 -176.59731)
		(end 79.664306 -174.471076)
		(width 0.12954)
		(layer "B.Cu")
		(net "PECI_CPU_GTL")
	)
	(segment
		(start 75.152758 -189.652656)
		(end 74.198988 -187.349384)
		(width 0.12954)
		(layer "B.Cu")
		(net "PECI_CPU_GTL")
	)
	(segment
		(start 76.485242 -179.776374)
		(end 79.664306 -176.59731)
		(width 0.12954)
		(layer "B.Cu")
		(net "PECI_CPU_GTL")
	)
	(segment
		(start 310.725058 -192.43421)
		(end 310.725058 -192.97142)
		(width 0.12954)
		(layer "B.Cu")
		(net "PECI_CPU_GTL")
	)
	(segment
		(start 308.878478 -189.99835)
		(end 310.725058 -191.84493)
		(width 0.12954)
		(layer "B.Cu")
		(net "PECI_CPU_GTL")
	)
	(segment
		(start 108.052362 -146.08302)
		(end 137.62228 -146.08302)
		(width 0.12954)
		(layer "B.Cu")
		(net "PECI_CPU_GTL")
	)
	(segment
		(start 74.198988 -182.962042)
		(end 74.55281 -182.60822)
		(width 0.12954)
		(layer "B.Cu")
		(net "PECI_CPU_GTL")
	)
	(segment
		(start 74.55281 -181.113938)
		(end 75.890374 -179.776374)
		(width 0.12954)
		(layer "B.Cu")
		(net "PECI_CPU_GTL")
	)
	(segment
		(start 310.40832 -66.725292)
		(end 315.155326 -78.185518)
		(width 0.127)
		(layer "In2.Cu")
		(net "PECI_CPU_GTL")
	)
	(segment
		(start 310.03748 -61.940948)
		(end 310.40832 -62.311788)
		(width 0.127)
		(layer "In2.Cu")
		(net "PECI_CPU_GTL")
	)
	(segment
		(start 319.00368 -116.144548)
		(end 319.00368 -129.885948)
		(width 0.127)
		(layer "In2.Cu")
		(net "PECI_CPU_GTL")
	)
	(segment
		(start 319.71488 -115.433348)
		(end 319.00368 -116.144548)
		(width 0.127)
		(layer "In2.Cu")
		(net "PECI_CPU_GTL")
	)
	(segment
		(start 319.71488 -82.745072)
		(end 319.71488 -115.433348)
		(width 0.127)
		(layer "In2.Cu")
		(net "PECI_CPU_GTL")
	)
	(segment
		(start 309.68188 -61.940948)
		(end 310.03748 -61.940948)
		(width 0.127)
		(layer "In2.Cu")
		(net "PECI_CPU_GTL")
	)
	(segment
		(start 310.40832 -62.311788)
		(end 310.40832 -66.725292)
		(width 0.127)
		(layer "In2.Cu")
		(net "PECI_CPU_GTL")
	)
	(segment
		(start 315.155326 -78.185518)
		(end 319.71488 -82.745072)
		(width 0.127)
		(layer "In2.Cu")
		(net "PECI_CPU_GTL")
	)
	(segment
		(start 254.53086 -152.032208)
		(end 255.51384 -151.049228)
		(width 0.127)
		(layer "In13.Cu")
		(net "PECI_CPU_GTL")
	)
	(segment
		(start 187.121546 -160.518348)
		(end 207.008476 -160.518348)
		(width 0.127)
		(layer "In13.Cu")
		(net "PECI_CPU_GTL")
	)
	(segment
		(start 215.494616 -152.032208)
		(end 254.53086 -152.032208)
		(width 0.127)
		(layer "In13.Cu")
		(net "PECI_CPU_GTL")
	)
	(segment
		(start 173.405546 -146.802348)
		(end 187.121546 -160.518348)
		(width 0.127)
		(layer "In13.Cu")
		(net "PECI_CPU_GTL")
	)
	(segment
		(start 153.127202 -146.802348)
		(end 173.405546 -146.802348)
		(width 0.127)
		(layer "In13.Cu")
		(net "PECI_CPU_GTL")
	)
	(segment
		(start 141.132052 -142.573248)
		(end 148.898102 -142.573248)
		(width 0.127)
		(layer "In13.Cu")
		(net "PECI_CPU_GTL")
	)
	(segment
		(start 207.008476 -160.518348)
		(end 215.494616 -152.032208)
		(width 0.127)
		(layer "In13.Cu")
		(net "PECI_CPU_GTL")
	)
	(segment
		(start 148.898102 -142.573248)
		(end 153.127202 -146.802348)
		(width 0.127)
		(layer "In13.Cu")
		(net "PECI_CPU_GTL")
	)
	(segment
		(start 137.62228 -146.08302)
		(end 141.132052 -142.573248)
		(width 0.127)
		(layer "In13.Cu")
		(net "PECI_CPU_GTL")
	)
	(segment
		(start 106.941112 -233.064304)
		(end 106.941366 -233.06405)
		(width 0.12954)
		(layer "F.Cu")
		(net "PECI_CPU1_GTL_R")
	)
	(segment
		(start 106.941366 -233.06405)
		(end 106.941366 -232.528364)
		(width 0.12954)
		(layer "F.Cu")
		(net "PECI_CPU1_GTL_R")
	)
	(via
		(at 106.941366 -232.528364)
		(size 0.4572)
		(drill 0.2032)
		(layers "F.Cu" "B.Cu")
		(net "PECI_CPU1_GTL_R")
	)
	(via
		(at 73.380854 -196.619622)
		(size 0.6604)
		(drill 0.3302)
		(layers "F.Cu" "B.Cu")
		(net "PECI_CPU1_GTL_R")
	)
	(segment
		(start 69.709538 -222.35795)
		(end 68.393056 -221.041468)
		(width 0.12954)
		(layer "B.Cu")
		(net "PECI_CPU1_GTL_R")
	)
	(segment
		(start 105.344214 -233.017822)
		(end 105.329482 -233.026458)
		(width 0.0889)
		(layer "B.Cu")
		(net "PECI_CPU1_GTL_R")
	)
	(segment
		(start 71.869808 -200.66)
		(end 73.380854 -199.148954)
		(width 0.12954)
		(layer "B.Cu")
		(net "PECI_CPU1_GTL_R")
	)
	(segment
		(start 83.693762 -234.220766)
		(end 78.631034 -234.220766)
		(width 0.12954)
		(layer "B.Cu")
		(net "PECI_CPU1_GTL_R")
	)
	(segment
		(start 91.247468 -233.017822)
		(end 91.237054 -233.023918)
		(width 0.0889)
		(layer "B.Cu")
		(net "PECI_CPU1_GTL_R")
	)
	(segment
		(start 106.628692 -232.528364)
		(end 106.562906 -232.59415)
		(width 0.0889)
		(layer "B.Cu")
		(net "PECI_CPU1_GTL_R")
	)
	(segment
		(start 85.480652 -233.239056)
		(end 85.073998 -233.64571)
		(width 0.0889)
		(layer "B.Cu")
		(net "PECI_CPU1_GTL_R")
	)
	(segment
		(start 73.380854 -196.619622)
		(end 73.380854 -193.876168)
		(width 0.12954)
		(layer "B.Cu")
		(net "PECI_CPU1_GTL_R")
	)
	(segment
		(start 84.142072 -233.772456)
		(end 83.693762 -234.220766)
		(width 0.12954)
		(layer "B.Cu")
		(net "PECI_CPU1_GTL_R")
	)
	(segment
		(start 78.631034 -234.220766)
		(end 69.709538 -225.29927)
		(width 0.12954)
		(layer "B.Cu")
		(net "PECI_CPU1_GTL_R")
	)
	(segment
		(start 69.51218 -204.185774)
		(end 71.869808 -201.828146)
		(width 0.12954)
		(layer "B.Cu")
		(net "PECI_CPU1_GTL_R")
	)
	(segment
		(start 101.585014 -233.017822)
		(end 101.570282 -233.026458)
		(width 0.0889)
		(layer "B.Cu")
		(net "PECI_CPU1_GTL_R")
	)
	(segment
		(start 95.006414 -233.017822)
		(end 94.991682 -233.026458)
		(width 0.0889)
		(layer "B.Cu")
		(net "PECI_CPU1_GTL_R")
	)
	(segment
		(start 91.632278 -233.023918)
		(end 91.621864 -233.017822)
		(width 0.0889)
		(layer "B.Cu")
		(net "PECI_CPU1_GTL_R")
	)
	(segment
		(start 102.524814 -233.017822)
		(end 102.510082 -233.026458)
		(width 0.0889)
		(layer "B.Cu")
		(net "PECI_CPU1_GTL_R")
	)
	(segment
		(start 68.393056 -206.794862)
		(end 69.51218 -205.675738)
		(width 0.12954)
		(layer "B.Cu")
		(net "PECI_CPU1_GTL_R")
	)
	(segment
		(start 71.869808 -201.828146)
		(end 71.869808 -200.66)
		(width 0.12954)
		(layer "B.Cu")
		(net "PECI_CPU1_GTL_R")
	)
	(segment
		(start 95.946214 -233.017822)
		(end 95.931482 -233.026458)
		(width 0.0889)
		(layer "B.Cu")
		(net "PECI_CPU1_GTL_R")
	)
	(segment
		(start 73.380854 -193.876168)
		(end 75.363324 -191.893698)
		(width 0.12954)
		(layer "B.Cu")
		(net "PECI_CPU1_GTL_R")
	)
	(segment
		(start 103.464614 -233.017822)
		(end 103.449882 -233.026458)
		(width 0.0889)
		(layer "B.Cu")
		(net "PECI_CPU1_GTL_R")
	)
	(segment
		(start 85.073998 -233.64571)
		(end 84.268818 -233.64571)
		(width 0.0889)
		(layer "B.Cu")
		(net "PECI_CPU1_GTL_R")
	)
	(segment
		(start 106.941366 -232.528364)
		(end 106.628692 -232.528364)
		(width 0.0889)
		(layer "B.Cu")
		(net "PECI_CPU1_GTL_R")
	)
	(segment
		(start 73.380854 -199.148954)
		(end 73.380854 -196.619622)
		(width 0.12954)
		(layer "B.Cu")
		(net "PECI_CPU1_GTL_R")
	)
	(segment
		(start 93.126814 -233.017822)
		(end 93.112082 -233.026458)
		(width 0.0889)
		(layer "B.Cu")
		(net "PECI_CPU1_GTL_R")
	)
	(segment
		(start 75.363324 -191.893698)
		(end 75.363324 -191.105282)
		(width 0.12954)
		(layer "B.Cu")
		(net "PECI_CPU1_GTL_R")
	)
	(segment
		(start 106.29011 -233.014266)
		(end 106.284014 -233.017822)
		(width 0.0889)
		(layer "B.Cu")
		(net "PECI_CPU1_GTL_R")
	)
	(segment
		(start 86.662514 -233.239056)
		(end 85.480652 -233.239056)
		(width 0.0889)
		(layer "B.Cu")
		(net "PECI_CPU1_GTL_R")
	)
	(segment
		(start 100.645214 -233.017822)
		(end 100.630482 -233.026458)
		(width 0.0889)
		(layer "B.Cu")
		(net "PECI_CPU1_GTL_R")
	)
	(segment
		(start 84.268818 -233.64571)
		(end 84.142072 -233.772456)
		(width 0.0889)
		(layer "B.Cu")
		(net "PECI_CPU1_GTL_R")
	)
	(segment
		(start 90.307414 -233.017822)
		(end 90.292682 -233.026458)
		(width 0.0889)
		(layer "B.Cu")
		(net "PECI_CPU1_GTL_R")
	)
	(segment
		(start 88.427814 -233.017822)
		(end 88.4174 -233.023918)
		(width 0.0889)
		(layer "B.Cu")
		(net "PECI_CPU1_GTL_R")
	)
	(segment
		(start 89.367614 -233.017822)
		(end 89.352882 -233.026458)
		(width 0.0889)
		(layer "B.Cu")
		(net "PECI_CPU1_GTL_R")
	)
	(segment
		(start 68.393056 -221.041468)
		(end 68.393056 -206.794862)
		(width 0.12954)
		(layer "B.Cu")
		(net "PECI_CPU1_GTL_R")
	)
	(segment
		(start 97.826068 -233.017822)
		(end 97.815654 -233.023918)
		(width 0.0889)
		(layer "B.Cu")
		(net "PECI_CPU1_GTL_R")
	)
	(segment
		(start 94.066614 -233.017822)
		(end 94.051882 -233.026458)
		(width 0.0889)
		(layer "B.Cu")
		(net "PECI_CPU1_GTL_R")
	)
	(segment
		(start 98.210878 -233.023918)
		(end 98.200464 -233.017822)
		(width 0.0889)
		(layer "B.Cu")
		(net "PECI_CPU1_GTL_R")
	)
	(segment
		(start 104.404414 -233.017822)
		(end 104.389682 -233.026458)
		(width 0.0889)
		(layer "B.Cu")
		(net "PECI_CPU1_GTL_R")
	)
	(segment
		(start 69.709538 -225.29927)
		(end 69.709538 -222.35795)
		(width 0.12954)
		(layer "B.Cu")
		(net "PECI_CPU1_GTL_R")
	)
	(segment
		(start 96.886014 -233.017822)
		(end 96.871282 -233.026458)
		(width 0.0889)
		(layer "B.Cu")
		(net "PECI_CPU1_GTL_R")
	)
	(segment
		(start 99.705414 -233.017822)
		(end 99.690682 -233.026458)
		(width 0.0889)
		(layer "B.Cu")
		(net "PECI_CPU1_GTL_R")
	)
	(segment
		(start 106.284014 -233.017822)
		(end 106.269282 -233.026458)
		(width 0.0889)
		(layer "B.Cu")
		(net "PECI_CPU1_GTL_R")
	)
	(segment
		(start 69.51218 -205.675738)
		(end 69.51218 -204.185774)
		(width 0.12954)
		(layer "B.Cu")
		(net "PECI_CPU1_GTL_R")
	)
	(arc
		(start 102.510082 -233.026458)
		(mid 102.233607 -233.093778)
		(end 101.95941 -233.017822)
		(width 0.0889)
		(layer "B.Cu")
		(net "PECI_CPU1_GTL_R")
	)
	(arc
		(start 98.200464 -233.017822)
		(mid 98.013266 -232.967679)
		(end 97.826068 -233.017822)
		(width 0.0889)
		(layer "B.Cu")
		(net "PECI_CPU1_GTL_R")
	)
	(arc
		(start 105.71861 -233.017822)
		(mid 105.531412 -232.967679)
		(end 105.344214 -233.017822)
		(width 0.0889)
		(layer "B.Cu")
		(net "PECI_CPU1_GTL_R")
	)
	(arc
		(start 101.01961 -233.017822)
		(mid 100.832412 -232.967679)
		(end 100.645214 -233.017822)
		(width 0.0889)
		(layer "B.Cu")
		(net "PECI_CPU1_GTL_R")
	)
	(arc
		(start 90.292682 -233.026458)
		(mid 90.016207 -233.093778)
		(end 89.74201 -233.017822)
		(width 0.0889)
		(layer "B.Cu")
		(net "PECI_CPU1_GTL_R")
	)
	(arc
		(start 100.07981 -233.017822)
		(mid 99.892612 -232.967679)
		(end 99.705414 -233.017822)
		(width 0.0889)
		(layer "B.Cu")
		(net "PECI_CPU1_GTL_R")
	)
	(arc
		(start 98.765614 -233.017822)
		(mid 98.489055 -233.093565)
		(end 98.210878 -233.023918)
		(width 0.0889)
		(layer "B.Cu")
		(net "PECI_CPU1_GTL_R")
	)
	(arc
		(start 94.44101 -233.017822)
		(mid 94.253812 -232.967679)
		(end 94.066614 -233.017822)
		(width 0.0889)
		(layer "B.Cu")
		(net "PECI_CPU1_GTL_R")
	)
	(arc
		(start 103.449882 -233.026458)
		(mid 103.173407 -233.093778)
		(end 102.89921 -233.017822)
		(width 0.0889)
		(layer "B.Cu")
		(net "PECI_CPU1_GTL_R")
	)
	(arc
		(start 92.56141 -233.017822)
		(mid 92.374212 -232.967679)
		(end 92.187014 -233.017822)
		(width 0.0889)
		(layer "B.Cu")
		(net "PECI_CPU1_GTL_R")
	)
	(arc
		(start 99.690682 -233.026458)
		(mid 99.414207 -233.093778)
		(end 99.14001 -233.017822)
		(width 0.0889)
		(layer "B.Cu")
		(net "PECI_CPU1_GTL_R")
	)
	(arc
		(start 101.570282 -233.026458)
		(mid 101.293807 -233.093778)
		(end 101.01961 -233.017822)
		(width 0.0889)
		(layer "B.Cu")
		(net "PECI_CPU1_GTL_R")
	)
	(arc
		(start 88.4174 -233.023918)
		(mid 88.139222 -233.093641)
		(end 87.862664 -233.017822)
		(width 0.0889)
		(layer "B.Cu")
		(net "PECI_CPU1_GTL_R")
	)
	(arc
		(start 89.74201 -233.017822)
		(mid 89.554812 -232.967679)
		(end 89.367614 -233.017822)
		(width 0.0889)
		(layer "B.Cu")
		(net "PECI_CPU1_GTL_R")
	)
	(arc
		(start 91.237054 -233.023918)
		(mid 90.958622 -233.093764)
		(end 90.68181 -233.017822)
		(width 0.0889)
		(layer "B.Cu")
		(net "PECI_CPU1_GTL_R")
	)
	(arc
		(start 94.991682 -233.026458)
		(mid 94.715207 -233.093778)
		(end 94.44101 -233.017822)
		(width 0.0889)
		(layer "B.Cu")
		(net "PECI_CPU1_GTL_R")
	)
	(arc
		(start 89.352882 -233.026458)
		(mid 89.076407 -233.093778)
		(end 88.80221 -233.017822)
		(width 0.0889)
		(layer "B.Cu")
		(net "PECI_CPU1_GTL_R")
	)
	(arc
		(start 91.621864 -233.017822)
		(mid 91.434666 -232.967679)
		(end 91.247468 -233.017822)
		(width 0.0889)
		(layer "B.Cu")
		(net "PECI_CPU1_GTL_R")
	)
	(arc
		(start 87.862664 -233.017822)
		(mid 87.675466 -232.967679)
		(end 87.488268 -233.017822)
		(width 0.0889)
		(layer "B.Cu")
		(net "PECI_CPU1_GTL_R")
	)
	(arc
		(start 90.68181 -233.017822)
		(mid 90.494612 -232.967679)
		(end 90.307414 -233.017822)
		(width 0.0889)
		(layer "B.Cu")
		(net "PECI_CPU1_GTL_R")
	)
	(arc
		(start 104.389682 -233.026458)
		(mid 104.113207 -233.093778)
		(end 103.83901 -233.017822)
		(width 0.0889)
		(layer "B.Cu")
		(net "PECI_CPU1_GTL_R")
	)
	(arc
		(start 102.89921 -233.017822)
		(mid 102.712012 -232.967679)
		(end 102.524814 -233.017822)
		(width 0.0889)
		(layer "B.Cu")
		(net "PECI_CPU1_GTL_R")
	)
	(arc
		(start 96.32061 -233.017822)
		(mid 96.133412 -232.967679)
		(end 95.946214 -233.017822)
		(width 0.0889)
		(layer "B.Cu")
		(net "PECI_CPU1_GTL_R")
	)
	(arc
		(start 87.488268 -233.017822)
		(mid 87.089946 -233.182756)
		(end 86.662514 -233.239056)
		(width 0.0889)
		(layer "B.Cu")
		(net "PECI_CPU1_GTL_R")
	)
	(arc
		(start 96.871282 -233.026458)
		(mid 96.594807 -233.093778)
		(end 96.32061 -233.017822)
		(width 0.0889)
		(layer "B.Cu")
		(net "PECI_CPU1_GTL_R")
	)
	(arc
		(start 95.931482 -233.026458)
		(mid 95.655007 -233.093778)
		(end 95.38081 -233.017822)
		(width 0.0889)
		(layer "B.Cu")
		(net "PECI_CPU1_GTL_R")
	)
	(arc
		(start 106.562906 -232.59415)
		(mid 106.475618 -232.836106)
		(end 106.29011 -233.014266)
		(width 0.0889)
		(layer "B.Cu")
		(net "PECI_CPU1_GTL_R")
	)
	(arc
		(start 99.14001 -233.017822)
		(mid 98.952812 -232.967679)
		(end 98.765614 -233.017822)
		(width 0.0889)
		(layer "B.Cu")
		(net "PECI_CPU1_GTL_R")
	)
	(arc
		(start 97.26041 -233.017822)
		(mid 97.073212 -232.967679)
		(end 96.886014 -233.017822)
		(width 0.0889)
		(layer "B.Cu")
		(net "PECI_CPU1_GTL_R")
	)
	(arc
		(start 95.38081 -233.017822)
		(mid 95.193612 -232.967679)
		(end 95.006414 -233.017822)
		(width 0.0889)
		(layer "B.Cu")
		(net "PECI_CPU1_GTL_R")
	)
	(arc
		(start 93.50121 -233.017822)
		(mid 93.314012 -232.967679)
		(end 93.126814 -233.017822)
		(width 0.0889)
		(layer "B.Cu")
		(net "PECI_CPU1_GTL_R")
	)
	(arc
		(start 88.80221 -233.017822)
		(mid 88.615012 -232.967679)
		(end 88.427814 -233.017822)
		(width 0.0889)
		(layer "B.Cu")
		(net "PECI_CPU1_GTL_R")
	)
	(arc
		(start 103.83901 -233.017822)
		(mid 103.651812 -232.967679)
		(end 103.464614 -233.017822)
		(width 0.0889)
		(layer "B.Cu")
		(net "PECI_CPU1_GTL_R")
	)
	(arc
		(start 105.329482 -233.026458)
		(mid 105.053007 -233.093778)
		(end 104.77881 -233.017822)
		(width 0.0889)
		(layer "B.Cu")
		(net "PECI_CPU1_GTL_R")
	)
	(arc
		(start 97.815654 -233.023918)
		(mid 97.537222 -233.093764)
		(end 97.26041 -233.017822)
		(width 0.0889)
		(layer "B.Cu")
		(net "PECI_CPU1_GTL_R")
	)
	(arc
		(start 94.051882 -233.026458)
		(mid 93.775407 -233.093778)
		(end 93.50121 -233.017822)
		(width 0.0889)
		(layer "B.Cu")
		(net "PECI_CPU1_GTL_R")
	)
	(arc
		(start 100.630482 -233.026458)
		(mid 100.354007 -233.093778)
		(end 100.07981 -233.017822)
		(width 0.0889)
		(layer "B.Cu")
		(net "PECI_CPU1_GTL_R")
	)
	(arc
		(start 93.112082 -233.026458)
		(mid 92.835607 -233.093778)
		(end 92.56141 -233.017822)
		(width 0.0889)
		(layer "B.Cu")
		(net "PECI_CPU1_GTL_R")
	)
	(arc
		(start 101.95941 -233.017822)
		(mid 101.772212 -232.967679)
		(end 101.585014 -233.017822)
		(width 0.0889)
		(layer "B.Cu")
		(net "PECI_CPU1_GTL_R")
	)
	(arc
		(start 104.77881 -233.017822)
		(mid 104.591612 -232.967679)
		(end 104.404414 -233.017822)
		(width 0.0889)
		(layer "B.Cu")
		(net "PECI_CPU1_GTL_R")
	)
	(arc
		(start 92.187014 -233.017822)
		(mid 91.910455 -233.093565)
		(end 91.632278 -233.023918)
		(width 0.0889)
		(layer "B.Cu")
		(net "PECI_CPU1_GTL_R")
	)
	(arc
		(start 106.269282 -233.026458)
		(mid 105.992807 -233.093778)
		(end 105.71861 -233.017822)
		(width 0.0889)
		(layer "B.Cu")
		(net "PECI_CPU1_GTL_R")
	)
	(segment
		(start 354.881434 -233.06405)
		(end 354.881434 -232.528364)
		(width 0.12954)
		(layer "F.Cu")
		(net "PECI_CPU0_GTL_R")
	)
	(segment
		(start 354.88118 -233.064304)
		(end 354.881434 -233.06405)
		(width 0.12954)
		(layer "F.Cu")
		(net "PECI_CPU0_GTL_R")
	)
	(via
		(at 354.881434 -232.528364)
		(size 0.4572)
		(drill 0.2032)
		(layers "F.Cu" "B.Cu")
		(net "PECI_CPU0_GTL_R")
	)
	(via
		(at 318.23152 -234.81411)
		(size 0.6604)
		(drill 0.3302)
		(layers "F.Cu" "B.Cu")
		(net "PECI_CPU0_GTL_R")
	)
	(segment
		(start 339.187536 -233.017822)
		(end 339.177122 -233.023918)
		(width 0.0889)
		(layer "B.Cu")
		(net "PECI_CPU0_GTL_R")
	)
	(segment
		(start 331.804772 -233.66349)
		(end 331.350112 -234.11815)
		(width 0.12954)
		(layer "B.Cu")
		(net "PECI_CPU0_GTL_R")
	)
	(segment
		(start 309.762144 -205.959964)
		(end 310.567578 -205.15453)
		(width 0.12954)
		(layer "B.Cu")
		(net "PECI_CPU0_GTL_R")
	)
	(segment
		(start 310.587898 -216.38133)
		(end 310.587898 -209.88401)
		(width 0.12954)
		(layer "B.Cu")
		(net "PECI_CPU0_GTL_R")
	)
	(segment
		(start 338.247482 -233.017822)
		(end 338.23275 -233.026458)
		(width 0.0889)
		(layer "B.Cu")
		(net "PECI_CPU0_GTL_R")
	)
	(segment
		(start 347.645482 -233.017822)
		(end 347.63075 -233.026458)
		(width 0.0889)
		(layer "B.Cu")
		(net "PECI_CPU0_GTL_R")
	)
	(segment
		(start 354.881434 -232.528364)
		(end 354.02012 -233.088434)
		(width 0.0889)
		(layer "B.Cu")
		(net "PECI_CPU0_GTL_R")
	)
	(segment
		(start 318.23152 -234.81411)
		(end 317.75908 -234.34167)
		(width 0.12954)
		(layer "B.Cu")
		(net "PECI_CPU0_GTL_R")
	)
	(segment
		(start 331.350112 -234.11815)
		(end 328.240898 -234.11815)
		(width 0.12954)
		(layer "B.Cu")
		(net "PECI_CPU0_GTL_R")
	)
	(segment
		(start 317.75908 -234.34167)
		(end 313.790838 -234.34167)
		(width 0.12954)
		(layer "B.Cu")
		(net "PECI_CPU0_GTL_R")
	)
	(segment
		(start 328.240898 -234.11815)
		(end 327.544938 -234.81411)
		(width 0.12954)
		(layer "B.Cu")
		(net "PECI_CPU0_GTL_R")
	)
	(segment
		(start 309.637938 -217.33129)
		(end 310.587898 -216.38133)
		(width 0.12954)
		(layer "B.Cu")
		(net "PECI_CPU0_GTL_R")
	)
	(segment
		(start 336.367882 -233.017822)
		(end 336.357468 -233.023918)
		(width 0.0889)
		(layer "B.Cu")
		(net "PECI_CPU0_GTL_R")
	)
	(segment
		(start 351.404682 -233.017822)
		(end 351.38995 -233.026458)
		(width 0.0889)
		(layer "B.Cu")
		(net "PECI_CPU0_GTL_R")
	)
	(segment
		(start 312.688478 -233.23931)
		(end 312.165238 -233.23931)
		(width 0.12954)
		(layer "B.Cu")
		(net "PECI_CPU0_GTL_R")
	)
	(segment
		(start 309.637938 -220.64345)
		(end 309.637938 -217.33129)
		(width 0.12954)
		(layer "B.Cu")
		(net "PECI_CPU0_GTL_R")
	)
	(segment
		(start 313.790838 -234.34167)
		(end 312.688478 -233.23931)
		(width 0.12954)
		(layer "B.Cu")
		(net "PECI_CPU0_GTL_R")
	)
	(segment
		(start 353.284282 -233.017822)
		(end 353.26955 -233.026458)
		(width 0.0889)
		(layer "B.Cu")
		(net "PECI_CPU0_GTL_R")
	)
	(segment
		(start 312.165238 -233.23931)
		(end 310.608218 -231.68229)
		(width 0.12954)
		(layer "B.Cu")
		(net "PECI_CPU0_GTL_R")
	)
	(segment
		(start 339.572346 -233.023918)
		(end 339.561932 -233.017822)
		(width 0.0889)
		(layer "B.Cu")
		(net "PECI_CPU0_GTL_R")
	)
	(segment
		(start 350.464882 -233.017822)
		(end 350.45015 -233.026458)
		(width 0.0889)
		(layer "B.Cu")
		(net "PECI_CPU0_GTL_R")
	)
	(segment
		(start 309.762144 -209.058256)
		(end 309.762144 -205.959964)
		(width 0.12954)
		(layer "B.Cu")
		(net "PECI_CPU0_GTL_R")
	)
	(segment
		(start 335.145634 -233.093514)
		(end 334.771492 -233.467656)
		(width 0.0889)
		(layer "B.Cu")
		(net "PECI_CPU0_GTL_R")
	)
	(segment
		(start 352.344482 -233.017822)
		(end 352.32975 -233.026458)
		(width 0.0889)
		(layer "B.Cu")
		(net "PECI_CPU0_GTL_R")
	)
	(segment
		(start 334.771492 -233.467656)
		(end 332.000606 -233.467656)
		(width 0.0889)
		(layer "B.Cu")
		(net "PECI_CPU0_GTL_R")
	)
	(segment
		(start 342.006682 -233.017822)
		(end 341.99195 -233.026458)
		(width 0.0889)
		(layer "B.Cu")
		(net "PECI_CPU0_GTL_R")
	)
	(segment
		(start 346.150946 -233.023918)
		(end 346.140532 -233.017822)
		(width 0.0889)
		(layer "B.Cu")
		(net "PECI_CPU0_GTL_R")
	)
	(segment
		(start 310.567578 -205.15453)
		(end 310.567578 -193.929)
		(width 0.12954)
		(layer "B.Cu")
		(net "PECI_CPU0_GTL_R")
	)
	(segment
		(start 310.587898 -209.88401)
		(end 309.762144 -209.058256)
		(width 0.12954)
		(layer "B.Cu")
		(net "PECI_CPU0_GTL_R")
	)
	(segment
		(start 348.585282 -233.017822)
		(end 348.57055 -233.026458)
		(width 0.0889)
		(layer "B.Cu")
		(net "PECI_CPU0_GTL_R")
	)
	(segment
		(start 310.608218 -231.68229)
		(end 310.608218 -221.61373)
		(width 0.12954)
		(layer "B.Cu")
		(net "PECI_CPU0_GTL_R")
	)
	(segment
		(start 327.544938 -234.81411)
		(end 318.23152 -234.81411)
		(width 0.12954)
		(layer "B.Cu")
		(net "PECI_CPU0_GTL_R")
	)
	(segment
		(start 310.608218 -221.61373)
		(end 309.637938 -220.64345)
		(width 0.12954)
		(layer "B.Cu")
		(net "PECI_CPU0_GTL_R")
	)
	(segment
		(start 332.000606 -233.467656)
		(end 331.804772 -233.66349)
		(width 0.0889)
		(layer "B.Cu")
		(net "PECI_CPU0_GTL_R")
	)
	(segment
		(start 342.946482 -233.017822)
		(end 342.93175 -233.026458)
		(width 0.0889)
		(layer "B.Cu")
		(net "PECI_CPU0_GTL_R")
	)
	(segment
		(start 343.886282 -233.017822)
		(end 343.87155 -233.026458)
		(width 0.0889)
		(layer "B.Cu")
		(net "PECI_CPU0_GTL_R")
	)
	(segment
		(start 341.066882 -233.017822)
		(end 341.05215 -233.026458)
		(width 0.0889)
		(layer "B.Cu")
		(net "PECI_CPU0_GTL_R")
	)
	(segment
		(start 337.307682 -233.017822)
		(end 337.29295 -233.026458)
		(width 0.0889)
		(layer "B.Cu")
		(net "PECI_CPU0_GTL_R")
	)
	(segment
		(start 344.826082 -233.017822)
		(end 344.81135 -233.026458)
		(width 0.0889)
		(layer "B.Cu")
		(net "PECI_CPU0_GTL_R")
	)
	(segment
		(start 349.525082 -233.017822)
		(end 349.51035 -233.026458)
		(width 0.0889)
		(layer "B.Cu")
		(net "PECI_CPU0_GTL_R")
	)
	(segment
		(start 345.766136 -233.017822)
		(end 345.755722 -233.023918)
		(width 0.0889)
		(layer "B.Cu")
		(net "PECI_CPU0_GTL_R")
	)
	(arc
		(start 352.32975 -233.026458)
		(mid 352.053275 -233.093778)
		(end 351.779078 -233.017822)
		(width 0.0889)
		(layer "B.Cu")
		(net "PECI_CPU0_GTL_R")
	)
	(arc
		(start 349.51035 -233.026458)
		(mid 349.233875 -233.093778)
		(end 348.959678 -233.017822)
		(width 0.0889)
		(layer "B.Cu")
		(net "PECI_CPU0_GTL_R")
	)
	(arc
		(start 338.23275 -233.026458)
		(mid 337.956275 -233.093778)
		(end 337.682078 -233.017822)
		(width 0.0889)
		(layer "B.Cu")
		(net "PECI_CPU0_GTL_R")
	)
	(arc
		(start 341.441278 -233.017822)
		(mid 341.25408 -232.967679)
		(end 341.066882 -233.017822)
		(width 0.0889)
		(layer "B.Cu")
		(net "PECI_CPU0_GTL_R")
	)
	(arc
		(start 350.839278 -233.017822)
		(mid 350.65208 -232.967679)
		(end 350.464882 -233.017822)
		(width 0.0889)
		(layer "B.Cu")
		(net "PECI_CPU0_GTL_R")
	)
	(arc
		(start 346.140532 -233.017822)
		(mid 345.953334 -232.967679)
		(end 345.766136 -233.017822)
		(width 0.0889)
		(layer "B.Cu")
		(net "PECI_CPU0_GTL_R")
	)
	(arc
		(start 337.29295 -233.026458)
		(mid 337.016475 -233.093778)
		(end 336.742278 -233.017822)
		(width 0.0889)
		(layer "B.Cu")
		(net "PECI_CPU0_GTL_R")
	)
	(arc
		(start 342.93175 -233.026458)
		(mid 342.655275 -233.093778)
		(end 342.381078 -233.017822)
		(width 0.0889)
		(layer "B.Cu")
		(net "PECI_CPU0_GTL_R")
	)
	(arc
		(start 343.320878 -233.017822)
		(mid 343.13368 -232.967679)
		(end 342.946482 -233.017822)
		(width 0.0889)
		(layer "B.Cu")
		(net "PECI_CPU0_GTL_R")
	)
	(arc
		(start 340.127082 -233.017822)
		(mid 339.850523 -233.093565)
		(end 339.572346 -233.023918)
		(width 0.0889)
		(layer "B.Cu")
		(net "PECI_CPU0_GTL_R")
	)
	(arc
		(start 340.501478 -233.017822)
		(mid 340.31428 -232.967679)
		(end 340.127082 -233.017822)
		(width 0.0889)
		(layer "B.Cu")
		(net "PECI_CPU0_GTL_R")
	)
	(arc
		(start 353.26955 -233.026458)
		(mid 352.993075 -233.093778)
		(end 352.718878 -233.017822)
		(width 0.0889)
		(layer "B.Cu")
		(net "PECI_CPU0_GTL_R")
	)
	(arc
		(start 354.02012 -233.088434)
		(mid 353.833486 -233.083384)
		(end 353.658678 -233.017822)
		(width 0.0889)
		(layer "B.Cu")
		(net "PECI_CPU0_GTL_R")
	)
	(arc
		(start 352.718878 -233.017822)
		(mid 352.53168 -232.967679)
		(end 352.344482 -233.017822)
		(width 0.0889)
		(layer "B.Cu")
		(net "PECI_CPU0_GTL_R")
	)
	(arc
		(start 346.705682 -233.017822)
		(mid 346.429123 -233.093565)
		(end 346.150946 -233.023918)
		(width 0.0889)
		(layer "B.Cu")
		(net "PECI_CPU0_GTL_R")
	)
	(arc
		(start 348.019878 -233.017822)
		(mid 347.83268 -232.967679)
		(end 347.645482 -233.017822)
		(width 0.0889)
		(layer "B.Cu")
		(net "PECI_CPU0_GTL_R")
	)
	(arc
		(start 342.381078 -233.017822)
		(mid 342.19388 -232.967679)
		(end 342.006682 -233.017822)
		(width 0.0889)
		(layer "B.Cu")
		(net "PECI_CPU0_GTL_R")
	)
	(arc
		(start 339.561932 -233.017822)
		(mid 339.374734 -232.967679)
		(end 339.187536 -233.017822)
		(width 0.0889)
		(layer "B.Cu")
		(net "PECI_CPU0_GTL_R")
	)
	(arc
		(start 339.177122 -233.023918)
		(mid 338.89869 -233.093764)
		(end 338.621878 -233.017822)
		(width 0.0889)
		(layer "B.Cu")
		(net "PECI_CPU0_GTL_R")
	)
	(arc
		(start 335.802732 -233.017822)
		(mid 335.615534 -232.967679)
		(end 335.428336 -233.017822)
		(width 0.0889)
		(layer "B.Cu")
		(net "PECI_CPU0_GTL_R")
	)
	(arc
		(start 348.959678 -233.017822)
		(mid 348.77248 -232.967679)
		(end 348.585282 -233.017822)
		(width 0.0889)
		(layer "B.Cu")
		(net "PECI_CPU0_GTL_R")
	)
	(arc
		(start 341.99195 -233.026458)
		(mid 341.715475 -233.093778)
		(end 341.441278 -233.017822)
		(width 0.0889)
		(layer "B.Cu")
		(net "PECI_CPU0_GTL_R")
	)
	(arc
		(start 336.357468 -233.023918)
		(mid 336.07929 -233.093641)
		(end 335.802732 -233.017822)
		(width 0.0889)
		(layer "B.Cu")
		(net "PECI_CPU0_GTL_R")
	)
	(arc
		(start 344.260678 -233.017822)
		(mid 344.07348 -232.967679)
		(end 343.886282 -233.017822)
		(width 0.0889)
		(layer "B.Cu")
		(net "PECI_CPU0_GTL_R")
	)
	(arc
		(start 349.899478 -233.017822)
		(mid 349.71228 -232.967679)
		(end 349.525082 -233.017822)
		(width 0.0889)
		(layer "B.Cu")
		(net "PECI_CPU0_GTL_R")
	)
	(arc
		(start 338.621878 -233.017822)
		(mid 338.43468 -232.967679)
		(end 338.247482 -233.017822)
		(width 0.0889)
		(layer "B.Cu")
		(net "PECI_CPU0_GTL_R")
	)
	(arc
		(start 343.87155 -233.026458)
		(mid 343.595075 -233.093778)
		(end 343.320878 -233.017822)
		(width 0.0889)
		(layer "B.Cu")
		(net "PECI_CPU0_GTL_R")
	)
	(arc
		(start 335.428336 -233.017822)
		(mid 335.291967 -233.074264)
		(end 335.145634 -233.093514)
		(width 0.0889)
		(layer "B.Cu")
		(net "PECI_CPU0_GTL_R")
	)
	(arc
		(start 347.63075 -233.026458)
		(mid 347.354275 -233.093778)
		(end 347.080078 -233.017822)
		(width 0.0889)
		(layer "B.Cu")
		(net "PECI_CPU0_GTL_R")
	)
	(arc
		(start 336.742278 -233.017822)
		(mid 336.55508 -232.967679)
		(end 336.367882 -233.017822)
		(width 0.0889)
		(layer "B.Cu")
		(net "PECI_CPU0_GTL_R")
	)
	(arc
		(start 345.755722 -233.023918)
		(mid 345.47729 -233.093764)
		(end 345.200478 -233.017822)
		(width 0.0889)
		(layer "B.Cu")
		(net "PECI_CPU0_GTL_R")
	)
	(arc
		(start 347.080078 -233.017822)
		(mid 346.89288 -232.967679)
		(end 346.705682 -233.017822)
		(width 0.0889)
		(layer "B.Cu")
		(net "PECI_CPU0_GTL_R")
	)
	(arc
		(start 348.57055 -233.026458)
		(mid 348.294075 -233.093778)
		(end 348.019878 -233.017822)
		(width 0.0889)
		(layer "B.Cu")
		(net "PECI_CPU0_GTL_R")
	)
	(arc
		(start 344.81135 -233.026458)
		(mid 344.534875 -233.093778)
		(end 344.260678 -233.017822)
		(width 0.0889)
		(layer "B.Cu")
		(net "PECI_CPU0_GTL_R")
	)
	(arc
		(start 341.05215 -233.026458)
		(mid 340.775675 -233.093778)
		(end 340.501478 -233.017822)
		(width 0.0889)
		(layer "B.Cu")
		(net "PECI_CPU0_GTL_R")
	)
	(arc
		(start 350.45015 -233.026458)
		(mid 350.173675 -233.093778)
		(end 349.899478 -233.017822)
		(width 0.0889)
		(layer "B.Cu")
		(net "PECI_CPU0_GTL_R")
	)
	(arc
		(start 353.658678 -233.017822)
		(mid 353.47148 -232.967679)
		(end 353.284282 -233.017822)
		(width 0.0889)
		(layer "B.Cu")
		(net "PECI_CPU0_GTL_R")
	)
	(arc
		(start 337.682078 -233.017822)
		(mid 337.49488 -232.967679)
		(end 337.307682 -233.017822)
		(width 0.0889)
		(layer "B.Cu")
		(net "PECI_CPU0_GTL_R")
	)
	(arc
		(start 351.779078 -233.017822)
		(mid 351.59188 -232.967679)
		(end 351.404682 -233.017822)
		(width 0.0889)
		(layer "B.Cu")
		(net "PECI_CPU0_GTL_R")
	)
	(arc
		(start 345.200478 -233.017822)
		(mid 345.01328 -232.967679)
		(end 344.826082 -233.017822)
		(width 0.0889)
		(layer "B.Cu")
		(net "PECI_CPU0_GTL_R")
	)
	(arc
		(start 351.38995 -233.026458)
		(mid 351.113475 -233.093778)
		(end 350.839278 -233.017822)
		(width 0.0889)
		(layer "B.Cu")
		(net "PECI_CPU0_GTL_R")
	)
	(segment
		(start 302.874426 -56.987948)
		(end 306.411376 -53.450998)
		(width 0.12954)
		(layer "F.Cu")
		(net "PECI_BMC_R")
	)
	(segment
		(start 170.55973 -24.113998)
		(end 167.386 -24.113998)
		(width 0.12954)
		(layer "F.Cu")
		(net "PECI_BMC_R")
	)
	(segment
		(start 301.9044 -57.394348)
		(end 302.3108 -56.987948)
		(width 0.12954)
		(layer "F.Cu")
		(net "PECI_BMC_R")
	)
	(segment
		(start 171.236386 -23.437342)
		(end 170.55973 -24.113998)
		(width 0.12954)
		(layer "F.Cu")
		(net "PECI_BMC_R")
	)
	(segment
		(start 171.192698 -22.266148)
		(end 171.236386 -22.309836)
		(width 0.12954)
		(layer "F.Cu")
		(net "PECI_BMC_R")
	)
	(segment
		(start 306.411376 -53.450998)
		(end 306.63388 -53.450998)
		(width 0.12954)
		(layer "F.Cu")
		(net "PECI_BMC_R")
	)
	(segment
		(start 166.37 -24.113998)
		(end 167.386 -24.113998)
		(width 0.12954)
		(layer "F.Cu")
		(net "PECI_BMC_R")
	)
	(segment
		(start 306.71262 -55.620158)
		(end 306.71262 -53.529738)
		(width 0.12954)
		(layer "F.Cu")
		(net "PECI_BMC_R")
	)
	(segment
		(start 171.236386 -22.309836)
		(end 171.236386 -23.437342)
		(width 0.12954)
		(layer "F.Cu")
		(net "PECI_BMC_R")
	)
	(segment
		(start 302.3108 -56.987948)
		(end 302.874426 -56.987948)
		(width 0.12954)
		(layer "F.Cu")
		(net "PECI_BMC_R")
	)
	(segment
		(start 306.71262 -53.529738)
		(end 306.63388 -53.450998)
		(width 0.12954)
		(layer "F.Cu")
		(net "PECI_BMC_R")
	)
	(via
		(at 171.192698 -22.266148)
		(size 0.762)
		(drill 0.254)
		(layers "F.Cu" "B.Cu")
		(net "PECI_BMC_R")
	)
	(via
		(at 301.9044 -57.394348)
		(size 0.508)
		(drill 0.254)
		(layers "F.Cu" "B.Cu")
		(net "PECI_BMC_R")
	)
	(segment
		(start 246.43588 -68.341748)
		(end 248.26468 -66.512948)
		(width 0.127)
		(layer "In6.Cu")
		(net "PECI_BMC_R")
	)
	(segment
		(start 183.75122 -24.635968)
		(end 184.5056 -25.390348)
		(width 0.127)
		(layer "In6.Cu")
		(net "PECI_BMC_R")
	)
	(segment
		(start 187.7568 -26.299668)
		(end 192.86474 -31.407608)
		(width 0.127)
		(layer "In6.Cu")
		(net "PECI_BMC_R")
	)
	(segment
		(start 192.86474 -31.407608)
		(end 192.86474 -33.167828)
		(width 0.127)
		(layer "In6.Cu")
		(net "PECI_BMC_R")
	)
	(segment
		(start 175.31588 -24.196548)
		(end 179.1208 -24.196548)
		(width 0.127)
		(layer "In6.Cu")
		(net "PECI_BMC_R")
	)
	(segment
		(start 275.26488 -63.972948)
		(end 283.745178 -55.49265)
		(width 0.127)
		(layer "In6.Cu")
		(net "PECI_BMC_R")
	)
	(segment
		(start 248.26468 -66.512948)
		(end 260.16585 -66.512948)
		(width 0.127)
		(layer "In6.Cu")
		(net "PECI_BMC_R")
	)
	(segment
		(start 173.08068 -21.961348)
		(end 175.31588 -24.196548)
		(width 0.127)
		(layer "In6.Cu")
		(net "PECI_BMC_R")
	)
	(segment
		(start 202.23226 -40.119808)
		(end 212.41766 -40.119808)
		(width 0.127)
		(layer "In6.Cu")
		(net "PECI_BMC_R")
	)
	(segment
		(start 212.41766 -40.119808)
		(end 213.88578 -41.587928)
		(width 0.127)
		(layer "In6.Cu")
		(net "PECI_BMC_R")
	)
	(segment
		(start 186.00928 -25.390348)
		(end 186.9186 -26.299668)
		(width 0.127)
		(layer "In6.Cu")
		(net "PECI_BMC_R")
	)
	(segment
		(start 290.420298 -55.49265)
		(end 290.70046 -55.772812)
		(width 0.127)
		(layer "In6.Cu")
		(net "PECI_BMC_R")
	)
	(segment
		(start 213.88578 -41.587928)
		(end 213.88578 -44.574968)
		(width 0.127)
		(layer "In6.Cu")
		(net "PECI_BMC_R")
	)
	(segment
		(start 186.9186 -26.299668)
		(end 187.7568 -26.299668)
		(width 0.127)
		(layer "In6.Cu")
		(net "PECI_BMC_R")
	)
	(segment
		(start 171.497498 -21.961348)
		(end 173.08068 -21.961348)
		(width 0.127)
		(layer "In6.Cu")
		(net "PECI_BMC_R")
	)
	(segment
		(start 171.192698 -22.266148)
		(end 171.497498 -21.961348)
		(width 0.127)
		(layer "In6.Cu")
		(net "PECI_BMC_R")
	)
	(segment
		(start 196.11086 -33.998408)
		(end 202.23226 -40.119808)
		(width 0.127)
		(layer "In6.Cu")
		(net "PECI_BMC_R")
	)
	(segment
		(start 179.56022 -24.635968)
		(end 183.75122 -24.635968)
		(width 0.127)
		(layer "In6.Cu")
		(net "PECI_BMC_R")
	)
	(segment
		(start 179.1208 -24.196548)
		(end 179.56022 -24.635968)
		(width 0.127)
		(layer "In6.Cu")
		(net "PECI_BMC_R")
	)
	(segment
		(start 213.233 -48.236124)
		(end 233.338624 -68.341748)
		(width 0.127)
		(layer "In6.Cu")
		(net "PECI_BMC_R")
	)
	(segment
		(start 294.275764 -55.772812)
		(end 296.0497 -57.546748)
		(width 0.127)
		(layer "In6.Cu")
		(net "PECI_BMC_R")
	)
	(segment
		(start 213.233 -45.227748)
		(end 213.233 -48.236124)
		(width 0.127)
		(layer "In6.Cu")
		(net "PECI_BMC_R")
	)
	(segment
		(start 283.745178 -55.49265)
		(end 290.420298 -55.49265)
		(width 0.127)
		(layer "In6.Cu")
		(net "PECI_BMC_R")
	)
	(segment
		(start 184.5056 -25.390348)
		(end 186.00928 -25.390348)
		(width 0.127)
		(layer "In6.Cu")
		(net "PECI_BMC_R")
	)
	(segment
		(start 265.04646 -63.972948)
		(end 275.26488 -63.972948)
		(width 0.127)
		(layer "In6.Cu")
		(net "PECI_BMC_R")
	)
	(segment
		(start 296.0497 -57.546748)
		(end 301.752 -57.546748)
		(width 0.127)
		(layer "In6.Cu")
		(net "PECI_BMC_R")
	)
	(segment
		(start 192.86474 -33.167828)
		(end 193.69532 -33.998408)
		(width 0.127)
		(layer "In6.Cu")
		(net "PECI_BMC_R")
	)
	(segment
		(start 264.161524 -64.857884)
		(end 265.04646 -63.972948)
		(width 0.127)
		(layer "In6.Cu")
		(net "PECI_BMC_R")
	)
	(segment
		(start 301.752 -57.546748)
		(end 301.9044 -57.394348)
		(width 0.127)
		(layer "In6.Cu")
		(net "PECI_BMC_R")
	)
	(segment
		(start 213.88578 -44.574968)
		(end 213.233 -45.227748)
		(width 0.127)
		(layer "In6.Cu")
		(net "PECI_BMC_R")
	)
	(segment
		(start 260.16585 -66.512948)
		(end 264.161524 -64.857884)
		(width 0.127)
		(layer "In6.Cu")
		(net "PECI_BMC_R")
	)
	(segment
		(start 193.69532 -33.998408)
		(end 196.11086 -33.998408)
		(width 0.127)
		(layer "In6.Cu")
		(net "PECI_BMC_R")
	)
	(segment
		(start 233.338624 -68.341748)
		(end 246.43588 -68.341748)
		(width 0.127)
		(layer "In6.Cu")
		(net "PECI_BMC_R")
	)
	(segment
		(start 290.70046 -55.772812)
		(end 294.275764 -55.772812)
		(width 0.127)
		(layer "In6.Cu")
		(net "PECI_BMC_R")
	)
	(segment
		(start 306.71262 -56.420258)
		(end 306.71135 -56.421528)
		(width 0.12954)
		(layer "F.Cu")
		(net "PECI_BMC_B1")
	)
	(segment
		(start 306.71135 -56.864758)
		(end 306.49164 -57.084468)
		(width 0.12954)
		(layer "F.Cu")
		(net "PECI_BMC_B1")
	)
	(segment
		(start 306.49164 -57.084468)
		(end 306.71135 -57.304178)
		(width 0.12954)
		(layer "F.Cu")
		(net "PECI_BMC_B1")
	)
	(segment
		(start 306.71135 -57.304178)
		(end 306.71135 -58.03773)
		(width 0.12954)
		(layer "F.Cu")
		(net "PECI_BMC_B1")
	)
	(segment
		(start 306.71135 -56.421528)
		(end 306.71135 -56.864758)
		(width 0.12954)
		(layer "F.Cu")
		(net "PECI_BMC_B1")
	)
	(via
		(at 306.49164 -57.084468)
		(size 0.508)
		(drill 0.254)
		(layers "F.Cu" "B.Cu")
		(net "PECI_BMC_B1")
	)
	(segment
		(start 165.27272 -20.762468)
		(end 165.27272 -23.000208)
		(width 0.12954)
		(layer "F.Cu")
		(net "PECI_BMC")
	)
	(segment
		(start 163.267136 -16.550132)
		(end 163.267136 -19.793204)
		(width 0.12954)
		(layer "F.Cu")
		(net "PECI_BMC")
	)
	(segment
		(start 164.657532 -20.193508)
		(end 164.70376 -20.193508)
		(width 0.12954)
		(layer "F.Cu")
		(net "PECI_BMC")
	)
	(segment
		(start 165.27272 -23.000208)
		(end 165.58641 -23.313898)
		(width 0.12954)
		(layer "F.Cu")
		(net "PECI_BMC")
	)
	(segment
		(start 164.70376 -20.193508)
		(end 165.27272 -20.762468)
		(width 0.12954)
		(layer "F.Cu")
		(net "PECI_BMC")
	)
	(segment
		(start 163.66744 -20.193508)
		(end 164.657532 -20.193508)
		(width 0.12954)
		(layer "F.Cu")
		(net "PECI_BMC")
	)
	(segment
		(start 163.267136 -19.793204)
		(end 163.66744 -20.193508)
		(width 0.12954)
		(layer "F.Cu")
		(net "PECI_BMC")
	)
	(segment
		(start 165.58641 -23.313898)
		(end 166.37 -23.313898)
		(width 0.12954)
		(layer "F.Cu")
		(net "PECI_BMC")
	)
	(via
		(at 164.657532 -20.193508)
		(size 0.762)
		(drill 0.381)
		(layers "F.Cu" "B.Cu")
		(net "PECI_BMC")
	)
	(segment
		(start 397.765016 -62.749938)
		(end 401.56257 -62.749938)
		(width 0.12954)
		(layer "F.Cu")
		(net "PD_TRST_P3")
	)
	(segment
		(start 401.806664 -62.994032)
		(end 403.546056 -62.994032)
		(width 0.12954)
		(layer "F.Cu")
		(net "PD_TRST_P3")
	)
	(segment
		(start 401.56257 -62.749938)
		(end 401.77974 -62.967108)
		(width 0.12954)
		(layer "F.Cu")
		(net "PD_TRST_P3")
	)
	(segment
		(start 401.77974 -62.967108)
		(end 401.806664 -62.994032)
		(width 0.12954)
		(layer "F.Cu")
		(net "PD_TRST_P3")
	)
	(via
		(at 401.77974 -62.967108)
		(size 0.762)
		(drill 0.381)
		(layers "F.Cu" "B.Cu")
		(net "PD_TRST_P3")
	)
	(segment
		(start 329.165966 -43.281346)
		(end 328.625708 -43.281346)
		(width 0.12954)
		(layer "F.Cu")
		(net "PD_SUSCLK")
	)
	(via
		(at 328.625708 -43.281346)
		(size 0.4572)
		(drill 0.2032)
		(layers "F.Cu" "B.Cu")
		(net "PD_SUSCLK")
	)
	(via
		(at 318.302894 -32.727392)
		(size 0.6604)
		(drill 0.3302)
		(layers "F.Cu" "B.Cu")
		(net "PD_SUSCLK")
	)
	(segment
		(start 318.758316 -33.182814)
		(end 318.302894 -32.727392)
		(width 0.12954)
		(layer "B.Cu")
		(net "PD_SUSCLK")
	)
	(segment
		(start 326.127872 -41.599358)
		(end 325.825612 -40.86987)
		(width 0.12954)
		(layer "B.Cu")
		(net "PD_SUSCLK")
	)
	(segment
		(start 323.654674 -37.8206)
		(end 320.889122 -35.055048)
		(width 0.12954)
		(layer "B.Cu")
		(net "PD_SUSCLK")
	)
	(segment
		(start 320.889122 -35.055048)
		(end 320.016378 -35.055048)
		(width 0.12954)
		(layer "B.Cu")
		(net "PD_SUSCLK")
	)
	(segment
		(start 325.825612 -40.86987)
		(end 325.266558 -40.310816)
		(width 0.12954)
		(layer "B.Cu")
		(net "PD_SUSCLK")
	)
	(segment
		(start 318.758316 -33.796986)
		(end 318.758316 -33.182814)
		(width 0.12954)
		(layer "B.Cu")
		(net "PD_SUSCLK")
	)
	(segment
		(start 323.654674 -38.051232)
		(end 323.654674 -37.8206)
		(width 0.12954)
		(layer "B.Cu")
		(net "PD_SUSCLK")
	)
	(segment
		(start 325.266558 -39.663116)
		(end 323.654674 -38.051232)
		(width 0.12954)
		(layer "B.Cu")
		(net "PD_SUSCLK")
	)
	(segment
		(start 327.80986 -43.281346)
		(end 326.127872 -41.599358)
		(width 0.12954)
		(layer "B.Cu")
		(net "PD_SUSCLK")
	)
	(segment
		(start 318.302894 -32.727392)
		(end 318.302894 -31.523178)
		(width 0.12954)
		(layer "B.Cu")
		(net "PD_SUSCLK")
	)
	(segment
		(start 328.625708 -43.281346)
		(end 327.80986 -43.281346)
		(width 0.12954)
		(layer "B.Cu")
		(net "PD_SUSCLK")
	)
	(segment
		(start 325.266558 -40.310816)
		(end 325.266558 -39.663116)
		(width 0.12954)
		(layer "B.Cu")
		(net "PD_SUSCLK")
	)
	(segment
		(start 320.016378 -35.055048)
		(end 318.758316 -33.796986)
		(width 0.12954)
		(layer "B.Cu")
		(net "PD_SUSCLK")
	)
	(segment
		(start 453.822054 -117.241574)
		(end 453.405748 -116.825268)
		(width 0.12954)
		(layer "F.Cu")
		(net "PD_SMB_OCP1_HP_ADD2")
	)
	(segment
		(start 450.506338 -117.241574)
		(end 450.421756 -117.241574)
		(width 0.12954)
		(layer "F.Cu")
		(net "PD_SMB_OCP1_HP_ADD2")
	)
	(segment
		(start 447.882264 -117.593872)
		(end 447.882264 -117.193822)
		(width 0.12954)
		(layer "F.Cu")
		(net "PD_SMB_OCP1_HP_ADD2")
	)
	(segment
		(start 450.421756 -117.241574)
		(end 450.374004 -117.193822)
		(width 0.12954)
		(layer "F.Cu")
		(net "PD_SMB_OCP1_HP_ADD2")
	)
	(segment
		(start 450.374004 -117.193822)
		(end 449.805298 -117.762528)
		(width 0.12954)
		(layer "F.Cu")
		(net "PD_SMB_OCP1_HP_ADD2")
	)
	(segment
		(start 450.922644 -116.825268)
		(end 450.506338 -117.241574)
		(width 0.12954)
		(layer "F.Cu")
		(net "PD_SMB_OCP1_HP_ADD2")
	)
	(segment
		(start 448.05092 -117.762528)
		(end 447.882264 -117.593872)
		(width 0.12954)
		(layer "F.Cu")
		(net "PD_SMB_OCP1_HP_ADD2")
	)
	(segment
		(start 449.805298 -117.762528)
		(end 448.05092 -117.762528)
		(width 0.12954)
		(layer "F.Cu")
		(net "PD_SMB_OCP1_HP_ADD2")
	)
	(segment
		(start 454.798684 -117.241574)
		(end 453.822054 -117.241574)
		(width 0.12954)
		(layer "F.Cu")
		(net "PD_SMB_OCP1_HP_ADD2")
	)
	(segment
		(start 453.405748 -116.825268)
		(end 452.05396 -116.825268)
		(width 0.12954)
		(layer "F.Cu")
		(net "PD_SMB_OCP1_HP_ADD2")
	)
	(segment
		(start 452.05396 -116.825268)
		(end 450.922644 -116.825268)
		(width 0.12954)
		(layer "F.Cu")
		(net "PD_SMB_OCP1_HP_ADD2")
	)
	(via
		(at 452.05396 -116.825268)
		(size 0.762)
		(drill 0.381)
		(layers "F.Cu" "B.Cu")
		(net "PD_SMB_OCP1_HP_ADD2")
	)
	(segment
		(start 450.374004 -118.336822)
		(end 449.825618 -118.885208)
		(width 0.12954)
		(layer "F.Cu")
		(net "PD_SMB_OCP1_HP_ADD1")
	)
	(segment
		(start 448.1703 -118.885208)
		(end 447.910204 -118.625112)
		(width 0.12954)
		(layer "F.Cu")
		(net "PD_SMB_OCP1_HP_ADD1")
	)
	(segment
		(start 447.910204 -118.625112)
		(end 447.910204 -118.336822)
		(width 0.12954)
		(layer "F.Cu")
		(net "PD_SMB_OCP1_HP_ADD1")
	)
	(segment
		(start 450.819266 -117.89156)
		(end 450.374004 -118.336822)
		(width 0.12954)
		(layer "F.Cu")
		(net "PD_SMB_OCP1_HP_ADD1")
	)
	(segment
		(start 453.036432 -117.89156)
		(end 450.819266 -117.89156)
		(width 0.12954)
		(layer "F.Cu")
		(net "PD_SMB_OCP1_HP_ADD1")
	)
	(segment
		(start 449.825618 -118.885208)
		(end 448.1703 -118.885208)
		(width 0.12954)
		(layer "F.Cu")
		(net "PD_SMB_OCP1_HP_ADD1")
	)
	(segment
		(start 454.798684 -117.89156)
		(end 453.036432 -117.89156)
		(width 0.12954)
		(layer "F.Cu")
		(net "PD_SMB_OCP1_HP_ADD1")
	)
	(via
		(at 453.036432 -117.89156)
		(size 0.762)
		(drill 0.381)
		(layers "F.Cu" "B.Cu")
		(net "PD_SMB_OCP1_HP_ADD1")
	)
	(segment
		(start 463.8548 -115.946428)
		(end 464.750658 -115.946428)
		(width 0.12954)
		(layer "F.Cu")
		(net "PD_SMB_OCP1_HP_ADD0")
	)
	(segment
		(start 464.750658 -115.946428)
		(end 465.420964 -116.616734)
		(width 0.12954)
		(layer "F.Cu")
		(net "PD_SMB_OCP1_HP_ADD0")
	)
	(segment
		(start 463.20964 -116.591588)
		(end 463.8548 -115.946428)
		(width 0.12954)
		(layer "F.Cu")
		(net "PD_SMB_OCP1_HP_ADD0")
	)
	(segment
		(start 465.423504 -115.295934)
		(end 465.423504 -116.614194)
		(width 0.12954)
		(layer "F.Cu")
		(net "PD_SMB_OCP1_HP_ADD0")
	)
	(segment
		(start 465.423504 -116.614194)
		(end 465.420964 -116.616734)
		(width 0.12954)
		(layer "F.Cu")
		(net "PD_SMB_OCP1_HP_ADD0")
	)
	(segment
		(start 460.648812 -116.591588)
		(end 463.20964 -116.591588)
		(width 0.12954)
		(layer "F.Cu")
		(net "PD_SMB_OCP1_HP_ADD0")
	)
	(via
		(at 463.8548 -115.946428)
		(size 0.762)
		(drill 0.381)
		(layers "F.Cu" "B.Cu")
		(net "PD_SMB_OCP1_HP_ADD0")
	)
	(segment
		(start 409.820364 -32.51327)
		(end 409.820364 -29.075888)
		(width 0.12954)
		(layer "F.Cu")
		(net "PD_RST_RTCRST_N")
	)
	(segment
		(start 409.820364 -29.075888)
		(end 409.823412 -29.078936)
		(width 0.12954)
		(layer "F.Cu")
		(net "PD_RST_RTCRST_N")
	)
	(segment
		(start 409.823412 -29.078936)
		(end 411.35681 -29.078936)
		(width 0.12954)
		(layer "F.Cu")
		(net "PD_RST_RTCRST_N")
	)
	(segment
		(start 409.820364 -40.46347)
		(end 409.820364 -32.51327)
		(width 0.12954)
		(layer "F.Cu")
		(net "PD_RST_RTCRST_N")
	)
	(via
		(at 409.820364 -29.075888)
		(size 0.762)
		(drill 0.381)
		(layers "F.Cu" "B.Cu")
		(net "PD_RST_RTCRST_N")
	)
	(segment
		(start 332.693518 -48.450246)
		(end 332.549246 -48.450246)
		(width 0.2032)
		(layer "F.Cu")
		(net "PD_RCOMP_1P8_3P3")
	)
	(segment
		(start 307.54193 -49.621948)
		(end 308.28488 -49.621948)
		(width 0.2032)
		(layer "F.Cu")
		(net "PD_RCOMP_1P8_3P3")
	)
	(segment
		(start 332.549246 -48.450246)
		(end 332.422246 -48.577246)
		(width 0.2032)
		(layer "F.Cu")
		(net "PD_RCOMP_1P8_3P3")
	)
	(segment
		(start 332.422246 -48.577246)
		(end 332.422246 -48.920146)
		(width 0.2032)
		(layer "F.Cu")
		(net "PD_RCOMP_1P8_3P3")
	)
	(via
		(at 308.28488 -49.621948)
		(size 0.508)
		(drill 0.254)
		(layers "F.Cu" "B.Cu")
		(net "PD_RCOMP_1P8_3P3")
	)
	(via
		(at 332.693518 -48.450246)
		(size 0.4572)
		(drill 0.2032)
		(layers "F.Cu" "B.Cu")
		(net "PD_RCOMP_1P8_3P3")
	)
	(segment
		(start 329.61072 -48.923448)
		(end 328.30262 -48.923448)
		(width 0.127)
		(layer "In11.Cu")
		(net "PD_RCOMP_1P8_3P3")
	)
	(segment
		(start 312.2422 -49.258728)
		(end 311.68086 -49.820068)
		(width 0.2032)
		(layer "In11.Cu")
		(net "PD_RCOMP_1P8_3P3")
	)
	(segment
		(start 324.84568 -47.922688)
		(end 316.42558 -47.922688)
		(width 0.2032)
		(layer "In11.Cu")
		(net "PD_RCOMP_1P8_3P3")
	)
	(segment
		(start 331.706982 -48.450246)
		(end 331.21981 -48.937418)
		(width 0.127)
		(layer "In11.Cu")
		(net "PD_RCOMP_1P8_3P3")
	)
	(segment
		(start 325.84644 -48.923448)
		(end 324.84568 -47.922688)
		(width 0.2032)
		(layer "In11.Cu")
		(net "PD_RCOMP_1P8_3P3")
	)
	(segment
		(start 330.4413 -48.473868)
		(end 330.0603 -48.473868)
		(width 0.127)
		(layer "In11.Cu")
		(net "PD_RCOMP_1P8_3P3")
	)
	(segment
		(start 331.21981 -48.937418)
		(end 330.90485 -48.937418)
		(width 0.127)
		(layer "In11.Cu")
		(net "PD_RCOMP_1P8_3P3")
	)
	(segment
		(start 316.42558 -47.922688)
		(end 315.08954 -49.258728)
		(width 0.2032)
		(layer "In11.Cu")
		(net "PD_RCOMP_1P8_3P3")
	)
	(segment
		(start 330.0603 -48.473868)
		(end 329.61072 -48.923448)
		(width 0.127)
		(layer "In11.Cu")
		(net "PD_RCOMP_1P8_3P3")
	)
	(segment
		(start 330.90485 -48.937418)
		(end 330.4413 -48.473868)
		(width 0.127)
		(layer "In11.Cu")
		(net "PD_RCOMP_1P8_3P3")
	)
	(segment
		(start 328.30262 -48.923448)
		(end 325.84644 -48.923448)
		(width 0.2032)
		(layer "In11.Cu")
		(net "PD_RCOMP_1P8_3P3")
	)
	(segment
		(start 315.08954 -49.258728)
		(end 312.2422 -49.258728)
		(width 0.2032)
		(layer "In11.Cu")
		(net "PD_RCOMP_1P8_3P3")
	)
	(segment
		(start 332.693518 -48.450246)
		(end 331.706982 -48.450246)
		(width 0.127)
		(layer "In11.Cu")
		(net "PD_RCOMP_1P8_3P3")
	)
	(segment
		(start 308.483 -49.820068)
		(end 308.28488 -49.621948)
		(width 0.2032)
		(layer "In11.Cu")
		(net "PD_RCOMP_1P8_3P3")
	)
	(segment
		(start 311.68086 -49.820068)
		(end 308.483 -49.820068)
		(width 0.2032)
		(layer "In11.Cu")
		(net "PD_RCOMP_1P8_3P3")
	)
	(segment
		(start 119.268748 -272.917412)
		(end 119.268748 -273.453098)
		(width 0.12954)
		(layer "F.Cu")
		(net "PD_PIROM_CPU1_ADDR2")
	)
	(segment
		(start 119.268494 -272.917158)
		(end 119.268748 -272.917412)
		(width 0.12954)
		(layer "F.Cu")
		(net "PD_PIROM_CPU1_ADDR2")
	)
	(segment
		(start 193.53403 -352.694748)
		(end 193.53403 -351.551748)
		(width 0.12954)
		(layer "F.Cu")
		(net "PD_PIROM_CPU1_ADDR2")
	)
	(segment
		(start 193.53403 -351.551748)
		(end 192.46088 -351.551748)
		(width 0.12954)
		(layer "F.Cu")
		(net "PD_PIROM_CPU1_ADDR2")
	)
	(via
		(at 192.46088 -351.551748)
		(size 0.508)
		(drill 0.254)
		(layers "F.Cu" "B.Cu")
		(net "PD_PIROM_CPU1_ADDR2")
	)
	(via
		(at 119.268748 -273.453098)
		(size 0.4572)
		(drill 0.2032)
		(layers "F.Cu" "B.Cu")
		(net "PD_PIROM_CPU1_ADDR2")
	)
	(segment
		(start 119.643398 -278.351996)
		(end 119.643398 -278.336502)
		(width 0.0889)
		(layer "In11.Cu")
		(net "PD_PIROM_CPU1_ADDR2")
	)
	(segment
		(start 118.51005 -273.781012)
		(end 118.516146 -273.777456)
		(width 0.0889)
		(layer "In11.Cu")
		(net "PD_PIROM_CPU1_ADDR2")
	)
	(segment
		(start 120.113044 -287.297876)
		(end 120.113044 -287.28924)
		(width 0.0889)
		(layer "In11.Cu")
		(net "PD_PIROM_CPU1_ADDR2")
	)
	(segment
		(start 119.455946 -273.777456)
		(end 119.464836 -273.772376)
		(width 0.0889)
		(layer "In11.Cu")
		(net "PD_PIROM_CPU1_ADDR2")
	)
	(segment
		(start 124.27712 -291.379148)
		(end 123.0122 -291.379148)
		(width 0.127)
		(layer "In11.Cu")
		(net "PD_PIROM_CPU1_ADDR2")
	)
	(segment
		(start 128.6002 -295.702228)
		(end 124.27712 -291.379148)
		(width 0.127)
		(layer "In11.Cu")
		(net "PD_PIROM_CPU1_ADDR2")
	)
	(segment
		(start 188.137038 -332.806548)
		(end 159.663638 -332.806548)
		(width 0.127)
		(layer "In11.Cu")
		(net "PD_PIROM_CPU1_ADDR2")
	)
	(segment
		(start 118.516146 -274.756372)
		(end 118.513352 -274.754848)
		(width 0.0889)
		(layer "In11.Cu")
		(net "PD_PIROM_CPU1_ADDR2")
	)
	(segment
		(start 120.874282 -280.458926)
		(end 120.865392 -280.453846)
		(width 0.0889)
		(layer "In11.Cu")
		(net "PD_PIROM_CPU1_ADDR2")
	)
	(segment
		(start 120.38965 -286.803338)
		(end 120.395746 -286.799782)
		(width 0.0889)
		(layer "In11.Cu")
		(net "PD_PIROM_CPU1_ADDR2")
	)
	(segment
		(start 120.865392 -285.985712)
		(end 120.874282 -285.980632)
		(width 0.0889)
		(layer "In11.Cu")
		(net "PD_PIROM_CPU1_ADDR2")
	)
	(segment
		(start 120.583198 -284.863032)
		(end 120.583198 -284.832044)
		(width 0.0889)
		(layer "In11.Cu")
		(net "PD_PIROM_CPU1_ADDR2")
	)
	(segment
		(start 119.173244 -277.536656)
		(end 119.173244 -277.512526)
		(width 0.0889)
		(layer "In11.Cu")
		(net "PD_PIROM_CPU1_ADDR2")
	)
	(segment
		(start 192.46088 -351.551748)
		(end 192.63868 -351.551748)
		(width 0.127)
		(layer "In11.Cu")
		(net "PD_PIROM_CPU1_ADDR2")
	)
	(segment
		(start 120.113044 -282.42006)
		(end 120.113044 -282.405836)
		(width 0.0889)
		(layer "In11.Cu")
		(net "PD_PIROM_CPU1_ADDR2")
	)
	(segment
		(start 193.47688 -350.713548)
		(end 193.47688 -338.14639)
		(width 0.127)
		(layer "In11.Cu")
		(net "PD_PIROM_CPU1_ADDR2")
	)
	(segment
		(start 119.425212 -273.18208)
		(end 119.268748 -273.453098)
		(width 0.0889)
		(layer "In11.Cu")
		(net "PD_PIROM_CPU1_ADDR2")
	)
	(segment
		(start 119.503444 -273.161252)
		(end 119.425212 -273.18208)
		(width 0.0889)
		(layer "In11.Cu")
		(net "PD_PIROM_CPU1_ADDR2")
	)
	(segment
		(start 120.476264 -281.093926)
		(end 120.490996 -281.102562)
		(width 0.0889)
		(layer "In11.Cu")
		(net "PD_PIROM_CPU1_ADDR2")
	)
	(segment
		(start 120.9294 -290.566348)
		(end 120.015 -290.566348)
		(width 0.0889)
		(layer "In11.Cu")
		(net "PD_PIROM_CPU1_ADDR2")
	)
	(segment
		(start 119.643398 -281.607514)
		(end 119.643398 -281.576526)
		(width 0.0889)
		(layer "In11.Cu")
		(net "PD_PIROM_CPU1_ADDR2")
	)
	(segment
		(start 118.516908 -274.75688)
		(end 118.516146 -274.756372)
		(width 0.0889)
		(layer "In11.Cu")
		(net "PD_PIROM_CPU1_ADDR2")
	)
	(segment
		(start 120.582944 -286.48406)
		(end 120.582944 -286.456882)
		(width 0.0889)
		(layer "In11.Cu")
		(net "PD_PIROM_CPU1_ADDR2")
	)
	(segment
		(start 120.395746 -279.639776)
		(end 120.383554 -279.632664)
		(width 0.0889)
		(layer "In11.Cu")
		(net "PD_PIROM_CPU1_ADDR2")
	)
	(segment
		(start 193.47688 -338.14639)
		(end 188.137038 -332.806548)
		(width 0.127)
		(layer "In11.Cu")
		(net "PD_PIROM_CPU1_ADDR2")
	)
	(segment
		(start 120.583198 -279.986232)
		(end 120.583198 -279.964134)
		(width 0.0889)
		(layer "In11.Cu")
		(net "PD_PIROM_CPU1_ADDR2")
	)
	(segment
		(start 119.91975 -287.617154)
		(end 119.925846 -287.613598)
		(width 0.0889)
		(layer "In11.Cu")
		(net "PD_PIROM_CPU1_ADDR2")
	)
	(segment
		(start 119.643144 -290.194492)
		(end 119.643144 -289.609784)
		(width 0.0889)
		(layer "In11.Cu")
		(net "PD_PIROM_CPU1_ADDR2")
	)
	(segment
		(start 119.455692 -277.032974)
		(end 119.464582 -277.027894)
		(width 0.0889)
		(layer "In11.Cu")
		(net "PD_PIROM_CPU1_ADDR2")
	)
	(segment
		(start 192.63868 -351.551748)
		(end 193.47688 -350.713548)
		(width 0.127)
		(layer "In11.Cu")
		(net "PD_PIROM_CPU1_ADDR2")
	)
	(segment
		(start 119.643144 -288.11728)
		(end 119.643144 -288.103056)
		(width 0.0889)
		(layer "In11.Cu")
		(net "PD_PIROM_CPU1_ADDR2")
	)
	(segment
		(start 120.865392 -284.35808)
		(end 120.874282 -284.353)
		(width 0.0889)
		(layer "In11.Cu")
		(net "PD_PIROM_CPU1_ADDR2")
	)
	(segment
		(start 119.934482 -282.086558)
		(end 119.925592 -282.081478)
		(width 0.0889)
		(layer "In11.Cu")
		(net "PD_PIROM_CPU1_ADDR2")
	)
	(segment
		(start 123.0122 -291.379148)
		(end 121.7422 -291.379148)
		(width 0.0889)
		(layer "In11.Cu")
		(net "PD_PIROM_CPU1_ADDR2")
	)
	(segment
		(start 120.015 -290.566348)
		(end 119.643144 -290.194492)
		(width 0.0889)
		(layer "In11.Cu")
		(net "PD_PIROM_CPU1_ADDR2")
	)
	(segment
		(start 120.874282 -285.342076)
		(end 120.865392 -285.336996)
		(width 0.0889)
		(layer "In11.Cu")
		(net "PD_PIROM_CPU1_ADDR2")
	)
	(segment
		(start 119.464582 -276.389338)
		(end 119.455692 -276.384258)
		(width 0.0889)
		(layer "In11.Cu")
		(net "PD_PIROM_CPU1_ADDR2")
	)
	(segment
		(start 119.934736 -288.597848)
		(end 119.925846 -288.592768)
		(width 0.0889)
		(layer "In11.Cu")
		(net "PD_PIROM_CPU1_ADDR2")
	)
	(segment
		(start 120.865392 -281.102562)
		(end 120.874282 -281.097482)
		(width 0.0889)
		(layer "In11.Cu")
		(net "PD_PIROM_CPU1_ADDR2")
	)
	(segment
		(start 120.582944 -283.229812)
		(end 120.582944 -283.21127)
		(width 0.0889)
		(layer "In11.Cu")
		(net "PD_PIROM_CPU1_ADDR2")
	)
	(segment
		(start 119.934482 -278.83104)
		(end 119.925592 -278.82596)
		(width 0.0889)
		(layer "In11.Cu")
		(net "PD_PIROM_CPU1_ADDR2")
	)
	(segment
		(start 118.703598 -275.081238)
		(end 118.703598 -275.078444)
		(width 0.0889)
		(layer "In11.Cu")
		(net "PD_PIROM_CPU1_ADDR2")
	)
	(segment
		(start 118.513352 -274.754848)
		(end 118.51005 -274.752816)
		(width 0.0889)
		(layer "In11.Cu")
		(net "PD_PIROM_CPU1_ADDR2")
	)
	(segment
		(start 119.464836 -278.017224)
		(end 119.455946 -278.012144)
		(width 0.0889)
		(layer "In11.Cu")
		(net "PD_PIROM_CPU1_ADDR2")
	)
	(segment
		(start 121.7422 -291.379148)
		(end 120.9294 -290.566348)
		(width 0.0889)
		(layer "In11.Cu")
		(net "PD_PIROM_CPU1_ADDR2")
	)
	(segment
		(start 120.404636 -279.644856)
		(end 120.395746 -279.639776)
		(width 0.0889)
		(layer "In11.Cu")
		(net "PD_PIROM_CPU1_ADDR2")
	)
	(segment
		(start 128.6002 -301.74311)
		(end 128.6002 -295.702228)
		(width 0.127)
		(layer "In11.Cu")
		(net "PD_PIROM_CPU1_ADDR2")
	)
	(segment
		(start 120.113298 -289.077908)
		(end 120.113298 -288.917126)
		(width 0.0889)
		(layer "In11.Cu")
		(net "PD_PIROM_CPU1_ADDR2")
	)
	(segment
		(start 118.516146 -273.777456)
		(end 118.530878 -273.76882)
		(width 0.0889)
		(layer "In11.Cu")
		(net "PD_PIROM_CPU1_ADDR2")
	)
	(segment
		(start 159.663638 -332.806548)
		(end 128.6002 -301.74311)
		(width 0.127)
		(layer "In11.Cu")
		(net "PD_PIROM_CPU1_ADDR2")
	)
	(segment
		(start 120.874282 -283.714444)
		(end 120.865392 -283.709364)
		(width 0.0889)
		(layer "In11.Cu")
		(net "PD_PIROM_CPU1_ADDR2")
	)
	(segment
		(start 119.173244 -275.904706)
		(end 119.173244 -275.886164)
		(width 0.0889)
		(layer "In11.Cu")
		(net "PD_PIROM_CPU1_ADDR2")
	)
	(arc
		(start 120.865392 -285.336996)
		(mid 120.662569 -285.136765)
		(end 120.583198 -284.863032)
		(width 0.0889)
		(layer "In11.Cu")
		(net "PD_PIROM_CPU1_ADDR2")
	)
	(arc
		(start 119.643398 -281.576526)
		(mid 119.722768 -281.302792)
		(end 119.925592 -281.102562)
		(width 0.0889)
		(layer "In11.Cu")
		(net "PD_PIROM_CPU1_ADDR2")
	)
	(arc
		(start 118.51005 -274.752816)
		(mid 118.233476 -274.266914)
		(end 118.51005 -273.781012)
		(width 0.0889)
		(layer "In11.Cu")
		(net "PD_PIROM_CPU1_ADDR2")
	)
	(arc
		(start 119.928894 -289.277806)
		(mid 120.03829 -289.193709)
		(end 120.113298 -289.077908)
		(width 0.0889)
		(layer "In11.Cu")
		(net "PD_PIROM_CPU1_ADDR2")
	)
	(arc
		(start 119.925846 -288.592768)
		(mid 119.722365 -288.391964)
		(end 119.643144 -288.11728)
		(width 0.0889)
		(layer "In11.Cu")
		(net "PD_PIROM_CPU1_ADDR2")
	)
	(arc
		(start 118.530878 -273.76882)
		(mid 118.807353 -273.7015)
		(end 119.08155 -273.777456)
		(width 0.0889)
		(layer "In11.Cu")
		(net "PD_PIROM_CPU1_ADDR2")
	)
	(arc
		(start 120.865392 -283.709364)
		(mid 120.661057 -283.506759)
		(end 120.582944 -283.229812)
		(width 0.0889)
		(layer "In11.Cu")
		(net "PD_PIROM_CPU1_ADDR2")
	)
	(arc
		(start 119.925592 -278.82596)
		(mid 119.722769 -278.625729)
		(end 119.643398 -278.351996)
		(width 0.0889)
		(layer "In11.Cu")
		(net "PD_PIROM_CPU1_ADDR2")
	)
	(arc
		(start 120.865392 -280.453846)
		(mid 120.66411 -280.256359)
		(end 120.583198 -279.986232)
		(width 0.0889)
		(layer "In11.Cu")
		(net "PD_PIROM_CPU1_ADDR2")
	)
	(arc
		(start 118.986046 -275.570442)
		(mid 118.779286 -275.363679)
		(end 118.703598 -275.081238)
		(width 0.0889)
		(layer "In11.Cu")
		(net "PD_PIROM_CPU1_ADDR2")
	)
	(arc
		(start 120.383554 -279.632664)
		(mid 120.185326 -279.426816)
		(end 120.113044 -279.150318)
		(width 0.0889)
		(layer "In11.Cu")
		(net "PD_PIROM_CPU1_ADDR2")
	)
	(arc
		(start 120.113044 -282.405836)
		(mid 120.065365 -282.222936)
		(end 119.934482 -282.086558)
		(width 0.0889)
		(layer "In11.Cu")
		(net "PD_PIROM_CPU1_ADDR2")
	)
	(arc
		(start 119.455692 -276.384258)
		(mid 119.251357 -276.181653)
		(end 119.173244 -275.904706)
		(width 0.0889)
		(layer "In11.Cu")
		(net "PD_PIROM_CPU1_ADDR2")
	)
	(arc
		(start 120.874282 -284.353)
		(mid 121.052879 -284.033722)
		(end 120.874282 -283.714444)
		(width 0.0889)
		(layer "In11.Cu")
		(net "PD_PIROM_CPU1_ADDR2")
	)
	(arc
		(start 120.874282 -285.980632)
		(mid 121.052879 -285.661354)
		(end 120.874282 -285.342076)
		(width 0.0889)
		(layer "In11.Cu")
		(net "PD_PIROM_CPU1_ADDR2")
	)
	(arc
		(start 120.490996 -281.102562)
		(mid 120.678194 -281.152705)
		(end 120.865392 -281.102562)
		(width 0.0889)
		(layer "In11.Cu")
		(net "PD_PIROM_CPU1_ADDR2")
	)
	(arc
		(start 119.173244 -277.512526)
		(mid 119.251355 -277.235577)
		(end 119.455692 -277.032974)
		(width 0.0889)
		(layer "In11.Cu")
		(net "PD_PIROM_CPU1_ADDR2")
	)
	(arc
		(start 119.464836 -273.772376)
		(mid 119.59575 -273.636016)
		(end 119.643398 -273.453098)
		(width 0.0889)
		(layer "In11.Cu")
		(net "PD_PIROM_CPU1_ADDR2")
	)
	(arc
		(start 120.113044 -279.150318)
		(mid 120.065365 -278.967418)
		(end 119.934482 -278.83104)
		(width 0.0889)
		(layer "In11.Cu")
		(net "PD_PIROM_CPU1_ADDR2")
	)
	(arc
		(start 118.703598 -275.078444)
		(mid 118.653546 -274.892524)
		(end 118.516908 -274.75688)
		(width 0.0889)
		(layer "In11.Cu")
		(net "PD_PIROM_CPU1_ADDR2")
	)
	(arc
		(start 120.395746 -282.895548)
		(mid 120.192265 -282.694744)
		(end 120.113044 -282.42006)
		(width 0.0889)
		(layer "In11.Cu")
		(net "PD_PIROM_CPU1_ADDR2")
	)
	(arc
		(start 119.643144 -288.103056)
		(mid 119.717135 -287.82349)
		(end 119.91975 -287.617154)
		(width 0.0889)
		(layer "In11.Cu")
		(net "PD_PIROM_CPU1_ADDR2")
	)
	(arc
		(start 120.582944 -283.21127)
		(mid 120.530674 -283.028905)
		(end 120.395746 -282.895548)
		(width 0.0889)
		(layer "In11.Cu")
		(net "PD_PIROM_CPU1_ADDR2")
	)
	(arc
		(start 120.395746 -286.799782)
		(mid 120.530679 -286.666428)
		(end 120.582944 -286.48406)
		(width 0.0889)
		(layer "In11.Cu")
		(net "PD_PIROM_CPU1_ADDR2")
	)
	(arc
		(start 120.113298 -288.917126)
		(mid 120.065619 -288.734226)
		(end 119.934736 -288.597848)
		(width 0.0889)
		(layer "In11.Cu")
		(net "PD_PIROM_CPU1_ADDR2")
	)
	(arc
		(start 119.925592 -281.102562)
		(mid 120.199791 -281.026727)
		(end 120.476264 -281.093926)
		(width 0.0889)
		(layer "In11.Cu")
		(net "PD_PIROM_CPU1_ADDR2")
	)
	(arc
		(start 119.643398 -273.453098)
		(mid 119.606538 -273.291301)
		(end 119.503444 -273.161252)
		(width 0.0889)
		(layer "In11.Cu")
		(net "PD_PIROM_CPU1_ADDR2")
	)
	(arc
		(start 120.874282 -281.097482)
		(mid 121.052879 -280.778204)
		(end 120.874282 -280.458926)
		(width 0.0889)
		(layer "In11.Cu")
		(net "PD_PIROM_CPU1_ADDR2")
	)
	(arc
		(start 119.925846 -287.613598)
		(mid 120.060779 -287.480244)
		(end 120.113044 -287.297876)
		(width 0.0889)
		(layer "In11.Cu")
		(net "PD_PIROM_CPU1_ADDR2")
	)
	(arc
		(start 119.643144 -289.609784)
		(mid 119.75454 -289.416691)
		(end 119.928894 -289.277806)
		(width 0.0889)
		(layer "In11.Cu")
		(net "PD_PIROM_CPU1_ADDR2")
	)
	(arc
		(start 120.583198 -279.964134)
		(mid 120.535519 -279.781234)
		(end 120.404636 -279.644856)
		(width 0.0889)
		(layer "In11.Cu")
		(net "PD_PIROM_CPU1_ADDR2")
	)
	(arc
		(start 120.583198 -284.832044)
		(mid 120.662568 -284.55831)
		(end 120.865392 -284.35808)
		(width 0.0889)
		(layer "In11.Cu")
		(net "PD_PIROM_CPU1_ADDR2")
	)
	(arc
		(start 119.464582 -277.027894)
		(mid 119.643179 -276.708616)
		(end 119.464582 -276.389338)
		(width 0.0889)
		(layer "In11.Cu")
		(net "PD_PIROM_CPU1_ADDR2")
	)
	(arc
		(start 119.173244 -275.886164)
		(mid 119.120974 -275.703799)
		(end 118.986046 -275.570442)
		(width 0.0889)
		(layer "In11.Cu")
		(net "PD_PIROM_CPU1_ADDR2")
	)
	(arc
		(start 119.643398 -278.336502)
		(mid 119.595719 -278.153602)
		(end 119.464836 -278.017224)
		(width 0.0889)
		(layer "In11.Cu")
		(net "PD_PIROM_CPU1_ADDR2")
	)
	(arc
		(start 119.925592 -282.081478)
		(mid 119.722769 -281.881247)
		(end 119.643398 -281.607514)
		(width 0.0889)
		(layer "In11.Cu")
		(net "PD_PIROM_CPU1_ADDR2")
	)
	(arc
		(start 119.455946 -278.012144)
		(mid 119.252465 -277.81134)
		(end 119.173244 -277.536656)
		(width 0.0889)
		(layer "In11.Cu")
		(net "PD_PIROM_CPU1_ADDR2")
	)
	(arc
		(start 119.08155 -273.777456)
		(mid 119.268748 -273.827599)
		(end 119.455946 -273.777456)
		(width 0.0889)
		(layer "In11.Cu")
		(net "PD_PIROM_CPU1_ADDR2")
	)
	(arc
		(start 120.582944 -286.456882)
		(mid 120.663106 -286.184693)
		(end 120.865392 -285.985712)
		(width 0.0889)
		(layer "In11.Cu")
		(net "PD_PIROM_CPU1_ADDR2")
	)
	(arc
		(start 120.113044 -287.28924)
		(mid 120.187035 -287.009674)
		(end 120.38965 -286.803338)
		(width 0.0889)
		(layer "In11.Cu")
		(net "PD_PIROM_CPU1_ADDR2")
	)
	(segment
		(start 193.50863 -358.206548)
		(end 193.50863 -359.349548)
		(width 0.12954)
		(layer "F.Cu")
		(net "PD_PIROM_CPU1_ADDR1")
	)
	(segment
		(start 193.50863 -359.349548)
		(end 192.56248 -359.349548)
		(width 0.12954)
		(layer "F.Cu")
		(net "PD_PIROM_CPU1_ADDR1")
	)
	(segment
		(start 120.208294 -272.917158)
		(end 120.208548 -272.917412)
		(width 0.12954)
		(layer "F.Cu")
		(net "PD_PIROM_CPU1_ADDR1")
	)
	(segment
		(start 120.208548 -272.917412)
		(end 120.208548 -273.453098)
		(width 0.12954)
		(layer "F.Cu")
		(net "PD_PIROM_CPU1_ADDR1")
	)
	(via
		(at 192.56248 -359.349548)
		(size 0.508)
		(drill 0.254)
		(layers "F.Cu" "B.Cu")
		(net "PD_PIROM_CPU1_ADDR1")
	)
	(via
		(at 120.208548 -273.453098)
		(size 0.4572)
		(drill 0.2032)
		(layers "F.Cu" "B.Cu")
		(net "PD_PIROM_CPU1_ADDR1")
	)
	(segment
		(start 192.91808 -359.349548)
		(end 194.59448 -357.673148)
		(width 0.127)
		(layer "In11.Cu")
		(net "PD_PIROM_CPU1_ADDR1")
	)
	(segment
		(start 121.430796 -286.964882)
		(end 121.442988 -286.95777)
		(width 0.0889)
		(layer "In11.Cu")
		(net "PD_PIROM_CPU1_ADDR1")
	)
	(segment
		(start 121.89206 -281.272742)
		(end 121.90095 -281.267662)
		(width 0.0889)
		(layer "In11.Cu")
		(net "PD_PIROM_CPU1_ADDR1")
	)
	(segment
		(start 122.183144 -280.793698)
		(end 122.183144 -280.756106)
		(width 0.0889)
		(layer "In11.Cu")
		(net "PD_PIROM_CPU1_ADDR1")
	)
	(segment
		(start 122.183144 -282.424378)
		(end 122.183144 -282.390342)
		(width 0.0889)
		(layer "In11.Cu")
		(net "PD_PIROM_CPU1_ADDR1")
	)
	(segment
		(start 120.96115 -288.427414)
		(end 120.95226 -288.422334)
		(width 0.0889)
		(layer "In11.Cu")
		(net "PD_PIROM_CPU1_ADDR1")
	)
	(segment
		(start 122.183144 -279.165812)
		(end 122.183144 -279.140412)
		(width 0.0889)
		(layer "In11.Cu")
		(net "PD_PIROM_CPU1_ADDR1")
	)
	(segment
		(start 120.96115 -275.405088)
		(end 120.95226 -275.400008)
		(width 0.0889)
		(layer "In11.Cu")
		(net "PD_PIROM_CPU1_ADDR1")
	)
	(segment
		(start 121.89206 -286.156146)
		(end 121.90095 -286.151066)
		(width 0.0889)
		(layer "In11.Cu")
		(net "PD_PIROM_CPU1_ADDR1")
	)
	(segment
		(start 122.065288 -290.413948)
		(end 121.713244 -290.061904)
		(width 0.0889)
		(layer "In11.Cu")
		(net "PD_PIROM_CPU1_ADDR1")
	)
	(segment
		(start 160.12668 -331.688948)
		(end 129.7178 -301.280068)
		(width 0.127)
		(layer "In11.Cu")
		(net "PD_PIROM_CPU1_ADDR1")
	)
	(segment
		(start 121.900696 -283.544264)
		(end 121.891806 -283.539184)
		(width 0.0889)
		(layer "In11.Cu")
		(net "PD_PIROM_CPU1_ADDR1")
	)
	(segment
		(start 121.243344 -275.910294)
		(end 121.243344 -275.872702)
		(width 0.0889)
		(layer "In11.Cu")
		(net "PD_PIROM_CPU1_ADDR1")
	)
	(segment
		(start 122.183144 -285.662116)
		(end 122.183144 -285.64586)
		(width 0.0889)
		(layer "In11.Cu")
		(net "PD_PIROM_CPU1_ADDR1")
	)
	(segment
		(start 121.430796 -277.84679)
		(end 121.421906 -277.84171)
		(width 0.0889)
		(layer "In11.Cu")
		(net "PD_PIROM_CPU1_ADDR1")
	)
	(segment
		(start 121.891806 -282.900628)
		(end 121.900696 -282.895548)
		(width 0.0889)
		(layer "In11.Cu")
		(net "PD_PIROM_CPU1_ADDR1")
	)
	(segment
		(start 121.243344 -277.522432)
		(end 121.243344 -277.506938)
		(width 0.0889)
		(layer "In11.Cu")
		(net "PD_PIROM_CPU1_ADDR1")
	)
	(segment
		(start 192.56248 -359.349548)
		(end 192.91808 -359.349548)
		(width 0.127)
		(layer "In11.Cu")
		(net "PD_PIROM_CPU1_ADDR1")
	)
	(segment
		(start 121.713244 -290.061904)
		(end 121.713244 -289.60953)
		(width 0.0889)
		(layer "In11.Cu")
		(net "PD_PIROM_CPU1_ADDR1")
	)
	(segment
		(start 121.421906 -286.969962)
		(end 121.430796 -286.964882)
		(width 0.0889)
		(layer "In11.Cu")
		(net "PD_PIROM_CPU1_ADDR1")
	)
	(segment
		(start 120.073166 -273.802094)
		(end 120.052084 -273.724116)
		(width 0.0889)
		(layer "In11.Cu")
		(net "PD_PIROM_CPU1_ADDR1")
	)
	(segment
		(start 129.7178 -301.280068)
		(end 129.7178 -295.315386)
		(width 0.127)
		(layer "In11.Cu")
		(net "PD_PIROM_CPU1_ADDR1")
	)
	(segment
		(start 129.7178 -295.315386)
		(end 124.816362 -290.413948)
		(width 0.127)
		(layer "In11.Cu")
		(net "PD_PIROM_CPU1_ADDR1")
	)
	(segment
		(start 120.95226 -274.761452)
		(end 120.96115 -274.756372)
		(width 0.0889)
		(layer "In11.Cu")
		(net "PD_PIROM_CPU1_ADDR1")
	)
	(segment
		(start 120.052084 -273.724116)
		(end 120.208548 -273.453098)
		(width 0.0889)
		(layer "In11.Cu")
		(net "PD_PIROM_CPU1_ADDR1")
	)
	(segment
		(start 122.183144 -284.049216)
		(end 122.183144 -284.023816)
		(width 0.0889)
		(layer "In11.Cu")
		(net "PD_PIROM_CPU1_ADDR1")
	)
	(segment
		(start 120.96115 -274.756372)
		(end 120.967246 -274.752816)
		(width 0.0889)
		(layer "In11.Cu")
		(net "PD_PIROM_CPU1_ADDR1")
	)
	(segment
		(start 120.96115 -277.032974)
		(end 120.95226 -277.027894)
		(width 0.0889)
		(layer "In11.Cu")
		(net "PD_PIROM_CPU1_ADDR1")
	)
	(segment
		(start 120.95226 -276.389338)
		(end 120.96115 -276.384258)
		(width 0.0889)
		(layer "In11.Cu")
		(net "PD_PIROM_CPU1_ADDR1")
	)
	(segment
		(start 120.95226 -287.783778)
		(end 120.96115 -287.778698)
		(width 0.0889)
		(layer "In11.Cu")
		(net "PD_PIROM_CPU1_ADDR1")
	)
	(segment
		(start 121.89206 -279.644856)
		(end 121.90095 -279.639776)
		(width 0.0889)
		(layer "In11.Cu")
		(net "PD_PIROM_CPU1_ADDR1")
	)
	(segment
		(start 123.0122 -290.413948)
		(end 122.065288 -290.413948)
		(width 0.0889)
		(layer "In11.Cu")
		(net "PD_PIROM_CPU1_ADDR1")
	)
	(segment
		(start 124.816362 -290.413948)
		(end 123.0122 -290.413948)
		(width 0.127)
		(layer "In11.Cu")
		(net "PD_PIROM_CPU1_ADDR1")
	)
	(segment
		(start 120.967246 -273.781012)
		(end 120.96115 -273.777456)
		(width 0.0889)
		(layer "In11.Cu")
		(net "PD_PIROM_CPU1_ADDR1")
	)
	(segment
		(start 121.90095 -280.288492)
		(end 121.89206 -280.283412)
		(width 0.0889)
		(layer "In11.Cu")
		(net "PD_PIROM_CPU1_ADDR1")
	)
	(segment
		(start 121.243344 -287.304734)
		(end 121.243344 -287.28924)
		(width 0.0889)
		(layer "In11.Cu")
		(net "PD_PIROM_CPU1_ADDR1")
	)
	(segment
		(start 194.59448 -337.683348)
		(end 188.60008 -331.688948)
		(width 0.127)
		(layer "In11.Cu")
		(net "PD_PIROM_CPU1_ADDR1")
	)
	(segment
		(start 121.90095 -281.916378)
		(end 121.89206 -281.911298)
		(width 0.0889)
		(layer "In11.Cu")
		(net "PD_PIROM_CPU1_ADDR1")
	)
	(segment
		(start 188.60008 -331.688948)
		(end 160.12668 -331.688948)
		(width 0.127)
		(layer "In11.Cu")
		(net "PD_PIROM_CPU1_ADDR1")
	)
	(segment
		(start 121.89206 -284.52826)
		(end 121.90095 -284.52318)
		(width 0.0889)
		(layer "In11.Cu")
		(net "PD_PIROM_CPU1_ADDR1")
	)
	(segment
		(start 121.243598 -289.078416)
		(end 121.243598 -288.898584)
		(width 0.0889)
		(layer "In11.Cu")
		(net "PD_PIROM_CPU1_ADDR1")
	)
	(segment
		(start 121.90095 -285.171896)
		(end 121.89206 -285.166816)
		(width 0.0889)
		(layer "In11.Cu")
		(net "PD_PIROM_CPU1_ADDR1")
	)
	(segment
		(start 120.410478 -273.76882)
		(end 120.395746 -273.777456)
		(width 0.0889)
		(layer "In11.Cu")
		(net "PD_PIROM_CPU1_ADDR1")
	)
	(segment
		(start 194.59448 -357.673148)
		(end 194.59448 -337.683348)
		(width 0.127)
		(layer "In11.Cu")
		(net "PD_PIROM_CPU1_ADDR1")
	)
	(segment
		(start 121.713498 -278.345138)
		(end 121.713498 -278.322278)
		(width 0.0889)
		(layer "In11.Cu")
		(net "PD_PIROM_CPU1_ADDR1")
	)
	(arc
		(start 121.90095 -279.639776)
		(mid 122.103773 -279.439545)
		(end 122.183144 -279.165812)
		(width 0.0889)
		(layer "In11.Cu")
		(net "PD_PIROM_CPU1_ADDR1")
	)
	(arc
		(start 122.183144 -284.023816)
		(mid 122.105033 -283.746867)
		(end 121.900696 -283.544264)
		(width 0.0889)
		(layer "In11.Cu")
		(net "PD_PIROM_CPU1_ADDR1")
	)
	(arc
		(start 120.96115 -287.778698)
		(mid 121.163973 -287.578467)
		(end 121.243344 -287.304734)
		(width 0.0889)
		(layer "In11.Cu")
		(net "PD_PIROM_CPU1_ADDR1")
	)
	(arc
		(start 121.891806 -283.539184)
		(mid 121.713209 -283.219906)
		(end 121.891806 -282.900628)
		(width 0.0889)
		(layer "In11.Cu")
		(net "PD_PIROM_CPU1_ADDR1")
	)
	(arc
		(start 122.183144 -282.390342)
		(mid 122.103774 -282.116608)
		(end 121.90095 -281.916378)
		(width 0.0889)
		(layer "In11.Cu")
		(net "PD_PIROM_CPU1_ADDR1")
	)
	(arc
		(start 122.183144 -285.64586)
		(mid 122.103774 -285.372126)
		(end 121.90095 -285.171896)
		(width 0.0889)
		(layer "In11.Cu")
		(net "PD_PIROM_CPU1_ADDR1")
	)
	(arc
		(start 120.395746 -273.777456)
		(mid 120.237258 -273.826389)
		(end 120.073166 -273.802094)
		(width 0.0889)
		(layer "In11.Cu")
		(net "PD_PIROM_CPU1_ADDR1")
	)
	(arc
		(start 120.95226 -275.400008)
		(mid 120.773663 -275.08073)
		(end 120.95226 -274.761452)
		(width 0.0889)
		(layer "In11.Cu")
		(net "PD_PIROM_CPU1_ADDR1")
	)
	(arc
		(start 122.183144 -280.756106)
		(mid 122.102233 -280.485978)
		(end 121.90095 -280.288492)
		(width 0.0889)
		(layer "In11.Cu")
		(net "PD_PIROM_CPU1_ADDR1")
	)
	(arc
		(start 121.713498 -278.322278)
		(mid 121.634279 -278.047593)
		(end 121.430796 -277.84679)
		(width 0.0889)
		(layer "In11.Cu")
		(net "PD_PIROM_CPU1_ADDR1")
	)
	(arc
		(start 121.89206 -281.911298)
		(mid 121.713463 -281.59202)
		(end 121.89206 -281.272742)
		(width 0.0889)
		(layer "In11.Cu")
		(net "PD_PIROM_CPU1_ADDR1")
	)
	(arc
		(start 122.183144 -279.140412)
		(mid 122.105033 -278.863463)
		(end 121.900696 -278.66086)
		(width 0.0889)
		(layer "In11.Cu")
		(net "PD_PIROM_CPU1_ADDR1")
	)
	(arc
		(start 120.95226 -277.027894)
		(mid 120.773663 -276.708616)
		(end 120.95226 -276.389338)
		(width 0.0889)
		(layer "In11.Cu")
		(net "PD_PIROM_CPU1_ADDR1")
	)
	(arc
		(start 121.421906 -277.84171)
		(mid 121.290992 -277.70535)
		(end 121.243344 -277.522432)
		(width 0.0889)
		(layer "In11.Cu")
		(net "PD_PIROM_CPU1_ADDR1")
	)
	(arc
		(start 121.89206 -280.283412)
		(mid 121.713463 -279.964134)
		(end 121.89206 -279.644856)
		(width 0.0889)
		(layer "In11.Cu")
		(net "PD_PIROM_CPU1_ADDR1")
	)
	(arc
		(start 121.90095 -286.151066)
		(mid 122.107551 -285.944392)
		(end 122.183144 -285.662116)
		(width 0.0889)
		(layer "In11.Cu")
		(net "PD_PIROM_CPU1_ADDR1")
	)
	(arc
		(start 121.243598 -288.898584)
		(mid 121.163436 -288.626395)
		(end 120.96115 -288.427414)
		(width 0.0889)
		(layer "In11.Cu")
		(net "PD_PIROM_CPU1_ADDR1")
	)
	(arc
		(start 121.243344 -275.872702)
		(mid 121.162433 -275.602574)
		(end 120.96115 -275.405088)
		(width 0.0889)
		(layer "In11.Cu")
		(net "PD_PIROM_CPU1_ADDR1")
	)
	(arc
		(start 121.900696 -282.895548)
		(mid 122.102982 -282.696567)
		(end 122.183144 -282.424378)
		(width 0.0889)
		(layer "In11.Cu")
		(net "PD_PIROM_CPU1_ADDR1")
	)
	(arc
		(start 121.90095 -281.267662)
		(mid 122.103773 -281.067431)
		(end 122.183144 -280.793698)
		(width 0.0889)
		(layer "In11.Cu")
		(net "PD_PIROM_CPU1_ADDR1")
	)
	(arc
		(start 121.243344 -277.506938)
		(mid 121.163974 -277.233204)
		(end 120.96115 -277.032974)
		(width 0.0889)
		(layer "In11.Cu")
		(net "PD_PIROM_CPU1_ADDR1")
	)
	(arc
		(start 121.427748 -289.277806)
		(mid 121.318601 -289.193878)
		(end 121.243598 -289.078416)
		(width 0.0889)
		(layer "In11.Cu")
		(net "PD_PIROM_CPU1_ADDR1")
	)
	(arc
		(start 121.89206 -285.166816)
		(mid 121.713463 -284.847538)
		(end 121.89206 -284.52826)
		(width 0.0889)
		(layer "In11.Cu")
		(net "PD_PIROM_CPU1_ADDR1")
	)
	(arc
		(start 120.96115 -273.777456)
		(mid 120.686951 -273.701621)
		(end 120.410478 -273.76882)
		(width 0.0889)
		(layer "In11.Cu")
		(net "PD_PIROM_CPU1_ADDR1")
	)
	(arc
		(start 121.90095 -284.52318)
		(mid 122.103773 -284.322949)
		(end 122.183144 -284.049216)
		(width 0.0889)
		(layer "In11.Cu")
		(net "PD_PIROM_CPU1_ADDR1")
	)
	(arc
		(start 121.442988 -286.95777)
		(mid 121.641216 -286.751922)
		(end 121.713498 -286.475424)
		(width 0.0889)
		(layer "In11.Cu")
		(net "PD_PIROM_CPU1_ADDR1")
	)
	(arc
		(start 120.96115 -276.384258)
		(mid 121.163973 -276.184027)
		(end 121.243344 -275.910294)
		(width 0.0889)
		(layer "In11.Cu")
		(net "PD_PIROM_CPU1_ADDR1")
	)
	(arc
		(start 121.900696 -278.66086)
		(mid 121.765763 -278.527506)
		(end 121.713498 -278.345138)
		(width 0.0889)
		(layer "In11.Cu")
		(net "PD_PIROM_CPU1_ADDR1")
	)
	(arc
		(start 120.95226 -288.422334)
		(mid 120.773663 -288.103056)
		(end 120.95226 -287.783778)
		(width 0.0889)
		(layer "In11.Cu")
		(net "PD_PIROM_CPU1_ADDR1")
	)
	(arc
		(start 121.243344 -287.28924)
		(mid 121.291023 -287.10634)
		(end 121.421906 -286.969962)
		(width 0.0889)
		(layer "In11.Cu")
		(net "PD_PIROM_CPU1_ADDR1")
	)
	(arc
		(start 120.967246 -274.752816)
		(mid 121.243572 -274.266914)
		(end 120.967246 -273.781012)
		(width 0.0889)
		(layer "In11.Cu")
		(net "PD_PIROM_CPU1_ADDR1")
	)
	(arc
		(start 121.713498 -286.475424)
		(mid 121.761177 -286.292524)
		(end 121.89206 -286.156146)
		(width 0.0889)
		(layer "In11.Cu")
		(net "PD_PIROM_CPU1_ADDR1")
	)
	(arc
		(start 121.713244 -289.60953)
		(mid 121.601906 -289.41663)
		(end 121.427748 -289.277806)
		(width 0.0889)
		(layer "In11.Cu")
		(net "PD_PIROM_CPU1_ADDR1")
	)
	(segment
		(start 367.208816 -272.917412)
		(end 367.208816 -273.453098)
		(width 0.12954)
		(layer "F.Cu")
		(net "PD_PIROM_CPU0_ADDR2")
	)
	(segment
		(start 405.724614 -360.722926)
		(end 405.724614 -361.865926)
		(width 0.12954)
		(layer "F.Cu")
		(net "PD_PIROM_CPU0_ADDR2")
	)
	(segment
		(start 383.546858 -362.15955)
		(end 404.28799 -362.15955)
		(width 0.12954)
		(layer "F.Cu")
		(net "PD_PIROM_CPU0_ADDR2")
	)
	(segment
		(start 367.208562 -272.917158)
		(end 367.208816 -272.917412)
		(width 0.12954)
		(layer "F.Cu")
		(net "PD_PIROM_CPU0_ADDR2")
	)
	(segment
		(start 404.28799 -362.15955)
		(end 405.724614 -360.722926)
		(width 0.12954)
		(layer "F.Cu")
		(net "PD_PIROM_CPU0_ADDR2")
	)
	(via
		(at 367.208816 -273.453098)
		(size 0.4572)
		(drill 0.2032)
		(layers "F.Cu" "B.Cu")
		(net "PD_PIROM_CPU0_ADDR2")
	)
	(via
		(at 383.546858 -362.15955)
		(size 0.508)
		(drill 0.254)
		(layers "F.Cu" "B.Cu")
		(net "PD_PIROM_CPU0_ADDR2")
	)
	(segment
		(start 368.053112 -282.42006)
		(end 368.053112 -282.405836)
		(width 0.0889)
		(layer "In11.Cu")
		(net "PD_PIROM_CPU0_ADDR2")
	)
	(segment
		(start 367.36528 -273.18208)
		(end 367.208816 -273.453098)
		(width 0.0889)
		(layer "In11.Cu")
		(net "PD_PIROM_CPU0_ADDR2")
	)
	(segment
		(start 368.523266 -279.986232)
		(end 368.523266 -279.964134)
		(width 0.0889)
		(layer "In11.Cu")
		(net "PD_PIROM_CPU0_ADDR2")
	)
	(segment
		(start 370.3828 -291.351208)
		(end 369.74526 -291.351208)
		(width 0.0889)
		(layer "In11.Cu")
		(net "PD_PIROM_CPU0_ADDR2")
	)
	(segment
		(start 383.546858 -362.15955)
		(end 383.871978 -361.83443)
		(width 0.127)
		(layer "In11.Cu")
		(net "PD_PIROM_CPU0_ADDR2")
	)
	(segment
		(start 366.450118 -273.781012)
		(end 366.456214 -273.777456)
		(width 0.0889)
		(layer "In11.Cu")
		(net "PD_PIROM_CPU0_ADDR2")
	)
	(segment
		(start 368.053112 -287.297876)
		(end 368.053112 -287.28924)
		(width 0.0889)
		(layer "In11.Cu")
		(net "PD_PIROM_CPU0_ADDR2")
	)
	(segment
		(start 367.87455 -278.83104)
		(end 367.86566 -278.82596)
		(width 0.0889)
		(layer "In11.Cu")
		(net "PD_PIROM_CPU0_ADDR2")
	)
	(segment
		(start 368.81435 -283.714444)
		(end 368.80546 -283.709364)
		(width 0.0889)
		(layer "In11.Cu")
		(net "PD_PIROM_CPU0_ADDR2")
	)
	(segment
		(start 369.74526 -291.351208)
		(end 368.8842 -290.490148)
		(width 0.0889)
		(layer "In11.Cu")
		(net "PD_PIROM_CPU0_ADDR2")
	)
	(segment
		(start 368.053366 -289.077908)
		(end 368.053366 -288.917126)
		(width 0.0889)
		(layer "In11.Cu")
		(net "PD_PIROM_CPU0_ADDR2")
	)
	(segment
		(start 367.583466 -281.607514)
		(end 367.583466 -281.576526)
		(width 0.0889)
		(layer "In11.Cu")
		(net "PD_PIROM_CPU0_ADDR2")
	)
	(segment
		(start 367.404904 -278.017224)
		(end 367.396014 -278.012144)
		(width 0.0889)
		(layer "In11.Cu")
		(net "PD_PIROM_CPU0_ADDR2")
	)
	(segment
		(start 367.40465 -276.389338)
		(end 367.39576 -276.384258)
		(width 0.0889)
		(layer "In11.Cu")
		(net "PD_PIROM_CPU0_ADDR2")
	)
	(segment
		(start 367.113312 -277.536656)
		(end 367.113312 -277.512526)
		(width 0.0889)
		(layer "In11.Cu")
		(net "PD_PIROM_CPU0_ADDR2")
	)
	(segment
		(start 367.583212 -288.11728)
		(end 367.583212 -288.103056)
		(width 0.0889)
		(layer "In11.Cu")
		(net "PD_PIROM_CPU0_ADDR2")
	)
	(segment
		(start 367.113312 -275.904706)
		(end 367.113312 -275.886164)
		(width 0.0889)
		(layer "In11.Cu")
		(net "PD_PIROM_CPU0_ADDR2")
	)
	(segment
		(start 384.915918 -361.83443)
		(end 393.824206 -352.926142)
		(width 0.127)
		(layer "In11.Cu")
		(net "PD_PIROM_CPU0_ADDR2")
	)
	(segment
		(start 368.523266 -284.863032)
		(end 368.523266 -284.832044)
		(width 0.0889)
		(layer "In11.Cu")
		(net "PD_PIROM_CPU0_ADDR2")
	)
	(segment
		(start 393.824206 -316.315598)
		(end 376.15114 -298.642532)
		(width 0.127)
		(layer "In11.Cu")
		(net "PD_PIROM_CPU0_ADDR2")
	)
	(segment
		(start 367.8174 -290.490148)
		(end 367.583212 -290.25596)
		(width 0.0889)
		(layer "In11.Cu")
		(net "PD_PIROM_CPU0_ADDR2")
	)
	(segment
		(start 367.443512 -273.161252)
		(end 367.36528 -273.18208)
		(width 0.0889)
		(layer "In11.Cu")
		(net "PD_PIROM_CPU0_ADDR2")
	)
	(segment
		(start 376.15114 -298.642532)
		(end 376.15114 -295.238932)
		(width 0.127)
		(layer "In11.Cu")
		(net "PD_PIROM_CPU0_ADDR2")
	)
	(segment
		(start 366.45342 -274.754848)
		(end 366.450118 -274.752816)
		(width 0.0889)
		(layer "In11.Cu")
		(net "PD_PIROM_CPU0_ADDR2")
	)
	(segment
		(start 368.80546 -281.102562)
		(end 368.81435 -281.097482)
		(width 0.0889)
		(layer "In11.Cu")
		(net "PD_PIROM_CPU0_ADDR2")
	)
	(segment
		(start 368.339878 -279.642062)
		(end 368.335814 -279.639776)
		(width 0.0889)
		(layer "In11.Cu")
		(net "PD_PIROM_CPU0_ADDR2")
	)
	(segment
		(start 366.456976 -274.75688)
		(end 366.456214 -274.756372)
		(width 0.0889)
		(layer "In11.Cu")
		(net "PD_PIROM_CPU0_ADDR2")
	)
	(segment
		(start 366.456214 -273.777456)
		(end 366.470946 -273.76882)
		(width 0.0889)
		(layer "In11.Cu")
		(net "PD_PIROM_CPU0_ADDR2")
	)
	(segment
		(start 372.263416 -291.351208)
		(end 370.3828 -291.351208)
		(width 0.127)
		(layer "In11.Cu")
		(net "PD_PIROM_CPU0_ADDR2")
	)
	(segment
		(start 367.396014 -273.777456)
		(end 367.404904 -273.772376)
		(width 0.0889)
		(layer "In11.Cu")
		(net "PD_PIROM_CPU0_ADDR2")
	)
	(segment
		(start 367.874804 -288.597848)
		(end 367.865914 -288.592768)
		(width 0.0889)
		(layer "In11.Cu")
		(net "PD_PIROM_CPU0_ADDR2")
	)
	(segment
		(start 367.39576 -277.032974)
		(end 367.40465 -277.027894)
		(width 0.0889)
		(layer "In11.Cu")
		(net "PD_PIROM_CPU0_ADDR2")
	)
	(segment
		(start 368.335814 -279.639776)
		(end 368.323622 -279.632664)
		(width 0.0889)
		(layer "In11.Cu")
		(net "PD_PIROM_CPU0_ADDR2")
	)
	(segment
		(start 368.81435 -280.458926)
		(end 368.80546 -280.453846)
		(width 0.0889)
		(layer "In11.Cu")
		(net "PD_PIROM_CPU0_ADDR2")
	)
	(segment
		(start 367.859818 -287.617154)
		(end 367.865914 -287.613598)
		(width 0.0889)
		(layer "In11.Cu")
		(net "PD_PIROM_CPU0_ADDR2")
	)
	(segment
		(start 368.81435 -285.342076)
		(end 368.80546 -285.336996)
		(width 0.0889)
		(layer "In11.Cu")
		(net "PD_PIROM_CPU0_ADDR2")
	)
	(segment
		(start 393.824206 -352.926142)
		(end 393.824206 -316.315598)
		(width 0.127)
		(layer "In11.Cu")
		(net "PD_PIROM_CPU0_ADDR2")
	)
	(segment
		(start 368.523012 -286.48406)
		(end 368.523012 -286.456882)
		(width 0.0889)
		(layer "In11.Cu")
		(net "PD_PIROM_CPU0_ADDR2")
	)
	(segment
		(start 368.329718 -286.803338)
		(end 368.335814 -286.799782)
		(width 0.0889)
		(layer "In11.Cu")
		(net "PD_PIROM_CPU0_ADDR2")
	)
	(segment
		(start 383.871978 -361.83443)
		(end 384.915918 -361.83443)
		(width 0.127)
		(layer "In11.Cu")
		(net "PD_PIROM_CPU0_ADDR2")
	)
	(segment
		(start 376.15114 -295.238932)
		(end 372.263416 -291.351208)
		(width 0.127)
		(layer "In11.Cu")
		(net "PD_PIROM_CPU0_ADDR2")
	)
	(segment
		(start 368.8842 -290.490148)
		(end 367.8174 -290.490148)
		(width 0.0889)
		(layer "In11.Cu")
		(net "PD_PIROM_CPU0_ADDR2")
	)
	(segment
		(start 366.456214 -274.756372)
		(end 366.45342 -274.754848)
		(width 0.0889)
		(layer "In11.Cu")
		(net "PD_PIROM_CPU0_ADDR2")
	)
	(segment
		(start 367.583466 -278.351996)
		(end 367.583466 -278.336502)
		(width 0.0889)
		(layer "In11.Cu")
		(net "PD_PIROM_CPU0_ADDR2")
	)
	(segment
		(start 368.80546 -285.985712)
		(end 368.81435 -285.980632)
		(width 0.0889)
		(layer "In11.Cu")
		(net "PD_PIROM_CPU0_ADDR2")
	)
	(segment
		(start 367.87455 -282.086558)
		(end 367.86566 -282.081478)
		(width 0.0889)
		(layer "In11.Cu")
		(net "PD_PIROM_CPU0_ADDR2")
	)
	(segment
		(start 366.643666 -275.081238)
		(end 366.643666 -275.078444)
		(width 0.0889)
		(layer "In11.Cu")
		(net "PD_PIROM_CPU0_ADDR2")
	)
	(segment
		(start 368.80546 -284.35808)
		(end 368.81435 -284.353)
		(width 0.0889)
		(layer "In11.Cu")
		(net "PD_PIROM_CPU0_ADDR2")
	)
	(segment
		(start 367.583212 -290.25596)
		(end 367.583212 -289.609784)
		(width 0.0889)
		(layer "In11.Cu")
		(net "PD_PIROM_CPU0_ADDR2")
	)
	(segment
		(start 368.523012 -283.229812)
		(end 368.523012 -283.21127)
		(width 0.0889)
		(layer "In11.Cu")
		(net "PD_PIROM_CPU0_ADDR2")
	)
	(segment
		(start 368.416332 -281.093926)
		(end 368.431064 -281.102562)
		(width 0.0889)
		(layer "In11.Cu")
		(net "PD_PIROM_CPU0_ADDR2")
	)
	(segment
		(start 368.344704 -279.644856)
		(end 368.339878 -279.642062)
		(width 0.0889)
		(layer "In11.Cu")
		(net "PD_PIROM_CPU0_ADDR2")
	)
	(arc
		(start 367.113312 -275.886164)
		(mid 367.061042 -275.703799)
		(end 366.926114 -275.570442)
		(width 0.0889)
		(layer "In11.Cu")
		(net "PD_PIROM_CPU0_ADDR2")
	)
	(arc
		(start 367.86566 -282.081478)
		(mid 367.662837 -281.881247)
		(end 367.583466 -281.607514)
		(width 0.0889)
		(layer "In11.Cu")
		(net "PD_PIROM_CPU0_ADDR2")
	)
	(arc
		(start 368.523012 -286.456882)
		(mid 368.603174 -286.184693)
		(end 368.80546 -285.985712)
		(width 0.0889)
		(layer "In11.Cu")
		(net "PD_PIROM_CPU0_ADDR2")
	)
	(arc
		(start 368.80546 -280.453846)
		(mid 368.604178 -280.256359)
		(end 368.523266 -279.986232)
		(width 0.0889)
		(layer "In11.Cu")
		(net "PD_PIROM_CPU0_ADDR2")
	)
	(arc
		(start 368.81435 -284.353)
		(mid 368.992947 -284.033722)
		(end 368.81435 -283.714444)
		(width 0.0889)
		(layer "In11.Cu")
		(net "PD_PIROM_CPU0_ADDR2")
	)
	(arc
		(start 366.470946 -273.76882)
		(mid 366.747421 -273.7015)
		(end 367.021618 -273.777456)
		(width 0.0889)
		(layer "In11.Cu")
		(net "PD_PIROM_CPU0_ADDR2")
	)
	(arc
		(start 367.583466 -278.336502)
		(mid 367.535787 -278.153602)
		(end 367.404904 -278.017224)
		(width 0.0889)
		(layer "In11.Cu")
		(net "PD_PIROM_CPU0_ADDR2")
	)
	(arc
		(start 368.335814 -286.799782)
		(mid 368.470747 -286.666428)
		(end 368.523012 -286.48406)
		(width 0.0889)
		(layer "In11.Cu")
		(net "PD_PIROM_CPU0_ADDR2")
	)
	(arc
		(start 368.323622 -279.632664)
		(mid 368.125394 -279.426816)
		(end 368.053112 -279.150318)
		(width 0.0889)
		(layer "In11.Cu")
		(net "PD_PIROM_CPU0_ADDR2")
	)
	(arc
		(start 367.868962 -289.277806)
		(mid 367.978358 -289.193709)
		(end 368.053366 -289.077908)
		(width 0.0889)
		(layer "In11.Cu")
		(net "PD_PIROM_CPU0_ADDR2")
	)
	(arc
		(start 368.523266 -279.964134)
		(mid 368.475587 -279.781234)
		(end 368.344704 -279.644856)
		(width 0.0889)
		(layer "In11.Cu")
		(net "PD_PIROM_CPU0_ADDR2")
	)
	(arc
		(start 367.021618 -273.777456)
		(mid 367.208816 -273.827599)
		(end 367.396014 -273.777456)
		(width 0.0889)
		(layer "In11.Cu")
		(net "PD_PIROM_CPU0_ADDR2")
	)
	(arc
		(start 368.80546 -283.709364)
		(mid 368.601125 -283.506759)
		(end 368.523012 -283.229812)
		(width 0.0889)
		(layer "In11.Cu")
		(net "PD_PIROM_CPU0_ADDR2")
	)
	(arc
		(start 368.80546 -285.336996)
		(mid 368.602637 -285.136765)
		(end 368.523266 -284.863032)
		(width 0.0889)
		(layer "In11.Cu")
		(net "PD_PIROM_CPU0_ADDR2")
	)
	(arc
		(start 367.39576 -276.384258)
		(mid 367.191425 -276.181653)
		(end 367.113312 -275.904706)
		(width 0.0889)
		(layer "In11.Cu")
		(net "PD_PIROM_CPU0_ADDR2")
	)
	(arc
		(start 367.86566 -278.82596)
		(mid 367.662837 -278.625729)
		(end 367.583466 -278.351996)
		(width 0.0889)
		(layer "In11.Cu")
		(net "PD_PIROM_CPU0_ADDR2")
	)
	(arc
		(start 368.523012 -283.21127)
		(mid 368.470742 -283.028905)
		(end 368.335814 -282.895548)
		(width 0.0889)
		(layer "In11.Cu")
		(net "PD_PIROM_CPU0_ADDR2")
	)
	(arc
		(start 368.335814 -282.895548)
		(mid 368.132333 -282.694744)
		(end 368.053112 -282.42006)
		(width 0.0889)
		(layer "In11.Cu")
		(net "PD_PIROM_CPU0_ADDR2")
	)
	(arc
		(start 367.865914 -287.613598)
		(mid 368.000847 -287.480244)
		(end 368.053112 -287.297876)
		(width 0.0889)
		(layer "In11.Cu")
		(net "PD_PIROM_CPU0_ADDR2")
	)
	(arc
		(start 368.523266 -284.832044)
		(mid 368.602636 -284.55831)
		(end 368.80546 -284.35808)
		(width 0.0889)
		(layer "In11.Cu")
		(net "PD_PIROM_CPU0_ADDR2")
	)
	(arc
		(start 367.86566 -281.102562)
		(mid 368.139859 -281.026727)
		(end 368.416332 -281.093926)
		(width 0.0889)
		(layer "In11.Cu")
		(net "PD_PIROM_CPU0_ADDR2")
	)
	(arc
		(start 367.583466 -281.576526)
		(mid 367.662836 -281.302792)
		(end 367.86566 -281.102562)
		(width 0.0889)
		(layer "In11.Cu")
		(net "PD_PIROM_CPU0_ADDR2")
	)
	(arc
		(start 367.583212 -289.609784)
		(mid 367.694608 -289.416691)
		(end 367.868962 -289.277806)
		(width 0.0889)
		(layer "In11.Cu")
		(net "PD_PIROM_CPU0_ADDR2")
	)
	(arc
		(start 367.583212 -288.103056)
		(mid 367.657203 -287.82349)
		(end 367.859818 -287.617154)
		(width 0.0889)
		(layer "In11.Cu")
		(net "PD_PIROM_CPU0_ADDR2")
	)
	(arc
		(start 368.053112 -279.150318)
		(mid 368.005433 -278.967418)
		(end 367.87455 -278.83104)
		(width 0.0889)
		(layer "In11.Cu")
		(net "PD_PIROM_CPU0_ADDR2")
	)
	(arc
		(start 367.404904 -273.772376)
		(mid 367.535818 -273.636016)
		(end 367.583466 -273.453098)
		(width 0.0889)
		(layer "In11.Cu")
		(net "PD_PIROM_CPU0_ADDR2")
	)
	(arc
		(start 368.053112 -287.28924)
		(mid 368.127103 -287.009674)
		(end 368.329718 -286.803338)
		(width 0.0889)
		(layer "In11.Cu")
		(net "PD_PIROM_CPU0_ADDR2")
	)
	(arc
		(start 368.053366 -288.917126)
		(mid 368.005687 -288.734226)
		(end 367.874804 -288.597848)
		(width 0.0889)
		(layer "In11.Cu")
		(net "PD_PIROM_CPU0_ADDR2")
	)
	(arc
		(start 368.81435 -285.980632)
		(mid 368.992947 -285.661354)
		(end 368.81435 -285.342076)
		(width 0.0889)
		(layer "In11.Cu")
		(net "PD_PIROM_CPU0_ADDR2")
	)
	(arc
		(start 366.926114 -275.570442)
		(mid 366.719354 -275.363679)
		(end 366.643666 -275.081238)
		(width 0.0889)
		(layer "In11.Cu")
		(net "PD_PIROM_CPU0_ADDR2")
	)
	(arc
		(start 368.053112 -282.405836)
		(mid 368.005433 -282.222936)
		(end 367.87455 -282.086558)
		(width 0.0889)
		(layer "In11.Cu")
		(net "PD_PIROM_CPU0_ADDR2")
	)
	(arc
		(start 367.865914 -288.592768)
		(mid 367.662433 -288.391964)
		(end 367.583212 -288.11728)
		(width 0.0889)
		(layer "In11.Cu")
		(net "PD_PIROM_CPU0_ADDR2")
	)
	(arc
		(start 366.450118 -274.752816)
		(mid 366.173544 -274.266914)
		(end 366.450118 -273.781012)
		(width 0.0889)
		(layer "In11.Cu")
		(net "PD_PIROM_CPU0_ADDR2")
	)
	(arc
		(start 368.431064 -281.102562)
		(mid 368.618262 -281.152705)
		(end 368.80546 -281.102562)
		(width 0.0889)
		(layer "In11.Cu")
		(net "PD_PIROM_CPU0_ADDR2")
	)
	(arc
		(start 367.583466 -273.453098)
		(mid 367.546606 -273.291301)
		(end 367.443512 -273.161252)
		(width 0.0889)
		(layer "In11.Cu")
		(net "PD_PIROM_CPU0_ADDR2")
	)
	(arc
		(start 367.396014 -278.012144)
		(mid 367.192533 -277.81134)
		(end 367.113312 -277.536656)
		(width 0.0889)
		(layer "In11.Cu")
		(net "PD_PIROM_CPU0_ADDR2")
	)
	(arc
		(start 366.643666 -275.078444)
		(mid 366.593614 -274.892524)
		(end 366.456976 -274.75688)
		(width 0.0889)
		(layer "In11.Cu")
		(net "PD_PIROM_CPU0_ADDR2")
	)
	(arc
		(start 367.40465 -277.027894)
		(mid 367.583247 -276.708616)
		(end 367.40465 -276.389338)
		(width 0.0889)
		(layer "In11.Cu")
		(net "PD_PIROM_CPU0_ADDR2")
	)
	(arc
		(start 368.81435 -281.097482)
		(mid 368.992947 -280.778204)
		(end 368.81435 -280.458926)
		(width 0.0889)
		(layer "In11.Cu")
		(net "PD_PIROM_CPU0_ADDR2")
	)
	(arc
		(start 367.113312 -277.512526)
		(mid 367.191423 -277.235577)
		(end 367.39576 -277.032974)
		(width 0.0889)
		(layer "In11.Cu")
		(net "PD_PIROM_CPU0_ADDR2")
	)
	(segment
		(start 385.098798 -363.76229)
		(end 388.91337 -367.576862)
		(width 0.12954)
		(layer "F.Cu")
		(net "PD_PIROM_CPU0_ADDR1")
	)
	(segment
		(start 388.91337 -367.576862)
		(end 405.724614 -367.576862)
		(width 0.12954)
		(layer "F.Cu")
		(net "PD_PIROM_CPU0_ADDR1")
	)
	(segment
		(start 368.148616 -272.917412)
		(end 368.148616 -273.453098)
		(width 0.12954)
		(layer "F.Cu")
		(net "PD_PIROM_CPU0_ADDR1")
	)
	(segment
		(start 368.148362 -272.917158)
		(end 368.148616 -272.917412)
		(width 0.12954)
		(layer "F.Cu")
		(net "PD_PIROM_CPU0_ADDR1")
	)
	(segment
		(start 405.724614 -368.826034)
		(end 405.724614 -367.576862)
		(width 0.12954)
		(layer "F.Cu")
		(net "PD_PIROM_CPU0_ADDR1")
	)
	(via
		(at 385.098798 -363.76229)
		(size 0.508)
		(drill 0.254)
		(layers "F.Cu" "B.Cu")
		(net "PD_PIROM_CPU0_ADDR1")
	)
	(via
		(at 368.148616 -273.453098)
		(size 0.4572)
		(drill 0.2032)
		(layers "F.Cu" "B.Cu")
		(net "PD_PIROM_CPU0_ADDR1")
	)
	(segment
		(start 369.832128 -279.644856)
		(end 369.841018 -279.639776)
		(width 0.0889)
		(layer "In11.Cu")
		(net "PD_PIROM_CPU0_ADDR1")
	)
	(segment
		(start 385.098798 -363.76229)
		(end 385.098798 -363.05363)
		(width 0.127)
		(layer "In11.Cu")
		(net "PD_PIROM_CPU0_ADDR1")
	)
	(segment
		(start 368.892328 -287.783778)
		(end 368.901218 -287.778698)
		(width 0.0889)
		(layer "In11.Cu")
		(net "PD_PIROM_CPU0_ADDR1")
	)
	(segment
		(start 394.863066 -353.289362)
		(end 394.863066 -315.884814)
		(width 0.127)
		(layer "In11.Cu")
		(net "PD_PIROM_CPU0_ADDR1")
	)
	(segment
		(start 385.098798 -363.05363)
		(end 394.863066 -353.289362)
		(width 0.127)
		(layer "In11.Cu")
		(net "PD_PIROM_CPU0_ADDR1")
	)
	(segment
		(start 369.832128 -286.156146)
		(end 369.841018 -286.151066)
		(width 0.0889)
		(layer "In11.Cu")
		(net "PD_PIROM_CPU0_ADDR1")
	)
	(segment
		(start 369.183412 -275.910294)
		(end 369.183412 -275.872702)
		(width 0.0889)
		(layer "In11.Cu")
		(net "PD_PIROM_CPU0_ADDR1")
	)
	(segment
		(start 394.863066 -315.884814)
		(end 377.19 -298.211748)
		(width 0.127)
		(layer "In11.Cu")
		(net "PD_PIROM_CPU0_ADDR1")
	)
	(segment
		(start 369.832128 -284.52826)
		(end 369.841018 -284.52318)
		(width 0.0889)
		(layer "In11.Cu")
		(net "PD_PIROM_CPU0_ADDR1")
	)
	(segment
		(start 369.370864 -286.964882)
		(end 369.383056 -286.95777)
		(width 0.0889)
		(layer "In11.Cu")
		(net "PD_PIROM_CPU0_ADDR1")
	)
	(segment
		(start 372.6942 -290.312348)
		(end 370.3828 -290.312348)
		(width 0.127)
		(layer "In11.Cu")
		(net "PD_PIROM_CPU0_ADDR1")
	)
	(segment
		(start 369.841018 -281.916378)
		(end 369.832128 -281.911298)
		(width 0.0889)
		(layer "In11.Cu")
		(net "PD_PIROM_CPU0_ADDR1")
	)
	(segment
		(start 369.183412 -277.522432)
		(end 369.183412 -277.506938)
		(width 0.0889)
		(layer "In11.Cu")
		(net "PD_PIROM_CPU0_ADDR1")
	)
	(segment
		(start 370.123212 -285.662116)
		(end 370.123212 -285.64586)
		(width 0.0889)
		(layer "In11.Cu")
		(net "PD_PIROM_CPU0_ADDR1")
	)
	(segment
		(start 377.19 -298.211748)
		(end 377.19 -294.808148)
		(width 0.127)
		(layer "In11.Cu")
		(net "PD_PIROM_CPU0_ADDR1")
	)
	(segment
		(start 368.901218 -277.032974)
		(end 368.892328 -277.027894)
		(width 0.0889)
		(layer "In11.Cu")
		(net "PD_PIROM_CPU0_ADDR1")
	)
	(segment
		(start 369.370864 -277.84679)
		(end 369.361974 -277.84171)
		(width 0.0889)
		(layer "In11.Cu")
		(net "PD_PIROM_CPU0_ADDR1")
	)
	(segment
		(start 370.123212 -280.793698)
		(end 370.123212 -280.756106)
		(width 0.0889)
		(layer "In11.Cu")
		(net "PD_PIROM_CPU0_ADDR1")
	)
	(segment
		(start 370.123212 -284.049216)
		(end 370.123212 -284.023816)
		(width 0.0889)
		(layer "In11.Cu")
		(net "PD_PIROM_CPU0_ADDR1")
	)
	(segment
		(start 368.907314 -273.781012)
		(end 368.901218 -273.777456)
		(width 0.0889)
		(layer "In11.Cu")
		(net "PD_PIROM_CPU0_ADDR1")
	)
	(segment
		(start 369.361974 -286.969962)
		(end 369.370864 -286.964882)
		(width 0.0889)
		(layer "In11.Cu")
		(net "PD_PIROM_CPU0_ADDR1")
	)
	(segment
		(start 370.3828 -290.312348)
		(end 369.951 -290.312348)
		(width 0.0889)
		(layer "In11.Cu")
		(net "PD_PIROM_CPU0_ADDR1")
	)
	(segment
		(start 369.951 -290.312348)
		(end 369.653312 -290.01466)
		(width 0.0889)
		(layer "In11.Cu")
		(net "PD_PIROM_CPU0_ADDR1")
	)
	(segment
		(start 369.183666 -289.078416)
		(end 369.183666 -288.898584)
		(width 0.0889)
		(layer "In11.Cu")
		(net "PD_PIROM_CPU0_ADDR1")
	)
	(segment
		(start 370.123212 -279.165812)
		(end 370.123212 -279.140412)
		(width 0.0889)
		(layer "In11.Cu")
		(net "PD_PIROM_CPU0_ADDR1")
	)
	(segment
		(start 368.339878 -273.77517)
		(end 368.335814 -273.777456)
		(width 0.0889)
		(layer "In11.Cu")
		(net "PD_PIROM_CPU0_ADDR1")
	)
	(segment
		(start 369.653566 -278.345138)
		(end 369.653566 -278.322278)
		(width 0.0889)
		(layer "In11.Cu")
		(net "PD_PIROM_CPU0_ADDR1")
	)
	(segment
		(start 367.992152 -273.724116)
		(end 368.148616 -273.453098)
		(width 0.0889)
		(layer "In11.Cu")
		(net "PD_PIROM_CPU0_ADDR1")
	)
	(segment
		(start 369.832128 -281.272742)
		(end 369.841018 -281.267662)
		(width 0.0889)
		(layer "In11.Cu")
		(net "PD_PIROM_CPU0_ADDR1")
	)
	(segment
		(start 369.840764 -283.544264)
		(end 369.831874 -283.539184)
		(width 0.0889)
		(layer "In11.Cu")
		(net "PD_PIROM_CPU0_ADDR1")
	)
	(segment
		(start 368.901218 -275.405088)
		(end 368.892328 -275.400008)
		(width 0.0889)
		(layer "In11.Cu")
		(net "PD_PIROM_CPU0_ADDR1")
	)
	(segment
		(start 369.841018 -280.288492)
		(end 369.832128 -280.283412)
		(width 0.0889)
		(layer "In11.Cu")
		(net "PD_PIROM_CPU0_ADDR1")
	)
	(segment
		(start 370.123212 -282.424378)
		(end 370.123212 -282.390342)
		(width 0.0889)
		(layer "In11.Cu")
		(net "PD_PIROM_CPU0_ADDR1")
	)
	(segment
		(start 369.831874 -282.900628)
		(end 369.840764 -282.895548)
		(width 0.0889)
		(layer "In11.Cu")
		(net "PD_PIROM_CPU0_ADDR1")
	)
	(segment
		(start 368.892328 -274.761452)
		(end 368.901218 -274.756372)
		(width 0.0889)
		(layer "In11.Cu")
		(net "PD_PIROM_CPU0_ADDR1")
	)
	(segment
		(start 368.350546 -273.76882)
		(end 368.339878 -273.77517)
		(width 0.0889)
		(layer "In11.Cu")
		(net "PD_PIROM_CPU0_ADDR1")
	)
	(segment
		(start 368.892328 -276.389338)
		(end 368.901218 -276.384258)
		(width 0.0889)
		(layer "In11.Cu")
		(net "PD_PIROM_CPU0_ADDR1")
	)
	(segment
		(start 369.841018 -285.171896)
		(end 369.832128 -285.166816)
		(width 0.0889)
		(layer "In11.Cu")
		(net "PD_PIROM_CPU0_ADDR1")
	)
	(segment
		(start 369.183412 -287.304734)
		(end 369.183412 -287.28924)
		(width 0.0889)
		(layer "In11.Cu")
		(net "PD_PIROM_CPU0_ADDR1")
	)
	(segment
		(start 368.901218 -288.427414)
		(end 368.892328 -288.422334)
		(width 0.0889)
		(layer "In11.Cu")
		(net "PD_PIROM_CPU0_ADDR1")
	)
	(segment
		(start 377.19 -294.808148)
		(end 372.6942 -290.312348)
		(width 0.127)
		(layer "In11.Cu")
		(net "PD_PIROM_CPU0_ADDR1")
	)
	(segment
		(start 368.901218 -274.756372)
		(end 368.907314 -274.752816)
		(width 0.0889)
		(layer "In11.Cu")
		(net "PD_PIROM_CPU0_ADDR1")
	)
	(segment
		(start 368.013234 -273.802094)
		(end 367.992152 -273.724116)
		(width 0.0889)
		(layer "In11.Cu")
		(net "PD_PIROM_CPU0_ADDR1")
	)
	(segment
		(start 369.653312 -290.01466)
		(end 369.653312 -289.60953)
		(width 0.0889)
		(layer "In11.Cu")
		(net "PD_PIROM_CPU0_ADDR1")
	)
	(arc
		(start 370.123212 -279.140412)
		(mid 370.045101 -278.863463)
		(end 369.840764 -278.66086)
		(width 0.0889)
		(layer "In11.Cu")
		(net "PD_PIROM_CPU0_ADDR1")
	)
	(arc
		(start 368.901218 -273.777456)
		(mid 368.627019 -273.701621)
		(end 368.350546 -273.76882)
		(width 0.0889)
		(layer "In11.Cu")
		(net "PD_PIROM_CPU0_ADDR1")
	)
	(arc
		(start 369.840764 -278.66086)
		(mid 369.705831 -278.527506)
		(end 369.653566 -278.345138)
		(width 0.0889)
		(layer "In11.Cu")
		(net "PD_PIROM_CPU0_ADDR1")
	)
	(arc
		(start 370.123212 -285.64586)
		(mid 370.043842 -285.372126)
		(end 369.841018 -285.171896)
		(width 0.0889)
		(layer "In11.Cu")
		(net "PD_PIROM_CPU0_ADDR1")
	)
	(arc
		(start 368.892328 -275.400008)
		(mid 368.713731 -275.08073)
		(end 368.892328 -274.761452)
		(width 0.0889)
		(layer "In11.Cu")
		(net "PD_PIROM_CPU0_ADDR1")
	)
	(arc
		(start 369.841018 -286.151066)
		(mid 370.047619 -285.944392)
		(end 370.123212 -285.662116)
		(width 0.0889)
		(layer "In11.Cu")
		(net "PD_PIROM_CPU0_ADDR1")
	)
	(arc
		(start 369.841018 -281.267662)
		(mid 370.043841 -281.067431)
		(end 370.123212 -280.793698)
		(width 0.0889)
		(layer "In11.Cu")
		(net "PD_PIROM_CPU0_ADDR1")
	)
	(arc
		(start 369.832128 -281.911298)
		(mid 369.653531 -281.59202)
		(end 369.832128 -281.272742)
		(width 0.0889)
		(layer "In11.Cu")
		(net "PD_PIROM_CPU0_ADDR1")
	)
	(arc
		(start 369.653566 -286.475424)
		(mid 369.701245 -286.292524)
		(end 369.832128 -286.156146)
		(width 0.0889)
		(layer "In11.Cu")
		(net "PD_PIROM_CPU0_ADDR1")
	)
	(arc
		(start 369.183666 -288.898584)
		(mid 369.103504 -288.626395)
		(end 368.901218 -288.427414)
		(width 0.0889)
		(layer "In11.Cu")
		(net "PD_PIROM_CPU0_ADDR1")
	)
	(arc
		(start 368.901218 -287.778698)
		(mid 369.104041 -287.578467)
		(end 369.183412 -287.304734)
		(width 0.0889)
		(layer "In11.Cu")
		(net "PD_PIROM_CPU0_ADDR1")
	)
	(arc
		(start 369.653566 -278.322278)
		(mid 369.574347 -278.047593)
		(end 369.370864 -277.84679)
		(width 0.0889)
		(layer "In11.Cu")
		(net "PD_PIROM_CPU0_ADDR1")
	)
	(arc
		(start 369.841018 -279.639776)
		(mid 370.043841 -279.439545)
		(end 370.123212 -279.165812)
		(width 0.0889)
		(layer "In11.Cu")
		(net "PD_PIROM_CPU0_ADDR1")
	)
	(arc
		(start 368.907314 -274.752816)
		(mid 369.18364 -274.266914)
		(end 368.907314 -273.781012)
		(width 0.0889)
		(layer "In11.Cu")
		(net "PD_PIROM_CPU0_ADDR1")
	)
	(arc
		(start 369.841018 -284.52318)
		(mid 370.043841 -284.322949)
		(end 370.123212 -284.049216)
		(width 0.0889)
		(layer "In11.Cu")
		(net "PD_PIROM_CPU0_ADDR1")
	)
	(arc
		(start 368.892328 -288.422334)
		(mid 368.761414 -288.285974)
		(end 368.713766 -288.103056)
		(width 0.0889)
		(layer "In11.Cu")
		(net "PD_PIROM_CPU0_ADDR1")
	)
	(arc
		(start 369.367816 -289.277806)
		(mid 369.258669 -289.193878)
		(end 369.183666 -289.078416)
		(width 0.0889)
		(layer "In11.Cu")
		(net "PD_PIROM_CPU0_ADDR1")
	)
	(arc
		(start 368.335814 -273.777456)
		(mid 368.177326 -273.826389)
		(end 368.013234 -273.802094)
		(width 0.0889)
		(layer "In11.Cu")
		(net "PD_PIROM_CPU0_ADDR1")
	)
	(arc
		(start 368.713766 -288.103056)
		(mid 368.761445 -287.920156)
		(end 368.892328 -287.783778)
		(width 0.0889)
		(layer "In11.Cu")
		(net "PD_PIROM_CPU0_ADDR1")
	)
	(arc
		(start 370.123212 -284.023816)
		(mid 370.045101 -283.746867)
		(end 369.840764 -283.544264)
		(width 0.0889)
		(layer "In11.Cu")
		(net "PD_PIROM_CPU0_ADDR1")
	)
	(arc
		(start 369.361974 -277.84171)
		(mid 369.23106 -277.70535)
		(end 369.183412 -277.522432)
		(width 0.0889)
		(layer "In11.Cu")
		(net "PD_PIROM_CPU0_ADDR1")
	)
	(arc
		(start 369.832128 -280.283412)
		(mid 369.653531 -279.964134)
		(end 369.832128 -279.644856)
		(width 0.0889)
		(layer "In11.Cu")
		(net "PD_PIROM_CPU0_ADDR1")
	)
	(arc
		(start 368.892328 -277.027894)
		(mid 368.713731 -276.708616)
		(end 368.892328 -276.389338)
		(width 0.0889)
		(layer "In11.Cu")
		(net "PD_PIROM_CPU0_ADDR1")
	)
	(arc
		(start 369.832128 -285.166816)
		(mid 369.653531 -284.847538)
		(end 369.832128 -284.52826)
		(width 0.0889)
		(layer "In11.Cu")
		(net "PD_PIROM_CPU0_ADDR1")
	)
	(arc
		(start 369.183412 -277.506938)
		(mid 369.104042 -277.233204)
		(end 368.901218 -277.032974)
		(width 0.0889)
		(layer "In11.Cu")
		(net "PD_PIROM_CPU0_ADDR1")
	)
	(arc
		(start 369.383056 -286.95777)
		(mid 369.581284 -286.751922)
		(end 369.653566 -286.475424)
		(width 0.0889)
		(layer "In11.Cu")
		(net "PD_PIROM_CPU0_ADDR1")
	)
	(arc
		(start 369.653312 -289.60953)
		(mid 369.541974 -289.41663)
		(end 369.367816 -289.277806)
		(width 0.0889)
		(layer "In11.Cu")
		(net "PD_PIROM_CPU0_ADDR1")
	)
	(arc
		(start 370.123212 -282.390342)
		(mid 370.043842 -282.116608)
		(end 369.841018 -281.916378)
		(width 0.0889)
		(layer "In11.Cu")
		(net "PD_PIROM_CPU0_ADDR1")
	)
	(arc
		(start 369.831874 -283.539184)
		(mid 369.653277 -283.219906)
		(end 369.831874 -282.900628)
		(width 0.0889)
		(layer "In11.Cu")
		(net "PD_PIROM_CPU0_ADDR1")
	)
	(arc
		(start 369.183412 -287.28924)
		(mid 369.231091 -287.10634)
		(end 369.361974 -286.969962)
		(width 0.0889)
		(layer "In11.Cu")
		(net "PD_PIROM_CPU0_ADDR1")
	)
	(arc
		(start 370.123212 -280.756106)
		(mid 370.042301 -280.485978)
		(end 369.841018 -280.288492)
		(width 0.0889)
		(layer "In11.Cu")
		(net "PD_PIROM_CPU0_ADDR1")
	)
	(arc
		(start 369.183412 -275.872702)
		(mid 369.102501 -275.602574)
		(end 368.901218 -275.405088)
		(width 0.0889)
		(layer "In11.Cu")
		(net "PD_PIROM_CPU0_ADDR1")
	)
	(arc
		(start 368.901218 -276.384258)
		(mid 369.104041 -276.184027)
		(end 369.183412 -275.910294)
		(width 0.0889)
		(layer "In11.Cu")
		(net "PD_PIROM_CPU0_ADDR1")
	)
	(arc
		(start 369.840764 -282.895548)
		(mid 370.04305 -282.696567)
		(end 370.123212 -282.424378)
		(width 0.0889)
		(layer "In11.Cu")
		(net "PD_PIROM_CPU0_ADDR1")
	)
	(segment
		(start 403.008338 -364.151926)
		(end 402.560536 -364.599728)
		(width 0.12954)
		(layer "F.Cu")
		(net "PD_PIROM_CPU0_ADDR0")
	)
	(segment
		(start 405.724614 -364.151926)
		(end 405.724614 -363.008926)
		(width 0.12954)
		(layer "F.Cu")
		(net "PD_PIROM_CPU0_ADDR0")
	)
	(segment
		(start 386.916422 -362.65993)
		(end 384.092958 -362.65993)
		(width 0.12954)
		(layer "F.Cu")
		(net "PD_PIROM_CPU0_ADDR0")
	)
	(segment
		(start 405.724614 -364.151926)
		(end 403.008338 -364.151926)
		(width 0.12954)
		(layer "F.Cu")
		(net "PD_PIROM_CPU0_ADDR0")
	)
	(segment
		(start 402.560536 -364.599728)
		(end 388.85622 -364.599728)
		(width 0.12954)
		(layer "F.Cu")
		(net "PD_PIROM_CPU0_ADDR0")
	)
	(segment
		(start 367.678716 -272.103342)
		(end 367.678462 -272.639282)
		(width 0.12954)
		(layer "F.Cu")
		(net "PD_PIROM_CPU0_ADDR0")
	)
	(segment
		(start 388.85622 -364.599728)
		(end 386.916422 -362.65993)
		(width 0.12954)
		(layer "F.Cu")
		(net "PD_PIROM_CPU0_ADDR0")
	)
	(via
		(at 384.092958 -362.65993)
		(size 0.508)
		(drill 0.254)
		(layers "F.Cu" "B.Cu")
		(net "PD_PIROM_CPU0_ADDR0")
	)
	(via
		(at 367.678462 -272.639282)
		(size 0.4572)
		(drill 0.2032)
		(layers "F.Cu" "B.Cu")
		(net "PD_PIROM_CPU0_ADDR0")
	)
	(via
		(at 403.008338 -364.151926)
		(size 0.762)
		(drill 0.381)
		(layers "F.Cu" "B.Cu")
		(net "PD_PIROM_CPU0_ADDR0")
	)
	(segment
		(start 368.713766 -279.964134)
		(end 368.713766 -279.954228)
		(width 0.0889)
		(layer "In11.Cu")
		(net "PD_PIROM_CPU0_ADDR0")
	)
	(segment
		(start 367.304066 -277.531068)
		(end 367.304066 -277.513796)
		(width 0.0889)
		(layer "In11.Cu")
		(net "PD_PIROM_CPU0_ADDR0")
	)
	(segment
		(start 368.431064 -286.964882)
		(end 368.434874 -286.962596)
		(width 0.0889)
		(layer "In11.Cu")
		(net "PD_PIROM_CPU0_ADDR0")
	)
	(segment
		(start 368.434874 -286.962596)
		(end 368.43716 -286.961326)
		(width 0.0889)
		(layer "In11.Cu")
		(net "PD_PIROM_CPU0_ADDR0")
	)
	(segment
		(start 367.951512 -290.261548)
		(end 367.773712 -290.083748)
		(width 0.0889)
		(layer "In11.Cu")
		(net "PD_PIROM_CPU0_ADDR0")
	)
	(segment
		(start 368.892328 -284.52826)
		(end 368.901218 -284.52318)
		(width 0.0889)
		(layer "In11.Cu")
		(net "PD_PIROM_CPU0_ADDR0")
	)
	(segment
		(start 368.713766 -286.475424)
		(end 368.713766 -286.466788)
		(width 0.0889)
		(layer "In11.Cu")
		(net "PD_PIROM_CPU0_ADDR0")
	)
	(segment
		(start 394.156946 -353.060762)
		(end 394.156946 -316.177676)
		(width 0.127)
		(layer "In11.Cu")
		(net "PD_PIROM_CPU0_ADDR0")
	)
	(segment
		(start 368.243612 -282.405836)
		(end 368.243612 -282.390342)
		(width 0.0889)
		(layer "In11.Cu")
		(net "PD_PIROM_CPU0_ADDR0")
	)
	(segment
		(start 367.967514 -278.664416)
		(end 367.961418 -278.66086)
		(width 0.0889)
		(layer "In11.Cu")
		(net "PD_PIROM_CPU0_ADDR0")
	)
	(segment
		(start 367.961164 -287.778698)
		(end 367.96726 -287.775142)
		(width 0.0889)
		(layer "In11.Cu")
		(net "PD_PIROM_CPU0_ADDR0")
	)
	(segment
		(start 368.335814 -281.267662)
		(end 368.339878 -281.269948)
		(width 0.0889)
		(layer "In11.Cu")
		(net "PD_PIROM_CPU0_ADDR0")
	)
	(segment
		(start 366.364266 -274.27555)
		(end 366.364266 -274.258278)
		(width 0.0889)
		(layer "In11.Cu")
		(net "PD_PIROM_CPU0_ADDR0")
	)
	(segment
		(start 367.961418 -278.66086)
		(end 367.952528 -278.65578)
		(width 0.0889)
		(layer "In11.Cu")
		(net "PD_PIROM_CPU0_ADDR0")
	)
	(segment
		(start 367.021618 -275.405088)
		(end 367.012728 -275.400008)
		(width 0.0889)
		(layer "In11.Cu")
		(net "PD_PIROM_CPU0_ADDR0")
	)
	(segment
		(start 367.476532 -273.951192)
		(end 367.502186 -273.936206)
		(width 0.0889)
		(layer "In11.Cu")
		(net "PD_PIROM_CPU0_ADDR0")
	)
	(segment
		(start 367.773966 -273.459956)
		(end 367.773966 -273.453098)
		(width 0.0889)
		(layer "In11.Cu")
		(net "PD_PIROM_CPU0_ADDR0")
	)
	(segment
		(start 367.952274 -287.783778)
		(end 367.961164 -287.778698)
		(width 0.0889)
		(layer "In11.Cu")
		(net "PD_PIROM_CPU0_ADDR0")
	)
	(segment
		(start 367.491264 -277.198074)
		(end 367.503456 -277.190962)
		(width 0.0889)
		(layer "In11.Cu")
		(net "PD_PIROM_CPU0_ADDR0")
	)
	(segment
		(start 368.431318 -279.474676)
		(end 368.422428 -279.469596)
		(width 0.0889)
		(layer "In11.Cu")
		(net "PD_PIROM_CPU0_ADDR0")
	)
	(segment
		(start 367.773966 -278.336502)
		(end 367.773966 -278.322278)
		(width 0.0889)
		(layer "In11.Cu")
		(net "PD_PIROM_CPU0_ADDR0")
	)
	(segment
		(start 384.557778 -362.65993)
		(end 394.156946 -353.060762)
		(width 0.127)
		(layer "In11.Cu")
		(net "PD_PIROM_CPU0_ADDR0")
	)
	(segment
		(start 368.901218 -285.171896)
		(end 368.892328 -285.166816)
		(width 0.0889)
		(layer "In11.Cu")
		(net "PD_PIROM_CPU0_ADDR0")
	)
	(segment
		(start 376.48388 -295.10101)
		(end 372.401338 -291.018468)
		(width 0.127)
		(layer "In11.Cu")
		(net "PD_PIROM_CPU0_ADDR0")
	)
	(segment
		(start 369.183412 -285.679896)
		(end 369.183412 -285.64586)
		(width 0.0889)
		(layer "In11.Cu")
		(net "PD_PIROM_CPU0_ADDR0")
	)
	(segment
		(start 368.901218 -280.288492)
		(end 368.892328 -280.283412)
		(width 0.0889)
		(layer "In11.Cu")
		(net "PD_PIROM_CPU0_ADDR0")
	)
	(segment
		(start 366.59566 -274.617434)
		(end 366.551464 -274.591272)
		(width 0.0889)
		(layer "In11.Cu")
		(net "PD_PIROM_CPU0_ADDR0")
	)
	(segment
		(start 368.243866 -289.114484)
		(end 368.243866 -288.902902)
		(width 0.0889)
		(layer "In11.Cu")
		(net "PD_PIROM_CPU0_ADDR0")
	)
	(segment
		(start 369.183412 -284.049216)
		(end 369.183412 -284.023816)
		(width 0.0889)
		(layer "In11.Cu")
		(net "PD_PIROM_CPU0_ADDR0")
	)
	(segment
		(start 367.304066 -275.903436)
		(end 367.304066 -275.876258)
		(width 0.0889)
		(layer "In11.Cu")
		(net "PD_PIROM_CPU0_ADDR0")
	)
	(segment
		(start 368.339878 -281.269948)
		(end 368.350546 -281.276298)
		(width 0.0889)
		(layer "In11.Cu")
		(net "PD_PIROM_CPU0_ADDR0")
	)
	(segment
		(start 368.713766 -283.228542)
		(end 368.713766 -283.205682)
		(width 0.0889)
		(layer "In11.Cu")
		(net "PD_PIROM_CPU0_ADDR0")
	)
	(segment
		(start 369.0112 -290.261548)
		(end 367.951512 -290.261548)
		(width 0.0889)
		(layer "In11.Cu")
		(net "PD_PIROM_CPU0_ADDR0")
	)
	(segment
		(start 372.401338 -291.018468)
		(end 370.3828 -291.018468)
		(width 0.127)
		(layer "In11.Cu")
		(net "PD_PIROM_CPU0_ADDR0")
	)
	(segment
		(start 368.431064 -282.730194)
		(end 368.422174 -282.725114)
		(width 0.0889)
		(layer "In11.Cu")
		(net "PD_PIROM_CPU0_ADDR0")
	)
	(segment
		(start 367.952528 -281.272742)
		(end 367.961418 -281.267662)
		(width 0.0889)
		(layer "In11.Cu")
		(net "PD_PIROM_CPU0_ADDR0")
	)
	(segment
		(start 366.834166 -275.08073)
		(end 366.834166 -275.035518)
		(width 0.0889)
		(layer "In11.Cu")
		(net "PD_PIROM_CPU0_ADDR0")
	)
	(segment
		(start 376.48388 -298.50461)
		(end 376.48388 -295.10101)
		(width 0.127)
		(layer "In11.Cu")
		(net "PD_PIROM_CPU0_ADDR0")
	)
	(segment
		(start 369.183412 -280.793698)
		(end 369.183412 -280.756106)
		(width 0.0889)
		(layer "In11.Cu")
		(net "PD_PIROM_CPU0_ADDR0")
	)
	(segment
		(start 367.961164 -288.427414)
		(end 367.952274 -288.422334)
		(width 0.0889)
		(layer "In11.Cu")
		(net "PD_PIROM_CPU0_ADDR0")
	)
	(segment
		(start 367.503456 -276.22627)
		(end 367.491264 -276.219158)
		(width 0.0889)
		(layer "In11.Cu")
		(net "PD_PIROM_CPU0_ADDR0")
	)
	(segment
		(start 368.243866 -287.28924)
		(end 368.243866 -287.280604)
		(width 0.0889)
		(layer "In11.Cu")
		(net "PD_PIROM_CPU0_ADDR0")
	)
	(segment
		(start 384.092958 -362.65993)
		(end 384.557778 -362.65993)
		(width 0.127)
		(layer "In11.Cu")
		(net "PD_PIROM_CPU0_ADDR0")
	)
	(segment
		(start 367.546128 -272.999454)
		(end 367.521998 -272.9103)
		(width 0.0889)
		(layer "In11.Cu")
		(net "PD_PIROM_CPU0_ADDR0")
	)
	(segment
		(start 367.521998 -272.9103)
		(end 367.678462 -272.639282)
		(width 0.0889)
		(layer "In11.Cu")
		(net "PD_PIROM_CPU0_ADDR0")
	)
	(segment
		(start 367.961418 -281.916378)
		(end 367.952528 -281.911298)
		(width 0.0889)
		(layer "In11.Cu")
		(net "PD_PIROM_CPU0_ADDR0")
	)
	(segment
		(start 369.76812 -291.018468)
		(end 369.0112 -290.261548)
		(width 0.0889)
		(layer "In11.Cu")
		(net "PD_PIROM_CPU0_ADDR0")
	)
	(segment
		(start 370.3828 -291.018468)
		(end 369.76812 -291.018468)
		(width 0.0889)
		(layer "In11.Cu")
		(net "PD_PIROM_CPU0_ADDR0")
	)
	(segment
		(start 394.156946 -316.177676)
		(end 376.48388 -298.50461)
		(width 0.127)
		(layer "In11.Cu")
		(net "PD_PIROM_CPU0_ADDR0")
	)
	(segment
		(start 367.773712 -290.083748)
		(end 367.773712 -289.64636)
		(width 0.0889)
		(layer "In11.Cu")
		(net "PD_PIROM_CPU0_ADDR0")
	)
	(arc
		(start 367.491264 -276.219158)
		(mid 367.356331 -276.085804)
		(end 367.304066 -275.903436)
		(width 0.0889)
		(layer "In11.Cu")
		(net "PD_PIROM_CPU0_ADDR0")
	)
	(arc
		(start 368.713766 -279.954228)
		(mid 368.635655 -279.677279)
		(end 368.431318 -279.474676)
		(width 0.0889)
		(layer "In11.Cu")
		(net "PD_PIROM_CPU0_ADDR0")
	)
	(arc
		(start 368.892328 -280.283412)
		(mid 368.761414 -280.147052)
		(end 368.713766 -279.964134)
		(width 0.0889)
		(layer "In11.Cu")
		(net "PD_PIROM_CPU0_ADDR0")
	)
	(arc
		(start 367.502186 -273.936206)
		(mid 367.701224 -273.734121)
		(end 367.773966 -273.459956)
		(width 0.0889)
		(layer "In11.Cu")
		(net "PD_PIROM_CPU0_ADDR0")
	)
	(arc
		(start 368.900964 -286.151066)
		(mid 369.10325 -285.952085)
		(end 369.183412 -285.679896)
		(width 0.0889)
		(layer "In11.Cu")
		(net "PD_PIROM_CPU0_ADDR0")
	)
	(arc
		(start 366.364266 -274.258278)
		(mid 366.416536 -274.075913)
		(end 366.551464 -273.942556)
		(width 0.0889)
		(layer "In11.Cu")
		(net "PD_PIROM_CPU0_ADDR0")
	)
	(arc
		(start 367.96726 -287.775142)
		(mid 368.169847 -287.568791)
		(end 368.243866 -287.28924)
		(width 0.0889)
		(layer "In11.Cu")
		(net "PD_PIROM_CPU0_ADDR0")
	)
	(arc
		(start 368.243866 -287.280604)
		(mid 368.296136 -287.098239)
		(end 368.431064 -286.964882)
		(width 0.0889)
		(layer "In11.Cu")
		(net "PD_PIROM_CPU0_ADDR0")
	)
	(arc
		(start 366.551464 -273.942556)
		(mid 366.738662 -273.892413)
		(end 366.92586 -273.942556)
		(width 0.0889)
		(layer "In11.Cu")
		(net "PD_PIROM_CPU0_ADDR0")
	)
	(arc
		(start 368.713766 -283.205682)
		(mid 368.634547 -282.930997)
		(end 368.431064 -282.730194)
		(width 0.0889)
		(layer "In11.Cu")
		(net "PD_PIROM_CPU0_ADDR0")
	)
	(arc
		(start 369.183412 -284.023816)
		(mid 369.105301 -283.746867)
		(end 368.900964 -283.544264)
		(width 0.0889)
		(layer "In11.Cu")
		(net "PD_PIROM_CPU0_ADDR0")
	)
	(arc
		(start 367.773966 -278.322278)
		(mid 367.694747 -278.047593)
		(end 367.491264 -277.84679)
		(width 0.0889)
		(layer "In11.Cu")
		(net "PD_PIROM_CPU0_ADDR0")
	)
	(arc
		(start 368.422174 -282.725114)
		(mid 368.29126 -282.588754)
		(end 368.243612 -282.405836)
		(width 0.0889)
		(layer "In11.Cu")
		(net "PD_PIROM_CPU0_ADDR0")
	)
	(arc
		(start 369.183412 -285.64586)
		(mid 369.104042 -285.372126)
		(end 368.901218 -285.171896)
		(width 0.0889)
		(layer "In11.Cu")
		(net "PD_PIROM_CPU0_ADDR0")
	)
	(arc
		(start 367.304066 -277.513796)
		(mid 367.356336 -277.331431)
		(end 367.491264 -277.198074)
		(width 0.0889)
		(layer "In11.Cu")
		(net "PD_PIROM_CPU0_ADDR0")
	)
	(arc
		(start 368.901218 -281.267662)
		(mid 369.104041 -281.067431)
		(end 369.183412 -280.793698)
		(width 0.0889)
		(layer "In11.Cu")
		(net "PD_PIROM_CPU0_ADDR0")
	)
	(arc
		(start 366.551464 -274.591272)
		(mid 366.416531 -274.457918)
		(end 366.364266 -274.27555)
		(width 0.0889)
		(layer "In11.Cu")
		(net "PD_PIROM_CPU0_ADDR0")
	)
	(arc
		(start 368.901218 -284.52318)
		(mid 369.104041 -284.322949)
		(end 369.183412 -284.049216)
		(width 0.0889)
		(layer "In11.Cu")
		(net "PD_PIROM_CPU0_ADDR0")
	)
	(arc
		(start 367.961418 -281.267662)
		(mid 368.148616 -281.217519)
		(end 368.335814 -281.267662)
		(width 0.0889)
		(layer "In11.Cu")
		(net "PD_PIROM_CPU0_ADDR0")
	)
	(arc
		(start 367.958116 -289.446462)
		(mid 368.132417 -289.307532)
		(end 368.243866 -289.114484)
		(width 0.0889)
		(layer "In11.Cu")
		(net "PD_PIROM_CPU0_ADDR0")
	)
	(arc
		(start 368.243866 -279.150318)
		(mid 368.16995 -278.870816)
		(end 367.967514 -278.664416)
		(width 0.0889)
		(layer "In11.Cu")
		(net "PD_PIROM_CPU0_ADDR0")
	)
	(arc
		(start 368.892328 -285.166816)
		(mid 368.713731 -284.847538)
		(end 368.892328 -284.52826)
		(width 0.0889)
		(layer "In11.Cu")
		(net "PD_PIROM_CPU0_ADDR0")
	)
	(arc
		(start 367.773712 -289.64636)
		(mid 367.848783 -289.530618)
		(end 367.958116 -289.446462)
		(width 0.0889)
		(layer "In11.Cu")
		(net "PD_PIROM_CPU0_ADDR0")
	)
	(arc
		(start 368.350546 -281.276298)
		(mid 368.627021 -281.343618)
		(end 368.901218 -281.267662)
		(width 0.0889)
		(layer "In11.Cu")
		(net "PD_PIROM_CPU0_ADDR0")
	)
	(arc
		(start 368.43716 -286.961326)
		(mid 368.639747 -286.754975)
		(end 368.713766 -286.475424)
		(width 0.0889)
		(layer "In11.Cu")
		(net "PD_PIROM_CPU0_ADDR0")
	)
	(arc
		(start 367.952274 -288.422334)
		(mid 367.773677 -288.103056)
		(end 367.952274 -287.783778)
		(width 0.0889)
		(layer "In11.Cu")
		(net "PD_PIROM_CPU0_ADDR0")
	)
	(arc
		(start 367.952528 -281.911298)
		(mid 367.773931 -281.59202)
		(end 367.952528 -281.272742)
		(width 0.0889)
		(layer "In11.Cu")
		(net "PD_PIROM_CPU0_ADDR0")
	)
	(arc
		(start 368.422428 -279.469596)
		(mid 368.291514 -279.333236)
		(end 368.243866 -279.150318)
		(width 0.0889)
		(layer "In11.Cu")
		(net "PD_PIROM_CPU0_ADDR0")
	)
	(arc
		(start 368.900964 -283.544264)
		(mid 368.766031 -283.41091)
		(end 368.713766 -283.228542)
		(width 0.0889)
		(layer "In11.Cu")
		(net "PD_PIROM_CPU0_ADDR0")
	)
	(arc
		(start 367.773966 -273.453098)
		(mid 367.713869 -273.199238)
		(end 367.546128 -272.999454)
		(width 0.0889)
		(layer "In11.Cu")
		(net "PD_PIROM_CPU0_ADDR0")
	)
	(arc
		(start 369.183412 -280.756106)
		(mid 369.102501 -280.485978)
		(end 368.901218 -280.288492)
		(width 0.0889)
		(layer "In11.Cu")
		(net "PD_PIROM_CPU0_ADDR0")
	)
	(arc
		(start 367.012728 -275.400008)
		(mid 366.881814 -275.263648)
		(end 366.834166 -275.08073)
		(width 0.0889)
		(layer "In11.Cu")
		(net "PD_PIROM_CPU0_ADDR0")
	)
	(arc
		(start 366.92586 -273.942556)
		(mid 367.200059 -274.018391)
		(end 367.476532 -273.951192)
		(width 0.0889)
		(layer "In11.Cu")
		(net "PD_PIROM_CPU0_ADDR0")
	)
	(arc
		(start 368.713766 -286.466788)
		(mid 368.766036 -286.284423)
		(end 368.900964 -286.151066)
		(width 0.0889)
		(layer "In11.Cu")
		(net "PD_PIROM_CPU0_ADDR0")
	)
	(arc
		(start 367.304066 -275.876258)
		(mid 367.223904 -275.604069)
		(end 367.021618 -275.405088)
		(width 0.0889)
		(layer "In11.Cu")
		(net "PD_PIROM_CPU0_ADDR0")
	)
	(arc
		(start 367.491264 -277.84679)
		(mid 367.356331 -277.713436)
		(end 367.304066 -277.531068)
		(width 0.0889)
		(layer "In11.Cu")
		(net "PD_PIROM_CPU0_ADDR0")
	)
	(arc
		(start 368.243866 -288.902902)
		(mid 368.164647 -288.628217)
		(end 367.961164 -288.427414)
		(width 0.0889)
		(layer "In11.Cu")
		(net "PD_PIROM_CPU0_ADDR0")
	)
	(arc
		(start 368.243612 -282.390342)
		(mid 368.164242 -282.116608)
		(end 367.961418 -281.916378)
		(width 0.0889)
		(layer "In11.Cu")
		(net "PD_PIROM_CPU0_ADDR0")
	)
	(arc
		(start 367.503456 -277.190962)
		(mid 367.773912 -276.708616)
		(end 367.503456 -276.22627)
		(width 0.0889)
		(layer "In11.Cu")
		(net "PD_PIROM_CPU0_ADDR0")
	)
	(arc
		(start 367.952528 -278.65578)
		(mid 367.821614 -278.51942)
		(end 367.773966 -278.336502)
		(width 0.0889)
		(layer "In11.Cu")
		(net "PD_PIROM_CPU0_ADDR0")
	)
	(arc
		(start 366.834166 -275.035518)
		(mid 366.770343 -274.794858)
		(end 366.59566 -274.617434)
		(width 0.0889)
		(layer "In11.Cu")
		(net "PD_PIROM_CPU0_ADDR0")
	)
	(segment
		(start 340.562946 -53.619146)
		(end 340.290658 -53.149246)
		(width 0.12954)
		(layer "F.Cu")
		(net "PD_PCH_XCLK_BIASREF")
	)
	(via
		(at 340.11743 -52.72405)
		(size 0.4064)
		(drill 0.2032)
		(layers "F.Cu" "B.Cu")
		(net "PD_PCH_XCLK_BIASREF")
	)
	(via
		(at 340.290658 -53.149246)
		(size 0.4572)
		(drill 0.2032)
		(layers "F.Cu" "B.Cu")
		(net "PD_PCH_XCLK_BIASREF")
	)
	(segment
		(start 340.11743 -52.72405)
		(end 340.237572 -52.603908)
		(width 0.12954)
		(layer "B.Cu")
		(net "PD_PCH_XCLK_BIASREF")
	)
	(segment
		(start 340.404704 -52.603908)
		(end 340.47176 -52.670964)
		(width 0.12954)
		(layer "B.Cu")
		(net "PD_PCH_XCLK_BIASREF")
	)
	(segment
		(start 339.82406 -53.752496)
		(end 339.82406 -53.01742)
		(width 0.12954)
		(layer "B.Cu")
		(net "PD_PCH_XCLK_BIASREF")
	)
	(segment
		(start 340.47176 -52.968144)
		(end 340.290658 -53.149246)
		(width 0.12954)
		(layer "B.Cu")
		(net "PD_PCH_XCLK_BIASREF")
	)
	(segment
		(start 340.47176 -52.670964)
		(end 340.47176 -52.968144)
		(width 0.12954)
		(layer "B.Cu")
		(net "PD_PCH_XCLK_BIASREF")
	)
	(segment
		(start 340.237572 -52.603908)
		(end 340.404704 -52.603908)
		(width 0.12954)
		(layer "B.Cu")
		(net "PD_PCH_XCLK_BIASREF")
	)
	(segment
		(start 340.120986 -53.908706)
		(end 339.98027 -53.908706)
		(width 0.12954)
		(layer "B.Cu")
		(net "PD_PCH_XCLK_BIASREF")
	)
	(segment
		(start 339.98027 -53.908706)
		(end 339.82406 -53.752496)
		(width 0.12954)
		(layer "B.Cu")
		(net "PD_PCH_XCLK_BIASREF")
	)
	(segment
		(start 339.82406 -53.01742)
		(end 340.11743 -52.72405)
		(width 0.12954)
		(layer "B.Cu")
		(net "PD_PCH_XCLK_BIASREF")
	)
	(segment
		(start 348.393766 -39.315898)
		(end 348.393766 -35.888676)
		(width 0.12954)
		(layer "F.Cu")
		(net "PD_PCH_USB2_COMP")
	)
	(segment
		(start 346.898976 -39.756588)
		(end 347.186758 -39.507922)
		(width 0.0889)
		(layer "F.Cu")
		(net "PD_PCH_USB2_COMP")
	)
	(segment
		(start 347.7514 -39.507922)
		(end 347.814646 -39.571168)
		(width 0.0889)
		(layer "F.Cu")
		(net "PD_PCH_USB2_COMP")
	)
	(segment
		(start 348.138496 -39.571168)
		(end 348.235016 -39.474648)
		(width 0.0889)
		(layer "F.Cu")
		(net "PD_PCH_USB2_COMP")
	)
	(segment
		(start 351.01276 -26.432002)
		(end 351.01276 -30.059884)
		(width 0.12954)
		(layer "F.Cu")
		(net "PD_PCH_USB2_COMP")
	)
	(segment
		(start 346.384626 -39.946072)
		(end 346.709238 -39.946072)
		(width 0.0889)
		(layer "F.Cu")
		(net "PD_PCH_USB2_COMP")
	)
	(segment
		(start 346.89669 -39.75862)
		(end 346.898976 -39.756588)
		(width 0.0889)
		(layer "F.Cu")
		(net "PD_PCH_USB2_COMP")
	)
	(segment
		(start 347.186758 -39.507922)
		(end 347.7514 -39.507922)
		(width 0.0889)
		(layer "F.Cu")
		(net "PD_PCH_USB2_COMP")
	)
	(segment
		(start 349.1738 -31.898844)
		(end 350.1517 -30.920944)
		(width 0.12954)
		(layer "F.Cu")
		(net "PD_PCH_USB2_COMP")
	)
	(segment
		(start 347.814646 -39.571168)
		(end 348.138496 -39.571168)
		(width 0.0889)
		(layer "F.Cu")
		(net "PD_PCH_USB2_COMP")
	)
	(segment
		(start 346.709238 -39.946072)
		(end 346.89669 -39.75862)
		(width 0.0889)
		(layer "F.Cu")
		(net "PD_PCH_USB2_COMP")
	)
	(segment
		(start 348.393766 -35.888676)
		(end 349.1738 -35.108642)
		(width 0.12954)
		(layer "F.Cu")
		(net "PD_PCH_USB2_COMP")
	)
	(segment
		(start 349.1738 -35.108642)
		(end 349.1738 -31.898844)
		(width 0.12954)
		(layer "F.Cu")
		(net "PD_PCH_USB2_COMP")
	)
	(segment
		(start 351.01276 -30.059884)
		(end 350.1517 -30.920944)
		(width 0.12954)
		(layer "F.Cu")
		(net "PD_PCH_USB2_COMP")
	)
	(segment
		(start 348.235016 -39.474648)
		(end 348.393766 -39.315898)
		(width 0.12954)
		(layer "F.Cu")
		(net "PD_PCH_USB2_COMP")
	)
	(via
		(at 351.01276 -26.432002)
		(size 0.762)
		(drill 0.381)
		(layers "F.Cu" "B.Cu")
		(net "PD_PCH_USB2_COMP")
	)
	(segment
		(start 415.860992 -29.68371)
		(end 415.698178 -29.520896)
		(width 0.12954)
		(layer "F.Cu")
		(net "PD_PASSWORD_CLEAR")
	)
	(segment
		(start 425.58716 -29.362908)
		(end 425.266358 -29.68371)
		(width 0.12954)
		(layer "F.Cu")
		(net "PD_PASSWORD_CLEAR")
	)
	(segment
		(start 426.613066 -29.362908)
		(end 425.58716 -29.362908)
		(width 0.12954)
		(layer "F.Cu")
		(net "PD_PASSWORD_CLEAR")
	)
	(segment
		(start 426.630084 -29.379926)
		(end 426.613066 -29.362908)
		(width 0.12954)
		(layer "F.Cu")
		(net "PD_PASSWORD_CLEAR")
	)
	(segment
		(start 414.276794 -29.520896)
		(end 413.920432 -29.877258)
		(width 0.12954)
		(layer "F.Cu")
		(net "PD_PASSWORD_CLEAR")
	)
	(segment
		(start 415.698178 -29.520896)
		(end 415.122106 -29.520896)
		(width 0.12954)
		(layer "F.Cu")
		(net "PD_PASSWORD_CLEAR")
	)
	(segment
		(start 415.122106 -29.520896)
		(end 414.276794 -29.520896)
		(width 0.12954)
		(layer "F.Cu")
		(net "PD_PASSWORD_CLEAR")
	)
	(segment
		(start 425.266358 -29.68371)
		(end 415.860992 -29.68371)
		(width 0.12954)
		(layer "F.Cu")
		(net "PD_PASSWORD_CLEAR")
	)
	(via
		(at 415.122106 -29.520896)
		(size 0.762)
		(drill 0.381)
		(layers "F.Cu" "B.Cu")
		(net "PD_PASSWORD_CLEAR")
	)
	(segment
		(start 426.630084 -31.919926)
		(end 425.663868 -30.95371)
		(width 0.12954)
		(layer "F.Cu")
		(net "PD_ME_RCVR_N")
	)
	(segment
		(start 415.122106 -30.790896)
		(end 414.022794 -30.790896)
		(width 0.12954)
		(layer "F.Cu")
		(net "PD_ME_RCVR_N")
	)
	(segment
		(start 415.891218 -30.95371)
		(end 415.728404 -30.790896)
		(width 0.12954)
		(layer "F.Cu")
		(net "PD_ME_RCVR_N")
	)
	(segment
		(start 425.663868 -30.95371)
		(end 415.891218 -30.95371)
		(width 0.12954)
		(layer "F.Cu")
		(net "PD_ME_RCVR_N")
	)
	(segment
		(start 415.728404 -30.790896)
		(end 415.122106 -30.790896)
		(width 0.12954)
		(layer "F.Cu")
		(net "PD_ME_RCVR_N")
	)
	(segment
		(start 414.022794 -30.790896)
		(end 413.920432 -30.893258)
		(width 0.12954)
		(layer "F.Cu")
		(net "PD_ME_RCVR_N")
	)
	(via
		(at 415.122106 -30.790896)
		(size 0.762)
		(drill 0.381)
		(layers "F.Cu" "B.Cu")
		(net "PD_ME_RCVR_N")
	)
	(segment
		(start 291.955474 -95.05569)
		(end 292.21049 -94.800674)
		(width 0.12954)
		(layer "F.Cu")
		(net "PD_MB_FRU_WP")
	)
	(segment
		(start 290.957 -95.05569)
		(end 291.955474 -95.05569)
		(width 0.12954)
		(layer "F.Cu")
		(net "PD_MB_FRU_WP")
	)
	(segment
		(start 286.994854 -95.05569)
		(end 290.957 -95.05569)
		(width 0.12954)
		(layer "F.Cu")
		(net "PD_MB_FRU_WP")
	)
	(via
		(at 290.957 -95.05569)
		(size 0.762)
		(drill 0.381)
		(layers "F.Cu" "B.Cu")
		(net "PD_MB_FRU_WP")
	)
	(segment
		(start 165.25875 -47.292768)
		(end 164.92093 -46.954948)
		(width 0.12954)
		(layer "F.Cu")
		(net "PD_M2_0_DEVSLP")
	)
	(segment
		(start 166.437564 -47.049944)
		(end 166.19474 -47.292768)
		(width 0.12954)
		(layer "F.Cu")
		(net "PD_M2_0_DEVSLP")
	)
	(segment
		(start 169.557954 -47.049944)
		(end 166.437564 -47.049944)
		(width 0.12954)
		(layer "F.Cu")
		(net "PD_M2_0_DEVSLP")
	)
	(segment
		(start 166.19474 -47.292768)
		(end 165.25875 -47.292768)
		(width 0.12954)
		(layer "F.Cu")
		(net "PD_M2_0_DEVSLP")
	)
	(via
		(at 166.19474 -47.292768)
		(size 0.762)
		(drill 0.381)
		(layers "F.Cu" "B.Cu")
		(net "PD_M2_0_DEVSLP")
	)
	(segment
		(start 376.271536 -104.755442)
		(end 376.271536 -105.083102)
		(width 0.12954)
		(layer "F.Cu")
		(net "PD_JTAG_DBP_B2")
	)
	(segment
		(start 377.01855 -102.054152)
		(end 377.01855 -103.590852)
		(width 0.12954)
		(layer "F.Cu")
		(net "PD_JTAG_DBP_B2")
	)
	(segment
		(start 376.5931 -104.44226)
		(end 376.584718 -104.44226)
		(width 0.12954)
		(layer "F.Cu")
		(net "PD_JTAG_DBP_B2")
	)
	(segment
		(start 376.584718 -104.44226)
		(end 376.271536 -104.755442)
		(width 0.12954)
		(layer "F.Cu")
		(net "PD_JTAG_DBP_B2")
	)
	(segment
		(start 377.01855 -103.590852)
		(end 376.5931 -104.016302)
		(width 0.12954)
		(layer "F.Cu")
		(net "PD_JTAG_DBP_B2")
	)
	(segment
		(start 376.5931 -104.016302)
		(end 376.5931 -104.44226)
		(width 0.12954)
		(layer "F.Cu")
		(net "PD_JTAG_DBP_B2")
	)
	(via
		(at 376.5931 -104.44226)
		(size 0.508)
		(drill 0.254)
		(layers "F.Cu" "B.Cu")
		(net "PD_JTAG_DBP_B2")
	)
	(segment
		(start 379.319536 -103.140256)
		(end 378.968508 -102.789228)
		(width 0.12954)
		(layer "F.Cu")
		(net "PD_JTAG_DBP_B0")
	)
	(segment
		(start 379.319536 -105.083102)
		(end 379.319536 -104.473502)
		(width 0.12954)
		(layer "F.Cu")
		(net "PD_JTAG_DBP_B0")
	)
	(segment
		(start 378.968508 -102.789228)
		(end 378.968508 -102.054152)
		(width 0.12954)
		(layer "F.Cu")
		(net "PD_JTAG_DBP_B0")
	)
	(segment
		(start 379.319536 -104.473502)
		(end 379.319536 -103.140256)
		(width 0.12954)
		(layer "F.Cu")
		(net "PD_JTAG_DBP_B0")
	)
	(via
		(at 379.319536 -104.473502)
		(size 0.508)
		(drill 0.254)
		(layers "F.Cu" "B.Cu")
		(net "PD_JTAG_DBP_B0")
	)
	(segment
		(start 121.977912 -230.900478)
		(end 121.977912 -231.436418)
		(width 0.12954)
		(layer "F.Cu")
		(net "PD_JTAG_CPU1_PLD_TCK")
	)
	(via
		(at 121.977912 -230.900478)
		(size 0.4572)
		(drill 0.2032)
		(layers "F.Cu" "B.Cu")
		(net "PD_JTAG_CPU1_PLD_TCK")
	)
	(via
		(at 153.81097 -197.948296)
		(size 0.6604)
		(drill 0.3302)
		(layers "F.Cu" "B.Cu")
		(net "PD_JTAG_CPU1_PLD_TCK")
	)
	(segment
		(start 153.430478 -198.328788)
		(end 153.81097 -197.948296)
		(width 0.12954)
		(layer "B.Cu")
		(net "PD_JTAG_CPU1_PLD_TCK")
	)
	(segment
		(start 125.924564 -230.57612)
		(end 125.939296 -230.584756)
		(width 0.0889)
		(layer "B.Cu")
		(net "PD_JTAG_CPU1_PLD_TCK")
	)
	(segment
		(start 129.683764 -230.57612)
		(end 129.698496 -230.584756)
		(width 0.0889)
		(layer "B.Cu")
		(net "PD_JTAG_CPU1_PLD_TCK")
	)
	(segment
		(start 121.977912 -230.900478)
		(end 121.665238 -230.900478)
		(width 0.0889)
		(layer "B.Cu")
		(net "PD_JTAG_CPU1_PLD_TCK")
	)
	(segment
		(start 132.1181 -230.582216)
		(end 132.128514 -230.57612)
		(width 0.0889)
		(layer "B.Cu")
		(net "PD_JTAG_CPU1_PLD_TCK")
	)
	(segment
		(start 138.141964 -230.57612)
		(end 138.152378 -230.582216)
		(width 0.0889)
		(layer "B.Cu")
		(net "PD_JTAG_CPU1_PLD_TCK")
	)
	(segment
		(start 139.878562 -230.652066)
		(end 139.96162 -230.569008)
		(width 0.12954)
		(layer "B.Cu")
		(net "PD_JTAG_CPU1_PLD_TCK")
	)
	(segment
		(start 154.956002 -196.803264)
		(end 154.956002 -196.776848)
		(width 0.12954)
		(layer "B.Cu")
		(net "PD_JTAG_CPU1_PLD_TCK")
	)
	(segment
		(start 137.202164 -230.57612)
		(end 137.216896 -230.584756)
		(width 0.0889)
		(layer "B.Cu")
		(net "PD_JTAG_CPU1_PLD_TCK")
	)
	(segment
		(start 122.16511 -230.57612)
		(end 122.175524 -230.582216)
		(width 0.0889)
		(layer "B.Cu")
		(net "PD_JTAG_CPU1_PLD_TCK")
	)
	(segment
		(start 127.804164 -230.57612)
		(end 127.818896 -230.584756)
		(width 0.0889)
		(layer "B.Cu")
		(net "PD_JTAG_CPU1_PLD_TCK")
	)
	(segment
		(start 126.864364 -230.57612)
		(end 126.879096 -230.584756)
		(width 0.0889)
		(layer "B.Cu")
		(net "PD_JTAG_CPU1_PLD_TCK")
	)
	(segment
		(start 139.356846 -230.652066)
		(end 139.878562 -230.652066)
		(width 0.0889)
		(layer "B.Cu")
		(net "PD_JTAG_CPU1_PLD_TCK")
	)
	(segment
		(start 124.044964 -230.57612)
		(end 124.059696 -230.584756)
		(width 0.0889)
		(layer "B.Cu")
		(net "PD_JTAG_CPU1_PLD_TCK")
	)
	(segment
		(start 121.665238 -230.900478)
		(end 121.608088 -230.843328)
		(width 0.0889)
		(layer "B.Cu")
		(net "PD_JTAG_CPU1_PLD_TCK")
	)
	(segment
		(start 132.50291 -230.57612)
		(end 132.513324 -230.582216)
		(width 0.0889)
		(layer "B.Cu")
		(net "PD_JTAG_CPU1_PLD_TCK")
	)
	(segment
		(start 130.623564 -230.57612)
		(end 130.638296 -230.584756)
		(width 0.0889)
		(layer "B.Cu")
		(net "PD_JTAG_CPU1_PLD_TCK")
	)
	(segment
		(start 123.105164 -230.57612)
		(end 123.119896 -230.584756)
		(width 0.0889)
		(layer "B.Cu")
		(net "PD_JTAG_CPU1_PLD_TCK")
	)
	(segment
		(start 128.743964 -230.57612)
		(end 128.758696 -230.584756)
		(width 0.0889)
		(layer "B.Cu")
		(net "PD_JTAG_CPU1_PLD_TCK")
	)
	(segment
		(start 144.895824 -230.569008)
		(end 153.430478 -222.034354)
		(width 0.12954)
		(layer "B.Cu")
		(net "PD_JTAG_CPU1_PLD_TCK")
	)
	(segment
		(start 153.430478 -222.034354)
		(end 153.430478 -198.328788)
		(width 0.12954)
		(layer "B.Cu")
		(net "PD_JTAG_CPU1_PLD_TCK")
	)
	(segment
		(start 139.96162 -230.569008)
		(end 144.895824 -230.569008)
		(width 0.12954)
		(layer "B.Cu")
		(net "PD_JTAG_CPU1_PLD_TCK")
	)
	(segment
		(start 153.81097 -197.948296)
		(end 154.956002 -196.803264)
		(width 0.12954)
		(layer "B.Cu")
		(net "PD_JTAG_CPU1_PLD_TCK")
	)
	(arc
		(start 137.216896 -230.584756)
		(mid 137.493371 -230.652076)
		(end 137.767568 -230.57612)
		(width 0.0889)
		(layer "B.Cu")
		(net "PD_JTAG_CPU1_PLD_TCK")
	)
	(arc
		(start 136.262364 -230.57612)
		(mid 136.545066 -230.651896)
		(end 136.827768 -230.57612)
		(width 0.0889)
		(layer "B.Cu")
		(net "PD_JTAG_CPU1_PLD_TCK")
	)
	(arc
		(start 132.513324 -230.582216)
		(mid 132.791756 -230.652062)
		(end 133.068568 -230.57612)
		(width 0.0889)
		(layer "B.Cu")
		(net "PD_JTAG_CPU1_PLD_TCK")
	)
	(arc
		(start 132.128514 -230.57612)
		(mid 132.315712 -230.525977)
		(end 132.50291 -230.57612)
		(width 0.0889)
		(layer "B.Cu")
		(net "PD_JTAG_CPU1_PLD_TCK")
	)
	(arc
		(start 121.790714 -230.57612)
		(mid 121.977912 -230.525977)
		(end 122.16511 -230.57612)
		(width 0.0889)
		(layer "B.Cu")
		(net "PD_JTAG_CPU1_PLD_TCK")
	)
	(arc
		(start 129.698496 -230.584756)
		(mid 129.974971 -230.652076)
		(end 130.249168 -230.57612)
		(width 0.0889)
		(layer "B.Cu")
		(net "PD_JTAG_CPU1_PLD_TCK")
	)
	(arc
		(start 122.175524 -230.582216)
		(mid 122.453956 -230.652062)
		(end 122.730768 -230.57612)
		(width 0.0889)
		(layer "B.Cu")
		(net "PD_JTAG_CPU1_PLD_TCK")
	)
	(arc
		(start 127.818896 -230.584756)
		(mid 128.095371 -230.652076)
		(end 128.369568 -230.57612)
		(width 0.0889)
		(layer "B.Cu")
		(net "PD_JTAG_CPU1_PLD_TCK")
	)
	(arc
		(start 124.610368 -230.57612)
		(mid 124.797566 -230.525977)
		(end 124.984764 -230.57612)
		(width 0.0889)
		(layer "B.Cu")
		(net "PD_JTAG_CPU1_PLD_TCK")
	)
	(arc
		(start 134.382764 -230.57612)
		(mid 134.665466 -230.651896)
		(end 134.948168 -230.57612)
		(width 0.0889)
		(layer "B.Cu")
		(net "PD_JTAG_CPU1_PLD_TCK")
	)
	(arc
		(start 135.887968 -230.57612)
		(mid 136.075166 -230.525977)
		(end 136.262364 -230.57612)
		(width 0.0889)
		(layer "B.Cu")
		(net "PD_JTAG_CPU1_PLD_TCK")
	)
	(arc
		(start 130.249168 -230.57612)
		(mid 130.436366 -230.525977)
		(end 130.623564 -230.57612)
		(width 0.0889)
		(layer "B.Cu")
		(net "PD_JTAG_CPU1_PLD_TCK")
	)
	(arc
		(start 123.119896 -230.584756)
		(mid 123.396371 -230.652076)
		(end 123.670568 -230.57612)
		(width 0.0889)
		(layer "B.Cu")
		(net "PD_JTAG_CPU1_PLD_TCK")
	)
	(arc
		(start 126.489968 -230.57612)
		(mid 126.677166 -230.525977)
		(end 126.864364 -230.57612)
		(width 0.0889)
		(layer "B.Cu")
		(net "PD_JTAG_CPU1_PLD_TCK")
	)
	(arc
		(start 124.059696 -230.584756)
		(mid 124.336171 -230.652076)
		(end 124.610368 -230.57612)
		(width 0.0889)
		(layer "B.Cu")
		(net "PD_JTAG_CPU1_PLD_TCK")
	)
	(arc
		(start 125.550168 -230.57612)
		(mid 125.737366 -230.525977)
		(end 125.924564 -230.57612)
		(width 0.0889)
		(layer "B.Cu")
		(net "PD_JTAG_CPU1_PLD_TCK")
	)
	(arc
		(start 135.322564 -230.57612)
		(mid 135.605266 -230.651896)
		(end 135.887968 -230.57612)
		(width 0.0889)
		(layer "B.Cu")
		(net "PD_JTAG_CPU1_PLD_TCK")
	)
	(arc
		(start 121.608088 -230.843328)
		(mid 121.669031 -230.688965)
		(end 121.790714 -230.57612)
		(width 0.0889)
		(layer "B.Cu")
		(net "PD_JTAG_CPU1_PLD_TCK")
	)
	(arc
		(start 123.670568 -230.57612)
		(mid 123.857766 -230.525977)
		(end 124.044964 -230.57612)
		(width 0.0889)
		(layer "B.Cu")
		(net "PD_JTAG_CPU1_PLD_TCK")
	)
	(arc
		(start 122.730768 -230.57612)
		(mid 122.917966 -230.525977)
		(end 123.105164 -230.57612)
		(width 0.0889)
		(layer "B.Cu")
		(net "PD_JTAG_CPU1_PLD_TCK")
	)
	(arc
		(start 134.008368 -230.57612)
		(mid 134.195566 -230.525977)
		(end 134.382764 -230.57612)
		(width 0.0889)
		(layer "B.Cu")
		(net "PD_JTAG_CPU1_PLD_TCK")
	)
	(arc
		(start 131.188968 -230.57612)
		(mid 131.376166 -230.525977)
		(end 131.563364 -230.57612)
		(width 0.0889)
		(layer "B.Cu")
		(net "PD_JTAG_CPU1_PLD_TCK")
	)
	(arc
		(start 134.948168 -230.57612)
		(mid 135.135366 -230.525977)
		(end 135.322564 -230.57612)
		(width 0.0889)
		(layer "B.Cu")
		(net "PD_JTAG_CPU1_PLD_TCK")
	)
	(arc
		(start 125.939296 -230.584756)
		(mid 126.215771 -230.652076)
		(end 126.489968 -230.57612)
		(width 0.0889)
		(layer "B.Cu")
		(net "PD_JTAG_CPU1_PLD_TCK")
	)
	(arc
		(start 139.08151 -230.57612)
		(mid 139.214302 -230.631778)
		(end 139.356846 -230.652066)
		(width 0.0889)
		(layer "B.Cu")
		(net "PD_JTAG_CPU1_PLD_TCK")
	)
	(arc
		(start 136.827768 -230.57612)
		(mid 137.014966 -230.525977)
		(end 137.202164 -230.57612)
		(width 0.0889)
		(layer "B.Cu")
		(net "PD_JTAG_CPU1_PLD_TCK")
	)
	(arc
		(start 128.369568 -230.57612)
		(mid 128.556766 -230.525977)
		(end 128.743964 -230.57612)
		(width 0.0889)
		(layer "B.Cu")
		(net "PD_JTAG_CPU1_PLD_TCK")
	)
	(arc
		(start 133.442964 -230.57612)
		(mid 133.725666 -230.651896)
		(end 134.008368 -230.57612)
		(width 0.0889)
		(layer "B.Cu")
		(net "PD_JTAG_CPU1_PLD_TCK")
	)
	(arc
		(start 137.767568 -230.57612)
		(mid 137.954766 -230.525977)
		(end 138.141964 -230.57612)
		(width 0.0889)
		(layer "B.Cu")
		(net "PD_JTAG_CPU1_PLD_TCK")
	)
	(arc
		(start 129.309368 -230.57612)
		(mid 129.496566 -230.525977)
		(end 129.683764 -230.57612)
		(width 0.0889)
		(layer "B.Cu")
		(net "PD_JTAG_CPU1_PLD_TCK")
	)
	(arc
		(start 138.707114 -230.57612)
		(mid 138.894312 -230.525977)
		(end 139.08151 -230.57612)
		(width 0.0889)
		(layer "B.Cu")
		(net "PD_JTAG_CPU1_PLD_TCK")
	)
	(arc
		(start 130.638296 -230.584756)
		(mid 130.914771 -230.652076)
		(end 131.188968 -230.57612)
		(width 0.0889)
		(layer "B.Cu")
		(net "PD_JTAG_CPU1_PLD_TCK")
	)
	(arc
		(start 126.879096 -230.584756)
		(mid 127.155571 -230.652076)
		(end 127.429768 -230.57612)
		(width 0.0889)
		(layer "B.Cu")
		(net "PD_JTAG_CPU1_PLD_TCK")
	)
	(arc
		(start 124.984764 -230.57612)
		(mid 125.267466 -230.651896)
		(end 125.550168 -230.57612)
		(width 0.0889)
		(layer "B.Cu")
		(net "PD_JTAG_CPU1_PLD_TCK")
	)
	(arc
		(start 131.563364 -230.57612)
		(mid 131.839923 -230.651863)
		(end 132.1181 -230.582216)
		(width 0.0889)
		(layer "B.Cu")
		(net "PD_JTAG_CPU1_PLD_TCK")
	)
	(arc
		(start 128.758696 -230.584756)
		(mid 129.035171 -230.652076)
		(end 129.309368 -230.57612)
		(width 0.0889)
		(layer "B.Cu")
		(net "PD_JTAG_CPU1_PLD_TCK")
	)
	(arc
		(start 133.068568 -230.57612)
		(mid 133.255766 -230.525977)
		(end 133.442964 -230.57612)
		(width 0.0889)
		(layer "B.Cu")
		(net "PD_JTAG_CPU1_PLD_TCK")
	)
	(arc
		(start 127.429768 -230.57612)
		(mid 127.616966 -230.525977)
		(end 127.804164 -230.57612)
		(width 0.0889)
		(layer "B.Cu")
		(net "PD_JTAG_CPU1_PLD_TCK")
	)
	(arc
		(start 138.152378 -230.582216)
		(mid 138.430556 -230.651939)
		(end 138.707114 -230.57612)
		(width 0.0889)
		(layer "B.Cu")
		(net "PD_JTAG_CPU1_PLD_TCK")
	)
	(segment
		(start 369.91798 -231.436418)
		(end 369.91798 -230.900478)
		(width 0.12954)
		(layer "F.Cu")
		(net "PD_JTAG_CPU0_PLD_TCK")
	)
	(via
		(at 369.91798 -230.900478)
		(size 0.4572)
		(drill 0.2032)
		(layers "F.Cu" "B.Cu")
		(net "PD_JTAG_CPU0_PLD_TCK")
	)
	(via
		(at 388.976362 -194.510914)
		(size 0.6604)
		(drill 0.3302)
		(layers "F.Cu" "B.Cu")
		(net "PD_JTAG_CPU0_PLD_TCK")
	)
	(segment
		(start 387.885178 -192.524888)
		(end 387.885178 -193.41973)
		(width 0.12954)
		(layer "B.Cu")
		(net "PD_JTAG_CPU0_PLD_TCK")
	)
	(segment
		(start 370.446046 -231.151938)
		(end 369.91798 -230.900478)
		(width 0.0889)
		(layer "B.Cu")
		(net "PD_JTAG_CPU0_PLD_TCK")
	)
	(segment
		(start 387.808724 -231.30637)
		(end 386.257038 -231.30637)
		(width 0.12954)
		(layer "B.Cu")
		(net "PD_JTAG_CPU0_PLD_TCK")
	)
	(segment
		(start 370.670836 -231.224836)
		(end 370.660422 -231.21874)
		(width 0.0889)
		(layer "B.Cu")
		(net "PD_JTAG_CPU0_PLD_TCK")
	)
	(segment
		(start 386.257038 -231.30637)
		(end 385.78917 -231.30637)
		(width 0.0889)
		(layer "B.Cu")
		(net "PD_JTAG_CPU0_PLD_TCK")
	)
	(segment
		(start 393.530074 -199.064626)
		(end 393.530074 -225.58502)
		(width 0.12954)
		(layer "B.Cu")
		(net "PD_JTAG_CPU0_PLD_TCK")
	)
	(segment
		(start 378.578364 -231.2162)
		(end 378.563632 -231.224836)
		(width 0.0889)
		(layer "B.Cu")
		(net "PD_JTAG_CPU0_PLD_TCK")
	)
	(segment
		(start 393.530074 -225.58502)
		(end 387.808724 -231.30637)
		(width 0.12954)
		(layer "B.Cu")
		(net "PD_JTAG_CPU0_PLD_TCK")
	)
	(segment
		(start 377.638564 -231.2162)
		(end 377.623832 -231.224836)
		(width 0.0889)
		(layer "B.Cu")
		(net "PD_JTAG_CPU0_PLD_TCK")
	)
	(segment
		(start 388.976362 -194.510914)
		(end 393.530074 -199.064626)
		(width 0.12954)
		(layer "B.Cu")
		(net "PD_JTAG_CPU0_PLD_TCK")
	)
	(segment
		(start 379.513846 -231.21874)
		(end 379.503432 -231.224836)
		(width 0.0889)
		(layer "B.Cu")
		(net "PD_JTAG_CPU0_PLD_TCK")
	)
	(segment
		(start 375.758964 -231.2162)
		(end 375.744232 -231.224836)
		(width 0.0889)
		(layer "B.Cu")
		(net "PD_JTAG_CPU0_PLD_TCK")
	)
	(segment
		(start 387.885178 -193.41973)
		(end 388.976362 -194.510914)
		(width 0.12954)
		(layer "B.Cu")
		(net "PD_JTAG_CPU0_PLD_TCK")
	)
	(segment
		(start 380.453392 -231.21874)
		(end 380.442978 -231.224836)
		(width 0.0889)
		(layer "B.Cu")
		(net "PD_JTAG_CPU0_PLD_TCK")
	)
	(segment
		(start 385.78917 -231.30637)
		(end 385.707636 -231.224836)
		(width 0.0889)
		(layer "B.Cu")
		(net "PD_JTAG_CPU0_PLD_TCK")
	)
	(segment
		(start 372.939564 -231.2162)
		(end 372.924832 -231.224836)
		(width 0.0889)
		(layer "B.Cu")
		(net "PD_JTAG_CPU0_PLD_TCK")
	)
	(segment
		(start 373.879364 -231.2162)
		(end 373.864632 -231.224836)
		(width 0.0889)
		(layer "B.Cu")
		(net "PD_JTAG_CPU0_PLD_TCK")
	)
	(segment
		(start 371.059964 -231.2162)
		(end 371.045232 -231.224836)
		(width 0.0889)
		(layer "B.Cu")
		(net "PD_JTAG_CPU0_PLD_TCK")
	)
	(segment
		(start 371.999764 -231.2162)
		(end 371.985032 -231.224836)
		(width 0.0889)
		(layer "B.Cu")
		(net "PD_JTAG_CPU0_PLD_TCK")
	)
	(segment
		(start 374.819164 -231.2162)
		(end 374.804432 -231.224836)
		(width 0.0889)
		(layer "B.Cu")
		(net "PD_JTAG_CPU0_PLD_TCK")
	)
	(segment
		(start 386.58165 -191.22136)
		(end 387.885178 -192.524888)
		(width 0.12954)
		(layer "B.Cu")
		(net "PD_JTAG_CPU0_PLD_TCK")
	)
	(arc
		(start 376.309636 -231.224836)
		(mid 376.035407 -231.148911)
		(end 375.758964 -231.2162)
		(width 0.0889)
		(layer "B.Cu")
		(net "PD_JTAG_CPU0_PLD_TCK")
	)
	(arc
		(start 383.262632 -231.224836)
		(mid 383.075434 -231.274979)
		(end 382.888236 -231.224836)
		(width 0.0889)
		(layer "B.Cu")
		(net "PD_JTAG_CPU0_PLD_TCK")
	)
	(arc
		(start 370.660422 -231.21874)
		(mid 370.55658 -231.174604)
		(end 370.446046 -231.151938)
		(width 0.0889)
		(layer "B.Cu")
		(net "PD_JTAG_CPU0_PLD_TCK")
	)
	(arc
		(start 378.563632 -231.224836)
		(mid 378.376434 -231.274979)
		(end 378.189236 -231.224836)
		(width 0.0889)
		(layer "B.Cu")
		(net "PD_JTAG_CPU0_PLD_TCK")
	)
	(arc
		(start 371.045232 -231.224836)
		(mid 370.858034 -231.274979)
		(end 370.670836 -231.224836)
		(width 0.0889)
		(layer "B.Cu")
		(net "PD_JTAG_CPU0_PLD_TCK")
	)
	(arc
		(start 376.684032 -231.224836)
		(mid 376.496834 -231.274979)
		(end 376.309636 -231.224836)
		(width 0.0889)
		(layer "B.Cu")
		(net "PD_JTAG_CPU0_PLD_TCK")
	)
	(arc
		(start 381.948436 -231.224836)
		(mid 381.665734 -231.149094)
		(end 381.383032 -231.224836)
		(width 0.0889)
		(layer "B.Cu")
		(net "PD_JTAG_CPU0_PLD_TCK")
	)
	(arc
		(start 372.550436 -231.224836)
		(mid 372.276207 -231.148911)
		(end 371.999764 -231.2162)
		(width 0.0889)
		(layer "B.Cu")
		(net "PD_JTAG_CPU0_PLD_TCK")
	)
	(arc
		(start 374.430036 -231.224836)
		(mid 374.155807 -231.148911)
		(end 373.879364 -231.2162)
		(width 0.0889)
		(layer "B.Cu")
		(net "PD_JTAG_CPU0_PLD_TCK")
	)
	(arc
		(start 381.383032 -231.224836)
		(mid 381.195834 -231.274979)
		(end 381.008636 -231.224836)
		(width 0.0889)
		(layer "B.Cu")
		(net "PD_JTAG_CPU0_PLD_TCK")
	)
	(arc
		(start 383.828036 -231.224836)
		(mid 383.545334 -231.149094)
		(end 383.262632 -231.224836)
		(width 0.0889)
		(layer "B.Cu")
		(net "PD_JTAG_CPU0_PLD_TCK")
	)
	(arc
		(start 385.142232 -231.224836)
		(mid 384.955034 -231.274979)
		(end 384.767836 -231.224836)
		(width 0.0889)
		(layer "B.Cu")
		(net "PD_JTAG_CPU0_PLD_TCK")
	)
	(arc
		(start 382.322832 -231.224836)
		(mid 382.135634 -231.274979)
		(end 381.948436 -231.224836)
		(width 0.0889)
		(layer "B.Cu")
		(net "PD_JTAG_CPU0_PLD_TCK")
	)
	(arc
		(start 382.888236 -231.224836)
		(mid 382.605534 -231.149094)
		(end 382.322832 -231.224836)
		(width 0.0889)
		(layer "B.Cu")
		(net "PD_JTAG_CPU0_PLD_TCK")
	)
	(arc
		(start 375.744232 -231.224836)
		(mid 375.557034 -231.274979)
		(end 375.369836 -231.224836)
		(width 0.0889)
		(layer "B.Cu")
		(net "PD_JTAG_CPU0_PLD_TCK")
	)
	(arc
		(start 378.189236 -231.224836)
		(mid 377.915007 -231.148911)
		(end 377.638564 -231.2162)
		(width 0.0889)
		(layer "B.Cu")
		(net "PD_JTAG_CPU0_PLD_TCK")
	)
	(arc
		(start 384.202432 -231.224836)
		(mid 384.015234 -231.274979)
		(end 383.828036 -231.224836)
		(width 0.0889)
		(layer "B.Cu")
		(net "PD_JTAG_CPU0_PLD_TCK")
	)
	(arc
		(start 377.623832 -231.224836)
		(mid 377.436634 -231.274979)
		(end 377.249436 -231.224836)
		(width 0.0889)
		(layer "B.Cu")
		(net "PD_JTAG_CPU0_PLD_TCK")
	)
	(arc
		(start 385.707636 -231.224836)
		(mid 385.424934 -231.149094)
		(end 385.142232 -231.224836)
		(width 0.0889)
		(layer "B.Cu")
		(net "PD_JTAG_CPU0_PLD_TCK")
	)
	(arc
		(start 371.985032 -231.224836)
		(mid 371.797834 -231.274979)
		(end 371.610636 -231.224836)
		(width 0.0889)
		(layer "B.Cu")
		(net "PD_JTAG_CPU0_PLD_TCK")
	)
	(arc
		(start 371.610636 -231.224836)
		(mid 371.336407 -231.148911)
		(end 371.059964 -231.2162)
		(width 0.0889)
		(layer "B.Cu")
		(net "PD_JTAG_CPU0_PLD_TCK")
	)
	(arc
		(start 384.767836 -231.224836)
		(mid 384.485134 -231.149094)
		(end 384.202432 -231.224836)
		(width 0.0889)
		(layer "B.Cu")
		(net "PD_JTAG_CPU0_PLD_TCK")
	)
	(arc
		(start 375.369836 -231.224836)
		(mid 375.095607 -231.148911)
		(end 374.819164 -231.2162)
		(width 0.0889)
		(layer "B.Cu")
		(net "PD_JTAG_CPU0_PLD_TCK")
	)
	(arc
		(start 379.503432 -231.224836)
		(mid 379.316234 -231.274979)
		(end 379.129036 -231.224836)
		(width 0.0889)
		(layer "B.Cu")
		(net "PD_JTAG_CPU0_PLD_TCK")
	)
	(arc
		(start 372.924832 -231.224836)
		(mid 372.737634 -231.274979)
		(end 372.550436 -231.224836)
		(width 0.0889)
		(layer "B.Cu")
		(net "PD_JTAG_CPU0_PLD_TCK")
	)
	(arc
		(start 373.864632 -231.224836)
		(mid 373.677434 -231.274979)
		(end 373.490236 -231.224836)
		(width 0.0889)
		(layer "B.Cu")
		(net "PD_JTAG_CPU0_PLD_TCK")
	)
	(arc
		(start 379.129036 -231.224836)
		(mid 378.854807 -231.148911)
		(end 378.578364 -231.2162)
		(width 0.0889)
		(layer "B.Cu")
		(net "PD_JTAG_CPU0_PLD_TCK")
	)
	(arc
		(start 373.490236 -231.224836)
		(mid 373.216007 -231.148911)
		(end 372.939564 -231.2162)
		(width 0.0889)
		(layer "B.Cu")
		(net "PD_JTAG_CPU0_PLD_TCK")
	)
	(arc
		(start 377.249436 -231.224836)
		(mid 376.966734 -231.149094)
		(end 376.684032 -231.224836)
		(width 0.0889)
		(layer "B.Cu")
		(net "PD_JTAG_CPU0_PLD_TCK")
	)
	(arc
		(start 380.068582 -231.224836)
		(mid 379.792023 -231.149127)
		(end 379.513846 -231.21874)
		(width 0.0889)
		(layer "B.Cu")
		(net "PD_JTAG_CPU0_PLD_TCK")
	)
	(arc
		(start 374.804432 -231.224836)
		(mid 374.617234 -231.274979)
		(end 374.430036 -231.224836)
		(width 0.0889)
		(layer "B.Cu")
		(net "PD_JTAG_CPU0_PLD_TCK")
	)
	(arc
		(start 381.008636 -231.224836)
		(mid 380.731823 -231.149)
		(end 380.453392 -231.21874)
		(width 0.0889)
		(layer "B.Cu")
		(net "PD_JTAG_CPU0_PLD_TCK")
	)
	(arc
		(start 380.442978 -231.224836)
		(mid 380.25578 -231.274979)
		(end 380.068582 -231.224836)
		(width 0.0889)
		(layer "B.Cu")
		(net "PD_JTAG_CPU0_PLD_TCK")
	)
	(segment
		(start 99.194366 -57.226962)
		(end 99.92741 -57.226962)
		(width 0.12954)
		(layer "F.Cu")
		(net "PD_JTAG_BMC_NTRST_N")
	)
	(segment
		(start 98.21926 -58.202068)
		(end 99.194366 -57.226962)
		(width 0.12954)
		(layer "F.Cu")
		(net "PD_JTAG_BMC_NTRST_N")
	)
	(segment
		(start 103.194866 -57.226962)
		(end 99.92741 -57.226962)
		(width 0.12954)
		(layer "F.Cu")
		(net "PD_JTAG_BMC_NTRST_N")
	)
	(segment
		(start 105.76941 -56.576976)
		(end 103.844852 -56.576976)
		(width 0.12954)
		(layer "F.Cu")
		(net "PD_JTAG_BMC_NTRST_N")
	)
	(segment
		(start 97.25914 -57.241948)
		(end 98.21926 -58.202068)
		(width 0.12954)
		(layer "F.Cu")
		(net "PD_JTAG_BMC_NTRST_N")
	)
	(segment
		(start 96.97593 -57.241948)
		(end 97.25914 -57.241948)
		(width 0.12954)
		(layer "F.Cu")
		(net "PD_JTAG_BMC_NTRST_N")
	)
	(segment
		(start 103.844852 -56.576976)
		(end 103.194866 -57.226962)
		(width 0.12954)
		(layer "F.Cu")
		(net "PD_JTAG_BMC_NTRST_N")
	)
	(via
		(at 98.21926 -58.202068)
		(size 0.762)
		(drill 0.381)
		(layers "F.Cu" "B.Cu")
		(net "PD_JTAG_BMC_NTRST_N")
	)
	(segment
		(start 83.843622 -149.265132)
		(end 84.07908 -149.50059)
		(width 0.12954)
		(layer "F.Cu")
		(net "PD_I3C_SPD_DDR_CPU1_OE_N")
	)
	(segment
		(start 84.07908 -149.50059)
		(end 84.07908 -150.967948)
		(width 0.12954)
		(layer "F.Cu")
		(net "PD_I3C_SPD_DDR_CPU1_OE_N")
	)
	(segment
		(start 82.384138 -149.265132)
		(end 83.843622 -149.265132)
		(width 0.12954)
		(layer "F.Cu")
		(net "PD_I3C_SPD_DDR_CPU1_OE_N")
	)
	(segment
		(start 83.338924 -151.708104)
		(end 83.338924 -152.221692)
		(width 0.12954)
		(layer "F.Cu")
		(net "PD_I3C_SPD_DDR_CPU1_OE_N")
	)
	(segment
		(start 84.07908 -150.967948)
		(end 83.338924 -151.708104)
		(width 0.12954)
		(layer "F.Cu")
		(net "PD_I3C_SPD_DDR_CPU1_OE_N")
	)
	(via
		(at 84.07908 -150.967948)
		(size 0.762)
		(drill 0.381)
		(layers "F.Cu" "B.Cu")
		(net "PD_I3C_SPD_DDR_CPU1_OE_N")
	)
	(via
		(at 305.302158 -150.686008)
		(size 0.6604)
		(drill 0.3302)
		(layers "F.Cu" "B.Cu")
		(net "PD_I3C_SPD_DDR_CPU0_OE_N")
	)
	(segment
		(start 305.989482 -149.998684)
		(end 305.989482 -149.533356)
		(width 0.12954)
		(layer "B.Cu")
		(net "PD_I3C_SPD_DDR_CPU0_OE_N")
	)
	(segment
		(start 305.302158 -150.686008)
		(end 305.989482 -149.998684)
		(width 0.12954)
		(layer "B.Cu")
		(net "PD_I3C_SPD_DDR_CPU0_OE_N")
	)
	(segment
		(start 305.067208 -150.451058)
		(end 305.302158 -150.686008)
		(width 0.12954)
		(layer "B.Cu")
		(net "PD_I3C_SPD_DDR_CPU0_OE_N")
	)
	(segment
		(start 301.258732 -150.451058)
		(end 305.067208 -150.451058)
		(width 0.12954)
		(layer "B.Cu")
		(net "PD_I3C_SPD_DDR_CPU0_OE_N")
	)
	(segment
		(start 371.672358 -95.19539)
		(end 371.672358 -96.264984)
		(width 0.12954)
		(layer "F.Cu")
		(net "PD_GTL2014_BMC_JTAG_VREF_1")
	)
	(segment
		(start 371.545358 -93.363034)
		(end 371.7544 -93.572076)
		(width 0.12954)
		(layer "F.Cu")
		(net "PD_GTL2014_BMC_JTAG_VREF_1")
	)
	(segment
		(start 371.7544 -95.113348)
		(end 371.672358 -95.19539)
		(width 0.12954)
		(layer "F.Cu")
		(net "PD_GTL2014_BMC_JTAG_VREF_1")
	)
	(segment
		(start 371.7544 -93.572076)
		(end 371.7544 -95.113348)
		(width 0.12954)
		(layer "F.Cu")
		(net "PD_GTL2014_BMC_JTAG_VREF_1")
	)
	(via
		(at 371.7544 -95.113348)
		(size 0.508)
		(drill 0.254)
		(layers "F.Cu" "B.Cu")
		(net "PD_GTL2014_BMC_JTAG_VREF_1")
	)
	(segment
		(start 112.579912 -233.064304)
		(end 112.579912 -232.528618)
		(width 0.12954)
		(layer "F.Cu")
		(net "PD_EXT_CLK_SEL_CPU1")
	)
	(segment
		(start 112.579912 -232.528618)
		(end 112.580166 -232.528364)
		(width 0.12954)
		(layer "F.Cu")
		(net "PD_EXT_CLK_SEL_CPU1")
	)
	(via
		(at 93.68282 -201.289666)
		(size 0.6604)
		(drill 0.3302)
		(layers "F.Cu" "B.Cu")
		(net "PD_EXT_CLK_SEL_CPU1")
	)
	(via
		(at 112.580166 -232.528364)
		(size 0.4572)
		(drill 0.2032)
		(layers "F.Cu" "B.Cu")
		(net "PD_EXT_CLK_SEL_CPU1")
	)
	(segment
		(start 109.4867 -224.88398)
		(end 109.47781 -224.8789)
		(width 0.0889)
		(layer "B.Cu")
		(net "PD_EXT_CLK_SEL_CPU1")
	)
	(segment
		(start 95.865696 -219.190316)
		(end 95.850964 -219.18168)
		(width 0.0889)
		(layer "B.Cu")
		(net "PD_EXT_CLK_SEL_CPU1")
	)
	(segment
		(start 92.106496 -219.190316)
		(end 92.091764 -219.18168)
		(width 0.0889)
		(layer "B.Cu")
		(net "PD_EXT_CLK_SEL_CPU1")
	)
	(segment
		(start 93.986096 -219.190316)
		(end 93.971364 -219.18168)
		(width 0.0889)
		(layer "B.Cu")
		(net "PD_EXT_CLK_SEL_CPU1")
	)
	(segment
		(start 98.678238 -219.186252)
		(end 98.670364 -219.18168)
		(width 0.0889)
		(layer "B.Cu")
		(net "PD_EXT_CLK_SEL_CPU1")
	)
	(segment
		(start 107.137454 -220.814646)
		(end 107.128564 -220.809566)
		(width 0.0889)
		(layer "B.Cu")
		(net "PD_EXT_CLK_SEL_CPU1")
	)
	(segment
		(start 109.195616 -224.404936)
		(end 109.195616 -224.373948)
		(width 0.0889)
		(layer "B.Cu")
		(net "PD_EXT_CLK_SEL_CPU1")
	)
	(segment
		(start 109.665262 -225.217482)
		(end 109.665262 -225.203258)
		(width 0.0889)
		(layer "B.Cu")
		(net "PD_EXT_CLK_SEL_CPU1")
	)
	(segment
		(start 112.776254 -230.5812)
		(end 112.767364 -230.57612)
		(width 0.0889)
		(layer "B.Cu")
		(net "PD_EXT_CLK_SEL_CPU1")
	)
	(segment
		(start 94.925896 -219.190316)
		(end 94.911164 -219.18168)
		(width 0.0889)
		(layer "B.Cu")
		(net "PD_EXT_CLK_SEL_CPU1")
	)
	(segment
		(start 104.496616 -219.515944)
		(end 104.496616 -219.506038)
		(width 0.0889)
		(layer "B.Cu")
		(net "PD_EXT_CLK_SEL_CPU1")
	)
	(segment
		(start 112.767364 -231.224836)
		(end 112.776254 -231.219756)
		(width 0.0889)
		(layer "B.Cu")
		(net "PD_EXT_CLK_SEL_CPU1")
	)
	(segment
		(start 112.533684 -232.146602)
		(end 112.48517 -231.748076)
		(width 0.0889)
		(layer "B.Cu")
		(net "PD_EXT_CLK_SEL_CPU1")
	)
	(segment
		(start 111.8362 -228.953568)
		(end 111.82731 -228.948488)
		(width 0.0889)
		(layer "B.Cu")
		(net "PD_EXT_CLK_SEL_CPU1")
	)
	(segment
		(start 91.166696 -219.190316)
		(end 91.151964 -219.18168)
		(width 0.0889)
		(layer "B.Cu")
		(net "PD_EXT_CLK_SEL_CPU1")
	)
	(segment
		(start 99.624896 -219.190316)
		(end 99.610164 -219.18168)
		(width 0.0889)
		(layer "B.Cu")
		(net "PD_EXT_CLK_SEL_CPU1")
	)
	(segment
		(start 111.544862 -228.468936)
		(end 111.544862 -228.450394)
		(width 0.0889)
		(layer "B.Cu")
		(net "PD_EXT_CLK_SEL_CPU1")
	)
	(segment
		(start 88.341454 -217.559128)
		(end 88.332564 -217.554048)
		(width 0.0889)
		(layer "B.Cu")
		(net "PD_EXT_CLK_SEL_CPU1")
	)
	(segment
		(start 90.226896 -219.190316)
		(end 90.212164 -219.18168)
		(width 0.0889)
		(layer "B.Cu")
		(net "PD_EXT_CLK_SEL_CPU1")
	)
	(segment
		(start 96.805496 -219.190316)
		(end 96.790764 -219.18168)
		(width 0.0889)
		(layer "B.Cu")
		(net "PD_EXT_CLK_SEL_CPU1")
	)
	(segment
		(start 103.384096 -219.190316)
		(end 103.369364 -219.18168)
		(width 0.0889)
		(layer "B.Cu")
		(net "PD_EXT_CLK_SEL_CPU1")
	)
	(segment
		(start 112.48517 -230.102156)
		(end 112.48517 -230.086662)
		(width 0.0889)
		(layer "B.Cu")
		(net "PD_EXT_CLK_SEL_CPU1")
	)
	(segment
		(start 112.580166 -232.528364)
		(end 112.559084 -232.355136)
		(width 0.0889)
		(layer "B.Cu")
		(net "PD_EXT_CLK_SEL_CPU1")
	)
	(segment
		(start 101.504496 -219.190316)
		(end 101.489764 -219.18168)
		(width 0.0889)
		(layer "B.Cu")
		(net "PD_EXT_CLK_SEL_CPU1")
	)
	(segment
		(start 109.956854 -225.69805)
		(end 109.947964 -225.69297)
		(width 0.0889)
		(layer "B.Cu")
		(net "PD_EXT_CLK_SEL_CPU1")
	)
	(segment
		(start 93.68282 -201.289666)
		(end 93.68282 -195.804028)
		(width 0.12954)
		(layer "B.Cu")
		(net "PD_EXT_CLK_SEL_CPU1")
	)
	(segment
		(start 90.547952 -211.12353)
		(end 91.416886 -211.12353)
		(width 0.12954)
		(layer "B.Cu")
		(net "PD_EXT_CLK_SEL_CPU1")
	)
	(segment
		(start 108.068364 -222.437198)
		(end 108.062268 -222.433642)
		(width 0.0889)
		(layer "B.Cu")
		(net "PD_EXT_CLK_SEL_CPU1")
	)
	(segment
		(start 107.6071 -221.628462)
		(end 107.59821 -221.623382)
		(width 0.0889)
		(layer "B.Cu")
		(net "PD_EXT_CLK_SEL_CPU1")
	)
	(segment
		(start 109.47781 -223.899984)
		(end 109.4867 -223.894904)
		(width 0.0889)
		(layer "B.Cu")
		(net "PD_EXT_CLK_SEL_CPU1")
	)
	(segment
		(start 110.605062 -226.831144)
		(end 110.605062 -226.822508)
		(width 0.0889)
		(layer "B.Cu")
		(net "PD_EXT_CLK_SEL_CPU1")
	)
	(segment
		(start 88.989662 -218.692222)
		(end 88.989662 -218.683586)
		(width 0.0889)
		(layer "B.Cu")
		(net "PD_EXT_CLK_SEL_CPU1")
	)
	(segment
		(start 102.444296 -219.190316)
		(end 102.429564 -219.18168)
		(width 0.0889)
		(layer "B.Cu")
		(net "PD_EXT_CLK_SEL_CPU1")
	)
	(segment
		(start 94.153482 -208.386934)
		(end 94.153482 -201.760328)
		(width 0.12954)
		(layer "B.Cu")
		(net "PD_EXT_CLK_SEL_CPU1")
	)
	(segment
		(start 112.559084 -232.355136)
		(end 112.533684 -232.146602)
		(width 0.0889)
		(layer "B.Cu")
		(net "PD_EXT_CLK_SEL_CPU1")
	)
	(segment
		(start 112.48517 -231.748076)
		(end 112.48517 -231.69245)
		(width 0.0889)
		(layer "B.Cu")
		(net "PD_EXT_CLK_SEL_CPU1")
	)
	(segment
		(start 110.887764 -227.320602)
		(end 110.881668 -227.317046)
		(width 0.0889)
		(layer "B.Cu")
		(net "PD_EXT_CLK_SEL_CPU1")
	)
	(segment
		(start 111.075216 -227.663502)
		(end 111.075216 -227.64496)
		(width 0.0889)
		(layer "B.Cu")
		(net "PD_EXT_CLK_SEL_CPU1")
	)
	(segment
		(start 91.416886 -211.12353)
		(end 94.153482 -208.386934)
		(width 0.12954)
		(layer "B.Cu")
		(net "PD_EXT_CLK_SEL_CPU1")
	)
	(segment
		(start 110.135416 -226.027234)
		(end 110.135416 -226.017328)
		(width 0.0889)
		(layer "B.Cu")
		(net "PD_EXT_CLK_SEL_CPU1")
	)
	(segment
		(start 87.110062 -215.452198)
		(end 87.021162 -215.363298)
		(width 0.0889)
		(layer "B.Cu")
		(net "PD_EXT_CLK_SEL_CPU1")
	)
	(segment
		(start 87.86241 -216.739978)
		(end 87.856314 -216.736422)
		(width 0.0889)
		(layer "B.Cu")
		(net "PD_EXT_CLK_SEL_CPU1")
	)
	(segment
		(start 107.316016 -221.149418)
		(end 107.316016 -221.133924)
		(width 0.0889)
		(layer "B.Cu")
		(net "PD_EXT_CLK_SEL_CPU1")
	)
	(segment
		(start 87.021162 -214.65032)
		(end 90.547952 -211.12353)
		(width 0.12954)
		(layer "B.Cu")
		(net "PD_EXT_CLK_SEL_CPU1")
	)
	(segment
		(start 89.272364 -219.18168)
		(end 89.266268 -219.178124)
		(width 0.0889)
		(layer "B.Cu")
		(net "PD_EXT_CLK_SEL_CPU1")
	)
	(segment
		(start 109.195616 -222.783654)
		(end 109.195616 -222.761556)
		(width 0.0889)
		(layer "B.Cu")
		(net "PD_EXT_CLK_SEL_CPU1")
	)
	(segment
		(start 112.48517 -230.086662)
		(end 112.484916 -230.086662)
		(width 0.0889)
		(layer "B.Cu")
		(net "PD_EXT_CLK_SEL_CPU1")
	)
	(segment
		(start 110.896654 -227.325682)
		(end 110.887764 -227.320602)
		(width 0.0889)
		(layer "B.Cu")
		(net "PD_EXT_CLK_SEL_CPU1")
	)
	(segment
		(start 112.297464 -229.762304)
		(end 112.285272 -229.755192)
		(width 0.0889)
		(layer "B.Cu")
		(net "PD_EXT_CLK_SEL_CPU1")
	)
	(segment
		(start 87.8713 -216.745058)
		(end 87.86241 -216.739978)
		(width 0.0889)
		(layer "B.Cu")
		(net "PD_EXT_CLK_SEL_CPU1")
	)
	(segment
		(start 109.4867 -223.256348)
		(end 109.47781 -223.251268)
		(width 0.0889)
		(layer "B.Cu")
		(net "PD_EXT_CLK_SEL_CPU1")
	)
	(segment
		(start 112.306354 -229.767384)
		(end 112.297464 -229.762304)
		(width 0.0889)
		(layer "B.Cu")
		(net "PD_EXT_CLK_SEL_CPU1")
	)
	(segment
		(start 87.021162 -215.363298)
		(end 87.021162 -214.65032)
		(width 0.12954)
		(layer "B.Cu")
		(net "PD_EXT_CLK_SEL_CPU1")
	)
	(segment
		(start 88.049862 -217.07856)
		(end 88.049862 -217.064336)
		(width 0.0889)
		(layer "B.Cu")
		(net "PD_EXT_CLK_SEL_CPU1")
	)
	(segment
		(start 109.017054 -222.442278)
		(end 109.008164 -222.437198)
		(width 0.0889)
		(layer "B.Cu")
		(net "PD_EXT_CLK_SEL_CPU1")
	)
	(segment
		(start 87.401146 -215.931242)
		(end 87.392256 -215.926162)
		(width 0.0889)
		(layer "B.Cu")
		(net "PD_EXT_CLK_SEL_CPU1")
	)
	(segment
		(start 94.153482 -201.760328)
		(end 93.68282 -201.289666)
		(width 0.12954)
		(layer "B.Cu")
		(net "PD_EXT_CLK_SEL_CPU1")
	)
	(segment
		(start 89.287096 -219.190316)
		(end 89.272364 -219.18168)
		(width 0.0889)
		(layer "B.Cu")
		(net "PD_EXT_CLK_SEL_CPU1")
	)
	(segment
		(start 88.520016 -217.888312)
		(end 88.520016 -217.878406)
		(width 0.0889)
		(layer "B.Cu")
		(net "PD_EXT_CLK_SEL_CPU1")
	)
	(segment
		(start 93.68282 -195.804028)
		(end 96.241108 -193.24574)
		(width 0.12954)
		(layer "B.Cu")
		(net "PD_EXT_CLK_SEL_CPU1")
	)
	(segment
		(start 100.564696 -219.190316)
		(end 100.549964 -219.18168)
		(width 0.0889)
		(layer "B.Cu")
		(net "PD_EXT_CLK_SEL_CPU1")
	)
	(segment
		(start 98.685096 -219.190316)
		(end 98.678238 -219.186252)
		(width 0.0889)
		(layer "B.Cu")
		(net "PD_EXT_CLK_SEL_CPU1")
	)
	(segment
		(start 97.745296 -219.190316)
		(end 97.730564 -219.18168)
		(width 0.0889)
		(layer "B.Cu")
		(net "PD_EXT_CLK_SEL_CPU1")
	)
	(segment
		(start 106.284268 -219.995496)
		(end 106.273854 -220.001592)
		(width 0.0889)
		(layer "B.Cu")
		(net "PD_EXT_CLK_SEL_CPU1")
	)
	(segment
		(start 93.046296 -219.190316)
		(end 93.031564 -219.18168)
		(width 0.0889)
		(layer "B.Cu")
		(net "PD_EXT_CLK_SEL_CPU1")
	)
	(segment
		(start 96.241108 -193.24574)
		(end 96.241108 -191.105282)
		(width 0.12954)
		(layer "B.Cu")
		(net "PD_EXT_CLK_SEL_CPU1")
	)
	(segment
		(start 105.344214 -219.995496)
		(end 105.3338 -220.001592)
		(width 0.0889)
		(layer "B.Cu")
		(net "PD_EXT_CLK_SEL_CPU1")
	)
	(segment
		(start 108.083096 -222.445834)
		(end 108.068364 -222.437198)
		(width 0.0889)
		(layer "B.Cu")
		(net "PD_EXT_CLK_SEL_CPU1")
	)
	(segment
		(start 104.318054 -219.18676)
		(end 104.309164 -219.18168)
		(width 0.0889)
		(layer "B.Cu")
		(net "PD_EXT_CLK_SEL_CPU1")
	)
	(segment
		(start 106.845862 -220.334078)
		(end 106.845862 -220.311218)
		(width 0.0889)
		(layer "B.Cu")
		(net "PD_EXT_CLK_SEL_CPU1")
	)
	(arc
		(start 104.309164 -219.18168)
		(mid 104.121966 -219.131537)
		(end 103.934768 -219.18168)
		(width 0.0889)
		(layer "B.Cu")
		(net "PD_EXT_CLK_SEL_CPU1")
	)
	(arc
		(start 91.717368 -219.18168)
		(mid 91.443169 -219.257515)
		(end 91.166696 -219.190316)
		(width 0.0889)
		(layer "B.Cu")
		(net "PD_EXT_CLK_SEL_CPU1")
	)
	(arc
		(start 93.596968 -219.18168)
		(mid 93.322769 -219.257515)
		(end 93.046296 -219.190316)
		(width 0.0889)
		(layer "B.Cu")
		(net "PD_EXT_CLK_SEL_CPU1")
	)
	(arc
		(start 109.665262 -225.203258)
		(mid 109.617583 -225.020358)
		(end 109.4867 -224.88398)
		(width 0.0889)
		(layer "B.Cu")
		(net "PD_EXT_CLK_SEL_CPU1")
	)
	(arc
		(start 87.856314 -216.736422)
		(mid 87.653727 -216.530071)
		(end 87.579708 -216.25052)
		(width 0.0889)
		(layer "B.Cu")
		(net "PD_EXT_CLK_SEL_CPU1")
	)
	(arc
		(start 94.536768 -219.18168)
		(mid 94.262569 -219.257515)
		(end 93.986096 -219.190316)
		(width 0.0889)
		(layer "B.Cu")
		(net "PD_EXT_CLK_SEL_CPU1")
	)
	(arc
		(start 104.779064 -219.995496)
		(mid 104.574729 -219.792891)
		(end 104.496616 -219.515944)
		(width 0.0889)
		(layer "B.Cu")
		(net "PD_EXT_CLK_SEL_CPU1")
	)
	(arc
		(start 104.496616 -219.506038)
		(mid 104.448937 -219.323138)
		(end 104.318054 -219.18676)
		(width 0.0889)
		(layer "B.Cu")
		(net "PD_EXT_CLK_SEL_CPU1")
	)
	(arc
		(start 92.657168 -219.18168)
		(mid 92.382969 -219.257515)
		(end 92.106496 -219.190316)
		(width 0.0889)
		(layer "B.Cu")
		(net "PD_EXT_CLK_SEL_CPU1")
	)
	(arc
		(start 96.416368 -219.18168)
		(mid 96.142169 -219.257515)
		(end 95.865696 -219.190316)
		(width 0.0889)
		(layer "B.Cu")
		(net "PD_EXT_CLK_SEL_CPU1")
	)
	(arc
		(start 101.489764 -219.18168)
		(mid 101.302566 -219.131537)
		(end 101.115368 -219.18168)
		(width 0.0889)
		(layer "B.Cu")
		(net "PD_EXT_CLK_SEL_CPU1")
	)
	(arc
		(start 103.934768 -219.18168)
		(mid 103.660569 -219.257515)
		(end 103.384096 -219.190316)
		(width 0.0889)
		(layer "B.Cu")
		(net "PD_EXT_CLK_SEL_CPU1")
	)
	(arc
		(start 108.062268 -222.433642)
		(mid 107.859681 -222.227291)
		(end 107.785662 -221.94774)
		(width 0.0889)
		(layer "B.Cu")
		(net "PD_EXT_CLK_SEL_CPU1")
	)
	(arc
		(start 110.135416 -226.017328)
		(mid 110.087737 -225.834428)
		(end 109.956854 -225.69805)
		(width 0.0889)
		(layer "B.Cu")
		(net "PD_EXT_CLK_SEL_CPU1")
	)
	(arc
		(start 109.195616 -224.373948)
		(mid 109.274986 -224.100214)
		(end 109.47781 -223.899984)
		(width 0.0889)
		(layer "B.Cu")
		(net "PD_EXT_CLK_SEL_CPU1")
	)
	(arc
		(start 91.151964 -219.18168)
		(mid 90.964766 -219.131537)
		(end 90.777568 -219.18168)
		(width 0.0889)
		(layer "B.Cu")
		(net "PD_EXT_CLK_SEL_CPU1")
	)
	(arc
		(start 102.055168 -219.18168)
		(mid 101.780969 -219.257515)
		(end 101.504496 -219.190316)
		(width 0.0889)
		(layer "B.Cu")
		(net "PD_EXT_CLK_SEL_CPU1")
	)
	(arc
		(start 105.71861 -219.995496)
		(mid 105.531412 -219.945353)
		(end 105.344214 -219.995496)
		(width 0.0889)
		(layer "B.Cu")
		(net "PD_EXT_CLK_SEL_CPU1")
	)
	(arc
		(start 108.633768 -222.437198)
		(mid 108.359569 -222.513033)
		(end 108.083096 -222.445834)
		(width 0.0889)
		(layer "B.Cu")
		(net "PD_EXT_CLK_SEL_CPU1")
	)
	(arc
		(start 100.175568 -219.18168)
		(mid 99.901369 -219.257515)
		(end 99.624896 -219.190316)
		(width 0.0889)
		(layer "B.Cu")
		(net "PD_EXT_CLK_SEL_CPU1")
	)
	(arc
		(start 97.356168 -219.18168)
		(mid 97.081969 -219.257515)
		(end 96.805496 -219.190316)
		(width 0.0889)
		(layer "B.Cu")
		(net "PD_EXT_CLK_SEL_CPU1")
	)
	(arc
		(start 99.235768 -219.18168)
		(mid 98.961569 -219.257515)
		(end 98.685096 -219.190316)
		(width 0.0889)
		(layer "B.Cu")
		(net "PD_EXT_CLK_SEL_CPU1")
	)
	(arc
		(start 88.989662 -218.683586)
		(mid 88.937392 -218.501221)
		(end 88.802464 -218.367864)
		(width 0.0889)
		(layer "B.Cu")
		(net "PD_EXT_CLK_SEL_CPU1")
	)
	(arc
		(start 111.075216 -227.64496)
		(mid 111.027537 -227.46206)
		(end 110.896654 -227.325682)
		(width 0.0889)
		(layer "B.Cu")
		(net "PD_EXT_CLK_SEL_CPU1")
	)
	(arc
		(start 92.091764 -219.18168)
		(mid 91.904566 -219.131537)
		(end 91.717368 -219.18168)
		(width 0.0889)
		(layer "B.Cu")
		(net "PD_EXT_CLK_SEL_CPU1")
	)
	(arc
		(start 95.850964 -219.18168)
		(mid 95.663766 -219.131537)
		(end 95.476568 -219.18168)
		(width 0.0889)
		(layer "B.Cu")
		(net "PD_EXT_CLK_SEL_CPU1")
	)
	(arc
		(start 89.266268 -219.178124)
		(mid 89.063681 -218.971773)
		(end 88.989662 -218.692222)
		(width 0.0889)
		(layer "B.Cu")
		(net "PD_EXT_CLK_SEL_CPU1")
	)
	(arc
		(start 88.332564 -217.554048)
		(mid 88.129083 -217.353244)
		(end 88.049862 -217.07856)
		(width 0.0889)
		(layer "B.Cu")
		(net "PD_EXT_CLK_SEL_CPU1")
	)
	(arc
		(start 97.730564 -219.18168)
		(mid 97.543366 -219.131537)
		(end 97.356168 -219.18168)
		(width 0.0889)
		(layer "B.Cu")
		(net "PD_EXT_CLK_SEL_CPU1")
	)
	(arc
		(start 111.82731 -228.948488)
		(mid 111.622975 -228.745883)
		(end 111.544862 -228.468936)
		(width 0.0889)
		(layer "B.Cu")
		(net "PD_EXT_CLK_SEL_CPU1")
	)
	(arc
		(start 94.911164 -219.18168)
		(mid 94.723966 -219.131537)
		(end 94.536768 -219.18168)
		(width 0.0889)
		(layer "B.Cu")
		(net "PD_EXT_CLK_SEL_CPU1")
	)
	(arc
		(start 112.014762 -229.272846)
		(mid 111.967083 -229.089946)
		(end 111.8362 -228.953568)
		(width 0.0889)
		(layer "B.Cu")
		(net "PD_EXT_CLK_SEL_CPU1")
	)
	(arc
		(start 112.484916 -230.086662)
		(mid 112.437237 -229.903762)
		(end 112.306354 -229.767384)
		(width 0.0889)
		(layer "B.Cu")
		(net "PD_EXT_CLK_SEL_CPU1")
	)
	(arc
		(start 102.994968 -219.18168)
		(mid 102.720769 -219.257515)
		(end 102.444296 -219.190316)
		(width 0.0889)
		(layer "B.Cu")
		(net "PD_EXT_CLK_SEL_CPU1")
	)
	(arc
		(start 100.549964 -219.18168)
		(mid 100.362766 -219.131537)
		(end 100.175568 -219.18168)
		(width 0.0889)
		(layer "B.Cu")
		(net "PD_EXT_CLK_SEL_CPU1")
	)
	(arc
		(start 109.195616 -222.761556)
		(mid 109.147937 -222.578656)
		(end 109.017054 -222.442278)
		(width 0.0889)
		(layer "B.Cu")
		(net "PD_EXT_CLK_SEL_CPU1")
	)
	(arc
		(start 112.767364 -230.57612)
		(mid 112.564541 -230.375889)
		(end 112.48517 -230.102156)
		(width 0.0889)
		(layer "B.Cu")
		(net "PD_EXT_CLK_SEL_CPU1")
	)
	(arc
		(start 103.369364 -219.18168)
		(mid 103.182166 -219.131537)
		(end 102.994968 -219.18168)
		(width 0.0889)
		(layer "B.Cu")
		(net "PD_EXT_CLK_SEL_CPU1")
	)
	(arc
		(start 110.417864 -226.506786)
		(mid 110.213529 -226.304181)
		(end 110.135416 -226.027234)
		(width 0.0889)
		(layer "B.Cu")
		(net "PD_EXT_CLK_SEL_CPU1")
	)
	(arc
		(start 105.3338 -220.001592)
		(mid 105.055622 -220.071315)
		(end 104.779064 -219.995496)
		(width 0.0889)
		(layer "B.Cu")
		(net "PD_EXT_CLK_SEL_CPU1")
	)
	(arc
		(start 88.802464 -218.367864)
		(mid 88.598129 -218.165259)
		(end 88.520016 -217.888312)
		(width 0.0889)
		(layer "B.Cu")
		(net "PD_EXT_CLK_SEL_CPU1")
	)
	(arc
		(start 87.579708 -216.25052)
		(mid 87.532029 -216.06762)
		(end 87.401146 -215.931242)
		(width 0.0889)
		(layer "B.Cu")
		(net "PD_EXT_CLK_SEL_CPU1")
	)
	(arc
		(start 102.429564 -219.18168)
		(mid 102.242366 -219.131537)
		(end 102.055168 -219.18168)
		(width 0.0889)
		(layer "B.Cu")
		(net "PD_EXT_CLK_SEL_CPU1")
	)
	(arc
		(start 109.47781 -223.251268)
		(mid 109.276528 -223.053781)
		(end 109.195616 -222.783654)
		(width 0.0889)
		(layer "B.Cu")
		(net "PD_EXT_CLK_SEL_CPU1")
	)
	(arc
		(start 107.59821 -221.623382)
		(mid 107.395387 -221.423151)
		(end 107.316016 -221.149418)
		(width 0.0889)
		(layer "B.Cu")
		(net "PD_EXT_CLK_SEL_CPU1")
	)
	(arc
		(start 110.881668 -227.317046)
		(mid 110.679081 -227.110695)
		(end 110.605062 -226.831144)
		(width 0.0889)
		(layer "B.Cu")
		(net "PD_EXT_CLK_SEL_CPU1")
	)
	(arc
		(start 107.316016 -221.133924)
		(mid 107.268337 -220.951024)
		(end 107.137454 -220.814646)
		(width 0.0889)
		(layer "B.Cu")
		(net "PD_EXT_CLK_SEL_CPU1")
	)
	(arc
		(start 87.392256 -215.926162)
		(mid 87.189433 -215.725931)
		(end 87.110062 -215.452198)
		(width 0.0889)
		(layer "B.Cu")
		(net "PD_EXT_CLK_SEL_CPU1")
	)
	(arc
		(start 89.837768 -219.18168)
		(mid 89.563569 -219.257515)
		(end 89.287096 -219.190316)
		(width 0.0889)
		(layer "B.Cu")
		(net "PD_EXT_CLK_SEL_CPU1")
	)
	(arc
		(start 109.008164 -222.437198)
		(mid 108.820966 -222.387055)
		(end 108.633768 -222.437198)
		(width 0.0889)
		(layer "B.Cu")
		(net "PD_EXT_CLK_SEL_CPU1")
	)
	(arc
		(start 99.610164 -219.18168)
		(mid 99.422966 -219.131537)
		(end 99.235768 -219.18168)
		(width 0.0889)
		(layer "B.Cu")
		(net "PD_EXT_CLK_SEL_CPU1")
	)
	(arc
		(start 98.295968 -219.18168)
		(mid 98.021769 -219.257515)
		(end 97.745296 -219.190316)
		(width 0.0889)
		(layer "B.Cu")
		(net "PD_EXT_CLK_SEL_CPU1")
	)
	(arc
		(start 109.47781 -224.8789)
		(mid 109.274987 -224.678669)
		(end 109.195616 -224.404936)
		(width 0.0889)
		(layer "B.Cu")
		(net "PD_EXT_CLK_SEL_CPU1")
	)
	(arc
		(start 110.605062 -226.822508)
		(mid 110.552792 -226.640143)
		(end 110.417864 -226.506786)
		(width 0.0889)
		(layer "B.Cu")
		(net "PD_EXT_CLK_SEL_CPU1")
	)
	(arc
		(start 88.520016 -217.878406)
		(mid 88.472337 -217.695506)
		(end 88.341454 -217.559128)
		(width 0.0889)
		(layer "B.Cu")
		(net "PD_EXT_CLK_SEL_CPU1")
	)
	(arc
		(start 101.115368 -219.18168)
		(mid 100.841169 -219.257515)
		(end 100.564696 -219.190316)
		(width 0.0889)
		(layer "B.Cu")
		(net "PD_EXT_CLK_SEL_CPU1")
	)
	(arc
		(start 109.947964 -225.69297)
		(mid 109.744483 -225.492166)
		(end 109.665262 -225.217482)
		(width 0.0889)
		(layer "B.Cu")
		(net "PD_EXT_CLK_SEL_CPU1")
	)
	(arc
		(start 106.273854 -220.001592)
		(mid 105.995422 -220.071438)
		(end 105.71861 -219.995496)
		(width 0.0889)
		(layer "B.Cu")
		(net "PD_EXT_CLK_SEL_CPU1")
	)
	(arc
		(start 106.845862 -220.311218)
		(mid 106.793592 -220.128853)
		(end 106.658664 -219.995496)
		(width 0.0889)
		(layer "B.Cu")
		(net "PD_EXT_CLK_SEL_CPU1")
	)
	(arc
		(start 107.785662 -221.94774)
		(mid 107.737983 -221.76484)
		(end 107.6071 -221.628462)
		(width 0.0889)
		(layer "B.Cu")
		(net "PD_EXT_CLK_SEL_CPU1")
	)
	(arc
		(start 93.031564 -219.18168)
		(mid 92.844366 -219.131537)
		(end 92.657168 -219.18168)
		(width 0.0889)
		(layer "B.Cu")
		(net "PD_EXT_CLK_SEL_CPU1")
	)
	(arc
		(start 112.776254 -231.219756)
		(mid 112.954851 -230.900478)
		(end 112.776254 -230.5812)
		(width 0.0889)
		(layer "B.Cu")
		(net "PD_EXT_CLK_SEL_CPU1")
	)
	(arc
		(start 112.285272 -229.755192)
		(mid 112.087044 -229.549344)
		(end 112.014762 -229.272846)
		(width 0.0889)
		(layer "B.Cu")
		(net "PD_EXT_CLK_SEL_CPU1")
	)
	(arc
		(start 96.790764 -219.18168)
		(mid 96.603566 -219.131537)
		(end 96.416368 -219.18168)
		(width 0.0889)
		(layer "B.Cu")
		(net "PD_EXT_CLK_SEL_CPU1")
	)
	(arc
		(start 98.670364 -219.18168)
		(mid 98.483166 -219.131537)
		(end 98.295968 -219.18168)
		(width 0.0889)
		(layer "B.Cu")
		(net "PD_EXT_CLK_SEL_CPU1")
	)
	(arc
		(start 109.4867 -223.894904)
		(mid 109.665297 -223.575626)
		(end 109.4867 -223.256348)
		(width 0.0889)
		(layer "B.Cu")
		(net "PD_EXT_CLK_SEL_CPU1")
	)
	(arc
		(start 90.212164 -219.18168)
		(mid 90.024966 -219.131537)
		(end 89.837768 -219.18168)
		(width 0.0889)
		(layer "B.Cu")
		(net "PD_EXT_CLK_SEL_CPU1")
	)
	(arc
		(start 88.049862 -217.064336)
		(mid 88.002183 -216.881436)
		(end 87.8713 -216.745058)
		(width 0.0889)
		(layer "B.Cu")
		(net "PD_EXT_CLK_SEL_CPU1")
	)
	(arc
		(start 107.128564 -220.809566)
		(mid 106.925083 -220.608762)
		(end 106.845862 -220.334078)
		(width 0.0889)
		(layer "B.Cu")
		(net "PD_EXT_CLK_SEL_CPU1")
	)
	(arc
		(start 93.971364 -219.18168)
		(mid 93.784166 -219.131537)
		(end 93.596968 -219.18168)
		(width 0.0889)
		(layer "B.Cu")
		(net "PD_EXT_CLK_SEL_CPU1")
	)
	(arc
		(start 106.658664 -219.995496)
		(mid 106.471466 -219.945353)
		(end 106.284268 -219.995496)
		(width 0.0889)
		(layer "B.Cu")
		(net "PD_EXT_CLK_SEL_CPU1")
	)
	(arc
		(start 95.476568 -219.18168)
		(mid 95.202369 -219.257515)
		(end 94.925896 -219.190316)
		(width 0.0889)
		(layer "B.Cu")
		(net "PD_EXT_CLK_SEL_CPU1")
	)
	(arc
		(start 111.357664 -228.134672)
		(mid 111.155378 -227.935691)
		(end 111.075216 -227.663502)
		(width 0.0889)
		(layer "B.Cu")
		(net "PD_EXT_CLK_SEL_CPU1")
	)
	(arc
		(start 111.544862 -228.450394)
		(mid 111.492592 -228.268029)
		(end 111.357664 -228.134672)
		(width 0.0889)
		(layer "B.Cu")
		(net "PD_EXT_CLK_SEL_CPU1")
	)
	(arc
		(start 90.777568 -219.18168)
		(mid 90.503369 -219.257515)
		(end 90.226896 -219.190316)
		(width 0.0889)
		(layer "B.Cu")
		(net "PD_EXT_CLK_SEL_CPU1")
	)
	(arc
		(start 112.48517 -231.69245)
		(mid 112.566081 -231.422322)
		(end 112.767364 -231.224836)
		(width 0.0889)
		(layer "B.Cu")
		(net "PD_EXT_CLK_SEL_CPU1")
	)
	(segment
		(start 360.51998 -233.064304)
		(end 360.51998 -232.528618)
		(width 0.12954)
		(layer "F.Cu")
		(net "PD_EXT_CLK_SEL_CPU0")
	)
	(segment
		(start 360.51998 -232.528618)
		(end 360.520234 -232.528364)
		(width 0.12954)
		(layer "F.Cu")
		(net "PD_EXT_CLK_SEL_CPU0")
	)
	(via
		(at 360.520234 -232.528364)
		(size 0.4572)
		(drill 0.2032)
		(layers "F.Cu" "B.Cu")
		(net "PD_EXT_CLK_SEL_CPU0")
	)
	(via
		(at 339.97773 -196.845936)
		(size 0.6604)
		(drill 0.3302)
		(layers "F.Cu" "B.Cu")
		(net "PD_EXT_CLK_SEL_CPU0")
	)
	(segment
		(start 339.97773 -199.061324)
		(end 339.97773 -196.845936)
		(width 0.12954)
		(layer "B.Cu")
		(net "PD_EXT_CLK_SEL_CPU0")
	)
	(segment
		(start 342.946482 -219.01658)
		(end 342.93175 -219.007944)
		(width 0.0889)
		(layer "B.Cu")
		(net "PD_EXT_CLK_SEL_CPU0")
	)
	(segment
		(start 353.203764 -219.82176)
		(end 353.189032 -219.830396)
		(width 0.0889)
		(layer "B.Cu")
		(net "PD_EXT_CLK_SEL_CPU0")
	)
	(segment
		(start 335.428082 -215.761062)
		(end 335.419192 -215.755982)
		(width 0.0889)
		(layer "B.Cu")
		(net "PD_EXT_CLK_SEL_CPU0")
	)
	(segment
		(start 340.552278 -196.271388)
		(end 340.552278 -190.877952)
		(width 0.12954)
		(layer "B.Cu")
		(net "PD_EXT_CLK_SEL_CPU0")
	)
	(segment
		(start 336.838036 -218.202764)
		(end 336.829146 -218.197684)
		(width 0.0889)
		(layer "B.Cu")
		(net "PD_EXT_CLK_SEL_CPU0")
	)
	(segment
		(start 336.18043 -217.064336)
		(end 336.18043 -217.05443)
		(width 0.0889)
		(layer "B.Cu")
		(net "PD_EXT_CLK_SEL_CPU0")
	)
	(segment
		(start 358.735884 -228.45903)
		(end 358.735884 -228.444806)
		(width 0.0889)
		(layer "B.Cu")
		(net "PD_EXT_CLK_SEL_CPU0")
	)
	(segment
		(start 360.516678 -232.524808)
		(end 360.516678 -231.89184)
		(width 0.0889)
		(layer "B.Cu")
		(net "PD_EXT_CLK_SEL_CPU0")
	)
	(segment
		(start 358.265984 -227.64496)
		(end 358.265984 -227.635054)
		(width 0.0889)
		(layer "B.Cu")
		(net "PD_EXT_CLK_SEL_CPU0")
	)
	(segment
		(start 336.650584 -217.878406)
		(end 336.650584 -217.864182)
		(width 0.0889)
		(layer "B.Cu")
		(net "PD_EXT_CLK_SEL_CPU0")
	)
	(segment
		(start 347.645482 -219.01658)
		(end 347.63075 -219.007944)
		(width 0.0889)
		(layer "B.Cu")
		(net "PD_EXT_CLK_SEL_CPU0")
	)
	(segment
		(start 337.120484 -218.700858)
		(end 337.120484 -218.682316)
		(width 0.0889)
		(layer "B.Cu")
		(net "PD_EXT_CLK_SEL_CPU0")
	)
	(segment
		(start 357.513636 -226.341686)
		(end 357.504746 -226.336606)
		(width 0.0889)
		(layer "B.Cu")
		(net "PD_EXT_CLK_SEL_CPU0")
	)
	(segment
		(start 344.826082 -219.01658)
		(end 344.81135 -219.007944)
		(width 0.0889)
		(layer "B.Cu")
		(net "PD_EXT_CLK_SEL_CPU0")
	)
	(segment
		(start 352.350578 -219.020136)
		(end 352.344482 -219.01658)
		(width 0.0889)
		(layer "B.Cu")
		(net "PD_EXT_CLK_SEL_CPU0")
	)
	(segment
		(start 346.705682 -219.01658)
		(end 346.69095 -219.007944)
		(width 0.0889)
		(layer "B.Cu")
		(net "PD_EXT_CLK_SEL_CPU0")
	)
	(segment
		(start 339.97773 -196.845936)
		(end 340.552278 -196.271388)
		(width 0.12954)
		(layer "B.Cu")
		(net "PD_EXT_CLK_SEL_CPU0")
	)
	(segment
		(start 356.103682 -222.272098)
		(end 356.094792 -222.267018)
		(width 0.0889)
		(layer "B.Cu")
		(net "PD_EXT_CLK_SEL_CPU0")
	)
	(segment
		(start 335.24063 -215.17229)
		(end 335.24063 -213.332568)
		(width 0.12954)
		(layer "B.Cu")
		(net "PD_EXT_CLK_SEL_CPU0")
	)
	(segment
		(start 356.856284 -223.585532)
		(end 356.856284 -223.557084)
		(width 0.0889)
		(layer "B.Cu")
		(net "PD_EXT_CLK_SEL_CPU0")
	)
	(segment
		(start 340.127082 -219.01658)
		(end 340.11235 -219.007944)
		(width 0.0889)
		(layer "B.Cu")
		(net "PD_EXT_CLK_SEL_CPU0")
	)
	(segment
		(start 356.573836 -224.7138)
		(end 356.564946 -224.70872)
		(width 0.0889)
		(layer "B.Cu")
		(net "PD_EXT_CLK_SEL_CPU0")
	)
	(segment
		(start 351.404682 -219.01658)
		(end 351.38995 -219.007944)
		(width 0.0889)
		(layer "B.Cu")
		(net "PD_EXT_CLK_SEL_CPU0")
	)
	(segment
		(start 358.453436 -227.969318)
		(end 358.444546 -227.964238)
		(width 0.0889)
		(layer "B.Cu")
		(net "PD_EXT_CLK_SEL_CPU0")
	)
	(segment
		(start 357.326184 -226.017328)
		(end 357.326184 -226.003104)
		(width 0.0889)
		(layer "B.Cu")
		(net "PD_EXT_CLK_SEL_CPU0")
	)
	(segment
		(start 338.247482 -219.01658)
		(end 338.23275 -219.007944)
		(width 0.0889)
		(layer "B.Cu")
		(net "PD_EXT_CLK_SEL_CPU0")
	)
	(segment
		(start 356.109778 -222.275654)
		(end 356.103682 -222.272098)
		(width 0.0889)
		(layer "B.Cu")
		(net "PD_EXT_CLK_SEL_CPU0")
	)
	(segment
		(start 345.765882 -219.01658)
		(end 345.75115 -219.007944)
		(width 0.0889)
		(layer "B.Cu")
		(net "PD_EXT_CLK_SEL_CPU0")
	)
	(segment
		(start 361.085384 -230.922576)
		(end 361.085384 -230.884984)
		(width 0.0889)
		(layer "B.Cu")
		(net "PD_EXT_CLK_SEL_CPU0")
	)
	(segment
		(start 339.187282 -219.01658)
		(end 339.17255 -219.007944)
		(width 0.0889)
		(layer "B.Cu")
		(net "PD_EXT_CLK_SEL_CPU0")
	)
	(segment
		(start 360.520234 -232.528364)
		(end 360.516678 -232.524808)
		(width 0.0889)
		(layer "B.Cu")
		(net "PD_EXT_CLK_SEL_CPU0")
	)
	(segment
		(start 352.814636 -219.830396)
		(end 352.805746 -219.825316)
		(width 0.0889)
		(layer "B.Cu")
		(net "PD_EXT_CLK_SEL_CPU0")
	)
	(segment
		(start 341.066882 -219.01658)
		(end 341.05215 -219.007944)
		(width 0.0889)
		(layer "B.Cu")
		(net "PD_EXT_CLK_SEL_CPU0")
	)
	(segment
		(start 335.24063 -213.332568)
		(end 334.329278 -212.421216)
		(width 0.12954)
		(layer "B.Cu")
		(net "PD_EXT_CLK_SEL_CPU0")
	)
	(segment
		(start 356.85603 -225.203258)
		(end 356.85603 -225.187764)
		(width 0.0889)
		(layer "B.Cu")
		(net "PD_EXT_CLK_SEL_CPU0")
	)
	(segment
		(start 354.976684 -220.32849)
		(end 354.976684 -220.309948)
		(width 0.0889)
		(layer "B.Cu")
		(net "PD_EXT_CLK_SEL_CPU0")
	)
	(segment
		(start 360.615738 -230.086662)
		(end 360.615484 -230.086662)
		(width 0.0889)
		(layer "B.Cu")
		(net "PD_EXT_CLK_SEL_CPU0")
	)
	(segment
		(start 340.552278 -190.877952)
		(end 339.97773 -190.303404)
		(width 0.12954)
		(layer "B.Cu")
		(net "PD_EXT_CLK_SEL_CPU0")
	)
	(segment
		(start 335.434178 -215.764618)
		(end 335.428082 -215.761062)
		(width 0.0889)
		(layer "B.Cu")
		(net "PD_EXT_CLK_SEL_CPU0")
	)
	(segment
		(start 360.80319 -230.41102)
		(end 360.7943 -230.40594)
		(width 0.0889)
		(layer "B.Cu")
		(net "PD_EXT_CLK_SEL_CPU0")
	)
	(segment
		(start 360.615484 -230.086662)
		(end 360.615484 -230.076756)
		(width 0.0889)
		(layer "B.Cu")
		(net "PD_EXT_CLK_SEL_CPU0")
	)
	(segment
		(start 355.446584 -221.133924)
		(end 355.446584 -221.1197)
		(width 0.0889)
		(layer "B.Cu")
		(net "PD_EXT_CLK_SEL_CPU0")
	)
	(segment
		(start 350.464882 -219.01658)
		(end 350.45015 -219.007944)
		(width 0.0889)
		(layer "B.Cu")
		(net "PD_EXT_CLK_SEL_CPU0")
	)
	(segment
		(start 335.24063 -215.436704)
		(end 335.24063 -215.17229)
		(width 0.0889)
		(layer "B.Cu")
		(net "PD_EXT_CLK_SEL_CPU0")
	)
	(segment
		(start 352.344482 -219.01658)
		(end 352.32975 -219.007944)
		(width 0.0889)
		(layer "B.Cu")
		(net "PD_EXT_CLK_SEL_CPU0")
	)
	(segment
		(start 334.329278 -204.709776)
		(end 339.97773 -199.061324)
		(width 0.12954)
		(layer "B.Cu")
		(net "PD_EXT_CLK_SEL_CPU0")
	)
	(segment
		(start 349.525082 -219.01658)
		(end 349.51035 -219.007944)
		(width 0.0889)
		(layer "B.Cu")
		(net "PD_EXT_CLK_SEL_CPU0")
	)
	(segment
		(start 343.886282 -219.01658)
		(end 343.87155 -219.007944)
		(width 0.0889)
		(layer "B.Cu")
		(net "PD_EXT_CLK_SEL_CPU0")
	)
	(segment
		(start 357.983536 -227.155502)
		(end 357.974646 -227.150422)
		(width 0.0889)
		(layer "B.Cu")
		(net "PD_EXT_CLK_SEL_CPU0")
	)
	(segment
		(start 358.923336 -228.783388)
		(end 358.914446 -228.778308)
		(width 0.0889)
		(layer "B.Cu")
		(net "PD_EXT_CLK_SEL_CPU0")
	)
	(segment
		(start 360.333036 -229.597204)
		(end 360.322622 -229.591108)
		(width 0.0889)
		(layer "B.Cu")
		(net "PD_EXT_CLK_SEL_CPU0")
	)
	(segment
		(start 336.367882 -217.388694)
		(end 336.358992 -217.383614)
		(width 0.0889)
		(layer "B.Cu")
		(net "PD_EXT_CLK_SEL_CPU0")
	)
	(segment
		(start 348.585282 -219.01658)
		(end 348.57055 -219.007944)
		(width 0.0889)
		(layer "B.Cu")
		(net "PD_EXT_CLK_SEL_CPU0")
	)
	(segment
		(start 357.519732 -226.345242)
		(end 357.513636 -226.341686)
		(width 0.0889)
		(layer "B.Cu")
		(net "PD_EXT_CLK_SEL_CPU0")
	)
	(segment
		(start 342.006682 -219.01658)
		(end 341.99195 -219.007944)
		(width 0.0889)
		(layer "B.Cu")
		(net "PD_EXT_CLK_SEL_CPU0")
	)
	(segment
		(start 359.205784 -229.281482)
		(end 359.205784 -229.26294)
		(width 0.0889)
		(layer "B.Cu")
		(net "PD_EXT_CLK_SEL_CPU0")
	)
	(segment
		(start 334.329278 -212.421216)
		(end 334.329278 -204.709776)
		(width 0.12954)
		(layer "B.Cu")
		(net "PD_EXT_CLK_SEL_CPU0")
	)
	(segment
		(start 355.634036 -221.458282)
		(end 355.625146 -221.453202)
		(width 0.0889)
		(layer "B.Cu")
		(net "PD_EXT_CLK_SEL_CPU0")
	)
	(segment
		(start 356.573836 -223.085914)
		(end 356.564946 -223.080834)
		(width 0.0889)
		(layer "B.Cu")
		(net "PD_EXT_CLK_SEL_CPU0")
	)
	(segment
		(start 357.043482 -225.527616)
		(end 357.034592 -225.522536)
		(width 0.0889)
		(layer "B.Cu")
		(net "PD_EXT_CLK_SEL_CPU0")
	)
	(segment
		(start 360.7943 -231.39527)
		(end 360.80319 -231.39019)
		(width 0.0889)
		(layer "B.Cu")
		(net "PD_EXT_CLK_SEL_CPU0")
	)
	(segment
		(start 335.897982 -216.574878)
		(end 335.889092 -216.569798)
		(width 0.0889)
		(layer "B.Cu")
		(net "PD_EXT_CLK_SEL_CPU0")
	)
	(segment
		(start 355.91623 -221.94774)
		(end 355.91623 -221.932246)
		(width 0.0889)
		(layer "B.Cu")
		(net "PD_EXT_CLK_SEL_CPU0")
	)
	(segment
		(start 356.564946 -224.070164)
		(end 356.573836 -224.065084)
		(width 0.0889)
		(layer "B.Cu")
		(net "PD_EXT_CLK_SEL_CPU0")
	)
	(arc
		(start 338.23275 -219.007944)
		(mid 337.956275 -218.940624)
		(end 337.682078 -219.01658)
		(width 0.0889)
		(layer "B.Cu")
		(net "PD_EXT_CLK_SEL_CPU0")
	)
	(arc
		(start 344.260678 -219.01658)
		(mid 344.07348 -219.066723)
		(end 343.886282 -219.01658)
		(width 0.0889)
		(layer "B.Cu")
		(net "PD_EXT_CLK_SEL_CPU0")
	)
	(arc
		(start 335.71053 -216.25052)
		(mid 335.636614 -215.971018)
		(end 335.434178 -215.764618)
		(width 0.0889)
		(layer "B.Cu")
		(net "PD_EXT_CLK_SEL_CPU0")
	)
	(arc
		(start 348.959678 -219.01658)
		(mid 348.77248 -219.066723)
		(end 348.585282 -219.01658)
		(width 0.0889)
		(layer "B.Cu")
		(net "PD_EXT_CLK_SEL_CPU0")
	)
	(arc
		(start 339.17255 -219.007944)
		(mid 338.896075 -218.940624)
		(end 338.621878 -219.01658)
		(width 0.0889)
		(layer "B.Cu")
		(net "PD_EXT_CLK_SEL_CPU0")
	)
	(arc
		(start 335.419192 -215.755982)
		(mid 335.288278 -215.619622)
		(end 335.24063 -215.436704)
		(width 0.0889)
		(layer "B.Cu")
		(net "PD_EXT_CLK_SEL_CPU0")
	)
	(arc
		(start 352.627184 -219.506038)
		(mid 352.553193 -219.226472)
		(end 352.350578 -219.020136)
		(width 0.0889)
		(layer "B.Cu")
		(net "PD_EXT_CLK_SEL_CPU0")
	)
	(arc
		(start 347.080078 -219.01658)
		(mid 346.89288 -219.066723)
		(end 346.705682 -219.01658)
		(width 0.0889)
		(layer "B.Cu")
		(net "PD_EXT_CLK_SEL_CPU0")
	)
	(arc
		(start 336.829146 -218.197684)
		(mid 336.698232 -218.061324)
		(end 336.650584 -217.878406)
		(width 0.0889)
		(layer "B.Cu")
		(net "PD_EXT_CLK_SEL_CPU0")
	)
	(arc
		(start 346.69095 -219.007944)
		(mid 346.414475 -218.940624)
		(end 346.140278 -219.01658)
		(width 0.0889)
		(layer "B.Cu")
		(net "PD_EXT_CLK_SEL_CPU0")
	)
	(arc
		(start 349.51035 -219.007944)
		(mid 349.233875 -218.940624)
		(end 348.959678 -219.01658)
		(width 0.0889)
		(layer "B.Cu")
		(net "PD_EXT_CLK_SEL_CPU0")
	)
	(arc
		(start 348.57055 -219.007944)
		(mid 348.294075 -218.940624)
		(end 348.019878 -219.01658)
		(width 0.0889)
		(layer "B.Cu")
		(net "PD_EXT_CLK_SEL_CPU0")
	)
	(arc
		(start 337.307682 -219.01658)
		(mid 337.172749 -218.883226)
		(end 337.120484 -218.700858)
		(width 0.0889)
		(layer "B.Cu")
		(net "PD_EXT_CLK_SEL_CPU0")
	)
	(arc
		(start 356.85603 -225.187764)
		(mid 356.77666 -224.91403)
		(end 356.573836 -224.7138)
		(width 0.0889)
		(layer "B.Cu")
		(net "PD_EXT_CLK_SEL_CPU0")
	)
	(arc
		(start 350.45015 -219.007944)
		(mid 350.173675 -218.940624)
		(end 349.899478 -219.01658)
		(width 0.0889)
		(layer "B.Cu")
		(net "PD_EXT_CLK_SEL_CPU0")
	)
	(arc
		(start 355.91623 -221.932246)
		(mid 355.83686 -221.658512)
		(end 355.634036 -221.458282)
		(width 0.0889)
		(layer "B.Cu")
		(net "PD_EXT_CLK_SEL_CPU0")
	)
	(arc
		(start 341.99195 -219.007944)
		(mid 341.715475 -218.940624)
		(end 341.441278 -219.01658)
		(width 0.0889)
		(layer "B.Cu")
		(net "PD_EXT_CLK_SEL_CPU0")
	)
	(arc
		(start 345.75115 -219.007944)
		(mid 345.474675 -218.940624)
		(end 345.200478 -219.01658)
		(width 0.0889)
		(layer "B.Cu")
		(net "PD_EXT_CLK_SEL_CPU0")
	)
	(arc
		(start 343.320878 -219.01658)
		(mid 343.13368 -219.066723)
		(end 342.946482 -219.01658)
		(width 0.0889)
		(layer "B.Cu")
		(net "PD_EXT_CLK_SEL_CPU0")
	)
	(arc
		(start 360.80319 -231.39019)
		(mid 361.004472 -231.192703)
		(end 361.085384 -230.922576)
		(width 0.0889)
		(layer "B.Cu")
		(net "PD_EXT_CLK_SEL_CPU0")
	)
	(arc
		(start 342.93175 -219.007944)
		(mid 342.655275 -218.940624)
		(end 342.381078 -219.01658)
		(width 0.0889)
		(layer "B.Cu")
		(net "PD_EXT_CLK_SEL_CPU0")
	)
	(arc
		(start 340.11235 -219.007944)
		(mid 339.835875 -218.940624)
		(end 339.561678 -219.01658)
		(width 0.0889)
		(layer "B.Cu")
		(net "PD_EXT_CLK_SEL_CPU0")
	)
	(arc
		(start 353.754436 -219.830396)
		(mid 353.480237 -219.754561)
		(end 353.203764 -219.82176)
		(width 0.0889)
		(layer "B.Cu")
		(net "PD_EXT_CLK_SEL_CPU0")
	)
	(arc
		(start 354.128832 -219.830396)
		(mid 353.941634 -219.880539)
		(end 353.754436 -219.830396)
		(width 0.0889)
		(layer "B.Cu")
		(net "PD_EXT_CLK_SEL_CPU0")
	)
	(arc
		(start 357.796084 -226.831144)
		(mid 357.722168 -226.551642)
		(end 357.519732 -226.345242)
		(width 0.0889)
		(layer "B.Cu")
		(net "PD_EXT_CLK_SEL_CPU0")
	)
	(arc
		(start 360.322622 -229.591108)
		(mid 360.04419 -229.521262)
		(end 359.767378 -229.597204)
		(width 0.0889)
		(layer "B.Cu")
		(net "PD_EXT_CLK_SEL_CPU0")
	)
	(arc
		(start 352.32975 -219.007944)
		(mid 352.053275 -218.940624)
		(end 351.779078 -219.01658)
		(width 0.0889)
		(layer "B.Cu")
		(net "PD_EXT_CLK_SEL_CPU0")
	)
	(arc
		(start 341.05215 -219.007944)
		(mid 340.775675 -218.940624)
		(end 340.501478 -219.01658)
		(width 0.0889)
		(layer "B.Cu")
		(net "PD_EXT_CLK_SEL_CPU0")
	)
	(arc
		(start 358.444546 -227.964238)
		(mid 358.313632 -227.827878)
		(end 358.265984 -227.64496)
		(width 0.0889)
		(layer "B.Cu")
		(net "PD_EXT_CLK_SEL_CPU0")
	)
	(arc
		(start 359.767378 -229.597204)
		(mid 359.58018 -229.647347)
		(end 359.392982 -229.597204)
		(width 0.0889)
		(layer "B.Cu")
		(net "PD_EXT_CLK_SEL_CPU0")
	)
	(arc
		(start 349.899478 -219.01658)
		(mid 349.71228 -219.066723)
		(end 349.525082 -219.01658)
		(width 0.0889)
		(layer "B.Cu")
		(net "PD_EXT_CLK_SEL_CPU0")
	)
	(arc
		(start 358.265984 -227.635054)
		(mid 358.187873 -227.358105)
		(end 357.983536 -227.155502)
		(width 0.0889)
		(layer "B.Cu")
		(net "PD_EXT_CLK_SEL_CPU0")
	)
	(arc
		(start 357.326184 -226.003104)
		(mid 357.246965 -225.728419)
		(end 357.043482 -225.527616)
		(width 0.0889)
		(layer "B.Cu")
		(net "PD_EXT_CLK_SEL_CPU0")
	)
	(arc
		(start 343.87155 -219.007944)
		(mid 343.595075 -218.940624)
		(end 343.320878 -219.01658)
		(width 0.0889)
		(layer "B.Cu")
		(net "PD_EXT_CLK_SEL_CPU0")
	)
	(arc
		(start 344.81135 -219.007944)
		(mid 344.534875 -218.940624)
		(end 344.260678 -219.01658)
		(width 0.0889)
		(layer "B.Cu")
		(net "PD_EXT_CLK_SEL_CPU0")
	)
	(arc
		(start 360.516678 -231.89184)
		(mid 360.590794 -231.607384)
		(end 360.7943 -231.39527)
		(width 0.0889)
		(layer "B.Cu")
		(net "PD_EXT_CLK_SEL_CPU0")
	)
	(arc
		(start 337.682078 -219.01658)
		(mid 337.49488 -219.066723)
		(end 337.307682 -219.01658)
		(width 0.0889)
		(layer "B.Cu")
		(net "PD_EXT_CLK_SEL_CPU0")
	)
	(arc
		(start 351.38995 -219.007944)
		(mid 351.113475 -218.940624)
		(end 350.839278 -219.01658)
		(width 0.0889)
		(layer "B.Cu")
		(net "PD_EXT_CLK_SEL_CPU0")
	)
	(arc
		(start 357.974646 -227.150422)
		(mid 357.843732 -227.014062)
		(end 357.796084 -226.831144)
		(width 0.0889)
		(layer "B.Cu")
		(net "PD_EXT_CLK_SEL_CPU0")
	)
	(arc
		(start 351.779078 -219.01658)
		(mid 351.59188 -219.066723)
		(end 351.404682 -219.01658)
		(width 0.0889)
		(layer "B.Cu")
		(net "PD_EXT_CLK_SEL_CPU0")
	)
	(arc
		(start 359.205784 -229.26294)
		(mid 359.127673 -228.985991)
		(end 358.923336 -228.783388)
		(width 0.0889)
		(layer "B.Cu")
		(net "PD_EXT_CLK_SEL_CPU0")
	)
	(arc
		(start 360.615484 -230.076756)
		(mid 360.537373 -229.799807)
		(end 360.333036 -229.597204)
		(width 0.0889)
		(layer "B.Cu")
		(net "PD_EXT_CLK_SEL_CPU0")
	)
	(arc
		(start 340.501478 -219.01658)
		(mid 340.31428 -219.066723)
		(end 340.127082 -219.01658)
		(width 0.0889)
		(layer "B.Cu")
		(net "PD_EXT_CLK_SEL_CPU0")
	)
	(arc
		(start 356.564946 -224.70872)
		(mid 356.386349 -224.389442)
		(end 356.564946 -224.070164)
		(width 0.0889)
		(layer "B.Cu")
		(net "PD_EXT_CLK_SEL_CPU0")
	)
	(arc
		(start 360.7943 -230.40594)
		(mid 360.663386 -230.26958)
		(end 360.615738 -230.086662)
		(width 0.0889)
		(layer "B.Cu")
		(net "PD_EXT_CLK_SEL_CPU0")
	)
	(arc
		(start 346.140278 -219.01658)
		(mid 345.95308 -219.066723)
		(end 345.765882 -219.01658)
		(width 0.0889)
		(layer "B.Cu")
		(net "PD_EXT_CLK_SEL_CPU0")
	)
	(arc
		(start 348.019878 -219.01658)
		(mid 347.83268 -219.066723)
		(end 347.645482 -219.01658)
		(width 0.0889)
		(layer "B.Cu")
		(net "PD_EXT_CLK_SEL_CPU0")
	)
	(arc
		(start 359.392982 -229.597204)
		(mid 359.258049 -229.46385)
		(end 359.205784 -229.281482)
		(width 0.0889)
		(layer "B.Cu")
		(net "PD_EXT_CLK_SEL_CPU0")
	)
	(arc
		(start 356.564946 -223.080834)
		(mid 356.434032 -222.944474)
		(end 356.386384 -222.761556)
		(width 0.0889)
		(layer "B.Cu")
		(net "PD_EXT_CLK_SEL_CPU0")
	)
	(arc
		(start 357.034592 -225.522536)
		(mid 356.903678 -225.386176)
		(end 356.85603 -225.203258)
		(width 0.0889)
		(layer "B.Cu")
		(net "PD_EXT_CLK_SEL_CPU0")
	)
	(arc
		(start 336.358992 -217.383614)
		(mid 336.228078 -217.247254)
		(end 336.18043 -217.064336)
		(width 0.0889)
		(layer "B.Cu")
		(net "PD_EXT_CLK_SEL_CPU0")
	)
	(arc
		(start 354.694236 -219.830396)
		(mid 354.411534 -219.75462)
		(end 354.128832 -219.830396)
		(width 0.0889)
		(layer "B.Cu")
		(net "PD_EXT_CLK_SEL_CPU0")
	)
	(arc
		(start 355.446584 -221.1197)
		(mid 355.367365 -220.845015)
		(end 355.163882 -220.644212)
		(width 0.0889)
		(layer "B.Cu")
		(net "PD_EXT_CLK_SEL_CPU0")
	)
	(arc
		(start 358.914446 -228.778308)
		(mid 358.783532 -228.641948)
		(end 358.735884 -228.45903)
		(width 0.0889)
		(layer "B.Cu")
		(net "PD_EXT_CLK_SEL_CPU0")
	)
	(arc
		(start 347.63075 -219.007944)
		(mid 347.354275 -218.940624)
		(end 347.080078 -219.01658)
		(width 0.0889)
		(layer "B.Cu")
		(net "PD_EXT_CLK_SEL_CPU0")
	)
	(arc
		(start 336.650584 -217.864182)
		(mid 336.571365 -217.589497)
		(end 336.367882 -217.388694)
		(width 0.0889)
		(layer "B.Cu")
		(net "PD_EXT_CLK_SEL_CPU0")
	)
	(arc
		(start 339.561678 -219.01658)
		(mid 339.37448 -219.066723)
		(end 339.187282 -219.01658)
		(width 0.0889)
		(layer "B.Cu")
		(net "PD_EXT_CLK_SEL_CPU0")
	)
	(arc
		(start 356.573836 -224.065084)
		(mid 356.778171 -223.862479)
		(end 356.856284 -223.585532)
		(width 0.0889)
		(layer "B.Cu")
		(net "PD_EXT_CLK_SEL_CPU0")
	)
	(arc
		(start 355.163882 -220.644212)
		(mid 355.028949 -220.510858)
		(end 354.976684 -220.32849)
		(width 0.0889)
		(layer "B.Cu")
		(net "PD_EXT_CLK_SEL_CPU0")
	)
	(arc
		(start 335.889092 -216.569798)
		(mid 335.758178 -216.433438)
		(end 335.71053 -216.25052)
		(width 0.0889)
		(layer "B.Cu")
		(net "PD_EXT_CLK_SEL_CPU0")
	)
	(arc
		(start 338.621878 -219.01658)
		(mid 338.43468 -219.066723)
		(end 338.247482 -219.01658)
		(width 0.0889)
		(layer "B.Cu")
		(net "PD_EXT_CLK_SEL_CPU0")
	)
	(arc
		(start 361.085384 -230.884984)
		(mid 361.006014 -230.61125)
		(end 360.80319 -230.41102)
		(width 0.0889)
		(layer "B.Cu")
		(net "PD_EXT_CLK_SEL_CPU0")
	)
	(arc
		(start 341.441278 -219.01658)
		(mid 341.25408 -219.066723)
		(end 341.066882 -219.01658)
		(width 0.0889)
		(layer "B.Cu")
		(net "PD_EXT_CLK_SEL_CPU0")
	)
	(arc
		(start 353.189032 -219.830396)
		(mid 353.001834 -219.880539)
		(end 352.814636 -219.830396)
		(width 0.0889)
		(layer "B.Cu")
		(net "PD_EXT_CLK_SEL_CPU0")
	)
	(arc
		(start 350.839278 -219.01658)
		(mid 350.65208 -219.066723)
		(end 350.464882 -219.01658)
		(width 0.0889)
		(layer "B.Cu")
		(net "PD_EXT_CLK_SEL_CPU0")
	)
	(arc
		(start 354.976684 -220.309948)
		(mid 354.898573 -220.032999)
		(end 354.694236 -219.830396)
		(width 0.0889)
		(layer "B.Cu")
		(net "PD_EXT_CLK_SEL_CPU0")
	)
	(arc
		(start 336.18043 -217.05443)
		(mid 336.102319 -216.777481)
		(end 335.897982 -216.574878)
		(width 0.0889)
		(layer "B.Cu")
		(net "PD_EXT_CLK_SEL_CPU0")
	)
	(arc
		(start 356.856284 -223.557084)
		(mid 356.776122 -223.284895)
		(end 356.573836 -223.085914)
		(width 0.0889)
		(layer "B.Cu")
		(net "PD_EXT_CLK_SEL_CPU0")
	)
	(arc
		(start 355.625146 -221.453202)
		(mid 355.494232 -221.316842)
		(end 355.446584 -221.133924)
		(width 0.0889)
		(layer "B.Cu")
		(net "PD_EXT_CLK_SEL_CPU0")
	)
	(arc
		(start 342.381078 -219.01658)
		(mid 342.19388 -219.066723)
		(end 342.006682 -219.01658)
		(width 0.0889)
		(layer "B.Cu")
		(net "PD_EXT_CLK_SEL_CPU0")
	)
	(arc
		(start 357.504746 -226.336606)
		(mid 357.373832 -226.200246)
		(end 357.326184 -226.017328)
		(width 0.0889)
		(layer "B.Cu")
		(net "PD_EXT_CLK_SEL_CPU0")
	)
	(arc
		(start 337.120484 -218.682316)
		(mid 337.042373 -218.405367)
		(end 336.838036 -218.202764)
		(width 0.0889)
		(layer "B.Cu")
		(net "PD_EXT_CLK_SEL_CPU0")
	)
	(arc
		(start 358.735884 -228.444806)
		(mid 358.656743 -228.170183)
		(end 358.453436 -227.969318)
		(width 0.0889)
		(layer "B.Cu")
		(net "PD_EXT_CLK_SEL_CPU0")
	)
	(arc
		(start 352.805746 -219.825316)
		(mid 352.674832 -219.688956)
		(end 352.627184 -219.506038)
		(width 0.0889)
		(layer "B.Cu")
		(net "PD_EXT_CLK_SEL_CPU0")
	)
	(arc
		(start 356.386384 -222.761556)
		(mid 356.312393 -222.48199)
		(end 356.109778 -222.275654)
		(width 0.0889)
		(layer "B.Cu")
		(net "PD_EXT_CLK_SEL_CPU0")
	)
	(arc
		(start 356.094792 -222.267018)
		(mid 355.963878 -222.130658)
		(end 355.91623 -221.94774)
		(width 0.0889)
		(layer "B.Cu")
		(net "PD_EXT_CLK_SEL_CPU0")
	)
	(arc
		(start 345.200478 -219.01658)
		(mid 345.01328 -219.066723)
		(end 344.826082 -219.01658)
		(width 0.0889)
		(layer "B.Cu")
		(net "PD_EXT_CLK_SEL_CPU0")
	)
	(segment
		(start 234.284266 -124.517912)
		(end 234.247944 -124.517912)
		(width 0.12954)
		(layer "F.Cu")
		(net "PD_DB2000_SMB_SA1")
	)
	(segment
		(start 234.854242 -124.992638)
		(end 234.758992 -124.992638)
		(width 0.12954)
		(layer "F.Cu")
		(net "PD_DB2000_SMB_SA1")
	)
	(segment
		(start 234.758992 -124.992638)
		(end 234.284266 -124.517912)
		(width 0.12954)
		(layer "F.Cu")
		(net "PD_DB2000_SMB_SA1")
	)
	(via
		(at 244.944138 -127.320548)
		(size 0.762)
		(drill 0.254)
		(layers "F.Cu" "B.Cu")
		(net "PD_DB2000_SMB_SA1")
	)
	(via
		(at 234.854242 -124.992638)
		(size 0.49022)
		(drill 0.254)
		(layers "F.Cu" "B.Cu")
		(net "PD_DB2000_SMB_SA1")
	)
	(segment
		(start 244.944138 -127.320548)
		(end 244.944138 -127.943864)
		(width 0.12954)
		(layer "B.Cu")
		(net "PD_DB2000_SMB_SA1")
	)
	(segment
		(start 244.936772 -127.936498)
		(end 244.944138 -127.943864)
		(width 0.12954)
		(layer "B.Cu")
		(net "PD_DB2000_SMB_SA1")
	)
	(segment
		(start 243.99748 -127.936498)
		(end 244.936772 -127.936498)
		(width 0.12954)
		(layer "B.Cu")
		(net "PD_DB2000_SMB_SA1")
	)
	(segment
		(start 234.854242 -125.94971)
		(end 234.854242 -124.992638)
		(width 0.127)
		(layer "In6.Cu")
		(net "PD_DB2000_SMB_SA1")
	)
	(segment
		(start 237.34268 -126.253748)
		(end 235.15828 -126.253748)
		(width 0.127)
		(layer "In6.Cu")
		(net "PD_DB2000_SMB_SA1")
	)
	(segment
		(start 235.15828 -126.253748)
		(end 234.854242 -125.94971)
		(width 0.127)
		(layer "In6.Cu")
		(net "PD_DB2000_SMB_SA1")
	)
	(segment
		(start 244.944138 -127.320548)
		(end 244.944138 -126.11862)
		(width 0.127)
		(layer "In6.Cu")
		(net "PD_DB2000_SMB_SA1")
	)
	(segment
		(start 238.31296 -125.283468)
		(end 237.34268 -126.253748)
		(width 0.127)
		(layer "In6.Cu")
		(net "PD_DB2000_SMB_SA1")
	)
	(segment
		(start 244.944138 -126.11862)
		(end 244.108986 -125.283468)
		(width 0.127)
		(layer "In6.Cu")
		(net "PD_DB2000_SMB_SA1")
	)
	(segment
		(start 244.108986 -125.283468)
		(end 238.31296 -125.283468)
		(width 0.127)
		(layer "In6.Cu")
		(net "PD_DB2000_SMB_SA1")
	)
	(segment
		(start 236.24794 -124.878338)
		(end 236.24794 -124.517912)
		(width 0.12954)
		(layer "F.Cu")
		(net "PD_DB2000_SMB_SA0")
	)
	(segment
		(start 236.132116 -124.994162)
		(end 236.24794 -124.878338)
		(width 0.12954)
		(layer "F.Cu")
		(net "PD_DB2000_SMB_SA0")
	)
	(via
		(at 246.580152 -127.31242)
		(size 0.762)
		(drill 0.254)
		(layers "F.Cu" "B.Cu")
		(net "PD_DB2000_SMB_SA0")
	)
	(via
		(at 236.132116 -124.994162)
		(size 0.49022)
		(drill 0.254)
		(layers "F.Cu" "B.Cu")
		(net "PD_DB2000_SMB_SA0")
	)
	(segment
		(start 246.580152 -127.31242)
		(end 245.96217 -127.930402)
		(width 0.12954)
		(layer "B.Cu")
		(net "PD_DB2000_SMB_SA0")
	)
	(segment
		(start 246.984266 -127.943864)
		(end 246.970804 -127.930402)
		(width 0.12954)
		(layer "B.Cu")
		(net "PD_DB2000_SMB_SA0")
	)
	(segment
		(start 246.970804 -127.930402)
		(end 245.96217 -127.930402)
		(width 0.12954)
		(layer "B.Cu")
		(net "PD_DB2000_SMB_SA0")
	)
	(segment
		(start 236.132116 -124.746512)
		(end 236.132116 -124.994162)
		(width 0.127)
		(layer "In6.Cu")
		(net "PD_DB2000_SMB_SA0")
	)
	(segment
		(start 246.580152 -126.96444)
		(end 243.32565 -123.709938)
		(width 0.127)
		(layer "In6.Cu")
		(net "PD_DB2000_SMB_SA0")
	)
	(segment
		(start 237.16869 -123.709938)
		(end 236.132116 -124.746512)
		(width 0.127)
		(layer "In6.Cu")
		(net "PD_DB2000_SMB_SA0")
	)
	(segment
		(start 246.580152 -127.31242)
		(end 246.580152 -126.96444)
		(width 0.127)
		(layer "In6.Cu")
		(net "PD_DB2000_SMB_SA0")
	)
	(segment
		(start 243.32565 -123.709938)
		(end 237.16869 -123.709938)
		(width 0.127)
		(layer "In6.Cu")
		(net "PD_DB2000_SMB_SA0")
	)
	(segment
		(start 120.098312 -229.808786)
		(end 120.098566 -229.808532)
		(width 0.12954)
		(layer "F.Cu")
		(net "PD_CPU1_TXT_PLTEN")
	)
	(segment
		(start 120.098566 -229.808532)
		(end 120.098566 -229.272846)
		(width 0.12954)
		(layer "F.Cu")
		(net "PD_CPU1_TXT_PLTEN")
	)
	(via
		(at 120.098566 -229.272846)
		(size 0.4572)
		(drill 0.2032)
		(layers "F.Cu" "B.Cu")
		(net "PD_CPU1_TXT_PLTEN")
	)
	(via
		(at 146.715988 -227.800916)
		(size 0.6604)
		(drill 0.3302)
		(layers "F.Cu" "B.Cu")
		(net "PD_CPU1_TXT_PLTEN")
	)
	(segment
		(start 121.320814 -229.762304)
		(end 121.306082 -229.77094)
		(width 0.0889)
		(layer "B.Cu")
		(net "PD_CPU1_TXT_PLTEN")
	)
	(segment
		(start 127.899414 -229.762304)
		(end 127.884682 -229.77094)
		(width 0.0889)
		(layer "B.Cu")
		(net "PD_CPU1_TXT_PLTEN")
	)
	(segment
		(start 120.476772 -229.338378)
		(end 120.41124 -229.272846)
		(width 0.0889)
		(layer "B.Cu")
		(net "PD_CPU1_TXT_PLTEN")
	)
	(segment
		(start 143.831818 -229.64775)
		(end 136.695434 -229.64775)
		(width 0.12954)
		(layer "B.Cu")
		(net "PD_CPU1_TXT_PLTEN")
	)
	(segment
		(start 152.87244 -221.644464)
		(end 146.715988 -227.800916)
		(width 0.12954)
		(layer "B.Cu")
		(net "PD_CPU1_TXT_PLTEN")
	)
	(segment
		(start 156.02458 -196.202808)
		(end 154.52598 -196.202808)
		(width 0.12954)
		(layer "B.Cu")
		(net "PD_CPU1_TXT_PLTEN")
	)
	(segment
		(start 150.99792 -187.020708)
		(end 157.1498 -187.020708)
		(width 0.12954)
		(layer "B.Cu")
		(net "PD_CPU1_TXT_PLTEN")
	)
	(segment
		(start 126.959614 -229.762304)
		(end 126.944882 -229.77094)
		(width 0.0889)
		(layer "B.Cu")
		(net "PD_CPU1_TXT_PLTEN")
	)
	(segment
		(start 157.20314 -191.046608)
		(end 158.3182 -192.161668)
		(width 0.12954)
		(layer "B.Cu")
		(net "PD_CPU1_TXT_PLTEN")
	)
	(segment
		(start 122.260614 -229.762304)
		(end 122.245882 -229.77094)
		(width 0.0889)
		(layer "B.Cu")
		(net "PD_CPU1_TXT_PLTEN")
	)
	(segment
		(start 157.20314 -188.900308)
		(end 157.20314 -191.046608)
		(width 0.12954)
		(layer "B.Cu")
		(net "PD_CPU1_TXT_PLTEN")
	)
	(segment
		(start 128.839214 -229.762304)
		(end 128.824482 -229.77094)
		(width 0.0889)
		(layer "B.Cu")
		(net "PD_CPU1_TXT_PLTEN")
	)
	(segment
		(start 145.678652 -227.800916)
		(end 143.831818 -229.64775)
		(width 0.12954)
		(layer "B.Cu")
		(net "PD_CPU1_TXT_PLTEN")
	)
	(segment
		(start 150.659338 -187.35929)
		(end 150.99792 -187.020708)
		(width 0.12954)
		(layer "B.Cu")
		(net "PD_CPU1_TXT_PLTEN")
	)
	(segment
		(start 124.140214 -229.762304)
		(end 124.125482 -229.77094)
		(width 0.0889)
		(layer "B.Cu")
		(net "PD_CPU1_TXT_PLTEN")
	)
	(segment
		(start 149.678898 -188.21019)
		(end 150.651718 -188.21019)
		(width 0.12954)
		(layer "B.Cu")
		(net "PD_CPU1_TXT_PLTEN")
	)
	(segment
		(start 146.715988 -227.800916)
		(end 145.678652 -227.800916)
		(width 0.12954)
		(layer "B.Cu")
		(net "PD_CPU1_TXT_PLTEN")
	)
	(segment
		(start 158.3182 -192.161668)
		(end 158.3182 -193.909188)
		(width 0.12954)
		(layer "B.Cu")
		(net "PD_CPU1_TXT_PLTEN")
	)
	(segment
		(start 126.019814 -229.762304)
		(end 126.0094 -229.7684)
		(width 0.0889)
		(layer "B.Cu")
		(net "PD_CPU1_TXT_PLTEN")
	)
	(segment
		(start 157.1498 -187.020708)
		(end 157.69082 -187.561728)
		(width 0.12954)
		(layer "B.Cu")
		(net "PD_CPU1_TXT_PLTEN")
	)
	(segment
		(start 152.87244 -197.856348)
		(end 152.87244 -221.644464)
		(width 0.12954)
		(layer "B.Cu")
		(net "PD_CPU1_TXT_PLTEN")
	)
	(segment
		(start 120.41124 -229.272846)
		(end 120.098566 -229.272846)
		(width 0.0889)
		(layer "B.Cu")
		(net "PD_CPU1_TXT_PLTEN")
	)
	(segment
		(start 131.658868 -229.762304)
		(end 131.648454 -229.7684)
		(width 0.0889)
		(layer "B.Cu")
		(net "PD_CPU1_TXT_PLTEN")
	)
	(segment
		(start 130.718814 -229.762304)
		(end 130.704082 -229.77094)
		(width 0.0889)
		(layer "B.Cu")
		(net "PD_CPU1_TXT_PLTEN")
	)
	(segment
		(start 157.69082 -188.412628)
		(end 157.20314 -188.900308)
		(width 0.12954)
		(layer "B.Cu")
		(net "PD_CPU1_TXT_PLTEN")
	)
	(segment
		(start 154.52598 -196.202808)
		(end 152.87244 -197.856348)
		(width 0.12954)
		(layer "B.Cu")
		(net "PD_CPU1_TXT_PLTEN")
	)
	(segment
		(start 132.598414 -229.762304)
		(end 132.588 -229.7684)
		(width 0.0889)
		(layer "B.Cu")
		(net "PD_CPU1_TXT_PLTEN")
	)
	(segment
		(start 133.538468 -229.762304)
		(end 133.528054 -229.7684)
		(width 0.0889)
		(layer "B.Cu")
		(net "PD_CPU1_TXT_PLTEN")
	)
	(segment
		(start 158.3182 -193.909188)
		(end 156.02458 -196.202808)
		(width 0.12954)
		(layer "B.Cu")
		(net "PD_CPU1_TXT_PLTEN")
	)
	(segment
		(start 125.080268 -229.762304)
		(end 125.069854 -229.7684)
		(width 0.0889)
		(layer "B.Cu")
		(net "PD_CPU1_TXT_PLTEN")
	)
	(segment
		(start 150.659338 -188.20257)
		(end 150.659338 -187.35929)
		(width 0.12954)
		(layer "B.Cu")
		(net "PD_CPU1_TXT_PLTEN")
	)
	(segment
		(start 150.651718 -188.21019)
		(end 150.659338 -188.20257)
		(width 0.12954)
		(layer "B.Cu")
		(net "PD_CPU1_TXT_PLTEN")
	)
	(segment
		(start 157.69082 -187.561728)
		(end 157.69082 -188.412628)
		(width 0.12954)
		(layer "B.Cu")
		(net "PD_CPU1_TXT_PLTEN")
	)
	(arc
		(start 134.852664 -229.762304)
		(mid 134.665466 -229.712161)
		(end 134.478268 -229.762304)
		(width 0.0889)
		(layer "B.Cu")
		(net "PD_CPU1_TXT_PLTEN")
	)
	(arc
		(start 129.21361 -229.762304)
		(mid 129.026412 -229.712161)
		(end 128.839214 -229.762304)
		(width 0.0889)
		(layer "B.Cu")
		(net "PD_CPU1_TXT_PLTEN")
	)
	(arc
		(start 131.09321 -229.762304)
		(mid 130.906012 -229.712161)
		(end 130.718814 -229.762304)
		(width 0.0889)
		(layer "B.Cu")
		(net "PD_CPU1_TXT_PLTEN")
	)
	(arc
		(start 125.454664 -229.762304)
		(mid 125.267466 -229.712161)
		(end 125.080268 -229.762304)
		(width 0.0889)
		(layer "B.Cu")
		(net "PD_CPU1_TXT_PLTEN")
	)
	(arc
		(start 132.033264 -229.762304)
		(mid 131.846066 -229.712161)
		(end 131.658868 -229.762304)
		(width 0.0889)
		(layer "B.Cu")
		(net "PD_CPU1_TXT_PLTEN")
	)
	(arc
		(start 128.824482 -229.77094)
		(mid 128.548007 -229.83826)
		(end 128.27381 -229.762304)
		(width 0.0889)
		(layer "B.Cu")
		(net "PD_CPU1_TXT_PLTEN")
	)
	(arc
		(start 130.15341 -229.762304)
		(mid 129.966212 -229.712161)
		(end 129.779014 -229.762304)
		(width 0.0889)
		(layer "B.Cu")
		(net "PD_CPU1_TXT_PLTEN")
	)
	(arc
		(start 132.588 -229.7684)
		(mid 132.309822 -229.838123)
		(end 132.033264 -229.762304)
		(width 0.0889)
		(layer "B.Cu")
		(net "PD_CPU1_TXT_PLTEN")
	)
	(arc
		(start 123.200414 -229.762304)
		(mid 122.917712 -229.83808)
		(end 122.63501 -229.762304)
		(width 0.0889)
		(layer "B.Cu")
		(net "PD_CPU1_TXT_PLTEN")
	)
	(arc
		(start 129.779014 -229.762304)
		(mid 129.496312 -229.83808)
		(end 129.21361 -229.762304)
		(width 0.0889)
		(layer "B.Cu")
		(net "PD_CPU1_TXT_PLTEN")
	)
	(arc
		(start 134.478268 -229.762304)
		(mid 134.195566 -229.83808)
		(end 133.912864 -229.762304)
		(width 0.0889)
		(layer "B.Cu")
		(net "PD_CPU1_TXT_PLTEN")
	)
	(arc
		(start 126.0094 -229.7684)
		(mid 125.731222 -229.838123)
		(end 125.454664 -229.762304)
		(width 0.0889)
		(layer "B.Cu")
		(net "PD_CPU1_TXT_PLTEN")
	)
	(arc
		(start 132.97281 -229.762304)
		(mid 132.785612 -229.712161)
		(end 132.598414 -229.762304)
		(width 0.0889)
		(layer "B.Cu")
		(net "PD_CPU1_TXT_PLTEN")
	)
	(arc
		(start 122.63501 -229.762304)
		(mid 122.447812 -229.712161)
		(end 122.260614 -229.762304)
		(width 0.0889)
		(layer "B.Cu")
		(net "PD_CPU1_TXT_PLTEN")
	)
	(arc
		(start 133.528054 -229.7684)
		(mid 133.249622 -229.838246)
		(end 132.97281 -229.762304)
		(width 0.0889)
		(layer "B.Cu")
		(net "PD_CPU1_TXT_PLTEN")
	)
	(arc
		(start 135.418068 -229.762304)
		(mid 135.135366 -229.83808)
		(end 134.852664 -229.762304)
		(width 0.0889)
		(layer "B.Cu")
		(net "PD_CPU1_TXT_PLTEN")
	)
	(arc
		(start 131.648454 -229.7684)
		(mid 131.370022 -229.838246)
		(end 131.09321 -229.762304)
		(width 0.0889)
		(layer "B.Cu")
		(net "PD_CPU1_TXT_PLTEN")
	)
	(arc
		(start 136.40816 -229.731824)
		(mid 136.383201 -229.747372)
		(end 136.357868 -229.762304)
		(width 0.0889)
		(layer "B.Cu")
		(net "PD_CPU1_TXT_PLTEN")
	)
	(arc
		(start 135.792464 -229.762304)
		(mid 135.605266 -229.712161)
		(end 135.418068 -229.762304)
		(width 0.0889)
		(layer "B.Cu")
		(net "PD_CPU1_TXT_PLTEN")
	)
	(arc
		(start 136.695434 -229.64775)
		(mid 136.545765 -229.669189)
		(end 136.40816 -229.731824)
		(width 0.0889)
		(layer "B.Cu")
		(net "PD_CPU1_TXT_PLTEN")
	)
	(arc
		(start 121.306082 -229.77094)
		(mid 121.029607 -229.83826)
		(end 120.75541 -229.762304)
		(width 0.0889)
		(layer "B.Cu")
		(net "PD_CPU1_TXT_PLTEN")
	)
	(arc
		(start 136.357868 -229.762304)
		(mid 136.075166 -229.83808)
		(end 135.792464 -229.762304)
		(width 0.0889)
		(layer "B.Cu")
		(net "PD_CPU1_TXT_PLTEN")
	)
	(arc
		(start 120.75541 -229.762304)
		(mid 120.565897 -229.583339)
		(end 120.476772 -229.338378)
		(width 0.0889)
		(layer "B.Cu")
		(net "PD_CPU1_TXT_PLTEN")
	)
	(arc
		(start 127.884682 -229.77094)
		(mid 127.608207 -229.83826)
		(end 127.33401 -229.762304)
		(width 0.0889)
		(layer "B.Cu")
		(net "PD_CPU1_TXT_PLTEN")
	)
	(arc
		(start 124.51461 -229.762304)
		(mid 124.327412 -229.712161)
		(end 124.140214 -229.762304)
		(width 0.0889)
		(layer "B.Cu")
		(net "PD_CPU1_TXT_PLTEN")
	)
	(arc
		(start 125.069854 -229.7684)
		(mid 124.791422 -229.838246)
		(end 124.51461 -229.762304)
		(width 0.0889)
		(layer "B.Cu")
		(net "PD_CPU1_TXT_PLTEN")
	)
	(arc
		(start 122.245882 -229.77094)
		(mid 121.969407 -229.83826)
		(end 121.69521 -229.762304)
		(width 0.0889)
		(layer "B.Cu")
		(net "PD_CPU1_TXT_PLTEN")
	)
	(arc
		(start 126.39421 -229.762304)
		(mid 126.207012 -229.712161)
		(end 126.019814 -229.762304)
		(width 0.0889)
		(layer "B.Cu")
		(net "PD_CPU1_TXT_PLTEN")
	)
	(arc
		(start 124.125482 -229.77094)
		(mid 123.849007 -229.83826)
		(end 123.57481 -229.762304)
		(width 0.0889)
		(layer "B.Cu")
		(net "PD_CPU1_TXT_PLTEN")
	)
	(arc
		(start 126.944882 -229.77094)
		(mid 126.668407 -229.83826)
		(end 126.39421 -229.762304)
		(width 0.0889)
		(layer "B.Cu")
		(net "PD_CPU1_TXT_PLTEN")
	)
	(arc
		(start 127.33401 -229.762304)
		(mid 127.146812 -229.712161)
		(end 126.959614 -229.762304)
		(width 0.0889)
		(layer "B.Cu")
		(net "PD_CPU1_TXT_PLTEN")
	)
	(arc
		(start 133.912864 -229.762304)
		(mid 133.725666 -229.712161)
		(end 133.538468 -229.762304)
		(width 0.0889)
		(layer "B.Cu")
		(net "PD_CPU1_TXT_PLTEN")
	)
	(arc
		(start 128.27381 -229.762304)
		(mid 128.086612 -229.712161)
		(end 127.899414 -229.762304)
		(width 0.0889)
		(layer "B.Cu")
		(net "PD_CPU1_TXT_PLTEN")
	)
	(arc
		(start 121.69521 -229.762304)
		(mid 121.508012 -229.712161)
		(end 121.320814 -229.762304)
		(width 0.0889)
		(layer "B.Cu")
		(net "PD_CPU1_TXT_PLTEN")
	)
	(arc
		(start 123.57481 -229.762304)
		(mid 123.387612 -229.712161)
		(end 123.200414 -229.762304)
		(width 0.0889)
		(layer "B.Cu")
		(net "PD_CPU1_TXT_PLTEN")
	)
	(arc
		(start 130.704082 -229.77094)
		(mid 130.427607 -229.83826)
		(end 130.15341 -229.762304)
		(width 0.0889)
		(layer "B.Cu")
		(net "PD_CPU1_TXT_PLTEN")
	)
	(segment
		(start 122.558048 -257.45313)
		(end 122.557794 -257.98907)
		(width 0.12954)
		(layer "F.Cu")
		(net "PD_CPU1_PROCDIS_COD_GTL_N")
	)
	(via
		(at 139.490958 -256.77495)
		(size 0.6604)
		(drill 0.3302)
		(layers "F.Cu" "B.Cu")
		(net "PD_CPU1_PROCDIS_COD_GTL_N")
	)
	(via
		(at 122.557794 -257.98907)
		(size 0.4572)
		(drill 0.2032)
		(layers "F.Cu" "B.Cu")
		(net "PD_CPU1_PROCDIS_COD_GTL_N")
	)
	(segment
		(start 134.526528 -257.590036)
		(end 134.53999 -257.582162)
		(width 0.12954)
		(layer "B.Cu")
		(net "PD_CPU1_PROCDIS_COD_GTL_N")
	)
	(segment
		(start 132.646928 -257.590036)
		(end 132.66039 -257.582162)
		(width 0.12954)
		(layer "B.Cu")
		(net "PD_CPU1_PROCDIS_COD_GTL_N")
	)
	(segment
		(start 126.068328 -257.590036)
		(end 126.08179 -257.582162)
		(width 0.12954)
		(layer "B.Cu")
		(net "PD_CPU1_PROCDIS_COD_GTL_N")
	)
	(segment
		(start 135.466328 -257.590036)
		(end 135.47979 -257.582162)
		(width 0.12954)
		(layer "B.Cu")
		(net "PD_CPU1_PROCDIS_COD_GTL_N")
	)
	(segment
		(start 131.707128 -257.590036)
		(end 131.72059 -257.582162)
		(width 0.12954)
		(layer "B.Cu")
		(net "PD_CPU1_PROCDIS_COD_GTL_N")
	)
	(segment
		(start 156.845762 -245.89359)
		(end 160.339278 -245.89359)
		(width 0.12954)
		(layer "B.Cu")
		(net "PD_CPU1_PROCDIS_COD_GTL_N")
	)
	(segment
		(start 138.695684 -257.570224)
		(end 139.490958 -256.77495)
		(width 0.12954)
		(layer "B.Cu")
		(net "PD_CPU1_PROCDIS_COD_GTL_N")
	)
	(segment
		(start 139.490958 -256.77495)
		(end 145.964402 -256.77495)
		(width 0.12954)
		(layer "B.Cu")
		(net "PD_CPU1_PROCDIS_COD_GTL_N")
	)
	(segment
		(start 164.583364 -245.04523)
		(end 165.901116 -246.362982)
		(width 0.12954)
		(layer "B.Cu")
		(net "PD_CPU1_PROCDIS_COD_GTL_N")
	)
	(segment
		(start 133.586728 -257.590036)
		(end 133.60019 -257.582162)
		(width 0.12954)
		(layer "B.Cu")
		(net "PD_CPU1_PROCDIS_COD_GTL_N")
	)
	(segment
		(start 136.020302 -257.570224)
		(end 138.695684 -257.570224)
		(width 0.12954)
		(layer "B.Cu")
		(net "PD_CPU1_PROCDIS_COD_GTL_N")
	)
	(segment
		(start 161.187638 -245.04523)
		(end 164.583364 -245.04523)
		(width 0.12954)
		(layer "B.Cu")
		(net "PD_CPU1_PROCDIS_COD_GTL_N")
	)
	(segment
		(start 124.188728 -257.590036)
		(end 124.20219 -257.582162)
		(width 0.12954)
		(layer "B.Cu")
		(net "PD_CPU1_PROCDIS_COD_GTL_N")
	)
	(segment
		(start 165.901116 -246.362982)
		(end 165.901116 -247.250712)
		(width 0.12954)
		(layer "B.Cu")
		(net "PD_CPU1_PROCDIS_COD_GTL_N")
	)
	(segment
		(start 127.947928 -257.590036)
		(end 127.96139 -257.582162)
		(width 0.12954)
		(layer "B.Cu")
		(net "PD_CPU1_PROCDIS_COD_GTL_N")
	)
	(segment
		(start 127.008128 -257.590036)
		(end 127.02159 -257.582162)
		(width 0.12954)
		(layer "B.Cu")
		(net "PD_CPU1_PROCDIS_COD_GTL_N")
	)
	(segment
		(start 160.339278 -245.89359)
		(end 161.187638 -245.04523)
		(width 0.12954)
		(layer "B.Cu")
		(net "PD_CPU1_PROCDIS_COD_GTL_N")
	)
	(segment
		(start 130.767328 -257.590036)
		(end 130.78079 -257.582162)
		(width 0.12954)
		(layer "B.Cu")
		(net "PD_CPU1_PROCDIS_COD_GTL_N")
	)
	(segment
		(start 125.128528 -257.590036)
		(end 125.14199 -257.582162)
		(width 0.12954)
		(layer "B.Cu")
		(net "PD_CPU1_PROCDIS_COD_GTL_N")
	)
	(segment
		(start 129.827528 -257.590036)
		(end 129.84099 -257.582162)
		(width 0.12954)
		(layer "B.Cu")
		(net "PD_CPU1_PROCDIS_COD_GTL_N")
	)
	(segment
		(start 145.964402 -256.77495)
		(end 156.845762 -245.89359)
		(width 0.12954)
		(layer "B.Cu")
		(net "PD_CPU1_PROCDIS_COD_GTL_N")
	)
	(segment
		(start 128.887728 -257.590036)
		(end 128.90119 -257.582162)
		(width 0.12954)
		(layer "B.Cu")
		(net "PD_CPU1_PROCDIS_COD_GTL_N")
	)
	(arc
		(start 133.13029 -257.582162)
		(mid 133.357477 -257.64518)
		(end 133.586728 -257.590036)
		(width 0.12954)
		(layer "B.Cu")
		(net "PD_CPU1_PROCDIS_COD_GTL_N")
	)
	(arc
		(start 135.47979 -257.582162)
		(mid 135.66964 -257.521269)
		(end 135.867648 -257.54457)
		(width 0.12954)
		(layer "B.Cu")
		(net "PD_CPU1_PROCDIS_COD_GTL_N")
	)
	(arc
		(start 133.60019 -257.582162)
		(mid 133.83514 -257.519202)
		(end 134.07009 -257.582162)
		(width 0.12954)
		(layer "B.Cu")
		(net "PD_CPU1_PROCDIS_COD_GTL_N")
	)
	(arc
		(start 127.49149 -257.582162)
		(mid 127.718677 -257.64518)
		(end 127.947928 -257.590036)
		(width 0.12954)
		(layer "B.Cu")
		(net "PD_CPU1_PROCDIS_COD_GTL_N")
	)
	(arc
		(start 124.20219 -257.582162)
		(mid 124.43714 -257.519202)
		(end 124.67209 -257.582162)
		(width 0.12954)
		(layer "B.Cu")
		(net "PD_CPU1_PROCDIS_COD_GTL_N")
	)
	(arc
		(start 130.78079 -257.582162)
		(mid 131.01574 -257.519202)
		(end 131.25069 -257.582162)
		(width 0.12954)
		(layer "B.Cu")
		(net "PD_CPU1_PROCDIS_COD_GTL_N")
	)
	(arc
		(start 129.37109 -257.582162)
		(mid 129.598277 -257.64518)
		(end 129.827528 -257.590036)
		(width 0.12954)
		(layer "B.Cu")
		(net "PD_CPU1_PROCDIS_COD_GTL_N")
	)
	(arc
		(start 128.43129 -257.582162)
		(mid 128.658477 -257.64518)
		(end 128.887728 -257.590036)
		(width 0.12954)
		(layer "B.Cu")
		(net "PD_CPU1_PROCDIS_COD_GTL_N")
	)
	(arc
		(start 123.207272 -257.659124)
		(mid 123.456397 -257.529293)
		(end 123.73229 -257.582162)
		(width 0.12954)
		(layer "B.Cu")
		(net "PD_CPU1_PROCDIS_COD_GTL_N")
	)
	(arc
		(start 124.67209 -257.582162)
		(mid 124.899277 -257.64518)
		(end 125.128528 -257.590036)
		(width 0.12954)
		(layer "B.Cu")
		(net "PD_CPU1_PROCDIS_COD_GTL_N")
	)
	(arc
		(start 128.90119 -257.582162)
		(mid 129.13614 -257.519202)
		(end 129.37109 -257.582162)
		(width 0.12954)
		(layer "B.Cu")
		(net "PD_CPU1_PROCDIS_COD_GTL_N")
	)
	(arc
		(start 125.61189 -257.582162)
		(mid 125.839077 -257.64518)
		(end 126.068328 -257.590036)
		(width 0.12954)
		(layer "B.Cu")
		(net "PD_CPU1_PROCDIS_COD_GTL_N")
	)
	(arc
		(start 127.02159 -257.582162)
		(mid 127.25654 -257.519202)
		(end 127.49149 -257.582162)
		(width 0.12954)
		(layer "B.Cu")
		(net "PD_CPU1_PROCDIS_COD_GTL_N")
	)
	(arc
		(start 130.31089 -257.582162)
		(mid 130.538077 -257.64518)
		(end 130.767328 -257.590036)
		(width 0.12954)
		(layer "B.Cu")
		(net "PD_CPU1_PROCDIS_COD_GTL_N")
	)
	(arc
		(start 134.07009 -257.582162)
		(mid 134.297277 -257.64518)
		(end 134.526528 -257.590036)
		(width 0.12954)
		(layer "B.Cu")
		(net "PD_CPU1_PROCDIS_COD_GTL_N")
	)
	(arc
		(start 127.96139 -257.582162)
		(mid 128.19634 -257.519202)
		(end 128.43129 -257.582162)
		(width 0.12954)
		(layer "B.Cu")
		(net "PD_CPU1_PROCDIS_COD_GTL_N")
	)
	(arc
		(start 126.08179 -257.582162)
		(mid 126.31674 -257.519202)
		(end 126.55169 -257.582162)
		(width 0.12954)
		(layer "B.Cu")
		(net "PD_CPU1_PROCDIS_COD_GTL_N")
	)
	(arc
		(start 132.66039 -257.582162)
		(mid 132.89534 -257.519202)
		(end 133.13029 -257.582162)
		(width 0.12954)
		(layer "B.Cu")
		(net "PD_CPU1_PROCDIS_COD_GTL_N")
	)
	(arc
		(start 122.557794 -257.98907)
		(mid 122.91128 -257.880691)
		(end 123.207272 -257.659124)
		(width 0.12954)
		(layer "B.Cu")
		(net "PD_CPU1_PROCDIS_COD_GTL_N")
	)
	(arc
		(start 134.53999 -257.582162)
		(mid 134.77494 -257.519202)
		(end 135.00989 -257.582162)
		(width 0.12954)
		(layer "B.Cu")
		(net "PD_CPU1_PROCDIS_COD_GTL_N")
	)
	(arc
		(start 123.73229 -257.582162)
		(mid 123.959477 -257.64518)
		(end 124.188728 -257.590036)
		(width 0.12954)
		(layer "B.Cu")
		(net "PD_CPU1_PROCDIS_COD_GTL_N")
	)
	(arc
		(start 132.19049 -257.582162)
		(mid 132.417677 -257.64518)
		(end 132.646928 -257.590036)
		(width 0.12954)
		(layer "B.Cu")
		(net "PD_CPU1_PROCDIS_COD_GTL_N")
	)
	(arc
		(start 131.72059 -257.582162)
		(mid 131.95554 -257.519202)
		(end 132.19049 -257.582162)
		(width 0.12954)
		(layer "B.Cu")
		(net "PD_CPU1_PROCDIS_COD_GTL_N")
	)
	(arc
		(start 135.867648 -257.54457)
		(mid 135.942911 -257.56373)
		(end 136.020302 -257.570224)
		(width 0.12954)
		(layer "B.Cu")
		(net "PD_CPU1_PROCDIS_COD_GTL_N")
	)
	(arc
		(start 131.25069 -257.582162)
		(mid 131.477877 -257.64518)
		(end 131.707128 -257.590036)
		(width 0.12954)
		(layer "B.Cu")
		(net "PD_CPU1_PROCDIS_COD_GTL_N")
	)
	(arc
		(start 129.84099 -257.582162)
		(mid 130.07594 -257.519202)
		(end 130.31089 -257.582162)
		(width 0.12954)
		(layer "B.Cu")
		(net "PD_CPU1_PROCDIS_COD_GTL_N")
	)
	(arc
		(start 126.55169 -257.582162)
		(mid 126.778877 -257.64518)
		(end 127.008128 -257.590036)
		(width 0.12954)
		(layer "B.Cu")
		(net "PD_CPU1_PROCDIS_COD_GTL_N")
	)
	(arc
		(start 125.14199 -257.582162)
		(mid 125.37694 -257.519202)
		(end 125.61189 -257.582162)
		(width 0.12954)
		(layer "B.Cu")
		(net "PD_CPU1_PROCDIS_COD_GTL_N")
	)
	(arc
		(start 135.00989 -257.582162)
		(mid 135.237077 -257.64518)
		(end 135.466328 -257.590036)
		(width 0.12954)
		(layer "B.Cu")
		(net "PD_CPU1_PROCDIS_COD_GTL_N")
	)
	(segment
		(start 116.339112 -231.436418)
		(end 116.339112 -230.900732)
		(width 0.12954)
		(layer "F.Cu")
		(net "PD_CPU1_ENH_MCECC_DIS")
	)
	(segment
		(start 116.339112 -230.900732)
		(end 116.339366 -230.900478)
		(width 0.12954)
		(layer "F.Cu")
		(net "PD_CPU1_ENH_MCECC_DIS")
	)
	(via
		(at 116.339366 -230.900478)
		(size 0.4572)
		(drill 0.2032)
		(layers "F.Cu" "B.Cu")
		(net "PD_CPU1_ENH_MCECC_DIS")
	)
	(via
		(at 141.718538 -224.09277)
		(size 0.6604)
		(drill 0.3302)
		(layers "F.Cu" "B.Cu")
		(net "PD_CPU1_ENH_MCECC_DIS")
	)
	(segment
		(start 137.659618 -225.62693)
		(end 138.754358 -225.62693)
		(width 0.12954)
		(layer "B.Cu")
		(net "PD_CPU1_ENH_MCECC_DIS")
	)
	(segment
		(start 140.288518 -224.09277)
		(end 141.718538 -224.09277)
		(width 0.12954)
		(layer "B.Cu")
		(net "PD_CPU1_ENH_MCECC_DIS")
	)
	(segment
		(start 118.962678 -227.325682)
		(end 118.977664 -227.317046)
		(width 0.0889)
		(layer "B.Cu")
		(net "PD_CPU1_ENH_MCECC_DIS")
	)
	(segment
		(start 137.041128 -226.24542)
		(end 137.659618 -225.62693)
		(width 0.12954)
		(layer "B.Cu")
		(net "PD_CPU1_ENH_MCECC_DIS")
	)
	(segment
		(start 138.754358 -225.62693)
		(end 140.288518 -224.09277)
		(width 0.12954)
		(layer "B.Cu")
		(net "PD_CPU1_ENH_MCECC_DIS")
	)
	(segment
		(start 134.4676 -226.512882)
		(end 134.478014 -226.506786)
		(width 0.0889)
		(layer "B.Cu")
		(net "PD_CPU1_ENH_MCECC_DIS")
	)
	(segment
		(start 117.374416 -230.086662)
		(end 117.374416 -230.078026)
		(width 0.0889)
		(layer "B.Cu")
		(net "PD_CPU1_ENH_MCECC_DIS")
	)
	(segment
		(start 126.949454 -226.512882)
		(end 126.959868 -226.506786)
		(width 0.0889)
		(layer "B.Cu")
		(net "PD_CPU1_ENH_MCECC_DIS")
	)
	(segment
		(start 135.407654 -226.512882)
		(end 135.418068 -226.506786)
		(width 0.0889)
		(layer "B.Cu")
		(net "PD_CPU1_ENH_MCECC_DIS")
	)
	(segment
		(start 141.718538 -224.09277)
		(end 142.723108 -224.09277)
		(width 0.12954)
		(layer "B.Cu")
		(net "PD_CPU1_ENH_MCECC_DIS")
	)
	(segment
		(start 116.495576 -230.629714)
		(end 116.58473 -230.605838)
		(width 0.0889)
		(layer "B.Cu")
		(net "PD_CPU1_ENH_MCECC_DIS")
	)
	(segment
		(start 118.784116 -227.659184)
		(end 118.784116 -227.64496)
		(width 0.0889)
		(layer "B.Cu")
		(net "PD_CPU1_ENH_MCECC_DIS")
	)
	(segment
		(start 124.130054 -226.512882)
		(end 124.140468 -226.506786)
		(width 0.0889)
		(layer "B.Cu")
		(net "PD_CPU1_ENH_MCECC_DIS")
	)
	(segment
		(start 132.583682 -226.515422)
		(end 132.598414 -226.506786)
		(width 0.0889)
		(layer "B.Cu")
		(net "PD_CPU1_ENH_MCECC_DIS")
	)
	(segment
		(start 126.005082 -226.515422)
		(end 126.019814 -226.506786)
		(width 0.0889)
		(layer "B.Cu")
		(net "PD_CPU1_ENH_MCECC_DIS")
	)
	(segment
		(start 129.764282 -226.515422)
		(end 129.779014 -226.506786)
		(width 0.0889)
		(layer "B.Cu")
		(net "PD_CPU1_ENH_MCECC_DIS")
	)
	(segment
		(start 148.378418 -194.600068)
		(end 149.499574 -193.478912)
		(width 0.12954)
		(layer "B.Cu")
		(net "PD_CPU1_ENH_MCECC_DIS")
	)
	(segment
		(start 128.8288 -226.512882)
		(end 128.839214 -226.506786)
		(width 0.0889)
		(layer "B.Cu")
		(net "PD_CPU1_ENH_MCECC_DIS")
	)
	(segment
		(start 117.37467 -230.096568)
		(end 117.374416 -230.086662)
		(width 0.0889)
		(layer "B.Cu")
		(net "PD_CPU1_ENH_MCECC_DIS")
	)
	(segment
		(start 118.492524 -228.139752)
		(end 118.501414 -228.134672)
		(width 0.0889)
		(layer "B.Cu")
		(net "PD_CPU1_ENH_MCECC_DIS")
	)
	(segment
		(start 133.528054 -226.512882)
		(end 133.538468 -226.506786)
		(width 0.0889)
		(layer "B.Cu")
		(net "PD_CPU1_ENH_MCECC_DIS")
	)
	(segment
		(start 148.378418 -218.43746)
		(end 148.378418 -194.600068)
		(width 0.12954)
		(layer "B.Cu")
		(net "PD_CPU1_ENH_MCECC_DIS")
	)
	(segment
		(start 130.708654 -226.512882)
		(end 130.719068 -226.506786)
		(width 0.0889)
		(layer "B.Cu")
		(net "PD_CPU1_ENH_MCECC_DIS")
	)
	(segment
		(start 116.339366 -230.900478)
		(end 116.495576 -230.629714)
		(width 0.0889)
		(layer "B.Cu")
		(net "PD_CPU1_ENH_MCECC_DIS")
	)
	(segment
		(start 121.310654 -226.512882)
		(end 121.321068 -226.506786)
		(width 0.0889)
		(layer "B.Cu")
		(net "PD_CPU1_ENH_MCECC_DIS")
	)
	(segment
		(start 136.830308 -226.45624)
		(end 137.041128 -226.24542)
		(width 0.0889)
		(layer "B.Cu")
		(net "PD_CPU1_ENH_MCECC_DIS")
	)
	(segment
		(start 122.2502 -226.512882)
		(end 122.260614 -226.506786)
		(width 0.0889)
		(layer "B.Cu")
		(net "PD_CPU1_ENH_MCECC_DIS")
	)
	(segment
		(start 123.185682 -226.515422)
		(end 123.200414 -226.506786)
		(width 0.0889)
		(layer "B.Cu")
		(net "PD_CPU1_ENH_MCECC_DIS")
	)
	(segment
		(start 118.022878 -228.953568)
		(end 118.031768 -228.948488)
		(width 0.0889)
		(layer "B.Cu")
		(net "PD_CPU1_ENH_MCECC_DIS")
	)
	(segment
		(start 136.545066 -226.45624)
		(end 136.830308 -226.45624)
		(width 0.0889)
		(layer "B.Cu")
		(net "PD_CPU1_ENH_MCECC_DIS")
	)
	(segment
		(start 120.3706 -226.512882)
		(end 120.381014 -226.506786)
		(width 0.0889)
		(layer "B.Cu")
		(net "PD_CPU1_ENH_MCECC_DIS")
	)
	(segment
		(start 118.313962 -228.474524)
		(end 118.313962 -228.45903)
		(width 0.0889)
		(layer "B.Cu")
		(net "PD_CPU1_ENH_MCECC_DIS")
	)
	(segment
		(start 117.561614 -229.762304)
		(end 117.56771 -229.758748)
		(width 0.0889)
		(layer "B.Cu")
		(net "PD_CPU1_ENH_MCECC_DIS")
	)
	(segment
		(start 125.0696 -226.512882)
		(end 125.080014 -226.506786)
		(width 0.0889)
		(layer "B.Cu")
		(net "PD_CPU1_ENH_MCECC_DIS")
	)
	(segment
		(start 149.499574 -193.478912)
		(end 149.499574 -189.963298)
		(width 0.12954)
		(layer "B.Cu")
		(net "PD_CPU1_ENH_MCECC_DIS")
	)
	(segment
		(start 142.723108 -224.09277)
		(end 148.378418 -218.43746)
		(width 0.12954)
		(layer "B.Cu")
		(net "PD_CPU1_ENH_MCECC_DIS")
	)
	(segment
		(start 131.6482 -226.512882)
		(end 131.658614 -226.506786)
		(width 0.0889)
		(layer "B.Cu")
		(net "PD_CPU1_ENH_MCECC_DIS")
	)
	(arc
		(start 118.501414 -228.134672)
		(mid 118.704895 -227.933868)
		(end 118.784116 -227.659184)
		(width 0.0889)
		(layer "B.Cu")
		(net "PD_CPU1_ENH_MCECC_DIS")
	)
	(arc
		(start 134.478014 -226.506786)
		(mid 134.665212 -226.456643)
		(end 134.85241 -226.506786)
		(width 0.0889)
		(layer "B.Cu")
		(net "PD_CPU1_ENH_MCECC_DIS")
	)
	(arc
		(start 132.03301 -226.506786)
		(mid 132.307209 -226.582621)
		(end 132.583682 -226.515422)
		(width 0.0889)
		(layer "B.Cu")
		(net "PD_CPU1_ENH_MCECC_DIS")
	)
	(arc
		(start 132.97281 -226.506786)
		(mid 133.249623 -226.582656)
		(end 133.528054 -226.512882)
		(width 0.0889)
		(layer "B.Cu")
		(net "PD_CPU1_ENH_MCECC_DIS")
	)
	(arc
		(start 122.63501 -226.506786)
		(mid 122.909209 -226.582621)
		(end 123.185682 -226.515422)
		(width 0.0889)
		(layer "B.Cu")
		(net "PD_CPU1_ENH_MCECC_DIS")
	)
	(arc
		(start 127.899668 -226.506786)
		(mid 128.086866 -226.456643)
		(end 128.274064 -226.506786)
		(width 0.0889)
		(layer "B.Cu")
		(net "PD_CPU1_ENH_MCECC_DIS")
	)
	(arc
		(start 134.85241 -226.506786)
		(mid 135.129223 -226.582656)
		(end 135.407654 -226.512882)
		(width 0.0889)
		(layer "B.Cu")
		(net "PD_CPU1_ENH_MCECC_DIS")
	)
	(arc
		(start 135.418068 -226.506786)
		(mid 135.605266 -226.456643)
		(end 135.792464 -226.506786)
		(width 0.0889)
		(layer "B.Cu")
		(net "PD_CPU1_ENH_MCECC_DIS")
	)
	(arc
		(start 118.977664 -227.317046)
		(mid 119.180077 -227.110633)
		(end 119.254016 -226.831144)
		(width 0.0889)
		(layer "B.Cu")
		(net "PD_CPU1_ENH_MCECC_DIS")
	)
	(arc
		(start 126.39421 -226.506786)
		(mid 126.671023 -226.582656)
		(end 126.949454 -226.512882)
		(width 0.0889)
		(layer "B.Cu")
		(net "PD_CPU1_ENH_MCECC_DIS")
	)
	(arc
		(start 117.844316 -229.272846)
		(mid 117.891995 -229.089946)
		(end 118.022878 -228.953568)
		(width 0.0889)
		(layer "B.Cu")
		(net "PD_CPU1_ENH_MCECC_DIS")
	)
	(arc
		(start 126.959868 -226.506786)
		(mid 127.147066 -226.456643)
		(end 127.334264 -226.506786)
		(width 0.0889)
		(layer "B.Cu")
		(net "PD_CPU1_ENH_MCECC_DIS")
	)
	(arc
		(start 127.334264 -226.506786)
		(mid 127.616966 -226.582562)
		(end 127.899668 -226.506786)
		(width 0.0889)
		(layer "B.Cu")
		(net "PD_CPU1_ENH_MCECC_DIS")
	)
	(arc
		(start 117.374416 -230.078026)
		(mid 117.426686 -229.895661)
		(end 117.561614 -229.762304)
		(width 0.0889)
		(layer "B.Cu")
		(net "PD_CPU1_ENH_MCECC_DIS")
	)
	(arc
		(start 116.58473 -230.605838)
		(mid 116.841839 -230.651278)
		(end 117.091968 -230.576374)
		(width 0.0889)
		(layer "B.Cu")
		(net "PD_CPU1_ENH_MCECC_DIS")
	)
	(arc
		(start 121.321068 -226.506786)
		(mid 121.508266 -226.456643)
		(end 121.695464 -226.506786)
		(width 0.0889)
		(layer "B.Cu")
		(net "PD_CPU1_ENH_MCECC_DIS")
	)
	(arc
		(start 135.792464 -226.506786)
		(mid 136.075166 -226.582562)
		(end 136.357868 -226.506786)
		(width 0.0889)
		(layer "B.Cu")
		(net "PD_CPU1_ENH_MCECC_DIS")
	)
	(arc
		(start 123.57481 -226.506786)
		(mid 123.851623 -226.582656)
		(end 124.130054 -226.512882)
		(width 0.0889)
		(layer "B.Cu")
		(net "PD_CPU1_ENH_MCECC_DIS")
	)
	(arc
		(start 133.538468 -226.506786)
		(mid 133.725666 -226.456643)
		(end 133.912864 -226.506786)
		(width 0.0889)
		(layer "B.Cu")
		(net "PD_CPU1_ENH_MCECC_DIS")
	)
	(arc
		(start 136.357868 -226.506786)
		(mid 136.44814 -226.469187)
		(end 136.545066 -226.45624)
		(width 0.0889)
		(layer "B.Cu")
		(net "PD_CPU1_ENH_MCECC_DIS")
	)
	(arc
		(start 118.031768 -228.948488)
		(mid 118.234591 -228.748257)
		(end 118.313962 -228.474524)
		(width 0.0889)
		(layer "B.Cu")
		(net "PD_CPU1_ENH_MCECC_DIS")
	)
	(arc
		(start 129.779014 -226.506786)
		(mid 129.966212 -226.456643)
		(end 130.15341 -226.506786)
		(width 0.0889)
		(layer "B.Cu")
		(net "PD_CPU1_ENH_MCECC_DIS")
	)
	(arc
		(start 130.719068 -226.506786)
		(mid 130.906266 -226.456643)
		(end 131.093464 -226.506786)
		(width 0.0889)
		(layer "B.Cu")
		(net "PD_CPU1_ENH_MCECC_DIS")
	)
	(arc
		(start 128.839214 -226.506786)
		(mid 129.026412 -226.456643)
		(end 129.21361 -226.506786)
		(width 0.0889)
		(layer "B.Cu")
		(net "PD_CPU1_ENH_MCECC_DIS")
	)
	(arc
		(start 119.254016 -226.831144)
		(mid 119.441315 -226.506703)
		(end 119.815864 -226.506786)
		(width 0.0889)
		(layer "B.Cu")
		(net "PD_CPU1_ENH_MCECC_DIS")
	)
	(arc
		(start 117.56771 -229.758748)
		(mid 117.770297 -229.552397)
		(end 117.844316 -229.272846)
		(width 0.0889)
		(layer "B.Cu")
		(net "PD_CPU1_ENH_MCECC_DIS")
	)
	(arc
		(start 118.784116 -227.64496)
		(mid 118.831795 -227.46206)
		(end 118.962678 -227.325682)
		(width 0.0889)
		(layer "B.Cu")
		(net "PD_CPU1_ENH_MCECC_DIS")
	)
	(arc
		(start 120.381014 -226.506786)
		(mid 120.568212 -226.456643)
		(end 120.75541 -226.506786)
		(width 0.0889)
		(layer "B.Cu")
		(net "PD_CPU1_ENH_MCECC_DIS")
	)
	(arc
		(start 124.514864 -226.506786)
		(mid 124.791423 -226.582529)
		(end 125.0696 -226.512882)
		(width 0.0889)
		(layer "B.Cu")
		(net "PD_CPU1_ENH_MCECC_DIS")
	)
	(arc
		(start 125.45441 -226.506786)
		(mid 125.728609 -226.582621)
		(end 126.005082 -226.515422)
		(width 0.0889)
		(layer "B.Cu")
		(net "PD_CPU1_ENH_MCECC_DIS")
	)
	(arc
		(start 122.260614 -226.506786)
		(mid 122.447812 -226.456643)
		(end 122.63501 -226.506786)
		(width 0.0889)
		(layer "B.Cu")
		(net "PD_CPU1_ENH_MCECC_DIS")
	)
	(arc
		(start 117.091968 -230.576374)
		(mid 117.296549 -230.373712)
		(end 117.37467 -230.096568)
		(width 0.0889)
		(layer "B.Cu")
		(net "PD_CPU1_ENH_MCECC_DIS")
	)
	(arc
		(start 121.695464 -226.506786)
		(mid 121.972023 -226.582529)
		(end 122.2502 -226.512882)
		(width 0.0889)
		(layer "B.Cu")
		(net "PD_CPU1_ENH_MCECC_DIS")
	)
	(arc
		(start 126.019814 -226.506786)
		(mid 126.207012 -226.456643)
		(end 126.39421 -226.506786)
		(width 0.0889)
		(layer "B.Cu")
		(net "PD_CPU1_ENH_MCECC_DIS")
	)
	(arc
		(start 132.598414 -226.506786)
		(mid 132.785612 -226.456643)
		(end 132.97281 -226.506786)
		(width 0.0889)
		(layer "B.Cu")
		(net "PD_CPU1_ENH_MCECC_DIS")
	)
	(arc
		(start 131.093464 -226.506786)
		(mid 131.370023 -226.582529)
		(end 131.6482 -226.512882)
		(width 0.0889)
		(layer "B.Cu")
		(net "PD_CPU1_ENH_MCECC_DIS")
	)
	(arc
		(start 123.200414 -226.506786)
		(mid 123.387612 -226.456643)
		(end 123.57481 -226.506786)
		(width 0.0889)
		(layer "B.Cu")
		(net "PD_CPU1_ENH_MCECC_DIS")
	)
	(arc
		(start 133.912864 -226.506786)
		(mid 134.189423 -226.582529)
		(end 134.4676 -226.512882)
		(width 0.0889)
		(layer "B.Cu")
		(net "PD_CPU1_ENH_MCECC_DIS")
	)
	(arc
		(start 120.75541 -226.506786)
		(mid 121.032223 -226.582656)
		(end 121.310654 -226.512882)
		(width 0.0889)
		(layer "B.Cu")
		(net "PD_CPU1_ENH_MCECC_DIS")
	)
	(arc
		(start 130.15341 -226.506786)
		(mid 130.430223 -226.582656)
		(end 130.708654 -226.512882)
		(width 0.0889)
		(layer "B.Cu")
		(net "PD_CPU1_ENH_MCECC_DIS")
	)
	(arc
		(start 125.080014 -226.506786)
		(mid 125.267212 -226.456643)
		(end 125.45441 -226.506786)
		(width 0.0889)
		(layer "B.Cu")
		(net "PD_CPU1_ENH_MCECC_DIS")
	)
	(arc
		(start 118.313962 -228.45903)
		(mid 118.361641 -228.27613)
		(end 118.492524 -228.139752)
		(width 0.0889)
		(layer "B.Cu")
		(net "PD_CPU1_ENH_MCECC_DIS")
	)
	(arc
		(start 131.658614 -226.506786)
		(mid 131.845812 -226.456643)
		(end 132.03301 -226.506786)
		(width 0.0889)
		(layer "B.Cu")
		(net "PD_CPU1_ENH_MCECC_DIS")
	)
	(arc
		(start 119.815864 -226.506786)
		(mid 120.092423 -226.582529)
		(end 120.3706 -226.512882)
		(width 0.0889)
		(layer "B.Cu")
		(net "PD_CPU1_ENH_MCECC_DIS")
	)
	(arc
		(start 129.21361 -226.506786)
		(mid 129.487809 -226.582621)
		(end 129.764282 -226.515422)
		(width 0.0889)
		(layer "B.Cu")
		(net "PD_CPU1_ENH_MCECC_DIS")
	)
	(arc
		(start 124.140468 -226.506786)
		(mid 124.327666 -226.456643)
		(end 124.514864 -226.506786)
		(width 0.0889)
		(layer "B.Cu")
		(net "PD_CPU1_ENH_MCECC_DIS")
	)
	(arc
		(start 128.274064 -226.506786)
		(mid 128.550623 -226.582529)
		(end 128.8288 -226.512882)
		(width 0.0889)
		(layer "B.Cu")
		(net "PD_CPU1_ENH_MCECC_DIS")
	)
	(segment
		(start 102.712266 -226.831398)
		(end 102.712012 -226.831144)
		(width 0.12954)
		(layer "F.Cu")
		(net "PD_CPU1_DMIMODE_OVERRIDE")
	)
	(segment
		(start 102.712266 -227.367084)
		(end 102.712266 -226.831398)
		(width 0.12954)
		(layer "F.Cu")
		(net "PD_CPU1_DMIMODE_OVERRIDE")
	)
	(via
		(at 102.712012 -226.831144)
		(size 0.4572)
		(drill 0.2032)
		(layers "F.Cu" "B.Cu")
		(net "PD_CPU1_DMIMODE_OVERRIDE")
	)
	(via
		(at 69.140832 -195.203064)
		(size 0.762)
		(drill 0.254)
		(layers "F.Cu" "B.Cu")
		(net "PD_CPU1_DMIMODE_OVERRIDE")
	)
	(segment
		(start 68.29298 -190.042292)
		(end 68.29298 -189.774322)
		(width 0.12954)
		(layer "B.Cu")
		(net "PD_CPU1_DMIMODE_OVERRIDE")
	)
	(segment
		(start 69.140832 -195.203064)
		(end 69.38772 -194.956176)
		(width 0.12954)
		(layer "B.Cu")
		(net "PD_CPU1_DMIMODE_OVERRIDE")
	)
	(segment
		(start 69.38772 -192.68567)
		(end 68.29298 -190.042292)
		(width 0.12954)
		(layer "B.Cu")
		(net "PD_CPU1_DMIMODE_OVERRIDE")
	)
	(segment
		(start 69.38772 -194.956176)
		(end 69.38772 -192.68567)
		(width 0.12954)
		(layer "B.Cu")
		(net "PD_CPU1_DMIMODE_OVERRIDE")
	)
	(segment
		(start 99.671378 -225.618294)
		(end 99.657916 -225.61042)
		(width 0.127)
		(layer "In2.Cu")
		(net "PD_CPU1_DMIMODE_OVERRIDE")
	)
	(segment
		(start 88.187022 -221.803214)
		(end 87.707978 -221.32417)
		(width 0.127)
		(layer "In2.Cu")
		(net "PD_CPU1_DMIMODE_OVERRIDE")
	)
	(segment
		(start 94.032578 -225.618294)
		(end 94.019116 -225.61042)
		(width 0.127)
		(layer "In2.Cu")
		(net "PD_CPU1_DMIMODE_OVERRIDE")
	)
	(segment
		(start 91.669616 -224.79635)
		(end 91.66479 -224.793556)
		(width 0.127)
		(layer "In2.Cu")
		(net "PD_CPU1_DMIMODE_OVERRIDE")
	)
	(segment
		(start 89.401396 -222.468948)
		(end 89.297256 -222.364808)
		(width 0.127)
		(layer "In2.Cu")
		(net "PD_CPU1_DMIMODE_OVERRIDE")
	)
	(segment
		(start 92.609416 -225.61042)
		(end 92.609162 -225.610166)
		(width 0.127)
		(layer "In2.Cu")
		(net "PD_CPU1_DMIMODE_OVERRIDE")
	)
	(segment
		(start 87.707978 -219.68079)
		(end 86.773258 -218.74607)
		(width 0.127)
		(layer "In2.Cu")
		(net "PD_CPU1_DMIMODE_OVERRIDE")
	)
	(segment
		(start 91.199716 -223.982534)
		(end 91.185492 -223.974152)
		(width 0.127)
		(layer "In2.Cu")
		(net "PD_CPU1_DMIMODE_OVERRIDE")
	)
	(segment
		(start 100.611178 -225.618294)
		(end 100.597716 -225.61042)
		(width 0.127)
		(layer "In2.Cu")
		(net "PD_CPU1_DMIMODE_OVERRIDE")
	)
	(segment
		(start 96.851978 -225.618294)
		(end 96.838516 -225.61042)
		(width 0.127)
		(layer "In2.Cu")
		(net "PD_CPU1_DMIMODE_OVERRIDE")
	)
	(segment
		(start 88.375744 -222.364808)
		(end 88.187022 -222.176086)
		(width 0.127)
		(layer "In2.Cu")
		(net "PD_CPU1_DMIMODE_OVERRIDE")
	)
	(segment
		(start 86.773258 -218.74607)
		(end 86.773258 -217.70467)
		(width 0.127)
		(layer "In2.Cu")
		(net "PD_CPU1_DMIMODE_OVERRIDE")
	)
	(segment
		(start 88.187022 -222.176086)
		(end 88.187022 -221.803214)
		(width 0.127)
		(layer "In2.Cu")
		(net "PD_CPU1_DMIMODE_OVERRIDE")
	)
	(segment
		(start 89.790016 -222.354648)
		(end 89.535 -222.468948)
		(width 0.127)
		(layer "In2.Cu")
		(net "PD_CPU1_DMIMODE_OVERRIDE")
	)
	(segment
		(start 86.310978 -215.39073)
		(end 81.733898 -210.81365)
		(width 0.127)
		(layer "In2.Cu")
		(net "PD_CPU1_DMIMODE_OVERRIDE")
	)
	(segment
		(start 95.912178 -225.618294)
		(end 95.898716 -225.61042)
		(width 0.127)
		(layer "In2.Cu")
		(net "PD_CPU1_DMIMODE_OVERRIDE")
	)
	(segment
		(start 86.773258 -217.70467)
		(end 86.310978 -217.24239)
		(width 0.127)
		(layer "In2.Cu")
		(net "PD_CPU1_DMIMODE_OVERRIDE")
	)
	(segment
		(start 90.964512 -223.575626)
		(end 90.964512 -223.558354)
		(width 0.127)
		(layer "In2.Cu")
		(net "PD_CPU1_DMIMODE_OVERRIDE")
	)
	(segment
		(start 102.007416 -226.424236)
		(end 102.00259 -226.421442)
		(width 0.127)
		(layer "In2.Cu")
		(net "PD_CPU1_DMIMODE_OVERRIDE")
	)
	(segment
		(start 91.204542 -223.985328)
		(end 91.199716 -223.982534)
		(width 0.127)
		(layer "In2.Cu")
		(net "PD_CPU1_DMIMODE_OVERRIDE")
	)
	(segment
		(start 93.092778 -225.618294)
		(end 93.079316 -225.61042)
		(width 0.127)
		(layer "In2.Cu")
		(net "PD_CPU1_DMIMODE_OVERRIDE")
	)
	(segment
		(start 91.904312 -225.210878)
		(end 91.904312 -225.193606)
		(width 0.127)
		(layer "In2.Cu")
		(net "PD_CPU1_DMIMODE_OVERRIDE")
	)
	(segment
		(start 98.731578 -225.618294)
		(end 98.718116 -225.61042)
		(width 0.127)
		(layer "In2.Cu")
		(net "PD_CPU1_DMIMODE_OVERRIDE")
	)
	(segment
		(start 81.733898 -199.84085)
		(end 79.223108 -197.33006)
		(width 0.127)
		(layer "In2.Cu")
		(net "PD_CPU1_DMIMODE_OVERRIDE")
	)
	(segment
		(start 89.535 -222.468948)
		(end 89.401396 -222.468948)
		(width 0.127)
		(layer "In2.Cu")
		(net "PD_CPU1_DMIMODE_OVERRIDE")
	)
	(segment
		(start 90.729816 -223.168464)
		(end 90.72499 -223.16567)
		(width 0.127)
		(layer "In2.Cu")
		(net "PD_CPU1_DMIMODE_OVERRIDE")
	)
	(segment
		(start 69.140832 -196.426328)
		(end 69.140832 -195.203064)
		(width 0.127)
		(layer "In2.Cu")
		(net "PD_CPU1_DMIMODE_OVERRIDE")
	)
	(segment
		(start 81.733898 -210.81365)
		(end 81.733898 -199.84085)
		(width 0.127)
		(layer "In2.Cu")
		(net "PD_CPU1_DMIMODE_OVERRIDE")
	)
	(segment
		(start 102.712012 -226.831144)
		(end 102.414324 -226.831144)
		(width 0.127)
		(layer "In2.Cu")
		(net "PD_CPU1_DMIMODE_OVERRIDE")
	)
	(segment
		(start 92.609162 -225.610166)
		(end 92.608908 -225.610166)
		(width 0.127)
		(layer "In2.Cu")
		(net "PD_CPU1_DMIMODE_OVERRIDE")
	)
	(segment
		(start 70.044564 -197.33006)
		(end 69.140832 -196.426328)
		(width 0.127)
		(layer "In2.Cu")
		(net "PD_CPU1_DMIMODE_OVERRIDE")
	)
	(segment
		(start 97.791778 -225.618294)
		(end 97.778316 -225.61042)
		(width 0.127)
		(layer "In2.Cu")
		(net "PD_CPU1_DMIMODE_OVERRIDE")
	)
	(segment
		(start 87.707978 -221.32417)
		(end 87.707978 -219.68079)
		(width 0.127)
		(layer "In2.Cu")
		(net "PD_CPU1_DMIMODE_OVERRIDE")
	)
	(segment
		(start 89.297256 -222.364808)
		(end 88.375744 -222.364808)
		(width 0.127)
		(layer "In2.Cu")
		(net "PD_CPU1_DMIMODE_OVERRIDE")
	)
	(segment
		(start 86.310978 -217.24239)
		(end 86.310978 -215.39073)
		(width 0.127)
		(layer "In2.Cu")
		(net "PD_CPU1_DMIMODE_OVERRIDE")
	)
	(segment
		(start 79.223108 -197.33006)
		(end 70.044564 -197.33006)
		(width 0.127)
		(layer "In2.Cu")
		(net "PD_CPU1_DMIMODE_OVERRIDE")
	)
	(segment
		(start 102.414324 -226.831144)
		(end 102.007416 -226.424236)
		(width 0.127)
		(layer "In2.Cu")
		(net "PD_CPU1_DMIMODE_OVERRIDE")
	)
	(segment
		(start 94.972378 -225.618294)
		(end 94.958916 -225.61042)
		(width 0.127)
		(layer "In2.Cu")
		(net "PD_CPU1_DMIMODE_OVERRIDE")
	)
	(arc
		(start 94.958916 -225.61042)
		(mid 94.723966 -225.54746)
		(end 94.489016 -225.61042)
		(width 0.127)
		(layer "In2.Cu")
		(net "PD_CPU1_DMIMODE_OVERRIDE")
	)
	(arc
		(start 98.248216 -225.61042)
		(mid 98.021029 -225.673404)
		(end 97.791778 -225.618294)
		(width 0.127)
		(layer "In2.Cu")
		(net "PD_CPU1_DMIMODE_OVERRIDE")
	)
	(arc
		(start 98.718116 -225.61042)
		(mid 98.483166 -225.54746)
		(end 98.248216 -225.61042)
		(width 0.127)
		(layer "In2.Cu")
		(net "PD_CPU1_DMIMODE_OVERRIDE")
	)
	(arc
		(start 90.964512 -223.558354)
		(mid 90.897474 -223.333125)
		(end 90.729816 -223.168464)
		(width 0.127)
		(layer "In2.Cu")
		(net "PD_CPU1_DMIMODE_OVERRIDE")
	)
	(arc
		(start 91.434666 -224.389442)
		(mid 91.373103 -224.156919)
		(end 91.204542 -223.985328)
		(width 0.127)
		(layer "In2.Cu")
		(net "PD_CPU1_DMIMODE_OVERRIDE")
	)
	(arc
		(start 97.778316 -225.61042)
		(mid 97.543366 -225.54746)
		(end 97.308416 -225.61042)
		(width 0.127)
		(layer "In2.Cu")
		(net "PD_CPU1_DMIMODE_OVERRIDE")
	)
	(arc
		(start 101.537516 -225.61042)
		(mid 101.302566 -225.54746)
		(end 101.067616 -225.61042)
		(width 0.127)
		(layer "In2.Cu")
		(net "PD_CPU1_DMIMODE_OVERRIDE")
	)
	(arc
		(start 102.00259 -226.421442)
		(mid 101.834034 -226.249848)
		(end 101.772466 -226.017328)
		(width 0.127)
		(layer "In2.Cu")
		(net "PD_CPU1_DMIMODE_OVERRIDE")
	)
	(arc
		(start 96.368616 -225.61042)
		(mid 96.141429 -225.673404)
		(end 95.912178 -225.618294)
		(width 0.127)
		(layer "In2.Cu")
		(net "PD_CPU1_DMIMODE_OVERRIDE")
	)
	(arc
		(start 90.494866 -222.761556)
		(mid 90.259908 -222.354606)
		(end 89.790016 -222.354648)
		(width 0.127)
		(layer "In2.Cu")
		(net "PD_CPU1_DMIMODE_OVERRIDE")
	)
	(arc
		(start 94.489016 -225.61042)
		(mid 94.261829 -225.673404)
		(end 94.032578 -225.618294)
		(width 0.127)
		(layer "In2.Cu")
		(net "PD_CPU1_DMIMODE_OVERRIDE")
	)
	(arc
		(start 94.019116 -225.61042)
		(mid 93.784166 -225.54746)
		(end 93.549216 -225.61042)
		(width 0.127)
		(layer "In2.Cu")
		(net "PD_CPU1_DMIMODE_OVERRIDE")
	)
	(arc
		(start 90.72499 -223.16567)
		(mid 90.556434 -222.994076)
		(end 90.494866 -222.761556)
		(width 0.127)
		(layer "In2.Cu")
		(net "PD_CPU1_DMIMODE_OVERRIDE")
	)
	(arc
		(start 91.904312 -225.193606)
		(mid 91.839069 -224.964194)
		(end 91.669616 -224.79635)
		(width 0.127)
		(layer "In2.Cu")
		(net "PD_CPU1_DMIMODE_OVERRIDE")
	)
	(arc
		(start 91.185492 -223.974152)
		(mid 91.02347 -223.803466)
		(end 90.964512 -223.575626)
		(width 0.127)
		(layer "In2.Cu")
		(net "PD_CPU1_DMIMODE_OVERRIDE")
	)
	(arc
		(start 92.139516 -225.61042)
		(mid 91.969216 -225.441672)
		(end 91.904312 -225.210878)
		(width 0.127)
		(layer "In2.Cu")
		(net "PD_CPU1_DMIMODE_OVERRIDE")
	)
	(arc
		(start 100.597716 -225.61042)
		(mid 100.362766 -225.54746)
		(end 100.127816 -225.61042)
		(width 0.127)
		(layer "In2.Cu")
		(net "PD_CPU1_DMIMODE_OVERRIDE")
	)
	(arc
		(start 92.608908 -225.610166)
		(mid 92.374241 -225.673194)
		(end 92.139516 -225.61042)
		(width 0.127)
		(layer "In2.Cu")
		(net "PD_CPU1_DMIMODE_OVERRIDE")
	)
	(arc
		(start 99.657916 -225.61042)
		(mid 99.422966 -225.54746)
		(end 99.188016 -225.61042)
		(width 0.127)
		(layer "In2.Cu")
		(net "PD_CPU1_DMIMODE_OVERRIDE")
	)
	(arc
		(start 96.838516 -225.61042)
		(mid 96.603566 -225.54746)
		(end 96.368616 -225.61042)
		(width 0.127)
		(layer "In2.Cu")
		(net "PD_CPU1_DMIMODE_OVERRIDE")
	)
	(arc
		(start 97.308416 -225.61042)
		(mid 97.081229 -225.673404)
		(end 96.851978 -225.618294)
		(width 0.127)
		(layer "In2.Cu")
		(net "PD_CPU1_DMIMODE_OVERRIDE")
	)
	(arc
		(start 91.66479 -224.793556)
		(mid 91.496234 -224.621962)
		(end 91.434666 -224.389442)
		(width 0.127)
		(layer "In2.Cu")
		(net "PD_CPU1_DMIMODE_OVERRIDE")
	)
	(arc
		(start 101.772466 -226.017328)
		(mid 101.709516 -225.782386)
		(end 101.537516 -225.61042)
		(width 0.127)
		(layer "In2.Cu")
		(net "PD_CPU1_DMIMODE_OVERRIDE")
	)
	(arc
		(start 99.188016 -225.61042)
		(mid 98.960829 -225.673404)
		(end 98.731578 -225.618294)
		(width 0.127)
		(layer "In2.Cu")
		(net "PD_CPU1_DMIMODE_OVERRIDE")
	)
	(arc
		(start 95.428816 -225.61042)
		(mid 95.201629 -225.673404)
		(end 94.972378 -225.618294)
		(width 0.127)
		(layer "In2.Cu")
		(net "PD_CPU1_DMIMODE_OVERRIDE")
	)
	(arc
		(start 100.127816 -225.61042)
		(mid 99.900629 -225.673404)
		(end 99.671378 -225.618294)
		(width 0.127)
		(layer "In2.Cu")
		(net "PD_CPU1_DMIMODE_OVERRIDE")
	)
	(arc
		(start 101.067616 -225.61042)
		(mid 100.840429 -225.673404)
		(end 100.611178 -225.618294)
		(width 0.127)
		(layer "In2.Cu")
		(net "PD_CPU1_DMIMODE_OVERRIDE")
	)
	(arc
		(start 93.079316 -225.61042)
		(mid 92.844366 -225.54746)
		(end 92.609416 -225.61042)
		(width 0.127)
		(layer "In2.Cu")
		(net "PD_CPU1_DMIMODE_OVERRIDE")
	)
	(arc
		(start 93.549216 -225.61042)
		(mid 93.322029 -225.673404)
		(end 93.092778 -225.618294)
		(width 0.127)
		(layer "In2.Cu")
		(net "PD_CPU1_DMIMODE_OVERRIDE")
	)
	(arc
		(start 95.898716 -225.61042)
		(mid 95.663766 -225.54746)
		(end 95.428816 -225.61042)
		(width 0.127)
		(layer "In2.Cu")
		(net "PD_CPU1_DMIMODE_OVERRIDE")
	)
	(segment
		(start 101.302566 -228.180646)
		(end 101.302566 -227.64496)
		(width 0.12954)
		(layer "F.Cu")
		(net "PD_CPU1_BIST_ENABLE")
	)
	(segment
		(start 88.051132 -179.27701)
		(end 88.051132 -180.33873)
		(width 0.12954)
		(layer "F.Cu")
		(net "PD_CPU1_BIST_ENABLE")
	)
	(segment
		(start 101.302312 -228.1809)
		(end 101.302566 -228.180646)
		(width 0.12954)
		(layer "F.Cu")
		(net "PD_CPU1_BIST_ENABLE")
	)
	(segment
		(start 88.041988 -179.267866)
		(end 88.051132 -179.27701)
		(width 0.12954)
		(layer "F.Cu")
		(net "PD_CPU1_BIST_ENABLE")
	)
	(segment
		(start 83.085178 -186.09691)
		(end 83.085178 -182.73141)
		(width 0.12954)
		(layer "F.Cu")
		(net "PD_CPU1_BIST_ENABLE")
	)
	(segment
		(start 85.477858 -180.33873)
		(end 88.051132 -180.33873)
		(width 0.12954)
		(layer "F.Cu")
		(net "PD_CPU1_BIST_ENABLE")
	)
	(segment
		(start 83.085178 -182.73141)
		(end 85.477858 -180.33873)
		(width 0.12954)
		(layer "F.Cu")
		(net "PD_CPU1_BIST_ENABLE")
	)
	(via
		(at 83.085178 -186.09691)
		(size 0.508)
		(drill 0.254)
		(layers "F.Cu" "B.Cu")
		(net "PD_CPU1_BIST_ENABLE")
	)
	(via
		(at 78.752446 -206.667862)
		(size 0.6604)
		(drill 0.3302)
		(layers "F.Cu" "B.Cu")
		(net "PD_CPU1_BIST_ENABLE")
	)
	(via
		(at 101.302566 -227.64496)
		(size 0.4572)
		(drill 0.2032)
		(layers "F.Cu" "B.Cu")
		(net "PD_CPU1_BIST_ENABLE")
	)
	(segment
		(start 86.463378 -227.326698)
		(end 86.452964 -227.320602)
		(width 0.0889)
		(layer "B.Cu")
		(net "PD_CPU1_BIST_ENABLE")
	)
	(segment
		(start 83.81873 -227.411026)
		(end 83.445096 -227.037392)
		(width 0.0889)
		(layer "B.Cu")
		(net "PD_CPU1_BIST_ENABLE")
	)
	(segment
		(start 81.895442 -198.388986)
		(end 81.895442 -188.757306)
		(width 0.12954)
		(layer "B.Cu")
		(net "PD_CPU1_BIST_ENABLE")
	)
	(segment
		(start 81.895442 -188.757306)
		(end 82.424778 -188.22797)
		(width 0.12954)
		(layer "B.Cu")
		(net "PD_CPU1_BIST_ENABLE")
	)
	(segment
		(start 89.287096 -227.329238)
		(end 89.272364 -227.320602)
		(width 0.0889)
		(layer "B.Cu")
		(net "PD_CPU1_BIST_ENABLE")
	)
	(segment
		(start 101.45903 -227.373942)
		(end 101.437948 -227.295964)
		(width 0.0889)
		(layer "B.Cu")
		(net "PD_CPU1_BIST_ENABLE")
	)
	(segment
		(start 85.029802 -227.411026)
		(end 83.81873 -227.411026)
		(width 0.0889)
		(layer "B.Cu")
		(net "PD_CPU1_BIST_ENABLE")
	)
	(segment
		(start 80.957674 -204.462634)
		(end 80.957674 -199.326754)
		(width 0.12954)
		(layer "B.Cu")
		(net "PD_CPU1_BIST_ENABLE")
	)
	(segment
		(start 101.302566 -227.64496)
		(end 101.45903 -227.373942)
		(width 0.0889)
		(layer "B.Cu")
		(net "PD_CPU1_BIST_ENABLE")
	)
	(segment
		(start 93.986096 -227.329238)
		(end 93.971364 -227.320602)
		(width 0.0889)
		(layer "B.Cu")
		(net "PD_CPU1_BIST_ENABLE")
	)
	(segment
		(start 78.752446 -206.667862)
		(end 80.957674 -204.462634)
		(width 0.12954)
		(layer "B.Cu")
		(net "PD_CPU1_BIST_ENABLE")
	)
	(segment
		(start 85.06079 -227.380038)
		(end 85.029802 -227.411026)
		(width 0.0889)
		(layer "B.Cu")
		(net "PD_CPU1_BIST_ENABLE")
	)
	(segment
		(start 82.424778 -188.22797)
		(end 82.424778 -186.75731)
		(width 0.12954)
		(layer "B.Cu")
		(net "PD_CPU1_BIST_ENABLE")
	)
	(segment
		(start 83.445096 -227.037392)
		(end 83.061302 -227.037392)
		(width 0.12954)
		(layer "B.Cu")
		(net "PD_CPU1_BIST_ENABLE")
	)
	(segment
		(start 90.226896 -227.329238)
		(end 90.212164 -227.320602)
		(width 0.0889)
		(layer "B.Cu")
		(net "PD_CPU1_BIST_ENABLE")
	)
	(segment
		(start 94.925896 -227.329238)
		(end 94.911164 -227.320602)
		(width 0.0889)
		(layer "B.Cu")
		(net "PD_CPU1_BIST_ENABLE")
	)
	(segment
		(start 96.805496 -227.329238)
		(end 96.790764 -227.320602)
		(width 0.0889)
		(layer "B.Cu")
		(net "PD_CPU1_BIST_ENABLE")
	)
	(segment
		(start 100.564696 -227.329238)
		(end 100.549964 -227.320602)
		(width 0.0889)
		(layer "B.Cu")
		(net "PD_CPU1_BIST_ENABLE")
	)
	(segment
		(start 78.301088 -207.11922)
		(end 78.752446 -206.667862)
		(width 0.12954)
		(layer "B.Cu")
		(net "PD_CPU1_BIST_ENABLE")
	)
	(segment
		(start 78.301088 -222.277178)
		(end 78.301088 -207.11922)
		(width 0.12954)
		(layer "B.Cu")
		(net "PD_CPU1_BIST_ENABLE")
	)
	(segment
		(start 91.717114 -227.320602)
		(end 91.7067 -227.326698)
		(width 0.0889)
		(layer "B.Cu")
		(net "PD_CPU1_BIST_ENABLE")
	)
	(segment
		(start 83.061302 -227.037392)
		(end 78.301088 -222.277178)
		(width 0.12954)
		(layer "B.Cu")
		(net "PD_CPU1_BIST_ENABLE")
	)
	(segment
		(start 92.101924 -227.326698)
		(end 92.09151 -227.320602)
		(width 0.0889)
		(layer "B.Cu")
		(net "PD_CPU1_BIST_ENABLE")
	)
	(segment
		(start 82.424778 -186.75731)
		(end 83.085178 -186.09691)
		(width 0.12954)
		(layer "B.Cu")
		(net "PD_CPU1_BIST_ENABLE")
	)
	(segment
		(start 97.745296 -227.329238)
		(end 97.730564 -227.320602)
		(width 0.0889)
		(layer "B.Cu")
		(net "PD_CPU1_BIST_ENABLE")
	)
	(segment
		(start 86.078568 -227.320602)
		(end 86.068154 -227.326698)
		(width 0.0889)
		(layer "B.Cu")
		(net "PD_CPU1_BIST_ENABLE")
	)
	(segment
		(start 93.046296 -227.329238)
		(end 93.031564 -227.320602)
		(width 0.0889)
		(layer "B.Cu")
		(net "PD_CPU1_BIST_ENABLE")
	)
	(segment
		(start 80.957674 -199.326754)
		(end 81.895442 -198.388986)
		(width 0.12954)
		(layer "B.Cu")
		(net "PD_CPU1_BIST_ENABLE")
	)
	(segment
		(start 88.347296 -227.329238)
		(end 88.332564 -227.320602)
		(width 0.0889)
		(layer "B.Cu")
		(net "PD_CPU1_BIST_ENABLE")
	)
	(segment
		(start 87.958168 -227.320602)
		(end 87.947754 -227.326698)
		(width 0.0889)
		(layer "B.Cu")
		(net "PD_CPU1_BIST_ENABLE")
	)
	(segment
		(start 99.620324 -227.326698)
		(end 99.60991 -227.320602)
		(width 0.0889)
		(layer "B.Cu")
		(net "PD_CPU1_BIST_ENABLE")
	)
	(segment
		(start 99.235514 -227.320602)
		(end 99.2251 -227.326698)
		(width 0.0889)
		(layer "B.Cu")
		(net "PD_CPU1_BIST_ENABLE")
	)
	(arc
		(start 97.730564 -227.320602)
		(mid 97.543366 -227.270459)
		(end 97.356168 -227.320602)
		(width 0.0889)
		(layer "B.Cu")
		(net "PD_CPU1_BIST_ENABLE")
	)
	(arc
		(start 88.897968 -227.320602)
		(mid 88.623769 -227.396437)
		(end 88.347296 -227.329238)
		(width 0.0889)
		(layer "B.Cu")
		(net "PD_CPU1_BIST_ENABLE")
	)
	(arc
		(start 92.657168 -227.320602)
		(mid 92.380355 -227.396472)
		(end 92.101924 -227.326698)
		(width 0.0889)
		(layer "B.Cu")
		(net "PD_CPU1_BIST_ENABLE")
	)
	(arc
		(start 101.437948 -227.295964)
		(mid 101.273852 -227.271617)
		(end 101.115368 -227.320602)
		(width 0.0889)
		(layer "B.Cu")
		(net "PD_CPU1_BIST_ENABLE")
	)
	(arc
		(start 100.175568 -227.320602)
		(mid 99.898755 -227.396472)
		(end 99.620324 -227.326698)
		(width 0.0889)
		(layer "B.Cu")
		(net "PD_CPU1_BIST_ENABLE")
	)
	(arc
		(start 85.51291 -227.320602)
		(mid 85.325712 -227.270459)
		(end 85.138514 -227.320602)
		(width 0.0889)
		(layer "B.Cu")
		(net "PD_CPU1_BIST_ENABLE")
	)
	(arc
		(start 93.971364 -227.320602)
		(mid 93.784166 -227.270459)
		(end 93.596968 -227.320602)
		(width 0.0889)
		(layer "B.Cu")
		(net "PD_CPU1_BIST_ENABLE")
	)
	(arc
		(start 87.39251 -227.320602)
		(mid 87.205312 -227.270459)
		(end 87.018114 -227.320602)
		(width 0.0889)
		(layer "B.Cu")
		(net "PD_CPU1_BIST_ENABLE")
	)
	(arc
		(start 90.212164 -227.320602)
		(mid 90.024966 -227.270459)
		(end 89.837768 -227.320602)
		(width 0.0889)
		(layer "B.Cu")
		(net "PD_CPU1_BIST_ENABLE")
	)
	(arc
		(start 85.138514 -227.320602)
		(mid 85.097705 -227.347774)
		(end 85.06079 -227.380038)
		(width 0.0889)
		(layer "B.Cu")
		(net "PD_CPU1_BIST_ENABLE")
	)
	(arc
		(start 94.536768 -227.320602)
		(mid 94.262569 -227.396437)
		(end 93.986096 -227.329238)
		(width 0.0889)
		(layer "B.Cu")
		(net "PD_CPU1_BIST_ENABLE")
	)
	(arc
		(start 101.115368 -227.320602)
		(mid 100.841169 -227.396437)
		(end 100.564696 -227.329238)
		(width 0.0889)
		(layer "B.Cu")
		(net "PD_CPU1_BIST_ENABLE")
	)
	(arc
		(start 96.416368 -227.320602)
		(mid 96.133666 -227.396378)
		(end 95.850964 -227.320602)
		(width 0.0889)
		(layer "B.Cu")
		(net "PD_CPU1_BIST_ENABLE")
	)
	(arc
		(start 88.332564 -227.320602)
		(mid 88.145366 -227.270459)
		(end 87.958168 -227.320602)
		(width 0.0889)
		(layer "B.Cu")
		(net "PD_CPU1_BIST_ENABLE")
	)
	(arc
		(start 95.476568 -227.320602)
		(mid 95.202369 -227.396437)
		(end 94.925896 -227.329238)
		(width 0.0889)
		(layer "B.Cu")
		(net "PD_CPU1_BIST_ENABLE")
	)
	(arc
		(start 99.60991 -227.320602)
		(mid 99.422712 -227.270459)
		(end 99.235514 -227.320602)
		(width 0.0889)
		(layer "B.Cu")
		(net "PD_CPU1_BIST_ENABLE")
	)
	(arc
		(start 87.947754 -227.326698)
		(mid 87.669322 -227.396544)
		(end 87.39251 -227.320602)
		(width 0.0889)
		(layer "B.Cu")
		(net "PD_CPU1_BIST_ENABLE")
	)
	(arc
		(start 89.837768 -227.320602)
		(mid 89.563569 -227.396437)
		(end 89.287096 -227.329238)
		(width 0.0889)
		(layer "B.Cu")
		(net "PD_CPU1_BIST_ENABLE")
	)
	(arc
		(start 97.356168 -227.320602)
		(mid 97.081969 -227.396437)
		(end 96.805496 -227.329238)
		(width 0.0889)
		(layer "B.Cu")
		(net "PD_CPU1_BIST_ENABLE")
	)
	(arc
		(start 100.549964 -227.320602)
		(mid 100.362766 -227.270459)
		(end 100.175568 -227.320602)
		(width 0.0889)
		(layer "B.Cu")
		(net "PD_CPU1_BIST_ENABLE")
	)
	(arc
		(start 96.790764 -227.320602)
		(mid 96.603566 -227.270459)
		(end 96.416368 -227.320602)
		(width 0.0889)
		(layer "B.Cu")
		(net "PD_CPU1_BIST_ENABLE")
	)
	(arc
		(start 98.295968 -227.320602)
		(mid 98.021769 -227.396437)
		(end 97.745296 -227.329238)
		(width 0.0889)
		(layer "B.Cu")
		(net "PD_CPU1_BIST_ENABLE")
	)
	(arc
		(start 93.596968 -227.320602)
		(mid 93.322769 -227.396437)
		(end 93.046296 -227.329238)
		(width 0.0889)
		(layer "B.Cu")
		(net "PD_CPU1_BIST_ENABLE")
	)
	(arc
		(start 86.452964 -227.320602)
		(mid 86.265766 -227.270459)
		(end 86.078568 -227.320602)
		(width 0.0889)
		(layer "B.Cu")
		(net "PD_CPU1_BIST_ENABLE")
	)
	(arc
		(start 91.7067 -227.326698)
		(mid 91.428522 -227.396421)
		(end 91.151964 -227.320602)
		(width 0.0889)
		(layer "B.Cu")
		(net "PD_CPU1_BIST_ENABLE")
	)
	(arc
		(start 99.2251 -227.326698)
		(mid 98.946922 -227.396421)
		(end 98.670364 -227.320602)
		(width 0.0889)
		(layer "B.Cu")
		(net "PD_CPU1_BIST_ENABLE")
	)
	(arc
		(start 95.850964 -227.320602)
		(mid 95.663766 -227.270459)
		(end 95.476568 -227.320602)
		(width 0.0889)
		(layer "B.Cu")
		(net "PD_CPU1_BIST_ENABLE")
	)
	(arc
		(start 87.018114 -227.320602)
		(mid 86.741555 -227.396345)
		(end 86.463378 -227.326698)
		(width 0.0889)
		(layer "B.Cu")
		(net "PD_CPU1_BIST_ENABLE")
	)
	(arc
		(start 86.068154 -227.326698)
		(mid 85.789722 -227.396544)
		(end 85.51291 -227.320602)
		(width 0.0889)
		(layer "B.Cu")
		(net "PD_CPU1_BIST_ENABLE")
	)
	(arc
		(start 91.151964 -227.320602)
		(mid 90.964766 -227.270459)
		(end 90.777568 -227.320602)
		(width 0.0889)
		(layer "B.Cu")
		(net "PD_CPU1_BIST_ENABLE")
	)
	(arc
		(start 93.031564 -227.320602)
		(mid 92.844366 -227.270459)
		(end 92.657168 -227.320602)
		(width 0.0889)
		(layer "B.Cu")
		(net "PD_CPU1_BIST_ENABLE")
	)
	(arc
		(start 90.777568 -227.320602)
		(mid 90.503369 -227.396437)
		(end 90.226896 -227.329238)
		(width 0.0889)
		(layer "B.Cu")
		(net "PD_CPU1_BIST_ENABLE")
	)
	(arc
		(start 92.09151 -227.320602)
		(mid 91.904312 -227.270459)
		(end 91.717114 -227.320602)
		(width 0.0889)
		(layer "B.Cu")
		(net "PD_CPU1_BIST_ENABLE")
	)
	(arc
		(start 98.670364 -227.320602)
		(mid 98.483166 -227.270459)
		(end 98.295968 -227.320602)
		(width 0.0889)
		(layer "B.Cu")
		(net "PD_CPU1_BIST_ENABLE")
	)
	(arc
		(start 94.911164 -227.320602)
		(mid 94.723966 -227.270459)
		(end 94.536768 -227.320602)
		(width 0.0889)
		(layer "B.Cu")
		(net "PD_CPU1_BIST_ENABLE")
	)
	(arc
		(start 89.272364 -227.320602)
		(mid 89.085166 -227.270459)
		(end 88.897968 -227.320602)
		(width 0.0889)
		(layer "B.Cu")
		(net "PD_CPU1_BIST_ENABLE")
	)
	(segment
		(start 368.03838 -229.808786)
		(end 368.038634 -229.808532)
		(width 0.12954)
		(layer "F.Cu")
		(net "PD_CPU0_TXT_PLTEN")
	)
	(segment
		(start 368.038634 -229.808532)
		(end 368.038634 -229.272846)
		(width 0.12954)
		(layer "F.Cu")
		(net "PD_CPU0_TXT_PLTEN")
	)
	(via
		(at 383.681478 -189.789308)
		(size 0.6604)
		(drill 0.3302)
		(layers "F.Cu" "B.Cu")
		(net "PD_CPU0_TXT_PLTEN")
	)
	(via
		(at 368.038634 -229.272846)
		(size 0.4572)
		(drill 0.2032)
		(layers "F.Cu" "B.Cu")
		(net "PD_CPU0_TXT_PLTEN")
	)
	(segment
		(start 373.879364 -229.588568)
		(end 373.864632 -229.597204)
		(width 0.0889)
		(layer "B.Cu")
		(net "PD_CPU0_TXT_PLTEN")
	)
	(segment
		(start 383.947924 -186.535314)
		(end 384.494786 -187.082176)
		(width 0.12954)
		(layer "B.Cu")
		(net "PD_CPU0_TXT_PLTEN")
	)
	(segment
		(start 382.77927 -186.538108)
		(end 381.608584 -186.538108)
		(width 0.12954)
		(layer "B.Cu")
		(net "PD_CPU0_TXT_PLTEN")
	)
	(segment
		(start 374.819164 -229.588568)
		(end 374.804432 -229.597204)
		(width 0.0889)
		(layer "B.Cu")
		(net "PD_CPU0_TXT_PLTEN")
	)
	(segment
		(start 384.494786 -187.082176)
		(end 384.494786 -188.237622)
		(width 0.12954)
		(layer "B.Cu")
		(net "PD_CPU0_TXT_PLTEN")
	)
	(segment
		(start 375.758964 -229.588568)
		(end 375.744232 -229.597204)
		(width 0.0889)
		(layer "B.Cu")
		(net "PD_CPU0_TXT_PLTEN")
	)
	(segment
		(start 369.216178 -228.89083)
		(end 368.720878 -228.89083)
		(width 0.0889)
		(layer "B.Cu")
		(net "PD_CPU0_TXT_PLTEN")
	)
	(segment
		(start 383.681478 -189.789308)
		(end 383.681478 -190.153036)
		(width 0.12954)
		(layer "B.Cu")
		(net "PD_CPU0_TXT_PLTEN")
	)
	(segment
		(start 392.072114 -200.387966)
		(end 392.072114 -224.277428)
		(width 0.12954)
		(layer "B.Cu")
		(net "PD_CPU0_TXT_PLTEN")
	)
	(segment
		(start 369.731036 -229.597204)
		(end 369.70843 -229.583996)
		(width 0.0889)
		(layer "B.Cu")
		(net "PD_CPU0_TXT_PLTEN")
	)
	(segment
		(start 371.999764 -229.588568)
		(end 371.985032 -229.597204)
		(width 0.0889)
		(layer "B.Cu")
		(net "PD_CPU0_TXT_PLTEN")
	)
	(segment
		(start 368.338862 -229.272846)
		(end 368.038634 -229.272846)
		(width 0.0889)
		(layer "B.Cu")
		(net "PD_CPU0_TXT_PLTEN")
	)
	(segment
		(start 383.681478 -190.153036)
		(end 383.338578 -190.495936)
		(width 0.12954)
		(layer "B.Cu")
		(net "PD_CPU0_TXT_PLTEN")
	)
	(segment
		(start 368.720878 -228.89083)
		(end 368.338862 -229.272846)
		(width 0.0889)
		(layer "B.Cu")
		(net "PD_CPU0_TXT_PLTEN")
	)
	(segment
		(start 386.025644 -194.341496)
		(end 392.072114 -200.387966)
		(width 0.12954)
		(layer "B.Cu")
		(net "PD_CPU0_TXT_PLTEN")
	)
	(segment
		(start 382.782064 -186.535314)
		(end 382.77927 -186.538108)
		(width 0.12954)
		(layer "B.Cu")
		(net "PD_CPU0_TXT_PLTEN")
	)
	(segment
		(start 370.115846 -229.591108)
		(end 370.105432 -229.597204)
		(width 0.0889)
		(layer "B.Cu")
		(net "PD_CPU0_TXT_PLTEN")
	)
	(segment
		(start 384.494786 -188.237622)
		(end 383.681478 -189.05093)
		(width 0.12954)
		(layer "B.Cu")
		(net "PD_CPU0_TXT_PLTEN")
	)
	(segment
		(start 384.52171 -229.296214)
		(end 384.280156 -229.537768)
		(width 0.0889)
		(layer "B.Cu")
		(net "PD_CPU0_TXT_PLTEN")
	)
	(segment
		(start 387.053328 -229.296214)
		(end 384.52171 -229.296214)
		(width 0.12954)
		(layer "B.Cu")
		(net "PD_CPU0_TXT_PLTEN")
	)
	(segment
		(start 383.681478 -189.05093)
		(end 383.681478 -189.789308)
		(width 0.12954)
		(layer "B.Cu")
		(net "PD_CPU0_TXT_PLTEN")
	)
	(segment
		(start 371.055392 -229.591108)
		(end 371.044978 -229.597204)
		(width 0.0889)
		(layer "B.Cu")
		(net "PD_CPU0_TXT_PLTEN")
	)
	(segment
		(start 377.633992 -229.591108)
		(end 377.623578 -229.597204)
		(width 0.0889)
		(layer "B.Cu")
		(net "PD_CPU0_TXT_PLTEN")
	)
	(segment
		(start 376.694446 -229.591108)
		(end 376.684032 -229.597204)
		(width 0.0889)
		(layer "B.Cu")
		(net "PD_CPU0_TXT_PLTEN")
	)
	(segment
		(start 378.578364 -229.588568)
		(end 378.563632 -229.597204)
		(width 0.0889)
		(layer "B.Cu")
		(net "PD_CPU0_TXT_PLTEN")
	)
	(segment
		(start 382.782064 -186.535314)
		(end 383.947924 -186.535314)
		(width 0.12954)
		(layer "B.Cu")
		(net "PD_CPU0_TXT_PLTEN")
	)
	(segment
		(start 392.072114 -224.277428)
		(end 387.053328 -229.296214)
		(width 0.12954)
		(layer "B.Cu")
		(net "PD_CPU0_TXT_PLTEN")
	)
	(segment
		(start 385.029964 -194.341496)
		(end 386.025644 -194.341496)
		(width 0.12954)
		(layer "B.Cu")
		(net "PD_CPU0_TXT_PLTEN")
	)
	(segment
		(start 369.433602 -229.108254)
		(end 369.216178 -228.89083)
		(width 0.0889)
		(layer "B.Cu")
		(net "PD_CPU0_TXT_PLTEN")
	)
	(segment
		(start 383.338578 -190.495936)
		(end 383.338578 -192.65011)
		(width 0.12954)
		(layer "B.Cu")
		(net "PD_CPU0_TXT_PLTEN")
	)
	(segment
		(start 383.338578 -192.65011)
		(end 385.029964 -194.341496)
		(width 0.12954)
		(layer "B.Cu")
		(net "PD_CPU0_TXT_PLTEN")
	)
	(segment
		(start 380.457964 -229.588568)
		(end 380.443232 -229.597204)
		(width 0.0889)
		(layer "B.Cu")
		(net "PD_CPU0_TXT_PLTEN")
	)
	(arc
		(start 381.948436 -229.597204)
		(mid 381.665734 -229.521428)
		(end 381.383032 -229.597204)
		(width 0.0889)
		(layer "B.Cu")
		(net "PD_CPU0_TXT_PLTEN")
	)
	(arc
		(start 377.623578 -229.597204)
		(mid 377.43638 -229.647347)
		(end 377.249182 -229.597204)
		(width 0.0889)
		(layer "B.Cu")
		(net "PD_CPU0_TXT_PLTEN")
	)
	(arc
		(start 378.189236 -229.597204)
		(mid 377.912423 -229.521334)
		(end 377.633992 -229.591108)
		(width 0.0889)
		(layer "B.Cu")
		(net "PD_CPU0_TXT_PLTEN")
	)
	(arc
		(start 384.280156 -229.537768)
		(mid 384.243246 -229.570039)
		(end 384.202432 -229.597204)
		(width 0.0889)
		(layer "B.Cu")
		(net "PD_CPU0_TXT_PLTEN")
	)
	(arc
		(start 371.044978 -229.597204)
		(mid 370.85778 -229.647347)
		(end 370.670582 -229.597204)
		(width 0.0889)
		(layer "B.Cu")
		(net "PD_CPU0_TXT_PLTEN")
	)
	(arc
		(start 375.369836 -229.597204)
		(mid 375.095637 -229.521369)
		(end 374.819164 -229.588568)
		(width 0.0889)
		(layer "B.Cu")
		(net "PD_CPU0_TXT_PLTEN")
	)
	(arc
		(start 382.888236 -229.597204)
		(mid 382.605534 -229.521428)
		(end 382.322832 -229.597204)
		(width 0.0889)
		(layer "B.Cu")
		(net "PD_CPU0_TXT_PLTEN")
	)
	(arc
		(start 373.490236 -229.597204)
		(mid 373.207534 -229.521428)
		(end 372.924832 -229.597204)
		(width 0.0889)
		(layer "B.Cu")
		(net "PD_CPU0_TXT_PLTEN")
	)
	(arc
		(start 374.430036 -229.597204)
		(mid 374.155837 -229.521369)
		(end 373.879364 -229.588568)
		(width 0.0889)
		(layer "B.Cu")
		(net "PD_CPU0_TXT_PLTEN")
	)
	(arc
		(start 370.105432 -229.597204)
		(mid 369.918234 -229.647347)
		(end 369.731036 -229.597204)
		(width 0.0889)
		(layer "B.Cu")
		(net "PD_CPU0_TXT_PLTEN")
	)
	(arc
		(start 380.068836 -229.597204)
		(mid 379.786134 -229.521428)
		(end 379.503432 -229.597204)
		(width 0.0889)
		(layer "B.Cu")
		(net "PD_CPU0_TXT_PLTEN")
	)
	(arc
		(start 376.309636 -229.597204)
		(mid 376.035437 -229.521369)
		(end 375.758964 -229.588568)
		(width 0.0889)
		(layer "B.Cu")
		(net "PD_CPU0_TXT_PLTEN")
	)
	(arc
		(start 383.828036 -229.597204)
		(mid 383.545334 -229.521428)
		(end 383.262632 -229.597204)
		(width 0.0889)
		(layer "B.Cu")
		(net "PD_CPU0_TXT_PLTEN")
	)
	(arc
		(start 378.563632 -229.597204)
		(mid 378.376434 -229.647347)
		(end 378.189236 -229.597204)
		(width 0.0889)
		(layer "B.Cu")
		(net "PD_CPU0_TXT_PLTEN")
	)
	(arc
		(start 372.550436 -229.597204)
		(mid 372.276237 -229.521369)
		(end 371.999764 -229.588568)
		(width 0.0889)
		(layer "B.Cu")
		(net "PD_CPU0_TXT_PLTEN")
	)
	(arc
		(start 370.670582 -229.597204)
		(mid 370.394023 -229.521461)
		(end 370.115846 -229.591108)
		(width 0.0889)
		(layer "B.Cu")
		(net "PD_CPU0_TXT_PLTEN")
	)
	(arc
		(start 384.202432 -229.597204)
		(mid 384.015234 -229.647347)
		(end 383.828036 -229.597204)
		(width 0.0889)
		(layer "B.Cu")
		(net "PD_CPU0_TXT_PLTEN")
	)
	(arc
		(start 374.804432 -229.597204)
		(mid 374.617234 -229.647347)
		(end 374.430036 -229.597204)
		(width 0.0889)
		(layer "B.Cu")
		(net "PD_CPU0_TXT_PLTEN")
	)
	(arc
		(start 379.129036 -229.597204)
		(mid 378.854837 -229.521369)
		(end 378.578364 -229.588568)
		(width 0.0889)
		(layer "B.Cu")
		(net "PD_CPU0_TXT_PLTEN")
	)
	(arc
		(start 375.744232 -229.597204)
		(mid 375.557034 -229.647347)
		(end 375.369836 -229.597204)
		(width 0.0889)
		(layer "B.Cu")
		(net "PD_CPU0_TXT_PLTEN")
	)
	(arc
		(start 369.70843 -229.583996)
		(mid 369.507324 -229.382936)
		(end 369.433602 -229.108254)
		(width 0.0889)
		(layer "B.Cu")
		(net "PD_CPU0_TXT_PLTEN")
	)
	(arc
		(start 381.383032 -229.597204)
		(mid 381.195834 -229.647347)
		(end 381.008636 -229.597204)
		(width 0.0889)
		(layer "B.Cu")
		(net "PD_CPU0_TXT_PLTEN")
	)
	(arc
		(start 379.503432 -229.597204)
		(mid 379.316234 -229.647347)
		(end 379.129036 -229.597204)
		(width 0.0889)
		(layer "B.Cu")
		(net "PD_CPU0_TXT_PLTEN")
	)
	(arc
		(start 376.684032 -229.597204)
		(mid 376.496834 -229.647347)
		(end 376.309636 -229.597204)
		(width 0.0889)
		(layer "B.Cu")
		(net "PD_CPU0_TXT_PLTEN")
	)
	(arc
		(start 381.008636 -229.597204)
		(mid 380.734437 -229.521369)
		(end 380.457964 -229.588568)
		(width 0.0889)
		(layer "B.Cu")
		(net "PD_CPU0_TXT_PLTEN")
	)
	(arc
		(start 371.985032 -229.597204)
		(mid 371.797834 -229.647347)
		(end 371.610636 -229.597204)
		(width 0.0889)
		(layer "B.Cu")
		(net "PD_CPU0_TXT_PLTEN")
	)
	(arc
		(start 371.610636 -229.597204)
		(mid 371.333823 -229.521334)
		(end 371.055392 -229.591108)
		(width 0.0889)
		(layer "B.Cu")
		(net "PD_CPU0_TXT_PLTEN")
	)
	(arc
		(start 372.924832 -229.597204)
		(mid 372.737634 -229.647347)
		(end 372.550436 -229.597204)
		(width 0.0889)
		(layer "B.Cu")
		(net "PD_CPU0_TXT_PLTEN")
	)
	(arc
		(start 373.864632 -229.597204)
		(mid 373.677434 -229.647347)
		(end 373.490236 -229.597204)
		(width 0.0889)
		(layer "B.Cu")
		(net "PD_CPU0_TXT_PLTEN")
	)
	(arc
		(start 383.262632 -229.597204)
		(mid 383.075434 -229.647347)
		(end 382.888236 -229.597204)
		(width 0.0889)
		(layer "B.Cu")
		(net "PD_CPU0_TXT_PLTEN")
	)
	(arc
		(start 377.249182 -229.597204)
		(mid 376.972623 -229.521461)
		(end 376.694446 -229.591108)
		(width 0.0889)
		(layer "B.Cu")
		(net "PD_CPU0_TXT_PLTEN")
	)
	(arc
		(start 380.443232 -229.597204)
		(mid 380.256034 -229.647347)
		(end 380.068836 -229.597204)
		(width 0.0889)
		(layer "B.Cu")
		(net "PD_CPU0_TXT_PLTEN")
	)
	(arc
		(start 382.322832 -229.597204)
		(mid 382.135634 -229.647347)
		(end 381.948436 -229.597204)
		(width 0.0889)
		(layer "B.Cu")
		(net "PD_CPU0_TXT_PLTEN")
	)
	(segment
		(start 364.27918 -230.900732)
		(end 364.279434 -230.900478)
		(width 0.12954)
		(layer "F.Cu")
		(net "PD_CPU0_ENH_MCECC_DIS")
	)
	(segment
		(start 364.27918 -231.436418)
		(end 364.27918 -230.900732)
		(width 0.12954)
		(layer "F.Cu")
		(net "PD_CPU0_ENH_MCECC_DIS")
	)
	(via
		(at 375.9835 -192.469262)
		(size 0.6604)
		(drill 0.3302)
		(layers "F.Cu" "B.Cu")
		(net "PD_CPU0_ENH_MCECC_DIS")
	)
	(via
		(at 364.279434 -230.900478)
		(size 0.4572)
		(drill 0.2032)
		(layers "F.Cu" "B.Cu")
		(net "PD_CPU0_ENH_MCECC_DIS")
	)
	(segment
		(start 371.059964 -226.33305)
		(end 371.045232 -226.341686)
		(width 0.0889)
		(layer "B.Cu")
		(net "PD_CPU0_ENH_MCECC_DIS")
	)
	(segment
		(start 380.457964 -226.33305)
		(end 380.443232 -226.341686)
		(width 0.0889)
		(layer "B.Cu")
		(net "PD_CPU0_ENH_MCECC_DIS")
	)
	(segment
		(start 366.824768 -227.150422)
		(end 366.815878 -227.155502)
		(width 0.0889)
		(layer "B.Cu")
		(net "PD_CPU0_ENH_MCECC_DIS")
	)
	(segment
		(start 388.692644 -201.63028)
		(end 388.692644 -223.468438)
		(width 0.12954)
		(layer "B.Cu")
		(net "PD_CPU0_ENH_MCECC_DIS")
	)
	(segment
		(start 385.023614 -197.96125)
		(end 388.692644 -201.63028)
		(width 0.12954)
		(layer "B.Cu")
		(net "PD_CPU0_ENH_MCECC_DIS")
	)
	(segment
		(start 365.274098 -229.70236)
		(end 364.569502 -229.70236)
		(width 0.0889)
		(layer "B.Cu")
		(net "PD_CPU0_ENH_MCECC_DIS")
	)
	(segment
		(start 379.215396 -193.35623)
		(end 383.820416 -197.96125)
		(width 0.12954)
		(layer "B.Cu")
		(net "PD_CPU0_ENH_MCECC_DIS")
	)
	(segment
		(start 382.337564 -226.33305)
		(end 382.322832 -226.341686)
		(width 0.0889)
		(layer "B.Cu")
		(net "PD_CPU0_ENH_MCECC_DIS")
	)
	(segment
		(start 366.06353 -228.444806)
		(end 366.06353 -228.45903)
		(width 0.0889)
		(layer "B.Cu")
		(net "PD_CPU0_ENH_MCECC_DIS")
	)
	(segment
		(start 366.533684 -227.629466)
		(end 366.533684 -227.64496)
		(width 0.0889)
		(layer "B.Cu")
		(net "PD_CPU0_ENH_MCECC_DIS")
	)
	(segment
		(start 388.692644 -223.468438)
		(end 386.505958 -225.655124)
		(width 0.12954)
		(layer "B.Cu")
		(net "PD_CPU0_ENH_MCECC_DIS")
	)
	(segment
		(start 368.240564 -226.33305)
		(end 368.225832 -226.341686)
		(width 0.0889)
		(layer "B.Cu")
		(net "PD_CPU0_ENH_MCECC_DIS")
	)
	(segment
		(start 375.9835 -192.469262)
		(end 376.870468 -193.35623)
		(width 0.12954)
		(layer "B.Cu")
		(net "PD_CPU0_ENH_MCECC_DIS")
	)
	(segment
		(start 376.870468 -193.35623)
		(end 379.215396 -193.35623)
		(width 0.12954)
		(layer "B.Cu")
		(net "PD_CPU0_ENH_MCECC_DIS")
	)
	(segment
		(start 385.019296 -225.655124)
		(end 384.92049 -225.655124)
		(width 0.0889)
		(layer "B.Cu")
		(net "PD_CPU0_ENH_MCECC_DIS")
	)
	(segment
		(start 365.294164 -229.682294)
		(end 365.274098 -229.70236)
		(width 0.0889)
		(layer "B.Cu")
		(net "PD_CPU0_ENH_MCECC_DIS")
	)
	(segment
		(start 379.518164 -226.33305)
		(end 379.503432 -226.341686)
		(width 0.0889)
		(layer "B.Cu")
		(net "PD_CPU0_ENH_MCECC_DIS")
	)
	(segment
		(start 365.884968 -228.778308)
		(end 365.876078 -228.783388)
		(width 0.0889)
		(layer "B.Cu")
		(net "PD_CPU0_ENH_MCECC_DIS")
	)
	(segment
		(start 372.939564 -226.33305)
		(end 372.924832 -226.341686)
		(width 0.0889)
		(layer "B.Cu")
		(net "PD_CPU0_ENH_MCECC_DIS")
	)
	(segment
		(start 375.578624 -191.103504)
		(end 375.578624 -192.064386)
		(width 0.12954)
		(layer "B.Cu")
		(net "PD_CPU0_ENH_MCECC_DIS")
	)
	(segment
		(start 376.698764 -226.33305)
		(end 376.684032 -226.341686)
		(width 0.0889)
		(layer "B.Cu")
		(net "PD_CPU0_ENH_MCECC_DIS")
	)
	(segment
		(start 370.120164 -226.33305)
		(end 370.105432 -226.341686)
		(width 0.0889)
		(layer "B.Cu")
		(net "PD_CPU0_ENH_MCECC_DIS")
	)
	(segment
		(start 377.638564 -226.33305)
		(end 377.623832 -226.341686)
		(width 0.0889)
		(layer "B.Cu")
		(net "PD_CPU0_ENH_MCECC_DIS")
	)
	(segment
		(start 367.286032 -226.341686)
		(end 367.27384 -226.348798)
		(width 0.0889)
		(layer "B.Cu")
		(net "PD_CPU0_ENH_MCECC_DIS")
	)
	(segment
		(start 365.415322 -229.592124)
		(end 365.406432 -229.597204)
		(width 0.0889)
		(layer "B.Cu")
		(net "PD_CPU0_ENH_MCECC_DIS")
	)
	(segment
		(start 366.355122 -227.964238)
		(end 366.346232 -227.969318)
		(width 0.0889)
		(layer "B.Cu")
		(net "PD_CPU0_ENH_MCECC_DIS")
	)
	(segment
		(start 383.820416 -197.96125)
		(end 385.023614 -197.96125)
		(width 0.12954)
		(layer "B.Cu")
		(net "PD_CPU0_ENH_MCECC_DIS")
	)
	(segment
		(start 365.406432 -229.597204)
		(end 365.400336 -229.60076)
		(width 0.0889)
		(layer "B.Cu")
		(net "PD_CPU0_ENH_MCECC_DIS")
	)
	(segment
		(start 375.578624 -192.064386)
		(end 375.9835 -192.469262)
		(width 0.12954)
		(layer "B.Cu")
		(net "PD_CPU0_ENH_MCECC_DIS")
	)
	(segment
		(start 364.279434 -229.992428)
		(end 364.279434 -230.900478)
		(width 0.0889)
		(layer "B.Cu")
		(net "PD_CPU0_ENH_MCECC_DIS")
	)
	(segment
		(start 373.879364 -226.33305)
		(end 373.864632 -226.341686)
		(width 0.0889)
		(layer "B.Cu")
		(net "PD_CPU0_ENH_MCECC_DIS")
	)
	(segment
		(start 384.897884 -225.664522)
		(end 384.280156 -226.28225)
		(width 0.0889)
		(layer "B.Cu")
		(net "PD_CPU0_ENH_MCECC_DIS")
	)
	(segment
		(start 364.569502 -229.70236)
		(end 364.279434 -229.992428)
		(width 0.0889)
		(layer "B.Cu")
		(net "PD_CPU0_ENH_MCECC_DIS")
	)
	(segment
		(start 386.505958 -225.655124)
		(end 385.019296 -225.655124)
		(width 0.12954)
		(layer "B.Cu")
		(net "PD_CPU0_ENH_MCECC_DIS")
	)
	(segment
		(start 365.593884 -229.257352)
		(end 365.593884 -229.272846)
		(width 0.0889)
		(layer "B.Cu")
		(net "PD_CPU0_ENH_MCECC_DIS")
	)
	(arc
		(start 372.550436 -226.341686)
		(mid 372.267734 -226.26591)
		(end 371.985032 -226.341686)
		(width 0.0889)
		(layer "B.Cu")
		(net "PD_CPU0_ENH_MCECC_DIS")
	)
	(arc
		(start 374.430036 -226.341686)
		(mid 374.155837 -226.265851)
		(end 373.879364 -226.33305)
		(width 0.0889)
		(layer "B.Cu")
		(net "PD_CPU0_ENH_MCECC_DIS")
	)
	(arc
		(start 366.815878 -227.155502)
		(mid 366.613055 -227.355733)
		(end 366.533684 -227.629466)
		(width 0.0889)
		(layer "B.Cu")
		(net "PD_CPU0_ENH_MCECC_DIS")
	)
	(arc
		(start 366.533684 -227.64496)
		(mid 366.486005 -227.82786)
		(end 366.355122 -227.964238)
		(width 0.0889)
		(layer "B.Cu")
		(net "PD_CPU0_ENH_MCECC_DIS")
	)
	(arc
		(start 373.864632 -226.341686)
		(mid 373.677434 -226.391829)
		(end 373.490236 -226.341686)
		(width 0.0889)
		(layer "B.Cu")
		(net "PD_CPU0_ENH_MCECC_DIS")
	)
	(arc
		(start 383.828036 -226.341686)
		(mid 383.545334 -226.26591)
		(end 383.262632 -226.341686)
		(width 0.0889)
		(layer "B.Cu")
		(net "PD_CPU0_ENH_MCECC_DIS")
	)
	(arc
		(start 368.791236 -226.341686)
		(mid 368.517037 -226.265851)
		(end 368.240564 -226.33305)
		(width 0.0889)
		(layer "B.Cu")
		(net "PD_CPU0_ENH_MCECC_DIS")
	)
	(arc
		(start 365.593884 -229.272846)
		(mid 365.546205 -229.455746)
		(end 365.415322 -229.592124)
		(width 0.0889)
		(layer "B.Cu")
		(net "PD_CPU0_ENH_MCECC_DIS")
	)
	(arc
		(start 369.165632 -226.341686)
		(mid 368.978434 -226.391829)
		(end 368.791236 -226.341686)
		(width 0.0889)
		(layer "B.Cu")
		(net "PD_CPU0_ENH_MCECC_DIS")
	)
	(arc
		(start 383.262632 -226.341686)
		(mid 383.075434 -226.391829)
		(end 382.888236 -226.341686)
		(width 0.0889)
		(layer "B.Cu")
		(net "PD_CPU0_ENH_MCECC_DIS")
	)
	(arc
		(start 382.322832 -226.341686)
		(mid 382.135634 -226.391829)
		(end 381.948436 -226.341686)
		(width 0.0889)
		(layer "B.Cu")
		(net "PD_CPU0_ENH_MCECC_DIS")
	)
	(arc
		(start 377.623832 -226.341686)
		(mid 377.436634 -226.391829)
		(end 377.249436 -226.341686)
		(width 0.0889)
		(layer "B.Cu")
		(net "PD_CPU0_ENH_MCECC_DIS")
	)
	(arc
		(start 373.490236 -226.341686)
		(mid 373.216037 -226.265851)
		(end 372.939564 -226.33305)
		(width 0.0889)
		(layer "B.Cu")
		(net "PD_CPU0_ENH_MCECC_DIS")
	)
	(arc
		(start 365.876078 -228.783388)
		(mid 365.673255 -228.983619)
		(end 365.593884 -229.257352)
		(width 0.0889)
		(layer "B.Cu")
		(net "PD_CPU0_ENH_MCECC_DIS")
	)
	(arc
		(start 379.503432 -226.341686)
		(mid 379.316234 -226.391829)
		(end 379.129036 -226.341686)
		(width 0.0889)
		(layer "B.Cu")
		(net "PD_CPU0_ENH_MCECC_DIS")
	)
	(arc
		(start 381.948436 -226.341686)
		(mid 381.665734 -226.26591)
		(end 381.383032 -226.341686)
		(width 0.0889)
		(layer "B.Cu")
		(net "PD_CPU0_ENH_MCECC_DIS")
	)
	(arc
		(start 372.924832 -226.341686)
		(mid 372.737634 -226.391829)
		(end 372.550436 -226.341686)
		(width 0.0889)
		(layer "B.Cu")
		(net "PD_CPU0_ENH_MCECC_DIS")
	)
	(arc
		(start 377.249436 -226.341686)
		(mid 376.975237 -226.265851)
		(end 376.698764 -226.33305)
		(width 0.0889)
		(layer "B.Cu")
		(net "PD_CPU0_ENH_MCECC_DIS")
	)
	(arc
		(start 367.00333 -226.831144)
		(mid 366.955651 -227.014044)
		(end 366.824768 -227.150422)
		(width 0.0889)
		(layer "B.Cu")
		(net "PD_CPU0_ENH_MCECC_DIS")
	)
	(arc
		(start 378.189236 -226.341686)
		(mid 377.915037 -226.265851)
		(end 377.638564 -226.33305)
		(width 0.0889)
		(layer "B.Cu")
		(net "PD_CPU0_ENH_MCECC_DIS")
	)
	(arc
		(start 380.443232 -226.341686)
		(mid 380.256034 -226.391829)
		(end 380.068836 -226.341686)
		(width 0.0889)
		(layer "B.Cu")
		(net "PD_CPU0_ENH_MCECC_DIS")
	)
	(arc
		(start 369.731036 -226.341686)
		(mid 369.448334 -226.26591)
		(end 369.165632 -226.341686)
		(width 0.0889)
		(layer "B.Cu")
		(net "PD_CPU0_ENH_MCECC_DIS")
	)
	(arc
		(start 380.068836 -226.341686)
		(mid 379.794637 -226.265851)
		(end 379.518164 -226.33305)
		(width 0.0889)
		(layer "B.Cu")
		(net "PD_CPU0_ENH_MCECC_DIS")
	)
	(arc
		(start 366.06353 -228.45903)
		(mid 366.015851 -228.64193)
		(end 365.884968 -228.778308)
		(width 0.0889)
		(layer "B.Cu")
		(net "PD_CPU0_ENH_MCECC_DIS")
	)
	(arc
		(start 367.851436 -226.341686)
		(mid 367.568734 -226.26591)
		(end 367.286032 -226.341686)
		(width 0.0889)
		(layer "B.Cu")
		(net "PD_CPU0_ENH_MCECC_DIS")
	)
	(arc
		(start 376.309636 -226.341686)
		(mid 376.026934 -226.26591)
		(end 375.744232 -226.341686)
		(width 0.0889)
		(layer "B.Cu")
		(net "PD_CPU0_ENH_MCECC_DIS")
	)
	(arc
		(start 384.92049 -225.655124)
		(mid 384.908257 -225.657575)
		(end 384.897884 -225.664522)
		(width 0.0889)
		(layer "B.Cu")
		(net "PD_CPU0_ENH_MCECC_DIS")
	)
	(arc
		(start 370.670836 -226.341686)
		(mid 370.396637 -226.265851)
		(end 370.120164 -226.33305)
		(width 0.0889)
		(layer "B.Cu")
		(net "PD_CPU0_ENH_MCECC_DIS")
	)
	(arc
		(start 381.383032 -226.341686)
		(mid 381.195834 -226.391829)
		(end 381.008636 -226.341686)
		(width 0.0889)
		(layer "B.Cu")
		(net "PD_CPU0_ENH_MCECC_DIS")
	)
	(arc
		(start 367.27384 -226.348798)
		(mid 367.075612 -226.554646)
		(end 367.00333 -226.831144)
		(width 0.0889)
		(layer "B.Cu")
		(net "PD_CPU0_ENH_MCECC_DIS")
	)
	(arc
		(start 366.346232 -227.969318)
		(mid 366.142751 -228.170122)
		(end 366.06353 -228.444806)
		(width 0.0889)
		(layer "B.Cu")
		(net "PD_CPU0_ENH_MCECC_DIS")
	)
	(arc
		(start 375.744232 -226.341686)
		(mid 375.557034 -226.391829)
		(end 375.369836 -226.341686)
		(width 0.0889)
		(layer "B.Cu")
		(net "PD_CPU0_ENH_MCECC_DIS")
	)
	(arc
		(start 371.985032 -226.341686)
		(mid 371.797834 -226.391829)
		(end 371.610636 -226.341686)
		(width 0.0889)
		(layer "B.Cu")
		(net "PD_CPU0_ENH_MCECC_DIS")
	)
	(arc
		(start 378.563632 -226.341686)
		(mid 378.376434 -226.391829)
		(end 378.189236 -226.341686)
		(width 0.0889)
		(layer "B.Cu")
		(net "PD_CPU0_ENH_MCECC_DIS")
	)
	(arc
		(start 371.610636 -226.341686)
		(mid 371.336437 -226.265851)
		(end 371.059964 -226.33305)
		(width 0.0889)
		(layer "B.Cu")
		(net "PD_CPU0_ENH_MCECC_DIS")
	)
	(arc
		(start 384.202432 -226.341686)
		(mid 384.015234 -226.391829)
		(end 383.828036 -226.341686)
		(width 0.0889)
		(layer "B.Cu")
		(net "PD_CPU0_ENH_MCECC_DIS")
	)
	(arc
		(start 375.369836 -226.341686)
		(mid 375.087134 -226.26591)
		(end 374.804432 -226.341686)
		(width 0.0889)
		(layer "B.Cu")
		(net "PD_CPU0_ENH_MCECC_DIS")
	)
	(arc
		(start 368.225832 -226.341686)
		(mid 368.038634 -226.391829)
		(end 367.851436 -226.341686)
		(width 0.0889)
		(layer "B.Cu")
		(net "PD_CPU0_ENH_MCECC_DIS")
	)
	(arc
		(start 376.684032 -226.341686)
		(mid 376.496834 -226.391829)
		(end 376.309636 -226.341686)
		(width 0.0889)
		(layer "B.Cu")
		(net "PD_CPU0_ENH_MCECC_DIS")
	)
	(arc
		(start 371.045232 -226.341686)
		(mid 370.858034 -226.391829)
		(end 370.670836 -226.341686)
		(width 0.0889)
		(layer "B.Cu")
		(net "PD_CPU0_ENH_MCECC_DIS")
	)
	(arc
		(start 384.280156 -226.28225)
		(mid 384.243246 -226.314521)
		(end 384.202432 -226.341686)
		(width 0.0889)
		(layer "B.Cu")
		(net "PD_CPU0_ENH_MCECC_DIS")
	)
	(arc
		(start 379.129036 -226.341686)
		(mid 378.846334 -226.26591)
		(end 378.563632 -226.341686)
		(width 0.0889)
		(layer "B.Cu")
		(net "PD_CPU0_ENH_MCECC_DIS")
	)
	(arc
		(start 370.105432 -226.341686)
		(mid 369.918234 -226.391829)
		(end 369.731036 -226.341686)
		(width 0.0889)
		(layer "B.Cu")
		(net "PD_CPU0_ENH_MCECC_DIS")
	)
	(arc
		(start 365.400336 -229.60076)
		(mid 365.344831 -229.638376)
		(end 365.294164 -229.682294)
		(width 0.0889)
		(layer "B.Cu")
		(net "PD_CPU0_ENH_MCECC_DIS")
	)
	(arc
		(start 382.888236 -226.341686)
		(mid 382.614037 -226.265851)
		(end 382.337564 -226.33305)
		(width 0.0889)
		(layer "B.Cu")
		(net "PD_CPU0_ENH_MCECC_DIS")
	)
	(arc
		(start 381.008636 -226.341686)
		(mid 380.734437 -226.265851)
		(end 380.457964 -226.33305)
		(width 0.0889)
		(layer "B.Cu")
		(net "PD_CPU0_ENH_MCECC_DIS")
	)
	(arc
		(start 374.804432 -226.341686)
		(mid 374.617234 -226.391829)
		(end 374.430036 -226.341686)
		(width 0.0889)
		(layer "B.Cu")
		(net "PD_CPU0_ENH_MCECC_DIS")
	)
	(segment
		(start 350.652334 -227.367084)
		(end 350.652334 -226.831398)
		(width 0.12954)
		(layer "F.Cu")
		(net "PD_CPU0_DMIMODE_OVERRIDE")
	)
	(segment
		(start 350.652334 -226.831398)
		(end 350.65208 -226.831144)
		(width 0.12954)
		(layer "F.Cu")
		(net "PD_CPU0_DMIMODE_OVERRIDE")
	)
	(via
		(at 350.65208 -226.831144)
		(size 0.4572)
		(drill 0.2032)
		(layers "F.Cu" "B.Cu")
		(net "PD_CPU0_DMIMODE_OVERRIDE")
	)
	(via
		(at 329.513692 -200.909428)
		(size 0.508)
		(drill 0.254)
		(layers "F.Cu" "B.Cu")
		(net "PD_CPU0_DMIMODE_OVERRIDE")
	)
	(segment
		(start 328.137266 -201.35342)
		(end 327.674986 -200.89114)
		(width 0.12954)
		(layer "B.Cu")
		(net "PD_CPU0_DMIMODE_OVERRIDE")
	)
	(segment
		(start 328.913998 -191.991234)
		(end 328.913998 -191.14516)
		(width 0.12954)
		(layer "B.Cu")
		(net "PD_CPU0_DMIMODE_OVERRIDE")
	)
	(segment
		(start 329.513692 -200.909428)
		(end 329.0697 -201.35342)
		(width 0.12954)
		(layer "B.Cu")
		(net "PD_CPU0_DMIMODE_OVERRIDE")
	)
	(segment
		(start 327.674986 -200.89114)
		(end 327.674986 -193.230246)
		(width 0.12954)
		(layer "B.Cu")
		(net "PD_CPU0_DMIMODE_OVERRIDE")
	)
	(segment
		(start 327.674986 -193.230246)
		(end 328.913998 -191.991234)
		(width 0.12954)
		(layer "B.Cu")
		(net "PD_CPU0_DMIMODE_OVERRIDE")
	)
	(segment
		(start 329.0697 -201.35342)
		(end 328.137266 -201.35342)
		(width 0.12954)
		(layer "B.Cu")
		(net "PD_CPU0_DMIMODE_OVERRIDE")
	)
	(segment
		(start 336.180684 -221.956376)
		(end 336.180684 -221.937834)
		(width 0.0889)
		(layer "In4.Cu")
		(net "PD_CPU0_DMIMODE_OVERRIDE")
	)
	(segment
		(start 329.513692 -201.793856)
		(end 329.513692 -200.909428)
		(width 0.127)
		(layer "In4.Cu")
		(net "PD_CPU0_DMIMODE_OVERRIDE")
	)
	(segment
		(start 339.469984 -224.389442)
		(end 339.469984 -224.379536)
		(width 0.0889)
		(layer "In4.Cu")
		(net "PD_CPU0_DMIMODE_OVERRIDE")
	)
	(segment
		(start 339.187536 -223.899984)
		(end 339.178646 -223.894904)
		(width 0.0889)
		(layer "In4.Cu")
		(net "PD_CPU0_DMIMODE_OVERRIDE")
	)
	(segment
		(start 341.537036 -226.341686)
		(end 341.528146 -226.336606)
		(width 0.0889)
		(layer "In4.Cu")
		(net "PD_CPU0_DMIMODE_OVERRIDE")
	)
	(segment
		(start 342.946482 -227.155502)
		(end 342.93175 -227.146866)
		(width 0.0889)
		(layer "In4.Cu")
		(net "PD_CPU0_DMIMODE_OVERRIDE")
	)
	(segment
		(start 333.10195 -220.219778)
		(end 329.452478 -216.570306)
		(width 0.127)
		(layer "In4.Cu")
		(net "PD_CPU0_DMIMODE_OVERRIDE")
	)
	(segment
		(start 348.504764 -227.960682)
		(end 348.490032 -227.969318)
		(width 0.0889)
		(layer "In4.Cu")
		(net "PD_CPU0_DMIMODE_OVERRIDE")
	)
	(segment
		(start 329.452478 -216.570306)
		(end 329.452478 -201.85507)
		(width 0.127)
		(layer "In4.Cu")
		(net "PD_CPU0_DMIMODE_OVERRIDE")
	)
	(segment
		(start 337.313778 -222.275654)
		(end 337.307682 -222.272098)
		(width 0.0889)
		(layer "In4.Cu")
		(net "PD_CPU0_DMIMODE_OVERRIDE")
	)
	(segment
		(start 343.805764 -227.960682)
		(end 343.791032 -227.969318)
		(width 0.0889)
		(layer "In4.Cu")
		(net "PD_CPU0_DMIMODE_OVERRIDE")
	)
	(segment
		(start 339.93963 -225.203258)
		(end 339.93963 -225.187764)
		(width 0.0889)
		(layer "In4.Cu")
		(net "PD_CPU0_DMIMODE_OVERRIDE")
	)
	(segment
		(start 335.615534 -221.38259)
		(end 335.510378 -221.38259)
		(width 0.0889)
		(layer "In4.Cu")
		(net "PD_CPU0_DMIMODE_OVERRIDE")
	)
	(segment
		(start 347.560392 -227.963222)
		(end 347.549978 -227.969318)
		(width 0.0889)
		(layer "In4.Cu")
		(net "PD_CPU0_DMIMODE_OVERRIDE")
	)
	(segment
		(start 349.617284 -227.629466)
		(end 349.617284 -227.64496)
		(width 0.0889)
		(layer "In4.Cu")
		(net "PD_CPU0_DMIMODE_OVERRIDE")
	)
	(segment
		(start 341.349584 -226.017328)
		(end 341.349584 -226.003104)
		(width 0.0889)
		(layer "In4.Cu")
		(net "PD_CPU0_DMIMODE_OVERRIDE")
	)
	(segment
		(start 340.127082 -225.527616)
		(end 340.118192 -225.522536)
		(width 0.0889)
		(layer "In4.Cu")
		(net "PD_CPU0_DMIMODE_OVERRIDE")
	)
	(segment
		(start 350.464882 -227.155502)
		(end 350.45015 -227.146866)
		(width 0.0889)
		(layer "In4.Cu")
		(net "PD_CPU0_DMIMODE_OVERRIDE")
	)
	(segment
		(start 334.748378 -220.9419)
		(end 334.601058 -220.79458)
		(width 0.0889)
		(layer "In4.Cu")
		(net "PD_CPU0_DMIMODE_OVERRIDE")
	)
	(segment
		(start 339.000084 -223.575626)
		(end 339.000084 -223.561402)
		(width 0.0889)
		(layer "In4.Cu")
		(net "PD_CPU0_DMIMODE_OVERRIDE")
	)
	(segment
		(start 350.808544 -227.102162)
		(end 350.787462 -227.18014)
		(width 0.0889)
		(layer "In4.Cu")
		(net "PD_CPU0_DMIMODE_OVERRIDE")
	)
	(segment
		(start 338.166964 -223.077278)
		(end 338.152232 -223.085914)
		(width 0.0889)
		(layer "In4.Cu")
		(net "PD_CPU0_DMIMODE_OVERRIDE")
	)
	(segment
		(start 344.745564 -227.960682)
		(end 344.730832 -227.969318)
		(width 0.0889)
		(layer "In4.Cu")
		(net "PD_CPU0_DMIMODE_OVERRIDE")
	)
	(segment
		(start 341.066882 -225.527616)
		(end 341.05215 -225.51898)
		(width 0.0889)
		(layer "In4.Cu")
		(net "PD_CPU0_DMIMODE_OVERRIDE")
	)
	(segment
		(start 339.657436 -224.7138)
		(end 339.648546 -224.70872)
		(width 0.0889)
		(layer "In4.Cu")
		(net "PD_CPU0_DMIMODE_OVERRIDE")
	)
	(segment
		(start 329.452478 -201.85507)
		(end 329.513692 -201.793856)
		(width 0.127)
		(layer "In4.Cu")
		(net "PD_CPU0_DMIMODE_OVERRIDE")
	)
	(segment
		(start 335.069688 -220.9419)
		(end 334.748378 -220.9419)
		(width 0.0889)
		(layer "In4.Cu")
		(net "PD_CPU0_DMIMODE_OVERRIDE")
	)
	(segment
		(start 334.601058 -220.79458)
		(end 334.026256 -220.219778)
		(width 0.127)
		(layer "In4.Cu")
		(net "PD_CPU0_DMIMODE_OVERRIDE")
	)
	(segment
		(start 337.307682 -222.272098)
		(end 337.29295 -222.263462)
		(width 0.0889)
		(layer "In4.Cu")
		(net "PD_CPU0_DMIMODE_OVERRIDE")
	)
	(segment
		(start 343.416636 -227.969318)
		(end 343.407746 -227.964238)
		(width 0.0889)
		(layer "In4.Cu")
		(net "PD_CPU0_DMIMODE_OVERRIDE")
	)
	(segment
		(start 337.777836 -223.085914)
		(end 337.768946 -223.080834)
		(width 0.0889)
		(layer "In4.Cu")
		(net "PD_CPU0_DMIMODE_OVERRIDE")
	)
	(segment
		(start 335.510378 -221.38259)
		(end 335.069688 -220.9419)
		(width 0.0889)
		(layer "In4.Cu")
		(net "PD_CPU0_DMIMODE_OVERRIDE")
	)
	(segment
		(start 341.819484 -226.83978)
		(end 341.819484 -226.821238)
		(width 0.0889)
		(layer "In4.Cu")
		(net "PD_CPU0_DMIMODE_OVERRIDE")
	)
	(segment
		(start 334.026256 -220.219778)
		(end 333.10195 -220.219778)
		(width 0.127)
		(layer "In4.Cu")
		(net "PD_CPU0_DMIMODE_OVERRIDE")
	)
	(segment
		(start 342.952578 -227.159058)
		(end 342.946482 -227.155502)
		(width 0.0889)
		(layer "In4.Cu")
		(net "PD_CPU0_DMIMODE_OVERRIDE")
	)
	(segment
		(start 349.11919 -228.006148)
		(end 349.055436 -227.969318)
		(width 0.0889)
		(layer "In4.Cu")
		(net "PD_CPU0_DMIMODE_OVERRIDE")
	)
	(segment
		(start 350.65208 -226.831144)
		(end 350.808544 -227.102162)
		(width 0.0889)
		(layer "In4.Cu")
		(net "PD_CPU0_DMIMODE_OVERRIDE")
	)
	(segment
		(start 346.620846 -227.963222)
		(end 346.610432 -227.969318)
		(width 0.0889)
		(layer "In4.Cu")
		(net "PD_CPU0_DMIMODE_OVERRIDE")
	)
	(arc
		(start 349.617284 -227.64496)
		(mid 349.569605 -227.82786)
		(end 349.438722 -227.964238)
		(width 0.0889)
		(layer "In4.Cu")
		(net "PD_CPU0_DMIMODE_OVERRIDE")
	)
	(arc
		(start 339.648546 -224.70872)
		(mid 339.517632 -224.57236)
		(end 339.469984 -224.389442)
		(width 0.0889)
		(layer "In4.Cu")
		(net "PD_CPU0_DMIMODE_OVERRIDE")
	)
	(arc
		(start 339.000084 -223.561402)
		(mid 338.920943 -223.286779)
		(end 338.717636 -223.085914)
		(width 0.0889)
		(layer "In4.Cu")
		(net "PD_CPU0_DMIMODE_OVERRIDE")
	)
	(arc
		(start 341.819484 -226.821238)
		(mid 341.741373 -226.544289)
		(end 341.537036 -226.341686)
		(width 0.0889)
		(layer "In4.Cu")
		(net "PD_CPU0_DMIMODE_OVERRIDE")
	)
	(arc
		(start 340.118192 -225.522536)
		(mid 339.987278 -225.386176)
		(end 339.93963 -225.203258)
		(width 0.0889)
		(layer "In4.Cu")
		(net "PD_CPU0_DMIMODE_OVERRIDE")
	)
	(arc
		(start 343.229184 -227.64496)
		(mid 343.155193 -227.365394)
		(end 342.952578 -227.159058)
		(width 0.0889)
		(layer "In4.Cu")
		(net "PD_CPU0_DMIMODE_OVERRIDE")
	)
	(arc
		(start 336.742278 -222.272098)
		(mid 336.55508 -222.322241)
		(end 336.367882 -222.272098)
		(width 0.0889)
		(layer "In4.Cu")
		(net "PD_CPU0_DMIMODE_OVERRIDE")
	)
	(arc
		(start 341.05215 -225.51898)
		(mid 340.775709 -225.451814)
		(end 340.501478 -225.527616)
		(width 0.0889)
		(layer "In4.Cu")
		(net "PD_CPU0_DMIMODE_OVERRIDE")
	)
	(arc
		(start 338.152232 -223.085914)
		(mid 337.965034 -223.136057)
		(end 337.777836 -223.085914)
		(width 0.0889)
		(layer "In4.Cu")
		(net "PD_CPU0_DMIMODE_OVERRIDE")
	)
	(arc
		(start 350.787462 -227.18014)
		(mid 350.623366 -227.204487)
		(end 350.464882 -227.155502)
		(width 0.0889)
		(layer "In4.Cu")
		(net "PD_CPU0_DMIMODE_OVERRIDE")
	)
	(arc
		(start 337.768946 -223.080834)
		(mid 337.638032 -222.944474)
		(end 337.590384 -222.761556)
		(width 0.0889)
		(layer "In4.Cu")
		(net "PD_CPU0_DMIMODE_OVERRIDE")
	)
	(arc
		(start 337.590384 -222.761556)
		(mid 337.516393 -222.48199)
		(end 337.313778 -222.275654)
		(width 0.0889)
		(layer "In4.Cu")
		(net "PD_CPU0_DMIMODE_OVERRIDE")
	)
	(arc
		(start 347.175582 -227.969318)
		(mid 346.899023 -227.893609)
		(end 346.620846 -227.963222)
		(width 0.0889)
		(layer "In4.Cu")
		(net "PD_CPU0_DMIMODE_OVERRIDE")
	)
	(arc
		(start 341.349584 -226.003104)
		(mid 341.270365 -225.728419)
		(end 341.066882 -225.527616)
		(width 0.0889)
		(layer "In4.Cu")
		(net "PD_CPU0_DMIMODE_OVERRIDE")
	)
	(arc
		(start 339.93963 -225.187764)
		(mid 339.86026 -224.91403)
		(end 339.657436 -224.7138)
		(width 0.0889)
		(layer "In4.Cu")
		(net "PD_CPU0_DMIMODE_OVERRIDE")
	)
	(arc
		(start 341.528146 -226.336606)
		(mid 341.397232 -226.200246)
		(end 341.349584 -226.017328)
		(width 0.0889)
		(layer "In4.Cu")
		(net "PD_CPU0_DMIMODE_OVERRIDE")
	)
	(arc
		(start 335.898236 -221.458282)
		(mid 335.761867 -221.40184)
		(end 335.615534 -221.38259)
		(width 0.0889)
		(layer "In4.Cu")
		(net "PD_CPU0_DMIMODE_OVERRIDE")
	)
	(arc
		(start 339.469984 -224.379536)
		(mid 339.391873 -224.102587)
		(end 339.187536 -223.899984)
		(width 0.0889)
		(layer "In4.Cu")
		(net "PD_CPU0_DMIMODE_OVERRIDE")
	)
	(arc
		(start 342.93175 -227.146866)
		(mid 342.655275 -227.079546)
		(end 342.381078 -227.155502)
		(width 0.0889)
		(layer "In4.Cu")
		(net "PD_CPU0_DMIMODE_OVERRIDE")
	)
	(arc
		(start 343.791032 -227.969318)
		(mid 343.603834 -228.019461)
		(end 343.416636 -227.969318)
		(width 0.0889)
		(layer "In4.Cu")
		(net "PD_CPU0_DMIMODE_OVERRIDE")
	)
	(arc
		(start 336.180684 -221.937834)
		(mid 336.102573 -221.660885)
		(end 335.898236 -221.458282)
		(width 0.0889)
		(layer "In4.Cu")
		(net "PD_CPU0_DMIMODE_OVERRIDE")
	)
	(arc
		(start 343.407746 -227.964238)
		(mid 343.276832 -227.827878)
		(end 343.229184 -227.64496)
		(width 0.0889)
		(layer "In4.Cu")
		(net "PD_CPU0_DMIMODE_OVERRIDE")
	)
	(arc
		(start 349.055436 -227.969318)
		(mid 348.781207 -227.893393)
		(end 348.504764 -227.960682)
		(width 0.0889)
		(layer "In4.Cu")
		(net "PD_CPU0_DMIMODE_OVERRIDE")
	)
	(arc
		(start 347.549978 -227.969318)
		(mid 347.36278 -228.019461)
		(end 347.175582 -227.969318)
		(width 0.0889)
		(layer "In4.Cu")
		(net "PD_CPU0_DMIMODE_OVERRIDE")
	)
	(arc
		(start 345.296236 -227.969318)
		(mid 345.022007 -227.893393)
		(end 344.745564 -227.960682)
		(width 0.0889)
		(layer "In4.Cu")
		(net "PD_CPU0_DMIMODE_OVERRIDE")
	)
	(arc
		(start 344.730832 -227.969318)
		(mid 344.543634 -228.019461)
		(end 344.356436 -227.969318)
		(width 0.0889)
		(layer "In4.Cu")
		(net "PD_CPU0_DMIMODE_OVERRIDE")
	)
	(arc
		(start 345.670632 -227.969318)
		(mid 345.483434 -228.019461)
		(end 345.296236 -227.969318)
		(width 0.0889)
		(layer "In4.Cu")
		(net "PD_CPU0_DMIMODE_OVERRIDE")
	)
	(arc
		(start 346.236036 -227.969318)
		(mid 345.953334 -227.893576)
		(end 345.670632 -227.969318)
		(width 0.0889)
		(layer "In4.Cu")
		(net "PD_CPU0_DMIMODE_OVERRIDE")
	)
	(arc
		(start 342.006682 -227.155502)
		(mid 341.871749 -227.022148)
		(end 341.819484 -226.83978)
		(width 0.0889)
		(layer "In4.Cu")
		(net "PD_CPU0_DMIMODE_OVERRIDE")
	)
	(arc
		(start 349.438722 -227.964238)
		(mid 349.286087 -228.039364)
		(end 349.11919 -228.006148)
		(width 0.0889)
		(layer "In4.Cu")
		(net "PD_CPU0_DMIMODE_OVERRIDE")
	)
	(arc
		(start 348.490032 -227.969318)
		(mid 348.302834 -228.019461)
		(end 348.115636 -227.969318)
		(width 0.0889)
		(layer "In4.Cu")
		(net "PD_CPU0_DMIMODE_OVERRIDE")
	)
	(arc
		(start 350.45015 -227.146866)
		(mid 350.173675 -227.079546)
		(end 349.899478 -227.155502)
		(width 0.0889)
		(layer "In4.Cu")
		(net "PD_CPU0_DMIMODE_OVERRIDE")
	)
	(arc
		(start 340.501478 -225.527616)
		(mid 340.31428 -225.577759)
		(end 340.127082 -225.527616)
		(width 0.0889)
		(layer "In4.Cu")
		(net "PD_CPU0_DMIMODE_OVERRIDE")
	)
	(arc
		(start 337.29295 -222.263462)
		(mid 337.016475 -222.196142)
		(end 336.742278 -222.272098)
		(width 0.0889)
		(layer "In4.Cu")
		(net "PD_CPU0_DMIMODE_OVERRIDE")
	)
	(arc
		(start 348.115636 -227.969318)
		(mid 347.838823 -227.893482)
		(end 347.560392 -227.963222)
		(width 0.0889)
		(layer "In4.Cu")
		(net "PD_CPU0_DMIMODE_OVERRIDE")
	)
	(arc
		(start 336.367882 -222.272098)
		(mid 336.232949 -222.138744)
		(end 336.180684 -221.956376)
		(width 0.0889)
		(layer "In4.Cu")
		(net "PD_CPU0_DMIMODE_OVERRIDE")
	)
	(arc
		(start 344.356436 -227.969318)
		(mid 344.082207 -227.893393)
		(end 343.805764 -227.960682)
		(width 0.0889)
		(layer "In4.Cu")
		(net "PD_CPU0_DMIMODE_OVERRIDE")
	)
	(arc
		(start 349.899478 -227.155502)
		(mid 349.696655 -227.355733)
		(end 349.617284 -227.629466)
		(width 0.0889)
		(layer "In4.Cu")
		(net "PD_CPU0_DMIMODE_OVERRIDE")
	)
	(arc
		(start 339.178646 -223.894904)
		(mid 339.047732 -223.758544)
		(end 339.000084 -223.575626)
		(width 0.0889)
		(layer "In4.Cu")
		(net "PD_CPU0_DMIMODE_OVERRIDE")
	)
	(arc
		(start 346.610432 -227.969318)
		(mid 346.423234 -228.019461)
		(end 346.236036 -227.969318)
		(width 0.0889)
		(layer "In4.Cu")
		(net "PD_CPU0_DMIMODE_OVERRIDE")
	)
	(arc
		(start 342.381078 -227.155502)
		(mid 342.19388 -227.205645)
		(end 342.006682 -227.155502)
		(width 0.0889)
		(layer "In4.Cu")
		(net "PD_CPU0_DMIMODE_OVERRIDE")
	)
	(arc
		(start 338.717636 -223.085914)
		(mid 338.443407 -223.009989)
		(end 338.166964 -223.077278)
		(width 0.0889)
		(layer "In4.Cu")
		(net "PD_CPU0_DMIMODE_OVERRIDE")
	)
	(segment
		(start 328.913998 -191.14516)
		(end 327.770998 -191.14516)
		(width 0.12954)
		(layer "F.Cu")
		(net "PD_CPU0_BIST_ENABLE")
	)
	(segment
		(start 349.242634 -228.180646)
		(end 349.242634 -227.64496)
		(width 0.12954)
		(layer "F.Cu")
		(net "PD_CPU0_BIST_ENABLE")
	)
	(segment
		(start 321.748658 -191.25057)
		(end 327.665588 -191.25057)
		(width 0.12954)
		(layer "F.Cu")
		(net "PD_CPU0_BIST_ENABLE")
	)
	(segment
		(start 327.665588 -191.25057)
		(end 327.770998 -191.14516)
		(width 0.12954)
		(layer "F.Cu")
		(net "PD_CPU0_BIST_ENABLE")
	)
	(segment
		(start 349.24238 -228.1809)
		(end 349.242634 -228.180646)
		(width 0.12954)
		(layer "F.Cu")
		(net "PD_CPU0_BIST_ENABLE")
	)
	(via
		(at 349.242634 -227.64496)
		(size 0.4572)
		(drill 0.2032)
		(layers "F.Cu" "B.Cu")
		(net "PD_CPU0_BIST_ENABLE")
	)
	(via
		(at 321.748658 -191.25057)
		(size 0.508)
		(drill 0.254)
		(layers "F.Cu" "B.Cu")
		(net "PD_CPU0_BIST_ENABLE")
	)
	(via
		(at 321.310762 -218.472512)
		(size 0.6604)
		(drill 0.3302)
		(layers "F.Cu" "B.Cu")
		(net "PD_CPU0_BIST_ENABLE")
	)
	(segment
		(start 336.287364 -227.329238)
		(end 336.272632 -227.320602)
		(width 0.0889)
		(layer "B.Cu")
		(net "PD_CPU0_BIST_ENABLE")
	)
	(segment
		(start 345.685364 -227.329238)
		(end 345.670632 -227.320602)
		(width 0.0889)
		(layer "B.Cu")
		(net "PD_CPU0_BIST_ENABLE")
	)
	(segment
		(start 347.560392 -227.326698)
		(end 347.549978 -227.320602)
		(width 0.0889)
		(layer "B.Cu")
		(net "PD_CPU0_BIST_ENABLE")
	)
	(segment
		(start 334.018636 -227.320602)
		(end 334.008222 -227.326698)
		(width 0.0889)
		(layer "B.Cu")
		(net "PD_CPU0_BIST_ENABLE")
	)
	(segment
		(start 340.986364 -227.329238)
		(end 340.971632 -227.320602)
		(width 0.0889)
		(layer "B.Cu")
		(net "PD_CPU0_BIST_ENABLE")
	)
	(segment
		(start 321.748658 -218.034616)
		(end 321.748658 -191.25057)
		(width 0.12954)
		(layer "B.Cu")
		(net "PD_CPU0_BIST_ENABLE")
	)
	(segment
		(start 328.132186 -226.15779)
		(end 321.310762 -219.336366)
		(width 0.12954)
		(layer "B.Cu")
		(net "PD_CPU0_BIST_ENABLE")
	)
	(segment
		(start 348.504764 -227.329238)
		(end 348.490032 -227.320602)
		(width 0.0889)
		(layer "B.Cu")
		(net "PD_CPU0_BIST_ENABLE")
	)
	(segment
		(start 347.175582 -227.320602)
		(end 347.165168 -227.326698)
		(width 0.0889)
		(layer "B.Cu")
		(net "PD_CPU0_BIST_ENABLE")
	)
	(segment
		(start 344.745564 -227.329238)
		(end 344.730832 -227.320602)
		(width 0.0889)
		(layer "B.Cu")
		(net "PD_CPU0_BIST_ENABLE")
	)
	(segment
		(start 331.57287 -227.446586)
		(end 330.284074 -226.15779)
		(width 0.12954)
		(layer "B.Cu")
		(net "PD_CPU0_BIST_ENABLE")
	)
	(segment
		(start 330.284074 -226.15779)
		(end 328.132186 -226.15779)
		(width 0.12954)
		(layer "B.Cu")
		(net "PD_CPU0_BIST_ENABLE")
	)
	(segment
		(start 339.657182 -227.320602)
		(end 339.646768 -227.326698)
		(width 0.0889)
		(layer "B.Cu")
		(net "PD_CPU0_BIST_ENABLE")
	)
	(segment
		(start 321.310762 -218.472512)
		(end 321.748658 -218.034616)
		(width 0.12954)
		(layer "B.Cu")
		(net "PD_CPU0_BIST_ENABLE")
	)
	(segment
		(start 334.403446 -227.326698)
		(end 334.393032 -227.320602)
		(width 0.0889)
		(layer "B.Cu")
		(net "PD_CPU0_BIST_ENABLE")
	)
	(segment
		(start 342.865964 -227.329238)
		(end 342.851232 -227.320602)
		(width 0.0889)
		(layer "B.Cu")
		(net "PD_CPU0_BIST_ENABLE")
	)
	(segment
		(start 349.399098 -227.373942)
		(end 349.378016 -227.295964)
		(width 0.0889)
		(layer "B.Cu")
		(net "PD_CPU0_BIST_ENABLE")
	)
	(segment
		(start 332.779878 -227.446586)
		(end 331.57287 -227.446586)
		(width 0.12954)
		(layer "B.Cu")
		(net "PD_CPU0_BIST_ENABLE")
	)
	(segment
		(start 335.898236 -227.320602)
		(end 335.887822 -227.326698)
		(width 0.0889)
		(layer "B.Cu")
		(net "PD_CPU0_BIST_ENABLE")
	)
	(segment
		(start 340.041992 -227.326698)
		(end 340.031578 -227.320602)
		(width 0.0889)
		(layer "B.Cu")
		(net "PD_CPU0_BIST_ENABLE")
	)
	(segment
		(start 321.310762 -219.336366)
		(end 321.310762 -218.472512)
		(width 0.12954)
		(layer "B.Cu")
		(net "PD_CPU0_BIST_ENABLE")
	)
	(segment
		(start 337.227164 -227.329238)
		(end 337.212432 -227.320602)
		(width 0.0889)
		(layer "B.Cu")
		(net "PD_CPU0_BIST_ENABLE")
	)
	(segment
		(start 349.242634 -227.64496)
		(end 349.399098 -227.373942)
		(width 0.0889)
		(layer "B.Cu")
		(net "PD_CPU0_BIST_ENABLE")
	)
	(segment
		(start 341.926164 -227.329238)
		(end 341.911432 -227.320602)
		(width 0.0889)
		(layer "B.Cu")
		(net "PD_CPU0_BIST_ENABLE")
	)
	(segment
		(start 333.000858 -227.380038)
		(end 332.93431 -227.446586)
		(width 0.0889)
		(layer "B.Cu")
		(net "PD_CPU0_BIST_ENABLE")
	)
	(segment
		(start 332.93431 -227.446586)
		(end 332.779878 -227.446586)
		(width 0.0889)
		(layer "B.Cu")
		(net "PD_CPU0_BIST_ENABLE")
	)
	(segment
		(start 338.166964 -227.329238)
		(end 338.152232 -227.320602)
		(width 0.0889)
		(layer "B.Cu")
		(net "PD_CPU0_BIST_ENABLE")
	)
	(arc
		(start 336.272632 -227.320602)
		(mid 336.085434 -227.270459)
		(end 335.898236 -227.320602)
		(width 0.0889)
		(layer "B.Cu")
		(net "PD_CPU0_BIST_ENABLE")
	)
	(arc
		(start 348.490032 -227.320602)
		(mid 348.302834 -227.270459)
		(end 348.115636 -227.320602)
		(width 0.0889)
		(layer "B.Cu")
		(net "PD_CPU0_BIST_ENABLE")
	)
	(arc
		(start 341.911432 -227.320602)
		(mid 341.724234 -227.270459)
		(end 341.537036 -227.320602)
		(width 0.0889)
		(layer "B.Cu")
		(net "PD_CPU0_BIST_ENABLE")
	)
	(arc
		(start 344.356436 -227.320602)
		(mid 344.073734 -227.396378)
		(end 343.791032 -227.320602)
		(width 0.0889)
		(layer "B.Cu")
		(net "PD_CPU0_BIST_ENABLE")
	)
	(arc
		(start 334.393032 -227.320602)
		(mid 334.205834 -227.270459)
		(end 334.018636 -227.320602)
		(width 0.0889)
		(layer "B.Cu")
		(net "PD_CPU0_BIST_ENABLE")
	)
	(arc
		(start 333.078582 -227.320602)
		(mid 333.037773 -227.347774)
		(end 333.000858 -227.380038)
		(width 0.0889)
		(layer "B.Cu")
		(net "PD_CPU0_BIST_ENABLE")
	)
	(arc
		(start 338.152232 -227.320602)
		(mid 337.965034 -227.270459)
		(end 337.777836 -227.320602)
		(width 0.0889)
		(layer "B.Cu")
		(net "PD_CPU0_BIST_ENABLE")
	)
	(arc
		(start 337.777836 -227.320602)
		(mid 337.503637 -227.396437)
		(end 337.227164 -227.329238)
		(width 0.0889)
		(layer "B.Cu")
		(net "PD_CPU0_BIST_ENABLE")
	)
	(arc
		(start 339.092032 -227.320602)
		(mid 338.904834 -227.270459)
		(end 338.717636 -227.320602)
		(width 0.0889)
		(layer "B.Cu")
		(net "PD_CPU0_BIST_ENABLE")
	)
	(arc
		(start 348.115636 -227.320602)
		(mid 347.838823 -227.396472)
		(end 347.560392 -227.326698)
		(width 0.0889)
		(layer "B.Cu")
		(net "PD_CPU0_BIST_ENABLE")
	)
	(arc
		(start 342.476836 -227.320602)
		(mid 342.202637 -227.396437)
		(end 341.926164 -227.329238)
		(width 0.0889)
		(layer "B.Cu")
		(net "PD_CPU0_BIST_ENABLE")
	)
	(arc
		(start 343.416636 -227.320602)
		(mid 343.142437 -227.396437)
		(end 342.865964 -227.329238)
		(width 0.0889)
		(layer "B.Cu")
		(net "PD_CPU0_BIST_ENABLE")
	)
	(arc
		(start 340.597236 -227.320602)
		(mid 340.320423 -227.396472)
		(end 340.041992 -227.326698)
		(width 0.0889)
		(layer "B.Cu")
		(net "PD_CPU0_BIST_ENABLE")
	)
	(arc
		(start 338.717636 -227.320602)
		(mid 338.443437 -227.396437)
		(end 338.166964 -227.329238)
		(width 0.0889)
		(layer "B.Cu")
		(net "PD_CPU0_BIST_ENABLE")
	)
	(arc
		(start 347.165168 -227.326698)
		(mid 346.88699 -227.396421)
		(end 346.610432 -227.320602)
		(width 0.0889)
		(layer "B.Cu")
		(net "PD_CPU0_BIST_ENABLE")
	)
	(arc
		(start 345.296236 -227.320602)
		(mid 345.022037 -227.396437)
		(end 344.745564 -227.329238)
		(width 0.0889)
		(layer "B.Cu")
		(net "PD_CPU0_BIST_ENABLE")
	)
	(arc
		(start 340.971632 -227.320602)
		(mid 340.784434 -227.270459)
		(end 340.597236 -227.320602)
		(width 0.0889)
		(layer "B.Cu")
		(net "PD_CPU0_BIST_ENABLE")
	)
	(arc
		(start 339.646768 -227.326698)
		(mid 339.36859 -227.396421)
		(end 339.092032 -227.320602)
		(width 0.0889)
		(layer "B.Cu")
		(net "PD_CPU0_BIST_ENABLE")
	)
	(arc
		(start 334.008222 -227.326698)
		(mid 333.72979 -227.396544)
		(end 333.452978 -227.320602)
		(width 0.0889)
		(layer "B.Cu")
		(net "PD_CPU0_BIST_ENABLE")
	)
	(arc
		(start 340.031578 -227.320602)
		(mid 339.84438 -227.270459)
		(end 339.657182 -227.320602)
		(width 0.0889)
		(layer "B.Cu")
		(net "PD_CPU0_BIST_ENABLE")
	)
	(arc
		(start 343.791032 -227.320602)
		(mid 343.603834 -227.270459)
		(end 343.416636 -227.320602)
		(width 0.0889)
		(layer "B.Cu")
		(net "PD_CPU0_BIST_ENABLE")
	)
	(arc
		(start 333.452978 -227.320602)
		(mid 333.26578 -227.270459)
		(end 333.078582 -227.320602)
		(width 0.0889)
		(layer "B.Cu")
		(net "PD_CPU0_BIST_ENABLE")
	)
	(arc
		(start 344.730832 -227.320602)
		(mid 344.543634 -227.270459)
		(end 344.356436 -227.320602)
		(width 0.0889)
		(layer "B.Cu")
		(net "PD_CPU0_BIST_ENABLE")
	)
	(arc
		(start 346.610432 -227.320602)
		(mid 346.423234 -227.270459)
		(end 346.236036 -227.320602)
		(width 0.0889)
		(layer "B.Cu")
		(net "PD_CPU0_BIST_ENABLE")
	)
	(arc
		(start 347.549978 -227.320602)
		(mid 347.36278 -227.270459)
		(end 347.175582 -227.320602)
		(width 0.0889)
		(layer "B.Cu")
		(net "PD_CPU0_BIST_ENABLE")
	)
	(arc
		(start 335.332578 -227.320602)
		(mid 335.14538 -227.270459)
		(end 334.958182 -227.320602)
		(width 0.0889)
		(layer "B.Cu")
		(net "PD_CPU0_BIST_ENABLE")
	)
	(arc
		(start 335.887822 -227.326698)
		(mid 335.60939 -227.396544)
		(end 335.332578 -227.320602)
		(width 0.0889)
		(layer "B.Cu")
		(net "PD_CPU0_BIST_ENABLE")
	)
	(arc
		(start 342.851232 -227.320602)
		(mid 342.664034 -227.270459)
		(end 342.476836 -227.320602)
		(width 0.0889)
		(layer "B.Cu")
		(net "PD_CPU0_BIST_ENABLE")
	)
	(arc
		(start 336.838036 -227.320602)
		(mid 336.563837 -227.396437)
		(end 336.287364 -227.329238)
		(width 0.0889)
		(layer "B.Cu")
		(net "PD_CPU0_BIST_ENABLE")
	)
	(arc
		(start 337.212432 -227.320602)
		(mid 337.025234 -227.270459)
		(end 336.838036 -227.320602)
		(width 0.0889)
		(layer "B.Cu")
		(net "PD_CPU0_BIST_ENABLE")
	)
	(arc
		(start 349.055436 -227.320602)
		(mid 348.781237 -227.396437)
		(end 348.504764 -227.329238)
		(width 0.0889)
		(layer "B.Cu")
		(net "PD_CPU0_BIST_ENABLE")
	)
	(arc
		(start 349.378016 -227.295964)
		(mid 349.21392 -227.271617)
		(end 349.055436 -227.320602)
		(width 0.0889)
		(layer "B.Cu")
		(net "PD_CPU0_BIST_ENABLE")
	)
	(arc
		(start 346.236036 -227.320602)
		(mid 345.961837 -227.396437)
		(end 345.685364 -227.329238)
		(width 0.0889)
		(layer "B.Cu")
		(net "PD_CPU0_BIST_ENABLE")
	)
	(arc
		(start 334.958182 -227.320602)
		(mid 334.681623 -227.396345)
		(end 334.403446 -227.326698)
		(width 0.0889)
		(layer "B.Cu")
		(net "PD_CPU0_BIST_ENABLE")
	)
	(arc
		(start 341.537036 -227.320602)
		(mid 341.262837 -227.396437)
		(end 340.986364 -227.329238)
		(width 0.0889)
		(layer "B.Cu")
		(net "PD_CPU0_BIST_ENABLE")
	)
	(arc
		(start 345.670632 -227.320602)
		(mid 345.483434 -227.270459)
		(end 345.296236 -227.320602)
		(width 0.0889)
		(layer "B.Cu")
		(net "PD_CPU0_BIST_ENABLE")
	)
	(segment
		(start 253.682754 -102.688136)
		(end 253.682754 -104.457246)
		(width 0.0889)
		(layer "F.Cu")
		(net "PD_CK440_SBI_DATA_IN")
	)
	(segment
		(start 253.682754 -104.457246)
		(end 253.394718 -104.745282)
		(width 0.0889)
		(layer "F.Cu")
		(net "PD_CK440_SBI_DATA_IN")
	)
	(via
		(at 253.394718 -104.745282)
		(size 0.508)
		(drill 0.254)
		(layers "F.Cu" "B.Cu")
		(net "PD_CK440_SBI_DATA_IN")
	)
	(segment
		(start 252.718824 -105.421176)
		(end 252.718824 -107.779058)
		(width 0.12954)
		(layer "B.Cu")
		(net "PD_CK440_SBI_DATA_IN")
	)
	(segment
		(start 253.394718 -104.745282)
		(end 252.718824 -105.421176)
		(width 0.12954)
		(layer "B.Cu")
		(net "PD_CK440_SBI_DATA_IN")
	)
	(segment
		(start 252.53188 -106.771948)
		(end 252.225048 -107.07878)
		(width 0.12954)
		(layer "F.Cu")
		(net "PD_CK440_SBI_CLK")
	)
	(segment
		(start 252.53188 -105.327958)
		(end 252.53188 -106.771948)
		(width 0.12954)
		(layer "F.Cu")
		(net "PD_CK440_SBI_CLK")
	)
	(segment
		(start 253.432818 -104.047798)
		(end 252.975872 -104.504744)
		(width 0.12954)
		(layer "F.Cu")
		(net "PD_CK440_SBI_CLK")
	)
	(segment
		(start 253.432818 -103.438198)
		(end 253.432818 -104.047798)
		(width 0.12954)
		(layer "F.Cu")
		(net "PD_CK440_SBI_CLK")
	)
	(segment
		(start 252.705108 -104.909874)
		(end 252.53188 -105.327958)
		(width 0.12954)
		(layer "F.Cu")
		(net "PD_CK440_SBI_CLK")
	)
	(segment
		(start 252.975872 -104.504744)
		(end 252.705108 -104.909874)
		(width 0.12954)
		(layer "F.Cu")
		(net "PD_CK440_SBI_CLK")
	)
	(via
		(at 252.225048 -107.07878)
		(size 0.508)
		(drill 0.254)
		(layers "F.Cu" "B.Cu")
		(net "PD_CK440_SBI_CLK")
	)
	(via
		(at 251.36729 -108.37037)
		(size 0.6604)
		(drill 0.3302)
		(layers "F.Cu" "B.Cu")
		(net "PD_CK440_SBI_CLK")
	)
	(segment
		(start 251.31395 -108.31703)
		(end 251.36729 -108.37037)
		(width 0.12954)
		(layer "B.Cu")
		(net "PD_CK440_SBI_CLK")
	)
	(segment
		(start 251.575316 -107.178094)
		(end 251.575316 -107.325414)
		(width 0.12954)
		(layer "B.Cu")
		(net "PD_CK440_SBI_CLK")
	)
	(segment
		(start 252.225048 -108.02366)
		(end 252.225048 -107.07878)
		(width 0.12954)
		(layer "B.Cu")
		(net "PD_CK440_SBI_CLK")
	)
	(segment
		(start 251.878338 -108.37037)
		(end 252.225048 -108.02366)
		(width 0.12954)
		(layer "B.Cu")
		(net "PD_CK440_SBI_CLK")
	)
	(segment
		(start 251.575316 -107.325414)
		(end 251.31395 -107.58678)
		(width 0.12954)
		(layer "B.Cu")
		(net "PD_CK440_SBI_CLK")
	)
	(segment
		(start 251.31395 -107.58678)
		(end 251.31395 -108.31703)
		(width 0.12954)
		(layer "B.Cu")
		(net "PD_CK440_SBI_CLK")
	)
	(segment
		(start 251.36729 -108.37037)
		(end 251.878338 -108.37037)
		(width 0.12954)
		(layer "B.Cu")
		(net "PD_CK440_SBI_CLK")
	)
	(segment
		(start 207.071214 -318.866774)
		(end 208.176114 -318.866774)
		(width 0.12954)
		(layer "F.Cu")
		(net "PD_CHH_CPU1_DIMM2_SAA")
	)
	(via
		(at 207.071214 -318.866774)
		(size 0.4572)
		(drill 0.254)
		(layers "F.Cu" "B.Cu")
		(net "PD_CHH_CPU1_DIMM2_SAA")
	)
	(segment
		(start 206.596488 -318.392048)
		(end 205.970632 -318.392048)
		(width 0.12954)
		(layer "B.Cu")
		(net "PD_CHH_CPU1_DIMM2_SAA")
	)
	(segment
		(start 207.071214 -318.866774)
		(end 206.596488 -318.392048)
		(width 0.12954)
		(layer "B.Cu")
		(net "PD_CHH_CPU1_DIMM2_SAA")
	)
	(segment
		(start 214.02802 -319.255648)
		(end 214.416894 -318.866774)
		(width 0.12954)
		(layer "F.Cu")
		(net "PD_CHH_CPU1_DIMM1_SAA")
	)
	(segment
		(start 214.416894 -318.866774)
		(end 215.719914 -318.866774)
		(width 0.12954)
		(layer "F.Cu")
		(net "PD_CHH_CPU1_DIMM1_SAA")
	)
	(via
		(at 214.02802 -319.255648)
		(size 0.4572)
		(drill 0.2032)
		(layers "F.Cu" "B.Cu")
		(net "PD_CHH_CPU1_DIMM1_SAA")
	)
	(segment
		(start 214.02802 -319.255648)
		(end 214.02802 -318.154558)
		(width 0.12954)
		(layer "B.Cu")
		(net "PD_CHH_CPU1_DIMM1_SAA")
	)
	(segment
		(start 214.02802 -318.154558)
		(end 213.98103 -318.107568)
		(width 0.12954)
		(layer "B.Cu")
		(net "PD_CHH_CPU1_DIMM1_SAA")
	)
	(segment
		(start 454.8759 -318.866774)
		(end 456.116182 -318.866774)
		(width 0.12954)
		(layer "F.Cu")
		(net "PD_CHH_CPU0_DIMM2_SAA")
	)
	(segment
		(start 454.207626 -319.535048)
		(end 454.8759 -318.866774)
		(width 0.12954)
		(layer "F.Cu")
		(net "PD_CHH_CPU0_DIMM2_SAA")
	)
	(segment
		(start 454.207626 -319.865248)
		(end 454.207626 -319.535048)
		(width 0.12954)
		(layer "F.Cu")
		(net "PD_CHH_CPU0_DIMM2_SAA")
	)
	(via
		(at 454.207626 -319.865248)
		(size 0.4572)
		(drill 0.2032)
		(layers "F.Cu" "B.Cu")
		(net "PD_CHH_CPU0_DIMM2_SAA")
	)
	(segment
		(start 454.207626 -318.748156)
		(end 454.250806 -318.704976)
		(width 0.12954)
		(layer "B.Cu")
		(net "PD_CHH_CPU0_DIMM2_SAA")
	)
	(segment
		(start 454.207626 -319.865248)
		(end 454.207626 -318.748156)
		(width 0.12954)
		(layer "B.Cu")
		(net "PD_CHH_CPU0_DIMM2_SAA")
	)
	(segment
		(start 464.79968 -319.311528)
		(end 464.354926 -318.866774)
		(width 0.12954)
		(layer "F.Cu")
		(net "PD_CHH_CPU0_DIMM1_SAA")
	)
	(segment
		(start 464.79968 -319.613788)
		(end 464.79968 -319.311528)
		(width 0.12954)
		(layer "F.Cu")
		(net "PD_CHH_CPU0_DIMM1_SAA")
	)
	(segment
		(start 464.354926 -318.866774)
		(end 463.659982 -318.866774)
		(width 0.12954)
		(layer "F.Cu")
		(net "PD_CHH_CPU0_DIMM1_SAA")
	)
	(via
		(at 464.79968 -319.613788)
		(size 0.4572)
		(drill 0.2032)
		(layers "F.Cu" "B.Cu")
		(net "PD_CHH_CPU0_DIMM1_SAA")
	)
	(segment
		(start 464.377532 -319.19164)
		(end 461.419448 -319.19164)
		(width 0.12954)
		(layer "B.Cu")
		(net "PD_CHH_CPU0_DIMM1_SAA")
	)
	(segment
		(start 464.79968 -319.613788)
		(end 464.377532 -319.19164)
		(width 0.12954)
		(layer "B.Cu")
		(net "PD_CHH_CPU0_DIMM1_SAA")
	)
	(segment
		(start 191.99606 -318.866774)
		(end 193.088514 -318.866774)
		(width 0.12954)
		(layer "F.Cu")
		(net "PD_CHG_CPU1_DIMM2_SAA")
	)
	(via
		(at 191.99606 -318.866774)
		(size 0.4572)
		(drill 0.2032)
		(layers "F.Cu" "B.Cu")
		(net "PD_CHG_CPU1_DIMM2_SAA")
	)
	(via
		(at 192.846198 -318.266826)
		(size 0.6604)
		(drill 0.3302)
		(layers "F.Cu" "B.Cu")
		(net "PD_CHG_CPU1_DIMM2_SAA")
	)
	(segment
		(start 192.846198 -318.779906)
		(end 192.266062 -319.360042)
		(width 0.12954)
		(layer "B.Cu")
		(net "PD_CHG_CPU1_DIMM2_SAA")
	)
	(segment
		(start 192.846198 -318.266826)
		(end 192.596008 -318.266826)
		(width 0.12954)
		(layer "B.Cu")
		(net "PD_CHG_CPU1_DIMM2_SAA")
	)
	(segment
		(start 192.266062 -319.360042)
		(end 191.591184 -319.360042)
		(width 0.12954)
		(layer "B.Cu")
		(net "PD_CHG_CPU1_DIMM2_SAA")
	)
	(segment
		(start 191.591184 -319.360042)
		(end 191.44869 -319.217548)
		(width 0.12954)
		(layer "B.Cu")
		(net "PD_CHG_CPU1_DIMM2_SAA")
	)
	(segment
		(start 192.846198 -318.266826)
		(end 192.846198 -318.779906)
		(width 0.12954)
		(layer "B.Cu")
		(net "PD_CHG_CPU1_DIMM2_SAA")
	)
	(segment
		(start 192.596008 -318.266826)
		(end 191.99606 -318.866774)
		(width 0.12954)
		(layer "B.Cu")
		(net "PD_CHG_CPU1_DIMM2_SAA")
	)
	(segment
		(start 199.527414 -318.866774)
		(end 200.632314 -318.866774)
		(width 0.12954)
		(layer "F.Cu")
		(net "PD_CHG_CPU1_DIMM1_SAA")
	)
	(via
		(at 199.527414 -318.866774)
		(size 0.4572)
		(drill 0.254)
		(layers "F.Cu" "B.Cu")
		(net "PD_CHG_CPU1_DIMM1_SAA")
	)
	(segment
		(start 198.992998 -318.332358)
		(end 198.486522 -318.332358)
		(width 0.12954)
		(layer "B.Cu")
		(net "PD_CHG_CPU1_DIMM1_SAA")
	)
	(segment
		(start 199.527414 -318.866774)
		(end 198.992998 -318.332358)
		(width 0.12954)
		(layer "B.Cu")
		(net "PD_CHG_CPU1_DIMM1_SAA")
	)
	(segment
		(start 441.028582 -318.866774)
		(end 439.923682 -318.866774)
		(width 0.12954)
		(layer "F.Cu")
		(net "PD_CHG_CPU0_DIMM2_SAA")
	)
	(via
		(at 439.923682 -318.866774)
		(size 0.4572)
		(drill 0.2032)
		(layers "F.Cu" "B.Cu")
		(net "PD_CHG_CPU0_DIMM2_SAA")
	)
	(via
		(at 439.087006 -319.74663)
		(size 0.6604)
		(drill 0.3302)
		(layers "F.Cu" "B.Cu")
		(net "PD_CHG_CPU0_DIMM2_SAA")
	)
	(segment
		(start 439.923682 -318.866774)
		(end 439.350404 -318.866774)
		(width 0.12954)
		(layer "B.Cu")
		(net "PD_CHG_CPU0_DIMM2_SAA")
	)
	(segment
		(start 439.350404 -318.866774)
		(end 439.087006 -318.603376)
		(width 0.12954)
		(layer "B.Cu")
		(net "PD_CHG_CPU0_DIMM2_SAA")
	)
	(segment
		(start 439.087006 -319.74663)
		(end 439.087006 -318.603376)
		(width 0.12954)
		(layer "B.Cu")
		(net "PD_CHG_CPU0_DIMM2_SAA")
	)
	(segment
		(start 448.572382 -318.866774)
		(end 447.467482 -318.866774)
		(width 0.12954)
		(layer "F.Cu")
		(net "PD_CHG_CPU0_DIMM1_SAA")
	)
	(via
		(at 446.580006 -319.75425)
		(size 0.6604)
		(drill 0.3302)
		(layers "F.Cu" "B.Cu")
		(net "PD_CHG_CPU0_DIMM1_SAA")
	)
	(via
		(at 447.467482 -318.866774)
		(size 0.4572)
		(drill 0.2032)
		(layers "F.Cu" "B.Cu")
		(net "PD_CHG_CPU0_DIMM1_SAA")
	)
	(segment
		(start 447.467482 -318.866774)
		(end 447.204084 -318.603376)
		(width 0.12954)
		(layer "B.Cu")
		(net "PD_CHG_CPU0_DIMM1_SAA")
	)
	(segment
		(start 447.204084 -318.603376)
		(end 446.580006 -318.603376)
		(width 0.12954)
		(layer "B.Cu")
		(net "PD_CHG_CPU0_DIMM1_SAA")
	)
	(segment
		(start 446.580006 -319.75425)
		(end 446.580006 -318.603376)
		(width 0.12954)
		(layer "B.Cu")
		(net "PD_CHG_CPU0_DIMM1_SAA")
	)
	(segment
		(start 176.896014 -318.866774)
		(end 178.000914 -318.866774)
		(width 0.12954)
		(layer "F.Cu")
		(net "PD_CHF_CPU1_DIMM2_SAA")
	)
	(via
		(at 176.896014 -318.866774)
		(size 0.4572)
		(drill 0.2032)
		(layers "F.Cu" "B.Cu")
		(net "PD_CHF_CPU1_DIMM2_SAA")
	)
	(via
		(at 177.173382 -318.145414)
		(size 0.6604)
		(drill 0.3302)
		(layers "F.Cu" "B.Cu")
		(net "PD_CHF_CPU1_DIMM2_SAA")
	)
	(segment
		(start 177.35042 -318.322452)
		(end 177.173382 -318.145414)
		(width 0.12954)
		(layer "B.Cu")
		(net "PD_CHF_CPU1_DIMM2_SAA")
	)
	(segment
		(start 177.173382 -318.145414)
		(end 177.024538 -318.294258)
		(width 0.12954)
		(layer "B.Cu")
		(net "PD_CHF_CPU1_DIMM2_SAA")
	)
	(segment
		(start 176.37125 -319.293748)
		(end 177.174144 -319.293748)
		(width 0.12954)
		(layer "B.Cu")
		(net "PD_CHF_CPU1_DIMM2_SAA")
	)
	(segment
		(start 177.024538 -318.73825)
		(end 176.896014 -318.866774)
		(width 0.12954)
		(layer "B.Cu")
		(net "PD_CHF_CPU1_DIMM2_SAA")
	)
	(segment
		(start 177.024538 -318.294258)
		(end 177.024538 -318.73825)
		(width 0.12954)
		(layer "B.Cu")
		(net "PD_CHF_CPU1_DIMM2_SAA")
	)
	(segment
		(start 177.35042 -319.117472)
		(end 177.35042 -318.322452)
		(width 0.12954)
		(layer "B.Cu")
		(net "PD_CHF_CPU1_DIMM2_SAA")
	)
	(segment
		(start 177.174144 -319.293748)
		(end 177.35042 -319.117472)
		(width 0.12954)
		(layer "B.Cu")
		(net "PD_CHF_CPU1_DIMM2_SAA")
	)
	(segment
		(start 184.439814 -318.866774)
		(end 185.544714 -318.866774)
		(width 0.12954)
		(layer "F.Cu")
		(net "PD_CHF_CPU1_DIMM1_SAA")
	)
	(via
		(at 184.439814 -318.866774)
		(size 0.4572)
		(drill 0.254)
		(layers "F.Cu" "B.Cu")
		(net "PD_CHF_CPU1_DIMM1_SAA")
	)
	(segment
		(start 184.439814 -318.866774)
		(end 183.925464 -318.352424)
		(width 0.12954)
		(layer "B.Cu")
		(net "PD_CHF_CPU1_DIMM1_SAA")
	)
	(segment
		(start 183.925464 -318.352424)
		(end 183.411876 -318.352424)
		(width 0.12954)
		(layer "B.Cu")
		(net "PD_CHF_CPU1_DIMM1_SAA")
	)
	(segment
		(start 425.940982 -318.866774)
		(end 424.836082 -318.866774)
		(width 0.12954)
		(layer "F.Cu")
		(net "PD_CHF_CPU0_DIMM2_SAA")
	)
	(via
		(at 424.836082 -318.866774)
		(size 0.4572)
		(drill 0.2032)
		(layers "F.Cu" "B.Cu")
		(net "PD_CHF_CPU0_DIMM2_SAA")
	)
	(via
		(at 424.050206 -319.92443)
		(size 0.6604)
		(drill 0.3302)
		(layers "F.Cu" "B.Cu")
		(net "PD_CHF_CPU0_DIMM2_SAA")
	)
	(segment
		(start 424.836082 -318.866774)
		(end 424.557698 -318.58839)
		(width 0.12954)
		(layer "B.Cu")
		(net "PD_CHF_CPU0_DIMM2_SAA")
	)
	(segment
		(start 424.050206 -319.92443)
		(end 424.050206 -318.781176)
		(width 0.12954)
		(layer "B.Cu")
		(net "PD_CHF_CPU0_DIMM2_SAA")
	)
	(segment
		(start 424.242992 -318.58839)
		(end 424.050206 -318.781176)
		(width 0.12954)
		(layer "B.Cu")
		(net "PD_CHF_CPU0_DIMM2_SAA")
	)
	(segment
		(start 424.557698 -318.58839)
		(end 424.242992 -318.58839)
		(width 0.12954)
		(layer "B.Cu")
		(net "PD_CHF_CPU0_DIMM2_SAA")
	)
	(segment
		(start 431.568606 -319.745868)
		(end 432.4477 -318.866774)
		(width 0.12954)
		(layer "F.Cu")
		(net "PD_CHF_CPU0_DIMM1_SAA")
	)
	(segment
		(start 432.4477 -318.866774)
		(end 433.484782 -318.866774)
		(width 0.12954)
		(layer "F.Cu")
		(net "PD_CHF_CPU0_DIMM1_SAA")
	)
	(via
		(at 431.568606 -319.745868)
		(size 0.4572)
		(drill 0.2032)
		(layers "F.Cu" "B.Cu")
		(net "PD_CHF_CPU0_DIMM1_SAA")
	)
	(segment
		(start 431.568606 -318.577976)
		(end 431.568606 -319.745868)
		(width 0.12954)
		(layer "B.Cu")
		(net "PD_CHF_CPU0_DIMM1_SAA")
	)
	(segment
		(start 162.913314 -318.866774)
		(end 162.024314 -318.866774)
		(width 0.12954)
		(layer "F.Cu")
		(net "PD_CHE_CPU1_DIMM2_SAA")
	)
	(segment
		(start 161.784284 -319.106804)
		(end 161.784284 -319.637156)
		(width 0.12954)
		(layer "F.Cu")
		(net "PD_CHE_CPU1_DIMM2_SAA")
	)
	(segment
		(start 162.024314 -318.866774)
		(end 161.784284 -319.106804)
		(width 0.12954)
		(layer "F.Cu")
		(net "PD_CHE_CPU1_DIMM2_SAA")
	)
	(via
		(at 162.123374 -318.750188)
		(size 0.7112)
		(drill 0.3556)
		(layers "F.Cu" "B.Cu")
		(net "PD_CHE_CPU1_DIMM2_SAA")
	)
	(via
		(at 161.784284 -319.637156)
		(size 0.4572)
		(drill 0.2032)
		(layers "F.Cu" "B.Cu")
		(net "PD_CHE_CPU1_DIMM2_SAA")
	)
	(segment
		(start 160.952942 -318.331342)
		(end 161.10585 -318.48425)
		(width 0.12954)
		(layer "B.Cu")
		(net "PD_CHE_CPU1_DIMM2_SAA")
	)
	(segment
		(start 160.952942 -318.305942)
		(end 160.952942 -318.331342)
		(width 0.12954)
		(layer "B.Cu")
		(net "PD_CHE_CPU1_DIMM2_SAA")
	)
	(segment
		(start 161.857436 -318.48425)
		(end 162.123374 -318.750188)
		(width 0.12954)
		(layer "B.Cu")
		(net "PD_CHE_CPU1_DIMM2_SAA")
	)
	(segment
		(start 162.123374 -318.750188)
		(end 162.123374 -319.298066)
		(width 0.12954)
		(layer "B.Cu")
		(net "PD_CHE_CPU1_DIMM2_SAA")
	)
	(segment
		(start 161.10585 -318.48425)
		(end 161.857436 -318.48425)
		(width 0.12954)
		(layer "B.Cu")
		(net "PD_CHE_CPU1_DIMM2_SAA")
	)
	(segment
		(start 162.123374 -319.298066)
		(end 161.784284 -319.637156)
		(width 0.12954)
		(layer "B.Cu")
		(net "PD_CHE_CPU1_DIMM2_SAA")
	)
	(segment
		(start 169.352214 -318.866774)
		(end 170.457114 -318.866774)
		(width 0.12954)
		(layer "F.Cu")
		(net "PD_CHE_CPU1_DIMM1_SAA")
	)
	(via
		(at 169.352214 -318.866774)
		(size 0.4572)
		(drill 0.254)
		(layers "F.Cu" "B.Cu")
		(net "PD_CHE_CPU1_DIMM1_SAA")
	)
	(segment
		(start 169.352214 -318.866774)
		(end 169.825162 -318.866774)
		(width 0.12954)
		(layer "B.Cu")
		(net "PD_CHE_CPU1_DIMM1_SAA")
	)
	(segment
		(start 169.825162 -318.866774)
		(end 169.965116 -319.006728)
		(width 0.12954)
		(layer "B.Cu")
		(net "PD_CHE_CPU1_DIMM1_SAA")
	)
	(segment
		(start 169.965116 -319.006728)
		(end 170.38574 -319.006728)
		(width 0.12954)
		(layer "B.Cu")
		(net "PD_CHE_CPU1_DIMM1_SAA")
	)
	(segment
		(start 409.724352 -319.066926)
		(end 409.924504 -318.866774)
		(width 0.12954)
		(layer "F.Cu")
		(net "PD_CHE_CPU0_DIMM2_SAA")
	)
	(segment
		(start 409.31465 -319.843658)
		(end 409.724352 -319.433956)
		(width 0.12954)
		(layer "F.Cu")
		(net "PD_CHE_CPU0_DIMM2_SAA")
	)
	(segment
		(start 409.924504 -318.866774)
		(end 410.853382 -318.866774)
		(width 0.12954)
		(layer "F.Cu")
		(net "PD_CHE_CPU0_DIMM2_SAA")
	)
	(segment
		(start 409.724352 -319.433956)
		(end 409.724352 -319.066926)
		(width 0.12954)
		(layer "F.Cu")
		(net "PD_CHE_CPU0_DIMM2_SAA")
	)
	(via
		(at 409.31465 -319.843658)
		(size 0.4572)
		(drill 0.2032)
		(layers "F.Cu" "B.Cu")
		(net "PD_CHE_CPU0_DIMM2_SAA")
	)
	(segment
		(start 409.31465 -319.843658)
		(end 409.702 -319.456308)
		(width 0.12954)
		(layer "B.Cu")
		(net "PD_CHE_CPU0_DIMM2_SAA")
	)
	(segment
		(start 409.702 -319.456308)
		(end 409.702 -318.86017)
		(width 0.12954)
		(layer "B.Cu")
		(net "PD_CHE_CPU0_DIMM2_SAA")
	)
	(segment
		(start 409.702 -318.86017)
		(end 409.597606 -318.755776)
		(width 0.12954)
		(layer "B.Cu")
		(net "PD_CHE_CPU0_DIMM2_SAA")
	)
	(segment
		(start 418.397182 -318.866774)
		(end 417.292282 -318.866774)
		(width 0.12954)
		(layer "F.Cu")
		(net "PD_CHE_CPU0_DIMM1_SAA")
	)
	(via
		(at 417.292282 -318.866774)
		(size 0.4572)
		(drill 0.2032)
		(layers "F.Cu" "B.Cu")
		(net "PD_CHE_CPU0_DIMM1_SAA")
	)
	(via
		(at 416.481006 -319.87363)
		(size 0.6604)
		(drill 0.3302)
		(layers "F.Cu" "B.Cu")
		(net "PD_CHE_CPU0_DIMM1_SAA")
	)
	(segment
		(start 416.481006 -319.87363)
		(end 416.481006 -318.730376)
		(width 0.12954)
		(layer "B.Cu")
		(net "PD_CHE_CPU0_DIMM1_SAA")
	)
	(segment
		(start 416.617404 -318.866774)
		(end 416.481006 -318.730376)
		(width 0.12954)
		(layer "B.Cu")
		(net "PD_CHE_CPU0_DIMM1_SAA")
	)
	(segment
		(start 417.292282 -318.866774)
		(end 416.617404 -318.866774)
		(width 0.12954)
		(layer "B.Cu")
		(net "PD_CHE_CPU0_DIMM1_SAA")
	)
	(segment
		(start 18.679414 -318.866774)
		(end 19.784314 -318.866774)
		(width 0.12954)
		(layer "F.Cu")
		(net "PD_CHD_CPU1_DIMM2_SAA")
	)
	(via
		(at 17.996408 -317.51397)
		(size 0.6604)
		(drill 0.3302)
		(layers "F.Cu" "B.Cu")
		(net "PD_CHD_CPU1_DIMM2_SAA")
	)
	(via
		(at 18.679414 -318.866774)
		(size 0.4572)
		(drill 0.2032)
		(layers "F.Cu" "B.Cu")
		(net "PD_CHD_CPU1_DIMM2_SAA")
	)
	(segment
		(start 18.679414 -318.866774)
		(end 18.479262 -318.666622)
		(width 0.12954)
		(layer "B.Cu")
		(net "PD_CHD_CPU1_DIMM2_SAA")
	)
	(segment
		(start 18.479262 -318.666622)
		(end 17.996408 -318.666622)
		(width 0.12954)
		(layer "B.Cu")
		(net "PD_CHD_CPU1_DIMM2_SAA")
	)
	(segment
		(start 17.996408 -318.666622)
		(end 17.996408 -317.51397)
		(width 0.12954)
		(layer "B.Cu")
		(net "PD_CHD_CPU1_DIMM2_SAA")
	)
	(segment
		(start 12.240514 -318.866774)
		(end 11.135614 -318.866774)
		(width 0.12954)
		(layer "F.Cu")
		(net "PD_CHD_CPU1_DIMM1_SAA")
	)
	(via
		(at 10.141458 -317.46063)
		(size 0.6604)
		(drill 0.3302)
		(layers "F.Cu" "B.Cu")
		(net "PD_CHD_CPU1_DIMM1_SAA")
	)
	(via
		(at 11.135614 -318.866774)
		(size 0.4572)
		(drill 0.2032)
		(layers "F.Cu" "B.Cu")
		(net "PD_CHD_CPU1_DIMM1_SAA")
	)
	(segment
		(start 10.141458 -317.97117)
		(end 10.39368 -318.223392)
		(width 0.12954)
		(layer "B.Cu")
		(net "PD_CHD_CPU1_DIMM1_SAA")
	)
	(segment
		(start 11.135614 -318.866774)
		(end 10.88644 -318.6176)
		(width 0.12954)
		(layer "B.Cu")
		(net "PD_CHD_CPU1_DIMM1_SAA")
	)
	(segment
		(start 10.88644 -318.6176)
		(end 10.39368 -318.6176)
		(width 0.12954)
		(layer "B.Cu")
		(net "PD_CHD_CPU1_DIMM1_SAA")
	)
	(segment
		(start 10.39368 -318.223392)
		(end 10.39368 -318.6176)
		(width 0.12954)
		(layer "B.Cu")
		(net "PD_CHD_CPU1_DIMM1_SAA")
	)
	(segment
		(start 10.141458 -317.46063)
		(end 10.141458 -317.97117)
		(width 0.12954)
		(layer "B.Cu")
		(net "PD_CHD_CPU1_DIMM1_SAA")
	)
	(segment
		(start 265.94054 -319.842388)
		(end 265.94054 -319.613788)
		(width 0.12954)
		(layer "F.Cu")
		(net "PD_CHD_CPU0_DIMM2_SAA")
	)
	(segment
		(start 265.94054 -319.613788)
		(end 266.687554 -318.866774)
		(width 0.12954)
		(layer "F.Cu")
		(net "PD_CHD_CPU0_DIMM2_SAA")
	)
	(segment
		(start 266.687554 -318.866774)
		(end 267.724382 -318.866774)
		(width 0.12954)
		(layer "F.Cu")
		(net "PD_CHD_CPU0_DIMM2_SAA")
	)
	(via
		(at 265.94054 -319.842388)
		(size 0.4572)
		(drill 0.2032)
		(layers "F.Cu" "B.Cu")
		(net "PD_CHD_CPU0_DIMM2_SAA")
	)
	(segment
		(start 265.94054 -318.831214)
		(end 265.806428 -318.697102)
		(width 0.12954)
		(layer "B.Cu")
		(net "PD_CHD_CPU0_DIMM2_SAA")
	)
	(segment
		(start 265.94054 -319.842388)
		(end 265.94054 -318.831214)
		(width 0.12954)
		(layer "B.Cu")
		(net "PD_CHD_CPU0_DIMM2_SAA")
	)
	(segment
		(start 260.180582 -318.866774)
		(end 259.075682 -318.866774)
		(width 0.12954)
		(layer "F.Cu")
		(net "PD_CHD_CPU0_DIMM1_SAA")
	)
	(via
		(at 257.85318 -317.429388)
		(size 0.6604)
		(drill 0.3302)
		(layers "F.Cu" "B.Cu")
		(net "PD_CHD_CPU0_DIMM1_SAA")
	)
	(via
		(at 259.075682 -318.866774)
		(size 0.4572)
		(drill 0.2032)
		(layers "F.Cu" "B.Cu")
		(net "PD_CHD_CPU0_DIMM1_SAA")
	)
	(segment
		(start 258.79171 -318.582802)
		(end 258.31292 -318.582802)
		(width 0.12954)
		(layer "B.Cu")
		(net "PD_CHD_CPU0_DIMM1_SAA")
	)
	(segment
		(start 259.075682 -318.866774)
		(end 258.79171 -318.582802)
		(width 0.12954)
		(layer "B.Cu")
		(net "PD_CHD_CPU0_DIMM1_SAA")
	)
	(segment
		(start 257.85318 -317.911734)
		(end 258.31292 -318.371474)
		(width 0.12954)
		(layer "B.Cu")
		(net "PD_CHD_CPU0_DIMM1_SAA")
	)
	(segment
		(start 257.85318 -317.429388)
		(end 257.85318 -317.911734)
		(width 0.12954)
		(layer "B.Cu")
		(net "PD_CHD_CPU0_DIMM1_SAA")
	)
	(segment
		(start 258.31292 -318.371474)
		(end 258.31292 -318.582802)
		(width 0.12954)
		(layer "B.Cu")
		(net "PD_CHD_CPU0_DIMM1_SAA")
	)
	(segment
		(start 33.767014 -318.866774)
		(end 34.871914 -318.866774)
		(width 0.12954)
		(layer "F.Cu")
		(net "PD_CHC_CPU1_DIMM2_SAA")
	)
	(via
		(at 33.767014 -318.866774)
		(size 0.4572)
		(drill 0.2032)
		(layers "F.Cu" "B.Cu")
		(net "PD_CHC_CPU1_DIMM2_SAA")
	)
	(via
		(at 33.057338 -317.49365)
		(size 0.6604)
		(drill 0.3302)
		(layers "F.Cu" "B.Cu")
		(net "PD_CHC_CPU1_DIMM2_SAA")
	)
	(segment
		(start 32.957262 -318.223392)
		(end 32.957262 -318.650112)
		(width 0.12954)
		(layer "B.Cu")
		(net "PD_CHC_CPU1_DIMM2_SAA")
	)
	(segment
		(start 33.057338 -318.123316)
		(end 32.957262 -318.223392)
		(width 0.12954)
		(layer "B.Cu")
		(net "PD_CHC_CPU1_DIMM2_SAA")
	)
	(segment
		(start 33.057338 -317.49365)
		(end 33.057338 -318.123316)
		(width 0.12954)
		(layer "B.Cu")
		(net "PD_CHC_CPU1_DIMM2_SAA")
	)
	(segment
		(start 33.767014 -318.866774)
		(end 33.550352 -318.650112)
		(width 0.12954)
		(layer "B.Cu")
		(net "PD_CHC_CPU1_DIMM2_SAA")
	)
	(segment
		(start 33.550352 -318.650112)
		(end 32.957262 -318.650112)
		(width 0.12954)
		(layer "B.Cu")
		(net "PD_CHC_CPU1_DIMM2_SAA")
	)
	(segment
		(start 26.223214 -318.866774)
		(end 27.328114 -318.866774)
		(width 0.12954)
		(layer "F.Cu")
		(net "PD_CHC_CPU1_DIMM1_SAA")
	)
	(via
		(at 25.472898 -317.481204)
		(size 0.6604)
		(drill 0.3302)
		(layers "F.Cu" "B.Cu")
		(net "PD_CHC_CPU1_DIMM1_SAA")
	)
	(via
		(at 26.223214 -318.866774)
		(size 0.4572)
		(drill 0.2032)
		(layers "F.Cu" "B.Cu")
		(net "PD_CHC_CPU1_DIMM1_SAA")
	)
	(segment
		(start 25.472898 -318.633856)
		(end 25.472898 -317.481204)
		(width 0.12954)
		(layer "B.Cu")
		(net "PD_CHC_CPU1_DIMM1_SAA")
	)
	(segment
		(start 26.223214 -318.866774)
		(end 25.990296 -318.633856)
		(width 0.12954)
		(layer "B.Cu")
		(net "PD_CHC_CPU1_DIMM1_SAA")
	)
	(segment
		(start 25.990296 -318.633856)
		(end 25.472898 -318.633856)
		(width 0.12954)
		(layer "B.Cu")
		(net "PD_CHC_CPU1_DIMM1_SAA")
	)
	(segment
		(start 280.29662 -320.954908)
		(end 280.29662 -320.792348)
		(width 0.12954)
		(layer "F.Cu")
		(net "PD_CHC_CPU0_DIMM2_SAA")
	)
	(segment
		(start 282.222194 -318.866774)
		(end 282.811982 -318.866774)
		(width 0.12954)
		(layer "F.Cu")
		(net "PD_CHC_CPU0_DIMM2_SAA")
	)
	(segment
		(start 280.29662 -320.792348)
		(end 282.222194 -318.866774)
		(width 0.12954)
		(layer "F.Cu")
		(net "PD_CHC_CPU0_DIMM2_SAA")
	)
	(via
		(at 280.29662 -320.954908)
		(size 0.4572)
		(drill 0.2032)
		(layers "F.Cu" "B.Cu")
		(net "PD_CHC_CPU0_DIMM2_SAA")
	)
	(segment
		(start 281.38882 -318.994282)
		(end 281.115262 -318.720724)
		(width 0.12954)
		(layer "B.Cu")
		(net "PD_CHC_CPU0_DIMM2_SAA")
	)
	(segment
		(start 281.115262 -318.720724)
		(end 280.852118 -318.720724)
		(width 0.12954)
		(layer "B.Cu")
		(net "PD_CHC_CPU0_DIMM2_SAA")
	)
	(segment
		(start 280.29662 -320.794888)
		(end 281.38882 -319.702688)
		(width 0.12954)
		(layer "B.Cu")
		(net "PD_CHC_CPU0_DIMM2_SAA")
	)
	(segment
		(start 281.38882 -319.702688)
		(end 281.38882 -318.994282)
		(width 0.12954)
		(layer "B.Cu")
		(net "PD_CHC_CPU0_DIMM2_SAA")
	)
	(segment
		(start 280.29662 -320.954908)
		(end 280.29662 -320.794888)
		(width 0.12954)
		(layer "B.Cu")
		(net "PD_CHC_CPU0_DIMM2_SAA")
	)
	(segment
		(start 273.43608 -319.804288)
		(end 274.373594 -318.866774)
		(width 0.12954)
		(layer "F.Cu")
		(net "PD_CHC_CPU0_DIMM1_SAA")
	)
	(segment
		(start 274.373594 -318.866774)
		(end 275.268182 -318.866774)
		(width 0.12954)
		(layer "F.Cu")
		(net "PD_CHC_CPU0_DIMM1_SAA")
	)
	(via
		(at 273.43608 -319.804288)
		(size 0.4572)
		(drill 0.2032)
		(layers "F.Cu" "B.Cu")
		(net "PD_CHC_CPU0_DIMM1_SAA")
	)
	(segment
		(start 273.43608 -319.804288)
		(end 273.43608 -318.73063)
		(width 0.12954)
		(layer "B.Cu")
		(net "PD_CHC_CPU0_DIMM1_SAA")
	)
	(segment
		(start 273.43608 -318.73063)
		(end 273.349466 -318.644016)
		(width 0.12954)
		(layer "B.Cu")
		(net "PD_CHC_CPU0_DIMM1_SAA")
	)
	(segment
		(start 48.854614 -318.866774)
		(end 49.959514 -318.866774)
		(width 0.12954)
		(layer "F.Cu")
		(net "PD_CHB_CPU1_DIMM2_SAA")
	)
	(via
		(at 48.854614 -318.866774)
		(size 0.4572)
		(drill 0.2032)
		(layers "F.Cu" "B.Cu")
		(net "PD_CHB_CPU1_DIMM2_SAA")
	)
	(via
		(at 47.877222 -317.8556)
		(size 0.6604)
		(drill 0.3302)
		(layers "F.Cu" "B.Cu")
		(net "PD_CHB_CPU1_DIMM2_SAA")
	)
	(segment
		(start 48.854614 -318.866774)
		(end 48.63973 -318.65189)
		(width 0.12954)
		(layer "B.Cu")
		(net "PD_CHB_CPU1_DIMM2_SAA")
	)
	(segment
		(start 47.877222 -317.8556)
		(end 47.877222 -318.389254)
		(width 0.12954)
		(layer "B.Cu")
		(net "PD_CHB_CPU1_DIMM2_SAA")
	)
	(segment
		(start 47.877222 -318.389254)
		(end 48.089566 -318.601598)
		(width 0.12954)
		(layer "B.Cu")
		(net "PD_CHB_CPU1_DIMM2_SAA")
	)
	(segment
		(start 48.089566 -318.601598)
		(end 48.089566 -319.009522)
		(width 0.12954)
		(layer "B.Cu")
		(net "PD_CHB_CPU1_DIMM2_SAA")
	)
	(segment
		(start 48.447198 -318.65189)
		(end 48.089566 -319.009522)
		(width 0.12954)
		(layer "B.Cu")
		(net "PD_CHB_CPU1_DIMM2_SAA")
	)
	(segment
		(start 48.63973 -318.65189)
		(end 48.447198 -318.65189)
		(width 0.12954)
		(layer "B.Cu")
		(net "PD_CHB_CPU1_DIMM2_SAA")
	)
	(segment
		(start 41.310814 -318.866774)
		(end 42.415714 -318.866774)
		(width 0.12954)
		(layer "F.Cu")
		(net "PD_CHB_CPU1_DIMM1_SAA")
	)
	(via
		(at 41.310814 -318.866774)
		(size 0.4572)
		(drill 0.2032)
		(layers "F.Cu" "B.Cu")
		(net "PD_CHB_CPU1_DIMM1_SAA")
	)
	(via
		(at 40.03294 -316.697868)
		(size 0.6604)
		(drill 0.3302)
		(layers "F.Cu" "B.Cu")
		(net "PD_CHB_CPU1_DIMM1_SAA")
	)
	(segment
		(start 41.310814 -318.866774)
		(end 40.521382 -318.866774)
		(width 0.12954)
		(layer "B.Cu")
		(net "PD_CHB_CPU1_DIMM1_SAA")
	)
	(segment
		(start 40.03294 -316.697868)
		(end 40.03294 -318.354964)
		(width 0.12954)
		(layer "B.Cu")
		(net "PD_CHB_CPU1_DIMM1_SAA")
	)
	(segment
		(start 40.03294 -318.354964)
		(end 40.021256 -318.366648)
		(width 0.12954)
		(layer "B.Cu")
		(net "PD_CHB_CPU1_DIMM1_SAA")
	)
	(segment
		(start 40.521382 -318.866774)
		(end 40.021256 -318.366648)
		(width 0.12954)
		(layer "B.Cu")
		(net "PD_CHB_CPU1_DIMM1_SAA")
	)
	(segment
		(start 296.794682 -318.866774)
		(end 297.899582 -318.866774)
		(width 0.12954)
		(layer "F.Cu")
		(net "PD_CHB_CPU0_DIMM2_SAA")
	)
	(via
		(at 296.794682 -318.866774)
		(size 0.4572)
		(drill 0.254)
		(layers "F.Cu" "B.Cu")
		(net "PD_CHB_CPU0_DIMM2_SAA")
	)
	(segment
		(start 296.136314 -318.866774)
		(end 296.070274 -318.800734)
		(width 0.12954)
		(layer "B.Cu")
		(net "PD_CHB_CPU0_DIMM2_SAA")
	)
	(segment
		(start 296.794682 -318.866774)
		(end 296.136314 -318.866774)
		(width 0.12954)
		(layer "B.Cu")
		(net "PD_CHB_CPU0_DIMM2_SAA")
	)
	(segment
		(start 295.651682 -318.800734)
		(end 295.628314 -318.777366)
		(width 0.12954)
		(layer "B.Cu")
		(net "PD_CHB_CPU0_DIMM2_SAA")
	)
	(segment
		(start 296.070274 -318.800734)
		(end 295.651682 -318.800734)
		(width 0.12954)
		(layer "B.Cu")
		(net "PD_CHB_CPU0_DIMM2_SAA")
	)
	(segment
		(start 289.250882 -318.866774)
		(end 290.355782 -318.866774)
		(width 0.12954)
		(layer "F.Cu")
		(net "PD_CHB_CPU0_DIMM1_SAA")
	)
	(via
		(at 289.250882 -318.866774)
		(size 0.4572)
		(drill 0.254)
		(layers "F.Cu" "B.Cu")
		(net "PD_CHB_CPU0_DIMM1_SAA")
	)
	(segment
		(start 288.560764 -319.99047)
		(end 288.575242 -320.004948)
		(width 0.12954)
		(layer "B.Cu")
		(net "PD_CHB_CPU0_DIMM1_SAA")
	)
	(segment
		(start 288.560764 -319.627504)
		(end 288.560764 -319.99047)
		(width 0.12954)
		(layer "B.Cu")
		(net "PD_CHB_CPU0_DIMM1_SAA")
	)
	(segment
		(start 289.250882 -318.866774)
		(end 289.250882 -318.937386)
		(width 0.12954)
		(layer "B.Cu")
		(net "PD_CHB_CPU0_DIMM1_SAA")
	)
	(segment
		(start 289.250882 -318.937386)
		(end 288.560764 -319.627504)
		(width 0.12954)
		(layer "B.Cu")
		(net "PD_CHB_CPU0_DIMM1_SAA")
	)
	(segment
		(start 64.098678 -319.35547)
		(end 64.587374 -318.866774)
		(width 0.12954)
		(layer "F.Cu")
		(net "PD_CHA_CPU1_DIMM2_SAA")
	)
	(segment
		(start 63.133478 -319.35547)
		(end 64.098678 -319.35547)
		(width 0.12954)
		(layer "F.Cu")
		(net "PD_CHA_CPU1_DIMM2_SAA")
	)
	(segment
		(start 63.003938 -319.82537)
		(end 63.003938 -319.48501)
		(width 0.12954)
		(layer "F.Cu")
		(net "PD_CHA_CPU1_DIMM2_SAA")
	)
	(segment
		(start 63.003938 -319.48501)
		(end 63.133478 -319.35547)
		(width 0.12954)
		(layer "F.Cu")
		(net "PD_CHA_CPU1_DIMM2_SAA")
	)
	(segment
		(start 64.587374 -318.866774)
		(end 65.047114 -318.866774)
		(width 0.12954)
		(layer "F.Cu")
		(net "PD_CHA_CPU1_DIMM2_SAA")
	)
	(via
		(at 63.003938 -320.523108)
		(size 0.6604)
		(drill 0.3302)
		(layers "F.Cu" "B.Cu")
		(net "PD_CHA_CPU1_DIMM2_SAA")
	)
	(via
		(at 63.003938 -319.82537)
		(size 0.4572)
		(drill 0.2032)
		(layers "F.Cu" "B.Cu")
		(net "PD_CHA_CPU1_DIMM2_SAA")
	)
	(segment
		(start 63.003938 -319.82537)
		(end 62.565534 -318.767206)
		(width 0.12954)
		(layer "B.Cu")
		(net "PD_CHA_CPU1_DIMM2_SAA")
	)
	(segment
		(start 62.565534 -318.767206)
		(end 62.392052 -318.593724)
		(width 0.12954)
		(layer "B.Cu")
		(net "PD_CHA_CPU1_DIMM2_SAA")
	)
	(segment
		(start 63.003938 -320.523108)
		(end 63.003938 -319.82537)
		(width 0.12954)
		(layer "B.Cu")
		(net "PD_CHA_CPU1_DIMM2_SAA")
	)
	(segment
		(start 62.392052 -318.593724)
		(end 62.246764 -318.593724)
		(width 0.12954)
		(layer "B.Cu")
		(net "PD_CHA_CPU1_DIMM2_SAA")
	)
	(segment
		(start 56.398414 -318.866774)
		(end 57.503314 -318.866774)
		(width 0.12954)
		(layer "F.Cu")
		(net "PD_CHA_CPU1_DIMM1_SAA")
	)
	(via
		(at 55.52186 -317.845948)
		(size 0.6604)
		(drill 0.3302)
		(layers "F.Cu" "B.Cu")
		(net "PD_CHA_CPU1_DIMM1_SAA")
	)
	(via
		(at 56.398414 -318.866774)
		(size 0.4572)
		(drill 0.2032)
		(layers "F.Cu" "B.Cu")
		(net "PD_CHA_CPU1_DIMM1_SAA")
	)
	(segment
		(start 56.398414 -318.722502)
		(end 55.52186 -317.845948)
		(width 0.12954)
		(layer "B.Cu")
		(net "PD_CHA_CPU1_DIMM1_SAA")
	)
	(segment
		(start 55.52186 -318.851534)
		(end 55.680102 -319.009776)
		(width 0.12954)
		(layer "B.Cu")
		(net "PD_CHA_CPU1_DIMM1_SAA")
	)
	(segment
		(start 56.398414 -318.866774)
		(end 56.398414 -318.722502)
		(width 0.12954)
		(layer "B.Cu")
		(net "PD_CHA_CPU1_DIMM1_SAA")
	)
	(segment
		(start 55.52186 -317.845948)
		(end 55.52186 -318.851534)
		(width 0.12954)
		(layer "B.Cu")
		(net "PD_CHA_CPU1_DIMM1_SAA")
	)
	(segment
		(start 310.944006 -319.82537)
		(end 310.944006 -319.43929)
		(width 0.12954)
		(layer "F.Cu")
		(net "PD_CHA_CPU0_DIMM2_SAA")
	)
	(segment
		(start 311.516522 -318.866774)
		(end 312.987182 -318.866774)
		(width 0.12954)
		(layer "F.Cu")
		(net "PD_CHA_CPU0_DIMM2_SAA")
	)
	(segment
		(start 310.944006 -319.43929)
		(end 311.516522 -318.866774)
		(width 0.12954)
		(layer "F.Cu")
		(net "PD_CHA_CPU0_DIMM2_SAA")
	)
	(via
		(at 310.944006 -319.82537)
		(size 0.4572)
		(drill 0.254)
		(layers "F.Cu" "B.Cu")
		(net "PD_CHA_CPU0_DIMM2_SAA")
	)
	(segment
		(start 310.944006 -319.82537)
		(end 310.343042 -319.224406)
		(width 0.12954)
		(layer "B.Cu")
		(net "PD_CHA_CPU0_DIMM2_SAA")
	)
	(segment
		(start 310.343042 -319.224406)
		(end 309.901082 -319.224406)
		(width 0.12954)
		(layer "B.Cu")
		(net "PD_CHA_CPU0_DIMM2_SAA")
	)
	(segment
		(start 303.10328 -321.981068)
		(end 303.10328 -320.048128)
		(width 0.12954)
		(layer "F.Cu")
		(net "PD_CHA_CPU0_DIMM1_SAA")
	)
	(segment
		(start 303.17186 -322.049648)
		(end 303.10328 -321.981068)
		(width 0.12954)
		(layer "F.Cu")
		(net "PD_CHA_CPU0_DIMM1_SAA")
	)
	(segment
		(start 303.10328 -320.048128)
		(end 304.284634 -318.866774)
		(width 0.12954)
		(layer "F.Cu")
		(net "PD_CHA_CPU0_DIMM1_SAA")
	)
	(segment
		(start 304.284634 -318.866774)
		(end 305.443382 -318.866774)
		(width 0.12954)
		(layer "F.Cu")
		(net "PD_CHA_CPU0_DIMM1_SAA")
	)
	(via
		(at 303.17186 -322.049648)
		(size 0.4572)
		(drill 0.2032)
		(layers "F.Cu" "B.Cu")
		(net "PD_CHA_CPU0_DIMM1_SAA")
	)
	(segment
		(start 303.17186 -322.049648)
		(end 303.07534 -321.953128)
		(width 0.12954)
		(layer "B.Cu")
		(net "PD_CHA_CPU0_DIMM1_SAA")
	)
	(segment
		(start 303.07534 -321.953128)
		(end 303.07534 -320.045588)
		(width 0.12954)
		(layer "B.Cu")
		(net "PD_CHA_CPU0_DIMM1_SAA")
	)
	(segment
		(start 303.549304 -319.571624)
		(end 303.549304 -319.05956)
		(width 0.12954)
		(layer "B.Cu")
		(net "PD_CHA_CPU0_DIMM1_SAA")
	)
	(segment
		(start 303.07534 -320.045588)
		(end 303.549304 -319.571624)
		(width 0.12954)
		(layer "B.Cu")
		(net "PD_CHA_CPU0_DIMM1_SAA")
	)
	(segment
		(start 434.248052 -40.104568)
		(end 434.785516 -40.104568)
		(width 0.12954)
		(layer "F.Cu")
		(net "PD_BIOS_IMAGE_SWAP_N")
	)
	(segment
		(start 426.630084 -36.999926)
		(end 426.806868 -36.999926)
		(width 0.12954)
		(layer "F.Cu")
		(net "PD_BIOS_IMAGE_SWAP_N")
	)
	(segment
		(start 430.546256 -35.817048)
		(end 433.272692 -38.543484)
		(width 0.12954)
		(layer "F.Cu")
		(net "PD_BIOS_IMAGE_SWAP_N")
	)
	(segment
		(start 433.272692 -39.129208)
		(end 434.248052 -40.104568)
		(width 0.12954)
		(layer "F.Cu")
		(net "PD_BIOS_IMAGE_SWAP_N")
	)
	(segment
		(start 426.806868 -36.999926)
		(end 427.989746 -35.817048)
		(width 0.12954)
		(layer "F.Cu")
		(net "PD_BIOS_IMAGE_SWAP_N")
	)
	(segment
		(start 433.272692 -38.543484)
		(end 433.272692 -39.129208)
		(width 0.12954)
		(layer "F.Cu")
		(net "PD_BIOS_IMAGE_SWAP_N")
	)
	(segment
		(start 427.989746 -35.817048)
		(end 430.546256 -35.817048)
		(width 0.12954)
		(layer "F.Cu")
		(net "PD_BIOS_IMAGE_SWAP_N")
	)
	(via
		(at 433.272692 -39.129208)
		(size 0.762)
		(drill 0.381)
		(layers "F.Cu" "B.Cu")
		(net "PD_BIOS_IMAGE_SWAP_N")
	)
	(segment
		(start 372.461282 -57.23382)
		(end 373.261636 -57.23382)
		(width 0.12954)
		(layer "F.Cu")
		(net "PD_74CB_A9")
	)
	(segment
		(start 373.261636 -57.23382)
		(end 373.291608 -57.263792)
		(width 0.12954)
		(layer "F.Cu")
		(net "PD_74CB_A9")
	)
	(segment
		(start 373.291608 -57.263792)
		(end 373.712232 -57.263792)
		(width 0.12954)
		(layer "F.Cu")
		(net "PD_74CB_A9")
	)
	(segment
		(start 370.683282 -57.23382)
		(end 372.461282 -57.23382)
		(width 0.12954)
		(layer "F.Cu")
		(net "PD_74CB_A9")
	)
	(via
		(at 372.461282 -57.23382)
		(size 0.762)
		(drill 0.381)
		(layers "F.Cu" "B.Cu")
		(net "PD_74CB_A9")
	)
	(segment
		(start 180.323744 -56.299862)
		(end 177.108104 -56.299862)
		(width 0.12954)
		(layer "F.Cu")
		(net "PCIE_M2_SSD0_PRSNT_N")
	)
	(segment
		(start 180.37683 -57.959498)
		(end 180.37683 -56.352948)
		(width 0.12954)
		(layer "F.Cu")
		(net "PCIE_M2_SSD0_PRSNT_N")
	)
	(segment
		(start 185.355738 -108.175552)
		(end 185.755788 -107.775502)
		(width 0.12954)
		(layer "F.Cu")
		(net "PCIE_M2_SSD0_PRSNT_N")
	)
	(segment
		(start 180.37683 -56.352948)
		(end 180.323744 -56.299862)
		(width 0.12954)
		(layer "F.Cu")
		(net "PCIE_M2_SSD0_PRSNT_N")
	)
	(segment
		(start 186.11088 -58.765948)
		(end 185.90768 -58.562748)
		(width 0.12954)
		(layer "F.Cu")
		(net "PCIE_M2_SSD0_PRSNT_N")
	)
	(segment
		(start 180.98008 -58.562748)
		(end 180.37683 -57.959498)
		(width 0.12954)
		(layer "F.Cu")
		(net "PCIE_M2_SSD0_PRSNT_N")
	)
	(segment
		(start 185.90768 -58.562748)
		(end 180.98008 -58.562748)
		(width 0.12954)
		(layer "F.Cu")
		(net "PCIE_M2_SSD0_PRSNT_N")
	)
	(via
		(at 185.755788 -107.775502)
		(size 0.4572)
		(drill 0.254)
		(layers "F.Cu" "B.Cu")
		(net "PCIE_M2_SSD0_PRSNT_N")
	)
	(via
		(at 186.11088 -58.765948)
		(size 0.508)
		(drill 0.254)
		(layers "F.Cu" "B.Cu")
		(net "PCIE_M2_SSD0_PRSNT_N")
	)
	(segment
		(start 185.586878 -59.28995)
		(end 186.11088 -58.765948)
		(width 0.127)
		(layer "In2.Cu")
		(net "PCIE_M2_SSD0_PRSNT_N")
	)
	(segment
		(start 186.1566 -102.641908)
		(end 185.5597 -102.045008)
		(width 0.127)
		(layer "In2.Cu")
		(net "PCIE_M2_SSD0_PRSNT_N")
	)
	(segment
		(start 185.5597 -102.045008)
		(end 185.5597 -100.556568)
		(width 0.127)
		(layer "In2.Cu")
		(net "PCIE_M2_SSD0_PRSNT_N")
	)
	(segment
		(start 186.1566 -107.37469)
		(end 186.1566 -102.641908)
		(width 0.127)
		(layer "In2.Cu")
		(net "PCIE_M2_SSD0_PRSNT_N")
	)
	(segment
		(start 187.2742 -98.0186)
		(end 188.5188 -98.0186)
		(width 0.127)
		(layer "In2.Cu")
		(net "PCIE_M2_SSD0_PRSNT_N")
	)
	(segment
		(start 185.586878 -78.915006)
		(end 185.586878 -59.28995)
		(width 0.127)
		(layer "In2.Cu")
		(net "PCIE_M2_SSD0_PRSNT_N")
	)
	(segment
		(start 185.5597 -100.556568)
		(end 186.78144 -99.334828)
		(width 0.127)
		(layer "In2.Cu")
		(net "PCIE_M2_SSD0_PRSNT_N")
	)
	(segment
		(start 189.4078 -97.1296)
		(end 189.4078 -82.735928)
		(width 0.127)
		(layer "In2.Cu")
		(net "PCIE_M2_SSD0_PRSNT_N")
	)
	(segment
		(start 186.78144 -98.51136)
		(end 187.2742 -98.0186)
		(width 0.127)
		(layer "In2.Cu")
		(net "PCIE_M2_SSD0_PRSNT_N")
	)
	(segment
		(start 186.78144 -99.334828)
		(end 186.78144 -98.51136)
		(width 0.127)
		(layer "In2.Cu")
		(net "PCIE_M2_SSD0_PRSNT_N")
	)
	(segment
		(start 185.755788 -107.775502)
		(end 186.1566 -107.37469)
		(width 0.127)
		(layer "In2.Cu")
		(net "PCIE_M2_SSD0_PRSNT_N")
	)
	(segment
		(start 189.4078 -82.735928)
		(end 185.586878 -78.915006)
		(width 0.127)
		(layer "In2.Cu")
		(net "PCIE_M2_SSD0_PRSNT_N")
	)
	(segment
		(start 188.5188 -98.0186)
		(end 189.4078 -97.1296)
		(width 0.127)
		(layer "In2.Cu")
		(net "PCIE_M2_SSD0_PRSNT_N")
	)
	(segment
		(start 340.562946 -43.281346)
		(end 340.290658 -42.811446)
		(width 0.254)
		(layer "F.Cu")
		(net "PCH_PCIEUP_RCOMPP")
	)
	(via
		(at 339.736938 -43.280838)
		(size 0.6604)
		(drill 0.3302)
		(layers "F.Cu" "B.Cu")
		(net "PCH_PCIEUP_RCOMPP")
	)
	(via
		(at 340.290658 -42.811446)
		(size 0.4572)
		(drill 0.2032)
		(layers "F.Cu" "B.Cu")
		(net "PCH_PCIEUP_RCOMPP")
	)
	(segment
		(start 339.736938 -43.280838)
		(end 339.736938 -43.367706)
		(width 0.254)
		(layer "B.Cu")
		(net "PCH_PCIEUP_RCOMPP")
	)
	(segment
		(start 340.290658 -42.811446)
		(end 340.20633 -42.811446)
		(width 0.254)
		(layer "B.Cu")
		(net "PCH_PCIEUP_RCOMPP")
	)
	(segment
		(start 339.736938 -43.367706)
		(end 340.533482 -44.16425)
		(width 0.254)
		(layer "B.Cu")
		(net "PCH_PCIEUP_RCOMPP")
	)
	(segment
		(start 340.20633 -42.811446)
		(end 339.736938 -43.280838)
		(width 0.254)
		(layer "B.Cu")
		(net "PCH_PCIEUP_RCOMPP")
	)
	(segment
		(start 341.097362 -43.281346)
		(end 341.36838 -43.74896)
		(width 0.254)
		(layer "F.Cu")
		(net "PCH_PCIEUP_RCOMPN")
	)
	(segment
		(start 341.36838 -43.74896)
		(end 341.37727 -43.751246)
		(width 0.254)
		(layer "F.Cu")
		(net "PCH_PCIEUP_RCOMPN")
	)
	(via
		(at 341.097362 -43.281346)
		(size 0.4572)
		(drill 0.2032)
		(layers "F.Cu" "B.Cu")
		(net "PCH_PCIEUP_RCOMPN")
	)
	(segment
		(start 341.226394 -44.007532)
		(end 341.226394 -44.564554)
		(width 0.254)
		(layer "B.Cu")
		(net "PCH_PCIEUP_RCOMPN")
	)
	(segment
		(start 341.097362 -43.518582)
		(end 341.226394 -44.007532)
		(width 0.254)
		(layer "B.Cu")
		(net "PCH_PCIEUP_RCOMPN")
	)
	(segment
		(start 341.097362 -43.281346)
		(end 341.097362 -43.518582)
		(width 0.254)
		(layer "B.Cu")
		(net "PCH_PCIEUP_RCOMPN")
	)
	(segment
		(start 54.642766 -117.40769)
		(end 55.893716 -117.40769)
		(width 0.12954)
		(layer "F.Cu")
		(net "PCA9548_PCIE0_ADDR0")
	)
	(segment
		(start 55.893716 -117.40769)
		(end 56.782716 -117.40769)
		(width 0.12954)
		(layer "F.Cu")
		(net "PCA9548_PCIE0_ADDR0")
	)
	(segment
		(start 54.642766 -117.43309)
		(end 53.139086 -118.93677)
		(width 0.12954)
		(layer "F.Cu")
		(net "PCA9548_PCIE0_ADDR0")
	)
	(segment
		(start 54.642766 -117.40769)
		(end 54.642766 -117.43309)
		(width 0.12954)
		(layer "F.Cu")
		(net "PCA9548_PCIE0_ADDR0")
	)
	(segment
		(start 57.61101 -114.801396)
		(end 58.37555 -114.801396)
		(width 0.12954)
		(layer "F.Cu")
		(net "PCA9548_PCIE0_ADDR0")
	)
	(segment
		(start 57.417716 -114.99469)
		(end 57.61101 -114.801396)
		(width 0.12954)
		(layer "F.Cu")
		(net "PCA9548_PCIE0_ADDR0")
	)
	(segment
		(start 57.417716 -116.77269)
		(end 57.417716 -114.99469)
		(width 0.12954)
		(layer "F.Cu")
		(net "PCA9548_PCIE0_ADDR0")
	)
	(segment
		(start 56.782716 -117.40769)
		(end 57.417716 -116.77269)
		(width 0.12954)
		(layer "F.Cu")
		(net "PCA9548_PCIE0_ADDR0")
	)
	(segment
		(start 53.139086 -118.93677)
		(end 51.993546 -118.93677)
		(width 0.12954)
		(layer "F.Cu")
		(net "PCA9548_PCIE0_ADDR0")
	)
	(via
		(at 55.893716 -117.40769)
		(size 0.762)
		(drill 0.381)
		(layers "F.Cu" "B.Cu")
		(net "PCA9548_PCIE0_ADDR0")
	)
	(segment
		(start 161.055304 -77.220064)
		(end 161.698178 -77.862938)
		(width 0.12954)
		(layer "F.Cu")
		(net "PCA9543_S3M_INT1_N")
	)
	(segment
		(start 157.985968 -77.220064)
		(end 159.665162 -77.220064)
		(width 0.12954)
		(layer "F.Cu")
		(net "PCA9543_S3M_INT1_N")
	)
	(segment
		(start 161.698178 -77.862938)
		(end 161.94278 -77.862938)
		(width 0.12954)
		(layer "F.Cu")
		(net "PCA9543_S3M_INT1_N")
	)
	(segment
		(start 159.665162 -77.220064)
		(end 161.055304 -77.220064)
		(width 0.12954)
		(layer "F.Cu")
		(net "PCA9543_S3M_INT1_N")
	)
	(via
		(at 159.665162 -77.220064)
		(size 0.762)
		(drill 0.381)
		(layers "F.Cu" "B.Cu")
		(net "PCA9543_S3M_INT1_N")
	)
	(segment
		(start 159.98698 -75.269852)
		(end 160.170876 -75.269852)
		(width 0.12954)
		(layer "F.Cu")
		(net "PCA9543_S3M_INT0_N")
	)
	(segment
		(start 161.94151 -74.757788)
		(end 161.94278 -74.759058)
		(width 0.12954)
		(layer "F.Cu")
		(net "PCA9543_S3M_INT0_N")
	)
	(segment
		(start 157.985968 -75.269852)
		(end 159.98698 -75.269852)
		(width 0.12954)
		(layer "F.Cu")
		(net "PCA9543_S3M_INT0_N")
	)
	(segment
		(start 160.170876 -75.269852)
		(end 160.68294 -74.757788)
		(width 0.12954)
		(layer "F.Cu")
		(net "PCA9543_S3M_INT0_N")
	)
	(segment
		(start 160.68294 -74.757788)
		(end 161.94151 -74.757788)
		(width 0.12954)
		(layer "F.Cu")
		(net "PCA9543_S3M_INT0_N")
	)
	(via
		(at 159.98698 -75.269852)
		(size 0.762)
		(drill 0.381)
		(layers "F.Cu" "B.Cu")
		(net "PCA9543_S3M_INT0_N")
	)
	(segment
		(start 153.60015 -70.66407)
		(end 154.65933 -70.66407)
		(width 0.12954)
		(layer "F.Cu")
		(net "PCA9543_S3M_ADDR1")
	)
	(segment
		(start 157.985968 -73.96988)
		(end 156.229812 -73.96988)
		(width 0.12954)
		(layer "F.Cu")
		(net "PCA9543_S3M_ADDR1")
	)
	(segment
		(start 154.66568 -71.956168)
		(end 154.66568 -70.67042)
		(width 0.12954)
		(layer "F.Cu")
		(net "PCA9543_S3M_ADDR1")
	)
	(segment
		(start 156.229812 -73.96988)
		(end 154.66568 -72.405748)
		(width 0.12954)
		(layer "F.Cu")
		(net "PCA9543_S3M_ADDR1")
	)
	(segment
		(start 154.66568 -70.67042)
		(end 154.65933 -70.66407)
		(width 0.12954)
		(layer "F.Cu")
		(net "PCA9543_S3M_ADDR1")
	)
	(segment
		(start 154.66568 -72.405748)
		(end 154.66568 -71.956168)
		(width 0.12954)
		(layer "F.Cu")
		(net "PCA9543_S3M_ADDR1")
	)
	(via
		(at 154.66568 -71.956168)
		(size 0.762)
		(drill 0.381)
		(layers "F.Cu" "B.Cu")
		(net "PCA9543_S3M_ADDR1")
	)
	(segment
		(start 157.985968 -73.319894)
		(end 157.362906 -73.319894)
		(width 0.12954)
		(layer "F.Cu")
		(net "PCA9543_S3M_ADDR0")
	)
	(segment
		(start 155.98013 -71.271638)
		(end 155.98013 -70.66407)
		(width 0.12954)
		(layer "F.Cu")
		(net "PCA9543_S3M_ADDR0")
	)
	(segment
		(start 157.362906 -73.319894)
		(end 156.66466 -72.621648)
		(width 0.12954)
		(layer "F.Cu")
		(net "PCA9543_S3M_ADDR0")
	)
	(segment
		(start 156.66466 -71.956168)
		(end 155.98013 -71.271638)
		(width 0.12954)
		(layer "F.Cu")
		(net "PCA9543_S3M_ADDR0")
	)
	(segment
		(start 156.66466 -72.621648)
		(end 156.66466 -71.956168)
		(width 0.12954)
		(layer "F.Cu")
		(net "PCA9543_S3M_ADDR0")
	)
	(segment
		(start 157.00121 -70.66407)
		(end 155.98013 -70.66407)
		(width 0.12954)
		(layer "F.Cu")
		(net "PCA9543_S3M_ADDR0")
	)
	(via
		(at 156.66466 -71.956168)
		(size 0.762)
		(drill 0.381)
		(layers "F.Cu" "B.Cu")
		(net "PCA9543_S3M_ADDR0")
	)
	(segment
		(start 152.36317 -116.506752)
		(end 151.69388 -116.506752)
		(width 0.4572)
		(layer "F.Cu")
		(net "P5V_AUX_VCC")
	)
	(segment
		(start 456.147678 -386.484368)
		(end 456.147678 -387.205982)
		(width 0.254)
		(layer "F.Cu")
		(net "P5V_AUX_VCC")
	)
	(segment
		(start 456.072494 -387.281166)
		(end 456.072494 -387.923278)
		(width 0.381)
		(layer "F.Cu")
		(net "P5V_AUX_VCC")
	)
	(segment
		(start 456.147678 -387.205982)
		(end 456.072494 -387.281166)
		(width 0.254)
		(layer "F.Cu")
		(net "P5V_AUX_VCC")
	)
	(segment
		(start 456.072494 -387.923278)
		(end 456.044808 -387.950964)
		(width 0.381)
		(layer "F.Cu")
		(net "P5V_AUX_VCC")
	)
	(via
		(at 155.41498 -130.19024)
		(size 0.508)
		(drill 0.254)
		(layers "F.Cu" "B.Cu")
		(net "P5V_AUX_VCC")
	)
	(via
		(at 456.072494 -387.281166)
		(size 0.508)
		(drill 0.254)
		(layers "F.Cu" "B.Cu")
		(net "P5V_AUX_VCC")
	)
	(via
		(at 202.54468 -130.175762)
		(size 0.508)
		(drill 0.254)
		(layers "F.Cu" "B.Cu")
		(net "P5V_AUX_VCC")
	)
	(via
		(at 238.440468 -204.173074)
		(size 0.508)
		(drill 0.254)
		(layers "F.Cu" "B.Cu")
		(net "P5V_AUX_VCC")
	)
	(via
		(at 151.69388 -116.506752)
		(size 0.508)
		(drill 0.254)
		(layers "F.Cu" "B.Cu")
		(net "P5V_AUX_VCC")
	)
	(via
		(at 304.418238 -391.075418)
		(size 0.508)
		(drill 0.254)
		(layers "F.Cu" "B.Cu")
		(net "P5V_AUX_VCC")
	)
	(segment
		(start 456.072494 -387.281166)
		(end 456.072494 -385.264914)
		(width 0.508)
		(layer "B.Cu")
		(net "P5V_AUX_VCC")
	)
	(segment
		(start 151.69388 -119.81688)
		(end 151.69388 -116.506752)
		(width 0.4572)
		(layer "B.Cu")
		(net "P5V_AUX_VCC")
	)
	(segment
		(start 154.7114 -122.8344)
		(end 151.69388 -119.81688)
		(width 0.4572)
		(layer "B.Cu")
		(net "P5V_AUX_VCC")
	)
	(segment
		(start 457.68641 -383.650998)
		(end 459.675738 -383.650998)
		(width 0.508)
		(layer "B.Cu")
		(net "P5V_AUX_VCC")
	)
	(segment
		(start 456.072494 -385.264914)
		(end 457.68641 -383.650998)
		(width 0.508)
		(layer "B.Cu")
		(net "P5V_AUX_VCC")
	)
	(segment
		(start 155.41498 -129.50698)
		(end 154.7114 -128.8034)
		(width 0.4572)
		(layer "B.Cu")
		(net "P5V_AUX_VCC")
	)
	(segment
		(start 154.7114 -128.8034)
		(end 154.7114 -122.8344)
		(width 0.4572)
		(layer "B.Cu")
		(net "P5V_AUX_VCC")
	)
	(segment
		(start 155.41498 -130.19024)
		(end 155.41498 -129.50698)
		(width 0.4572)
		(layer "B.Cu")
		(net "P5V_AUX_VCC")
	)
	(segment
		(start 297.635168 -391.233152)
		(end 295.344596 -388.94258)
		(width 0.4572)
		(layer "In4.Cu")
		(net "P5V_AUX_VCC")
	)
	(segment
		(start 277.899114 -374.421654)
		(end 277.899114 -360.319574)
		(width 0.4572)
		(layer "In4.Cu")
		(net "P5V_AUX_VCC")
	)
	(segment
		(start 304.418238 -391.075418)
		(end 304.260504 -391.233152)
		(width 0.4572)
		(layer "In4.Cu")
		(net "P5V_AUX_VCC")
	)
	(segment
		(start 245.534434 -327.954894)
		(end 245.534434 -280.178002)
		(width 0.4572)
		(layer "In4.Cu")
		(net "P5V_AUX_VCC")
	)
	(segment
		(start 245.534434 -280.178002)
		(end 249.26798 -276.444456)
		(width 0.4572)
		(layer "In4.Cu")
		(net "P5V_AUX_VCC")
	)
	(segment
		(start 295.344596 -388.94258)
		(end 292.42004 -388.94258)
		(width 0.4572)
		(layer "In4.Cu")
		(net "P5V_AUX_VCC")
	)
	(segment
		(start 292.42004 -388.94258)
		(end 277.899114 -374.421654)
		(width 0.4572)
		(layer "In4.Cu")
		(net "P5V_AUX_VCC")
	)
	(segment
		(start 304.260504 -391.233152)
		(end 297.635168 -391.233152)
		(width 0.4572)
		(layer "In4.Cu")
		(net "P5V_AUX_VCC")
	)
	(segment
		(start 249.26798 -215.000586)
		(end 238.440468 -204.173074)
		(width 0.4572)
		(layer "In4.Cu")
		(net "P5V_AUX_VCC")
	)
	(segment
		(start 249.26798 -276.444456)
		(end 249.26798 -215.000586)
		(width 0.4572)
		(layer "In4.Cu")
		(net "P5V_AUX_VCC")
	)
	(segment
		(start 277.899114 -360.319574)
		(end 245.534434 -327.954894)
		(width 0.4572)
		(layer "In4.Cu")
		(net "P5V_AUX_VCC")
	)
	(segment
		(start 204.90942 -135.788908)
		(end 204.90942 -132.540502)
		(width 0.4572)
		(layer "In11.Cu")
		(net "P5V_AUX_VCC")
	)
	(segment
		(start 353.03841 -391.075418)
		(end 304.418238 -391.075418)
		(width 0.4572)
		(layer "In11.Cu")
		(net "P5V_AUX_VCC")
	)
	(segment
		(start 430.474882 -379.494034)
		(end 426.209714 -379.494034)
		(width 0.4572)
		(layer "In11.Cu")
		(net "P5V_AUX_VCC")
	)
	(segment
		(start 229.54488 -195.277486)
		(end 229.54488 -172.200824)
		(width 0.4572)
		(layer "In11.Cu")
		(net "P5V_AUX_VCC")
	)
	(segment
		(start 441.68568 -379.649228)
		(end 439.4454 -377.408948)
		(width 0.4572)
		(layer "In11.Cu")
		(net "P5V_AUX_VCC")
	)
	(segment
		(start 422.0718 -382.971548)
		(end 419.6334 -385.409948)
		(width 0.4572)
		(layer "In11.Cu")
		(net "P5V_AUX_VCC")
	)
	(segment
		(start 356.92588 -387.187948)
		(end 353.03841 -391.075418)
		(width 0.4572)
		(layer "In11.Cu")
		(net "P5V_AUX_VCC")
	)
	(segment
		(start 424.66768 -381.036068)
		(end 424.66768 -382.311148)
		(width 0.4572)
		(layer "In11.Cu")
		(net "P5V_AUX_VCC")
	)
	(segment
		(start 426.209714 -379.494034)
		(end 424.66768 -381.036068)
		(width 0.4572)
		(layer "In11.Cu")
		(net "P5V_AUX_VCC")
	)
	(segment
		(start 454.16216 -379.649228)
		(end 441.68568 -379.649228)
		(width 0.4572)
		(layer "In11.Cu")
		(net "P5V_AUX_VCC")
	)
	(segment
		(start 358.32288 -387.187948)
		(end 356.92588 -387.187948)
		(width 0.4572)
		(layer "In11.Cu")
		(net "P5V_AUX_VCC")
	)
	(segment
		(start 215.78824 -146.667728)
		(end 204.90942 -135.788908)
		(width 0.4572)
		(layer "In11.Cu")
		(net "P5V_AUX_VCC")
	)
	(segment
		(start 358.70388 -387.568948)
		(end 358.32288 -387.187948)
		(width 0.4572)
		(layer "In11.Cu")
		(net "P5V_AUX_VCC")
	)
	(segment
		(start 424.00728 -382.971548)
		(end 422.0718 -382.971548)
		(width 0.4572)
		(layer "In11.Cu")
		(net "P5V_AUX_VCC")
	)
	(segment
		(start 419.6334 -385.409948)
		(end 364.800134 -385.409948)
		(width 0.4572)
		(layer "In11.Cu")
		(net "P5V_AUX_VCC")
	)
	(segment
		(start 238.440468 -204.173074)
		(end 229.54488 -195.277486)
		(width 0.4572)
		(layer "In11.Cu")
		(net "P5V_AUX_VCC")
	)
	(segment
		(start 456.072494 -387.281166)
		(end 456.072494 -381.559562)
		(width 0.4572)
		(layer "In11.Cu")
		(net "P5V_AUX_VCC")
	)
	(segment
		(start 229.54488 -172.200824)
		(end 215.78824 -158.444184)
		(width 0.4572)
		(layer "In11.Cu")
		(net "P5V_AUX_VCC")
	)
	(segment
		(start 432.559968 -377.408948)
		(end 430.474882 -379.494034)
		(width 0.4572)
		(layer "In11.Cu")
		(net "P5V_AUX_VCC")
	)
	(segment
		(start 364.800134 -385.409948)
		(end 362.641134 -387.568948)
		(width 0.4572)
		(layer "In11.Cu")
		(net "P5V_AUX_VCC")
	)
	(segment
		(start 424.66768 -382.311148)
		(end 424.00728 -382.971548)
		(width 0.4572)
		(layer "In11.Cu")
		(net "P5V_AUX_VCC")
	)
	(segment
		(start 362.641134 -387.568948)
		(end 358.70388 -387.568948)
		(width 0.4572)
		(layer "In11.Cu")
		(net "P5V_AUX_VCC")
	)
	(segment
		(start 204.90942 -132.540502)
		(end 202.54468 -130.175762)
		(width 0.4572)
		(layer "In11.Cu")
		(net "P5V_AUX_VCC")
	)
	(segment
		(start 439.4454 -377.408948)
		(end 432.559968 -377.408948)
		(width 0.4572)
		(layer "In11.Cu")
		(net "P5V_AUX_VCC")
	)
	(segment
		(start 456.072494 -381.559562)
		(end 454.16216 -379.649228)
		(width 0.4572)
		(layer "In11.Cu")
		(net "P5V_AUX_VCC")
	)
	(segment
		(start 215.78824 -158.444184)
		(end 215.78824 -146.667728)
		(width 0.4572)
		(layer "In11.Cu")
		(net "P5V_AUX_VCC")
	)
	(segment
		(start 202.54468 -129.920238)
		(end 202.54468 -130.175762)
		(width 0.4572)
		(layer "In13.Cu")
		(net "P5V_AUX_VCC")
	)
	(segment
		(start 165.328092 -132.107178)
		(end 166.975282 -132.107178)
		(width 0.4572)
		(layer "In13.Cu")
		(net "P5V_AUX_VCC")
	)
	(segment
		(start 197.0913 -130.246628)
		(end 198.44258 -128.895348)
		(width 0.4572)
		(layer "In13.Cu")
		(net "P5V_AUX_VCC")
	)
	(segment
		(start 155.41498 -130.19024)
		(end 158.925768 -133.701028)
		(width 0.4572)
		(layer "In13.Cu")
		(net "P5V_AUX_VCC")
	)
	(segment
		(start 168.835832 -130.246628)
		(end 197.0913 -130.246628)
		(width 0.4572)
		(layer "In13.Cu")
		(net "P5V_AUX_VCC")
	)
	(segment
		(start 201.51979 -128.895348)
		(end 202.54468 -129.920238)
		(width 0.4572)
		(layer "In13.Cu")
		(net "P5V_AUX_VCC")
	)
	(segment
		(start 166.975282 -132.107178)
		(end 168.835832 -130.246628)
		(width 0.4572)
		(layer "In13.Cu")
		(net "P5V_AUX_VCC")
	)
	(segment
		(start 158.925768 -133.701028)
		(end 163.734242 -133.701028)
		(width 0.4572)
		(layer "In13.Cu")
		(net "P5V_AUX_VCC")
	)
	(segment
		(start 198.44258 -128.895348)
		(end 201.51979 -128.895348)
		(width 0.4572)
		(layer "In13.Cu")
		(net "P5V_AUX_VCC")
	)
	(segment
		(start 163.734242 -133.701028)
		(end 165.328092 -132.107178)
		(width 0.4572)
		(layer "In13.Cu")
		(net "P5V_AUX_VCC")
	)
	(segment
		(start 457.7461 -381.998474)
		(end 457.7461 -381.64897)
		(width 0.1778)
		(layer "F.Cu")
		(net "P5V_AUX_REF")
	)
	(segment
		(start 457.8477 -383.684272)
		(end 457.8477 -382.100074)
		(width 0.1778)
		(layer "F.Cu")
		(net "P5V_AUX_REF")
	)
	(segment
		(start 457.8477 -382.100074)
		(end 457.7461 -381.998474)
		(width 0.1778)
		(layer "F.Cu")
		(net "P5V_AUX_REF")
	)
	(segment
		(start 459.667864 -381.789686)
		(end 459.0161 -382.44145)
		(width 0.254)
		(layer "F.Cu")
		(net "P5V_AUX_FB")
	)
	(segment
		(start 458.867764 -380.649988)
		(end 459.667864 -381.450088)
		(width 0.254)
		(layer "F.Cu")
		(net "P5V_AUX_FB")
	)
	(segment
		(start 459.0161 -382.82372)
		(end 459.0161 -382.613916)
		(width 0.1778)
		(layer "F.Cu")
		(net "P5V_AUX_FB")
	)
	(segment
		(start 458.6478 -383.684272)
		(end 458.6478 -383.19202)
		(width 0.1778)
		(layer "F.Cu")
		(net "P5V_AUX_FB")
	)
	(segment
		(start 458.6478 -383.19202)
		(end 459.0161 -382.82372)
		(width 0.1778)
		(layer "F.Cu")
		(net "P5V_AUX_FB")
	)
	(segment
		(start 459.0161 -382.613916)
		(end 459.0161 -382.44145)
		(width 0.254)
		(layer "F.Cu")
		(net "P5V_AUX_FB")
	)
	(segment
		(start 458.867764 -380.572772)
		(end 458.867764 -380.649988)
		(width 0.254)
		(layer "F.Cu")
		(net "P5V_AUX_FB")
	)
	(segment
		(start 458.867764 -379.556772)
		(end 458.867764 -380.572772)
		(width 0.254)
		(layer "F.Cu")
		(net "P5V_AUX_FB")
	)
	(segment
		(start 459.667864 -381.450088)
		(end 459.667864 -381.606298)
		(width 0.254)
		(layer "F.Cu")
		(net "P5V_AUX_FB")
	)
	(segment
		(start 459.667864 -381.606298)
		(end 459.667864 -381.789686)
		(width 0.254)
		(layer "F.Cu")
		(net "P5V_AUX_FB")
	)
	(via
		(at 459.0161 -382.44145)
		(size 0.508)
		(drill 0.254)
		(layers "F.Cu" "B.Cu")
		(net "P5V_AUX_FB")
	)
	(segment
		(start 457.0476 -383.141474)
		(end 456.795886 -382.533906)
		(width 0.2032)
		(layer "F.Cu")
		(net "P5V_AUX_CS")
	)
	(segment
		(start 456.621388 -382.359408)
		(end 456.621388 -381.664972)
		(width 0.2032)
		(layer "F.Cu")
		(net "P5V_AUX_CS")
	)
	(segment
		(start 456.795886 -382.533906)
		(end 456.621388 -382.359408)
		(width 0.2032)
		(layer "F.Cu")
		(net "P5V_AUX_CS")
	)
	(segment
		(start 457.0476 -383.684272)
		(end 457.0476 -383.24282)
		(width 0.1778)
		(layer "F.Cu")
		(net "P5V_AUX_CS")
	)
	(segment
		(start 457.0476 -383.24282)
		(end 457.0476 -383.141474)
		(width 0.2032)
		(layer "F.Cu")
		(net "P5V_AUX_CS")
	)
	(segment
		(start 459.286864 -378.681488)
		(end 459.667864 -379.062488)
		(width 0.254)
		(layer "F.Cu")
		(net "P5V_AUX")
	)
	(segment
		(start 112.33531 -74.508106)
		(end 112.33531 -73.898506)
		(width 0.381)
		(layer "F.Cu")
		(net "P5V_AUX")
	)
	(segment
		(start 450.7357 -378.681488)
		(end 459.286864 -378.681488)
		(width 0.254)
		(layer "F.Cu")
		(net "P5V_AUX")
	)
	(segment
		(start 459.667864 -380.572772)
		(end 459.667864 -379.556772)
		(width 0.254)
		(layer "F.Cu")
		(net "P5V_AUX")
	)
	(segment
		(start 379.941836 -71.126858)
		(end 379.295406 -71.126858)
		(width 0.381)
		(layer "F.Cu")
		(net "P5V_AUX")
	)
	(segment
		(start 306.151534 -89.28862)
		(end 305.93665 -89.073736)
		(width 0.508)
		(layer "F.Cu")
		(net "P5V_AUX")
	)
	(segment
		(start 445.98844 -379.834648)
		(end 449.58254 -379.834648)
		(width 0.254)
		(layer "F.Cu")
		(net "P5V_AUX")
	)
	(segment
		(start 449.58254 -379.834648)
		(end 450.7357 -378.681488)
		(width 0.254)
		(layer "F.Cu")
		(net "P5V_AUX")
	)
	(segment
		(start 459.667864 -379.062488)
		(end 459.667864 -379.556772)
		(width 0.254)
		(layer "F.Cu")
		(net "P5V_AUX")
	)
	(segment
		(start 362.368338 -83.5787)
		(end 356.658418 -89.28862)
		(width 0.508)
		(layer "F.Cu")
		(net "P5V_AUX")
	)
	(segment
		(start 356.658418 -89.28862)
		(end 306.151534 -89.28862)
		(width 0.508)
		(layer "F.Cu")
		(net "P5V_AUX")
	)
	(via
		(at 400.453606 -76.435458)
		(size 0.508)
		(drill 0.254)
		(layers "F.Cu" "B.Cu")
		(net "P5V_AUX")
	)
	(via
		(at 443.053216 -387.343904)
		(size 0.508)
		(drill 0.254)
		(layers "F.Cu" "B.Cu")
		(net "P5V_AUX")
	)
	(via
		(at 438.829196 -384.54203)
		(size 0.508)
		(drill 0.254)
		(layers "F.Cu" "B.Cu")
		(net "P5V_AUX")
	)
	(via
		(at 439.24474 -386.321554)
		(size 0.508)
		(drill 0.254)
		(layers "F.Cu" "B.Cu")
		(net "P5V_AUX")
	)
	(via
		(at 440.00674 -388.73303)
		(size 0.508)
		(drill 0.254)
		(layers "F.Cu" "B.Cu")
		(net "P5V_AUX")
	)
	(via
		(at 439.24474 -388.73303)
		(size 0.508)
		(drill 0.254)
		(layers "F.Cu" "B.Cu")
		(net "P5V_AUX")
	)
	(via
		(at 438.441846 -380.05258)
		(size 0.508)
		(drill 0.254)
		(layers "F.Cu" "B.Cu")
		(net "P5V_AUX")
	)
	(via
		(at 440.76874 -388.73303)
		(size 0.508)
		(drill 0.254)
		(layers "F.Cu" "B.Cu")
		(net "P5V_AUX")
	)
	(via
		(at 438.829196 -382.49733)
		(size 0.508)
		(drill 0.254)
		(layers "F.Cu" "B.Cu")
		(net "P5V_AUX")
	)
	(via
		(at 438.48274 -386.321554)
		(size 0.508)
		(drill 0.254)
		(layers "F.Cu" "B.Cu")
		(net "P5V_AUX")
	)
	(via
		(at 305.93665 -89.073736)
		(size 0.508)
		(drill 0.254)
		(layers "F.Cu" "B.Cu")
		(net "P5V_AUX")
	)
	(via
		(at 440.00674 -386.321554)
		(size 0.508)
		(drill 0.254)
		(layers "F.Cu" "B.Cu")
		(net "P5V_AUX")
	)
	(via
		(at 112.33531 -73.898506)
		(size 0.508)
		(drill 0.254)
		(layers "F.Cu" "B.Cu")
		(net "P5V_AUX")
	)
	(via
		(at 438.060846 -384.54203)
		(size 0.508)
		(drill 0.254)
		(layers "F.Cu" "B.Cu")
		(net "P5V_AUX")
	)
	(via
		(at 438.48274 -388.73303)
		(size 0.508)
		(drill 0.254)
		(layers "F.Cu" "B.Cu")
		(net "P5V_AUX")
	)
	(via
		(at 443.147958 -382.876552)
		(size 0.508)
		(drill 0.254)
		(layers "F.Cu" "B.Cu")
		(net "P5V_AUX")
	)
	(via
		(at 362.368338 -83.5787)
		(size 0.508)
		(drill 0.254)
		(layers "F.Cu" "B.Cu")
		(net "P5V_AUX")
	)
	(via
		(at 443.815216 -387.343904)
		(size 0.508)
		(drill 0.254)
		(layers "F.Cu" "B.Cu")
		(net "P5V_AUX")
	)
	(via
		(at 443.909958 -382.876552)
		(size 0.508)
		(drill 0.254)
		(layers "F.Cu" "B.Cu")
		(net "P5V_AUX")
	)
	(via
		(at 440.76874 -386.321554)
		(size 0.508)
		(drill 0.254)
		(layers "F.Cu" "B.Cu")
		(net "P5V_AUX")
	)
	(via
		(at 438.060846 -382.49733)
		(size 0.508)
		(drill 0.254)
		(layers "F.Cu" "B.Cu")
		(net "P5V_AUX")
	)
	(via
		(at 379.295406 -71.126858)
		(size 0.508)
		(drill 0.254)
		(layers "F.Cu" "B.Cu")
		(net "P5V_AUX")
	)
	(via
		(at 414.810194 -52.500022)
		(size 0.508)
		(drill 0.254)
		(layers "F.Cu" "B.Cu")
		(net "P5V_AUX")
	)
	(via
		(at 438.43448 -378.526548)
		(size 0.508)
		(drill 0.254)
		(layers "F.Cu" "B.Cu")
		(net "P5V_AUX")
	)
	(segment
		(start 400.453606 -76.435458)
		(end 401.359116 -77.340968)
		(width 0.508)
		(layer "In4.Cu")
		(net "P5V_AUX")
	)
	(segment
		(start 404.964138 -81.78292)
		(end 464.97113 -81.78292)
		(width 0.508)
		(layer "In4.Cu")
		(net "P5V_AUX")
	)
	(segment
		(start 465.508086 -82.319876)
		(end 465.508086 -84.32546)
		(width 0.508)
		(layer "In4.Cu")
		(net "P5V_AUX")
	)
	(segment
		(start 438.499758 -363.993176)
		(end 438.499758 -378.46127)
		(width 0.508)
		(layer "In4.Cu")
		(net "P5V_AUX")
	)
	(segment
		(start 463.280252 -86.553294)
		(end 463.280252 -120.61698)
		(width 0.508)
		(layer "In4.Cu")
		(net "P5V_AUX")
	)
	(segment
		(start 463.280252 -120.61698)
		(end 454.960228 -128.937004)
		(width 0.508)
		(layer "In4.Cu")
		(net "P5V_AUX")
	)
	(segment
		(start 466.774276 -174.286418)
		(end 466.774276 -333.875888)
		(width 0.508)
		(layer "In4.Cu")
		(net "P5V_AUX")
	)
	(segment
		(start 466.774276 -333.875888)
		(end 452.01205 -348.638114)
		(width 0.508)
		(layer "In4.Cu")
		(net "P5V_AUX")
	)
	(segment
		(start 454.960228 -128.937004)
		(end 454.960228 -162.47237)
		(width 0.508)
		(layer "In4.Cu")
		(net "P5V_AUX")
	)
	(segment
		(start 438.499758 -378.46127)
		(end 438.43448 -378.526548)
		(width 0.508)
		(layer "In4.Cu")
		(net "P5V_AUX")
	)
	(segment
		(start 452.01205 -348.638114)
		(end 452.01205 -350.480884)
		(width 0.508)
		(layer "In4.Cu")
		(net "P5V_AUX")
	)
	(segment
		(start 465.508086 -84.32546)
		(end 463.280252 -86.553294)
		(width 0.508)
		(layer "In4.Cu")
		(net "P5V_AUX")
	)
	(segment
		(start 454.960228 -162.47237)
		(end 466.774276 -174.286418)
		(width 0.508)
		(layer "In4.Cu")
		(net "P5V_AUX")
	)
	(segment
		(start 401.359116 -77.340968)
		(end 401.359116 -78.177898)
		(width 0.508)
		(layer "In4.Cu")
		(net "P5V_AUX")
	)
	(segment
		(start 401.359116 -78.177898)
		(end 404.964138 -81.78292)
		(width 0.508)
		(layer "In4.Cu")
		(net "P5V_AUX")
	)
	(segment
		(start 452.01205 -350.480884)
		(end 438.499758 -363.993176)
		(width 0.508)
		(layer "In4.Cu")
		(net "P5V_AUX")
	)
	(segment
		(start 464.97113 -81.78292)
		(end 465.508086 -82.319876)
		(width 0.508)
		(layer "In4.Cu")
		(net "P5V_AUX")
	)
	(segment
		(start 189.991238 -86.924134)
		(end 190.513208 -87.446104)
		(width 0.508)
		(layer "In6.Cu")
		(net "P5V_AUX")
	)
	(segment
		(start 190.513208 -87.446104)
		(end 204.08646 -87.446104)
		(width 0.508)
		(layer "In6.Cu")
		(net "P5V_AUX")
	)
	(segment
		(start 242.842796 -94.785942)
		(end 246.531892 -94.785942)
		(width 0.508)
		(layer "In6.Cu")
		(net "P5V_AUX")
	)
	(segment
		(start 415.81324 -61.441838)
		(end 415.81324 -53.503068)
		(width 0.381)
		(layer "In6.Cu")
		(net "P5V_AUX")
	)
	(segment
		(start 241.952272 -93.895418)
		(end 242.842796 -94.785942)
		(width 0.508)
		(layer "In6.Cu")
		(net "P5V_AUX")
	)
	(segment
		(start 205.67142 -90.452956)
		(end 211.085684 -95.86722)
		(width 0.508)
		(layer "In6.Cu")
		(net "P5V_AUX")
	)
	(segment
		(start 164.470334 -81.365598)
		(end 167.909748 -81.365598)
		(width 0.508)
		(layer "In6.Cu")
		(net "P5V_AUX")
	)
	(segment
		(start 263.879076 -90.855038)
		(end 265.660378 -89.073736)
		(width 0.508)
		(layer "In6.Cu")
		(net "P5V_AUX")
	)
	(segment
		(start 162.291522 -75.63612)
		(end 162.291522 -79.186786)
		(width 0.508)
		(layer "In6.Cu")
		(net "P5V_AUX")
	)
	(segment
		(start 113.615978 -72.399652)
		(end 133.175248 -72.399652)
		(width 0.508)
		(layer "In6.Cu")
		(net "P5V_AUX")
	)
	(segment
		(start 150.498556 -71.498968)
		(end 152.687528 -73.68794)
		(width 0.508)
		(layer "In6.Cu")
		(net "P5V_AUX")
	)
	(segment
		(start 162.291522 -79.186786)
		(end 164.470334 -81.365598)
		(width 0.508)
		(layer "In6.Cu")
		(net "P5V_AUX")
	)
	(segment
		(start 173.468284 -86.924134)
		(end 189.991238 -86.924134)
		(width 0.508)
		(layer "In6.Cu")
		(net "P5V_AUX")
	)
	(segment
		(start 380.534164 -69.236082)
		(end 379.295406 -70.47484)
		(width 0.508)
		(layer "In6.Cu")
		(net "P5V_AUX")
	)
	(segment
		(start 399.945606 -79.283052)
		(end 398.20469 -79.283052)
		(width 0.508)
		(layer "In6.Cu")
		(net "P5V_AUX")
	)
	(segment
		(start 160.343342 -73.68794)
		(end 162.291522 -75.63612)
		(width 0.508)
		(layer "In6.Cu")
		(net "P5V_AUX")
	)
	(segment
		(start 401.302728 -77.28458)
		(end 401.302728 -77.92593)
		(width 0.508)
		(layer "In6.Cu")
		(net "P5V_AUX")
	)
	(segment
		(start 215.8492 -95.86722)
		(end 217.821002 -93.895418)
		(width 0.508)
		(layer "In6.Cu")
		(net "P5V_AUX")
	)
	(segment
		(start 415.81324 -53.503068)
		(end 414.810194 -52.500022)
		(width 0.381)
		(layer "In6.Cu")
		(net "P5V_AUX")
	)
	(segment
		(start 400.453606 -76.435458)
		(end 401.302728 -77.28458)
		(width 0.508)
		(layer "In6.Cu")
		(net "P5V_AUX")
	)
	(segment
		(start 134.075932 -71.498968)
		(end 150.498556 -71.498968)
		(width 0.508)
		(layer "In6.Cu")
		(net "P5V_AUX")
	)
	(segment
		(start 379.295406 -70.47484)
		(end 379.295406 -71.126858)
		(width 0.508)
		(layer "In6.Cu")
		(net "P5V_AUX")
	)
	(segment
		(start 265.660378 -89.073736)
		(end 305.93665 -89.073736)
		(width 0.508)
		(layer "In6.Cu")
		(net "P5V_AUX")
	)
	(segment
		(start 401.302728 -77.92593)
		(end 399.945606 -79.283052)
		(width 0.508)
		(layer "In6.Cu")
		(net "P5V_AUX")
	)
	(segment
		(start 167.909748 -81.365598)
		(end 173.468284 -86.924134)
		(width 0.508)
		(layer "In6.Cu")
		(net "P5V_AUX")
	)
	(segment
		(start 217.821002 -93.895418)
		(end 241.952272 -93.895418)
		(width 0.508)
		(layer "In6.Cu")
		(net "P5V_AUX")
	)
	(segment
		(start 398.20469 -79.283052)
		(end 388.15772 -69.236082)
		(width 0.508)
		(layer "In6.Cu")
		(net "P5V_AUX")
	)
	(segment
		(start 247.593358 -93.724476)
		(end 249.739912 -93.724476)
		(width 0.508)
		(layer "In6.Cu")
		(net "P5V_AUX")
	)
	(segment
		(start 261.757922 -90.453718)
		(end 262.159242 -90.855038)
		(width 0.508)
		(layer "In6.Cu")
		(net "P5V_AUX")
	)
	(segment
		(start 211.085684 -95.86722)
		(end 215.8492 -95.86722)
		(width 0.508)
		(layer "In6.Cu")
		(net "P5V_AUX")
	)
	(segment
		(start 400.453606 -76.435458)
		(end 400.81962 -76.435458)
		(width 0.381)
		(layer "In6.Cu")
		(net "P5V_AUX")
	)
	(segment
		(start 262.159242 -90.855038)
		(end 263.879076 -90.855038)
		(width 0.508)
		(layer "In6.Cu")
		(net "P5V_AUX")
	)
	(segment
		(start 249.739912 -93.724476)
		(end 253.01067 -90.453718)
		(width 0.508)
		(layer "In6.Cu")
		(net "P5V_AUX")
	)
	(segment
		(start 400.81962 -76.435458)
		(end 415.81324 -61.441838)
		(width 0.381)
		(layer "In6.Cu")
		(net "P5V_AUX")
	)
	(segment
		(start 246.531892 -94.785942)
		(end 247.593358 -93.724476)
		(width 0.508)
		(layer "In6.Cu")
		(net "P5V_AUX")
	)
	(segment
		(start 388.15772 -69.236082)
		(end 380.534164 -69.236082)
		(width 0.508)
		(layer "In6.Cu")
		(net "P5V_AUX")
	)
	(segment
		(start 112.33531 -73.898506)
		(end 112.33531 -73.68032)
		(width 0.508)
		(layer "In6.Cu")
		(net "P5V_AUX")
	)
	(segment
		(start 204.08646 -87.446104)
		(end 205.67142 -89.031064)
		(width 0.508)
		(layer "In6.Cu")
		(net "P5V_AUX")
	)
	(segment
		(start 152.687528 -73.68794)
		(end 160.343342 -73.68794)
		(width 0.508)
		(layer "In6.Cu")
		(net "P5V_AUX")
	)
	(segment
		(start 112.33531 -73.68032)
		(end 113.615978 -72.399652)
		(width 0.508)
		(layer "In6.Cu")
		(net "P5V_AUX")
	)
	(segment
		(start 253.01067 -90.453718)
		(end 261.757922 -90.453718)
		(width 0.508)
		(layer "In6.Cu")
		(net "P5V_AUX")
	)
	(segment
		(start 133.175248 -72.399652)
		(end 134.075932 -71.498968)
		(width 0.508)
		(layer "In6.Cu")
		(net "P5V_AUX")
	)
	(segment
		(start 205.67142 -89.031064)
		(end 205.67142 -90.452956)
		(width 0.508)
		(layer "In6.Cu")
		(net "P5V_AUX")
	)
	(segment
		(start 379.334014 -71.165466)
		(end 379.334014 -80.10779)
		(width 0.508)
		(layer "In11.Cu")
		(net "P5V_AUX")
	)
	(segment
		(start 379.295406 -71.126858)
		(end 379.334014 -71.165466)
		(width 0.508)
		(layer "In11.Cu")
		(net "P5V_AUX")
	)
	(segment
		(start 375.863104 -83.5787)
		(end 362.368338 -83.5787)
		(width 0.508)
		(layer "In11.Cu")
		(net "P5V_AUX")
	)
	(segment
		(start 379.334014 -80.10779)
		(end 375.863104 -83.5787)
		(width 0.508)
		(layer "In11.Cu")
		(net "P5V_AUX")
	)
	(segment
		(start 421.510206 -45.83684)
		(end 417.83762 -45.83684)
		(width 0.381)
		(layer "F.Cu")
		(net "P5V")
	)
	(segment
		(start 410.801058 -363.193584)
		(end 410.191458 -363.193584)
		(width 0.381)
		(layer "F.Cu")
		(net "P5V")
	)
	(segment
		(start 417.83762 -45.83684)
		(end 417.83762 -47.231808)
		(width 0.381)
		(layer "F.Cu")
		(net "P5V")
	)
	(segment
		(start 166.664894 -354.6602)
		(end 166.055294 -354.6602)
		(width 0.381)
		(layer "F.Cu")
		(net "P5V")
	)
	(segment
		(start 46.982634 -109.444282)
		(end 47.592234 -109.444282)
		(width 0.508)
		(layer "F.Cu")
		(net "P5V")
	)
	(segment
		(start 423.6974 -45.936408)
		(end 423.306494 -45.545502)
		(width 0.3556)
		(layer "F.Cu")
		(net "P5V")
	)
	(segment
		(start 423.391076 -156.365194)
		(end 423.90568 -156.879798)
		(width 0.381)
		(layer "F.Cu")
		(net "P5V")
	)
	(segment
		(start 422.453308 -156.365194)
		(end 423.391076 -156.365194)
		(width 0.381)
		(layer "F.Cu")
		(net "P5V")
	)
	(segment
		(start 423.306494 -45.545502)
		(end 421.801544 -45.545502)
		(width 0.3556)
		(layer "F.Cu")
		(net "P5V")
	)
	(segment
		(start 89.95283 -74.419714)
		(end 89.95283 -73.810114)
		(width 0.381)
		(layer "F.Cu")
		(net "P5V")
	)
	(segment
		(start 421.801544 -45.545502)
		(end 421.510206 -45.83684)
		(width 0.381)
		(layer "F.Cu")
		(net "P5V")
	)
	(segment
		(start 36.205668 -354.65385)
		(end 35.596068 -354.65385)
		(width 0.381)
		(layer "F.Cu")
		(net "P5V")
	)
	(segment
		(start 145.17497 -343.531698)
		(end 144.94383 -343.762838)
		(width 0.381)
		(layer "F.Cu")
		(net "P5V")
	)
	(segment
		(start 422.091104 -156.727398)
		(end 422.453308 -156.365194)
		(width 0.381)
		(layer "F.Cu")
		(net "P5V")
	)
	(segment
		(start 144.94383 -343.762838)
		(end 144.94383 -344.232738)
		(width 0.381)
		(layer "F.Cu")
		(net "P5V")
	)
	(segment
		(start 283.426662 -363.881416)
		(end 283.426662 -364.625128)
		(width 0.381)
		(layer "F.Cu")
		(net "P5V")
	)
	(segment
		(start 421.92448 -156.727398)
		(end 422.091104 -156.727398)
		(width 0.381)
		(layer "F.Cu")
		(net "P5V")
	)
	(via
		(at 43.32478 -383.3495)
		(size 0.508)
		(drill 0.254)
		(layers "F.Cu" "B.Cu")
		(net "P5V")
	)
	(via
		(at 167.9194 -368.557048)
		(size 0.508)
		(drill 0.254)
		(layers "F.Cu" "B.Cu")
		(net "P5V")
	)
	(via
		(at 204.2414 -364.49254)
		(size 0.508)
		(drill 0.254)
		(layers "F.Cu" "B.Cu")
		(net "P5V")
	)
	(via
		(at 145.17497 -343.531698)
		(size 0.508)
		(drill 0.254)
		(layers "F.Cu" "B.Cu")
		(net "P5V")
	)
	(via
		(at 145.19148 -361.820968)
		(size 0.508)
		(drill 0.254)
		(layers "F.Cu" "B.Cu")
		(net "P5V")
	)
	(via
		(at 168.50614 -394.711428)
		(size 0.508)
		(drill 0.254)
		(layers "F.Cu" "B.Cu")
		(net "P5V")
	)
	(via
		(at 441.0456 -370.571268)
		(size 0.508)
		(drill 0.254)
		(layers "F.Cu" "B.Cu")
		(net "P5V")
	)
	(via
		(at 119.408194 -393.260326)
		(size 0.508)
		(drill 0.254)
		(layers "F.Cu" "B.Cu")
		(net "P5V")
	)
	(via
		(at 57.6072 -91.303856)
		(size 0.508)
		(drill 0.254)
		(layers "F.Cu" "B.Cu")
		(net "P5V")
	)
	(via
		(at 58.511186 -117.267482)
		(size 0.508)
		(drill 0.254)
		(layers "F.Cu" "B.Cu")
		(net "P5V")
	)
	(via
		(at 423.6974 -45.936408)
		(size 0.508)
		(drill 0.254)
		(layers "F.Cu" "B.Cu")
		(net "P5V")
	)
	(via
		(at 422.261538 -122.077226)
		(size 0.508)
		(drill 0.254)
		(layers "F.Cu" "B.Cu")
		(net "P5V")
	)
	(via
		(at 35.596068 -354.65385)
		(size 0.508)
		(drill 0.254)
		(layers "F.Cu" "B.Cu")
		(net "P5V")
	)
	(via
		(at 418.327332 -381.394462)
		(size 0.508)
		(drill 0.254)
		(layers "F.Cu" "B.Cu")
		(net "P5V")
	)
	(via
		(at 439.3438 -371.584728)
		(size 0.508)
		(drill 0.254)
		(layers "F.Cu" "B.Cu")
		(net "P5V")
	)
	(via
		(at 455.139552 -173.68647)
		(size 0.508)
		(drill 0.254)
		(layers "F.Cu" "B.Cu")
		(net "P5V")
	)
	(via
		(at 423.90568 -156.879798)
		(size 0.508)
		(drill 0.254)
		(layers "F.Cu" "B.Cu")
		(net "P5V")
	)
	(via
		(at 89.95283 -73.810114)
		(size 0.508)
		(drill 0.254)
		(layers "F.Cu" "B.Cu")
		(net "P5V")
	)
	(via
		(at 436.76062 -41.3893)
		(size 0.508)
		(drill 0.254)
		(layers "F.Cu" "B.Cu")
		(net "P5V")
	)
	(via
		(at 248.760742 -341.051896)
		(size 0.508)
		(drill 0.254)
		(layers "F.Cu" "B.Cu")
		(net "P5V")
	)
	(via
		(at 440.2328 -371.584728)
		(size 0.508)
		(drill 0.254)
		(layers "F.Cu" "B.Cu")
		(net "P5V")
	)
	(via
		(at 47.592234 -109.444282)
		(size 0.508)
		(drill 0.254)
		(layers "F.Cu" "B.Cu")
		(net "P5V")
	)
	(via
		(at 52.73548 -170.500548)
		(size 0.508)
		(drill 0.254)
		(layers "F.Cu" "B.Cu")
		(net "P5V")
	)
	(via
		(at 410.191458 -363.193584)
		(size 0.508)
		(drill 0.254)
		(layers "F.Cu" "B.Cu")
		(net "P5V")
	)
	(via
		(at 441.0456 -369.682268)
		(size 0.508)
		(drill 0.254)
		(layers "F.Cu" "B.Cu")
		(net "P5V")
	)
	(via
		(at 93.458792 -389.008366)
		(size 0.508)
		(drill 0.254)
		(layers "F.Cu" "B.Cu")
		(net "P5V")
	)
	(via
		(at 136.144 -132.171948)
		(size 0.508)
		(drill 0.254)
		(layers "F.Cu" "B.Cu")
		(net "P5V")
	)
	(via
		(at 442.0108 -371.584728)
		(size 0.508)
		(drill 0.254)
		(layers "F.Cu" "B.Cu")
		(net "P5V")
	)
	(via
		(at 440.618118 -356.70236)
		(size 0.508)
		(drill 0.254)
		(layers "F.Cu" "B.Cu")
		(net "P5V")
	)
	(via
		(at 196.94525 -356.504494)
		(size 0.508)
		(drill 0.254)
		(layers "F.Cu" "B.Cu")
		(net "P5V")
	)
	(via
		(at 158.41218 -128.996948)
		(size 0.508)
		(drill 0.254)
		(layers "F.Cu" "B.Cu")
		(net "P5V")
	)
	(via
		(at 441.1218 -371.584728)
		(size 0.508)
		(drill 0.254)
		(layers "F.Cu" "B.Cu")
		(net "P5V")
	)
	(via
		(at 439.8264 -370.13642)
		(size 0.508)
		(drill 0.254)
		(layers "F.Cu" "B.Cu")
		(net "P5V")
	)
	(via
		(at 441.63996 -368.742468)
		(size 0.508)
		(drill 0.254)
		(layers "F.Cu" "B.Cu")
		(net "P5V")
	)
	(via
		(at 166.055294 -354.6602)
		(size 0.508)
		(drill 0.254)
		(layers "F.Cu" "B.Cu")
		(net "P5V")
	)
	(via
		(at 283.0576 -385.632198)
		(size 0.508)
		(drill 0.254)
		(layers "F.Cu" "B.Cu")
		(net "P5V")
	)
	(via
		(at 283.426662 -364.625128)
		(size 0.508)
		(drill 0.254)
		(layers "F.Cu" "B.Cu")
		(net "P5V")
	)
	(via
		(at 323.08546 -344.952066)
		(size 0.508)
		(drill 0.254)
		(layers "F.Cu" "B.Cu")
		(net "P5V")
	)
	(segment
		(start 416.3568 -140.299694)
		(end 419.305486 -143.24838)
		(width 0.508)
		(layer "B.Cu")
		(net "P5V")
	)
	(segment
		(start 434.00472 -43.19016)
		(end 434.00472 -43.73245)
		(width 0.381)
		(layer "B.Cu")
		(net "P5V")
	)
	(segment
		(start 89.95283 -73.810114)
		(end 89.95283 -72.59828)
		(width 0.508)
		(layer "B.Cu")
		(net "P5V")
	)
	(segment
		(start 167.73652 -389.446008)
		(end 175.025304 -389.446008)
		(width 1.016)
		(layer "B.Cu")
		(net "P5V")
	)
	(segment
		(start 427.411896 -142.204948)
		(end 440.750706 -142.204948)
		(width 0.508)
		(layer "B.Cu")
		(net "P5V")
	)
	(segment
		(start 48.665384 -110.517432)
		(end 47.592234 -109.444282)
		(width 0.508)
		(layer "B.Cu")
		(net "P5V")
	)
	(segment
		(start 93.05671 -389.410448)
		(end 93.458792 -389.008366)
		(width 1.016)
		(layer "B.Cu")
		(net "P5V")
	)
	(segment
		(start 58.511186 -117.267482)
		(end 55.078122 -117.267482)
		(width 0.508)
		(layer "B.Cu")
		(net "P5V")
	)
	(segment
		(start 52.73548 -170.500548)
		(end 52.73548 -170.608498)
		(width 0.381)
		(layer "B.Cu")
		(net "P5V")
	)
	(segment
		(start 166.398194 -390.784334)
		(end 167.73652 -389.446008)
		(width 1.016)
		(layer "B.Cu")
		(net "P5V")
	)
	(segment
		(start 168.435782 -369.07343)
		(end 167.9194 -368.557048)
		(width 1.016)
		(layer "B.Cu")
		(net "P5V")
	)
	(segment
		(start 89.95283 -72.59828)
		(end 89.16162 -71.80707)
		(width 0.508)
		(layer "B.Cu")
		(net "P5V")
	)
	(segment
		(start 170.332146 -370.347748)
		(end 169.057828 -369.07343)
		(width 1.016)
		(layer "B.Cu")
		(net "P5V")
	)
	(segment
		(start 47.383192 -383.96164)
		(end 52.832 -389.410448)
		(width 1.016)
		(layer "B.Cu")
		(net "P5V")
	)
	(segment
		(start 436.89524 -42.418)
		(end 436.37962 -42.93362)
		(width 0.381)
		(layer "B.Cu")
		(net "P5V")
	)
	(segment
		(start 436.76062 -41.3893)
		(end 436.89524 -41.52392)
		(width 0.381)
		(layer "B.Cu")
		(net "P5V")
	)
	(segment
		(start 419.305486 -143.24838)
		(end 424.893232 -143.24838)
		(width 0.508)
		(layer "B.Cu")
		(net "P5V")
	)
	(segment
		(start 43.32478 -383.3495)
		(end 43.93692 -383.96164)
		(width 1.016)
		(layer "B.Cu")
		(net "P5V")
	)
	(segment
		(start 66.481452 -71.80707)
		(end 58.793888 -79.494634)
		(width 0.508)
		(layer "B.Cu")
		(net "P5V")
	)
	(segment
		(start 196.94525 -356.504494)
		(end 196.94525 -359.07599)
		(width 1.016)
		(layer "B.Cu")
		(net "P5V")
	)
	(segment
		(start 52.73548 -170.608498)
		(end 52.20208 -171.141898)
		(width 0.381)
		(layer "B.Cu")
		(net "P5V")
	)
	(segment
		(start 43.93692 -383.96164)
		(end 47.383192 -383.96164)
		(width 1.016)
		(layer "B.Cu")
		(net "P5V")
	)
	(segment
		(start 54.089554 -118.25605)
		(end 51.278536 -118.25605)
		(width 0.508)
		(layer "B.Cu")
		(net "P5V")
	)
	(segment
		(start 436.37962 -42.93362)
		(end 434.26126 -42.93362)
		(width 0.381)
		(layer "B.Cu")
		(net "P5V")
	)
	(segment
		(start 185.673492 -370.347748)
		(end 170.332146 -370.347748)
		(width 1.016)
		(layer "B.Cu")
		(net "P5V")
	)
	(segment
		(start 436.89524 -41.52392)
		(end 436.89524 -42.418)
		(width 0.381)
		(layer "B.Cu")
		(net "P5V")
	)
	(segment
		(start 48.665384 -115.642898)
		(end 48.665384 -110.517432)
		(width 0.508)
		(layer "B.Cu")
		(net "P5V")
	)
	(segment
		(start 416.3568 -127.981964)
		(end 416.3568 -140.299694)
		(width 0.508)
		(layer "B.Cu")
		(net "P5V")
	)
	(segment
		(start 323.08546 -344.952066)
		(end 323.175884 -344.861642)
		(width 0.381)
		(layer "B.Cu")
		(net "P5V")
	)
	(segment
		(start 451.890638 -153.34488)
		(end 451.890638 -170.437556)
		(width 0.508)
		(layer "B.Cu")
		(net "P5V")
	)
	(segment
		(start 175.025304 -389.446008)
		(end 198.320152 -366.15116)
		(width 1.016)
		(layer "B.Cu")
		(net "P5V")
	)
	(segment
		(start 58.793888 -90.117168)
		(end 57.6072 -91.303856)
		(width 0.508)
		(layer "B.Cu")
		(net "P5V")
	)
	(segment
		(start 323.175884 -344.861642)
		(end 323.175884 -344.327988)
		(width 0.381)
		(layer "B.Cu")
		(net "P5V")
	)
	(segment
		(start 196.94525 -359.07599)
		(end 185.673492 -370.347748)
		(width 1.016)
		(layer "B.Cu")
		(net "P5V")
	)
	(segment
		(start 451.890638 -170.437556)
		(end 455.139552 -173.68647)
		(width 0.508)
		(layer "B.Cu")
		(net "P5V")
	)
	(segment
		(start 203.8477 -364.49254)
		(end 204.2414 -364.49254)
		(width 1.016)
		(layer "B.Cu")
		(net "P5V")
	)
	(segment
		(start 55.078122 -117.267482)
		(end 54.089554 -118.25605)
		(width 0.508)
		(layer "B.Cu")
		(net "P5V")
	)
	(segment
		(start 422.261538 -122.077226)
		(end 416.3568 -127.981964)
		(width 0.508)
		(layer "B.Cu")
		(net "P5V")
	)
	(segment
		(start 167.2844 -394.711428)
		(end 166.398194 -393.825222)
		(width 1.016)
		(layer "B.Cu")
		(net "P5V")
	)
	(segment
		(start 440.750706 -142.204948)
		(end 451.890638 -153.34488)
		(width 0.508)
		(layer "B.Cu")
		(net "P5V")
	)
	(segment
		(start 52.20208 -171.141898)
		(end 52.15128 -171.141898)
		(width 0.381)
		(layer "B.Cu")
		(net "P5V")
	)
	(segment
		(start 424.893232 -143.24838)
		(end 427.411896 -142.204948)
		(width 0.508)
		(layer "B.Cu")
		(net "P5V")
	)
	(segment
		(start 434.26126 -42.93362)
		(end 434.00472 -43.19016)
		(width 0.381)
		(layer "B.Cu")
		(net "P5V")
	)
	(segment
		(start 58.793888 -79.494634)
		(end 58.793888 -90.117168)
		(width 0.508)
		(layer "B.Cu")
		(net "P5V")
	)
	(segment
		(start 202.18908 -366.15116)
		(end 203.8477 -364.49254)
		(width 1.016)
		(layer "B.Cu")
		(net "P5V")
	)
	(segment
		(start 166.398194 -393.825222)
		(end 166.398194 -390.784334)
		(width 1.016)
		(layer "B.Cu")
		(net "P5V")
	)
	(segment
		(start 198.320152 -366.15116)
		(end 202.18908 -366.15116)
		(width 1.016)
		(layer "B.Cu")
		(net "P5V")
	)
	(segment
		(start 168.50614 -394.711428)
		(end 167.2844 -394.711428)
		(width 1.016)
		(layer "B.Cu")
		(net "P5V")
	)
	(segment
		(start 51.278536 -118.25605)
		(end 48.665384 -115.642898)
		(width 0.508)
		(layer "B.Cu")
		(net "P5V")
	)
	(segment
		(start 89.16162 -71.80707)
		(end 66.481452 -71.80707)
		(width 0.508)
		(layer "B.Cu")
		(net "P5V")
	)
	(segment
		(start 169.057828 -369.07343)
		(end 168.435782 -369.07343)
		(width 1.016)
		(layer "B.Cu")
		(net "P5V")
	)
	(segment
		(start 52.832 -389.410448)
		(end 93.05671 -389.410448)
		(width 1.016)
		(layer "B.Cu")
		(net "P5V")
	)
	(segment
		(start 104.99725 -390.41832)
		(end 102.612444 -388.033514)
		(width 1.016)
		(layer "In2.Cu")
		(net "P5V")
	)
	(segment
		(start 119.408194 -393.260326)
		(end 119.408194 -391.60704)
		(width 1.016)
		(layer "In2.Cu")
		(net "P5V")
	)
	(segment
		(start 429.819054 -378.948188)
		(end 426.390816 -378.948188)
		(width 1.016)
		(layer "In2.Cu")
		(net "P5V")
	)
	(segment
		(start 411.7467 -365.046514)
		(end 410.979366 -363.193584)
		(width 1.016)
		(layer "In2.Cu")
		(net "P5V")
	)
	(segment
		(start 143.83258 -345.343734)
		(end 145.17497 -344.001344)
		(width 1.016)
		(layer "In2.Cu")
		(net "P5V")
	)
	(segment
		(start 437.182514 -371.584728)
		(end 429.819054 -378.948188)
		(width 1.016)
		(layer "In2.Cu")
		(net "P5V")
	)
	(segment
		(start 143.83258 -361.249468)
		(end 143.83258 -345.343734)
		(width 1.016)
		(layer "In2.Cu")
		(net "P5V")
	)
	(segment
		(start 435.1655 -378.285502)
		(end 439.3438 -374.107202)
		(width 1.016)
		(layer "In2.Cu")
		(net "P5V")
	)
	(segment
		(start 168.01338 -368.463068)
		(end 168.01338 -361.043474)
		(width 1.016)
		(layer "In2.Cu")
		(net "P5V")
	)
	(segment
		(start 145.17497 -344.001344)
		(end 145.17497 -343.531698)
		(width 1.016)
		(layer "In2.Cu")
		(net "P5V")
	)
	(segment
		(start 94.433644 -388.033514)
		(end 93.458792 -389.008366)
		(width 1.016)
		(layer "In2.Cu")
		(net "P5V")
	)
	(segment
		(start 102.612444 -388.033514)
		(end 94.433644 -388.033514)
		(width 1.016)
		(layer "In2.Cu")
		(net "P5V")
	)
	(segment
		(start 35.090354 -365.855758)
		(end 35.090354 -355.159564)
		(width 1.016)
		(layer "In2.Cu")
		(net "P5V")
	)
	(segment
		(start 411.7467 -374.093232)
		(end 411.7467 -365.046514)
		(width 1.016)
		(layer "In2.Cu")
		(net "P5V")
	)
	(segment
		(start 429.008286 -383.141728)
		(end 433.864512 -378.285502)
		(width 1.016)
		(layer "In2.Cu")
		(net "P5V")
	)
	(segment
		(start 166.40556 -359.435654)
		(end 166.40556 -355.010466)
		(width 1.016)
		(layer "In2.Cu")
		(net "P5V")
	)
	(segment
		(start 414.902396 -377.248928)
		(end 411.7467 -374.093232)
		(width 1.016)
		(layer "In2.Cu")
		(net "P5V")
	)
	(segment
		(start 42.252392 -382.277112)
		(end 42.252392 -373.017796)
		(width 1.016)
		(layer "In2.Cu")
		(net "P5V")
	)
	(segment
		(start 43.32478 -383.3495)
		(end 42.252392 -382.277112)
		(width 1.016)
		(layer "In2.Cu")
		(net "P5V")
	)
	(segment
		(start 439.3438 -374.107202)
		(end 439.3438 -371.584728)
		(width 1.016)
		(layer "In2.Cu")
		(net "P5V")
	)
	(segment
		(start 426.390816 -378.948188)
		(end 424.691556 -377.248928)
		(width 1.016)
		(layer "In2.Cu")
		(net "P5V")
	)
	(segment
		(start 418.327332 -381.394462)
		(end 420.074598 -383.141728)
		(width 1.016)
		(layer "In2.Cu")
		(net "P5V")
	)
	(segment
		(start 144.40408 -361.820968)
		(end 143.83258 -361.249468)
		(width 1.016)
		(layer "In2.Cu")
		(net "P5V")
	)
	(segment
		(start 167.9194 -368.557048)
		(end 168.01338 -368.463068)
		(width 1.016)
		(layer "In2.Cu")
		(net "P5V")
	)
	(segment
		(start 42.252392 -373.017796)
		(end 35.090354 -365.855758)
		(width 1.016)
		(layer "In2.Cu")
		(net "P5V")
	)
	(segment
		(start 166.40556 -355.010466)
		(end 166.055294 -354.6602)
		(width 1.016)
		(layer "In2.Cu")
		(net "P5V")
	)
	(segment
		(start 119.408194 -391.60704)
		(end 118.219474 -390.41832)
		(width 1.016)
		(layer "In2.Cu")
		(net "P5V")
	)
	(segment
		(start 410.979366 -363.193584)
		(end 410.191458 -363.193584)
		(width 1.016)
		(layer "In2.Cu")
		(net "P5V")
	)
	(segment
		(start 145.19148 -361.820968)
		(end 144.40408 -361.820968)
		(width 1.016)
		(layer "In2.Cu")
		(net "P5V")
	)
	(segment
		(start 35.090354 -355.159564)
		(end 35.596068 -354.65385)
		(width 1.016)
		(layer "In2.Cu")
		(net "P5V")
	)
	(segment
		(start 433.864512 -378.285502)
		(end 435.1655 -378.285502)
		(width 1.016)
		(layer "In2.Cu")
		(net "P5V")
	)
	(segment
		(start 424.691556 -377.248928)
		(end 414.902396 -377.248928)
		(width 1.016)
		(layer "In2.Cu")
		(net "P5V")
	)
	(segment
		(start 168.01338 -361.043474)
		(end 166.40556 -359.435654)
		(width 1.016)
		(layer "In2.Cu")
		(net "P5V")
	)
	(segment
		(start 420.074598 -383.141728)
		(end 429.008286 -383.141728)
		(width 1.016)
		(layer "In2.Cu")
		(net "P5V")
	)
	(segment
		(start 439.3438 -371.584728)
		(end 437.182514 -371.584728)
		(width 1.016)
		(layer "In2.Cu")
		(net "P5V")
	)
	(segment
		(start 118.219474 -390.41832)
		(end 104.99725 -390.41832)
		(width 1.016)
		(layer "In2.Cu")
		(net "P5V")
	)
	(segment
		(start 55.149242 -91.303856)
		(end 57.6072 -91.303856)
		(width 0.508)
		(layer "In4.Cu")
		(net "P5V")
	)
	(segment
		(start 50.459386 -102.237032)
		(end 50.459386 -95.993712)
		(width 0.508)
		(layer "In4.Cu")
		(net "P5V")
	)
	(segment
		(start 50.459386 -95.993712)
		(end 55.149242 -91.303856)
		(width 0.508)
		(layer "In4.Cu")
		(net "P5V")
	)
	(segment
		(start 46.504098 -108.356146)
		(end 46.504098 -104.949498)
		(width 0.508)
		(layer "In4.Cu")
		(net "P5V")
	)
	(segment
		(start 47.592234 -109.444282)
		(end 46.504098 -108.356146)
		(width 0.508)
		(layer "In4.Cu")
		(net "P5V")
	)
	(segment
		(start 46.504098 -104.949498)
		(end 48.651414 -102.802182)
		(width 0.508)
		(layer "In4.Cu")
		(net "P5V")
	)
	(segment
		(start 49.894236 -102.802182)
		(end 50.459386 -102.237032)
		(width 0.508)
		(layer "In4.Cu")
		(net "P5V")
	)
	(segment
		(start 48.651414 -102.802182)
		(end 49.894236 -102.802182)
		(width 0.508)
		(layer "In4.Cu")
		(net "P5V")
	)
	(segment
		(start 124.1298 -394.1826)
		(end 125.323854 -395.376654)
		(width 1.016)
		(layer "In6.Cu")
		(net "P5V")
	)
	(segment
		(start 436.76062 -41.3893)
		(end 436.71236 -41.34104)
		(width 0.381)
		(layer "In6.Cu")
		(net "P5V")
	)
	(segment
		(start 232.176828 -342.35136)
		(end 223.701102 -350.827086)
		(width 1.016)
		(layer "In6.Cu")
		(net "P5V")
	)
	(segment
		(start 304.0126 -356.502208)
		(end 284.432248 -356.502208)
		(width 1.016)
		(layer "In6.Cu")
		(net "P5V")
	)
	(segment
		(start 430.87036 -45.06214)
		(end 429.996092 -45.936408)
		(width 0.381)
		(layer "In6.Cu")
		(net "P5V")
	)
	(segment
		(start 125.323854 -395.376654)
		(end 166.890954 -395.376654)
		(width 1.016)
		(layer "In6.Cu")
		(net "P5V")
	)
	(segment
		(start 322.563998 -345.473528)
		(end 315.04128 -345.473528)
		(width 1.016)
		(layer "In6.Cu")
		(net "P5V")
	)
	(segment
		(start 282.45054 -363.649006)
		(end 283.426662 -364.625128)
		(width 1.016)
		(layer "In6.Cu")
		(net "P5V")
	)
	(segment
		(start 247.461278 -342.35136)
		(end 232.176828 -342.35136)
		(width 1.016)
		(layer "In6.Cu")
		(net "P5V")
	)
	(segment
		(start 432.7398 -41.34104)
		(end 430.87036 -43.21048)
		(width 0.381)
		(layer "In6.Cu")
		(net "P5V")
	)
	(segment
		(start 413.20212 -131.136644)
		(end 422.261538 -122.077226)
		(width 0.508)
		(layer "In6.Cu")
		(net "P5V")
	)
	(segment
		(start 166.890954 -395.376654)
		(end 167.55618 -394.711428)
		(width 1.016)
		(layer "In6.Cu")
		(net "P5V")
	)
	(segment
		(start 223.701102 -350.827086)
		(end 211.383372 -350.827086)
		(width 1.016)
		(layer "In6.Cu")
		(net "P5V")
	)
	(segment
		(start 284.432248 -356.502208)
		(end 282.45054 -358.483916)
		(width 1.016)
		(layer "In6.Cu")
		(net "P5V")
	)
	(segment
		(start 211.383372 -350.827086)
		(end 205.705964 -356.504494)
		(width 1.016)
		(layer "In6.Cu")
		(net "P5V")
	)
	(segment
		(start 416.66668 -145.633948)
		(end 413.20212 -142.169388)
		(width 0.508)
		(layer "In6.Cu")
		(net "P5V")
	)
	(segment
		(start 120.330468 -394.1826)
		(end 124.1298 -394.1826)
		(width 1.016)
		(layer "In6.Cu")
		(net "P5V")
	)
	(segment
		(start 323.08546 -344.952066)
		(end 322.563998 -345.473528)
		(width 1.016)
		(layer "In6.Cu")
		(net "P5V")
	)
	(segment
		(start 430.87036 -43.21048)
		(end 430.87036 -45.06214)
		(width 0.381)
		(layer "In6.Cu")
		(net "P5V")
	)
	(segment
		(start 205.705964 -356.504494)
		(end 196.94525 -356.504494)
		(width 1.016)
		(layer "In6.Cu")
		(net "P5V")
	)
	(segment
		(start 119.408194 -393.260326)
		(end 120.330468 -394.1826)
		(width 1.016)
		(layer "In6.Cu")
		(net "P5V")
	)
	(segment
		(start 167.55618 -394.711428)
		(end 168.50614 -394.711428)
		(width 1.016)
		(layer "In6.Cu")
		(net "P5V")
	)
	(segment
		(start 436.71236 -41.34104)
		(end 432.7398 -41.34104)
		(width 0.381)
		(layer "In6.Cu")
		(net "P5V")
	)
	(segment
		(start 424.24477 -156.879798)
		(end 427.7614 -153.363168)
		(width 0.508)
		(layer "In6.Cu")
		(net "P5V")
	)
	(segment
		(start 427.7614 -146.776948)
		(end 426.6184 -145.633948)
		(width 0.508)
		(layer "In6.Cu")
		(net "P5V")
	)
	(segment
		(start 427.7614 -153.363168)
		(end 427.7614 -146.776948)
		(width 0.508)
		(layer "In6.Cu")
		(net "P5V")
	)
	(segment
		(start 426.6184 -145.633948)
		(end 416.66668 -145.633948)
		(width 0.508)
		(layer "In6.Cu")
		(net "P5V")
	)
	(segment
		(start 423.90568 -156.879798)
		(end 424.24477 -156.879798)
		(width 0.508)
		(layer "In6.Cu")
		(net "P5V")
	)
	(segment
		(start 248.760742 -341.051896)
		(end 247.461278 -342.35136)
		(width 1.016)
		(layer "In6.Cu")
		(net "P5V")
	)
	(segment
		(start 413.20212 -142.169388)
		(end 413.20212 -131.136644)
		(width 0.508)
		(layer "In6.Cu")
		(net "P5V")
	)
	(segment
		(start 429.996092 -45.936408)
		(end 423.6974 -45.936408)
		(width 0.381)
		(layer "In6.Cu")
		(net "P5V")
	)
	(segment
		(start 315.04128 -345.473528)
		(end 304.0126 -356.502208)
		(width 1.016)
		(layer "In6.Cu")
		(net "P5V")
	)
	(segment
		(start 282.45054 -358.483916)
		(end 282.45054 -363.649006)
		(width 1.016)
		(layer "In6.Cu")
		(net "P5V")
	)
	(segment
		(start 417.282122 -93.05544)
		(end 432.963574 -77.373988)
		(width 0.508)
		(layer "In11.Cu")
		(net "P5V")
	)
	(segment
		(start 283.0576 -385.632198)
		(end 283.0576 -384.79857)
		(width 1.016)
		(layer "In11.Cu")
		(net "P5V")
	)
	(segment
		(start 284.251146 -383.605024)
		(end 288.503106 -383.605024)
		(width 1.016)
		(layer "In11.Cu")
		(net "P5V")
	)
	(segment
		(start 440.618118 -367.720626)
		(end 440.618118 -356.70236)
		(width 1.016)
		(layer "In11.Cu")
		(net "P5V")
	)
	(segment
		(start 165.273482 -364.584488)
		(end 163.636452 -362.947458)
		(width 1.016)
		(layer "In11.Cu")
		(net "P5V")
	)
	(segment
		(start 289.069526 -383.038604)
		(end 289.069526 -381.754126)
		(width 1.016)
		(layer "In11.Cu")
		(net "P5V")
	)
	(segment
		(start 163.636452 -362.947458)
		(end 145.836132 -362.947458)
		(width 1.016)
		(layer "In11.Cu")
		(net "P5V")
	)
	(segment
		(start 424.288712 -46.52772)
		(end 423.6974 -45.936408)
		(width 0.508)
		(layer "In11.Cu")
		(net "P5V")
	)
	(segment
		(start 282.32608 -365.214916)
		(end 282.32608 -375.01068)
		(width 1.016)
		(layer "In11.Cu")
		(net "P5V")
	)
	(segment
		(start 441.63996 -368.742468)
		(end 440.618118 -367.720626)
		(width 1.016)
		(layer "In11.Cu")
		(net "P5V")
	)
	(segment
		(start 422.261538 -122.077226)
		(end 414.174432 -113.99012)
		(width 0.508)
		(layer "In11.Cu")
		(net "P5V")
	)
	(segment
		(start 414.174432 -113.99012)
		(end 414.174432 -101.255576)
		(width 0.508)
		(layer "In11.Cu")
		(net "P5V")
	)
	(segment
		(start 283.426662 -364.625128)
		(end 282.915868 -364.625128)
		(width 1.016)
		(layer "In11.Cu")
		(net "P5V")
	)
	(segment
		(start 424.288712 -49.787302)
		(end 424.288712 -46.52772)
		(width 0.508)
		(layer "In11.Cu")
		(net "P5V")
	)
	(segment
		(start 282.915868 -364.625128)
		(end 282.32608 -365.214916)
		(width 1.016)
		(layer "In11.Cu")
		(net "P5V")
	)
	(segment
		(start 428.330106 -58.631328)
		(end 428.330106 -53.828696)
		(width 0.508)
		(layer "In11.Cu")
		(net "P5V")
	)
	(segment
		(start 432.963574 -63.264796)
		(end 428.330106 -58.631328)
		(width 0.508)
		(layer "In11.Cu")
		(net "P5V")
	)
	(segment
		(start 165.273482 -365.91113)
		(end 165.273482 -364.584488)
		(width 1.016)
		(layer "In11.Cu")
		(net "P5V")
	)
	(segment
		(start 428.330106 -53.828696)
		(end 424.288712 -49.787302)
		(width 0.508)
		(layer "In11.Cu")
		(net "P5V")
	)
	(segment
		(start 167.9194 -368.557048)
		(end 165.273482 -365.91113)
		(width 1.016)
		(layer "In11.Cu")
		(net "P5V")
	)
	(segment
		(start 418.327332 -381.394462)
		(end 417.967668 -381.754126)
		(width 1.016)
		(layer "In11.Cu")
		(net "P5V")
	)
	(segment
		(start 414.174432 -101.255576)
		(end 417.282122 -98.147886)
		(width 0.508)
		(layer "In11.Cu")
		(net "P5V")
	)
	(segment
		(start 145.836132 -362.947458)
		(end 145.19148 -362.302806)
		(width 1.016)
		(layer "In11.Cu")
		(net "P5V")
	)
	(segment
		(start 417.282122 -98.147886)
		(end 417.282122 -93.05544)
		(width 0.508)
		(layer "In11.Cu")
		(net "P5V")
	)
	(segment
		(start 432.963574 -77.373988)
		(end 432.963574 -63.264796)
		(width 0.508)
		(layer "In11.Cu")
		(net "P5V")
	)
	(segment
		(start 417.967668 -381.754126)
		(end 289.069526 -381.754126)
		(width 1.016)
		(layer "In11.Cu")
		(net "P5V")
	)
	(segment
		(start 282.32608 -375.01068)
		(end 289.069526 -381.754126)
		(width 1.016)
		(layer "In11.Cu")
		(net "P5V")
	)
	(segment
		(start 145.19148 -362.302806)
		(end 145.19148 -361.820968)
		(width 1.016)
		(layer "In11.Cu")
		(net "P5V")
	)
	(segment
		(start 283.0576 -384.79857)
		(end 284.251146 -383.605024)
		(width 1.016)
		(layer "In11.Cu")
		(net "P5V")
	)
	(segment
		(start 288.503106 -383.605024)
		(end 289.069526 -383.038604)
		(width 1.016)
		(layer "In11.Cu")
		(net "P5V")
	)
	(segment
		(start 443.210442 -356.70236)
		(end 440.618118 -356.70236)
		(width 1.016)
		(layer "In13.Cu")
		(net "P5V")
	)
	(segment
		(start 455.139552 -173.68647)
		(end 460.157322 -173.68647)
		(width 1.016)
		(layer "In13.Cu")
		(net "P5V")
	)
	(segment
		(start 466.2297 -179.758848)
		(end 466.2297 -327.02246)
		(width 1.016)
		(layer "In13.Cu")
		(net "P5V")
	)
	(segment
		(start 466.2297 -327.02246)
		(end 458.66304 -334.58912)
		(width 1.016)
		(layer "In13.Cu")
		(net "P5V")
	)
	(segment
		(start 458.66304 -341.249762)
		(end 443.210442 -356.70236)
		(width 1.016)
		(layer "In13.Cu")
		(net "P5V")
	)
	(segment
		(start 460.157322 -173.68647)
		(end 466.2297 -179.758848)
		(width 1.016)
		(layer "In13.Cu")
		(net "P5V")
	)
	(segment
		(start 136.144 -132.171948)
		(end 137.7696 -130.546348)
		(width 0.508)
		(layer "In13.Cu")
		(net "P5V")
	)
	(segment
		(start 458.66304 -334.58912)
		(end 458.66304 -341.249762)
		(width 1.016)
		(layer "In13.Cu")
		(net "P5V")
	)
	(segment
		(start 150.8252 -128.996948)
		(end 158.41218 -128.996948)
		(width 0.508)
		(layer "In13.Cu")
		(net "P5V")
	)
	(segment
		(start 149.2758 -130.546348)
		(end 150.8252 -128.996948)
		(width 0.508)
		(layer "In13.Cu")
		(net "P5V")
	)
	(segment
		(start 137.7696 -130.546348)
		(end 149.2758 -130.546348)
		(width 0.508)
		(layer "In13.Cu")
		(net "P5V")
	)
	(segment
		(start 52.73548 -170.500548)
		(end 52.73548 -171.01058)
		(width 0.508)
		(layer "In15.Cu")
		(net "P5V")
	)
	(segment
		(start 45.49902 -175.2092)
		(end 40.907208 -175.2092)
		(width 1.016)
		(layer "In15.Cu")
		(net "P5V")
	)
	(segment
		(start 283.0576 -385.170934)
		(end 282.438094 -384.551428)
		(width 1.016)
		(layer "In15.Cu")
		(net "P5V")
	)
	(segment
		(start 282.438094 -384.551428)
		(end 277.53056 -384.551428)
		(width 1.016)
		(layer "In15.Cu")
		(net "P5V")
	)
	(segment
		(start 38.001194 -381.0762)
		(end 41.05148 -381.0762)
		(width 1.016)
		(layer "In15.Cu")
		(net "P5V")
	)
	(segment
		(start 43.820334 -129.257806)
		(end 55.330598 -117.747542)
		(width 1.016)
		(layer "In15.Cu")
		(net "P5V")
	)
	(segment
		(start 5.99186 -326.921368)
		(end 9.76884 -330.698348)
		(width 1.016)
		(layer "In15.Cu")
		(net "P5V")
	)
	(segment
		(start 52.73548 -171.01058)
		(end 53.269388 -171.544488)
		(width 0.762)
		(layer "In15.Cu")
		(net "P5V")
	)
	(segment
		(start 111.1504 -134.991348)
		(end 112.0902 -134.051548)
		(width 1.016)
		(layer "In15.Cu")
		(net "P5V")
	)
	(segment
		(start 7.24154 -191.34074)
		(end 8.23722 -192.33642)
		(width 1.016)
		(layer "In15.Cu")
		(net "P5V")
	)
	(segment
		(start 115.4684 -134.051548)
		(end 116.8654 -135.448548)
		(width 1.016)
		(layer "In15.Cu")
		(net "P5V")
	)
	(segment
		(start 43.820334 -133.483858)
		(end 43.820334 -129.257806)
		(width 1.016)
		(layer "In15.Cu")
		(net "P5V")
	)
	(segment
		(start 8.23722 -192.33642)
		(end 8.23722 -199.13854)
		(width 1.016)
		(layer "In15.Cu")
		(net "P5V")
	)
	(segment
		(start 21.947632 -375.61012)
		(end 32.535114 -375.61012)
		(width 1.016)
		(layer "In15.Cu")
		(net "P5V")
	)
	(segment
		(start 16.085566 -334.130142)
		(end 15.367 -334.848708)
		(width 1.016)
		(layer "In15.Cu")
		(net "P5V")
	)
	(segment
		(start 8.23722 -199.13854)
		(end 5.99186 -201.3839)
		(width 1.016)
		(layer "In15.Cu")
		(net "P5V")
	)
	(segment
		(start 14.80058 -330.698348)
		(end 16.085566 -331.983334)
		(width 1.016)
		(layer "In15.Cu")
		(net "P5V")
	)
	(segment
		(start 55.51932 -176.34966)
		(end 54.495446 -177.373534)
		(width 0.762)
		(layer "In15.Cu")
		(net "P5V")
	)
	(segment
		(start 204.2414 -364.49254)
		(end 204.2414 -360.756708)
		(width 1.016)
		(layer "In15.Cu")
		(net "P5V")
	)
	(segment
		(start 132.8674 -135.448548)
		(end 136.144 -132.171948)
		(width 1.016)
		(layer "In15.Cu")
		(net "P5V")
	)
	(segment
		(start 112.0902 -134.051548)
		(end 115.4684 -134.051548)
		(width 1.016)
		(layer "In15.Cu")
		(net "P5V")
	)
	(segment
		(start 40.907208 -175.2092)
		(end 35.740086 -170.042078)
		(width 1.016)
		(layer "In15.Cu")
		(net "P5V")
	)
	(segment
		(start 19.79676 -373.459248)
		(end 21.947632 -375.61012)
		(width 1.016)
		(layer "In15.Cu")
		(net "P5V")
	)
	(segment
		(start 19.79676 -345.615768)
		(end 19.79676 -373.459248)
		(width 1.016)
		(layer "In15.Cu")
		(net "P5V")
	)
	(segment
		(start 54.495446 -177.373534)
		(end 54.495446 -177.581814)
		(width 0.508)
		(layer "In15.Cu")
		(net "P5V")
	)
	(segment
		(start 35.740086 -157.6959)
		(end 36.644326 -156.79166)
		(width 1.016)
		(layer "In15.Cu")
		(net "P5V")
	)
	(segment
		(start 283.0576 -385.632198)
		(end 283.0576 -385.170934)
		(width 1.016)
		(layer "In15.Cu")
		(net "P5V")
	)
	(segment
		(start 204.2414 -360.756708)
		(end 201.48804 -358.003348)
		(width 1.016)
		(layer "In15.Cu")
		(net "P5V")
	)
	(segment
		(start 55.51932 -172.263308)
		(end 55.51932 -176.34966)
		(width 0.762)
		(layer "In15.Cu")
		(net "P5V")
	)
	(segment
		(start 15.367 -334.848708)
		(end 15.367 -338.539328)
		(width 1.016)
		(layer "In15.Cu")
		(net "P5V")
	)
	(segment
		(start 53.269388 -171.544488)
		(end 54.8005 -171.544488)
		(width 0.762)
		(layer "In15.Cu")
		(net "P5V")
	)
	(segment
		(start 116.8654 -135.448548)
		(end 132.8674 -135.448548)
		(width 1.016)
		(layer "In15.Cu")
		(net "P5V")
	)
	(segment
		(start 8.804148 -185.70194)
		(end 7.24154 -187.264548)
		(width 1.016)
		(layer "In15.Cu")
		(net "P5V")
	)
	(segment
		(start 7.24154 -187.264548)
		(end 7.24154 -191.34074)
		(width 1.016)
		(layer "In15.Cu")
		(net "P5V")
	)
	(segment
		(start 51.95316 -171.856146)
		(end 50.562002 -173.247304)
		(width 0.381)
		(layer "In15.Cu")
		(net "P5V")
	)
	(segment
		(start 46.37532 -185.70194)
		(end 8.804148 -185.70194)
		(width 1.016)
		(layer "In15.Cu")
		(net "P5V")
	)
	(segment
		(start 92.9386 -134.991348)
		(end 111.1504 -134.991348)
		(width 1.016)
		(layer "In15.Cu")
		(net "P5V")
	)
	(segment
		(start 198.444104 -358.003348)
		(end 196.94525 -356.504494)
		(width 1.016)
		(layer "In15.Cu")
		(net "P5V")
	)
	(segment
		(start 9.76884 -330.698348)
		(end 14.80058 -330.698348)
		(width 1.016)
		(layer "In15.Cu")
		(net "P5V")
	)
	(segment
		(start 277.53056 -384.551428)
		(end 260.29666 -367.317528)
		(width 1.016)
		(layer "In15.Cu")
		(net "P5V")
	)
	(segment
		(start 83.5152 -125.567948)
		(end 92.9386 -134.991348)
		(width 1.016)
		(layer "In15.Cu")
		(net "P5V")
	)
	(segment
		(start 54.8005 -171.544488)
		(end 55.51932 -172.263308)
		(width 0.762)
		(layer "In15.Cu")
		(net "P5V")
	)
	(segment
		(start 52.73548 -170.500548)
		(end 51.95316 -171.282868)
		(width 0.508)
		(layer "In15.Cu")
		(net "P5V")
	)
	(segment
		(start 54.495446 -177.581814)
		(end 46.37532 -185.70194)
		(width 1.016)
		(layer "In15.Cu")
		(net "P5V")
	)
	(segment
		(start 36.644326 -156.79166)
		(end 36.644326 -140.659866)
		(width 1.016)
		(layer "In15.Cu")
		(net "P5V")
	)
	(segment
		(start 55.330598 -117.747542)
		(end 58.031126 -117.747542)
		(width 1.016)
		(layer "In15.Cu")
		(net "P5V")
	)
	(segment
		(start 41.05148 -381.0762)
		(end 43.32478 -383.3495)
		(width 1.016)
		(layer "In15.Cu")
		(net "P5V")
	)
	(segment
		(start 16.46174 -339.634068)
		(end 16.46174 -342.280748)
		(width 1.016)
		(layer "In15.Cu")
		(net "P5V")
	)
	(segment
		(start 58.511186 -117.267482)
		(end 66.811652 -125.567948)
		(width 1.016)
		(layer "In15.Cu")
		(net "P5V")
	)
	(segment
		(start 47.460916 -173.247304)
		(end 45.49902 -175.2092)
		(width 1.016)
		(layer "In15.Cu")
		(net "P5V")
	)
	(segment
		(start 58.031126 -117.747542)
		(end 58.511186 -117.267482)
		(width 1.016)
		(layer "In15.Cu")
		(net "P5V")
	)
	(segment
		(start 51.95316 -171.282868)
		(end 51.95316 -171.856146)
		(width 0.508)
		(layer "In15.Cu")
		(net "P5V")
	)
	(segment
		(start 35.740086 -170.042078)
		(end 35.740086 -157.6959)
		(width 1.016)
		(layer "In15.Cu")
		(net "P5V")
	)
	(segment
		(start 260.29666 -367.317528)
		(end 254.3175 -367.317528)
		(width 1.016)
		(layer "In15.Cu")
		(net "P5V")
	)
	(segment
		(start 36.644326 -140.659866)
		(end 43.820334 -133.483858)
		(width 1.016)
		(layer "In15.Cu")
		(net "P5V")
	)
	(segment
		(start 5.99186 -201.3839)
		(end 5.99186 -326.921368)
		(width 1.016)
		(layer "In15.Cu")
		(net "P5V")
	)
	(segment
		(start 50.562002 -173.247304)
		(end 47.460916 -173.247304)
		(width 0.381)
		(layer "In15.Cu")
		(net "P5V")
	)
	(segment
		(start 16.46174 -342.280748)
		(end 19.79676 -345.615768)
		(width 1.016)
		(layer "In15.Cu")
		(net "P5V")
	)
	(segment
		(start 15.367 -338.539328)
		(end 16.46174 -339.634068)
		(width 1.016)
		(layer "In15.Cu")
		(net "P5V")
	)
	(segment
		(start 201.48804 -358.003348)
		(end 198.444104 -358.003348)
		(width 1.016)
		(layer "In15.Cu")
		(net "P5V")
	)
	(segment
		(start 254.3175 -367.317528)
		(end 248.760742 -361.76077)
		(width 1.016)
		(layer "In15.Cu")
		(net "P5V")
	)
	(segment
		(start 32.535114 -375.61012)
		(end 38.001194 -381.0762)
		(width 1.016)
		(layer "In15.Cu")
		(net "P5V")
	)
	(segment
		(start 248.760742 -361.76077)
		(end 248.760742 -341.051896)
		(width 1.016)
		(layer "In15.Cu")
		(net "P5V")
	)
	(segment
		(start 66.811652 -125.567948)
		(end 83.5152 -125.567948)
		(width 1.016)
		(layer "In15.Cu")
		(net "P5V")
	)
	(segment
		(start 16.085566 -331.983334)
		(end 16.085566 -334.130142)
		(width 1.016)
		(layer "In15.Cu")
		(net "P5V")
	)
	(segment
		(start 98.592894 -284.311598)
		(end 98.592894 -284.847284)
		(width 0.13208)
		(layer "F.Cu")
		(net "P5E_CPU1_PE4_TX_DP<9>")
	)
	(segment
		(start 77.45984 -407.303478)
		(end 77.758798 -407.00452)
		(width 0.13208)
		(layer "F.Cu")
		(net "P5E_CPU1_PE4_TX_DP<9>")
	)
	(segment
		(start 98.592894 -284.847284)
		(end 98.593148 -284.847538)
		(width 0.13208)
		(layer "F.Cu")
		(net "P5E_CPU1_PE4_TX_DP<9>")
	)
	(segment
		(start 77.784198 -408.250644)
		(end 77.45984 -407.926286)
		(width 0.13208)
		(layer "F.Cu")
		(net "P5E_CPU1_PE4_TX_DP<9>")
	)
	(segment
		(start 77.45984 -407.926286)
		(end 77.45984 -407.303478)
		(width 0.13208)
		(layer "F.Cu")
		(net "P5E_CPU1_PE4_TX_DP<9>")
	)
	(segment
		(start 97.748344 -287.28924)
		(end 97.748344 -287.304734)
		(width 0.0889)
		(layer "In2.Cu")
		(net "P5E_CPU1_PE4_TX_DP<9>")
	)
	(segment
		(start 98.688144 -285.64586)
		(end 98.688144 -285.679896)
		(width 0.0889)
		(layer "In2.Cu")
		(net "P5E_CPU1_PE4_TX_DP<9>")
	)
	(segment
		(start 97.278698 -288.103056)
		(end 97.278698 -288.121598)
		(width 0.0889)
		(layer "In2.Cu")
		(net "P5E_CPU1_PE4_TX_DP<9>")
	)
	(segment
		(start 98.436684 -285.118556)
		(end 98.460814 -285.20771)
		(width 0.0889)
		(layer "In2.Cu")
		(net "P5E_CPU1_PE4_TX_DP<9>")
	)
	(segment
		(start 96.934528 -290.739068)
		(end 96.934528 -290.761166)
		(width 0.0889)
		(layer "In2.Cu")
		(net "P5E_CPU1_PE4_TX_DP<9>")
	)
	(segment
		(start 97.9297 -286.968438)
		(end 97.926906 -286.969962)
		(width 0.0889)
		(layer "In2.Cu")
		(net "P5E_CPU1_PE4_TX_DP<9>")
	)
	(segment
		(start 73.633076 -373.257572)
		(end 77.649578 -399.00225)
		(width 0.14732)
		(layer "In2.Cu")
		(net "P5E_CPU1_PE4_TX_DP<9>")
	)
	(segment
		(start 97.930462 -286.96793)
		(end 97.9297 -286.968438)
		(width 0.0889)
		(layer "In2.Cu")
		(net "P5E_CPU1_PE4_TX_DP<9>")
	)
	(segment
		(start 77.649578 -405.231346)
		(end 77.464158 -405.416766)
		(width 0.14732)
		(layer "In2.Cu")
		(net "P5E_CPU1_PE4_TX_DP<9>")
	)
	(segment
		(start 96.934528 -290.761166)
		(end 96.934528 -299.373798)
		(width 0.14732)
		(layer "In2.Cu")
		(net "P5E_CPU1_PE4_TX_DP<9>")
	)
	(segment
		(start 96.892364 -290.561014)
		(end 96.892364 -290.696904)
		(width 0.0889)
		(layer "In2.Cu")
		(net "P5E_CPU1_PE4_TX_DP<9>")
	)
	(segment
		(start 67.922902 -334.214216)
		(end 67.738752 -335.35874)
		(width 0.14732)
		(layer "In2.Cu")
		(net "P5E_CPU1_PE4_TX_DP<9>")
	)
	(segment
		(start 96.808798 -288.917126)
		(end 96.808798 -289.079178)
		(width 0.0889)
		(layer "In2.Cu")
		(net "P5E_CPU1_PE4_TX_DP<9>")
	)
	(segment
		(start 96.934528 -299.373798)
		(end 95.708978 -302.33239)
		(width 0.14732)
		(layer "In2.Cu")
		(net "P5E_CPU1_PE4_TX_DP<9>")
	)
	(segment
		(start 97.46615 -287.778698)
		(end 97.45726 -287.783778)
		(width 0.0889)
		(layer "In2.Cu")
		(net "P5E_CPU1_PE4_TX_DP<9>")
	)
	(segment
		(start 70.817994 -327.224136)
		(end 67.922902 -334.214216)
		(width 0.14732)
		(layer "In2.Cu")
		(net "P5E_CPU1_PE4_TX_DP<9>")
	)
	(segment
		(start 96.992948 -289.277806)
		(end 96.992948 -289.278314)
		(width 0.0889)
		(layer "In2.Cu")
		(net "P5E_CPU1_PE4_TX_DP<9>")
	)
	(segment
		(start 97.941892 -286.961326)
		(end 97.930462 -286.96793)
		(width 0.0889)
		(layer "In2.Cu")
		(net "P5E_CPU1_PE4_TX_DP<9>")
	)
	(segment
		(start 68.110862 -349.698818)
		(end 73.633076 -373.257572)
		(width 0.14732)
		(layer "In2.Cu")
		(net "P5E_CPU1_PE4_TX_DP<9>")
	)
	(segment
		(start 97.27819 -289.752278)
		(end 97.27819 -290.175188)
		(width 0.0889)
		(layer "In2.Cu")
		(net "P5E_CPU1_PE4_TX_DP<9>")
	)
	(segment
		(start 98.593148 -284.847538)
		(end 98.436684 -285.118556)
		(width 0.0889)
		(layer "In2.Cu")
		(net "P5E_CPU1_PE4_TX_DP<9>")
	)
	(segment
		(start 77.464158 -406.70988)
		(end 77.758798 -407.00452)
		(width 0.14732)
		(layer "In2.Cu")
		(net "P5E_CPU1_PE4_TX_DP<9>")
	)
	(segment
		(start 67.738752 -335.35874)
		(end 68.110862 -349.698818)
		(width 0.14732)
		(layer "In2.Cu")
		(net "P5E_CPU1_PE4_TX_DP<9>")
	)
	(segment
		(start 77.464158 -405.416766)
		(end 77.464158 -406.70988)
		(width 0.14732)
		(layer "In2.Cu")
		(net "P5E_CPU1_PE4_TX_DP<9>")
	)
	(segment
		(start 97.27819 -290.175188)
		(end 96.892364 -290.561014)
		(width 0.0889)
		(layer "In2.Cu")
		(net "P5E_CPU1_PE4_TX_DP<9>")
	)
	(segment
		(start 96.99625 -288.592768)
		(end 96.98736 -288.597848)
		(width 0.0889)
		(layer "In2.Cu")
		(net "P5E_CPU1_PE4_TX_DP<9>")
	)
	(segment
		(start 96.892364 -290.696904)
		(end 96.934528 -290.739068)
		(width 0.0889)
		(layer "In2.Cu")
		(net "P5E_CPU1_PE4_TX_DP<9>")
	)
	(segment
		(start 98.218498 -286.466788)
		(end 98.218498 -286.475424)
		(width 0.0889)
		(layer "In2.Cu")
		(net "P5E_CPU1_PE4_TX_DP<9>")
	)
	(segment
		(start 77.649578 -399.00225)
		(end 77.649578 -405.231346)
		(width 0.14732)
		(layer "In2.Cu")
		(net "P5E_CPU1_PE4_TX_DP<9>")
	)
	(segment
		(start 95.708978 -302.33239)
		(end 70.817994 -327.224136)
		(width 0.14732)
		(layer "In2.Cu")
		(net "P5E_CPU1_PE4_TX_DP<9>")
	)
	(arc
		(start 98.218498 -286.475424)
		(mid 98.144507 -286.75499)
		(end 97.941892 -286.961326)
		(width 0.0889)
		(layer "In2.Cu")
		(net "P5E_CPU1_PE4_TX_DP<9>")
	)
	(arc
		(start 97.748344 -287.304734)
		(mid 97.668974 -287.578468)
		(end 97.46615 -287.778698)
		(width 0.0889)
		(layer "In2.Cu")
		(net "P5E_CPU1_PE4_TX_DP<9>")
	)
	(arc
		(start 98.460814 -285.20771)
		(mid 98.469255 -285.21411)
		(end 98.477578 -285.220664)
		(width 0.0889)
		(layer "In2.Cu")
		(net "P5E_CPU1_PE4_TX_DP<9>")
	)
	(arc
		(start 97.45726 -287.783778)
		(mid 97.326346 -287.920138)
		(end 97.278698 -288.103056)
		(width 0.0889)
		(layer "In2.Cu")
		(net "P5E_CPU1_PE4_TX_DP<9>")
	)
	(arc
		(start 98.405696 -286.151066)
		(mid 98.270763 -286.28442)
		(end 98.218498 -286.466788)
		(width 0.0889)
		(layer "In2.Cu")
		(net "P5E_CPU1_PE4_TX_DP<9>")
	)
	(arc
		(start 97.278698 -288.121598)
		(mid 97.198536 -288.393787)
		(end 96.99625 -288.592768)
		(width 0.0889)
		(layer "In2.Cu")
		(net "P5E_CPU1_PE4_TX_DP<9>")
	)
	(arc
		(start 96.992948 -289.278314)
		(mid 97.201547 -289.475614)
		(end 97.27819 -289.752278)
		(width 0.0889)
		(layer "In2.Cu")
		(net "P5E_CPU1_PE4_TX_DP<9>")
	)
	(arc
		(start 98.688144 -285.679896)
		(mid 98.607982 -285.952085)
		(end 98.405696 -286.151066)
		(width 0.0889)
		(layer "In2.Cu")
		(net "P5E_CPU1_PE4_TX_DP<9>")
	)
	(arc
		(start 96.808798 -289.079178)
		(mid 96.883892 -289.194242)
		(end 96.992948 -289.277806)
		(width 0.0889)
		(layer "In2.Cu")
		(net "P5E_CPU1_PE4_TX_DP<9>")
	)
	(arc
		(start 98.477578 -285.220664)
		(mid 98.62966 -285.410096)
		(end 98.688144 -285.64586)
		(width 0.0889)
		(layer "In2.Cu")
		(net "P5E_CPU1_PE4_TX_DP<9>")
	)
	(arc
		(start 96.98736 -288.597848)
		(mid 96.856446 -288.734208)
		(end 96.808798 -288.917126)
		(width 0.0889)
		(layer "In2.Cu")
		(net "P5E_CPU1_PE4_TX_DP<9>")
	)
	(arc
		(start 97.926906 -286.969962)
		(mid 97.795992 -287.106322)
		(end 97.748344 -287.28924)
		(width 0.0889)
		(layer "In2.Cu")
		(net "P5E_CPU1_PE4_TX_DP<9>")
	)
	(segment
		(start 97.653094 -285.939484)
		(end 97.653094 -286.47517)
		(width 0.13208)
		(layer "F.Cu")
		(net "P5E_CPU1_PE4_TX_DP<8>")
	)
	(segment
		(start 74.3966 -407.303478)
		(end 74.695558 -407.00452)
		(width 0.13208)
		(layer "F.Cu")
		(net "P5E_CPU1_PE4_TX_DP<8>")
	)
	(segment
		(start 97.653094 -286.47517)
		(end 97.653348 -286.475424)
		(width 0.13208)
		(layer "F.Cu")
		(net "P5E_CPU1_PE4_TX_DP<8>")
	)
	(segment
		(start 74.3966 -407.926286)
		(end 74.3966 -407.303478)
		(width 0.13208)
		(layer "F.Cu")
		(net "P5E_CPU1_PE4_TX_DP<8>")
	)
	(segment
		(start 74.720958 -408.250644)
		(end 74.3966 -407.926286)
		(width 0.13208)
		(layer "F.Cu")
		(net "P5E_CPU1_PE4_TX_DP<8>")
	)
	(segment
		(start 74.059034 -393.652756)
		(end 74.213212 -393.7762)
		(width 0.14732)
		(layer "In2.Cu")
		(net "P5E_CPU1_PE4_TX_DP<8>")
	)
	(segment
		(start 74.37628 -395.260068)
		(end 74.252582 -395.414246)
		(width 0.14732)
		(layer "In2.Cu")
		(net "P5E_CPU1_PE4_TX_DP<8>")
	)
	(segment
		(start 96.05645 -288.592768)
		(end 96.04756 -288.597848)
		(width 0.0889)
		(layer "In2.Cu")
		(net "P5E_CPU1_PE4_TX_DP<8>")
	)
	(segment
		(start 94.870778 -301.851568)
		(end 69.954902 -326.768206)
		(width 0.14732)
		(layer "In2.Cu")
		(net "P5E_CPU1_PE4_TX_DP<8>")
	)
	(segment
		(start 66.910458 -334.118458)
		(end 66.777362 -334.881474)
		(width 0.14732)
		(layer "In2.Cu")
		(net "P5E_CPU1_PE4_TX_DP<8>")
	)
	(segment
		(start 66.777362 -334.881474)
		(end 67.14363 -349.701866)
		(width 0.14732)
		(layer "In2.Cu")
		(net "P5E_CPU1_PE4_TX_DP<8>")
	)
	(segment
		(start 74.213212 -393.7762)
		(end 74.253344 -394.142722)
		(width 0.14732)
		(layer "In2.Cu")
		(net "P5E_CPU1_PE4_TX_DP<8>")
	)
	(segment
		(start 95.960438 -290.717986)
		(end 96.002602 -290.76015)
		(width 0.0889)
		(layer "In2.Cu")
		(net "P5E_CPU1_PE4_TX_DP<8>")
	)
	(segment
		(start 97.653348 -286.475424)
		(end 97.496884 -286.204406)
		(width 0.0889)
		(layer "In2.Cu")
		(net "P5E_CPU1_PE4_TX_DP<8>")
	)
	(segment
		(start 96.002602 -290.782248)
		(end 96.002602 -299.118782)
		(width 0.14732)
		(layer "In2.Cu")
		(net "P5E_CPU1_PE4_TX_DP<8>")
	)
	(segment
		(start 74.181716 -394.770102)
		(end 74.336148 -394.8938)
		(width 0.14732)
		(layer "In2.Cu")
		(net "P5E_CPU1_PE4_TX_DP<8>")
	)
	(segment
		(start 96.808544 -287.28924)
		(end 96.808544 -287.304734)
		(width 0.0889)
		(layer "In2.Cu")
		(net "P5E_CPU1_PE4_TX_DP<8>")
	)
	(segment
		(start 69.954902 -326.768206)
		(end 66.910458 -334.118458)
		(width 0.14732)
		(layer "In2.Cu")
		(net "P5E_CPU1_PE4_TX_DP<8>")
	)
	(segment
		(start 96.338898 -288.103056)
		(end 96.338898 -288.121598)
		(width 0.0889)
		(layer "In2.Cu")
		(net "P5E_CPU1_PE4_TX_DP<8>")
	)
	(segment
		(start 96.002602 -290.76015)
		(end 96.002602 -290.782248)
		(width 0.0889)
		(layer "In2.Cu")
		(net "P5E_CPU1_PE4_TX_DP<8>")
	)
	(segment
		(start 74.253344 -394.142722)
		(end 74.1299 -394.296646)
		(width 0.14732)
		(layer "In2.Cu")
		(net "P5E_CPU1_PE4_TX_DP<8>")
	)
	(segment
		(start 74.400918 -405.416766)
		(end 74.400918 -406.70988)
		(width 0.14732)
		(layer "In2.Cu")
		(net "P5E_CPU1_PE4_TX_DP<8>")
	)
	(segment
		(start 74.586338 -398.458944)
		(end 74.586338 -405.231346)
		(width 0.14732)
		(layer "In2.Cu")
		(net "P5E_CPU1_PE4_TX_DP<8>")
	)
	(segment
		(start 74.1299 -394.296646)
		(end 74.181716 -394.770102)
		(width 0.14732)
		(layer "In2.Cu")
		(net "P5E_CPU1_PE4_TX_DP<8>")
	)
	(segment
		(start 74.336148 -394.8938)
		(end 74.37628 -395.260068)
		(width 0.14732)
		(layer "In2.Cu")
		(net "P5E_CPU1_PE4_TX_DP<8>")
	)
	(segment
		(start 95.960438 -290.58235)
		(end 95.960438 -290.717986)
		(width 0.0889)
		(layer "In2.Cu")
		(net "P5E_CPU1_PE4_TX_DP<8>")
	)
	(segment
		(start 96.338644 -290.371784)
		(end 95.960438 -290.58235)
		(width 0.0889)
		(layer "In2.Cu")
		(net "P5E_CPU1_PE4_TX_DP<8>")
	)
	(segment
		(start 74.252582 -395.414246)
		(end 74.586338 -398.458944)
		(width 0.14732)
		(layer "In2.Cu")
		(net "P5E_CPU1_PE4_TX_DP<8>")
	)
	(segment
		(start 96.002602 -299.118782)
		(end 94.870778 -301.851568)
		(width 0.14732)
		(layer "In2.Cu")
		(net "P5E_CPU1_PE4_TX_DP<8>")
	)
	(segment
		(start 97.496884 -286.204406)
		(end 97.418652 -286.183578)
		(width 0.0889)
		(layer "In2.Cu")
		(net "P5E_CPU1_PE4_TX_DP<8>")
	)
	(segment
		(start 67.14363 -349.701866)
		(end 71.814436 -373.1895)
		(width 0.14732)
		(layer "In2.Cu")
		(net "P5E_CPU1_PE4_TX_DP<8>")
	)
	(segment
		(start 71.814436 -373.1895)
		(end 74.059034 -393.652756)
		(width 0.14732)
		(layer "In2.Cu")
		(net "P5E_CPU1_PE4_TX_DP<8>")
	)
	(segment
		(start 97.008188 -286.95777)
		(end 96.987106 -286.969962)
		(width 0.0889)
		(layer "In2.Cu")
		(net "P5E_CPU1_PE4_TX_DP<8>")
	)
	(segment
		(start 74.586338 -405.231346)
		(end 74.400918 -405.416766)
		(width 0.14732)
		(layer "In2.Cu")
		(net "P5E_CPU1_PE4_TX_DP<8>")
	)
	(segment
		(start 74.400918 -406.70988)
		(end 74.695558 -407.00452)
		(width 0.14732)
		(layer "In2.Cu")
		(net "P5E_CPU1_PE4_TX_DP<8>")
	)
	(segment
		(start 96.52635 -287.778698)
		(end 96.51746 -287.783778)
		(width 0.0889)
		(layer "In2.Cu")
		(net "P5E_CPU1_PE4_TX_DP<8>")
	)
	(segment
		(start 96.338644 -289.60953)
		(end 96.338644 -290.371784)
		(width 0.0889)
		(layer "In2.Cu")
		(net "P5E_CPU1_PE4_TX_DP<8>")
	)
	(segment
		(start 95.868998 -288.917126)
		(end 95.868998 -289.078416)
		(width 0.0889)
		(layer "In2.Cu")
		(net "P5E_CPU1_PE4_TX_DP<8>")
	)
	(arc
		(start 97.278698 -286.475424)
		(mid 97.206463 -286.751948)
		(end 97.008188 -286.95777)
		(width 0.0889)
		(layer "In2.Cu")
		(net "P5E_CPU1_PE4_TX_DP<8>")
	)
	(arc
		(start 96.808544 -287.304734)
		(mid 96.729174 -287.578468)
		(end 96.52635 -287.778698)
		(width 0.0889)
		(layer "In2.Cu")
		(net "P5E_CPU1_PE4_TX_DP<8>")
	)
	(arc
		(start 95.868998 -289.078416)
		(mid 95.944003 -289.193875)
		(end 96.053148 -289.277806)
		(width 0.0889)
		(layer "In2.Cu")
		(net "P5E_CPU1_PE4_TX_DP<8>")
	)
	(arc
		(start 97.418652 -286.183578)
		(mid 97.315507 -286.313603)
		(end 97.278698 -286.475424)
		(width 0.0889)
		(layer "In2.Cu")
		(net "P5E_CPU1_PE4_TX_DP<8>")
	)
	(arc
		(start 96.04756 -288.597848)
		(mid 95.916646 -288.734208)
		(end 95.868998 -288.917126)
		(width 0.0889)
		(layer "In2.Cu")
		(net "P5E_CPU1_PE4_TX_DP<8>")
	)
	(arc
		(start 96.987106 -286.969962)
		(mid 96.856192 -287.106322)
		(end 96.808544 -287.28924)
		(width 0.0889)
		(layer "In2.Cu")
		(net "P5E_CPU1_PE4_TX_DP<8>")
	)
	(arc
		(start 96.053148 -289.277806)
		(mid 96.22728 -289.416653)
		(end 96.338644 -289.60953)
		(width 0.0889)
		(layer "In2.Cu")
		(net "P5E_CPU1_PE4_TX_DP<8>")
	)
	(arc
		(start 96.51746 -287.783778)
		(mid 96.386546 -287.920138)
		(end 96.338898 -288.103056)
		(width 0.0889)
		(layer "In2.Cu")
		(net "P5E_CPU1_PE4_TX_DP<8>")
	)
	(arc
		(start 96.338898 -288.121598)
		(mid 96.258736 -288.393787)
		(end 96.05645 -288.592768)
		(width 0.0889)
		(layer "In2.Cu")
		(net "P5E_CPU1_PE4_TX_DP<8>")
	)
	(segment
		(start 96.713294 -284.847284)
		(end 96.713548 -284.847538)
		(width 0.13208)
		(layer "F.Cu")
		(net "P5E_CPU1_PE4_TX_DP<7>")
	)
	(segment
		(start 71.33336 -407.926286)
		(end 71.33336 -407.303478)
		(width 0.13208)
		(layer "F.Cu")
		(net "P5E_CPU1_PE4_TX_DP<7>")
	)
	(segment
		(start 96.713294 -284.311598)
		(end 96.713294 -284.847284)
		(width 0.13208)
		(layer "F.Cu")
		(net "P5E_CPU1_PE4_TX_DP<7>")
	)
	(segment
		(start 71.657718 -408.250644)
		(end 71.33336 -407.926286)
		(width 0.13208)
		(layer "F.Cu")
		(net "P5E_CPU1_PE4_TX_DP<7>")
	)
	(segment
		(start 71.33336 -407.303478)
		(end 71.632318 -407.00452)
		(width 0.13208)
		(layer "F.Cu")
		(net "P5E_CPU1_PE4_TX_DP<7>")
	)
	(segment
		(start 96.338898 -286.466788)
		(end 96.338898 -286.475424)
		(width 0.0889)
		(layer "In2.Cu")
		(net "P5E_CPU1_PE4_TX_DP<7>")
	)
	(segment
		(start 96.713548 -284.847538)
		(end 96.557084 -285.118556)
		(width 0.0889)
		(layer "In2.Cu")
		(net "P5E_CPU1_PE4_TX_DP<7>")
	)
	(segment
		(start 95.398844 -290.270184)
		(end 95.018098 -290.65093)
		(width 0.0889)
		(layer "In2.Cu")
		(net "P5E_CPU1_PE4_TX_DP<7>")
	)
	(segment
		(start 66.064892 -349.271844)
		(end 69.926454 -373.071898)
		(width 0.14732)
		(layer "In2.Cu")
		(net "P5E_CPU1_PE4_TX_DP<7>")
	)
	(segment
		(start 96.054672 -286.965644)
		(end 96.047306 -286.969962)
		(width 0.0889)
		(layer "In2.Cu")
		(net "P5E_CPU1_PE4_TX_DP<7>")
	)
	(segment
		(start 96.557084 -285.118556)
		(end 96.581214 -285.20771)
		(width 0.0889)
		(layer "In2.Cu")
		(net "P5E_CPU1_PE4_TX_DP<7>")
	)
	(segment
		(start 71.337678 -406.70988)
		(end 71.632318 -407.00452)
		(width 0.14732)
		(layer "In2.Cu")
		(net "P5E_CPU1_PE4_TX_DP<7>")
	)
	(segment
		(start 96.808544 -285.64586)
		(end 96.808544 -285.679896)
		(width 0.0889)
		(layer "In2.Cu")
		(net "P5E_CPU1_PE4_TX_DP<7>")
	)
	(segment
		(start 69.926454 -373.071898)
		(end 71.523098 -398.012158)
		(width 0.14732)
		(layer "In2.Cu")
		(net "P5E_CPU1_PE4_TX_DP<7>")
	)
	(segment
		(start 69.139308 -326.266556)
		(end 65.867788 -334.16494)
		(width 0.14732)
		(layer "In2.Cu")
		(net "P5E_CPU1_PE4_TX_DP<7>")
	)
	(segment
		(start 95.58655 -287.778698)
		(end 95.57766 -287.783778)
		(width 0.0889)
		(layer "In2.Cu")
		(net "P5E_CPU1_PE4_TX_DP<7>")
	)
	(segment
		(start 71.337678 -405.416766)
		(end 71.337678 -406.70988)
		(width 0.14732)
		(layer "In2.Cu")
		(net "P5E_CPU1_PE4_TX_DP<7>")
	)
	(segment
		(start 66.043302 -349.093282)
		(end 66.064892 -349.271844)
		(width 0.14732)
		(layer "In2.Cu")
		(net "P5E_CPU1_PE4_TX_DP<7>")
	)
	(segment
		(start 95.398844 -289.60953)
		(end 95.398844 -290.270184)
		(width 0.0889)
		(layer "In2.Cu")
		(net "P5E_CPU1_PE4_TX_DP<7>")
	)
	(segment
		(start 65.867788 -334.16494)
		(end 65.628774 -335.245202)
		(width 0.14732)
		(layer "In2.Cu")
		(net "P5E_CPU1_PE4_TX_DP<7>")
	)
	(segment
		(start 93.996002 -301.409862)
		(end 69.139308 -326.266556)
		(width 0.14732)
		(layer "In2.Cu")
		(net "P5E_CPU1_PE4_TX_DP<7>")
	)
	(segment
		(start 95.11665 -288.592768)
		(end 95.10776 -288.597848)
		(width 0.0889)
		(layer "In2.Cu")
		(net "P5E_CPU1_PE4_TX_DP<7>")
	)
	(segment
		(start 95.060262 -290.828984)
		(end 95.060262 -290.851082)
		(width 0.0889)
		(layer "In2.Cu")
		(net "P5E_CPU1_PE4_TX_DP<7>")
	)
	(segment
		(start 71.523098 -398.012158)
		(end 71.523098 -405.231346)
		(width 0.14732)
		(layer "In2.Cu")
		(net "P5E_CPU1_PE4_TX_DP<7>")
	)
	(segment
		(start 95.399098 -288.103056)
		(end 95.399098 -288.121598)
		(width 0.0889)
		(layer "In2.Cu")
		(net "P5E_CPU1_PE4_TX_DP<7>")
	)
	(segment
		(start 95.060262 -298.840906)
		(end 93.996002 -301.409862)
		(width 0.14732)
		(layer "In2.Cu")
		(net "P5E_CPU1_PE4_TX_DP<7>")
	)
	(segment
		(start 71.523098 -405.231346)
		(end 71.337678 -405.416766)
		(width 0.14732)
		(layer "In2.Cu")
		(net "P5E_CPU1_PE4_TX_DP<7>")
	)
	(segment
		(start 95.018098 -290.65093)
		(end 95.018098 -290.78682)
		(width 0.0889)
		(layer "In2.Cu")
		(net "P5E_CPU1_PE4_TX_DP<7>")
	)
	(segment
		(start 95.018098 -290.78682)
		(end 95.060262 -290.828984)
		(width 0.0889)
		(layer "In2.Cu")
		(net "P5E_CPU1_PE4_TX_DP<7>")
	)
	(segment
		(start 95.868744 -287.28924)
		(end 95.868744 -287.304734)
		(width 0.0889)
		(layer "In2.Cu")
		(net "P5E_CPU1_PE4_TX_DP<7>")
	)
	(segment
		(start 65.628774 -335.245202)
		(end 66.043302 -349.093282)
		(width 0.14732)
		(layer "In2.Cu")
		(net "P5E_CPU1_PE4_TX_DP<7>")
	)
	(segment
		(start 94.929198 -288.917126)
		(end 94.929198 -289.078416)
		(width 0.0889)
		(layer "In2.Cu")
		(net "P5E_CPU1_PE4_TX_DP<7>")
	)
	(segment
		(start 95.060262 -290.851082)
		(end 95.060262 -298.840906)
		(width 0.14732)
		(layer "In2.Cu")
		(net "P5E_CPU1_PE4_TX_DP<7>")
	)
	(segment
		(start 96.062292 -286.961326)
		(end 96.054672 -286.965644)
		(width 0.0889)
		(layer "In2.Cu")
		(net "P5E_CPU1_PE4_TX_DP<7>")
	)
	(arc
		(start 96.338898 -286.475424)
		(mid 96.264907 -286.75499)
		(end 96.062292 -286.961326)
		(width 0.0889)
		(layer "In2.Cu")
		(net "P5E_CPU1_PE4_TX_DP<7>")
	)
	(arc
		(start 95.10776 -288.597848)
		(mid 94.976846 -288.734208)
		(end 94.929198 -288.917126)
		(width 0.0889)
		(layer "In2.Cu")
		(net "P5E_CPU1_PE4_TX_DP<7>")
	)
	(arc
		(start 96.597978 -285.220664)
		(mid 96.75006 -285.410096)
		(end 96.808544 -285.64586)
		(width 0.0889)
		(layer "In2.Cu")
		(net "P5E_CPU1_PE4_TX_DP<7>")
	)
	(arc
		(start 96.581214 -285.20771)
		(mid 96.589655 -285.21411)
		(end 96.597978 -285.220664)
		(width 0.0889)
		(layer "In2.Cu")
		(net "P5E_CPU1_PE4_TX_DP<7>")
	)
	(arc
		(start 95.868744 -287.304734)
		(mid 95.789374 -287.578468)
		(end 95.58655 -287.778698)
		(width 0.0889)
		(layer "In2.Cu")
		(net "P5E_CPU1_PE4_TX_DP<7>")
	)
	(arc
		(start 96.047306 -286.969962)
		(mid 95.916392 -287.106322)
		(end 95.868744 -287.28924)
		(width 0.0889)
		(layer "In2.Cu")
		(net "P5E_CPU1_PE4_TX_DP<7>")
	)
	(arc
		(start 95.57766 -287.783778)
		(mid 95.446746 -287.920138)
		(end 95.399098 -288.103056)
		(width 0.0889)
		(layer "In2.Cu")
		(net "P5E_CPU1_PE4_TX_DP<7>")
	)
	(arc
		(start 95.113348 -289.277806)
		(mid 95.28748 -289.416653)
		(end 95.398844 -289.60953)
		(width 0.0889)
		(layer "In2.Cu")
		(net "P5E_CPU1_PE4_TX_DP<7>")
	)
	(arc
		(start 94.929198 -289.078416)
		(mid 95.004203 -289.193875)
		(end 95.113348 -289.277806)
		(width 0.0889)
		(layer "In2.Cu")
		(net "P5E_CPU1_PE4_TX_DP<7>")
	)
	(arc
		(start 96.526096 -286.151066)
		(mid 96.391163 -286.28442)
		(end 96.338898 -286.466788)
		(width 0.0889)
		(layer "In2.Cu")
		(net "P5E_CPU1_PE4_TX_DP<7>")
	)
	(arc
		(start 95.399098 -288.121598)
		(mid 95.318936 -288.393787)
		(end 95.11665 -288.592768)
		(width 0.0889)
		(layer "In2.Cu")
		(net "P5E_CPU1_PE4_TX_DP<7>")
	)
	(arc
		(start 96.808544 -285.679896)
		(mid 96.728382 -285.952085)
		(end 96.526096 -286.151066)
		(width 0.0889)
		(layer "In2.Cu")
		(net "P5E_CPU1_PE4_TX_DP<7>")
	)
	(segment
		(start 95.773494 -285.939484)
		(end 95.773494 -286.47517)
		(width 0.13208)
		(layer "F.Cu")
		(net "P5E_CPU1_PE4_TX_DP<6>")
	)
	(segment
		(start 68.27012 -407.926286)
		(end 68.27012 -407.303478)
		(width 0.13208)
		(layer "F.Cu")
		(net "P5E_CPU1_PE4_TX_DP<6>")
	)
	(segment
		(start 68.27012 -407.303478)
		(end 68.569078 -407.00452)
		(width 0.13208)
		(layer "F.Cu")
		(net "P5E_CPU1_PE4_TX_DP<6>")
	)
	(segment
		(start 68.594478 -408.250644)
		(end 68.27012 -407.926286)
		(width 0.13208)
		(layer "F.Cu")
		(net "P5E_CPU1_PE4_TX_DP<6>")
	)
	(segment
		(start 95.773494 -286.47517)
		(end 95.773748 -286.475424)
		(width 0.13208)
		(layer "F.Cu")
		(net "P5E_CPU1_PE4_TX_DP<6>")
	)
	(segment
		(start 94.459044 -289.60953)
		(end 94.459044 -290.29914)
		(width 0.0889)
		(layer "In2.Cu")
		(net "P5E_CPU1_PE4_TX_DP<6>")
	)
	(segment
		(start 94.64675 -287.778698)
		(end 94.63786 -287.783778)
		(width 0.0889)
		(layer "In2.Cu")
		(net "P5E_CPU1_PE4_TX_DP<6>")
	)
	(segment
		(start 94.088458 -290.995862)
		(end 94.130622 -291.038026)
		(width 0.0889)
		(layer "In2.Cu")
		(net "P5E_CPU1_PE4_TX_DP<6>")
	)
	(segment
		(start 94.928944 -287.28924)
		(end 94.928944 -287.304734)
		(width 0.0889)
		(layer "In2.Cu")
		(net "P5E_CPU1_PE4_TX_DP<6>")
	)
	(segment
		(start 95.773748 -286.475424)
		(end 95.617284 -286.204406)
		(width 0.0889)
		(layer "In2.Cu")
		(net "P5E_CPU1_PE4_TX_DP<6>")
	)
	(segment
		(start 68.436744 -398.12849)
		(end 68.459858 -400.59229)
		(width 0.14732)
		(layer "In2.Cu")
		(net "P5E_CPU1_PE4_TX_DP<6>")
	)
	(segment
		(start 93.989398 -288.917126)
		(end 93.989398 -289.078416)
		(width 0.0889)
		(layer "In2.Cu")
		(net "P5E_CPU1_PE4_TX_DP<6>")
	)
	(segment
		(start 68.459858 -400.59229)
		(end 68.459858 -405.231346)
		(width 0.14732)
		(layer "In2.Cu")
		(net "P5E_CPU1_PE4_TX_DP<6>")
	)
	(segment
		(start 94.088458 -290.669726)
		(end 94.088458 -290.995862)
		(width 0.0889)
		(layer "In2.Cu")
		(net "P5E_CPU1_PE4_TX_DP<6>")
	)
	(segment
		(start 94.459298 -288.103056)
		(end 94.459298 -288.121598)
		(width 0.0889)
		(layer "In2.Cu")
		(net "P5E_CPU1_PE4_TX_DP<6>")
	)
	(segment
		(start 68.425822 -397.00581)
		(end 68.429886 -397.442436)
		(width 0.14732)
		(layer "In2.Cu")
		(net "P5E_CPU1_PE4_TX_DP<6>")
	)
	(segment
		(start 68.419726 -396.319502)
		(end 68.419218 -396.319756)
		(width 0.14732)
		(layer "In2.Cu")
		(net "P5E_CPU1_PE4_TX_DP<6>")
	)
	(segment
		(start 94.130622 -291.060124)
		(end 94.130622 -298.544996)
		(width 0.14732)
		(layer "In2.Cu")
		(net "P5E_CPU1_PE4_TX_DP<6>")
	)
	(segment
		(start 68.429886 -397.442436)
		(end 68.55587 -397.56588)
		(width 0.14732)
		(layer "In2.Cu")
		(net "P5E_CPU1_PE4_TX_DP<6>")
	)
	(segment
		(start 94.459044 -290.29914)
		(end 94.088458 -290.669726)
		(width 0.0889)
		(layer "In2.Cu")
		(net "P5E_CPU1_PE4_TX_DP<6>")
	)
	(segment
		(start 68.274438 -405.416766)
		(end 68.274438 -406.70988)
		(width 0.14732)
		(layer "In2.Cu")
		(net "P5E_CPU1_PE4_TX_DP<6>")
	)
	(segment
		(start 93.136212 -300.946058)
		(end 68.148708 -325.933562)
		(width 0.14732)
		(layer "In2.Cu")
		(net "P5E_CPU1_PE4_TX_DP<6>")
	)
	(segment
		(start 68.204334 -373.489728)
		(end 68.419726 -396.319502)
		(width 0.14732)
		(layer "In2.Cu")
		(net "P5E_CPU1_PE4_TX_DP<6>")
	)
	(segment
		(start 64.640968 -335.334356)
		(end 64.91351 -346.112084)
		(width 0.14732)
		(layer "In2.Cu")
		(net "P5E_CPU1_PE4_TX_DP<6>")
	)
	(segment
		(start 68.20408 -373.489728)
		(end 68.204334 -373.489728)
		(width 0.14732)
		(layer "In2.Cu")
		(net "P5E_CPU1_PE4_TX_DP<6>")
	)
	(segment
		(start 68.148708 -325.933562)
		(end 64.934338 -333.694278)
		(width 0.14732)
		(layer "In2.Cu")
		(net "P5E_CPU1_PE4_TX_DP<6>")
	)
	(segment
		(start 94.130622 -291.038026)
		(end 94.130622 -291.060124)
		(width 0.0889)
		(layer "In2.Cu")
		(net "P5E_CPU1_PE4_TX_DP<6>")
	)
	(segment
		(start 68.459858 -405.231346)
		(end 68.274438 -405.416766)
		(width 0.14732)
		(layer "In2.Cu")
		(net "P5E_CPU1_PE4_TX_DP<6>")
	)
	(segment
		(start 94.17685 -288.592768)
		(end 94.16796 -288.597848)
		(width 0.0889)
		(layer "In2.Cu")
		(net "P5E_CPU1_PE4_TX_DP<6>")
	)
	(segment
		(start 64.934338 -333.694278)
		(end 64.640968 -335.334356)
		(width 0.14732)
		(layer "In2.Cu")
		(net "P5E_CPU1_PE4_TX_DP<6>")
	)
	(segment
		(start 68.202048 -373.45747)
		(end 68.201794 -373.45747)
		(width 0.14732)
		(layer "In2.Cu")
		(net "P5E_CPU1_PE4_TX_DP<6>")
	)
	(segment
		(start 68.274438 -406.70988)
		(end 68.569078 -407.00452)
		(width 0.14732)
		(layer "In2.Cu")
		(net "P5E_CPU1_PE4_TX_DP<6>")
	)
	(segment
		(start 95.617284 -286.204406)
		(end 95.539052 -286.183578)
		(width 0.0889)
		(layer "In2.Cu")
		(net "P5E_CPU1_PE4_TX_DP<6>")
	)
	(segment
		(start 68.201794 -373.45747)
		(end 68.20408 -373.489728)
		(width 0.14732)
		(layer "In2.Cu")
		(net "P5E_CPU1_PE4_TX_DP<6>")
	)
	(segment
		(start 68.419218 -396.319756)
		(end 68.544948 -396.442946)
		(width 0.14732)
		(layer "In2.Cu")
		(net "P5E_CPU1_PE4_TX_DP<6>")
	)
	(segment
		(start 64.91351 -346.112084)
		(end 65.107058 -349.136716)
		(width 0.14732)
		(layer "In2.Cu")
		(net "P5E_CPU1_PE4_TX_DP<6>")
	)
	(segment
		(start 94.130622 -298.544996)
		(end 93.136212 -300.946058)
		(width 0.14732)
		(layer "In2.Cu")
		(net "P5E_CPU1_PE4_TX_DP<6>")
	)
	(segment
		(start 68.559934 -398.003014)
		(end 68.436744 -398.12849)
		(width 0.14732)
		(layer "In2.Cu")
		(net "P5E_CPU1_PE4_TX_DP<6>")
	)
	(segment
		(start 95.116396 -286.964882)
		(end 95.107506 -286.969962)
		(width 0.0889)
		(layer "In2.Cu")
		(net "P5E_CPU1_PE4_TX_DP<6>")
	)
	(segment
		(start 95.128588 -286.95777)
		(end 95.116396 -286.964882)
		(width 0.0889)
		(layer "In2.Cu")
		(net "P5E_CPU1_PE4_TX_DP<6>")
	)
	(segment
		(start 68.549266 -396.88008)
		(end 68.425822 -397.00581)
		(width 0.14732)
		(layer "In2.Cu")
		(net "P5E_CPU1_PE4_TX_DP<6>")
	)
	(segment
		(start 68.55587 -397.56588)
		(end 68.559934 -398.003014)
		(width 0.14732)
		(layer "In2.Cu")
		(net "P5E_CPU1_PE4_TX_DP<6>")
	)
	(segment
		(start 68.544948 -396.442946)
		(end 68.549266 -396.88008)
		(width 0.14732)
		(layer "In2.Cu")
		(net "P5E_CPU1_PE4_TX_DP<6>")
	)
	(segment
		(start 65.107058 -349.136716)
		(end 68.202048 -373.45747)
		(width 0.14732)
		(layer "In2.Cu")
		(net "P5E_CPU1_PE4_TX_DP<6>")
	)
	(arc
		(start 94.16796 -288.597848)
		(mid 94.037046 -288.734208)
		(end 93.989398 -288.917126)
		(width 0.0889)
		(layer "In2.Cu")
		(net "P5E_CPU1_PE4_TX_DP<6>")
	)
	(arc
		(start 94.928944 -287.304734)
		(mid 94.849574 -287.578468)
		(end 94.64675 -287.778698)
		(width 0.0889)
		(layer "In2.Cu")
		(net "P5E_CPU1_PE4_TX_DP<6>")
	)
	(arc
		(start 93.989398 -289.078416)
		(mid 94.064403 -289.193875)
		(end 94.173548 -289.277806)
		(width 0.0889)
		(layer "In2.Cu")
		(net "P5E_CPU1_PE4_TX_DP<6>")
	)
	(arc
		(start 94.63786 -287.783778)
		(mid 94.506946 -287.920138)
		(end 94.459298 -288.103056)
		(width 0.0889)
		(layer "In2.Cu")
		(net "P5E_CPU1_PE4_TX_DP<6>")
	)
	(arc
		(start 94.459298 -288.121598)
		(mid 94.379136 -288.393787)
		(end 94.17685 -288.592768)
		(width 0.0889)
		(layer "In2.Cu")
		(net "P5E_CPU1_PE4_TX_DP<6>")
	)
	(arc
		(start 94.173548 -289.277806)
		(mid 94.34768 -289.416653)
		(end 94.459044 -289.60953)
		(width 0.0889)
		(layer "In2.Cu")
		(net "P5E_CPU1_PE4_TX_DP<6>")
	)
	(arc
		(start 95.539052 -286.183578)
		(mid 95.435907 -286.313603)
		(end 95.399098 -286.475424)
		(width 0.0889)
		(layer "In2.Cu")
		(net "P5E_CPU1_PE4_TX_DP<6>")
	)
	(arc
		(start 95.107506 -286.969962)
		(mid 94.976592 -287.106322)
		(end 94.928944 -287.28924)
		(width 0.0889)
		(layer "In2.Cu")
		(net "P5E_CPU1_PE4_TX_DP<6>")
	)
	(arc
		(start 95.399098 -286.475424)
		(mid 95.326863 -286.751948)
		(end 95.128588 -286.95777)
		(width 0.0889)
		(layer "In2.Cu")
		(net "P5E_CPU1_PE4_TX_DP<6>")
	)
	(segment
		(start 65.20688 -407.303478)
		(end 65.505838 -407.00452)
		(width 0.13208)
		(layer "F.Cu")
		(net "P5E_CPU1_PE4_TX_DP<5>")
	)
	(segment
		(start 65.531238 -408.250644)
		(end 65.20688 -407.926286)
		(width 0.13208)
		(layer "F.Cu")
		(net "P5E_CPU1_PE4_TX_DP<5>")
	)
	(segment
		(start 94.833694 -284.847284)
		(end 94.833948 -284.847538)
		(width 0.13208)
		(layer "F.Cu")
		(net "P5E_CPU1_PE4_TX_DP<5>")
	)
	(segment
		(start 65.20688 -407.926286)
		(end 65.20688 -407.303478)
		(width 0.13208)
		(layer "F.Cu")
		(net "P5E_CPU1_PE4_TX_DP<5>")
	)
	(segment
		(start 94.833694 -284.311598)
		(end 94.833694 -284.847284)
		(width 0.13208)
		(layer "F.Cu")
		(net "P5E_CPU1_PE4_TX_DP<5>")
	)
	(segment
		(start 65.396618 -405.231346)
		(end 65.211198 -405.416766)
		(width 0.14732)
		(layer "In2.Cu")
		(net "P5E_CPU1_PE4_TX_DP<5>")
	)
	(segment
		(start 94.45879 -286.460438)
		(end 94.45879 -286.486092)
		(width 0.0889)
		(layer "In2.Cu")
		(net "P5E_CPU1_PE4_TX_DP<5>")
	)
	(segment
		(start 93.049344 -288.90214)
		(end 93.049344 -289.082226)
		(width 0.0889)
		(layer "In2.Cu")
		(net "P5E_CPU1_PE4_TX_DP<5>")
	)
	(segment
		(start 93.719904 -287.77057)
		(end 93.702632 -287.78073)
		(width 0.0889)
		(layer "In2.Cu")
		(net "P5E_CPU1_PE4_TX_DP<5>")
	)
	(segment
		(start 65.211198 -406.70988)
		(end 65.505838 -407.00452)
		(width 0.14732)
		(layer "In2.Cu")
		(net "P5E_CPU1_PE4_TX_DP<5>")
	)
	(segment
		(start 63.996316 -333.177896)
		(end 63.520574 -335.33334)
		(width 0.14732)
		(layer "In2.Cu")
		(net "P5E_CPU1_PE4_TX_DP<5>")
	)
	(segment
		(start 93.049344 -289.082226)
		(end 93.060266 -289.112706)
		(width 0.0889)
		(layer "In2.Cu")
		(net "P5E_CPU1_PE4_TX_DP<5>")
	)
	(segment
		(start 63.520574 -337.9089)
		(end 63.946532 -347.107002)
		(width 0.14732)
		(layer "In2.Cu")
		(net "P5E_CPU1_PE4_TX_DP<5>")
	)
	(segment
		(start 93.519244 -288.09061)
		(end 93.519244 -288.103056)
		(width 0.0889)
		(layer "In2.Cu")
		(net "P5E_CPU1_PE4_TX_DP<5>")
	)
	(segment
		(start 93.200982 -298.050204)
		(end 92.135452 -300.622716)
		(width 0.14732)
		(layer "In2.Cu")
		(net "P5E_CPU1_PE4_TX_DP<5>")
	)
	(segment
		(start 94.833948 -284.847538)
		(end 94.677484 -285.118556)
		(width 0.0889)
		(layer "In2.Cu")
		(net "P5E_CPU1_PE4_TX_DP<5>")
	)
	(segment
		(start 93.158818 -290.788344)
		(end 93.200982 -290.830508)
		(width 0.0889)
		(layer "In2.Cu")
		(net "P5E_CPU1_PE4_TX_DP<5>")
	)
	(segment
		(start 94.701614 -285.20771)
		(end 94.70136 -285.208218)
		(width 0.0889)
		(layer "In2.Cu")
		(net "P5E_CPU1_PE4_TX_DP<5>")
	)
	(segment
		(start 92.135452 -300.622716)
		(end 67.118484 -325.639684)
		(width 0.14732)
		(layer "In2.Cu")
		(net "P5E_CPU1_PE4_TX_DP<5>")
	)
	(segment
		(start 93.200982 -290.852606)
		(end 93.200982 -298.050204)
		(width 0.14732)
		(layer "In2.Cu")
		(net "P5E_CPU1_PE4_TX_DP<5>")
	)
	(segment
		(start 93.518736 -289.751008)
		(end 93.518736 -290.29279)
		(width 0.0889)
		(layer "In2.Cu")
		(net "P5E_CPU1_PE4_TX_DP<5>")
	)
	(segment
		(start 93.176344 -289.247834)
		(end 93.233748 -289.27806)
		(width 0.0889)
		(layer "In2.Cu")
		(net "P5E_CPU1_PE4_TX_DP<5>")
	)
	(segment
		(start 63.946532 -347.107002)
		(end 66.381376 -373.51081)
		(width 0.14732)
		(layer "In2.Cu")
		(net "P5E_CPU1_PE4_TX_DP<5>")
	)
	(segment
		(start 66.392044 -373.627142)
		(end 65.396618 -400.599656)
		(width 0.14732)
		(layer "In2.Cu")
		(net "P5E_CPU1_PE4_TX_DP<5>")
	)
	(segment
		(start 93.518736 -290.29279)
		(end 93.158818 -290.652708)
		(width 0.0889)
		(layer "In2.Cu")
		(net "P5E_CPU1_PE4_TX_DP<5>")
	)
	(segment
		(start 93.702632 -287.78073)
		(end 93.700854 -287.781746)
		(width 0.0889)
		(layer "In2.Cu")
		(net "P5E_CPU1_PE4_TX_DP<5>")
	)
	(segment
		(start 94.186502 -286.958786)
		(end 94.174818 -286.965644)
		(width 0.0889)
		(layer "In2.Cu")
		(net "P5E_CPU1_PE4_TX_DP<5>")
	)
	(segment
		(start 93.200982 -290.830508)
		(end 93.200982 -290.852606)
		(width 0.0889)
		(layer "In2.Cu")
		(net "P5E_CPU1_PE4_TX_DP<5>")
	)
	(segment
		(start 94.174818 -286.965644)
		(end 94.171262 -286.967676)
		(width 0.0889)
		(layer "In2.Cu")
		(net "P5E_CPU1_PE4_TX_DP<5>")
	)
	(segment
		(start 94.656656 -286.144462)
		(end 94.645988 -286.150812)
		(width 0.0889)
		(layer "In2.Cu")
		(net "P5E_CPU1_PE4_TX_DP<5>")
	)
	(segment
		(start 63.520574 -335.33334)
		(end 63.520574 -337.9089)
		(width 0.14732)
		(layer "In2.Cu")
		(net "P5E_CPU1_PE4_TX_DP<5>")
	)
	(segment
		(start 67.118484 -325.639684)
		(end 63.996316 -333.177896)
		(width 0.14732)
		(layer "In2.Cu")
		(net "P5E_CPU1_PE4_TX_DP<5>")
	)
	(segment
		(start 93.24721 -288.586164)
		(end 93.236542 -288.592514)
		(width 0.0889)
		(layer "In2.Cu")
		(net "P5E_CPU1_PE4_TX_DP<5>")
	)
	(segment
		(start 65.211198 -405.416766)
		(end 65.211198 -406.70988)
		(width 0.14732)
		(layer "In2.Cu")
		(net "P5E_CPU1_PE4_TX_DP<5>")
	)
	(segment
		(start 94.677484 -285.118556)
		(end 94.701614 -285.20771)
		(width 0.0889)
		(layer "In2.Cu")
		(net "P5E_CPU1_PE4_TX_DP<5>")
	)
	(segment
		(start 65.396618 -400.599656)
		(end 65.396618 -405.231346)
		(width 0.14732)
		(layer "In2.Cu")
		(net "P5E_CPU1_PE4_TX_DP<5>")
	)
	(segment
		(start 66.381376 -373.51081)
		(end 66.392044 -373.627142)
		(width 0.14732)
		(layer "In2.Cu")
		(net "P5E_CPU1_PE4_TX_DP<5>")
	)
	(segment
		(start 93.158818 -290.652708)
		(end 93.158818 -290.788344)
		(width 0.0889)
		(layer "In2.Cu")
		(net "P5E_CPU1_PE4_TX_DP<5>")
	)
	(arc
		(start 94.928436 -285.679896)
		(mid 94.851426 -285.946625)
		(end 94.656656 -286.144462)
		(width 0.0889)
		(layer "In2.Cu")
		(net "P5E_CPU1_PE4_TX_DP<5>")
	)
	(arc
		(start 93.233748 -289.27806)
		(mid 93.441893 -289.474967)
		(end 93.518736 -289.751008)
		(width 0.0889)
		(layer "In2.Cu")
		(net "P5E_CPU1_PE4_TX_DP<5>")
	)
	(arc
		(start 94.171262 -286.967676)
		(mid 94.037646 -287.104396)
		(end 93.98889 -287.28924)
		(width 0.0889)
		(layer "In2.Cu")
		(net "P5E_CPU1_PE4_TX_DP<5>")
	)
	(arc
		(start 94.70136 -285.208218)
		(mid 94.709676 -285.214618)
		(end 94.71787 -285.221172)
		(width 0.0889)
		(layer "In2.Cu")
		(net "P5E_CPU1_PE4_TX_DP<5>")
	)
	(arc
		(start 93.98889 -287.28924)
		(mid 93.917082 -287.564936)
		(end 93.719904 -287.77057)
		(width 0.0889)
		(layer "In2.Cu")
		(net "P5E_CPU1_PE4_TX_DP<5>")
	)
	(arc
		(start 94.45879 -286.486092)
		(mid 94.38353 -286.757519)
		(end 94.186502 -286.958786)
		(width 0.0889)
		(layer "In2.Cu")
		(net "P5E_CPU1_PE4_TX_DP<5>")
	)
	(arc
		(start 93.236542 -288.592514)
		(mid 93.103165 -288.723274)
		(end 93.049344 -288.90214)
		(width 0.0889)
		(layer "In2.Cu")
		(net "P5E_CPU1_PE4_TX_DP<5>")
	)
	(arc
		(start 93.700854 -287.781746)
		(mid 93.570759 -287.913086)
		(end 93.519244 -288.09061)
		(width 0.0889)
		(layer "In2.Cu")
		(net "P5E_CPU1_PE4_TX_DP<5>")
	)
	(arc
		(start 94.645988 -286.150812)
		(mid 94.512611 -286.281572)
		(end 94.45879 -286.460438)
		(width 0.0889)
		(layer "In2.Cu")
		(net "P5E_CPU1_PE4_TX_DP<5>")
	)
	(arc
		(start 93.060266 -289.112706)
		(mid 93.105517 -289.191255)
		(end 93.176344 -289.247834)
		(width 0.0889)
		(layer "In2.Cu")
		(net "P5E_CPU1_PE4_TX_DP<5>")
	)
	(arc
		(start 94.71787 -285.221172)
		(mid 94.869829 -285.410239)
		(end 94.928436 -285.645606)
		(width 0.0889)
		(layer "In2.Cu")
		(net "P5E_CPU1_PE4_TX_DP<5>")
	)
	(arc
		(start 94.928436 -285.645606)
		(mid 94.9287 -285.662751)
		(end 94.928436 -285.679896)
		(width 0.0889)
		(layer "In2.Cu")
		(net "P5E_CPU1_PE4_TX_DP<5>")
	)
	(arc
		(start 93.519244 -288.103056)
		(mid 93.446552 -288.380261)
		(end 93.24721 -288.586164)
		(width 0.0889)
		(layer "In2.Cu")
		(net "P5E_CPU1_PE4_TX_DP<5>")
	)
	(segment
		(start 93.893894 -285.939484)
		(end 93.893894 -286.47517)
		(width 0.13208)
		(layer "F.Cu")
		(net "P5E_CPU1_PE4_TX_DP<4>")
	)
	(segment
		(start 62.14364 -407.926286)
		(end 62.14364 -407.303478)
		(width 0.13208)
		(layer "F.Cu")
		(net "P5E_CPU1_PE4_TX_DP<4>")
	)
	(segment
		(start 62.14364 -407.303478)
		(end 62.442598 -407.00452)
		(width 0.13208)
		(layer "F.Cu")
		(net "P5E_CPU1_PE4_TX_DP<4>")
	)
	(segment
		(start 62.467998 -408.250644)
		(end 62.14364 -407.926286)
		(width 0.13208)
		(layer "F.Cu")
		(net "P5E_CPU1_PE4_TX_DP<4>")
	)
	(segment
		(start 93.893894 -286.47517)
		(end 93.894148 -286.475424)
		(width 0.13208)
		(layer "F.Cu")
		(net "P5E_CPU1_PE4_TX_DP<4>")
	)
	(segment
		(start 62.333378 -405.231346)
		(end 62.147958 -405.416766)
		(width 0.14732)
		(layer "In2.Cu")
		(net "P5E_CPU1_PE4_TX_DP<4>")
	)
	(segment
		(start 92.579698 -288.103056)
		(end 92.579698 -288.121598)
		(width 0.0889)
		(layer "In2.Cu")
		(net "P5E_CPU1_PE4_TX_DP<4>")
	)
	(segment
		(start 66.344292 -325.074026)
		(end 65.591436 -326.609964)
		(width 0.14732)
		(layer "In2.Cu")
		(net "P5E_CPU1_PE4_TX_DP<4>")
	)
	(segment
		(start 62.333378 -400.195288)
		(end 62.333378 -405.231346)
		(width 0.14732)
		(layer "In2.Cu")
		(net "P5E_CPU1_PE4_TX_DP<4>")
	)
	(segment
		(start 63.27394 -350.173544)
		(end 64.62649 -373.601488)
		(width 0.14732)
		(layer "In2.Cu")
		(net "P5E_CPU1_PE4_TX_DP<4>")
	)
	(segment
		(start 93.242892 -286.961326)
		(end 93.240606 -286.962596)
		(width 0.0889)
		(layer "In2.Cu")
		(net "P5E_CPU1_PE4_TX_DP<4>")
	)
	(segment
		(start 62.638432 -398.122394)
		(end 62.503558 -398.235424)
		(width 0.14732)
		(layer "In2.Cu")
		(net "P5E_CPU1_PE4_TX_DP<4>")
	)
	(segment
		(start 62.77356 -396.568422)
		(end 62.735714 -397.003778)
		(width 0.14732)
		(layer "In2.Cu")
		(net "P5E_CPU1_PE4_TX_DP<4>")
	)
	(segment
		(start 92.579698 -289.752532)
		(end 92.579698 -290.354004)
		(width 0.0889)
		(layer "In2.Cu")
		(net "P5E_CPU1_PE4_TX_DP<4>")
	)
	(segment
		(start 62.731396 -333.805784)
		(end 62.496446 -335.65846)
		(width 0.14732)
		(layer "In2.Cu")
		(net "P5E_CPU1_PE4_TX_DP<4>")
	)
	(segment
		(start 64.624458 -373.81053)
		(end 62.660276 -396.433548)
		(width 0.14732)
		(layer "In2.Cu")
		(net "P5E_CPU1_PE4_TX_DP<4>")
	)
	(segment
		(start 92.296488 -288.593276)
		(end 92.28836 -288.597848)
		(width 0.0889)
		(layer "In2.Cu")
		(net "P5E_CPU1_PE4_TX_DP<4>")
	)
	(segment
		(start 92.109798 -288.917126)
		(end 92.109544 -288.91738)
		(width 0.0889)
		(layer "In2.Cu")
		(net "P5E_CPU1_PE4_TX_DP<4>")
	)
	(segment
		(start 62.676278 -397.687038)
		(end 62.638432 -398.122394)
		(width 0.14732)
		(layer "In2.Cu")
		(net "P5E_CPU1_PE4_TX_DP<4>")
	)
	(segment
		(start 92.215462 -290.71824)
		(end 92.215462 -290.853876)
		(width 0.0889)
		(layer "In2.Cu")
		(net "P5E_CPU1_PE4_TX_DP<4>")
	)
	(segment
		(start 92.579698 -290.354004)
		(end 92.215462 -290.71824)
		(width 0.0889)
		(layer "In2.Cu")
		(net "P5E_CPU1_PE4_TX_DP<4>")
	)
	(segment
		(start 93.240606 -286.962596)
		(end 93.23959 -286.963104)
		(width 0.0889)
		(layer "In2.Cu")
		(net "P5E_CPU1_PE4_TX_DP<4>")
	)
	(segment
		(start 62.562994 -397.552164)
		(end 62.676278 -397.687038)
		(width 0.14732)
		(layer "In2.Cu")
		(net "P5E_CPU1_PE4_TX_DP<4>")
	)
	(segment
		(start 65.591436 -326.609964)
		(end 63.80607 -330.823316)
		(width 0.14732)
		(layer "In2.Cu")
		(net "P5E_CPU1_PE4_TX_DP<4>")
	)
	(segment
		(start 92.257626 -292.072822)
		(end 88.589104 -295.741344)
		(width 0.14732)
		(layer "In2.Cu")
		(net "P5E_CPU1_PE4_TX_DP<4>")
	)
	(segment
		(start 62.147958 -406.70988)
		(end 62.442598 -407.00452)
		(width 0.14732)
		(layer "In2.Cu")
		(net "P5E_CPU1_PE4_TX_DP<4>")
	)
	(segment
		(start 92.109544 -288.91738)
		(end 92.109544 -289.079178)
		(width 0.0889)
		(layer "In2.Cu")
		(net "P5E_CPU1_PE4_TX_DP<4>")
	)
	(segment
		(start 92.215462 -290.853876)
		(end 92.257626 -290.89604)
		(width 0.0889)
		(layer "In2.Cu")
		(net "P5E_CPU1_PE4_TX_DP<4>")
	)
	(segment
		(start 62.660276 -396.433548)
		(end 62.77356 -396.568422)
		(width 0.14732)
		(layer "In2.Cu")
		(net "P5E_CPU1_PE4_TX_DP<4>")
	)
	(segment
		(start 62.91072 -346.31249)
		(end 63.27394 -350.173544)
		(width 0.14732)
		(layer "In2.Cu")
		(net "P5E_CPU1_PE4_TX_DP<4>")
	)
	(segment
		(start 92.29725 -288.592768)
		(end 92.296488 -288.593276)
		(width 0.0889)
		(layer "In2.Cu")
		(net "P5E_CPU1_PE4_TX_DP<4>")
	)
	(segment
		(start 92.257626 -290.918138)
		(end 92.257626 -292.072822)
		(width 0.14732)
		(layer "In2.Cu")
		(net "P5E_CPU1_PE4_TX_DP<4>")
	)
	(segment
		(start 93.23959 -286.963104)
		(end 93.236796 -286.964882)
		(width 0.0889)
		(layer "In2.Cu")
		(net "P5E_CPU1_PE4_TX_DP<4>")
	)
	(segment
		(start 93.894148 -286.475424)
		(end 93.737684 -286.204406)
		(width 0.0889)
		(layer "In2.Cu")
		(net "P5E_CPU1_PE4_TX_DP<4>")
	)
	(segment
		(start 62.496446 -335.65846)
		(end 62.91072 -346.31249)
		(width 0.14732)
		(layer "In2.Cu")
		(net "P5E_CPU1_PE4_TX_DP<4>")
	)
	(segment
		(start 62.735714 -397.003778)
		(end 62.600586 -397.117062)
		(width 0.14732)
		(layer "In2.Cu")
		(net "P5E_CPU1_PE4_TX_DP<4>")
	)
	(segment
		(start 92.76715 -287.778698)
		(end 92.75826 -287.783778)
		(width 0.0889)
		(layer "In2.Cu")
		(net "P5E_CPU1_PE4_TX_DP<4>")
	)
	(segment
		(start 93.737684 -286.204406)
		(end 93.659452 -286.183578)
		(width 0.0889)
		(layer "In2.Cu")
		(net "P5E_CPU1_PE4_TX_DP<4>")
	)
	(segment
		(start 92.29344 -289.263074)
		(end 92.29344 -289.27806)
		(width 0.0889)
		(layer "In2.Cu")
		(net "P5E_CPU1_PE4_TX_DP<4>")
	)
	(segment
		(start 64.62649 -373.601488)
		(end 64.626744 -373.604282)
		(width 0.14732)
		(layer "In2.Cu")
		(net "P5E_CPU1_PE4_TX_DP<4>")
	)
	(segment
		(start 80.892904 -310.525414)
		(end 66.344292 -325.074026)
		(width 0.14732)
		(layer "In2.Cu")
		(net "P5E_CPU1_PE4_TX_DP<4>")
	)
	(segment
		(start 62.147958 -405.416766)
		(end 62.147958 -406.70988)
		(width 0.14732)
		(layer "In2.Cu")
		(net "P5E_CPU1_PE4_TX_DP<4>")
	)
	(segment
		(start 92.257626 -290.89604)
		(end 92.257626 -290.918138)
		(width 0.0889)
		(layer "In2.Cu")
		(net "P5E_CPU1_PE4_TX_DP<4>")
	)
	(segment
		(start 63.80607 -330.823316)
		(end 62.731396 -333.805784)
		(width 0.14732)
		(layer "In2.Cu")
		(net "P5E_CPU1_PE4_TX_DP<4>")
	)
	(segment
		(start 64.626744 -373.604282)
		(end 64.626236 -373.60479)
		(width 0.14732)
		(layer "In2.Cu")
		(net "P5E_CPU1_PE4_TX_DP<4>")
	)
	(segment
		(start 88.589104 -295.741344)
		(end 80.892904 -310.525414)
		(width 0.14732)
		(layer "In2.Cu")
		(net "P5E_CPU1_PE4_TX_DP<4>")
	)
	(segment
		(start 93.049598 -287.280604)
		(end 93.049598 -287.299146)
		(width 0.0889)
		(layer "In2.Cu")
		(net "P5E_CPU1_PE4_TX_DP<4>")
	)
	(segment
		(start 62.503558 -398.235424)
		(end 62.333378 -400.195288)
		(width 0.14732)
		(layer "In2.Cu")
		(net "P5E_CPU1_PE4_TX_DP<4>")
	)
	(segment
		(start 62.600586 -397.117062)
		(end 62.562994 -397.552164)
		(width 0.14732)
		(layer "In2.Cu")
		(net "P5E_CPU1_PE4_TX_DP<4>")
	)
	(segment
		(start 64.626236 -373.60479)
		(end 64.624458 -373.81053)
		(width 0.14732)
		(layer "In2.Cu")
		(net "P5E_CPU1_PE4_TX_DP<4>")
	)
	(arc
		(start 92.28836 -288.597848)
		(mid 92.157446 -288.734208)
		(end 92.109798 -288.917126)
		(width 0.0889)
		(layer "In2.Cu")
		(net "P5E_CPU1_PE4_TX_DP<4>")
	)
	(arc
		(start 92.579698 -288.121598)
		(mid 92.499536 -288.393787)
		(end 92.29725 -288.592768)
		(width 0.0889)
		(layer "In2.Cu")
		(net "P5E_CPU1_PE4_TX_DP<4>")
	)
	(arc
		(start 93.236796 -286.964882)
		(mid 93.101863 -287.098236)
		(end 93.049598 -287.280604)
		(width 0.0889)
		(layer "In2.Cu")
		(net "P5E_CPU1_PE4_TX_DP<4>")
	)
	(arc
		(start 92.29344 -289.27806)
		(mid 92.502555 -289.475491)
		(end 92.579698 -289.752532)
		(width 0.0889)
		(layer "In2.Cu")
		(net "P5E_CPU1_PE4_TX_DP<4>")
	)
	(arc
		(start 92.75826 -287.783778)
		(mid 92.627346 -287.920138)
		(end 92.579698 -288.103056)
		(width 0.0889)
		(layer "In2.Cu")
		(net "P5E_CPU1_PE4_TX_DP<4>")
	)
	(arc
		(start 93.049598 -287.299146)
		(mid 92.971487 -287.576095)
		(end 92.76715 -287.778698)
		(width 0.0889)
		(layer "In2.Cu")
		(net "P5E_CPU1_PE4_TX_DP<4>")
	)
	(arc
		(start 93.519498 -286.475424)
		(mid 93.445507 -286.75499)
		(end 93.242892 -286.961326)
		(width 0.0889)
		(layer "In2.Cu")
		(net "P5E_CPU1_PE4_TX_DP<4>")
	)
	(arc
		(start 93.659452 -286.183578)
		(mid 93.556307 -286.313603)
		(end 93.519498 -286.475424)
		(width 0.0889)
		(layer "In2.Cu")
		(net "P5E_CPU1_PE4_TX_DP<4>")
	)
	(arc
		(start 92.109544 -289.079178)
		(mid 92.186183 -289.186435)
		(end 92.29344 -289.263074)
		(width 0.0889)
		(layer "In2.Cu")
		(net "P5E_CPU1_PE4_TX_DP<4>")
	)
	(segment
		(start 59.0804 -407.926286)
		(end 59.0804 -407.303478)
		(width 0.13208)
		(layer "F.Cu")
		(net "P5E_CPU1_PE4_TX_DP<3>")
	)
	(segment
		(start 59.404758 -408.250644)
		(end 59.0804 -407.926286)
		(width 0.13208)
		(layer "F.Cu")
		(net "P5E_CPU1_PE4_TX_DP<3>")
	)
	(segment
		(start 59.0804 -407.303478)
		(end 59.379358 -407.00452)
		(width 0.13208)
		(layer "F.Cu")
		(net "P5E_CPU1_PE4_TX_DP<3>")
	)
	(segment
		(start 92.954094 -284.847284)
		(end 92.954348 -284.847538)
		(width 0.13208)
		(layer "F.Cu")
		(net "P5E_CPU1_PE4_TX_DP<3>")
	)
	(segment
		(start 92.954094 -284.311598)
		(end 92.954094 -284.847284)
		(width 0.13208)
		(layer "F.Cu")
		(net "P5E_CPU1_PE4_TX_DP<3>")
	)
	(segment
		(start 91.284044 -290.934902)
		(end 91.326208 -290.977066)
		(width 0.0889)
		(layer "In2.Cu")
		(net "P5E_CPU1_PE4_TX_DP<3>")
	)
	(segment
		(start 62.832234 -373.394224)
		(end 59.270138 -400.195796)
		(width 0.14732)
		(layer "In2.Cu")
		(net "P5E_CPU1_PE4_TX_DP<3>")
	)
	(segment
		(start 92.29725 -286.964882)
		(end 92.28836 -286.969962)
		(width 0.0889)
		(layer "In2.Cu")
		(net "P5E_CPU1_PE4_TX_DP<3>")
	)
	(segment
		(start 61.200284 -342.612726)
		(end 62.421008 -355.305106)
		(width 0.14732)
		(layer "In2.Cu")
		(net "P5E_CPU1_PE4_TX_DP<3>")
	)
	(segment
		(start 92.109798 -287.28924)
		(end 92.109798 -287.299146)
		(width 0.0889)
		(layer "In2.Cu")
		(net "P5E_CPU1_PE4_TX_DP<3>")
	)
	(segment
		(start 92.76715 -286.151066)
		(end 92.75826 -286.156146)
		(width 0.0889)
		(layer "In2.Cu")
		(net "P5E_CPU1_PE4_TX_DP<3>")
	)
	(segment
		(start 62.849506 -325.643748)
		(end 62.849506 -325.644002)
		(width 0.14732)
		(layer "In2.Cu")
		(net "P5E_CPU1_PE4_TX_DP<3>")
	)
	(segment
		(start 91.326208 -290.977066)
		(end 91.326208 -290.999164)
		(width 0.0889)
		(layer "In2.Cu")
		(net "P5E_CPU1_PE4_TX_DP<3>")
	)
	(segment
		(start 62.849506 -325.644002)
		(end 61.417454 -326.237092)
		(width 0.14732)
		(layer "In2.Cu")
		(net "P5E_CPU1_PE4_TX_DP<3>")
	)
	(segment
		(start 91.326208 -290.999164)
		(end 91.326208 -291.57549)
		(width 0.14732)
		(layer "In2.Cu")
		(net "P5E_CPU1_PE4_TX_DP<3>")
	)
	(segment
		(start 91.825064 -287.780222)
		(end 91.824048 -287.78073)
		(width 0.0889)
		(layer "In2.Cu")
		(net "P5E_CPU1_PE4_TX_DP<3>")
	)
	(segment
		(start 59.084718 -406.70988)
		(end 59.379358 -407.00452)
		(width 0.14732)
		(layer "In2.Cu")
		(net "P5E_CPU1_PE4_TX_DP<3>")
	)
	(segment
		(start 92.954348 -284.847538)
		(end 92.797884 -285.118556)
		(width 0.0889)
		(layer "In2.Cu")
		(net "P5E_CPU1_PE4_TX_DP<3>")
	)
	(segment
		(start 61.038994 -326.734678)
		(end 61.200284 -342.612726)
		(width 0.14732)
		(layer "In2.Cu")
		(net "P5E_CPU1_PE4_TX_DP<3>")
	)
	(segment
		(start 62.421008 -355.305106)
		(end 62.832234 -373.393208)
		(width 0.14732)
		(layer "In2.Cu")
		(net "P5E_CPU1_PE4_TX_DP<3>")
	)
	(segment
		(start 91.82735 -287.778698)
		(end 91.825064 -287.780222)
		(width 0.0889)
		(layer "In2.Cu")
		(net "P5E_CPU1_PE4_TX_DP<3>")
	)
	(segment
		(start 91.354148 -289.277806)
		(end 91.460828 -289.33394)
		(width 0.0889)
		(layer "In2.Cu")
		(net "P5E_CPU1_PE4_TX_DP<3>")
	)
	(segment
		(start 91.169998 -288.917126)
		(end 91.169998 -289.078416)
		(width 0.0889)
		(layer "In2.Cu")
		(net "P5E_CPU1_PE4_TX_DP<3>")
	)
	(segment
		(start 59.270138 -400.195796)
		(end 59.270138 -405.231346)
		(width 0.14732)
		(layer "In2.Cu")
		(net "P5E_CPU1_PE4_TX_DP<3>")
	)
	(segment
		(start 91.35745 -288.592768)
		(end 91.34856 -288.597848)
		(width 0.0889)
		(layer "In2.Cu")
		(net "P5E_CPU1_PE4_TX_DP<3>")
	)
	(segment
		(start 92.579698 -286.475424)
		(end 92.579698 -286.48533)
		(width 0.0889)
		(layer "In2.Cu")
		(net "P5E_CPU1_PE4_TX_DP<3>")
	)
	(segment
		(start 92.797884 -285.118556)
		(end 92.822014 -285.20771)
		(width 0.0889)
		(layer "In2.Cu")
		(net "P5E_CPU1_PE4_TX_DP<3>")
	)
	(segment
		(start 61.302392 -326.331834)
		(end 61.098938 -326.55637)
		(width 0.14732)
		(layer "In2.Cu")
		(net "P5E_CPU1_PE4_TX_DP<3>")
	)
	(segment
		(start 91.284044 -290.52139)
		(end 91.284044 -290.934902)
		(width 0.0889)
		(layer "In2.Cu")
		(net "P5E_CPU1_PE4_TX_DP<3>")
	)
	(segment
		(start 91.639898 -288.103056)
		(end 91.639898 -288.11728)
		(width 0.0889)
		(layer "In2.Cu")
		(net "P5E_CPU1_PE4_TX_DP<3>")
	)
	(segment
		(start 61.098938 -326.55637)
		(end 61.038994 -326.734678)
		(width 0.14732)
		(layer "In2.Cu")
		(net "P5E_CPU1_PE4_TX_DP<3>")
	)
	(segment
		(start 91.639644 -289.630612)
		(end 91.639644 -290.31311)
		(width 0.0889)
		(layer "In2.Cu")
		(net "P5E_CPU1_PE4_TX_DP<3>")
	)
	(segment
		(start 64.28232 -325.05015)
		(end 62.849506 -325.643748)
		(width 0.14732)
		(layer "In2.Cu")
		(net "P5E_CPU1_PE4_TX_DP<3>")
	)
	(segment
		(start 91.639644 -290.31311)
		(end 91.284044 -290.52139)
		(width 0.0889)
		(layer "In2.Cu")
		(net "P5E_CPU1_PE4_TX_DP<3>")
	)
	(segment
		(start 93.04655 -285.541974)
		(end 93.049344 -285.683452)
		(width 0.0889)
		(layer "In2.Cu")
		(net "P5E_CPU1_PE4_TX_DP<3>")
	)
	(segment
		(start 66.579496 -323.515228)
		(end 64.28232 -325.05015)
		(width 0.14732)
		(layer "In2.Cu")
		(net "P5E_CPU1_PE4_TX_DP<3>")
	)
	(segment
		(start 91.824048 -287.78073)
		(end 91.81846 -287.783778)
		(width 0.0889)
		(layer "In2.Cu")
		(net "P5E_CPU1_PE4_TX_DP<3>")
	)
	(segment
		(start 79.834994 -310.25973)
		(end 66.579496 -323.515228)
		(width 0.14732)
		(layer "In2.Cu")
		(net "P5E_CPU1_PE4_TX_DP<3>")
	)
	(segment
		(start 91.460828 -289.33394)
		(end 91.639644 -289.630612)
		(width 0.0889)
		(layer "In2.Cu")
		(net "P5E_CPU1_PE4_TX_DP<3>")
	)
	(segment
		(start 62.832234 -373.393208)
		(end 62.832234 -373.394224)
		(width 0.14732)
		(layer "In2.Cu")
		(net "P5E_CPU1_PE4_TX_DP<3>")
	)
	(segment
		(start 59.270138 -405.231346)
		(end 59.084718 -405.416766)
		(width 0.14732)
		(layer "In2.Cu")
		(net "P5E_CPU1_PE4_TX_DP<3>")
	)
	(segment
		(start 92.838778 -285.220664)
		(end 92.91955 -285.285688)
		(width 0.0889)
		(layer "In2.Cu")
		(net "P5E_CPU1_PE4_TX_DP<3>")
	)
	(segment
		(start 61.417454 -326.237092)
		(end 61.302392 -326.331834)
		(width 0.14732)
		(layer "In2.Cu")
		(net "P5E_CPU1_PE4_TX_DP<3>")
	)
	(segment
		(start 91.326208 -291.57549)
		(end 87.644986 -295.256966)
		(width 0.14732)
		(layer "In2.Cu")
		(net "P5E_CPU1_PE4_TX_DP<3>")
	)
	(segment
		(start 87.644986 -295.256966)
		(end 79.834994 -310.25973)
		(width 0.14732)
		(layer "In2.Cu")
		(net "P5E_CPU1_PE4_TX_DP<3>")
	)
	(segment
		(start 59.084718 -405.416766)
		(end 59.084718 -406.70988)
		(width 0.14732)
		(layer "In2.Cu")
		(net "P5E_CPU1_PE4_TX_DP<3>")
	)
	(arc
		(start 92.822014 -285.20771)
		(mid 92.830455 -285.21411)
		(end 92.838778 -285.220664)
		(width 0.0889)
		(layer "In2.Cu")
		(net "P5E_CPU1_PE4_TX_DP<3>")
	)
	(arc
		(start 91.169998 -289.078416)
		(mid 91.245003 -289.193875)
		(end 91.354148 -289.277806)
		(width 0.0889)
		(layer "In2.Cu")
		(net "P5E_CPU1_PE4_TX_DP<3>")
	)
	(arc
		(start 92.109798 -287.299146)
		(mid 92.031687 -287.576095)
		(end 91.82735 -287.778698)
		(width 0.0889)
		(layer "In2.Cu")
		(net "P5E_CPU1_PE4_TX_DP<3>")
	)
	(arc
		(start 92.91955 -285.285688)
		(mid 93.011232 -285.399862)
		(end 93.04655 -285.541974)
		(width 0.0889)
		(layer "In2.Cu")
		(net "P5E_CPU1_PE4_TX_DP<3>")
	)
	(arc
		(start 91.34856 -288.597848)
		(mid 91.221306 -288.727814)
		(end 91.170252 -288.902394)
		(width 0.0889)
		(layer "In2.Cu")
		(net "P5E_CPU1_PE4_TX_DP<3>")
	)
	(arc
		(start 91.81846 -287.783778)
		(mid 91.687546 -287.920138)
		(end 91.639898 -288.103056)
		(width 0.0889)
		(layer "In2.Cu")
		(net "P5E_CPU1_PE4_TX_DP<3>")
	)
	(arc
		(start 91.170252 -288.902394)
		(mid 91.170055 -288.909759)
		(end 91.169998 -288.917126)
		(width 0.0889)
		(layer "In2.Cu")
		(net "P5E_CPU1_PE4_TX_DP<3>")
	)
	(arc
		(start 91.639898 -288.11728)
		(mid 91.560757 -288.391903)
		(end 91.35745 -288.592768)
		(width 0.0889)
		(layer "In2.Cu")
		(net "P5E_CPU1_PE4_TX_DP<3>")
	)
	(arc
		(start 92.579952 -286.460692)
		(mid 92.579755 -286.468057)
		(end 92.579698 -286.475424)
		(width 0.0889)
		(layer "In2.Cu")
		(net "P5E_CPU1_PE4_TX_DP<3>")
	)
	(arc
		(start 93.049344 -285.683452)
		(mid 92.968433 -285.95358)
		(end 92.76715 -286.151066)
		(width 0.0889)
		(layer "In2.Cu")
		(net "P5E_CPU1_PE4_TX_DP<3>")
	)
	(arc
		(start 92.28836 -286.969962)
		(mid 92.157446 -287.106322)
		(end 92.109798 -287.28924)
		(width 0.0889)
		(layer "In2.Cu")
		(net "P5E_CPU1_PE4_TX_DP<3>")
	)
	(arc
		(start 92.579698 -286.48533)
		(mid 92.501587 -286.762279)
		(end 92.29725 -286.964882)
		(width 0.0889)
		(layer "In2.Cu")
		(net "P5E_CPU1_PE4_TX_DP<3>")
	)
	(arc
		(start 92.75826 -286.156146)
		(mid 92.631006 -286.286112)
		(end 92.579952 -286.460692)
		(width 0.0889)
		(layer "In2.Cu")
		(net "P5E_CPU1_PE4_TX_DP<3>")
	)
	(segment
		(start 56.341518 -408.250644)
		(end 56.01716 -407.926286)
		(width 0.13208)
		(layer "F.Cu")
		(net "P5E_CPU1_PE4_TX_DP<2>")
	)
	(segment
		(start 92.014294 -286.47517)
		(end 92.014548 -286.475424)
		(width 0.13208)
		(layer "F.Cu")
		(net "P5E_CPU1_PE4_TX_DP<2>")
	)
	(segment
		(start 56.01716 -407.303478)
		(end 56.316118 -407.00452)
		(width 0.13208)
		(layer "F.Cu")
		(net "P5E_CPU1_PE4_TX_DP<2>")
	)
	(segment
		(start 56.01716 -407.926286)
		(end 56.01716 -407.303478)
		(width 0.13208)
		(layer "F.Cu")
		(net "P5E_CPU1_PE4_TX_DP<2>")
	)
	(segment
		(start 92.014294 -285.939484)
		(end 92.014294 -286.47517)
		(width 0.13208)
		(layer "F.Cu")
		(net "P5E_CPU1_PE4_TX_DP<2>")
	)
	(segment
		(start 91.858084 -286.204406)
		(end 91.779852 -286.183578)
		(width 0.0889)
		(layer "In2.Cu")
		(net "P5E_CPU1_PE4_TX_DP<2>")
	)
	(segment
		(start 67.649344 -321.113404)
		(end 62.152022 -324.786752)
		(width 0.14732)
		(layer "In2.Cu")
		(net "P5E_CPU1_PE4_TX_DP<2>")
	)
	(segment
		(start 56.732932 -397.995648)
		(end 56.588152 -398.095724)
		(width 0.14732)
		(layer "In2.Cu")
		(net "P5E_CPU1_PE4_TX_DP<2>")
	)
	(segment
		(start 56.933338 -396.891002)
		(end 56.788558 -396.991078)
		(width 0.14732)
		(layer "In2.Cu")
		(net "P5E_CPU1_PE4_TX_DP<2>")
	)
	(segment
		(start 90.229944 -288.917126)
		(end 90.229944 -289.713924)
		(width 0.0889)
		(layer "In2.Cu")
		(net "P5E_CPU1_PE4_TX_DP<2>")
	)
	(segment
		(start 56.81091 -397.565626)
		(end 56.732932 -397.995648)
		(width 0.14732)
		(layer "In2.Cu")
		(net "P5E_CPU1_PE4_TX_DP<2>")
	)
	(segment
		(start 56.71058 -397.420846)
		(end 56.81091 -397.565626)
		(width 0.14732)
		(layer "In2.Cu")
		(net "P5E_CPU1_PE4_TX_DP<2>")
	)
	(segment
		(start 56.206898 -400.195288)
		(end 56.206898 -405.231346)
		(width 0.14732)
		(layer "In2.Cu")
		(net "P5E_CPU1_PE4_TX_DP<2>")
	)
	(segment
		(start 60.30595 -325.773542)
		(end 60.10656 -326.14616)
		(width 0.14732)
		(layer "In2.Cu")
		(net "P5E_CPU1_PE4_TX_DP<2>")
	)
	(segment
		(start 90.272108 -291.20846)
		(end 86.788498 -294.692324)
		(width 0.14732)
		(layer "In2.Cu")
		(net "P5E_CPU1_PE4_TX_DP<2>")
	)
	(segment
		(start 92.014548 -286.475424)
		(end 91.858084 -286.204406)
		(width 0.0889)
		(layer "In2.Cu")
		(net "P5E_CPU1_PE4_TX_DP<2>")
	)
	(segment
		(start 90.887296 -287.778698)
		(end 90.88247 -287.781238)
		(width 0.0889)
		(layer "In2.Cu")
		(net "P5E_CPU1_PE4_TX_DP<2>")
	)
	(segment
		(start 56.206898 -405.231346)
		(end 56.021478 -405.416766)
		(width 0.14732)
		(layer "In2.Cu")
		(net "P5E_CPU1_PE4_TX_DP<2>")
	)
	(segment
		(start 60.10656 -326.14616)
		(end 60.084716 -338.308696)
		(width 0.14732)
		(layer "In2.Cu")
		(net "P5E_CPU1_PE4_TX_DP<2>")
	)
	(segment
		(start 56.788558 -396.991078)
		(end 56.71058 -397.420846)
		(width 0.14732)
		(layer "In2.Cu")
		(net "P5E_CPU1_PE4_TX_DP<2>")
	)
	(segment
		(start 90.699844 -288.103056)
		(end 90.699844 -288.125154)
		(width 0.0889)
		(layer "In2.Cu")
		(net "P5E_CPU1_PE4_TX_DP<2>")
	)
	(segment
		(start 91.363546 -286.961326)
		(end 91.35745 -286.964882)
		(width 0.0889)
		(layer "In2.Cu")
		(net "P5E_CPU1_PE4_TX_DP<2>")
	)
	(segment
		(start 90.888058 -287.77819)
		(end 90.887296 -287.778698)
		(width 0.0889)
		(layer "In2.Cu")
		(net "P5E_CPU1_PE4_TX_DP<2>")
	)
	(segment
		(start 90.88247 -287.781238)
		(end 90.878406 -287.783778)
		(width 0.0889)
		(layer "In2.Cu")
		(net "P5E_CPU1_PE4_TX_DP<2>")
	)
	(segment
		(start 91.35745 -286.964882)
		(end 91.34856 -286.969962)
		(width 0.0889)
		(layer "In2.Cu")
		(net "P5E_CPU1_PE4_TX_DP<2>")
	)
	(segment
		(start 78.883002 -309.879746)
		(end 67.649344 -321.113404)
		(width 0.14732)
		(layer "In2.Cu")
		(net "P5E_CPU1_PE4_TX_DP<2>")
	)
	(segment
		(start 56.588152 -398.095724)
		(end 56.206898 -400.195288)
		(width 0.14732)
		(layer "In2.Cu")
		(net "P5E_CPU1_PE4_TX_DP<2>")
	)
	(segment
		(start 61.034676 -373.601488)
		(end 56.91124 -396.3162)
		(width 0.14732)
		(layer "In2.Cu")
		(net "P5E_CPU1_PE4_TX_DP<2>")
	)
	(segment
		(start 61.157358 -363.304074)
		(end 61.034676 -373.601488)
		(width 0.14732)
		(layer "In2.Cu")
		(net "P5E_CPU1_PE4_TX_DP<2>")
	)
	(segment
		(start 90.272108 -289.756088)
		(end 90.272108 -289.778186)
		(width 0.0889)
		(layer "In2.Cu")
		(net "P5E_CPU1_PE4_TX_DP<2>")
	)
	(segment
		(start 90.417142 -288.593022)
		(end 90.416634 -288.593276)
		(width 0.0889)
		(layer "In2.Cu")
		(net "P5E_CPU1_PE4_TX_DP<2>")
	)
	(segment
		(start 61.228732 -325.280274)
		(end 61.228986 -325.280274)
		(width 0.14732)
		(layer "In2.Cu")
		(net "P5E_CPU1_PE4_TX_DP<2>")
	)
	(segment
		(start 90.893392 -287.775142)
		(end 90.888058 -287.77819)
		(width 0.0889)
		(layer "In2.Cu")
		(net "P5E_CPU1_PE4_TX_DP<2>")
	)
	(segment
		(start 57.01157 -396.460726)
		(end 56.933338 -396.891002)
		(width 0.14732)
		(layer "In2.Cu")
		(net "P5E_CPU1_PE4_TX_DP<2>")
	)
	(segment
		(start 86.788498 -294.692324)
		(end 78.883002 -309.879746)
		(width 0.14732)
		(layer "In2.Cu")
		(net "P5E_CPU1_PE4_TX_DP<2>")
	)
	(segment
		(start 62.152022 -324.786752)
		(end 61.228732 -325.280274)
		(width 0.14732)
		(layer "In2.Cu")
		(net "P5E_CPU1_PE4_TX_DP<2>")
	)
	(segment
		(start 90.229944 -289.713924)
		(end 90.272108 -289.756088)
		(width 0.0889)
		(layer "In2.Cu")
		(net "P5E_CPU1_PE4_TX_DP<2>")
	)
	(segment
		(start 61.228986 -325.280274)
		(end 60.30595 -325.773542)
		(width 0.14732)
		(layer "In2.Cu")
		(net "P5E_CPU1_PE4_TX_DP<2>")
	)
	(segment
		(start 90.272108 -289.778186)
		(end 90.272108 -291.20846)
		(width 0.14732)
		(layer "In2.Cu")
		(net "P5E_CPU1_PE4_TX_DP<2>")
	)
	(segment
		(start 56.91124 -396.3162)
		(end 57.01157 -396.460726)
		(width 0.14732)
		(layer "In2.Cu")
		(net "P5E_CPU1_PE4_TX_DP<2>")
	)
	(segment
		(start 56.021478 -405.416766)
		(end 56.021478 -406.70988)
		(width 0.14732)
		(layer "In2.Cu")
		(net "P5E_CPU1_PE4_TX_DP<2>")
	)
	(segment
		(start 60.084716 -338.308696)
		(end 61.157358 -363.304074)
		(width 0.14732)
		(layer "In2.Cu")
		(net "P5E_CPU1_PE4_TX_DP<2>")
	)
	(segment
		(start 56.021478 -406.70988)
		(end 56.316118 -407.00452)
		(width 0.14732)
		(layer "In2.Cu")
		(net "P5E_CPU1_PE4_TX_DP<2>")
	)
	(arc
		(start 91.779852 -286.183578)
		(mid 91.676707 -286.313603)
		(end 91.639898 -286.475424)
		(width 0.0889)
		(layer "In2.Cu")
		(net "P5E_CPU1_PE4_TX_DP<2>")
	)
	(arc
		(start 91.34856 -286.969962)
		(mid 91.217646 -287.106322)
		(end 91.169998 -287.28924)
		(width 0.0889)
		(layer "In2.Cu")
		(net "P5E_CPU1_PE4_TX_DP<2>")
	)
	(arc
		(start 91.169998 -287.28924)
		(mid 91.096007 -287.568806)
		(end 90.893392 -287.775142)
		(width 0.0889)
		(layer "In2.Cu")
		(net "P5E_CPU1_PE4_TX_DP<2>")
	)
	(arc
		(start 90.699844 -288.125154)
		(mid 90.618786 -288.395524)
		(end 90.417142 -288.593022)
		(width 0.0889)
		(layer "In2.Cu")
		(net "P5E_CPU1_PE4_TX_DP<2>")
	)
	(arc
		(start 90.416634 -288.593276)
		(mid 90.279926 -288.730211)
		(end 90.229944 -288.917126)
		(width 0.0889)
		(layer "In2.Cu")
		(net "P5E_CPU1_PE4_TX_DP<2>")
	)
	(arc
		(start 91.639898 -286.475424)
		(mid 91.565982 -286.754926)
		(end 91.363546 -286.961326)
		(width 0.0889)
		(layer "In2.Cu")
		(net "P5E_CPU1_PE4_TX_DP<2>")
	)
	(arc
		(start 90.878406 -287.783778)
		(mid 90.747492 -287.920138)
		(end 90.699844 -288.103056)
		(width 0.0889)
		(layer "In2.Cu")
		(net "P5E_CPU1_PE4_TX_DP<2>")
	)
	(segment
		(start 52.363878 -408.250644)
		(end 52.36845 -408.250644)
		(width 0.13208)
		(layer "F.Cu")
		(net "P5E_CPU1_PE4_TX_DP<1>")
	)
	(segment
		(start 52.36845 -408.250644)
		(end 52.69484 -407.924254)
		(width 0.13208)
		(layer "F.Cu")
		(net "P5E_CPU1_PE4_TX_DP<1>")
	)
	(segment
		(start 90.604848 -285.125414)
		(end 90.604848 -285.661354)
		(width 0.13208)
		(layer "F.Cu")
		(net "P5E_CPU1_PE4_TX_DP<1>")
	)
	(segment
		(start 52.69484 -407.924254)
		(end 52.69484 -407.310082)
		(width 0.13208)
		(layer "F.Cu")
		(net "P5E_CPU1_PE4_TX_DP<1>")
	)
	(segment
		(start 52.69484 -407.310082)
		(end 52.389278 -407.00452)
		(width 0.13208)
		(layer "F.Cu")
		(net "P5E_CPU1_PE4_TX_DP<1>")
	)
	(segment
		(start 77.732128 -309.317898)
		(end 66.876422 -320.173858)
		(width 0.14732)
		(layer "In2.Cu")
		(net "P5E_CPU1_PE4_TX_DP<1>")
	)
	(segment
		(start 89.390982 -288.422334)
		(end 89.382092 -288.427414)
		(width 0.0889)
		(layer "In2.Cu")
		(net "P5E_CPU1_PE4_TX_DP<1>")
	)
	(segment
		(start 60.000642 -324.451726)
		(end 59.212734 -325.09841)
		(width 0.14732)
		(layer "In2.Cu")
		(net "P5E_CPU1_PE4_TX_DP<1>")
	)
	(segment
		(start 53.555138 -396.643606)
		(end 53.45684 -397.069564)
		(width 0.14732)
		(layer "In2.Cu")
		(net "P5E_CPU1_PE4_TX_DP<1>")
	)
	(segment
		(start 77.732636 -309.31739)
		(end 77.732128 -309.317898)
		(width 0.14732)
		(layer "In2.Cu")
		(net "P5E_CPU1_PE4_TX_DP<1>")
	)
	(segment
		(start 90.761312 -285.390336)
		(end 90.839544 -285.369508)
		(width 0.0889)
		(layer "In2.Cu")
		(net "P5E_CPU1_PE4_TX_DP<1>")
	)
	(segment
		(start 89.852754 -287.61309)
		(end 89.851992 -287.613598)
		(width 0.0889)
		(layer "In2.Cu")
		(net "P5E_CPU1_PE4_TX_DP<1>")
	)
	(segment
		(start 58.966608 -373.580914)
		(end 58.966608 -373.581422)
		(width 0.14732)
		(layer "In2.Cu")
		(net "P5E_CPU1_PE4_TX_DP<1>")
	)
	(segment
		(start 53.704744 -396.549372)
		(end 53.704744 -396.550388)
		(width 0.14732)
		(layer "In2.Cu")
		(net "P5E_CPU1_PE4_TX_DP<1>")
	)
	(segment
		(start 89.05748 -290.688522)
		(end 85.66531 -294.080438)
		(width 0.14732)
		(layer "In2.Cu")
		(net "P5E_CPU1_PE4_TX_DP<1>")
	)
	(segment
		(start 53.550058 -397.218916)
		(end 53.45176 -397.644366)
		(width 0.14732)
		(layer "In2.Cu")
		(net "P5E_CPU1_PE4_TX_DP<1>")
	)
	(segment
		(start 58.966862 -373.582438)
		(end 58.905394 -374.048274)
		(width 0.14732)
		(layer "In2.Cu")
		(net "P5E_CPU1_PE4_TX_DP<1>")
	)
	(segment
		(start 58.88101 -338.44611)
		(end 58.878978 -338.449412)
		(width 0.14732)
		(layer "In2.Cu")
		(net "P5E_CPU1_PE4_TX_DP<1>")
	)
	(segment
		(start 90.604848 -285.661354)
		(end 90.761312 -285.390336)
		(width 0.0889)
		(layer "In2.Cu")
		(net "P5E_CPU1_PE4_TX_DP<1>")
	)
	(segment
		(start 52.869338 -400.163792)
		(end 52.869338 -405.117554)
		(width 0.14732)
		(layer "In2.Cu")
		(net "P5E_CPU1_PE4_TX_DP<1>")
	)
	(segment
		(start 89.05748 -289.798506)
		(end 89.05748 -290.688522)
		(width 0.14732)
		(layer "In2.Cu")
		(net "P5E_CPU1_PE4_TX_DP<1>")
	)
	(segment
		(start 61.60516 -323.696838)
		(end 60.858908 -324.095872)
		(width 0.14732)
		(layer "In2.Cu")
		(net "P5E_CPU1_PE4_TX_DP<1>")
	)
	(segment
		(start 53.704744 -396.550388)
		(end 53.555138 -396.643606)
		(width 0.14732)
		(layer "In2.Cu")
		(net "P5E_CPU1_PE4_TX_DP<1>")
	)
	(segment
		(start 89.09939 -289.734498)
		(end 89.05748 -289.776408)
		(width 0.0889)
		(layer "In2.Cu")
		(net "P5E_CPU1_PE4_TX_DP<1>")
	)
	(segment
		(start 89.860882 -287.608518)
		(end 89.852754 -287.61309)
		(width 0.0889)
		(layer "In2.Cu")
		(net "P5E_CPU1_PE4_TX_DP<1>")
	)
	(segment
		(start 53.45176 -397.644366)
		(end 53.302154 -397.737584)
		(width 0.14732)
		(layer "In2.Cu")
		(net "P5E_CPU1_PE4_TX_DP<1>")
	)
	(segment
		(start 60.858908 -324.095872)
		(end 60.000642 -324.451726)
		(width 0.14732)
		(layer "In2.Cu")
		(net "P5E_CPU1_PE4_TX_DP<1>")
	)
	(segment
		(start 89.05748 -289.776408)
		(end 89.05748 -289.798506)
		(width 0.0889)
		(layer "In2.Cu")
		(net "P5E_CPU1_PE4_TX_DP<1>")
	)
	(segment
		(start 58.878978 -338.449412)
		(end 59.50585 -362.023406)
		(width 0.14732)
		(layer "In2.Cu")
		(net "P5E_CPU1_PE4_TX_DP<1>")
	)
	(segment
		(start 53.297074 -398.312894)
		(end 52.869338 -400.163792)
		(width 0.14732)
		(layer "In2.Cu")
		(net "P5E_CPU1_PE4_TX_DP<1>")
	)
	(segment
		(start 53.302154 -397.737584)
		(end 53.203856 -398.163542)
		(width 0.14732)
		(layer "In2.Cu")
		(net "P5E_CPU1_PE4_TX_DP<1>")
	)
	(segment
		(start 90.330782 -286.794702)
		(end 90.317066 -286.802576)
		(width 0.0889)
		(layer "In2.Cu")
		(net "P5E_CPU1_PE4_TX_DP<1>")
	)
	(segment
		(start 89.569544 -288.09315)
		(end 89.569544 -288.103056)
		(width 0.0889)
		(layer "In2.Cu")
		(net "P5E_CPU1_PE4_TX_DP<1>")
	)
	(segment
		(start 89.09939 -288.902902)
		(end 89.09939 -289.734498)
		(width 0.0889)
		(layer "In2.Cu")
		(net "P5E_CPU1_PE4_TX_DP<1>")
	)
	(segment
		(start 58.987436 -325.574914)
		(end 58.79973 -326.469502)
		(width 0.14732)
		(layer "In2.Cu")
		(net "P5E_CPU1_PE4_TX_DP<1>")
	)
	(segment
		(start 58.966862 -373.581676)
		(end 58.966862 -373.582438)
		(width 0.14732)
		(layer "In2.Cu")
		(net "P5E_CPU1_PE4_TX_DP<1>")
	)
	(segment
		(start 66.876422 -320.173858)
		(end 61.60516 -323.696838)
		(width 0.14732)
		(layer "In2.Cu")
		(net "P5E_CPU1_PE4_TX_DP<1>")
	)
	(segment
		(start 90.317066 -286.802576)
		(end 90.315796 -286.803338)
		(width 0.0889)
		(layer "In2.Cu")
		(net "P5E_CPU1_PE4_TX_DP<1>")
	)
	(segment
		(start 58.878724 -338.444078)
		(end 58.88101 -338.44611)
		(width 0.14732)
		(layer "In2.Cu")
		(net "P5E_CPU1_PE4_TX_DP<1>")
	)
	(segment
		(start 85.66531 -294.080438)
		(end 77.732636 -309.31739)
		(width 0.14732)
		(layer "In2.Cu")
		(net "P5E_CPU1_PE4_TX_DP<1>")
	)
	(segment
		(start 52.683918 -405.302974)
		(end 52.683918 -406.70988)
		(width 0.14732)
		(layer "In2.Cu")
		(net "P5E_CPU1_PE4_TX_DP<1>")
	)
	(segment
		(start 52.869338 -405.117554)
		(end 52.683918 -405.302974)
		(width 0.14732)
		(layer "In2.Cu")
		(net "P5E_CPU1_PE4_TX_DP<1>")
	)
	(segment
		(start 59.212734 -325.09841)
		(end 58.987436 -325.574914)
		(width 0.14732)
		(layer "In2.Cu")
		(net "P5E_CPU1_PE4_TX_DP<1>")
	)
	(segment
		(start 58.966608 -373.581422)
		(end 58.966862 -373.581676)
		(width 0.14732)
		(layer "In2.Cu")
		(net "P5E_CPU1_PE4_TX_DP<1>")
	)
	(segment
		(start 53.45684 -397.069564)
		(end 53.550058 -397.218916)
		(width 0.14732)
		(layer "In2.Cu")
		(net "P5E_CPU1_PE4_TX_DP<1>")
	)
	(segment
		(start 58.966862 -373.58066)
		(end 58.966608 -373.580914)
		(width 0.14732)
		(layer "In2.Cu")
		(net "P5E_CPU1_PE4_TX_DP<1>")
	)
	(segment
		(start 52.683918 -406.70988)
		(end 52.389278 -407.00452)
		(width 0.14732)
		(layer "In2.Cu")
		(net "P5E_CPU1_PE4_TX_DP<1>")
	)
	(segment
		(start 53.203856 -398.163542)
		(end 53.297074 -398.312894)
		(width 0.14732)
		(layer "In2.Cu")
		(net "P5E_CPU1_PE4_TX_DP<1>")
	)
	(segment
		(start 58.79973 -326.469502)
		(end 58.878724 -338.444078)
		(width 0.14732)
		(layer "In2.Cu")
		(net "P5E_CPU1_PE4_TX_DP<1>")
	)
	(segment
		(start 90.800936 -285.980632)
		(end 90.792046 -285.985712)
		(width 0.0889)
		(layer "In2.Cu")
		(net "P5E_CPU1_PE4_TX_DP<1>")
	)
	(segment
		(start 58.905394 -374.048274)
		(end 53.704744 -396.549372)
		(width 0.14732)
		(layer "In2.Cu")
		(net "P5E_CPU1_PE4_TX_DP<1>")
	)
	(segment
		(start 90.509344 -286.4612)
		(end 90.509344 -286.475424)
		(width 0.0889)
		(layer "In2.Cu")
		(net "P5E_CPU1_PE4_TX_DP<1>")
	)
	(segment
		(start 59.50585 -362.023406)
		(end 58.966862 -373.58066)
		(width 0.14732)
		(layer "In2.Cu")
		(net "P5E_CPU1_PE4_TX_DP<1>")
	)
	(arc
		(start 90.839544 -285.369508)
		(mid 90.978607 -285.685029)
		(end 90.800936 -285.980632)
		(width 0.0889)
		(layer "In2.Cu")
		(net "P5E_CPU1_PE4_TX_DP<1>")
	)
	(arc
		(start 90.509344 -286.475424)
		(mid 90.461665 -286.658324)
		(end 90.330782 -286.794702)
		(width 0.0889)
		(layer "In2.Cu")
		(net "P5E_CPU1_PE4_TX_DP<1>")
	)
	(arc
		(start 90.315796 -286.803338)
		(mid 90.113383 -287.009751)
		(end 90.039444 -287.28924)
		(width 0.0889)
		(layer "In2.Cu")
		(net "P5E_CPU1_PE4_TX_DP<1>")
	)
	(arc
		(start 90.792046 -285.985712)
		(mid 90.588565 -286.186516)
		(end 90.509344 -286.4612)
		(width 0.0889)
		(layer "In2.Cu")
		(net "P5E_CPU1_PE4_TX_DP<1>")
	)
	(arc
		(start 90.039444 -287.28924)
		(mid 89.991765 -287.47214)
		(end 89.860882 -287.608518)
		(width 0.0889)
		(layer "In2.Cu")
		(net "P5E_CPU1_PE4_TX_DP<1>")
	)
	(arc
		(start 89.382092 -288.427414)
		(mid 89.178611 -288.628218)
		(end 89.09939 -288.902902)
		(width 0.0889)
		(layer "In2.Cu")
		(net "P5E_CPU1_PE4_TX_DP<1>")
	)
	(arc
		(start 89.851992 -287.613598)
		(mid 89.647657 -287.816203)
		(end 89.569544 -288.09315)
		(width 0.0889)
		(layer "In2.Cu")
		(net "P5E_CPU1_PE4_TX_DP<1>")
	)
	(arc
		(start 89.569544 -288.103056)
		(mid 89.521865 -288.285956)
		(end 89.390982 -288.422334)
		(width 0.0889)
		(layer "In2.Cu")
		(net "P5E_CPU1_PE4_TX_DP<1>")
	)
	(segment
		(start 95.83928 -407.303478)
		(end 96.138238 -407.00452)
		(width 0.13208)
		(layer "F.Cu")
		(net "P5E_CPU1_PE4_TX_DP<15>")
	)
	(segment
		(start 104.231694 -284.847284)
		(end 104.231948 -284.847538)
		(width 0.13208)
		(layer "F.Cu")
		(net "P5E_CPU1_PE4_TX_DP<15>")
	)
	(segment
		(start 95.83928 -407.926286)
		(end 95.83928 -407.303478)
		(width 0.13208)
		(layer "F.Cu")
		(net "P5E_CPU1_PE4_TX_DP<15>")
	)
	(segment
		(start 104.231694 -284.311598)
		(end 104.231694 -284.847284)
		(width 0.13208)
		(layer "F.Cu")
		(net "P5E_CPU1_PE4_TX_DP<15>")
	)
	(segment
		(start 96.163638 -408.250644)
		(end 95.83928 -407.926286)
		(width 0.13208)
		(layer "F.Cu")
		(net "P5E_CPU1_PE4_TX_DP<15>")
	)
	(segment
		(start 104.099614 -285.20771)
		(end 104.075484 -285.118556)
		(width 0.0889)
		(layer "In2.Cu")
		(net "P5E_CPU1_PE4_TX_DP<15>")
	)
	(segment
		(start 96.029018 -405.231346)
		(end 96.029018 -399.79981)
		(width 0.14732)
		(layer "In2.Cu")
		(net "P5E_CPU1_PE4_TX_DP<15>")
	)
	(segment
		(start 102.917498 -288.121598)
		(end 102.917498 -288.103056)
		(width 0.0889)
		(layer "In2.Cu")
		(net "P5E_CPU1_PE4_TX_DP<15>")
	)
	(segment
		(start 96.138238 -407.00452)
		(end 95.843598 -406.70988)
		(width 0.14732)
		(layer "In2.Cu")
		(net "P5E_CPU1_PE4_TX_DP<15>")
	)
	(segment
		(start 74.347832 -350.03232)
		(end 73.595738 -336.177382)
		(width 0.14732)
		(layer "In2.Cu")
		(net "P5E_CPU1_PE4_TX_DP<15>")
	)
	(segment
		(start 100.433632 -305.566318)
		(end 102.47757 -301.634144)
		(width 0.14732)
		(layer "In2.Cu")
		(net "P5E_CPU1_PE4_TX_DP<15>")
	)
	(segment
		(start 95.843598 -406.70988)
		(end 95.843598 -405.416766)
		(width 0.14732)
		(layer "In2.Cu")
		(net "P5E_CPU1_PE4_TX_DP<15>")
	)
	(segment
		(start 104.326944 -285.679896)
		(end 104.326944 -285.64586)
		(width 0.0889)
		(layer "In2.Cu")
		(net "P5E_CPU1_PE4_TX_DP<15>")
	)
	(segment
		(start 103.133652 -290.611052)
		(end 103.091488 -290.568888)
		(width 0.0889)
		(layer "In2.Cu")
		(net "P5E_CPU1_PE4_TX_DP<15>")
	)
	(segment
		(start 103.387144 -287.304734)
		(end 103.387144 -287.28924)
		(width 0.0889)
		(layer "In2.Cu")
		(net "P5E_CPU1_PE4_TX_DP<15>")
	)
	(segment
		(start 103.091488 -290.568888)
		(end 103.091488 -290.31057)
		(width 0.0889)
		(layer "In2.Cu")
		(net "P5E_CPU1_PE4_TX_DP<15>")
	)
	(segment
		(start 102.91699 -290.136072)
		(end 102.91699 -289.65906)
		(width 0.0889)
		(layer "In2.Cu")
		(net "P5E_CPU1_PE4_TX_DP<15>")
	)
	(segment
		(start 103.565706 -286.969962)
		(end 103.5685 -286.968438)
		(width 0.0889)
		(layer "In2.Cu")
		(net "P5E_CPU1_PE4_TX_DP<15>")
	)
	(segment
		(start 102.62616 -288.597848)
		(end 102.63505 -288.592768)
		(width 0.0889)
		(layer "In2.Cu")
		(net "P5E_CPU1_PE4_TX_DP<15>")
	)
	(segment
		(start 73.595738 -336.177382)
		(end 76.264008 -329.735688)
		(width 0.14732)
		(layer "In2.Cu")
		(net "P5E_CPU1_PE4_TX_DP<15>")
	)
	(segment
		(start 103.133652 -297.912536)
		(end 103.133652 -290.63315)
		(width 0.14732)
		(layer "In2.Cu")
		(net "P5E_CPU1_PE4_TX_DP<15>")
	)
	(segment
		(start 103.09606 -287.783778)
		(end 103.10495 -287.778698)
		(width 0.0889)
		(layer "In2.Cu")
		(net "P5E_CPU1_PE4_TX_DP<15>")
	)
	(segment
		(start 103.569262 -286.96793)
		(end 103.580692 -286.961326)
		(width 0.0889)
		(layer "In2.Cu")
		(net "P5E_CPU1_PE4_TX_DP<15>")
	)
	(segment
		(start 95.850202 -399.382742)
		(end 95.194374 -397.853662)
		(width 0.14732)
		(layer "In2.Cu")
		(net "P5E_CPU1_PE4_TX_DP<15>")
	)
	(segment
		(start 102.447598 -289.078416)
		(end 102.447598 -288.917126)
		(width 0.0889)
		(layer "In2.Cu")
		(net "P5E_CPU1_PE4_TX_DP<15>")
	)
	(segment
		(start 104.075484 -285.118556)
		(end 104.231948 -284.847538)
		(width 0.0889)
		(layer "In2.Cu")
		(net "P5E_CPU1_PE4_TX_DP<15>")
	)
	(segment
		(start 95.843598 -405.416766)
		(end 96.029018 -405.231346)
		(width 0.14732)
		(layer "In2.Cu")
		(net "P5E_CPU1_PE4_TX_DP<15>")
	)
	(segment
		(start 95.194628 -397.853408)
		(end 74.347832 -350.03232)
		(width 0.14732)
		(layer "In2.Cu")
		(net "P5E_CPU1_PE4_TX_DP<15>")
	)
	(segment
		(start 103.857298 -286.475424)
		(end 103.857298 -286.466788)
		(width 0.0889)
		(layer "In2.Cu")
		(net "P5E_CPU1_PE4_TX_DP<15>")
	)
	(segment
		(start 76.264008 -329.735688)
		(end 100.433632 -305.566318)
		(width 0.14732)
		(layer "In2.Cu")
		(net "P5E_CPU1_PE4_TX_DP<15>")
	)
	(segment
		(start 103.091488 -290.31057)
		(end 102.91699 -290.136072)
		(width 0.0889)
		(layer "In2.Cu")
		(net "P5E_CPU1_PE4_TX_DP<15>")
	)
	(segment
		(start 96.029018 -399.79981)
		(end 95.850456 -399.38325)
		(width 0.14732)
		(layer "In2.Cu")
		(net "P5E_CPU1_PE4_TX_DP<15>")
	)
	(segment
		(start 95.850456 -399.38325)
		(end 95.850202 -399.382742)
		(width 0.14732)
		(layer "In2.Cu")
		(net "P5E_CPU1_PE4_TX_DP<15>")
	)
	(segment
		(start 103.133652 -290.63315)
		(end 103.133652 -290.611052)
		(width 0.0889)
		(layer "In2.Cu")
		(net "P5E_CPU1_PE4_TX_DP<15>")
	)
	(segment
		(start 102.47757 -301.634144)
		(end 103.133652 -297.912536)
		(width 0.14732)
		(layer "In2.Cu")
		(net "P5E_CPU1_PE4_TX_DP<15>")
	)
	(segment
		(start 95.194374 -397.853662)
		(end 95.194628 -397.853408)
		(width 0.14732)
		(layer "In2.Cu")
		(net "P5E_CPU1_PE4_TX_DP<15>")
	)
	(segment
		(start 103.5685 -286.968438)
		(end 103.569262 -286.96793)
		(width 0.0889)
		(layer "In2.Cu")
		(net "P5E_CPU1_PE4_TX_DP<15>")
	)
	(arc
		(start 103.580692 -286.961326)
		(mid 103.783279 -286.754975)
		(end 103.857298 -286.475424)
		(width 0.0889)
		(layer "In2.Cu")
		(net "P5E_CPU1_PE4_TX_DP<15>")
	)
	(arc
		(start 103.857298 -286.466788)
		(mid 103.909568 -286.284423)
		(end 104.044496 -286.151066)
		(width 0.0889)
		(layer "In2.Cu")
		(net "P5E_CPU1_PE4_TX_DP<15>")
	)
	(arc
		(start 104.116378 -285.220664)
		(mid 104.108058 -285.214107)
		(end 104.099614 -285.20771)
		(width 0.0889)
		(layer "In2.Cu")
		(net "P5E_CPU1_PE4_TX_DP<15>")
	)
	(arc
		(start 102.447598 -288.917126)
		(mid 102.495277 -288.734226)
		(end 102.62616 -288.597848)
		(width 0.0889)
		(layer "In2.Cu")
		(net "P5E_CPU1_PE4_TX_DP<15>")
	)
	(arc
		(start 104.044496 -286.151066)
		(mid 104.246782 -285.952085)
		(end 104.326944 -285.679896)
		(width 0.0889)
		(layer "In2.Cu")
		(net "P5E_CPU1_PE4_TX_DP<15>")
	)
	(arc
		(start 102.63505 -288.592768)
		(mid 102.837336 -288.393787)
		(end 102.917498 -288.121598)
		(width 0.0889)
		(layer "In2.Cu")
		(net "P5E_CPU1_PE4_TX_DP<15>")
	)
	(arc
		(start 102.917498 -288.103056)
		(mid 102.965177 -287.920156)
		(end 103.09606 -287.783778)
		(width 0.0889)
		(layer "In2.Cu")
		(net "P5E_CPU1_PE4_TX_DP<15>")
	)
	(arc
		(start 103.387144 -287.28924)
		(mid 103.434823 -287.10634)
		(end 103.565706 -286.969962)
		(width 0.0889)
		(layer "In2.Cu")
		(net "P5E_CPU1_PE4_TX_DP<15>")
	)
	(arc
		(start 104.326944 -285.64586)
		(mid 104.268391 -285.41013)
		(end 104.116378 -285.220664)
		(width 0.0889)
		(layer "In2.Cu")
		(net "P5E_CPU1_PE4_TX_DP<15>")
	)
	(arc
		(start 103.10495 -287.778698)
		(mid 103.307773 -287.578467)
		(end 103.387144 -287.304734)
		(width 0.0889)
		(layer "In2.Cu")
		(net "P5E_CPU1_PE4_TX_DP<15>")
	)
	(arc
		(start 102.91699 -289.65906)
		(mid 102.911378 -289.605092)
		(end 102.89413 -289.55365)
		(width 0.0889)
		(layer "In2.Cu")
		(net "P5E_CPU1_PE4_TX_DP<15>")
	)
	(arc
		(start 102.631748 -289.277806)
		(mid 102.522601 -289.193878)
		(end 102.447598 -289.078416)
		(width 0.0889)
		(layer "In2.Cu")
		(net "P5E_CPU1_PE4_TX_DP<15>")
	)
	(arc
		(start 102.89413 -289.55365)
		(mid 102.785438 -289.394334)
		(end 102.631748 -289.277806)
		(width 0.0889)
		(layer "In2.Cu")
		(net "P5E_CPU1_PE4_TX_DP<15>")
	)
	(segment
		(start 103.291894 -286.47517)
		(end 103.292148 -286.475424)
		(width 0.13208)
		(layer "F.Cu")
		(net "P5E_CPU1_PE4_TX_DP<14>")
	)
	(segment
		(start 92.77604 -407.926286)
		(end 92.77604 -407.303478)
		(width 0.13208)
		(layer "F.Cu")
		(net "P5E_CPU1_PE4_TX_DP<14>")
	)
	(segment
		(start 93.100398 -408.250644)
		(end 92.77604 -407.926286)
		(width 0.13208)
		(layer "F.Cu")
		(net "P5E_CPU1_PE4_TX_DP<14>")
	)
	(segment
		(start 103.291894 -285.939484)
		(end 103.291894 -286.47517)
		(width 0.13208)
		(layer "F.Cu")
		(net "P5E_CPU1_PE4_TX_DP<14>")
	)
	(segment
		(start 92.77604 -407.303478)
		(end 93.074998 -407.00452)
		(width 0.13208)
		(layer "F.Cu")
		(net "P5E_CPU1_PE4_TX_DP<14>")
	)
	(segment
		(start 102.1588 -290.995862)
		(end 102.200964 -291.038026)
		(width 0.0889)
		(layer "In2.Cu")
		(net "P5E_CPU1_PE4_TX_DP<14>")
	)
	(segment
		(start 101.977698 -288.103056)
		(end 101.977698 -288.121598)
		(width 0.0889)
		(layer "In2.Cu")
		(net "P5E_CPU1_PE4_TX_DP<14>")
	)
	(segment
		(start 99.669092 -305.015646)
		(end 75.304904 -329.379834)
		(width 0.14732)
		(layer "In2.Cu")
		(net "P5E_CPU1_PE4_TX_DP<14>")
	)
	(segment
		(start 92.780358 -406.70988)
		(end 93.074998 -407.00452)
		(width 0.14732)
		(layer "In2.Cu")
		(net "P5E_CPU1_PE4_TX_DP<14>")
	)
	(segment
		(start 101.691948 -289.277806)
		(end 101.692456 -289.27806)
		(width 0.0889)
		(layer "In2.Cu")
		(net "P5E_CPU1_PE4_TX_DP<14>")
	)
	(segment
		(start 102.200964 -291.060124)
		(end 102.200964 -297.345862)
		(width 0.14732)
		(layer "In2.Cu")
		(net "P5E_CPU1_PE4_TX_DP<14>")
	)
	(segment
		(start 101.507798 -288.917126)
		(end 101.507798 -289.078416)
		(width 0.0889)
		(layer "In2.Cu")
		(net "P5E_CPU1_PE4_TX_DP<14>")
	)
	(segment
		(start 72.637396 -335.81975)
		(end 72.60209 -336.078576)
		(width 0.14732)
		(layer "In2.Cu")
		(net "P5E_CPU1_PE4_TX_DP<14>")
	)
	(segment
		(start 102.16515 -287.778698)
		(end 102.15626 -287.783778)
		(width 0.0889)
		(layer "In2.Cu")
		(net "P5E_CPU1_PE4_TX_DP<14>")
	)
	(segment
		(start 75.304904 -329.379834)
		(end 72.637396 -335.81975)
		(width 0.14732)
		(layer "In2.Cu")
		(net "P5E_CPU1_PE4_TX_DP<14>")
	)
	(segment
		(start 92.09532 -397.210788)
		(end 92.023692 -397.37157)
		(width 0.14732)
		(layer "In2.Cu")
		(net "P5E_CPU1_PE4_TX_DP<14>")
	)
	(segment
		(start 92.965778 -405.231346)
		(end 92.780358 -405.416766)
		(width 0.14732)
		(layer "In2.Cu")
		(net "P5E_CPU1_PE4_TX_DP<14>")
	)
	(segment
		(start 102.447344 -287.28924)
		(end 102.447344 -287.304734)
		(width 0.0889)
		(layer "In2.Cu")
		(net "P5E_CPU1_PE4_TX_DP<14>")
	)
	(segment
		(start 101.452426 -301.589948)
		(end 99.669092 -305.015646)
		(width 0.14732)
		(layer "In2.Cu")
		(net "P5E_CPU1_PE4_TX_DP<14>")
	)
	(segment
		(start 102.646988 -286.95777)
		(end 102.637082 -286.963358)
		(width 0.0889)
		(layer "In2.Cu")
		(net "P5E_CPU1_PE4_TX_DP<14>")
	)
	(segment
		(start 92.497402 -398.259046)
		(end 92.425774 -398.419828)
		(width 0.14732)
		(layer "In2.Cu")
		(net "P5E_CPU1_PE4_TX_DP<14>")
	)
	(segment
		(start 92.780358 -405.416766)
		(end 92.780358 -406.70988)
		(width 0.14732)
		(layer "In2.Cu")
		(net "P5E_CPU1_PE4_TX_DP<14>")
	)
	(segment
		(start 103.135684 -286.204406)
		(end 103.057452 -286.183578)
		(width 0.0889)
		(layer "In2.Cu")
		(net "P5E_CPU1_PE4_TX_DP<14>")
	)
	(segment
		(start 92.179902 -397.77924)
		(end 92.340938 -397.850868)
		(width 0.14732)
		(layer "In2.Cu")
		(net "P5E_CPU1_PE4_TX_DP<14>")
	)
	(segment
		(start 91.778074 -396.730728)
		(end 91.778074 -396.730982)
		(width 0.14732)
		(layer "In2.Cu")
		(net "P5E_CPU1_PE4_TX_DP<14>")
	)
	(segment
		(start 102.1588 -290.583112)
		(end 102.1588 -290.995862)
		(width 0.0889)
		(layer "In2.Cu")
		(net "P5E_CPU1_PE4_TX_DP<14>")
	)
	(segment
		(start 82.869278 -373.497856)
		(end 91.778074 -396.730728)
		(width 0.14732)
		(layer "In2.Cu")
		(net "P5E_CPU1_PE4_TX_DP<14>")
	)
	(segment
		(start 102.637082 -286.963358)
		(end 102.625906 -286.969962)
		(width 0.0889)
		(layer "In2.Cu")
		(net "P5E_CPU1_PE4_TX_DP<14>")
	)
	(segment
		(start 92.965778 -399.828258)
		(end 92.965778 -405.231346)
		(width 0.14732)
		(layer "In2.Cu")
		(net "P5E_CPU1_PE4_TX_DP<14>")
	)
	(segment
		(start 92.425774 -398.419828)
		(end 92.965778 -399.828258)
		(width 0.14732)
		(layer "In2.Cu")
		(net "P5E_CPU1_PE4_TX_DP<14>")
	)
	(segment
		(start 102.200964 -291.038026)
		(end 102.200964 -291.060124)
		(width 0.0889)
		(layer "In2.Cu")
		(net "P5E_CPU1_PE4_TX_DP<14>")
	)
	(segment
		(start 101.69525 -288.592768)
		(end 101.68636 -288.597848)
		(width 0.0889)
		(layer "In2.Cu")
		(net "P5E_CPU1_PE4_TX_DP<14>")
	)
	(segment
		(start 101.977444 -289.60953)
		(end 101.977444 -290.295076)
		(width 0.0889)
		(layer "In2.Cu")
		(net "P5E_CPU1_PE4_TX_DP<14>")
	)
	(segment
		(start 101.977444 -290.295076)
		(end 102.1588 -290.583112)
		(width 0.0889)
		(layer "In2.Cu")
		(net "P5E_CPU1_PE4_TX_DP<14>")
	)
	(segment
		(start 92.340938 -397.850868)
		(end 92.497402 -398.259046)
		(width 0.14732)
		(layer "In2.Cu")
		(net "P5E_CPU1_PE4_TX_DP<14>")
	)
	(segment
		(start 91.938856 -396.80261)
		(end 92.09532 -397.210788)
		(width 0.14732)
		(layer "In2.Cu")
		(net "P5E_CPU1_PE4_TX_DP<14>")
	)
	(segment
		(start 73.295002 -350.062546)
		(end 82.869278 -373.497856)
		(width 0.14732)
		(layer "In2.Cu")
		(net "P5E_CPU1_PE4_TX_DP<14>")
	)
	(segment
		(start 102.200964 -297.345862)
		(end 101.452426 -301.589948)
		(width 0.14732)
		(layer "In2.Cu")
		(net "P5E_CPU1_PE4_TX_DP<14>")
	)
	(segment
		(start 91.778074 -396.730982)
		(end 91.938856 -396.80261)
		(width 0.14732)
		(layer "In2.Cu")
		(net "P5E_CPU1_PE4_TX_DP<14>")
	)
	(segment
		(start 72.60209 -336.078576)
		(end 73.295002 -350.062546)
		(width 0.14732)
		(layer "In2.Cu")
		(net "P5E_CPU1_PE4_TX_DP<14>")
	)
	(segment
		(start 103.292148 -286.475424)
		(end 103.135684 -286.204406)
		(width 0.0889)
		(layer "In2.Cu")
		(net "P5E_CPU1_PE4_TX_DP<14>")
	)
	(segment
		(start 92.023692 -397.37157)
		(end 92.179902 -397.77924)
		(width 0.14732)
		(layer "In2.Cu")
		(net "P5E_CPU1_PE4_TX_DP<14>")
	)
	(arc
		(start 101.68636 -288.597848)
		(mid 101.555446 -288.734208)
		(end 101.507798 -288.917126)
		(width 0.0889)
		(layer "In2.Cu")
		(net "P5E_CPU1_PE4_TX_DP<14>")
	)
	(arc
		(start 102.917498 -286.475424)
		(mid 102.845263 -286.751948)
		(end 102.646988 -286.95777)
		(width 0.0889)
		(layer "In2.Cu")
		(net "P5E_CPU1_PE4_TX_DP<14>")
	)
	(arc
		(start 101.507798 -289.078416)
		(mid 101.582803 -289.193875)
		(end 101.691948 -289.277806)
		(width 0.0889)
		(layer "In2.Cu")
		(net "P5E_CPU1_PE4_TX_DP<14>")
	)
	(arc
		(start 101.692456 -289.27806)
		(mid 101.866275 -289.41686)
		(end 101.977444 -289.60953)
		(width 0.0889)
		(layer "In2.Cu")
		(net "P5E_CPU1_PE4_TX_DP<14>")
	)
	(arc
		(start 103.057452 -286.183578)
		(mid 102.954307 -286.313603)
		(end 102.917498 -286.475424)
		(width 0.0889)
		(layer "In2.Cu")
		(net "P5E_CPU1_PE4_TX_DP<14>")
	)
	(arc
		(start 102.447344 -287.304734)
		(mid 102.367974 -287.578468)
		(end 102.16515 -287.778698)
		(width 0.0889)
		(layer "In2.Cu")
		(net "P5E_CPU1_PE4_TX_DP<14>")
	)
	(arc
		(start 102.625906 -286.969962)
		(mid 102.494992 -287.106322)
		(end 102.447344 -287.28924)
		(width 0.0889)
		(layer "In2.Cu")
		(net "P5E_CPU1_PE4_TX_DP<14>")
	)
	(arc
		(start 102.15626 -287.783778)
		(mid 102.025346 -287.920138)
		(end 101.977698 -288.103056)
		(width 0.0889)
		(layer "In2.Cu")
		(net "P5E_CPU1_PE4_TX_DP<14>")
	)
	(arc
		(start 101.977698 -288.121598)
		(mid 101.897536 -288.393787)
		(end 101.69525 -288.592768)
		(width 0.0889)
		(layer "In2.Cu")
		(net "P5E_CPU1_PE4_TX_DP<14>")
	)
	(segment
		(start 89.7128 -407.926286)
		(end 89.7128 -407.303478)
		(width 0.13208)
		(layer "F.Cu")
		(net "P5E_CPU1_PE4_TX_DP<13>")
	)
	(segment
		(start 102.352094 -284.311598)
		(end 102.352094 -284.847284)
		(width 0.13208)
		(layer "F.Cu")
		(net "P5E_CPU1_PE4_TX_DP<13>")
	)
	(segment
		(start 102.352094 -284.847284)
		(end 102.352348 -284.847538)
		(width 0.13208)
		(layer "F.Cu")
		(net "P5E_CPU1_PE4_TX_DP<13>")
	)
	(segment
		(start 89.7128 -407.303478)
		(end 90.011758 -407.00452)
		(width 0.13208)
		(layer "F.Cu")
		(net "P5E_CPU1_PE4_TX_DP<13>")
	)
	(segment
		(start 90.037158 -408.250644)
		(end 89.7128 -407.926286)
		(width 0.13208)
		(layer "F.Cu")
		(net "P5E_CPU1_PE4_TX_DP<13>")
	)
	(segment
		(start 101.701092 -286.961326)
		(end 101.690424 -286.967422)
		(width 0.0889)
		(layer "In2.Cu")
		(net "P5E_CPU1_PE4_TX_DP<13>")
	)
	(segment
		(start 102.447344 -285.64586)
		(end 102.447344 -285.679896)
		(width 0.0889)
		(layer "In2.Cu")
		(net "P5E_CPU1_PE4_TX_DP<13>")
	)
	(segment
		(start 89.717118 -406.70988)
		(end 90.011758 -407.00452)
		(width 0.14732)
		(layer "In2.Cu")
		(net "P5E_CPU1_PE4_TX_DP<13>")
	)
	(segment
		(start 101.6889 -286.968438)
		(end 101.686106 -286.969962)
		(width 0.0889)
		(layer "In2.Cu")
		(net "P5E_CPU1_PE4_TX_DP<13>")
	)
	(segment
		(start 101.079808 -291.492686)
		(end 100.661724 -291.91077)
		(width 0.14732)
		(layer "In2.Cu")
		(net "P5E_CPU1_PE4_TX_DP<13>")
	)
	(segment
		(start 89.632536 -398.791684)
		(end 89.902538 -399.586958)
		(width 0.14732)
		(layer "In2.Cu")
		(net "P5E_CPU1_PE4_TX_DP<13>")
	)
	(segment
		(start 101.037898 -288.103056)
		(end 101.037898 -288.121598)
		(width 0.0889)
		(layer "In2.Cu")
		(net "P5E_CPU1_PE4_TX_DP<13>")
	)
	(segment
		(start 100.661724 -291.91077)
		(end 100.661724 -300.251368)
		(width 0.14732)
		(layer "In2.Cu")
		(net "P5E_CPU1_PE4_TX_DP<13>")
	)
	(segment
		(start 72.228964 -349.944182)
		(end 81.04124 -373.49938)
		(width 0.14732)
		(layer "In2.Cu")
		(net "P5E_CPU1_PE4_TX_DP<13>")
	)
	(segment
		(start 100.567998 -288.917126)
		(end 100.567998 -289.078416)
		(width 0.0889)
		(layer "In2.Cu")
		(net "P5E_CPU1_PE4_TX_DP<13>")
	)
	(segment
		(start 89.717118 -405.416766)
		(end 89.717118 -406.70988)
		(width 0.14732)
		(layer "In2.Cu")
		(net "P5E_CPU1_PE4_TX_DP<13>")
	)
	(segment
		(start 74.409808 -328.92111)
		(end 71.685404 -335.497932)
		(width 0.14732)
		(layer "In2.Cu")
		(net "P5E_CPU1_PE4_TX_DP<13>")
	)
	(segment
		(start 71.685404 -335.497932)
		(end 71.610982 -336.045556)
		(width 0.14732)
		(layer "In2.Cu")
		(net "P5E_CPU1_PE4_TX_DP<13>")
	)
	(segment
		(start 89.902538 -405.231346)
		(end 89.717118 -405.416766)
		(width 0.14732)
		(layer "In2.Cu")
		(net "P5E_CPU1_PE4_TX_DP<13>")
	)
	(segment
		(start 89.902538 -399.586958)
		(end 89.902538 -405.231346)
		(width 0.14732)
		(layer "In2.Cu")
		(net "P5E_CPU1_PE4_TX_DP<13>")
	)
	(segment
		(start 71.610982 -336.045556)
		(end 72.228964 -349.944182)
		(width 0.14732)
		(layer "In2.Cu")
		(net "P5E_CPU1_PE4_TX_DP<13>")
	)
	(segment
		(start 98.95205 -304.378868)
		(end 74.409808 -328.92111)
		(width 0.14732)
		(layer "In2.Cu")
		(net "P5E_CPU1_PE4_TX_DP<13>")
	)
	(segment
		(start 89.632282 -398.79143)
		(end 89.632536 -398.791684)
		(width 0.14732)
		(layer "In2.Cu")
		(net "P5E_CPU1_PE4_TX_DP<13>")
	)
	(segment
		(start 101.079808 -290.588446)
		(end 101.079808 -290.610544)
		(width 0.0889)
		(layer "In2.Cu")
		(net "P5E_CPU1_PE4_TX_DP<13>")
	)
	(segment
		(start 101.037644 -289.60953)
		(end 101.037644 -290.546282)
		(width 0.0889)
		(layer "In2.Cu")
		(net "P5E_CPU1_PE4_TX_DP<13>")
	)
	(segment
		(start 81.04124 -373.49938)
		(end 89.632282 -398.79143)
		(width 0.14732)
		(layer "In2.Cu")
		(net "P5E_CPU1_PE4_TX_DP<13>")
	)
	(segment
		(start 101.507544 -287.28924)
		(end 101.507544 -287.304734)
		(width 0.0889)
		(layer "In2.Cu")
		(net "P5E_CPU1_PE4_TX_DP<13>")
	)
	(segment
		(start 101.079808 -290.610544)
		(end 101.079808 -291.492686)
		(width 0.14732)
		(layer "In2.Cu")
		(net "P5E_CPU1_PE4_TX_DP<13>")
	)
	(segment
		(start 100.661724 -300.251368)
		(end 98.95205 -304.378868)
		(width 0.14732)
		(layer "In2.Cu")
		(net "P5E_CPU1_PE4_TX_DP<13>")
	)
	(segment
		(start 102.352348 -284.847538)
		(end 102.195884 -285.118556)
		(width 0.0889)
		(layer "In2.Cu")
		(net "P5E_CPU1_PE4_TX_DP<13>")
	)
	(segment
		(start 101.690424 -286.967422)
		(end 101.6889 -286.968438)
		(width 0.0889)
		(layer "In2.Cu")
		(net "P5E_CPU1_PE4_TX_DP<13>")
	)
	(segment
		(start 100.75545 -288.592768)
		(end 100.74656 -288.597848)
		(width 0.0889)
		(layer "In2.Cu")
		(net "P5E_CPU1_PE4_TX_DP<13>")
	)
	(segment
		(start 101.22535 -287.778698)
		(end 101.21646 -287.783778)
		(width 0.0889)
		(layer "In2.Cu")
		(net "P5E_CPU1_PE4_TX_DP<13>")
	)
	(segment
		(start 101.977698 -286.466788)
		(end 101.977698 -286.475424)
		(width 0.0889)
		(layer "In2.Cu")
		(net "P5E_CPU1_PE4_TX_DP<13>")
	)
	(segment
		(start 102.195884 -285.118556)
		(end 102.220014 -285.20771)
		(width 0.0889)
		(layer "In2.Cu")
		(net "P5E_CPU1_PE4_TX_DP<13>")
	)
	(segment
		(start 101.037644 -290.546282)
		(end 101.079808 -290.588446)
		(width 0.0889)
		(layer "In2.Cu")
		(net "P5E_CPU1_PE4_TX_DP<13>")
	)
	(arc
		(start 101.977698 -286.475424)
		(mid 101.903707 -286.75499)
		(end 101.701092 -286.961326)
		(width 0.0889)
		(layer "In2.Cu")
		(net "P5E_CPU1_PE4_TX_DP<13>")
	)
	(arc
		(start 100.752148 -289.277806)
		(mid 100.92628 -289.416653)
		(end 101.037644 -289.60953)
		(width 0.0889)
		(layer "In2.Cu")
		(net "P5E_CPU1_PE4_TX_DP<13>")
	)
	(arc
		(start 100.567998 -289.078416)
		(mid 100.643003 -289.193875)
		(end 100.752148 -289.277806)
		(width 0.0889)
		(layer "In2.Cu")
		(net "P5E_CPU1_PE4_TX_DP<13>")
	)
	(arc
		(start 101.037898 -288.121598)
		(mid 100.957736 -288.393787)
		(end 100.75545 -288.592768)
		(width 0.0889)
		(layer "In2.Cu")
		(net "P5E_CPU1_PE4_TX_DP<13>")
	)
	(arc
		(start 102.236778 -285.220664)
		(mid 102.38886 -285.410096)
		(end 102.447344 -285.64586)
		(width 0.0889)
		(layer "In2.Cu")
		(net "P5E_CPU1_PE4_TX_DP<13>")
	)
	(arc
		(start 101.21646 -287.783778)
		(mid 101.085546 -287.920138)
		(end 101.037898 -288.103056)
		(width 0.0889)
		(layer "In2.Cu")
		(net "P5E_CPU1_PE4_TX_DP<13>")
	)
	(arc
		(start 101.686106 -286.969962)
		(mid 101.555192 -287.106322)
		(end 101.507544 -287.28924)
		(width 0.0889)
		(layer "In2.Cu")
		(net "P5E_CPU1_PE4_TX_DP<13>")
	)
	(arc
		(start 101.507544 -287.304734)
		(mid 101.428174 -287.578468)
		(end 101.22535 -287.778698)
		(width 0.0889)
		(layer "In2.Cu")
		(net "P5E_CPU1_PE4_TX_DP<13>")
	)
	(arc
		(start 102.164896 -286.151066)
		(mid 102.029963 -286.28442)
		(end 101.977698 -286.466788)
		(width 0.0889)
		(layer "In2.Cu")
		(net "P5E_CPU1_PE4_TX_DP<13>")
	)
	(arc
		(start 102.220014 -285.20771)
		(mid 102.228455 -285.21411)
		(end 102.236778 -285.220664)
		(width 0.0889)
		(layer "In2.Cu")
		(net "P5E_CPU1_PE4_TX_DP<13>")
	)
	(arc
		(start 102.447344 -285.679896)
		(mid 102.367182 -285.952085)
		(end 102.164896 -286.151066)
		(width 0.0889)
		(layer "In2.Cu")
		(net "P5E_CPU1_PE4_TX_DP<13>")
	)
	(arc
		(start 100.74656 -288.597848)
		(mid 100.615646 -288.734208)
		(end 100.567998 -288.917126)
		(width 0.0889)
		(layer "In2.Cu")
		(net "P5E_CPU1_PE4_TX_DP<13>")
	)
	(segment
		(start 86.973918 -408.250644)
		(end 86.64956 -407.926286)
		(width 0.13208)
		(layer "F.Cu")
		(net "P5E_CPU1_PE4_TX_DP<12>")
	)
	(segment
		(start 86.64956 -407.926286)
		(end 86.64956 -407.303478)
		(width 0.13208)
		(layer "F.Cu")
		(net "P5E_CPU1_PE4_TX_DP<12>")
	)
	(segment
		(start 101.412294 -285.939484)
		(end 101.412294 -286.47517)
		(width 0.13208)
		(layer "F.Cu")
		(net "P5E_CPU1_PE4_TX_DP<12>")
	)
	(segment
		(start 101.412294 -286.47517)
		(end 101.412548 -286.475424)
		(width 0.13208)
		(layer "F.Cu")
		(net "P5E_CPU1_PE4_TX_DP<12>")
	)
	(segment
		(start 86.64956 -407.303478)
		(end 86.948518 -407.00452)
		(width 0.13208)
		(layer "F.Cu")
		(net "P5E_CPU1_PE4_TX_DP<12>")
	)
	(segment
		(start 86.653878 -405.416766)
		(end 86.653878 -406.70988)
		(width 0.14732)
		(layer "In2.Cu")
		(net "P5E_CPU1_PE4_TX_DP<12>")
	)
	(segment
		(start 99.731068 -290.959794)
		(end 99.731068 -290.981892)
		(width 0.0889)
		(layer "In2.Cu")
		(net "P5E_CPU1_PE4_TX_DP<12>")
	)
	(segment
		(start 79.46263 -374.638062)
		(end 79.635604 -374.732296)
		(width 0.14732)
		(layer "In2.Cu")
		(net "P5E_CPU1_PE4_TX_DP<12>")
	)
	(segment
		(start 99.688904 -290.91763)
		(end 99.731068 -290.959794)
		(width 0.0889)
		(layer "In2.Cu")
		(net "P5E_CPU1_PE4_TX_DP<12>")
	)
	(segment
		(start 100.098098 -288.103056)
		(end 100.098098 -288.121598)
		(width 0.0889)
		(layer "In2.Cu")
		(net "P5E_CPU1_PE4_TX_DP<12>")
	)
	(segment
		(start 99.688904 -290.781994)
		(end 99.688904 -290.91763)
		(width 0.0889)
		(layer "In2.Cu")
		(net "P5E_CPU1_PE4_TX_DP<12>")
	)
	(segment
		(start 70.646544 -335.73847)
		(end 71.14667 -349.894906)
		(width 0.14732)
		(layer "In2.Cu")
		(net "P5E_CPU1_PE4_TX_DP<12>")
	)
	(segment
		(start 79.35849 -374.283732)
		(end 79.46263 -374.638062)
		(width 0.14732)
		(layer "In2.Cu")
		(net "P5E_CPU1_PE4_TX_DP<12>")
	)
	(segment
		(start 99.628198 -288.917126)
		(end 99.628198 -289.078416)
		(width 0.0889)
		(layer "In2.Cu")
		(net "P5E_CPU1_PE4_TX_DP<12>")
	)
	(segment
		(start 79.175356 -373.66194)
		(end 79.175356 -373.662956)
		(width 0.14732)
		(layer "In2.Cu")
		(net "P5E_CPU1_PE4_TX_DP<12>")
	)
	(segment
		(start 79.635604 -374.732296)
		(end 79.73949 -375.085864)
		(width 0.14732)
		(layer "In2.Cu")
		(net "P5E_CPU1_PE4_TX_DP<12>")
	)
	(segment
		(start 98.161348 -303.83607)
		(end 73.561702 -328.435716)
		(width 0.14732)
		(layer "In2.Cu")
		(net "P5E_CPU1_PE4_TX_DP<12>")
	)
	(segment
		(start 101.256084 -286.204406)
		(end 101.177852 -286.183578)
		(width 0.0889)
		(layer "In2.Cu")
		(net "P5E_CPU1_PE4_TX_DP<12>")
	)
	(segment
		(start 78.97114 -372.967758)
		(end 79.175356 -373.66194)
		(width 0.14732)
		(layer "In2.Cu")
		(net "P5E_CPU1_PE4_TX_DP<12>")
	)
	(segment
		(start 100.097844 -289.60953)
		(end 100.097844 -290.373054)
		(width 0.0889)
		(layer "In2.Cu")
		(net "P5E_CPU1_PE4_TX_DP<12>")
	)
	(segment
		(start 100.097844 -290.373054)
		(end 99.688904 -290.781994)
		(width 0.0889)
		(layer "In2.Cu")
		(net "P5E_CPU1_PE4_TX_DP<12>")
	)
	(segment
		(start 100.767388 -286.95777)
		(end 100.746306 -286.969962)
		(width 0.0889)
		(layer "In2.Cu")
		(net "P5E_CPU1_PE4_TX_DP<12>")
	)
	(segment
		(start 79.73949 -375.085864)
		(end 79.645002 -375.259346)
		(width 0.14732)
		(layer "In2.Cu")
		(net "P5E_CPU1_PE4_TX_DP<12>")
	)
	(segment
		(start 71.14667 -349.894906)
		(end 78.97114 -372.967758)
		(width 0.14732)
		(layer "In2.Cu")
		(net "P5E_CPU1_PE4_TX_DP<12>")
	)
	(segment
		(start 79.175356 -373.662956)
		(end 79.349092 -373.757444)
		(width 0.14732)
		(layer "In2.Cu")
		(net "P5E_CPU1_PE4_TX_DP<12>")
	)
	(segment
		(start 86.839298 -399.732246)
		(end 86.839298 -405.231346)
		(width 0.14732)
		(layer "In2.Cu")
		(net "P5E_CPU1_PE4_TX_DP<12>")
	)
	(segment
		(start 79.349092 -373.757444)
		(end 79.452978 -374.111012)
		(width 0.14732)
		(layer "In2.Cu")
		(net "P5E_CPU1_PE4_TX_DP<12>")
	)
	(segment
		(start 86.653878 -406.70988)
		(end 86.948518 -407.00452)
		(width 0.14732)
		(layer "In2.Cu")
		(net "P5E_CPU1_PE4_TX_DP<12>")
	)
	(segment
		(start 100.567744 -287.28924)
		(end 100.567744 -287.304734)
		(width 0.0889)
		(layer "In2.Cu")
		(net "P5E_CPU1_PE4_TX_DP<12>")
	)
	(segment
		(start 99.81565 -288.592768)
		(end 99.80676 -288.597848)
		(width 0.0889)
		(layer "In2.Cu")
		(net "P5E_CPU1_PE4_TX_DP<12>")
	)
	(segment
		(start 100.28555 -287.778698)
		(end 100.27666 -287.783778)
		(width 0.0889)
		(layer "In2.Cu")
		(net "P5E_CPU1_PE4_TX_DP<12>")
	)
	(segment
		(start 73.561702 -328.435716)
		(end 70.739762 -335.248758)
		(width 0.14732)
		(layer "In2.Cu")
		(net "P5E_CPU1_PE4_TX_DP<12>")
	)
	(segment
		(start 99.731068 -290.981892)
		(end 99.731068 -300.045882)
		(width 0.14732)
		(layer "In2.Cu")
		(net "P5E_CPU1_PE4_TX_DP<12>")
	)
	(segment
		(start 101.412548 -286.475424)
		(end 101.256084 -286.204406)
		(width 0.0889)
		(layer "In2.Cu")
		(net "P5E_CPU1_PE4_TX_DP<12>")
	)
	(segment
		(start 79.645002 -375.259346)
		(end 86.839298 -399.732246)
		(width 0.14732)
		(layer "In2.Cu")
		(net "P5E_CPU1_PE4_TX_DP<12>")
	)
	(segment
		(start 86.839298 -405.231346)
		(end 86.653878 -405.416766)
		(width 0.14732)
		(layer "In2.Cu")
		(net "P5E_CPU1_PE4_TX_DP<12>")
	)
	(segment
		(start 79.452978 -374.111012)
		(end 79.35849 -374.283732)
		(width 0.14732)
		(layer "In2.Cu")
		(net "P5E_CPU1_PE4_TX_DP<12>")
	)
	(segment
		(start 99.731068 -300.045882)
		(end 98.161348 -303.83607)
		(width 0.14732)
		(layer "In2.Cu")
		(net "P5E_CPU1_PE4_TX_DP<12>")
	)
	(segment
		(start 70.739762 -335.248758)
		(end 70.646544 -335.73847)
		(width 0.14732)
		(layer "In2.Cu")
		(net "P5E_CPU1_PE4_TX_DP<12>")
	)
	(arc
		(start 100.27666 -287.783778)
		(mid 100.145746 -287.920138)
		(end 100.098098 -288.103056)
		(width 0.0889)
		(layer "In2.Cu")
		(net "P5E_CPU1_PE4_TX_DP<12>")
	)
	(arc
		(start 100.746306 -286.969962)
		(mid 100.615392 -287.106322)
		(end 100.567744 -287.28924)
		(width 0.0889)
		(layer "In2.Cu")
		(net "P5E_CPU1_PE4_TX_DP<12>")
	)
	(arc
		(start 101.177852 -286.183578)
		(mid 101.074707 -286.313603)
		(end 101.037898 -286.475424)
		(width 0.0889)
		(layer "In2.Cu")
		(net "P5E_CPU1_PE4_TX_DP<12>")
	)
	(arc
		(start 99.628198 -289.078416)
		(mid 99.703203 -289.193875)
		(end 99.812348 -289.277806)
		(width 0.0889)
		(layer "In2.Cu")
		(net "P5E_CPU1_PE4_TX_DP<12>")
	)
	(arc
		(start 100.098098 -288.121598)
		(mid 100.017936 -288.393787)
		(end 99.81565 -288.592768)
		(width 0.0889)
		(layer "In2.Cu")
		(net "P5E_CPU1_PE4_TX_DP<12>")
	)
	(arc
		(start 99.812348 -289.277806)
		(mid 99.98648 -289.416653)
		(end 100.097844 -289.60953)
		(width 0.0889)
		(layer "In2.Cu")
		(net "P5E_CPU1_PE4_TX_DP<12>")
	)
	(arc
		(start 99.80676 -288.597848)
		(mid 99.675846 -288.734208)
		(end 99.628198 -288.917126)
		(width 0.0889)
		(layer "In2.Cu")
		(net "P5E_CPU1_PE4_TX_DP<12>")
	)
	(arc
		(start 100.567744 -287.304734)
		(mid 100.488374 -287.578468)
		(end 100.28555 -287.778698)
		(width 0.0889)
		(layer "In2.Cu")
		(net "P5E_CPU1_PE4_TX_DP<12>")
	)
	(arc
		(start 101.037898 -286.475424)
		(mid 100.965663 -286.751948)
		(end 100.767388 -286.95777)
		(width 0.0889)
		(layer "In2.Cu")
		(net "P5E_CPU1_PE4_TX_DP<12>")
	)
	(segment
		(start 100.002848 -285.6611)
		(end 100.002594 -285.661354)
		(width 0.13208)
		(layer "F.Cu")
		(net "P5E_CPU1_PE4_TX_DP<11>")
	)
	(segment
		(start 83.00085 -408.250644)
		(end 83.32724 -407.924254)
		(width 0.13208)
		(layer "F.Cu")
		(net "P5E_CPU1_PE4_TX_DP<11>")
	)
	(segment
		(start 100.002848 -285.125414)
		(end 100.002848 -285.6611)
		(width 0.13208)
		(layer "F.Cu")
		(net "P5E_CPU1_PE4_TX_DP<11>")
	)
	(segment
		(start 82.996278 -408.250644)
		(end 83.00085 -408.250644)
		(width 0.13208)
		(layer "F.Cu")
		(net "P5E_CPU1_PE4_TX_DP<11>")
	)
	(segment
		(start 83.32724 -407.310082)
		(end 83.021678 -407.00452)
		(width 0.13208)
		(layer "F.Cu")
		(net "P5E_CPU1_PE4_TX_DP<11>")
	)
	(segment
		(start 83.32724 -407.924254)
		(end 83.32724 -407.310082)
		(width 0.13208)
		(layer "F.Cu")
		(net "P5E_CPU1_PE4_TX_DP<11>")
	)
	(segment
		(start 100.238306 -285.369254)
		(end 100.253038 -285.380938)
		(width 0.0889)
		(layer "In2.Cu")
		(net "P5E_CPU1_PE4_TX_DP<11>")
	)
	(segment
		(start 82.22107 -395.064996)
		(end 82.390742 -395.16685)
		(width 0.14732)
		(layer "In2.Cu")
		(net "P5E_CPU1_PE4_TX_DP<11>")
	)
	(segment
		(start 83.316318 -406.70988)
		(end 83.021678 -407.00452)
		(width 0.14732)
		(layer "In2.Cu")
		(net "P5E_CPU1_PE4_TX_DP<11>")
	)
	(segment
		(start 98.566478 -290.423346)
		(end 98.566478 -290.940236)
		(width 0.0889)
		(layer "In2.Cu")
		(net "P5E_CPU1_PE4_TX_DP<11>")
	)
	(segment
		(start 98.967544 -289.644582)
		(end 98.967544 -290.160964)
		(width 0.0889)
		(layer "In2.Cu")
		(net "P5E_CPU1_PE4_TX_DP<11>")
	)
	(segment
		(start 98.524568 -290.982146)
		(end 98.524568 -291.004244)
		(width 0.0889)
		(layer "In2.Cu")
		(net "P5E_CPU1_PE4_TX_DP<11>")
	)
	(segment
		(start 98.780854 -288.427668)
		(end 98.770186 -288.434018)
		(width 0.0889)
		(layer "In2.Cu")
		(net "P5E_CPU1_PE4_TX_DP<11>")
	)
	(segment
		(start 99.907852 -286.464756)
		(end 99.907852 -286.475424)
		(width 0.0889)
		(layer "In2.Cu")
		(net "P5E_CPU1_PE4_TX_DP<11>")
	)
	(segment
		(start 69.869558 -349.980758)
		(end 76.885546 -373.034306)
		(width 0.14732)
		(layer "In2.Cu")
		(net "P5E_CPU1_PE4_TX_DP<11>")
	)
	(segment
		(start 82.466434 -396.051024)
		(end 82.635598 -396.152624)
		(width 0.14732)
		(layer "In2.Cu")
		(net "P5E_CPU1_PE4_TX_DP<11>")
	)
	(segment
		(start 82.13217 -394.707364)
		(end 82.22107 -395.064996)
		(width 0.14732)
		(layer "In2.Cu")
		(net "P5E_CPU1_PE4_TX_DP<11>")
	)
	(segment
		(start 99.250754 -287.613598)
		(end 99.240086 -287.619948)
		(width 0.0889)
		(layer "In2.Cu")
		(net "P5E_CPU1_PE4_TX_DP<11>")
	)
	(segment
		(start 69.518022 -334.86471)
		(end 69.408294 -335.53908)
		(width 0.14732)
		(layer "In2.Cu")
		(net "P5E_CPU1_PE4_TX_DP<11>")
	)
	(segment
		(start 82.635598 -396.152624)
		(end 83.501738 -399.63471)
		(width 0.14732)
		(layer "In2.Cu")
		(net "P5E_CPU1_PE4_TX_DP<11>")
	)
	(segment
		(start 99.71786 -286.801306)
		(end 99.708716 -286.80664)
		(width 0.0889)
		(layer "In2.Cu")
		(net "P5E_CPU1_PE4_TX_DP<11>")
	)
	(segment
		(start 97.067116 -303.219866)
		(end 72.41413 -327.872852)
		(width 0.14732)
		(layer "In2.Cu")
		(net "P5E_CPU1_PE4_TX_DP<11>")
	)
	(segment
		(start 98.498152 -288.917126)
		(end 98.498152 -289.113976)
		(width 0.0889)
		(layer "In2.Cu")
		(net "P5E_CPU1_PE4_TX_DP<11>")
	)
	(segment
		(start 82.390742 -395.16685)
		(end 82.479388 -395.524228)
		(width 0.14732)
		(layer "In2.Cu")
		(net "P5E_CPU1_PE4_TX_DP<11>")
	)
	(segment
		(start 100.37699 -285.630366)
		(end 100.377244 -285.677102)
		(width 0.0889)
		(layer "In2.Cu")
		(net "P5E_CPU1_PE4_TX_DP<11>")
	)
	(segment
		(start 98.968052 -288.103056)
		(end 98.968052 -288.118042)
		(width 0.0889)
		(layer "In2.Cu")
		(net "P5E_CPU1_PE4_TX_DP<11>")
	)
	(segment
		(start 100.23729 -285.369508)
		(end 100.237544 -285.368746)
		(width 0.0889)
		(layer "In2.Cu")
		(net "P5E_CPU1_PE4_TX_DP<11>")
	)
	(segment
		(start 100.237544 -285.368746)
		(end 100.238052 -285.369)
		(width 0.0889)
		(layer "In2.Cu")
		(net "P5E_CPU1_PE4_TX_DP<11>")
	)
	(segment
		(start 99.719384 -286.800544)
		(end 99.71786 -286.801306)
		(width 0.0889)
		(layer "In2.Cu")
		(net "P5E_CPU1_PE4_TX_DP<11>")
	)
	(segment
		(start 76.885546 -373.034306)
		(end 82.234024 -394.5382)
		(width 0.14732)
		(layer "In2.Cu")
		(net "P5E_CPU1_PE4_TX_DP<11>")
	)
	(segment
		(start 99.437698 -287.28924)
		(end 99.437698 -287.301686)
		(width 0.0889)
		(layer "In2.Cu")
		(net "P5E_CPU1_PE4_TX_DP<11>")
	)
	(segment
		(start 98.967544 -290.160964)
		(end 98.566478 -290.423346)
		(width 0.0889)
		(layer "In2.Cu")
		(net "P5E_CPU1_PE4_TX_DP<11>")
	)
	(segment
		(start 83.501738 -399.63471)
		(end 83.501738 -405.117554)
		(width 0.14732)
		(layer "In2.Cu")
		(net "P5E_CPU1_PE4_TX_DP<11>")
	)
	(segment
		(start 82.234024 -394.5382)
		(end 82.13217 -394.707364)
		(width 0.14732)
		(layer "In2.Cu")
		(net "P5E_CPU1_PE4_TX_DP<11>")
	)
	(segment
		(start 98.566478 -290.940236)
		(end 98.524568 -290.982146)
		(width 0.0889)
		(layer "In2.Cu")
		(net "P5E_CPU1_PE4_TX_DP<11>")
	)
	(segment
		(start 82.377534 -395.693392)
		(end 82.466434 -396.051024)
		(width 0.14732)
		(layer "In2.Cu")
		(net "P5E_CPU1_PE4_TX_DP<11>")
	)
	(segment
		(start 98.524568 -299.701712)
		(end 97.067116 -303.219866)
		(width 0.14732)
		(layer "In2.Cu")
		(net "P5E_CPU1_PE4_TX_DP<11>")
	)
	(segment
		(start 98.524568 -291.004244)
		(end 98.524568 -299.701712)
		(width 0.14732)
		(layer "In2.Cu")
		(net "P5E_CPU1_PE4_TX_DP<11>")
	)
	(segment
		(start 83.501738 -405.117554)
		(end 83.316318 -405.302974)
		(width 0.14732)
		(layer "In2.Cu")
		(net "P5E_CPU1_PE4_TX_DP<11>")
	)
	(segment
		(start 83.316318 -405.302974)
		(end 83.316318 -406.70988)
		(width 0.14732)
		(layer "In2.Cu")
		(net "P5E_CPU1_PE4_TX_DP<11>")
	)
	(segment
		(start 100.002594 -285.661354)
		(end 100.159058 -285.390336)
		(width 0.0889)
		(layer "In2.Cu")
		(net "P5E_CPU1_PE4_TX_DP<11>")
	)
	(segment
		(start 82.479388 -395.524228)
		(end 82.377534 -395.693392)
		(width 0.14732)
		(layer "In2.Cu")
		(net "P5E_CPU1_PE4_TX_DP<11>")
	)
	(segment
		(start 99.72548 -286.796988)
		(end 99.719384 -286.800544)
		(width 0.0889)
		(layer "In2.Cu")
		(net "P5E_CPU1_PE4_TX_DP<11>")
	)
	(segment
		(start 100.159058 -285.390336)
		(end 100.23729 -285.369508)
		(width 0.0889)
		(layer "In2.Cu")
		(net "P5E_CPU1_PE4_TX_DP<11>")
	)
	(segment
		(start 72.41413 -327.872852)
		(end 69.518022 -334.86471)
		(width 0.14732)
		(layer "In2.Cu")
		(net "P5E_CPU1_PE4_TX_DP<11>")
	)
	(segment
		(start 100.238052 -285.369)
		(end 100.238306 -285.369254)
		(width 0.0889)
		(layer "In2.Cu")
		(net "P5E_CPU1_PE4_TX_DP<11>")
	)
	(segment
		(start 69.408294 -335.53908)
		(end 69.869558 -349.980758)
		(width 0.14732)
		(layer "In2.Cu")
		(net "P5E_CPU1_PE4_TX_DP<11>")
	)
	(arc
		(start 98.783648 -289.446208)
		(mid 98.892535 -289.529701)
		(end 98.967544 -289.644582)
		(width 0.0889)
		(layer "In2.Cu")
		(net "P5E_CPU1_PE4_TX_DP<11>")
	)
	(arc
		(start 99.708716 -286.80664)
		(mid 99.510075 -287.012489)
		(end 99.437698 -287.28924)
		(width 0.0889)
		(layer "In2.Cu")
		(net "P5E_CPU1_PE4_TX_DP<11>")
	)
	(arc
		(start 99.907852 -286.475424)
		(mid 99.859083 -286.66026)
		(end 99.72548 -286.796988)
		(width 0.0889)
		(layer "In2.Cu")
		(net "P5E_CPU1_PE4_TX_DP<11>")
	)
	(arc
		(start 100.190046 -285.98622)
		(mid 99.986068 -286.188396)
		(end 99.907852 -286.464756)
		(width 0.0889)
		(layer "In2.Cu")
		(net "P5E_CPU1_PE4_TX_DP<11>")
	)
	(arc
		(start 99.240086 -287.619948)
		(mid 99.040702 -287.825828)
		(end 98.968052 -288.103056)
		(width 0.0889)
		(layer "In2.Cu")
		(net "P5E_CPU1_PE4_TX_DP<11>")
	)
	(arc
		(start 98.770186 -288.434018)
		(mid 98.570802 -288.639898)
		(end 98.498152 -288.917126)
		(width 0.0889)
		(layer "In2.Cu")
		(net "P5E_CPU1_PE4_TX_DP<11>")
	)
	(arc
		(start 100.253038 -285.380938)
		(mid 100.342285 -285.492106)
		(end 100.37699 -285.630366)
		(width 0.0889)
		(layer "In2.Cu")
		(net "P5E_CPU1_PE4_TX_DP<11>")
	)
	(arc
		(start 100.377244 -285.677102)
		(mid 100.323303 -285.855664)
		(end 100.190046 -285.98622)
		(width 0.0889)
		(layer "In2.Cu")
		(net "P5E_CPU1_PE4_TX_DP<11>")
	)
	(arc
		(start 98.498152 -289.113976)
		(mid 98.609382 -289.30718)
		(end 98.783648 -289.446208)
		(width 0.0889)
		(layer "In2.Cu")
		(net "P5E_CPU1_PE4_TX_DP<11>")
	)
	(arc
		(start 98.968052 -288.118042)
		(mid 98.914247 -288.296917)
		(end 98.780854 -288.427668)
		(width 0.0889)
		(layer "In2.Cu")
		(net "P5E_CPU1_PE4_TX_DP<11>")
	)
	(arc
		(start 99.437698 -287.301686)
		(mid 99.384556 -287.481816)
		(end 99.250754 -287.613598)
		(width 0.0889)
		(layer "In2.Cu")
		(net "P5E_CPU1_PE4_TX_DP<11>")
	)
	(segment
		(start 80.52308 -407.303478)
		(end 80.822038 -407.00452)
		(width 0.13208)
		(layer "F.Cu")
		(net "P5E_CPU1_PE4_TX_DP<10>")
	)
	(segment
		(start 80.847438 -408.250644)
		(end 80.52308 -407.926286)
		(width 0.13208)
		(layer "F.Cu")
		(net "P5E_CPU1_PE4_TX_DP<10>")
	)
	(segment
		(start 99.532694 -286.47517)
		(end 99.532948 -286.475424)
		(width 0.13208)
		(layer "F.Cu")
		(net "P5E_CPU1_PE4_TX_DP<10>")
	)
	(segment
		(start 99.532694 -285.939484)
		(end 99.532694 -286.47517)
		(width 0.13208)
		(layer "F.Cu")
		(net "P5E_CPU1_PE4_TX_DP<10>")
	)
	(segment
		(start 80.52308 -407.926286)
		(end 80.52308 -407.303478)
		(width 0.13208)
		(layer "F.Cu")
		(net "P5E_CPU1_PE4_TX_DP<10>")
	)
	(segment
		(start 97.866708 -291.004244)
		(end 97.866708 -299.563282)
		(width 0.14732)
		(layer "In2.Cu")
		(net "P5E_CPU1_PE4_TX_DP<10>")
	)
	(segment
		(start 96.502982 -302.856138)
		(end 71.76897 -327.590658)
		(width 0.14732)
		(layer "In2.Cu")
		(net "P5E_CPU1_PE4_TX_DP<10>")
	)
	(segment
		(start 69.148198 -349.894906)
		(end 69.153024 -349.926148)
		(width 0.14732)
		(layer "In2.Cu")
		(net "P5E_CPU1_PE4_TX_DP<10>")
	)
	(segment
		(start 97.824544 -290.939982)
		(end 97.866708 -290.982146)
		(width 0.0889)
		(layer "In2.Cu")
		(net "P5E_CPU1_PE4_TX_DP<10>")
	)
	(segment
		(start 79.994506 -395.762734)
		(end 80.141318 -395.860016)
		(width 0.14732)
		(layer "In2.Cu")
		(net "P5E_CPU1_PE4_TX_DP<10>")
	)
	(segment
		(start 80.467708 -397.478504)
		(end 80.370426 -397.625062)
		(width 0.14732)
		(layer "In2.Cu")
		(net "P5E_CPU1_PE4_TX_DP<10>")
	)
	(segment
		(start 80.227678 -396.288514)
		(end 80.130396 -396.435072)
		(width 0.14732)
		(layer "In2.Cu")
		(net "P5E_CPU1_PE4_TX_DP<10>")
	)
	(segment
		(start 97.824544 -290.52647)
		(end 97.824544 -290.939982)
		(width 0.0889)
		(layer "In2.Cu")
		(net "P5E_CPU1_PE4_TX_DP<10>")
	)
	(segment
		(start 80.712818 -399.322544)
		(end 80.712818 -405.231346)
		(width 0.14732)
		(layer "In2.Cu")
		(net "P5E_CPU1_PE4_TX_DP<10>")
	)
	(segment
		(start 99.158298 -286.475424)
		(end 99.158044 -286.475424)
		(width 0.0889)
		(layer "In2.Cu")
		(net "P5E_CPU1_PE4_TX_DP<10>")
	)
	(segment
		(start 99.376484 -286.204406)
		(end 99.298252 -286.183578)
		(width 0.0889)
		(layer "In2.Cu")
		(net "P5E_CPU1_PE4_TX_DP<10>")
	)
	(segment
		(start 98.218244 -290.293298)
		(end 97.824544 -290.52647)
		(width 0.0889)
		(layer "In2.Cu")
		(net "P5E_CPU1_PE4_TX_DP<10>")
	)
	(segment
		(start 97.748598 -288.90214)
		(end 97.748598 -289.078416)
		(width 0.0889)
		(layer "In2.Cu")
		(net "P5E_CPU1_PE4_TX_DP<10>")
	)
	(segment
		(start 98.88601 -286.95904)
		(end 98.875088 -286.965136)
		(width 0.0889)
		(layer "In2.Cu")
		(net "P5E_CPU1_PE4_TX_DP<10>")
	)
	(segment
		(start 80.234536 -396.95247)
		(end 80.381348 -397.050006)
		(width 0.14732)
		(layer "In2.Cu")
		(net "P5E_CPU1_PE4_TX_DP<10>")
	)
	(segment
		(start 98.688144 -287.281366)
		(end 98.688144 -287.28924)
		(width 0.0889)
		(layer "In2.Cu")
		(net "P5E_CPU1_PE4_TX_DP<10>")
	)
	(segment
		(start 69.153024 -349.926148)
		(end 75.491848 -373.448326)
		(width 0.14732)
		(layer "In2.Cu")
		(net "P5E_CPU1_PE4_TX_DP<10>")
	)
	(segment
		(start 68.733162 -335.507838)
		(end 69.148198 -349.894906)
		(width 0.14732)
		(layer "In2.Cu")
		(net "P5E_CPU1_PE4_TX_DP<10>")
	)
	(segment
		(start 98.41611 -287.772856)
		(end 98.405442 -287.778952)
		(width 0.0889)
		(layer "In2.Cu")
		(net "P5E_CPU1_PE4_TX_DP<10>")
	)
	(segment
		(start 98.218498 -288.09061)
		(end 98.218498 -288.103056)
		(width 0.0889)
		(layer "In2.Cu")
		(net "P5E_CPU1_PE4_TX_DP<10>")
	)
	(segment
		(start 97.866708 -290.982146)
		(end 97.866708 -291.004244)
		(width 0.0889)
		(layer "In2.Cu")
		(net "P5E_CPU1_PE4_TX_DP<10>")
	)
	(segment
		(start 80.234536 -396.951708)
		(end 80.234536 -396.95247)
		(width 0.14732)
		(layer "In2.Cu")
		(net "P5E_CPU1_PE4_TX_DP<10>")
	)
	(segment
		(start 80.130396 -396.435072)
		(end 80.234536 -396.951708)
		(width 0.14732)
		(layer "In2.Cu")
		(net "P5E_CPU1_PE4_TX_DP<10>")
	)
	(segment
		(start 80.381348 -397.050006)
		(end 80.467708 -397.478504)
		(width 0.14732)
		(layer "In2.Cu")
		(net "P5E_CPU1_PE4_TX_DP<10>")
	)
	(segment
		(start 80.527398 -405.416766)
		(end 80.527398 -406.70988)
		(width 0.14732)
		(layer "In2.Cu")
		(net "P5E_CPU1_PE4_TX_DP<10>")
	)
	(segment
		(start 80.370426 -397.625062)
		(end 80.712818 -399.322544)
		(width 0.14732)
		(layer "In2.Cu")
		(net "P5E_CPU1_PE4_TX_DP<10>")
	)
	(segment
		(start 80.141318 -395.860016)
		(end 80.227678 -396.288514)
		(width 0.14732)
		(layer "In2.Cu")
		(net "P5E_CPU1_PE4_TX_DP<10>")
	)
	(segment
		(start 97.946464 -288.586672)
		(end 97.935542 -288.592768)
		(width 0.0889)
		(layer "In2.Cu")
		(net "P5E_CPU1_PE4_TX_DP<10>")
	)
	(segment
		(start 99.532948 -286.475424)
		(end 99.376484 -286.204406)
		(width 0.0889)
		(layer "In2.Cu")
		(net "P5E_CPU1_PE4_TX_DP<10>")
	)
	(segment
		(start 97.866708 -299.563282)
		(end 96.502982 -302.856138)
		(width 0.14732)
		(layer "In2.Cu")
		(net "P5E_CPU1_PE4_TX_DP<10>")
	)
	(segment
		(start 68.885054 -334.553306)
		(end 68.733162 -335.507838)
		(width 0.14732)
		(layer "In2.Cu")
		(net "P5E_CPU1_PE4_TX_DP<10>")
	)
	(segment
		(start 71.76897 -327.590658)
		(end 68.885054 -334.553306)
		(width 0.14732)
		(layer "In2.Cu")
		(net "P5E_CPU1_PE4_TX_DP<10>")
	)
	(segment
		(start 98.218244 -289.60953)
		(end 98.218244 -290.293298)
		(width 0.0889)
		(layer "In2.Cu")
		(net "P5E_CPU1_PE4_TX_DP<10>")
	)
	(segment
		(start 80.712818 -405.231346)
		(end 80.527398 -405.416766)
		(width 0.14732)
		(layer "In2.Cu")
		(net "P5E_CPU1_PE4_TX_DP<10>")
	)
	(segment
		(start 80.527398 -406.70988)
		(end 80.822038 -407.00452)
		(width 0.14732)
		(layer "In2.Cu")
		(net "P5E_CPU1_PE4_TX_DP<10>")
	)
	(segment
		(start 75.491848 -373.448326)
		(end 79.994506 -395.762734)
		(width 0.14732)
		(layer "In2.Cu")
		(net "P5E_CPU1_PE4_TX_DP<10>")
	)
	(arc
		(start 98.218498 -288.103056)
		(mid 98.145877 -288.380521)
		(end 97.946464 -288.586672)
		(width 0.0889)
		(layer "In2.Cu")
		(net "P5E_CPU1_PE4_TX_DP<10>")
	)
	(arc
		(start 97.748598 -289.078416)
		(mid 97.823603 -289.193875)
		(end 97.932748 -289.277806)
		(width 0.0889)
		(layer "In2.Cu")
		(net "P5E_CPU1_PE4_TX_DP<10>")
	)
	(arc
		(start 97.935542 -288.592768)
		(mid 97.802323 -288.723438)
		(end 97.748598 -288.90214)
		(width 0.0889)
		(layer "In2.Cu")
		(net "P5E_CPU1_PE4_TX_DP<10>")
	)
	(arc
		(start 97.932748 -289.277806)
		(mid 98.10688 -289.416653)
		(end 98.218244 -289.60953)
		(width 0.0889)
		(layer "In2.Cu")
		(net "P5E_CPU1_PE4_TX_DP<10>")
	)
	(arc
		(start 99.158044 -286.475424)
		(mid 99.085423 -286.752889)
		(end 98.88601 -286.95904)
		(width 0.0889)
		(layer "In2.Cu")
		(net "P5E_CPU1_PE4_TX_DP<10>")
	)
	(arc
		(start 98.875088 -286.965136)
		(mid 98.740201 -287.098771)
		(end 98.688144 -287.281366)
		(width 0.0889)
		(layer "In2.Cu")
		(net "P5E_CPU1_PE4_TX_DP<10>")
	)
	(arc
		(start 98.405442 -287.778952)
		(mid 98.271724 -287.910623)
		(end 98.218498 -288.09061)
		(width 0.0889)
		(layer "In2.Cu")
		(net "P5E_CPU1_PE4_TX_DP<10>")
	)
	(arc
		(start 99.298252 -286.183578)
		(mid 99.195107 -286.313603)
		(end 99.158298 -286.475424)
		(width 0.0889)
		(layer "In2.Cu")
		(net "P5E_CPU1_PE4_TX_DP<10>")
	)
	(arc
		(start 98.688144 -287.28924)
		(mid 98.615523 -287.566705)
		(end 98.41611 -287.772856)
		(width 0.0889)
		(layer "In2.Cu")
		(net "P5E_CPU1_PE4_TX_DP<10>")
	)
	(segment
		(start 50.215038 -408.250644)
		(end 49.89068 -407.926286)
		(width 0.13208)
		(layer "F.Cu")
		(net "P5E_CPU1_PE4_TX_DP<0>")
	)
	(segment
		(start 49.89068 -407.303478)
		(end 50.189638 -407.00452)
		(width 0.13208)
		(layer "F.Cu")
		(net "P5E_CPU1_PE4_TX_DP<0>")
	)
	(segment
		(start 90.134694 -285.939484)
		(end 90.134694 -286.475424)
		(width 0.13208)
		(layer "F.Cu")
		(net "P5E_CPU1_PE4_TX_DP<0>")
	)
	(segment
		(start 49.89068 -407.926286)
		(end 49.89068 -407.303478)
		(width 0.13208)
		(layer "F.Cu")
		(net "P5E_CPU1_PE4_TX_DP<0>")
	)
	(segment
		(start 77.058266 -309.06466)
		(end 66.553842 -319.569084)
		(width 0.14732)
		(layer "In2.Cu")
		(net "P5E_CPU1_PE4_TX_DP<0>")
	)
	(segment
		(start 51.150774 -396.35938)
		(end 51.237642 -396.512542)
		(width 0.14732)
		(layer "In2.Cu")
		(net "P5E_CPU1_PE4_TX_DP<0>")
	)
	(segment
		(start 49.894998 -405.416766)
		(end 49.894998 -406.70988)
		(width 0.14732)
		(layer "In2.Cu")
		(net "P5E_CPU1_PE4_TX_DP<0>")
	)
	(segment
		(start 89.290144 -287.28924)
		(end 89.290144 -287.299146)
		(width 0.0889)
		(layer "In2.Cu")
		(net "P5E_CPU1_PE4_TX_DP<0>")
	)
	(segment
		(start 51.121056 -396.933928)
		(end 50.967894 -397.020796)
		(width 0.14732)
		(layer "In2.Cu")
		(net "P5E_CPU1_PE4_TX_DP<0>")
	)
	(segment
		(start 50.080418 -405.231346)
		(end 49.894998 -405.416766)
		(width 0.14732)
		(layer "In2.Cu")
		(net "P5E_CPU1_PE4_TX_DP<0>")
	)
	(segment
		(start 88.392254 -289.488372)
		(end 88.392254 -290.411408)
		(width 0.14732)
		(layer "In2.Cu")
		(net "P5E_CPU1_PE4_TX_DP<0>")
	)
	(segment
		(start 66.553842 -319.569084)
		(end 63.438532 -320.85915)
		(width 0.14732)
		(layer "In2.Cu")
		(net "P5E_CPU1_PE4_TX_DP<0>")
	)
	(segment
		(start 58.24728 -339.349588)
		(end 58.471562 -360.893614)
		(width 0.14732)
		(layer "In2.Cu")
		(net "P5E_CPU1_PE4_TX_DP<0>")
	)
	(segment
		(start 89.483692 -286.961326)
		(end 89.468706 -286.969962)
		(width 0.0889)
		(layer "In2.Cu")
		(net "P5E_CPU1_PE4_TX_DP<0>")
	)
	(segment
		(start 88.537542 -288.592768)
		(end 88.528652 -288.597848)
		(width 0.0889)
		(layer "In2.Cu")
		(net "P5E_CPU1_PE4_TX_DP<0>")
	)
	(segment
		(start 57.425844 -373.649748)
		(end 51.150774 -396.35938)
		(width 0.14732)
		(layer "In2.Cu")
		(net "P5E_CPU1_PE4_TX_DP<0>")
	)
	(segment
		(start 50.822098 -398.016222)
		(end 50.668936 -398.102836)
		(width 0.14732)
		(layer "In2.Cu")
		(net "P5E_CPU1_PE4_TX_DP<0>")
	)
	(segment
		(start 88.392254 -289.466274)
		(end 88.392254 -289.488372)
		(width 0.0889)
		(layer "In2.Cu")
		(net "P5E_CPU1_PE4_TX_DP<0>")
	)
	(segment
		(start 50.668936 -398.102836)
		(end 50.080418 -400.232626)
		(width 0.14732)
		(layer "In2.Cu")
		(net "P5E_CPU1_PE4_TX_DP<0>")
	)
	(segment
		(start 90.134694 -286.475424)
		(end 89.97823 -286.204406)
		(width 0.0889)
		(layer "In2.Cu")
		(net "P5E_CPU1_PE4_TX_DP<0>")
	)
	(segment
		(start 89.760298 -286.466788)
		(end 89.760298 -286.475424)
		(width 0.0889)
		(layer "In2.Cu")
		(net "P5E_CPU1_PE4_TX_DP<0>")
	)
	(segment
		(start 88.392254 -290.411408)
		(end 85.010498 -293.793164)
		(width 0.14732)
		(layer "In2.Cu")
		(net "P5E_CPU1_PE4_TX_DP<0>")
	)
	(segment
		(start 58.525918 -324.841362)
		(end 58.289444 -325.412354)
		(width 0.14732)
		(layer "In2.Cu")
		(net "P5E_CPU1_PE4_TX_DP<0>")
	)
	(segment
		(start 85.010498 -293.793164)
		(end 77.058266 -309.06466)
		(width 0.14732)
		(layer "In2.Cu")
		(net "P5E_CPU1_PE4_TX_DP<0>")
	)
	(segment
		(start 88.820244 -288.103056)
		(end 88.820244 -288.11728)
		(width 0.0889)
		(layer "In2.Cu")
		(net "P5E_CPU1_PE4_TX_DP<0>")
	)
	(segment
		(start 88.350344 -289.424364)
		(end 88.392254 -289.466274)
		(width 0.0889)
		(layer "In2.Cu")
		(net "P5E_CPU1_PE4_TX_DP<0>")
	)
	(segment
		(start 88.350344 -288.907728)
		(end 88.350344 -289.424364)
		(width 0.0889)
		(layer "In2.Cu")
		(net "P5E_CPU1_PE4_TX_DP<0>")
	)
	(segment
		(start 89.97823 -286.204406)
		(end 89.900252 -286.183578)
		(width 0.0889)
		(layer "In2.Cu")
		(net "P5E_CPU1_PE4_TX_DP<0>")
	)
	(segment
		(start 49.894998 -406.70988)
		(end 50.189638 -407.00452)
		(width 0.14732)
		(layer "In2.Cu")
		(net "P5E_CPU1_PE4_TX_DP<0>")
	)
	(segment
		(start 51.237642 -396.512542)
		(end 51.121056 -396.933928)
		(width 0.14732)
		(layer "In2.Cu")
		(net "P5E_CPU1_PE4_TX_DP<0>")
	)
	(segment
		(start 50.93843 -397.594836)
		(end 50.822098 -398.016222)
		(width 0.14732)
		(layer "In2.Cu")
		(net "P5E_CPU1_PE4_TX_DP<0>")
	)
	(segment
		(start 50.967894 -397.020796)
		(end 50.851562 -397.441674)
		(width 0.14732)
		(layer "In2.Cu")
		(net "P5E_CPU1_PE4_TX_DP<0>")
	)
	(segment
		(start 58.471562 -360.893614)
		(end 57.429908 -373.601488)
		(width 0.14732)
		(layer "In2.Cu")
		(net "P5E_CPU1_PE4_TX_DP<0>")
	)
	(segment
		(start 57.429908 -373.601488)
		(end 57.425844 -373.648478)
		(width 0.14732)
		(layer "In2.Cu")
		(net "P5E_CPU1_PE4_TX_DP<0>")
	)
	(segment
		(start 58.039 -333.720948)
		(end 58.24728 -339.349588)
		(width 0.14732)
		(layer "In2.Cu")
		(net "P5E_CPU1_PE4_TX_DP<0>")
	)
	(segment
		(start 60.633864 -322.73367)
		(end 58.525918 -324.841362)
		(width 0.14732)
		(layer "In2.Cu")
		(net "P5E_CPU1_PE4_TX_DP<0>")
	)
	(segment
		(start 50.080418 -400.232626)
		(end 50.080418 -405.231346)
		(width 0.14732)
		(layer "In2.Cu")
		(net "P5E_CPU1_PE4_TX_DP<0>")
	)
	(segment
		(start 89.007696 -287.778698)
		(end 88.998806 -287.783778)
		(width 0.0889)
		(layer "In2.Cu")
		(net "P5E_CPU1_PE4_TX_DP<0>")
	)
	(segment
		(start 63.438532 -320.85915)
		(end 60.633864 -322.73367)
		(width 0.14732)
		(layer "In2.Cu")
		(net "P5E_CPU1_PE4_TX_DP<0>")
	)
	(segment
		(start 57.425844 -373.648478)
		(end 57.425844 -373.649748)
		(width 0.14732)
		(layer "In2.Cu")
		(net "P5E_CPU1_PE4_TX_DP<0>")
	)
	(segment
		(start 58.289444 -325.412354)
		(end 58.121042 -326.305672)
		(width 0.14732)
		(layer "In2.Cu")
		(net "P5E_CPU1_PE4_TX_DP<0>")
	)
	(segment
		(start 50.851562 -397.441674)
		(end 50.93843 -397.594836)
		(width 0.14732)
		(layer "In2.Cu")
		(net "P5E_CPU1_PE4_TX_DP<0>")
	)
	(segment
		(start 58.121042 -326.305672)
		(end 58.039 -333.720948)
		(width 0.14732)
		(layer "In2.Cu")
		(net "P5E_CPU1_PE4_TX_DP<0>")
	)
	(arc
		(start 89.290144 -287.299146)
		(mid 89.212033 -287.576095)
		(end 89.007696 -287.778698)
		(width 0.0889)
		(layer "In2.Cu")
		(net "P5E_CPU1_PE4_TX_DP<0>")
	)
	(arc
		(start 88.998806 -287.783778)
		(mid 88.867892 -287.920138)
		(end 88.820244 -288.103056)
		(width 0.0889)
		(layer "In2.Cu")
		(net "P5E_CPU1_PE4_TX_DP<0>")
	)
	(arc
		(start 89.468706 -286.969962)
		(mid 89.337792 -287.106322)
		(end 89.290144 -287.28924)
		(width 0.0889)
		(layer "In2.Cu")
		(net "P5E_CPU1_PE4_TX_DP<0>")
	)
	(arc
		(start 89.900252 -286.183578)
		(mid 89.798931 -286.309699)
		(end 89.760298 -286.466788)
		(width 0.0889)
		(layer "In2.Cu")
		(net "P5E_CPU1_PE4_TX_DP<0>")
	)
	(arc
		(start 88.528652 -288.597848)
		(mid 88.400142 -288.73015)
		(end 88.350344 -288.907728)
		(width 0.0889)
		(layer "In2.Cu")
		(net "P5E_CPU1_PE4_TX_DP<0>")
	)
	(arc
		(start 88.820244 -288.11728)
		(mid 88.741025 -288.391965)
		(end 88.537542 -288.592768)
		(width 0.0889)
		(layer "In2.Cu")
		(net "P5E_CPU1_PE4_TX_DP<0>")
	)
	(arc
		(start 89.760298 -286.475424)
		(mid 89.686307 -286.75499)
		(end 89.483692 -286.961326)
		(width 0.0889)
		(layer "In2.Cu")
		(net "P5E_CPU1_PE4_TX_DP<0>")
	)
	(segment
		(start 98.123248 -285.125414)
		(end 98.123248 -285.6611)
		(width 0.13208)
		(layer "F.Cu")
		(net "P5E_CPU1_PE4_TX_DN<9>")
	)
	(segment
		(start 77.20076 -407.310082)
		(end 76.895198 -407.00452)
		(width 0.13208)
		(layer "F.Cu")
		(net "P5E_CPU1_PE4_TX_DN<9>")
	)
	(segment
		(start 76.869798 -408.250644)
		(end 76.87437 -408.250644)
		(width 0.13208)
		(layer "F.Cu")
		(net "P5E_CPU1_PE4_TX_DN<9>")
	)
	(segment
		(start 76.87437 -408.250644)
		(end 77.20076 -407.924254)
		(width 0.13208)
		(layer "F.Cu")
		(net "P5E_CPU1_PE4_TX_DN<9>")
	)
	(segment
		(start 77.20076 -407.924254)
		(end 77.20076 -407.310082)
		(width 0.13208)
		(layer "F.Cu")
		(net "P5E_CPU1_PE4_TX_DN<9>")
	)
	(segment
		(start 98.123248 -285.6611)
		(end 98.122994 -285.661354)
		(width 0.13208)
		(layer "F.Cu")
		(net "P5E_CPU1_PE4_TX_DN<9>")
	)
	(segment
		(start 96.660208 -290.739068)
		(end 96.660208 -290.761166)
		(width 0.0889)
		(layer "In2.Cu")
		(net "P5E_CPU1_PE4_TX_DN<9>")
	)
	(segment
		(start 77.375258 -405.117554)
		(end 77.189838 -405.302974)
		(width 0.14732)
		(layer "In2.Cu")
		(net "P5E_CPU1_PE4_TX_DN<9>")
	)
	(segment
		(start 77.189838 -406.70988)
		(end 76.895198 -407.00452)
		(width 0.14732)
		(layer "In2.Cu")
		(net "P5E_CPU1_PE4_TX_DN<9>")
	)
	(segment
		(start 77.156818 -397.62303)
		(end 77.21346 -397.986758)
		(width 0.14732)
		(layer "In2.Cu")
		(net "P5E_CPU1_PE4_TX_DN<9>")
	)
	(segment
		(start 96.660208 -290.761166)
		(end 96.660208 -299.319188)
		(width 0.14732)
		(layer "In2.Cu")
		(net "P5E_CPU1_PE4_TX_DN<9>")
	)
	(segment
		(start 98.122994 -285.661354)
		(end 98.279458 -285.390336)
		(width 0.0889)
		(layer "In2.Cu")
		(net "P5E_CPU1_PE4_TX_DN<9>")
	)
	(segment
		(start 97.379282 -287.608518)
		(end 97.370392 -287.613598)
		(width 0.0889)
		(layer "In2.Cu")
		(net "P5E_CPU1_PE4_TX_DN<9>")
	)
	(segment
		(start 97.088198 -288.087562)
		(end 97.088198 -288.103056)
		(width 0.0889)
		(layer "In2.Cu")
		(net "P5E_CPU1_PE4_TX_DN<9>")
	)
	(segment
		(start 97.087944 -289.752024)
		(end 97.087944 -290.096194)
		(width 0.0889)
		(layer "In2.Cu")
		(net "P5E_CPU1_PE4_TX_DN<9>")
	)
	(segment
		(start 98.027744 -286.456882)
		(end 98.027744 -286.48406)
		(width 0.0889)
		(layer "In2.Cu")
		(net "P5E_CPU1_PE4_TX_DN<9>")
	)
	(segment
		(start 77.056742 -396.982696)
		(end 76.940156 -397.142462)
		(width 0.14732)
		(layer "In2.Cu")
		(net "P5E_CPU1_PE4_TX_DN<9>")
	)
	(segment
		(start 77.313536 -398.626838)
		(end 77.375258 -399.023586)
		(width 0.14732)
		(layer "In2.Cu")
		(net "P5E_CPU1_PE4_TX_DN<9>")
	)
	(segment
		(start 98.279458 -285.390336)
		(end 98.35769 -285.369508)
		(width 0.0889)
		(layer "In2.Cu")
		(net "P5E_CPU1_PE4_TX_DN<9>")
	)
	(segment
		(start 76.940156 -397.142462)
		(end 76.997052 -397.506444)
		(width 0.14732)
		(layer "In2.Cu")
		(net "P5E_CPU1_PE4_TX_DN<9>")
	)
	(segment
		(start 73.363582 -373.31015)
		(end 77.056742 -396.982696)
		(width 0.14732)
		(layer "In2.Cu")
		(net "P5E_CPU1_PE4_TX_DN<9>")
	)
	(segment
		(start 95.476314 -302.176942)
		(end 70.58533 -327.068688)
		(width 0.14732)
		(layer "In2.Cu")
		(net "P5E_CPU1_PE4_TX_DN<9>")
	)
	(segment
		(start 96.702118 -290.697158)
		(end 96.660208 -290.739068)
		(width 0.0889)
		(layer "In2.Cu")
		(net "P5E_CPU1_PE4_TX_DN<9>")
	)
	(segment
		(start 77.21346 -397.986758)
		(end 77.096874 -398.14627)
		(width 0.14732)
		(layer "In2.Cu")
		(net "P5E_CPU1_PE4_TX_DN<9>")
	)
	(segment
		(start 98.319082 -285.980632)
		(end 98.310192 -285.985712)
		(width 0.0889)
		(layer "In2.Cu")
		(net "P5E_CPU1_PE4_TX_DN<9>")
	)
	(segment
		(start 96.618298 -288.898584)
		(end 96.618298 -289.114738)
		(width 0.0889)
		(layer "In2.Cu")
		(net "P5E_CPU1_PE4_TX_DN<9>")
	)
	(segment
		(start 96.660208 -299.319188)
		(end 95.476314 -302.176942)
		(width 0.14732)
		(layer "In2.Cu")
		(net "P5E_CPU1_PE4_TX_DN<9>")
	)
	(segment
		(start 77.189838 -405.302974)
		(end 77.189838 -406.70988)
		(width 0.14732)
		(layer "In2.Cu")
		(net "P5E_CPU1_PE4_TX_DN<9>")
	)
	(segment
		(start 77.15377 -398.510506)
		(end 77.313536 -398.626838)
		(width 0.14732)
		(layer "In2.Cu")
		(net "P5E_CPU1_PE4_TX_DN<9>")
	)
	(segment
		(start 67.656964 -334.138778)
		(end 67.46367 -335.340198)
		(width 0.14732)
		(layer "In2.Cu")
		(net "P5E_CPU1_PE4_TX_DN<9>")
	)
	(segment
		(start 76.997052 -397.506444)
		(end 77.156818 -397.62303)
		(width 0.14732)
		(layer "In2.Cu")
		(net "P5E_CPU1_PE4_TX_DN<9>")
	)
	(segment
		(start 67.46367 -335.340198)
		(end 67.837304 -349.734124)
		(width 0.14732)
		(layer "In2.Cu")
		(net "P5E_CPU1_PE4_TX_DN<9>")
	)
	(segment
		(start 96.702118 -290.48202)
		(end 96.702118 -290.697158)
		(width 0.0889)
		(layer "In2.Cu")
		(net "P5E_CPU1_PE4_TX_DN<9>")
	)
	(segment
		(start 77.375258 -399.023586)
		(end 77.375258 -405.117554)
		(width 0.14732)
		(layer "In2.Cu")
		(net "P5E_CPU1_PE4_TX_DN<9>")
	)
	(segment
		(start 70.58533 -327.068688)
		(end 67.656964 -334.138778)
		(width 0.14732)
		(layer "In2.Cu")
		(net "P5E_CPU1_PE4_TX_DN<9>")
	)
	(segment
		(start 97.840546 -286.799782)
		(end 97.83445 -286.803338)
		(width 0.0889)
		(layer "In2.Cu")
		(net "P5E_CPU1_PE4_TX_DN<9>")
	)
	(segment
		(start 67.837304 -349.734124)
		(end 73.363582 -373.31015)
		(width 0.14732)
		(layer "In2.Cu")
		(net "P5E_CPU1_PE4_TX_DN<9>")
	)
	(segment
		(start 97.087944 -290.096194)
		(end 96.702118 -290.48202)
		(width 0.0889)
		(layer "In2.Cu")
		(net "P5E_CPU1_PE4_TX_DN<9>")
	)
	(segment
		(start 77.096874 -398.14627)
		(end 77.15377 -398.510506)
		(width 0.14732)
		(layer "In2.Cu")
		(net "P5E_CPU1_PE4_TX_DN<9>")
	)
	(segment
		(start 96.909636 -288.422334)
		(end 96.900746 -288.427414)
		(width 0.0889)
		(layer "In2.Cu")
		(net "P5E_CPU1_PE4_TX_DN<9>")
	)
	(arc
		(start 98.310192 -285.985712)
		(mid 98.107906 -286.184693)
		(end 98.027744 -286.456882)
		(width 0.0889)
		(layer "In2.Cu")
		(net "P5E_CPU1_PE4_TX_DN<9>")
	)
	(arc
		(start 96.618298 -289.114738)
		(mid 96.729636 -289.307638)
		(end 96.903794 -289.446462)
		(width 0.0889)
		(layer "In2.Cu")
		(net "P5E_CPU1_PE4_TX_DN<9>")
	)
	(arc
		(start 98.027744 -286.48406)
		(mid 97.975474 -286.666425)
		(end 97.840546 -286.799782)
		(width 0.0889)
		(layer "In2.Cu")
		(net "P5E_CPU1_PE4_TX_DN<9>")
	)
	(arc
		(start 97.557844 -287.28924)
		(mid 97.510165 -287.47214)
		(end 97.379282 -287.608518)
		(width 0.0889)
		(layer "In2.Cu")
		(net "P5E_CPU1_PE4_TX_DN<9>")
	)
	(arc
		(start 97.088198 -288.103056)
		(mid 97.040519 -288.285956)
		(end 96.909636 -288.422334)
		(width 0.0889)
		(layer "In2.Cu")
		(net "P5E_CPU1_PE4_TX_DN<9>")
	)
	(arc
		(start 98.35769 -285.369508)
		(mid 98.458519 -285.494984)
		(end 98.49739 -285.651194)
		(width 0.0889)
		(layer "In2.Cu")
		(net "P5E_CPU1_PE4_TX_DN<9>")
	)
	(arc
		(start 98.49739 -285.651194)
		(mid 98.497564 -285.662497)
		(end 98.49739 -285.6738)
		(width 0.0889)
		(layer "In2.Cu")
		(net "P5E_CPU1_PE4_TX_DN<9>")
	)
	(arc
		(start 97.370392 -287.613598)
		(mid 97.167569 -287.813829)
		(end 97.088198 -288.087562)
		(width 0.0889)
		(layer "In2.Cu")
		(net "P5E_CPU1_PE4_TX_DN<9>")
	)
	(arc
		(start 97.83445 -286.803338)
		(mid 97.631863 -287.009689)
		(end 97.557844 -287.28924)
		(width 0.0889)
		(layer "In2.Cu")
		(net "P5E_CPU1_PE4_TX_DN<9>")
	)
	(arc
		(start 98.49739 -285.6738)
		(mid 98.44684 -285.849638)
		(end 98.319082 -285.980632)
		(width 0.0889)
		(layer "In2.Cu")
		(net "P5E_CPU1_PE4_TX_DN<9>")
	)
	(arc
		(start 96.903794 -289.446462)
		(mid 97.038402 -289.573623)
		(end 97.087944 -289.752024)
		(width 0.0889)
		(layer "In2.Cu")
		(net "P5E_CPU1_PE4_TX_DN<9>")
	)
	(arc
		(start 96.900746 -288.427414)
		(mid 96.69846 -288.626395)
		(end 96.618298 -288.898584)
		(width 0.0889)
		(layer "In2.Cu")
		(net "P5E_CPU1_PE4_TX_DN<9>")
	)
	(segment
		(start 74.13752 -407.924254)
		(end 74.13752 -407.310082)
		(width 0.13208)
		(layer "F.Cu")
		(net "P5E_CPU1_PE4_TX_DN<8>")
	)
	(segment
		(start 97.183448 -285.125414)
		(end 97.183448 -285.6611)
		(width 0.13208)
		(layer "F.Cu")
		(net "P5E_CPU1_PE4_TX_DN<8>")
	)
	(segment
		(start 73.81113 -408.250644)
		(end 74.13752 -407.924254)
		(width 0.13208)
		(layer "F.Cu")
		(net "P5E_CPU1_PE4_TX_DN<8>")
	)
	(segment
		(start 74.13752 -407.310082)
		(end 73.831958 -407.00452)
		(width 0.13208)
		(layer "F.Cu")
		(net "P5E_CPU1_PE4_TX_DN<8>")
	)
	(segment
		(start 73.806558 -408.250644)
		(end 73.81113 -408.250644)
		(width 0.13208)
		(layer "F.Cu")
		(net "P5E_CPU1_PE4_TX_DN<8>")
	)
	(segment
		(start 97.183448 -285.6611)
		(end 97.183194 -285.661354)
		(width 0.13208)
		(layer "F.Cu")
		(net "P5E_CPU1_PE4_TX_DN<8>")
	)
	(segment
		(start 71.54291 -373.23141)
		(end 73.979532 -395.443964)
		(width 0.14732)
		(layer "In2.Cu")
		(net "P5E_CPU1_PE4_TX_DN<8>")
	)
	(segment
		(start 73.979786 -395.443964)
		(end 74.312018 -398.474184)
		(width 0.14732)
		(layer "In2.Cu")
		(net "P5E_CPU1_PE4_TX_DN<8>")
	)
	(segment
		(start 66.50228 -334.861154)
		(end 66.869818 -349.732346)
		(width 0.14732)
		(layer "In2.Cu")
		(net "P5E_CPU1_PE4_TX_DN<8>")
	)
	(segment
		(start 95.728282 -299.064172)
		(end 94.638368 -301.695612)
		(width 0.14732)
		(layer "In2.Cu")
		(net "P5E_CPU1_PE4_TX_DN<8>")
	)
	(segment
		(start 96.148398 -289.645344)
		(end 96.148398 -290.25977)
		(width 0.0889)
		(layer "In2.Cu")
		(net "P5E_CPU1_PE4_TX_DN<8>")
	)
	(segment
		(start 95.728282 -290.76015)
		(end 95.728282 -290.782248)
		(width 0.0889)
		(layer "In2.Cu")
		(net "P5E_CPU1_PE4_TX_DN<8>")
	)
	(segment
		(start 74.126598 -405.302974)
		(end 74.126598 -406.70988)
		(width 0.14732)
		(layer "In2.Cu")
		(net "P5E_CPU1_PE4_TX_DN<8>")
	)
	(segment
		(start 96.148652 -288.103056)
		(end 96.148652 -288.118042)
		(width 0.0889)
		(layer "In2.Cu")
		(net "P5E_CPU1_PE4_TX_DN<8>")
	)
	(segment
		(start 96.910652 -286.794194)
		(end 96.889824 -286.806386)
		(width 0.0889)
		(layer "In2.Cu")
		(net "P5E_CPU1_PE4_TX_DN<8>")
	)
	(segment
		(start 96.431354 -287.613598)
		(end 96.420686 -287.619948)
		(width 0.0889)
		(layer "In2.Cu")
		(net "P5E_CPU1_PE4_TX_DN<8>")
	)
	(segment
		(start 97.339658 -285.932372)
		(end 97.315528 -286.021526)
		(width 0.0889)
		(layer "In2.Cu")
		(net "P5E_CPU1_PE4_TX_DN<8>")
	)
	(segment
		(start 95.770192 -290.71824)
		(end 95.728282 -290.76015)
		(width 0.0889)
		(layer "In2.Cu")
		(net "P5E_CPU1_PE4_TX_DN<8>")
	)
	(segment
		(start 74.312018 -398.474184)
		(end 74.312018 -405.117554)
		(width 0.14732)
		(layer "In2.Cu")
		(net "P5E_CPU1_PE4_TX_DN<8>")
	)
	(segment
		(start 96.148398 -290.25977)
		(end 95.770192 -290.470336)
		(width 0.0889)
		(layer "In2.Cu")
		(net "P5E_CPU1_PE4_TX_DN<8>")
	)
	(segment
		(start 95.961454 -288.427668)
		(end 95.950786 -288.434018)
		(width 0.0889)
		(layer "In2.Cu")
		(net "P5E_CPU1_PE4_TX_DN<8>")
	)
	(segment
		(start 95.770192 -290.470336)
		(end 95.770192 -290.71824)
		(width 0.0889)
		(layer "In2.Cu")
		(net "P5E_CPU1_PE4_TX_DN<8>")
	)
	(segment
		(start 95.728282 -290.782248)
		(end 95.728282 -299.064172)
		(width 0.14732)
		(layer "In2.Cu")
		(net "P5E_CPU1_PE4_TX_DN<8>")
	)
	(segment
		(start 97.183194 -285.661354)
		(end 97.339658 -285.932372)
		(width 0.0889)
		(layer "In2.Cu")
		(net "P5E_CPU1_PE4_TX_DN<8>")
	)
	(segment
		(start 73.979532 -395.443964)
		(end 73.979786 -395.443964)
		(width 0.14732)
		(layer "In2.Cu")
		(net "P5E_CPU1_PE4_TX_DN<8>")
	)
	(segment
		(start 74.312018 -405.117554)
		(end 74.126598 -405.302974)
		(width 0.14732)
		(layer "In2.Cu")
		(net "P5E_CPU1_PE4_TX_DN<8>")
	)
	(segment
		(start 96.618298 -287.28924)
		(end 96.618298 -287.301686)
		(width 0.0889)
		(layer "In2.Cu")
		(net "P5E_CPU1_PE4_TX_DN<8>")
	)
	(segment
		(start 69.722238 -326.612758)
		(end 66.645282 -334.041496)
		(width 0.14732)
		(layer "In2.Cu")
		(net "P5E_CPU1_PE4_TX_DN<8>")
	)
	(segment
		(start 74.126598 -406.70988)
		(end 73.831958 -407.00452)
		(width 0.14732)
		(layer "In2.Cu")
		(net "P5E_CPU1_PE4_TX_DN<8>")
	)
	(segment
		(start 97.315528 -286.021526)
		(end 97.316036 -286.021272)
		(width 0.0889)
		(layer "In2.Cu")
		(net "P5E_CPU1_PE4_TX_DN<8>")
	)
	(segment
		(start 94.638368 -301.695612)
		(end 69.722238 -326.612758)
		(width 0.14732)
		(layer "In2.Cu")
		(net "P5E_CPU1_PE4_TX_DN<8>")
	)
	(segment
		(start 95.678752 -288.917126)
		(end 95.678752 -289.113976)
		(width 0.0889)
		(layer "In2.Cu")
		(net "P5E_CPU1_PE4_TX_DN<8>")
	)
	(segment
		(start 66.869818 -349.732346)
		(end 71.54291 -373.23141)
		(width 0.14732)
		(layer "In2.Cu")
		(net "P5E_CPU1_PE4_TX_DN<8>")
	)
	(segment
		(start 66.645282 -334.041496)
		(end 66.50228 -334.861154)
		(width 0.14732)
		(layer "In2.Cu")
		(net "P5E_CPU1_PE4_TX_DN<8>")
	)
	(arc
		(start 95.678752 -289.113976)
		(mid 95.789982 -289.30718)
		(end 95.964248 -289.446208)
		(width 0.0889)
		(layer "In2.Cu")
		(net "P5E_CPU1_PE4_TX_DN<8>")
	)
	(arc
		(start 97.29851 -286.034734)
		(mid 97.143349 -286.231209)
		(end 97.088198 -286.475424)
		(width 0.0889)
		(layer "In2.Cu")
		(net "P5E_CPU1_PE4_TX_DN<8>")
	)
	(arc
		(start 96.889824 -286.806386)
		(mid 96.690855 -287.012266)
		(end 96.618298 -287.28924)
		(width 0.0889)
		(layer "In2.Cu")
		(net "P5E_CPU1_PE4_TX_DN<8>")
	)
	(arc
		(start 97.088198 -286.475424)
		(mid 97.040815 -286.65786)
		(end 96.910652 -286.794194)
		(width 0.0889)
		(layer "In2.Cu")
		(net "P5E_CPU1_PE4_TX_DN<8>")
	)
	(arc
		(start 97.316036 -286.021272)
		(mid 97.307206 -286.027915)
		(end 97.29851 -286.034734)
		(width 0.0889)
		(layer "In2.Cu")
		(net "P5E_CPU1_PE4_TX_DN<8>")
	)
	(arc
		(start 96.148652 -288.118042)
		(mid 96.094847 -288.296917)
		(end 95.961454 -288.427668)
		(width 0.0889)
		(layer "In2.Cu")
		(net "P5E_CPU1_PE4_TX_DN<8>")
	)
	(arc
		(start 95.964248 -289.446208)
		(mid 96.073351 -289.530034)
		(end 96.148398 -289.645344)
		(width 0.0889)
		(layer "In2.Cu")
		(net "P5E_CPU1_PE4_TX_DN<8>")
	)
	(arc
		(start 96.618298 -287.301686)
		(mid 96.565156 -287.481816)
		(end 96.431354 -287.613598)
		(width 0.0889)
		(layer "In2.Cu")
		(net "P5E_CPU1_PE4_TX_DN<8>")
	)
	(arc
		(start 95.950786 -288.434018)
		(mid 95.751402 -288.639898)
		(end 95.678752 -288.917126)
		(width 0.0889)
		(layer "In2.Cu")
		(net "P5E_CPU1_PE4_TX_DN<8>")
	)
	(arc
		(start 96.420686 -287.619948)
		(mid 96.221302 -287.825828)
		(end 96.148652 -288.103056)
		(width 0.0889)
		(layer "In2.Cu")
		(net "P5E_CPU1_PE4_TX_DN<8>")
	)
	(segment
		(start 70.74789 -408.250644)
		(end 71.07428 -407.924254)
		(width 0.13208)
		(layer "F.Cu")
		(net "P5E_CPU1_PE4_TX_DN<7>")
	)
	(segment
		(start 96.243648 -285.125414)
		(end 96.243648 -285.6611)
		(width 0.13208)
		(layer "F.Cu")
		(net "P5E_CPU1_PE4_TX_DN<7>")
	)
	(segment
		(start 70.743318 -408.250644)
		(end 70.74789 -408.250644)
		(width 0.13208)
		(layer "F.Cu")
		(net "P5E_CPU1_PE4_TX_DN<7>")
	)
	(segment
		(start 71.07428 -407.310082)
		(end 70.768718 -407.00452)
		(width 0.13208)
		(layer "F.Cu")
		(net "P5E_CPU1_PE4_TX_DN<7>")
	)
	(segment
		(start 96.243648 -285.6611)
		(end 96.243394 -285.661354)
		(width 0.13208)
		(layer "F.Cu")
		(net "P5E_CPU1_PE4_TX_DN<7>")
	)
	(segment
		(start 71.07428 -407.924254)
		(end 71.07428 -407.310082)
		(width 0.13208)
		(layer "F.Cu")
		(net "P5E_CPU1_PE4_TX_DN<7>")
	)
	(segment
		(start 95.208344 -289.645852)
		(end 95.208598 -289.64636)
		(width 0.0889)
		(layer "In2.Cu")
		(net "P5E_CPU1_PE4_TX_DN<7>")
	)
	(segment
		(start 96.148144 -286.456882)
		(end 96.148144 -286.48406)
		(width 0.0889)
		(layer "In2.Cu")
		(net "P5E_CPU1_PE4_TX_DN<7>")
	)
	(segment
		(start 94.827852 -290.571936)
		(end 94.827852 -290.787074)
		(width 0.0889)
		(layer "In2.Cu")
		(net "P5E_CPU1_PE4_TX_DN<7>")
	)
	(segment
		(start 65.793112 -349.310198)
		(end 69.653404 -373.102632)
		(width 0.14732)
		(layer "In2.Cu")
		(net "P5E_CPU1_PE4_TX_DN<7>")
	)
	(segment
		(start 95.960946 -286.799782)
		(end 95.960184 -286.80029)
		(width 0.0889)
		(layer "In2.Cu")
		(net "P5E_CPU1_PE4_TX_DN<7>")
	)
	(segment
		(start 71.063358 -406.70988)
		(end 70.768718 -407.00452)
		(width 0.14732)
		(layer "In2.Cu")
		(net "P5E_CPU1_PE4_TX_DN<7>")
	)
	(segment
		(start 70.969632 -395.851888)
		(end 70.993254 -396.21968)
		(width 0.14732)
		(layer "In2.Cu")
		(net "P5E_CPU1_PE4_TX_DN<7>")
	)
	(segment
		(start 65.769236 -349.113856)
		(end 65.793112 -349.310198)
		(width 0.14732)
		(layer "In2.Cu")
		(net "P5E_CPU1_PE4_TX_DN<7>")
	)
	(segment
		(start 94.785942 -290.828984)
		(end 94.785942 -290.851082)
		(width 0.0889)
		(layer "In2.Cu")
		(net "P5E_CPU1_PE4_TX_DN<7>")
	)
	(segment
		(start 71.248778 -398.021048)
		(end 71.248778 -405.117554)
		(width 0.14732)
		(layer "In2.Cu")
		(net "P5E_CPU1_PE4_TX_DN<7>")
	)
	(segment
		(start 69.653404 -373.102632)
		(end 71.100188 -395.703552)
		(width 0.14732)
		(layer "In2.Cu")
		(net "P5E_CPU1_PE4_TX_DN<7>")
	)
	(segment
		(start 95.208598 -289.64636)
		(end 95.208598 -290.19119)
		(width 0.0889)
		(layer "In2.Cu")
		(net "P5E_CPU1_PE4_TX_DN<7>")
	)
	(segment
		(start 94.827852 -290.787074)
		(end 94.785942 -290.828984)
		(width 0.0889)
		(layer "In2.Cu")
		(net "P5E_CPU1_PE4_TX_DN<7>")
	)
	(segment
		(start 96.439482 -285.980632)
		(end 96.430592 -285.985712)
		(width 0.0889)
		(layer "In2.Cu")
		(net "P5E_CPU1_PE4_TX_DN<7>")
	)
	(segment
		(start 95.208598 -290.19119)
		(end 94.827852 -290.571936)
		(width 0.0889)
		(layer "In2.Cu")
		(net "P5E_CPU1_PE4_TX_DN<7>")
	)
	(segment
		(start 71.100188 -395.703552)
		(end 70.969632 -395.851888)
		(width 0.14732)
		(layer "In2.Cu")
		(net "P5E_CPU1_PE4_TX_DN<7>")
	)
	(segment
		(start 95.208598 -288.087562)
		(end 95.208598 -288.103056)
		(width 0.0889)
		(layer "In2.Cu")
		(net "P5E_CPU1_PE4_TX_DN<7>")
	)
	(segment
		(start 95.021908 -288.426906)
		(end 95.021146 -288.427414)
		(width 0.0889)
		(layer "In2.Cu")
		(net "P5E_CPU1_PE4_TX_DN<7>")
	)
	(segment
		(start 93.763338 -301.254414)
		(end 68.906644 -326.111108)
		(width 0.14732)
		(layer "In2.Cu")
		(net "P5E_CPU1_PE4_TX_DN<7>")
	)
	(segment
		(start 71.206614 -397.36395)
		(end 71.248778 -398.021048)
		(width 0.14732)
		(layer "In2.Cu")
		(net "P5E_CPU1_PE4_TX_DN<7>")
	)
	(segment
		(start 94.785942 -290.851082)
		(end 94.785942 -298.786296)
		(width 0.14732)
		(layer "In2.Cu")
		(net "P5E_CPU1_PE4_TX_DN<7>")
	)
	(segment
		(start 95.030036 -288.422334)
		(end 95.021908 -288.426906)
		(width 0.0889)
		(layer "In2.Cu")
		(net "P5E_CPU1_PE4_TX_DN<7>")
	)
	(segment
		(start 68.906644 -326.111108)
		(end 65.605152 -334.082136)
		(width 0.14732)
		(layer "In2.Cu")
		(net "P5E_CPU1_PE4_TX_DN<7>")
	)
	(segment
		(start 95.491808 -287.61309)
		(end 95.490792 -287.613598)
		(width 0.0889)
		(layer "In2.Cu")
		(net "P5E_CPU1_PE4_TX_DN<7>")
	)
	(segment
		(start 71.058278 -397.233902)
		(end 71.206614 -397.36395)
		(width 0.14732)
		(layer "In2.Cu")
		(net "P5E_CPU1_PE4_TX_DN<7>")
	)
	(segment
		(start 71.034656 -396.86611)
		(end 71.058278 -397.233902)
		(width 0.14732)
		(layer "In2.Cu")
		(net "P5E_CPU1_PE4_TX_DN<7>")
	)
	(segment
		(start 94.738698 -288.898584)
		(end 94.738698 -289.114738)
		(width 0.0889)
		(layer "In2.Cu")
		(net "P5E_CPU1_PE4_TX_DN<7>")
	)
	(segment
		(start 70.993254 -396.21968)
		(end 71.141844 -396.350236)
		(width 0.14732)
		(layer "In2.Cu")
		(net "P5E_CPU1_PE4_TX_DN<7>")
	)
	(segment
		(start 65.605152 -334.082136)
		(end 65.353438 -335.219294)
		(width 0.14732)
		(layer "In2.Cu")
		(net "P5E_CPU1_PE4_TX_DN<7>")
	)
	(segment
		(start 96.399858 -285.390336)
		(end 96.47809 -285.369508)
		(width 0.0889)
		(layer "In2.Cu")
		(net "P5E_CPU1_PE4_TX_DN<7>")
	)
	(segment
		(start 95.499682 -287.608518)
		(end 95.491808 -287.61309)
		(width 0.0889)
		(layer "In2.Cu")
		(net "P5E_CPU1_PE4_TX_DN<7>")
	)
	(segment
		(start 65.353438 -335.219294)
		(end 65.769236 -349.113856)
		(width 0.14732)
		(layer "In2.Cu")
		(net "P5E_CPU1_PE4_TX_DN<7>")
	)
	(segment
		(start 95.960184 -286.80029)
		(end 95.95485 -286.803338)
		(width 0.0889)
		(layer "In2.Cu")
		(net "P5E_CPU1_PE4_TX_DN<7>")
	)
	(segment
		(start 96.243394 -285.661354)
		(end 96.399858 -285.390336)
		(width 0.0889)
		(layer "In2.Cu")
		(net "P5E_CPU1_PE4_TX_DN<7>")
	)
	(segment
		(start 94.785942 -298.786296)
		(end 93.763338 -301.254414)
		(width 0.14732)
		(layer "In2.Cu")
		(net "P5E_CPU1_PE4_TX_DN<7>")
	)
	(segment
		(start 71.063358 -405.302974)
		(end 71.063358 -406.70988)
		(width 0.14732)
		(layer "In2.Cu")
		(net "P5E_CPU1_PE4_TX_DN<7>")
	)
	(segment
		(start 71.248778 -405.117554)
		(end 71.063358 -405.302974)
		(width 0.14732)
		(layer "In2.Cu")
		(net "P5E_CPU1_PE4_TX_DN<7>")
	)
	(segment
		(start 71.165212 -396.717774)
		(end 71.034656 -396.86611)
		(width 0.14732)
		(layer "In2.Cu")
		(net "P5E_CPU1_PE4_TX_DN<7>")
	)
	(segment
		(start 71.141844 -396.350236)
		(end 71.165212 -396.717774)
		(width 0.14732)
		(layer "In2.Cu")
		(net "P5E_CPU1_PE4_TX_DN<7>")
	)
	(arc
		(start 95.208598 -288.103056)
		(mid 95.160919 -288.285956)
		(end 95.030036 -288.422334)
		(width 0.0889)
		(layer "In2.Cu")
		(net "P5E_CPU1_PE4_TX_DN<7>")
	)
	(arc
		(start 95.021146 -288.427414)
		(mid 94.81886 -288.626395)
		(end 94.738698 -288.898584)
		(width 0.0889)
		(layer "In2.Cu")
		(net "P5E_CPU1_PE4_TX_DN<7>")
	)
	(arc
		(start 96.148144 -286.48406)
		(mid 96.095874 -286.666425)
		(end 95.960946 -286.799782)
		(width 0.0889)
		(layer "In2.Cu")
		(net "P5E_CPU1_PE4_TX_DN<7>")
	)
	(arc
		(start 95.490792 -287.613598)
		(mid 95.287969 -287.813829)
		(end 95.208598 -288.087562)
		(width 0.0889)
		(layer "In2.Cu")
		(net "P5E_CPU1_PE4_TX_DN<7>")
	)
	(arc
		(start 96.47809 -285.369508)
		(mid 96.578919 -285.494984)
		(end 96.61779 -285.651194)
		(width 0.0889)
		(layer "In2.Cu")
		(net "P5E_CPU1_PE4_TX_DN<7>")
	)
	(arc
		(start 96.61779 -285.651194)
		(mid 96.617964 -285.662497)
		(end 96.61779 -285.6738)
		(width 0.0889)
		(layer "In2.Cu")
		(net "P5E_CPU1_PE4_TX_DN<7>")
	)
	(arc
		(start 96.61779 -285.6738)
		(mid 96.56724 -285.849638)
		(end 96.439482 -285.980632)
		(width 0.0889)
		(layer "In2.Cu")
		(net "P5E_CPU1_PE4_TX_DN<7>")
	)
	(arc
		(start 95.024194 -289.446462)
		(mid 95.133341 -289.53039)
		(end 95.208344 -289.645852)
		(width 0.0889)
		(layer "In2.Cu")
		(net "P5E_CPU1_PE4_TX_DN<7>")
	)
	(arc
		(start 95.95485 -286.803338)
		(mid 95.752263 -287.009689)
		(end 95.678244 -287.28924)
		(width 0.0889)
		(layer "In2.Cu")
		(net "P5E_CPU1_PE4_TX_DN<7>")
	)
	(arc
		(start 94.738698 -289.114738)
		(mid 94.850036 -289.307638)
		(end 95.024194 -289.446462)
		(width 0.0889)
		(layer "In2.Cu")
		(net "P5E_CPU1_PE4_TX_DN<7>")
	)
	(arc
		(start 95.678244 -287.28924)
		(mid 95.630565 -287.47214)
		(end 95.499682 -287.608518)
		(width 0.0889)
		(layer "In2.Cu")
		(net "P5E_CPU1_PE4_TX_DN<7>")
	)
	(arc
		(start 96.430592 -285.985712)
		(mid 96.228306 -286.184693)
		(end 96.148144 -286.456882)
		(width 0.0889)
		(layer "In2.Cu")
		(net "P5E_CPU1_PE4_TX_DN<7>")
	)
	(segment
		(start 68.01104 -407.310082)
		(end 67.705478 -407.00452)
		(width 0.13208)
		(layer "F.Cu")
		(net "P5E_CPU1_PE4_TX_DN<6>")
	)
	(segment
		(start 95.303848 -285.125414)
		(end 95.303848 -285.6611)
		(width 0.13208)
		(layer "F.Cu")
		(net "P5E_CPU1_PE4_TX_DN<6>")
	)
	(segment
		(start 67.68465 -408.250644)
		(end 68.01104 -407.924254)
		(width 0.13208)
		(layer "F.Cu")
		(net "P5E_CPU1_PE4_TX_DN<6>")
	)
	(segment
		(start 67.680078 -408.250644)
		(end 67.68465 -408.250644)
		(width 0.13208)
		(layer "F.Cu")
		(net "P5E_CPU1_PE4_TX_DN<6>")
	)
	(segment
		(start 68.01104 -407.924254)
		(end 68.01104 -407.310082)
		(width 0.13208)
		(layer "F.Cu")
		(net "P5E_CPU1_PE4_TX_DN<6>")
	)
	(segment
		(start 95.303848 -285.6611)
		(end 95.303594 -285.661354)
		(width 0.13208)
		(layer "F.Cu")
		(net "P5E_CPU1_PE4_TX_DN<6>")
	)
	(segment
		(start 94.551754 -287.613598)
		(end 94.541086 -287.619948)
		(width 0.0889)
		(layer "In2.Cu")
		(net "P5E_CPU1_PE4_TX_DN<6>")
	)
	(segment
		(start 94.268798 -289.64509)
		(end 94.268798 -290.220146)
		(width 0.0889)
		(layer "In2.Cu")
		(net "P5E_CPU1_PE4_TX_DN<6>")
	)
	(segment
		(start 68.185538 -405.117554)
		(end 68.000118 -405.302974)
		(width 0.14732)
		(layer "In2.Cu")
		(net "P5E_CPU1_PE4_TX_DN<6>")
	)
	(segment
		(start 94.269052 -288.103056)
		(end 94.269052 -288.118042)
		(width 0.0889)
		(layer "In2.Cu")
		(net "P5E_CPU1_PE4_TX_DN<6>")
	)
	(segment
		(start 93.856302 -298.490386)
		(end 92.903548 -300.79061)
		(width 0.14732)
		(layer "In2.Cu")
		(net "P5E_CPU1_PE4_TX_DN<6>")
	)
	(segment
		(start 94.738698 -287.28924)
		(end 94.738698 -287.301686)
		(width 0.0889)
		(layer "In2.Cu")
		(net "P5E_CPU1_PE4_TX_DN<6>")
	)
	(segment
		(start 95.460058 -285.932372)
		(end 95.435928 -286.021526)
		(width 0.0889)
		(layer "In2.Cu")
		(net "P5E_CPU1_PE4_TX_DN<6>")
	)
	(segment
		(start 94.268798 -290.220146)
		(end 93.898212 -290.590732)
		(width 0.0889)
		(layer "In2.Cu")
		(net "P5E_CPU1_PE4_TX_DN<6>")
	)
	(segment
		(start 93.856302 -291.060124)
		(end 93.856302 -298.490386)
		(width 0.14732)
		(layer "In2.Cu")
		(net "P5E_CPU1_PE4_TX_DN<6>")
	)
	(segment
		(start 95.435928 -286.021526)
		(end 95.436436 -286.021272)
		(width 0.0889)
		(layer "In2.Cu")
		(net "P5E_CPU1_PE4_TX_DN<6>")
	)
	(segment
		(start 67.92976 -373.492268)
		(end 68.185538 -400.59483)
		(width 0.14732)
		(layer "In2.Cu")
		(net "P5E_CPU1_PE4_TX_DN<6>")
	)
	(segment
		(start 64.63919 -346.124276)
		(end 64.833754 -349.162878)
		(width 0.14732)
		(layer "In2.Cu")
		(net "P5E_CPU1_PE4_TX_DN<6>")
	)
	(segment
		(start 68.000118 -405.302974)
		(end 68.000118 -406.70988)
		(width 0.14732)
		(layer "In2.Cu")
		(net "P5E_CPU1_PE4_TX_DN<6>")
	)
	(segment
		(start 64.669416 -333.616808)
		(end 64.365886 -335.311242)
		(width 0.14732)
		(layer "In2.Cu")
		(net "P5E_CPU1_PE4_TX_DN<6>")
	)
	(segment
		(start 95.013272 -286.804608)
		(end 95.007684 -286.80791)
		(width 0.0889)
		(layer "In2.Cu")
		(net "P5E_CPU1_PE4_TX_DN<6>")
	)
	(segment
		(start 64.365886 -335.313528)
		(end 64.63919 -346.124276)
		(width 0.14732)
		(layer "In2.Cu")
		(net "P5E_CPU1_PE4_TX_DN<6>")
	)
	(segment
		(start 68.185538 -400.59483)
		(end 68.185538 -405.117554)
		(width 0.14732)
		(layer "In2.Cu")
		(net "P5E_CPU1_PE4_TX_DN<6>")
	)
	(segment
		(start 92.903548 -300.79061)
		(end 67.916044 -325.778114)
		(width 0.14732)
		(layer "In2.Cu")
		(net "P5E_CPU1_PE4_TX_DN<6>")
	)
	(segment
		(start 95.022162 -286.799528)
		(end 95.013272 -286.804608)
		(width 0.0889)
		(layer "In2.Cu")
		(net "P5E_CPU1_PE4_TX_DN<6>")
	)
	(segment
		(start 93.856302 -291.038026)
		(end 93.856302 -291.060124)
		(width 0.0889)
		(layer "In2.Cu")
		(net "P5E_CPU1_PE4_TX_DN<6>")
	)
	(segment
		(start 93.898212 -290.996116)
		(end 93.856302 -291.038026)
		(width 0.0889)
		(layer "In2.Cu")
		(net "P5E_CPU1_PE4_TX_DN<6>")
	)
	(segment
		(start 93.898212 -290.590732)
		(end 93.898212 -290.996116)
		(width 0.0889)
		(layer "In2.Cu")
		(net "P5E_CPU1_PE4_TX_DN<6>")
	)
	(segment
		(start 64.833754 -349.162878)
		(end 67.92976 -373.492268)
		(width 0.14732)
		(layer "In2.Cu")
		(net "P5E_CPU1_PE4_TX_DN<6>")
	)
	(segment
		(start 94.084648 -289.446208)
		(end 94.084902 -289.446208)
		(width 0.0889)
		(layer "In2.Cu")
		(net "P5E_CPU1_PE4_TX_DN<6>")
	)
	(segment
		(start 95.030798 -286.794194)
		(end 95.022162 -286.799528)
		(width 0.0889)
		(layer "In2.Cu")
		(net "P5E_CPU1_PE4_TX_DN<6>")
	)
	(segment
		(start 67.916044 -325.778114)
		(end 64.669416 -333.616808)
		(width 0.14732)
		(layer "In2.Cu")
		(net "P5E_CPU1_PE4_TX_DN<6>")
	)
	(segment
		(start 68.000118 -406.70988)
		(end 67.705478 -407.00452)
		(width 0.14732)
		(layer "In2.Cu")
		(net "P5E_CPU1_PE4_TX_DN<6>")
	)
	(segment
		(start 64.365886 -335.311242)
		(end 64.365886 -335.313528)
		(width 0.14732)
		(layer "In2.Cu")
		(net "P5E_CPU1_PE4_TX_DN<6>")
	)
	(segment
		(start 93.799152 -288.917126)
		(end 93.799152 -289.113976)
		(width 0.0889)
		(layer "In2.Cu")
		(net "P5E_CPU1_PE4_TX_DN<6>")
	)
	(segment
		(start 94.081854 -288.427668)
		(end 94.071186 -288.434018)
		(width 0.0889)
		(layer "In2.Cu")
		(net "P5E_CPU1_PE4_TX_DN<6>")
	)
	(segment
		(start 95.303594 -285.661354)
		(end 95.460058 -285.932372)
		(width 0.0889)
		(layer "In2.Cu")
		(net "P5E_CPU1_PE4_TX_DN<6>")
	)
	(arc
		(start 95.41891 -286.034734)
		(mid 95.263749 -286.231209)
		(end 95.208598 -286.475424)
		(width 0.0889)
		(layer "In2.Cu")
		(net "P5E_CPU1_PE4_TX_DN<6>")
	)
	(arc
		(start 95.436436 -286.021272)
		(mid 95.427608 -286.027918)
		(end 95.41891 -286.034734)
		(width 0.0889)
		(layer "In2.Cu")
		(net "P5E_CPU1_PE4_TX_DN<6>")
	)
	(arc
		(start 94.738698 -287.301686)
		(mid 94.685556 -287.481816)
		(end 94.551754 -287.613598)
		(width 0.0889)
		(layer "In2.Cu")
		(net "P5E_CPU1_PE4_TX_DN<6>")
	)
	(arc
		(start 94.269052 -288.118042)
		(mid 94.215247 -288.296917)
		(end 94.081854 -288.427668)
		(width 0.0889)
		(layer "In2.Cu")
		(net "P5E_CPU1_PE4_TX_DN<6>")
	)
	(arc
		(start 93.799152 -289.113976)
		(mid 93.910382 -289.30718)
		(end 94.084648 -289.446208)
		(width 0.0889)
		(layer "In2.Cu")
		(net "P5E_CPU1_PE4_TX_DN<6>")
	)
	(arc
		(start 95.007684 -286.80791)
		(mid 94.810508 -287.013545)
		(end 94.738698 -287.28924)
		(width 0.0889)
		(layer "In2.Cu")
		(net "P5E_CPU1_PE4_TX_DN<6>")
	)
	(arc
		(start 94.541086 -287.619948)
		(mid 94.341702 -287.825828)
		(end 94.269052 -288.103056)
		(width 0.0889)
		(layer "In2.Cu")
		(net "P5E_CPU1_PE4_TX_DN<6>")
	)
	(arc
		(start 94.084902 -289.446208)
		(mid 94.19379 -289.529978)
		(end 94.268798 -289.64509)
		(width 0.0889)
		(layer "In2.Cu")
		(net "P5E_CPU1_PE4_TX_DN<6>")
	)
	(arc
		(start 94.071186 -288.434018)
		(mid 93.871802 -288.639898)
		(end 93.799152 -288.917126)
		(width 0.0889)
		(layer "In2.Cu")
		(net "P5E_CPU1_PE4_TX_DN<6>")
	)
	(arc
		(start 95.208598 -286.475424)
		(mid 95.161142 -286.657925)
		(end 95.030798 -286.794194)
		(width 0.0889)
		(layer "In2.Cu")
		(net "P5E_CPU1_PE4_TX_DN<6>")
	)
	(segment
		(start 94.364048 -285.125414)
		(end 94.364048 -285.6611)
		(width 0.13208)
		(layer "F.Cu")
		(net "P5E_CPU1_PE4_TX_DN<5>")
	)
	(segment
		(start 64.9478 -407.924254)
		(end 64.9478 -407.310082)
		(width 0.13208)
		(layer "F.Cu")
		(net "P5E_CPU1_PE4_TX_DN<5>")
	)
	(segment
		(start 64.616838 -408.250644)
		(end 64.62141 -408.250644)
		(width 0.13208)
		(layer "F.Cu")
		(net "P5E_CPU1_PE4_TX_DN<5>")
	)
	(segment
		(start 64.9478 -407.310082)
		(end 64.642238 -407.00452)
		(width 0.13208)
		(layer "F.Cu")
		(net "P5E_CPU1_PE4_TX_DN<5>")
	)
	(segment
		(start 94.364048 -285.6611)
		(end 94.363794 -285.661354)
		(width 0.13208)
		(layer "F.Cu")
		(net "P5E_CPU1_PE4_TX_DN<5>")
	)
	(segment
		(start 64.62141 -408.250644)
		(end 64.9478 -407.924254)
		(width 0.13208)
		(layer "F.Cu")
		(net "P5E_CPU1_PE4_TX_DN<5>")
	)
	(segment
		(start 91.902788 -300.467268)
		(end 66.88582 -325.484236)
		(width 0.14732)
		(layer "In2.Cu")
		(net "P5E_CPU1_PE4_TX_DN<5>")
	)
	(segment
		(start 65.271904 -396.547086)
		(end 65.142872 -396.66672)
		(width 0.14732)
		(layer "In2.Cu")
		(net "P5E_CPU1_PE4_TX_DN<5>")
	)
	(segment
		(start 63.67272 -347.126052)
		(end 66.117216 -373.634762)
		(width 0.14732)
		(layer "In2.Cu")
		(net "P5E_CPU1_PE4_TX_DN<5>")
	)
	(segment
		(start 94.363794 -285.661354)
		(end 94.520258 -285.390336)
		(width 0.0889)
		(layer "In2.Cu")
		(net "P5E_CPU1_PE4_TX_DN<5>")
	)
	(segment
		(start 92.926662 -290.830508)
		(end 92.926662 -290.852606)
		(width 0.0889)
		(layer "In2.Cu")
		(net "P5E_CPU1_PE4_TX_DN<5>")
	)
	(segment
		(start 94.268544 -286.456882)
		(end 94.268544 -286.48406)
		(width 0.0889)
		(layer "In2.Cu")
		(net "P5E_CPU1_PE4_TX_DN<5>")
	)
	(segment
		(start 65.204848 -398.35455)
		(end 65.122298 -400.594576)
		(width 0.14732)
		(layer "In2.Cu")
		(net "P5E_CPU1_PE4_TX_DN<5>")
	)
	(segment
		(start 92.859098 -288.898584)
		(end 92.859098 -289.114738)
		(width 0.0889)
		(layer "In2.Cu")
		(net "P5E_CPU1_PE4_TX_DN<5>")
	)
	(segment
		(start 65.122298 -400.594576)
		(end 65.122298 -405.117554)
		(width 0.14732)
		(layer "In2.Cu")
		(net "P5E_CPU1_PE4_TX_DN<5>")
	)
	(segment
		(start 93.32849 -290.213796)
		(end 92.968572 -290.573714)
		(width 0.0889)
		(layer "In2.Cu")
		(net "P5E_CPU1_PE4_TX_DN<5>")
	)
	(segment
		(start 94.559882 -285.980632)
		(end 94.550992 -285.985712)
		(width 0.0889)
		(layer "In2.Cu")
		(net "P5E_CPU1_PE4_TX_DN<5>")
	)
	(segment
		(start 65.246504 -397.232632)
		(end 65.230502 -397.669004)
		(width 0.14732)
		(layer "In2.Cu")
		(net "P5E_CPU1_PE4_TX_DN<5>")
	)
	(segment
		(start 92.859098 -289.114738)
		(end 92.880434 -289.175698)
		(width 0.0889)
		(layer "In2.Cu")
		(net "P5E_CPU1_PE4_TX_DN<5>")
	)
	(segment
		(start 65.122298 -405.117554)
		(end 64.936878 -405.302974)
		(width 0.14732)
		(layer "In2.Cu")
		(net "P5E_CPU1_PE4_TX_DN<5>")
	)
	(segment
		(start 65.271396 -396.546832)
		(end 65.271904 -396.547086)
		(width 0.14732)
		(layer "In2.Cu")
		(net "P5E_CPU1_PE4_TX_DN<5>")
	)
	(segment
		(start 93.087444 -289.416236)
		(end 93.144594 -289.446462)
		(width 0.0889)
		(layer "In2.Cu")
		(net "P5E_CPU1_PE4_TX_DN<5>")
	)
	(segment
		(start 63.733426 -333.095092)
		(end 63.246254 -335.303368)
		(width 0.14732)
		(layer "In2.Cu")
		(net "P5E_CPU1_PE4_TX_DN<5>")
	)
	(segment
		(start 94.080584 -286.80029)
		(end 94.07525 -286.803338)
		(width 0.0889)
		(layer "In2.Cu")
		(net "P5E_CPU1_PE4_TX_DN<5>")
	)
	(segment
		(start 65.230502 -397.669004)
		(end 65.101216 -397.788638)
		(width 0.14732)
		(layer "In2.Cu")
		(net "P5E_CPU1_PE4_TX_DN<5>")
	)
	(segment
		(start 64.936878 -406.70988)
		(end 64.642238 -407.00452)
		(width 0.14732)
		(layer "In2.Cu")
		(net "P5E_CPU1_PE4_TX_DN<5>")
	)
	(segment
		(start 93.612208 -287.61309)
		(end 93.611192 -287.613598)
		(width 0.0889)
		(layer "In2.Cu")
		(net "P5E_CPU1_PE4_TX_DN<5>")
	)
	(segment
		(start 92.968572 -290.788598)
		(end 92.926662 -290.830508)
		(width 0.0889)
		(layer "In2.Cu")
		(net "P5E_CPU1_PE4_TX_DN<5>")
	)
	(segment
		(start 63.246254 -337.91525)
		(end 63.67272 -347.126052)
		(width 0.14732)
		(layer "In2.Cu")
		(net "P5E_CPU1_PE4_TX_DN<5>")
	)
	(segment
		(start 94.081346 -286.799782)
		(end 94.080584 -286.80029)
		(width 0.0889)
		(layer "In2.Cu")
		(net "P5E_CPU1_PE4_TX_DN<5>")
	)
	(segment
		(start 92.926662 -290.852606)
		(end 92.926662 -297.995594)
		(width 0.14732)
		(layer "In2.Cu")
		(net "P5E_CPU1_PE4_TX_DN<5>")
	)
	(segment
		(start 65.126616 -397.1036)
		(end 65.246504 -397.232632)
		(width 0.14732)
		(layer "In2.Cu")
		(net "P5E_CPU1_PE4_TX_DN<5>")
	)
	(segment
		(start 93.150436 -288.422334)
		(end 93.141546 -288.427414)
		(width 0.0889)
		(layer "In2.Cu")
		(net "P5E_CPU1_PE4_TX_DN<5>")
	)
	(segment
		(start 93.328998 -288.087562)
		(end 93.328998 -288.103056)
		(width 0.0889)
		(layer "In2.Cu")
		(net "P5E_CPU1_PE4_TX_DN<5>")
	)
	(segment
		(start 92.968572 -290.573714)
		(end 92.968572 -290.788598)
		(width 0.0889)
		(layer "In2.Cu")
		(net "P5E_CPU1_PE4_TX_DN<5>")
	)
	(segment
		(start 65.142872 -396.66672)
		(end 65.126616 -397.1036)
		(width 0.14732)
		(layer "In2.Cu")
		(net "P5E_CPU1_PE4_TX_DN<5>")
	)
	(segment
		(start 92.926662 -297.995594)
		(end 91.902788 -300.467268)
		(width 0.14732)
		(layer "In2.Cu")
		(net "P5E_CPU1_PE4_TX_DN<5>")
	)
	(segment
		(start 93.620082 -287.608518)
		(end 93.612208 -287.61309)
		(width 0.0889)
		(layer "In2.Cu")
		(net "P5E_CPU1_PE4_TX_DN<5>")
	)
	(segment
		(start 66.117216 -373.634762)
		(end 65.271396 -396.546832)
		(width 0.14732)
		(layer "In2.Cu")
		(net "P5E_CPU1_PE4_TX_DN<5>")
	)
	(segment
		(start 66.88582 -325.484236)
		(end 63.733426 -333.095092)
		(width 0.14732)
		(layer "In2.Cu")
		(net "P5E_CPU1_PE4_TX_DN<5>")
	)
	(segment
		(start 94.520258 -285.390336)
		(end 94.59849 -285.369508)
		(width 0.0889)
		(layer "In2.Cu")
		(net "P5E_CPU1_PE4_TX_DN<5>")
	)
	(segment
		(start 65.101216 -397.788638)
		(end 65.08496 -398.225518)
		(width 0.14732)
		(layer "In2.Cu")
		(net "P5E_CPU1_PE4_TX_DN<5>")
	)
	(segment
		(start 93.32849 -289.751008)
		(end 93.32849 -290.213796)
		(width 0.0889)
		(layer "In2.Cu")
		(net "P5E_CPU1_PE4_TX_DN<5>")
	)
	(segment
		(start 64.936878 -405.302974)
		(end 64.936878 -406.70988)
		(width 0.14732)
		(layer "In2.Cu")
		(net "P5E_CPU1_PE4_TX_DN<5>")
	)
	(segment
		(start 63.246254 -335.303368)
		(end 63.246254 -337.91525)
		(width 0.14732)
		(layer "In2.Cu")
		(net "P5E_CPU1_PE4_TX_DN<5>")
	)
	(segment
		(start 65.08496 -398.225518)
		(end 65.204848 -398.35455)
		(width 0.14732)
		(layer "In2.Cu")
		(net "P5E_CPU1_PE4_TX_DN<5>")
	)
	(arc
		(start 94.550992 -285.985712)
		(mid 94.348706 -286.184693)
		(end 94.268544 -286.456882)
		(width 0.0889)
		(layer "In2.Cu")
		(net "P5E_CPU1_PE4_TX_DN<5>")
	)
	(arc
		(start 93.328998 -288.103056)
		(mid 93.281319 -288.285956)
		(end 93.150436 -288.422334)
		(width 0.0889)
		(layer "In2.Cu")
		(net "P5E_CPU1_PE4_TX_DN<5>")
	)
	(arc
		(start 93.141546 -288.427414)
		(mid 92.93926 -288.626395)
		(end 92.859098 -288.898584)
		(width 0.0889)
		(layer "In2.Cu")
		(net "P5E_CPU1_PE4_TX_DN<5>")
	)
	(arc
		(start 94.07525 -286.803338)
		(mid 93.872663 -287.009689)
		(end 93.798644 -287.28924)
		(width 0.0889)
		(layer "In2.Cu")
		(net "P5E_CPU1_PE4_TX_DN<5>")
	)
	(arc
		(start 94.268544 -286.48406)
		(mid 94.216274 -286.666425)
		(end 94.081346 -286.799782)
		(width 0.0889)
		(layer "In2.Cu")
		(net "P5E_CPU1_PE4_TX_DN<5>")
	)
	(arc
		(start 92.880434 -289.175698)
		(mid 92.961168 -289.315564)
		(end 93.087444 -289.416236)
		(width 0.0889)
		(layer "In2.Cu")
		(net "P5E_CPU1_PE4_TX_DN<5>")
	)
	(arc
		(start 93.144594 -289.446462)
		(mid 93.278842 -289.573196)
		(end 93.32849 -289.751008)
		(width 0.0889)
		(layer "In2.Cu")
		(net "P5E_CPU1_PE4_TX_DN<5>")
	)
	(arc
		(start 94.73819 -285.6738)
		(mid 94.68764 -285.849638)
		(end 94.559882 -285.980632)
		(width 0.0889)
		(layer "In2.Cu")
		(net "P5E_CPU1_PE4_TX_DN<5>")
	)
	(arc
		(start 93.798644 -287.28924)
		(mid 93.750965 -287.47214)
		(end 93.620082 -287.608518)
		(width 0.0889)
		(layer "In2.Cu")
		(net "P5E_CPU1_PE4_TX_DN<5>")
	)
	(arc
		(start 94.73819 -285.651194)
		(mid 94.738364 -285.662497)
		(end 94.73819 -285.6738)
		(width 0.0889)
		(layer "In2.Cu")
		(net "P5E_CPU1_PE4_TX_DN<5>")
	)
	(arc
		(start 93.611192 -287.613598)
		(mid 93.408369 -287.813829)
		(end 93.328998 -288.087562)
		(width 0.0889)
		(layer "In2.Cu")
		(net "P5E_CPU1_PE4_TX_DN<5>")
	)
	(arc
		(start 94.59849 -285.369508)
		(mid 94.699319 -285.494984)
		(end 94.73819 -285.651194)
		(width 0.0889)
		(layer "In2.Cu")
		(net "P5E_CPU1_PE4_TX_DN<5>")
	)
	(segment
		(start 61.88456 -407.924254)
		(end 61.88456 -407.310082)
		(width 0.13208)
		(layer "F.Cu")
		(net "P5E_CPU1_PE4_TX_DN<4>")
	)
	(segment
		(start 61.55817 -408.250644)
		(end 61.88456 -407.924254)
		(width 0.13208)
		(layer "F.Cu")
		(net "P5E_CPU1_PE4_TX_DN<4>")
	)
	(segment
		(start 61.553598 -408.250644)
		(end 61.55817 -408.250644)
		(width 0.13208)
		(layer "F.Cu")
		(net "P5E_CPU1_PE4_TX_DN<4>")
	)
	(segment
		(start 93.424248 -285.125414)
		(end 93.424248 -285.6611)
		(width 0.13208)
		(layer "F.Cu")
		(net "P5E_CPU1_PE4_TX_DN<4>")
	)
	(segment
		(start 93.424248 -285.6611)
		(end 93.423994 -285.661354)
		(width 0.13208)
		(layer "F.Cu")
		(net "P5E_CPU1_PE4_TX_DN<4>")
	)
	(segment
		(start 61.88456 -407.310082)
		(end 61.578998 -407.00452)
		(width 0.13208)
		(layer "F.Cu")
		(net "P5E_CPU1_PE4_TX_DN<4>")
	)
	(segment
		(start 62.462918 -333.741268)
		(end 62.221364 -335.646522)
		(width 0.14732)
		(layer "In2.Cu")
		(net "P5E_CPU1_PE4_TX_DN<4>")
	)
	(segment
		(start 93.328744 -286.475424)
		(end 93.328998 -286.475424)
		(width 0.0889)
		(layer "In2.Cu")
		(net "P5E_CPU1_PE4_TX_DN<4>")
	)
	(segment
		(start 91.983306 -291.95903)
		(end 88.365076 -295.577006)
		(width 0.14732)
		(layer "In2.Cu")
		(net "P5E_CPU1_PE4_TX_DN<4>")
	)
	(segment
		(start 92.389452 -289.752786)
		(end 92.389452 -290.27501)
		(width 0.0889)
		(layer "In2.Cu")
		(net "P5E_CPU1_PE4_TX_DN<4>")
	)
	(segment
		(start 92.389198 -288.09315)
		(end 92.389198 -288.103056)
		(width 0.0889)
		(layer "In2.Cu")
		(net "P5E_CPU1_PE4_TX_DN<4>")
	)
	(segment
		(start 93.423994 -285.661354)
		(end 93.580458 -285.932372)
		(width 0.0889)
		(layer "In2.Cu")
		(net "P5E_CPU1_PE4_TX_DN<4>")
	)
	(segment
		(start 93.328744 -286.4612)
		(end 93.328744 -286.475424)
		(width 0.0889)
		(layer "In2.Cu")
		(net "P5E_CPU1_PE4_TX_DN<4>")
	)
	(segment
		(start 63.000128 -350.194372)
		(end 64.351662 -373.601488)
		(width 0.14732)
		(layer "In2.Cu")
		(net "P5E_CPU1_PE4_TX_DN<4>")
	)
	(segment
		(start 66.117978 -324.912228)
		(end 65.341754 -326.495918)
		(width 0.14732)
		(layer "In2.Cu")
		(net "P5E_CPU1_PE4_TX_DN<4>")
	)
	(segment
		(start 80.668876 -310.361076)
		(end 66.117978 -324.912228)
		(width 0.14732)
		(layer "In2.Cu")
		(net "P5E_CPU1_PE4_TX_DN<4>")
	)
	(segment
		(start 92.025216 -290.85413)
		(end 91.983306 -290.89604)
		(width 0.0889)
		(layer "In2.Cu")
		(net "P5E_CPU1_PE4_TX_DN<4>")
	)
	(segment
		(start 93.150436 -286.794702)
		(end 93.13545 -286.803338)
		(width 0.0889)
		(layer "In2.Cu")
		(net "P5E_CPU1_PE4_TX_DN<4>")
	)
	(segment
		(start 92.858844 -287.28924)
		(end 92.858844 -287.297876)
		(width 0.0889)
		(layer "In2.Cu")
		(net "P5E_CPU1_PE4_TX_DN<4>")
	)
	(segment
		(start 62.059058 -400.18335)
		(end 62.059058 -405.117554)
		(width 0.14732)
		(layer "In2.Cu")
		(net "P5E_CPU1_PE4_TX_DN<4>")
	)
	(segment
		(start 61.873638 -406.70988)
		(end 61.578998 -407.00452)
		(width 0.14732)
		(layer "In2.Cu")
		(net "P5E_CPU1_PE4_TX_DN<4>")
	)
	(segment
		(start 88.365076 -295.577006)
		(end 80.668876 -310.361076)
		(width 0.14732)
		(layer "In2.Cu")
		(net "P5E_CPU1_PE4_TX_DN<4>")
	)
	(segment
		(start 92.025216 -290.639246)
		(end 92.025216 -290.85413)
		(width 0.0889)
		(layer "In2.Cu")
		(net "P5E_CPU1_PE4_TX_DN<4>")
	)
	(segment
		(start 91.919298 -288.898584)
		(end 91.919298 -289.114738)
		(width 0.0889)
		(layer "In2.Cu")
		(net "P5E_CPU1_PE4_TX_DN<4>")
	)
	(segment
		(start 62.059058 -405.117554)
		(end 61.873638 -405.302974)
		(width 0.14732)
		(layer "In2.Cu")
		(net "P5E_CPU1_PE4_TX_DN<4>")
	)
	(segment
		(start 64.351408 -373.601742)
		(end 64.351662 -373.60479)
		(width 0.14732)
		(layer "In2.Cu")
		(net "P5E_CPU1_PE4_TX_DN<4>")
	)
	(segment
		(start 91.983306 -290.918138)
		(end 91.983306 -291.95903)
		(width 0.14732)
		(layer "In2.Cu")
		(net "P5E_CPU1_PE4_TX_DN<4>")
	)
	(segment
		(start 64.350138 -373.797576)
		(end 62.059058 -400.18335)
		(width 0.14732)
		(layer "In2.Cu")
		(net "P5E_CPU1_PE4_TX_DN<4>")
	)
	(segment
		(start 65.341754 -326.495918)
		(end 63.550292 -330.72324)
		(width 0.14732)
		(layer "In2.Cu")
		(net "P5E_CPU1_PE4_TX_DN<4>")
	)
	(segment
		(start 91.983306 -290.89604)
		(end 91.983306 -290.918138)
		(width 0.0889)
		(layer "In2.Cu")
		(net "P5E_CPU1_PE4_TX_DN<4>")
	)
	(segment
		(start 92.210636 -288.422334)
		(end 92.201746 -288.427414)
		(width 0.0889)
		(layer "In2.Cu")
		(net "P5E_CPU1_PE4_TX_DN<4>")
	)
	(segment
		(start 62.221364 -335.646522)
		(end 62.636654 -346.330778)
		(width 0.14732)
		(layer "In2.Cu")
		(net "P5E_CPU1_PE4_TX_DN<4>")
	)
	(segment
		(start 64.351662 -373.601488)
		(end 64.351408 -373.601742)
		(width 0.14732)
		(layer "In2.Cu")
		(net "P5E_CPU1_PE4_TX_DN<4>")
	)
	(segment
		(start 64.351662 -373.60479)
		(end 64.350138 -373.797576)
		(width 0.14732)
		(layer "In2.Cu")
		(net "P5E_CPU1_PE4_TX_DN<4>")
	)
	(segment
		(start 61.873638 -405.302974)
		(end 61.873638 -406.70988)
		(width 0.14732)
		(layer "In2.Cu")
		(net "P5E_CPU1_PE4_TX_DN<4>")
	)
	(segment
		(start 92.389452 -290.27501)
		(end 92.025216 -290.639246)
		(width 0.0889)
		(layer "In2.Cu")
		(net "P5E_CPU1_PE4_TX_DN<4>")
	)
	(segment
		(start 63.550292 -330.72324)
		(end 62.462918 -333.741268)
		(width 0.14732)
		(layer "In2.Cu")
		(net "P5E_CPU1_PE4_TX_DN<4>")
	)
	(segment
		(start 62.636654 -346.330778)
		(end 63.000128 -350.194372)
		(width 0.14732)
		(layer "In2.Cu")
		(net "P5E_CPU1_PE4_TX_DN<4>")
	)
	(segment
		(start 93.580458 -285.932372)
		(end 93.556328 -286.021526)
		(width 0.0889)
		(layer "In2.Cu")
		(net "P5E_CPU1_PE4_TX_DN<4>")
	)
	(arc
		(start 91.919298 -289.114738)
		(mid 92.030636 -289.307638)
		(end 92.204794 -289.446462)
		(width 0.0889)
		(layer "In2.Cu")
		(net "P5E_CPU1_PE4_TX_DN<4>")
	)
	(arc
		(start 92.858844 -287.297876)
		(mid 92.806574 -287.480241)
		(end 92.671646 -287.613598)
		(width 0.0889)
		(layer "In2.Cu")
		(net "P5E_CPU1_PE4_TX_DN<4>")
	)
	(arc
		(start 92.201746 -288.427414)
		(mid 91.99946 -288.626395)
		(end 91.919298 -288.898584)
		(width 0.0889)
		(layer "In2.Cu")
		(net "P5E_CPU1_PE4_TX_DN<4>")
	)
	(arc
		(start 92.671646 -287.613598)
		(mid 92.467311 -287.816203)
		(end 92.389198 -288.09315)
		(width 0.0889)
		(layer "In2.Cu")
		(net "P5E_CPU1_PE4_TX_DN<4>")
	)
	(arc
		(start 93.556328 -286.021526)
		(mid 93.547885 -286.027924)
		(end 93.539564 -286.03448)
		(width 0.0889)
		(layer "In2.Cu")
		(net "P5E_CPU1_PE4_TX_DN<4>")
	)
	(arc
		(start 92.204794 -289.446462)
		(mid 92.339698 -289.573954)
		(end 92.389452 -289.752786)
		(width 0.0889)
		(layer "In2.Cu")
		(net "P5E_CPU1_PE4_TX_DN<4>")
	)
	(arc
		(start 93.13545 -286.803338)
		(mid 92.932863 -287.009689)
		(end 92.858844 -287.28924)
		(width 0.0889)
		(layer "In2.Cu")
		(net "P5E_CPU1_PE4_TX_DN<4>")
	)
	(arc
		(start 92.389198 -288.103056)
		(mid 92.341519 -288.285956)
		(end 92.210636 -288.422334)
		(width 0.0889)
		(layer "In2.Cu")
		(net "P5E_CPU1_PE4_TX_DN<4>")
	)
	(arc
		(start 93.328998 -286.475424)
		(mid 93.281319 -286.658324)
		(end 93.150436 -286.794702)
		(width 0.0889)
		(layer "In2.Cu")
		(net "P5E_CPU1_PE4_TX_DN<4>")
	)
	(arc
		(start 93.539564 -286.03448)
		(mid 93.387057 -286.224578)
		(end 93.328744 -286.4612)
		(width 0.0889)
		(layer "In2.Cu")
		(net "P5E_CPU1_PE4_TX_DN<4>")
	)
	(segment
		(start 92.484448 -285.6611)
		(end 92.484194 -285.661354)
		(width 0.13208)
		(layer "F.Cu")
		(net "P5E_CPU1_PE4_TX_DN<3>")
	)
	(segment
		(start 58.82132 -407.924254)
		(end 58.82132 -407.310082)
		(width 0.13208)
		(layer "F.Cu")
		(net "P5E_CPU1_PE4_TX_DN<3>")
	)
	(segment
		(start 92.484448 -285.125414)
		(end 92.484448 -285.6611)
		(width 0.13208)
		(layer "F.Cu")
		(net "P5E_CPU1_PE4_TX_DN<3>")
	)
	(segment
		(start 58.490358 -408.250644)
		(end 58.49493 -408.250644)
		(width 0.13208)
		(layer "F.Cu")
		(net "P5E_CPU1_PE4_TX_DN<3>")
	)
	(segment
		(start 58.82132 -407.310082)
		(end 58.515758 -407.00452)
		(width 0.13208)
		(layer "F.Cu")
		(net "P5E_CPU1_PE4_TX_DN<3>")
	)
	(segment
		(start 58.49493 -408.250644)
		(end 58.82132 -407.924254)
		(width 0.13208)
		(layer "F.Cu")
		(net "P5E_CPU1_PE4_TX_DN<3>")
	)
	(segment
		(start 62.146942 -355.321362)
		(end 62.557406 -373.379238)
		(width 0.14732)
		(layer "In2.Cu")
		(net "P5E_CPU1_PE4_TX_DN<3>")
	)
	(segment
		(start 87.420958 -295.092628)
		(end 79.610966 -310.095392)
		(width 0.14732)
		(layer "In2.Cu")
		(net "P5E_CPU1_PE4_TX_DN<3>")
	)
	(segment
		(start 61.1124 -326.132698)
		(end 60.856876 -326.414638)
		(width 0.14732)
		(layer "In2.Cu")
		(net "P5E_CPU1_PE4_TX_DN<3>")
	)
	(segment
		(start 59.161426 -397.985488)
		(end 59.26836 -398.125188)
		(width 0.14732)
		(layer "In2.Cu")
		(net "P5E_CPU1_PE4_TX_DN<3>")
	)
	(segment
		(start 92.484194 -285.661354)
		(end 92.640658 -285.390336)
		(width 0.0889)
		(layer "In2.Cu")
		(net "P5E_CPU1_PE4_TX_DN<3>")
	)
	(segment
		(start 79.610966 -310.095392)
		(end 66.40449 -323.301868)
		(width 0.14732)
		(layer "In2.Cu")
		(net "P5E_CPU1_PE4_TX_DN<3>")
	)
	(segment
		(start 59.367166 -396.438882)
		(end 59.309508 -396.872206)
		(width 0.14732)
		(layer "In2.Cu")
		(net "P5E_CPU1_PE4_TX_DN<3>")
	)
	(segment
		(start 60.856876 -326.414638)
		(end 60.764166 -326.691244)
		(width 0.14732)
		(layer "In2.Cu")
		(net "P5E_CPU1_PE4_TX_DN<3>")
	)
	(segment
		(start 91.051888 -291.461698)
		(end 87.420958 -295.092628)
		(width 0.14732)
		(layer "In2.Cu")
		(net "P5E_CPU1_PE4_TX_DN<3>")
	)
	(segment
		(start 91.728544 -287.615884)
		(end 91.72702 -287.6169)
		(width 0.0889)
		(layer "In2.Cu")
		(net "P5E_CPU1_PE4_TX_DN<3>")
	)
	(segment
		(start 60.764166 -326.691244)
		(end 60.925964 -342.627204)
		(width 0.14732)
		(layer "In2.Cu")
		(net "P5E_CPU1_PE4_TX_DN<3>")
	)
	(segment
		(start 92.719144 -285.368746)
		(end 92.719652 -285.369)
		(width 0.0889)
		(layer "In2.Cu")
		(net "P5E_CPU1_PE4_TX_DN<3>")
	)
	(segment
		(start 59.359038 -397.444976)
		(end 59.219084 -397.552164)
		(width 0.14732)
		(layer "In2.Cu")
		(net "P5E_CPU1_PE4_TX_DN<3>")
	)
	(segment
		(start 66.40449 -323.301868)
		(end 64.152272 -324.807072)
		(width 0.14732)
		(layer "In2.Cu")
		(net "P5E_CPU1_PE4_TX_DN<3>")
	)
	(segment
		(start 91.449398 -290.20389)
		(end 91.093798 -290.41217)
		(width 0.0889)
		(layer "In2.Cu")
		(net "P5E_CPU1_PE4_TX_DN<3>")
	)
	(segment
		(start 58.995818 -405.117554)
		(end 58.810398 -405.302974)
		(width 0.14732)
		(layer "In2.Cu")
		(net "P5E_CPU1_PE4_TX_DN<3>")
	)
	(segment
		(start 91.449652 -288.103056)
		(end 91.449652 -288.114486)
		(width 0.0889)
		(layer "In2.Cu")
		(net "P5E_CPU1_PE4_TX_DN<3>")
	)
	(segment
		(start 92.856304 -285.546546)
		(end 92.858844 -285.680912)
		(width 0.0889)
		(layer "In2.Cu")
		(net "P5E_CPU1_PE4_TX_DN<3>")
	)
	(segment
		(start 91.265502 -289.446208)
		(end 91.325192 -289.477704)
		(width 0.0889)
		(layer "In2.Cu")
		(net "P5E_CPU1_PE4_TX_DN<3>")
	)
	(segment
		(start 91.262454 -288.427668)
		(end 91.251786 -288.434018)
		(width 0.0889)
		(layer "In2.Cu")
		(net "P5E_CPU1_PE4_TX_DN<3>")
	)
	(segment
		(start 91.325192 -289.477704)
		(end 91.449398 -289.683698)
		(width 0.0889)
		(layer "In2.Cu")
		(net "P5E_CPU1_PE4_TX_DN<3>")
	)
	(segment
		(start 58.810398 -406.70988)
		(end 58.515758 -407.00452)
		(width 0.14732)
		(layer "In2.Cu")
		(net "P5E_CPU1_PE4_TX_DN<3>")
	)
	(segment
		(start 59.506866 -396.332202)
		(end 59.367166 -396.438882)
		(width 0.14732)
		(layer "In2.Cu")
		(net "P5E_CPU1_PE4_TX_DN<3>")
	)
	(segment
		(start 91.72702 -287.6169)
		(end 91.72321 -287.618678)
		(width 0.0889)
		(layer "In2.Cu")
		(net "P5E_CPU1_PE4_TX_DN<3>")
	)
	(segment
		(start 91.051888 -290.977066)
		(end 91.051888 -290.999164)
		(width 0.0889)
		(layer "In2.Cu")
		(net "P5E_CPU1_PE4_TX_DN<3>")
	)
	(segment
		(start 90.979752 -288.91738)
		(end 90.979752 -289.113976)
		(width 0.0889)
		(layer "In2.Cu")
		(net "P5E_CPU1_PE4_TX_DN<3>")
	)
	(segment
		(start 59.309508 -396.872206)
		(end 59.416442 -397.011906)
		(width 0.14732)
		(layer "In2.Cu")
		(net "P5E_CPU1_PE4_TX_DN<3>")
	)
	(segment
		(start 59.416442 -397.011906)
		(end 59.359038 -397.444976)
		(width 0.14732)
		(layer "In2.Cu")
		(net "P5E_CPU1_PE4_TX_DN<3>")
	)
	(segment
		(start 91.051888 -290.999164)
		(end 91.051888 -291.461698)
		(width 0.14732)
		(layer "In2.Cu")
		(net "P5E_CPU1_PE4_TX_DN<3>")
	)
	(segment
		(start 59.26836 -398.125188)
		(end 58.995818 -400.177508)
		(width 0.14732)
		(layer "In2.Cu")
		(net "P5E_CPU1_PE4_TX_DN<3>")
	)
	(segment
		(start 91.919552 -287.28924)
		(end 91.919552 -287.297114)
		(width 0.0889)
		(layer "In2.Cu")
		(net "P5E_CPU1_PE4_TX_DN<3>")
	)
	(segment
		(start 91.093798 -290.41217)
		(end 91.093798 -290.935156)
		(width 0.0889)
		(layer "In2.Cu")
		(net "P5E_CPU1_PE4_TX_DN<3>")
	)
	(segment
		(start 92.389452 -286.475678)
		(end 92.389452 -286.481774)
		(width 0.0889)
		(layer "In2.Cu")
		(net "P5E_CPU1_PE4_TX_DN<3>")
	)
	(segment
		(start 64.152272 -324.807072)
		(end 61.274452 -325.999094)
		(width 0.14732)
		(layer "In2.Cu")
		(net "P5E_CPU1_PE4_TX_DN<3>")
	)
	(segment
		(start 62.557406 -373.379238)
		(end 59.506866 -396.332202)
		(width 0.14732)
		(layer "In2.Cu")
		(net "P5E_CPU1_PE4_TX_DN<3>")
	)
	(segment
		(start 91.449398 -289.683698)
		(end 91.449398 -290.20389)
		(width 0.0889)
		(layer "In2.Cu")
		(net "P5E_CPU1_PE4_TX_DN<3>")
	)
	(segment
		(start 91.7321 -287.613852)
		(end 91.728544 -287.615884)
		(width 0.0889)
		(layer "In2.Cu")
		(net "P5E_CPU1_PE4_TX_DN<3>")
	)
	(segment
		(start 59.219084 -397.552164)
		(end 59.161426 -397.985488)
		(width 0.14732)
		(layer "In2.Cu")
		(net "P5E_CPU1_PE4_TX_DN<3>")
	)
	(segment
		(start 92.640658 -285.390336)
		(end 92.71889 -285.369508)
		(width 0.0889)
		(layer "In2.Cu")
		(net "P5E_CPU1_PE4_TX_DN<3>")
	)
	(segment
		(start 58.995818 -400.177508)
		(end 58.995818 -405.117554)
		(width 0.14732)
		(layer "In2.Cu")
		(net "P5E_CPU1_PE4_TX_DN<3>")
	)
	(segment
		(start 92.389706 -286.453326)
		(end 92.389706 -286.453834)
		(width 0.0889)
		(layer "In2.Cu")
		(net "P5E_CPU1_PE4_TX_DN<3>")
	)
	(segment
		(start 92.202254 -286.799782)
		(end 92.191586 -286.806132)
		(width 0.0889)
		(layer "In2.Cu")
		(net "P5E_CPU1_PE4_TX_DN<3>")
	)
	(segment
		(start 92.672154 -285.985966)
		(end 92.661486 -285.992316)
		(width 0.0889)
		(layer "In2.Cu")
		(net "P5E_CPU1_PE4_TX_DN<3>")
	)
	(segment
		(start 61.274452 -325.999094)
		(end 61.1124 -326.132698)
		(width 0.14732)
		(layer "In2.Cu")
		(net "P5E_CPU1_PE4_TX_DN<3>")
	)
	(segment
		(start 60.925964 -342.627204)
		(end 62.146942 -355.321362)
		(width 0.14732)
		(layer "In2.Cu")
		(net "P5E_CPU1_PE4_TX_DN<3>")
	)
	(segment
		(start 92.71889 -285.369508)
		(end 92.719144 -285.368746)
		(width 0.0889)
		(layer "In2.Cu")
		(net "P5E_CPU1_PE4_TX_DN<3>")
	)
	(segment
		(start 91.093798 -290.935156)
		(end 91.051888 -290.977066)
		(width 0.0889)
		(layer "In2.Cu")
		(net "P5E_CPU1_PE4_TX_DN<3>")
	)
	(segment
		(start 92.719652 -285.369)
		(end 92.80017 -285.434024)
		(width 0.0889)
		(layer "In2.Cu")
		(net "P5E_CPU1_PE4_TX_DN<3>")
	)
	(segment
		(start 58.810398 -405.302974)
		(end 58.810398 -406.70988)
		(width 0.14732)
		(layer "In2.Cu")
		(net "P5E_CPU1_PE4_TX_DN<3>")
	)
	(arc
		(start 92.661486 -285.992316)
		(mid 92.467529 -286.1886)
		(end 92.389706 -286.453326)
		(width 0.0889)
		(layer "In2.Cu")
		(net "P5E_CPU1_PE4_TX_DN<3>")
	)
	(arc
		(start 90.980006 -288.895028)
		(mid 90.97977 -288.906203)
		(end 90.979752 -288.91738)
		(width 0.0889)
		(layer "In2.Cu")
		(net "P5E_CPU1_PE4_TX_DN<3>")
	)
	(arc
		(start 91.449652 -288.114486)
		(mid 91.396676 -288.295361)
		(end 91.262454 -288.427668)
		(width 0.0889)
		(layer "In2.Cu")
		(net "P5E_CPU1_PE4_TX_DN<3>")
	)
	(arc
		(start 90.979752 -289.113976)
		(mid 91.091108 -289.307202)
		(end 91.265502 -289.446208)
		(width 0.0889)
		(layer "In2.Cu")
		(net "P5E_CPU1_PE4_TX_DN<3>")
	)
	(arc
		(start 92.389452 -286.481774)
		(mid 92.337675 -286.665395)
		(end 92.202254 -286.799782)
		(width 0.0889)
		(layer "In2.Cu")
		(net "P5E_CPU1_PE4_TX_DN<3>")
	)
	(arc
		(start 92.389706 -286.453834)
		(mid 92.389473 -286.464755)
		(end 92.389452 -286.475678)
		(width 0.0889)
		(layer "In2.Cu")
		(net "P5E_CPU1_PE4_TX_DN<3>")
	)
	(arc
		(start 92.80017 -285.434024)
		(mid 92.840582 -285.484133)
		(end 92.856304 -285.546546)
		(width 0.0889)
		(layer "In2.Cu")
		(net "P5E_CPU1_PE4_TX_DN<3>")
	)
	(arc
		(start 92.191586 -286.806132)
		(mid 91.992202 -287.012012)
		(end 91.919552 -287.28924)
		(width 0.0889)
		(layer "In2.Cu")
		(net "P5E_CPU1_PE4_TX_DN<3>")
	)
	(arc
		(start 91.72321 -287.618678)
		(mid 91.522704 -287.824878)
		(end 91.449652 -288.103056)
		(width 0.0889)
		(layer "In2.Cu")
		(net "P5E_CPU1_PE4_TX_DN<3>")
	)
	(arc
		(start 91.251786 -288.434018)
		(mid 91.057829 -288.630302)
		(end 90.980006 -288.895028)
		(width 0.0889)
		(layer "In2.Cu")
		(net "P5E_CPU1_PE4_TX_DN<3>")
	)
	(arc
		(start 92.858844 -285.680912)
		(mid 92.804214 -285.857141)
		(end 92.672154 -285.985966)
		(width 0.0889)
		(layer "In2.Cu")
		(net "P5E_CPU1_PE4_TX_DN<3>")
	)
	(arc
		(start 91.919552 -287.297114)
		(mid 91.867325 -287.480032)
		(end 91.7321 -287.613852)
		(width 0.0889)
		(layer "In2.Cu")
		(net "P5E_CPU1_PE4_TX_DN<3>")
	)
	(segment
		(start 55.427118 -408.250644)
		(end 55.43169 -408.250644)
		(width 0.13208)
		(layer "F.Cu")
		(net "P5E_CPU1_PE4_TX_DN<2>")
	)
	(segment
		(start 55.75808 -407.310082)
		(end 55.452518 -407.00452)
		(width 0.13208)
		(layer "F.Cu")
		(net "P5E_CPU1_PE4_TX_DN<2>")
	)
	(segment
		(start 55.75808 -407.924254)
		(end 55.75808 -407.310082)
		(width 0.13208)
		(layer "F.Cu")
		(net "P5E_CPU1_PE4_TX_DN<2>")
	)
	(segment
		(start 55.43169 -408.250644)
		(end 55.75808 -407.924254)
		(width 0.13208)
		(layer "F.Cu")
		(net "P5E_CPU1_PE4_TX_DN<2>")
	)
	(segment
		(start 91.544648 -285.125414)
		(end 91.544648 -285.661354)
		(width 0.13208)
		(layer "F.Cu")
		(net "P5E_CPU1_PE4_TX_DN<2>")
	)
	(segment
		(start 86.56447 -294.527986)
		(end 78.658974 -309.715408)
		(width 0.14732)
		(layer "In2.Cu")
		(net "P5E_CPU1_PE4_TX_DN<2>")
	)
	(segment
		(start 60.882784 -363.308392)
		(end 60.76061 -373.575072)
		(width 0.14732)
		(layer "In2.Cu")
		(net "P5E_CPU1_PE4_TX_DN<2>")
	)
	(segment
		(start 62.010798 -324.55104)
		(end 60.103004 -325.570596)
		(width 0.14732)
		(layer "In2.Cu")
		(net "P5E_CPU1_PE4_TX_DN<2>")
	)
	(segment
		(start 78.658974 -309.715408)
		(end 67.474338 -320.900044)
		(width 0.14732)
		(layer "In2.Cu")
		(net "P5E_CPU1_PE4_TX_DN<2>")
	)
	(segment
		(start 89.997788 -291.094668)
		(end 86.56447 -294.527986)
		(width 0.14732)
		(layer "In2.Cu")
		(net "P5E_CPU1_PE4_TX_DN<2>")
	)
	(segment
		(start 91.544648 -285.661354)
		(end 91.701112 -285.932372)
		(width 0.0889)
		(layer "In2.Cu")
		(net "P5E_CPU1_PE4_TX_DN<2>")
	)
	(segment
		(start 91.267026 -286.796988)
		(end 91.250516 -286.806894)
		(width 0.0889)
		(layer "In2.Cu")
		(net "P5E_CPU1_PE4_TX_DN<2>")
	)
	(segment
		(start 89.997788 -289.778186)
		(end 89.997788 -291.094668)
		(width 0.14732)
		(layer "In2.Cu")
		(net "P5E_CPU1_PE4_TX_DN<2>")
	)
	(segment
		(start 90.793824 -287.612836)
		(end 90.783664 -287.618424)
		(width 0.0889)
		(layer "In2.Cu")
		(net "P5E_CPU1_PE4_TX_DN<2>")
	)
	(segment
		(start 59.810142 -338.314284)
		(end 60.882784 -363.308392)
		(width 0.14732)
		(layer "In2.Cu")
		(net "P5E_CPU1_PE4_TX_DN<2>")
	)
	(segment
		(start 55.747158 -405.302974)
		(end 55.747158 -406.70988)
		(width 0.14732)
		(layer "In2.Cu")
		(net "P5E_CPU1_PE4_TX_DN<2>")
	)
	(segment
		(start 55.932578 -400.170396)
		(end 55.932578 -405.117554)
		(width 0.14732)
		(layer "In2.Cu")
		(net "P5E_CPU1_PE4_TX_DN<2>")
	)
	(segment
		(start 90.039698 -288.917126)
		(end 90.039698 -289.714178)
		(width 0.0889)
		(layer "In2.Cu")
		(net "P5E_CPU1_PE4_TX_DN<2>")
	)
	(segment
		(start 60.103004 -325.570596)
		(end 59.83224 -326.077326)
		(width 0.14732)
		(layer "In2.Cu")
		(net "P5E_CPU1_PE4_TX_DN<2>")
	)
	(segment
		(start 90.783664 -287.618424)
		(end 90.778584 -287.621726)
		(width 0.0889)
		(layer "In2.Cu")
		(net "P5E_CPU1_PE4_TX_DN<2>")
	)
	(segment
		(start 90.039698 -289.714178)
		(end 89.997788 -289.756088)
		(width 0.0889)
		(layer "In2.Cu")
		(net "P5E_CPU1_PE4_TX_DN<2>")
	)
	(segment
		(start 91.659964 -286.034734)
		(end 91.660218 -286.035242)
		(width 0.0889)
		(layer "In2.Cu")
		(net "P5E_CPU1_PE4_TX_DN<2>")
	)
	(segment
		(start 55.932578 -405.117554)
		(end 55.747158 -405.302974)
		(width 0.14732)
		(layer "In2.Cu")
		(net "P5E_CPU1_PE4_TX_DN<2>")
	)
	(segment
		(start 90.79738 -287.610804)
		(end 90.793824 -287.612836)
		(width 0.0889)
		(layer "In2.Cu")
		(net "P5E_CPU1_PE4_TX_DN<2>")
	)
	(segment
		(start 60.76061 -373.575072)
		(end 55.932578 -400.170396)
		(width 0.14732)
		(layer "In2.Cu")
		(net "P5E_CPU1_PE4_TX_DN<2>")
	)
	(segment
		(start 59.83224 -326.077326)
		(end 59.810142 -338.314284)
		(width 0.14732)
		(layer "In2.Cu")
		(net "P5E_CPU1_PE4_TX_DN<2>")
	)
	(segment
		(start 91.701112 -285.932372)
		(end 91.676982 -286.021526)
		(width 0.0889)
		(layer "In2.Cu")
		(net "P5E_CPU1_PE4_TX_DN<2>")
	)
	(segment
		(start 91.250516 -286.806894)
		(end 91.248738 -286.80791)
		(width 0.0889)
		(layer "In2.Cu")
		(net "P5E_CPU1_PE4_TX_DN<2>")
	)
	(segment
		(start 55.747158 -406.70988)
		(end 55.452518 -407.00452)
		(width 0.14732)
		(layer "In2.Cu")
		(net "P5E_CPU1_PE4_TX_DN<2>")
	)
	(segment
		(start 90.509598 -288.103056)
		(end 90.509598 -288.120836)
		(width 0.0889)
		(layer "In2.Cu")
		(net "P5E_CPU1_PE4_TX_DN<2>")
	)
	(segment
		(start 67.474338 -320.900044)
		(end 62.010798 -324.55104)
		(width 0.14732)
		(layer "In2.Cu")
		(net "P5E_CPU1_PE4_TX_DN<2>")
	)
	(segment
		(start 89.997788 -289.756088)
		(end 89.997788 -289.778186)
		(width 0.0889)
		(layer "In2.Cu")
		(net "P5E_CPU1_PE4_TX_DN<2>")
	)
	(arc
		(start 90.509598 -288.120836)
		(mid 90.454013 -288.300068)
		(end 90.31859 -288.429954)
		(width 0.0889)
		(layer "In2.Cu")
		(net "P5E_CPU1_PE4_TX_DN<2>")
	)
	(arc
		(start 90.778584 -287.621726)
		(mid 90.581408 -287.827361)
		(end 90.509598 -288.103056)
		(width 0.0889)
		(layer "In2.Cu")
		(net "P5E_CPU1_PE4_TX_DN<2>")
	)
	(arc
		(start 91.449398 -286.475424)
		(mid 91.400629 -286.66026)
		(end 91.267026 -286.796988)
		(width 0.0889)
		(layer "In2.Cu")
		(net "P5E_CPU1_PE4_TX_DN<2>")
	)
	(arc
		(start 91.248738 -286.80791)
		(mid 91.051562 -287.013545)
		(end 90.979752 -287.28924)
		(width 0.0889)
		(layer "In2.Cu")
		(net "P5E_CPU1_PE4_TX_DN<2>")
	)
	(arc
		(start 90.31859 -288.429954)
		(mid 90.114344 -288.636433)
		(end 90.039698 -288.917126)
		(width 0.0889)
		(layer "In2.Cu")
		(net "P5E_CPU1_PE4_TX_DN<2>")
	)
	(arc
		(start 91.660218 -286.035242)
		(mid 91.504875 -286.231409)
		(end 91.449398 -286.475424)
		(width 0.0889)
		(layer "In2.Cu")
		(net "P5E_CPU1_PE4_TX_DN<2>")
	)
	(arc
		(start 90.979752 -287.28924)
		(mid 90.930983 -287.474076)
		(end 90.79738 -287.610804)
		(width 0.0889)
		(layer "In2.Cu")
		(net "P5E_CPU1_PE4_TX_DN<2>")
	)
	(arc
		(start 91.676982 -286.021526)
		(mid 91.66841 -286.028049)
		(end 91.659964 -286.034734)
		(width 0.0889)
		(layer "In2.Cu")
		(net "P5E_CPU1_PE4_TX_DN<2>")
	)
	(segment
		(start 52.95392 -407.926286)
		(end 52.95392 -407.303478)
		(width 0.13208)
		(layer "F.Cu")
		(net "P5E_CPU1_PE4_TX_DN<1>")
	)
	(segment
		(start 53.278278 -408.250644)
		(end 52.95392 -407.926286)
		(width 0.13208)
		(layer "F.Cu")
		(net "P5E_CPU1_PE4_TX_DN<1>")
	)
	(segment
		(start 52.95392 -407.303478)
		(end 53.252878 -407.00452)
		(width 0.13208)
		(layer "F.Cu")
		(net "P5E_CPU1_PE4_TX_DN<1>")
	)
	(segment
		(start 91.074494 -284.311598)
		(end 91.074494 -284.847538)
		(width 0.13208)
		(layer "F.Cu")
		(net "P5E_CPU1_PE4_TX_DN<1>")
	)
	(segment
		(start 59.17565 -374.097296)
		(end 53.143658 -400.195288)
		(width 0.14732)
		(layer "In2.Cu")
		(net "P5E_CPU1_PE4_TX_DN<1>")
	)
	(segment
		(start 89.28989 -288.905696)
		(end 89.289636 -288.914078)
		(width 0.0889)
		(layer "In2.Cu")
		(net "P5E_CPU1_PE4_TX_DN<1>")
	)
	(segment
		(start 90.41765 -286.964882)
		(end 90.416634 -286.96539)
		(width 0.0889)
		(layer "In2.Cu")
		(net "P5E_CPU1_PE4_TX_DN<1>")
	)
	(segment
		(start 52.958238 -405.416766)
		(end 52.958238 -406.70988)
		(width 0.14732)
		(layer "In2.Cu")
		(net "P5E_CPU1_PE4_TX_DN<1>")
	)
	(segment
		(start 59.153298 -338.442046)
		(end 59.780424 -362.0262)
		(width 0.14732)
		(layer "In2.Cu")
		(net "P5E_CPU1_PE4_TX_DN<1>")
	)
	(segment
		(start 59.780424 -362.0262)
		(end 59.239912 -373.616728)
		(width 0.14732)
		(layer "In2.Cu")
		(net "P5E_CPU1_PE4_TX_DN<1>")
	)
	(segment
		(start 59.23915 -373.61749)
		(end 59.23915 -373.618252)
		(width 0.14732)
		(layer "In2.Cu")
		(net "P5E_CPU1_PE4_TX_DN<1>")
	)
	(segment
		(start 90.412824 -286.967676)
		(end 90.40876 -286.969962)
		(width 0.0889)
		(layer "In2.Cu")
		(net "P5E_CPU1_PE4_TX_DN<1>")
	)
	(segment
		(start 90.887296 -286.151066)
		(end 90.878406 -286.156146)
		(width 0.0889)
		(layer "In2.Cu")
		(net "P5E_CPU1_PE4_TX_DN<1>")
	)
	(segment
		(start 61.746638 -323.93255)
		(end 60.97651 -324.344284)
		(width 0.14732)
		(layer "In2.Cu")
		(net "P5E_CPU1_PE4_TX_DN<1>")
	)
	(segment
		(start 90.91803 -285.118556)
		(end 90.94216 -285.20771)
		(width 0.0889)
		(layer "In2.Cu")
		(net "P5E_CPU1_PE4_TX_DN<1>")
	)
	(segment
		(start 59.249564 -325.663052)
		(end 59.074304 -326.496934)
		(width 0.14732)
		(layer "In2.Cu")
		(net "P5E_CPU1_PE4_TX_DN<1>")
	)
	(segment
		(start 59.074304 -326.496934)
		(end 59.153298 -338.442046)
		(width 0.14732)
		(layer "In2.Cu")
		(net "P5E_CPU1_PE4_TX_DN<1>")
	)
	(segment
		(start 53.143658 -405.231346)
		(end 52.958238 -405.416766)
		(width 0.14732)
		(layer "In2.Cu")
		(net "P5E_CPU1_PE4_TX_DN<1>")
	)
	(segment
		(start 91.074494 -284.847538)
		(end 90.91803 -285.118556)
		(width 0.0889)
		(layer "In2.Cu")
		(net "P5E_CPU1_PE4_TX_DN<1>")
	)
	(segment
		(start 90.699844 -286.475424)
		(end 90.699844 -286.490918)
		(width 0.0889)
		(layer "In2.Cu")
		(net "P5E_CPU1_PE4_TX_DN<1>")
	)
	(segment
		(start 85.889338 -294.244776)
		(end 77.956156 -309.482236)
		(width 0.14732)
		(layer "In2.Cu")
		(net "P5E_CPU1_PE4_TX_DN<1>")
	)
	(segment
		(start 89.959688 -287.771586)
		(end 89.947496 -287.778698)
		(width 0.0889)
		(layer "In2.Cu")
		(net "P5E_CPU1_PE4_TX_DN<1>")
	)
	(segment
		(start 89.760044 -288.103056)
		(end 89.760044 -288.11728)
		(width 0.0889)
		(layer "In2.Cu")
		(net "P5E_CPU1_PE4_TX_DN<1>")
	)
	(segment
		(start 89.947496 -287.778698)
		(end 89.938606 -287.783778)
		(width 0.0889)
		(layer "In2.Cu")
		(net "P5E_CPU1_PE4_TX_DN<1>")
	)
	(segment
		(start 53.143658 -400.195288)
		(end 53.143658 -405.231346)
		(width 0.14732)
		(layer "In2.Cu")
		(net "P5E_CPU1_PE4_TX_DN<1>")
	)
	(segment
		(start 59.434476 -325.271384)
		(end 59.249564 -325.663052)
		(width 0.14732)
		(layer "In2.Cu")
		(net "P5E_CPU1_PE4_TX_DN<1>")
	)
	(segment
		(start 60.97651 -324.344284)
		(end 60.14339 -324.689724)
		(width 0.14732)
		(layer "In2.Cu")
		(net "P5E_CPU1_PE4_TX_DN<1>")
	)
	(segment
		(start 89.485724 -288.587688)
		(end 89.477342 -288.592514)
		(width 0.0889)
		(layer "In2.Cu")
		(net "P5E_CPU1_PE4_TX_DN<1>")
	)
	(segment
		(start 89.289636 -288.914078)
		(end 89.289636 -289.734244)
		(width 0.0889)
		(layer "In2.Cu")
		(net "P5E_CPU1_PE4_TX_DN<1>")
	)
	(segment
		(start 52.958238 -406.70988)
		(end 53.252878 -407.00452)
		(width 0.14732)
		(layer "In2.Cu")
		(net "P5E_CPU1_PE4_TX_DN<1>")
	)
	(segment
		(start 89.3318 -289.776408)
		(end 89.3318 -289.798506)
		(width 0.0889)
		(layer "In2.Cu")
		(net "P5E_CPU1_PE4_TX_DN<1>")
	)
	(segment
		(start 77.956156 -309.482236)
		(end 67.051428 -320.386964)
		(width 0.14732)
		(layer "In2.Cu")
		(net "P5E_CPU1_PE4_TX_DN<1>")
	)
	(segment
		(start 59.239912 -373.616728)
		(end 59.23915 -373.61749)
		(width 0.14732)
		(layer "In2.Cu")
		(net "P5E_CPU1_PE4_TX_DN<1>")
	)
	(segment
		(start 67.051428 -320.386964)
		(end 61.746638 -323.93255)
		(width 0.14732)
		(layer "In2.Cu")
		(net "P5E_CPU1_PE4_TX_DN<1>")
	)
	(segment
		(start 89.3318 -289.798506)
		(end 89.3318 -290.802314)
		(width 0.14732)
		(layer "In2.Cu")
		(net "P5E_CPU1_PE4_TX_DN<1>")
	)
	(segment
		(start 89.289636 -289.734244)
		(end 89.3318 -289.776408)
		(width 0.0889)
		(layer "In2.Cu")
		(net "P5E_CPU1_PE4_TX_DN<1>")
	)
	(segment
		(start 89.3318 -290.802314)
		(end 85.889338 -294.244776)
		(width 0.14732)
		(layer "In2.Cu")
		(net "P5E_CPU1_PE4_TX_DN<1>")
	)
	(segment
		(start 59.23915 -373.618252)
		(end 59.17565 -374.097296)
		(width 0.14732)
		(layer "In2.Cu")
		(net "P5E_CPU1_PE4_TX_DN<1>")
	)
	(segment
		(start 89.485724 -288.587942)
		(end 89.485724 -288.587688)
		(width 0.0889)
		(layer "In2.Cu")
		(net "P5E_CPU1_PE4_TX_DN<1>")
	)
	(segment
		(start 60.14339 -324.689724)
		(end 59.434476 -325.271384)
		(width 0.14732)
		(layer "In2.Cu")
		(net "P5E_CPU1_PE4_TX_DN<1>")
	)
	(segment
		(start 90.416634 -286.96539)
		(end 90.412824 -286.967676)
		(width 0.0889)
		(layer "In2.Cu")
		(net "P5E_CPU1_PE4_TX_DN<1>")
	)
	(arc
		(start 90.94216 -285.20771)
		(mid 90.950732 -285.214232)
		(end 90.959178 -285.220918)
		(width 0.0889)
		(layer "In2.Cu")
		(net "P5E_CPU1_PE4_TX_DN<1>")
	)
	(arc
		(start 90.40876 -286.969962)
		(mid 90.277846 -287.106322)
		(end 90.230198 -287.28924)
		(width 0.0889)
		(layer "In2.Cu")
		(net "P5E_CPU1_PE4_TX_DN<1>")
	)
	(arc
		(start 89.477342 -288.592514)
		(mid 89.342965 -288.724758)
		(end 89.28989 -288.905696)
		(width 0.0889)
		(layer "In2.Cu")
		(net "P5E_CPU1_PE4_TX_DN<1>")
	)
	(arc
		(start 89.938606 -287.783778)
		(mid 89.807692 -287.920138)
		(end 89.760044 -288.103056)
		(width 0.0889)
		(layer "In2.Cu")
		(net "P5E_CPU1_PE4_TX_DN<1>")
	)
	(arc
		(start 89.760044 -288.11728)
		(mid 89.683278 -288.387798)
		(end 89.485724 -288.587942)
		(width 0.0889)
		(layer "In2.Cu")
		(net "P5E_CPU1_PE4_TX_DN<1>")
	)
	(arc
		(start 90.878406 -286.156146)
		(mid 90.747492 -286.292506)
		(end 90.699844 -286.475424)
		(width 0.0889)
		(layer "In2.Cu")
		(net "P5E_CPU1_PE4_TX_DN<1>")
	)
	(arc
		(start 90.699844 -286.490918)
		(mid 90.620474 -286.764652)
		(end 90.41765 -286.964882)
		(width 0.0889)
		(layer "In2.Cu")
		(net "P5E_CPU1_PE4_TX_DN<1>")
	)
	(arc
		(start 90.959178 -285.220918)
		(mid 91.168439 -285.704927)
		(end 90.887296 -286.151066)
		(width 0.0889)
		(layer "In2.Cu")
		(net "P5E_CPU1_PE4_TX_DN<1>")
	)
	(arc
		(start 90.230198 -287.28924)
		(mid 90.157963 -287.565764)
		(end 89.959688 -287.771586)
		(width 0.0889)
		(layer "In2.Cu")
		(net "P5E_CPU1_PE4_TX_DN<1>")
	)
	(segment
		(start 95.5802 -407.310082)
		(end 95.274638 -407.00452)
		(width 0.13208)
		(layer "F.Cu")
		(net "P5E_CPU1_PE4_TX_DN<15>")
	)
	(segment
		(start 95.249238 -408.250644)
		(end 95.25381 -408.250644)
		(width 0.13208)
		(layer "F.Cu")
		(net "P5E_CPU1_PE4_TX_DN<15>")
	)
	(segment
		(start 95.5802 -407.924254)
		(end 95.5802 -407.310082)
		(width 0.13208)
		(layer "F.Cu")
		(net "P5E_CPU1_PE4_TX_DN<15>")
	)
	(segment
		(start 95.25381 -408.250644)
		(end 95.5802 -407.924254)
		(width 0.13208)
		(layer "F.Cu")
		(net "P5E_CPU1_PE4_TX_DN<15>")
	)
	(segment
		(start 103.762048 -285.6611)
		(end 103.761794 -285.661354)
		(width 0.13208)
		(layer "F.Cu")
		(net "P5E_CPU1_PE4_TX_DN<15>")
	)
	(segment
		(start 103.762048 -285.125414)
		(end 103.762048 -285.6611)
		(width 0.13208)
		(layer "F.Cu")
		(net "P5E_CPU1_PE4_TX_DN<15>")
	)
	(segment
		(start 102.21468 -301.54499)
		(end 102.859332 -297.888406)
		(width 0.14732)
		(layer "In2.Cu")
		(net "P5E_CPU1_PE4_TX_DN<15>")
	)
	(segment
		(start 95.598234 -399.4912)
		(end 95.414592 -399.417794)
		(width 0.14732)
		(layer "In2.Cu")
		(net "P5E_CPU1_PE4_TX_DN<15>")
	)
	(segment
		(start 102.539546 -288.427414)
		(end 102.540308 -288.426906)
		(width 0.0889)
		(layer "In2.Cu")
		(net "P5E_CPU1_PE4_TX_DN<15>")
	)
	(segment
		(start 102.901242 -290.569142)
		(end 102.901242 -290.389564)
		(width 0.0889)
		(layer "In2.Cu")
		(net "P5E_CPU1_PE4_TX_DN<15>")
	)
	(segment
		(start 95.197676 -398.557242)
		(end 95.014034 -398.483836)
		(width 0.14732)
		(layer "In2.Cu")
		(net "P5E_CPU1_PE4_TX_DN<15>")
	)
	(segment
		(start 95.274638 -407.00452)
		(end 95.569278 -406.70988)
		(width 0.14732)
		(layer "In2.Cu")
		(net "P5E_CPU1_PE4_TX_DN<15>")
	)
	(segment
		(start 103.948992 -285.985712)
		(end 103.957882 -285.980632)
		(width 0.0889)
		(layer "In2.Cu")
		(net "P5E_CPU1_PE4_TX_DN<15>")
	)
	(segment
		(start 102.859332 -297.888406)
		(end 102.859332 -290.63315)
		(width 0.14732)
		(layer "In2.Cu")
		(net "P5E_CPU1_PE4_TX_DN<15>")
	)
	(segment
		(start 95.414592 -399.417794)
		(end 95.269304 -399.079212)
		(width 0.14732)
		(layer "In2.Cu")
		(net "P5E_CPU1_PE4_TX_DN<15>")
	)
	(segment
		(start 102.859332 -290.63315)
		(end 102.859332 -290.611052)
		(width 0.0889)
		(layer "In2.Cu")
		(net "P5E_CPU1_PE4_TX_DN<15>")
	)
	(segment
		(start 95.269304 -399.079212)
		(end 95.34271 -398.89557)
		(width 0.14732)
		(layer "In2.Cu")
		(net "P5E_CPU1_PE4_TX_DN<15>")
	)
	(segment
		(start 95.34271 -398.89557)
		(end 95.197676 -398.557242)
		(width 0.14732)
		(layer "In2.Cu")
		(net "P5E_CPU1_PE4_TX_DN<15>")
	)
	(segment
		(start 103.478584 -286.80029)
		(end 103.479346 -286.799782)
		(width 0.0889)
		(layer "In2.Cu")
		(net "P5E_CPU1_PE4_TX_DN<15>")
	)
	(segment
		(start 95.014034 -398.483836)
		(end 94.868746 -398.145254)
		(width 0.14732)
		(layer "In2.Cu")
		(net "P5E_CPU1_PE4_TX_DN<15>")
	)
	(segment
		(start 95.754698 -399.856198)
		(end 95.598234 -399.4912)
		(width 0.14732)
		(layer "In2.Cu")
		(net "P5E_CPU1_PE4_TX_DN<15>")
	)
	(segment
		(start 95.569278 -405.302974)
		(end 95.754698 -405.117554)
		(width 0.14732)
		(layer "In2.Cu")
		(net "P5E_CPU1_PE4_TX_DN<15>")
	)
	(segment
		(start 76.031344 -329.58024)
		(end 100.209604 -305.40198)
		(width 0.14732)
		(layer "In2.Cu")
		(net "P5E_CPU1_PE4_TX_DN<15>")
	)
	(segment
		(start 103.009192 -287.613598)
		(end 103.018082 -287.608518)
		(width 0.0889)
		(layer "In2.Cu")
		(net "P5E_CPU1_PE4_TX_DN<15>")
	)
	(segment
		(start 94.868746 -398.145254)
		(end 94.942152 -397.961612)
		(width 0.14732)
		(layer "In2.Cu")
		(net "P5E_CPU1_PE4_TX_DN<15>")
	)
	(segment
		(start 102.257098 -289.114738)
		(end 102.257098 -288.898584)
		(width 0.0889)
		(layer "In2.Cu")
		(net "P5E_CPU1_PE4_TX_DN<15>")
	)
	(segment
		(start 102.726744 -290.215066)
		(end 102.726744 -289.658298)
		(width 0.0889)
		(layer "In2.Cu")
		(net "P5E_CPU1_PE4_TX_DN<15>")
	)
	(segment
		(start 102.540308 -288.426906)
		(end 102.548436 -288.422334)
		(width 0.0889)
		(layer "In2.Cu")
		(net "P5E_CPU1_PE4_TX_DN<15>")
	)
	(segment
		(start 103.666544 -286.48406)
		(end 103.666544 -286.456882)
		(width 0.0889)
		(layer "In2.Cu")
		(net "P5E_CPU1_PE4_TX_DN<15>")
	)
	(segment
		(start 103.918258 -285.390336)
		(end 103.761794 -285.661354)
		(width 0.0889)
		(layer "In2.Cu")
		(net "P5E_CPU1_PE4_TX_DN<15>")
	)
	(segment
		(start 100.209604 -305.40198)
		(end 102.21468 -301.54499)
		(width 0.14732)
		(layer "In2.Cu")
		(net "P5E_CPU1_PE4_TX_DN<15>")
	)
	(segment
		(start 103.99649 -285.369508)
		(end 103.918258 -285.390336)
		(width 0.0889)
		(layer "In2.Cu")
		(net "P5E_CPU1_PE4_TX_DN<15>")
	)
	(segment
		(start 95.569278 -406.70988)
		(end 95.569278 -405.302974)
		(width 0.14732)
		(layer "In2.Cu")
		(net "P5E_CPU1_PE4_TX_DN<15>")
	)
	(segment
		(start 73.31837 -336.129884)
		(end 76.031344 -329.58024)
		(width 0.14732)
		(layer "In2.Cu")
		(net "P5E_CPU1_PE4_TX_DN<15>")
	)
	(segment
		(start 103.47325 -286.803338)
		(end 103.47579 -286.802068)
		(width 0.0889)
		(layer "In2.Cu")
		(net "P5E_CPU1_PE4_TX_DN<15>")
	)
	(segment
		(start 95.754698 -405.117554)
		(end 95.754698 -399.856198)
		(width 0.14732)
		(layer "In2.Cu")
		(net "P5E_CPU1_PE4_TX_DN<15>")
	)
	(segment
		(start 103.47579 -286.802068)
		(end 103.478584 -286.80029)
		(width 0.0889)
		(layer "In2.Cu")
		(net "P5E_CPU1_PE4_TX_DN<15>")
	)
	(segment
		(start 74.07656 -350.097344)
		(end 73.31837 -336.129884)
		(width 0.14732)
		(layer "In2.Cu")
		(net "P5E_CPU1_PE4_TX_DN<15>")
	)
	(segment
		(start 102.859332 -290.611052)
		(end 102.901242 -290.569142)
		(width 0.0889)
		(layer "In2.Cu")
		(net "P5E_CPU1_PE4_TX_DN<15>")
	)
	(segment
		(start 102.901242 -290.389564)
		(end 102.726744 -290.215066)
		(width 0.0889)
		(layer "In2.Cu")
		(net "P5E_CPU1_PE4_TX_DN<15>")
	)
	(segment
		(start 102.726998 -288.103056)
		(end 102.726998 -288.087562)
		(width 0.0889)
		(layer "In2.Cu")
		(net "P5E_CPU1_PE4_TX_DN<15>")
	)
	(segment
		(start 94.942152 -397.961612)
		(end 74.07656 -350.097344)
		(width 0.14732)
		(layer "In2.Cu")
		(net "P5E_CPU1_PE4_TX_DN<15>")
	)
	(arc
		(start 102.257098 -288.898584)
		(mid 102.33726 -288.626395)
		(end 102.539546 -288.427414)
		(width 0.0889)
		(layer "In2.Cu")
		(net "P5E_CPU1_PE4_TX_DN<15>")
	)
	(arc
		(start 103.957882 -285.980632)
		(mid 104.088796 -285.844272)
		(end 104.136444 -285.661354)
		(width 0.0889)
		(layer "In2.Cu")
		(net "P5E_CPU1_PE4_TX_DN<15>")
	)
	(arc
		(start 104.136444 -285.661354)
		(mid 104.099584 -285.499557)
		(end 103.99649 -285.369508)
		(width 0.0889)
		(layer "In2.Cu")
		(net "P5E_CPU1_PE4_TX_DN<15>")
	)
	(arc
		(start 102.548436 -288.422334)
		(mid 102.67935 -288.285974)
		(end 102.726998 -288.103056)
		(width 0.0889)
		(layer "In2.Cu")
		(net "P5E_CPU1_PE4_TX_DN<15>")
	)
	(arc
		(start 102.726998 -288.087562)
		(mid 102.806368 -287.813828)
		(end 103.009192 -287.613598)
		(width 0.0889)
		(layer "In2.Cu")
		(net "P5E_CPU1_PE4_TX_DN<15>")
	)
	(arc
		(start 103.479346 -286.799782)
		(mid 103.614279 -286.666428)
		(end 103.666544 -286.48406)
		(width 0.0889)
		(layer "In2.Cu")
		(net "P5E_CPU1_PE4_TX_DN<15>")
	)
	(arc
		(start 103.666544 -286.456882)
		(mid 103.746706 -286.184693)
		(end 103.948992 -285.985712)
		(width 0.0889)
		(layer "In2.Cu")
		(net "P5E_CPU1_PE4_TX_DN<15>")
	)
	(arc
		(start 102.542594 -289.446462)
		(mid 102.368462 -289.307615)
		(end 102.257098 -289.114738)
		(width 0.0889)
		(layer "In2.Cu")
		(net "P5E_CPU1_PE4_TX_DN<15>")
	)
	(arc
		(start 102.72141 -289.63366)
		(mid 102.647216 -289.525538)
		(end 102.542594 -289.446462)
		(width 0.0889)
		(layer "In2.Cu")
		(net "P5E_CPU1_PE4_TX_DN<15>")
	)
	(arc
		(start 103.196644 -287.28924)
		(mid 103.270635 -287.009674)
		(end 103.47325 -286.803338)
		(width 0.0889)
		(layer "In2.Cu")
		(net "P5E_CPU1_PE4_TX_DN<15>")
	)
	(arc
		(start 102.726744 -289.658298)
		(mid 102.725449 -289.645682)
		(end 102.72141 -289.63366)
		(width 0.0889)
		(layer "In2.Cu")
		(net "P5E_CPU1_PE4_TX_DN<15>")
	)
	(arc
		(start 103.018082 -287.608518)
		(mid 103.148996 -287.472158)
		(end 103.196644 -287.28924)
		(width 0.0889)
		(layer "In2.Cu")
		(net "P5E_CPU1_PE4_TX_DN<15>")
	)
	(segment
		(start 92.19057 -408.250644)
		(end 92.51696 -407.924254)
		(width 0.13208)
		(layer "F.Cu")
		(net "P5E_CPU1_PE4_TX_DN<14>")
	)
	(segment
		(start 92.51696 -407.310082)
		(end 92.211398 -407.00452)
		(width 0.13208)
		(layer "F.Cu")
		(net "P5E_CPU1_PE4_TX_DN<14>")
	)
	(segment
		(start 92.51696 -407.924254)
		(end 92.51696 -407.310082)
		(width 0.13208)
		(layer "F.Cu")
		(net "P5E_CPU1_PE4_TX_DN<14>")
	)
	(segment
		(start 92.185998 -408.250644)
		(end 92.19057 -408.250644)
		(width 0.13208)
		(layer "F.Cu")
		(net "P5E_CPU1_PE4_TX_DN<14>")
	)
	(segment
		(start 102.822248 -285.125414)
		(end 102.822248 -285.6611)
		(width 0.13208)
		(layer "F.Cu")
		(net "P5E_CPU1_PE4_TX_DN<14>")
	)
	(segment
		(start 102.822248 -285.6611)
		(end 102.821994 -285.661354)
		(width 0.13208)
		(layer "F.Cu")
		(net "P5E_CPU1_PE4_TX_DN<14>")
	)
	(segment
		(start 73.023222 -350.122998)
		(end 82.614008 -373.598948)
		(width 0.14732)
		(layer "In2.Cu")
		(net "P5E_CPU1_PE4_TX_DN<14>")
	)
	(segment
		(start 92.691458 -399.879058)
		(end 92.691458 -405.117554)
		(width 0.14732)
		(layer "In2.Cu")
		(net "P5E_CPU1_PE4_TX_DN<14>")
	)
	(segment
		(start 101.787198 -289.64509)
		(end 101.787198 -290.350194)
		(width 0.0889)
		(layer "In2.Cu")
		(net "P5E_CPU1_PE4_TX_DN<14>")
	)
	(segment
		(start 101.926644 -291.060124)
		(end 101.926644 -297.321732)
		(width 0.14732)
		(layer "In2.Cu")
		(net "P5E_CPU1_PE4_TX_DN<14>")
	)
	(segment
		(start 101.787452 -288.103056)
		(end 101.787452 -288.118042)
		(width 0.0889)
		(layer "In2.Cu")
		(net "P5E_CPU1_PE4_TX_DN<14>")
	)
	(segment
		(start 101.968554 -290.63823)
		(end 101.968554 -290.996116)
		(width 0.0889)
		(layer "In2.Cu")
		(net "P5E_CPU1_PE4_TX_DN<14>")
	)
	(segment
		(start 92.506038 -405.302974)
		(end 92.506038 -406.70988)
		(width 0.14732)
		(layer "In2.Cu")
		(net "P5E_CPU1_PE4_TX_DN<14>")
	)
	(segment
		(start 102.821994 -285.661354)
		(end 102.978458 -285.932372)
		(width 0.0889)
		(layer "In2.Cu")
		(net "P5E_CPU1_PE4_TX_DN<14>")
	)
	(segment
		(start 99.445064 -304.851308)
		(end 75.07224 -329.224386)
		(width 0.14732)
		(layer "In2.Cu")
		(net "P5E_CPU1_PE4_TX_DN<14>")
	)
	(segment
		(start 101.189536 -301.500794)
		(end 99.445064 -304.851308)
		(width 0.14732)
		(layer "In2.Cu")
		(net "P5E_CPU1_PE4_TX_DN<14>")
	)
	(segment
		(start 92.506038 -406.70988)
		(end 92.211398 -407.00452)
		(width 0.14732)
		(layer "In2.Cu")
		(net "P5E_CPU1_PE4_TX_DN<14>")
	)
	(segment
		(start 102.546912 -286.795464)
		(end 102.54107 -286.79902)
		(width 0.0889)
		(layer "In2.Cu")
		(net "P5E_CPU1_PE4_TX_DN<14>")
	)
	(segment
		(start 102.978458 -285.932372)
		(end 102.954328 -286.021526)
		(width 0.0889)
		(layer "In2.Cu")
		(net "P5E_CPU1_PE4_TX_DN<14>")
	)
	(segment
		(start 75.07224 -329.224386)
		(end 72.370188 -335.747614)
		(width 0.14732)
		(layer "In2.Cu")
		(net "P5E_CPU1_PE4_TX_DN<14>")
	)
	(segment
		(start 101.603048 -289.446208)
		(end 101.603302 -289.446208)
		(width 0.0889)
		(layer "In2.Cu")
		(net "P5E_CPU1_PE4_TX_DN<14>")
	)
	(segment
		(start 102.257098 -287.28924)
		(end 102.257098 -287.301686)
		(width 0.0889)
		(layer "In2.Cu")
		(net "P5E_CPU1_PE4_TX_DN<14>")
	)
	(segment
		(start 101.317552 -288.917126)
		(end 101.317552 -289.113976)
		(width 0.0889)
		(layer "In2.Cu")
		(net "P5E_CPU1_PE4_TX_DN<14>")
	)
	(segment
		(start 102.529386 -286.805878)
		(end 102.526084 -286.80791)
		(width 0.0889)
		(layer "In2.Cu")
		(net "P5E_CPU1_PE4_TX_DN<14>")
	)
	(segment
		(start 101.600254 -288.427668)
		(end 101.589586 -288.434018)
		(width 0.0889)
		(layer "In2.Cu")
		(net "P5E_CPU1_PE4_TX_DN<14>")
	)
	(segment
		(start 101.787198 -290.350194)
		(end 101.968554 -290.63823)
		(width 0.0889)
		(layer "In2.Cu")
		(net "P5E_CPU1_PE4_TX_DN<14>")
	)
	(segment
		(start 102.54996 -286.793686)
		(end 102.546912 -286.795464)
		(width 0.0889)
		(layer "In2.Cu")
		(net "P5E_CPU1_PE4_TX_DN<14>")
	)
	(segment
		(start 101.968554 -290.996116)
		(end 101.926644 -291.038026)
		(width 0.0889)
		(layer "In2.Cu")
		(net "P5E_CPU1_PE4_TX_DN<14>")
	)
	(segment
		(start 72.326754 -336.066638)
		(end 73.023222 -350.122998)
		(width 0.14732)
		(layer "In2.Cu")
		(net "P5E_CPU1_PE4_TX_DN<14>")
	)
	(segment
		(start 82.614008 -373.598948)
		(end 92.691458 -399.879058)
		(width 0.14732)
		(layer "In2.Cu")
		(net "P5E_CPU1_PE4_TX_DN<14>")
	)
	(segment
		(start 72.370188 -335.747614)
		(end 72.326754 -336.066638)
		(width 0.14732)
		(layer "In2.Cu")
		(net "P5E_CPU1_PE4_TX_DN<14>")
	)
	(segment
		(start 102.954328 -286.021526)
		(end 102.954836 -286.021272)
		(width 0.0889)
		(layer "In2.Cu")
		(net "P5E_CPU1_PE4_TX_DN<14>")
	)
	(segment
		(start 101.926644 -291.038026)
		(end 101.926644 -291.060124)
		(width 0.0889)
		(layer "In2.Cu")
		(net "P5E_CPU1_PE4_TX_DN<14>")
	)
	(segment
		(start 92.691458 -405.117554)
		(end 92.506038 -405.302974)
		(width 0.14732)
		(layer "In2.Cu")
		(net "P5E_CPU1_PE4_TX_DN<14>")
	)
	(segment
		(start 102.070154 -287.613598)
		(end 102.059486 -287.619948)
		(width 0.0889)
		(layer "In2.Cu")
		(net "P5E_CPU1_PE4_TX_DN<14>")
	)
	(segment
		(start 101.926644 -297.321732)
		(end 101.189536 -301.500794)
		(width 0.14732)
		(layer "In2.Cu")
		(net "P5E_CPU1_PE4_TX_DN<14>")
	)
	(segment
		(start 102.54107 -286.79902)
		(end 102.529386 -286.805878)
		(width 0.0889)
		(layer "In2.Cu")
		(net "P5E_CPU1_PE4_TX_DN<14>")
	)
	(arc
		(start 101.787452 -288.118042)
		(mid 101.733647 -288.296917)
		(end 101.600254 -288.427668)
		(width 0.0889)
		(layer "In2.Cu")
		(net "P5E_CPU1_PE4_TX_DN<14>")
	)
	(arc
		(start 101.317552 -289.113976)
		(mid 101.428782 -289.30718)
		(end 101.603048 -289.446208)
		(width 0.0889)
		(layer "In2.Cu")
		(net "P5E_CPU1_PE4_TX_DN<14>")
	)
	(arc
		(start 102.954836 -286.021272)
		(mid 102.946006 -286.027915)
		(end 102.93731 -286.034734)
		(width 0.0889)
		(layer "In2.Cu")
		(net "P5E_CPU1_PE4_TX_DN<14>")
	)
	(arc
		(start 102.526084 -286.80791)
		(mid 102.328908 -287.013545)
		(end 102.257098 -287.28924)
		(width 0.0889)
		(layer "In2.Cu")
		(net "P5E_CPU1_PE4_TX_DN<14>")
	)
	(arc
		(start 102.726998 -286.475424)
		(mid 102.679765 -286.657525)
		(end 102.54996 -286.793686)
		(width 0.0889)
		(layer "In2.Cu")
		(net "P5E_CPU1_PE4_TX_DN<14>")
	)
	(arc
		(start 101.589586 -288.434018)
		(mid 101.390202 -288.639898)
		(end 101.317552 -288.917126)
		(width 0.0889)
		(layer "In2.Cu")
		(net "P5E_CPU1_PE4_TX_DN<14>")
	)
	(arc
		(start 102.059486 -287.619948)
		(mid 101.860102 -287.825828)
		(end 101.787452 -288.103056)
		(width 0.0889)
		(layer "In2.Cu")
		(net "P5E_CPU1_PE4_TX_DN<14>")
	)
	(arc
		(start 102.257098 -287.301686)
		(mid 102.203956 -287.481816)
		(end 102.070154 -287.613598)
		(width 0.0889)
		(layer "In2.Cu")
		(net "P5E_CPU1_PE4_TX_DN<14>")
	)
	(arc
		(start 102.93731 -286.034734)
		(mid 102.782149 -286.231209)
		(end 102.726998 -286.475424)
		(width 0.0889)
		(layer "In2.Cu")
		(net "P5E_CPU1_PE4_TX_DN<14>")
	)
	(arc
		(start 101.603302 -289.446208)
		(mid 101.71219 -289.529978)
		(end 101.787198 -289.64509)
		(width 0.0889)
		(layer "In2.Cu")
		(net "P5E_CPU1_PE4_TX_DN<14>")
	)
	(segment
		(start 101.882448 -285.125414)
		(end 101.882448 -285.6611)
		(width 0.13208)
		(layer "F.Cu")
		(net "P5E_CPU1_PE4_TX_DN<13>")
	)
	(segment
		(start 89.45372 -407.924254)
		(end 89.45372 -407.310082)
		(width 0.13208)
		(layer "F.Cu")
		(net "P5E_CPU1_PE4_TX_DN<13>")
	)
	(segment
		(start 89.122758 -408.250644)
		(end 89.12733 -408.250644)
		(width 0.13208)
		(layer "F.Cu")
		(net "P5E_CPU1_PE4_TX_DN<13>")
	)
	(segment
		(start 89.12733 -408.250644)
		(end 89.45372 -407.924254)
		(width 0.13208)
		(layer "F.Cu")
		(net "P5E_CPU1_PE4_TX_DN<13>")
	)
	(segment
		(start 89.45372 -407.310082)
		(end 89.148158 -407.00452)
		(width 0.13208)
		(layer "F.Cu")
		(net "P5E_CPU1_PE4_TX_DN<13>")
	)
	(segment
		(start 101.882448 -285.6611)
		(end 101.882194 -285.661354)
		(width 0.13208)
		(layer "F.Cu")
		(net "P5E_CPU1_PE4_TX_DN<13>")
	)
	(segment
		(start 88.749632 -397.481298)
		(end 88.867996 -397.830294)
		(width 0.14732)
		(layer "In2.Cu")
		(net "P5E_CPU1_PE4_TX_DN<13>")
	)
	(segment
		(start 71.335646 -336.034126)
		(end 71.956676 -349.999808)
		(width 0.14732)
		(layer "In2.Cu")
		(net "P5E_CPU1_PE4_TX_DN<13>")
	)
	(segment
		(start 102.038658 -285.390336)
		(end 102.11689 -285.369508)
		(width 0.0889)
		(layer "In2.Cu")
		(net "P5E_CPU1_PE4_TX_DN<13>")
	)
	(segment
		(start 74.177144 -328.765662)
		(end 71.418196 -335.425796)
		(width 0.14732)
		(layer "In2.Cu")
		(net "P5E_CPU1_PE4_TX_DN<13>")
	)
	(segment
		(start 88.837008 -397.304006)
		(end 88.749632 -397.481298)
		(width 0.14732)
		(layer "In2.Cu")
		(net "P5E_CPU1_PE4_TX_DN<13>")
	)
	(segment
		(start 100.847398 -290.546536)
		(end 100.805488 -290.588446)
		(width 0.0889)
		(layer "In2.Cu")
		(net "P5E_CPU1_PE4_TX_DN<13>")
	)
	(segment
		(start 101.786944 -286.456882)
		(end 101.786944 -286.48406)
		(width 0.0889)
		(layer "In2.Cu")
		(net "P5E_CPU1_PE4_TX_DN<13>")
	)
	(segment
		(start 100.387404 -300.196758)
		(end 98.719386 -304.22342)
		(width 0.14732)
		(layer "In2.Cu")
		(net "P5E_CPU1_PE4_TX_DN<13>")
	)
	(segment
		(start 89.628218 -399.632424)
		(end 89.628218 -405.117554)
		(width 0.14732)
		(layer "In2.Cu")
		(net "P5E_CPU1_PE4_TX_DN<13>")
	)
	(segment
		(start 100.805488 -291.378894)
		(end 100.387404 -291.796978)
		(width 0.14732)
		(layer "In2.Cu")
		(net "P5E_CPU1_PE4_TX_DN<13>")
	)
	(segment
		(start 89.372694 -398.879822)
		(end 89.628218 -399.632424)
		(width 0.14732)
		(layer "In2.Cu")
		(net "P5E_CPU1_PE4_TX_DN<13>")
	)
	(segment
		(start 100.847398 -289.64636)
		(end 100.847398 -290.546536)
		(width 0.0889)
		(layer "In2.Cu")
		(net "P5E_CPU1_PE4_TX_DN<13>")
	)
	(segment
		(start 100.847398 -288.087562)
		(end 100.847398 -288.103056)
		(width 0.0889)
		(layer "In2.Cu")
		(net "P5E_CPU1_PE4_TX_DN<13>")
	)
	(segment
		(start 101.138482 -287.608518)
		(end 101.129592 -287.613598)
		(width 0.0889)
		(layer "In2.Cu")
		(net "P5E_CPU1_PE4_TX_DN<13>")
	)
	(segment
		(start 100.847144 -289.645852)
		(end 100.847398 -289.64636)
		(width 0.0889)
		(layer "In2.Cu")
		(net "P5E_CPU1_PE4_TX_DN<13>")
	)
	(segment
		(start 89.628218 -405.117554)
		(end 89.442798 -405.302974)
		(width 0.14732)
		(layer "In2.Cu")
		(net "P5E_CPU1_PE4_TX_DN<13>")
	)
	(segment
		(start 100.668836 -288.422334)
		(end 100.659946 -288.427414)
		(width 0.0889)
		(layer "In2.Cu")
		(net "P5E_CPU1_PE4_TX_DN<13>")
	)
	(segment
		(start 89.442798 -406.70988)
		(end 89.148158 -407.00452)
		(width 0.14732)
		(layer "In2.Cu")
		(net "P5E_CPU1_PE4_TX_DN<13>")
	)
	(segment
		(start 71.418196 -335.425796)
		(end 71.335646 -336.034126)
		(width 0.14732)
		(layer "In2.Cu")
		(net "P5E_CPU1_PE4_TX_DN<13>")
	)
	(segment
		(start 89.076784 -398.44345)
		(end 89.195148 -398.792446)
		(width 0.14732)
		(layer "In2.Cu")
		(net "P5E_CPU1_PE4_TX_DN<13>")
	)
	(segment
		(start 100.805488 -290.610544)
		(end 100.805488 -291.378894)
		(width 0.14732)
		(layer "In2.Cu")
		(net "P5E_CPU1_PE4_TX_DN<13>")
	)
	(segment
		(start 71.956676 -349.999808)
		(end 80.782668 -373.591582)
		(width 0.14732)
		(layer "In2.Cu")
		(net "P5E_CPU1_PE4_TX_DN<13>")
	)
	(segment
		(start 102.078282 -285.980632)
		(end 102.069392 -285.985712)
		(width 0.0889)
		(layer "In2.Cu")
		(net "P5E_CPU1_PE4_TX_DN<13>")
	)
	(segment
		(start 101.882194 -285.661354)
		(end 102.038658 -285.390336)
		(width 0.0889)
		(layer "In2.Cu")
		(net "P5E_CPU1_PE4_TX_DN<13>")
	)
	(segment
		(start 101.598984 -286.80029)
		(end 101.595174 -286.802576)
		(width 0.0889)
		(layer "In2.Cu")
		(net "P5E_CPU1_PE4_TX_DN<13>")
	)
	(segment
		(start 101.595174 -286.802576)
		(end 101.59365 -286.803338)
		(width 0.0889)
		(layer "In2.Cu")
		(net "P5E_CPU1_PE4_TX_DN<13>")
	)
	(segment
		(start 89.442798 -405.302974)
		(end 89.442798 -406.70988)
		(width 0.14732)
		(layer "In2.Cu")
		(net "P5E_CPU1_PE4_TX_DN<13>")
	)
	(segment
		(start 100.377498 -288.898584)
		(end 100.377498 -289.114738)
		(width 0.0889)
		(layer "In2.Cu")
		(net "P5E_CPU1_PE4_TX_DN<13>")
	)
	(segment
		(start 98.719386 -304.22342)
		(end 74.177144 -328.765662)
		(width 0.14732)
		(layer "In2.Cu")
		(net "P5E_CPU1_PE4_TX_DN<13>")
	)
	(segment
		(start 100.387404 -291.796978)
		(end 100.387404 -300.196758)
		(width 0.14732)
		(layer "In2.Cu")
		(net "P5E_CPU1_PE4_TX_DN<13>")
	)
	(segment
		(start 100.805488 -290.588446)
		(end 100.805488 -290.610544)
		(width 0.0889)
		(layer "In2.Cu")
		(net "P5E_CPU1_PE4_TX_DN<13>")
	)
	(segment
		(start 89.195148 -398.792446)
		(end 89.372694 -398.879822)
		(width 0.14732)
		(layer "In2.Cu")
		(net "P5E_CPU1_PE4_TX_DN<13>")
	)
	(segment
		(start 89.045542 -397.91767)
		(end 89.163906 -398.266158)
		(width 0.14732)
		(layer "In2.Cu")
		(net "P5E_CPU1_PE4_TX_DN<13>")
	)
	(segment
		(start 80.782668 -373.591582)
		(end 88.837008 -397.304006)
		(width 0.14732)
		(layer "In2.Cu")
		(net "P5E_CPU1_PE4_TX_DN<13>")
	)
	(segment
		(start 101.599746 -286.799782)
		(end 101.598984 -286.80029)
		(width 0.0889)
		(layer "In2.Cu")
		(net "P5E_CPU1_PE4_TX_DN<13>")
	)
	(segment
		(start 89.163906 -398.266158)
		(end 89.076784 -398.44345)
		(width 0.14732)
		(layer "In2.Cu")
		(net "P5E_CPU1_PE4_TX_DN<13>")
	)
	(segment
		(start 88.867996 -397.830294)
		(end 89.045542 -397.91767)
		(width 0.14732)
		(layer "In2.Cu")
		(net "P5E_CPU1_PE4_TX_DN<13>")
	)
	(arc
		(start 102.25659 -285.651194)
		(mid 102.256764 -285.662497)
		(end 102.25659 -285.6738)
		(width 0.0889)
		(layer "In2.Cu")
		(net "P5E_CPU1_PE4_TX_DN<13>")
	)
	(arc
		(start 102.25659 -285.6738)
		(mid 102.20604 -285.849638)
		(end 102.078282 -285.980632)
		(width 0.0889)
		(layer "In2.Cu")
		(net "P5E_CPU1_PE4_TX_DN<13>")
	)
	(arc
		(start 100.847398 -288.103056)
		(mid 100.799719 -288.285956)
		(end 100.668836 -288.422334)
		(width 0.0889)
		(layer "In2.Cu")
		(net "P5E_CPU1_PE4_TX_DN<13>")
	)
	(arc
		(start 101.129592 -287.613598)
		(mid 100.926769 -287.813829)
		(end 100.847398 -288.087562)
		(width 0.0889)
		(layer "In2.Cu")
		(net "P5E_CPU1_PE4_TX_DN<13>")
	)
	(arc
		(start 101.786944 -286.48406)
		(mid 101.734674 -286.666425)
		(end 101.599746 -286.799782)
		(width 0.0889)
		(layer "In2.Cu")
		(net "P5E_CPU1_PE4_TX_DN<13>")
	)
	(arc
		(start 101.317044 -287.28924)
		(mid 101.269365 -287.47214)
		(end 101.138482 -287.608518)
		(width 0.0889)
		(layer "In2.Cu")
		(net "P5E_CPU1_PE4_TX_DN<13>")
	)
	(arc
		(start 100.377498 -289.114738)
		(mid 100.488836 -289.307638)
		(end 100.662994 -289.446462)
		(width 0.0889)
		(layer "In2.Cu")
		(net "P5E_CPU1_PE4_TX_DN<13>")
	)
	(arc
		(start 100.662994 -289.446462)
		(mid 100.772141 -289.53039)
		(end 100.847144 -289.645852)
		(width 0.0889)
		(layer "In2.Cu")
		(net "P5E_CPU1_PE4_TX_DN<13>")
	)
	(arc
		(start 101.59365 -286.803338)
		(mid 101.391063 -287.009689)
		(end 101.317044 -287.28924)
		(width 0.0889)
		(layer "In2.Cu")
		(net "P5E_CPU1_PE4_TX_DN<13>")
	)
	(arc
		(start 102.069392 -285.985712)
		(mid 101.867106 -286.184693)
		(end 101.786944 -286.456882)
		(width 0.0889)
		(layer "In2.Cu")
		(net "P5E_CPU1_PE4_TX_DN<13>")
	)
	(arc
		(start 100.659946 -288.427414)
		(mid 100.45766 -288.626395)
		(end 100.377498 -288.898584)
		(width 0.0889)
		(layer "In2.Cu")
		(net "P5E_CPU1_PE4_TX_DN<13>")
	)
	(arc
		(start 102.11689 -285.369508)
		(mid 102.217719 -285.494984)
		(end 102.25659 -285.651194)
		(width 0.0889)
		(layer "In2.Cu")
		(net "P5E_CPU1_PE4_TX_DN<13>")
	)
	(segment
		(start 100.942648 -285.125414)
		(end 100.942648 -285.6611)
		(width 0.13208)
		(layer "F.Cu")
		(net "P5E_CPU1_PE4_TX_DN<12>")
	)
	(segment
		(start 86.06409 -408.250644)
		(end 86.39048 -407.924254)
		(width 0.13208)
		(layer "F.Cu")
		(net "P5E_CPU1_PE4_TX_DN<12>")
	)
	(segment
		(start 100.942648 -285.6611)
		(end 100.942394 -285.661354)
		(width 0.13208)
		(layer "F.Cu")
		(net "P5E_CPU1_PE4_TX_DN<12>")
	)
	(segment
		(start 86.39048 -407.924254)
		(end 86.39048 -407.310082)
		(width 0.13208)
		(layer "F.Cu")
		(net "P5E_CPU1_PE4_TX_DN<12>")
	)
	(segment
		(start 86.39048 -407.310082)
		(end 86.084918 -407.00452)
		(width 0.13208)
		(layer "F.Cu")
		(net "P5E_CPU1_PE4_TX_DN<12>")
	)
	(segment
		(start 86.059518 -408.250644)
		(end 86.06409 -408.250644)
		(width 0.13208)
		(layer "F.Cu")
		(net "P5E_CPU1_PE4_TX_DN<12>")
	)
	(segment
		(start 97.928684 -303.680622)
		(end 73.329038 -328.280268)
		(width 0.14732)
		(layer "In2.Cu")
		(net "P5E_CPU1_PE4_TX_DN<12>")
	)
	(segment
		(start 86.564978 -399.77187)
		(end 86.564978 -405.117554)
		(width 0.14732)
		(layer "In2.Cu")
		(net "P5E_CPU1_PE4_TX_DN<12>")
	)
	(segment
		(start 99.729036 -288.422334)
		(end 99.720146 -288.427414)
		(width 0.0889)
		(layer "In2.Cu")
		(net "P5E_CPU1_PE4_TX_DN<12>")
	)
	(segment
		(start 78.70952 -373.050562)
		(end 78.911958 -373.739156)
		(width 0.14732)
		(layer "In2.Cu")
		(net "P5E_CPU1_PE4_TX_DN<12>")
	)
	(segment
		(start 99.437698 -288.898584)
		(end 99.437698 -289.114738)
		(width 0.0889)
		(layer "In2.Cu")
		(net "P5E_CPU1_PE4_TX_DN<12>")
	)
	(segment
		(start 100.662486 -286.798258)
		(end 100.660454 -286.799274)
		(width 0.0889)
		(layer "In2.Cu")
		(net "P5E_CPU1_PE4_TX_DN<12>")
	)
	(segment
		(start 86.379558 -405.302974)
		(end 86.379558 -406.70988)
		(width 0.14732)
		(layer "In2.Cu")
		(net "P5E_CPU1_PE4_TX_DN<12>")
	)
	(segment
		(start 100.942394 -285.661354)
		(end 101.098858 -285.932372)
		(width 0.0889)
		(layer "In2.Cu")
		(net "P5E_CPU1_PE4_TX_DN<12>")
	)
	(segment
		(start 101.098858 -285.932372)
		(end 101.074728 -286.021526)
		(width 0.0889)
		(layer "In2.Cu")
		(net "P5E_CPU1_PE4_TX_DN<12>")
	)
	(segment
		(start 78.912212 -373.739918)
		(end 86.564978 -399.77187)
		(width 0.14732)
		(layer "In2.Cu")
		(net "P5E_CPU1_PE4_TX_DN<12>")
	)
	(segment
		(start 99.907344 -289.645852)
		(end 99.907598 -289.64636)
		(width 0.0889)
		(layer "In2.Cu")
		(net "P5E_CPU1_PE4_TX_DN<12>")
	)
	(segment
		(start 78.911958 -373.739156)
		(end 78.912212 -373.739918)
		(width 0.14732)
		(layer "In2.Cu")
		(net "P5E_CPU1_PE4_TX_DN<12>")
	)
	(segment
		(start 86.379558 -406.70988)
		(end 86.084918 -407.00452)
		(width 0.14732)
		(layer "In2.Cu")
		(net "P5E_CPU1_PE4_TX_DN<12>")
	)
	(segment
		(start 70.475348 -335.169764)
		(end 70.371208 -335.717388)
		(width 0.14732)
		(layer "In2.Cu")
		(net "P5E_CPU1_PE4_TX_DN<12>")
	)
	(segment
		(start 86.564978 -405.117554)
		(end 86.379558 -405.302974)
		(width 0.14732)
		(layer "In2.Cu")
		(net "P5E_CPU1_PE4_TX_DN<12>")
	)
	(segment
		(start 100.847144 -286.4612)
		(end 100.847144 -286.475424)
		(width 0.0889)
		(layer "In2.Cu")
		(net "P5E_CPU1_PE4_TX_DN<12>")
	)
	(segment
		(start 99.456748 -290.981892)
		(end 99.456748 -299.991272)
		(width 0.14732)
		(layer "In2.Cu")
		(net "P5E_CPU1_PE4_TX_DN<12>")
	)
	(segment
		(start 99.907598 -289.64636)
		(end 99.907598 -290.29406)
		(width 0.0889)
		(layer "In2.Cu")
		(net "P5E_CPU1_PE4_TX_DN<12>")
	)
	(segment
		(start 99.456748 -290.959794)
		(end 99.456748 -290.981892)
		(width 0.0889)
		(layer "In2.Cu")
		(net "P5E_CPU1_PE4_TX_DN<12>")
	)
	(segment
		(start 99.498658 -290.917884)
		(end 99.456748 -290.959794)
		(width 0.0889)
		(layer "In2.Cu")
		(net "P5E_CPU1_PE4_TX_DN<12>")
	)
	(segment
		(start 100.660454 -286.799274)
		(end 100.659692 -286.799782)
		(width 0.0889)
		(layer "In2.Cu")
		(net "P5E_CPU1_PE4_TX_DN<12>")
	)
	(segment
		(start 100.668582 -286.794702)
		(end 100.662486 -286.798258)
		(width 0.0889)
		(layer "In2.Cu")
		(net "P5E_CPU1_PE4_TX_DN<12>")
	)
	(segment
		(start 70.873874 -349.944944)
		(end 78.70952 -373.050562)
		(width 0.14732)
		(layer "In2.Cu")
		(net "P5E_CPU1_PE4_TX_DN<12>")
	)
	(segment
		(start 99.456748 -299.991272)
		(end 97.928684 -303.680622)
		(width 0.14732)
		(layer "In2.Cu")
		(net "P5E_CPU1_PE4_TX_DN<12>")
	)
	(segment
		(start 99.498658 -290.703)
		(end 99.498658 -290.917884)
		(width 0.0889)
		(layer "In2.Cu")
		(net "P5E_CPU1_PE4_TX_DN<12>")
	)
	(segment
		(start 100.198682 -287.608518)
		(end 100.189792 -287.613598)
		(width 0.0889)
		(layer "In2.Cu")
		(net "P5E_CPU1_PE4_TX_DN<12>")
	)
	(segment
		(start 99.907598 -288.087562)
		(end 99.907598 -288.103056)
		(width 0.0889)
		(layer "In2.Cu")
		(net "P5E_CPU1_PE4_TX_DN<12>")
	)
	(segment
		(start 99.907598 -290.29406)
		(end 99.498658 -290.703)
		(width 0.0889)
		(layer "In2.Cu")
		(net "P5E_CPU1_PE4_TX_DN<12>")
	)
	(segment
		(start 100.377244 -287.279334)
		(end 100.377244 -287.28924)
		(width 0.0889)
		(layer "In2.Cu")
		(net "P5E_CPU1_PE4_TX_DN<12>")
	)
	(segment
		(start 73.329038 -328.280268)
		(end 70.475348 -335.169764)
		(width 0.14732)
		(layer "In2.Cu")
		(net "P5E_CPU1_PE4_TX_DN<12>")
	)
	(segment
		(start 70.371208 -335.717388)
		(end 70.873874 -349.944944)
		(width 0.14732)
		(layer "In2.Cu")
		(net "P5E_CPU1_PE4_TX_DN<12>")
	)
	(arc
		(start 100.847144 -286.475424)
		(mid 100.799465 -286.658324)
		(end 100.668582 -286.794702)
		(width 0.0889)
		(layer "In2.Cu")
		(net "P5E_CPU1_PE4_TX_DN<12>")
	)
	(arc
		(start 99.907598 -288.103056)
		(mid 99.859919 -288.285956)
		(end 99.729036 -288.422334)
		(width 0.0889)
		(layer "In2.Cu")
		(net "P5E_CPU1_PE4_TX_DN<12>")
	)
	(arc
		(start 99.720146 -288.427414)
		(mid 99.51786 -288.626395)
		(end 99.437698 -288.898584)
		(width 0.0889)
		(layer "In2.Cu")
		(net "P5E_CPU1_PE4_TX_DN<12>")
	)
	(arc
		(start 101.057964 -286.03448)
		(mid 100.905457 -286.224578)
		(end 100.847144 -286.4612)
		(width 0.0889)
		(layer "In2.Cu")
		(net "P5E_CPU1_PE4_TX_DN<12>")
	)
	(arc
		(start 99.437698 -289.114738)
		(mid 99.549036 -289.307638)
		(end 99.723194 -289.446462)
		(width 0.0889)
		(layer "In2.Cu")
		(net "P5E_CPU1_PE4_TX_DN<12>")
	)
	(arc
		(start 100.189792 -287.613598)
		(mid 99.986969 -287.813829)
		(end 99.907598 -288.087562)
		(width 0.0889)
		(layer "In2.Cu")
		(net "P5E_CPU1_PE4_TX_DN<12>")
	)
	(arc
		(start 100.659692 -286.799782)
		(mid 100.455357 -287.002387)
		(end 100.377244 -287.279334)
		(width 0.0889)
		(layer "In2.Cu")
		(net "P5E_CPU1_PE4_TX_DN<12>")
	)
	(arc
		(start 100.377244 -287.28924)
		(mid 100.329565 -287.47214)
		(end 100.198682 -287.608518)
		(width 0.0889)
		(layer "In2.Cu")
		(net "P5E_CPU1_PE4_TX_DN<12>")
	)
	(arc
		(start 101.074728 -286.021526)
		(mid 101.066285 -286.027924)
		(end 101.057964 -286.03448)
		(width 0.0889)
		(layer "In2.Cu")
		(net "P5E_CPU1_PE4_TX_DN<12>")
	)
	(arc
		(start 99.723194 -289.446462)
		(mid 99.832341 -289.53039)
		(end 99.907344 -289.645852)
		(width 0.0889)
		(layer "In2.Cu")
		(net "P5E_CPU1_PE4_TX_DN<12>")
	)
	(segment
		(start 100.472494 -284.311598)
		(end 100.472494 -284.847284)
		(width 0.13208)
		(layer "F.Cu")
		(net "P5E_CPU1_PE4_TX_DN<11>")
	)
	(segment
		(start 83.910678 -408.250644)
		(end 83.58632 -407.926286)
		(width 0.13208)
		(layer "F.Cu")
		(net "P5E_CPU1_PE4_TX_DN<11>")
	)
	(segment
		(start 83.58632 -407.303478)
		(end 83.885278 -407.00452)
		(width 0.13208)
		(layer "F.Cu")
		(net "P5E_CPU1_PE4_TX_DN<11>")
	)
	(segment
		(start 83.58632 -407.926286)
		(end 83.58632 -407.303478)
		(width 0.13208)
		(layer "F.Cu")
		(net "P5E_CPU1_PE4_TX_DN<11>")
	)
	(segment
		(start 100.472494 -284.847284)
		(end 100.472748 -284.847538)
		(width 0.13208)
		(layer "F.Cu")
		(net "P5E_CPU1_PE4_TX_DN<11>")
	)
	(segment
		(start 99.815396 -286.964882)
		(end 99.813872 -286.965644)
		(width 0.0889)
		(layer "In2.Cu")
		(net "P5E_CPU1_PE4_TX_DN<11>")
	)
	(segment
		(start 98.756724 -290.939982)
		(end 98.798888 -290.982146)
		(width 0.0889)
		(layer "In2.Cu")
		(net "P5E_CPU1_PE4_TX_DN<11>")
	)
	(segment
		(start 83.590638 -406.70988)
		(end 83.885278 -407.00452)
		(width 0.14732)
		(layer "In2.Cu")
		(net "P5E_CPU1_PE4_TX_DN<11>")
	)
	(segment
		(start 72.646794 -328.0283)
		(end 69.783706 -334.940148)
		(width 0.14732)
		(layer "In2.Cu")
		(net "P5E_CPU1_PE4_TX_DN<11>")
	)
	(segment
		(start 99.821492 -286.961326)
		(end 99.815396 -286.964882)
		(width 0.0889)
		(layer "In2.Cu")
		(net "P5E_CPU1_PE4_TX_DN<11>")
	)
	(segment
		(start 99.627944 -287.28924)
		(end 99.627944 -287.304734)
		(width 0.0889)
		(layer "In2.Cu")
		(net "P5E_CPU1_PE4_TX_DN<11>")
	)
	(segment
		(start 100.098098 -286.466788)
		(end 100.098098 -286.475424)
		(width 0.0889)
		(layer "In2.Cu")
		(net "P5E_CPU1_PE4_TX_DN<11>")
	)
	(segment
		(start 83.590638 -405.416766)
		(end 83.590638 -406.70988)
		(width 0.14732)
		(layer "In2.Cu")
		(net "P5E_CPU1_PE4_TX_DN<11>")
	)
	(segment
		(start 100.567236 -285.62681)
		(end 100.567744 -285.679896)
		(width 0.0889)
		(layer "In2.Cu")
		(net "P5E_CPU1_PE4_TX_DN<11>")
	)
	(segment
		(start 97.29978 -303.375314)
		(end 72.646794 -328.0283)
		(width 0.14732)
		(layer "In2.Cu")
		(net "P5E_CPU1_PE4_TX_DN<11>")
	)
	(segment
		(start 98.798888 -291.004244)
		(end 98.798888 -299.756322)
		(width 0.14732)
		(layer "In2.Cu")
		(net "P5E_CPU1_PE4_TX_DN<11>")
	)
	(segment
		(start 99.158298 -288.103056)
		(end 99.158298 -288.121598)
		(width 0.0889)
		(layer "In2.Cu")
		(net "P5E_CPU1_PE4_TX_DN<11>")
	)
	(segment
		(start 77.150214 -372.961154)
		(end 83.776058 -399.600928)
		(width 0.14732)
		(layer "In2.Cu")
		(net "P5E_CPU1_PE4_TX_DN<11>")
	)
	(segment
		(start 98.798888 -299.756322)
		(end 97.29978 -303.375314)
		(width 0.14732)
		(layer "In2.Cu")
		(net "P5E_CPU1_PE4_TX_DN<11>")
	)
	(segment
		(start 99.15779 -290.264088)
		(end 98.756724 -290.52647)
		(width 0.0889)
		(layer "In2.Cu")
		(net "P5E_CPU1_PE4_TX_DN<11>")
	)
	(segment
		(start 99.158044 -289.60953)
		(end 99.15779 -289.645852)
		(width 0.0889)
		(layer "In2.Cu")
		(net "P5E_CPU1_PE4_TX_DN<11>")
	)
	(segment
		(start 99.15779 -289.645852)
		(end 99.15779 -290.264088)
		(width 0.0889)
		(layer "In2.Cu")
		(net "P5E_CPU1_PE4_TX_DN<11>")
	)
	(segment
		(start 99.813872 -286.965644)
		(end 99.806506 -286.969962)
		(width 0.0889)
		(layer "In2.Cu")
		(net "P5E_CPU1_PE4_TX_DN<11>")
	)
	(segment
		(start 98.756724 -290.52647)
		(end 98.756724 -290.939982)
		(width 0.0889)
		(layer "In2.Cu")
		(net "P5E_CPU1_PE4_TX_DN<11>")
	)
	(segment
		(start 98.798888 -290.982146)
		(end 98.798888 -291.004244)
		(width 0.0889)
		(layer "In2.Cu")
		(net "P5E_CPU1_PE4_TX_DN<11>")
	)
	(segment
		(start 98.87585 -288.592768)
		(end 98.86696 -288.597848)
		(width 0.0889)
		(layer "In2.Cu")
		(net "P5E_CPU1_PE4_TX_DN<11>")
	)
	(segment
		(start 99.34575 -287.778698)
		(end 99.33686 -287.783778)
		(width 0.0889)
		(layer "In2.Cu")
		(net "P5E_CPU1_PE4_TX_DN<11>")
	)
	(segment
		(start 83.776058 -399.600928)
		(end 83.776058 -405.231346)
		(width 0.14732)
		(layer "In2.Cu")
		(net "P5E_CPU1_PE4_TX_DN<11>")
	)
	(segment
		(start 98.688398 -288.917126)
		(end 98.688398 -289.078416)
		(width 0.0889)
		(layer "In2.Cu")
		(net "P5E_CPU1_PE4_TX_DN<11>")
	)
	(segment
		(start 100.316284 -285.118556)
		(end 100.340414 -285.20771)
		(width 0.0889)
		(layer "In2.Cu")
		(net "P5E_CPU1_PE4_TX_DN<11>")
	)
	(segment
		(start 70.142608 -349.935546)
		(end 77.150214 -372.961154)
		(width 0.14732)
		(layer "In2.Cu")
		(net "P5E_CPU1_PE4_TX_DN<11>")
	)
	(segment
		(start 69.783706 -334.940148)
		(end 69.683376 -335.55686)
		(width 0.14732)
		(layer "In2.Cu")
		(net "P5E_CPU1_PE4_TX_DN<11>")
	)
	(segment
		(start 100.357178 -285.220664)
		(end 100.372164 -285.232602)
		(width 0.0889)
		(layer "In2.Cu")
		(net "P5E_CPU1_PE4_TX_DN<11>")
	)
	(segment
		(start 69.683376 -335.55686)
		(end 70.142608 -349.935546)
		(width 0.14732)
		(layer "In2.Cu")
		(net "P5E_CPU1_PE4_TX_DN<11>")
	)
	(segment
		(start 83.776058 -405.231346)
		(end 83.590638 -405.416766)
		(width 0.14732)
		(layer "In2.Cu")
		(net "P5E_CPU1_PE4_TX_DN<11>")
	)
	(segment
		(start 100.472748 -284.847538)
		(end 100.316284 -285.118556)
		(width 0.0889)
		(layer "In2.Cu")
		(net "P5E_CPU1_PE4_TX_DN<11>")
	)
	(arc
		(start 99.806506 -286.969962)
		(mid 99.675592 -287.106322)
		(end 99.627944 -287.28924)
		(width 0.0889)
		(layer "In2.Cu")
		(net "P5E_CPU1_PE4_TX_DN<11>")
	)
	(arc
		(start 98.872548 -289.277806)
		(mid 99.04668 -289.416653)
		(end 99.158044 -289.60953)
		(width 0.0889)
		(layer "In2.Cu")
		(net "P5E_CPU1_PE4_TX_DN<11>")
	)
	(arc
		(start 100.372164 -285.232602)
		(mid 100.513059 -285.408254)
		(end 100.567236 -285.62681)
		(width 0.0889)
		(layer "In2.Cu")
		(net "P5E_CPU1_PE4_TX_DN<11>")
	)
	(arc
		(start 100.285296 -286.151066)
		(mid 100.150363 -286.28442)
		(end 100.098098 -286.466788)
		(width 0.0889)
		(layer "In2.Cu")
		(net "P5E_CPU1_PE4_TX_DN<11>")
	)
	(arc
		(start 100.340414 -285.20771)
		(mid 100.348855 -285.21411)
		(end 100.357178 -285.220664)
		(width 0.0889)
		(layer "In2.Cu")
		(net "P5E_CPU1_PE4_TX_DN<11>")
	)
	(arc
		(start 99.627944 -287.304734)
		(mid 99.548574 -287.578468)
		(end 99.34575 -287.778698)
		(width 0.0889)
		(layer "In2.Cu")
		(net "P5E_CPU1_PE4_TX_DN<11>")
	)
	(arc
		(start 99.158298 -288.121598)
		(mid 99.078136 -288.393787)
		(end 98.87585 -288.592768)
		(width 0.0889)
		(layer "In2.Cu")
		(net "P5E_CPU1_PE4_TX_DN<11>")
	)
	(arc
		(start 99.33686 -287.783778)
		(mid 99.205946 -287.920138)
		(end 99.158298 -288.103056)
		(width 0.0889)
		(layer "In2.Cu")
		(net "P5E_CPU1_PE4_TX_DN<11>")
	)
	(arc
		(start 98.688398 -289.078416)
		(mid 98.763403 -289.193875)
		(end 98.872548 -289.277806)
		(width 0.0889)
		(layer "In2.Cu")
		(net "P5E_CPU1_PE4_TX_DN<11>")
	)
	(arc
		(start 98.86696 -288.597848)
		(mid 98.736046 -288.734208)
		(end 98.688398 -288.917126)
		(width 0.0889)
		(layer "In2.Cu")
		(net "P5E_CPU1_PE4_TX_DN<11>")
	)
	(arc
		(start 100.567744 -285.679896)
		(mid 100.487582 -285.952085)
		(end 100.285296 -286.151066)
		(width 0.0889)
		(layer "In2.Cu")
		(net "P5E_CPU1_PE4_TX_DN<11>")
	)
	(arc
		(start 100.098098 -286.475424)
		(mid 100.024107 -286.75499)
		(end 99.821492 -286.961326)
		(width 0.0889)
		(layer "In2.Cu")
		(net "P5E_CPU1_PE4_TX_DN<11>")
	)
	(segment
		(start 80.264 -407.924254)
		(end 80.264 -407.310082)
		(width 0.13208)
		(layer "F.Cu")
		(net "P5E_CPU1_PE4_TX_DN<10>")
	)
	(segment
		(start 80.264 -407.310082)
		(end 79.958438 -407.00452)
		(width 0.13208)
		(layer "F.Cu")
		(net "P5E_CPU1_PE4_TX_DN<10>")
	)
	(segment
		(start 99.063048 -285.125414)
		(end 99.063048 -285.6611)
		(width 0.13208)
		(layer "F.Cu")
		(net "P5E_CPU1_PE4_TX_DN<10>")
	)
	(segment
		(start 79.933038 -408.250644)
		(end 79.93761 -408.250644)
		(width 0.13208)
		(layer "F.Cu")
		(net "P5E_CPU1_PE4_TX_DN<10>")
	)
	(segment
		(start 79.93761 -408.250644)
		(end 80.264 -407.924254)
		(width 0.13208)
		(layer "F.Cu")
		(net "P5E_CPU1_PE4_TX_DN<10>")
	)
	(segment
		(start 99.063048 -285.6611)
		(end 99.062794 -285.661354)
		(width 0.13208)
		(layer "F.Cu")
		(net "P5E_CPU1_PE4_TX_DN<10>")
	)
	(segment
		(start 68.884038 -349.98279)
		(end 75.22464 -373.511318)
		(width 0.14732)
		(layer "In2.Cu")
		(net "P5E_CPU1_PE4_TX_DN<10>")
	)
	(segment
		(start 97.634298 -290.418012)
		(end 97.634298 -290.940236)
		(width 0.0889)
		(layer "In2.Cu")
		(net "P5E_CPU1_PE4_TX_DN<10>")
	)
	(segment
		(start 98.497898 -287.289494)
		(end 98.497644 -287.28924)
		(width 0.0889)
		(layer "In2.Cu")
		(net "P5E_CPU1_PE4_TX_DN<10>")
	)
	(segment
		(start 80.253078 -406.70988)
		(end 79.958438 -407.00452)
		(width 0.14732)
		(layer "In2.Cu")
		(net "P5E_CPU1_PE4_TX_DN<10>")
	)
	(segment
		(start 98.027998 -289.645344)
		(end 98.027998 -290.18484)
		(width 0.0889)
		(layer "In2.Cu")
		(net "P5E_CPU1_PE4_TX_DN<10>")
	)
	(segment
		(start 71.536306 -327.43521)
		(end 68.619116 -334.478122)
		(width 0.14732)
		(layer "In2.Cu")
		(net "P5E_CPU1_PE4_TX_DN<10>")
	)
	(segment
		(start 98.319336 -287.609026)
		(end 98.310446 -287.613852)
		(width 0.0889)
		(layer "In2.Cu")
		(net "P5E_CPU1_PE4_TX_DN<10>")
	)
	(segment
		(start 98.027998 -290.18484)
		(end 97.634298 -290.418012)
		(width 0.0889)
		(layer "In2.Cu")
		(net "P5E_CPU1_PE4_TX_DN<10>")
	)
	(segment
		(start 97.558352 -288.898584)
		(end 97.558352 -289.113976)
		(width 0.0889)
		(layer "In2.Cu")
		(net "P5E_CPU1_PE4_TX_DN<10>")
	)
	(segment
		(start 80.253078 -405.302974)
		(end 80.253078 -406.70988)
		(width 0.14732)
		(layer "In2.Cu")
		(net "P5E_CPU1_PE4_TX_DN<10>")
	)
	(segment
		(start 98.789998 -286.794702)
		(end 98.781108 -286.799528)
		(width 0.0889)
		(layer "In2.Cu")
		(net "P5E_CPU1_PE4_TX_DN<10>")
	)
	(segment
		(start 99.219258 -285.932372)
		(end 99.195128 -286.021526)
		(width 0.0889)
		(layer "In2.Cu")
		(net "P5E_CPU1_PE4_TX_DN<10>")
	)
	(segment
		(start 97.634298 -290.940236)
		(end 97.592388 -290.982146)
		(width 0.0889)
		(layer "In2.Cu")
		(net "P5E_CPU1_PE4_TX_DN<10>")
	)
	(segment
		(start 80.438498 -405.117554)
		(end 80.253078 -405.302974)
		(width 0.14732)
		(layer "In2.Cu")
		(net "P5E_CPU1_PE4_TX_DN<10>")
	)
	(segment
		(start 97.592388 -291.004244)
		(end 97.592388 -299.508672)
		(width 0.14732)
		(layer "In2.Cu")
		(net "P5E_CPU1_PE4_TX_DN<10>")
	)
	(segment
		(start 68.45808 -335.490058)
		(end 68.874386 -349.919544)
		(width 0.14732)
		(layer "In2.Cu")
		(net "P5E_CPU1_PE4_TX_DN<10>")
	)
	(segment
		(start 68.874386 -349.919544)
		(end 68.884038 -349.98279)
		(width 0.14732)
		(layer "In2.Cu")
		(net "P5E_CPU1_PE4_TX_DN<10>")
	)
	(segment
		(start 75.22464 -373.511318)
		(end 80.438498 -399.349976)
		(width 0.14732)
		(layer "In2.Cu")
		(net "P5E_CPU1_PE4_TX_DN<10>")
	)
	(segment
		(start 98.028252 -288.10331)
		(end 98.027998 -288.103056)
		(width 0.0889)
		(layer "In2.Cu")
		(net "P5E_CPU1_PE4_TX_DN<10>")
	)
	(segment
		(start 98.967798 -286.285178)
		(end 98.967798 -286.475678)
		(width 0.0889)
		(layer "In2.Cu")
		(net "P5E_CPU1_PE4_TX_DN<10>")
	)
	(segment
		(start 97.592388 -299.508672)
		(end 96.270318 -302.70069)
		(width 0.14732)
		(layer "In2.Cu")
		(net "P5E_CPU1_PE4_TX_DN<10>")
	)
	(segment
		(start 99.062794 -285.661354)
		(end 99.219258 -285.932372)
		(width 0.0889)
		(layer "In2.Cu")
		(net "P5E_CPU1_PE4_TX_DN<10>")
	)
	(segment
		(start 98.967798 -286.475678)
		(end 98.967544 -286.475424)
		(width 0.0889)
		(layer "In2.Cu")
		(net "P5E_CPU1_PE4_TX_DN<10>")
	)
	(segment
		(start 99.001072 -286.285178)
		(end 98.967798 -286.285178)
		(width 0.0889)
		(layer "In2.Cu")
		(net "P5E_CPU1_PE4_TX_DN<10>")
	)
	(segment
		(start 80.438498 -399.349976)
		(end 80.438498 -405.117554)
		(width 0.14732)
		(layer "In2.Cu")
		(net "P5E_CPU1_PE4_TX_DN<10>")
	)
	(segment
		(start 96.270318 -302.70069)
		(end 71.536306 -327.43521)
		(width 0.14732)
		(layer "In2.Cu")
		(net "P5E_CPU1_PE4_TX_DN<10>")
	)
	(segment
		(start 98.497898 -287.279334)
		(end 98.497898 -287.289494)
		(width 0.0889)
		(layer "In2.Cu")
		(net "P5E_CPU1_PE4_TX_DN<10>")
	)
	(segment
		(start 99.195128 -286.021526)
		(end 99.195636 -286.021272)
		(width 0.0889)
		(layer "In2.Cu")
		(net "P5E_CPU1_PE4_TX_DN<10>")
	)
	(segment
		(start 98.028252 -288.087562)
		(end 98.028252 -288.10331)
		(width 0.0889)
		(layer "In2.Cu")
		(net "P5E_CPU1_PE4_TX_DN<10>")
	)
	(segment
		(start 97.850452 -288.422334)
		(end 97.841562 -288.42716)
		(width 0.0889)
		(layer "In2.Cu")
		(net "P5E_CPU1_PE4_TX_DN<10>")
	)
	(segment
		(start 68.619116 -334.478122)
		(end 68.45808 -335.490058)
		(width 0.14732)
		(layer "In2.Cu")
		(net "P5E_CPU1_PE4_TX_DN<10>")
	)
	(segment
		(start 97.592388 -290.982146)
		(end 97.592388 -291.004244)
		(width 0.0889)
		(layer "In2.Cu")
		(net "P5E_CPU1_PE4_TX_DN<10>")
	)
	(arc
		(start 98.027998 -288.103056)
		(mid 97.980759 -288.285807)
		(end 97.850452 -288.422334)
		(width 0.0889)
		(layer "In2.Cu")
		(net "P5E_CPU1_PE4_TX_DN<10>")
	)
	(arc
		(start 99.195636 -286.021272)
		(mid 99.078801 -286.138811)
		(end 99.001072 -286.285178)
		(width 0.0889)
		(layer "In2.Cu")
		(net "P5E_CPU1_PE4_TX_DN<10>")
	)
	(arc
		(start 98.781108 -286.799528)
		(mid 98.576262 -287.002097)
		(end 98.497898 -287.279334)
		(width 0.0889)
		(layer "In2.Cu")
		(net "P5E_CPU1_PE4_TX_DN<10>")
	)
	(arc
		(start 98.967544 -286.475424)
		(mid 98.920305 -286.658175)
		(end 98.789998 -286.794702)
		(width 0.0889)
		(layer "In2.Cu")
		(net "P5E_CPU1_PE4_TX_DN<10>")
	)
	(arc
		(start 98.497644 -287.28924)
		(mid 98.450183 -287.472391)
		(end 98.319336 -287.609026)
		(width 0.0889)
		(layer "In2.Cu")
		(net "P5E_CPU1_PE4_TX_DN<10>")
	)
	(arc
		(start 98.310446 -287.613852)
		(mid 98.107693 -287.813964)
		(end 98.028252 -288.087562)
		(width 0.0889)
		(layer "In2.Cu")
		(net "P5E_CPU1_PE4_TX_DN<10>")
	)
	(arc
		(start 97.558352 -289.113976)
		(mid 97.669582 -289.30718)
		(end 97.843848 -289.446208)
		(width 0.0889)
		(layer "In2.Cu")
		(net "P5E_CPU1_PE4_TX_DN<10>")
	)
	(arc
		(start 97.843848 -289.446208)
		(mid 97.952951 -289.530034)
		(end 98.027998 -289.645344)
		(width 0.0889)
		(layer "In2.Cu")
		(net "P5E_CPU1_PE4_TX_DN<10>")
	)
	(arc
		(start 97.841562 -288.42716)
		(mid 97.638767 -288.626107)
		(end 97.558352 -288.898584)
		(width 0.0889)
		(layer "In2.Cu")
		(net "P5E_CPU1_PE4_TX_DN<10>")
	)
	(segment
		(start 49.6316 -407.310082)
		(end 49.326038 -407.00452)
		(width 0.13208)
		(layer "F.Cu")
		(net "P5E_CPU1_PE4_TX_DN<0>")
	)
	(segment
		(start 49.30521 -408.250644)
		(end 49.6316 -407.924254)
		(width 0.13208)
		(layer "F.Cu")
		(net "P5E_CPU1_PE4_TX_DN<0>")
	)
	(segment
		(start 89.664794 -285.125414)
		(end 89.664794 -285.661354)
		(width 0.13208)
		(layer "F.Cu")
		(net "P5E_CPU1_PE4_TX_DN<0>")
	)
	(segment
		(start 49.6316 -407.924254)
		(end 49.6316 -407.310082)
		(width 0.13208)
		(layer "F.Cu")
		(net "P5E_CPU1_PE4_TX_DN<0>")
	)
	(segment
		(start 49.300638 -408.250644)
		(end 49.30521 -408.250644)
		(width 0.13208)
		(layer "F.Cu")
		(net "P5E_CPU1_PE4_TX_DN<0>")
	)
	(segment
		(start 58.02503 -325.333614)
		(end 57.846976 -326.278494)
		(width 0.14732)
		(layer "In2.Cu")
		(net "P5E_CPU1_PE4_TX_DN<0>")
	)
	(segment
		(start 88.117934 -289.488372)
		(end 88.117934 -290.297616)
		(width 0.14732)
		(layer "In2.Cu")
		(net "P5E_CPU1_PE4_TX_DN<0>")
	)
	(segment
		(start 89.382346 -286.799782)
		(end 89.381584 -286.80029)
		(width 0.0889)
		(layer "In2.Cu")
		(net "P5E_CPU1_PE4_TX_DN<0>")
	)
	(segment
		(start 49.806098 -400.195288)
		(end 49.806098 -405.117554)
		(width 0.14732)
		(layer "In2.Cu")
		(net "P5E_CPU1_PE4_TX_DN<0>")
	)
	(segment
		(start 88.160098 -289.42411)
		(end 88.117934 -289.466274)
		(width 0.0889)
		(layer "In2.Cu")
		(net "P5E_CPU1_PE4_TX_DN<0>")
	)
	(segment
		(start 88.451182 -288.422334)
		(end 88.446864 -288.424874)
		(width 0.0889)
		(layer "In2.Cu")
		(net "P5E_CPU1_PE4_TX_DN<0>")
	)
	(segment
		(start 88.921082 -287.608518)
		(end 88.912192 -287.613598)
		(width 0.0889)
		(layer "In2.Cu")
		(net "P5E_CPU1_PE4_TX_DN<0>")
	)
	(segment
		(start 57.154318 -373.601488)
		(end 49.806098 -400.195288)
		(width 0.14732)
		(layer "In2.Cu")
		(net "P5E_CPU1_PE4_TX_DN<0>")
	)
	(segment
		(start 88.117934 -289.466274)
		(end 88.117934 -289.488372)
		(width 0.0889)
		(layer "In2.Cu")
		(net "P5E_CPU1_PE4_TX_DN<0>")
	)
	(segment
		(start 58.293254 -324.685914)
		(end 58.02503 -325.333614)
		(width 0.14732)
		(layer "In2.Cu")
		(net "P5E_CPU1_PE4_TX_DN<0>")
	)
	(segment
		(start 80.790796 -301.302166)
		(end 76.834238 -308.900322)
		(width 0.14732)
		(layer "In2.Cu")
		(net "P5E_CPU1_PE4_TX_DN<0>")
	)
	(segment
		(start 89.569544 -286.456882)
		(end 89.569544 -286.48406)
		(width 0.0889)
		(layer "In2.Cu")
		(net "P5E_CPU1_PE4_TX_DN<0>")
	)
	(segment
		(start 58.196988 -360.883708)
		(end 57.154318 -373.601488)
		(width 0.14732)
		(layer "In2.Cu")
		(net "P5E_CPU1_PE4_TX_DN<0>")
	)
	(segment
		(start 88.440768 -288.428938)
		(end 88.432894 -288.433256)
		(width 0.0889)
		(layer "In2.Cu")
		(net "P5E_CPU1_PE4_TX_DN<0>")
	)
	(segment
		(start 57.846976 -326.278494)
		(end 57.764426 -333.724504)
		(width 0.14732)
		(layer "In2.Cu")
		(net "P5E_CPU1_PE4_TX_DN<0>")
	)
	(segment
		(start 49.620678 -406.70988)
		(end 49.326038 -407.00452)
		(width 0.14732)
		(layer "In2.Cu")
		(net "P5E_CPU1_PE4_TX_DN<0>")
	)
	(segment
		(start 88.160098 -288.905442)
		(end 88.160098 -289.42411)
		(width 0.0889)
		(layer "In2.Cu")
		(net "P5E_CPU1_PE4_TX_DN<0>")
	)
	(segment
		(start 89.381584 -286.80029)
		(end 89.37625 -286.803338)
		(width 0.0889)
		(layer "In2.Cu")
		(net "P5E_CPU1_PE4_TX_DN<0>")
	)
	(segment
		(start 76.834238 -308.900322)
		(end 66.398394 -319.33642)
		(width 0.14732)
		(layer "In2.Cu")
		(net "P5E_CPU1_PE4_TX_DN<0>")
	)
	(segment
		(start 89.664794 -285.661354)
		(end 89.821258 -285.932372)
		(width 0.0889)
		(layer "In2.Cu")
		(net "P5E_CPU1_PE4_TX_DN<0>")
	)
	(segment
		(start 84.78647 -293.628826)
		(end 80.790796 -301.302166)
		(width 0.14732)
		(layer "In2.Cu")
		(net "P5E_CPU1_PE4_TX_DN<0>")
	)
	(segment
		(start 88.629744 -288.09315)
		(end 88.629744 -288.103056)
		(width 0.0889)
		(layer "In2.Cu")
		(net "P5E_CPU1_PE4_TX_DN<0>")
	)
	(segment
		(start 49.806098 -405.117554)
		(end 49.620678 -405.302974)
		(width 0.14732)
		(layer "In2.Cu")
		(net "P5E_CPU1_PE4_TX_DN<0>")
	)
	(segment
		(start 57.764426 -333.724504)
		(end 57.97296 -339.356192)
		(width 0.14732)
		(layer "In2.Cu")
		(net "P5E_CPU1_PE4_TX_DN<0>")
	)
	(segment
		(start 89.821258 -285.932372)
		(end 89.797128 -286.021526)
		(width 0.0889)
		(layer "In2.Cu")
		(net "P5E_CPU1_PE4_TX_DN<0>")
	)
	(segment
		(start 66.398394 -319.33642)
		(end 63.308484 -320.616072)
		(width 0.14732)
		(layer "In2.Cu")
		(net "P5E_CPU1_PE4_TX_DN<0>")
	)
	(segment
		(start 88.446864 -288.424874)
		(end 88.442292 -288.427414)
		(width 0.0889)
		(layer "In2.Cu")
		(net "P5E_CPU1_PE4_TX_DN<0>")
	)
	(segment
		(start 63.308484 -320.616072)
		(end 60.458858 -322.52031)
		(width 0.14732)
		(layer "In2.Cu")
		(net "P5E_CPU1_PE4_TX_DN<0>")
	)
	(segment
		(start 49.620678 -405.302974)
		(end 49.620678 -406.70988)
		(width 0.14732)
		(layer "In2.Cu")
		(net "P5E_CPU1_PE4_TX_DN<0>")
	)
	(segment
		(start 57.97296 -339.356192)
		(end 58.196988 -360.883708)
		(width 0.14732)
		(layer "In2.Cu")
		(net "P5E_CPU1_PE4_TX_DN<0>")
	)
	(segment
		(start 60.458858 -322.52031)
		(end 58.293254 -324.685914)
		(width 0.14732)
		(layer "In2.Cu")
		(net "P5E_CPU1_PE4_TX_DN<0>")
	)
	(segment
		(start 88.117934 -290.297616)
		(end 84.78647 -293.628826)
		(width 0.14732)
		(layer "In2.Cu")
		(net "P5E_CPU1_PE4_TX_DN<0>")
	)
	(arc
		(start 88.432894 -288.433256)
		(mid 88.430859 -288.434522)
		(end 88.42883 -288.435796)
		(width 0.0889)
		(layer "In2.Cu")
		(net "P5E_CPU1_PE4_TX_DN<0>")
	)
	(arc
		(start 89.797128 -286.021526)
		(mid 89.788814 -286.027928)
		(end 89.780618 -286.03448)
		(width 0.0889)
		(layer "In2.Cu")
		(net "P5E_CPU1_PE4_TX_DN<0>")
	)
	(arc
		(start 88.42883 -288.435796)
		(mid 88.234623 -288.636366)
		(end 88.160098 -288.905442)
		(width 0.0889)
		(layer "In2.Cu")
		(net "P5E_CPU1_PE4_TX_DN<0>")
	)
	(arc
		(start 88.912192 -287.613598)
		(mid 88.707857 -287.816203)
		(end 88.629744 -288.09315)
		(width 0.0889)
		(layer "In2.Cu")
		(net "P5E_CPU1_PE4_TX_DN<0>")
	)
	(arc
		(start 89.37625 -286.803338)
		(mid 89.173663 -287.009689)
		(end 89.099644 -287.28924)
		(width 0.0889)
		(layer "In2.Cu")
		(net "P5E_CPU1_PE4_TX_DN<0>")
	)
	(arc
		(start 88.442292 -288.427414)
		(mid 88.441529 -288.428175)
		(end 88.440768 -288.428938)
		(width 0.0889)
		(layer "In2.Cu")
		(net "P5E_CPU1_PE4_TX_DN<0>")
	)
	(arc
		(start 89.099644 -287.28924)
		(mid 89.051965 -287.47214)
		(end 88.921082 -287.608518)
		(width 0.0889)
		(layer "In2.Cu")
		(net "P5E_CPU1_PE4_TX_DN<0>")
	)
	(arc
		(start 89.780618 -286.03448)
		(mid 89.628826 -286.222562)
		(end 89.569544 -286.456882)
		(width 0.0889)
		(layer "In2.Cu")
		(net "P5E_CPU1_PE4_TX_DN<0>")
	)
	(arc
		(start 89.569544 -286.48406)
		(mid 89.517274 -286.666425)
		(end 89.382346 -286.799782)
		(width 0.0889)
		(layer "In2.Cu")
		(net "P5E_CPU1_PE4_TX_DN<0>")
	)
	(arc
		(start 88.629744 -288.103056)
		(mid 88.582065 -288.285956)
		(end 88.451182 -288.422334)
		(width 0.0889)
		(layer "In2.Cu")
		(net "P5E_CPU1_PE4_TX_DN<0>")
	)
	(segment
		(start 77.4573 -409.72867)
		(end 77.758798 -410.030168)
		(width 0.13208)
		(layer "F.Cu")
		(net "P5E_CPU1_PE4_TX_C_DP<9>")
	)
	(segment
		(start 77.4573 -409.110942)
		(end 77.4573 -409.72867)
		(width 0.13208)
		(layer "F.Cu")
		(net "P5E_CPU1_PE4_TX_C_DP<9>")
	)
	(segment
		(start 77.784198 -408.784044)
		(end 77.4573 -409.110942)
		(width 0.13208)
		(layer "F.Cu")
		(net "P5E_CPU1_PE4_TX_C_DP<9>")
	)
	(segment
		(start 77.113638 -427.552612)
		(end 77.415644 -427.552612)
		(width 0.14732)
		(layer "In6.Cu")
		(net "P5E_CPU1_PE4_TX_C_DP<9>")
	)
	(segment
		(start 77.207872 -421.837866)
		(end 77.189584 -422.206166)
		(width 0.14732)
		(layer "In6.Cu")
		(net "P5E_CPU1_PE4_TX_C_DP<9>")
	)
	(segment
		(start 77.758798 -410.030168)
		(end 77.464158 -410.324808)
		(width 0.14732)
		(layer "In6.Cu")
		(net "P5E_CPU1_PE4_TX_C_DP<9>")
	)
	(segment
		(start 77.075284 -421.691562)
		(end 77.207872 -421.837866)
		(width 0.14732)
		(layer "In6.Cu")
		(net "P5E_CPU1_PE4_TX_C_DP<9>")
	)
	(segment
		(start 77.176376 -419.661594)
		(end 77.308964 -419.808152)
		(width 0.14732)
		(layer "In6.Cu")
		(net "P5E_CPU1_PE4_TX_C_DP<9>")
	)
	(segment
		(start 77.042772 -422.338754)
		(end 76.966318 -423.87774)
		(width 0.14732)
		(layer "In6.Cu")
		(net "P5E_CPU1_PE4_TX_C_DP<9>")
	)
	(segment
		(start 77.258418 -420.823136)
		(end 77.24013 -421.191182)
		(width 0.14732)
		(layer "In6.Cu")
		(net "P5E_CPU1_PE4_TX_C_DP<9>")
	)
	(segment
		(start 77.464158 -410.324808)
		(end 77.464158 -413.86887)
		(width 0.14732)
		(layer "In6.Cu")
		(net "P5E_CPU1_PE4_TX_C_DP<9>")
	)
	(segment
		(start 77.290676 -420.176198)
		(end 77.143864 -420.308786)
		(width 0.14732)
		(layer "In6.Cu")
		(net "P5E_CPU1_PE4_TX_C_DP<9>")
	)
	(segment
		(start 77.12583 -420.676578)
		(end 77.258418 -420.823136)
		(width 0.14732)
		(layer "In6.Cu")
		(net "P5E_CPU1_PE4_TX_C_DP<9>")
	)
	(segment
		(start 77.24013 -421.191182)
		(end 77.093572 -421.32377)
		(width 0.14732)
		(layer "In6.Cu")
		(net "P5E_CPU1_PE4_TX_C_DP<9>")
	)
	(segment
		(start 77.197966 -419.225476)
		(end 77.176376 -419.661594)
		(width 0.14732)
		(layer "In6.Cu")
		(net "P5E_CPU1_PE4_TX_C_DP<9>")
	)
	(segment
		(start 77.143864 -420.308786)
		(end 77.12583 -420.676578)
		(width 0.14732)
		(layer "In6.Cu")
		(net "P5E_CPU1_PE4_TX_C_DP<9>")
	)
	(segment
		(start 77.189584 -422.206166)
		(end 77.042772 -422.338754)
		(width 0.14732)
		(layer "In6.Cu")
		(net "P5E_CPU1_PE4_TX_C_DP<9>")
	)
	(segment
		(start 77.650086 -427.31817)
		(end 77.650086 -427.089824)
		(width 0.14732)
		(layer "In6.Cu")
		(net "P5E_CPU1_PE4_TX_C_DP<9>")
	)
	(segment
		(start 77.232256 -418.539676)
		(end 77.232256 -418.540184)
		(width 0.14732)
		(layer "In6.Cu")
		(net "P5E_CPU1_PE4_TX_C_DP<9>")
	)
	(segment
		(start 76.966318 -427.405292)
		(end 77.113638 -427.552612)
		(width 0.14732)
		(layer "In6.Cu")
		(net "P5E_CPU1_PE4_TX_C_DP<9>")
	)
	(segment
		(start 76.966318 -423.87774)
		(end 76.966318 -427.405292)
		(width 0.14732)
		(layer "In6.Cu")
		(net "P5E_CPU1_PE4_TX_C_DP<9>")
	)
	(segment
		(start 77.093572 -421.32377)
		(end 77.075284 -421.691562)
		(width 0.14732)
		(layer "In6.Cu")
		(net "P5E_CPU1_PE4_TX_C_DP<9>")
	)
	(segment
		(start 77.415644 -427.552612)
		(end 77.650086 -427.31817)
		(width 0.14732)
		(layer "In6.Cu")
		(net "P5E_CPU1_PE4_TX_C_DP<9>")
	)
	(segment
		(start 77.308964 -419.808152)
		(end 77.290676 -420.176198)
		(width 0.14732)
		(layer "In6.Cu")
		(net "P5E_CPU1_PE4_TX_C_DP<9>")
	)
	(segment
		(start 77.232256 -418.540184)
		(end 77.350366 -418.67074)
		(width 0.14732)
		(layer "In6.Cu")
		(net "P5E_CPU1_PE4_TX_C_DP<9>")
	)
	(segment
		(start 77.328776 -419.107366)
		(end 77.197966 -419.225476)
		(width 0.14732)
		(layer "In6.Cu")
		(net "P5E_CPU1_PE4_TX_C_DP<9>")
	)
	(segment
		(start 77.464158 -413.86887)
		(end 77.232256 -418.539676)
		(width 0.14732)
		(layer "In6.Cu")
		(net "P5E_CPU1_PE4_TX_C_DP<9>")
	)
	(segment
		(start 77.350366 -418.67074)
		(end 77.328776 -419.107366)
		(width 0.14732)
		(layer "In6.Cu")
		(net "P5E_CPU1_PE4_TX_C_DP<9>")
	)
	(segment
		(start 74.720958 -408.784044)
		(end 74.39406 -409.110942)
		(width 0.13208)
		(layer "F.Cu")
		(net "P5E_CPU1_PE4_TX_C_DP<8>")
	)
	(segment
		(start 74.39406 -409.110942)
		(end 74.39406 -409.72867)
		(width 0.13208)
		(layer "F.Cu")
		(net "P5E_CPU1_PE4_TX_C_DP<8>")
	)
	(segment
		(start 74.39406 -409.72867)
		(end 74.695558 -410.030168)
		(width 0.13208)
		(layer "F.Cu")
		(net "P5E_CPU1_PE4_TX_C_DP<8>")
	)
	(segment
		(start 74.50709 -414.399476)
		(end 74.518266 -414.767522)
		(width 0.14732)
		(layer "In6.Cu")
		(net "P5E_CPU1_PE4_TX_C_DP<8>")
	)
	(segment
		(start 74.694034 -415.91865)
		(end 74.705464 -416.28695)
		(width 0.14732)
		(layer "In6.Cu")
		(net "P5E_CPU1_PE4_TX_C_DP<8>")
	)
	(segment
		(start 74.695558 -410.030168)
		(end 74.400918 -410.324808)
		(width 0.14732)
		(layer "In6.Cu")
		(net "P5E_CPU1_PE4_TX_C_DP<8>")
	)
	(segment
		(start 74.642472 -414.255458)
		(end 74.50709 -414.399476)
		(width 0.14732)
		(layer "In6.Cu")
		(net "P5E_CPU1_PE4_TX_C_DP<8>")
	)
	(segment
		(start 74.455274 -412.73603)
		(end 74.599546 -412.871412)
		(width 0.14732)
		(layer "In6.Cu")
		(net "P5E_CPU1_PE4_TX_C_DP<8>")
	)
	(segment
		(start 74.673968 -415.271204)
		(end 74.538586 -415.415222)
		(width 0.14732)
		(layer "In6.Cu")
		(net "P5E_CPU1_PE4_TX_C_DP<8>")
	)
	(segment
		(start 74.518266 -414.767522)
		(end 74.662538 -414.902904)
		(width 0.14732)
		(layer "In6.Cu")
		(net "P5E_CPU1_PE4_TX_C_DP<8>")
	)
	(segment
		(start 74.400918 -410.969968)
		(end 74.455528 -412.734506)
		(width 0.14732)
		(layer "In6.Cu")
		(net "P5E_CPU1_PE4_TX_C_DP<8>")
	)
	(segment
		(start 75.415648 -426.552868)
		(end 75.65009 -426.318426)
		(width 0.14732)
		(layer "In6.Cu")
		(net "P5E_CPU1_PE4_TX_C_DP<8>")
	)
	(segment
		(start 74.966322 -426.405548)
		(end 75.113642 -426.552868)
		(width 0.14732)
		(layer "In6.Cu")
		(net "P5E_CPU1_PE4_TX_C_DP<8>")
	)
	(segment
		(start 74.455528 -412.734506)
		(end 74.455274 -412.73603)
		(width 0.14732)
		(layer "In6.Cu")
		(net "P5E_CPU1_PE4_TX_C_DP<8>")
	)
	(segment
		(start 74.73061 -421.635936)
		(end 74.730356 -421.638222)
		(width 0.14732)
		(layer "In6.Cu")
		(net "P5E_CPU1_PE4_TX_C_DP<8>")
	)
	(segment
		(start 74.581258 -416.799014)
		(end 74.72553 -416.934396)
		(width 0.14732)
		(layer "In6.Cu")
		(net "P5E_CPU1_PE4_TX_C_DP<8>")
	)
	(segment
		(start 74.400918 -410.324808)
		(end 74.400918 -410.969968)
		(width 0.14732)
		(layer "In6.Cu")
		(net "P5E_CPU1_PE4_TX_C_DP<8>")
	)
	(segment
		(start 74.599546 -412.871412)
		(end 74.610976 -413.239712)
		(width 0.14732)
		(layer "In6.Cu")
		(net "P5E_CPU1_PE4_TX_C_DP<8>")
	)
	(segment
		(start 74.730356 -421.638222)
		(end 74.839576 -425.166536)
		(width 0.14732)
		(layer "In6.Cu")
		(net "P5E_CPU1_PE4_TX_C_DP<8>")
	)
	(segment
		(start 74.610976 -413.239712)
		(end 74.475594 -413.38373)
		(width 0.14732)
		(layer "In6.Cu")
		(net "P5E_CPU1_PE4_TX_C_DP<8>")
	)
	(segment
		(start 74.736706 -417.302696)
		(end 74.601578 -417.446714)
		(width 0.14732)
		(layer "In6.Cu")
		(net "P5E_CPU1_PE4_TX_C_DP<8>")
	)
	(segment
		(start 74.538586 -415.415222)
		(end 74.549762 -415.783268)
		(width 0.14732)
		(layer "In6.Cu")
		(net "P5E_CPU1_PE4_TX_C_DP<8>")
	)
	(segment
		(start 74.631042 -413.887158)
		(end 74.642472 -414.255458)
		(width 0.14732)
		(layer "In6.Cu")
		(net "P5E_CPU1_PE4_TX_C_DP<8>")
	)
	(segment
		(start 74.662538 -414.902904)
		(end 74.673968 -415.271204)
		(width 0.14732)
		(layer "In6.Cu")
		(net "P5E_CPU1_PE4_TX_C_DP<8>")
	)
	(segment
		(start 74.549762 -415.783268)
		(end 74.694034 -415.91865)
		(width 0.14732)
		(layer "In6.Cu")
		(net "P5E_CPU1_PE4_TX_C_DP<8>")
	)
	(segment
		(start 75.113642 -426.552868)
		(end 75.415648 -426.552868)
		(width 0.14732)
		(layer "In6.Cu")
		(net "P5E_CPU1_PE4_TX_C_DP<8>")
	)
	(segment
		(start 75.65009 -426.318426)
		(end 75.65009 -426.089826)
		(width 0.14732)
		(layer "In6.Cu")
		(net "P5E_CPU1_PE4_TX_C_DP<8>")
	)
	(segment
		(start 74.72553 -416.934396)
		(end 74.736706 -417.302696)
		(width 0.14732)
		(layer "In6.Cu")
		(net "P5E_CPU1_PE4_TX_C_DP<8>")
	)
	(segment
		(start 74.570082 -416.430968)
		(end 74.581258 -416.799014)
		(width 0.14732)
		(layer "In6.Cu")
		(net "P5E_CPU1_PE4_TX_C_DP<8>")
	)
	(segment
		(start 74.601578 -417.446714)
		(end 74.73061 -421.635936)
		(width 0.14732)
		(layer "In6.Cu")
		(net "P5E_CPU1_PE4_TX_C_DP<8>")
	)
	(segment
		(start 74.839576 -425.166536)
		(end 74.966322 -426.405548)
		(width 0.14732)
		(layer "In6.Cu")
		(net "P5E_CPU1_PE4_TX_C_DP<8>")
	)
	(segment
		(start 74.705464 -416.28695)
		(end 74.570082 -416.430968)
		(width 0.14732)
		(layer "In6.Cu")
		(net "P5E_CPU1_PE4_TX_C_DP<8>")
	)
	(segment
		(start 74.48677 -413.751776)
		(end 74.631042 -413.887158)
		(width 0.14732)
		(layer "In6.Cu")
		(net "P5E_CPU1_PE4_TX_C_DP<8>")
	)
	(segment
		(start 74.475594 -413.38373)
		(end 74.48677 -413.751776)
		(width 0.14732)
		(layer "In6.Cu")
		(net "P5E_CPU1_PE4_TX_C_DP<8>")
	)
	(segment
		(start 71.657718 -408.784044)
		(end 71.33082 -409.110942)
		(width 0.13208)
		(layer "F.Cu")
		(net "P5E_CPU1_PE4_TX_C_DP<7>")
	)
	(segment
		(start 71.33082 -409.110942)
		(end 71.33082 -409.72867)
		(width 0.13208)
		(layer "F.Cu")
		(net "P5E_CPU1_PE4_TX_C_DP<7>")
	)
	(segment
		(start 71.33082 -409.72867)
		(end 71.632318 -410.030168)
		(width 0.13208)
		(layer "F.Cu")
		(net "P5E_CPU1_PE4_TX_C_DP<7>")
	)
	(segment
		(start 72.113648 -427.552612)
		(end 71.966328 -427.405292)
		(width 0.14732)
		(layer "In6.Cu")
		(net "P5E_CPU1_PE4_TX_C_DP<7>")
	)
	(segment
		(start 71.601838 -413.424878)
		(end 71.713598 -413.288734)
		(width 0.14732)
		(layer "In6.Cu")
		(net "P5E_CPU1_PE4_TX_C_DP<7>")
	)
	(segment
		(start 71.712328 -414.542224)
		(end 71.824088 -414.40608)
		(width 0.14732)
		(layer "In6.Cu")
		(net "P5E_CPU1_PE4_TX_C_DP<7>")
	)
	(segment
		(start 71.337678 -410.755338)
		(end 71.337678 -410.324808)
		(width 0.14732)
		(layer "In6.Cu")
		(net "P5E_CPU1_PE4_TX_C_DP<7>")
	)
	(segment
		(start 71.822818 -415.65957)
		(end 71.934578 -415.523426)
		(width 0.14732)
		(layer "In6.Cu")
		(net "P5E_CPU1_PE4_TX_C_DP<7>")
	)
	(segment
		(start 71.644764 -413.859472)
		(end 71.601838 -413.424878)
		(width 0.14732)
		(layer "In6.Cu")
		(net "P5E_CPU1_PE4_TX_C_DP<7>")
	)
	(segment
		(start 71.966328 -417.113212)
		(end 71.822818 -415.65957)
		(width 0.14732)
		(layer "In6.Cu")
		(net "P5E_CPU1_PE4_TX_C_DP<7>")
	)
	(segment
		(start 71.534274 -412.742126)
		(end 71.491348 -412.307532)
		(width 0.14732)
		(layer "In6.Cu")
		(net "P5E_CPU1_PE4_TX_C_DP<7>")
	)
	(segment
		(start 72.650096 -427.089824)
		(end 72.650096 -427.31817)
		(width 0.14732)
		(layer "In6.Cu")
		(net "P5E_CPU1_PE4_TX_C_DP<7>")
	)
	(segment
		(start 71.934578 -415.523426)
		(end 71.891398 -415.088578)
		(width 0.14732)
		(layer "In6.Cu")
		(net "P5E_CPU1_PE4_TX_C_DP<7>")
	)
	(segment
		(start 71.891398 -415.088578)
		(end 71.755254 -414.976818)
		(width 0.14732)
		(layer "In6.Cu")
		(net "P5E_CPU1_PE4_TX_C_DP<7>")
	)
	(segment
		(start 71.559928 -411.736286)
		(end 71.42353 -411.62478)
		(width 0.14732)
		(layer "In6.Cu")
		(net "P5E_CPU1_PE4_TX_C_DP<7>")
	)
	(segment
		(start 72.415654 -427.552612)
		(end 72.113648 -427.552612)
		(width 0.14732)
		(layer "In6.Cu")
		(net "P5E_CPU1_PE4_TX_C_DP<7>")
	)
	(segment
		(start 71.670418 -412.853886)
		(end 71.534274 -412.742126)
		(width 0.14732)
		(layer "In6.Cu")
		(net "P5E_CPU1_PE4_TX_C_DP<7>")
	)
	(segment
		(start 71.780908 -413.971232)
		(end 71.644764 -413.859472)
		(width 0.14732)
		(layer "In6.Cu")
		(net "P5E_CPU1_PE4_TX_C_DP<7>")
	)
	(segment
		(start 71.602854 -412.171388)
		(end 71.559928 -411.736286)
		(width 0.14732)
		(layer "In6.Cu")
		(net "P5E_CPU1_PE4_TX_C_DP<7>")
	)
	(segment
		(start 71.713598 -413.288734)
		(end 71.670418 -412.853886)
		(width 0.14732)
		(layer "In6.Cu")
		(net "P5E_CPU1_PE4_TX_C_DP<7>")
	)
	(segment
		(start 71.966328 -427.405292)
		(end 71.966328 -417.113212)
		(width 0.14732)
		(layer "In6.Cu")
		(net "P5E_CPU1_PE4_TX_C_DP<7>")
	)
	(segment
		(start 71.491348 -412.307532)
		(end 71.602854 -412.171388)
		(width 0.14732)
		(layer "In6.Cu")
		(net "P5E_CPU1_PE4_TX_C_DP<7>")
	)
	(segment
		(start 71.337678 -410.324808)
		(end 71.632318 -410.030168)
		(width 0.14732)
		(layer "In6.Cu")
		(net "P5E_CPU1_PE4_TX_C_DP<7>")
	)
	(segment
		(start 72.650096 -427.31817)
		(end 72.415654 -427.552612)
		(width 0.14732)
		(layer "In6.Cu")
		(net "P5E_CPU1_PE4_TX_C_DP<7>")
	)
	(segment
		(start 71.42353 -411.62478)
		(end 71.337678 -410.755338)
		(width 0.14732)
		(layer "In6.Cu")
		(net "P5E_CPU1_PE4_TX_C_DP<7>")
	)
	(segment
		(start 71.824088 -414.40608)
		(end 71.780908 -413.971232)
		(width 0.14732)
		(layer "In6.Cu")
		(net "P5E_CPU1_PE4_TX_C_DP<7>")
	)
	(segment
		(start 71.755254 -414.976818)
		(end 71.712328 -414.542224)
		(width 0.14732)
		(layer "In6.Cu")
		(net "P5E_CPU1_PE4_TX_C_DP<7>")
	)
	(segment
		(start 68.26758 -409.72867)
		(end 68.569078 -410.030168)
		(width 0.13208)
		(layer "F.Cu")
		(net "P5E_CPU1_PE4_TX_C_DP<6>")
	)
	(segment
		(start 68.26758 -409.110942)
		(end 68.26758 -409.72867)
		(width 0.13208)
		(layer "F.Cu")
		(net "P5E_CPU1_PE4_TX_C_DP<6>")
	)
	(segment
		(start 68.594478 -408.784044)
		(end 68.26758 -409.110942)
		(width 0.13208)
		(layer "F.Cu")
		(net "P5E_CPU1_PE4_TX_C_DP<6>")
	)
	(segment
		(start 68.952364 -412.974282)
		(end 68.838572 -412.552134)
		(width 0.14732)
		(layer "In6.Cu")
		(net "P5E_CPU1_PE4_TX_C_DP<6>")
	)
	(segment
		(start 69.157088 -414.211008)
		(end 69.244718 -414.058354)
		(width 0.14732)
		(layer "In6.Cu")
		(net "P5E_CPU1_PE4_TX_C_DP<6>")
	)
	(segment
		(start 70.50278 -426.578268)
		(end 70.139052 -426.578268)
		(width 0.14732)
		(layer "In6.Cu")
		(net "P5E_CPU1_PE4_TX_C_DP<6>")
	)
	(segment
		(start 68.86448 -413.126936)
		(end 68.952364 -412.974282)
		(width 0.14732)
		(layer "In6.Cu")
		(net "P5E_CPU1_PE4_TX_C_DP<6>")
	)
	(segment
		(start 68.274438 -410.939996)
		(end 68.274438 -410.324808)
		(width 0.14732)
		(layer "In6.Cu")
		(net "P5E_CPU1_PE4_TX_C_DP<6>")
	)
	(segment
		(start 68.654676 -411.871414)
		(end 68.540884 -411.44952)
		(width 0.14732)
		(layer "In6.Cu")
		(net "P5E_CPU1_PE4_TX_C_DP<6>")
	)
	(segment
		(start 68.274438 -410.324808)
		(end 68.569078 -410.030168)
		(width 0.14732)
		(layer "In6.Cu")
		(net "P5E_CPU1_PE4_TX_C_DP<6>")
	)
	(segment
		(start 69.966332 -426.405548)
		(end 69.966332 -417.211764)
		(width 0.14732)
		(layer "In6.Cu")
		(net "P5E_CPU1_PE4_TX_C_DP<6>")
	)
	(segment
		(start 70.139052 -426.578268)
		(end 69.966332 -426.405548)
		(width 0.14732)
		(layer "In6.Cu")
		(net "P5E_CPU1_PE4_TX_C_DP<6>")
	)
	(segment
		(start 68.978018 -413.548576)
		(end 68.86448 -413.126936)
		(width 0.14732)
		(layer "In6.Cu")
		(net "P5E_CPU1_PE4_TX_C_DP<6>")
	)
	(segment
		(start 68.838572 -412.552134)
		(end 68.685664 -412.464504)
		(width 0.14732)
		(layer "In6.Cu")
		(net "P5E_CPU1_PE4_TX_C_DP<6>")
	)
	(segment
		(start 69.244718 -414.058354)
		(end 69.130926 -413.63646)
		(width 0.14732)
		(layer "In6.Cu")
		(net "P5E_CPU1_PE4_TX_C_DP<6>")
	)
	(segment
		(start 69.130926 -413.63646)
		(end 68.978018 -413.548576)
		(width 0.14732)
		(layer "In6.Cu")
		(net "P5E_CPU1_PE4_TX_C_DP<6>")
	)
	(segment
		(start 69.966332 -417.211764)
		(end 69.449442 -415.29508)
		(width 0.14732)
		(layer "In6.Cu")
		(net "P5E_CPU1_PE4_TX_C_DP<6>")
	)
	(segment
		(start 68.540884 -411.44952)
		(end 68.387976 -411.361636)
		(width 0.14732)
		(layer "In6.Cu")
		(net "P5E_CPU1_PE4_TX_C_DP<6>")
	)
	(segment
		(start 69.270626 -414.632648)
		(end 69.157088 -414.211008)
		(width 0.14732)
		(layer "In6.Cu")
		(net "P5E_CPU1_PE4_TX_C_DP<6>")
	)
	(segment
		(start 69.537326 -415.142426)
		(end 69.423534 -414.720532)
		(width 0.14732)
		(layer "In6.Cu")
		(net "P5E_CPU1_PE4_TX_C_DP<6>")
	)
	(segment
		(start 70.6501 -426.089826)
		(end 70.6501 -426.430948)
		(width 0.14732)
		(layer "In6.Cu")
		(net "P5E_CPU1_PE4_TX_C_DP<6>")
	)
	(segment
		(start 68.567046 -412.024068)
		(end 68.654676 -411.871414)
		(width 0.14732)
		(layer "In6.Cu")
		(net "P5E_CPU1_PE4_TX_C_DP<6>")
	)
	(segment
		(start 69.449442 -415.29508)
		(end 69.537326 -415.142426)
		(width 0.14732)
		(layer "In6.Cu")
		(net "P5E_CPU1_PE4_TX_C_DP<6>")
	)
	(segment
		(start 70.6501 -426.430948)
		(end 70.50278 -426.578268)
		(width 0.14732)
		(layer "In6.Cu")
		(net "P5E_CPU1_PE4_TX_C_DP<6>")
	)
	(segment
		(start 68.387976 -411.361636)
		(end 68.274438 -410.939996)
		(width 0.14732)
		(layer "In6.Cu")
		(net "P5E_CPU1_PE4_TX_C_DP<6>")
	)
	(segment
		(start 68.685664 -412.464504)
		(end 68.567046 -412.024068)
		(width 0.14732)
		(layer "In6.Cu")
		(net "P5E_CPU1_PE4_TX_C_DP<6>")
	)
	(segment
		(start 69.423534 -414.720532)
		(end 69.270626 -414.632648)
		(width 0.14732)
		(layer "In6.Cu")
		(net "P5E_CPU1_PE4_TX_C_DP<6>")
	)
	(segment
		(start 65.531238 -408.784044)
		(end 65.20434 -409.110942)
		(width 0.13208)
		(layer "F.Cu")
		(net "P5E_CPU1_PE4_TX_C_DP<5>")
	)
	(segment
		(start 65.20434 -409.110942)
		(end 65.20434 -409.72867)
		(width 0.13208)
		(layer "F.Cu")
		(net "P5E_CPU1_PE4_TX_C_DP<5>")
	)
	(segment
		(start 65.20434 -409.72867)
		(end 65.505838 -410.030168)
		(width 0.13208)
		(layer "F.Cu")
		(net "P5E_CPU1_PE4_TX_C_DP<5>")
	)
	(segment
		(start 68.502784 -427.510448)
		(end 68.071492 -427.510448)
		(width 0.14732)
		(layer "In6.Cu")
		(net "P5E_CPU1_PE4_TX_C_DP<5>")
	)
	(segment
		(start 65.706752 -411.817058)
		(end 65.211198 -410.718)
		(width 0.14732)
		(layer "In6.Cu")
		(net "P5E_CPU1_PE4_TX_C_DP<5>")
	)
	(segment
		(start 66.33337 -412.902908)
		(end 66.168524 -412.840424)
		(width 0.14732)
		(layer "In6.Cu")
		(net "P5E_CPU1_PE4_TX_C_DP<5>")
	)
	(segment
		(start 65.211198 -410.324808)
		(end 65.505838 -410.030168)
		(width 0.14732)
		(layer "In6.Cu")
		(net "P5E_CPU1_PE4_TX_C_DP<5>")
	)
	(segment
		(start 67.966336 -427.405292)
		(end 67.966336 -416.827462)
		(width 0.14732)
		(layer "In6.Cu")
		(net "P5E_CPU1_PE4_TX_C_DP<5>")
	)
	(segment
		(start 67.966336 -416.827462)
		(end 67.427856 -415.6329)
		(width 0.14732)
		(layer "In6.Cu")
		(net "P5E_CPU1_PE4_TX_C_DP<5>")
	)
	(segment
		(start 67.427856 -415.6329)
		(end 67.490086 -415.468308)
		(width 0.14732)
		(layer "In6.Cu")
		(net "P5E_CPU1_PE4_TX_C_DP<5>")
	)
	(segment
		(start 66.925952 -414.520126)
		(end 66.988182 -414.355534)
		(width 0.14732)
		(layer "In6.Cu")
		(net "P5E_CPU1_PE4_TX_C_DP<5>")
	)
	(segment
		(start 68.650104 -427.089824)
		(end 68.650104 -427.363128)
		(width 0.14732)
		(layer "In6.Cu")
		(net "P5E_CPU1_PE4_TX_C_DP<5>")
	)
	(segment
		(start 68.071492 -427.510448)
		(end 67.966336 -427.405292)
		(width 0.14732)
		(layer "In6.Cu")
		(net "P5E_CPU1_PE4_TX_C_DP<5>")
	)
	(segment
		(start 67.310508 -415.069782)
		(end 67.145662 -415.007552)
		(width 0.14732)
		(layer "In6.Cu")
		(net "P5E_CPU1_PE4_TX_C_DP<5>")
	)
	(segment
		(start 66.450464 -413.466026)
		(end 66.512948 -413.301434)
		(width 0.14732)
		(layer "In6.Cu")
		(net "P5E_CPU1_PE4_TX_C_DP<5>")
	)
	(segment
		(start 66.643758 -413.894778)
		(end 66.450464 -413.466026)
		(width 0.14732)
		(layer "In6.Cu")
		(net "P5E_CPU1_PE4_TX_C_DP<5>")
	)
	(segment
		(start 66.168524 -412.840424)
		(end 65.988946 -412.442406)
		(width 0.14732)
		(layer "In6.Cu")
		(net "P5E_CPU1_PE4_TX_C_DP<5>")
	)
	(segment
		(start 67.490086 -415.468308)
		(end 67.310508 -415.069782)
		(width 0.14732)
		(layer "In6.Cu")
		(net "P5E_CPU1_PE4_TX_C_DP<5>")
	)
	(segment
		(start 65.871598 -411.879288)
		(end 65.706752 -411.817058)
		(width 0.14732)
		(layer "In6.Cu")
		(net "P5E_CPU1_PE4_TX_C_DP<5>")
	)
	(segment
		(start 65.211198 -410.718)
		(end 65.211198 -410.324808)
		(width 0.14732)
		(layer "In6.Cu")
		(net "P5E_CPU1_PE4_TX_C_DP<5>")
	)
	(segment
		(start 68.650104 -427.363128)
		(end 68.502784 -427.510448)
		(width 0.14732)
		(layer "In6.Cu")
		(net "P5E_CPU1_PE4_TX_C_DP<5>")
	)
	(segment
		(start 66.512948 -413.301434)
		(end 66.33337 -412.902908)
		(width 0.14732)
		(layer "In6.Cu")
		(net "P5E_CPU1_PE4_TX_C_DP<5>")
	)
	(segment
		(start 66.808604 -413.957008)
		(end 66.643758 -413.894778)
		(width 0.14732)
		(layer "In6.Cu")
		(net "P5E_CPU1_PE4_TX_C_DP<5>")
	)
	(segment
		(start 66.988182 -414.355534)
		(end 66.808604 -413.957008)
		(width 0.14732)
		(layer "In6.Cu")
		(net "P5E_CPU1_PE4_TX_C_DP<5>")
	)
	(segment
		(start 65.988946 -412.442406)
		(end 66.051176 -412.277814)
		(width 0.14732)
		(layer "In6.Cu")
		(net "P5E_CPU1_PE4_TX_C_DP<5>")
	)
	(segment
		(start 67.145662 -415.007552)
		(end 66.925952 -414.520126)
		(width 0.14732)
		(layer "In6.Cu")
		(net "P5E_CPU1_PE4_TX_C_DP<5>")
	)
	(segment
		(start 66.051176 -412.277814)
		(end 65.871598 -411.879288)
		(width 0.14732)
		(layer "In6.Cu")
		(net "P5E_CPU1_PE4_TX_C_DP<5>")
	)
	(segment
		(start 62.1411 -409.110942)
		(end 62.1411 -409.72867)
		(width 0.13208)
		(layer "F.Cu")
		(net "P5E_CPU1_PE4_TX_C_DP<4>")
	)
	(segment
		(start 62.467998 -408.784044)
		(end 62.1411 -409.110942)
		(width 0.13208)
		(layer "F.Cu")
		(net "P5E_CPU1_PE4_TX_C_DP<4>")
	)
	(segment
		(start 62.1411 -409.72867)
		(end 62.442598 -410.030168)
		(width 0.13208)
		(layer "F.Cu")
		(net "P5E_CPU1_PE4_TX_C_DP<4>")
	)
	(segment
		(start 65.539874 -416.186112)
		(end 65.31483 -415.811208)
		(width 0.14732)
		(layer "In6.Cu")
		(net "P5E_CPU1_PE4_TX_C_DP<4>")
	)
	(segment
		(start 63.228474 -412.335218)
		(end 63.003176 -411.960568)
		(width 0.14732)
		(layer "In6.Cu")
		(net "P5E_CPU1_PE4_TX_C_DP<4>")
	)
	(segment
		(start 66.502788 -426.570648)
		(end 66.13144 -426.570648)
		(width 0.14732)
		(layer "In6.Cu")
		(net "P5E_CPU1_PE4_TX_C_DP<4>")
	)
	(segment
		(start 65.497202 -416.3568)
		(end 65.539874 -416.186112)
		(width 0.14732)
		(layer "In6.Cu")
		(net "P5E_CPU1_PE4_TX_C_DP<4>")
	)
	(segment
		(start 64.341502 -414.43148)
		(end 64.384174 -414.260792)
		(width 0.14732)
		(layer "In6.Cu")
		(net "P5E_CPU1_PE4_TX_C_DP<4>")
	)
	(segment
		(start 64.919352 -415.39414)
		(end 64.962024 -415.223452)
		(width 0.14732)
		(layer "In6.Cu")
		(net "P5E_CPU1_PE4_TX_C_DP<4>")
	)
	(segment
		(start 62.832488 -411.917896)
		(end 62.147958 -410.777182)
		(width 0.14732)
		(layer "In6.Cu")
		(net "P5E_CPU1_PE4_TX_C_DP<4>")
	)
	(segment
		(start 64.566292 -414.805876)
		(end 64.341502 -414.43148)
		(width 0.14732)
		(layer "In6.Cu")
		(net "P5E_CPU1_PE4_TX_C_DP<4>")
	)
	(segment
		(start 63.58128 -412.923228)
		(end 63.410592 -412.880556)
		(width 0.14732)
		(layer "In6.Cu")
		(net "P5E_CPU1_PE4_TX_C_DP<4>")
	)
	(segment
		(start 66.650108 -426.089826)
		(end 66.650108 -426.423328)
		(width 0.14732)
		(layer "In6.Cu")
		(net "P5E_CPU1_PE4_TX_C_DP<4>")
	)
	(segment
		(start 65.966848 -426.406056)
		(end 65.966848 -417.139628)
		(width 0.14732)
		(layer "In6.Cu")
		(net "P5E_CPU1_PE4_TX_C_DP<4>")
	)
	(segment
		(start 65.31483 -415.811208)
		(end 65.144142 -415.768536)
		(width 0.14732)
		(layer "In6.Cu")
		(net "P5E_CPU1_PE4_TX_C_DP<4>")
	)
	(segment
		(start 64.73698 -414.848548)
		(end 64.566292 -414.805876)
		(width 0.14732)
		(layer "In6.Cu")
		(net "P5E_CPU1_PE4_TX_C_DP<4>")
	)
	(segment
		(start 62.147958 -410.324808)
		(end 62.442598 -410.030168)
		(width 0.14732)
		(layer "In6.Cu")
		(net "P5E_CPU1_PE4_TX_C_DP<4>")
	)
	(segment
		(start 66.13144 -426.570648)
		(end 65.966848 -426.406056)
		(width 0.14732)
		(layer "In6.Cu")
		(net "P5E_CPU1_PE4_TX_C_DP<4>")
	)
	(segment
		(start 62.147958 -410.777182)
		(end 62.147958 -410.324808)
		(width 0.14732)
		(layer "In6.Cu")
		(net "P5E_CPU1_PE4_TX_C_DP<4>")
	)
	(segment
		(start 64.384174 -414.260792)
		(end 64.15913 -413.885888)
		(width 0.14732)
		(layer "In6.Cu")
		(net "P5E_CPU1_PE4_TX_C_DP<4>")
	)
	(segment
		(start 65.144142 -415.768536)
		(end 64.919352 -415.39414)
		(width 0.14732)
		(layer "In6.Cu")
		(net "P5E_CPU1_PE4_TX_C_DP<4>")
	)
	(segment
		(start 64.962024 -415.223452)
		(end 64.73698 -414.848548)
		(width 0.14732)
		(layer "In6.Cu")
		(net "P5E_CPU1_PE4_TX_C_DP<4>")
	)
	(segment
		(start 63.003176 -411.960568)
		(end 62.832488 -411.917896)
		(width 0.14732)
		(layer "In6.Cu")
		(net "P5E_CPU1_PE4_TX_C_DP<4>")
	)
	(segment
		(start 66.650108 -426.423328)
		(end 66.502788 -426.570648)
		(width 0.14732)
		(layer "In6.Cu")
		(net "P5E_CPU1_PE4_TX_C_DP<4>")
	)
	(segment
		(start 64.15913 -413.885888)
		(end 63.988442 -413.843216)
		(width 0.14732)
		(layer "In6.Cu")
		(net "P5E_CPU1_PE4_TX_C_DP<4>")
	)
	(segment
		(start 63.185802 -412.50616)
		(end 63.228474 -412.335218)
		(width 0.14732)
		(layer "In6.Cu")
		(net "P5E_CPU1_PE4_TX_C_DP<4>")
	)
	(segment
		(start 63.988442 -413.843216)
		(end 63.763652 -413.46882)
		(width 0.14732)
		(layer "In6.Cu")
		(net "P5E_CPU1_PE4_TX_C_DP<4>")
	)
	(segment
		(start 63.806324 -413.298132)
		(end 63.58128 -412.923228)
		(width 0.14732)
		(layer "In6.Cu")
		(net "P5E_CPU1_PE4_TX_C_DP<4>")
	)
	(segment
		(start 63.763652 -413.46882)
		(end 63.806324 -413.298132)
		(width 0.14732)
		(layer "In6.Cu")
		(net "P5E_CPU1_PE4_TX_C_DP<4>")
	)
	(segment
		(start 65.966848 -417.139628)
		(end 65.497202 -416.3568)
		(width 0.14732)
		(layer "In6.Cu")
		(net "P5E_CPU1_PE4_TX_C_DP<4>")
	)
	(segment
		(start 63.410592 -412.880556)
		(end 63.185802 -412.50616)
		(width 0.14732)
		(layer "In6.Cu")
		(net "P5E_CPU1_PE4_TX_C_DP<4>")
	)
	(segment
		(start 59.07786 -409.72867)
		(end 59.379358 -410.030168)
		(width 0.13208)
		(layer "F.Cu")
		(net "P5E_CPU1_PE4_TX_C_DP<3>")
	)
	(segment
		(start 59.07786 -409.110942)
		(end 59.07786 -409.72867)
		(width 0.13208)
		(layer "F.Cu")
		(net "P5E_CPU1_PE4_TX_C_DP<3>")
	)
	(segment
		(start 59.404758 -408.784044)
		(end 59.07786 -409.110942)
		(width 0.13208)
		(layer "F.Cu")
		(net "P5E_CPU1_PE4_TX_C_DP<3>")
	)
	(segment
		(start 60.74537 -412.828232)
		(end 60.57138 -412.8008)
		(width 0.14732)
		(layer "In6.Cu")
		(net "P5E_CPU1_PE4_TX_C_DP<3>")
	)
	(segment
		(start 59.910472 -411.893004)
		(end 59.084718 -410.759148)
		(width 0.14732)
		(layer "In6.Cu")
		(net "P5E_CPU1_PE4_TX_C_DP<3>")
	)
	(segment
		(start 63.712344 -417.114228)
		(end 63.712344 -417.113974)
		(width 0.14732)
		(layer "In6.Cu")
		(net "P5E_CPU1_PE4_TX_C_DP<3>")
	)
	(segment
		(start 62.29731 -415.170874)
		(end 62.324488 -414.997138)
		(width 0.14732)
		(layer "In6.Cu")
		(net "P5E_CPU1_PE4_TX_C_DP<3>")
	)
	(segment
		(start 63.712344 -417.113974)
		(end 63.711328 -417.112704)
		(width 0.14732)
		(layer "In6.Cu")
		(net "P5E_CPU1_PE4_TX_C_DP<3>")
	)
	(segment
		(start 62.324488 -414.997138)
		(end 62.067186 -414.643824)
		(width 0.14732)
		(layer "In6.Cu")
		(net "P5E_CPU1_PE4_TX_C_DP<3>")
	)
	(segment
		(start 64.650112 -427.089824)
		(end 64.650112 -427.31817)
		(width 0.14732)
		(layer "In6.Cu")
		(net "P5E_CPU1_PE4_TX_C_DP<3>")
	)
	(segment
		(start 60.341764 -412.27375)
		(end 60.084208 -411.920436)
		(width 0.14732)
		(layer "In6.Cu")
		(net "P5E_CPU1_PE4_TX_C_DP<3>")
	)
	(segment
		(start 61.232288 -413.708596)
		(end 60.97524 -413.355536)
		(width 0.14732)
		(layer "In6.Cu")
		(net "P5E_CPU1_PE4_TX_C_DP<3>")
	)
	(segment
		(start 64.41567 -427.552612)
		(end 64.113664 -427.552612)
		(width 0.14732)
		(layer "In6.Cu")
		(net "P5E_CPU1_PE4_TX_C_DP<3>")
	)
	(segment
		(start 59.084718 -410.324808)
		(end 59.379358 -410.030168)
		(width 0.14732)
		(layer "In6.Cu")
		(net "P5E_CPU1_PE4_TX_C_DP<3>")
	)
	(segment
		(start 60.314332 -412.44774)
		(end 60.341764 -412.27375)
		(width 0.14732)
		(layer "In6.Cu")
		(net "P5E_CPU1_PE4_TX_C_DP<3>")
	)
	(segment
		(start 60.57138 -412.8008)
		(end 60.314332 -412.44774)
		(width 0.14732)
		(layer "In6.Cu")
		(net "P5E_CPU1_PE4_TX_C_DP<3>")
	)
	(segment
		(start 60.97524 -413.355536)
		(end 61.002672 -413.181546)
		(width 0.14732)
		(layer "In6.Cu")
		(net "P5E_CPU1_PE4_TX_C_DP<3>")
	)
	(segment
		(start 61.893196 -414.616392)
		(end 61.636148 -414.263332)
		(width 0.14732)
		(layer "In6.Cu")
		(net "P5E_CPU1_PE4_TX_C_DP<3>")
	)
	(segment
		(start 64.650112 -427.31817)
		(end 64.41567 -427.552612)
		(width 0.14732)
		(layer "In6.Cu")
		(net "P5E_CPU1_PE4_TX_C_DP<3>")
	)
	(segment
		(start 60.084208 -411.920436)
		(end 59.910472 -411.893004)
		(width 0.14732)
		(layer "In6.Cu")
		(net "P5E_CPU1_PE4_TX_C_DP<3>")
	)
	(segment
		(start 61.636148 -414.263332)
		(end 61.66358 -414.089342)
		(width 0.14732)
		(layer "In6.Cu")
		(net "P5E_CPU1_PE4_TX_C_DP<3>")
	)
	(segment
		(start 63.966344 -427.405292)
		(end 63.966344 -417.464748)
		(width 0.14732)
		(layer "In6.Cu")
		(net "P5E_CPU1_PE4_TX_C_DP<3>")
	)
	(segment
		(start 59.084718 -410.759148)
		(end 59.084718 -410.324808)
		(width 0.14732)
		(layer "In6.Cu")
		(net "P5E_CPU1_PE4_TX_C_DP<3>")
	)
	(segment
		(start 61.406278 -413.736028)
		(end 61.232288 -413.708596)
		(width 0.14732)
		(layer "In6.Cu")
		(net "P5E_CPU1_PE4_TX_C_DP<3>")
	)
	(segment
		(start 63.966344 -417.464748)
		(end 63.712344 -417.114228)
		(width 0.14732)
		(layer "In6.Cu")
		(net "P5E_CPU1_PE4_TX_C_DP<3>")
	)
	(segment
		(start 61.002672 -413.181546)
		(end 60.74537 -412.828232)
		(width 0.14732)
		(layer "In6.Cu")
		(net "P5E_CPU1_PE4_TX_C_DP<3>")
	)
	(segment
		(start 62.067186 -414.643824)
		(end 61.893196 -414.616392)
		(width 0.14732)
		(layer "In6.Cu")
		(net "P5E_CPU1_PE4_TX_C_DP<3>")
	)
	(segment
		(start 64.113664 -427.552612)
		(end 63.966344 -427.405292)
		(width 0.14732)
		(layer "In6.Cu")
		(net "P5E_CPU1_PE4_TX_C_DP<3>")
	)
	(segment
		(start 61.66358 -414.089342)
		(end 61.406278 -413.736028)
		(width 0.14732)
		(layer "In6.Cu")
		(net "P5E_CPU1_PE4_TX_C_DP<3>")
	)
	(segment
		(start 63.711328 -417.112704)
		(end 62.29731 -415.170874)
		(width 0.14732)
		(layer "In6.Cu")
		(net "P5E_CPU1_PE4_TX_C_DP<3>")
	)
	(segment
		(start 56.01462 -409.72867)
		(end 56.316118 -410.030168)
		(width 0.13208)
		(layer "F.Cu")
		(net "P5E_CPU1_PE4_TX_C_DP<2>")
	)
	(segment
		(start 56.01462 -409.110942)
		(end 56.01462 -409.72867)
		(width 0.13208)
		(layer "F.Cu")
		(net "P5E_CPU1_PE4_TX_C_DP<2>")
	)
	(segment
		(start 56.341518 -408.784044)
		(end 56.01462 -409.110942)
		(width 0.13208)
		(layer "F.Cu")
		(net "P5E_CPU1_PE4_TX_C_DP<2>")
	)
	(segment
		(start 58.158634 -412.858458)
		(end 57.982866 -412.853886)
		(width 0.14732)
		(layer "In6.Cu")
		(net "P5E_CPU1_PE4_TX_C_DP<2>")
	)
	(segment
		(start 56.021478 -410.787596)
		(end 56.021478 -410.324808)
		(width 0.14732)
		(layer "In6.Cu")
		(net "P5E_CPU1_PE4_TX_C_DP<2>")
	)
	(segment
		(start 57.209944 -412.039308)
		(end 56.021478 -410.787596)
		(width 0.14732)
		(layer "In6.Cu")
		(net "P5E_CPU1_PE4_TX_C_DP<2>")
	)
	(segment
		(start 58.459878 -413.17545)
		(end 58.158634 -412.858458)
		(width 0.14732)
		(layer "In6.Cu")
		(net "P5E_CPU1_PE4_TX_C_DP<2>")
	)
	(segment
		(start 59.233054 -413.989774)
		(end 58.93181 -413.672782)
		(width 0.14732)
		(layer "In6.Cu")
		(net "P5E_CPU1_PE4_TX_C_DP<2>")
	)
	(segment
		(start 59.228482 -414.165796)
		(end 59.233054 -413.989774)
		(width 0.14732)
		(layer "In6.Cu")
		(net "P5E_CPU1_PE4_TX_C_DP<2>")
	)
	(segment
		(start 57.385712 -412.04388)
		(end 57.209944 -412.039308)
		(width 0.14732)
		(layer "In6.Cu")
		(net "P5E_CPU1_PE4_TX_C_DP<2>")
	)
	(segment
		(start 62.139068 -426.578268)
		(end 61.966348 -426.405548)
		(width 0.14732)
		(layer "In6.Cu")
		(net "P5E_CPU1_PE4_TX_C_DP<2>")
	)
	(segment
		(start 62.650116 -426.430948)
		(end 62.502796 -426.578268)
		(width 0.14732)
		(layer "In6.Cu")
		(net "P5E_CPU1_PE4_TX_C_DP<2>")
	)
	(segment
		(start 60.001658 -414.98012)
		(end 60.00623 -414.804098)
		(width 0.14732)
		(layer "In6.Cu")
		(net "P5E_CPU1_PE4_TX_C_DP<2>")
	)
	(segment
		(start 61.966348 -426.405548)
		(end 61.966348 -417.049966)
		(width 0.14732)
		(layer "In6.Cu")
		(net "P5E_CPU1_PE4_TX_C_DP<2>")
	)
	(segment
		(start 60.00623 -414.804098)
		(end 59.704986 -414.487106)
		(width 0.14732)
		(layer "In6.Cu")
		(net "P5E_CPU1_PE4_TX_C_DP<2>")
	)
	(segment
		(start 57.68213 -412.537148)
		(end 57.686702 -412.361126)
		(width 0.14732)
		(layer "In6.Cu")
		(net "P5E_CPU1_PE4_TX_C_DP<2>")
	)
	(segment
		(start 59.704986 -414.487106)
		(end 59.529218 -414.482534)
		(width 0.14732)
		(layer "In6.Cu")
		(net "P5E_CPU1_PE4_TX_C_DP<2>")
	)
	(segment
		(start 58.455306 -413.351472)
		(end 58.459878 -413.17545)
		(width 0.14732)
		(layer "In6.Cu")
		(net "P5E_CPU1_PE4_TX_C_DP<2>")
	)
	(segment
		(start 62.650116 -426.089826)
		(end 62.650116 -426.430948)
		(width 0.14732)
		(layer "In6.Cu")
		(net "P5E_CPU1_PE4_TX_C_DP<2>")
	)
	(segment
		(start 57.982866 -412.853886)
		(end 57.68213 -412.537148)
		(width 0.14732)
		(layer "In6.Cu")
		(net "P5E_CPU1_PE4_TX_C_DP<2>")
	)
	(segment
		(start 56.021478 -410.324808)
		(end 56.316118 -410.030168)
		(width 0.14732)
		(layer "In6.Cu")
		(net "P5E_CPU1_PE4_TX_C_DP<2>")
	)
	(segment
		(start 58.93181 -413.672782)
		(end 58.756042 -413.66821)
		(width 0.14732)
		(layer "In6.Cu")
		(net "P5E_CPU1_PE4_TX_C_DP<2>")
	)
	(segment
		(start 58.756042 -413.66821)
		(end 58.455306 -413.351472)
		(width 0.14732)
		(layer "In6.Cu")
		(net "P5E_CPU1_PE4_TX_C_DP<2>")
	)
	(segment
		(start 62.502796 -426.578268)
		(end 62.139068 -426.578268)
		(width 0.14732)
		(layer "In6.Cu")
		(net "P5E_CPU1_PE4_TX_C_DP<2>")
	)
	(segment
		(start 59.529218 -414.482534)
		(end 59.228482 -414.165796)
		(width 0.14732)
		(layer "In6.Cu")
		(net "P5E_CPU1_PE4_TX_C_DP<2>")
	)
	(segment
		(start 57.686702 -412.361126)
		(end 57.385712 -412.04388)
		(width 0.14732)
		(layer "In6.Cu")
		(net "P5E_CPU1_PE4_TX_C_DP<2>")
	)
	(segment
		(start 61.966348 -417.049966)
		(end 60.001658 -414.98012)
		(width 0.14732)
		(layer "In6.Cu")
		(net "P5E_CPU1_PE4_TX_C_DP<2>")
	)
	(segment
		(start 52.6923 -409.109164)
		(end 52.6923 -409.727146)
		(width 0.13208)
		(layer "F.Cu")
		(net "P5E_CPU1_PE4_TX_C_DP<1>")
	)
	(segment
		(start 52.36718 -408.784044)
		(end 52.6923 -409.109164)
		(width 0.13208)
		(layer "F.Cu")
		(net "P5E_CPU1_PE4_TX_C_DP<1>")
	)
	(segment
		(start 52.363878 -408.784044)
		(end 52.36718 -408.784044)
		(width 0.13208)
		(layer "F.Cu")
		(net "P5E_CPU1_PE4_TX_C_DP<1>")
	)
	(segment
		(start 52.6923 -409.727146)
		(end 52.389278 -410.030168)
		(width 0.13208)
		(layer "F.Cu")
		(net "P5E_CPU1_PE4_TX_C_DP<1>")
	)
	(segment
		(start 52.683918 -410.324808)
		(end 52.389278 -410.030168)
		(width 0.14732)
		(layer "In6.Cu")
		(net "P5E_CPU1_PE4_TX_C_DP<1>")
	)
	(segment
		(start 60.65012 -427.974506)
		(end 60.502546 -427.826932)
		(width 0.14732)
		(layer "In6.Cu")
		(net "P5E_CPU1_PE4_TX_C_DP<1>")
	)
	(segment
		(start 59.506866 -417.186618)
		(end 59.437778 -416.967162)
		(width 0.14732)
		(layer "In6.Cu")
		(net "P5E_CPU1_PE4_TX_C_DP<1>")
	)
	(segment
		(start 59.437778 -416.967162)
		(end 53.009546 -411.301438)
		(width 0.14732)
		(layer "In6.Cu")
		(net "P5E_CPU1_PE4_TX_C_DP<1>")
	)
	(segment
		(start 59.692032 -417.591748)
		(end 59.506866 -417.186618)
		(width 0.14732)
		(layer "In6.Cu")
		(net "P5E_CPU1_PE4_TX_C_DP<1>")
	)
	(segment
		(start 52.683918 -410.84754)
		(end 52.683918 -410.324808)
		(width 0.14732)
		(layer "In6.Cu")
		(net "P5E_CPU1_PE4_TX_C_DP<1>")
	)
	(segment
		(start 60.502546 -427.826932)
		(end 59.99988 -427.826932)
		(width 0.14732)
		(layer "In6.Cu")
		(net "P5E_CPU1_PE4_TX_C_DP<1>")
	)
	(segment
		(start 53.009546 -411.301438)
		(end 52.683918 -410.84754)
		(width 0.14732)
		(layer "In6.Cu")
		(net "P5E_CPU1_PE4_TX_C_DP<1>")
	)
	(segment
		(start 59.692032 -427.519084)
		(end 59.692032 -417.591748)
		(width 0.14732)
		(layer "In6.Cu")
		(net "P5E_CPU1_PE4_TX_C_DP<1>")
	)
	(segment
		(start 60.65012 -428.28972)
		(end 60.65012 -427.974506)
		(width 0.14732)
		(layer "In6.Cu")
		(net "P5E_CPU1_PE4_TX_C_DP<1>")
	)
	(segment
		(start 59.99988 -427.826932)
		(end 59.692032 -427.519084)
		(width 0.14732)
		(layer "In6.Cu")
		(net "P5E_CPU1_PE4_TX_C_DP<1>")
	)
	(segment
		(start 95.83674 -409.72867)
		(end 96.138238 -410.030168)
		(width 0.13208)
		(layer "F.Cu")
		(net "P5E_CPU1_PE4_TX_C_DP<15>")
	)
	(segment
		(start 95.83674 -409.110942)
		(end 95.83674 -409.72867)
		(width 0.13208)
		(layer "F.Cu")
		(net "P5E_CPU1_PE4_TX_C_DP<15>")
	)
	(segment
		(start 96.163638 -408.784044)
		(end 95.83674 -409.110942)
		(width 0.13208)
		(layer "F.Cu")
		(net "P5E_CPU1_PE4_TX_C_DP<15>")
	)
	(segment
		(start 90.08237 -421.936164)
		(end 90.13952 -422.125394)
		(width 0.14732)
		(layer "In6.Cu")
		(net "P5E_CPU1_PE4_TX_C_DP<15>")
	)
	(segment
		(start 95.843598 -411.219904)
		(end 95.811086 -411.252416)
		(width 0.14732)
		(layer "In6.Cu")
		(net "P5E_CPU1_PE4_TX_C_DP<15>")
	)
	(segment
		(start 93.426788 -415.69894)
		(end 91.042998 -420.144956)
		(width 0.14732)
		(layer "In6.Cu")
		(net "P5E_CPU1_PE4_TX_C_DP<15>")
	)
	(segment
		(start 96.138238 -410.030168)
		(end 95.843598 -410.324808)
		(width 0.14732)
		(layer "In6.Cu")
		(net "P5E_CPU1_PE4_TX_C_DP<15>")
	)
	(segment
		(start 89.602056 -422.831768)
		(end 89.659206 -423.020744)
		(width 0.14732)
		(layer "In6.Cu")
		(net "P5E_CPU1_PE4_TX_C_DP<15>")
	)
	(segment
		(start 91.100148 -420.334186)
		(end 90.925904 -420.659052)
		(width 0.14732)
		(layer "In6.Cu")
		(net "P5E_CPU1_PE4_TX_C_DP<15>")
	)
	(segment
		(start 90.25636 -421.611806)
		(end 90.08237 -421.936164)
		(width 0.14732)
		(layer "In6.Cu")
		(net "P5E_CPU1_PE4_TX_C_DP<15>")
	)
	(segment
		(start 90.562684 -421.04056)
		(end 90.619834 -421.22979)
		(width 0.14732)
		(layer "In6.Cu")
		(net "P5E_CPU1_PE4_TX_C_DP<15>")
	)
	(segment
		(start 89.295732 -423.40276)
		(end 88.954864 -424.038522)
		(width 0.14732)
		(layer "In6.Cu")
		(net "P5E_CPU1_PE4_TX_C_DP<15>")
	)
	(segment
		(start 90.44559 -421.554656)
		(end 90.25636 -421.611806)
		(width 0.14732)
		(layer "In6.Cu")
		(net "P5E_CPU1_PE4_TX_C_DP<15>")
	)
	(segment
		(start 90.925904 -420.659052)
		(end 90.736674 -420.716202)
		(width 0.14732)
		(layer "In6.Cu")
		(net "P5E_CPU1_PE4_TX_C_DP<15>")
	)
	(segment
		(start 89.113614 -427.552612)
		(end 89.41562 -427.552612)
		(width 0.14732)
		(layer "In6.Cu")
		(net "P5E_CPU1_PE4_TX_C_DP<15>")
	)
	(segment
		(start 89.965276 -422.45026)
		(end 89.776046 -422.50741)
		(width 0.14732)
		(layer "In6.Cu")
		(net "P5E_CPU1_PE4_TX_C_DP<15>")
	)
	(segment
		(start 91.042998 -420.144956)
		(end 91.100148 -420.334186)
		(width 0.14732)
		(layer "In6.Cu")
		(net "P5E_CPU1_PE4_TX_C_DP<15>")
	)
	(segment
		(start 89.776046 -422.50741)
		(end 89.602056 -422.831768)
		(width 0.14732)
		(layer "In6.Cu")
		(net "P5E_CPU1_PE4_TX_C_DP<15>")
	)
	(segment
		(start 95.811086 -411.252416)
		(end 93.426788 -415.69894)
		(width 0.14732)
		(layer "In6.Cu")
		(net "P5E_CPU1_PE4_TX_C_DP<15>")
	)
	(segment
		(start 90.619834 -421.22979)
		(end 90.44559 -421.554656)
		(width 0.14732)
		(layer "In6.Cu")
		(net "P5E_CPU1_PE4_TX_C_DP<15>")
	)
	(segment
		(start 89.650062 -427.31817)
		(end 89.650062 -427.089824)
		(width 0.14732)
		(layer "In6.Cu")
		(net "P5E_CPU1_PE4_TX_C_DP<15>")
	)
	(segment
		(start 89.485216 -423.34561)
		(end 89.295732 -423.40276)
		(width 0.14732)
		(layer "In6.Cu")
		(net "P5E_CPU1_PE4_TX_C_DP<15>")
	)
	(segment
		(start 90.13952 -422.125394)
		(end 89.965276 -422.45026)
		(width 0.14732)
		(layer "In6.Cu")
		(net "P5E_CPU1_PE4_TX_C_DP<15>")
	)
	(segment
		(start 88.954864 -427.393862)
		(end 89.113614 -427.552612)
		(width 0.14732)
		(layer "In6.Cu")
		(net "P5E_CPU1_PE4_TX_C_DP<15>")
	)
	(segment
		(start 89.659206 -423.020744)
		(end 89.485216 -423.34561)
		(width 0.14732)
		(layer "In6.Cu")
		(net "P5E_CPU1_PE4_TX_C_DP<15>")
	)
	(segment
		(start 95.843598 -410.324808)
		(end 95.843598 -411.219904)
		(width 0.14732)
		(layer "In6.Cu")
		(net "P5E_CPU1_PE4_TX_C_DP<15>")
	)
	(segment
		(start 88.954864 -424.038522)
		(end 88.954864 -427.393862)
		(width 0.14732)
		(layer "In6.Cu")
		(net "P5E_CPU1_PE4_TX_C_DP<15>")
	)
	(segment
		(start 90.736674 -420.716202)
		(end 90.562684 -421.04056)
		(width 0.14732)
		(layer "In6.Cu")
		(net "P5E_CPU1_PE4_TX_C_DP<15>")
	)
	(segment
		(start 89.41562 -427.552612)
		(end 89.650062 -427.31817)
		(width 0.14732)
		(layer "In6.Cu")
		(net "P5E_CPU1_PE4_TX_C_DP<15>")
	)
	(segment
		(start 93.100398 -408.784044)
		(end 92.7735 -409.110942)
		(width 0.13208)
		(layer "F.Cu")
		(net "P5E_CPU1_PE4_TX_C_DP<14>")
	)
	(segment
		(start 92.7735 -409.110942)
		(end 92.7735 -409.72867)
		(width 0.13208)
		(layer "F.Cu")
		(net "P5E_CPU1_PE4_TX_C_DP<14>")
	)
	(segment
		(start 92.7735 -409.72867)
		(end 93.074998 -410.030168)
		(width 0.13208)
		(layer "F.Cu")
		(net "P5E_CPU1_PE4_TX_C_DP<14>")
	)
	(segment
		(start 89.36101 -418.89045)
		(end 89.431876 -419.075108)
		(width 0.14732)
		(layer "In6.Cu")
		(net "P5E_CPU1_PE4_TX_C_DP<14>")
	)
	(segment
		(start 87.088218 -426.527468)
		(end 87.441024 -426.527468)
		(width 0.14732)
		(layer "In6.Cu")
		(net "P5E_CPU1_PE4_TX_C_DP<14>")
	)
	(segment
		(start 89.431876 -419.075108)
		(end 89.282016 -419.411658)
		(width 0.14732)
		(layer "In6.Cu")
		(net "P5E_CPU1_PE4_TX_C_DP<14>")
	)
	(segment
		(start 88.120474 -421.675052)
		(end 88.191086 -421.859456)
		(width 0.14732)
		(layer "In6.Cu")
		(net "P5E_CPU1_PE4_TX_C_DP<14>")
	)
	(segment
		(start 88.947498 -419.81882)
		(end 89.018364 -420.003224)
		(width 0.14732)
		(layer "In6.Cu")
		(net "P5E_CPU1_PE4_TX_C_DP<14>")
	)
	(segment
		(start 92.780358 -411.24378)
		(end 92.756736 -411.267402)
		(width 0.14732)
		(layer "In6.Cu")
		(net "P5E_CPU1_PE4_TX_C_DP<14>")
	)
	(segment
		(start 88.683846 -420.41064)
		(end 88.533986 -420.746936)
		(width 0.14732)
		(layer "In6.Cu")
		(net "P5E_CPU1_PE4_TX_C_DP<14>")
	)
	(segment
		(start 89.282016 -419.411658)
		(end 89.097358 -419.482524)
		(width 0.14732)
		(layer "In6.Cu")
		(net "P5E_CPU1_PE4_TX_C_DP<14>")
	)
	(segment
		(start 86.966298 -426.405548)
		(end 87.088218 -426.527468)
		(width 0.14732)
		(layer "In6.Cu")
		(net "P5E_CPU1_PE4_TX_C_DP<14>")
	)
	(segment
		(start 87.597742 -423.19194)
		(end 87.413338 -423.262552)
		(width 0.14732)
		(layer "In6.Cu")
		(net "P5E_CPU1_PE4_TX_C_DP<14>")
	)
	(segment
		(start 87.676736 -422.670732)
		(end 87.747602 -422.855136)
		(width 0.14732)
		(layer "In6.Cu")
		(net "P5E_CPU1_PE4_TX_C_DP<14>")
	)
	(segment
		(start 88.191086 -421.859456)
		(end 88.041226 -422.196006)
		(width 0.14732)
		(layer "In6.Cu")
		(net "P5E_CPU1_PE4_TX_C_DP<14>")
	)
	(segment
		(start 88.533986 -420.746936)
		(end 88.604852 -420.93134)
		(width 0.14732)
		(layer "In6.Cu")
		(net "P5E_CPU1_PE4_TX_C_DP<14>")
	)
	(segment
		(start 89.018364 -420.003224)
		(end 88.868504 -420.339774)
		(width 0.14732)
		(layer "In6.Cu")
		(net "P5E_CPU1_PE4_TX_C_DP<14>")
	)
	(segment
		(start 92.756736 -411.267402)
		(end 89.36101 -418.89045)
		(width 0.14732)
		(layer "In6.Cu")
		(net "P5E_CPU1_PE4_TX_C_DP<14>")
	)
	(segment
		(start 87.413338 -423.262552)
		(end 86.966298 -424.265598)
		(width 0.14732)
		(layer "In6.Cu")
		(net "P5E_CPU1_PE4_TX_C_DP<14>")
	)
	(segment
		(start 87.856568 -422.266872)
		(end 87.676736 -422.670732)
		(width 0.14732)
		(layer "In6.Cu")
		(net "P5E_CPU1_PE4_TX_C_DP<14>")
	)
	(segment
		(start 88.041226 -422.196006)
		(end 87.856568 -422.266872)
		(width 0.14732)
		(layer "In6.Cu")
		(net "P5E_CPU1_PE4_TX_C_DP<14>")
	)
	(segment
		(start 87.747602 -422.855136)
		(end 87.597742 -423.19194)
		(width 0.14732)
		(layer "In6.Cu")
		(net "P5E_CPU1_PE4_TX_C_DP<14>")
	)
	(segment
		(start 92.780358 -410.324808)
		(end 92.780358 -411.24378)
		(width 0.14732)
		(layer "In6.Cu")
		(net "P5E_CPU1_PE4_TX_C_DP<14>")
	)
	(segment
		(start 88.868504 -420.339774)
		(end 88.683846 -420.41064)
		(width 0.14732)
		(layer "In6.Cu")
		(net "P5E_CPU1_PE4_TX_C_DP<14>")
	)
	(segment
		(start 87.441024 -426.527468)
		(end 87.650066 -426.318426)
		(width 0.14732)
		(layer "In6.Cu")
		(net "P5E_CPU1_PE4_TX_C_DP<14>")
	)
	(segment
		(start 88.270334 -421.338756)
		(end 88.120474 -421.675052)
		(width 0.14732)
		(layer "In6.Cu")
		(net "P5E_CPU1_PE4_TX_C_DP<14>")
	)
	(segment
		(start 88.604852 -420.93134)
		(end 88.454992 -421.26789)
		(width 0.14732)
		(layer "In6.Cu")
		(net "P5E_CPU1_PE4_TX_C_DP<14>")
	)
	(segment
		(start 87.650066 -426.318426)
		(end 87.650066 -426.089826)
		(width 0.14732)
		(layer "In6.Cu")
		(net "P5E_CPU1_PE4_TX_C_DP<14>")
	)
	(segment
		(start 88.454992 -421.26789)
		(end 88.270334 -421.338756)
		(width 0.14732)
		(layer "In6.Cu")
		(net "P5E_CPU1_PE4_TX_C_DP<14>")
	)
	(segment
		(start 93.074998 -410.030168)
		(end 92.780358 -410.324808)
		(width 0.14732)
		(layer "In6.Cu")
		(net "P5E_CPU1_PE4_TX_C_DP<14>")
	)
	(segment
		(start 86.966298 -424.265598)
		(end 86.966298 -426.405548)
		(width 0.14732)
		(layer "In6.Cu")
		(net "P5E_CPU1_PE4_TX_C_DP<14>")
	)
	(segment
		(start 89.097358 -419.482524)
		(end 88.947498 -419.81882)
		(width 0.14732)
		(layer "In6.Cu")
		(net "P5E_CPU1_PE4_TX_C_DP<14>")
	)
	(segment
		(start 89.71026 -409.110942)
		(end 89.71026 -409.72867)
		(width 0.13208)
		(layer "F.Cu")
		(net "P5E_CPU1_PE4_TX_C_DP<13>")
	)
	(segment
		(start 89.71026 -409.72867)
		(end 90.011758 -410.030168)
		(width 0.13208)
		(layer "F.Cu")
		(net "P5E_CPU1_PE4_TX_C_DP<13>")
	)
	(segment
		(start 90.037158 -408.784044)
		(end 89.71026 -409.110942)
		(width 0.13208)
		(layer "F.Cu")
		(net "P5E_CPU1_PE4_TX_C_DP<13>")
	)
	(segment
		(start 86.53526 -420.189914)
		(end 86.355174 -420.271702)
		(width 0.14732)
		(layer "In6.Cu")
		(net "P5E_CPU1_PE4_TX_C_DP<13>")
	)
	(segment
		(start 86.581996 -419.664388)
		(end 86.58225 -419.664896)
		(width 0.14732)
		(layer "In6.Cu")
		(net "P5E_CPU1_PE4_TX_C_DP<13>")
	)
	(segment
		(start 85.415628 -427.552612)
		(end 85.65007 -427.31817)
		(width 0.14732)
		(layer "In6.Cu")
		(net "P5E_CPU1_PE4_TX_C_DP<13>")
	)
	(segment
		(start 85.467698 -423.045128)
		(end 85.287612 -423.126916)
		(width 0.14732)
		(layer "In6.Cu")
		(net "P5E_CPU1_PE4_TX_C_DP<13>")
	)
	(segment
		(start 86.355174 -420.271702)
		(end 86.22665 -420.615872)
		(width 0.14732)
		(layer "In6.Cu")
		(net "P5E_CPU1_PE4_TX_C_DP<13>")
	)
	(segment
		(start 86.308438 -420.796212)
		(end 86.179406 -421.141652)
		(width 0.14732)
		(layer "In6.Cu")
		(net "P5E_CPU1_PE4_TX_C_DP<13>")
	)
	(segment
		(start 85.287612 -423.126916)
		(end 84.966302 -423.986706)
		(width 0.14732)
		(layer "In6.Cu")
		(net "P5E_CPU1_PE4_TX_C_DP<13>")
	)
	(segment
		(start 86.22665 -420.615872)
		(end 86.226396 -420.616634)
		(width 0.14732)
		(layer "In6.Cu")
		(net "P5E_CPU1_PE4_TX_C_DP<13>")
	)
	(segment
		(start 85.65007 -427.31817)
		(end 85.65007 -427.089824)
		(width 0.14732)
		(layer "In6.Cu")
		(net "P5E_CPU1_PE4_TX_C_DP<13>")
	)
	(segment
		(start 86.58225 -419.664896)
		(end 86.664292 -419.844474)
		(width 0.14732)
		(layer "In6.Cu")
		(net "P5E_CPU1_PE4_TX_C_DP<13>")
	)
	(segment
		(start 86.226396 -420.616634)
		(end 86.308438 -420.796212)
		(width 0.14732)
		(layer "In6.Cu")
		(net "P5E_CPU1_PE4_TX_C_DP<13>")
	)
	(segment
		(start 85.99932 -421.22344)
		(end 85.870542 -421.568372)
		(width 0.14732)
		(layer "In6.Cu")
		(net "P5E_CPU1_PE4_TX_C_DP<13>")
	)
	(segment
		(start 89.717118 -410.324808)
		(end 89.717118 -411.2768)
		(width 0.14732)
		(layer "In6.Cu")
		(net "P5E_CPU1_PE4_TX_C_DP<13>")
	)
	(segment
		(start 85.643466 -422.175178)
		(end 85.514942 -422.519348)
		(width 0.14732)
		(layer "In6.Cu")
		(net "P5E_CPU1_PE4_TX_C_DP<13>")
	)
	(segment
		(start 86.664292 -419.844474)
		(end 86.53526 -420.189914)
		(width 0.14732)
		(layer "In6.Cu")
		(net "P5E_CPU1_PE4_TX_C_DP<13>")
	)
	(segment
		(start 84.966302 -427.405292)
		(end 85.113622 -427.552612)
		(width 0.14732)
		(layer "In6.Cu")
		(net "P5E_CPU1_PE4_TX_C_DP<13>")
	)
	(segment
		(start 86.179406 -421.141652)
		(end 85.99932 -421.22344)
		(width 0.14732)
		(layer "In6.Cu")
		(net "P5E_CPU1_PE4_TX_C_DP<13>")
	)
	(segment
		(start 85.952584 -421.74795)
		(end 85.823552 -422.09339)
		(width 0.14732)
		(layer "In6.Cu")
		(net "P5E_CPU1_PE4_TX_C_DP<13>")
	)
	(segment
		(start 84.966302 -423.986706)
		(end 84.966302 -427.405292)
		(width 0.14732)
		(layer "In6.Cu")
		(net "P5E_CPU1_PE4_TX_C_DP<13>")
	)
	(segment
		(start 85.113622 -427.552612)
		(end 85.415628 -427.552612)
		(width 0.14732)
		(layer "In6.Cu")
		(net "P5E_CPU1_PE4_TX_C_DP<13>")
	)
	(segment
		(start 85.870542 -421.568372)
		(end 85.952584 -421.74795)
		(width 0.14732)
		(layer "In6.Cu")
		(net "P5E_CPU1_PE4_TX_C_DP<13>")
	)
	(segment
		(start 90.011758 -410.030168)
		(end 89.717118 -410.324808)
		(width 0.14732)
		(layer "In6.Cu")
		(net "P5E_CPU1_PE4_TX_C_DP<13>")
	)
	(segment
		(start 85.514942 -422.519348)
		(end 85.514688 -422.52011)
		(width 0.14732)
		(layer "In6.Cu")
		(net "P5E_CPU1_PE4_TX_C_DP<13>")
	)
	(segment
		(start 89.717118 -411.2768)
		(end 86.581996 -419.664388)
		(width 0.14732)
		(layer "In6.Cu")
		(net "P5E_CPU1_PE4_TX_C_DP<13>")
	)
	(segment
		(start 85.514688 -422.52011)
		(end 85.596476 -422.699942)
		(width 0.14732)
		(layer "In6.Cu")
		(net "P5E_CPU1_PE4_TX_C_DP<13>")
	)
	(segment
		(start 85.596476 -422.699942)
		(end 85.467698 -423.045128)
		(width 0.14732)
		(layer "In6.Cu")
		(net "P5E_CPU1_PE4_TX_C_DP<13>")
	)
	(segment
		(start 85.823552 -422.09339)
		(end 85.643466 -422.175178)
		(width 0.14732)
		(layer "In6.Cu")
		(net "P5E_CPU1_PE4_TX_C_DP<13>")
	)
	(segment
		(start 86.64702 -409.110942)
		(end 86.64702 -409.72867)
		(width 0.13208)
		(layer "F.Cu")
		(net "P5E_CPU1_PE4_TX_C_DP<12>")
	)
	(segment
		(start 86.973918 -408.784044)
		(end 86.64702 -409.110942)
		(width 0.13208)
		(layer "F.Cu")
		(net "P5E_CPU1_PE4_TX_C_DP<12>")
	)
	(segment
		(start 86.64702 -409.72867)
		(end 86.948518 -410.030168)
		(width 0.13208)
		(layer "F.Cu")
		(net "P5E_CPU1_PE4_TX_C_DP<12>")
	)
	(segment
		(start 84.074 -420.680896)
		(end 83.970622 -421.034718)
		(width 0.14732)
		(layer "In6.Cu")
		(net "P5E_CPU1_PE4_TX_C_DP<12>")
	)
	(segment
		(start 84.550758 -418.557456)
		(end 84.6455 -418.730684)
		(width 0.14732)
		(layer "In6.Cu")
		(net "P5E_CPU1_PE4_TX_C_DP<12>")
	)
	(segment
		(start 83.407758 -422.45788)
		(end 83.5025 -422.631362)
		(width 0.14732)
		(layer "In6.Cu")
		(net "P5E_CPU1_PE4_TX_C_DP<12>")
	)
	(segment
		(start 84.35975 -419.70579)
		(end 84.256372 -420.059612)
		(width 0.14732)
		(layer "In6.Cu")
		(net "P5E_CPU1_PE4_TX_C_DP<12>")
	)
	(segment
		(start 86.653878 -411.404816)
		(end 86.642956 -411.415738)
		(width 0.14732)
		(layer "In6.Cu")
		(net "P5E_CPU1_PE4_TX_C_DP<12>")
	)
	(segment
		(start 83.650074 -426.318426)
		(end 83.650074 -426.089826)
		(width 0.14732)
		(layer "In6.Cu")
		(net "P5E_CPU1_PE4_TX_C_DP<12>")
	)
	(segment
		(start 84.256372 -420.059612)
		(end 84.082636 -420.154354)
		(width 0.14732)
		(layer "In6.Cu")
		(net "P5E_CPU1_PE4_TX_C_DP<12>")
	)
	(segment
		(start 86.642956 -411.415738)
		(end 84.550758 -418.557456)
		(width 0.14732)
		(layer "In6.Cu")
		(net "P5E_CPU1_PE4_TX_C_DP<12>")
	)
	(segment
		(start 82.966306 -423.964608)
		(end 82.966306 -426.405548)
		(width 0.14732)
		(layer "In6.Cu")
		(net "P5E_CPU1_PE4_TX_C_DP<12>")
	)
	(segment
		(start 83.970622 -421.034718)
		(end 83.796886 -421.12946)
		(width 0.14732)
		(layer "In6.Cu")
		(net "P5E_CPU1_PE4_TX_C_DP<12>")
	)
	(segment
		(start 86.653878 -410.324808)
		(end 86.653878 -411.404816)
		(width 0.14732)
		(layer "In6.Cu")
		(net "P5E_CPU1_PE4_TX_C_DP<12>")
	)
	(segment
		(start 84.368386 -419.179248)
		(end 84.265008 -419.532562)
		(width 0.14732)
		(layer "In6.Cu")
		(net "P5E_CPU1_PE4_TX_C_DP<12>")
	)
	(segment
		(start 83.415632 -426.552868)
		(end 83.650074 -426.318426)
		(width 0.14732)
		(layer "In6.Cu")
		(net "P5E_CPU1_PE4_TX_C_DP<12>")
	)
	(segment
		(start 82.966306 -426.405548)
		(end 83.113626 -426.552868)
		(width 0.14732)
		(layer "In6.Cu")
		(net "P5E_CPU1_PE4_TX_C_DP<12>")
	)
	(segment
		(start 84.542122 -419.084506)
		(end 84.368386 -419.179248)
		(width 0.14732)
		(layer "In6.Cu")
		(net "P5E_CPU1_PE4_TX_C_DP<12>")
	)
	(segment
		(start 84.082636 -420.154354)
		(end 83.979258 -420.507668)
		(width 0.14732)
		(layer "In6.Cu")
		(net "P5E_CPU1_PE4_TX_C_DP<12>")
	)
	(segment
		(start 83.113626 -426.552868)
		(end 83.415632 -426.552868)
		(width 0.14732)
		(layer "In6.Cu")
		(net "P5E_CPU1_PE4_TX_C_DP<12>")
	)
	(segment
		(start 83.979258 -420.507668)
		(end 84.074 -420.680896)
		(width 0.14732)
		(layer "In6.Cu")
		(net "P5E_CPU1_PE4_TX_C_DP<12>")
	)
	(segment
		(start 83.796886 -421.12946)
		(end 83.693508 -421.482774)
		(width 0.14732)
		(layer "In6.Cu")
		(net "P5E_CPU1_PE4_TX_C_DP<12>")
	)
	(segment
		(start 84.265008 -419.532562)
		(end 84.35975 -419.70579)
		(width 0.14732)
		(layer "In6.Cu")
		(net "P5E_CPU1_PE4_TX_C_DP<12>")
	)
	(segment
		(start 86.948518 -410.030168)
		(end 86.653878 -410.324808)
		(width 0.14732)
		(layer "In6.Cu")
		(net "P5E_CPU1_PE4_TX_C_DP<12>")
	)
	(segment
		(start 83.399122 -422.98493)
		(end 83.22564 -423.079418)
		(width 0.14732)
		(layer "In6.Cu")
		(net "P5E_CPU1_PE4_TX_C_DP<12>")
	)
	(segment
		(start 83.511136 -422.104566)
		(end 83.407758 -422.45788)
		(width 0.14732)
		(layer "In6.Cu")
		(net "P5E_CPU1_PE4_TX_C_DP<12>")
	)
	(segment
		(start 83.5025 -422.631362)
		(end 83.399122 -422.98493)
		(width 0.14732)
		(layer "In6.Cu")
		(net "P5E_CPU1_PE4_TX_C_DP<12>")
	)
	(segment
		(start 83.693508 -421.482774)
		(end 83.78825 -421.656002)
		(width 0.14732)
		(layer "In6.Cu")
		(net "P5E_CPU1_PE4_TX_C_DP<12>")
	)
	(segment
		(start 83.684872 -422.009824)
		(end 83.511136 -422.104566)
		(width 0.14732)
		(layer "In6.Cu")
		(net "P5E_CPU1_PE4_TX_C_DP<12>")
	)
	(segment
		(start 83.22564 -423.079418)
		(end 82.966306 -423.964608)
		(width 0.14732)
		(layer "In6.Cu")
		(net "P5E_CPU1_PE4_TX_C_DP<12>")
	)
	(segment
		(start 83.78825 -421.656002)
		(end 83.684872 -422.009824)
		(width 0.14732)
		(layer "In6.Cu")
		(net "P5E_CPU1_PE4_TX_C_DP<12>")
	)
	(segment
		(start 84.6455 -418.730684)
		(end 84.542122 -419.084506)
		(width 0.14732)
		(layer "In6.Cu")
		(net "P5E_CPU1_PE4_TX_C_DP<12>")
	)
	(segment
		(start 82.996278 -408.784044)
		(end 82.99958 -408.784044)
		(width 0.13208)
		(layer "F.Cu")
		(net "P5E_CPU1_PE4_TX_C_DP<11>")
	)
	(segment
		(start 82.99958 -408.784044)
		(end 83.3247 -409.109164)
		(width 0.13208)
		(layer "F.Cu")
		(net "P5E_CPU1_PE4_TX_C_DP<11>")
	)
	(segment
		(start 83.3247 -409.109164)
		(end 83.3247 -409.727146)
		(width 0.13208)
		(layer "F.Cu")
		(net "P5E_CPU1_PE4_TX_C_DP<11>")
	)
	(segment
		(start 83.3247 -409.727146)
		(end 83.021678 -410.030168)
		(width 0.13208)
		(layer "F.Cu")
		(net "P5E_CPU1_PE4_TX_C_DP<11>")
	)
	(segment
		(start 81.650078 -428.28972)
		(end 81.650078 -427.974506)
		(width 0.14732)
		(layer "In6.Cu")
		(net "P5E_CPU1_PE4_TX_C_DP<11>")
	)
	(segment
		(start 80.69199 -423.752518)
		(end 83.316318 -411.530546)
		(width 0.14732)
		(layer "In6.Cu")
		(net "P5E_CPU1_PE4_TX_C_DP<11>")
	)
	(segment
		(start 80.69199 -427.519084)
		(end 80.69199 -423.752518)
		(width 0.14732)
		(layer "In6.Cu")
		(net "P5E_CPU1_PE4_TX_C_DP<11>")
	)
	(segment
		(start 83.316318 -410.324808)
		(end 83.021678 -410.030168)
		(width 0.14732)
		(layer "In6.Cu")
		(net "P5E_CPU1_PE4_TX_C_DP<11>")
	)
	(segment
		(start 83.316318 -411.530546)
		(end 83.316318 -410.324808)
		(width 0.14732)
		(layer "In6.Cu")
		(net "P5E_CPU1_PE4_TX_C_DP<11>")
	)
	(segment
		(start 81.650078 -427.974506)
		(end 81.502504 -427.826932)
		(width 0.14732)
		(layer "In6.Cu")
		(net "P5E_CPU1_PE4_TX_C_DP<11>")
	)
	(segment
		(start 81.502504 -427.826932)
		(end 80.999838 -427.826932)
		(width 0.14732)
		(layer "In6.Cu")
		(net "P5E_CPU1_PE4_TX_C_DP<11>")
	)
	(segment
		(start 80.999838 -427.826932)
		(end 80.69199 -427.519084)
		(width 0.14732)
		(layer "In6.Cu")
		(net "P5E_CPU1_PE4_TX_C_DP<11>")
	)
	(segment
		(start 80.52054 -409.110942)
		(end 80.52054 -409.72867)
		(width 0.13208)
		(layer "F.Cu")
		(net "P5E_CPU1_PE4_TX_C_DP<10>")
	)
	(segment
		(start 80.847438 -408.784044)
		(end 80.52054 -409.110942)
		(width 0.13208)
		(layer "F.Cu")
		(net "P5E_CPU1_PE4_TX_C_DP<10>")
	)
	(segment
		(start 80.52054 -409.72867)
		(end 80.822038 -410.030168)
		(width 0.13208)
		(layer "F.Cu")
		(net "P5E_CPU1_PE4_TX_C_DP<10>")
	)
	(segment
		(start 79.650082 -426.318426)
		(end 79.650082 -426.089826)
		(width 0.14732)
		(layer "In6.Cu")
		(net "P5E_CPU1_PE4_TX_C_DP<10>")
	)
	(segment
		(start 79.194152 -422.125394)
		(end 79.314548 -422.282112)
		(width 0.14732)
		(layer "In6.Cu")
		(net "P5E_CPU1_PE4_TX_C_DP<10>")
	)
	(segment
		(start 79.796894 -418.617908)
		(end 79.639922 -418.738304)
		(width 0.14732)
		(layer "In6.Cu")
		(net "P5E_CPU1_PE4_TX_C_DP<10>")
	)
	(segment
		(start 79.531718 -420.632636)
		(end 79.374746 -420.753032)
		(width 0.14732)
		(layer "In6.Cu")
		(net "P5E_CPU1_PE4_TX_C_DP<10>")
	)
	(segment
		(start 79.507334 -419.745668)
		(end 79.459328 -420.110666)
		(width 0.14732)
		(layer "In6.Cu")
		(net "P5E_CPU1_PE4_TX_C_DP<10>")
	)
	(segment
		(start 79.39913 -421.64)
		(end 79.242158 -421.760396)
		(width 0.14732)
		(layer "In6.Cu")
		(net "P5E_CPU1_PE4_TX_C_DP<10>")
	)
	(segment
		(start 79.266542 -422.647618)
		(end 79.10957 -422.768014)
		(width 0.14732)
		(layer "In6.Cu")
		(net "P5E_CPU1_PE4_TX_C_DP<10>")
	)
	(segment
		(start 79.591916 -419.103302)
		(end 79.712312 -419.26002)
		(width 0.14732)
		(layer "In6.Cu")
		(net "P5E_CPU1_PE4_TX_C_DP<10>")
	)
	(segment
		(start 79.664306 -419.625272)
		(end 79.507334 -419.745668)
		(width 0.14732)
		(layer "In6.Cu")
		(net "P5E_CPU1_PE4_TX_C_DP<10>")
	)
	(segment
		(start 80.527398 -410.324808)
		(end 80.527398 -411.991302)
		(width 0.14732)
		(layer "In6.Cu")
		(net "P5E_CPU1_PE4_TX_C_DP<10>")
	)
	(segment
		(start 79.8449 -418.252656)
		(end 79.796894 -418.617908)
		(width 0.14732)
		(layer "In6.Cu")
		(net "P5E_CPU1_PE4_TX_C_DP<10>")
	)
	(segment
		(start 80.822038 -410.030168)
		(end 80.527398 -410.324808)
		(width 0.14732)
		(layer "In6.Cu")
		(net "P5E_CPU1_PE4_TX_C_DP<10>")
	)
	(segment
		(start 78.966314 -423.857166)
		(end 78.966314 -426.405548)
		(width 0.14732)
		(layer "In6.Cu")
		(net "P5E_CPU1_PE4_TX_C_DP<10>")
	)
	(segment
		(start 79.314548 -422.282112)
		(end 79.266542 -422.647618)
		(width 0.14732)
		(layer "In6.Cu")
		(net "P5E_CPU1_PE4_TX_C_DP<10>")
	)
	(segment
		(start 79.113634 -426.552868)
		(end 79.41564 -426.552868)
		(width 0.14732)
		(layer "In6.Cu")
		(net "P5E_CPU1_PE4_TX_C_DP<10>")
	)
	(segment
		(start 79.242158 -421.760396)
		(end 79.194152 -422.125394)
		(width 0.14732)
		(layer "In6.Cu")
		(net "P5E_CPU1_PE4_TX_C_DP<10>")
	)
	(segment
		(start 79.459328 -420.110666)
		(end 79.579724 -420.267384)
		(width 0.14732)
		(layer "In6.Cu")
		(net "P5E_CPU1_PE4_TX_C_DP<10>")
	)
	(segment
		(start 79.41564 -426.552868)
		(end 79.650082 -426.318426)
		(width 0.14732)
		(layer "In6.Cu")
		(net "P5E_CPU1_PE4_TX_C_DP<10>")
	)
	(segment
		(start 79.712312 -419.26002)
		(end 79.664306 -419.625272)
		(width 0.14732)
		(layer "In6.Cu")
		(net "P5E_CPU1_PE4_TX_C_DP<10>")
	)
	(segment
		(start 79.724504 -418.095938)
		(end 79.8449 -418.252656)
		(width 0.14732)
		(layer "In6.Cu")
		(net "P5E_CPU1_PE4_TX_C_DP<10>")
	)
	(segment
		(start 79.579724 -420.267384)
		(end 79.531718 -420.632636)
		(width 0.14732)
		(layer "In6.Cu")
		(net "P5E_CPU1_PE4_TX_C_DP<10>")
	)
	(segment
		(start 80.527398 -411.991302)
		(end 79.724504 -418.095938)
		(width 0.14732)
		(layer "In6.Cu")
		(net "P5E_CPU1_PE4_TX_C_DP<10>")
	)
	(segment
		(start 79.447136 -421.274748)
		(end 79.39913 -421.64)
		(width 0.14732)
		(layer "In6.Cu")
		(net "P5E_CPU1_PE4_TX_C_DP<10>")
	)
	(segment
		(start 79.10957 -422.768014)
		(end 78.966314 -423.857166)
		(width 0.14732)
		(layer "In6.Cu")
		(net "P5E_CPU1_PE4_TX_C_DP<10>")
	)
	(segment
		(start 79.32674 -421.11803)
		(end 79.447136 -421.274748)
		(width 0.14732)
		(layer "In6.Cu")
		(net "P5E_CPU1_PE4_TX_C_DP<10>")
	)
	(segment
		(start 79.374746 -420.753032)
		(end 79.32674 -421.11803)
		(width 0.14732)
		(layer "In6.Cu")
		(net "P5E_CPU1_PE4_TX_C_DP<10>")
	)
	(segment
		(start 78.966314 -426.405548)
		(end 79.113634 -426.552868)
		(width 0.14732)
		(layer "In6.Cu")
		(net "P5E_CPU1_PE4_TX_C_DP<10>")
	)
	(segment
		(start 79.639922 -418.738304)
		(end 79.591916 -419.103302)
		(width 0.14732)
		(layer "In6.Cu")
		(net "P5E_CPU1_PE4_TX_C_DP<10>")
	)
	(segment
		(start 49.88814 -409.72867)
		(end 50.189638 -410.030168)
		(width 0.13208)
		(layer "F.Cu")
		(net "P5E_CPU1_PE4_TX_C_DP<0>")
	)
	(segment
		(start 49.88814 -409.110942)
		(end 49.88814 -409.72867)
		(width 0.13208)
		(layer "F.Cu")
		(net "P5E_CPU1_PE4_TX_C_DP<0>")
	)
	(segment
		(start 50.215038 -408.784044)
		(end 49.88814 -409.110942)
		(width 0.13208)
		(layer "F.Cu")
		(net "P5E_CPU1_PE4_TX_C_DP<0>")
	)
	(segment
		(start 53.918358 -418.58057)
		(end 53.750464 -418.526976)
		(width 0.14732)
		(layer "In6.Cu")
		(net "P5E_CPU1_PE4_TX_C_DP<0>")
	)
	(segment
		(start 49.894998 -410.324808)
		(end 50.189638 -410.030168)
		(width 0.14732)
		(layer "In6.Cu")
		(net "P5E_CPU1_PE4_TX_C_DP<0>")
	)
	(segment
		(start 52.522882 -416.14217)
		(end 52.576476 -415.97453)
		(width 0.14732)
		(layer "In6.Cu")
		(net "P5E_CPU1_PE4_TX_C_DP<0>")
	)
	(segment
		(start 52.008786 -415.14395)
		(end 52.06238 -414.97631)
		(width 0.14732)
		(layer "In6.Cu")
		(net "P5E_CPU1_PE4_TX_C_DP<0>")
	)
	(segment
		(start 52.208684 -415.532316)
		(end 52.008786 -415.14395)
		(width 0.14732)
		(layer "In6.Cu")
		(net "P5E_CPU1_PE4_TX_C_DP<0>")
	)
	(segment
		(start 58.650124 -426.318426)
		(end 58.415682 -426.552868)
		(width 0.14732)
		(layer "In6.Cu")
		(net "P5E_CPU1_PE4_TX_C_DP<0>")
	)
	(segment
		(start 54.118256 -418.96919)
		(end 53.918358 -418.58057)
		(width 0.14732)
		(layer "In6.Cu")
		(net "P5E_CPU1_PE4_TX_C_DP<0>")
	)
	(segment
		(start 49.894998 -411.038548)
		(end 49.894998 -410.324808)
		(width 0.14732)
		(layer "In6.Cu")
		(net "P5E_CPU1_PE4_TX_C_DP<0>")
	)
	(segment
		(start 53.604414 -417.97097)
		(end 53.404516 -417.58235)
		(width 0.14732)
		(layer "In6.Cu")
		(net "P5E_CPU1_PE4_TX_C_DP<0>")
	)
	(segment
		(start 53.750464 -418.526976)
		(end 53.550566 -418.13861)
		(width 0.14732)
		(layer "In6.Cu")
		(net "P5E_CPU1_PE4_TX_C_DP<0>")
	)
	(segment
		(start 53.404516 -417.58235)
		(end 53.236622 -417.528756)
		(width 0.14732)
		(layer "In6.Cu")
		(net "P5E_CPU1_PE4_TX_C_DP<0>")
	)
	(segment
		(start 58.650124 -426.089826)
		(end 58.650124 -426.318426)
		(width 0.14732)
		(layer "In6.Cu")
		(net "P5E_CPU1_PE4_TX_C_DP<0>")
	)
	(segment
		(start 58.11393 -426.552868)
		(end 57.634886 -426.073062)
		(width 0.14732)
		(layer "In6.Cu")
		(net "P5E_CPU1_PE4_TX_C_DP<0>")
	)
	(segment
		(start 57.634886 -426.073062)
		(end 54.064408 -419.137084)
		(width 0.14732)
		(layer "In6.Cu")
		(net "P5E_CPU1_PE4_TX_C_DP<0>")
	)
	(segment
		(start 51.548284 -413.97809)
		(end 51.348386 -413.58947)
		(width 0.14732)
		(layer "In6.Cu")
		(net "P5E_CPU1_PE4_TX_C_DP<0>")
	)
	(segment
		(start 51.180492 -413.535622)
		(end 49.894998 -411.038548)
		(width 0.14732)
		(layer "In6.Cu")
		(net "P5E_CPU1_PE4_TX_C_DP<0>")
	)
	(segment
		(start 53.236622 -417.528756)
		(end 53.036724 -417.14039)
		(width 0.14732)
		(layer "In6.Cu")
		(net "P5E_CPU1_PE4_TX_C_DP<0>")
	)
	(segment
		(start 52.72278 -416.530536)
		(end 52.522882 -416.14217)
		(width 0.14732)
		(layer "In6.Cu")
		(net "P5E_CPU1_PE4_TX_C_DP<0>")
	)
	(segment
		(start 54.064408 -419.137084)
		(end 54.118256 -418.96919)
		(width 0.14732)
		(layer "In6.Cu")
		(net "P5E_CPU1_PE4_TX_C_DP<0>")
	)
	(segment
		(start 58.415682 -426.552868)
		(end 58.11393 -426.552868)
		(width 0.14732)
		(layer "In6.Cu")
		(net "P5E_CPU1_PE4_TX_C_DP<0>")
	)
	(segment
		(start 53.550566 -418.13861)
		(end 53.604414 -417.97097)
		(width 0.14732)
		(layer "In6.Cu")
		(net "P5E_CPU1_PE4_TX_C_DP<0>")
	)
	(segment
		(start 51.862482 -414.58769)
		(end 51.694588 -414.534096)
		(width 0.14732)
		(layer "In6.Cu")
		(net "P5E_CPU1_PE4_TX_C_DP<0>")
	)
	(segment
		(start 53.036724 -417.14039)
		(end 53.090572 -416.97275)
		(width 0.14732)
		(layer "In6.Cu")
		(net "P5E_CPU1_PE4_TX_C_DP<0>")
	)
	(segment
		(start 51.348386 -413.58947)
		(end 51.180492 -413.535622)
		(width 0.14732)
		(layer "In6.Cu")
		(net "P5E_CPU1_PE4_TX_C_DP<0>")
	)
	(segment
		(start 52.576476 -415.97453)
		(end 52.376578 -415.58591)
		(width 0.14732)
		(layer "In6.Cu")
		(net "P5E_CPU1_PE4_TX_C_DP<0>")
	)
	(segment
		(start 52.890674 -416.58413)
		(end 52.72278 -416.530536)
		(width 0.14732)
		(layer "In6.Cu")
		(net "P5E_CPU1_PE4_TX_C_DP<0>")
	)
	(segment
		(start 52.376578 -415.58591)
		(end 52.208684 -415.532316)
		(width 0.14732)
		(layer "In6.Cu")
		(net "P5E_CPU1_PE4_TX_C_DP<0>")
	)
	(segment
		(start 52.06238 -414.97631)
		(end 51.862482 -414.58769)
		(width 0.14732)
		(layer "In6.Cu")
		(net "P5E_CPU1_PE4_TX_C_DP<0>")
	)
	(segment
		(start 53.090572 -416.97275)
		(end 52.890674 -416.58413)
		(width 0.14732)
		(layer "In6.Cu")
		(net "P5E_CPU1_PE4_TX_C_DP<0>")
	)
	(segment
		(start 51.694588 -414.534096)
		(end 51.49469 -414.14573)
		(width 0.14732)
		(layer "In6.Cu")
		(net "P5E_CPU1_PE4_TX_C_DP<0>")
	)
	(segment
		(start 51.49469 -414.14573)
		(end 51.548284 -413.97809)
		(width 0.14732)
		(layer "In6.Cu")
		(net "P5E_CPU1_PE4_TX_C_DP<0>")
	)
	(segment
		(start 76.8731 -408.784044)
		(end 77.19822 -409.109164)
		(width 0.13208)
		(layer "F.Cu")
		(net "P5E_CPU1_PE4_TX_C_DN<9>")
	)
	(segment
		(start 77.19822 -409.727146)
		(end 76.895198 -410.030168)
		(width 0.13208)
		(layer "F.Cu")
		(net "P5E_CPU1_PE4_TX_C_DN<9>")
	)
	(segment
		(start 76.869798 -408.784044)
		(end 76.8731 -408.784044)
		(width 0.13208)
		(layer "F.Cu")
		(net "P5E_CPU1_PE4_TX_C_DN<9>")
	)
	(segment
		(start 77.19822 -409.109164)
		(end 77.19822 -409.727146)
		(width 0.13208)
		(layer "F.Cu")
		(net "P5E_CPU1_PE4_TX_C_DN<9>")
	)
	(segment
		(start 76.691998 -427.519084)
		(end 76.691998 -423.870882)
		(width 0.14732)
		(layer "In6.Cu")
		(net "P5E_CPU1_PE4_TX_C_DN<9>")
	)
	(segment
		(start 77.502512 -427.826932)
		(end 76.999846 -427.826932)
		(width 0.14732)
		(layer "In6.Cu")
		(net "P5E_CPU1_PE4_TX_C_DN<9>")
	)
	(segment
		(start 77.650086 -427.974506)
		(end 77.502512 -427.826932)
		(width 0.14732)
		(layer "In6.Cu")
		(net "P5E_CPU1_PE4_TX_C_DN<9>")
	)
	(segment
		(start 77.650086 -428.28972)
		(end 77.650086 -427.974506)
		(width 0.14732)
		(layer "In6.Cu")
		(net "P5E_CPU1_PE4_TX_C_DN<9>")
	)
	(segment
		(start 77.189838 -413.862012)
		(end 77.189838 -410.324808)
		(width 0.14732)
		(layer "In6.Cu")
		(net "P5E_CPU1_PE4_TX_C_DN<9>")
	)
	(segment
		(start 76.691998 -423.870882)
		(end 77.189838 -413.862012)
		(width 0.14732)
		(layer "In6.Cu")
		(net "P5E_CPU1_PE4_TX_C_DN<9>")
	)
	(segment
		(start 77.189838 -410.324808)
		(end 76.895198 -410.030168)
		(width 0.14732)
		(layer "In6.Cu")
		(net "P5E_CPU1_PE4_TX_C_DN<9>")
	)
	(segment
		(start 76.999846 -427.826932)
		(end 76.691998 -427.519084)
		(width 0.14732)
		(layer "In6.Cu")
		(net "P5E_CPU1_PE4_TX_C_DN<9>")
	)
	(segment
		(start 74.13498 -409.727146)
		(end 73.831958 -410.030168)
		(width 0.13208)
		(layer "F.Cu")
		(net "P5E_CPU1_PE4_TX_C_DN<8>")
	)
	(segment
		(start 73.806558 -408.784044)
		(end 73.80986 -408.784044)
		(width 0.13208)
		(layer "F.Cu")
		(net "P5E_CPU1_PE4_TX_C_DN<8>")
	)
	(segment
		(start 74.13498 -409.109164)
		(end 74.13498 -409.727146)
		(width 0.13208)
		(layer "F.Cu")
		(net "P5E_CPU1_PE4_TX_C_DN<8>")
	)
	(segment
		(start 73.80986 -408.784044)
		(end 74.13498 -409.109164)
		(width 0.13208)
		(layer "F.Cu")
		(net "P5E_CPU1_PE4_TX_C_DN<8>")
	)
	(segment
		(start 75.502516 -426.827188)
		(end 74.99985 -426.827188)
		(width 0.14732)
		(layer "In6.Cu")
		(net "P5E_CPU1_PE4_TX_C_DN<8>")
	)
	(segment
		(start 74.456036 -421.646604)
		(end 74.456036 -421.643556)
		(width 0.14732)
		(layer "In6.Cu")
		(net "P5E_CPU1_PE4_TX_C_DN<8>")
	)
	(segment
		(start 74.99985 -426.827188)
		(end 74.703178 -426.530516)
		(width 0.14732)
		(layer "In6.Cu")
		(net "P5E_CPU1_PE4_TX_C_DN<8>")
	)
	(segment
		(start 75.65009 -426.974762)
		(end 75.502516 -426.827188)
		(width 0.14732)
		(layer "In6.Cu")
		(net "P5E_CPU1_PE4_TX_C_DN<8>")
	)
	(segment
		(start 74.56551 -425.184824)
		(end 74.456036 -421.646604)
		(width 0.14732)
		(layer "In6.Cu")
		(net "P5E_CPU1_PE4_TX_C_DN<8>")
	)
	(segment
		(start 74.126598 -410.324808)
		(end 73.831958 -410.030168)
		(width 0.14732)
		(layer "In6.Cu")
		(net "P5E_CPU1_PE4_TX_C_DN<8>")
	)
	(segment
		(start 74.703178 -426.530516)
		(end 74.56551 -425.184824)
		(width 0.14732)
		(layer "In6.Cu")
		(net "P5E_CPU1_PE4_TX_C_DN<8>")
	)
	(segment
		(start 74.126598 -410.974286)
		(end 74.126598 -410.324808)
		(width 0.14732)
		(layer "In6.Cu")
		(net "P5E_CPU1_PE4_TX_C_DN<8>")
	)
	(segment
		(start 74.456036 -421.643556)
		(end 74.126598 -410.974286)
		(width 0.14732)
		(layer "In6.Cu")
		(net "P5E_CPU1_PE4_TX_C_DN<8>")
	)
	(segment
		(start 75.65009 -427.289976)
		(end 75.65009 -426.974762)
		(width 0.14732)
		(layer "In6.Cu")
		(net "P5E_CPU1_PE4_TX_C_DN<8>")
	)
	(segment
		(start 70.743318 -408.784044)
		(end 70.74662 -408.784044)
		(width 0.13208)
		(layer "F.Cu")
		(net "P5E_CPU1_PE4_TX_C_DN<7>")
	)
	(segment
		(start 71.07174 -409.109164)
		(end 71.07174 -409.727146)
		(width 0.13208)
		(layer "F.Cu")
		(net "P5E_CPU1_PE4_TX_C_DN<7>")
	)
	(segment
		(start 71.07174 -409.727146)
		(end 70.768718 -410.030168)
		(width 0.13208)
		(layer "F.Cu")
		(net "P5E_CPU1_PE4_TX_C_DN<7>")
	)
	(segment
		(start 70.74662 -408.784044)
		(end 71.07174 -409.109164)
		(width 0.13208)
		(layer "F.Cu")
		(net "P5E_CPU1_PE4_TX_C_DN<7>")
	)
	(segment
		(start 71.692008 -427.519084)
		(end 71.692008 -417.126928)
		(width 0.14732)
		(layer "In6.Cu")
		(net "P5E_CPU1_PE4_TX_C_DN<7>")
	)
	(segment
		(start 71.999856 -427.826932)
		(end 71.692008 -427.519084)
		(width 0.14732)
		(layer "In6.Cu")
		(net "P5E_CPU1_PE4_TX_C_DN<7>")
	)
	(segment
		(start 71.063358 -410.324808)
		(end 70.768718 -410.030168)
		(width 0.14732)
		(layer "In6.Cu")
		(net "P5E_CPU1_PE4_TX_C_DN<7>")
	)
	(segment
		(start 72.650096 -428.28972)
		(end 72.650096 -427.974506)
		(width 0.14732)
		(layer "In6.Cu")
		(net "P5E_CPU1_PE4_TX_C_DN<7>")
	)
	(segment
		(start 71.063358 -410.769054)
		(end 71.063358 -410.324808)
		(width 0.14732)
		(layer "In6.Cu")
		(net "P5E_CPU1_PE4_TX_C_DN<7>")
	)
	(segment
		(start 72.650096 -427.974506)
		(end 72.502522 -427.826932)
		(width 0.14732)
		(layer "In6.Cu")
		(net "P5E_CPU1_PE4_TX_C_DN<7>")
	)
	(segment
		(start 71.692008 -417.126928)
		(end 71.063358 -410.769054)
		(width 0.14732)
		(layer "In6.Cu")
		(net "P5E_CPU1_PE4_TX_C_DN<7>")
	)
	(segment
		(start 72.502522 -427.826932)
		(end 71.999856 -427.826932)
		(width 0.14732)
		(layer "In6.Cu")
		(net "P5E_CPU1_PE4_TX_C_DN<7>")
	)
	(segment
		(start 67.68338 -408.784044)
		(end 68.0085 -409.109164)
		(width 0.13208)
		(layer "F.Cu")
		(net "P5E_CPU1_PE4_TX_C_DN<6>")
	)
	(segment
		(start 67.680078 -408.784044)
		(end 67.68338 -408.784044)
		(width 0.13208)
		(layer "F.Cu")
		(net "P5E_CPU1_PE4_TX_C_DN<6>")
	)
	(segment
		(start 68.0085 -409.109164)
		(end 68.0085 -409.727146)
		(width 0.13208)
		(layer "F.Cu")
		(net "P5E_CPU1_PE4_TX_C_DN<6>")
	)
	(segment
		(start 68.0085 -409.727146)
		(end 67.705478 -410.030168)
		(width 0.13208)
		(layer "F.Cu")
		(net "P5E_CPU1_PE4_TX_C_DN<6>")
	)
	(segment
		(start 69.692012 -417.24834)
		(end 68.000118 -410.976572)
		(width 0.14732)
		(layer "In6.Cu")
		(net "P5E_CPU1_PE4_TX_C_DN<6>")
	)
	(segment
		(start 70.02526 -426.852588)
		(end 69.692012 -426.51934)
		(width 0.14732)
		(layer "In6.Cu")
		(net "P5E_CPU1_PE4_TX_C_DN<6>")
	)
	(segment
		(start 70.6501 -427.289976)
		(end 70.6501 -427.000162)
		(width 0.14732)
		(layer "In6.Cu")
		(net "P5E_CPU1_PE4_TX_C_DN<6>")
	)
	(segment
		(start 69.692012 -426.51934)
		(end 69.692012 -417.24834)
		(width 0.14732)
		(layer "In6.Cu")
		(net "P5E_CPU1_PE4_TX_C_DN<6>")
	)
	(segment
		(start 68.000118 -410.976572)
		(end 68.000118 -410.324808)
		(width 0.14732)
		(layer "In6.Cu")
		(net "P5E_CPU1_PE4_TX_C_DN<6>")
	)
	(segment
		(start 70.6501 -427.000162)
		(end 70.502526 -426.852588)
		(width 0.14732)
		(layer "In6.Cu")
		(net "P5E_CPU1_PE4_TX_C_DN<6>")
	)
	(segment
		(start 70.502526 -426.852588)
		(end 70.02526 -426.852588)
		(width 0.14732)
		(layer "In6.Cu")
		(net "P5E_CPU1_PE4_TX_C_DN<6>")
	)
	(segment
		(start 68.000118 -410.324808)
		(end 67.705478 -410.030168)
		(width 0.14732)
		(layer "In6.Cu")
		(net "P5E_CPU1_PE4_TX_C_DN<6>")
	)
	(segment
		(start 64.94526 -409.109164)
		(end 64.94526 -409.727146)
		(width 0.13208)
		(layer "F.Cu")
		(net "P5E_CPU1_PE4_TX_C_DN<5>")
	)
	(segment
		(start 64.62014 -408.784044)
		(end 64.94526 -409.109164)
		(width 0.13208)
		(layer "F.Cu")
		(net "P5E_CPU1_PE4_TX_C_DN<5>")
	)
	(segment
		(start 64.616838 -408.784044)
		(end 64.62014 -408.784044)
		(width 0.13208)
		(layer "F.Cu")
		(net "P5E_CPU1_PE4_TX_C_DN<5>")
	)
	(segment
		(start 64.94526 -409.727146)
		(end 64.642238 -410.030168)
		(width 0.13208)
		(layer "F.Cu")
		(net "P5E_CPU1_PE4_TX_C_DN<5>")
	)
	(segment
		(start 67.692016 -427.519084)
		(end 67.692016 -416.886644)
		(width 0.14732)
		(layer "In6.Cu")
		(net "P5E_CPU1_PE4_TX_C_DN<5>")
	)
	(segment
		(start 67.9577 -427.784768)
		(end 67.692016 -427.519084)
		(width 0.14732)
		(layer "In6.Cu")
		(net "P5E_CPU1_PE4_TX_C_DN<5>")
	)
	(segment
		(start 68.514214 -427.784768)
		(end 67.9577 -427.784768)
		(width 0.14732)
		(layer "In6.Cu")
		(net "P5E_CPU1_PE4_TX_C_DN<5>")
	)
	(segment
		(start 67.692016 -416.886644)
		(end 64.936878 -410.777182)
		(width 0.14732)
		(layer "In6.Cu")
		(net "P5E_CPU1_PE4_TX_C_DN<5>")
	)
	(segment
		(start 68.650104 -427.920658)
		(end 68.514214 -427.784768)
		(width 0.14732)
		(layer "In6.Cu")
		(net "P5E_CPU1_PE4_TX_C_DN<5>")
	)
	(segment
		(start 68.650104 -428.28972)
		(end 68.650104 -427.920658)
		(width 0.14732)
		(layer "In6.Cu")
		(net "P5E_CPU1_PE4_TX_C_DN<5>")
	)
	(segment
		(start 64.936878 -410.324808)
		(end 64.642238 -410.030168)
		(width 0.14732)
		(layer "In6.Cu")
		(net "P5E_CPU1_PE4_TX_C_DN<5>")
	)
	(segment
		(start 64.936878 -410.777182)
		(end 64.936878 -410.324808)
		(width 0.14732)
		(layer "In6.Cu")
		(net "P5E_CPU1_PE4_TX_C_DN<5>")
	)
	(segment
		(start 61.553598 -408.784044)
		(end 61.5569 -408.784044)
		(width 0.13208)
		(layer "F.Cu")
		(net "P5E_CPU1_PE4_TX_C_DN<4>")
	)
	(segment
		(start 61.5569 -408.784044)
		(end 61.88202 -409.109164)
		(width 0.13208)
		(layer "F.Cu")
		(net "P5E_CPU1_PE4_TX_C_DN<4>")
	)
	(segment
		(start 61.88202 -409.109164)
		(end 61.88202 -409.727146)
		(width 0.13208)
		(layer "F.Cu")
		(net "P5E_CPU1_PE4_TX_C_DN<4>")
	)
	(segment
		(start 61.88202 -409.727146)
		(end 61.578998 -410.030168)
		(width 0.13208)
		(layer "F.Cu")
		(net "P5E_CPU1_PE4_TX_C_DN<4>")
	)
	(segment
		(start 66.520314 -426.844968)
		(end 66.017648 -426.844968)
		(width 0.14732)
		(layer "In6.Cu")
		(net "P5E_CPU1_PE4_TX_C_DN<4>")
	)
	(segment
		(start 66.017648 -426.844968)
		(end 65.692528 -426.519848)
		(width 0.14732)
		(layer "In6.Cu")
		(net "P5E_CPU1_PE4_TX_C_DN<4>")
	)
	(segment
		(start 65.692528 -426.519848)
		(end 65.692528 -417.215828)
		(width 0.14732)
		(layer "In6.Cu")
		(net "P5E_CPU1_PE4_TX_C_DN<4>")
	)
	(segment
		(start 65.692528 -417.215828)
		(end 61.873638 -410.853382)
		(width 0.14732)
		(layer "In6.Cu")
		(net "P5E_CPU1_PE4_TX_C_DN<4>")
	)
	(segment
		(start 61.873638 -410.853382)
		(end 61.873638 -410.324808)
		(width 0.14732)
		(layer "In6.Cu")
		(net "P5E_CPU1_PE4_TX_C_DN<4>")
	)
	(segment
		(start 66.650108 -426.974762)
		(end 66.520314 -426.844968)
		(width 0.14732)
		(layer "In6.Cu")
		(net "P5E_CPU1_PE4_TX_C_DN<4>")
	)
	(segment
		(start 66.650108 -427.289976)
		(end 66.650108 -426.974762)
		(width 0.14732)
		(layer "In6.Cu")
		(net "P5E_CPU1_PE4_TX_C_DN<4>")
	)
	(segment
		(start 61.873638 -410.324808)
		(end 61.578998 -410.030168)
		(width 0.14732)
		(layer "In6.Cu")
		(net "P5E_CPU1_PE4_TX_C_DN<4>")
	)
	(segment
		(start 58.49366 -408.784044)
		(end 58.81878 -409.109164)
		(width 0.13208)
		(layer "F.Cu")
		(net "P5E_CPU1_PE4_TX_C_DN<3>")
	)
	(segment
		(start 58.81878 -409.109164)
		(end 58.81878 -409.727146)
		(width 0.13208)
		(layer "F.Cu")
		(net "P5E_CPU1_PE4_TX_C_DN<3>")
	)
	(segment
		(start 58.81878 -409.727146)
		(end 58.515758 -410.030168)
		(width 0.13208)
		(layer "F.Cu")
		(net "P5E_CPU1_PE4_TX_C_DN<3>")
	)
	(segment
		(start 58.490358 -408.784044)
		(end 58.49366 -408.784044)
		(width 0.13208)
		(layer "F.Cu")
		(net "P5E_CPU1_PE4_TX_C_DN<3>")
	)
	(segment
		(start 63.692024 -427.519084)
		(end 63.692024 -417.553902)
		(width 0.14732)
		(layer "In6.Cu")
		(net "P5E_CPU1_PE4_TX_C_DN<3>")
	)
	(segment
		(start 63.999872 -427.826932)
		(end 63.692024 -427.519084)
		(width 0.14732)
		(layer "In6.Cu")
		(net "P5E_CPU1_PE4_TX_C_DN<3>")
	)
	(segment
		(start 64.650112 -427.974506)
		(end 64.502538 -427.826932)
		(width 0.14732)
		(layer "In6.Cu")
		(net "P5E_CPU1_PE4_TX_C_DN<3>")
	)
	(segment
		(start 63.48984 -417.276026)
		(end 63.488824 -417.274756)
		(width 0.14732)
		(layer "In6.Cu")
		(net "P5E_CPU1_PE4_TX_C_DN<3>")
	)
	(segment
		(start 63.692024 -417.553902)
		(end 63.48984 -417.276026)
		(width 0.14732)
		(layer "In6.Cu")
		(net "P5E_CPU1_PE4_TX_C_DN<3>")
	)
	(segment
		(start 64.502538 -427.826932)
		(end 63.999872 -427.826932)
		(width 0.14732)
		(layer "In6.Cu")
		(net "P5E_CPU1_PE4_TX_C_DN<3>")
	)
	(segment
		(start 58.810398 -410.324808)
		(end 58.515758 -410.030168)
		(width 0.14732)
		(layer "In6.Cu")
		(net "P5E_CPU1_PE4_TX_C_DN<3>")
	)
	(segment
		(start 63.488824 -417.274756)
		(end 58.810398 -410.848556)
		(width 0.14732)
		(layer "In6.Cu")
		(net "P5E_CPU1_PE4_TX_C_DN<3>")
	)
	(segment
		(start 64.650112 -428.28972)
		(end 64.650112 -427.974506)
		(width 0.14732)
		(layer "In6.Cu")
		(net "P5E_CPU1_PE4_TX_C_DN<3>")
	)
	(segment
		(start 58.810398 -410.848556)
		(end 58.810398 -410.324808)
		(width 0.14732)
		(layer "In6.Cu")
		(net "P5E_CPU1_PE4_TX_C_DN<3>")
	)
	(segment
		(start 55.75554 -409.727146)
		(end 55.452518 -410.030168)
		(width 0.13208)
		(layer "F.Cu")
		(net "P5E_CPU1_PE4_TX_C_DN<2>")
	)
	(segment
		(start 55.43042 -408.784044)
		(end 55.75554 -409.109164)
		(width 0.13208)
		(layer "F.Cu")
		(net "P5E_CPU1_PE4_TX_C_DN<2>")
	)
	(segment
		(start 55.427118 -408.784044)
		(end 55.43042 -408.784044)
		(width 0.13208)
		(layer "F.Cu")
		(net "P5E_CPU1_PE4_TX_C_DN<2>")
	)
	(segment
		(start 55.75554 -409.109164)
		(end 55.75554 -409.727146)
		(width 0.13208)
		(layer "F.Cu")
		(net "P5E_CPU1_PE4_TX_C_DN<2>")
	)
	(segment
		(start 62.502542 -426.852588)
		(end 62.025276 -426.852588)
		(width 0.14732)
		(layer "In6.Cu")
		(net "P5E_CPU1_PE4_TX_C_DN<2>")
	)
	(segment
		(start 62.025276 -426.852588)
		(end 61.692028 -426.51934)
		(width 0.14732)
		(layer "In6.Cu")
		(net "P5E_CPU1_PE4_TX_C_DN<2>")
	)
	(segment
		(start 62.650116 -427.000162)
		(end 62.502542 -426.852588)
		(width 0.14732)
		(layer "In6.Cu")
		(net "P5E_CPU1_PE4_TX_C_DN<2>")
	)
	(segment
		(start 61.692028 -426.51934)
		(end 61.692028 -417.15944)
		(width 0.14732)
		(layer "In6.Cu")
		(net "P5E_CPU1_PE4_TX_C_DN<2>")
	)
	(segment
		(start 62.650116 -427.289976)
		(end 62.650116 -427.000162)
		(width 0.14732)
		(layer "In6.Cu")
		(net "P5E_CPU1_PE4_TX_C_DN<2>")
	)
	(segment
		(start 61.692028 -417.15944)
		(end 55.747158 -410.89707)
		(width 0.14732)
		(layer "In6.Cu")
		(net "P5E_CPU1_PE4_TX_C_DN<2>")
	)
	(segment
		(start 55.747158 -410.324808)
		(end 55.452518 -410.030168)
		(width 0.14732)
		(layer "In6.Cu")
		(net "P5E_CPU1_PE4_TX_C_DN<2>")
	)
	(segment
		(start 55.747158 -410.89707)
		(end 55.747158 -410.324808)
		(width 0.14732)
		(layer "In6.Cu")
		(net "P5E_CPU1_PE4_TX_C_DN<2>")
	)
	(segment
		(start 53.278278 -408.784044)
		(end 52.95138 -409.110942)
		(width 0.13208)
		(layer "F.Cu")
		(net "P5E_CPU1_PE4_TX_C_DN<1>")
	)
	(segment
		(start 52.95138 -409.72867)
		(end 53.252878 -410.030168)
		(width 0.13208)
		(layer "F.Cu")
		(net "P5E_CPU1_PE4_TX_C_DN<1>")
	)
	(segment
		(start 52.95138 -409.110942)
		(end 52.95138 -409.72867)
		(width 0.13208)
		(layer "F.Cu")
		(net "P5E_CPU1_PE4_TX_C_DN<1>")
	)
	(segment
		(start 55.343806 -412.826962)
		(end 55.168292 -412.838138)
		(width 0.14732)
		(layer "In6.Cu")
		(net "P5E_CPU1_PE4_TX_C_DN<1>")
	)
	(segment
		(start 56.010556 -413.58058)
		(end 55.682896 -413.291782)
		(width 0.14732)
		(layer "In6.Cu")
		(net "P5E_CPU1_PE4_TX_C_DN<1>")
	)
	(segment
		(start 59.763406 -417.087812)
		(end 59.676792 -416.811714)
		(width 0.14732)
		(layer "In6.Cu")
		(net "P5E_CPU1_PE4_TX_C_DN<1>")
	)
	(segment
		(start 52.958238 -410.324808)
		(end 53.252878 -410.030168)
		(width 0.14732)
		(layer "In6.Cu")
		(net "P5E_CPU1_PE4_TX_C_DN<1>")
	)
	(segment
		(start 54.82971 -412.373572)
		(end 54.501542 -412.08452)
		(width 0.14732)
		(layer "In6.Cu")
		(net "P5E_CPU1_PE4_TX_C_DN<1>")
	)
	(segment
		(start 56.85282 -414.323022)
		(end 56.52516 -414.034224)
		(width 0.14732)
		(layer "In6.Cu")
		(net "P5E_CPU1_PE4_TX_C_DN<1>")
	)
	(segment
		(start 55.671974 -413.116014)
		(end 55.343806 -412.826962)
		(width 0.14732)
		(layer "In6.Cu")
		(net "P5E_CPU1_PE4_TX_C_DN<1>")
	)
	(segment
		(start 59.966352 -427.405292)
		(end 59.966352 -417.531804)
		(width 0.14732)
		(layer "In6.Cu")
		(net "P5E_CPU1_PE4_TX_C_DN<1>")
	)
	(segment
		(start 55.682896 -413.291782)
		(end 55.671974 -413.116014)
		(width 0.14732)
		(layer "In6.Cu")
		(net "P5E_CPU1_PE4_TX_C_DN<1>")
	)
	(segment
		(start 52.958238 -410.759148)
		(end 52.958238 -410.324808)
		(width 0.14732)
		(layer "In6.Cu")
		(net "P5E_CPU1_PE4_TX_C_DN<1>")
	)
	(segment
		(start 60.415678 -427.552612)
		(end 60.113672 -427.552612)
		(width 0.14732)
		(layer "In6.Cu")
		(net "P5E_CPU1_PE4_TX_C_DN<1>")
	)
	(segment
		(start 60.65012 -427.31817)
		(end 60.415678 -427.552612)
		(width 0.14732)
		(layer "In6.Cu")
		(net "P5E_CPU1_PE4_TX_C_DN<1>")
	)
	(segment
		(start 55.168292 -412.838138)
		(end 54.840632 -412.54934)
		(width 0.14732)
		(layer "In6.Cu")
		(net "P5E_CPU1_PE4_TX_C_DN<1>")
	)
	(segment
		(start 54.501542 -412.08452)
		(end 54.326028 -412.095696)
		(width 0.14732)
		(layer "In6.Cu")
		(net "P5E_CPU1_PE4_TX_C_DN<1>")
	)
	(segment
		(start 60.65012 -427.089824)
		(end 60.65012 -427.31817)
		(width 0.14732)
		(layer "In6.Cu")
		(net "P5E_CPU1_PE4_TX_C_DN<1>")
	)
	(segment
		(start 59.966352 -417.531804)
		(end 59.763406 -417.087812)
		(width 0.14732)
		(layer "In6.Cu")
		(net "P5E_CPU1_PE4_TX_C_DN<1>")
	)
	(segment
		(start 56.18607 -413.569404)
		(end 56.010556 -413.58058)
		(width 0.14732)
		(layer "In6.Cu")
		(net "P5E_CPU1_PE4_TX_C_DN<1>")
	)
	(segment
		(start 60.113672 -427.552612)
		(end 59.966352 -427.405292)
		(width 0.14732)
		(layer "In6.Cu")
		(net "P5E_CPU1_PE4_TX_C_DN<1>")
	)
	(segment
		(start 54.840632 -412.54934)
		(end 54.82971 -412.373572)
		(width 0.14732)
		(layer "In6.Cu")
		(net "P5E_CPU1_PE4_TX_C_DN<1>")
	)
	(segment
		(start 57.367678 -414.776666)
		(end 57.356502 -414.600898)
		(width 0.14732)
		(layer "In6.Cu")
		(net "P5E_CPU1_PE4_TX_C_DN<1>")
	)
	(segment
		(start 57.356502 -414.600898)
		(end 57.028334 -414.311846)
		(width 0.14732)
		(layer "In6.Cu")
		(net "P5E_CPU1_PE4_TX_C_DN<1>")
	)
	(segment
		(start 54.326028 -412.095696)
		(end 53.214524 -411.116018)
		(width 0.14732)
		(layer "In6.Cu")
		(net "P5E_CPU1_PE4_TX_C_DN<1>")
	)
	(segment
		(start 53.214524 -411.116018)
		(end 52.958238 -410.759148)
		(width 0.14732)
		(layer "In6.Cu")
		(net "P5E_CPU1_PE4_TX_C_DN<1>")
	)
	(segment
		(start 56.52516 -414.034224)
		(end 56.514238 -413.858456)
		(width 0.14732)
		(layer "In6.Cu")
		(net "P5E_CPU1_PE4_TX_C_DN<1>")
	)
	(segment
		(start 56.514238 -413.858456)
		(end 56.18607 -413.569404)
		(width 0.14732)
		(layer "In6.Cu")
		(net "P5E_CPU1_PE4_TX_C_DN<1>")
	)
	(segment
		(start 57.028334 -414.311846)
		(end 56.85282 -414.323022)
		(width 0.14732)
		(layer "In6.Cu")
		(net "P5E_CPU1_PE4_TX_C_DN<1>")
	)
	(segment
		(start 59.676792 -416.811714)
		(end 57.367678 -414.776666)
		(width 0.14732)
		(layer "In6.Cu")
		(net "P5E_CPU1_PE4_TX_C_DN<1>")
	)
	(segment
		(start 95.249238 -408.784044)
		(end 95.25254 -408.784044)
		(width 0.13208)
		(layer "F.Cu")
		(net "P5E_CPU1_PE4_TX_C_DN<15>")
	)
	(segment
		(start 95.57766 -409.109164)
		(end 95.57766 -409.727146)
		(width 0.13208)
		(layer "F.Cu")
		(net "P5E_CPU1_PE4_TX_C_DN<15>")
	)
	(segment
		(start 95.25254 -408.784044)
		(end 95.57766 -409.109164)
		(width 0.13208)
		(layer "F.Cu")
		(net "P5E_CPU1_PE4_TX_C_DN<15>")
	)
	(segment
		(start 95.57766 -409.727146)
		(end 95.274638 -410.030168)
		(width 0.13208)
		(layer "F.Cu")
		(net "P5E_CPU1_PE4_TX_C_DN<15>")
	)
	(segment
		(start 88.999822 -427.826932)
		(end 88.680544 -427.507654)
		(width 0.14732)
		(layer "In6.Cu")
		(net "P5E_CPU1_PE4_TX_C_DN<15>")
	)
	(segment
		(start 88.680544 -423.969434)
		(end 95.569278 -411.122876)
		(width 0.14732)
		(layer "In6.Cu")
		(net "P5E_CPU1_PE4_TX_C_DN<15>")
	)
	(segment
		(start 89.650062 -428.28972)
		(end 89.650062 -427.974506)
		(width 0.14732)
		(layer "In6.Cu")
		(net "P5E_CPU1_PE4_TX_C_DN<15>")
	)
	(segment
		(start 95.569278 -411.122876)
		(end 95.569278 -410.324808)
		(width 0.14732)
		(layer "In6.Cu")
		(net "P5E_CPU1_PE4_TX_C_DN<15>")
	)
	(segment
		(start 89.502488 -427.826932)
		(end 88.999822 -427.826932)
		(width 0.14732)
		(layer "In6.Cu")
		(net "P5E_CPU1_PE4_TX_C_DN<15>")
	)
	(segment
		(start 89.650062 -427.974506)
		(end 89.502488 -427.826932)
		(width 0.14732)
		(layer "In6.Cu")
		(net "P5E_CPU1_PE4_TX_C_DN<15>")
	)
	(segment
		(start 88.680544 -427.507654)
		(end 88.680544 -423.969434)
		(width 0.14732)
		(layer "In6.Cu")
		(net "P5E_CPU1_PE4_TX_C_DN<15>")
	)
	(segment
		(start 95.569278 -410.324808)
		(end 95.274638 -410.030168)
		(width 0.14732)
		(layer "In6.Cu")
		(net "P5E_CPU1_PE4_TX_C_DN<15>")
	)
	(segment
		(start 92.51442 -409.727146)
		(end 92.211398 -410.030168)
		(width 0.13208)
		(layer "F.Cu")
		(net "P5E_CPU1_PE4_TX_C_DN<14>")
	)
	(segment
		(start 92.1893 -408.784044)
		(end 92.51442 -409.109164)
		(width 0.13208)
		(layer "F.Cu")
		(net "P5E_CPU1_PE4_TX_C_DN<14>")
	)
	(segment
		(start 92.51442 -409.109164)
		(end 92.51442 -409.727146)
		(width 0.13208)
		(layer "F.Cu")
		(net "P5E_CPU1_PE4_TX_C_DN<14>")
	)
	(segment
		(start 92.185998 -408.784044)
		(end 92.1893 -408.784044)
		(width 0.13208)
		(layer "F.Cu")
		(net "P5E_CPU1_PE4_TX_C_DN<14>")
	)
	(segment
		(start 86.691978 -424.207178)
		(end 92.506038 -411.155896)
		(width 0.14732)
		(layer "In6.Cu")
		(net "P5E_CPU1_PE4_TX_C_DN<14>")
	)
	(segment
		(start 87.650066 -427.289976)
		(end 87.650066 -426.974762)
		(width 0.14732)
		(layer "In6.Cu")
		(net "P5E_CPU1_PE4_TX_C_DN<14>")
	)
	(segment
		(start 86.691978 -426.51934)
		(end 86.691978 -424.207178)
		(width 0.14732)
		(layer "In6.Cu")
		(net "P5E_CPU1_PE4_TX_C_DN<14>")
	)
	(segment
		(start 87.477092 -426.801788)
		(end 86.974426 -426.801788)
		(width 0.14732)
		(layer "In6.Cu")
		(net "P5E_CPU1_PE4_TX_C_DN<14>")
	)
	(segment
		(start 92.506038 -410.324808)
		(end 92.211398 -410.030168)
		(width 0.14732)
		(layer "In6.Cu")
		(net "P5E_CPU1_PE4_TX_C_DN<14>")
	)
	(segment
		(start 86.974426 -426.801788)
		(end 86.691978 -426.51934)
		(width 0.14732)
		(layer "In6.Cu")
		(net "P5E_CPU1_PE4_TX_C_DN<14>")
	)
	(segment
		(start 92.506038 -411.155896)
		(end 92.506038 -410.324808)
		(width 0.14732)
		(layer "In6.Cu")
		(net "P5E_CPU1_PE4_TX_C_DN<14>")
	)
	(segment
		(start 87.650066 -426.974762)
		(end 87.477092 -426.801788)
		(width 0.14732)
		(layer "In6.Cu")
		(net "P5E_CPU1_PE4_TX_C_DN<14>")
	)
	(segment
		(start 89.45118 -409.109164)
		(end 89.45118 -409.727146)
		(width 0.13208)
		(layer "F.Cu")
		(net "P5E_CPU1_PE4_TX_C_DN<13>")
	)
	(segment
		(start 89.45118 -409.727146)
		(end 89.148158 -410.030168)
		(width 0.13208)
		(layer "F.Cu")
		(net "P5E_CPU1_PE4_TX_C_DN<13>")
	)
	(segment
		(start 89.12606 -408.784044)
		(end 89.45118 -409.109164)
		(width 0.13208)
		(layer "F.Cu")
		(net "P5E_CPU1_PE4_TX_C_DN<13>")
	)
	(segment
		(start 89.122758 -408.784044)
		(end 89.12606 -408.784044)
		(width 0.13208)
		(layer "F.Cu")
		(net "P5E_CPU1_PE4_TX_C_DN<13>")
	)
	(segment
		(start 85.65007 -428.28972)
		(end 85.65007 -427.974506)
		(width 0.14732)
		(layer "In6.Cu")
		(net "P5E_CPU1_PE4_TX_C_DN<13>")
	)
	(segment
		(start 84.691982 -423.936922)
		(end 89.442798 -411.227016)
		(width 0.14732)
		(layer "In6.Cu")
		(net "P5E_CPU1_PE4_TX_C_DN<13>")
	)
	(segment
		(start 85.65007 -427.974506)
		(end 85.502496 -427.826932)
		(width 0.14732)
		(layer "In6.Cu")
		(net "P5E_CPU1_PE4_TX_C_DN<13>")
	)
	(segment
		(start 89.442798 -410.324808)
		(end 89.148158 -410.030168)
		(width 0.14732)
		(layer "In6.Cu")
		(net "P5E_CPU1_PE4_TX_C_DN<13>")
	)
	(segment
		(start 84.691982 -427.519084)
		(end 84.691982 -423.936922)
		(width 0.14732)
		(layer "In6.Cu")
		(net "P5E_CPU1_PE4_TX_C_DN<13>")
	)
	(segment
		(start 84.99983 -427.826932)
		(end 84.691982 -427.519084)
		(width 0.14732)
		(layer "In6.Cu")
		(net "P5E_CPU1_PE4_TX_C_DN<13>")
	)
	(segment
		(start 89.442798 -411.227016)
		(end 89.442798 -410.324808)
		(width 0.14732)
		(layer "In6.Cu")
		(net "P5E_CPU1_PE4_TX_C_DN<13>")
	)
	(segment
		(start 85.502496 -427.826932)
		(end 84.99983 -427.826932)
		(width 0.14732)
		(layer "In6.Cu")
		(net "P5E_CPU1_PE4_TX_C_DN<13>")
	)
	(segment
		(start 86.06282 -408.784044)
		(end 86.38794 -409.109164)
		(width 0.13208)
		(layer "F.Cu")
		(net "P5E_CPU1_PE4_TX_C_DN<12>")
	)
	(segment
		(start 86.38794 -409.109164)
		(end 86.38794 -409.727146)
		(width 0.13208)
		(layer "F.Cu")
		(net "P5E_CPU1_PE4_TX_C_DN<12>")
	)
	(segment
		(start 86.059518 -408.784044)
		(end 86.06282 -408.784044)
		(width 0.13208)
		(layer "F.Cu")
		(net "P5E_CPU1_PE4_TX_C_DN<12>")
	)
	(segment
		(start 86.38794 -409.727146)
		(end 86.084918 -410.030168)
		(width 0.13208)
		(layer "F.Cu")
		(net "P5E_CPU1_PE4_TX_C_DN<12>")
	)
	(segment
		(start 86.379558 -411.338776)
		(end 86.379558 -410.324808)
		(width 0.14732)
		(layer "In6.Cu")
		(net "P5E_CPU1_PE4_TX_C_DN<12>")
	)
	(segment
		(start 83.650074 -426.974762)
		(end 83.5025 -426.827188)
		(width 0.14732)
		(layer "In6.Cu")
		(net "P5E_CPU1_PE4_TX_C_DN<12>")
	)
	(segment
		(start 82.691986 -426.51934)
		(end 82.691986 -423.925238)
		(width 0.14732)
		(layer "In6.Cu")
		(net "P5E_CPU1_PE4_TX_C_DN<12>")
	)
	(segment
		(start 83.650074 -427.289976)
		(end 83.650074 -426.974762)
		(width 0.14732)
		(layer "In6.Cu")
		(net "P5E_CPU1_PE4_TX_C_DN<12>")
	)
	(segment
		(start 83.5025 -426.827188)
		(end 82.999834 -426.827188)
		(width 0.14732)
		(layer "In6.Cu")
		(net "P5E_CPU1_PE4_TX_C_DN<12>")
	)
	(segment
		(start 86.379558 -410.324808)
		(end 86.084918 -410.030168)
		(width 0.14732)
		(layer "In6.Cu")
		(net "P5E_CPU1_PE4_TX_C_DN<12>")
	)
	(segment
		(start 82.999834 -426.827188)
		(end 82.691986 -426.51934)
		(width 0.14732)
		(layer "In6.Cu")
		(net "P5E_CPU1_PE4_TX_C_DN<12>")
	)
	(segment
		(start 82.691986 -423.925238)
		(end 86.379558 -411.338776)
		(width 0.14732)
		(layer "In6.Cu")
		(net "P5E_CPU1_PE4_TX_C_DN<12>")
	)
	(segment
		(start 83.58378 -409.110942)
		(end 83.58378 -409.72867)
		(width 0.13208)
		(layer "F.Cu")
		(net "P5E_CPU1_PE4_TX_C_DN<11>")
	)
	(segment
		(start 83.58378 -409.72867)
		(end 83.885278 -410.030168)
		(width 0.13208)
		(layer "F.Cu")
		(net "P5E_CPU1_PE4_TX_C_DN<11>")
	)
	(segment
		(start 83.910678 -408.784044)
		(end 83.58378 -409.110942)
		(width 0.13208)
		(layer "F.Cu")
		(net "P5E_CPU1_PE4_TX_C_DN<11>")
	)
	(segment
		(start 81.650078 -427.31817)
		(end 81.650078 -427.089824)
		(width 0.14732)
		(layer "In6.Cu")
		(net "P5E_CPU1_PE4_TX_C_DN<11>")
	)
	(segment
		(start 81.19237 -422.727882)
		(end 80.96631 -423.781728)
		(width 0.14732)
		(layer "In6.Cu")
		(net "P5E_CPU1_PE4_TX_C_DN<11>")
	)
	(segment
		(start 82.076036 -419.280086)
		(end 81.99882 -419.640512)
		(width 0.14732)
		(layer "In6.Cu")
		(net "P5E_CPU1_PE4_TX_C_DN<11>")
	)
	(segment
		(start 81.35874 -422.620694)
		(end 81.19237 -422.727882)
		(width 0.14732)
		(layer "In6.Cu")
		(net "P5E_CPU1_PE4_TX_C_DN<11>")
	)
	(segment
		(start 80.96631 -423.781728)
		(end 80.96631 -427.405292)
		(width 0.14732)
		(layer "In6.Cu")
		(net "P5E_CPU1_PE4_TX_C_DN<11>")
	)
	(segment
		(start 81.832704 -419.7477)
		(end 81.755488 -420.107618)
		(width 0.14732)
		(layer "In6.Cu")
		(net "P5E_CPU1_PE4_TX_C_DN<11>")
	)
	(segment
		(start 81.99882 -419.640512)
		(end 81.832704 -419.7477)
		(width 0.14732)
		(layer "In6.Cu")
		(net "P5E_CPU1_PE4_TX_C_DN<11>")
	)
	(segment
		(start 81.649316 -421.266874)
		(end 81.5721 -421.6273)
		(width 0.14732)
		(layer "In6.Cu")
		(net "P5E_CPU1_PE4_TX_C_DN<11>")
	)
	(segment
		(start 81.11363 -427.552612)
		(end 81.415636 -427.552612)
		(width 0.14732)
		(layer "In6.Cu")
		(net "P5E_CPU1_PE4_TX_C_DN<11>")
	)
	(segment
		(start 83.885278 -410.030168)
		(end 83.590638 -410.324808)
		(width 0.14732)
		(layer "In6.Cu")
		(net "P5E_CPU1_PE4_TX_C_DN<11>")
	)
	(segment
		(start 81.5721 -421.6273)
		(end 81.405984 -421.734488)
		(width 0.14732)
		(layer "In6.Cu")
		(net "P5E_CPU1_PE4_TX_C_DN<11>")
	)
	(segment
		(start 81.862676 -420.27348)
		(end 81.78546 -420.633906)
		(width 0.14732)
		(layer "In6.Cu")
		(net "P5E_CPU1_PE4_TX_C_DN<11>")
	)
	(segment
		(start 81.968848 -419.114224)
		(end 82.076036 -419.280086)
		(width 0.14732)
		(layer "In6.Cu")
		(net "P5E_CPU1_PE4_TX_C_DN<11>")
	)
	(segment
		(start 81.405984 -421.734488)
		(end 81.328768 -422.094406)
		(width 0.14732)
		(layer "In6.Cu")
		(net "P5E_CPU1_PE4_TX_C_DN<11>")
	)
	(segment
		(start 80.96631 -427.405292)
		(end 81.11363 -427.552612)
		(width 0.14732)
		(layer "In6.Cu")
		(net "P5E_CPU1_PE4_TX_C_DN<11>")
	)
	(segment
		(start 81.78546 -420.633906)
		(end 81.619344 -420.741094)
		(width 0.14732)
		(layer "In6.Cu")
		(net "P5E_CPU1_PE4_TX_C_DN<11>")
	)
	(segment
		(start 81.415636 -427.552612)
		(end 81.650078 -427.31817)
		(width 0.14732)
		(layer "In6.Cu")
		(net "P5E_CPU1_PE4_TX_C_DN<11>")
	)
	(segment
		(start 81.435956 -422.260268)
		(end 81.35874 -422.620694)
		(width 0.14732)
		(layer "In6.Cu")
		(net "P5E_CPU1_PE4_TX_C_DN<11>")
	)
	(segment
		(start 81.755488 -420.107618)
		(end 81.862676 -420.27348)
		(width 0.14732)
		(layer "In6.Cu")
		(net "P5E_CPU1_PE4_TX_C_DN<11>")
	)
	(segment
		(start 81.542128 -421.101012)
		(end 81.649316 -421.266874)
		(width 0.14732)
		(layer "In6.Cu")
		(net "P5E_CPU1_PE4_TX_C_DN<11>")
	)
	(segment
		(start 81.619344 -420.741094)
		(end 81.542128 -421.101012)
		(width 0.14732)
		(layer "In6.Cu")
		(net "P5E_CPU1_PE4_TX_C_DN<11>")
	)
	(segment
		(start 83.590638 -410.324808)
		(end 83.590638 -411.559756)
		(width 0.14732)
		(layer "In6.Cu")
		(net "P5E_CPU1_PE4_TX_C_DN<11>")
	)
	(segment
		(start 81.328768 -422.094406)
		(end 81.435956 -422.260268)
		(width 0.14732)
		(layer "In6.Cu")
		(net "P5E_CPU1_PE4_TX_C_DN<11>")
	)
	(segment
		(start 81.968594 -419.11397)
		(end 81.968848 -419.114224)
		(width 0.14732)
		(layer "In6.Cu")
		(net "P5E_CPU1_PE4_TX_C_DN<11>")
	)
	(segment
		(start 83.590638 -411.559756)
		(end 81.968594 -419.11397)
		(width 0.14732)
		(layer "In6.Cu")
		(net "P5E_CPU1_PE4_TX_C_DN<11>")
	)
	(segment
		(start 79.933038 -408.784044)
		(end 79.93634 -408.784044)
		(width 0.13208)
		(layer "F.Cu")
		(net "P5E_CPU1_PE4_TX_C_DN<10>")
	)
	(segment
		(start 79.93634 -408.784044)
		(end 80.26146 -409.109164)
		(width 0.13208)
		(layer "F.Cu")
		(net "P5E_CPU1_PE4_TX_C_DN<10>")
	)
	(segment
		(start 80.26146 -409.727146)
		(end 79.958438 -410.030168)
		(width 0.13208)
		(layer "F.Cu")
		(net "P5E_CPU1_PE4_TX_C_DN<10>")
	)
	(segment
		(start 80.26146 -409.109164)
		(end 80.26146 -409.727146)
		(width 0.13208)
		(layer "F.Cu")
		(net "P5E_CPU1_PE4_TX_C_DN<10>")
	)
	(segment
		(start 79.650082 -426.974762)
		(end 79.502508 -426.827188)
		(width 0.14732)
		(layer "In6.Cu")
		(net "P5E_CPU1_PE4_TX_C_DN<10>")
	)
	(segment
		(start 80.253078 -410.324808)
		(end 79.958438 -410.030168)
		(width 0.14732)
		(layer "In6.Cu")
		(net "P5E_CPU1_PE4_TX_C_DN<10>")
	)
	(segment
		(start 78.691994 -423.839132)
		(end 80.253078 -411.973268)
		(width 0.14732)
		(layer "In6.Cu")
		(net "P5E_CPU1_PE4_TX_C_DN<10>")
	)
	(segment
		(start 80.253078 -411.973268)
		(end 80.253078 -410.324808)
		(width 0.14732)
		(layer "In6.Cu")
		(net "P5E_CPU1_PE4_TX_C_DN<10>")
	)
	(segment
		(start 79.502508 -426.827188)
		(end 78.999842 -426.827188)
		(width 0.14732)
		(layer "In6.Cu")
		(net "P5E_CPU1_PE4_TX_C_DN<10>")
	)
	(segment
		(start 79.650082 -427.289976)
		(end 79.650082 -426.974762)
		(width 0.14732)
		(layer "In6.Cu")
		(net "P5E_CPU1_PE4_TX_C_DN<10>")
	)
	(segment
		(start 78.999842 -426.827188)
		(end 78.691994 -426.51934)
		(width 0.14732)
		(layer "In6.Cu")
		(net "P5E_CPU1_PE4_TX_C_DN<10>")
	)
	(segment
		(start 78.691994 -426.51934)
		(end 78.691994 -423.839132)
		(width 0.14732)
		(layer "In6.Cu")
		(net "P5E_CPU1_PE4_TX_C_DN<10>")
	)
	(segment
		(start 49.300638 -408.784044)
		(end 49.30394 -408.784044)
		(width 0.13208)
		(layer "F.Cu")
		(net "P5E_CPU1_PE4_TX_C_DN<0>")
	)
	(segment
		(start 49.62906 -409.727146)
		(end 49.326038 -410.030168)
		(width 0.13208)
		(layer "F.Cu")
		(net "P5E_CPU1_PE4_TX_C_DN<0>")
	)
	(segment
		(start 49.62906 -409.109164)
		(end 49.62906 -409.727146)
		(width 0.13208)
		(layer "F.Cu")
		(net "P5E_CPU1_PE4_TX_C_DN<0>")
	)
	(segment
		(start 49.30394 -408.784044)
		(end 49.62906 -409.109164)
		(width 0.13208)
		(layer "F.Cu")
		(net "P5E_CPU1_PE4_TX_C_DN<0>")
	)
	(segment
		(start 58.650124 -427.289976)
		(end 58.650124 -426.974762)
		(width 0.14732)
		(layer "In6.Cu")
		(net "P5E_CPU1_PE4_TX_C_DN<0>")
	)
	(segment
		(start 58.650124 -426.974762)
		(end 58.50255 -426.827188)
		(width 0.14732)
		(layer "In6.Cu")
		(net "P5E_CPU1_PE4_TX_C_DN<0>")
	)
	(segment
		(start 49.620678 -411.105096)
		(end 49.620678 -410.324808)
		(width 0.14732)
		(layer "In6.Cu")
		(net "P5E_CPU1_PE4_TX_C_DN<0>")
	)
	(segment
		(start 58.50255 -426.827188)
		(end 58.000138 -426.827188)
		(width 0.14732)
		(layer "In6.Cu")
		(net "P5E_CPU1_PE4_TX_C_DN<0>")
	)
	(segment
		(start 57.41035 -426.236892)
		(end 49.620678 -411.105096)
		(width 0.14732)
		(layer "In6.Cu")
		(net "P5E_CPU1_PE4_TX_C_DN<0>")
	)
	(segment
		(start 49.620678 -410.324808)
		(end 49.326038 -410.030168)
		(width 0.14732)
		(layer "In6.Cu")
		(net "P5E_CPU1_PE4_TX_C_DN<0>")
	)
	(segment
		(start 58.000138 -426.827188)
		(end 57.41035 -426.236892)
		(width 0.14732)
		(layer "In6.Cu")
		(net "P5E_CPU1_PE4_TX_C_DN<0>")
	)
	(segment
		(start 98.123248 -288.381186)
		(end 98.123248 -288.917126)
		(width 0.13208)
		(layer "F.Cu")
		(net "P5E_CPU1_PE4_RX_DP<9>")
	)
	(segment
		(start 96.630744 -297.069764)
		(end 96.630744 -297.070018)
		(width 0.14732)
		(layer "In4.Cu")
		(net "P5E_CPU1_PE4_RX_DP<9>")
	)
	(segment
		(start 75.658218 -410.677868)
		(end 75.658218 -406.19934)
		(width 0.14732)
		(layer "In4.Cu")
		(net "P5E_CPU1_PE4_RX_DP<9>")
	)
	(segment
		(start 96.630744 -297.070018)
		(end 96.631252 -297.06824)
		(width 0.14732)
		(layer "In4.Cu")
		(net "P5E_CPU1_PE4_RX_DP<9>")
	)
	(segment
		(start 67.996562 -351.077276)
		(end 67.622674 -335.097628)
		(width 0.14732)
		(layer "In4.Cu")
		(net "P5E_CPU1_PE4_RX_DP<9>")
	)
	(segment
		(start 98.279712 -288.646108)
		(end 98.123248 -288.917126)
		(width 0.0889)
		(layer "In4.Cu")
		(net "P5E_CPU1_PE4_RX_DP<9>")
	)
	(segment
		(start 98.497898 -289.114738)
		(end 98.497898 -288.917126)
		(width 0.0889)
		(layer "In4.Cu")
		(net "P5E_CPU1_PE4_RX_DP<9>")
	)
	(segment
		(start 77.000354 -435.02707)
		(end 76.692506 -434.719222)
		(width 0.14732)
		(layer "In4.Cu")
		(net "P5E_CPU1_PE4_RX_DP<9>")
	)
	(segment
		(start 75.658218 -406.19934)
		(end 77.375258 -404.4823)
		(width 0.14732)
		(layer "In4.Cu")
		(net "P5E_CPU1_PE4_RX_DP<9>")
	)
	(segment
		(start 96.631252 -292.992048)
		(end 96.631252 -292.96995)
		(width 0.0889)
		(layer "In4.Cu")
		(net "P5E_CPU1_PE4_RX_DP<9>")
	)
	(segment
		(start 96.631252 -297.06824)
		(end 96.631252 -292.992048)
		(width 0.14732)
		(layer "In4.Cu")
		(net "P5E_CPU1_PE4_RX_DP<9>")
	)
	(segment
		(start 67.622674 -335.097628)
		(end 67.684904 -334.026002)
		(width 0.14732)
		(layer "In4.Cu")
		(net "P5E_CPU1_PE4_RX_DP<9>")
	)
	(segment
		(start 96.673162 -292.508432)
		(end 98.967544 -290.21405)
		(width 0.0889)
		(layer "In4.Cu")
		(net "P5E_CPU1_PE4_RX_DP<9>")
	)
	(segment
		(start 98.967544 -290.21405)
		(end 98.967544 -289.645852)
		(width 0.0889)
		(layer "In4.Cu")
		(net "P5E_CPU1_PE4_RX_DP<9>")
	)
	(segment
		(start 98.357944 -288.62528)
		(end 98.279712 -288.646108)
		(width 0.0889)
		(layer "In4.Cu")
		(net "P5E_CPU1_PE4_RX_DP<9>")
	)
	(segment
		(start 96.631252 -292.96995)
		(end 96.673162 -292.92804)
		(width 0.0889)
		(layer "In4.Cu")
		(net "P5E_CPU1_PE4_RX_DP<9>")
	)
	(segment
		(start 76.692506 -423.90822)
		(end 75.884786 -411.92323)
		(width 0.14732)
		(layer "In4.Cu")
		(net "P5E_CPU1_PE4_RX_DP<9>")
	)
	(segment
		(start 77.375258 -404.4823)
		(end 77.375258 -399.109184)
		(width 0.14732)
		(layer "In4.Cu")
		(net "P5E_CPU1_PE4_RX_DP<9>")
	)
	(segment
		(start 76.692506 -434.719222)
		(end 76.692506 -423.90822)
		(width 0.14732)
		(layer "In4.Cu")
		(net "P5E_CPU1_PE4_RX_DP<9>")
	)
	(segment
		(start 70.552818 -327.101454)
		(end 95.7834 -301.87011)
		(width 0.14732)
		(layer "In4.Cu")
		(net "P5E_CPU1_PE4_RX_DP<9>")
	)
	(segment
		(start 67.684904 -334.026002)
		(end 70.552818 -327.101454)
		(width 0.14732)
		(layer "In4.Cu")
		(net "P5E_CPU1_PE4_RX_DP<9>")
	)
	(segment
		(start 77.650086 -435.489858)
		(end 77.650086 -435.174644)
		(width 0.14732)
		(layer "In4.Cu")
		(net "P5E_CPU1_PE4_RX_DP<9>")
	)
	(segment
		(start 77.502512 -435.02707)
		(end 77.000354 -435.02707)
		(width 0.14732)
		(layer "In4.Cu")
		(net "P5E_CPU1_PE4_RX_DP<9>")
	)
	(segment
		(start 96.673162 -292.92804)
		(end 96.673162 -292.508432)
		(width 0.0889)
		(layer "In4.Cu")
		(net "P5E_CPU1_PE4_RX_DP<9>")
	)
	(segment
		(start 75.884786 -411.92323)
		(end 75.658218 -410.677868)
		(width 0.14732)
		(layer "In4.Cu")
		(net "P5E_CPU1_PE4_RX_DP<9>")
	)
	(segment
		(start 95.7834 -301.87011)
		(end 96.630744 -297.069764)
		(width 0.14732)
		(layer "In4.Cu")
		(net "P5E_CPU1_PE4_RX_DP<9>")
	)
	(segment
		(start 77.375258 -399.109184)
		(end 70.787514 -367.424716)
		(width 0.14732)
		(layer "In4.Cu")
		(net "P5E_CPU1_PE4_RX_DP<9>")
	)
	(segment
		(start 77.650086 -435.174644)
		(end 77.502512 -435.02707)
		(width 0.14732)
		(layer "In4.Cu")
		(net "P5E_CPU1_PE4_RX_DP<9>")
	)
	(segment
		(start 70.787514 -367.424716)
		(end 67.996562 -351.077276)
		(width 0.14732)
		(layer "In4.Cu")
		(net "P5E_CPU1_PE4_RX_DP<9>")
	)
	(arc
		(start 98.497898 -288.917126)
		(mid 98.461038 -288.755329)
		(end 98.357944 -288.62528)
		(width 0.0889)
		(layer "In4.Cu")
		(net "P5E_CPU1_PE4_RX_DP<9>")
	)
	(arc
		(start 98.783394 -289.446462)
		(mid 98.609262 -289.307615)
		(end 98.497898 -289.114738)
		(width 0.0889)
		(layer "In4.Cu")
		(net "P5E_CPU1_PE4_RX_DP<9>")
	)
	(arc
		(start 98.967544 -289.645852)
		(mid 98.892539 -289.530393)
		(end 98.783394 -289.446462)
		(width 0.0889)
		(layer "In4.Cu")
		(net "P5E_CPU1_PE4_RX_DP<9>")
	)
	(segment
		(start 97.183448 -288.381186)
		(end 97.183448 -288.917126)
		(width 0.13208)
		(layer "F.Cu")
		(net "P5E_CPU1_PE4_RX_DP<8>")
	)
	(segment
		(start 73.09612 -411.257242)
		(end 73.167494 -411.745176)
		(width 0.14732)
		(layer "In4.Cu")
		(net "P5E_CPU1_PE4_RX_DP<8>")
	)
	(segment
		(start 98.218244 -289.60953)
		(end 98.218244 -290.229798)
		(width 0.0889)
		(layer "In4.Cu")
		(net "P5E_CPU1_PE4_RX_DP<8>")
	)
	(segment
		(start 97.183448 -288.917126)
		(end 97.342198 -289.218116)
		(width 0.0889)
		(layer "In4.Cu")
		(net "P5E_CPU1_PE4_RX_DP<8>")
	)
	(segment
		(start 73.52665 -413.233362)
		(end 73.40854 -413.391604)
		(width 0.14732)
		(layer "In4.Cu")
		(net "P5E_CPU1_PE4_RX_DP<8>")
	)
	(segment
		(start 98.218244 -290.229798)
		(end 95.93072 -292.517322)
		(width 0.0889)
		(layer "In4.Cu")
		(net "P5E_CPU1_PE4_RX_DP<8>")
	)
	(segment
		(start 95.93072 -292.927786)
		(end 95.972884 -292.96995)
		(width 0.0889)
		(layer "In4.Cu")
		(net "P5E_CPU1_PE4_RX_DP<8>")
	)
	(segment
		(start 95.972884 -292.992048)
		(end 95.972884 -297.006264)
		(width 0.14732)
		(layer "In4.Cu")
		(net "P5E_CPU1_PE4_RX_DP<8>")
	)
	(segment
		(start 73.37933 -412.227776)
		(end 73.261474 -412.386272)
		(width 0.14732)
		(layer "In4.Cu")
		(net "P5E_CPU1_PE4_RX_DP<8>")
	)
	(segment
		(start 73.47331 -412.868618)
		(end 73.52665 -413.233362)
		(width 0.14732)
		(layer "In4.Cu")
		(net "P5E_CPU1_PE4_RX_DP<8>")
	)
	(segment
		(start 72.869298 -406.313132)
		(end 72.869298 -410.535628)
		(width 0.14732)
		(layer "In4.Cu")
		(net "P5E_CPU1_PE4_RX_DP<8>")
	)
	(segment
		(start 95.93072 -292.517322)
		(end 95.93072 -292.927786)
		(width 0.0889)
		(layer "In4.Cu")
		(net "P5E_CPU1_PE4_RX_DP<8>")
	)
	(segment
		(start 95.171006 -301.55134)
		(end 69.907658 -326.81545)
		(width 0.14732)
		(layer "In4.Cu")
		(net "P5E_CPU1_PE4_RX_DP<8>")
	)
	(segment
		(start 69.907658 -326.81545)
		(end 66.991738 -333.855822)
		(width 0.14732)
		(layer "In4.Cu")
		(net "P5E_CPU1_PE4_RX_DP<8>")
	)
	(segment
		(start 97.342198 -289.218116)
		(end 97.438972 -289.247834)
		(width 0.0889)
		(layer "In4.Cu")
		(net "P5E_CPU1_PE4_RX_DP<8>")
	)
	(segment
		(start 74.586338 -404.596092)
		(end 72.869298 -406.313132)
		(width 0.14732)
		(layer "In4.Cu")
		(net "P5E_CPU1_PE4_RX_DP<8>")
	)
	(segment
		(start 73.261474 -412.386272)
		(end 73.31456 -412.750508)
		(width 0.14732)
		(layer "In4.Cu")
		(net "P5E_CPU1_PE4_RX_DP<8>")
	)
	(segment
		(start 73.31456 -412.750508)
		(end 73.47331 -412.868618)
		(width 0.14732)
		(layer "In4.Cu")
		(net "P5E_CPU1_PE4_RX_DP<8>")
	)
	(segment
		(start 75.151742 -433.752752)
		(end 75.502516 -433.752752)
		(width 0.14732)
		(layer "In4.Cu")
		(net "P5E_CPU1_PE4_RX_DP<8>")
	)
	(segment
		(start 95.972884 -297.006264)
		(end 95.171006 -301.55134)
		(width 0.14732)
		(layer "In4.Cu")
		(net "P5E_CPU1_PE4_RX_DP<8>")
	)
	(segment
		(start 66.991738 -333.855822)
		(end 66.85026 -335.417668)
		(width 0.14732)
		(layer "In4.Cu")
		(net "P5E_CPU1_PE4_RX_DP<8>")
	)
	(segment
		(start 75.65009 -433.605178)
		(end 75.65009 -433.289964)
		(width 0.14732)
		(layer "In4.Cu")
		(net "P5E_CPU1_PE4_RX_DP<8>")
	)
	(segment
		(start 67.119754 -350.03867)
		(end 70.345554 -372.674388)
		(width 0.14732)
		(layer "In4.Cu")
		(net "P5E_CPU1_PE4_RX_DP<8>")
	)
	(segment
		(start 75.502516 -433.752752)
		(end 75.65009 -433.605178)
		(width 0.14732)
		(layer "In4.Cu")
		(net "P5E_CPU1_PE4_RX_DP<8>")
	)
	(segment
		(start 74.03084 -417.647882)
		(end 74.901298 -433.502308)
		(width 0.14732)
		(layer "In4.Cu")
		(net "P5E_CPU1_PE4_RX_DP<8>")
	)
	(segment
		(start 74.586338 -398.399762)
		(end 74.586338 -404.596092)
		(width 0.14732)
		(layer "In4.Cu")
		(net "P5E_CPU1_PE4_RX_DP<8>")
	)
	(segment
		(start 95.972884 -292.96995)
		(end 95.972884 -292.992048)
		(width 0.0889)
		(layer "In4.Cu")
		(net "P5E_CPU1_PE4_RX_DP<8>")
	)
	(segment
		(start 73.32599 -411.863286)
		(end 73.37933 -412.227776)
		(width 0.14732)
		(layer "In4.Cu")
		(net "P5E_CPU1_PE4_RX_DP<8>")
	)
	(segment
		(start 66.85026 -335.417668)
		(end 67.119754 -350.03867)
		(width 0.14732)
		(layer "In4.Cu")
		(net "P5E_CPU1_PE4_RX_DP<8>")
	)
	(segment
		(start 73.40854 -413.391604)
		(end 74.03084 -417.647882)
		(width 0.14732)
		(layer "In4.Cu")
		(net "P5E_CPU1_PE4_RX_DP<8>")
	)
	(segment
		(start 70.345554 -372.674388)
		(end 74.586338 -398.399762)
		(width 0.14732)
		(layer "In4.Cu")
		(net "P5E_CPU1_PE4_RX_DP<8>")
	)
	(segment
		(start 72.869298 -410.535628)
		(end 73.09612 -411.257242)
		(width 0.14732)
		(layer "In4.Cu")
		(net "P5E_CPU1_PE4_RX_DP<8>")
	)
	(segment
		(start 73.167494 -411.745176)
		(end 73.32599 -411.863286)
		(width 0.14732)
		(layer "In4.Cu")
		(net "P5E_CPU1_PE4_RX_DP<8>")
	)
	(segment
		(start 74.901298 -433.502308)
		(end 75.151742 -433.752752)
		(width 0.14732)
		(layer "In4.Cu")
		(net "P5E_CPU1_PE4_RX_DP<8>")
	)
	(arc
		(start 97.438972 -289.247834)
		(mid 97.448847 -289.244192)
		(end 97.458784 -289.240722)
		(width 0.0889)
		(layer "In4.Cu")
		(net "P5E_CPU1_PE4_RX_DP<8>")
	)
	(arc
		(start 97.458784 -289.240722)
		(mid 97.914626 -289.26845)
		(end 98.218244 -289.60953)
		(width 0.0889)
		(layer "In4.Cu")
		(net "P5E_CPU1_PE4_RX_DP<8>")
	)
	(segment
		(start 96.243648 -288.381186)
		(end 96.243648 -288.917126)
		(width 0.13208)
		(layer "F.Cu")
		(net "P5E_CPU1_PE4_RX_DP<7>")
	)
	(segment
		(start 71.692516 -434.719222)
		(end 71.692516 -417.244784)
		(width 0.14732)
		(layer "In4.Cu")
		(net "P5E_CPU1_PE4_RX_DP<7>")
	)
	(segment
		(start 65.716658 -333.676244)
		(end 68.810378 -326.20712)
		(width 0.14732)
		(layer "In4.Cu")
		(net "P5E_CPU1_PE4_RX_DP<7>")
	)
	(segment
		(start 65.762632 -348.955614)
		(end 65.606168 -334.39862)
		(width 0.14732)
		(layer "In4.Cu")
		(net "P5E_CPU1_PE4_RX_DP<7>")
	)
	(segment
		(start 68.810378 -326.20712)
		(end 94.047564 -300.96968)
		(width 0.14732)
		(layer "In4.Cu")
		(net "P5E_CPU1_PE4_RX_DP<7>")
	)
	(segment
		(start 94.765876 -296.89933)
		(end 94.765876 -292.992048)
		(width 0.14732)
		(layer "In4.Cu")
		(net "P5E_CPU1_PE4_RX_DP<7>")
	)
	(segment
		(start 72.502522 -435.10835)
		(end 72.081644 -435.10835)
		(width 0.14732)
		(layer "In4.Cu")
		(net "P5E_CPU1_PE4_RX_DP<7>")
	)
	(segment
		(start 96.618298 -289.114738)
		(end 96.618298 -288.917126)
		(width 0.0889)
		(layer "In4.Cu")
		(net "P5E_CPU1_PE4_RX_DP<7>")
	)
	(segment
		(start 71.248778 -398.263364)
		(end 65.762632 -348.955614)
		(width 0.14732)
		(layer "In4.Cu")
		(net "P5E_CPU1_PE4_RX_DP<7>")
	)
	(segment
		(start 72.650096 -435.489858)
		(end 72.650096 -435.255924)
		(width 0.14732)
		(layer "In4.Cu")
		(net "P5E_CPU1_PE4_RX_DP<7>")
	)
	(segment
		(start 72.650096 -435.255924)
		(end 72.502522 -435.10835)
		(width 0.14732)
		(layer "In4.Cu")
		(net "P5E_CPU1_PE4_RX_DP<7>")
	)
	(segment
		(start 94.807786 -292.327076)
		(end 97.087944 -290.046918)
		(width 0.0889)
		(layer "In4.Cu")
		(net "P5E_CPU1_PE4_RX_DP<7>")
	)
	(segment
		(start 69.531738 -410.595826)
		(end 69.531738 -406.19934)
		(width 0.14732)
		(layer "In4.Cu")
		(net "P5E_CPU1_PE4_RX_DP<7>")
	)
	(segment
		(start 72.081644 -435.10835)
		(end 71.692516 -434.719222)
		(width 0.14732)
		(layer "In4.Cu")
		(net "P5E_CPU1_PE4_RX_DP<7>")
	)
	(segment
		(start 96.478344 -288.62528)
		(end 96.400112 -288.646108)
		(width 0.0889)
		(layer "In4.Cu")
		(net "P5E_CPU1_PE4_RX_DP<7>")
	)
	(segment
		(start 94.765876 -292.96995)
		(end 94.807786 -292.92804)
		(width 0.0889)
		(layer "In4.Cu")
		(net "P5E_CPU1_PE4_RX_DP<7>")
	)
	(segment
		(start 96.400112 -288.646108)
		(end 96.243648 -288.917126)
		(width 0.0889)
		(layer "In4.Cu")
		(net "P5E_CPU1_PE4_RX_DP<7>")
	)
	(segment
		(start 71.248778 -404.4823)
		(end 71.248778 -398.263364)
		(width 0.14732)
		(layer "In4.Cu")
		(net "P5E_CPU1_PE4_RX_DP<7>")
	)
	(segment
		(start 94.807786 -292.92804)
		(end 94.807786 -292.327076)
		(width 0.0889)
		(layer "In4.Cu")
		(net "P5E_CPU1_PE4_RX_DP<7>")
	)
	(segment
		(start 65.606168 -334.39862)
		(end 65.716658 -333.676244)
		(width 0.14732)
		(layer "In4.Cu")
		(net "P5E_CPU1_PE4_RX_DP<7>")
	)
	(segment
		(start 94.047564 -300.96968)
		(end 94.765876 -296.89933)
		(width 0.14732)
		(layer "In4.Cu")
		(net "P5E_CPU1_PE4_RX_DP<7>")
	)
	(segment
		(start 69.531738 -406.19934)
		(end 71.248778 -404.4823)
		(width 0.14732)
		(layer "In4.Cu")
		(net "P5E_CPU1_PE4_RX_DP<7>")
	)
	(segment
		(start 97.087944 -290.046918)
		(end 97.087944 -289.645852)
		(width 0.0889)
		(layer "In4.Cu")
		(net "P5E_CPU1_PE4_RX_DP<7>")
	)
	(segment
		(start 71.692516 -417.244784)
		(end 69.531738 -410.595826)
		(width 0.14732)
		(layer "In4.Cu")
		(net "P5E_CPU1_PE4_RX_DP<7>")
	)
	(segment
		(start 94.765876 -292.992048)
		(end 94.765876 -292.96995)
		(width 0.0889)
		(layer "In4.Cu")
		(net "P5E_CPU1_PE4_RX_DP<7>")
	)
	(arc
		(start 96.618298 -288.917126)
		(mid 96.581438 -288.755329)
		(end 96.478344 -288.62528)
		(width 0.0889)
		(layer "In4.Cu")
		(net "P5E_CPU1_PE4_RX_DP<7>")
	)
	(arc
		(start 96.903794 -289.446462)
		(mid 96.729662 -289.307615)
		(end 96.618298 -289.114738)
		(width 0.0889)
		(layer "In4.Cu")
		(net "P5E_CPU1_PE4_RX_DP<7>")
	)
	(arc
		(start 97.087944 -289.645852)
		(mid 97.012939 -289.530393)
		(end 96.903794 -289.446462)
		(width 0.0889)
		(layer "In4.Cu")
		(net "P5E_CPU1_PE4_RX_DP<7>")
	)
	(segment
		(start 95.303848 -288.381186)
		(end 95.303848 -288.917126)
		(width 0.13208)
		(layer "F.Cu")
		(net "P5E_CPU1_PE4_RX_DP<6>")
	)
	(segment
		(start 65.087754 -349.00108)
		(end 64.929258 -334.199738)
		(width 0.14732)
		(layer "In4.Cu")
		(net "P5E_CPU1_PE4_RX_DP<6>")
	)
	(segment
		(start 68.12915 -325.95312)
		(end 93.436186 -300.646084)
		(width 0.14732)
		(layer "In4.Cu")
		(net "P5E_CPU1_PE4_RX_DP<6>")
	)
	(segment
		(start 68.04533 -413.374586)
		(end 68.102226 -413.18561)
		(width 0.14732)
		(layer "In4.Cu")
		(net "P5E_CPU1_PE4_RX_DP<6>")
	)
	(segment
		(start 95.462598 -289.218116)
		(end 95.303848 -288.917126)
		(width 0.0889)
		(layer "In4.Cu")
		(net "P5E_CPU1_PE4_RX_DP<6>")
	)
	(segment
		(start 68.459858 -396.745968)
		(end 65.087754 -349.00108)
		(width 0.14732)
		(layer "In4.Cu")
		(net "P5E_CPU1_PE4_RX_DP<6>")
	)
	(segment
		(start 93.436186 -300.646084)
		(end 94.106238 -296.849292)
		(width 0.14732)
		(layer "In4.Cu")
		(net "P5E_CPU1_PE4_RX_DP<6>")
	)
	(segment
		(start 67.928236 -412.860744)
		(end 67.738752 -412.803594)
		(width 0.14732)
		(layer "In4.Cu")
		(net "P5E_CPU1_PE4_RX_DP<6>")
	)
	(segment
		(start 70.6501 -433.605178)
		(end 70.502526 -433.752752)
		(width 0.14732)
		(layer "In4.Cu")
		(net "P5E_CPU1_PE4_RX_DP<6>")
	)
	(segment
		(start 67.564762 -412.479236)
		(end 67.621658 -412.290006)
		(width 0.14732)
		(layer "In4.Cu")
		(net "P5E_CPU1_PE4_RX_DP<6>")
	)
	(segment
		(start 70.6501 -433.289964)
		(end 70.6501 -433.605178)
		(width 0.14732)
		(layer "In4.Cu")
		(net "P5E_CPU1_PE4_RX_DP<6>")
	)
	(segment
		(start 94.064328 -292.405054)
		(end 96.33839 -290.130992)
		(width 0.0889)
		(layer "In4.Cu")
		(net "P5E_CPU1_PE4_RX_DP<6>")
	)
	(segment
		(start 67.738752 -412.803594)
		(end 67.564762 -412.479236)
		(width 0.14732)
		(layer "In4.Cu")
		(net "P5E_CPU1_PE4_RX_DP<6>")
	)
	(segment
		(start 69.96684 -433.622196)
		(end 69.96684 -416.956748)
		(width 0.14732)
		(layer "In4.Cu")
		(net "P5E_CPU1_PE4_RX_DP<6>")
	)
	(segment
		(start 96.33839 -290.130992)
		(end 96.33839 -289.610292)
		(width 0.0889)
		(layer "In4.Cu")
		(net "P5E_CPU1_PE4_RX_DP<6>")
	)
	(segment
		(start 65.100708 -333.265272)
		(end 65.100454 -333.265272)
		(width 0.14732)
		(layer "In4.Cu")
		(net "P5E_CPU1_PE4_RX_DP<6>")
	)
	(segment
		(start 70.097396 -433.752752)
		(end 69.96684 -433.622196)
		(width 0.14732)
		(layer "In4.Cu")
		(net "P5E_CPU1_PE4_RX_DP<6>")
	)
	(segment
		(start 65.100454 -333.265272)
		(end 68.12915 -325.95312)
		(width 0.14732)
		(layer "In4.Cu")
		(net "P5E_CPU1_PE4_RX_DP<6>")
	)
	(segment
		(start 94.106492 -296.849038)
		(end 94.106492 -292.992048)
		(width 0.14732)
		(layer "In4.Cu")
		(net "P5E_CPU1_PE4_RX_DP<6>")
	)
	(segment
		(start 94.106492 -292.96995)
		(end 94.064328 -292.927786)
		(width 0.0889)
		(layer "In4.Cu")
		(net "P5E_CPU1_PE4_RX_DP<6>")
	)
	(segment
		(start 67.621658 -412.290006)
		(end 67.447668 -411.965394)
		(width 0.14732)
		(layer "In4.Cu")
		(net "P5E_CPU1_PE4_RX_DP<6>")
	)
	(segment
		(start 94.106238 -296.849292)
		(end 94.106492 -296.849038)
		(width 0.14732)
		(layer "In4.Cu")
		(net "P5E_CPU1_PE4_RX_DP<6>")
	)
	(segment
		(start 94.064328 -292.927786)
		(end 94.064328 -292.405054)
		(width 0.0889)
		(layer "In4.Cu")
		(net "P5E_CPU1_PE4_RX_DP<6>")
	)
	(segment
		(start 67.447668 -411.965394)
		(end 67.258184 -411.908244)
		(width 0.14732)
		(layer "In4.Cu")
		(net "P5E_CPU1_PE4_RX_DP<6>")
	)
	(segment
		(start 66.742818 -410.94787)
		(end 66.742818 -406.313132)
		(width 0.14732)
		(layer "In4.Cu")
		(net "P5E_CPU1_PE4_RX_DP<6>")
	)
	(segment
		(start 70.502526 -433.752752)
		(end 70.097396 -433.752752)
		(width 0.14732)
		(layer "In4.Cu")
		(net "P5E_CPU1_PE4_RX_DP<6>")
	)
	(segment
		(start 94.106492 -292.992048)
		(end 94.106492 -292.96995)
		(width 0.0889)
		(layer "In4.Cu")
		(net "P5E_CPU1_PE4_RX_DP<6>")
	)
	(segment
		(start 95.559372 -289.247834)
		(end 95.462598 -289.218116)
		(width 0.0889)
		(layer "In4.Cu")
		(net "P5E_CPU1_PE4_RX_DP<6>")
	)
	(segment
		(start 67.258184 -411.908244)
		(end 66.742818 -410.94787)
		(width 0.14732)
		(layer "In4.Cu")
		(net "P5E_CPU1_PE4_RX_DP<6>")
	)
	(segment
		(start 64.929258 -334.199738)
		(end 65.100708 -333.265272)
		(width 0.14732)
		(layer "In4.Cu")
		(net "P5E_CPU1_PE4_RX_DP<6>")
	)
	(segment
		(start 69.96684 -416.956748)
		(end 68.04533 -413.374586)
		(width 0.14732)
		(layer "In4.Cu")
		(net "P5E_CPU1_PE4_RX_DP<6>")
	)
	(segment
		(start 68.459858 -404.596092)
		(end 68.459858 -396.745968)
		(width 0.14732)
		(layer "In4.Cu")
		(net "P5E_CPU1_PE4_RX_DP<6>")
	)
	(segment
		(start 66.742818 -406.313132)
		(end 68.459858 -404.596092)
		(width 0.14732)
		(layer "In4.Cu")
		(net "P5E_CPU1_PE4_RX_DP<6>")
	)
	(segment
		(start 68.102226 -413.18561)
		(end 67.928236 -412.860744)
		(width 0.14732)
		(layer "In4.Cu")
		(net "P5E_CPU1_PE4_RX_DP<6>")
	)
	(arc
		(start 95.579438 -289.241484)
		(mid 95.579303 -289.241106)
		(end 95.579184 -289.240722)
		(width 0.0889)
		(layer "In4.Cu")
		(net "P5E_CPU1_PE4_RX_DP<6>")
	)
	(arc
		(start 96.33839 -289.610292)
		(mid 96.035042 -289.269136)
		(end 95.579438 -289.241484)
		(width 0.0889)
		(layer "In4.Cu")
		(net "P5E_CPU1_PE4_RX_DP<6>")
	)
	(arc
		(start 95.579184 -289.240722)
		(mid 95.569246 -289.24419)
		(end 95.559372 -289.247834)
		(width 0.0889)
		(layer "In4.Cu")
		(net "P5E_CPU1_PE4_RX_DP<6>")
	)
	(segment
		(start 94.364048 -288.381186)
		(end 94.364048 -288.917126)
		(width 0.13208)
		(layer "F.Cu")
		(net "P5E_CPU1_PE4_RX_DP<5>")
	)
	(segment
		(start 94.598744 -288.62528)
		(end 94.520512 -288.646108)
		(width 0.0889)
		(layer "In4.Cu")
		(net "P5E_CPU1_PE4_RX_DP<5>")
	)
	(segment
		(start 92.894658 -292.812724)
		(end 92.894658 -292.790626)
		(width 0.0889)
		(layer "In4.Cu")
		(net "P5E_CPU1_PE4_RX_DP<5>")
	)
	(segment
		(start 65.122298 -399.72488)
		(end 64.79667 -372.674388)
		(width 0.14732)
		(layer "In4.Cu")
		(net "P5E_CPU1_PE4_RX_DP<5>")
	)
	(segment
		(start 89.316052 -294.767508)
		(end 91.105482 -294.767508)
		(width 0.14732)
		(layer "In4.Cu")
		(net "P5E_CPU1_PE4_RX_DP<5>")
	)
	(segment
		(start 94.738698 -289.114738)
		(end 94.738698 -288.917126)
		(width 0.0889)
		(layer "In4.Cu")
		(net "P5E_CPU1_PE4_RX_DP<5>")
	)
	(segment
		(start 91.105482 -294.767508)
		(end 92.894658 -292.978332)
		(width 0.14732)
		(layer "In4.Cu")
		(net "P5E_CPU1_PE4_RX_DP<5>")
	)
	(segment
		(start 94.520512 -288.646108)
		(end 94.364048 -288.917126)
		(width 0.0889)
		(layer "In4.Cu")
		(net "P5E_CPU1_PE4_RX_DP<5>")
	)
	(segment
		(start 68.650104 -435.242208)
		(end 68.50253 -435.094634)
		(width 0.14732)
		(layer "In4.Cu")
		(net "P5E_CPU1_PE4_RX_DP<5>")
	)
	(segment
		(start 63.875412 -332.814168)
		(end 63.875412 -332.81366)
		(width 0.14732)
		(layer "In4.Cu")
		(net "P5E_CPU1_PE4_RX_DP<5>")
	)
	(segment
		(start 68.079112 -435.094634)
		(end 67.692524 -434.708046)
		(width 0.14732)
		(layer "In4.Cu")
		(net "P5E_CPU1_PE4_RX_DP<5>")
	)
	(segment
		(start 64.79667 -372.674388)
		(end 63.876174 -349.0468)
		(width 0.14732)
		(layer "In4.Cu")
		(net "P5E_CPU1_PE4_RX_DP<5>")
	)
	(segment
		(start 66.929508 -325.440548)
		(end 79.618078 -312.751978)
		(width 0.14732)
		(layer "In4.Cu")
		(net "P5E_CPU1_PE4_RX_DP<5>")
	)
	(segment
		(start 95.208344 -289.998658)
		(end 95.208344 -289.645852)
		(width 0.0889)
		(layer "In4.Cu")
		(net "P5E_CPU1_PE4_RX_DP<5>")
	)
	(segment
		(start 63.405258 -411.090872)
		(end 63.405258 -406.19934)
		(width 0.14732)
		(layer "In4.Cu")
		(net "P5E_CPU1_PE4_RX_DP<5>")
	)
	(segment
		(start 63.875412 -332.81366)
		(end 66.929508 -325.440548)
		(width 0.14732)
		(layer "In4.Cu")
		(net "P5E_CPU1_PE4_RX_DP<5>")
	)
	(segment
		(start 92.936568 -292.748716)
		(end 92.936568 -292.270434)
		(width 0.0889)
		(layer "In4.Cu")
		(net "P5E_CPU1_PE4_RX_DP<5>")
	)
	(segment
		(start 67.692524 -434.708046)
		(end 67.692524 -417.233862)
		(width 0.14732)
		(layer "In4.Cu")
		(net "P5E_CPU1_PE4_RX_DP<5>")
	)
	(segment
		(start 63.56858 -333.948786)
		(end 63.875412 -332.814168)
		(width 0.14732)
		(layer "In4.Cu")
		(net "P5E_CPU1_PE4_RX_DP<5>")
	)
	(segment
		(start 79.618078 -312.751978)
		(end 85.125814 -303.221136)
		(width 0.14732)
		(layer "In4.Cu")
		(net "P5E_CPU1_PE4_RX_DP<5>")
	)
	(segment
		(start 65.122298 -404.4823)
		(end 65.122298 -399.72488)
		(width 0.14732)
		(layer "In4.Cu")
		(net "P5E_CPU1_PE4_RX_DP<5>")
	)
	(segment
		(start 85.125814 -303.221136)
		(end 88.140286 -295.943274)
		(width 0.14732)
		(layer "In4.Cu")
		(net "P5E_CPU1_PE4_RX_DP<5>")
	)
	(segment
		(start 68.50253 -435.094634)
		(end 68.079112 -435.094634)
		(width 0.14732)
		(layer "In4.Cu")
		(net "P5E_CPU1_PE4_RX_DP<5>")
	)
	(segment
		(start 67.692524 -417.233862)
		(end 63.405258 -411.090872)
		(width 0.14732)
		(layer "In4.Cu")
		(net "P5E_CPU1_PE4_RX_DP<5>")
	)
	(segment
		(start 88.140286 -295.943274)
		(end 89.316052 -294.767508)
		(width 0.14732)
		(layer "In4.Cu")
		(net "P5E_CPU1_PE4_RX_DP<5>")
	)
	(segment
		(start 63.876174 -349.0468)
		(end 63.56858 -333.948786)
		(width 0.14732)
		(layer "In4.Cu")
		(net "P5E_CPU1_PE4_RX_DP<5>")
	)
	(segment
		(start 92.936568 -292.270434)
		(end 95.208344 -289.998658)
		(width 0.0889)
		(layer "In4.Cu")
		(net "P5E_CPU1_PE4_RX_DP<5>")
	)
	(segment
		(start 68.650104 -435.489858)
		(end 68.650104 -435.242208)
		(width 0.14732)
		(layer "In4.Cu")
		(net "P5E_CPU1_PE4_RX_DP<5>")
	)
	(segment
		(start 92.894658 -292.790626)
		(end 92.936568 -292.748716)
		(width 0.0889)
		(layer "In4.Cu")
		(net "P5E_CPU1_PE4_RX_DP<5>")
	)
	(segment
		(start 92.894658 -292.978332)
		(end 92.894658 -292.812724)
		(width 0.14732)
		(layer "In4.Cu")
		(net "P5E_CPU1_PE4_RX_DP<5>")
	)
	(segment
		(start 63.405258 -406.19934)
		(end 65.122298 -404.4823)
		(width 0.14732)
		(layer "In4.Cu")
		(net "P5E_CPU1_PE4_RX_DP<5>")
	)
	(arc
		(start 95.208344 -289.645852)
		(mid 95.133339 -289.530393)
		(end 95.024194 -289.446462)
		(width 0.0889)
		(layer "In4.Cu")
		(net "P5E_CPU1_PE4_RX_DP<5>")
	)
	(arc
		(start 95.024194 -289.446462)
		(mid 94.850062 -289.307615)
		(end 94.738698 -289.114738)
		(width 0.0889)
		(layer "In4.Cu")
		(net "P5E_CPU1_PE4_RX_DP<5>")
	)
	(arc
		(start 94.738698 -288.917126)
		(mid 94.701838 -288.755329)
		(end 94.598744 -288.62528)
		(width 0.0889)
		(layer "In4.Cu")
		(net "P5E_CPU1_PE4_RX_DP<5>")
	)
	(segment
		(start 93.424248 -288.381186)
		(end 93.424248 -288.917126)
		(width 0.13208)
		(layer "F.Cu")
		(net "P5E_CPU1_PE4_RX_DP<4>")
	)
	(segment
		(start 66.084196 -433.752752)
		(end 65.966848 -433.635404)
		(width 0.14732)
		(layer "In4.Cu")
		(net "P5E_CPU1_PE4_RX_DP<4>")
	)
	(segment
		(start 94.459044 -289.601402)
		(end 94.44101 -289.56508)
		(width 0.0889)
		(layer "In4.Cu")
		(net "P5E_CPU1_PE4_RX_DP<4>")
	)
	(segment
		(start 92.003372 -292.586664)
		(end 92.004388 -292.586664)
		(width 0.14732)
		(layer "In4.Cu")
		(net "P5E_CPU1_PE4_RX_DP<4>")
	)
	(segment
		(start 90.500708 -294.089328)
		(end 92.003372 -292.586664)
		(width 0.14732)
		(layer "In4.Cu")
		(net "P5E_CPU1_PE4_RX_DP<4>")
	)
	(segment
		(start 62.897004 -332.953614)
		(end 65.947036 -325.591424)
		(width 0.14732)
		(layer "In4.Cu")
		(net "P5E_CPU1_PE4_RX_DP<4>")
	)
	(segment
		(start 63.263272 -372.674388)
		(end 62.897004 -332.953614)
		(width 0.14732)
		(layer "In4.Cu")
		(net "P5E_CPU1_PE4_RX_DP<4>")
	)
	(segment
		(start 65.10274 -416.231324)
		(end 62.894718 -413.540956)
		(width 0.14732)
		(layer "In4.Cu")
		(net "P5E_CPU1_PE4_RX_DP<4>")
	)
	(segment
		(start 79.386684 -311.836308)
		(end 84.542122 -302.914558)
		(width 0.14732)
		(layer "In4.Cu")
		(net "P5E_CPU1_PE4_RX_DP<4>")
	)
	(segment
		(start 92.369132 -292.161976)
		(end 92.46489 -292.066218)
		(width 0.0889)
		(layer "In4.Cu")
		(net "P5E_CPU1_PE4_RX_DP<4>")
	)
	(segment
		(start 65.955164 -417.507166)
		(end 65.10274 -416.231324)
		(width 0.14732)
		(layer "In4.Cu")
		(net "P5E_CPU1_PE4_RX_DP<4>")
	)
	(segment
		(start 62.894718 -413.540956)
		(end 62.914022 -413.344106)
		(width 0.14732)
		(layer "In4.Cu")
		(net "P5E_CPU1_PE4_RX_DP<4>")
	)
	(segment
		(start 66.588894 -324.634352)
		(end 79.386684 -311.836308)
		(width 0.14732)
		(layer "In4.Cu")
		(net "P5E_CPU1_PE4_RX_DP<4>")
	)
	(segment
		(start 87.597488 -295.53916)
		(end 89.04732 -294.089328)
		(width 0.14732)
		(layer "In4.Cu")
		(net "P5E_CPU1_PE4_RX_DP<4>")
	)
	(segment
		(start 94.459044 -290.072318)
		(end 94.459044 -289.601402)
		(width 0.0889)
		(layer "In4.Cu")
		(net "P5E_CPU1_PE4_RX_DP<4>")
	)
	(segment
		(start 62.250066 -412.755334)
		(end 62.26937 -412.558738)
		(width 0.14732)
		(layer "In4.Cu")
		(net "P5E_CPU1_PE4_RX_DP<4>")
	)
	(segment
		(start 89.04732 -294.089328)
		(end 90.500708 -294.089328)
		(width 0.14732)
		(layer "In4.Cu")
		(net "P5E_CPU1_PE4_RX_DP<4>")
	)
	(segment
		(start 65.966848 -417.51885)
		(end 65.955164 -417.507166)
		(width 0.14732)
		(layer "In4.Cu")
		(net "P5E_CPU1_PE4_RX_DP<4>")
	)
	(segment
		(start 66.502534 -433.752752)
		(end 66.084196 -433.752752)
		(width 0.14732)
		(layer "In4.Cu")
		(net "P5E_CPU1_PE4_RX_DP<4>")
	)
	(segment
		(start 84.542122 -302.914558)
		(end 87.597488 -295.53916)
		(width 0.14732)
		(layer "In4.Cu")
		(net "P5E_CPU1_PE4_RX_DP<4>")
	)
	(segment
		(start 65.947036 -325.591424)
		(end 66.588894 -324.634352)
		(width 0.14732)
		(layer "In4.Cu")
		(net "P5E_CPU1_PE4_RX_DP<4>")
	)
	(segment
		(start 92.46489 -292.066218)
		(end 94.459044 -290.072318)
		(width 0.0889)
		(layer "In4.Cu")
		(net "P5E_CPU1_PE4_RX_DP<4>")
	)
	(segment
		(start 93.699838 -289.241484)
		(end 93.699584 -289.240722)
		(width 0.0889)
		(layer "In4.Cu")
		(net "P5E_CPU1_PE4_RX_DP<4>")
	)
	(segment
		(start 62.914022 -413.344106)
		(end 62.680088 -413.059372)
		(width 0.14732)
		(layer "In4.Cu")
		(net "P5E_CPU1_PE4_RX_DP<4>")
	)
	(segment
		(start 63.263272 -372.67769)
		(end 63.263272 -372.674388)
		(width 0.14732)
		(layer "In4.Cu")
		(net "P5E_CPU1_PE4_RX_DP<4>")
	)
	(segment
		(start 93.582998 -289.218116)
		(end 93.424248 -288.917126)
		(width 0.0889)
		(layer "In4.Cu")
		(net "P5E_CPU1_PE4_RX_DP<4>")
	)
	(segment
		(start 66.650108 -433.289964)
		(end 66.650108 -433.605178)
		(width 0.14732)
		(layer "In4.Cu")
		(net "P5E_CPU1_PE4_RX_DP<4>")
	)
	(segment
		(start 65.966848 -433.635404)
		(end 65.966848 -417.51885)
		(width 0.14732)
		(layer "In4.Cu")
		(net "P5E_CPU1_PE4_RX_DP<4>")
	)
	(segment
		(start 62.333378 -400.477228)
		(end 63.263272 -372.67769)
		(width 0.14732)
		(layer "In4.Cu")
		(net "P5E_CPU1_PE4_RX_DP<4>")
	)
	(segment
		(start 61.83884 -412.254446)
		(end 60.616338 -410.76499)
		(width 0.14732)
		(layer "In4.Cu")
		(net "P5E_CPU1_PE4_RX_DP<4>")
	)
	(segment
		(start 66.650108 -433.605178)
		(end 66.502534 -433.752752)
		(width 0.14732)
		(layer "In4.Cu")
		(net "P5E_CPU1_PE4_RX_DP<4>")
	)
	(segment
		(start 60.616338 -410.76499)
		(end 60.616338 -406.313132)
		(width 0.14732)
		(layer "In4.Cu")
		(net "P5E_CPU1_PE4_RX_DP<4>")
	)
	(segment
		(start 62.26937 -412.558738)
		(end 62.035436 -412.27375)
		(width 0.14732)
		(layer "In4.Cu")
		(net "P5E_CPU1_PE4_RX_DP<4>")
	)
	(segment
		(start 62.035436 -412.27375)
		(end 61.83884 -412.254446)
		(width 0.14732)
		(layer "In4.Cu")
		(net "P5E_CPU1_PE4_RX_DP<4>")
	)
	(segment
		(start 93.679772 -289.247834)
		(end 93.582998 -289.218116)
		(width 0.0889)
		(layer "In4.Cu")
		(net "P5E_CPU1_PE4_RX_DP<4>")
	)
	(segment
		(start 62.680088 -413.059372)
		(end 62.483492 -413.039814)
		(width 0.14732)
		(layer "In4.Cu")
		(net "P5E_CPU1_PE4_RX_DP<4>")
	)
	(segment
		(start 62.483492 -413.039814)
		(end 62.250066 -412.755334)
		(width 0.14732)
		(layer "In4.Cu")
		(net "P5E_CPU1_PE4_RX_DP<4>")
	)
	(segment
		(start 60.616338 -406.313132)
		(end 62.333378 -404.596092)
		(width 0.14732)
		(layer "In4.Cu")
		(net "P5E_CPU1_PE4_RX_DP<4>")
	)
	(segment
		(start 92.353638 -292.237414)
		(end 92.369132 -292.22192)
		(width 0.0889)
		(layer "In4.Cu")
		(net "P5E_CPU1_PE4_RX_DP<4>")
	)
	(segment
		(start 92.004388 -292.586664)
		(end 92.353638 -292.237414)
		(width 0.14732)
		(layer "In4.Cu")
		(net "P5E_CPU1_PE4_RX_DP<4>")
	)
	(segment
		(start 92.369132 -292.22192)
		(end 92.369132 -292.161976)
		(width 0.0889)
		(layer "In4.Cu")
		(net "P5E_CPU1_PE4_RX_DP<4>")
	)
	(segment
		(start 62.333378 -404.596092)
		(end 62.333378 -400.477228)
		(width 0.14732)
		(layer "In4.Cu")
		(net "P5E_CPU1_PE4_RX_DP<4>")
	)
	(arc
		(start 94.44101 -289.56508)
		(mid 94.133409 -289.259049)
		(end 93.699838 -289.241484)
		(width 0.0889)
		(layer "In4.Cu")
		(net "P5E_CPU1_PE4_RX_DP<4>")
	)
	(arc
		(start 93.699584 -289.240722)
		(mid 93.689646 -289.24419)
		(end 93.679772 -289.247834)
		(width 0.0889)
		(layer "In4.Cu")
		(net "P5E_CPU1_PE4_RX_DP<4>")
	)
	(segment
		(start 92.484448 -288.381186)
		(end 92.484448 -288.917126)
		(width 0.13208)
		(layer "F.Cu")
		(net "P5E_CPU1_PE4_RX_DP<3>")
	)
	(segment
		(start 83.90509 -301.296578)
		(end 86.634828 -294.707056)
		(width 0.14732)
		(layer "In4.Cu")
		(net "P5E_CPU1_PE4_RX_DP<3>")
	)
	(segment
		(start 61.280294 -325.990966)
		(end 65.077086 -324.417944)
		(width 0.14732)
		(layer "In4.Cu")
		(net "P5E_CPU1_PE4_RX_DP<3>")
	)
	(segment
		(start 91.010486 -291.744654)
		(end 91.06916 -291.744654)
		(width 0.0889)
		(layer "In4.Cu")
		(net "P5E_CPU1_PE4_RX_DP<3>")
	)
	(segment
		(start 78.294992 -311.004966)
		(end 83.90509 -301.296578)
		(width 0.14732)
		(layer "In4.Cu")
		(net "P5E_CPU1_PE4_RX_DP<3>")
	)
	(segment
		(start 93.328744 -290.062412)
		(end 93.328744 -289.644836)
		(width 0.0889)
		(layer "In4.Cu")
		(net "P5E_CPU1_PE4_RX_DP<3>")
	)
	(segment
		(start 89.925906 -292.829234)
		(end 90.994992 -291.760148)
		(width 0.14732)
		(layer "In4.Cu")
		(net "P5E_CPU1_PE4_RX_DP<3>")
	)
	(segment
		(start 66.468752 -322.831206)
		(end 78.294992 -311.004966)
		(width 0.14732)
		(layer "In4.Cu")
		(net "P5E_CPU1_PE4_RX_DP<3>")
	)
	(segment
		(start 66.075814 -323.419216)
		(end 66.468752 -322.831206)
		(width 0.14732)
		(layer "In4.Cu")
		(net "P5E_CPU1_PE4_RX_DP<3>")
	)
	(segment
		(start 92.719398 -288.624772)
		(end 92.719144 -288.62528)
		(width 0.0889)
		(layer "In4.Cu")
		(net "P5E_CPU1_PE4_RX_DP<3>")
	)
	(segment
		(start 88.51265 -292.829234)
		(end 89.925906 -292.829234)
		(width 0.14732)
		(layer "In4.Cu")
		(net "P5E_CPU1_PE4_RX_DP<3>")
	)
	(segment
		(start 92.859352 -289.113976)
		(end 92.859352 -288.90214)
		(width 0.0889)
		(layer "In4.Cu")
		(net "P5E_CPU1_PE4_RX_DP<3>")
	)
	(segment
		(start 64.502538 -435.053994)
		(end 64.027304 -435.053994)
		(width 0.14732)
		(layer "In4.Cu")
		(net "P5E_CPU1_PE4_RX_DP<3>")
	)
	(segment
		(start 65.077086 -324.417944)
		(end 66.075814 -323.419216)
		(width 0.14732)
		(layer "In4.Cu")
		(net "P5E_CPU1_PE4_RX_DP<3>")
	)
	(segment
		(start 57.278778 -411.012386)
		(end 57.278778 -406.19934)
		(width 0.14732)
		(layer "In4.Cu")
		(net "P5E_CPU1_PE4_RX_DP<3>")
	)
	(segment
		(start 60.071254 -329.022456)
		(end 60.071254 -327.200006)
		(width 0.14732)
		(layer "In4.Cu")
		(net "P5E_CPU1_PE4_RX_DP<3>")
	)
	(segment
		(start 91.488514 -291.3253)
		(end 93.328744 -290.062412)
		(width 0.0889)
		(layer "In4.Cu")
		(net "P5E_CPU1_PE4_RX_DP<3>")
	)
	(segment
		(start 64.650112 -435.201568)
		(end 64.502538 -435.053994)
		(width 0.14732)
		(layer "In4.Cu")
		(net "P5E_CPU1_PE4_RX_DP<3>")
	)
	(segment
		(start 64.027304 -435.053994)
		(end 63.692532 -434.719222)
		(width 0.14732)
		(layer "In4.Cu")
		(net "P5E_CPU1_PE4_RX_DP<3>")
	)
	(segment
		(start 92.719144 -288.62528)
		(end 92.640912 -288.646108)
		(width 0.0889)
		(layer "In4.Cu")
		(net "P5E_CPU1_PE4_RX_DP<3>")
	)
	(segment
		(start 61.947298 -367.118138)
		(end 60.071254 -329.022456)
		(width 0.14732)
		(layer "In4.Cu")
		(net "P5E_CPU1_PE4_RX_DP<3>")
	)
	(segment
		(start 86.634828 -294.707056)
		(end 88.51265 -292.829234)
		(width 0.14732)
		(layer "In4.Cu")
		(net "P5E_CPU1_PE4_RX_DP<3>")
	)
	(segment
		(start 58.995818 -399.931128)
		(end 61.947298 -367.118138)
		(width 0.14732)
		(layer "In4.Cu")
		(net "P5E_CPU1_PE4_RX_DP<3>")
	)
	(segment
		(start 63.692532 -434.719222)
		(end 63.692532 -417.42614)
		(width 0.14732)
		(layer "In4.Cu")
		(net "P5E_CPU1_PE4_RX_DP<3>")
	)
	(segment
		(start 58.995818 -404.4823)
		(end 58.995818 -399.931128)
		(width 0.14732)
		(layer "In4.Cu")
		(net "P5E_CPU1_PE4_RX_DP<3>")
	)
	(segment
		(start 92.640912 -288.646108)
		(end 92.484448 -288.917126)
		(width 0.0889)
		(layer "In4.Cu")
		(net "P5E_CPU1_PE4_RX_DP<3>")
	)
	(segment
		(start 64.650112 -435.489858)
		(end 64.650112 -435.201568)
		(width 0.14732)
		(layer "In4.Cu")
		(net "P5E_CPU1_PE4_RX_DP<3>")
	)
	(segment
		(start 60.071254 -327.200006)
		(end 61.280294 -325.990966)
		(width 0.14732)
		(layer "In4.Cu")
		(net "P5E_CPU1_PE4_RX_DP<3>")
	)
	(segment
		(start 63.692532 -417.42614)
		(end 57.278778 -411.012386)
		(width 0.14732)
		(layer "In4.Cu")
		(net "P5E_CPU1_PE4_RX_DP<3>")
	)
	(segment
		(start 57.278778 -406.19934)
		(end 58.995818 -404.4823)
		(width 0.14732)
		(layer "In4.Cu")
		(net "P5E_CPU1_PE4_RX_DP<3>")
	)
	(segment
		(start 91.06916 -291.744654)
		(end 91.488514 -291.3253)
		(width 0.0889)
		(layer "In4.Cu")
		(net "P5E_CPU1_PE4_RX_DP<3>")
	)
	(segment
		(start 90.994992 -291.760148)
		(end 91.010486 -291.744654)
		(width 0.0889)
		(layer "In4.Cu")
		(net "P5E_CPU1_PE4_RX_DP<3>")
	)
	(arc
		(start 93.328744 -289.644836)
		(mid 93.253754 -289.529816)
		(end 93.144848 -289.446208)
		(width 0.0889)
		(layer "In4.Cu")
		(net "P5E_CPU1_PE4_RX_DP<3>")
	)
	(arc
		(start 92.859352 -288.90214)
		(mid 92.819474 -288.748263)
		(end 92.719398 -288.624772)
		(width 0.0889)
		(layer "In4.Cu")
		(net "P5E_CPU1_PE4_RX_DP<3>")
	)
	(arc
		(start 93.144848 -289.446208)
		(mid 92.970603 -289.307162)
		(end 92.859352 -289.113976)
		(width 0.0889)
		(layer "In4.Cu")
		(net "P5E_CPU1_PE4_RX_DP<3>")
	)
	(segment
		(start 91.544648 -288.381186)
		(end 91.544648 -288.917126)
		(width 0.13208)
		(layer "F.Cu")
		(net "P5E_CPU1_PE4_RX_DP<2>")
	)
	(segment
		(start 57.142888 -413.05226)
		(end 54.940454 -411.244542)
		(width 0.14732)
		(layer "In4.Cu")
		(net "P5E_CPU1_PE4_RX_DP<2>")
	)
	(segment
		(start 61.731144 -325.07428)
		(end 66.353944 -321.980052)
		(width 0.14732)
		(layer "In4.Cu")
		(net "P5E_CPU1_PE4_RX_DP<2>")
	)
	(segment
		(start 83.343242 -300.928024)
		(end 83.344766 -300.92523)
		(width 0.14732)
		(layer "In4.Cu")
		(net "P5E_CPU1_PE4_RX_DP<2>")
	)
	(segment
		(start 58.40984 -413.911542)
		(end 58.124852 -413.677608)
		(width 0.14732)
		(layer "In4.Cu")
		(net "P5E_CPU1_PE4_RX_DP<2>")
	)
	(segment
		(start 56.206898 -404.596092)
		(end 56.206898 -400.029426)
		(width 0.14732)
		(layer "In4.Cu")
		(net "P5E_CPU1_PE4_RX_DP<2>")
	)
	(segment
		(start 54.489858 -410.794708)
		(end 54.489858 -406.313132)
		(width 0.14732)
		(layer "In4.Cu")
		(net "P5E_CPU1_PE4_RX_DP<2>")
	)
	(segment
		(start 57.643776 -413.463486)
		(end 57.624472 -413.26689)
		(width 0.14732)
		(layer "In4.Cu")
		(net "P5E_CPU1_PE4_RX_DP<2>")
	)
	(segment
		(start 60.835286 -325.444866)
		(end 61.731144 -325.07428)
		(width 0.14732)
		(layer "In4.Cu")
		(net "P5E_CPU1_PE4_RX_DP<2>")
	)
	(segment
		(start 91.703398 -289.218116)
		(end 91.544648 -288.917126)
		(width 0.0889)
		(layer "In4.Cu")
		(net "P5E_CPU1_PE4_RX_DP<2>")
	)
	(segment
		(start 88.255856 -292.072314)
		(end 89.722198 -292.072314)
		(width 0.14732)
		(layer "In4.Cu")
		(net "P5E_CPU1_PE4_RX_DP<2>")
	)
	(segment
		(start 62.650116 -433.605178)
		(end 62.502542 -433.752752)
		(width 0.14732)
		(layer "In4.Cu")
		(net "P5E_CPU1_PE4_RX_DP<2>")
	)
	(segment
		(start 91.22537 -290.509198)
		(end 92.142564 -290.509198)
		(width 0.0889)
		(layer "In4.Cu")
		(net "P5E_CPU1_PE4_RX_DP<2>")
	)
	(segment
		(start 89.722198 -292.072314)
		(end 90.88755 -290.906962)
		(width 0.14732)
		(layer "In4.Cu")
		(net "P5E_CPU1_PE4_RX_DP<2>")
	)
	(segment
		(start 83.344766 -300.92523)
		(end 86.131908 -294.196262)
		(width 0.14732)
		(layer "In4.Cu")
		(net "P5E_CPU1_PE4_RX_DP<2>")
	)
	(segment
		(start 59.393328 -326.886824)
		(end 60.835286 -325.444866)
		(width 0.14732)
		(layer "In4.Cu")
		(net "P5E_CPU1_PE4_RX_DP<2>")
	)
	(segment
		(start 54.489858 -406.313132)
		(end 56.206898 -404.596092)
		(width 0.14732)
		(layer "In4.Cu")
		(net "P5E_CPU1_PE4_RX_DP<2>")
	)
	(segment
		(start 61.966856 -433.605432)
		(end 61.966856 -417.34486)
		(width 0.14732)
		(layer "In4.Cu")
		(net "P5E_CPU1_PE4_RX_DP<2>")
	)
	(segment
		(start 56.206898 -400.029426)
		(end 61.265308 -366.647222)
		(width 0.14732)
		(layer "In4.Cu")
		(net "P5E_CPU1_PE4_RX_DP<2>")
	)
	(segment
		(start 92.579444 -290.072318)
		(end 92.579444 -289.60953)
		(width 0.0889)
		(layer "In4.Cu")
		(net "P5E_CPU1_PE4_RX_DP<2>")
	)
	(segment
		(start 61.966856 -417.34486)
		(end 60.107068 -415.485072)
		(width 0.14732)
		(layer "In4.Cu")
		(net "P5E_CPU1_PE4_RX_DP<2>")
	)
	(segment
		(start 62.650116 -433.289964)
		(end 62.650116 -433.605178)
		(width 0.14732)
		(layer "In4.Cu")
		(net "P5E_CPU1_PE4_RX_DP<2>")
	)
	(segment
		(start 58.429398 -414.108138)
		(end 58.40984 -413.911542)
		(width 0.14732)
		(layer "In4.Cu")
		(net "P5E_CPU1_PE4_RX_DP<2>")
	)
	(segment
		(start 62.502542 -433.752752)
		(end 62.114176 -433.752752)
		(width 0.14732)
		(layer "In4.Cu")
		(net "P5E_CPU1_PE4_RX_DP<2>")
	)
	(segment
		(start 59.393328 -329.439524)
		(end 59.393328 -326.886824)
		(width 0.14732)
		(layer "In4.Cu")
		(net "P5E_CPU1_PE4_RX_DP<2>")
	)
	(segment
		(start 62.114176 -433.752752)
		(end 61.966856 -433.605432)
		(width 0.14732)
		(layer "In4.Cu")
		(net "P5E_CPU1_PE4_RX_DP<2>")
	)
	(segment
		(start 54.940454 -411.244542)
		(end 54.489858 -410.794708)
		(width 0.14732)
		(layer "In4.Cu")
		(net "P5E_CPU1_PE4_RX_DP<2>")
	)
	(segment
		(start 58.124852 -413.677608)
		(end 57.928256 -413.696912)
		(width 0.14732)
		(layer "In4.Cu")
		(net "P5E_CPU1_PE4_RX_DP<2>")
	)
	(segment
		(start 90.88755 -290.906962)
		(end 90.903044 -290.891468)
		(width 0.0889)
		(layer "In4.Cu")
		(net "P5E_CPU1_PE4_RX_DP<2>")
	)
	(segment
		(start 90.903044 -290.831524)
		(end 91.22537 -290.509198)
		(width 0.0889)
		(layer "In4.Cu")
		(net "P5E_CPU1_PE4_RX_DP<2>")
	)
	(segment
		(start 57.624472 -413.26689)
		(end 57.339484 -413.032956)
		(width 0.14732)
		(layer "In4.Cu")
		(net "P5E_CPU1_PE4_RX_DP<2>")
	)
	(segment
		(start 77.781912 -310.552084)
		(end 83.343242 -300.928024)
		(width 0.14732)
		(layer "In4.Cu")
		(net "P5E_CPU1_PE4_RX_DP<2>")
	)
	(segment
		(start 90.903044 -290.891468)
		(end 90.903044 -290.831524)
		(width 0.0889)
		(layer "In4.Cu")
		(net "P5E_CPU1_PE4_RX_DP<2>")
	)
	(segment
		(start 60.107068 -415.485072)
		(end 58.429398 -414.108138)
		(width 0.14732)
		(layer "In4.Cu")
		(net "P5E_CPU1_PE4_RX_DP<2>")
	)
	(segment
		(start 57.928256 -413.696912)
		(end 57.643776 -413.463486)
		(width 0.14732)
		(layer "In4.Cu")
		(net "P5E_CPU1_PE4_RX_DP<2>")
	)
	(segment
		(start 91.800172 -289.247834)
		(end 91.703398 -289.218116)
		(width 0.0889)
		(layer "In4.Cu")
		(net "P5E_CPU1_PE4_RX_DP<2>")
	)
	(segment
		(start 92.142564 -290.509198)
		(end 92.579444 -290.072318)
		(width 0.0889)
		(layer "In4.Cu")
		(net "P5E_CPU1_PE4_RX_DP<2>")
	)
	(segment
		(start 61.265308 -366.647222)
		(end 59.393328 -329.439524)
		(width 0.14732)
		(layer "In4.Cu")
		(net "P5E_CPU1_PE4_RX_DP<2>")
	)
	(segment
		(start 86.131908 -294.196262)
		(end 88.255856 -292.072314)
		(width 0.14732)
		(layer "In4.Cu")
		(net "P5E_CPU1_PE4_RX_DP<2>")
	)
	(segment
		(start 66.353944 -321.980052)
		(end 77.781912 -310.552084)
		(width 0.14732)
		(layer "In4.Cu")
		(net "P5E_CPU1_PE4_RX_DP<2>")
	)
	(segment
		(start 57.339484 -413.032956)
		(end 57.142888 -413.05226)
		(width 0.14732)
		(layer "In4.Cu")
		(net "P5E_CPU1_PE4_RX_DP<2>")
	)
	(arc
		(start 92.579444 -289.60953)
		(mid 92.27577 -289.268413)
		(end 91.819984 -289.240722)
		(width 0.0889)
		(layer "In4.Cu")
		(net "P5E_CPU1_PE4_RX_DP<2>")
	)
	(arc
		(start 91.819984 -289.240722)
		(mid 91.810046 -289.24419)
		(end 91.800172 -289.247834)
		(width 0.0889)
		(layer "In4.Cu")
		(net "P5E_CPU1_PE4_RX_DP<2>")
	)
	(segment
		(start 90.604848 -288.381186)
		(end 90.604848 -288.917126)
		(width 0.13208)
		(layer "F.Cu")
		(net "P5E_CPU1_PE4_RX_DP<1>")
	)
	(segment
		(start 89.226898 -290.786058)
		(end 89.827608 -290.185348)
		(width 0.14732)
		(layer "In4.Cu")
		(net "P5E_CPU1_PE4_RX_DP<1>")
	)
	(segment
		(start 51.152298 -410.58338)
		(end 51.152298 -406.19934)
		(width 0.14732)
		(layer "In4.Cu")
		(net "P5E_CPU1_PE4_RX_DP<1>")
	)
	(segment
		(start 83.710272 -296.890694)
		(end 83.710018 -296.890694)
		(width 0.14732)
		(layer "In4.Cu")
		(net "P5E_CPU1_PE4_RX_DP<1>")
	)
	(segment
		(start 60.65012 -435.489858)
		(end 60.65012 -435.224174)
		(width 0.14732)
		(layer "In4.Cu")
		(net "P5E_CPU1_PE4_RX_DP<1>")
	)
	(segment
		(start 85.117432 -293.49319)
		(end 87.824564 -290.786058)
		(width 0.14732)
		(layer "In4.Cu")
		(net "P5E_CPU1_PE4_RX_DP<1>")
	)
	(segment
		(start 58.17108 -326.356726)
		(end 60.12561 -324.402196)
		(width 0.14732)
		(layer "In4.Cu")
		(net "P5E_CPU1_PE4_RX_DP<1>")
	)
	(segment
		(start 58.17108 -329.757278)
		(end 58.17108 -326.356726)
		(width 0.14732)
		(layer "In4.Cu")
		(net "P5E_CPU1_PE4_RX_DP<1>")
	)
	(segment
		(start 90.014298 -289.999674)
		(end 90.073226 -289.999674)
		(width 0.0889)
		(layer "In4.Cu")
		(net "P5E_CPU1_PE4_RX_DP<1>")
	)
	(segment
		(start 51.285394 -411.03423)
		(end 51.152298 -410.58338)
		(width 0.14732)
		(layer "In4.Cu")
		(net "P5E_CPU1_PE4_RX_DP<1>")
	)
	(segment
		(start 60.049918 -435.0766)
		(end 59.69254 -434.719222)
		(width 0.14732)
		(layer "In4.Cu")
		(net "P5E_CPU1_PE4_RX_DP<1>")
	)
	(segment
		(start 60.502546 -435.0766)
		(end 60.049918 -435.0766)
		(width 0.14732)
		(layer "In4.Cu")
		(net "P5E_CPU1_PE4_RX_DP<1>")
	)
	(segment
		(start 83.710018 -296.890694)
		(end 83.710272 -296.89044)
		(width 0.14732)
		(layer "In4.Cu")
		(net "P5E_CPU1_PE4_RX_DP<1>")
	)
	(segment
		(start 59.69254 -434.719222)
		(end 59.69254 -417.458652)
		(width 0.14732)
		(layer "In4.Cu")
		(net "P5E_CPU1_PE4_RX_DP<1>")
	)
	(segment
		(start 90.839544 -288.624772)
		(end 90.839544 -288.62528)
		(width 0.0889)
		(layer "In4.Cu")
		(net "P5E_CPU1_PE4_RX_DP<1>")
	)
	(segment
		(start 58.780172 -416.546538)
		(end 55.056024 -413.489902)
		(width 0.14732)
		(layer "In4.Cu")
		(net "P5E_CPU1_PE4_RX_DP<1>")
	)
	(segment
		(start 55.056278 -413.489902)
		(end 53.297582 -412.046674)
		(width 0.14732)
		(layer "In4.Cu")
		(net "P5E_CPU1_PE4_RX_DP<1>")
	)
	(segment
		(start 51.152298 -406.19934)
		(end 52.869338 -404.4823)
		(width 0.14732)
		(layer "In4.Cu")
		(net "P5E_CPU1_PE4_RX_DP<1>")
	)
	(segment
		(start 60.65012 -435.224174)
		(end 60.502546 -435.0766)
		(width 0.14732)
		(layer "In4.Cu")
		(net "P5E_CPU1_PE4_RX_DP<1>")
	)
	(segment
		(start 90.793062 -289.279838)
		(end 90.813636 -289.2679)
		(width 0.0889)
		(layer "In4.Cu")
		(net "P5E_CPU1_PE4_RX_DP<1>")
	)
	(segment
		(start 87.824564 -290.786058)
		(end 89.226898 -290.786058)
		(width 0.14732)
		(layer "In4.Cu")
		(net "P5E_CPU1_PE4_RX_DP<1>")
	)
	(segment
		(start 90.979752 -289.078924)
		(end 90.979752 -288.905696)
		(width 0.0889)
		(layer "In4.Cu")
		(net "P5E_CPU1_PE4_RX_DP<1>")
	)
	(segment
		(start 52.869338 -399.995644)
		(end 60.044076 -366.50549)
		(width 0.14732)
		(layer "In4.Cu")
		(net "P5E_CPU1_PE4_RX_DP<1>")
	)
	(segment
		(start 51.542696 -411.31998)
		(end 51.285394 -411.03423)
		(width 0.14732)
		(layer "In4.Cu")
		(net "P5E_CPU1_PE4_RX_DP<1>")
	)
	(segment
		(start 59.69254 -417.458652)
		(end 58.77941 -416.545776)
		(width 0.14732)
		(layer "In4.Cu")
		(net "P5E_CPU1_PE4_RX_DP<1>")
	)
	(segment
		(start 90.839544 -288.62528)
		(end 90.761312 -288.646108)
		(width 0.0889)
		(layer "In4.Cu")
		(net "P5E_CPU1_PE4_RX_DP<1>")
	)
	(segment
		(start 53.297582 -412.046674)
		(end 51.542696 -411.31998)
		(width 0.14732)
		(layer "In4.Cu")
		(net "P5E_CPU1_PE4_RX_DP<1>")
	)
	(segment
		(start 58.77941 -416.545776)
		(end 58.780172 -416.546538)
		(width 0.14732)
		(layer "In4.Cu")
		(net "P5E_CPU1_PE4_RX_DP<1>")
	)
	(segment
		(start 76.76007 -309.861204)
		(end 82.330544 -300.22165)
		(width 0.14732)
		(layer "In4.Cu")
		(net "P5E_CPU1_PE4_RX_DP<1>")
	)
	(segment
		(start 89.998804 -290.015168)
		(end 90.014298 -289.999674)
		(width 0.0889)
		(layer "In4.Cu")
		(net "P5E_CPU1_PE4_RX_DP<1>")
	)
	(segment
		(start 89.828624 -290.185348)
		(end 89.998804 -290.015168)
		(width 0.14732)
		(layer "In4.Cu")
		(net "P5E_CPU1_PE4_RX_DP<1>")
	)
	(segment
		(start 61.204602 -323.955156)
		(end 65.611502 -321.009518)
		(width 0.14732)
		(layer "In4.Cu")
		(net "P5E_CPU1_PE4_RX_DP<1>")
	)
	(segment
		(start 90.761312 -288.646108)
		(end 90.604848 -288.917126)
		(width 0.0889)
		(layer "In4.Cu")
		(net "P5E_CPU1_PE4_RX_DP<1>")
	)
	(segment
		(start 65.611502 -321.009518)
		(end 76.76007 -309.861204)
		(width 0.14732)
		(layer "In4.Cu")
		(net "P5E_CPU1_PE4_RX_DP<1>")
	)
	(segment
		(start 55.056024 -413.489902)
		(end 55.056278 -413.489902)
		(width 0.14732)
		(layer "In4.Cu")
		(net "P5E_CPU1_PE4_RX_DP<1>")
	)
	(segment
		(start 82.330544 -300.22165)
		(end 83.710272 -296.890694)
		(width 0.14732)
		(layer "In4.Cu")
		(net "P5E_CPU1_PE4_RX_DP<1>")
	)
	(segment
		(start 52.869338 -404.4823)
		(end 52.869338 -399.995644)
		(width 0.14732)
		(layer "In4.Cu")
		(net "P5E_CPU1_PE4_RX_DP<1>")
	)
	(segment
		(start 90.073226 -289.999674)
		(end 90.793062 -289.279838)
		(width 0.0889)
		(layer "In4.Cu")
		(net "P5E_CPU1_PE4_RX_DP<1>")
	)
	(segment
		(start 89.827608 -290.185348)
		(end 89.828624 -290.185348)
		(width 0.14732)
		(layer "In4.Cu")
		(net "P5E_CPU1_PE4_RX_DP<1>")
	)
	(segment
		(start 60.12561 -324.402196)
		(end 61.204602 -323.955156)
		(width 0.14732)
		(layer "In4.Cu")
		(net "P5E_CPU1_PE4_RX_DP<1>")
	)
	(segment
		(start 60.044076 -366.50549)
		(end 58.17108 -329.757278)
		(width 0.14732)
		(layer "In4.Cu")
		(net "P5E_CPU1_PE4_RX_DP<1>")
	)
	(segment
		(start 83.710272 -296.89044)
		(end 85.117432 -293.49319)
		(width 0.14732)
		(layer "In4.Cu")
		(net "P5E_CPU1_PE4_RX_DP<1>")
	)
	(arc
		(start 90.813636 -289.2679)
		(mid 90.911608 -289.186522)
		(end 90.979752 -289.078924)
		(width 0.0889)
		(layer "In4.Cu")
		(net "P5E_CPU1_PE4_RX_DP<1>")
	)
	(arc
		(start 90.979752 -288.905696)
		(mid 90.940429 -288.749885)
		(end 90.839544 -288.624772)
		(width 0.0889)
		(layer "In4.Cu")
		(net "P5E_CPU1_PE4_RX_DP<1>")
	)
	(segment
		(start 103.762048 -288.381186)
		(end 103.762048 -288.917126)
		(width 0.13208)
		(layer "F.Cu")
		(net "P5E_CPU1_PE4_RX_DP<15>")
	)
	(segment
		(start 94.037658 -406.19934)
		(end 95.754698 -404.4823)
		(width 0.14732)
		(layer "In4.Cu")
		(net "P5E_CPU1_PE4_RX_DP<15>")
	)
	(segment
		(start 88.692482 -424.588432)
		(end 94.037658 -411.414468)
		(width 0.14732)
		(layer "In4.Cu")
		(net "P5E_CPU1_PE4_RX_DP<15>")
	)
	(segment
		(start 104.606344 -291.060124)
		(end 104.606344 -289.645852)
		(width 0.0889)
		(layer "In4.Cu")
		(net "P5E_CPU1_PE4_RX_DP<15>")
	)
	(segment
		(start 103.918512 -288.646108)
		(end 103.762048 -288.917126)
		(width 0.0889)
		(layer "In4.Cu")
		(net "P5E_CPU1_PE4_RX_DP<15>")
	)
	(segment
		(start 88.692482 -434.719222)
		(end 88.692482 -424.588432)
		(width 0.14732)
		(layer "In4.Cu")
		(net "P5E_CPU1_PE4_RX_DP<15>")
	)
	(segment
		(start 73.481438 -336.203544)
		(end 73.479406 -336.172048)
		(width 0.14732)
		(layer "In4.Cu")
		(net "P5E_CPU1_PE4_RX_DP<15>")
	)
	(segment
		(start 102.906322 -293.394638)
		(end 102.906322 -292.760146)
		(width 0.0889)
		(layer "In4.Cu")
		(net "P5E_CPU1_PE4_RX_DP<15>")
	)
	(segment
		(start 102.864412 -293.436548)
		(end 102.906322 -293.394638)
		(width 0.0889)
		(layer "In4.Cu")
		(net "P5E_CPU1_PE4_RX_DP<15>")
	)
	(segment
		(start 103.996744 -288.62528)
		(end 103.918512 -288.646108)
		(width 0.0889)
		(layer "In4.Cu")
		(net "P5E_CPU1_PE4_RX_DP<15>")
	)
	(segment
		(start 73.591674 -335.487772)
		(end 76.035154 -329.58913)
		(width 0.14732)
		(layer "In4.Cu")
		(net "P5E_CPU1_PE4_RX_DP<15>")
	)
	(segment
		(start 102.864412 -297.622468)
		(end 102.864412 -293.458646)
		(width 0.14732)
		(layer "In4.Cu")
		(net "P5E_CPU1_PE4_RX_DP<15>")
	)
	(segment
		(start 102.864412 -293.458646)
		(end 102.864412 -293.436548)
		(width 0.0889)
		(layer "In4.Cu")
		(net "P5E_CPU1_PE4_RX_DP<15>")
	)
	(segment
		(start 89.650062 -435.489858)
		(end 89.650062 -435.174644)
		(width 0.14732)
		(layer "In4.Cu")
		(net "P5E_CPU1_PE4_RX_DP<15>")
	)
	(segment
		(start 89.502488 -435.02707)
		(end 89.00033 -435.02707)
		(width 0.14732)
		(layer "In4.Cu")
		(net "P5E_CPU1_PE4_RX_DP<15>")
	)
	(segment
		(start 101.764338 -303.859946)
		(end 102.864412 -297.622468)
		(width 0.14732)
		(layer "In4.Cu")
		(net "P5E_CPU1_PE4_RX_DP<15>")
	)
	(segment
		(start 94.037658 -411.414468)
		(end 94.037658 -406.19934)
		(width 0.14732)
		(layer "In4.Cu")
		(net "P5E_CPU1_PE4_RX_DP<15>")
	)
	(segment
		(start 73.479406 -336.172048)
		(end 73.591674 -335.487772)
		(width 0.14732)
		(layer "In4.Cu")
		(net "P5E_CPU1_PE4_RX_DP<15>")
	)
	(segment
		(start 89.00033 -435.02707)
		(end 88.692482 -434.719222)
		(width 0.14732)
		(layer "In4.Cu")
		(net "P5E_CPU1_PE4_RX_DP<15>")
	)
	(segment
		(start 89.650062 -435.174644)
		(end 89.502488 -435.02707)
		(width 0.14732)
		(layer "In4.Cu")
		(net "P5E_CPU1_PE4_RX_DP<15>")
	)
	(segment
		(start 104.136698 -289.114738)
		(end 104.136698 -288.917126)
		(width 0.0889)
		(layer "In4.Cu")
		(net "P5E_CPU1_PE4_RX_DP<15>")
	)
	(segment
		(start 74.546206 -352.032316)
		(end 73.481438 -336.203544)
		(width 0.14732)
		(layer "In4.Cu")
		(net "P5E_CPU1_PE4_RX_DP<15>")
	)
	(segment
		(start 76.035154 -329.58913)
		(end 101.764338 -303.859946)
		(width 0.14732)
		(layer "In4.Cu")
		(net "P5E_CPU1_PE4_RX_DP<15>")
	)
	(segment
		(start 95.754698 -404.4823)
		(end 95.754698 -399.744184)
		(width 0.14732)
		(layer "In4.Cu")
		(net "P5E_CPU1_PE4_RX_DP<15>")
	)
	(segment
		(start 102.906322 -292.760146)
		(end 104.606344 -291.060124)
		(width 0.0889)
		(layer "In4.Cu")
		(net "P5E_CPU1_PE4_RX_DP<15>")
	)
	(segment
		(start 82.304128 -371.968776)
		(end 74.546206 -352.032316)
		(width 0.14732)
		(layer "In4.Cu")
		(net "P5E_CPU1_PE4_RX_DP<15>")
	)
	(segment
		(start 95.754698 -399.744184)
		(end 82.304128 -371.968776)
		(width 0.14732)
		(layer "In4.Cu")
		(net "P5E_CPU1_PE4_RX_DP<15>")
	)
	(arc
		(start 104.422194 -289.446462)
		(mid 104.248062 -289.307615)
		(end 104.136698 -289.114738)
		(width 0.0889)
		(layer "In4.Cu")
		(net "P5E_CPU1_PE4_RX_DP<15>")
	)
	(arc
		(start 104.136698 -288.917126)
		(mid 104.099838 -288.755329)
		(end 103.996744 -288.62528)
		(width 0.0889)
		(layer "In4.Cu")
		(net "P5E_CPU1_PE4_RX_DP<15>")
	)
	(arc
		(start 104.606344 -289.645852)
		(mid 104.531339 -289.530393)
		(end 104.422194 -289.446462)
		(width 0.0889)
		(layer "In4.Cu")
		(net "P5E_CPU1_PE4_RX_DP<15>")
	)
	(segment
		(start 102.822248 -288.381186)
		(end 102.822248 -288.917126)
		(width 0.13208)
		(layer "F.Cu")
		(net "P5E_CPU1_PE4_RX_DP<14>")
	)
	(segment
		(start 91.248738 -411.379416)
		(end 87.708994 -421.730932)
		(width 0.14732)
		(layer "In4.Cu")
		(net "P5E_CPU1_PE4_RX_DP<14>")
	)
	(segment
		(start 92.965778 -399.706592)
		(end 92.965778 -404.596092)
		(width 0.14732)
		(layer "In4.Cu")
		(net "P5E_CPU1_PE4_RX_DP<14>")
	)
	(segment
		(start 75.299062 -329.398376)
		(end 72.901556 -335.186528)
		(width 0.14732)
		(layer "In4.Cu")
		(net "P5E_CPU1_PE4_RX_DP<14>")
	)
	(segment
		(start 91.248738 -406.313132)
		(end 91.248738 -411.379416)
		(width 0.14732)
		(layer "In4.Cu")
		(net "P5E_CPU1_PE4_RX_DP<14>")
	)
	(segment
		(start 87.380064 -422.692322)
		(end 87.466932 -422.869868)
		(width 0.14732)
		(layer "In4.Cu")
		(net "P5E_CPU1_PE4_RX_DP<14>")
	)
	(segment
		(start 73.748392 -352.03638)
		(end 80.728312 -371.859556)
		(width 0.14732)
		(layer "In4.Cu")
		(net "P5E_CPU1_PE4_RX_DP<14>")
	)
	(segment
		(start 87.347806 -423.21861)
		(end 87.17026 -423.305478)
		(width 0.14732)
		(layer "In4.Cu")
		(net "P5E_CPU1_PE4_RX_DP<14>")
	)
	(segment
		(start 87.115142 -433.752752)
		(end 87.502492 -433.752752)
		(width 0.14732)
		(layer "In4.Cu")
		(net "P5E_CPU1_PE4_RX_DP<14>")
	)
	(segment
		(start 80.728312 -371.859556)
		(end 92.965778 -399.706592)
		(width 0.14732)
		(layer "In4.Cu")
		(net "P5E_CPU1_PE4_RX_DP<14>")
	)
	(segment
		(start 86.966298 -433.603908)
		(end 87.115142 -433.752752)
		(width 0.14732)
		(layer "In4.Cu")
		(net "P5E_CPU1_PE4_RX_DP<14>")
	)
	(segment
		(start 87.676736 -422.256966)
		(end 87.49919 -422.344088)
		(width 0.14732)
		(layer "In4.Cu")
		(net "P5E_CPU1_PE4_RX_DP<14>")
	)
	(segment
		(start 86.966298 -423.902124)
		(end 86.966298 -433.603908)
		(width 0.14732)
		(layer "In4.Cu")
		(net "P5E_CPU1_PE4_RX_DP<14>")
	)
	(segment
		(start 87.49919 -422.344088)
		(end 87.380064 -422.692322)
		(width 0.14732)
		(layer "In4.Cu")
		(net "P5E_CPU1_PE4_RX_DP<14>")
	)
	(segment
		(start 102.980998 -289.218116)
		(end 103.077772 -289.247834)
		(width 0.0889)
		(layer "In4.Cu")
		(net "P5E_CPU1_PE4_RX_DP<14>")
	)
	(segment
		(start 73.747122 -352.029776)
		(end 73.748392 -352.03638)
		(width 0.14732)
		(layer "In4.Cu")
		(net "P5E_CPU1_PE4_RX_DP<14>")
	)
	(segment
		(start 101.12248 -303.574958)
		(end 75.299062 -329.398376)
		(width 0.14732)
		(layer "In4.Cu")
		(net "P5E_CPU1_PE4_RX_DP<14>")
	)
	(segment
		(start 72.901556 -335.186528)
		(end 72.76719 -335.98993)
		(width 0.14732)
		(layer "In4.Cu")
		(net "P5E_CPU1_PE4_RX_DP<14>")
	)
	(segment
		(start 87.466932 -422.869868)
		(end 87.347806 -423.21861)
		(width 0.14732)
		(layer "In4.Cu")
		(net "P5E_CPU1_PE4_RX_DP<14>")
	)
	(segment
		(start 103.85679 -290.852352)
		(end 102.166928 -292.542214)
		(width 0.0889)
		(layer "In4.Cu")
		(net "P5E_CPU1_PE4_RX_DP<14>")
	)
	(segment
		(start 102.166928 -292.542214)
		(end 102.166928 -293.394384)
		(width 0.0889)
		(layer "In4.Cu")
		(net "P5E_CPU1_PE4_RX_DP<14>")
	)
	(segment
		(start 87.502492 -433.752752)
		(end 87.650066 -433.605178)
		(width 0.14732)
		(layer "In4.Cu")
		(net "P5E_CPU1_PE4_RX_DP<14>")
	)
	(segment
		(start 102.822248 -288.917126)
		(end 102.980998 -289.218116)
		(width 0.0889)
		(layer "In4.Cu")
		(net "P5E_CPU1_PE4_RX_DP<14>")
	)
	(segment
		(start 87.708994 -421.730932)
		(end 87.795862 -421.908224)
		(width 0.14732)
		(layer "In4.Cu")
		(net "P5E_CPU1_PE4_RX_DP<14>")
	)
	(segment
		(start 72.76719 -335.98993)
		(end 73.747122 -352.029776)
		(width 0.14732)
		(layer "In4.Cu")
		(net "P5E_CPU1_PE4_RX_DP<14>")
	)
	(segment
		(start 103.85679 -289.610292)
		(end 103.85679 -290.852352)
		(width 0.0889)
		(layer "In4.Cu")
		(net "P5E_CPU1_PE4_RX_DP<14>")
	)
	(segment
		(start 102.209092 -293.436548)
		(end 102.209092 -293.458646)
		(width 0.0889)
		(layer "In4.Cu")
		(net "P5E_CPU1_PE4_RX_DP<14>")
	)
	(segment
		(start 92.965778 -404.596092)
		(end 91.248738 -406.313132)
		(width 0.14732)
		(layer "In4.Cu")
		(net "P5E_CPU1_PE4_RX_DP<14>")
	)
	(segment
		(start 102.166928 -293.394384)
		(end 102.209092 -293.436548)
		(width 0.0889)
		(layer "In4.Cu")
		(net "P5E_CPU1_PE4_RX_DP<14>")
	)
	(segment
		(start 102.209092 -297.413426)
		(end 101.12248 -303.574958)
		(width 0.14732)
		(layer "In4.Cu")
		(net "P5E_CPU1_PE4_RX_DP<14>")
	)
	(segment
		(start 87.17026 -423.305478)
		(end 86.966298 -423.902124)
		(width 0.14732)
		(layer "In4.Cu")
		(net "P5E_CPU1_PE4_RX_DP<14>")
	)
	(segment
		(start 102.209092 -293.458646)
		(end 102.209092 -297.413426)
		(width 0.14732)
		(layer "In4.Cu")
		(net "P5E_CPU1_PE4_RX_DP<14>")
	)
	(segment
		(start 87.795862 -421.908224)
		(end 87.676736 -422.256966)
		(width 0.14732)
		(layer "In4.Cu")
		(net "P5E_CPU1_PE4_RX_DP<14>")
	)
	(segment
		(start 87.650066 -433.605178)
		(end 87.650066 -433.289964)
		(width 0.14732)
		(layer "In4.Cu")
		(net "P5E_CPU1_PE4_RX_DP<14>")
	)
	(arc
		(start 103.077772 -289.247834)
		(mid 103.087647 -289.244192)
		(end 103.097584 -289.240722)
		(width 0.0889)
		(layer "In4.Cu")
		(net "P5E_CPU1_PE4_RX_DP<14>")
	)
	(arc
		(start 103.097584 -289.240722)
		(mid 103.097691 -289.24111)
		(end 103.097838 -289.241484)
		(width 0.0889)
		(layer "In4.Cu")
		(net "P5E_CPU1_PE4_RX_DP<14>")
	)
	(arc
		(start 103.097838 -289.241484)
		(mid 103.553358 -289.26931)
		(end 103.85679 -289.610292)
		(width 0.0889)
		(layer "In4.Cu")
		(net "P5E_CPU1_PE4_RX_DP<14>")
	)
	(segment
		(start 101.882448 -288.381186)
		(end 101.882448 -288.917126)
		(width 0.13208)
		(layer "F.Cu")
		(net "P5E_CPU1_PE4_RX_DP<13>")
	)
	(segment
		(start 71.4375 -335.785714)
		(end 71.647558 -334.896206)
		(width 0.14732)
		(layer "In4.Cu")
		(net "P5E_CPU1_PE4_RX_DP<13>")
	)
	(segment
		(start 100.404168 -292.92804)
		(end 100.404168 -292.704774)
		(width 0.0889)
		(layer "In4.Cu")
		(net "P5E_CPU1_PE4_RX_DP<13>")
	)
	(segment
		(start 102.117144 -288.62528)
		(end 102.038912 -288.646108)
		(width 0.0889)
		(layer "In4.Cu")
		(net "P5E_CPU1_PE4_RX_DP<13>")
	)
	(segment
		(start 100.362258 -297.397424)
		(end 100.362258 -292.992048)
		(width 0.14732)
		(layer "In4.Cu")
		(net "P5E_CPU1_PE4_RX_DP<13>")
	)
	(segment
		(start 102.257098 -289.114738)
		(end 102.257098 -288.917126)
		(width 0.0889)
		(layer "In4.Cu")
		(net "P5E_CPU1_PE4_RX_DP<13>")
	)
	(segment
		(start 84.691982 -434.64861)
		(end 84.691982 -423.922952)
		(width 0.14732)
		(layer "In4.Cu")
		(net "P5E_CPU1_PE4_RX_DP<13>")
	)
	(segment
		(start 89.628218 -399.699988)
		(end 78.718664 -371.950996)
		(width 0.14732)
		(layer "In4.Cu")
		(net "P5E_CPU1_PE4_RX_DP<13>")
	)
	(segment
		(start 99.25177 -303.69256)
		(end 100.362258 -297.397424)
		(width 0.14732)
		(layer "In4.Cu")
		(net "P5E_CPU1_PE4_RX_DP<13>")
	)
	(segment
		(start 74.192892 -328.751438)
		(end 99.25177 -303.69256)
		(width 0.14732)
		(layer "In4.Cu")
		(net "P5E_CPU1_PE4_RX_DP<13>")
	)
	(segment
		(start 85.070442 -435.02707)
		(end 84.691982 -434.64861)
		(width 0.14732)
		(layer "In4.Cu")
		(net "P5E_CPU1_PE4_RX_DP<13>")
	)
	(segment
		(start 102.726744 -290.382198)
		(end 102.726744 -289.645852)
		(width 0.0889)
		(layer "In4.Cu")
		(net "P5E_CPU1_PE4_RX_DP<13>")
	)
	(segment
		(start 100.404168 -292.704774)
		(end 102.726744 -290.382198)
		(width 0.0889)
		(layer "In4.Cu")
		(net "P5E_CPU1_PE4_RX_DP<13>")
	)
	(segment
		(start 85.65007 -435.174644)
		(end 85.502496 -435.02707)
		(width 0.14732)
		(layer "In4.Cu")
		(net "P5E_CPU1_PE4_RX_DP<13>")
	)
	(segment
		(start 102.038912 -288.646108)
		(end 101.882448 -288.917126)
		(width 0.0889)
		(layer "In4.Cu")
		(net "P5E_CPU1_PE4_RX_DP<13>")
	)
	(segment
		(start 84.691982 -423.922952)
		(end 87.911178 -411.476444)
		(width 0.14732)
		(layer "In4.Cu")
		(net "P5E_CPU1_PE4_RX_DP<13>")
	)
	(segment
		(start 71.647558 -334.896206)
		(end 74.192892 -328.751438)
		(width 0.14732)
		(layer "In4.Cu")
		(net "P5E_CPU1_PE4_RX_DP<13>")
	)
	(segment
		(start 78.718664 -371.950996)
		(end 72.39381 -352.063558)
		(width 0.14732)
		(layer "In4.Cu")
		(net "P5E_CPU1_PE4_RX_DP<13>")
	)
	(segment
		(start 100.362258 -292.96995)
		(end 100.404168 -292.92804)
		(width 0.0889)
		(layer "In4.Cu")
		(net "P5E_CPU1_PE4_RX_DP<13>")
	)
	(segment
		(start 72.39381 -352.063558)
		(end 72.381618 -351.996502)
		(width 0.14732)
		(layer "In4.Cu")
		(net "P5E_CPU1_PE4_RX_DP<13>")
	)
	(segment
		(start 87.911178 -406.19934)
		(end 89.628218 -404.4823)
		(width 0.14732)
		(layer "In4.Cu")
		(net "P5E_CPU1_PE4_RX_DP<13>")
	)
	(segment
		(start 100.362258 -292.992048)
		(end 100.362258 -292.96995)
		(width 0.0889)
		(layer "In4.Cu")
		(net "P5E_CPU1_PE4_RX_DP<13>")
	)
	(segment
		(start 87.911178 -411.476444)
		(end 87.911178 -406.19934)
		(width 0.14732)
		(layer "In4.Cu")
		(net "P5E_CPU1_PE4_RX_DP<13>")
	)
	(segment
		(start 85.502496 -435.02707)
		(end 85.070442 -435.02707)
		(width 0.14732)
		(layer "In4.Cu")
		(net "P5E_CPU1_PE4_RX_DP<13>")
	)
	(segment
		(start 89.628218 -404.4823)
		(end 89.628218 -399.699988)
		(width 0.14732)
		(layer "In4.Cu")
		(net "P5E_CPU1_PE4_RX_DP<13>")
	)
	(segment
		(start 85.65007 -435.489858)
		(end 85.65007 -435.174644)
		(width 0.14732)
		(layer "In4.Cu")
		(net "P5E_CPU1_PE4_RX_DP<13>")
	)
	(segment
		(start 72.381618 -351.996502)
		(end 71.4375 -335.785714)
		(width 0.14732)
		(layer "In4.Cu")
		(net "P5E_CPU1_PE4_RX_DP<13>")
	)
	(arc
		(start 102.542594 -289.446462)
		(mid 102.368462 -289.307615)
		(end 102.257098 -289.114738)
		(width 0.0889)
		(layer "In4.Cu")
		(net "P5E_CPU1_PE4_RX_DP<13>")
	)
	(arc
		(start 102.257098 -288.917126)
		(mid 102.220238 -288.755329)
		(end 102.117144 -288.62528)
		(width 0.0889)
		(layer "In4.Cu")
		(net "P5E_CPU1_PE4_RX_DP<13>")
	)
	(arc
		(start 102.726744 -289.645852)
		(mid 102.651739 -289.530393)
		(end 102.542594 -289.446462)
		(width 0.0889)
		(layer "In4.Cu")
		(net "P5E_CPU1_PE4_RX_DP<13>")
	)
	(segment
		(start 100.942648 -288.381186)
		(end 100.942648 -288.917126)
		(width 0.13208)
		(layer "F.Cu")
		(net "P5E_CPU1_PE4_RX_DP<12>")
	)
	(segment
		(start 98.637344 -303.372774)
		(end 73.64222 -328.367898)
		(width 0.14732)
		(layer "In4.Cu")
		(net "P5E_CPU1_PE4_RX_DP<12>")
	)
	(segment
		(start 83.152742 -433.752752)
		(end 83.5025 -433.752752)
		(width 0.14732)
		(layer "In4.Cu")
		(net "P5E_CPU1_PE4_RX_DP<12>")
	)
	(segment
		(start 83.37042 -421.88384)
		(end 83.484466 -422.04513)
		(width 0.14732)
		(layer "In4.Cu")
		(net "P5E_CPU1_PE4_RX_DP<12>")
	)
	(segment
		(start 84.89315 -412.980124)
		(end 84.99475 -413.123888)
		(width 0.14732)
		(layer "In4.Cu")
		(net "P5E_CPU1_PE4_RX_DP<12>")
	)
	(segment
		(start 83.5025 -433.752752)
		(end 83.650074 -433.605178)
		(width 0.14732)
		(layer "In4.Cu")
		(net "P5E_CPU1_PE4_RX_DP<12>")
	)
	(segment
		(start 84.92109 -413.554672)
		(end 84.777326 -413.656526)
		(width 0.14732)
		(layer "In4.Cu")
		(net "P5E_CPU1_PE4_RX_DP<12>")
	)
	(segment
		(start 83.25104 -423.409872)
		(end 83.089496 -423.524172)
		(width 0.14732)
		(layer "In4.Cu")
		(net "P5E_CPU1_PE4_RX_DP<12>")
	)
	(segment
		(start 71.397368 -351.397062)
		(end 77.19568 -371.859048)
		(width 0.14732)
		(layer "In4.Cu")
		(net "P5E_CPU1_PE4_RX_DP<12>")
	)
	(segment
		(start 70.859396 -335.086452)
		(end 70.775068 -335.669382)
		(width 0.14732)
		(layer "In4.Cu")
		(net "P5E_CPU1_PE4_RX_DP<12>")
	)
	(segment
		(start 99.701858 -292.992048)
		(end 99.701858 -297.339512)
		(width 0.14732)
		(layer "In4.Cu")
		(net "P5E_CPU1_PE4_RX_DP<12>")
	)
	(segment
		(start 99.701858 -297.339512)
		(end 98.637344 -303.372774)
		(width 0.14732)
		(layer "In4.Cu")
		(net "P5E_CPU1_PE4_RX_DP<12>")
	)
	(segment
		(start 83.089496 -423.524172)
		(end 82.966814 -424.242484)
		(width 0.14732)
		(layer "In4.Cu")
		(net "P5E_CPU1_PE4_RX_DP<12>")
	)
	(segment
		(start 82.966814 -433.566824)
		(end 83.152742 -433.752752)
		(width 0.14732)
		(layer "In4.Cu")
		(net "P5E_CPU1_PE4_RX_DP<12>")
	)
	(segment
		(start 84.777326 -413.656526)
		(end 83.37042 -421.88384)
		(width 0.14732)
		(layer "In4.Cu")
		(net "P5E_CPU1_PE4_RX_DP<12>")
	)
	(segment
		(start 86.839298 -404.596092)
		(end 85.122258 -406.313132)
		(width 0.14732)
		(layer "In4.Cu")
		(net "P5E_CPU1_PE4_RX_DP<12>")
	)
	(segment
		(start 70.775068 -335.669382)
		(end 71.397368 -351.397062)
		(width 0.14732)
		(layer "In4.Cu")
		(net "P5E_CPU1_PE4_RX_DP<12>")
	)
	(segment
		(start 85.122258 -406.313132)
		(end 85.122258 -411.639258)
		(width 0.14732)
		(layer "In4.Cu")
		(net "P5E_CPU1_PE4_RX_DP<12>")
	)
	(segment
		(start 83.260946 -422.522396)
		(end 83.19897 -422.885362)
		(width 0.14732)
		(layer "In4.Cu")
		(net "P5E_CPU1_PE4_RX_DP<12>")
	)
	(segment
		(start 101.101398 -289.218116)
		(end 101.198172 -289.247834)
		(width 0.0889)
		(layer "In4.Cu")
		(net "P5E_CPU1_PE4_RX_DP<12>")
	)
	(segment
		(start 73.64222 -328.367898)
		(end 70.859396 -335.086452)
		(width 0.14732)
		(layer "In4.Cu")
		(net "P5E_CPU1_PE4_RX_DP<12>")
	)
	(segment
		(start 83.42249 -422.40835)
		(end 83.260946 -422.522396)
		(width 0.14732)
		(layer "In4.Cu")
		(net "P5E_CPU1_PE4_RX_DP<12>")
	)
	(segment
		(start 85.122258 -411.639258)
		(end 84.89315 -412.980124)
		(width 0.14732)
		(layer "In4.Cu")
		(net "P5E_CPU1_PE4_RX_DP<12>")
	)
	(segment
		(start 99.659694 -292.927786)
		(end 99.701858 -292.96995)
		(width 0.0889)
		(layer "In4.Cu")
		(net "P5E_CPU1_PE4_RX_DP<12>")
	)
	(segment
		(start 99.659694 -292.765988)
		(end 99.659694 -292.927786)
		(width 0.0889)
		(layer "In4.Cu")
		(net "P5E_CPU1_PE4_RX_DP<12>")
	)
	(segment
		(start 99.701858 -292.96995)
		(end 99.701858 -292.992048)
		(width 0.0889)
		(layer "In4.Cu")
		(net "P5E_CPU1_PE4_RX_DP<12>")
	)
	(segment
		(start 101.977444 -289.60953)
		(end 101.977444 -290.448238)
		(width 0.0889)
		(layer "In4.Cu")
		(net "P5E_CPU1_PE4_RX_DP<12>")
	)
	(segment
		(start 84.99475 -413.123888)
		(end 84.92109 -413.554672)
		(width 0.14732)
		(layer "In4.Cu")
		(net "P5E_CPU1_PE4_RX_DP<12>")
	)
	(segment
		(start 83.650074 -433.605178)
		(end 83.650074 -433.289964)
		(width 0.14732)
		(layer "In4.Cu")
		(net "P5E_CPU1_PE4_RX_DP<12>")
	)
	(segment
		(start 82.966814 -424.242484)
		(end 82.966814 -433.566824)
		(width 0.14732)
		(layer "In4.Cu")
		(net "P5E_CPU1_PE4_RX_DP<12>")
	)
	(segment
		(start 100.942648 -288.917126)
		(end 101.101398 -289.218116)
		(width 0.0889)
		(layer "In4.Cu")
		(net "P5E_CPU1_PE4_RX_DP<12>")
	)
	(segment
		(start 83.31327 -423.046652)
		(end 83.25104 -423.409872)
		(width 0.14732)
		(layer "In4.Cu")
		(net "P5E_CPU1_PE4_RX_DP<12>")
	)
	(segment
		(start 83.484466 -422.04513)
		(end 83.42249 -422.40835)
		(width 0.14732)
		(layer "In4.Cu")
		(net "P5E_CPU1_PE4_RX_DP<12>")
	)
	(segment
		(start 83.19897 -422.885362)
		(end 83.31327 -423.046652)
		(width 0.14732)
		(layer "In4.Cu")
		(net "P5E_CPU1_PE4_RX_DP<12>")
	)
	(segment
		(start 101.977444 -290.448238)
		(end 99.659694 -292.765988)
		(width 0.0889)
		(layer "In4.Cu")
		(net "P5E_CPU1_PE4_RX_DP<12>")
	)
	(segment
		(start 86.839298 -399.574258)
		(end 86.839298 -404.596092)
		(width 0.14732)
		(layer "In4.Cu")
		(net "P5E_CPU1_PE4_RX_DP<12>")
	)
	(segment
		(start 77.19568 -371.859048)
		(end 86.839298 -399.574258)
		(width 0.14732)
		(layer "In4.Cu")
		(net "P5E_CPU1_PE4_RX_DP<12>")
	)
	(arc
		(start 101.217984 -289.240722)
		(mid 101.673826 -289.26845)
		(end 101.977444 -289.60953)
		(width 0.0889)
		(layer "In4.Cu")
		(net "P5E_CPU1_PE4_RX_DP<12>")
	)
	(arc
		(start 101.198172 -289.247834)
		(mid 101.208047 -289.244192)
		(end 101.217984 -289.240722)
		(width 0.0889)
		(layer "In4.Cu")
		(net "P5E_CPU1_PE4_RX_DP<12>")
	)
	(segment
		(start 100.002848 -288.381186)
		(end 100.002848 -288.917126)
		(width 0.13208)
		(layer "F.Cu")
		(net "P5E_CPU1_PE4_RX_DP<11>")
	)
	(segment
		(start 81.650078 -435.489858)
		(end 81.650078 -435.174644)
		(width 0.14732)
		(layer "In4.Cu")
		(net "P5E_CPU1_PE4_RX_DP<11>")
	)
	(segment
		(start 81.650078 -435.174644)
		(end 81.502504 -435.02707)
		(width 0.14732)
		(layer "In4.Cu")
		(net "P5E_CPU1_PE4_RX_DP<11>")
	)
	(segment
		(start 100.377498 -289.114738)
		(end 100.377498 -288.917126)
		(width 0.0889)
		(layer "In4.Cu")
		(net "P5E_CPU1_PE4_RX_DP<11>")
	)
	(segment
		(start 97.517712 -302.78197)
		(end 98.492818 -297.258232)
		(width 0.14732)
		(layer "In4.Cu")
		(net "P5E_CPU1_PE4_RX_DP<11>")
	)
	(segment
		(start 98.534728 -292.92804)
		(end 98.534728 -292.638734)
		(width 0.0889)
		(layer "In4.Cu")
		(net "P5E_CPU1_PE4_RX_DP<11>")
	)
	(segment
		(start 98.534728 -292.638734)
		(end 100.847144 -290.326318)
		(width 0.0889)
		(layer "In4.Cu")
		(net "P5E_CPU1_PE4_RX_DP<11>")
	)
	(segment
		(start 80.707484 -424.130978)
		(end 81.784698 -412.442914)
		(width 0.14732)
		(layer "In4.Cu")
		(net "P5E_CPU1_PE4_RX_DP<11>")
	)
	(segment
		(start 81.502504 -435.02707)
		(end 81.000346 -435.02707)
		(width 0.14732)
		(layer "In4.Cu")
		(net "P5E_CPU1_PE4_RX_DP<11>")
	)
	(segment
		(start 72.45858 -327.841102)
		(end 97.517712 -302.78197)
		(width 0.14732)
		(layer "In4.Cu")
		(net "P5E_CPU1_PE4_RX_DP<11>")
	)
	(segment
		(start 98.492818 -292.96995)
		(end 98.534728 -292.92804)
		(width 0.0889)
		(layer "In4.Cu")
		(net "P5E_CPU1_PE4_RX_DP<11>")
	)
	(segment
		(start 72.437752 -327.891648)
		(end 72.437498 -327.891648)
		(width 0.14732)
		(layer "In4.Cu")
		(net "P5E_CPU1_PE4_RX_DP<11>")
	)
	(segment
		(start 75.329796 -372.52148)
		(end 70.067932 -351.415096)
		(width 0.14732)
		(layer "In4.Cu")
		(net "P5E_CPU1_PE4_RX_DP<11>")
	)
	(segment
		(start 81.784698 -412.442914)
		(end 81.784698 -406.19934)
		(width 0.14732)
		(layer "In4.Cu")
		(net "P5E_CPU1_PE4_RX_DP<11>")
	)
	(segment
		(start 98.492818 -297.258232)
		(end 98.492818 -292.992048)
		(width 0.14732)
		(layer "In4.Cu")
		(net "P5E_CPU1_PE4_RX_DP<11>")
	)
	(segment
		(start 83.501738 -399.37182)
		(end 75.329796 -372.52148)
		(width 0.14732)
		(layer "In4.Cu")
		(net "P5E_CPU1_PE4_RX_DP<11>")
	)
	(segment
		(start 72.437498 -327.891648)
		(end 72.45858 -327.841102)
		(width 0.14732)
		(layer "In4.Cu")
		(net "P5E_CPU1_PE4_RX_DP<11>")
	)
	(segment
		(start 100.847144 -290.326318)
		(end 100.847144 -289.645852)
		(width 0.0889)
		(layer "In4.Cu")
		(net "P5E_CPU1_PE4_RX_DP<11>")
	)
	(segment
		(start 83.501738 -404.4823)
		(end 83.501738 -399.37182)
		(width 0.14732)
		(layer "In4.Cu")
		(net "P5E_CPU1_PE4_RX_DP<11>")
	)
	(segment
		(start 80.692498 -434.719222)
		(end 80.692498 -424.45432)
		(width 0.14732)
		(layer "In4.Cu")
		(net "P5E_CPU1_PE4_RX_DP<11>")
	)
	(segment
		(start 100.159312 -288.646108)
		(end 100.002848 -288.917126)
		(width 0.0889)
		(layer "In4.Cu")
		(net "P5E_CPU1_PE4_RX_DP<11>")
	)
	(segment
		(start 69.65823 -334.60182)
		(end 72.437752 -327.891648)
		(width 0.14732)
		(layer "In4.Cu")
		(net "P5E_CPU1_PE4_RX_DP<11>")
	)
	(segment
		(start 80.692498 -424.45432)
		(end 80.707484 -424.130978)
		(width 0.14732)
		(layer "In4.Cu")
		(net "P5E_CPU1_PE4_RX_DP<11>")
	)
	(segment
		(start 100.237544 -288.62528)
		(end 100.159312 -288.646108)
		(width 0.0889)
		(layer "In4.Cu")
		(net "P5E_CPU1_PE4_RX_DP<11>")
	)
	(segment
		(start 70.067932 -351.415096)
		(end 69.537326 -335.37144)
		(width 0.14732)
		(layer "In4.Cu")
		(net "P5E_CPU1_PE4_RX_DP<11>")
	)
	(segment
		(start 81.000346 -435.02707)
		(end 80.692498 -434.719222)
		(width 0.14732)
		(layer "In4.Cu")
		(net "P5E_CPU1_PE4_RX_DP<11>")
	)
	(segment
		(start 98.492818 -292.992048)
		(end 98.492818 -292.96995)
		(width 0.0889)
		(layer "In4.Cu")
		(net "P5E_CPU1_PE4_RX_DP<11>")
	)
	(segment
		(start 81.784698 -406.19934)
		(end 83.501738 -404.4823)
		(width 0.14732)
		(layer "In4.Cu")
		(net "P5E_CPU1_PE4_RX_DP<11>")
	)
	(segment
		(start 69.537326 -335.37144)
		(end 69.65823 -334.60182)
		(width 0.14732)
		(layer "In4.Cu")
		(net "P5E_CPU1_PE4_RX_DP<11>")
	)
	(arc
		(start 100.662994 -289.446462)
		(mid 100.488862 -289.307615)
		(end 100.377498 -289.114738)
		(width 0.0889)
		(layer "In4.Cu")
		(net "P5E_CPU1_PE4_RX_DP<11>")
	)
	(arc
		(start 100.377498 -288.917126)
		(mid 100.340638 -288.755329)
		(end 100.237544 -288.62528)
		(width 0.0889)
		(layer "In4.Cu")
		(net "P5E_CPU1_PE4_RX_DP<11>")
	)
	(arc
		(start 100.847144 -289.645852)
		(mid 100.772139 -289.530393)
		(end 100.662994 -289.446462)
		(width 0.0889)
		(layer "In4.Cu")
		(net "P5E_CPU1_PE4_RX_DP<11>")
	)
	(segment
		(start 99.063048 -288.381186)
		(end 99.063048 -288.917126)
		(width 0.13208)
		(layer "F.Cu")
		(net "P5E_CPU1_PE4_RX_DP<10>")
	)
	(segment
		(start 79.650082 -433.605178)
		(end 79.650082 -433.289964)
		(width 0.14732)
		(layer "In4.Cu")
		(net "P5E_CPU1_PE4_RX_DP<10>")
	)
	(segment
		(start 78.995778 -406.313132)
		(end 78.995778 -421.181276)
		(width 0.14732)
		(layer "In4.Cu")
		(net "P5E_CPU1_PE4_RX_DP<10>")
	)
	(segment
		(start 78.954884 -433.542694)
		(end 79.164942 -433.752752)
		(width 0.14732)
		(layer "In4.Cu")
		(net "P5E_CPU1_PE4_RX_DP<10>")
	)
	(segment
		(start 78.984094 -422.10609)
		(end 79.122016 -422.247568)
		(width 0.14732)
		(layer "In4.Cu")
		(net "P5E_CPU1_PE4_RX_DP<10>")
	)
	(segment
		(start 78.954884 -424.40479)
		(end 78.954884 -433.542694)
		(width 0.14732)
		(layer "In4.Cu")
		(net "P5E_CPU1_PE4_RX_DP<10>")
	)
	(segment
		(start 68.854828 -335.362296)
		(end 68.854574 -335.357724)
		(width 0.14732)
		(layer "In4.Cu")
		(net "P5E_CPU1_PE4_RX_DP<10>")
	)
	(segment
		(start 68.854574 -335.357724)
		(end 69.293994 -351.16135)
		(width 0.14732)
		(layer "In4.Cu")
		(net "P5E_CPU1_PE4_RX_DP<10>")
	)
	(segment
		(start 97.83699 -297.175682)
		(end 96.904556 -302.457104)
		(width 0.14732)
		(layer "In4.Cu")
		(net "P5E_CPU1_PE4_RX_DP<10>")
	)
	(segment
		(start 97.83699 -292.992048)
		(end 97.83699 -297.175682)
		(width 0.14732)
		(layer "In4.Cu")
		(net "P5E_CPU1_PE4_RX_DP<10>")
	)
	(segment
		(start 79.122016 -422.247568)
		(end 79.117444 -422.616122)
		(width 0.14732)
		(layer "In4.Cu")
		(net "P5E_CPU1_PE4_RX_DP<10>")
	)
	(segment
		(start 69.293994 -351.16135)
		(end 73.895966 -372.61419)
		(width 0.14732)
		(layer "In4.Cu")
		(net "P5E_CPU1_PE4_RX_DP<10>")
	)
	(segment
		(start 80.712818 -399.34261)
		(end 80.712818 -404.596092)
		(width 0.14732)
		(layer "In4.Cu")
		(net "P5E_CPU1_PE4_RX_DP<10>")
	)
	(segment
		(start 99.221798 -289.218116)
		(end 99.318572 -289.247834)
		(width 0.0889)
		(layer "In4.Cu")
		(net "P5E_CPU1_PE4_RX_DP<10>")
	)
	(segment
		(start 79.109062 -423.263568)
		(end 79.10449 -423.632122)
		(width 0.14732)
		(layer "In4.Cu")
		(net "P5E_CPU1_PE4_RX_DP<10>")
	)
	(segment
		(start 100.097844 -289.60953)
		(end 100.097844 -290.336478)
		(width 0.0889)
		(layer "In4.Cu")
		(net "P5E_CPU1_PE4_RX_DP<10>")
	)
	(segment
		(start 79.117444 -422.616122)
		(end 78.975712 -422.754044)
		(width 0.14732)
		(layer "In4.Cu")
		(net "P5E_CPU1_PE4_RX_DP<10>")
	)
	(segment
		(start 96.904556 -302.457104)
		(end 71.757032 -327.605644)
		(width 0.14732)
		(layer "In4.Cu")
		(net "P5E_CPU1_PE4_RX_DP<10>")
	)
	(segment
		(start 79.502508 -433.752752)
		(end 79.650082 -433.605178)
		(width 0.14732)
		(layer "In4.Cu")
		(net "P5E_CPU1_PE4_RX_DP<10>")
	)
	(segment
		(start 73.895966 -372.61419)
		(end 80.712818 -399.34261)
		(width 0.14732)
		(layer "In4.Cu")
		(net "P5E_CPU1_PE4_RX_DP<10>")
	)
	(segment
		(start 99.063048 -288.917126)
		(end 99.221798 -289.218116)
		(width 0.0889)
		(layer "In4.Cu")
		(net "P5E_CPU1_PE4_RX_DP<10>")
	)
	(segment
		(start 78.995778 -421.181276)
		(end 78.984094 -422.10609)
		(width 0.14732)
		(layer "In4.Cu")
		(net "P5E_CPU1_PE4_RX_DP<10>")
	)
	(segment
		(start 100.097844 -290.336478)
		(end 97.794826 -292.639496)
		(width 0.0889)
		(layer "In4.Cu")
		(net "P5E_CPU1_PE4_RX_DP<10>")
	)
	(segment
		(start 79.10449 -423.632122)
		(end 78.962758 -423.770044)
		(width 0.14732)
		(layer "In4.Cu")
		(net "P5E_CPU1_PE4_RX_DP<10>")
	)
	(segment
		(start 97.794826 -292.927786)
		(end 97.83699 -292.96995)
		(width 0.0889)
		(layer "In4.Cu")
		(net "P5E_CPU1_PE4_RX_DP<10>")
	)
	(segment
		(start 71.757032 -327.605644)
		(end 68.978272 -334.314546)
		(width 0.14732)
		(layer "In4.Cu")
		(net "P5E_CPU1_PE4_RX_DP<10>")
	)
	(segment
		(start 97.83699 -292.96995)
		(end 97.83699 -292.992048)
		(width 0.0889)
		(layer "In4.Cu")
		(net "P5E_CPU1_PE4_RX_DP<10>")
	)
	(segment
		(start 68.978272 -334.314546)
		(end 68.854828 -335.362296)
		(width 0.14732)
		(layer "In4.Cu")
		(net "P5E_CPU1_PE4_RX_DP<10>")
	)
	(segment
		(start 80.712818 -404.596092)
		(end 78.995778 -406.313132)
		(width 0.14732)
		(layer "In4.Cu")
		(net "P5E_CPU1_PE4_RX_DP<10>")
	)
	(segment
		(start 78.962758 -423.770044)
		(end 78.954884 -424.40479)
		(width 0.14732)
		(layer "In4.Cu")
		(net "P5E_CPU1_PE4_RX_DP<10>")
	)
	(segment
		(start 78.975712 -422.754044)
		(end 78.97114 -423.12209)
		(width 0.14732)
		(layer "In4.Cu")
		(net "P5E_CPU1_PE4_RX_DP<10>")
	)
	(segment
		(start 79.164942 -433.752752)
		(end 79.502508 -433.752752)
		(width 0.14732)
		(layer "In4.Cu")
		(net "P5E_CPU1_PE4_RX_DP<10>")
	)
	(segment
		(start 97.794826 -292.639496)
		(end 97.794826 -292.927786)
		(width 0.0889)
		(layer "In4.Cu")
		(net "P5E_CPU1_PE4_RX_DP<10>")
	)
	(segment
		(start 78.97114 -423.12209)
		(end 79.109062 -423.263568)
		(width 0.14732)
		(layer "In4.Cu")
		(net "P5E_CPU1_PE4_RX_DP<10>")
	)
	(arc
		(start 99.318572 -289.247834)
		(mid 99.328447 -289.244192)
		(end 99.338384 -289.240722)
		(width 0.0889)
		(layer "In4.Cu")
		(net "P5E_CPU1_PE4_RX_DP<10>")
	)
	(arc
		(start 99.338384 -289.240722)
		(mid 99.794226 -289.26845)
		(end 100.097844 -289.60953)
		(width 0.0889)
		(layer "In4.Cu")
		(net "P5E_CPU1_PE4_RX_DP<10>")
	)
	(segment
		(start 89.194894 -287.567116)
		(end 89.194894 -288.103056)
		(width 0.13208)
		(layer "F.Cu")
		(net "P5E_CPU1_PE4_RX_DP<0>")
	)
	(segment
		(start 52.175156 -416.740848)
		(end 52.26304 -416.564064)
		(width 0.14732)
		(layer "In4.Cu")
		(net "P5E_CPU1_PE4_RX_DP<0>")
	)
	(segment
		(start 52.145946 -416.21456)
		(end 51.968654 -416.126676)
		(width 0.14732)
		(layer "In4.Cu")
		(net "P5E_CPU1_PE4_RX_DP<0>")
	)
	(segment
		(start 88.918034 -289.70097)
		(end 88.918034 -289.641026)
		(width 0.0889)
		(layer "In4.Cu")
		(net "P5E_CPU1_PE4_RX_DP<0>")
	)
	(segment
		(start 84.574634 -293.078154)
		(end 87.602568 -290.05022)
		(width 0.14732)
		(layer "In4.Cu")
		(net "P5E_CPU1_PE4_RX_DP<0>")
	)
	(segment
		(start 64.199008 -320.749168)
		(end 65.438528 -320.235834)
		(width 0.14732)
		(layer "In4.Cu")
		(net "P5E_CPU1_PE4_RX_DP<0>")
	)
	(segment
		(start 63.228728 -320.749168)
		(end 64.199008 -320.749168)
		(width 0.14732)
		(layer "In4.Cu")
		(net "P5E_CPU1_PE4_RX_DP<0>")
	)
	(segment
		(start 76.117958 -309.556404)
		(end 81.870804 -299.60062)
		(width 0.14732)
		(layer "In4.Cu")
		(net "P5E_CPU1_PE4_RX_DP<0>")
	)
	(segment
		(start 48.363378 -406.313132)
		(end 50.080418 -404.596092)
		(width 0.14732)
		(layer "In4.Cu")
		(net "P5E_CPU1_PE4_RX_DP<0>")
	)
	(segment
		(start 58.650124 -433.605178)
		(end 58.50255 -433.752752)
		(width 0.14732)
		(layer "In4.Cu")
		(net "P5E_CPU1_PE4_RX_DP<0>")
	)
	(segment
		(start 52.586636 -417.527232)
		(end 52.469542 -417.177728)
		(width 0.14732)
		(layer "In4.Cu")
		(net "P5E_CPU1_PE4_RX_DP<0>")
	)
	(segment
		(start 52.26304 -416.564064)
		(end 52.145946 -416.21456)
		(width 0.14732)
		(layer "In4.Cu")
		(net "P5E_CPU1_PE4_RX_DP<0>")
	)
	(segment
		(start 57.501536 -325.986648)
		(end 58.67781 -324.810374)
		(width 0.14732)
		(layer "In4.Cu")
		(net "P5E_CPU1_PE4_RX_DP<0>")
	)
	(segment
		(start 48.453294 -410.868622)
		(end 48.363378 -410.41828)
		(width 0.14732)
		(layer "In4.Cu")
		(net "P5E_CPU1_PE4_RX_DP<0>")
	)
	(segment
		(start 50.080418 -399.936716)
		(end 59.333892 -366.554258)
		(width 0.14732)
		(layer "In4.Cu")
		(net "P5E_CPU1_PE4_RX_DP<0>")
	)
	(segment
		(start 87.602568 -290.05022)
		(end 88.567768 -290.05022)
		(width 0.14732)
		(layer "In4.Cu")
		(net "P5E_CPU1_PE4_RX_DP<0>")
	)
	(segment
		(start 51.82235 -415.251392)
		(end 51.645312 -415.163508)
		(width 0.14732)
		(layer "In4.Cu")
		(net "P5E_CPU1_PE4_RX_DP<0>")
	)
	(segment
		(start 88.763856 -289.854132)
		(end 88.764872 -289.854132)
		(width 0.14732)
		(layer "In4.Cu")
		(net "P5E_CPU1_PE4_RX_DP<0>")
	)
	(segment
		(start 51.252882 -413.995362)
		(end 48.453294 -410.868622)
		(width 0.14732)
		(layer "In4.Cu")
		(net "P5E_CPU1_PE4_RX_DP<0>")
	)
	(segment
		(start 89.06256 -288.463228)
		(end 89.03843 -288.374074)
		(width 0.0889)
		(layer "In4.Cu")
		(net "P5E_CPU1_PE4_RX_DP<0>")
	)
	(segment
		(start 81.870804 -299.60062)
		(end 84.574634 -293.078154)
		(width 0.14732)
		(layer "In4.Cu")
		(net "P5E_CPU1_PE4_RX_DP<0>")
	)
	(segment
		(start 59.333892 -366.554258)
		(end 57.501536 -330.390754)
		(width 0.14732)
		(layer "In4.Cu")
		(net "P5E_CPU1_PE4_RX_DP<0>")
	)
	(segment
		(start 50.080418 -404.596092)
		(end 50.080418 -399.936716)
		(width 0.14732)
		(layer "In4.Cu")
		(net "P5E_CPU1_PE4_RX_DP<0>")
	)
	(segment
		(start 57.501536 -330.390754)
		(end 57.501536 -325.986648)
		(width 0.14732)
		(layer "In4.Cu")
		(net "P5E_CPU1_PE4_RX_DP<0>")
	)
	(segment
		(start 52.469542 -417.177728)
		(end 52.29225 -417.089844)
		(width 0.14732)
		(layer "In4.Cu")
		(net "P5E_CPU1_PE4_RX_DP<0>")
	)
	(segment
		(start 65.438528 -320.235834)
		(end 76.117958 -309.556404)
		(width 0.14732)
		(layer "In4.Cu")
		(net "P5E_CPU1_PE4_RX_DP<0>")
	)
	(segment
		(start 52.498752 -417.704016)
		(end 52.586636 -417.527232)
		(width 0.14732)
		(layer "In4.Cu")
		(net "P5E_CPU1_PE4_RX_DP<0>")
	)
	(segment
		(start 51.939698 -415.600896)
		(end 51.82235 -415.251392)
		(width 0.14732)
		(layer "In4.Cu")
		(net "P5E_CPU1_PE4_RX_DP<0>")
	)
	(segment
		(start 89.28989 -288.901886)
		(end 89.290398 -288.902902)
		(width 0.0889)
		(layer "In4.Cu")
		(net "P5E_CPU1_PE4_RX_DP<0>")
	)
	(segment
		(start 58.650124 -433.289964)
		(end 58.650124 -433.605178)
		(width 0.14732)
		(layer "In4.Cu")
		(net "P5E_CPU1_PE4_RX_DP<0>")
	)
	(segment
		(start 51.645312 -415.163508)
		(end 51.252882 -413.995362)
		(width 0.14732)
		(layer "In4.Cu")
		(net "P5E_CPU1_PE4_RX_DP<0>")
	)
	(segment
		(start 51.85156 -415.77768)
		(end 51.939698 -415.600896)
		(width 0.14732)
		(layer "In4.Cu")
		(net "P5E_CPU1_PE4_RX_DP<0>")
	)
	(segment
		(start 57.774078 -433.412392)
		(end 52.498752 -417.704016)
		(width 0.14732)
		(layer "In4.Cu")
		(net "P5E_CPU1_PE4_RX_DP<0>")
	)
	(segment
		(start 88.90254 -289.716464)
		(end 88.918034 -289.70097)
		(width 0.0889)
		(layer "In4.Cu")
		(net "P5E_CPU1_PE4_RX_DP<0>")
	)
	(segment
		(start 58.50255 -433.752752)
		(end 58.114184 -433.752752)
		(width 0.14732)
		(layer "In4.Cu")
		(net "P5E_CPU1_PE4_RX_DP<0>")
	)
	(segment
		(start 89.28989 -289.26917)
		(end 89.28989 -288.901886)
		(width 0.0889)
		(layer "In4.Cu")
		(net "P5E_CPU1_PE4_RX_DP<0>")
	)
	(segment
		(start 88.918034 -289.641026)
		(end 89.28989 -289.26917)
		(width 0.0889)
		(layer "In4.Cu")
		(net "P5E_CPU1_PE4_RX_DP<0>")
	)
	(segment
		(start 48.363378 -410.41828)
		(end 48.363378 -406.313132)
		(width 0.14732)
		(layer "In4.Cu")
		(net "P5E_CPU1_PE4_RX_DP<0>")
	)
	(segment
		(start 51.968654 -416.126676)
		(end 51.85156 -415.77768)
		(width 0.14732)
		(layer "In4.Cu")
		(net "P5E_CPU1_PE4_RX_DP<0>")
	)
	(segment
		(start 58.114184 -433.752752)
		(end 57.774078 -433.412392)
		(width 0.14732)
		(layer "In4.Cu")
		(net "P5E_CPU1_PE4_RX_DP<0>")
	)
	(segment
		(start 89.03843 -288.374074)
		(end 89.194894 -288.103056)
		(width 0.0889)
		(layer "In4.Cu")
		(net "P5E_CPU1_PE4_RX_DP<0>")
	)
	(segment
		(start 88.764872 -289.854132)
		(end 88.90254 -289.716464)
		(width 0.14732)
		(layer "In4.Cu")
		(net "P5E_CPU1_PE4_RX_DP<0>")
	)
	(segment
		(start 88.567768 -290.05022)
		(end 88.763856 -289.854132)
		(width 0.14732)
		(layer "In4.Cu")
		(net "P5E_CPU1_PE4_RX_DP<0>")
	)
	(segment
		(start 58.67781 -324.810374)
		(end 63.228728 -320.749168)
		(width 0.14732)
		(layer "In4.Cu")
		(net "P5E_CPU1_PE4_RX_DP<0>")
	)
	(segment
		(start 52.29225 -417.089844)
		(end 52.175156 -416.740848)
		(width 0.14732)
		(layer "In4.Cu")
		(net "P5E_CPU1_PE4_RX_DP<0>")
	)
	(arc
		(start 89.079578 -288.476182)
		(mid 89.07113 -288.469625)
		(end 89.06256 -288.463228)
		(width 0.0889)
		(layer "In4.Cu")
		(net "P5E_CPU1_PE4_RX_DP<0>")
	)
	(arc
		(start 89.290398 -288.902902)
		(mid 89.232104 -288.666259)
		(end 89.079578 -288.476182)
		(width 0.0889)
		(layer "In4.Cu")
		(net "P5E_CPU1_PE4_RX_DP<0>")
	)
	(segment
		(start 98.592894 -287.567116)
		(end 98.592894 -288.102802)
		(width 0.13208)
		(layer "F.Cu")
		(net "P5E_CPU1_PE4_RX_DN<9>")
	)
	(segment
		(start 98.592894 -288.102802)
		(end 98.593148 -288.103056)
		(width 0.13208)
		(layer "F.Cu")
		(net "P5E_CPU1_PE4_RX_DN<9>")
	)
	(segment
		(start 76.720446 -420.24173)
		(end 76.86929 -420.371778)
		(width 0.14732)
		(layer "In4.Cu")
		(net "P5E_CPU1_PE4_RX_DN<9>")
	)
	(segment
		(start 99.15779 -290.293044)
		(end 96.863408 -292.587426)
		(width 0.0889)
		(layer "In4.Cu")
		(net "P5E_CPU1_PE4_RX_DN<9>")
	)
	(segment
		(start 76.93787 -421.385492)
		(end 76.962508 -421.753284)
		(width 0.14732)
		(layer "In4.Cu")
		(net "P5E_CPU1_PE4_RX_DN<9>")
	)
	(segment
		(start 98.688144 -288.916872)
		(end 98.688398 -288.91738)
		(width 0.0889)
		(layer "In4.Cu")
		(net "P5E_CPU1_PE4_RX_DN<9>")
	)
	(segment
		(start 77.649578 -404.596092)
		(end 75.932538 -406.313132)
		(width 0.14732)
		(layer "In4.Cu")
		(net "P5E_CPU1_PE4_RX_DN<9>")
	)
	(segment
		(start 98.593148 -288.103056)
		(end 98.436684 -288.374074)
		(width 0.0889)
		(layer "In4.Cu")
		(net "P5E_CPU1_PE4_RX_DN<9>")
	)
	(segment
		(start 96.863408 -292.587426)
		(end 96.863408 -292.927786)
		(width 0.0889)
		(layer "In4.Cu")
		(net "P5E_CPU1_PE4_RX_DN<9>")
	)
	(segment
		(start 68.270374 -351.05086)
		(end 71.057262 -367.373662)
		(width 0.14732)
		(layer "In4.Cu")
		(net "P5E_CPU1_PE4_RX_DN<9>")
	)
	(segment
		(start 96.863408 -292.927786)
		(end 96.905572 -292.96995)
		(width 0.0889)
		(layer "In4.Cu")
		(net "P5E_CPU1_PE4_RX_DN<9>")
	)
	(segment
		(start 76.962508 -421.753284)
		(end 76.83246 -421.901874)
		(width 0.14732)
		(layer "In4.Cu")
		(net "P5E_CPU1_PE4_RX_DN<9>")
	)
	(segment
		(start 75.932538 -406.313132)
		(end 75.932538 -410.652976)
		(width 0.14732)
		(layer "In4.Cu")
		(net "P5E_CPU1_PE4_RX_DN<9>")
	)
	(segment
		(start 67.956176 -334.088232)
		(end 67.926966 -334.59547)
		(width 0.14732)
		(layer "In4.Cu")
		(net "P5E_CPU1_PE4_RX_DN<9>")
	)
	(segment
		(start 67.926966 -334.59547)
		(end 67.926712 -334.595724)
		(width 0.14732)
		(layer "In4.Cu")
		(net "P5E_CPU1_PE4_RX_DN<9>")
	)
	(segment
		(start 77.502512 -434.75275)
		(end 77.650086 -434.605176)
		(width 0.14732)
		(layer "In4.Cu")
		(net "P5E_CPU1_PE4_RX_DN<9>")
	)
	(segment
		(start 77.042772 -422.944798)
		(end 76.912724 -423.093642)
		(width 0.14732)
		(layer "In4.Cu")
		(net "P5E_CPU1_PE4_RX_DN<9>")
	)
	(segment
		(start 75.932538 -410.652976)
		(end 76.157582 -411.889194)
		(width 0.14732)
		(layer "In4.Cu")
		(net "P5E_CPU1_PE4_RX_DN<9>")
	)
	(segment
		(start 76.894182 -420.73957)
		(end 76.764134 -420.88816)
		(width 0.14732)
		(layer "In4.Cu")
		(net "P5E_CPU1_PE4_RX_DN<9>")
	)
	(segment
		(start 98.436684 -288.374074)
		(end 98.460814 -288.463228)
		(width 0.0889)
		(layer "In4.Cu")
		(net "P5E_CPU1_PE4_RX_DN<9>")
	)
	(segment
		(start 67.926712 -334.595724)
		(end 67.897248 -335.102454)
		(width 0.14732)
		(layer "In4.Cu")
		(net "P5E_CPU1_PE4_RX_DN<9>")
	)
	(segment
		(start 77.650086 -434.605176)
		(end 77.650086 -434.289962)
		(width 0.14732)
		(layer "In4.Cu")
		(net "P5E_CPU1_PE4_RX_DN<9>")
	)
	(segment
		(start 67.897248 -335.102454)
		(end 68.270374 -351.05086)
		(width 0.14732)
		(layer "In4.Cu")
		(net "P5E_CPU1_PE4_RX_DN<9>")
	)
	(segment
		(start 76.157582 -411.889194)
		(end 76.720446 -420.24173)
		(width 0.14732)
		(layer "In4.Cu")
		(net "P5E_CPU1_PE4_RX_DN<9>")
	)
	(segment
		(start 70.785482 -327.256902)
		(end 67.956176 -334.088232)
		(width 0.14732)
		(layer "In4.Cu")
		(net "P5E_CPU1_PE4_RX_DN<9>")
	)
	(segment
		(start 99.15779 -289.610292)
		(end 99.15779 -290.293044)
		(width 0.0889)
		(layer "In4.Cu")
		(net "P5E_CPU1_PE4_RX_DN<9>")
	)
	(segment
		(start 96.905572 -292.992048)
		(end 96.905572 -297.09237)
		(width 0.14732)
		(layer "In4.Cu")
		(net "P5E_CPU1_PE4_RX_DN<9>")
	)
	(segment
		(start 76.86929 -420.371778)
		(end 76.894182 -420.73957)
		(width 0.14732)
		(layer "In4.Cu")
		(net "P5E_CPU1_PE4_RX_DN<9>")
	)
	(segment
		(start 77.649578 -399.080736)
		(end 77.649578 -404.596092)
		(width 0.14732)
		(layer "In4.Cu")
		(net "P5E_CPU1_PE4_RX_DN<9>")
	)
	(segment
		(start 76.83246 -421.901874)
		(end 76.869036 -422.446958)
		(width 0.14732)
		(layer "In4.Cu")
		(net "P5E_CPU1_PE4_RX_DN<9>")
	)
	(segment
		(start 76.788772 -421.255444)
		(end 76.93787 -421.385492)
		(width 0.14732)
		(layer "In4.Cu")
		(net "P5E_CPU1_PE4_RX_DN<9>")
	)
	(segment
		(start 96.03867 -302.002952)
		(end 70.785482 -327.256902)
		(width 0.14732)
		(layer "In4.Cu")
		(net "P5E_CPU1_PE4_RX_DN<9>")
	)
	(segment
		(start 76.869036 -422.446958)
		(end 77.018134 -422.577006)
		(width 0.14732)
		(layer "In4.Cu")
		(net "P5E_CPU1_PE4_RX_DN<9>")
	)
	(segment
		(start 76.764134 -420.88816)
		(end 76.788772 -421.255444)
		(width 0.14732)
		(layer "In4.Cu")
		(net "P5E_CPU1_PE4_RX_DN<9>")
	)
	(segment
		(start 76.966826 -423.89933)
		(end 76.966826 -434.60543)
		(width 0.14732)
		(layer "In4.Cu")
		(net "P5E_CPU1_PE4_RX_DN<9>")
	)
	(segment
		(start 98.688398 -288.91738)
		(end 98.688398 -289.078416)
		(width 0.0889)
		(layer "In4.Cu")
		(net "P5E_CPU1_PE4_RX_DN<9>")
	)
	(segment
		(start 77.114146 -434.75275)
		(end 77.502512 -434.75275)
		(width 0.14732)
		(layer "In4.Cu")
		(net "P5E_CPU1_PE4_RX_DN<9>")
	)
	(segment
		(start 77.018134 -422.577006)
		(end 77.042772 -422.944798)
		(width 0.14732)
		(layer "In4.Cu")
		(net "P5E_CPU1_PE4_RX_DN<9>")
	)
	(segment
		(start 76.912724 -423.093642)
		(end 76.966826 -423.89933)
		(width 0.14732)
		(layer "In4.Cu")
		(net "P5E_CPU1_PE4_RX_DN<9>")
	)
	(segment
		(start 71.057262 -367.373662)
		(end 77.649578 -399.080736)
		(width 0.14732)
		(layer "In4.Cu")
		(net "P5E_CPU1_PE4_RX_DN<9>")
	)
	(segment
		(start 98.477832 -288.476436)
		(end 98.477324 -288.476944)
		(width 0.0889)
		(layer "In4.Cu")
		(net "P5E_CPU1_PE4_RX_DN<9>")
	)
	(segment
		(start 76.966826 -434.60543)
		(end 77.114146 -434.75275)
		(width 0.14732)
		(layer "In4.Cu")
		(net "P5E_CPU1_PE4_RX_DN<9>")
	)
	(segment
		(start 98.872548 -289.277806)
		(end 98.872294 -289.27806)
		(width 0.0889)
		(layer "In4.Cu")
		(net "P5E_CPU1_PE4_RX_DN<9>")
	)
	(segment
		(start 96.905572 -292.96995)
		(end 96.905572 -292.992048)
		(width 0.0889)
		(layer "In4.Cu")
		(net "P5E_CPU1_PE4_RX_DN<9>")
	)
	(segment
		(start 96.905572 -297.09237)
		(end 96.03867 -302.002952)
		(width 0.14732)
		(layer "In4.Cu")
		(net "P5E_CPU1_PE4_RX_DN<9>")
	)
	(arc
		(start 98.460814 -288.463228)
		(mid 98.469386 -288.469751)
		(end 98.477832 -288.476436)
		(width 0.0889)
		(layer "In4.Cu")
		(net "P5E_CPU1_PE4_RX_DN<9>")
	)
	(arc
		(start 98.688398 -289.078416)
		(mid 98.763403 -289.193875)
		(end 98.872548 -289.277806)
		(width 0.0889)
		(layer "In4.Cu")
		(net "P5E_CPU1_PE4_RX_DN<9>")
	)
	(arc
		(start 98.477324 -288.476944)
		(mid 98.63268 -288.672976)
		(end 98.688144 -288.916872)
		(width 0.0889)
		(layer "In4.Cu")
		(net "P5E_CPU1_PE4_RX_DN<9>")
	)
	(arc
		(start 98.872294 -289.27806)
		(mid 99.046539 -289.417106)
		(end 99.15779 -289.610292)
		(width 0.0889)
		(layer "In4.Cu")
		(net "P5E_CPU1_PE4_RX_DN<9>")
	)
	(segment
		(start 97.653094 -289.195002)
		(end 97.653094 -289.807142)
		(width 0.13208)
		(layer "F.Cu")
		(net "P5E_CPU1_PE4_RX_DN<8>")
	)
	(segment
		(start 72.827642 -411.31871)
		(end 72.594978 -410.577792)
		(width 0.14732)
		(layer "In4.Cu")
		(net "P5E_CPU1_PE4_RX_DN<8>")
	)
	(segment
		(start 72.594978 -406.19934)
		(end 74.312018 -404.4823)
		(width 0.14732)
		(layer "In4.Cu")
		(net "P5E_CPU1_PE4_RX_DN<8>")
	)
	(segment
		(start 75.03795 -434.027072)
		(end 74.633074 -433.622196)
		(width 0.14732)
		(layer "In4.Cu")
		(net "P5E_CPU1_PE4_RX_DN<8>")
	)
	(segment
		(start 95.698564 -292.96995)
		(end 95.740474 -292.92804)
		(width 0.0889)
		(layer "In4.Cu")
		(net "P5E_CPU1_PE4_RX_DN<8>")
	)
	(segment
		(start 73.757536 -417.675314)
		(end 72.827642 -411.31871)
		(width 0.14732)
		(layer "In4.Cu")
		(net "P5E_CPU1_PE4_RX_DN<8>")
	)
	(segment
		(start 70.073266 -372.709186)
		(end 66.845688 -350.060514)
		(width 0.14732)
		(layer "In4.Cu")
		(net "P5E_CPU1_PE4_RX_DN<8>")
	)
	(segment
		(start 74.633074 -433.622196)
		(end 73.757536 -417.675314)
		(width 0.14732)
		(layer "In4.Cu")
		(net "P5E_CPU1_PE4_RX_DN<8>")
	)
	(segment
		(start 72.594978 -410.577792)
		(end 72.594978 -406.19934)
		(width 0.14732)
		(layer "In4.Cu")
		(net "P5E_CPU1_PE4_RX_DN<8>")
	)
	(segment
		(start 97.494344 -289.506152)
		(end 97.653094 -289.807142)
		(width 0.0889)
		(layer "In4.Cu")
		(net "P5E_CPU1_PE4_RX_DN<8>")
	)
	(segment
		(start 66.845688 -350.060514)
		(end 66.575686 -335.407762)
		(width 0.14732)
		(layer "In4.Cu")
		(net "P5E_CPU1_PE4_RX_DN<8>")
	)
	(segment
		(start 75.65009 -434.48986)
		(end 75.65009 -434.174646)
		(width 0.14732)
		(layer "In4.Cu")
		(net "P5E_CPU1_PE4_RX_DN<8>")
	)
	(segment
		(start 69.674994 -326.660002)
		(end 94.915736 -301.418498)
		(width 0.14732)
		(layer "In4.Cu")
		(net "P5E_CPU1_PE4_RX_DN<8>")
	)
	(segment
		(start 70.074282 -372.716044)
		(end 70.073266 -372.709186)
		(width 0.14732)
		(layer "In4.Cu")
		(net "P5E_CPU1_PE4_RX_DN<8>")
	)
	(segment
		(start 98.027998 -290.150804)
		(end 98.027998 -289.64509)
		(width 0.0889)
		(layer "In4.Cu")
		(net "P5E_CPU1_PE4_RX_DN<8>")
	)
	(segment
		(start 66.722244 -333.789528)
		(end 69.674994 -326.660002)
		(width 0.14732)
		(layer "In4.Cu")
		(net "P5E_CPU1_PE4_RX_DN<8>")
	)
	(segment
		(start 74.312018 -404.4823)
		(end 74.312018 -398.422368)
		(width 0.14732)
		(layer "In4.Cu")
		(net "P5E_CPU1_PE4_RX_DN<8>")
	)
	(segment
		(start 95.740474 -292.438328)
		(end 98.027998 -290.150804)
		(width 0.0889)
		(layer "In4.Cu")
		(net "P5E_CPU1_PE4_RX_DN<8>")
	)
	(segment
		(start 95.740474 -292.92804)
		(end 95.740474 -292.438328)
		(width 0.0889)
		(layer "In4.Cu")
		(net "P5E_CPU1_PE4_RX_DN<8>")
	)
	(segment
		(start 94.915736 -301.418498)
		(end 95.698564 -296.982134)
		(width 0.14732)
		(layer "In4.Cu")
		(net "P5E_CPU1_PE4_RX_DN<8>")
	)
	(segment
		(start 75.502516 -434.027072)
		(end 75.03795 -434.027072)
		(width 0.14732)
		(layer "In4.Cu")
		(net "P5E_CPU1_PE4_RX_DN<8>")
	)
	(segment
		(start 97.52076 -289.42157)
		(end 97.494344 -289.506152)
		(width 0.0889)
		(layer "In4.Cu")
		(net "P5E_CPU1_PE4_RX_DN<8>")
	)
	(segment
		(start 74.312018 -398.422368)
		(end 70.074282 -372.716044)
		(width 0.14732)
		(layer "In4.Cu")
		(net "P5E_CPU1_PE4_RX_DN<8>")
	)
	(segment
		(start 75.65009 -434.174646)
		(end 75.502516 -434.027072)
		(width 0.14732)
		(layer "In4.Cu")
		(net "P5E_CPU1_PE4_RX_DN<8>")
	)
	(segment
		(start 95.698564 -292.992048)
		(end 95.698564 -292.96995)
		(width 0.0889)
		(layer "In4.Cu")
		(net "P5E_CPU1_PE4_RX_DN<8>")
	)
	(segment
		(start 66.575686 -335.407762)
		(end 66.722244 -333.789528)
		(width 0.14732)
		(layer "In4.Cu")
		(net "P5E_CPU1_PE4_RX_DN<8>")
	)
	(segment
		(start 95.698564 -296.982134)
		(end 95.698564 -292.992048)
		(width 0.14732)
		(layer "In4.Cu")
		(net "P5E_CPU1_PE4_RX_DN<8>")
	)
	(arc
		(start 97.520252 -289.420808)
		(mid 97.520507 -289.421188)
		(end 97.52076 -289.42157)
		(width 0.0889)
		(layer "In4.Cu")
		(net "P5E_CPU1_PE4_RX_DN<8>")
	)
	(arc
		(start 98.027998 -289.64509)
		(mid 97.81807 -289.433515)
		(end 97.520252 -289.420808)
		(width 0.0889)
		(layer "In4.Cu")
		(net "P5E_CPU1_PE4_RX_DN<8>")
	)
	(segment
		(start 96.713294 -287.567116)
		(end 96.713294 -288.102802)
		(width 0.13208)
		(layer "F.Cu")
		(net "P5E_CPU1_PE4_RX_DN<7>")
	)
	(segment
		(start 96.713294 -288.102802)
		(end 96.713548 -288.103056)
		(width 0.13208)
		(layer "F.Cu")
		(net "P5E_CPU1_PE4_RX_DN<7>")
	)
	(segment
		(start 95.040196 -292.992048)
		(end 95.040196 -292.96995)
		(width 0.0889)
		(layer "In4.Cu")
		(net "P5E_CPU1_PE4_RX_DN<7>")
	)
	(segment
		(start 65.98285 -333.750666)
		(end 69.043042 -326.362568)
		(width 0.14732)
		(layer "In4.Cu")
		(net "P5E_CPU1_PE4_RX_DN<7>")
	)
	(segment
		(start 70.640194 -412.715964)
		(end 70.50532 -412.30042)
		(width 0.14732)
		(layer "In4.Cu")
		(net "P5E_CPU1_PE4_RX_DN<7>")
	)
	(segment
		(start 95.040196 -292.96995)
		(end 94.998032 -292.927786)
		(width 0.0889)
		(layer "In4.Cu")
		(net "P5E_CPU1_PE4_RX_DN<7>")
	)
	(segment
		(start 70.50532 -412.30042)
		(end 70.348348 -412.220664)
		(width 0.14732)
		(layer "In4.Cu")
		(net "P5E_CPU1_PE4_RX_DN<7>")
	)
	(segment
		(start 96.808798 -289.078416)
		(end 96.808798 -288.898584)
		(width 0.0889)
		(layer "In4.Cu")
		(net "P5E_CPU1_PE4_RX_DN<7>")
	)
	(segment
		(start 71.523098 -398.247616)
		(end 66.036952 -348.939358)
		(width 0.14732)
		(layer "In4.Cu")
		(net "P5E_CPU1_PE4_RX_DN<7>")
	)
	(segment
		(start 94.998032 -292.40607)
		(end 97.27819 -290.125912)
		(width 0.0889)
		(layer "In4.Cu")
		(net "P5E_CPU1_PE4_RX_DN<7>")
	)
	(segment
		(start 96.557084 -288.374074)
		(end 96.713548 -288.103056)
		(width 0.0889)
		(layer "In4.Cu")
		(net "P5E_CPU1_PE4_RX_DN<7>")
	)
	(segment
		(start 70.348348 -412.220664)
		(end 69.806058 -410.552138)
		(width 0.14732)
		(layer "In4.Cu")
		(net "P5E_CPU1_PE4_RX_DN<7>")
	)
	(segment
		(start 66.036952 -348.939358)
		(end 65.880742 -334.417924)
		(width 0.14732)
		(layer "In4.Cu")
		(net "P5E_CPU1_PE4_RX_DN<7>")
	)
	(segment
		(start 72.195436 -434.83403)
		(end 71.966836 -434.60543)
		(width 0.14732)
		(layer "In4.Cu")
		(net "P5E_CPU1_PE4_RX_DN<7>")
	)
	(segment
		(start 95.039688 -296.926254)
		(end 95.040196 -296.925746)
		(width 0.14732)
		(layer "In4.Cu")
		(net "P5E_CPU1_PE4_RX_DN<7>")
	)
	(segment
		(start 70.987412 -413.784034)
		(end 70.852284 -413.368236)
		(width 0.14732)
		(layer "In4.Cu")
		(net "P5E_CPU1_PE4_RX_DN<7>")
	)
	(segment
		(start 70.907402 -413.940752)
		(end 70.987412 -413.784034)
		(width 0.14732)
		(layer "In4.Cu")
		(net "P5E_CPU1_PE4_RX_DN<7>")
	)
	(segment
		(start 69.806058 -410.552138)
		(end 69.806058 -406.313132)
		(width 0.14732)
		(layer "In4.Cu")
		(net "P5E_CPU1_PE4_RX_DN<7>")
	)
	(segment
		(start 72.650096 -434.289962)
		(end 72.650096 -434.686456)
		(width 0.14732)
		(layer "In4.Cu")
		(net "P5E_CPU1_PE4_RX_DN<7>")
	)
	(segment
		(start 97.27819 -289.609276)
		(end 97.278444 -289.60953)
		(width 0.0889)
		(layer "In4.Cu")
		(net "P5E_CPU1_PE4_RX_DN<7>")
	)
	(segment
		(start 70.560438 -412.872936)
		(end 70.640194 -412.715964)
		(width 0.14732)
		(layer "In4.Cu")
		(net "P5E_CPU1_PE4_RX_DN<7>")
	)
	(segment
		(start 70.852284 -413.368236)
		(end 70.695312 -413.288226)
		(width 0.14732)
		(layer "In4.Cu")
		(net "P5E_CPU1_PE4_RX_DN<7>")
	)
	(segment
		(start 94.302834 -301.102522)
		(end 95.039688 -296.926254)
		(width 0.14732)
		(layer "In4.Cu")
		(net "P5E_CPU1_PE4_RX_DN<7>")
	)
	(segment
		(start 71.966836 -434.60543)
		(end 71.966836 -417.201096)
		(width 0.14732)
		(layer "In4.Cu")
		(net "P5E_CPU1_PE4_RX_DN<7>")
	)
	(segment
		(start 70.695312 -413.288226)
		(end 70.560438 -412.872936)
		(width 0.14732)
		(layer "In4.Cu")
		(net "P5E_CPU1_PE4_RX_DN<7>")
	)
	(segment
		(start 69.043042 -326.362568)
		(end 94.302834 -301.102522)
		(width 0.14732)
		(layer "In4.Cu")
		(net "P5E_CPU1_PE4_RX_DN<7>")
	)
	(segment
		(start 71.523098 -404.596092)
		(end 71.523098 -398.247616)
		(width 0.14732)
		(layer "In4.Cu")
		(net "P5E_CPU1_PE4_RX_DN<7>")
	)
	(segment
		(start 72.650096 -434.686456)
		(end 72.502522 -434.83403)
		(width 0.14732)
		(layer "In4.Cu")
		(net "P5E_CPU1_PE4_RX_DN<7>")
	)
	(segment
		(start 71.966836 -417.201096)
		(end 70.907402 -413.940752)
		(width 0.14732)
		(layer "In4.Cu")
		(net "P5E_CPU1_PE4_RX_DN<7>")
	)
	(segment
		(start 96.581214 -288.463228)
		(end 96.557084 -288.374074)
		(width 0.0889)
		(layer "In4.Cu")
		(net "P5E_CPU1_PE4_RX_DN<7>")
	)
	(segment
		(start 72.502522 -434.83403)
		(end 72.195436 -434.83403)
		(width 0.14732)
		(layer "In4.Cu")
		(net "P5E_CPU1_PE4_RX_DN<7>")
	)
	(segment
		(start 97.27819 -290.125912)
		(end 97.27819 -289.609276)
		(width 0.0889)
		(layer "In4.Cu")
		(net "P5E_CPU1_PE4_RX_DN<7>")
	)
	(segment
		(start 65.880742 -334.417924)
		(end 65.98285 -333.750666)
		(width 0.14732)
		(layer "In4.Cu")
		(net "P5E_CPU1_PE4_RX_DN<7>")
	)
	(segment
		(start 94.998032 -292.927786)
		(end 94.998032 -292.40607)
		(width 0.0889)
		(layer "In4.Cu")
		(net "P5E_CPU1_PE4_RX_DN<7>")
	)
	(segment
		(start 95.040196 -296.925746)
		(end 95.040196 -292.992048)
		(width 0.14732)
		(layer "In4.Cu")
		(net "P5E_CPU1_PE4_RX_DN<7>")
	)
	(segment
		(start 69.806058 -406.313132)
		(end 71.523098 -404.596092)
		(width 0.14732)
		(layer "In4.Cu")
		(net "P5E_CPU1_PE4_RX_DN<7>")
	)
	(arc
		(start 96.992948 -289.277806)
		(mid 96.883801 -289.193878)
		(end 96.808798 -289.078416)
		(width 0.0889)
		(layer "In4.Cu")
		(net "P5E_CPU1_PE4_RX_DN<7>")
	)
	(arc
		(start 96.808798 -288.898584)
		(mid 96.749648 -288.664497)
		(end 96.598232 -288.476436)
		(width 0.0889)
		(layer "In4.Cu")
		(net "P5E_CPU1_PE4_RX_DN<7>")
	)
	(arc
		(start 96.598232 -288.476436)
		(mid 96.589786 -288.469751)
		(end 96.581214 -288.463228)
		(width 0.0889)
		(layer "In4.Cu")
		(net "P5E_CPU1_PE4_RX_DN<7>")
	)
	(arc
		(start 97.278444 -289.60953)
		(mid 97.167106 -289.41663)
		(end 96.992948 -289.277806)
		(width 0.0889)
		(layer "In4.Cu")
		(net "P5E_CPU1_PE4_RX_DN<7>")
	)
	(segment
		(start 95.773494 -289.195002)
		(end 95.773494 -289.807142)
		(width 0.13208)
		(layer "F.Cu")
		(net "P5E_CPU1_PE4_RX_DN<6>")
	)
	(segment
		(start 64.813434 -349.012256)
		(end 64.65443 -334.176116)
		(width 0.14732)
		(layer "In4.Cu")
		(net "P5E_CPU1_PE4_RX_DN<6>")
	)
	(segment
		(start 95.64116 -289.42157)
		(end 95.614744 -289.506152)
		(width 0.0889)
		(layer "In4.Cu")
		(net "P5E_CPU1_PE4_RX_DN<6>")
	)
	(segment
		(start 68.185538 -404.4823)
		(end 68.185538 -396.755874)
		(width 0.14732)
		(layer "In4.Cu")
		(net "P5E_CPU1_PE4_RX_DN<6>")
	)
	(segment
		(start 95.614744 -289.506152)
		(end 95.773494 -289.807142)
		(width 0.0889)
		(layer "In4.Cu")
		(net "P5E_CPU1_PE4_RX_DN<6>")
	)
	(segment
		(start 69.69252 -433.735988)
		(end 69.69252 -417.025836)
		(width 0.14732)
		(layer "In4.Cu")
		(net "P5E_CPU1_PE4_RX_DN<6>")
	)
	(segment
		(start 67.896486 -325.797672)
		(end 93.180916 -300.513242)
		(width 0.14732)
		(layer "In4.Cu")
		(net "P5E_CPU1_PE4_RX_DN<6>")
	)
	(segment
		(start 93.832172 -292.96995)
		(end 93.874082 -292.92804)
		(width 0.0889)
		(layer "In4.Cu")
		(net "P5E_CPU1_PE4_RX_DN<6>")
	)
	(segment
		(start 70.502526 -434.027072)
		(end 69.983604 -434.027072)
		(width 0.14732)
		(layer "In4.Cu")
		(net "P5E_CPU1_PE4_RX_DN<6>")
	)
	(segment
		(start 70.6501 -434.48986)
		(end 70.6501 -434.174646)
		(width 0.14732)
		(layer "In4.Cu")
		(net "P5E_CPU1_PE4_RX_DN<6>")
	)
	(segment
		(start 64.65443 -334.176116)
		(end 64.835786 -333.187294)
		(width 0.14732)
		(layer "In4.Cu")
		(net "P5E_CPU1_PE4_RX_DN<6>")
	)
	(segment
		(start 93.874082 -292.92804)
		(end 93.874082 -292.32606)
		(width 0.0889)
		(layer "In4.Cu")
		(net "P5E_CPU1_PE4_RX_DN<6>")
	)
	(segment
		(start 93.180916 -300.513242)
		(end 93.831918 -296.824146)
		(width 0.14732)
		(layer "In4.Cu")
		(net "P5E_CPU1_PE4_RX_DN<6>")
	)
	(segment
		(start 96.148144 -290.051998)
		(end 96.148144 -289.645852)
		(width 0.0889)
		(layer "In4.Cu")
		(net "P5E_CPU1_PE4_RX_DN<6>")
	)
	(segment
		(start 93.832172 -296.8244)
		(end 93.832172 -292.992048)
		(width 0.14732)
		(layer "In4.Cu")
		(net "P5E_CPU1_PE4_RX_DN<6>")
	)
	(segment
		(start 93.874082 -292.32606)
		(end 96.148144 -290.051998)
		(width 0.0889)
		(layer "In4.Cu")
		(net "P5E_CPU1_PE4_RX_DN<6>")
	)
	(segment
		(start 66.468498 -411.016958)
		(end 66.468498 -406.19934)
		(width 0.14732)
		(layer "In4.Cu")
		(net "P5E_CPU1_PE4_RX_DN<6>")
	)
	(segment
		(start 68.185538 -396.755874)
		(end 64.813434 -349.012256)
		(width 0.14732)
		(layer "In4.Cu")
		(net "P5E_CPU1_PE4_RX_DN<6>")
	)
	(segment
		(start 69.983604 -434.027072)
		(end 69.69252 -433.735988)
		(width 0.14732)
		(layer "In4.Cu")
		(net "P5E_CPU1_PE4_RX_DN<6>")
	)
	(segment
		(start 66.468498 -406.19934)
		(end 68.185538 -404.4823)
		(width 0.14732)
		(layer "In4.Cu")
		(net "P5E_CPU1_PE4_RX_DN<6>")
	)
	(segment
		(start 64.835786 -333.187294)
		(end 67.896486 -325.797672)
		(width 0.14732)
		(layer "In4.Cu")
		(net "P5E_CPU1_PE4_RX_DN<6>")
	)
	(segment
		(start 93.832172 -292.992048)
		(end 93.832172 -292.96995)
		(width 0.0889)
		(layer "In4.Cu")
		(net "P5E_CPU1_PE4_RX_DN<6>")
	)
	(segment
		(start 70.6501 -434.174646)
		(end 70.502526 -434.027072)
		(width 0.14732)
		(layer "In4.Cu")
		(net "P5E_CPU1_PE4_RX_DN<6>")
	)
	(segment
		(start 69.69252 -417.025836)
		(end 66.468498 -411.016958)
		(width 0.14732)
		(layer "In4.Cu")
		(net "P5E_CPU1_PE4_RX_DN<6>")
	)
	(segment
		(start 93.831918 -296.824146)
		(end 93.832172 -296.8244)
		(width 0.14732)
		(layer "In4.Cu")
		(net "P5E_CPU1_PE4_RX_DN<6>")
	)
	(arc
		(start 96.148144 -289.645852)
		(mid 95.938609 -289.434449)
		(end 95.64116 -289.42157)
		(width 0.0889)
		(layer "In4.Cu")
		(net "P5E_CPU1_PE4_RX_DN<6>")
	)
	(segment
		(start 94.833694 -288.102802)
		(end 94.833948 -288.103056)
		(width 0.13208)
		(layer "F.Cu")
		(net "P5E_CPU1_PE4_RX_DN<5>")
	)
	(segment
		(start 94.833694 -287.567116)
		(end 94.833694 -288.102802)
		(width 0.13208)
		(layer "F.Cu")
		(net "P5E_CPU1_PE4_RX_DN<5>")
	)
	(segment
		(start 65.65011 -413.827722)
		(end 65.680844 -413.654494)
		(width 0.14732)
		(layer "In4.Cu")
		(net "P5E_CPU1_PE4_RX_DN<5>")
	)
	(segment
		(start 88.37295 -296.098722)
		(end 89.429844 -295.041828)
		(width 0.14732)
		(layer "In4.Cu")
		(net "P5E_CPU1_PE4_RX_DN<5>")
	)
	(segment
		(start 93.126814 -292.748462)
		(end 93.126814 -292.349428)
		(width 0.0889)
		(layer "In4.Cu")
		(net "P5E_CPU1_PE4_RX_DN<5>")
	)
	(segment
		(start 65.430654 -413.295846)
		(end 65.257426 -413.265112)
		(width 0.14732)
		(layer "In4.Cu")
		(net "P5E_CPU1_PE4_RX_DN<5>")
	)
	(segment
		(start 68.50253 -434.820314)
		(end 68.192904 -434.820314)
		(width 0.14732)
		(layer "In4.Cu")
		(net "P5E_CPU1_PE4_RX_DN<5>")
	)
	(segment
		(start 95.398844 -290.077398)
		(end 95.398844 -289.60953)
		(width 0.0889)
		(layer "In4.Cu")
		(net "P5E_CPU1_PE4_RX_DN<5>")
	)
	(segment
		(start 91.219274 -295.041828)
		(end 93.168978 -293.092124)
		(width 0.14732)
		(layer "In4.Cu")
		(net "P5E_CPU1_PE4_RX_DN<5>")
	)
	(segment
		(start 64.614806 -412.344362)
		(end 63.679578 -411.004512)
		(width 0.14732)
		(layer "In4.Cu")
		(net "P5E_CPU1_PE4_RX_DN<5>")
	)
	(segment
		(start 67.966844 -417.147502)
		(end 65.65011 -413.827722)
		(width 0.14732)
		(layer "In4.Cu")
		(net "P5E_CPU1_PE4_RX_DN<5>")
	)
	(segment
		(start 68.650104 -434.67274)
		(end 68.50253 -434.820314)
		(width 0.14732)
		(layer "In4.Cu")
		(net "P5E_CPU1_PE4_RX_DN<5>")
	)
	(segment
		(start 79.837788 -312.920634)
		(end 85.372448 -303.342802)
		(width 0.14732)
		(layer "In4.Cu")
		(net "P5E_CPU1_PE4_RX_DN<5>")
	)
	(segment
		(start 64.150494 -349.038672)
		(end 63.843662 -333.982568)
		(width 0.14732)
		(layer "In4.Cu")
		(net "P5E_CPU1_PE4_RX_DN<5>")
	)
	(segment
		(start 65.00749 -412.906972)
		(end 65.038224 -412.733744)
		(width 0.14732)
		(layer "In4.Cu")
		(net "P5E_CPU1_PE4_RX_DN<5>")
	)
	(segment
		(start 65.038224 -412.733744)
		(end 64.788034 -412.37535)
		(width 0.14732)
		(layer "In4.Cu")
		(net "P5E_CPU1_PE4_RX_DN<5>")
	)
	(segment
		(start 89.429844 -295.041828)
		(end 91.219274 -295.041828)
		(width 0.14732)
		(layer "In4.Cu")
		(net "P5E_CPU1_PE4_RX_DN<5>")
	)
	(segment
		(start 94.677484 -288.374074)
		(end 94.833948 -288.103056)
		(width 0.0889)
		(layer "In4.Cu")
		(net "P5E_CPU1_PE4_RX_DN<5>")
	)
	(segment
		(start 93.126814 -292.349428)
		(end 95.398844 -290.077398)
		(width 0.0889)
		(layer "In4.Cu")
		(net "P5E_CPU1_PE4_RX_DN<5>")
	)
	(segment
		(start 85.372448 -303.342802)
		(end 88.37295 -296.098722)
		(width 0.14732)
		(layer "In4.Cu")
		(net "P5E_CPU1_PE4_RX_DN<5>")
	)
	(segment
		(start 68.650104 -434.289962)
		(end 68.650104 -434.67274)
		(width 0.14732)
		(layer "In4.Cu")
		(net "P5E_CPU1_PE4_RX_DN<5>")
	)
	(segment
		(start 94.701614 -288.463228)
		(end 94.677484 -288.374074)
		(width 0.0889)
		(layer "In4.Cu")
		(net "P5E_CPU1_PE4_RX_DN<5>")
	)
	(segment
		(start 64.13627 -332.901544)
		(end 67.162172 -325.595996)
		(width 0.14732)
		(layer "In4.Cu")
		(net "P5E_CPU1_PE4_RX_DN<5>")
	)
	(segment
		(start 65.396618 -404.596092)
		(end 65.396618 -399.721832)
		(width 0.14732)
		(layer "In4.Cu")
		(net "P5E_CPU1_PE4_RX_DN<5>")
	)
	(segment
		(start 67.162172 -325.595996)
		(end 79.837788 -312.920634)
		(width 0.14732)
		(layer "In4.Cu")
		(net "P5E_CPU1_PE4_RX_DN<5>")
	)
	(segment
		(start 63.679578 -411.004512)
		(end 63.679578 -406.313132)
		(width 0.14732)
		(layer "In4.Cu")
		(net "P5E_CPU1_PE4_RX_DN<5>")
	)
	(segment
		(start 64.788034 -412.37535)
		(end 64.614806 -412.344362)
		(width 0.14732)
		(layer "In4.Cu")
		(net "P5E_CPU1_PE4_RX_DN<5>")
	)
	(segment
		(start 67.966844 -434.594254)
		(end 67.966844 -417.147502)
		(width 0.14732)
		(layer "In4.Cu")
		(net "P5E_CPU1_PE4_RX_DN<5>")
	)
	(segment
		(start 65.07099 -372.667276)
		(end 64.150494 -349.038672)
		(width 0.14732)
		(layer "In4.Cu")
		(net "P5E_CPU1_PE4_RX_DN<5>")
	)
	(segment
		(start 65.396618 -399.721832)
		(end 65.07099 -372.667276)
		(width 0.14732)
		(layer "In4.Cu")
		(net "P5E_CPU1_PE4_RX_DN<5>")
	)
	(segment
		(start 65.680844 -413.654494)
		(end 65.430654 -413.295846)
		(width 0.14732)
		(layer "In4.Cu")
		(net "P5E_CPU1_PE4_RX_DN<5>")
	)
	(segment
		(start 63.843662 -333.982568)
		(end 64.13627 -332.901544)
		(width 0.14732)
		(layer "In4.Cu")
		(net "P5E_CPU1_PE4_RX_DN<5>")
	)
	(segment
		(start 68.192904 -434.820314)
		(end 67.966844 -434.594254)
		(width 0.14732)
		(layer "In4.Cu")
		(net "P5E_CPU1_PE4_RX_DN<5>")
	)
	(segment
		(start 65.257426 -413.265112)
		(end 65.00749 -412.906972)
		(width 0.14732)
		(layer "In4.Cu")
		(net "P5E_CPU1_PE4_RX_DN<5>")
	)
	(segment
		(start 94.929198 -289.078416)
		(end 94.929198 -288.898584)
		(width 0.0889)
		(layer "In4.Cu")
		(net "P5E_CPU1_PE4_RX_DN<5>")
	)
	(segment
		(start 93.168978 -293.092124)
		(end 93.168978 -292.812724)
		(width 0.14732)
		(layer "In4.Cu")
		(net "P5E_CPU1_PE4_RX_DN<5>")
	)
	(segment
		(start 63.679578 -406.313132)
		(end 65.396618 -404.596092)
		(width 0.14732)
		(layer "In4.Cu")
		(net "P5E_CPU1_PE4_RX_DN<5>")
	)
	(segment
		(start 93.168978 -292.812724)
		(end 93.168978 -292.790626)
		(width 0.0889)
		(layer "In4.Cu")
		(net "P5E_CPU1_PE4_RX_DN<5>")
	)
	(segment
		(start 93.168978 -292.790626)
		(end 93.126814 -292.748462)
		(width 0.0889)
		(layer "In4.Cu")
		(net "P5E_CPU1_PE4_RX_DN<5>")
	)
	(arc
		(start 95.398844 -289.60953)
		(mid 95.287506 -289.41663)
		(end 95.113348 -289.277806)
		(width 0.0889)
		(layer "In4.Cu")
		(net "P5E_CPU1_PE4_RX_DN<5>")
	)
	(arc
		(start 94.929198 -288.898584)
		(mid 94.870048 -288.664497)
		(end 94.718632 -288.476436)
		(width 0.0889)
		(layer "In4.Cu")
		(net "P5E_CPU1_PE4_RX_DN<5>")
	)
	(arc
		(start 94.718632 -288.476436)
		(mid 94.710186 -288.469751)
		(end 94.701614 -288.463228)
		(width 0.0889)
		(layer "In4.Cu")
		(net "P5E_CPU1_PE4_RX_DN<5>")
	)
	(arc
		(start 95.113348 -289.277806)
		(mid 95.004201 -289.193878)
		(end 94.929198 -289.078416)
		(width 0.0889)
		(layer "In4.Cu")
		(net "P5E_CPU1_PE4_RX_DN<5>")
	)
	(segment
		(start 93.893894 -289.195002)
		(end 93.893894 -289.807142)
		(width 0.13208)
		(layer "F.Cu")
		(net "P5E_CPU1_PE4_RX_DN<4>")
	)
	(segment
		(start 91.890596 -292.312344)
		(end 92.159582 -292.043358)
		(width 0.14732)
		(layer "In4.Cu")
		(net "P5E_CPU1_PE4_RX_DN<4>")
	)
	(segment
		(start 60.342018 -410.863288)
		(end 60.342018 -406.19934)
		(width 0.14732)
		(layer "In4.Cu")
		(net "P5E_CPU1_PE4_RX_DN<4>")
	)
	(segment
		(start 92.175076 -292.027864)
		(end 92.234004 -292.027864)
		(width 0.0889)
		(layer "In4.Cu")
		(net "P5E_CPU1_PE4_RX_DN<4>")
	)
	(segment
		(start 62.621922 -332.900274)
		(end 65.703704 -325.461122)
		(width 0.14732)
		(layer "In4.Cu")
		(net "P5E_CPU1_PE4_RX_DN<4>")
	)
	(segment
		(start 65.680844 -417.590478)
		(end 64.882014 -416.3949)
		(width 0.14732)
		(layer "In4.Cu")
		(net "P5E_CPU1_PE4_RX_DN<4>")
	)
	(segment
		(start 88.933528 -293.815008)
		(end 90.386916 -293.815008)
		(width 0.14732)
		(layer "In4.Cu")
		(net "P5E_CPU1_PE4_RX_DN<4>")
	)
	(segment
		(start 84.295488 -302.792892)
		(end 87.364824 -295.383712)
		(width 0.14732)
		(layer "In4.Cu")
		(net "P5E_CPU1_PE4_RX_DN<4>")
	)
	(segment
		(start 66.375788 -324.459092)
		(end 79.166974 -311.667652)
		(width 0.14732)
		(layer "In4.Cu")
		(net "P5E_CPU1_PE4_RX_DN<4>")
	)
	(segment
		(start 64.882014 -416.3949)
		(end 61.62675 -412.42869)
		(width 0.14732)
		(layer "In4.Cu")
		(net "P5E_CPU1_PE4_RX_DN<4>")
	)
	(segment
		(start 92.33027 -291.931598)
		(end 94.268798 -289.993324)
		(width 0.0889)
		(layer "In4.Cu")
		(net "P5E_CPU1_PE4_RX_DN<4>")
	)
	(segment
		(start 93.76156 -289.42157)
		(end 93.735144 -289.506152)
		(width 0.0889)
		(layer "In4.Cu")
		(net "P5E_CPU1_PE4_RX_DN<4>")
	)
	(segment
		(start 65.692528 -417.602162)
		(end 65.680844 -417.590478)
		(width 0.14732)
		(layer "In4.Cu")
		(net "P5E_CPU1_PE4_RX_DN<4>")
	)
	(segment
		(start 65.692528 -433.749196)
		(end 65.692528 -417.602162)
		(width 0.14732)
		(layer "In4.Cu")
		(net "P5E_CPU1_PE4_RX_DN<4>")
	)
	(segment
		(start 65.970404 -434.027072)
		(end 65.692528 -433.749196)
		(width 0.14732)
		(layer "In4.Cu")
		(net "P5E_CPU1_PE4_RX_DN<4>")
	)
	(segment
		(start 90.386916 -293.815008)
		(end 91.88958 -292.312344)
		(width 0.14732)
		(layer "In4.Cu")
		(net "P5E_CPU1_PE4_RX_DN<4>")
	)
	(segment
		(start 61.62675 -412.42869)
		(end 61.62675 -412.428436)
		(width 0.14732)
		(layer "In4.Cu")
		(net "P5E_CPU1_PE4_RX_DN<4>")
	)
	(segment
		(start 60.342018 -406.19934)
		(end 62.059058 -404.4823)
		(width 0.14732)
		(layer "In4.Cu")
		(net "P5E_CPU1_PE4_RX_DN<4>")
	)
	(segment
		(start 66.650108 -434.48986)
		(end 66.650108 -434.174646)
		(width 0.14732)
		(layer "In4.Cu")
		(net "P5E_CPU1_PE4_RX_DN<4>")
	)
	(segment
		(start 65.703704 -325.461122)
		(end 66.375788 -324.459092)
		(width 0.14732)
		(layer "In4.Cu")
		(net "P5E_CPU1_PE4_RX_DN<4>")
	)
	(segment
		(start 79.166974 -311.667652)
		(end 84.295488 -302.792892)
		(width 0.14732)
		(layer "In4.Cu")
		(net "P5E_CPU1_PE4_RX_DN<4>")
	)
	(segment
		(start 62.059058 -404.4823)
		(end 62.059058 -400.472402)
		(width 0.14732)
		(layer "In4.Cu")
		(net "P5E_CPU1_PE4_RX_DN<4>")
	)
	(segment
		(start 91.88958 -292.312344)
		(end 91.890596 -292.312344)
		(width 0.14732)
		(layer "In4.Cu")
		(net "P5E_CPU1_PE4_RX_DN<4>")
	)
	(segment
		(start 61.62675 -412.428436)
		(end 60.342018 -410.863288)
		(width 0.14732)
		(layer "In4.Cu")
		(net "P5E_CPU1_PE4_RX_DN<4>")
	)
	(segment
		(start 94.268798 -289.993324)
		(end 94.268798 -289.64636)
		(width 0.0889)
		(layer "In4.Cu")
		(net "P5E_CPU1_PE4_RX_DN<4>")
	)
	(segment
		(start 94.268798 -289.64636)
		(end 94.268544 -289.645852)
		(width 0.0889)
		(layer "In4.Cu")
		(net "P5E_CPU1_PE4_RX_DN<4>")
	)
	(segment
		(start 66.650108 -434.174646)
		(end 66.502534 -434.027072)
		(width 0.14732)
		(layer "In4.Cu")
		(net "P5E_CPU1_PE4_RX_DN<4>")
	)
	(segment
		(start 87.364824 -295.383712)
		(end 88.933528 -293.815008)
		(width 0.14732)
		(layer "In4.Cu")
		(net "P5E_CPU1_PE4_RX_DN<4>")
	)
	(segment
		(start 92.159582 -292.043358)
		(end 92.175076 -292.027864)
		(width 0.0889)
		(layer "In4.Cu")
		(net "P5E_CPU1_PE4_RX_DN<4>")
	)
	(segment
		(start 62.988698 -372.674388)
		(end 62.621922 -332.900274)
		(width 0.14732)
		(layer "In4.Cu")
		(net "P5E_CPU1_PE4_RX_DN<4>")
	)
	(segment
		(start 93.735144 -289.506152)
		(end 93.893894 -289.807142)
		(width 0.0889)
		(layer "In4.Cu")
		(net "P5E_CPU1_PE4_RX_DN<4>")
	)
	(segment
		(start 92.234004 -292.027864)
		(end 92.33027 -291.931598)
		(width 0.0889)
		(layer "In4.Cu")
		(net "P5E_CPU1_PE4_RX_DN<4>")
	)
	(segment
		(start 66.502534 -434.027072)
		(end 65.970404 -434.027072)
		(width 0.14732)
		(layer "In4.Cu")
		(net "P5E_CPU1_PE4_RX_DN<4>")
	)
	(segment
		(start 62.059058 -400.472402)
		(end 62.988698 -372.674388)
		(width 0.14732)
		(layer "In4.Cu")
		(net "P5E_CPU1_PE4_RX_DN<4>")
	)
	(arc
		(start 94.268544 -289.645852)
		(mid 94.059009 -289.434449)
		(end 93.76156 -289.42157)
		(width 0.0889)
		(layer "In4.Cu")
		(net "P5E_CPU1_PE4_RX_DN<4>")
	)
	(segment
		(start 92.954094 -288.102802)
		(end 92.954348 -288.103056)
		(width 0.13208)
		(layer "F.Cu")
		(net "P5E_CPU1_PE4_RX_DN<3>")
	)
	(segment
		(start 92.954094 -287.567116)
		(end 92.954094 -288.102802)
		(width 0.13208)
		(layer "F.Cu")
		(net "P5E_CPU1_PE4_RX_DN<3>")
	)
	(segment
		(start 59.961526 -413.10941)
		(end 59.763914 -413.10941)
		(width 0.14732)
		(layer "In4.Cu")
		(net "P5E_CPU1_PE4_RX_DN<3>")
	)
	(segment
		(start 62.22238 -367.123726)
		(end 60.345574 -329.015598)
		(width 0.14732)
		(layer "In4.Cu")
		(net "P5E_CPU1_PE4_RX_DN<3>")
	)
	(segment
		(start 84.151724 -301.418244)
		(end 86.867492 -294.862504)
		(width 0.14732)
		(layer "In4.Cu")
		(net "P5E_CPU1_PE4_RX_DN<3>")
	)
	(segment
		(start 63.966852 -434.60543)
		(end 63.966852 -417.312348)
		(width 0.14732)
		(layer "In4.Cu")
		(net "P5E_CPU1_PE4_RX_DN<3>")
	)
	(segment
		(start 66.289174 -323.594222)
		(end 66.682112 -323.006212)
		(width 0.14732)
		(layer "In4.Cu")
		(net "P5E_CPU1_PE4_RX_DN<3>")
	)
	(segment
		(start 60.22213 -413.567626)
		(end 60.22213 -413.370014)
		(width 0.14732)
		(layer "In4.Cu")
		(net "P5E_CPU1_PE4_RX_DN<3>")
	)
	(segment
		(start 91.61145 -291.471858)
		(end 93.506544 -290.171378)
		(width 0.0889)
		(layer "In4.Cu")
		(net "P5E_CPU1_PE4_RX_DN<3>")
	)
	(segment
		(start 60.345574 -327.313798)
		(end 61.435742 -326.22363)
		(width 0.14732)
		(layer "In4.Cu")
		(net "P5E_CPU1_PE4_RX_DN<3>")
	)
	(segment
		(start 90.039698 -293.103554)
		(end 91.189048 -291.954204)
		(width 0.14732)
		(layer "In4.Cu")
		(net "P5E_CPU1_PE4_RX_DN<3>")
	)
	(segment
		(start 63.966852 -417.312348)
		(end 60.940696 -414.286192)
		(width 0.14732)
		(layer "In4.Cu")
		(net "P5E_CPU1_PE4_RX_DN<3>")
	)
	(segment
		(start 57.553098 -410.898594)
		(end 57.553098 -406.313132)
		(width 0.14732)
		(layer "In4.Cu")
		(net "P5E_CPU1_PE4_RX_DN<3>")
	)
	(segment
		(start 61.435742 -326.22363)
		(end 65.232534 -324.650608)
		(width 0.14732)
		(layer "In4.Cu")
		(net "P5E_CPU1_PE4_RX_DN<3>")
	)
	(segment
		(start 92.797884 -288.374074)
		(end 92.954348 -288.103056)
		(width 0.0889)
		(layer "In4.Cu")
		(net "P5E_CPU1_PE4_RX_DN<3>")
	)
	(segment
		(start 64.502538 -434.779674)
		(end 64.141096 -434.779674)
		(width 0.14732)
		(layer "In4.Cu")
		(net "P5E_CPU1_PE4_RX_DN<3>")
	)
	(segment
		(start 59.763914 -413.10941)
		(end 59.46521 -412.810706)
		(width 0.14732)
		(layer "In4.Cu")
		(net "P5E_CPU1_PE4_RX_DN<3>")
	)
	(segment
		(start 86.867492 -294.862504)
		(end 88.626442 -293.103554)
		(width 0.14732)
		(layer "In4.Cu")
		(net "P5E_CPU1_PE4_RX_DN<3>")
	)
	(segment
		(start 60.22213 -413.370014)
		(end 59.961526 -413.10941)
		(width 0.14732)
		(layer "In4.Cu")
		(net "P5E_CPU1_PE4_RX_DN<3>")
	)
	(segment
		(start 93.049598 -289.078416)
		(end 93.049598 -288.898584)
		(width 0.0889)
		(layer "In4.Cu")
		(net "P5E_CPU1_PE4_RX_DN<3>")
	)
	(segment
		(start 65.232534 -324.650608)
		(end 66.289174 -323.594222)
		(width 0.14732)
		(layer "In4.Cu")
		(net "P5E_CPU1_PE4_RX_DN<3>")
	)
	(segment
		(start 78.514702 -311.173622)
		(end 84.151724 -301.418244)
		(width 0.14732)
		(layer "In4.Cu")
		(net "P5E_CPU1_PE4_RX_DN<3>")
	)
	(segment
		(start 57.553098 -406.313132)
		(end 59.270138 -404.596092)
		(width 0.14732)
		(layer "In4.Cu")
		(net "P5E_CPU1_PE4_RX_DN<3>")
	)
	(segment
		(start 60.940696 -414.08858)
		(end 60.680092 -413.827976)
		(width 0.14732)
		(layer "In4.Cu")
		(net "P5E_CPU1_PE4_RX_DN<3>")
	)
	(segment
		(start 59.204606 -412.35249)
		(end 59.006994 -412.35249)
		(width 0.14732)
		(layer "In4.Cu")
		(net "P5E_CPU1_PE4_RX_DN<3>")
	)
	(segment
		(start 64.650112 -434.6321)
		(end 64.502538 -434.779674)
		(width 0.14732)
		(layer "In4.Cu")
		(net "P5E_CPU1_PE4_RX_DN<3>")
	)
	(segment
		(start 60.345574 -329.015598)
		(end 60.345574 -327.313798)
		(width 0.14732)
		(layer "In4.Cu")
		(net "P5E_CPU1_PE4_RX_DN<3>")
	)
	(segment
		(start 88.626442 -293.103554)
		(end 90.039698 -293.103554)
		(width 0.14732)
		(layer "In4.Cu")
		(net "P5E_CPU1_PE4_RX_DN<3>")
	)
	(segment
		(start 59.270138 -404.596092)
		(end 59.270138 -399.943574)
		(width 0.14732)
		(layer "In4.Cu")
		(net "P5E_CPU1_PE4_RX_DN<3>")
	)
	(segment
		(start 93.506544 -290.171378)
		(end 93.519244 -290.158678)
		(width 0.0889)
		(layer "In4.Cu")
		(net "P5E_CPU1_PE4_RX_DN<3>")
	)
	(segment
		(start 91.189048 -291.954204)
		(end 91.204542 -291.93871)
		(width 0.0889)
		(layer "In4.Cu")
		(net "P5E_CPU1_PE4_RX_DN<3>")
	)
	(segment
		(start 59.46521 -412.810706)
		(end 59.46521 -412.613094)
		(width 0.14732)
		(layer "In4.Cu")
		(net "P5E_CPU1_PE4_RX_DN<3>")
	)
	(segment
		(start 92.822014 -288.463228)
		(end 92.797884 -288.374074)
		(width 0.0889)
		(layer "In4.Cu")
		(net "P5E_CPU1_PE4_RX_DN<3>")
	)
	(segment
		(start 60.48248 -413.827976)
		(end 60.22213 -413.567626)
		(width 0.14732)
		(layer "In4.Cu")
		(net "P5E_CPU1_PE4_RX_DN<3>")
	)
	(segment
		(start 64.650112 -434.289962)
		(end 64.650112 -434.6321)
		(width 0.14732)
		(layer "In4.Cu")
		(net "P5E_CPU1_PE4_RX_DN<3>")
	)
	(segment
		(start 59.46521 -412.613094)
		(end 59.204606 -412.35249)
		(width 0.14732)
		(layer "In4.Cu")
		(net "P5E_CPU1_PE4_RX_DN<3>")
	)
	(segment
		(start 66.682112 -323.006212)
		(end 78.514702 -311.173622)
		(width 0.14732)
		(layer "In4.Cu")
		(net "P5E_CPU1_PE4_RX_DN<3>")
	)
	(segment
		(start 59.270138 -399.943574)
		(end 62.22238 -367.123726)
		(width 0.14732)
		(layer "In4.Cu")
		(net "P5E_CPU1_PE4_RX_DN<3>")
	)
	(segment
		(start 60.940696 -414.286192)
		(end 60.940696 -414.08858)
		(width 0.14732)
		(layer "In4.Cu")
		(net "P5E_CPU1_PE4_RX_DN<3>")
	)
	(segment
		(start 91.204542 -291.878766)
		(end 91.61145 -291.471858)
		(width 0.0889)
		(layer "In4.Cu")
		(net "P5E_CPU1_PE4_RX_DN<3>")
	)
	(segment
		(start 91.204542 -291.93871)
		(end 91.204542 -291.878766)
		(width 0.0889)
		(layer "In4.Cu")
		(net "P5E_CPU1_PE4_RX_DN<3>")
	)
	(segment
		(start 93.519244 -290.158678)
		(end 93.519244 -289.60953)
		(width 0.0889)
		(layer "In4.Cu")
		(net "P5E_CPU1_PE4_RX_DN<3>")
	)
	(segment
		(start 59.006994 -412.35249)
		(end 57.553098 -410.898594)
		(width 0.14732)
		(layer "In4.Cu")
		(net "P5E_CPU1_PE4_RX_DN<3>")
	)
	(segment
		(start 60.680092 -413.827976)
		(end 60.48248 -413.827976)
		(width 0.14732)
		(layer "In4.Cu")
		(net "P5E_CPU1_PE4_RX_DN<3>")
	)
	(segment
		(start 64.141096 -434.779674)
		(end 63.966852 -434.60543)
		(width 0.14732)
		(layer "In4.Cu")
		(net "P5E_CPU1_PE4_RX_DN<3>")
	)
	(arc
		(start 93.233748 -289.277806)
		(mid 93.124601 -289.193878)
		(end 93.049598 -289.078416)
		(width 0.0889)
		(layer "In4.Cu")
		(net "P5E_CPU1_PE4_RX_DN<3>")
	)
	(arc
		(start 92.839032 -288.476436)
		(mid 92.830586 -288.469751)
		(end 92.822014 -288.463228)
		(width 0.0889)
		(layer "In4.Cu")
		(net "P5E_CPU1_PE4_RX_DN<3>")
	)
	(arc
		(start 93.049598 -288.898584)
		(mid 92.990448 -288.664497)
		(end 92.839032 -288.476436)
		(width 0.0889)
		(layer "In4.Cu")
		(net "P5E_CPU1_PE4_RX_DN<3>")
	)
	(arc
		(start 93.503496 -289.569144)
		(mid 93.393497 -289.400435)
		(end 93.233748 -289.277806)
		(width 0.0889)
		(layer "In4.Cu")
		(net "P5E_CPU1_PE4_RX_DN<3>")
	)
	(arc
		(start 93.519244 -289.60953)
		(mid 93.511739 -289.589193)
		(end 93.503496 -289.569144)
		(width 0.0889)
		(layer "In4.Cu")
		(net "P5E_CPU1_PE4_RX_DN<3>")
	)
	(segment
		(start 92.014294 -289.807142)
		(end 92.014294 -289.195002)
		(width 0.13208)
		(layer "F.Cu")
		(net "P5E_CPU1_PE4_RX_DN<2>")
	)
	(segment
		(start 61.601096 -324.831202)
		(end 66.178938 -321.766946)
		(width 0.14732)
		(layer "In4.Cu")
		(net "P5E_CPU1_PE4_RX_DN<2>")
	)
	(segment
		(start 89.608406 -291.797994)
		(end 90.693494 -290.712906)
		(width 0.14732)
		(layer "In4.Cu")
		(net "P5E_CPU1_PE4_RX_DN<2>")
	)
	(segment
		(start 88.142064 -291.797994)
		(end 89.608406 -291.797994)
		(width 0.14732)
		(layer "In4.Cu")
		(net "P5E_CPU1_PE4_RX_DN<2>")
	)
	(segment
		(start 54.215538 -410.9085)
		(end 54.215538 -406.19934)
		(width 0.14732)
		(layer "In4.Cu")
		(net "P5E_CPU1_PE4_RX_DN<2>")
	)
	(segment
		(start 54.755796 -411.44825)
		(end 54.215538 -410.9085)
		(width 0.14732)
		(layer "In4.Cu")
		(net "P5E_CPU1_PE4_RX_DN<2>")
	)
	(segment
		(start 66.178938 -321.766946)
		(end 77.562202 -310.383428)
		(width 0.14732)
		(layer "In4.Cu")
		(net "P5E_CPU1_PE4_RX_DN<2>")
	)
	(segment
		(start 59.92241 -415.68878)
		(end 54.755796 -411.44825)
		(width 0.14732)
		(layer "In4.Cu")
		(net "P5E_CPU1_PE4_RX_DN<2>")
	)
	(segment
		(start 77.562202 -310.383428)
		(end 83.096608 -300.806358)
		(width 0.14732)
		(layer "In4.Cu")
		(net "P5E_CPU1_PE4_RX_DN<2>")
	)
	(segment
		(start 91.146376 -290.318952)
		(end 92.06357 -290.318952)
		(width 0.0889)
		(layer "In4.Cu")
		(net "P5E_CPU1_PE4_RX_DN<2>")
	)
	(segment
		(start 61.692536 -433.719224)
		(end 61.692536 -417.458652)
		(width 0.14732)
		(layer "In4.Cu")
		(net "P5E_CPU1_PE4_RX_DN<2>")
	)
	(segment
		(start 90.693494 -290.712906)
		(end 90.708988 -290.697412)
		(width 0.0889)
		(layer "In4.Cu")
		(net "P5E_CPU1_PE4_RX_DN<2>")
	)
	(segment
		(start 62.650116 -434.48986)
		(end 62.650116 -434.174646)
		(width 0.14732)
		(layer "In4.Cu")
		(net "P5E_CPU1_PE4_RX_DN<2>")
	)
	(segment
		(start 83.096608 -300.806358)
		(end 85.899244 -294.040814)
		(width 0.14732)
		(layer "In4.Cu")
		(net "P5E_CPU1_PE4_RX_DN<2>")
	)
	(segment
		(start 92.389198 -289.993324)
		(end 92.389198 -289.64636)
		(width 0.0889)
		(layer "In4.Cu")
		(net "P5E_CPU1_PE4_RX_DN<2>")
	)
	(segment
		(start 92.389198 -289.64636)
		(end 92.388944 -289.645852)
		(width 0.0889)
		(layer "In4.Cu")
		(net "P5E_CPU1_PE4_RX_DN<2>")
	)
	(segment
		(start 85.899244 -294.040814)
		(end 88.142064 -291.797994)
		(width 0.14732)
		(layer "In4.Cu")
		(net "P5E_CPU1_PE4_RX_DN<2>")
	)
	(segment
		(start 54.215538 -406.19934)
		(end 55.932578 -404.4823)
		(width 0.14732)
		(layer "In4.Cu")
		(net "P5E_CPU1_PE4_RX_DN<2>")
	)
	(segment
		(start 91.855544 -289.506152)
		(end 92.014294 -289.807142)
		(width 0.0889)
		(layer "In4.Cu")
		(net "P5E_CPU1_PE4_RX_DN<2>")
	)
	(segment
		(start 55.932578 -404.4823)
		(end 55.932578 -400.008598)
		(width 0.14732)
		(layer "In4.Cu")
		(net "P5E_CPU1_PE4_RX_DN<2>")
	)
	(segment
		(start 62.502542 -434.027072)
		(end 62.000384 -434.027072)
		(width 0.14732)
		(layer "In4.Cu")
		(net "P5E_CPU1_PE4_RX_DN<2>")
	)
	(segment
		(start 92.06357 -290.318952)
		(end 92.389198 -289.993324)
		(width 0.0889)
		(layer "In4.Cu")
		(net "P5E_CPU1_PE4_RX_DN<2>")
	)
	(segment
		(start 90.708988 -290.697412)
		(end 90.767916 -290.697412)
		(width 0.0889)
		(layer "In4.Cu")
		(net "P5E_CPU1_PE4_RX_DN<2>")
	)
	(segment
		(start 61.692536 -417.458652)
		(end 59.92241 -415.68878)
		(width 0.14732)
		(layer "In4.Cu")
		(net "P5E_CPU1_PE4_RX_DN<2>")
	)
	(segment
		(start 55.932578 -400.008598)
		(end 60.989718 -366.633506)
		(width 0.14732)
		(layer "In4.Cu")
		(net "P5E_CPU1_PE4_RX_DN<2>")
	)
	(segment
		(start 60.989718 -366.633506)
		(end 59.119008 -329.446636)
		(width 0.14732)
		(layer "In4.Cu")
		(net "P5E_CPU1_PE4_RX_DN<2>")
	)
	(segment
		(start 60.679838 -325.212202)
		(end 61.601096 -324.831202)
		(width 0.14732)
		(layer "In4.Cu")
		(net "P5E_CPU1_PE4_RX_DN<2>")
	)
	(segment
		(start 59.119008 -329.446636)
		(end 59.119008 -326.773032)
		(width 0.14732)
		(layer "In4.Cu")
		(net "P5E_CPU1_PE4_RX_DN<2>")
	)
	(segment
		(start 62.000384 -434.027072)
		(end 61.692536 -433.719224)
		(width 0.14732)
		(layer "In4.Cu")
		(net "P5E_CPU1_PE4_RX_DN<2>")
	)
	(segment
		(start 91.88196 -289.42157)
		(end 91.855544 -289.506152)
		(width 0.0889)
		(layer "In4.Cu")
		(net "P5E_CPU1_PE4_RX_DN<2>")
	)
	(segment
		(start 62.650116 -434.174646)
		(end 62.502542 -434.027072)
		(width 0.14732)
		(layer "In4.Cu")
		(net "P5E_CPU1_PE4_RX_DN<2>")
	)
	(segment
		(start 59.119008 -326.773032)
		(end 60.679838 -325.212202)
		(width 0.14732)
		(layer "In4.Cu")
		(net "P5E_CPU1_PE4_RX_DN<2>")
	)
	(segment
		(start 90.767916 -290.697412)
		(end 91.146376 -290.318952)
		(width 0.0889)
		(layer "In4.Cu")
		(net "P5E_CPU1_PE4_RX_DN<2>")
	)
	(arc
		(start 92.388944 -289.645852)
		(mid 92.179409 -289.434449)
		(end 91.88196 -289.42157)
		(width 0.0889)
		(layer "In4.Cu")
		(net "P5E_CPU1_PE4_RX_DN<2>")
	)
	(segment
		(start 91.074494 -287.567116)
		(end 91.074494 -288.103056)
		(width 0.13208)
		(layer "F.Cu")
		(net "P5E_CPU1_PE4_RX_DN<1>")
	)
	(segment
		(start 56.817768 -414.399984)
		(end 56.621172 -414.419288)
		(width 0.14732)
		(layer "In4.Cu")
		(net "P5E_CPU1_PE4_RX_DN<1>")
	)
	(segment
		(start 60.281058 -324.63486)
		(end 61.33465 -324.198234)
		(width 0.14732)
		(layer "In4.Cu")
		(net "P5E_CPU1_PE4_RX_DN<1>")
	)
	(segment
		(start 90.500962 -289.841178)
		(end 90.910918 -289.431476)
		(width 0.0889)
		(layer "In4.Cu")
		(net "P5E_CPU1_PE4_RX_DN<1>")
	)
	(segment
		(start 83.964018 -296.995596)
		(end 85.350096 -293.648638)
		(width 0.14732)
		(layer "In4.Cu")
		(net "P5E_CPU1_PE4_RX_DN<1>")
	)
	(segment
		(start 58.4454 -326.470518)
		(end 60.281058 -324.63486)
		(width 0.14732)
		(layer "In4.Cu")
		(net "P5E_CPU1_PE4_RX_DN<1>")
	)
	(segment
		(start 60.502546 -434.80228)
		(end 60.16371 -434.80228)
		(width 0.14732)
		(layer "In4.Cu")
		(net "P5E_CPU1_PE4_RX_DN<1>")
	)
	(segment
		(start 56.621172 -414.419288)
		(end 56.336692 -414.185862)
		(width 0.14732)
		(layer "In4.Cu")
		(net "P5E_CPU1_PE4_RX_DN<1>")
	)
	(segment
		(start 56.317134 -413.989266)
		(end 56.032146 -413.755332)
		(width 0.14732)
		(layer "In4.Cu")
		(net "P5E_CPU1_PE4_RX_DN<1>")
	)
	(segment
		(start 90.208354 -290.133786)
		(end 90.500962 -289.841178)
		(width 0.0889)
		(layer "In4.Cu")
		(net "P5E_CPU1_PE4_RX_DN<1>")
	)
	(segment
		(start 76.97978 -310.02986)
		(end 82.577178 -300.343316)
		(width 0.14732)
		(layer "In4.Cu")
		(net "P5E_CPU1_PE4_RX_DN<1>")
	)
	(segment
		(start 90.208354 -290.19373)
		(end 90.208354 -290.133786)
		(width 0.0889)
		(layer "In4.Cu")
		(net "P5E_CPU1_PE4_RX_DN<1>")
	)
	(segment
		(start 53.143658 -400.024854)
		(end 60.31992 -366.527588)
		(width 0.14732)
		(layer "In4.Cu")
		(net "P5E_CPU1_PE4_RX_DN<1>")
	)
	(segment
		(start 51.426618 -410.543502)
		(end 51.426618 -406.313132)
		(width 0.14732)
		(layer "In4.Cu")
		(net "P5E_CPU1_PE4_RX_DN<1>")
	)
	(segment
		(start 56.336692 -414.185862)
		(end 56.317134 -413.989266)
		(width 0.14732)
		(layer "In4.Cu")
		(net "P5E_CPU1_PE4_RX_DN<1>")
	)
	(segment
		(start 60.16371 -434.80228)
		(end 59.96686 -434.60543)
		(width 0.14732)
		(layer "In4.Cu")
		(net "P5E_CPU1_PE4_RX_DN<1>")
	)
	(segment
		(start 53.143658 -404.596092)
		(end 53.143658 -400.024854)
		(width 0.14732)
		(layer "In4.Cu")
		(net "P5E_CPU1_PE4_RX_DN<1>")
	)
	(segment
		(start 55.480712 -413.322516)
		(end 55.142638 -413.045148)
		(width 0.14732)
		(layer "In4.Cu")
		(net "P5E_CPU1_PE4_RX_DN<1>")
	)
	(segment
		(start 65.786508 -321.222878)
		(end 76.97978 -310.02986)
		(width 0.14732)
		(layer "In4.Cu")
		(net "P5E_CPU1_PE4_RX_DN<1>")
	)
	(segment
		(start 54.967632 -413.062166)
		(end 53.440076 -411.808676)
		(width 0.14732)
		(layer "In4.Cu")
		(net "P5E_CPU1_PE4_RX_DN<1>")
	)
	(segment
		(start 60.31992 -366.527588)
		(end 58.4454 -329.750166)
		(width 0.14732)
		(layer "In4.Cu")
		(net "P5E_CPU1_PE4_RX_DN<1>")
	)
	(segment
		(start 91.169998 -289.114484)
		(end 91.169998 -288.902902)
		(width 0.0889)
		(layer "In4.Cu")
		(net "P5E_CPU1_PE4_RX_DN<1>")
	)
	(segment
		(start 51.426618 -406.313132)
		(end 53.143658 -404.596092)
		(width 0.14732)
		(layer "In4.Cu")
		(net "P5E_CPU1_PE4_RX_DN<1>")
	)
	(segment
		(start 55.497984 -413.497522)
		(end 55.480712 -413.322516)
		(width 0.14732)
		(layer "In4.Cu")
		(net "P5E_CPU1_PE4_RX_DN<1>")
	)
	(segment
		(start 87.938356 -291.060378)
		(end 89.34069 -291.060378)
		(width 0.14732)
		(layer "In4.Cu")
		(net "P5E_CPU1_PE4_RX_DN<1>")
	)
	(segment
		(start 58.964068 -416.342068)
		(end 57.122314 -414.830514)
		(width 0.14732)
		(layer "In4.Cu")
		(net "P5E_CPU1_PE4_RX_DN<1>")
	)
	(segment
		(start 59.96686 -434.60543)
		(end 59.96686 -417.34486)
		(width 0.14732)
		(layer "In4.Cu")
		(net "P5E_CPU1_PE4_RX_DN<1>")
	)
	(segment
		(start 51.705256 -411.09011)
		(end 51.531012 -410.896816)
		(width 0.14732)
		(layer "In4.Cu")
		(net "P5E_CPU1_PE4_RX_DN<1>")
	)
	(segment
		(start 90.91803 -288.374074)
		(end 91.074494 -288.103056)
		(width 0.0889)
		(layer "In4.Cu")
		(net "P5E_CPU1_PE4_RX_DN<1>")
	)
	(segment
		(start 90.94216 -288.463228)
		(end 90.91803 -288.374074)
		(width 0.0889)
		(layer "In4.Cu")
		(net "P5E_CPU1_PE4_RX_DN<1>")
	)
	(segment
		(start 82.577178 -300.343316)
		(end 83.963764 -296.995596)
		(width 0.14732)
		(layer "In4.Cu")
		(net "P5E_CPU1_PE4_RX_DN<1>")
	)
	(segment
		(start 53.440076 -411.808676)
		(end 51.705256 -411.09011)
		(width 0.14732)
		(layer "In4.Cu")
		(net "P5E_CPU1_PE4_RX_DN<1>")
	)
	(segment
		(start 56.032146 -413.755332)
		(end 55.83555 -413.774636)
		(width 0.14732)
		(layer "In4.Cu")
		(net "P5E_CPU1_PE4_RX_DN<1>")
	)
	(segment
		(start 60.65012 -434.654706)
		(end 60.502546 -434.80228)
		(width 0.14732)
		(layer "In4.Cu")
		(net "P5E_CPU1_PE4_RX_DN<1>")
	)
	(segment
		(start 58.4454 -329.750166)
		(end 58.4454 -326.470518)
		(width 0.14732)
		(layer "In4.Cu")
		(net "P5E_CPU1_PE4_RX_DN<1>")
	)
	(segment
		(start 59.96686 -417.34486)
		(end 58.964068 -416.342068)
		(width 0.14732)
		(layer "In4.Cu")
		(net "P5E_CPU1_PE4_RX_DN<1>")
	)
	(segment
		(start 89.34069 -291.060378)
		(end 90.021664 -290.379404)
		(width 0.14732)
		(layer "In4.Cu")
		(net "P5E_CPU1_PE4_RX_DN<1>")
	)
	(segment
		(start 90.021664 -290.379404)
		(end 90.02268 -290.379404)
		(width 0.14732)
		(layer "In4.Cu")
		(net "P5E_CPU1_PE4_RX_DN<1>")
	)
	(segment
		(start 55.83555 -413.774636)
		(end 55.497984 -413.497522)
		(width 0.14732)
		(layer "In4.Cu")
		(net "P5E_CPU1_PE4_RX_DN<1>")
	)
	(segment
		(start 90.02268 -290.379404)
		(end 90.19286 -290.209224)
		(width 0.14732)
		(layer "In4.Cu")
		(net "P5E_CPU1_PE4_RX_DN<1>")
	)
	(segment
		(start 55.142638 -413.045148)
		(end 54.967632 -413.062166)
		(width 0.14732)
		(layer "In4.Cu")
		(net "P5E_CPU1_PE4_RX_DN<1>")
	)
	(segment
		(start 57.122314 -414.830514)
		(end 57.102756 -414.633918)
		(width 0.14732)
		(layer "In4.Cu")
		(net "P5E_CPU1_PE4_RX_DN<1>")
	)
	(segment
		(start 61.33465 -324.198234)
		(end 65.786508 -321.222878)
		(width 0.14732)
		(layer "In4.Cu")
		(net "P5E_CPU1_PE4_RX_DN<1>")
	)
	(segment
		(start 90.19286 -290.209224)
		(end 90.208354 -290.19373)
		(width 0.0889)
		(layer "In4.Cu")
		(net "P5E_CPU1_PE4_RX_DN<1>")
	)
	(segment
		(start 85.350096 -293.648638)
		(end 87.938356 -291.060378)
		(width 0.14732)
		(layer "In4.Cu")
		(net "P5E_CPU1_PE4_RX_DN<1>")
	)
	(segment
		(start 57.102756 -414.633918)
		(end 56.817768 -414.399984)
		(width 0.14732)
		(layer "In4.Cu")
		(net "P5E_CPU1_PE4_RX_DN<1>")
	)
	(segment
		(start 51.531012 -410.896816)
		(end 51.426618 -410.543502)
		(width 0.14732)
		(layer "In4.Cu")
		(net "P5E_CPU1_PE4_RX_DN<1>")
	)
	(segment
		(start 60.65012 -434.289962)
		(end 60.65012 -434.654706)
		(width 0.14732)
		(layer "In4.Cu")
		(net "P5E_CPU1_PE4_RX_DN<1>")
	)
	(segment
		(start 83.963764 -296.995596)
		(end 83.964018 -296.995596)
		(width 0.14732)
		(layer "In4.Cu")
		(net "P5E_CPU1_PE4_RX_DN<1>")
	)
	(arc
		(start 90.910918 -289.431476)
		(mid 91.068361 -289.295796)
		(end 91.169998 -289.114484)
		(width 0.0889)
		(layer "In4.Cu")
		(net "P5E_CPU1_PE4_RX_DN<1>")
	)
	(arc
		(start 91.169998 -288.902902)
		(mid 91.111653 -288.666397)
		(end 90.959178 -288.476436)
		(width 0.0889)
		(layer "In4.Cu")
		(net "P5E_CPU1_PE4_RX_DN<1>")
	)
	(arc
		(start 90.959178 -288.476436)
		(mid 90.950732 -288.469751)
		(end 90.94216 -288.463228)
		(width 0.0889)
		(layer "In4.Cu")
		(net "P5E_CPU1_PE4_RX_DN<1>")
	)
	(segment
		(start 104.231694 -288.102802)
		(end 104.231948 -288.103056)
		(width 0.13208)
		(layer "F.Cu")
		(net "P5E_CPU1_PE4_RX_DN<15>")
	)
	(segment
		(start 104.231694 -287.567116)
		(end 104.231694 -288.102802)
		(width 0.13208)
		(layer "F.Cu")
		(net "P5E_CPU1_PE4_RX_DN<15>")
	)
	(segment
		(start 104.79659 -289.610292)
		(end 104.79659 -291.139118)
		(width 0.0889)
		(layer "In4.Cu")
		(net "P5E_CPU1_PE4_RX_DN<15>")
	)
	(segment
		(start 103.138732 -293.436548)
		(end 103.138732 -293.458646)
		(width 0.0889)
		(layer "In4.Cu")
		(net "P5E_CPU1_PE4_RX_DN<15>")
	)
	(segment
		(start 90.211402 -421.574468)
		(end 89.932764 -422.261284)
		(width 0.14732)
		(layer "In4.Cu")
		(net "P5E_CPU1_PE4_RX_DN<15>")
	)
	(segment
		(start 89.502488 -434.75275)
		(end 89.650062 -434.605176)
		(width 0.14732)
		(layer "In4.Cu")
		(net "P5E_CPU1_PE4_RX_DN<15>")
	)
	(segment
		(start 104.511348 -289.277806)
		(end 104.511094 -289.27806)
		(width 0.0889)
		(layer "In4.Cu")
		(net "P5E_CPU1_PE4_RX_DN<15>")
	)
	(segment
		(start 89.114122 -434.75275)
		(end 89.502488 -434.75275)
		(width 0.14732)
		(layer "In4.Cu")
		(net "P5E_CPU1_PE4_RX_DN<15>")
	)
	(segment
		(start 89.62771 -423.384726)
		(end 89.48928 -423.726356)
		(width 0.14732)
		(layer "In4.Cu")
		(net "P5E_CPU1_PE4_RX_DN<15>")
	)
	(segment
		(start 102.019608 -303.992788)
		(end 76.267818 -329.744578)
		(width 0.14732)
		(layer "In4.Cu")
		(net "P5E_CPU1_PE4_RX_DN<15>")
	)
	(segment
		(start 74.817224 -351.971864)
		(end 82.555842 -371.859048)
		(width 0.14732)
		(layer "In4.Cu")
		(net "P5E_CPU1_PE4_RX_DN<15>")
	)
	(segment
		(start 103.138732 -293.458646)
		(end 103.138732 -297.646598)
		(width 0.14732)
		(layer "In4.Cu")
		(net "P5E_CPU1_PE4_RX_DN<15>")
	)
	(segment
		(start 73.857358 -335.563464)
		(end 73.75525 -336.185256)
		(width 0.14732)
		(layer "In4.Cu")
		(net "P5E_CPU1_PE4_RX_DN<15>")
	)
	(segment
		(start 104.075484 -288.374074)
		(end 104.099614 -288.463228)
		(width 0.0889)
		(layer "In4.Cu")
		(net "P5E_CPU1_PE4_RX_DN<15>")
	)
	(segment
		(start 88.966802 -424.642026)
		(end 88.966802 -434.60543)
		(width 0.14732)
		(layer "In4.Cu")
		(net "P5E_CPU1_PE4_RX_DN<15>")
	)
	(segment
		(start 96.029018 -399.681192)
		(end 96.029018 -404.596092)
		(width 0.14732)
		(layer "In4.Cu")
		(net "P5E_CPU1_PE4_RX_DN<15>")
	)
	(segment
		(start 89.871296 -422.784778)
		(end 89.689178 -422.86174)
		(width 0.14732)
		(layer "In4.Cu")
		(net "P5E_CPU1_PE4_RX_DN<15>")
	)
	(segment
		(start 103.096568 -293.394384)
		(end 103.138732 -293.436548)
		(width 0.0889)
		(layer "In4.Cu")
		(net "P5E_CPU1_PE4_RX_DN<15>")
	)
	(segment
		(start 76.267818 -329.744578)
		(end 73.857358 -335.563464)
		(width 0.14732)
		(layer "In4.Cu")
		(net "P5E_CPU1_PE4_RX_DN<15>")
	)
	(segment
		(start 89.689178 -422.86174)
		(end 89.550748 -423.202862)
		(width 0.14732)
		(layer "In4.Cu")
		(net "P5E_CPU1_PE4_RX_DN<15>")
	)
	(segment
		(start 90.53195 -421.15613)
		(end 90.39352 -421.497506)
		(width 0.14732)
		(layer "In4.Cu")
		(net "P5E_CPU1_PE4_RX_DN<15>")
	)
	(segment
		(start 104.231948 -288.103056)
		(end 104.075484 -288.374074)
		(width 0.0889)
		(layer "In4.Cu")
		(net "P5E_CPU1_PE4_RX_DN<15>")
	)
	(segment
		(start 90.455242 -420.974012)
		(end 90.53195 -421.15613)
		(width 0.14732)
		(layer "In4.Cu")
		(net "P5E_CPU1_PE4_RX_DN<15>")
	)
	(segment
		(start 103.138732 -297.646598)
		(end 102.019608 -303.992788)
		(width 0.14732)
		(layer "In4.Cu")
		(net "P5E_CPU1_PE4_RX_DN<15>")
	)
	(segment
		(start 103.096568 -292.83914)
		(end 103.096568 -293.394384)
		(width 0.0889)
		(layer "In4.Cu")
		(net "P5E_CPU1_PE4_RX_DN<15>")
	)
	(segment
		(start 94.311978 -406.313132)
		(end 94.311978 -411.468062)
		(width 0.14732)
		(layer "In4.Cu")
		(net "P5E_CPU1_PE4_RX_DN<15>")
	)
	(segment
		(start 90.39352 -421.497506)
		(end 90.211402 -421.574468)
		(width 0.14732)
		(layer "In4.Cu")
		(net "P5E_CPU1_PE4_RX_DN<15>")
	)
	(segment
		(start 104.79659 -291.139118)
		(end 103.096568 -292.83914)
		(width 0.0889)
		(layer "In4.Cu")
		(net "P5E_CPU1_PE4_RX_DN<15>")
	)
	(segment
		(start 96.029018 -404.596092)
		(end 94.311978 -406.313132)
		(width 0.14732)
		(layer "In4.Cu")
		(net "P5E_CPU1_PE4_RX_DN<15>")
	)
	(segment
		(start 89.932764 -422.261284)
		(end 90.009726 -422.443148)
		(width 0.14732)
		(layer "In4.Cu")
		(net "P5E_CPU1_PE4_RX_DN<15>")
	)
	(segment
		(start 94.311978 -411.468062)
		(end 90.455242 -420.974012)
		(width 0.14732)
		(layer "In4.Cu")
		(net "P5E_CPU1_PE4_RX_DN<15>")
	)
	(segment
		(start 88.966802 -434.60543)
		(end 89.114122 -434.75275)
		(width 0.14732)
		(layer "In4.Cu")
		(net "P5E_CPU1_PE4_RX_DN<15>")
	)
	(segment
		(start 89.650062 -434.605176)
		(end 89.650062 -434.289962)
		(width 0.14732)
		(layer "In4.Cu")
		(net "P5E_CPU1_PE4_RX_DN<15>")
	)
	(segment
		(start 90.009726 -422.443148)
		(end 89.871296 -422.784778)
		(width 0.14732)
		(layer "In4.Cu")
		(net "P5E_CPU1_PE4_RX_DN<15>")
	)
	(segment
		(start 89.48928 -423.726356)
		(end 89.307162 -423.803318)
		(width 0.14732)
		(layer "In4.Cu")
		(net "P5E_CPU1_PE4_RX_DN<15>")
	)
	(segment
		(start 82.555842 -371.859048)
		(end 96.029018 -399.681192)
		(width 0.14732)
		(layer "In4.Cu")
		(net "P5E_CPU1_PE4_RX_DN<15>")
	)
	(segment
		(start 73.75525 -336.185256)
		(end 74.817224 -351.971864)
		(width 0.14732)
		(layer "In4.Cu")
		(net "P5E_CPU1_PE4_RX_DN<15>")
	)
	(segment
		(start 89.307162 -423.803318)
		(end 88.966802 -424.642026)
		(width 0.14732)
		(layer "In4.Cu")
		(net "P5E_CPU1_PE4_RX_DN<15>")
	)
	(segment
		(start 89.550748 -423.202862)
		(end 89.62771 -423.384726)
		(width 0.14732)
		(layer "In4.Cu")
		(net "P5E_CPU1_PE4_RX_DN<15>")
	)
	(segment
		(start 104.327198 -288.898584)
		(end 104.327198 -289.078416)
		(width 0.0889)
		(layer "In4.Cu")
		(net "P5E_CPU1_PE4_RX_DN<15>")
	)
	(arc
		(start 104.099614 -288.463228)
		(mid 104.108186 -288.469751)
		(end 104.116632 -288.476436)
		(width 0.0889)
		(layer "In4.Cu")
		(net "P5E_CPU1_PE4_RX_DN<15>")
	)
	(arc
		(start 104.327198 -289.078416)
		(mid 104.402203 -289.193875)
		(end 104.511348 -289.277806)
		(width 0.0889)
		(layer "In4.Cu")
		(net "P5E_CPU1_PE4_RX_DN<15>")
	)
	(arc
		(start 104.511094 -289.27806)
		(mid 104.685339 -289.417106)
		(end 104.79659 -289.610292)
		(width 0.0889)
		(layer "In4.Cu")
		(net "P5E_CPU1_PE4_RX_DN<15>")
	)
	(arc
		(start 104.116632 -288.476436)
		(mid 104.268036 -288.664503)
		(end 104.327198 -288.898584)
		(width 0.0889)
		(layer "In4.Cu")
		(net "P5E_CPU1_PE4_RX_DN<15>")
	)
	(segment
		(start 103.291894 -289.195002)
		(end 103.291894 -289.807142)
		(width 0.13208)
		(layer "F.Cu")
		(net "P5E_CPU1_PE4_RX_DN<14>")
	)
	(segment
		(start 101.934772 -297.389296)
		(end 101.934772 -293.458646)
		(width 0.14732)
		(layer "In4.Cu")
		(net "P5E_CPU1_PE4_RX_DN<14>")
	)
	(segment
		(start 80.472788 -371.96014)
		(end 73.482708 -352.108008)
		(width 0.14732)
		(layer "In4.Cu")
		(net "P5E_CPU1_PE4_RX_DN<14>")
	)
	(segment
		(start 101.976682 -293.394638)
		(end 101.976682 -292.46322)
		(width 0.0889)
		(layer "In4.Cu")
		(net "P5E_CPU1_PE4_RX_DN<14>")
	)
	(segment
		(start 75.066398 -329.242928)
		(end 100.86721 -303.442116)
		(width 0.14732)
		(layer "In4.Cu")
		(net "P5E_CPU1_PE4_RX_DN<14>")
	)
	(segment
		(start 86.691978 -433.7177)
		(end 86.691978 -423.856404)
		(width 0.14732)
		(layer "In4.Cu")
		(net "P5E_CPU1_PE4_RX_DN<14>")
	)
	(segment
		(start 103.15956 -289.42157)
		(end 103.133144 -289.506152)
		(width 0.0889)
		(layer "In4.Cu")
		(net "P5E_CPU1_PE4_RX_DN<14>")
	)
	(segment
		(start 86.691978 -423.856404)
		(end 90.974418 -411.333696)
		(width 0.14732)
		(layer "In4.Cu")
		(net "P5E_CPU1_PE4_RX_DN<14>")
	)
	(segment
		(start 87.502492 -434.027072)
		(end 87.00135 -434.027072)
		(width 0.14732)
		(layer "In4.Cu")
		(net "P5E_CPU1_PE4_RX_DN<14>")
	)
	(segment
		(start 103.133144 -289.506152)
		(end 103.291894 -289.807142)
		(width 0.0889)
		(layer "In4.Cu")
		(net "P5E_CPU1_PE4_RX_DN<14>")
	)
	(segment
		(start 101.934772 -293.458646)
		(end 101.934772 -293.436548)
		(width 0.0889)
		(layer "In4.Cu")
		(net "P5E_CPU1_PE4_RX_DN<14>")
	)
	(segment
		(start 87.650066 -434.174646)
		(end 87.502492 -434.027072)
		(width 0.14732)
		(layer "In4.Cu")
		(net "P5E_CPU1_PE4_RX_DN<14>")
	)
	(segment
		(start 92.691458 -399.76425)
		(end 80.472788 -371.96014)
		(width 0.14732)
		(layer "In4.Cu")
		(net "P5E_CPU1_PE4_RX_DN<14>")
	)
	(segment
		(start 101.976682 -292.46322)
		(end 103.666544 -290.773358)
		(width 0.0889)
		(layer "In4.Cu")
		(net "P5E_CPU1_PE4_RX_DN<14>")
	)
	(segment
		(start 101.934772 -293.436548)
		(end 101.976682 -293.394638)
		(width 0.0889)
		(layer "In4.Cu")
		(net "P5E_CPU1_PE4_RX_DN<14>")
	)
	(segment
		(start 72.636126 -335.110328)
		(end 75.066398 -329.242928)
		(width 0.14732)
		(layer "In4.Cu")
		(net "P5E_CPU1_PE4_RX_DN<14>")
	)
	(segment
		(start 87.650066 -434.48986)
		(end 87.650066 -434.174646)
		(width 0.14732)
		(layer "In4.Cu")
		(net "P5E_CPU1_PE4_RX_DN<14>")
	)
	(segment
		(start 100.86721 -303.442116)
		(end 101.934772 -297.389296)
		(width 0.14732)
		(layer "In4.Cu")
		(net "P5E_CPU1_PE4_RX_DN<14>")
	)
	(segment
		(start 73.482708 -352.108008)
		(end 73.474326 -352.064066)
		(width 0.14732)
		(layer "In4.Cu")
		(net "P5E_CPU1_PE4_RX_DN<14>")
	)
	(segment
		(start 90.974418 -411.333696)
		(end 90.974418 -406.19934)
		(width 0.14732)
		(layer "In4.Cu")
		(net "P5E_CPU1_PE4_RX_DN<14>")
	)
	(segment
		(start 87.00135 -434.027072)
		(end 86.691978 -433.7177)
		(width 0.14732)
		(layer "In4.Cu")
		(net "P5E_CPU1_PE4_RX_DN<14>")
	)
	(segment
		(start 73.474326 -352.064066)
		(end 72.491346 -335.975452)
		(width 0.14732)
		(layer "In4.Cu")
		(net "P5E_CPU1_PE4_RX_DN<14>")
	)
	(segment
		(start 72.491346 -335.975452)
		(end 72.636126 -335.110328)
		(width 0.14732)
		(layer "In4.Cu")
		(net "P5E_CPU1_PE4_RX_DN<14>")
	)
	(segment
		(start 103.666544 -290.773358)
		(end 103.666544 -289.645852)
		(width 0.0889)
		(layer "In4.Cu")
		(net "P5E_CPU1_PE4_RX_DN<14>")
	)
	(segment
		(start 90.974418 -406.19934)
		(end 92.691458 -404.4823)
		(width 0.14732)
		(layer "In4.Cu")
		(net "P5E_CPU1_PE4_RX_DN<14>")
	)
	(segment
		(start 92.691458 -404.4823)
		(end 92.691458 -399.76425)
		(width 0.14732)
		(layer "In4.Cu")
		(net "P5E_CPU1_PE4_RX_DN<14>")
	)
	(arc
		(start 103.666544 -289.645852)
		(mid 103.457009 -289.434449)
		(end 103.15956 -289.42157)
		(width 0.0889)
		(layer "In4.Cu")
		(net "P5E_CPU1_PE4_RX_DN<14>")
	)
	(segment
		(start 102.352094 -287.567116)
		(end 102.352094 -288.102802)
		(width 0.13208)
		(layer "F.Cu")
		(net "P5E_CPU1_PE4_RX_DN<13>")
	)
	(segment
		(start 102.352094 -288.102802)
		(end 102.352348 -288.103056)
		(width 0.13208)
		(layer "F.Cu")
		(net "P5E_CPU1_PE4_RX_DN<13>")
	)
	(segment
		(start 102.195884 -288.374074)
		(end 102.220014 -288.463228)
		(width 0.0889)
		(layer "In4.Cu")
		(net "P5E_CPU1_PE4_RX_DN<13>")
	)
	(segment
		(start 85.184234 -434.75275)
		(end 85.502496 -434.75275)
		(width 0.14732)
		(layer "In4.Cu")
		(net "P5E_CPU1_PE4_RX_DN<13>")
	)
	(segment
		(start 85.453474 -422.632378)
		(end 85.361272 -422.989248)
		(width 0.14732)
		(layer "In4.Cu")
		(net "P5E_CPU1_PE4_RX_DN<13>")
	)
	(segment
		(start 100.636578 -292.992048)
		(end 100.636578 -297.421554)
		(width 0.14732)
		(layer "In4.Cu")
		(net "P5E_CPU1_PE4_RX_DN<13>")
	)
	(segment
		(start 71.909686 -334.980788)
		(end 71.713852 -335.809844)
		(width 0.14732)
		(layer "In4.Cu")
		(net "P5E_CPU1_PE4_RX_DN<13>")
	)
	(segment
		(start 85.190838 -423.089324)
		(end 84.966302 -423.958004)
		(width 0.14732)
		(layer "In4.Cu")
		(net "P5E_CPU1_PE4_RX_DN<13>")
	)
	(segment
		(start 85.361272 -422.989248)
		(end 85.190838 -423.089324)
		(width 0.14732)
		(layer "In4.Cu")
		(net "P5E_CPU1_PE4_RX_DN<13>")
	)
	(segment
		(start 85.862414 -420.494714)
		(end 85.962744 -420.664894)
		(width 0.14732)
		(layer "In4.Cu")
		(net "P5E_CPU1_PE4_RX_DN<13>")
	)
	(segment
		(start 102.917244 -289.60953)
		(end 102.91699 -289.609276)
		(width 0.0889)
		(layer "In4.Cu")
		(net "P5E_CPU1_PE4_RX_DN<13>")
	)
	(segment
		(start 100.636578 -292.96995)
		(end 100.636578 -292.992048)
		(width 0.0889)
		(layer "In4.Cu")
		(net "P5E_CPU1_PE4_RX_DN<13>")
	)
	(segment
		(start 72.654668 -351.963736)
		(end 72.660764 -351.99701)
		(width 0.14732)
		(layer "In4.Cu")
		(net "P5E_CPU1_PE4_RX_DN<13>")
	)
	(segment
		(start 100.594414 -292.783768)
		(end 100.594414 -292.927786)
		(width 0.0889)
		(layer "In4.Cu")
		(net "P5E_CPU1_PE4_RX_DN<13>")
	)
	(segment
		(start 84.966302 -423.958004)
		(end 84.966302 -434.534818)
		(width 0.14732)
		(layer "In4.Cu")
		(net "P5E_CPU1_PE4_RX_DN<13>")
	)
	(segment
		(start 85.962744 -420.664894)
		(end 85.870542 -421.021764)
		(width 0.14732)
		(layer "In4.Cu")
		(net "P5E_CPU1_PE4_RX_DN<13>")
	)
	(segment
		(start 102.447598 -288.898584)
		(end 102.447598 -289.078416)
		(width 0.0889)
		(layer "In4.Cu")
		(net "P5E_CPU1_PE4_RX_DN<13>")
	)
	(segment
		(start 102.352348 -288.103056)
		(end 102.195884 -288.374074)
		(width 0.0889)
		(layer "In4.Cu")
		(net "P5E_CPU1_PE4_RX_DN<13>")
	)
	(segment
		(start 85.4456 -422.105836)
		(end 85.353398 -422.462198)
		(width 0.14732)
		(layer "In4.Cu")
		(net "P5E_CPU1_PE4_RX_DN<13>")
	)
	(segment
		(start 85.708236 -421.648636)
		(end 85.616034 -422.005506)
		(width 0.14732)
		(layer "In4.Cu")
		(net "P5E_CPU1_PE4_RX_DN<13>")
	)
	(segment
		(start 100.594414 -292.927786)
		(end 100.636578 -292.96995)
		(width 0.0889)
		(layer "In4.Cu")
		(net "P5E_CPU1_PE4_RX_DN<13>")
	)
	(segment
		(start 85.616034 -422.005506)
		(end 85.4456 -422.105836)
		(width 0.14732)
		(layer "In4.Cu")
		(net "P5E_CPU1_PE4_RX_DN<13>")
	)
	(segment
		(start 102.91699 -289.609276)
		(end 102.91699 -290.461192)
		(width 0.0889)
		(layer "In4.Cu")
		(net "P5E_CPU1_PE4_RX_DN<13>")
	)
	(segment
		(start 99.50704 -303.825402)
		(end 74.425556 -328.906886)
		(width 0.14732)
		(layer "In4.Cu")
		(net "P5E_CPU1_PE4_RX_DN<13>")
	)
	(segment
		(start 88.185498 -411.511496)
		(end 85.86216 -420.49446)
		(width 0.14732)
		(layer "In4.Cu")
		(net "P5E_CPU1_PE4_RX_DN<13>")
	)
	(segment
		(start 89.902538 -399.647918)
		(end 89.902538 -404.596092)
		(width 0.14732)
		(layer "In4.Cu")
		(net "P5E_CPU1_PE4_RX_DN<13>")
	)
	(segment
		(start 85.65007 -434.605176)
		(end 85.65007 -434.289962)
		(width 0.14732)
		(layer "In4.Cu")
		(net "P5E_CPU1_PE4_RX_DN<13>")
	)
	(segment
		(start 89.902538 -404.596092)
		(end 88.185498 -406.313132)
		(width 0.14732)
		(layer "In4.Cu")
		(net "P5E_CPU1_PE4_RX_DN<13>")
	)
	(segment
		(start 85.502496 -434.75275)
		(end 85.65007 -434.605176)
		(width 0.14732)
		(layer "In4.Cu")
		(net "P5E_CPU1_PE4_RX_DN<13>")
	)
	(segment
		(start 85.870542 -421.021764)
		(end 85.700108 -421.122094)
		(width 0.14732)
		(layer "In4.Cu")
		(net "P5E_CPU1_PE4_RX_DN<13>")
	)
	(segment
		(start 74.425556 -328.906886)
		(end 71.909686 -334.980788)
		(width 0.14732)
		(layer "In4.Cu")
		(net "P5E_CPU1_PE4_RX_DN<13>")
	)
	(segment
		(start 71.713852 -335.809844)
		(end 72.654668 -351.963736)
		(width 0.14732)
		(layer "In4.Cu")
		(net "P5E_CPU1_PE4_RX_DN<13>")
	)
	(segment
		(start 84.966302 -434.534818)
		(end 85.184234 -434.75275)
		(width 0.14732)
		(layer "In4.Cu")
		(net "P5E_CPU1_PE4_RX_DN<13>")
	)
	(segment
		(start 85.86216 -420.49446)
		(end 85.862414 -420.494714)
		(width 0.14732)
		(layer "In4.Cu")
		(net "P5E_CPU1_PE4_RX_DN<13>")
	)
	(segment
		(start 88.185498 -406.313132)
		(end 88.185498 -411.511496)
		(width 0.14732)
		(layer "In4.Cu")
		(net "P5E_CPU1_PE4_RX_DN<13>")
	)
	(segment
		(start 102.91699 -290.461192)
		(end 100.594414 -292.783768)
		(width 0.0889)
		(layer "In4.Cu")
		(net "P5E_CPU1_PE4_RX_DN<13>")
	)
	(segment
		(start 85.353398 -422.462198)
		(end 85.453474 -422.632378)
		(width 0.14732)
		(layer "In4.Cu")
		(net "P5E_CPU1_PE4_RX_DN<13>")
	)
	(segment
		(start 72.660764 -351.99701)
		(end 78.97749 -371.859048)
		(width 0.14732)
		(layer "In4.Cu")
		(net "P5E_CPU1_PE4_RX_DN<13>")
	)
	(segment
		(start 85.607906 -421.478456)
		(end 85.708236 -421.648636)
		(width 0.14732)
		(layer "In4.Cu")
		(net "P5E_CPU1_PE4_RX_DN<13>")
	)
	(segment
		(start 78.97749 -371.859048)
		(end 89.902538 -399.647918)
		(width 0.14732)
		(layer "In4.Cu")
		(net "P5E_CPU1_PE4_RX_DN<13>")
	)
	(segment
		(start 85.700108 -421.122094)
		(end 85.607906 -421.478456)
		(width 0.14732)
		(layer "In4.Cu")
		(net "P5E_CPU1_PE4_RX_DN<13>")
	)
	(segment
		(start 100.636578 -297.421554)
		(end 99.50704 -303.825402)
		(width 0.14732)
		(layer "In4.Cu")
		(net "P5E_CPU1_PE4_RX_DN<13>")
	)
	(arc
		(start 102.447598 -289.078416)
		(mid 102.522603 -289.193875)
		(end 102.631748 -289.277806)
		(width 0.0889)
		(layer "In4.Cu")
		(net "P5E_CPU1_PE4_RX_DN<13>")
	)
	(arc
		(start 102.631748 -289.277806)
		(mid 102.80588 -289.416653)
		(end 102.917244 -289.60953)
		(width 0.0889)
		(layer "In4.Cu")
		(net "P5E_CPU1_PE4_RX_DN<13>")
	)
	(arc
		(start 102.220014 -288.463228)
		(mid 102.228586 -288.469751)
		(end 102.237032 -288.476436)
		(width 0.0889)
		(layer "In4.Cu")
		(net "P5E_CPU1_PE4_RX_DN<13>")
	)
	(arc
		(start 102.237032 -288.476436)
		(mid 102.388436 -288.664503)
		(end 102.447598 -288.898584)
		(width 0.0889)
		(layer "In4.Cu")
		(net "P5E_CPU1_PE4_RX_DN<13>")
	)
	(segment
		(start 101.412294 -289.195002)
		(end 101.412294 -289.807142)
		(width 0.13208)
		(layer "F.Cu")
		(net "P5E_CPU1_PE4_RX_DN<12>")
	)
	(segment
		(start 86.564978 -399.62074)
		(end 76.933806 -371.941852)
		(width 0.14732)
		(layer "In4.Cu")
		(net "P5E_CPU1_PE4_RX_DN<12>")
	)
	(segment
		(start 71.124318 -351.440496)
		(end 70.499732 -335.654904)
		(width 0.14732)
		(layer "In4.Cu")
		(net "P5E_CPU1_PE4_RX_DN<12>")
	)
	(segment
		(start 99.427538 -292.96995)
		(end 99.469448 -292.92804)
		(width 0.0889)
		(layer "In4.Cu")
		(net "P5E_CPU1_PE4_RX_DN<12>")
	)
	(segment
		(start 99.427538 -297.315382)
		(end 99.427538 -292.992048)
		(width 0.14732)
		(layer "In4.Cu")
		(net "P5E_CPU1_PE4_RX_DN<12>")
	)
	(segment
		(start 82.692494 -433.680616)
		(end 82.692494 -424.219116)
		(width 0.14732)
		(layer "In4.Cu")
		(net "P5E_CPU1_PE4_RX_DN<12>")
	)
	(segment
		(start 73.409556 -328.21245)
		(end 98.382074 -303.239932)
		(width 0.14732)
		(layer "In4.Cu")
		(net "P5E_CPU1_PE4_RX_DN<12>")
	)
	(segment
		(start 83.5025 -434.027072)
		(end 83.03895 -434.027072)
		(width 0.14732)
		(layer "In4.Cu")
		(net "P5E_CPU1_PE4_RX_DN<12>")
	)
	(segment
		(start 99.427538 -292.992048)
		(end 99.427538 -292.96995)
		(width 0.0889)
		(layer "In4.Cu")
		(net "P5E_CPU1_PE4_RX_DN<12>")
	)
	(segment
		(start 99.469448 -292.92804)
		(end 99.469448 -292.686994)
		(width 0.0889)
		(layer "In4.Cu")
		(net "P5E_CPU1_PE4_RX_DN<12>")
	)
	(segment
		(start 70.592696 -335.013046)
		(end 73.409556 -328.21245)
		(width 0.14732)
		(layer "In4.Cu")
		(net "P5E_CPU1_PE4_RX_DN<12>")
	)
	(segment
		(start 86.564978 -404.4823)
		(end 86.564978 -399.62074)
		(width 0.14732)
		(layer "In4.Cu")
		(net "P5E_CPU1_PE4_RX_DN<12>")
	)
	(segment
		(start 76.933806 -371.941852)
		(end 71.124318 -351.440496)
		(width 0.14732)
		(layer "In4.Cu")
		(net "P5E_CPU1_PE4_RX_DN<12>")
	)
	(segment
		(start 84.847938 -406.19934)
		(end 86.564978 -404.4823)
		(width 0.14732)
		(layer "In4.Cu")
		(net "P5E_CPU1_PE4_RX_DN<12>")
	)
	(segment
		(start 101.253544 -289.506152)
		(end 101.412294 -289.807142)
		(width 0.0889)
		(layer "In4.Cu")
		(net "P5E_CPU1_PE4_RX_DN<12>")
	)
	(segment
		(start 70.499732 -335.654904)
		(end 70.592696 -335.013046)
		(width 0.14732)
		(layer "In4.Cu")
		(net "P5E_CPU1_PE4_RX_DN<12>")
	)
	(segment
		(start 84.847938 -411.61589)
		(end 84.847938 -406.19934)
		(width 0.14732)
		(layer "In4.Cu")
		(net "P5E_CPU1_PE4_RX_DN<12>")
	)
	(segment
		(start 83.650074 -434.174646)
		(end 83.5025 -434.027072)
		(width 0.14732)
		(layer "In4.Cu")
		(net "P5E_CPU1_PE4_RX_DN<12>")
	)
	(segment
		(start 101.786944 -290.369498)
		(end 101.786944 -289.645852)
		(width 0.0889)
		(layer "In4.Cu")
		(net "P5E_CPU1_PE4_RX_DN<12>")
	)
	(segment
		(start 98.382074 -303.239932)
		(end 99.427538 -297.315382)
		(width 0.14732)
		(layer "In4.Cu")
		(net "P5E_CPU1_PE4_RX_DN<12>")
	)
	(segment
		(start 83.03895 -434.027072)
		(end 82.692494 -433.680616)
		(width 0.14732)
		(layer "In4.Cu")
		(net "P5E_CPU1_PE4_RX_DN<12>")
	)
	(segment
		(start 101.27996 -289.42157)
		(end 101.253544 -289.506152)
		(width 0.0889)
		(layer "In4.Cu")
		(net "P5E_CPU1_PE4_RX_DN<12>")
	)
	(segment
		(start 82.692494 -424.219116)
		(end 84.847938 -411.61589)
		(width 0.14732)
		(layer "In4.Cu")
		(net "P5E_CPU1_PE4_RX_DN<12>")
	)
	(segment
		(start 99.469448 -292.686994)
		(end 101.786944 -290.369498)
		(width 0.0889)
		(layer "In4.Cu")
		(net "P5E_CPU1_PE4_RX_DN<12>")
	)
	(segment
		(start 83.650074 -434.48986)
		(end 83.650074 -434.174646)
		(width 0.14732)
		(layer "In4.Cu")
		(net "P5E_CPU1_PE4_RX_DN<12>")
	)
	(arc
		(start 101.786944 -289.645852)
		(mid 101.577409 -289.434449)
		(end 101.27996 -289.42157)
		(width 0.0889)
		(layer "In4.Cu")
		(net "P5E_CPU1_PE4_RX_DN<12>")
	)
	(segment
		(start 100.472494 -288.102802)
		(end 100.472748 -288.103056)
		(width 0.13208)
		(layer "F.Cu")
		(net "P5E_CPU1_PE4_RX_DN<11>")
	)
	(segment
		(start 100.472494 -287.567116)
		(end 100.472494 -288.102802)
		(width 0.13208)
		(layer "F.Cu")
		(net "P5E_CPU1_PE4_RX_DN<11>")
	)
	(segment
		(start 81.650078 -434.605176)
		(end 81.650078 -434.289962)
		(width 0.14732)
		(layer "In4.Cu")
		(net "P5E_CPU1_PE4_RX_DN<11>")
	)
	(segment
		(start 98.767138 -292.992048)
		(end 98.767138 -297.282362)
		(width 0.14732)
		(layer "In4.Cu")
		(net "P5E_CPU1_PE4_RX_DN<11>")
	)
	(segment
		(start 101.037644 -289.60953)
		(end 101.03739 -289.609276)
		(width 0.0889)
		(layer "In4.Cu")
		(net "P5E_CPU1_PE4_RX_DN<11>")
	)
	(segment
		(start 100.567998 -288.898584)
		(end 100.567998 -289.078416)
		(width 0.0889)
		(layer "In4.Cu")
		(net "P5E_CPU1_PE4_RX_DN<11>")
	)
	(segment
		(start 83.776058 -404.596092)
		(end 82.059018 -406.313132)
		(width 0.14732)
		(layer "In4.Cu")
		(net "P5E_CPU1_PE4_RX_DN<11>")
	)
	(segment
		(start 81.404714 -421.081708)
		(end 81.252314 -421.207946)
		(width 0.14732)
		(layer "In4.Cu")
		(net "P5E_CPU1_PE4_RX_DN<11>")
	)
	(segment
		(start 81.252314 -421.207946)
		(end 81.217008 -421.593264)
		(width 0.14732)
		(layer "In4.Cu")
		(net "P5E_CPU1_PE4_RX_DN<11>")
	)
	(segment
		(start 81.312004 -420.562532)
		(end 81.438496 -420.714678)
		(width 0.14732)
		(layer "In4.Cu")
		(net "P5E_CPU1_PE4_RX_DN<11>")
	)
	(segment
		(start 98.724974 -292.717728)
		(end 98.724974 -292.927786)
		(width 0.0889)
		(layer "In4.Cu")
		(net "P5E_CPU1_PE4_RX_DN<11>")
	)
	(segment
		(start 98.767138 -297.282362)
		(end 97.772982 -302.914812)
		(width 0.14732)
		(layer "In4.Cu")
		(net "P5E_CPU1_PE4_RX_DN<11>")
	)
	(segment
		(start 98.724974 -292.927786)
		(end 98.767138 -292.96995)
		(width 0.0889)
		(layer "In4.Cu")
		(net "P5E_CPU1_PE4_RX_DN<11>")
	)
	(segment
		(start 81.343246 -421.74541)
		(end 81.309464 -422.112186)
		(width 0.14732)
		(layer "In4.Cu")
		(net "P5E_CPU1_PE4_RX_DN<11>")
	)
	(segment
		(start 81.249774 -422.757092)
		(end 81.215992 -423.124122)
		(width 0.14732)
		(layer "In4.Cu")
		(net "P5E_CPU1_PE4_RX_DN<11>")
	)
	(segment
		(start 100.472748 -288.103056)
		(end 100.316284 -288.374074)
		(width 0.0889)
		(layer "In4.Cu")
		(net "P5E_CPU1_PE4_RX_DN<11>")
	)
	(segment
		(start 97.772982 -302.914812)
		(end 72.691244 -327.99655)
		(width 0.14732)
		(layer "In4.Cu")
		(net "P5E_CPU1_PE4_RX_DN<11>")
	)
	(segment
		(start 70.341236 -351.376996)
		(end 75.594464 -372.448328)
		(width 0.14732)
		(layer "In4.Cu")
		(net "P5E_CPU1_PE4_RX_DN<11>")
	)
	(segment
		(start 81.114138 -434.75275)
		(end 81.502504 -434.75275)
		(width 0.14732)
		(layer "In4.Cu")
		(net "P5E_CPU1_PE4_RX_DN<11>")
	)
	(segment
		(start 82.059018 -412.455614)
		(end 81.312004 -420.562532)
		(width 0.14732)
		(layer "In4.Cu")
		(net "P5E_CPU1_PE4_RX_DN<11>")
	)
	(segment
		(start 72.691244 -327.99655)
		(end 69.924168 -334.67675)
		(width 0.14732)
		(layer "In4.Cu")
		(net "P5E_CPU1_PE4_RX_DN<11>")
	)
	(segment
		(start 75.594464 -372.448328)
		(end 83.776058 -399.330926)
		(width 0.14732)
		(layer "In4.Cu")
		(net "P5E_CPU1_PE4_RX_DN<11>")
	)
	(segment
		(start 82.059018 -406.313132)
		(end 82.059018 -412.455614)
		(width 0.14732)
		(layer "In4.Cu")
		(net "P5E_CPU1_PE4_RX_DN<11>")
	)
	(segment
		(start 98.767138 -292.96995)
		(end 98.767138 -292.992048)
		(width 0.0889)
		(layer "In4.Cu")
		(net "P5E_CPU1_PE4_RX_DN<11>")
	)
	(segment
		(start 81.064354 -423.250106)
		(end 80.981296 -424.150028)
		(width 0.14732)
		(layer "In4.Cu")
		(net "P5E_CPU1_PE4_RX_DN<11>")
	)
	(segment
		(start 81.157318 -422.238678)
		(end 81.123536 -422.6052)
		(width 0.14732)
		(layer "In4.Cu")
		(net "P5E_CPU1_PE4_RX_DN<11>")
	)
	(segment
		(start 80.966818 -424.460924)
		(end 80.966818 -434.60543)
		(width 0.14732)
		(layer "In4.Cu")
		(net "P5E_CPU1_PE4_RX_DN<11>")
	)
	(segment
		(start 69.812408 -335.388458)
		(end 70.341236 -351.376996)
		(width 0.14732)
		(layer "In4.Cu")
		(net "P5E_CPU1_PE4_RX_DN<11>")
	)
	(segment
		(start 81.502504 -434.75275)
		(end 81.650078 -434.605176)
		(width 0.14732)
		(layer "In4.Cu")
		(net "P5E_CPU1_PE4_RX_DN<11>")
	)
	(segment
		(start 100.316284 -288.374074)
		(end 100.340414 -288.463228)
		(width 0.0889)
		(layer "In4.Cu")
		(net "P5E_CPU1_PE4_RX_DN<11>")
	)
	(segment
		(start 101.03739 -290.405312)
		(end 98.724974 -292.717728)
		(width 0.0889)
		(layer "In4.Cu")
		(net "P5E_CPU1_PE4_RX_DN<11>")
	)
	(segment
		(start 69.924168 -334.67675)
		(end 69.812408 -335.388458)
		(width 0.14732)
		(layer "In4.Cu")
		(net "P5E_CPU1_PE4_RX_DN<11>")
	)
	(segment
		(start 81.123536 -422.6052)
		(end 81.249774 -422.757092)
		(width 0.14732)
		(layer "In4.Cu")
		(net "P5E_CPU1_PE4_RX_DN<11>")
	)
	(segment
		(start 81.438496 -420.714678)
		(end 81.404714 -421.081708)
		(width 0.14732)
		(layer "In4.Cu")
		(net "P5E_CPU1_PE4_RX_DN<11>")
	)
	(segment
		(start 81.217008 -421.593264)
		(end 81.343246 -421.74541)
		(width 0.14732)
		(layer "In4.Cu")
		(net "P5E_CPU1_PE4_RX_DN<11>")
	)
	(segment
		(start 81.215992 -423.124122)
		(end 81.064354 -423.250106)
		(width 0.14732)
		(layer "In4.Cu")
		(net "P5E_CPU1_PE4_RX_DN<11>")
	)
	(segment
		(start 83.776058 -399.330926)
		(end 83.776058 -404.596092)
		(width 0.14732)
		(layer "In4.Cu")
		(net "P5E_CPU1_PE4_RX_DN<11>")
	)
	(segment
		(start 101.03739 -289.609276)
		(end 101.03739 -290.405312)
		(width 0.0889)
		(layer "In4.Cu")
		(net "P5E_CPU1_PE4_RX_DN<11>")
	)
	(segment
		(start 80.981296 -424.150028)
		(end 80.966818 -424.460924)
		(width 0.14732)
		(layer "In4.Cu")
		(net "P5E_CPU1_PE4_RX_DN<11>")
	)
	(segment
		(start 80.966818 -434.60543)
		(end 81.114138 -434.75275)
		(width 0.14732)
		(layer "In4.Cu")
		(net "P5E_CPU1_PE4_RX_DN<11>")
	)
	(segment
		(start 81.309464 -422.112186)
		(end 81.157318 -422.238678)
		(width 0.14732)
		(layer "In4.Cu")
		(net "P5E_CPU1_PE4_RX_DN<11>")
	)
	(arc
		(start 100.567998 -289.078416)
		(mid 100.643003 -289.193875)
		(end 100.752148 -289.277806)
		(width 0.0889)
		(layer "In4.Cu")
		(net "P5E_CPU1_PE4_RX_DN<11>")
	)
	(arc
		(start 100.752148 -289.277806)
		(mid 100.92628 -289.416653)
		(end 101.037644 -289.60953)
		(width 0.0889)
		(layer "In4.Cu")
		(net "P5E_CPU1_PE4_RX_DN<11>")
	)
	(arc
		(start 100.340414 -288.463228)
		(mid 100.348986 -288.469751)
		(end 100.357432 -288.476436)
		(width 0.0889)
		(layer "In4.Cu")
		(net "P5E_CPU1_PE4_RX_DN<11>")
	)
	(arc
		(start 100.357432 -288.476436)
		(mid 100.508836 -288.664503)
		(end 100.567998 -288.898584)
		(width 0.0889)
		(layer "In4.Cu")
		(net "P5E_CPU1_PE4_RX_DN<11>")
	)
	(segment
		(start 99.532694 -289.195002)
		(end 99.532694 -289.807142)
		(width 0.13208)
		(layer "F.Cu")
		(net "P5E_CPU1_PE4_RX_DN<10>")
	)
	(segment
		(start 80.438498 -404.4823)
		(end 80.438498 -399.377154)
		(width 0.14732)
		(layer "In4.Cu")
		(net "P5E_CPU1_PE4_RX_DN<10>")
	)
	(segment
		(start 68.579746 -335.345278)
		(end 68.710048 -334.244442)
		(width 0.14732)
		(layer "In4.Cu")
		(net "P5E_CPU1_PE4_RX_DN<10>")
	)
	(segment
		(start 79.05115 -434.027072)
		(end 78.680564 -433.656486)
		(width 0.14732)
		(layer "In4.Cu")
		(net "P5E_CPU1_PE4_RX_DN<10>")
	)
	(segment
		(start 78.721458 -406.19934)
		(end 80.438498 -404.4823)
		(width 0.14732)
		(layer "In4.Cu")
		(net "P5E_CPU1_PE4_RX_DN<10>")
	)
	(segment
		(start 97.56267 -297.151552)
		(end 97.56267 -292.992048)
		(width 0.14732)
		(layer "In4.Cu")
		(net "P5E_CPU1_PE4_RX_DN<10>")
	)
	(segment
		(start 71.524368 -327.450196)
		(end 96.649286 -302.324262)
		(width 0.14732)
		(layer "In4.Cu")
		(net "P5E_CPU1_PE4_RX_DN<10>")
	)
	(segment
		(start 73.628758 -372.676928)
		(end 69.020436 -351.194116)
		(width 0.14732)
		(layer "In4.Cu")
		(net "P5E_CPU1_PE4_RX_DN<10>")
	)
	(segment
		(start 78.709774 -422.102788)
		(end 78.721458 -421.179498)
		(width 0.14732)
		(layer "In4.Cu")
		(net "P5E_CPU1_PE4_RX_DN<10>")
	)
	(segment
		(start 78.721458 -421.179498)
		(end 78.721458 -406.19934)
		(width 0.14732)
		(layer "In4.Cu")
		(net "P5E_CPU1_PE4_RX_DN<10>")
	)
	(segment
		(start 99.907598 -290.257484)
		(end 99.907598 -289.64509)
		(width 0.0889)
		(layer "In4.Cu")
		(net "P5E_CPU1_PE4_RX_DN<10>")
	)
	(segment
		(start 68.710048 -334.244442)
		(end 71.524368 -327.450196)
		(width 0.14732)
		(layer "In4.Cu")
		(net "P5E_CPU1_PE4_RX_DN<10>")
	)
	(segment
		(start 79.502508 -434.027072)
		(end 79.05115 -434.027072)
		(width 0.14732)
		(layer "In4.Cu")
		(net "P5E_CPU1_PE4_RX_DN<10>")
	)
	(segment
		(start 69.020436 -351.194116)
		(end 68.799964 -343.26703)
		(width 0.14732)
		(layer "In4.Cu")
		(net "P5E_CPU1_PE4_RX_DN<10>")
	)
	(segment
		(start 99.40036 -289.42157)
		(end 99.373944 -289.506152)
		(width 0.0889)
		(layer "In4.Cu")
		(net "P5E_CPU1_PE4_RX_DN<10>")
	)
	(segment
		(start 97.56267 -292.96995)
		(end 97.60458 -292.92804)
		(width 0.0889)
		(layer "In4.Cu")
		(net "P5E_CPU1_PE4_RX_DN<10>")
	)
	(segment
		(start 68.799964 -343.26703)
		(end 68.579746 -335.345278)
		(width 0.14732)
		(layer "In4.Cu")
		(net "P5E_CPU1_PE4_RX_DN<10>")
	)
	(segment
		(start 96.649286 -302.324262)
		(end 97.56267 -297.151552)
		(width 0.14732)
		(layer "In4.Cu")
		(net "P5E_CPU1_PE4_RX_DN<10>")
	)
	(segment
		(start 80.438498 -399.377154)
		(end 73.628758 -372.676928)
		(width 0.14732)
		(layer "In4.Cu")
		(net "P5E_CPU1_PE4_RX_DN<10>")
	)
	(segment
		(start 99.373944 -289.506152)
		(end 99.532694 -289.807142)
		(width 0.0889)
		(layer "In4.Cu")
		(net "P5E_CPU1_PE4_RX_DN<10>")
	)
	(segment
		(start 78.70952 -422.108884)
		(end 78.709774 -422.102788)
		(width 0.14732)
		(layer "In4.Cu")
		(net "P5E_CPU1_PE4_RX_DN<10>")
	)
	(segment
		(start 79.650082 -434.174646)
		(end 79.502508 -434.027072)
		(width 0.14732)
		(layer "In4.Cu")
		(net "P5E_CPU1_PE4_RX_DN<10>")
	)
	(segment
		(start 97.60458 -292.92804)
		(end 97.60458 -292.560502)
		(width 0.0889)
		(layer "In4.Cu")
		(net "P5E_CPU1_PE4_RX_DN<10>")
	)
	(segment
		(start 78.680564 -433.656486)
		(end 78.680564 -424.403012)
		(width 0.14732)
		(layer "In4.Cu")
		(net "P5E_CPU1_PE4_RX_DN<10>")
	)
	(segment
		(start 78.680564 -424.403012)
		(end 78.70952 -422.108884)
		(width 0.14732)
		(layer "In4.Cu")
		(net "P5E_CPU1_PE4_RX_DN<10>")
	)
	(segment
		(start 97.60458 -292.560502)
		(end 99.907598 -290.257484)
		(width 0.0889)
		(layer "In4.Cu")
		(net "P5E_CPU1_PE4_RX_DN<10>")
	)
	(segment
		(start 79.650082 -434.48986)
		(end 79.650082 -434.174646)
		(width 0.14732)
		(layer "In4.Cu")
		(net "P5E_CPU1_PE4_RX_DN<10>")
	)
	(segment
		(start 97.56267 -292.992048)
		(end 97.56267 -292.96995)
		(width 0.0889)
		(layer "In4.Cu")
		(net "P5E_CPU1_PE4_RX_DN<10>")
	)
	(arc
		(start 99.399852 -289.420808)
		(mid 99.400107 -289.421188)
		(end 99.40036 -289.42157)
		(width 0.0889)
		(layer "In4.Cu")
		(net "P5E_CPU1_PE4_RX_DN<10>")
	)
	(arc
		(start 99.907598 -289.64509)
		(mid 99.69767 -289.433515)
		(end 99.399852 -289.420808)
		(width 0.0889)
		(layer "In4.Cu")
		(net "P5E_CPU1_PE4_RX_DN<10>")
	)
	(segment
		(start 88.725248 -288.381186)
		(end 88.725248 -288.917126)
		(width 0.13208)
		(layer "F.Cu")
		(net "P5E_CPU1_PE4_RX_DN<0>")
	)
	(segment
		(start 51.385216 -415.251138)
		(end 51.385216 -415.250884)
		(width 0.14732)
		(layer "In4.Cu")
		(net "P5E_CPU1_PE4_RX_DN<0>")
	)
	(segment
		(start 58.650124 -434.48986)
		(end 58.650124 -434.174646)
		(width 0.14732)
		(layer "In4.Cu")
		(net "P5E_CPU1_PE4_RX_DN<0>")
	)
	(segment
		(start 88.723978 -289.506914)
		(end 88.782906 -289.506914)
		(width 0.0889)
		(layer "In4.Cu")
		(net "P5E_CPU1_PE4_RX_DN<0>")
	)
	(segment
		(start 49.806098 -399.899378)
		(end 59.05754 -366.523778)
		(width 0.14732)
		(layer "In4.Cu")
		(net "P5E_CPU1_PE4_RX_DN<0>")
	)
	(segment
		(start 87.488776 -289.7759)
		(end 88.453976 -289.7759)
		(width 0.14732)
		(layer "In4.Cu")
		(net "P5E_CPU1_PE4_RX_DN<0>")
	)
	(segment
		(start 48.198786 -410.995876)
		(end 48.089058 -410.445458)
		(width 0.14732)
		(layer "In4.Cu")
		(net "P5E_CPU1_PE4_RX_DN<0>")
	)
	(segment
		(start 65.28308 -320.00317)
		(end 75.898248 -309.387748)
		(width 0.14732)
		(layer "In4.Cu")
		(net "P5E_CPU1_PE4_RX_DN<0>")
	)
	(segment
		(start 88.570816 -289.660076)
		(end 88.708484 -289.522408)
		(width 0.14732)
		(layer "In4.Cu")
		(net "P5E_CPU1_PE4_RX_DN<0>")
	)
	(segment
		(start 58.50255 -434.027072)
		(end 58.000392 -434.027072)
		(width 0.14732)
		(layer "In4.Cu")
		(net "P5E_CPU1_PE4_RX_DN<0>")
	)
	(segment
		(start 81.62417 -299.478954)
		(end 82.969354 -296.234104)
		(width 0.14732)
		(layer "In4.Cu")
		(net "P5E_CPU1_PE4_RX_DN<0>")
	)
	(segment
		(start 57.227216 -325.872856)
		(end 58.492644 -324.607174)
		(width 0.14732)
		(layer "In4.Cu")
		(net "P5E_CPU1_PE4_RX_DN<0>")
	)
	(segment
		(start 58.492644 -324.607174)
		(end 58.502296 -324.5993)
		(width 0.14732)
		(layer "In4.Cu")
		(net "P5E_CPU1_PE4_RX_DN<0>")
	)
	(segment
		(start 64.144398 -320.474848)
		(end 65.28308 -320.00317)
		(width 0.14732)
		(layer "In4.Cu")
		(net "P5E_CPU1_PE4_RX_DN<0>")
	)
	(segment
		(start 57.534302 -433.560982)
		(end 51.385216 -415.251138)
		(width 0.14732)
		(layer "In4.Cu")
		(net "P5E_CPU1_PE4_RX_DN<0>")
	)
	(segment
		(start 48.089058 -410.445458)
		(end 48.089058 -406.19934)
		(width 0.14732)
		(layer "In4.Cu")
		(net "P5E_CPU1_PE4_RX_DN<0>")
	)
	(segment
		(start 88.95969 -288.62528)
		(end 88.881712 -288.646108)
		(width 0.0889)
		(layer "In4.Cu")
		(net "P5E_CPU1_PE4_RX_DN<0>")
	)
	(segment
		(start 88.708484 -289.522408)
		(end 88.723978 -289.506914)
		(width 0.0889)
		(layer "In4.Cu")
		(net "P5E_CPU1_PE4_RX_DN<0>")
	)
	(segment
		(start 58.000392 -434.027072)
		(end 57.534302 -433.560982)
		(width 0.14732)
		(layer "In4.Cu")
		(net "P5E_CPU1_PE4_RX_DN<0>")
	)
	(segment
		(start 58.502296 -324.5993)
		(end 63.12408 -320.474848)
		(width 0.14732)
		(layer "In4.Cu")
		(net "P5E_CPU1_PE4_RX_DN<0>")
	)
	(segment
		(start 88.5698 -289.660076)
		(end 88.570816 -289.660076)
		(width 0.14732)
		(layer "In4.Cu")
		(net "P5E_CPU1_PE4_RX_DN<0>")
	)
	(segment
		(start 51.01082 -414.136332)
		(end 48.198786 -410.995876)
		(width 0.14732)
		(layer "In4.Cu")
		(net "P5E_CPU1_PE4_RX_DN<0>")
	)
	(segment
		(start 49.806098 -404.4823)
		(end 49.806098 -399.899378)
		(width 0.14732)
		(layer "In4.Cu")
		(net "P5E_CPU1_PE4_RX_DN<0>")
	)
	(segment
		(start 59.05754 -366.523778)
		(end 57.227216 -330.397866)
		(width 0.14732)
		(layer "In4.Cu")
		(net "P5E_CPU1_PE4_RX_DN<0>")
	)
	(segment
		(start 82.969354 -296.234104)
		(end 84.34197 -292.922706)
		(width 0.14732)
		(layer "In4.Cu")
		(net "P5E_CPU1_PE4_RX_DN<0>")
	)
	(segment
		(start 63.12408 -320.474848)
		(end 64.144398 -320.474848)
		(width 0.14732)
		(layer "In4.Cu")
		(net "P5E_CPU1_PE4_RX_DN<0>")
	)
	(segment
		(start 84.34197 -292.922706)
		(end 87.488776 -289.7759)
		(width 0.14732)
		(layer "In4.Cu")
		(net "P5E_CPU1_PE4_RX_DN<0>")
	)
	(segment
		(start 88.782906 -289.506914)
		(end 89.099644 -289.190176)
		(width 0.0889)
		(layer "In4.Cu")
		(net "P5E_CPU1_PE4_RX_DN<0>")
	)
	(segment
		(start 88.881712 -288.646108)
		(end 88.725248 -288.917126)
		(width 0.0889)
		(layer "In4.Cu")
		(net "P5E_CPU1_PE4_RX_DN<0>")
	)
	(segment
		(start 88.453976 -289.7759)
		(end 88.5698 -289.660076)
		(width 0.14732)
		(layer "In4.Cu")
		(net "P5E_CPU1_PE4_RX_DN<0>")
	)
	(segment
		(start 48.089058 -406.19934)
		(end 49.806098 -404.4823)
		(width 0.14732)
		(layer "In4.Cu")
		(net "P5E_CPU1_PE4_RX_DN<0>")
	)
	(segment
		(start 51.385216 -415.250884)
		(end 51.01082 -414.136332)
		(width 0.14732)
		(layer "In4.Cu")
		(net "P5E_CPU1_PE4_RX_DN<0>")
	)
	(segment
		(start 58.650124 -434.174646)
		(end 58.50255 -434.027072)
		(width 0.14732)
		(layer "In4.Cu")
		(net "P5E_CPU1_PE4_RX_DN<0>")
	)
	(segment
		(start 57.227216 -330.397866)
		(end 57.227216 -325.872856)
		(width 0.14732)
		(layer "In4.Cu")
		(net "P5E_CPU1_PE4_RX_DN<0>")
	)
	(segment
		(start 89.099644 -289.190176)
		(end 89.099644 -288.90849)
		(width 0.0889)
		(layer "In4.Cu")
		(net "P5E_CPU1_PE4_RX_DN<0>")
	)
	(segment
		(start 75.898248 -309.387748)
		(end 81.62417 -299.478954)
		(width 0.14732)
		(layer "In4.Cu")
		(net "P5E_CPU1_PE4_RX_DN<0>")
	)
	(arc
		(start 89.099644 -288.90849)
		(mid 89.06097 -288.751422)
		(end 88.95969 -288.62528)
		(width 0.0889)
		(layer "In4.Cu")
		(net "P5E_CPU1_PE4_RX_DN<0>")
	)
	(segment
		(start 140.445236 -407.926286)
		(end 140.769594 -408.250644)
		(width 0.13208)
		(layer "F.Cu")
		(net "P5E_CPU1_PE3_TX_DP<9>")
	)
	(segment
		(start 125.377448 -285.6611)
		(end 125.377194 -285.661354)
		(width 0.13208)
		(layer "F.Cu")
		(net "P5E_CPU1_PE3_TX_DP<9>")
	)
	(segment
		(start 140.445236 -407.303478)
		(end 140.445236 -407.926286)
		(width 0.13208)
		(layer "F.Cu")
		(net "P5E_CPU1_PE3_TX_DP<9>")
	)
	(segment
		(start 125.377448 -285.125414)
		(end 125.377448 -285.6611)
		(width 0.13208)
		(layer "F.Cu")
		(net "P5E_CPU1_PE3_TX_DP<9>")
	)
	(segment
		(start 140.744194 -407.00452)
		(end 140.445236 -407.303478)
		(width 0.13208)
		(layer "F.Cu")
		(net "P5E_CPU1_PE3_TX_DP<9>")
	)
	(segment
		(start 141.901418 -396.701772)
		(end 141.972284 -396.886176)
		(width 0.14732)
		(layer "In2.Cu")
		(net "P5E_CPU1_PE3_TX_DP<9>")
	)
	(segment
		(start 125.659134 -286.799274)
		(end 125.66015 -286.799782)
		(width 0.0889)
		(layer "In2.Cu")
		(net "P5E_CPU1_PE3_TX_DP<9>")
	)
	(segment
		(start 141.225778 -398.222724)
		(end 140.634974 -399.55343)
		(width 0.14732)
		(layer "In2.Cu")
		(net "P5E_CPU1_PE3_TX_DP<9>")
	)
	(segment
		(start 143.4973 -318.770508)
		(end 150.985728 -327.500234)
		(width 0.14732)
		(layer "In2.Cu")
		(net "P5E_CPU1_PE3_TX_DP<9>")
	)
	(segment
		(start 125.22073 -285.390336)
		(end 125.142498 -285.369508)
		(width 0.0889)
		(layer "In2.Cu")
		(net "P5E_CPU1_PE3_TX_DP<9>")
	)
	(segment
		(start 141.488922 -397.630396)
		(end 141.560042 -397.8148)
		(width 0.14732)
		(layer "In2.Cu")
		(net "P5E_CPU1_PE3_TX_DP<9>")
	)
	(segment
		(start 140.634974 -399.55343)
		(end 140.634974 -405.231346)
		(width 0.14732)
		(layer "In2.Cu")
		(net "P5E_CPU1_PE3_TX_DP<9>")
	)
	(segment
		(start 155.155646 -336.019902)
		(end 155.452572 -337.704176)
		(width 0.14732)
		(layer "In2.Cu")
		(net "P5E_CPU1_PE3_TX_DP<9>")
	)
	(segment
		(start 126.129796 -287.613598)
		(end 126.135892 -287.617154)
		(width 0.0889)
		(layer "In2.Cu")
		(net "P5E_CPU1_PE3_TX_DP<9>")
	)
	(segment
		(start 126.41199 -289.646868)
		(end 126.41199 -290.315904)
		(width 0.0889)
		(layer "In2.Cu")
		(net "P5E_CPU1_PE3_TX_DP<9>")
	)
	(segment
		(start 125.942344 -287.273746)
		(end 125.942344 -287.28924)
		(width 0.0889)
		(layer "In2.Cu")
		(net "P5E_CPU1_PE3_TX_DP<9>")
	)
	(segment
		(start 126.882398 -288.898584)
		(end 126.882398 -289.114484)
		(width 0.0889)
		(layer "In2.Cu")
		(net "P5E_CPU1_PE3_TX_DP<9>")
	)
	(segment
		(start 140.449554 -406.70988)
		(end 140.744194 -407.00452)
		(width 0.14732)
		(layer "In2.Cu")
		(net "P5E_CPU1_PE3_TX_DP<9>")
	)
	(segment
		(start 141.822932 -397.22298)
		(end 141.638274 -397.293846)
		(width 0.14732)
		(layer "In2.Cu")
		(net "P5E_CPU1_PE3_TX_DP<9>")
	)
	(segment
		(start 126.412244 -289.64636)
		(end 126.41199 -289.646868)
		(width 0.0889)
		(layer "In2.Cu")
		(net "P5E_CPU1_PE3_TX_DP<9>")
	)
	(segment
		(start 126.454154 -290.380166)
		(end 126.454154 -295.045638)
		(width 0.14732)
		(layer "In2.Cu")
		(net "P5E_CPU1_PE3_TX_DP<9>")
	)
	(segment
		(start 125.377194 -285.661354)
		(end 125.22073 -285.390336)
		(width 0.0889)
		(layer "In2.Cu")
		(net "P5E_CPU1_PE3_TX_DP<9>")
	)
	(segment
		(start 141.560042 -397.8148)
		(end 141.410436 -398.151604)
		(width 0.14732)
		(layer "In2.Cu")
		(net "P5E_CPU1_PE3_TX_DP<9>")
	)
	(segment
		(start 135.9027 -307.924708)
		(end 143.4973 -318.770508)
		(width 0.14732)
		(layer "In2.Cu")
		(net "P5E_CPU1_PE3_TX_DP<9>")
	)
	(segment
		(start 141.972284 -396.886176)
		(end 141.822932 -397.22298)
		(width 0.14732)
		(layer "In2.Cu")
		(net "P5E_CPU1_PE3_TX_DP<9>")
	)
	(segment
		(start 125.65126 -286.794702)
		(end 125.659134 -286.799274)
		(width 0.0889)
		(layer "In2.Cu")
		(net "P5E_CPU1_PE3_TX_DP<9>")
	)
	(segment
		(start 152.124156 -372.677436)
		(end 150.236682 -377.932442)
		(width 0.14732)
		(layer "In2.Cu")
		(net "P5E_CPU1_PE3_TX_DP<9>")
	)
	(segment
		(start 155.753308 -341.528908)
		(end 152.124156 -372.677436)
		(width 0.14732)
		(layer "In2.Cu")
		(net "P5E_CPU1_PE3_TX_DP<9>")
	)
	(segment
		(start 150.985728 -327.500234)
		(end 154.55138 -332.59268)
		(width 0.14732)
		(layer "In2.Cu")
		(net "P5E_CPU1_PE3_TX_DP<9>")
	)
	(segment
		(start 128.880362 -300.902878)
		(end 135.9027 -307.924708)
		(width 0.14732)
		(layer "In2.Cu")
		(net "P5E_CPU1_PE3_TX_DP<9>")
	)
	(segment
		(start 141.638274 -397.293846)
		(end 141.488922 -397.630396)
		(width 0.14732)
		(layer "In2.Cu")
		(net "P5E_CPU1_PE3_TX_DP<9>")
	)
	(segment
		(start 126.41199 -290.315904)
		(end 126.454154 -290.358068)
		(width 0.0889)
		(layer "In2.Cu")
		(net "P5E_CPU1_PE3_TX_DP<9>")
	)
	(segment
		(start 126.454154 -290.358068)
		(end 126.454154 -290.380166)
		(width 0.0889)
		(layer "In2.Cu")
		(net "P5E_CPU1_PE3_TX_DP<9>")
	)
	(segment
		(start 140.634974 -405.231346)
		(end 140.449554 -405.416766)
		(width 0.14732)
		(layer "In2.Cu")
		(net "P5E_CPU1_PE3_TX_DP<9>")
	)
	(segment
		(start 125.181106 -285.980632)
		(end 125.189996 -285.985712)
		(width 0.0889)
		(layer "In2.Cu")
		(net "P5E_CPU1_PE3_TX_DP<9>")
	)
	(segment
		(start 126.59106 -288.422334)
		(end 126.59995 -288.427414)
		(width 0.0889)
		(layer "In2.Cu")
		(net "P5E_CPU1_PE3_TX_DP<9>")
	)
	(segment
		(start 155.452572 -337.704176)
		(end 155.753308 -339.410548)
		(width 0.14732)
		(layer "In2.Cu")
		(net "P5E_CPU1_PE3_TX_DP<9>")
	)
	(segment
		(start 126.120906 -287.608518)
		(end 126.129796 -287.613598)
		(width 0.0889)
		(layer "In2.Cu")
		(net "P5E_CPU1_PE3_TX_DP<9>")
	)
	(segment
		(start 126.454154 -295.045638)
		(end 128.880362 -300.902878)
		(width 0.14732)
		(layer "In2.Cu")
		(net "P5E_CPU1_PE3_TX_DP<9>")
	)
	(segment
		(start 155.753308 -339.410548)
		(end 155.753308 -341.528908)
		(width 0.14732)
		(layer "In2.Cu")
		(net "P5E_CPU1_PE3_TX_DP<9>")
	)
	(segment
		(start 154.55138 -332.59268)
		(end 155.155646 -336.019902)
		(width 0.14732)
		(layer "In2.Cu")
		(net "P5E_CPU1_PE3_TX_DP<9>")
	)
	(segment
		(start 150.236682 -377.932442)
		(end 141.901418 -396.701772)
		(width 0.14732)
		(layer "In2.Cu")
		(net "P5E_CPU1_PE3_TX_DP<9>")
	)
	(segment
		(start 125.472698 -286.467804)
		(end 125.472698 -286.475424)
		(width 0.0889)
		(layer "In2.Cu")
		(net "P5E_CPU1_PE3_TX_DP<9>")
	)
	(segment
		(start 141.410436 -398.151604)
		(end 141.225778 -398.222724)
		(width 0.14732)
		(layer "In2.Cu")
		(net "P5E_CPU1_PE3_TX_DP<9>")
	)
	(segment
		(start 140.449554 -405.416766)
		(end 140.449554 -406.70988)
		(width 0.14732)
		(layer "In2.Cu")
		(net "P5E_CPU1_PE3_TX_DP<9>")
	)
	(arc
		(start 125.472698 -286.475424)
		(mid 125.520377 -286.658324)
		(end 125.65126 -286.794702)
		(width 0.0889)
		(layer "In2.Cu")
		(net "P5E_CPU1_PE3_TX_DP<9>")
	)
	(arc
		(start 125.189996 -285.985712)
		(mid 125.395068 -286.189391)
		(end 125.472698 -286.467804)
		(width 0.0889)
		(layer "In2.Cu")
		(net "P5E_CPU1_PE3_TX_DP<9>")
	)
	(arc
		(start 126.59995 -288.427414)
		(mid 126.802236 -288.626395)
		(end 126.882398 -288.898584)
		(width 0.0889)
		(layer "In2.Cu")
		(net "P5E_CPU1_PE3_TX_DP<9>")
	)
	(arc
		(start 126.596648 -289.446462)
		(mid 126.487252 -289.530559)
		(end 126.412244 -289.64636)
		(width 0.0889)
		(layer "In2.Cu")
		(net "P5E_CPU1_PE3_TX_DP<9>")
	)
	(arc
		(start 125.942344 -287.28924)
		(mid 125.990023 -287.47214)
		(end 126.120906 -287.608518)
		(width 0.0889)
		(layer "In2.Cu")
		(net "P5E_CPU1_PE3_TX_DP<9>")
	)
	(arc
		(start 125.142498 -285.369508)
		(mid 125.039353 -285.499533)
		(end 125.002544 -285.661354)
		(width 0.0889)
		(layer "In2.Cu")
		(net "P5E_CPU1_PE3_TX_DP<9>")
	)
	(arc
		(start 125.66015 -286.799782)
		(mid 125.862973 -287.000013)
		(end 125.942344 -287.273746)
		(width 0.0889)
		(layer "In2.Cu")
		(net "P5E_CPU1_PE3_TX_DP<9>")
	)
	(arc
		(start 126.135892 -287.617154)
		(mid 126.338479 -287.823505)
		(end 126.412498 -288.103056)
		(width 0.0889)
		(layer "In2.Cu")
		(net "P5E_CPU1_PE3_TX_DP<9>")
	)
	(arc
		(start 125.002544 -285.661354)
		(mid 125.050223 -285.844254)
		(end 125.181106 -285.980632)
		(width 0.0889)
		(layer "In2.Cu")
		(net "P5E_CPU1_PE3_TX_DP<9>")
	)
	(arc
		(start 126.412498 -288.103056)
		(mid 126.460177 -288.285956)
		(end 126.59106 -288.422334)
		(width 0.0889)
		(layer "In2.Cu")
		(net "P5E_CPU1_PE3_TX_DP<9>")
	)
	(arc
		(start 126.882398 -289.114484)
		(mid 126.771002 -289.307577)
		(end 126.596648 -289.446462)
		(width 0.0889)
		(layer "In2.Cu")
		(net "P5E_CPU1_PE3_TX_DP<9>")
	)
	(segment
		(start 143.508476 -407.926286)
		(end 143.832834 -408.250644)
		(width 0.13208)
		(layer "F.Cu")
		(net "P5E_CPU1_PE3_TX_DP<8>")
	)
	(segment
		(start 126.317248 -285.125414)
		(end 126.317248 -285.6611)
		(width 0.13208)
		(layer "F.Cu")
		(net "P5E_CPU1_PE3_TX_DP<8>")
	)
	(segment
		(start 143.807434 -407.00452)
		(end 143.508476 -407.303478)
		(width 0.13208)
		(layer "F.Cu")
		(net "P5E_CPU1_PE3_TX_DP<8>")
	)
	(segment
		(start 126.317248 -285.6611)
		(end 126.316994 -285.661354)
		(width 0.13208)
		(layer "F.Cu")
		(net "P5E_CPU1_PE3_TX_DP<8>")
	)
	(segment
		(start 143.508476 -407.303478)
		(end 143.508476 -407.926286)
		(width 0.13208)
		(layer "F.Cu")
		(net "P5E_CPU1_PE3_TX_DP<8>")
	)
	(segment
		(start 126.882144 -287.279334)
		(end 126.882144 -287.28924)
		(width 0.0889)
		(layer "In2.Cu")
		(net "P5E_CPU1_PE3_TX_DP<8>")
	)
	(segment
		(start 144.19072 -398.093184)
		(end 143.698214 -399.417794)
		(width 0.14732)
		(layer "In2.Cu")
		(net "P5E_CPU1_PE3_TX_DP<8>")
	)
	(segment
		(start 127.060706 -287.608518)
		(end 127.068072 -287.612836)
		(width 0.0889)
		(layer "In2.Cu")
		(net "P5E_CPU1_PE3_TX_DP<8>")
	)
	(segment
		(start 127.535432 -288.424874)
		(end 127.53975 -288.427414)
		(width 0.0889)
		(layer "In2.Cu")
		(net "P5E_CPU1_PE3_TX_DP<8>")
	)
	(segment
		(start 129.619248 -300.256956)
		(end 136.269222 -306.90693)
		(width 0.14732)
		(layer "In2.Cu")
		(net "P5E_CPU1_PE3_TX_DP<8>")
	)
	(segment
		(start 127.822198 -288.898584)
		(end 127.822198 -289.114484)
		(width 0.0889)
		(layer "In2.Cu")
		(net "P5E_CPU1_PE3_TX_DP<8>")
	)
	(segment
		(start 126.412498 -286.4612)
		(end 126.412498 -286.48406)
		(width 0.0889)
		(layer "In2.Cu")
		(net "P5E_CPU1_PE3_TX_DP<8>")
	)
	(segment
		(start 144.416526 -397.486378)
		(end 144.190974 -398.093184)
		(width 0.14732)
		(layer "In2.Cu")
		(net "P5E_CPU1_PE3_TX_DP<8>")
	)
	(segment
		(start 151.14524 -379.390656)
		(end 144.771618 -396.531084)
		(width 0.14732)
		(layer "In2.Cu")
		(net "P5E_CPU1_PE3_TX_DP<8>")
	)
	(segment
		(start 144.770856 -396.53337)
		(end 144.41678 -397.485616)
		(width 0.14732)
		(layer "In2.Cu")
		(net "P5E_CPU1_PE3_TX_DP<8>")
	)
	(segment
		(start 151.723344 -326.931782)
		(end 155.60929 -332.481682)
		(width 0.14732)
		(layer "In2.Cu")
		(net "P5E_CPU1_PE3_TX_DP<8>")
	)
	(segment
		(start 127.393954 -294.884602)
		(end 129.619248 -300.256956)
		(width 0.14732)
		(layer "In2.Cu")
		(net "P5E_CPU1_PE3_TX_DP<8>")
	)
	(segment
		(start 144.190974 -398.093184)
		(end 144.19072 -398.093184)
		(width 0.14732)
		(layer "In2.Cu")
		(net "P5E_CPU1_PE3_TX_DP<8>")
	)
	(segment
		(start 144.238218 -318.205866)
		(end 151.723344 -326.931782)
		(width 0.14732)
		(layer "In2.Cu")
		(net "P5E_CPU1_PE3_TX_DP<8>")
	)
	(segment
		(start 143.512794 -406.70988)
		(end 143.807434 -407.00452)
		(width 0.14732)
		(layer "In2.Cu")
		(net "P5E_CPU1_PE3_TX_DP<8>")
	)
	(segment
		(start 156.691584 -341.560912)
		(end 152.885648 -374.226582)
		(width 0.14732)
		(layer "In2.Cu")
		(net "P5E_CPU1_PE3_TX_DP<8>")
	)
	(segment
		(start 156.691584 -338.612734)
		(end 156.691584 -341.560912)
		(width 0.14732)
		(layer "In2.Cu")
		(net "P5E_CPU1_PE3_TX_DP<8>")
	)
	(segment
		(start 143.512794 -405.416766)
		(end 143.512794 -406.70988)
		(width 0.14732)
		(layer "In2.Cu")
		(net "P5E_CPU1_PE3_TX_DP<8>")
	)
	(segment
		(start 136.269222 -306.90693)
		(end 136.382506 -306.986178)
		(width 0.14732)
		(layer "In2.Cu")
		(net "P5E_CPU1_PE3_TX_DP<8>")
	)
	(segment
		(start 127.068072 -287.612836)
		(end 127.069596 -287.613598)
		(width 0.0889)
		(layer "In2.Cu")
		(net "P5E_CPU1_PE3_TX_DP<8>")
	)
	(segment
		(start 127.069596 -287.613598)
		(end 127.07112 -287.614614)
		(width 0.0889)
		(layer "In2.Cu")
		(net "P5E_CPU1_PE3_TX_DP<8>")
	)
	(segment
		(start 152.885648 -374.226582)
		(end 151.14524 -379.390656)
		(width 0.14732)
		(layer "In2.Cu")
		(net "P5E_CPU1_PE3_TX_DP<8>")
	)
	(segment
		(start 126.316994 -285.661354)
		(end 126.16053 -285.932372)
		(width 0.0889)
		(layer "In2.Cu")
		(net "P5E_CPU1_PE3_TX_DP<8>")
	)
	(segment
		(start 127.393954 -290.380166)
		(end 127.393954 -294.884602)
		(width 0.14732)
		(layer "In2.Cu")
		(net "P5E_CPU1_PE3_TX_DP<8>")
	)
	(segment
		(start 144.771618 -396.531084)
		(end 144.770856 -396.53337)
		(width 0.14732)
		(layer "In2.Cu")
		(net "P5E_CPU1_PE3_TX_DP<8>")
	)
	(segment
		(start 136.382506 -306.986178)
		(end 144.238218 -318.205866)
		(width 0.14732)
		(layer "In2.Cu")
		(net "P5E_CPU1_PE3_TX_DP<8>")
	)
	(segment
		(start 155.60929 -332.481682)
		(end 156.691584 -338.612734)
		(width 0.14732)
		(layer "In2.Cu")
		(net "P5E_CPU1_PE3_TX_DP<8>")
	)
	(segment
		(start 143.698214 -405.231346)
		(end 143.512794 -405.416766)
		(width 0.14732)
		(layer "In2.Cu")
		(net "P5E_CPU1_PE3_TX_DP<8>")
	)
	(segment
		(start 127.35179 -290.315904)
		(end 127.393954 -290.358068)
		(width 0.0889)
		(layer "In2.Cu")
		(net "P5E_CPU1_PE3_TX_DP<8>")
	)
	(segment
		(start 127.53086 -288.422334)
		(end 127.535432 -288.424874)
		(width 0.0889)
		(layer "In2.Cu")
		(net "P5E_CPU1_PE3_TX_DP<8>")
	)
	(segment
		(start 144.41678 -397.485616)
		(end 144.416526 -397.486378)
		(width 0.14732)
		(layer "In2.Cu")
		(net "P5E_CPU1_PE3_TX_DP<8>")
	)
	(segment
		(start 127.07112 -287.614614)
		(end 127.075692 -287.617154)
		(width 0.0889)
		(layer "In2.Cu")
		(net "P5E_CPU1_PE3_TX_DP<8>")
	)
	(segment
		(start 143.698214 -399.417794)
		(end 143.698214 -405.231346)
		(width 0.14732)
		(layer "In2.Cu")
		(net "P5E_CPU1_PE3_TX_DP<8>")
	)
	(segment
		(start 126.16053 -285.932372)
		(end 126.18466 -286.021526)
		(width 0.0889)
		(layer "In2.Cu")
		(net "P5E_CPU1_PE3_TX_DP<8>")
	)
	(segment
		(start 127.35179 -289.752786)
		(end 127.35179 -290.315904)
		(width 0.0889)
		(layer "In2.Cu")
		(net "P5E_CPU1_PE3_TX_DP<8>")
	)
	(segment
		(start 127.393954 -290.358068)
		(end 127.393954 -290.380166)
		(width 0.0889)
		(layer "In2.Cu")
		(net "P5E_CPU1_PE3_TX_DP<8>")
	)
	(arc
		(start 127.536448 -289.446462)
		(mid 127.401449 -289.573919)
		(end 127.35179 -289.752786)
		(width 0.0889)
		(layer "In2.Cu")
		(net "P5E_CPU1_PE3_TX_DP<8>")
	)
	(arc
		(start 126.18466 -286.021526)
		(mid 126.349346 -286.215067)
		(end 126.412498 -286.4612)
		(width 0.0889)
		(layer "In2.Cu")
		(net "P5E_CPU1_PE3_TX_DP<8>")
	)
	(arc
		(start 126.412498 -286.48406)
		(mid 126.464768 -286.666425)
		(end 126.599696 -286.799782)
		(width 0.0889)
		(layer "In2.Cu")
		(net "P5E_CPU1_PE3_TX_DP<8>")
	)
	(arc
		(start 127.53975 -288.427414)
		(mid 127.742036 -288.626395)
		(end 127.822198 -288.898584)
		(width 0.0889)
		(layer "In2.Cu")
		(net "P5E_CPU1_PE3_TX_DP<8>")
	)
	(arc
		(start 127.822198 -289.114484)
		(mid 127.710802 -289.307577)
		(end 127.536448 -289.446462)
		(width 0.0889)
		(layer "In2.Cu")
		(net "P5E_CPU1_PE3_TX_DP<8>")
	)
	(arc
		(start 126.599696 -286.799782)
		(mid 126.804031 -287.002387)
		(end 126.882144 -287.279334)
		(width 0.0889)
		(layer "In2.Cu")
		(net "P5E_CPU1_PE3_TX_DP<8>")
	)
	(arc
		(start 126.882144 -287.28924)
		(mid 126.929823 -287.47214)
		(end 127.060706 -287.608518)
		(width 0.0889)
		(layer "In2.Cu")
		(net "P5E_CPU1_PE3_TX_DP<8>")
	)
	(arc
		(start 127.352298 -288.103056)
		(mid 127.399977 -288.285956)
		(end 127.53086 -288.422334)
		(width 0.0889)
		(layer "In2.Cu")
		(net "P5E_CPU1_PE3_TX_DP<8>")
	)
	(arc
		(start 127.075692 -287.617154)
		(mid 127.278279 -287.823505)
		(end 127.352298 -288.103056)
		(width 0.0889)
		(layer "In2.Cu")
		(net "P5E_CPU1_PE3_TX_DP<8>")
	)
	(segment
		(start 127.257048 -285.6611)
		(end 127.256794 -285.661354)
		(width 0.13208)
		(layer "F.Cu")
		(net "P5E_CPU1_PE3_TX_DP<7>")
	)
	(segment
		(start 146.571716 -407.926286)
		(end 146.896074 -408.250644)
		(width 0.13208)
		(layer "F.Cu")
		(net "P5E_CPU1_PE3_TX_DP<7>")
	)
	(segment
		(start 127.257048 -285.125414)
		(end 127.257048 -285.6611)
		(width 0.13208)
		(layer "F.Cu")
		(net "P5E_CPU1_PE3_TX_DP<7>")
	)
	(segment
		(start 146.571716 -407.303478)
		(end 146.571716 -407.926286)
		(width 0.13208)
		(layer "F.Cu")
		(net "P5E_CPU1_PE3_TX_DP<7>")
	)
	(segment
		(start 146.870674 -407.00452)
		(end 146.571716 -407.303478)
		(width 0.13208)
		(layer "F.Cu")
		(net "P5E_CPU1_PE3_TX_DP<7>")
	)
	(segment
		(start 156.492448 -332.121256)
		(end 152.45842 -326.360028)
		(width 0.14732)
		(layer "In2.Cu")
		(net "P5E_CPU1_PE3_TX_DP<7>")
	)
	(segment
		(start 147.501356 -397.20647)
		(end 147.407122 -397.032734)
		(width 0.14732)
		(layer "In2.Cu")
		(net "P5E_CPU1_PE3_TX_DP<7>")
	)
	(segment
		(start 127.352298 -286.475424)
		(end 127.352298 -286.467804)
		(width 0.0889)
		(layer "In2.Cu")
		(net "P5E_CPU1_PE3_TX_DP<7>")
	)
	(segment
		(start 128.334008 -294.724074)
		(end 128.334008 -290.380166)
		(width 0.14732)
		(layer "In2.Cu")
		(net "P5E_CPU1_PE3_TX_DP<7>")
	)
	(segment
		(start 145.083784 -317.76289)
		(end 137.15873 -306.44465)
		(width 0.14732)
		(layer "In2.Cu")
		(net "P5E_CPU1_PE3_TX_DP<7>")
	)
	(segment
		(start 147.222972 -397.654018)
		(end 147.396708 -397.559784)
		(width 0.14732)
		(layer "In2.Cu")
		(net "P5E_CPU1_PE3_TX_DP<7>")
	)
	(segment
		(start 147.212558 -398.18056)
		(end 147.118324 -398.007078)
		(width 0.14732)
		(layer "In2.Cu")
		(net "P5E_CPU1_PE3_TX_DP<7>")
	)
	(segment
		(start 127.538734 -286.799274)
		(end 127.53086 -286.794702)
		(width 0.0889)
		(layer "In2.Cu")
		(net "P5E_CPU1_PE3_TX_DP<7>")
	)
	(segment
		(start 147.396708 -397.559784)
		(end 147.501356 -397.20647)
		(width 0.14732)
		(layer "In2.Cu")
		(net "P5E_CPU1_PE3_TX_DP<7>")
	)
	(segment
		(start 147.118324 -398.007078)
		(end 147.222972 -397.654018)
		(width 0.14732)
		(layer "In2.Cu")
		(net "P5E_CPU1_PE3_TX_DP<7>")
	)
	(segment
		(start 128.009396 -287.613598)
		(end 128.007872 -287.612836)
		(width 0.0889)
		(layer "In2.Cu")
		(net "P5E_CPU1_PE3_TX_DP<7>")
	)
	(segment
		(start 147.10791 -398.534128)
		(end 147.212558 -398.18056)
		(width 0.14732)
		(layer "In2.Cu")
		(net "P5E_CPU1_PE3_TX_DP<7>")
	)
	(segment
		(start 137.15873 -306.44465)
		(end 130.382264 -299.668946)
		(width 0.14732)
		(layer "In2.Cu")
		(net "P5E_CPU1_PE3_TX_DP<7>")
	)
	(segment
		(start 146.934174 -398.628362)
		(end 147.10791 -398.534128)
		(width 0.14732)
		(layer "In2.Cu")
		(net "P5E_CPU1_PE3_TX_DP<7>")
	)
	(segment
		(start 157.629606 -338.564982)
		(end 156.492448 -332.121256)
		(width 0.14732)
		(layer "In2.Cu")
		(net "P5E_CPU1_PE3_TX_DP<7>")
	)
	(segment
		(start 130.382264 -299.668946)
		(end 128.334008 -294.724074)
		(width 0.14732)
		(layer "In2.Cu")
		(net "P5E_CPU1_PE3_TX_DP<7>")
	)
	(segment
		(start 152.45842 -326.360028)
		(end 145.083784 -317.76289)
		(width 0.14732)
		(layer "In2.Cu")
		(net "P5E_CPU1_PE3_TX_DP<7>")
	)
	(segment
		(start 127.068834 -285.985204)
		(end 127.060706 -285.980632)
		(width 0.0889)
		(layer "In2.Cu")
		(net "P5E_CPU1_PE3_TX_DP<7>")
	)
	(segment
		(start 146.870674 -407.00452)
		(end 146.576034 -406.70988)
		(width 0.14732)
		(layer "In2.Cu")
		(net "P5E_CPU1_PE3_TX_DP<7>")
	)
	(segment
		(start 146.761454 -405.231346)
		(end 146.761454 -399.210276)
		(width 0.14732)
		(layer "In2.Cu")
		(net "P5E_CPU1_PE3_TX_DP<7>")
	)
	(segment
		(start 127.10033 -285.390336)
		(end 127.256794 -285.661354)
		(width 0.0889)
		(layer "In2.Cu")
		(net "P5E_CPU1_PE3_TX_DP<7>")
	)
	(segment
		(start 128.015492 -287.617154)
		(end 128.01092 -287.614614)
		(width 0.0889)
		(layer "In2.Cu")
		(net "P5E_CPU1_PE3_TX_DP<7>")
	)
	(segment
		(start 146.576034 -405.416766)
		(end 146.761454 -405.231346)
		(width 0.14732)
		(layer "In2.Cu")
		(net "P5E_CPU1_PE3_TX_DP<7>")
	)
	(segment
		(start 127.069596 -285.985712)
		(end 127.068834 -285.985204)
		(width 0.0889)
		(layer "In2.Cu")
		(net "P5E_CPU1_PE3_TX_DP<7>")
	)
	(segment
		(start 147.407122 -397.032734)
		(end 153.599134 -376.146314)
		(width 0.14732)
		(layer "In2.Cu")
		(net "P5E_CPU1_PE3_TX_DP<7>")
	)
	(segment
		(start 127.821944 -287.28924)
		(end 127.821944 -287.273746)
		(width 0.0889)
		(layer "In2.Cu")
		(net "P5E_CPU1_PE3_TX_DP<7>")
	)
	(segment
		(start 128.01092 -287.614614)
		(end 128.009396 -287.613598)
		(width 0.0889)
		(layer "In2.Cu")
		(net "P5E_CPU1_PE3_TX_DP<7>")
	)
	(segment
		(start 128.761998 -289.114484)
		(end 128.761998 -288.898584)
		(width 0.0889)
		(layer "In2.Cu")
		(net "P5E_CPU1_PE3_TX_DP<7>")
	)
	(segment
		(start 153.599134 -376.146314)
		(end 157.629606 -341.553546)
		(width 0.14732)
		(layer "In2.Cu")
		(net "P5E_CPU1_PE3_TX_DP<7>")
	)
	(segment
		(start 128.291844 -290.315904)
		(end 128.291844 -289.64636)
		(width 0.0889)
		(layer "In2.Cu")
		(net "P5E_CPU1_PE3_TX_DP<7>")
	)
	(segment
		(start 128.334008 -290.358068)
		(end 128.291844 -290.315904)
		(width 0.0889)
		(layer "In2.Cu")
		(net "P5E_CPU1_PE3_TX_DP<7>")
	)
	(segment
		(start 128.007872 -287.612836)
		(end 128.000506 -287.608518)
		(width 0.0889)
		(layer "In2.Cu")
		(net "P5E_CPU1_PE3_TX_DP<7>")
	)
	(segment
		(start 127.022098 -285.369508)
		(end 127.10033 -285.390336)
		(width 0.0889)
		(layer "In2.Cu")
		(net "P5E_CPU1_PE3_TX_DP<7>")
	)
	(segment
		(start 128.47955 -288.427414)
		(end 128.47066 -288.422334)
		(width 0.0889)
		(layer "In2.Cu")
		(net "P5E_CPU1_PE3_TX_DP<7>")
	)
	(segment
		(start 157.629606 -341.553546)
		(end 157.629606 -338.564982)
		(width 0.14732)
		(layer "In2.Cu")
		(net "P5E_CPU1_PE3_TX_DP<7>")
	)
	(segment
		(start 146.576034 -406.70988)
		(end 146.576034 -405.416766)
		(width 0.14732)
		(layer "In2.Cu")
		(net "P5E_CPU1_PE3_TX_DP<7>")
	)
	(segment
		(start 127.53975 -286.799782)
		(end 127.538734 -286.799274)
		(width 0.0889)
		(layer "In2.Cu")
		(net "P5E_CPU1_PE3_TX_DP<7>")
	)
	(segment
		(start 128.334008 -290.380166)
		(end 128.334008 -290.358068)
		(width 0.0889)
		(layer "In2.Cu")
		(net "P5E_CPU1_PE3_TX_DP<7>")
	)
	(segment
		(start 146.761454 -399.210276)
		(end 146.934174 -398.628362)
		(width 0.14732)
		(layer "In2.Cu")
		(net "P5E_CPU1_PE3_TX_DP<7>")
	)
	(arc
		(start 128.291844 -289.64636)
		(mid 128.366915 -289.530618)
		(end 128.476248 -289.446462)
		(width 0.0889)
		(layer "In2.Cu")
		(net "P5E_CPU1_PE3_TX_DP<7>")
	)
	(arc
		(start 127.352298 -286.467804)
		(mid 127.274669 -286.189391)
		(end 127.069596 -285.985712)
		(width 0.0889)
		(layer "In2.Cu")
		(net "P5E_CPU1_PE3_TX_DP<7>")
	)
	(arc
		(start 128.292098 -288.103056)
		(mid 128.218107 -287.82349)
		(end 128.015492 -287.617154)
		(width 0.0889)
		(layer "In2.Cu")
		(net "P5E_CPU1_PE3_TX_DP<7>")
	)
	(arc
		(start 128.761998 -288.898584)
		(mid 128.681836 -288.626395)
		(end 128.47955 -288.427414)
		(width 0.0889)
		(layer "In2.Cu")
		(net "P5E_CPU1_PE3_TX_DP<7>")
	)
	(arc
		(start 128.476248 -289.446462)
		(mid 128.650549 -289.307532)
		(end 128.761998 -289.114484)
		(width 0.0889)
		(layer "In2.Cu")
		(net "P5E_CPU1_PE3_TX_DP<7>")
	)
	(arc
		(start 128.000506 -287.608518)
		(mid 127.869592 -287.472158)
		(end 127.821944 -287.28924)
		(width 0.0889)
		(layer "In2.Cu")
		(net "P5E_CPU1_PE3_TX_DP<7>")
	)
	(arc
		(start 127.821944 -287.273746)
		(mid 127.742574 -287.000012)
		(end 127.53975 -286.799782)
		(width 0.0889)
		(layer "In2.Cu")
		(net "P5E_CPU1_PE3_TX_DP<7>")
	)
	(arc
		(start 127.53086 -286.794702)
		(mid 127.399946 -286.658342)
		(end 127.352298 -286.475424)
		(width 0.0889)
		(layer "In2.Cu")
		(net "P5E_CPU1_PE3_TX_DP<7>")
	)
	(arc
		(start 127.060706 -285.980632)
		(mid 126.929792 -285.844272)
		(end 126.882144 -285.661354)
		(width 0.0889)
		(layer "In2.Cu")
		(net "P5E_CPU1_PE3_TX_DP<7>")
	)
	(arc
		(start 126.882144 -285.661354)
		(mid 126.919004 -285.499557)
		(end 127.022098 -285.369508)
		(width 0.0889)
		(layer "In2.Cu")
		(net "P5E_CPU1_PE3_TX_DP<7>")
	)
	(arc
		(start 128.47066 -288.422334)
		(mid 128.339746 -288.285974)
		(end 128.292098 -288.103056)
		(width 0.0889)
		(layer "In2.Cu")
		(net "P5E_CPU1_PE3_TX_DP<7>")
	)
	(segment
		(start 128.196848 -285.125414)
		(end 128.196848 -285.6611)
		(width 0.13208)
		(layer "F.Cu")
		(net "P5E_CPU1_PE3_TX_DP<6>")
	)
	(segment
		(start 149.634956 -407.926286)
		(end 149.959314 -408.250644)
		(width 0.13208)
		(layer "F.Cu")
		(net "P5E_CPU1_PE3_TX_DP<6>")
	)
	(segment
		(start 128.196848 -285.6611)
		(end 128.196594 -285.661354)
		(width 0.13208)
		(layer "F.Cu")
		(net "P5E_CPU1_PE3_TX_DP<6>")
	)
	(segment
		(start 149.634956 -407.303478)
		(end 149.634956 -407.926286)
		(width 0.13208)
		(layer "F.Cu")
		(net "P5E_CPU1_PE3_TX_DP<6>")
	)
	(segment
		(start 149.933914 -407.00452)
		(end 149.634956 -407.303478)
		(width 0.13208)
		(layer "F.Cu")
		(net "P5E_CPU1_PE3_TX_DP<6>")
	)
	(segment
		(start 154.514296 -376.428254)
		(end 158.569152 -341.619586)
		(width 0.14732)
		(layer "In2.Cu")
		(net "P5E_CPU1_PE3_TX_DP<6>")
	)
	(segment
		(start 149.933914 -407.00452)
		(end 149.639274 -406.70988)
		(width 0.14732)
		(layer "In2.Cu")
		(net "P5E_CPU1_PE3_TX_DP<6>")
	)
	(segment
		(start 145.901156 -317.287148)
		(end 137.84707 -305.784504)
		(width 0.14732)
		(layer "In2.Cu")
		(net "P5E_CPU1_PE3_TX_DP<6>")
	)
	(segment
		(start 149.824694 -400.144488)
		(end 154.514296 -376.428254)
		(width 0.14732)
		(layer "In2.Cu")
		(net "P5E_CPU1_PE3_TX_DP<6>")
	)
	(segment
		(start 153.190702 -325.784464)
		(end 145.901156 -317.287148)
		(width 0.14732)
		(layer "In2.Cu")
		(net "P5E_CPU1_PE3_TX_DP<6>")
	)
	(segment
		(start 128.292098 -286.48406)
		(end 128.292098 -286.4612)
		(width 0.0889)
		(layer "In2.Cu")
		(net "P5E_CPU1_PE3_TX_DP<6>")
	)
	(segment
		(start 158.144464 -335.878424)
		(end 158.004256 -335.08315)
		(width 0.14732)
		(layer "In2.Cu")
		(net "P5E_CPU1_PE3_TX_DP<6>")
	)
	(segment
		(start 157.432756 -331.842364)
		(end 153.190702 -325.784464)
		(width 0.14732)
		(layer "In2.Cu")
		(net "P5E_CPU1_PE3_TX_DP<6>")
	)
	(segment
		(start 149.639274 -406.70988)
		(end 149.639274 -405.416766)
		(width 0.14732)
		(layer "In2.Cu")
		(net "P5E_CPU1_PE3_TX_DP<6>")
	)
	(segment
		(start 158.004256 -335.08315)
		(end 158.004256 -335.082896)
		(width 0.14732)
		(layer "In2.Cu")
		(net "P5E_CPU1_PE3_TX_DP<6>")
	)
	(segment
		(start 158.569152 -341.619586)
		(end 158.569152 -338.286852)
		(width 0.14732)
		(layer "In2.Cu")
		(net "P5E_CPU1_PE3_TX_DP<6>")
	)
	(segment
		(start 129.273554 -294.562022)
		(end 129.273554 -290.380166)
		(width 0.14732)
		(layer "In2.Cu")
		(net "P5E_CPU1_PE3_TX_DP<6>")
	)
	(segment
		(start 158.569152 -338.286852)
		(end 158.144464 -335.878424)
		(width 0.14732)
		(layer "In2.Cu")
		(net "P5E_CPU1_PE3_TX_DP<6>")
	)
	(segment
		(start 129.701544 -288.917126)
		(end 129.701798 -288.898584)
		(width 0.0889)
		(layer "In2.Cu")
		(net "P5E_CPU1_PE3_TX_DP<6>")
	)
	(segment
		(start 149.824694 -405.231346)
		(end 149.824694 -400.144488)
		(width 0.14732)
		(layer "In2.Cu")
		(net "P5E_CPU1_PE3_TX_DP<6>")
	)
	(segment
		(start 149.639274 -405.416766)
		(end 149.824694 -405.231346)
		(width 0.14732)
		(layer "In2.Cu")
		(net "P5E_CPU1_PE3_TX_DP<6>")
	)
	(segment
		(start 128.06426 -286.021526)
		(end 128.04013 -285.932372)
		(width 0.0889)
		(layer "In2.Cu")
		(net "P5E_CPU1_PE3_TX_DP<6>")
	)
	(segment
		(start 129.273554 -290.380166)
		(end 129.273554 -290.358068)
		(width 0.0889)
		(layer "In2.Cu")
		(net "P5E_CPU1_PE3_TX_DP<6>")
	)
	(segment
		(start 128.949196 -287.613598)
		(end 128.940306 -287.608518)
		(width 0.0889)
		(layer "In2.Cu")
		(net "P5E_CPU1_PE3_TX_DP<6>")
	)
	(segment
		(start 137.84707 -305.784504)
		(end 131.146804 -299.084492)
		(width 0.14732)
		(layer "In2.Cu")
		(net "P5E_CPU1_PE3_TX_DP<6>")
	)
	(segment
		(start 129.41935 -288.427414)
		(end 129.41046 -288.422334)
		(width 0.0889)
		(layer "In2.Cu")
		(net "P5E_CPU1_PE3_TX_DP<6>")
	)
	(segment
		(start 128.04013 -285.932372)
		(end 128.196594 -285.661354)
		(width 0.0889)
		(layer "In2.Cu")
		(net "P5E_CPU1_PE3_TX_DP<6>")
	)
	(segment
		(start 131.146804 -299.084492)
		(end 129.273554 -294.562022)
		(width 0.14732)
		(layer "In2.Cu")
		(net "P5E_CPU1_PE3_TX_DP<6>")
	)
	(segment
		(start 129.701544 -288.963608)
		(end 129.701544 -288.917126)
		(width 0.0889)
		(layer "In2.Cu")
		(net "P5E_CPU1_PE3_TX_DP<6>")
	)
	(segment
		(start 158.004256 -335.082896)
		(end 157.432756 -331.842364)
		(width 0.14732)
		(layer "In2.Cu")
		(net "P5E_CPU1_PE3_TX_DP<6>")
	)
	(segment
		(start 129.23139 -290.315904)
		(end 129.23139 -289.76447)
		(width 0.0889)
		(layer "In2.Cu")
		(net "P5E_CPU1_PE3_TX_DP<6>")
	)
	(segment
		(start 128.955292 -287.617154)
		(end 128.949196 -287.613598)
		(width 0.0889)
		(layer "In2.Cu")
		(net "P5E_CPU1_PE3_TX_DP<6>")
	)
	(segment
		(start 129.273554 -290.358068)
		(end 129.23139 -290.315904)
		(width 0.0889)
		(layer "In2.Cu")
		(net "P5E_CPU1_PE3_TX_DP<6>")
	)
	(segment
		(start 128.761744 -287.28924)
		(end 128.761744 -287.279334)
		(width 0.0889)
		(layer "In2.Cu")
		(net "P5E_CPU1_PE3_TX_DP<6>")
	)
	(arc
		(start 128.761744 -287.279334)
		(mid 128.683633 -287.002385)
		(end 128.479296 -286.799782)
		(width 0.0889)
		(layer "In2.Cu")
		(net "P5E_CPU1_PE3_TX_DP<6>")
	)
	(arc
		(start 129.419604 -289.443922)
		(mid 129.625916 -289.242119)
		(end 129.701544 -288.963608)
		(width 0.0889)
		(layer "In2.Cu")
		(net "P5E_CPU1_PE3_TX_DP<6>")
	)
	(arc
		(start 128.940306 -287.608518)
		(mid 128.809392 -287.472158)
		(end 128.761744 -287.28924)
		(width 0.0889)
		(layer "In2.Cu")
		(net "P5E_CPU1_PE3_TX_DP<6>")
	)
	(arc
		(start 129.701798 -288.898584)
		(mid 129.621636 -288.626395)
		(end 129.41935 -288.427414)
		(width 0.0889)
		(layer "In2.Cu")
		(net "P5E_CPU1_PE3_TX_DP<6>")
	)
	(arc
		(start 129.23139 -289.76447)
		(mid 129.281925 -289.578615)
		(end 129.419604 -289.443922)
		(width 0.0889)
		(layer "In2.Cu")
		(net "P5E_CPU1_PE3_TX_DP<6>")
	)
	(arc
		(start 128.081278 -286.03448)
		(mid 128.07283 -286.027923)
		(end 128.06426 -286.021526)
		(width 0.0889)
		(layer "In2.Cu")
		(net "P5E_CPU1_PE3_TX_DP<6>")
	)
	(arc
		(start 128.292098 -286.4612)
		(mid 128.233804 -286.224557)
		(end 128.081278 -286.03448)
		(width 0.0889)
		(layer "In2.Cu")
		(net "P5E_CPU1_PE3_TX_DP<6>")
	)
	(arc
		(start 128.479296 -286.799782)
		(mid 128.344363 -286.666428)
		(end 128.292098 -286.48406)
		(width 0.0889)
		(layer "In2.Cu")
		(net "P5E_CPU1_PE3_TX_DP<6>")
	)
	(arc
		(start 129.41046 -288.422334)
		(mid 129.279546 -288.285974)
		(end 129.231898 -288.103056)
		(width 0.0889)
		(layer "In2.Cu")
		(net "P5E_CPU1_PE3_TX_DP<6>")
	)
	(arc
		(start 129.231898 -288.103056)
		(mid 129.157907 -287.82349)
		(end 128.955292 -287.617154)
		(width 0.0889)
		(layer "In2.Cu")
		(net "P5E_CPU1_PE3_TX_DP<6>")
	)
	(segment
		(start 152.698196 -407.926286)
		(end 153.022554 -408.250644)
		(width 0.13208)
		(layer "F.Cu")
		(net "P5E_CPU1_PE3_TX_DP<5>")
	)
	(segment
		(start 129.136648 -285.6611)
		(end 129.136394 -285.661354)
		(width 0.13208)
		(layer "F.Cu")
		(net "P5E_CPU1_PE3_TX_DP<5>")
	)
	(segment
		(start 152.997154 -407.00452)
		(end 152.698196 -407.303478)
		(width 0.13208)
		(layer "F.Cu")
		(net "P5E_CPU1_PE3_TX_DP<5>")
	)
	(segment
		(start 129.136648 -285.125414)
		(end 129.136648 -285.6611)
		(width 0.13208)
		(layer "F.Cu")
		(net "P5E_CPU1_PE3_TX_DP<5>")
	)
	(segment
		(start 152.698196 -407.303478)
		(end 152.698196 -407.926286)
		(width 0.13208)
		(layer "F.Cu")
		(net "P5E_CPU1_PE3_TX_DP<5>")
	)
	(segment
		(start 128.97993 -285.390336)
		(end 129.136394 -285.661354)
		(width 0.0889)
		(layer "In2.Cu")
		(net "P5E_CPU1_PE3_TX_DP<5>")
	)
	(segment
		(start 130.35915 -288.427414)
		(end 130.35026 -288.422334)
		(width 0.0889)
		(layer "In2.Cu")
		(net "P5E_CPU1_PE3_TX_DP<5>")
	)
	(segment
		(start 129.888996 -287.613598)
		(end 129.880106 -287.608518)
		(width 0.0889)
		(layer "In2.Cu")
		(net "P5E_CPU1_PE3_TX_DP<5>")
	)
	(segment
		(start 135.35406 -295.33215)
		(end 131.548886 -293.75608)
		(width 0.14732)
		(layer "In2.Cu")
		(net "P5E_CPU1_PE3_TX_DP<5>")
	)
	(segment
		(start 130.641598 -289.114484)
		(end 130.641598 -288.898584)
		(width 0.0889)
		(layer "In2.Cu")
		(net "P5E_CPU1_PE3_TX_DP<5>")
	)
	(segment
		(start 130.213608 -290.380166)
		(end 130.213608 -290.358068)
		(width 0.0889)
		(layer "In2.Cu")
		(net "P5E_CPU1_PE3_TX_DP<5>")
	)
	(segment
		(start 129.231898 -286.475424)
		(end 129.231898 -286.467804)
		(width 0.0889)
		(layer "In2.Cu")
		(net "P5E_CPU1_PE3_TX_DP<5>")
	)
	(segment
		(start 129.895092 -287.617154)
		(end 129.888996 -287.613598)
		(width 0.0889)
		(layer "In2.Cu")
		(net "P5E_CPU1_PE3_TX_DP<5>")
	)
	(segment
		(start 152.887934 -400.144488)
		(end 153.059384 -398.634458)
		(width 0.14732)
		(layer "In2.Cu")
		(net "P5E_CPU1_PE3_TX_DP<5>")
	)
	(segment
		(start 140.828522 -308.393592)
		(end 140.057632 -307.10759)
		(width 0.14732)
		(layer "In2.Cu")
		(net "P5E_CPU1_PE3_TX_DP<5>")
	)
	(segment
		(start 153.05913 -398.63395)
		(end 153.197052 -398.524222)
		(width 0.14732)
		(layer "In2.Cu")
		(net "P5E_CPU1_PE3_TX_DP<5>")
	)
	(segment
		(start 129.701544 -287.28924)
		(end 129.701544 -287.273746)
		(width 0.0889)
		(layer "In2.Cu")
		(net "P5E_CPU1_PE3_TX_DP<5>")
	)
	(segment
		(start 159.507428 -338.127594)
		(end 158.19755 -330.701396)
		(width 0.14732)
		(layer "In2.Cu")
		(net "P5E_CPU1_PE3_TX_DP<5>")
	)
	(segment
		(start 153.37282 -396.974314)
		(end 153.263346 -396.836646)
		(width 0.14732)
		(layer "In2.Cu")
		(net "P5E_CPU1_PE3_TX_DP<5>")
	)
	(segment
		(start 152.702514 -405.416766)
		(end 152.887934 -405.231346)
		(width 0.14732)
		(layer "In2.Cu")
		(net "P5E_CPU1_PE3_TX_DP<5>")
	)
	(segment
		(start 153.197052 -398.524222)
		(end 153.246328 -398.089882)
		(width 0.14732)
		(layer "In2.Cu")
		(net "P5E_CPU1_PE3_TX_DP<5>")
	)
	(segment
		(start 136.670034 -299.50029)
		(end 136.224772 -297.000422)
		(width 0.14732)
		(layer "In2.Cu")
		(net "P5E_CPU1_PE3_TX_DP<5>")
	)
	(segment
		(start 129.418334 -286.799274)
		(end 129.41046 -286.794702)
		(width 0.0889)
		(layer "In2.Cu")
		(net "P5E_CPU1_PE3_TX_DP<5>")
	)
	(segment
		(start 153.246328 -398.089882)
		(end 153.1366 -397.952214)
		(width 0.14732)
		(layer "In2.Cu")
		(net "P5E_CPU1_PE3_TX_DP<5>")
	)
	(segment
		(start 130.213608 -290.358068)
		(end 130.171444 -290.315904)
		(width 0.0889)
		(layer "In2.Cu")
		(net "P5E_CPU1_PE3_TX_DP<5>")
	)
	(segment
		(start 153.263346 -396.836646)
		(end 159.507428 -341.778844)
		(width 0.14732)
		(layer "In2.Cu")
		(net "P5E_CPU1_PE3_TX_DP<5>")
	)
	(segment
		(start 153.185622 -397.518128)
		(end 153.323544 -397.408654)
		(width 0.14732)
		(layer "In2.Cu")
		(net "P5E_CPU1_PE3_TX_DP<5>")
	)
	(segment
		(start 136.224772 -297.000422)
		(end 135.660892 -295.638982)
		(width 0.14732)
		(layer "In2.Cu")
		(net "P5E_CPU1_PE3_TX_DP<5>")
	)
	(segment
		(start 152.887934 -405.231346)
		(end 152.887934 -400.144488)
		(width 0.14732)
		(layer "In2.Cu")
		(net "P5E_CPU1_PE3_TX_DP<5>")
	)
	(segment
		(start 159.507428 -341.778844)
		(end 159.507428 -338.127594)
		(width 0.14732)
		(layer "In2.Cu")
		(net "P5E_CPU1_PE3_TX_DP<5>")
	)
	(segment
		(start 128.949196 -285.985712)
		(end 128.940306 -285.980632)
		(width 0.0889)
		(layer "In2.Cu")
		(net "P5E_CPU1_PE3_TX_DP<5>")
	)
	(segment
		(start 152.702514 -406.70988)
		(end 152.702514 -405.416766)
		(width 0.14732)
		(layer "In2.Cu")
		(net "P5E_CPU1_PE3_TX_DP<5>")
	)
	(segment
		(start 129.41935 -286.799782)
		(end 129.418334 -286.799274)
		(width 0.0889)
		(layer "In2.Cu")
		(net "P5E_CPU1_PE3_TX_DP<5>")
	)
	(segment
		(start 140.057632 -307.10759)
		(end 136.670034 -299.50029)
		(width 0.14732)
		(layer "In2.Cu")
		(net "P5E_CPU1_PE3_TX_DP<5>")
	)
	(segment
		(start 153.1366 -397.952214)
		(end 153.185622 -397.518128)
		(width 0.14732)
		(layer "In2.Cu")
		(net "P5E_CPU1_PE3_TX_DP<5>")
	)
	(segment
		(start 128.901698 -285.369508)
		(end 128.97993 -285.390336)
		(width 0.0889)
		(layer "In2.Cu")
		(net "P5E_CPU1_PE3_TX_DP<5>")
	)
	(segment
		(start 152.997154 -407.00452)
		(end 152.702514 -406.70988)
		(width 0.14732)
		(layer "In2.Cu")
		(net "P5E_CPU1_PE3_TX_DP<5>")
	)
	(segment
		(start 131.548886 -293.75608)
		(end 130.213608 -292.420802)
		(width 0.14732)
		(layer "In2.Cu")
		(net "P5E_CPU1_PE3_TX_DP<5>")
	)
	(segment
		(start 153.323544 -397.408654)
		(end 153.37282 -396.974314)
		(width 0.14732)
		(layer "In2.Cu")
		(net "P5E_CPU1_PE3_TX_DP<5>")
	)
	(segment
		(start 135.660892 -295.638982)
		(end 135.35406 -295.33215)
		(width 0.14732)
		(layer "In2.Cu")
		(net "P5E_CPU1_PE3_TX_DP<5>")
	)
	(segment
		(start 153.059638 -398.63395)
		(end 153.05913 -398.63395)
		(width 0.14732)
		(layer "In2.Cu")
		(net "P5E_CPU1_PE3_TX_DP<5>")
	)
	(segment
		(start 158.19755 -330.701396)
		(end 140.828522 -308.393592)
		(width 0.14732)
		(layer "In2.Cu")
		(net "P5E_CPU1_PE3_TX_DP<5>")
	)
	(segment
		(start 130.171444 -290.315904)
		(end 130.171444 -289.64636)
		(width 0.0889)
		(layer "In2.Cu")
		(net "P5E_CPU1_PE3_TX_DP<5>")
	)
	(segment
		(start 153.059384 -398.634458)
		(end 153.059638 -398.63395)
		(width 0.14732)
		(layer "In2.Cu")
		(net "P5E_CPU1_PE3_TX_DP<5>")
	)
	(segment
		(start 130.213608 -292.420802)
		(end 130.213608 -290.380166)
		(width 0.14732)
		(layer "In2.Cu")
		(net "P5E_CPU1_PE3_TX_DP<5>")
	)
	(arc
		(start 128.940306 -285.980632)
		(mid 128.809392 -285.844272)
		(end 128.761744 -285.661354)
		(width 0.0889)
		(layer "In2.Cu")
		(net "P5E_CPU1_PE3_TX_DP<5>")
	)
	(arc
		(start 130.171698 -288.103056)
		(mid 130.097707 -287.82349)
		(end 129.895092 -287.617154)
		(width 0.0889)
		(layer "In2.Cu")
		(net "P5E_CPU1_PE3_TX_DP<5>")
	)
	(arc
		(start 130.35026 -288.422334)
		(mid 130.219346 -288.285974)
		(end 130.171698 -288.103056)
		(width 0.0889)
		(layer "In2.Cu")
		(net "P5E_CPU1_PE3_TX_DP<5>")
	)
	(arc
		(start 129.701544 -287.273746)
		(mid 129.622174 -287.000012)
		(end 129.41935 -286.799782)
		(width 0.0889)
		(layer "In2.Cu")
		(net "P5E_CPU1_PE3_TX_DP<5>")
	)
	(arc
		(start 129.231898 -286.467804)
		(mid 129.154269 -286.189391)
		(end 128.949196 -285.985712)
		(width 0.0889)
		(layer "In2.Cu")
		(net "P5E_CPU1_PE3_TX_DP<5>")
	)
	(arc
		(start 128.761744 -285.661354)
		(mid 128.798604 -285.499557)
		(end 128.901698 -285.369508)
		(width 0.0889)
		(layer "In2.Cu")
		(net "P5E_CPU1_PE3_TX_DP<5>")
	)
	(arc
		(start 130.171444 -289.64636)
		(mid 130.246515 -289.530618)
		(end 130.355848 -289.446462)
		(width 0.0889)
		(layer "In2.Cu")
		(net "P5E_CPU1_PE3_TX_DP<5>")
	)
	(arc
		(start 129.880106 -287.608518)
		(mid 129.749192 -287.472158)
		(end 129.701544 -287.28924)
		(width 0.0889)
		(layer "In2.Cu")
		(net "P5E_CPU1_PE3_TX_DP<5>")
	)
	(arc
		(start 129.41046 -286.794702)
		(mid 129.279546 -286.658342)
		(end 129.231898 -286.475424)
		(width 0.0889)
		(layer "In2.Cu")
		(net "P5E_CPU1_PE3_TX_DP<5>")
	)
	(arc
		(start 130.355848 -289.446462)
		(mid 130.530149 -289.307532)
		(end 130.641598 -289.114484)
		(width 0.0889)
		(layer "In2.Cu")
		(net "P5E_CPU1_PE3_TX_DP<5>")
	)
	(arc
		(start 130.641598 -288.898584)
		(mid 130.561436 -288.626395)
		(end 130.35915 -288.427414)
		(width 0.0889)
		(layer "In2.Cu")
		(net "P5E_CPU1_PE3_TX_DP<5>")
	)
	(segment
		(start 155.761436 -407.303478)
		(end 155.761436 -407.926286)
		(width 0.13208)
		(layer "F.Cu")
		(net "P5E_CPU1_PE3_TX_DP<4>")
	)
	(segment
		(start 130.076448 -285.6611)
		(end 130.076194 -285.661354)
		(width 0.13208)
		(layer "F.Cu")
		(net "P5E_CPU1_PE3_TX_DP<4>")
	)
	(segment
		(start 155.761436 -407.926286)
		(end 156.085794 -408.250644)
		(width 0.13208)
		(layer "F.Cu")
		(net "P5E_CPU1_PE3_TX_DP<4>")
	)
	(segment
		(start 156.060394 -407.00452)
		(end 155.761436 -407.303478)
		(width 0.13208)
		(layer "F.Cu")
		(net "P5E_CPU1_PE3_TX_DP<4>")
	)
	(segment
		(start 130.076448 -285.125414)
		(end 130.076448 -285.6611)
		(width 0.13208)
		(layer "F.Cu")
		(net "P5E_CPU1_PE3_TX_DP<4>")
	)
	(segment
		(start 130.828796 -287.613598)
		(end 130.827272 -287.612836)
		(width 0.0889)
		(layer "In2.Cu")
		(net "P5E_CPU1_PE3_TX_DP<4>")
	)
	(segment
		(start 130.83159 -287.615376)
		(end 130.83032 -287.614614)
		(width 0.0889)
		(layer "In2.Cu")
		(net "P5E_CPU1_PE3_TX_DP<4>")
	)
	(segment
		(start 137.16127 -296.807382)
		(end 136.459468 -295.112948)
		(width 0.14732)
		(layer "In2.Cu")
		(net "P5E_CPU1_PE3_TX_DP<4>")
	)
	(segment
		(start 131.153154 -291.977318)
		(end 131.153154 -290.446206)
		(width 0.14732)
		(layer "In2.Cu")
		(net "P5E_CPU1_PE3_TX_DP<4>")
	)
	(segment
		(start 130.641344 -287.28924)
		(end 130.641344 -287.279334)
		(width 0.0889)
		(layer "In2.Cu")
		(net "P5E_CPU1_PE3_TX_DP<4>")
	)
	(segment
		(start 130.827272 -287.612836)
		(end 130.819906 -287.608518)
		(width 0.0889)
		(layer "In2.Cu")
		(net "P5E_CPU1_PE3_TX_DP<4>")
	)
	(segment
		(start 135.734044 -294.387524)
		(end 132.028692 -292.852856)
		(width 0.14732)
		(layer "In2.Cu")
		(net "P5E_CPU1_PE3_TX_DP<4>")
	)
	(segment
		(start 156.590746 -375.748804)
		(end 160.445704 -342.67013)
		(width 0.14732)
		(layer "In2.Cu")
		(net "P5E_CPU1_PE3_TX_DP<4>")
	)
	(segment
		(start 131.29895 -288.427414)
		(end 131.29006 -288.422334)
		(width 0.0889)
		(layer "In2.Cu")
		(net "P5E_CPU1_PE3_TX_DP<4>")
	)
	(segment
		(start 130.83032 -287.614614)
		(end 130.828796 -287.613598)
		(width 0.0889)
		(layer "In2.Cu")
		(net "P5E_CPU1_PE3_TX_DP<4>")
	)
	(segment
		(start 156.060394 -407.00452)
		(end 155.765754 -406.70988)
		(width 0.14732)
		(layer "In2.Cu")
		(net "P5E_CPU1_PE3_TX_DP<4>")
	)
	(segment
		(start 129.91973 -285.932372)
		(end 130.076194 -285.661354)
		(width 0.0889)
		(layer "In2.Cu")
		(net "P5E_CPU1_PE3_TX_DP<4>")
	)
	(segment
		(start 129.94386 -286.021526)
		(end 129.91973 -285.932372)
		(width 0.0889)
		(layer "In2.Cu")
		(net "P5E_CPU1_PE3_TX_DP<4>")
	)
	(segment
		(start 131.581398 -289.114484)
		(end 131.581398 -288.898584)
		(width 0.0889)
		(layer "In2.Cu")
		(net "P5E_CPU1_PE3_TX_DP<4>")
	)
	(segment
		(start 137.605516 -299.29963)
		(end 137.16127 -296.807382)
		(width 0.14732)
		(layer "In2.Cu")
		(net "P5E_CPU1_PE3_TX_DP<4>")
	)
	(segment
		(start 136.459468 -295.112948)
		(end 135.734044 -294.387524)
		(width 0.14732)
		(layer "In2.Cu")
		(net "P5E_CPU1_PE3_TX_DP<4>")
	)
	(segment
		(start 131.11099 -290.381944)
		(end 131.11099 -289.646614)
		(width 0.0889)
		(layer "In2.Cu")
		(net "P5E_CPU1_PE3_TX_DP<4>")
	)
	(segment
		(start 130.171698 -286.48406)
		(end 130.171698 -286.4612)
		(width 0.0889)
		(layer "In2.Cu")
		(net "P5E_CPU1_PE3_TX_DP<4>")
	)
	(segment
		(start 155.951174 -405.231346)
		(end 155.951174 -400.144488)
		(width 0.14732)
		(layer "In2.Cu")
		(net "P5E_CPU1_PE3_TX_DP<4>")
	)
	(segment
		(start 160.445704 -338.088986)
		(end 159.071818 -330.299568)
		(width 0.14732)
		(layer "In2.Cu")
		(net "P5E_CPU1_PE3_TX_DP<4>")
	)
	(segment
		(start 160.445704 -342.67013)
		(end 160.445704 -338.088986)
		(width 0.14732)
		(layer "In2.Cu")
		(net "P5E_CPU1_PE3_TX_DP<4>")
	)
	(segment
		(start 131.11099 -289.646614)
		(end 131.111244 -289.64636)
		(width 0.0889)
		(layer "In2.Cu")
		(net "P5E_CPU1_PE3_TX_DP<4>")
	)
	(segment
		(start 155.765754 -405.416766)
		(end 155.951174 -405.231346)
		(width 0.14732)
		(layer "In2.Cu")
		(net "P5E_CPU1_PE3_TX_DP<4>")
	)
	(segment
		(start 130.834892 -287.617154)
		(end 130.83159 -287.615376)
		(width 0.0889)
		(layer "In2.Cu")
		(net "P5E_CPU1_PE3_TX_DP<4>")
	)
	(segment
		(start 155.951174 -400.144488)
		(end 156.590746 -375.748804)
		(width 0.14732)
		(layer "In2.Cu")
		(net "P5E_CPU1_PE3_TX_DP<4>")
	)
	(segment
		(start 132.028692 -292.852856)
		(end 131.153154 -291.977318)
		(width 0.14732)
		(layer "In2.Cu")
		(net "P5E_CPU1_PE3_TX_DP<4>")
	)
	(segment
		(start 131.153154 -290.446206)
		(end 131.153154 -290.424108)
		(width 0.0889)
		(layer "In2.Cu")
		(net "P5E_CPU1_PE3_TX_DP<4>")
	)
	(segment
		(start 159.071818 -330.299568)
		(end 141.716506 -308.009036)
		(width 0.14732)
		(layer "In2.Cu")
		(net "P5E_CPU1_PE3_TX_DP<4>")
	)
	(segment
		(start 140.814298 -306.504594)
		(end 137.605516 -299.29963)
		(width 0.14732)
		(layer "In2.Cu")
		(net "P5E_CPU1_PE3_TX_DP<4>")
	)
	(segment
		(start 155.765754 -406.70988)
		(end 155.765754 -405.416766)
		(width 0.14732)
		(layer "In2.Cu")
		(net "P5E_CPU1_PE3_TX_DP<4>")
	)
	(segment
		(start 131.153154 -290.424108)
		(end 131.11099 -290.381944)
		(width 0.0889)
		(layer "In2.Cu")
		(net "P5E_CPU1_PE3_TX_DP<4>")
	)
	(segment
		(start 141.716506 -308.009036)
		(end 140.814298 -306.504594)
		(width 0.14732)
		(layer "In2.Cu")
		(net "P5E_CPU1_PE3_TX_DP<4>")
	)
	(arc
		(start 130.819906 -287.608518)
		(mid 130.688992 -287.472158)
		(end 130.641344 -287.28924)
		(width 0.0889)
		(layer "In2.Cu")
		(net "P5E_CPU1_PE3_TX_DP<4>")
	)
	(arc
		(start 131.295648 -289.446462)
		(mid 131.469949 -289.307532)
		(end 131.581398 -289.114484)
		(width 0.0889)
		(layer "In2.Cu")
		(net "P5E_CPU1_PE3_TX_DP<4>")
	)
	(arc
		(start 130.641344 -287.279334)
		(mid 130.563233 -287.002385)
		(end 130.358896 -286.799782)
		(width 0.0889)
		(layer "In2.Cu")
		(net "P5E_CPU1_PE3_TX_DP<4>")
	)
	(arc
		(start 130.358896 -286.799782)
		(mid 130.223963 -286.666428)
		(end 130.171698 -286.48406)
		(width 0.0889)
		(layer "In2.Cu")
		(net "P5E_CPU1_PE3_TX_DP<4>")
	)
	(arc
		(start 131.581398 -288.898584)
		(mid 131.501236 -288.626395)
		(end 131.29895 -288.427414)
		(width 0.0889)
		(layer "In2.Cu")
		(net "P5E_CPU1_PE3_TX_DP<4>")
	)
	(arc
		(start 131.29006 -288.422334)
		(mid 131.159146 -288.285974)
		(end 131.111498 -288.103056)
		(width 0.0889)
		(layer "In2.Cu")
		(net "P5E_CPU1_PE3_TX_DP<4>")
	)
	(arc
		(start 129.960878 -286.03448)
		(mid 129.95243 -286.027923)
		(end 129.94386 -286.021526)
		(width 0.0889)
		(layer "In2.Cu")
		(net "P5E_CPU1_PE3_TX_DP<4>")
	)
	(arc
		(start 131.111244 -289.64636)
		(mid 131.186315 -289.530618)
		(end 131.295648 -289.446462)
		(width 0.0889)
		(layer "In2.Cu")
		(net "P5E_CPU1_PE3_TX_DP<4>")
	)
	(arc
		(start 131.111498 -288.103056)
		(mid 131.037507 -287.82349)
		(end 130.834892 -287.617154)
		(width 0.0889)
		(layer "In2.Cu")
		(net "P5E_CPU1_PE3_TX_DP<4>")
	)
	(arc
		(start 130.171698 -286.4612)
		(mid 130.113404 -286.224557)
		(end 129.960878 -286.03448)
		(width 0.0889)
		(layer "In2.Cu")
		(net "P5E_CPU1_PE3_TX_DP<4>")
	)
	(segment
		(start 159.123634 -407.00452)
		(end 158.824676 -407.303478)
		(width 0.13208)
		(layer "F.Cu")
		(net "P5E_CPU1_PE3_TX_DP<3>")
	)
	(segment
		(start 158.824676 -407.303478)
		(end 158.824676 -407.926286)
		(width 0.13208)
		(layer "F.Cu")
		(net "P5E_CPU1_PE3_TX_DP<3>")
	)
	(segment
		(start 158.824676 -407.926286)
		(end 159.149034 -408.250644)
		(width 0.13208)
		(layer "F.Cu")
		(net "P5E_CPU1_PE3_TX_DP<3>")
	)
	(segment
		(start 131.016248 -285.6611)
		(end 131.015994 -285.661354)
		(width 0.13208)
		(layer "F.Cu")
		(net "P5E_CPU1_PE3_TX_DP<3>")
	)
	(segment
		(start 131.016248 -285.125414)
		(end 131.016248 -285.6611)
		(width 0.13208)
		(layer "F.Cu")
		(net "P5E_CPU1_PE3_TX_DP<3>")
	)
	(segment
		(start 132.092954 -291.599366)
		(end 132.092954 -290.446206)
		(width 0.14732)
		(layer "In2.Cu")
		(net "P5E_CPU1_PE3_TX_DP<3>")
	)
	(segment
		(start 158.816294 -396.360396)
		(end 158.814262 -396.32382)
		(width 0.14732)
		(layer "In2.Cu")
		(net "P5E_CPU1_PE3_TX_DP<3>")
	)
	(segment
		(start 132.051044 -290.382198)
		(end 132.051044 -289.64636)
		(width 0.0889)
		(layer "In2.Cu")
		(net "P5E_CPU1_PE3_TX_DP<3>")
	)
	(segment
		(start 159.123634 -407.00452)
		(end 158.828994 -406.70988)
		(width 0.14732)
		(layer "In2.Cu")
		(net "P5E_CPU1_PE3_TX_DP<3>")
	)
	(segment
		(start 159.014414 -405.231346)
		(end 159.014414 -400.106134)
		(width 0.14732)
		(layer "In2.Cu")
		(net "P5E_CPU1_PE3_TX_DP<3>")
	)
	(segment
		(start 158.875476 -397.484092)
		(end 158.852616 -397.047974)
		(width 0.14732)
		(layer "In2.Cu")
		(net "P5E_CPU1_PE3_TX_DP<3>")
	)
	(segment
		(start 142.464282 -307.41239)
		(end 141.645132 -306.046124)
		(width 0.14732)
		(layer "In2.Cu")
		(net "P5E_CPU1_PE3_TX_DP<3>")
	)
	(segment
		(start 157.698186 -375.238772)
		(end 157.69844 -375.237248)
		(width 0.14732)
		(layer "In2.Cu")
		(net "P5E_CPU1_PE3_TX_DP<3>")
	)
	(segment
		(start 158.814262 -396.32382)
		(end 157.698186 -375.238772)
		(width 0.14732)
		(layer "In2.Cu")
		(net "P5E_CPU1_PE3_TX_DP<3>")
	)
	(segment
		(start 159.029654 -398.03832)
		(end 159.00654 -397.601948)
		(width 0.14732)
		(layer "In2.Cu")
		(net "P5E_CPU1_PE3_TX_DP<3>")
	)
	(segment
		(start 131.774692 -287.617154)
		(end 131.768596 -287.613598)
		(width 0.0889)
		(layer "In2.Cu")
		(net "P5E_CPU1_PE3_TX_DP<3>")
	)
	(segment
		(start 158.912052 -398.169384)
		(end 159.029654 -398.03832)
		(width 0.14732)
		(layer "In2.Cu")
		(net "P5E_CPU1_PE3_TX_DP<3>")
	)
	(segment
		(start 130.85953 -285.390336)
		(end 131.015994 -285.661354)
		(width 0.0889)
		(layer "In2.Cu")
		(net "P5E_CPU1_PE3_TX_DP<3>")
	)
	(segment
		(start 158.970218 -396.917164)
		(end 158.947104 -396.480538)
		(width 0.14732)
		(layer "In2.Cu")
		(net "P5E_CPU1_PE3_TX_DP<3>")
	)
	(segment
		(start 159.98571 -329.916028)
		(end 142.464282 -307.41239)
		(width 0.14732)
		(layer "In2.Cu")
		(net "P5E_CPU1_PE3_TX_DP<3>")
	)
	(segment
		(start 141.645132 -306.046124)
		(end 138.574526 -299.15231)
		(width 0.14732)
		(layer "In2.Cu")
		(net "P5E_CPU1_PE3_TX_DP<3>")
	)
	(segment
		(start 158.828994 -405.416766)
		(end 159.014414 -405.231346)
		(width 0.14732)
		(layer "In2.Cu")
		(net "P5E_CPU1_PE3_TX_DP<3>")
	)
	(segment
		(start 158.852616 -397.047974)
		(end 158.970218 -396.917164)
		(width 0.14732)
		(layer "In2.Cu")
		(net "P5E_CPU1_PE3_TX_DP<3>")
	)
	(segment
		(start 131.29895 -286.799782)
		(end 131.297934 -286.799274)
		(width 0.0889)
		(layer "In2.Cu")
		(net "P5E_CPU1_PE3_TX_DP<3>")
	)
	(segment
		(start 131.111498 -286.475424)
		(end 131.111498 -286.467804)
		(width 0.0889)
		(layer "In2.Cu")
		(net "P5E_CPU1_PE3_TX_DP<3>")
	)
	(segment
		(start 132.092954 -290.424108)
		(end 132.051044 -290.382198)
		(width 0.0889)
		(layer "In2.Cu")
		(net "P5E_CPU1_PE3_TX_DP<3>")
	)
	(segment
		(start 131.581144 -287.28924)
		(end 131.581144 -287.273746)
		(width 0.0889)
		(layer "In2.Cu")
		(net "P5E_CPU1_PE3_TX_DP<3>")
	)
	(segment
		(start 158.81604 -396.362936)
		(end 158.816294 -396.360396)
		(width 0.14732)
		(layer "In2.Cu")
		(net "P5E_CPU1_PE3_TX_DP<3>")
	)
	(segment
		(start 138.574526 -299.15231)
		(end 138.126978 -296.642028)
		(width 0.14732)
		(layer "In2.Cu")
		(net "P5E_CPU1_PE3_TX_DP<3>")
	)
	(segment
		(start 131.768596 -287.613598)
		(end 131.759706 -287.608518)
		(width 0.0889)
		(layer "In2.Cu")
		(net "P5E_CPU1_PE3_TX_DP<3>")
	)
	(segment
		(start 130.828796 -285.985712)
		(end 130.819906 -285.980632)
		(width 0.0889)
		(layer "In2.Cu")
		(net "P5E_CPU1_PE3_TX_DP<3>")
	)
	(segment
		(start 130.781298 -285.369508)
		(end 130.85953 -285.390336)
		(width 0.0889)
		(layer "In2.Cu")
		(net "P5E_CPU1_PE3_TX_DP<3>")
	)
	(segment
		(start 159.00654 -397.601948)
		(end 158.875476 -397.484092)
		(width 0.14732)
		(layer "In2.Cu")
		(net "P5E_CPU1_PE3_TX_DP<3>")
	)
	(segment
		(start 161.383726 -337.843114)
		(end 159.98571 -329.916028)
		(width 0.14732)
		(layer "In2.Cu")
		(net "P5E_CPU1_PE3_TX_DP<3>")
	)
	(segment
		(start 138.126978 -296.642028)
		(end 137.268458 -294.569134)
		(width 0.14732)
		(layer "In2.Cu")
		(net "P5E_CPU1_PE3_TX_DP<3>")
	)
	(segment
		(start 136.245092 -293.545768)
		(end 132.479542 -291.985954)
		(width 0.14732)
		(layer "In2.Cu")
		(net "P5E_CPU1_PE3_TX_DP<3>")
	)
	(segment
		(start 131.297934 -286.799274)
		(end 131.29006 -286.794702)
		(width 0.0889)
		(layer "In2.Cu")
		(net "P5E_CPU1_PE3_TX_DP<3>")
	)
	(segment
		(start 137.268458 -294.569134)
		(end 136.245092 -293.545768)
		(width 0.14732)
		(layer "In2.Cu")
		(net "P5E_CPU1_PE3_TX_DP<3>")
	)
	(segment
		(start 132.521198 -289.114484)
		(end 132.521198 -288.898584)
		(width 0.0889)
		(layer "In2.Cu")
		(net "P5E_CPU1_PE3_TX_DP<3>")
	)
	(segment
		(start 161.383726 -343.602818)
		(end 161.383726 -337.843114)
		(width 0.14732)
		(layer "In2.Cu")
		(net "P5E_CPU1_PE3_TX_DP<3>")
	)
	(segment
		(start 158.828994 -406.70988)
		(end 158.828994 -405.416766)
		(width 0.14732)
		(layer "In2.Cu")
		(net "P5E_CPU1_PE3_TX_DP<3>")
	)
	(segment
		(start 132.479542 -291.985954)
		(end 132.092954 -291.599366)
		(width 0.14732)
		(layer "In2.Cu")
		(net "P5E_CPU1_PE3_TX_DP<3>")
	)
	(segment
		(start 132.092954 -290.446206)
		(end 132.092954 -290.424108)
		(width 0.0889)
		(layer "In2.Cu")
		(net "P5E_CPU1_PE3_TX_DP<3>")
	)
	(segment
		(start 132.23875 -288.427414)
		(end 132.22986 -288.422334)
		(width 0.0889)
		(layer "In2.Cu")
		(net "P5E_CPU1_PE3_TX_DP<3>")
	)
	(segment
		(start 158.947104 -396.480538)
		(end 158.81604 -396.362936)
		(width 0.14732)
		(layer "In2.Cu")
		(net "P5E_CPU1_PE3_TX_DP<3>")
	)
	(segment
		(start 159.014414 -400.106134)
		(end 158.912052 -398.169384)
		(width 0.14732)
		(layer "In2.Cu")
		(net "P5E_CPU1_PE3_TX_DP<3>")
	)
	(segment
		(start 157.69844 -375.237248)
		(end 161.383726 -343.602818)
		(width 0.14732)
		(layer "In2.Cu")
		(net "P5E_CPU1_PE3_TX_DP<3>")
	)
	(arc
		(start 132.521198 -288.898584)
		(mid 132.441036 -288.626395)
		(end 132.23875 -288.427414)
		(width 0.0889)
		(layer "In2.Cu")
		(net "P5E_CPU1_PE3_TX_DP<3>")
	)
	(arc
		(start 130.641344 -285.661354)
		(mid 130.678204 -285.499557)
		(end 130.781298 -285.369508)
		(width 0.0889)
		(layer "In2.Cu")
		(net "P5E_CPU1_PE3_TX_DP<3>")
	)
	(arc
		(start 130.819906 -285.980632)
		(mid 130.688992 -285.844272)
		(end 130.641344 -285.661354)
		(width 0.0889)
		(layer "In2.Cu")
		(net "P5E_CPU1_PE3_TX_DP<3>")
	)
	(arc
		(start 132.235448 -289.446462)
		(mid 132.409749 -289.307532)
		(end 132.521198 -289.114484)
		(width 0.0889)
		(layer "In2.Cu")
		(net "P5E_CPU1_PE3_TX_DP<3>")
	)
	(arc
		(start 132.051044 -289.64636)
		(mid 132.126115 -289.530618)
		(end 132.235448 -289.446462)
		(width 0.0889)
		(layer "In2.Cu")
		(net "P5E_CPU1_PE3_TX_DP<3>")
	)
	(arc
		(start 132.22986 -288.422334)
		(mid 132.098946 -288.285974)
		(end 132.051298 -288.103056)
		(width 0.0889)
		(layer "In2.Cu")
		(net "P5E_CPU1_PE3_TX_DP<3>")
	)
	(arc
		(start 131.581144 -287.273746)
		(mid 131.501774 -287.000012)
		(end 131.29895 -286.799782)
		(width 0.0889)
		(layer "In2.Cu")
		(net "P5E_CPU1_PE3_TX_DP<3>")
	)
	(arc
		(start 132.051298 -288.103056)
		(mid 131.977307 -287.82349)
		(end 131.774692 -287.617154)
		(width 0.0889)
		(layer "In2.Cu")
		(net "P5E_CPU1_PE3_TX_DP<3>")
	)
	(arc
		(start 131.29006 -286.794702)
		(mid 131.159146 -286.658342)
		(end 131.111498 -286.475424)
		(width 0.0889)
		(layer "In2.Cu")
		(net "P5E_CPU1_PE3_TX_DP<3>")
	)
	(arc
		(start 131.759706 -287.608518)
		(mid 131.628792 -287.472158)
		(end 131.581144 -287.28924)
		(width 0.0889)
		(layer "In2.Cu")
		(net "P5E_CPU1_PE3_TX_DP<3>")
	)
	(arc
		(start 131.111498 -286.467804)
		(mid 131.033869 -286.189391)
		(end 130.828796 -285.985712)
		(width 0.0889)
		(layer "In2.Cu")
		(net "P5E_CPU1_PE3_TX_DP<3>")
	)
	(segment
		(start 162.186874 -407.00452)
		(end 161.887916 -407.303478)
		(width 0.13208)
		(layer "F.Cu")
		(net "P5E_CPU1_PE3_TX_DP<2>")
	)
	(segment
		(start 131.956048 -285.6611)
		(end 131.955794 -285.661354)
		(width 0.13208)
		(layer "F.Cu")
		(net "P5E_CPU1_PE3_TX_DP<2>")
	)
	(segment
		(start 161.887916 -407.926286)
		(end 162.212274 -408.250644)
		(width 0.13208)
		(layer "F.Cu")
		(net "P5E_CPU1_PE3_TX_DP<2>")
	)
	(segment
		(start 161.887916 -407.303478)
		(end 161.887916 -407.926286)
		(width 0.13208)
		(layer "F.Cu")
		(net "P5E_CPU1_PE3_TX_DP<2>")
	)
	(segment
		(start 131.956048 -285.125414)
		(end 131.956048 -285.6611)
		(width 0.13208)
		(layer "F.Cu")
		(net "P5E_CPU1_PE3_TX_DP<2>")
	)
	(segment
		(start 137.238232 -293.027354)
		(end 133.944868 -291.66312)
		(width 0.14732)
		(layer "In2.Cu")
		(net "P5E_CPU1_PE3_TX_DP<2>")
	)
	(segment
		(start 133.032754 -290.542472)
		(end 133.032754 -290.520374)
		(width 0.0889)
		(layer "In2.Cu")
		(net "P5E_CPU1_PE3_TX_DP<2>")
	)
	(segment
		(start 139.509754 -298.880276)
		(end 139.065762 -296.390568)
		(width 0.14732)
		(layer "In2.Cu")
		(net "P5E_CPU1_PE3_TX_DP<2>")
	)
	(segment
		(start 133.032754 -290.520374)
		(end 132.990844 -290.478464)
		(width 0.0889)
		(layer "In2.Cu")
		(net "P5E_CPU1_PE3_TX_DP<2>")
	)
	(segment
		(start 133.944868 -291.66312)
		(end 133.032754 -290.751006)
		(width 0.14732)
		(layer "In2.Cu")
		(net "P5E_CPU1_PE3_TX_DP<2>")
	)
	(segment
		(start 132.990844 -290.478464)
		(end 132.990844 -289.645344)
		(width 0.0889)
		(layer "In2.Cu")
		(net "P5E_CPU1_PE3_TX_DP<2>")
	)
	(segment
		(start 160.864296 -329.500738)
		(end 143.197326 -306.810156)
		(width 0.14732)
		(layer "In2.Cu")
		(net "P5E_CPU1_PE3_TX_DP<2>")
	)
	(segment
		(start 133.17474 -289.446462)
		(end 133.175248 -289.446462)
		(width 0.0889)
		(layer "In2.Cu")
		(net "P5E_CPU1_PE3_TX_DP<2>")
	)
	(segment
		(start 133.17601 -288.426144)
		(end 133.16966 -288.422334)
		(width 0.0889)
		(layer "In2.Cu")
		(net "P5E_CPU1_PE3_TX_DP<2>")
	)
	(segment
		(start 132.520944 -287.28924)
		(end 132.520944 -287.279334)
		(width 0.0889)
		(layer "In2.Cu")
		(net "P5E_CPU1_PE3_TX_DP<2>")
	)
	(segment
		(start 142.593822 -305.803808)
		(end 139.509754 -298.880276)
		(width 0.14732)
		(layer "In2.Cu")
		(net "P5E_CPU1_PE3_TX_DP<2>")
	)
	(segment
		(start 133.177026 -288.426652)
		(end 133.17601 -288.426144)
		(width 0.0889)
		(layer "In2.Cu")
		(net "P5E_CPU1_PE3_TX_DP<2>")
	)
	(segment
		(start 131.82346 -286.021526)
		(end 131.79933 -285.932372)
		(width 0.0889)
		(layer "In2.Cu")
		(net "P5E_CPU1_PE3_TX_DP<2>")
	)
	(segment
		(start 139.065762 -296.390568)
		(end 137.979912 -293.769034)
		(width 0.14732)
		(layer "In2.Cu")
		(net "P5E_CPU1_PE3_TX_DP<2>")
	)
	(segment
		(start 162.077654 -405.231346)
		(end 162.077654 -400.131788)
		(width 0.14732)
		(layer "In2.Cu")
		(net "P5E_CPU1_PE3_TX_DP<2>")
	)
	(segment
		(start 162.320478 -337.760056)
		(end 160.864296 -329.500738)
		(width 0.14732)
		(layer "In2.Cu")
		(net "P5E_CPU1_PE3_TX_DP<2>")
	)
	(segment
		(start 132.051298 -286.48406)
		(end 132.051298 -286.4612)
		(width 0.0889)
		(layer "In2.Cu")
		(net "P5E_CPU1_PE3_TX_DP<2>")
	)
	(segment
		(start 161.892234 -405.416766)
		(end 162.077654 -405.231346)
		(width 0.14732)
		(layer "In2.Cu")
		(net "P5E_CPU1_PE3_TX_DP<2>")
	)
	(segment
		(start 137.979912 -293.769034)
		(end 137.238232 -293.027354)
		(width 0.14732)
		(layer "In2.Cu")
		(net "P5E_CPU1_PE3_TX_DP<2>")
	)
	(segment
		(start 162.320478 -343.857326)
		(end 162.320478 -337.760056)
		(width 0.14732)
		(layer "In2.Cu")
		(net "P5E_CPU1_PE3_TX_DP<2>")
	)
	(segment
		(start 133.455664 -289.021774)
		(end 133.459982 -288.957512)
		(width 0.0889)
		(layer "In2.Cu")
		(net "P5E_CPU1_PE3_TX_DP<2>")
	)
	(segment
		(start 162.077654 -400.131788)
		(end 159.636714 -375.237248)
		(width 0.14732)
		(layer "In2.Cu")
		(net "P5E_CPU1_PE3_TX_DP<2>")
	)
	(segment
		(start 159.636714 -375.237248)
		(end 162.320478 -343.857326)
		(width 0.14732)
		(layer "In2.Cu")
		(net "P5E_CPU1_PE3_TX_DP<2>")
	)
	(segment
		(start 132.714492 -287.617154)
		(end 132.699506 -287.608518)
		(width 0.0889)
		(layer "In2.Cu")
		(net "P5E_CPU1_PE3_TX_DP<2>")
	)
	(segment
		(start 162.186874 -407.00452)
		(end 161.892234 -406.70988)
		(width 0.14732)
		(layer "In2.Cu")
		(net "P5E_CPU1_PE3_TX_DP<2>")
	)
	(segment
		(start 131.79933 -285.932372)
		(end 131.955794 -285.661354)
		(width 0.0889)
		(layer "In2.Cu")
		(net "P5E_CPU1_PE3_TX_DP<2>")
	)
	(segment
		(start 133.032754 -290.751006)
		(end 133.032754 -290.542472)
		(width 0.14732)
		(layer "In2.Cu")
		(net "P5E_CPU1_PE3_TX_DP<2>")
	)
	(segment
		(start 161.892234 -406.70988)
		(end 161.892234 -405.416766)
		(width 0.14732)
		(layer "In2.Cu")
		(net "P5E_CPU1_PE3_TX_DP<2>")
	)
	(segment
		(start 143.197326 -306.810156)
		(end 142.593822 -305.803808)
		(width 0.14732)
		(layer "In2.Cu")
		(net "P5E_CPU1_PE3_TX_DP<2>")
	)
	(arc
		(start 132.990844 -289.645344)
		(mid 133.065784 -289.530167)
		(end 133.17474 -289.446462)
		(width 0.0889)
		(layer "In2.Cu")
		(net "P5E_CPU1_PE3_TX_DP<2>")
	)
	(arc
		(start 131.840478 -286.03448)
		(mid 131.83203 -286.027923)
		(end 131.82346 -286.021526)
		(width 0.0889)
		(layer "In2.Cu")
		(net "P5E_CPU1_PE3_TX_DP<2>")
	)
	(arc
		(start 133.16966 -288.422334)
		(mid 133.038746 -288.285974)
		(end 132.991098 -288.103056)
		(width 0.0889)
		(layer "In2.Cu")
		(net "P5E_CPU1_PE3_TX_DP<2>")
	)
	(arc
		(start 132.520944 -287.279334)
		(mid 132.442833 -287.002385)
		(end 132.238496 -286.799782)
		(width 0.0889)
		(layer "In2.Cu")
		(net "P5E_CPU1_PE3_TX_DP<2>")
	)
	(arc
		(start 133.228842 -289.414458)
		(mid 133.387886 -289.244472)
		(end 133.455664 -289.021774)
		(width 0.0889)
		(layer "In2.Cu")
		(net "P5E_CPU1_PE3_TX_DP<2>")
	)
	(arc
		(start 133.459982 -288.957512)
		(mid 133.394509 -288.651558)
		(end 133.177026 -288.426652)
		(width 0.0889)
		(layer "In2.Cu")
		(net "P5E_CPU1_PE3_TX_DP<2>")
	)
	(arc
		(start 132.051298 -286.4612)
		(mid 131.993004 -286.224557)
		(end 131.840478 -286.03448)
		(width 0.0889)
		(layer "In2.Cu")
		(net "P5E_CPU1_PE3_TX_DP<2>")
	)
	(arc
		(start 132.991098 -288.103056)
		(mid 132.917107 -287.82349)
		(end 132.714492 -287.617154)
		(width 0.0889)
		(layer "In2.Cu")
		(net "P5E_CPU1_PE3_TX_DP<2>")
	)
	(arc
		(start 132.699506 -287.608518)
		(mid 132.568592 -287.472158)
		(end 132.520944 -287.28924)
		(width 0.0889)
		(layer "In2.Cu")
		(net "P5E_CPU1_PE3_TX_DP<2>")
	)
	(arc
		(start 132.238496 -286.799782)
		(mid 132.103563 -286.666428)
		(end 132.051298 -286.48406)
		(width 0.0889)
		(layer "In2.Cu")
		(net "P5E_CPU1_PE3_TX_DP<2>")
	)
	(arc
		(start 133.175248 -289.446462)
		(mid 133.202461 -289.431157)
		(end 133.228842 -289.414458)
		(width 0.0889)
		(layer "In2.Cu")
		(net "P5E_CPU1_PE3_TX_DP<2>")
	)
	(segment
		(start 164.951156 -407.926286)
		(end 165.275514 -408.250644)
		(width 0.13208)
		(layer "F.Cu")
		(net "P5E_CPU1_PE3_TX_DP<1>")
	)
	(segment
		(start 165.250114 -407.00452)
		(end 164.951156 -407.303478)
		(width 0.13208)
		(layer "F.Cu")
		(net "P5E_CPU1_PE3_TX_DP<1>")
	)
	(segment
		(start 164.951156 -407.303478)
		(end 164.951156 -407.926286)
		(width 0.13208)
		(layer "F.Cu")
		(net "P5E_CPU1_PE3_TX_DP<1>")
	)
	(segment
		(start 132.895848 -285.125414)
		(end 132.895848 -285.6611)
		(width 0.13208)
		(layer "F.Cu")
		(net "P5E_CPU1_PE3_TX_DP<1>")
	)
	(segment
		(start 132.895848 -285.6611)
		(end 132.895594 -285.661354)
		(width 0.13208)
		(layer "F.Cu")
		(net "P5E_CPU1_PE3_TX_DP<1>")
	)
	(segment
		(start 165.250114 -407.00452)
		(end 164.955474 -406.70988)
		(width 0.14732)
		(layer "In2.Cu")
		(net "P5E_CPU1_PE3_TX_DP<1>")
	)
	(segment
		(start 132.708396 -285.985712)
		(end 132.699506 -285.980632)
		(width 0.0889)
		(layer "In2.Cu")
		(net "P5E_CPU1_PE3_TX_DP<1>")
	)
	(segment
		(start 160.142428 -325.17461)
		(end 156.933646 -322.927218)
		(width 0.14732)
		(layer "In2.Cu")
		(net "P5E_CPU1_PE3_TX_DP<1>")
	)
	(segment
		(start 133.64845 -287.613598)
		(end 133.63956 -287.608518)
		(width 0.0889)
		(layer "In2.Cu")
		(net "P5E_CPU1_PE3_TX_DP<1>")
	)
	(segment
		(start 160.136078 -325.170038)
		(end 160.142428 -325.17461)
		(width 0.14732)
		(layer "In2.Cu")
		(net "P5E_CPU1_PE3_TX_DP<1>")
	)
	(segment
		(start 143.486632 -305.455066)
		(end 140.425678 -298.565062)
		(width 0.14732)
		(layer "In2.Cu")
		(net "P5E_CPU1_PE3_TX_DP<1>")
	)
	(segment
		(start 133.930898 -288.111692)
		(end 133.930898 -288.09315)
		(width 0.0889)
		(layer "In2.Cu")
		(net "P5E_CPU1_PE3_TX_DP<1>")
	)
	(segment
		(start 156.933646 -322.927218)
		(end 144.010888 -306.330096)
		(width 0.14732)
		(layer "In2.Cu")
		(net "P5E_CPU1_PE3_TX_DP<1>")
	)
	(segment
		(start 132.660898 -285.369508)
		(end 132.73913 -285.390336)
		(width 0.0889)
		(layer "In2.Cu")
		(net "P5E_CPU1_PE3_TX_DP<1>")
	)
	(segment
		(start 138.73861 -293.103046)
		(end 137.555224 -291.91966)
		(width 0.14732)
		(layer "In2.Cu")
		(net "P5E_CPU1_PE3_TX_DP<1>")
	)
	(segment
		(start 134.400798 -289.077654)
		(end 134.400798 -288.917634)
		(width 0.0889)
		(layer "In2.Cu")
		(net "P5E_CPU1_PE3_TX_DP<1>")
	)
	(segment
		(start 162.81527 -326.339962)
		(end 162.370516 -325.704708)
		(width 0.14732)
		(layer "In2.Cu")
		(net "P5E_CPU1_PE3_TX_DP<1>")
	)
	(segment
		(start 134.87019 -289.552126)
		(end 134.596124 -289.27806)
		(width 0.0889)
		(layer "In2.Cu")
		(net "P5E_CPU1_PE3_TX_DP<1>")
	)
	(segment
		(start 135.323326 -290.397184)
		(end 135.307832 -290.38169)
		(width 0.0889)
		(layer "In2.Cu")
		(net "P5E_CPU1_PE3_TX_DP<1>")
	)
	(segment
		(start 132.73913 -285.390336)
		(end 132.895594 -285.661354)
		(width 0.0889)
		(layer "In2.Cu")
		(net "P5E_CPU1_PE3_TX_DP<1>")
	)
	(segment
		(start 164.955474 -405.416766)
		(end 165.140894 -405.231346)
		(width 0.14732)
		(layer "In2.Cu")
		(net "P5E_CPU1_PE3_TX_DP<1>")
	)
	(segment
		(start 162.10788 -325.521066)
		(end 160.136078 -325.170038)
		(width 0.14732)
		(layer "In2.Cu")
		(net "P5E_CPU1_PE3_TX_DP<1>")
	)
	(segment
		(start 134.596124 -289.27806)
		(end 134.584948 -289.27806)
		(width 0.0889)
		(layer "In2.Cu")
		(net "P5E_CPU1_PE3_TX_DP<1>")
	)
	(segment
		(start 144.010888 -306.330096)
		(end 143.486632 -305.455066)
		(width 0.14732)
		(layer "In2.Cu")
		(net "P5E_CPU1_PE3_TX_DP<1>")
	)
	(segment
		(start 164.955474 -406.70988)
		(end 164.955474 -405.416766)
		(width 0.14732)
		(layer "In2.Cu")
		(net "P5E_CPU1_PE3_TX_DP<1>")
	)
	(segment
		(start 164.917374 -397.689832)
		(end 164.855144 -397.25727)
		(width 0.14732)
		(layer "In2.Cu")
		(net "P5E_CPU1_PE3_TX_DP<1>")
	)
	(segment
		(start 164.855144 -397.25727)
		(end 164.714174 -397.151606)
		(width 0.14732)
		(layer "In2.Cu")
		(net "P5E_CPU1_PE3_TX_DP<1>")
	)
	(segment
		(start 161.634424 -375.693686)
		(end 163.708588 -337.903566)
		(width 0.14732)
		(layer "In2.Cu")
		(net "P5E_CPU1_PE3_TX_DP<1>")
	)
	(segment
		(start 135.307832 -290.38169)
		(end 135.248904 -290.38169)
		(width 0.0889)
		(layer "In2.Cu")
		(net "P5E_CPU1_PE3_TX_DP<1>")
	)
	(segment
		(start 136.344152 -291.41801)
		(end 135.323326 -290.397184)
		(width 0.14732)
		(layer "In2.Cu")
		(net "P5E_CPU1_PE3_TX_DP<1>")
	)
	(segment
		(start 164.81171 -397.830802)
		(end 164.917374 -397.689832)
		(width 0.14732)
		(layer "In2.Cu")
		(net "P5E_CPU1_PE3_TX_DP<1>")
	)
	(segment
		(start 135.248904 -290.38169)
		(end 134.87019 -290.002976)
		(width 0.0889)
		(layer "In2.Cu")
		(net "P5E_CPU1_PE3_TX_DP<1>")
	)
	(segment
		(start 163.708588 -331.4065)
		(end 162.81527 -326.339962)
		(width 0.14732)
		(layer "In2.Cu")
		(net "P5E_CPU1_PE3_TX_DP<1>")
	)
	(segment
		(start 133.184646 -286.803338)
		(end 133.17855 -286.799782)
		(width 0.0889)
		(layer "In2.Cu")
		(net "P5E_CPU1_PE3_TX_DP<1>")
	)
	(segment
		(start 132.991098 -286.475424)
		(end 132.991098 -286.467804)
		(width 0.0889)
		(layer "In2.Cu")
		(net "P5E_CPU1_PE3_TX_DP<1>")
	)
	(segment
		(start 139.999212 -296.146474)
		(end 138.73861 -293.103046)
		(width 0.14732)
		(layer "In2.Cu")
		(net "P5E_CPU1_PE3_TX_DP<1>")
	)
	(segment
		(start 134.400798 -288.917634)
		(end 134.401052 -288.90341)
		(width 0.0889)
		(layer "In2.Cu")
		(net "P5E_CPU1_PE3_TX_DP<1>")
	)
	(segment
		(start 164.714174 -397.151606)
		(end 161.634424 -375.693686)
		(width 0.14732)
		(layer "In2.Cu")
		(net "P5E_CPU1_PE3_TX_DP<1>")
	)
	(segment
		(start 165.140894 -400.124676)
		(end 164.81171 -397.830802)
		(width 0.14732)
		(layer "In2.Cu")
		(net "P5E_CPU1_PE3_TX_DP<1>")
	)
	(segment
		(start 134.87019 -290.002976)
		(end 134.87019 -289.552126)
		(width 0.0889)
		(layer "In2.Cu")
		(net "P5E_CPU1_PE3_TX_DP<1>")
	)
	(segment
		(start 165.140894 -405.231346)
		(end 165.140894 -400.124676)
		(width 0.14732)
		(layer "In2.Cu")
		(net "P5E_CPU1_PE3_TX_DP<1>")
	)
	(segment
		(start 133.17855 -286.799782)
		(end 133.16966 -286.794702)
		(width 0.0889)
		(layer "In2.Cu")
		(net "P5E_CPU1_PE3_TX_DP<1>")
	)
	(segment
		(start 163.708588 -337.903566)
		(end 163.708588 -331.4065)
		(width 0.14732)
		(layer "In2.Cu")
		(net "P5E_CPU1_PE3_TX_DP<1>")
	)
	(segment
		(start 137.555224 -291.91966)
		(end 136.344152 -291.41801)
		(width 0.14732)
		(layer "In2.Cu")
		(net "P5E_CPU1_PE3_TX_DP<1>")
	)
	(segment
		(start 140.425678 -298.565062)
		(end 139.999212 -296.146474)
		(width 0.14732)
		(layer "In2.Cu")
		(net "P5E_CPU1_PE3_TX_DP<1>")
	)
	(segment
		(start 162.370516 -325.704708)
		(end 162.10788 -325.521066)
		(width 0.14732)
		(layer "In2.Cu")
		(net "P5E_CPU1_PE3_TX_DP<1>")
	)
	(arc
		(start 133.930898 -288.09315)
		(mid 133.852787 -287.816201)
		(end 133.64845 -287.613598)
		(width 0.0889)
		(layer "In2.Cu")
		(net "P5E_CPU1_PE3_TX_DP<1>")
	)
	(arc
		(start 132.520944 -285.661354)
		(mid 132.557804 -285.499557)
		(end 132.660898 -285.369508)
		(width 0.0889)
		(layer "In2.Cu")
		(net "P5E_CPU1_PE3_TX_DP<1>")
	)
	(arc
		(start 133.63956 -287.608518)
		(mid 133.508646 -287.472158)
		(end 133.460998 -287.28924)
		(width 0.0889)
		(layer "In2.Cu")
		(net "P5E_CPU1_PE3_TX_DP<1>")
	)
	(arc
		(start 132.991098 -286.467804)
		(mid 132.913469 -286.189391)
		(end 132.708396 -285.985712)
		(width 0.0889)
		(layer "In2.Cu")
		(net "P5E_CPU1_PE3_TX_DP<1>")
	)
	(arc
		(start 134.118096 -288.427414)
		(mid 133.983163 -288.29406)
		(end 133.930898 -288.111692)
		(width 0.0889)
		(layer "In2.Cu")
		(net "P5E_CPU1_PE3_TX_DP<1>")
	)
	(arc
		(start 133.460998 -287.28924)
		(mid 133.387082 -287.009738)
		(end 133.184646 -286.803338)
		(width 0.0889)
		(layer "In2.Cu")
		(net "P5E_CPU1_PE3_TX_DP<1>")
	)
	(arc
		(start 133.16966 -286.794702)
		(mid 133.038746 -286.658342)
		(end 132.991098 -286.475424)
		(width 0.0889)
		(layer "In2.Cu")
		(net "P5E_CPU1_PE3_TX_DP<1>")
	)
	(arc
		(start 134.401052 -288.90341)
		(mid 134.321803 -288.628435)
		(end 134.118096 -288.427414)
		(width 0.0889)
		(layer "In2.Cu")
		(net "P5E_CPU1_PE3_TX_DP<1>")
	)
	(arc
		(start 132.699506 -285.980632)
		(mid 132.568592 -285.844272)
		(end 132.520944 -285.661354)
		(width 0.0889)
		(layer "In2.Cu")
		(net "P5E_CPU1_PE3_TX_DP<1>")
	)
	(arc
		(start 134.584948 -289.27806)
		(mid 134.475678 -289.193667)
		(end 134.400798 -289.077654)
		(width 0.0889)
		(layer "In2.Cu")
		(net "P5E_CPU1_PE3_TX_DP<1>")
	)
	(segment
		(start 119.738648 -285.6611)
		(end 119.738394 -285.661354)
		(width 0.13208)
		(layer "F.Cu")
		(net "P5E_CPU1_PE3_TX_DP<15>")
	)
	(segment
		(start 122.364754 -407.00452)
		(end 122.065796 -407.303478)
		(width 0.13208)
		(layer "F.Cu")
		(net "P5E_CPU1_PE3_TX_DP<15>")
	)
	(segment
		(start 119.738648 -285.125414)
		(end 119.738648 -285.6611)
		(width 0.13208)
		(layer "F.Cu")
		(net "P5E_CPU1_PE3_TX_DP<15>")
	)
	(segment
		(start 122.065796 -407.303478)
		(end 122.065796 -407.926286)
		(width 0.13208)
		(layer "F.Cu")
		(net "P5E_CPU1_PE3_TX_DP<15>")
	)
	(segment
		(start 122.065796 -407.926286)
		(end 122.390154 -408.250644)
		(width 0.13208)
		(layer "F.Cu")
		(net "P5E_CPU1_PE3_TX_DP<15>")
	)
	(segment
		(start 149.159468 -334.856836)
		(end 150.147274 -340.451948)
		(width 0.14732)
		(layer "In2.Cu")
		(net "P5E_CPU1_PE3_TX_DP<15>")
	)
	(segment
		(start 125.230636 -396.495778)
		(end 124.99721 -396.78102)
		(width 0.14732)
		(layer "In2.Cu")
		(net "P5E_CPU1_PE3_TX_DP<15>")
	)
	(segment
		(start 120.490996 -287.613598)
		(end 120.503188 -287.62071)
		(width 0.0889)
		(layer "In2.Cu")
		(net "P5E_CPU1_PE3_TX_DP<15>")
	)
	(segment
		(start 125.210824 -396.299182)
		(end 125.230636 -396.495778)
		(width 0.14732)
		(layer "In2.Cu")
		(net "P5E_CPU1_PE3_TX_DP<15>")
	)
	(segment
		(start 150.147274 -340.451948)
		(end 147.019772 -367.291874)
		(width 0.14732)
		(layer "In2.Cu")
		(net "P5E_CPU1_PE3_TX_DP<15>")
	)
	(segment
		(start 119.363998 -285.652718)
		(end 119.363998 -285.66999)
		(width 0.0889)
		(layer "In2.Cu")
		(net "P5E_CPU1_PE3_TX_DP<15>")
	)
	(segment
		(start 120.49125 -288.592768)
		(end 120.48236 -288.597848)
		(width 0.0889)
		(layer "In2.Cu")
		(net "P5E_CPU1_PE3_TX_DP<15>")
	)
	(segment
		(start 120.773698 -288.103056)
		(end 120.773698 -288.11728)
		(width 0.0889)
		(layer "In2.Cu")
		(net "P5E_CPU1_PE3_TX_DP<15>")
	)
	(segment
		(start 119.738394 -285.661354)
		(end 119.58193 -285.390336)
		(width 0.0889)
		(layer "In2.Cu")
		(net "P5E_CPU1_PE3_TX_DP<15>")
	)
	(segment
		(start 119.833644 -290.374578)
		(end 119.875554 -290.416488)
		(width 0.0889)
		(layer "In2.Cu")
		(net "P5E_CPU1_PE3_TX_DP<15>")
	)
	(segment
		(start 144.345152 -372.897146)
		(end 125.210824 -396.299182)
		(width 0.14732)
		(layer "In2.Cu")
		(net "P5E_CPU1_PE3_TX_DP<15>")
	)
	(segment
		(start 118.918736 -297.002708)
		(end 120.461278 -300.725586)
		(width 0.14732)
		(layer "In2.Cu")
		(net "P5E_CPU1_PE3_TX_DP<15>")
	)
	(segment
		(start 119.58193 -285.390336)
		(end 119.503952 -285.369508)
		(width 0.0889)
		(layer "In2.Cu")
		(net "P5E_CPU1_PE3_TX_DP<15>")
	)
	(segment
		(start 119.875554 -290.438586)
		(end 119.875554 -291.333682)
		(width 0.14732)
		(layer "In2.Cu")
		(net "P5E_CPU1_PE3_TX_DP<15>")
	)
	(segment
		(start 119.833898 -286.4612)
		(end 119.833898 -286.475424)
		(width 0.0889)
		(layer "In2.Cu")
		(net "P5E_CPU1_PE3_TX_DP<15>")
	)
	(segment
		(start 120.01246 -286.794702)
		(end 120.02135 -286.799782)
		(width 0.0889)
		(layer "In2.Cu")
		(net "P5E_CPU1_PE3_TX_DP<15>")
	)
	(segment
		(start 120.303798 -287.279334)
		(end 120.303798 -287.297876)
		(width 0.0889)
		(layer "In2.Cu")
		(net "P5E_CPU1_PE3_TX_DP<15>")
	)
	(segment
		(start 122.255534 -405.231346)
		(end 122.070114 -405.416766)
		(width 0.14732)
		(layer "In2.Cu")
		(net "P5E_CPU1_PE3_TX_DP<15>")
	)
	(segment
		(start 120.303798 -288.917126)
		(end 120.303798 -289.114484)
		(width 0.0889)
		(layer "In2.Cu")
		(net "P5E_CPU1_PE3_TX_DP<15>")
	)
	(segment
		(start 145.787618 -330.040996)
		(end 149.159468 -334.856836)
		(width 0.14732)
		(layer "In2.Cu")
		(net "P5E_CPU1_PE3_TX_DP<15>")
	)
	(segment
		(start 122.070114 -405.416766)
		(end 122.070114 -406.70988)
		(width 0.14732)
		(layer "In2.Cu")
		(net "P5E_CPU1_PE3_TX_DP<15>")
	)
	(segment
		(start 147.019772 -367.291874)
		(end 144.345152 -372.897146)
		(width 0.14732)
		(layer "In2.Cu")
		(net "P5E_CPU1_PE3_TX_DP<15>")
	)
	(segment
		(start 138.158474 -321.146678)
		(end 145.787618 -330.040996)
		(width 0.14732)
		(layer "In2.Cu")
		(net "P5E_CPU1_PE3_TX_DP<15>")
	)
	(segment
		(start 124.157232 -397.58747)
		(end 122.255534 -399.913602)
		(width 0.14732)
		(layer "In2.Cu")
		(net "P5E_CPU1_PE3_TX_DP<15>")
	)
	(segment
		(start 119.875554 -291.333682)
		(end 118.852188 -292.357048)
		(width 0.14732)
		(layer "In2.Cu")
		(net "P5E_CPU1_PE3_TX_DP<15>")
	)
	(segment
		(start 131.797552 -312.06186)
		(end 138.158474 -321.146678)
		(width 0.14732)
		(layer "In2.Cu")
		(net "P5E_CPU1_PE3_TX_DP<15>")
	)
	(segment
		(start 118.852188 -292.357048)
		(end 118.852188 -296.624756)
		(width 0.14732)
		(layer "In2.Cu")
		(net "P5E_CPU1_PE3_TX_DP<15>")
	)
	(segment
		(start 118.852188 -296.624756)
		(end 118.918736 -297.002708)
		(width 0.14732)
		(layer "In2.Cu")
		(net "P5E_CPU1_PE3_TX_DP<15>")
	)
	(segment
		(start 122.255534 -399.913602)
		(end 122.255534 -405.231346)
		(width 0.14732)
		(layer "In2.Cu")
		(net "P5E_CPU1_PE3_TX_DP<15>")
	)
	(segment
		(start 124.567696 -397.08582)
		(end 124.587254 -397.282416)
		(width 0.14732)
		(layer "In2.Cu")
		(net "P5E_CPU1_PE3_TX_DP<15>")
	)
	(segment
		(start 119.833644 -289.64636)
		(end 119.833644 -290.374578)
		(width 0.0889)
		(layer "In2.Cu")
		(net "P5E_CPU1_PE3_TX_DP<15>")
	)
	(segment
		(start 122.070114 -406.70988)
		(end 122.364754 -407.00452)
		(width 0.14732)
		(layer "In2.Cu")
		(net "P5E_CPU1_PE3_TX_DP<15>")
	)
	(segment
		(start 124.587254 -397.282416)
		(end 124.353828 -397.567912)
		(width 0.14732)
		(layer "In2.Cu")
		(net "P5E_CPU1_PE3_TX_DP<15>")
	)
	(segment
		(start 124.353828 -397.567912)
		(end 124.157232 -397.58747)
		(width 0.14732)
		(layer "In2.Cu")
		(net "P5E_CPU1_PE3_TX_DP<15>")
	)
	(segment
		(start 124.800614 -396.800832)
		(end 124.567696 -397.08582)
		(width 0.14732)
		(layer "In2.Cu")
		(net "P5E_CPU1_PE3_TX_DP<15>")
	)
	(segment
		(start 124.99721 -396.78102)
		(end 124.800614 -396.800832)
		(width 0.14732)
		(layer "In2.Cu")
		(net "P5E_CPU1_PE3_TX_DP<15>")
	)
	(segment
		(start 119.875554 -290.416488)
		(end 119.875554 -290.438586)
		(width 0.0889)
		(layer "In2.Cu")
		(net "P5E_CPU1_PE3_TX_DP<15>")
	)
	(segment
		(start 120.461278 -300.725586)
		(end 131.797552 -312.06186)
		(width 0.14732)
		(layer "In2.Cu")
		(net "P5E_CPU1_PE3_TX_DP<15>")
	)
	(arc
		(start 120.02135 -286.799782)
		(mid 120.225685 -287.002387)
		(end 120.303798 -287.279334)
		(width 0.0889)
		(layer "In2.Cu")
		(net "P5E_CPU1_PE3_TX_DP<15>")
	)
	(arc
		(start 119.363998 -285.66999)
		(mid 119.416268 -285.852355)
		(end 119.551196 -285.985712)
		(width 0.0889)
		(layer "In2.Cu")
		(net "P5E_CPU1_PE3_TX_DP<15>")
	)
	(arc
		(start 120.303798 -287.297876)
		(mid 120.356068 -287.480241)
		(end 120.490996 -287.613598)
		(width 0.0889)
		(layer "In2.Cu")
		(net "P5E_CPU1_PE3_TX_DP<15>")
	)
	(arc
		(start 120.48236 -288.597848)
		(mid 120.351446 -288.734208)
		(end 120.303798 -288.917126)
		(width 0.0889)
		(layer "In2.Cu")
		(net "P5E_CPU1_PE3_TX_DP<15>")
	)
	(arc
		(start 119.833898 -286.475424)
		(mid 119.881577 -286.658324)
		(end 120.01246 -286.794702)
		(width 0.0889)
		(layer "In2.Cu")
		(net "P5E_CPU1_PE3_TX_DP<15>")
	)
	(arc
		(start 119.503952 -285.369508)
		(mid 119.402631 -285.495629)
		(end 119.363998 -285.652718)
		(width 0.0889)
		(layer "In2.Cu")
		(net "P5E_CPU1_PE3_TX_DP<15>")
	)
	(arc
		(start 120.773698 -288.11728)
		(mid 120.694557 -288.391903)
		(end 120.49125 -288.592768)
		(width 0.0889)
		(layer "In2.Cu")
		(net "P5E_CPU1_PE3_TX_DP<15>")
	)
	(arc
		(start 120.503188 -287.62071)
		(mid 120.701416 -287.826558)
		(end 120.773698 -288.103056)
		(width 0.0889)
		(layer "In2.Cu")
		(net "P5E_CPU1_PE3_TX_DP<15>")
	)
	(arc
		(start 120.303798 -289.114484)
		(mid 120.192402 -289.307577)
		(end 120.018048 -289.446462)
		(width 0.0889)
		(layer "In2.Cu")
		(net "P5E_CPU1_PE3_TX_DP<15>")
	)
	(arc
		(start 119.551196 -285.985712)
		(mid 119.754677 -286.186516)
		(end 119.833898 -286.4612)
		(width 0.0889)
		(layer "In2.Cu")
		(net "P5E_CPU1_PE3_TX_DP<15>")
	)
	(arc
		(start 120.018048 -289.446462)
		(mid 119.908652 -289.530559)
		(end 119.833644 -289.64636)
		(width 0.0889)
		(layer "In2.Cu")
		(net "P5E_CPU1_PE3_TX_DP<15>")
	)
	(segment
		(start 120.678448 -285.6611)
		(end 120.678194 -285.661354)
		(width 0.13208)
		(layer "F.Cu")
		(net "P5E_CPU1_PE3_TX_DP<14>")
	)
	(segment
		(start 125.427994 -407.00452)
		(end 125.129036 -407.303478)
		(width 0.13208)
		(layer "F.Cu")
		(net "P5E_CPU1_PE3_TX_DP<14>")
	)
	(segment
		(start 125.129036 -407.303478)
		(end 125.129036 -407.926286)
		(width 0.13208)
		(layer "F.Cu")
		(net "P5E_CPU1_PE3_TX_DP<14>")
	)
	(segment
		(start 120.678448 -285.125414)
		(end 120.678448 -285.6611)
		(width 0.13208)
		(layer "F.Cu")
		(net "P5E_CPU1_PE3_TX_DP<14>")
	)
	(segment
		(start 125.129036 -407.926286)
		(end 125.453394 -408.250644)
		(width 0.13208)
		(layer "F.Cu")
		(net "P5E_CPU1_PE3_TX_DP<14>")
	)
	(segment
		(start 151.083264 -341.180928)
		(end 147.978114 -367.830354)
		(width 0.14732)
		(layer "In2.Cu")
		(net "P5E_CPU1_PE3_TX_DP<14>")
	)
	(segment
		(start 132.422392 -311.31002)
		(end 138.981434 -320.677286)
		(width 0.14732)
		(layer "In2.Cu")
		(net "P5E_CPU1_PE3_TX_DP<14>")
	)
	(segment
		(start 121.755662 -290.438586)
		(end 121.755662 -291.472112)
		(width 0.14732)
		(layer "In2.Cu")
		(net "P5E_CPU1_PE3_TX_DP<14>")
	)
	(segment
		(start 120.52173 -285.932372)
		(end 120.54586 -286.021526)
		(width 0.0889)
		(layer "In2.Cu")
		(net "P5E_CPU1_PE3_TX_DP<14>")
	)
	(segment
		(start 120.678194 -285.661354)
		(end 120.52173 -285.932372)
		(width 0.0889)
		(layer "In2.Cu")
		(net "P5E_CPU1_PE3_TX_DP<14>")
	)
	(segment
		(start 125.133354 -406.70988)
		(end 125.427994 -407.00452)
		(width 0.14732)
		(layer "In2.Cu")
		(net "P5E_CPU1_PE3_TX_DP<14>")
	)
	(segment
		(start 120.77319 -286.464756)
		(end 120.773444 -286.48406)
		(width 0.0889)
		(layer "In2.Cu")
		(net "P5E_CPU1_PE3_TX_DP<14>")
	)
	(segment
		(start 121.226072 -292.001702)
		(end 121.226072 -297.282616)
		(width 0.14732)
		(layer "In2.Cu")
		(net "P5E_CPU1_PE3_TX_DP<14>")
	)
	(segment
		(start 121.755662 -290.416488)
		(end 121.755662 -290.438586)
		(width 0.0889)
		(layer "In2.Cu")
		(net "P5E_CPU1_PE3_TX_DP<14>")
	)
	(segment
		(start 122.183144 -288.917126)
		(end 122.183144 -289.113214)
		(width 0.0889)
		(layer "In2.Cu")
		(net "P5E_CPU1_PE3_TX_DP<14>")
	)
	(segment
		(start 121.226072 -297.282616)
		(end 123.227846 -302.115474)
		(width 0.14732)
		(layer "In2.Cu")
		(net "P5E_CPU1_PE3_TX_DP<14>")
	)
	(segment
		(start 150.030688 -334.340454)
		(end 151.083264 -340.305898)
		(width 0.14732)
		(layer "In2.Cu")
		(net "P5E_CPU1_PE3_TX_DP<14>")
	)
	(segment
		(start 151.083264 -340.305898)
		(end 151.083264 -341.180928)
		(width 0.14732)
		(layer "In2.Cu")
		(net "P5E_CPU1_PE3_TX_DP<14>")
	)
	(segment
		(start 147.978114 -367.830354)
		(end 145.381726 -373.497094)
		(width 0.14732)
		(layer "In2.Cu")
		(net "P5E_CPU1_PE3_TX_DP<14>")
	)
	(segment
		(start 125.133354 -405.416766)
		(end 125.133354 -406.70988)
		(width 0.14732)
		(layer "In2.Cu")
		(net "P5E_CPU1_PE3_TX_DP<14>")
	)
	(segment
		(start 125.318774 -399.877026)
		(end 125.318774 -405.231346)
		(width 0.14732)
		(layer "In2.Cu")
		(net "P5E_CPU1_PE3_TX_DP<14>")
	)
	(segment
		(start 121.713498 -290.374324)
		(end 121.755662 -290.416488)
		(width 0.0889)
		(layer "In2.Cu")
		(net "P5E_CPU1_PE3_TX_DP<14>")
	)
	(segment
		(start 122.183398 -288.898584)
		(end 122.183144 -288.917126)
		(width 0.0889)
		(layer "In2.Cu")
		(net "P5E_CPU1_PE3_TX_DP<14>")
	)
	(segment
		(start 123.227846 -302.115474)
		(end 132.422392 -311.31002)
		(width 0.14732)
		(layer "In2.Cu")
		(net "P5E_CPU1_PE3_TX_DP<14>")
	)
	(segment
		(start 125.318774 -405.231346)
		(end 125.133354 -405.416766)
		(width 0.14732)
		(layer "In2.Cu")
		(net "P5E_CPU1_PE3_TX_DP<14>")
	)
	(segment
		(start 121.713498 -289.751008)
		(end 121.713498 -290.374324)
		(width 0.0889)
		(layer "In2.Cu")
		(net "P5E_CPU1_PE3_TX_DP<14>")
	)
	(segment
		(start 121.755662 -291.472112)
		(end 121.226072 -292.001702)
		(width 0.14732)
		(layer "In2.Cu")
		(net "P5E_CPU1_PE3_TX_DP<14>")
	)
	(segment
		(start 138.981434 -320.677286)
		(end 147.04949 -330.082906)
		(width 0.14732)
		(layer "In2.Cu")
		(net "P5E_CPU1_PE3_TX_DP<14>")
	)
	(segment
		(start 120.773444 -286.48406)
		(end 120.773698 -286.48406)
		(width 0.0889)
		(layer "In2.Cu")
		(net "P5E_CPU1_PE3_TX_DP<14>")
	)
	(segment
		(start 121.421906 -287.608518)
		(end 121.430796 -287.613598)
		(width 0.0889)
		(layer "In2.Cu")
		(net "P5E_CPU1_PE3_TX_DP<14>")
	)
	(segment
		(start 121.430796 -287.613598)
		(end 121.436892 -287.617154)
		(width 0.0889)
		(layer "In2.Cu")
		(net "P5E_CPU1_PE3_TX_DP<14>")
	)
	(segment
		(start 121.243344 -287.279334)
		(end 121.243344 -287.28924)
		(width 0.0889)
		(layer "In2.Cu")
		(net "P5E_CPU1_PE3_TX_DP<14>")
	)
	(segment
		(start 145.381726 -373.497094)
		(end 125.318774 -399.877026)
		(width 0.14732)
		(layer "In2.Cu")
		(net "P5E_CPU1_PE3_TX_DP<14>")
	)
	(segment
		(start 147.04949 -330.082906)
		(end 150.030688 -334.340454)
		(width 0.14732)
		(layer "In2.Cu")
		(net "P5E_CPU1_PE3_TX_DP<14>")
	)
	(segment
		(start 121.89206 -288.422334)
		(end 121.90095 -288.427414)
		(width 0.0889)
		(layer "In2.Cu")
		(net "P5E_CPU1_PE3_TX_DP<14>")
	)
	(arc
		(start 120.960896 -286.799782)
		(mid 121.165231 -287.002387)
		(end 121.243344 -287.279334)
		(width 0.0889)
		(layer "In2.Cu")
		(net "P5E_CPU1_PE3_TX_DP<14>")
	)
	(arc
		(start 120.54586 -286.021526)
		(mid 120.554431 -286.027922)
		(end 120.562878 -286.03448)
		(width 0.0889)
		(layer "In2.Cu")
		(net "P5E_CPU1_PE3_TX_DP<14>")
	)
	(arc
		(start 120.562878 -286.03448)
		(mid 120.562495 -286.034859)
		(end 120.562116 -286.035242)
		(width 0.0889)
		(layer "In2.Cu")
		(net "P5E_CPU1_PE3_TX_DP<14>")
	)
	(arc
		(start 120.562116 -286.035242)
		(mid 120.715421 -286.226531)
		(end 120.77319 -286.464756)
		(width 0.0889)
		(layer "In2.Cu")
		(net "P5E_CPU1_PE3_TX_DP<14>")
	)
	(arc
		(start 120.773698 -286.48406)
		(mid 120.825968 -286.666425)
		(end 120.960896 -286.799782)
		(width 0.0889)
		(layer "In2.Cu")
		(net "P5E_CPU1_PE3_TX_DP<14>")
	)
	(arc
		(start 121.897394 -289.446208)
		(mid 121.762988 -289.573002)
		(end 121.713498 -289.751008)
		(width 0.0889)
		(layer "In2.Cu")
		(net "P5E_CPU1_PE3_TX_DP<14>")
	)
	(arc
		(start 121.713498 -288.103056)
		(mid 121.761177 -288.285956)
		(end 121.89206 -288.422334)
		(width 0.0889)
		(layer "In2.Cu")
		(net "P5E_CPU1_PE3_TX_DP<14>")
	)
	(arc
		(start 121.243344 -287.28924)
		(mid 121.291023 -287.47214)
		(end 121.421906 -287.608518)
		(width 0.0889)
		(layer "In2.Cu")
		(net "P5E_CPU1_PE3_TX_DP<14>")
	)
	(arc
		(start 121.436892 -287.617154)
		(mid 121.639479 -287.823505)
		(end 121.713498 -288.103056)
		(width 0.0889)
		(layer "In2.Cu")
		(net "P5E_CPU1_PE3_TX_DP<14>")
	)
	(arc
		(start 121.90095 -288.427414)
		(mid 122.103236 -288.626395)
		(end 122.183398 -288.898584)
		(width 0.0889)
		(layer "In2.Cu")
		(net "P5E_CPU1_PE3_TX_DP<14>")
	)
	(arc
		(start 122.183144 -289.113214)
		(mid 122.071914 -289.306869)
		(end 121.897394 -289.446208)
		(width 0.0889)
		(layer "In2.Cu")
		(net "P5E_CPU1_PE3_TX_DP<14>")
	)
	(segment
		(start 121.618248 -285.6611)
		(end 121.617994 -285.661354)
		(width 0.13208)
		(layer "F.Cu")
		(net "P5E_CPU1_PE3_TX_DP<13>")
	)
	(segment
		(start 128.192276 -407.303478)
		(end 128.192276 -407.926286)
		(width 0.13208)
		(layer "F.Cu")
		(net "P5E_CPU1_PE3_TX_DP<13>")
	)
	(segment
		(start 121.618248 -285.125414)
		(end 121.618248 -285.6611)
		(width 0.13208)
		(layer "F.Cu")
		(net "P5E_CPU1_PE3_TX_DP<13>")
	)
	(segment
		(start 128.192276 -407.926286)
		(end 128.516634 -408.250644)
		(width 0.13208)
		(layer "F.Cu")
		(net "P5E_CPU1_PE3_TX_DP<13>")
	)
	(segment
		(start 128.491234 -407.00452)
		(end 128.192276 -407.303478)
		(width 0.13208)
		(layer "F.Cu")
		(net "P5E_CPU1_PE3_TX_DP<13>")
	)
	(segment
		(start 121.617994 -285.661354)
		(end 121.46153 -285.390336)
		(width 0.0889)
		(layer "In2.Cu")
		(net "P5E_CPU1_PE3_TX_DP<13>")
	)
	(segment
		(start 122.694954 -291.804344)
		(end 122.15622 -292.343078)
		(width 0.14732)
		(layer "In2.Cu")
		(net "P5E_CPU1_PE3_TX_DP<13>")
	)
	(segment
		(start 130.536188 -397.009112)
		(end 130.324606 -397.31061)
		(width 0.14732)
		(layer "In2.Cu")
		(net "P5E_CPU1_PE3_TX_DP<13>")
	)
	(segment
		(start 129.545842 -398.176496)
		(end 128.382014 -399.834862)
		(width 0.14732)
		(layer "In2.Cu")
		(net "P5E_CPU1_PE3_TX_DP<13>")
	)
	(segment
		(start 122.370596 -287.613598)
		(end 122.376692 -287.617154)
		(width 0.0889)
		(layer "In2.Cu")
		(net "P5E_CPU1_PE3_TX_DP<13>")
	)
	(segment
		(start 122.15622 -297.098212)
		(end 123.983496 -301.509684)
		(width 0.14732)
		(layer "In2.Cu")
		(net "P5E_CPU1_PE3_TX_DP<13>")
	)
	(segment
		(start 128.382014 -405.231346)
		(end 128.196594 -405.416766)
		(width 0.14732)
		(layer "In2.Cu")
		(net "P5E_CPU1_PE3_TX_DP<13>")
	)
	(segment
		(start 128.382014 -399.834862)
		(end 128.382014 -405.231346)
		(width 0.14732)
		(layer "In2.Cu")
		(net "P5E_CPU1_PE3_TX_DP<13>")
	)
	(segment
		(start 150.984712 -333.989426)
		(end 152.015952 -339.84184)
		(width 0.14732)
		(layer "In2.Cu")
		(net "P5E_CPU1_PE3_TX_DP<13>")
	)
	(segment
		(start 122.15622 -292.343078)
		(end 122.15622 -297.098212)
		(width 0.14732)
		(layer "In2.Cu")
		(net "P5E_CPU1_PE3_TX_DP<13>")
	)
	(segment
		(start 148.81606 -368.690906)
		(end 146.454114 -374.085104)
		(width 0.14732)
		(layer "In2.Cu")
		(net "P5E_CPU1_PE3_TX_DP<13>")
	)
	(segment
		(start 129.740914 -398.14246)
		(end 129.545842 -398.176496)
		(width 0.14732)
		(layer "In2.Cu")
		(net "P5E_CPU1_PE3_TX_DP<13>")
	)
	(segment
		(start 129.952496 -397.840708)
		(end 129.740914 -398.14246)
		(width 0.14732)
		(layer "In2.Cu")
		(net "P5E_CPU1_PE3_TX_DP<13>")
	)
	(segment
		(start 122.694954 -290.438586)
		(end 122.694954 -291.804344)
		(width 0.14732)
		(layer "In2.Cu")
		(net "P5E_CPU1_PE3_TX_DP<13>")
	)
	(segment
		(start 128.196594 -405.416766)
		(end 128.196594 -406.70988)
		(width 0.14732)
		(layer "In2.Cu")
		(net "P5E_CPU1_PE3_TX_DP<13>")
	)
	(segment
		(start 130.129534 -397.3449)
		(end 129.918206 -397.646144)
		(width 0.14732)
		(layer "In2.Cu")
		(net "P5E_CPU1_PE3_TX_DP<13>")
	)
	(segment
		(start 146.454114 -374.085104)
		(end 130.501898 -396.814294)
		(width 0.14732)
		(layer "In2.Cu")
		(net "P5E_CPU1_PE3_TX_DP<13>")
	)
	(segment
		(start 121.713498 -286.467804)
		(end 121.713498 -286.475424)
		(width 0.0889)
		(layer "In2.Cu")
		(net "P5E_CPU1_PE3_TX_DP<13>")
	)
	(segment
		(start 130.501898 -396.814294)
		(end 130.536188 -397.009112)
		(width 0.14732)
		(layer "In2.Cu")
		(net "P5E_CPU1_PE3_TX_DP<13>")
	)
	(segment
		(start 151.814784 -342.95588)
		(end 151.81453 -342.956388)
		(width 0.14732)
		(layer "In2.Cu")
		(net "P5E_CPU1_PE3_TX_DP<13>")
	)
	(segment
		(start 140.175742 -320.64071)
		(end 148.131022 -329.914504)
		(width 0.14732)
		(layer "In2.Cu")
		(net "P5E_CPU1_PE3_TX_DP<13>")
	)
	(segment
		(start 121.89206 -286.794702)
		(end 121.899934 -286.799274)
		(width 0.0889)
		(layer "In2.Cu")
		(net "P5E_CPU1_PE3_TX_DP<13>")
	)
	(segment
		(start 133.311646 -310.837834)
		(end 140.175742 -320.64071)
		(width 0.14732)
		(layer "In2.Cu")
		(net "P5E_CPU1_PE3_TX_DP<13>")
	)
	(segment
		(start 122.361706 -287.608518)
		(end 122.370596 -287.613598)
		(width 0.0889)
		(layer "In2.Cu")
		(net "P5E_CPU1_PE3_TX_DP<13>")
	)
	(segment
		(start 122.183144 -287.273746)
		(end 122.183144 -287.28924)
		(width 0.0889)
		(layer "In2.Cu")
		(net "P5E_CPU1_PE3_TX_DP<13>")
	)
	(segment
		(start 122.83186 -288.422334)
		(end 122.84075 -288.427414)
		(width 0.0889)
		(layer "In2.Cu")
		(net "P5E_CPU1_PE3_TX_DP<13>")
	)
	(segment
		(start 121.46153 -285.390336)
		(end 121.383298 -285.369508)
		(width 0.0889)
		(layer "In2.Cu")
		(net "P5E_CPU1_PE3_TX_DP<13>")
	)
	(segment
		(start 128.196594 -406.70988)
		(end 128.491234 -407.00452)
		(width 0.14732)
		(layer "In2.Cu")
		(net "P5E_CPU1_PE3_TX_DP<13>")
	)
	(segment
		(start 122.65279 -289.646614)
		(end 122.65279 -290.374324)
		(width 0.0889)
		(layer "In2.Cu")
		(net "P5E_CPU1_PE3_TX_DP<13>")
	)
	(segment
		(start 122.653044 -289.64636)
		(end 122.65279 -289.646614)
		(width 0.0889)
		(layer "In2.Cu")
		(net "P5E_CPU1_PE3_TX_DP<13>")
	)
	(segment
		(start 122.694954 -290.416488)
		(end 122.694954 -290.438586)
		(width 0.0889)
		(layer "In2.Cu")
		(net "P5E_CPU1_PE3_TX_DP<13>")
	)
	(segment
		(start 151.81453 -342.95588)
		(end 151.814784 -342.95588)
		(width 0.14732)
		(layer "In2.Cu")
		(net "P5E_CPU1_PE3_TX_DP<13>")
	)
	(segment
		(start 129.918206 -397.646144)
		(end 129.952496 -397.840708)
		(width 0.14732)
		(layer "In2.Cu")
		(net "P5E_CPU1_PE3_TX_DP<13>")
	)
	(segment
		(start 152.015952 -341.227156)
		(end 151.81453 -342.95588)
		(width 0.14732)
		(layer "In2.Cu")
		(net "P5E_CPU1_PE3_TX_DP<13>")
	)
	(segment
		(start 121.421906 -285.980632)
		(end 121.430796 -285.985712)
		(width 0.0889)
		(layer "In2.Cu")
		(net "P5E_CPU1_PE3_TX_DP<13>")
	)
	(segment
		(start 123.123198 -288.898584)
		(end 123.123198 -289.114484)
		(width 0.0889)
		(layer "In2.Cu")
		(net "P5E_CPU1_PE3_TX_DP<13>")
	)
	(segment
		(start 121.899934 -286.799274)
		(end 121.90095 -286.799782)
		(width 0.0889)
		(layer "In2.Cu")
		(net "P5E_CPU1_PE3_TX_DP<13>")
	)
	(segment
		(start 130.324606 -397.31061)
		(end 130.129534 -397.3449)
		(width 0.14732)
		(layer "In2.Cu")
		(net "P5E_CPU1_PE3_TX_DP<13>")
	)
	(segment
		(start 123.983496 -301.509684)
		(end 133.311646 -310.837834)
		(width 0.14732)
		(layer "In2.Cu")
		(net "P5E_CPU1_PE3_TX_DP<13>")
	)
	(segment
		(start 151.81453 -342.956388)
		(end 148.81606 -368.690906)
		(width 0.14732)
		(layer "In2.Cu")
		(net "P5E_CPU1_PE3_TX_DP<13>")
	)
	(segment
		(start 152.015952 -339.84184)
		(end 152.015952 -341.227156)
		(width 0.14732)
		(layer "In2.Cu")
		(net "P5E_CPU1_PE3_TX_DP<13>")
	)
	(segment
		(start 122.65279 -290.374324)
		(end 122.694954 -290.416488)
		(width 0.0889)
		(layer "In2.Cu")
		(net "P5E_CPU1_PE3_TX_DP<13>")
	)
	(segment
		(start 148.131022 -329.914504)
		(end 150.984712 -333.989426)
		(width 0.14732)
		(layer "In2.Cu")
		(net "P5E_CPU1_PE3_TX_DP<13>")
	)
	(arc
		(start 121.90095 -286.799782)
		(mid 122.103773 -287.000013)
		(end 122.183144 -287.273746)
		(width 0.0889)
		(layer "In2.Cu")
		(net "P5E_CPU1_PE3_TX_DP<13>")
	)
	(arc
		(start 121.713498 -286.475424)
		(mid 121.761177 -286.658324)
		(end 121.89206 -286.794702)
		(width 0.0889)
		(layer "In2.Cu")
		(net "P5E_CPU1_PE3_TX_DP<13>")
	)
	(arc
		(start 121.383298 -285.369508)
		(mid 121.280153 -285.499533)
		(end 121.243344 -285.661354)
		(width 0.0889)
		(layer "In2.Cu")
		(net "P5E_CPU1_PE3_TX_DP<13>")
	)
	(arc
		(start 123.123198 -289.114484)
		(mid 123.011802 -289.307577)
		(end 122.837448 -289.446462)
		(width 0.0889)
		(layer "In2.Cu")
		(net "P5E_CPU1_PE3_TX_DP<13>")
	)
	(arc
		(start 122.653298 -288.103056)
		(mid 122.700977 -288.285956)
		(end 122.83186 -288.422334)
		(width 0.0889)
		(layer "In2.Cu")
		(net "P5E_CPU1_PE3_TX_DP<13>")
	)
	(arc
		(start 121.430796 -285.985712)
		(mid 121.635868 -286.189391)
		(end 121.713498 -286.467804)
		(width 0.0889)
		(layer "In2.Cu")
		(net "P5E_CPU1_PE3_TX_DP<13>")
	)
	(arc
		(start 122.183144 -287.28924)
		(mid 122.230823 -287.47214)
		(end 122.361706 -287.608518)
		(width 0.0889)
		(layer "In2.Cu")
		(net "P5E_CPU1_PE3_TX_DP<13>")
	)
	(arc
		(start 122.837448 -289.446462)
		(mid 122.728052 -289.530559)
		(end 122.653044 -289.64636)
		(width 0.0889)
		(layer "In2.Cu")
		(net "P5E_CPU1_PE3_TX_DP<13>")
	)
	(arc
		(start 122.84075 -288.427414)
		(mid 123.043036 -288.626395)
		(end 123.123198 -288.898584)
		(width 0.0889)
		(layer "In2.Cu")
		(net "P5E_CPU1_PE3_TX_DP<13>")
	)
	(arc
		(start 122.376692 -287.617154)
		(mid 122.579279 -287.823505)
		(end 122.653298 -288.103056)
		(width 0.0889)
		(layer "In2.Cu")
		(net "P5E_CPU1_PE3_TX_DP<13>")
	)
	(arc
		(start 121.243344 -285.661354)
		(mid 121.291023 -285.844254)
		(end 121.421906 -285.980632)
		(width 0.0889)
		(layer "In2.Cu")
		(net "P5E_CPU1_PE3_TX_DP<13>")
	)
	(segment
		(start 131.255516 -407.926286)
		(end 131.579874 -408.250644)
		(width 0.13208)
		(layer "F.Cu")
		(net "P5E_CPU1_PE3_TX_DP<12>")
	)
	(segment
		(start 131.255516 -407.303478)
		(end 131.255516 -407.926286)
		(width 0.13208)
		(layer "F.Cu")
		(net "P5E_CPU1_PE3_TX_DP<12>")
	)
	(segment
		(start 122.558048 -285.6611)
		(end 122.557794 -285.661354)
		(width 0.13208)
		(layer "F.Cu")
		(net "P5E_CPU1_PE3_TX_DP<12>")
	)
	(segment
		(start 131.554474 -407.00452)
		(end 131.255516 -407.303478)
		(width 0.13208)
		(layer "F.Cu")
		(net "P5E_CPU1_PE3_TX_DP<12>")
	)
	(segment
		(start 122.558048 -285.125414)
		(end 122.558048 -285.6611)
		(width 0.13208)
		(layer "F.Cu")
		(net "P5E_CPU1_PE3_TX_DP<12>")
	)
	(segment
		(start 147.041362 -375.51614)
		(end 131.445254 -399.78584)
		(width 0.14732)
		(layer "In2.Cu")
		(net "P5E_CPU1_PE3_TX_DP<12>")
	)
	(segment
		(start 152.948894 -339.73135)
		(end 152.948894 -341.382858)
		(width 0.14732)
		(layer "In2.Cu")
		(net "P5E_CPU1_PE3_TX_DP<12>")
	)
	(segment
		(start 131.445254 -399.78584)
		(end 131.445254 -405.231346)
		(width 0.14732)
		(layer "In2.Cu")
		(net "P5E_CPU1_PE3_TX_DP<12>")
	)
	(segment
		(start 131.259834 -405.416766)
		(end 131.259834 -406.70988)
		(width 0.14732)
		(layer "In2.Cu")
		(net "P5E_CPU1_PE3_TX_DP<12>")
	)
	(segment
		(start 122.557794 -285.661354)
		(end 122.40133 -285.932372)
		(width 0.0889)
		(layer "In2.Cu")
		(net "P5E_CPU1_PE3_TX_DP<12>")
	)
	(segment
		(start 133.867906 -310.008524)
		(end 133.89483 -310.046878)
		(width 0.14732)
		(layer "In2.Cu")
		(net "P5E_CPU1_PE3_TX_DP<12>")
	)
	(segment
		(start 140.898626 -320.050414)
		(end 148.870924 -329.345036)
		(width 0.14732)
		(layer "In2.Cu")
		(net "P5E_CPU1_PE3_TX_DP<12>")
	)
	(segment
		(start 123.122944 -287.279334)
		(end 123.122944 -287.28924)
		(width 0.0889)
		(layer "In2.Cu")
		(net "P5E_CPU1_PE3_TX_DP<12>")
	)
	(segment
		(start 123.635262 -290.375848)
		(end 123.635262 -295.53027)
		(width 0.14732)
		(layer "In2.Cu")
		(net "P5E_CPU1_PE3_TX_DP<12>")
	)
	(segment
		(start 133.89483 -310.047132)
		(end 140.898626 -320.050414)
		(width 0.14732)
		(layer "In2.Cu")
		(net "P5E_CPU1_PE3_TX_DP<12>")
	)
	(segment
		(start 123.301506 -287.608518)
		(end 123.310396 -287.613598)
		(width 0.0889)
		(layer "In2.Cu")
		(net "P5E_CPU1_PE3_TX_DP<12>")
	)
	(segment
		(start 126.64186 -302.788828)
		(end 133.846316 -309.99303)
		(width 0.14732)
		(layer "In2.Cu")
		(net "P5E_CPU1_PE3_TX_DP<12>")
	)
	(segment
		(start 133.89483 -310.046878)
		(end 133.89483 -310.047132)
		(width 0.14732)
		(layer "In2.Cu")
		(net "P5E_CPU1_PE3_TX_DP<12>")
	)
	(segment
		(start 133.846316 -309.99303)
		(end 133.867906 -310.008524)
		(width 0.14732)
		(layer "In2.Cu")
		(net "P5E_CPU1_PE3_TX_DP<12>")
	)
	(segment
		(start 131.445254 -405.231346)
		(end 131.259834 -405.416766)
		(width 0.14732)
		(layer "In2.Cu")
		(net "P5E_CPU1_PE3_TX_DP<12>")
	)
	(segment
		(start 123.79325 -289.42792)
		(end 123.669044 -289.49015)
		(width 0.0889)
		(layer "In2.Cu")
		(net "P5E_CPU1_PE3_TX_DP<12>")
	)
	(segment
		(start 152.948894 -341.382858)
		(end 149.692868 -369.329462)
		(width 0.14732)
		(layer "In2.Cu")
		(net "P5E_CPU1_PE3_TX_DP<12>")
	)
	(segment
		(start 131.259834 -406.70988)
		(end 131.554474 -407.00452)
		(width 0.14732)
		(layer "In2.Cu")
		(net "P5E_CPU1_PE3_TX_DP<12>")
	)
	(segment
		(start 123.593098 -290.311586)
		(end 123.635262 -290.35375)
		(width 0.0889)
		(layer "In2.Cu")
		(net "P5E_CPU1_PE3_TX_DP<12>")
	)
	(segment
		(start 123.310396 -287.613598)
		(end 123.316492 -287.617154)
		(width 0.0889)
		(layer "In2.Cu")
		(net "P5E_CPU1_PE3_TX_DP<12>")
	)
	(segment
		(start 123.593098 -289.613086)
		(end 123.593098 -290.311586)
		(width 0.0889)
		(layer "In2.Cu")
		(net "P5E_CPU1_PE3_TX_DP<12>")
	)
	(segment
		(start 149.692868 -369.329462)
		(end 147.284186 -375.054876)
		(width 0.14732)
		(layer "In2.Cu")
		(net "P5E_CPU1_PE3_TX_DP<12>")
	)
	(segment
		(start 151.871934 -333.63154)
		(end 152.948894 -339.73135)
		(width 0.14732)
		(layer "In2.Cu")
		(net "P5E_CPU1_PE3_TX_DP<12>")
	)
	(segment
		(start 124.062998 -288.898584)
		(end 124.062998 -289.114484)
		(width 0.0889)
		(layer "In2.Cu")
		(net "P5E_CPU1_PE3_TX_DP<12>")
	)
	(segment
		(start 123.635262 -290.35375)
		(end 123.635262 -290.375848)
		(width 0.0889)
		(layer "In2.Cu")
		(net "P5E_CPU1_PE3_TX_DP<12>")
	)
	(segment
		(start 148.870924 -329.345036)
		(end 151.871934 -333.63154)
		(width 0.14732)
		(layer "In2.Cu")
		(net "P5E_CPU1_PE3_TX_DP<12>")
	)
	(segment
		(start 122.653298 -286.4612)
		(end 122.653298 -286.48406)
		(width 0.0889)
		(layer "In2.Cu")
		(net "P5E_CPU1_PE3_TX_DP<12>")
	)
	(segment
		(start 123.77166 -288.422334)
		(end 123.78055 -288.427414)
		(width 0.0889)
		(layer "In2.Cu")
		(net "P5E_CPU1_PE3_TX_DP<12>")
	)
	(segment
		(start 123.635262 -295.53027)
		(end 126.64186 -302.788828)
		(width 0.14732)
		(layer "In2.Cu")
		(net "P5E_CPU1_PE3_TX_DP<12>")
	)
	(segment
		(start 122.40133 -285.932372)
		(end 122.42546 -286.021526)
		(width 0.0889)
		(layer "In2.Cu")
		(net "P5E_CPU1_PE3_TX_DP<12>")
	)
	(segment
		(start 147.284186 -375.054876)
		(end 147.041362 -375.51614)
		(width 0.14732)
		(layer "In2.Cu")
		(net "P5E_CPU1_PE3_TX_DP<12>")
	)
	(arc
		(start 123.669044 -289.49015)
		(mid 123.613593 -289.540826)
		(end 123.593098 -289.613086)
		(width 0.0889)
		(layer "In2.Cu")
		(net "P5E_CPU1_PE3_TX_DP<12>")
	)
	(arc
		(start 122.840496 -286.799782)
		(mid 123.044831 -287.002387)
		(end 123.122944 -287.279334)
		(width 0.0889)
		(layer "In2.Cu")
		(net "P5E_CPU1_PE3_TX_DP<12>")
	)
	(arc
		(start 123.122944 -287.28924)
		(mid 123.170623 -287.47214)
		(end 123.301506 -287.608518)
		(width 0.0889)
		(layer "In2.Cu")
		(net "P5E_CPU1_PE3_TX_DP<12>")
	)
	(arc
		(start 123.316492 -287.617154)
		(mid 123.519079 -287.823505)
		(end 123.593098 -288.103056)
		(width 0.0889)
		(layer "In2.Cu")
		(net "P5E_CPU1_PE3_TX_DP<12>")
	)
	(arc
		(start 124.062998 -289.114484)
		(mid 123.957794 -289.296724)
		(end 123.79325 -289.42792)
		(width 0.0889)
		(layer "In2.Cu")
		(net "P5E_CPU1_PE3_TX_DP<12>")
	)
	(arc
		(start 122.442478 -286.03448)
		(mid 122.594965 -286.224576)
		(end 122.653298 -286.4612)
		(width 0.0889)
		(layer "In2.Cu")
		(net "P5E_CPU1_PE3_TX_DP<12>")
	)
	(arc
		(start 122.42546 -286.021526)
		(mid 122.434031 -286.027922)
		(end 122.442478 -286.03448)
		(width 0.0889)
		(layer "In2.Cu")
		(net "P5E_CPU1_PE3_TX_DP<12>")
	)
	(arc
		(start 123.78055 -288.427414)
		(mid 123.982836 -288.626395)
		(end 124.062998 -288.898584)
		(width 0.0889)
		(layer "In2.Cu")
		(net "P5E_CPU1_PE3_TX_DP<12>")
	)
	(arc
		(start 123.593098 -288.103056)
		(mid 123.640777 -288.285956)
		(end 123.77166 -288.422334)
		(width 0.0889)
		(layer "In2.Cu")
		(net "P5E_CPU1_PE3_TX_DP<12>")
	)
	(arc
		(start 122.653298 -286.48406)
		(mid 122.705568 -286.666425)
		(end 122.840496 -286.799782)
		(width 0.0889)
		(layer "In2.Cu")
		(net "P5E_CPU1_PE3_TX_DP<12>")
	)
	(segment
		(start 123.497848 -285.6611)
		(end 123.497594 -285.661354)
		(width 0.13208)
		(layer "F.Cu")
		(net "P5E_CPU1_PE3_TX_DP<11>")
	)
	(segment
		(start 123.497848 -285.125414)
		(end 123.497848 -285.6611)
		(width 0.13208)
		(layer "F.Cu")
		(net "P5E_CPU1_PE3_TX_DP<11>")
	)
	(segment
		(start 134.318756 -407.303478)
		(end 134.318756 -407.926286)
		(width 0.13208)
		(layer "F.Cu")
		(net "P5E_CPU1_PE3_TX_DP<11>")
	)
	(segment
		(start 134.318756 -407.926286)
		(end 134.643114 -408.250644)
		(width 0.13208)
		(layer "F.Cu")
		(net "P5E_CPU1_PE3_TX_DP<11>")
	)
	(segment
		(start 134.617714 -407.00452)
		(end 134.318756 -407.303478)
		(width 0.13208)
		(layer "F.Cu")
		(net "P5E_CPU1_PE3_TX_DP<11>")
	)
	(segment
		(start 141.857476 -319.73139)
		(end 149.57298 -328.726292)
		(width 0.14732)
		(layer "In2.Cu")
		(net "P5E_CPU1_PE3_TX_DP<11>")
	)
	(segment
		(start 123.593098 -286.467804)
		(end 123.593098 -286.475424)
		(width 0.0889)
		(layer "In2.Cu")
		(net "P5E_CPU1_PE3_TX_DP<11>")
	)
	(segment
		(start 124.574808 -290.403534)
		(end 124.574808 -295.368472)
		(width 0.14732)
		(layer "In2.Cu")
		(net "P5E_CPU1_PE3_TX_DP<11>")
	)
	(segment
		(start 153.88209 -341.41283)
		(end 150.514558 -370.317014)
		(width 0.14732)
		(layer "In2.Cu")
		(net "P5E_CPU1_PE3_TX_DP<11>")
	)
	(segment
		(start 123.779534 -286.799274)
		(end 123.78055 -286.799782)
		(width 0.0889)
		(layer "In2.Cu")
		(net "P5E_CPU1_PE3_TX_DP<11>")
	)
	(segment
		(start 124.53239 -290.313364)
		(end 124.574554 -290.355528)
		(width 0.0889)
		(layer "In2.Cu")
		(net "P5E_CPU1_PE3_TX_DP<11>")
	)
	(segment
		(start 134.508494 -399.725642)
		(end 134.508494 -405.231346)
		(width 0.14732)
		(layer "In2.Cu")
		(net "P5E_CPU1_PE3_TX_DP<11>")
	)
	(segment
		(start 136.410446 -396.719552)
		(end 136.226042 -397.038576)
		(width 0.14732)
		(layer "In2.Cu")
		(net "P5E_CPU1_PE3_TX_DP<11>")
	)
	(segment
		(start 123.497594 -285.661354)
		(end 123.34113 -285.390336)
		(width 0.0889)
		(layer "In2.Cu")
		(net "P5E_CPU1_PE3_TX_DP<11>")
	)
	(segment
		(start 123.77166 -286.794702)
		(end 123.779534 -286.799274)
		(width 0.0889)
		(layer "In2.Cu")
		(net "P5E_CPU1_PE3_TX_DP<11>")
	)
	(segment
		(start 136.226042 -397.038576)
		(end 136.03478 -397.08963)
		(width 0.14732)
		(layer "In2.Cu")
		(net "P5E_CPU1_PE3_TX_DP<11>")
	)
	(segment
		(start 135.901176 -397.5989)
		(end 135.716772 -397.917924)
		(width 0.14732)
		(layer "In2.Cu")
		(net "P5E_CPU1_PE3_TX_DP<11>")
	)
	(segment
		(start 123.301506 -285.980632)
		(end 123.310396 -285.985712)
		(width 0.0889)
		(layer "In2.Cu")
		(net "P5E_CPU1_PE3_TX_DP<11>")
	)
	(segment
		(start 134.676896 -309.475378)
		(end 141.857476 -319.73139)
		(width 0.14732)
		(layer "In2.Cu")
		(net "P5E_CPU1_PE3_TX_DP<11>")
	)
	(segment
		(start 124.574554 -290.355528)
		(end 124.574554 -290.377372)
		(width 0.0889)
		(layer "In2.Cu")
		(net "P5E_CPU1_PE3_TX_DP<11>")
	)
	(segment
		(start 124.574808 -295.368472)
		(end 127.4064 -302.204882)
		(width 0.14732)
		(layer "In2.Cu")
		(net "P5E_CPU1_PE3_TX_DP<11>")
	)
	(segment
		(start 150.514558 -370.317014)
		(end 148.212302 -376.052588)
		(width 0.14732)
		(layer "In2.Cu")
		(net "P5E_CPU1_PE3_TX_DP<11>")
	)
	(segment
		(start 123.34113 -285.390336)
		(end 123.262898 -285.369508)
		(width 0.0889)
		(layer "In2.Cu")
		(net "P5E_CPU1_PE3_TX_DP<11>")
	)
	(segment
		(start 152.753822 -333.269082)
		(end 153.88209 -339.662008)
		(width 0.14732)
		(layer "In2.Cu")
		(net "P5E_CPU1_PE3_TX_DP<11>")
	)
	(segment
		(start 134.323074 -405.416766)
		(end 134.323074 -406.70988)
		(width 0.14732)
		(layer "In2.Cu")
		(net "P5E_CPU1_PE3_TX_DP<11>")
	)
	(segment
		(start 124.241306 -287.608518)
		(end 124.248672 -287.612836)
		(width 0.0889)
		(layer "In2.Cu")
		(net "P5E_CPU1_PE3_TX_DP<11>")
	)
	(segment
		(start 124.574554 -290.377372)
		(end 124.574808 -290.403534)
		(width 0.14732)
		(layer "In2.Cu")
		(net "P5E_CPU1_PE3_TX_DP<11>")
	)
	(segment
		(start 134.323074 -406.70988)
		(end 134.617714 -407.00452)
		(width 0.14732)
		(layer "In2.Cu")
		(net "P5E_CPU1_PE3_TX_DP<11>")
	)
	(segment
		(start 153.88209 -339.662008)
		(end 153.88209 -341.41283)
		(width 0.14732)
		(layer "In2.Cu")
		(net "P5E_CPU1_PE3_TX_DP<11>")
	)
	(segment
		(start 134.508494 -405.231346)
		(end 134.323074 -405.416766)
		(width 0.14732)
		(layer "In2.Cu")
		(net "P5E_CPU1_PE3_TX_DP<11>")
	)
	(segment
		(start 135.52551 -397.968724)
		(end 134.508494 -399.725642)
		(width 0.14732)
		(layer "In2.Cu")
		(net "P5E_CPU1_PE3_TX_DP<11>")
	)
	(segment
		(start 124.25172 -287.614614)
		(end 124.256292 -287.617154)
		(width 0.0889)
		(layer "In2.Cu")
		(net "P5E_CPU1_PE3_TX_DP<11>")
	)
	(segment
		(start 148.212302 -376.052588)
		(end 136.359392 -396.52829)
		(width 0.14732)
		(layer "In2.Cu")
		(net "P5E_CPU1_PE3_TX_DP<11>")
	)
	(segment
		(start 124.71146 -288.422334)
		(end 124.72035 -288.427414)
		(width 0.0889)
		(layer "In2.Cu")
		(net "P5E_CPU1_PE3_TX_DP<11>")
	)
	(segment
		(start 125.002798 -288.898584)
		(end 125.002798 -289.114484)
		(width 0.0889)
		(layer "In2.Cu")
		(net "P5E_CPU1_PE3_TX_DP<11>")
	)
	(segment
		(start 136.359392 -396.52829)
		(end 136.359646 -396.528798)
		(width 0.14732)
		(layer "In2.Cu")
		(net "P5E_CPU1_PE3_TX_DP<11>")
	)
	(segment
		(start 124.062744 -287.273746)
		(end 124.062744 -287.28924)
		(width 0.0889)
		(layer "In2.Cu")
		(net "P5E_CPU1_PE3_TX_DP<11>")
	)
	(segment
		(start 135.716772 -397.917924)
		(end 135.52551 -397.968724)
		(width 0.14732)
		(layer "In2.Cu")
		(net "P5E_CPU1_PE3_TX_DP<11>")
	)
	(segment
		(start 124.53239 -289.646868)
		(end 124.53239 -290.313364)
		(width 0.0889)
		(layer "In2.Cu")
		(net "P5E_CPU1_PE3_TX_DP<11>")
	)
	(segment
		(start 136.03478 -397.08963)
		(end 135.850376 -397.408146)
		(width 0.14732)
		(layer "In2.Cu")
		(net "P5E_CPU1_PE3_TX_DP<11>")
	)
	(segment
		(start 127.4064 -302.204882)
		(end 134.676896 -309.475378)
		(width 0.14732)
		(layer "In2.Cu")
		(net "P5E_CPU1_PE3_TX_DP<11>")
	)
	(segment
		(start 124.250196 -287.613598)
		(end 124.25172 -287.614614)
		(width 0.0889)
		(layer "In2.Cu")
		(net "P5E_CPU1_PE3_TX_DP<11>")
	)
	(segment
		(start 124.248672 -287.612836)
		(end 124.250196 -287.613598)
		(width 0.0889)
		(layer "In2.Cu")
		(net "P5E_CPU1_PE3_TX_DP<11>")
	)
	(segment
		(start 149.57298 -328.726292)
		(end 152.753822 -333.269082)
		(width 0.14732)
		(layer "In2.Cu")
		(net "P5E_CPU1_PE3_TX_DP<11>")
	)
	(segment
		(start 136.359646 -396.528798)
		(end 136.410446 -396.719552)
		(width 0.14732)
		(layer "In2.Cu")
		(net "P5E_CPU1_PE3_TX_DP<11>")
	)
	(segment
		(start 135.850376 -397.408146)
		(end 135.901176 -397.5989)
		(width 0.14732)
		(layer "In2.Cu")
		(net "P5E_CPU1_PE3_TX_DP<11>")
	)
	(segment
		(start 124.532644 -289.64636)
		(end 124.53239 -289.646868)
		(width 0.0889)
		(layer "In2.Cu")
		(net "P5E_CPU1_PE3_TX_DP<11>")
	)
	(arc
		(start 123.593098 -286.475424)
		(mid 123.640777 -286.658324)
		(end 123.77166 -286.794702)
		(width 0.0889)
		(layer "In2.Cu")
		(net "P5E_CPU1_PE3_TX_DP<11>")
	)
	(arc
		(start 124.717048 -289.446462)
		(mid 124.607652 -289.530559)
		(end 124.532644 -289.64636)
		(width 0.0889)
		(layer "In2.Cu")
		(net "P5E_CPU1_PE3_TX_DP<11>")
	)
	(arc
		(start 124.062744 -287.28924)
		(mid 124.110423 -287.47214)
		(end 124.241306 -287.608518)
		(width 0.0889)
		(layer "In2.Cu")
		(net "P5E_CPU1_PE3_TX_DP<11>")
	)
	(arc
		(start 123.78055 -286.799782)
		(mid 123.983373 -287.000013)
		(end 124.062744 -287.273746)
		(width 0.0889)
		(layer "In2.Cu")
		(net "P5E_CPU1_PE3_TX_DP<11>")
	)
	(arc
		(start 124.256292 -287.617154)
		(mid 124.458879 -287.823505)
		(end 124.532898 -288.103056)
		(width 0.0889)
		(layer "In2.Cu")
		(net "P5E_CPU1_PE3_TX_DP<11>")
	)
	(arc
		(start 123.262898 -285.369508)
		(mid 123.123835 -285.685029)
		(end 123.301506 -285.980632)
		(width 0.0889)
		(layer "In2.Cu")
		(net "P5E_CPU1_PE3_TX_DP<11>")
	)
	(arc
		(start 124.72035 -288.427414)
		(mid 124.922636 -288.626395)
		(end 125.002798 -288.898584)
		(width 0.0889)
		(layer "In2.Cu")
		(net "P5E_CPU1_PE3_TX_DP<11>")
	)
	(arc
		(start 125.002798 -289.114484)
		(mid 124.891402 -289.307577)
		(end 124.717048 -289.446462)
		(width 0.0889)
		(layer "In2.Cu")
		(net "P5E_CPU1_PE3_TX_DP<11>")
	)
	(arc
		(start 124.532898 -288.103056)
		(mid 124.580577 -288.285956)
		(end 124.71146 -288.422334)
		(width 0.0889)
		(layer "In2.Cu")
		(net "P5E_CPU1_PE3_TX_DP<11>")
	)
	(arc
		(start 123.310396 -285.985712)
		(mid 123.515468 -286.189391)
		(end 123.593098 -286.467804)
		(width 0.0889)
		(layer "In2.Cu")
		(net "P5E_CPU1_PE3_TX_DP<11>")
	)
	(segment
		(start 124.437648 -285.125414)
		(end 124.437648 -285.6611)
		(width 0.13208)
		(layer "F.Cu")
		(net "P5E_CPU1_PE3_TX_DP<10>")
	)
	(segment
		(start 137.381996 -407.303478)
		(end 137.381996 -407.926286)
		(width 0.13208)
		(layer "F.Cu")
		(net "P5E_CPU1_PE3_TX_DP<10>")
	)
	(segment
		(start 137.680954 -407.00452)
		(end 137.381996 -407.303478)
		(width 0.13208)
		(layer "F.Cu")
		(net "P5E_CPU1_PE3_TX_DP<10>")
	)
	(segment
		(start 124.437648 -285.6611)
		(end 124.437394 -285.661354)
		(width 0.13208)
		(layer "F.Cu")
		(net "P5E_CPU1_PE3_TX_DP<10>")
	)
	(segment
		(start 137.381996 -407.926286)
		(end 137.706354 -408.250644)
		(width 0.13208)
		(layer "F.Cu")
		(net "P5E_CPU1_PE3_TX_DP<10>")
	)
	(segment
		(start 137.571734 -399.65122)
		(end 137.571734 -405.231346)
		(width 0.14732)
		(layer "In2.Cu")
		(net "P5E_CPU1_PE3_TX_DP<10>")
	)
	(segment
		(start 125.47219 -289.64636)
		(end 125.47219 -290.315904)
		(width 0.0889)
		(layer "In2.Cu")
		(net "P5E_CPU1_PE3_TX_DP<10>")
	)
	(segment
		(start 125.942598 -288.898584)
		(end 125.942598 -289.114484)
		(width 0.0889)
		(layer "In2.Cu")
		(net "P5E_CPU1_PE3_TX_DP<10>")
	)
	(segment
		(start 125.514354 -290.358068)
		(end 125.514354 -290.380166)
		(width 0.0889)
		(layer "In2.Cu")
		(net "P5E_CPU1_PE3_TX_DP<10>")
	)
	(segment
		(start 125.472444 -289.64636)
		(end 125.47219 -289.64636)
		(width 0.0889)
		(layer "In2.Cu")
		(net "P5E_CPU1_PE3_TX_DP<10>")
	)
	(segment
		(start 125.65126 -288.422334)
		(end 125.66015 -288.427414)
		(width 0.0889)
		(layer "In2.Cu")
		(net "P5E_CPU1_PE3_TX_DP<10>")
	)
	(segment
		(start 124.28093 -285.932372)
		(end 124.30506 -286.021526)
		(width 0.0889)
		(layer "In2.Cu")
		(net "P5E_CPU1_PE3_TX_DP<10>")
	)
	(segment
		(start 124.437394 -285.661354)
		(end 124.28093 -285.932372)
		(width 0.0889)
		(layer "In2.Cu")
		(net "P5E_CPU1_PE3_TX_DP<10>")
	)
	(segment
		(start 124.532898 -286.4612)
		(end 124.532898 -286.48406)
		(width 0.0889)
		(layer "In2.Cu")
		(net "P5E_CPU1_PE3_TX_DP<10>")
	)
	(segment
		(start 125.514354 -290.380166)
		(end 125.514354 -295.20642)
		(width 0.14732)
		(layer "In2.Cu")
		(net "P5E_CPU1_PE3_TX_DP<10>")
	)
	(segment
		(start 137.386314 -405.416766)
		(end 137.386314 -406.70988)
		(width 0.14732)
		(layer "In2.Cu")
		(net "P5E_CPU1_PE3_TX_DP<10>")
	)
	(segment
		(start 149.2123 -376.992134)
		(end 149.222206 -376.965972)
		(width 0.14732)
		(layer "In2.Cu")
		(net "P5E_CPU1_PE3_TX_DP<10>")
	)
	(segment
		(start 151.333454 -371.423184)
		(end 149.2123 -376.992134)
		(width 0.14732)
		(layer "In2.Cu")
		(net "P5E_CPU1_PE3_TX_DP<10>")
	)
	(segment
		(start 154.815032 -339.583776)
		(end 154.815032 -341.540084)
		(width 0.14732)
		(layer "In2.Cu")
		(net "P5E_CPU1_PE3_TX_DP<10>")
	)
	(segment
		(start 154.815032 -341.540084)
		(end 151.333454 -371.423184)
		(width 0.14732)
		(layer "In2.Cu")
		(net "P5E_CPU1_PE3_TX_DP<10>")
	)
	(segment
		(start 128.140714 -301.547276)
		(end 135.34771 -308.75351)
		(width 0.14732)
		(layer "In2.Cu")
		(net "P5E_CPU1_PE3_TX_DP<10>")
	)
	(segment
		(start 150.248366 -328.069194)
		(end 153.63825 -332.91018)
		(width 0.14732)
		(layer "In2.Cu")
		(net "P5E_CPU1_PE3_TX_DP<10>")
	)
	(segment
		(start 125.189996 -287.613598)
		(end 125.196092 -287.617154)
		(width 0.0889)
		(layer "In2.Cu")
		(net "P5E_CPU1_PE3_TX_DP<10>")
	)
	(segment
		(start 149.222206 -376.965972)
		(end 137.571734 -399.65122)
		(width 0.14732)
		(layer "In2.Cu")
		(net "P5E_CPU1_PE3_TX_DP<10>")
	)
	(segment
		(start 125.514354 -295.20642)
		(end 128.140714 -301.547276)
		(width 0.14732)
		(layer "In2.Cu")
		(net "P5E_CPU1_PE3_TX_DP<10>")
	)
	(segment
		(start 137.571734 -405.231346)
		(end 137.386314 -405.416766)
		(width 0.14732)
		(layer "In2.Cu")
		(net "P5E_CPU1_PE3_TX_DP<10>")
	)
	(segment
		(start 125.47219 -290.315904)
		(end 125.514354 -290.358068)
		(width 0.0889)
		(layer "In2.Cu")
		(net "P5E_CPU1_PE3_TX_DP<10>")
	)
	(segment
		(start 153.63825 -332.91018)
		(end 154.815032 -339.583776)
		(width 0.14732)
		(layer "In2.Cu")
		(net "P5E_CPU1_PE3_TX_DP<10>")
	)
	(segment
		(start 125.181106 -287.608518)
		(end 125.189996 -287.613598)
		(width 0.0889)
		(layer "In2.Cu")
		(net "P5E_CPU1_PE3_TX_DP<10>")
	)
	(segment
		(start 125.002544 -287.279334)
		(end 125.002544 -287.28924)
		(width 0.0889)
		(layer "In2.Cu")
		(net "P5E_CPU1_PE3_TX_DP<10>")
	)
	(segment
		(start 137.386314 -406.70988)
		(end 137.680954 -407.00452)
		(width 0.14732)
		(layer "In2.Cu")
		(net "P5E_CPU1_PE3_TX_DP<10>")
	)
	(segment
		(start 142.7607 -319.340484)
		(end 150.248366 -328.069194)
		(width 0.14732)
		(layer "In2.Cu")
		(net "P5E_CPU1_PE3_TX_DP<10>")
	)
	(segment
		(start 135.34771 -308.75351)
		(end 142.7607 -319.340484)
		(width 0.14732)
		(layer "In2.Cu")
		(net "P5E_CPU1_PE3_TX_DP<10>")
	)
	(arc
		(start 125.472698 -288.103056)
		(mid 125.520377 -288.285956)
		(end 125.65126 -288.422334)
		(width 0.0889)
		(layer "In2.Cu")
		(net "P5E_CPU1_PE3_TX_DP<10>")
	)
	(arc
		(start 125.66015 -288.427414)
		(mid 125.862436 -288.626395)
		(end 125.942598 -288.898584)
		(width 0.0889)
		(layer "In2.Cu")
		(net "P5E_CPU1_PE3_TX_DP<10>")
	)
	(arc
		(start 125.942598 -289.114484)
		(mid 125.831202 -289.307577)
		(end 125.656848 -289.446462)
		(width 0.0889)
		(layer "In2.Cu")
		(net "P5E_CPU1_PE3_TX_DP<10>")
	)
	(arc
		(start 124.322078 -286.03448)
		(mid 124.474565 -286.224576)
		(end 124.532898 -286.4612)
		(width 0.0889)
		(layer "In2.Cu")
		(net "P5E_CPU1_PE3_TX_DP<10>")
	)
	(arc
		(start 125.656848 -289.446462)
		(mid 125.547452 -289.530559)
		(end 125.472444 -289.64636)
		(width 0.0889)
		(layer "In2.Cu")
		(net "P5E_CPU1_PE3_TX_DP<10>")
	)
	(arc
		(start 124.532898 -286.48406)
		(mid 124.585168 -286.666425)
		(end 124.720096 -286.799782)
		(width 0.0889)
		(layer "In2.Cu")
		(net "P5E_CPU1_PE3_TX_DP<10>")
	)
	(arc
		(start 124.720096 -286.799782)
		(mid 124.924431 -287.002387)
		(end 125.002544 -287.279334)
		(width 0.0889)
		(layer "In2.Cu")
		(net "P5E_CPU1_PE3_TX_DP<10>")
	)
	(arc
		(start 125.002544 -287.28924)
		(mid 125.050223 -287.47214)
		(end 125.181106 -287.608518)
		(width 0.0889)
		(layer "In2.Cu")
		(net "P5E_CPU1_PE3_TX_DP<10>")
	)
	(arc
		(start 124.30506 -286.021526)
		(mid 124.313631 -286.027922)
		(end 124.322078 -286.03448)
		(width 0.0889)
		(layer "In2.Cu")
		(net "P5E_CPU1_PE3_TX_DP<10>")
	)
	(arc
		(start 125.196092 -287.617154)
		(mid 125.398679 -287.823505)
		(end 125.472698 -288.103056)
		(width 0.0889)
		(layer "In2.Cu")
		(net "P5E_CPU1_PE3_TX_DP<10>")
	)
	(segment
		(start 133.365494 -286.47517)
		(end 133.365748 -286.475424)
		(width 0.13208)
		(layer "F.Cu")
		(net "P5E_CPU1_PE3_TX_DP<0>")
	)
	(segment
		(start 167.755316 -407.924254)
		(end 167.428926 -408.250644)
		(width 0.13208)
		(layer "F.Cu")
		(net "P5E_CPU1_PE3_TX_DP<0>")
	)
	(segment
		(start 133.365494 -285.939484)
		(end 133.365494 -286.47517)
		(width 0.13208)
		(layer "F.Cu")
		(net "P5E_CPU1_PE3_TX_DP<0>")
	)
	(segment
		(start 167.428926 -408.250644)
		(end 167.424354 -408.250644)
		(width 0.13208)
		(layer "F.Cu")
		(net "P5E_CPU1_PE3_TX_DP<0>")
	)
	(segment
		(start 167.449754 -407.00452)
		(end 167.755316 -407.310082)
		(width 0.13208)
		(layer "F.Cu")
		(net "P5E_CPU1_PE3_TX_DP<0>")
	)
	(segment
		(start 167.755316 -407.310082)
		(end 167.755316 -407.924254)
		(width 0.13208)
		(layer "F.Cu")
		(net "P5E_CPU1_PE3_TX_DP<0>")
	)
	(segment
		(start 164.391848 -331.230986)
		(end 163.415726 -325.697342)
		(width 0.14732)
		(layer "In2.Cu")
		(net "P5E_CPU1_PE3_TX_DP<0>")
	)
	(segment
		(start 163.415726 -325.697342)
		(end 162.973004 -325.065136)
		(width 0.14732)
		(layer "In2.Cu")
		(net "P5E_CPU1_PE3_TX_DP<0>")
	)
	(segment
		(start 167.389048 -397.590264)
		(end 167.24376 -397.490696)
		(width 0.14732)
		(layer "In2.Cu")
		(net "P5E_CPU1_PE3_TX_DP<0>")
	)
	(segment
		(start 140.693902 -295.948862)
		(end 139.390628 -292.802056)
		(width 0.14732)
		(layer "In2.Cu")
		(net "P5E_CPU1_PE3_TX_DP<0>")
	)
	(segment
		(start 135.432546 -289.406584)
		(end 135.408162 -289.392614)
		(width 0.0889)
		(layer "In2.Cu")
		(net "P5E_CPU1_PE3_TX_DP<0>")
	)
	(segment
		(start 144.58696 -305.998372)
		(end 144.10055 -305.186334)
		(width 0.14732)
		(layer "In2.Cu")
		(net "P5E_CPU1_PE3_TX_DP<0>")
	)
	(segment
		(start 167.184578 -396.486126)
		(end 167.03929 -396.386558)
		(width 0.14732)
		(layer "In2.Cu")
		(net "P5E_CPU1_PE3_TX_DP<0>")
	)
	(segment
		(start 137.859008 -291.270436)
		(end 136.796018 -290.83)
		(width 0.14732)
		(layer "In2.Cu")
		(net "P5E_CPU1_PE3_TX_DP<0>")
	)
	(segment
		(start 167.744394 -406.70988)
		(end 167.744394 -405.302974)
		(width 0.14732)
		(layer "In2.Cu")
		(net "P5E_CPU1_PE3_TX_DP<0>")
	)
	(segment
		(start 164.233098 -340.321392)
		(end 164.391848 -339.420708)
		(width 0.14732)
		(layer "In2.Cu")
		(net "P5E_CPU1_PE3_TX_DP<0>")
	)
	(segment
		(start 135.938514 -289.912552)
		(end 135.432546 -289.406584)
		(width 0.0889)
		(layer "In2.Cu")
		(net "P5E_CPU1_PE3_TX_DP<0>")
	)
	(segment
		(start 133.600444 -286.183578)
		(end 133.522212 -286.204406)
		(width 0.0889)
		(layer "In2.Cu")
		(net "P5E_CPU1_PE3_TX_DP<0>")
	)
	(segment
		(start 167.03929 -396.386558)
		(end 166.959788 -395.956536)
		(width 0.14732)
		(layer "In2.Cu")
		(net "P5E_CPU1_PE3_TX_DP<0>")
	)
	(segment
		(start 167.368728 -398.164812)
		(end 167.468296 -398.019778)
		(width 0.14732)
		(layer "In2.Cu")
		(net "P5E_CPU1_PE3_TX_DP<0>")
	)
	(segment
		(start 144.10055 -305.186334)
		(end 141.153388 -298.55287)
		(width 0.14732)
		(layer "In2.Cu")
		(net "P5E_CPU1_PE3_TX_DP<0>")
	)
	(segment
		(start 155.188666 -319.615058)
		(end 144.58696 -305.998372)
		(width 0.14732)
		(layer "In2.Cu")
		(net "P5E_CPU1_PE3_TX_DP<0>")
	)
	(segment
		(start 135.938514 -289.972496)
		(end 135.938514 -289.912552)
		(width 0.0889)
		(layer "In2.Cu")
		(net "P5E_CPU1_PE3_TX_DP<0>")
	)
	(segment
		(start 134.031482 -286.969962)
		(end 134.022592 -286.964882)
		(width 0.0889)
		(layer "In2.Cu")
		(net "P5E_CPU1_PE3_TX_DP<0>")
	)
	(segment
		(start 167.24376 -397.490696)
		(end 167.164258 -397.060674)
		(width 0.14732)
		(layer "In2.Cu")
		(net "P5E_CPU1_PE3_TX_DP<0>")
	)
	(segment
		(start 134.501636 -287.783778)
		(end 134.492746 -287.778698)
		(width 0.0889)
		(layer "In2.Cu")
		(net "P5E_CPU1_PE3_TX_DP<0>")
	)
	(segment
		(start 167.44823 -398.59458)
		(end 167.368728 -398.164812)
		(width 0.14732)
		(layer "In2.Cu")
		(net "P5E_CPU1_PE3_TX_DP<0>")
	)
	(segment
		(start 139.390628 -292.802056)
		(end 137.859008 -291.270436)
		(width 0.14732)
		(layer "In2.Cu")
		(net "P5E_CPU1_PE3_TX_DP<0>")
	)
	(segment
		(start 167.449754 -407.00452)
		(end 167.744394 -406.70988)
		(width 0.14732)
		(layer "In2.Cu")
		(net "P5E_CPU1_PE3_TX_DP<0>")
	)
	(segment
		(start 167.164258 -397.060674)
		(end 167.26408 -396.91564)
		(width 0.14732)
		(layer "In2.Cu")
		(net "P5E_CPU1_PE3_TX_DP<0>")
	)
	(segment
		(start 167.26408 -396.91564)
		(end 167.184578 -396.486126)
		(width 0.14732)
		(layer "In2.Cu")
		(net "P5E_CPU1_PE3_TX_DP<0>")
	)
	(segment
		(start 166.959788 -395.956536)
		(end 167.05961 -395.811502)
		(width 0.14732)
		(layer "In2.Cu")
		(net "P5E_CPU1_PE3_TX_DP<0>")
	)
	(segment
		(start 134.680198 -288.112962)
		(end 134.680198 -288.103056)
		(width 0.0889)
		(layer "In2.Cu")
		(net "P5E_CPU1_PE3_TX_DP<0>")
	)
	(segment
		(start 141.153388 -298.55287)
		(end 140.693902 -295.948862)
		(width 0.14732)
		(layer "In2.Cu")
		(net "P5E_CPU1_PE3_TX_DP<0>")
	)
	(segment
		(start 167.929814 -405.117554)
		(end 167.929814 -400.51228)
		(width 0.14732)
		(layer "In2.Cu")
		(net "P5E_CPU1_PE3_TX_DP<0>")
	)
	(segment
		(start 133.740398 -286.490918)
		(end 133.740398 -286.475424)
		(width 0.0889)
		(layer "In2.Cu")
		(net "P5E_CPU1_PE3_TX_DP<0>")
	)
	(segment
		(start 135.150606 -288.95929)
		(end 135.149844 -288.908236)
		(width 0.0889)
		(layer "In2.Cu")
		(net "P5E_CPU1_PE3_TX_DP<0>")
	)
	(segment
		(start 167.468296 -398.019778)
		(end 167.389048 -397.590264)
		(width 0.14732)
		(layer "In2.Cu")
		(net "P5E_CPU1_PE3_TX_DP<0>")
	)
	(segment
		(start 167.05961 -395.811502)
		(end 163.311586 -375.559828)
		(width 0.14732)
		(layer "In2.Cu")
		(net "P5E_CPU1_PE3_TX_DP<0>")
	)
	(segment
		(start 167.744394 -405.302974)
		(end 167.929814 -405.117554)
		(width 0.14732)
		(layer "In2.Cu")
		(net "P5E_CPU1_PE3_TX_DP<0>")
	)
	(segment
		(start 163.311586 -375.559828)
		(end 164.233098 -340.321392)
		(width 0.14732)
		(layer "In2.Cu")
		(net "P5E_CPU1_PE3_TX_DP<0>")
	)
	(segment
		(start 134.492746 -287.778698)
		(end 134.48665 -287.775142)
		(width 0.0889)
		(layer "In2.Cu")
		(net "P5E_CPU1_PE3_TX_DP<0>")
	)
	(segment
		(start 164.391848 -339.420708)
		(end 164.391848 -331.230986)
		(width 0.14732)
		(layer "In2.Cu")
		(net "P5E_CPU1_PE3_TX_DP<0>")
	)
	(segment
		(start 167.593264 -398.694148)
		(end 167.44823 -398.59458)
		(width 0.14732)
		(layer "In2.Cu")
		(net "P5E_CPU1_PE3_TX_DP<0>")
	)
	(segment
		(start 135.954008 -289.98799)
		(end 135.938514 -289.972496)
		(width 0.0889)
		(layer "In2.Cu")
		(net "P5E_CPU1_PE3_TX_DP<0>")
	)
	(segment
		(start 133.522212 -286.204406)
		(end 133.365748 -286.475424)
		(width 0.0889)
		(layer "In2.Cu")
		(net "P5E_CPU1_PE3_TX_DP<0>")
	)
	(segment
		(start 167.929814 -400.51228)
		(end 167.593264 -398.694148)
		(width 0.14732)
		(layer "In2.Cu")
		(net "P5E_CPU1_PE3_TX_DP<0>")
	)
	(segment
		(start 162.973004 -325.065136)
		(end 155.188666 -319.615058)
		(width 0.14732)
		(layer "In2.Cu")
		(net "P5E_CPU1_PE3_TX_DP<0>")
	)
	(segment
		(start 136.796018 -290.83)
		(end 135.954008 -289.98799)
		(width 0.14732)
		(layer "In2.Cu")
		(net "P5E_CPU1_PE3_TX_DP<0>")
	)
	(arc
		(start 135.408162 -289.392614)
		(mid 135.222781 -289.209597)
		(end 135.150606 -288.95929)
		(width 0.0889)
		(layer "In2.Cu")
		(net "P5E_CPU1_PE3_TX_DP<0>")
	)
	(arc
		(start 135.149844 -288.908236)
		(mid 135.097574 -288.725871)
		(end 134.962646 -288.592514)
		(width 0.0889)
		(layer "In2.Cu")
		(net "P5E_CPU1_PE3_TX_DP<0>")
	)
	(arc
		(start 134.962646 -288.592514)
		(mid 134.758311 -288.389909)
		(end 134.680198 -288.112962)
		(width 0.0889)
		(layer "In2.Cu")
		(net "P5E_CPU1_PE3_TX_DP<0>")
	)
	(arc
		(start 134.210044 -287.28924)
		(mid 134.162365 -287.10634)
		(end 134.031482 -286.969962)
		(width 0.0889)
		(layer "In2.Cu")
		(net "P5E_CPU1_PE3_TX_DP<0>")
	)
	(arc
		(start 133.740398 -286.475424)
		(mid 133.703538 -286.313627)
		(end 133.600444 -286.183578)
		(width 0.0889)
		(layer "In2.Cu")
		(net "P5E_CPU1_PE3_TX_DP<0>")
	)
	(arc
		(start 134.022592 -286.964882)
		(mid 133.819769 -286.764651)
		(end 133.740398 -286.490918)
		(width 0.0889)
		(layer "In2.Cu")
		(net "P5E_CPU1_PE3_TX_DP<0>")
	)
	(arc
		(start 134.680198 -288.103056)
		(mid 134.632519 -287.920156)
		(end 134.501636 -287.783778)
		(width 0.0889)
		(layer "In2.Cu")
		(net "P5E_CPU1_PE3_TX_DP<0>")
	)
	(arc
		(start 134.48665 -287.775142)
		(mid 134.284063 -287.568791)
		(end 134.210044 -287.28924)
		(width 0.0889)
		(layer "In2.Cu")
		(net "P5E_CPU1_PE3_TX_DP<0>")
	)
	(segment
		(start 140.186156 -407.924254)
		(end 139.859766 -408.250644)
		(width 0.13208)
		(layer "F.Cu")
		(net "P5E_CPU1_PE3_TX_DN<9>")
	)
	(segment
		(start 140.186156 -407.310082)
		(end 140.186156 -407.924254)
		(width 0.13208)
		(layer "F.Cu")
		(net "P5E_CPU1_PE3_TX_DN<9>")
	)
	(segment
		(start 139.880594 -407.00452)
		(end 140.186156 -407.310082)
		(width 0.13208)
		(layer "F.Cu")
		(net "P5E_CPU1_PE3_TX_DN<9>")
	)
	(segment
		(start 124.907294 -284.311598)
		(end 124.907548 -284.847538)
		(width 0.13208)
		(layer "F.Cu")
		(net "P5E_CPU1_PE3_TX_DN<9>")
	)
	(segment
		(start 139.859766 -408.250644)
		(end 139.855194 -408.250644)
		(width 0.13208)
		(layer "F.Cu")
		(net "P5E_CPU1_PE3_TX_DN<9>")
	)
	(segment
		(start 140.175234 -405.302974)
		(end 140.175234 -406.70988)
		(width 0.14732)
		(layer "In2.Cu")
		(net "P5E_CPU1_PE3_TX_DN<9>")
	)
	(segment
		(start 125.094492 -286.151066)
		(end 125.103382 -286.156146)
		(width 0.0889)
		(layer "In2.Cu")
		(net "P5E_CPU1_PE3_TX_DN<9>")
	)
	(segment
		(start 126.179834 -295.100248)
		(end 128.647698 -301.058326)
		(width 0.14732)
		(layer "In2.Cu")
		(net "P5E_CPU1_PE3_TX_DN<9>")
	)
	(segment
		(start 126.034546 -287.778698)
		(end 126.043436 -287.783778)
		(width 0.0889)
		(layer "In2.Cu")
		(net "P5E_CPU1_PE3_TX_DN<9>")
	)
	(segment
		(start 140.360654 -405.117554)
		(end 140.175234 -405.302974)
		(width 0.14732)
		(layer "In2.Cu")
		(net "P5E_CPU1_PE3_TX_DN<9>")
	)
	(segment
		(start 126.221998 -288.103056)
		(end 126.221998 -288.121598)
		(width 0.0889)
		(layer "In2.Cu")
		(net "P5E_CPU1_PE3_TX_DN<9>")
	)
	(segment
		(start 150.768558 -327.66889)
		(end 154.291538 -332.700376)
		(width 0.14732)
		(layer "In2.Cu")
		(net "P5E_CPU1_PE3_TX_DN<9>")
	)
	(segment
		(start 155.478988 -339.434678)
		(end 155.478988 -341.512906)
		(width 0.14732)
		(layer "In2.Cu")
		(net "P5E_CPU1_PE3_TX_DN<9>")
	)
	(segment
		(start 155.478988 -341.512906)
		(end 151.85517 -372.614444)
		(width 0.14732)
		(layer "In2.Cu")
		(net "P5E_CPU1_PE3_TX_DN<9>")
	)
	(segment
		(start 126.504446 -288.592768)
		(end 126.513336 -288.597848)
		(width 0.0889)
		(layer "In2.Cu")
		(net "P5E_CPU1_PE3_TX_DN<9>")
	)
	(segment
		(start 126.179834 -290.380166)
		(end 126.179834 -295.100248)
		(width 0.14732)
		(layer "In2.Cu")
		(net "P5E_CPU1_PE3_TX_DN<9>")
	)
	(segment
		(start 125.558296 -286.961326)
		(end 125.564392 -286.964882)
		(width 0.0889)
		(layer "In2.Cu")
		(net "P5E_CPU1_PE3_TX_DN<9>")
	)
	(segment
		(start 149.986238 -377.817634)
		(end 140.360654 -399.49501)
		(width 0.14732)
		(layer "In2.Cu")
		(net "P5E_CPU1_PE3_TX_DN<9>")
	)
	(segment
		(start 126.179834 -290.358068)
		(end 126.179834 -290.380166)
		(width 0.0889)
		(layer "In2.Cu")
		(net "P5E_CPU1_PE3_TX_DN<9>")
	)
	(segment
		(start 125.064012 -285.118556)
		(end 125.039882 -285.20771)
		(width 0.0889)
		(layer "In2.Cu")
		(net "P5E_CPU1_PE3_TX_DN<9>")
	)
	(segment
		(start 124.907548 -284.847538)
		(end 125.064012 -285.118556)
		(width 0.0889)
		(layer "In2.Cu")
		(net "P5E_CPU1_PE3_TX_DN<9>")
	)
	(segment
		(start 135.691626 -308.102)
		(end 143.28013 -318.939164)
		(width 0.14732)
		(layer "In2.Cu")
		(net "P5E_CPU1_PE3_TX_DN<9>")
	)
	(segment
		(start 154.291538 -332.700376)
		(end 155.478988 -339.434678)
		(width 0.14732)
		(layer "In2.Cu")
		(net "P5E_CPU1_PE3_TX_DN<9>")
	)
	(segment
		(start 126.221744 -290.316158)
		(end 126.179834 -290.358068)
		(width 0.0889)
		(layer "In2.Cu")
		(net "P5E_CPU1_PE3_TX_DN<9>")
	)
	(segment
		(start 151.85517 -372.614444)
		(end 149.986238 -377.817634)
		(width 0.14732)
		(layer "In2.Cu")
		(net "P5E_CPU1_PE3_TX_DN<9>")
	)
	(segment
		(start 140.360654 -399.49501)
		(end 140.360654 -405.117554)
		(width 0.14732)
		(layer "In2.Cu")
		(net "P5E_CPU1_PE3_TX_DN<9>")
	)
	(segment
		(start 140.175234 -406.70988)
		(end 139.880594 -407.00452)
		(width 0.14732)
		(layer "In2.Cu")
		(net "P5E_CPU1_PE3_TX_DN<9>")
	)
	(segment
		(start 126.221744 -289.609784)
		(end 126.221744 -290.316158)
		(width 0.0889)
		(layer "In2.Cu")
		(net "P5E_CPU1_PE3_TX_DN<9>")
	)
	(segment
		(start 143.28013 -318.939164)
		(end 150.768558 -327.66889)
		(width 0.14732)
		(layer "In2.Cu")
		(net "P5E_CPU1_PE3_TX_DN<9>")
	)
	(segment
		(start 124.812044 -285.661354)
		(end 124.812044 -285.679896)
		(width 0.0889)
		(layer "In2.Cu")
		(net "P5E_CPU1_PE3_TX_DN<9>")
	)
	(segment
		(start 128.647698 -301.058326)
		(end 135.691626 -308.102)
		(width 0.14732)
		(layer "In2.Cu")
		(net "P5E_CPU1_PE3_TX_DN<9>")
	)
	(segment
		(start 125.564392 -286.964882)
		(end 125.573282 -286.969962)
		(width 0.0889)
		(layer "In2.Cu")
		(net "P5E_CPU1_PE3_TX_DN<9>")
	)
	(segment
		(start 126.691898 -288.917126)
		(end 126.691898 -289.077908)
		(width 0.0889)
		(layer "In2.Cu")
		(net "P5E_CPU1_PE3_TX_DN<9>")
	)
	(segment
		(start 126.02845 -287.775142)
		(end 126.034546 -287.778698)
		(width 0.0889)
		(layer "In2.Cu")
		(net "P5E_CPU1_PE3_TX_DN<9>")
	)
	(arc
		(start 124.812044 -285.679896)
		(mid 124.892206 -285.952085)
		(end 125.094492 -286.151066)
		(width 0.0889)
		(layer "In2.Cu")
		(net "P5E_CPU1_PE3_TX_DN<9>")
	)
	(arc
		(start 125.281944 -286.475424)
		(mid 125.35586 -286.754926)
		(end 125.558296 -286.961326)
		(width 0.0889)
		(layer "In2.Cu")
		(net "P5E_CPU1_PE3_TX_DN<9>")
	)
	(arc
		(start 126.23673 -289.570922)
		(mid 126.228898 -289.590222)
		(end 126.221744 -289.609784)
		(width 0.0889)
		(layer "In2.Cu")
		(net "P5E_CPU1_PE3_TX_DN<9>")
	)
	(arc
		(start 125.751844 -287.28924)
		(mid 125.825835 -287.568806)
		(end 126.02845 -287.775142)
		(width 0.0889)
		(layer "In2.Cu")
		(net "P5E_CPU1_PE3_TX_DN<9>")
	)
	(arc
		(start 125.103382 -286.156146)
		(mid 125.234296 -286.292506)
		(end 125.281944 -286.475424)
		(width 0.0889)
		(layer "In2.Cu")
		(net "P5E_CPU1_PE3_TX_DN<9>")
	)
	(arc
		(start 125.573282 -286.969962)
		(mid 125.704196 -287.106322)
		(end 125.751844 -287.28924)
		(width 0.0889)
		(layer "In2.Cu")
		(net "P5E_CPU1_PE3_TX_DN<9>")
	)
	(arc
		(start 125.039882 -285.20771)
		(mid 125.03131 -285.214232)
		(end 125.022864 -285.220918)
		(width 0.0889)
		(layer "In2.Cu")
		(net "P5E_CPU1_PE3_TX_DN<9>")
	)
	(arc
		(start 126.513336 -288.597848)
		(mid 126.64425 -288.734208)
		(end 126.691898 -288.917126)
		(width 0.0889)
		(layer "In2.Cu")
		(net "P5E_CPU1_PE3_TX_DN<9>")
	)
	(arc
		(start 126.507494 -289.277806)
		(mid 126.346946 -289.401124)
		(end 126.23673 -289.570922)
		(width 0.0889)
		(layer "In2.Cu")
		(net "P5E_CPU1_PE3_TX_DN<9>")
	)
	(arc
		(start 126.043436 -287.783778)
		(mid 126.17435 -287.920138)
		(end 126.221998 -288.103056)
		(width 0.0889)
		(layer "In2.Cu")
		(net "P5E_CPU1_PE3_TX_DN<9>")
	)
	(arc
		(start 126.691898 -289.077908)
		(mid 126.616827 -289.19365)
		(end 126.507494 -289.277806)
		(width 0.0889)
		(layer "In2.Cu")
		(net "P5E_CPU1_PE3_TX_DN<9>")
	)
	(arc
		(start 125.022864 -285.220918)
		(mid 124.867466 -285.417199)
		(end 124.812044 -285.661354)
		(width 0.0889)
		(layer "In2.Cu")
		(net "P5E_CPU1_PE3_TX_DN<9>")
	)
	(arc
		(start 126.221998 -288.121598)
		(mid 126.30216 -288.393787)
		(end 126.504446 -288.592768)
		(width 0.0889)
		(layer "In2.Cu")
		(net "P5E_CPU1_PE3_TX_DN<9>")
	)
	(segment
		(start 142.943834 -407.00452)
		(end 143.249396 -407.310082)
		(width 0.13208)
		(layer "F.Cu")
		(net "P5E_CPU1_PE3_TX_DN<8>")
	)
	(segment
		(start 142.923006 -408.250644)
		(end 142.918434 -408.250644)
		(width 0.13208)
		(layer "F.Cu")
		(net "P5E_CPU1_PE3_TX_DN<8>")
	)
	(segment
		(start 125.847094 -286.47517)
		(end 125.847348 -286.475424)
		(width 0.13208)
		(layer "F.Cu")
		(net "P5E_CPU1_PE3_TX_DN<8>")
	)
	(segment
		(start 125.847094 -285.939484)
		(end 125.847094 -286.47517)
		(width 0.13208)
		(layer "F.Cu")
		(net "P5E_CPU1_PE3_TX_DN<8>")
	)
	(segment
		(start 143.249396 -407.924254)
		(end 142.923006 -408.250644)
		(width 0.13208)
		(layer "F.Cu")
		(net "P5E_CPU1_PE3_TX_DN<8>")
	)
	(segment
		(start 143.249396 -407.310082)
		(end 143.249396 -407.924254)
		(width 0.13208)
		(layer "F.Cu")
		(net "P5E_CPU1_PE3_TX_DN<8>")
	)
	(segment
		(start 144.159478 -397.390366)
		(end 143.979646 -397.472662)
		(width 0.14732)
		(layer "In2.Cu")
		(net "P5E_CPU1_PE3_TX_DN<8>")
	)
	(segment
		(start 126.975108 -287.779206)
		(end 126.976124 -287.779714)
		(width 0.0889)
		(layer "In2.Cu")
		(net "P5E_CPU1_PE3_TX_DN<8>")
	)
	(segment
		(start 126.003812 -286.204406)
		(end 126.08179 -286.183578)
		(width 0.0889)
		(layer "In2.Cu")
		(net "P5E_CPU1_PE3_TX_DN<8>")
	)
	(segment
		(start 144.333722 -396.520162)
		(end 144.205452 -396.865602)
		(width 0.14732)
		(layer "In2.Cu")
		(net "P5E_CPU1_PE3_TX_DN<8>")
	)
	(segment
		(start 127.631952 -288.90849)
		(end 127.631952 -289.078924)
		(width 0.0889)
		(layer "In2.Cu")
		(net "P5E_CPU1_PE3_TX_DN<8>")
	)
	(segment
		(start 156.417264 -341.54491)
		(end 152.616408 -374.16613)
		(width 0.14732)
		(layer "In2.Cu")
		(net "P5E_CPU1_PE3_TX_DN<8>")
	)
	(segment
		(start 144.513554 -396.43812)
		(end 144.333722 -396.520162)
		(width 0.14732)
		(layer "In2.Cu")
		(net "P5E_CPU1_PE3_TX_DN<8>")
	)
	(segment
		(start 136.092184 -307.118004)
		(end 136.185402 -307.183282)
		(width 0.14732)
		(layer "In2.Cu")
		(net "P5E_CPU1_PE3_TX_DN<8>")
	)
	(segment
		(start 126.221998 -286.463994)
		(end 126.221998 -286.486092)
		(width 0.0889)
		(layer "In2.Cu")
		(net "P5E_CPU1_PE3_TX_DN<8>")
	)
	(segment
		(start 127.433832 -288.586672)
		(end 127.444754 -288.592768)
		(width 0.0889)
		(layer "In2.Cu")
		(net "P5E_CPU1_PE3_TX_DN<8>")
	)
	(segment
		(start 143.423894 -405.117554)
		(end 143.238474 -405.302974)
		(width 0.14732)
		(layer "In2.Cu")
		(net "P5E_CPU1_PE3_TX_DN<8>")
	)
	(segment
		(start 155.349448 -332.589378)
		(end 156.417264 -338.636864)
		(width 0.14732)
		(layer "In2.Cu")
		(net "P5E_CPU1_PE3_TX_DN<8>")
	)
	(segment
		(start 126.976124 -287.779714)
		(end 126.983236 -287.783778)
		(width 0.0889)
		(layer "In2.Cu")
		(net "P5E_CPU1_PE3_TX_DN<8>")
	)
	(segment
		(start 144.021048 -318.374522)
		(end 151.505158 -327.099168)
		(width 0.14732)
		(layer "In2.Cu")
		(net "P5E_CPU1_PE3_TX_DN<8>")
	)
	(segment
		(start 127.119634 -294.939212)
		(end 129.386584 -300.412404)
		(width 0.14732)
		(layer "In2.Cu")
		(net "P5E_CPU1_PE3_TX_DN<8>")
	)
	(segment
		(start 126.973584 -287.77819)
		(end 126.975108 -287.779206)
		(width 0.0889)
		(layer "In2.Cu")
		(net "P5E_CPU1_PE3_TX_DN<8>")
	)
	(segment
		(start 143.238474 -406.70988)
		(end 142.943834 -407.00452)
		(width 0.14732)
		(layer "In2.Cu")
		(net "P5E_CPU1_PE3_TX_DN<8>")
	)
	(segment
		(start 136.185402 -307.183282)
		(end 144.021048 -318.374522)
		(width 0.14732)
		(layer "In2.Cu")
		(net "P5E_CPU1_PE3_TX_DN<8>")
	)
	(segment
		(start 127.631698 -288.90214)
		(end 127.631952 -288.90849)
		(width 0.0889)
		(layer "In2.Cu")
		(net "P5E_CPU1_PE3_TX_DN<8>")
	)
	(segment
		(start 129.386584 -300.412404)
		(end 136.092184 -307.118004)
		(width 0.14732)
		(layer "In2.Cu")
		(net "P5E_CPU1_PE3_TX_DN<8>")
	)
	(segment
		(start 156.417264 -338.636864)
		(end 156.417264 -341.54491)
		(width 0.14732)
		(layer "In2.Cu")
		(net "P5E_CPU1_PE3_TX_DN<8>")
	)
	(segment
		(start 125.847348 -286.475424)
		(end 126.003812 -286.204406)
		(width 0.0889)
		(layer "In2.Cu")
		(net "P5E_CPU1_PE3_TX_DN<8>")
	)
	(segment
		(start 127.119634 -290.358068)
		(end 127.119634 -290.380166)
		(width 0.0889)
		(layer "In2.Cu")
		(net "P5E_CPU1_PE3_TX_DN<8>")
	)
	(segment
		(start 144.205452 -396.865602)
		(end 144.287748 -397.04518)
		(width 0.14732)
		(layer "In2.Cu")
		(net "P5E_CPU1_PE3_TX_DN<8>")
	)
	(segment
		(start 152.616408 -374.16613)
		(end 150.886922 -379.2982)
		(width 0.14732)
		(layer "In2.Cu")
		(net "P5E_CPU1_PE3_TX_DN<8>")
	)
	(segment
		(start 126.08179 -286.183578)
		(end 126.082044 -286.18307)
		(width 0.0889)
		(layer "In2.Cu")
		(net "P5E_CPU1_PE3_TX_DN<8>")
	)
	(segment
		(start 143.851122 -397.818102)
		(end 143.933418 -397.99768)
		(width 0.14732)
		(layer "In2.Cu")
		(net "P5E_CPU1_PE3_TX_DN<8>")
	)
	(segment
		(start 144.514316 -396.435834)
		(end 144.513554 -396.43812)
		(width 0.14732)
		(layer "In2.Cu")
		(net "P5E_CPU1_PE3_TX_DN<8>")
	)
	(segment
		(start 144.287748 -397.04518)
		(end 144.159478 -397.390366)
		(width 0.14732)
		(layer "In2.Cu")
		(net "P5E_CPU1_PE3_TX_DN<8>")
	)
	(segment
		(start 151.506174 -327.100438)
		(end 155.349448 -332.589378)
		(width 0.14732)
		(layer "In2.Cu")
		(net "P5E_CPU1_PE3_TX_DN<8>")
	)
	(segment
		(start 126.691644 -287.281366)
		(end 126.691644 -287.28924)
		(width 0.0889)
		(layer "In2.Cu")
		(net "P5E_CPU1_PE3_TX_DN<8>")
	)
	(segment
		(start 127.161544 -289.75304)
		(end 127.161544 -290.316158)
		(width 0.0889)
		(layer "In2.Cu")
		(net "P5E_CPU1_PE3_TX_DN<8>")
	)
	(segment
		(start 150.886922 -379.2982)
		(end 144.514316 -396.435834)
		(width 0.14732)
		(layer "In2.Cu")
		(net "P5E_CPU1_PE3_TX_DN<8>")
	)
	(segment
		(start 126.96825 -287.775142)
		(end 126.973584 -287.77819)
		(width 0.0889)
		(layer "In2.Cu")
		(net "P5E_CPU1_PE3_TX_DN<8>")
	)
	(segment
		(start 143.933418 -397.99768)
		(end 143.423894 -399.368264)
		(width 0.14732)
		(layer "In2.Cu")
		(net "P5E_CPU1_PE3_TX_DN<8>")
	)
	(segment
		(start 127.119634 -290.380166)
		(end 127.119634 -294.939212)
		(width 0.14732)
		(layer "In2.Cu")
		(net "P5E_CPU1_PE3_TX_DN<8>")
	)
	(segment
		(start 143.423894 -399.368264)
		(end 143.423894 -405.117554)
		(width 0.14732)
		(layer "In2.Cu")
		(net "P5E_CPU1_PE3_TX_DN<8>")
	)
	(segment
		(start 143.238474 -405.302974)
		(end 143.238474 -406.70988)
		(width 0.14732)
		(layer "In2.Cu")
		(net "P5E_CPU1_PE3_TX_DN<8>")
	)
	(segment
		(start 143.979646 -397.472662)
		(end 143.851122 -397.818102)
		(width 0.14732)
		(layer "In2.Cu")
		(net "P5E_CPU1_PE3_TX_DN<8>")
	)
	(segment
		(start 127.161544 -290.316158)
		(end 127.119634 -290.358068)
		(width 0.0889)
		(layer "In2.Cu")
		(net "P5E_CPU1_PE3_TX_DN<8>")
	)
	(segment
		(start 151.505158 -327.099168)
		(end 151.506174 -327.100438)
		(width 0.14732)
		(layer "In2.Cu")
		(net "P5E_CPU1_PE3_TX_DN<8>")
	)
	(arc
		(start 127.631952 -289.078924)
		(mid 127.556774 -289.194253)
		(end 127.447548 -289.27806)
		(width 0.0889)
		(layer "In2.Cu")
		(net "P5E_CPU1_PE3_TX_DN<8>")
	)
	(arc
		(start 127.161798 -288.103056)
		(mid 127.234419 -288.380521)
		(end 127.433832 -288.586672)
		(width 0.0889)
		(layer "In2.Cu")
		(net "P5E_CPU1_PE3_TX_DN<8>")
	)
	(arc
		(start 126.983236 -287.783778)
		(mid 127.11415 -287.920138)
		(end 127.161798 -288.103056)
		(width 0.0889)
		(layer "In2.Cu")
		(net "P5E_CPU1_PE3_TX_DN<8>")
	)
	(arc
		(start 127.447548 -289.27806)
		(mid 127.238398 -289.47573)
		(end 127.161544 -289.75304)
		(width 0.0889)
		(layer "In2.Cu")
		(net "P5E_CPU1_PE3_TX_DN<8>")
	)
	(arc
		(start 126.504446 -286.964882)
		(mid 126.639486 -287.098596)
		(end 126.691644 -287.281366)
		(width 0.0889)
		(layer "In2.Cu")
		(net "P5E_CPU1_PE3_TX_DN<8>")
	)
	(arc
		(start 126.691644 -287.28924)
		(mid 126.765635 -287.568806)
		(end 126.96825 -287.775142)
		(width 0.0889)
		(layer "In2.Cu")
		(net "P5E_CPU1_PE3_TX_DN<8>")
	)
	(arc
		(start 127.444754 -288.592768)
		(mid 127.577973 -288.723438)
		(end 127.631698 -288.90214)
		(width 0.0889)
		(layer "In2.Cu")
		(net "P5E_CPU1_PE3_TX_DN<8>")
	)
	(arc
		(start 126.221998 -286.486092)
		(mid 126.300312 -286.762582)
		(end 126.504446 -286.964882)
		(width 0.0889)
		(layer "In2.Cu")
		(net "P5E_CPU1_PE3_TX_DN<8>")
	)
	(arc
		(start 126.082044 -286.18307)
		(mid 126.182876 -286.30817)
		(end 126.221998 -286.463994)
		(width 0.0889)
		(layer "In2.Cu")
		(net "P5E_CPU1_PE3_TX_DN<8>")
	)
	(segment
		(start 126.786894 -284.311598)
		(end 126.787148 -284.847538)
		(width 0.13208)
		(layer "F.Cu")
		(net "P5E_CPU1_PE3_TX_DN<7>")
	)
	(segment
		(start 146.007074 -407.00452)
		(end 146.312636 -407.310082)
		(width 0.13208)
		(layer "F.Cu")
		(net "P5E_CPU1_PE3_TX_DN<7>")
	)
	(segment
		(start 145.986246 -408.250644)
		(end 145.981674 -408.250644)
		(width 0.13208)
		(layer "F.Cu")
		(net "P5E_CPU1_PE3_TX_DN<7>")
	)
	(segment
		(start 146.312636 -407.310082)
		(end 146.312636 -407.924254)
		(width 0.13208)
		(layer "F.Cu")
		(net "P5E_CPU1_PE3_TX_DN<7>")
	)
	(segment
		(start 146.312636 -407.924254)
		(end 145.986246 -408.250644)
		(width 0.13208)
		(layer "F.Cu")
		(net "P5E_CPU1_PE3_TX_DN<7>")
	)
	(segment
		(start 153.329386 -376.089164)
		(end 157.355286 -341.537544)
		(width 0.14732)
		(layer "In2.Cu")
		(net "P5E_CPU1_PE3_TX_DN<7>")
	)
	(segment
		(start 128.392936 -288.597848)
		(end 128.384046 -288.592768)
		(width 0.0889)
		(layer "In2.Cu")
		(net "P5E_CPU1_PE3_TX_DN<7>")
	)
	(segment
		(start 146.487134 -405.117554)
		(end 146.487134 -399.170398)
		(width 0.14732)
		(layer "In2.Cu")
		(net "P5E_CPU1_PE3_TX_DN<7>")
	)
	(segment
		(start 146.487134 -399.170398)
		(end 153.329386 -376.089164)
		(width 0.14732)
		(layer "In2.Cu")
		(net "P5E_CPU1_PE3_TX_DN<7>")
	)
	(segment
		(start 146.007074 -407.00452)
		(end 146.301714 -406.70988)
		(width 0.14732)
		(layer "In2.Cu")
		(net "P5E_CPU1_PE3_TX_DN<7>")
	)
	(segment
		(start 127.915924 -287.779714)
		(end 127.914908 -287.779206)
		(width 0.0889)
		(layer "In2.Cu")
		(net "P5E_CPU1_PE3_TX_DN<7>")
	)
	(segment
		(start 156.232606 -332.228952)
		(end 152.24125 -326.528684)
		(width 0.14732)
		(layer "In2.Cu")
		(net "P5E_CPU1_PE3_TX_DN<7>")
	)
	(segment
		(start 126.943612 -285.118556)
		(end 126.787148 -284.847538)
		(width 0.0889)
		(layer "In2.Cu")
		(net "P5E_CPU1_PE3_TX_DN<7>")
	)
	(segment
		(start 127.913384 -287.77819)
		(end 127.90805 -287.775142)
		(width 0.0889)
		(layer "In2.Cu")
		(net "P5E_CPU1_PE3_TX_DN<7>")
	)
	(segment
		(start 136.947656 -306.621942)
		(end 130.1496 -299.824394)
		(width 0.14732)
		(layer "In2.Cu")
		(net "P5E_CPU1_PE3_TX_DN<7>")
	)
	(segment
		(start 128.059688 -290.358068)
		(end 128.101598 -290.316158)
		(width 0.0889)
		(layer "In2.Cu")
		(net "P5E_CPU1_PE3_TX_DN<7>")
	)
	(segment
		(start 126.982982 -286.156146)
		(end 126.974092 -286.151066)
		(width 0.0889)
		(layer "In2.Cu")
		(net "P5E_CPU1_PE3_TX_DN<7>")
	)
	(segment
		(start 144.866614 -317.931546)
		(end 136.947656 -306.621942)
		(width 0.14732)
		(layer "In2.Cu")
		(net "P5E_CPU1_PE3_TX_DN<7>")
	)
	(segment
		(start 127.923036 -287.783778)
		(end 127.915924 -287.779714)
		(width 0.0889)
		(layer "In2.Cu")
		(net "P5E_CPU1_PE3_TX_DN<7>")
	)
	(segment
		(start 127.443992 -286.964882)
		(end 127.437896 -286.961326)
		(width 0.0889)
		(layer "In2.Cu")
		(net "P5E_CPU1_PE3_TX_DN<7>")
	)
	(segment
		(start 128.059688 -290.380166)
		(end 128.059688 -290.358068)
		(width 0.0889)
		(layer "In2.Cu")
		(net "P5E_CPU1_PE3_TX_DN<7>")
	)
	(segment
		(start 128.059688 -294.778684)
		(end 128.059688 -290.380166)
		(width 0.14732)
		(layer "In2.Cu")
		(net "P5E_CPU1_PE3_TX_DN<7>")
	)
	(segment
		(start 128.101598 -288.121598)
		(end 128.101598 -288.103056)
		(width 0.0889)
		(layer "In2.Cu")
		(net "P5E_CPU1_PE3_TX_DN<7>")
	)
	(segment
		(start 128.571498 -289.077908)
		(end 128.571498 -288.917126)
		(width 0.0889)
		(layer "In2.Cu")
		(net "P5E_CPU1_PE3_TX_DN<7>")
	)
	(segment
		(start 157.355286 -341.537544)
		(end 157.355286 -338.589112)
		(width 0.14732)
		(layer "In2.Cu")
		(net "P5E_CPU1_PE3_TX_DN<7>")
	)
	(segment
		(start 157.355286 -338.589112)
		(end 156.232606 -332.228952)
		(width 0.14732)
		(layer "In2.Cu")
		(net "P5E_CPU1_PE3_TX_DN<7>")
	)
	(segment
		(start 128.101598 -290.316158)
		(end 128.101598 -289.609022)
		(width 0.0889)
		(layer "In2.Cu")
		(net "P5E_CPU1_PE3_TX_DN<7>")
	)
	(segment
		(start 127.914908 -287.779206)
		(end 127.913384 -287.77819)
		(width 0.0889)
		(layer "In2.Cu")
		(net "P5E_CPU1_PE3_TX_DN<7>")
	)
	(segment
		(start 152.24125 -326.528684)
		(end 144.866614 -317.931546)
		(width 0.14732)
		(layer "In2.Cu")
		(net "P5E_CPU1_PE3_TX_DN<7>")
	)
	(segment
		(start 146.301714 -405.302974)
		(end 146.487134 -405.117554)
		(width 0.14732)
		(layer "In2.Cu")
		(net "P5E_CPU1_PE3_TX_DN<7>")
	)
	(segment
		(start 127.452882 -286.969962)
		(end 127.443992 -286.964882)
		(width 0.0889)
		(layer "In2.Cu")
		(net "P5E_CPU1_PE3_TX_DN<7>")
	)
	(segment
		(start 130.1496 -299.824394)
		(end 128.059688 -294.778684)
		(width 0.14732)
		(layer "In2.Cu")
		(net "P5E_CPU1_PE3_TX_DN<7>")
	)
	(segment
		(start 146.301714 -406.70988)
		(end 146.301714 -405.302974)
		(width 0.14732)
		(layer "In2.Cu")
		(net "P5E_CPU1_PE3_TX_DN<7>")
	)
	(segment
		(start 128.101598 -289.609022)
		(end 128.101344 -289.609784)
		(width 0.0889)
		(layer "In2.Cu")
		(net "P5E_CPU1_PE3_TX_DN<7>")
	)
	(segment
		(start 126.919482 -285.20771)
		(end 126.943612 -285.118556)
		(width 0.0889)
		(layer "In2.Cu")
		(net "P5E_CPU1_PE3_TX_DN<7>")
	)
	(arc
		(start 126.974092 -286.151066)
		(mid 126.693014 -285.704831)
		(end 126.902464 -285.220918)
		(width 0.0889)
		(layer "In2.Cu")
		(net "P5E_CPU1_PE3_TX_DN<7>")
	)
	(arc
		(start 127.437896 -286.961326)
		(mid 127.235483 -286.754913)
		(end 127.161544 -286.475424)
		(width 0.0889)
		(layer "In2.Cu")
		(net "P5E_CPU1_PE3_TX_DN<7>")
	)
	(arc
		(start 127.90805 -287.775142)
		(mid 127.705463 -287.568791)
		(end 127.631444 -287.28924)
		(width 0.0889)
		(layer "In2.Cu")
		(net "P5E_CPU1_PE3_TX_DN<7>")
	)
	(arc
		(start 126.902464 -285.220918)
		(mid 126.91091 -285.214233)
		(end 126.919482 -285.20771)
		(width 0.0889)
		(layer "In2.Cu")
		(net "P5E_CPU1_PE3_TX_DN<7>")
	)
	(arc
		(start 127.161544 -286.475424)
		(mid 127.113865 -286.292524)
		(end 126.982982 -286.156146)
		(width 0.0889)
		(layer "In2.Cu")
		(net "P5E_CPU1_PE3_TX_DN<7>")
	)
	(arc
		(start 128.384046 -288.592768)
		(mid 128.18176 -288.393787)
		(end 128.101598 -288.121598)
		(width 0.0889)
		(layer "In2.Cu")
		(net "P5E_CPU1_PE3_TX_DN<7>")
	)
	(arc
		(start 128.571498 -288.917126)
		(mid 128.523819 -288.734226)
		(end 128.392936 -288.597848)
		(width 0.0889)
		(layer "In2.Cu")
		(net "P5E_CPU1_PE3_TX_DN<7>")
	)
	(arc
		(start 128.387094 -289.277806)
		(mid 128.49649 -289.193709)
		(end 128.571498 -289.077908)
		(width 0.0889)
		(layer "In2.Cu")
		(net "P5E_CPU1_PE3_TX_DN<7>")
	)
	(arc
		(start 127.631444 -287.28924)
		(mid 127.583765 -287.10634)
		(end 127.452882 -286.969962)
		(width 0.0889)
		(layer "In2.Cu")
		(net "P5E_CPU1_PE3_TX_DN<7>")
	)
	(arc
		(start 128.101344 -289.609784)
		(mid 128.1085 -289.590223)
		(end 128.11633 -289.570922)
		(width 0.0889)
		(layer "In2.Cu")
		(net "P5E_CPU1_PE3_TX_DN<7>")
	)
	(arc
		(start 128.11633 -289.570922)
		(mid 128.226587 -289.401162)
		(end 128.387094 -289.277806)
		(width 0.0889)
		(layer "In2.Cu")
		(net "P5E_CPU1_PE3_TX_DN<7>")
	)
	(arc
		(start 128.101598 -288.103056)
		(mid 128.053919 -287.920156)
		(end 127.923036 -287.783778)
		(width 0.0889)
		(layer "In2.Cu")
		(net "P5E_CPU1_PE3_TX_DN<7>")
	)
	(segment
		(start 149.049486 -408.250644)
		(end 149.044914 -408.250644)
		(width 0.13208)
		(layer "F.Cu")
		(net "P5E_CPU1_PE3_TX_DN<6>")
	)
	(segment
		(start 149.070314 -407.00452)
		(end 149.375876 -407.310082)
		(width 0.13208)
		(layer "F.Cu")
		(net "P5E_CPU1_PE3_TX_DN<6>")
	)
	(segment
		(start 127.726694 -286.47517)
		(end 127.726948 -286.475424)
		(width 0.13208)
		(layer "F.Cu")
		(net "P5E_CPU1_PE3_TX_DN<6>")
	)
	(segment
		(start 127.726694 -285.939484)
		(end 127.726694 -286.47517)
		(width 0.13208)
		(layer "F.Cu")
		(net "P5E_CPU1_PE3_TX_DN<6>")
	)
	(segment
		(start 149.375876 -407.310082)
		(end 149.375876 -407.924254)
		(width 0.13208)
		(layer "F.Cu")
		(net "P5E_CPU1_PE3_TX_DN<6>")
	)
	(segment
		(start 149.375876 -407.924254)
		(end 149.049486 -408.250644)
		(width 0.13208)
		(layer "F.Cu")
		(net "P5E_CPU1_PE3_TX_DN<6>")
	)
	(segment
		(start 150.040594 -396.996666)
		(end 150.187152 -396.898622)
		(width 0.14732)
		(layer "In2.Cu")
		(net "P5E_CPU1_PE3_TX_DN<6>")
	)
	(segment
		(start 127.96139 -286.183578)
		(end 127.883412 -286.204406)
		(width 0.0889)
		(layer "In2.Cu")
		(net "P5E_CPU1_PE3_TX_DN<6>")
	)
	(segment
		(start 152.972516 -325.95185)
		(end 145.683986 -317.455804)
		(width 0.14732)
		(layer "In2.Cu")
		(net "P5E_CPU1_PE3_TX_DN<6>")
	)
	(segment
		(start 128.862836 -287.783778)
		(end 128.853946 -287.778698)
		(width 0.0889)
		(layer "In2.Cu")
		(net "P5E_CPU1_PE3_TX_DN<6>")
	)
	(segment
		(start 145.683986 -317.455804)
		(end 137.635996 -305.961796)
		(width 0.14732)
		(layer "In2.Cu")
		(net "P5E_CPU1_PE3_TX_DN<6>")
	)
	(segment
		(start 158.294832 -338.310982)
		(end 157.172914 -331.95006)
		(width 0.14732)
		(layer "In2.Cu")
		(net "P5E_CPU1_PE3_TX_DN<6>")
	)
	(segment
		(start 152.973532 -325.95312)
		(end 152.972516 -325.95185)
		(width 0.14732)
		(layer "In2.Cu")
		(net "P5E_CPU1_PE3_TX_DN<6>")
	)
	(segment
		(start 155.07335 -328.95159)
		(end 152.973532 -325.95312)
		(width 0.14732)
		(layer "In2.Cu")
		(net "P5E_CPU1_PE3_TX_DN<6>")
	)
	(segment
		(start 128.999234 -290.380166)
		(end 128.999234 -290.358068)
		(width 0.0889)
		(layer "In2.Cu")
		(net "P5E_CPU1_PE3_TX_DN<6>")
	)
	(segment
		(start 129.041398 -288.121598)
		(end 129.041398 -288.103056)
		(width 0.0889)
		(layer "In2.Cu")
		(net "P5E_CPU1_PE3_TX_DN<6>")
	)
	(segment
		(start 149.550374 -400.117564)
		(end 149.83587 -398.67332)
		(width 0.14732)
		(layer "In2.Cu")
		(net "P5E_CPU1_PE3_TX_DN<6>")
	)
	(segment
		(start 149.070314 -407.00452)
		(end 149.364954 -406.70988)
		(width 0.14732)
		(layer "In2.Cu")
		(net "P5E_CPU1_PE3_TX_DN<6>")
	)
	(segment
		(start 149.550374 -405.117554)
		(end 149.550374 -400.117564)
		(width 0.14732)
		(layer "In2.Cu")
		(net "P5E_CPU1_PE3_TX_DN<6>")
	)
	(segment
		(start 129.332736 -288.597848)
		(end 129.323846 -288.592768)
		(width 0.0889)
		(layer "In2.Cu")
		(net "P5E_CPU1_PE3_TX_DN<6>")
	)
	(segment
		(start 128.853946 -287.778698)
		(end 128.84785 -287.775142)
		(width 0.0889)
		(layer "In2.Cu")
		(net "P5E_CPU1_PE3_TX_DN<6>")
	)
	(segment
		(start 127.883412 -286.204406)
		(end 127.726948 -286.475424)
		(width 0.0889)
		(layer "In2.Cu")
		(net "P5E_CPU1_PE3_TX_DN<6>")
	)
	(segment
		(start 128.392682 -286.969962)
		(end 128.383792 -286.964882)
		(width 0.0889)
		(layer "In2.Cu")
		(net "P5E_CPU1_PE3_TX_DN<6>")
	)
	(segment
		(start 149.737826 -398.527016)
		(end 149.822662 -398.09801)
		(width 0.14732)
		(layer "In2.Cu")
		(net "P5E_CPU1_PE3_TX_DN<6>")
	)
	(segment
		(start 130.91414 -299.23994)
		(end 128.999234 -294.616632)
		(width 0.14732)
		(layer "In2.Cu")
		(net "P5E_CPU1_PE3_TX_DN<6>")
	)
	(segment
		(start 129.511298 -288.963608)
		(end 129.511298 -288.917126)
		(width 0.0889)
		(layer "In2.Cu")
		(net "P5E_CPU1_PE3_TX_DN<6>")
	)
	(segment
		(start 149.364954 -406.70988)
		(end 149.364954 -405.302974)
		(width 0.14732)
		(layer "In2.Cu")
		(net "P5E_CPU1_PE3_TX_DN<6>")
	)
	(segment
		(start 149.83587 -398.67332)
		(end 149.737826 -398.527016)
		(width 0.14732)
		(layer "In2.Cu")
		(net "P5E_CPU1_PE3_TX_DN<6>")
	)
	(segment
		(start 149.96922 -398.00022)
		(end 150.053802 -397.571722)
		(width 0.14732)
		(layer "In2.Cu")
		(net "P5E_CPU1_PE3_TX_DN<6>")
	)
	(segment
		(start 128.101344 -286.48533)
		(end 128.101344 -286.466788)
		(width 0.0889)
		(layer "In2.Cu")
		(net "P5E_CPU1_PE3_TX_DN<6>")
	)
	(segment
		(start 158.294832 -341.602568)
		(end 158.294832 -338.310982)
		(width 0.14732)
		(layer "In2.Cu")
		(net "P5E_CPU1_PE3_TX_DN<6>")
	)
	(segment
		(start 149.955758 -397.425418)
		(end 150.040594 -396.996666)
		(width 0.14732)
		(layer "In2.Cu")
		(net "P5E_CPU1_PE3_TX_DN<6>")
	)
	(segment
		(start 129.041144 -290.316158)
		(end 129.041144 -289.764724)
		(width 0.0889)
		(layer "In2.Cu")
		(net "P5E_CPU1_PE3_TX_DN<6>")
	)
	(segment
		(start 149.364954 -405.302974)
		(end 149.550374 -405.117554)
		(width 0.14732)
		(layer "In2.Cu")
		(net "P5E_CPU1_PE3_TX_DN<6>")
	)
	(segment
		(start 157.172914 -331.95006)
		(end 155.07335 -328.95159)
		(width 0.14732)
		(layer "In2.Cu")
		(net "P5E_CPU1_PE3_TX_DN<6>")
	)
	(segment
		(start 137.635996 -305.961796)
		(end 130.91414 -299.23994)
		(width 0.14732)
		(layer "In2.Cu")
		(net "P5E_CPU1_PE3_TX_DN<6>")
	)
	(segment
		(start 128.999234 -294.616632)
		(end 128.999234 -290.380166)
		(width 0.14732)
		(layer "In2.Cu")
		(net "P5E_CPU1_PE3_TX_DN<6>")
	)
	(segment
		(start 150.187152 -396.896844)
		(end 154.243024 -376.385836)
		(width 0.14732)
		(layer "In2.Cu")
		(net "P5E_CPU1_PE3_TX_DN<6>")
	)
	(segment
		(start 150.053802 -397.571722)
		(end 149.955758 -397.425418)
		(width 0.14732)
		(layer "In2.Cu")
		(net "P5E_CPU1_PE3_TX_DN<6>")
	)
	(segment
		(start 154.243024 -376.385836)
		(end 158.294832 -341.602568)
		(width 0.14732)
		(layer "In2.Cu")
		(net "P5E_CPU1_PE3_TX_DN<6>")
	)
	(segment
		(start 149.822662 -398.09801)
		(end 149.96922 -398.00022)
		(width 0.14732)
		(layer "In2.Cu")
		(net "P5E_CPU1_PE3_TX_DN<6>")
	)
	(segment
		(start 150.187152 -396.898622)
		(end 150.187152 -396.896844)
		(width 0.14732)
		(layer "In2.Cu")
		(net "P5E_CPU1_PE3_TX_DN<6>")
	)
	(segment
		(start 128.999234 -290.358068)
		(end 129.041144 -290.316158)
		(width 0.0889)
		(layer "In2.Cu")
		(net "P5E_CPU1_PE3_TX_DN<6>")
	)
	(arc
		(start 129.323846 -288.592768)
		(mid 129.12156 -288.393787)
		(end 129.041398 -288.121598)
		(width 0.0889)
		(layer "In2.Cu")
		(net "P5E_CPU1_PE3_TX_DN<6>")
	)
	(arc
		(start 129.041144 -289.764724)
		(mid 129.117887 -289.482256)
		(end 129.327148 -289.277552)
		(width 0.0889)
		(layer "In2.Cu")
		(net "P5E_CPU1_PE3_TX_DN<6>")
	)
	(arc
		(start 129.041398 -288.103056)
		(mid 128.993719 -287.920156)
		(end 128.862836 -287.783778)
		(width 0.0889)
		(layer "In2.Cu")
		(net "P5E_CPU1_PE3_TX_DN<6>")
	)
	(arc
		(start 128.383792 -286.964882)
		(mid 128.179457 -286.762277)
		(end 128.101344 -286.48533)
		(width 0.0889)
		(layer "In2.Cu")
		(net "P5E_CPU1_PE3_TX_DN<6>")
	)
	(arc
		(start 128.571244 -287.28924)
		(mid 128.523565 -287.10634)
		(end 128.392682 -286.969962)
		(width 0.0889)
		(layer "In2.Cu")
		(net "P5E_CPU1_PE3_TX_DN<6>")
	)
	(arc
		(start 129.511298 -288.917126)
		(mid 129.463619 -288.734226)
		(end 129.332736 -288.597848)
		(width 0.0889)
		(layer "In2.Cu")
		(net "P5E_CPU1_PE3_TX_DN<6>")
	)
	(arc
		(start 128.84785 -287.775142)
		(mid 128.645263 -287.568791)
		(end 128.571244 -287.28924)
		(width 0.0889)
		(layer "In2.Cu")
		(net "P5E_CPU1_PE3_TX_DN<6>")
	)
	(arc
		(start 129.327148 -289.277552)
		(mid 129.461962 -289.145627)
		(end 129.511298 -288.963608)
		(width 0.0889)
		(layer "In2.Cu")
		(net "P5E_CPU1_PE3_TX_DN<6>")
	)
	(arc
		(start 128.101344 -286.466788)
		(mid 128.06267 -286.30972)
		(end 127.96139 -286.183578)
		(width 0.0889)
		(layer "In2.Cu")
		(net "P5E_CPU1_PE3_TX_DN<6>")
	)
	(segment
		(start 152.439116 -407.310082)
		(end 152.439116 -407.924254)
		(width 0.13208)
		(layer "F.Cu")
		(net "P5E_CPU1_PE3_TX_DN<5>")
	)
	(segment
		(start 152.439116 -407.924254)
		(end 152.112726 -408.250644)
		(width 0.13208)
		(layer "F.Cu")
		(net "P5E_CPU1_PE3_TX_DN<5>")
	)
	(segment
		(start 152.133554 -407.00452)
		(end 152.439116 -407.310082)
		(width 0.13208)
		(layer "F.Cu")
		(net "P5E_CPU1_PE3_TX_DN<5>")
	)
	(segment
		(start 152.112726 -408.250644)
		(end 152.108154 -408.250644)
		(width 0.13208)
		(layer "F.Cu")
		(net "P5E_CPU1_PE3_TX_DN<5>")
	)
	(segment
		(start 128.666494 -284.311598)
		(end 128.666748 -284.847538)
		(width 0.13208)
		(layer "F.Cu")
		(net "P5E_CPU1_PE3_TX_DN<5>")
	)
	(segment
		(start 129.802636 -287.783778)
		(end 129.793746 -287.778698)
		(width 0.0889)
		(layer "In2.Cu")
		(net "P5E_CPU1_PE3_TX_DN<5>")
	)
	(segment
		(start 159.233108 -341.763096)
		(end 159.233108 -338.151724)
		(width 0.14732)
		(layer "In2.Cu")
		(net "P5E_CPU1_PE3_TX_DN<5>")
	)
	(segment
		(start 128.823212 -285.118556)
		(end 128.666748 -284.847538)
		(width 0.0889)
		(layer "In2.Cu")
		(net "P5E_CPU1_PE3_TX_DN<5>")
	)
	(segment
		(start 129.939288 -290.358068)
		(end 129.981198 -290.316158)
		(width 0.0889)
		(layer "In2.Cu")
		(net "P5E_CPU1_PE3_TX_DN<5>")
	)
	(segment
		(start 152.428194 -405.302974)
		(end 152.613614 -405.117554)
		(width 0.14732)
		(layer "In2.Cu")
		(net "P5E_CPU1_PE3_TX_DN<5>")
	)
	(segment
		(start 129.332482 -286.969962)
		(end 129.323592 -286.964882)
		(width 0.0889)
		(layer "In2.Cu")
		(net "P5E_CPU1_PE3_TX_DN<5>")
	)
	(segment
		(start 130.266948 -289.27806)
		(end 130.266694 -289.277806)
		(width 0.0889)
		(layer "In2.Cu")
		(net "P5E_CPU1_PE3_TX_DN<5>")
	)
	(segment
		(start 159.233108 -338.151724)
		(end 157.939232 -330.816204)
		(width 0.14732)
		(layer "In2.Cu")
		(net "P5E_CPU1_PE3_TX_DN<5>")
	)
	(segment
		(start 128.799082 -285.20771)
		(end 128.823212 -285.118556)
		(width 0.0889)
		(layer "In2.Cu")
		(net "P5E_CPU1_PE3_TX_DN<5>")
	)
	(segment
		(start 130.451098 -289.077908)
		(end 130.451098 -288.917126)
		(width 0.0889)
		(layer "In2.Cu")
		(net "P5E_CPU1_PE3_TX_DN<5>")
	)
	(segment
		(start 129.793746 -287.778698)
		(end 129.78765 -287.775142)
		(width 0.0889)
		(layer "In2.Cu")
		(net "P5E_CPU1_PE3_TX_DN<5>")
	)
	(segment
		(start 129.939288 -292.534594)
		(end 129.939288 -290.380166)
		(width 0.14732)
		(layer "In2.Cu")
		(net "P5E_CPU1_PE3_TX_DN<5>")
	)
	(segment
		(start 129.981198 -288.121598)
		(end 129.981198 -288.103056)
		(width 0.0889)
		(layer "In2.Cu")
		(net "P5E_CPU1_PE3_TX_DN<5>")
	)
	(segment
		(start 135.428228 -295.79443)
		(end 135.198612 -295.564814)
		(width 0.14732)
		(layer "In2.Cu")
		(net "P5E_CPU1_PE3_TX_DN<5>")
	)
	(segment
		(start 130.272536 -288.597848)
		(end 130.263646 -288.592768)
		(width 0.0889)
		(layer "In2.Cu")
		(net "P5E_CPU1_PE3_TX_DN<5>")
	)
	(segment
		(start 140.6017 -308.54904)
		(end 139.813538 -307.23459)
		(width 0.14732)
		(layer "In2.Cu")
		(net "P5E_CPU1_PE3_TX_DN<5>")
	)
	(segment
		(start 152.613614 -405.117554)
		(end 152.613614 -400.12874)
		(width 0.14732)
		(layer "In2.Cu")
		(net "P5E_CPU1_PE3_TX_DN<5>")
	)
	(segment
		(start 128.571244 -285.679896)
		(end 128.571244 -285.661354)
		(width 0.0889)
		(layer "In2.Cu")
		(net "P5E_CPU1_PE3_TX_DN<5>")
	)
	(segment
		(start 157.939232 -330.816204)
		(end 140.6017 -308.54904)
		(width 0.14732)
		(layer "In2.Cu")
		(net "P5E_CPU1_PE3_TX_DN<5>")
	)
	(segment
		(start 136.40562 -299.581316)
		(end 135.95985 -297.077892)
		(width 0.14732)
		(layer "In2.Cu")
		(net "P5E_CPU1_PE3_TX_DN<5>")
	)
	(segment
		(start 135.198612 -295.564814)
		(end 131.393438 -293.988744)
		(width 0.14732)
		(layer "In2.Cu")
		(net "P5E_CPU1_PE3_TX_DN<5>")
	)
	(segment
		(start 129.981198 -290.316158)
		(end 129.981198 -289.611054)
		(width 0.0889)
		(layer "In2.Cu")
		(net "P5E_CPU1_PE3_TX_DN<5>")
	)
	(segment
		(start 152.428194 -406.70988)
		(end 152.428194 -405.302974)
		(width 0.14732)
		(layer "In2.Cu")
		(net "P5E_CPU1_PE3_TX_DN<5>")
	)
	(segment
		(start 129.323592 -286.964882)
		(end 129.317496 -286.961326)
		(width 0.0889)
		(layer "In2.Cu")
		(net "P5E_CPU1_PE3_TX_DN<5>")
	)
	(segment
		(start 152.133554 -407.00452)
		(end 152.428194 -406.70988)
		(width 0.14732)
		(layer "In2.Cu")
		(net "P5E_CPU1_PE3_TX_DN<5>")
	)
	(segment
		(start 128.862582 -286.156146)
		(end 128.853692 -286.151066)
		(width 0.0889)
		(layer "In2.Cu")
		(net "P5E_CPU1_PE3_TX_DN<5>")
	)
	(segment
		(start 135.95985 -297.077892)
		(end 135.428228 -295.79443)
		(width 0.14732)
		(layer "In2.Cu")
		(net "P5E_CPU1_PE3_TX_DN<5>")
	)
	(segment
		(start 139.813538 -307.23459)
		(end 136.40562 -299.581316)
		(width 0.14732)
		(layer "In2.Cu")
		(net "P5E_CPU1_PE3_TX_DN<5>")
	)
	(segment
		(start 152.613614 -400.12874)
		(end 159.233108 -341.763096)
		(width 0.14732)
		(layer "In2.Cu")
		(net "P5E_CPU1_PE3_TX_DN<5>")
	)
	(segment
		(start 129.939288 -290.380166)
		(end 129.939288 -290.358068)
		(width 0.0889)
		(layer "In2.Cu")
		(net "P5E_CPU1_PE3_TX_DN<5>")
	)
	(segment
		(start 131.393438 -293.988744)
		(end 129.939288 -292.534594)
		(width 0.14732)
		(layer "In2.Cu")
		(net "P5E_CPU1_PE3_TX_DN<5>")
	)
	(arc
		(start 129.511044 -287.28924)
		(mid 129.463365 -287.10634)
		(end 129.332482 -286.969962)
		(width 0.0889)
		(layer "In2.Cu")
		(net "P5E_CPU1_PE3_TX_DN<5>")
	)
	(arc
		(start 129.78765 -287.775142)
		(mid 129.585063 -287.568791)
		(end 129.511044 -287.28924)
		(width 0.0889)
		(layer "In2.Cu")
		(net "P5E_CPU1_PE3_TX_DN<5>")
	)
	(arc
		(start 128.782064 -285.220918)
		(mid 128.79051 -285.214233)
		(end 128.799082 -285.20771)
		(width 0.0889)
		(layer "In2.Cu")
		(net "P5E_CPU1_PE3_TX_DN<5>")
	)
	(arc
		(start 129.317496 -286.961326)
		(mid 129.115083 -286.754913)
		(end 129.041144 -286.475424)
		(width 0.0889)
		(layer "In2.Cu")
		(net "P5E_CPU1_PE3_TX_DN<5>")
	)
	(arc
		(start 129.981198 -289.611054)
		(mid 129.988469 -289.591108)
		(end 129.996438 -289.57143)
		(width 0.0889)
		(layer "In2.Cu")
		(net "P5E_CPU1_PE3_TX_DN<5>")
	)
	(arc
		(start 129.996438 -289.57143)
		(mid 130.106504 -289.401521)
		(end 130.266948 -289.27806)
		(width 0.0889)
		(layer "In2.Cu")
		(net "P5E_CPU1_PE3_TX_DN<5>")
	)
	(arc
		(start 128.853692 -286.151066)
		(mid 128.651406 -285.952085)
		(end 128.571244 -285.679896)
		(width 0.0889)
		(layer "In2.Cu")
		(net "P5E_CPU1_PE3_TX_DN<5>")
	)
	(arc
		(start 129.981198 -288.103056)
		(mid 129.933519 -287.920156)
		(end 129.802636 -287.783778)
		(width 0.0889)
		(layer "In2.Cu")
		(net "P5E_CPU1_PE3_TX_DN<5>")
	)
	(arc
		(start 130.451098 -288.917126)
		(mid 130.403419 -288.734226)
		(end 130.272536 -288.597848)
		(width 0.0889)
		(layer "In2.Cu")
		(net "P5E_CPU1_PE3_TX_DN<5>")
	)
	(arc
		(start 130.266694 -289.277806)
		(mid 130.37609 -289.193709)
		(end 130.451098 -289.077908)
		(width 0.0889)
		(layer "In2.Cu")
		(net "P5E_CPU1_PE3_TX_DN<5>")
	)
	(arc
		(start 129.041144 -286.475424)
		(mid 128.993465 -286.292524)
		(end 128.862582 -286.156146)
		(width 0.0889)
		(layer "In2.Cu")
		(net "P5E_CPU1_PE3_TX_DN<5>")
	)
	(arc
		(start 130.263646 -288.592768)
		(mid 130.06136 -288.393787)
		(end 129.981198 -288.121598)
		(width 0.0889)
		(layer "In2.Cu")
		(net "P5E_CPU1_PE3_TX_DN<5>")
	)
	(arc
		(start 128.571244 -285.661354)
		(mid 128.626599 -285.417167)
		(end 128.782064 -285.220918)
		(width 0.0889)
		(layer "In2.Cu")
		(net "P5E_CPU1_PE3_TX_DN<5>")
	)
	(segment
		(start 155.502356 -407.310082)
		(end 155.502356 -407.924254)
		(width 0.13208)
		(layer "F.Cu")
		(net "P5E_CPU1_PE3_TX_DN<4>")
	)
	(segment
		(start 129.606294 -285.939484)
		(end 129.606294 -286.47517)
		(width 0.13208)
		(layer "F.Cu")
		(net "P5E_CPU1_PE3_TX_DN<4>")
	)
	(segment
		(start 155.502356 -407.924254)
		(end 155.175966 -408.250644)
		(width 0.13208)
		(layer "F.Cu")
		(net "P5E_CPU1_PE3_TX_DN<4>")
	)
	(segment
		(start 155.175966 -408.250644)
		(end 155.171394 -408.250644)
		(width 0.13208)
		(layer "F.Cu")
		(net "P5E_CPU1_PE3_TX_DN<4>")
	)
	(segment
		(start 129.606294 -286.47517)
		(end 129.606548 -286.475424)
		(width 0.13208)
		(layer "F.Cu")
		(net "P5E_CPU1_PE3_TX_DN<4>")
	)
	(segment
		(start 155.196794 -407.00452)
		(end 155.502356 -407.310082)
		(width 0.13208)
		(layer "F.Cu")
		(net "P5E_CPU1_PE3_TX_DN<4>")
	)
	(segment
		(start 130.878834 -290.446206)
		(end 130.878834 -290.424108)
		(width 0.0889)
		(layer "In2.Cu")
		(net "P5E_CPU1_PE3_TX_DN<4>")
	)
	(segment
		(start 156.31668 -375.729246)
		(end 160.171384 -342.654128)
		(width 0.14732)
		(layer "In2.Cu")
		(net "P5E_CPU1_PE3_TX_DN<4>")
	)
	(segment
		(start 155.676854 -400.140678)
		(end 155.717494 -398.588992)
		(width 0.14732)
		(layer "In2.Cu")
		(net "P5E_CPU1_PE3_TX_DN<4>")
	)
	(segment
		(start 155.6258 -397.338804)
		(end 155.63723 -396.901924)
		(width 0.14732)
		(layer "In2.Cu")
		(net "P5E_CPU1_PE3_TX_DN<4>")
	)
	(segment
		(start 130.920998 -288.121598)
		(end 130.920998 -288.103056)
		(width 0.0889)
		(layer "In2.Cu")
		(net "P5E_CPU1_PE3_TX_DN<4>")
	)
	(segment
		(start 155.607766 -398.02435)
		(end 155.735528 -397.903192)
		(width 0.14732)
		(layer "In2.Cu")
		(net "P5E_CPU1_PE3_TX_DN<4>")
	)
	(segment
		(start 155.491434 -406.70988)
		(end 155.491434 -405.302974)
		(width 0.14732)
		(layer "In2.Cu")
		(net "P5E_CPU1_PE3_TX_DN<4>")
	)
	(segment
		(start 136.896348 -296.884852)
		(end 136.226804 -295.268396)
		(width 0.14732)
		(layer "In2.Cu")
		(net "P5E_CPU1_PE3_TX_DN<4>")
	)
	(segment
		(start 131.212336 -288.597848)
		(end 131.203446 -288.592768)
		(width 0.0889)
		(layer "In2.Cu")
		(net "P5E_CPU1_PE3_TX_DN<4>")
	)
	(segment
		(start 131.390898 -289.077908)
		(end 131.390898 -288.917126)
		(width 0.0889)
		(layer "In2.Cu")
		(net "P5E_CPU1_PE3_TX_DN<4>")
	)
	(segment
		(start 155.491434 -405.302974)
		(end 155.676854 -405.117554)
		(width 0.14732)
		(layer "In2.Cu")
		(net "P5E_CPU1_PE3_TX_DN<4>")
	)
	(segment
		(start 160.171384 -342.654128)
		(end 160.171384 -338.113116)
		(width 0.14732)
		(layer "In2.Cu")
		(net "P5E_CPU1_PE3_TX_DN<4>")
	)
	(segment
		(start 155.764738 -396.78102)
		(end 156.31668 -375.729246)
		(width 0.14732)
		(layer "In2.Cu")
		(net "P5E_CPU1_PE3_TX_DN<4>")
	)
	(segment
		(start 129.763012 -286.204406)
		(end 129.606548 -286.475424)
		(width 0.0889)
		(layer "In2.Cu")
		(net "P5E_CPU1_PE3_TX_DN<4>")
	)
	(segment
		(start 130.878834 -290.424108)
		(end 130.920744 -290.382198)
		(width 0.0889)
		(layer "In2.Cu")
		(net "P5E_CPU1_PE3_TX_DN<4>")
	)
	(segment
		(start 130.272282 -286.969962)
		(end 130.263392 -286.964882)
		(width 0.0889)
		(layer "In2.Cu")
		(net "P5E_CPU1_PE3_TX_DN<4>")
	)
	(segment
		(start 129.980944 -286.48533)
		(end 129.980944 -286.466788)
		(width 0.0889)
		(layer "In2.Cu")
		(net "P5E_CPU1_PE3_TX_DN<4>")
	)
	(segment
		(start 155.735528 -397.903192)
		(end 155.746958 -397.466566)
		(width 0.14732)
		(layer "In2.Cu")
		(net "P5E_CPU1_PE3_TX_DN<4>")
	)
	(segment
		(start 130.920744 -290.382198)
		(end 130.920744 -289.609784)
		(width 0.0889)
		(layer "In2.Cu")
		(net "P5E_CPU1_PE3_TX_DN<4>")
	)
	(segment
		(start 135.578596 -294.620188)
		(end 131.873244 -293.08552)
		(width 0.14732)
		(layer "In2.Cu")
		(net "P5E_CPU1_PE3_TX_DN<4>")
	)
	(segment
		(start 130.742436 -287.783778)
		(end 130.741166 -287.783016)
		(width 0.0889)
		(layer "In2.Cu")
		(net "P5E_CPU1_PE3_TX_DN<4>")
	)
	(segment
		(start 130.732784 -287.77819)
		(end 130.72745 -287.775142)
		(width 0.0889)
		(layer "In2.Cu")
		(net "P5E_CPU1_PE3_TX_DN<4>")
	)
	(segment
		(start 155.196794 -407.00452)
		(end 155.491434 -406.70988)
		(width 0.14732)
		(layer "In2.Cu")
		(net "P5E_CPU1_PE3_TX_DN<4>")
	)
	(segment
		(start 130.878834 -292.09111)
		(end 130.878834 -290.446206)
		(width 0.14732)
		(layer "In2.Cu")
		(net "P5E_CPU1_PE3_TX_DN<4>")
	)
	(segment
		(start 130.741166 -287.783016)
		(end 130.739134 -287.782)
		(width 0.0889)
		(layer "In2.Cu")
		(net "P5E_CPU1_PE3_TX_DN<4>")
	)
	(segment
		(start 158.8135 -330.414376)
		(end 141.489684 -308.164484)
		(width 0.14732)
		(layer "In2.Cu")
		(net "P5E_CPU1_PE3_TX_DN<4>")
	)
	(segment
		(start 130.734308 -287.779206)
		(end 130.732784 -287.77819)
		(width 0.0889)
		(layer "In2.Cu")
		(net "P5E_CPU1_PE3_TX_DN<4>")
	)
	(segment
		(start 155.63723 -396.901924)
		(end 155.764738 -396.78102)
		(width 0.14732)
		(layer "In2.Cu")
		(net "P5E_CPU1_PE3_TX_DN<4>")
	)
	(segment
		(start 141.489684 -308.164484)
		(end 140.570204 -306.631594)
		(width 0.14732)
		(layer "In2.Cu")
		(net "P5E_CPU1_PE3_TX_DN<4>")
	)
	(segment
		(start 155.596336 -398.461484)
		(end 155.607766 -398.02435)
		(width 0.14732)
		(layer "In2.Cu")
		(net "P5E_CPU1_PE3_TX_DN<4>")
	)
	(segment
		(start 155.746958 -397.466566)
		(end 155.6258 -397.338804)
		(width 0.14732)
		(layer "In2.Cu")
		(net "P5E_CPU1_PE3_TX_DN<4>")
	)
	(segment
		(start 129.84099 -286.183578)
		(end 129.763012 -286.204406)
		(width 0.0889)
		(layer "In2.Cu")
		(net "P5E_CPU1_PE3_TX_DN<4>")
	)
	(segment
		(start 140.570204 -306.631594)
		(end 137.341102 -299.380656)
		(width 0.14732)
		(layer "In2.Cu")
		(net "P5E_CPU1_PE3_TX_DN<4>")
	)
	(segment
		(start 136.226804 -295.268396)
		(end 135.578596 -294.620188)
		(width 0.14732)
		(layer "In2.Cu")
		(net "P5E_CPU1_PE3_TX_DN<4>")
	)
	(segment
		(start 155.717494 -398.588992)
		(end 155.596336 -398.461484)
		(width 0.14732)
		(layer "In2.Cu")
		(net "P5E_CPU1_PE3_TX_DN<4>")
	)
	(segment
		(start 137.341102 -299.380656)
		(end 136.896348 -296.884852)
		(width 0.14732)
		(layer "In2.Cu")
		(net "P5E_CPU1_PE3_TX_DN<4>")
	)
	(segment
		(start 155.676854 -405.117554)
		(end 155.676854 -400.140678)
		(width 0.14732)
		(layer "In2.Cu")
		(net "P5E_CPU1_PE3_TX_DN<4>")
	)
	(segment
		(start 160.171384 -338.113116)
		(end 158.8135 -330.414376)
		(width 0.14732)
		(layer "In2.Cu")
		(net "P5E_CPU1_PE3_TX_DN<4>")
	)
	(segment
		(start 130.739134 -287.782)
		(end 130.734308 -287.779206)
		(width 0.0889)
		(layer "In2.Cu")
		(net "P5E_CPU1_PE3_TX_DN<4>")
	)
	(segment
		(start 131.873244 -293.08552)
		(end 130.878834 -292.09111)
		(width 0.14732)
		(layer "In2.Cu")
		(net "P5E_CPU1_PE3_TX_DN<4>")
	)
	(arc
		(start 131.203446 -288.592768)
		(mid 131.00116 -288.393787)
		(end 130.920998 -288.121598)
		(width 0.0889)
		(layer "In2.Cu")
		(net "P5E_CPU1_PE3_TX_DN<4>")
	)
	(arc
		(start 131.206494 -289.277806)
		(mid 131.31589 -289.193709)
		(end 131.390898 -289.077908)
		(width 0.0889)
		(layer "In2.Cu")
		(net "P5E_CPU1_PE3_TX_DN<4>")
	)
	(arc
		(start 130.450844 -287.28924)
		(mid 130.403165 -287.10634)
		(end 130.272282 -286.969962)
		(width 0.0889)
		(layer "In2.Cu")
		(net "P5E_CPU1_PE3_TX_DN<4>")
	)
	(arc
		(start 131.390898 -288.917126)
		(mid 131.343219 -288.734226)
		(end 131.212336 -288.597848)
		(width 0.0889)
		(layer "In2.Cu")
		(net "P5E_CPU1_PE3_TX_DN<4>")
	)
	(arc
		(start 130.920744 -289.609784)
		(mid 131.03214 -289.416691)
		(end 131.206494 -289.277806)
		(width 0.0889)
		(layer "In2.Cu")
		(net "P5E_CPU1_PE3_TX_DN<4>")
	)
	(arc
		(start 130.920998 -288.103056)
		(mid 130.873319 -287.920156)
		(end 130.742436 -287.783778)
		(width 0.0889)
		(layer "In2.Cu")
		(net "P5E_CPU1_PE3_TX_DN<4>")
	)
	(arc
		(start 129.980944 -286.466788)
		(mid 129.94227 -286.30972)
		(end 129.84099 -286.183578)
		(width 0.0889)
		(layer "In2.Cu")
		(net "P5E_CPU1_PE3_TX_DN<4>")
	)
	(arc
		(start 130.72745 -287.775142)
		(mid 130.524863 -287.568791)
		(end 130.450844 -287.28924)
		(width 0.0889)
		(layer "In2.Cu")
		(net "P5E_CPU1_PE3_TX_DN<4>")
	)
	(arc
		(start 130.263392 -286.964882)
		(mid 130.059057 -286.762277)
		(end 129.980944 -286.48533)
		(width 0.0889)
		(layer "In2.Cu")
		(net "P5E_CPU1_PE3_TX_DN<4>")
	)
	(segment
		(start 158.260034 -407.00452)
		(end 158.565596 -407.310082)
		(width 0.13208)
		(layer "F.Cu")
		(net "P5E_CPU1_PE3_TX_DN<3>")
	)
	(segment
		(start 158.565596 -407.924254)
		(end 158.239206 -408.250644)
		(width 0.13208)
		(layer "F.Cu")
		(net "P5E_CPU1_PE3_TX_DN<3>")
	)
	(segment
		(start 158.239206 -408.250644)
		(end 158.234634 -408.250644)
		(width 0.13208)
		(layer "F.Cu")
		(net "P5E_CPU1_PE3_TX_DN<3>")
	)
	(segment
		(start 158.565596 -407.310082)
		(end 158.565596 -407.924254)
		(width 0.13208)
		(layer "F.Cu")
		(net "P5E_CPU1_PE3_TX_DN<3>")
	)
	(segment
		(start 130.546094 -284.311598)
		(end 130.546348 -284.847538)
		(width 0.13208)
		(layer "F.Cu")
		(net "P5E_CPU1_PE3_TX_DN<3>")
	)
	(segment
		(start 136.089644 -293.778432)
		(end 132.324094 -292.218618)
		(width 0.14732)
		(layer "In2.Cu")
		(net "P5E_CPU1_PE3_TX_DN<3>")
	)
	(segment
		(start 130.742182 -286.156146)
		(end 130.733292 -286.151066)
		(width 0.0889)
		(layer "In2.Cu")
		(net "P5E_CPU1_PE3_TX_DN<3>")
	)
	(segment
		(start 131.860544 -290.382198)
		(end 131.860544 -289.609784)
		(width 0.0889)
		(layer "In2.Cu")
		(net "P5E_CPU1_PE3_TX_DN<3>")
	)
	(segment
		(start 131.212082 -286.969962)
		(end 131.203192 -286.964882)
		(width 0.0889)
		(layer "In2.Cu")
		(net "P5E_CPU1_PE3_TX_DN<3>")
	)
	(segment
		(start 131.818634 -291.713158)
		(end 131.818634 -290.446206)
		(width 0.14732)
		(layer "In2.Cu")
		(net "P5E_CPU1_PE3_TX_DN<3>")
	)
	(segment
		(start 158.554674 -406.70988)
		(end 158.554674 -405.302974)
		(width 0.14732)
		(layer "In2.Cu")
		(net "P5E_CPU1_PE3_TX_DN<3>")
	)
	(segment
		(start 158.260034 -407.00452)
		(end 158.554674 -406.70988)
		(width 0.14732)
		(layer "In2.Cu")
		(net "P5E_CPU1_PE3_TX_DN<3>")
	)
	(segment
		(start 138.310112 -299.233336)
		(end 137.862056 -296.719498)
		(width 0.14732)
		(layer "In2.Cu")
		(net "P5E_CPU1_PE3_TX_DN<3>")
	)
	(segment
		(start 131.682236 -287.783778)
		(end 131.673346 -287.778698)
		(width 0.0889)
		(layer "In2.Cu")
		(net "P5E_CPU1_PE3_TX_DN<3>")
	)
	(segment
		(start 142.23746 -307.567838)
		(end 141.401038 -306.173124)
		(width 0.14732)
		(layer "In2.Cu")
		(net "P5E_CPU1_PE3_TX_DN<3>")
	)
	(segment
		(start 132.324094 -292.218618)
		(end 131.818634 -291.713158)
		(width 0.14732)
		(layer "In2.Cu")
		(net "P5E_CPU1_PE3_TX_DN<3>")
	)
	(segment
		(start 132.152136 -288.597848)
		(end 132.143246 -288.592768)
		(width 0.0889)
		(layer "In2.Cu")
		(net "P5E_CPU1_PE3_TX_DN<3>")
	)
	(segment
		(start 137.862056 -296.719498)
		(end 137.035794 -294.724582)
		(width 0.14732)
		(layer "In2.Cu")
		(net "P5E_CPU1_PE3_TX_DN<3>")
	)
	(segment
		(start 158.740094 -400.1135)
		(end 157.423358 -375.238264)
		(width 0.14732)
		(layer "In2.Cu")
		(net "P5E_CPU1_PE3_TX_DN<3>")
	)
	(segment
		(start 131.203192 -286.964882)
		(end 131.197096 -286.961326)
		(width 0.0889)
		(layer "In2.Cu")
		(net "P5E_CPU1_PE3_TX_DN<3>")
	)
	(segment
		(start 158.740094 -405.117554)
		(end 158.740094 -400.1135)
		(width 0.14732)
		(layer "In2.Cu")
		(net "P5E_CPU1_PE3_TX_DN<3>")
	)
	(segment
		(start 161.109406 -343.586816)
		(end 161.109406 -337.867244)
		(width 0.14732)
		(layer "In2.Cu")
		(net "P5E_CPU1_PE3_TX_DN<3>")
	)
	(segment
		(start 158.554674 -405.302974)
		(end 158.740094 -405.117554)
		(width 0.14732)
		(layer "In2.Cu")
		(net "P5E_CPU1_PE3_TX_DN<3>")
	)
	(segment
		(start 137.035794 -294.724582)
		(end 136.089644 -293.778432)
		(width 0.14732)
		(layer "In2.Cu")
		(net "P5E_CPU1_PE3_TX_DN<3>")
	)
	(segment
		(start 131.818634 -290.446206)
		(end 131.818634 -290.424108)
		(width 0.0889)
		(layer "In2.Cu")
		(net "P5E_CPU1_PE3_TX_DN<3>")
	)
	(segment
		(start 159.727392 -330.030836)
		(end 142.23746 -307.567838)
		(width 0.14732)
		(layer "In2.Cu")
		(net "P5E_CPU1_PE3_TX_DN<3>")
	)
	(segment
		(start 130.450844 -285.679896)
		(end 130.450844 -285.661354)
		(width 0.0889)
		(layer "In2.Cu")
		(net "P5E_CPU1_PE3_TX_DN<3>")
	)
	(segment
		(start 130.678682 -285.20771)
		(end 130.702812 -285.118556)
		(width 0.0889)
		(layer "In2.Cu")
		(net "P5E_CPU1_PE3_TX_DN<3>")
	)
	(segment
		(start 141.401038 -306.173124)
		(end 138.310112 -299.233336)
		(width 0.14732)
		(layer "In2.Cu")
		(net "P5E_CPU1_PE3_TX_DN<3>")
	)
	(segment
		(start 131.818634 -290.424108)
		(end 131.860544 -290.382198)
		(width 0.0889)
		(layer "In2.Cu")
		(net "P5E_CPU1_PE3_TX_DN<3>")
	)
	(segment
		(start 132.330698 -289.077908)
		(end 132.330698 -288.917126)
		(width 0.0889)
		(layer "In2.Cu")
		(net "P5E_CPU1_PE3_TX_DN<3>")
	)
	(segment
		(start 131.673346 -287.778698)
		(end 131.66725 -287.775142)
		(width 0.0889)
		(layer "In2.Cu")
		(net "P5E_CPU1_PE3_TX_DN<3>")
	)
	(segment
		(start 161.109406 -337.867244)
		(end 159.727392 -330.030836)
		(width 0.14732)
		(layer "In2.Cu")
		(net "P5E_CPU1_PE3_TX_DN<3>")
	)
	(segment
		(start 131.860798 -288.121598)
		(end 131.860798 -288.103056)
		(width 0.0889)
		(layer "In2.Cu")
		(net "P5E_CPU1_PE3_TX_DN<3>")
	)
	(segment
		(start 157.423358 -375.238264)
		(end 157.422088 -375.237248)
		(width 0.14732)
		(layer "In2.Cu")
		(net "P5E_CPU1_PE3_TX_DN<3>")
	)
	(segment
		(start 157.422088 -375.237248)
		(end 161.109406 -343.586816)
		(width 0.14732)
		(layer "In2.Cu")
		(net "P5E_CPU1_PE3_TX_DN<3>")
	)
	(segment
		(start 130.702812 -285.118556)
		(end 130.546348 -284.847538)
		(width 0.0889)
		(layer "In2.Cu")
		(net "P5E_CPU1_PE3_TX_DN<3>")
	)
	(arc
		(start 131.66725 -287.775142)
		(mid 131.464663 -287.568791)
		(end 131.390644 -287.28924)
		(width 0.0889)
		(layer "In2.Cu")
		(net "P5E_CPU1_PE3_TX_DN<3>")
	)
	(arc
		(start 132.330698 -288.917126)
		(mid 132.283019 -288.734226)
		(end 132.152136 -288.597848)
		(width 0.0889)
		(layer "In2.Cu")
		(net "P5E_CPU1_PE3_TX_DN<3>")
	)
	(arc
		(start 131.390644 -287.28924)
		(mid 131.342965 -287.10634)
		(end 131.212082 -286.969962)
		(width 0.0889)
		(layer "In2.Cu")
		(net "P5E_CPU1_PE3_TX_DN<3>")
	)
	(arc
		(start 130.733292 -286.151066)
		(mid 130.531006 -285.952085)
		(end 130.450844 -285.679896)
		(width 0.0889)
		(layer "In2.Cu")
		(net "P5E_CPU1_PE3_TX_DN<3>")
	)
	(arc
		(start 130.920744 -286.475424)
		(mid 130.873065 -286.292524)
		(end 130.742182 -286.156146)
		(width 0.0889)
		(layer "In2.Cu")
		(net "P5E_CPU1_PE3_TX_DN<3>")
	)
	(arc
		(start 130.450844 -285.661354)
		(mid 130.506199 -285.417167)
		(end 130.661664 -285.220918)
		(width 0.0889)
		(layer "In2.Cu")
		(net "P5E_CPU1_PE3_TX_DN<3>")
	)
	(arc
		(start 131.197096 -286.961326)
		(mid 130.994683 -286.754913)
		(end 130.920744 -286.475424)
		(width 0.0889)
		(layer "In2.Cu")
		(net "P5E_CPU1_PE3_TX_DN<3>")
	)
	(arc
		(start 132.146294 -289.277806)
		(mid 132.25569 -289.193709)
		(end 132.330698 -289.077908)
		(width 0.0889)
		(layer "In2.Cu")
		(net "P5E_CPU1_PE3_TX_DN<3>")
	)
	(arc
		(start 131.860798 -288.103056)
		(mid 131.813119 -287.920156)
		(end 131.682236 -287.783778)
		(width 0.0889)
		(layer "In2.Cu")
		(net "P5E_CPU1_PE3_TX_DN<3>")
	)
	(arc
		(start 130.661664 -285.220918)
		(mid 130.67011 -285.214233)
		(end 130.678682 -285.20771)
		(width 0.0889)
		(layer "In2.Cu")
		(net "P5E_CPU1_PE3_TX_DN<3>")
	)
	(arc
		(start 132.143246 -288.592768)
		(mid 131.94096 -288.393787)
		(end 131.860798 -288.121598)
		(width 0.0889)
		(layer "In2.Cu")
		(net "P5E_CPU1_PE3_TX_DN<3>")
	)
	(arc
		(start 131.860544 -289.609784)
		(mid 131.97194 -289.416691)
		(end 132.146294 -289.277806)
		(width 0.0889)
		(layer "In2.Cu")
		(net "P5E_CPU1_PE3_TX_DN<3>")
	)
	(segment
		(start 131.485894 -286.47517)
		(end 131.486148 -286.475424)
		(width 0.13208)
		(layer "F.Cu")
		(net "P5E_CPU1_PE3_TX_DN<2>")
	)
	(segment
		(start 161.628836 -407.310082)
		(end 161.628836 -407.924254)
		(width 0.13208)
		(layer "F.Cu")
		(net "P5E_CPU1_PE3_TX_DN<2>")
	)
	(segment
		(start 161.628836 -407.924254)
		(end 161.302446 -408.250644)
		(width 0.13208)
		(layer "F.Cu")
		(net "P5E_CPU1_PE3_TX_DN<2>")
	)
	(segment
		(start 131.485894 -285.939484)
		(end 131.485894 -286.47517)
		(width 0.13208)
		(layer "F.Cu")
		(net "P5E_CPU1_PE3_TX_DN<2>")
	)
	(segment
		(start 161.323274 -407.00452)
		(end 161.628836 -407.310082)
		(width 0.13208)
		(layer "F.Cu")
		(net "P5E_CPU1_PE3_TX_DN<2>")
	)
	(segment
		(start 161.302446 -408.250644)
		(end 161.297874 -408.250644)
		(width 0.13208)
		(layer "F.Cu")
		(net "P5E_CPU1_PE3_TX_DN<2>")
	)
	(segment
		(start 133.085586 -289.27806)
		(end 133.107684 -289.255962)
		(width 0.0889)
		(layer "In2.Cu")
		(net "P5E_CPU1_PE3_TX_DN<2>")
	)
	(segment
		(start 161.427668 -396.31747)
		(end 159.361124 -375.239026)
		(width 0.14732)
		(layer "In2.Cu")
		(net "P5E_CPU1_PE3_TX_DN<2>")
	)
	(segment
		(start 132.800598 -290.47821)
		(end 132.800598 -289.609784)
		(width 0.0889)
		(layer "In2.Cu")
		(net "P5E_CPU1_PE3_TX_DN<2>")
	)
	(segment
		(start 132.330444 -287.28924)
		(end 132.330444 -287.281366)
		(width 0.0889)
		(layer "In2.Cu")
		(net "P5E_CPU1_PE3_TX_DN<2>")
	)
	(segment
		(start 161.604706 -398.117568)
		(end 161.468308 -398.005808)
		(width 0.14732)
		(layer "In2.Cu")
		(net "P5E_CPU1_PE3_TX_DN<2>")
	)
	(segment
		(start 142.349728 -305.930808)
		(end 139.24534 -298.961302)
		(width 0.14732)
		(layer "In2.Cu")
		(net "P5E_CPU1_PE3_TX_DN<2>")
	)
	(segment
		(start 133.081268 -288.591244)
		(end 133.07187 -288.585656)
		(width 0.0889)
		(layer "In2.Cu")
		(net "P5E_CPU1_PE3_TX_DN<2>")
	)
	(segment
		(start 161.617914 -406.70988)
		(end 161.617914 -405.302974)
		(width 0.14732)
		(layer "In2.Cu")
		(net "P5E_CPU1_PE3_TX_DN<2>")
	)
	(segment
		(start 160.605978 -329.615546)
		(end 142.970504 -306.965604)
		(width 0.14732)
		(layer "In2.Cu")
		(net "P5E_CPU1_PE3_TX_DN<2>")
	)
	(segment
		(start 133.78942 -291.895784)
		(end 132.758434 -290.864798)
		(width 0.14732)
		(layer "In2.Cu")
		(net "P5E_CPU1_PE3_TX_DN<2>")
	)
	(segment
		(start 133.085586 -289.278314)
		(end 133.085586 -289.27806)
		(width 0.0889)
		(layer "In2.Cu")
		(net "P5E_CPU1_PE3_TX_DN<2>")
	)
	(segment
		(start 138.80084 -296.468038)
		(end 137.747248 -293.924482)
		(width 0.14732)
		(layer "In2.Cu")
		(net "P5E_CPU1_PE3_TX_DN<2>")
	)
	(segment
		(start 159.361124 -375.237248)
		(end 162.046158 -343.845388)
		(width 0.14732)
		(layer "In2.Cu")
		(net "P5E_CPU1_PE3_TX_DN<2>")
	)
	(segment
		(start 161.803334 -405.117554)
		(end 161.803334 -400.14525)
		(width 0.14732)
		(layer "In2.Cu")
		(net "P5E_CPU1_PE3_TX_DN<2>")
	)
	(segment
		(start 162.046158 -343.845388)
		(end 162.046158 -337.784186)
		(width 0.14732)
		(layer "In2.Cu")
		(net "P5E_CPU1_PE3_TX_DN<2>")
	)
	(segment
		(start 161.468308 -398.005808)
		(end 161.425636 -397.570706)
		(width 0.14732)
		(layer "In2.Cu")
		(net "P5E_CPU1_PE3_TX_DN<2>")
	)
	(segment
		(start 161.35858 -396.888462)
		(end 161.315908 -396.45336)
		(width 0.14732)
		(layer "In2.Cu")
		(net "P5E_CPU1_PE3_TX_DN<2>")
	)
	(segment
		(start 159.361124 -375.239026)
		(end 159.361124 -375.237248)
		(width 0.14732)
		(layer "In2.Cu")
		(net "P5E_CPU1_PE3_TX_DN<2>")
	)
	(segment
		(start 132.143246 -286.964882)
		(end 132.142992 -286.964882)
		(width 0.0889)
		(layer "In2.Cu")
		(net "P5E_CPU1_PE3_TX_DN<2>")
	)
	(segment
		(start 132.758434 -290.864798)
		(end 132.758434 -290.542472)
		(width 0.14732)
		(layer "In2.Cu")
		(net "P5E_CPU1_PE3_TX_DN<2>")
	)
	(segment
		(start 137.082784 -293.260018)
		(end 133.78942 -291.895784)
		(width 0.14732)
		(layer "In2.Cu")
		(net "P5E_CPU1_PE3_TX_DN<2>")
	)
	(segment
		(start 142.970504 -306.965604)
		(end 142.349728 -305.930808)
		(width 0.14732)
		(layer "In2.Cu")
		(net "P5E_CPU1_PE3_TX_DN<2>")
	)
	(segment
		(start 137.747248 -293.924482)
		(end 137.082784 -293.260018)
		(width 0.14732)
		(layer "In2.Cu")
		(net "P5E_CPU1_PE3_TX_DN<2>")
	)
	(segment
		(start 132.800852 -288.103056)
		(end 132.800598 -288.103056)
		(width 0.0889)
		(layer "In2.Cu")
		(net "P5E_CPU1_PE3_TX_DN<2>")
	)
	(segment
		(start 162.046158 -337.784186)
		(end 160.605978 -329.615546)
		(width 0.14732)
		(layer "In2.Cu")
		(net "P5E_CPU1_PE3_TX_DN<2>")
	)
	(segment
		(start 132.758434 -290.542472)
		(end 132.758434 -290.520374)
		(width 0.0889)
		(layer "In2.Cu")
		(net "P5E_CPU1_PE3_TX_DN<2>")
	)
	(segment
		(start 161.315908 -396.45336)
		(end 161.427668 -396.31747)
		(width 0.14732)
		(layer "In2.Cu")
		(net "P5E_CPU1_PE3_TX_DN<2>")
	)
	(segment
		(start 131.860544 -286.48533)
		(end 131.860544 -286.466788)
		(width 0.0889)
		(layer "In2.Cu")
		(net "P5E_CPU1_PE3_TX_DN<2>")
	)
	(segment
		(start 131.642612 -286.204406)
		(end 131.486148 -286.475424)
		(width 0.0889)
		(layer "In2.Cu")
		(net "P5E_CPU1_PE3_TX_DN<2>")
	)
	(segment
		(start 133.081776 -288.591498)
		(end 133.081268 -288.591244)
		(width 0.0889)
		(layer "In2.Cu")
		(net "P5E_CPU1_PE3_TX_DN<2>")
	)
	(segment
		(start 161.803334 -400.14525)
		(end 161.604706 -398.117568)
		(width 0.14732)
		(layer "In2.Cu")
		(net "P5E_CPU1_PE3_TX_DN<2>")
	)
	(segment
		(start 161.494978 -397.000222)
		(end 161.35858 -396.888462)
		(width 0.14732)
		(layer "In2.Cu")
		(net "P5E_CPU1_PE3_TX_DN<2>")
	)
	(segment
		(start 161.323274 -407.00452)
		(end 161.617914 -406.70988)
		(width 0.14732)
		(layer "In2.Cu")
		(net "P5E_CPU1_PE3_TX_DN<2>")
	)
	(segment
		(start 161.617914 -405.302974)
		(end 161.803334 -405.117554)
		(width 0.14732)
		(layer "In2.Cu")
		(net "P5E_CPU1_PE3_TX_DN<2>")
	)
	(segment
		(start 132.758434 -290.520374)
		(end 132.800598 -290.47821)
		(width 0.0889)
		(layer "In2.Cu")
		(net "P5E_CPU1_PE3_TX_DN<2>")
	)
	(segment
		(start 139.24534 -298.961302)
		(end 138.80084 -296.468038)
		(width 0.14732)
		(layer "In2.Cu")
		(net "P5E_CPU1_PE3_TX_DN<2>")
	)
	(segment
		(start 132.617718 -287.781492)
		(end 132.613146 -287.778698)
		(width 0.0889)
		(layer "In2.Cu")
		(net "P5E_CPU1_PE3_TX_DN<2>")
	)
	(segment
		(start 133.107684 -289.255962)
		(end 133.122924 -289.255962)
		(width 0.0889)
		(layer "In2.Cu")
		(net "P5E_CPU1_PE3_TX_DN<2>")
	)
	(segment
		(start 131.72059 -286.183578)
		(end 131.642612 -286.204406)
		(width 0.0889)
		(layer "In2.Cu")
		(net "P5E_CPU1_PE3_TX_DN<2>")
	)
	(segment
		(start 161.537396 -397.434816)
		(end 161.494978 -397.000222)
		(width 0.14732)
		(layer "In2.Cu")
		(net "P5E_CPU1_PE3_TX_DN<2>")
	)
	(segment
		(start 133.265672 -289.00882)
		(end 133.26999 -288.944558)
		(width 0.0889)
		(layer "In2.Cu")
		(net "P5E_CPU1_PE3_TX_DN<2>")
	)
	(segment
		(start 133.122924 -289.255962)
		(end 133.123178 -289.256216)
		(width 0.0889)
		(layer "In2.Cu")
		(net "P5E_CPU1_PE3_TX_DN<2>")
	)
	(segment
		(start 161.425636 -397.570706)
		(end 161.537396 -397.434816)
		(width 0.14732)
		(layer "In2.Cu")
		(net "P5E_CPU1_PE3_TX_DN<2>")
	)
	(segment
		(start 132.613146 -287.778698)
		(end 132.602478 -287.772856)
		(width 0.0889)
		(layer "In2.Cu")
		(net "P5E_CPU1_PE3_TX_DN<2>")
	)
	(arc
		(start 132.816092 -289.569906)
		(mid 132.925919 -289.401067)
		(end 133.085586 -289.278314)
		(width 0.0889)
		(layer "In2.Cu")
		(net "P5E_CPU1_PE3_TX_DN<2>")
	)
	(arc
		(start 132.142992 -286.964882)
		(mid 131.938657 -286.762277)
		(end 131.860544 -286.48533)
		(width 0.0889)
		(layer "In2.Cu")
		(net "P5E_CPU1_PE3_TX_DN<2>")
	)
	(arc
		(start 132.330444 -287.281366)
		(mid 132.278376 -287.098543)
		(end 132.143246 -286.964882)
		(width 0.0889)
		(layer "In2.Cu")
		(net "P5E_CPU1_PE3_TX_DN<2>")
	)
	(arc
		(start 132.800598 -288.103056)
		(mid 132.751606 -287.918148)
		(end 132.617718 -287.781492)
		(width 0.0889)
		(layer "In2.Cu")
		(net "P5E_CPU1_PE3_TX_DN<2>")
	)
	(arc
		(start 133.26999 -288.944558)
		(mid 133.226429 -288.741077)
		(end 133.081776 -288.591498)
		(width 0.0889)
		(layer "In2.Cu")
		(net "P5E_CPU1_PE3_TX_DN<2>")
	)
	(arc
		(start 133.07187 -288.585656)
		(mid 132.873229 -288.379807)
		(end 132.800852 -288.103056)
		(width 0.0889)
		(layer "In2.Cu")
		(net "P5E_CPU1_PE3_TX_DN<2>")
	)
	(arc
		(start 133.123178 -289.256216)
		(mid 133.223157 -289.149069)
		(end 133.265672 -289.00882)
		(width 0.0889)
		(layer "In2.Cu")
		(net "P5E_CPU1_PE3_TX_DN<2>")
	)
	(arc
		(start 132.800598 -289.609784)
		(mid 132.807987 -289.589706)
		(end 132.816092 -289.569906)
		(width 0.0889)
		(layer "In2.Cu")
		(net "P5E_CPU1_PE3_TX_DN<2>")
	)
	(arc
		(start 131.860544 -286.466788)
		(mid 131.82187 -286.30972)
		(end 131.72059 -286.183578)
		(width 0.0889)
		(layer "In2.Cu")
		(net "P5E_CPU1_PE3_TX_DN<2>")
	)
	(arc
		(start 132.602478 -287.772856)
		(mid 132.403047 -287.566715)
		(end 132.330444 -287.28924)
		(width 0.0889)
		(layer "In2.Cu")
		(net "P5E_CPU1_PE3_TX_DN<2>")
	)
	(segment
		(start 164.365686 -408.250644)
		(end 164.361114 -408.250644)
		(width 0.13208)
		(layer "F.Cu")
		(net "P5E_CPU1_PE3_TX_DN<1>")
	)
	(segment
		(start 132.425694 -284.311598)
		(end 132.425948 -284.847538)
		(width 0.13208)
		(layer "F.Cu")
		(net "P5E_CPU1_PE3_TX_DN<1>")
	)
	(segment
		(start 164.692076 -407.310082)
		(end 164.692076 -407.924254)
		(width 0.13208)
		(layer "F.Cu")
		(net "P5E_CPU1_PE3_TX_DN<1>")
	)
	(segment
		(start 164.692076 -407.924254)
		(end 164.365686 -408.250644)
		(width 0.13208)
		(layer "F.Cu")
		(net "P5E_CPU1_PE3_TX_DN<1>")
	)
	(segment
		(start 164.386514 -407.00452)
		(end 164.692076 -407.310082)
		(width 0.13208)
		(layer "F.Cu")
		(net "P5E_CPU1_PE3_TX_DN<1>")
	)
	(segment
		(start 164.866574 -400.144488)
		(end 161.358834 -375.705878)
		(width 0.14732)
		(layer "In2.Cu")
		(net "P5E_CPU1_PE3_TX_DN<1>")
	)
	(segment
		(start 143.784066 -306.485544)
		(end 143.242538 -305.581812)
		(width 0.14732)
		(layer "In2.Cu")
		(net "P5E_CPU1_PE3_TX_DN<1>")
	)
	(segment
		(start 133.082792 -286.964882)
		(end 133.076696 -286.961326)
		(width 0.0889)
		(layer "In2.Cu")
		(net "P5E_CPU1_PE3_TX_DN<1>")
	)
	(segment
		(start 138.505946 -293.258494)
		(end 137.399776 -292.152324)
		(width 0.14732)
		(layer "In2.Cu")
		(net "P5E_CPU1_PE3_TX_DN<1>")
	)
	(segment
		(start 164.866574 -405.117554)
		(end 164.866574 -400.144488)
		(width 0.14732)
		(layer "In2.Cu")
		(net "P5E_CPU1_PE3_TX_DN<1>")
	)
	(segment
		(start 133.54304 -287.772856)
		(end 133.540754 -287.771586)
		(width 0.0889)
		(layer "In2.Cu")
		(net "P5E_CPU1_PE3_TX_DN<1>")
	)
	(segment
		(start 139.734036 -296.22369)
		(end 138.505946 -293.258494)
		(width 0.14732)
		(layer "In2.Cu")
		(net "P5E_CPU1_PE3_TX_DN<1>")
	)
	(segment
		(start 160.034732 -325.434452)
		(end 156.742384 -323.128386)
		(width 0.14732)
		(layer "In2.Cu")
		(net "P5E_CPU1_PE3_TX_DN<1>")
	)
	(segment
		(start 135.12927 -290.59124)
		(end 135.113776 -290.575746)
		(width 0.0889)
		(layer "In2.Cu")
		(net "P5E_CPU1_PE3_TX_DN<1>")
	)
	(segment
		(start 164.681154 -406.70988)
		(end 164.681154 -405.302974)
		(width 0.14732)
		(layer "In2.Cu")
		(net "P5E_CPU1_PE3_TX_DN<1>")
	)
	(segment
		(start 162.000438 -325.780908)
		(end 160.034732 -325.434452)
		(width 0.14732)
		(layer "In2.Cu")
		(net "P5E_CPU1_PE3_TX_DN<1>")
	)
	(segment
		(start 140.161264 -298.645834)
		(end 139.734036 -296.22369)
		(width 0.14732)
		(layer "In2.Cu")
		(net "P5E_CPU1_PE3_TX_DN<1>")
	)
	(segment
		(start 162.555428 -326.447658)
		(end 162.173412 -325.901812)
		(width 0.14732)
		(layer "In2.Cu")
		(net "P5E_CPU1_PE3_TX_DN<1>")
	)
	(segment
		(start 137.399776 -292.152324)
		(end 136.188704 -291.650674)
		(width 0.14732)
		(layer "In2.Cu")
		(net "P5E_CPU1_PE3_TX_DN<1>")
	)
	(segment
		(start 134.03199 -288.597848)
		(end 134.022846 -288.592768)
		(width 0.0889)
		(layer "In2.Cu")
		(net "P5E_CPU1_PE3_TX_DN<1>")
	)
	(segment
		(start 164.681154 -405.302974)
		(end 164.866574 -405.117554)
		(width 0.14732)
		(layer "In2.Cu")
		(net "P5E_CPU1_PE3_TX_DN<1>")
	)
	(segment
		(start 163.434268 -337.895946)
		(end 163.434268 -331.43063)
		(width 0.14732)
		(layer "In2.Cu")
		(net "P5E_CPU1_PE3_TX_DN<1>")
	)
	(segment
		(start 132.621782 -286.156146)
		(end 132.612892 -286.151066)
		(width 0.0889)
		(layer "In2.Cu")
		(net "P5E_CPU1_PE3_TX_DN<1>")
	)
	(segment
		(start 135.113776 -290.575746)
		(end 135.113776 -290.515802)
		(width 0.0889)
		(layer "In2.Cu")
		(net "P5E_CPU1_PE3_TX_DN<1>")
	)
	(segment
		(start 132.582412 -285.118556)
		(end 132.425948 -284.847538)
		(width 0.0889)
		(layer "In2.Cu")
		(net "P5E_CPU1_PE3_TX_DN<1>")
	)
	(segment
		(start 163.434268 -331.43063)
		(end 162.555428 -326.447658)
		(width 0.14732)
		(layer "In2.Cu")
		(net "P5E_CPU1_PE3_TX_DN<1>")
	)
	(segment
		(start 133.552946 -287.778698)
		(end 133.54304 -287.772856)
		(width 0.0889)
		(layer "In2.Cu")
		(net "P5E_CPU1_PE3_TX_DN<1>")
	)
	(segment
		(start 143.242538 -305.581812)
		(end 140.161264 -298.645834)
		(width 0.14732)
		(layer "In2.Cu")
		(net "P5E_CPU1_PE3_TX_DN<1>")
	)
	(segment
		(start 164.386514 -407.00452)
		(end 164.681154 -406.70988)
		(width 0.14732)
		(layer "In2.Cu")
		(net "P5E_CPU1_PE3_TX_DN<1>")
	)
	(segment
		(start 133.740144 -288.11728)
		(end 133.740144 -288.09442)
		(width 0.0889)
		(layer "In2.Cu")
		(net "P5E_CPU1_PE3_TX_DN<1>")
	)
	(segment
		(start 134.679944 -290.08197)
		(end 134.679944 -289.63112)
		(width 0.0889)
		(layer "In2.Cu")
		(net "P5E_CPU1_PE3_TX_DN<1>")
	)
	(segment
		(start 162.173412 -325.901812)
		(end 162.000438 -325.780908)
		(width 0.14732)
		(layer "In2.Cu")
		(net "P5E_CPU1_PE3_TX_DN<1>")
	)
	(segment
		(start 134.210044 -289.11423)
		(end 134.210298 -288.91738)
		(width 0.0889)
		(layer "In2.Cu")
		(net "P5E_CPU1_PE3_TX_DN<1>")
	)
	(segment
		(start 156.742384 -323.128386)
		(end 143.784066 -306.485544)
		(width 0.14732)
		(layer "In2.Cu")
		(net "P5E_CPU1_PE3_TX_DN<1>")
	)
	(segment
		(start 132.330444 -285.679896)
		(end 132.330444 -285.661354)
		(width 0.0889)
		(layer "In2.Cu")
		(net "P5E_CPU1_PE3_TX_DN<1>")
	)
	(segment
		(start 133.091682 -286.969962)
		(end 133.082792 -286.964882)
		(width 0.0889)
		(layer "In2.Cu")
		(net "P5E_CPU1_PE3_TX_DN<1>")
	)
	(segment
		(start 136.188704 -291.650674)
		(end 135.12927 -290.59124)
		(width 0.14732)
		(layer "In2.Cu")
		(net "P5E_CPU1_PE3_TX_DN<1>")
	)
	(segment
		(start 161.358834 -375.705878)
		(end 163.434268 -337.895946)
		(width 0.14732)
		(layer "In2.Cu")
		(net "P5E_CPU1_PE3_TX_DN<1>")
	)
	(segment
		(start 132.558282 -285.20771)
		(end 132.582412 -285.118556)
		(width 0.0889)
		(layer "In2.Cu")
		(net "P5E_CPU1_PE3_TX_DN<1>")
	)
	(segment
		(start 135.113776 -290.515802)
		(end 134.679944 -290.08197)
		(width 0.0889)
		(layer "In2.Cu")
		(net "P5E_CPU1_PE3_TX_DN<1>")
	)
	(segment
		(start 134.679944 -289.63112)
		(end 134.495794 -289.44697)
		(width 0.0889)
		(layer "In2.Cu")
		(net "P5E_CPU1_PE3_TX_DN<1>")
	)
	(arc
		(start 132.330444 -285.661354)
		(mid 132.385799 -285.417167)
		(end 132.541264 -285.220918)
		(width 0.0889)
		(layer "In2.Cu")
		(net "P5E_CPU1_PE3_TX_DN<1>")
	)
	(arc
		(start 134.022846 -288.592768)
		(mid 133.819365 -288.391964)
		(end 133.740144 -288.11728)
		(width 0.0889)
		(layer "In2.Cu")
		(net "P5E_CPU1_PE3_TX_DN<1>")
	)
	(arc
		(start 134.210298 -288.91738)
		(mid 134.162828 -288.734346)
		(end 134.03199 -288.597848)
		(width 0.0889)
		(layer "In2.Cu")
		(net "P5E_CPU1_PE3_TX_DN<1>")
	)
	(arc
		(start 133.740144 -288.09442)
		(mid 133.687874 -287.912055)
		(end 133.552946 -287.778698)
		(width 0.0889)
		(layer "In2.Cu")
		(net "P5E_CPU1_PE3_TX_DN<1>")
	)
	(arc
		(start 132.612892 -286.151066)
		(mid 132.410606 -285.952085)
		(end 132.330444 -285.679896)
		(width 0.0889)
		(layer "In2.Cu")
		(net "P5E_CPU1_PE3_TX_DN<1>")
	)
	(arc
		(start 132.541264 -285.220918)
		(mid 132.54971 -285.214233)
		(end 132.558282 -285.20771)
		(width 0.0889)
		(layer "In2.Cu")
		(net "P5E_CPU1_PE3_TX_DN<1>")
	)
	(arc
		(start 133.076696 -286.961326)
		(mid 132.874283 -286.754913)
		(end 132.800344 -286.475424)
		(width 0.0889)
		(layer "In2.Cu")
		(net "P5E_CPU1_PE3_TX_DN<1>")
	)
	(arc
		(start 132.800344 -286.475424)
		(mid 132.752665 -286.292524)
		(end 132.621782 -286.156146)
		(width 0.0889)
		(layer "In2.Cu")
		(net "P5E_CPU1_PE3_TX_DN<1>")
	)
	(arc
		(start 133.540754 -287.771586)
		(mid 133.342526 -287.565738)
		(end 133.270244 -287.28924)
		(width 0.0889)
		(layer "In2.Cu")
		(net "P5E_CPU1_PE3_TX_DN<1>")
	)
	(arc
		(start 134.495794 -289.44697)
		(mid 134.321376 -289.307699)
		(end 134.210044 -289.11423)
		(width 0.0889)
		(layer "In2.Cu")
		(net "P5E_CPU1_PE3_TX_DN<1>")
	)
	(arc
		(start 133.270244 -287.28924)
		(mid 133.222565 -287.10634)
		(end 133.091682 -286.969962)
		(width 0.0889)
		(layer "In2.Cu")
		(net "P5E_CPU1_PE3_TX_DN<1>")
	)
	(segment
		(start 119.268494 -284.311598)
		(end 119.268748 -284.847538)
		(width 0.13208)
		(layer "F.Cu")
		(net "P5E_CPU1_PE3_TX_DN<15>")
	)
	(segment
		(start 121.480326 -408.250644)
		(end 121.475754 -408.250644)
		(width 0.13208)
		(layer "F.Cu")
		(net "P5E_CPU1_PE3_TX_DN<15>")
	)
	(segment
		(start 121.806716 -407.924254)
		(end 121.480326 -408.250644)
		(width 0.13208)
		(layer "F.Cu")
		(net "P5E_CPU1_PE3_TX_DN<15>")
	)
	(segment
		(start 121.501154 -407.00452)
		(end 121.806716 -407.310082)
		(width 0.13208)
		(layer "F.Cu")
		(net "P5E_CPU1_PE3_TX_DN<15>")
	)
	(segment
		(start 121.806716 -407.310082)
		(end 121.806716 -407.924254)
		(width 0.13208)
		(layer "F.Cu")
		(net "P5E_CPU1_PE3_TX_DN<15>")
	)
	(segment
		(start 119.268748 -284.847538)
		(end 119.425212 -285.118556)
		(width 0.0889)
		(layer "In2.Cu")
		(net "P5E_CPU1_PE3_TX_DN<15>")
	)
	(segment
		(start 120.404382 -288.422334)
		(end 120.395492 -288.427414)
		(width 0.0889)
		(layer "In2.Cu")
		(net "P5E_CPU1_PE3_TX_DN<15>")
	)
	(segment
		(start 119.601234 -291.21989)
		(end 118.577868 -292.243256)
		(width 0.14732)
		(layer "In2.Cu")
		(net "P5E_CPU1_PE3_TX_DN<15>")
	)
	(segment
		(start 118.577868 -296.648886)
		(end 118.65356 -297.079924)
		(width 0.14732)
		(layer "In2.Cu")
		(net "P5E_CPU1_PE3_TX_DN<15>")
	)
	(segment
		(start 121.795794 -406.70988)
		(end 121.501154 -407.00452)
		(width 0.14732)
		(layer "In2.Cu")
		(net "P5E_CPU1_PE3_TX_DN<15>")
	)
	(segment
		(start 120.113044 -287.280604)
		(end 120.113044 -287.299146)
		(width 0.0889)
		(layer "In2.Cu")
		(net "P5E_CPU1_PE3_TX_DN<15>")
	)
	(segment
		(start 120.228614 -300.881034)
		(end 131.586478 -312.238898)
		(width 0.14732)
		(layer "In2.Cu")
		(net "P5E_CPU1_PE3_TX_DN<15>")
	)
	(segment
		(start 120.113298 -288.895028)
		(end 120.113298 -289.077908)
		(width 0.0889)
		(layer "In2.Cu")
		(net "P5E_CPU1_PE3_TX_DN<15>")
	)
	(segment
		(start 144.113504 -372.745254)
		(end 121.981214 -399.815558)
		(width 0.14732)
		(layer "In2.Cu")
		(net "P5E_CPU1_PE3_TX_DN<15>")
	)
	(segment
		(start 137.941304 -321.315334)
		(end 145.570448 -330.209398)
		(width 0.14732)
		(layer "In2.Cu")
		(net "P5E_CPU1_PE3_TX_DN<15>")
	)
	(segment
		(start 121.981214 -399.815558)
		(end 121.981214 -405.117554)
		(width 0.14732)
		(layer "In2.Cu")
		(net "P5E_CPU1_PE3_TX_DN<15>")
	)
	(segment
		(start 119.643398 -286.475424)
		(end 119.643398 -286.48533)
		(width 0.0889)
		(layer "In2.Cu")
		(net "P5E_CPU1_PE3_TX_DN<15>")
	)
	(segment
		(start 119.643144 -290.374578)
		(end 119.601234 -290.416488)
		(width 0.0889)
		(layer "In2.Cu")
		(net "P5E_CPU1_PE3_TX_DN<15>")
	)
	(segment
		(start 121.795794 -405.302974)
		(end 121.795794 -406.70988)
		(width 0.14732)
		(layer "In2.Cu")
		(net "P5E_CPU1_PE3_TX_DN<15>")
	)
	(segment
		(start 146.75231 -367.214912)
		(end 144.113504 -372.745254)
		(width 0.14732)
		(layer "In2.Cu")
		(net "P5E_CPU1_PE3_TX_DN<15>")
	)
	(segment
		(start 118.65356 -297.079924)
		(end 120.228614 -300.881034)
		(width 0.14732)
		(layer "In2.Cu")
		(net "P5E_CPU1_PE3_TX_DN<15>")
	)
	(segment
		(start 119.601234 -290.416488)
		(end 119.601234 -290.438586)
		(width 0.0889)
		(layer "In2.Cu")
		(net "P5E_CPU1_PE3_TX_DN<15>")
	)
	(segment
		(start 120.395492 -287.778698)
		(end 120.404382 -287.783778)
		(width 0.0889)
		(layer "In2.Cu")
		(net "P5E_CPU1_PE3_TX_DN<15>")
	)
	(segment
		(start 149.869906 -340.460584)
		(end 146.75231 -367.214912)
		(width 0.14732)
		(layer "In2.Cu")
		(net "P5E_CPU1_PE3_TX_DN<15>")
	)
	(segment
		(start 119.601234 -290.438586)
		(end 119.601234 -291.21989)
		(width 0.14732)
		(layer "In2.Cu")
		(net "P5E_CPU1_PE3_TX_DN<15>")
	)
	(segment
		(start 119.643144 -289.609784)
		(end 119.643144 -290.374578)
		(width 0.0889)
		(layer "In2.Cu")
		(net "P5E_CPU1_PE3_TX_DN<15>")
	)
	(segment
		(start 119.425212 -285.118556)
		(end 119.401082 -285.20771)
		(width 0.0889)
		(layer "In2.Cu")
		(net "P5E_CPU1_PE3_TX_DN<15>")
	)
	(segment
		(start 121.981214 -405.117554)
		(end 121.795794 -405.302974)
		(width 0.14732)
		(layer "In2.Cu")
		(net "P5E_CPU1_PE3_TX_DN<15>")
	)
	(segment
		(start 119.173244 -285.661354)
		(end 119.173244 -285.675578)
		(width 0.0889)
		(layer "In2.Cu")
		(net "P5E_CPU1_PE3_TX_DN<15>")
	)
	(segment
		(start 118.577868 -292.243256)
		(end 118.577868 -296.648886)
		(width 0.14732)
		(layer "In2.Cu")
		(net "P5E_CPU1_PE3_TX_DN<15>")
	)
	(segment
		(start 131.586478 -312.238898)
		(end 137.941304 -321.315334)
		(width 0.14732)
		(layer "In2.Cu")
		(net "P5E_CPU1_PE3_TX_DN<15>")
	)
	(segment
		(start 149.869906 -340.460076)
		(end 149.869906 -340.460584)
		(width 0.14732)
		(layer "In2.Cu")
		(net "P5E_CPU1_PE3_TX_DN<15>")
	)
	(segment
		(start 145.570448 -330.209398)
		(end 148.899626 -334.964532)
		(width 0.14732)
		(layer "In2.Cu")
		(net "P5E_CPU1_PE3_TX_DN<15>")
	)
	(segment
		(start 148.899626 -334.964532)
		(end 149.869906 -340.460076)
		(width 0.14732)
		(layer "In2.Cu")
		(net "P5E_CPU1_PE3_TX_DN<15>")
	)
	(segment
		(start 119.455946 -286.151066)
		(end 119.464836 -286.156146)
		(width 0.0889)
		(layer "In2.Cu")
		(net "P5E_CPU1_PE3_TX_DN<15>")
	)
	(arc
		(start 120.395492 -288.427414)
		(mid 120.19421 -288.624901)
		(end 120.113298 -288.895028)
		(width 0.0889)
		(layer "In2.Cu")
		(net "P5E_CPU1_PE3_TX_DN<15>")
	)
	(arc
		(start 119.401082 -285.20771)
		(mid 119.23331 -285.407492)
		(end 119.173244 -285.661354)
		(width 0.0889)
		(layer "In2.Cu")
		(net "P5E_CPU1_PE3_TX_DN<15>")
	)
	(arc
		(start 120.404382 -287.783778)
		(mid 120.582979 -288.103056)
		(end 120.404382 -288.422334)
		(width 0.0889)
		(layer "In2.Cu")
		(net "P5E_CPU1_PE3_TX_DN<15>")
	)
	(arc
		(start 119.643398 -286.48533)
		(mid 119.721509 -286.762279)
		(end 119.925846 -286.964882)
		(width 0.0889)
		(layer "In2.Cu")
		(net "P5E_CPU1_PE3_TX_DN<15>")
	)
	(arc
		(start 119.925846 -286.964882)
		(mid 120.060779 -287.098236)
		(end 120.113044 -287.280604)
		(width 0.0889)
		(layer "In2.Cu")
		(net "P5E_CPU1_PE3_TX_DN<15>")
	)
	(arc
		(start 120.113298 -289.077908)
		(mid 120.038227 -289.19365)
		(end 119.928894 -289.277806)
		(width 0.0889)
		(layer "In2.Cu")
		(net "P5E_CPU1_PE3_TX_DN<15>")
	)
	(arc
		(start 119.173244 -285.675578)
		(mid 119.252463 -285.950263)
		(end 119.455946 -286.151066)
		(width 0.0889)
		(layer "In2.Cu")
		(net "P5E_CPU1_PE3_TX_DN<15>")
	)
	(arc
		(start 119.464836 -286.156146)
		(mid 119.59575 -286.292506)
		(end 119.643398 -286.475424)
		(width 0.0889)
		(layer "In2.Cu")
		(net "P5E_CPU1_PE3_TX_DN<15>")
	)
	(arc
		(start 120.113044 -287.299146)
		(mid 120.191155 -287.576095)
		(end 120.395492 -287.778698)
		(width 0.0889)
		(layer "In2.Cu")
		(net "P5E_CPU1_PE3_TX_DN<15>")
	)
	(arc
		(start 119.928894 -289.277806)
		(mid 119.754593 -289.416736)
		(end 119.643144 -289.609784)
		(width 0.0889)
		(layer "In2.Cu")
		(net "P5E_CPU1_PE3_TX_DN<15>")
	)
	(segment
		(start 124.869956 -407.924254)
		(end 124.543566 -408.250644)
		(width 0.13208)
		(layer "F.Cu")
		(net "P5E_CPU1_PE3_TX_DN<14>")
	)
	(segment
		(start 120.208294 -286.47517)
		(end 120.208548 -286.475424)
		(width 0.13208)
		(layer "F.Cu")
		(net "P5E_CPU1_PE3_TX_DN<14>")
	)
	(segment
		(start 124.869956 -407.310082)
		(end 124.869956 -407.924254)
		(width 0.13208)
		(layer "F.Cu")
		(net "P5E_CPU1_PE3_TX_DN<14>")
	)
	(segment
		(start 124.564394 -407.00452)
		(end 124.869956 -407.310082)
		(width 0.13208)
		(layer "F.Cu")
		(net "P5E_CPU1_PE3_TX_DN<14>")
	)
	(segment
		(start 120.208294 -285.939484)
		(end 120.208294 -286.47517)
		(width 0.13208)
		(layer "F.Cu")
		(net "P5E_CPU1_PE3_TX_DN<14>")
	)
	(segment
		(start 124.543566 -408.250644)
		(end 124.538994 -408.250644)
		(width 0.13208)
		(layer "F.Cu")
		(net "P5E_CPU1_PE3_TX_DN<14>")
	)
	(segment
		(start 124.859034 -406.70988)
		(end 124.564394 -407.00452)
		(width 0.14732)
		(layer "In2.Cu")
		(net "P5E_CPU1_PE3_TX_DN<14>")
	)
	(segment
		(start 121.32945 -287.775142)
		(end 121.335546 -287.778698)
		(width 0.0889)
		(layer "In2.Cu")
		(net "P5E_CPU1_PE3_TX_DN<14>")
	)
	(segment
		(start 124.859034 -405.302974)
		(end 124.859034 -406.70988)
		(width 0.14732)
		(layer "In2.Cu")
		(net "P5E_CPU1_PE3_TX_DN<14>")
	)
	(segment
		(start 132.211318 -311.487312)
		(end 138.764264 -320.845942)
		(width 0.14732)
		(layer "In2.Cu")
		(net "P5E_CPU1_PE3_TX_DN<14>")
	)
	(segment
		(start 145.144998 -373.355108)
		(end 127.668528 -396.333726)
		(width 0.14732)
		(layer "In2.Cu")
		(net "P5E_CPU1_PE3_TX_DN<14>")
	)
	(segment
		(start 146.83232 -330.251562)
		(end 149.770846 -334.44815)
		(width 0.14732)
		(layer "In2.Cu")
		(net "P5E_CPU1_PE3_TX_DN<14>")
	)
	(segment
		(start 127.668782 -396.333726)
		(end 127.669036 -396.33398)
		(width 0.14732)
		(layer "In2.Cu")
		(net "P5E_CPU1_PE3_TX_DN<14>")
	)
	(segment
		(start 138.764264 -320.845942)
		(end 146.83232 -330.251562)
		(width 0.14732)
		(layer "In2.Cu")
		(net "P5E_CPU1_PE3_TX_DN<14>")
	)
	(segment
		(start 127.053848 -397.142716)
		(end 126.858014 -397.169132)
		(width 0.14732)
		(layer "In2.Cu")
		(net "P5E_CPU1_PE3_TX_DN<14>")
	)
	(segment
		(start 121.481342 -290.438586)
		(end 121.481342 -291.35832)
		(width 0.14732)
		(layer "In2.Cu")
		(net "P5E_CPU1_PE3_TX_DN<14>")
	)
	(segment
		(start 120.365012 -286.204406)
		(end 120.44299 -286.183578)
		(width 0.0889)
		(layer "In2.Cu")
		(net "P5E_CPU1_PE3_TX_DN<14>")
	)
	(segment
		(start 121.481342 -291.35832)
		(end 120.951752 -291.88791)
		(width 0.14732)
		(layer "In2.Cu")
		(net "P5E_CPU1_PE3_TX_DN<14>")
	)
	(segment
		(start 120.951752 -291.88791)
		(end 120.951752 -297.337226)
		(width 0.14732)
		(layer "In2.Cu")
		(net "P5E_CPU1_PE3_TX_DN<14>")
	)
	(segment
		(start 127.669036 -396.33398)
		(end 127.473202 -396.36065)
		(width 0.14732)
		(layer "In2.Cu")
		(net "P5E_CPU1_PE3_TX_DN<14>")
	)
	(segment
		(start 122.995182 -302.270922)
		(end 132.211318 -311.487312)
		(width 0.14732)
		(layer "In2.Cu")
		(net "P5E_CPU1_PE3_TX_DN<14>")
	)
	(segment
		(start 120.951752 -297.337226)
		(end 122.995182 -302.270922)
		(width 0.14732)
		(layer "In2.Cu")
		(net "P5E_CPU1_PE3_TX_DN<14>")
	)
	(segment
		(start 120.582944 -286.466788)
		(end 120.582944 -286.48533)
		(width 0.0889)
		(layer "In2.Cu")
		(net "P5E_CPU1_PE3_TX_DN<14>")
	)
	(segment
		(start 127.473202 -396.36065)
		(end 127.249936 -396.65402)
		(width 0.14732)
		(layer "In2.Cu")
		(net "P5E_CPU1_PE3_TX_DN<14>")
	)
	(segment
		(start 125.044454 -399.784316)
		(end 125.044454 -405.117554)
		(width 0.14732)
		(layer "In2.Cu")
		(net "P5E_CPU1_PE3_TX_DN<14>")
	)
	(segment
		(start 121.335546 -287.778698)
		(end 121.344436 -287.783778)
		(width 0.0889)
		(layer "In2.Cu")
		(net "P5E_CPU1_PE3_TX_DN<14>")
	)
	(segment
		(start 126.634748 -397.462756)
		(end 126.661418 -397.658336)
		(width 0.14732)
		(layer "In2.Cu")
		(net "P5E_CPU1_PE3_TX_DN<14>")
	)
	(segment
		(start 126.661418 -397.658336)
		(end 125.044454 -399.784316)
		(width 0.14732)
		(layer "In2.Cu")
		(net "P5E_CPU1_PE3_TX_DN<14>")
	)
	(segment
		(start 127.276606 -396.8496)
		(end 127.053848 -397.142716)
		(width 0.14732)
		(layer "In2.Cu")
		(net "P5E_CPU1_PE3_TX_DN<14>")
	)
	(segment
		(start 121.523252 -289.750754)
		(end 121.523252 -290.374578)
		(width 0.0889)
		(layer "In2.Cu")
		(net "P5E_CPU1_PE3_TX_DN<14>")
	)
	(segment
		(start 121.992898 -288.917126)
		(end 121.992898 -289.077908)
		(width 0.0889)
		(layer "In2.Cu")
		(net "P5E_CPU1_PE3_TX_DN<14>")
	)
	(segment
		(start 150.808944 -341.164926)
		(end 147.710652 -367.755424)
		(width 0.14732)
		(layer "In2.Cu")
		(net "P5E_CPU1_PE3_TX_DN<14>")
	)
	(segment
		(start 127.668528 -396.333726)
		(end 127.668782 -396.333726)
		(width 0.14732)
		(layer "In2.Cu")
		(net "P5E_CPU1_PE3_TX_DN<14>")
	)
	(segment
		(start 121.805446 -288.592768)
		(end 121.814336 -288.597848)
		(width 0.0889)
		(layer "In2.Cu")
		(net "P5E_CPU1_PE3_TX_DN<14>")
	)
	(segment
		(start 121.523252 -290.374578)
		(end 121.481342 -290.416488)
		(width 0.0889)
		(layer "In2.Cu")
		(net "P5E_CPU1_PE3_TX_DN<14>")
	)
	(segment
		(start 150.808944 -340.330028)
		(end 150.808944 -341.164926)
		(width 0.14732)
		(layer "In2.Cu")
		(net "P5E_CPU1_PE3_TX_DN<14>")
	)
	(segment
		(start 120.208548 -286.475424)
		(end 120.365012 -286.204406)
		(width 0.0889)
		(layer "In2.Cu")
		(net "P5E_CPU1_PE3_TX_DN<14>")
	)
	(segment
		(start 121.481342 -290.416488)
		(end 121.481342 -290.438586)
		(width 0.0889)
		(layer "In2.Cu")
		(net "P5E_CPU1_PE3_TX_DN<14>")
	)
	(segment
		(start 149.770846 -334.44815)
		(end 150.808944 -340.330028)
		(width 0.14732)
		(layer "In2.Cu")
		(net "P5E_CPU1_PE3_TX_DN<14>")
	)
	(segment
		(start 147.710652 -367.755424)
		(end 145.144998 -373.355108)
		(width 0.14732)
		(layer "In2.Cu")
		(net "P5E_CPU1_PE3_TX_DN<14>")
	)
	(segment
		(start 121.522998 -288.103056)
		(end 121.522998 -288.121598)
		(width 0.0889)
		(layer "In2.Cu")
		(net "P5E_CPU1_PE3_TX_DN<14>")
	)
	(segment
		(start 127.249936 -396.65402)
		(end 127.276606 -396.8496)
		(width 0.14732)
		(layer "In2.Cu")
		(net "P5E_CPU1_PE3_TX_DN<14>")
	)
	(segment
		(start 126.858014 -397.169132)
		(end 126.634748 -397.462756)
		(width 0.14732)
		(layer "In2.Cu")
		(net "P5E_CPU1_PE3_TX_DN<14>")
	)
	(segment
		(start 125.044454 -405.117554)
		(end 124.859034 -405.302974)
		(width 0.14732)
		(layer "In2.Cu")
		(net "P5E_CPU1_PE3_TX_DN<14>")
	)
	(segment
		(start 120.865392 -286.964882)
		(end 120.874282 -286.969962)
		(width 0.0889)
		(layer "In2.Cu")
		(net "P5E_CPU1_PE3_TX_DN<14>")
	)
	(arc
		(start 121.522998 -288.121598)
		(mid 121.60316 -288.393787)
		(end 121.805446 -288.592768)
		(width 0.0889)
		(layer "In2.Cu")
		(net "P5E_CPU1_PE3_TX_DN<14>")
	)
	(arc
		(start 120.582944 -286.48533)
		(mid 120.661055 -286.762279)
		(end 120.865392 -286.964882)
		(width 0.0889)
		(layer "In2.Cu")
		(net "P5E_CPU1_PE3_TX_DN<14>")
	)
	(arc
		(start 121.992898 -289.077908)
		(mid 121.917827 -289.19365)
		(end 121.808494 -289.277806)
		(width 0.0889)
		(layer "In2.Cu")
		(net "P5E_CPU1_PE3_TX_DN<14>")
	)
	(arc
		(start 121.344436 -287.783778)
		(mid 121.47535 -287.920138)
		(end 121.522998 -288.103056)
		(width 0.0889)
		(layer "In2.Cu")
		(net "P5E_CPU1_PE3_TX_DN<14>")
	)
	(arc
		(start 121.814336 -288.597848)
		(mid 121.94525 -288.734208)
		(end 121.992898 -288.917126)
		(width 0.0889)
		(layer "In2.Cu")
		(net "P5E_CPU1_PE3_TX_DN<14>")
	)
	(arc
		(start 120.874282 -286.969962)
		(mid 121.005196 -287.106322)
		(end 121.052844 -287.28924)
		(width 0.0889)
		(layer "In2.Cu")
		(net "P5E_CPU1_PE3_TX_DN<14>")
	)
	(arc
		(start 120.44299 -286.183578)
		(mid 120.544311 -286.309699)
		(end 120.582944 -286.466788)
		(width 0.0889)
		(layer "In2.Cu")
		(net "P5E_CPU1_PE3_TX_DN<14>")
	)
	(arc
		(start 121.052844 -287.28924)
		(mid 121.126835 -287.568806)
		(end 121.32945 -287.775142)
		(width 0.0889)
		(layer "In2.Cu")
		(net "P5E_CPU1_PE3_TX_DN<14>")
	)
	(arc
		(start 121.808494 -289.277806)
		(mid 121.600162 -289.47463)
		(end 121.523252 -289.750754)
		(width 0.0889)
		(layer "In2.Cu")
		(net "P5E_CPU1_PE3_TX_DN<14>")
	)
	(segment
		(start 127.933196 -407.924254)
		(end 127.606806 -408.250644)
		(width 0.13208)
		(layer "F.Cu")
		(net "P5E_CPU1_PE3_TX_DN<13>")
	)
	(segment
		(start 121.148094 -284.311598)
		(end 121.148348 -284.847538)
		(width 0.13208)
		(layer "F.Cu")
		(net "P5E_CPU1_PE3_TX_DN<13>")
	)
	(segment
		(start 127.606806 -408.250644)
		(end 127.602234 -408.250644)
		(width 0.13208)
		(layer "F.Cu")
		(net "P5E_CPU1_PE3_TX_DN<13>")
	)
	(segment
		(start 127.933196 -407.310082)
		(end 127.933196 -407.924254)
		(width 0.13208)
		(layer "F.Cu")
		(net "P5E_CPU1_PE3_TX_DN<13>")
	)
	(segment
		(start 127.627634 -407.00452)
		(end 127.933196 -407.310082)
		(width 0.13208)
		(layer "F.Cu")
		(net "P5E_CPU1_PE3_TX_DN<13>")
	)
	(segment
		(start 122.26925 -287.775142)
		(end 122.275346 -287.778698)
		(width 0.0889)
		(layer "In2.Cu")
		(net "P5E_CPU1_PE3_TX_DN<13>")
	)
	(segment
		(start 139.958572 -320.809366)
		(end 147.913852 -330.08316)
		(width 0.14732)
		(layer "In2.Cu")
		(net "P5E_CPU1_PE3_TX_DN<13>")
	)
	(segment
		(start 147.913852 -330.08316)
		(end 150.72487 -334.097122)
		(width 0.14732)
		(layer "In2.Cu")
		(net "P5E_CPU1_PE3_TX_DN<13>")
	)
	(segment
		(start 148.54809 -368.618262)
		(end 146.215862 -373.94515)
		(width 0.14732)
		(layer "In2.Cu")
		(net "P5E_CPU1_PE3_TX_DN<13>")
	)
	(segment
		(start 127.922274 -405.302974)
		(end 127.922274 -406.70988)
		(width 0.14732)
		(layer "In2.Cu")
		(net "P5E_CPU1_PE3_TX_DN<13>")
	)
	(segment
		(start 133.100572 -311.015126)
		(end 139.958572 -320.809366)
		(width 0.14732)
		(layer "In2.Cu")
		(net "P5E_CPU1_PE3_TX_DN<13>")
	)
	(segment
		(start 150.72487 -334.097122)
		(end 151.741632 -339.86597)
		(width 0.14732)
		(layer "In2.Cu")
		(net "P5E_CPU1_PE3_TX_DN<13>")
	)
	(segment
		(start 128.107694 -399.747994)
		(end 128.107694 -405.117554)
		(width 0.14732)
		(layer "In2.Cu")
		(net "P5E_CPU1_PE3_TX_DN<13>")
	)
	(segment
		(start 122.462544 -290.374578)
		(end 122.420634 -290.416488)
		(width 0.0889)
		(layer "In2.Cu")
		(net "P5E_CPU1_PE3_TX_DN<13>")
	)
	(segment
		(start 151.741632 -341.211154)
		(end 148.54809 -368.618262)
		(width 0.14732)
		(layer "In2.Cu")
		(net "P5E_CPU1_PE3_TX_DN<13>")
	)
	(segment
		(start 121.8819 -297.152822)
		(end 123.750832 -301.665132)
		(width 0.14732)
		(layer "In2.Cu")
		(net "P5E_CPU1_PE3_TX_DN<13>")
	)
	(segment
		(start 122.462798 -288.103056)
		(end 122.462798 -288.121598)
		(width 0.0889)
		(layer "In2.Cu")
		(net "P5E_CPU1_PE3_TX_DN<13>")
	)
	(segment
		(start 151.741632 -339.86597)
		(end 151.741632 -341.211154)
		(width 0.14732)
		(layer "In2.Cu")
		(net "P5E_CPU1_PE3_TX_DN<13>")
	)
	(segment
		(start 121.052844 -285.661354)
		(end 121.052844 -285.679896)
		(width 0.0889)
		(layer "In2.Cu")
		(net "P5E_CPU1_PE3_TX_DN<13>")
	)
	(segment
		(start 128.107694 -405.117554)
		(end 127.922274 -405.302974)
		(width 0.14732)
		(layer "In2.Cu")
		(net "P5E_CPU1_PE3_TX_DN<13>")
	)
	(segment
		(start 127.922274 -406.70988)
		(end 127.627634 -407.00452)
		(width 0.14732)
		(layer "In2.Cu")
		(net "P5E_CPU1_PE3_TX_DN<13>")
	)
	(segment
		(start 123.750832 -301.665132)
		(end 133.100572 -311.015126)
		(width 0.14732)
		(layer "In2.Cu")
		(net "P5E_CPU1_PE3_TX_DN<13>")
	)
	(segment
		(start 122.462544 -289.609784)
		(end 122.462544 -290.374578)
		(width 0.0889)
		(layer "In2.Cu")
		(net "P5E_CPU1_PE3_TX_DN<13>")
	)
	(segment
		(start 122.420634 -290.416488)
		(end 122.420634 -290.438586)
		(width 0.0889)
		(layer "In2.Cu")
		(net "P5E_CPU1_PE3_TX_DN<13>")
	)
	(segment
		(start 121.8819 -292.229286)
		(end 121.8819 -297.152822)
		(width 0.14732)
		(layer "In2.Cu")
		(net "P5E_CPU1_PE3_TX_DN<13>")
	)
	(segment
		(start 121.335292 -286.151066)
		(end 121.344182 -286.156146)
		(width 0.0889)
		(layer "In2.Cu")
		(net "P5E_CPU1_PE3_TX_DN<13>")
	)
	(segment
		(start 122.932698 -288.917126)
		(end 122.932698 -289.077908)
		(width 0.0889)
		(layer "In2.Cu")
		(net "P5E_CPU1_PE3_TX_DN<13>")
	)
	(segment
		(start 122.275346 -287.778698)
		(end 122.284236 -287.783778)
		(width 0.0889)
		(layer "In2.Cu")
		(net "P5E_CPU1_PE3_TX_DN<13>")
	)
	(segment
		(start 122.420634 -291.690552)
		(end 121.8819 -292.229286)
		(width 0.14732)
		(layer "In2.Cu")
		(net "P5E_CPU1_PE3_TX_DN<13>")
	)
	(segment
		(start 121.799096 -286.961326)
		(end 121.805192 -286.964882)
		(width 0.0889)
		(layer "In2.Cu")
		(net "P5E_CPU1_PE3_TX_DN<13>")
	)
	(segment
		(start 121.805192 -286.964882)
		(end 121.814082 -286.969962)
		(width 0.0889)
		(layer "In2.Cu")
		(net "P5E_CPU1_PE3_TX_DN<13>")
	)
	(segment
		(start 121.304812 -285.118556)
		(end 121.280682 -285.20771)
		(width 0.0889)
		(layer "In2.Cu")
		(net "P5E_CPU1_PE3_TX_DN<13>")
	)
	(segment
		(start 122.420634 -290.438586)
		(end 122.420634 -291.690552)
		(width 0.14732)
		(layer "In2.Cu")
		(net "P5E_CPU1_PE3_TX_DN<13>")
	)
	(segment
		(start 121.148348 -284.847538)
		(end 121.304812 -285.118556)
		(width 0.0889)
		(layer "In2.Cu")
		(net "P5E_CPU1_PE3_TX_DN<13>")
	)
	(segment
		(start 122.745246 -288.592768)
		(end 122.754136 -288.597848)
		(width 0.0889)
		(layer "In2.Cu")
		(net "P5E_CPU1_PE3_TX_DN<13>")
	)
	(segment
		(start 146.215862 -373.94515)
		(end 128.107694 -399.747994)
		(width 0.14732)
		(layer "In2.Cu")
		(net "P5E_CPU1_PE3_TX_DN<13>")
	)
	(arc
		(start 122.462798 -288.121598)
		(mid 122.54296 -288.393787)
		(end 122.745246 -288.592768)
		(width 0.0889)
		(layer "In2.Cu")
		(net "P5E_CPU1_PE3_TX_DN<13>")
	)
	(arc
		(start 121.280682 -285.20771)
		(mid 121.27211 -285.214232)
		(end 121.263664 -285.220918)
		(width 0.0889)
		(layer "In2.Cu")
		(net "P5E_CPU1_PE3_TX_DN<13>")
	)
	(arc
		(start 121.522744 -286.475424)
		(mid 121.59666 -286.754926)
		(end 121.799096 -286.961326)
		(width 0.0889)
		(layer "In2.Cu")
		(net "P5E_CPU1_PE3_TX_DN<13>")
	)
	(arc
		(start 121.992644 -287.28924)
		(mid 122.066635 -287.568806)
		(end 122.26925 -287.775142)
		(width 0.0889)
		(layer "In2.Cu")
		(net "P5E_CPU1_PE3_TX_DN<13>")
	)
	(arc
		(start 122.748294 -289.277806)
		(mid 122.587746 -289.401124)
		(end 122.47753 -289.570922)
		(width 0.0889)
		(layer "In2.Cu")
		(net "P5E_CPU1_PE3_TX_DN<13>")
	)
	(arc
		(start 122.932698 -289.077908)
		(mid 122.857627 -289.19365)
		(end 122.748294 -289.277806)
		(width 0.0889)
		(layer "In2.Cu")
		(net "P5E_CPU1_PE3_TX_DN<13>")
	)
	(arc
		(start 121.814082 -286.969962)
		(mid 121.944996 -287.106322)
		(end 121.992644 -287.28924)
		(width 0.0889)
		(layer "In2.Cu")
		(net "P5E_CPU1_PE3_TX_DN<13>")
	)
	(arc
		(start 121.263664 -285.220918)
		(mid 121.108266 -285.417199)
		(end 121.052844 -285.661354)
		(width 0.0889)
		(layer "In2.Cu")
		(net "P5E_CPU1_PE3_TX_DN<13>")
	)
	(arc
		(start 121.052844 -285.679896)
		(mid 121.133006 -285.952085)
		(end 121.335292 -286.151066)
		(width 0.0889)
		(layer "In2.Cu")
		(net "P5E_CPU1_PE3_TX_DN<13>")
	)
	(arc
		(start 122.284236 -287.783778)
		(mid 122.41515 -287.920138)
		(end 122.462798 -288.103056)
		(width 0.0889)
		(layer "In2.Cu")
		(net "P5E_CPU1_PE3_TX_DN<13>")
	)
	(arc
		(start 122.754136 -288.597848)
		(mid 122.88505 -288.734208)
		(end 122.932698 -288.917126)
		(width 0.0889)
		(layer "In2.Cu")
		(net "P5E_CPU1_PE3_TX_DN<13>")
	)
	(arc
		(start 121.344182 -286.156146)
		(mid 121.475096 -286.292506)
		(end 121.522744 -286.475424)
		(width 0.0889)
		(layer "In2.Cu")
		(net "P5E_CPU1_PE3_TX_DN<13>")
	)
	(arc
		(start 122.47753 -289.570922)
		(mid 122.469698 -289.590222)
		(end 122.462544 -289.609784)
		(width 0.0889)
		(layer "In2.Cu")
		(net "P5E_CPU1_PE3_TX_DN<13>")
	)
	(segment
		(start 130.690874 -407.00452)
		(end 130.996436 -407.310082)
		(width 0.13208)
		(layer "F.Cu")
		(net "P5E_CPU1_PE3_TX_DN<12>")
	)
	(segment
		(start 130.670046 -408.250644)
		(end 130.665474 -408.250644)
		(width 0.13208)
		(layer "F.Cu")
		(net "P5E_CPU1_PE3_TX_DN<12>")
	)
	(segment
		(start 130.996436 -407.310082)
		(end 130.996436 -407.924254)
		(width 0.13208)
		(layer "F.Cu")
		(net "P5E_CPU1_PE3_TX_DN<12>")
	)
	(segment
		(start 122.087894 -285.939484)
		(end 122.087894 -286.47517)
		(width 0.13208)
		(layer "F.Cu")
		(net "P5E_CPU1_PE3_TX_DN<12>")
	)
	(segment
		(start 130.996436 -407.924254)
		(end 130.670046 -408.250644)
		(width 0.13208)
		(layer "F.Cu")
		(net "P5E_CPU1_PE3_TX_DN<12>")
	)
	(segment
		(start 122.087894 -286.47517)
		(end 122.088148 -286.475424)
		(width 0.13208)
		(layer "F.Cu")
		(net "P5E_CPU1_PE3_TX_DN<12>")
	)
	(segment
		(start 123.872752 -288.90214)
		(end 123.872752 -289.07867)
		(width 0.0889)
		(layer "In2.Cu")
		(net "P5E_CPU1_PE3_TX_DN<12>")
	)
	(segment
		(start 122.932698 -287.281366)
		(end 122.932698 -287.28924)
		(width 0.0889)
		(layer "In2.Cu")
		(net "P5E_CPU1_PE3_TX_DN<12>")
	)
	(segment
		(start 123.706128 -289.258756)
		(end 123.5837 -289.31997)
		(width 0.0889)
		(layer "In2.Cu")
		(net "P5E_CPU1_PE3_TX_DN<12>")
	)
	(segment
		(start 123.360942 -295.58488)
		(end 126.409196 -302.944276)
		(width 0.14732)
		(layer "In2.Cu")
		(net "P5E_CPU1_PE3_TX_DN<12>")
	)
	(segment
		(start 123.360942 -290.375848)
		(end 123.360942 -295.58488)
		(width 0.14732)
		(layer "In2.Cu")
		(net "P5E_CPU1_PE3_TX_DN<12>")
	)
	(segment
		(start 152.674574 -339.75548)
		(end 152.674574 -341.363808)
		(width 0.14732)
		(layer "In2.Cu")
		(net "P5E_CPU1_PE3_TX_DN<12>")
	)
	(segment
		(start 149.424644 -369.25885)
		(end 147.035774 -374.937528)
		(width 0.14732)
		(layer "In2.Cu")
		(net "P5E_CPU1_PE3_TX_DN<12>")
	)
	(segment
		(start 130.985514 -405.302974)
		(end 130.985514 -406.70988)
		(width 0.14732)
		(layer "In2.Cu")
		(net "P5E_CPU1_PE3_TX_DN<12>")
	)
	(segment
		(start 133.311138 -396.11554)
		(end 133.112002 -396.425674)
		(width 0.14732)
		(layer "In2.Cu")
		(net "P5E_CPU1_PE3_TX_DN<12>")
	)
	(segment
		(start 131.170934 -399.705068)
		(end 131.170934 -405.117554)
		(width 0.14732)
		(layer "In2.Cu")
		(net "P5E_CPU1_PE3_TX_DN<12>")
	)
	(segment
		(start 122.088148 -286.475424)
		(end 122.244612 -286.204406)
		(width 0.0889)
		(layer "In2.Cu")
		(net "P5E_CPU1_PE3_TX_DN<12>")
	)
	(segment
		(start 122.32259 -286.183578)
		(end 122.323098 -286.18307)
		(width 0.0889)
		(layer "In2.Cu")
		(net "P5E_CPU1_PE3_TX_DN<12>")
	)
	(segment
		(start 123.360942 -290.35375)
		(end 123.360942 -290.375848)
		(width 0.0889)
		(layer "In2.Cu")
		(net "P5E_CPU1_PE3_TX_DN<12>")
	)
	(segment
		(start 123.674886 -288.586164)
		(end 123.685554 -288.592514)
		(width 0.0889)
		(layer "In2.Cu")
		(net "P5E_CPU1_PE3_TX_DN<12>")
	)
	(segment
		(start 123.402852 -289.613086)
		(end 123.402852 -290.31184)
		(width 0.0889)
		(layer "In2.Cu")
		(net "P5E_CPU1_PE3_TX_DN<12>")
	)
	(segment
		(start 132.76199 -396.970504)
		(end 132.562854 -397.280638)
		(width 0.14732)
		(layer "In2.Cu")
		(net "P5E_CPU1_PE3_TX_DN<12>")
	)
	(segment
		(start 148.653754 -329.513438)
		(end 151.612092 -333.739236)
		(width 0.14732)
		(layer "In2.Cu")
		(net "P5E_CPU1_PE3_TX_DN<12>")
	)
	(segment
		(start 132.562854 -397.280638)
		(end 132.604764 -397.473678)
		(width 0.14732)
		(layer "In2.Cu")
		(net "P5E_CPU1_PE3_TX_DN<12>")
	)
	(segment
		(start 132.604764 -397.473678)
		(end 131.170934 -399.705068)
		(width 0.14732)
		(layer "In2.Cu")
		(net "P5E_CPU1_PE3_TX_DN<12>")
	)
	(segment
		(start 130.985514 -406.70988)
		(end 130.690874 -407.00452)
		(width 0.14732)
		(layer "In2.Cu")
		(net "P5E_CPU1_PE3_TX_DN<12>")
	)
	(segment
		(start 140.681456 -320.218816)
		(end 148.653754 -329.513438)
		(width 0.14732)
		(layer "In2.Cu")
		(net "P5E_CPU1_PE3_TX_DN<12>")
	)
	(segment
		(start 133.67004 -310.204612)
		(end 140.681456 -320.218816)
		(width 0.14732)
		(layer "In2.Cu")
		(net "P5E_CPU1_PE3_TX_DN<12>")
	)
	(segment
		(start 126.409196 -302.944276)
		(end 133.668262 -310.203342)
		(width 0.14732)
		(layer "In2.Cu")
		(net "P5E_CPU1_PE3_TX_DN<12>")
	)
	(segment
		(start 146.803872 -375.37771)
		(end 133.504432 -396.073376)
		(width 0.14732)
		(layer "In2.Cu")
		(net "P5E_CPU1_PE3_TX_DN<12>")
	)
	(segment
		(start 122.323098 -286.18307)
		(end 122.323606 -286.183324)
		(width 0.0889)
		(layer "In2.Cu")
		(net "P5E_CPU1_PE3_TX_DN<12>")
	)
	(segment
		(start 133.504432 -396.073376)
		(end 133.311138 -396.11554)
		(width 0.14732)
		(layer "In2.Cu")
		(net "P5E_CPU1_PE3_TX_DN<12>")
	)
	(segment
		(start 123.215146 -287.778444)
		(end 123.219718 -287.781238)
		(width 0.0889)
		(layer "In2.Cu")
		(net "P5E_CPU1_PE3_TX_DN<12>")
	)
	(segment
		(start 152.674574 -341.363808)
		(end 149.424644 -369.25885)
		(width 0.14732)
		(layer "In2.Cu")
		(net "P5E_CPU1_PE3_TX_DN<12>")
	)
	(segment
		(start 133.668262 -310.203342)
		(end 133.67004 -310.204612)
		(width 0.14732)
		(layer "In2.Cu")
		(net "P5E_CPU1_PE3_TX_DN<12>")
	)
	(segment
		(start 122.244612 -286.204406)
		(end 122.32259 -286.183578)
		(width 0.0889)
		(layer "In2.Cu")
		(net "P5E_CPU1_PE3_TX_DN<12>")
	)
	(segment
		(start 131.170934 -405.117554)
		(end 130.985514 -405.302974)
		(width 0.14732)
		(layer "In2.Cu")
		(net "P5E_CPU1_PE3_TX_DN<12>")
	)
	(segment
		(start 147.035774 -374.937528)
		(end 146.803872 -375.37771)
		(width 0.14732)
		(layer "In2.Cu")
		(net "P5E_CPU1_PE3_TX_DN<12>")
	)
	(segment
		(start 122.463052 -286.463994)
		(end 122.463052 -286.486092)
		(width 0.0889)
		(layer "In2.Cu")
		(net "P5E_CPU1_PE3_TX_DN<12>")
	)
	(segment
		(start 123.204732 -287.772348)
		(end 123.21413 -287.777936)
		(width 0.0889)
		(layer "In2.Cu")
		(net "P5E_CPU1_PE3_TX_DN<12>")
	)
	(segment
		(start 133.112002 -396.425674)
		(end 133.154166 -396.618714)
		(width 0.14732)
		(layer "In2.Cu")
		(net "P5E_CPU1_PE3_TX_DN<12>")
	)
	(segment
		(start 132.955284 -396.92834)
		(end 132.76199 -396.970504)
		(width 0.14732)
		(layer "In2.Cu")
		(net "P5E_CPU1_PE3_TX_DN<12>")
	)
	(segment
		(start 133.154166 -396.618714)
		(end 132.955284 -396.92834)
		(width 0.14732)
		(layer "In2.Cu")
		(net "P5E_CPU1_PE3_TX_DN<12>")
	)
	(segment
		(start 123.21413 -287.777936)
		(end 123.215146 -287.778444)
		(width 0.0889)
		(layer "In2.Cu")
		(net "P5E_CPU1_PE3_TX_DN<12>")
	)
	(segment
		(start 151.612092 -333.739236)
		(end 152.674574 -339.75548)
		(width 0.14732)
		(layer "In2.Cu")
		(net "P5E_CPU1_PE3_TX_DN<12>")
	)
	(segment
		(start 123.402852 -290.31184)
		(end 123.360942 -290.35375)
		(width 0.0889)
		(layer "In2.Cu")
		(net "P5E_CPU1_PE3_TX_DN<12>")
	)
	(arc
		(start 123.402852 -288.103056)
		(mid 123.475544 -288.380261)
		(end 123.674886 -288.586164)
		(width 0.0889)
		(layer "In2.Cu")
		(net "P5E_CPU1_PE3_TX_DN<12>")
	)
	(arc
		(start 122.745246 -286.964628)
		(mid 122.880537 -287.09841)
		(end 122.932698 -287.281366)
		(width 0.0889)
		(layer "In2.Cu")
		(net "P5E_CPU1_PE3_TX_DN<12>")
	)
	(arc
		(start 123.685554 -288.592514)
		(mid 123.818931 -288.723274)
		(end 123.872752 -288.90214)
		(width 0.0889)
		(layer "In2.Cu")
		(net "P5E_CPU1_PE3_TX_DN<12>")
	)
	(arc
		(start 122.932698 -287.28924)
		(mid 123.00539 -287.566445)
		(end 123.204732 -287.772348)
		(width 0.0889)
		(layer "In2.Cu")
		(net "P5E_CPU1_PE3_TX_DN<12>")
	)
	(arc
		(start 123.219718 -287.781238)
		(mid 123.353848 -287.917936)
		(end 123.402852 -288.103056)
		(width 0.0889)
		(layer "In2.Cu")
		(net "P5E_CPU1_PE3_TX_DN<12>")
	)
	(arc
		(start 122.323606 -286.183324)
		(mid 122.424011 -286.308405)
		(end 122.463052 -286.463994)
		(width 0.0889)
		(layer "In2.Cu")
		(net "P5E_CPU1_PE3_TX_DN<12>")
	)
	(arc
		(start 123.5837 -289.31997)
		(mid 123.451683 -289.44087)
		(end 123.402852 -289.613086)
		(width 0.0889)
		(layer "In2.Cu")
		(net "P5E_CPU1_PE3_TX_DN<12>")
	)
	(arc
		(start 122.463052 -286.486092)
		(mid 122.541207 -286.762488)
		(end 122.745246 -286.964628)
		(width 0.0889)
		(layer "In2.Cu")
		(net "P5E_CPU1_PE3_TX_DN<12>")
	)
	(arc
		(start 123.872752 -289.07867)
		(mid 123.804583 -289.182723)
		(end 123.706128 -289.258756)
		(width 0.0889)
		(layer "In2.Cu")
		(net "P5E_CPU1_PE3_TX_DN<12>")
	)
	(segment
		(start 134.059676 -407.310082)
		(end 134.059676 -407.924254)
		(width 0.13208)
		(layer "F.Cu")
		(net "P5E_CPU1_PE3_TX_DN<11>")
	)
	(segment
		(start 134.059676 -407.924254)
		(end 133.733286 -408.250644)
		(width 0.13208)
		(layer "F.Cu")
		(net "P5E_CPU1_PE3_TX_DN<11>")
	)
	(segment
		(start 123.027694 -284.311598)
		(end 123.027948 -284.847538)
		(width 0.13208)
		(layer "F.Cu")
		(net "P5E_CPU1_PE3_TX_DN<11>")
	)
	(segment
		(start 133.754114 -407.00452)
		(end 134.059676 -407.310082)
		(width 0.13208)
		(layer "F.Cu")
		(net "P5E_CPU1_PE3_TX_DN<11>")
	)
	(segment
		(start 133.733286 -408.250644)
		(end 133.728714 -408.250644)
		(width 0.13208)
		(layer "F.Cu")
		(net "P5E_CPU1_PE3_TX_DN<11>")
	)
	(segment
		(start 150.24608 -370.248688)
		(end 147.964906 -375.931938)
		(width 0.14732)
		(layer "In2.Cu")
		(net "P5E_CPU1_PE3_TX_DN<11>")
	)
	(segment
		(start 153.60777 -339.686138)
		(end 153.60777 -341.396828)
		(width 0.14732)
		(layer "In2.Cu")
		(net "P5E_CPU1_PE3_TX_DN<11>")
	)
	(segment
		(start 134.234174 -399.651728)
		(end 134.234174 -405.117554)
		(width 0.14732)
		(layer "In2.Cu")
		(net "P5E_CPU1_PE3_TX_DN<11>")
	)
	(segment
		(start 134.048754 -406.70988)
		(end 133.754114 -407.00452)
		(width 0.14732)
		(layer "In2.Cu")
		(net "P5E_CPU1_PE3_TX_DN<11>")
	)
	(segment
		(start 147.964906 -375.931938)
		(end 134.234174 -399.651728)
		(width 0.14732)
		(layer "In2.Cu")
		(net "P5E_CPU1_PE3_TX_DN<11>")
	)
	(segment
		(start 123.027948 -284.847538)
		(end 123.184412 -285.118556)
		(width 0.0889)
		(layer "In2.Cu")
		(net "P5E_CPU1_PE3_TX_DN<11>")
	)
	(segment
		(start 124.627894 -289.277806)
		(end 124.627894 -289.27806)
		(width 0.0889)
		(layer "In2.Cu")
		(net "P5E_CPU1_PE3_TX_DN<11>")
	)
	(segment
		(start 124.812298 -288.917126)
		(end 124.812298 -289.077908)
		(width 0.0889)
		(layer "In2.Cu")
		(net "P5E_CPU1_PE3_TX_DN<11>")
	)
	(segment
		(start 124.300488 -295.423082)
		(end 127.173736 -302.36033)
		(width 0.14732)
		(layer "In2.Cu")
		(net "P5E_CPU1_PE3_TX_DN<11>")
	)
	(segment
		(start 124.342398 -288.103056)
		(end 124.342398 -288.121598)
		(width 0.0889)
		(layer "In2.Cu")
		(net "P5E_CPU1_PE3_TX_DN<11>")
	)
	(segment
		(start 141.640306 -319.899792)
		(end 149.35581 -328.894948)
		(width 0.14732)
		(layer "In2.Cu")
		(net "P5E_CPU1_PE3_TX_DN<11>")
	)
	(segment
		(start 123.214892 -286.151066)
		(end 123.223782 -286.156146)
		(width 0.0889)
		(layer "In2.Cu")
		(net "P5E_CPU1_PE3_TX_DN<11>")
	)
	(segment
		(start 123.684792 -286.964882)
		(end 123.693682 -286.969962)
		(width 0.0889)
		(layer "In2.Cu")
		(net "P5E_CPU1_PE3_TX_DN<11>")
	)
	(segment
		(start 124.300488 -290.405058)
		(end 124.300488 -295.423082)
		(width 0.14732)
		(layer "In2.Cu")
		(net "P5E_CPU1_PE3_TX_DN<11>")
	)
	(segment
		(start 153.60777 -341.396828)
		(end 150.24608 -370.248688)
		(width 0.14732)
		(layer "In2.Cu")
		(net "P5E_CPU1_PE3_TX_DN<11>")
	)
	(segment
		(start 134.048754 -405.302974)
		(end 134.048754 -406.70988)
		(width 0.14732)
		(layer "In2.Cu")
		(net "P5E_CPU1_PE3_TX_DN<11>")
	)
	(segment
		(start 124.624846 -288.592768)
		(end 124.633736 -288.597848)
		(width 0.0889)
		(layer "In2.Cu")
		(net "P5E_CPU1_PE3_TX_DN<11>")
	)
	(segment
		(start 124.300234 -290.392612)
		(end 124.300488 -290.405058)
		(width 0.14732)
		(layer "In2.Cu")
		(net "P5E_CPU1_PE3_TX_DN<11>")
	)
	(segment
		(start 149.35581 -328.894948)
		(end 152.49398 -333.376778)
		(width 0.14732)
		(layer "In2.Cu")
		(net "P5E_CPU1_PE3_TX_DN<11>")
	)
	(segment
		(start 124.154184 -287.77819)
		(end 124.155708 -287.779206)
		(width 0.0889)
		(layer "In2.Cu")
		(net "P5E_CPU1_PE3_TX_DN<11>")
	)
	(segment
		(start 123.184412 -285.118556)
		(end 123.160282 -285.20771)
		(width 0.0889)
		(layer "In2.Cu")
		(net "P5E_CPU1_PE3_TX_DN<11>")
	)
	(segment
		(start 134.465822 -309.652416)
		(end 141.640306 -319.899792)
		(width 0.14732)
		(layer "In2.Cu")
		(net "P5E_CPU1_PE3_TX_DN<11>")
	)
	(segment
		(start 124.342144 -289.611054)
		(end 124.342144 -290.313618)
		(width 0.0889)
		(layer "In2.Cu")
		(net "P5E_CPU1_PE3_TX_DN<11>")
	)
	(segment
		(start 123.678696 -286.961326)
		(end 123.684792 -286.964882)
		(width 0.0889)
		(layer "In2.Cu")
		(net "P5E_CPU1_PE3_TX_DN<11>")
	)
	(segment
		(start 127.173736 -302.36033)
		(end 134.465822 -309.652416)
		(width 0.14732)
		(layer "In2.Cu")
		(net "P5E_CPU1_PE3_TX_DN<11>")
	)
	(segment
		(start 124.156724 -287.779714)
		(end 124.163836 -287.783778)
		(width 0.0889)
		(layer "In2.Cu")
		(net "P5E_CPU1_PE3_TX_DN<11>")
	)
	(segment
		(start 124.155708 -287.779206)
		(end 124.156724 -287.779714)
		(width 0.0889)
		(layer "In2.Cu")
		(net "P5E_CPU1_PE3_TX_DN<11>")
	)
	(segment
		(start 124.300234 -290.377626)
		(end 124.300234 -290.392612)
		(width 0.14732)
		(layer "In2.Cu")
		(net "P5E_CPU1_PE3_TX_DN<11>")
	)
	(segment
		(start 124.300234 -290.355528)
		(end 124.300234 -290.377626)
		(width 0.0889)
		(layer "In2.Cu")
		(net "P5E_CPU1_PE3_TX_DN<11>")
	)
	(segment
		(start 124.14885 -287.775142)
		(end 124.154184 -287.77819)
		(width 0.0889)
		(layer "In2.Cu")
		(net "P5E_CPU1_PE3_TX_DN<11>")
	)
	(segment
		(start 134.234174 -405.117554)
		(end 134.048754 -405.302974)
		(width 0.14732)
		(layer "In2.Cu")
		(net "P5E_CPU1_PE3_TX_DN<11>")
	)
	(segment
		(start 124.342144 -290.313618)
		(end 124.300234 -290.355528)
		(width 0.0889)
		(layer "In2.Cu")
		(net "P5E_CPU1_PE3_TX_DN<11>")
	)
	(segment
		(start 152.49398 -333.376778)
		(end 153.60777 -339.686138)
		(width 0.14732)
		(layer "In2.Cu")
		(net "P5E_CPU1_PE3_TX_DN<11>")
	)
	(arc
		(start 124.342398 -288.121598)
		(mid 124.42256 -288.393787)
		(end 124.624846 -288.592768)
		(width 0.0889)
		(layer "In2.Cu")
		(net "P5E_CPU1_PE3_TX_DN<11>")
	)
	(arc
		(start 123.143264 -285.220918)
		(mid 122.933994 -285.704817)
		(end 123.214892 -286.151066)
		(width 0.0889)
		(layer "In2.Cu")
		(net "P5E_CPU1_PE3_TX_DN<11>")
	)
	(arc
		(start 123.872244 -287.28924)
		(mid 123.946235 -287.568806)
		(end 124.14885 -287.775142)
		(width 0.0889)
		(layer "In2.Cu")
		(net "P5E_CPU1_PE3_TX_DN<11>")
	)
	(arc
		(start 124.627894 -289.27806)
		(mid 124.467665 -289.401465)
		(end 124.357638 -289.571176)
		(width 0.0889)
		(layer "In2.Cu")
		(net "P5E_CPU1_PE3_TX_DN<11>")
	)
	(arc
		(start 124.633736 -288.597848)
		(mid 124.76465 -288.734208)
		(end 124.812298 -288.917126)
		(width 0.0889)
		(layer "In2.Cu")
		(net "P5E_CPU1_PE3_TX_DN<11>")
	)
	(arc
		(start 123.693682 -286.969962)
		(mid 123.824596 -287.106322)
		(end 123.872244 -287.28924)
		(width 0.0889)
		(layer "In2.Cu")
		(net "P5E_CPU1_PE3_TX_DN<11>")
	)
	(arc
		(start 124.163836 -287.783778)
		(mid 124.29475 -287.920138)
		(end 124.342398 -288.103056)
		(width 0.0889)
		(layer "In2.Cu")
		(net "P5E_CPU1_PE3_TX_DN<11>")
	)
	(arc
		(start 123.160282 -285.20771)
		(mid 123.15171 -285.214232)
		(end 123.143264 -285.220918)
		(width 0.0889)
		(layer "In2.Cu")
		(net "P5E_CPU1_PE3_TX_DN<11>")
	)
	(arc
		(start 123.402344 -286.475424)
		(mid 123.47626 -286.754926)
		(end 123.678696 -286.961326)
		(width 0.0889)
		(layer "In2.Cu")
		(net "P5E_CPU1_PE3_TX_DN<11>")
	)
	(arc
		(start 124.812298 -289.077908)
		(mid 124.737227 -289.19365)
		(end 124.627894 -289.277806)
		(width 0.0889)
		(layer "In2.Cu")
		(net "P5E_CPU1_PE3_TX_DN<11>")
	)
	(arc
		(start 124.357638 -289.571176)
		(mid 124.349536 -289.590977)
		(end 124.342144 -289.611054)
		(width 0.0889)
		(layer "In2.Cu")
		(net "P5E_CPU1_PE3_TX_DN<11>")
	)
	(arc
		(start 123.223782 -286.156146)
		(mid 123.354696 -286.292506)
		(end 123.402344 -286.475424)
		(width 0.0889)
		(layer "In2.Cu")
		(net "P5E_CPU1_PE3_TX_DN<11>")
	)
	(segment
		(start 137.122916 -407.924254)
		(end 136.796526 -408.250644)
		(width 0.13208)
		(layer "F.Cu")
		(net "P5E_CPU1_PE3_TX_DN<10>")
	)
	(segment
		(start 123.967494 -285.939484)
		(end 123.967494 -286.47517)
		(width 0.13208)
		(layer "F.Cu")
		(net "P5E_CPU1_PE3_TX_DN<10>")
	)
	(segment
		(start 136.817354 -407.00452)
		(end 137.122916 -407.310082)
		(width 0.13208)
		(layer "F.Cu")
		(net "P5E_CPU1_PE3_TX_DN<10>")
	)
	(segment
		(start 136.796526 -408.250644)
		(end 136.791954 -408.250644)
		(width 0.13208)
		(layer "F.Cu")
		(net "P5E_CPU1_PE3_TX_DN<10>")
	)
	(segment
		(start 123.967494 -286.47517)
		(end 123.967748 -286.475424)
		(width 0.13208)
		(layer "F.Cu")
		(net "P5E_CPU1_PE3_TX_DN<10>")
	)
	(segment
		(start 137.122916 -407.310082)
		(end 137.122916 -407.924254)
		(width 0.13208)
		(layer "F.Cu")
		(net "P5E_CPU1_PE3_TX_DN<10>")
	)
	(segment
		(start 142.54353 -319.50914)
		(end 150.031196 -328.23785)
		(width 0.14732)
		(layer "In2.Cu")
		(net "P5E_CPU1_PE3_TX_DN<10>")
	)
	(segment
		(start 138.034268 -398.15008)
		(end 137.297414 -399.584672)
		(width 0.14732)
		(layer "In2.Cu")
		(net "P5E_CPU1_PE3_TX_DN<10>")
	)
	(segment
		(start 124.342144 -286.466788)
		(end 124.342144 -286.48533)
		(width 0.0889)
		(layer "In2.Cu")
		(net "P5E_CPU1_PE3_TX_DN<10>")
	)
	(segment
		(start 125.240034 -295.26103)
		(end 127.90805 -301.702724)
		(width 0.14732)
		(layer "In2.Cu")
		(net "P5E_CPU1_PE3_TX_DN<10>")
	)
	(segment
		(start 137.297414 -405.117554)
		(end 137.111994 -405.302974)
		(width 0.14732)
		(layer "In2.Cu")
		(net "P5E_CPU1_PE3_TX_DN<10>")
	)
	(segment
		(start 127.90805 -301.702724)
		(end 135.136636 -308.930802)
		(width 0.14732)
		(layer "In2.Cu")
		(net "P5E_CPU1_PE3_TX_DN<10>")
	)
	(segment
		(start 138.794744 -396.669768)
		(end 138.60653 -396.73022)
		(width 0.14732)
		(layer "In2.Cu")
		(net "P5E_CPU1_PE3_TX_DN<10>")
	)
	(segment
		(start 125.282198 -288.103056)
		(end 125.282198 -288.121598)
		(width 0.0889)
		(layer "In2.Cu")
		(net "P5E_CPU1_PE3_TX_DN<10>")
	)
	(segment
		(start 137.111994 -405.302974)
		(end 137.111994 -406.70988)
		(width 0.14732)
		(layer "In2.Cu")
		(net "P5E_CPU1_PE3_TX_DN<10>")
	)
	(segment
		(start 125.752098 -288.917126)
		(end 125.752098 -289.077908)
		(width 0.0889)
		(layer "In2.Cu")
		(net "P5E_CPU1_PE3_TX_DN<10>")
	)
	(segment
		(start 151.064722 -371.357398)
		(end 148.965158 -376.870214)
		(width 0.14732)
		(layer "In2.Cu")
		(net "P5E_CPU1_PE3_TX_DN<10>")
	)
	(segment
		(start 137.297414 -399.584672)
		(end 137.297414 -405.117554)
		(width 0.14732)
		(layer "In2.Cu")
		(net "P5E_CPU1_PE3_TX_DN<10>")
	)
	(segment
		(start 124.624592 -286.964882)
		(end 124.633482 -286.969962)
		(width 0.0889)
		(layer "In2.Cu")
		(net "P5E_CPU1_PE3_TX_DN<10>")
	)
	(segment
		(start 148.965158 -376.870214)
		(end 148.962618 -376.870722)
		(width 0.14732)
		(layer "In2.Cu")
		(net "P5E_CPU1_PE3_TX_DN<10>")
	)
	(segment
		(start 137.111994 -406.70988)
		(end 136.817354 -407.00452)
		(width 0.14732)
		(layer "In2.Cu")
		(net "P5E_CPU1_PE3_TX_DN<10>")
	)
	(segment
		(start 123.967748 -286.475424)
		(end 124.124212 -286.204406)
		(width 0.0889)
		(layer "In2.Cu")
		(net "P5E_CPU1_PE3_TX_DN<10>")
	)
	(segment
		(start 153.378408 -333.017876)
		(end 154.540712 -339.607906)
		(width 0.14732)
		(layer "In2.Cu")
		(net "P5E_CPU1_PE3_TX_DN<10>")
	)
	(segment
		(start 138.438128 -397.05788)
		(end 138.49858 -397.246094)
		(width 0.14732)
		(layer "In2.Cu")
		(net "P5E_CPU1_PE3_TX_DN<10>")
	)
	(segment
		(start 124.124212 -286.204406)
		(end 124.20219 -286.183578)
		(width 0.0889)
		(layer "In2.Cu")
		(net "P5E_CPU1_PE3_TX_DN<10>")
	)
	(segment
		(start 138.49858 -397.246094)
		(end 138.330432 -397.5735)
		(width 0.14732)
		(layer "In2.Cu")
		(net "P5E_CPU1_PE3_TX_DN<10>")
	)
	(segment
		(start 125.281944 -289.609784)
		(end 125.281944 -290.316158)
		(width 0.0889)
		(layer "In2.Cu")
		(net "P5E_CPU1_PE3_TX_DN<10>")
	)
	(segment
		(start 137.973816 -397.961866)
		(end 138.034268 -398.15008)
		(width 0.14732)
		(layer "In2.Cu")
		(net "P5E_CPU1_PE3_TX_DN<10>")
	)
	(segment
		(start 138.79449 -396.669768)
		(end 138.794744 -396.669768)
		(width 0.14732)
		(layer "In2.Cu")
		(net "P5E_CPU1_PE3_TX_DN<10>")
	)
	(segment
		(start 138.142218 -397.633952)
		(end 137.973816 -397.961866)
		(width 0.14732)
		(layer "In2.Cu")
		(net "P5E_CPU1_PE3_TX_DN<10>")
	)
	(segment
		(start 135.136636 -308.930802)
		(end 142.54353 -319.50914)
		(width 0.14732)
		(layer "In2.Cu")
		(net "P5E_CPU1_PE3_TX_DN<10>")
	)
	(segment
		(start 125.08865 -287.775142)
		(end 125.094746 -287.778698)
		(width 0.0889)
		(layer "In2.Cu")
		(net "P5E_CPU1_PE3_TX_DN<10>")
	)
	(segment
		(start 138.60653 -396.73022)
		(end 138.438128 -397.05788)
		(width 0.14732)
		(layer "In2.Cu")
		(net "P5E_CPU1_PE3_TX_DN<10>")
	)
	(segment
		(start 148.962618 -376.870722)
		(end 138.79449 -396.669768)
		(width 0.14732)
		(layer "In2.Cu")
		(net "P5E_CPU1_PE3_TX_DN<10>")
	)
	(segment
		(start 138.330432 -397.5735)
		(end 138.142218 -397.633952)
		(width 0.14732)
		(layer "In2.Cu")
		(net "P5E_CPU1_PE3_TX_DN<10>")
	)
	(segment
		(start 150.031196 -328.23785)
		(end 153.378408 -333.017876)
		(width 0.14732)
		(layer "In2.Cu")
		(net "P5E_CPU1_PE3_TX_DN<10>")
	)
	(segment
		(start 125.094746 -287.778698)
		(end 125.103636 -287.783778)
		(width 0.0889)
		(layer "In2.Cu")
		(net "P5E_CPU1_PE3_TX_DN<10>")
	)
	(segment
		(start 125.281944 -290.316158)
		(end 125.240034 -290.358068)
		(width 0.0889)
		(layer "In2.Cu")
		(net "P5E_CPU1_PE3_TX_DN<10>")
	)
	(segment
		(start 125.240034 -290.358068)
		(end 125.240034 -290.380166)
		(width 0.0889)
		(layer "In2.Cu")
		(net "P5E_CPU1_PE3_TX_DN<10>")
	)
	(segment
		(start 125.240034 -290.380166)
		(end 125.240034 -295.26103)
		(width 0.14732)
		(layer "In2.Cu")
		(net "P5E_CPU1_PE3_TX_DN<10>")
	)
	(segment
		(start 154.540712 -339.607906)
		(end 154.540712 -341.522812)
		(width 0.14732)
		(layer "In2.Cu")
		(net "P5E_CPU1_PE3_TX_DN<10>")
	)
	(segment
		(start 125.564646 -288.592768)
		(end 125.573536 -288.597848)
		(width 0.0889)
		(layer "In2.Cu")
		(net "P5E_CPU1_PE3_TX_DN<10>")
	)
	(segment
		(start 154.540712 -341.522812)
		(end 151.064722 -371.357398)
		(width 0.14732)
		(layer "In2.Cu")
		(net "P5E_CPU1_PE3_TX_DN<10>")
	)
	(arc
		(start 125.573536 -288.597848)
		(mid 125.70445 -288.734208)
		(end 125.752098 -288.917126)
		(width 0.0889)
		(layer "In2.Cu")
		(net "P5E_CPU1_PE3_TX_DN<10>")
	)
	(arc
		(start 124.20219 -286.183578)
		(mid 124.303511 -286.309699)
		(end 124.342144 -286.466788)
		(width 0.0889)
		(layer "In2.Cu")
		(net "P5E_CPU1_PE3_TX_DN<10>")
	)
	(arc
		(start 124.812044 -287.28924)
		(mid 124.886035 -287.568806)
		(end 125.08865 -287.775142)
		(width 0.0889)
		(layer "In2.Cu")
		(net "P5E_CPU1_PE3_TX_DN<10>")
	)
	(arc
		(start 125.103636 -287.783778)
		(mid 125.23455 -287.920138)
		(end 125.282198 -288.103056)
		(width 0.0889)
		(layer "In2.Cu")
		(net "P5E_CPU1_PE3_TX_DN<10>")
	)
	(arc
		(start 124.633482 -286.969962)
		(mid 124.764396 -287.106322)
		(end 124.812044 -287.28924)
		(width 0.0889)
		(layer "In2.Cu")
		(net "P5E_CPU1_PE3_TX_DN<10>")
	)
	(arc
		(start 125.282198 -288.121598)
		(mid 125.36236 -288.393787)
		(end 125.564646 -288.592768)
		(width 0.0889)
		(layer "In2.Cu")
		(net "P5E_CPU1_PE3_TX_DN<10>")
	)
	(arc
		(start 125.752098 -289.077908)
		(mid 125.677027 -289.19365)
		(end 125.567694 -289.277806)
		(width 0.0889)
		(layer "In2.Cu")
		(net "P5E_CPU1_PE3_TX_DN<10>")
	)
	(arc
		(start 125.567694 -289.277806)
		(mid 125.407146 -289.401124)
		(end 125.29693 -289.570922)
		(width 0.0889)
		(layer "In2.Cu")
		(net "P5E_CPU1_PE3_TX_DN<10>")
	)
	(arc
		(start 124.342144 -286.48533)
		(mid 124.420255 -286.762279)
		(end 124.624592 -286.964882)
		(width 0.0889)
		(layer "In2.Cu")
		(net "P5E_CPU1_PE3_TX_DN<10>")
	)
	(arc
		(start 125.29693 -289.570922)
		(mid 125.289098 -289.590222)
		(end 125.281944 -289.609784)
		(width 0.0889)
		(layer "In2.Cu")
		(net "P5E_CPU1_PE3_TX_DN<10>")
	)
	(segment
		(start 133.835648 -285.125414)
		(end 133.835648 -285.6611)
		(width 0.13208)
		(layer "F.Cu")
		(net "P5E_CPU1_PE3_TX_DN<0>")
	)
	(segment
		(start 168.014396 -407.926286)
		(end 168.338754 -408.250644)
		(width 0.13208)
		(layer "F.Cu")
		(net "P5E_CPU1_PE3_TX_DN<0>")
	)
	(segment
		(start 133.835648 -285.6611)
		(end 133.835394 -285.661354)
		(width 0.13208)
		(layer "F.Cu")
		(net "P5E_CPU1_PE3_TX_DN<0>")
	)
	(segment
		(start 168.014396 -407.303478)
		(end 168.014396 -407.926286)
		(width 0.13208)
		(layer "F.Cu")
		(net "P5E_CPU1_PE3_TX_DN<0>")
	)
	(segment
		(start 168.313354 -407.00452)
		(end 168.014396 -407.303478)
		(width 0.13208)
		(layer "F.Cu")
		(net "P5E_CPU1_PE3_TX_DN<0>")
	)
	(segment
		(start 140.959078 -295.871646)
		(end 139.623292 -292.646608)
		(width 0.14732)
		(layer "In2.Cu")
		(net "P5E_CPU1_PE3_TX_DN<0>")
	)
	(segment
		(start 134.594092 -287.617154)
		(end 134.587996 -287.613598)
		(width 0.0889)
		(layer "In2.Cu")
		(net "P5E_CPU1_PE3_TX_DN<0>")
	)
	(segment
		(start 136.073896 -289.77844)
		(end 135.549386 -289.25393)
		(width 0.0889)
		(layer "In2.Cu")
		(net "P5E_CPU1_PE3_TX_DN<0>")
	)
	(segment
		(start 163.675568 -325.589646)
		(end 163.17214 -324.869556)
		(width 0.14732)
		(layer "In2.Cu")
		(net "P5E_CPU1_PE3_TX_DN<0>")
	)
	(segment
		(start 134.400544 -287.28924)
		(end 134.400544 -287.273746)
		(width 0.0889)
		(layer "In2.Cu")
		(net "P5E_CPU1_PE3_TX_DN<0>")
	)
	(segment
		(start 155.379928 -319.41389)
		(end 144.813782 -305.842924)
		(width 0.14732)
		(layer "In2.Cu")
		(net "P5E_CPU1_PE3_TX_DN<0>")
	)
	(segment
		(start 135.057642 -288.426906)
		(end 135.04926 -288.422334)
		(width 0.0889)
		(layer "In2.Cu")
		(net "P5E_CPU1_PE3_TX_DN<0>")
	)
	(segment
		(start 135.549386 -289.25393)
		(end 135.503158 -289.227514)
		(width 0.0889)
		(layer "In2.Cu")
		(net "P5E_CPU1_PE3_TX_DN<0>")
	)
	(segment
		(start 134.587996 -287.613598)
		(end 134.579106 -287.608518)
		(width 0.0889)
		(layer "In2.Cu")
		(net "P5E_CPU1_PE3_TX_DN<0>")
	)
	(segment
		(start 136.148064 -289.793934)
		(end 136.13257 -289.77844)
		(width 0.0889)
		(layer "In2.Cu")
		(net "P5E_CPU1_PE3_TX_DN<0>")
	)
	(segment
		(start 168.313354 -407.00452)
		(end 168.018714 -406.70988)
		(width 0.14732)
		(layer "In2.Cu")
		(net "P5E_CPU1_PE3_TX_DN<0>")
	)
	(segment
		(start 133.70306 -286.021526)
		(end 133.67893 -285.932372)
		(width 0.0889)
		(layer "In2.Cu")
		(net "P5E_CPU1_PE3_TX_DN<0>")
	)
	(segment
		(start 138.014456 -291.037772)
		(end 136.951466 -290.597336)
		(width 0.14732)
		(layer "In2.Cu")
		(net "P5E_CPU1_PE3_TX_DN<0>")
	)
	(segment
		(start 135.341106 -288.955226)
		(end 135.34009 -288.90468)
		(width 0.0889)
		(layer "In2.Cu")
		(net "P5E_CPU1_PE3_TX_DN<0>")
	)
	(segment
		(start 139.623292 -292.646608)
		(end 138.014456 -291.037772)
		(width 0.14732)
		(layer "In2.Cu")
		(net "P5E_CPU1_PE3_TX_DN<0>")
	)
	(segment
		(start 163.170108 -324.868032)
		(end 155.379928 -319.41389)
		(width 0.14732)
		(layer "In2.Cu")
		(net "P5E_CPU1_PE3_TX_DN<0>")
	)
	(segment
		(start 136.951466 -290.597336)
		(end 136.148064 -289.793934)
		(width 0.14732)
		(layer "In2.Cu")
		(net "P5E_CPU1_PE3_TX_DN<0>")
	)
	(segment
		(start 133.67893 -285.932372)
		(end 133.835394 -285.661354)
		(width 0.0889)
		(layer "In2.Cu")
		(net "P5E_CPU1_PE3_TX_DN<0>")
	)
	(segment
		(start 168.018714 -406.70988)
		(end 168.018714 -405.416766)
		(width 0.14732)
		(layer "In2.Cu")
		(net "P5E_CPU1_PE3_TX_DN<0>")
	)
	(segment
		(start 141.417802 -298.472098)
		(end 140.959078 -295.871646)
		(width 0.14732)
		(layer "In2.Cu")
		(net "P5E_CPU1_PE3_TX_DN<0>")
	)
	(segment
		(start 164.666168 -339.444838)
		(end 164.666168 -331.206856)
		(width 0.14732)
		(layer "In2.Cu")
		(net "P5E_CPU1_PE3_TX_DN<0>")
	)
	(segment
		(start 133.930898 -286.475424)
		(end 133.930898 -286.4612)
		(width 0.0889)
		(layer "In2.Cu")
		(net "P5E_CPU1_PE3_TX_DN<0>")
	)
	(segment
		(start 164.50691 -340.348824)
		(end 164.666168 -339.444838)
		(width 0.14732)
		(layer "In2.Cu")
		(net "P5E_CPU1_PE3_TX_DN<0>")
	)
	(segment
		(start 168.018714 -405.416766)
		(end 168.204134 -405.231346)
		(width 0.14732)
		(layer "In2.Cu")
		(net "P5E_CPU1_PE3_TX_DN<0>")
	)
	(segment
		(start 144.813782 -305.842924)
		(end 144.344644 -305.059588)
		(width 0.14732)
		(layer "In2.Cu")
		(net "P5E_CPU1_PE3_TX_DN<0>")
	)
	(segment
		(start 136.13257 -289.77844)
		(end 136.073896 -289.77844)
		(width 0.0889)
		(layer "In2.Cu")
		(net "P5E_CPU1_PE3_TX_DN<0>")
	)
	(segment
		(start 164.666168 -331.206856)
		(end 163.675568 -325.589646)
		(width 0.14732)
		(layer "In2.Cu")
		(net "P5E_CPU1_PE3_TX_DN<0>")
	)
	(segment
		(start 135.057642 -288.427668)
		(end 135.057642 -288.426906)
		(width 0.0889)
		(layer "In2.Cu")
		(net "P5E_CPU1_PE3_TX_DN<0>")
	)
	(segment
		(start 144.344644 -305.059588)
		(end 141.417802 -298.472098)
		(width 0.14732)
		(layer "In2.Cu")
		(net "P5E_CPU1_PE3_TX_DN<0>")
	)
	(segment
		(start 163.17214 -324.869556)
		(end 163.170108 -324.868032)
		(width 0.14732)
		(layer "In2.Cu")
		(net "P5E_CPU1_PE3_TX_DN<0>")
	)
	(segment
		(start 168.204134 -405.231346)
		(end 168.204134 -400.48688)
		(width 0.14732)
		(layer "In2.Cu")
		(net "P5E_CPU1_PE3_TX_DN<0>")
	)
	(segment
		(start 134.11835 -286.799782)
		(end 134.10946 -286.794702)
		(width 0.0889)
		(layer "In2.Cu")
		(net "P5E_CPU1_PE3_TX_DN<0>")
	)
	(segment
		(start 168.204134 -400.48688)
		(end 163.586668 -375.538238)
		(width 0.14732)
		(layer "In2.Cu")
		(net "P5E_CPU1_PE3_TX_DN<0>")
	)
	(segment
		(start 163.586668 -375.538238)
		(end 164.50691 -340.348824)
		(width 0.14732)
		(layer "In2.Cu")
		(net "P5E_CPU1_PE3_TX_DN<0>")
	)
	(arc
		(start 133.930898 -286.4612)
		(mid 133.872553 -286.224695)
		(end 133.720078 -286.034734)
		(width 0.0889)
		(layer "In2.Cu")
		(net "P5E_CPU1_PE3_TX_DN<0>")
	)
	(arc
		(start 134.400544 -287.273746)
		(mid 134.321174 -287.000012)
		(end 134.11835 -286.799782)
		(width 0.0889)
		(layer "In2.Cu")
		(net "P5E_CPU1_PE3_TX_DN<0>")
	)
	(arc
		(start 135.503158 -289.227514)
		(mid 135.386644 -289.112482)
		(end 135.341106 -288.955226)
		(width 0.0889)
		(layer "In2.Cu")
		(net "P5E_CPU1_PE3_TX_DN<0>")
	)
	(arc
		(start 134.870698 -288.103056)
		(mid 134.796707 -287.82349)
		(end 134.594092 -287.617154)
		(width 0.0889)
		(layer "In2.Cu")
		(net "P5E_CPU1_PE3_TX_DN<0>")
	)
	(arc
		(start 135.34009 -288.90468)
		(mid 135.261425 -288.62913)
		(end 135.057642 -288.427668)
		(width 0.0889)
		(layer "In2.Cu")
		(net "P5E_CPU1_PE3_TX_DN<0>")
	)
	(arc
		(start 134.579106 -287.608518)
		(mid 134.448192 -287.472158)
		(end 134.400544 -287.28924)
		(width 0.0889)
		(layer "In2.Cu")
		(net "P5E_CPU1_PE3_TX_DN<0>")
	)
	(arc
		(start 135.04926 -288.422334)
		(mid 134.918346 -288.285974)
		(end 134.870698 -288.103056)
		(width 0.0889)
		(layer "In2.Cu")
		(net "P5E_CPU1_PE3_TX_DN<0>")
	)
	(arc
		(start 134.10946 -286.794702)
		(mid 133.978546 -286.658342)
		(end 133.930898 -286.475424)
		(width 0.0889)
		(layer "In2.Cu")
		(net "P5E_CPU1_PE3_TX_DN<0>")
	)
	(arc
		(start 133.720078 -286.034734)
		(mid 133.711632 -286.028049)
		(end 133.70306 -286.021526)
		(width 0.0889)
		(layer "In2.Cu")
		(net "P5E_CPU1_PE3_TX_DN<0>")
	)
	(segment
		(start 140.442696 -409.110942)
		(end 140.769594 -408.784044)
		(width 0.13208)
		(layer "F.Cu")
		(net "P5E_CPU1_PE3_TX_C_DP<9>")
	)
	(segment
		(start 140.744194 -410.030168)
		(end 140.442696 -409.72867)
		(width 0.13208)
		(layer "F.Cu")
		(net "P5E_CPU1_PE3_TX_C_DP<9>")
	)
	(segment
		(start 140.442696 -409.72867)
		(end 140.442696 -409.110942)
		(width 0.13208)
		(layer "F.Cu")
		(net "P5E_CPU1_PE3_TX_C_DP<9>")
	)
	(segment
		(start 137.357104 -423.42689)
		(end 137.186924 -423.528236)
		(width 0.14732)
		(layer "In6.Cu")
		(net "P5E_CPU1_PE3_TX_C_DP<9>")
	)
	(segment
		(start 137.84453 -420.93007)
		(end 137.945876 -421.099742)
		(width 0.14732)
		(layer "In6.Cu")
		(net "P5E_CPU1_PE3_TX_C_DP<9>")
	)
	(segment
		(start 137.945876 -421.099742)
		(end 137.855452 -421.456866)
		(width 0.14732)
		(layer "In6.Cu")
		(net "P5E_CPU1_PE3_TX_C_DP<9>")
	)
	(segment
		(start 137.750042 -429.97882)
		(end 137.750042 -429.689768)
		(width 0.14732)
		(layer "In6.Cu")
		(net "P5E_CPU1_PE3_TX_C_DP<9>")
	)
	(segment
		(start 137.447274 -423.069766)
		(end 137.357104 -423.42689)
		(width 0.14732)
		(layer "In6.Cu")
		(net "P5E_CPU1_PE3_TX_C_DP<9>")
	)
	(segment
		(start 140.4493 -410.325062)
		(end 140.4493 -410.63164)
		(width 0.14732)
		(layer "In6.Cu")
		(net "P5E_CPU1_PE3_TX_C_DP<9>")
	)
	(segment
		(start 137.066782 -430.00549)
		(end 137.214102 -430.15281)
		(width 0.14732)
		(layer "In6.Cu")
		(net "P5E_CPU1_PE3_TX_C_DP<9>")
	)
	(segment
		(start 137.685526 -421.558212)
		(end 137.595356 -421.915082)
		(width 0.14732)
		(layer "In6.Cu")
		(net "P5E_CPU1_PE3_TX_C_DP<9>")
	)
	(segment
		(start 137.214102 -430.15281)
		(end 137.576052 -430.15281)
		(width 0.14732)
		(layer "In6.Cu")
		(net "P5E_CPU1_PE3_TX_C_DP<9>")
	)
	(segment
		(start 140.4493 -410.63164)
		(end 137.84453 -420.93007)
		(width 0.14732)
		(layer "In6.Cu")
		(net "P5E_CPU1_PE3_TX_C_DP<9>")
	)
	(segment
		(start 137.606278 -422.441878)
		(end 137.436352 -422.543224)
		(width 0.14732)
		(layer "In6.Cu")
		(net "P5E_CPU1_PE3_TX_C_DP<9>")
	)
	(segment
		(start 137.855452 -421.456866)
		(end 137.685526 -421.558212)
		(width 0.14732)
		(layer "In6.Cu")
		(net "P5E_CPU1_PE3_TX_C_DP<9>")
	)
	(segment
		(start 137.696702 -422.084754)
		(end 137.606278 -422.441878)
		(width 0.14732)
		(layer "In6.Cu")
		(net "P5E_CPU1_PE3_TX_C_DP<9>")
	)
	(segment
		(start 137.346182 -422.900094)
		(end 137.447274 -423.069766)
		(width 0.14732)
		(layer "In6.Cu")
		(net "P5E_CPU1_PE3_TX_C_DP<9>")
	)
	(segment
		(start 140.744194 -410.030168)
		(end 140.4493 -410.325062)
		(width 0.14732)
		(layer "In6.Cu")
		(net "P5E_CPU1_PE3_TX_C_DP<9>")
	)
	(segment
		(start 137.595356 -421.915082)
		(end 137.696702 -422.084754)
		(width 0.14732)
		(layer "In6.Cu")
		(net "P5E_CPU1_PE3_TX_C_DP<9>")
	)
	(segment
		(start 137.066782 -424.003978)
		(end 137.066782 -430.00549)
		(width 0.14732)
		(layer "In6.Cu")
		(net "P5E_CPU1_PE3_TX_C_DP<9>")
	)
	(segment
		(start 137.436352 -422.543224)
		(end 137.346182 -422.900094)
		(width 0.14732)
		(layer "In6.Cu")
		(net "P5E_CPU1_PE3_TX_C_DP<9>")
	)
	(segment
		(start 137.186924 -423.528236)
		(end 137.066782 -424.003978)
		(width 0.14732)
		(layer "In6.Cu")
		(net "P5E_CPU1_PE3_TX_C_DP<9>")
	)
	(segment
		(start 137.576052 -430.15281)
		(end 137.750042 -429.97882)
		(width 0.14732)
		(layer "In6.Cu")
		(net "P5E_CPU1_PE3_TX_C_DP<9>")
	)
	(segment
		(start 143.505936 -409.110942)
		(end 143.832834 -408.784044)
		(width 0.13208)
		(layer "F.Cu")
		(net "P5E_CPU1_PE3_TX_C_DP<8>")
	)
	(segment
		(start 143.505936 -409.72867)
		(end 143.505936 -409.110942)
		(width 0.13208)
		(layer "F.Cu")
		(net "P5E_CPU1_PE3_TX_C_DP<8>")
	)
	(segment
		(start 143.807434 -410.030168)
		(end 143.505936 -409.72867)
		(width 0.13208)
		(layer "F.Cu")
		(net "P5E_CPU1_PE3_TX_C_DP<8>")
	)
	(segment
		(start 139.856464 -421.596566)
		(end 139.739624 -421.945562)
		(width 0.14732)
		(layer "In6.Cu")
		(net "P5E_CPU1_PE3_TX_C_DP<8>")
	)
	(segment
		(start 139.066778 -423.953686)
		(end 139.066778 -430.96688)
		(width 0.14732)
		(layer "In6.Cu")
		(net "P5E_CPU1_PE3_TX_C_DP<8>")
	)
	(segment
		(start 143.512794 -410.324808)
		(end 143.512794 -410.710126)
		(width 0.14732)
		(layer "In6.Cu")
		(net "P5E_CPU1_PE3_TX_C_DP<8>")
	)
	(segment
		(start 139.538456 -431.152808)
		(end 139.750038 -430.941226)
		(width 0.14732)
		(layer "In6.Cu")
		(net "P5E_CPU1_PE3_TX_C_DP<8>")
	)
	(segment
		(start 141.700504 -416.092132)
		(end 140.062458 -420.98214)
		(width 0.14732)
		(layer "In6.Cu")
		(net "P5E_CPU1_PE3_TX_C_DP<8>")
	)
	(segment
		(start 143.512794 -410.710126)
		(end 143.49857 -410.72435)
		(width 0.14732)
		(layer "In6.Cu")
		(net "P5E_CPU1_PE3_TX_C_DP<8>")
	)
	(segment
		(start 139.388088 -423.435272)
		(end 139.210796 -423.523156)
		(width 0.14732)
		(layer "In6.Cu")
		(net "P5E_CPU1_PE3_TX_C_DP<8>")
	)
	(segment
		(start 139.710668 -422.47185)
		(end 139.53363 -422.559988)
		(width 0.14732)
		(layer "In6.Cu")
		(net "P5E_CPU1_PE3_TX_C_DP<8>")
	)
	(segment
		(start 139.53363 -422.559988)
		(end 139.41679 -422.908984)
		(width 0.14732)
		(layer "In6.Cu")
		(net "P5E_CPU1_PE3_TX_C_DP<8>")
	)
	(segment
		(start 139.41679 -422.908984)
		(end 139.504928 -423.085768)
		(width 0.14732)
		(layer "In6.Cu")
		(net "P5E_CPU1_PE3_TX_C_DP<8>")
	)
	(segment
		(start 143.807434 -410.030168)
		(end 143.512794 -410.324808)
		(width 0.14732)
		(layer "In6.Cu")
		(net "P5E_CPU1_PE3_TX_C_DP<8>")
	)
	(segment
		(start 139.066778 -430.96688)
		(end 139.252706 -431.152808)
		(width 0.14732)
		(layer "In6.Cu")
		(net "P5E_CPU1_PE3_TX_C_DP<8>")
	)
	(segment
		(start 140.150596 -421.158924)
		(end 140.033502 -421.508428)
		(width 0.14732)
		(layer "In6.Cu")
		(net "P5E_CPU1_PE3_TX_C_DP<8>")
	)
	(segment
		(start 139.504928 -423.085768)
		(end 139.388088 -423.435272)
		(width 0.14732)
		(layer "In6.Cu")
		(net "P5E_CPU1_PE3_TX_C_DP<8>")
	)
	(segment
		(start 140.062458 -420.98214)
		(end 140.150596 -421.158924)
		(width 0.14732)
		(layer "In6.Cu")
		(net "P5E_CPU1_PE3_TX_C_DP<8>")
	)
	(segment
		(start 143.49857 -410.72435)
		(end 141.700504 -416.092132)
		(width 0.14732)
		(layer "In6.Cu")
		(net "P5E_CPU1_PE3_TX_C_DP<8>")
	)
	(segment
		(start 139.827762 -422.122346)
		(end 139.710668 -422.47185)
		(width 0.14732)
		(layer "In6.Cu")
		(net "P5E_CPU1_PE3_TX_C_DP<8>")
	)
	(segment
		(start 139.210796 -423.523156)
		(end 139.066778 -423.953686)
		(width 0.14732)
		(layer "In6.Cu")
		(net "P5E_CPU1_PE3_TX_C_DP<8>")
	)
	(segment
		(start 139.750038 -430.941226)
		(end 139.750038 -430.689766)
		(width 0.14732)
		(layer "In6.Cu")
		(net "P5E_CPU1_PE3_TX_C_DP<8>")
	)
	(segment
		(start 139.739624 -421.945562)
		(end 139.827762 -422.122346)
		(width 0.14732)
		(layer "In6.Cu")
		(net "P5E_CPU1_PE3_TX_C_DP<8>")
	)
	(segment
		(start 139.252706 -431.152808)
		(end 139.538456 -431.152808)
		(width 0.14732)
		(layer "In6.Cu")
		(net "P5E_CPU1_PE3_TX_C_DP<8>")
	)
	(segment
		(start 140.033502 -421.508428)
		(end 139.856464 -421.596566)
		(width 0.14732)
		(layer "In6.Cu")
		(net "P5E_CPU1_PE3_TX_C_DP<8>")
	)
	(segment
		(start 146.569176 -409.72867)
		(end 146.569176 -409.110942)
		(width 0.13208)
		(layer "F.Cu")
		(net "P5E_CPU1_PE3_TX_C_DP<7>")
	)
	(segment
		(start 146.870674 -410.030168)
		(end 146.569176 -409.72867)
		(width 0.13208)
		(layer "F.Cu")
		(net "P5E_CPU1_PE3_TX_C_DP<7>")
	)
	(segment
		(start 146.569176 -409.110942)
		(end 146.896074 -408.784044)
		(width 0.13208)
		(layer "F.Cu")
		(net "P5E_CPU1_PE3_TX_C_DP<7>")
	)
	(segment
		(start 142.97787 -421.28948)
		(end 142.860268 -421.638476)
		(width 0.14732)
		(layer "In6.Cu")
		(net "P5E_CPU1_PE3_TX_C_DP<7>")
	)
	(segment
		(start 143.27251 -420.8526)
		(end 143.154908 -421.20185)
		(width 0.14732)
		(layer "In6.Cu")
		(net "P5E_CPU1_PE3_TX_C_DP<7>")
	)
	(segment
		(start 142.066772 -423.99204)
		(end 142.066772 -430.00549)
		(width 0.14732)
		(layer "In6.Cu")
		(net "P5E_CPU1_PE3_TX_C_DP<7>")
	)
	(segment
		(start 142.505684 -423.127678)
		(end 142.328392 -423.215308)
		(width 0.14732)
		(layer "In6.Cu")
		(net "P5E_CPU1_PE3_TX_C_DP<7>")
	)
	(segment
		(start 143.47952 -420.238936)
		(end 143.302482 -420.326566)
		(width 0.14732)
		(layer "In6.Cu")
		(net "P5E_CPU1_PE3_TX_C_DP<7>")
	)
	(segment
		(start 146.870674 -410.030168)
		(end 146.58086 -410.319982)
		(width 0.14732)
		(layer "In6.Cu")
		(net "P5E_CPU1_PE3_TX_C_DP<7>")
	)
	(segment
		(start 142.653258 -422.252394)
		(end 142.535656 -422.60139)
		(width 0.14732)
		(layer "In6.Cu")
		(net "P5E_CPU1_PE3_TX_C_DP<7>")
	)
	(segment
		(start 146.58086 -410.319982)
		(end 146.58086 -410.59735)
		(width 0.14732)
		(layer "In6.Cu")
		(net "P5E_CPU1_PE3_TX_C_DP<7>")
	)
	(segment
		(start 142.214092 -430.15281)
		(end 142.53845 -430.15281)
		(width 0.14732)
		(layer "In6.Cu")
		(net "P5E_CPU1_PE3_TX_C_DP<7>")
	)
	(segment
		(start 142.830296 -422.164764)
		(end 142.653258 -422.252394)
		(width 0.14732)
		(layer "In6.Cu")
		(net "P5E_CPU1_PE3_TX_C_DP<7>")
	)
	(segment
		(start 142.53845 -430.15281)
		(end 142.750032 -429.941228)
		(width 0.14732)
		(layer "In6.Cu")
		(net "P5E_CPU1_PE3_TX_C_DP<7>")
	)
	(segment
		(start 142.947898 -421.815514)
		(end 142.830296 -422.164764)
		(width 0.14732)
		(layer "In6.Cu")
		(net "P5E_CPU1_PE3_TX_C_DP<7>")
	)
	(segment
		(start 142.535656 -422.60139)
		(end 142.623286 -422.778174)
		(width 0.14732)
		(layer "In6.Cu")
		(net "P5E_CPU1_PE3_TX_C_DP<7>")
	)
	(segment
		(start 146.58086 -410.59735)
		(end 143.509492 -419.712648)
		(width 0.14732)
		(layer "In6.Cu")
		(net "P5E_CPU1_PE3_TX_C_DP<7>")
	)
	(segment
		(start 143.154908 -421.20185)
		(end 142.97787 -421.28948)
		(width 0.14732)
		(layer "In6.Cu")
		(net "P5E_CPU1_PE3_TX_C_DP<7>")
	)
	(segment
		(start 143.597122 -419.889686)
		(end 143.47952 -420.238936)
		(width 0.14732)
		(layer "In6.Cu")
		(net "P5E_CPU1_PE3_TX_C_DP<7>")
	)
	(segment
		(start 142.328392 -423.215308)
		(end 142.066772 -423.99204)
		(width 0.14732)
		(layer "In6.Cu")
		(net "P5E_CPU1_PE3_TX_C_DP<7>")
	)
	(segment
		(start 143.302482 -420.326566)
		(end 143.18488 -420.675562)
		(width 0.14732)
		(layer "In6.Cu")
		(net "P5E_CPU1_PE3_TX_C_DP<7>")
	)
	(segment
		(start 143.18488 -420.675562)
		(end 143.27251 -420.8526)
		(width 0.14732)
		(layer "In6.Cu")
		(net "P5E_CPU1_PE3_TX_C_DP<7>")
	)
	(segment
		(start 142.066772 -430.00549)
		(end 142.214092 -430.15281)
		(width 0.14732)
		(layer "In6.Cu")
		(net "P5E_CPU1_PE3_TX_C_DP<7>")
	)
	(segment
		(start 142.623286 -422.778174)
		(end 142.505684 -423.127678)
		(width 0.14732)
		(layer "In6.Cu")
		(net "P5E_CPU1_PE3_TX_C_DP<7>")
	)
	(segment
		(start 143.509492 -419.712648)
		(end 143.597122 -419.889686)
		(width 0.14732)
		(layer "In6.Cu")
		(net "P5E_CPU1_PE3_TX_C_DP<7>")
	)
	(segment
		(start 142.860268 -421.638476)
		(end 142.947898 -421.815514)
		(width 0.14732)
		(layer "In6.Cu")
		(net "P5E_CPU1_PE3_TX_C_DP<7>")
	)
	(segment
		(start 142.750032 -429.941228)
		(end 142.750032 -429.689768)
		(width 0.14732)
		(layer "In6.Cu")
		(net "P5E_CPU1_PE3_TX_C_DP<7>")
	)
	(segment
		(start 149.632416 -409.72867)
		(end 149.632416 -409.110942)
		(width 0.13208)
		(layer "F.Cu")
		(net "P5E_CPU1_PE3_TX_C_DP<6>")
	)
	(segment
		(start 149.632416 -409.110942)
		(end 149.959314 -408.784044)
		(width 0.13208)
		(layer "F.Cu")
		(net "P5E_CPU1_PE3_TX_C_DP<6>")
	)
	(segment
		(start 149.933914 -410.030168)
		(end 149.632416 -409.72867)
		(width 0.13208)
		(layer "F.Cu")
		(net "P5E_CPU1_PE3_TX_C_DP<6>")
	)
	(segment
		(start 145.212816 -421.636952)
		(end 145.07083 -421.977312)
		(width 0.14732)
		(layer "In6.Cu")
		(net "P5E_CPU1_PE3_TX_C_DP<6>")
	)
	(segment
		(start 144.679416 -422.914826)
		(end 144.496282 -422.99001)
		(width 0.14732)
		(layer "In6.Cu")
		(net "P5E_CPU1_PE3_TX_C_DP<6>")
	)
	(segment
		(start 144.821148 -422.57472)
		(end 144.679416 -422.914826)
		(width 0.14732)
		(layer "In6.Cu")
		(net "P5E_CPU1_PE3_TX_C_DP<6>")
	)
	(segment
		(start 149.639274 -410.666692)
		(end 145.137632 -421.454326)
		(width 0.14732)
		(layer "In6.Cu")
		(net "P5E_CPU1_PE3_TX_C_DP<6>")
	)
	(segment
		(start 144.746218 -422.392094)
		(end 144.821148 -422.57472)
		(width 0.14732)
		(layer "In6.Cu")
		(net "P5E_CPU1_PE3_TX_C_DP<6>")
	)
	(segment
		(start 144.88795 -422.052242)
		(end 144.746218 -422.392094)
		(width 0.14732)
		(layer "In6.Cu")
		(net "P5E_CPU1_PE3_TX_C_DP<6>")
	)
	(segment
		(start 144.750028 -430.941226)
		(end 144.750028 -430.689766)
		(width 0.14732)
		(layer "In6.Cu")
		(net "P5E_CPU1_PE3_TX_C_DP<6>")
	)
	(segment
		(start 149.933914 -410.030168)
		(end 149.639274 -410.324808)
		(width 0.14732)
		(layer "In6.Cu")
		(net "P5E_CPU1_PE3_TX_C_DP<6>")
	)
	(segment
		(start 144.496282 -422.99001)
		(end 144.066768 -424.019726)
		(width 0.14732)
		(layer "In6.Cu")
		(net "P5E_CPU1_PE3_TX_C_DP<6>")
	)
	(segment
		(start 144.538446 -431.152808)
		(end 144.750028 -430.941226)
		(width 0.14732)
		(layer "In6.Cu")
		(net "P5E_CPU1_PE3_TX_C_DP<6>")
	)
	(segment
		(start 149.639274 -410.324808)
		(end 149.639274 -410.666692)
		(width 0.14732)
		(layer "In6.Cu")
		(net "P5E_CPU1_PE3_TX_C_DP<6>")
	)
	(segment
		(start 145.07083 -421.977312)
		(end 144.88795 -422.052242)
		(width 0.14732)
		(layer "In6.Cu")
		(net "P5E_CPU1_PE3_TX_C_DP<6>")
	)
	(segment
		(start 145.137632 -421.454326)
		(end 145.212816 -421.636952)
		(width 0.14732)
		(layer "In6.Cu")
		(net "P5E_CPU1_PE3_TX_C_DP<6>")
	)
	(segment
		(start 144.205452 -431.152808)
		(end 144.538446 -431.152808)
		(width 0.14732)
		(layer "In6.Cu")
		(net "P5E_CPU1_PE3_TX_C_DP<6>")
	)
	(segment
		(start 144.066768 -431.014124)
		(end 144.205452 -431.152808)
		(width 0.14732)
		(layer "In6.Cu")
		(net "P5E_CPU1_PE3_TX_C_DP<6>")
	)
	(segment
		(start 144.066768 -424.019726)
		(end 144.066768 -431.014124)
		(width 0.14732)
		(layer "In6.Cu")
		(net "P5E_CPU1_PE3_TX_C_DP<6>")
	)
	(segment
		(start 152.695656 -409.72867)
		(end 152.695656 -409.110942)
		(width 0.13208)
		(layer "F.Cu")
		(net "P5E_CPU1_PE3_TX_C_DP<5>")
	)
	(segment
		(start 152.997154 -410.030168)
		(end 152.695656 -409.72867)
		(width 0.13208)
		(layer "F.Cu")
		(net "P5E_CPU1_PE3_TX_C_DP<5>")
	)
	(segment
		(start 152.695656 -409.110942)
		(end 153.022554 -408.784044)
		(width 0.13208)
		(layer "F.Cu")
		(net "P5E_CPU1_PE3_TX_C_DP<5>")
	)
	(segment
		(start 147.28825 -421.780462)
		(end 147.352258 -421.967152)
		(width 0.14732)
		(layer "In6.Cu")
		(net "P5E_CPU1_PE3_TX_C_DP<5>")
	)
	(segment
		(start 148.180806 -419.95471)
		(end 148.244814 -420.1414)
		(width 0.14732)
		(layer "In6.Cu")
		(net "P5E_CPU1_PE3_TX_C_DP<5>")
	)
	(segment
		(start 146.538442 -430.15281)
		(end 146.750024 -429.941228)
		(width 0.14732)
		(layer "In6.Cu")
		(net "P5E_CPU1_PE3_TX_C_DP<5>")
	)
	(segment
		(start 152.702514 -410.70022)
		(end 148.180552 -419.954202)
		(width 0.14732)
		(layer "In6.Cu")
		(net "P5E_CPU1_PE3_TX_C_DP<5>")
	)
	(segment
		(start 148.180552 -419.954202)
		(end 148.180806 -419.95471)
		(width 0.14732)
		(layer "In6.Cu")
		(net "P5E_CPU1_PE3_TX_C_DP<5>")
	)
	(segment
		(start 146.557238 -423.275506)
		(end 146.066764 -424.279568)
		(width 0.14732)
		(layer "In6.Cu")
		(net "P5E_CPU1_PE3_TX_C_DP<5>")
	)
	(segment
		(start 147.449794 -421.449754)
		(end 147.28825 -421.780462)
		(width 0.14732)
		(layer "In6.Cu")
		(net "P5E_CPU1_PE3_TX_C_DP<5>")
	)
	(segment
		(start 147.190714 -422.298368)
		(end 147.003516 -422.36263)
		(width 0.14732)
		(layer "In6.Cu")
		(net "P5E_CPU1_PE3_TX_C_DP<5>")
	)
	(segment
		(start 152.997154 -410.030168)
		(end 152.702514 -410.324808)
		(width 0.14732)
		(layer "In6.Cu")
		(net "P5E_CPU1_PE3_TX_C_DP<5>")
	)
	(segment
		(start 148.08327 -420.472616)
		(end 147.896072 -420.536878)
		(width 0.14732)
		(layer "In6.Cu")
		(net "P5E_CPU1_PE3_TX_C_DP<5>")
	)
	(segment
		(start 147.352258 -421.967152)
		(end 147.190714 -422.298368)
		(width 0.14732)
		(layer "In6.Cu")
		(net "P5E_CPU1_PE3_TX_C_DP<5>")
	)
	(segment
		(start 147.636992 -421.385492)
		(end 147.449794 -421.449754)
		(width 0.14732)
		(layer "In6.Cu")
		(net "P5E_CPU1_PE3_TX_C_DP<5>")
	)
	(segment
		(start 147.896072 -420.536878)
		(end 147.734528 -420.867586)
		(width 0.14732)
		(layer "In6.Cu")
		(net "P5E_CPU1_PE3_TX_C_DP<5>")
	)
	(segment
		(start 146.906234 -422.880282)
		(end 146.744436 -423.211498)
		(width 0.14732)
		(layer "In6.Cu")
		(net "P5E_CPU1_PE3_TX_C_DP<5>")
	)
	(segment
		(start 146.25066 -430.15281)
		(end 146.538442 -430.15281)
		(width 0.14732)
		(layer "In6.Cu")
		(net "P5E_CPU1_PE3_TX_C_DP<5>")
	)
	(segment
		(start 146.744436 -423.211498)
		(end 146.557238 -423.275506)
		(width 0.14732)
		(layer "In6.Cu")
		(net "P5E_CPU1_PE3_TX_C_DP<5>")
	)
	(segment
		(start 147.798536 -421.054276)
		(end 147.636992 -421.385492)
		(width 0.14732)
		(layer "In6.Cu")
		(net "P5E_CPU1_PE3_TX_C_DP<5>")
	)
	(segment
		(start 147.003516 -422.36263)
		(end 146.841972 -422.693338)
		(width 0.14732)
		(layer "In6.Cu")
		(net "P5E_CPU1_PE3_TX_C_DP<5>")
	)
	(segment
		(start 147.734528 -420.867586)
		(end 147.798536 -421.054276)
		(width 0.14732)
		(layer "In6.Cu")
		(net "P5E_CPU1_PE3_TX_C_DP<5>")
	)
	(segment
		(start 152.702514 -410.324808)
		(end 152.702514 -410.70022)
		(width 0.14732)
		(layer "In6.Cu")
		(net "P5E_CPU1_PE3_TX_C_DP<5>")
	)
	(segment
		(start 146.066764 -424.279568)
		(end 146.066764 -429.968914)
		(width 0.14732)
		(layer "In6.Cu")
		(net "P5E_CPU1_PE3_TX_C_DP<5>")
	)
	(segment
		(start 146.841972 -422.693338)
		(end 146.906234 -422.880282)
		(width 0.14732)
		(layer "In6.Cu")
		(net "P5E_CPU1_PE3_TX_C_DP<5>")
	)
	(segment
		(start 146.750024 -429.941228)
		(end 146.750024 -429.689768)
		(width 0.14732)
		(layer "In6.Cu")
		(net "P5E_CPU1_PE3_TX_C_DP<5>")
	)
	(segment
		(start 146.066764 -429.968914)
		(end 146.25066 -430.15281)
		(width 0.14732)
		(layer "In6.Cu")
		(net "P5E_CPU1_PE3_TX_C_DP<5>")
	)
	(segment
		(start 148.244814 -420.1414)
		(end 148.08327 -420.472616)
		(width 0.14732)
		(layer "In6.Cu")
		(net "P5E_CPU1_PE3_TX_C_DP<5>")
	)
	(segment
		(start 155.758896 -409.72867)
		(end 155.758896 -409.110942)
		(width 0.13208)
		(layer "F.Cu")
		(net "P5E_CPU1_PE3_TX_C_DP<4>")
	)
	(segment
		(start 155.758896 -409.110942)
		(end 156.085794 -408.784044)
		(width 0.13208)
		(layer "F.Cu")
		(net "P5E_CPU1_PE3_TX_C_DP<4>")
	)
	(segment
		(start 156.060394 -410.030168)
		(end 155.758896 -409.72867)
		(width 0.13208)
		(layer "F.Cu")
		(net "P5E_CPU1_PE3_TX_C_DP<4>")
	)
	(segment
		(start 148.06676 -424.000422)
		(end 148.06676 -430.873916)
		(width 0.14732)
		(layer "In6.Cu")
		(net "P5E_CPU1_PE3_TX_C_DP<4>")
	)
	(segment
		(start 148.637244 -423.296842)
		(end 148.445982 -423.347642)
		(width 0.14732)
		(layer "In6.Cu")
		(net "P5E_CPU1_PE3_TX_C_DP<4>")
	)
	(segment
		(start 156.060394 -410.030168)
		(end 155.765754 -410.324808)
		(width 0.14732)
		(layer "In6.Cu")
		(net "P5E_CPU1_PE3_TX_C_DP<4>")
	)
	(segment
		(start 149.332442 -422.099486)
		(end 149.14753 -422.418256)
		(width 0.14732)
		(layer "In6.Cu")
		(net "P5E_CPU1_PE3_TX_C_DP<4>")
	)
	(segment
		(start 148.445982 -423.347642)
		(end 148.06676 -424.000422)
		(width 0.14732)
		(layer "In6.Cu")
		(net "P5E_CPU1_PE3_TX_C_DP<4>")
	)
	(segment
		(start 149.792436 -421.030146)
		(end 149.842982 -421.2209)
		(width 0.14732)
		(layer "In6.Cu")
		(net "P5E_CPU1_PE3_TX_C_DP<4>")
	)
	(segment
		(start 148.553678 -431.137568)
		(end 148.75002 -430.941226)
		(width 0.14732)
		(layer "In6.Cu")
		(net "P5E_CPU1_PE3_TX_C_DP<4>")
	)
	(segment
		(start 148.06676 -430.873916)
		(end 148.330412 -431.137568)
		(width 0.14732)
		(layer "In6.Cu")
		(net "P5E_CPU1_PE3_TX_C_DP<4>")
	)
	(segment
		(start 149.842982 -421.2209)
		(end 149.65807 -421.53967)
		(width 0.14732)
		(layer "In6.Cu")
		(net "P5E_CPU1_PE3_TX_C_DP<4>")
	)
	(segment
		(start 155.765754 -410.74594)
		(end 149.792436 -421.030146)
		(width 0.14732)
		(layer "In6.Cu")
		(net "P5E_CPU1_PE3_TX_C_DP<4>")
	)
	(segment
		(start 148.75002 -430.941226)
		(end 148.75002 -430.689766)
		(width 0.14732)
		(layer "In6.Cu")
		(net "P5E_CPU1_PE3_TX_C_DP<4>")
	)
	(segment
		(start 148.330412 -431.137568)
		(end 148.553678 -431.137568)
		(width 0.14732)
		(layer "In6.Cu")
		(net "P5E_CPU1_PE3_TX_C_DP<4>")
	)
	(segment
		(start 155.765754 -410.324808)
		(end 155.765754 -410.74594)
		(width 0.14732)
		(layer "In6.Cu")
		(net "P5E_CPU1_PE3_TX_C_DP<4>")
	)
	(segment
		(start 148.822156 -422.978326)
		(end 148.637244 -423.296842)
		(width 0.14732)
		(layer "In6.Cu")
		(net "P5E_CPU1_PE3_TX_C_DP<4>")
	)
	(segment
		(start 148.956268 -422.469056)
		(end 148.771356 -422.787318)
		(width 0.14732)
		(layer "In6.Cu")
		(net "P5E_CPU1_PE3_TX_C_DP<4>")
	)
	(segment
		(start 148.771356 -422.787318)
		(end 148.822156 -422.978326)
		(width 0.14732)
		(layer "In6.Cu")
		(net "P5E_CPU1_PE3_TX_C_DP<4>")
	)
	(segment
		(start 149.14753 -422.418256)
		(end 148.956268 -422.469056)
		(width 0.14732)
		(layer "In6.Cu")
		(net "P5E_CPU1_PE3_TX_C_DP<4>")
	)
	(segment
		(start 149.466808 -421.59047)
		(end 149.281896 -421.908732)
		(width 0.14732)
		(layer "In6.Cu")
		(net "P5E_CPU1_PE3_TX_C_DP<4>")
	)
	(segment
		(start 149.65807 -421.53967)
		(end 149.466808 -421.59047)
		(width 0.14732)
		(layer "In6.Cu")
		(net "P5E_CPU1_PE3_TX_C_DP<4>")
	)
	(segment
		(start 149.281896 -421.908732)
		(end 149.332442 -422.099486)
		(width 0.14732)
		(layer "In6.Cu")
		(net "P5E_CPU1_PE3_TX_C_DP<4>")
	)
	(segment
		(start 159.123634 -410.030168)
		(end 158.822136 -409.72867)
		(width 0.13208)
		(layer "F.Cu")
		(net "P5E_CPU1_PE3_TX_C_DP<3>")
	)
	(segment
		(start 158.822136 -409.72867)
		(end 158.822136 -409.110942)
		(width 0.13208)
		(layer "F.Cu")
		(net "P5E_CPU1_PE3_TX_C_DP<3>")
	)
	(segment
		(start 158.822136 -409.110942)
		(end 159.149034 -408.784044)
		(width 0.13208)
		(layer "F.Cu")
		(net "P5E_CPU1_PE3_TX_C_DP<3>")
	)
	(segment
		(start 150.802086 -422.591992)
		(end 150.83917 -422.786048)
		(width 0.14732)
		(layer "In6.Cu")
		(net "P5E_CPU1_PE3_TX_C_DP<3>")
	)
	(segment
		(start 152.151588 -420.606982)
		(end 151.944578 -420.911528)
		(width 0.14732)
		(layer "In6.Cu")
		(net "P5E_CPU1_PE3_TX_C_DP<3>")
	)
	(segment
		(start 159.123634 -410.030168)
		(end 158.828994 -410.324808)
		(width 0.14732)
		(layer "In6.Cu")
		(net "P5E_CPU1_PE3_TX_C_DP<3>")
	)
	(segment
		(start 150.43785 -423.127678)
		(end 150.066756 -423.673524)
		(width 0.14732)
		(layer "In6.Cu")
		(net "P5E_CPU1_PE3_TX_C_DP<3>")
	)
	(segment
		(start 150.63216 -423.090848)
		(end 150.43785 -423.127678)
		(width 0.14732)
		(layer "In6.Cu")
		(net "P5E_CPU1_PE3_TX_C_DP<3>")
	)
	(segment
		(start 150.214076 -430.15281)
		(end 150.538434 -430.15281)
		(width 0.14732)
		(layer "In6.Cu")
		(net "P5E_CPU1_PE3_TX_C_DP<3>")
	)
	(segment
		(start 152.515824 -420.071296)
		(end 152.552908 -420.265352)
		(width 0.14732)
		(layer "In6.Cu")
		(net "P5E_CPU1_PE3_TX_C_DP<3>")
	)
	(segment
		(start 151.774652 -421.410384)
		(end 151.580342 -421.447214)
		(width 0.14732)
		(layer "In6.Cu")
		(net "P5E_CPU1_PE3_TX_C_DP<3>")
	)
	(segment
		(start 150.83917 -422.786048)
		(end 150.63216 -423.090848)
		(width 0.14732)
		(layer "In6.Cu")
		(net "P5E_CPU1_PE3_TX_C_DP<3>")
	)
	(segment
		(start 150.538434 -430.15281)
		(end 150.750016 -429.941228)
		(width 0.14732)
		(layer "In6.Cu")
		(net "P5E_CPU1_PE3_TX_C_DP<3>")
	)
	(segment
		(start 158.828994 -410.324808)
		(end 158.828994 -410.785818)
		(width 0.14732)
		(layer "In6.Cu")
		(net "P5E_CPU1_PE3_TX_C_DP<3>")
	)
	(segment
		(start 152.552908 -420.265352)
		(end 152.345898 -420.570152)
		(width 0.14732)
		(layer "In6.Cu")
		(net "P5E_CPU1_PE3_TX_C_DP<3>")
	)
	(segment
		(start 151.981662 -421.105584)
		(end 151.774652 -421.410384)
		(width 0.14732)
		(layer "In6.Cu")
		(net "P5E_CPU1_PE3_TX_C_DP<3>")
	)
	(segment
		(start 151.410416 -421.945816)
		(end 151.203406 -422.250616)
		(width 0.14732)
		(layer "In6.Cu")
		(net "P5E_CPU1_PE3_TX_C_DP<3>")
	)
	(segment
		(start 151.944578 -420.911528)
		(end 151.981662 -421.105584)
		(width 0.14732)
		(layer "In6.Cu")
		(net "P5E_CPU1_PE3_TX_C_DP<3>")
	)
	(segment
		(start 152.345898 -420.570152)
		(end 152.151588 -420.606982)
		(width 0.14732)
		(layer "In6.Cu")
		(net "P5E_CPU1_PE3_TX_C_DP<3>")
	)
	(segment
		(start 151.203406 -422.250616)
		(end 151.009096 -422.287446)
		(width 0.14732)
		(layer "In6.Cu")
		(net "P5E_CPU1_PE3_TX_C_DP<3>")
	)
	(segment
		(start 150.066756 -423.673524)
		(end 150.066756 -430.00549)
		(width 0.14732)
		(layer "In6.Cu")
		(net "P5E_CPU1_PE3_TX_C_DP<3>")
	)
	(segment
		(start 150.066756 -430.00549)
		(end 150.214076 -430.15281)
		(width 0.14732)
		(layer "In6.Cu")
		(net "P5E_CPU1_PE3_TX_C_DP<3>")
	)
	(segment
		(start 151.009096 -422.287446)
		(end 150.802086 -422.591992)
		(width 0.14732)
		(layer "In6.Cu")
		(net "P5E_CPU1_PE3_TX_C_DP<3>")
	)
	(segment
		(start 150.750016 -429.941228)
		(end 150.750016 -429.689768)
		(width 0.14732)
		(layer "In6.Cu")
		(net "P5E_CPU1_PE3_TX_C_DP<3>")
	)
	(segment
		(start 158.828994 -410.785818)
		(end 152.515824 -420.071296)
		(width 0.14732)
		(layer "In6.Cu")
		(net "P5E_CPU1_PE3_TX_C_DP<3>")
	)
	(segment
		(start 151.373332 -421.75176)
		(end 151.410416 -421.945816)
		(width 0.14732)
		(layer "In6.Cu")
		(net "P5E_CPU1_PE3_TX_C_DP<3>")
	)
	(segment
		(start 151.580342 -421.447214)
		(end 151.373332 -421.75176)
		(width 0.14732)
		(layer "In6.Cu")
		(net "P5E_CPU1_PE3_TX_C_DP<3>")
	)
	(segment
		(start 161.885376 -409.72867)
		(end 161.885376 -409.110942)
		(width 0.13208)
		(layer "F.Cu")
		(net "P5E_CPU1_PE3_TX_C_DP<2>")
	)
	(segment
		(start 162.186874 -410.030168)
		(end 161.885376 -409.72867)
		(width 0.13208)
		(layer "F.Cu")
		(net "P5E_CPU1_PE3_TX_C_DP<2>")
	)
	(segment
		(start 161.885376 -409.110942)
		(end 162.212274 -408.784044)
		(width 0.13208)
		(layer "F.Cu")
		(net "P5E_CPU1_PE3_TX_C_DP<2>")
	)
	(segment
		(start 153.41854 -422.192704)
		(end 153.22296 -422.219374)
		(width 0.14732)
		(layer "In6.Cu")
		(net "P5E_CPU1_PE3_TX_C_DP<2>")
	)
	(segment
		(start 153.026872 -422.70807)
		(end 152.80386 -423.001694)
		(width 0.14732)
		(layer "In6.Cu")
		(net "P5E_CPU1_PE3_TX_C_DP<2>")
	)
	(segment
		(start 152.608534 -423.028364)
		(end 152.176734 -423.596816)
		(width 0.14732)
		(layer "In6.Cu")
		(net "P5E_CPU1_PE3_TX_C_DP<2>")
	)
	(segment
		(start 152.066498 -423.92346)
		(end 152.066498 -427.188122)
		(width 0.14732)
		(layer "In6.Cu")
		(net "P5E_CPU1_PE3_TX_C_DP<2>")
	)
	(segment
		(start 152.53843 -431.152808)
		(end 152.750012 -430.941226)
		(width 0.14732)
		(layer "In6.Cu")
		(net "P5E_CPU1_PE3_TX_C_DP<2>")
	)
	(segment
		(start 152.80386 -423.001694)
		(end 152.608534 -423.028364)
		(width 0.14732)
		(layer "In6.Cu")
		(net "P5E_CPU1_PE3_TX_C_DP<2>")
	)
	(segment
		(start 152.066498 -427.188122)
		(end 152.066752 -427.188376)
		(width 0.14732)
		(layer "In6.Cu")
		(net "P5E_CPU1_PE3_TX_C_DP<2>")
	)
	(segment
		(start 153.000202 -422.51249)
		(end 153.026872 -422.70807)
		(width 0.14732)
		(layer "In6.Cu")
		(net "P5E_CPU1_PE3_TX_C_DP<2>")
	)
	(segment
		(start 161.892234 -410.324808)
		(end 161.892234 -410.805884)
		(width 0.14732)
		(layer "In6.Cu")
		(net "P5E_CPU1_PE3_TX_C_DP<2>")
	)
	(segment
		(start 152.750012 -430.941226)
		(end 152.750012 -430.689766)
		(width 0.14732)
		(layer "In6.Cu")
		(net "P5E_CPU1_PE3_TX_C_DP<2>")
	)
	(segment
		(start 162.186874 -410.030168)
		(end 161.892234 -410.324808)
		(width 0.14732)
		(layer "In6.Cu")
		(net "P5E_CPU1_PE3_TX_C_DP<2>")
	)
	(segment
		(start 152.066752 -427.188376)
		(end 152.066752 -431.038508)
		(width 0.14732)
		(layer "In6.Cu")
		(net "P5E_CPU1_PE3_TX_C_DP<2>")
	)
	(segment
		(start 152.066752 -431.038508)
		(end 152.181052 -431.152808)
		(width 0.14732)
		(layer "In6.Cu")
		(net "P5E_CPU1_PE3_TX_C_DP<2>")
	)
	(segment
		(start 152.181052 -431.152808)
		(end 152.53843 -431.152808)
		(width 0.14732)
		(layer "In6.Cu")
		(net "P5E_CPU1_PE3_TX_C_DP<2>")
	)
	(segment
		(start 152.176734 -423.596816)
		(end 152.066498 -423.92346)
		(width 0.14732)
		(layer "In6.Cu")
		(net "P5E_CPU1_PE3_TX_C_DP<2>")
	)
	(segment
		(start 161.892234 -410.805884)
		(end 153.614882 -421.703246)
		(width 0.14732)
		(layer "In6.Cu")
		(net "P5E_CPU1_PE3_TX_C_DP<2>")
	)
	(segment
		(start 153.614882 -421.703246)
		(end 153.641552 -421.89908)
		(width 0.14732)
		(layer "In6.Cu")
		(net "P5E_CPU1_PE3_TX_C_DP<2>")
	)
	(segment
		(start 153.641552 -421.89908)
		(end 153.41854 -422.192704)
		(width 0.14732)
		(layer "In6.Cu")
		(net "P5E_CPU1_PE3_TX_C_DP<2>")
	)
	(segment
		(start 153.22296 -422.219374)
		(end 153.000202 -422.51249)
		(width 0.14732)
		(layer "In6.Cu")
		(net "P5E_CPU1_PE3_TX_C_DP<2>")
	)
	(segment
		(start 165.250114 -410.030168)
		(end 164.948616 -409.72867)
		(width 0.13208)
		(layer "F.Cu")
		(net "P5E_CPU1_PE3_TX_C_DP<1>")
	)
	(segment
		(start 164.948616 -409.72867)
		(end 164.948616 -409.110942)
		(width 0.13208)
		(layer "F.Cu")
		(net "P5E_CPU1_PE3_TX_C_DP<1>")
	)
	(segment
		(start 164.948616 -409.110942)
		(end 165.275514 -408.784044)
		(width 0.13208)
		(layer "F.Cu")
		(net "P5E_CPU1_PE3_TX_C_DP<1>")
	)
	(segment
		(start 164.432488 -412.073598)
		(end 164.505132 -412.25724)
		(width 0.14732)
		(layer "In6.Cu")
		(net "P5E_CPU1_PE3_TX_C_DP<1>")
	)
	(segment
		(start 164.955474 -410.324808)
		(end 164.955474 -410.865574)
		(width 0.14732)
		(layer "In6.Cu")
		(net "P5E_CPU1_PE3_TX_C_DP<1>")
	)
	(segment
		(start 155.01366 -423.248836)
		(end 155.025852 -423.44594)
		(width 0.14732)
		(layer "In6.Cu")
		(net "P5E_CPU1_PE3_TX_C_DP<1>")
	)
	(segment
		(start 154.231086 -430.169828)
		(end 154.61742 -430.169828)
		(width 0.14732)
		(layer "In6.Cu")
		(net "P5E_CPU1_PE3_TX_C_DP<1>")
	)
	(segment
		(start 164.505132 -412.25724)
		(end 164.358574 -412.595568)
		(width 0.14732)
		(layer "In6.Cu")
		(net "P5E_CPU1_PE3_TX_C_DP<1>")
	)
	(segment
		(start 154.066748 -430.00549)
		(end 154.231086 -430.169828)
		(width 0.14732)
		(layer "In6.Cu")
		(net "P5E_CPU1_PE3_TX_C_DP<1>")
	)
	(segment
		(start 155.68676 -422.487598)
		(end 155.698698 -422.684702)
		(width 0.14732)
		(layer "In6.Cu")
		(net "P5E_CPU1_PE3_TX_C_DP<1>")
	)
	(segment
		(start 154.066748 -424.544236)
		(end 154.066748 -430.00549)
		(width 0.14732)
		(layer "In6.Cu")
		(net "P5E_CPU1_PE3_TX_C_DP<1>")
	)
	(segment
		(start 155.68676 -422.48709)
		(end 155.68676 -422.487598)
		(width 0.14732)
		(layer "In6.Cu")
		(net "P5E_CPU1_PE3_TX_C_DP<1>")
	)
	(segment
		(start 163.990528 -413.093662)
		(end 155.68676 -422.48709)
		(width 0.14732)
		(layer "In6.Cu")
		(net "P5E_CPU1_PE3_TX_C_DP<1>")
	)
	(segment
		(start 155.025852 -423.44594)
		(end 154.781758 -423.722038)
		(width 0.14732)
		(layer "In6.Cu")
		(net "P5E_CPU1_PE3_TX_C_DP<1>")
	)
	(segment
		(start 154.781758 -423.722038)
		(end 154.584654 -423.73423)
		(width 0.14732)
		(layer "In6.Cu")
		(net "P5E_CPU1_PE3_TX_C_DP<1>")
	)
	(segment
		(start 154.215338 -424.15206)
		(end 154.066748 -424.544236)
		(width 0.14732)
		(layer "In6.Cu")
		(net "P5E_CPU1_PE3_TX_C_DP<1>")
	)
	(segment
		(start 164.358574 -412.595568)
		(end 164.174678 -412.668212)
		(width 0.14732)
		(layer "In6.Cu")
		(net "P5E_CPU1_PE3_TX_C_DP<1>")
	)
	(segment
		(start 154.584654 -423.73423)
		(end 154.215338 -424.15206)
		(width 0.14732)
		(layer "In6.Cu")
		(net "P5E_CPU1_PE3_TX_C_DP<1>")
	)
	(segment
		(start 155.454604 -422.9608)
		(end 155.2575 -422.972992)
		(width 0.14732)
		(layer "In6.Cu")
		(net "P5E_CPU1_PE3_TX_C_DP<1>")
	)
	(segment
		(start 165.250114 -410.030168)
		(end 164.955474 -410.324808)
		(width 0.14732)
		(layer "In6.Cu")
		(net "P5E_CPU1_PE3_TX_C_DP<1>")
	)
	(segment
		(start 164.174678 -412.668212)
		(end 163.990528 -413.093662)
		(width 0.14732)
		(layer "In6.Cu")
		(net "P5E_CPU1_PE3_TX_C_DP<1>")
	)
	(segment
		(start 155.698698 -422.684702)
		(end 155.454604 -422.9608)
		(width 0.14732)
		(layer "In6.Cu")
		(net "P5E_CPU1_PE3_TX_C_DP<1>")
	)
	(segment
		(start 154.750008 -430.03724)
		(end 154.750008 -429.689768)
		(width 0.14732)
		(layer "In6.Cu")
		(net "P5E_CPU1_PE3_TX_C_DP<1>")
	)
	(segment
		(start 155.2575 -422.972992)
		(end 155.01366 -423.248836)
		(width 0.14732)
		(layer "In6.Cu")
		(net "P5E_CPU1_PE3_TX_C_DP<1>")
	)
	(segment
		(start 164.955474 -410.865574)
		(end 164.432488 -412.073598)
		(width 0.14732)
		(layer "In6.Cu")
		(net "P5E_CPU1_PE3_TX_C_DP<1>")
	)
	(segment
		(start 154.61742 -430.169828)
		(end 154.750008 -430.03724)
		(width 0.14732)
		(layer "In6.Cu")
		(net "P5E_CPU1_PE3_TX_C_DP<1>")
	)
	(segment
		(start 122.063256 -409.110942)
		(end 122.390154 -408.784044)
		(width 0.13208)
		(layer "F.Cu")
		(net "P5E_CPU1_PE3_TX_C_DP<15>")
	)
	(segment
		(start 122.063256 -409.72867)
		(end 122.063256 -409.110942)
		(width 0.13208)
		(layer "F.Cu")
		(net "P5E_CPU1_PE3_TX_C_DP<15>")
	)
	(segment
		(start 122.364754 -410.030168)
		(end 122.063256 -409.72867)
		(width 0.13208)
		(layer "F.Cu")
		(net "P5E_CPU1_PE3_TX_C_DP<15>")
	)
	(segment
		(start 122.243596 -413.187134)
		(end 122.306334 -413.549846)
		(width 0.14732)
		(layer "In6.Cu")
		(net "P5E_CPU1_PE3_TX_C_DP<15>")
	)
	(segment
		(start 122.070114 -410.324808)
		(end 122.070114 -412.185866)
		(width 0.14732)
		(layer "In6.Cu")
		(net "P5E_CPU1_PE3_TX_C_DP<15>")
	)
	(segment
		(start 125.365002 -430.15281)
		(end 125.538484 -430.15281)
		(width 0.14732)
		(layer "In6.Cu")
		(net "P5E_CPU1_PE3_TX_C_DP<15>")
	)
	(segment
		(start 122.364754 -410.030168)
		(end 122.070114 -410.324808)
		(width 0.14732)
		(layer "In6.Cu")
		(net "P5E_CPU1_PE3_TX_C_DP<15>")
	)
	(segment
		(start 122.306334 -413.549846)
		(end 122.467878 -413.663638)
		(width 0.14732)
		(layer "In6.Cu")
		(net "P5E_CPU1_PE3_TX_C_DP<15>")
	)
	(segment
		(start 122.132852 -412.548578)
		(end 122.294396 -412.66237)
		(width 0.14732)
		(layer "In6.Cu")
		(net "P5E_CPU1_PE3_TX_C_DP<15>")
	)
	(segment
		(start 122.294396 -412.66237)
		(end 122.357388 -413.02559)
		(width 0.14732)
		(layer "In6.Cu")
		(net "P5E_CPU1_PE3_TX_C_DP<15>")
	)
	(segment
		(start 122.704352 -415.028126)
		(end 122.590306 -415.18967)
		(width 0.14732)
		(layer "In6.Cu")
		(net "P5E_CPU1_PE3_TX_C_DP<15>")
	)
	(segment
		(start 122.590306 -415.18967)
		(end 122.653044 -415.552382)
		(width 0.14732)
		(layer "In6.Cu")
		(net "P5E_CPU1_PE3_TX_C_DP<15>")
	)
	(segment
		(start 122.763534 -416.190938)
		(end 125.147578 -429.969676)
		(width 0.14732)
		(layer "In6.Cu")
		(net "P5E_CPU1_PE3_TX_C_DP<15>")
	)
	(segment
		(start 122.53087 -414.026858)
		(end 122.417078 -414.188402)
		(width 0.14732)
		(layer "In6.Cu")
		(net "P5E_CPU1_PE3_TX_C_DP<15>")
	)
	(segment
		(start 125.750066 -429.941228)
		(end 125.750066 -429.689768)
		(width 0.14732)
		(layer "In6.Cu")
		(net "P5E_CPU1_PE3_TX_C_DP<15>")
	)
	(segment
		(start 125.147578 -429.969676)
		(end 125.365002 -430.15281)
		(width 0.14732)
		(layer "In6.Cu")
		(net "P5E_CPU1_PE3_TX_C_DP<15>")
	)
	(segment
		(start 122.814588 -415.666174)
		(end 122.87758 -416.029394)
		(width 0.14732)
		(layer "In6.Cu")
		(net "P5E_CPU1_PE3_TX_C_DP<15>")
	)
	(segment
		(start 122.070114 -412.185866)
		(end 122.132852 -412.548578)
		(width 0.14732)
		(layer "In6.Cu")
		(net "P5E_CPU1_PE3_TX_C_DP<15>")
	)
	(segment
		(start 122.357388 -413.02559)
		(end 122.243596 -413.187134)
		(width 0.14732)
		(layer "In6.Cu")
		(net "P5E_CPU1_PE3_TX_C_DP<15>")
	)
	(segment
		(start 122.653044 -415.552382)
		(end 122.814588 -415.666174)
		(width 0.14732)
		(layer "In6.Cu")
		(net "P5E_CPU1_PE3_TX_C_DP<15>")
	)
	(segment
		(start 122.417078 -414.188402)
		(end 122.479816 -414.551114)
		(width 0.14732)
		(layer "In6.Cu")
		(net "P5E_CPU1_PE3_TX_C_DP<15>")
	)
	(segment
		(start 122.467878 -413.663638)
		(end 122.53087 -414.026858)
		(width 0.14732)
		(layer "In6.Cu")
		(net "P5E_CPU1_PE3_TX_C_DP<15>")
	)
	(segment
		(start 122.64136 -414.664906)
		(end 122.704352 -415.028126)
		(width 0.14732)
		(layer "In6.Cu")
		(net "P5E_CPU1_PE3_TX_C_DP<15>")
	)
	(segment
		(start 125.538484 -430.15281)
		(end 125.750066 -429.941228)
		(width 0.14732)
		(layer "In6.Cu")
		(net "P5E_CPU1_PE3_TX_C_DP<15>")
	)
	(segment
		(start 122.479816 -414.551114)
		(end 122.64136 -414.664906)
		(width 0.14732)
		(layer "In6.Cu")
		(net "P5E_CPU1_PE3_TX_C_DP<15>")
	)
	(segment
		(start 122.87758 -416.029394)
		(end 122.763534 -416.190938)
		(width 0.14732)
		(layer "In6.Cu")
		(net "P5E_CPU1_PE3_TX_C_DP<15>")
	)
	(segment
		(start 125.427994 -410.030168)
		(end 125.126496 -409.72867)
		(width 0.13208)
		(layer "F.Cu")
		(net "P5E_CPU1_PE3_TX_C_DP<14>")
	)
	(segment
		(start 125.126496 -409.72867)
		(end 125.126496 -409.110942)
		(width 0.13208)
		(layer "F.Cu")
		(net "P5E_CPU1_PE3_TX_C_DP<14>")
	)
	(segment
		(start 125.126496 -409.110942)
		(end 125.453394 -408.784044)
		(width 0.13208)
		(layer "F.Cu")
		(net "P5E_CPU1_PE3_TX_C_DP<14>")
	)
	(segment
		(start 125.41377 -412.997142)
		(end 127.066802 -423.952416)
		(width 0.14732)
		(layer "In6.Cu")
		(net "P5E_CPU1_PE3_TX_C_DP<14>")
	)
	(segment
		(start 125.324616 -411.468824)
		(end 125.37948 -411.833314)
		(width 0.14732)
		(layer "In6.Cu")
		(net "P5E_CPU1_PE3_TX_C_DP<14>")
	)
	(segment
		(start 127.750062 -430.941226)
		(end 127.750062 -430.689766)
		(width 0.14732)
		(layer "In6.Cu")
		(net "P5E_CPU1_PE3_TX_C_DP<14>")
	)
	(segment
		(start 125.262132 -411.992318)
		(end 125.316996 -412.3563)
		(width 0.14732)
		(layer "In6.Cu")
		(net "P5E_CPU1_PE3_TX_C_DP<14>")
	)
	(segment
		(start 125.37948 -411.833314)
		(end 125.262132 -411.992318)
		(width 0.14732)
		(layer "In6.Cu")
		(net "P5E_CPU1_PE3_TX_C_DP<14>")
	)
	(segment
		(start 127.289306 -431.152808)
		(end 127.53848 -431.152808)
		(width 0.14732)
		(layer "In6.Cu")
		(net "P5E_CPU1_PE3_TX_C_DP<14>")
	)
	(segment
		(start 127.066802 -430.930304)
		(end 127.289306 -431.152808)
		(width 0.14732)
		(layer "In6.Cu")
		(net "P5E_CPU1_PE3_TX_C_DP<14>")
	)
	(segment
		(start 125.476254 -412.473648)
		(end 125.531118 -412.838138)
		(width 0.14732)
		(layer "In6.Cu")
		(net "P5E_CPU1_PE3_TX_C_DP<14>")
	)
	(segment
		(start 127.066802 -423.952416)
		(end 127.066802 -430.930304)
		(width 0.14732)
		(layer "In6.Cu")
		(net "P5E_CPU1_PE3_TX_C_DP<14>")
	)
	(segment
		(start 125.133354 -410.324808)
		(end 125.133354 -411.139132)
		(width 0.14732)
		(layer "In6.Cu")
		(net "P5E_CPU1_PE3_TX_C_DP<14>")
	)
	(segment
		(start 125.316996 -412.3563)
		(end 125.476254 -412.473648)
		(width 0.14732)
		(layer "In6.Cu")
		(net "P5E_CPU1_PE3_TX_C_DP<14>")
	)
	(segment
		(start 125.427994 -410.030168)
		(end 125.133354 -410.324808)
		(width 0.14732)
		(layer "In6.Cu")
		(net "P5E_CPU1_PE3_TX_C_DP<14>")
	)
	(segment
		(start 125.531118 -412.838138)
		(end 125.41377 -412.997142)
		(width 0.14732)
		(layer "In6.Cu")
		(net "P5E_CPU1_PE3_TX_C_DP<14>")
	)
	(segment
		(start 125.133354 -411.139132)
		(end 125.165358 -411.351476)
		(width 0.14732)
		(layer "In6.Cu")
		(net "P5E_CPU1_PE3_TX_C_DP<14>")
	)
	(segment
		(start 127.53848 -431.152808)
		(end 127.750062 -430.941226)
		(width 0.14732)
		(layer "In6.Cu")
		(net "P5E_CPU1_PE3_TX_C_DP<14>")
	)
	(segment
		(start 125.165358 -411.351476)
		(end 125.324616 -411.468824)
		(width 0.14732)
		(layer "In6.Cu")
		(net "P5E_CPU1_PE3_TX_C_DP<14>")
	)
	(segment
		(start 128.189736 -409.72867)
		(end 128.189736 -409.110942)
		(width 0.13208)
		(layer "F.Cu")
		(net "P5E_CPU1_PE3_TX_C_DP<13>")
	)
	(segment
		(start 128.189736 -409.110942)
		(end 128.516634 -408.784044)
		(width 0.13208)
		(layer "F.Cu")
		(net "P5E_CPU1_PE3_TX_C_DP<13>")
	)
	(segment
		(start 128.491234 -410.030168)
		(end 128.189736 -409.72867)
		(width 0.13208)
		(layer "F.Cu")
		(net "P5E_CPU1_PE3_TX_C_DP<13>")
	)
	(segment
		(start 128.491234 -410.030168)
		(end 128.196594 -410.324808)
		(width 0.14732)
		(layer "In6.Cu")
		(net "P5E_CPU1_PE3_TX_C_DP<13>")
	)
	(segment
		(start 128.498854 -413.875474)
		(end 128.524762 -414.243012)
		(width 0.14732)
		(layer "In6.Cu")
		(net "P5E_CPU1_PE3_TX_C_DP<13>")
	)
	(segment
		(start 128.349502 -413.745934)
		(end 128.498854 -413.875474)
		(width 0.14732)
		(layer "In6.Cu")
		(net "P5E_CPU1_PE3_TX_C_DP<13>")
	)
	(segment
		(start 129.066798 -430.00549)
		(end 129.214118 -430.15281)
		(width 0.14732)
		(layer "In6.Cu")
		(net "P5E_CPU1_PE3_TX_C_DP<13>")
	)
	(segment
		(start 128.323594 -413.37865)
		(end 128.349502 -413.745934)
		(width 0.14732)
		(layer "In6.Cu")
		(net "P5E_CPU1_PE3_TX_C_DP<13>")
	)
	(segment
		(start 128.196594 -411.580584)
		(end 128.277874 -412.73222)
		(width 0.14732)
		(layer "In6.Cu")
		(net "P5E_CPU1_PE3_TX_C_DP<13>")
	)
	(segment
		(start 128.524762 -414.243012)
		(end 128.395222 -414.392364)
		(width 0.14732)
		(layer "In6.Cu")
		(net "P5E_CPU1_PE3_TX_C_DP<13>")
	)
	(segment
		(start 128.395222 -414.392364)
		(end 128.425956 -414.827974)
		(width 0.14732)
		(layer "In6.Cu")
		(net "P5E_CPU1_PE3_TX_C_DP<13>")
	)
	(segment
		(start 129.214118 -430.15281)
		(end 129.580132 -430.15281)
		(width 0.14732)
		(layer "In6.Cu")
		(net "P5E_CPU1_PE3_TX_C_DP<13>")
	)
	(segment
		(start 129.750058 -429.982884)
		(end 129.750058 -429.689768)
		(width 0.14732)
		(layer "In6.Cu")
		(net "P5E_CPU1_PE3_TX_C_DP<13>")
	)
	(segment
		(start 128.553718 -416.632644)
		(end 129.066798 -423.901362)
		(width 0.14732)
		(layer "In6.Cu")
		(net "P5E_CPU1_PE3_TX_C_DP<13>")
	)
	(segment
		(start 128.427226 -412.86176)
		(end 128.453134 -413.229298)
		(width 0.14732)
		(layer "In6.Cu")
		(net "P5E_CPU1_PE3_TX_C_DP<13>")
	)
	(segment
		(start 128.453134 -413.229298)
		(end 128.323594 -413.37865)
		(width 0.14732)
		(layer "In6.Cu")
		(net "P5E_CPU1_PE3_TX_C_DP<13>")
	)
	(segment
		(start 128.559052 -414.94329)
		(end 128.589786 -415.379408)
		(width 0.14732)
		(layer "In6.Cu")
		(net "P5E_CPU1_PE3_TX_C_DP<13>")
	)
	(segment
		(start 128.669034 -416.499548)
		(end 128.553718 -416.632644)
		(width 0.14732)
		(layer "In6.Cu")
		(net "P5E_CPU1_PE3_TX_C_DP<13>")
	)
	(segment
		(start 128.47447 -415.512504)
		(end 128.505204 -415.948114)
		(width 0.14732)
		(layer "In6.Cu")
		(net "P5E_CPU1_PE3_TX_C_DP<13>")
	)
	(segment
		(start 128.505204 -415.948114)
		(end 128.6383 -416.06343)
		(width 0.14732)
		(layer "In6.Cu")
		(net "P5E_CPU1_PE3_TX_C_DP<13>")
	)
	(segment
		(start 128.589786 -415.379408)
		(end 128.47447 -415.512504)
		(width 0.14732)
		(layer "In6.Cu")
		(net "P5E_CPU1_PE3_TX_C_DP<13>")
	)
	(segment
		(start 129.066798 -423.901362)
		(end 129.066798 -430.00549)
		(width 0.14732)
		(layer "In6.Cu")
		(net "P5E_CPU1_PE3_TX_C_DP<13>")
	)
	(segment
		(start 128.277874 -412.73222)
		(end 128.427226 -412.86176)
		(width 0.14732)
		(layer "In6.Cu")
		(net "P5E_CPU1_PE3_TX_C_DP<13>")
	)
	(segment
		(start 129.580132 -430.15281)
		(end 129.750058 -429.982884)
		(width 0.14732)
		(layer "In6.Cu")
		(net "P5E_CPU1_PE3_TX_C_DP<13>")
	)
	(segment
		(start 128.6383 -416.06343)
		(end 128.669034 -416.499548)
		(width 0.14732)
		(layer "In6.Cu")
		(net "P5E_CPU1_PE3_TX_C_DP<13>")
	)
	(segment
		(start 128.196594 -410.324808)
		(end 128.196594 -411.580584)
		(width 0.14732)
		(layer "In6.Cu")
		(net "P5E_CPU1_PE3_TX_C_DP<13>")
	)
	(segment
		(start 128.425956 -414.827974)
		(end 128.559052 -414.94329)
		(width 0.14732)
		(layer "In6.Cu")
		(net "P5E_CPU1_PE3_TX_C_DP<13>")
	)
	(segment
		(start 131.252976 -409.110942)
		(end 131.579874 -408.784044)
		(width 0.13208)
		(layer "F.Cu")
		(net "P5E_CPU1_PE3_TX_C_DP<12>")
	)
	(segment
		(start 131.252976 -409.72867)
		(end 131.252976 -409.110942)
		(width 0.13208)
		(layer "F.Cu")
		(net "P5E_CPU1_PE3_TX_C_DP<12>")
	)
	(segment
		(start 131.554474 -410.030168)
		(end 131.252976 -409.72867)
		(width 0.13208)
		(layer "F.Cu")
		(net "P5E_CPU1_PE3_TX_C_DP<12>")
	)
	(segment
		(start 131.18846 -411.472888)
		(end 131.099052 -420.716456)
		(width 0.14732)
		(layer "In6.Cu")
		(net "P5E_CPU1_PE3_TX_C_DP<12>")
	)
	(segment
		(start 131.259834 -410.324808)
		(end 131.259834 -410.755084)
		(width 0.14732)
		(layer "In6.Cu")
		(net "P5E_CPU1_PE3_TX_C_DP<12>")
	)
	(segment
		(start 131.072636 -423.39641)
		(end 131.066794 -424.009312)
		(width 0.14732)
		(layer "In6.Cu")
		(net "P5E_CPU1_PE3_TX_C_DP<12>")
	)
	(segment
		(start 131.556252 -431.135028)
		(end 131.750054 -430.941226)
		(width 0.14732)
		(layer "In6.Cu")
		(net "P5E_CPU1_PE3_TX_C_DP<12>")
	)
	(segment
		(start 131.183126 -431.135028)
		(end 131.556252 -431.135028)
		(width 0.14732)
		(layer "In6.Cu")
		(net "P5E_CPU1_PE3_TX_C_DP<12>")
	)
	(segment
		(start 131.089146 -421.732456)
		(end 131.227576 -421.873426)
		(width 0.14732)
		(layer "In6.Cu")
		(net "P5E_CPU1_PE3_TX_C_DP<12>")
	)
	(segment
		(start 131.082796 -422.38041)
		(end 131.07924 -422.748456)
		(width 0.14732)
		(layer "In6.Cu")
		(net "P5E_CPU1_PE3_TX_C_DP<12>")
	)
	(segment
		(start 131.099052 -420.716456)
		(end 131.237482 -420.857426)
		(width 0.14732)
		(layer "In6.Cu")
		(net "P5E_CPU1_PE3_TX_C_DP<12>")
	)
	(segment
		(start 131.233926 -421.22598)
		(end 131.092702 -421.36441)
		(width 0.14732)
		(layer "In6.Cu")
		(net "P5E_CPU1_PE3_TX_C_DP<12>")
	)
	(segment
		(start 131.21386 -423.258234)
		(end 131.072636 -423.39641)
		(width 0.14732)
		(layer "In6.Cu")
		(net "P5E_CPU1_PE3_TX_C_DP<12>")
	)
	(segment
		(start 131.092702 -421.36441)
		(end 131.089146 -421.732456)
		(width 0.14732)
		(layer "In6.Cu")
		(net "P5E_CPU1_PE3_TX_C_DP<12>")
	)
	(segment
		(start 131.217416 -422.88968)
		(end 131.21386 -423.258234)
		(width 0.14732)
		(layer "In6.Cu")
		(net "P5E_CPU1_PE3_TX_C_DP<12>")
	)
	(segment
		(start 131.554474 -410.030168)
		(end 131.259834 -410.324808)
		(width 0.14732)
		(layer "In6.Cu")
		(net "P5E_CPU1_PE3_TX_C_DP<12>")
	)
	(segment
		(start 131.750054 -430.941226)
		(end 131.750054 -430.689766)
		(width 0.14732)
		(layer "In6.Cu")
		(net "P5E_CPU1_PE3_TX_C_DP<12>")
	)
	(segment
		(start 131.237482 -420.857426)
		(end 131.233926 -421.22598)
		(width 0.14732)
		(layer "In6.Cu")
		(net "P5E_CPU1_PE3_TX_C_DP<12>")
	)
	(segment
		(start 131.066794 -431.018696)
		(end 131.183126 -431.135028)
		(width 0.14732)
		(layer "In6.Cu")
		(net "P5E_CPU1_PE3_TX_C_DP<12>")
	)
	(segment
		(start 131.227576 -421.873426)
		(end 131.22402 -422.24198)
		(width 0.14732)
		(layer "In6.Cu")
		(net "P5E_CPU1_PE3_TX_C_DP<12>")
	)
	(segment
		(start 131.066794 -424.009312)
		(end 131.066794 -431.018696)
		(width 0.14732)
		(layer "In6.Cu")
		(net "P5E_CPU1_PE3_TX_C_DP<12>")
	)
	(segment
		(start 131.259834 -410.755084)
		(end 131.18846 -411.472888)
		(width 0.14732)
		(layer "In6.Cu")
		(net "P5E_CPU1_PE3_TX_C_DP<12>")
	)
	(segment
		(start 131.22402 -422.24198)
		(end 131.082796 -422.38041)
		(width 0.14732)
		(layer "In6.Cu")
		(net "P5E_CPU1_PE3_TX_C_DP<12>")
	)
	(segment
		(start 131.07924 -422.748456)
		(end 131.217416 -422.88968)
		(width 0.14732)
		(layer "In6.Cu")
		(net "P5E_CPU1_PE3_TX_C_DP<12>")
	)
	(segment
		(start 134.316216 -409.72867)
		(end 134.316216 -409.110942)
		(width 0.13208)
		(layer "F.Cu")
		(net "P5E_CPU1_PE3_TX_C_DP<11>")
	)
	(segment
		(start 134.316216 -409.110942)
		(end 134.643114 -408.784044)
		(width 0.13208)
		(layer "F.Cu")
		(net "P5E_CPU1_PE3_TX_C_DP<11>")
	)
	(segment
		(start 134.617714 -410.030168)
		(end 134.316216 -409.72867)
		(width 0.13208)
		(layer "F.Cu")
		(net "P5E_CPU1_PE3_TX_C_DP<11>")
	)
	(segment
		(start 133.384036 -420.474648)
		(end 133.350762 -420.84117)
		(width 0.14732)
		(layer "In6.Cu")
		(net "P5E_CPU1_PE3_TX_C_DP<11>")
	)
	(segment
		(start 133.258306 -423.383964)
		(end 133.106414 -423.510456)
		(width 0.14732)
		(layer "In6.Cu")
		(net "P5E_CPU1_PE3_TX_C_DP<11>")
	)
	(segment
		(start 133.258052 -421.853106)
		(end 133.384544 -422.004998)
		(width 0.14732)
		(layer "In6.Cu")
		(net "P5E_CPU1_PE3_TX_C_DP<11>")
	)
	(segment
		(start 133.067298 -423.944288)
		(end 133.06679 -423.944796)
		(width 0.14732)
		(layer "In6.Cu")
		(net "P5E_CPU1_PE3_TX_C_DP<11>")
	)
	(segment
		(start 133.106414 -423.510456)
		(end 133.106922 -423.510456)
		(width 0.14732)
		(layer "In6.Cu")
		(net "P5E_CPU1_PE3_TX_C_DP<11>")
	)
	(segment
		(start 134.323074 -410.736796)
		(end 134.246366 -411.037786)
		(width 0.14732)
		(layer "In6.Cu")
		(net "P5E_CPU1_PE3_TX_C_DP<11>")
	)
	(segment
		(start 133.106922 -423.510456)
		(end 133.067298 -423.944288)
		(width 0.14732)
		(layer "In6.Cu")
		(net "P5E_CPU1_PE3_TX_C_DP<11>")
	)
	(segment
		(start 133.19887 -422.49852)
		(end 133.165596 -422.865042)
		(width 0.14732)
		(layer "In6.Cu")
		(net "P5E_CPU1_PE3_TX_C_DP<11>")
	)
	(segment
		(start 133.351016 -422.372028)
		(end 133.19887 -422.49852)
		(width 0.14732)
		(layer "In6.Cu")
		(net "P5E_CPU1_PE3_TX_C_DP<11>")
	)
	(segment
		(start 133.384544 -422.004998)
		(end 133.351016 -422.372028)
		(width 0.14732)
		(layer "In6.Cu")
		(net "P5E_CPU1_PE3_TX_C_DP<11>")
	)
	(segment
		(start 133.291834 -423.016934)
		(end 133.258306 -423.383964)
		(width 0.14732)
		(layer "In6.Cu")
		(net "P5E_CPU1_PE3_TX_C_DP<11>")
	)
	(segment
		(start 133.536182 -420.348156)
		(end 133.384036 -420.474648)
		(width 0.14732)
		(layer "In6.Cu")
		(net "P5E_CPU1_PE3_TX_C_DP<11>")
	)
	(segment
		(start 134.617714 -410.030168)
		(end 134.323074 -410.324808)
		(width 0.14732)
		(layer "In6.Cu")
		(net "P5E_CPU1_PE3_TX_C_DP<11>")
	)
	(segment
		(start 133.538468 -430.15281)
		(end 133.75005 -429.941228)
		(width 0.14732)
		(layer "In6.Cu")
		(net "P5E_CPU1_PE3_TX_C_DP<11>")
	)
	(segment
		(start 134.323074 -410.324808)
		(end 134.323074 -410.736796)
		(width 0.14732)
		(layer "In6.Cu")
		(net "P5E_CPU1_PE3_TX_C_DP<11>")
	)
	(segment
		(start 133.21411 -430.15281)
		(end 133.538468 -430.15281)
		(width 0.14732)
		(layer "In6.Cu")
		(net "P5E_CPU1_PE3_TX_C_DP<11>")
	)
	(segment
		(start 133.06679 -430.00549)
		(end 133.21411 -430.15281)
		(width 0.14732)
		(layer "In6.Cu")
		(net "P5E_CPU1_PE3_TX_C_DP<11>")
	)
	(segment
		(start 134.246366 -411.037786)
		(end 133.443218 -419.829234)
		(width 0.14732)
		(layer "In6.Cu")
		(net "P5E_CPU1_PE3_TX_C_DP<11>")
	)
	(segment
		(start 133.06679 -423.944796)
		(end 133.06679 -430.00549)
		(width 0.14732)
		(layer "In6.Cu")
		(net "P5E_CPU1_PE3_TX_C_DP<11>")
	)
	(segment
		(start 133.477 -420.993062)
		(end 133.443472 -421.360092)
		(width 0.14732)
		(layer "In6.Cu")
		(net "P5E_CPU1_PE3_TX_C_DP<11>")
	)
	(segment
		(start 133.165596 -422.865042)
		(end 133.291834 -423.016934)
		(width 0.14732)
		(layer "In6.Cu")
		(net "P5E_CPU1_PE3_TX_C_DP<11>")
	)
	(segment
		(start 133.443218 -419.829234)
		(end 133.56971 -419.981126)
		(width 0.14732)
		(layer "In6.Cu")
		(net "P5E_CPU1_PE3_TX_C_DP<11>")
	)
	(segment
		(start 133.75005 -429.941228)
		(end 133.75005 -429.689768)
		(width 0.14732)
		(layer "In6.Cu")
		(net "P5E_CPU1_PE3_TX_C_DP<11>")
	)
	(segment
		(start 133.56971 -419.981126)
		(end 133.536182 -420.348156)
		(width 0.14732)
		(layer "In6.Cu")
		(net "P5E_CPU1_PE3_TX_C_DP<11>")
	)
	(segment
		(start 133.350762 -420.84117)
		(end 133.477 -420.993062)
		(width 0.14732)
		(layer "In6.Cu")
		(net "P5E_CPU1_PE3_TX_C_DP<11>")
	)
	(segment
		(start 133.443472 -421.360092)
		(end 133.291326 -421.486584)
		(width 0.14732)
		(layer "In6.Cu")
		(net "P5E_CPU1_PE3_TX_C_DP<11>")
	)
	(segment
		(start 133.291326 -421.486584)
		(end 133.258052 -421.853106)
		(width 0.14732)
		(layer "In6.Cu")
		(net "P5E_CPU1_PE3_TX_C_DP<11>")
	)
	(segment
		(start 137.680954 -410.030168)
		(end 137.379456 -409.72867)
		(width 0.13208)
		(layer "F.Cu")
		(net "P5E_CPU1_PE3_TX_C_DP<10>")
	)
	(segment
		(start 137.379456 -409.72867)
		(end 137.379456 -409.110942)
		(width 0.13208)
		(layer "F.Cu")
		(net "P5E_CPU1_PE3_TX_C_DP<10>")
	)
	(segment
		(start 137.379456 -409.110942)
		(end 137.706354 -408.784044)
		(width 0.13208)
		(layer "F.Cu")
		(net "P5E_CPU1_PE3_TX_C_DP<10>")
	)
	(segment
		(start 135.410702 -422.028366)
		(end 135.524748 -422.189656)
		(width 0.14732)
		(layer "In6.Cu")
		(net "P5E_CPU1_PE3_TX_C_DP<10>")
	)
	(segment
		(start 135.129016 -423.668444)
		(end 135.066786 -424.03141)
		(width 0.14732)
		(layer "In6.Cu")
		(net "P5E_CPU1_PE3_TX_C_DP<10>")
	)
	(segment
		(start 137.386314 -410.324808)
		(end 137.386314 -410.539438)
		(width 0.14732)
		(layer "In6.Cu")
		(net "P5E_CPU1_PE3_TX_C_DP<10>")
	)
	(segment
		(start 135.066786 -431.005488)
		(end 135.214106 -431.152808)
		(width 0.14732)
		(layer "In6.Cu")
		(net "P5E_CPU1_PE3_TX_C_DP<10>")
	)
	(segment
		(start 137.386314 -410.539438)
		(end 137.382504 -410.543248)
		(width 0.14732)
		(layer "In6.Cu")
		(net "P5E_CPU1_PE3_TX_C_DP<10>")
	)
	(segment
		(start 137.382504 -410.543248)
		(end 135.410702 -422.028366)
		(width 0.14732)
		(layer "In6.Cu")
		(net "P5E_CPU1_PE3_TX_C_DP<10>")
	)
	(segment
		(start 135.462518 -422.552876)
		(end 135.300974 -422.666922)
		(width 0.14732)
		(layer "In6.Cu")
		(net "P5E_CPU1_PE3_TX_C_DP<10>")
	)
	(segment
		(start 135.29056 -423.554398)
		(end 135.129016 -423.668444)
		(width 0.14732)
		(layer "In6.Cu")
		(net "P5E_CPU1_PE3_TX_C_DP<10>")
	)
	(segment
		(start 135.214106 -431.152808)
		(end 135.538464 -431.152808)
		(width 0.14732)
		(layer "In6.Cu")
		(net "P5E_CPU1_PE3_TX_C_DP<10>")
	)
	(segment
		(start 135.35279 -423.191178)
		(end 135.29056 -423.554398)
		(width 0.14732)
		(layer "In6.Cu")
		(net "P5E_CPU1_PE3_TX_C_DP<10>")
	)
	(segment
		(start 137.680954 -410.030168)
		(end 137.386314 -410.324808)
		(width 0.14732)
		(layer "In6.Cu")
		(net "P5E_CPU1_PE3_TX_C_DP<10>")
	)
	(segment
		(start 135.066786 -424.03141)
		(end 135.066786 -431.005488)
		(width 0.14732)
		(layer "In6.Cu")
		(net "P5E_CPU1_PE3_TX_C_DP<10>")
	)
	(segment
		(start 135.238744 -423.029888)
		(end 135.35279 -423.191178)
		(width 0.14732)
		(layer "In6.Cu")
		(net "P5E_CPU1_PE3_TX_C_DP<10>")
	)
	(segment
		(start 135.538464 -431.152808)
		(end 135.750046 -430.941226)
		(width 0.14732)
		(layer "In6.Cu")
		(net "P5E_CPU1_PE3_TX_C_DP<10>")
	)
	(segment
		(start 135.300974 -422.666922)
		(end 135.238744 -423.029888)
		(width 0.14732)
		(layer "In6.Cu")
		(net "P5E_CPU1_PE3_TX_C_DP<10>")
	)
	(segment
		(start 135.750046 -430.941226)
		(end 135.750046 -430.689766)
		(width 0.14732)
		(layer "In6.Cu")
		(net "P5E_CPU1_PE3_TX_C_DP<10>")
	)
	(segment
		(start 135.524748 -422.189656)
		(end 135.462518 -422.552876)
		(width 0.14732)
		(layer "In6.Cu")
		(net "P5E_CPU1_PE3_TX_C_DP<10>")
	)
	(segment
		(start 167.427656 -408.784044)
		(end 167.424354 -408.784044)
		(width 0.13208)
		(layer "F.Cu")
		(net "P5E_CPU1_PE3_TX_C_DP<0>")
	)
	(segment
		(start 167.449754 -410.030168)
		(end 167.752776 -409.727146)
		(width 0.13208)
		(layer "F.Cu")
		(net "P5E_CPU1_PE3_TX_C_DP<0>")
	)
	(segment
		(start 167.752776 -409.727146)
		(end 167.752776 -409.109164)
		(width 0.13208)
		(layer "F.Cu")
		(net "P5E_CPU1_PE3_TX_C_DP<0>")
	)
	(segment
		(start 167.752776 -409.109164)
		(end 167.427656 -408.784044)
		(width 0.13208)
		(layer "F.Cu")
		(net "P5E_CPU1_PE3_TX_C_DP<0>")
	)
	(segment
		(start 155.792424 -424.1165)
		(end 156.100018 -423.330624)
		(width 0.14732)
		(layer "In6.Cu")
		(net "P5E_CPU1_PE3_TX_C_DP<0>")
	)
	(segment
		(start 155.792424 -431.11928)
		(end 155.792424 -424.1165)
		(width 0.14732)
		(layer "In6.Cu")
		(net "P5E_CPU1_PE3_TX_C_DP<0>")
	)
	(segment
		(start 158.259272 -420.99484)
		(end 161.447226 -417.546028)
		(width 0.14732)
		(layer "In6.Cu")
		(net "P5E_CPU1_PE3_TX_C_DP<0>")
	)
	(segment
		(start 156.100018 -423.330624)
		(end 158.259018 -420.99484)
		(width 0.14732)
		(layer "In6.Cu")
		(net "P5E_CPU1_PE3_TX_C_DP<0>")
	)
	(segment
		(start 156.100272 -431.427128)
		(end 155.792424 -431.11928)
		(width 0.14732)
		(layer "In6.Cu")
		(net "P5E_CPU1_PE3_TX_C_DP<0>")
	)
	(segment
		(start 161.447226 -417.546028)
		(end 166.963852 -412.508954)
		(width 0.14732)
		(layer "In6.Cu")
		(net "P5E_CPU1_PE3_TX_C_DP<0>")
	)
	(segment
		(start 158.259018 -420.99484)
		(end 158.259272 -420.99484)
		(width 0.14732)
		(layer "In6.Cu")
		(net "P5E_CPU1_PE3_TX_C_DP<0>")
	)
	(segment
		(start 156.750004 -431.574702)
		(end 156.60243 -431.427128)
		(width 0.14732)
		(layer "In6.Cu")
		(net "P5E_CPU1_PE3_TX_C_DP<0>")
	)
	(segment
		(start 167.744394 -410.324808)
		(end 167.449754 -410.030168)
		(width 0.14732)
		(layer "In6.Cu")
		(net "P5E_CPU1_PE3_TX_C_DP<0>")
	)
	(segment
		(start 166.963852 -412.508954)
		(end 167.744394 -410.739336)
		(width 0.14732)
		(layer "In6.Cu")
		(net "P5E_CPU1_PE3_TX_C_DP<0>")
	)
	(segment
		(start 156.60243 -431.427128)
		(end 156.100272 -431.427128)
		(width 0.14732)
		(layer "In6.Cu")
		(net "P5E_CPU1_PE3_TX_C_DP<0>")
	)
	(segment
		(start 167.744394 -410.739336)
		(end 167.744394 -410.324808)
		(width 0.14732)
		(layer "In6.Cu")
		(net "P5E_CPU1_PE3_TX_C_DP<0>")
	)
	(segment
		(start 156.750004 -431.889916)
		(end 156.750004 -431.574702)
		(width 0.14732)
		(layer "In6.Cu")
		(net "P5E_CPU1_PE3_TX_C_DP<0>")
	)
	(segment
		(start 140.183616 -409.727146)
		(end 140.183616 -409.109164)
		(width 0.13208)
		(layer "F.Cu")
		(net "P5E_CPU1_PE3_TX_C_DN<9>")
	)
	(segment
		(start 139.880594 -410.030168)
		(end 140.183616 -409.727146)
		(width 0.13208)
		(layer "F.Cu")
		(net "P5E_CPU1_PE3_TX_C_DN<9>")
	)
	(segment
		(start 140.183616 -409.109164)
		(end 139.858496 -408.784044)
		(width 0.13208)
		(layer "F.Cu")
		(net "P5E_CPU1_PE3_TX_C_DN<9>")
	)
	(segment
		(start 139.858496 -408.784044)
		(end 139.855194 -408.784044)
		(width 0.13208)
		(layer "F.Cu")
		(net "P5E_CPU1_PE3_TX_C_DN<9>")
	)
	(segment
		(start 137.10031 -430.42713)
		(end 136.792462 -430.119282)
		(width 0.14732)
		(layer "In6.Cu")
		(net "P5E_CPU1_PE3_TX_C_DN<9>")
	)
	(segment
		(start 137.602468 -430.42713)
		(end 137.10031 -430.42713)
		(width 0.14732)
		(layer "In6.Cu")
		(net "P5E_CPU1_PE3_TX_C_DN<9>")
	)
	(segment
		(start 140.17498 -410.59735)
		(end 140.17498 -410.324554)
		(width 0.14732)
		(layer "In6.Cu")
		(net "P5E_CPU1_PE3_TX_C_DN<9>")
	)
	(segment
		(start 137.750042 -430.889918)
		(end 137.750042 -430.574704)
		(width 0.14732)
		(layer "In6.Cu")
		(net "P5E_CPU1_PE3_TX_C_DN<9>")
	)
	(segment
		(start 140.17498 -410.324554)
		(end 139.880594 -410.030168)
		(width 0.14732)
		(layer "In6.Cu")
		(net "P5E_CPU1_PE3_TX_C_DN<9>")
	)
	(segment
		(start 136.792462 -430.119282)
		(end 136.792462 -423.968164)
		(width 0.14732)
		(layer "In6.Cu")
		(net "P5E_CPU1_PE3_TX_C_DN<9>")
	)
	(segment
		(start 136.792462 -423.968164)
		(end 140.17498 -410.59735)
		(width 0.14732)
		(layer "In6.Cu")
		(net "P5E_CPU1_PE3_TX_C_DN<9>")
	)
	(segment
		(start 137.750042 -430.574704)
		(end 137.602468 -430.42713)
		(width 0.14732)
		(layer "In6.Cu")
		(net "P5E_CPU1_PE3_TX_C_DN<9>")
	)
	(segment
		(start 143.246856 -409.109164)
		(end 142.921736 -408.784044)
		(width 0.13208)
		(layer "F.Cu")
		(net "P5E_CPU1_PE3_TX_C_DN<8>")
	)
	(segment
		(start 142.943834 -410.030168)
		(end 143.246856 -409.727146)
		(width 0.13208)
		(layer "F.Cu")
		(net "P5E_CPU1_PE3_TX_C_DN<8>")
	)
	(segment
		(start 142.921736 -408.784044)
		(end 142.918434 -408.784044)
		(width 0.13208)
		(layer "F.Cu")
		(net "P5E_CPU1_PE3_TX_C_DN<8>")
	)
	(segment
		(start 143.246856 -409.727146)
		(end 143.246856 -409.109164)
		(width 0.13208)
		(layer "F.Cu")
		(net "P5E_CPU1_PE3_TX_C_DN<8>")
	)
	(segment
		(start 139.750038 -431.889916)
		(end 139.750038 -431.574702)
		(width 0.14732)
		(layer "In6.Cu")
		(net "P5E_CPU1_PE3_TX_C_DN<8>")
	)
	(segment
		(start 138.792458 -423.908728)
		(end 143.238474 -410.636974)
		(width 0.14732)
		(layer "In6.Cu")
		(net "P5E_CPU1_PE3_TX_C_DN<8>")
	)
	(segment
		(start 139.138914 -431.427128)
		(end 138.792458 -431.080672)
		(width 0.14732)
		(layer "In6.Cu")
		(net "P5E_CPU1_PE3_TX_C_DN<8>")
	)
	(segment
		(start 143.238474 -410.324808)
		(end 142.943834 -410.030168)
		(width 0.14732)
		(layer "In6.Cu")
		(net "P5E_CPU1_PE3_TX_C_DN<8>")
	)
	(segment
		(start 139.602464 -431.427128)
		(end 139.138914 -431.427128)
		(width 0.14732)
		(layer "In6.Cu")
		(net "P5E_CPU1_PE3_TX_C_DN<8>")
	)
	(segment
		(start 138.792458 -431.080672)
		(end 138.792458 -423.908728)
		(width 0.14732)
		(layer "In6.Cu")
		(net "P5E_CPU1_PE3_TX_C_DN<8>")
	)
	(segment
		(start 143.238474 -410.636974)
		(end 143.238474 -410.324808)
		(width 0.14732)
		(layer "In6.Cu")
		(net "P5E_CPU1_PE3_TX_C_DN<8>")
	)
	(segment
		(start 139.750038 -431.574702)
		(end 139.602464 -431.427128)
		(width 0.14732)
		(layer "In6.Cu")
		(net "P5E_CPU1_PE3_TX_C_DN<8>")
	)
	(segment
		(start 145.984976 -408.784044)
		(end 145.981674 -408.784044)
		(width 0.13208)
		(layer "F.Cu")
		(net "P5E_CPU1_PE3_TX_C_DN<7>")
	)
	(segment
		(start 146.310096 -409.109164)
		(end 145.984976 -408.784044)
		(width 0.13208)
		(layer "F.Cu")
		(net "P5E_CPU1_PE3_TX_C_DN<7>")
	)
	(segment
		(start 146.007074 -410.030168)
		(end 146.310096 -409.727146)
		(width 0.13208)
		(layer "F.Cu")
		(net "P5E_CPU1_PE3_TX_C_DN<7>")
	)
	(segment
		(start 146.310096 -409.727146)
		(end 146.310096 -409.109164)
		(width 0.13208)
		(layer "F.Cu")
		(net "P5E_CPU1_PE3_TX_C_DN<7>")
	)
	(segment
		(start 146.30654 -410.552138)
		(end 146.30654 -410.329634)
		(width 0.14732)
		(layer "In6.Cu")
		(net "P5E_CPU1_PE3_TX_C_DN<7>")
	)
	(segment
		(start 142.750032 -430.574704)
		(end 142.602458 -430.42713)
		(width 0.14732)
		(layer "In6.Cu")
		(net "P5E_CPU1_PE3_TX_C_DN<7>")
	)
	(segment
		(start 142.602458 -430.42713)
		(end 142.1003 -430.42713)
		(width 0.14732)
		(layer "In6.Cu")
		(net "P5E_CPU1_PE3_TX_C_DN<7>")
	)
	(segment
		(start 142.750032 -430.889918)
		(end 142.750032 -430.574704)
		(width 0.14732)
		(layer "In6.Cu")
		(net "P5E_CPU1_PE3_TX_C_DN<7>")
	)
	(segment
		(start 141.792452 -423.946828)
		(end 146.30654 -410.552138)
		(width 0.14732)
		(layer "In6.Cu")
		(net "P5E_CPU1_PE3_TX_C_DN<7>")
	)
	(segment
		(start 142.1003 -430.42713)
		(end 141.792452 -430.119282)
		(width 0.14732)
		(layer "In6.Cu")
		(net "P5E_CPU1_PE3_TX_C_DN<7>")
	)
	(segment
		(start 146.30654 -410.329634)
		(end 146.007074 -410.030168)
		(width 0.14732)
		(layer "In6.Cu")
		(net "P5E_CPU1_PE3_TX_C_DN<7>")
	)
	(segment
		(start 141.792452 -430.119282)
		(end 141.792452 -423.946828)
		(width 0.14732)
		(layer "In6.Cu")
		(net "P5E_CPU1_PE3_TX_C_DN<7>")
	)
	(segment
		(start 149.070314 -410.030168)
		(end 149.373336 -409.727146)
		(width 0.13208)
		(layer "F.Cu")
		(net "P5E_CPU1_PE3_TX_C_DN<6>")
	)
	(segment
		(start 149.373336 -409.727146)
		(end 149.373336 -409.109164)
		(width 0.13208)
		(layer "F.Cu")
		(net "P5E_CPU1_PE3_TX_C_DN<6>")
	)
	(segment
		(start 149.048216 -408.784044)
		(end 149.044914 -408.784044)
		(width 0.13208)
		(layer "F.Cu")
		(net "P5E_CPU1_PE3_TX_C_DN<6>")
	)
	(segment
		(start 149.373336 -409.109164)
		(end 149.048216 -408.784044)
		(width 0.13208)
		(layer "F.Cu")
		(net "P5E_CPU1_PE3_TX_C_DN<6>")
	)
	(segment
		(start 144.602454 -431.427128)
		(end 144.09166 -431.427128)
		(width 0.14732)
		(layer "In6.Cu")
		(net "P5E_CPU1_PE3_TX_C_DN<6>")
	)
	(segment
		(start 143.792448 -423.964608)
		(end 149.364954 -410.611574)
		(width 0.14732)
		(layer "In6.Cu")
		(net "P5E_CPU1_PE3_TX_C_DN<6>")
	)
	(segment
		(start 149.364954 -410.324808)
		(end 149.070314 -410.030168)
		(width 0.14732)
		(layer "In6.Cu")
		(net "P5E_CPU1_PE3_TX_C_DN<6>")
	)
	(segment
		(start 144.750028 -431.574702)
		(end 144.602454 -431.427128)
		(width 0.14732)
		(layer "In6.Cu")
		(net "P5E_CPU1_PE3_TX_C_DN<6>")
	)
	(segment
		(start 143.792448 -431.127916)
		(end 143.792448 -423.964608)
		(width 0.14732)
		(layer "In6.Cu")
		(net "P5E_CPU1_PE3_TX_C_DN<6>")
	)
	(segment
		(start 144.750028 -431.889916)
		(end 144.750028 -431.574702)
		(width 0.14732)
		(layer "In6.Cu")
		(net "P5E_CPU1_PE3_TX_C_DN<6>")
	)
	(segment
		(start 149.364954 -410.611574)
		(end 149.364954 -410.324808)
		(width 0.14732)
		(layer "In6.Cu")
		(net "P5E_CPU1_PE3_TX_C_DN<6>")
	)
	(segment
		(start 144.09166 -431.427128)
		(end 143.792448 -431.127916)
		(width 0.14732)
		(layer "In6.Cu")
		(net "P5E_CPU1_PE3_TX_C_DN<6>")
	)
	(segment
		(start 152.133554 -410.030168)
		(end 152.436576 -409.727146)
		(width 0.13208)
		(layer "F.Cu")
		(net "P5E_CPU1_PE3_TX_C_DN<5>")
	)
	(segment
		(start 152.111456 -408.784044)
		(end 152.108154 -408.784044)
		(width 0.13208)
		(layer "F.Cu")
		(net "P5E_CPU1_PE3_TX_C_DN<5>")
	)
	(segment
		(start 152.436576 -409.109164)
		(end 152.111456 -408.784044)
		(width 0.13208)
		(layer "F.Cu")
		(net "P5E_CPU1_PE3_TX_C_DN<5>")
	)
	(segment
		(start 152.436576 -409.727146)
		(end 152.436576 -409.109164)
		(width 0.13208)
		(layer "F.Cu")
		(net "P5E_CPU1_PE3_TX_C_DN<5>")
	)
	(segment
		(start 146.60245 -430.42713)
		(end 146.136868 -430.42713)
		(width 0.14732)
		(layer "In6.Cu")
		(net "P5E_CPU1_PE3_TX_C_DN<5>")
	)
	(segment
		(start 152.428194 -410.63672)
		(end 152.428194 -410.324808)
		(width 0.14732)
		(layer "In6.Cu")
		(net "P5E_CPU1_PE3_TX_C_DN<5>")
	)
	(segment
		(start 146.136868 -430.42713)
		(end 145.792444 -430.082706)
		(width 0.14732)
		(layer "In6.Cu")
		(net "P5E_CPU1_PE3_TX_C_DN<5>")
	)
	(segment
		(start 146.750024 -430.574704)
		(end 146.60245 -430.42713)
		(width 0.14732)
		(layer "In6.Cu")
		(net "P5E_CPU1_PE3_TX_C_DN<5>")
	)
	(segment
		(start 145.792444 -430.082706)
		(end 145.792444 -424.216068)
		(width 0.14732)
		(layer "In6.Cu")
		(net "P5E_CPU1_PE3_TX_C_DN<5>")
	)
	(segment
		(start 145.792444 -424.216068)
		(end 152.428194 -410.63672)
		(width 0.14732)
		(layer "In6.Cu")
		(net "P5E_CPU1_PE3_TX_C_DN<5>")
	)
	(segment
		(start 146.750024 -430.889918)
		(end 146.750024 -430.574704)
		(width 0.14732)
		(layer "In6.Cu")
		(net "P5E_CPU1_PE3_TX_C_DN<5>")
	)
	(segment
		(start 152.428194 -410.324808)
		(end 152.133554 -410.030168)
		(width 0.14732)
		(layer "In6.Cu")
		(net "P5E_CPU1_PE3_TX_C_DN<5>")
	)
	(segment
		(start 155.499816 -409.109164)
		(end 155.174696 -408.784044)
		(width 0.13208)
		(layer "F.Cu")
		(net "P5E_CPU1_PE3_TX_C_DN<4>")
	)
	(segment
		(start 155.174696 -408.784044)
		(end 155.171394 -408.784044)
		(width 0.13208)
		(layer "F.Cu")
		(net "P5E_CPU1_PE3_TX_C_DN<4>")
	)
	(segment
		(start 155.499816 -409.727146)
		(end 155.499816 -409.109164)
		(width 0.13208)
		(layer "F.Cu")
		(net "P5E_CPU1_PE3_TX_C_DN<4>")
	)
	(segment
		(start 155.196794 -410.030168)
		(end 155.499816 -409.727146)
		(width 0.13208)
		(layer "F.Cu")
		(net "P5E_CPU1_PE3_TX_C_DN<4>")
	)
	(segment
		(start 148.587206 -431.411888)
		(end 148.21662 -431.411888)
		(width 0.14732)
		(layer "In6.Cu")
		(net "P5E_CPU1_PE3_TX_C_DN<4>")
	)
	(segment
		(start 155.491434 -410.324808)
		(end 155.196794 -410.030168)
		(width 0.14732)
		(layer "In6.Cu")
		(net "P5E_CPU1_PE3_TX_C_DN<4>")
	)
	(segment
		(start 148.75002 -431.889916)
		(end 148.75002 -431.574702)
		(width 0.14732)
		(layer "In6.Cu")
		(net "P5E_CPU1_PE3_TX_C_DN<4>")
	)
	(segment
		(start 148.21662 -431.411888)
		(end 147.79244 -430.987708)
		(width 0.14732)
		(layer "In6.Cu")
		(net "P5E_CPU1_PE3_TX_C_DN<4>")
	)
	(segment
		(start 148.75002 -431.574702)
		(end 148.587206 -431.411888)
		(width 0.14732)
		(layer "In6.Cu")
		(net "P5E_CPU1_PE3_TX_C_DN<4>")
	)
	(segment
		(start 147.79244 -430.987708)
		(end 147.79244 -423.926508)
		(width 0.14732)
		(layer "In6.Cu")
		(net "P5E_CPU1_PE3_TX_C_DN<4>")
	)
	(segment
		(start 147.79244 -423.926508)
		(end 155.491434 -410.672026)
		(width 0.14732)
		(layer "In6.Cu")
		(net "P5E_CPU1_PE3_TX_C_DN<4>")
	)
	(segment
		(start 155.491434 -410.672026)
		(end 155.491434 -410.324808)
		(width 0.14732)
		(layer "In6.Cu")
		(net "P5E_CPU1_PE3_TX_C_DN<4>")
	)
	(segment
		(start 158.563056 -409.109164)
		(end 158.237936 -408.784044)
		(width 0.13208)
		(layer "F.Cu")
		(net "P5E_CPU1_PE3_TX_C_DN<3>")
	)
	(segment
		(start 158.563056 -409.727146)
		(end 158.563056 -409.109164)
		(width 0.13208)
		(layer "F.Cu")
		(net "P5E_CPU1_PE3_TX_C_DN<3>")
	)
	(segment
		(start 158.260034 -410.030168)
		(end 158.563056 -409.727146)
		(width 0.13208)
		(layer "F.Cu")
		(net "P5E_CPU1_PE3_TX_C_DN<3>")
	)
	(segment
		(start 158.237936 -408.784044)
		(end 158.234634 -408.784044)
		(width 0.13208)
		(layer "F.Cu")
		(net "P5E_CPU1_PE3_TX_C_DN<3>")
	)
	(segment
		(start 149.792436 -423.588942)
		(end 158.554674 -410.701236)
		(width 0.14732)
		(layer "In6.Cu")
		(net "P5E_CPU1_PE3_TX_C_DN<3>")
	)
	(segment
		(start 150.100284 -430.42713)
		(end 149.792436 -430.119282)
		(width 0.14732)
		(layer "In6.Cu")
		(net "P5E_CPU1_PE3_TX_C_DN<3>")
	)
	(segment
		(start 150.750016 -430.574704)
		(end 150.602442 -430.42713)
		(width 0.14732)
		(layer "In6.Cu")
		(net "P5E_CPU1_PE3_TX_C_DN<3>")
	)
	(segment
		(start 158.554674 -410.324808)
		(end 158.260034 -410.030168)
		(width 0.14732)
		(layer "In6.Cu")
		(net "P5E_CPU1_PE3_TX_C_DN<3>")
	)
	(segment
		(start 158.554674 -410.701236)
		(end 158.554674 -410.324808)
		(width 0.14732)
		(layer "In6.Cu")
		(net "P5E_CPU1_PE3_TX_C_DN<3>")
	)
	(segment
		(start 150.602442 -430.42713)
		(end 150.100284 -430.42713)
		(width 0.14732)
		(layer "In6.Cu")
		(net "P5E_CPU1_PE3_TX_C_DN<3>")
	)
	(segment
		(start 150.750016 -430.889918)
		(end 150.750016 -430.574704)
		(width 0.14732)
		(layer "In6.Cu")
		(net "P5E_CPU1_PE3_TX_C_DN<3>")
	)
	(segment
		(start 149.792436 -430.119282)
		(end 149.792436 -423.588942)
		(width 0.14732)
		(layer "In6.Cu")
		(net "P5E_CPU1_PE3_TX_C_DN<3>")
	)
	(segment
		(start 161.301176 -408.784044)
		(end 161.297874 -408.784044)
		(width 0.13208)
		(layer "F.Cu")
		(net "P5E_CPU1_PE3_TX_C_DN<2>")
	)
	(segment
		(start 161.626296 -409.109164)
		(end 161.301176 -408.784044)
		(width 0.13208)
		(layer "F.Cu")
		(net "P5E_CPU1_PE3_TX_C_DN<2>")
	)
	(segment
		(start 161.323274 -410.030168)
		(end 161.626296 -409.727146)
		(width 0.13208)
		(layer "F.Cu")
		(net "P5E_CPU1_PE3_TX_C_DN<2>")
	)
	(segment
		(start 161.626296 -409.727146)
		(end 161.626296 -409.109164)
		(width 0.13208)
		(layer "F.Cu")
		(net "P5E_CPU1_PE3_TX_C_DN<2>")
	)
	(segment
		(start 151.792432 -427.18863)
		(end 151.792178 -427.188376)
		(width 0.14732)
		(layer "In6.Cu")
		(net "P5E_CPU1_PE3_TX_C_DN<2>")
	)
	(segment
		(start 151.792178 -423.878502)
		(end 151.930862 -423.466514)
		(width 0.14732)
		(layer "In6.Cu")
		(net "P5E_CPU1_PE3_TX_C_DN<2>")
	)
	(segment
		(start 152.750012 -431.889916)
		(end 152.750012 -431.574702)
		(width 0.14732)
		(layer "In6.Cu")
		(net "P5E_CPU1_PE3_TX_C_DN<2>")
	)
	(segment
		(start 151.792432 -431.1523)
		(end 151.792432 -427.18863)
		(width 0.14732)
		(layer "In6.Cu")
		(net "P5E_CPU1_PE3_TX_C_DN<2>")
	)
	(segment
		(start 151.792178 -427.188376)
		(end 151.792178 -423.878502)
		(width 0.14732)
		(layer "In6.Cu")
		(net "P5E_CPU1_PE3_TX_C_DN<2>")
	)
	(segment
		(start 152.06726 -431.427128)
		(end 151.792432 -431.1523)
		(width 0.14732)
		(layer "In6.Cu")
		(net "P5E_CPU1_PE3_TX_C_DN<2>")
	)
	(segment
		(start 161.617914 -410.713428)
		(end 161.617914 -410.324808)
		(width 0.14732)
		(layer "In6.Cu")
		(net "P5E_CPU1_PE3_TX_C_DN<2>")
	)
	(segment
		(start 152.602438 -431.427128)
		(end 152.06726 -431.427128)
		(width 0.14732)
		(layer "In6.Cu")
		(net "P5E_CPU1_PE3_TX_C_DN<2>")
	)
	(segment
		(start 161.617914 -410.324808)
		(end 161.323274 -410.030168)
		(width 0.14732)
		(layer "In6.Cu")
		(net "P5E_CPU1_PE3_TX_C_DN<2>")
	)
	(segment
		(start 152.750012 -431.574702)
		(end 152.602438 -431.427128)
		(width 0.14732)
		(layer "In6.Cu")
		(net "P5E_CPU1_PE3_TX_C_DN<2>")
	)
	(segment
		(start 151.930862 -423.466514)
		(end 161.617914 -410.713428)
		(width 0.14732)
		(layer "In6.Cu")
		(net "P5E_CPU1_PE3_TX_C_DN<2>")
	)
	(segment
		(start 164.689536 -409.727146)
		(end 164.689536 -409.109164)
		(width 0.13208)
		(layer "F.Cu")
		(net "P5E_CPU1_PE3_TX_C_DN<1>")
	)
	(segment
		(start 164.386514 -410.030168)
		(end 164.689536 -409.727146)
		(width 0.13208)
		(layer "F.Cu")
		(net "P5E_CPU1_PE3_TX_C_DN<1>")
	)
	(segment
		(start 164.689536 -409.109164)
		(end 164.364416 -408.784044)
		(width 0.13208)
		(layer "F.Cu")
		(net "P5E_CPU1_PE3_TX_C_DN<1>")
	)
	(segment
		(start 164.364416 -408.784044)
		(end 164.361114 -408.784044)
		(width 0.13208)
		(layer "F.Cu")
		(net "P5E_CPU1_PE3_TX_C_DN<1>")
	)
	(segment
		(start 154.117294 -430.444148)
		(end 153.792428 -430.119282)
		(width 0.14732)
		(layer "In6.Cu")
		(net "P5E_CPU1_PE3_TX_C_DN<1>")
	)
	(segment
		(start 164.681154 -410.324808)
		(end 164.386514 -410.030168)
		(width 0.14732)
		(layer "In6.Cu")
		(net "P5E_CPU1_PE3_TX_C_DN<1>")
	)
	(segment
		(start 164.681154 -410.808678)
		(end 164.681154 -410.324808)
		(width 0.14732)
		(layer "In6.Cu")
		(net "P5E_CPU1_PE3_TX_C_DN<1>")
	)
	(segment
		(start 154.750008 -430.574704)
		(end 154.619452 -430.444148)
		(width 0.14732)
		(layer "In6.Cu")
		(net "P5E_CPU1_PE3_TX_C_DN<1>")
	)
	(segment
		(start 164.27958 -411.736032)
		(end 164.681154 -410.808678)
		(width 0.14732)
		(layer "In6.Cu")
		(net "P5E_CPU1_PE3_TX_C_DN<1>")
	)
	(segment
		(start 154.619452 -430.444148)
		(end 154.117294 -430.444148)
		(width 0.14732)
		(layer "In6.Cu")
		(net "P5E_CPU1_PE3_TX_C_DN<1>")
	)
	(segment
		(start 154.750008 -430.889918)
		(end 154.750008 -430.574704)
		(width 0.14732)
		(layer "In6.Cu")
		(net "P5E_CPU1_PE3_TX_C_DN<1>")
	)
	(segment
		(start 153.792428 -430.119282)
		(end 153.792428 -424.493944)
		(width 0.14732)
		(layer "In6.Cu")
		(net "P5E_CPU1_PE3_TX_C_DN<1>")
	)
	(segment
		(start 163.922964 -412.558992)
		(end 163.922964 -412.559246)
		(width 0.14732)
		(layer "In6.Cu")
		(net "P5E_CPU1_PE3_TX_C_DN<1>")
	)
	(segment
		(start 153.792428 -424.493944)
		(end 153.976324 -424.007788)
		(width 0.14732)
		(layer "In6.Cu")
		(net "P5E_CPU1_PE3_TX_C_DN<1>")
	)
	(segment
		(start 163.756086 -412.944564)
		(end 163.922964 -412.558992)
		(width 0.14732)
		(layer "In6.Cu")
		(net "P5E_CPU1_PE3_TX_C_DN<1>")
	)
	(segment
		(start 163.922964 -412.559246)
		(end 164.27958 -411.736032)
		(width 0.14732)
		(layer "In6.Cu")
		(net "P5E_CPU1_PE3_TX_C_DN<1>")
	)
	(segment
		(start 153.976324 -424.007788)
		(end 163.756086 -412.944564)
		(width 0.14732)
		(layer "In6.Cu")
		(net "P5E_CPU1_PE3_TX_C_DN<1>")
	)
	(segment
		(start 121.501154 -410.030168)
		(end 121.804176 -409.727146)
		(width 0.13208)
		(layer "F.Cu")
		(net "P5E_CPU1_PE3_TX_C_DN<15>")
	)
	(segment
		(start 121.479056 -408.784044)
		(end 121.475754 -408.784044)
		(width 0.13208)
		(layer "F.Cu")
		(net "P5E_CPU1_PE3_TX_C_DN<15>")
	)
	(segment
		(start 121.804176 -409.109164)
		(end 121.479056 -408.784044)
		(width 0.13208)
		(layer "F.Cu")
		(net "P5E_CPU1_PE3_TX_C_DN<15>")
	)
	(segment
		(start 121.804176 -409.727146)
		(end 121.804176 -409.109164)
		(width 0.13208)
		(layer "F.Cu")
		(net "P5E_CPU1_PE3_TX_C_DN<15>")
	)
	(segment
		(start 125.602492 -430.42713)
		(end 125.264672 -430.42713)
		(width 0.14732)
		(layer "In6.Cu")
		(net "P5E_CPU1_PE3_TX_C_DN<15>")
	)
	(segment
		(start 124.894086 -430.115218)
		(end 121.795794 -412.209488)
		(width 0.14732)
		(layer "In6.Cu")
		(net "P5E_CPU1_PE3_TX_C_DN<15>")
	)
	(segment
		(start 125.264672 -430.42713)
		(end 124.894086 -430.115218)
		(width 0.14732)
		(layer "In6.Cu")
		(net "P5E_CPU1_PE3_TX_C_DN<15>")
	)
	(segment
		(start 121.795794 -412.209488)
		(end 121.795794 -410.324808)
		(width 0.14732)
		(layer "In6.Cu")
		(net "P5E_CPU1_PE3_TX_C_DN<15>")
	)
	(segment
		(start 121.795794 -410.324808)
		(end 121.501154 -410.030168)
		(width 0.14732)
		(layer "In6.Cu")
		(net "P5E_CPU1_PE3_TX_C_DN<15>")
	)
	(segment
		(start 125.750066 -430.889918)
		(end 125.750066 -430.574704)
		(width 0.14732)
		(layer "In6.Cu")
		(net "P5E_CPU1_PE3_TX_C_DN<15>")
	)
	(segment
		(start 125.750066 -430.574704)
		(end 125.602492 -430.42713)
		(width 0.14732)
		(layer "In6.Cu")
		(net "P5E_CPU1_PE3_TX_C_DN<15>")
	)
	(segment
		(start 124.867416 -409.727146)
		(end 124.867416 -409.109164)
		(width 0.13208)
		(layer "F.Cu")
		(net "P5E_CPU1_PE3_TX_C_DN<14>")
	)
	(segment
		(start 124.564394 -410.030168)
		(end 124.867416 -409.727146)
		(width 0.13208)
		(layer "F.Cu")
		(net "P5E_CPU1_PE3_TX_C_DN<14>")
	)
	(segment
		(start 124.867416 -409.109164)
		(end 124.542296 -408.784044)
		(width 0.13208)
		(layer "F.Cu")
		(net "P5E_CPU1_PE3_TX_C_DN<14>")
	)
	(segment
		(start 124.542296 -408.784044)
		(end 124.538994 -408.784044)
		(width 0.13208)
		(layer "F.Cu")
		(net "P5E_CPU1_PE3_TX_C_DN<14>")
	)
	(segment
		(start 127.750062 -431.889916)
		(end 127.750062 -431.574702)
		(width 0.14732)
		(layer "In6.Cu")
		(net "P5E_CPU1_PE3_TX_C_DN<14>")
	)
	(segment
		(start 124.91085 -411.504892)
		(end 124.859034 -411.159706)
		(width 0.14732)
		(layer "In6.Cu")
		(net "P5E_CPU1_PE3_TX_C_DN<14>")
	)
	(segment
		(start 127.602488 -431.427128)
		(end 127.175514 -431.427128)
		(width 0.14732)
		(layer "In6.Cu")
		(net "P5E_CPU1_PE3_TX_C_DN<14>")
	)
	(segment
		(start 127.750062 -431.574702)
		(end 127.602488 -431.427128)
		(width 0.14732)
		(layer "In6.Cu")
		(net "P5E_CPU1_PE3_TX_C_DN<14>")
	)
	(segment
		(start 126.792482 -423.973244)
		(end 124.911104 -411.505146)
		(width 0.14732)
		(layer "In6.Cu")
		(net "P5E_CPU1_PE3_TX_C_DN<14>")
	)
	(segment
		(start 124.859034 -410.324808)
		(end 124.564394 -410.030168)
		(width 0.14732)
		(layer "In6.Cu")
		(net "P5E_CPU1_PE3_TX_C_DN<14>")
	)
	(segment
		(start 126.792482 -431.044096)
		(end 126.792482 -423.973244)
		(width 0.14732)
		(layer "In6.Cu")
		(net "P5E_CPU1_PE3_TX_C_DN<14>")
	)
	(segment
		(start 124.859034 -411.159706)
		(end 124.859034 -410.324808)
		(width 0.14732)
		(layer "In6.Cu")
		(net "P5E_CPU1_PE3_TX_C_DN<14>")
	)
	(segment
		(start 124.911104 -411.505146)
		(end 124.91085 -411.504892)
		(width 0.14732)
		(layer "In6.Cu")
		(net "P5E_CPU1_PE3_TX_C_DN<14>")
	)
	(segment
		(start 127.175514 -431.427128)
		(end 126.792482 -431.044096)
		(width 0.14732)
		(layer "In6.Cu")
		(net "P5E_CPU1_PE3_TX_C_DN<14>")
	)
	(segment
		(start 127.930656 -409.109164)
		(end 127.605536 -408.784044)
		(width 0.13208)
		(layer "F.Cu")
		(net "P5E_CPU1_PE3_TX_C_DN<13>")
	)
	(segment
		(start 127.930656 -409.727146)
		(end 127.930656 -409.109164)
		(width 0.13208)
		(layer "F.Cu")
		(net "P5E_CPU1_PE3_TX_C_DN<13>")
	)
	(segment
		(start 127.627634 -410.030168)
		(end 127.930656 -409.727146)
		(width 0.13208)
		(layer "F.Cu")
		(net "P5E_CPU1_PE3_TX_C_DN<13>")
	)
	(segment
		(start 127.605536 -408.784044)
		(end 127.602234 -408.784044)
		(width 0.13208)
		(layer "F.Cu")
		(net "P5E_CPU1_PE3_TX_C_DN<13>")
	)
	(segment
		(start 129.750058 -430.889918)
		(end 129.750058 -430.574704)
		(width 0.14732)
		(layer "In6.Cu")
		(net "P5E_CPU1_PE3_TX_C_DN<13>")
	)
	(segment
		(start 127.922274 -411.59049)
		(end 127.922274 -410.324808)
		(width 0.14732)
		(layer "In6.Cu")
		(net "P5E_CPU1_PE3_TX_C_DN<13>")
	)
	(segment
		(start 127.922274 -410.324808)
		(end 127.627634 -410.030168)
		(width 0.14732)
		(layer "In6.Cu")
		(net "P5E_CPU1_PE3_TX_C_DN<13>")
	)
	(segment
		(start 128.792478 -430.119282)
		(end 128.792478 -423.911268)
		(width 0.14732)
		(layer "In6.Cu")
		(net "P5E_CPU1_PE3_TX_C_DN<13>")
	)
	(segment
		(start 129.750058 -430.574704)
		(end 129.602484 -430.42713)
		(width 0.14732)
		(layer "In6.Cu")
		(net "P5E_CPU1_PE3_TX_C_DN<13>")
	)
	(segment
		(start 129.602484 -430.42713)
		(end 129.100326 -430.42713)
		(width 0.14732)
		(layer "In6.Cu")
		(net "P5E_CPU1_PE3_TX_C_DN<13>")
	)
	(segment
		(start 128.011936 -412.865062)
		(end 128.01219 -412.865062)
		(width 0.14732)
		(layer "In6.Cu")
		(net "P5E_CPU1_PE3_TX_C_DN<13>")
	)
	(segment
		(start 129.100326 -430.42713)
		(end 128.792478 -430.119282)
		(width 0.14732)
		(layer "In6.Cu")
		(net "P5E_CPU1_PE3_TX_C_DN<13>")
	)
	(segment
		(start 128.01219 -412.865062)
		(end 127.922274 -411.59049)
		(width 0.14732)
		(layer "In6.Cu")
		(net "P5E_CPU1_PE3_TX_C_DN<13>")
	)
	(segment
		(start 128.792478 -423.911268)
		(end 128.011936 -412.865062)
		(width 0.14732)
		(layer "In6.Cu")
		(net "P5E_CPU1_PE3_TX_C_DN<13>")
	)
	(segment
		(start 130.993896 -409.727146)
		(end 130.993896 -409.109164)
		(width 0.13208)
		(layer "F.Cu")
		(net "P5E_CPU1_PE3_TX_C_DN<12>")
	)
	(segment
		(start 130.993896 -409.109164)
		(end 130.668776 -408.784044)
		(width 0.13208)
		(layer "F.Cu")
		(net "P5E_CPU1_PE3_TX_C_DN<12>")
	)
	(segment
		(start 130.690874 -410.030168)
		(end 130.993896 -409.727146)
		(width 0.13208)
		(layer "F.Cu")
		(net "P5E_CPU1_PE3_TX_C_DN<12>")
	)
	(segment
		(start 130.668776 -408.784044)
		(end 130.665474 -408.784044)
		(width 0.13208)
		(layer "F.Cu")
		(net "P5E_CPU1_PE3_TX_C_DN<12>")
	)
	(segment
		(start 130.985514 -410.741368)
		(end 130.985514 -410.324808)
		(width 0.14732)
		(layer "In6.Cu")
		(net "P5E_CPU1_PE3_TX_C_DN<12>")
	)
	(segment
		(start 130.985514 -410.324808)
		(end 130.690874 -410.030168)
		(width 0.14732)
		(layer "In6.Cu")
		(net "P5E_CPU1_PE3_TX_C_DN<12>")
	)
	(segment
		(start 130.792474 -431.132488)
		(end 130.792474 -424.05173)
		(width 0.14732)
		(layer "In6.Cu")
		(net "P5E_CPU1_PE3_TX_C_DN<12>")
	)
	(segment
		(start 131.5847 -431.409348)
		(end 131.069334 -431.409348)
		(width 0.14732)
		(layer "In6.Cu")
		(net "P5E_CPU1_PE3_TX_C_DN<12>")
	)
	(segment
		(start 131.750054 -431.574702)
		(end 131.5847 -431.409348)
		(width 0.14732)
		(layer "In6.Cu")
		(net "P5E_CPU1_PE3_TX_C_DN<12>")
	)
	(segment
		(start 131.069334 -431.409348)
		(end 130.792474 -431.132488)
		(width 0.14732)
		(layer "In6.Cu")
		(net "P5E_CPU1_PE3_TX_C_DN<12>")
	)
	(segment
		(start 130.91414 -411.457902)
		(end 130.985514 -410.741368)
		(width 0.14732)
		(layer "In6.Cu")
		(net "P5E_CPU1_PE3_TX_C_DN<12>")
	)
	(segment
		(start 130.792474 -424.05173)
		(end 130.91414 -411.457902)
		(width 0.14732)
		(layer "In6.Cu")
		(net "P5E_CPU1_PE3_TX_C_DN<12>")
	)
	(segment
		(start 131.750054 -431.889916)
		(end 131.750054 -431.574702)
		(width 0.14732)
		(layer "In6.Cu")
		(net "P5E_CPU1_PE3_TX_C_DN<12>")
	)
	(segment
		(start 133.754114 -410.030168)
		(end 134.057136 -409.727146)
		(width 0.13208)
		(layer "F.Cu")
		(net "P5E_CPU1_PE3_TX_C_DN<11>")
	)
	(segment
		(start 134.057136 -409.727146)
		(end 134.057136 -409.109164)
		(width 0.13208)
		(layer "F.Cu")
		(net "P5E_CPU1_PE3_TX_C_DN<11>")
	)
	(segment
		(start 134.057136 -409.109164)
		(end 133.732016 -408.784044)
		(width 0.13208)
		(layer "F.Cu")
		(net "P5E_CPU1_PE3_TX_C_DN<11>")
	)
	(segment
		(start 133.732016 -408.784044)
		(end 133.728714 -408.784044)
		(width 0.13208)
		(layer "F.Cu")
		(net "P5E_CPU1_PE3_TX_C_DN<11>")
	)
	(segment
		(start 133.75005 -430.889918)
		(end 133.75005 -430.574704)
		(width 0.14732)
		(layer "In6.Cu")
		(net "P5E_CPU1_PE3_TX_C_DN<11>")
	)
	(segment
		(start 133.602476 -430.42713)
		(end 133.100318 -430.42713)
		(width 0.14732)
		(layer "In6.Cu")
		(net "P5E_CPU1_PE3_TX_C_DN<11>")
	)
	(segment
		(start 134.048754 -410.702252)
		(end 134.048754 -410.324808)
		(width 0.14732)
		(layer "In6.Cu")
		(net "P5E_CPU1_PE3_TX_C_DN<11>")
	)
	(segment
		(start 133.975094 -410.99105)
		(end 134.048754 -410.702252)
		(width 0.14732)
		(layer "In6.Cu")
		(net "P5E_CPU1_PE3_TX_C_DN<11>")
	)
	(segment
		(start 132.79247 -430.119282)
		(end 132.79247 -423.934636)
		(width 0.14732)
		(layer "In6.Cu")
		(net "P5E_CPU1_PE3_TX_C_DN<11>")
	)
	(segment
		(start 132.79247 -423.934636)
		(end 133.975094 -410.99105)
		(width 0.14732)
		(layer "In6.Cu")
		(net "P5E_CPU1_PE3_TX_C_DN<11>")
	)
	(segment
		(start 133.75005 -430.574704)
		(end 133.602476 -430.42713)
		(width 0.14732)
		(layer "In6.Cu")
		(net "P5E_CPU1_PE3_TX_C_DN<11>")
	)
	(segment
		(start 133.100318 -430.42713)
		(end 132.79247 -430.119282)
		(width 0.14732)
		(layer "In6.Cu")
		(net "P5E_CPU1_PE3_TX_C_DN<11>")
	)
	(segment
		(start 134.048754 -410.324808)
		(end 133.754114 -410.030168)
		(width 0.14732)
		(layer "In6.Cu")
		(net "P5E_CPU1_PE3_TX_C_DN<11>")
	)
	(segment
		(start 136.817354 -410.030168)
		(end 137.120376 -409.727146)
		(width 0.13208)
		(layer "F.Cu")
		(net "P5E_CPU1_PE3_TX_C_DN<10>")
	)
	(segment
		(start 137.120376 -409.109164)
		(end 136.795256 -408.784044)
		(width 0.13208)
		(layer "F.Cu")
		(net "P5E_CPU1_PE3_TX_C_DN<10>")
	)
	(segment
		(start 137.120376 -409.727146)
		(end 137.120376 -409.109164)
		(width 0.13208)
		(layer "F.Cu")
		(net "P5E_CPU1_PE3_TX_C_DN<10>")
	)
	(segment
		(start 136.795256 -408.784044)
		(end 136.791954 -408.784044)
		(width 0.13208)
		(layer "F.Cu")
		(net "P5E_CPU1_PE3_TX_C_DN<10>")
	)
	(segment
		(start 135.750046 -431.889916)
		(end 135.750046 -431.574702)
		(width 0.14732)
		(layer "In6.Cu")
		(net "P5E_CPU1_PE3_TX_C_DN<10>")
	)
	(segment
		(start 134.792466 -431.11928)
		(end 134.792466 -424.007788)
		(width 0.14732)
		(layer "In6.Cu")
		(net "P5E_CPU1_PE3_TX_C_DN<10>")
	)
	(segment
		(start 137.111994 -410.49702)
		(end 137.111994 -410.324808)
		(width 0.14732)
		(layer "In6.Cu")
		(net "P5E_CPU1_PE3_TX_C_DN<10>")
	)
	(segment
		(start 135.750046 -431.574702)
		(end 135.602472 -431.427128)
		(width 0.14732)
		(layer "In6.Cu")
		(net "P5E_CPU1_PE3_TX_C_DN<10>")
	)
	(segment
		(start 135.100314 -431.427128)
		(end 134.792466 -431.11928)
		(width 0.14732)
		(layer "In6.Cu")
		(net "P5E_CPU1_PE3_TX_C_DN<10>")
	)
	(segment
		(start 137.111994 -410.324808)
		(end 136.817354 -410.030168)
		(width 0.14732)
		(layer "In6.Cu")
		(net "P5E_CPU1_PE3_TX_C_DN<10>")
	)
	(segment
		(start 134.792466 -424.007788)
		(end 137.111994 -410.49702)
		(width 0.14732)
		(layer "In6.Cu")
		(net "P5E_CPU1_PE3_TX_C_DN<10>")
	)
	(segment
		(start 135.602472 -431.427128)
		(end 135.100314 -431.427128)
		(width 0.14732)
		(layer "In6.Cu")
		(net "P5E_CPU1_PE3_TX_C_DN<10>")
	)
	(segment
		(start 168.011856 -409.72867)
		(end 168.011856 -409.110942)
		(width 0.13208)
		(layer "F.Cu")
		(net "P5E_CPU1_PE3_TX_C_DN<0>")
	)
	(segment
		(start 168.011856 -409.110942)
		(end 168.338754 -408.784044)
		(width 0.13208)
		(layer "F.Cu")
		(net "P5E_CPU1_PE3_TX_C_DN<0>")
	)
	(segment
		(start 168.313354 -410.030168)
		(end 168.011856 -409.72867)
		(width 0.13208)
		(layer "F.Cu")
		(net "P5E_CPU1_PE3_TX_C_DN<0>")
	)
	(segment
		(start 157.165802 -422.787826)
		(end 156.915612 -423.05859)
		(width 0.14732)
		(layer "In6.Cu")
		(net "P5E_CPU1_PE3_TX_C_DN<0>")
	)
	(segment
		(start 158.53791 -421.09771)
		(end 158.54553 -421.295322)
		(width 0.14732)
		(layer "In6.Cu")
		(net "P5E_CPU1_PE3_TX_C_DN<0>")
	)
	(segment
		(start 156.336746 -423.47896)
		(end 156.066744 -424.168316)
		(width 0.14732)
		(layer "In6.Cu")
		(net "P5E_CPU1_PE3_TX_C_DN<0>")
	)
	(segment
		(start 158.54553 -421.295322)
		(end 158.29534 -421.566086)
		(width 0.14732)
		(layer "In6.Cu")
		(net "P5E_CPU1_PE3_TX_C_DN<0>")
	)
	(segment
		(start 156.538422 -431.152808)
		(end 156.750004 -430.941226)
		(width 0.14732)
		(layer "In6.Cu")
		(net "P5E_CPU1_PE3_TX_C_DN<0>")
	)
	(segment
		(start 158.097982 -421.57396)
		(end 157.848046 -421.844216)
		(width 0.14732)
		(layer "In6.Cu")
		(net "P5E_CPU1_PE3_TX_C_DN<0>")
	)
	(segment
		(start 156.718254 -423.06621)
		(end 156.336746 -423.47896)
		(width 0.14732)
		(layer "In6.Cu")
		(net "P5E_CPU1_PE3_TX_C_DN<0>")
	)
	(segment
		(start 156.915612 -423.05859)
		(end 156.718254 -423.06621)
		(width 0.14732)
		(layer "In6.Cu")
		(net "P5E_CPU1_PE3_TX_C_DN<0>")
	)
	(segment
		(start 156.214064 -431.152808)
		(end 156.538422 -431.152808)
		(width 0.14732)
		(layer "In6.Cu")
		(net "P5E_CPU1_PE3_TX_C_DN<0>")
	)
	(segment
		(start 157.408118 -422.320212)
		(end 157.158182 -422.590468)
		(width 0.14732)
		(layer "In6.Cu")
		(net "P5E_CPU1_PE3_TX_C_DN<0>")
	)
	(segment
		(start 157.855666 -422.041574)
		(end 157.605476 -422.312338)
		(width 0.14732)
		(layer "In6.Cu")
		(net "P5E_CPU1_PE3_TX_C_DN<0>")
	)
	(segment
		(start 156.750004 -430.941226)
		(end 156.750004 -430.689766)
		(width 0.14732)
		(layer "In6.Cu")
		(net "P5E_CPU1_PE3_TX_C_DN<0>")
	)
	(segment
		(start 158.29534 -421.566086)
		(end 158.097982 -421.57396)
		(width 0.14732)
		(layer "In6.Cu")
		(net "P5E_CPU1_PE3_TX_C_DN<0>")
	)
	(segment
		(start 168.313354 -410.030168)
		(end 168.018714 -410.324808)
		(width 0.14732)
		(layer "In6.Cu")
		(net "P5E_CPU1_PE3_TX_C_DN<0>")
	)
	(segment
		(start 157.605476 -422.312338)
		(end 157.408118 -422.320212)
		(width 0.14732)
		(layer "In6.Cu")
		(net "P5E_CPU1_PE3_TX_C_DN<0>")
	)
	(segment
		(start 161.640774 -417.740846)
		(end 158.53791 -421.09771)
		(width 0.14732)
		(layer "In6.Cu")
		(net "P5E_CPU1_PE3_TX_C_DN<0>")
	)
	(segment
		(start 156.066744 -431.005488)
		(end 156.214064 -431.152808)
		(width 0.14732)
		(layer "In6.Cu")
		(net "P5E_CPU1_PE3_TX_C_DN<0>")
	)
	(segment
		(start 167.19169 -412.672784)
		(end 161.640774 -417.740846)
		(width 0.14732)
		(layer "In6.Cu")
		(net "P5E_CPU1_PE3_TX_C_DN<0>")
	)
	(segment
		(start 168.018714 -410.797248)
		(end 167.19169 -412.672784)
		(width 0.14732)
		(layer "In6.Cu")
		(net "P5E_CPU1_PE3_TX_C_DN<0>")
	)
	(segment
		(start 156.066744 -424.168316)
		(end 156.066744 -431.005488)
		(width 0.14732)
		(layer "In6.Cu")
		(net "P5E_CPU1_PE3_TX_C_DN<0>")
	)
	(segment
		(start 157.848046 -421.844216)
		(end 157.855666 -422.041574)
		(width 0.14732)
		(layer "In6.Cu")
		(net "P5E_CPU1_PE3_TX_C_DN<0>")
	)
	(segment
		(start 168.018714 -410.324808)
		(end 168.018714 -410.797248)
		(width 0.14732)
		(layer "In6.Cu")
		(net "P5E_CPU1_PE3_TX_C_DN<0>")
	)
	(segment
		(start 157.158182 -422.590468)
		(end 157.165802 -422.787826)
		(width 0.14732)
		(layer "In6.Cu")
		(net "P5E_CPU1_PE3_TX_C_DN<0>")
	)
	(segment
		(start 126.317248 -288.381186)
		(end 126.317248 -288.917126)
		(width 0.13208)
		(layer "F.Cu")
		(net "P5E_CPU1_PE3_RX_DP<9>")
	)
	(segment
		(start 137.602468 -437.352694)
		(end 137.750042 -437.20512)
		(width 0.14732)
		(layer "In4.Cu")
		(net "P5E_CPU1_PE3_RX_DP<9>")
	)
	(segment
		(start 137.346944 -422.289732)
		(end 137.189464 -422.409112)
		(width 0.14732)
		(layer "In4.Cu")
		(net "P5E_CPU1_PE3_RX_DP<9>")
	)
	(segment
		(start 126.462282 -294.563038)
		(end 127.134874 -298.37634)
		(width 0.14732)
		(layer "In4.Cu")
		(net "P5E_CPU1_PE3_RX_DP<9>")
	)
	(segment
		(start 138.629136 -411.911292)
		(end 137.415778 -420.760398)
		(width 0.14732)
		(layer "In4.Cu")
		(net "P5E_CPU1_PE3_RX_DP<9>")
	)
	(segment
		(start 137.214102 -437.352694)
		(end 137.602468 -437.352694)
		(width 0.14732)
		(layer "In4.Cu")
		(net "P5E_CPU1_PE3_RX_DP<9>")
	)
	(segment
		(start 126.454408 -290.511992)
		(end 126.454662 -290.512246)
		(width 0.0889)
		(layer "In4.Cu")
		(net "P5E_CPU1_PE3_RX_DP<9>")
	)
	(segment
		(start 126.454408 -290.50107)
		(end 126.454408 -290.511992)
		(width 0.0889)
		(layer "In4.Cu")
		(net "P5E_CPU1_PE3_RX_DP<9>")
	)
	(segment
		(start 126.317248 -288.917126)
		(end 126.158244 -289.218116)
		(width 0.0889)
		(layer "In4.Cu")
		(net "P5E_CPU1_PE3_RX_DP<9>")
	)
	(segment
		(start 153.055066 -372.18747)
		(end 140.634974 -398.977612)
		(width 0.14732)
		(layer "In4.Cu")
		(net "P5E_CPU1_PE3_RX_DP<9>")
	)
	(segment
		(start 140.634974 -398.977612)
		(end 140.634974 -404.596092)
		(width 0.14732)
		(layer "In4.Cu")
		(net "P5E_CPU1_PE3_RX_DP<9>")
	)
	(segment
		(start 137.327386 -421.402256)
		(end 137.277602 -421.767)
		(width 0.14732)
		(layer "In4.Cu")
		(net "P5E_CPU1_PE3_RX_DP<9>")
	)
	(segment
		(start 126.158244 -289.218116)
		(end 126.188216 -289.315144)
		(width 0.0889)
		(layer "In4.Cu")
		(net "P5E_CPU1_PE3_RX_DP<9>")
	)
	(segment
		(start 126.20498 -289.327336)
		(end 126.204726 -289.32759)
		(width 0.0889)
		(layer "In4.Cu")
		(net "P5E_CPU1_PE3_RX_DP<9>")
	)
	(segment
		(start 137.750042 -437.20512)
		(end 137.750042 -436.889906)
		(width 0.14732)
		(layer "In4.Cu")
		(net "P5E_CPU1_PE3_RX_DP<9>")
	)
	(segment
		(start 140.634974 -404.596092)
		(end 138.917934 -406.313132)
		(width 0.14732)
		(layer "In4.Cu")
		(net "P5E_CPU1_PE3_RX_DP<9>")
	)
	(segment
		(start 137.066782 -423.303954)
		(end 137.066782 -437.205374)
		(width 0.14732)
		(layer "In4.Cu")
		(net "P5E_CPU1_PE3_RX_DP<9>")
	)
	(segment
		(start 137.277602 -421.767)
		(end 137.396982 -421.92448)
		(width 0.14732)
		(layer "In4.Cu")
		(net "P5E_CPU1_PE3_RX_DP<9>")
	)
	(segment
		(start 126.412244 -290.458906)
		(end 126.454408 -290.50107)
		(width 0.0889)
		(layer "In4.Cu")
		(net "P5E_CPU1_PE3_RX_DP<9>")
	)
	(segment
		(start 129.422906 -301.643034)
		(end 154.587702 -332.27518)
		(width 0.14732)
		(layer "In4.Cu")
		(net "P5E_CPU1_PE3_RX_DP<9>")
	)
	(segment
		(start 137.535158 -420.917624)
		(end 137.48512 -421.282876)
		(width 0.14732)
		(layer "In4.Cu")
		(net "P5E_CPU1_PE3_RX_DP<9>")
	)
	(segment
		(start 154.587702 -332.27518)
		(end 155.716478 -338.68487)
		(width 0.14732)
		(layer "In4.Cu")
		(net "P5E_CPU1_PE3_RX_DP<9>")
	)
	(segment
		(start 138.917934 -406.313132)
		(end 138.917934 -410.459174)
		(width 0.14732)
		(layer "In4.Cu")
		(net "P5E_CPU1_PE3_RX_DP<9>")
	)
	(segment
		(start 137.48512 -421.282876)
		(end 137.327386 -421.402256)
		(width 0.14732)
		(layer "In4.Cu")
		(net "P5E_CPU1_PE3_RX_DP<9>")
	)
	(segment
		(start 137.415778 -420.760398)
		(end 137.535158 -420.917624)
		(width 0.14732)
		(layer "In4.Cu")
		(net "P5E_CPU1_PE3_RX_DP<9>")
	)
	(segment
		(start 155.716478 -338.68487)
		(end 155.529026 -364.07598)
		(width 0.14732)
		(layer "In4.Cu")
		(net "P5E_CPU1_PE3_RX_DP<9>")
	)
	(segment
		(start 126.454662 -290.512246)
		(end 126.462282 -294.563038)
		(width 0.14732)
		(layer "In4.Cu")
		(net "P5E_CPU1_PE3_RX_DP<9>")
	)
	(segment
		(start 137.396982 -421.92448)
		(end 137.346944 -422.289732)
		(width 0.14732)
		(layer "In4.Cu")
		(net "P5E_CPU1_PE3_RX_DP<9>")
	)
	(segment
		(start 138.917934 -410.459174)
		(end 138.629136 -411.911292)
		(width 0.14732)
		(layer "In4.Cu")
		(net "P5E_CPU1_PE3_RX_DP<9>")
	)
	(segment
		(start 155.529026 -364.07598)
		(end 153.055066 -372.18747)
		(width 0.14732)
		(layer "In4.Cu")
		(net "P5E_CPU1_PE3_RX_DP<9>")
	)
	(segment
		(start 137.189464 -422.409112)
		(end 137.066782 -423.303954)
		(width 0.14732)
		(layer "In4.Cu")
		(net "P5E_CPU1_PE3_RX_DP<9>")
	)
	(segment
		(start 126.412244 -289.610292)
		(end 126.412244 -290.458906)
		(width 0.0889)
		(layer "In4.Cu")
		(net "P5E_CPU1_PE3_RX_DP<9>")
	)
	(segment
		(start 137.066782 -437.205374)
		(end 137.214102 -437.352694)
		(width 0.14732)
		(layer "In4.Cu")
		(net "P5E_CPU1_PE3_RX_DP<9>")
	)
	(segment
		(start 127.134874 -298.37634)
		(end 129.422906 -301.643034)
		(width 0.14732)
		(layer "In4.Cu")
		(net "P5E_CPU1_PE3_RX_DP<9>")
	)
	(arc
		(start 126.204726 -289.32759)
		(mid 126.329654 -289.4534)
		(end 126.412244 -289.610292)
		(width 0.0889)
		(layer "In4.Cu")
		(net "P5E_CPU1_PE3_RX_DP<9>")
	)
	(arc
		(start 126.188216 -289.315144)
		(mid 126.196651 -289.321167)
		(end 126.20498 -289.327336)
		(width 0.0889)
		(layer "In4.Cu")
		(net "P5E_CPU1_PE3_RX_DP<9>")
	)
	(segment
		(start 126.786894 -288.102802)
		(end 126.787148 -288.103056)
		(width 0.13208)
		(layer "F.Cu")
		(net "P5E_CPU1_PE3_RX_DP<8>")
	)
	(segment
		(start 126.786894 -287.567116)
		(end 126.786894 -288.102802)
		(width 0.13208)
		(layer "F.Cu")
		(net "P5E_CPU1_PE3_RX_DP<8>")
	)
	(segment
		(start 141.434312 -412.4706)
		(end 139.066778 -424.428412)
		(width 0.14732)
		(layer "In4.Cu")
		(net "P5E_CPU1_PE3_RX_DP<8>")
	)
	(segment
		(start 155.557982 -331.9907)
		(end 156.76499 -338.844128)
		(width 0.14732)
		(layer "In4.Cu")
		(net "P5E_CPU1_PE3_RX_DP<8>")
	)
	(segment
		(start 141.981174 -406.313132)
		(end 141.981174 -410.665168)
		(width 0.14732)
		(layer "In4.Cu")
		(net "P5E_CPU1_PE3_RX_DP<8>")
	)
	(segment
		(start 139.204954 -438.343548)
		(end 139.5476 -438.343548)
		(width 0.14732)
		(layer "In4.Cu")
		(net "P5E_CPU1_PE3_RX_DP<8>")
	)
	(segment
		(start 153.999438 -372.864126)
		(end 143.698214 -399.180304)
		(width 0.14732)
		(layer "In4.Cu")
		(net "P5E_CPU1_PE3_RX_DP<8>")
	)
	(segment
		(start 127.822198 -288.898584)
		(end 127.822198 -289.114484)
		(width 0.0889)
		(layer "In4.Cu")
		(net "P5E_CPU1_PE3_RX_DP<8>")
	)
	(segment
		(start 128.153668 -297.988482)
		(end 131.21386 -302.357536)
		(width 0.14732)
		(layer "In4.Cu")
		(net "P5E_CPU1_PE3_RX_DP<8>")
	)
	(segment
		(start 139.5476 -438.343548)
		(end 139.750038 -438.14111)
		(width 0.14732)
		(layer "In4.Cu")
		(net "P5E_CPU1_PE3_RX_DP<8>")
	)
	(segment
		(start 126.943612 -288.374074)
		(end 127.032766 -288.39795)
		(width 0.0889)
		(layer "In4.Cu")
		(net "P5E_CPU1_PE3_RX_DP<8>")
	)
	(segment
		(start 127.394208 -290.490148)
		(end 127.394208 -290.512246)
		(width 0.0889)
		(layer "In4.Cu")
		(net "P5E_CPU1_PE3_RX_DP<8>")
	)
	(segment
		(start 156.4894 -364.185962)
		(end 153.999438 -372.864126)
		(width 0.14732)
		(layer "In4.Cu")
		(net "P5E_CPU1_PE3_RX_DP<8>")
	)
	(segment
		(start 131.21386 -302.357536)
		(end 155.557982 -331.9907)
		(width 0.14732)
		(layer "In4.Cu")
		(net "P5E_CPU1_PE3_RX_DP<8>")
	)
	(segment
		(start 126.787148 -288.103056)
		(end 126.943612 -288.374074)
		(width 0.0889)
		(layer "In4.Cu")
		(net "P5E_CPU1_PE3_RX_DP<8>")
	)
	(segment
		(start 127.352044 -290.447984)
		(end 127.394208 -290.490148)
		(width 0.0889)
		(layer "In4.Cu")
		(net "P5E_CPU1_PE3_RX_DP<8>")
	)
	(segment
		(start 141.981174 -410.665168)
		(end 141.434312 -412.4706)
		(width 0.14732)
		(layer "In4.Cu")
		(net "P5E_CPU1_PE3_RX_DP<8>")
	)
	(segment
		(start 127.394462 -293.6748)
		(end 128.153668 -297.988482)
		(width 0.14732)
		(layer "In4.Cu")
		(net "P5E_CPU1_PE3_RX_DP<8>")
	)
	(segment
		(start 143.698214 -399.180304)
		(end 143.698214 -404.596092)
		(width 0.14732)
		(layer "In4.Cu")
		(net "P5E_CPU1_PE3_RX_DP<8>")
	)
	(segment
		(start 127.394208 -290.512246)
		(end 127.394208 -293.674546)
		(width 0.14732)
		(layer "In4.Cu")
		(net "P5E_CPU1_PE3_RX_DP<8>")
	)
	(segment
		(start 139.066524 -438.205118)
		(end 139.204954 -438.343548)
		(width 0.14732)
		(layer "In4.Cu")
		(net "P5E_CPU1_PE3_RX_DP<8>")
	)
	(segment
		(start 139.066778 -424.428412)
		(end 139.066524 -438.205118)
		(width 0.14732)
		(layer "In4.Cu")
		(net "P5E_CPU1_PE3_RX_DP<8>")
	)
	(segment
		(start 127.394208 -293.674546)
		(end 127.394462 -293.6748)
		(width 0.14732)
		(layer "In4.Cu")
		(net "P5E_CPU1_PE3_RX_DP<8>")
	)
	(segment
		(start 143.698214 -404.596092)
		(end 141.981174 -406.313132)
		(width 0.14732)
		(layer "In4.Cu")
		(net "P5E_CPU1_PE3_RX_DP<8>")
	)
	(segment
		(start 139.750038 -438.14111)
		(end 139.750038 -437.889904)
		(width 0.14732)
		(layer "In4.Cu")
		(net "P5E_CPU1_PE3_RX_DP<8>")
	)
	(segment
		(start 156.76499 -338.844128)
		(end 156.4894 -364.185962)
		(width 0.14732)
		(layer "In4.Cu")
		(net "P5E_CPU1_PE3_RX_DP<8>")
	)
	(segment
		(start 127.352044 -289.64636)
		(end 127.352044 -290.447984)
		(width 0.0889)
		(layer "In4.Cu")
		(net "P5E_CPU1_PE3_RX_DP<8>")
	)
	(arc
		(start 127.536448 -289.446462)
		(mid 127.427108 -289.530598)
		(end 127.352044 -289.64636)
		(width 0.0889)
		(layer "In4.Cu")
		(net "P5E_CPU1_PE3_RX_DP<8>")
	)
	(arc
		(start 127.822198 -289.114484)
		(mid 127.710802 -289.307577)
		(end 127.536448 -289.446462)
		(width 0.0889)
		(layer "In4.Cu")
		(net "P5E_CPU1_PE3_RX_DP<8>")
	)
	(arc
		(start 127.052324 -288.389822)
		(mid 127.300304 -288.35321)
		(end 127.53975 -288.427414)
		(width 0.0889)
		(layer "In4.Cu")
		(net "P5E_CPU1_PE3_RX_DP<8>")
	)
	(arc
		(start 127.032766 -288.39795)
		(mid 127.042507 -288.393795)
		(end 127.052324 -288.389822)
		(width 0.0889)
		(layer "In4.Cu")
		(net "P5E_CPU1_PE3_RX_DP<8>")
	)
	(arc
		(start 127.53975 -288.427414)
		(mid 127.742036 -288.626395)
		(end 127.822198 -288.898584)
		(width 0.0889)
		(layer "In4.Cu")
		(net "P5E_CPU1_PE3_RX_DP<8>")
	)
	(segment
		(start 127.726694 -289.195002)
		(end 127.726694 -289.807142)
		(width 0.13208)
		(layer "F.Cu")
		(net "P5E_CPU1_PE3_RX_DP<7>")
	)
	(segment
		(start 127.97028 -289.480244)
		(end 127.885698 -289.506152)
		(width 0.0889)
		(layer "In4.Cu")
		(net "P5E_CPU1_PE3_RX_DP<7>")
	)
	(segment
		(start 144.770094 -410.311346)
		(end 144.770094 -406.19934)
		(width 0.14732)
		(layer "In4.Cu")
		(net "P5E_CPU1_PE3_RX_DP<7>")
	)
	(segment
		(start 127.885698 -289.506152)
		(end 127.726694 -289.807142)
		(width 0.0889)
		(layer "In4.Cu")
		(net "P5E_CPU1_PE3_RX_DP<7>")
	)
	(segment
		(start 142.750032 -438.089802)
		(end 142.750032 -437.774588)
		(width 0.14732)
		(layer "In4.Cu")
		(net "P5E_CPU1_PE3_RX_DP<7>")
	)
	(segment
		(start 128.101344 -290.448238)
		(end 128.101344 -289.64509)
		(width 0.0889)
		(layer "In4.Cu")
		(net "P5E_CPU1_PE3_RX_DP<7>")
	)
	(segment
		(start 127.970534 -289.47999)
		(end 127.97028 -289.480244)
		(width 0.0889)
		(layer "In4.Cu")
		(net "P5E_CPU1_PE3_RX_DP<7>")
	)
	(segment
		(start 156.214064 -331.750162)
		(end 131.790186 -302.020224)
		(width 0.14732)
		(layer "In4.Cu")
		(net "P5E_CPU1_PE3_RX_DP<7>")
	)
	(segment
		(start 157.16504 -364.209584)
		(end 157.539944 -339.276436)
		(width 0.14732)
		(layer "In4.Cu")
		(net "P5E_CPU1_PE3_RX_DP<7>")
	)
	(segment
		(start 142.602458 -437.627014)
		(end 142.1003 -437.627014)
		(width 0.14732)
		(layer "In4.Cu")
		(net "P5E_CPU1_PE3_RX_DP<7>")
	)
	(segment
		(start 128.059434 -290.512246)
		(end 128.059434 -290.490148)
		(width 0.0889)
		(layer "In4.Cu")
		(net "P5E_CPU1_PE3_RX_DP<7>")
	)
	(segment
		(start 142.750032 -437.774588)
		(end 142.602458 -437.627014)
		(width 0.14732)
		(layer "In4.Cu")
		(net "P5E_CPU1_PE3_RX_DP<7>")
	)
	(segment
		(start 142.1003 -437.627014)
		(end 141.792452 -437.319166)
		(width 0.14732)
		(layer "In4.Cu")
		(net "P5E_CPU1_PE3_RX_DP<7>")
	)
	(segment
		(start 131.790186 -302.020224)
		(end 128.85547 -297.83024)
		(width 0.14732)
		(layer "In4.Cu")
		(net "P5E_CPU1_PE3_RX_DP<7>")
	)
	(segment
		(start 128.059434 -290.490148)
		(end 128.101344 -290.448238)
		(width 0.0889)
		(layer "In4.Cu")
		(net "P5E_CPU1_PE3_RX_DP<7>")
	)
	(segment
		(start 141.792452 -437.319166)
		(end 141.792452 -424.428666)
		(width 0.14732)
		(layer "In4.Cu")
		(net "P5E_CPU1_PE3_RX_DP<7>")
	)
	(segment
		(start 146.487134 -399.236184)
		(end 154.571446 -374.225058)
		(width 0.14732)
		(layer "In4.Cu")
		(net "P5E_CPU1_PE3_RX_DP<7>")
	)
	(segment
		(start 154.571446 -374.225058)
		(end 157.16504 -364.209584)
		(width 0.14732)
		(layer "In4.Cu")
		(net "P5E_CPU1_PE3_RX_DP<7>")
	)
	(segment
		(start 141.792452 -424.428666)
		(end 144.770094 -410.311346)
		(width 0.14732)
		(layer "In4.Cu")
		(net "P5E_CPU1_PE3_RX_DP<7>")
	)
	(segment
		(start 146.487134 -404.4823)
		(end 146.487134 -399.236184)
		(width 0.14732)
		(layer "In4.Cu")
		(net "P5E_CPU1_PE3_RX_DP<7>")
	)
	(segment
		(start 144.770094 -406.19934)
		(end 146.487134 -404.4823)
		(width 0.14732)
		(layer "In4.Cu")
		(net "P5E_CPU1_PE3_RX_DP<7>")
	)
	(segment
		(start 128.85547 -297.83024)
		(end 128.059434 -293.310818)
		(width 0.14732)
		(layer "In4.Cu")
		(net "P5E_CPU1_PE3_RX_DP<7>")
	)
	(segment
		(start 157.539944 -339.276436)
		(end 156.214064 -331.750162)
		(width 0.14732)
		(layer "In4.Cu")
		(net "P5E_CPU1_PE3_RX_DP<7>")
	)
	(segment
		(start 128.059434 -293.310818)
		(end 128.059434 -290.512246)
		(width 0.14732)
		(layer "In4.Cu")
		(net "P5E_CPU1_PE3_RX_DP<7>")
	)
	(arc
		(start 128.101344 -289.64509)
		(mid 128.04677 -289.55396)
		(end 127.970534 -289.47999)
		(width 0.0889)
		(layer "In4.Cu")
		(net "P5E_CPU1_PE3_RX_DP<7>")
	)
	(segment
		(start 129.136648 -288.381186)
		(end 129.136648 -288.917126)
		(width 0.13208)
		(layer "F.Cu")
		(net "P5E_CPU1_PE3_RX_DP<6>")
	)
	(segment
		(start 129.326894 -289.278314)
		(end 129.326894 -289.277806)
		(width 0.0889)
		(layer "In4.Cu")
		(net "P5E_CPU1_PE3_RX_DP<6>")
	)
	(segment
		(start 157.126686 -331.392022)
		(end 132.594604 -301.530258)
		(width 0.14732)
		(layer "In4.Cu")
		(net "P5E_CPU1_PE3_RX_DP<6>")
	)
	(segment
		(start 128.999488 -292.918896)
		(end 128.999488 -290.512246)
		(width 0.14732)
		(layer "In4.Cu")
		(net "P5E_CPU1_PE3_RX_DP<6>")
	)
	(segment
		(start 144.750028 -438.774586)
		(end 144.602454 -438.627012)
		(width 0.14732)
		(layer "In4.Cu")
		(net "P5E_CPU1_PE3_RX_DP<6>")
	)
	(segment
		(start 128.999488 -290.490148)
		(end 129.041398 -290.448238)
		(width 0.0889)
		(layer "In4.Cu")
		(net "P5E_CPU1_PE3_RX_DP<6>")
	)
	(segment
		(start 158.575756 -339.619844)
		(end 157.126686 -331.392022)
		(width 0.14732)
		(layer "In4.Cu")
		(net "P5E_CPU1_PE3_RX_DP<6>")
	)
	(segment
		(start 145.727928 -417.499038)
		(end 147.833334 -410.32303)
		(width 0.14732)
		(layer "In4.Cu")
		(net "P5E_CPU1_PE3_RX_DP<6>")
	)
	(segment
		(start 129.041398 -290.448238)
		(end 129.041398 -289.611054)
		(width 0.0889)
		(layer "In4.Cu")
		(net "P5E_CPU1_PE3_RX_DP<6>")
	)
	(segment
		(start 145.545048 -418.121592)
		(end 145.450306 -417.94811)
		(width 0.14732)
		(layer "In4.Cu")
		(net "P5E_CPU1_PE3_RX_DP<6>")
	)
	(segment
		(start 143.792448 -438.319164)
		(end 143.792448 -424.095164)
		(width 0.14732)
		(layer "In4.Cu")
		(net "P5E_CPU1_PE3_RX_DP<6>")
	)
	(segment
		(start 132.594604 -301.530258)
		(end 129.818892 -297.567096)
		(width 0.14732)
		(layer "In4.Cu")
		(net "P5E_CPU1_PE3_RX_DP<6>")
	)
	(segment
		(start 149.550374 -404.4823)
		(end 149.550374 -399.135092)
		(width 0.14732)
		(layer "In4.Cu")
		(net "P5E_CPU1_PE3_RX_DP<6>")
	)
	(segment
		(start 144.602454 -438.627012)
		(end 144.100296 -438.627012)
		(width 0.14732)
		(layer "In4.Cu")
		(net "P5E_CPU1_PE3_RX_DP<6>")
	)
	(segment
		(start 129.001266 -288.56813)
		(end 128.980184 -288.646108)
		(width 0.0889)
		(layer "In4.Cu")
		(net "P5E_CPU1_PE3_RX_DP<6>")
	)
	(segment
		(start 158.119826 -364.248446)
		(end 158.575756 -339.619844)
		(width 0.14732)
		(layer "In4.Cu")
		(net "P5E_CPU1_PE3_RX_DP<6>")
	)
	(segment
		(start 129.818892 -297.567096)
		(end 128.999488 -292.918896)
		(width 0.14732)
		(layer "In4.Cu")
		(net "P5E_CPU1_PE3_RX_DP<6>")
	)
	(segment
		(start 128.980184 -288.646108)
		(end 129.136648 -288.917126)
		(width 0.0889)
		(layer "In4.Cu")
		(net "P5E_CPU1_PE3_RX_DP<6>")
	)
	(segment
		(start 129.511298 -289.077908)
		(end 129.511298 -288.917126)
		(width 0.0889)
		(layer "In4.Cu")
		(net "P5E_CPU1_PE3_RX_DP<6>")
	)
	(segment
		(start 128.999488 -290.512246)
		(end 128.999488 -290.490148)
		(width 0.0889)
		(layer "In4.Cu")
		(net "P5E_CPU1_PE3_RX_DP<6>")
	)
	(segment
		(start 143.792448 -424.095164)
		(end 145.545048 -418.121592)
		(width 0.14732)
		(layer "In4.Cu")
		(net "P5E_CPU1_PE3_RX_DP<6>")
	)
	(segment
		(start 147.833334 -406.19934)
		(end 149.550374 -404.4823)
		(width 0.14732)
		(layer "In4.Cu")
		(net "P5E_CPU1_PE3_RX_DP<6>")
	)
	(segment
		(start 149.550374 -399.135092)
		(end 158.119826 -364.248446)
		(width 0.14732)
		(layer "In4.Cu")
		(net "P5E_CPU1_PE3_RX_DP<6>")
	)
	(segment
		(start 144.750028 -439.0898)
		(end 144.750028 -438.774586)
		(width 0.14732)
		(layer "In4.Cu")
		(net "P5E_CPU1_PE3_RX_DP<6>")
	)
	(segment
		(start 147.833334 -410.32303)
		(end 147.833334 -406.19934)
		(width 0.14732)
		(layer "In4.Cu")
		(net "P5E_CPU1_PE3_RX_DP<6>")
	)
	(segment
		(start 145.553938 -417.594542)
		(end 145.727674 -417.4998)
		(width 0.14732)
		(layer "In4.Cu")
		(net "P5E_CPU1_PE3_RX_DP<6>")
	)
	(segment
		(start 145.727674 -417.4998)
		(end 145.727928 -417.499038)
		(width 0.14732)
		(layer "In4.Cu")
		(net "P5E_CPU1_PE3_RX_DP<6>")
	)
	(segment
		(start 129.332736 -288.597848)
		(end 129.323846 -288.592768)
		(width 0.0889)
		(layer "In4.Cu")
		(net "P5E_CPU1_PE3_RX_DP<6>")
	)
	(segment
		(start 145.450306 -417.94811)
		(end 145.553938 -417.594542)
		(width 0.14732)
		(layer "In4.Cu")
		(net "P5E_CPU1_PE3_RX_DP<6>")
	)
	(segment
		(start 144.100296 -438.627012)
		(end 143.792448 -438.319164)
		(width 0.14732)
		(layer "In4.Cu")
		(net "P5E_CPU1_PE3_RX_DP<6>")
	)
	(arc
		(start 129.323846 -288.592768)
		(mid 129.165358 -288.543835)
		(end 129.001266 -288.56813)
		(width 0.0889)
		(layer "In4.Cu")
		(net "P5E_CPU1_PE3_RX_DP<6>")
	)
	(arc
		(start 129.041398 -289.611054)
		(mid 129.152544 -289.417569)
		(end 129.326894 -289.278314)
		(width 0.0889)
		(layer "In4.Cu")
		(net "P5E_CPU1_PE3_RX_DP<6>")
	)
	(arc
		(start 129.511298 -288.917126)
		(mid 129.463619 -288.734226)
		(end 129.332736 -288.597848)
		(width 0.0889)
		(layer "In4.Cu")
		(net "P5E_CPU1_PE3_RX_DP<6>")
	)
	(arc
		(start 129.326894 -289.277806)
		(mid 129.43629 -289.193709)
		(end 129.511298 -289.077908)
		(width 0.0889)
		(layer "In4.Cu")
		(net "P5E_CPU1_PE3_RX_DP<6>")
	)
	(segment
		(start 129.606294 -289.195002)
		(end 129.606294 -289.807142)
		(width 0.13208)
		(layer "F.Cu")
		(net "P5E_CPU1_PE3_RX_DP<5>")
	)
	(segment
		(start 150.896574 -406.19934)
		(end 152.613614 -404.4823)
		(width 0.14732)
		(layer "In4.Cu")
		(net "P5E_CPU1_PE3_RX_DP<5>")
	)
	(segment
		(start 129.765298 -289.506152)
		(end 129.606294 -289.807142)
		(width 0.0889)
		(layer "In4.Cu")
		(net "P5E_CPU1_PE3_RX_DP<5>")
	)
	(segment
		(start 145.792444 -424.770042)
		(end 145.79219 -424.232578)
		(width 0.14732)
		(layer "In4.Cu")
		(net "P5E_CPU1_PE3_RX_DP<5>")
	)
	(segment
		(start 129.939034 -291.183568)
		(end 129.980944 -291.141658)
		(width 0.0889)
		(layer "In4.Cu")
		(net "P5E_CPU1_PE3_RX_DP<5>")
	)
	(segment
		(start 134.694422 -295.060878)
		(end 133.215634 -295.060878)
		(width 0.14732)
		(layer "In4.Cu")
		(net "P5E_CPU1_PE3_RX_DP<5>")
	)
	(segment
		(start 153.902918 -325.735442)
		(end 135.443976 -295.810432)
		(width 0.14732)
		(layer "In4.Cu")
		(net "P5E_CPU1_PE3_RX_DP<5>")
	)
	(segment
		(start 158.070296 -331.087222)
		(end 153.902918 -325.735442)
		(width 0.14732)
		(layer "In4.Cu")
		(net "P5E_CPU1_PE3_RX_DP<5>")
	)
	(segment
		(start 133.215634 -295.060878)
		(end 129.93878 -291.784024)
		(width 0.14732)
		(layer "In4.Cu")
		(net "P5E_CPU1_PE3_RX_DP<5>")
	)
	(segment
		(start 146.750024 -437.774588)
		(end 146.60245 -437.627014)
		(width 0.14732)
		(layer "In4.Cu")
		(net "P5E_CPU1_PE3_RX_DP<5>")
	)
	(segment
		(start 159.635698 -339.996018)
		(end 158.070296 -331.087222)
		(width 0.14732)
		(layer "In4.Cu")
		(net "P5E_CPU1_PE3_RX_DP<5>")
	)
	(segment
		(start 129.93878 -291.379148)
		(end 129.939034 -291.378894)
		(width 0.14732)
		(layer "In4.Cu")
		(net "P5E_CPU1_PE3_RX_DP<5>")
	)
	(segment
		(start 129.939034 -291.378894)
		(end 129.939034 -291.205666)
		(width 0.14732)
		(layer "In4.Cu")
		(net "P5E_CPU1_PE3_RX_DP<5>")
	)
	(segment
		(start 150.896574 -410.318966)
		(end 150.896574 -406.19934)
		(width 0.14732)
		(layer "In4.Cu")
		(net "P5E_CPU1_PE3_RX_DP<5>")
	)
	(segment
		(start 146.750024 -438.089802)
		(end 146.750024 -437.774588)
		(width 0.14732)
		(layer "In4.Cu")
		(net "P5E_CPU1_PE3_RX_DP<5>")
	)
	(segment
		(start 135.443976 -295.810432)
		(end 134.694422 -295.060878)
		(width 0.14732)
		(layer "In4.Cu")
		(net "P5E_CPU1_PE3_RX_DP<5>")
	)
	(segment
		(start 145.792444 -437.319166)
		(end 145.792444 -424.770042)
		(width 0.14732)
		(layer "In4.Cu")
		(net "P5E_CPU1_PE3_RX_DP<5>")
	)
	(segment
		(start 145.79219 -424.232578)
		(end 145.79219 -424.034458)
		(width 0.14732)
		(layer "In4.Cu")
		(net "P5E_CPU1_PE3_RX_DP<5>")
	)
	(segment
		(start 146.60245 -437.627014)
		(end 146.100292 -437.627014)
		(width 0.14732)
		(layer "In4.Cu")
		(net "P5E_CPU1_PE3_RX_DP<5>")
	)
	(segment
		(start 145.79219 -424.034458)
		(end 150.896574 -410.318966)
		(width 0.14732)
		(layer "In4.Cu")
		(net "P5E_CPU1_PE3_RX_DP<5>")
	)
	(segment
		(start 146.100292 -437.627014)
		(end 145.792444 -437.319166)
		(width 0.14732)
		(layer "In4.Cu")
		(net "P5E_CPU1_PE3_RX_DP<5>")
	)
	(segment
		(start 129.980944 -291.141658)
		(end 129.980944 -289.645852)
		(width 0.0889)
		(layer "In4.Cu")
		(net "P5E_CPU1_PE3_RX_DP<5>")
	)
	(segment
		(start 129.939034 -291.205666)
		(end 129.939034 -291.183568)
		(width 0.0889)
		(layer "In4.Cu")
		(net "P5E_CPU1_PE3_RX_DP<5>")
	)
	(segment
		(start 152.613614 -398.65808)
		(end 159.072326 -364.275878)
		(width 0.14732)
		(layer "In4.Cu")
		(net "P5E_CPU1_PE3_RX_DP<5>")
	)
	(segment
		(start 129.93878 -291.784024)
		(end 129.93878 -291.379148)
		(width 0.14732)
		(layer "In4.Cu")
		(net "P5E_CPU1_PE3_RX_DP<5>")
	)
	(segment
		(start 159.072326 -364.275878)
		(end 159.635698 -339.996018)
		(width 0.14732)
		(layer "In4.Cu")
		(net "P5E_CPU1_PE3_RX_DP<5>")
	)
	(segment
		(start 152.613614 -404.4823)
		(end 152.613614 -398.65808)
		(width 0.14732)
		(layer "In4.Cu")
		(net "P5E_CPU1_PE3_RX_DP<5>")
	)
	(segment
		(start 129.84988 -289.480244)
		(end 129.765298 -289.506152)
		(width 0.0889)
		(layer "In4.Cu")
		(net "P5E_CPU1_PE3_RX_DP<5>")
	)
	(arc
		(start 129.980944 -289.645852)
		(mid 129.926293 -289.554442)
		(end 129.84988 -289.480244)
		(width 0.0889)
		(layer "In4.Cu")
		(net "P5E_CPU1_PE3_RX_DP<5>")
	)
	(segment
		(start 131.016248 -288.381186)
		(end 131.016248 -288.917126)
		(width 0.13208)
		(layer "F.Cu")
		(net "P5E_CPU1_PE3_RX_DP<4>")
	)
	(segment
		(start 135.082788 -294.12438)
		(end 133.7056 -294.12438)
		(width 0.14732)
		(layer "In4.Cu")
		(net "P5E_CPU1_PE3_RX_DP<4>")
	)
	(segment
		(start 130.878834 -291.297614)
		(end 130.878834 -290.723828)
		(width 0.14732)
		(layer "In4.Cu")
		(net "P5E_CPU1_PE3_RX_DP<4>")
	)
	(segment
		(start 148.602446 -438.627012)
		(end 148.100288 -438.627012)
		(width 0.14732)
		(layer "In4.Cu")
		(net "P5E_CPU1_PE3_RX_DP<4>")
	)
	(segment
		(start 130.920998 -290.504118)
		(end 130.920998 -289.611054)
		(width 0.0889)
		(layer "In4.Cu")
		(net "P5E_CPU1_PE3_RX_DP<4>")
	)
	(segment
		(start 130.879088 -290.568126)
		(end 130.879088 -290.546028)
		(width 0.0889)
		(layer "In4.Cu")
		(net "P5E_CPU1_PE3_RX_DP<4>")
	)
	(segment
		(start 130.878834 -290.723828)
		(end 130.879088 -290.723574)
		(width 0.14732)
		(layer "In4.Cu")
		(net "P5E_CPU1_PE3_RX_DP<4>")
	)
	(segment
		(start 147.79244 -424.069256)
		(end 153.959814 -410.784548)
		(width 0.14732)
		(layer "In4.Cu")
		(net "P5E_CPU1_PE3_RX_DP<4>")
	)
	(segment
		(start 130.879088 -290.723574)
		(end 130.879088 -290.568126)
		(width 0.14732)
		(layer "In4.Cu")
		(net "P5E_CPU1_PE3_RX_DP<4>")
	)
	(segment
		(start 148.75002 -439.0898)
		(end 148.75002 -438.774586)
		(width 0.14732)
		(layer "In4.Cu")
		(net "P5E_CPU1_PE3_RX_DP<4>")
	)
	(segment
		(start 155.676854 -397.512794)
		(end 160.147254 -364.361222)
		(width 0.14732)
		(layer "In4.Cu")
		(net "P5E_CPU1_PE3_RX_DP<4>")
	)
	(segment
		(start 131.206494 -289.278314)
		(end 131.206494 -289.277806)
		(width 0.0889)
		(layer "In4.Cu")
		(net "P5E_CPU1_PE3_RX_DP<4>")
	)
	(segment
		(start 131.390898 -289.077908)
		(end 131.390898 -288.917126)
		(width 0.0889)
		(layer "In4.Cu")
		(net "P5E_CPU1_PE3_RX_DP<4>")
	)
	(segment
		(start 160.652968 -340.37651)
		(end 158.953962 -330.704444)
		(width 0.14732)
		(layer "In4.Cu")
		(net "P5E_CPU1_PE3_RX_DP<4>")
	)
	(segment
		(start 153.959814 -410.784548)
		(end 153.959814 -406.19934)
		(width 0.14732)
		(layer "In4.Cu")
		(net "P5E_CPU1_PE3_RX_DP<4>")
	)
	(segment
		(start 154.801824 -325.371714)
		(end 136.226804 -295.268396)
		(width 0.14732)
		(layer "In4.Cu")
		(net "P5E_CPU1_PE3_RX_DP<4>")
	)
	(segment
		(start 130.880866 -288.56813)
		(end 130.859784 -288.646108)
		(width 0.0889)
		(layer "In4.Cu")
		(net "P5E_CPU1_PE3_RX_DP<4>")
	)
	(segment
		(start 136.226804 -295.268396)
		(end 135.082788 -294.12438)
		(width 0.14732)
		(layer "In4.Cu")
		(net "P5E_CPU1_PE3_RX_DP<4>")
	)
	(segment
		(start 147.79244 -438.319164)
		(end 147.79244 -424.069256)
		(width 0.14732)
		(layer "In4.Cu")
		(net "P5E_CPU1_PE3_RX_DP<4>")
	)
	(segment
		(start 131.212336 -288.597848)
		(end 131.203446 -288.592768)
		(width 0.0889)
		(layer "In4.Cu")
		(net "P5E_CPU1_PE3_RX_DP<4>")
	)
	(segment
		(start 148.75002 -438.774586)
		(end 148.602446 -438.627012)
		(width 0.14732)
		(layer "In4.Cu")
		(net "P5E_CPU1_PE3_RX_DP<4>")
	)
	(segment
		(start 130.879088 -290.546028)
		(end 130.920998 -290.504118)
		(width 0.0889)
		(layer "In4.Cu")
		(net "P5E_CPU1_PE3_RX_DP<4>")
	)
	(segment
		(start 158.953962 -330.704444)
		(end 154.801824 -325.371714)
		(width 0.14732)
		(layer "In4.Cu")
		(net "P5E_CPU1_PE3_RX_DP<4>")
	)
	(segment
		(start 148.100288 -438.627012)
		(end 147.79244 -438.319164)
		(width 0.14732)
		(layer "In4.Cu")
		(net "P5E_CPU1_PE3_RX_DP<4>")
	)
	(segment
		(start 155.676854 -404.4823)
		(end 155.676854 -397.512794)
		(width 0.14732)
		(layer "In4.Cu")
		(net "P5E_CPU1_PE3_RX_DP<4>")
	)
	(segment
		(start 133.7056 -294.12438)
		(end 130.878834 -291.297614)
		(width 0.14732)
		(layer "In4.Cu")
		(net "P5E_CPU1_PE3_RX_DP<4>")
	)
	(segment
		(start 153.959814 -406.19934)
		(end 155.676854 -404.4823)
		(width 0.14732)
		(layer "In4.Cu")
		(net "P5E_CPU1_PE3_RX_DP<4>")
	)
	(segment
		(start 130.859784 -288.646108)
		(end 131.016248 -288.917126)
		(width 0.0889)
		(layer "In4.Cu")
		(net "P5E_CPU1_PE3_RX_DP<4>")
	)
	(segment
		(start 160.147254 -364.361222)
		(end 160.652968 -340.37651)
		(width 0.14732)
		(layer "In4.Cu")
		(net "P5E_CPU1_PE3_RX_DP<4>")
	)
	(arc
		(start 130.920998 -289.611054)
		(mid 131.032144 -289.417569)
		(end 131.206494 -289.278314)
		(width 0.0889)
		(layer "In4.Cu")
		(net "P5E_CPU1_PE3_RX_DP<4>")
	)
	(arc
		(start 131.206494 -289.277806)
		(mid 131.31589 -289.193709)
		(end 131.390898 -289.077908)
		(width 0.0889)
		(layer "In4.Cu")
		(net "P5E_CPU1_PE3_RX_DP<4>")
	)
	(arc
		(start 131.390898 -288.917126)
		(mid 131.343219 -288.734226)
		(end 131.212336 -288.597848)
		(width 0.0889)
		(layer "In4.Cu")
		(net "P5E_CPU1_PE3_RX_DP<4>")
	)
	(arc
		(start 131.203446 -288.592768)
		(mid 131.044958 -288.543835)
		(end 130.880866 -288.56813)
		(width 0.0889)
		(layer "In4.Cu")
		(net "P5E_CPU1_PE3_RX_DP<4>")
	)
	(segment
		(start 131.956048 -288.381186)
		(end 131.956048 -288.917126)
		(width 0.13208)
		(layer "F.Cu")
		(net "P5E_CPU1_PE3_RX_DP<3>")
	)
	(segment
		(start 132.200904 -290.652708)
		(end 132.200904 -290.674806)
		(width 0.0889)
		(layer "In4.Cu")
		(net "P5E_CPU1_PE3_RX_DP<3>")
	)
	(segment
		(start 132.051044 -289.60953)
		(end 132.051044 -290.142422)
		(width 0.0889)
		(layer "In4.Cu")
		(net "P5E_CPU1_PE3_RX_DP<3>")
	)
	(segment
		(start 151.67737 -421.669464)
		(end 151.488648 -421.7289)
		(width 0.14732)
		(layer "In4.Cu")
		(net "P5E_CPU1_PE3_RX_DP<3>")
	)
	(segment
		(start 132.200904 -290.886388)
		(end 134.189724 -292.875208)
		(width 0.14732)
		(layer "In4.Cu")
		(net "P5E_CPU1_PE3_RX_DP<3>")
	)
	(segment
		(start 151.318976 -422.055544)
		(end 151.378666 -422.244012)
		(width 0.14732)
		(layer "In4.Cu")
		(net "P5E_CPU1_PE3_RX_DP<3>")
	)
	(segment
		(start 157.297374 -410.55925)
		(end 151.78786 -421.154098)
		(width 0.14732)
		(layer "In4.Cu")
		(net "P5E_CPU1_PE3_RX_DP<3>")
	)
	(segment
		(start 150.750016 -437.20512)
		(end 150.750016 -436.889906)
		(width 0.14732)
		(layer "In4.Cu")
		(net "P5E_CPU1_PE3_RX_DP<3>")
	)
	(segment
		(start 161.594292 -364.96117)
		(end 159.014414 -400.711924)
		(width 0.14732)
		(layer "In4.Cu")
		(net "P5E_CPU1_PE3_RX_DP<3>")
	)
	(segment
		(start 150.214076 -437.352694)
		(end 150.602442 -437.352694)
		(width 0.14732)
		(layer "In4.Cu")
		(net "P5E_CPU1_PE3_RX_DP<3>")
	)
	(segment
		(start 132.200904 -290.674806)
		(end 132.200904 -290.886388)
		(width 0.14732)
		(layer "In4.Cu")
		(net "P5E_CPU1_PE3_RX_DP<3>")
	)
	(segment
		(start 151.78786 -421.154098)
		(end 151.847296 -421.342312)
		(width 0.14732)
		(layer "In4.Cu")
		(net "P5E_CPU1_PE3_RX_DP<3>")
	)
	(segment
		(start 151.20874 -422.571164)
		(end 151.020018 -422.6306)
		(width 0.14732)
		(layer "In4.Cu")
		(net "P5E_CPU1_PE3_RX_DP<3>")
	)
	(segment
		(start 157.297374 -406.313132)
		(end 157.297374 -410.55925)
		(width 0.14732)
		(layer "In4.Cu")
		(net "P5E_CPU1_PE3_RX_DP<3>")
	)
	(segment
		(start 150.066502 -424.464226)
		(end 150.066756 -424.46448)
		(width 0.14732)
		(layer "In4.Cu")
		(net "P5E_CPU1_PE3_RX_DP<3>")
	)
	(segment
		(start 151.488648 -421.7289)
		(end 151.318976 -422.055544)
		(width 0.14732)
		(layer "In4.Cu")
		(net "P5E_CPU1_PE3_RX_DP<3>")
	)
	(segment
		(start 151.847296 -421.342312)
		(end 151.67737 -421.669464)
		(width 0.14732)
		(layer "In4.Cu")
		(net "P5E_CPU1_PE3_RX_DP<3>")
	)
	(segment
		(start 132.15874 -290.610544)
		(end 132.200904 -290.652708)
		(width 0.0889)
		(layer "In4.Cu")
		(net "P5E_CPU1_PE3_RX_DP<3>")
	)
	(segment
		(start 150.066756 -424.46448)
		(end 150.066756 -437.205374)
		(width 0.14732)
		(layer "In4.Cu")
		(net "P5E_CPU1_PE3_RX_DP<3>")
	)
	(segment
		(start 135.574532 -292.875208)
		(end 137.25271 -294.553132)
		(width 0.14732)
		(layer "In4.Cu")
		(net "P5E_CPU1_PE3_RX_DP<3>")
	)
	(segment
		(start 150.602442 -437.352694)
		(end 150.750016 -437.20512)
		(width 0.14732)
		(layer "In4.Cu")
		(net "P5E_CPU1_PE3_RX_DP<3>")
	)
	(segment
		(start 132.15874 -290.37026)
		(end 132.15874 -290.610544)
		(width 0.0889)
		(layer "In4.Cu")
		(net "P5E_CPU1_PE3_RX_DP<3>")
	)
	(segment
		(start 151.020018 -422.6306)
		(end 150.066502 -424.464226)
		(width 0.14732)
		(layer "In4.Cu")
		(net "P5E_CPU1_PE3_RX_DP<3>")
	)
	(segment
		(start 159.014414 -404.596092)
		(end 157.297374 -406.313132)
		(width 0.14732)
		(layer "In4.Cu")
		(net "P5E_CPU1_PE3_RX_DP<3>")
	)
	(segment
		(start 159.014414 -400.711924)
		(end 159.014414 -404.596092)
		(width 0.14732)
		(layer "In4.Cu")
		(net "P5E_CPU1_PE3_RX_DP<3>")
	)
	(segment
		(start 131.797044 -289.218116)
		(end 131.827016 -289.315144)
		(width 0.0889)
		(layer "In4.Cu")
		(net "P5E_CPU1_PE3_RX_DP<3>")
	)
	(segment
		(start 134.189724 -292.875208)
		(end 135.574532 -292.875208)
		(width 0.14732)
		(layer "In4.Cu")
		(net "P5E_CPU1_PE3_RX_DP<3>")
	)
	(segment
		(start 160.299908 -330.4413)
		(end 161.133282 -335.165954)
		(width 0.14732)
		(layer "In4.Cu")
		(net "P5E_CPU1_PE3_RX_DP<3>")
	)
	(segment
		(start 131.956048 -288.917126)
		(end 131.797044 -289.218116)
		(width 0.0889)
		(layer "In4.Cu")
		(net "P5E_CPU1_PE3_RX_DP<3>")
	)
	(segment
		(start 150.066756 -437.205374)
		(end 150.214076 -437.352694)
		(width 0.14732)
		(layer "In4.Cu")
		(net "P5E_CPU1_PE3_RX_DP<3>")
	)
	(segment
		(start 132.051044 -290.142422)
		(end 132.15874 -290.37026)
		(width 0.0889)
		(layer "In4.Cu")
		(net "P5E_CPU1_PE3_RX_DP<3>")
	)
	(segment
		(start 161.983166 -340.620858)
		(end 161.60369 -364.768638)
		(width 0.14732)
		(layer "In4.Cu")
		(net "P5E_CPU1_PE3_RX_DP<3>")
	)
	(segment
		(start 161.60369 -364.768638)
		(end 161.594292 -364.96117)
		(width 0.14732)
		(layer "In4.Cu")
		(net "P5E_CPU1_PE3_RX_DP<3>")
	)
	(segment
		(start 151.378666 -422.244012)
		(end 151.20874 -422.571164)
		(width 0.14732)
		(layer "In4.Cu")
		(net "P5E_CPU1_PE3_RX_DP<3>")
	)
	(segment
		(start 137.25271 -294.553132)
		(end 155.949904 -324.854062)
		(width 0.14732)
		(layer "In4.Cu")
		(net "P5E_CPU1_PE3_RX_DP<3>")
	)
	(segment
		(start 161.133282 -335.165954)
		(end 161.983166 -340.620858)
		(width 0.14732)
		(layer "In4.Cu")
		(net "P5E_CPU1_PE3_RX_DP<3>")
	)
	(segment
		(start 155.949904 -324.854062)
		(end 160.299908 -330.4413)
		(width 0.14732)
		(layer "In4.Cu")
		(net "P5E_CPU1_PE3_RX_DP<3>")
	)
	(arc
		(start 131.827016 -289.315144)
		(mid 131.962331 -289.444603)
		(end 132.051044 -289.60953)
		(width 0.0889)
		(layer "In4.Cu")
		(net "P5E_CPU1_PE3_RX_DP<3>")
	)
	(segment
		(start 132.425694 -288.102802)
		(end 132.425948 -288.103056)
		(width 0.13208)
		(layer "F.Cu")
		(net "P5E_CPU1_PE3_RX_DP<2>")
	)
	(segment
		(start 132.425694 -287.567116)
		(end 132.425694 -288.102802)
		(width 0.13208)
		(layer "F.Cu")
		(net "P5E_CPU1_PE3_RX_DP<2>")
	)
	(segment
		(start 152.066498 -423.833036)
		(end 152.066498 -438.205118)
		(width 0.14732)
		(layer "In4.Cu")
		(net "P5E_CPU1_PE3_RX_DP<2>")
	)
	(segment
		(start 134.537704 -291.800788)
		(end 136.011666 -291.800788)
		(width 0.14732)
		(layer "In4.Cu")
		(net "P5E_CPU1_PE3_RX_DP<2>")
	)
	(segment
		(start 133.252718 -290.575746)
		(end 133.312662 -290.575746)
		(width 0.0889)
		(layer "In4.Cu")
		(net "P5E_CPU1_PE3_RX_DP<2>")
	)
	(segment
		(start 157.249876 -325.007732)
		(end 161.216086 -330.101956)
		(width 0.14732)
		(layer "In4.Cu")
		(net "P5E_CPU1_PE3_RX_DP<2>")
	)
	(segment
		(start 152.214072 -438.352692)
		(end 152.53843 -438.352692)
		(width 0.14732)
		(layer "In4.Cu")
		(net "P5E_CPU1_PE3_RX_DP<2>")
	)
	(segment
		(start 132.990844 -289.64636)
		(end 132.990844 -290.313872)
		(width 0.0889)
		(layer "In4.Cu")
		(net "P5E_CPU1_PE3_RX_DP<2>")
	)
	(segment
		(start 152.066498 -438.205118)
		(end 152.214072 -438.352692)
		(width 0.14732)
		(layer "In4.Cu")
		(net "P5E_CPU1_PE3_RX_DP<2>")
	)
	(segment
		(start 162.077654 -404.596092)
		(end 160.360614 -406.313132)
		(width 0.14732)
		(layer "In4.Cu")
		(net "P5E_CPU1_PE3_RX_DP<2>")
	)
	(segment
		(start 133.328156 -290.59124)
		(end 134.537704 -291.800788)
		(width 0.14732)
		(layer "In4.Cu")
		(net "P5E_CPU1_PE3_RX_DP<2>")
	)
	(segment
		(start 133.460998 -288.898584)
		(end 133.460998 -289.114484)
		(width 0.0889)
		(layer "In4.Cu")
		(net "P5E_CPU1_PE3_RX_DP<2>")
	)
	(segment
		(start 132.990844 -290.313872)
		(end 133.252718 -290.575746)
		(width 0.0889)
		(layer "In4.Cu")
		(net "P5E_CPU1_PE3_RX_DP<2>")
	)
	(segment
		(start 161.216086 -330.101956)
		(end 163.087304 -340.765384)
		(width 0.14732)
		(layer "In4.Cu")
		(net "P5E_CPU1_PE3_RX_DP<2>")
	)
	(segment
		(start 132.425948 -288.103056)
		(end 132.582412 -288.374074)
		(width 0.0889)
		(layer "In4.Cu")
		(net "P5E_CPU1_PE3_RX_DP<2>")
	)
	(segment
		(start 162.066986 -399.890234)
		(end 162.077654 -399.900902)
		(width 0.14732)
		(layer "In4.Cu")
		(net "P5E_CPU1_PE3_RX_DP<2>")
	)
	(segment
		(start 137.964164 -293.753032)
		(end 157.249876 -325.007732)
		(width 0.14732)
		(layer "In4.Cu")
		(net "P5E_CPU1_PE3_RX_DP<2>")
	)
	(segment
		(start 160.360614 -410.72435)
		(end 152.066498 -423.833036)
		(width 0.14732)
		(layer "In4.Cu")
		(net "P5E_CPU1_PE3_RX_DP<2>")
	)
	(segment
		(start 136.011666 -291.800788)
		(end 137.964164 -293.753032)
		(width 0.14732)
		(layer "In4.Cu")
		(net "P5E_CPU1_PE3_RX_DP<2>")
	)
	(segment
		(start 160.360614 -406.313132)
		(end 160.360614 -410.72435)
		(width 0.14732)
		(layer "In4.Cu")
		(net "P5E_CPU1_PE3_RX_DP<2>")
	)
	(segment
		(start 163.087304 -340.765384)
		(end 162.066986 -399.890234)
		(width 0.14732)
		(layer "In4.Cu")
		(net "P5E_CPU1_PE3_RX_DP<2>")
	)
	(segment
		(start 162.077654 -399.900902)
		(end 162.077654 -404.596092)
		(width 0.14732)
		(layer "In4.Cu")
		(net "P5E_CPU1_PE3_RX_DP<2>")
	)
	(segment
		(start 132.582412 -288.374074)
		(end 132.671566 -288.39795)
		(width 0.0889)
		(layer "In4.Cu")
		(net "P5E_CPU1_PE3_RX_DP<2>")
	)
	(segment
		(start 133.312662 -290.575746)
		(end 133.328156 -290.59124)
		(width 0.0889)
		(layer "In4.Cu")
		(net "P5E_CPU1_PE3_RX_DP<2>")
	)
	(segment
		(start 152.750012 -438.14111)
		(end 152.750012 -437.889904)
		(width 0.14732)
		(layer "In4.Cu")
		(net "P5E_CPU1_PE3_RX_DP<2>")
	)
	(segment
		(start 152.53843 -438.352692)
		(end 152.750012 -438.14111)
		(width 0.14732)
		(layer "In4.Cu")
		(net "P5E_CPU1_PE3_RX_DP<2>")
	)
	(arc
		(start 133.17855 -288.427414)
		(mid 133.380836 -288.626395)
		(end 133.460998 -288.898584)
		(width 0.0889)
		(layer "In4.Cu")
		(net "P5E_CPU1_PE3_RX_DP<2>")
	)
	(arc
		(start 133.460998 -289.114484)
		(mid 133.349602 -289.307577)
		(end 133.175248 -289.446462)
		(width 0.0889)
		(layer "In4.Cu")
		(net "P5E_CPU1_PE3_RX_DP<2>")
	)
	(arc
		(start 132.671566 -288.39795)
		(mid 132.681307 -288.393795)
		(end 132.691124 -288.389822)
		(width 0.0889)
		(layer "In4.Cu")
		(net "P5E_CPU1_PE3_RX_DP<2>")
	)
	(arc
		(start 133.175248 -289.446462)
		(mid 133.065852 -289.530559)
		(end 132.990844 -289.64636)
		(width 0.0889)
		(layer "In4.Cu")
		(net "P5E_CPU1_PE3_RX_DP<2>")
	)
	(arc
		(start 132.691124 -288.389822)
		(mid 132.939104 -288.35321)
		(end 133.17855 -288.427414)
		(width 0.0889)
		(layer "In4.Cu")
		(net "P5E_CPU1_PE3_RX_DP<2>")
	)
	(segment
		(start 133.835648 -288.917126)
		(end 133.835648 -288.381186)
		(width 0.13208)
		(layer "F.Cu")
		(net "P5E_CPU1_PE3_RX_DP<1>")
	)
	(segment
		(start 163.11626 -327.175368)
		(end 164.062918 -340.872572)
		(width 0.14732)
		(layer "In4.Cu")
		(net "P5E_CPU1_PE3_RX_DP<1>")
	)
	(segment
		(start 155.486354 -422.583102)
		(end 155.278328 -422.887394)
		(width 0.14732)
		(layer "In4.Cu")
		(net "P5E_CPU1_PE3_RX_DP<1>")
	)
	(segment
		(start 136.516618 -290.881308)
		(end 138.73861 -293.103046)
		(width 0.14732)
		(layer "In4.Cu")
		(net "P5E_CPU1_PE3_RX_DP<1>")
	)
	(segment
		(start 165.140894 -400.683476)
		(end 165.140894 -404.596092)
		(width 0.14732)
		(layer "In4.Cu")
		(net "P5E_CPU1_PE3_RX_DP<1>")
	)
	(segment
		(start 154.750008 -437.20512)
		(end 154.750008 -436.889906)
		(width 0.14732)
		(layer "In4.Cu")
		(net "P5E_CPU1_PE3_RX_DP<1>")
	)
	(segment
		(start 155.85186 -422.048686)
		(end 155.65755 -422.085008)
		(width 0.14732)
		(layer "In4.Cu")
		(net "P5E_CPU1_PE3_RX_DP<1>")
	)
	(segment
		(start 158.92018 -324.277736)
		(end 160.626806 -324.578726)
		(width 0.14732)
		(layer "In4.Cu")
		(net "P5E_CPU1_PE3_RX_DP<1>")
	)
	(segment
		(start 155.449778 -422.389046)
		(end 155.486354 -422.583102)
		(width 0.14732)
		(layer "In4.Cu")
		(net "P5E_CPU1_PE3_RX_DP<1>")
	)
	(segment
		(start 154.066748 -424.413172)
		(end 154.066748 -437.205374)
		(width 0.14732)
		(layer "In4.Cu")
		(net "P5E_CPU1_PE3_RX_DP<1>")
	)
	(segment
		(start 160.626806 -324.578726)
		(end 162.69208 -326.024748)
		(width 0.14732)
		(layer "In4.Cu")
		(net "P5E_CPU1_PE3_RX_DP<1>")
	)
	(segment
		(start 155.65755 -422.085008)
		(end 155.449778 -422.389046)
		(width 0.14732)
		(layer "In4.Cu")
		(net "P5E_CPU1_PE3_RX_DP<1>")
	)
	(segment
		(start 155.278328 -422.887394)
		(end 155.084018 -422.92397)
		(width 0.14732)
		(layer "In4.Cu")
		(net "P5E_CPU1_PE3_RX_DP<1>")
	)
	(segment
		(start 163.619688 -365.802164)
		(end 165.140894 -400.683476)
		(width 0.14732)
		(layer "In4.Cu")
		(net "P5E_CPU1_PE3_RX_DP<1>")
	)
	(segment
		(start 162.99053 -326.45096)
		(end 163.096448 -327.052686)
		(width 0.14732)
		(layer "In4.Cu")
		(net "P5E_CPU1_PE3_RX_DP<1>")
	)
	(segment
		(start 133.930644 -289.60953)
		(end 133.930644 -289.994086)
		(width 0.0889)
		(layer "In4.Cu")
		(net "P5E_CPU1_PE3_RX_DP<1>")
	)
	(segment
		(start 134.344156 -290.347654)
		(end 134.87781 -290.881308)
		(width 0.14732)
		(layer "In4.Cu")
		(net "P5E_CPU1_PE3_RX_DP<1>")
	)
	(segment
		(start 164.062918 -340.872572)
		(end 163.619688 -365.798354)
		(width 0.14732)
		(layer "In4.Cu")
		(net "P5E_CPU1_PE3_RX_DP<1>")
	)
	(segment
		(start 163.423854 -406.313132)
		(end 163.423854 -410.721302)
		(width 0.14732)
		(layer "In4.Cu")
		(net "P5E_CPU1_PE3_RX_DP<1>")
	)
	(segment
		(start 138.73861 -293.103046)
		(end 156.435552 -321.793108)
		(width 0.14732)
		(layer "In4.Cu")
		(net "P5E_CPU1_PE3_RX_DP<1>")
	)
	(segment
		(start 165.140894 -404.596092)
		(end 163.423854 -406.313132)
		(width 0.14732)
		(layer "In4.Cu")
		(net "P5E_CPU1_PE3_RX_DP<1>")
	)
	(segment
		(start 163.11626 -327.072498)
		(end 163.11626 -327.175368)
		(width 0.14732)
		(layer "In4.Cu")
		(net "P5E_CPU1_PE3_RX_DP<1>")
	)
	(segment
		(start 133.930644 -289.994086)
		(end 134.268718 -290.33216)
		(width 0.0889)
		(layer "In4.Cu")
		(net "P5E_CPU1_PE3_RX_DP<1>")
	)
	(segment
		(start 134.87781 -290.881308)
		(end 136.516618 -290.881308)
		(width 0.14732)
		(layer "In4.Cu")
		(net "P5E_CPU1_PE3_RX_DP<1>")
	)
	(segment
		(start 163.619688 -365.798354)
		(end 163.619688 -365.802164)
		(width 0.14732)
		(layer "In4.Cu")
		(net "P5E_CPU1_PE3_RX_DP<1>")
	)
	(segment
		(start 156.435552 -321.793108)
		(end 158.92018 -324.277736)
		(width 0.14732)
		(layer "In4.Cu")
		(net "P5E_CPU1_PE3_RX_DP<1>")
	)
	(segment
		(start 163.096448 -327.052686)
		(end 163.11626 -327.072498)
		(width 0.14732)
		(layer "In4.Cu")
		(net "P5E_CPU1_PE3_RX_DP<1>")
	)
	(segment
		(start 154.066494 -424.412918)
		(end 154.066748 -424.413172)
		(width 0.14732)
		(layer "In4.Cu")
		(net "P5E_CPU1_PE3_RX_DP<1>")
	)
	(segment
		(start 156.023056 -421.550084)
		(end 156.059632 -421.74414)
		(width 0.14732)
		(layer "In4.Cu")
		(net "P5E_CPU1_PE3_RX_DP<1>")
	)
	(segment
		(start 162.69208 -326.024748)
		(end 162.99053 -326.45096)
		(width 0.14732)
		(layer "In4.Cu")
		(net "P5E_CPU1_PE3_RX_DP<1>")
	)
	(segment
		(start 156.059632 -421.74414)
		(end 155.85186 -422.048686)
		(width 0.14732)
		(layer "In4.Cu")
		(net "P5E_CPU1_PE3_RX_DP<1>")
	)
	(segment
		(start 154.602434 -437.352694)
		(end 154.750008 -437.20512)
		(width 0.14732)
		(layer "In4.Cu")
		(net "P5E_CPU1_PE3_RX_DP<1>")
	)
	(segment
		(start 133.835648 -288.917126)
		(end 133.676644 -289.218116)
		(width 0.0889)
		(layer "In4.Cu")
		(net "P5E_CPU1_PE3_RX_DP<1>")
	)
	(segment
		(start 134.268718 -290.33216)
		(end 134.328662 -290.33216)
		(width 0.0889)
		(layer "In4.Cu")
		(net "P5E_CPU1_PE3_RX_DP<1>")
	)
	(segment
		(start 154.214068 -437.352694)
		(end 154.602434 -437.352694)
		(width 0.14732)
		(layer "In4.Cu")
		(net "P5E_CPU1_PE3_RX_DP<1>")
	)
	(segment
		(start 134.328662 -290.33216)
		(end 134.344156 -290.347654)
		(width 0.0889)
		(layer "In4.Cu")
		(net "P5E_CPU1_PE3_RX_DP<1>")
	)
	(segment
		(start 133.676644 -289.218116)
		(end 133.706616 -289.315144)
		(width 0.0889)
		(layer "In4.Cu")
		(net "P5E_CPU1_PE3_RX_DP<1>")
	)
	(segment
		(start 154.066748 -437.205374)
		(end 154.214068 -437.352694)
		(width 0.14732)
		(layer "In4.Cu")
		(net "P5E_CPU1_PE3_RX_DP<1>")
	)
	(segment
		(start 163.423854 -410.721302)
		(end 156.023056 -421.550084)
		(width 0.14732)
		(layer "In4.Cu")
		(net "P5E_CPU1_PE3_RX_DP<1>")
	)
	(segment
		(start 155.084018 -422.92397)
		(end 154.066494 -424.412918)
		(width 0.14732)
		(layer "In4.Cu")
		(net "P5E_CPU1_PE3_RX_DP<1>")
	)
	(arc
		(start 133.706616 -289.315144)
		(mid 133.841931 -289.444603)
		(end 133.930644 -289.60953)
		(width 0.0889)
		(layer "In4.Cu")
		(net "P5E_CPU1_PE3_RX_DP<1>")
	)
	(segment
		(start 120.208294 -289.195002)
		(end 120.208294 -289.807142)
		(width 0.13208)
		(layer "F.Cu")
		(net "P5E_CPU1_PE3_RX_DP<15>")
	)
	(segment
		(start 147.073874 -369.901724)
		(end 147.074128 -369.901724)
		(width 0.14732)
		(layer "In4.Cu")
		(net "P5E_CPU1_PE3_RX_DP<15>")
	)
	(segment
		(start 118.75008 -292.527228)
		(end 120.541034 -290.736274)
		(width 0.14732)
		(layer "In4.Cu")
		(net "P5E_CPU1_PE3_RX_DP<15>")
	)
	(segment
		(start 120.45188 -289.480244)
		(end 120.367298 -289.506152)
		(width 0.0889)
		(layer "In4.Cu")
		(net "P5E_CPU1_PE3_RX_DP<15>")
	)
	(segment
		(start 120.264174 -406.19934)
		(end 121.981214 -404.4823)
		(width 0.14732)
		(layer "In4.Cu")
		(net "P5E_CPU1_PE3_RX_DP<15>")
	)
	(segment
		(start 149.18436 -336.638392)
		(end 148.84146 -334.696054)
		(width 0.14732)
		(layer "In4.Cu")
		(net "P5E_CPU1_PE3_RX_DP<15>")
	)
	(segment
		(start 147.074128 -369.901724)
		(end 148.969476 -363.97438)
		(width 0.14732)
		(layer "In4.Cu")
		(net "P5E_CPU1_PE3_RX_DP<15>")
	)
	(segment
		(start 122.018552 -302.015652)
		(end 118.835932 -297.797728)
		(width 0.14732)
		(layer "In4.Cu")
		(net "P5E_CPU1_PE3_RX_DP<15>")
	)
	(segment
		(start 120.264174 -410.422852)
		(end 120.264174 -406.19934)
		(width 0.14732)
		(layer "In4.Cu")
		(net "P5E_CPU1_PE3_RX_DP<15>")
	)
	(segment
		(start 120.367298 -289.506152)
		(end 120.208294 -289.807142)
		(width 0.0889)
		(layer "In4.Cu")
		(net "P5E_CPU1_PE3_RX_DP<15>")
	)
	(segment
		(start 118.835932 -297.797728)
		(end 118.75008 -297.31081)
		(width 0.14732)
		(layer "In4.Cu")
		(net "P5E_CPU1_PE3_RX_DP<15>")
	)
	(segment
		(start 121.276618 -412.817564)
		(end 120.264174 -410.422852)
		(width 0.14732)
		(layer "In4.Cu")
		(net "P5E_CPU1_PE3_RX_DP<15>")
	)
	(segment
		(start 148.969476 -363.97438)
		(end 149.18436 -338.05749)
		(width 0.14732)
		(layer "In4.Cu")
		(net "P5E_CPU1_PE3_RX_DP<15>")
	)
	(segment
		(start 125.750066 -437.774588)
		(end 125.602492 -437.627014)
		(width 0.14732)
		(layer "In4.Cu")
		(net "P5E_CPU1_PE3_RX_DP<15>")
	)
	(segment
		(start 122.5169 -399.148554)
		(end 147.073874 -369.901724)
		(width 0.14732)
		(layer "In4.Cu")
		(net "P5E_CPU1_PE3_RX_DP<15>")
	)
	(segment
		(start 125.602492 -437.627014)
		(end 125.100334 -437.627014)
		(width 0.14732)
		(layer "In4.Cu")
		(net "P5E_CPU1_PE3_RX_DP<15>")
	)
	(segment
		(start 120.541034 -290.736274)
		(end 120.541034 -290.512246)
		(width 0.14732)
		(layer "In4.Cu")
		(net "P5E_CPU1_PE3_RX_DP<15>")
	)
	(segment
		(start 118.75008 -297.31081)
		(end 118.75008 -292.527228)
		(width 0.14732)
		(layer "In4.Cu")
		(net "P5E_CPU1_PE3_RX_DP<15>")
	)
	(segment
		(start 120.582944 -290.448238)
		(end 120.582944 -289.645852)
		(width 0.0889)
		(layer "In4.Cu")
		(net "P5E_CPU1_PE3_RX_DP<15>")
	)
	(segment
		(start 148.84146 -334.696054)
		(end 122.018552 -302.015652)
		(width 0.14732)
		(layer "In4.Cu")
		(net "P5E_CPU1_PE3_RX_DP<15>")
	)
	(segment
		(start 125.100334 -437.627014)
		(end 124.727462 -437.254396)
		(width 0.14732)
		(layer "In4.Cu")
		(net "P5E_CPU1_PE3_RX_DP<15>")
	)
	(segment
		(start 125.750066 -438.089802)
		(end 125.750066 -437.774588)
		(width 0.14732)
		(layer "In4.Cu")
		(net "P5E_CPU1_PE3_RX_DP<15>")
	)
	(segment
		(start 120.541034 -290.512246)
		(end 120.541034 -290.490148)
		(width 0.0889)
		(layer "In4.Cu")
		(net "P5E_CPU1_PE3_RX_DP<15>")
	)
	(segment
		(start 124.727462 -437.254396)
		(end 121.276618 -412.817564)
		(width 0.14732)
		(layer "In4.Cu")
		(net "P5E_CPU1_PE3_RX_DP<15>")
	)
	(segment
		(start 121.981214 -404.4823)
		(end 121.981214 -400.362928)
		(width 0.14732)
		(layer "In4.Cu")
		(net "P5E_CPU1_PE3_RX_DP<15>")
	)
	(segment
		(start 120.541034 -290.490148)
		(end 120.582944 -290.448238)
		(width 0.0889)
		(layer "In4.Cu")
		(net "P5E_CPU1_PE3_RX_DP<15>")
	)
	(segment
		(start 121.981214 -400.362928)
		(end 122.5169 -399.148554)
		(width 0.14732)
		(layer "In4.Cu")
		(net "P5E_CPU1_PE3_RX_DP<15>")
	)
	(segment
		(start 149.18436 -338.05749)
		(end 149.18436 -336.638392)
		(width 0.14732)
		(layer "In4.Cu")
		(net "P5E_CPU1_PE3_RX_DP<15>")
	)
	(arc
		(start 120.582944 -289.645852)
		(mid 120.528293 -289.554442)
		(end 120.45188 -289.480244)
		(width 0.0889)
		(layer "In4.Cu")
		(net "P5E_CPU1_PE3_RX_DP<15>")
	)
	(segment
		(start 121.618248 -288.381186)
		(end 121.618248 -288.917126)
		(width 0.13208)
		(layer "F.Cu")
		(net "P5E_CPU1_PE3_RX_DP<14>")
	)
	(segment
		(start 150.048722 -363.913928)
		(end 150.22322 -337.655916)
		(width 0.14732)
		(layer "In4.Cu")
		(net "P5E_CPU1_PE3_RX_DP<14>")
	)
	(segment
		(start 121.992898 -289.077908)
		(end 121.992898 -288.917126)
		(width 0.0889)
		(layer "In4.Cu")
		(net "P5E_CPU1_PE3_RX_DP<14>")
	)
	(segment
		(start 148.192236 -370.264182)
		(end 150.048722 -363.913928)
		(width 0.14732)
		(layer "In4.Cu")
		(net "P5E_CPU1_PE3_RX_DP<14>")
	)
	(segment
		(start 121.461784 -288.646108)
		(end 121.618248 -288.917126)
		(width 0.0889)
		(layer "In4.Cu")
		(net "P5E_CPU1_PE3_RX_DP<14>")
	)
	(segment
		(start 120.951752 -291.855144)
		(end 121.481088 -291.325808)
		(width 0.14732)
		(layer "In4.Cu")
		(net "P5E_CPU1_PE3_RX_DP<14>")
	)
	(segment
		(start 121.522998 -290.448238)
		(end 121.522998 -289.611054)
		(width 0.0889)
		(layer "In4.Cu")
		(net "P5E_CPU1_PE3_RX_DP<14>")
	)
	(segment
		(start 125.044454 -404.4823)
		(end 125.044454 -400.1897)
		(width 0.14732)
		(layer "In4.Cu")
		(net "P5E_CPU1_PE3_RX_DP<14>")
	)
	(segment
		(start 120.806972 -294.242998)
		(end 120.806972 -293.874698)
		(width 0.14732)
		(layer "In4.Cu")
		(net "P5E_CPU1_PE3_RX_DP<14>")
	)
	(segment
		(start 126.792482 -423.477436)
		(end 123.327414 -410.401516)
		(width 0.14732)
		(layer "In4.Cu")
		(net "P5E_CPU1_PE3_RX_DP<14>")
	)
	(segment
		(start 124.429012 -303.443894)
		(end 121.245884 -298.898056)
		(width 0.14732)
		(layer "In4.Cu")
		(net "P5E_CPU1_PE3_RX_DP<14>")
	)
	(segment
		(start 127.602488 -438.627012)
		(end 127.10033 -438.627012)
		(width 0.14732)
		(layer "In4.Cu")
		(net "P5E_CPU1_PE3_RX_DP<14>")
	)
	(segment
		(start 150.22322 -337.655916)
		(end 150.22322 -337.133438)
		(width 0.14732)
		(layer "In4.Cu")
		(net "P5E_CPU1_PE3_RX_DP<14>")
	)
	(segment
		(start 125.377956 -399.323052)
		(end 148.192236 -370.264182)
		(width 0.14732)
		(layer "In4.Cu")
		(net "P5E_CPU1_PE3_RX_DP<14>")
	)
	(segment
		(start 127.750062 -438.774586)
		(end 127.602488 -438.627012)
		(width 0.14732)
		(layer "In4.Cu")
		(net "P5E_CPU1_PE3_RX_DP<14>")
	)
	(segment
		(start 121.481088 -290.512246)
		(end 121.481088 -290.490148)
		(width 0.0889)
		(layer "In4.Cu")
		(net "P5E_CPU1_PE3_RX_DP<14>")
	)
	(segment
		(start 121.808748 -289.27806)
		(end 121.808494 -289.277806)
		(width 0.0889)
		(layer "In4.Cu")
		(net "P5E_CPU1_PE3_RX_DP<14>")
	)
	(segment
		(start 123.327414 -406.19934)
		(end 125.044454 -404.4823)
		(width 0.14732)
		(layer "In4.Cu")
		(net "P5E_CPU1_PE3_RX_DP<14>")
	)
	(segment
		(start 127.750062 -439.0898)
		(end 127.750062 -438.774586)
		(width 0.14732)
		(layer "In4.Cu")
		(net "P5E_CPU1_PE3_RX_DP<14>")
	)
	(segment
		(start 120.951752 -294.387778)
		(end 120.806972 -294.242998)
		(width 0.14732)
		(layer "In4.Cu")
		(net "P5E_CPU1_PE3_RX_DP<14>")
	)
	(segment
		(start 126.792482 -438.319164)
		(end 126.792482 -423.477436)
		(width 0.14732)
		(layer "In4.Cu")
		(net "P5E_CPU1_PE3_RX_DP<14>")
	)
	(segment
		(start 149.717506 -334.26527)
		(end 124.429012 -303.443894)
		(width 0.14732)
		(layer "In4.Cu")
		(net "P5E_CPU1_PE3_RX_DP<14>")
	)
	(segment
		(start 125.044454 -400.1897)
		(end 125.377956 -399.323052)
		(width 0.14732)
		(layer "In4.Cu")
		(net "P5E_CPU1_PE3_RX_DP<14>")
	)
	(segment
		(start 121.245884 -298.898056)
		(end 120.951752 -297.225212)
		(width 0.14732)
		(layer "In4.Cu")
		(net "P5E_CPU1_PE3_RX_DP<14>")
	)
	(segment
		(start 121.481088 -290.490148)
		(end 121.522998 -290.448238)
		(width 0.0889)
		(layer "In4.Cu")
		(net "P5E_CPU1_PE3_RX_DP<14>")
	)
	(segment
		(start 120.806972 -293.874698)
		(end 120.951752 -293.729918)
		(width 0.14732)
		(layer "In4.Cu")
		(net "P5E_CPU1_PE3_RX_DP<14>")
	)
	(segment
		(start 120.951752 -297.225212)
		(end 120.951752 -294.387778)
		(width 0.14732)
		(layer "In4.Cu")
		(net "P5E_CPU1_PE3_RX_DP<14>")
	)
	(segment
		(start 121.482866 -288.56813)
		(end 121.461784 -288.646108)
		(width 0.0889)
		(layer "In4.Cu")
		(net "P5E_CPU1_PE3_RX_DP<14>")
	)
	(segment
		(start 120.951752 -293.729918)
		(end 120.951752 -291.855144)
		(width 0.14732)
		(layer "In4.Cu")
		(net "P5E_CPU1_PE3_RX_DP<14>")
	)
	(segment
		(start 123.327414 -410.401516)
		(end 123.327414 -406.19934)
		(width 0.14732)
		(layer "In4.Cu")
		(net "P5E_CPU1_PE3_RX_DP<14>")
	)
	(segment
		(start 127.10033 -438.627012)
		(end 126.792482 -438.319164)
		(width 0.14732)
		(layer "In4.Cu")
		(net "P5E_CPU1_PE3_RX_DP<14>")
	)
	(segment
		(start 150.22322 -337.133438)
		(end 149.717506 -334.26527)
		(width 0.14732)
		(layer "In4.Cu")
		(net "P5E_CPU1_PE3_RX_DP<14>")
	)
	(segment
		(start 121.481088 -291.325808)
		(end 121.481088 -290.512246)
		(width 0.14732)
		(layer "In4.Cu")
		(net "P5E_CPU1_PE3_RX_DP<14>")
	)
	(arc
		(start 121.992898 -288.917126)
		(mid 121.82992 -288.608136)
		(end 121.482866 -288.56813)
		(width 0.0889)
		(layer "In4.Cu")
		(net "P5E_CPU1_PE3_RX_DP<14>")
	)
	(arc
		(start 121.808494 -289.277806)
		(mid 121.91789 -289.193709)
		(end 121.992898 -289.077908)
		(width 0.0889)
		(layer "In4.Cu")
		(net "P5E_CPU1_PE3_RX_DP<14>")
	)
	(arc
		(start 121.522998 -289.611054)
		(mid 121.634228 -289.417399)
		(end 121.808748 -289.27806)
		(width 0.0889)
		(layer "In4.Cu")
		(net "P5E_CPU1_PE3_RX_DP<14>")
	)
	(segment
		(start 122.087894 -289.195002)
		(end 122.087894 -289.807142)
		(width 0.13208)
		(layer "F.Cu")
		(net "P5E_CPU1_PE3_RX_DP<13>")
	)
	(segment
		(start 126.20498 -304.137822)
		(end 122.074178 -298.238164)
		(width 0.14732)
		(layer "In4.Cu")
		(net "P5E_CPU1_PE3_RX_DP<13>")
	)
	(segment
		(start 151.16302 -337.265772)
		(end 151.16302 -337.050634)
		(width 0.14732)
		(layer "In4.Cu")
		(net "P5E_CPU1_PE3_RX_DP<13>")
	)
	(segment
		(start 151.16302 -337.050634)
		(end 150.59406 -333.825088)
		(width 0.14732)
		(layer "In4.Cu")
		(net "P5E_CPU1_PE3_RX_DP<13>")
	)
	(segment
		(start 128.107694 -404.4823)
		(end 128.107694 -400.417284)
		(width 0.14732)
		(layer "In4.Cu")
		(net "P5E_CPU1_PE3_RX_DP<13>")
	)
	(segment
		(start 122.420888 -290.512246)
		(end 122.420888 -290.490148)
		(width 0.0889)
		(layer "In4.Cu")
		(net "P5E_CPU1_PE3_RX_DP<13>")
	)
	(segment
		(start 129.602484 -437.627014)
		(end 129.100326 -437.627014)
		(width 0.14732)
		(layer "In4.Cu")
		(net "P5E_CPU1_PE3_RX_DP<13>")
	)
	(segment
		(start 129.750058 -437.774588)
		(end 129.602484 -437.627014)
		(width 0.14732)
		(layer "In4.Cu")
		(net "P5E_CPU1_PE3_RX_DP<13>")
	)
	(segment
		(start 149.14372 -370.655596)
		(end 151.054054 -363.84357)
		(width 0.14732)
		(layer "In4.Cu")
		(net "P5E_CPU1_PE3_RX_DP<13>")
	)
	(segment
		(start 122.33148 -289.480244)
		(end 122.246898 -289.506152)
		(width 0.0889)
		(layer "In4.Cu")
		(net "P5E_CPU1_PE3_RX_DP<13>")
	)
	(segment
		(start 122.420888 -290.490148)
		(end 122.462798 -290.448238)
		(width 0.0889)
		(layer "In4.Cu")
		(net "P5E_CPU1_PE3_RX_DP<13>")
	)
	(segment
		(start 122.462798 -290.448238)
		(end 122.462798 -289.646106)
		(width 0.0889)
		(layer "In4.Cu")
		(net "P5E_CPU1_PE3_RX_DP<13>")
	)
	(segment
		(start 121.881392 -297.143678)
		(end 121.881392 -292.48354)
		(width 0.14732)
		(layer "In4.Cu")
		(net "P5E_CPU1_PE3_RX_DP<13>")
	)
	(segment
		(start 128.792478 -423.905426)
		(end 126.390654 -411.025594)
		(width 0.14732)
		(layer "In4.Cu")
		(net "P5E_CPU1_PE3_RX_DP<13>")
	)
	(segment
		(start 121.881392 -292.48354)
		(end 122.420888 -291.944044)
		(width 0.14732)
		(layer "In4.Cu")
		(net "P5E_CPU1_PE3_RX_DP<13>")
	)
	(segment
		(start 129.750058 -438.089802)
		(end 129.750058 -437.774588)
		(width 0.14732)
		(layer "In4.Cu")
		(net "P5E_CPU1_PE3_RX_DP<13>")
	)
	(segment
		(start 122.074178 -298.238164)
		(end 121.881392 -297.143678)
		(width 0.14732)
		(layer "In4.Cu")
		(net "P5E_CPU1_PE3_RX_DP<13>")
	)
	(segment
		(start 129.100326 -437.627014)
		(end 128.792478 -437.319166)
		(width 0.14732)
		(layer "In4.Cu")
		(net "P5E_CPU1_PE3_RX_DP<13>")
	)
	(segment
		(start 122.246898 -289.506152)
		(end 122.087894 -289.807142)
		(width 0.0889)
		(layer "In4.Cu")
		(net "P5E_CPU1_PE3_RX_DP<13>")
	)
	(segment
		(start 128.255522 -399.955512)
		(end 149.14372 -370.655596)
		(width 0.14732)
		(layer "In4.Cu")
		(net "P5E_CPU1_PE3_RX_DP<13>")
	)
	(segment
		(start 128.107694 -400.417284)
		(end 128.255522 -399.955512)
		(width 0.14732)
		(layer "In4.Cu")
		(net "P5E_CPU1_PE3_RX_DP<13>")
	)
	(segment
		(start 128.792478 -437.319166)
		(end 128.792478 -423.905426)
		(width 0.14732)
		(layer "In4.Cu")
		(net "P5E_CPU1_PE3_RX_DP<13>")
	)
	(segment
		(start 122.462798 -289.646106)
		(end 122.462544 -289.645852)
		(width 0.0889)
		(layer "In4.Cu")
		(net "P5E_CPU1_PE3_RX_DP<13>")
	)
	(segment
		(start 150.59406 -333.825088)
		(end 126.20498 -304.137822)
		(width 0.14732)
		(layer "In4.Cu")
		(net "P5E_CPU1_PE3_RX_DP<13>")
	)
	(segment
		(start 126.390654 -411.025594)
		(end 126.390654 -406.19934)
		(width 0.14732)
		(layer "In4.Cu")
		(net "P5E_CPU1_PE3_RX_DP<13>")
	)
	(segment
		(start 126.390654 -406.19934)
		(end 128.107694 -404.4823)
		(width 0.14732)
		(layer "In4.Cu")
		(net "P5E_CPU1_PE3_RX_DP<13>")
	)
	(segment
		(start 122.420888 -291.944044)
		(end 122.420888 -290.512246)
		(width 0.14732)
		(layer "In4.Cu")
		(net "P5E_CPU1_PE3_RX_DP<13>")
	)
	(segment
		(start 151.054054 -363.84357)
		(end 151.16302 -337.265772)
		(width 0.14732)
		(layer "In4.Cu")
		(net "P5E_CPU1_PE3_RX_DP<13>")
	)
	(arc
		(start 122.462544 -289.645852)
		(mid 122.407893 -289.554442)
		(end 122.33148 -289.480244)
		(width 0.0889)
		(layer "In4.Cu")
		(net "P5E_CPU1_PE3_RX_DP<13>")
	)
	(segment
		(start 123.497848 -288.381186)
		(end 123.497848 -288.917126)
		(width 0.13208)
		(layer "F.Cu")
		(net "P5E_CPU1_PE3_RX_DP<12>")
	)
	(segment
		(start 123.362466 -288.56813)
		(end 123.341384 -288.646108)
		(width 0.0889)
		(layer "In4.Cu")
		(net "P5E_CPU1_PE3_RX_DP<12>")
	)
	(segment
		(start 123.360688 -290.490148)
		(end 123.402598 -290.448238)
		(width 0.0889)
		(layer "In4.Cu")
		(net "P5E_CPU1_PE3_RX_DP<12>")
	)
	(segment
		(start 127.286512 -303.988978)
		(end 124.059442 -299.381672)
		(width 0.14732)
		(layer "In4.Cu")
		(net "P5E_CPU1_PE3_RX_DP<12>")
	)
	(segment
		(start 123.341384 -288.646108)
		(end 123.497848 -288.917126)
		(width 0.0889)
		(layer "In4.Cu")
		(net "P5E_CPU1_PE3_RX_DP<12>")
	)
	(segment
		(start 131.100322 -438.627012)
		(end 130.792474 -438.319164)
		(width 0.14732)
		(layer "In4.Cu")
		(net "P5E_CPU1_PE3_RX_DP<12>")
	)
	(segment
		(start 131.170934 -404.4823)
		(end 131.170934 -400.708368)
		(width 0.14732)
		(layer "In4.Cu")
		(net "P5E_CPU1_PE3_RX_DP<12>")
	)
	(segment
		(start 151.47036 -333.426308)
		(end 127.286512 -303.988978)
		(width 0.14732)
		(layer "In4.Cu")
		(net "P5E_CPU1_PE3_RX_DP<12>")
	)
	(segment
		(start 129.453894 -411.118304)
		(end 129.453894 -406.19934)
		(width 0.14732)
		(layer "In4.Cu")
		(net "P5E_CPU1_PE3_RX_DP<12>")
	)
	(segment
		(start 123.686062 -289.279838)
		(end 123.706636 -289.2679)
		(width 0.0889)
		(layer "In4.Cu")
		(net "P5E_CPU1_PE3_RX_DP<12>")
	)
	(segment
		(start 152.01519 -363.19079)
		(end 152.168606 -337.38566)
		(width 0.14732)
		(layer "In4.Cu")
		(net "P5E_CPU1_PE3_RX_DP<12>")
	)
	(segment
		(start 130.792474 -438.319164)
		(end 130.792474 -423.501312)
		(width 0.14732)
		(layer "In4.Cu")
		(net "P5E_CPU1_PE3_RX_DP<12>")
	)
	(segment
		(start 130.792474 -423.501312)
		(end 129.453894 -411.118304)
		(width 0.14732)
		(layer "In4.Cu")
		(net "P5E_CPU1_PE3_RX_DP<12>")
	)
	(segment
		(start 131.750054 -439.0898)
		(end 131.750054 -438.774586)
		(width 0.14732)
		(layer "In4.Cu")
		(net "P5E_CPU1_PE3_RX_DP<12>")
	)
	(segment
		(start 123.402598 -289.563556)
		(end 123.686062 -289.279838)
		(width 0.0889)
		(layer "In4.Cu")
		(net "P5E_CPU1_PE3_RX_DP<12>")
	)
	(segment
		(start 131.28371 -399.869914)
		(end 150.22068 -370.72697)
		(width 0.14732)
		(layer "In4.Cu")
		(net "P5E_CPU1_PE3_RX_DP<12>")
	)
	(segment
		(start 123.360688 -290.554918)
		(end 123.360688 -290.490148)
		(width 0.14732)
		(layer "In4.Cu")
		(net "P5E_CPU1_PE3_RX_DP<12>")
	)
	(segment
		(start 129.453894 -406.19934)
		(end 131.170934 -404.4823)
		(width 0.14732)
		(layer "In4.Cu")
		(net "P5E_CPU1_PE3_RX_DP<12>")
	)
	(segment
		(start 150.22068 -370.72697)
		(end 152.01519 -364.033054)
		(width 0.14732)
		(layer "In4.Cu")
		(net "P5E_CPU1_PE3_RX_DP<12>")
	)
	(segment
		(start 124.059442 -299.381672)
		(end 123.364498 -295.434258)
		(width 0.14732)
		(layer "In4.Cu")
		(net "P5E_CPU1_PE3_RX_DP<12>")
	)
	(segment
		(start 123.872752 -289.078924)
		(end 123.872752 -288.91738)
		(width 0.0889)
		(layer "In4.Cu")
		(net "P5E_CPU1_PE3_RX_DP<12>")
	)
	(segment
		(start 123.872752 -288.91738)
		(end 123.872498 -288.917126)
		(width 0.0889)
		(layer "In4.Cu")
		(net "P5E_CPU1_PE3_RX_DP<12>")
	)
	(segment
		(start 131.750054 -438.774586)
		(end 131.60248 -438.627012)
		(width 0.14732)
		(layer "In4.Cu")
		(net "P5E_CPU1_PE3_RX_DP<12>")
	)
	(segment
		(start 152.01519 -364.033054)
		(end 152.01519 -363.19079)
		(width 0.14732)
		(layer "In4.Cu")
		(net "P5E_CPU1_PE3_RX_DP<12>")
	)
	(segment
		(start 123.402598 -290.448238)
		(end 123.402598 -289.563556)
		(width 0.0889)
		(layer "In4.Cu")
		(net "P5E_CPU1_PE3_RX_DP<12>")
	)
	(segment
		(start 123.364498 -295.434258)
		(end 123.360688 -290.554918)
		(width 0.14732)
		(layer "In4.Cu")
		(net "P5E_CPU1_PE3_RX_DP<12>")
	)
	(segment
		(start 152.168606 -337.38566)
		(end 151.47036 -333.426308)
		(width 0.14732)
		(layer "In4.Cu")
		(net "P5E_CPU1_PE3_RX_DP<12>")
	)
	(segment
		(start 131.60248 -438.627012)
		(end 131.100322 -438.627012)
		(width 0.14732)
		(layer "In4.Cu")
		(net "P5E_CPU1_PE3_RX_DP<12>")
	)
	(segment
		(start 131.170934 -400.708368)
		(end 131.28371 -399.869914)
		(width 0.14732)
		(layer "In4.Cu")
		(net "P5E_CPU1_PE3_RX_DP<12>")
	)
	(segment
		(start 123.693936 -288.597848)
		(end 123.685046 -288.592768)
		(width 0.0889)
		(layer "In4.Cu")
		(net "P5E_CPU1_PE3_RX_DP<12>")
	)
	(arc
		(start 123.706636 -289.2679)
		(mid 123.804608 -289.186522)
		(end 123.872752 -289.078924)
		(width 0.0889)
		(layer "In4.Cu")
		(net "P5E_CPU1_PE3_RX_DP<12>")
	)
	(arc
		(start 123.685046 -288.592768)
		(mid 123.526558 -288.543835)
		(end 123.362466 -288.56813)
		(width 0.0889)
		(layer "In4.Cu")
		(net "P5E_CPU1_PE3_RX_DP<12>")
	)
	(arc
		(start 123.872498 -288.917126)
		(mid 123.824819 -288.734226)
		(end 123.693936 -288.597848)
		(width 0.0889)
		(layer "In4.Cu")
		(net "P5E_CPU1_PE3_RX_DP<12>")
	)
	(segment
		(start 124.437648 -288.381186)
		(end 124.437648 -288.917126)
		(width 0.13208)
		(layer "F.Cu")
		(net "P5E_CPU1_PE3_RX_DP<11>")
	)
	(segment
		(start 132.791454 -410.308044)
		(end 132.727192 -411.61716)
		(width 0.14732)
		(layer "In4.Cu")
		(net "P5E_CPU1_PE3_RX_DP<11>")
	)
	(segment
		(start 124.532644 -289.610292)
		(end 124.53239 -289.610292)
		(width 0.0889)
		(layer "In4.Cu")
		(net "P5E_CPU1_PE3_RX_DP<11>")
	)
	(segment
		(start 132.77088 -413.171132)
		(end 132.896356 -413.289496)
		(width 0.14732)
		(layer "In4.Cu")
		(net "P5E_CPU1_PE3_RX_DP<11>")
	)
	(segment
		(start 134.897368 -399.232628)
		(end 134.508494 -399.991834)
		(width 0.14732)
		(layer "In4.Cu")
		(net "P5E_CPU1_PE3_RX_DP<11>")
	)
	(segment
		(start 153.534364 -338.146898)
		(end 153.4287 -363.918246)
		(width 0.14732)
		(layer "In4.Cu")
		(net "P5E_CPU1_PE3_RX_DP<11>")
	)
	(segment
		(start 134.508494 -404.596092)
		(end 132.791454 -406.313132)
		(width 0.14732)
		(layer "In4.Cu")
		(net "P5E_CPU1_PE3_RX_DP<11>")
	)
	(segment
		(start 133.21411 -437.352694)
		(end 133.602476 -437.352694)
		(width 0.14732)
		(layer "In4.Cu")
		(net "P5E_CPU1_PE3_RX_DP<11>")
	)
	(segment
		(start 124.574554 -290.490148)
		(end 124.574554 -290.512246)
		(width 0.0889)
		(layer "In4.Cu")
		(net "P5E_CPU1_PE3_RX_DP<11>")
	)
	(segment
		(start 153.4287 -363.918246)
		(end 151.33701 -371.242082)
		(width 0.14732)
		(layer "In4.Cu")
		(net "P5E_CPU1_PE3_RX_DP<11>")
	)
	(segment
		(start 125.212348 -298.925488)
		(end 127.69469 -302.470058)
		(width 0.14732)
		(layer "In4.Cu")
		(net "P5E_CPU1_PE3_RX_DP<11>")
	)
	(segment
		(start 132.739384 -412.053786)
		(end 132.86486 -412.17215)
		(width 0.14732)
		(layer "In4.Cu")
		(net "P5E_CPU1_PE3_RX_DP<11>")
	)
	(segment
		(start 127.69469 -302.470058)
		(end 152.587198 -332.77048)
		(width 0.14732)
		(layer "In4.Cu")
		(net "P5E_CPU1_PE3_RX_DP<11>")
	)
	(segment
		(start 134.895336 -399.236692)
		(end 134.897368 -399.232628)
		(width 0.14732)
		(layer "In4.Cu")
		(net "P5E_CPU1_PE3_RX_DP<11>")
	)
	(segment
		(start 132.758688 -412.734506)
		(end 132.77088 -413.171132)
		(width 0.14732)
		(layer "In4.Cu")
		(net "P5E_CPU1_PE3_RX_DP<11>")
	)
	(segment
		(start 124.574554 -290.512246)
		(end 124.574554 -295.303448)
		(width 0.14732)
		(layer "In4.Cu")
		(net "P5E_CPU1_PE3_RX_DP<11>")
	)
	(segment
		(start 132.790184 -413.851852)
		(end 133.069584 -423.845482)
		(width 0.14732)
		(layer "In4.Cu")
		(net "P5E_CPU1_PE3_RX_DP<11>")
	)
	(segment
		(start 151.33701 -371.242082)
		(end 134.895336 -399.236692)
		(width 0.14732)
		(layer "In4.Cu")
		(net "P5E_CPU1_PE3_RX_DP<11>")
	)
	(segment
		(start 124.278644 -289.218116)
		(end 124.308616 -289.315144)
		(width 0.0889)
		(layer "In4.Cu")
		(net "P5E_CPU1_PE3_RX_DP<11>")
	)
	(segment
		(start 134.508494 -399.991834)
		(end 134.508494 -404.596092)
		(width 0.14732)
		(layer "In4.Cu")
		(net "P5E_CPU1_PE3_RX_DP<11>")
	)
	(segment
		(start 152.587198 -332.77048)
		(end 153.534364 -338.146898)
		(width 0.14732)
		(layer "In4.Cu")
		(net "P5E_CPU1_PE3_RX_DP<11>")
	)
	(segment
		(start 124.437648 -288.917126)
		(end 124.278644 -289.218116)
		(width 0.0889)
		(layer "In4.Cu")
		(net "P5E_CPU1_PE3_RX_DP<11>")
	)
	(segment
		(start 124.308616 -289.315144)
		(end 124.308362 -289.315398)
		(width 0.0889)
		(layer "In4.Cu")
		(net "P5E_CPU1_PE3_RX_DP<11>")
	)
	(segment
		(start 133.069584 -423.845482)
		(end 133.069584 -437.208168)
		(width 0.14732)
		(layer "In4.Cu")
		(net "P5E_CPU1_PE3_RX_DP<11>")
	)
	(segment
		(start 133.602476 -437.352694)
		(end 133.75005 -437.20512)
		(width 0.14732)
		(layer "In4.Cu")
		(net "P5E_CPU1_PE3_RX_DP<11>")
	)
	(segment
		(start 124.53239 -289.610292)
		(end 124.53239 -290.447984)
		(width 0.0889)
		(layer "In4.Cu")
		(net "P5E_CPU1_PE3_RX_DP<11>")
	)
	(segment
		(start 132.727192 -411.61716)
		(end 132.739384 -412.053786)
		(width 0.14732)
		(layer "In4.Cu")
		(net "P5E_CPU1_PE3_RX_DP<11>")
	)
	(segment
		(start 132.86486 -412.17215)
		(end 132.877052 -412.609284)
		(width 0.14732)
		(layer "In4.Cu")
		(net "P5E_CPU1_PE3_RX_DP<11>")
	)
	(segment
		(start 132.877052 -412.609284)
		(end 132.758688 -412.734506)
		(width 0.14732)
		(layer "In4.Cu")
		(net "P5E_CPU1_PE3_RX_DP<11>")
	)
	(segment
		(start 133.069584 -437.208168)
		(end 133.21411 -437.352694)
		(width 0.14732)
		(layer "In4.Cu")
		(net "P5E_CPU1_PE3_RX_DP<11>")
	)
	(segment
		(start 132.908548 -413.72663)
		(end 132.790184 -413.851852)
		(width 0.14732)
		(layer "In4.Cu")
		(net "P5E_CPU1_PE3_RX_DP<11>")
	)
	(segment
		(start 132.791454 -406.313132)
		(end 132.791454 -410.308044)
		(width 0.14732)
		(layer "In4.Cu")
		(net "P5E_CPU1_PE3_RX_DP<11>")
	)
	(segment
		(start 132.896356 -413.289496)
		(end 132.908548 -413.72663)
		(width 0.14732)
		(layer "In4.Cu")
		(net "P5E_CPU1_PE3_RX_DP<11>")
	)
	(segment
		(start 133.75005 -437.20512)
		(end 133.75005 -436.889906)
		(width 0.14732)
		(layer "In4.Cu")
		(net "P5E_CPU1_PE3_RX_DP<11>")
	)
	(segment
		(start 124.53239 -290.447984)
		(end 124.574554 -290.490148)
		(width 0.0889)
		(layer "In4.Cu")
		(net "P5E_CPU1_PE3_RX_DP<11>")
	)
	(segment
		(start 124.574554 -295.303448)
		(end 125.212348 -298.925488)
		(width 0.14732)
		(layer "In4.Cu")
		(net "P5E_CPU1_PE3_RX_DP<11>")
	)
	(arc
		(start 124.308362 -289.315398)
		(mid 124.430644 -289.428259)
		(end 124.51715 -289.570414)
		(width 0.0889)
		(layer "In4.Cu")
		(net "P5E_CPU1_PE3_RX_DP<11>")
	)
	(arc
		(start 124.51715 -289.570414)
		(mid 124.525252 -289.590215)
		(end 124.532644 -289.610292)
		(width 0.0889)
		(layer "In4.Cu")
		(net "P5E_CPU1_PE3_RX_DP<11>")
	)
	(segment
		(start 124.907294 -288.102802)
		(end 124.907548 -288.103056)
		(width 0.13208)
		(layer "F.Cu")
		(net "P5E_CPU1_PE3_RX_DP<10>")
	)
	(segment
		(start 124.907294 -287.567116)
		(end 124.907294 -288.102802)
		(width 0.13208)
		(layer "F.Cu")
		(net "P5E_CPU1_PE3_RX_DP<10>")
	)
	(segment
		(start 125.47219 -290.447984)
		(end 125.514354 -290.490148)
		(width 0.0889)
		(layer "In4.Cu")
		(net "P5E_CPU1_PE3_RX_DP<10>")
	)
	(segment
		(start 124.907548 -288.103056)
		(end 125.064012 -288.374074)
		(width 0.0889)
		(layer "In4.Cu")
		(net "P5E_CPU1_PE3_RX_DP<10>")
	)
	(segment
		(start 135.741156 -411.791912)
		(end 135.066786 -424.022012)
		(width 0.14732)
		(layer "In4.Cu")
		(net "P5E_CPU1_PE3_RX_DP<10>")
	)
	(segment
		(start 137.571734 -399.257774)
		(end 137.571734 -404.596092)
		(width 0.14732)
		(layer "In4.Cu")
		(net "P5E_CPU1_PE3_RX_DP<10>")
	)
	(segment
		(start 154.40787 -364.072678)
		(end 152.239218 -371.535452)
		(width 0.14732)
		(layer "In4.Cu")
		(net "P5E_CPU1_PE3_RX_DP<10>")
	)
	(segment
		(start 125.683518 -289.431476)
		(end 125.577854 -289.536886)
		(width 0.0889)
		(layer "In4.Cu")
		(net "P5E_CPU1_PE3_RX_DP<10>")
	)
	(segment
		(start 128.52908 -302.01997)
		(end 153.484072 -332.3971)
		(width 0.14732)
		(layer "In4.Cu")
		(net "P5E_CPU1_PE3_RX_DP<10>")
	)
	(segment
		(start 125.514354 -290.512246)
		(end 125.514608 -290.5125)
		(width 0.14732)
		(layer "In4.Cu")
		(net "P5E_CPU1_PE3_RX_DP<10>")
	)
	(segment
		(start 135.066786 -438.205372)
		(end 135.214106 -438.352692)
		(width 0.14732)
		(layer "In4.Cu")
		(net "P5E_CPU1_PE3_RX_DP<10>")
	)
	(segment
		(start 154.5717 -338.571586)
		(end 154.40787 -364.072678)
		(width 0.14732)
		(layer "In4.Cu")
		(net "P5E_CPU1_PE3_RX_DP<10>")
	)
	(segment
		(start 135.854694 -410.63799)
		(end 135.741156 -411.791912)
		(width 0.14732)
		(layer "In4.Cu")
		(net "P5E_CPU1_PE3_RX_DP<10>")
	)
	(segment
		(start 137.571734 -404.596092)
		(end 135.854694 -406.313132)
		(width 0.14732)
		(layer "In4.Cu")
		(net "P5E_CPU1_PE3_RX_DP<10>")
	)
	(segment
		(start 135.066786 -424.022012)
		(end 135.066786 -438.205372)
		(width 0.14732)
		(layer "In4.Cu")
		(net "P5E_CPU1_PE3_RX_DP<10>")
	)
	(segment
		(start 126.261622 -298.78147)
		(end 128.52908 -302.01997)
		(width 0.14732)
		(layer "In4.Cu")
		(net "P5E_CPU1_PE3_RX_DP<10>")
	)
	(segment
		(start 135.750046 -438.205118)
		(end 135.750046 -437.889904)
		(width 0.14732)
		(layer "In4.Cu")
		(net "P5E_CPU1_PE3_RX_DP<10>")
	)
	(segment
		(start 153.484072 -332.3971)
		(end 154.5717 -338.571586)
		(width 0.14732)
		(layer "In4.Cu")
		(net "P5E_CPU1_PE3_RX_DP<10>")
	)
	(segment
		(start 135.214106 -438.352692)
		(end 135.602472 -438.352692)
		(width 0.14732)
		(layer "In4.Cu")
		(net "P5E_CPU1_PE3_RX_DP<10>")
	)
	(segment
		(start 135.602472 -438.352692)
		(end 135.750046 -438.205118)
		(width 0.14732)
		(layer "In4.Cu")
		(net "P5E_CPU1_PE3_RX_DP<10>")
	)
	(segment
		(start 125.577854 -289.536886)
		(end 125.47219 -289.64255)
		(width 0.0889)
		(layer "In4.Cu")
		(net "P5E_CPU1_PE3_RX_DP<10>")
	)
	(segment
		(start 125.47219 -289.64255)
		(end 125.47219 -290.447984)
		(width 0.0889)
		(layer "In4.Cu")
		(net "P5E_CPU1_PE3_RX_DP<10>")
	)
	(segment
		(start 125.514354 -290.490148)
		(end 125.514354 -290.512246)
		(width 0.0889)
		(layer "In4.Cu")
		(net "P5E_CPU1_PE3_RX_DP<10>")
	)
	(segment
		(start 125.942598 -288.898584)
		(end 125.942598 -289.114484)
		(width 0.0889)
		(layer "In4.Cu")
		(net "P5E_CPU1_PE3_RX_DP<10>")
	)
	(segment
		(start 125.514608 -294.542972)
		(end 126.261622 -298.78147)
		(width 0.14732)
		(layer "In4.Cu")
		(net "P5E_CPU1_PE3_RX_DP<10>")
	)
	(segment
		(start 125.064012 -288.374074)
		(end 125.153166 -288.39795)
		(width 0.0889)
		(layer "In4.Cu")
		(net "P5E_CPU1_PE3_RX_DP<10>")
	)
	(segment
		(start 125.514608 -290.5125)
		(end 125.514608 -294.542972)
		(width 0.14732)
		(layer "In4.Cu")
		(net "P5E_CPU1_PE3_RX_DP<10>")
	)
	(segment
		(start 135.854694 -406.313132)
		(end 135.854694 -410.63799)
		(width 0.14732)
		(layer "In4.Cu")
		(net "P5E_CPU1_PE3_RX_DP<10>")
	)
	(segment
		(start 152.239218 -371.535452)
		(end 137.571734 -399.257774)
		(width 0.14732)
		(layer "In4.Cu")
		(net "P5E_CPU1_PE3_RX_DP<10>")
	)
	(arc
		(start 125.66015 -288.427414)
		(mid 125.862436 -288.626395)
		(end 125.942598 -288.898584)
		(width 0.0889)
		(layer "In4.Cu")
		(net "P5E_CPU1_PE3_RX_DP<10>")
	)
	(arc
		(start 125.153166 -288.39795)
		(mid 125.162907 -288.393795)
		(end 125.172724 -288.389822)
		(width 0.0889)
		(layer "In4.Cu")
		(net "P5E_CPU1_PE3_RX_DP<10>")
	)
	(arc
		(start 125.942598 -289.114484)
		(mid 125.841032 -289.295854)
		(end 125.683518 -289.431476)
		(width 0.0889)
		(layer "In4.Cu")
		(net "P5E_CPU1_PE3_RX_DP<10>")
	)
	(arc
		(start 125.172724 -288.389822)
		(mid 125.420704 -288.35321)
		(end 125.66015 -288.427414)
		(width 0.0889)
		(layer "In4.Cu")
		(net "P5E_CPU1_PE3_RX_DP<10>")
	)
	(segment
		(start 135.714994 -288.916872)
		(end 135.715248 -288.917126)
		(width 0.13208)
		(layer "F.Cu")
		(net "P5E_CPU1_PE3_RX_DP<0>")
	)
	(segment
		(start 135.714994 -288.381186)
		(end 135.714994 -288.916872)
		(width 0.13208)
		(layer "F.Cu")
		(net "P5E_CPU1_PE3_RX_DP<0>")
	)
	(segment
		(start 136.6393 -289.369754)
		(end 136.623806 -289.35426)
		(width 0.0889)
		(layer "In4.Cu")
		(net "P5E_CPU1_PE3_RX_DP<0>")
	)
	(segment
		(start 155.792424 -424.262042)
		(end 157.483302 -422.087802)
		(width 0.14732)
		(layer "In4.Cu")
		(net "P5E_CPU1_PE3_RX_DP<0>")
	)
	(segment
		(start 136.8933 -289.62477)
		(end 136.8933 -289.623754)
		(width 0.14732)
		(layer "In4.Cu")
		(net "P5E_CPU1_PE3_RX_DP<0>")
	)
	(segment
		(start 156.750004 -439.0898)
		(end 156.750004 -438.838594)
		(width 0.14732)
		(layer "In4.Cu")
		(net "P5E_CPU1_PE3_RX_DP<0>")
	)
	(segment
		(start 157.88132 -421.576246)
		(end 166.212774 -410.863542)
		(width 0.14732)
		(layer "In4.Cu")
		(net "P5E_CPU1_PE3_RX_DP<0>")
	)
	(segment
		(start 136.623806 -289.295332)
		(end 135.980424 -288.65195)
		(width 0.0889)
		(layer "In4.Cu")
		(net "P5E_CPU1_PE3_RX_DP<0>")
	)
	(segment
		(start 167.929814 -404.4823)
		(end 167.929814 -400.58721)
		(width 0.14732)
		(layer "In4.Cu")
		(net "P5E_CPU1_PE3_RX_DP<0>")
	)
	(segment
		(start 164.569648 -353.310952)
		(end 164.56914 -353.310952)
		(width 0.14732)
		(layer "In4.Cu")
		(net "P5E_CPU1_PE3_RX_DP<0>")
	)
	(segment
		(start 157.483302 -422.087802)
		(end 157.458918 -421.891714)
		(width 0.14732)
		(layer "In4.Cu")
		(net "P5E_CPU1_PE3_RX_DP<0>")
	)
	(segment
		(start 156.46146 -320.5353)
		(end 138.185906 -290.917122)
		(width 0.14732)
		(layer "In4.Cu")
		(net "P5E_CPU1_PE3_RX_DP<0>")
	)
	(segment
		(start 163.048442 -325.147432)
		(end 156.46146 -320.5353)
		(width 0.14732)
		(layer "In4.Cu")
		(net "P5E_CPU1_PE3_RX_DP<0>")
	)
	(segment
		(start 135.579866 -288.56813)
		(end 135.558784 -288.646108)
		(width 0.0889)
		(layer "In4.Cu")
		(net "P5E_CPU1_PE3_RX_DP<0>")
	)
	(segment
		(start 163.62426 -325.969884)
		(end 163.048442 -325.147432)
		(width 0.14732)
		(layer "In4.Cu")
		(net "P5E_CPU1_PE3_RX_DP<0>")
	)
	(segment
		(start 156.750004 -438.838594)
		(end 156.538422 -438.627012)
		(width 0.14732)
		(layer "In4.Cu")
		(net "P5E_CPU1_PE3_RX_DP<0>")
	)
	(segment
		(start 164.37991 -365.538766)
		(end 164.56914 -353.311206)
		(width 0.14732)
		(layer "In4.Cu")
		(net "P5E_CPU1_PE3_RX_DP<0>")
	)
	(segment
		(start 157.685232 -421.600884)
		(end 157.88132 -421.576246)
		(width 0.14732)
		(layer "In4.Cu")
		(net "P5E_CPU1_PE3_RX_DP<0>")
	)
	(segment
		(start 163.876228 -327.400158)
		(end 163.62426 -325.969884)
		(width 0.14732)
		(layer "In4.Cu")
		(net "P5E_CPU1_PE3_RX_DP<0>")
	)
	(segment
		(start 156.100272 -438.627012)
		(end 155.792424 -438.319164)
		(width 0.14732)
		(layer "In4.Cu")
		(net "P5E_CPU1_PE3_RX_DP<0>")
	)
	(segment
		(start 164.56914 -353.310952)
		(end 164.75837 -341.109046)
		(width 0.14732)
		(layer "In4.Cu")
		(net "P5E_CPU1_PE3_RX_DP<0>")
	)
	(segment
		(start 167.280336 -396.221712)
		(end 164.37991 -365.538766)
		(width 0.14732)
		(layer "In4.Cu")
		(net "P5E_CPU1_PE3_RX_DP<0>")
	)
	(segment
		(start 166.212774 -410.863542)
		(end 166.212774 -406.19934)
		(width 0.14732)
		(layer "In4.Cu")
		(net "P5E_CPU1_PE3_RX_DP<0>")
	)
	(segment
		(start 164.56914 -353.311206)
		(end 164.569648 -353.310952)
		(width 0.14732)
		(layer "In4.Cu")
		(net "P5E_CPU1_PE3_RX_DP<0>")
	)
	(segment
		(start 155.792424 -438.319164)
		(end 155.792424 -424.262042)
		(width 0.14732)
		(layer "In4.Cu")
		(net "P5E_CPU1_PE3_RX_DP<0>")
	)
	(segment
		(start 136.8933 -289.623754)
		(end 136.6393 -289.369754)
		(width 0.14732)
		(layer "In4.Cu")
		(net "P5E_CPU1_PE3_RX_DP<0>")
	)
	(segment
		(start 136.973564 -289.705034)
		(end 136.8933 -289.62477)
		(width 0.14732)
		(layer "In4.Cu")
		(net "P5E_CPU1_PE3_RX_DP<0>")
	)
	(segment
		(start 166.212774 -406.19934)
		(end 167.929814 -404.4823)
		(width 0.14732)
		(layer "In4.Cu")
		(net "P5E_CPU1_PE3_RX_DP<0>")
	)
	(segment
		(start 164.75837 -341.109046)
		(end 163.876228 -327.400158)
		(width 0.14732)
		(layer "In4.Cu")
		(net "P5E_CPU1_PE3_RX_DP<0>")
	)
	(segment
		(start 138.185906 -290.917122)
		(end 136.973564 -289.705034)
		(width 0.14732)
		(layer "In4.Cu")
		(net "P5E_CPU1_PE3_RX_DP<0>")
	)
	(segment
		(start 167.929814 -400.58721)
		(end 167.280336 -396.221712)
		(width 0.14732)
		(layer "In4.Cu")
		(net "P5E_CPU1_PE3_RX_DP<0>")
	)
	(segment
		(start 136.623806 -289.35426)
		(end 136.623806 -289.295332)
		(width 0.0889)
		(layer "In4.Cu")
		(net "P5E_CPU1_PE3_RX_DP<0>")
	)
	(segment
		(start 157.458918 -421.891714)
		(end 157.685232 -421.600884)
		(width 0.14732)
		(layer "In4.Cu")
		(net "P5E_CPU1_PE3_RX_DP<0>")
	)
	(segment
		(start 156.538422 -438.627012)
		(end 156.100272 -438.627012)
		(width 0.14732)
		(layer "In4.Cu")
		(net "P5E_CPU1_PE3_RX_DP<0>")
	)
	(segment
		(start 135.558784 -288.646108)
		(end 135.715248 -288.917126)
		(width 0.0889)
		(layer "In4.Cu")
		(net "P5E_CPU1_PE3_RX_DP<0>")
	)
	(arc
		(start 135.902446 -288.592768)
		(mid 135.743958 -288.543835)
		(end 135.579866 -288.56813)
		(width 0.0889)
		(layer "In4.Cu")
		(net "P5E_CPU1_PE3_RX_DP<0>")
	)
	(arc
		(start 135.980424 -288.65195)
		(mid 135.943374 -288.619804)
		(end 135.902446 -288.592768)
		(width 0.0889)
		(layer "In4.Cu")
		(net "P5E_CPU1_PE3_RX_DP<0>")
	)
	(segment
		(start 125.847094 -289.195002)
		(end 125.847094 -289.807142)
		(width 0.13208)
		(layer "F.Cu")
		(net "P5E_CPU1_PE3_RX_DN<9>")
	)
	(segment
		(start 126.180342 -290.512754)
		(end 126.180088 -290.490148)
		(width 0.0889)
		(layer "In4.Cu")
		(net "P5E_CPU1_PE3_RX_DN<9>")
	)
	(segment
		(start 136.792462 -423.286936)
		(end 138.358372 -411.865826)
		(width 0.14732)
		(layer "In4.Cu")
		(net "P5E_CPU1_PE3_RX_DN<9>")
	)
	(segment
		(start 129.204212 -301.80915)
		(end 126.875032 -298.484036)
		(width 0.14732)
		(layer "In4.Cu")
		(net "P5E_CPU1_PE3_RX_DN<9>")
	)
	(segment
		(start 126.180088 -290.490148)
		(end 126.221998 -290.448238)
		(width 0.0889)
		(layer "In4.Cu")
		(net "P5E_CPU1_PE3_RX_DN<9>")
	)
	(segment
		(start 126.875032 -298.484036)
		(end 126.187962 -294.587422)
		(width 0.14732)
		(layer "In4.Cu")
		(net "P5E_CPU1_PE3_RX_DN<9>")
	)
	(segment
		(start 138.643614 -410.431996)
		(end 138.643614 -406.19934)
		(width 0.14732)
		(layer "In4.Cu")
		(net "P5E_CPU1_PE3_RX_DN<9>")
	)
	(segment
		(start 126.006098 -289.506152)
		(end 125.847094 -289.807142)
		(width 0.0889)
		(layer "In4.Cu")
		(net "P5E_CPU1_PE3_RX_DN<9>")
	)
	(segment
		(start 137.750042 -438.089802)
		(end 137.750042 -437.774588)
		(width 0.14732)
		(layer "In4.Cu")
		(net "P5E_CPU1_PE3_RX_DN<9>")
	)
	(segment
		(start 154.329892 -332.393798)
		(end 129.204212 -301.80915)
		(width 0.14732)
		(layer "In4.Cu")
		(net "P5E_CPU1_PE3_RX_DN<9>")
	)
	(segment
		(start 137.10031 -437.627014)
		(end 136.792462 -437.319166)
		(width 0.14732)
		(layer "In4.Cu")
		(net "P5E_CPU1_PE3_RX_DN<9>")
	)
	(segment
		(start 152.798018 -372.089172)
		(end 155.25496 -364.03407)
		(width 0.14732)
		(layer "In4.Cu")
		(net "P5E_CPU1_PE3_RX_DN<9>")
	)
	(segment
		(start 126.187962 -294.587422)
		(end 126.180342 -290.512754)
		(width 0.14732)
		(layer "In4.Cu")
		(net "P5E_CPU1_PE3_RX_DN<9>")
	)
	(segment
		(start 126.09068 -289.480244)
		(end 126.006098 -289.506152)
		(width 0.0889)
		(layer "In4.Cu")
		(net "P5E_CPU1_PE3_RX_DN<9>")
	)
	(segment
		(start 137.750042 -437.774588)
		(end 137.602468 -437.627014)
		(width 0.14732)
		(layer "In4.Cu")
		(net "P5E_CPU1_PE3_RX_DN<9>")
	)
	(segment
		(start 136.792462 -437.319166)
		(end 136.792462 -423.286936)
		(width 0.14732)
		(layer "In4.Cu")
		(net "P5E_CPU1_PE3_RX_DN<9>")
	)
	(segment
		(start 140.360654 -398.916906)
		(end 152.798018 -372.089172)
		(width 0.14732)
		(layer "In4.Cu")
		(net "P5E_CPU1_PE3_RX_DN<9>")
	)
	(segment
		(start 155.441904 -338.70773)
		(end 154.329892 -332.393798)
		(width 0.14732)
		(layer "In4.Cu")
		(net "P5E_CPU1_PE3_RX_DN<9>")
	)
	(segment
		(start 126.090934 -289.480244)
		(end 126.09068 -289.480244)
		(width 0.0889)
		(layer "In4.Cu")
		(net "P5E_CPU1_PE3_RX_DN<9>")
	)
	(segment
		(start 138.358372 -411.865826)
		(end 138.643614 -410.431996)
		(width 0.14732)
		(layer "In4.Cu")
		(net "P5E_CPU1_PE3_RX_DN<9>")
	)
	(segment
		(start 138.643614 -406.19934)
		(end 140.360654 -404.4823)
		(width 0.14732)
		(layer "In4.Cu")
		(net "P5E_CPU1_PE3_RX_DN<9>")
	)
	(segment
		(start 155.25496 -364.03407)
		(end 155.441904 -338.70773)
		(width 0.14732)
		(layer "In4.Cu")
		(net "P5E_CPU1_PE3_RX_DN<9>")
	)
	(segment
		(start 140.360654 -404.4823)
		(end 140.360654 -398.916906)
		(width 0.14732)
		(layer "In4.Cu")
		(net "P5E_CPU1_PE3_RX_DN<9>")
	)
	(segment
		(start 126.221998 -290.448238)
		(end 126.221998 -289.645852)
		(width 0.0889)
		(layer "In4.Cu")
		(net "P5E_CPU1_PE3_RX_DN<9>")
	)
	(segment
		(start 137.602468 -437.627014)
		(end 137.10031 -437.627014)
		(width 0.14732)
		(layer "In4.Cu")
		(net "P5E_CPU1_PE3_RX_DN<9>")
	)
	(arc
		(start 126.221998 -289.645852)
		(mid 126.16737 -289.554417)
		(end 126.090934 -289.480244)
		(width 0.0889)
		(layer "In4.Cu")
		(net "P5E_CPU1_PE3_RX_DN<9>")
	)
	(segment
		(start 127.257048 -288.381186)
		(end 127.257048 -288.917126)
		(width 0.13208)
		(layer "F.Cu")
		(net "P5E_CPU1_PE3_RX_DN<8>")
	)
	(segment
		(start 127.100584 -288.646108)
		(end 127.257048 -288.917126)
		(width 0.0889)
		(layer "In4.Cu")
		(net "P5E_CPU1_PE3_RX_DN<8>")
	)
	(segment
		(start 155.300172 -332.109318)
		(end 130.995166 -302.523652)
		(width 0.14732)
		(layer "In4.Cu")
		(net "P5E_CPU1_PE3_RX_DN<8>")
	)
	(segment
		(start 127.631698 -289.077908)
		(end 127.631698 -288.917126)
		(width 0.0889)
		(layer "In4.Cu")
		(net "P5E_CPU1_PE3_RX_DN<8>")
	)
	(segment
		(start 139.091162 -438.617868)
		(end 138.792204 -438.31891)
		(width 0.14732)
		(layer "In4.Cu")
		(net "P5E_CPU1_PE3_RX_DN<8>")
	)
	(segment
		(start 141.706854 -410.624528)
		(end 141.706854 -406.19934)
		(width 0.14732)
		(layer "In4.Cu")
		(net "P5E_CPU1_PE3_RX_DN<8>")
	)
	(segment
		(start 139.59332 -438.617868)
		(end 139.091162 -438.617868)
		(width 0.14732)
		(layer "In4.Cu")
		(net "P5E_CPU1_PE3_RX_DN<8>")
	)
	(segment
		(start 141.167612 -412.404052)
		(end 141.706854 -410.624528)
		(width 0.14732)
		(layer "In4.Cu")
		(net "P5E_CPU1_PE3_RX_DN<8>")
	)
	(segment
		(start 127.119888 -293.69893)
		(end 127.119888 -290.512246)
		(width 0.14732)
		(layer "In4.Cu")
		(net "P5E_CPU1_PE3_RX_DN<8>")
	)
	(segment
		(start 138.792204 -424.314874)
		(end 138.813794 -424.293284)
		(width 0.14732)
		(layer "In4.Cu")
		(net "P5E_CPU1_PE3_RX_DN<8>")
	)
	(segment
		(start 143.423894 -404.4823)
		(end 143.423894 -399.128488)
		(width 0.14732)
		(layer "In4.Cu")
		(net "P5E_CPU1_PE3_RX_DN<8>")
	)
	(segment
		(start 139.750038 -439.0898)
		(end 139.750038 -438.774586)
		(width 0.14732)
		(layer "In4.Cu")
		(net "P5E_CPU1_PE3_RX_DN<8>")
	)
	(segment
		(start 127.161798 -289.58667)
		(end 127.177038 -289.57143)
		(width 0.0889)
		(layer "In4.Cu")
		(net "P5E_CPU1_PE3_RX_DN<8>")
	)
	(segment
		(start 156.215334 -364.14583)
		(end 156.490162 -338.866734)
		(width 0.14732)
		(layer "In4.Cu")
		(net "P5E_CPU1_PE3_RX_DN<8>")
	)
	(segment
		(start 141.706854 -406.19934)
		(end 143.423894 -404.4823)
		(width 0.14732)
		(layer "In4.Cu")
		(net "P5E_CPU1_PE3_RX_DN<8>")
	)
	(segment
		(start 127.161798 -290.448238)
		(end 127.161798 -289.58667)
		(width 0.0889)
		(layer "In4.Cu")
		(net "P5E_CPU1_PE3_RX_DN<8>")
	)
	(segment
		(start 156.490162 -338.866734)
		(end 155.300172 -332.109318)
		(width 0.14732)
		(layer "In4.Cu")
		(net "P5E_CPU1_PE3_RX_DN<8>")
	)
	(segment
		(start 127.453136 -288.597848)
		(end 127.444246 -288.592768)
		(width 0.0889)
		(layer "In4.Cu")
		(net "P5E_CPU1_PE3_RX_DN<8>")
	)
	(segment
		(start 127.121666 -288.56813)
		(end 127.100584 -288.646108)
		(width 0.0889)
		(layer "In4.Cu")
		(net "P5E_CPU1_PE3_RX_DN<8>")
	)
	(segment
		(start 127.893826 -298.096178)
		(end 127.119888 -293.69893)
		(width 0.14732)
		(layer "In4.Cu")
		(net "P5E_CPU1_PE3_RX_DN<8>")
	)
	(segment
		(start 127.119888 -290.512246)
		(end 127.119888 -290.490148)
		(width 0.0889)
		(layer "In4.Cu")
		(net "P5E_CPU1_PE3_RX_DN<8>")
	)
	(segment
		(start 138.792204 -438.31891)
		(end 138.792204 -424.314874)
		(width 0.14732)
		(layer "In4.Cu")
		(net "P5E_CPU1_PE3_RX_DN<8>")
	)
	(segment
		(start 138.813794 -424.293284)
		(end 141.167612 -412.404052)
		(width 0.14732)
		(layer "In4.Cu")
		(net "P5E_CPU1_PE3_RX_DN<8>")
	)
	(segment
		(start 130.995166 -302.523652)
		(end 127.893826 -298.096178)
		(width 0.14732)
		(layer "In4.Cu")
		(net "P5E_CPU1_PE3_RX_DN<8>")
	)
	(segment
		(start 153.739088 -372.775988)
		(end 156.215334 -364.14583)
		(width 0.14732)
		(layer "In4.Cu")
		(net "P5E_CPU1_PE3_RX_DN<8>")
	)
	(segment
		(start 127.447294 -289.278314)
		(end 127.447294 -289.277806)
		(width 0.0889)
		(layer "In4.Cu")
		(net "P5E_CPU1_PE3_RX_DN<8>")
	)
	(segment
		(start 139.750038 -438.774586)
		(end 139.59332 -438.617868)
		(width 0.14732)
		(layer "In4.Cu")
		(net "P5E_CPU1_PE3_RX_DN<8>")
	)
	(segment
		(start 127.119888 -290.490148)
		(end 127.161798 -290.448238)
		(width 0.0889)
		(layer "In4.Cu")
		(net "P5E_CPU1_PE3_RX_DN<8>")
	)
	(segment
		(start 143.423894 -399.128488)
		(end 153.739088 -372.775988)
		(width 0.14732)
		(layer "In4.Cu")
		(net "P5E_CPU1_PE3_RX_DN<8>")
	)
	(arc
		(start 127.444246 -288.592768)
		(mid 127.285758 -288.543835)
		(end 127.121666 -288.56813)
		(width 0.0889)
		(layer "In4.Cu")
		(net "P5E_CPU1_PE3_RX_DN<8>")
	)
	(arc
		(start 127.447294 -289.277806)
		(mid 127.55669 -289.193709)
		(end 127.631698 -289.077908)
		(width 0.0889)
		(layer "In4.Cu")
		(net "P5E_CPU1_PE3_RX_DN<8>")
	)
	(arc
		(start 127.631698 -288.917126)
		(mid 127.584019 -288.734226)
		(end 127.453136 -288.597848)
		(width 0.0889)
		(layer "In4.Cu")
		(net "P5E_CPU1_PE3_RX_DN<8>")
	)
	(arc
		(start 127.404876 -289.302952)
		(mid 127.425833 -289.2902)
		(end 127.447294 -289.278314)
		(width 0.0889)
		(layer "In4.Cu")
		(net "P5E_CPU1_PE3_RX_DN<8>")
	)
	(arc
		(start 127.177038 -289.57143)
		(mid 127.270777 -289.420074)
		(end 127.404876 -289.302952)
		(width 0.0889)
		(layer "In4.Cu")
		(net "P5E_CPU1_PE3_RX_DN<8>")
	)
	(segment
		(start 128.196848 -288.381186)
		(end 128.196848 -288.917126)
		(width 0.13208)
		(layer "F.Cu")
		(net "P5E_CPU1_PE3_RX_DN<7>")
	)
	(segment
		(start 142.772638 -421.701976)
		(end 142.628112 -421.795956)
		(width 0.14732)
		(layer "In4.Cu")
		(net "P5E_CPU1_PE3_RX_DN<7>")
	)
	(segment
		(start 142.862808 -421.27424)
		(end 142.772638 -421.701976)
		(width 0.14732)
		(layer "In4.Cu")
		(net "P5E_CPU1_PE3_RX_DN<7>")
	)
	(segment
		(start 157.814772 -339.254592)
		(end 157.438852 -364.246668)
		(width 0.14732)
		(layer "In4.Cu")
		(net "P5E_CPU1_PE3_RX_DN<7>")
	)
	(segment
		(start 142.750032 -437.20512)
		(end 142.750032 -436.889906)
		(width 0.14732)
		(layer "In4.Cu")
		(net "P5E_CPU1_PE3_RX_DN<7>")
	)
	(segment
		(start 128.333754 -293.286688)
		(end 129.115312 -297.722544)
		(width 0.14732)
		(layer "In4.Cu")
		(net "P5E_CPU1_PE3_RX_DN<7>")
	)
	(segment
		(start 142.542006 -422.795446)
		(end 142.397226 -422.88968)
		(width 0.14732)
		(layer "In4.Cu")
		(net "P5E_CPU1_PE3_RX_DN<7>")
	)
	(segment
		(start 128.196848 -288.917126)
		(end 128.037844 -289.218116)
		(width 0.0889)
		(layer "In4.Cu")
		(net "P5E_CPU1_PE3_RX_DN<7>")
	)
	(segment
		(start 145.044414 -410.361892)
		(end 145.038572 -410.367734)
		(width 0.14732)
		(layer "In4.Cu")
		(net "P5E_CPU1_PE3_RX_DN<7>")
	)
	(segment
		(start 142.066772 -424.457368)
		(end 142.066772 -437.205374)
		(width 0.14732)
		(layer "In4.Cu")
		(net "P5E_CPU1_PE3_RX_DN<7>")
	)
	(segment
		(start 142.066772 -437.205374)
		(end 142.214092 -437.352694)
		(width 0.14732)
		(layer "In4.Cu")
		(net "P5E_CPU1_PE3_RX_DN<7>")
	)
	(segment
		(start 145.038572 -410.367734)
		(end 142.768828 -421.129714)
		(width 0.14732)
		(layer "In4.Cu")
		(net "P5E_CPU1_PE3_RX_DN<7>")
	)
	(segment
		(start 128.29159 -289.609784)
		(end 128.29159 -290.447984)
		(width 0.0889)
		(layer "In4.Cu")
		(net "P5E_CPU1_PE3_RX_DN<7>")
	)
	(segment
		(start 128.29159 -290.447984)
		(end 128.333754 -290.490148)
		(width 0.0889)
		(layer "In4.Cu")
		(net "P5E_CPU1_PE3_RX_DN<7>")
	)
	(segment
		(start 142.538196 -422.223184)
		(end 142.632176 -422.36771)
		(width 0.14732)
		(layer "In4.Cu")
		(net "P5E_CPU1_PE3_RX_DN<7>")
	)
	(segment
		(start 154.835098 -374.301766)
		(end 146.761454 -399.279618)
		(width 0.14732)
		(layer "In4.Cu")
		(net "P5E_CPU1_PE3_RX_DN<7>")
	)
	(segment
		(start 142.768828 -421.129714)
		(end 142.862808 -421.27424)
		(width 0.14732)
		(layer "In4.Cu")
		(net "P5E_CPU1_PE3_RX_DN<7>")
	)
	(segment
		(start 142.397226 -422.88968)
		(end 142.066772 -424.457368)
		(width 0.14732)
		(layer "In4.Cu")
		(net "P5E_CPU1_PE3_RX_DN<7>")
	)
	(segment
		(start 156.471874 -331.631544)
		(end 157.814772 -339.254592)
		(width 0.14732)
		(layer "In4.Cu")
		(net "P5E_CPU1_PE3_RX_DN<7>")
	)
	(segment
		(start 142.214092 -437.352694)
		(end 142.602458 -437.352694)
		(width 0.14732)
		(layer "In4.Cu")
		(net "P5E_CPU1_PE3_RX_DN<7>")
	)
	(segment
		(start 128.291844 -289.60953)
		(end 128.29159 -289.609784)
		(width 0.0889)
		(layer "In4.Cu")
		(net "P5E_CPU1_PE3_RX_DN<7>")
	)
	(segment
		(start 145.044414 -406.313132)
		(end 145.044414 -410.361892)
		(width 0.14732)
		(layer "In4.Cu")
		(net "P5E_CPU1_PE3_RX_DN<7>")
	)
	(segment
		(start 142.632176 -422.36771)
		(end 142.542006 -422.795446)
		(width 0.14732)
		(layer "In4.Cu")
		(net "P5E_CPU1_PE3_RX_DN<7>")
	)
	(segment
		(start 146.761454 -399.279618)
		(end 146.761454 -404.596092)
		(width 0.14732)
		(layer "In4.Cu")
		(net "P5E_CPU1_PE3_RX_DN<7>")
	)
	(segment
		(start 129.115312 -297.722544)
		(end 132.00888 -301.854108)
		(width 0.14732)
		(layer "In4.Cu")
		(net "P5E_CPU1_PE3_RX_DN<7>")
	)
	(segment
		(start 132.00888 -301.854108)
		(end 156.471874 -331.631544)
		(width 0.14732)
		(layer "In4.Cu")
		(net "P5E_CPU1_PE3_RX_DN<7>")
	)
	(segment
		(start 157.438852 -364.246668)
		(end 154.835098 -374.301766)
		(width 0.14732)
		(layer "In4.Cu")
		(net "P5E_CPU1_PE3_RX_DN<7>")
	)
	(segment
		(start 142.628112 -421.795956)
		(end 142.538196 -422.223184)
		(width 0.14732)
		(layer "In4.Cu")
		(net "P5E_CPU1_PE3_RX_DN<7>")
	)
	(segment
		(start 146.761454 -404.596092)
		(end 145.044414 -406.313132)
		(width 0.14732)
		(layer "In4.Cu")
		(net "P5E_CPU1_PE3_RX_DN<7>")
	)
	(segment
		(start 128.333754 -290.512246)
		(end 128.333754 -293.286688)
		(width 0.14732)
		(layer "In4.Cu")
		(net "P5E_CPU1_PE3_RX_DN<7>")
	)
	(segment
		(start 142.602458 -437.352694)
		(end 142.750032 -437.20512)
		(width 0.14732)
		(layer "In4.Cu")
		(net "P5E_CPU1_PE3_RX_DN<7>")
	)
	(segment
		(start 128.037844 -289.218116)
		(end 128.067816 -289.315144)
		(width 0.0889)
		(layer "In4.Cu")
		(net "P5E_CPU1_PE3_RX_DN<7>")
	)
	(segment
		(start 128.333754 -290.490148)
		(end 128.333754 -290.512246)
		(width 0.0889)
		(layer "In4.Cu")
		(net "P5E_CPU1_PE3_RX_DN<7>")
	)
	(arc
		(start 128.276096 -289.569398)
		(mid 128.284327 -289.589324)
		(end 128.291844 -289.60953)
		(width 0.0889)
		(layer "In4.Cu")
		(net "P5E_CPU1_PE3_RX_DN<7>")
	)
	(arc
		(start 128.067816 -289.315144)
		(mid 128.189768 -289.427684)
		(end 128.276096 -289.569398)
		(width 0.0889)
		(layer "In4.Cu")
		(net "P5E_CPU1_PE3_RX_DN<7>")
	)
	(segment
		(start 128.666494 -288.102802)
		(end 128.666748 -288.103056)
		(width 0.13208)
		(layer "F.Cu")
		(net "P5E_CPU1_PE3_RX_DN<6>")
	)
	(segment
		(start 128.666494 -287.567116)
		(end 128.666494 -288.102802)
		(width 0.13208)
		(layer "F.Cu")
		(net "P5E_CPU1_PE3_RX_DN<6>")
	)
	(segment
		(start 144.214088 -438.352692)
		(end 144.602454 -438.352692)
		(width 0.14732)
		(layer "In4.Cu")
		(net "P5E_CPU1_PE3_RX_DN<6>")
	)
	(segment
		(start 148.107654 -406.313132)
		(end 148.107654 -410.362654)
		(width 0.14732)
		(layer "In4.Cu")
		(net "P5E_CPU1_PE3_RX_DN<6>")
	)
	(segment
		(start 148.107654 -410.362654)
		(end 145.991326 -417.576508)
		(width 0.14732)
		(layer "In4.Cu")
		(net "P5E_CPU1_PE3_RX_DN<6>")
	)
	(segment
		(start 130.078734 -297.4594)
		(end 132.813298 -301.364142)
		(width 0.14732)
		(layer "In4.Cu")
		(net "P5E_CPU1_PE3_RX_DN<6>")
	)
	(segment
		(start 129.231644 -289.64636)
		(end 129.231644 -290.447984)
		(width 0.0889)
		(layer "In4.Cu")
		(net "P5E_CPU1_PE3_RX_DN<6>")
	)
	(segment
		(start 145.990564 -417.57727)
		(end 144.066768 -424.134788)
		(width 0.14732)
		(layer "In4.Cu")
		(net "P5E_CPU1_PE3_RX_DN<6>")
	)
	(segment
		(start 128.666748 -288.103056)
		(end 128.823212 -288.374074)
		(width 0.0889)
		(layer "In4.Cu")
		(net "P5E_CPU1_PE3_RX_DN<6>")
	)
	(segment
		(start 158.393638 -364.28426)
		(end 149.824694 -399.168366)
		(width 0.14732)
		(layer "In4.Cu")
		(net "P5E_CPU1_PE3_RX_DN<6>")
	)
	(segment
		(start 145.991326 -417.576508)
		(end 145.990818 -417.576508)
		(width 0.14732)
		(layer "In4.Cu")
		(net "P5E_CPU1_PE3_RX_DN<6>")
	)
	(segment
		(start 149.824694 -399.168366)
		(end 149.824694 -404.596092)
		(width 0.14732)
		(layer "In4.Cu")
		(net "P5E_CPU1_PE3_RX_DN<6>")
	)
	(segment
		(start 129.701798 -288.898584)
		(end 129.701798 -289.114484)
		(width 0.0889)
		(layer "In4.Cu")
		(net "P5E_CPU1_PE3_RX_DN<6>")
	)
	(segment
		(start 129.273808 -290.490148)
		(end 129.273808 -290.512246)
		(width 0.0889)
		(layer "In4.Cu")
		(net "P5E_CPU1_PE3_RX_DN<6>")
	)
	(segment
		(start 144.602454 -438.352692)
		(end 144.750028 -438.205118)
		(width 0.14732)
		(layer "In4.Cu")
		(net "P5E_CPU1_PE3_RX_DN<6>")
	)
	(segment
		(start 157.384496 -331.273404)
		(end 158.850584 -339.598508)
		(width 0.14732)
		(layer "In4.Cu")
		(net "P5E_CPU1_PE3_RX_DN<6>")
	)
	(segment
		(start 129.273808 -292.894766)
		(end 130.078734 -297.4594)
		(width 0.14732)
		(layer "In4.Cu")
		(net "P5E_CPU1_PE3_RX_DN<6>")
	)
	(segment
		(start 144.066768 -438.205372)
		(end 144.214088 -438.352692)
		(width 0.14732)
		(layer "In4.Cu")
		(net "P5E_CPU1_PE3_RX_DN<6>")
	)
	(segment
		(start 132.813298 -301.364142)
		(end 157.384496 -331.273404)
		(width 0.14732)
		(layer "In4.Cu")
		(net "P5E_CPU1_PE3_RX_DN<6>")
	)
	(segment
		(start 158.850584 -339.598508)
		(end 158.393638 -364.28426)
		(width 0.14732)
		(layer "In4.Cu")
		(net "P5E_CPU1_PE3_RX_DN<6>")
	)
	(segment
		(start 129.231644 -290.447984)
		(end 129.273808 -290.490148)
		(width 0.0889)
		(layer "In4.Cu")
		(net "P5E_CPU1_PE3_RX_DN<6>")
	)
	(segment
		(start 144.066768 -424.134788)
		(end 144.066768 -438.205372)
		(width 0.14732)
		(layer "In4.Cu")
		(net "P5E_CPU1_PE3_RX_DN<6>")
	)
	(segment
		(start 129.273808 -290.512246)
		(end 129.273808 -292.894766)
		(width 0.14732)
		(layer "In4.Cu")
		(net "P5E_CPU1_PE3_RX_DN<6>")
	)
	(segment
		(start 145.990818 -417.576508)
		(end 145.990564 -417.57727)
		(width 0.14732)
		(layer "In4.Cu")
		(net "P5E_CPU1_PE3_RX_DN<6>")
	)
	(segment
		(start 144.750028 -438.205118)
		(end 144.750028 -437.889904)
		(width 0.14732)
		(layer "In4.Cu")
		(net "P5E_CPU1_PE3_RX_DN<6>")
	)
	(segment
		(start 128.823212 -288.374074)
		(end 128.912366 -288.39795)
		(width 0.0889)
		(layer "In4.Cu")
		(net "P5E_CPU1_PE3_RX_DN<6>")
	)
	(segment
		(start 149.824694 -404.596092)
		(end 148.107654 -406.313132)
		(width 0.14732)
		(layer "In4.Cu")
		(net "P5E_CPU1_PE3_RX_DN<6>")
	)
	(arc
		(start 128.912366 -288.39795)
		(mid 128.922107 -288.393795)
		(end 128.931924 -288.389822)
		(width 0.0889)
		(layer "In4.Cu")
		(net "P5E_CPU1_PE3_RX_DN<6>")
	)
	(arc
		(start 128.931924 -288.389822)
		(mid 129.179904 -288.35321)
		(end 129.41935 -288.427414)
		(width 0.0889)
		(layer "In4.Cu")
		(net "P5E_CPU1_PE3_RX_DN<6>")
	)
	(arc
		(start 129.701798 -289.114484)
		(mid 129.590402 -289.307577)
		(end 129.416048 -289.446462)
		(width 0.0889)
		(layer "In4.Cu")
		(net "P5E_CPU1_PE3_RX_DN<6>")
	)
	(arc
		(start 129.41935 -288.427414)
		(mid 129.621636 -288.626395)
		(end 129.701798 -288.898584)
		(width 0.0889)
		(layer "In4.Cu")
		(net "P5E_CPU1_PE3_RX_DN<6>")
	)
	(arc
		(start 129.416048 -289.446462)
		(mid 129.306652 -289.530559)
		(end 129.231644 -289.64636)
		(width 0.0889)
		(layer "In4.Cu")
		(net "P5E_CPU1_PE3_RX_DN<6>")
	)
	(segment
		(start 130.076448 -288.381186)
		(end 130.076448 -288.917126)
		(width 0.13208)
		(layer "F.Cu")
		(net "P5E_CPU1_PE3_RX_DN<5>")
	)
	(segment
		(start 130.2131 -291.379148)
		(end 130.2131 -291.670232)
		(width 0.14732)
		(layer "In4.Cu")
		(net "P5E_CPU1_PE3_RX_DN<5>")
	)
	(segment
		(start 146.76755 -422.60139)
		(end 146.639026 -422.94683)
		(width 0.14732)
		(layer "In4.Cu")
		(net "P5E_CPU1_PE3_RX_DN<5>")
	)
	(segment
		(start 129.947416 -289.315144)
		(end 129.947162 -289.315652)
		(width 0.0889)
		(layer "In4.Cu")
		(net "P5E_CPU1_PE3_RX_DN<5>")
	)
	(segment
		(start 159.91078 -339.97519)
		(end 159.346138 -364.30458)
		(width 0.14732)
		(layer "In4.Cu")
		(net "P5E_CPU1_PE3_RX_DN<5>")
	)
	(segment
		(start 146.214084 -437.352694)
		(end 146.60245 -437.352694)
		(width 0.14732)
		(layer "In4.Cu")
		(net "P5E_CPU1_PE3_RX_DN<5>")
	)
	(segment
		(start 159.91078 -339.972904)
		(end 159.91078 -339.97519)
		(width 0.14732)
		(layer "In4.Cu")
		(net "P5E_CPU1_PE3_RX_DN<5>")
	)
	(segment
		(start 146.06651 -424.083988)
		(end 146.06651 -424.232324)
		(width 0.14732)
		(layer "In4.Cu")
		(net "P5E_CPU1_PE3_RX_DN<5>")
	)
	(segment
		(start 146.813524 -422.07688)
		(end 146.685254 -422.421812)
		(width 0.14732)
		(layer "In4.Cu")
		(net "P5E_CPU1_PE3_RX_DN<5>")
	)
	(segment
		(start 130.17119 -291.141404)
		(end 130.213354 -291.183568)
		(width 0.0889)
		(layer "In4.Cu")
		(net "P5E_CPU1_PE3_RX_DN<5>")
	)
	(segment
		(start 158.328868 -330.972414)
		(end 159.91078 -339.972904)
		(width 0.14732)
		(layer "In4.Cu")
		(net "P5E_CPU1_PE3_RX_DN<5>")
	)
	(segment
		(start 146.066764 -437.205374)
		(end 146.214084 -437.352694)
		(width 0.14732)
		(layer "In4.Cu")
		(net "P5E_CPU1_PE3_RX_DN<5>")
	)
	(segment
		(start 146.639026 -422.94683)
		(end 146.459194 -423.028872)
		(width 0.14732)
		(layer "In4.Cu")
		(net "P5E_CPU1_PE3_RX_DN<5>")
	)
	(segment
		(start 159.346138 -364.30458)
		(end 152.887934 -398.683734)
		(width 0.14732)
		(layer "In4.Cu")
		(net "P5E_CPU1_PE3_RX_DN<5>")
	)
	(segment
		(start 135.660892 -295.638982)
		(end 154.128724 -325.57847)
		(width 0.14732)
		(layer "In4.Cu")
		(net "P5E_CPU1_PE3_RX_DN<5>")
	)
	(segment
		(start 129.917444 -289.218116)
		(end 129.947416 -289.315144)
		(width 0.0889)
		(layer "In4.Cu")
		(net "P5E_CPU1_PE3_RX_DN<5>")
	)
	(segment
		(start 130.213354 -291.378894)
		(end 130.2131 -291.379148)
		(width 0.14732)
		(layer "In4.Cu")
		(net "P5E_CPU1_PE3_RX_DN<5>")
	)
	(segment
		(start 146.750024 -437.20512)
		(end 146.750024 -436.889906)
		(width 0.14732)
		(layer "In4.Cu")
		(net "P5E_CPU1_PE3_RX_DN<5>")
	)
	(segment
		(start 134.808214 -294.786558)
		(end 135.660892 -295.638982)
		(width 0.14732)
		(layer "In4.Cu")
		(net "P5E_CPU1_PE3_RX_DN<5>")
	)
	(segment
		(start 130.213354 -291.205666)
		(end 130.213354 -291.378894)
		(width 0.14732)
		(layer "In4.Cu")
		(net "P5E_CPU1_PE3_RX_DN<5>")
	)
	(segment
		(start 154.128724 -325.57847)
		(end 158.328868 -330.972414)
		(width 0.14732)
		(layer "In4.Cu")
		(net "P5E_CPU1_PE3_RX_DN<5>")
	)
	(segment
		(start 151.170894 -410.368496)
		(end 147.039838 -421.469566)
		(width 0.14732)
		(layer "In4.Cu")
		(net "P5E_CPU1_PE3_RX_DN<5>")
	)
	(segment
		(start 130.076448 -288.917126)
		(end 129.917444 -289.218116)
		(width 0.0889)
		(layer "In4.Cu")
		(net "P5E_CPU1_PE3_RX_DN<5>")
	)
	(segment
		(start 152.887934 -398.683734)
		(end 152.887934 -404.596092)
		(width 0.14732)
		(layer "In4.Cu")
		(net "P5E_CPU1_PE3_RX_DN<5>")
	)
	(segment
		(start 146.06651 -424.232324)
		(end 146.066764 -424.769788)
		(width 0.14732)
		(layer "In4.Cu")
		(net "P5E_CPU1_PE3_RX_DN<5>")
	)
	(segment
		(start 146.99361 -421.994584)
		(end 146.813524 -422.07688)
		(width 0.14732)
		(layer "In4.Cu")
		(net "P5E_CPU1_PE3_RX_DN<5>")
	)
	(segment
		(start 130.213354 -291.183568)
		(end 130.213354 -291.205666)
		(width 0.0889)
		(layer "In4.Cu")
		(net "P5E_CPU1_PE3_RX_DN<5>")
	)
	(segment
		(start 147.12188 -421.649144)
		(end 146.99361 -421.994584)
		(width 0.14732)
		(layer "In4.Cu")
		(net "P5E_CPU1_PE3_RX_DN<5>")
	)
	(segment
		(start 146.459194 -423.028872)
		(end 146.06651 -424.083988)
		(width 0.14732)
		(layer "In4.Cu")
		(net "P5E_CPU1_PE3_RX_DN<5>")
	)
	(segment
		(start 147.039838 -421.469566)
		(end 147.12188 -421.649144)
		(width 0.14732)
		(layer "In4.Cu")
		(net "P5E_CPU1_PE3_RX_DN<5>")
	)
	(segment
		(start 146.685254 -422.421812)
		(end 146.76755 -422.60139)
		(width 0.14732)
		(layer "In4.Cu")
		(net "P5E_CPU1_PE3_RX_DN<5>")
	)
	(segment
		(start 146.60245 -437.352694)
		(end 146.750024 -437.20512)
		(width 0.14732)
		(layer "In4.Cu")
		(net "P5E_CPU1_PE3_RX_DN<5>")
	)
	(segment
		(start 151.170894 -406.313132)
		(end 151.170894 -410.368496)
		(width 0.14732)
		(layer "In4.Cu")
		(net "P5E_CPU1_PE3_RX_DN<5>")
	)
	(segment
		(start 133.329426 -294.786558)
		(end 134.808214 -294.786558)
		(width 0.14732)
		(layer "In4.Cu")
		(net "P5E_CPU1_PE3_RX_DN<5>")
	)
	(segment
		(start 152.887934 -404.596092)
		(end 151.170894 -406.313132)
		(width 0.14732)
		(layer "In4.Cu")
		(net "P5E_CPU1_PE3_RX_DN<5>")
	)
	(segment
		(start 130.2131 -291.670232)
		(end 133.329426 -294.786558)
		(width 0.14732)
		(layer "In4.Cu")
		(net "P5E_CPU1_PE3_RX_DN<5>")
	)
	(segment
		(start 146.066764 -424.769788)
		(end 146.066764 -437.205374)
		(width 0.14732)
		(layer "In4.Cu")
		(net "P5E_CPU1_PE3_RX_DN<5>")
	)
	(segment
		(start 130.17119 -289.610292)
		(end 130.17119 -291.141404)
		(width 0.0889)
		(layer "In4.Cu")
		(net "P5E_CPU1_PE3_RX_DN<5>")
	)
	(arc
		(start 129.947162 -289.315652)
		(mid 130.08255 -289.445204)
		(end 130.17119 -289.610292)
		(width 0.0889)
		(layer "In4.Cu")
		(net "P5E_CPU1_PE3_RX_DN<5>")
	)
	(segment
		(start 130.546094 -288.102802)
		(end 130.546348 -288.103056)
		(width 0.13208)
		(layer "F.Cu")
		(net "P5E_CPU1_PE3_RX_DN<4>")
	)
	(segment
		(start 130.546094 -287.567116)
		(end 130.546094 -288.102802)
		(width 0.13208)
		(layer "F.Cu")
		(net "P5E_CPU1_PE3_RX_DN<4>")
	)
	(segment
		(start 154.234134 -406.313132)
		(end 154.234134 -410.845254)
		(width 0.14732)
		(layer "In4.Cu")
		(net "P5E_CPU1_PE3_RX_DN<4>")
	)
	(segment
		(start 131.153408 -290.723574)
		(end 131.153154 -290.723828)
		(width 0.14732)
		(layer "In4.Cu")
		(net "P5E_CPU1_PE3_RX_DN<4>")
	)
	(segment
		(start 131.153154 -291.183822)
		(end 133.819392 -293.85006)
		(width 0.14732)
		(layer "In4.Cu")
		(net "P5E_CPU1_PE3_RX_DN<4>")
	)
	(segment
		(start 154.234134 -410.845254)
		(end 148.06676 -424.129962)
		(width 0.14732)
		(layer "In4.Cu")
		(net "P5E_CPU1_PE3_RX_DN<4>")
	)
	(segment
		(start 148.21408 -438.352692)
		(end 148.538438 -438.352692)
		(width 0.14732)
		(layer "In4.Cu")
		(net "P5E_CPU1_PE3_RX_DN<4>")
	)
	(segment
		(start 131.153408 -290.568126)
		(end 131.153408 -290.723574)
		(width 0.14732)
		(layer "In4.Cu")
		(net "P5E_CPU1_PE3_RX_DN<4>")
	)
	(segment
		(start 131.111244 -290.503864)
		(end 131.153408 -290.546028)
		(width 0.0889)
		(layer "In4.Cu")
		(net "P5E_CPU1_PE3_RX_DN<4>")
	)
	(segment
		(start 130.546348 -288.103056)
		(end 130.702812 -288.374074)
		(width 0.0889)
		(layer "In4.Cu")
		(net "P5E_CPU1_PE3_RX_DN<4>")
	)
	(segment
		(start 135.196834 -293.85006)
		(end 136.44372 -295.096946)
		(width 0.14732)
		(layer "In4.Cu")
		(net "P5E_CPU1_PE3_RX_DN<4>")
	)
	(segment
		(start 148.75002 -438.14111)
		(end 148.75002 -437.889904)
		(width 0.14732)
		(layer "In4.Cu")
		(net "P5E_CPU1_PE3_RX_DN<4>")
	)
	(segment
		(start 131.111244 -289.64636)
		(end 131.111244 -290.503864)
		(width 0.0889)
		(layer "In4.Cu")
		(net "P5E_CPU1_PE3_RX_DN<4>")
	)
	(segment
		(start 136.44372 -295.096946)
		(end 155.02763 -325.214742)
		(width 0.14732)
		(layer "In4.Cu")
		(net "P5E_CPU1_PE3_RX_DN<4>")
	)
	(segment
		(start 131.153408 -290.546028)
		(end 131.153408 -290.568126)
		(width 0.0889)
		(layer "In4.Cu")
		(net "P5E_CPU1_PE3_RX_DN<4>")
	)
	(segment
		(start 155.02763 -325.214742)
		(end 159.212534 -330.589636)
		(width 0.14732)
		(layer "In4.Cu")
		(net "P5E_CPU1_PE3_RX_DN<4>")
	)
	(segment
		(start 160.42132 -364.382558)
		(end 155.951174 -397.531336)
		(width 0.14732)
		(layer "In4.Cu")
		(net "P5E_CPU1_PE3_RX_DN<4>")
	)
	(segment
		(start 155.951174 -404.596092)
		(end 154.234134 -406.313132)
		(width 0.14732)
		(layer "In4.Cu")
		(net "P5E_CPU1_PE3_RX_DN<4>")
	)
	(segment
		(start 131.153154 -290.723828)
		(end 131.153154 -291.183822)
		(width 0.14732)
		(layer "In4.Cu")
		(net "P5E_CPU1_PE3_RX_DN<4>")
	)
	(segment
		(start 159.212534 -330.589636)
		(end 160.927796 -340.355428)
		(width 0.14732)
		(layer "In4.Cu")
		(net "P5E_CPU1_PE3_RX_DN<4>")
	)
	(segment
		(start 155.951174 -397.531336)
		(end 155.951174 -404.596092)
		(width 0.14732)
		(layer "In4.Cu")
		(net "P5E_CPU1_PE3_RX_DN<4>")
	)
	(segment
		(start 160.927796 -340.355428)
		(end 160.42132 -364.382558)
		(width 0.14732)
		(layer "In4.Cu")
		(net "P5E_CPU1_PE3_RX_DN<4>")
	)
	(segment
		(start 130.702812 -288.374074)
		(end 130.791966 -288.39795)
		(width 0.0889)
		(layer "In4.Cu")
		(net "P5E_CPU1_PE3_RX_DN<4>")
	)
	(segment
		(start 148.06676 -424.129962)
		(end 148.06676 -438.205372)
		(width 0.14732)
		(layer "In4.Cu")
		(net "P5E_CPU1_PE3_RX_DN<4>")
	)
	(segment
		(start 133.819392 -293.85006)
		(end 135.196834 -293.85006)
		(width 0.14732)
		(layer "In4.Cu")
		(net "P5E_CPU1_PE3_RX_DN<4>")
	)
	(segment
		(start 148.538438 -438.352692)
		(end 148.75002 -438.14111)
		(width 0.14732)
		(layer "In4.Cu")
		(net "P5E_CPU1_PE3_RX_DN<4>")
	)
	(segment
		(start 131.581398 -288.898584)
		(end 131.581398 -289.114484)
		(width 0.0889)
		(layer "In4.Cu")
		(net "P5E_CPU1_PE3_RX_DN<4>")
	)
	(segment
		(start 148.06676 -438.205372)
		(end 148.21408 -438.352692)
		(width 0.14732)
		(layer "In4.Cu")
		(net "P5E_CPU1_PE3_RX_DN<4>")
	)
	(arc
		(start 131.29895 -288.427414)
		(mid 131.501236 -288.626395)
		(end 131.581398 -288.898584)
		(width 0.0889)
		(layer "In4.Cu")
		(net "P5E_CPU1_PE3_RX_DN<4>")
	)
	(arc
		(start 131.581398 -289.114484)
		(mid 131.470002 -289.307577)
		(end 131.295648 -289.446462)
		(width 0.0889)
		(layer "In4.Cu")
		(net "P5E_CPU1_PE3_RX_DN<4>")
	)
	(arc
		(start 130.811524 -288.389822)
		(mid 131.059504 -288.35321)
		(end 131.29895 -288.427414)
		(width 0.0889)
		(layer "In4.Cu")
		(net "P5E_CPU1_PE3_RX_DN<4>")
	)
	(arc
		(start 130.791966 -288.39795)
		(mid 130.801707 -288.393795)
		(end 130.811524 -288.389822)
		(width 0.0889)
		(layer "In4.Cu")
		(net "P5E_CPU1_PE3_RX_DN<4>")
	)
	(arc
		(start 131.295648 -289.446462)
		(mid 131.186252 -289.530559)
		(end 131.111244 -289.64636)
		(width 0.0889)
		(layer "In4.Cu")
		(net "P5E_CPU1_PE3_RX_DN<4>")
	)
	(segment
		(start 131.485894 -289.195002)
		(end 131.485894 -289.807142)
		(width 0.13208)
		(layer "F.Cu")
		(net "P5E_CPU1_PE3_RX_DN<3>")
	)
	(segment
		(start 137.035794 -294.724582)
		(end 135.46074 -293.149528)
		(width 0.14732)
		(layer "In4.Cu")
		(net "P5E_CPU1_PE3_RX_DN<3>")
	)
	(segment
		(start 161.32937 -364.759748)
		(end 161.708338 -340.639908)
		(width 0.14732)
		(layer "In4.Cu")
		(net "P5E_CPU1_PE3_RX_DN<3>")
	)
	(segment
		(start 158.740094 -400.702018)
		(end 161.320226 -364.944406)
		(width 0.14732)
		(layer "In4.Cu")
		(net "P5E_CPU1_PE3_RX_DN<3>")
	)
	(segment
		(start 157.023054 -406.19934)
		(end 158.740094 -404.4823)
		(width 0.14732)
		(layer "In4.Cu")
		(net "P5E_CPU1_PE3_RX_DN<3>")
	)
	(segment
		(start 131.729734 -289.479736)
		(end 131.72948 -289.480244)
		(width 0.0889)
		(layer "In4.Cu")
		(net "P5E_CPU1_PE3_RX_DN<3>")
	)
	(segment
		(start 161.708338 -340.639908)
		(end 160.862518 -335.210912)
		(width 0.14732)
		(layer "In4.Cu")
		(net "P5E_CPU1_PE3_RX_DN<3>")
	)
	(segment
		(start 157.023054 -410.49194)
		(end 157.023054 -406.19934)
		(width 0.14732)
		(layer "In4.Cu")
		(net "P5E_CPU1_PE3_RX_DN<3>")
	)
	(segment
		(start 160.04159 -330.556108)
		(end 155.724098 -325.011034)
		(width 0.14732)
		(layer "In4.Cu")
		(net "P5E_CPU1_PE3_RX_DN<3>")
	)
	(segment
		(start 149.792182 -424.396916)
		(end 157.023054 -410.49194)
		(width 0.14732)
		(layer "In4.Cu")
		(net "P5E_CPU1_PE3_RX_DN<3>")
	)
	(segment
		(start 131.72948 -289.480244)
		(end 131.644898 -289.506152)
		(width 0.0889)
		(layer "In4.Cu")
		(net "P5E_CPU1_PE3_RX_DN<3>")
	)
	(segment
		(start 150.602442 -437.627014)
		(end 150.100284 -437.627014)
		(width 0.14732)
		(layer "In4.Cu")
		(net "P5E_CPU1_PE3_RX_DN<3>")
	)
	(segment
		(start 161.320226 -364.944406)
		(end 161.32937 -364.759748)
		(width 0.14732)
		(layer "In4.Cu")
		(net "P5E_CPU1_PE3_RX_DN<3>")
	)
	(segment
		(start 155.724098 -325.011034)
		(end 137.035794 -294.724582)
		(width 0.14732)
		(layer "In4.Cu")
		(net "P5E_CPU1_PE3_RX_DN<3>")
	)
	(segment
		(start 150.750016 -438.089802)
		(end 150.750016 -437.774588)
		(width 0.14732)
		(layer "In4.Cu")
		(net "P5E_CPU1_PE3_RX_DN<3>")
	)
	(segment
		(start 150.100284 -437.627014)
		(end 149.792436 -437.319166)
		(width 0.14732)
		(layer "In4.Cu")
		(net "P5E_CPU1_PE3_RX_DN<3>")
	)
	(segment
		(start 149.792436 -437.319166)
		(end 149.792436 -424.39717)
		(width 0.14732)
		(layer "In4.Cu")
		(net "P5E_CPU1_PE3_RX_DN<3>")
	)
	(segment
		(start 160.862518 -335.210912)
		(end 160.04159 -330.556108)
		(width 0.14732)
		(layer "In4.Cu")
		(net "P5E_CPU1_PE3_RX_DN<3>")
	)
	(segment
		(start 149.792436 -424.39717)
		(end 149.792182 -424.396916)
		(width 0.14732)
		(layer "In4.Cu")
		(net "P5E_CPU1_PE3_RX_DN<3>")
	)
	(segment
		(start 131.860798 -290.185348)
		(end 131.860798 -289.64509)
		(width 0.0889)
		(layer "In4.Cu")
		(net "P5E_CPU1_PE3_RX_DN<3>")
	)
	(segment
		(start 131.968494 -290.413186)
		(end 131.860798 -290.185348)
		(width 0.0889)
		(layer "In4.Cu")
		(net "P5E_CPU1_PE3_RX_DN<3>")
	)
	(segment
		(start 131.644898 -289.506152)
		(end 131.485894 -289.807142)
		(width 0.0889)
		(layer "In4.Cu")
		(net "P5E_CPU1_PE3_RX_DN<3>")
	)
	(segment
		(start 150.750016 -437.774588)
		(end 150.602442 -437.627014)
		(width 0.14732)
		(layer "In4.Cu")
		(net "P5E_CPU1_PE3_RX_DN<3>")
	)
	(segment
		(start 131.926584 -291.00018)
		(end 131.926584 -290.674806)
		(width 0.14732)
		(layer "In4.Cu")
		(net "P5E_CPU1_PE3_RX_DN<3>")
	)
	(segment
		(start 158.740094 -404.4823)
		(end 158.740094 -400.702018)
		(width 0.14732)
		(layer "In4.Cu")
		(net "P5E_CPU1_PE3_RX_DN<3>")
	)
	(segment
		(start 131.926584 -290.652708)
		(end 131.968494 -290.610798)
		(width 0.0889)
		(layer "In4.Cu")
		(net "P5E_CPU1_PE3_RX_DN<3>")
	)
	(segment
		(start 135.46074 -293.149528)
		(end 134.075932 -293.149528)
		(width 0.14732)
		(layer "In4.Cu")
		(net "P5E_CPU1_PE3_RX_DN<3>")
	)
	(segment
		(start 134.075932 -293.149528)
		(end 131.926584 -291.00018)
		(width 0.14732)
		(layer "In4.Cu")
		(net "P5E_CPU1_PE3_RX_DN<3>")
	)
	(segment
		(start 131.926584 -290.674806)
		(end 131.926584 -290.652708)
		(width 0.0889)
		(layer "In4.Cu")
		(net "P5E_CPU1_PE3_RX_DN<3>")
	)
	(segment
		(start 131.968494 -290.610798)
		(end 131.968494 -290.413186)
		(width 0.0889)
		(layer "In4.Cu")
		(net "P5E_CPU1_PE3_RX_DN<3>")
	)
	(arc
		(start 131.860798 -289.64509)
		(mid 131.806137 -289.553796)
		(end 131.729734 -289.479736)
		(width 0.0889)
		(layer "In4.Cu")
		(net "P5E_CPU1_PE3_RX_DN<3>")
	)
	(segment
		(start 132.895848 -288.381186)
		(end 132.895848 -288.917126)
		(width 0.13208)
		(layer "F.Cu")
		(net "P5E_CPU1_PE3_RX_DN<2>")
	)
	(segment
		(start 133.091936 -288.597848)
		(end 133.083046 -288.592768)
		(width 0.0889)
		(layer "In4.Cu")
		(net "P5E_CPU1_PE3_RX_DN<2>")
	)
	(segment
		(start 135.897874 -292.075108)
		(end 134.423912 -292.075108)
		(width 0.14732)
		(layer "In4.Cu")
		(net "P5E_CPU1_PE3_RX_DN<2>")
	)
	(segment
		(start 160.086294 -406.19934)
		(end 161.803334 -404.4823)
		(width 0.14732)
		(layer "In4.Cu")
		(net "P5E_CPU1_PE3_RX_DN<2>")
	)
	(segment
		(start 133.118606 -290.710874)
		(end 132.800598 -290.392866)
		(width 0.0889)
		(layer "In4.Cu")
		(net "P5E_CPU1_PE3_RX_DN<2>")
	)
	(segment
		(start 132.800598 -289.609022)
		(end 132.800344 -289.609784)
		(width 0.0889)
		(layer "In4.Cu")
		(net "P5E_CPU1_PE3_RX_DN<2>")
	)
	(segment
		(start 157.024324 -325.164958)
		(end 137.747502 -293.924482)
		(width 0.14732)
		(layer "In4.Cu")
		(net "P5E_CPU1_PE3_RX_DN<2>")
	)
	(segment
		(start 133.270498 -289.077908)
		(end 133.270498 -288.917126)
		(width 0.0889)
		(layer "In4.Cu")
		(net "P5E_CPU1_PE3_RX_DN<2>")
	)
	(segment
		(start 132.800598 -290.392866)
		(end 132.800598 -289.609022)
		(width 0.0889)
		(layer "In4.Cu")
		(net "P5E_CPU1_PE3_RX_DN<2>")
	)
	(segment
		(start 152.10028 -438.627012)
		(end 151.792178 -438.31891)
		(width 0.14732)
		(layer "In4.Cu")
		(net "P5E_CPU1_PE3_RX_DN<2>")
	)
	(segment
		(start 133.118606 -290.769802)
		(end 133.118606 -290.710874)
		(width 0.0889)
		(layer "In4.Cu")
		(net "P5E_CPU1_PE3_RX_DN<2>")
	)
	(segment
		(start 153.540968 -420.727886)
		(end 153.734008 -420.684452)
		(width 0.14732)
		(layer "In4.Cu")
		(net "P5E_CPU1_PE3_RX_DN<2>")
	)
	(segment
		(start 161.803334 -404.4823)
		(end 161.803334 -400.014694)
		(width 0.14732)
		(layer "In4.Cu")
		(net "P5E_CPU1_PE3_RX_DN<2>")
	)
	(segment
		(start 160.957514 -330.216764)
		(end 157.02407 -325.164704)
		(width 0.14732)
		(layer "In4.Cu")
		(net "P5E_CPU1_PE3_RX_DN<2>")
	)
	(segment
		(start 152.53843 -438.627012)
		(end 152.10028 -438.627012)
		(width 0.14732)
		(layer "In4.Cu")
		(net "P5E_CPU1_PE3_RX_DN<2>")
	)
	(segment
		(start 161.803334 -400.014694)
		(end 161.790634 -400.001994)
		(width 0.14732)
		(layer "In4.Cu")
		(net "P5E_CPU1_PE3_RX_DN<2>")
	)
	(segment
		(start 153.387552 -421.232076)
		(end 153.344118 -421.03929)
		(width 0.14732)
		(layer "In4.Cu")
		(net "P5E_CPU1_PE3_RX_DN<2>")
	)
	(segment
		(start 151.792178 -438.31891)
		(end 151.792178 -423.753534)
		(width 0.14732)
		(layer "In4.Cu")
		(net "P5E_CPU1_PE3_RX_DN<2>")
	)
	(segment
		(start 152.750012 -438.838594)
		(end 152.53843 -438.627012)
		(width 0.14732)
		(layer "In4.Cu")
		(net "P5E_CPU1_PE3_RX_DN<2>")
	)
	(segment
		(start 153.734008 -420.684452)
		(end 160.086294 -410.644848)
		(width 0.14732)
		(layer "In4.Cu")
		(net "P5E_CPU1_PE3_RX_DN<2>")
	)
	(segment
		(start 133.1341 -290.785296)
		(end 133.118606 -290.769802)
		(width 0.0889)
		(layer "In4.Cu")
		(net "P5E_CPU1_PE3_RX_DN<2>")
	)
	(segment
		(start 132.760466 -288.56813)
		(end 132.739384 -288.646108)
		(width 0.0889)
		(layer "In4.Cu")
		(net "P5E_CPU1_PE3_RX_DN<2>")
	)
	(segment
		(start 151.792178 -423.753534)
		(end 153.387552 -421.232076)
		(width 0.14732)
		(layer "In4.Cu")
		(net "P5E_CPU1_PE3_RX_DN<2>")
	)
	(segment
		(start 153.344118 -421.03929)
		(end 153.540968 -420.727886)
		(width 0.14732)
		(layer "In4.Cu")
		(net "P5E_CPU1_PE3_RX_DN<2>")
	)
	(segment
		(start 160.086294 -410.644848)
		(end 160.086294 -406.19934)
		(width 0.14732)
		(layer "In4.Cu")
		(net "P5E_CPU1_PE3_RX_DN<2>")
	)
	(segment
		(start 137.747502 -293.924482)
		(end 135.897874 -292.075108)
		(width 0.14732)
		(layer "In4.Cu")
		(net "P5E_CPU1_PE3_RX_DN<2>")
	)
	(segment
		(start 157.02407 -325.164704)
		(end 157.024324 -325.164958)
		(width 0.14732)
		(layer "In4.Cu")
		(net "P5E_CPU1_PE3_RX_DN<2>")
	)
	(segment
		(start 132.739384 -288.646108)
		(end 132.895848 -288.917126)
		(width 0.0889)
		(layer "In4.Cu")
		(net "P5E_CPU1_PE3_RX_DN<2>")
	)
	(segment
		(start 134.423912 -292.075108)
		(end 133.1341 -290.785296)
		(width 0.14732)
		(layer "In4.Cu")
		(net "P5E_CPU1_PE3_RX_DN<2>")
	)
	(segment
		(start 152.750012 -439.0898)
		(end 152.750012 -438.838594)
		(width 0.14732)
		(layer "In4.Cu")
		(net "P5E_CPU1_PE3_RX_DN<2>")
	)
	(segment
		(start 162.812476 -340.786974)
		(end 160.957514 -330.216764)
		(width 0.14732)
		(layer "In4.Cu")
		(net "P5E_CPU1_PE3_RX_DN<2>")
	)
	(segment
		(start 161.790634 -400.001994)
		(end 162.812476 -340.786974)
		(width 0.14732)
		(layer "In4.Cu")
		(net "P5E_CPU1_PE3_RX_DN<2>")
	)
	(arc
		(start 132.800344 -289.609784)
		(mid 132.8075 -289.590223)
		(end 132.81533 -289.570922)
		(width 0.0889)
		(layer "In4.Cu")
		(net "P5E_CPU1_PE3_RX_DN<2>")
	)
	(arc
		(start 133.083046 -288.592768)
		(mid 132.924558 -288.543835)
		(end 132.760466 -288.56813)
		(width 0.0889)
		(layer "In4.Cu")
		(net "P5E_CPU1_PE3_RX_DN<2>")
	)
	(arc
		(start 133.270498 -288.917126)
		(mid 133.222819 -288.734226)
		(end 133.091936 -288.597848)
		(width 0.0889)
		(layer "In4.Cu")
		(net "P5E_CPU1_PE3_RX_DN<2>")
	)
	(arc
		(start 133.086094 -289.277806)
		(mid 133.19549 -289.193709)
		(end 133.270498 -289.077908)
		(width 0.0889)
		(layer "In4.Cu")
		(net "P5E_CPU1_PE3_RX_DN<2>")
	)
	(arc
		(start 132.81533 -289.570922)
		(mid 132.925587 -289.401162)
		(end 133.086094 -289.277806)
		(width 0.0889)
		(layer "In4.Cu")
		(net "P5E_CPU1_PE3_RX_DN<2>")
	)
	(segment
		(start 133.365494 -289.195002)
		(end 133.365494 -289.807142)
		(width 0.13208)
		(layer "F.Cu")
		(net "P5E_CPU1_PE3_RX_DN<1>")
	)
	(segment
		(start 133.524498 -289.506152)
		(end 133.365494 -289.807142)
		(width 0.0889)
		(layer "In4.Cu")
		(net "P5E_CPU1_PE3_RX_DN<1>")
	)
	(segment
		(start 163.788344 -340.879684)
		(end 162.84194 -327.187052)
		(width 0.14732)
		(layer "In4.Cu")
		(net "P5E_CPU1_PE3_RX_DN<1>")
	)
	(segment
		(start 154.750008 -438.089802)
		(end 154.750008 -437.774588)
		(width 0.14732)
		(layer "In4.Cu")
		(net "P5E_CPU1_PE3_RX_DN<1>")
	)
	(segment
		(start 138.521694 -293.274496)
		(end 136.402826 -291.155628)
		(width 0.14732)
		(layer "In4.Cu")
		(net "P5E_CPU1_PE3_RX_DN<1>")
	)
	(segment
		(start 163.345114 -365.798608)
		(end 163.788344 -340.879684)
		(width 0.14732)
		(layer "In4.Cu")
		(net "P5E_CPU1_PE3_RX_DN<1>")
	)
	(segment
		(start 162.730688 -326.558656)
		(end 162.494976 -326.221852)
		(width 0.14732)
		(layer "In4.Cu")
		(net "P5E_CPU1_PE3_RX_DN<1>")
	)
	(segment
		(start 162.84194 -327.18629)
		(end 162.841178 -327.185528)
		(width 0.14732)
		(layer "In4.Cu")
		(net "P5E_CPU1_PE3_RX_DN<1>")
	)
	(segment
		(start 136.402826 -291.155628)
		(end 134.764018 -291.155628)
		(width 0.14732)
		(layer "In4.Cu")
		(net "P5E_CPU1_PE3_RX_DN<1>")
	)
	(segment
		(start 164.866574 -400.699478)
		(end 163.345368 -365.811054)
		(width 0.14732)
		(layer "In4.Cu")
		(net "P5E_CPU1_PE3_RX_DN<1>")
	)
	(segment
		(start 134.134606 -290.526216)
		(end 134.134606 -290.467288)
		(width 0.0889)
		(layer "In4.Cu")
		(net "P5E_CPU1_PE3_RX_DN<1>")
	)
	(segment
		(start 133.740398 -289.64636)
		(end 133.740144 -289.645852)
		(width 0.0889)
		(layer "In4.Cu")
		(net "P5E_CPU1_PE3_RX_DN<1>")
	)
	(segment
		(start 154.100276 -437.627014)
		(end 153.792428 -437.319166)
		(width 0.14732)
		(layer "In4.Cu")
		(net "P5E_CPU1_PE3_RX_DN<1>")
	)
	(segment
		(start 153.792174 -424.328082)
		(end 163.149534 -410.636466)
		(width 0.14732)
		(layer "In4.Cu")
		(net "P5E_CPU1_PE3_RX_DN<1>")
	)
	(segment
		(start 164.866574 -404.4823)
		(end 164.866574 -400.699478)
		(width 0.14732)
		(layer "In4.Cu")
		(net "P5E_CPU1_PE3_RX_DN<1>")
	)
	(segment
		(start 134.134606 -290.467288)
		(end 133.740398 -290.07308)
		(width 0.0889)
		(layer "In4.Cu")
		(net "P5E_CPU1_PE3_RX_DN<1>")
	)
	(segment
		(start 153.792428 -424.328336)
		(end 153.792174 -424.328082)
		(width 0.14732)
		(layer "In4.Cu")
		(net "P5E_CPU1_PE3_RX_DN<1>")
	)
	(segment
		(start 134.1501 -290.54171)
		(end 134.134606 -290.526216)
		(width 0.0889)
		(layer "In4.Cu")
		(net "P5E_CPU1_PE3_RX_DN<1>")
	)
	(segment
		(start 158.787338 -324.533006)
		(end 156.218636 -321.964558)
		(width 0.14732)
		(layer "In4.Cu")
		(net "P5E_CPU1_PE3_RX_DN<1>")
	)
	(segment
		(start 160.51911 -324.838568)
		(end 158.787338 -324.533006)
		(width 0.14732)
		(layer "In4.Cu")
		(net "P5E_CPU1_PE3_RX_DN<1>")
	)
	(segment
		(start 133.60908 -289.480244)
		(end 133.524498 -289.506152)
		(width 0.0889)
		(layer "In4.Cu")
		(net "P5E_CPU1_PE3_RX_DN<1>")
	)
	(segment
		(start 162.494976 -326.221852)
		(end 160.51911 -324.838568)
		(width 0.14732)
		(layer "In4.Cu")
		(net "P5E_CPU1_PE3_RX_DN<1>")
	)
	(segment
		(start 156.218636 -321.964558)
		(end 138.521694 -293.274496)
		(width 0.14732)
		(layer "In4.Cu")
		(net "P5E_CPU1_PE3_RX_DN<1>")
	)
	(segment
		(start 153.792428 -437.319166)
		(end 153.792428 -424.328336)
		(width 0.14732)
		(layer "In4.Cu")
		(net "P5E_CPU1_PE3_RX_DN<1>")
	)
	(segment
		(start 162.841178 -327.185528)
		(end 162.730688 -326.558656)
		(width 0.14732)
		(layer "In4.Cu")
		(net "P5E_CPU1_PE3_RX_DN<1>")
	)
	(segment
		(start 163.149534 -406.19934)
		(end 164.866574 -404.4823)
		(width 0.14732)
		(layer "In4.Cu")
		(net "P5E_CPU1_PE3_RX_DN<1>")
	)
	(segment
		(start 134.764018 -291.155628)
		(end 134.1501 -290.54171)
		(width 0.14732)
		(layer "In4.Cu")
		(net "P5E_CPU1_PE3_RX_DN<1>")
	)
	(segment
		(start 163.149534 -410.636466)
		(end 163.149534 -406.19934)
		(width 0.14732)
		(layer "In4.Cu")
		(net "P5E_CPU1_PE3_RX_DN<1>")
	)
	(segment
		(start 154.602434 -437.627014)
		(end 154.100276 -437.627014)
		(width 0.14732)
		(layer "In4.Cu")
		(net "P5E_CPU1_PE3_RX_DN<1>")
	)
	(segment
		(start 162.84194 -327.187052)
		(end 162.84194 -327.18629)
		(width 0.14732)
		(layer "In4.Cu")
		(net "P5E_CPU1_PE3_RX_DN<1>")
	)
	(segment
		(start 133.740398 -290.07308)
		(end 133.740398 -289.64636)
		(width 0.0889)
		(layer "In4.Cu")
		(net "P5E_CPU1_PE3_RX_DN<1>")
	)
	(segment
		(start 154.750008 -437.774588)
		(end 154.602434 -437.627014)
		(width 0.14732)
		(layer "In4.Cu")
		(net "P5E_CPU1_PE3_RX_DN<1>")
	)
	(segment
		(start 163.345368 -365.811054)
		(end 163.345114 -365.798608)
		(width 0.14732)
		(layer "In4.Cu")
		(net "P5E_CPU1_PE3_RX_DN<1>")
	)
	(arc
		(start 133.740144 -289.645852)
		(mid 133.685493 -289.554442)
		(end 133.60908 -289.480244)
		(width 0.0889)
		(layer "In4.Cu")
		(net "P5E_CPU1_PE3_RX_DN<1>")
	)
	(segment
		(start 120.678448 -288.381186)
		(end 120.678448 -288.917126)
		(width 0.13208)
		(layer "F.Cu")
		(net "P5E_CPU1_PE3_RX_DN<15>")
	)
	(segment
		(start 149.45868 -338.05876)
		(end 149.243542 -364.018322)
		(width 0.14732)
		(layer "In4.Cu")
		(net "P5E_CPU1_PE3_RX_DN<15>")
	)
	(segment
		(start 149.243542 -364.018322)
		(end 147.318984 -370.036852)
		(width 0.14732)
		(layer "In4.Cu")
		(net "P5E_CPU1_PE3_RX_DN<15>")
	)
	(segment
		(start 120.77319 -290.447984)
		(end 120.815354 -290.490148)
		(width 0.0889)
		(layer "In4.Cu")
		(net "P5E_CPU1_PE3_RX_DN<15>")
	)
	(segment
		(start 122.34672 -417.432744)
		(end 122.227848 -417.590732)
		(width 0.14732)
		(layer "In4.Cu")
		(net "P5E_CPU1_PE3_RX_DN<15>")
	)
	(segment
		(start 122.255534 -404.596092)
		(end 120.538494 -406.313132)
		(width 0.14732)
		(layer "In4.Cu")
		(net "P5E_CPU1_PE3_RX_DN<15>")
	)
	(segment
		(start 120.815354 -290.850066)
		(end 119.0244 -292.64102)
		(width 0.14732)
		(layer "In4.Cu")
		(net "P5E_CPU1_PE3_RX_DN<15>")
	)
	(segment
		(start 119.0244 -292.64102)
		(end 119.0244 -297.28668)
		(width 0.14732)
		(layer "In4.Cu")
		(net "P5E_CPU1_PE3_RX_DN<15>")
	)
	(segment
		(start 122.752104 -399.295112)
		(end 122.255534 -400.42084)
		(width 0.14732)
		(layer "In4.Cu")
		(net "P5E_CPU1_PE3_RX_DN<15>")
	)
	(segment
		(start 122.370088 -418.596826)
		(end 124.986542 -437.12511)
		(width 0.14732)
		(layer "In4.Cu")
		(net "P5E_CPU1_PE3_RX_DN<15>")
	)
	(segment
		(start 125.750066 -437.20512)
		(end 125.750066 -436.889906)
		(width 0.14732)
		(layer "In4.Cu")
		(net "P5E_CPU1_PE3_RX_DN<15>")
	)
	(segment
		(start 121.543318 -412.74365)
		(end 122.13717 -416.949128)
		(width 0.14732)
		(layer "In4.Cu")
		(net "P5E_CPU1_PE3_RX_DN<15>")
	)
	(segment
		(start 125.602492 -437.352694)
		(end 125.750066 -437.20512)
		(width 0.14732)
		(layer "In4.Cu")
		(net "P5E_CPU1_PE3_RX_DN<15>")
	)
	(segment
		(start 120.773444 -289.60953)
		(end 120.77319 -289.609276)
		(width 0.0889)
		(layer "In4.Cu")
		(net "P5E_CPU1_PE3_RX_DN<15>")
	)
	(segment
		(start 122.234198 -301.84598)
		(end 149.09927 -334.577436)
		(width 0.14732)
		(layer "In4.Cu")
		(net "P5E_CPU1_PE3_RX_DN<15>")
	)
	(segment
		(start 147.318984 -370.036852)
		(end 122.752104 -399.295112)
		(width 0.14732)
		(layer "In4.Cu")
		(net "P5E_CPU1_PE3_RX_DN<15>")
	)
	(segment
		(start 149.09927 -334.577436)
		(end 149.45868 -336.614262)
		(width 0.14732)
		(layer "In4.Cu")
		(net "P5E_CPU1_PE3_RX_DN<15>")
	)
	(segment
		(start 119.094758 -297.685206)
		(end 122.234198 -301.84598)
		(width 0.14732)
		(layer "In4.Cu")
		(net "P5E_CPU1_PE3_RX_DN<15>")
	)
	(segment
		(start 119.0244 -297.28668)
		(end 119.094758 -297.685206)
		(width 0.14732)
		(layer "In4.Cu")
		(net "P5E_CPU1_PE3_RX_DN<15>")
	)
	(segment
		(start 120.519444 -289.218116)
		(end 120.549416 -289.315144)
		(width 0.0889)
		(layer "In4.Cu")
		(net "P5E_CPU1_PE3_RX_DN<15>")
	)
	(segment
		(start 122.295158 -417.067746)
		(end 122.34672 -417.432744)
		(width 0.14732)
		(layer "In4.Cu")
		(net "P5E_CPU1_PE3_RX_DN<15>")
	)
	(segment
		(start 122.255534 -400.42084)
		(end 122.255534 -404.596092)
		(width 0.14732)
		(layer "In4.Cu")
		(net "P5E_CPU1_PE3_RX_DN<15>")
	)
	(segment
		(start 122.437398 -418.074094)
		(end 122.48896 -418.439092)
		(width 0.14732)
		(layer "In4.Cu")
		(net "P5E_CPU1_PE3_RX_DN<15>")
	)
	(segment
		(start 120.538494 -406.313132)
		(end 120.538494 -410.367226)
		(width 0.14732)
		(layer "In4.Cu")
		(net "P5E_CPU1_PE3_RX_DN<15>")
	)
	(segment
		(start 122.227848 -417.590732)
		(end 122.279156 -417.955222)
		(width 0.14732)
		(layer "In4.Cu")
		(net "P5E_CPU1_PE3_RX_DN<15>")
	)
	(segment
		(start 120.815354 -290.512246)
		(end 120.815354 -290.850066)
		(width 0.14732)
		(layer "In4.Cu")
		(net "P5E_CPU1_PE3_RX_DN<15>")
	)
	(segment
		(start 125.214126 -437.352694)
		(end 125.602492 -437.352694)
		(width 0.14732)
		(layer "In4.Cu")
		(net "P5E_CPU1_PE3_RX_DN<15>")
	)
	(segment
		(start 120.815354 -290.490148)
		(end 120.815354 -290.512246)
		(width 0.0889)
		(layer "In4.Cu")
		(net "P5E_CPU1_PE3_RX_DN<15>")
	)
	(segment
		(start 120.77319 -289.609276)
		(end 120.77319 -290.447984)
		(width 0.0889)
		(layer "In4.Cu")
		(net "P5E_CPU1_PE3_RX_DN<15>")
	)
	(segment
		(start 120.678448 -288.917126)
		(end 120.519444 -289.218116)
		(width 0.0889)
		(layer "In4.Cu")
		(net "P5E_CPU1_PE3_RX_DN<15>")
	)
	(segment
		(start 122.48896 -418.439092)
		(end 122.370088 -418.596826)
		(width 0.14732)
		(layer "In4.Cu")
		(net "P5E_CPU1_PE3_RX_DN<15>")
	)
	(segment
		(start 124.986542 -437.12511)
		(end 125.214126 -437.352694)
		(width 0.14732)
		(layer "In4.Cu")
		(net "P5E_CPU1_PE3_RX_DN<15>")
	)
	(segment
		(start 122.13717 -416.949128)
		(end 122.295158 -417.067746)
		(width 0.14732)
		(layer "In4.Cu")
		(net "P5E_CPU1_PE3_RX_DN<15>")
	)
	(segment
		(start 122.279156 -417.955222)
		(end 122.437398 -418.074094)
		(width 0.14732)
		(layer "In4.Cu")
		(net "P5E_CPU1_PE3_RX_DN<15>")
	)
	(segment
		(start 120.538494 -410.367226)
		(end 121.543318 -412.74365)
		(width 0.14732)
		(layer "In4.Cu")
		(net "P5E_CPU1_PE3_RX_DN<15>")
	)
	(segment
		(start 149.45868 -336.614262)
		(end 149.45868 -338.05876)
		(width 0.14732)
		(layer "In4.Cu")
		(net "P5E_CPU1_PE3_RX_DN<15>")
	)
	(arc
		(start 120.549416 -289.315144)
		(mid 120.684731 -289.444603)
		(end 120.773444 -289.60953)
		(width 0.0889)
		(layer "In4.Cu")
		(net "P5E_CPU1_PE3_RX_DN<15>")
	)
	(segment
		(start 121.148094 -287.567116)
		(end 121.148094 -288.102802)
		(width 0.13208)
		(layer "F.Cu")
		(net "P5E_CPU1_PE3_RX_DN<14>")
	)
	(segment
		(start 121.148094 -288.102802)
		(end 121.148348 -288.103056)
		(width 0.13208)
		(layer "F.Cu")
		(net "P5E_CPU1_PE3_RX_DN<14>")
	)
	(segment
		(start 149.975316 -334.146652)
		(end 150.49754 -337.109308)
		(width 0.14732)
		(layer "In4.Cu")
		(net "P5E_CPU1_PE3_RX_DN<14>")
	)
	(segment
		(start 127.214122 -438.352692)
		(end 127.602488 -438.352692)
		(width 0.14732)
		(layer "In4.Cu")
		(net "P5E_CPU1_PE3_RX_DN<14>")
	)
	(segment
		(start 127.602488 -438.352692)
		(end 127.750062 -438.205118)
		(width 0.14732)
		(layer "In4.Cu")
		(net "P5E_CPU1_PE3_RX_DN<14>")
	)
	(segment
		(start 121.755408 -291.4396)
		(end 121.226072 -291.968936)
		(width 0.14732)
		(layer "In4.Cu")
		(net "P5E_CPU1_PE3_RX_DN<14>")
	)
	(segment
		(start 150.49754 -337.109308)
		(end 150.49754 -337.656932)
		(width 0.14732)
		(layer "In4.Cu")
		(net "P5E_CPU1_PE3_RX_DN<14>")
	)
	(segment
		(start 121.755408 -290.512246)
		(end 121.755408 -291.4396)
		(width 0.14732)
		(layer "In4.Cu")
		(net "P5E_CPU1_PE3_RX_DN<14>")
	)
	(segment
		(start 123.601734 -410.365702)
		(end 127.066802 -423.441622)
		(width 0.14732)
		(layer "In4.Cu")
		(net "P5E_CPU1_PE3_RX_DN<14>")
	)
	(segment
		(start 123.601734 -406.313132)
		(end 123.601734 -410.365702)
		(width 0.14732)
		(layer "In4.Cu")
		(net "P5E_CPU1_PE3_RX_DN<14>")
	)
	(segment
		(start 150.49754 -337.656932)
		(end 150.323042 -363.95406)
		(width 0.14732)
		(layer "In4.Cu")
		(net "P5E_CPU1_PE3_RX_DN<14>")
	)
	(segment
		(start 121.713244 -289.64636)
		(end 121.713244 -290.447984)
		(width 0.0889)
		(layer "In4.Cu")
		(net "P5E_CPU1_PE3_RX_DN<14>")
	)
	(segment
		(start 125.318774 -404.596092)
		(end 123.601734 -406.313132)
		(width 0.14732)
		(layer "In4.Cu")
		(net "P5E_CPU1_PE3_RX_DN<14>")
	)
	(segment
		(start 125.318774 -400.240754)
		(end 125.318774 -404.596092)
		(width 0.14732)
		(layer "In4.Cu")
		(net "P5E_CPU1_PE3_RX_DN<14>")
	)
	(segment
		(start 148.440902 -370.391944)
		(end 125.619256 -399.459958)
		(width 0.14732)
		(layer "In4.Cu")
		(net "P5E_CPU1_PE3_RX_DN<14>")
	)
	(segment
		(start 127.066802 -423.441622)
		(end 127.066802 -438.205372)
		(width 0.14732)
		(layer "In4.Cu")
		(net "P5E_CPU1_PE3_RX_DN<14>")
	)
	(segment
		(start 121.505726 -298.790614)
		(end 124.64796 -303.277778)
		(width 0.14732)
		(layer "In4.Cu")
		(net "P5E_CPU1_PE3_RX_DN<14>")
	)
	(segment
		(start 121.148348 -288.103056)
		(end 121.304812 -288.374074)
		(width 0.0889)
		(layer "In4.Cu")
		(net "P5E_CPU1_PE3_RX_DN<14>")
	)
	(segment
		(start 121.755408 -290.490148)
		(end 121.755408 -290.512246)
		(width 0.0889)
		(layer "In4.Cu")
		(net "P5E_CPU1_PE3_RX_DN<14>")
	)
	(segment
		(start 122.183398 -288.898584)
		(end 122.183398 -289.114484)
		(width 0.0889)
		(layer "In4.Cu")
		(net "P5E_CPU1_PE3_RX_DN<14>")
	)
	(segment
		(start 121.304812 -288.374074)
		(end 121.393966 -288.39795)
		(width 0.0889)
		(layer "In4.Cu")
		(net "P5E_CPU1_PE3_RX_DN<14>")
	)
	(segment
		(start 121.713244 -290.447984)
		(end 121.755408 -290.490148)
		(width 0.0889)
		(layer "In4.Cu")
		(net "P5E_CPU1_PE3_RX_DN<14>")
	)
	(segment
		(start 127.750062 -438.205118)
		(end 127.750062 -437.889904)
		(width 0.14732)
		(layer "In4.Cu")
		(net "P5E_CPU1_PE3_RX_DN<14>")
	)
	(segment
		(start 148.442934 -370.384578)
		(end 148.440902 -370.391944)
		(width 0.14732)
		(layer "In4.Cu")
		(net "P5E_CPU1_PE3_RX_DN<14>")
	)
	(segment
		(start 124.64796 -303.277778)
		(end 149.975316 -334.146652)
		(width 0.14732)
		(layer "In4.Cu")
		(net "P5E_CPU1_PE3_RX_DN<14>")
	)
	(segment
		(start 127.066802 -438.205372)
		(end 127.214122 -438.352692)
		(width 0.14732)
		(layer "In4.Cu")
		(net "P5E_CPU1_PE3_RX_DN<14>")
	)
	(segment
		(start 150.323042 -363.95406)
		(end 148.442934 -370.384578)
		(width 0.14732)
		(layer "In4.Cu")
		(net "P5E_CPU1_PE3_RX_DN<14>")
	)
	(segment
		(start 125.619256 -399.459958)
		(end 125.318774 -400.240754)
		(width 0.14732)
		(layer "In4.Cu")
		(net "P5E_CPU1_PE3_RX_DN<14>")
	)
	(segment
		(start 121.226072 -291.968936)
		(end 121.226072 -297.201082)
		(width 0.14732)
		(layer "In4.Cu")
		(net "P5E_CPU1_PE3_RX_DN<14>")
	)
	(segment
		(start 121.226072 -297.201082)
		(end 121.505726 -298.790614)
		(width 0.14732)
		(layer "In4.Cu")
		(net "P5E_CPU1_PE3_RX_DN<14>")
	)
	(arc
		(start 121.413524 -288.389822)
		(mid 121.661504 -288.35321)
		(end 121.90095 -288.427414)
		(width 0.0889)
		(layer "In4.Cu")
		(net "P5E_CPU1_PE3_RX_DN<14>")
	)
	(arc
		(start 121.897648 -289.446462)
		(mid 121.788252 -289.530559)
		(end 121.713244 -289.64636)
		(width 0.0889)
		(layer "In4.Cu")
		(net "P5E_CPU1_PE3_RX_DN<14>")
	)
	(arc
		(start 122.183398 -289.114484)
		(mid 122.072002 -289.307577)
		(end 121.897648 -289.446462)
		(width 0.0889)
		(layer "In4.Cu")
		(net "P5E_CPU1_PE3_RX_DN<14>")
	)
	(arc
		(start 121.90095 -288.427414)
		(mid 122.103236 -288.626395)
		(end 122.183398 -288.898584)
		(width 0.0889)
		(layer "In4.Cu")
		(net "P5E_CPU1_PE3_RX_DN<14>")
	)
	(arc
		(start 121.393966 -288.39795)
		(mid 121.403707 -288.393795)
		(end 121.413524 -288.389822)
		(width 0.0889)
		(layer "In4.Cu")
		(net "P5E_CPU1_PE3_RX_DN<14>")
	)
	(segment
		(start 122.558048 -288.381186)
		(end 122.558048 -288.917126)
		(width 0.13208)
		(layer "F.Cu")
		(net "P5E_CPU1_PE3_RX_DN<13>")
	)
	(segment
		(start 122.653044 -290.447984)
		(end 122.695208 -290.490148)
		(width 0.0889)
		(layer "In4.Cu")
		(net "P5E_CPU1_PE3_RX_DN<13>")
	)
	(segment
		(start 122.155712 -297.119548)
		(end 122.33402 -298.130468)
		(width 0.14732)
		(layer "In4.Cu")
		(net "P5E_CPU1_PE3_RX_DN<13>")
	)
	(segment
		(start 126.892304 -412.219394)
		(end 127.055372 -412.3309)
		(width 0.14732)
		(layer "In4.Cu")
		(net "P5E_CPU1_PE3_RX_DN<13>")
	)
	(segment
		(start 127.241046 -413.408622)
		(end 127.321056 -413.83839)
		(width 0.14732)
		(layer "In4.Cu")
		(net "P5E_CPU1_PE3_RX_DN<13>")
	)
	(segment
		(start 126.423928 -303.971706)
		(end 150.85187 -333.70647)
		(width 0.14732)
		(layer "In4.Cu")
		(net "P5E_CPU1_PE3_RX_DN<13>")
	)
	(segment
		(start 129.750058 -437.20512)
		(end 129.750058 -436.889906)
		(width 0.14732)
		(layer "In4.Cu")
		(net "P5E_CPU1_PE3_RX_DN<13>")
	)
	(segment
		(start 122.155712 -292.597332)
		(end 122.155712 -297.119548)
		(width 0.14732)
		(layer "In4.Cu")
		(net "P5E_CPU1_PE3_RX_DN<13>")
	)
	(segment
		(start 150.85187 -333.70647)
		(end 151.43734 -337.026504)
		(width 0.14732)
		(layer "In4.Cu")
		(net "P5E_CPU1_PE3_RX_DN<13>")
	)
	(segment
		(start 128.382014 -400.46021)
		(end 128.382014 -404.596092)
		(width 0.14732)
		(layer "In4.Cu")
		(net "P5E_CPU1_PE3_RX_DN<13>")
	)
	(segment
		(start 149.39518 -370.775992)
		(end 128.503934 -400.079972)
		(width 0.14732)
		(layer "In4.Cu")
		(net "P5E_CPU1_PE3_RX_DN<13>")
	)
	(segment
		(start 126.664974 -406.313132)
		(end 126.664974 -411.000194)
		(width 0.14732)
		(layer "In4.Cu")
		(net "P5E_CPU1_PE3_RX_DN<13>")
	)
	(segment
		(start 127.221742 -413.983678)
		(end 129.066798 -423.871898)
		(width 0.14732)
		(layer "In4.Cu")
		(net "P5E_CPU1_PE3_RX_DN<13>")
	)
	(segment
		(start 122.33402 -298.130468)
		(end 126.423928 -303.971706)
		(width 0.14732)
		(layer "In4.Cu")
		(net "P5E_CPU1_PE3_RX_DN<13>")
	)
	(segment
		(start 127.321056 -413.83839)
		(end 127.221742 -413.983678)
		(width 0.14732)
		(layer "In4.Cu")
		(net "P5E_CPU1_PE3_RX_DN<13>")
	)
	(segment
		(start 129.602484 -437.352694)
		(end 129.750058 -437.20512)
		(width 0.14732)
		(layer "In4.Cu")
		(net "P5E_CPU1_PE3_RX_DN<13>")
	)
	(segment
		(start 127.011176 -412.856172)
		(end 127.095504 -413.309054)
		(width 0.14732)
		(layer "In4.Cu")
		(net "P5E_CPU1_PE3_RX_DN<13>")
	)
	(segment
		(start 129.214118 -437.352694)
		(end 129.602484 -437.352694)
		(width 0.14732)
		(layer "In4.Cu")
		(net "P5E_CPU1_PE3_RX_DN<13>")
	)
	(segment
		(start 127.122936 -412.693104)
		(end 127.011176 -412.856172)
		(width 0.14732)
		(layer "In4.Cu")
		(net "P5E_CPU1_PE3_RX_DN<13>")
	)
	(segment
		(start 129.066798 -437.205374)
		(end 129.214118 -437.352694)
		(width 0.14732)
		(layer "In4.Cu")
		(net "P5E_CPU1_PE3_RX_DN<13>")
	)
	(segment
		(start 151.43734 -337.026504)
		(end 151.43734 -337.267042)
		(width 0.14732)
		(layer "In4.Cu")
		(net "P5E_CPU1_PE3_RX_DN<13>")
	)
	(segment
		(start 128.382014 -404.596092)
		(end 126.664974 -406.313132)
		(width 0.14732)
		(layer "In4.Cu")
		(net "P5E_CPU1_PE3_RX_DN<13>")
	)
	(segment
		(start 127.095504 -413.309054)
		(end 127.241046 -413.408622)
		(width 0.14732)
		(layer "In4.Cu")
		(net "P5E_CPU1_PE3_RX_DN<13>")
	)
	(segment
		(start 122.558048 -288.917126)
		(end 122.399044 -289.218116)
		(width 0.0889)
		(layer "In4.Cu")
		(net "P5E_CPU1_PE3_RX_DN<13>")
	)
	(segment
		(start 122.695208 -290.512246)
		(end 122.695208 -292.057836)
		(width 0.14732)
		(layer "In4.Cu")
		(net "P5E_CPU1_PE3_RX_DN<13>")
	)
	(segment
		(start 122.695208 -290.490148)
		(end 122.695208 -290.512246)
		(width 0.0889)
		(layer "In4.Cu")
		(net "P5E_CPU1_PE3_RX_DN<13>")
	)
	(segment
		(start 129.066798 -423.871898)
		(end 129.066798 -437.205374)
		(width 0.14732)
		(layer "In4.Cu")
		(net "P5E_CPU1_PE3_RX_DN<13>")
	)
	(segment
		(start 128.503934 -400.079972)
		(end 128.382014 -400.46021)
		(width 0.14732)
		(layer "In4.Cu")
		(net "P5E_CPU1_PE3_RX_DN<13>")
	)
	(segment
		(start 151.328374 -363.881924)
		(end 149.39518 -370.775992)
		(width 0.14732)
		(layer "In4.Cu")
		(net "P5E_CPU1_PE3_RX_DN<13>")
	)
	(segment
		(start 122.399044 -289.218116)
		(end 122.429016 -289.315144)
		(width 0.0889)
		(layer "In4.Cu")
		(net "P5E_CPU1_PE3_RX_DN<13>")
	)
	(segment
		(start 127.055372 -412.3309)
		(end 127.122936 -412.693104)
		(width 0.14732)
		(layer "In4.Cu")
		(net "P5E_CPU1_PE3_RX_DN<13>")
	)
	(segment
		(start 151.43734 -337.267042)
		(end 151.328374 -363.881924)
		(width 0.14732)
		(layer "In4.Cu")
		(net "P5E_CPU1_PE3_RX_DN<13>")
	)
	(segment
		(start 126.664974 -411.000194)
		(end 126.892304 -412.219394)
		(width 0.14732)
		(layer "In4.Cu")
		(net "P5E_CPU1_PE3_RX_DN<13>")
	)
	(segment
		(start 122.653044 -289.60953)
		(end 122.653044 -290.447984)
		(width 0.0889)
		(layer "In4.Cu")
		(net "P5E_CPU1_PE3_RX_DN<13>")
	)
	(segment
		(start 122.695208 -292.057836)
		(end 122.155712 -292.597332)
		(width 0.14732)
		(layer "In4.Cu")
		(net "P5E_CPU1_PE3_RX_DN<13>")
	)
	(arc
		(start 122.429016 -289.315144)
		(mid 122.564331 -289.444603)
		(end 122.653044 -289.60953)
		(width 0.0889)
		(layer "In4.Cu")
		(net "P5E_CPU1_PE3_RX_DN<13>")
	)
	(segment
		(start 123.027694 -288.102802)
		(end 123.027948 -288.103056)
		(width 0.13208)
		(layer "F.Cu")
		(net "P5E_CPU1_PE3_RX_DN<12>")
	)
	(segment
		(start 123.027694 -287.567116)
		(end 123.027694 -288.102802)
		(width 0.13208)
		(layer "F.Cu")
		(net "P5E_CPU1_PE3_RX_DN<12>")
	)
	(segment
		(start 127.505206 -303.822862)
		(end 151.72817 -333.30769)
		(width 0.14732)
		(layer "In4.Cu")
		(net "P5E_CPU1_PE3_RX_DN<12>")
	)
	(segment
		(start 131.445254 -404.596092)
		(end 129.728214 -406.313132)
		(width 0.14732)
		(layer "In4.Cu")
		(net "P5E_CPU1_PE3_RX_DN<12>")
	)
	(segment
		(start 152.28951 -364.069376)
		(end 150.474426 -370.84)
		(width 0.14732)
		(layer "In4.Cu")
		(net "P5E_CPU1_PE3_RX_DN<12>")
	)
	(segment
		(start 131.750054 -438.205118)
		(end 131.750054 -437.889904)
		(width 0.14732)
		(layer "In4.Cu")
		(net "P5E_CPU1_PE3_RX_DN<12>")
	)
	(segment
		(start 123.635008 -290.554664)
		(end 123.638818 -295.410128)
		(width 0.14732)
		(layer "In4.Cu")
		(net "P5E_CPU1_PE3_RX_DN<12>")
	)
	(segment
		(start 129.728214 -411.103318)
		(end 131.066794 -423.486326)
		(width 0.14732)
		(layer "In4.Cu")
		(net "P5E_CPU1_PE3_RX_DN<12>")
	)
	(segment
		(start 123.803918 -289.431476)
		(end 123.592844 -289.64255)
		(width 0.0889)
		(layer "In4.Cu")
		(net "P5E_CPU1_PE3_RX_DN<12>")
	)
	(segment
		(start 152.44318 -337.362546)
		(end 152.28951 -363.191806)
		(width 0.14732)
		(layer "In4.Cu")
		(net "P5E_CPU1_PE3_RX_DN<12>")
	)
	(segment
		(start 131.214114 -438.352692)
		(end 131.60248 -438.352692)
		(width 0.14732)
		(layer "In4.Cu")
		(net "P5E_CPU1_PE3_RX_DN<12>")
	)
	(segment
		(start 131.066794 -438.205372)
		(end 131.214114 -438.352692)
		(width 0.14732)
		(layer "In4.Cu")
		(net "P5E_CPU1_PE3_RX_DN<12>")
	)
	(segment
		(start 123.184412 -288.374074)
		(end 123.273566 -288.39795)
		(width 0.0889)
		(layer "In4.Cu")
		(net "P5E_CPU1_PE3_RX_DN<12>")
	)
	(segment
		(start 150.474426 -370.84)
		(end 131.547362 -399.967704)
		(width 0.14732)
		(layer "In4.Cu")
		(net "P5E_CPU1_PE3_RX_DN<12>")
	)
	(segment
		(start 123.635008 -290.512246)
		(end 123.635008 -290.554664)
		(width 0.14732)
		(layer "In4.Cu")
		(net "P5E_CPU1_PE3_RX_DN<12>")
	)
	(segment
		(start 124.062998 -288.898584)
		(end 124.062998 -289.114484)
		(width 0.0889)
		(layer "In4.Cu")
		(net "P5E_CPU1_PE3_RX_DN<12>")
	)
	(segment
		(start 123.592844 -289.64255)
		(end 123.592844 -290.447984)
		(width 0.0889)
		(layer "In4.Cu")
		(net "P5E_CPU1_PE3_RX_DN<12>")
	)
	(segment
		(start 151.72817 -333.30769)
		(end 152.44318 -337.362546)
		(width 0.14732)
		(layer "In4.Cu")
		(net "P5E_CPU1_PE3_RX_DN<12>")
	)
	(segment
		(start 123.027948 -288.103056)
		(end 123.184412 -288.374074)
		(width 0.0889)
		(layer "In4.Cu")
		(net "P5E_CPU1_PE3_RX_DN<12>")
	)
	(segment
		(start 131.445254 -400.72691)
		(end 131.445254 -404.596092)
		(width 0.14732)
		(layer "In4.Cu")
		(net "P5E_CPU1_PE3_RX_DN<12>")
	)
	(segment
		(start 131.60248 -438.352692)
		(end 131.750054 -438.205118)
		(width 0.14732)
		(layer "In4.Cu")
		(net "P5E_CPU1_PE3_RX_DN<12>")
	)
	(segment
		(start 123.635008 -290.490148)
		(end 123.635008 -290.512246)
		(width 0.0889)
		(layer "In4.Cu")
		(net "P5E_CPU1_PE3_RX_DN<12>")
	)
	(segment
		(start 131.547362 -399.967704)
		(end 131.445254 -400.72691)
		(width 0.14732)
		(layer "In4.Cu")
		(net "P5E_CPU1_PE3_RX_DN<12>")
	)
	(segment
		(start 124.319284 -299.273976)
		(end 127.505206 -303.822862)
		(width 0.14732)
		(layer "In4.Cu")
		(net "P5E_CPU1_PE3_RX_DN<12>")
	)
	(segment
		(start 129.728214 -406.313132)
		(end 129.728214 -411.103318)
		(width 0.14732)
		(layer "In4.Cu")
		(net "P5E_CPU1_PE3_RX_DN<12>")
	)
	(segment
		(start 152.28951 -363.191806)
		(end 152.28951 -364.069376)
		(width 0.14732)
		(layer "In4.Cu")
		(net "P5E_CPU1_PE3_RX_DN<12>")
	)
	(segment
		(start 123.638818 -295.410128)
		(end 124.319284 -299.273976)
		(width 0.14732)
		(layer "In4.Cu")
		(net "P5E_CPU1_PE3_RX_DN<12>")
	)
	(segment
		(start 123.592844 -290.447984)
		(end 123.635008 -290.490148)
		(width 0.0889)
		(layer "In4.Cu")
		(net "P5E_CPU1_PE3_RX_DN<12>")
	)
	(segment
		(start 131.066794 -423.486326)
		(end 131.066794 -438.205372)
		(width 0.14732)
		(layer "In4.Cu")
		(net "P5E_CPU1_PE3_RX_DN<12>")
	)
	(arc
		(start 123.273566 -288.39795)
		(mid 123.283307 -288.393795)
		(end 123.293124 -288.389822)
		(width 0.0889)
		(layer "In4.Cu")
		(net "P5E_CPU1_PE3_RX_DN<12>")
	)
	(arc
		(start 123.78055 -288.427414)
		(mid 123.982836 -288.626395)
		(end 124.062998 -288.898584)
		(width 0.0889)
		(layer "In4.Cu")
		(net "P5E_CPU1_PE3_RX_DN<12>")
	)
	(arc
		(start 124.062998 -289.114484)
		(mid 123.961432 -289.295854)
		(end 123.803918 -289.431476)
		(width 0.0889)
		(layer "In4.Cu")
		(net "P5E_CPU1_PE3_RX_DN<12>")
	)
	(arc
		(start 123.293124 -288.389822)
		(mid 123.541104 -288.35321)
		(end 123.78055 -288.427414)
		(width 0.0889)
		(layer "In4.Cu")
		(net "P5E_CPU1_PE3_RX_DN<12>")
	)
	(segment
		(start 123.967494 -289.195002)
		(end 123.967494 -289.807142)
		(width 0.13208)
		(layer "F.Cu")
		(net "P5E_CPU1_PE3_RX_DN<11>")
	)
	(segment
		(start 124.300234 -295.346882)
		(end 124.300234 -290.512246)
		(width 0.14732)
		(layer "In4.Cu")
		(net "P5E_CPU1_PE3_RX_DN<11>")
	)
	(segment
		(start 124.342144 -290.448238)
		(end 124.342144 -289.645852)
		(width 0.0889)
		(layer "In4.Cu")
		(net "P5E_CPU1_PE3_RX_DN<11>")
	)
	(segment
		(start 134.656576 -399.100294)
		(end 151.083518 -371.130068)
		(width 0.14732)
		(layer "In4.Cu")
		(net "P5E_CPU1_PE3_RX_DN<11>")
	)
	(segment
		(start 124.952506 -299.033184)
		(end 124.304298 -295.350946)
		(width 0.14732)
		(layer "In4.Cu")
		(net "P5E_CPU1_PE3_RX_DN<11>")
	)
	(segment
		(start 132.517134 -406.19934)
		(end 134.234174 -404.4823)
		(width 0.14732)
		(layer "In4.Cu")
		(net "P5E_CPU1_PE3_RX_DN<11>")
	)
	(segment
		(start 127.475996 -302.636174)
		(end 124.952506 -299.033184)
		(width 0.14732)
		(layer "In4.Cu")
		(net "P5E_CPU1_PE3_RX_DN<11>")
	)
	(segment
		(start 132.795264 -423.849546)
		(end 132.452618 -411.614366)
		(width 0.14732)
		(layer "In4.Cu")
		(net "P5E_CPU1_PE3_RX_DN<11>")
	)
	(segment
		(start 132.795264 -437.32196)
		(end 132.795264 -423.849546)
		(width 0.14732)
		(layer "In4.Cu")
		(net "P5E_CPU1_PE3_RX_DN<11>")
	)
	(segment
		(start 153.15438 -363.87913)
		(end 153.25979 -338.170266)
		(width 0.14732)
		(layer "In4.Cu")
		(net "P5E_CPU1_PE3_RX_DN<11>")
	)
	(segment
		(start 124.21108 -289.480244)
		(end 124.126498 -289.506152)
		(width 0.0889)
		(layer "In4.Cu")
		(net "P5E_CPU1_PE3_RX_DN<11>")
	)
	(segment
		(start 133.75005 -437.774588)
		(end 133.602476 -437.627014)
		(width 0.14732)
		(layer "In4.Cu")
		(net "P5E_CPU1_PE3_RX_DN<11>")
	)
	(segment
		(start 124.300234 -290.512246)
		(end 124.300234 -290.490148)
		(width 0.0889)
		(layer "In4.Cu")
		(net "P5E_CPU1_PE3_RX_DN<11>")
	)
	(segment
		(start 132.517134 -410.301186)
		(end 132.517134 -406.19934)
		(width 0.14732)
		(layer "In4.Cu")
		(net "P5E_CPU1_PE3_RX_DN<11>")
	)
	(segment
		(start 124.300234 -290.490148)
		(end 124.342144 -290.448238)
		(width 0.0889)
		(layer "In4.Cu")
		(net "P5E_CPU1_PE3_RX_DN<11>")
	)
	(segment
		(start 152.329388 -332.889098)
		(end 127.475996 -302.636174)
		(width 0.14732)
		(layer "In4.Cu")
		(net "P5E_CPU1_PE3_RX_DN<11>")
	)
	(segment
		(start 133.602476 -437.627014)
		(end 133.100318 -437.627014)
		(width 0.14732)
		(layer "In4.Cu")
		(net "P5E_CPU1_PE3_RX_DN<11>")
	)
	(segment
		(start 132.452618 -411.614366)
		(end 132.517134 -410.301186)
		(width 0.14732)
		(layer "In4.Cu")
		(net "P5E_CPU1_PE3_RX_DN<11>")
	)
	(segment
		(start 124.304298 -295.350946)
		(end 124.300234 -295.346882)
		(width 0.14732)
		(layer "In4.Cu")
		(net "P5E_CPU1_PE3_RX_DN<11>")
	)
	(segment
		(start 151.083518 -371.130068)
		(end 153.15438 -363.87913)
		(width 0.14732)
		(layer "In4.Cu")
		(net "P5E_CPU1_PE3_RX_DN<11>")
	)
	(segment
		(start 153.25979 -338.170266)
		(end 152.329388 -332.889098)
		(width 0.14732)
		(layer "In4.Cu")
		(net "P5E_CPU1_PE3_RX_DN<11>")
	)
	(segment
		(start 124.126498 -289.506152)
		(end 123.967494 -289.807142)
		(width 0.0889)
		(layer "In4.Cu")
		(net "P5E_CPU1_PE3_RX_DN<11>")
	)
	(segment
		(start 134.234174 -404.4823)
		(end 134.234174 -399.92554)
		(width 0.14732)
		(layer "In4.Cu")
		(net "P5E_CPU1_PE3_RX_DN<11>")
	)
	(segment
		(start 133.100318 -437.627014)
		(end 132.795264 -437.32196)
		(width 0.14732)
		(layer "In4.Cu")
		(net "P5E_CPU1_PE3_RX_DN<11>")
	)
	(segment
		(start 134.234174 -399.92554)
		(end 134.656576 -399.100294)
		(width 0.14732)
		(layer "In4.Cu")
		(net "P5E_CPU1_PE3_RX_DN<11>")
	)
	(segment
		(start 133.75005 -438.089802)
		(end 133.75005 -437.774588)
		(width 0.14732)
		(layer "In4.Cu")
		(net "P5E_CPU1_PE3_RX_DN<11>")
	)
	(arc
		(start 124.342144 -289.645852)
		(mid 124.287493 -289.554442)
		(end 124.21108 -289.480244)
		(width 0.0889)
		(layer "In4.Cu")
		(net "P5E_CPU1_PE3_RX_DN<11>")
	)
	(segment
		(start 125.377448 -288.381186)
		(end 125.377448 -288.917126)
		(width 0.13208)
		(layer "F.Cu")
		(net "P5E_CPU1_PE3_RX_DN<10>")
	)
	(segment
		(start 137.297414 -404.4823)
		(end 137.297414 -399.189448)
		(width 0.14732)
		(layer "In4.Cu")
		(net "P5E_CPU1_PE3_RX_DN<10>")
	)
	(segment
		(start 125.281944 -290.448238)
		(end 125.281944 -289.563556)
		(width 0.0889)
		(layer "In4.Cu")
		(net "P5E_CPU1_PE3_RX_DN<10>")
	)
	(segment
		(start 125.240288 -290.5125)
		(end 125.240034 -290.512246)
		(width 0.14732)
		(layer "In4.Cu")
		(net "P5E_CPU1_PE3_RX_DN<10>")
	)
	(segment
		(start 154.297126 -338.5947)
		(end 153.226262 -332.515718)
		(width 0.14732)
		(layer "In4.Cu")
		(net "P5E_CPU1_PE3_RX_DN<10>")
	)
	(segment
		(start 137.297414 -399.189448)
		(end 151.98344 -371.43182)
		(width 0.14732)
		(layer "In4.Cu")
		(net "P5E_CPU1_PE3_RX_DN<10>")
	)
	(segment
		(start 135.750046 -439.0898)
		(end 135.750046 -438.774586)
		(width 0.14732)
		(layer "In4.Cu")
		(net "P5E_CPU1_PE3_RX_DN<10>")
	)
	(segment
		(start 135.602472 -438.627012)
		(end 135.100314 -438.627012)
		(width 0.14732)
		(layer "In4.Cu")
		(net "P5E_CPU1_PE3_RX_DN<10>")
	)
	(segment
		(start 125.240034 -290.490148)
		(end 125.281944 -290.448238)
		(width 0.0889)
		(layer "In4.Cu")
		(net "P5E_CPU1_PE3_RX_DN<10>")
	)
	(segment
		(start 125.220984 -288.646108)
		(end 125.377448 -288.917126)
		(width 0.0889)
		(layer "In4.Cu")
		(net "P5E_CPU1_PE3_RX_DN<10>")
	)
	(segment
		(start 125.242066 -288.56813)
		(end 125.220984 -288.646108)
		(width 0.0889)
		(layer "In4.Cu")
		(net "P5E_CPU1_PE3_RX_DN<10>")
	)
	(segment
		(start 125.240288 -294.567102)
		(end 125.240288 -290.5125)
		(width 0.14732)
		(layer "In4.Cu")
		(net "P5E_CPU1_PE3_RX_DN<10>")
	)
	(segment
		(start 154.13355 -364.0328)
		(end 154.297126 -338.5947)
		(width 0.14732)
		(layer "In4.Cu")
		(net "P5E_CPU1_PE3_RX_DN<10>")
	)
	(segment
		(start 134.792466 -424.014392)
		(end 135.467344 -411.77083)
		(width 0.14732)
		(layer "In4.Cu")
		(net "P5E_CPU1_PE3_RX_DN<10>")
	)
	(segment
		(start 125.281944 -289.563556)
		(end 125.567694 -289.277806)
		(width 0.0889)
		(layer "In4.Cu")
		(net "P5E_CPU1_PE3_RX_DN<10>")
	)
	(segment
		(start 151.98344 -371.43182)
		(end 154.13355 -364.0328)
		(width 0.14732)
		(layer "In4.Cu")
		(net "P5E_CPU1_PE3_RX_DN<10>")
	)
	(segment
		(start 153.226262 -332.515718)
		(end 128.310132 -302.186086)
		(width 0.14732)
		(layer "In4.Cu")
		(net "P5E_CPU1_PE3_RX_DN<10>")
	)
	(segment
		(start 128.310132 -302.186086)
		(end 126.00178 -298.889166)
		(width 0.14732)
		(layer "In4.Cu")
		(net "P5E_CPU1_PE3_RX_DN<10>")
	)
	(segment
		(start 135.580374 -410.624274)
		(end 135.580374 -406.19934)
		(width 0.14732)
		(layer "In4.Cu")
		(net "P5E_CPU1_PE3_RX_DN<10>")
	)
	(segment
		(start 125.240034 -290.512246)
		(end 125.240034 -290.490148)
		(width 0.0889)
		(layer "In4.Cu")
		(net "P5E_CPU1_PE3_RX_DN<10>")
	)
	(segment
		(start 135.580374 -406.19934)
		(end 137.297414 -404.4823)
		(width 0.14732)
		(layer "In4.Cu")
		(net "P5E_CPU1_PE3_RX_DN<10>")
	)
	(segment
		(start 135.100314 -438.627012)
		(end 134.792466 -438.319164)
		(width 0.14732)
		(layer "In4.Cu")
		(net "P5E_CPU1_PE3_RX_DN<10>")
	)
	(segment
		(start 125.573536 -288.597848)
		(end 125.564646 -288.592768)
		(width 0.0889)
		(layer "In4.Cu")
		(net "P5E_CPU1_PE3_RX_DN<10>")
	)
	(segment
		(start 134.792466 -438.319164)
		(end 134.792466 -424.014392)
		(width 0.14732)
		(layer "In4.Cu")
		(net "P5E_CPU1_PE3_RX_DN<10>")
	)
	(segment
		(start 135.467344 -411.77083)
		(end 135.580374 -410.624274)
		(width 0.14732)
		(layer "In4.Cu")
		(net "P5E_CPU1_PE3_RX_DN<10>")
	)
	(segment
		(start 135.750046 -438.774586)
		(end 135.602472 -438.627012)
		(width 0.14732)
		(layer "In4.Cu")
		(net "P5E_CPU1_PE3_RX_DN<10>")
	)
	(segment
		(start 126.00178 -298.889166)
		(end 125.240288 -294.567102)
		(width 0.14732)
		(layer "In4.Cu")
		(net "P5E_CPU1_PE3_RX_DN<10>")
	)
	(segment
		(start 125.752098 -289.077908)
		(end 125.752098 -288.917126)
		(width 0.0889)
		(layer "In4.Cu")
		(net "P5E_CPU1_PE3_RX_DN<10>")
	)
	(arc
		(start 125.567694 -289.277806)
		(mid 125.67709 -289.193709)
		(end 125.752098 -289.077908)
		(width 0.0889)
		(layer "In4.Cu")
		(net "P5E_CPU1_PE3_RX_DN<10>")
	)
	(arc
		(start 125.564646 -288.592768)
		(mid 125.406158 -288.543835)
		(end 125.242066 -288.56813)
		(width 0.0889)
		(layer "In4.Cu")
		(net "P5E_CPU1_PE3_RX_DN<10>")
	)
	(arc
		(start 125.752098 -288.917126)
		(mid 125.704419 -288.734226)
		(end 125.573536 -288.597848)
		(width 0.0889)
		(layer "In4.Cu")
		(net "P5E_CPU1_PE3_RX_DN<10>")
	)
	(segment
		(start 135.245094 -287.567116)
		(end 135.245094 -288.102802)
		(width 0.13208)
		(layer "F.Cu")
		(net "P5E_CPU1_PE3_RX_DN<0>")
	)
	(segment
		(start 135.245094 -288.102802)
		(end 135.245348 -288.103056)
		(width 0.13208)
		(layer "F.Cu")
		(net "P5E_CPU1_PE3_RX_DN<0>")
	)
	(segment
		(start 164.149024 -327.367392)
		(end 165.032944 -341.102442)
		(width 0.14732)
		(layer "In4.Cu")
		(net "P5E_CPU1_PE3_RX_DN<0>")
	)
	(segment
		(start 156.665168 -320.343022)
		(end 163.245546 -324.950328)
		(width 0.14732)
		(layer "In4.Cu")
		(net "P5E_CPU1_PE3_RX_DN<0>")
	)
	(segment
		(start 135.245348 -288.103056)
		(end 135.401812 -288.374074)
		(width 0.0889)
		(layer "In4.Cu")
		(net "P5E_CPU1_PE3_RX_DN<0>")
	)
	(segment
		(start 156.066744 -424.356784)
		(end 156.066744 -438.205372)
		(width 0.14732)
		(layer "In4.Cu")
		(net "P5E_CPU1_PE3_RX_DN<0>")
	)
	(segment
		(start 168.204134 -404.596092)
		(end 166.487094 -406.313132)
		(width 0.14732)
		(layer "In4.Cu")
		(net "P5E_CPU1_PE3_RX_DN<0>")
	)
	(segment
		(start 156.214064 -438.352692)
		(end 156.538422 -438.352692)
		(width 0.14732)
		(layer "In4.Cu")
		(net "P5E_CPU1_PE3_RX_DN<0>")
	)
	(segment
		(start 167.552878 -396.188692)
		(end 168.204134 -400.560032)
		(width 0.14732)
		(layer "In4.Cu")
		(net "P5E_CPU1_PE3_RX_DN<0>")
	)
	(segment
		(start 156.538422 -438.352692)
		(end 156.750004 -438.14111)
		(width 0.14732)
		(layer "In4.Cu")
		(net "P5E_CPU1_PE3_RX_DN<0>")
	)
	(segment
		(start 156.066744 -438.205372)
		(end 156.214064 -438.352692)
		(width 0.14732)
		(layer "In4.Cu")
		(net "P5E_CPU1_PE3_RX_DN<0>")
	)
	(segment
		(start 136.833356 -289.175698)
		(end 137.16762 -289.509962)
		(width 0.14732)
		(layer "In4.Cu")
		(net "P5E_CPU1_PE3_RX_DN<0>")
	)
	(segment
		(start 156.066998 -424.35653)
		(end 156.066744 -424.356784)
		(width 0.14732)
		(layer "In4.Cu")
		(net "P5E_CPU1_PE3_RX_DN<0>")
	)
	(segment
		(start 137.16762 -289.510978)
		(end 138.402568 -290.745672)
		(width 0.14732)
		(layer "In4.Cu")
		(net "P5E_CPU1_PE3_RX_DN<0>")
	)
	(segment
		(start 156.750004 -438.14111)
		(end 156.750004 -437.889904)
		(width 0.14732)
		(layer "In4.Cu")
		(net "P5E_CPU1_PE3_RX_DN<0>")
	)
	(segment
		(start 135.401812 -288.374074)
		(end 135.490966 -288.39795)
		(width 0.0889)
		(layer "In4.Cu")
		(net "P5E_CPU1_PE3_RX_DN<0>")
	)
	(segment
		(start 164.654484 -365.527844)
		(end 167.552878 -396.188692)
		(width 0.14732)
		(layer "In4.Cu")
		(net "P5E_CPU1_PE3_RX_DN<0>")
	)
	(segment
		(start 163.245546 -324.950328)
		(end 163.884356 -325.862696)
		(width 0.14732)
		(layer "In4.Cu")
		(net "P5E_CPU1_PE3_RX_DN<0>")
	)
	(segment
		(start 166.487094 -406.313132)
		(end 166.487094 -410.957776)
		(width 0.14732)
		(layer "In4.Cu")
		(net "P5E_CPU1_PE3_RX_DN<0>")
	)
	(segment
		(start 168.204134 -400.560032)
		(end 168.204134 -404.596092)
		(width 0.14732)
		(layer "In4.Cu")
		(net "P5E_CPU1_PE3_RX_DN<0>")
	)
	(segment
		(start 136.115044 -288.51733)
		(end 136.757918 -289.160204)
		(width 0.0889)
		(layer "In4.Cu")
		(net "P5E_CPU1_PE3_RX_DN<0>")
	)
	(segment
		(start 166.487094 -410.957776)
		(end 156.066998 -424.35653)
		(width 0.14732)
		(layer "In4.Cu")
		(net "P5E_CPU1_PE3_RX_DN<0>")
	)
	(segment
		(start 136.757918 -289.160204)
		(end 136.817862 -289.160204)
		(width 0.0889)
		(layer "In4.Cu")
		(net "P5E_CPU1_PE3_RX_DN<0>")
	)
	(segment
		(start 138.402568 -290.745672)
		(end 156.665168 -320.343022)
		(width 0.14732)
		(layer "In4.Cu")
		(net "P5E_CPU1_PE3_RX_DN<0>")
	)
	(segment
		(start 137.16762 -289.509962)
		(end 137.16762 -289.510978)
		(width 0.14732)
		(layer "In4.Cu")
		(net "P5E_CPU1_PE3_RX_DN<0>")
	)
	(segment
		(start 165.032944 -341.102442)
		(end 164.654484 -365.527844)
		(width 0.14732)
		(layer "In4.Cu")
		(net "P5E_CPU1_PE3_RX_DN<0>")
	)
	(segment
		(start 136.817862 -289.160204)
		(end 136.833356 -289.175698)
		(width 0.0889)
		(layer "In4.Cu")
		(net "P5E_CPU1_PE3_RX_DN<0>")
	)
	(segment
		(start 163.884356 -325.862696)
		(end 164.149024 -327.367392)
		(width 0.14732)
		(layer "In4.Cu")
		(net "P5E_CPU1_PE3_RX_DN<0>")
	)
	(arc
		(start 135.99795 -288.427414)
		(mid 136.059445 -288.468533)
		(end 136.115044 -288.51733)
		(width 0.0889)
		(layer "In4.Cu")
		(net "P5E_CPU1_PE3_RX_DN<0>")
	)
	(arc
		(start 135.490966 -288.39795)
		(mid 135.500707 -288.393795)
		(end 135.510524 -288.389822)
		(width 0.0889)
		(layer "In4.Cu")
		(net "P5E_CPU1_PE3_RX_DN<0>")
	)
	(arc
		(start 135.510524 -288.389822)
		(mid 135.758504 -288.35321)
		(end 135.99795 -288.427414)
		(width 0.0889)
		(layer "In4.Cu")
		(net "P5E_CPU1_PE3_RX_DN<0>")
	)
	(segment
		(start 129.026666 -225.203512)
		(end 129.026412 -225.203258)
		(width 0.13208)
		(layer "F.Cu")
		(net "P5E_CPU1_PE2_TX_DP<9>")
	)
	(segment
		(start 138.513566 -402.104352)
		(end 138.508994 -402.104352)
		(width 0.13208)
		(layer "F.Cu")
		(net "P5E_CPU1_PE2_TX_DP<9>")
	)
	(segment
		(start 129.026666 -225.739198)
		(end 129.026666 -225.203512)
		(width 0.13208)
		(layer "F.Cu")
		(net "P5E_CPU1_PE2_TX_DP<9>")
	)
	(segment
		(start 138.839956 -401.16379)
		(end 138.839956 -401.777962)
		(width 0.13208)
		(layer "F.Cu")
		(net "P5E_CPU1_PE2_TX_DP<9>")
	)
	(segment
		(start 138.839956 -401.777962)
		(end 138.513566 -402.104352)
		(width 0.13208)
		(layer "F.Cu")
		(net "P5E_CPU1_PE2_TX_DP<9>")
	)
	(segment
		(start 138.534394 -400.858228)
		(end 138.839956 -401.16379)
		(width 0.13208)
		(layer "F.Cu")
		(net "P5E_CPU1_PE2_TX_DP<9>")
	)
	(segment
		(start 139.540742 -398.105376)
		(end 139.540996 -398.10563)
		(width 0.14732)
		(layer "In15.Cu")
		(net "P5E_CPU1_PE2_TX_DP<9>")
	)
	(segment
		(start 151.90978 -370.393468)
		(end 140.913612 -395.02969)
		(width 0.14732)
		(layer "In15.Cu")
		(net "P5E_CPU1_PE2_TX_DP<9>")
	)
	(segment
		(start 138.676888 -218.12885)
		(end 141.281404 -220.73362)
		(width 0.14732)
		(layer "In15.Cu")
		(net "P5E_CPU1_PE2_TX_DP<9>")
	)
	(segment
		(start 156.660596 -345.995498)
		(end 155.949396 -350.035622)
		(width 0.14732)
		(layer "In15.Cu")
		(net "P5E_CPU1_PE2_TX_DP<9>")
	)
	(segment
		(start 130.709924 -221.628462)
		(end 130.718814 -221.623382)
		(width 0.0889)
		(layer "In15.Cu")
		(net "P5E_CPU1_PE2_TX_DP<9>")
	)
	(segment
		(start 140.913612 -395.02969)
		(end 140.749274 -395.092682)
		(width 0.14732)
		(layer "In15.Cu")
		(net "P5E_CPU1_PE2_TX_DP<9>")
	)
	(segment
		(start 139.655804 -397.542512)
		(end 139.718796 -397.706596)
		(width 0.14732)
		(layer "In15.Cu")
		(net "P5E_CPU1_PE2_TX_DP<9>")
	)
	(segment
		(start 131.001516 -221.133924)
		(end 131.001516 -221.115382)
		(width 0.0889)
		(layer "In15.Cu")
		(net "P5E_CPU1_PE2_TX_DP<9>")
	)
	(segment
		(start 148.4122 -253.148846)
		(end 144.1069 -309.364888)
		(width 0.14732)
		(layer "In15.Cu")
		(net "P5E_CPU1_PE2_TX_DP<9>")
	)
	(segment
		(start 141.281404 -220.73362)
		(end 143.831564 -224.101914)
		(width 0.14732)
		(layer "In15.Cu")
		(net "P5E_CPU1_PE2_TX_DP<9>")
	)
	(segment
		(start 130.718814 -221.623382)
		(end 130.72491 -221.619826)
		(width 0.0889)
		(layer "In15.Cu")
		(net "P5E_CPU1_PE2_TX_DP<9>")
	)
	(segment
		(start 138.661394 -218.054428)
		(end 138.661394 -218.113356)
		(width 0.0889)
		(layer "In15.Cu")
		(net "P5E_CPU1_PE2_TX_DP<9>")
	)
	(segment
		(start 130.531362 -221.963234)
		(end 130.531362 -221.94774)
		(width 0.0889)
		(layer "In15.Cu")
		(net "P5E_CPU1_PE2_TX_DP<9>")
	)
	(segment
		(start 138.829034 -399.700496)
		(end 138.829034 -400.563588)
		(width 0.14732)
		(layer "In15.Cu")
		(net "P5E_CPU1_PE2_TX_DP<9>")
	)
	(segment
		(start 155.949396 -350.035622)
		(end 154.797252 -363.22635)
		(width 0.14732)
		(layer "In15.Cu")
		(net "P5E_CPU1_PE2_TX_DP<9>")
	)
	(segment
		(start 131.001516 -219.515944)
		(end 131.001516 -219.506038)
		(width 0.0889)
		(layer "In15.Cu")
		(net "P5E_CPU1_PE2_TX_DP<9>")
	)
	(segment
		(start 148.316696 -250.312428)
		(end 148.4122 -253.148846)
		(width 0.14732)
		(layer "In15.Cu")
		(net "P5E_CPU1_PE2_TX_DP<9>")
	)
	(segment
		(start 143.831564 -224.101914)
		(end 144.343628 -225.870516)
		(width 0.14732)
		(layer "In15.Cu")
		(net "P5E_CPU1_PE2_TX_DP<9>")
	)
	(segment
		(start 130.061716 -222.77578)
		(end 130.061716 -222.761556)
		(width 0.0889)
		(layer "In15.Cu")
		(net "P5E_CPU1_PE2_TX_DP<9>")
	)
	(segment
		(start 133.059678 -217.559128)
		(end 133.068568 -217.554048)
		(width 0.0889)
		(layer "In15.Cu")
		(net "P5E_CPU1_PE2_TX_DP<9>")
	)
	(segment
		(start 131.180078 -219.18676)
		(end 131.188968 -219.18168)
		(width 0.0889)
		(layer "In15.Cu")
		(net "P5E_CPU1_PE2_TX_DP<9>")
	)
	(segment
		(start 147.91182 -325.303388)
		(end 154.327352 -332.77048)
		(width 0.14732)
		(layer "In15.Cu")
		(net "P5E_CPU1_PE2_TX_DP<9>")
	)
	(segment
		(start 138.829034 -400.563588)
		(end 138.534394 -400.858228)
		(width 0.14732)
		(layer "In15.Cu")
		(net "P5E_CPU1_PE2_TX_DP<9>")
	)
	(segment
		(start 134.467854 -216.746074)
		(end 134.478268 -216.739978)
		(width 0.0889)
		(layer "In15.Cu")
		(net "P5E_CPU1_PE2_TX_DP<9>")
	)
	(segment
		(start 129.026412 -225.203258)
		(end 128.869948 -224.93224)
		(width 0.0889)
		(layer "In15.Cu")
		(net "P5E_CPU1_PE2_TX_DP<9>")
	)
	(segment
		(start 144.343628 -225.870516)
		(end 145.10512 -229.720648)
		(width 0.14732)
		(layer "In15.Cu")
		(net "P5E_CPU1_PE2_TX_DP<9>")
	)
	(segment
		(start 154.327352 -332.77048)
		(end 156.660596 -345.995498)
		(width 0.14732)
		(layer "In15.Cu")
		(net "P5E_CPU1_PE2_TX_DP<9>")
	)
	(segment
		(start 138.220196 -217.61323)
		(end 138.661394 -218.054428)
		(width 0.0889)
		(layer "In15.Cu")
		(net "P5E_CPU1_PE2_TX_DP<9>")
	)
	(segment
		(start 139.37615 -398.168622)
		(end 139.198096 -398.56791)
		(width 0.14732)
		(layer "In15.Cu")
		(net "P5E_CPU1_PE2_TX_DP<9>")
	)
	(segment
		(start 140.113512 -396.517368)
		(end 140.176504 -396.681706)
		(width 0.14732)
		(layer "In15.Cu")
		(net "P5E_CPU1_PE2_TX_DP<9>")
	)
	(segment
		(start 144.1069 -309.364888)
		(end 147.91182 -325.303388)
		(width 0.14732)
		(layer "In15.Cu")
		(net "P5E_CPU1_PE2_TX_DP<9>")
	)
	(segment
		(start 139.833858 -397.143478)
		(end 139.655804 -397.542512)
		(width 0.14732)
		(layer "In15.Cu")
		(net "P5E_CPU1_PE2_TX_DP<9>")
	)
	(segment
		(start 140.176504 -396.681706)
		(end 139.99845 -397.080486)
		(width 0.14732)
		(layer "In15.Cu")
		(net "P5E_CPU1_PE2_TX_DP<9>")
	)
	(segment
		(start 154.797252 -363.22635)
		(end 151.90978 -370.393468)
		(width 0.14732)
		(layer "In15.Cu")
		(net "P5E_CPU1_PE2_TX_DP<9>")
	)
	(segment
		(start 140.749274 -395.092682)
		(end 140.57122 -395.49197)
		(width 0.14732)
		(layer "In15.Cu")
		(net "P5E_CPU1_PE2_TX_DP<9>")
	)
	(segment
		(start 137.672064 -216.739978)
		(end 137.680954 -216.745058)
		(width 0.0889)
		(layer "In15.Cu")
		(net "P5E_CPU1_PE2_TX_DP<9>")
	)
	(segment
		(start 128.869948 -224.93224)
		(end 128.894078 -224.843086)
		(width 0.0889)
		(layer "In15.Cu")
		(net "P5E_CPU1_PE2_TX_DP<9>")
	)
	(segment
		(start 137.859516 -217.064336)
		(end 137.859516 -217.07856)
		(width 0.0889)
		(layer "In15.Cu")
		(net "P5E_CPU1_PE2_TX_DP<9>")
	)
	(segment
		(start 145.10512 -229.720648)
		(end 148.316696 -250.312428)
		(width 0.14732)
		(layer "In15.Cu")
		(net "P5E_CPU1_PE2_TX_DP<9>")
	)
	(segment
		(start 132.589524 -218.372944)
		(end 132.598414 -218.367864)
		(width 0.0889)
		(layer "In15.Cu")
		(net "P5E_CPU1_PE2_TX_DP<9>")
	)
	(segment
		(start 132.410962 -218.707716)
		(end 132.410962 -218.692222)
		(width 0.0889)
		(layer "In15.Cu")
		(net "P5E_CPU1_PE2_TX_DP<9>")
	)
	(segment
		(start 139.718796 -397.706596)
		(end 139.540742 -398.105376)
		(width 0.14732)
		(layer "In15.Cu")
		(net "P5E_CPU1_PE2_TX_DP<9>")
	)
	(segment
		(start 139.198096 -398.56791)
		(end 139.261088 -398.732248)
		(width 0.14732)
		(layer "In15.Cu")
		(net "P5E_CPU1_PE2_TX_DP<9>")
	)
	(segment
		(start 130.240278 -222.442278)
		(end 130.249168 -222.437198)
		(width 0.0889)
		(layer "In15.Cu")
		(net "P5E_CPU1_PE2_TX_DP<9>")
	)
	(segment
		(start 138.661394 -218.113356)
		(end 138.676888 -218.12885)
		(width 0.0889)
		(layer "In15.Cu")
		(net "P5E_CPU1_PE2_TX_DP<9>")
	)
	(segment
		(start 140.57122 -395.49197)
		(end 140.634212 -395.656308)
		(width 0.14732)
		(layer "In15.Cu")
		(net "P5E_CPU1_PE2_TX_DP<9>")
	)
	(segment
		(start 140.291566 -396.11808)
		(end 140.113512 -396.517368)
		(width 0.14732)
		(layer "In15.Cu")
		(net "P5E_CPU1_PE2_TX_DP<9>")
	)
	(segment
		(start 139.261088 -398.732248)
		(end 138.829034 -399.700496)
		(width 0.14732)
		(layer "In15.Cu")
		(net "P5E_CPU1_PE2_TX_DP<9>")
	)
	(segment
		(start 139.540996 -398.10563)
		(end 139.37615 -398.168622)
		(width 0.14732)
		(layer "In15.Cu")
		(net "P5E_CPU1_PE2_TX_DP<9>")
	)
	(segment
		(start 140.634212 -395.656308)
		(end 140.456158 -396.055088)
		(width 0.14732)
		(layer "In15.Cu")
		(net "P5E_CPU1_PE2_TX_DP<9>")
	)
	(segment
		(start 132.598414 -218.367864)
		(end 132.60451 -218.364308)
		(width 0.0889)
		(layer "In15.Cu")
		(net "P5E_CPU1_PE2_TX_DP<9>")
	)
	(segment
		(start 140.456158 -396.055088)
		(end 140.291566 -396.11808)
		(width 0.14732)
		(layer "In15.Cu")
		(net "P5E_CPU1_PE2_TX_DP<9>")
	)
	(segment
		(start 139.99845 -397.080486)
		(end 139.833858 -397.143478)
		(width 0.14732)
		(layer "In15.Cu")
		(net "P5E_CPU1_PE2_TX_DP<9>")
	)
	(segment
		(start 133.351016 -217.082878)
		(end 133.351016 -217.0557)
		(width 0.0889)
		(layer "In15.Cu")
		(net "P5E_CPU1_PE2_TX_DP<9>")
	)
	(segment
		(start 129.300478 -224.070164)
		(end 129.309368 -224.065084)
		(width 0.0889)
		(layer "In15.Cu")
		(net "P5E_CPU1_PE2_TX_DP<9>")
	)
	(segment
		(start 130.710178 -220.000576)
		(end 130.719068 -219.995496)
		(width 0.0889)
		(layer "In15.Cu")
		(net "P5E_CPU1_PE2_TX_DP<9>")
	)
	(segment
		(start 131.563364 -219.18168)
		(end 131.578096 -219.190316)
		(width 0.0889)
		(layer "In15.Cu")
		(net "P5E_CPU1_PE2_TX_DP<9>")
	)
	(segment
		(start 129.591816 -223.585532)
		(end 129.591816 -223.56699)
		(width 0.0889)
		(layer "In15.Cu")
		(net "P5E_CPU1_PE2_TX_DP<9>")
	)
	(segment
		(start 130.719068 -220.644212)
		(end 130.710178 -220.639132)
		(width 0.0889)
		(layer "In15.Cu")
		(net "P5E_CPU1_PE2_TX_DP<9>")
	)
	(arc
		(start 136.732264 -216.739978)
		(mid 137.014966 -216.815754)
		(end 137.297668 -216.739978)
		(width 0.0889)
		(layer "In15.Cu")
		(net "P5E_CPU1_PE2_TX_DP<9>")
	)
	(arc
		(start 130.249168 -222.437198)
		(mid 130.451991 -222.236967)
		(end 130.531362 -221.963234)
		(width 0.0889)
		(layer "In15.Cu")
		(net "P5E_CPU1_PE2_TX_DP<9>")
	)
	(arc
		(start 133.068568 -217.554048)
		(mid 133.270854 -217.355067)
		(end 133.351016 -217.082878)
		(width 0.0889)
		(layer "In15.Cu")
		(net "P5E_CPU1_PE2_TX_DP<9>")
	)
	(arc
		(start 130.719068 -219.995496)
		(mid 130.923403 -219.792891)
		(end 131.001516 -219.515944)
		(width 0.0889)
		(layer "In15.Cu")
		(net "P5E_CPU1_PE2_TX_DP<9>")
	)
	(arc
		(start 133.91261 -216.739978)
		(mid 134.189423 -216.815848)
		(end 134.467854 -216.746074)
		(width 0.0889)
		(layer "In15.Cu")
		(net "P5E_CPU1_PE2_TX_DP<9>")
	)
	(arc
		(start 132.60451 -218.364308)
		(mid 132.807097 -218.157957)
		(end 132.881116 -217.878406)
		(width 0.0889)
		(layer "In15.Cu")
		(net "P5E_CPU1_PE2_TX_DP<9>")
	)
	(arc
		(start 129.309368 -224.065084)
		(mid 129.513703 -223.862479)
		(end 129.591816 -223.585532)
		(width 0.0889)
		(layer "In15.Cu")
		(net "P5E_CPU1_PE2_TX_DP<9>")
	)
	(arc
		(start 135.418068 -216.739978)
		(mid 135.605266 -216.689835)
		(end 135.792464 -216.739978)
		(width 0.0889)
		(layer "In15.Cu")
		(net "P5E_CPU1_PE2_TX_DP<9>")
	)
	(arc
		(start 130.710178 -220.639132)
		(mid 130.579264 -220.502772)
		(end 130.531616 -220.319854)
		(width 0.0889)
		(layer "In15.Cu")
		(net "P5E_CPU1_PE2_TX_DP<9>")
	)
	(arc
		(start 132.128768 -219.18168)
		(mid 132.331591 -218.981449)
		(end 132.410962 -218.707716)
		(width 0.0889)
		(layer "In15.Cu")
		(net "P5E_CPU1_PE2_TX_DP<9>")
	)
	(arc
		(start 131.001516 -221.115382)
		(mid 130.921354 -220.843193)
		(end 130.719068 -220.644212)
		(width 0.0889)
		(layer "In15.Cu")
		(net "P5E_CPU1_PE2_TX_DP<9>")
	)
	(arc
		(start 134.478268 -216.739978)
		(mid 134.665466 -216.689835)
		(end 134.852664 -216.739978)
		(width 0.0889)
		(layer "In15.Cu")
		(net "P5E_CPU1_PE2_TX_DP<9>")
	)
	(arc
		(start 133.351016 -217.0557)
		(mid 133.403286 -216.873335)
		(end 133.538214 -216.739978)
		(width 0.0889)
		(layer "In15.Cu")
		(net "P5E_CPU1_PE2_TX_DP<9>")
	)
	(arc
		(start 133.538214 -216.739978)
		(mid 133.725412 -216.689835)
		(end 133.91261 -216.739978)
		(width 0.0889)
		(layer "In15.Cu")
		(net "P5E_CPU1_PE2_TX_DP<9>")
	)
	(arc
		(start 130.531616 -220.319854)
		(mid 130.579295 -220.136954)
		(end 130.710178 -220.000576)
		(width 0.0889)
		(layer "In15.Cu")
		(net "P5E_CPU1_PE2_TX_DP<9>")
	)
	(arc
		(start 130.531362 -221.94774)
		(mid 130.579041 -221.76484)
		(end 130.709924 -221.628462)
		(width 0.0889)
		(layer "In15.Cu")
		(net "P5E_CPU1_PE2_TX_DP<9>")
	)
	(arc
		(start 131.578096 -219.190316)
		(mid 131.854571 -219.257636)
		(end 132.128768 -219.18168)
		(width 0.0889)
		(layer "In15.Cu")
		(net "P5E_CPU1_PE2_TX_DP<9>")
	)
	(arc
		(start 130.72491 -221.619826)
		(mid 130.927497 -221.413475)
		(end 131.001516 -221.133924)
		(width 0.0889)
		(layer "In15.Cu")
		(net "P5E_CPU1_PE2_TX_DP<9>")
	)
	(arc
		(start 129.591816 -223.56699)
		(mid 129.644086 -223.384625)
		(end 129.779014 -223.251268)
		(width 0.0889)
		(layer "In15.Cu")
		(net "P5E_CPU1_PE2_TX_DP<9>")
	)
	(arc
		(start 129.779014 -223.251268)
		(mid 129.982495 -223.050464)
		(end 130.061716 -222.77578)
		(width 0.0889)
		(layer "In15.Cu")
		(net "P5E_CPU1_PE2_TX_DP<9>")
	)
	(arc
		(start 128.894078 -224.843086)
		(mid 128.90265 -224.836564)
		(end 128.911096 -224.829878)
		(width 0.0889)
		(layer "In15.Cu")
		(net "P5E_CPU1_PE2_TX_DP<9>")
	)
	(arc
		(start 137.680954 -216.745058)
		(mid 137.811868 -216.881418)
		(end 137.859516 -217.064336)
		(width 0.0889)
		(layer "In15.Cu")
		(net "P5E_CPU1_PE2_TX_DP<9>")
	)
	(arc
		(start 136.357868 -216.739978)
		(mid 136.545066 -216.689835)
		(end 136.732264 -216.739978)
		(width 0.0889)
		(layer "In15.Cu")
		(net "P5E_CPU1_PE2_TX_DP<9>")
	)
	(arc
		(start 132.881116 -217.878406)
		(mid 132.928795 -217.695506)
		(end 133.059678 -217.559128)
		(width 0.0889)
		(layer "In15.Cu")
		(net "P5E_CPU1_PE2_TX_DP<9>")
	)
	(arc
		(start 130.061716 -222.761556)
		(mid 130.109395 -222.578656)
		(end 130.240278 -222.442278)
		(width 0.0889)
		(layer "In15.Cu")
		(net "P5E_CPU1_PE2_TX_DP<9>")
	)
	(arc
		(start 137.297668 -216.739978)
		(mid 137.484866 -216.689835)
		(end 137.672064 -216.739978)
		(width 0.0889)
		(layer "In15.Cu")
		(net "P5E_CPU1_PE2_TX_DP<9>")
	)
	(arc
		(start 131.001516 -219.506038)
		(mid 131.049195 -219.323138)
		(end 131.180078 -219.18676)
		(width 0.0889)
		(layer "In15.Cu")
		(net "P5E_CPU1_PE2_TX_DP<9>")
	)
	(arc
		(start 134.852664 -216.739978)
		(mid 135.135366 -216.815754)
		(end 135.418068 -216.739978)
		(width 0.0889)
		(layer "In15.Cu")
		(net "P5E_CPU1_PE2_TX_DP<9>")
	)
	(arc
		(start 131.188968 -219.18168)
		(mid 131.376166 -219.131537)
		(end 131.563364 -219.18168)
		(width 0.0889)
		(layer "In15.Cu")
		(net "P5E_CPU1_PE2_TX_DP<9>")
	)
	(arc
		(start 132.410962 -218.692222)
		(mid 132.458641 -218.509322)
		(end 132.589524 -218.372944)
		(width 0.0889)
		(layer "In15.Cu")
		(net "P5E_CPU1_PE2_TX_DP<9>")
	)
	(arc
		(start 138.142218 -217.554048)
		(mid 138.183148 -217.581081)
		(end 138.220196 -217.61323)
		(width 0.0889)
		(layer "In15.Cu")
		(net "P5E_CPU1_PE2_TX_DP<9>")
	)
	(arc
		(start 128.911096 -224.829878)
		(mid 129.066494 -224.633597)
		(end 129.121916 -224.389442)
		(width 0.0889)
		(layer "In15.Cu")
		(net "P5E_CPU1_PE2_TX_DP<9>")
	)
	(arc
		(start 129.121916 -224.389442)
		(mid 129.169595 -224.206542)
		(end 129.300478 -224.070164)
		(width 0.0889)
		(layer "In15.Cu")
		(net "P5E_CPU1_PE2_TX_DP<9>")
	)
	(arc
		(start 135.792464 -216.739978)
		(mid 136.075166 -216.815754)
		(end 136.357868 -216.739978)
		(width 0.0889)
		(layer "In15.Cu")
		(net "P5E_CPU1_PE2_TX_DP<9>")
	)
	(arc
		(start 137.859516 -217.07856)
		(mid 137.938735 -217.353245)
		(end 138.142218 -217.554048)
		(width 0.0889)
		(layer "In15.Cu")
		(net "P5E_CPU1_PE2_TX_DP<9>")
	)
	(segment
		(start 141.903196 -401.777962)
		(end 141.576806 -402.104352)
		(width 0.13208)
		(layer "F.Cu")
		(net "P5E_CPU1_PE2_TX_DP<8>")
	)
	(segment
		(start 127.616966 -224.925128)
		(end 127.616966 -224.389442)
		(width 0.13208)
		(layer "F.Cu")
		(net "P5E_CPU1_PE2_TX_DP<8>")
	)
	(segment
		(start 141.597634 -400.858228)
		(end 141.903196 -401.16379)
		(width 0.13208)
		(layer "F.Cu")
		(net "P5E_CPU1_PE2_TX_DP<8>")
	)
	(segment
		(start 141.903196 -401.16379)
		(end 141.903196 -401.777962)
		(width 0.13208)
		(layer "F.Cu")
		(net "P5E_CPU1_PE2_TX_DP<8>")
	)
	(segment
		(start 141.576806 -402.104352)
		(end 141.572234 -402.104352)
		(width 0.13208)
		(layer "F.Cu")
		(net "P5E_CPU1_PE2_TX_DP<8>")
	)
	(segment
		(start 127.616712 -224.925382)
		(end 127.616966 -224.925128)
		(width 0.13208)
		(layer "F.Cu")
		(net "P5E_CPU1_PE2_TX_DP<8>")
	)
	(segment
		(start 137.746994 -215.938354)
		(end 137.767822 -215.926162)
		(width 0.0889)
		(layer "In15.Cu")
		(net "P5E_CPU1_PE2_TX_DP<8>")
	)
	(segment
		(start 142.949168 -397.397986)
		(end 142.79372 -397.806164)
		(width 0.14732)
		(layer "In15.Cu")
		(net "P5E_CPU1_PE2_TX_DP<8>")
	)
	(segment
		(start 129.591562 -221.963234)
		(end 129.591562 -221.94774)
		(width 0.0889)
		(layer "In15.Cu")
		(net "P5E_CPU1_PE2_TX_DP<8>")
	)
	(segment
		(start 137.767822 -215.926162)
		(end 137.7823 -215.91778)
		(width 0.0889)
		(layer "In15.Cu")
		(net "P5E_CPU1_PE2_TX_DP<8>")
	)
	(segment
		(start 143.34871 -396.348712)
		(end 143.193262 -396.75689)
		(width 0.14732)
		(layer "In15.Cu")
		(net "P5E_CPU1_PE2_TX_DP<8>")
	)
	(segment
		(start 155.198826 -332.298548)
		(end 157.615128 -345.996006)
		(width 0.14732)
		(layer "In15.Cu")
		(net "P5E_CPU1_PE2_TX_DP<8>")
	)
	(segment
		(start 143.831564 -394.730224)
		(end 143.676116 -395.13891)
		(width 0.14732)
		(layer "In15.Cu")
		(net "P5E_CPU1_PE2_TX_DP<8>")
	)
	(segment
		(start 142.632938 -397.878046)
		(end 142.47749 -398.286732)
		(width 0.14732)
		(layer "In15.Cu")
		(net "P5E_CPU1_PE2_TX_DP<8>")
	)
	(segment
		(start 149.345904 -253.2126)
		(end 145.07972 -309.309008)
		(width 0.14732)
		(layer "In15.Cu")
		(net "P5E_CPU1_PE2_TX_DP<8>")
	)
	(segment
		(start 127.77343 -224.118424)
		(end 127.86233 -224.094802)
		(width 0.0889)
		(layer "In15.Cu")
		(net "P5E_CPU1_PE2_TX_DP<8>")
	)
	(segment
		(start 145.325338 -225.886518)
		(end 146.03095 -229.551484)
		(width 0.14732)
		(layer "In15.Cu")
		(net "P5E_CPU1_PE2_TX_DP<8>")
	)
	(segment
		(start 142.549626 -398.44726)
		(end 141.892274 -400.173698)
		(width 0.14732)
		(layer "In15.Cu")
		(net "P5E_CPU1_PE2_TX_DP<8>")
	)
	(segment
		(start 132.881116 -216.260426)
		(end 132.881116 -216.25052)
		(width 0.0889)
		(layer "In15.Cu")
		(net "P5E_CPU1_PE2_TX_DP<8>")
	)
	(segment
		(start 144.759172 -223.748346)
		(end 145.325338 -225.886518)
		(width 0.14732)
		(layer "In15.Cu")
		(net "P5E_CPU1_PE2_TX_DP<8>")
	)
	(segment
		(start 130.718814 -218.367864)
		(end 130.72491 -218.364308)
		(width 0.0889)
		(layer "In15.Cu")
		(net "P5E_CPU1_PE2_TX_DP<8>")
	)
	(segment
		(start 130.709924 -218.372944)
		(end 130.718814 -218.367864)
		(width 0.0889)
		(layer "In15.Cu")
		(net "P5E_CPU1_PE2_TX_DP<8>")
	)
	(segment
		(start 130.061716 -221.133924)
		(end 130.061716 -221.1197)
		(width 0.0889)
		(layer "In15.Cu")
		(net "P5E_CPU1_PE2_TX_DP<8>")
	)
	(segment
		(start 155.734512 -363.818678)
		(end 143.992092 -394.658596)
		(width 0.14732)
		(layer "In15.Cu")
		(net "P5E_CPU1_PE2_TX_DP<8>")
	)
	(segment
		(start 156.972762 -349.643954)
		(end 155.734512 -363.818678)
		(width 0.14732)
		(layer "In15.Cu")
		(net "P5E_CPU1_PE2_TX_DP<8>")
	)
	(segment
		(start 129.591816 -220.32849)
		(end 129.591816 -220.311218)
		(width 0.0889)
		(layer "In15.Cu")
		(net "P5E_CPU1_PE2_TX_DP<8>")
	)
	(segment
		(start 128.369568 -224.065084)
		(end 128.375664 -224.061528)
		(width 0.0889)
		(layer "In15.Cu")
		(net "P5E_CPU1_PE2_TX_DP<8>")
	)
	(segment
		(start 146.03095 -229.551484)
		(end 147.63369 -239.764062)
		(width 0.14732)
		(layer "In15.Cu")
		(net "P5E_CPU1_PE2_TX_DP<8>")
	)
	(segment
		(start 135.322564 -215.926162)
		(end 135.337296 -215.934798)
		(width 0.0889)
		(layer "In15.Cu")
		(net "P5E_CPU1_PE2_TX_DP<8>")
	)
	(segment
		(start 129.779014 -221.623382)
		(end 129.78511 -221.619826)
		(width 0.0889)
		(layer "In15.Cu")
		(net "P5E_CPU1_PE2_TX_DP<8>")
	)
	(segment
		(start 140.985494 -218.810586)
		(end 144.759172 -223.748346)
		(width 0.14732)
		(layer "In15.Cu")
		(net "P5E_CPU1_PE2_TX_DP<8>")
	)
	(segment
		(start 143.748252 -395.299438)
		(end 143.592804 -395.707616)
		(width 0.14732)
		(layer "In15.Cu")
		(net "P5E_CPU1_PE2_TX_DP<8>")
	)
	(segment
		(start 147.63369 -239.764062)
		(end 147.633944 -239.764062)
		(width 0.14732)
		(layer "In15.Cu")
		(net "P5E_CPU1_PE2_TX_DP<8>")
	)
	(segment
		(start 145.07972 -309.309008)
		(end 148.76018 -324.803008)
		(width 0.14732)
		(layer "In15.Cu")
		(net "P5E_CPU1_PE2_TX_DP<8>")
	)
	(segment
		(start 129.300478 -222.442278)
		(end 129.309368 -222.437198)
		(width 0.0889)
		(layer "In15.Cu")
		(net "P5E_CPU1_PE2_TX_DP<8>")
	)
	(segment
		(start 147.633944 -239.764062)
		(end 149.236938 -249.976386)
		(width 0.14732)
		(layer "In15.Cu")
		(net "P5E_CPU1_PE2_TX_DP<8>")
	)
	(segment
		(start 132.588254 -216.746074)
		(end 132.598668 -216.739978)
		(width 0.0889)
		(layer "In15.Cu")
		(net "P5E_CPU1_PE2_TX_DP<8>")
	)
	(segment
		(start 133.059678 -215.931242)
		(end 133.068568 -215.926162)
		(width 0.0889)
		(layer "In15.Cu")
		(net "P5E_CPU1_PE2_TX_DP<8>")
	)
	(segment
		(start 130.531362 -218.707716)
		(end 130.531362 -218.692222)
		(width 0.0889)
		(layer "In15.Cu")
		(net "P5E_CPU1_PE2_TX_DP<8>")
	)
	(segment
		(start 129.779014 -219.995496)
		(end 129.779776 -219.994988)
		(width 0.0889)
		(layer "In15.Cu")
		(net "P5E_CPU1_PE2_TX_DP<8>")
	)
	(segment
		(start 149.291548 -251.59462)
		(end 149.345904 -253.2126)
		(width 0.14732)
		(layer "In15.Cu")
		(net "P5E_CPU1_PE2_TX_DP<8>")
	)
	(segment
		(start 143.193262 -396.75689)
		(end 143.03248 -396.828772)
		(width 0.14732)
		(layer "In15.Cu")
		(net "P5E_CPU1_PE2_TX_DP<8>")
	)
	(segment
		(start 142.79372 -397.806164)
		(end 142.632938 -397.878046)
		(width 0.14732)
		(layer "In15.Cu")
		(net "P5E_CPU1_PE2_TX_DP<8>")
	)
	(segment
		(start 130.240278 -219.18676)
		(end 130.249168 -219.18168)
		(width 0.0889)
		(layer "In15.Cu")
		(net "P5E_CPU1_PE2_TX_DP<8>")
	)
	(segment
		(start 133.442964 -215.926162)
		(end 133.457696 -215.934798)
		(width 0.0889)
		(layer "In15.Cu")
		(net "P5E_CPU1_PE2_TX_DP<8>")
	)
	(segment
		(start 134.382764 -215.926162)
		(end 134.397496 -215.934798)
		(width 0.0889)
		(layer "In15.Cu")
		(net "P5E_CPU1_PE2_TX_DP<8>")
	)
	(segment
		(start 143.592804 -395.707616)
		(end 143.432022 -395.779498)
		(width 0.14732)
		(layer "In15.Cu")
		(net "P5E_CPU1_PE2_TX_DP<8>")
	)
	(segment
		(start 127.616966 -224.389442)
		(end 127.77343 -224.118424)
		(width 0.0889)
		(layer "In15.Cu")
		(net "P5E_CPU1_PE2_TX_DP<8>")
	)
	(segment
		(start 138.556746 -216.32164)
		(end 138.556746 -216.381584)
		(width 0.0889)
		(layer "In15.Cu")
		(net "P5E_CPU1_PE2_TX_DP<8>")
	)
	(segment
		(start 131.180078 -217.559128)
		(end 131.188968 -217.554048)
		(width 0.0889)
		(layer "In15.Cu")
		(net "P5E_CPU1_PE2_TX_DP<8>")
	)
	(segment
		(start 157.615128 -345.996006)
		(end 156.972762 -349.643954)
		(width 0.14732)
		(layer "In15.Cu")
		(net "P5E_CPU1_PE2_TX_DP<8>")
	)
	(segment
		(start 143.276574 -396.188184)
		(end 143.34871 -396.348712)
		(width 0.14732)
		(layer "In15.Cu")
		(net "P5E_CPU1_PE2_TX_DP<8>")
	)
	(segment
		(start 129.770124 -221.628462)
		(end 129.779014 -221.623382)
		(width 0.0889)
		(layer "In15.Cu")
		(net "P5E_CPU1_PE2_TX_DP<8>")
	)
	(segment
		(start 141.892274 -400.173698)
		(end 141.892274 -400.563588)
		(width 0.14732)
		(layer "In15.Cu")
		(net "P5E_CPU1_PE2_TX_DP<8>")
	)
	(segment
		(start 138.556746 -216.381584)
		(end 138.57224 -216.397078)
		(width 0.0889)
		(layer "In15.Cu")
		(net "P5E_CPU1_PE2_TX_DP<8>")
	)
	(segment
		(start 136.827768 -215.926162)
		(end 136.83615 -215.921336)
		(width 0.0889)
		(layer "In15.Cu")
		(net "P5E_CPU1_PE2_TX_DP<8>")
	)
	(segment
		(start 143.432022 -395.779498)
		(end 143.276574 -396.188184)
		(width 0.14732)
		(layer "In15.Cu")
		(net "P5E_CPU1_PE2_TX_DP<8>")
	)
	(segment
		(start 138.220196 -215.98509)
		(end 138.556746 -216.32164)
		(width 0.0889)
		(layer "In15.Cu")
		(net "P5E_CPU1_PE2_TX_DP<8>")
	)
	(segment
		(start 148.76018 -324.803008)
		(end 155.198826 -332.298548)
		(width 0.14732)
		(layer "In15.Cu")
		(net "P5E_CPU1_PE2_TX_DP<8>")
	)
	(segment
		(start 141.892274 -400.563588)
		(end 141.597634 -400.858228)
		(width 0.14732)
		(layer "In15.Cu")
		(net "P5E_CPU1_PE2_TX_DP<8>")
	)
	(segment
		(start 143.676116 -395.13891)
		(end 143.748252 -395.299438)
		(width 0.14732)
		(layer "In15.Cu")
		(net "P5E_CPU1_PE2_TX_DP<8>")
	)
	(segment
		(start 149.236938 -249.976386)
		(end 149.291548 -251.59462)
		(width 0.14732)
		(layer "In15.Cu")
		(net "P5E_CPU1_PE2_TX_DP<8>")
	)
	(segment
		(start 136.813036 -215.934798)
		(end 136.827768 -215.926162)
		(width 0.0889)
		(layer "In15.Cu")
		(net "P5E_CPU1_PE2_TX_DP<8>")
	)
	(segment
		(start 129.779776 -219.994988)
		(end 129.78511 -219.99194)
		(width 0.0889)
		(layer "In15.Cu")
		(net "P5E_CPU1_PE2_TX_DP<8>")
	)
	(segment
		(start 143.992092 -394.658596)
		(end 143.831564 -394.730224)
		(width 0.14732)
		(layer "In15.Cu")
		(net "P5E_CPU1_PE2_TX_DP<8>")
	)
	(segment
		(start 142.47749 -398.286732)
		(end 142.549626 -398.44726)
		(width 0.14732)
		(layer "In15.Cu")
		(net "P5E_CPU1_PE2_TX_DP<8>")
	)
	(segment
		(start 129.121916 -222.780098)
		(end 129.121916 -222.761556)
		(width 0.0889)
		(layer "In15.Cu")
		(net "P5E_CPU1_PE2_TX_DP<8>")
	)
	(segment
		(start 131.471416 -217.082878)
		(end 131.471416 -217.0557)
		(width 0.0889)
		(layer "In15.Cu")
		(net "P5E_CPU1_PE2_TX_DP<8>")
	)
	(segment
		(start 138.57224 -216.397078)
		(end 140.985494 -218.810586)
		(width 0.14732)
		(layer "In15.Cu")
		(net "P5E_CPU1_PE2_TX_DP<8>")
	)
	(segment
		(start 142.877032 -397.237458)
		(end 142.949168 -397.397986)
		(width 0.14732)
		(layer "In15.Cu")
		(net "P5E_CPU1_PE2_TX_DP<8>")
	)
	(segment
		(start 128.830578 -223.256348)
		(end 128.839468 -223.251268)
		(width 0.0889)
		(layer "In15.Cu")
		(net "P5E_CPU1_PE2_TX_DP<8>")
	)
	(segment
		(start 143.03248 -396.828772)
		(end 142.877032 -397.237458)
		(width 0.14732)
		(layer "In15.Cu")
		(net "P5E_CPU1_PE2_TX_DP<8>")
	)
	(arc
		(start 137.7823 -215.91778)
		(mid 137.963463 -215.87584)
		(end 138.142472 -215.926162)
		(width 0.0889)
		(layer "In15.Cu")
		(net "P5E_CPU1_PE2_TX_DP<8>")
	)
	(arc
		(start 128.652016 -223.575626)
		(mid 128.699695 -223.392726)
		(end 128.830578 -223.256348)
		(width 0.0889)
		(layer "In15.Cu")
		(net "P5E_CPU1_PE2_TX_DP<8>")
	)
	(arc
		(start 133.068568 -215.926162)
		(mid 133.255766 -215.876019)
		(end 133.442964 -215.926162)
		(width 0.0889)
		(layer "In15.Cu")
		(net "P5E_CPU1_PE2_TX_DP<8>")
	)
	(arc
		(start 138.142472 -215.926162)
		(mid 138.165098 -215.940235)
		(end 138.186668 -215.95588)
		(width 0.0889)
		(layer "In15.Cu")
		(net "P5E_CPU1_PE2_TX_DP<8>")
	)
	(arc
		(start 131.471416 -217.0557)
		(mid 131.523686 -216.873335)
		(end 131.658614 -216.739978)
		(width 0.0889)
		(layer "In15.Cu")
		(net "P5E_CPU1_PE2_TX_DP<8>")
	)
	(arc
		(start 135.887968 -215.926162)
		(mid 136.075166 -215.876019)
		(end 136.262364 -215.926162)
		(width 0.0889)
		(layer "In15.Cu")
		(net "P5E_CPU1_PE2_TX_DP<8>")
	)
	(arc
		(start 138.186668 -215.95588)
		(mid 138.203868 -215.969985)
		(end 138.220196 -215.98509)
		(width 0.0889)
		(layer "In15.Cu")
		(net "P5E_CPU1_PE2_TX_DP<8>")
	)
	(arc
		(start 133.457696 -215.934798)
		(mid 133.734171 -216.002118)
		(end 134.008368 -215.926162)
		(width 0.0889)
		(layer "In15.Cu")
		(net "P5E_CPU1_PE2_TX_DP<8>")
	)
	(arc
		(start 129.78511 -221.619826)
		(mid 129.987697 -221.413475)
		(end 130.061716 -221.133924)
		(width 0.0889)
		(layer "In15.Cu")
		(net "P5E_CPU1_PE2_TX_DP<8>")
	)
	(arc
		(start 129.591562 -221.94774)
		(mid 129.639241 -221.76484)
		(end 129.770124 -221.628462)
		(width 0.0889)
		(layer "In15.Cu")
		(net "P5E_CPU1_PE2_TX_DP<8>")
	)
	(arc
		(start 135.337296 -215.934798)
		(mid 135.613771 -216.002118)
		(end 135.887968 -215.926162)
		(width 0.0889)
		(layer "In15.Cu")
		(net "P5E_CPU1_PE2_TX_DP<8>")
	)
	(arc
		(start 129.779014 -220.644212)
		(mid 129.644081 -220.510858)
		(end 129.591816 -220.32849)
		(width 0.0889)
		(layer "In15.Cu")
		(net "P5E_CPU1_PE2_TX_DP<8>")
	)
	(arc
		(start 128.375664 -224.061528)
		(mid 128.578077 -223.855115)
		(end 128.652016 -223.575626)
		(width 0.0889)
		(layer "In15.Cu")
		(net "P5E_CPU1_PE2_TX_DP<8>")
	)
	(arc
		(start 131.188968 -217.554048)
		(mid 131.391254 -217.355067)
		(end 131.471416 -217.082878)
		(width 0.0889)
		(layer "In15.Cu")
		(net "P5E_CPU1_PE2_TX_DP<8>")
	)
	(arc
		(start 128.839468 -223.251268)
		(mid 129.041754 -223.052287)
		(end 129.121916 -222.780098)
		(width 0.0889)
		(layer "In15.Cu")
		(net "P5E_CPU1_PE2_TX_DP<8>")
	)
	(arc
		(start 129.591816 -220.311218)
		(mid 129.644086 -220.128853)
		(end 129.779014 -219.995496)
		(width 0.0889)
		(layer "In15.Cu")
		(net "P5E_CPU1_PE2_TX_DP<8>")
	)
	(arc
		(start 130.72491 -218.364308)
		(mid 130.927497 -218.157957)
		(end 131.001516 -217.878406)
		(width 0.0889)
		(layer "In15.Cu")
		(net "P5E_CPU1_PE2_TX_DP<8>")
	)
	(arc
		(start 127.882142 -224.10293)
		(mid 128.130153 -224.139395)
		(end 128.369568 -224.065084)
		(width 0.0889)
		(layer "In15.Cu")
		(net "P5E_CPU1_PE2_TX_DP<8>")
	)
	(arc
		(start 130.061716 -219.506038)
		(mid 130.109395 -219.323138)
		(end 130.240278 -219.18676)
		(width 0.0889)
		(layer "In15.Cu")
		(net "P5E_CPU1_PE2_TX_DP<8>")
	)
	(arc
		(start 131.658614 -216.739978)
		(mid 131.845812 -216.689835)
		(end 132.03301 -216.739978)
		(width 0.0889)
		(layer "In15.Cu")
		(net "P5E_CPU1_PE2_TX_DP<8>")
	)
	(arc
		(start 127.86233 -224.094802)
		(mid 127.872197 -224.098961)
		(end 127.882142 -224.10293)
		(width 0.0889)
		(layer "In15.Cu")
		(net "P5E_CPU1_PE2_TX_DP<8>")
	)
	(arc
		(start 134.948168 -215.926162)
		(mid 135.135366 -215.876019)
		(end 135.322564 -215.926162)
		(width 0.0889)
		(layer "In15.Cu")
		(net "P5E_CPU1_PE2_TX_DP<8>")
	)
	(arc
		(start 130.061716 -221.1197)
		(mid 129.982497 -220.845015)
		(end 129.779014 -220.644212)
		(width 0.0889)
		(layer "In15.Cu")
		(net "P5E_CPU1_PE2_TX_DP<8>")
	)
	(arc
		(start 137.202418 -215.926162)
		(mid 137.473151 -216.002176)
		(end 137.746994 -215.938354)
		(width 0.0889)
		(layer "In15.Cu")
		(net "P5E_CPU1_PE2_TX_DP<8>")
	)
	(arc
		(start 129.121916 -222.761556)
		(mid 129.169595 -222.578656)
		(end 129.300478 -222.442278)
		(width 0.0889)
		(layer "In15.Cu")
		(net "P5E_CPU1_PE2_TX_DP<8>")
	)
	(arc
		(start 134.397496 -215.934798)
		(mid 134.673971 -216.002118)
		(end 134.948168 -215.926162)
		(width 0.0889)
		(layer "In15.Cu")
		(net "P5E_CPU1_PE2_TX_DP<8>")
	)
	(arc
		(start 136.83615 -215.921336)
		(mid 137.019912 -215.875936)
		(end 137.202418 -215.926162)
		(width 0.0889)
		(layer "In15.Cu")
		(net "P5E_CPU1_PE2_TX_DP<8>")
	)
	(arc
		(start 129.78511 -219.99194)
		(mid 129.987697 -219.785589)
		(end 130.061716 -219.506038)
		(width 0.0889)
		(layer "In15.Cu")
		(net "P5E_CPU1_PE2_TX_DP<8>")
	)
	(arc
		(start 130.249168 -219.18168)
		(mid 130.451991 -218.981449)
		(end 130.531362 -218.707716)
		(width 0.0889)
		(layer "In15.Cu")
		(net "P5E_CPU1_PE2_TX_DP<8>")
	)
	(arc
		(start 136.262364 -215.926162)
		(mid 136.536563 -216.001997)
		(end 136.813036 -215.934798)
		(width 0.0889)
		(layer "In15.Cu")
		(net "P5E_CPU1_PE2_TX_DP<8>")
	)
	(arc
		(start 131.001516 -217.878406)
		(mid 131.049195 -217.695506)
		(end 131.180078 -217.559128)
		(width 0.0889)
		(layer "In15.Cu")
		(net "P5E_CPU1_PE2_TX_DP<8>")
	)
	(arc
		(start 134.008368 -215.926162)
		(mid 134.195566 -215.876019)
		(end 134.382764 -215.926162)
		(width 0.0889)
		(layer "In15.Cu")
		(net "P5E_CPU1_PE2_TX_DP<8>")
	)
	(arc
		(start 132.598668 -216.739978)
		(mid 132.803003 -216.537373)
		(end 132.881116 -216.260426)
		(width 0.0889)
		(layer "In15.Cu")
		(net "P5E_CPU1_PE2_TX_DP<8>")
	)
	(arc
		(start 130.531362 -218.692222)
		(mid 130.579041 -218.509322)
		(end 130.709924 -218.372944)
		(width 0.0889)
		(layer "In15.Cu")
		(net "P5E_CPU1_PE2_TX_DP<8>")
	)
	(arc
		(start 129.309368 -222.437198)
		(mid 129.512191 -222.236967)
		(end 129.591562 -221.963234)
		(width 0.0889)
		(layer "In15.Cu")
		(net "P5E_CPU1_PE2_TX_DP<8>")
	)
	(arc
		(start 132.881116 -216.25052)
		(mid 132.928795 -216.06762)
		(end 133.059678 -215.931242)
		(width 0.0889)
		(layer "In15.Cu")
		(net "P5E_CPU1_PE2_TX_DP<8>")
	)
	(arc
		(start 132.03301 -216.739978)
		(mid 132.309823 -216.815848)
		(end 132.588254 -216.746074)
		(width 0.0889)
		(layer "In15.Cu")
		(net "P5E_CPU1_PE2_TX_DP<8>")
	)
	(segment
		(start 144.640046 -402.104352)
		(end 144.635474 -402.104352)
		(width 0.13208)
		(layer "F.Cu")
		(net "P5E_CPU1_PE2_TX_DP<7>")
	)
	(segment
		(start 127.147066 -225.739198)
		(end 127.146812 -225.738944)
		(width 0.13208)
		(layer "F.Cu")
		(net "P5E_CPU1_PE2_TX_DP<7>")
	)
	(segment
		(start 144.966436 -401.16379)
		(end 144.966436 -401.777962)
		(width 0.13208)
		(layer "F.Cu")
		(net "P5E_CPU1_PE2_TX_DP<7>")
	)
	(segment
		(start 144.660874 -400.858228)
		(end 144.966436 -401.16379)
		(width 0.13208)
		(layer "F.Cu")
		(net "P5E_CPU1_PE2_TX_DP<7>")
	)
	(segment
		(start 144.966436 -401.777962)
		(end 144.640046 -402.104352)
		(width 0.13208)
		(layer "F.Cu")
		(net "P5E_CPU1_PE2_TX_DP<7>")
	)
	(segment
		(start 127.146812 -225.738944)
		(end 127.146812 -225.203258)
		(width 0.13208)
		(layer "F.Cu")
		(net "P5E_CPU1_PE2_TX_DP<7>")
	)
	(segment
		(start 148.259292 -237.522766)
		(end 150.143464 -249.23877)
		(width 0.14732)
		(layer "In15.Cu")
		(net "P5E_CPU1_PE2_TX_DP<7>")
	)
	(segment
		(start 145.654268 -397.110458)
		(end 145.517362 -397.525494)
		(width 0.14732)
		(layer "In15.Cu")
		(net "P5E_CPU1_PE2_TX_DP<7>")
	)
	(segment
		(start 147.23364 -392.72464)
		(end 147.076414 -392.803634)
		(width 0.14732)
		(layer "In15.Cu")
		(net "P5E_CPU1_PE2_TX_DP<7>")
	)
	(segment
		(start 146.04238 -309.215028)
		(end 149.60854 -324.343268)
		(width 0.14732)
		(layer "In15.Cu")
		(net "P5E_CPU1_PE2_TX_DP<7>")
	)
	(segment
		(start 128.839468 -220.644212)
		(end 128.830578 -220.639132)
		(width 0.0889)
		(layer "In15.Cu")
		(net "P5E_CPU1_PE2_TX_DP<7>")
	)
	(segment
		(start 126.990348 -224.93224)
		(end 127.014478 -224.843086)
		(width 0.0889)
		(layer "In15.Cu")
		(net "P5E_CPU1_PE2_TX_DP<7>")
	)
	(segment
		(start 129.121916 -219.515944)
		(end 129.121916 -219.506038)
		(width 0.0889)
		(layer "In15.Cu")
		(net "P5E_CPU1_PE2_TX_DP<7>")
	)
	(segment
		(start 146.573494 -394.326618)
		(end 146.652742 -394.483844)
		(width 0.14732)
		(layer "In15.Cu")
		(net "P5E_CPU1_PE2_TX_DP<7>")
	)
	(segment
		(start 132.589524 -215.117426)
		(end 132.598414 -215.112346)
		(width 0.0889)
		(layer "In15.Cu")
		(net "P5E_CPU1_PE2_TX_DP<7>")
	)
	(segment
		(start 144.955514 -399.624042)
		(end 144.955514 -400.563588)
		(width 0.14732)
		(layer "In15.Cu")
		(net "P5E_CPU1_PE2_TX_DP<7>")
	)
	(segment
		(start 157.925008 -350.115886)
		(end 156.709364 -364.028736)
		(width 0.14732)
		(layer "In15.Cu")
		(net "P5E_CPU1_PE2_TX_DP<7>")
	)
	(segment
		(start 146.300698 -395.550136)
		(end 146.163792 -395.964918)
		(width 0.14732)
		(layer "In15.Cu")
		(net "P5E_CPU1_PE2_TX_DP<7>")
	)
	(segment
		(start 128.360678 -222.442278)
		(end 128.369568 -222.437198)
		(width 0.0889)
		(layer "In15.Cu")
		(net "P5E_CPU1_PE2_TX_DP<7>")
	)
	(segment
		(start 146.86788 -393.832334)
		(end 146.7104 -393.911582)
		(width 0.14732)
		(layer "In15.Cu")
		(net "P5E_CPU1_PE2_TX_DP<7>")
	)
	(segment
		(start 139.666218 -215.563704)
		(end 145.662142 -223.35871)
		(width 0.14732)
		(layer "In15.Cu")
		(net "P5E_CPU1_PE2_TX_DP<7>")
	)
	(segment
		(start 130.623564 -215.926162)
		(end 130.638296 -215.934798)
		(width 0.0889)
		(layer "In15.Cu")
		(net "P5E_CPU1_PE2_TX_DP<7>")
	)
	(segment
		(start 145.596356 -397.68272)
		(end 144.955514 -399.624042)
		(width 0.14732)
		(layer "In15.Cu")
		(net "P5E_CPU1_PE2_TX_DP<7>")
	)
	(segment
		(start 150.278338 -253.24562)
		(end 150.278338 -253.245874)
		(width 0.14732)
		(layer "In15.Cu")
		(net "P5E_CPU1_PE2_TX_DP<7>")
	)
	(segment
		(start 130.061716 -217.878406)
		(end 130.061716 -217.864182)
		(width 0.0889)
		(layer "In15.Cu")
		(net "P5E_CPU1_PE2_TX_DP<7>")
	)
	(segment
		(start 147.018502 -393.375896)
		(end 146.86788 -393.832334)
		(width 0.14732)
		(layer "In15.Cu")
		(net "P5E_CPU1_PE2_TX_DP<7>")
	)
	(segment
		(start 146.358356 -394.977874)
		(end 146.22145 -395.39291)
		(width 0.14732)
		(layer "In15.Cu")
		(net "P5E_CPU1_PE2_TX_DP<7>")
	)
	(segment
		(start 146.515836 -394.898626)
		(end 146.358356 -394.977874)
		(width 0.14732)
		(layer "In15.Cu")
		(net "P5E_CPU1_PE2_TX_DP<7>")
	)
	(segment
		(start 128.838706 -219.996004)
		(end 128.839468 -219.995496)
		(width 0.0889)
		(layer "In15.Cu")
		(net "P5E_CPU1_PE2_TX_DP<7>")
	)
	(segment
		(start 129.591816 -217.072972)
		(end 129.591816 -217.0557)
		(width 0.0889)
		(layer "In15.Cu")
		(net "P5E_CPU1_PE2_TX_DP<7>")
	)
	(segment
		(start 132.880608 -214.644732)
		(end 132.880354 -214.622634)
		(width 0.0889)
		(layer "In15.Cu")
		(net "P5E_CPU1_PE2_TX_DP<7>")
	)
	(segment
		(start 130.240278 -215.931242)
		(end 130.249168 -215.926162)
		(width 0.0889)
		(layer "In15.Cu")
		(net "P5E_CPU1_PE2_TX_DP<7>")
	)
	(segment
		(start 156.182568 -332.007972)
		(end 158.650432 -345.996514)
		(width 0.14732)
		(layer "In15.Cu")
		(net "P5E_CPU1_PE2_TX_DP<7>")
	)
	(segment
		(start 150.278338 -253.245874)
		(end 146.04238 -309.215028)
		(width 0.14732)
		(layer "In15.Cu")
		(net "P5E_CPU1_PE2_TX_DP<7>")
	)
	(segment
		(start 129.779014 -218.367864)
		(end 129.78511 -218.364308)
		(width 0.0889)
		(layer "In15.Cu")
		(net "P5E_CPU1_PE2_TX_DP<7>")
	)
	(segment
		(start 133.064758 -214.2617)
		(end 133.090412 -214.248238)
		(width 0.0889)
		(layer "In15.Cu")
		(net "P5E_CPU1_PE2_TX_DP<7>")
	)
	(segment
		(start 144.955514 -400.563588)
		(end 144.660874 -400.858228)
		(width 0.14732)
		(layer "In15.Cu")
		(net "P5E_CPU1_PE2_TX_DP<7>")
	)
	(segment
		(start 156.709364 -364.028736)
		(end 147.23364 -392.72464)
		(width 0.14732)
		(layer "In15.Cu")
		(net "P5E_CPU1_PE2_TX_DP<7>")
	)
	(segment
		(start 127.146812 -225.203258)
		(end 126.990348 -224.93224)
		(width 0.0889)
		(layer "In15.Cu")
		(net "P5E_CPU1_PE2_TX_DP<7>")
	)
	(segment
		(start 146.006312 -396.044166)
		(end 145.869406 -396.459202)
		(width 0.14732)
		(layer "In15.Cu")
		(net "P5E_CPU1_PE2_TX_DP<7>")
	)
	(segment
		(start 146.163792 -395.964918)
		(end 146.006312 -396.044166)
		(width 0.14732)
		(layer "In15.Cu")
		(net "P5E_CPU1_PE2_TX_DP<7>")
	)
	(segment
		(start 145.869406 -396.459202)
		(end 145.948654 -396.616428)
		(width 0.14732)
		(layer "In15.Cu")
		(net "P5E_CPU1_PE2_TX_DP<7>")
	)
	(segment
		(start 129.591562 -218.707716)
		(end 129.591562 -218.692222)
		(width 0.0889)
		(layer "In15.Cu")
		(net "P5E_CPU1_PE2_TX_DP<7>")
	)
	(segment
		(start 132.410962 -215.452198)
		(end 132.410962 -215.436704)
		(width 0.0889)
		(layer "In15.Cu")
		(net "P5E_CPU1_PE2_TX_DP<7>")
	)
	(segment
		(start 133.549136 -213.789514)
		(end 133.81609 -213.789514)
		(width 0.0889)
		(layer "In15.Cu")
		(net "P5E_CPU1_PE2_TX_DP<7>")
	)
	(segment
		(start 149.60854 -324.343268)
		(end 156.182568 -332.007972)
		(width 0.14732)
		(layer "In15.Cu")
		(net "P5E_CPU1_PE2_TX_DP<7>")
	)
	(segment
		(start 146.22145 -395.39291)
		(end 146.300698 -395.550136)
		(width 0.14732)
		(layer "In15.Cu")
		(net "P5E_CPU1_PE2_TX_DP<7>")
	)
	(segment
		(start 148.259292 -237.52302)
		(end 148.259292 -237.522766)
		(width 0.14732)
		(layer "In15.Cu")
		(net "P5E_CPU1_PE2_TX_DP<7>")
	)
	(segment
		(start 146.372326 -225.789998)
		(end 148.259292 -237.52302)
		(width 0.14732)
		(layer "In15.Cu")
		(net "P5E_CPU1_PE2_TX_DP<7>")
	)
	(segment
		(start 132.880354 -214.622634)
		(end 132.880354 -214.461344)
		(width 0.0889)
		(layer "In15.Cu")
		(net "P5E_CPU1_PE2_TX_DP<7>")
	)
	(segment
		(start 129.779776 -216.73947)
		(end 129.78511 -216.736422)
		(width 0.0889)
		(layer "In15.Cu")
		(net "P5E_CPU1_PE2_TX_DP<7>")
	)
	(segment
		(start 129.121916 -221.133924)
		(end 129.121916 -221.115382)
		(width 0.0889)
		(layer "In15.Cu")
		(net "P5E_CPU1_PE2_TX_DP<7>")
	)
	(segment
		(start 133.090412 -214.248238)
		(end 133.549136 -213.789514)
		(width 0.0889)
		(layer "In15.Cu")
		(net "P5E_CPU1_PE2_TX_DP<7>")
	)
	(segment
		(start 146.7104 -393.911582)
		(end 146.573494 -394.326618)
		(width 0.14732)
		(layer "In15.Cu")
		(net "P5E_CPU1_PE2_TX_DP<7>")
	)
	(segment
		(start 145.811748 -397.03121)
		(end 145.654268 -397.110458)
		(width 0.14732)
		(layer "In15.Cu")
		(net "P5E_CPU1_PE2_TX_DP<7>")
	)
	(segment
		(start 133.880098 -213.831424)
		(end 135.485632 -213.831424)
		(width 0.14732)
		(layer "In15.Cu")
		(net "P5E_CPU1_PE2_TX_DP<7>")
	)
	(segment
		(start 128.839214 -221.623382)
		(end 128.84531 -221.619826)
		(width 0.0889)
		(layer "In15.Cu")
		(net "P5E_CPU1_PE2_TX_DP<7>")
	)
	(segment
		(start 129.770124 -218.372944)
		(end 129.779014 -218.367864)
		(width 0.0889)
		(layer "In15.Cu")
		(net "P5E_CPU1_PE2_TX_DP<7>")
	)
	(segment
		(start 128.830324 -221.628462)
		(end 128.839214 -221.623382)
		(width 0.0889)
		(layer "In15.Cu")
		(net "P5E_CPU1_PE2_TX_DP<7>")
	)
	(segment
		(start 128.830578 -220.000576)
		(end 128.838706 -219.996004)
		(width 0.0889)
		(layer "In15.Cu")
		(net "P5E_CPU1_PE2_TX_DP<7>")
	)
	(segment
		(start 150.143464 -249.23877)
		(end 150.278338 -253.24562)
		(width 0.14732)
		(layer "In15.Cu")
		(net "P5E_CPU1_PE2_TX_DP<7>")
	)
	(segment
		(start 145.662142 -223.35871)
		(end 146.372326 -225.789998)
		(width 0.14732)
		(layer "In15.Cu")
		(net "P5E_CPU1_PE2_TX_DP<7>")
	)
	(segment
		(start 135.485632 -213.831424)
		(end 139.666218 -215.563704)
		(width 0.14732)
		(layer "In15.Cu")
		(net "P5E_CPU1_PE2_TX_DP<7>")
	)
	(segment
		(start 129.779014 -216.739978)
		(end 129.779776 -216.73947)
		(width 0.0889)
		(layer "In15.Cu")
		(net "P5E_CPU1_PE2_TX_DP<7>")
	)
	(segment
		(start 128.182116 -222.77578)
		(end 128.182116 -222.761556)
		(width 0.0889)
		(layer "In15.Cu")
		(net "P5E_CPU1_PE2_TX_DP<7>")
	)
	(segment
		(start 133.81609 -213.789514)
		(end 133.858 -213.831424)
		(width 0.0889)
		(layer "In15.Cu")
		(net "P5E_CPU1_PE2_TX_DP<7>")
	)
	(segment
		(start 128.651762 -221.963234)
		(end 128.651762 -221.94774)
		(width 0.0889)
		(layer "In15.Cu")
		(net "P5E_CPU1_PE2_TX_DP<7>")
	)
	(segment
		(start 146.652742 -394.483844)
		(end 146.515836 -394.898626)
		(width 0.14732)
		(layer "In15.Cu")
		(net "P5E_CPU1_PE2_TX_DP<7>")
	)
	(segment
		(start 129.300478 -219.18676)
		(end 129.309368 -219.18168)
		(width 0.0889)
		(layer "In15.Cu")
		(net "P5E_CPU1_PE2_TX_DP<7>")
	)
	(segment
		(start 145.517362 -397.525494)
		(end 145.596356 -397.68272)
		(width 0.14732)
		(layer "In15.Cu")
		(net "P5E_CPU1_PE2_TX_DP<7>")
	)
	(segment
		(start 131.563364 -215.926162)
		(end 131.578096 -215.934798)
		(width 0.0889)
		(layer "In15.Cu")
		(net "P5E_CPU1_PE2_TX_DP<7>")
	)
	(segment
		(start 147.076414 -392.803634)
		(end 146.939254 -393.21867)
		(width 0.14732)
		(layer "In15.Cu")
		(net "P5E_CPU1_PE2_TX_DP<7>")
	)
	(segment
		(start 127.712216 -223.585532)
		(end 127.712216 -223.56699)
		(width 0.0889)
		(layer "In15.Cu")
		(net "P5E_CPU1_PE2_TX_DP<7>")
	)
	(segment
		(start 146.939254 -393.21867)
		(end 147.018502 -393.375896)
		(width 0.14732)
		(layer "In15.Cu")
		(net "P5E_CPU1_PE2_TX_DP<7>")
	)
	(segment
		(start 133.858 -213.831424)
		(end 133.880098 -213.831424)
		(width 0.0889)
		(layer "In15.Cu")
		(net "P5E_CPU1_PE2_TX_DP<7>")
	)
	(segment
		(start 158.650432 -345.996514)
		(end 157.925008 -350.115886)
		(width 0.14732)
		(layer "In15.Cu")
		(net "P5E_CPU1_PE2_TX_DP<7>")
	)
	(segment
		(start 127.420878 -224.070164)
		(end 127.429768 -224.065084)
		(width 0.0889)
		(layer "In15.Cu")
		(net "P5E_CPU1_PE2_TX_DP<7>")
	)
	(segment
		(start 145.948654 -396.616428)
		(end 145.811748 -397.03121)
		(width 0.14732)
		(layer "In15.Cu")
		(net "P5E_CPU1_PE2_TX_DP<7>")
	)
	(arc
		(start 127.899414 -223.251268)
		(mid 128.102895 -223.050464)
		(end 128.182116 -222.77578)
		(width 0.0889)
		(layer "In15.Cu")
		(net "P5E_CPU1_PE2_TX_DP<7>")
	)
	(arc
		(start 132.880354 -214.461344)
		(mid 132.955448 -214.34572)
		(end 133.064758 -214.2617)
		(width 0.0889)
		(layer "In15.Cu")
		(net "P5E_CPU1_PE2_TX_DP<7>")
	)
	(arc
		(start 129.121916 -219.506038)
		(mid 129.169595 -219.323138)
		(end 129.300478 -219.18676)
		(width 0.0889)
		(layer "In15.Cu")
		(net "P5E_CPU1_PE2_TX_DP<7>")
	)
	(arc
		(start 130.249168 -215.926162)
		(mid 130.436366 -215.876019)
		(end 130.623564 -215.926162)
		(width 0.0889)
		(layer "In15.Cu")
		(net "P5E_CPU1_PE2_TX_DP<7>")
	)
	(arc
		(start 128.830578 -220.639132)
		(mid 128.699664 -220.502772)
		(end 128.652016 -220.319854)
		(width 0.0889)
		(layer "In15.Cu")
		(net "P5E_CPU1_PE2_TX_DP<7>")
	)
	(arc
		(start 128.651762 -221.94774)
		(mid 128.699441 -221.76484)
		(end 128.830324 -221.628462)
		(width 0.0889)
		(layer "In15.Cu")
		(net "P5E_CPU1_PE2_TX_DP<7>")
	)
	(arc
		(start 129.591562 -218.692222)
		(mid 129.639241 -218.509322)
		(end 129.770124 -218.372944)
		(width 0.0889)
		(layer "In15.Cu")
		(net "P5E_CPU1_PE2_TX_DP<7>")
	)
	(arc
		(start 128.839468 -219.995496)
		(mid 129.043803 -219.792891)
		(end 129.121916 -219.515944)
		(width 0.0889)
		(layer "In15.Cu")
		(net "P5E_CPU1_PE2_TX_DP<7>")
	)
	(arc
		(start 127.014478 -224.843086)
		(mid 127.02305 -224.836564)
		(end 127.031496 -224.829878)
		(width 0.0889)
		(layer "In15.Cu")
		(net "P5E_CPU1_PE2_TX_DP<7>")
	)
	(arc
		(start 129.78511 -218.364308)
		(mid 129.987697 -218.157957)
		(end 130.061716 -217.878406)
		(width 0.0889)
		(layer "In15.Cu")
		(net "P5E_CPU1_PE2_TX_DP<7>")
	)
	(arc
		(start 130.638296 -215.934798)
		(mid 130.914771 -216.002118)
		(end 131.188968 -215.926162)
		(width 0.0889)
		(layer "In15.Cu")
		(net "P5E_CPU1_PE2_TX_DP<7>")
	)
	(arc
		(start 127.712216 -223.56699)
		(mid 127.764486 -223.384625)
		(end 127.899414 -223.251268)
		(width 0.0889)
		(layer "In15.Cu")
		(net "P5E_CPU1_PE2_TX_DP<7>")
	)
	(arc
		(start 130.061716 -216.25052)
		(mid 130.109395 -216.06762)
		(end 130.240278 -215.931242)
		(width 0.0889)
		(layer "In15.Cu")
		(net "P5E_CPU1_PE2_TX_DP<7>")
	)
	(arc
		(start 128.652016 -220.319854)
		(mid 128.699695 -220.136954)
		(end 128.830578 -220.000576)
		(width 0.0889)
		(layer "In15.Cu")
		(net "P5E_CPU1_PE2_TX_DP<7>")
	)
	(arc
		(start 130.061716 -217.864182)
		(mid 129.982497 -217.589497)
		(end 129.779014 -217.388694)
		(width 0.0889)
		(layer "In15.Cu")
		(net "P5E_CPU1_PE2_TX_DP<7>")
	)
	(arc
		(start 127.429768 -224.065084)
		(mid 127.634103 -223.862479)
		(end 127.712216 -223.585532)
		(width 0.0889)
		(layer "In15.Cu")
		(net "P5E_CPU1_PE2_TX_DP<7>")
	)
	(arc
		(start 127.031496 -224.829878)
		(mid 127.186894 -224.633597)
		(end 127.242316 -224.389442)
		(width 0.0889)
		(layer "In15.Cu")
		(net "P5E_CPU1_PE2_TX_DP<7>")
	)
	(arc
		(start 132.598414 -215.112346)
		(mid 132.799696 -214.914859)
		(end 132.880608 -214.644732)
		(width 0.0889)
		(layer "In15.Cu")
		(net "P5E_CPU1_PE2_TX_DP<7>")
	)
	(arc
		(start 129.121916 -221.115382)
		(mid 129.041754 -220.843193)
		(end 128.839468 -220.644212)
		(width 0.0889)
		(layer "In15.Cu")
		(net "P5E_CPU1_PE2_TX_DP<7>")
	)
	(arc
		(start 131.578096 -215.934798)
		(mid 131.854571 -216.002118)
		(end 132.128768 -215.926162)
		(width 0.0889)
		(layer "In15.Cu")
		(net "P5E_CPU1_PE2_TX_DP<7>")
	)
	(arc
		(start 128.84531 -221.619826)
		(mid 129.047897 -221.413475)
		(end 129.121916 -221.133924)
		(width 0.0889)
		(layer "In15.Cu")
		(net "P5E_CPU1_PE2_TX_DP<7>")
	)
	(arc
		(start 132.128768 -215.926162)
		(mid 132.331591 -215.725931)
		(end 132.410962 -215.452198)
		(width 0.0889)
		(layer "In15.Cu")
		(net "P5E_CPU1_PE2_TX_DP<7>")
	)
	(arc
		(start 129.309368 -219.18168)
		(mid 129.512191 -218.981449)
		(end 129.591562 -218.707716)
		(width 0.0889)
		(layer "In15.Cu")
		(net "P5E_CPU1_PE2_TX_DP<7>")
	)
	(arc
		(start 129.78511 -216.736422)
		(mid 129.987697 -216.530071)
		(end 130.061716 -216.25052)
		(width 0.0889)
		(layer "In15.Cu")
		(net "P5E_CPU1_PE2_TX_DP<7>")
	)
	(arc
		(start 127.242316 -224.389442)
		(mid 127.289995 -224.206542)
		(end 127.420878 -224.070164)
		(width 0.0889)
		(layer "In15.Cu")
		(net "P5E_CPU1_PE2_TX_DP<7>")
	)
	(arc
		(start 128.182116 -222.761556)
		(mid 128.229795 -222.578656)
		(end 128.360678 -222.442278)
		(width 0.0889)
		(layer "In15.Cu")
		(net "P5E_CPU1_PE2_TX_DP<7>")
	)
	(arc
		(start 131.188968 -215.926162)
		(mid 131.376166 -215.876019)
		(end 131.563364 -215.926162)
		(width 0.0889)
		(layer "In15.Cu")
		(net "P5E_CPU1_PE2_TX_DP<7>")
	)
	(arc
		(start 128.369568 -222.437198)
		(mid 128.572391 -222.236967)
		(end 128.651762 -221.963234)
		(width 0.0889)
		(layer "In15.Cu")
		(net "P5E_CPU1_PE2_TX_DP<7>")
	)
	(arc
		(start 132.410962 -215.436704)
		(mid 132.411014 -215.429337)
		(end 132.411216 -215.421972)
		(width 0.0889)
		(layer "In15.Cu")
		(net "P5E_CPU1_PE2_TX_DP<7>")
	)
	(arc
		(start 129.591816 -217.0557)
		(mid 129.644086 -216.873335)
		(end 129.779014 -216.739978)
		(width 0.0889)
		(layer "In15.Cu")
		(net "P5E_CPU1_PE2_TX_DP<7>")
	)
	(arc
		(start 132.411216 -215.421972)
		(mid 132.46227 -215.247392)
		(end 132.589524 -215.117426)
		(width 0.0889)
		(layer "In15.Cu")
		(net "P5E_CPU1_PE2_TX_DP<7>")
	)
	(arc
		(start 129.779014 -217.388694)
		(mid 129.644081 -217.25534)
		(end 129.591816 -217.072972)
		(width 0.0889)
		(layer "In15.Cu")
		(net "P5E_CPU1_PE2_TX_DP<7>")
	)
	(segment
		(start 125.737112 -224.389696)
		(end 125.737366 -224.389442)
		(width 0.13208)
		(layer "F.Cu")
		(net "P5E_CPU1_PE2_TX_DP<6>")
	)
	(segment
		(start 148.029676 -401.777962)
		(end 147.703286 -402.104352)
		(width 0.13208)
		(layer "F.Cu")
		(net "P5E_CPU1_PE2_TX_DP<6>")
	)
	(segment
		(start 125.737112 -224.925382)
		(end 125.737112 -224.389696)
		(width 0.13208)
		(layer "F.Cu")
		(net "P5E_CPU1_PE2_TX_DP<6>")
	)
	(segment
		(start 147.724114 -400.858228)
		(end 148.029676 -401.16379)
		(width 0.13208)
		(layer "F.Cu")
		(net "P5E_CPU1_PE2_TX_DP<6>")
	)
	(segment
		(start 147.703286 -402.104352)
		(end 147.698714 -402.104352)
		(width 0.13208)
		(layer "F.Cu")
		(net "P5E_CPU1_PE2_TX_DP<6>")
	)
	(segment
		(start 148.029676 -401.16379)
		(end 148.029676 -401.777962)
		(width 0.13208)
		(layer "F.Cu")
		(net "P5E_CPU1_PE2_TX_DP<6>")
	)
	(segment
		(start 127.711962 -221.963234)
		(end 127.711962 -221.94774)
		(width 0.0889)
		(layer "In15.Cu")
		(net "P5E_CPU1_PE2_TX_DP<6>")
	)
	(segment
		(start 159.055054 -349.118682)
		(end 157.766512 -363.857794)
		(width 0.14732)
		(layer "In15.Cu")
		(net "P5E_CPU1_PE2_TX_DP<6>")
	)
	(segment
		(start 128.182116 -221.133924)
		(end 128.182116 -221.1197)
		(width 0.0889)
		(layer "In15.Cu")
		(net "P5E_CPU1_PE2_TX_DP<6>")
	)
	(segment
		(start 147.324826 -225.59264)
		(end 151.076406 -248.92)
		(width 0.14732)
		(layer "In15.Cu")
		(net "P5E_CPU1_PE2_TX_DP<6>")
	)
	(segment
		(start 129.770124 -215.117426)
		(end 129.779014 -215.112346)
		(width 0.0889)
		(layer "In15.Cu")
		(net "P5E_CPU1_PE2_TX_DP<6>")
	)
	(segment
		(start 151.224996 -253.339854)
		(end 151.224996 -253.340108)
		(width 0.14732)
		(layer "In15.Cu")
		(net "P5E_CPU1_PE2_TX_DP<6>")
	)
	(segment
		(start 148.719794 -396.616936)
		(end 148.80717 -396.769844)
		(width 0.14732)
		(layer "In15.Cu")
		(net "P5E_CPU1_PE2_TX_DP<6>")
	)
	(segment
		(start 159.604964 -345.996768)
		(end 159.055054 -349.118682)
		(width 0.14732)
		(layer "In15.Cu")
		(net "P5E_CPU1_PE2_TX_DP<6>")
	)
	(segment
		(start 127.899414 -219.995496)
		(end 127.900176 -219.994988)
		(width 0.0889)
		(layer "In15.Cu")
		(net "P5E_CPU1_PE2_TX_DP<6>")
	)
	(segment
		(start 146.469608 -222.659194)
		(end 147.324826 -225.59264)
		(width 0.14732)
		(layer "In15.Cu")
		(net "P5E_CPU1_PE2_TX_DP<6>")
	)
	(segment
		(start 129.591562 -215.452198)
		(end 129.591562 -215.436704)
		(width 0.0889)
		(layer "In15.Cu")
		(net "P5E_CPU1_PE2_TX_DP<6>")
	)
	(segment
		(start 151.076406 -248.92)
		(end 151.224996 -253.339854)
		(width 0.14732)
		(layer "In15.Cu")
		(net "P5E_CPU1_PE2_TX_DP<6>")
	)
	(segment
		(start 126.489968 -224.065084)
		(end 126.496064 -224.061528)
		(width 0.0889)
		(layer "In15.Cu")
		(net "P5E_CPU1_PE2_TX_DP<6>")
	)
	(segment
		(start 129.300478 -215.931242)
		(end 129.309368 -215.926162)
		(width 0.0889)
		(layer "In15.Cu")
		(net "P5E_CPU1_PE2_TX_DP<6>")
	)
	(segment
		(start 148.834602 -396.195296)
		(end 148.719794 -396.616936)
		(width 0.14732)
		(layer "In15.Cu")
		(net "P5E_CPU1_PE2_TX_DP<6>")
	)
	(segment
		(start 131.687824 -212.863684)
		(end 135.724138 -212.863684)
		(width 0.14732)
		(layer "In15.Cu")
		(net "P5E_CPU1_PE2_TX_DP<6>")
	)
	(segment
		(start 131.001008 -214.644732)
		(end 131.001008 -214.461852)
		(width 0.0889)
		(layer "In15.Cu")
		(net "P5E_CPU1_PE2_TX_DP<6>")
	)
	(segment
		(start 141.880336 -216.588848)
		(end 141.85646 -216.75979)
		(width 0.14732)
		(layer "In15.Cu")
		(net "P5E_CPU1_PE2_TX_DP<6>")
	)
	(segment
		(start 127.420878 -222.442278)
		(end 127.429768 -222.437198)
		(width 0.0889)
		(layer "In15.Cu")
		(net "P5E_CPU1_PE2_TX_DP<6>")
	)
	(segment
		(start 129.121916 -217.878406)
		(end 129.121916 -217.859864)
		(width 0.0889)
		(layer "In15.Cu")
		(net "P5E_CPU1_PE2_TX_DP<6>")
	)
	(segment
		(start 131.513072 -213.269068)
		(end 131.513072 -213.24697)
		(width 0.0889)
		(layer "In15.Cu")
		(net "P5E_CPU1_PE2_TX_DP<6>")
	)
	(segment
		(start 141.85646 -216.75979)
		(end 142.120112 -217.108532)
		(width 0.14732)
		(layer "In15.Cu")
		(net "P5E_CPU1_PE2_TX_DP<6>")
	)
	(segment
		(start 148.4249 -397.7005)
		(end 148.512276 -397.853154)
		(width 0.14732)
		(layer "In15.Cu")
		(net "P5E_CPU1_PE2_TX_DP<6>")
	)
	(segment
		(start 131.513072 -213.24697)
		(end 131.513072 -213.038436)
		(width 0.14732)
		(layer "In15.Cu")
		(net "P5E_CPU1_PE2_TX_DP<6>")
	)
	(segment
		(start 148.018754 -400.563588)
		(end 147.724114 -400.858228)
		(width 0.14732)
		(layer "In15.Cu")
		(net "P5E_CPU1_PE2_TX_DP<6>")
	)
	(segment
		(start 149.102064 -395.686534)
		(end 148.98751 -396.10792)
		(width 0.14732)
		(layer "In15.Cu")
		(net "P5E_CPU1_PE2_TX_DP<6>")
	)
	(segment
		(start 127.900176 -219.994988)
		(end 127.90551 -219.99194)
		(width 0.0889)
		(layer "In15.Cu")
		(net "P5E_CPU1_PE2_TX_DP<6>")
	)
	(segment
		(start 157.058868 -331.560932)
		(end 159.604964 -345.996768)
		(width 0.14732)
		(layer "In15.Cu")
		(net "P5E_CPU1_PE2_TX_DP<6>")
	)
	(segment
		(start 128.839214 -218.367864)
		(end 128.84531 -218.364308)
		(width 0.0889)
		(layer "In15.Cu")
		(net "P5E_CPU1_PE2_TX_DP<6>")
	)
	(segment
		(start 125.737366 -224.389442)
		(end 125.89383 -224.118424)
		(width 0.0889)
		(layer "In15.Cu")
		(net "P5E_CPU1_PE2_TX_DP<6>")
	)
	(segment
		(start 131.471416 -213.929468)
		(end 131.471416 -213.92896)
		(width 0.0889)
		(layer "In15.Cu")
		(net "P5E_CPU1_PE2_TX_DP<6>")
	)
	(segment
		(start 146.9898 -309.095648)
		(end 150.4442 -323.835268)
		(width 0.14732)
		(layer "In15.Cu")
		(net "P5E_CPU1_PE2_TX_DP<6>")
	)
	(segment
		(start 128.838706 -216.740486)
		(end 128.839468 -216.739978)
		(width 0.0889)
		(layer "In15.Cu")
		(net "P5E_CPU1_PE2_TX_DP<6>")
	)
	(segment
		(start 128.651762 -218.707716)
		(end 128.651762 -218.692222)
		(width 0.0889)
		(layer "In15.Cu")
		(net "P5E_CPU1_PE2_TX_DP<6>")
	)
	(segment
		(start 148.512276 -397.853154)
		(end 148.018754 -399.666206)
		(width 0.14732)
		(layer "In15.Cu")
		(net "P5E_CPU1_PE2_TX_DP<6>")
	)
	(segment
		(start 127.712216 -220.32849)
		(end 127.712216 -220.311218)
		(width 0.0889)
		(layer "In15.Cu")
		(net "P5E_CPU1_PE2_TX_DP<6>")
	)
	(segment
		(start 128.360678 -219.18676)
		(end 128.369568 -219.18168)
		(width 0.0889)
		(layer "In15.Cu")
		(net "P5E_CPU1_PE2_TX_DP<6>")
	)
	(segment
		(start 127.242316 -222.780098)
		(end 127.242316 -222.761556)
		(width 0.0889)
		(layer "In15.Cu")
		(net "P5E_CPU1_PE2_TX_DP<6>")
	)
	(segment
		(start 127.890524 -221.628462)
		(end 127.899414 -221.623382)
		(width 0.0889)
		(layer "In15.Cu")
		(net "P5E_CPU1_PE2_TX_DP<6>")
	)
	(segment
		(start 135.724138 -212.863684)
		(end 140.58646 -214.87765)
		(width 0.14732)
		(layer "In15.Cu")
		(net "P5E_CPU1_PE2_TX_DP<6>")
	)
	(segment
		(start 149.396958 -394.603224)
		(end 149.282404 -395.02461)
		(width 0.14732)
		(layer "In15.Cu")
		(net "P5E_CPU1_PE2_TX_DP<6>")
	)
	(segment
		(start 128.830578 -216.745058)
		(end 128.838706 -216.740486)
		(width 0.0889)
		(layer "In15.Cu")
		(net "P5E_CPU1_PE2_TX_DP<6>")
	)
	(segment
		(start 157.766512 -363.857794)
		(end 149.577044 -393.941554)
		(width 0.14732)
		(layer "In15.Cu")
		(net "P5E_CPU1_PE2_TX_DP<6>")
	)
	(segment
		(start 130.15341 -215.112346)
		(end 130.168142 -215.120982)
		(width 0.0889)
		(layer "In15.Cu")
		(net "P5E_CPU1_PE2_TX_DP<6>")
	)
	(segment
		(start 128.830324 -218.372944)
		(end 128.839214 -218.367864)
		(width 0.0889)
		(layer "In15.Cu")
		(net "P5E_CPU1_PE2_TX_DP<6>")
	)
	(segment
		(start 149.282404 -395.02461)
		(end 149.129496 -395.111986)
		(width 0.14732)
		(layer "In15.Cu")
		(net "P5E_CPU1_PE2_TX_DP<6>")
	)
	(segment
		(start 148.80717 -396.769844)
		(end 148.692616 -397.19123)
		(width 0.14732)
		(layer "In15.Cu")
		(net "P5E_CPU1_PE2_TX_DP<6>")
	)
	(segment
		(start 148.98751 -396.10792)
		(end 148.834602 -396.195296)
		(width 0.14732)
		(layer "In15.Cu")
		(net "P5E_CPU1_PE2_TX_DP<6>")
	)
	(segment
		(start 149.42439 -394.028676)
		(end 149.309582 -394.450316)
		(width 0.14732)
		(layer "In15.Cu")
		(net "P5E_CPU1_PE2_TX_DP<6>")
	)
	(segment
		(start 129.121916 -216.260426)
		(end 129.121916 -216.25052)
		(width 0.0889)
		(layer "In15.Cu")
		(net "P5E_CPU1_PE2_TX_DP<6>")
	)
	(segment
		(start 131.471162 -213.310978)
		(end 131.513072 -213.269068)
		(width 0.0889)
		(layer "In15.Cu")
		(net "P5E_CPU1_PE2_TX_DP<6>")
	)
	(segment
		(start 131.471416 -213.92896)
		(end 131.471162 -213.928706)
		(width 0.0889)
		(layer "In15.Cu")
		(net "P5E_CPU1_PE2_TX_DP<6>")
	)
	(segment
		(start 149.577044 -393.941554)
		(end 149.42439 -394.028676)
		(width 0.14732)
		(layer "In15.Cu")
		(net "P5E_CPU1_PE2_TX_DP<6>")
	)
	(segment
		(start 149.309582 -394.450316)
		(end 149.396958 -394.603224)
		(width 0.14732)
		(layer "In15.Cu")
		(net "P5E_CPU1_PE2_TX_DP<6>")
	)
	(segment
		(start 126.950978 -223.256348)
		(end 126.959868 -223.251268)
		(width 0.0889)
		(layer "In15.Cu")
		(net "P5E_CPU1_PE2_TX_DP<6>")
	)
	(segment
		(start 148.539454 -397.278606)
		(end 148.4249 -397.7005)
		(width 0.14732)
		(layer "In15.Cu")
		(net "P5E_CPU1_PE2_TX_DP<6>")
	)
	(segment
		(start 149.129496 -395.111986)
		(end 149.014688 -395.533626)
		(width 0.14732)
		(layer "In15.Cu")
		(net "P5E_CPU1_PE2_TX_DP<6>")
	)
	(segment
		(start 127.899414 -221.623382)
		(end 127.90551 -221.619826)
		(width 0.0889)
		(layer "In15.Cu")
		(net "P5E_CPU1_PE2_TX_DP<6>")
	)
	(segment
		(start 151.224996 -253.340108)
		(end 146.9898 -309.095648)
		(width 0.14732)
		(layer "In15.Cu")
		(net "P5E_CPU1_PE2_TX_DP<6>")
	)
	(segment
		(start 148.692616 -397.19123)
		(end 148.539454 -397.278606)
		(width 0.14732)
		(layer "In15.Cu")
		(net "P5E_CPU1_PE2_TX_DP<6>")
	)
	(segment
		(start 128.839468 -217.388694)
		(end 128.830578 -217.383614)
		(width 0.0889)
		(layer "In15.Cu")
		(net "P5E_CPU1_PE2_TX_DP<6>")
	)
	(segment
		(start 149.014688 -395.533626)
		(end 149.102064 -395.686534)
		(width 0.14732)
		(layer "In15.Cu")
		(net "P5E_CPU1_PE2_TX_DP<6>")
	)
	(segment
		(start 131.471162 -213.928706)
		(end 131.471162 -213.310978)
		(width 0.0889)
		(layer "In15.Cu")
		(net "P5E_CPU1_PE2_TX_DP<6>")
	)
	(segment
		(start 148.018754 -399.666206)
		(end 148.018754 -400.563588)
		(width 0.14732)
		(layer "In15.Cu")
		(net "P5E_CPU1_PE2_TX_DP<6>")
	)
	(segment
		(start 131.513072 -213.038436)
		(end 131.687824 -212.863684)
		(width 0.14732)
		(layer "In15.Cu")
		(net "P5E_CPU1_PE2_TX_DP<6>")
	)
	(segment
		(start 150.4442 -323.835268)
		(end 157.058868 -331.560932)
		(width 0.14732)
		(layer "In15.Cu")
		(net "P5E_CPU1_PE2_TX_DP<6>")
	)
	(segment
		(start 140.58646 -214.87765)
		(end 141.880336 -216.588848)
		(width 0.14732)
		(layer "In15.Cu")
		(net "P5E_CPU1_PE2_TX_DP<6>")
	)
	(segment
		(start 142.120112 -217.108532)
		(end 142.291054 -217.132154)
		(width 0.14732)
		(layer "In15.Cu")
		(net "P5E_CPU1_PE2_TX_DP<6>")
	)
	(segment
		(start 125.89383 -224.118424)
		(end 125.98273 -224.094802)
		(width 0.0889)
		(layer "In15.Cu")
		(net "P5E_CPU1_PE2_TX_DP<6>")
	)
	(segment
		(start 142.291054 -217.132154)
		(end 146.469608 -222.659194)
		(width 0.14732)
		(layer "In15.Cu")
		(net "P5E_CPU1_PE2_TX_DP<6>")
	)
	(arc
		(start 126.496064 -224.061528)
		(mid 126.698477 -223.855115)
		(end 126.772416 -223.575626)
		(width 0.0889)
		(layer "In15.Cu")
		(net "P5E_CPU1_PE2_TX_DP<6>")
	)
	(arc
		(start 129.121916 -217.859864)
		(mid 129.041754 -217.587675)
		(end 128.839468 -217.388694)
		(width 0.0889)
		(layer "In15.Cu")
		(net "P5E_CPU1_PE2_TX_DP<6>")
	)
	(arc
		(start 127.899414 -220.644212)
		(mid 127.764481 -220.510858)
		(end 127.712216 -220.32849)
		(width 0.0889)
		(layer "In15.Cu")
		(net "P5E_CPU1_PE2_TX_DP<6>")
	)
	(arc
		(start 128.84531 -218.364308)
		(mid 129.047897 -218.157957)
		(end 129.121916 -217.878406)
		(width 0.0889)
		(layer "In15.Cu")
		(net "P5E_CPU1_PE2_TX_DP<6>")
	)
	(arc
		(start 128.839468 -216.739978)
		(mid 129.043803 -216.537373)
		(end 129.121916 -216.260426)
		(width 0.0889)
		(layer "In15.Cu")
		(net "P5E_CPU1_PE2_TX_DP<6>")
	)
	(arc
		(start 127.242316 -222.761556)
		(mid 127.289995 -222.578656)
		(end 127.420878 -222.442278)
		(width 0.0889)
		(layer "In15.Cu")
		(net "P5E_CPU1_PE2_TX_DP<6>")
	)
	(arc
		(start 128.830578 -217.383614)
		(mid 128.651981 -217.064336)
		(end 128.830578 -216.745058)
		(width 0.0889)
		(layer "In15.Cu")
		(net "P5E_CPU1_PE2_TX_DP<6>")
	)
	(arc
		(start 129.779014 -215.112346)
		(mid 129.966212 -215.062203)
		(end 130.15341 -215.112346)
		(width 0.0889)
		(layer "In15.Cu")
		(net "P5E_CPU1_PE2_TX_DP<6>")
	)
	(arc
		(start 125.98273 -224.094802)
		(mid 125.992597 -224.098961)
		(end 126.002542 -224.10293)
		(width 0.0889)
		(layer "In15.Cu")
		(net "P5E_CPU1_PE2_TX_DP<6>")
	)
	(arc
		(start 129.121916 -216.25052)
		(mid 129.169595 -216.06762)
		(end 129.300478 -215.931242)
		(width 0.0889)
		(layer "In15.Cu")
		(net "P5E_CPU1_PE2_TX_DP<6>")
	)
	(arc
		(start 131.001008 -214.461852)
		(mid 131.076079 -214.34611)
		(end 131.185412 -214.261954)
		(width 0.0889)
		(layer "In15.Cu")
		(net "P5E_CPU1_PE2_TX_DP<6>")
	)
	(arc
		(start 127.429768 -222.437198)
		(mid 127.632591 -222.236967)
		(end 127.711962 -221.963234)
		(width 0.0889)
		(layer "In15.Cu")
		(net "P5E_CPU1_PE2_TX_DP<6>")
	)
	(arc
		(start 128.369568 -219.18168)
		(mid 128.572391 -218.981449)
		(end 128.651762 -218.707716)
		(width 0.0889)
		(layer "In15.Cu")
		(net "P5E_CPU1_PE2_TX_DP<6>")
	)
	(arc
		(start 129.591816 -215.421972)
		(mid 129.64287 -215.247392)
		(end 129.770124 -215.117426)
		(width 0.0889)
		(layer "In15.Cu")
		(net "P5E_CPU1_PE2_TX_DP<6>")
	)
	(arc
		(start 126.959868 -223.251268)
		(mid 127.162154 -223.052287)
		(end 127.242316 -222.780098)
		(width 0.0889)
		(layer "In15.Cu")
		(net "P5E_CPU1_PE2_TX_DP<6>")
	)
	(arc
		(start 130.718814 -215.112346)
		(mid 130.920096 -214.914859)
		(end 131.001008 -214.644732)
		(width 0.0889)
		(layer "In15.Cu")
		(net "P5E_CPU1_PE2_TX_DP<6>")
	)
	(arc
		(start 128.182116 -221.1197)
		(mid 128.102897 -220.845015)
		(end 127.899414 -220.644212)
		(width 0.0889)
		(layer "In15.Cu")
		(net "P5E_CPU1_PE2_TX_DP<6>")
	)
	(arc
		(start 128.651762 -218.692222)
		(mid 128.699441 -218.509322)
		(end 128.830324 -218.372944)
		(width 0.0889)
		(layer "In15.Cu")
		(net "P5E_CPU1_PE2_TX_DP<6>")
	)
	(arc
		(start 127.712216 -220.311218)
		(mid 127.764486 -220.128853)
		(end 127.899414 -219.995496)
		(width 0.0889)
		(layer "In15.Cu")
		(net "P5E_CPU1_PE2_TX_DP<6>")
	)
	(arc
		(start 131.456176 -213.968584)
		(mid 131.464141 -213.94916)
		(end 131.471416 -213.929468)
		(width 0.0889)
		(layer "In15.Cu")
		(net "P5E_CPU1_PE2_TX_DP<6>")
	)
	(arc
		(start 126.772416 -223.575626)
		(mid 126.820095 -223.392726)
		(end 126.950978 -223.256348)
		(width 0.0889)
		(layer "In15.Cu")
		(net "P5E_CPU1_PE2_TX_DP<6>")
	)
	(arc
		(start 131.185412 -214.261954)
		(mid 131.345993 -214.138523)
		(end 131.456176 -213.968584)
		(width 0.0889)
		(layer "In15.Cu")
		(net "P5E_CPU1_PE2_TX_DP<6>")
	)
	(arc
		(start 127.711962 -221.94774)
		(mid 127.759641 -221.76484)
		(end 127.890524 -221.628462)
		(width 0.0889)
		(layer "In15.Cu")
		(net "P5E_CPU1_PE2_TX_DP<6>")
	)
	(arc
		(start 129.591562 -215.436704)
		(mid 129.591614 -215.429337)
		(end 129.591816 -215.421972)
		(width 0.0889)
		(layer "In15.Cu")
		(net "P5E_CPU1_PE2_TX_DP<6>")
	)
	(arc
		(start 127.90551 -221.619826)
		(mid 128.108097 -221.413475)
		(end 128.182116 -221.133924)
		(width 0.0889)
		(layer "In15.Cu")
		(net "P5E_CPU1_PE2_TX_DP<6>")
	)
	(arc
		(start 129.309368 -215.926162)
		(mid 129.512191 -215.725931)
		(end 129.591562 -215.452198)
		(width 0.0889)
		(layer "In15.Cu")
		(net "P5E_CPU1_PE2_TX_DP<6>")
	)
	(arc
		(start 127.90551 -219.99194)
		(mid 128.108097 -219.785589)
		(end 128.182116 -219.506038)
		(width 0.0889)
		(layer "In15.Cu")
		(net "P5E_CPU1_PE2_TX_DP<6>")
	)
	(arc
		(start 130.168142 -215.120982)
		(mid 130.444583 -215.188148)
		(end 130.718814 -215.112346)
		(width 0.0889)
		(layer "In15.Cu")
		(net "P5E_CPU1_PE2_TX_DP<6>")
	)
	(arc
		(start 126.002542 -224.10293)
		(mid 126.250553 -224.139395)
		(end 126.489968 -224.065084)
		(width 0.0889)
		(layer "In15.Cu")
		(net "P5E_CPU1_PE2_TX_DP<6>")
	)
	(arc
		(start 128.182116 -219.506038)
		(mid 128.229795 -219.323138)
		(end 128.360678 -219.18676)
		(width 0.0889)
		(layer "In15.Cu")
		(net "P5E_CPU1_PE2_TX_DP<6>")
	)
	(segment
		(start 151.092916 -401.16379)
		(end 151.092916 -401.777962)
		(width 0.13208)
		(layer "F.Cu")
		(net "P5E_CPU1_PE2_TX_DP<5>")
	)
	(segment
		(start 125.267466 -225.203512)
		(end 125.267212 -225.203258)
		(width 0.13208)
		(layer "F.Cu")
		(net "P5E_CPU1_PE2_TX_DP<5>")
	)
	(segment
		(start 150.787354 -400.858228)
		(end 151.092916 -401.16379)
		(width 0.13208)
		(layer "F.Cu")
		(net "P5E_CPU1_PE2_TX_DP<5>")
	)
	(segment
		(start 125.267466 -225.739198)
		(end 125.267466 -225.203512)
		(width 0.13208)
		(layer "F.Cu")
		(net "P5E_CPU1_PE2_TX_DP<5>")
	)
	(segment
		(start 151.092916 -401.777962)
		(end 150.766526 -402.104352)
		(width 0.13208)
		(layer "F.Cu")
		(net "P5E_CPU1_PE2_TX_DP<5>")
	)
	(segment
		(start 150.766526 -402.104352)
		(end 150.761954 -402.104352)
		(width 0.13208)
		(layer "F.Cu")
		(net "P5E_CPU1_PE2_TX_DP<5>")
	)
	(segment
		(start 152.28443 -394.029946)
		(end 152.285192 -394.0302)
		(width 0.14732)
		(layer "In15.Cu")
		(net "P5E_CPU1_PE2_TX_DP<5>")
	)
	(segment
		(start 148.251926 -225.405188)
		(end 151.99995 -248.69013)
		(width 0.14732)
		(layer "In15.Cu")
		(net "P5E_CPU1_PE2_TX_DP<5>")
	)
	(segment
		(start 144.12087 -217.73134)
		(end 147.217638 -221.822264)
		(width 0.14732)
		(layer "In15.Cu")
		(net "P5E_CPU1_PE2_TX_DP<5>")
	)
	(segment
		(start 143.265906 -216.803732)
		(end 143.436594 -216.827354)
		(width 0.14732)
		(layer "In15.Cu")
		(net "P5E_CPU1_PE2_TX_DP<5>")
	)
	(segment
		(start 127.899414 -218.367864)
		(end 127.900176 -218.367356)
		(width 0.0889)
		(layer "In15.Cu")
		(net "P5E_CPU1_PE2_TX_DP<5>")
	)
	(segment
		(start 152.281128 -393.455398)
		(end 152.376632 -393.603226)
		(width 0.14732)
		(layer "In15.Cu")
		(net "P5E_CPU1_PE2_TX_DP<5>")
	)
	(segment
		(start 152.045416 -394.553186)
		(end 152.14092 -394.701014)
		(width 0.14732)
		(layer "In15.Cu")
		(net "P5E_CPU1_PE2_TX_DP<5>")
	)
	(segment
		(start 151.3078 -323.360288)
		(end 158.039308 -331.268324)
		(width 0.14732)
		(layer "In15.Cu")
		(net "P5E_CPU1_PE2_TX_DP<5>")
	)
	(segment
		(start 127.890524 -218.372944)
		(end 127.89789 -218.368626)
		(width 0.0889)
		(layer "In15.Cu")
		(net "P5E_CPU1_PE2_TX_DP<5>")
	)
	(segment
		(start 151.81326 -396.225776)
		(end 151.813768 -396.225776)
		(width 0.14732)
		(layer "In15.Cu")
		(net "P5E_CPU1_PE2_TX_DP<5>")
	)
	(segment
		(start 151.813768 -396.225776)
		(end 151.665686 -396.32128)
		(width 0.14732)
		(layer "In15.Cu")
		(net "P5E_CPU1_PE2_TX_DP<5>")
	)
	(segment
		(start 126.959868 -220.644212)
		(end 126.950978 -220.639132)
		(width 0.0889)
		(layer "In15.Cu")
		(net "P5E_CPU1_PE2_TX_DP<5>")
	)
	(segment
		(start 128.830324 -215.117426)
		(end 128.839214 -215.112346)
		(width 0.0889)
		(layer "In15.Cu")
		(net "P5E_CPU1_PE2_TX_DP<5>")
	)
	(segment
		(start 151.577802 -397.323818)
		(end 151.429974 -397.419068)
		(width 0.14732)
		(layer "In15.Cu")
		(net "P5E_CPU1_PE2_TX_DP<5>")
	)
	(segment
		(start 151.434038 -397.994378)
		(end 151.081994 -399.635472)
		(width 0.14732)
		(layer "In15.Cu")
		(net "P5E_CPU1_PE2_TX_DP<5>")
	)
	(segment
		(start 151.904954 -395.798548)
		(end 151.81326 -396.225776)
		(width 0.14732)
		(layer "In15.Cu")
		(net "P5E_CPU1_PE2_TX_DP<5>")
	)
	(segment
		(start 160.63722 -345.99753)
		(end 159.987234 -349.686626)
		(width 0.14732)
		(layer "In15.Cu")
		(net "P5E_CPU1_PE2_TX_DP<5>")
	)
	(segment
		(start 147.217638 -221.822264)
		(end 148.251926 -225.405188)
		(width 0.14732)
		(layer "In15.Cu")
		(net "P5E_CPU1_PE2_TX_DP<5>")
	)
	(segment
		(start 125.541278 -224.070164)
		(end 125.550168 -224.065084)
		(width 0.0889)
		(layer "In15.Cu")
		(net "P5E_CPU1_PE2_TX_DP<5>")
	)
	(segment
		(start 152.14092 -394.701014)
		(end 152.140412 -394.701014)
		(width 0.14732)
		(layer "In15.Cu")
		(net "P5E_CPU1_PE2_TX_DP<5>")
	)
	(segment
		(start 158.039308 -331.268324)
		(end 160.63722 -345.99753)
		(width 0.14732)
		(layer "In15.Cu")
		(net "P5E_CPU1_PE2_TX_DP<5>")
	)
	(segment
		(start 147.94484 -308.976268)
		(end 151.3078 -323.360288)
		(width 0.14732)
		(layer "In15.Cu")
		(net "P5E_CPU1_PE2_TX_DP<5>")
	)
	(segment
		(start 129.591816 -213.929468)
		(end 129.591816 -213.270592)
		(width 0.0889)
		(layer "In15.Cu")
		(net "P5E_CPU1_PE2_TX_DP<5>")
	)
	(segment
		(start 143.002 -216.455244)
		(end 143.265906 -216.803732)
		(width 0.14732)
		(layer "In15.Cu")
		(net "P5E_CPU1_PE2_TX_DP<5>")
	)
	(segment
		(start 152.140412 -394.701014)
		(end 152.048972 -395.127734)
		(width 0.14732)
		(layer "In15.Cu")
		(net "P5E_CPU1_PE2_TX_DP<5>")
	)
	(segment
		(start 129.121408 -214.644732)
		(end 129.121408 -214.461852)
		(width 0.0889)
		(layer "In15.Cu")
		(net "P5E_CPU1_PE2_TX_DP<5>")
	)
	(segment
		(start 152.285192 -394.0302)
		(end 152.13711 -394.125704)
		(width 0.14732)
		(layer "In15.Cu")
		(net "P5E_CPU1_PE2_TX_DP<5>")
	)
	(segment
		(start 127.899414 -216.739978)
		(end 127.900176 -216.73947)
		(width 0.0889)
		(layer "In15.Cu")
		(net "P5E_CPU1_PE2_TX_DP<5>")
	)
	(segment
		(start 143.950182 -217.707718)
		(end 144.121124 -217.73134)
		(width 0.14732)
		(layer "In15.Cu")
		(net "P5E_CPU1_PE2_TX_DP<5>")
	)
	(segment
		(start 152.37587 -393.603226)
		(end 152.28443 -394.029946)
		(width 0.14732)
		(layer "In15.Cu")
		(net "P5E_CPU1_PE2_TX_DP<5>")
	)
	(segment
		(start 126.950724 -221.628462)
		(end 126.959614 -221.623382)
		(width 0.0889)
		(layer "In15.Cu")
		(net "P5E_CPU1_PE2_TX_DP<5>")
	)
	(segment
		(start 143.025368 -216.284302)
		(end 143.025622 -216.284302)
		(width 0.14732)
		(layer "In15.Cu")
		(net "P5E_CPU1_PE2_TX_DP<5>")
	)
	(segment
		(start 126.950978 -220.000576)
		(end 126.959106 -219.996004)
		(width 0.0889)
		(layer "In15.Cu")
		(net "P5E_CPU1_PE2_TX_DP<5>")
	)
	(segment
		(start 151.081994 -399.635472)
		(end 151.081994 -400.563588)
		(width 0.14732)
		(layer "In15.Cu")
		(net "P5E_CPU1_PE2_TX_DP<5>")
	)
	(segment
		(start 129.63398 -213.20633)
		(end 129.63398 -212.819488)
		(width 0.14732)
		(layer "In15.Cu")
		(net "P5E_CPU1_PE2_TX_DP<5>")
	)
	(segment
		(start 151.809704 -395.650974)
		(end 151.904954 -395.798548)
		(width 0.14732)
		(layer "In15.Cu")
		(net "P5E_CPU1_PE2_TX_DP<5>")
	)
	(segment
		(start 143.025622 -216.284302)
		(end 143.002 -216.455244)
		(width 0.14732)
		(layer "In15.Cu")
		(net "P5E_CPU1_PE2_TX_DP<5>")
	)
	(segment
		(start 143.709898 -217.188542)
		(end 143.686276 -217.35923)
		(width 0.14732)
		(layer "In15.Cu")
		(net "P5E_CPU1_PE2_TX_DP<5>")
	)
	(segment
		(start 128.182116 -217.878406)
		(end 128.182116 -217.864182)
		(width 0.0889)
		(layer "In15.Cu")
		(net "P5E_CPU1_PE2_TX_DP<5>")
	)
	(segment
		(start 152.1587 -253.406402)
		(end 152.1587 -253.406656)
		(width 0.14732)
		(layer "In15.Cu")
		(net "P5E_CPU1_PE2_TX_DP<5>")
	)
	(segment
		(start 143.686276 -217.35923)
		(end 143.950182 -217.707718)
		(width 0.14732)
		(layer "In15.Cu")
		(net "P5E_CPU1_PE2_TX_DP<5>")
	)
	(segment
		(start 152.52065 -392.932412)
		(end 152.372822 -393.027916)
		(width 0.14732)
		(layer "In15.Cu")
		(net "P5E_CPU1_PE2_TX_DP<5>")
	)
	(segment
		(start 128.360678 -215.931242)
		(end 128.369568 -215.926162)
		(width 0.0889)
		(layer "In15.Cu")
		(net "P5E_CPU1_PE2_TX_DP<5>")
	)
	(segment
		(start 151.99995 -248.69013)
		(end 152.1587 -253.406402)
		(width 0.14732)
		(layer "In15.Cu")
		(net "P5E_CPU1_PE2_TX_DP<5>")
	)
	(segment
		(start 128.651762 -215.452198)
		(end 128.651762 -215.436704)
		(width 0.0889)
		(layer "In15.Cu")
		(net "P5E_CPU1_PE2_TX_DP<5>")
	)
	(segment
		(start 152.519888 -392.932158)
		(end 152.52065 -392.932412)
		(width 0.14732)
		(layer "In15.Cu")
		(net "P5E_CPU1_PE2_TX_DP<5>")
	)
	(segment
		(start 129.63398 -212.819488)
		(end 129.959608 -212.49386)
		(width 0.14732)
		(layer "In15.Cu")
		(net "P5E_CPU1_PE2_TX_DP<5>")
	)
	(segment
		(start 159.987234 -349.686626)
		(end 158.74111 -363.93247)
		(width 0.14732)
		(layer "In15.Cu")
		(net "P5E_CPU1_PE2_TX_DP<5>")
	)
	(segment
		(start 129.959608 -212.49386)
		(end 131.336034 -211.923884)
		(width 0.14732)
		(layer "In15.Cu")
		(net "P5E_CPU1_PE2_TX_DP<5>")
	)
	(segment
		(start 151.33828 -397.84655)
		(end 151.434038 -397.994378)
		(width 0.14732)
		(layer "In15.Cu")
		(net "P5E_CPU1_PE2_TX_DP<5>")
	)
	(segment
		(start 152.13711 -394.125704)
		(end 152.045416 -394.553186)
		(width 0.14732)
		(layer "In15.Cu")
		(net "P5E_CPU1_PE2_TX_DP<5>")
	)
	(segment
		(start 131.336034 -211.923884)
		(end 135.911336 -211.923884)
		(width 0.14732)
		(layer "In15.Cu")
		(net "P5E_CPU1_PE2_TX_DP<5>")
	)
	(segment
		(start 127.89789 -218.368626)
		(end 127.899414 -218.367864)
		(width 0.0889)
		(layer "In15.Cu")
		(net "P5E_CPU1_PE2_TX_DP<5>")
	)
	(segment
		(start 152.1587 -253.406656)
		(end 147.94484 -308.976268)
		(width 0.14732)
		(layer "In15.Cu")
		(net "P5E_CPU1_PE2_TX_DP<5>")
	)
	(segment
		(start 143.436594 -216.827354)
		(end 143.709898 -217.188542)
		(width 0.14732)
		(layer "In15.Cu")
		(net "P5E_CPU1_PE2_TX_DP<5>")
	)
	(segment
		(start 126.959614 -221.623382)
		(end 126.96571 -221.619826)
		(width 0.0889)
		(layer "In15.Cu")
		(net "P5E_CPU1_PE2_TX_DP<5>")
	)
	(segment
		(start 151.665686 -396.32128)
		(end 151.573992 -396.748762)
		(width 0.14732)
		(layer "In15.Cu")
		(net "P5E_CPU1_PE2_TX_DP<5>")
	)
	(segment
		(start 151.429974 -397.419068)
		(end 151.33828 -397.84655)
		(width 0.14732)
		(layer "In15.Cu")
		(net "P5E_CPU1_PE2_TX_DP<5>")
	)
	(segment
		(start 151.901398 -395.223492)
		(end 151.809704 -395.650974)
		(width 0.14732)
		(layer "In15.Cu")
		(net "P5E_CPU1_PE2_TX_DP<5>")
	)
	(segment
		(start 126.772162 -221.963234)
		(end 126.772162 -221.94774)
		(width 0.0889)
		(layer "In15.Cu")
		(net "P5E_CPU1_PE2_TX_DP<5>")
	)
	(segment
		(start 127.900176 -216.73947)
		(end 127.90551 -216.736422)
		(width 0.0889)
		(layer "In15.Cu")
		(net "P5E_CPU1_PE2_TX_DP<5>")
	)
	(segment
		(start 151.081994 -400.563588)
		(end 150.787354 -400.858228)
		(width 0.14732)
		(layer "In15.Cu")
		(net "P5E_CPU1_PE2_TX_DP<5>")
	)
	(segment
		(start 152.376632 -393.603226)
		(end 152.37587 -393.603226)
		(width 0.14732)
		(layer "In15.Cu")
		(net "P5E_CPU1_PE2_TX_DP<5>")
	)
	(segment
		(start 151.669496 -396.89659)
		(end 151.577802 -397.323818)
		(width 0.14732)
		(layer "In15.Cu")
		(net "P5E_CPU1_PE2_TX_DP<5>")
	)
	(segment
		(start 152.372822 -393.027916)
		(end 152.281128 -393.455398)
		(width 0.14732)
		(layer "In15.Cu")
		(net "P5E_CPU1_PE2_TX_DP<5>")
	)
	(segment
		(start 158.74111 -363.93247)
		(end 152.519888 -392.932158)
		(width 0.14732)
		(layer "In15.Cu")
		(net "P5E_CPU1_PE2_TX_DP<5>")
	)
	(segment
		(start 127.420878 -219.18676)
		(end 127.429768 -219.18168)
		(width 0.0889)
		(layer "In15.Cu")
		(net "P5E_CPU1_PE2_TX_DP<5>")
	)
	(segment
		(start 129.591816 -213.270592)
		(end 129.63398 -213.228428)
		(width 0.0889)
		(layer "In15.Cu")
		(net "P5E_CPU1_PE2_TX_DP<5>")
	)
	(segment
		(start 141.466316 -214.224616)
		(end 143.025368 -216.284302)
		(width 0.14732)
		(layer "In15.Cu")
		(net "P5E_CPU1_PE2_TX_DP<5>")
	)
	(segment
		(start 151.573992 -396.748762)
		(end 151.669496 -396.89659)
		(width 0.14732)
		(layer "In15.Cu")
		(net "P5E_CPU1_PE2_TX_DP<5>")
	)
	(segment
		(start 152.04948 -395.127988)
		(end 151.901398 -395.223492)
		(width 0.14732)
		(layer "In15.Cu")
		(net "P5E_CPU1_PE2_TX_DP<5>")
	)
	(segment
		(start 125.267212 -225.203258)
		(end 125.110748 -224.93224)
		(width 0.0889)
		(layer "In15.Cu")
		(net "P5E_CPU1_PE2_TX_DP<5>")
	)
	(segment
		(start 126.302516 -222.77578)
		(end 126.302516 -222.761556)
		(width 0.0889)
		(layer "In15.Cu")
		(net "P5E_CPU1_PE2_TX_DP<5>")
	)
	(segment
		(start 127.711962 -218.707716)
		(end 127.711962 -218.692222)
		(width 0.0889)
		(layer "In15.Cu")
		(net "P5E_CPU1_PE2_TX_DP<5>")
	)
	(segment
		(start 126.481078 -222.442278)
		(end 126.489968 -222.437198)
		(width 0.0889)
		(layer "In15.Cu")
		(net "P5E_CPU1_PE2_TX_DP<5>")
	)
	(segment
		(start 152.048972 -395.127734)
		(end 152.04948 -395.127988)
		(width 0.14732)
		(layer "In15.Cu")
		(net "P5E_CPU1_PE2_TX_DP<5>")
	)
	(segment
		(start 135.911336 -211.923884)
		(end 141.466316 -214.224616)
		(width 0.14732)
		(layer "In15.Cu")
		(net "P5E_CPU1_PE2_TX_DP<5>")
	)
	(segment
		(start 127.242316 -221.133924)
		(end 127.242316 -221.115382)
		(width 0.0889)
		(layer "In15.Cu")
		(net "P5E_CPU1_PE2_TX_DP<5>")
	)
	(segment
		(start 125.832616 -223.585532)
		(end 125.832616 -223.56699)
		(width 0.0889)
		(layer "In15.Cu")
		(net "P5E_CPU1_PE2_TX_DP<5>")
	)
	(segment
		(start 126.959106 -219.996004)
		(end 126.959868 -219.995496)
		(width 0.0889)
		(layer "In15.Cu")
		(net "P5E_CPU1_PE2_TX_DP<5>")
	)
	(segment
		(start 127.712216 -217.072972)
		(end 127.712216 -217.0557)
		(width 0.0889)
		(layer "In15.Cu")
		(net "P5E_CPU1_PE2_TX_DP<5>")
	)
	(segment
		(start 125.110748 -224.93224)
		(end 125.134878 -224.843086)
		(width 0.0889)
		(layer "In15.Cu")
		(net "P5E_CPU1_PE2_TX_DP<5>")
	)
	(segment
		(start 144.121124 -217.73134)
		(end 144.12087 -217.73134)
		(width 0.14732)
		(layer "In15.Cu")
		(net "P5E_CPU1_PE2_TX_DP<5>")
	)
	(segment
		(start 127.900176 -218.367356)
		(end 127.90551 -218.364308)
		(width 0.0889)
		(layer "In15.Cu")
		(net "P5E_CPU1_PE2_TX_DP<5>")
	)
	(segment
		(start 129.63398 -213.228428)
		(end 129.63398 -213.20633)
		(width 0.0889)
		(layer "In15.Cu")
		(net "P5E_CPU1_PE2_TX_DP<5>")
	)
	(segment
		(start 127.242316 -219.515944)
		(end 127.242316 -219.506038)
		(width 0.0889)
		(layer "In15.Cu")
		(net "P5E_CPU1_PE2_TX_DP<5>")
	)
	(arc
		(start 126.302516 -222.761556)
		(mid 126.350195 -222.578656)
		(end 126.481078 -222.442278)
		(width 0.0889)
		(layer "In15.Cu")
		(net "P5E_CPU1_PE2_TX_DP<5>")
	)
	(arc
		(start 126.950978 -220.639132)
		(mid 126.820064 -220.502772)
		(end 126.772416 -220.319854)
		(width 0.0889)
		(layer "In15.Cu")
		(net "P5E_CPU1_PE2_TX_DP<5>")
	)
	(arc
		(start 125.550168 -224.065084)
		(mid 125.754503 -223.862479)
		(end 125.832616 -223.585532)
		(width 0.0889)
		(layer "In15.Cu")
		(net "P5E_CPU1_PE2_TX_DP<5>")
	)
	(arc
		(start 129.305812 -214.261954)
		(mid 129.466393 -214.138523)
		(end 129.576576 -213.968584)
		(width 0.0889)
		(layer "In15.Cu")
		(net "P5E_CPU1_PE2_TX_DP<5>")
	)
	(arc
		(start 126.772416 -220.319854)
		(mid 126.820095 -220.136954)
		(end 126.950978 -220.000576)
		(width 0.0889)
		(layer "In15.Cu")
		(net "P5E_CPU1_PE2_TX_DP<5>")
	)
	(arc
		(start 126.489968 -222.437198)
		(mid 126.692791 -222.236967)
		(end 126.772162 -221.963234)
		(width 0.0889)
		(layer "In15.Cu")
		(net "P5E_CPU1_PE2_TX_DP<5>")
	)
	(arc
		(start 126.96571 -221.619826)
		(mid 127.168297 -221.413475)
		(end 127.242316 -221.133924)
		(width 0.0889)
		(layer "In15.Cu")
		(net "P5E_CPU1_PE2_TX_DP<5>")
	)
	(arc
		(start 127.711962 -218.692222)
		(mid 127.759641 -218.509322)
		(end 127.890524 -218.372944)
		(width 0.0889)
		(layer "In15.Cu")
		(net "P5E_CPU1_PE2_TX_DP<5>")
	)
	(arc
		(start 127.242316 -221.115382)
		(mid 127.162154 -220.843193)
		(end 126.959868 -220.644212)
		(width 0.0889)
		(layer "In15.Cu")
		(net "P5E_CPU1_PE2_TX_DP<5>")
	)
	(arc
		(start 125.151896 -224.829878)
		(mid 125.307294 -224.633597)
		(end 125.362716 -224.389442)
		(width 0.0889)
		(layer "In15.Cu")
		(net "P5E_CPU1_PE2_TX_DP<5>")
	)
	(arc
		(start 128.652016 -215.421972)
		(mid 128.70307 -215.247392)
		(end 128.830324 -215.117426)
		(width 0.0889)
		(layer "In15.Cu")
		(net "P5E_CPU1_PE2_TX_DP<5>")
	)
	(arc
		(start 129.576576 -213.968584)
		(mid 129.584541 -213.94916)
		(end 129.591816 -213.929468)
		(width 0.0889)
		(layer "In15.Cu")
		(net "P5E_CPU1_PE2_TX_DP<5>")
	)
	(arc
		(start 126.772162 -221.94774)
		(mid 126.819841 -221.76484)
		(end 126.950724 -221.628462)
		(width 0.0889)
		(layer "In15.Cu")
		(net "P5E_CPU1_PE2_TX_DP<5>")
	)
	(arc
		(start 127.899414 -217.388694)
		(mid 127.764481 -217.25534)
		(end 127.712216 -217.072972)
		(width 0.0889)
		(layer "In15.Cu")
		(net "P5E_CPU1_PE2_TX_DP<5>")
	)
	(arc
		(start 125.832616 -223.56699)
		(mid 125.884886 -223.384625)
		(end 126.019814 -223.251268)
		(width 0.0889)
		(layer "In15.Cu")
		(net "P5E_CPU1_PE2_TX_DP<5>")
	)
	(arc
		(start 128.651762 -215.436704)
		(mid 128.651814 -215.429337)
		(end 128.652016 -215.421972)
		(width 0.0889)
		(layer "In15.Cu")
		(net "P5E_CPU1_PE2_TX_DP<5>")
	)
	(arc
		(start 128.839214 -215.112346)
		(mid 129.040496 -214.914859)
		(end 129.121408 -214.644732)
		(width 0.0889)
		(layer "In15.Cu")
		(net "P5E_CPU1_PE2_TX_DP<5>")
	)
	(arc
		(start 128.182116 -217.864182)
		(mid 128.102897 -217.589497)
		(end 127.899414 -217.388694)
		(width 0.0889)
		(layer "In15.Cu")
		(net "P5E_CPU1_PE2_TX_DP<5>")
	)
	(arc
		(start 127.90551 -216.736422)
		(mid 128.108097 -216.530071)
		(end 128.182116 -216.25052)
		(width 0.0889)
		(layer "In15.Cu")
		(net "P5E_CPU1_PE2_TX_DP<5>")
	)
	(arc
		(start 128.182116 -216.25052)
		(mid 128.229795 -216.06762)
		(end 128.360678 -215.931242)
		(width 0.0889)
		(layer "In15.Cu")
		(net "P5E_CPU1_PE2_TX_DP<5>")
	)
	(arc
		(start 129.121408 -214.461852)
		(mid 129.196479 -214.34611)
		(end 129.305812 -214.261954)
		(width 0.0889)
		(layer "In15.Cu")
		(net "P5E_CPU1_PE2_TX_DP<5>")
	)
	(arc
		(start 127.429768 -219.18168)
		(mid 127.632591 -218.981449)
		(end 127.711962 -218.707716)
		(width 0.0889)
		(layer "In15.Cu")
		(net "P5E_CPU1_PE2_TX_DP<5>")
	)
	(arc
		(start 127.90551 -218.364308)
		(mid 128.108097 -218.157957)
		(end 128.182116 -217.878406)
		(width 0.0889)
		(layer "In15.Cu")
		(net "P5E_CPU1_PE2_TX_DP<5>")
	)
	(arc
		(start 125.134878 -224.843086)
		(mid 125.14345 -224.836564)
		(end 125.151896 -224.829878)
		(width 0.0889)
		(layer "In15.Cu")
		(net "P5E_CPU1_PE2_TX_DP<5>")
	)
	(arc
		(start 126.959868 -219.995496)
		(mid 127.164203 -219.792891)
		(end 127.242316 -219.515944)
		(width 0.0889)
		(layer "In15.Cu")
		(net "P5E_CPU1_PE2_TX_DP<5>")
	)
	(arc
		(start 127.242316 -219.506038)
		(mid 127.289995 -219.323138)
		(end 127.420878 -219.18676)
		(width 0.0889)
		(layer "In15.Cu")
		(net "P5E_CPU1_PE2_TX_DP<5>")
	)
	(arc
		(start 125.362716 -224.389442)
		(mid 125.410395 -224.206542)
		(end 125.541278 -224.070164)
		(width 0.0889)
		(layer "In15.Cu")
		(net "P5E_CPU1_PE2_TX_DP<5>")
	)
	(arc
		(start 126.019814 -223.251268)
		(mid 126.223295 -223.050464)
		(end 126.302516 -222.77578)
		(width 0.0889)
		(layer "In15.Cu")
		(net "P5E_CPU1_PE2_TX_DP<5>")
	)
	(arc
		(start 127.712216 -217.0557)
		(mid 127.764486 -216.873335)
		(end 127.899414 -216.739978)
		(width 0.0889)
		(layer "In15.Cu")
		(net "P5E_CPU1_PE2_TX_DP<5>")
	)
	(arc
		(start 128.369568 -215.926162)
		(mid 128.572391 -215.725931)
		(end 128.651762 -215.452198)
		(width 0.0889)
		(layer "In15.Cu")
		(net "P5E_CPU1_PE2_TX_DP<5>")
	)
	(segment
		(start 123.857766 -224.925128)
		(end 123.857766 -224.389442)
		(width 0.13208)
		(layer "F.Cu")
		(net "P5E_CPU1_PE2_TX_DP<4>")
	)
	(segment
		(start 154.156156 -401.777962)
		(end 153.829766 -402.104352)
		(width 0.13208)
		(layer "F.Cu")
		(net "P5E_CPU1_PE2_TX_DP<4>")
	)
	(segment
		(start 123.857512 -224.925382)
		(end 123.857766 -224.925128)
		(width 0.13208)
		(layer "F.Cu")
		(net "P5E_CPU1_PE2_TX_DP<4>")
	)
	(segment
		(start 154.156156 -401.16379)
		(end 154.156156 -401.777962)
		(width 0.13208)
		(layer "F.Cu")
		(net "P5E_CPU1_PE2_TX_DP<4>")
	)
	(segment
		(start 153.850594 -400.858228)
		(end 154.156156 -401.16379)
		(width 0.13208)
		(layer "F.Cu")
		(net "P5E_CPU1_PE2_TX_DP<4>")
	)
	(segment
		(start 153.829766 -402.104352)
		(end 153.825194 -402.104352)
		(width 0.13208)
		(layer "F.Cu")
		(net "P5E_CPU1_PE2_TX_DP<4>")
	)
	(segment
		(start 154.365198 -397.60144)
		(end 154.469338 -397.743426)
		(width 0.14732)
		(layer "In15.Cu")
		(net "P5E_CPU1_PE2_TX_DP<4>")
	)
	(segment
		(start 154.945334 -393.840462)
		(end 154.878786 -394.272516)
		(width 0.14732)
		(layer "In15.Cu")
		(net "P5E_CPU1_PE2_TX_DP<4>")
	)
	(segment
		(start 139.005056 -212.184742)
		(end 142.09522 -213.464648)
		(width 0.14732)
		(layer "In15.Cu")
		(net "P5E_CPU1_PE2_TX_DP<4>")
	)
	(segment
		(start 154.916378 -394.846048)
		(end 154.774138 -394.950188)
		(width 0.14732)
		(layer "In15.Cu")
		(net "P5E_CPU1_PE2_TX_DP<4>")
	)
	(segment
		(start 152.18918 -322.925948)
		(end 158.9659 -330.906882)
		(width 0.14732)
		(layer "In15.Cu")
		(net "P5E_CPU1_PE2_TX_DP<4>")
	)
	(segment
		(start 154.573478 -397.0655)
		(end 154.573986 -397.0655)
		(width 0.14732)
		(layer "In15.Cu")
		(net "P5E_CPU1_PE2_TX_DP<4>")
	)
	(segment
		(start 131.304538 -210.904836)
		(end 135.914638 -210.904836)
		(width 0.14732)
		(layer "In15.Cu")
		(net "P5E_CPU1_PE2_TX_DP<4>")
	)
	(segment
		(start 154.982418 -394.414756)
		(end 154.91587 -394.846048)
		(width 0.14732)
		(layer "In15.Cu")
		(net "P5E_CPU1_PE2_TX_DP<4>")
	)
	(segment
		(start 124.610368 -224.065084)
		(end 124.616464 -224.061528)
		(width 0.0889)
		(layer "In15.Cu")
		(net "P5E_CPU1_PE2_TX_DP<4>")
	)
	(segment
		(start 153.090118 -253.435612)
		(end 148.90242 -308.854348)
		(width 0.14732)
		(layer "In15.Cu")
		(net "P5E_CPU1_PE2_TX_DP<4>")
	)
	(segment
		(start 154.982926 -394.414248)
		(end 154.982418 -394.414756)
		(width 0.14732)
		(layer "In15.Cu")
		(net "P5E_CPU1_PE2_TX_DP<4>")
	)
	(segment
		(start 154.70759 -395.382242)
		(end 154.81173 -395.524228)
		(width 0.14732)
		(layer "In15.Cu")
		(net "P5E_CPU1_PE2_TX_DP<4>")
	)
	(segment
		(start 125.541278 -222.442278)
		(end 125.550168 -222.437198)
		(width 0.0889)
		(layer "In15.Cu")
		(net "P5E_CPU1_PE2_TX_DP<4>")
	)
	(segment
		(start 154.811222 -395.524228)
		(end 154.744674 -395.955774)
		(width 0.14732)
		(layer "In15.Cu")
		(net "P5E_CPU1_PE2_TX_DP<4>")
	)
	(segment
		(start 154.81173 -395.524228)
		(end 154.811222 -395.524228)
		(width 0.14732)
		(layer "In15.Cu")
		(net "P5E_CPU1_PE2_TX_DP<4>")
	)
	(segment
		(start 125.832616 -220.32849)
		(end 125.832616 -220.311218)
		(width 0.0889)
		(layer "In15.Cu")
		(net "P5E_CPU1_PE2_TX_DP<4>")
	)
	(segment
		(start 126.950978 -216.745058)
		(end 126.959106 -216.740486)
		(width 0.0889)
		(layer "In15.Cu")
		(net "P5E_CPU1_PE2_TX_DP<4>")
	)
	(segment
		(start 126.950724 -218.372944)
		(end 126.959614 -218.367864)
		(width 0.0889)
		(layer "In15.Cu")
		(net "P5E_CPU1_PE2_TX_DP<4>")
	)
	(segment
		(start 154.536394 -396.491968)
		(end 154.640534 -396.633954)
		(width 0.14732)
		(layer "In15.Cu")
		(net "P5E_CPU1_PE2_TX_DP<4>")
	)
	(segment
		(start 126.959614 -218.367864)
		(end 126.96571 -218.364308)
		(width 0.0889)
		(layer "In15.Cu")
		(net "P5E_CPU1_PE2_TX_DP<4>")
	)
	(segment
		(start 155.11653 -392.730736)
		(end 155.049982 -393.16279)
		(width 0.14732)
		(layer "In15.Cu")
		(net "P5E_CPU1_PE2_TX_DP<4>")
	)
	(segment
		(start 128.846072 -211.923122)
		(end 131.304538 -210.904836)
		(width 0.14732)
		(layer "In15.Cu")
		(net "P5E_CPU1_PE2_TX_DP<4>")
	)
	(segment
		(start 126.019814 -221.623382)
		(end 126.02591 -221.619826)
		(width 0.0889)
		(layer "In15.Cu")
		(net "P5E_CPU1_PE2_TX_DP<4>")
	)
	(segment
		(start 128.181608 -214.644732)
		(end 128.181608 -214.424768)
		(width 0.0889)
		(layer "In15.Cu")
		(net "P5E_CPU1_PE2_TX_DP<4>")
	)
	(segment
		(start 127.712216 -213.893908)
		(end 127.712216 -213.242398)
		(width 0.0889)
		(layer "In15.Cu")
		(net "P5E_CPU1_PE2_TX_DP<4>")
	)
	(segment
		(start 139.005056 -212.184996)
		(end 139.005056 -212.184742)
		(width 0.14732)
		(layer "In15.Cu")
		(net "P5E_CPU1_PE2_TX_DP<4>")
	)
	(segment
		(start 154.878786 -394.272516)
		(end 154.982926 -394.414248)
		(width 0.14732)
		(layer "In15.Cu")
		(net "P5E_CPU1_PE2_TX_DP<4>")
	)
	(segment
		(start 161.627058 -345.997784)
		(end 160.942528 -349.883222)
		(width 0.14732)
		(layer "In15.Cu")
		(net "P5E_CPU1_PE2_TX_DP<4>")
	)
	(segment
		(start 127.754126 -213.200488)
		(end 127.754126 -213.17839)
		(width 0.0889)
		(layer "In15.Cu")
		(net "P5E_CPU1_PE2_TX_DP<4>")
	)
	(segment
		(start 154.145234 -399.84553)
		(end 154.145234 -400.563588)
		(width 0.14732)
		(layer "In15.Cu")
		(net "P5E_CPU1_PE2_TX_DP<4>")
	)
	(segment
		(start 149.640798 -226.604322)
		(end 152.91816 -248.316496)
		(width 0.14732)
		(layer "In15.Cu")
		(net "P5E_CPU1_PE2_TX_DP<4>")
	)
	(segment
		(start 159.755078 -363.462062)
		(end 155.258262 -392.626596)
		(width 0.14732)
		(layer "In15.Cu")
		(net "P5E_CPU1_PE2_TX_DP<4>")
	)
	(segment
		(start 155.258262 -392.626596)
		(end 155.25877 -392.626596)
		(width 0.14732)
		(layer "In15.Cu")
		(net "P5E_CPU1_PE2_TX_DP<4>")
	)
	(segment
		(start 154.431746 -397.169386)
		(end 154.365198 -397.60144)
		(width 0.14732)
		(layer "In15.Cu")
		(net "P5E_CPU1_PE2_TX_DP<4>")
	)
	(segment
		(start 127.242316 -216.260426)
		(end 127.242316 -216.25052)
		(width 0.0889)
		(layer "In15.Cu")
		(net "P5E_CPU1_PE2_TX_DP<4>")
	)
	(segment
		(start 126.959868 -217.388694)
		(end 126.950978 -217.383614)
		(width 0.0889)
		(layer "In15.Cu")
		(net "P5E_CPU1_PE2_TX_DP<4>")
	)
	(segment
		(start 125.362716 -222.780098)
		(end 125.362716 -222.761556)
		(width 0.0889)
		(layer "In15.Cu")
		(net "P5E_CPU1_PE2_TX_DP<4>")
	)
	(segment
		(start 154.145234 -400.563588)
		(end 153.850594 -400.858228)
		(width 0.14732)
		(layer "In15.Cu")
		(net "P5E_CPU1_PE2_TX_DP<4>")
	)
	(segment
		(start 158.9659 -330.906882)
		(end 161.627058 -345.997784)
		(width 0.14732)
		(layer "In15.Cu")
		(net "P5E_CPU1_PE2_TX_DP<4>")
	)
	(segment
		(start 124.01423 -224.118424)
		(end 124.10313 -224.094802)
		(width 0.0889)
		(layer "In15.Cu")
		(net "P5E_CPU1_PE2_TX_DP<4>")
	)
	(segment
		(start 155.154122 -393.304776)
		(end 155.15336 -393.304776)
		(width 0.14732)
		(layer "In15.Cu")
		(net "P5E_CPU1_PE2_TX_DP<4>")
	)
	(segment
		(start 123.857766 -224.389442)
		(end 124.01423 -224.118424)
		(width 0.0889)
		(layer "In15.Cu")
		(net "P5E_CPU1_PE2_TX_DP<4>")
	)
	(segment
		(start 154.573986 -397.0655)
		(end 154.431746 -397.169386)
		(width 0.14732)
		(layer "In15.Cu")
		(net "P5E_CPU1_PE2_TX_DP<4>")
	)
	(segment
		(start 154.602942 -396.059914)
		(end 154.536394 -396.491968)
		(width 0.14732)
		(layer "In15.Cu")
		(net "P5E_CPU1_PE2_TX_DP<4>")
	)
	(segment
		(start 127.712216 -213.242398)
		(end 127.754126 -213.200488)
		(width 0.0889)
		(layer "In15.Cu")
		(net "P5E_CPU1_PE2_TX_DP<4>")
	)
	(segment
		(start 127.754126 -213.015068)
		(end 128.846072 -211.923122)
		(width 0.14732)
		(layer "In15.Cu")
		(net "P5E_CPU1_PE2_TX_DP<4>")
	)
	(segment
		(start 126.020576 -219.994988)
		(end 126.02591 -219.99194)
		(width 0.0889)
		(layer "In15.Cu")
		(net "P5E_CPU1_PE2_TX_DP<4>")
	)
	(segment
		(start 127.242316 -217.878406)
		(end 127.242316 -217.859864)
		(width 0.0889)
		(layer "In15.Cu")
		(net "P5E_CPU1_PE2_TX_DP<4>")
	)
	(segment
		(start 155.086812 -393.736322)
		(end 155.087574 -393.736322)
		(width 0.14732)
		(layer "In15.Cu")
		(net "P5E_CPU1_PE2_TX_DP<4>")
	)
	(segment
		(start 155.049982 -393.16279)
		(end 155.154122 -393.304776)
		(width 0.14732)
		(layer "In15.Cu")
		(net "P5E_CPU1_PE2_TX_DP<4>")
	)
	(segment
		(start 125.071378 -223.256348)
		(end 125.080268 -223.251268)
		(width 0.0889)
		(layer "In15.Cu")
		(net "P5E_CPU1_PE2_TX_DP<4>")
	)
	(segment
		(start 126.959106 -216.740486)
		(end 126.959868 -216.739978)
		(width 0.0889)
		(layer "In15.Cu")
		(net "P5E_CPU1_PE2_TX_DP<4>")
	)
	(segment
		(start 152.91816 -248.316496)
		(end 153.090118 -253.435612)
		(width 0.14732)
		(layer "In15.Cu")
		(net "P5E_CPU1_PE2_TX_DP<4>")
	)
	(segment
		(start 126.010924 -221.628462)
		(end 126.019814 -221.623382)
		(width 0.0889)
		(layer "In15.Cu")
		(net "P5E_CPU1_PE2_TX_DP<4>")
	)
	(segment
		(start 127.711962 -215.452198)
		(end 127.711962 -215.436704)
		(width 0.0889)
		(layer "In15.Cu")
		(net "P5E_CPU1_PE2_TX_DP<4>")
	)
	(segment
		(start 148.162518 -221.491302)
		(end 149.640798 -226.604322)
		(width 0.14732)
		(layer "In15.Cu")
		(net "P5E_CPU1_PE2_TX_DP<4>")
	)
	(segment
		(start 125.832362 -221.963234)
		(end 125.832362 -221.94774)
		(width 0.0889)
		(layer "In15.Cu")
		(net "P5E_CPU1_PE2_TX_DP<4>")
	)
	(segment
		(start 154.91587 -394.846048)
		(end 154.916378 -394.846048)
		(width 0.14732)
		(layer "In15.Cu")
		(net "P5E_CPU1_PE2_TX_DP<4>")
	)
	(segment
		(start 155.15336 -393.304776)
		(end 155.086812 -393.736322)
		(width 0.14732)
		(layer "In15.Cu")
		(net "P5E_CPU1_PE2_TX_DP<4>")
	)
	(segment
		(start 127.754126 -213.17839)
		(end 127.754126 -213.015068)
		(width 0.14732)
		(layer "In15.Cu")
		(net "P5E_CPU1_PE2_TX_DP<4>")
	)
	(segment
		(start 148.90242 -308.854348)
		(end 152.18918 -322.925948)
		(width 0.14732)
		(layer "In15.Cu")
		(net "P5E_CPU1_PE2_TX_DP<4>")
	)
	(segment
		(start 126.481078 -219.18676)
		(end 126.489968 -219.18168)
		(width 0.0889)
		(layer "In15.Cu")
		(net "P5E_CPU1_PE2_TX_DP<4>")
	)
	(segment
		(start 155.25877 -392.626596)
		(end 155.11653 -392.730736)
		(width 0.14732)
		(layer "In15.Cu")
		(net "P5E_CPU1_PE2_TX_DP<4>")
	)
	(segment
		(start 142.09522 -213.464648)
		(end 148.162518 -221.491302)
		(width 0.14732)
		(layer "In15.Cu")
		(net "P5E_CPU1_PE2_TX_DP<4>")
	)
	(segment
		(start 127.890524 -215.117426)
		(end 127.899414 -215.112346)
		(width 0.0889)
		(layer "In15.Cu")
		(net "P5E_CPU1_PE2_TX_DP<4>")
	)
	(segment
		(start 154.640534 -396.633954)
		(end 154.64028 -396.6337)
		(width 0.14732)
		(layer "In15.Cu")
		(net "P5E_CPU1_PE2_TX_DP<4>")
	)
	(segment
		(start 154.745182 -395.955774)
		(end 154.602942 -396.059914)
		(width 0.14732)
		(layer "In15.Cu")
		(net "P5E_CPU1_PE2_TX_DP<4>")
	)
	(segment
		(start 154.744674 -395.955774)
		(end 154.745182 -395.955774)
		(width 0.14732)
		(layer "In15.Cu")
		(net "P5E_CPU1_PE2_TX_DP<4>")
	)
	(segment
		(start 126.019814 -219.995496)
		(end 126.020576 -219.994988)
		(width 0.0889)
		(layer "In15.Cu")
		(net "P5E_CPU1_PE2_TX_DP<4>")
	)
	(segment
		(start 154.774138 -394.950188)
		(end 154.70759 -395.382242)
		(width 0.14732)
		(layer "In15.Cu")
		(net "P5E_CPU1_PE2_TX_DP<4>")
	)
	(segment
		(start 126.772162 -218.707716)
		(end 126.772162 -218.692222)
		(width 0.0889)
		(layer "In15.Cu")
		(net "P5E_CPU1_PE2_TX_DP<4>")
	)
	(segment
		(start 154.469338 -397.743426)
		(end 154.145234 -399.84553)
		(width 0.14732)
		(layer "In15.Cu")
		(net "P5E_CPU1_PE2_TX_DP<4>")
	)
	(segment
		(start 155.087574 -393.736322)
		(end 154.945334 -393.840462)
		(width 0.14732)
		(layer "In15.Cu")
		(net "P5E_CPU1_PE2_TX_DP<4>")
	)
	(segment
		(start 135.914638 -210.904836)
		(end 139.005056 -212.184996)
		(width 0.14732)
		(layer "In15.Cu")
		(net "P5E_CPU1_PE2_TX_DP<4>")
	)
	(segment
		(start 154.64028 -396.6337)
		(end 154.573478 -397.0655)
		(width 0.14732)
		(layer "In15.Cu")
		(net "P5E_CPU1_PE2_TX_DP<4>")
	)
	(segment
		(start 160.942528 -349.883222)
		(end 159.755078 -363.462062)
		(width 0.14732)
		(layer "In15.Cu")
		(net "P5E_CPU1_PE2_TX_DP<4>")
	)
	(segment
		(start 127.420878 -215.931242)
		(end 127.429768 -215.926162)
		(width 0.0889)
		(layer "In15.Cu")
		(net "P5E_CPU1_PE2_TX_DP<4>")
	)
	(segment
		(start 126.302516 -221.133924)
		(end 126.302516 -221.1197)
		(width 0.0889)
		(layer "In15.Cu")
		(net "P5E_CPU1_PE2_TX_DP<4>")
	)
	(arc
		(start 126.02591 -221.619826)
		(mid 126.228497 -221.413475)
		(end 126.302516 -221.133924)
		(width 0.0889)
		(layer "In15.Cu")
		(net "P5E_CPU1_PE2_TX_DP<4>")
	)
	(arc
		(start 124.892816 -223.575626)
		(mid 124.940495 -223.392726)
		(end 125.071378 -223.256348)
		(width 0.0889)
		(layer "In15.Cu")
		(net "P5E_CPU1_PE2_TX_DP<4>")
	)
	(arc
		(start 124.10313 -224.094802)
		(mid 124.112997 -224.098961)
		(end 124.122942 -224.10293)
		(width 0.0889)
		(layer "In15.Cu")
		(net "P5E_CPU1_PE2_TX_DP<4>")
	)
	(arc
		(start 127.711962 -215.436704)
		(mid 127.712014 -215.429337)
		(end 127.712216 -215.421972)
		(width 0.0889)
		(layer "In15.Cu")
		(net "P5E_CPU1_PE2_TX_DP<4>")
	)
	(arc
		(start 126.019814 -220.644212)
		(mid 125.884881 -220.510858)
		(end 125.832616 -220.32849)
		(width 0.0889)
		(layer "In15.Cu")
		(net "P5E_CPU1_PE2_TX_DP<4>")
	)
	(arc
		(start 126.02591 -219.99194)
		(mid 126.228497 -219.785589)
		(end 126.302516 -219.506038)
		(width 0.0889)
		(layer "In15.Cu")
		(net "P5E_CPU1_PE2_TX_DP<4>")
	)
	(arc
		(start 126.302516 -221.1197)
		(mid 126.223297 -220.845015)
		(end 126.019814 -220.644212)
		(width 0.0889)
		(layer "In15.Cu")
		(net "P5E_CPU1_PE2_TX_DP<4>")
	)
	(arc
		(start 124.122942 -224.10293)
		(mid 124.370953 -224.139395)
		(end 124.610368 -224.065084)
		(width 0.0889)
		(layer "In15.Cu")
		(net "P5E_CPU1_PE2_TX_DP<4>")
	)
	(arc
		(start 125.362716 -222.761556)
		(mid 125.410395 -222.578656)
		(end 125.541278 -222.442278)
		(width 0.0889)
		(layer "In15.Cu")
		(net "P5E_CPU1_PE2_TX_DP<4>")
	)
	(arc
		(start 124.616464 -224.061528)
		(mid 124.818877 -223.855115)
		(end 124.892816 -223.575626)
		(width 0.0889)
		(layer "In15.Cu")
		(net "P5E_CPU1_PE2_TX_DP<4>")
	)
	(arc
		(start 125.832616 -220.311218)
		(mid 125.884886 -220.128853)
		(end 126.019814 -219.995496)
		(width 0.0889)
		(layer "In15.Cu")
		(net "P5E_CPU1_PE2_TX_DP<4>")
	)
	(arc
		(start 127.242316 -217.859864)
		(mid 127.162154 -217.587675)
		(end 126.959868 -217.388694)
		(width 0.0889)
		(layer "In15.Cu")
		(net "P5E_CPU1_PE2_TX_DP<4>")
	)
	(arc
		(start 126.96571 -218.364308)
		(mid 127.168297 -218.157957)
		(end 127.242316 -217.878406)
		(width 0.0889)
		(layer "In15.Cu")
		(net "P5E_CPU1_PE2_TX_DP<4>")
	)
	(arc
		(start 126.950978 -217.383614)
		(mid 126.772381 -217.064336)
		(end 126.950978 -216.745058)
		(width 0.0889)
		(layer "In15.Cu")
		(net "P5E_CPU1_PE2_TX_DP<4>")
	)
	(arc
		(start 125.550168 -222.437198)
		(mid 125.752991 -222.236967)
		(end 125.832362 -221.963234)
		(width 0.0889)
		(layer "In15.Cu")
		(net "P5E_CPU1_PE2_TX_DP<4>")
	)
	(arc
		(start 127.899414 -215.112346)
		(mid 128.100696 -214.914859)
		(end 128.181608 -214.644732)
		(width 0.0889)
		(layer "In15.Cu")
		(net "P5E_CPU1_PE2_TX_DP<4>")
	)
	(arc
		(start 126.959868 -216.739978)
		(mid 127.164203 -216.537373)
		(end 127.242316 -216.260426)
		(width 0.0889)
		(layer "In15.Cu")
		(net "P5E_CPU1_PE2_TX_DP<4>")
	)
	(arc
		(start 127.429768 -215.926162)
		(mid 127.632591 -215.725931)
		(end 127.711962 -215.452198)
		(width 0.0889)
		(layer "In15.Cu")
		(net "P5E_CPU1_PE2_TX_DP<4>")
	)
	(arc
		(start 125.080268 -223.251268)
		(mid 125.282554 -223.052287)
		(end 125.362716 -222.780098)
		(width 0.0889)
		(layer "In15.Cu")
		(net "P5E_CPU1_PE2_TX_DP<4>")
	)
	(arc
		(start 126.489968 -219.18168)
		(mid 126.692791 -218.981449)
		(end 126.772162 -218.707716)
		(width 0.0889)
		(layer "In15.Cu")
		(net "P5E_CPU1_PE2_TX_DP<4>")
	)
	(arc
		(start 127.896366 -214.093298)
		(mid 127.787219 -214.00937)
		(end 127.712216 -213.893908)
		(width 0.0889)
		(layer "In15.Cu")
		(net "P5E_CPU1_PE2_TX_DP<4>")
	)
	(arc
		(start 128.181608 -214.424768)
		(mid 128.070329 -214.232062)
		(end 127.896366 -214.093298)
		(width 0.0889)
		(layer "In15.Cu")
		(net "P5E_CPU1_PE2_TX_DP<4>")
	)
	(arc
		(start 126.772162 -218.692222)
		(mid 126.819841 -218.509322)
		(end 126.950724 -218.372944)
		(width 0.0889)
		(layer "In15.Cu")
		(net "P5E_CPU1_PE2_TX_DP<4>")
	)
	(arc
		(start 126.302516 -219.506038)
		(mid 126.350195 -219.323138)
		(end 126.481078 -219.18676)
		(width 0.0889)
		(layer "In15.Cu")
		(net "P5E_CPU1_PE2_TX_DP<4>")
	)
	(arc
		(start 127.242316 -216.25052)
		(mid 127.289995 -216.06762)
		(end 127.420878 -215.931242)
		(width 0.0889)
		(layer "In15.Cu")
		(net "P5E_CPU1_PE2_TX_DP<4>")
	)
	(arc
		(start 127.712216 -215.421972)
		(mid 127.76327 -215.247392)
		(end 127.890524 -215.117426)
		(width 0.0889)
		(layer "In15.Cu")
		(net "P5E_CPU1_PE2_TX_DP<4>")
	)
	(arc
		(start 125.832362 -221.94774)
		(mid 125.880041 -221.76484)
		(end 126.010924 -221.628462)
		(width 0.0889)
		(layer "In15.Cu")
		(net "P5E_CPU1_PE2_TX_DP<4>")
	)
	(segment
		(start 157.219396 -401.16379)
		(end 157.219396 -401.777962)
		(width 0.13208)
		(layer "F.Cu")
		(net "P5E_CPU1_PE2_TX_DP<3>")
	)
	(segment
		(start 156.893006 -402.104352)
		(end 156.888434 -402.104352)
		(width 0.13208)
		(layer "F.Cu")
		(net "P5E_CPU1_PE2_TX_DP<3>")
	)
	(segment
		(start 157.219396 -401.777962)
		(end 156.893006 -402.104352)
		(width 0.13208)
		(layer "F.Cu")
		(net "P5E_CPU1_PE2_TX_DP<3>")
	)
	(segment
		(start 123.387866 -225.739198)
		(end 123.387866 -225.203512)
		(width 0.13208)
		(layer "F.Cu")
		(net "P5E_CPU1_PE2_TX_DP<3>")
	)
	(segment
		(start 123.387866 -225.203512)
		(end 123.387612 -225.203258)
		(width 0.13208)
		(layer "F.Cu")
		(net "P5E_CPU1_PE2_TX_DP<3>")
	)
	(segment
		(start 156.913834 -400.858228)
		(end 157.219396 -401.16379)
		(width 0.13208)
		(layer "F.Cu")
		(net "P5E_CPU1_PE2_TX_DP<3>")
	)
	(segment
		(start 125.362716 -221.133924)
		(end 125.362716 -221.115382)
		(width 0.0889)
		(layer "In15.Cu")
		(net "P5E_CPU1_PE2_TX_DP<3>")
	)
	(segment
		(start 149.876002 -223.925892)
		(end 150.62962 -226.681792)
		(width 0.14732)
		(layer "In15.Cu")
		(net "P5E_CPU1_PE2_TX_DP<3>")
	)
	(segment
		(start 159.62376 -374.878854)
		(end 157.828234 -393.3063)
		(width 0.14732)
		(layer "In15.Cu")
		(net "P5E_CPU1_PE2_TX_DP<3>")
	)
	(segment
		(start 157.50159 -396.659354)
		(end 157.3657 -396.77086)
		(width 0.14732)
		(layer "In15.Cu")
		(net "P5E_CPU1_PE2_TX_DP<3>")
	)
	(segment
		(start 124.892562 -221.963234)
		(end 124.892562 -221.94774)
		(width 0.0889)
		(layer "In15.Cu")
		(net "P5E_CPU1_PE2_TX_DP<3>")
	)
	(segment
		(start 126.814326 -212.73389)
		(end 127.080772 -212.090762)
		(width 0.14732)
		(layer "In15.Cu")
		(net "P5E_CPU1_PE2_TX_DP<3>")
	)
	(segment
		(start 157.208474 -400.563588)
		(end 156.913834 -400.858228)
		(width 0.14732)
		(layer "In15.Cu")
		(net "P5E_CPU1_PE2_TX_DP<3>")
	)
	(segment
		(start 125.080268 -220.644212)
		(end 125.071378 -220.639132)
		(width 0.0889)
		(layer "In15.Cu")
		(net "P5E_CPU1_PE2_TX_DP<3>")
	)
	(segment
		(start 150.62962 -226.681792)
		(end 153.844498 -247.986296)
		(width 0.14732)
		(layer "In15.Cu")
		(net "P5E_CPU1_PE2_TX_DP<3>")
	)
	(segment
		(start 157.435042 -397.341852)
		(end 157.392878 -397.776446)
		(width 0.14732)
		(layer "In15.Cu")
		(net "P5E_CPU1_PE2_TX_DP<3>")
	)
	(segment
		(start 126.814326 -213.17839)
		(end 126.814326 -212.73389)
		(width 0.14732)
		(layer "In15.Cu")
		(net "P5E_CPU1_PE2_TX_DP<3>")
	)
	(segment
		(start 125.079506 -219.996004)
		(end 125.080268 -219.995496)
		(width 0.0889)
		(layer "In15.Cu")
		(net "P5E_CPU1_PE2_TX_DP<3>")
	)
	(segment
		(start 157.761686 -393.989052)
		(end 157.719522 -394.424154)
		(width 0.14732)
		(layer "In15.Cu")
		(net "P5E_CPU1_PE2_TX_DP<3>")
	)
	(segment
		(start 126.302516 -217.878406)
		(end 126.302516 -217.864182)
		(width 0.0889)
		(layer "In15.Cu")
		(net "P5E_CPU1_PE2_TX_DP<3>")
	)
	(segment
		(start 126.481078 -215.931242)
		(end 126.489968 -215.926162)
		(width 0.0889)
		(layer "In15.Cu")
		(net "P5E_CPU1_PE2_TX_DP<3>")
	)
	(segment
		(start 126.010924 -218.372944)
		(end 126.019814 -218.367864)
		(width 0.0889)
		(layer "In15.Cu")
		(net "P5E_CPU1_PE2_TX_DP<3>")
	)
	(segment
		(start 125.080014 -221.623382)
		(end 125.08611 -221.619826)
		(width 0.0889)
		(layer "In15.Cu")
		(net "P5E_CPU1_PE2_TX_DP<3>")
	)
	(segment
		(start 149.86254 -308.694328)
		(end 153.04262 -322.425568)
		(width 0.14732)
		(layer "In15.Cu")
		(net "P5E_CPU1_PE2_TX_DP<3>")
	)
	(segment
		(start 157.583632 -394.535914)
		(end 157.541214 -394.970762)
		(width 0.14732)
		(layer "In15.Cu")
		(net "P5E_CPU1_PE2_TX_DP<3>")
	)
	(segment
		(start 126.019814 -218.367864)
		(end 126.02591 -218.364308)
		(width 0.0889)
		(layer "In15.Cu")
		(net "P5E_CPU1_PE2_TX_DP<3>")
	)
	(segment
		(start 157.544008 -396.224506)
		(end 157.544008 -396.225268)
		(width 0.14732)
		(layer "In15.Cu")
		(net "P5E_CPU1_PE2_TX_DP<3>")
	)
	(segment
		(start 140.761212 -211.642198)
		(end 140.827252 -211.80171)
		(width 0.14732)
		(layer "In15.Cu")
		(net "P5E_CPU1_PE2_TX_DP<3>")
	)
	(segment
		(start 157.256734 -397.88846)
		(end 157.214316 -398.323562)
		(width 0.14732)
		(layer "In15.Cu")
		(net "P5E_CPU1_PE2_TX_DP<3>")
	)
	(segment
		(start 157.323282 -397.205962)
		(end 157.435042 -397.341852)
		(width 0.14732)
		(layer "In15.Cu")
		(net "P5E_CPU1_PE2_TX_DP<3>")
	)
	(segment
		(start 140.827252 -211.80171)
		(end 141.231112 -211.968842)
		(width 0.14732)
		(layer "In15.Cu")
		(net "P5E_CPU1_PE2_TX_DP<3>")
	)
	(segment
		(start 162.5854 -346.019882)
		(end 161.95167 -349.613982)
		(width 0.14732)
		(layer "In15.Cu")
		(net "P5E_CPU1_PE2_TX_DP<3>")
	)
	(segment
		(start 123.953016 -223.585532)
		(end 123.953016 -223.56699)
		(width 0.0889)
		(layer "In15.Cu")
		(net "P5E_CPU1_PE2_TX_DP<3>")
	)
	(segment
		(start 123.231148 -224.93224)
		(end 123.255278 -224.843086)
		(width 0.0889)
		(layer "In15.Cu")
		(net "P5E_CPU1_PE2_TX_DP<3>")
	)
	(segment
		(start 157.719522 -394.424154)
		(end 157.583632 -394.535914)
		(width 0.14732)
		(layer "In15.Cu")
		(net "P5E_CPU1_PE2_TX_DP<3>")
	)
	(segment
		(start 157.392878 -397.776446)
		(end 157.256734 -397.88846)
		(width 0.14732)
		(layer "In15.Cu")
		(net "P5E_CPU1_PE2_TX_DP<3>")
	)
	(segment
		(start 126.958598 -215.112854)
		(end 126.959614 -215.112346)
		(width 0.0889)
		(layer "In15.Cu")
		(net "P5E_CPU1_PE2_TX_DP<3>")
	)
	(segment
		(start 125.832362 -218.707716)
		(end 125.832362 -218.692222)
		(width 0.0889)
		(layer "In15.Cu")
		(net "P5E_CPU1_PE2_TX_DP<3>")
	)
	(segment
		(start 149.121876 -221.16796)
		(end 149.876002 -223.924622)
		(width 0.14732)
		(layer "In15.Cu")
		(net "P5E_CPU1_PE2_TX_DP<3>")
	)
	(segment
		(start 157.65018 -393.853162)
		(end 157.761686 -393.989052)
		(width 0.14732)
		(layer "In15.Cu")
		(net "P5E_CPU1_PE2_TX_DP<3>")
	)
	(segment
		(start 157.326076 -398.459452)
		(end 157.208474 -399.669508)
		(width 0.14732)
		(layer "In15.Cu")
		(net "P5E_CPU1_PE2_TX_DP<3>")
	)
	(segment
		(start 149.865842 -308.652672)
		(end 149.865588 -308.652672)
		(width 0.14732)
		(layer "In15.Cu")
		(net "P5E_CPU1_PE2_TX_DP<3>")
	)
	(segment
		(start 131.067556 -209.965036)
		(end 136.71169 -209.965036)
		(width 0.14732)
		(layer "In15.Cu")
		(net "P5E_CPU1_PE2_TX_DP<3>")
	)
	(segment
		(start 153.04262 -322.425568)
		(end 159.845756 -330.484226)
		(width 0.14732)
		(layer "In15.Cu")
		(net "P5E_CPU1_PE2_TX_DP<3>")
	)
	(segment
		(start 124.601478 -222.442278)
		(end 124.610368 -222.437198)
		(width 0.0889)
		(layer "In15.Cu")
		(net "P5E_CPU1_PE2_TX_DP<3>")
	)
	(segment
		(start 157.541214 -394.970762)
		(end 157.652974 -395.106906)
		(width 0.14732)
		(layer "In15.Cu")
		(net "P5E_CPU1_PE2_TX_DP<3>")
	)
	(segment
		(start 123.661678 -224.070164)
		(end 123.670568 -224.065084)
		(width 0.0889)
		(layer "In15.Cu")
		(net "P5E_CPU1_PE2_TX_DP<3>")
	)
	(segment
		(start 126.814326 -213.200488)
		(end 126.814326 -213.17839)
		(width 0.0889)
		(layer "In15.Cu")
		(net "P5E_CPU1_PE2_TX_DP<3>")
	)
	(segment
		(start 127.241808 -214.644732)
		(end 127.241808 -214.424768)
		(width 0.0889)
		(layer "In15.Cu")
		(net "P5E_CPU1_PE2_TX_DP<3>")
	)
	(segment
		(start 123.387612 -225.203258)
		(end 123.231148 -224.93224)
		(width 0.0889)
		(layer "In15.Cu")
		(net "P5E_CPU1_PE2_TX_DP<3>")
	)
	(segment
		(start 157.3657 -396.77086)
		(end 157.323282 -397.205962)
		(width 0.14732)
		(layer "In15.Cu")
		(net "P5E_CPU1_PE2_TX_DP<3>")
	)
	(segment
		(start 157.544008 -396.225268)
		(end 157.50159 -396.659354)
		(width 0.14732)
		(layer "In15.Cu")
		(net "P5E_CPU1_PE2_TX_DP<3>")
	)
	(segment
		(start 159.89935 -373.320564)
		(end 159.62376 -374.878854)
		(width 0.14732)
		(layer "In15.Cu")
		(net "P5E_CPU1_PE2_TX_DP<3>")
	)
	(segment
		(start 161.95167 -349.613982)
		(end 159.89935 -373.320564)
		(width 0.14732)
		(layer "In15.Cu")
		(net "P5E_CPU1_PE2_TX_DP<3>")
	)
	(segment
		(start 126.019814 -216.739978)
		(end 126.020576 -216.73947)
		(width 0.0889)
		(layer "In15.Cu")
		(net "P5E_CPU1_PE2_TX_DP<3>")
	)
	(segment
		(start 125.541278 -219.18676)
		(end 125.550168 -219.18168)
		(width 0.0889)
		(layer "In15.Cu")
		(net "P5E_CPU1_PE2_TX_DP<3>")
	)
	(segment
		(start 126.772416 -213.242398)
		(end 126.814326 -213.200488)
		(width 0.0889)
		(layer "In15.Cu")
		(net "P5E_CPU1_PE2_TX_DP<3>")
	)
	(segment
		(start 126.772416 -213.893908)
		(end 126.772416 -213.242398)
		(width 0.0889)
		(layer "In15.Cu")
		(net "P5E_CPU1_PE2_TX_DP<3>")
	)
	(segment
		(start 149.876002 -223.924622)
		(end 149.875748 -223.924876)
		(width 0.14732)
		(layer "In15.Cu")
		(net "P5E_CPU1_PE2_TX_DP<3>")
	)
	(segment
		(start 157.652974 -395.106906)
		(end 157.610556 -395.541754)
		(width 0.14732)
		(layer "In15.Cu")
		(net "P5E_CPU1_PE2_TX_DP<3>")
	)
	(segment
		(start 154.036776 -253.69901)
		(end 149.865842 -308.652672)
		(width 0.14732)
		(layer "In15.Cu")
		(net "P5E_CPU1_PE2_TX_DP<3>")
	)
	(segment
		(start 141.39037 -211.902802)
		(end 142.44828 -212.340952)
		(width 0.14732)
		(layer "In15.Cu")
		(net "P5E_CPU1_PE2_TX_DP<3>")
	)
	(segment
		(start 157.828234 -393.3063)
		(end 157.828742 -393.3063)
		(width 0.14732)
		(layer "In15.Cu")
		(net "P5E_CPU1_PE2_TX_DP<3>")
	)
	(segment
		(start 124.422916 -222.77578)
		(end 124.422916 -222.761556)
		(width 0.0889)
		(layer "In15.Cu")
		(net "P5E_CPU1_PE2_TX_DP<3>")
	)
	(segment
		(start 159.845756 -330.484226)
		(end 162.5854 -346.019882)
		(width 0.14732)
		(layer "In15.Cu")
		(net "P5E_CPU1_PE2_TX_DP<3>")
	)
	(segment
		(start 125.071124 -221.628462)
		(end 125.080014 -221.623382)
		(width 0.0889)
		(layer "In15.Cu")
		(net "P5E_CPU1_PE2_TX_DP<3>")
	)
	(segment
		(start 142.44828 -212.340952)
		(end 149.121876 -221.16796)
		(width 0.14732)
		(layer "In15.Cu")
		(net "P5E_CPU1_PE2_TX_DP<3>")
	)
	(segment
		(start 126.020576 -216.73947)
		(end 126.02591 -216.736422)
		(width 0.0889)
		(layer "In15.Cu")
		(net "P5E_CPU1_PE2_TX_DP<3>")
	)
	(segment
		(start 127.890778 -211.280756)
		(end 131.067556 -209.965036)
		(width 0.14732)
		(layer "In15.Cu")
		(net "P5E_CPU1_PE2_TX_DP<3>")
	)
	(segment
		(start 126.772162 -215.452198)
		(end 126.772162 -215.436704)
		(width 0.0889)
		(layer "In15.Cu")
		(net "P5E_CPU1_PE2_TX_DP<3>")
	)
	(segment
		(start 125.362716 -219.515944)
		(end 125.362716 -219.506038)
		(width 0.0889)
		(layer "In15.Cu")
		(net "P5E_CPU1_PE2_TX_DP<3>")
	)
	(segment
		(start 149.865588 -308.652672)
		(end 149.86254 -308.694328)
		(width 0.14732)
		(layer "In15.Cu")
		(net "P5E_CPU1_PE2_TX_DP<3>")
	)
	(segment
		(start 138.736832 -210.803744)
		(end 138.736578 -210.803744)
		(width 0.14732)
		(layer "In15.Cu")
		(net "P5E_CPU1_PE2_TX_DP<3>")
	)
	(segment
		(start 153.844498 -247.986296)
		(end 154.036776 -253.69901)
		(width 0.14732)
		(layer "In15.Cu")
		(net "P5E_CPU1_PE2_TX_DP<3>")
	)
	(segment
		(start 157.474666 -395.653514)
		(end 157.432248 -396.088362)
		(width 0.14732)
		(layer "In15.Cu")
		(net "P5E_CPU1_PE2_TX_DP<3>")
	)
	(segment
		(start 127.080772 -212.090762)
		(end 127.890778 -211.280756)
		(width 0.14732)
		(layer "In15.Cu")
		(net "P5E_CPU1_PE2_TX_DP<3>")
	)
	(segment
		(start 125.071378 -220.000576)
		(end 125.079506 -219.996004)
		(width 0.0889)
		(layer "In15.Cu")
		(net "P5E_CPU1_PE2_TX_DP<3>")
	)
	(segment
		(start 149.875748 -223.924876)
		(end 149.876002 -223.925892)
		(width 0.14732)
		(layer "In15.Cu")
		(net "P5E_CPU1_PE2_TX_DP<3>")
	)
	(segment
		(start 157.828742 -393.3063)
		(end 157.692598 -393.418314)
		(width 0.14732)
		(layer "In15.Cu")
		(net "P5E_CPU1_PE2_TX_DP<3>")
	)
	(segment
		(start 157.610556 -395.541754)
		(end 157.474666 -395.653514)
		(width 0.14732)
		(layer "In15.Cu")
		(net "P5E_CPU1_PE2_TX_DP<3>")
	)
	(segment
		(start 157.214316 -398.323562)
		(end 157.326076 -398.459452)
		(width 0.14732)
		(layer "In15.Cu")
		(net "P5E_CPU1_PE2_TX_DP<3>")
	)
	(segment
		(start 141.231112 -211.968842)
		(end 141.39037 -211.902802)
		(width 0.14732)
		(layer "In15.Cu")
		(net "P5E_CPU1_PE2_TX_DP<3>")
	)
	(segment
		(start 125.832616 -217.072972)
		(end 125.832616 -217.0557)
		(width 0.0889)
		(layer "In15.Cu")
		(net "P5E_CPU1_PE2_TX_DP<3>")
	)
	(segment
		(start 136.71169 -209.965036)
		(end 138.736832 -210.803744)
		(width 0.14732)
		(layer "In15.Cu")
		(net "P5E_CPU1_PE2_TX_DP<3>")
	)
	(segment
		(start 126.950724 -215.117426)
		(end 126.958598 -215.112854)
		(width 0.0889)
		(layer "In15.Cu")
		(net "P5E_CPU1_PE2_TX_DP<3>")
	)
	(segment
		(start 157.432248 -396.088362)
		(end 157.544008 -396.224506)
		(width 0.14732)
		(layer "In15.Cu")
		(net "P5E_CPU1_PE2_TX_DP<3>")
	)
	(segment
		(start 138.736578 -210.803744)
		(end 140.761212 -211.642198)
		(width 0.14732)
		(layer "In15.Cu")
		(net "P5E_CPU1_PE2_TX_DP<3>")
	)
	(segment
		(start 157.208474 -399.669508)
		(end 157.208474 -400.563588)
		(width 0.14732)
		(layer "In15.Cu")
		(net "P5E_CPU1_PE2_TX_DP<3>")
	)
	(segment
		(start 157.692598 -393.418314)
		(end 157.65018 -393.853162)
		(width 0.14732)
		(layer "In15.Cu")
		(net "P5E_CPU1_PE2_TX_DP<3>")
	)
	(arc
		(start 126.489968 -215.926162)
		(mid 126.692791 -215.725931)
		(end 126.772162 -215.452198)
		(width 0.0889)
		(layer "In15.Cu")
		(net "P5E_CPU1_PE2_TX_DP<3>")
	)
	(arc
		(start 127.241808 -214.424768)
		(mid 127.130529 -214.232062)
		(end 126.956566 -214.093298)
		(width 0.0889)
		(layer "In15.Cu")
		(net "P5E_CPU1_PE2_TX_DP<3>")
	)
	(arc
		(start 126.959614 -215.112346)
		(mid 127.160896 -214.914859)
		(end 127.241808 -214.644732)
		(width 0.0889)
		(layer "In15.Cu")
		(net "P5E_CPU1_PE2_TX_DP<3>")
	)
	(arc
		(start 126.772416 -215.421972)
		(mid 126.82347 -215.247392)
		(end 126.950724 -215.117426)
		(width 0.0889)
		(layer "In15.Cu")
		(net "P5E_CPU1_PE2_TX_DP<3>")
	)
	(arc
		(start 126.02591 -216.736422)
		(mid 126.228497 -216.530071)
		(end 126.302516 -216.25052)
		(width 0.0889)
		(layer "In15.Cu")
		(net "P5E_CPU1_PE2_TX_DP<3>")
	)
	(arc
		(start 123.483116 -224.389442)
		(mid 123.530795 -224.206542)
		(end 123.661678 -224.070164)
		(width 0.0889)
		(layer "In15.Cu")
		(net "P5E_CPU1_PE2_TX_DP<3>")
	)
	(arc
		(start 125.832362 -218.692222)
		(mid 125.880041 -218.509322)
		(end 126.010924 -218.372944)
		(width 0.0889)
		(layer "In15.Cu")
		(net "P5E_CPU1_PE2_TX_DP<3>")
	)
	(arc
		(start 124.610368 -222.437198)
		(mid 124.813191 -222.236967)
		(end 124.892562 -221.963234)
		(width 0.0889)
		(layer "In15.Cu")
		(net "P5E_CPU1_PE2_TX_DP<3>")
	)
	(arc
		(start 126.956566 -214.093298)
		(mid 126.847419 -214.00937)
		(end 126.772416 -213.893908)
		(width 0.0889)
		(layer "In15.Cu")
		(net "P5E_CPU1_PE2_TX_DP<3>")
	)
	(arc
		(start 126.02591 -218.364308)
		(mid 126.228497 -218.157957)
		(end 126.302516 -217.878406)
		(width 0.0889)
		(layer "In15.Cu")
		(net "P5E_CPU1_PE2_TX_DP<3>")
	)
	(arc
		(start 125.832616 -217.0557)
		(mid 125.884886 -216.873335)
		(end 126.019814 -216.739978)
		(width 0.0889)
		(layer "In15.Cu")
		(net "P5E_CPU1_PE2_TX_DP<3>")
	)
	(arc
		(start 125.08611 -221.619826)
		(mid 125.288697 -221.413475)
		(end 125.362716 -221.133924)
		(width 0.0889)
		(layer "In15.Cu")
		(net "P5E_CPU1_PE2_TX_DP<3>")
	)
	(arc
		(start 124.892562 -221.94774)
		(mid 124.940241 -221.76484)
		(end 125.071124 -221.628462)
		(width 0.0889)
		(layer "In15.Cu")
		(net "P5E_CPU1_PE2_TX_DP<3>")
	)
	(arc
		(start 124.422916 -222.761556)
		(mid 124.470595 -222.578656)
		(end 124.601478 -222.442278)
		(width 0.0889)
		(layer "In15.Cu")
		(net "P5E_CPU1_PE2_TX_DP<3>")
	)
	(arc
		(start 125.550168 -219.18168)
		(mid 125.752991 -218.981449)
		(end 125.832362 -218.707716)
		(width 0.0889)
		(layer "In15.Cu")
		(net "P5E_CPU1_PE2_TX_DP<3>")
	)
	(arc
		(start 126.772162 -215.436704)
		(mid 126.772214 -215.429337)
		(end 126.772416 -215.421972)
		(width 0.0889)
		(layer "In15.Cu")
		(net "P5E_CPU1_PE2_TX_DP<3>")
	)
	(arc
		(start 125.362716 -221.115382)
		(mid 125.282554 -220.843193)
		(end 125.080268 -220.644212)
		(width 0.0889)
		(layer "In15.Cu")
		(net "P5E_CPU1_PE2_TX_DP<3>")
	)
	(arc
		(start 125.071378 -220.639132)
		(mid 124.940464 -220.502772)
		(end 124.892816 -220.319854)
		(width 0.0889)
		(layer "In15.Cu")
		(net "P5E_CPU1_PE2_TX_DP<3>")
	)
	(arc
		(start 125.362716 -219.506038)
		(mid 125.410395 -219.323138)
		(end 125.541278 -219.18676)
		(width 0.0889)
		(layer "In15.Cu")
		(net "P5E_CPU1_PE2_TX_DP<3>")
	)
	(arc
		(start 123.670568 -224.065084)
		(mid 123.874903 -223.862479)
		(end 123.953016 -223.585532)
		(width 0.0889)
		(layer "In15.Cu")
		(net "P5E_CPU1_PE2_TX_DP<3>")
	)
	(arc
		(start 126.302516 -217.864182)
		(mid 126.223297 -217.589497)
		(end 126.019814 -217.388694)
		(width 0.0889)
		(layer "In15.Cu")
		(net "P5E_CPU1_PE2_TX_DP<3>")
	)
	(arc
		(start 123.255278 -224.843086)
		(mid 123.26385 -224.836564)
		(end 123.272296 -224.829878)
		(width 0.0889)
		(layer "In15.Cu")
		(net "P5E_CPU1_PE2_TX_DP<3>")
	)
	(arc
		(start 126.019814 -217.388694)
		(mid 125.884881 -217.25534)
		(end 125.832616 -217.072972)
		(width 0.0889)
		(layer "In15.Cu")
		(net "P5E_CPU1_PE2_TX_DP<3>")
	)
	(arc
		(start 124.140214 -223.251268)
		(mid 124.343695 -223.050464)
		(end 124.422916 -222.77578)
		(width 0.0889)
		(layer "In15.Cu")
		(net "P5E_CPU1_PE2_TX_DP<3>")
	)
	(arc
		(start 123.272296 -224.829878)
		(mid 123.427694 -224.633597)
		(end 123.483116 -224.389442)
		(width 0.0889)
		(layer "In15.Cu")
		(net "P5E_CPU1_PE2_TX_DP<3>")
	)
	(arc
		(start 123.953016 -223.56699)
		(mid 124.005286 -223.384625)
		(end 124.140214 -223.251268)
		(width 0.0889)
		(layer "In15.Cu")
		(net "P5E_CPU1_PE2_TX_DP<3>")
	)
	(arc
		(start 125.080268 -219.995496)
		(mid 125.284603 -219.792891)
		(end 125.362716 -219.515944)
		(width 0.0889)
		(layer "In15.Cu")
		(net "P5E_CPU1_PE2_TX_DP<3>")
	)
	(arc
		(start 126.302516 -216.25052)
		(mid 126.350195 -216.06762)
		(end 126.481078 -215.931242)
		(width 0.0889)
		(layer "In15.Cu")
		(net "P5E_CPU1_PE2_TX_DP<3>")
	)
	(arc
		(start 124.892816 -220.319854)
		(mid 124.940495 -220.136954)
		(end 125.071378 -220.000576)
		(width 0.0889)
		(layer "In15.Cu")
		(net "P5E_CPU1_PE2_TX_DP<3>")
	)
	(segment
		(start 159.956246 -402.104352)
		(end 159.951674 -402.104352)
		(width 0.13208)
		(layer "F.Cu")
		(net "P5E_CPU1_PE2_TX_DP<2>")
	)
	(segment
		(start 121.978166 -224.925128)
		(end 121.978166 -224.389442)
		(width 0.13208)
		(layer "F.Cu")
		(net "P5E_CPU1_PE2_TX_DP<2>")
	)
	(segment
		(start 159.977074 -400.858228)
		(end 160.282636 -401.16379)
		(width 0.13208)
		(layer "F.Cu")
		(net "P5E_CPU1_PE2_TX_DP<2>")
	)
	(segment
		(start 160.282636 -401.777962)
		(end 159.956246 -402.104352)
		(width 0.13208)
		(layer "F.Cu")
		(net "P5E_CPU1_PE2_TX_DP<2>")
	)
	(segment
		(start 160.282636 -401.16379)
		(end 160.282636 -401.777962)
		(width 0.13208)
		(layer "F.Cu")
		(net "P5E_CPU1_PE2_TX_DP<2>")
	)
	(segment
		(start 121.977912 -224.925382)
		(end 121.978166 -224.925128)
		(width 0.13208)
		(layer "F.Cu")
		(net "P5E_CPU1_PE2_TX_DP<2>")
	)
	(segment
		(start 122.730768 -224.065084)
		(end 122.736864 -224.061528)
		(width 0.0889)
		(layer "In15.Cu")
		(net "P5E_CPU1_PE2_TX_DP<2>")
	)
	(segment
		(start 125.362716 -216.260426)
		(end 125.362716 -216.25052)
		(width 0.0889)
		(layer "In15.Cu")
		(net "P5E_CPU1_PE2_TX_DP<2>")
	)
	(segment
		(start 126.294134 -211.49818)
		(end 127.325882 -210.466432)
		(width 0.14732)
		(layer "In15.Cu")
		(net "P5E_CPU1_PE2_TX_DP<2>")
	)
	(segment
		(start 124.140976 -219.994988)
		(end 124.14631 -219.99194)
		(width 0.0889)
		(layer "In15.Cu")
		(net "P5E_CPU1_PE2_TX_DP<2>")
	)
	(segment
		(start 153.89098 -321.897248)
		(end 160.72358 -330.048616)
		(width 0.14732)
		(layer "In15.Cu")
		(net "P5E_CPU1_PE2_TX_DP<2>")
	)
	(segment
		(start 125.541278 -215.931242)
		(end 125.550168 -215.926162)
		(width 0.0889)
		(layer "In15.Cu")
		(net "P5E_CPU1_PE2_TX_DP<2>")
	)
	(segment
		(start 160.401 -395.043152)
		(end 160.378648 -395.479524)
		(width 0.14732)
		(layer "In15.Cu")
		(net "P5E_CPU1_PE2_TX_DP<2>")
	)
	(segment
		(start 136.759442 -208.949036)
		(end 139.90955 -210.253834)
		(width 0.14732)
		(layer "In15.Cu")
		(net "P5E_CPU1_PE2_TX_DP<2>")
	)
	(segment
		(start 125.874526 -213.17839)
		(end 125.874526 -212.511132)
		(width 0.14732)
		(layer "In15.Cu")
		(net "P5E_CPU1_PE2_TX_DP<2>")
	)
	(segment
		(start 160.496504 -395.610334)
		(end 160.474152 -396.046452)
		(width 0.14732)
		(layer "In15.Cu")
		(net "P5E_CPU1_PE2_TX_DP<2>")
	)
	(segment
		(start 160.320736 -396.600934)
		(end 160.438592 -396.731744)
		(width 0.14732)
		(layer "In15.Cu")
		(net "P5E_CPU1_PE2_TX_DP<2>")
	)
	(segment
		(start 160.646872 -392.68146)
		(end 160.647888 -392.682222)
		(width 0.14732)
		(layer "In15.Cu")
		(net "P5E_CPU1_PE2_TX_DP<2>")
	)
	(segment
		(start 160.43656 -394.358114)
		(end 160.554416 -394.488924)
		(width 0.14732)
		(layer "In15.Cu")
		(net "P5E_CPU1_PE2_TX_DP<2>")
	)
	(segment
		(start 160.532064 -394.925042)
		(end 160.401 -395.043152)
		(width 0.14732)
		(layer "In15.Cu")
		(net "P5E_CPU1_PE2_TX_DP<2>")
	)
	(segment
		(start 126.018798 -215.112854)
		(end 126.019814 -215.112346)
		(width 0.0889)
		(layer "In15.Cu")
		(net "P5E_CPU1_PE2_TX_DP<2>")
	)
	(segment
		(start 162.769042 -351.455482)
		(end 160.646872 -392.68146)
		(width 0.14732)
		(layer "In15.Cu")
		(net "P5E_CPU1_PE2_TX_DP<2>")
	)
	(segment
		(start 125.832616 -213.894416)
		(end 125.832616 -213.242398)
		(width 0.0889)
		(layer "In15.Cu")
		(net "P5E_CPU1_PE2_TX_DP<2>")
	)
	(segment
		(start 125.362716 -217.878406)
		(end 125.362716 -217.859864)
		(width 0.0889)
		(layer "In15.Cu")
		(net "P5E_CPU1_PE2_TX_DP<2>")
	)
	(segment
		(start 160.262824 -397.722344)
		(end 160.38068 -397.8529)
		(width 0.14732)
		(layer "In15.Cu")
		(net "P5E_CPU1_PE2_TX_DP<2>")
	)
	(segment
		(start 160.516824 -392.800332)
		(end 160.494472 -393.236704)
		(width 0.14732)
		(layer "In15.Cu")
		(net "P5E_CPU1_PE2_TX_DP<2>")
	)
	(segment
		(start 160.41624 -397.167862)
		(end 160.28543 -397.285718)
		(width 0.14732)
		(layer "In15.Cu")
		(net "P5E_CPU1_PE2_TX_DP<2>")
	)
	(segment
		(start 125.079506 -216.740486)
		(end 125.080268 -216.739978)
		(width 0.0889)
		(layer "In15.Cu")
		(net "P5E_CPU1_PE2_TX_DP<2>")
	)
	(segment
		(start 126.010924 -215.117426)
		(end 126.018798 -215.112854)
		(width 0.0889)
		(layer "In15.Cu")
		(net "P5E_CPU1_PE2_TX_DP<2>")
	)
	(segment
		(start 160.271714 -400.563588)
		(end 159.977074 -400.858228)
		(width 0.14732)
		(layer "In15.Cu")
		(net "P5E_CPU1_PE2_TX_DP<2>")
	)
	(segment
		(start 150.109428 -220.765878)
		(end 151.722328 -226.783392)
		(width 0.14732)
		(layer "In15.Cu")
		(net "P5E_CPU1_PE2_TX_DP<2>")
	)
	(segment
		(start 124.422916 -221.133924)
		(end 124.422916 -221.1197)
		(width 0.0889)
		(layer "In15.Cu")
		(net "P5E_CPU1_PE2_TX_DP<2>")
	)
	(segment
		(start 160.554416 -394.488924)
		(end 160.532064 -394.925042)
		(width 0.14732)
		(layer "In15.Cu")
		(net "P5E_CPU1_PE2_TX_DP<2>")
	)
	(segment
		(start 125.071124 -218.372944)
		(end 125.080014 -218.367864)
		(width 0.0889)
		(layer "In15.Cu")
		(net "P5E_CPU1_PE2_TX_DP<2>")
	)
	(segment
		(start 160.72358 -330.048616)
		(end 163.536376 -345.998292)
		(width 0.14732)
		(layer "In15.Cu")
		(net "P5E_CPU1_PE2_TX_DP<2>")
	)
	(segment
		(start 125.832362 -215.452198)
		(end 125.832362 -215.436704)
		(width 0.0889)
		(layer "In15.Cu")
		(net "P5E_CPU1_PE2_TX_DP<2>")
	)
	(segment
		(start 126.302008 -214.644732)
		(end 126.302008 -214.425022)
		(width 0.0889)
		(layer "In15.Cu")
		(net "P5E_CPU1_PE2_TX_DP<2>")
	)
	(segment
		(start 154.766264 -246.95531)
		(end 154.986228 -253.490476)
		(width 0.14732)
		(layer "In15.Cu")
		(net "P5E_CPU1_PE2_TX_DP<2>")
	)
	(segment
		(start 160.589976 -393.803632)
		(end 160.458912 -393.921742)
		(width 0.14732)
		(layer "In15.Cu")
		(net "P5E_CPU1_PE2_TX_DP<2>")
	)
	(segment
		(start 125.080014 -218.367864)
		(end 125.08611 -218.364308)
		(width 0.0889)
		(layer "In15.Cu")
		(net "P5E_CPU1_PE2_TX_DP<2>")
	)
	(segment
		(start 125.874526 -213.200488)
		(end 125.874526 -213.17839)
		(width 0.0889)
		(layer "In15.Cu")
		(net "P5E_CPU1_PE2_TX_DP<2>")
	)
	(segment
		(start 125.071378 -216.745058)
		(end 125.079506 -216.740486)
		(width 0.0889)
		(layer "In15.Cu")
		(net "P5E_CPU1_PE2_TX_DP<2>")
	)
	(segment
		(start 160.474152 -396.046452)
		(end 160.343088 -396.164562)
		(width 0.14732)
		(layer "In15.Cu")
		(net "P5E_CPU1_PE2_TX_DP<2>")
	)
	(segment
		(start 124.892562 -218.707716)
		(end 124.892562 -218.692222)
		(width 0.0889)
		(layer "In15.Cu")
		(net "P5E_CPU1_PE2_TX_DP<2>")
	)
	(segment
		(start 151.722328 -226.783392)
		(end 154.766264 -246.95531)
		(width 0.14732)
		(layer "In15.Cu")
		(net "P5E_CPU1_PE2_TX_DP<2>")
	)
	(segment
		(start 160.271714 -399.974816)
		(end 160.271714 -400.563588)
		(width 0.14732)
		(layer "In15.Cu")
		(net "P5E_CPU1_PE2_TX_DP<2>")
	)
	(segment
		(start 154.986228 -253.490476)
		(end 150.84552 -308.546754)
		(width 0.14732)
		(layer "In15.Cu")
		(net "P5E_CPU1_PE2_TX_DP<2>")
	)
	(segment
		(start 124.140214 -219.995496)
		(end 124.140976 -219.994988)
		(width 0.0889)
		(layer "In15.Cu")
		(net "P5E_CPU1_PE2_TX_DP<2>")
	)
	(segment
		(start 160.612328 -393.367514)
		(end 160.589976 -393.803632)
		(width 0.14732)
		(layer "In15.Cu")
		(net "P5E_CPU1_PE2_TX_DP<2>")
	)
	(segment
		(start 123.661678 -222.442278)
		(end 123.670568 -222.437198)
		(width 0.0889)
		(layer "In15.Cu")
		(net "P5E_CPU1_PE2_TX_DP<2>")
	)
	(segment
		(start 160.458912 -393.921742)
		(end 160.43656 -394.358114)
		(width 0.14732)
		(layer "In15.Cu")
		(net "P5E_CPU1_PE2_TX_DP<2>")
	)
	(segment
		(start 123.483116 -222.780098)
		(end 123.483116 -222.761556)
		(width 0.0889)
		(layer "In15.Cu")
		(net "P5E_CPU1_PE2_TX_DP<2>")
	)
	(segment
		(start 124.140214 -221.623382)
		(end 124.14631 -221.619826)
		(width 0.0889)
		(layer "In15.Cu")
		(net "P5E_CPU1_PE2_TX_DP<2>")
	)
	(segment
		(start 160.494472 -393.236704)
		(end 160.612328 -393.367514)
		(width 0.14732)
		(layer "In15.Cu")
		(net "P5E_CPU1_PE2_TX_DP<2>")
	)
	(segment
		(start 123.191778 -223.256348)
		(end 123.200668 -223.251268)
		(width 0.0889)
		(layer "In15.Cu")
		(net "P5E_CPU1_PE2_TX_DP<2>")
	)
	(segment
		(start 160.378648 -395.479524)
		(end 160.496504 -395.610334)
		(width 0.14732)
		(layer "In15.Cu")
		(net "P5E_CPU1_PE2_TX_DP<2>")
	)
	(segment
		(start 139.90955 -210.253834)
		(end 139.909296 -210.253834)
		(width 0.14732)
		(layer "In15.Cu")
		(net "P5E_CPU1_PE2_TX_DP<2>")
	)
	(segment
		(start 139.909296 -210.253834)
		(end 143.058896 -211.558378)
		(width 0.14732)
		(layer "In15.Cu")
		(net "P5E_CPU1_PE2_TX_DP<2>")
	)
	(segment
		(start 125.832616 -213.242398)
		(end 125.874526 -213.200488)
		(width 0.0889)
		(layer "In15.Cu")
		(net "P5E_CPU1_PE2_TX_DP<2>")
	)
	(segment
		(start 123.953016 -220.32849)
		(end 123.953016 -220.311218)
		(width 0.0889)
		(layer "In15.Cu")
		(net "P5E_CPU1_PE2_TX_DP<2>")
	)
	(segment
		(start 160.343088 -396.164562)
		(end 160.320736 -396.600934)
		(width 0.14732)
		(layer "In15.Cu")
		(net "P5E_CPU1_PE2_TX_DP<2>")
	)
	(segment
		(start 162.960812 -349.26397)
		(end 162.769042 -351.455482)
		(width 0.14732)
		(layer "In15.Cu")
		(net "P5E_CPU1_PE2_TX_DP<2>")
	)
	(segment
		(start 122.13463 -224.118424)
		(end 122.22353 -224.094802)
		(width 0.0889)
		(layer "In15.Cu")
		(net "P5E_CPU1_PE2_TX_DP<2>")
	)
	(segment
		(start 121.978166 -224.389442)
		(end 122.13463 -224.118424)
		(width 0.0889)
		(layer "In15.Cu")
		(net "P5E_CPU1_PE2_TX_DP<2>")
	)
	(segment
		(start 124.601478 -219.18676)
		(end 124.610368 -219.18168)
		(width 0.0889)
		(layer "In15.Cu")
		(net "P5E_CPU1_PE2_TX_DP<2>")
	)
	(segment
		(start 160.647888 -392.682222)
		(end 160.516824 -392.800332)
		(width 0.14732)
		(layer "In15.Cu")
		(net "P5E_CPU1_PE2_TX_DP<2>")
	)
	(segment
		(start 124.131324 -221.628462)
		(end 124.140214 -221.623382)
		(width 0.0889)
		(layer "In15.Cu")
		(net "P5E_CPU1_PE2_TX_DP<2>")
	)
	(segment
		(start 125.874526 -212.511132)
		(end 126.294134 -211.49818)
		(width 0.14732)
		(layer "In15.Cu")
		(net "P5E_CPU1_PE2_TX_DP<2>")
	)
	(segment
		(start 150.84552 -308.546754)
		(end 153.89098 -321.897248)
		(width 0.14732)
		(layer "In15.Cu")
		(net "P5E_CPU1_PE2_TX_DP<2>")
	)
	(segment
		(start 125.080268 -217.388694)
		(end 125.071378 -217.383614)
		(width 0.0889)
		(layer "In15.Cu")
		(net "P5E_CPU1_PE2_TX_DP<2>")
	)
	(segment
		(start 163.536376 -345.998292)
		(end 162.960812 -349.26397)
		(width 0.14732)
		(layer "In15.Cu")
		(net "P5E_CPU1_PE2_TX_DP<2>")
	)
	(segment
		(start 127.325882 -210.466432)
		(end 130.989578 -208.949036)
		(width 0.14732)
		(layer "In15.Cu")
		(net "P5E_CPU1_PE2_TX_DP<2>")
	)
	(segment
		(start 143.058896 -211.558378)
		(end 150.109428 -220.765878)
		(width 0.14732)
		(layer "In15.Cu")
		(net "P5E_CPU1_PE2_TX_DP<2>")
	)
	(segment
		(start 123.952762 -221.963234)
		(end 123.952762 -221.94774)
		(width 0.0889)
		(layer "In15.Cu")
		(net "P5E_CPU1_PE2_TX_DP<2>")
	)
	(segment
		(start 160.38068 -397.8529)
		(end 160.271714 -399.974816)
		(width 0.14732)
		(layer "In15.Cu")
		(net "P5E_CPU1_PE2_TX_DP<2>")
	)
	(segment
		(start 160.438592 -396.731744)
		(end 160.41624 -397.167862)
		(width 0.14732)
		(layer "In15.Cu")
		(net "P5E_CPU1_PE2_TX_DP<2>")
	)
	(segment
		(start 160.28543 -397.285718)
		(end 160.262824 -397.722344)
		(width 0.14732)
		(layer "In15.Cu")
		(net "P5E_CPU1_PE2_TX_DP<2>")
	)
	(segment
		(start 130.989578 -208.949036)
		(end 136.759442 -208.949036)
		(width 0.14732)
		(layer "In15.Cu")
		(net "P5E_CPU1_PE2_TX_DP<2>")
	)
	(arc
		(start 123.952762 -221.94774)
		(mid 124.000441 -221.76484)
		(end 124.131324 -221.628462)
		(width 0.0889)
		(layer "In15.Cu")
		(net "P5E_CPU1_PE2_TX_DP<2>")
	)
	(arc
		(start 125.08611 -218.364308)
		(mid 125.288697 -218.157957)
		(end 125.362716 -217.878406)
		(width 0.0889)
		(layer "In15.Cu")
		(net "P5E_CPU1_PE2_TX_DP<2>")
	)
	(arc
		(start 123.670568 -222.437198)
		(mid 123.873391 -222.236967)
		(end 123.952762 -221.963234)
		(width 0.0889)
		(layer "In15.Cu")
		(net "P5E_CPU1_PE2_TX_DP<2>")
	)
	(arc
		(start 126.019814 -215.112346)
		(mid 126.221096 -214.914859)
		(end 126.302008 -214.644732)
		(width 0.0889)
		(layer "In15.Cu")
		(net "P5E_CPU1_PE2_TX_DP<2>")
	)
	(arc
		(start 125.362716 -217.859864)
		(mid 125.282554 -217.587675)
		(end 125.080268 -217.388694)
		(width 0.0889)
		(layer "In15.Cu")
		(net "P5E_CPU1_PE2_TX_DP<2>")
	)
	(arc
		(start 124.610368 -219.18168)
		(mid 124.813191 -218.981449)
		(end 124.892562 -218.707716)
		(width 0.0889)
		(layer "In15.Cu")
		(net "P5E_CPU1_PE2_TX_DP<2>")
	)
	(arc
		(start 122.22353 -224.094802)
		(mid 122.233397 -224.098961)
		(end 122.243342 -224.10293)
		(width 0.0889)
		(layer "In15.Cu")
		(net "P5E_CPU1_PE2_TX_DP<2>")
	)
	(arc
		(start 125.832616 -215.421972)
		(mid 125.88367 -215.247392)
		(end 126.010924 -215.117426)
		(width 0.0889)
		(layer "In15.Cu")
		(net "P5E_CPU1_PE2_TX_DP<2>")
	)
	(arc
		(start 123.200668 -223.251268)
		(mid 123.402954 -223.052287)
		(end 123.483116 -222.780098)
		(width 0.0889)
		(layer "In15.Cu")
		(net "P5E_CPU1_PE2_TX_DP<2>")
	)
	(arc
		(start 125.362716 -216.25052)
		(mid 125.410395 -216.06762)
		(end 125.541278 -215.931242)
		(width 0.0889)
		(layer "In15.Cu")
		(net "P5E_CPU1_PE2_TX_DP<2>")
	)
	(arc
		(start 123.013216 -223.575626)
		(mid 123.060895 -223.392726)
		(end 123.191778 -223.256348)
		(width 0.0889)
		(layer "In15.Cu")
		(net "P5E_CPU1_PE2_TX_DP<2>")
	)
	(arc
		(start 125.550168 -215.926162)
		(mid 125.752991 -215.725931)
		(end 125.832362 -215.452198)
		(width 0.0889)
		(layer "In15.Cu")
		(net "P5E_CPU1_PE2_TX_DP<2>")
	)
	(arc
		(start 124.140214 -220.644212)
		(mid 124.005281 -220.510858)
		(end 123.953016 -220.32849)
		(width 0.0889)
		(layer "In15.Cu")
		(net "P5E_CPU1_PE2_TX_DP<2>")
	)
	(arc
		(start 124.422916 -219.506038)
		(mid 124.470595 -219.323138)
		(end 124.601478 -219.18676)
		(width 0.0889)
		(layer "In15.Cu")
		(net "P5E_CPU1_PE2_TX_DP<2>")
	)
	(arc
		(start 126.016512 -214.093298)
		(mid 125.907557 -214.009578)
		(end 125.832616 -213.894416)
		(width 0.0889)
		(layer "In15.Cu")
		(net "P5E_CPU1_PE2_TX_DP<2>")
	)
	(arc
		(start 125.080268 -216.739978)
		(mid 125.284603 -216.537373)
		(end 125.362716 -216.260426)
		(width 0.0889)
		(layer "In15.Cu")
		(net "P5E_CPU1_PE2_TX_DP<2>")
	)
	(arc
		(start 125.832362 -215.436704)
		(mid 125.832414 -215.429337)
		(end 125.832616 -215.421972)
		(width 0.0889)
		(layer "In15.Cu")
		(net "P5E_CPU1_PE2_TX_DP<2>")
	)
	(arc
		(start 124.14631 -219.99194)
		(mid 124.348897 -219.785589)
		(end 124.422916 -219.506038)
		(width 0.0889)
		(layer "In15.Cu")
		(net "P5E_CPU1_PE2_TX_DP<2>")
	)
	(arc
		(start 126.302008 -214.425022)
		(mid 126.19067 -214.232122)
		(end 126.016512 -214.093298)
		(width 0.0889)
		(layer "In15.Cu")
		(net "P5E_CPU1_PE2_TX_DP<2>")
	)
	(arc
		(start 122.736864 -224.061528)
		(mid 122.939277 -223.855115)
		(end 123.013216 -223.575626)
		(width 0.0889)
		(layer "In15.Cu")
		(net "P5E_CPU1_PE2_TX_DP<2>")
	)
	(arc
		(start 124.892562 -218.692222)
		(mid 124.940241 -218.509322)
		(end 125.071124 -218.372944)
		(width 0.0889)
		(layer "In15.Cu")
		(net "P5E_CPU1_PE2_TX_DP<2>")
	)
	(arc
		(start 123.483116 -222.761556)
		(mid 123.530795 -222.578656)
		(end 123.661678 -222.442278)
		(width 0.0889)
		(layer "In15.Cu")
		(net "P5E_CPU1_PE2_TX_DP<2>")
	)
	(arc
		(start 123.953016 -220.311218)
		(mid 124.005286 -220.128853)
		(end 124.140214 -219.995496)
		(width 0.0889)
		(layer "In15.Cu")
		(net "P5E_CPU1_PE2_TX_DP<2>")
	)
	(arc
		(start 124.14631 -221.619826)
		(mid 124.348897 -221.413475)
		(end 124.422916 -221.133924)
		(width 0.0889)
		(layer "In15.Cu")
		(net "P5E_CPU1_PE2_TX_DP<2>")
	)
	(arc
		(start 125.071378 -217.383614)
		(mid 124.892781 -217.064336)
		(end 125.071378 -216.745058)
		(width 0.0889)
		(layer "In15.Cu")
		(net "P5E_CPU1_PE2_TX_DP<2>")
	)
	(arc
		(start 122.243342 -224.10293)
		(mid 122.491353 -224.139395)
		(end 122.730768 -224.065084)
		(width 0.0889)
		(layer "In15.Cu")
		(net "P5E_CPU1_PE2_TX_DP<2>")
	)
	(arc
		(start 124.422916 -221.1197)
		(mid 124.343697 -220.845015)
		(end 124.140214 -220.644212)
		(width 0.0889)
		(layer "In15.Cu")
		(net "P5E_CPU1_PE2_TX_DP<2>")
	)
	(segment
		(start 121.508266 -225.203512)
		(end 121.508012 -225.203258)
		(width 0.13208)
		(layer "F.Cu")
		(net "P5E_CPU1_PE2_TX_DP<1>")
	)
	(segment
		(start 163.040314 -400.858228)
		(end 163.345876 -401.16379)
		(width 0.13208)
		(layer "F.Cu")
		(net "P5E_CPU1_PE2_TX_DP<1>")
	)
	(segment
		(start 121.508266 -225.739198)
		(end 121.508266 -225.203512)
		(width 0.13208)
		(layer "F.Cu")
		(net "P5E_CPU1_PE2_TX_DP<1>")
	)
	(segment
		(start 163.345876 -401.16379)
		(end 163.345876 -401.777962)
		(width 0.13208)
		(layer "F.Cu")
		(net "P5E_CPU1_PE2_TX_DP<1>")
	)
	(segment
		(start 163.345876 -401.777962)
		(end 163.019486 -402.104352)
		(width 0.13208)
		(layer "F.Cu")
		(net "P5E_CPU1_PE2_TX_DP<1>")
	)
	(segment
		(start 163.019486 -402.104352)
		(end 163.014914 -402.104352)
		(width 0.13208)
		(layer "F.Cu")
		(net "P5E_CPU1_PE2_TX_DP<1>")
	)
	(segment
		(start 159.824166 -325.309992)
		(end 161.937192 -325.68261)
		(width 0.14732)
		(layer "In15.Cu")
		(net "P5E_CPU1_PE2_TX_DP<1>")
	)
	(segment
		(start 122.543316 -222.77578)
		(end 122.543316 -222.761556)
		(width 0.0889)
		(layer "In15.Cu")
		(net "P5E_CPU1_PE2_TX_DP<1>")
	)
	(segment
		(start 163.390072 -392.395202)
		(end 163.264342 -392.518392)
		(width 0.14732)
		(layer "In15.Cu")
		(net "P5E_CPU1_PE2_TX_DP<1>")
	)
	(segment
		(start 163.38042 -393.518136)
		(end 163.25469 -393.641326)
		(width 0.14732)
		(layer "In15.Cu")
		(net "P5E_CPU1_PE2_TX_DP<1>")
	)
	(segment
		(start 137.007854 -204.066648)
		(end 144.879568 -211.938616)
		(width 0.14732)
		(layer "In15.Cu")
		(net "P5E_CPU1_PE2_TX_DP<1>")
	)
	(segment
		(start 163.363656 -395.326616)
		(end 163.359846 -395.76375)
		(width 0.14732)
		(layer "In15.Cu")
		(net "P5E_CPU1_PE2_TX_DP<1>")
	)
	(segment
		(start 124.934726 -212.256116)
		(end 125.491494 -210.911948)
		(width 0.14732)
		(layer "In15.Cu")
		(net "P5E_CPU1_PE2_TX_DP<1>")
	)
	(segment
		(start 163.24453 -394.764006)
		(end 163.240466 -395.20114)
		(width 0.14732)
		(layer "In15.Cu")
		(net "P5E_CPU1_PE2_TX_DP<1>")
	)
	(segment
		(start 163.37026 -394.640816)
		(end 163.24453 -394.764006)
		(width 0.14732)
		(layer "In15.Cu")
		(net "P5E_CPU1_PE2_TX_DP<1>")
	)
	(segment
		(start 163.264342 -392.518392)
		(end 163.260278 -392.955526)
		(width 0.14732)
		(layer "In15.Cu")
		(net "P5E_CPU1_PE2_TX_DP<1>")
	)
	(segment
		(start 163.35375 -396.44955)
		(end 163.34994 -396.87373)
		(width 0.14732)
		(layer "In15.Cu")
		(net "P5E_CPU1_PE2_TX_DP<1>")
	)
	(segment
		(start 152.625806 -226.476306)
		(end 152.62606 -226.476306)
		(width 0.14732)
		(layer "In15.Cu")
		(net "P5E_CPU1_PE2_TX_DP<1>")
	)
	(segment
		(start 151.78786 -308.440328)
		(end 154.314398 -319.463928)
		(width 0.14732)
		(layer "In15.Cu")
		(net "P5E_CPU1_PE2_TX_DP<1>")
	)
	(segment
		(start 162.126676 -332.589378)
		(end 163.21405 -338.755736)
		(width 0.14732)
		(layer "In15.Cu")
		(net "P5E_CPU1_PE2_TX_DP<1>")
	)
	(segment
		(start 162.450526 -326.04202)
		(end 162.759136 -326.48271)
		(width 0.14732)
		(layer "In15.Cu")
		(net "P5E_CPU1_PE2_TX_DP<1>")
	)
	(segment
		(start 163.37407 -394.20419)
		(end 163.373816 -394.204444)
		(width 0.14732)
		(layer "In15.Cu")
		(net "P5E_CPU1_PE2_TX_DP<1>")
	)
	(segment
		(start 161.937192 -325.68261)
		(end 162.450526 -326.04202)
		(width 0.14732)
		(layer "In15.Cu")
		(net "P5E_CPU1_PE2_TX_DP<1>")
	)
	(segment
		(start 163.213796 -338.756498)
		(end 164.490908 -345.9988)
		(width 0.14732)
		(layer "In15.Cu")
		(net "P5E_CPU1_PE2_TX_DP<1>")
	)
	(segment
		(start 123.661678 -219.18676)
		(end 123.670568 -219.18168)
		(width 0.0889)
		(layer "In15.Cu")
		(net "P5E_CPU1_PE2_TX_DP<1>")
	)
	(segment
		(start 158.295848 -324.239636)
		(end 159.824166 -325.309992)
		(width 0.14732)
		(layer "In15.Cu")
		(net "P5E_CPU1_PE2_TX_DP<1>")
	)
	(segment
		(start 164.490908 -345.9988)
		(end 164.006022 -348.749112)
		(width 0.14732)
		(layer "In15.Cu")
		(net "P5E_CPU1_PE2_TX_DP<1>")
	)
	(segment
		(start 163.373816 -394.21562)
		(end 163.369752 -394.640562)
		(width 0.14732)
		(layer "In15.Cu")
		(net "P5E_CPU1_PE2_TX_DP<1>")
	)
	(segment
		(start 163.324794 -399.67662)
		(end 163.324794 -400.573748)
		(width 0.14732)
		(layer "In15.Cu")
		(net "P5E_CPU1_PE2_TX_DP<1>")
	)
	(segment
		(start 163.21405 -338.755736)
		(end 163.213796 -338.756498)
		(width 0.14732)
		(layer "In15.Cu")
		(net "P5E_CPU1_PE2_TX_DP<1>")
	)
	(segment
		(start 122.721878 -222.442278)
		(end 122.730768 -222.437198)
		(width 0.0889)
		(layer "In15.Cu")
		(net "P5E_CPU1_PE2_TX_DP<1>")
	)
	(segment
		(start 150.60041 -219.533978)
		(end 150.936706 -219.980256)
		(width 0.14732)
		(layer "In15.Cu")
		(net "P5E_CPU1_PE2_TX_DP<1>")
	)
	(segment
		(start 121.508012 -225.203258)
		(end 121.351548 -224.93224)
		(width 0.0889)
		(layer "In15.Cu")
		(net "P5E_CPU1_PE2_TX_DP<1>")
	)
	(segment
		(start 123.952762 -218.707716)
		(end 123.952762 -218.692222)
		(width 0.0889)
		(layer "In15.Cu")
		(net "P5E_CPU1_PE2_TX_DP<1>")
	)
	(segment
		(start 150.190708 -218.98991)
		(end 150.166578 -219.160598)
		(width 0.14732)
		(layer "In15.Cu")
		(net "P5E_CPU1_PE2_TX_DP<1>")
	)
	(segment
		(start 123.200668 -220.644212)
		(end 123.191778 -220.639132)
		(width 0.0889)
		(layer "In15.Cu")
		(net "P5E_CPU1_PE2_TX_DP<1>")
	)
	(segment
		(start 121.351548 -224.93224)
		(end 121.375678 -224.843086)
		(width 0.0889)
		(layer "In15.Cu")
		(net "P5E_CPU1_PE2_TX_DP<1>")
	)
	(segment
		(start 163.324794 -400.573748)
		(end 163.040314 -400.858228)
		(width 0.14732)
		(layer "In15.Cu")
		(net "P5E_CPU1_PE2_TX_DP<1>")
	)
	(segment
		(start 124.892562 -215.452198)
		(end 124.892562 -215.436704)
		(width 0.0889)
		(layer "In15.Cu")
		(net "P5E_CPU1_PE2_TX_DP<1>")
	)
	(segment
		(start 163.383722 -393.081256)
		(end 163.379912 -393.517882)
		(width 0.14732)
		(layer "In15.Cu")
		(net "P5E_CPU1_PE2_TX_DP<1>")
	)
	(segment
		(start 123.953016 -217.072972)
		(end 123.953016 -217.0557)
		(width 0.0889)
		(layer "In15.Cu")
		(net "P5E_CPU1_PE2_TX_DP<1>")
	)
	(segment
		(start 156.548582 -322.485004)
		(end 158.295848 -324.239636)
		(width 0.14732)
		(layer "In15.Cu")
		(net "P5E_CPU1_PE2_TX_DP<1>")
	)
	(segment
		(start 163.274502 -391.395712)
		(end 163.270438 -391.832846)
		(width 0.14732)
		(layer "In15.Cu")
		(net "P5E_CPU1_PE2_TX_DP<1>")
	)
	(segment
		(start 150.166578 -219.160598)
		(end 150.429722 -219.509848)
		(width 0.14732)
		(layer "In15.Cu")
		(net "P5E_CPU1_PE2_TX_DP<1>")
	)
	(segment
		(start 150.936706 -219.980256)
		(end 152.625806 -226.476306)
		(width 0.14732)
		(layer "In15.Cu")
		(net "P5E_CPU1_PE2_TX_DP<1>")
	)
	(segment
		(start 125.362208 -214.644732)
		(end 125.362208 -214.424768)
		(width 0.0889)
		(layer "In15.Cu")
		(net "P5E_CPU1_PE2_TX_DP<1>")
	)
	(segment
		(start 163.23437 -395.886686)
		(end 163.230306 -396.32382)
		(width 0.14732)
		(layer "In15.Cu")
		(net "P5E_CPU1_PE2_TX_DP<1>")
	)
	(segment
		(start 123.012962 -221.963234)
		(end 123.012962 -221.94774)
		(width 0.0889)
		(layer "In15.Cu")
		(net "P5E_CPU1_PE2_TX_DP<1>")
	)
	(segment
		(start 163.34994 -396.87373)
		(end 163.34994 -396.886176)
		(width 0.14732)
		(layer "In15.Cu")
		(net "P5E_CPU1_PE2_TX_DP<1>")
	)
	(segment
		(start 123.200414 -221.623382)
		(end 123.20651 -221.619826)
		(width 0.0889)
		(layer "In15.Cu")
		(net "P5E_CPU1_PE2_TX_DP<1>")
	)
	(segment
		(start 163.373816 -394.204444)
		(end 163.373816 -394.21562)
		(width 0.14732)
		(layer "In15.Cu")
		(net "P5E_CPU1_PE2_TX_DP<1>")
	)
	(segment
		(start 162.759136 -326.48271)
		(end 162.981386 -327.742042)
		(width 0.14732)
		(layer "In15.Cu")
		(net "P5E_CPU1_PE2_TX_DP<1>")
	)
	(segment
		(start 154.314398 -319.463928)
		(end 155.777692 -321.672966)
		(width 0.14732)
		(layer "In15.Cu")
		(net "P5E_CPU1_PE2_TX_DP<1>")
	)
	(segment
		(start 163.240466 -395.20114)
		(end 163.363656 -395.326616)
		(width 0.14732)
		(layer "In15.Cu")
		(net "P5E_CPU1_PE2_TX_DP<1>")
	)
	(segment
		(start 124.140214 -216.739978)
		(end 124.140976 -216.73947)
		(width 0.0889)
		(layer "In15.Cu")
		(net "P5E_CPU1_PE2_TX_DP<1>")
	)
	(segment
		(start 163.230306 -396.32382)
		(end 163.35375 -396.44955)
		(width 0.14732)
		(layer "In15.Cu")
		(net "P5E_CPU1_PE2_TX_DP<1>")
	)
	(segment
		(start 121.782078 -224.070164)
		(end 121.790968 -224.065084)
		(width 0.0889)
		(layer "In15.Cu")
		(net "P5E_CPU1_PE2_TX_DP<1>")
	)
	(segment
		(start 124.140976 -216.73947)
		(end 124.14631 -216.736422)
		(width 0.0889)
		(layer "In15.Cu")
		(net "P5E_CPU1_PE2_TX_DP<1>")
	)
	(segment
		(start 124.131324 -218.372944)
		(end 124.140214 -218.367864)
		(width 0.0889)
		(layer "In15.Cu")
		(net "P5E_CPU1_PE2_TX_DP<1>")
	)
	(segment
		(start 132.223256 -204.180186)
		(end 133.906514 -203.482956)
		(width 0.14732)
		(layer "In15.Cu")
		(net "P5E_CPU1_PE2_TX_DP<1>")
	)
	(segment
		(start 152.62606 -226.476306)
		(end 155.760928 -247.251982)
		(width 0.14732)
		(layer "In15.Cu")
		(net "P5E_CPU1_PE2_TX_DP<1>")
	)
	(segment
		(start 125.071124 -215.117426)
		(end 125.080014 -215.112346)
		(width 0.0889)
		(layer "In15.Cu")
		(net "P5E_CPU1_PE2_TX_DP<1>")
	)
	(segment
		(start 124.892816 -213.242398)
		(end 124.934726 -213.200488)
		(width 0.0889)
		(layer "In15.Cu")
		(net "P5E_CPU1_PE2_TX_DP<1>")
	)
	(segment
		(start 124.601478 -215.931242)
		(end 124.610368 -215.926162)
		(width 0.0889)
		(layer "In15.Cu")
		(net "P5E_CPU1_PE2_TX_DP<1>")
	)
	(segment
		(start 150.429722 -219.509848)
		(end 150.60041 -219.533978)
		(width 0.14732)
		(layer "In15.Cu")
		(net "P5E_CPU1_PE2_TX_DP<1>")
	)
	(segment
		(start 135.59917 -203.482956)
		(end 137.007854 -204.066648)
		(width 0.14732)
		(layer "In15.Cu")
		(net "P5E_CPU1_PE2_TX_DP<1>")
	)
	(segment
		(start 122.073416 -223.585532)
		(end 122.073416 -223.56699)
		(width 0.0889)
		(layer "In15.Cu")
		(net "P5E_CPU1_PE2_TX_DP<1>")
	)
	(segment
		(start 163.393882 -391.958576)
		(end 163.390072 -392.395202)
		(width 0.14732)
		(layer "In15.Cu")
		(net "P5E_CPU1_PE2_TX_DP<1>")
	)
	(segment
		(start 155.970224 -253.48057)
		(end 151.78786 -308.440328)
		(width 0.14732)
		(layer "In15.Cu")
		(net "P5E_CPU1_PE2_TX_DP<1>")
	)
	(segment
		(start 162.981386 -327.742042)
		(end 162.126676 -332.589378)
		(width 0.14732)
		(layer "In15.Cu")
		(net "P5E_CPU1_PE2_TX_DP<1>")
	)
	(segment
		(start 124.934726 -213.200488)
		(end 124.934726 -213.17839)
		(width 0.0889)
		(layer "In15.Cu")
		(net "P5E_CPU1_PE2_TX_DP<1>")
	)
	(segment
		(start 123.191524 -221.628462)
		(end 123.200414 -221.623382)
		(width 0.0889)
		(layer "In15.Cu")
		(net "P5E_CPU1_PE2_TX_DP<1>")
	)
	(segment
		(start 163.369752 -394.640562)
		(end 163.37026 -394.640816)
		(width 0.14732)
		(layer "In15.Cu")
		(net "P5E_CPU1_PE2_TX_DP<1>")
	)
	(segment
		(start 124.892816 -213.893908)
		(end 124.892816 -213.242398)
		(width 0.0889)
		(layer "In15.Cu")
		(net "P5E_CPU1_PE2_TX_DP<1>")
	)
	(segment
		(start 123.199906 -219.996004)
		(end 123.200668 -219.995496)
		(width 0.0889)
		(layer "In15.Cu")
		(net "P5E_CPU1_PE2_TX_DP<1>")
	)
	(segment
		(start 163.220146 -397.4465)
		(end 163.34359 -397.571976)
		(width 0.14732)
		(layer "In15.Cu")
		(net "P5E_CPU1_PE2_TX_DP<1>")
	)
	(segment
		(start 163.25469 -393.641326)
		(end 163.250626 -394.07846)
		(width 0.14732)
		(layer "In15.Cu")
		(net "P5E_CPU1_PE2_TX_DP<1>")
	)
	(segment
		(start 124.140214 -218.367864)
		(end 124.14631 -218.364308)
		(width 0.0889)
		(layer "In15.Cu")
		(net "P5E_CPU1_PE2_TX_DP<1>")
	)
	(segment
		(start 124.934726 -213.17839)
		(end 124.934726 -212.256116)
		(width 0.14732)
		(layer "In15.Cu")
		(net "P5E_CPU1_PE2_TX_DP<1>")
	)
	(segment
		(start 133.906514 -203.482956)
		(end 135.59917 -203.482956)
		(width 0.14732)
		(layer "In15.Cu")
		(net "P5E_CPU1_PE2_TX_DP<1>")
	)
	(segment
		(start 163.250626 -394.07846)
		(end 163.37407 -394.20419)
		(width 0.14732)
		(layer "In15.Cu")
		(net "P5E_CPU1_PE2_TX_DP<1>")
	)
	(segment
		(start 123.191778 -220.000576)
		(end 123.199906 -219.996004)
		(width 0.0889)
		(layer "In15.Cu")
		(net "P5E_CPU1_PE2_TX_DP<1>")
	)
	(segment
		(start 163.34994 -396.886176)
		(end 163.22421 -397.009366)
		(width 0.14732)
		(layer "In15.Cu")
		(net "P5E_CPU1_PE2_TX_DP<1>")
	)
	(segment
		(start 163.359846 -395.76375)
		(end 163.23437 -395.886686)
		(width 0.14732)
		(layer "In15.Cu")
		(net "P5E_CPU1_PE2_TX_DP<1>")
	)
	(segment
		(start 124.422916 -217.878406)
		(end 124.422916 -217.864182)
		(width 0.0889)
		(layer "In15.Cu")
		(net "P5E_CPU1_PE2_TX_DP<1>")
	)
	(segment
		(start 163.400232 -391.272522)
		(end 163.274502 -391.395712)
		(width 0.14732)
		(layer "In15.Cu")
		(net "P5E_CPU1_PE2_TX_DP<1>")
	)
	(segment
		(start 164.006022 -348.749112)
		(end 163.75634 -351.602294)
		(width 0.14732)
		(layer "In15.Cu")
		(net "P5E_CPU1_PE2_TX_DP<1>")
	)
	(segment
		(start 163.379912 -393.517882)
		(end 163.38042 -393.518136)
		(width 0.14732)
		(layer "In15.Cu")
		(net "P5E_CPU1_PE2_TX_DP<1>")
	)
	(segment
		(start 163.22421 -397.009366)
		(end 163.220146 -397.4465)
		(width 0.14732)
		(layer "In15.Cu")
		(net "P5E_CPU1_PE2_TX_DP<1>")
	)
	(segment
		(start 163.270438 -391.832846)
		(end 163.393882 -391.958576)
		(width 0.14732)
		(layer "In15.Cu")
		(net "P5E_CPU1_PE2_TX_DP<1>")
	)
	(segment
		(start 155.760928 -247.251982)
		(end 155.970224 -253.48057)
		(width 0.14732)
		(layer "In15.Cu")
		(net "P5E_CPU1_PE2_TX_DP<1>")
	)
	(segment
		(start 163.34359 -397.571976)
		(end 163.324794 -399.67662)
		(width 0.14732)
		(layer "In15.Cu")
		(net "P5E_CPU1_PE2_TX_DP<1>")
	)
	(segment
		(start 123.483116 -219.515944)
		(end 123.483116 -219.506038)
		(width 0.0889)
		(layer "In15.Cu")
		(net "P5E_CPU1_PE2_TX_DP<1>")
	)
	(segment
		(start 125.491494 -210.911948)
		(end 132.223256 -204.180186)
		(width 0.14732)
		(layer "In15.Cu")
		(net "P5E_CPU1_PE2_TX_DP<1>")
	)
	(segment
		(start 123.483116 -221.133924)
		(end 123.483116 -221.115382)
		(width 0.0889)
		(layer "In15.Cu")
		(net "P5E_CPU1_PE2_TX_DP<1>")
	)
	(segment
		(start 163.75634 -351.602294)
		(end 163.400232 -391.272522)
		(width 0.14732)
		(layer "In15.Cu")
		(net "P5E_CPU1_PE2_TX_DP<1>")
	)
	(segment
		(start 155.777692 -321.672966)
		(end 156.548582 -322.485004)
		(width 0.14732)
		(layer "In15.Cu")
		(net "P5E_CPU1_PE2_TX_DP<1>")
	)
	(segment
		(start 163.260278 -392.955526)
		(end 163.383722 -393.081256)
		(width 0.14732)
		(layer "In15.Cu")
		(net "P5E_CPU1_PE2_TX_DP<1>")
	)
	(segment
		(start 144.879568 -211.938616)
		(end 150.190708 -218.98991)
		(width 0.14732)
		(layer "In15.Cu")
		(net "P5E_CPU1_PE2_TX_DP<1>")
	)
	(arc
		(start 124.140214 -217.388694)
		(mid 124.005281 -217.25534)
		(end 123.953016 -217.072972)
		(width 0.0889)
		(layer "In15.Cu")
		(net "P5E_CPU1_PE2_TX_DP<1>")
	)
	(arc
		(start 123.483116 -219.506038)
		(mid 123.530795 -219.323138)
		(end 123.661678 -219.18676)
		(width 0.0889)
		(layer "In15.Cu")
		(net "P5E_CPU1_PE2_TX_DP<1>")
	)
	(arc
		(start 121.392696 -224.829878)
		(mid 121.548094 -224.633597)
		(end 121.603516 -224.389442)
		(width 0.0889)
		(layer "In15.Cu")
		(net "P5E_CPU1_PE2_TX_DP<1>")
	)
	(arc
		(start 125.362208 -214.424768)
		(mid 125.250929 -214.232062)
		(end 125.076966 -214.093298)
		(width 0.0889)
		(layer "In15.Cu")
		(net "P5E_CPU1_PE2_TX_DP<1>")
	)
	(arc
		(start 125.080014 -215.112346)
		(mid 125.281296 -214.914859)
		(end 125.362208 -214.644732)
		(width 0.0889)
		(layer "In15.Cu")
		(net "P5E_CPU1_PE2_TX_DP<1>")
	)
	(arc
		(start 124.422916 -216.25052)
		(mid 124.470595 -216.06762)
		(end 124.601478 -215.931242)
		(width 0.0889)
		(layer "In15.Cu")
		(net "P5E_CPU1_PE2_TX_DP<1>")
	)
	(arc
		(start 123.953016 -217.0557)
		(mid 124.005286 -216.873335)
		(end 124.140214 -216.739978)
		(width 0.0889)
		(layer "In15.Cu")
		(net "P5E_CPU1_PE2_TX_DP<1>")
	)
	(arc
		(start 123.670568 -219.18168)
		(mid 123.873391 -218.981449)
		(end 123.952762 -218.707716)
		(width 0.0889)
		(layer "In15.Cu")
		(net "P5E_CPU1_PE2_TX_DP<1>")
	)
	(arc
		(start 122.260614 -223.251268)
		(mid 122.464095 -223.050464)
		(end 122.543316 -222.77578)
		(width 0.0889)
		(layer "In15.Cu")
		(net "P5E_CPU1_PE2_TX_DP<1>")
	)
	(arc
		(start 121.790968 -224.065084)
		(mid 121.995303 -223.862479)
		(end 122.073416 -223.585532)
		(width 0.0889)
		(layer "In15.Cu")
		(net "P5E_CPU1_PE2_TX_DP<1>")
	)
	(arc
		(start 122.730768 -222.437198)
		(mid 122.933591 -222.236967)
		(end 123.012962 -221.963234)
		(width 0.0889)
		(layer "In15.Cu")
		(net "P5E_CPU1_PE2_TX_DP<1>")
	)
	(arc
		(start 122.543316 -222.761556)
		(mid 122.590995 -222.578656)
		(end 122.721878 -222.442278)
		(width 0.0889)
		(layer "In15.Cu")
		(net "P5E_CPU1_PE2_TX_DP<1>")
	)
	(arc
		(start 123.012962 -221.94774)
		(mid 123.060641 -221.76484)
		(end 123.191524 -221.628462)
		(width 0.0889)
		(layer "In15.Cu")
		(net "P5E_CPU1_PE2_TX_DP<1>")
	)
	(arc
		(start 124.610368 -215.926162)
		(mid 124.813191 -215.725931)
		(end 124.892562 -215.452198)
		(width 0.0889)
		(layer "In15.Cu")
		(net "P5E_CPU1_PE2_TX_DP<1>")
	)
	(arc
		(start 123.200668 -219.995496)
		(mid 123.405003 -219.792891)
		(end 123.483116 -219.515944)
		(width 0.0889)
		(layer "In15.Cu")
		(net "P5E_CPU1_PE2_TX_DP<1>")
	)
	(arc
		(start 124.14631 -218.364308)
		(mid 124.348897 -218.157957)
		(end 124.422916 -217.878406)
		(width 0.0889)
		(layer "In15.Cu")
		(net "P5E_CPU1_PE2_TX_DP<1>")
	)
	(arc
		(start 125.076966 -214.093298)
		(mid 124.967819 -214.00937)
		(end 124.892816 -213.893908)
		(width 0.0889)
		(layer "In15.Cu")
		(net "P5E_CPU1_PE2_TX_DP<1>")
	)
	(arc
		(start 121.375678 -224.843086)
		(mid 121.38425 -224.836564)
		(end 121.392696 -224.829878)
		(width 0.0889)
		(layer "In15.Cu")
		(net "P5E_CPU1_PE2_TX_DP<1>")
	)
	(arc
		(start 124.892562 -215.436704)
		(mid 124.892614 -215.429337)
		(end 124.892816 -215.421972)
		(width 0.0889)
		(layer "In15.Cu")
		(net "P5E_CPU1_PE2_TX_DP<1>")
	)
	(arc
		(start 123.013216 -220.319854)
		(mid 123.060895 -220.136954)
		(end 123.191778 -220.000576)
		(width 0.0889)
		(layer "In15.Cu")
		(net "P5E_CPU1_PE2_TX_DP<1>")
	)
	(arc
		(start 124.892816 -215.421972)
		(mid 124.94387 -215.247392)
		(end 125.071124 -215.117426)
		(width 0.0889)
		(layer "In15.Cu")
		(net "P5E_CPU1_PE2_TX_DP<1>")
	)
	(arc
		(start 122.073416 -223.56699)
		(mid 122.125686 -223.384625)
		(end 122.260614 -223.251268)
		(width 0.0889)
		(layer "In15.Cu")
		(net "P5E_CPU1_PE2_TX_DP<1>")
	)
	(arc
		(start 123.20651 -221.619826)
		(mid 123.409097 -221.413475)
		(end 123.483116 -221.133924)
		(width 0.0889)
		(layer "In15.Cu")
		(net "P5E_CPU1_PE2_TX_DP<1>")
	)
	(arc
		(start 123.483116 -221.115382)
		(mid 123.402954 -220.843193)
		(end 123.200668 -220.644212)
		(width 0.0889)
		(layer "In15.Cu")
		(net "P5E_CPU1_PE2_TX_DP<1>")
	)
	(arc
		(start 123.952762 -218.692222)
		(mid 124.000441 -218.509322)
		(end 124.131324 -218.372944)
		(width 0.0889)
		(layer "In15.Cu")
		(net "P5E_CPU1_PE2_TX_DP<1>")
	)
	(arc
		(start 124.422916 -217.864182)
		(mid 124.343697 -217.589497)
		(end 124.140214 -217.388694)
		(width 0.0889)
		(layer "In15.Cu")
		(net "P5E_CPU1_PE2_TX_DP<1>")
	)
	(arc
		(start 124.14631 -216.736422)
		(mid 124.348897 -216.530071)
		(end 124.422916 -216.25052)
		(width 0.0889)
		(layer "In15.Cu")
		(net "P5E_CPU1_PE2_TX_DP<1>")
	)
	(arc
		(start 121.603516 -224.389442)
		(mid 121.651195 -224.206542)
		(end 121.782078 -224.070164)
		(width 0.0889)
		(layer "In15.Cu")
		(net "P5E_CPU1_PE2_TX_DP<1>")
	)
	(arc
		(start 123.191778 -220.639132)
		(mid 123.060864 -220.502772)
		(end 123.013216 -220.319854)
		(width 0.0889)
		(layer "In15.Cu")
		(net "P5E_CPU1_PE2_TX_DP<1>")
	)
	(segment
		(start 120.460516 -401.777962)
		(end 120.134126 -402.104352)
		(width 0.13208)
		(layer "F.Cu")
		(net "P5E_CPU1_PE2_TX_DP<15>")
	)
	(segment
		(start 120.134126 -402.104352)
		(end 120.129554 -402.104352)
		(width 0.13208)
		(layer "F.Cu")
		(net "P5E_CPU1_PE2_TX_DP<15>")
	)
	(segment
		(start 134.665466 -225.739198)
		(end 134.665466 -225.203258)
		(width 0.13208)
		(layer "F.Cu")
		(net "P5E_CPU1_PE2_TX_DP<15>")
	)
	(segment
		(start 120.154954 -400.858228)
		(end 120.460516 -401.16379)
		(width 0.13208)
		(layer "F.Cu")
		(net "P5E_CPU1_PE2_TX_DP<15>")
	)
	(segment
		(start 120.460516 -401.16379)
		(end 120.460516 -401.777962)
		(width 0.13208)
		(layer "F.Cu")
		(net "P5E_CPU1_PE2_TX_DP<15>")
	)
	(segment
		(start 140.189966 -271.507204)
		(end 140.189966 -271.50695)
		(width 0.14732)
		(layer "In15.Cu")
		(net "P5E_CPU1_PE2_TX_DP<15>")
	)
	(segment
		(start 138.55827 -232.604056)
		(end 138.43381 -232.72369)
		(width 0.14732)
		(layer "In15.Cu")
		(net "P5E_CPU1_PE2_TX_DP<15>")
	)
	(segment
		(start 135.979916 -226.831144)
		(end 135.979916 -226.84105)
		(width 0.0889)
		(layer "In15.Cu")
		(net "P5E_CPU1_PE2_TX_DP<15>")
	)
	(segment
		(start 123.916948 -395.311884)
		(end 123.741942 -395.329664)
		(width 0.14732)
		(layer "In15.Cu")
		(net "P5E_CPU1_PE2_TX_DP<15>")
	)
	(segment
		(start 138.43381 -232.72369)
		(end 138.425682 -233.160824)
		(width 0.14732)
		(layer "In15.Cu")
		(net "P5E_CPU1_PE2_TX_DP<15>")
	)
	(segment
		(start 146.076924 -368.177572)
		(end 123.916948 -395.311884)
		(width 0.14732)
		(layer "In15.Cu")
		(net "P5E_CPU1_PE2_TX_DP<15>")
	)
	(segment
		(start 122.755152 -396.537942)
		(end 122.772678 -396.712948)
		(width 0.14732)
		(layer "In15.Cu")
		(net "P5E_CPU1_PE2_TX_DP<15>")
	)
	(segment
		(start 123.206764 -396.18158)
		(end 123.031758 -396.19936)
		(width 0.14732)
		(layer "In15.Cu")
		(net "P5E_CPU1_PE2_TX_DP<15>")
	)
	(segment
		(start 150.546816 -345.36253)
		(end 150.087838 -347.966284)
		(width 0.14732)
		(layer "In15.Cu")
		(net "P5E_CPU1_PE2_TX_DP<15>")
	)
	(segment
		(start 136.705086 -227.804726)
		(end 137.278872 -228.378512)
		(width 0.14732)
		(layer "In15.Cu")
		(net "P5E_CPU1_PE2_TX_DP<15>")
	)
	(segment
		(start 134.852664 -224.8789)
		(end 134.854188 -224.879662)
		(width 0.0889)
		(layer "In15.Cu")
		(net "P5E_CPU1_PE2_TX_DP<15>")
	)
	(segment
		(start 138.168126 -253.529846)
		(end 138.768836 -254.979932)
		(width 0.14732)
		(layer "In15.Cu")
		(net "P5E_CPU1_PE2_TX_DP<15>")
	)
	(segment
		(start 136.689592 -227.789232)
		(end 136.705086 -227.804726)
		(width 0.0889)
		(layer "In15.Cu")
		(net "P5E_CPU1_PE2_TX_DP<15>")
	)
	(segment
		(start 138.545316 -233.28503)
		(end 138.30681 -245.965218)
		(width 0.14732)
		(layer "In15.Cu")
		(net "P5E_CPU1_PE2_TX_DP<15>")
	)
	(segment
		(start 137.684002 -248.024142)
		(end 137.233406 -250.579636)
		(width 0.14732)
		(layer "In15.Cu")
		(net "P5E_CPU1_PE2_TX_DP<15>")
	)
	(segment
		(start 137.614152 -252.73889)
		(end 138.168126 -253.529846)
		(width 0.14732)
		(layer "In15.Cu")
		(net "P5E_CPU1_PE2_TX_DP<15>")
	)
	(segment
		(start 122.062494 -397.582898)
		(end 120.638062 -399.327116)
		(width 0.14732)
		(layer "In15.Cu")
		(net "P5E_CPU1_PE2_TX_DP<15>")
	)
	(segment
		(start 137.278872 -228.378512)
		(end 138.466322 -230.618792)
		(width 0.14732)
		(layer "In15.Cu")
		(net "P5E_CPU1_PE2_TX_DP<15>")
	)
	(segment
		(start 135.322564 -225.69297)
		(end 135.331454 -225.69805)
		(width 0.0889)
		(layer "In15.Cu")
		(net "P5E_CPU1_PE2_TX_DP<15>")
	)
	(segment
		(start 134.509002 -224.93224)
		(end 134.530084 -224.854262)
		(width 0.0889)
		(layer "In15.Cu")
		(net "P5E_CPU1_PE2_TX_DP<15>")
	)
	(segment
		(start 148.919946 -361.310682)
		(end 146.076924 -368.177572)
		(width 0.14732)
		(layer "In15.Cu")
		(net "P5E_CPU1_PE2_TX_DP<15>")
	)
	(segment
		(start 122.321574 -397.069056)
		(end 122.044968 -397.407638)
		(width 0.14732)
		(layer "In15.Cu")
		(net "P5E_CPU1_PE2_TX_DP<15>")
	)
	(segment
		(start 138.30681 -245.965218)
		(end 137.684002 -248.024142)
		(width 0.14732)
		(layer "In15.Cu")
		(net "P5E_CPU1_PE2_TX_DP<15>")
	)
	(segment
		(start 138.425682 -233.160824)
		(end 138.545316 -233.28503)
		(width 0.14732)
		(layer "In15.Cu")
		(net "P5E_CPU1_PE2_TX_DP<15>")
	)
	(segment
		(start 137.233406 -250.579636)
		(end 137.614152 -252.73889)
		(width 0.14732)
		(layer "In15.Cu")
		(net "P5E_CPU1_PE2_TX_DP<15>")
	)
	(segment
		(start 138.466322 -230.618792)
		(end 138.566398 -232.16743)
		(width 0.14732)
		(layer "In15.Cu")
		(net "P5E_CPU1_PE2_TX_DP<15>")
	)
	(segment
		(start 123.465336 -395.668246)
		(end 123.482862 -395.843252)
		(width 0.14732)
		(layer "In15.Cu")
		(net "P5E_CPU1_PE2_TX_DP<15>")
	)
	(segment
		(start 140.188442 -257.006852)
		(end 141.047216 -259.7023)
		(width 0.14732)
		(layer "In15.Cu")
		(net "P5E_CPU1_PE2_TX_DP<15>")
	)
	(segment
		(start 138.309096 -310.04637)
		(end 142.772384 -328.442066)
		(width 0.14732)
		(layer "In15.Cu")
		(net "P5E_CPU1_PE2_TX_DP<15>")
	)
	(segment
		(start 123.741942 -395.329664)
		(end 123.465336 -395.668246)
		(width 0.14732)
		(layer "In15.Cu")
		(net "P5E_CPU1_PE2_TX_DP<15>")
	)
	(segment
		(start 120.449594 -400.563588)
		(end 120.154954 -400.858228)
		(width 0.14732)
		(layer "In15.Cu")
		(net "P5E_CPU1_PE2_TX_DP<15>")
	)
	(segment
		(start 123.482862 -395.843252)
		(end 123.206764 -396.18158)
		(width 0.14732)
		(layer "In15.Cu")
		(net "P5E_CPU1_PE2_TX_DP<15>")
	)
	(segment
		(start 135.510016 -226.017328)
		(end 135.510016 -226.027234)
		(width 0.0889)
		(layer "In15.Cu")
		(net "P5E_CPU1_PE2_TX_DP<15>")
	)
	(segment
		(start 141.047216 -259.7023)
		(end 140.189966 -271.507204)
		(width 0.14732)
		(layer "In15.Cu")
		(net "P5E_CPU1_PE2_TX_DP<15>")
	)
	(segment
		(start 134.665466 -225.203258)
		(end 134.509002 -224.93224)
		(width 0.0889)
		(layer "In15.Cu")
		(net "P5E_CPU1_PE2_TX_DP<15>")
	)
	(segment
		(start 136.340088 -227.379784)
		(end 136.689592 -227.729288)
		(width 0.0889)
		(layer "In15.Cu")
		(net "P5E_CPU1_PE2_TX_DP<15>")
	)
	(segment
		(start 122.772678 -396.712948)
		(end 122.49658 -397.051276)
		(width 0.14732)
		(layer "In15.Cu")
		(net "P5E_CPU1_PE2_TX_DP<15>")
	)
	(segment
		(start 150.087838 -347.966284)
		(end 148.919946 -361.310682)
		(width 0.14732)
		(layer "In15.Cu")
		(net "P5E_CPU1_PE2_TX_DP<15>")
	)
	(segment
		(start 135.792464 -226.506786)
		(end 135.801354 -226.511866)
		(width 0.0889)
		(layer "In15.Cu")
		(net "P5E_CPU1_PE2_TX_DP<15>")
	)
	(segment
		(start 120.638062 -399.327116)
		(end 120.449594 -399.855436)
		(width 0.14732)
		(layer "In15.Cu")
		(net "P5E_CPU1_PE2_TX_DP<15>")
	)
	(segment
		(start 140.189966 -271.50695)
		(end 138.309096 -310.04637)
		(width 0.14732)
		(layer "In15.Cu")
		(net "P5E_CPU1_PE2_TX_DP<15>")
	)
	(segment
		(start 135.040116 -225.203258)
		(end 135.040116 -225.2218)
		(width 0.0889)
		(layer "In15.Cu")
		(net "P5E_CPU1_PE2_TX_DP<15>")
	)
	(segment
		(start 122.49658 -397.051276)
		(end 122.321574 -397.069056)
		(width 0.14732)
		(layer "In15.Cu")
		(net "P5E_CPU1_PE2_TX_DP<15>")
	)
	(segment
		(start 122.044968 -397.407638)
		(end 122.062494 -397.582898)
		(width 0.14732)
		(layer "In15.Cu")
		(net "P5E_CPU1_PE2_TX_DP<15>")
	)
	(segment
		(start 138.768836 -254.979932)
		(end 140.188442 -257.006852)
		(width 0.14732)
		(layer "In15.Cu")
		(net "P5E_CPU1_PE2_TX_DP<15>")
	)
	(segment
		(start 136.689592 -227.729288)
		(end 136.689592 -227.789232)
		(width 0.0889)
		(layer "In15.Cu")
		(net "P5E_CPU1_PE2_TX_DP<15>")
	)
	(segment
		(start 148.739352 -335.116424)
		(end 150.546816 -345.36253)
		(width 0.14732)
		(layer "In15.Cu")
		(net "P5E_CPU1_PE2_TX_DP<15>")
	)
	(segment
		(start 138.566398 -232.16743)
		(end 138.55827 -232.604056)
		(width 0.14732)
		(layer "In15.Cu")
		(net "P5E_CPU1_PE2_TX_DP<15>")
	)
	(segment
		(start 134.854188 -224.879662)
		(end 134.861554 -224.88398)
		(width 0.0889)
		(layer "In15.Cu")
		(net "P5E_CPU1_PE2_TX_DP<15>")
	)
	(segment
		(start 120.449594 -399.855436)
		(end 120.449594 -400.563588)
		(width 0.14732)
		(layer "In15.Cu")
		(net "P5E_CPU1_PE2_TX_DP<15>")
	)
	(segment
		(start 123.031758 -396.19936)
		(end 122.755152 -396.537942)
		(width 0.14732)
		(layer "In15.Cu")
		(net "P5E_CPU1_PE2_TX_DP<15>")
	)
	(segment
		(start 142.772384 -328.442066)
		(end 148.739352 -335.116424)
		(width 0.14732)
		(layer "In15.Cu")
		(net "P5E_CPU1_PE2_TX_DP<15>")
	)
	(arc
		(start 134.530084 -224.854262)
		(mid 134.69418 -224.829915)
		(end 134.852664 -224.8789)
		(width 0.0889)
		(layer "In15.Cu")
		(net "P5E_CPU1_PE2_TX_DP<15>")
	)
	(arc
		(start 135.801354 -226.511866)
		(mid 135.932268 -226.648226)
		(end 135.979916 -226.831144)
		(width 0.0889)
		(layer "In15.Cu")
		(net "P5E_CPU1_PE2_TX_DP<15>")
	)
	(arc
		(start 136.262364 -227.320602)
		(mid 136.303174 -227.347636)
		(end 136.340088 -227.379784)
		(width 0.0889)
		(layer "In15.Cu")
		(net "P5E_CPU1_PE2_TX_DP<15>")
	)
	(arc
		(start 135.979916 -226.84105)
		(mid 136.058027 -227.117999)
		(end 136.262364 -227.320602)
		(width 0.0889)
		(layer "In15.Cu")
		(net "P5E_CPU1_PE2_TX_DP<15>")
	)
	(arc
		(start 135.040116 -225.2218)
		(mid 135.120278 -225.493989)
		(end 135.322564 -225.69297)
		(width 0.0889)
		(layer "In15.Cu")
		(net "P5E_CPU1_PE2_TX_DP<15>")
	)
	(arc
		(start 135.331454 -225.69805)
		(mid 135.462368 -225.83441)
		(end 135.510016 -226.017328)
		(width 0.0889)
		(layer "In15.Cu")
		(net "P5E_CPU1_PE2_TX_DP<15>")
	)
	(arc
		(start 134.861554 -224.88398)
		(mid 134.992468 -225.02034)
		(end 135.040116 -225.203258)
		(width 0.0889)
		(layer "In15.Cu")
		(net "P5E_CPU1_PE2_TX_DP<15>")
	)
	(arc
		(start 135.510016 -226.027234)
		(mid 135.588127 -226.304183)
		(end 135.792464 -226.506786)
		(width 0.0889)
		(layer "In15.Cu")
		(net "P5E_CPU1_PE2_TX_DP<15>")
	)
	(segment
		(start 123.523756 -401.777962)
		(end 123.197366 -402.104352)
		(width 0.13208)
		(layer "F.Cu")
		(net "P5E_CPU1_PE2_TX_DP<14>")
	)
	(segment
		(start 123.218194 -400.858228)
		(end 123.523756 -401.16379)
		(width 0.13208)
		(layer "F.Cu")
		(net "P5E_CPU1_PE2_TX_DP<14>")
	)
	(segment
		(start 133.255512 -224.389696)
		(end 133.255766 -224.389442)
		(width 0.13208)
		(layer "F.Cu")
		(net "P5E_CPU1_PE2_TX_DP<14>")
	)
	(segment
		(start 123.523756 -401.16379)
		(end 123.523756 -401.777962)
		(width 0.13208)
		(layer "F.Cu")
		(net "P5E_CPU1_PE2_TX_DP<14>")
	)
	(segment
		(start 123.197366 -402.104352)
		(end 123.192794 -402.104352)
		(width 0.13208)
		(layer "F.Cu")
		(net "P5E_CPU1_PE2_TX_DP<14>")
	)
	(segment
		(start 133.255512 -224.925382)
		(end 133.255512 -224.389696)
		(width 0.13208)
		(layer "F.Cu")
		(net "P5E_CPU1_PE2_TX_DP<14>")
	)
	(segment
		(start 137.28573 -227.056442)
		(end 137.28573 -227.116386)
		(width 0.0889)
		(layer "In15.Cu")
		(net "P5E_CPU1_PE2_TX_DP<14>")
	)
	(segment
		(start 149.708362 -334.783684)
		(end 151.55545 -345.256104)
		(width 0.14732)
		(layer "In15.Cu")
		(net "P5E_CPU1_PE2_TX_DP<14>")
	)
	(segment
		(start 140.787628 -245.842536)
		(end 140.298424 -247.374156)
		(width 0.14732)
		(layer "In15.Cu")
		(net "P5E_CPU1_PE2_TX_DP<14>")
	)
	(segment
		(start 135.792464 -224.8789)
		(end 135.801354 -224.88398)
		(width 0.0889)
		(layer "In15.Cu")
		(net "P5E_CPU1_PE2_TX_DP<14>")
	)
	(segment
		(start 125.133862 -397.429736)
		(end 123.512834 -399.569178)
		(width 0.14732)
		(layer "In15.Cu")
		(net "P5E_CPU1_PE2_TX_DP<14>")
	)
	(segment
		(start 133.41223 -224.118424)
		(end 133.501384 -224.094548)
		(width 0.0889)
		(layer "In15.Cu")
		(net "P5E_CPU1_PE2_TX_DP<14>")
	)
	(segment
		(start 139.645136 -229.475792)
		(end 140.342874 -231.006142)
		(width 0.14732)
		(layer "In15.Cu")
		(net "P5E_CPU1_PE2_TX_DP<14>")
	)
	(segment
		(start 137.28573 -227.116386)
		(end 137.301224 -227.13188)
		(width 0.0889)
		(layer "In15.Cu")
		(net "P5E_CPU1_PE2_TX_DP<14>")
	)
	(segment
		(start 143.646144 -327.942702)
		(end 149.708362 -334.783684)
		(width 0.14732)
		(layer "In15.Cu")
		(net "P5E_CPU1_PE2_TX_DP<14>")
	)
	(segment
		(start 123.512834 -400.563588)
		(end 123.218194 -400.858228)
		(width 0.14732)
		(layer "In15.Cu")
		(net "P5E_CPU1_PE2_TX_DP<14>")
	)
	(segment
		(start 136.732264 -226.506786)
		(end 136.733026 -226.507294)
		(width 0.0889)
		(layer "In15.Cu")
		(net "P5E_CPU1_PE2_TX_DP<14>")
	)
	(segment
		(start 126.730252 -395.116812)
		(end 126.466346 -395.4653)
		(width 0.14732)
		(layer "In15.Cu")
		(net "P5E_CPU1_PE2_TX_DP<14>")
	)
	(segment
		(start 135.32231 -224.065084)
		(end 135.323326 -224.065592)
		(width 0.0889)
		(layer "In15.Cu")
		(net "P5E_CPU1_PE2_TX_DP<14>")
	)
	(segment
		(start 140.027914 -247.546114)
		(end 139.75715 -247.718326)
		(width 0.14732)
		(layer "In15.Cu")
		(net "P5E_CPU1_PE2_TX_DP<14>")
	)
	(segment
		(start 140.298424 -247.374156)
		(end 140.027914 -247.546114)
		(width 0.14732)
		(layer "In15.Cu")
		(net "P5E_CPU1_PE2_TX_DP<14>")
	)
	(segment
		(start 140.687806 -255.888236)
		(end 141.307312 -256.750566)
		(width 0.14732)
		(layer "In15.Cu")
		(net "P5E_CPU1_PE2_TX_DP<14>")
	)
	(segment
		(start 137.301224 -227.13188)
		(end 139.645136 -229.475792)
		(width 0.14732)
		(layer "In15.Cu")
		(net "P5E_CPU1_PE2_TX_DP<14>")
	)
	(segment
		(start 139.355068 -247.999758)
		(end 138.964416 -248.390664)
		(width 0.14732)
		(layer "In15.Cu")
		(net "P5E_CPU1_PE2_TX_DP<14>")
	)
	(segment
		(start 133.255766 -224.389442)
		(end 133.41223 -224.118424)
		(width 0.0889)
		(layer "In15.Cu")
		(net "P5E_CPU1_PE2_TX_DP<14>")
	)
	(segment
		(start 136.262364 -225.69297)
		(end 136.271254 -225.69805)
		(width 0.0889)
		(layer "In15.Cu")
		(net "P5E_CPU1_PE2_TX_DP<14>")
	)
	(segment
		(start 123.512834 -399.569178)
		(end 123.512834 -400.563588)
		(width 0.14732)
		(layer "In15.Cu")
		(net "P5E_CPU1_PE2_TX_DP<14>")
	)
	(segment
		(start 135.780272 -224.871788)
		(end 135.792464 -224.8789)
		(width 0.0889)
		(layer "In15.Cu")
		(net "P5E_CPU1_PE2_TX_DP<14>")
	)
	(segment
		(start 140.337286 -255.06045)
		(end 140.337032 -255.06045)
		(width 0.14732)
		(layer "In15.Cu")
		(net "P5E_CPU1_PE2_TX_DP<14>")
	)
	(segment
		(start 139.75715 -247.718326)
		(end 139.355068 -247.999758)
		(width 0.14732)
		(layer "In15.Cu")
		(net "P5E_CPU1_PE2_TX_DP<14>")
	)
	(segment
		(start 141.277594 -244.310154)
		(end 140.787882 -245.842536)
		(width 0.14732)
		(layer "In15.Cu")
		(net "P5E_CPU1_PE2_TX_DP<14>")
	)
	(segment
		(start 142.072868 -259.517896)
		(end 139.26566 -309.977028)
		(width 0.14732)
		(layer "In15.Cu")
		(net "P5E_CPU1_PE2_TX_DP<14>")
	)
	(segment
		(start 134.9375 -224.07118)
		(end 134.947914 -224.065084)
		(width 0.0889)
		(layer "In15.Cu")
		(net "P5E_CPU1_PE2_TX_DP<14>")
	)
	(segment
		(start 126.90475 -395.092936)
		(end 126.730252 -395.116812)
		(width 0.14732)
		(layer "In15.Cu")
		(net "P5E_CPU1_PE2_TX_DP<14>")
	)
	(segment
		(start 126.904496 -395.092682)
		(end 126.90475 -395.092936)
		(width 0.14732)
		(layer "In15.Cu")
		(net "P5E_CPU1_PE2_TX_DP<14>")
	)
	(segment
		(start 140.337032 -255.06045)
		(end 140.687806 -255.888236)
		(width 0.14732)
		(layer "In15.Cu")
		(net "P5E_CPU1_PE2_TX_DP<14>")
	)
	(segment
		(start 151.55545 -345.256104)
		(end 151.089614 -347.897704)
		(width 0.14732)
		(layer "In15.Cu")
		(net "P5E_CPU1_PE2_TX_DP<14>")
	)
	(segment
		(start 139.26566 -309.977028)
		(end 143.646144 -327.942702)
		(width 0.14732)
		(layer "In15.Cu")
		(net "P5E_CPU1_PE2_TX_DP<14>")
	)
	(segment
		(start 135.979916 -225.203258)
		(end 135.979916 -225.2218)
		(width 0.0889)
		(layer "In15.Cu")
		(net "P5E_CPU1_PE2_TX_DP<14>")
	)
	(segment
		(start 126.490222 -395.639798)
		(end 126.22657 -395.987778)
		(width 0.14732)
		(layer "In15.Cu")
		(net "P5E_CPU1_PE2_TX_DP<14>")
	)
	(segment
		(start 136.733026 -226.507294)
		(end 136.741154 -226.511866)
		(width 0.0889)
		(layer "In15.Cu")
		(net "P5E_CPU1_PE2_TX_DP<14>")
	)
	(segment
		(start 125.373892 -396.90675)
		(end 125.109986 -397.255238)
		(width 0.14732)
		(layer "In15.Cu")
		(net "P5E_CPU1_PE2_TX_DP<14>")
	)
	(segment
		(start 140.787882 -245.842536)
		(end 140.787628 -245.842536)
		(width 0.14732)
		(layer "In15.Cu")
		(net "P5E_CPU1_PE2_TX_DP<14>")
	)
	(segment
		(start 125.812042 -396.53464)
		(end 125.54839 -396.88262)
		(width 0.14732)
		(layer "In15.Cu")
		(net "P5E_CPU1_PE2_TX_DP<14>")
	)
	(segment
		(start 141.307312 -256.750566)
		(end 142.072868 -259.517896)
		(width 0.14732)
		(layer "In15.Cu")
		(net "P5E_CPU1_PE2_TX_DP<14>")
	)
	(segment
		(start 135.323326 -224.065592)
		(end 135.3312 -224.070164)
		(width 0.0889)
		(layer "In15.Cu")
		(net "P5E_CPU1_PE2_TX_DP<14>")
	)
	(segment
		(start 151.089614 -347.897704)
		(end 149.896322 -361.53344)
		(width 0.14732)
		(layer "In15.Cu")
		(net "P5E_CPU1_PE2_TX_DP<14>")
	)
	(segment
		(start 136.741154 -226.511866)
		(end 137.28573 -227.056442)
		(width 0.0889)
		(layer "In15.Cu")
		(net "P5E_CPU1_PE2_TX_DP<14>")
	)
	(segment
		(start 138.964416 -248.390664)
		(end 138.964416 -251.254514)
		(width 0.14732)
		(layer "In15.Cu")
		(net "P5E_CPU1_PE2_TX_DP<14>")
	)
	(segment
		(start 125.54839 -396.88262)
		(end 125.373892 -396.90675)
		(width 0.14732)
		(layer "In15.Cu")
		(net "P5E_CPU1_PE2_TX_DP<14>")
	)
	(segment
		(start 126.052072 -396.011654)
		(end 125.788166 -396.360142)
		(width 0.14732)
		(layer "In15.Cu")
		(net "P5E_CPU1_PE2_TX_DP<14>")
	)
	(segment
		(start 138.964416 -251.254514)
		(end 139.995148 -254.252476)
		(width 0.14732)
		(layer "In15.Cu")
		(net "P5E_CPU1_PE2_TX_DP<14>")
	)
	(segment
		(start 146.960082 -368.623088)
		(end 146.959828 -368.623342)
		(width 0.14732)
		(layer "In15.Cu")
		(net "P5E_CPU1_PE2_TX_DP<14>")
	)
	(segment
		(start 125.109986 -397.255238)
		(end 125.133862 -397.429736)
		(width 0.14732)
		(layer "In15.Cu")
		(net "P5E_CPU1_PE2_TX_DP<14>")
	)
	(segment
		(start 139.995148 -254.252476)
		(end 140.337286 -255.06045)
		(width 0.14732)
		(layer "In15.Cu")
		(net "P5E_CPU1_PE2_TX_DP<14>")
	)
	(segment
		(start 136.449816 -226.017328)
		(end 136.45007 -226.03587)
		(width 0.0889)
		(layer "In15.Cu")
		(net "P5E_CPU1_PE2_TX_DP<14>")
	)
	(segment
		(start 146.959828 -368.623342)
		(end 146.959828 -368.623596)
		(width 0.14732)
		(layer "In15.Cu")
		(net "P5E_CPU1_PE2_TX_DP<14>")
	)
	(segment
		(start 126.22657 -395.987778)
		(end 126.052072 -396.011654)
		(width 0.14732)
		(layer "In15.Cu")
		(net "P5E_CPU1_PE2_TX_DP<14>")
	)
	(segment
		(start 146.959828 -368.623596)
		(end 126.904496 -395.092682)
		(width 0.14732)
		(layer "In15.Cu")
		(net "P5E_CPU1_PE2_TX_DP<14>")
	)
	(segment
		(start 140.342874 -231.006142)
		(end 141.277594 -244.310154)
		(width 0.14732)
		(layer "In15.Cu")
		(net "P5E_CPU1_PE2_TX_DP<14>")
	)
	(segment
		(start 149.896322 -361.53344)
		(end 146.960082 -368.623088)
		(width 0.14732)
		(layer "In15.Cu")
		(net "P5E_CPU1_PE2_TX_DP<14>")
	)
	(segment
		(start 125.788166 -396.360142)
		(end 125.812042 -396.53464)
		(width 0.14732)
		(layer "In15.Cu")
		(net "P5E_CPU1_PE2_TX_DP<14>")
	)
	(segment
		(start 126.466346 -395.4653)
		(end 126.490222 -395.639798)
		(width 0.14732)
		(layer "In15.Cu")
		(net "P5E_CPU1_PE2_TX_DP<14>")
	)
	(arc
		(start 134.382764 -224.065084)
		(mid 134.659323 -224.140827)
		(end 134.9375 -224.07118)
		(width 0.0889)
		(layer "In15.Cu")
		(net "P5E_CPU1_PE2_TX_DP<14>")
	)
	(arc
		(start 135.801354 -224.88398)
		(mid 135.932268 -225.02034)
		(end 135.979916 -225.203258)
		(width 0.0889)
		(layer "In15.Cu")
		(net "P5E_CPU1_PE2_TX_DP<14>")
	)
	(arc
		(start 136.45007 -226.03587)
		(mid 136.530143 -226.307911)
		(end 136.732264 -226.506786)
		(width 0.0889)
		(layer "In15.Cu")
		(net "P5E_CPU1_PE2_TX_DP<14>")
	)
	(arc
		(start 135.979916 -225.2218)
		(mid 136.060078 -225.493989)
		(end 136.262364 -225.69297)
		(width 0.0889)
		(layer "In15.Cu")
		(net "P5E_CPU1_PE2_TX_DP<14>")
	)
	(arc
		(start 134.008368 -224.065084)
		(mid 134.195566 -224.014941)
		(end 134.382764 -224.065084)
		(width 0.0889)
		(layer "In15.Cu")
		(net "P5E_CPU1_PE2_TX_DP<14>")
	)
	(arc
		(start 133.501384 -224.094548)
		(mid 133.758382 -224.140036)
		(end 134.008368 -224.065084)
		(width 0.0889)
		(layer "In15.Cu")
		(net "P5E_CPU1_PE2_TX_DP<14>")
	)
	(arc
		(start 135.3312 -224.070164)
		(mid 135.462114 -224.206524)
		(end 135.509762 -224.389442)
		(width 0.0889)
		(layer "In15.Cu")
		(net "P5E_CPU1_PE2_TX_DP<14>")
	)
	(arc
		(start 134.947914 -224.065084)
		(mid 135.135112 -224.014941)
		(end 135.32231 -224.065084)
		(width 0.0889)
		(layer "In15.Cu")
		(net "P5E_CPU1_PE2_TX_DP<14>")
	)
	(arc
		(start 135.509762 -224.389442)
		(mid 135.581997 -224.665966)
		(end 135.780272 -224.871788)
		(width 0.0889)
		(layer "In15.Cu")
		(net "P5E_CPU1_PE2_TX_DP<14>")
	)
	(arc
		(start 136.271254 -225.69805)
		(mid 136.402168 -225.83441)
		(end 136.449816 -226.017328)
		(width 0.0889)
		(layer "In15.Cu")
		(net "P5E_CPU1_PE2_TX_DP<14>")
	)
	(segment
		(start 132.785866 -225.203512)
		(end 132.785612 -225.203258)
		(width 0.13208)
		(layer "F.Cu")
		(net "P5E_CPU1_PE2_TX_DP<13>")
	)
	(segment
		(start 132.785866 -225.739198)
		(end 132.785866 -225.203512)
		(width 0.13208)
		(layer "F.Cu")
		(net "P5E_CPU1_PE2_TX_DP<13>")
	)
	(segment
		(start 126.260606 -402.104352)
		(end 126.256034 -402.104352)
		(width 0.13208)
		(layer "F.Cu")
		(net "P5E_CPU1_PE2_TX_DP<13>")
	)
	(segment
		(start 126.586996 -401.16379)
		(end 126.586996 -401.777962)
		(width 0.13208)
		(layer "F.Cu")
		(net "P5E_CPU1_PE2_TX_DP<13>")
	)
	(segment
		(start 126.586996 -401.777962)
		(end 126.260606 -402.104352)
		(width 0.13208)
		(layer "F.Cu")
		(net "P5E_CPU1_PE2_TX_DP<13>")
	)
	(segment
		(start 126.281434 -400.858228)
		(end 126.586996 -401.16379)
		(width 0.13208)
		(layer "F.Cu")
		(net "P5E_CPU1_PE2_TX_DP<13>")
	)
	(segment
		(start 140.276834 -309.76189)
		(end 144.525492 -327.458324)
		(width 0.14732)
		(layer "In15.Cu")
		(net "P5E_CPU1_PE2_TX_DP<13>")
	)
	(segment
		(start 140.77315 -253.64821)
		(end 141.384528 -255.123188)
		(width 0.14732)
		(layer "In15.Cu")
		(net "P5E_CPU1_PE2_TX_DP<13>")
	)
	(segment
		(start 143.099536 -259.378704)
		(end 140.276834 -309.76189)
		(width 0.14732)
		(layer "In15.Cu")
		(net "P5E_CPU1_PE2_TX_DP<13>")
	)
	(segment
		(start 137.104882 -225.649536)
		(end 137.451084 -225.995738)
		(width 0.0889)
		(layer "In15.Cu")
		(net "P5E_CPU1_PE2_TX_DP<13>")
	)
	(segment
		(start 140.261594 -228.478842)
		(end 141.315948 -230.790242)
		(width 0.14732)
		(layer "In15.Cu")
		(net "P5E_CPU1_PE2_TX_DP<13>")
	)
	(segment
		(start 137.992612 -226.209606)
		(end 138.008106 -226.2251)
		(width 0.0889)
		(layer "In15.Cu")
		(net "P5E_CPU1_PE2_TX_DP<13>")
	)
	(segment
		(start 126.576074 -399.67281)
		(end 126.576074 -400.563588)
		(width 0.14732)
		(layer "In15.Cu")
		(net "P5E_CPU1_PE2_TX_DP<13>")
	)
	(segment
		(start 140.326618 -252.182884)
		(end 140.65631 -253.31547)
		(width 0.14732)
		(layer "In15.Cu")
		(net "P5E_CPU1_PE2_TX_DP<13>")
	)
	(segment
		(start 138.008106 -226.2251)
		(end 139.040108 -227.257356)
		(width 0.14732)
		(layer "In15.Cu")
		(net "P5E_CPU1_PE2_TX_DP<13>")
	)
	(segment
		(start 132.785612 -225.203258)
		(end 132.629148 -224.93224)
		(width 0.0889)
		(layer "In15.Cu")
		(net "P5E_CPU1_PE2_TX_DP<13>")
	)
	(segment
		(start 139.349226 -227.73894)
		(end 139.521692 -227.73894)
		(width 0.14732)
		(layer "In15.Cu")
		(net "P5E_CPU1_PE2_TX_DP<13>")
	)
	(segment
		(start 142.273528 -244.346476)
		(end 140.944346 -248.426732)
		(width 0.14732)
		(layer "In15.Cu")
		(net "P5E_CPU1_PE2_TX_DP<13>")
	)
	(segment
		(start 140.65631 -253.31547)
		(end 140.77315 -253.64821)
		(width 0.14732)
		(layer "In15.Cu")
		(net "P5E_CPU1_PE2_TX_DP<13>")
	)
	(segment
		(start 136.919716 -225.203258)
		(end 136.919716 -225.213164)
		(width 0.0889)
		(layer "In15.Cu")
		(net "P5E_CPU1_PE2_TX_DP<13>")
	)
	(segment
		(start 140.435076 -249.154442)
		(end 140.224764 -250.344686)
		(width 0.14732)
		(layer "In15.Cu")
		(net "P5E_CPU1_PE2_TX_DP<13>")
	)
	(segment
		(start 137.451084 -225.995738)
		(end 137.838688 -225.995738)
		(width 0.0889)
		(layer "In15.Cu")
		(net "P5E_CPU1_PE2_TX_DP<13>")
	)
	(segment
		(start 139.521692 -227.73894)
		(end 140.261594 -228.478842)
		(width 0.14732)
		(layer "In15.Cu")
		(net "P5E_CPU1_PE2_TX_DP<13>")
	)
	(segment
		(start 147.77847 -369.151916)
		(end 129.569464 -395.363446)
		(width 0.14732)
		(layer "In15.Cu")
		(net "P5E_CPU1_PE2_TX_DP<13>")
	)
	(segment
		(start 129.569464 -395.363446)
		(end 129.396236 -395.394688)
		(width 0.14732)
		(layer "In15.Cu")
		(net "P5E_CPU1_PE2_TX_DP<13>")
	)
	(segment
		(start 139.040108 -227.429822)
		(end 139.349226 -227.73894)
		(width 0.14732)
		(layer "In15.Cu")
		(net "P5E_CPU1_PE2_TX_DP<13>")
	)
	(segment
		(start 128.11506 -397.239236)
		(end 127.865632 -397.598392)
		(width 0.14732)
		(layer "In15.Cu")
		(net "P5E_CPU1_PE2_TX_DP<13>")
	)
	(segment
		(start 144.525492 -327.458324)
		(end 150.579328 -334.213708)
		(width 0.14732)
		(layer "In15.Cu")
		(net "P5E_CPU1_PE2_TX_DP<13>")
	)
	(segment
		(start 133.059678 -224.070164)
		(end 133.068568 -224.065084)
		(width 0.0889)
		(layer "In15.Cu")
		(net "P5E_CPU1_PE2_TX_DP<13>")
	)
	(segment
		(start 129.396236 -395.394688)
		(end 129.146808 -395.753844)
		(width 0.14732)
		(layer "In15.Cu")
		(net "P5E_CPU1_PE2_TX_DP<13>")
	)
	(segment
		(start 150.902416 -361.794806)
		(end 147.77847 -369.151916)
		(width 0.14732)
		(layer "In15.Cu")
		(net "P5E_CPU1_PE2_TX_DP<13>")
	)
	(segment
		(start 136.732264 -224.8789)
		(end 136.741154 -224.88398)
		(width 0.0889)
		(layer "In15.Cu")
		(net "P5E_CPU1_PE2_TX_DP<13>")
	)
	(segment
		(start 136.262364 -224.065084)
		(end 136.263888 -224.065846)
		(width 0.0889)
		(layer "In15.Cu")
		(net "P5E_CPU1_PE2_TX_DP<13>")
	)
	(segment
		(start 151.202644 -358.35717)
		(end 150.902416 -361.794806)
		(width 0.14732)
		(layer "In15.Cu")
		(net "P5E_CPU1_PE2_TX_DP<13>")
	)
	(segment
		(start 139.040108 -227.257356)
		(end 139.040108 -227.429822)
		(width 0.14732)
		(layer "In15.Cu")
		(net "P5E_CPU1_PE2_TX_DP<13>")
	)
	(segment
		(start 129.146808 -395.753844)
		(end 129.17805 -395.927072)
		(width 0.14732)
		(layer "In15.Cu")
		(net "P5E_CPU1_PE2_TX_DP<13>")
	)
	(segment
		(start 132.629148 -224.93224)
		(end 132.653278 -224.843086)
		(width 0.0889)
		(layer "In15.Cu")
		(net "P5E_CPU1_PE2_TX_DP<13>")
	)
	(segment
		(start 150.579328 -334.213708)
		(end 152.561798 -345.45397)
		(width 0.14732)
		(layer "In15.Cu")
		(net "P5E_CPU1_PE2_TX_DP<13>")
	)
	(segment
		(start 136.256268 -224.061528)
		(end 136.262364 -224.065084)
		(width 0.0889)
		(layer "In15.Cu")
		(net "P5E_CPU1_PE2_TX_DP<13>")
	)
	(segment
		(start 136.263888 -224.065846)
		(end 136.271254 -224.070164)
		(width 0.0889)
		(layer "In15.Cu")
		(net "P5E_CPU1_PE2_TX_DP<13>")
	)
	(segment
		(start 128.288288 -397.207994)
		(end 128.11506 -397.239236)
		(width 0.14732)
		(layer "In15.Cu")
		(net "P5E_CPU1_PE2_TX_DP<13>")
	)
	(segment
		(start 136.449816 -224.389442)
		(end 136.449816 -224.399348)
		(width 0.0889)
		(layer "In15.Cu")
		(net "P5E_CPU1_PE2_TX_DP<13>")
	)
	(segment
		(start 133.351016 -223.585532)
		(end 133.351016 -223.575626)
		(width 0.0889)
		(layer "In15.Cu")
		(net "P5E_CPU1_PE2_TX_DP<13>")
	)
	(segment
		(start 140.224764 -250.344686)
		(end 140.326618 -252.182884)
		(width 0.14732)
		(layer "In15.Cu")
		(net "P5E_CPU1_PE2_TX_DP<13>")
	)
	(segment
		(start 135.979662 -223.56699)
		(end 135.979662 -223.575626)
		(width 0.0889)
		(layer "In15.Cu")
		(net "P5E_CPU1_PE2_TX_DP<13>")
	)
	(segment
		(start 128.50622 -396.676118)
		(end 128.537462 -396.849346)
		(width 0.14732)
		(layer "In15.Cu")
		(net "P5E_CPU1_PE2_TX_DP<13>")
	)
	(segment
		(start 152.561798 -345.45397)
		(end 152.105614 -348.041976)
		(width 0.14732)
		(layer "In15.Cu")
		(net "P5E_CPU1_PE2_TX_DP<13>")
	)
	(segment
		(start 141.315948 -230.790242)
		(end 142.273528 -244.346476)
		(width 0.14732)
		(layer "In15.Cu")
		(net "P5E_CPU1_PE2_TX_DP<13>")
	)
	(segment
		(start 137.992612 -226.149662)
		(end 137.992612 -226.209606)
		(width 0.0889)
		(layer "In15.Cu")
		(net "P5E_CPU1_PE2_TX_DP<13>")
	)
	(segment
		(start 142.368016 -256.528062)
		(end 143.099536 -259.378704)
		(width 0.14732)
		(layer "In15.Cu")
		(net "P5E_CPU1_PE2_TX_DP<13>")
	)
	(segment
		(start 141.384528 -255.123188)
		(end 142.368016 -256.528062)
		(width 0.14732)
		(layer "In15.Cu")
		(net "P5E_CPU1_PE2_TX_DP<13>")
	)
	(segment
		(start 128.928876 -396.28572)
		(end 128.755648 -396.316962)
		(width 0.14732)
		(layer "In15.Cu")
		(net "P5E_CPU1_PE2_TX_DP<13>")
	)
	(segment
		(start 137.838688 -225.995738)
		(end 137.992612 -226.149662)
		(width 0.0889)
		(layer "In15.Cu")
		(net "P5E_CPU1_PE2_TX_DP<13>")
	)
	(segment
		(start 128.537462 -396.849346)
		(end 128.288288 -397.207994)
		(width 0.14732)
		(layer "In15.Cu")
		(net "P5E_CPU1_PE2_TX_DP<13>")
	)
	(segment
		(start 152.105614 -348.041976)
		(end 151.203152 -358.35717)
		(width 0.14732)
		(layer "In15.Cu")
		(net "P5E_CPU1_PE2_TX_DP<13>")
	)
	(segment
		(start 126.576074 -400.563588)
		(end 126.281434 -400.858228)
		(width 0.14732)
		(layer "In15.Cu")
		(net "P5E_CPU1_PE2_TX_DP<13>")
	)
	(segment
		(start 127.896874 -397.77162)
		(end 126.576074 -399.67281)
		(width 0.14732)
		(layer "In15.Cu")
		(net "P5E_CPU1_PE2_TX_DP<13>")
	)
	(segment
		(start 140.944346 -248.426732)
		(end 140.435076 -249.154442)
		(width 0.14732)
		(layer "In15.Cu")
		(net "P5E_CPU1_PE2_TX_DP<13>")
	)
	(segment
		(start 151.203152 -358.35717)
		(end 151.202644 -358.35717)
		(width 0.14732)
		(layer "In15.Cu")
		(net "P5E_CPU1_PE2_TX_DP<13>")
	)
	(segment
		(start 129.17805 -395.927072)
		(end 128.928876 -396.28572)
		(width 0.14732)
		(layer "In15.Cu")
		(net "P5E_CPU1_PE2_TX_DP<13>")
	)
	(segment
		(start 127.865632 -397.598392)
		(end 127.896874 -397.77162)
		(width 0.14732)
		(layer "In15.Cu")
		(net "P5E_CPU1_PE2_TX_DP<13>")
	)
	(segment
		(start 133.529578 -223.256348)
		(end 133.538468 -223.251268)
		(width 0.0889)
		(layer "In15.Cu")
		(net "P5E_CPU1_PE2_TX_DP<13>")
	)
	(segment
		(start 128.755648 -396.316962)
		(end 128.50622 -396.676118)
		(width 0.14732)
		(layer "In15.Cu")
		(net "P5E_CPU1_PE2_TX_DP<13>")
	)
	(arc
		(start 136.449816 -224.399348)
		(mid 136.527927 -224.676297)
		(end 136.732264 -224.8789)
		(width 0.0889)
		(layer "In15.Cu")
		(net "P5E_CPU1_PE2_TX_DP<13>")
	)
	(arc
		(start 133.912864 -223.251268)
		(mid 134.195566 -223.32701)
		(end 134.478268 -223.251268)
		(width 0.0889)
		(layer "In15.Cu")
		(net "P5E_CPU1_PE2_TX_DP<13>")
	)
	(arc
		(start 135.418068 -223.251268)
		(mid 135.605266 -223.201125)
		(end 135.792464 -223.251268)
		(width 0.0889)
		(layer "In15.Cu")
		(net "P5E_CPU1_PE2_TX_DP<13>")
	)
	(arc
		(start 136.741154 -224.88398)
		(mid 136.872068 -225.02034)
		(end 136.919716 -225.203258)
		(width 0.0889)
		(layer "In15.Cu")
		(net "P5E_CPU1_PE2_TX_DP<13>")
	)
	(arc
		(start 135.792464 -223.251268)
		(mid 135.927397 -223.384622)
		(end 135.979662 -223.56699)
		(width 0.0889)
		(layer "In15.Cu")
		(net "P5E_CPU1_PE2_TX_DP<13>")
	)
	(arc
		(start 136.271254 -224.070164)
		(mid 136.402168 -224.206524)
		(end 136.449816 -224.389442)
		(width 0.0889)
		(layer "In15.Cu")
		(net "P5E_CPU1_PE2_TX_DP<13>")
	)
	(arc
		(start 135.979662 -223.575626)
		(mid 136.053653 -223.855192)
		(end 136.256268 -224.061528)
		(width 0.0889)
		(layer "In15.Cu")
		(net "P5E_CPU1_PE2_TX_DP<13>")
	)
	(arc
		(start 133.351016 -223.575626)
		(mid 133.398695 -223.392726)
		(end 133.529578 -223.256348)
		(width 0.0889)
		(layer "In15.Cu")
		(net "P5E_CPU1_PE2_TX_DP<13>")
	)
	(arc
		(start 134.852664 -223.251268)
		(mid 135.135366 -223.32701)
		(end 135.418068 -223.251268)
		(width 0.0889)
		(layer "In15.Cu")
		(net "P5E_CPU1_PE2_TX_DP<13>")
	)
	(arc
		(start 134.478268 -223.251268)
		(mid 134.665466 -223.201125)
		(end 134.852664 -223.251268)
		(width 0.0889)
		(layer "In15.Cu")
		(net "P5E_CPU1_PE2_TX_DP<13>")
	)
	(arc
		(start 133.068568 -224.065084)
		(mid 133.272903 -223.862479)
		(end 133.351016 -223.585532)
		(width 0.0889)
		(layer "In15.Cu")
		(net "P5E_CPU1_PE2_TX_DP<13>")
	)
	(arc
		(start 132.670296 -224.829878)
		(mid 132.825694 -224.633597)
		(end 132.881116 -224.389442)
		(width 0.0889)
		(layer "In15.Cu")
		(net "P5E_CPU1_PE2_TX_DP<13>")
	)
	(arc
		(start 132.881116 -224.389442)
		(mid 132.928795 -224.206542)
		(end 133.059678 -224.070164)
		(width 0.0889)
		(layer "In15.Cu")
		(net "P5E_CPU1_PE2_TX_DP<13>")
	)
	(arc
		(start 136.919716 -225.213164)
		(mid 136.969949 -225.449308)
		(end 137.104882 -225.649536)
		(width 0.0889)
		(layer "In15.Cu")
		(net "P5E_CPU1_PE2_TX_DP<13>")
	)
	(arc
		(start 133.538468 -223.251268)
		(mid 133.725666 -223.201125)
		(end 133.912864 -223.251268)
		(width 0.0889)
		(layer "In15.Cu")
		(net "P5E_CPU1_PE2_TX_DP<13>")
	)
	(arc
		(start 132.653278 -224.843086)
		(mid 132.66185 -224.836564)
		(end 132.670296 -224.829878)
		(width 0.0889)
		(layer "In15.Cu")
		(net "P5E_CPU1_PE2_TX_DP<13>")
	)
	(segment
		(start 131.375912 -224.389696)
		(end 131.376166 -224.389442)
		(width 0.13208)
		(layer "F.Cu")
		(net "P5E_CPU1_PE2_TX_DP<12>")
	)
	(segment
		(start 129.323846 -402.104352)
		(end 129.319274 -402.104352)
		(width 0.13208)
		(layer "F.Cu")
		(net "P5E_CPU1_PE2_TX_DP<12>")
	)
	(segment
		(start 129.650236 -401.16379)
		(end 129.650236 -401.777962)
		(width 0.13208)
		(layer "F.Cu")
		(net "P5E_CPU1_PE2_TX_DP<12>")
	)
	(segment
		(start 129.650236 -401.777962)
		(end 129.323846 -402.104352)
		(width 0.13208)
		(layer "F.Cu")
		(net "P5E_CPU1_PE2_TX_DP<12>")
	)
	(segment
		(start 131.375912 -224.925382)
		(end 131.375912 -224.389696)
		(width 0.13208)
		(layer "F.Cu")
		(net "P5E_CPU1_PE2_TX_DP<12>")
	)
	(segment
		(start 129.344674 -400.858228)
		(end 129.650236 -401.16379)
		(width 0.13208)
		(layer "F.Cu")
		(net "P5E_CPU1_PE2_TX_DP<12>")
	)
	(segment
		(start 136.262364 -222.437198)
		(end 136.272778 -222.443294)
		(width 0.0889)
		(layer "In15.Cu")
		(net "P5E_CPU1_PE2_TX_DP<12>")
	)
	(segment
		(start 131.93522 -396.044674)
		(end 131.701794 -396.413736)
		(width 0.14732)
		(layer "In15.Cu")
		(net "P5E_CPU1_PE2_TX_DP<12>")
	)
	(segment
		(start 131.296156 -396.82166)
		(end 131.334764 -396.993364)
		(width 0.14732)
		(layer "In15.Cu")
		(net "P5E_CPU1_PE2_TX_DP<12>")
	)
	(segment
		(start 139.037568 -223.658176)
		(end 139.037568 -223.71812)
		(width 0.0889)
		(layer "In15.Cu")
		(net "P5E_CPU1_PE2_TX_DP<12>")
	)
	(segment
		(start 132.597906 -223.251776)
		(end 132.598668 -223.251268)
		(width 0.0889)
		(layer "In15.Cu")
		(net "P5E_CPU1_PE2_TX_DP<12>")
	)
	(segment
		(start 132.881116 -222.780098)
		(end 132.881116 -222.761556)
		(width 0.0889)
		(layer "In15.Cu")
		(net "P5E_CPU1_PE2_TX_DP<12>")
	)
	(segment
		(start 129.639314 -399.671286)
		(end 129.639314 -400.563588)
		(width 0.14732)
		(layer "In15.Cu")
		(net "P5E_CPU1_PE2_TX_DP<12>")
	)
	(segment
		(start 151.824436 -362.148882)
		(end 148.851112 -369.324382)
		(width 0.14732)
		(layer "In15.Cu")
		(net "P5E_CPU1_PE2_TX_DP<12>")
	)
	(segment
		(start 141.28496 -250.44146)
		(end 141.28496 -252.137418)
		(width 0.14732)
		(layer "In15.Cu")
		(net "P5E_CPU1_PE2_TX_DP<12>")
	)
	(segment
		(start 133.059678 -222.442278)
		(end 133.068568 -222.437198)
		(width 0.0889)
		(layer "In15.Cu")
		(net "P5E_CPU1_PE2_TX_DP<12>")
	)
	(segment
		(start 129.639314 -400.563588)
		(end 129.344674 -400.858228)
		(width 0.14732)
		(layer "In15.Cu")
		(net "P5E_CPU1_PE2_TX_DP<12>")
	)
	(segment
		(start 141.693392 -228.442266)
		(end 142.244572 -230.525066)
		(width 0.14732)
		(layer "In15.Cu")
		(net "P5E_CPU1_PE2_TX_DP<12>")
	)
	(segment
		(start 132.1308 -395.503654)
		(end 131.896866 -395.87297)
		(width 0.14732)
		(layer "In15.Cu")
		(net "P5E_CPU1_PE2_TX_DP<12>")
	)
	(segment
		(start 132.30225 -395.464792)
		(end 132.302504 -395.465046)
		(width 0.14732)
		(layer "In15.Cu")
		(net "P5E_CPU1_PE2_TX_DP<12>")
	)
	(segment
		(start 130.92938 -397.401034)
		(end 130.695446 -397.77035)
		(width 0.14732)
		(layer "In15.Cu")
		(net "P5E_CPU1_PE2_TX_DP<12>")
	)
	(segment
		(start 131.376166 -224.389442)
		(end 131.53263 -224.118424)
		(width 0.0889)
		(layer "In15.Cu")
		(net "P5E_CPU1_PE2_TX_DP<12>")
	)
	(segment
		(start 132.302504 -395.465046)
		(end 132.1308 -395.503654)
		(width 0.14732)
		(layer "In15.Cu")
		(net "P5E_CPU1_PE2_TX_DP<12>")
	)
	(segment
		(start 145.350484 -326.897492)
		(end 151.459438 -333.802228)
		(width 0.14732)
		(layer "In15.Cu")
		(net "P5E_CPU1_PE2_TX_DP<12>")
	)
	(segment
		(start 132.589778 -223.256348)
		(end 132.597906 -223.251776)
		(width 0.0889)
		(layer "In15.Cu")
		(net "P5E_CPU1_PE2_TX_DP<12>")
	)
	(segment
		(start 141.492224 -249.266456)
		(end 141.28496 -250.44146)
		(width 0.14732)
		(layer "In15.Cu")
		(net "P5E_CPU1_PE2_TX_DP<12>")
	)
	(segment
		(start 139.261088 -223.94164)
		(end 141.693392 -228.442266)
		(width 0.14732)
		(layer "In15.Cu")
		(net "P5E_CPU1_PE2_TX_DP<12>")
	)
	(segment
		(start 137.20191 -222.437198)
		(end 137.202926 -222.437706)
		(width 0.0889)
		(layer "In15.Cu")
		(net "P5E_CPU1_PE2_TX_DP<12>")
	)
	(segment
		(start 143.23441 -244.452902)
		(end 141.81709 -248.802144)
		(width 0.14732)
		(layer "In15.Cu")
		(net "P5E_CPU1_PE2_TX_DP<12>")
	)
	(segment
		(start 141.562582 -253.08941)
		(end 141.633448 -253.29134)
		(width 0.14732)
		(layer "In15.Cu")
		(net "P5E_CPU1_PE2_TX_DP<12>")
	)
	(segment
		(start 130.695446 -397.77035)
		(end 130.734054 -397.942054)
		(width 0.14732)
		(layer "In15.Cu")
		(net "P5E_CPU1_PE2_TX_DP<12>")
	)
	(segment
		(start 141.21892 -309.644288)
		(end 145.350484 -326.897492)
		(width 0.14732)
		(layer "In15.Cu")
		(net "P5E_CPU1_PE2_TX_DP<12>")
	)
	(segment
		(start 141.633448 -253.29134)
		(end 142.20825 -254.67818)
		(width 0.14732)
		(layer "In15.Cu")
		(net "P5E_CPU1_PE2_TX_DP<12>")
	)
	(segment
		(start 141.81709 -248.802144)
		(end 141.492224 -249.266456)
		(width 0.14732)
		(layer "In15.Cu")
		(net "P5E_CPU1_PE2_TX_DP<12>")
	)
	(segment
		(start 131.53263 -224.118424)
		(end 131.62153 -224.094802)
		(width 0.0889)
		(layer "In15.Cu")
		(net "P5E_CPU1_PE2_TX_DP<12>")
	)
	(segment
		(start 131.334764 -396.993364)
		(end 131.101084 -397.362426)
		(width 0.14732)
		(layer "In15.Cu")
		(net "P5E_CPU1_PE2_TX_DP<12>")
	)
	(segment
		(start 153.067258 -347.942662)
		(end 151.824436 -362.148882)
		(width 0.14732)
		(layer "In15.Cu")
		(net "P5E_CPU1_PE2_TX_DP<12>")
	)
	(segment
		(start 153.510488 -345.429332)
		(end 153.067258 -347.942662)
		(width 0.14732)
		(layer "In15.Cu")
		(net "P5E_CPU1_PE2_TX_DP<12>")
	)
	(segment
		(start 142.20825 -254.67818)
		(end 143.32966 -256.280158)
		(width 0.14732)
		(layer "In15.Cu")
		(net "P5E_CPU1_PE2_TX_DP<12>")
	)
	(segment
		(start 151.459438 -333.802228)
		(end 153.510488 -345.429332)
		(width 0.14732)
		(layer "In15.Cu")
		(net "P5E_CPU1_PE2_TX_DP<12>")
	)
	(segment
		(start 134.382764 -222.437198)
		(end 134.397496 -222.445834)
		(width 0.0889)
		(layer "In15.Cu")
		(net "P5E_CPU1_PE2_TX_DP<12>")
	)
	(segment
		(start 131.701794 -396.413736)
		(end 131.53009 -396.452344)
		(width 0.14732)
		(layer "In15.Cu")
		(net "P5E_CPU1_PE2_TX_DP<12>")
	)
	(segment
		(start 141.28496 -252.137418)
		(end 141.562582 -253.08941)
		(width 0.14732)
		(layer "In15.Cu")
		(net "P5E_CPU1_PE2_TX_DP<12>")
	)
	(segment
		(start 144.078706 -259.28701)
		(end 141.21892 -309.644288)
		(width 0.14732)
		(layer "In15.Cu")
		(net "P5E_CPU1_PE2_TX_DP<12>")
	)
	(segment
		(start 131.53009 -396.452344)
		(end 131.296156 -396.82166)
		(width 0.14732)
		(layer "In15.Cu")
		(net "P5E_CPU1_PE2_TX_DP<12>")
	)
	(segment
		(start 143.32966 -256.280158)
		(end 144.078706 -259.28701)
		(width 0.14732)
		(layer "In15.Cu")
		(net "P5E_CPU1_PE2_TX_DP<12>")
	)
	(segment
		(start 138.689842 -223.31045)
		(end 139.037568 -223.658176)
		(width 0.0889)
		(layer "In15.Cu")
		(net "P5E_CPU1_PE2_TX_DP<12>")
	)
	(segment
		(start 139.037568 -223.71812)
		(end 139.045696 -223.726248)
		(width 0.0889)
		(layer "In15.Cu")
		(net "P5E_CPU1_PE2_TX_DP<12>")
	)
	(segment
		(start 137.202926 -222.437706)
		(end 137.2108 -222.442278)
		(width 0.0889)
		(layer "In15.Cu")
		(net "P5E_CPU1_PE2_TX_DP<12>")
	)
	(segment
		(start 131.896866 -395.87297)
		(end 131.93522 -396.044674)
		(width 0.14732)
		(layer "In15.Cu")
		(net "P5E_CPU1_PE2_TX_DP<12>")
	)
	(segment
		(start 148.851112 -369.324382)
		(end 132.30225 -395.464792)
		(width 0.14732)
		(layer "In15.Cu")
		(net "P5E_CPU1_PE2_TX_DP<12>")
	)
	(segment
		(start 142.244572 -230.525066)
		(end 143.23441 -244.452902)
		(width 0.14732)
		(layer "In15.Cu")
		(net "P5E_CPU1_PE2_TX_DP<12>")
	)
	(segment
		(start 131.101084 -397.362426)
		(end 130.92938 -397.401034)
		(width 0.14732)
		(layer "In15.Cu")
		(net "P5E_CPU1_PE2_TX_DP<12>")
	)
	(segment
		(start 139.045696 -223.726248)
		(end 139.261088 -223.94164)
		(width 0.14732)
		(layer "In15.Cu")
		(net "P5E_CPU1_PE2_TX_DP<12>")
	)
	(segment
		(start 132.128768 -224.065084)
		(end 132.134864 -224.061528)
		(width 0.0889)
		(layer "In15.Cu")
		(net "P5E_CPU1_PE2_TX_DP<12>")
	)
	(segment
		(start 130.734054 -397.942054)
		(end 129.639314 -399.671286)
		(width 0.14732)
		(layer "In15.Cu")
		(net "P5E_CPU1_PE2_TX_DP<12>")
	)
	(segment
		(start 137.389362 -222.761556)
		(end 137.389362 -222.769176)
		(width 0.0889)
		(layer "In15.Cu")
		(net "P5E_CPU1_PE2_TX_DP<12>")
	)
	(arc
		(start 134.397496 -222.445834)
		(mid 134.673971 -222.513154)
		(end 134.948168 -222.437198)
		(width 0.0889)
		(layer "In15.Cu")
		(net "P5E_CPU1_PE2_TX_DP<12>")
	)
	(arc
		(start 132.411216 -223.575626)
		(mid 132.458895 -223.392726)
		(end 132.589778 -223.256348)
		(width 0.0889)
		(layer "In15.Cu")
		(net "P5E_CPU1_PE2_TX_DP<12>")
	)
	(arc
		(start 136.827514 -222.437198)
		(mid 137.014712 -222.387055)
		(end 137.20191 -222.437198)
		(width 0.0889)
		(layer "In15.Cu")
		(net "P5E_CPU1_PE2_TX_DP<12>")
	)
	(arc
		(start 137.389362 -222.769176)
		(mid 137.466991 -223.047589)
		(end 137.672064 -223.251268)
		(width 0.0889)
		(layer "In15.Cu")
		(net "P5E_CPU1_PE2_TX_DP<12>")
	)
	(arc
		(start 134.008368 -222.437198)
		(mid 134.195566 -222.387055)
		(end 134.382764 -222.437198)
		(width 0.0889)
		(layer "In15.Cu")
		(net "P5E_CPU1_PE2_TX_DP<12>")
	)
	(arc
		(start 137.672064 -223.251268)
		(mid 137.954766 -223.32701)
		(end 138.237468 -223.251268)
		(width 0.0889)
		(layer "In15.Cu")
		(net "P5E_CPU1_PE2_TX_DP<12>")
	)
	(arc
		(start 132.881116 -222.761556)
		(mid 132.928795 -222.578656)
		(end 133.059678 -222.442278)
		(width 0.0889)
		(layer "In15.Cu")
		(net "P5E_CPU1_PE2_TX_DP<12>")
	)
	(arc
		(start 136.272778 -222.443294)
		(mid 136.550956 -222.513017)
		(end 136.827514 -222.437198)
		(width 0.0889)
		(layer "In15.Cu")
		(net "P5E_CPU1_PE2_TX_DP<12>")
	)
	(arc
		(start 138.611864 -223.251268)
		(mid 138.652794 -223.278301)
		(end 138.689842 -223.31045)
		(width 0.0889)
		(layer "In15.Cu")
		(net "P5E_CPU1_PE2_TX_DP<12>")
	)
	(arc
		(start 135.887968 -222.437198)
		(mid 136.075166 -222.387055)
		(end 136.262364 -222.437198)
		(width 0.0889)
		(layer "In15.Cu")
		(net "P5E_CPU1_PE2_TX_DP<12>")
	)
	(arc
		(start 132.598668 -223.251268)
		(mid 132.800954 -223.052287)
		(end 132.881116 -222.780098)
		(width 0.0889)
		(layer "In15.Cu")
		(net "P5E_CPU1_PE2_TX_DP<12>")
	)
	(arc
		(start 133.068568 -222.437198)
		(mid 133.255766 -222.387055)
		(end 133.442964 -222.437198)
		(width 0.0889)
		(layer "In15.Cu")
		(net "P5E_CPU1_PE2_TX_DP<12>")
	)
	(arc
		(start 132.134864 -224.061528)
		(mid 132.337277 -223.855115)
		(end 132.411216 -223.575626)
		(width 0.0889)
		(layer "In15.Cu")
		(net "P5E_CPU1_PE2_TX_DP<12>")
	)
	(arc
		(start 133.442964 -222.437198)
		(mid 133.725666 -222.512974)
		(end 134.008368 -222.437198)
		(width 0.0889)
		(layer "In15.Cu")
		(net "P5E_CPU1_PE2_TX_DP<12>")
	)
	(arc
		(start 131.62153 -224.094802)
		(mid 131.631397 -224.098961)
		(end 131.641342 -224.10293)
		(width 0.0889)
		(layer "In15.Cu")
		(net "P5E_CPU1_PE2_TX_DP<12>")
	)
	(arc
		(start 134.948168 -222.437198)
		(mid 135.135366 -222.387055)
		(end 135.322564 -222.437198)
		(width 0.0889)
		(layer "In15.Cu")
		(net "P5E_CPU1_PE2_TX_DP<12>")
	)
	(arc
		(start 138.237468 -223.251268)
		(mid 138.424666 -223.201125)
		(end 138.611864 -223.251268)
		(width 0.0889)
		(layer "In15.Cu")
		(net "P5E_CPU1_PE2_TX_DP<12>")
	)
	(arc
		(start 135.322564 -222.437198)
		(mid 135.605266 -222.512974)
		(end 135.887968 -222.437198)
		(width 0.0889)
		(layer "In15.Cu")
		(net "P5E_CPU1_PE2_TX_DP<12>")
	)
	(arc
		(start 137.2108 -222.442278)
		(mid 137.341714 -222.578638)
		(end 137.389362 -222.761556)
		(width 0.0889)
		(layer "In15.Cu")
		(net "P5E_CPU1_PE2_TX_DP<12>")
	)
	(arc
		(start 131.641342 -224.10293)
		(mid 131.889353 -224.139395)
		(end 132.128768 -224.065084)
		(width 0.0889)
		(layer "In15.Cu")
		(net "P5E_CPU1_PE2_TX_DP<12>")
	)
	(segment
		(start 132.713476 -401.777962)
		(end 132.387086 -402.104352)
		(width 0.13208)
		(layer "F.Cu")
		(net "P5E_CPU1_PE2_TX_DP<11>")
	)
	(segment
		(start 130.906266 -225.739198)
		(end 130.906266 -225.203512)
		(width 0.13208)
		(layer "F.Cu")
		(net "P5E_CPU1_PE2_TX_DP<11>")
	)
	(segment
		(start 132.713476 -401.16379)
		(end 132.713476 -401.777962)
		(width 0.13208)
		(layer "F.Cu")
		(net "P5E_CPU1_PE2_TX_DP<11>")
	)
	(segment
		(start 132.407914 -400.858228)
		(end 132.713476 -401.16379)
		(width 0.13208)
		(layer "F.Cu")
		(net "P5E_CPU1_PE2_TX_DP<11>")
	)
	(segment
		(start 130.906266 -225.203512)
		(end 130.906012 -225.203258)
		(width 0.13208)
		(layer "F.Cu")
		(net "P5E_CPU1_PE2_TX_DP<11>")
	)
	(segment
		(start 132.387086 -402.104352)
		(end 132.382514 -402.104352)
		(width 0.13208)
		(layer "F.Cu")
		(net "P5E_CPU1_PE2_TX_DP<11>")
	)
	(segment
		(start 134.018782 -397.262604)
		(end 133.848856 -397.308832)
		(width 0.14732)
		(layer "In15.Cu")
		(net "P5E_CPU1_PE2_TX_DP<11>")
	)
	(segment
		(start 134.57682 -396.28826)
		(end 134.406894 -396.334488)
		(width 0.14732)
		(layer "In15.Cu")
		(net "P5E_CPU1_PE2_TX_DP<11>")
	)
	(segment
		(start 145.122646 -259.19303)
		(end 145.122392 -259.19303)
		(width 0.14732)
		(layer "In15.Cu")
		(net "P5E_CPU1_PE2_TX_DP<11>")
	)
	(segment
		(start 134.4676 -220.001592)
		(end 134.478014 -219.995496)
		(width 0.0889)
		(layer "In15.Cu")
		(net "P5E_CPU1_PE2_TX_DP<11>")
	)
	(segment
		(start 153.516584 -355.512624)
		(end 153.516584 -355.51237)
		(width 0.14732)
		(layer "In15.Cu")
		(net "P5E_CPU1_PE2_TX_DP<11>")
	)
	(segment
		(start 133.631686 -397.688054)
		(end 133.67766 -397.85798)
		(width 0.14732)
		(layer "In15.Cu")
		(net "P5E_CPU1_PE2_TX_DP<11>")
	)
	(segment
		(start 135.52297 -394.3858)
		(end 135.3058 -394.765022)
		(width 0.14732)
		(layer "In15.Cu")
		(net "P5E_CPU1_PE2_TX_DP<11>")
	)
	(segment
		(start 130.749548 -224.93224)
		(end 130.773678 -224.843086)
		(width 0.0889)
		(layer "In15.Cu")
		(net "P5E_CPU1_PE2_TX_DP<11>")
	)
	(segment
		(start 138.141964 -220.809566)
		(end 138.150854 -220.814646)
		(width 0.0889)
		(layer "In15.Cu")
		(net "P5E_CPU1_PE2_TX_DP<11>")
	)
	(segment
		(start 142.30096 -252.300232)
		(end 142.413228 -252.661166)
		(width 0.14732)
		(layer "In15.Cu")
		(net "P5E_CPU1_PE2_TX_DP<11>")
	)
	(segment
		(start 138.689842 -221.682818)
		(end 139.440158 -222.43288)
		(width 0.0889)
		(layer "In15.Cu")
		(net "P5E_CPU1_PE2_TX_DP<11>")
	)
	(segment
		(start 139.536424 -222.529146)
		(end 139.536424 -222.588074)
		(width 0.0889)
		(layer "In15.Cu")
		(net "P5E_CPU1_PE2_TX_DP<11>")
	)
	(segment
		(start 135.692896 -394.339572)
		(end 135.52297 -394.3858)
		(width 0.14732)
		(layer "In15.Cu")
		(net "P5E_CPU1_PE2_TX_DP<11>")
	)
	(segment
		(start 136.733788 -219.996258)
		(end 136.741154 -220.000576)
		(width 0.0889)
		(layer "In15.Cu")
		(net "P5E_CPU1_PE2_TX_DP<11>")
	)
	(segment
		(start 154.116024 -348.660974)
		(end 153.516584 -355.512624)
		(width 0.14732)
		(layer "In15.Cu")
		(net "P5E_CPU1_PE2_TX_DP<11>")
	)
	(segment
		(start 134.235698 -396.883636)
		(end 134.018782 -397.262604)
		(width 0.14732)
		(layer "In15.Cu")
		(net "P5E_CPU1_PE2_TX_DP<11>")
	)
	(segment
		(start 136.919716 -220.319854)
		(end 136.919716 -220.338396)
		(width 0.0889)
		(layer "In15.Cu")
		(net "P5E_CPU1_PE2_TX_DP<11>")
	)
	(segment
		(start 142.229078 -226.810062)
		(end 142.497302 -227.753164)
		(width 0.14732)
		(layer "In15.Cu")
		(net "P5E_CPU1_PE2_TX_DP<11>")
	)
	(segment
		(start 134.406894 -396.334488)
		(end 134.189724 -396.71371)
		(width 0.14732)
		(layer "In15.Cu")
		(net "P5E_CPU1_PE2_TX_DP<11>")
	)
	(segment
		(start 134.189724 -396.71371)
		(end 134.235698 -396.883636)
		(width 0.14732)
		(layer "In15.Cu")
		(net "P5E_CPU1_PE2_TX_DP<11>")
	)
	(segment
		(start 139.440158 -222.43288)
		(end 139.536424 -222.529146)
		(width 0.0889)
		(layer "In15.Cu")
		(net "P5E_CPU1_PE2_TX_DP<11>")
	)
	(segment
		(start 134.964932 -395.360144)
		(end 134.747762 -395.739366)
		(width 0.14732)
		(layer "In15.Cu")
		(net "P5E_CPU1_PE2_TX_DP<11>")
	)
	(segment
		(start 144.431004 -256.06883)
		(end 145.122646 -259.19303)
		(width 0.14732)
		(layer "In15.Cu")
		(net "P5E_CPU1_PE2_TX_DP<11>")
	)
	(segment
		(start 143.234664 -230.621078)
		(end 144.19453 -244.545104)
		(width 0.14732)
		(layer "In15.Cu")
		(net "P5E_CPU1_PE2_TX_DP<11>")
	)
	(segment
		(start 132.702554 -399.560796)
		(end 132.702554 -400.563588)
		(width 0.14732)
		(layer "In15.Cu")
		(net "P5E_CPU1_PE2_TX_DP<11>")
	)
	(segment
		(start 142.684754 -249.184414)
		(end 142.499334 -249.44959)
		(width 0.14732)
		(layer "In15.Cu")
		(net "P5E_CPU1_PE2_TX_DP<11>")
	)
	(segment
		(start 133.67766 -397.85798)
		(end 132.702554 -399.560796)
		(width 0.14732)
		(layer "In15.Cu")
		(net "P5E_CPU1_PE2_TX_DP<11>")
	)
	(segment
		(start 132.410962 -221.963234)
		(end 132.410962 -221.94774)
		(width 0.0889)
		(layer "In15.Cu")
		(net "P5E_CPU1_PE2_TX_DP<11>")
	)
	(segment
		(start 138.689842 -221.682564)
		(end 138.689842 -221.682818)
		(width 0.0889)
		(layer "In15.Cu")
		(net "P5E_CPU1_PE2_TX_DP<11>")
	)
	(segment
		(start 139.551918 -222.603568)
		(end 140.050012 -223.101916)
		(width 0.14732)
		(layer "In15.Cu")
		(net "P5E_CPU1_PE2_TX_DP<11>")
	)
	(segment
		(start 132.59689 -221.624144)
		(end 132.598414 -221.623382)
		(width 0.0889)
		(layer "In15.Cu")
		(net "P5E_CPU1_PE2_TX_DP<11>")
	)
	(segment
		(start 142.499334 -249.44959)
		(end 142.30096 -250.57481)
		(width 0.14732)
		(layer "In15.Cu")
		(net "P5E_CPU1_PE2_TX_DP<11>")
	)
	(segment
		(start 135.407654 -220.001592)
		(end 135.418068 -219.995496)
		(width 0.0889)
		(layer "In15.Cu")
		(net "P5E_CPU1_PE2_TX_DP<11>")
	)
	(segment
		(start 133.059678 -220.814646)
		(end 133.068568 -220.809566)
		(width 0.0889)
		(layer "In15.Cu")
		(net "P5E_CPU1_PE2_TX_DP<11>")
	)
	(segment
		(start 132.119878 -222.442278)
		(end 132.128768 -222.437198)
		(width 0.0889)
		(layer "In15.Cu")
		(net "P5E_CPU1_PE2_TX_DP<11>")
	)
	(segment
		(start 152.917144 -362.363766)
		(end 149.430994 -370.350796)
		(width 0.14732)
		(layer "In15.Cu")
		(net "P5E_CPU1_PE2_TX_DP<11>")
	)
	(segment
		(start 134.747762 -395.739366)
		(end 134.793736 -395.909292)
		(width 0.14732)
		(layer "In15.Cu")
		(net "P5E_CPU1_PE2_TX_DP<11>")
	)
	(segment
		(start 142.17904 -309.563008)
		(end 146.215608 -326.350376)
		(width 0.14732)
		(layer "In15.Cu")
		(net "P5E_CPU1_PE2_TX_DP<11>")
	)
	(segment
		(start 138.329416 -221.133924)
		(end 138.329416 -221.14383)
		(width 0.0889)
		(layer "In15.Cu")
		(net "P5E_CPU1_PE2_TX_DP<11>")
	)
	(segment
		(start 153.516584 -355.51237)
		(end 153.217372 -358.93248)
		(width 0.14732)
		(layer "In15.Cu")
		(net "P5E_CPU1_PE2_TX_DP<11>")
	)
	(segment
		(start 149.430994 -370.350796)
		(end 135.692896 -394.339572)
		(width 0.14732)
		(layer "In15.Cu")
		(net "P5E_CPU1_PE2_TX_DP<11>")
	)
	(segment
		(start 135.351774 -394.934948)
		(end 135.134858 -395.313916)
		(width 0.14732)
		(layer "In15.Cu")
		(net "P5E_CPU1_PE2_TX_DP<11>")
	)
	(segment
		(start 154.643582 -345.669616)
		(end 154.116024 -348.660974)
		(width 0.14732)
		(layer "In15.Cu")
		(net "P5E_CPU1_PE2_TX_DP<11>")
	)
	(segment
		(start 140.050012 -223.101916)
		(end 142.229078 -226.810062)
		(width 0.14732)
		(layer "In15.Cu")
		(net "P5E_CPU1_PE2_TX_DP<11>")
	)
	(segment
		(start 135.134858 -395.313916)
		(end 134.964932 -395.360144)
		(width 0.14732)
		(layer "In15.Cu")
		(net "P5E_CPU1_PE2_TX_DP<11>")
	)
	(segment
		(start 136.732264 -219.995496)
		(end 136.733788 -219.996258)
		(width 0.0889)
		(layer "In15.Cu")
		(net "P5E_CPU1_PE2_TX_DP<11>")
	)
	(segment
		(start 142.497302 -227.753164)
		(end 143.234664 -230.621078)
		(width 0.14732)
		(layer "In15.Cu")
		(net "P5E_CPU1_PE2_TX_DP<11>")
	)
	(segment
		(start 130.906012 -225.203258)
		(end 130.749548 -224.93224)
		(width 0.0889)
		(layer "In15.Cu")
		(net "P5E_CPU1_PE2_TX_DP<11>")
	)
	(segment
		(start 142.413228 -252.661166)
		(end 142.517114 -252.994668)
		(width 0.14732)
		(layer "In15.Cu")
		(net "P5E_CPU1_PE2_TX_DP<11>")
	)
	(segment
		(start 131.180078 -224.070164)
		(end 131.188968 -224.065084)
		(width 0.0889)
		(layer "In15.Cu")
		(net "P5E_CPU1_PE2_TX_DP<11>")
	)
	(segment
		(start 133.351016 -220.338396)
		(end 133.351016 -220.319854)
		(width 0.0889)
		(layer "In15.Cu")
		(net "P5E_CPU1_PE2_TX_DP<11>")
	)
	(segment
		(start 132.598414 -221.623382)
		(end 132.599176 -221.622874)
		(width 0.0889)
		(layer "In15.Cu")
		(net "P5E_CPU1_PE2_TX_DP<11>")
	)
	(segment
		(start 132.702554 -400.563588)
		(end 132.407914 -400.858228)
		(width 0.14732)
		(layer "In15.Cu")
		(net "P5E_CPU1_PE2_TX_DP<11>")
	)
	(segment
		(start 144.19453 -244.545104)
		(end 142.684754 -249.184414)
		(width 0.14732)
		(layer "In15.Cu")
		(net "P5E_CPU1_PE2_TX_DP<11>")
	)
	(segment
		(start 133.529578 -220.000576)
		(end 133.538468 -219.995496)
		(width 0.0889)
		(layer "In15.Cu")
		(net "P5E_CPU1_PE2_TX_DP<11>")
	)
	(segment
		(start 135.3058 -394.765022)
		(end 135.351774 -394.934948)
		(width 0.14732)
		(layer "In15.Cu")
		(net "P5E_CPU1_PE2_TX_DP<11>")
	)
	(segment
		(start 145.122392 -259.19303)
		(end 142.17904 -309.563008)
		(width 0.14732)
		(layer "In15.Cu")
		(net "P5E_CPU1_PE2_TX_DP<11>")
	)
	(segment
		(start 131.471416 -223.585532)
		(end 131.471416 -223.56699)
		(width 0.0889)
		(layer "In15.Cu")
		(net "P5E_CPU1_PE2_TX_DP<11>")
	)
	(segment
		(start 142.30096 -250.57481)
		(end 142.30096 -252.300232)
		(width 0.14732)
		(layer "In15.Cu")
		(net "P5E_CPU1_PE2_TX_DP<11>")
	)
	(segment
		(start 133.848856 -397.308832)
		(end 133.631686 -397.688054)
		(width 0.14732)
		(layer "In15.Cu")
		(net "P5E_CPU1_PE2_TX_DP<11>")
	)
	(segment
		(start 131.941316 -222.77578)
		(end 131.941316 -222.761556)
		(width 0.0889)
		(layer "In15.Cu")
		(net "P5E_CPU1_PE2_TX_DP<11>")
	)
	(segment
		(start 142.86357 -253.830074)
		(end 144.431004 -256.06883)
		(width 0.14732)
		(layer "In15.Cu")
		(net "P5E_CPU1_PE2_TX_DP<11>")
	)
	(segment
		(start 132.599176 -221.622874)
		(end 132.60451 -221.619826)
		(width 0.0889)
		(layer "In15.Cu")
		(net "P5E_CPU1_PE2_TX_DP<11>")
	)
	(segment
		(start 142.517114 -252.994668)
		(end 142.86357 -253.830074)
		(width 0.14732)
		(layer "In15.Cu")
		(net "P5E_CPU1_PE2_TX_DP<11>")
	)
	(segment
		(start 139.536424 -222.588074)
		(end 139.551918 -222.603568)
		(width 0.0889)
		(layer "In15.Cu")
		(net "P5E_CPU1_PE2_TX_DP<11>")
	)
	(segment
		(start 146.215608 -326.350376)
		(end 152.50922 -333.570326)
		(width 0.14732)
		(layer "In15.Cu")
		(net "P5E_CPU1_PE2_TX_DP<11>")
	)
	(segment
		(start 152.50922 -333.570326)
		(end 154.643582 -345.669616)
		(width 0.14732)
		(layer "In15.Cu")
		(net "P5E_CPU1_PE2_TX_DP<11>")
	)
	(segment
		(start 153.217372 -358.93248)
		(end 152.917144 -362.363766)
		(width 0.14732)
		(layer "In15.Cu")
		(net "P5E_CPU1_PE2_TX_DP<11>")
	)
	(segment
		(start 132.589524 -221.628462)
		(end 132.59689 -221.624144)
		(width 0.0889)
		(layer "In15.Cu")
		(net "P5E_CPU1_PE2_TX_DP<11>")
	)
	(segment
		(start 134.793736 -395.909292)
		(end 134.57682 -396.28826)
		(width 0.14732)
		(layer "In15.Cu")
		(net "P5E_CPU1_PE2_TX_DP<11>")
	)
	(arc
		(start 134.85241 -219.995496)
		(mid 135.129223 -220.071366)
		(end 135.407654 -220.001592)
		(width 0.0889)
		(layer "In15.Cu")
		(net "P5E_CPU1_PE2_TX_DP<11>")
	)
	(arc
		(start 131.001516 -224.389442)
		(mid 131.049195 -224.206542)
		(end 131.180078 -224.070164)
		(width 0.0889)
		(layer "In15.Cu")
		(net "P5E_CPU1_PE2_TX_DP<11>")
	)
	(arc
		(start 138.150854 -220.814646)
		(mid 138.281768 -220.951006)
		(end 138.329416 -221.133924)
		(width 0.0889)
		(layer "In15.Cu")
		(net "P5E_CPU1_PE2_TX_DP<11>")
	)
	(arc
		(start 133.912864 -219.995496)
		(mid 134.189423 -220.071239)
		(end 134.4676 -220.001592)
		(width 0.0889)
		(layer "In15.Cu")
		(net "P5E_CPU1_PE2_TX_DP<11>")
	)
	(arc
		(start 131.941316 -222.761556)
		(mid 131.988995 -222.578656)
		(end 132.119878 -222.442278)
		(width 0.0889)
		(layer "In15.Cu")
		(net "P5E_CPU1_PE2_TX_DP<11>")
	)
	(arc
		(start 132.881116 -221.133924)
		(mid 132.928795 -220.951024)
		(end 133.059678 -220.814646)
		(width 0.0889)
		(layer "In15.Cu")
		(net "P5E_CPU1_PE2_TX_DP<11>")
	)
	(arc
		(start 134.478014 -219.995496)
		(mid 134.665212 -219.945353)
		(end 134.85241 -219.995496)
		(width 0.0889)
		(layer "In15.Cu")
		(net "P5E_CPU1_PE2_TX_DP<11>")
	)
	(arc
		(start 137.202164 -220.809566)
		(mid 137.484866 -220.885308)
		(end 137.767568 -220.809566)
		(width 0.0889)
		(layer "In15.Cu")
		(net "P5E_CPU1_PE2_TX_DP<11>")
	)
	(arc
		(start 131.188968 -224.065084)
		(mid 131.393303 -223.862479)
		(end 131.471416 -223.585532)
		(width 0.0889)
		(layer "In15.Cu")
		(net "P5E_CPU1_PE2_TX_DP<11>")
	)
	(arc
		(start 133.351016 -220.319854)
		(mid 133.398695 -220.136954)
		(end 133.529578 -220.000576)
		(width 0.0889)
		(layer "In15.Cu")
		(net "P5E_CPU1_PE2_TX_DP<11>")
	)
	(arc
		(start 138.329416 -221.14383)
		(mid 138.407527 -221.420779)
		(end 138.611864 -221.623382)
		(width 0.0889)
		(layer "In15.Cu")
		(net "P5E_CPU1_PE2_TX_DP<11>")
	)
	(arc
		(start 131.658614 -223.251268)
		(mid 131.862095 -223.050464)
		(end 131.941316 -222.77578)
		(width 0.0889)
		(layer "In15.Cu")
		(net "P5E_CPU1_PE2_TX_DP<11>")
	)
	(arc
		(start 136.741154 -220.000576)
		(mid 136.872068 -220.136936)
		(end 136.919716 -220.319854)
		(width 0.0889)
		(layer "In15.Cu")
		(net "P5E_CPU1_PE2_TX_DP<11>")
	)
	(arc
		(start 130.773678 -224.843086)
		(mid 130.78225 -224.836564)
		(end 130.790696 -224.829878)
		(width 0.0889)
		(layer "In15.Cu")
		(net "P5E_CPU1_PE2_TX_DP<11>")
	)
	(arc
		(start 133.538468 -219.995496)
		(mid 133.725666 -219.945353)
		(end 133.912864 -219.995496)
		(width 0.0889)
		(layer "In15.Cu")
		(net "P5E_CPU1_PE2_TX_DP<11>")
	)
	(arc
		(start 130.790696 -224.829878)
		(mid 130.946094 -224.633597)
		(end 131.001516 -224.389442)
		(width 0.0889)
		(layer "In15.Cu")
		(net "P5E_CPU1_PE2_TX_DP<11>")
	)
	(arc
		(start 136.357868 -219.995496)
		(mid 136.545066 -219.945353)
		(end 136.732264 -219.995496)
		(width 0.0889)
		(layer "In15.Cu")
		(net "P5E_CPU1_PE2_TX_DP<11>")
	)
	(arc
		(start 132.60451 -221.619826)
		(mid 132.807097 -221.413475)
		(end 132.881116 -221.133924)
		(width 0.0889)
		(layer "In15.Cu")
		(net "P5E_CPU1_PE2_TX_DP<11>")
	)
	(arc
		(start 132.410962 -221.94774)
		(mid 132.458641 -221.76484)
		(end 132.589524 -221.628462)
		(width 0.0889)
		(layer "In15.Cu")
		(net "P5E_CPU1_PE2_TX_DP<11>")
	)
	(arc
		(start 138.611864 -221.623382)
		(mid 138.652794 -221.650415)
		(end 138.689842 -221.682564)
		(width 0.0889)
		(layer "In15.Cu")
		(net "P5E_CPU1_PE2_TX_DP<11>")
	)
	(arc
		(start 137.767568 -220.809566)
		(mid 137.954766 -220.759423)
		(end 138.141964 -220.809566)
		(width 0.0889)
		(layer "In15.Cu")
		(net "P5E_CPU1_PE2_TX_DP<11>")
	)
	(arc
		(start 136.919716 -220.338396)
		(mid 136.999878 -220.610585)
		(end 137.202164 -220.809566)
		(width 0.0889)
		(layer "In15.Cu")
		(net "P5E_CPU1_PE2_TX_DP<11>")
	)
	(arc
		(start 133.068568 -220.809566)
		(mid 133.270854 -220.610585)
		(end 133.351016 -220.338396)
		(width 0.0889)
		(layer "In15.Cu")
		(net "P5E_CPU1_PE2_TX_DP<11>")
	)
	(arc
		(start 132.128768 -222.437198)
		(mid 132.331591 -222.236967)
		(end 132.410962 -221.963234)
		(width 0.0889)
		(layer "In15.Cu")
		(net "P5E_CPU1_PE2_TX_DP<11>")
	)
	(arc
		(start 135.418068 -219.995496)
		(mid 135.605266 -219.945353)
		(end 135.792464 -219.995496)
		(width 0.0889)
		(layer "In15.Cu")
		(net "P5E_CPU1_PE2_TX_DP<11>")
	)
	(arc
		(start 131.471416 -223.56699)
		(mid 131.523686 -223.384625)
		(end 131.658614 -223.251268)
		(width 0.0889)
		(layer "In15.Cu")
		(net "P5E_CPU1_PE2_TX_DP<11>")
	)
	(arc
		(start 135.792464 -219.995496)
		(mid 136.075166 -220.071272)
		(end 136.357868 -219.995496)
		(width 0.0889)
		(layer "In15.Cu")
		(net "P5E_CPU1_PE2_TX_DP<11>")
	)
	(segment
		(start 135.450326 -402.104352)
		(end 135.445754 -402.104352)
		(width 0.13208)
		(layer "F.Cu")
		(net "P5E_CPU1_PE2_TX_DP<10>")
	)
	(segment
		(start 129.496312 -224.925382)
		(end 129.496312 -224.389696)
		(width 0.13208)
		(layer "F.Cu")
		(net "P5E_CPU1_PE2_TX_DP<10>")
	)
	(segment
		(start 135.776716 -401.777962)
		(end 135.450326 -402.104352)
		(width 0.13208)
		(layer "F.Cu")
		(net "P5E_CPU1_PE2_TX_DP<10>")
	)
	(segment
		(start 129.496312 -224.389696)
		(end 129.496566 -224.389442)
		(width 0.13208)
		(layer "F.Cu")
		(net "P5E_CPU1_PE2_TX_DP<10>")
	)
	(segment
		(start 135.471154 -400.858228)
		(end 135.776716 -401.16379)
		(width 0.13208)
		(layer "F.Cu")
		(net "P5E_CPU1_PE2_TX_DP<10>")
	)
	(segment
		(start 135.776716 -401.16379)
		(end 135.776716 -401.777962)
		(width 0.13208)
		(layer "F.Cu")
		(net "P5E_CPU1_PE2_TX_DP<10>")
	)
	(segment
		(start 143.58112 -249.527314)
		(end 143.580358 -249.52833)
		(width 0.14732)
		(layer "In15.Cu")
		(net "P5E_CPU1_PE2_TX_DP<10>")
	)
	(segment
		(start 137.715244 -395.576806)
		(end 137.770108 -395.743938)
		(width 0.14732)
		(layer "In15.Cu")
		(net "P5E_CPU1_PE2_TX_DP<10>")
	)
	(segment
		(start 138.079734 -395.131798)
		(end 137.912348 -395.186662)
		(width 0.14732)
		(layer "In15.Cu")
		(net "P5E_CPU1_PE2_TX_DP<10>")
	)
	(segment
		(start 136.899142 -397.190722)
		(end 136.702292 -397.580866)
		(width 0.14732)
		(layer "In15.Cu")
		(net "P5E_CPU1_PE2_TX_DP<10>")
	)
	(segment
		(start 143.581628 -249.526552)
		(end 143.58112 -249.527314)
		(width 0.14732)
		(layer "In15.Cu")
		(net "P5E_CPU1_PE2_TX_DP<10>")
	)
	(segment
		(start 153.3779 -333.139034)
		(end 155.638246 -345.956128)
		(width 0.14732)
		(layer "In15.Cu")
		(net "P5E_CPU1_PE2_TX_DP<10>")
	)
	(segment
		(start 143.58239 -249.525536)
		(end 143.581628 -249.526552)
		(width 0.14732)
		(layer "In15.Cu")
		(net "P5E_CPU1_PE2_TX_DP<10>")
	)
	(segment
		(start 143.669512 -253.345696)
		(end 145.328386 -255.715008)
		(width 0.14732)
		(layer "In15.Cu")
		(net "P5E_CPU1_PE2_TX_DP<10>")
	)
	(segment
		(start 145.147284 -244.737382)
		(end 143.595852 -249.506232)
		(width 0.14732)
		(layer "In15.Cu")
		(net "P5E_CPU1_PE2_TX_DP<10>")
	)
	(segment
		(start 137.405872 -396.188692)
		(end 137.208768 -396.578836)
		(width 0.14732)
		(layer "In15.Cu")
		(net "P5E_CPU1_PE2_TX_DP<10>")
	)
	(segment
		(start 143.580358 -249.52833)
		(end 143.57985 -249.529092)
		(width 0.14732)
		(layer "In15.Cu")
		(net "P5E_CPU1_PE2_TX_DP<10>")
	)
	(segment
		(start 137.667746 -219.992956)
		(end 137.669778 -219.994226)
		(width 0.0889)
		(layer "In15.Cu")
		(net "P5E_CPU1_PE2_TX_DP<10>")
	)
	(segment
		(start 137.263632 -396.745968)
		(end 137.066782 -397.135858)
		(width 0.14732)
		(layer "In15.Cu")
		(net "P5E_CPU1_PE2_TX_DP<10>")
	)
	(segment
		(start 138.689588 -220.054932)
		(end 138.953494 -220.318838)
		(width 0.0889)
		(layer "In15.Cu")
		(net "P5E_CPU1_PE2_TX_DP<10>")
	)
	(segment
		(start 143.391128 -252.673866)
		(end 143.669512 -253.345696)
		(width 0.14732)
		(layer "In15.Cu")
		(net "P5E_CPU1_PE2_TX_DP<10>")
	)
	(segment
		(start 142.38478 -223.810068)
		(end 143.458946 -227.531168)
		(width 0.14732)
		(layer "In15.Cu")
		(net "P5E_CPU1_PE2_TX_DP<10>")
	)
	(segment
		(start 131.001516 -222.780098)
		(end 131.001516 -222.761556)
		(width 0.0889)
		(layer "In15.Cu")
		(net "P5E_CPU1_PE2_TX_DP<10>")
	)
	(segment
		(start 143.584168 -249.522996)
		(end 143.58366 -249.523758)
		(width 0.14732)
		(layer "In15.Cu")
		(net "P5E_CPU1_PE2_TX_DP<10>")
	)
	(segment
		(start 130.249168 -224.065084)
		(end 130.255264 -224.061528)
		(width 0.0889)
		(layer "In15.Cu")
		(net "P5E_CPU1_PE2_TX_DP<10>")
	)
	(segment
		(start 137.770108 -395.743938)
		(end 137.573258 -396.133828)
		(width 0.14732)
		(layer "In15.Cu")
		(net "P5E_CPU1_PE2_TX_DP<10>")
	)
	(segment
		(start 137.066782 -397.135858)
		(end 136.899142 -397.190722)
		(width 0.14732)
		(layer "In15.Cu")
		(net "P5E_CPU1_PE2_TX_DP<10>")
	)
	(segment
		(start 137.573258 -396.133828)
		(end 137.405872 -396.188692)
		(width 0.14732)
		(layer "In15.Cu")
		(net "P5E_CPU1_PE2_TX_DP<10>")
	)
	(segment
		(start 137.669778 -219.994226)
		(end 137.672064 -219.995496)
		(width 0.0889)
		(layer "In15.Cu")
		(net "P5E_CPU1_PE2_TX_DP<10>")
	)
	(segment
		(start 137.912348 -395.186662)
		(end 137.715244 -395.576806)
		(width 0.14732)
		(layer "In15.Cu")
		(net "P5E_CPU1_PE2_TX_DP<10>")
	)
	(segment
		(start 143.595852 -249.506232)
		(end 143.585692 -249.520964)
		(width 0.14732)
		(layer "In15.Cu")
		(net "P5E_CPU1_PE2_TX_DP<10>")
	)
	(segment
		(start 146.128994 -259.091938)
		(end 143.13662 -309.484268)
		(width 0.14732)
		(layer "In15.Cu")
		(net "P5E_CPU1_PE2_TX_DP<10>")
	)
	(segment
		(start 129.65303 -224.118424)
		(end 129.74193 -224.094802)
		(width 0.0889)
		(layer "In15.Cu")
		(net "P5E_CPU1_PE2_TX_DP<10>")
	)
	(segment
		(start 155.05303 -349.273622)
		(end 155.050998 -349.285052)
		(width 0.14732)
		(layer "In15.Cu")
		(net "P5E_CPU1_PE2_TX_DP<10>")
	)
	(segment
		(start 135.765794 -399.70964)
		(end 135.765794 -400.563588)
		(width 0.14732)
		(layer "In15.Cu")
		(net "P5E_CPU1_PE2_TX_DP<10>")
	)
	(segment
		(start 131.661408 -221.621604)
		(end 131.66471 -221.619826)
		(width 0.0889)
		(layer "In15.Cu")
		(net "P5E_CPU1_PE2_TX_DP<10>")
	)
	(segment
		(start 137.672064 -219.995496)
		(end 137.686796 -220.004132)
		(width 0.0889)
		(layer "In15.Cu")
		(net "P5E_CPU1_PE2_TX_DP<10>")
	)
	(segment
		(start 155.050998 -349.285052)
		(end 155.050744 -349.285052)
		(width 0.14732)
		(layer "In15.Cu")
		(net "P5E_CPU1_PE2_TX_DP<10>")
	)
	(segment
		(start 143.503904 -249.63755)
		(end 143.24076 -251.128022)
		(width 0.14732)
		(layer "In15.Cu")
		(net "P5E_CPU1_PE2_TX_DP<10>")
	)
	(segment
		(start 143.585692 -249.520964)
		(end 143.584168 -249.522996)
		(width 0.14732)
		(layer "In15.Cu")
		(net "P5E_CPU1_PE2_TX_DP<10>")
	)
	(segment
		(start 136.702292 -397.580866)
		(end 136.757156 -397.747998)
		(width 0.14732)
		(layer "In15.Cu")
		(net "P5E_CPU1_PE2_TX_DP<10>")
	)
	(segment
		(start 132.588254 -220.001592)
		(end 132.598668 -219.995496)
		(width 0.0889)
		(layer "In15.Cu")
		(net "P5E_CPU1_PE2_TX_DP<10>")
	)
	(segment
		(start 155.050744 -349.285052)
		(end 153.89733 -362.472478)
		(width 0.14732)
		(layer "In15.Cu")
		(net "P5E_CPU1_PE2_TX_DP<10>")
	)
	(segment
		(start 132.881116 -219.515944)
		(end 132.881116 -219.506038)
		(width 0.0889)
		(layer "In15.Cu")
		(net "P5E_CPU1_PE2_TX_DP<10>")
	)
	(segment
		(start 143.13662 -309.484268)
		(end 147.05584 -325.798688)
		(width 0.14732)
		(layer "In15.Cu")
		(net "P5E_CPU1_PE2_TX_DP<10>")
	)
	(segment
		(start 143.24076 -252.157992)
		(end 143.391128 -252.673866)
		(width 0.14732)
		(layer "In15.Cu")
		(net "P5E_CPU1_PE2_TX_DP<10>")
	)
	(segment
		(start 131.471416 -220.32849)
		(end 131.471416 -220.311218)
		(width 0.0889)
		(layer "In15.Cu")
		(net "P5E_CPU1_PE2_TX_DP<10>")
	)
	(segment
		(start 131.941316 -221.133924)
		(end 131.941316 -221.1197)
		(width 0.0889)
		(layer "In15.Cu")
		(net "P5E_CPU1_PE2_TX_DP<10>")
	)
	(segment
		(start 133.059678 -219.18676)
		(end 133.068568 -219.18168)
		(width 0.0889)
		(layer "In15.Cu")
		(net "P5E_CPU1_PE2_TX_DP<10>")
	)
	(segment
		(start 143.24076 -251.128022)
		(end 143.24076 -252.157992)
		(width 0.14732)
		(layer "In15.Cu")
		(net "P5E_CPU1_PE2_TX_DP<10>")
	)
	(segment
		(start 155.638246 -345.956128)
		(end 155.05303 -349.273368)
		(width 0.14732)
		(layer "In15.Cu")
		(net "P5E_CPU1_PE2_TX_DP<10>")
	)
	(segment
		(start 131.657852 -221.62389)
		(end 131.660138 -221.622366)
		(width 0.0889)
		(layer "In15.Cu")
		(net "P5E_CPU1_PE2_TX_DP<10>")
	)
	(segment
		(start 135.765794 -400.563588)
		(end 135.471154 -400.858228)
		(width 0.14732)
		(layer "In15.Cu")
		(net "P5E_CPU1_PE2_TX_DP<10>")
	)
	(segment
		(start 131.649724 -221.628462)
		(end 131.656836 -221.624398)
		(width 0.0889)
		(layer "In15.Cu")
		(net "P5E_CPU1_PE2_TX_DP<10>")
	)
	(segment
		(start 138.953494 -220.318838)
		(end 138.953494 -220.378782)
		(width 0.0889)
		(layer "In15.Cu")
		(net "P5E_CPU1_PE2_TX_DP<10>")
	)
	(segment
		(start 145.328386 -255.715008)
		(end 146.128994 -259.091938)
		(width 0.14732)
		(layer "In15.Cu")
		(net "P5E_CPU1_PE2_TX_DP<10>")
	)
	(segment
		(start 131.180078 -222.442278)
		(end 131.188968 -222.437198)
		(width 0.0889)
		(layer "In15.Cu")
		(net "P5E_CPU1_PE2_TX_DP<10>")
	)
	(segment
		(start 144.184116 -230.424482)
		(end 145.147284 -244.737382)
		(width 0.14732)
		(layer "In15.Cu")
		(net "P5E_CPU1_PE2_TX_DP<10>")
	)
	(segment
		(start 136.8171 -219.187776)
		(end 136.827514 -219.18168)
		(width 0.0889)
		(layer "In15.Cu")
		(net "P5E_CPU1_PE2_TX_DP<10>")
	)
	(segment
		(start 143.58366 -249.523758)
		(end 143.582898 -249.524774)
		(width 0.14732)
		(layer "In15.Cu")
		(net "P5E_CPU1_PE2_TX_DP<10>")
	)
	(segment
		(start 137.20191 -219.18168)
		(end 137.2108 -219.18676)
		(width 0.0889)
		(layer "In15.Cu")
		(net "P5E_CPU1_PE2_TX_DP<10>")
	)
	(segment
		(start 130.710178 -223.256348)
		(end 130.719068 -223.251268)
		(width 0.0889)
		(layer "In15.Cu")
		(net "P5E_CPU1_PE2_TX_DP<10>")
	)
	(segment
		(start 143.582898 -249.524774)
		(end 143.58239 -249.525536)
		(width 0.14732)
		(layer "In15.Cu")
		(net "P5E_CPU1_PE2_TX_DP<10>")
	)
	(segment
		(start 131.471162 -221.963234)
		(end 131.471162 -221.94774)
		(width 0.0889)
		(layer "In15.Cu")
		(net "P5E_CPU1_PE2_TX_DP<10>")
	)
	(segment
		(start 153.89733 -362.472478)
		(end 150.83409 -369.895628)
		(width 0.14732)
		(layer "In15.Cu")
		(net "P5E_CPU1_PE2_TX_DP<10>")
	)
	(segment
		(start 155.05303 -349.273368)
		(end 155.05303 -349.273622)
		(width 0.14732)
		(layer "In15.Cu")
		(net "P5E_CPU1_PE2_TX_DP<10>")
	)
	(segment
		(start 137.665968 -219.99194)
		(end 137.667746 -219.992956)
		(width 0.0889)
		(layer "In15.Cu")
		(net "P5E_CPU1_PE2_TX_DP<10>")
	)
	(segment
		(start 143.57985 -249.529092)
		(end 143.579088 -249.530108)
		(width 0.14732)
		(layer "In15.Cu")
		(net "P5E_CPU1_PE2_TX_DP<10>")
	)
	(segment
		(start 150.83409 -369.895628)
		(end 138.079734 -395.131798)
		(width 0.14732)
		(layer "In15.Cu")
		(net "P5E_CPU1_PE2_TX_DP<10>")
	)
	(segment
		(start 129.496566 -224.389442)
		(end 129.65303 -224.118424)
		(width 0.0889)
		(layer "In15.Cu")
		(net "P5E_CPU1_PE2_TX_DP<10>")
	)
	(segment
		(start 131.660138 -221.622366)
		(end 131.661408 -221.621604)
		(width 0.0889)
		(layer "In15.Cu")
		(net "P5E_CPU1_PE2_TX_DP<10>")
	)
	(segment
		(start 138.953494 -220.378782)
		(end 138.968988 -220.394276)
		(width 0.0889)
		(layer "In15.Cu")
		(net "P5E_CPU1_PE2_TX_DP<10>")
	)
	(segment
		(start 143.579088 -249.530108)
		(end 143.503904 -249.63755)
		(width 0.14732)
		(layer "In15.Cu")
		(net "P5E_CPU1_PE2_TX_DP<10>")
	)
	(segment
		(start 131.656836 -221.624398)
		(end 131.657852 -221.62389)
		(width 0.0889)
		(layer "In15.Cu")
		(net "P5E_CPU1_PE2_TX_DP<10>")
	)
	(segment
		(start 136.757156 -397.747998)
		(end 135.765794 -399.70964)
		(width 0.14732)
		(layer "In15.Cu")
		(net "P5E_CPU1_PE2_TX_DP<10>")
	)
	(segment
		(start 138.968988 -220.394276)
		(end 142.38478 -223.810068)
		(width 0.14732)
		(layer "In15.Cu")
		(net "P5E_CPU1_PE2_TX_DP<10>")
	)
	(segment
		(start 143.458946 -227.531168)
		(end 144.184116 -230.424482)
		(width 0.14732)
		(layer "In15.Cu")
		(net "P5E_CPU1_PE2_TX_DP<10>")
	)
	(segment
		(start 137.208768 -396.578836)
		(end 137.263632 -396.745968)
		(width 0.14732)
		(layer "In15.Cu")
		(net "P5E_CPU1_PE2_TX_DP<10>")
	)
	(segment
		(start 147.05584 -325.798688)
		(end 153.3779 -333.139034)
		(width 0.14732)
		(layer "In15.Cu")
		(net "P5E_CPU1_PE2_TX_DP<10>")
	)
	(arc
		(start 137.2108 -219.18676)
		(mid 137.341714 -219.32312)
		(end 137.389362 -219.506038)
		(width 0.0889)
		(layer "In15.Cu")
		(net "P5E_CPU1_PE2_TX_DP<10>")
	)
	(arc
		(start 137.686796 -220.004132)
		(mid 137.963271 -220.071452)
		(end 138.237468 -219.995496)
		(width 0.0889)
		(layer "In15.Cu")
		(net "P5E_CPU1_PE2_TX_DP<10>")
	)
	(arc
		(start 133.442964 -219.18168)
		(mid 133.725666 -219.257456)
		(end 134.008368 -219.18168)
		(width 0.0889)
		(layer "In15.Cu")
		(net "P5E_CPU1_PE2_TX_DP<10>")
	)
	(arc
		(start 129.761742 -224.10293)
		(mid 130.009753 -224.139395)
		(end 130.249168 -224.065084)
		(width 0.0889)
		(layer "In15.Cu")
		(net "P5E_CPU1_PE2_TX_DP<10>")
	)
	(arc
		(start 132.598668 -219.995496)
		(mid 132.803003 -219.792891)
		(end 132.881116 -219.515944)
		(width 0.0889)
		(layer "In15.Cu")
		(net "P5E_CPU1_PE2_TX_DP<10>")
	)
	(arc
		(start 132.881116 -219.506038)
		(mid 132.928795 -219.323138)
		(end 133.059678 -219.18676)
		(width 0.0889)
		(layer "In15.Cu")
		(net "P5E_CPU1_PE2_TX_DP<10>")
	)
	(arc
		(start 130.531616 -223.575626)
		(mid 130.579295 -223.392726)
		(end 130.710178 -223.256348)
		(width 0.0889)
		(layer "In15.Cu")
		(net "P5E_CPU1_PE2_TX_DP<10>")
	)
	(arc
		(start 131.188968 -222.437198)
		(mid 131.391791 -222.236967)
		(end 131.471162 -221.963234)
		(width 0.0889)
		(layer "In15.Cu")
		(net "P5E_CPU1_PE2_TX_DP<10>")
	)
	(arc
		(start 130.255264 -224.061528)
		(mid 130.457677 -223.855115)
		(end 130.531616 -223.575626)
		(width 0.0889)
		(layer "In15.Cu")
		(net "P5E_CPU1_PE2_TX_DP<10>")
	)
	(arc
		(start 134.948168 -219.18168)
		(mid 135.135366 -219.131537)
		(end 135.322564 -219.18168)
		(width 0.0889)
		(layer "In15.Cu")
		(net "P5E_CPU1_PE2_TX_DP<10>")
	)
	(arc
		(start 129.74193 -224.094802)
		(mid 129.751797 -224.098961)
		(end 129.761742 -224.10293)
		(width 0.0889)
		(layer "In15.Cu")
		(net "P5E_CPU1_PE2_TX_DP<10>")
	)
	(arc
		(start 137.389362 -219.506038)
		(mid 137.463353 -219.785604)
		(end 137.665968 -219.99194)
		(width 0.0889)
		(layer "In15.Cu")
		(net "P5E_CPU1_PE2_TX_DP<10>")
	)
	(arc
		(start 131.001516 -222.761556)
		(mid 131.049195 -222.578656)
		(end 131.180078 -222.442278)
		(width 0.0889)
		(layer "In15.Cu")
		(net "P5E_CPU1_PE2_TX_DP<10>")
	)
	(arc
		(start 138.237468 -219.995496)
		(mid 138.424666 -219.945353)
		(end 138.611864 -219.995496)
		(width 0.0889)
		(layer "In15.Cu")
		(net "P5E_CPU1_PE2_TX_DP<10>")
	)
	(arc
		(start 136.262364 -219.18168)
		(mid 136.538923 -219.257423)
		(end 136.8171 -219.187776)
		(width 0.0889)
		(layer "In15.Cu")
		(net "P5E_CPU1_PE2_TX_DP<10>")
	)
	(arc
		(start 131.471162 -221.94774)
		(mid 131.518841 -221.76484)
		(end 131.649724 -221.628462)
		(width 0.0889)
		(layer "In15.Cu")
		(net "P5E_CPU1_PE2_TX_DP<10>")
	)
	(arc
		(start 134.008368 -219.18168)
		(mid 134.195566 -219.131537)
		(end 134.382764 -219.18168)
		(width 0.0889)
		(layer "In15.Cu")
		(net "P5E_CPU1_PE2_TX_DP<10>")
	)
	(arc
		(start 131.941316 -221.1197)
		(mid 131.862097 -220.845015)
		(end 131.658614 -220.644212)
		(width 0.0889)
		(layer "In15.Cu")
		(net "P5E_CPU1_PE2_TX_DP<10>")
	)
	(arc
		(start 131.658614 -219.995496)
		(mid 131.845812 -219.945353)
		(end 132.03301 -219.995496)
		(width 0.0889)
		(layer "In15.Cu")
		(net "P5E_CPU1_PE2_TX_DP<10>")
	)
	(arc
		(start 135.322564 -219.18168)
		(mid 135.605266 -219.257456)
		(end 135.887968 -219.18168)
		(width 0.0889)
		(layer "In15.Cu")
		(net "P5E_CPU1_PE2_TX_DP<10>")
	)
	(arc
		(start 135.887968 -219.18168)
		(mid 136.075166 -219.131537)
		(end 136.262364 -219.18168)
		(width 0.0889)
		(layer "In15.Cu")
		(net "P5E_CPU1_PE2_TX_DP<10>")
	)
	(arc
		(start 134.382764 -219.18168)
		(mid 134.665466 -219.257456)
		(end 134.948168 -219.18168)
		(width 0.0889)
		(layer "In15.Cu")
		(net "P5E_CPU1_PE2_TX_DP<10>")
	)
	(arc
		(start 131.658614 -220.644212)
		(mid 131.523681 -220.510858)
		(end 131.471416 -220.32849)
		(width 0.0889)
		(layer "In15.Cu")
		(net "P5E_CPU1_PE2_TX_DP<10>")
	)
	(arc
		(start 133.068568 -219.18168)
		(mid 133.255766 -219.131537)
		(end 133.442964 -219.18168)
		(width 0.0889)
		(layer "In15.Cu")
		(net "P5E_CPU1_PE2_TX_DP<10>")
	)
	(arc
		(start 130.719068 -223.251268)
		(mid 130.921354 -223.052287)
		(end 131.001516 -222.780098)
		(width 0.0889)
		(layer "In15.Cu")
		(net "P5E_CPU1_PE2_TX_DP<10>")
	)
	(arc
		(start 131.66471 -221.619826)
		(mid 131.867297 -221.413475)
		(end 131.941316 -221.133924)
		(width 0.0889)
		(layer "In15.Cu")
		(net "P5E_CPU1_PE2_TX_DP<10>")
	)
	(arc
		(start 132.03301 -219.995496)
		(mid 132.309823 -220.071366)
		(end 132.588254 -220.001592)
		(width 0.0889)
		(layer "In15.Cu")
		(net "P5E_CPU1_PE2_TX_DP<10>")
	)
	(arc
		(start 136.827514 -219.18168)
		(mid 137.014712 -219.131537)
		(end 137.20191 -219.18168)
		(width 0.0889)
		(layer "In15.Cu")
		(net "P5E_CPU1_PE2_TX_DP<10>")
	)
	(arc
		(start 138.611864 -219.995496)
		(mid 138.643161 -220.015586)
		(end 138.672316 -220.038676)
		(width 0.0889)
		(layer "In15.Cu")
		(net "P5E_CPU1_PE2_TX_DP<10>")
	)
	(arc
		(start 138.672316 -220.038676)
		(mid 138.68108 -220.046668)
		(end 138.689588 -220.054932)
		(width 0.0889)
		(layer "In15.Cu")
		(net "P5E_CPU1_PE2_TX_DP<10>")
	)
	(arc
		(start 131.471416 -220.311218)
		(mid 131.523686 -220.128853)
		(end 131.658614 -219.995496)
		(width 0.0889)
		(layer "In15.Cu")
		(net "P5E_CPU1_PE2_TX_DP<10>")
	)
	(segment
		(start 166.409116 -401.777962)
		(end 166.082726 -402.104352)
		(width 0.13208)
		(layer "F.Cu")
		(net "P5E_CPU1_PE2_TX_DP<0>")
	)
	(segment
		(start 166.103554 -400.858228)
		(end 166.409116 -401.16379)
		(width 0.13208)
		(layer "F.Cu")
		(net "P5E_CPU1_PE2_TX_DP<0>")
	)
	(segment
		(start 166.409116 -401.16379)
		(end 166.409116 -401.777962)
		(width 0.13208)
		(layer "F.Cu")
		(net "P5E_CPU1_PE2_TX_DP<0>")
	)
	(segment
		(start 120.098312 -224.389696)
		(end 120.098566 -224.389442)
		(width 0.13208)
		(layer "F.Cu")
		(net "P5E_CPU1_PE2_TX_DP<0>")
	)
	(segment
		(start 166.082726 -402.104352)
		(end 166.078154 -402.104352)
		(width 0.13208)
		(layer "F.Cu")
		(net "P5E_CPU1_PE2_TX_DP<0>")
	)
	(segment
		(start 120.098312 -224.925382)
		(end 120.098312 -224.389696)
		(width 0.13208)
		(layer "F.Cu")
		(net "P5E_CPU1_PE2_TX_DP<0>")
	)
	(segment
		(start 164.071808 -327.654158)
		(end 163.15055 -332.880716)
		(width 0.14732)
		(layer "In15.Cu")
		(net "P5E_CPU1_PE2_TX_DP<0>")
	)
	(segment
		(start 123.994926 -213.17839)
		(end 123.994926 -212.050122)
		(width 0.14732)
		(layer "In15.Cu")
		(net "P5E_CPU1_PE2_TX_DP<0>")
	)
	(segment
		(start 123.483116 -216.260426)
		(end 123.483116 -216.25052)
		(width 0.0889)
		(layer "In15.Cu")
		(net "P5E_CPU1_PE2_TX_DP<0>")
	)
	(segment
		(start 123.191778 -216.745058)
		(end 123.199906 -216.740486)
		(width 0.0889)
		(layer "In15.Cu")
		(net "P5E_CPU1_PE2_TX_DP<0>")
	)
	(segment
		(start 166.17696 -397.286734)
		(end 166.189406 -397.655034)
		(width 0.14732)
		(layer "In15.Cu")
		(net "P5E_CPU1_PE2_TX_DP<0>")
	)
	(segment
		(start 123.953016 -213.894416)
		(end 123.953016 -213.242398)
		(width 0.0889)
		(layer "In15.Cu")
		(net "P5E_CPU1_PE2_TX_DP<0>")
	)
	(segment
		(start 123.994926 -212.050122)
		(end 124.690378 -210.371436)
		(width 0.14732)
		(layer "In15.Cu")
		(net "P5E_CPU1_PE2_TX_DP<0>")
	)
	(segment
		(start 135.845296 -202.543156)
		(end 137.605008 -203.272136)
		(width 0.14732)
		(layer "In15.Cu")
		(net "P5E_CPU1_PE2_TX_DP<0>")
	)
	(segment
		(start 166.207948 -394.09497)
		(end 166.242492 -395.11097)
		(width 0.14732)
		(layer "In15.Cu")
		(net "P5E_CPU1_PE2_TX_DP<0>")
	)
	(segment
		(start 166.277036 -396.126716)
		(end 166.142162 -396.270988)
		(width 0.14732)
		(layer "In15.Cu")
		(net "P5E_CPU1_PE2_TX_DP<0>")
	)
	(segment
		(start 121.603516 -222.780098)
		(end 121.603516 -222.761556)
		(width 0.0889)
		(layer "In15.Cu")
		(net "P5E_CPU1_PE2_TX_DP<0>")
	)
	(segment
		(start 165.463474 -345.999054)
		(end 164.998908 -348.63405)
		(width 0.14732)
		(layer "In15.Cu")
		(net "P5E_CPU1_PE2_TX_DP<0>")
	)
	(segment
		(start 164.753544 -351.436686)
		(end 166.207948 -394.09497)
		(width 0.14732)
		(layer "In15.Cu")
		(net "P5E_CPU1_PE2_TX_DP<0>")
	)
	(segment
		(start 166.120064 -395.623796)
		(end 166.26459 -395.75867)
		(width 0.14732)
		(layer "In15.Cu")
		(net "P5E_CPU1_PE2_TX_DP<0>")
	)
	(segment
		(start 122.261376 -219.994988)
		(end 122.26671 -219.99194)
		(width 0.0889)
		(layer "In15.Cu")
		(net "P5E_CPU1_PE2_TX_DP<0>")
	)
	(segment
		(start 145.762218 -211.429346)
		(end 151.885904 -219.684346)
		(width 0.14732)
		(layer "In15.Cu")
		(net "P5E_CPU1_PE2_TX_DP<0>")
	)
	(segment
		(start 131.781042 -203.280772)
		(end 133.561836 -202.543156)
		(width 0.14732)
		(layer "In15.Cu")
		(net "P5E_CPU1_PE2_TX_DP<0>")
	)
	(segment
		(start 154.375358 -231.519222)
		(end 154.375358 -231.519476)
		(width 0.14732)
		(layer "In15.Cu")
		(net "P5E_CPU1_PE2_TX_DP<0>")
	)
	(segment
		(start 156.625036 -320.81978)
		(end 160.58388 -323.416676)
		(width 0.14732)
		(layer "In15.Cu")
		(net "P5E_CPU1_PE2_TX_DP<0>")
	)
	(segment
		(start 123.483116 -217.878406)
		(end 123.483116 -217.859864)
		(width 0.0889)
		(layer "In15.Cu")
		(net "P5E_CPU1_PE2_TX_DP<0>")
	)
	(segment
		(start 122.073162 -221.963234)
		(end 122.073162 -221.94774)
		(width 0.0889)
		(layer "In15.Cu")
		(net "P5E_CPU1_PE2_TX_DP<0>")
	)
	(segment
		(start 166.398194 -399.674334)
		(end 166.398194 -400.563588)
		(width 0.14732)
		(layer "In15.Cu")
		(net "P5E_CPU1_PE2_TX_DP<0>")
	)
	(segment
		(start 122.260614 -219.995496)
		(end 122.261376 -219.994988)
		(width 0.0889)
		(layer "In15.Cu")
		(net "P5E_CPU1_PE2_TX_DP<0>")
	)
	(segment
		(start 123.952762 -215.452198)
		(end 123.952762 -215.436704)
		(width 0.0889)
		(layer "In15.Cu")
		(net "P5E_CPU1_PE2_TX_DP<0>")
	)
	(segment
		(start 157.003242 -253.498604)
		(end 152.75052 -308.333648)
		(width 0.14732)
		(layer "In15.Cu")
		(net "P5E_CPU1_PE2_TX_DP<0>")
	)
	(segment
		(start 164.998908 -348.63405)
		(end 164.753544 -351.436686)
		(width 0.14732)
		(layer "In15.Cu")
		(net "P5E_CPU1_PE2_TX_DP<0>")
	)
	(segment
		(start 122.073416 -220.32849)
		(end 122.073416 -220.311218)
		(width 0.0889)
		(layer "In15.Cu")
		(net "P5E_CPU1_PE2_TX_DP<0>")
	)
	(segment
		(start 166.142162 -396.270988)
		(end 166.154862 -396.639288)
		(width 0.14732)
		(layer "In15.Cu")
		(net "P5E_CPU1_PE2_TX_DP<0>")
	)
	(segment
		(start 166.311834 -397.142208)
		(end 166.17696 -397.286734)
		(width 0.14732)
		(layer "In15.Cu")
		(net "P5E_CPU1_PE2_TX_DP<0>")
	)
	(segment
		(start 122.260614 -221.623382)
		(end 122.26671 -221.619826)
		(width 0.0889)
		(layer "In15.Cu")
		(net "P5E_CPU1_PE2_TX_DP<0>")
	)
	(segment
		(start 151.885904 -219.684346)
		(end 153.566368 -226.15779)
		(width 0.14732)
		(layer "In15.Cu")
		(net "P5E_CPU1_PE2_TX_DP<0>")
	)
	(segment
		(start 123.012962 -218.707716)
		(end 123.012962 -218.692222)
		(width 0.0889)
		(layer "In15.Cu")
		(net "P5E_CPU1_PE2_TX_DP<0>")
	)
	(segment
		(start 133.561836 -202.543156)
		(end 135.845296 -202.543156)
		(width 0.14732)
		(layer "In15.Cu")
		(net "P5E_CPU1_PE2_TX_DP<0>")
	)
	(segment
		(start 166.242238 -395.111224)
		(end 166.107364 -395.255496)
		(width 0.14732)
		(layer "In15.Cu")
		(net "P5E_CPU1_PE2_TX_DP<0>")
	)
	(segment
		(start 123.994926 -213.200488)
		(end 123.994926 -213.17839)
		(width 0.0889)
		(layer "In15.Cu")
		(net "P5E_CPU1_PE2_TX_DP<0>")
	)
	(segment
		(start 156.806392 -247.631712)
		(end 157.003242 -253.498604)
		(width 0.14732)
		(layer "In15.Cu")
		(net "P5E_CPU1_PE2_TX_DP<0>")
	)
	(segment
		(start 137.605008 -203.272136)
		(end 145.762218 -211.429346)
		(width 0.14732)
		(layer "In15.Cu")
		(net "P5E_CPU1_PE2_TX_DP<0>")
	)
	(segment
		(start 121.312178 -223.256348)
		(end 121.321068 -223.251268)
		(width 0.0889)
		(layer "In15.Cu")
		(net "P5E_CPU1_PE2_TX_DP<0>")
	)
	(segment
		(start 123.199906 -216.740486)
		(end 123.200668 -216.739978)
		(width 0.0889)
		(layer "In15.Cu")
		(net "P5E_CPU1_PE2_TX_DP<0>")
	)
	(segment
		(start 120.098566 -224.389442)
		(end 120.25503 -224.118424)
		(width 0.0889)
		(layer "In15.Cu")
		(net "P5E_CPU1_PE2_TX_DP<0>")
	)
	(segment
		(start 123.661678 -215.931242)
		(end 123.670568 -215.926162)
		(width 0.0889)
		(layer "In15.Cu")
		(net "P5E_CPU1_PE2_TX_DP<0>")
	)
	(segment
		(start 123.953016 -213.242398)
		(end 123.994926 -213.200488)
		(width 0.0889)
		(layer "In15.Cu")
		(net "P5E_CPU1_PE2_TX_DP<0>")
	)
	(segment
		(start 166.299388 -396.774162)
		(end 166.311834 -397.142208)
		(width 0.14732)
		(layer "In15.Cu")
		(net "P5E_CPU1_PE2_TX_DP<0>")
	)
	(segment
		(start 124.422408 -214.644732)
		(end 124.422408 -214.425022)
		(width 0.0889)
		(layer "In15.Cu")
		(net "P5E_CPU1_PE2_TX_DP<0>")
	)
	(segment
		(start 163.846764 -326.379332)
		(end 164.071808 -327.654158)
		(width 0.14732)
		(layer "In15.Cu")
		(net "P5E_CPU1_PE2_TX_DP<0>")
	)
	(segment
		(start 163.15055 -332.880716)
		(end 165.463474 -345.999054)
		(width 0.14732)
		(layer "In15.Cu")
		(net "P5E_CPU1_PE2_TX_DP<0>")
	)
	(segment
		(start 123.191524 -218.372944)
		(end 123.200414 -218.367864)
		(width 0.0889)
		(layer "In15.Cu")
		(net "P5E_CPU1_PE2_TX_DP<0>")
	)
	(segment
		(start 166.333932 -397.789908)
		(end 166.398194 -399.674334)
		(width 0.14732)
		(layer "In15.Cu")
		(net "P5E_CPU1_PE2_TX_DP<0>")
	)
	(segment
		(start 123.200414 -218.367864)
		(end 123.20651 -218.364308)
		(width 0.0889)
		(layer "In15.Cu")
		(net "P5E_CPU1_PE2_TX_DP<0>")
	)
	(segment
		(start 160.58388 -323.416676)
		(end 162.9156 -325.049134)
		(width 0.14732)
		(layer "In15.Cu")
		(net "P5E_CPU1_PE2_TX_DP<0>")
	)
	(segment
		(start 124.131324 -215.117426)
		(end 124.140214 -215.112346)
		(width 0.0889)
		(layer "In15.Cu")
		(net "P5E_CPU1_PE2_TX_DP<0>")
	)
	(segment
		(start 155.173172 -318.885316)
		(end 156.625036 -320.81978)
		(width 0.14732)
		(layer "In15.Cu")
		(net "P5E_CPU1_PE2_TX_DP<0>")
	)
	(segment
		(start 153.566368 -226.15779)
		(end 154.375358 -231.519222)
		(width 0.14732)
		(layer "In15.Cu")
		(net "P5E_CPU1_PE2_TX_DP<0>")
	)
	(segment
		(start 120.851168 -224.065084)
		(end 120.857264 -224.061528)
		(width 0.0889)
		(layer "In15.Cu")
		(net "P5E_CPU1_PE2_TX_DP<0>")
	)
	(segment
		(start 122.543316 -221.133924)
		(end 122.543316 -221.1197)
		(width 0.0889)
		(layer "In15.Cu")
		(net "P5E_CPU1_PE2_TX_DP<0>")
	)
	(segment
		(start 120.25503 -224.118424)
		(end 120.34393 -224.094802)
		(width 0.0889)
		(layer "In15.Cu")
		(net "P5E_CPU1_PE2_TX_DP<0>")
	)
	(segment
		(start 166.26459 -395.75867)
		(end 166.277036 -396.126716)
		(width 0.14732)
		(layer "In15.Cu")
		(net "P5E_CPU1_PE2_TX_DP<0>")
	)
	(segment
		(start 162.9156 -325.049134)
		(end 163.846764 -326.379332)
		(width 0.14732)
		(layer "In15.Cu")
		(net "P5E_CPU1_PE2_TX_DP<0>")
	)
	(segment
		(start 122.251724 -221.628462)
		(end 122.260614 -221.623382)
		(width 0.0889)
		(layer "In15.Cu")
		(net "P5E_CPU1_PE2_TX_DP<0>")
	)
	(segment
		(start 152.75052 -308.333648)
		(end 155.173172 -318.885316)
		(width 0.14732)
		(layer "In15.Cu")
		(net "P5E_CPU1_PE2_TX_DP<0>")
	)
	(segment
		(start 166.154862 -396.639288)
		(end 166.299388 -396.774162)
		(width 0.14732)
		(layer "In15.Cu")
		(net "P5E_CPU1_PE2_TX_DP<0>")
	)
	(segment
		(start 121.782078 -222.442278)
		(end 121.790968 -222.437198)
		(width 0.0889)
		(layer "In15.Cu")
		(net "P5E_CPU1_PE2_TX_DP<0>")
	)
	(segment
		(start 124.690378 -210.371436)
		(end 131.781042 -203.280772)
		(width 0.14732)
		(layer "In15.Cu")
		(net "P5E_CPU1_PE2_TX_DP<0>")
	)
	(segment
		(start 166.398194 -400.563588)
		(end 166.103554 -400.858228)
		(width 0.14732)
		(layer "In15.Cu")
		(net "P5E_CPU1_PE2_TX_DP<0>")
	)
	(segment
		(start 166.107364 -395.255496)
		(end 166.120064 -395.623796)
		(width 0.14732)
		(layer "In15.Cu")
		(net "P5E_CPU1_PE2_TX_DP<0>")
	)
	(segment
		(start 123.200668 -217.388694)
		(end 123.191778 -217.383614)
		(width 0.0889)
		(layer "In15.Cu")
		(net "P5E_CPU1_PE2_TX_DP<0>")
	)
	(segment
		(start 166.242492 -395.11097)
		(end 166.242238 -395.111224)
		(width 0.14732)
		(layer "In15.Cu")
		(net "P5E_CPU1_PE2_TX_DP<0>")
	)
	(segment
		(start 166.189406 -397.655034)
		(end 166.333932 -397.789908)
		(width 0.14732)
		(layer "In15.Cu")
		(net "P5E_CPU1_PE2_TX_DP<0>")
	)
	(segment
		(start 154.375358 -231.519476)
		(end 156.806392 -247.631712)
		(width 0.14732)
		(layer "In15.Cu")
		(net "P5E_CPU1_PE2_TX_DP<0>")
	)
	(segment
		(start 122.721878 -219.18676)
		(end 122.730768 -219.18168)
		(width 0.0889)
		(layer "In15.Cu")
		(net "P5E_CPU1_PE2_TX_DP<0>")
	)
	(arc
		(start 124.136912 -214.093298)
		(mid 124.027957 -214.009578)
		(end 123.953016 -213.894416)
		(width 0.0889)
		(layer "In15.Cu")
		(net "P5E_CPU1_PE2_TX_DP<0>")
	)
	(arc
		(start 120.363742 -224.10293)
		(mid 120.611753 -224.139395)
		(end 120.851168 -224.065084)
		(width 0.0889)
		(layer "In15.Cu")
		(net "P5E_CPU1_PE2_TX_DP<0>")
	)
	(arc
		(start 123.200668 -216.739978)
		(mid 123.405003 -216.537373)
		(end 123.483116 -216.260426)
		(width 0.0889)
		(layer "In15.Cu")
		(net "P5E_CPU1_PE2_TX_DP<0>")
	)
	(arc
		(start 122.543316 -219.506038)
		(mid 122.590995 -219.323138)
		(end 122.721878 -219.18676)
		(width 0.0889)
		(layer "In15.Cu")
		(net "P5E_CPU1_PE2_TX_DP<0>")
	)
	(arc
		(start 124.422408 -214.425022)
		(mid 124.31107 -214.232122)
		(end 124.136912 -214.093298)
		(width 0.0889)
		(layer "In15.Cu")
		(net "P5E_CPU1_PE2_TX_DP<0>")
	)
	(arc
		(start 121.603516 -222.761556)
		(mid 121.651195 -222.578656)
		(end 121.782078 -222.442278)
		(width 0.0889)
		(layer "In15.Cu")
		(net "P5E_CPU1_PE2_TX_DP<0>")
	)
	(arc
		(start 122.073162 -221.94774)
		(mid 122.120841 -221.76484)
		(end 122.251724 -221.628462)
		(width 0.0889)
		(layer "In15.Cu")
		(net "P5E_CPU1_PE2_TX_DP<0>")
	)
	(arc
		(start 120.857264 -224.061528)
		(mid 121.059677 -223.855115)
		(end 121.133616 -223.575626)
		(width 0.0889)
		(layer "In15.Cu")
		(net "P5E_CPU1_PE2_TX_DP<0>")
	)
	(arc
		(start 123.953016 -215.421972)
		(mid 124.00407 -215.247392)
		(end 124.131324 -215.117426)
		(width 0.0889)
		(layer "In15.Cu")
		(net "P5E_CPU1_PE2_TX_DP<0>")
	)
	(arc
		(start 123.191778 -217.383614)
		(mid 123.013181 -217.064336)
		(end 123.191778 -216.745058)
		(width 0.0889)
		(layer "In15.Cu")
		(net "P5E_CPU1_PE2_TX_DP<0>")
	)
	(arc
		(start 121.133616 -223.575626)
		(mid 121.181295 -223.392726)
		(end 121.312178 -223.256348)
		(width 0.0889)
		(layer "In15.Cu")
		(net "P5E_CPU1_PE2_TX_DP<0>")
	)
	(arc
		(start 122.26671 -219.99194)
		(mid 122.469297 -219.785589)
		(end 122.543316 -219.506038)
		(width 0.0889)
		(layer "In15.Cu")
		(net "P5E_CPU1_PE2_TX_DP<0>")
	)
	(arc
		(start 120.34393 -224.094802)
		(mid 120.353797 -224.098961)
		(end 120.363742 -224.10293)
		(width 0.0889)
		(layer "In15.Cu")
		(net "P5E_CPU1_PE2_TX_DP<0>")
	)
	(arc
		(start 122.073416 -220.311218)
		(mid 122.125686 -220.128853)
		(end 122.260614 -219.995496)
		(width 0.0889)
		(layer "In15.Cu")
		(net "P5E_CPU1_PE2_TX_DP<0>")
	)
	(arc
		(start 121.790968 -222.437198)
		(mid 121.993791 -222.236967)
		(end 122.073162 -221.963234)
		(width 0.0889)
		(layer "In15.Cu")
		(net "P5E_CPU1_PE2_TX_DP<0>")
	)
	(arc
		(start 122.543316 -221.1197)
		(mid 122.464097 -220.845015)
		(end 122.260614 -220.644212)
		(width 0.0889)
		(layer "In15.Cu")
		(net "P5E_CPU1_PE2_TX_DP<0>")
	)
	(arc
		(start 123.20651 -218.364308)
		(mid 123.409097 -218.157957)
		(end 123.483116 -217.878406)
		(width 0.0889)
		(layer "In15.Cu")
		(net "P5E_CPU1_PE2_TX_DP<0>")
	)
	(arc
		(start 123.012962 -218.692222)
		(mid 123.060641 -218.509322)
		(end 123.191524 -218.372944)
		(width 0.0889)
		(layer "In15.Cu")
		(net "P5E_CPU1_PE2_TX_DP<0>")
	)
	(arc
		(start 123.670568 -215.926162)
		(mid 123.873391 -215.725931)
		(end 123.952762 -215.452198)
		(width 0.0889)
		(layer "In15.Cu")
		(net "P5E_CPU1_PE2_TX_DP<0>")
	)
	(arc
		(start 121.321068 -223.251268)
		(mid 121.523354 -223.052287)
		(end 121.603516 -222.780098)
		(width 0.0889)
		(layer "In15.Cu")
		(net "P5E_CPU1_PE2_TX_DP<0>")
	)
	(arc
		(start 122.260614 -220.644212)
		(mid 122.125681 -220.510858)
		(end 122.073416 -220.32849)
		(width 0.0889)
		(layer "In15.Cu")
		(net "P5E_CPU1_PE2_TX_DP<0>")
	)
	(arc
		(start 122.26671 -221.619826)
		(mid 122.469297 -221.413475)
		(end 122.543316 -221.133924)
		(width 0.0889)
		(layer "In15.Cu")
		(net "P5E_CPU1_PE2_TX_DP<0>")
	)
	(arc
		(start 123.483116 -217.859864)
		(mid 123.402954 -217.587675)
		(end 123.200668 -217.388694)
		(width 0.0889)
		(layer "In15.Cu")
		(net "P5E_CPU1_PE2_TX_DP<0>")
	)
	(arc
		(start 124.140214 -215.112346)
		(mid 124.341496 -214.914859)
		(end 124.422408 -214.644732)
		(width 0.0889)
		(layer "In15.Cu")
		(net "P5E_CPU1_PE2_TX_DP<0>")
	)
	(arc
		(start 123.952762 -215.436704)
		(mid 123.952814 -215.429337)
		(end 123.953016 -215.421972)
		(width 0.0889)
		(layer "In15.Cu")
		(net "P5E_CPU1_PE2_TX_DP<0>")
	)
	(arc
		(start 123.483116 -216.25052)
		(mid 123.530795 -216.06762)
		(end 123.661678 -215.931242)
		(width 0.0889)
		(layer "In15.Cu")
		(net "P5E_CPU1_PE2_TX_DP<0>")
	)
	(arc
		(start 122.730768 -219.18168)
		(mid 122.933591 -218.981449)
		(end 123.012962 -218.707716)
		(width 0.0889)
		(layer "In15.Cu")
		(net "P5E_CPU1_PE2_TX_DP<0>")
	)
	(segment
		(start 128.556512 -224.925382)
		(end 128.556766 -224.925128)
		(width 0.13208)
		(layer "F.Cu")
		(net "P5E_CPU1_PE2_TX_DN<9>")
	)
	(segment
		(start 139.397994 -400.858228)
		(end 139.099036 -401.157186)
		(width 0.13208)
		(layer "F.Cu")
		(net "P5E_CPU1_PE2_TX_DN<9>")
	)
	(segment
		(start 139.099036 -401.779994)
		(end 139.423394 -402.104352)
		(width 0.13208)
		(layer "F.Cu")
		(net "P5E_CPU1_PE2_TX_DN<9>")
	)
	(segment
		(start 139.099036 -401.157186)
		(end 139.099036 -401.779994)
		(width 0.13208)
		(layer "F.Cu")
		(net "P5E_CPU1_PE2_TX_DN<9>")
	)
	(segment
		(start 128.556766 -224.925128)
		(end 128.556766 -224.389442)
		(width 0.13208)
		(layer "F.Cu")
		(net "P5E_CPU1_PE2_TX_DN<9>")
	)
	(segment
		(start 129.683764 -223.085914)
		(end 129.692654 -223.080834)
		(width 0.0889)
		(layer "In15.Cu")
		(net "P5E_CPU1_PE2_TX_DN<9>")
	)
	(segment
		(start 129.401062 -223.584262)
		(end 129.401062 -223.561402)
		(width 0.0889)
		(layer "In15.Cu")
		(net "P5E_CPU1_PE2_TX_DN<9>")
	)
	(segment
		(start 128.931416 -224.389442)
		(end 128.931416 -224.379536)
		(width 0.0889)
		(layer "In15.Cu")
		(net "P5E_CPU1_PE2_TX_DN<9>")
	)
	(segment
		(start 128.556766 -224.389442)
		(end 128.71323 -224.66046)
		(width 0.0889)
		(layer "In15.Cu")
		(net "P5E_CPU1_PE2_TX_DN<9>")
	)
	(segment
		(start 141.488922 -220.552772)
		(end 144.081246 -223.976692)
		(width 0.14732)
		(layer "In15.Cu")
		(net "P5E_CPU1_PE2_TX_DN<9>")
	)
	(segment
		(start 139.103354 -400.563588)
		(end 139.397994 -400.858228)
		(width 0.14732)
		(layer "In15.Cu")
		(net "P5E_CPU1_PE2_TX_DN<9>")
	)
	(segment
		(start 130.623564 -221.458282)
		(end 130.632454 -221.453202)
		(width 0.0889)
		(layer "In15.Cu")
		(net "P5E_CPU1_PE2_TX_DN<9>")
	)
	(segment
		(start 130.340862 -220.327474)
		(end 130.340862 -220.319854)
		(width 0.0889)
		(layer "In15.Cu")
		(net "P5E_CPU1_PE2_TX_DN<9>")
	)
	(segment
		(start 130.811016 -219.506038)
		(end 130.811016 -219.490544)
		(width 0.0889)
		(layer "In15.Cu")
		(net "P5E_CPU1_PE2_TX_DN<9>")
	)
	(segment
		(start 133.436868 -216.578434)
		(end 133.442964 -216.574878)
		(width 0.0889)
		(layer "In15.Cu")
		(net "P5E_CPU1_PE2_TX_DN<9>")
	)
	(segment
		(start 130.632454 -220.814646)
		(end 130.624326 -220.810074)
		(width 0.0889)
		(layer "In15.Cu")
		(net "P5E_CPU1_PE2_TX_DN<9>")
	)
	(segment
		(start 144.610582 -225.805492)
		(end 145.375376 -229.672896)
		(width 0.14732)
		(layer "In15.Cu")
		(net "P5E_CPU1_PE2_TX_DN<9>")
	)
	(segment
		(start 130.623564 -219.830396)
		(end 130.632454 -219.825316)
		(width 0.0889)
		(layer "In15.Cu")
		(net "P5E_CPU1_PE2_TX_DN<9>")
	)
	(segment
		(start 144.38376 -309.343044)
		(end 148.16328 -325.175118)
		(width 0.14732)
		(layer "In15.Cu")
		(net "P5E_CPU1_PE2_TX_DN<9>")
	)
	(segment
		(start 148.687028 -253.154688)
		(end 148.686012 -253.169674)
		(width 0.14732)
		(layer "In15.Cu")
		(net "P5E_CPU1_PE2_TX_DN<9>")
	)
	(segment
		(start 156.221684 -350.071436)
		(end 155.067254 -363.29112)
		(width 0.14732)
		(layer "In15.Cu")
		(net "P5E_CPU1_PE2_TX_DN<9>")
	)
	(segment
		(start 130.15341 -222.272098)
		(end 130.1623 -222.267018)
		(width 0.0889)
		(layer "In15.Cu")
		(net "P5E_CPU1_PE2_TX_DN<9>")
	)
	(segment
		(start 155.067254 -363.29112)
		(end 152.164288 -370.49583)
		(width 0.14732)
		(layer "In15.Cu")
		(net "P5E_CPU1_PE2_TX_DN<9>")
	)
	(segment
		(start 152.164288 -370.49583)
		(end 152.16251 -370.500656)
		(width 0.14732)
		(layer "In15.Cu")
		(net "P5E_CPU1_PE2_TX_DN<9>")
	)
	(segment
		(start 148.16328 -325.175118)
		(end 154.584654 -332.64856)
		(width 0.14732)
		(layer "In15.Cu")
		(net "P5E_CPU1_PE2_TX_DN<9>")
	)
	(segment
		(start 132.03301 -219.01658)
		(end 132.0419 -219.0115)
		(width 0.0889)
		(layer "In15.Cu")
		(net "P5E_CPU1_PE2_TX_DN<9>")
	)
	(segment
		(start 148.587968 -250.27001)
		(end 148.590508 -250.28652)
		(width 0.14732)
		(layer "In15.Cu")
		(net "P5E_CPU1_PE2_TX_DN<9>")
	)
	(segment
		(start 138.354816 -217.47861)
		(end 138.795506 -217.9193)
		(width 0.0889)
		(layer "In15.Cu")
		(net "P5E_CPU1_PE2_TX_DN<9>")
	)
	(segment
		(start 132.497068 -218.20632)
		(end 132.503164 -218.202764)
		(width 0.0889)
		(layer "In15.Cu")
		(net "P5E_CPU1_PE2_TX_DN<9>")
	)
	(segment
		(start 138.050016 -217.05443)
		(end 138.050016 -217.064336)
		(width 0.0889)
		(layer "In15.Cu")
		(net "P5E_CPU1_PE2_TX_DN<9>")
	)
	(segment
		(start 130.617468 -221.461838)
		(end 130.623564 -221.458282)
		(width 0.0889)
		(layer "In15.Cu")
		(net "P5E_CPU1_PE2_TX_DN<9>")
	)
	(segment
		(start 132.690616 -217.878406)
		(end 132.690616 -217.859864)
		(width 0.0889)
		(layer "In15.Cu")
		(net "P5E_CPU1_PE2_TX_DN<9>")
	)
	(segment
		(start 131.643882 -219.007944)
		(end 131.658614 -219.01658)
		(width 0.0889)
		(layer "In15.Cu")
		(net "P5E_CPU1_PE2_TX_DN<9>")
	)
	(segment
		(start 156.939234 -345.995498)
		(end 156.221684 -350.071436)
		(width 0.14732)
		(layer "In15.Cu")
		(net "P5E_CPU1_PE2_TX_DN<9>")
	)
	(segment
		(start 139.103354 -399.75917)
		(end 139.103354 -400.563588)
		(width 0.14732)
		(layer "In15.Cu")
		(net "P5E_CPU1_PE2_TX_DN<9>")
	)
	(segment
		(start 128.71323 -224.66046)
		(end 128.791462 -224.681288)
		(width 0.0889)
		(layer "In15.Cu")
		(net "P5E_CPU1_PE2_TX_DN<9>")
	)
	(segment
		(start 144.081246 -223.976692)
		(end 144.610582 -225.805492)
		(width 0.14732)
		(layer "In15.Cu")
		(net "P5E_CPU1_PE2_TX_DN<9>")
	)
	(segment
		(start 152.16251 -370.500656)
		(end 139.103354 -399.75917)
		(width 0.14732)
		(layer "In15.Cu")
		(net "P5E_CPU1_PE2_TX_DN<9>")
	)
	(segment
		(start 148.686012 -253.169674)
		(end 148.685758 -253.169674)
		(width 0.14732)
		(layer "In15.Cu")
		(net "P5E_CPU1_PE2_TX_DN<9>")
	)
	(segment
		(start 154.584654 -332.64856)
		(end 156.939234 -345.995498)
		(width 0.14732)
		(layer "In15.Cu")
		(net "P5E_CPU1_PE2_TX_DN<9>")
	)
	(segment
		(start 138.228578 -217.383614)
		(end 138.237468 -217.388694)
		(width 0.0889)
		(layer "In15.Cu")
		(net "P5E_CPU1_PE2_TX_DN<9>")
	)
	(segment
		(start 129.871216 -222.761556)
		(end 129.871216 -222.746062)
		(width 0.0889)
		(layer "In15.Cu")
		(net "P5E_CPU1_PE2_TX_DN<9>")
	)
	(segment
		(start 130.624326 -220.810074)
		(end 130.623564 -220.809566)
		(width 0.0889)
		(layer "In15.Cu")
		(net "P5E_CPU1_PE2_TX_DN<9>")
	)
	(segment
		(start 148.685758 -253.169674)
		(end 144.38376 -309.343044)
		(width 0.14732)
		(layer "In15.Cu")
		(net "P5E_CPU1_PE2_TX_DN<9>")
	)
	(segment
		(start 133.442964 -216.574878)
		(end 133.457696 -216.566242)
		(width 0.0889)
		(layer "In15.Cu")
		(net "P5E_CPU1_PE2_TX_DN<9>")
	)
	(segment
		(start 130.622294 -219.831158)
		(end 130.623564 -219.830396)
		(width 0.0889)
		(layer "In15.Cu")
		(net "P5E_CPU1_PE2_TX_DN<9>")
	)
	(segment
		(start 138.85545 -217.9193)
		(end 138.870944 -217.934794)
		(width 0.0889)
		(layer "In15.Cu")
		(net "P5E_CPU1_PE2_TX_DN<9>")
	)
	(segment
		(start 148.59127 -250.30557)
		(end 148.687028 -253.154688)
		(width 0.14732)
		(layer "In15.Cu")
		(net "P5E_CPU1_PE2_TX_DN<9>")
	)
	(segment
		(start 138.795506 -217.9193)
		(end 138.85545 -217.9193)
		(width 0.0889)
		(layer "In15.Cu")
		(net "P5E_CPU1_PE2_TX_DN<9>")
	)
	(segment
		(start 130.611372 -219.837508)
		(end 130.622294 -219.831158)
		(width 0.0889)
		(layer "In15.Cu")
		(net "P5E_CPU1_PE2_TX_DN<9>")
	)
	(segment
		(start 148.587968 -250.270264)
		(end 148.587968 -250.27001)
		(width 0.14732)
		(layer "In15.Cu")
		(net "P5E_CPU1_PE2_TX_DN<9>")
	)
	(segment
		(start 145.375376 -229.672896)
		(end 148.587968 -250.270264)
		(width 0.14732)
		(layer "In15.Cu")
		(net "P5E_CPU1_PE2_TX_DN<9>")
	)
	(segment
		(start 133.160262 -217.072972)
		(end 133.160262 -217.064336)
		(width 0.0889)
		(layer "In15.Cu")
		(net "P5E_CPU1_PE2_TX_DN<9>")
	)
	(segment
		(start 132.503164 -218.202764)
		(end 132.512054 -218.197684)
		(width 0.0889)
		(layer "In15.Cu")
		(net "P5E_CPU1_PE2_TX_DN<9>")
	)
	(segment
		(start 148.590508 -250.28652)
		(end 148.59127 -250.30557)
		(width 0.14732)
		(layer "In15.Cu")
		(net "P5E_CPU1_PE2_TX_DN<9>")
	)
	(segment
		(start 138.870944 -217.934794)
		(end 141.488922 -220.552772)
		(width 0.14732)
		(layer "In15.Cu")
		(net "P5E_CPU1_PE2_TX_DN<9>")
	)
	(arc
		(start 130.340862 -221.94774)
		(mid 130.414853 -221.668174)
		(end 130.617468 -221.461838)
		(width 0.0889)
		(layer "In15.Cu")
		(net "P5E_CPU1_PE2_TX_DN<9>")
	)
	(arc
		(start 128.791462 -224.681288)
		(mid 128.894607 -224.551263)
		(end 128.931416 -224.389442)
		(width 0.0889)
		(layer "In15.Cu")
		(net "P5E_CPU1_PE2_TX_DN<9>")
	)
	(arc
		(start 133.160262 -217.064336)
		(mid 133.234253 -216.78477)
		(end 133.436868 -216.578434)
		(width 0.0889)
		(layer "In15.Cu")
		(net "P5E_CPU1_PE2_TX_DN<9>")
	)
	(arc
		(start 131.658614 -219.01658)
		(mid 131.845812 -219.066723)
		(end 132.03301 -219.01658)
		(width 0.0889)
		(layer "In15.Cu")
		(net "P5E_CPU1_PE2_TX_DN<9>")
	)
	(arc
		(start 136.262364 -216.574878)
		(mid 136.545066 -216.499102)
		(end 136.827768 -216.574878)
		(width 0.0889)
		(layer "In15.Cu")
		(net "P5E_CPU1_PE2_TX_DN<9>")
	)
	(arc
		(start 132.690616 -217.859864)
		(mid 132.770778 -217.587675)
		(end 132.973064 -217.388694)
		(width 0.0889)
		(layer "In15.Cu")
		(net "P5E_CPU1_PE2_TX_DN<9>")
	)
	(arc
		(start 132.220462 -218.692222)
		(mid 132.294453 -218.412656)
		(end 132.497068 -218.20632)
		(width 0.0889)
		(layer "In15.Cu")
		(net "P5E_CPU1_PE2_TX_DN<9>")
	)
	(arc
		(start 132.512054 -218.197684)
		(mid 132.642968 -218.061324)
		(end 132.690616 -217.878406)
		(width 0.0889)
		(layer "In15.Cu")
		(net "P5E_CPU1_PE2_TX_DN<9>")
	)
	(arc
		(start 129.692654 -223.080834)
		(mid 129.823568 -222.944474)
		(end 129.871216 -222.761556)
		(width 0.0889)
		(layer "In15.Cu")
		(net "P5E_CPU1_PE2_TX_DN<9>")
	)
	(arc
		(start 137.767568 -216.574878)
		(mid 137.971903 -216.777483)
		(end 138.050016 -217.05443)
		(width 0.0889)
		(layer "In15.Cu")
		(net "P5E_CPU1_PE2_TX_DN<9>")
	)
	(arc
		(start 131.09321 -219.01658)
		(mid 131.367409 -218.940745)
		(end 131.643882 -219.007944)
		(width 0.0889)
		(layer "In15.Cu")
		(net "P5E_CPU1_PE2_TX_DN<9>")
	)
	(arc
		(start 129.213864 -223.899984)
		(mid 129.348797 -223.76663)
		(end 129.401062 -223.584262)
		(width 0.0889)
		(layer "In15.Cu")
		(net "P5E_CPU1_PE2_TX_DN<9>")
	)
	(arc
		(start 129.871216 -222.746062)
		(mid 129.950586 -222.472328)
		(end 130.15341 -222.272098)
		(width 0.0889)
		(layer "In15.Cu")
		(net "P5E_CPU1_PE2_TX_DN<9>")
	)
	(arc
		(start 135.322564 -216.574878)
		(mid 135.605266 -216.499102)
		(end 135.887968 -216.574878)
		(width 0.0889)
		(layer "In15.Cu")
		(net "P5E_CPU1_PE2_TX_DN<9>")
	)
	(arc
		(start 135.887968 -216.574878)
		(mid 136.075166 -216.625021)
		(end 136.262364 -216.574878)
		(width 0.0889)
		(layer "In15.Cu")
		(net "P5E_CPU1_PE2_TX_DN<9>")
	)
	(arc
		(start 128.931416 -224.379536)
		(mid 129.009527 -224.102587)
		(end 129.213864 -223.899984)
		(width 0.0889)
		(layer "In15.Cu")
		(net "P5E_CPU1_PE2_TX_DN<9>")
	)
	(arc
		(start 132.973064 -217.388694)
		(mid 133.107997 -217.25534)
		(end 133.160262 -217.072972)
		(width 0.0889)
		(layer "In15.Cu")
		(net "P5E_CPU1_PE2_TX_DN<9>")
	)
	(arc
		(start 133.457696 -216.566242)
		(mid 133.734171 -216.498922)
		(end 134.008368 -216.574878)
		(width 0.0889)
		(layer "In15.Cu")
		(net "P5E_CPU1_PE2_TX_DN<9>")
	)
	(arc
		(start 129.401062 -223.561402)
		(mid 129.480281 -223.286717)
		(end 129.683764 -223.085914)
		(width 0.0889)
		(layer "In15.Cu")
		(net "P5E_CPU1_PE2_TX_DN<9>")
	)
	(arc
		(start 136.827768 -216.574878)
		(mid 137.014966 -216.625021)
		(end 137.202164 -216.574878)
		(width 0.0889)
		(layer "In15.Cu")
		(net "P5E_CPU1_PE2_TX_DN<9>")
	)
	(arc
		(start 130.811016 -219.490544)
		(mid 130.890386 -219.21681)
		(end 131.09321 -219.01658)
		(width 0.0889)
		(layer "In15.Cu")
		(net "P5E_CPU1_PE2_TX_DN<9>")
	)
	(arc
		(start 132.0419 -219.0115)
		(mid 132.172814 -218.87514)
		(end 132.220462 -218.692222)
		(width 0.0889)
		(layer "In15.Cu")
		(net "P5E_CPU1_PE2_TX_DN<9>")
	)
	(arc
		(start 134.008368 -216.574878)
		(mid 134.195566 -216.625021)
		(end 134.382764 -216.574878)
		(width 0.0889)
		(layer "In15.Cu")
		(net "P5E_CPU1_PE2_TX_DN<9>")
	)
	(arc
		(start 134.382764 -216.574878)
		(mid 134.665466 -216.499102)
		(end 134.948168 -216.574878)
		(width 0.0889)
		(layer "In15.Cu")
		(net "P5E_CPU1_PE2_TX_DN<9>")
	)
	(arc
		(start 138.050016 -217.064336)
		(mid 138.097695 -217.247236)
		(end 138.228578 -217.383614)
		(width 0.0889)
		(layer "In15.Cu")
		(net "P5E_CPU1_PE2_TX_DN<9>")
	)
	(arc
		(start 130.1623 -222.267018)
		(mid 130.293214 -222.130658)
		(end 130.340862 -221.94774)
		(width 0.0889)
		(layer "In15.Cu")
		(net "P5E_CPU1_PE2_TX_DN<9>")
	)
	(arc
		(start 134.948168 -216.574878)
		(mid 135.135366 -216.625021)
		(end 135.322564 -216.574878)
		(width 0.0889)
		(layer "In15.Cu")
		(net "P5E_CPU1_PE2_TX_DN<9>")
	)
	(arc
		(start 137.202164 -216.574878)
		(mid 137.484866 -216.499102)
		(end 137.767568 -216.574878)
		(width 0.0889)
		(layer "In15.Cu")
		(net "P5E_CPU1_PE2_TX_DN<9>")
	)
	(arc
		(start 130.632454 -219.825316)
		(mid 130.763368 -219.688956)
		(end 130.811016 -219.506038)
		(width 0.0889)
		(layer "In15.Cu")
		(net "P5E_CPU1_PE2_TX_DN<9>")
	)
	(arc
		(start 138.237468 -217.388694)
		(mid 138.299101 -217.429791)
		(end 138.354816 -217.47861)
		(width 0.0889)
		(layer "In15.Cu")
		(net "P5E_CPU1_PE2_TX_DN<9>")
	)
	(arc
		(start 130.632454 -221.453202)
		(mid 130.811051 -221.133924)
		(end 130.632454 -220.814646)
		(width 0.0889)
		(layer "In15.Cu")
		(net "P5E_CPU1_PE2_TX_DN<9>")
	)
	(arc
		(start 130.340862 -220.319854)
		(mid 130.413097 -220.04333)
		(end 130.611372 -219.837508)
		(width 0.0889)
		(layer "In15.Cu")
		(net "P5E_CPU1_PE2_TX_DN<9>")
	)
	(arc
		(start 130.623564 -220.809566)
		(mid 130.418492 -220.605887)
		(end 130.340862 -220.327474)
		(width 0.0889)
		(layer "In15.Cu")
		(net "P5E_CPU1_PE2_TX_DN<9>")
	)
	(segment
		(start 142.162276 -401.779994)
		(end 142.486634 -402.104352)
		(width 0.13208)
		(layer "F.Cu")
		(net "P5E_CPU1_PE2_TX_DN<8>")
	)
	(segment
		(start 128.086866 -223.57588)
		(end 128.086612 -223.575626)
		(width 0.13208)
		(layer "F.Cu")
		(net "P5E_CPU1_PE2_TX_DN<8>")
	)
	(segment
		(start 142.461234 -400.858228)
		(end 142.162276 -401.157186)
		(width 0.13208)
		(layer "F.Cu")
		(net "P5E_CPU1_PE2_TX_DN<8>")
	)
	(segment
		(start 128.086866 -224.111566)
		(end 128.086866 -223.57588)
		(width 0.13208)
		(layer "F.Cu")
		(net "P5E_CPU1_PE2_TX_DN<8>")
	)
	(segment
		(start 142.162276 -401.157186)
		(end 142.162276 -401.779994)
		(width 0.13208)
		(layer "F.Cu")
		(net "P5E_CPU1_PE2_TX_DN<8>")
	)
	(segment
		(start 129.685288 -219.829634)
		(end 129.692654 -219.825316)
		(width 0.0889)
		(layer "In15.Cu")
		(net "P5E_CPU1_PE2_TX_DN<8>")
	)
	(segment
		(start 131.557268 -216.578434)
		(end 131.563364 -216.574878)
		(width 0.0889)
		(layer "In15.Cu")
		(net "P5E_CPU1_PE2_TX_DN<8>")
	)
	(segment
		(start 147.904708 -239.72139)
		(end 147.905216 -239.721644)
		(width 0.14732)
		(layer "In15.Cu")
		(net "P5E_CPU1_PE2_TX_DN<8>")
	)
	(segment
		(start 139.69746 -217.134186)
		(end 141.192504 -218.629484)
		(width 0.14732)
		(layer "In15.Cu")
		(net "P5E_CPU1_PE2_TX_DN<8>")
	)
	(segment
		(start 129.871216 -219.506038)
		(end 129.871216 -219.490544)
		(width 0.0889)
		(layer "In15.Cu")
		(net "P5E_CPU1_PE2_TX_DN<8>")
	)
	(segment
		(start 145.010378 -223.625156)
		(end 145.593054 -225.825304)
		(width 0.14732)
		(layer "In15.Cu")
		(net "P5E_CPU1_PE2_TX_DN<8>")
	)
	(segment
		(start 149.51075 -249.950478)
		(end 149.620732 -253.218442)
		(width 0.14732)
		(layer "In15.Cu")
		(net "P5E_CPU1_PE2_TX_DN<8>")
	)
	(segment
		(start 145.35658 -309.287164)
		(end 149.011894 -324.674738)
		(width 0.14732)
		(layer "In15.Cu")
		(net "P5E_CPU1_PE2_TX_DN<8>")
	)
	(segment
		(start 138.750802 -216.187528)
		(end 138.766296 -216.203022)
		(width 0.0889)
		(layer "In15.Cu")
		(net "P5E_CPU1_PE2_TX_DN<8>")
	)
	(segment
		(start 149.011894 -324.674738)
		(end 155.456128 -332.176628)
		(width 0.14732)
		(layer "In15.Cu")
		(net "P5E_CPU1_PE2_TX_DN<8>")
	)
	(segment
		(start 146.30146 -229.50424)
		(end 147.904708 -239.72139)
		(width 0.14732)
		(layer "In15.Cu")
		(net "P5E_CPU1_PE2_TX_DN<8>")
	)
	(segment
		(start 129.683764 -219.830396)
		(end 129.685288 -219.829634)
		(width 0.0889)
		(layer "In15.Cu")
		(net "P5E_CPU1_PE2_TX_DN<8>")
	)
	(segment
		(start 135.403082 -215.752426)
		(end 135.417814 -215.761062)
		(width 0.0889)
		(layer "In15.Cu")
		(net "P5E_CPU1_PE2_TX_DN<8>")
	)
	(segment
		(start 128.931416 -222.761556)
		(end 128.931416 -222.746062)
		(width 0.0889)
		(layer "In15.Cu")
		(net "P5E_CPU1_PE2_TX_DN<8>")
	)
	(segment
		(start 156.004514 -363.880654)
		(end 142.166594 -400.224244)
		(width 0.14732)
		(layer "In15.Cu")
		(net "P5E_CPU1_PE2_TX_DN<8>")
	)
	(segment
		(start 129.21361 -222.272098)
		(end 129.2225 -222.267018)
		(width 0.0889)
		(layer "In15.Cu")
		(net "P5E_CPU1_PE2_TX_DN<8>")
	)
	(segment
		(start 127.930148 -223.846644)
		(end 127.95123 -223.924622)
		(width 0.0889)
		(layer "In15.Cu")
		(net "P5E_CPU1_PE2_TX_DN<8>")
	)
	(segment
		(start 157.24505 -349.679768)
		(end 156.004514 -363.880654)
		(width 0.14732)
		(layer "In15.Cu")
		(net "P5E_CPU1_PE2_TX_DN<8>")
	)
	(segment
		(start 147.905216 -239.721644)
		(end 149.51075 -249.950478)
		(width 0.14732)
		(layer "In15.Cu")
		(net "P5E_CPU1_PE2_TX_DN<8>")
	)
	(segment
		(start 132.503164 -216.574878)
		(end 132.512054 -216.569798)
		(width 0.0889)
		(layer "In15.Cu")
		(net "P5E_CPU1_PE2_TX_DN<8>")
	)
	(segment
		(start 142.166594 -400.563588)
		(end 142.461234 -400.858228)
		(width 0.14732)
		(layer "In15.Cu")
		(net "P5E_CPU1_PE2_TX_DN<8>")
	)
	(segment
		(start 139.388088 -216.652348)
		(end 139.69746 -216.96172)
		(width 0.14732)
		(layer "In15.Cu")
		(net "P5E_CPU1_PE2_TX_DN<8>")
	)
	(segment
		(start 138.354562 -215.849962)
		(end 138.595608 -216.091262)
		(width 0.0889)
		(layer "In15.Cu")
		(net "P5E_CPU1_PE2_TX_DN<8>")
	)
	(segment
		(start 128.274826 -223.899476)
		(end 128.2827 -223.894904)
		(width 0.0889)
		(layer "In15.Cu")
		(net "P5E_CPU1_PE2_TX_DN<8>")
	)
	(segment
		(start 129.401062 -220.334078)
		(end 129.401062 -220.319854)
		(width 0.0889)
		(layer "In15.Cu")
		(net "P5E_CPU1_PE2_TX_DN<8>")
	)
	(segment
		(start 141.192504 -218.62923)
		(end 145.010378 -223.625156)
		(width 0.14732)
		(layer "In15.Cu")
		(net "P5E_CPU1_PE2_TX_DN<8>")
	)
	(segment
		(start 141.192504 -218.629484)
		(end 141.192504 -218.62923)
		(width 0.14732)
		(layer "In15.Cu")
		(net "P5E_CPU1_PE2_TX_DN<8>")
	)
	(segment
		(start 128.743964 -223.085914)
		(end 128.752854 -223.080834)
		(width 0.0889)
		(layer "In15.Cu")
		(net "P5E_CPU1_PE2_TX_DN<8>")
	)
	(segment
		(start 136.732518 -215.761062)
		(end 136.750552 -215.750648)
		(width 0.0889)
		(layer "In15.Cu")
		(net "P5E_CPU1_PE2_TX_DN<8>")
	)
	(segment
		(start 137.660634 -215.76792)
		(end 137.672572 -215.761062)
		(width 0.0889)
		(layer "In15.Cu")
		(net "P5E_CPU1_PE2_TX_DN<8>")
	)
	(segment
		(start 129.692654 -220.814646)
		(end 129.683764 -220.809566)
		(width 0.0889)
		(layer "In15.Cu")
		(net "P5E_CPU1_PE2_TX_DN<8>")
	)
	(segment
		(start 128.461262 -223.575626)
		(end 128.461262 -223.568006)
		(width 0.0889)
		(layer "In15.Cu")
		(net "P5E_CPU1_PE2_TX_DN<8>")
	)
	(segment
		(start 138.766296 -216.203022)
		(end 139.215622 -216.652348)
		(width 0.14732)
		(layer "In15.Cu")
		(net "P5E_CPU1_PE2_TX_DN<8>")
	)
	(segment
		(start 129.677668 -221.461838)
		(end 129.683764 -221.458282)
		(width 0.0889)
		(layer "In15.Cu")
		(net "P5E_CPU1_PE2_TX_DN<8>")
	)
	(segment
		(start 132.690616 -216.25052)
		(end 132.690616 -216.235026)
		(width 0.0889)
		(layer "In15.Cu")
		(net "P5E_CPU1_PE2_TX_DN<8>")
	)
	(segment
		(start 130.623564 -218.202764)
		(end 130.632454 -218.197684)
		(width 0.0889)
		(layer "In15.Cu")
		(net "P5E_CPU1_PE2_TX_DN<8>")
	)
	(segment
		(start 138.691874 -216.187528)
		(end 138.750802 -216.187528)
		(width 0.0889)
		(layer "In15.Cu")
		(net "P5E_CPU1_PE2_TX_DN<8>")
	)
	(segment
		(start 142.166594 -400.224244)
		(end 142.166594 -400.563588)
		(width 0.14732)
		(layer "In15.Cu")
		(net "P5E_CPU1_PE2_TX_DN<8>")
	)
	(segment
		(start 130.811016 -217.878406)
		(end 130.811016 -217.859864)
		(width 0.0889)
		(layer "In15.Cu")
		(net "P5E_CPU1_PE2_TX_DN<8>")
	)
	(segment
		(start 137.672572 -215.761062)
		(end 137.69594 -215.7476)
		(width 0.0889)
		(layer "In15.Cu")
		(net "P5E_CPU1_PE2_TX_DN<8>")
	)
	(segment
		(start 155.456128 -332.176628)
		(end 157.893766 -345.996006)
		(width 0.14732)
		(layer "In15.Cu")
		(net "P5E_CPU1_PE2_TX_DN<8>")
	)
	(segment
		(start 128.086612 -223.575626)
		(end 127.930148 -223.846644)
		(width 0.0889)
		(layer "In15.Cu")
		(net "P5E_CPU1_PE2_TX_DN<8>")
	)
	(segment
		(start 134.463282 -215.752426)
		(end 134.478014 -215.761062)
		(width 0.0889)
		(layer "In15.Cu")
		(net "P5E_CPU1_PE2_TX_DN<8>")
	)
	(segment
		(start 129.683764 -221.458282)
		(end 129.692654 -221.453202)
		(width 0.0889)
		(layer "In15.Cu")
		(net "P5E_CPU1_PE2_TX_DN<8>")
	)
	(segment
		(start 149.620732 -253.218442)
		(end 145.35658 -309.287164)
		(width 0.14732)
		(layer "In15.Cu")
		(net "P5E_CPU1_PE2_TX_DN<8>")
	)
	(segment
		(start 131.280662 -217.072972)
		(end 131.280662 -217.064336)
		(width 0.0889)
		(layer "In15.Cu")
		(net "P5E_CPU1_PE2_TX_DN<8>")
	)
	(segment
		(start 130.617468 -218.20632)
		(end 130.623564 -218.202764)
		(width 0.0889)
		(layer "In15.Cu")
		(net "P5E_CPU1_PE2_TX_DN<8>")
	)
	(segment
		(start 133.523482 -215.752426)
		(end 133.538214 -215.761062)
		(width 0.0889)
		(layer "In15.Cu")
		(net "P5E_CPU1_PE2_TX_DN<8>")
	)
	(segment
		(start 131.563364 -216.574878)
		(end 131.578096 -216.566242)
		(width 0.0889)
		(layer "In15.Cu")
		(net "P5E_CPU1_PE2_TX_DN<8>")
	)
	(segment
		(start 139.215622 -216.652348)
		(end 139.388088 -216.652348)
		(width 0.14732)
		(layer "In15.Cu")
		(net "P5E_CPU1_PE2_TX_DN<8>")
	)
	(segment
		(start 130.15341 -219.01658)
		(end 130.1623 -219.0115)
		(width 0.0889)
		(layer "In15.Cu")
		(net "P5E_CPU1_PE2_TX_DN<8>")
	)
	(segment
		(start 157.893766 -345.996006)
		(end 157.24505 -349.679768)
		(width 0.14732)
		(layer "In15.Cu")
		(net "P5E_CPU1_PE2_TX_DN<8>")
	)
	(segment
		(start 128.27381 -223.899984)
		(end 128.274826 -223.899476)
		(width 0.0889)
		(layer "In15.Cu")
		(net "P5E_CPU1_PE2_TX_DN<8>")
	)
	(segment
		(start 145.593054 -225.825304)
		(end 146.30146 -229.50424)
		(width 0.14732)
		(layer "In15.Cu")
		(net "P5E_CPU1_PE2_TX_DN<8>")
	)
	(segment
		(start 129.677668 -219.833952)
		(end 129.683764 -219.830396)
		(width 0.0889)
		(layer "In15.Cu")
		(net "P5E_CPU1_PE2_TX_DN<8>")
	)
	(segment
		(start 139.69746 -216.96172)
		(end 139.69746 -217.134186)
		(width 0.14732)
		(layer "In15.Cu")
		(net "P5E_CPU1_PE2_TX_DN<8>")
	)
	(segment
		(start 138.595608 -216.091262)
		(end 138.691874 -216.187528)
		(width 0.0889)
		(layer "In15.Cu")
		(net "P5E_CPU1_PE2_TX_DN<8>")
	)
	(arc
		(start 131.280662 -217.064336)
		(mid 131.354653 -216.78477)
		(end 131.557268 -216.578434)
		(width 0.0889)
		(layer "In15.Cu")
		(net "P5E_CPU1_PE2_TX_DN<8>")
	)
	(arc
		(start 129.692654 -219.825316)
		(mid 129.823568 -219.688956)
		(end 129.871216 -219.506038)
		(width 0.0889)
		(layer "In15.Cu")
		(net "P5E_CPU1_PE2_TX_DN<8>")
	)
	(arc
		(start 132.512054 -216.569798)
		(mid 132.642968 -216.433438)
		(end 132.690616 -216.25052)
		(width 0.0889)
		(layer "In15.Cu")
		(net "P5E_CPU1_PE2_TX_DN<8>")
	)
	(arc
		(start 138.23823 -215.761062)
		(mid 138.271771 -215.782011)
		(end 138.303762 -215.805258)
		(width 0.0889)
		(layer "In15.Cu")
		(net "P5E_CPU1_PE2_TX_DN<8>")
	)
	(arc
		(start 138.303762 -215.805258)
		(mid 138.32983 -215.826851)
		(end 138.354562 -215.849962)
		(width 0.0889)
		(layer "In15.Cu")
		(net "P5E_CPU1_PE2_TX_DN<8>")
	)
	(arc
		(start 130.811016 -217.859864)
		(mid 130.891178 -217.587675)
		(end 131.093464 -217.388694)
		(width 0.0889)
		(layer "In15.Cu")
		(net "P5E_CPU1_PE2_TX_DN<8>")
	)
	(arc
		(start 136.750552 -215.750648)
		(mid 137.02571 -215.685125)
		(end 137.298176 -215.761062)
		(width 0.0889)
		(layer "In15.Cu")
		(net "P5E_CPU1_PE2_TX_DN<8>")
	)
	(arc
		(start 128.2827 -223.894904)
		(mid 128.413614 -223.758544)
		(end 128.461262 -223.575626)
		(width 0.0889)
		(layer "In15.Cu")
		(net "P5E_CPU1_PE2_TX_DN<8>")
	)
	(arc
		(start 132.97281 -215.761062)
		(mid 133.247009 -215.685227)
		(end 133.523482 -215.752426)
		(width 0.0889)
		(layer "In15.Cu")
		(net "P5E_CPU1_PE2_TX_DN<8>")
	)
	(arc
		(start 129.683764 -220.809566)
		(mid 129.480283 -220.608762)
		(end 129.401062 -220.334078)
		(width 0.0889)
		(layer "In15.Cu")
		(net "P5E_CPU1_PE2_TX_DN<8>")
	)
	(arc
		(start 134.85241 -215.761062)
		(mid 135.126609 -215.685227)
		(end 135.403082 -215.752426)
		(width 0.0889)
		(layer "In15.Cu")
		(net "P5E_CPU1_PE2_TX_DN<8>")
	)
	(arc
		(start 129.401062 -220.319854)
		(mid 129.475053 -220.040288)
		(end 129.677668 -219.833952)
		(width 0.0889)
		(layer "In15.Cu")
		(net "P5E_CPU1_PE2_TX_DN<8>")
	)
	(arc
		(start 130.632454 -218.197684)
		(mid 130.763368 -218.061324)
		(end 130.811016 -217.878406)
		(width 0.0889)
		(layer "In15.Cu")
		(net "P5E_CPU1_PE2_TX_DN<8>")
	)
	(arc
		(start 128.461262 -223.568006)
		(mid 128.538891 -223.289593)
		(end 128.743964 -223.085914)
		(width 0.0889)
		(layer "In15.Cu")
		(net "P5E_CPU1_PE2_TX_DN<8>")
	)
	(arc
		(start 129.401062 -221.94774)
		(mid 129.475053 -221.668174)
		(end 129.677668 -221.461838)
		(width 0.0889)
		(layer "In15.Cu")
		(net "P5E_CPU1_PE2_TX_DN<8>")
	)
	(arc
		(start 130.340862 -218.692222)
		(mid 130.414853 -218.412656)
		(end 130.617468 -218.20632)
		(width 0.0889)
		(layer "In15.Cu")
		(net "P5E_CPU1_PE2_TX_DN<8>")
	)
	(arc
		(start 133.91261 -215.761062)
		(mid 134.186809 -215.685227)
		(end 134.463282 -215.752426)
		(width 0.0889)
		(layer "In15.Cu")
		(net "P5E_CPU1_PE2_TX_DN<8>")
	)
	(arc
		(start 128.752854 -223.080834)
		(mid 128.883768 -222.944474)
		(end 128.931416 -222.761556)
		(width 0.0889)
		(layer "In15.Cu")
		(net "P5E_CPU1_PE2_TX_DN<8>")
	)
	(arc
		(start 132.690616 -216.235026)
		(mid 132.769986 -215.961292)
		(end 132.97281 -215.761062)
		(width 0.0889)
		(layer "In15.Cu")
		(net "P5E_CPU1_PE2_TX_DN<8>")
	)
	(arc
		(start 131.093464 -217.388694)
		(mid 131.228397 -217.25534)
		(end 131.280662 -217.072972)
		(width 0.0889)
		(layer "In15.Cu")
		(net "P5E_CPU1_PE2_TX_DN<8>")
	)
	(arc
		(start 135.417814 -215.761062)
		(mid 135.605012 -215.811205)
		(end 135.79221 -215.761062)
		(width 0.0889)
		(layer "In15.Cu")
		(net "P5E_CPU1_PE2_TX_DN<8>")
	)
	(arc
		(start 132.128768 -216.574878)
		(mid 132.315966 -216.625021)
		(end 132.503164 -216.574878)
		(width 0.0889)
		(layer "In15.Cu")
		(net "P5E_CPU1_PE2_TX_DN<8>")
	)
	(arc
		(start 129.871216 -219.490544)
		(mid 129.950586 -219.21681)
		(end 130.15341 -219.01658)
		(width 0.0889)
		(layer "In15.Cu")
		(net "P5E_CPU1_PE2_TX_DN<8>")
	)
	(arc
		(start 130.1623 -219.0115)
		(mid 130.293214 -218.87514)
		(end 130.340862 -218.692222)
		(width 0.0889)
		(layer "In15.Cu")
		(net "P5E_CPU1_PE2_TX_DN<8>")
	)
	(arc
		(start 137.69594 -215.7476)
		(mid 137.968804 -215.68508)
		(end 138.23823 -215.761062)
		(width 0.0889)
		(layer "In15.Cu")
		(net "P5E_CPU1_PE2_TX_DN<8>")
	)
	(arc
		(start 131.578096 -216.566242)
		(mid 131.854571 -216.498922)
		(end 132.128768 -216.574878)
		(width 0.0889)
		(layer "In15.Cu")
		(net "P5E_CPU1_PE2_TX_DN<8>")
	)
	(arc
		(start 134.478014 -215.761062)
		(mid 134.665212 -215.811205)
		(end 134.85241 -215.761062)
		(width 0.0889)
		(layer "In15.Cu")
		(net "P5E_CPU1_PE2_TX_DN<8>")
	)
	(arc
		(start 136.358122 -215.761062)
		(mid 136.54532 -215.811205)
		(end 136.732518 -215.761062)
		(width 0.0889)
		(layer "In15.Cu")
		(net "P5E_CPU1_PE2_TX_DN<8>")
	)
	(arc
		(start 135.79221 -215.761062)
		(mid 136.075166 -215.685159)
		(end 136.358122 -215.761062)
		(width 0.0889)
		(layer "In15.Cu")
		(net "P5E_CPU1_PE2_TX_DN<8>")
	)
	(arc
		(start 128.931416 -222.746062)
		(mid 129.010786 -222.472328)
		(end 129.21361 -222.272098)
		(width 0.0889)
		(layer "In15.Cu")
		(net "P5E_CPU1_PE2_TX_DN<8>")
	)
	(arc
		(start 129.2225 -222.267018)
		(mid 129.353414 -222.130658)
		(end 129.401062 -221.94774)
		(width 0.0889)
		(layer "In15.Cu")
		(net "P5E_CPU1_PE2_TX_DN<8>")
	)
	(arc
		(start 127.95123 -223.924622)
		(mid 128.115326 -223.948969)
		(end 128.27381 -223.899984)
		(width 0.0889)
		(layer "In15.Cu")
		(net "P5E_CPU1_PE2_TX_DN<8>")
	)
	(arc
		(start 133.538214 -215.761062)
		(mid 133.725412 -215.811205)
		(end 133.91261 -215.761062)
		(width 0.0889)
		(layer "In15.Cu")
		(net "P5E_CPU1_PE2_TX_DN<8>")
	)
	(arc
		(start 129.692654 -221.453202)
		(mid 129.871251 -221.133924)
		(end 129.692654 -220.814646)
		(width 0.0889)
		(layer "In15.Cu")
		(net "P5E_CPU1_PE2_TX_DN<8>")
	)
	(arc
		(start 137.298176 -215.761062)
		(mid 137.478523 -215.811265)
		(end 137.660634 -215.76792)
		(width 0.0889)
		(layer "In15.Cu")
		(net "P5E_CPU1_PE2_TX_DN<8>")
	)
	(segment
		(start 145.225516 -401.157186)
		(end 145.225516 -401.779994)
		(width 0.13208)
		(layer "F.Cu")
		(net "P5E_CPU1_PE2_TX_DN<7>")
	)
	(segment
		(start 145.524474 -400.858228)
		(end 145.225516 -401.157186)
		(width 0.13208)
		(layer "F.Cu")
		(net "P5E_CPU1_PE2_TX_DN<7>")
	)
	(segment
		(start 126.677166 -224.925128)
		(end 126.677166 -224.389442)
		(width 0.13208)
		(layer "F.Cu")
		(net "P5E_CPU1_PE2_TX_DN<7>")
	)
	(segment
		(start 145.225516 -401.779994)
		(end 145.549874 -402.104352)
		(width 0.13208)
		(layer "F.Cu")
		(net "P5E_CPU1_PE2_TX_DN<7>")
	)
	(segment
		(start 126.676912 -224.925382)
		(end 126.677166 -224.925128)
		(width 0.13208)
		(layer "F.Cu")
		(net "P5E_CPU1_PE2_TX_DN<7>")
	)
	(segment
		(start 129.683764 -218.202764)
		(end 129.692654 -218.197684)
		(width 0.0889)
		(layer "In15.Cu")
		(net "P5E_CPU1_PE2_TX_DN<7>")
	)
	(segment
		(start 127.991616 -222.761556)
		(end 127.991616 -222.746062)
		(width 0.0889)
		(layer "In15.Cu")
		(net "P5E_CPU1_PE2_TX_DN<7>")
	)
	(segment
		(start 132.03301 -215.761062)
		(end 132.0419 -215.755982)
		(width 0.0889)
		(layer "In15.Cu")
		(net "P5E_CPU1_PE2_TX_DN<7>")
	)
	(segment
		(start 132.220462 -215.436704)
		(end 132.220462 -215.414606)
		(width 0.0889)
		(layer "In15.Cu")
		(net "P5E_CPU1_PE2_TX_DN<7>")
	)
	(segment
		(start 156.980128 -364.084362)
		(end 145.229834 -399.668238)
		(width 0.14732)
		(layer "In15.Cu")
		(net "P5E_CPU1_PE2_TX_DN<7>")
	)
	(segment
		(start 132.690108 -214.622634)
		(end 132.690108 -214.425784)
		(width 0.0889)
		(layer "In15.Cu")
		(net "P5E_CPU1_PE2_TX_DN<7>")
	)
	(segment
		(start 135.540242 -213.557104)
		(end 139.839192 -215.338152)
		(width 0.14732)
		(layer "In15.Cu")
		(net "P5E_CPU1_PE2_TX_DN<7>")
	)
	(segment
		(start 146.64055 -225.729546)
		(end 148.53031 -237.479586)
		(width 0.14732)
		(layer "In15.Cu")
		(net "P5E_CPU1_PE2_TX_DN<7>")
	)
	(segment
		(start 129.685288 -216.574116)
		(end 129.692654 -216.569798)
		(width 0.0889)
		(layer "In15.Cu")
		(net "P5E_CPU1_PE2_TX_DN<7>")
	)
	(segment
		(start 150.552658 -253.236476)
		(end 150.552658 -253.23673)
		(width 0.14732)
		(layer "In15.Cu")
		(net "P5E_CPU1_PE2_TX_DN<7>")
	)
	(segment
		(start 156.43987 -331.886306)
		(end 158.92907 -345.996514)
		(width 0.14732)
		(layer "In15.Cu")
		(net "P5E_CPU1_PE2_TX_DN<7>")
	)
	(segment
		(start 133.858 -213.557104)
		(end 133.880098 -213.557104)
		(width 0.0889)
		(layer "In15.Cu")
		(net "P5E_CPU1_PE2_TX_DN<7>")
	)
	(segment
		(start 129.871216 -216.25052)
		(end 129.871216 -216.235026)
		(width 0.0889)
		(layer "In15.Cu")
		(net "P5E_CPU1_PE2_TX_DN<7>")
	)
	(segment
		(start 129.401062 -217.07856)
		(end 129.401062 -217.064336)
		(width 0.0889)
		(layer "In15.Cu")
		(net "P5E_CPU1_PE2_TX_DN<7>")
	)
	(segment
		(start 150.417276 -249.212354)
		(end 150.552658 -253.236476)
		(width 0.14732)
		(layer "In15.Cu")
		(net "P5E_CPU1_PE2_TX_DN<7>")
	)
	(segment
		(start 158.92907 -345.996514)
		(end 158.197296 -350.1517)
		(width 0.14732)
		(layer "In15.Cu")
		(net "P5E_CPU1_PE2_TX_DN<7>")
	)
	(segment
		(start 128.931416 -219.506038)
		(end 128.931416 -219.490544)
		(width 0.0889)
		(layer "In15.Cu")
		(net "P5E_CPU1_PE2_TX_DN<7>")
	)
	(segment
		(start 129.21361 -219.01658)
		(end 129.2225 -219.0115)
		(width 0.0889)
		(layer "In15.Cu")
		(net "P5E_CPU1_PE2_TX_DN<7>")
	)
	(segment
		(start 132.976112 -214.093298)
		(end 133.470142 -213.599268)
		(width 0.0889)
		(layer "In15.Cu")
		(net "P5E_CPU1_PE2_TX_DN<7>")
	)
	(segment
		(start 133.880098 -213.557104)
		(end 135.540242 -213.557104)
		(width 0.14732)
		(layer "In15.Cu")
		(net "P5E_CPU1_PE2_TX_DN<7>")
	)
	(segment
		(start 145.229834 -399.668238)
		(end 145.229834 -400.563588)
		(width 0.14732)
		(layer "In15.Cu")
		(net "P5E_CPU1_PE2_TX_DN<7>")
	)
	(segment
		(start 128.743964 -219.830396)
		(end 128.752854 -219.825316)
		(width 0.0889)
		(layer "In15.Cu")
		(net "P5E_CPU1_PE2_TX_DN<7>")
	)
	(segment
		(start 133.470142 -213.599268)
		(end 133.815836 -213.599268)
		(width 0.0889)
		(layer "In15.Cu")
		(net "P5E_CPU1_PE2_TX_DN<7>")
	)
	(segment
		(start 128.461262 -220.327474)
		(end 128.461262 -220.319854)
		(width 0.0889)
		(layer "In15.Cu")
		(net "P5E_CPU1_PE2_TX_DN<7>")
	)
	(segment
		(start 146.31924 -309.193438)
		(end 149.860254 -324.215252)
		(width 0.14732)
		(layer "In15.Cu")
		(net "P5E_CPU1_PE2_TX_DN<7>")
	)
	(segment
		(start 148.53031 -237.479586)
		(end 148.530564 -237.479586)
		(width 0.14732)
		(layer "In15.Cu")
		(net "P5E_CPU1_PE2_TX_DN<7>")
	)
	(segment
		(start 127.051816 -224.389442)
		(end 127.051816 -224.379536)
		(width 0.0889)
		(layer "In15.Cu")
		(net "P5E_CPU1_PE2_TX_DN<7>")
	)
	(segment
		(start 158.197296 -350.1517)
		(end 156.980128 -364.084362)
		(width 0.14732)
		(layer "In15.Cu")
		(net "P5E_CPU1_PE2_TX_DN<7>")
	)
	(segment
		(start 130.704082 -215.752426)
		(end 130.718814 -215.761062)
		(width 0.0889)
		(layer "In15.Cu")
		(net "P5E_CPU1_PE2_TX_DN<7>")
	)
	(segment
		(start 127.521462 -223.584262)
		(end 127.521462 -223.561402)
		(width 0.0889)
		(layer "In15.Cu")
		(net "P5E_CPU1_PE2_TX_DN<7>")
	)
	(segment
		(start 126.677166 -224.389442)
		(end 126.83363 -224.66046)
		(width 0.0889)
		(layer "In15.Cu")
		(net "P5E_CPU1_PE2_TX_DN<7>")
	)
	(segment
		(start 128.744726 -220.810074)
		(end 128.743964 -220.809566)
		(width 0.0889)
		(layer "In15.Cu")
		(net "P5E_CPU1_PE2_TX_DN<7>")
	)
	(segment
		(start 145.229834 -400.563588)
		(end 145.524474 -400.858228)
		(width 0.14732)
		(layer "In15.Cu")
		(net "P5E_CPU1_PE2_TX_DN<7>")
	)
	(segment
		(start 139.839192 -215.338152)
		(end 145.911062 -223.232218)
		(width 0.14732)
		(layer "In15.Cu")
		(net "P5E_CPU1_PE2_TX_DN<7>")
	)
	(segment
		(start 128.27381 -222.272098)
		(end 128.2827 -222.267018)
		(width 0.0889)
		(layer "In15.Cu")
		(net "P5E_CPU1_PE2_TX_DN<7>")
	)
	(segment
		(start 150.55215 -253.266448)
		(end 150.551896 -253.266448)
		(width 0.14732)
		(layer "In15.Cu")
		(net "P5E_CPU1_PE2_TX_DN<7>")
	)
	(segment
		(start 133.815836 -213.599268)
		(end 133.858 -213.557104)
		(width 0.0889)
		(layer "In15.Cu")
		(net "P5E_CPU1_PE2_TX_DN<7>")
	)
	(segment
		(start 150.551896 -253.266448)
		(end 146.31924 -309.193438)
		(width 0.14732)
		(layer "In15.Cu")
		(net "P5E_CPU1_PE2_TX_DN<7>")
	)
	(segment
		(start 129.677668 -216.578434)
		(end 129.683764 -216.574878)
		(width 0.0889)
		(layer "In15.Cu")
		(net "P5E_CPU1_PE2_TX_DN<7>")
	)
	(segment
		(start 128.752854 -220.814646)
		(end 128.744726 -220.810074)
		(width 0.0889)
		(layer "In15.Cu")
		(net "P5E_CPU1_PE2_TX_DN<7>")
	)
	(segment
		(start 128.731772 -219.837508)
		(end 128.743964 -219.830396)
		(width 0.0889)
		(layer "In15.Cu")
		(net "P5E_CPU1_PE2_TX_DN<7>")
	)
	(segment
		(start 127.804164 -223.085914)
		(end 127.813054 -223.080834)
		(width 0.0889)
		(layer "In15.Cu")
		(net "P5E_CPU1_PE2_TX_DN<7>")
	)
	(segment
		(start 128.737868 -221.461838)
		(end 128.743964 -221.458282)
		(width 0.0889)
		(layer "In15.Cu")
		(net "P5E_CPU1_PE2_TX_DN<7>")
	)
	(segment
		(start 132.502656 -214.946992)
		(end 132.511546 -214.941912)
		(width 0.0889)
		(layer "In15.Cu")
		(net "P5E_CPU1_PE2_TX_DN<7>")
	)
	(segment
		(start 128.743964 -221.458282)
		(end 128.752854 -221.453202)
		(width 0.0889)
		(layer "In15.Cu")
		(net "P5E_CPU1_PE2_TX_DN<7>")
	)
	(segment
		(start 126.83363 -224.66046)
		(end 126.911862 -224.681288)
		(width 0.0889)
		(layer "In15.Cu")
		(net "P5E_CPU1_PE2_TX_DN<7>")
	)
	(segment
		(start 145.911062 -223.232218)
		(end 146.64055 -225.729546)
		(width 0.14732)
		(layer "In15.Cu")
		(net "P5E_CPU1_PE2_TX_DN<7>")
	)
	(segment
		(start 129.677668 -218.20632)
		(end 129.683764 -218.202764)
		(width 0.0889)
		(layer "In15.Cu")
		(net "P5E_CPU1_PE2_TX_DN<7>")
	)
	(segment
		(start 148.530564 -237.479586)
		(end 150.417276 -249.212354)
		(width 0.14732)
		(layer "In15.Cu")
		(net "P5E_CPU1_PE2_TX_DN<7>")
	)
	(segment
		(start 150.552658 -253.23673)
		(end 150.553166 -253.251716)
		(width 0.14732)
		(layer "In15.Cu")
		(net "P5E_CPU1_PE2_TX_DN<7>")
	)
	(segment
		(start 131.643882 -215.752426)
		(end 131.658614 -215.761062)
		(width 0.0889)
		(layer "In15.Cu")
		(net "P5E_CPU1_PE2_TX_DN<7>")
	)
	(segment
		(start 129.683764 -216.574878)
		(end 129.685288 -216.574116)
		(width 0.0889)
		(layer "In15.Cu")
		(net "P5E_CPU1_PE2_TX_DN<7>")
	)
	(segment
		(start 149.860254 -324.215252)
		(end 156.43987 -331.886306)
		(width 0.14732)
		(layer "In15.Cu")
		(net "P5E_CPU1_PE2_TX_DN<7>")
	)
	(segment
		(start 129.692654 -217.559128)
		(end 129.683764 -217.554048)
		(width 0.0889)
		(layer "In15.Cu")
		(net "P5E_CPU1_PE2_TX_DN<7>")
	)
	(segment
		(start 150.553166 -253.251716)
		(end 150.55215 -253.266448)
		(width 0.14732)
		(layer "In15.Cu")
		(net "P5E_CPU1_PE2_TX_DN<7>")
	)
	(arc
		(start 128.743964 -220.809566)
		(mid 128.538892 -220.605887)
		(end 128.461262 -220.327474)
		(width 0.0889)
		(layer "In15.Cu")
		(net "P5E_CPU1_PE2_TX_DN<7>")
	)
	(arc
		(start 130.718814 -215.761062)
		(mid 130.906012 -215.811205)
		(end 131.09321 -215.761062)
		(width 0.0889)
		(layer "In15.Cu")
		(net "P5E_CPU1_PE2_TX_DN<7>")
	)
	(arc
		(start 126.911862 -224.681288)
		(mid 127.015007 -224.551263)
		(end 127.051816 -224.389442)
		(width 0.0889)
		(layer "In15.Cu")
		(net "P5E_CPU1_PE2_TX_DN<7>")
	)
	(arc
		(start 128.752854 -219.825316)
		(mid 128.883768 -219.688956)
		(end 128.931416 -219.506038)
		(width 0.0889)
		(layer "In15.Cu")
		(net "P5E_CPU1_PE2_TX_DN<7>")
	)
	(arc
		(start 127.813054 -223.080834)
		(mid 127.943968 -222.944474)
		(end 127.991616 -222.761556)
		(width 0.0889)
		(layer "In15.Cu")
		(net "P5E_CPU1_PE2_TX_DN<7>")
	)
	(arc
		(start 129.692654 -218.197684)
		(mid 129.871251 -217.878406)
		(end 129.692654 -217.559128)
		(width 0.0889)
		(layer "In15.Cu")
		(net "P5E_CPU1_PE2_TX_DN<7>")
	)
	(arc
		(start 128.752854 -221.453202)
		(mid 128.931451 -221.133924)
		(end 128.752854 -220.814646)
		(width 0.0889)
		(layer "In15.Cu")
		(net "P5E_CPU1_PE2_TX_DN<7>")
	)
	(arc
		(start 129.401062 -218.692222)
		(mid 129.475053 -218.412656)
		(end 129.677668 -218.20632)
		(width 0.0889)
		(layer "In15.Cu")
		(net "P5E_CPU1_PE2_TX_DN<7>")
	)
	(arc
		(start 129.692654 -216.569798)
		(mid 129.823568 -216.433438)
		(end 129.871216 -216.25052)
		(width 0.0889)
		(layer "In15.Cu")
		(net "P5E_CPU1_PE2_TX_DN<7>")
	)
	(arc
		(start 128.931416 -219.490544)
		(mid 129.010786 -219.21681)
		(end 129.21361 -219.01658)
		(width 0.0889)
		(layer "In15.Cu")
		(net "P5E_CPU1_PE2_TX_DN<7>")
	)
	(arc
		(start 130.15341 -215.761062)
		(mid 130.427609 -215.685227)
		(end 130.704082 -215.752426)
		(width 0.0889)
		(layer "In15.Cu")
		(net "P5E_CPU1_PE2_TX_DN<7>")
	)
	(arc
		(start 127.521462 -223.561402)
		(mid 127.600681 -223.286717)
		(end 127.804164 -223.085914)
		(width 0.0889)
		(layer "In15.Cu")
		(net "P5E_CPU1_PE2_TX_DN<7>")
	)
	(arc
		(start 127.051816 -224.379536)
		(mid 127.129927 -224.102587)
		(end 127.334264 -223.899984)
		(width 0.0889)
		(layer "In15.Cu")
		(net "P5E_CPU1_PE2_TX_DN<7>")
	)
	(arc
		(start 131.09321 -215.761062)
		(mid 131.367409 -215.685227)
		(end 131.643882 -215.752426)
		(width 0.0889)
		(layer "In15.Cu")
		(net "P5E_CPU1_PE2_TX_DN<7>")
	)
	(arc
		(start 132.689854 -214.637366)
		(mid 132.690051 -214.630001)
		(end 132.690108 -214.622634)
		(width 0.0889)
		(layer "In15.Cu")
		(net "P5E_CPU1_PE2_TX_DN<7>")
	)
	(arc
		(start 132.0419 -215.755982)
		(mid 132.172814 -215.619622)
		(end 132.220462 -215.436704)
		(width 0.0889)
		(layer "In15.Cu")
		(net "P5E_CPU1_PE2_TX_DN<7>")
	)
	(arc
		(start 132.690108 -214.425784)
		(mid 132.801548 -214.232389)
		(end 132.976112 -214.093298)
		(width 0.0889)
		(layer "In15.Cu")
		(net "P5E_CPU1_PE2_TX_DN<7>")
	)
	(arc
		(start 131.658614 -215.761062)
		(mid 131.845812 -215.811205)
		(end 132.03301 -215.761062)
		(width 0.0889)
		(layer "In15.Cu")
		(net "P5E_CPU1_PE2_TX_DN<7>")
	)
	(arc
		(start 129.683764 -217.554048)
		(mid 129.480283 -217.353244)
		(end 129.401062 -217.07856)
		(width 0.0889)
		(layer "In15.Cu")
		(net "P5E_CPU1_PE2_TX_DN<7>")
	)
	(arc
		(start 127.991616 -222.746062)
		(mid 128.070986 -222.472328)
		(end 128.27381 -222.272098)
		(width 0.0889)
		(layer "In15.Cu")
		(net "P5E_CPU1_PE2_TX_DN<7>")
	)
	(arc
		(start 129.401062 -217.064336)
		(mid 129.475053 -216.78477)
		(end 129.677668 -216.578434)
		(width 0.0889)
		(layer "In15.Cu")
		(net "P5E_CPU1_PE2_TX_DN<7>")
	)
	(arc
		(start 132.220462 -215.414606)
		(mid 132.301373 -215.144478)
		(end 132.502656 -214.946992)
		(width 0.0889)
		(layer "In15.Cu")
		(net "P5E_CPU1_PE2_TX_DN<7>")
	)
	(arc
		(start 132.511546 -214.941912)
		(mid 132.6388 -214.811946)
		(end 132.689854 -214.637366)
		(width 0.0889)
		(layer "In15.Cu")
		(net "P5E_CPU1_PE2_TX_DN<7>")
	)
	(arc
		(start 128.461262 -221.94774)
		(mid 128.535253 -221.668174)
		(end 128.737868 -221.461838)
		(width 0.0889)
		(layer "In15.Cu")
		(net "P5E_CPU1_PE2_TX_DN<7>")
	)
	(arc
		(start 129.2225 -219.0115)
		(mid 129.353414 -218.87514)
		(end 129.401062 -218.692222)
		(width 0.0889)
		(layer "In15.Cu")
		(net "P5E_CPU1_PE2_TX_DN<7>")
	)
	(arc
		(start 128.2827 -222.267018)
		(mid 128.413614 -222.130658)
		(end 128.461262 -221.94774)
		(width 0.0889)
		(layer "In15.Cu")
		(net "P5E_CPU1_PE2_TX_DN<7>")
	)
	(arc
		(start 128.461262 -220.319854)
		(mid 128.533497 -220.04333)
		(end 128.731772 -219.837508)
		(width 0.0889)
		(layer "In15.Cu")
		(net "P5E_CPU1_PE2_TX_DN<7>")
	)
	(arc
		(start 127.334264 -223.899984)
		(mid 127.469197 -223.76663)
		(end 127.521462 -223.584262)
		(width 0.0889)
		(layer "In15.Cu")
		(net "P5E_CPU1_PE2_TX_DN<7>")
	)
	(arc
		(start 129.871216 -216.235026)
		(mid 129.950586 -215.961292)
		(end 130.15341 -215.761062)
		(width 0.0889)
		(layer "In15.Cu")
		(net "P5E_CPU1_PE2_TX_DN<7>")
	)
	(segment
		(start 126.207012 -224.111312)
		(end 126.207012 -223.575626)
		(width 0.13208)
		(layer "F.Cu")
		(net "P5E_CPU1_PE2_TX_DN<6>")
	)
	(segment
		(start 148.587714 -400.858228)
		(end 148.288756 -401.157186)
		(width 0.13208)
		(layer "F.Cu")
		(net "P5E_CPU1_PE2_TX_DN<6>")
	)
	(segment
		(start 148.288756 -401.779994)
		(end 148.613114 -402.104352)
		(width 0.13208)
		(layer "F.Cu")
		(net "P5E_CPU1_PE2_TX_DN<6>")
	)
	(segment
		(start 126.207266 -224.111566)
		(end 126.207012 -224.111312)
		(width 0.13208)
		(layer "F.Cu")
		(net "P5E_CPU1_PE2_TX_DN<6>")
	)
	(segment
		(start 148.288756 -401.157186)
		(end 148.288756 -401.779994)
		(width 0.13208)
		(layer "F.Cu")
		(net "P5E_CPU1_PE2_TX_DN<6>")
	)
	(segment
		(start 131.238752 -212.924644)
		(end 131.574032 -212.589364)
		(width 0.14732)
		(layer "In15.Cu")
		(net "P5E_CPU1_PE2_TX_DN<6>")
	)
	(segment
		(start 126.39421 -223.899984)
		(end 126.395226 -223.899476)
		(width 0.0889)
		(layer "In15.Cu")
		(net "P5E_CPU1_PE2_TX_DN<6>")
	)
	(segment
		(start 159.327342 -349.154496)
		(end 158.037784 -363.906308)
		(width 0.14732)
		(layer "In15.Cu")
		(net "P5E_CPU1_PE2_TX_DN<6>")
	)
	(segment
		(start 128.931416 -216.25052)
		(end 128.931416 -216.235026)
		(width 0.0889)
		(layer "In15.Cu")
		(net "P5E_CPU1_PE2_TX_DN<6>")
	)
	(segment
		(start 148.293074 -400.563588)
		(end 148.587714 -400.858228)
		(width 0.14732)
		(layer "In15.Cu")
		(net "P5E_CPU1_PE2_TX_DN<6>")
	)
	(segment
		(start 157.31617 -331.439266)
		(end 159.883602 -345.996768)
		(width 0.14732)
		(layer "In15.Cu")
		(net "P5E_CPU1_PE2_TX_DN<6>")
	)
	(segment
		(start 159.883602 -345.996768)
		(end 159.327342 -349.154496)
		(width 0.14732)
		(layer "In15.Cu")
		(net "P5E_CPU1_PE2_TX_DN<6>")
	)
	(segment
		(start 131.574032 -212.589364)
		(end 135.778748 -212.589364)
		(width 0.14732)
		(layer "In15.Cu")
		(net "P5E_CPU1_PE2_TX_DN<6>")
	)
	(segment
		(start 151.499316 -253.33071)
		(end 151.499316 -253.330964)
		(width 0.14732)
		(layer "In15.Cu")
		(net "P5E_CPU1_PE2_TX_DN<6>")
	)
	(segment
		(start 127.813054 -220.814646)
		(end 127.804164 -220.809566)
		(width 0.0889)
		(layer "In15.Cu")
		(net "P5E_CPU1_PE2_TX_DN<6>")
	)
	(segment
		(start 148.293074 -399.703036)
		(end 148.293074 -400.563588)
		(width 0.14732)
		(layer "In15.Cu")
		(net "P5E_CPU1_PE2_TX_DN<6>")
	)
	(segment
		(start 140.76045 -214.652606)
		(end 146.719036 -222.533972)
		(width 0.14732)
		(layer "In15.Cu")
		(net "P5E_CPU1_PE2_TX_DN<6>")
	)
	(segment
		(start 126.207012 -223.575626)
		(end 126.050548 -223.846644)
		(width 0.0889)
		(layer "In15.Cu")
		(net "P5E_CPU1_PE2_TX_DN<6>")
	)
	(segment
		(start 128.743964 -216.574878)
		(end 128.752854 -216.569798)
		(width 0.0889)
		(layer "In15.Cu")
		(net "P5E_CPU1_PE2_TX_DN<6>")
	)
	(segment
		(start 147.26666 -309.074312)
		(end 150.696168 -323.707506)
		(width 0.14732)
		(layer "In15.Cu")
		(net "P5E_CPU1_PE2_TX_DN<6>")
	)
	(segment
		(start 130.623056 -214.946992)
		(end 130.631946 -214.941912)
		(width 0.0889)
		(layer "In15.Cu")
		(net "P5E_CPU1_PE2_TX_DN<6>")
	)
	(segment
		(start 128.744726 -217.554556)
		(end 128.743964 -217.554048)
		(width 0.0889)
		(layer "In15.Cu")
		(net "P5E_CPU1_PE2_TX_DN<6>")
	)
	(segment
		(start 128.27381 -219.01658)
		(end 128.2827 -219.0115)
		(width 0.0889)
		(layer "In15.Cu")
		(net "P5E_CPU1_PE2_TX_DN<6>")
	)
	(segment
		(start 127.991616 -219.506038)
		(end 127.991616 -219.490544)
		(width 0.0889)
		(layer "In15.Cu")
		(net "P5E_CPU1_PE2_TX_DN<6>")
	)
	(segment
		(start 126.050548 -223.846644)
		(end 126.07163 -223.924622)
		(width 0.0889)
		(layer "In15.Cu")
		(net "P5E_CPU1_PE2_TX_DN<6>")
	)
	(segment
		(start 128.752854 -217.559128)
		(end 128.744726 -217.554556)
		(width 0.0889)
		(layer "In15.Cu")
		(net "P5E_CPU1_PE2_TX_DN<6>")
	)
	(segment
		(start 129.21361 -215.761062)
		(end 129.2225 -215.755982)
		(width 0.0889)
		(layer "In15.Cu")
		(net "P5E_CPU1_PE2_TX_DN<6>")
	)
	(segment
		(start 127.798068 -219.833952)
		(end 127.804164 -219.830396)
		(width 0.0889)
		(layer "In15.Cu")
		(net "P5E_CPU1_PE2_TX_DN<6>")
	)
	(segment
		(start 126.581662 -223.575626)
		(end 126.581662 -223.568006)
		(width 0.0889)
		(layer "In15.Cu")
		(net "P5E_CPU1_PE2_TX_DN<6>")
	)
	(segment
		(start 135.778748 -212.589364)
		(end 140.76045 -214.652606)
		(width 0.14732)
		(layer "In15.Cu")
		(net "P5E_CPU1_PE2_TX_DN<6>")
	)
	(segment
		(start 127.804164 -219.830396)
		(end 127.805688 -219.829634)
		(width 0.0889)
		(layer "In15.Cu")
		(net "P5E_CPU1_PE2_TX_DN<6>")
	)
	(segment
		(start 128.731772 -216.58199)
		(end 128.743964 -216.574878)
		(width 0.0889)
		(layer "In15.Cu")
		(net "P5E_CPU1_PE2_TX_DN<6>")
	)
	(segment
		(start 127.798068 -221.461838)
		(end 127.804164 -221.458282)
		(width 0.0889)
		(layer "In15.Cu")
		(net "P5E_CPU1_PE2_TX_DN<6>")
	)
	(segment
		(start 126.395226 -223.899476)
		(end 126.4031 -223.894904)
		(width 0.0889)
		(layer "In15.Cu")
		(net "P5E_CPU1_PE2_TX_DN<6>")
	)
	(segment
		(start 131.238752 -213.24697)
		(end 131.238752 -212.924644)
		(width 0.14732)
		(layer "In15.Cu")
		(net "P5E_CPU1_PE2_TX_DN<6>")
	)
	(segment
		(start 129.401062 -215.436704)
		(end 129.401062 -215.414606)
		(width 0.0889)
		(layer "In15.Cu")
		(net "P5E_CPU1_PE2_TX_DN<6>")
	)
	(segment
		(start 151.498554 -253.360682)
		(end 147.26666 -309.074312)
		(width 0.14732)
		(layer "In15.Cu")
		(net "P5E_CPU1_PE2_TX_DN<6>")
	)
	(segment
		(start 151.499316 -253.330964)
		(end 151.499824 -253.34595)
		(width 0.14732)
		(layer "In15.Cu")
		(net "P5E_CPU1_PE2_TX_DN<6>")
	)
	(segment
		(start 131.280916 -213.311232)
		(end 131.238752 -213.269068)
		(width 0.0889)
		(layer "In15.Cu")
		(net "P5E_CPU1_PE2_TX_DN<6>")
	)
	(segment
		(start 130.810508 -214.622634)
		(end 130.810508 -214.425784)
		(width 0.0889)
		(layer "In15.Cu")
		(net "P5E_CPU1_PE2_TX_DN<6>")
	)
	(segment
		(start 128.461262 -217.071956)
		(end 128.461262 -217.064336)
		(width 0.0889)
		(layer "In15.Cu")
		(net "P5E_CPU1_PE2_TX_DN<6>")
	)
	(segment
		(start 128.743964 -218.202764)
		(end 128.752854 -218.197684)
		(width 0.0889)
		(layer "In15.Cu")
		(net "P5E_CPU1_PE2_TX_DN<6>")
	)
	(segment
		(start 131.238752 -213.269068)
		(end 131.238752 -213.24697)
		(width 0.0889)
		(layer "In15.Cu")
		(net "P5E_CPU1_PE2_TX_DN<6>")
	)
	(segment
		(start 127.804164 -221.458282)
		(end 127.813054 -221.453202)
		(width 0.0889)
		(layer "In15.Cu")
		(net "P5E_CPU1_PE2_TX_DN<6>")
	)
	(segment
		(start 127.33401 -222.272098)
		(end 127.3429 -222.267018)
		(width 0.0889)
		(layer "In15.Cu")
		(net "P5E_CPU1_PE2_TX_DN<6>")
	)
	(segment
		(start 146.719036 -222.533972)
		(end 147.59305 -225.532188)
		(width 0.14732)
		(layer "In15.Cu")
		(net "P5E_CPU1_PE2_TX_DN<6>")
	)
	(segment
		(start 151.498808 -253.360682)
		(end 151.498554 -253.360682)
		(width 0.14732)
		(layer "In15.Cu")
		(net "P5E_CPU1_PE2_TX_DN<6>")
	)
	(segment
		(start 127.805688 -219.829634)
		(end 127.813054 -219.825316)
		(width 0.0889)
		(layer "In15.Cu")
		(net "P5E_CPU1_PE2_TX_DN<6>")
	)
	(segment
		(start 128.737868 -218.20632)
		(end 128.743964 -218.202764)
		(width 0.0889)
		(layer "In15.Cu")
		(net "P5E_CPU1_PE2_TX_DN<6>")
	)
	(segment
		(start 127.051816 -222.761556)
		(end 127.051816 -222.746062)
		(width 0.0889)
		(layer "In15.Cu")
		(net "P5E_CPU1_PE2_TX_DN<6>")
	)
	(segment
		(start 147.59305 -225.532188)
		(end 151.350218 -248.893584)
		(width 0.14732)
		(layer "In15.Cu")
		(net "P5E_CPU1_PE2_TX_DN<6>")
	)
	(segment
		(start 127.521462 -220.334078)
		(end 127.521462 -220.319854)
		(width 0.0889)
		(layer "In15.Cu")
		(net "P5E_CPU1_PE2_TX_DN<6>")
	)
	(segment
		(start 131.280916 -213.8934)
		(end 131.280916 -213.311232)
		(width 0.0889)
		(layer "In15.Cu")
		(net "P5E_CPU1_PE2_TX_DN<6>")
	)
	(segment
		(start 151.350218 -248.893584)
		(end 151.499316 -253.33071)
		(width 0.14732)
		(layer "In15.Cu")
		(net "P5E_CPU1_PE2_TX_DN<6>")
	)
	(segment
		(start 150.696168 -323.707506)
		(end 157.31617 -331.439266)
		(width 0.14732)
		(layer "In15.Cu")
		(net "P5E_CPU1_PE2_TX_DN<6>")
	)
	(segment
		(start 130.233928 -214.938356)
		(end 130.24866 -214.946992)
		(width 0.0889)
		(layer "In15.Cu")
		(net "P5E_CPU1_PE2_TX_DN<6>")
	)
	(segment
		(start 126.864364 -223.085914)
		(end 126.873254 -223.080834)
		(width 0.0889)
		(layer "In15.Cu")
		(net "P5E_CPU1_PE2_TX_DN<6>")
	)
	(segment
		(start 158.037784 -363.906308)
		(end 148.293074 -399.703036)
		(width 0.14732)
		(layer "In15.Cu")
		(net "P5E_CPU1_PE2_TX_DN<6>")
	)
	(segment
		(start 151.499824 -253.34595)
		(end 151.498808 -253.360682)
		(width 0.14732)
		(layer "In15.Cu")
		(net "P5E_CPU1_PE2_TX_DN<6>")
	)
	(arc
		(start 128.752854 -218.197684)
		(mid 128.931451 -217.878406)
		(end 128.752854 -217.559128)
		(width 0.0889)
		(layer "In15.Cu")
		(net "P5E_CPU1_PE2_TX_DN<6>")
	)
	(arc
		(start 127.521462 -221.94774)
		(mid 127.595453 -221.668174)
		(end 127.798068 -221.461838)
		(width 0.0889)
		(layer "In15.Cu")
		(net "P5E_CPU1_PE2_TX_DN<6>")
	)
	(arc
		(start 126.581662 -223.568006)
		(mid 126.659291 -223.289593)
		(end 126.864364 -223.085914)
		(width 0.0889)
		(layer "In15.Cu")
		(net "P5E_CPU1_PE2_TX_DN<6>")
	)
	(arc
		(start 131.096512 -214.093298)
		(mid 131.205908 -214.009201)
		(end 131.280916 -213.8934)
		(width 0.0889)
		(layer "In15.Cu")
		(net "P5E_CPU1_PE2_TX_DN<6>")
	)
	(arc
		(start 128.461262 -217.064336)
		(mid 128.533497 -216.787812)
		(end 128.731772 -216.58199)
		(width 0.0889)
		(layer "In15.Cu")
		(net "P5E_CPU1_PE2_TX_DN<6>")
	)
	(arc
		(start 126.07163 -223.924622)
		(mid 126.235726 -223.948969)
		(end 126.39421 -223.899984)
		(width 0.0889)
		(layer "In15.Cu")
		(net "P5E_CPU1_PE2_TX_DN<6>")
	)
	(arc
		(start 127.804164 -220.809566)
		(mid 127.600683 -220.608762)
		(end 127.521462 -220.334078)
		(width 0.0889)
		(layer "In15.Cu")
		(net "P5E_CPU1_PE2_TX_DN<6>")
	)
	(arc
		(start 127.813054 -219.825316)
		(mid 127.943968 -219.688956)
		(end 127.991616 -219.506038)
		(width 0.0889)
		(layer "In15.Cu")
		(net "P5E_CPU1_PE2_TX_DN<6>")
	)
	(arc
		(start 127.521462 -220.319854)
		(mid 127.595453 -220.040288)
		(end 127.798068 -219.833952)
		(width 0.0889)
		(layer "In15.Cu")
		(net "P5E_CPU1_PE2_TX_DN<6>")
	)
	(arc
		(start 127.051816 -222.746062)
		(mid 127.131186 -222.472328)
		(end 127.33401 -222.272098)
		(width 0.0889)
		(layer "In15.Cu")
		(net "P5E_CPU1_PE2_TX_DN<6>")
	)
	(arc
		(start 128.752854 -216.569798)
		(mid 128.883768 -216.433438)
		(end 128.931416 -216.25052)
		(width 0.0889)
		(layer "In15.Cu")
		(net "P5E_CPU1_PE2_TX_DN<6>")
	)
	(arc
		(start 128.461262 -218.692222)
		(mid 128.535253 -218.412656)
		(end 128.737868 -218.20632)
		(width 0.0889)
		(layer "In15.Cu")
		(net "P5E_CPU1_PE2_TX_DN<6>")
	)
	(arc
		(start 130.24866 -214.946992)
		(mid 130.435858 -214.997135)
		(end 130.623056 -214.946992)
		(width 0.0889)
		(layer "In15.Cu")
		(net "P5E_CPU1_PE2_TX_DN<6>")
	)
	(arc
		(start 127.3429 -222.267018)
		(mid 127.473814 -222.130658)
		(end 127.521462 -221.94774)
		(width 0.0889)
		(layer "In15.Cu")
		(net "P5E_CPU1_PE2_TX_DN<6>")
	)
	(arc
		(start 130.631946 -214.941912)
		(mid 130.76286 -214.805552)
		(end 130.810508 -214.622634)
		(width 0.0889)
		(layer "In15.Cu")
		(net "P5E_CPU1_PE2_TX_DN<6>")
	)
	(arc
		(start 128.2827 -219.0115)
		(mid 128.413614 -218.87514)
		(end 128.461262 -218.692222)
		(width 0.0889)
		(layer "In15.Cu")
		(net "P5E_CPU1_PE2_TX_DN<6>")
	)
	(arc
		(start 127.813054 -221.453202)
		(mid 127.991651 -221.133924)
		(end 127.813054 -220.814646)
		(width 0.0889)
		(layer "In15.Cu")
		(net "P5E_CPU1_PE2_TX_DN<6>")
	)
	(arc
		(start 129.2225 -215.755982)
		(mid 129.353414 -215.619622)
		(end 129.401062 -215.436704)
		(width 0.0889)
		(layer "In15.Cu")
		(net "P5E_CPU1_PE2_TX_DN<6>")
	)
	(arc
		(start 130.810508 -214.425784)
		(mid 130.921948 -214.232389)
		(end 131.096512 -214.093298)
		(width 0.0889)
		(layer "In15.Cu")
		(net "P5E_CPU1_PE2_TX_DN<6>")
	)
	(arc
		(start 126.873254 -223.080834)
		(mid 127.004168 -222.944474)
		(end 127.051816 -222.761556)
		(width 0.0889)
		(layer "In15.Cu")
		(net "P5E_CPU1_PE2_TX_DN<6>")
	)
	(arc
		(start 126.4031 -223.894904)
		(mid 126.534014 -223.758544)
		(end 126.581662 -223.575626)
		(width 0.0889)
		(layer "In15.Cu")
		(net "P5E_CPU1_PE2_TX_DN<6>")
	)
	(arc
		(start 129.401062 -215.414606)
		(mid 129.481973 -215.144478)
		(end 129.683256 -214.946992)
		(width 0.0889)
		(layer "In15.Cu")
		(net "P5E_CPU1_PE2_TX_DN<6>")
	)
	(arc
		(start 127.991616 -219.490544)
		(mid 128.070986 -219.21681)
		(end 128.27381 -219.01658)
		(width 0.0889)
		(layer "In15.Cu")
		(net "P5E_CPU1_PE2_TX_DN<6>")
	)
	(arc
		(start 128.743964 -217.554048)
		(mid 128.538892 -217.350369)
		(end 128.461262 -217.071956)
		(width 0.0889)
		(layer "In15.Cu")
		(net "P5E_CPU1_PE2_TX_DN<6>")
	)
	(arc
		(start 129.683256 -214.946992)
		(mid 129.957485 -214.871067)
		(end 130.233928 -214.938356)
		(width 0.0889)
		(layer "In15.Cu")
		(net "P5E_CPU1_PE2_TX_DN<6>")
	)
	(arc
		(start 128.931416 -216.235026)
		(mid 129.010786 -215.961292)
		(end 129.21361 -215.761062)
		(width 0.0889)
		(layer "In15.Cu")
		(net "P5E_CPU1_PE2_TX_DN<6>")
	)
	(segment
		(start 151.351996 -401.779994)
		(end 151.676354 -402.104352)
		(width 0.13208)
		(layer "F.Cu")
		(net "P5E_CPU1_PE2_TX_DN<5>")
	)
	(segment
		(start 124.797566 -224.925128)
		(end 124.797566 -224.389442)
		(width 0.13208)
		(layer "F.Cu")
		(net "P5E_CPU1_PE2_TX_DN<5>")
	)
	(segment
		(start 151.351996 -401.157186)
		(end 151.351996 -401.779994)
		(width 0.13208)
		(layer "F.Cu")
		(net "P5E_CPU1_PE2_TX_DN<5>")
	)
	(segment
		(start 151.650954 -400.858228)
		(end 151.351996 -401.157186)
		(width 0.13208)
		(layer "F.Cu")
		(net "P5E_CPU1_PE2_TX_DN<5>")
	)
	(segment
		(start 124.797312 -224.925382)
		(end 124.797566 -224.925128)
		(width 0.13208)
		(layer "F.Cu")
		(net "P5E_CPU1_PE2_TX_DN<5>")
	)
	(segment
		(start 148.2217 -308.954932)
		(end 151.559768 -323.233034)
		(width 0.14732)
		(layer "In15.Cu")
		(net "P5E_CPU1_PE2_TX_DN<5>")
	)
	(segment
		(start 152.273762 -248.663714)
		(end 152.43302 -253.397258)
		(width 0.14732)
		(layer "In15.Cu")
		(net "P5E_CPU1_PE2_TX_DN<5>")
	)
	(segment
		(start 127.813054 -217.559128)
		(end 127.804164 -217.554048)
		(width 0.0889)
		(layer "In15.Cu")
		(net "P5E_CPU1_PE2_TX_DN<5>")
	)
	(segment
		(start 135.965946 -211.649564)
		(end 141.640052 -213.999572)
		(width 0.14732)
		(layer "In15.Cu")
		(net "P5E_CPU1_PE2_TX_DN<5>")
	)
	(segment
		(start 127.805688 -216.574116)
		(end 127.813054 -216.569798)
		(width 0.0889)
		(layer "In15.Cu")
		(net "P5E_CPU1_PE2_TX_DN<5>")
	)
	(segment
		(start 151.356314 -400.563588)
		(end 151.650954 -400.858228)
		(width 0.14732)
		(layer "In15.Cu")
		(net "P5E_CPU1_PE2_TX_DN<5>")
	)
	(segment
		(start 151.559768 -323.233034)
		(end 158.29661 -331.147166)
		(width 0.14732)
		(layer "In15.Cu")
		(net "P5E_CPU1_PE2_TX_DN<5>")
	)
	(segment
		(start 125.172216 -224.389442)
		(end 125.172216 -224.379536)
		(width 0.0889)
		(layer "In15.Cu")
		(net "P5E_CPU1_PE2_TX_DN<5>")
	)
	(segment
		(start 152.43302 -253.397512)
		(end 152.433528 -253.412498)
		(width 0.14732)
		(layer "In15.Cu")
		(net "P5E_CPU1_PE2_TX_DN<5>")
	)
	(segment
		(start 160.915858 -345.99753)
		(end 160.259522 -349.72244)
		(width 0.14732)
		(layer "In15.Cu")
		(net "P5E_CPU1_PE2_TX_DN<5>")
	)
	(segment
		(start 152.433528 -253.412498)
		(end 152.432512 -253.42723)
		(width 0.14732)
		(layer "In15.Cu")
		(net "P5E_CPU1_PE2_TX_DN<5>")
	)
	(segment
		(start 125.924564 -223.085914)
		(end 125.933454 -223.080834)
		(width 0.0889)
		(layer "In15.Cu")
		(net "P5E_CPU1_PE2_TX_DN<5>")
	)
	(segment
		(start 124.797566 -224.389442)
		(end 124.95403 -224.66046)
		(width 0.0889)
		(layer "In15.Cu")
		(net "P5E_CPU1_PE2_TX_DN<5>")
	)
	(segment
		(start 124.95403 -224.66046)
		(end 125.032262 -224.681288)
		(width 0.0889)
		(layer "In15.Cu")
		(net "P5E_CPU1_PE2_TX_DN<5>")
	)
	(segment
		(start 131.281424 -211.649564)
		(end 135.965946 -211.649564)
		(width 0.14732)
		(layer "In15.Cu")
		(net "P5E_CPU1_PE2_TX_DN<5>")
	)
	(segment
		(start 158.29661 -331.147166)
		(end 160.915858 -345.99753)
		(width 0.14732)
		(layer "In15.Cu")
		(net "P5E_CPU1_PE2_TX_DN<5>")
	)
	(segment
		(start 126.852172 -219.837508)
		(end 126.864364 -219.830396)
		(width 0.0889)
		(layer "In15.Cu")
		(net "P5E_CPU1_PE2_TX_DN<5>")
	)
	(segment
		(start 129.40157 -213.892892)
		(end 129.40157 -213.270338)
		(width 0.0889)
		(layer "In15.Cu")
		(net "P5E_CPU1_PE2_TX_DN<5>")
	)
	(segment
		(start 128.743456 -214.946992)
		(end 128.752346 -214.941912)
		(width 0.0889)
		(layer "In15.Cu")
		(net "P5E_CPU1_PE2_TX_DN<5>")
	)
	(segment
		(start 127.80137 -218.204288)
		(end 127.804164 -218.202764)
		(width 0.0889)
		(layer "In15.Cu")
		(net "P5E_CPU1_PE2_TX_DN<5>")
	)
	(segment
		(start 127.798068 -218.20632)
		(end 127.80137 -218.204288)
		(width 0.0889)
		(layer "In15.Cu")
		(net "P5E_CPU1_PE2_TX_DN<5>")
	)
	(segment
		(start 148.52015 -225.345244)
		(end 152.273762 -248.663714)
		(width 0.14732)
		(layer "In15.Cu")
		(net "P5E_CPU1_PE2_TX_DN<5>")
	)
	(segment
		(start 152.43302 -253.397258)
		(end 152.43302 -253.397512)
		(width 0.14732)
		(layer "In15.Cu")
		(net "P5E_CPU1_PE2_TX_DN<5>")
	)
	(segment
		(start 159.013144 -363.973364)
		(end 151.356314 -399.664682)
		(width 0.14732)
		(layer "In15.Cu")
		(net "P5E_CPU1_PE2_TX_DN<5>")
	)
	(segment
		(start 129.35966 -213.228428)
		(end 129.35966 -213.20633)
		(width 0.0889)
		(layer "In15.Cu")
		(net "P5E_CPU1_PE2_TX_DN<5>")
	)
	(segment
		(start 126.112016 -222.761556)
		(end 126.112016 -222.746062)
		(width 0.0889)
		(layer "In15.Cu")
		(net "P5E_CPU1_PE2_TX_DN<5>")
	)
	(segment
		(start 127.521462 -217.07856)
		(end 127.521462 -217.064336)
		(width 0.0889)
		(layer "In15.Cu")
		(net "P5E_CPU1_PE2_TX_DN<5>")
	)
	(segment
		(start 126.39421 -222.272098)
		(end 126.4031 -222.267018)
		(width 0.0889)
		(layer "In15.Cu")
		(net "P5E_CPU1_PE2_TX_DN<5>")
	)
	(segment
		(start 129.35966 -213.20633)
		(end 129.35966 -212.705696)
		(width 0.14732)
		(layer "In15.Cu")
		(net "P5E_CPU1_PE2_TX_DN<5>")
	)
	(segment
		(start 126.873254 -220.814646)
		(end 126.865126 -220.810074)
		(width 0.0889)
		(layer "In15.Cu")
		(net "P5E_CPU1_PE2_TX_DN<5>")
	)
	(segment
		(start 152.432512 -253.42723)
		(end 152.432258 -253.42723)
		(width 0.14732)
		(layer "In15.Cu")
		(net "P5E_CPU1_PE2_TX_DN<5>")
	)
	(segment
		(start 128.930908 -214.622634)
		(end 128.930908 -214.425784)
		(width 0.0889)
		(layer "In15.Cu")
		(net "P5E_CPU1_PE2_TX_DN<5>")
	)
	(segment
		(start 129.80416 -212.261196)
		(end 131.281424 -211.649564)
		(width 0.14732)
		(layer "In15.Cu")
		(net "P5E_CPU1_PE2_TX_DN<5>")
	)
	(segment
		(start 127.804164 -218.202764)
		(end 127.805688 -218.202002)
		(width 0.0889)
		(layer "In15.Cu")
		(net "P5E_CPU1_PE2_TX_DN<5>")
	)
	(segment
		(start 126.864364 -219.830396)
		(end 126.873254 -219.825316)
		(width 0.0889)
		(layer "In15.Cu")
		(net "P5E_CPU1_PE2_TX_DN<5>")
	)
	(segment
		(start 126.858268 -221.461838)
		(end 126.864364 -221.458282)
		(width 0.0889)
		(layer "In15.Cu")
		(net "P5E_CPU1_PE2_TX_DN<5>")
	)
	(segment
		(start 125.641862 -223.584262)
		(end 125.641862 -223.561402)
		(width 0.0889)
		(layer "In15.Cu")
		(net "P5E_CPU1_PE2_TX_DN<5>")
	)
	(segment
		(start 126.864364 -221.458282)
		(end 126.873254 -221.453202)
		(width 0.0889)
		(layer "In15.Cu")
		(net "P5E_CPU1_PE2_TX_DN<5>")
	)
	(segment
		(start 127.798068 -216.578434)
		(end 127.804164 -216.574878)
		(width 0.0889)
		(layer "In15.Cu")
		(net "P5E_CPU1_PE2_TX_DN<5>")
	)
	(segment
		(start 127.051816 -219.506038)
		(end 127.051816 -219.490544)
		(width 0.0889)
		(layer "In15.Cu")
		(net "P5E_CPU1_PE2_TX_DN<5>")
	)
	(segment
		(start 128.27381 -215.761062)
		(end 128.2827 -215.755982)
		(width 0.0889)
		(layer "In15.Cu")
		(net "P5E_CPU1_PE2_TX_DN<5>")
	)
	(segment
		(start 127.991616 -216.25052)
		(end 127.991616 -216.235026)
		(width 0.0889)
		(layer "In15.Cu")
		(net "P5E_CPU1_PE2_TX_DN<5>")
	)
	(segment
		(start 152.432258 -253.42723)
		(end 148.2217 -308.954932)
		(width 0.14732)
		(layer "In15.Cu")
		(net "P5E_CPU1_PE2_TX_DN<5>")
	)
	(segment
		(start 129.40157 -213.270338)
		(end 129.35966 -213.228428)
		(width 0.0889)
		(layer "In15.Cu")
		(net "P5E_CPU1_PE2_TX_DN<5>")
	)
	(segment
		(start 126.581662 -220.327474)
		(end 126.581662 -220.319854)
		(width 0.0889)
		(layer "In15.Cu")
		(net "P5E_CPU1_PE2_TX_DN<5>")
	)
	(segment
		(start 129.401316 -213.8934)
		(end 129.40157 -213.892892)
		(width 0.0889)
		(layer "In15.Cu")
		(net "P5E_CPU1_PE2_TX_DN<5>")
	)
	(segment
		(start 127.33401 -219.01658)
		(end 127.3429 -219.0115)
		(width 0.0889)
		(layer "In15.Cu")
		(net "P5E_CPU1_PE2_TX_DN<5>")
	)
	(segment
		(start 128.461262 -215.436704)
		(end 128.461262 -215.414606)
		(width 0.0889)
		(layer "In15.Cu")
		(net "P5E_CPU1_PE2_TX_DN<5>")
	)
	(segment
		(start 141.640052 -213.999572)
		(end 147.46732 -221.697296)
		(width 0.14732)
		(layer "In15.Cu")
		(net "P5E_CPU1_PE2_TX_DN<5>")
	)
	(segment
		(start 129.35966 -212.705696)
		(end 129.80416 -212.261196)
		(width 0.14732)
		(layer "In15.Cu")
		(net "P5E_CPU1_PE2_TX_DN<5>")
	)
	(segment
		(start 151.356314 -399.664682)
		(end 151.356314 -400.563588)
		(width 0.14732)
		(layer "In15.Cu")
		(net "P5E_CPU1_PE2_TX_DN<5>")
	)
	(segment
		(start 147.46732 -221.697296)
		(end 148.52015 -225.345244)
		(width 0.14732)
		(layer "In15.Cu")
		(net "P5E_CPU1_PE2_TX_DN<5>")
	)
	(segment
		(start 127.805688 -218.202002)
		(end 127.813054 -218.197684)
		(width 0.0889)
		(layer "In15.Cu")
		(net "P5E_CPU1_PE2_TX_DN<5>")
	)
	(segment
		(start 126.865126 -220.810074)
		(end 126.864364 -220.809566)
		(width 0.0889)
		(layer "In15.Cu")
		(net "P5E_CPU1_PE2_TX_DN<5>")
	)
	(segment
		(start 127.804164 -216.574878)
		(end 127.805688 -216.574116)
		(width 0.0889)
		(layer "In15.Cu")
		(net "P5E_CPU1_PE2_TX_DN<5>")
	)
	(segment
		(start 160.259522 -349.72244)
		(end 159.013144 -363.973364)
		(width 0.14732)
		(layer "In15.Cu")
		(net "P5E_CPU1_PE2_TX_DN<5>")
	)
	(arc
		(start 126.581662 -220.319854)
		(mid 126.653897 -220.04333)
		(end 126.852172 -219.837508)
		(width 0.0889)
		(layer "In15.Cu")
		(net "P5E_CPU1_PE2_TX_DN<5>")
	)
	(arc
		(start 125.172216 -224.379536)
		(mid 125.250327 -224.102587)
		(end 125.454664 -223.899984)
		(width 0.0889)
		(layer "In15.Cu")
		(net "P5E_CPU1_PE2_TX_DN<5>")
	)
	(arc
		(start 126.4031 -222.267018)
		(mid 126.534014 -222.130658)
		(end 126.581662 -221.94774)
		(width 0.0889)
		(layer "In15.Cu")
		(net "P5E_CPU1_PE2_TX_DN<5>")
	)
	(arc
		(start 126.581662 -221.94774)
		(mid 126.655653 -221.668174)
		(end 126.858268 -221.461838)
		(width 0.0889)
		(layer "In15.Cu")
		(net "P5E_CPU1_PE2_TX_DN<5>")
	)
	(arc
		(start 126.873254 -221.453202)
		(mid 127.051851 -221.133924)
		(end 126.873254 -220.814646)
		(width 0.0889)
		(layer "In15.Cu")
		(net "P5E_CPU1_PE2_TX_DN<5>")
	)
	(arc
		(start 127.3429 -219.0115)
		(mid 127.473814 -218.87514)
		(end 127.521462 -218.692222)
		(width 0.0889)
		(layer "In15.Cu")
		(net "P5E_CPU1_PE2_TX_DN<5>")
	)
	(arc
		(start 127.991616 -216.235026)
		(mid 128.070986 -215.961292)
		(end 128.27381 -215.761062)
		(width 0.0889)
		(layer "In15.Cu")
		(net "P5E_CPU1_PE2_TX_DN<5>")
	)
	(arc
		(start 126.873254 -219.825316)
		(mid 127.004168 -219.688956)
		(end 127.051816 -219.506038)
		(width 0.0889)
		(layer "In15.Cu")
		(net "P5E_CPU1_PE2_TX_DN<5>")
	)
	(arc
		(start 128.2827 -215.755982)
		(mid 128.413614 -215.619622)
		(end 128.461262 -215.436704)
		(width 0.0889)
		(layer "In15.Cu")
		(net "P5E_CPU1_PE2_TX_DN<5>")
	)
	(arc
		(start 127.521462 -218.692222)
		(mid 127.595453 -218.412656)
		(end 127.798068 -218.20632)
		(width 0.0889)
		(layer "In15.Cu")
		(net "P5E_CPU1_PE2_TX_DN<5>")
	)
	(arc
		(start 128.461262 -215.414606)
		(mid 128.542173 -215.144478)
		(end 128.743456 -214.946992)
		(width 0.0889)
		(layer "In15.Cu")
		(net "P5E_CPU1_PE2_TX_DN<5>")
	)
	(arc
		(start 127.521462 -217.064336)
		(mid 127.595453 -216.78477)
		(end 127.798068 -216.578434)
		(width 0.0889)
		(layer "In15.Cu")
		(net "P5E_CPU1_PE2_TX_DN<5>")
	)
	(arc
		(start 125.454664 -223.899984)
		(mid 125.589597 -223.76663)
		(end 125.641862 -223.584262)
		(width 0.0889)
		(layer "In15.Cu")
		(net "P5E_CPU1_PE2_TX_DN<5>")
	)
	(arc
		(start 127.813054 -218.197684)
		(mid 127.991651 -217.878406)
		(end 127.813054 -217.559128)
		(width 0.0889)
		(layer "In15.Cu")
		(net "P5E_CPU1_PE2_TX_DN<5>")
	)
	(arc
		(start 125.641862 -223.561402)
		(mid 125.721081 -223.286717)
		(end 125.924564 -223.085914)
		(width 0.0889)
		(layer "In15.Cu")
		(net "P5E_CPU1_PE2_TX_DN<5>")
	)
	(arc
		(start 125.032262 -224.681288)
		(mid 125.135407 -224.551263)
		(end 125.172216 -224.389442)
		(width 0.0889)
		(layer "In15.Cu")
		(net "P5E_CPU1_PE2_TX_DN<5>")
	)
	(arc
		(start 126.864364 -220.809566)
		(mid 126.659292 -220.605887)
		(end 126.581662 -220.327474)
		(width 0.0889)
		(layer "In15.Cu")
		(net "P5E_CPU1_PE2_TX_DN<5>")
	)
	(arc
		(start 127.813054 -216.569798)
		(mid 127.943968 -216.433438)
		(end 127.991616 -216.25052)
		(width 0.0889)
		(layer "In15.Cu")
		(net "P5E_CPU1_PE2_TX_DN<5>")
	)
	(arc
		(start 125.933454 -223.080834)
		(mid 126.064368 -222.944474)
		(end 126.112016 -222.761556)
		(width 0.0889)
		(layer "In15.Cu")
		(net "P5E_CPU1_PE2_TX_DN<5>")
	)
	(arc
		(start 126.112016 -222.746062)
		(mid 126.191386 -222.472328)
		(end 126.39421 -222.272098)
		(width 0.0889)
		(layer "In15.Cu")
		(net "P5E_CPU1_PE2_TX_DN<5>")
	)
	(arc
		(start 128.752346 -214.941912)
		(mid 128.88326 -214.805552)
		(end 128.930908 -214.622634)
		(width 0.0889)
		(layer "In15.Cu")
		(net "P5E_CPU1_PE2_TX_DN<5>")
	)
	(arc
		(start 129.216912 -214.093298)
		(mid 129.326308 -214.009201)
		(end 129.401316 -213.8934)
		(width 0.0889)
		(layer "In15.Cu")
		(net "P5E_CPU1_PE2_TX_DN<5>")
	)
	(arc
		(start 127.804164 -217.554048)
		(mid 127.600683 -217.353244)
		(end 127.521462 -217.07856)
		(width 0.0889)
		(layer "In15.Cu")
		(net "P5E_CPU1_PE2_TX_DN<5>")
	)
	(arc
		(start 127.051816 -219.490544)
		(mid 127.131186 -219.21681)
		(end 127.33401 -219.01658)
		(width 0.0889)
		(layer "In15.Cu")
		(net "P5E_CPU1_PE2_TX_DN<5>")
	)
	(arc
		(start 128.930908 -214.425784)
		(mid 129.042348 -214.232389)
		(end 129.216912 -214.093298)
		(width 0.0889)
		(layer "In15.Cu")
		(net "P5E_CPU1_PE2_TX_DN<5>")
	)
	(segment
		(start 154.415236 -401.157186)
		(end 154.415236 -401.779994)
		(width 0.13208)
		(layer "F.Cu")
		(net "P5E_CPU1_PE2_TX_DN<4>")
	)
	(segment
		(start 124.327666 -224.111566)
		(end 124.327412 -224.111312)
		(width 0.13208)
		(layer "F.Cu")
		(net "P5E_CPU1_PE2_TX_DN<4>")
	)
	(segment
		(start 154.415236 -401.779994)
		(end 154.739594 -402.104352)
		(width 0.13208)
		(layer "F.Cu")
		(net "P5E_CPU1_PE2_TX_DN<4>")
	)
	(segment
		(start 154.714194 -400.858228)
		(end 154.415236 -401.157186)
		(width 0.13208)
		(layer "F.Cu")
		(net "P5E_CPU1_PE2_TX_DN<4>")
	)
	(segment
		(start 124.327412 -224.111312)
		(end 124.327412 -223.575626)
		(width 0.13208)
		(layer "F.Cu")
		(net "P5E_CPU1_PE2_TX_DN<4>")
	)
	(segment
		(start 153.189686 -248.275602)
		(end 153.191972 -248.29135)
		(width 0.14732)
		(layer "In15.Cu")
		(net "P5E_CPU1_PE2_TX_DN<4>")
	)
	(segment
		(start 135.969248 -210.630516)
		(end 137.564876 -211.291424)
		(width 0.14732)
		(layer "In15.Cu")
		(net "P5E_CPU1_PE2_TX_DN<4>")
	)
	(segment
		(start 137.564876 -211.291424)
		(end 137.56513 -211.291424)
		(width 0.14732)
		(layer "In15.Cu")
		(net "P5E_CPU1_PE2_TX_DN<4>")
	)
	(segment
		(start 127.803656 -214.946992)
		(end 127.812546 -214.941912)
		(width 0.0889)
		(layer "In15.Cu")
		(net "P5E_CPU1_PE2_TX_DN<4>")
	)
	(segment
		(start 153.189432 -248.275602)
		(end 153.189686 -248.275602)
		(width 0.14732)
		(layer "In15.Cu")
		(net "P5E_CPU1_PE2_TX_DN<4>")
	)
	(segment
		(start 125.172216 -222.761556)
		(end 125.172216 -222.746062)
		(width 0.0889)
		(layer "In15.Cu")
		(net "P5E_CPU1_PE2_TX_DN<4>")
	)
	(segment
		(start 127.991108 -214.622634)
		(end 127.991108 -214.461344)
		(width 0.0889)
		(layer "In15.Cu")
		(net "P5E_CPU1_PE2_TX_DN<4>")
	)
	(segment
		(start 127.521462 -215.436704)
		(end 127.521462 -215.414606)
		(width 0.0889)
		(layer "In15.Cu")
		(net "P5E_CPU1_PE2_TX_DN<4>")
	)
	(segment
		(start 126.873254 -217.559128)
		(end 126.865126 -217.554556)
		(width 0.0889)
		(layer "In15.Cu")
		(net "P5E_CPU1_PE2_TX_DN<4>")
	)
	(segment
		(start 124.984764 -223.085914)
		(end 124.993654 -223.080834)
		(width 0.0889)
		(layer "In15.Cu")
		(net "P5E_CPU1_PE2_TX_DN<4>")
	)
	(segment
		(start 126.581662 -217.071956)
		(end 126.581662 -217.064336)
		(width 0.0889)
		(layer "In15.Cu")
		(net "P5E_CPU1_PE2_TX_DN<4>")
	)
	(segment
		(start 127.521716 -213.929722)
		(end 127.52197 -213.929468)
		(width 0.0889)
		(layer "In15.Cu")
		(net "P5E_CPU1_PE2_TX_DN<4>")
	)
	(segment
		(start 125.933454 -220.814646)
		(end 125.924564 -220.809566)
		(width 0.0889)
		(layer "In15.Cu")
		(net "P5E_CPU1_PE2_TX_DN<4>")
	)
	(segment
		(start 125.918468 -221.461838)
		(end 125.924564 -221.458282)
		(width 0.0889)
		(layer "In15.Cu")
		(net "P5E_CPU1_PE2_TX_DN<4>")
	)
	(segment
		(start 125.924564 -221.458282)
		(end 125.933454 -221.453202)
		(width 0.0889)
		(layer "In15.Cu")
		(net "P5E_CPU1_PE2_TX_DN<4>")
	)
	(segment
		(start 153.191972 -248.29135)
		(end 153.364946 -253.441454)
		(width 0.14732)
		(layer "In15.Cu")
		(net "P5E_CPU1_PE2_TX_DN<4>")
	)
	(segment
		(start 125.924564 -219.830396)
		(end 125.926088 -219.829634)
		(width 0.0889)
		(layer "In15.Cu")
		(net "P5E_CPU1_PE2_TX_DN<4>")
	)
	(segment
		(start 127.52197 -213.242652)
		(end 127.479806 -213.200488)
		(width 0.0889)
		(layer "In15.Cu")
		(net "P5E_CPU1_PE2_TX_DN<4>")
	)
	(segment
		(start 148.411946 -221.366334)
		(end 149.90953 -226.545394)
		(width 0.14732)
		(layer "In15.Cu")
		(net "P5E_CPU1_PE2_TX_DN<4>")
	)
	(segment
		(start 160.02762 -363.494828)
		(end 154.419554 -399.866612)
		(width 0.14732)
		(layer "In15.Cu")
		(net "P5E_CPU1_PE2_TX_DN<4>")
	)
	(segment
		(start 127.479806 -213.17839)
		(end 127.479806 -212.901276)
		(width 0.14732)
		(layer "In15.Cu")
		(net "P5E_CPU1_PE2_TX_DN<4>")
	)
	(segment
		(start 124.51461 -223.899984)
		(end 124.515626 -223.899476)
		(width 0.0889)
		(layer "In15.Cu")
		(net "P5E_CPU1_PE2_TX_DN<4>")
	)
	(segment
		(start 124.515626 -223.899476)
		(end 124.5235 -223.894904)
		(width 0.0889)
		(layer "In15.Cu")
		(net "P5E_CPU1_PE2_TX_DN<4>")
	)
	(segment
		(start 126.865126 -217.554556)
		(end 126.864364 -217.554048)
		(width 0.0889)
		(layer "In15.Cu")
		(net "P5E_CPU1_PE2_TX_DN<4>")
	)
	(segment
		(start 124.170948 -223.846644)
		(end 124.19203 -223.924622)
		(width 0.0889)
		(layer "In15.Cu")
		(net "P5E_CPU1_PE2_TX_DN<4>")
	)
	(segment
		(start 125.926088 -219.829634)
		(end 125.933454 -219.825316)
		(width 0.0889)
		(layer "In15.Cu")
		(net "P5E_CPU1_PE2_TX_DN<4>")
	)
	(segment
		(start 125.641862 -220.334078)
		(end 125.641862 -220.319854)
		(width 0.0889)
		(layer "In15.Cu")
		(net "P5E_CPU1_PE2_TX_DN<4>")
	)
	(segment
		(start 126.858268 -218.20632)
		(end 126.864364 -218.202764)
		(width 0.0889)
		(layer "In15.Cu")
		(net "P5E_CPU1_PE2_TX_DN<4>")
	)
	(segment
		(start 153.364946 -253.441454)
		(end 149.17928 -308.833012)
		(width 0.14732)
		(layer "In15.Cu")
		(net "P5E_CPU1_PE2_TX_DN<4>")
	)
	(segment
		(start 127.479806 -212.901276)
		(end 128.690624 -211.690458)
		(width 0.14732)
		(layer "In15.Cu")
		(net "P5E_CPU1_PE2_TX_DN<4>")
	)
	(segment
		(start 154.419554 -400.563588)
		(end 154.714194 -400.858228)
		(width 0.14732)
		(layer "In15.Cu")
		(net "P5E_CPU1_PE2_TX_DN<4>")
	)
	(segment
		(start 124.327412 -223.575626)
		(end 124.170948 -223.846644)
		(width 0.0889)
		(layer "In15.Cu")
		(net "P5E_CPU1_PE2_TX_DN<4>")
	)
	(segment
		(start 161.905696 -345.997784)
		(end 161.214816 -349.919036)
		(width 0.14732)
		(layer "In15.Cu")
		(net "P5E_CPU1_PE2_TX_DN<4>")
	)
	(segment
		(start 142.26921 -213.239604)
		(end 145.347944 -217.312748)
		(width 0.14732)
		(layer "In15.Cu")
		(net "P5E_CPU1_PE2_TX_DN<4>")
	)
	(segment
		(start 127.479806 -213.200488)
		(end 127.479806 -213.17839)
		(width 0.0889)
		(layer "In15.Cu")
		(net "P5E_CPU1_PE2_TX_DN<4>")
	)
	(segment
		(start 152.441402 -322.798948)
		(end 159.223202 -330.785978)
		(width 0.14732)
		(layer "In15.Cu")
		(net "P5E_CPU1_PE2_TX_DN<4>")
	)
	(segment
		(start 149.90953 -226.545394)
		(end 153.189432 -248.275602)
		(width 0.14732)
		(layer "In15.Cu")
		(net "P5E_CPU1_PE2_TX_DN<4>")
	)
	(segment
		(start 137.56513 -211.291424)
		(end 142.26921 -213.239604)
		(width 0.14732)
		(layer "In15.Cu")
		(net "P5E_CPU1_PE2_TX_DN<4>")
	)
	(segment
		(start 126.852172 -216.58199)
		(end 126.864364 -216.574878)
		(width 0.0889)
		(layer "In15.Cu")
		(net "P5E_CPU1_PE2_TX_DN<4>")
	)
	(segment
		(start 154.419554 -399.866612)
		(end 154.419554 -400.563588)
		(width 0.14732)
		(layer "In15.Cu")
		(net "P5E_CPU1_PE2_TX_DN<4>")
	)
	(segment
		(start 127.33401 -215.761062)
		(end 127.3429 -215.755982)
		(width 0.0889)
		(layer "In15.Cu")
		(net "P5E_CPU1_PE2_TX_DN<4>")
	)
	(segment
		(start 125.918468 -219.833952)
		(end 125.924564 -219.830396)
		(width 0.0889)
		(layer "In15.Cu")
		(net "P5E_CPU1_PE2_TX_DN<4>")
	)
	(segment
		(start 126.112016 -219.506038)
		(end 126.112016 -219.490544)
		(width 0.0889)
		(layer "In15.Cu")
		(net "P5E_CPU1_PE2_TX_DN<4>")
	)
	(segment
		(start 127.521716 -213.930484)
		(end 127.521716 -213.929722)
		(width 0.0889)
		(layer "In15.Cu")
		(net "P5E_CPU1_PE2_TX_DN<4>")
	)
	(segment
		(start 131.249928 -210.630516)
		(end 135.969248 -210.630516)
		(width 0.14732)
		(layer "In15.Cu")
		(net "P5E_CPU1_PE2_TX_DN<4>")
	)
	(segment
		(start 125.45441 -222.272098)
		(end 125.4633 -222.267018)
		(width 0.0889)
		(layer "In15.Cu")
		(net "P5E_CPU1_PE2_TX_DN<4>")
	)
	(segment
		(start 127.051816 -216.25052)
		(end 127.051816 -216.235026)
		(width 0.0889)
		(layer "In15.Cu")
		(net "P5E_CPU1_PE2_TX_DN<4>")
	)
	(segment
		(start 127.52197 -213.929468)
		(end 127.52197 -213.242652)
		(width 0.0889)
		(layer "In15.Cu")
		(net "P5E_CPU1_PE2_TX_DN<4>")
	)
	(segment
		(start 126.39421 -219.01658)
		(end 126.4031 -219.0115)
		(width 0.0889)
		(layer "In15.Cu")
		(net "P5E_CPU1_PE2_TX_DN<4>")
	)
	(segment
		(start 149.17928 -308.833012)
		(end 152.441402 -322.798948)
		(width 0.14732)
		(layer "In15.Cu")
		(net "P5E_CPU1_PE2_TX_DN<4>")
	)
	(segment
		(start 124.702062 -223.575626)
		(end 124.702062 -223.568006)
		(width 0.0889)
		(layer "In15.Cu")
		(net "P5E_CPU1_PE2_TX_DN<4>")
	)
	(segment
		(start 126.864364 -218.202764)
		(end 126.873254 -218.197684)
		(width 0.0889)
		(layer "In15.Cu")
		(net "P5E_CPU1_PE2_TX_DN<4>")
	)
	(segment
		(start 161.214816 -349.919036)
		(end 160.02762 -363.494828)
		(width 0.14732)
		(layer "In15.Cu")
		(net "P5E_CPU1_PE2_TX_DN<4>")
	)
	(segment
		(start 126.864364 -216.574878)
		(end 126.873254 -216.569798)
		(width 0.0889)
		(layer "In15.Cu")
		(net "P5E_CPU1_PE2_TX_DN<4>")
	)
	(segment
		(start 145.347944 -217.312748)
		(end 148.411946 -221.366334)
		(width 0.14732)
		(layer "In15.Cu")
		(net "P5E_CPU1_PE2_TX_DN<4>")
	)
	(segment
		(start 128.690624 -211.690458)
		(end 131.249928 -210.630516)
		(width 0.14732)
		(layer "In15.Cu")
		(net "P5E_CPU1_PE2_TX_DN<4>")
	)
	(segment
		(start 159.223202 -330.785978)
		(end 161.905696 -345.997784)
		(width 0.14732)
		(layer "In15.Cu")
		(net "P5E_CPU1_PE2_TX_DN<4>")
	)
	(arc
		(start 124.702062 -223.568006)
		(mid 124.779691 -223.289593)
		(end 124.984764 -223.085914)
		(width 0.0889)
		(layer "In15.Cu")
		(net "P5E_CPU1_PE2_TX_DN<4>")
	)
	(arc
		(start 126.873254 -216.569798)
		(mid 127.004168 -216.433438)
		(end 127.051816 -216.25052)
		(width 0.0889)
		(layer "In15.Cu")
		(net "P5E_CPU1_PE2_TX_DN<4>")
	)
	(arc
		(start 127.990854 -214.637366)
		(mid 127.991051 -214.630001)
		(end 127.991108 -214.622634)
		(width 0.0889)
		(layer "In15.Cu")
		(net "P5E_CPU1_PE2_TX_DN<4>")
	)
	(arc
		(start 126.581662 -218.692222)
		(mid 126.655653 -218.412656)
		(end 126.858268 -218.20632)
		(width 0.0889)
		(layer "In15.Cu")
		(net "P5E_CPU1_PE2_TX_DN<4>")
	)
	(arc
		(start 127.806958 -214.261954)
		(mid 127.646886 -214.138774)
		(end 127.536956 -213.969346)
		(width 0.0889)
		(layer "In15.Cu")
		(net "P5E_CPU1_PE2_TX_DN<4>")
	)
	(arc
		(start 126.873254 -218.197684)
		(mid 127.051851 -217.878406)
		(end 126.873254 -217.559128)
		(width 0.0889)
		(layer "In15.Cu")
		(net "P5E_CPU1_PE2_TX_DN<4>")
	)
	(arc
		(start 125.933454 -221.453202)
		(mid 126.112051 -221.133924)
		(end 125.933454 -220.814646)
		(width 0.0889)
		(layer "In15.Cu")
		(net "P5E_CPU1_PE2_TX_DN<4>")
	)
	(arc
		(start 126.864364 -217.554048)
		(mid 126.659292 -217.350369)
		(end 126.581662 -217.071956)
		(width 0.0889)
		(layer "In15.Cu")
		(net "P5E_CPU1_PE2_TX_DN<4>")
	)
	(arc
		(start 127.051816 -216.235026)
		(mid 127.131186 -215.961292)
		(end 127.33401 -215.761062)
		(width 0.0889)
		(layer "In15.Cu")
		(net "P5E_CPU1_PE2_TX_DN<4>")
	)
	(arc
		(start 127.812546 -214.941912)
		(mid 127.9398 -214.811946)
		(end 127.990854 -214.637366)
		(width 0.0889)
		(layer "In15.Cu")
		(net "P5E_CPU1_PE2_TX_DN<4>")
	)
	(arc
		(start 127.521462 -215.414606)
		(mid 127.602373 -215.144478)
		(end 127.803656 -214.946992)
		(width 0.0889)
		(layer "In15.Cu")
		(net "P5E_CPU1_PE2_TX_DN<4>")
	)
	(arc
		(start 125.924564 -220.809566)
		(mid 125.721083 -220.608762)
		(end 125.641862 -220.334078)
		(width 0.0889)
		(layer "In15.Cu")
		(net "P5E_CPU1_PE2_TX_DN<4>")
	)
	(arc
		(start 125.933454 -219.825316)
		(mid 126.064368 -219.688956)
		(end 126.112016 -219.506038)
		(width 0.0889)
		(layer "In15.Cu")
		(net "P5E_CPU1_PE2_TX_DN<4>")
	)
	(arc
		(start 127.991108 -214.461344)
		(mid 127.916103 -214.345885)
		(end 127.806958 -214.261954)
		(width 0.0889)
		(layer "In15.Cu")
		(net "P5E_CPU1_PE2_TX_DN<4>")
	)
	(arc
		(start 124.993654 -223.080834)
		(mid 125.124568 -222.944474)
		(end 125.172216 -222.761556)
		(width 0.0889)
		(layer "In15.Cu")
		(net "P5E_CPU1_PE2_TX_DN<4>")
	)
	(arc
		(start 124.19203 -223.924622)
		(mid 124.356126 -223.948969)
		(end 124.51461 -223.899984)
		(width 0.0889)
		(layer "In15.Cu")
		(net "P5E_CPU1_PE2_TX_DN<4>")
	)
	(arc
		(start 124.5235 -223.894904)
		(mid 124.654414 -223.758544)
		(end 124.702062 -223.575626)
		(width 0.0889)
		(layer "In15.Cu")
		(net "P5E_CPU1_PE2_TX_DN<4>")
	)
	(arc
		(start 126.112016 -219.490544)
		(mid 126.191386 -219.21681)
		(end 126.39421 -219.01658)
		(width 0.0889)
		(layer "In15.Cu")
		(net "P5E_CPU1_PE2_TX_DN<4>")
	)
	(arc
		(start 127.536956 -213.969346)
		(mid 127.528993 -213.950049)
		(end 127.521716 -213.930484)
		(width 0.0889)
		(layer "In15.Cu")
		(net "P5E_CPU1_PE2_TX_DN<4>")
	)
	(arc
		(start 125.172216 -222.746062)
		(mid 125.251586 -222.472328)
		(end 125.45441 -222.272098)
		(width 0.0889)
		(layer "In15.Cu")
		(net "P5E_CPU1_PE2_TX_DN<4>")
	)
	(arc
		(start 126.581662 -217.064336)
		(mid 126.653897 -216.787812)
		(end 126.852172 -216.58199)
		(width 0.0889)
		(layer "In15.Cu")
		(net "P5E_CPU1_PE2_TX_DN<4>")
	)
	(arc
		(start 125.641862 -220.319854)
		(mid 125.715853 -220.040288)
		(end 125.918468 -219.833952)
		(width 0.0889)
		(layer "In15.Cu")
		(net "P5E_CPU1_PE2_TX_DN<4>")
	)
	(arc
		(start 125.641862 -221.94774)
		(mid 125.715853 -221.668174)
		(end 125.918468 -221.461838)
		(width 0.0889)
		(layer "In15.Cu")
		(net "P5E_CPU1_PE2_TX_DN<4>")
	)
	(arc
		(start 127.3429 -215.755982)
		(mid 127.473814 -215.619622)
		(end 127.521462 -215.436704)
		(width 0.0889)
		(layer "In15.Cu")
		(net "P5E_CPU1_PE2_TX_DN<4>")
	)
	(arc
		(start 126.4031 -219.0115)
		(mid 126.534014 -218.87514)
		(end 126.581662 -218.692222)
		(width 0.0889)
		(layer "In15.Cu")
		(net "P5E_CPU1_PE2_TX_DN<4>")
	)
	(arc
		(start 125.4633 -222.267018)
		(mid 125.594214 -222.130658)
		(end 125.641862 -221.94774)
		(width 0.0889)
		(layer "In15.Cu")
		(net "P5E_CPU1_PE2_TX_DN<4>")
	)
	(segment
		(start 122.917966 -224.925128)
		(end 122.917966 -224.389442)
		(width 0.13208)
		(layer "F.Cu")
		(net "P5E_CPU1_PE2_TX_DN<3>")
	)
	(segment
		(start 157.478476 -401.157186)
		(end 157.478476 -401.779994)
		(width 0.13208)
		(layer "F.Cu")
		(net "P5E_CPU1_PE2_TX_DN<3>")
	)
	(segment
		(start 122.917712 -224.925382)
		(end 122.917966 -224.925128)
		(width 0.13208)
		(layer "F.Cu")
		(net "P5E_CPU1_PE2_TX_DN<3>")
	)
	(segment
		(start 157.478476 -401.779994)
		(end 157.802834 -402.104352)
		(width 0.13208)
		(layer "F.Cu")
		(net "P5E_CPU1_PE2_TX_DN<3>")
	)
	(segment
		(start 157.777434 -400.858228)
		(end 157.478476 -401.157186)
		(width 0.13208)
		(layer "F.Cu")
		(net "P5E_CPU1_PE2_TX_DN<3>")
	)
	(segment
		(start 126.112016 -216.25052)
		(end 126.112016 -216.235026)
		(width 0.0889)
		(layer "In15.Cu")
		(net "P5E_CPU1_PE2_TX_DN<3>")
	)
	(segment
		(start 123.07443 -224.66046)
		(end 123.152662 -224.681288)
		(width 0.0889)
		(layer "In15.Cu")
		(net "P5E_CPU1_PE2_TX_DN<3>")
	)
	(segment
		(start 124.51461 -222.272098)
		(end 124.5235 -222.267018)
		(width 0.0889)
		(layer "In15.Cu")
		(net "P5E_CPU1_PE2_TX_DN<3>")
	)
	(segment
		(start 124.702062 -220.327474)
		(end 124.702062 -220.319854)
		(width 0.0889)
		(layer "In15.Cu")
		(net "P5E_CPU1_PE2_TX_DN<3>")
	)
	(segment
		(start 159.895794 -374.916192)
		(end 157.482794 -399.68297)
		(width 0.14732)
		(layer "In15.Cu")
		(net "P5E_CPU1_PE2_TX_DN<3>")
	)
	(segment
		(start 125.918468 -216.578434)
		(end 125.924564 -216.574878)
		(width 0.0889)
		(layer "In15.Cu")
		(net "P5E_CPU1_PE2_TX_DN<3>")
	)
	(segment
		(start 127.73533 -211.048092)
		(end 131.012946 -209.690716)
		(width 0.14732)
		(layer "In15.Cu")
		(net "P5E_CPU1_PE2_TX_DN<3>")
	)
	(segment
		(start 124.984764 -221.458282)
		(end 124.993654 -221.453202)
		(width 0.0889)
		(layer "In15.Cu")
		(net "P5E_CPU1_PE2_TX_DN<3>")
	)
	(segment
		(start 150.1394 -308.673246)
		(end 153.295096 -322.299076)
		(width 0.14732)
		(layer "In15.Cu")
		(net "P5E_CPU1_PE2_TX_DN<3>")
	)
	(segment
		(start 154.116024 -247.945402)
		(end 154.11831 -247.96115)
		(width 0.14732)
		(layer "In15.Cu")
		(net "P5E_CPU1_PE2_TX_DN<3>")
	)
	(segment
		(start 124.044964 -223.085914)
		(end 124.053854 -223.080834)
		(width 0.0889)
		(layer "In15.Cu")
		(net "P5E_CPU1_PE2_TX_DN<3>")
	)
	(segment
		(start 149.372828 -221.044516)
		(end 150.140416 -223.851978)
		(width 0.14732)
		(layer "In15.Cu")
		(net "P5E_CPU1_PE2_TX_DN<3>")
	)
	(segment
		(start 124.993654 -220.814646)
		(end 124.985526 -220.810074)
		(width 0.0889)
		(layer "In15.Cu")
		(net "P5E_CPU1_PE2_TX_DN<3>")
	)
	(segment
		(start 125.45441 -219.01658)
		(end 125.4633 -219.0115)
		(width 0.0889)
		(layer "In15.Cu")
		(net "P5E_CPU1_PE2_TX_DN<3>")
	)
	(segment
		(start 125.933454 -217.559128)
		(end 125.924564 -217.554048)
		(width 0.0889)
		(layer "In15.Cu")
		(net "P5E_CPU1_PE2_TX_DN<3>")
	)
	(segment
		(start 127.051308 -214.622634)
		(end 127.051308 -214.461344)
		(width 0.0889)
		(layer "In15.Cu")
		(net "P5E_CPU1_PE2_TX_DN<3>")
	)
	(segment
		(start 124.984764 -219.830396)
		(end 124.993654 -219.825316)
		(width 0.0889)
		(layer "In15.Cu")
		(net "P5E_CPU1_PE2_TX_DN<3>")
	)
	(segment
		(start 154.11577 -247.945402)
		(end 154.116024 -247.945402)
		(width 0.14732)
		(layer "In15.Cu")
		(net "P5E_CPU1_PE2_TX_DN<3>")
	)
	(segment
		(start 150.898606 -226.624896)
		(end 154.11577 -247.945402)
		(width 0.14732)
		(layer "In15.Cu")
		(net "P5E_CPU1_PE2_TX_DN<3>")
	)
	(segment
		(start 126.581662 -213.929976)
		(end 126.581662 -213.929722)
		(width 0.0889)
		(layer "In15.Cu")
		(net "P5E_CPU1_PE2_TX_DN<3>")
	)
	(segment
		(start 136.7663 -209.690716)
		(end 142.62227 -212.115908)
		(width 0.14732)
		(layer "In15.Cu")
		(net "P5E_CPU1_PE2_TX_DN<3>")
	)
	(segment
		(start 131.012946 -209.690716)
		(end 136.7663 -209.690716)
		(width 0.14732)
		(layer "In15.Cu")
		(net "P5E_CPU1_PE2_TX_DN<3>")
	)
	(segment
		(start 125.172216 -219.506038)
		(end 125.172216 -219.490544)
		(width 0.0889)
		(layer "In15.Cu")
		(net "P5E_CPU1_PE2_TX_DN<3>")
	)
	(segment
		(start 160.171638 -373.356378)
		(end 159.895794 -374.916192)
		(width 0.14732)
		(layer "In15.Cu")
		(net "P5E_CPU1_PE2_TX_DN<3>")
	)
	(segment
		(start 150.140416 -223.851978)
		(end 150.898606 -226.624896)
		(width 0.14732)
		(layer "In15.Cu")
		(net "P5E_CPU1_PE2_TX_DN<3>")
	)
	(segment
		(start 157.482794 -400.563588)
		(end 157.777434 -400.858228)
		(width 0.14732)
		(layer "In15.Cu")
		(net "P5E_CPU1_PE2_TX_DN<3>")
	)
	(segment
		(start 160.103312 -330.363576)
		(end 162.864038 -346.019882)
		(width 0.14732)
		(layer "In15.Cu")
		(net "P5E_CPU1_PE2_TX_DN<3>")
	)
	(segment
		(start 162.223958 -349.649796)
		(end 160.171638 -373.356378)
		(width 0.14732)
		(layer "In15.Cu")
		(net "P5E_CPU1_PE2_TX_DN<3>")
	)
	(segment
		(start 123.762262 -223.584262)
		(end 123.762262 -223.561402)
		(width 0.0889)
		(layer "In15.Cu")
		(net "P5E_CPU1_PE2_TX_DN<3>")
	)
	(segment
		(start 125.924564 -216.574878)
		(end 125.926088 -216.574116)
		(width 0.0889)
		(layer "In15.Cu")
		(net "P5E_CPU1_PE2_TX_DN<3>")
	)
	(segment
		(start 126.581662 -213.929722)
		(end 126.58217 -213.929214)
		(width 0.0889)
		(layer "In15.Cu")
		(net "P5E_CPU1_PE2_TX_DN<3>")
	)
	(segment
		(start 125.641862 -217.07856)
		(end 125.641862 -217.064336)
		(width 0.0889)
		(layer "In15.Cu")
		(net "P5E_CPU1_PE2_TX_DN<3>")
	)
	(segment
		(start 126.39421 -215.761062)
		(end 126.4031 -215.755982)
		(width 0.0889)
		(layer "In15.Cu")
		(net "P5E_CPU1_PE2_TX_DN<3>")
	)
	(segment
		(start 124.232416 -222.761556)
		(end 124.232416 -222.746062)
		(width 0.0889)
		(layer "In15.Cu")
		(net "P5E_CPU1_PE2_TX_DN<3>")
	)
	(segment
		(start 122.917966 -224.389442)
		(end 123.07443 -224.66046)
		(width 0.0889)
		(layer "In15.Cu")
		(net "P5E_CPU1_PE2_TX_DN<3>")
	)
	(segment
		(start 126.848108 -211.935314)
		(end 127.73533 -211.048092)
		(width 0.14732)
		(layer "In15.Cu")
		(net "P5E_CPU1_PE2_TX_DN<3>")
	)
	(segment
		(start 126.540006 -212.67928)
		(end 126.848108 -211.935314)
		(width 0.14732)
		(layer "In15.Cu")
		(net "P5E_CPU1_PE2_TX_DN<3>")
	)
	(segment
		(start 157.482794 -399.68297)
		(end 157.482794 -400.563588)
		(width 0.14732)
		(layer "In15.Cu")
		(net "P5E_CPU1_PE2_TX_DN<3>")
	)
	(segment
		(start 124.972572 -219.837508)
		(end 124.984764 -219.830396)
		(width 0.0889)
		(layer "In15.Cu")
		(net "P5E_CPU1_PE2_TX_DN<3>")
	)
	(segment
		(start 154.311604 -253.704852)
		(end 150.1394 -308.673246)
		(width 0.14732)
		(layer "In15.Cu")
		(net "P5E_CPU1_PE2_TX_DN<3>")
	)
	(segment
		(start 126.540006 -213.17839)
		(end 126.540006 -212.67928)
		(width 0.14732)
		(layer "In15.Cu")
		(net "P5E_CPU1_PE2_TX_DN<3>")
	)
	(segment
		(start 126.58217 -213.929214)
		(end 126.58217 -213.242652)
		(width 0.0889)
		(layer "In15.Cu")
		(net "P5E_CPU1_PE2_TX_DN<3>")
	)
	(segment
		(start 126.581662 -215.436704)
		(end 126.581662 -215.414606)
		(width 0.0889)
		(layer "In15.Cu")
		(net "P5E_CPU1_PE2_TX_DN<3>")
	)
	(segment
		(start 123.292616 -224.389442)
		(end 123.292616 -224.379536)
		(width 0.0889)
		(layer "In15.Cu")
		(net "P5E_CPU1_PE2_TX_DN<3>")
	)
	(segment
		(start 154.11831 -247.96115)
		(end 154.311604 -253.704852)
		(width 0.14732)
		(layer "In15.Cu")
		(net "P5E_CPU1_PE2_TX_DN<3>")
	)
	(segment
		(start 153.295096 -322.299076)
		(end 160.103312 -330.363576)
		(width 0.14732)
		(layer "In15.Cu")
		(net "P5E_CPU1_PE2_TX_DN<3>")
	)
	(segment
		(start 125.926088 -216.574116)
		(end 125.933454 -216.569798)
		(width 0.0889)
		(layer "In15.Cu")
		(net "P5E_CPU1_PE2_TX_DN<3>")
	)
	(segment
		(start 125.918468 -218.20632)
		(end 125.924564 -218.202764)
		(width 0.0889)
		(layer "In15.Cu")
		(net "P5E_CPU1_PE2_TX_DN<3>")
	)
	(segment
		(start 126.863856 -214.946992)
		(end 126.872746 -214.941912)
		(width 0.0889)
		(layer "In15.Cu")
		(net "P5E_CPU1_PE2_TX_DN<3>")
	)
	(segment
		(start 124.985526 -220.810074)
		(end 124.984764 -220.809566)
		(width 0.0889)
		(layer "In15.Cu")
		(net "P5E_CPU1_PE2_TX_DN<3>")
	)
	(segment
		(start 125.924564 -218.202764)
		(end 125.933454 -218.197684)
		(width 0.0889)
		(layer "In15.Cu")
		(net "P5E_CPU1_PE2_TX_DN<3>")
	)
	(segment
		(start 124.978668 -221.461838)
		(end 124.984764 -221.458282)
		(width 0.0889)
		(layer "In15.Cu")
		(net "P5E_CPU1_PE2_TX_DN<3>")
	)
	(segment
		(start 162.864038 -346.019882)
		(end 162.223958 -349.649796)
		(width 0.14732)
		(layer "In15.Cu")
		(net "P5E_CPU1_PE2_TX_DN<3>")
	)
	(segment
		(start 126.58217 -213.242652)
		(end 126.540006 -213.200488)
		(width 0.0889)
		(layer "In15.Cu")
		(net "P5E_CPU1_PE2_TX_DN<3>")
	)
	(segment
		(start 126.540006 -213.200488)
		(end 126.540006 -213.17839)
		(width 0.0889)
		(layer "In15.Cu")
		(net "P5E_CPU1_PE2_TX_DN<3>")
	)
	(segment
		(start 142.62227 -212.115908)
		(end 149.372828 -221.044516)
		(width 0.14732)
		(layer "In15.Cu")
		(net "P5E_CPU1_PE2_TX_DN<3>")
	)
	(arc
		(start 126.867158 -214.261954)
		(mid 126.707086 -214.138774)
		(end 126.597156 -213.969346)
		(width 0.0889)
		(layer "In15.Cu")
		(net "P5E_CPU1_PE2_TX_DN<3>")
	)
	(arc
		(start 125.933454 -218.197684)
		(mid 126.112051 -217.878406)
		(end 125.933454 -217.559128)
		(width 0.0889)
		(layer "In15.Cu")
		(net "P5E_CPU1_PE2_TX_DN<3>")
	)
	(arc
		(start 123.575064 -223.899984)
		(mid 123.709997 -223.76663)
		(end 123.762262 -223.584262)
		(width 0.0889)
		(layer "In15.Cu")
		(net "P5E_CPU1_PE2_TX_DN<3>")
	)
	(arc
		(start 124.993654 -219.825316)
		(mid 125.124568 -219.688956)
		(end 125.172216 -219.506038)
		(width 0.0889)
		(layer "In15.Cu")
		(net "P5E_CPU1_PE2_TX_DN<3>")
	)
	(arc
		(start 124.053854 -223.080834)
		(mid 124.184768 -222.944474)
		(end 124.232416 -222.761556)
		(width 0.0889)
		(layer "In15.Cu")
		(net "P5E_CPU1_PE2_TX_DN<3>")
	)
	(arc
		(start 125.641862 -218.692222)
		(mid 125.715853 -218.412656)
		(end 125.918468 -218.20632)
		(width 0.0889)
		(layer "In15.Cu")
		(net "P5E_CPU1_PE2_TX_DN<3>")
	)
	(arc
		(start 126.112016 -216.235026)
		(mid 126.191386 -215.961292)
		(end 126.39421 -215.761062)
		(width 0.0889)
		(layer "In15.Cu")
		(net "P5E_CPU1_PE2_TX_DN<3>")
	)
	(arc
		(start 123.292616 -224.379536)
		(mid 123.370727 -224.102587)
		(end 123.575064 -223.899984)
		(width 0.0889)
		(layer "In15.Cu")
		(net "P5E_CPU1_PE2_TX_DN<3>")
	)
	(arc
		(start 125.172216 -219.490544)
		(mid 125.251586 -219.21681)
		(end 125.45441 -219.01658)
		(width 0.0889)
		(layer "In15.Cu")
		(net "P5E_CPU1_PE2_TX_DN<3>")
	)
	(arc
		(start 124.984764 -220.809566)
		(mid 124.779692 -220.605887)
		(end 124.702062 -220.327474)
		(width 0.0889)
		(layer "In15.Cu")
		(net "P5E_CPU1_PE2_TX_DN<3>")
	)
	(arc
		(start 124.702062 -220.319854)
		(mid 124.774297 -220.04333)
		(end 124.972572 -219.837508)
		(width 0.0889)
		(layer "In15.Cu")
		(net "P5E_CPU1_PE2_TX_DN<3>")
	)
	(arc
		(start 123.762262 -223.561402)
		(mid 123.841481 -223.286717)
		(end 124.044964 -223.085914)
		(width 0.0889)
		(layer "In15.Cu")
		(net "P5E_CPU1_PE2_TX_DN<3>")
	)
	(arc
		(start 127.051054 -214.637366)
		(mid 127.051251 -214.630001)
		(end 127.051308 -214.622634)
		(width 0.0889)
		(layer "In15.Cu")
		(net "P5E_CPU1_PE2_TX_DN<3>")
	)
	(arc
		(start 125.641862 -217.064336)
		(mid 125.715853 -216.78477)
		(end 125.918468 -216.578434)
		(width 0.0889)
		(layer "In15.Cu")
		(net "P5E_CPU1_PE2_TX_DN<3>")
	)
	(arc
		(start 125.924564 -217.554048)
		(mid 125.721083 -217.353244)
		(end 125.641862 -217.07856)
		(width 0.0889)
		(layer "In15.Cu")
		(net "P5E_CPU1_PE2_TX_DN<3>")
	)
	(arc
		(start 126.872746 -214.941912)
		(mid 127 -214.811946)
		(end 127.051054 -214.637366)
		(width 0.0889)
		(layer "In15.Cu")
		(net "P5E_CPU1_PE2_TX_DN<3>")
	)
	(arc
		(start 125.933454 -216.569798)
		(mid 126.064368 -216.433438)
		(end 126.112016 -216.25052)
		(width 0.0889)
		(layer "In15.Cu")
		(net "P5E_CPU1_PE2_TX_DN<3>")
	)
	(arc
		(start 124.232416 -222.746062)
		(mid 124.311786 -222.472328)
		(end 124.51461 -222.272098)
		(width 0.0889)
		(layer "In15.Cu")
		(net "P5E_CPU1_PE2_TX_DN<3>")
	)
	(arc
		(start 126.597156 -213.969346)
		(mid 126.589064 -213.949797)
		(end 126.581662 -213.929976)
		(width 0.0889)
		(layer "In15.Cu")
		(net "P5E_CPU1_PE2_TX_DN<3>")
	)
	(arc
		(start 124.702062 -221.94774)
		(mid 124.776053 -221.668174)
		(end 124.978668 -221.461838)
		(width 0.0889)
		(layer "In15.Cu")
		(net "P5E_CPU1_PE2_TX_DN<3>")
	)
	(arc
		(start 125.4633 -219.0115)
		(mid 125.594214 -218.87514)
		(end 125.641862 -218.692222)
		(width 0.0889)
		(layer "In15.Cu")
		(net "P5E_CPU1_PE2_TX_DN<3>")
	)
	(arc
		(start 123.152662 -224.681288)
		(mid 123.255807 -224.551263)
		(end 123.292616 -224.389442)
		(width 0.0889)
		(layer "In15.Cu")
		(net "P5E_CPU1_PE2_TX_DN<3>")
	)
	(arc
		(start 127.051308 -214.461344)
		(mid 126.976303 -214.345885)
		(end 126.867158 -214.261954)
		(width 0.0889)
		(layer "In15.Cu")
		(net "P5E_CPU1_PE2_TX_DN<3>")
	)
	(arc
		(start 126.581662 -215.414606)
		(mid 126.662573 -215.144478)
		(end 126.863856 -214.946992)
		(width 0.0889)
		(layer "In15.Cu")
		(net "P5E_CPU1_PE2_TX_DN<3>")
	)
	(arc
		(start 126.4031 -215.755982)
		(mid 126.534014 -215.619622)
		(end 126.581662 -215.436704)
		(width 0.0889)
		(layer "In15.Cu")
		(net "P5E_CPU1_PE2_TX_DN<3>")
	)
	(arc
		(start 124.993654 -221.453202)
		(mid 125.172251 -221.133924)
		(end 124.993654 -220.814646)
		(width 0.0889)
		(layer "In15.Cu")
		(net "P5E_CPU1_PE2_TX_DN<3>")
	)
	(arc
		(start 124.5235 -222.267018)
		(mid 124.654414 -222.130658)
		(end 124.702062 -221.94774)
		(width 0.0889)
		(layer "In15.Cu")
		(net "P5E_CPU1_PE2_TX_DN<3>")
	)
	(segment
		(start 122.448066 -223.57588)
		(end 122.447812 -223.575626)
		(width 0.13208)
		(layer "F.Cu")
		(net "P5E_CPU1_PE2_TX_DN<2>")
	)
	(segment
		(start 160.541716 -401.157186)
		(end 160.541716 -401.779994)
		(width 0.13208)
		(layer "F.Cu")
		(net "P5E_CPU1_PE2_TX_DN<2>")
	)
	(segment
		(start 160.541716 -401.779994)
		(end 160.866074 -402.104352)
		(width 0.13208)
		(layer "F.Cu")
		(net "P5E_CPU1_PE2_TX_DN<2>")
	)
	(segment
		(start 122.448066 -224.111566)
		(end 122.448066 -223.57588)
		(width 0.13208)
		(layer "F.Cu")
		(net "P5E_CPU1_PE2_TX_DN<2>")
	)
	(segment
		(start 160.840674 -400.858228)
		(end 160.541716 -401.157186)
		(width 0.13208)
		(layer "F.Cu")
		(net "P5E_CPU1_PE2_TX_DN<2>")
	)
	(segment
		(start 155.260802 -253.481332)
		(end 155.261056 -253.496064)
		(width 0.14732)
		(layer "In15.Cu")
		(net "P5E_CPU1_PE2_TX_DN<2>")
	)
	(segment
		(start 123.762262 -220.334078)
		(end 123.762262 -220.319854)
		(width 0.0889)
		(layer "In15.Cu")
		(net "P5E_CPU1_PE2_TX_DN<2>")
	)
	(segment
		(start 155.260548 -253.481332)
		(end 155.260802 -253.481332)
		(width 0.14732)
		(layer "In15.Cu")
		(net "P5E_CPU1_PE2_TX_DN<2>")
	)
	(segment
		(start 143.232124 -211.332826)
		(end 150.32736 -220.599254)
		(width 0.14732)
		(layer "In15.Cu")
		(net "P5E_CPU1_PE2_TX_DN<2>")
	)
	(segment
		(start 160.546034 -400.563588)
		(end 160.840674 -400.858228)
		(width 0.14732)
		(layer "In15.Cu")
		(net "P5E_CPU1_PE2_TX_DN<2>")
	)
	(segment
		(start 124.038868 -219.833952)
		(end 124.044964 -219.830396)
		(width 0.0889)
		(layer "In15.Cu")
		(net "P5E_CPU1_PE2_TX_DN<2>")
	)
	(segment
		(start 124.972572 -216.58199)
		(end 124.984764 -216.574878)
		(width 0.0889)
		(layer "In15.Cu")
		(net "P5E_CPU1_PE2_TX_DN<2>")
	)
	(segment
		(start 155.261056 -253.496064)
		(end 151.12238 -308.52618)
		(width 0.14732)
		(layer "In15.Cu")
		(net "P5E_CPU1_PE2_TX_DN<2>")
	)
	(segment
		(start 122.822462 -223.575626)
		(end 122.822462 -223.568006)
		(width 0.0889)
		(layer "In15.Cu")
		(net "P5E_CPU1_PE2_TX_DN<2>")
	)
	(segment
		(start 125.45441 -215.761062)
		(end 125.4633 -215.755982)
		(width 0.0889)
		(layer "In15.Cu")
		(net "P5E_CPU1_PE2_TX_DN<2>")
	)
	(segment
		(start 127.170434 -210.233768)
		(end 130.934968 -208.674716)
		(width 0.14732)
		(layer "In15.Cu")
		(net "P5E_CPU1_PE2_TX_DN<2>")
	)
	(segment
		(start 163.2331 -349.299784)
		(end 163.042854 -351.474532)
		(width 0.14732)
		(layer "In15.Cu")
		(net "P5E_CPU1_PE2_TX_DN<2>")
	)
	(segment
		(start 124.993654 -217.559128)
		(end 124.985526 -217.554556)
		(width 0.0889)
		(layer "In15.Cu")
		(net "P5E_CPU1_PE2_TX_DN<2>")
	)
	(segment
		(start 123.105164 -223.085914)
		(end 123.114054 -223.080834)
		(width 0.0889)
		(layer "In15.Cu")
		(net "P5E_CPU1_PE2_TX_DN<2>")
	)
	(segment
		(start 150.32736 -220.599254)
		(end 150.32736 -220.599)
		(width 0.14732)
		(layer "In15.Cu")
		(net "P5E_CPU1_PE2_TX_DN<2>")
	)
	(segment
		(start 151.12238 -308.52618)
		(end 154.143964 -321.771518)
		(width 0.14732)
		(layer "In15.Cu")
		(net "P5E_CPU1_PE2_TX_DN<2>")
	)
	(segment
		(start 124.984764 -216.574878)
		(end 124.993654 -216.569798)
		(width 0.0889)
		(layer "In15.Cu")
		(net "P5E_CPU1_PE2_TX_DN<2>")
	)
	(segment
		(start 122.447812 -223.575626)
		(end 122.291348 -223.846644)
		(width 0.0889)
		(layer "In15.Cu")
		(net "P5E_CPU1_PE2_TX_DN<2>")
	)
	(segment
		(start 136.814052 -208.674716)
		(end 143.232124 -211.332826)
		(width 0.14732)
		(layer "In15.Cu")
		(net "P5E_CPU1_PE2_TX_DN<2>")
	)
	(segment
		(start 130.934968 -208.674716)
		(end 136.814052 -208.674716)
		(width 0.14732)
		(layer "In15.Cu")
		(net "P5E_CPU1_PE2_TX_DN<2>")
	)
	(segment
		(start 124.51461 -219.01658)
		(end 124.5235 -219.0115)
		(width 0.0889)
		(layer "In15.Cu")
		(net "P5E_CPU1_PE2_TX_DN<2>")
	)
	(segment
		(start 124.984764 -218.202764)
		(end 124.993654 -218.197684)
		(width 0.0889)
		(layer "In15.Cu")
		(net "P5E_CPU1_PE2_TX_DN<2>")
	)
	(segment
		(start 124.053854 -220.814646)
		(end 124.044964 -220.809566)
		(width 0.0889)
		(layer "In15.Cu")
		(net "P5E_CPU1_PE2_TX_DN<2>")
	)
	(segment
		(start 124.702062 -217.071956)
		(end 124.702062 -217.064336)
		(width 0.0889)
		(layer "In15.Cu")
		(net "P5E_CPU1_PE2_TX_DN<2>")
	)
	(segment
		(start 125.924056 -214.946992)
		(end 125.932946 -214.941912)
		(width 0.0889)
		(layer "In15.Cu")
		(net "P5E_CPU1_PE2_TX_DN<2>")
	)
	(segment
		(start 150.32736 -220.599)
		(end 150.36038 -220.64218)
		(width 0.14732)
		(layer "In15.Cu")
		(net "P5E_CPU1_PE2_TX_DN<2>")
	)
	(segment
		(start 125.64237 -213.242652)
		(end 125.600206 -213.200488)
		(width 0.0889)
		(layer "In15.Cu")
		(net "P5E_CPU1_PE2_TX_DN<2>")
	)
	(segment
		(start 124.044964 -221.458282)
		(end 124.053854 -221.453202)
		(width 0.0889)
		(layer "In15.Cu")
		(net "P5E_CPU1_PE2_TX_DN<2>")
	)
	(segment
		(start 124.985526 -217.554556)
		(end 124.984764 -217.554048)
		(width 0.0889)
		(layer "In15.Cu")
		(net "P5E_CPU1_PE2_TX_DN<2>")
	)
	(segment
		(start 160.981136 -329.928474)
		(end 163.815014 -345.998292)
		(width 0.14732)
		(layer "In15.Cu")
		(net "P5E_CPU1_PE2_TX_DN<2>")
	)
	(segment
		(start 125.641862 -215.436704)
		(end 125.641862 -215.414606)
		(width 0.0889)
		(layer "In15.Cu")
		(net "P5E_CPU1_PE2_TX_DN<2>")
	)
	(segment
		(start 123.57481 -222.272098)
		(end 123.5837 -222.267018)
		(width 0.0889)
		(layer "In15.Cu")
		(net "P5E_CPU1_PE2_TX_DN<2>")
	)
	(segment
		(start 124.232416 -219.506038)
		(end 124.232416 -219.490544)
		(width 0.0889)
		(layer "In15.Cu")
		(net "P5E_CPU1_PE2_TX_DN<2>")
	)
	(segment
		(start 125.641862 -213.93023)
		(end 125.641862 -213.929976)
		(width 0.0889)
		(layer "In15.Cu")
		(net "P5E_CPU1_PE2_TX_DN<2>")
	)
	(segment
		(start 124.044964 -219.830396)
		(end 124.046488 -219.829634)
		(width 0.0889)
		(layer "In15.Cu")
		(net "P5E_CPU1_PE2_TX_DN<2>")
	)
	(segment
		(start 124.978668 -218.20632)
		(end 124.984764 -218.202764)
		(width 0.0889)
		(layer "In15.Cu")
		(net "P5E_CPU1_PE2_TX_DN<2>")
	)
	(segment
		(start 125.600206 -212.456522)
		(end 126.06147 -211.342732)
		(width 0.14732)
		(layer "In15.Cu")
		(net "P5E_CPU1_PE2_TX_DN<2>")
	)
	(segment
		(start 122.636026 -223.899476)
		(end 122.6439 -223.894904)
		(width 0.0889)
		(layer "In15.Cu")
		(net "P5E_CPU1_PE2_TX_DN<2>")
	)
	(segment
		(start 150.36038 -220.64218)
		(end 151.991314 -226.727258)
		(width 0.14732)
		(layer "In15.Cu")
		(net "P5E_CPU1_PE2_TX_DN<2>")
	)
	(segment
		(start 154.143964 -321.771518)
		(end 160.981136 -329.928474)
		(width 0.14732)
		(layer "In15.Cu")
		(net "P5E_CPU1_PE2_TX_DN<2>")
	)
	(segment
		(start 163.815014 -345.998292)
		(end 163.2331 -349.299784)
		(width 0.14732)
		(layer "In15.Cu")
		(net "P5E_CPU1_PE2_TX_DN<2>")
	)
	(segment
		(start 155.040076 -246.930164)
		(end 155.260548 -253.481332)
		(width 0.14732)
		(layer "In15.Cu")
		(net "P5E_CPU1_PE2_TX_DN<2>")
	)
	(segment
		(start 151.991314 -226.727258)
		(end 155.037536 -246.914416)
		(width 0.14732)
		(layer "In15.Cu")
		(net "P5E_CPU1_PE2_TX_DN<2>")
	)
	(segment
		(start 163.042854 -351.474532)
		(end 160.546034 -399.981928)
		(width 0.14732)
		(layer "In15.Cu")
		(net "P5E_CPU1_PE2_TX_DN<2>")
	)
	(segment
		(start 123.292616 -222.761556)
		(end 123.292616 -222.746062)
		(width 0.0889)
		(layer "In15.Cu")
		(net "P5E_CPU1_PE2_TX_DN<2>")
	)
	(segment
		(start 155.03779 -246.914416)
		(end 155.040076 -246.930164)
		(width 0.14732)
		(layer "In15.Cu")
		(net "P5E_CPU1_PE2_TX_DN<2>")
	)
	(segment
		(start 160.546034 -399.981928)
		(end 160.546034 -400.563588)
		(width 0.14732)
		(layer "In15.Cu")
		(net "P5E_CPU1_PE2_TX_DN<2>")
	)
	(segment
		(start 155.037536 -246.914416)
		(end 155.03779 -246.914416)
		(width 0.14732)
		(layer "In15.Cu")
		(net "P5E_CPU1_PE2_TX_DN<2>")
	)
	(segment
		(start 125.641862 -213.929976)
		(end 125.64237 -213.929468)
		(width 0.0889)
		(layer "In15.Cu")
		(net "P5E_CPU1_PE2_TX_DN<2>")
	)
	(segment
		(start 122.291348 -223.846644)
		(end 122.31243 -223.924622)
		(width 0.0889)
		(layer "In15.Cu")
		(net "P5E_CPU1_PE2_TX_DN<2>")
	)
	(segment
		(start 125.600206 -213.200488)
		(end 125.600206 -213.17839)
		(width 0.0889)
		(layer "In15.Cu")
		(net "P5E_CPU1_PE2_TX_DN<2>")
	)
	(segment
		(start 125.172216 -216.25052)
		(end 125.172216 -216.235026)
		(width 0.0889)
		(layer "In15.Cu")
		(net "P5E_CPU1_PE2_TX_DN<2>")
	)
	(segment
		(start 124.038868 -221.461838)
		(end 124.044964 -221.458282)
		(width 0.0889)
		(layer "In15.Cu")
		(net "P5E_CPU1_PE2_TX_DN<2>")
	)
	(segment
		(start 126.06147 -211.342732)
		(end 127.170434 -210.233768)
		(width 0.14732)
		(layer "In15.Cu")
		(net "P5E_CPU1_PE2_TX_DN<2>")
	)
	(segment
		(start 126.111508 -214.622634)
		(end 126.111508 -214.461344)
		(width 0.0889)
		(layer "In15.Cu")
		(net "P5E_CPU1_PE2_TX_DN<2>")
	)
	(segment
		(start 125.64237 -213.929468)
		(end 125.64237 -213.242652)
		(width 0.0889)
		(layer "In15.Cu")
		(net "P5E_CPU1_PE2_TX_DN<2>")
	)
	(segment
		(start 125.600206 -213.17839)
		(end 125.600206 -212.456522)
		(width 0.14732)
		(layer "In15.Cu")
		(net "P5E_CPU1_PE2_TX_DN<2>")
	)
	(segment
		(start 122.63501 -223.899984)
		(end 122.636026 -223.899476)
		(width 0.0889)
		(layer "In15.Cu")
		(net "P5E_CPU1_PE2_TX_DN<2>")
	)
	(segment
		(start 124.046488 -219.829634)
		(end 124.053854 -219.825316)
		(width 0.0889)
		(layer "In15.Cu")
		(net "P5E_CPU1_PE2_TX_DN<2>")
	)
	(arc
		(start 125.641862 -215.414606)
		(mid 125.722773 -215.144478)
		(end 125.924056 -214.946992)
		(width 0.0889)
		(layer "In15.Cu")
		(net "P5E_CPU1_PE2_TX_DN<2>")
	)
	(arc
		(start 122.6439 -223.894904)
		(mid 122.774814 -223.758544)
		(end 122.822462 -223.575626)
		(width 0.0889)
		(layer "In15.Cu")
		(net "P5E_CPU1_PE2_TX_DN<2>")
	)
	(arc
		(start 125.657356 -213.970108)
		(mid 125.649249 -213.950309)
		(end 125.641862 -213.93023)
		(width 0.0889)
		(layer "In15.Cu")
		(net "P5E_CPU1_PE2_TX_DN<2>")
	)
	(arc
		(start 124.984764 -217.554048)
		(mid 124.779692 -217.350369)
		(end 124.702062 -217.071956)
		(width 0.0889)
		(layer "In15.Cu")
		(net "P5E_CPU1_PE2_TX_DN<2>")
	)
	(arc
		(start 124.053854 -221.453202)
		(mid 124.232451 -221.133924)
		(end 124.053854 -220.814646)
		(width 0.0889)
		(layer "In15.Cu")
		(net "P5E_CPU1_PE2_TX_DN<2>")
	)
	(arc
		(start 122.822462 -223.568006)
		(mid 122.900091 -223.289593)
		(end 123.105164 -223.085914)
		(width 0.0889)
		(layer "In15.Cu")
		(net "P5E_CPU1_PE2_TX_DN<2>")
	)
	(arc
		(start 123.292616 -222.746062)
		(mid 123.371986 -222.472328)
		(end 123.57481 -222.272098)
		(width 0.0889)
		(layer "In15.Cu")
		(net "P5E_CPU1_PE2_TX_DN<2>")
	)
	(arc
		(start 126.111254 -214.637366)
		(mid 126.111451 -214.630001)
		(end 126.111508 -214.622634)
		(width 0.0889)
		(layer "In15.Cu")
		(net "P5E_CPU1_PE2_TX_DN<2>")
	)
	(arc
		(start 123.762262 -221.94774)
		(mid 123.836253 -221.668174)
		(end 124.038868 -221.461838)
		(width 0.0889)
		(layer "In15.Cu")
		(net "P5E_CPU1_PE2_TX_DN<2>")
	)
	(arc
		(start 125.172216 -216.235026)
		(mid 125.251586 -215.961292)
		(end 125.45441 -215.761062)
		(width 0.0889)
		(layer "In15.Cu")
		(net "P5E_CPU1_PE2_TX_DN<2>")
	)
	(arc
		(start 124.702062 -218.692222)
		(mid 124.776053 -218.412656)
		(end 124.978668 -218.20632)
		(width 0.0889)
		(layer "In15.Cu")
		(net "P5E_CPU1_PE2_TX_DN<2>")
	)
	(arc
		(start 124.5235 -219.0115)
		(mid 124.654414 -218.87514)
		(end 124.702062 -218.692222)
		(width 0.0889)
		(layer "In15.Cu")
		(net "P5E_CPU1_PE2_TX_DN<2>")
	)
	(arc
		(start 124.232416 -219.490544)
		(mid 124.311786 -219.21681)
		(end 124.51461 -219.01658)
		(width 0.0889)
		(layer "In15.Cu")
		(net "P5E_CPU1_PE2_TX_DN<2>")
	)
	(arc
		(start 122.31243 -223.924622)
		(mid 122.476526 -223.948969)
		(end 122.63501 -223.899984)
		(width 0.0889)
		(layer "In15.Cu")
		(net "P5E_CPU1_PE2_TX_DN<2>")
	)
	(arc
		(start 123.5837 -222.267018)
		(mid 123.714614 -222.130658)
		(end 123.762262 -221.94774)
		(width 0.0889)
		(layer "In15.Cu")
		(net "P5E_CPU1_PE2_TX_DN<2>")
	)
	(arc
		(start 123.762262 -220.319854)
		(mid 123.836253 -220.040288)
		(end 124.038868 -219.833952)
		(width 0.0889)
		(layer "In15.Cu")
		(net "P5E_CPU1_PE2_TX_DN<2>")
	)
	(arc
		(start 125.932946 -214.941912)
		(mid 126.0602 -214.811946)
		(end 126.111254 -214.637366)
		(width 0.0889)
		(layer "In15.Cu")
		(net "P5E_CPU1_PE2_TX_DN<2>")
	)
	(arc
		(start 125.927358 -214.261954)
		(mid 125.767467 -214.13907)
		(end 125.657356 -213.970108)
		(width 0.0889)
		(layer "In15.Cu")
		(net "P5E_CPU1_PE2_TX_DN<2>")
	)
	(arc
		(start 124.993654 -216.569798)
		(mid 125.124568 -216.433438)
		(end 125.172216 -216.25052)
		(width 0.0889)
		(layer "In15.Cu")
		(net "P5E_CPU1_PE2_TX_DN<2>")
	)
	(arc
		(start 125.4633 -215.755982)
		(mid 125.594214 -215.619622)
		(end 125.641862 -215.436704)
		(width 0.0889)
		(layer "In15.Cu")
		(net "P5E_CPU1_PE2_TX_DN<2>")
	)
	(arc
		(start 124.993654 -218.197684)
		(mid 125.172251 -217.878406)
		(end 124.993654 -217.559128)
		(width 0.0889)
		(layer "In15.Cu")
		(net "P5E_CPU1_PE2_TX_DN<2>")
	)
	(arc
		(start 124.044964 -220.809566)
		(mid 123.841483 -220.608762)
		(end 123.762262 -220.334078)
		(width 0.0889)
		(layer "In15.Cu")
		(net "P5E_CPU1_PE2_TX_DN<2>")
	)
	(arc
		(start 126.111508 -214.461344)
		(mid 126.036503 -214.345885)
		(end 125.927358 -214.261954)
		(width 0.0889)
		(layer "In15.Cu")
		(net "P5E_CPU1_PE2_TX_DN<2>")
	)
	(arc
		(start 124.053854 -219.825316)
		(mid 124.184768 -219.688956)
		(end 124.232416 -219.506038)
		(width 0.0889)
		(layer "In15.Cu")
		(net "P5E_CPU1_PE2_TX_DN<2>")
	)
	(arc
		(start 123.114054 -223.080834)
		(mid 123.244968 -222.944474)
		(end 123.292616 -222.761556)
		(width 0.0889)
		(layer "In15.Cu")
		(net "P5E_CPU1_PE2_TX_DN<2>")
	)
	(arc
		(start 124.702062 -217.064336)
		(mid 124.774297 -216.787812)
		(end 124.972572 -216.58199)
		(width 0.0889)
		(layer "In15.Cu")
		(net "P5E_CPU1_PE2_TX_DN<2>")
	)
	(segment
		(start 121.038112 -224.925382)
		(end 121.038112 -224.389696)
		(width 0.13208)
		(layer "F.Cu")
		(net "P5E_CPU1_PE2_TX_DN<1>")
	)
	(segment
		(start 163.604956 -401.779994)
		(end 163.929314 -402.104352)
		(width 0.13208)
		(layer "F.Cu")
		(net "P5E_CPU1_PE2_TX_DN<1>")
	)
	(segment
		(start 163.903914 -400.858228)
		(end 163.604956 -401.157186)
		(width 0.13208)
		(layer "F.Cu")
		(net "P5E_CPU1_PE2_TX_DN<1>")
	)
	(segment
		(start 121.038112 -224.389696)
		(end 121.038366 -224.389442)
		(width 0.13208)
		(layer "F.Cu")
		(net "P5E_CPU1_PE2_TX_DN<1>")
	)
	(segment
		(start 163.604956 -401.157186)
		(end 163.604956 -401.779994)
		(width 0.13208)
		(layer "F.Cu")
		(net "P5E_CPU1_PE2_TX_DN<1>")
	)
	(segment
		(start 122.822462 -220.327474)
		(end 122.822462 -220.319854)
		(width 0.0889)
		(layer "In15.Cu")
		(net "P5E_CPU1_PE2_TX_DN<1>")
	)
	(segment
		(start 163.260024 -327.742042)
		(end 162.405314 -332.589378)
		(width 0.14732)
		(layer "In15.Cu")
		(net "P5E_CPU1_PE2_TX_DN<1>")
	)
	(segment
		(start 156.03474 -247.226836)
		(end 156.244544 -253.471426)
		(width 0.14732)
		(layer "In15.Cu")
		(net "P5E_CPU1_PE2_TX_DN<1>")
	)
	(segment
		(start 121.038366 -224.389442)
		(end 121.19483 -224.66046)
		(width 0.0889)
		(layer "In15.Cu")
		(net "P5E_CPU1_PE2_TX_DN<1>")
	)
	(segment
		(start 123.105164 -221.458282)
		(end 123.114054 -221.453202)
		(width 0.0889)
		(layer "In15.Cu")
		(net "P5E_CPU1_PE2_TX_DN<1>")
	)
	(segment
		(start 123.105926 -220.810074)
		(end 123.105164 -220.809566)
		(width 0.0889)
		(layer "In15.Cu")
		(net "P5E_CPU1_PE2_TX_DN<1>")
	)
	(segment
		(start 123.762262 -217.07856)
		(end 123.762262 -217.064336)
		(width 0.0889)
		(layer "In15.Cu")
		(net "P5E_CPU1_PE2_TX_DN<1>")
	)
	(segment
		(start 152.8953 -226.421188)
		(end 156.03474 -247.226836)
		(width 0.14732)
		(layer "In15.Cu")
		(net "P5E_CPU1_PE2_TX_DN<1>")
	)
	(segment
		(start 123.114054 -220.814646)
		(end 123.105926 -220.810074)
		(width 0.0889)
		(layer "In15.Cu")
		(net "P5E_CPU1_PE2_TX_DN<1>")
	)
	(segment
		(start 156.244544 -253.471172)
		(end 156.245052 -253.486412)
		(width 0.14732)
		(layer "In15.Cu")
		(net "P5E_CPU1_PE2_TX_DN<1>")
	)
	(segment
		(start 123.105164 -219.830396)
		(end 123.114054 -219.825316)
		(width 0.0889)
		(layer "In15.Cu")
		(net "P5E_CPU1_PE2_TX_DN<1>")
	)
	(segment
		(start 154.570684 -319.353946)
		(end 155.993338 -321.501262)
		(width 0.14732)
		(layer "In15.Cu")
		(net "P5E_CPU1_PE2_TX_DN<1>")
	)
	(segment
		(start 163.599114 -400.553428)
		(end 163.903914 -400.858228)
		(width 0.14732)
		(layer "In15.Cu")
		(net "P5E_CPU1_PE2_TX_DN<1>")
	)
	(segment
		(start 124.660406 -212.201506)
		(end 125.25883 -210.7565)
		(width 0.14732)
		(layer "In15.Cu")
		(net "P5E_CPU1_PE2_TX_DN<1>")
	)
	(segment
		(start 163.484306 -338.708492)
		(end 163.484052 -338.709)
		(width 0.14732)
		(layer "In15.Cu")
		(net "P5E_CPU1_PE2_TX_DN<1>")
	)
	(segment
		(start 124.660406 -213.200488)
		(end 124.660406 -213.17839)
		(width 0.0889)
		(layer "In15.Cu")
		(net "P5E_CPU1_PE2_TX_DN<1>")
	)
	(segment
		(start 121.19483 -224.66046)
		(end 121.273062 -224.681288)
		(width 0.0889)
		(layer "In15.Cu")
		(net "P5E_CPU1_PE2_TX_DN<1>")
	)
	(segment
		(start 163.599114 -399.67789)
		(end 163.599114 -400.553428)
		(width 0.14732)
		(layer "In15.Cu")
		(net "P5E_CPU1_PE2_TX_DN<1>")
	)
	(segment
		(start 122.165364 -223.085914)
		(end 122.174254 -223.080834)
		(width 0.0889)
		(layer "In15.Cu")
		(net "P5E_CPU1_PE2_TX_DN<1>")
	)
	(segment
		(start 135.65378 -203.208636)
		(end 137.163302 -203.833984)
		(width 0.14732)
		(layer "In15.Cu")
		(net "P5E_CPU1_PE2_TX_DN<1>")
	)
	(segment
		(start 152.06472 -308.4195)
		(end 154.570684 -319.353946)
		(width 0.14732)
		(layer "In15.Cu")
		(net "P5E_CPU1_PE2_TX_DN<1>")
	)
	(segment
		(start 121.413016 -224.389442)
		(end 121.413016 -224.379536)
		(width 0.0889)
		(layer "In15.Cu")
		(net "P5E_CPU1_PE2_TX_DN<1>")
	)
	(segment
		(start 124.232416 -216.25052)
		(end 124.232416 -216.235026)
		(width 0.0889)
		(layer "In15.Cu")
		(net "P5E_CPU1_PE2_TX_DN<1>")
	)
	(segment
		(start 124.038868 -218.20632)
		(end 124.044964 -218.202764)
		(width 0.0889)
		(layer "In15.Cu")
		(net "P5E_CPU1_PE2_TX_DN<1>")
	)
	(segment
		(start 124.038868 -216.578434)
		(end 124.044964 -216.574878)
		(width 0.0889)
		(layer "In15.Cu")
		(net "P5E_CPU1_PE2_TX_DN<1>")
	)
	(segment
		(start 145.08734 -211.758022)
		(end 151.188674 -219.85859)
		(width 0.14732)
		(layer "In15.Cu")
		(net "P5E_CPU1_PE2_TX_DN<1>")
	)
	(segment
		(start 124.984256 -214.946992)
		(end 124.993146 -214.941912)
		(width 0.0889)
		(layer "In15.Cu")
		(net "P5E_CPU1_PE2_TX_DN<1>")
	)
	(segment
		(start 164.03066 -351.615502)
		(end 163.599114 -399.67789)
		(width 0.14732)
		(layer "In15.Cu")
		(net "P5E_CPU1_PE2_TX_DN<1>")
	)
	(segment
		(start 122.352816 -222.761556)
		(end 122.352816 -222.746062)
		(width 0.0889)
		(layer "In15.Cu")
		(net "P5E_CPU1_PE2_TX_DN<1>")
	)
	(segment
		(start 125.171708 -214.622634)
		(end 125.171708 -214.461344)
		(width 0.0889)
		(layer "In15.Cu")
		(net "P5E_CPU1_PE2_TX_DN<1>")
	)
	(segment
		(start 156.745432 -322.293488)
		(end 158.47314 -324.028816)
		(width 0.14732)
		(layer "In15.Cu")
		(net "P5E_CPU1_PE2_TX_DN<1>")
	)
	(segment
		(start 162.405314 -332.589378)
		(end 163.484306 -338.708492)
		(width 0.14732)
		(layer "In15.Cu")
		(net "P5E_CPU1_PE2_TX_DN<1>")
	)
	(segment
		(start 151.188674 -219.85859)
		(end 152.8953 -226.421188)
		(width 0.14732)
		(layer "In15.Cu")
		(net "P5E_CPU1_PE2_TX_DN<1>")
	)
	(segment
		(start 162.64763 -325.844916)
		(end 163.018978 -326.375014)
		(width 0.14732)
		(layer "In15.Cu")
		(net "P5E_CPU1_PE2_TX_DN<1>")
	)
	(segment
		(start 159.931862 -325.05015)
		(end 162.044888 -325.422768)
		(width 0.14732)
		(layer "In15.Cu")
		(net "P5E_CPU1_PE2_TX_DN<1>")
	)
	(segment
		(start 155.993338 -321.501262)
		(end 156.745432 -322.293488)
		(width 0.14732)
		(layer "In15.Cu")
		(net "P5E_CPU1_PE2_TX_DN<1>")
	)
	(segment
		(start 124.044964 -216.574878)
		(end 124.046488 -216.574116)
		(width 0.0889)
		(layer "In15.Cu")
		(net "P5E_CPU1_PE2_TX_DN<1>")
	)
	(segment
		(start 124.702062 -213.929976)
		(end 124.702062 -213.929722)
		(width 0.0889)
		(layer "In15.Cu")
		(net "P5E_CPU1_PE2_TX_DN<1>")
	)
	(segment
		(start 137.163302 -203.833984)
		(end 145.08734 -211.758022)
		(width 0.14732)
		(layer "In15.Cu")
		(net "P5E_CPU1_PE2_TX_DN<1>")
	)
	(segment
		(start 123.099068 -221.461838)
		(end 123.105164 -221.458282)
		(width 0.0889)
		(layer "In15.Cu")
		(net "P5E_CPU1_PE2_TX_DN<1>")
	)
	(segment
		(start 124.053854 -217.559128)
		(end 124.044964 -217.554048)
		(width 0.0889)
		(layer "In15.Cu")
		(net "P5E_CPU1_PE2_TX_DN<1>")
	)
	(segment
		(start 164.769546 -345.9988)
		(end 164.27831 -348.784926)
		(width 0.14732)
		(layer "In15.Cu")
		(net "P5E_CPU1_PE2_TX_DN<1>")
	)
	(segment
		(start 124.70257 -213.929214)
		(end 124.70257 -213.242652)
		(width 0.0889)
		(layer "In15.Cu")
		(net "P5E_CPU1_PE2_TX_DN<1>")
	)
	(segment
		(start 124.70257 -213.242652)
		(end 124.660406 -213.200488)
		(width 0.0889)
		(layer "In15.Cu")
		(net "P5E_CPU1_PE2_TX_DN<1>")
	)
	(segment
		(start 122.63501 -222.272098)
		(end 122.6439 -222.267018)
		(width 0.0889)
		(layer "In15.Cu")
		(net "P5E_CPU1_PE2_TX_DN<1>")
	)
	(segment
		(start 156.245052 -253.486412)
		(end 152.06472 -308.4195)
		(width 0.14732)
		(layer "In15.Cu")
		(net "P5E_CPU1_PE2_TX_DN<1>")
	)
	(segment
		(start 163.484052 -338.709)
		(end 164.769546 -345.9988)
		(width 0.14732)
		(layer "In15.Cu")
		(net "P5E_CPU1_PE2_TX_DN<1>")
	)
	(segment
		(start 163.018978 -326.375014)
		(end 163.260024 -327.742042)
		(width 0.14732)
		(layer "In15.Cu")
		(net "P5E_CPU1_PE2_TX_DN<1>")
	)
	(segment
		(start 132.067808 -203.947522)
		(end 133.851904 -203.208636)
		(width 0.14732)
		(layer "In15.Cu")
		(net "P5E_CPU1_PE2_TX_DN<1>")
	)
	(segment
		(start 133.851904 -203.208636)
		(end 135.65378 -203.208636)
		(width 0.14732)
		(layer "In15.Cu")
		(net "P5E_CPU1_PE2_TX_DN<1>")
	)
	(segment
		(start 124.51461 -215.761062)
		(end 124.5235 -215.755982)
		(width 0.0889)
		(layer "In15.Cu")
		(net "P5E_CPU1_PE2_TX_DN<1>")
	)
	(segment
		(start 124.660406 -213.17839)
		(end 124.660406 -212.201506)
		(width 0.14732)
		(layer "In15.Cu")
		(net "P5E_CPU1_PE2_TX_DN<1>")
	)
	(segment
		(start 123.57481 -219.01658)
		(end 123.5837 -219.0115)
		(width 0.0889)
		(layer "In15.Cu")
		(net "P5E_CPU1_PE2_TX_DN<1>")
	)
	(segment
		(start 124.702062 -213.929722)
		(end 124.70257 -213.929214)
		(width 0.0889)
		(layer "In15.Cu")
		(net "P5E_CPU1_PE2_TX_DN<1>")
	)
	(segment
		(start 123.292616 -219.506038)
		(end 123.292616 -219.490544)
		(width 0.0889)
		(layer "In15.Cu")
		(net "P5E_CPU1_PE2_TX_DN<1>")
	)
	(segment
		(start 121.882662 -223.584262)
		(end 121.882662 -223.561402)
		(width 0.0889)
		(layer "In15.Cu")
		(net "P5E_CPU1_PE2_TX_DN<1>")
	)
	(segment
		(start 164.27831 -348.784926)
		(end 164.03066 -351.615502)
		(width 0.14732)
		(layer "In15.Cu")
		(net "P5E_CPU1_PE2_TX_DN<1>")
	)
	(segment
		(start 123.092972 -219.837508)
		(end 123.105164 -219.830396)
		(width 0.0889)
		(layer "In15.Cu")
		(net "P5E_CPU1_PE2_TX_DN<1>")
	)
	(segment
		(start 124.702062 -215.436704)
		(end 124.702062 -215.414606)
		(width 0.0889)
		(layer "In15.Cu")
		(net "P5E_CPU1_PE2_TX_DN<1>")
	)
	(segment
		(start 124.044964 -218.202764)
		(end 124.053854 -218.197684)
		(width 0.0889)
		(layer "In15.Cu")
		(net "P5E_CPU1_PE2_TX_DN<1>")
	)
	(segment
		(start 162.044888 -325.422768)
		(end 162.64763 -325.844916)
		(width 0.14732)
		(layer "In15.Cu")
		(net "P5E_CPU1_PE2_TX_DN<1>")
	)
	(segment
		(start 158.47314 -324.028816)
		(end 159.931862 -325.05015)
		(width 0.14732)
		(layer "In15.Cu")
		(net "P5E_CPU1_PE2_TX_DN<1>")
	)
	(segment
		(start 124.046488 -216.574116)
		(end 124.053854 -216.569798)
		(width 0.0889)
		(layer "In15.Cu")
		(net "P5E_CPU1_PE2_TX_DN<1>")
	)
	(segment
		(start 125.25883 -210.7565)
		(end 132.067808 -203.947522)
		(width 0.14732)
		(layer "In15.Cu")
		(net "P5E_CPU1_PE2_TX_DN<1>")
	)
	(segment
		(start 156.244544 -253.471426)
		(end 156.244544 -253.471172)
		(width 0.14732)
		(layer "In15.Cu")
		(net "P5E_CPU1_PE2_TX_DN<1>")
	)
	(arc
		(start 121.273062 -224.681288)
		(mid 121.376207 -224.551263)
		(end 121.413016 -224.389442)
		(width 0.0889)
		(layer "In15.Cu")
		(net "P5E_CPU1_PE2_TX_DN<1>")
	)
	(arc
		(start 124.702062 -215.414606)
		(mid 124.782973 -215.144478)
		(end 124.984256 -214.946992)
		(width 0.0889)
		(layer "In15.Cu")
		(net "P5E_CPU1_PE2_TX_DN<1>")
	)
	(arc
		(start 124.993146 -214.941912)
		(mid 125.1204 -214.811946)
		(end 125.171454 -214.637366)
		(width 0.0889)
		(layer "In15.Cu")
		(net "P5E_CPU1_PE2_TX_DN<1>")
	)
	(arc
		(start 122.822462 -221.94774)
		(mid 122.896453 -221.668174)
		(end 123.099068 -221.461838)
		(width 0.0889)
		(layer "In15.Cu")
		(net "P5E_CPU1_PE2_TX_DN<1>")
	)
	(arc
		(start 124.232416 -216.235026)
		(mid 124.311786 -215.961292)
		(end 124.51461 -215.761062)
		(width 0.0889)
		(layer "In15.Cu")
		(net "P5E_CPU1_PE2_TX_DN<1>")
	)
	(arc
		(start 124.053854 -218.197684)
		(mid 124.232451 -217.878406)
		(end 124.053854 -217.559128)
		(width 0.0889)
		(layer "In15.Cu")
		(net "P5E_CPU1_PE2_TX_DN<1>")
	)
	(arc
		(start 121.882662 -223.561402)
		(mid 121.961881 -223.286717)
		(end 122.165364 -223.085914)
		(width 0.0889)
		(layer "In15.Cu")
		(net "P5E_CPU1_PE2_TX_DN<1>")
	)
	(arc
		(start 123.762262 -217.064336)
		(mid 123.836253 -216.78477)
		(end 124.038868 -216.578434)
		(width 0.0889)
		(layer "In15.Cu")
		(net "P5E_CPU1_PE2_TX_DN<1>")
	)
	(arc
		(start 125.171708 -214.461344)
		(mid 125.096703 -214.345885)
		(end 124.987558 -214.261954)
		(width 0.0889)
		(layer "In15.Cu")
		(net "P5E_CPU1_PE2_TX_DN<1>")
	)
	(arc
		(start 124.053854 -216.569798)
		(mid 124.184768 -216.433438)
		(end 124.232416 -216.25052)
		(width 0.0889)
		(layer "In15.Cu")
		(net "P5E_CPU1_PE2_TX_DN<1>")
	)
	(arc
		(start 121.413016 -224.379536)
		(mid 121.491127 -224.102587)
		(end 121.695464 -223.899984)
		(width 0.0889)
		(layer "In15.Cu")
		(net "P5E_CPU1_PE2_TX_DN<1>")
	)
	(arc
		(start 121.695464 -223.899984)
		(mid 121.830397 -223.76663)
		(end 121.882662 -223.584262)
		(width 0.0889)
		(layer "In15.Cu")
		(net "P5E_CPU1_PE2_TX_DN<1>")
	)
	(arc
		(start 124.717556 -213.969346)
		(mid 124.709464 -213.949797)
		(end 124.702062 -213.929976)
		(width 0.0889)
		(layer "In15.Cu")
		(net "P5E_CPU1_PE2_TX_DN<1>")
	)
	(arc
		(start 123.114054 -221.453202)
		(mid 123.292651 -221.133924)
		(end 123.114054 -220.814646)
		(width 0.0889)
		(layer "In15.Cu")
		(net "P5E_CPU1_PE2_TX_DN<1>")
	)
	(arc
		(start 124.044964 -217.554048)
		(mid 123.841483 -217.353244)
		(end 123.762262 -217.07856)
		(width 0.0889)
		(layer "In15.Cu")
		(net "P5E_CPU1_PE2_TX_DN<1>")
	)
	(arc
		(start 123.292616 -219.490544)
		(mid 123.371986 -219.21681)
		(end 123.57481 -219.01658)
		(width 0.0889)
		(layer "In15.Cu")
		(net "P5E_CPU1_PE2_TX_DN<1>")
	)
	(arc
		(start 123.114054 -219.825316)
		(mid 123.244968 -219.688956)
		(end 123.292616 -219.506038)
		(width 0.0889)
		(layer "In15.Cu")
		(net "P5E_CPU1_PE2_TX_DN<1>")
	)
	(arc
		(start 123.5837 -219.0115)
		(mid 123.714614 -218.87514)
		(end 123.762262 -218.692222)
		(width 0.0889)
		(layer "In15.Cu")
		(net "P5E_CPU1_PE2_TX_DN<1>")
	)
	(arc
		(start 122.6439 -222.267018)
		(mid 122.774814 -222.130658)
		(end 122.822462 -221.94774)
		(width 0.0889)
		(layer "In15.Cu")
		(net "P5E_CPU1_PE2_TX_DN<1>")
	)
	(arc
		(start 122.352816 -222.746062)
		(mid 122.432186 -222.472328)
		(end 122.63501 -222.272098)
		(width 0.0889)
		(layer "In15.Cu")
		(net "P5E_CPU1_PE2_TX_DN<1>")
	)
	(arc
		(start 122.174254 -223.080834)
		(mid 122.305168 -222.944474)
		(end 122.352816 -222.761556)
		(width 0.0889)
		(layer "In15.Cu")
		(net "P5E_CPU1_PE2_TX_DN<1>")
	)
	(arc
		(start 125.171454 -214.637366)
		(mid 125.171651 -214.630001)
		(end 125.171708 -214.622634)
		(width 0.0889)
		(layer "In15.Cu")
		(net "P5E_CPU1_PE2_TX_DN<1>")
	)
	(arc
		(start 123.105164 -220.809566)
		(mid 122.900092 -220.605887)
		(end 122.822462 -220.327474)
		(width 0.0889)
		(layer "In15.Cu")
		(net "P5E_CPU1_PE2_TX_DN<1>")
	)
	(arc
		(start 123.762262 -218.692222)
		(mid 123.836253 -218.412656)
		(end 124.038868 -218.20632)
		(width 0.0889)
		(layer "In15.Cu")
		(net "P5E_CPU1_PE2_TX_DN<1>")
	)
	(arc
		(start 122.822462 -220.319854)
		(mid 122.894697 -220.04333)
		(end 123.092972 -219.837508)
		(width 0.0889)
		(layer "In15.Cu")
		(net "P5E_CPU1_PE2_TX_DN<1>")
	)
	(arc
		(start 124.5235 -215.755982)
		(mid 124.654414 -215.619622)
		(end 124.702062 -215.436704)
		(width 0.0889)
		(layer "In15.Cu")
		(net "P5E_CPU1_PE2_TX_DN<1>")
	)
	(arc
		(start 124.987558 -214.261954)
		(mid 124.827486 -214.138774)
		(end 124.717556 -213.969346)
		(width 0.0889)
		(layer "In15.Cu")
		(net "P5E_CPU1_PE2_TX_DN<1>")
	)
	(segment
		(start 134.195566 -224.925382)
		(end 134.195566 -224.389442)
		(width 0.13208)
		(layer "F.Cu")
		(net "P5E_CPU1_PE2_TX_DN<15>")
	)
	(segment
		(start 120.719596 -401.779994)
		(end 121.043954 -402.104352)
		(width 0.13208)
		(layer "F.Cu")
		(net "P5E_CPU1_PE2_TX_DN<15>")
	)
	(segment
		(start 121.018554 -400.858228)
		(end 120.719596 -401.157186)
		(width 0.13208)
		(layer "F.Cu")
		(net "P5E_CPU1_PE2_TX_DN<15>")
	)
	(segment
		(start 120.719596 -401.157186)
		(end 120.719596 -401.779994)
		(width 0.13208)
		(layer "F.Cu")
		(net "P5E_CPU1_PE2_TX_DN<15>")
	)
	(segment
		(start 138.580368 -246.008398)
		(end 137.951464 -248.087896)
		(width 0.14732)
		(layer "In15.Cu")
		(net "P5E_CPU1_PE2_TX_DN<15>")
	)
	(segment
		(start 136.82472 -227.595176)
		(end 136.883648 -227.595176)
		(width 0.0889)
		(layer "In15.Cu")
		(net "P5E_CPU1_PE2_TX_DN<15>")
	)
	(segment
		(start 137.951464 -248.087896)
		(end 137.512044 -250.579636)
		(width 0.14732)
		(layer "In15.Cu")
		(net "P5E_CPU1_PE2_TX_DN<15>")
	)
	(segment
		(start 136.348978 -227.150422)
		(end 136.357868 -227.155502)
		(width 0.0889)
		(layer "In15.Cu")
		(net "P5E_CPU1_PE2_TX_DN<15>")
	)
	(segment
		(start 149.189694 -361.376722)
		(end 146.315176 -368.320066)
		(width 0.14732)
		(layer "In15.Cu")
		(net "P5E_CPU1_PE2_TX_DN<15>")
	)
	(segment
		(start 134.35203 -224.66046)
		(end 134.441184 -224.684336)
		(width 0.0889)
		(layer "In15.Cu")
		(net "P5E_CPU1_PE2_TX_DN<15>")
	)
	(segment
		(start 136.883648 -227.595176)
		(end 136.899142 -227.61067)
		(width 0.0889)
		(layer "In15.Cu")
		(net "P5E_CPU1_PE2_TX_DN<15>")
	)
	(segment
		(start 140.437108 -256.883662)
		(end 141.324838 -259.66928)
		(width 0.14732)
		(layer "In15.Cu")
		(net "P5E_CPU1_PE2_TX_DN<15>")
	)
	(segment
		(start 138.840972 -232.159302)
		(end 138.580368 -246.008398)
		(width 0.14732)
		(layer "In15.Cu")
		(net "P5E_CPU1_PE2_TX_DN<15>")
	)
	(segment
		(start 135.409178 -225.522536)
		(end 135.418068 -225.527616)
		(width 0.0889)
		(layer "In15.Cu")
		(net "P5E_CPU1_PE2_TX_DN<15>")
	)
	(segment
		(start 143.022828 -328.310494)
		(end 148.996146 -334.99171)
		(width 0.14732)
		(layer "In15.Cu")
		(net "P5E_CPU1_PE2_TX_DN<15>")
	)
	(segment
		(start 138.410188 -253.397258)
		(end 139.010898 -254.84709)
		(width 0.14732)
		(layer "In15.Cu")
		(net "P5E_CPU1_PE2_TX_DN<15>")
	)
	(segment
		(start 150.825454 -345.36253)
		(end 150.360126 -348.002098)
		(width 0.14732)
		(layer "In15.Cu")
		(net "P5E_CPU1_PE2_TX_DN<15>")
	)
	(segment
		(start 135.700516 -225.998786)
		(end 135.700516 -226.017328)
		(width 0.0889)
		(layer "In15.Cu")
		(net "P5E_CPU1_PE2_TX_DN<15>")
	)
	(segment
		(start 136.899142 -227.61067)
		(end 137.502138 -228.213412)
		(width 0.14732)
		(layer "In15.Cu")
		(net "P5E_CPU1_PE2_TX_DN<15>")
	)
	(segment
		(start 137.512044 -250.579636)
		(end 137.873994 -252.631194)
		(width 0.14732)
		(layer "In15.Cu")
		(net "P5E_CPU1_PE2_TX_DN<15>")
	)
	(segment
		(start 138.736324 -230.542338)
		(end 138.840718 -232.157778)
		(width 0.14732)
		(layer "In15.Cu")
		(net "P5E_CPU1_PE2_TX_DN<15>")
	)
	(segment
		(start 138.840718 -232.157778)
		(end 138.840972 -232.159302)
		(width 0.14732)
		(layer "In15.Cu")
		(net "P5E_CPU1_PE2_TX_DN<15>")
	)
	(segment
		(start 136.170416 -226.821238)
		(end 136.170416 -226.831144)
		(width 0.0889)
		(layer "In15.Cu")
		(net "P5E_CPU1_PE2_TX_DN<15>")
	)
	(segment
		(start 134.947914 -224.7138)
		(end 134.948676 -224.714308)
		(width 0.0889)
		(layer "In15.Cu")
		(net "P5E_CPU1_PE2_TX_DN<15>")
	)
	(segment
		(start 134.195566 -224.389442)
		(end 134.35203 -224.66046)
		(width 0.0889)
		(layer "In15.Cu")
		(net "P5E_CPU1_PE2_TX_DN<15>")
	)
	(segment
		(start 150.360126 -348.002098)
		(end 149.189694 -361.376722)
		(width 0.14732)
		(layer "In15.Cu")
		(net "P5E_CPU1_PE2_TX_DN<15>")
	)
	(segment
		(start 120.880632 -399.464022)
		(end 120.723914 -399.902934)
		(width 0.14732)
		(layer "In15.Cu")
		(net "P5E_CPU1_PE2_TX_DN<15>")
	)
	(segment
		(start 137.502138 -228.213412)
		(end 138.736324 -230.542338)
		(width 0.14732)
		(layer "In15.Cu")
		(net "P5E_CPU1_PE2_TX_DN<15>")
	)
	(segment
		(start 137.873994 -252.631194)
		(end 138.410188 -253.397258)
		(width 0.14732)
		(layer "In15.Cu")
		(net "P5E_CPU1_PE2_TX_DN<15>")
	)
	(segment
		(start 134.9375 -224.707704)
		(end 134.947914 -224.7138)
		(width 0.0889)
		(layer "In15.Cu")
		(net "P5E_CPU1_PE2_TX_DN<15>")
	)
	(segment
		(start 120.723914 -400.563588)
		(end 121.018554 -400.858228)
		(width 0.14732)
		(layer "In15.Cu")
		(net "P5E_CPU1_PE2_TX_DN<15>")
	)
	(segment
		(start 134.948676 -224.714308)
		(end 134.95401 -224.717356)
		(width 0.0889)
		(layer "In15.Cu")
		(net "P5E_CPU1_PE2_TX_DN<15>")
	)
	(segment
		(start 141.324838 -259.66928)
		(end 140.464032 -271.523714)
		(width 0.14732)
		(layer "In15.Cu")
		(net "P5E_CPU1_PE2_TX_DN<15>")
	)
	(segment
		(start 140.464032 -271.523714)
		(end 138.585194 -310.020208)
		(width 0.14732)
		(layer "In15.Cu")
		(net "P5E_CPU1_PE2_TX_DN<15>")
	)
	(segment
		(start 120.723914 -399.902934)
		(end 120.723914 -400.563588)
		(width 0.14732)
		(layer "In15.Cu")
		(net "P5E_CPU1_PE2_TX_DN<15>")
	)
	(segment
		(start 135.879078 -226.336606)
		(end 135.887968 -226.341686)
		(width 0.0889)
		(layer "In15.Cu")
		(net "P5E_CPU1_PE2_TX_DN<15>")
	)
	(segment
		(start 136.474454 -227.24491)
		(end 136.82472 -227.595176)
		(width 0.0889)
		(layer "In15.Cu")
		(net "P5E_CPU1_PE2_TX_DN<15>")
	)
	(segment
		(start 148.996146 -334.99171)
		(end 150.825454 -345.36253)
		(width 0.14732)
		(layer "In15.Cu")
		(net "P5E_CPU1_PE2_TX_DN<15>")
	)
	(segment
		(start 138.585194 -310.020208)
		(end 143.022828 -328.310494)
		(width 0.14732)
		(layer "In15.Cu")
		(net "P5E_CPU1_PE2_TX_DN<15>")
	)
	(segment
		(start 146.315176 -368.320066)
		(end 120.880632 -399.464022)
		(width 0.14732)
		(layer "In15.Cu")
		(net "P5E_CPU1_PE2_TX_DN<15>")
	)
	(segment
		(start 139.010898 -254.84709)
		(end 140.437108 -256.883662)
		(width 0.14732)
		(layer "In15.Cu")
		(net "P5E_CPU1_PE2_TX_DN<15>")
	)
	(arc
		(start 136.357868 -227.155502)
		(mid 136.414964 -227.193213)
		(end 136.467088 -227.237544)
		(width 0.0889)
		(layer "In15.Cu")
		(net "P5E_CPU1_PE2_TX_DN<15>")
	)
	(arc
		(start 136.467088 -227.237544)
		(mid 136.470788 -227.24121)
		(end 136.474454 -227.24491)
		(width 0.0889)
		(layer "In15.Cu")
		(net "P5E_CPU1_PE2_TX_DN<15>")
	)
	(arc
		(start 136.170416 -226.831144)
		(mid 136.218095 -227.014044)
		(end 136.348978 -227.150422)
		(width 0.0889)
		(layer "In15.Cu")
		(net "P5E_CPU1_PE2_TX_DN<15>")
	)
	(arc
		(start 135.700516 -226.017328)
		(mid 135.748195 -226.200228)
		(end 135.879078 -226.336606)
		(width 0.0889)
		(layer "In15.Cu")
		(net "P5E_CPU1_PE2_TX_DN<15>")
	)
	(arc
		(start 134.441184 -224.684336)
		(mid 134.692047 -224.638526)
		(end 134.9375 -224.707704)
		(width 0.0889)
		(layer "In15.Cu")
		(net "P5E_CPU1_PE2_TX_DN<15>")
	)
	(arc
		(start 135.230616 -225.203258)
		(mid 135.278295 -225.386158)
		(end 135.409178 -225.522536)
		(width 0.0889)
		(layer "In15.Cu")
		(net "P5E_CPU1_PE2_TX_DN<15>")
	)
	(arc
		(start 134.95401 -224.717356)
		(mid 135.156597 -224.923707)
		(end 135.230616 -225.203258)
		(width 0.0889)
		(layer "In15.Cu")
		(net "P5E_CPU1_PE2_TX_DN<15>")
	)
	(arc
		(start 135.418068 -225.527616)
		(mid 135.620354 -225.726597)
		(end 135.700516 -225.998786)
		(width 0.0889)
		(layer "In15.Cu")
		(net "P5E_CPU1_PE2_TX_DN<15>")
	)
	(arc
		(start 135.887968 -226.341686)
		(mid 136.092303 -226.544291)
		(end 136.170416 -226.821238)
		(width 0.0889)
		(layer "In15.Cu")
		(net "P5E_CPU1_PE2_TX_DN<15>")
	)
	(segment
		(start 133.725666 -224.111566)
		(end 133.725666 -223.575626)
		(width 0.13208)
		(layer "F.Cu")
		(net "P5E_CPU1_PE2_TX_DN<14>")
	)
	(segment
		(start 123.782836 -401.157186)
		(end 123.782836 -401.779994)
		(width 0.13208)
		(layer "F.Cu")
		(net "P5E_CPU1_PE2_TX_DN<14>")
	)
	(segment
		(start 124.081794 -400.858228)
		(end 123.782836 -401.157186)
		(width 0.13208)
		(layer "F.Cu")
		(net "P5E_CPU1_PE2_TX_DN<14>")
	)
	(segment
		(start 123.782836 -401.779994)
		(end 124.107194 -402.104352)
		(width 0.13208)
		(layer "F.Cu")
		(net "P5E_CPU1_PE2_TX_DN<14>")
	)
	(segment
		(start 139.90955 -247.946672)
		(end 139.53236 -248.210832)
		(width 0.14732)
		(layer "In15.Cu")
		(net "P5E_CPU1_PE2_TX_DN<14>")
	)
	(segment
		(start 139.53236 -248.210832)
		(end 139.238736 -248.504456)
		(width 0.14732)
		(layer "In15.Cu")
		(net "P5E_CPU1_PE2_TX_DN<14>")
	)
	(segment
		(start 134.852664 -223.899984)
		(end 134.867396 -223.891348)
		(width 0.0889)
		(layer "In15.Cu")
		(net "P5E_CPU1_PE2_TX_DN<14>")
	)
	(segment
		(start 139.238736 -249.878088)
		(end 139.360656 -250.000008)
		(width 0.14732)
		(layer "In15.Cu")
		(net "P5E_CPU1_PE2_TX_DN<14>")
	)
	(segment
		(start 136.348978 -225.522536)
		(end 136.357868 -225.527616)
		(width 0.0889)
		(layer "In15.Cu")
		(net "P5E_CPU1_PE2_TX_DN<14>")
	)
	(segment
		(start 147.199858 -368.761264)
		(end 123.787154 -399.66138)
		(width 0.14732)
		(layer "In15.Cu")
		(net "P5E_CPU1_PE2_TX_DN<14>")
	)
	(segment
		(start 150.16607 -361.59948)
		(end 147.199858 -368.761264)
		(width 0.14732)
		(layer "In15.Cu")
		(net "P5E_CPU1_PE2_TX_DN<14>")
	)
	(segment
		(start 136.82726 -226.34194)
		(end 136.857994 -226.359466)
		(width 0.0889)
		(layer "In15.Cu")
		(net "P5E_CPU1_PE2_TX_DN<14>")
	)
	(segment
		(start 135.418068 -223.899984)
		(end 135.424164 -223.90354)
		(width 0.0889)
		(layer "In15.Cu")
		(net "P5E_CPU1_PE2_TX_DN<14>")
	)
	(segment
		(start 137.420858 -226.92233)
		(end 137.479786 -226.92233)
		(width 0.0889)
		(layer "In15.Cu")
		(net "P5E_CPU1_PE2_TX_DN<14>")
	)
	(segment
		(start 142.349474 -259.488178)
		(end 139.542012 -309.951628)
		(width 0.14732)
		(layer "In15.Cu")
		(net "P5E_CPU1_PE2_TX_DN<14>")
	)
	(segment
		(start 133.569202 -223.846644)
		(end 133.590284 -223.924622)
		(width 0.0889)
		(layer "In15.Cu")
		(net "P5E_CPU1_PE2_TX_DN<14>")
	)
	(segment
		(start 136.857994 -226.359466)
		(end 137.420858 -226.92233)
		(width 0.0889)
		(layer "In15.Cu")
		(net "P5E_CPU1_PE2_TX_DN<14>")
	)
	(segment
		(start 141.555978 -244.340634)
		(end 140.529564 -247.552464)
		(width 0.14732)
		(layer "In15.Cu")
		(net "P5E_CPU1_PE2_TX_DN<14>")
	)
	(segment
		(start 123.787154 -400.563588)
		(end 124.081794 -400.858228)
		(width 0.14732)
		(layer "In15.Cu")
		(net "P5E_CPU1_PE2_TX_DN<14>")
	)
	(segment
		(start 140.529564 -247.552464)
		(end 139.90955 -247.946672)
		(width 0.14732)
		(layer "In15.Cu")
		(net "P5E_CPU1_PE2_TX_DN<14>")
	)
	(segment
		(start 137.49528 -226.937824)
		(end 139.874244 -229.316788)
		(width 0.14732)
		(layer "In15.Cu")
		(net "P5E_CPU1_PE2_TX_DN<14>")
	)
	(segment
		(start 139.238736 -248.504456)
		(end 139.238736 -249.878088)
		(width 0.14732)
		(layer "In15.Cu")
		(net "P5E_CPU1_PE2_TX_DN<14>")
	)
	(segment
		(start 139.360656 -250.436888)
		(end 139.238736 -250.558808)
		(width 0.14732)
		(layer "In15.Cu")
		(net "P5E_CPU1_PE2_TX_DN<14>")
	)
	(segment
		(start 123.787154 -399.66138)
		(end 123.787154 -400.563588)
		(width 0.14732)
		(layer "In15.Cu")
		(net "P5E_CPU1_PE2_TX_DN<14>")
	)
	(segment
		(start 151.361902 -347.933518)
		(end 150.16607 -361.59948)
		(width 0.14732)
		(layer "In15.Cu")
		(net "P5E_CPU1_PE2_TX_DN<14>")
	)
	(segment
		(start 139.360656 -250.000008)
		(end 139.360656 -250.436888)
		(width 0.14732)
		(layer "In15.Cu")
		(net "P5E_CPU1_PE2_TX_DN<14>")
	)
	(segment
		(start 141.558772 -256.63017)
		(end 141.57198 -256.677414)
		(width 0.14732)
		(layer "In15.Cu")
		(net "P5E_CPU1_PE2_TX_DN<14>")
	)
	(segment
		(start 139.542012 -309.951628)
		(end 143.896588 -327.811638)
		(width 0.14732)
		(layer "In15.Cu")
		(net "P5E_CPU1_PE2_TX_DN<14>")
	)
	(segment
		(start 137.479786 -226.92233)
		(end 137.49528 -226.937824)
		(width 0.0889)
		(layer "In15.Cu")
		(net "P5E_CPU1_PE2_TX_DN<14>")
	)
	(segment
		(start 151.834088 -345.256104)
		(end 151.361902 -347.933518)
		(width 0.14732)
		(layer "In15.Cu")
		(net "P5E_CPU1_PE2_TX_DN<14>")
	)
	(segment
		(start 140.251434 -254.154178)
		(end 140.928598 -255.752854)
		(width 0.14732)
		(layer "In15.Cu")
		(net "P5E_CPU1_PE2_TX_DN<14>")
	)
	(segment
		(start 133.725666 -223.575626)
		(end 133.569202 -223.846644)
		(width 0.0889)
		(layer "In15.Cu")
		(net "P5E_CPU1_PE2_TX_DN<14>")
	)
	(segment
		(start 140.928598 -255.752854)
		(end 141.558772 -256.63017)
		(width 0.14732)
		(layer "In15.Cu")
		(net "P5E_CPU1_PE2_TX_DN<14>")
	)
	(segment
		(start 141.57198 -256.677414)
		(end 141.571726 -256.677414)
		(width 0.14732)
		(layer "In15.Cu")
		(net "P5E_CPU1_PE2_TX_DN<14>")
	)
	(segment
		(start 135.879078 -224.70872)
		(end 135.887206 -224.713292)
		(width 0.0889)
		(layer "In15.Cu")
		(net "P5E_CPU1_PE2_TX_DN<14>")
	)
	(segment
		(start 140.61313 -230.937562)
		(end 141.551406 -244.291104)
		(width 0.14732)
		(layer "In15.Cu")
		(net "P5E_CPU1_PE2_TX_DN<14>")
	)
	(segment
		(start 143.896588 -327.811638)
		(end 149.965156 -334.659732)
		(width 0.14732)
		(layer "In15.Cu")
		(net "P5E_CPU1_PE2_TX_DN<14>")
	)
	(segment
		(start 136.170416 -225.193352)
		(end 136.170416 -225.203258)
		(width 0.0889)
		(layer "In15.Cu")
		(net "P5E_CPU1_PE2_TX_DN<14>")
	)
	(segment
		(start 141.551406 -244.291104)
		(end 141.555978 -244.340634)
		(width 0.14732)
		(layer "In15.Cu")
		(net "P5E_CPU1_PE2_TX_DN<14>")
	)
	(segment
		(start 139.238736 -251.20854)
		(end 140.251434 -254.154178)
		(width 0.14732)
		(layer "In15.Cu")
		(net "P5E_CPU1_PE2_TX_DN<14>")
	)
	(segment
		(start 136.640062 -225.998532)
		(end 136.640316 -226.017074)
		(width 0.0889)
		(layer "In15.Cu")
		(net "P5E_CPU1_PE2_TX_DN<14>")
	)
	(segment
		(start 139.874244 -229.316788)
		(end 140.61313 -230.937562)
		(width 0.14732)
		(layer "In15.Cu")
		(net "P5E_CPU1_PE2_TX_DN<14>")
	)
	(segment
		(start 141.571726 -256.677414)
		(end 142.349474 -259.488178)
		(width 0.14732)
		(layer "In15.Cu")
		(net "P5E_CPU1_PE2_TX_DN<14>")
	)
	(segment
		(start 149.965156 -334.659732)
		(end 151.834088 -345.256104)
		(width 0.14732)
		(layer "In15.Cu")
		(net "P5E_CPU1_PE2_TX_DN<14>")
	)
	(segment
		(start 135.887206 -224.713292)
		(end 135.887968 -224.7138)
		(width 0.0889)
		(layer "In15.Cu")
		(net "P5E_CPU1_PE2_TX_DN<14>")
	)
	(segment
		(start 139.238736 -250.558808)
		(end 139.238736 -251.20854)
		(width 0.14732)
		(layer "In15.Cu")
		(net "P5E_CPU1_PE2_TX_DN<14>")
	)
	(arc
		(start 136.640316 -226.029774)
		(mid 136.6934 -226.210045)
		(end 136.82726 -226.34194)
		(width 0.0889)
		(layer "In15.Cu")
		(net "P5E_CPU1_PE2_TX_DN<14>")
	)
	(arc
		(start 135.424164 -223.90354)
		(mid 135.626577 -224.109953)
		(end 135.700516 -224.389442)
		(width 0.0889)
		(layer "In15.Cu")
		(net "P5E_CPU1_PE2_TX_DN<14>")
	)
	(arc
		(start 136.640316 -226.017074)
		(mid 136.640262 -226.023424)
		(end 136.640316 -226.029774)
		(width 0.0889)
		(layer "In15.Cu")
		(net "P5E_CPU1_PE2_TX_DN<14>")
	)
	(arc
		(start 134.867396 -223.891348)
		(mid 135.143871 -223.824028)
		(end 135.418068 -223.899984)
		(width 0.0889)
		(layer "In15.Cu")
		(net "P5E_CPU1_PE2_TX_DN<14>")
	)
	(arc
		(start 134.478268 -223.899984)
		(mid 134.665466 -223.950127)
		(end 134.852664 -223.899984)
		(width 0.0889)
		(layer "In15.Cu")
		(net "P5E_CPU1_PE2_TX_DN<14>")
	)
	(arc
		(start 136.357868 -225.527616)
		(mid 136.55991 -225.726539)
		(end 136.640062 -225.998532)
		(width 0.0889)
		(layer "In15.Cu")
		(net "P5E_CPU1_PE2_TX_DN<14>")
	)
	(arc
		(start 136.170416 -225.203258)
		(mid 136.218095 -225.386158)
		(end 136.348978 -225.522536)
		(width 0.0889)
		(layer "In15.Cu")
		(net "P5E_CPU1_PE2_TX_DN<14>")
	)
	(arc
		(start 133.590284 -223.924622)
		(mid 133.75438 -223.948969)
		(end 133.912864 -223.899984)
		(width 0.0889)
		(layer "In15.Cu")
		(net "P5E_CPU1_PE2_TX_DN<14>")
	)
	(arc
		(start 135.700516 -224.389442)
		(mid 135.748195 -224.572342)
		(end 135.879078 -224.70872)
		(width 0.0889)
		(layer "In15.Cu")
		(net "P5E_CPU1_PE2_TX_DN<14>")
	)
	(arc
		(start 133.912864 -223.899984)
		(mid 134.195566 -223.824208)
		(end 134.478268 -223.899984)
		(width 0.0889)
		(layer "In15.Cu")
		(net "P5E_CPU1_PE2_TX_DN<14>")
	)
	(arc
		(start 135.887968 -224.7138)
		(mid 136.092303 -224.916405)
		(end 136.170416 -225.193352)
		(width 0.0889)
		(layer "In15.Cu")
		(net "P5E_CPU1_PE2_TX_DN<14>")
	)
	(segment
		(start 127.145034 -400.858228)
		(end 126.846076 -401.157186)
		(width 0.13208)
		(layer "F.Cu")
		(net "P5E_CPU1_PE2_TX_DN<13>")
	)
	(segment
		(start 126.846076 -401.779994)
		(end 127.170434 -402.104352)
		(width 0.13208)
		(layer "F.Cu")
		(net "P5E_CPU1_PE2_TX_DN<13>")
	)
	(segment
		(start 126.846076 -401.157186)
		(end 126.846076 -401.779994)
		(width 0.13208)
		(layer "F.Cu")
		(net "P5E_CPU1_PE2_TX_DN<13>")
	)
	(segment
		(start 132.315966 -224.925128)
		(end 132.315966 -224.389442)
		(width 0.13208)
		(layer "F.Cu")
		(net "P5E_CPU1_PE2_TX_DN<13>")
	)
	(segment
		(start 132.315712 -224.925382)
		(end 132.315966 -224.925128)
		(width 0.13208)
		(layer "F.Cu")
		(net "P5E_CPU1_PE2_TX_DN<13>")
	)
	(segment
		(start 136.358376 -223.900492)
		(end 136.36371 -223.90354)
		(width 0.0889)
		(layer "In15.Cu")
		(net "P5E_CPU1_PE2_TX_DN<13>")
	)
	(segment
		(start 141.62659 -254.990346)
		(end 142.621508 -256.411476)
		(width 0.14732)
		(layer "In15.Cu")
		(net "P5E_CPU1_PE2_TX_DN<13>")
	)
	(segment
		(start 140.917676 -253.23165)
		(end 141.02969 -253.549912)
		(width 0.14732)
		(layer "In15.Cu")
		(net "P5E_CPU1_PE2_TX_DN<13>")
	)
	(segment
		(start 126.850394 -399.758916)
		(end 126.850394 -400.563588)
		(width 0.14732)
		(layer "In15.Cu")
		(net "P5E_CPU1_PE2_TX_DN<13>")
	)
	(segment
		(start 144.77619 -327.326752)
		(end 150.836122 -334.08874)
		(width 0.14732)
		(layer "In15.Cu")
		(net "P5E_CPU1_PE2_TX_DN<13>")
	)
	(segment
		(start 136.827006 -224.713292)
		(end 136.827768 -224.7138)
		(width 0.0889)
		(layer "In15.Cu")
		(net "P5E_CPU1_PE2_TX_DN<13>")
	)
	(segment
		(start 140.553186 -309.736998)
		(end 144.77619 -327.326752)
		(width 0.14732)
		(layer "In15.Cu")
		(net "P5E_CPU1_PE2_TX_DN<13>")
	)
	(segment
		(start 132.47243 -224.66046)
		(end 132.550662 -224.681288)
		(width 0.0889)
		(layer "In15.Cu")
		(net "P5E_CPU1_PE2_TX_DN<13>")
	)
	(segment
		(start 152.377902 -348.078044)
		(end 152.377902 -348.07779)
		(width 0.14732)
		(layer "In15.Cu")
		(net "P5E_CPU1_PE2_TX_DN<13>")
	)
	(segment
		(start 140.598906 -252.136402)
		(end 140.917676 -253.23165)
		(width 0.14732)
		(layer "In15.Cu")
		(net "P5E_CPU1_PE2_TX_DN<13>")
	)
	(segment
		(start 141.869922 -246.471694)
		(end 141.192758 -248.550684)
		(width 0.14732)
		(layer "In15.Cu")
		(net "P5E_CPU1_PE2_TX_DN<13>")
	)
	(segment
		(start 132.315966 -224.389442)
		(end 132.47243 -224.66046)
		(width 0.0889)
		(layer "In15.Cu")
		(net "P5E_CPU1_PE2_TX_DN<13>")
	)
	(segment
		(start 137.239502 -225.514916)
		(end 137.530078 -225.805492)
		(width 0.0889)
		(layer "In15.Cu")
		(net "P5E_CPU1_PE2_TX_DN<13>")
	)
	(segment
		(start 142.621508 -256.411476)
		(end 143.375888 -259.351526)
		(width 0.14732)
		(layer "In15.Cu")
		(net "P5E_CPU1_PE2_TX_DN<13>")
	)
	(segment
		(start 140.550138 -251.24918)
		(end 140.598906 -252.136402)
		(width 0.14732)
		(layer "In15.Cu")
		(net "P5E_CPU1_PE2_TX_DN<13>")
	)
	(segment
		(start 126.850394 -400.563588)
		(end 127.145034 -400.858228)
		(width 0.14732)
		(layer "In15.Cu")
		(net "P5E_CPU1_PE2_TX_DN<13>")
	)
	(segment
		(start 148.019262 -369.28679)
		(end 126.850394 -399.758916)
		(width 0.14732)
		(layer "In15.Cu")
		(net "P5E_CPU1_PE2_TX_DN<13>")
	)
	(segment
		(start 132.973064 -223.899984)
		(end 132.981954 -223.894904)
		(width 0.0889)
		(layer "In15.Cu")
		(net "P5E_CPU1_PE2_TX_DN<13>")
	)
	(segment
		(start 141.192758 -248.550684)
		(end 140.694918 -249.262138)
		(width 0.14732)
		(layer "In15.Cu")
		(net "P5E_CPU1_PE2_TX_DN<13>")
	)
	(segment
		(start 132.690616 -224.389442)
		(end 132.690616 -224.379536)
		(width 0.0889)
		(layer "In15.Cu")
		(net "P5E_CPU1_PE2_TX_DN<13>")
	)
	(segment
		(start 136.357614 -223.899984)
		(end 136.358376 -223.900492)
		(width 0.0889)
		(layer "In15.Cu")
		(net "P5E_CPU1_PE2_TX_DN<13>")
	)
	(segment
		(start 136.818878 -224.70872)
		(end 136.827006 -224.713292)
		(width 0.0889)
		(layer "In15.Cu")
		(net "P5E_CPU1_PE2_TX_DN<13>")
	)
	(segment
		(start 136.170416 -223.557084)
		(end 136.170416 -223.584262)
		(width 0.0889)
		(layer "In15.Cu")
		(net "P5E_CPU1_PE2_TX_DN<13>")
	)
	(segment
		(start 143.375888 -259.351526)
		(end 140.553186 -309.736998)
		(width 0.14732)
		(layer "In15.Cu")
		(net "P5E_CPU1_PE2_TX_DN<13>")
	)
	(segment
		(start 137.109962 -225.203258)
		(end 137.109962 -225.211132)
		(width 0.0889)
		(layer "In15.Cu")
		(net "P5E_CPU1_PE2_TX_DN<13>")
	)
	(segment
		(start 140.549884 -251.24918)
		(end 140.550138 -251.24918)
		(width 0.14732)
		(layer "In15.Cu")
		(net "P5E_CPU1_PE2_TX_DN<13>")
	)
	(segment
		(start 138.202162 -226.031044)
		(end 140.490702 -228.319838)
		(width 0.14732)
		(layer "In15.Cu")
		(net "P5E_CPU1_PE2_TX_DN<13>")
	)
	(segment
		(start 140.694918 -249.262138)
		(end 140.500608 -250.361196)
		(width 0.14732)
		(layer "In15.Cu")
		(net "P5E_CPU1_PE2_TX_DN<13>")
	)
	(segment
		(start 142.55115 -244.380512)
		(end 141.869668 -246.471694)
		(width 0.14732)
		(layer "In15.Cu")
		(net "P5E_CPU1_PE2_TX_DN<13>")
	)
	(segment
		(start 141.869668 -246.471694)
		(end 141.869922 -246.471694)
		(width 0.14732)
		(layer "In15.Cu")
		(net "P5E_CPU1_PE2_TX_DN<13>")
	)
	(segment
		(start 137.917682 -225.805492)
		(end 138.12774 -226.01555)
		(width 0.0889)
		(layer "In15.Cu")
		(net "P5E_CPU1_PE2_TX_DN<13>")
	)
	(segment
		(start 141.02969 -253.549912)
		(end 141.62659 -254.990346)
		(width 0.14732)
		(layer "In15.Cu")
		(net "P5E_CPU1_PE2_TX_DN<13>")
	)
	(segment
		(start 140.490702 -228.319838)
		(end 141.586204 -230.721408)
		(width 0.14732)
		(layer "In15.Cu")
		(net "P5E_CPU1_PE2_TX_DN<13>")
	)
	(segment
		(start 150.836122 -334.08874)
		(end 152.840436 -345.45397)
		(width 0.14732)
		(layer "In15.Cu")
		(net "P5E_CPU1_PE2_TX_DN<13>")
	)
	(segment
		(start 138.12774 -226.01555)
		(end 138.186668 -226.01555)
		(width 0.0889)
		(layer "In15.Cu")
		(net "P5E_CPU1_PE2_TX_DN<13>")
	)
	(segment
		(start 141.586204 -230.721408)
		(end 142.55115 -244.380512)
		(width 0.14732)
		(layer "In15.Cu")
		(net "P5E_CPU1_PE2_TX_DN<13>")
	)
	(segment
		(start 152.840436 -345.45397)
		(end 152.377902 -348.078044)
		(width 0.14732)
		(layer "In15.Cu")
		(net "P5E_CPU1_PE2_TX_DN<13>")
	)
	(segment
		(start 152.377902 -348.07779)
		(end 151.17191 -361.862116)
		(width 0.14732)
		(layer "In15.Cu")
		(net "P5E_CPU1_PE2_TX_DN<13>")
	)
	(segment
		(start 133.160516 -223.575626)
		(end 133.160516 -223.557084)
		(width 0.0889)
		(layer "In15.Cu")
		(net "P5E_CPU1_PE2_TX_DN<13>")
	)
	(segment
		(start 140.500608 -250.361196)
		(end 140.549884 -251.24918)
		(width 0.14732)
		(layer "In15.Cu")
		(net "P5E_CPU1_PE2_TX_DN<13>")
	)
	(segment
		(start 151.17191 -361.862116)
		(end 148.019262 -369.28679)
		(width 0.14732)
		(layer "In15.Cu")
		(net "P5E_CPU1_PE2_TX_DN<13>")
	)
	(segment
		(start 138.186668 -226.01555)
		(end 138.202162 -226.031044)
		(width 0.0889)
		(layer "In15.Cu")
		(net "P5E_CPU1_PE2_TX_DN<13>")
	)
	(segment
		(start 137.530078 -225.805492)
		(end 137.917682 -225.805492)
		(width 0.0889)
		(layer "In15.Cu")
		(net "P5E_CPU1_PE2_TX_DN<13>")
	)
	(arc
		(start 136.827768 -224.7138)
		(mid 136.834399 -224.71782)
		(end 136.840976 -224.721928)
		(width 0.0889)
		(layer "In15.Cu")
		(net "P5E_CPU1_PE2_TX_DN<13>")
	)
	(arc
		(start 135.887968 -223.085914)
		(mid 136.090254 -223.284895)
		(end 136.170416 -223.557084)
		(width 0.0889)
		(layer "In15.Cu")
		(net "P5E_CPU1_PE2_TX_DN<13>")
	)
	(arc
		(start 137.109962 -225.211132)
		(mid 137.145327 -225.375564)
		(end 137.239502 -225.514916)
		(width 0.0889)
		(layer "In15.Cu")
		(net "P5E_CPU1_PE2_TX_DN<13>")
	)
	(arc
		(start 135.322564 -223.085914)
		(mid 135.605266 -223.010172)
		(end 135.887968 -223.085914)
		(width 0.0889)
		(layer "In15.Cu")
		(net "P5E_CPU1_PE2_TX_DN<13>")
	)
	(arc
		(start 132.981954 -223.894904)
		(mid 133.112868 -223.758544)
		(end 133.160516 -223.575626)
		(width 0.0889)
		(layer "In15.Cu")
		(net "P5E_CPU1_PE2_TX_DN<13>")
	)
	(arc
		(start 136.170416 -223.584262)
		(mid 136.222686 -223.766627)
		(end 136.357614 -223.899984)
		(width 0.0889)
		(layer "In15.Cu")
		(net "P5E_CPU1_PE2_TX_DN<13>")
	)
	(arc
		(start 133.160516 -223.557084)
		(mid 133.240678 -223.284895)
		(end 133.442964 -223.085914)
		(width 0.0889)
		(layer "In15.Cu")
		(net "P5E_CPU1_PE2_TX_DN<13>")
	)
	(arc
		(start 134.008368 -223.085914)
		(mid 134.195566 -223.136057)
		(end 134.382764 -223.085914)
		(width 0.0889)
		(layer "In15.Cu")
		(net "P5E_CPU1_PE2_TX_DN<13>")
	)
	(arc
		(start 132.550662 -224.681288)
		(mid 132.653807 -224.551263)
		(end 132.690616 -224.389442)
		(width 0.0889)
		(layer "In15.Cu")
		(net "P5E_CPU1_PE2_TX_DN<13>")
	)
	(arc
		(start 136.840976 -224.721928)
		(mid 137.038152 -224.927563)
		(end 137.109962 -225.203258)
		(width 0.0889)
		(layer "In15.Cu")
		(net "P5E_CPU1_PE2_TX_DN<13>")
	)
	(arc
		(start 134.948168 -223.085914)
		(mid 135.135366 -223.136057)
		(end 135.322564 -223.085914)
		(width 0.0889)
		(layer "In15.Cu")
		(net "P5E_CPU1_PE2_TX_DN<13>")
	)
	(arc
		(start 136.640316 -224.389442)
		(mid 136.687995 -224.572342)
		(end 136.818878 -224.70872)
		(width 0.0889)
		(layer "In15.Cu")
		(net "P5E_CPU1_PE2_TX_DN<13>")
	)
	(arc
		(start 136.36371 -223.90354)
		(mid 136.566297 -224.109891)
		(end 136.640316 -224.389442)
		(width 0.0889)
		(layer "In15.Cu")
		(net "P5E_CPU1_PE2_TX_DN<13>")
	)
	(arc
		(start 132.690616 -224.379536)
		(mid 132.768727 -224.102587)
		(end 132.973064 -223.899984)
		(width 0.0889)
		(layer "In15.Cu")
		(net "P5E_CPU1_PE2_TX_DN<13>")
	)
	(arc
		(start 134.382764 -223.085914)
		(mid 134.665466 -223.010172)
		(end 134.948168 -223.085914)
		(width 0.0889)
		(layer "In15.Cu")
		(net "P5E_CPU1_PE2_TX_DN<13>")
	)
	(arc
		(start 133.442964 -223.085914)
		(mid 133.725666 -223.010172)
		(end 134.008368 -223.085914)
		(width 0.0889)
		(layer "In15.Cu")
		(net "P5E_CPU1_PE2_TX_DN<13>")
	)
	(segment
		(start 131.846066 -224.111566)
		(end 131.846066 -223.57588)
		(width 0.13208)
		(layer "F.Cu")
		(net "P5E_CPU1_PE2_TX_DN<12>")
	)
	(segment
		(start 129.909316 -401.779994)
		(end 130.233674 -402.104352)
		(width 0.13208)
		(layer "F.Cu")
		(net "P5E_CPU1_PE2_TX_DN<12>")
	)
	(segment
		(start 130.208274 -400.858228)
		(end 129.909316 -401.157186)
		(width 0.13208)
		(layer "F.Cu")
		(net "P5E_CPU1_PE2_TX_DN<12>")
	)
	(segment
		(start 131.846066 -223.57588)
		(end 131.845812 -223.575626)
		(width 0.13208)
		(layer "F.Cu")
		(net "P5E_CPU1_PE2_TX_DN<12>")
	)
	(segment
		(start 129.909316 -401.157186)
		(end 129.909316 -401.779994)
		(width 0.13208)
		(layer "F.Cu")
		(net "P5E_CPU1_PE2_TX_DN<12>")
	)
	(segment
		(start 141.823948 -253.00559)
		(end 141.889734 -253.193042)
		(width 0.14732)
		(layer "In15.Cu")
		(net "P5E_CPU1_PE2_TX_DN<12>")
	)
	(segment
		(start 141.039342 -226.654106)
		(end 141.95044 -228.340412)
		(width 0.14732)
		(layer "In15.Cu")
		(net "P5E_CPU1_PE2_TX_DN<12>")
	)
	(segment
		(start 132.503164 -223.085914)
		(end 132.512054 -223.080834)
		(width 0.0889)
		(layer "In15.Cu")
		(net "P5E_CPU1_PE2_TX_DN<12>")
	)
	(segment
		(start 141.752066 -249.374152)
		(end 141.55928 -250.46559)
		(width 0.14732)
		(layer "In15.Cu")
		(net "P5E_CPU1_PE2_TX_DN<12>")
	)
	(segment
		(start 132.220462 -223.575626)
		(end 132.220462 -223.568006)
		(width 0.0889)
		(layer "In15.Cu")
		(net "P5E_CPU1_PE2_TX_DN<12>")
	)
	(segment
		(start 141.088618 -226.489006)
		(end 141.039342 -226.654106)
		(width 0.14732)
		(layer "In15.Cu")
		(net "P5E_CPU1_PE2_TX_DN<12>")
	)
	(segment
		(start 153.339546 -347.978476)
		(end 152.094184 -362.214922)
		(width 0.14732)
		(layer "In15.Cu")
		(net "P5E_CPU1_PE2_TX_DN<12>")
	)
	(segment
		(start 141.95044 -228.340412)
		(end 142.516606 -230.479854)
		(width 0.14732)
		(layer "In15.Cu")
		(net "P5E_CPU1_PE2_TX_DN<12>")
	)
	(segment
		(start 142.065502 -248.926096)
		(end 141.752066 -249.374152)
		(width 0.14732)
		(layer "In15.Cu")
		(net "P5E_CPU1_PE2_TX_DN<12>")
	)
	(segment
		(start 145.601436 -326.766936)
		(end 151.716232 -333.678276)
		(width 0.14732)
		(layer "In15.Cu")
		(net "P5E_CPU1_PE2_TX_DN<12>")
	)
	(segment
		(start 132.034026 -223.899476)
		(end 132.0419 -223.894904)
		(width 0.0889)
		(layer "In15.Cu")
		(net "P5E_CPU1_PE2_TX_DN<12>")
	)
	(segment
		(start 140.715238 -226.055174)
		(end 140.880846 -226.10445)
		(width 0.14732)
		(layer "In15.Cu")
		(net "P5E_CPU1_PE2_TX_DN<12>")
	)
	(segment
		(start 153.789126 -345.429332)
		(end 153.339546 -347.978476)
		(width 0.14732)
		(layer "In15.Cu")
		(net "P5E_CPU1_PE2_TX_DN<12>")
	)
	(segment
		(start 151.716232 -333.678276)
		(end 153.789126 -345.429332)
		(width 0.14732)
		(layer "In15.Cu")
		(net "P5E_CPU1_PE2_TX_DN<12>")
	)
	(segment
		(start 137.758678 -223.080834)
		(end 137.767568 -223.085914)
		(width 0.0889)
		(layer "In15.Cu")
		(net "P5E_CPU1_PE2_TX_DN<12>")
	)
	(segment
		(start 141.495272 -309.61965)
		(end 145.601436 -326.766936)
		(width 0.14732)
		(layer "In15.Cu")
		(net "P5E_CPU1_PE2_TX_DN<12>")
	)
	(segment
		(start 132.690616 -222.761556)
		(end 132.690616 -222.746062)
		(width 0.0889)
		(layer "In15.Cu")
		(net "P5E_CPU1_PE2_TX_DN<12>")
	)
	(segment
		(start 139.483592 -223.775778)
		(end 140.715238 -226.055174)
		(width 0.14732)
		(layer "In15.Cu")
		(net "P5E_CPU1_PE2_TX_DN<12>")
	)
	(segment
		(start 142.516606 -230.479854)
		(end 143.512032 -244.486938)
		(width 0.14732)
		(layer "In15.Cu")
		(net "P5E_CPU1_PE2_TX_DN<12>")
	)
	(segment
		(start 143.58366 -256.164588)
		(end 144.355058 -259.261102)
		(width 0.14732)
		(layer "In15.Cu")
		(net "P5E_CPU1_PE2_TX_DN<12>")
	)
	(segment
		(start 152.094184 -362.214922)
		(end 149.095714 -369.451382)
		(width 0.14732)
		(layer "In15.Cu")
		(net "P5E_CPU1_PE2_TX_DN<12>")
	)
	(segment
		(start 139.224258 -223.516698)
		(end 139.239752 -223.532192)
		(width 0.0889)
		(layer "In15.Cu")
		(net "P5E_CPU1_PE2_TX_DN<12>")
	)
	(segment
		(start 133.528054 -222.266002)
		(end 133.538468 -222.272098)
		(width 0.0889)
		(layer "In15.Cu")
		(net "P5E_CPU1_PE2_TX_DN<12>")
	)
	(segment
		(start 144.355058 -259.261102)
		(end 141.495272 -309.61965)
		(width 0.14732)
		(layer "In15.Cu")
		(net "P5E_CPU1_PE2_TX_DN<12>")
	)
	(segment
		(start 141.889734 -253.193042)
		(end 142.450312 -254.545338)
		(width 0.14732)
		(layer "In15.Cu")
		(net "P5E_CPU1_PE2_TX_DN<12>")
	)
	(segment
		(start 142.450312 -254.545338)
		(end 143.58366 -256.164588)
		(width 0.14732)
		(layer "In15.Cu")
		(net "P5E_CPU1_PE2_TX_DN<12>")
	)
	(segment
		(start 140.880846 -226.10445)
		(end 141.088618 -226.489006)
		(width 0.14732)
		(layer "In15.Cu")
		(net "P5E_CPU1_PE2_TX_DN<12>")
	)
	(segment
		(start 132.03301 -223.899984)
		(end 132.034026 -223.899476)
		(width 0.0889)
		(layer "In15.Cu")
		(net "P5E_CPU1_PE2_TX_DN<12>")
	)
	(segment
		(start 136.73201 -222.272098)
		(end 136.742424 -222.266002)
		(width 0.0889)
		(layer "In15.Cu")
		(net "P5E_CPU1_PE2_TX_DN<12>")
	)
	(segment
		(start 131.689348 -223.846644)
		(end 131.71043 -223.924622)
		(width 0.0889)
		(layer "In15.Cu")
		(net "P5E_CPU1_PE2_TX_DN<12>")
	)
	(segment
		(start 129.913634 -399.751042)
		(end 129.913634 -400.563588)
		(width 0.14732)
		(layer "In15.Cu")
		(net "P5E_CPU1_PE2_TX_DN<12>")
	)
	(segment
		(start 138.824462 -223.17583)
		(end 139.16533 -223.516698)
		(width 0.0889)
		(layer "In15.Cu")
		(net "P5E_CPU1_PE2_TX_DN<12>")
	)
	(segment
		(start 131.845812 -223.575626)
		(end 131.689348 -223.846644)
		(width 0.0889)
		(layer "In15.Cu")
		(net "P5E_CPU1_PE2_TX_DN<12>")
	)
	(segment
		(start 141.55928 -250.46559)
		(end 141.55928 -252.098048)
		(width 0.14732)
		(layer "In15.Cu")
		(net "P5E_CPU1_PE2_TX_DN<12>")
	)
	(segment
		(start 149.095714 -369.451382)
		(end 129.913634 -399.751042)
		(width 0.14732)
		(layer "In15.Cu")
		(net "P5E_CPU1_PE2_TX_DN<12>")
	)
	(segment
		(start 141.55928 -252.098048)
		(end 141.823948 -253.00559)
		(width 0.14732)
		(layer "In15.Cu")
		(net "P5E_CPU1_PE2_TX_DN<12>")
	)
	(segment
		(start 143.512032 -244.486938)
		(end 142.786608 -246.71274)
		(width 0.14732)
		(layer "In15.Cu")
		(net "P5E_CPU1_PE2_TX_DN<12>")
	)
	(segment
		(start 137.297668 -222.272098)
		(end 137.303764 -222.275654)
		(width 0.0889)
		(layer "In15.Cu")
		(net "P5E_CPU1_PE2_TX_DN<12>")
	)
	(segment
		(start 135.407654 -222.266002)
		(end 135.418068 -222.272098)
		(width 0.0889)
		(layer "In15.Cu")
		(net "P5E_CPU1_PE2_TX_DN<12>")
	)
	(segment
		(start 139.239752 -223.532192)
		(end 139.483592 -223.775778)
		(width 0.14732)
		(layer "In15.Cu")
		(net "P5E_CPU1_PE2_TX_DN<12>")
	)
	(segment
		(start 136.3472 -222.266002)
		(end 136.357614 -222.272098)
		(width 0.0889)
		(layer "In15.Cu")
		(net "P5E_CPU1_PE2_TX_DN<12>")
	)
	(segment
		(start 129.913634 -400.563588)
		(end 130.208274 -400.858228)
		(width 0.14732)
		(layer "In15.Cu")
		(net "P5E_CPU1_PE2_TX_DN<12>")
	)
	(segment
		(start 139.16533 -223.516698)
		(end 139.224258 -223.516698)
		(width 0.0889)
		(layer "In15.Cu")
		(net "P5E_CPU1_PE2_TX_DN<12>")
	)
	(segment
		(start 134.4676 -222.266002)
		(end 134.478014 -222.272098)
		(width 0.0889)
		(layer "In15.Cu")
		(net "P5E_CPU1_PE2_TX_DN<12>")
	)
	(segment
		(start 142.786608 -246.71274)
		(end 142.065502 -248.926096)
		(width 0.14732)
		(layer "In15.Cu")
		(net "P5E_CPU1_PE2_TX_DN<12>")
	)
	(arc
		(start 134.85241 -222.272098)
		(mid 135.129223 -222.196228)
		(end 135.407654 -222.266002)
		(width 0.0889)
		(layer "In15.Cu")
		(net "P5E_CPU1_PE2_TX_DN<12>")
	)
	(arc
		(start 138.141964 -223.085914)
		(mid 138.498487 -223.015011)
		(end 138.824462 -223.17583)
		(width 0.0889)
		(layer "In15.Cu")
		(net "P5E_CPU1_PE2_TX_DN<12>")
	)
	(arc
		(start 132.220462 -223.568006)
		(mid 132.298091 -223.289593)
		(end 132.503164 -223.085914)
		(width 0.0889)
		(layer "In15.Cu")
		(net "P5E_CPU1_PE2_TX_DN<12>")
	)
	(arc
		(start 132.97281 -222.272098)
		(mid 133.249623 -222.196228)
		(end 133.528054 -222.266002)
		(width 0.0889)
		(layer "In15.Cu")
		(net "P5E_CPU1_PE2_TX_DN<12>")
	)
	(arc
		(start 132.512054 -223.080834)
		(mid 132.642968 -222.944474)
		(end 132.690616 -222.761556)
		(width 0.0889)
		(layer "In15.Cu")
		(net "P5E_CPU1_PE2_TX_DN<12>")
	)
	(arc
		(start 136.357614 -222.272098)
		(mid 136.544812 -222.322241)
		(end 136.73201 -222.272098)
		(width 0.0889)
		(layer "In15.Cu")
		(net "P5E_CPU1_PE2_TX_DN<12>")
	)
	(arc
		(start 133.538468 -222.272098)
		(mid 133.725666 -222.322241)
		(end 133.912864 -222.272098)
		(width 0.0889)
		(layer "In15.Cu")
		(net "P5E_CPU1_PE2_TX_DN<12>")
	)
	(arc
		(start 134.478014 -222.272098)
		(mid 134.665212 -222.322241)
		(end 134.85241 -222.272098)
		(width 0.0889)
		(layer "In15.Cu")
		(net "P5E_CPU1_PE2_TX_DN<12>")
	)
	(arc
		(start 137.580116 -222.761556)
		(mid 137.627795 -222.944456)
		(end 137.758678 -223.080834)
		(width 0.0889)
		(layer "In15.Cu")
		(net "P5E_CPU1_PE2_TX_DN<12>")
	)
	(arc
		(start 136.742424 -222.266002)
		(mid 137.020856 -222.196156)
		(end 137.297668 -222.272098)
		(width 0.0889)
		(layer "In15.Cu")
		(net "P5E_CPU1_PE2_TX_DN<12>")
	)
	(arc
		(start 132.690616 -222.746062)
		(mid 132.769986 -222.472328)
		(end 132.97281 -222.272098)
		(width 0.0889)
		(layer "In15.Cu")
		(net "P5E_CPU1_PE2_TX_DN<12>")
	)
	(arc
		(start 135.792464 -222.272098)
		(mid 136.069023 -222.196355)
		(end 136.3472 -222.266002)
		(width 0.0889)
		(layer "In15.Cu")
		(net "P5E_CPU1_PE2_TX_DN<12>")
	)
	(arc
		(start 133.912864 -222.272098)
		(mid 134.189423 -222.196355)
		(end 134.4676 -222.266002)
		(width 0.0889)
		(layer "In15.Cu")
		(net "P5E_CPU1_PE2_TX_DN<12>")
	)
	(arc
		(start 132.0419 -223.894904)
		(mid 132.172814 -223.758544)
		(end 132.220462 -223.575626)
		(width 0.0889)
		(layer "In15.Cu")
		(net "P5E_CPU1_PE2_TX_DN<12>")
	)
	(arc
		(start 131.71043 -223.924622)
		(mid 131.874526 -223.948969)
		(end 132.03301 -223.899984)
		(width 0.0889)
		(layer "In15.Cu")
		(net "P5E_CPU1_PE2_TX_DN<12>")
	)
	(arc
		(start 137.767568 -223.085914)
		(mid 137.954766 -223.136057)
		(end 138.141964 -223.085914)
		(width 0.0889)
		(layer "In15.Cu")
		(net "P5E_CPU1_PE2_TX_DN<12>")
	)
	(arc
		(start 135.418068 -222.272098)
		(mid 135.605266 -222.322241)
		(end 135.792464 -222.272098)
		(width 0.0889)
		(layer "In15.Cu")
		(net "P5E_CPU1_PE2_TX_DN<12>")
	)
	(arc
		(start 137.303764 -222.275654)
		(mid 137.506177 -222.482067)
		(end 137.580116 -222.761556)
		(width 0.0889)
		(layer "In15.Cu")
		(net "P5E_CPU1_PE2_TX_DN<12>")
	)
	(segment
		(start 130.436112 -224.389696)
		(end 130.436366 -224.389442)
		(width 0.13208)
		(layer "F.Cu")
		(net "P5E_CPU1_PE2_TX_DN<11>")
	)
	(segment
		(start 132.972556 -401.779994)
		(end 133.296914 -402.104352)
		(width 0.13208)
		(layer "F.Cu")
		(net "P5E_CPU1_PE2_TX_DN<11>")
	)
	(segment
		(start 133.271514 -400.858228)
		(end 132.972556 -401.157186)
		(width 0.13208)
		(layer "F.Cu")
		(net "P5E_CPU1_PE2_TX_DN<11>")
	)
	(segment
		(start 130.436112 -224.925382)
		(end 130.436112 -224.389696)
		(width 0.13208)
		(layer "F.Cu")
		(net "P5E_CPU1_PE2_TX_DN<11>")
	)
	(segment
		(start 132.972556 -401.157186)
		(end 132.972556 -401.779994)
		(width 0.13208)
		(layer "F.Cu")
		(net "P5E_CPU1_PE2_TX_DN<11>")
	)
	(segment
		(start 143.506698 -230.577136)
		(end 143.988536 -237.564422)
		(width 0.14732)
		(layer "In15.Cu")
		(net "P5E_CPU1_PE2_TX_DN<11>")
	)
	(segment
		(start 132.50037 -221.459806)
		(end 132.503164 -221.458282)
		(width 0.0889)
		(layer "In15.Cu")
		(net "P5E_CPU1_PE2_TX_DN<11>")
	)
	(segment
		(start 142.57528 -250.59894)
		(end 142.57528 -252.258322)
		(width 0.14732)
		(layer "In15.Cu")
		(net "P5E_CPU1_PE2_TX_DN<11>")
	)
	(segment
		(start 130.436366 -224.389442)
		(end 130.59283 -224.66046)
		(width 0.0889)
		(layer "In15.Cu")
		(net "P5E_CPU1_PE2_TX_DN<11>")
	)
	(segment
		(start 132.976874 -400.563588)
		(end 133.271514 -400.858228)
		(width 0.14732)
		(layer "In15.Cu")
		(net "P5E_CPU1_PE2_TX_DN<11>")
	)
	(segment
		(start 139.73048 -222.394018)
		(end 139.745974 -222.409512)
		(width 0.0889)
		(layer "In15.Cu")
		(net "P5E_CPU1_PE2_TX_DN<11>")
	)
	(segment
		(start 145.398744 -259.170932)
		(end 142.455392 -309.53837)
		(width 0.14732)
		(layer "In15.Cu")
		(net "P5E_CPU1_PE2_TX_DN<11>")
	)
	(segment
		(start 143.988536 -237.564422)
		(end 144.471898 -244.579394)
		(width 0.14732)
		(layer "In15.Cu")
		(net "P5E_CPU1_PE2_TX_DN<11>")
	)
	(segment
		(start 137.288778 -220.639132)
		(end 137.297668 -220.644212)
		(width 0.0889)
		(layer "In15.Cu")
		(net "P5E_CPU1_PE2_TX_DN<11>")
	)
	(segment
		(start 140.26896 -222.932498)
		(end 142.483586 -226.701096)
		(width 0.14732)
		(layer "In15.Cu")
		(net "P5E_CPU1_PE2_TX_DN<11>")
	)
	(segment
		(start 136.828276 -219.830904)
		(end 136.83361 -219.833952)
		(width 0.0889)
		(layer "In15.Cu")
		(net "P5E_CPU1_PE2_TX_DN<11>")
	)
	(segment
		(start 144.68729 -255.956054)
		(end 145.398744 -259.170932)
		(width 0.14732)
		(layer "In15.Cu")
		(net "P5E_CPU1_PE2_TX_DN<11>")
	)
	(segment
		(start 132.504688 -221.45752)
		(end 132.512054 -221.453202)
		(width 0.0889)
		(layer "In15.Cu")
		(net "P5E_CPU1_PE2_TX_DN<11>")
	)
	(segment
		(start 134.382764 -219.830396)
		(end 134.397496 -219.82176)
		(width 0.0889)
		(layer "In15.Cu")
		(net "P5E_CPU1_PE2_TX_DN<11>")
	)
	(segment
		(start 139.745974 -222.409512)
		(end 140.26896 -222.932498)
		(width 0.14732)
		(layer "In15.Cu")
		(net "P5E_CPU1_PE2_TX_DN<11>")
	)
	(segment
		(start 131.750816 -222.761556)
		(end 131.750816 -222.746062)
		(width 0.0889)
		(layer "In15.Cu")
		(net "P5E_CPU1_PE2_TX_DN<11>")
	)
	(segment
		(start 149.675088 -370.477796)
		(end 132.976874 -399.633948)
		(width 0.14732)
		(layer "In15.Cu")
		(net "P5E_CPU1_PE2_TX_DN<11>")
	)
	(segment
		(start 142.455392 -309.53837)
		(end 146.466814 -326.220836)
		(width 0.14732)
		(layer "In15.Cu")
		(net "P5E_CPU1_PE2_TX_DN<11>")
	)
	(segment
		(start 136.8171 -219.8243)
		(end 136.827514 -219.830396)
		(width 0.0889)
		(layer "In15.Cu")
		(net "P5E_CPU1_PE2_TX_DN<11>")
	)
	(segment
		(start 154.388312 -348.696788)
		(end 153.186638 -362.432346)
		(width 0.14732)
		(layer "In15.Cu")
		(net "P5E_CPU1_PE2_TX_DN<11>")
	)
	(segment
		(start 132.976874 -399.633948)
		(end 132.976874 -400.563588)
		(width 0.14732)
		(layer "In15.Cu")
		(net "P5E_CPU1_PE2_TX_DN<11>")
	)
	(segment
		(start 142.759176 -249.557286)
		(end 142.57528 -250.59894)
		(width 0.14732)
		(layer "In15.Cu")
		(net "P5E_CPU1_PE2_TX_DN<11>")
	)
	(segment
		(start 132.497068 -221.461838)
		(end 132.50037 -221.459806)
		(width 0.0889)
		(layer "In15.Cu")
		(net "P5E_CPU1_PE2_TX_DN<11>")
	)
	(segment
		(start 132.03301 -222.272098)
		(end 132.0419 -222.267018)
		(width 0.0889)
		(layer "In15.Cu")
		(net "P5E_CPU1_PE2_TX_DN<11>")
	)
	(segment
		(start 146.466814 -326.220836)
		(end 152.766268 -333.44739)
		(width 0.14732)
		(layer "In15.Cu")
		(net "P5E_CPU1_PE2_TX_DN<11>")
	)
	(segment
		(start 136.827514 -219.830396)
		(end 136.828276 -219.830904)
		(width 0.0889)
		(layer "In15.Cu")
		(net "P5E_CPU1_PE2_TX_DN<11>")
	)
	(segment
		(start 144.471898 -244.579394)
		(end 142.933166 -249.308366)
		(width 0.14732)
		(layer "In15.Cu")
		(net "P5E_CPU1_PE2_TX_DN<11>")
	)
	(segment
		(start 131.563364 -223.085914)
		(end 131.572254 -223.080834)
		(width 0.0889)
		(layer "In15.Cu")
		(net "P5E_CPU1_PE2_TX_DN<11>")
	)
	(segment
		(start 153.186638 -362.432346)
		(end 149.675088 -370.477796)
		(width 0.14732)
		(layer "In15.Cu")
		(net "P5E_CPU1_PE2_TX_DN<11>")
	)
	(segment
		(start 152.766268 -333.44739)
		(end 154.92222 -345.669616)
		(width 0.14732)
		(layer "In15.Cu")
		(net "P5E_CPU1_PE2_TX_DN<11>")
	)
	(segment
		(start 132.973064 -220.644212)
		(end 132.981954 -220.639132)
		(width 0.0889)
		(layer "In15.Cu")
		(net "P5E_CPU1_PE2_TX_DN<11>")
	)
	(segment
		(start 138.519916 -221.115382)
		(end 138.519916 -221.133924)
		(width 0.0889)
		(layer "In15.Cu")
		(net "P5E_CPU1_PE2_TX_DN<11>")
	)
	(segment
		(start 143.105632 -253.697232)
		(end 144.68729 -255.956054)
		(width 0.14732)
		(layer "In15.Cu")
		(net "P5E_CPU1_PE2_TX_DN<11>")
	)
	(segment
		(start 130.811016 -224.389442)
		(end 130.811016 -224.379536)
		(width 0.0889)
		(layer "In15.Cu")
		(net "P5E_CPU1_PE2_TX_DN<11>")
	)
	(segment
		(start 142.775432 -252.901196)
		(end 143.105632 -253.697232)
		(width 0.14732)
		(layer "In15.Cu")
		(net "P5E_CPU1_PE2_TX_DN<11>")
	)
	(segment
		(start 131.280662 -223.584262)
		(end 131.280662 -223.561402)
		(width 0.0889)
		(layer "In15.Cu")
		(net "P5E_CPU1_PE2_TX_DN<11>")
	)
	(segment
		(start 130.59283 -224.66046)
		(end 130.671062 -224.681288)
		(width 0.0889)
		(layer "In15.Cu")
		(net "P5E_CPU1_PE2_TX_DN<11>")
	)
	(segment
		(start 142.483586 -226.701096)
		(end 142.762224 -227.681536)
		(width 0.14732)
		(layer "In15.Cu")
		(net "P5E_CPU1_PE2_TX_DN<11>")
	)
	(segment
		(start 154.92222 -345.669616)
		(end 154.388312 -348.696788)
		(width 0.14732)
		(layer "In15.Cu")
		(net "P5E_CPU1_PE2_TX_DN<11>")
	)
	(segment
		(start 133.160516 -220.319854)
		(end 133.160516 -220.309948)
		(width 0.0889)
		(layer "In15.Cu")
		(net "P5E_CPU1_PE2_TX_DN<11>")
	)
	(segment
		(start 139.670536 -222.394018)
		(end 139.73048 -222.394018)
		(width 0.0889)
		(layer "In15.Cu")
		(net "P5E_CPU1_PE2_TX_DN<11>")
	)
	(segment
		(start 132.690616 -221.133924)
		(end 132.690616 -221.115382)
		(width 0.0889)
		(layer "In15.Cu")
		(net "P5E_CPU1_PE2_TX_DN<11>")
	)
	(segment
		(start 142.762224 -227.681536)
		(end 143.506698 -230.577136)
		(width 0.14732)
		(layer "In15.Cu")
		(net "P5E_CPU1_PE2_TX_DN<11>")
	)
	(segment
		(start 132.503164 -221.458282)
		(end 132.504688 -221.45752)
		(width 0.0889)
		(layer "In15.Cu")
		(net "P5E_CPU1_PE2_TX_DN<11>")
	)
	(segment
		(start 142.933166 -249.308366)
		(end 142.759176 -249.557286)
		(width 0.14732)
		(layer "In15.Cu")
		(net "P5E_CPU1_PE2_TX_DN<11>")
	)
	(segment
		(start 138.824462 -221.547944)
		(end 139.670536 -222.394018)
		(width 0.0889)
		(layer "In15.Cu")
		(net "P5E_CPU1_PE2_TX_DN<11>")
	)
	(segment
		(start 142.57528 -252.258322)
		(end 142.775432 -252.901196)
		(width 0.14732)
		(layer "In15.Cu")
		(net "P5E_CPU1_PE2_TX_DN<11>")
	)
	(arc
		(start 131.750816 -222.746062)
		(mid 131.830186 -222.472328)
		(end 132.03301 -222.272098)
		(width 0.0889)
		(layer "In15.Cu")
		(net "P5E_CPU1_PE2_TX_DN<11>")
	)
	(arc
		(start 135.887968 -219.830396)
		(mid 136.075166 -219.880539)
		(end 136.262364 -219.830396)
		(width 0.0889)
		(layer "In15.Cu")
		(net "P5E_CPU1_PE2_TX_DN<11>")
	)
	(arc
		(start 136.83361 -219.833952)
		(mid 137.036197 -220.040303)
		(end 137.110216 -220.319854)
		(width 0.0889)
		(layer "In15.Cu")
		(net "P5E_CPU1_PE2_TX_DN<11>")
	)
	(arc
		(start 137.297668 -220.644212)
		(mid 137.484866 -220.694355)
		(end 137.672064 -220.644212)
		(width 0.0889)
		(layer "In15.Cu")
		(net "P5E_CPU1_PE2_TX_DN<11>")
	)
	(arc
		(start 138.698478 -221.453202)
		(mid 138.764782 -221.496168)
		(end 138.824462 -221.547944)
		(width 0.0889)
		(layer "In15.Cu")
		(net "P5E_CPU1_PE2_TX_DN<11>")
	)
	(arc
		(start 132.0419 -222.267018)
		(mid 132.172814 -222.130658)
		(end 132.220462 -221.94774)
		(width 0.0889)
		(layer "In15.Cu")
		(net "P5E_CPU1_PE2_TX_DN<11>")
	)
	(arc
		(start 135.322564 -219.830396)
		(mid 135.605266 -219.75462)
		(end 135.887968 -219.830396)
		(width 0.0889)
		(layer "In15.Cu")
		(net "P5E_CPU1_PE2_TX_DN<11>")
	)
	(arc
		(start 130.811016 -224.379536)
		(mid 130.889127 -224.102587)
		(end 131.093464 -223.899984)
		(width 0.0889)
		(layer "In15.Cu")
		(net "P5E_CPU1_PE2_TX_DN<11>")
	)
	(arc
		(start 131.280662 -223.561402)
		(mid 131.359881 -223.286717)
		(end 131.563364 -223.085914)
		(width 0.0889)
		(layer "In15.Cu")
		(net "P5E_CPU1_PE2_TX_DN<11>")
	)
	(arc
		(start 137.672064 -220.644212)
		(mid 137.954766 -220.56847)
		(end 138.237468 -220.644212)
		(width 0.0889)
		(layer "In15.Cu")
		(net "P5E_CPU1_PE2_TX_DN<11>")
	)
	(arc
		(start 134.008368 -219.830396)
		(mid 134.195566 -219.880539)
		(end 134.382764 -219.830396)
		(width 0.0889)
		(layer "In15.Cu")
		(net "P5E_CPU1_PE2_TX_DN<11>")
	)
	(arc
		(start 132.981954 -220.639132)
		(mid 133.112868 -220.502772)
		(end 133.160516 -220.319854)
		(width 0.0889)
		(layer "In15.Cu")
		(net "P5E_CPU1_PE2_TX_DN<11>")
	)
	(arc
		(start 138.519916 -221.133924)
		(mid 138.567595 -221.316824)
		(end 138.698478 -221.453202)
		(width 0.0889)
		(layer "In15.Cu")
		(net "P5E_CPU1_PE2_TX_DN<11>")
	)
	(arc
		(start 136.262364 -219.830396)
		(mid 136.538923 -219.754653)
		(end 136.8171 -219.8243)
		(width 0.0889)
		(layer "In15.Cu")
		(net "P5E_CPU1_PE2_TX_DN<11>")
	)
	(arc
		(start 133.160516 -220.309948)
		(mid 133.238627 -220.032999)
		(end 133.442964 -219.830396)
		(width 0.0889)
		(layer "In15.Cu")
		(net "P5E_CPU1_PE2_TX_DN<11>")
	)
	(arc
		(start 134.397496 -219.82176)
		(mid 134.673971 -219.75444)
		(end 134.948168 -219.830396)
		(width 0.0889)
		(layer "In15.Cu")
		(net "P5E_CPU1_PE2_TX_DN<11>")
	)
	(arc
		(start 133.442964 -219.830396)
		(mid 133.725666 -219.75462)
		(end 134.008368 -219.830396)
		(width 0.0889)
		(layer "In15.Cu")
		(net "P5E_CPU1_PE2_TX_DN<11>")
	)
	(arc
		(start 137.110216 -220.319854)
		(mid 137.157895 -220.502754)
		(end 137.288778 -220.639132)
		(width 0.0889)
		(layer "In15.Cu")
		(net "P5E_CPU1_PE2_TX_DN<11>")
	)
	(arc
		(start 131.572254 -223.080834)
		(mid 131.703168 -222.944474)
		(end 131.750816 -222.761556)
		(width 0.0889)
		(layer "In15.Cu")
		(net "P5E_CPU1_PE2_TX_DN<11>")
	)
	(arc
		(start 134.948168 -219.830396)
		(mid 135.135366 -219.880539)
		(end 135.322564 -219.830396)
		(width 0.0889)
		(layer "In15.Cu")
		(net "P5E_CPU1_PE2_TX_DN<11>")
	)
	(arc
		(start 130.671062 -224.681288)
		(mid 130.774207 -224.551263)
		(end 130.811016 -224.389442)
		(width 0.0889)
		(layer "In15.Cu")
		(net "P5E_CPU1_PE2_TX_DN<11>")
	)
	(arc
		(start 132.220462 -221.94774)
		(mid 132.294453 -221.668174)
		(end 132.497068 -221.461838)
		(width 0.0889)
		(layer "In15.Cu")
		(net "P5E_CPU1_PE2_TX_DN<11>")
	)
	(arc
		(start 131.093464 -223.899984)
		(mid 131.228397 -223.76663)
		(end 131.280662 -223.584262)
		(width 0.0889)
		(layer "In15.Cu")
		(net "P5E_CPU1_PE2_TX_DN<11>")
	)
	(arc
		(start 138.237468 -220.644212)
		(mid 138.439754 -220.843193)
		(end 138.519916 -221.115382)
		(width 0.0889)
		(layer "In15.Cu")
		(net "P5E_CPU1_PE2_TX_DN<11>")
	)
	(arc
		(start 132.690616 -221.115382)
		(mid 132.770778 -220.843193)
		(end 132.973064 -220.644212)
		(width 0.0889)
		(layer "In15.Cu")
		(net "P5E_CPU1_PE2_TX_DN<11>")
	)
	(arc
		(start 132.512054 -221.453202)
		(mid 132.642968 -221.316842)
		(end 132.690616 -221.133924)
		(width 0.0889)
		(layer "In15.Cu")
		(net "P5E_CPU1_PE2_TX_DN<11>")
	)
	(segment
		(start 129.966466 -223.57588)
		(end 129.966212 -223.575626)
		(width 0.13208)
		(layer "F.Cu")
		(net "P5E_CPU1_PE2_TX_DN<10>")
	)
	(segment
		(start 136.035796 -401.157186)
		(end 136.035796 -401.779994)
		(width 0.13208)
		(layer "F.Cu")
		(net "P5E_CPU1_PE2_TX_DN<10>")
	)
	(segment
		(start 136.035796 -401.779994)
		(end 136.360154 -402.104352)
		(width 0.13208)
		(layer "F.Cu")
		(net "P5E_CPU1_PE2_TX_DN<10>")
	)
	(segment
		(start 136.334754 -400.858228)
		(end 136.035796 -401.157186)
		(width 0.13208)
		(layer "F.Cu")
		(net "P5E_CPU1_PE2_TX_DN<10>")
	)
	(segment
		(start 129.966466 -224.111566)
		(end 129.966466 -223.57588)
		(width 0.13208)
		(layer "F.Cu")
		(net "P5E_CPU1_PE2_TX_DN<10>")
	)
	(segment
		(start 140.918438 -221.955614)
		(end 142.628874 -223.66605)
		(width 0.14732)
		(layer "In15.Cu")
		(net "P5E_CPU1_PE2_TX_DN<10>")
	)
	(segment
		(start 143.51508 -252.118622)
		(end 143.650462 -252.582426)
		(width 0.14732)
		(layer "In15.Cu")
		(net "P5E_CPU1_PE2_TX_DN<10>")
	)
	(segment
		(start 133.528054 -219.010484)
		(end 133.538468 -219.01658)
		(width 0.0889)
		(layer "In15.Cu")
		(net "P5E_CPU1_PE2_TX_DN<10>")
	)
	(segment
		(start 137.579862 -219.490544)
		(end 137.579862 -219.506038)
		(width 0.0889)
		(layer "In15.Cu")
		(net "P5E_CPU1_PE2_TX_DN<10>")
	)
	(segment
		(start 145.583402 -255.600454)
		(end 146.405346 -259.067808)
		(width 0.14732)
		(layer "In15.Cu")
		(net "P5E_CPU1_PE2_TX_DN<10>")
	)
	(segment
		(start 143.80591 -249.685048)
		(end 143.805402 -249.68581)
		(width 0.14732)
		(layer "In15.Cu")
		(net "P5E_CPU1_PE2_TX_DN<10>")
	)
	(segment
		(start 130.154426 -223.899476)
		(end 130.1623 -223.894904)
		(width 0.0889)
		(layer "In15.Cu")
		(net "P5E_CPU1_PE2_TX_DN<10>")
	)
	(segment
		(start 130.811016 -222.761556)
		(end 130.811016 -222.746062)
		(width 0.0889)
		(layer "In15.Cu")
		(net "P5E_CPU1_PE2_TX_DN<10>")
	)
	(segment
		(start 130.623564 -223.085914)
		(end 130.632454 -223.080834)
		(width 0.0889)
		(layer "In15.Cu")
		(net "P5E_CPU1_PE2_TX_DN<10>")
	)
	(segment
		(start 129.809748 -223.846644)
		(end 129.83083 -223.924622)
		(width 0.0889)
		(layer "In15.Cu")
		(net "P5E_CPU1_PE2_TX_DN<10>")
	)
	(segment
		(start 143.804132 -249.687588)
		(end 143.803878 -249.687588)
		(width 0.14732)
		(layer "In15.Cu")
		(net "P5E_CPU1_PE2_TX_DN<10>")
	)
	(segment
		(start 144.456404 -230.381556)
		(end 145.421096 -244.719094)
		(width 0.14732)
		(layer "In15.Cu")
		(net "P5E_CPU1_PE2_TX_DN<10>")
	)
	(segment
		(start 132.690616 -219.506038)
		(end 132.690616 -219.490544)
		(width 0.0889)
		(layer "In15.Cu")
		(net "P5E_CPU1_PE2_TX_DN<10>")
	)
	(segment
		(start 143.51508 -251.152152)
		(end 143.51508 -252.118622)
		(width 0.14732)
		(layer "In15.Cu")
		(net "P5E_CPU1_PE2_TX_DN<10>")
	)
	(segment
		(start 143.723868 -227.459794)
		(end 144.456404 -230.381556)
		(width 0.14732)
		(layer "In15.Cu")
		(net "P5E_CPU1_PE2_TX_DN<10>")
	)
	(segment
		(start 131.563364 -221.458282)
		(end 131.559554 -221.460822)
		(width 0.0889)
		(layer "In15.Cu")
		(net "P5E_CPU1_PE2_TX_DN<10>")
	)
	(segment
		(start 143.650462 -252.582426)
		(end 143.911574 -253.212854)
		(width 0.14732)
		(layer "In15.Cu")
		(net "P5E_CPU1_PE2_TX_DN<10>")
	)
	(segment
		(start 151.080724 -370.017548)
		(end 136.040114 -399.775172)
		(width 0.14732)
		(layer "In15.Cu")
		(net "P5E_CPU1_PE2_TX_DN<10>")
	)
	(segment
		(start 130.340862 -223.575626)
		(end 130.340862 -223.568006)
		(width 0.0889)
		(layer "In15.Cu")
		(net "P5E_CPU1_PE2_TX_DN<10>")
	)
	(segment
		(start 130.15341 -223.899984)
		(end 130.154426 -223.899476)
		(width 0.0889)
		(layer "In15.Cu")
		(net "P5E_CPU1_PE2_TX_DN<10>")
	)
	(segment
		(start 155.323032 -349.321628)
		(end 154.167078 -362.538264)
		(width 0.14732)
		(layer "In15.Cu")
		(net "P5E_CPU1_PE2_TX_DN<10>")
	)
	(segment
		(start 140.918438 -221.783148)
		(end 140.918438 -221.955614)
		(width 0.14732)
		(layer "In15.Cu")
		(net "P5E_CPU1_PE2_TX_DN<10>")
	)
	(segment
		(start 139.088622 -220.184726)
		(end 139.14755 -220.184726)
		(width 0.0889)
		(layer "In15.Cu")
		(net "P5E_CPU1_PE2_TX_DN<10>")
	)
	(segment
		(start 131.559554 -221.460822)
		(end 131.563618 -221.458282)
		(width 0.0889)
		(layer "In15.Cu")
		(net "P5E_CPU1_PE2_TX_DN<10>")
	)
	(segment
		(start 155.323286 -349.320866)
		(end 155.323032 -349.321628)
		(width 0.14732)
		(layer "In15.Cu")
		(net "P5E_CPU1_PE2_TX_DN<10>")
	)
	(segment
		(start 132.503164 -219.830396)
		(end 132.512054 -219.825316)
		(width 0.0889)
		(layer "In15.Cu")
		(net "P5E_CPU1_PE2_TX_DN<10>")
	)
	(segment
		(start 131.572254 -220.814646)
		(end 131.563364 -220.809566)
		(width 0.0889)
		(layer "In15.Cu")
		(net "P5E_CPU1_PE2_TX_DN<10>")
	)
	(segment
		(start 146.405346 -259.067808)
		(end 143.412972 -309.459884)
		(width 0.14732)
		(layer "In15.Cu")
		(net "P5E_CPU1_PE2_TX_DN<10>")
	)
	(segment
		(start 145.421096 -244.719094)
		(end 145.421096 -244.71884)
		(width 0.14732)
		(layer "In15.Cu")
		(net "P5E_CPU1_PE2_TX_DN<10>")
	)
	(segment
		(start 145.421096 -244.71884)
		(end 145.424652 -244.771926)
		(width 0.14732)
		(layer "In15.Cu")
		(net "P5E_CPU1_PE2_TX_DN<10>")
	)
	(segment
		(start 145.424652 -244.771926)
		(end 143.84401 -249.630184)
		(width 0.14732)
		(layer "In15.Cu")
		(net "P5E_CPU1_PE2_TX_DN<10>")
	)
	(segment
		(start 143.80464 -249.686826)
		(end 143.804132 -249.687588)
		(width 0.14732)
		(layer "In15.Cu")
		(net "P5E_CPU1_PE2_TX_DN<10>")
	)
	(segment
		(start 138.824208 -219.920058)
		(end 138.992356 -220.08846)
		(width 0.0889)
		(layer "In15.Cu")
		(net "P5E_CPU1_PE2_TX_DN<10>")
	)
	(segment
		(start 143.810482 -249.678952)
		(end 143.80591 -249.685048)
		(width 0.14732)
		(layer "In15.Cu")
		(net "P5E_CPU1_PE2_TX_DN<10>")
	)
	(segment
		(start 140.436854 -221.47403)
		(end 140.60932 -221.47403)
		(width 0.14732)
		(layer "In15.Cu")
		(net "P5E_CPU1_PE2_TX_DN<10>")
	)
	(segment
		(start 138.692382 -219.82176)
		(end 138.707114 -219.830396)
		(width 0.0889)
		(layer "In15.Cu")
		(net "P5E_CPU1_PE2_TX_DN<10>")
	)
	(segment
		(start 137.758424 -219.825316)
		(end 137.76579 -219.829634)
		(width 0.0889)
		(layer "In15.Cu")
		(net "P5E_CPU1_PE2_TX_DN<10>")
	)
	(segment
		(start 154.167078 -362.538264)
		(end 151.080724 -370.017548)
		(width 0.14732)
		(layer "In15.Cu")
		(net "P5E_CPU1_PE2_TX_DN<10>")
	)
	(segment
		(start 131.09321 -222.272098)
		(end 131.1021 -222.267018)
		(width 0.0889)
		(layer "In15.Cu")
		(net "P5E_CPU1_PE2_TX_DN<10>")
	)
	(segment
		(start 153.635202 -333.017114)
		(end 155.916884 -345.956128)
		(width 0.14732)
		(layer "In15.Cu")
		(net "P5E_CPU1_PE2_TX_DN<10>")
	)
	(segment
		(start 140.60932 -221.47403)
		(end 140.918438 -221.783148)
		(width 0.14732)
		(layer "In15.Cu")
		(net "P5E_CPU1_PE2_TX_DN<10>")
	)
	(segment
		(start 147.307046 -325.66991)
		(end 153.635202 -333.017114)
		(width 0.14732)
		(layer "In15.Cu")
		(net "P5E_CPU1_PE2_TX_DN<10>")
	)
	(segment
		(start 143.412972 -309.459884)
		(end 147.307046 -325.66991)
		(width 0.14732)
		(layer "In15.Cu")
		(net "P5E_CPU1_PE2_TX_DN<10>")
	)
	(segment
		(start 143.805402 -249.68581)
		(end 143.80464 -249.686826)
		(width 0.14732)
		(layer "In15.Cu")
		(net "P5E_CPU1_PE2_TX_DN<10>")
	)
	(segment
		(start 139.14755 -220.184726)
		(end 139.163044 -220.20022)
		(width 0.0889)
		(layer "In15.Cu")
		(net "P5E_CPU1_PE2_TX_DN<10>")
	)
	(segment
		(start 143.84401 -249.630184)
		(end 143.810482 -249.678952)
		(width 0.14732)
		(layer "In15.Cu")
		(net "P5E_CPU1_PE2_TX_DN<10>")
	)
	(segment
		(start 136.040114 -399.775172)
		(end 136.040114 -400.563588)
		(width 0.14732)
		(layer "In15.Cu")
		(net "P5E_CPU1_PE2_TX_DN<10>")
	)
	(segment
		(start 139.163044 -220.20022)
		(end 140.436854 -221.47403)
		(width 0.14732)
		(layer "In15.Cu")
		(net "P5E_CPU1_PE2_TX_DN<10>")
	)
	(segment
		(start 138.992356 -220.08846)
		(end 139.088622 -220.184726)
		(width 0.0889)
		(layer "In15.Cu")
		(net "P5E_CPU1_PE2_TX_DN<10>")
	)
	(segment
		(start 137.76579 -219.829634)
		(end 137.767314 -219.830396)
		(width 0.0889)
		(layer "In15.Cu")
		(net "P5E_CPU1_PE2_TX_DN<10>")
	)
	(segment
		(start 143.911574 -253.212854)
		(end 145.583402 -255.600454)
		(width 0.14732)
		(layer "In15.Cu")
		(net "P5E_CPU1_PE2_TX_DN<10>")
	)
	(segment
		(start 131.557268 -219.833952)
		(end 131.563364 -219.830396)
		(width 0.0889)
		(layer "In15.Cu")
		(net "P5E_CPU1_PE2_TX_DN<10>")
	)
	(segment
		(start 155.916884 -345.956128)
		(end 155.323286 -349.320866)
		(width 0.14732)
		(layer "In15.Cu")
		(net "P5E_CPU1_PE2_TX_DN<10>")
	)
	(segment
		(start 131.563618 -221.458282)
		(end 131.572254 -221.453202)
		(width 0.0889)
		(layer "In15.Cu")
		(net "P5E_CPU1_PE2_TX_DN<10>")
	)
	(segment
		(start 131.280662 -220.334078)
		(end 131.280662 -220.319854)
		(width 0.0889)
		(layer "In15.Cu")
		(net "P5E_CPU1_PE2_TX_DN<10>")
	)
	(segment
		(start 136.040114 -400.563588)
		(end 136.334754 -400.858228)
		(width 0.14732)
		(layer "In15.Cu")
		(net "P5E_CPU1_PE2_TX_DN<10>")
	)
	(segment
		(start 143.803878 -249.687588)
		(end 143.763746 -249.745246)
		(width 0.14732)
		(layer "In15.Cu")
		(net "P5E_CPU1_PE2_TX_DN<10>")
	)
	(segment
		(start 136.732264 -219.01658)
		(end 136.746996 -219.007944)
		(width 0.0889)
		(layer "In15.Cu")
		(net "P5E_CPU1_PE2_TX_DN<10>")
	)
	(segment
		(start 131.563364 -219.830396)
		(end 131.578096 -219.82176)
		(width 0.0889)
		(layer "In15.Cu")
		(net "P5E_CPU1_PE2_TX_DN<10>")
	)
	(segment
		(start 142.628874 -223.66605)
		(end 143.723868 -227.459794)
		(width 0.14732)
		(layer "In15.Cu")
		(net "P5E_CPU1_PE2_TX_DN<10>")
	)
	(segment
		(start 143.763746 -249.745246)
		(end 143.51508 -251.152152)
		(width 0.14732)
		(layer "In15.Cu")
		(net "P5E_CPU1_PE2_TX_DN<10>")
	)
	(segment
		(start 131.557268 -221.461838)
		(end 131.56057 -221.459806)
		(width 0.0889)
		(layer "In15.Cu")
		(net "P5E_CPU1_PE2_TX_DN<10>")
	)
	(segment
		(start 131.56057 -221.459806)
		(end 131.563364 -221.458282)
		(width 0.0889)
		(layer "In15.Cu")
		(net "P5E_CPU1_PE2_TX_DN<10>")
	)
	(segment
		(start 129.966212 -223.575626)
		(end 129.809748 -223.846644)
		(width 0.0889)
		(layer "In15.Cu")
		(net "P5E_CPU1_PE2_TX_DN<10>")
	)
	(arc
		(start 138.798046 -219.89542)
		(mid 138.811322 -219.907532)
		(end 138.824208 -219.920058)
		(width 0.0889)
		(layer "In15.Cu")
		(net "P5E_CPU1_PE2_TX_DN<10>")
	)
	(arc
		(start 136.357868 -219.01658)
		(mid 136.545066 -219.066723)
		(end 136.732264 -219.01658)
		(width 0.0889)
		(layer "In15.Cu")
		(net "P5E_CPU1_PE2_TX_DN<10>")
	)
	(arc
		(start 129.83083 -223.924622)
		(mid 129.994926 -223.948969)
		(end 130.15341 -223.899984)
		(width 0.0889)
		(layer "In15.Cu")
		(net "P5E_CPU1_PE2_TX_DN<10>")
	)
	(arc
		(start 132.690616 -219.490544)
		(mid 132.769986 -219.21681)
		(end 132.97281 -219.01658)
		(width 0.0889)
		(layer "In15.Cu")
		(net "P5E_CPU1_PE2_TX_DN<10>")
	)
	(arc
		(start 133.912864 -219.01658)
		(mid 134.195566 -218.940804)
		(end 134.478268 -219.01658)
		(width 0.0889)
		(layer "In15.Cu")
		(net "P5E_CPU1_PE2_TX_DN<10>")
	)
	(arc
		(start 137.767314 -219.830396)
		(mid 137.954512 -219.880539)
		(end 138.14171 -219.830396)
		(width 0.0889)
		(layer "In15.Cu")
		(net "P5E_CPU1_PE2_TX_DN<10>")
	)
	(arc
		(start 135.792464 -219.01658)
		(mid 136.075166 -218.940804)
		(end 136.357868 -219.01658)
		(width 0.0889)
		(layer "In15.Cu")
		(net "P5E_CPU1_PE2_TX_DN<10>")
	)
	(arc
		(start 132.128768 -219.830396)
		(mid 132.315966 -219.880539)
		(end 132.503164 -219.830396)
		(width 0.0889)
		(layer "In15.Cu")
		(net "P5E_CPU1_PE2_TX_DN<10>")
	)
	(arc
		(start 131.280662 -221.94774)
		(mid 131.354653 -221.668174)
		(end 131.557268 -221.461838)
		(width 0.0889)
		(layer "In15.Cu")
		(net "P5E_CPU1_PE2_TX_DN<10>")
	)
	(arc
		(start 132.97281 -219.01658)
		(mid 133.249623 -218.94071)
		(end 133.528054 -219.010484)
		(width 0.0889)
		(layer "In15.Cu")
		(net "P5E_CPU1_PE2_TX_DN<10>")
	)
	(arc
		(start 138.14171 -219.830396)
		(mid 138.415909 -219.754561)
		(end 138.692382 -219.82176)
		(width 0.0889)
		(layer "In15.Cu")
		(net "P5E_CPU1_PE2_TX_DN<10>")
	)
	(arc
		(start 135.418068 -219.01658)
		(mid 135.605266 -219.066723)
		(end 135.792464 -219.01658)
		(width 0.0889)
		(layer "In15.Cu")
		(net "P5E_CPU1_PE2_TX_DN<10>")
	)
	(arc
		(start 133.538468 -219.01658)
		(mid 133.725666 -219.066723)
		(end 133.912864 -219.01658)
		(width 0.0889)
		(layer "In15.Cu")
		(net "P5E_CPU1_PE2_TX_DN<10>")
	)
	(arc
		(start 138.707114 -219.830396)
		(mid 138.75419 -219.860656)
		(end 138.798046 -219.89542)
		(width 0.0889)
		(layer "In15.Cu")
		(net "P5E_CPU1_PE2_TX_DN<10>")
	)
	(arc
		(start 130.340862 -223.568006)
		(mid 130.418491 -223.289593)
		(end 130.623564 -223.085914)
		(width 0.0889)
		(layer "In15.Cu")
		(net "P5E_CPU1_PE2_TX_DN<10>")
	)
	(arc
		(start 131.1021 -222.267018)
		(mid 131.233014 -222.130658)
		(end 131.280662 -221.94774)
		(width 0.0889)
		(layer "In15.Cu")
		(net "P5E_CPU1_PE2_TX_DN<10>")
	)
	(arc
		(start 137.579862 -219.506038)
		(mid 137.627541 -219.688938)
		(end 137.758424 -219.825316)
		(width 0.0889)
		(layer "In15.Cu")
		(net "P5E_CPU1_PE2_TX_DN<10>")
	)
	(arc
		(start 130.811016 -222.746062)
		(mid 130.890386 -222.472328)
		(end 131.09321 -222.272098)
		(width 0.0889)
		(layer "In15.Cu")
		(net "P5E_CPU1_PE2_TX_DN<10>")
	)
	(arc
		(start 134.478268 -219.01658)
		(mid 134.665466 -219.066723)
		(end 134.852664 -219.01658)
		(width 0.0889)
		(layer "In15.Cu")
		(net "P5E_CPU1_PE2_TX_DN<10>")
	)
	(arc
		(start 131.280662 -220.319854)
		(mid 131.354653 -220.040288)
		(end 131.557268 -219.833952)
		(width 0.0889)
		(layer "In15.Cu")
		(net "P5E_CPU1_PE2_TX_DN<10>")
	)
	(arc
		(start 131.563364 -220.809566)
		(mid 131.359883 -220.608762)
		(end 131.280662 -220.334078)
		(width 0.0889)
		(layer "In15.Cu")
		(net "P5E_CPU1_PE2_TX_DN<10>")
	)
	(arc
		(start 136.746996 -219.007944)
		(mid 137.023471 -218.940624)
		(end 137.297668 -219.01658)
		(width 0.0889)
		(layer "In15.Cu")
		(net "P5E_CPU1_PE2_TX_DN<10>")
	)
	(arc
		(start 131.578096 -219.82176)
		(mid 131.854571 -219.75444)
		(end 132.128768 -219.830396)
		(width 0.0889)
		(layer "In15.Cu")
		(net "P5E_CPU1_PE2_TX_DN<10>")
	)
	(arc
		(start 134.852664 -219.01658)
		(mid 135.135366 -218.940804)
		(end 135.418068 -219.01658)
		(width 0.0889)
		(layer "In15.Cu")
		(net "P5E_CPU1_PE2_TX_DN<10>")
	)
	(arc
		(start 131.572254 -221.453202)
		(mid 131.750851 -221.133924)
		(end 131.572254 -220.814646)
		(width 0.0889)
		(layer "In15.Cu")
		(net "P5E_CPU1_PE2_TX_DN<10>")
	)
	(arc
		(start 130.1623 -223.894904)
		(mid 130.293214 -223.758544)
		(end 130.340862 -223.575626)
		(width 0.0889)
		(layer "In15.Cu")
		(net "P5E_CPU1_PE2_TX_DN<10>")
	)
	(arc
		(start 130.632454 -223.080834)
		(mid 130.763368 -222.944474)
		(end 130.811016 -222.761556)
		(width 0.0889)
		(layer "In15.Cu")
		(net "P5E_CPU1_PE2_TX_DN<10>")
	)
	(arc
		(start 132.512054 -219.825316)
		(mid 132.642968 -219.688956)
		(end 132.690616 -219.506038)
		(width 0.0889)
		(layer "In15.Cu")
		(net "P5E_CPU1_PE2_TX_DN<10>")
	)
	(arc
		(start 137.297668 -219.01658)
		(mid 137.500491 -219.216811)
		(end 137.579862 -219.490544)
		(width 0.0889)
		(layer "In15.Cu")
		(net "P5E_CPU1_PE2_TX_DN<10>")
	)
	(segment
		(start 120.568466 -223.57588)
		(end 120.568212 -223.575626)
		(width 0.13208)
		(layer "F.Cu")
		(net "P5E_CPU1_PE2_TX_DN<0>")
	)
	(segment
		(start 166.668196 -401.779994)
		(end 166.992554 -402.104352)
		(width 0.13208)
		(layer "F.Cu")
		(net "P5E_CPU1_PE2_TX_DN<0>")
	)
	(segment
		(start 120.568466 -224.111566)
		(end 120.568466 -223.57588)
		(width 0.13208)
		(layer "F.Cu")
		(net "P5E_CPU1_PE2_TX_DN<0>")
	)
	(segment
		(start 166.668196 -401.157186)
		(end 166.668196 -401.779994)
		(width 0.13208)
		(layer "F.Cu")
		(net "P5E_CPU1_PE2_TX_DN<0>")
	)
	(segment
		(start 166.967154 -400.858228)
		(end 166.668196 -401.157186)
		(width 0.13208)
		(layer "F.Cu")
		(net "P5E_CPU1_PE2_TX_DN<0>")
	)
	(segment
		(start 165.742112 -345.999054)
		(end 165.271196 -348.669864)
		(width 0.14732)
		(layer "In15.Cu")
		(net "P5E_CPU1_PE2_TX_DN<0>")
	)
	(segment
		(start 123.105164 -216.574878)
		(end 123.114054 -216.569798)
		(width 0.0889)
		(layer "In15.Cu")
		(net "P5E_CPU1_PE2_TX_DN<0>")
	)
	(segment
		(start 123.720606 -213.17839)
		(end 123.720606 -211.995512)
		(width 0.14732)
		(layer "In15.Cu")
		(net "P5E_CPU1_PE2_TX_DN<0>")
	)
	(segment
		(start 153.02738 -308.313074)
		(end 155.42768 -318.767206)
		(width 0.14732)
		(layer "In15.Cu")
		(net "P5E_CPU1_PE2_TX_DN<0>")
	)
	(segment
		(start 123.105164 -218.202764)
		(end 123.114054 -218.197684)
		(width 0.0889)
		(layer "In15.Cu")
		(net "P5E_CPU1_PE2_TX_DN<0>")
	)
	(segment
		(start 122.166888 -219.829634)
		(end 122.174254 -219.825316)
		(width 0.0889)
		(layer "In15.Cu")
		(net "P5E_CPU1_PE2_TX_DN<0>")
	)
	(segment
		(start 152.138126 -219.563696)
		(end 153.835608 -226.102672)
		(width 0.14732)
		(layer "In15.Cu")
		(net "P5E_CPU1_PE2_TX_DN<0>")
	)
	(segment
		(start 145.970752 -211.249514)
		(end 152.138126 -219.563696)
		(width 0.14732)
		(layer "In15.Cu")
		(net "P5E_CPU1_PE2_TX_DN<0>")
	)
	(segment
		(start 121.882662 -220.334078)
		(end 121.882662 -220.319854)
		(width 0.0889)
		(layer "In15.Cu")
		(net "P5E_CPU1_PE2_TX_DN<0>")
	)
	(segment
		(start 155.42768 -318.767206)
		(end 156.81579 -320.61658)
		(width 0.14732)
		(layer "In15.Cu")
		(net "P5E_CPU1_PE2_TX_DN<0>")
	)
	(segment
		(start 166.672514 -400.563588)
		(end 166.967154 -400.858228)
		(width 0.14732)
		(layer "In15.Cu")
		(net "P5E_CPU1_PE2_TX_DN<0>")
	)
	(segment
		(start 120.568212 -223.575626)
		(end 120.411748 -223.846644)
		(width 0.0889)
		(layer "In15.Cu")
		(net "P5E_CPU1_PE2_TX_DN<0>")
	)
	(segment
		(start 122.159268 -221.461838)
		(end 122.165364 -221.458282)
		(width 0.0889)
		(layer "In15.Cu")
		(net "P5E_CPU1_PE2_TX_DN<0>")
	)
	(segment
		(start 133.507226 -202.268836)
		(end 135.899906 -202.268836)
		(width 0.14732)
		(layer "In15.Cu")
		(net "P5E_CPU1_PE2_TX_DN<0>")
	)
	(segment
		(start 123.720606 -211.995512)
		(end 124.457714 -210.215988)
		(width 0.14732)
		(layer "In15.Cu")
		(net "P5E_CPU1_PE2_TX_DN<0>")
	)
	(segment
		(start 120.942862 -223.575626)
		(end 120.942862 -223.568006)
		(width 0.0889)
		(layer "In15.Cu")
		(net "P5E_CPU1_PE2_TX_DN<0>")
	)
	(segment
		(start 165.028372 -351.444052)
		(end 166.672514 -399.66519)
		(width 0.14732)
		(layer "In15.Cu")
		(net "P5E_CPU1_PE2_TX_DN<0>")
	)
	(segment
		(start 124.044456 -214.946992)
		(end 124.053346 -214.941912)
		(width 0.0889)
		(layer "In15.Cu")
		(net "P5E_CPU1_PE2_TX_DN<0>")
	)
	(segment
		(start 121.225564 -223.085914)
		(end 121.234454 -223.080834)
		(width 0.0889)
		(layer "In15.Cu")
		(net "P5E_CPU1_PE2_TX_DN<0>")
	)
	(segment
		(start 122.174254 -220.814646)
		(end 122.165364 -220.809566)
		(width 0.0889)
		(layer "In15.Cu")
		(net "P5E_CPU1_PE2_TX_DN<0>")
	)
	(segment
		(start 123.76277 -213.929468)
		(end 123.76277 -213.242652)
		(width 0.0889)
		(layer "In15.Cu")
		(net "P5E_CPU1_PE2_TX_DN<0>")
	)
	(segment
		(start 123.57481 -215.761062)
		(end 123.5837 -215.755982)
		(width 0.0889)
		(layer "In15.Cu")
		(net "P5E_CPU1_PE2_TX_DN<0>")
	)
	(segment
		(start 166.672514 -399.66519)
		(end 166.672514 -400.563588)
		(width 0.14732)
		(layer "In15.Cu")
		(net "P5E_CPU1_PE2_TX_DN<0>")
	)
	(segment
		(start 122.159268 -219.833952)
		(end 122.165364 -219.830396)
		(width 0.0889)
		(layer "In15.Cu")
		(net "P5E_CPU1_PE2_TX_DN<0>")
	)
	(segment
		(start 165.271196 -348.669864)
		(end 165.028372 -351.444052)
		(width 0.14732)
		(layer "In15.Cu")
		(net "P5E_CPU1_PE2_TX_DN<0>")
	)
	(segment
		(start 120.411748 -223.846644)
		(end 120.43283 -223.924622)
		(width 0.0889)
		(layer "In15.Cu")
		(net "P5E_CPU1_PE2_TX_DN<0>")
	)
	(segment
		(start 123.092972 -216.58199)
		(end 123.105164 -216.574878)
		(width 0.0889)
		(layer "In15.Cu")
		(net "P5E_CPU1_PE2_TX_DN<0>")
	)
	(segment
		(start 157.077918 -247.590818)
		(end 157.080204 -247.606566)
		(width 0.14732)
		(layer "In15.Cu")
		(net "P5E_CPU1_PE2_TX_DN<0>")
	)
	(segment
		(start 160.738058 -323.189346)
		(end 163.112704 -324.85203)
		(width 0.14732)
		(layer "In15.Cu")
		(net "P5E_CPU1_PE2_TX_DN<0>")
	)
	(segment
		(start 163.112704 -324.85203)
		(end 164.106606 -326.271636)
		(width 0.14732)
		(layer "In15.Cu")
		(net "P5E_CPU1_PE2_TX_DN<0>")
	)
	(segment
		(start 164.106606 -326.271636)
		(end 164.350446 -327.654158)
		(width 0.14732)
		(layer "In15.Cu")
		(net "P5E_CPU1_PE2_TX_DN<0>")
	)
	(segment
		(start 122.165364 -219.830396)
		(end 122.166888 -219.829634)
		(width 0.0889)
		(layer "In15.Cu")
		(net "P5E_CPU1_PE2_TX_DN<0>")
	)
	(segment
		(start 157.080204 -247.606566)
		(end 157.27807 -253.5047)
		(width 0.14732)
		(layer "In15.Cu")
		(net "P5E_CPU1_PE2_TX_DN<0>")
	)
	(segment
		(start 124.457714 -210.215988)
		(end 131.625594 -203.048108)
		(width 0.14732)
		(layer "In15.Cu")
		(net "P5E_CPU1_PE2_TX_DN<0>")
	)
	(segment
		(start 123.105926 -217.554556)
		(end 123.105164 -217.554048)
		(width 0.0889)
		(layer "In15.Cu")
		(net "P5E_CPU1_PE2_TX_DN<0>")
	)
	(segment
		(start 122.63501 -219.01658)
		(end 122.6439 -219.0115)
		(width 0.0889)
		(layer "In15.Cu")
		(net "P5E_CPU1_PE2_TX_DN<0>")
	)
	(segment
		(start 137.760456 -203.039472)
		(end 145.970752 -211.249514)
		(width 0.14732)
		(layer "In15.Cu")
		(net "P5E_CPU1_PE2_TX_DN<0>")
	)
	(segment
		(start 157.077664 -247.590818)
		(end 157.077918 -247.590818)
		(width 0.14732)
		(layer "In15.Cu")
		(net "P5E_CPU1_PE2_TX_DN<0>")
	)
	(segment
		(start 164.350446 -327.654158)
		(end 163.429188 -332.880716)
		(width 0.14732)
		(layer "In15.Cu")
		(net "P5E_CPU1_PE2_TX_DN<0>")
	)
	(segment
		(start 157.27807 -253.5047)
		(end 153.02738 -308.313074)
		(width 0.14732)
		(layer "In15.Cu")
		(net "P5E_CPU1_PE2_TX_DN<0>")
	)
	(segment
		(start 156.81579 -320.61658)
		(end 160.738058 -323.189346)
		(width 0.14732)
		(layer "In15.Cu")
		(net "P5E_CPU1_PE2_TX_DN<0>")
	)
	(segment
		(start 122.165364 -221.458282)
		(end 122.174254 -221.453202)
		(width 0.0889)
		(layer "In15.Cu")
		(net "P5E_CPU1_PE2_TX_DN<0>")
	)
	(segment
		(start 124.231908 -214.622634)
		(end 124.231908 -214.461344)
		(width 0.0889)
		(layer "In15.Cu")
		(net "P5E_CPU1_PE2_TX_DN<0>")
	)
	(segment
		(start 123.762262 -213.929976)
		(end 123.76277 -213.929468)
		(width 0.0889)
		(layer "In15.Cu")
		(net "P5E_CPU1_PE2_TX_DN<0>")
	)
	(segment
		(start 153.835608 -226.102672)
		(end 157.077664 -247.590818)
		(width 0.14732)
		(layer "In15.Cu")
		(net "P5E_CPU1_PE2_TX_DN<0>")
	)
	(segment
		(start 135.899906 -202.268836)
		(end 137.760456 -203.039472)
		(width 0.14732)
		(layer "In15.Cu")
		(net "P5E_CPU1_PE2_TX_DN<0>")
	)
	(segment
		(start 121.413016 -222.761556)
		(end 121.413016 -222.746062)
		(width 0.0889)
		(layer "In15.Cu")
		(net "P5E_CPU1_PE2_TX_DN<0>")
	)
	(segment
		(start 123.762262 -213.93023)
		(end 123.762262 -213.929976)
		(width 0.0889)
		(layer "In15.Cu")
		(net "P5E_CPU1_PE2_TX_DN<0>")
	)
	(segment
		(start 120.75541 -223.899984)
		(end 120.756426 -223.899476)
		(width 0.0889)
		(layer "In15.Cu")
		(net "P5E_CPU1_PE2_TX_DN<0>")
	)
	(segment
		(start 122.822462 -217.071956)
		(end 122.822462 -217.064336)
		(width 0.0889)
		(layer "In15.Cu")
		(net "P5E_CPU1_PE2_TX_DN<0>")
	)
	(segment
		(start 123.114054 -217.559128)
		(end 123.105926 -217.554556)
		(width 0.0889)
		(layer "In15.Cu")
		(net "P5E_CPU1_PE2_TX_DN<0>")
	)
	(segment
		(start 163.429188 -332.880716)
		(end 165.742112 -345.999054)
		(width 0.14732)
		(layer "In15.Cu")
		(net "P5E_CPU1_PE2_TX_DN<0>")
	)
	(segment
		(start 131.625594 -203.048108)
		(end 133.507226 -202.268836)
		(width 0.14732)
		(layer "In15.Cu")
		(net "P5E_CPU1_PE2_TX_DN<0>")
	)
	(segment
		(start 121.69521 -222.272098)
		(end 121.7041 -222.267018)
		(width 0.0889)
		(layer "In15.Cu")
		(net "P5E_CPU1_PE2_TX_DN<0>")
	)
	(segment
		(start 123.099068 -218.20632)
		(end 123.105164 -218.202764)
		(width 0.0889)
		(layer "In15.Cu")
		(net "P5E_CPU1_PE2_TX_DN<0>")
	)
	(segment
		(start 123.292616 -216.25052)
		(end 123.292616 -216.235026)
		(width 0.0889)
		(layer "In15.Cu")
		(net "P5E_CPU1_PE2_TX_DN<0>")
	)
	(segment
		(start 122.352816 -219.506038)
		(end 122.352816 -219.490544)
		(width 0.0889)
		(layer "In15.Cu")
		(net "P5E_CPU1_PE2_TX_DN<0>")
	)
	(segment
		(start 120.756426 -223.899476)
		(end 120.7643 -223.894904)
		(width 0.0889)
		(layer "In15.Cu")
		(net "P5E_CPU1_PE2_TX_DN<0>")
	)
	(segment
		(start 123.720606 -213.200488)
		(end 123.720606 -213.17839)
		(width 0.0889)
		(layer "In15.Cu")
		(net "P5E_CPU1_PE2_TX_DN<0>")
	)
	(segment
		(start 123.762262 -215.436704)
		(end 123.762262 -215.414606)
		(width 0.0889)
		(layer "In15.Cu")
		(net "P5E_CPU1_PE2_TX_DN<0>")
	)
	(segment
		(start 123.76277 -213.242652)
		(end 123.720606 -213.200488)
		(width 0.0889)
		(layer "In15.Cu")
		(net "P5E_CPU1_PE2_TX_DN<0>")
	)
	(arc
		(start 122.174254 -221.453202)
		(mid 122.352851 -221.133924)
		(end 122.174254 -220.814646)
		(width 0.0889)
		(layer "In15.Cu")
		(net "P5E_CPU1_PE2_TX_DN<0>")
	)
	(arc
		(start 122.822462 -218.692222)
		(mid 122.896453 -218.412656)
		(end 123.099068 -218.20632)
		(width 0.0889)
		(layer "In15.Cu")
		(net "P5E_CPU1_PE2_TX_DN<0>")
	)
	(arc
		(start 124.231908 -214.461344)
		(mid 124.156903 -214.345885)
		(end 124.047758 -214.261954)
		(width 0.0889)
		(layer "In15.Cu")
		(net "P5E_CPU1_PE2_TX_DN<0>")
	)
	(arc
		(start 124.053346 -214.941912)
		(mid 124.1806 -214.811946)
		(end 124.231654 -214.637366)
		(width 0.0889)
		(layer "In15.Cu")
		(net "P5E_CPU1_PE2_TX_DN<0>")
	)
	(arc
		(start 122.6439 -219.0115)
		(mid 122.774814 -218.87514)
		(end 122.822462 -218.692222)
		(width 0.0889)
		(layer "In15.Cu")
		(net "P5E_CPU1_PE2_TX_DN<0>")
	)
	(arc
		(start 122.165364 -220.809566)
		(mid 121.961883 -220.608762)
		(end 121.882662 -220.334078)
		(width 0.0889)
		(layer "In15.Cu")
		(net "P5E_CPU1_PE2_TX_DN<0>")
	)
	(arc
		(start 123.114054 -218.197684)
		(mid 123.292651 -217.878406)
		(end 123.114054 -217.559128)
		(width 0.0889)
		(layer "In15.Cu")
		(net "P5E_CPU1_PE2_TX_DN<0>")
	)
	(arc
		(start 123.5837 -215.755982)
		(mid 123.714614 -215.619622)
		(end 123.762262 -215.436704)
		(width 0.0889)
		(layer "In15.Cu")
		(net "P5E_CPU1_PE2_TX_DN<0>")
	)
	(arc
		(start 122.822462 -217.064336)
		(mid 122.894697 -216.787812)
		(end 123.092972 -216.58199)
		(width 0.0889)
		(layer "In15.Cu")
		(net "P5E_CPU1_PE2_TX_DN<0>")
	)
	(arc
		(start 121.882662 -221.94774)
		(mid 121.956653 -221.668174)
		(end 122.159268 -221.461838)
		(width 0.0889)
		(layer "In15.Cu")
		(net "P5E_CPU1_PE2_TX_DN<0>")
	)
	(arc
		(start 120.43283 -223.924622)
		(mid 120.596926 -223.948969)
		(end 120.75541 -223.899984)
		(width 0.0889)
		(layer "In15.Cu")
		(net "P5E_CPU1_PE2_TX_DN<0>")
	)
	(arc
		(start 124.231654 -214.637366)
		(mid 124.231851 -214.630001)
		(end 124.231908 -214.622634)
		(width 0.0889)
		(layer "In15.Cu")
		(net "P5E_CPU1_PE2_TX_DN<0>")
	)
	(arc
		(start 121.413016 -222.746062)
		(mid 121.492386 -222.472328)
		(end 121.69521 -222.272098)
		(width 0.0889)
		(layer "In15.Cu")
		(net "P5E_CPU1_PE2_TX_DN<0>")
	)
	(arc
		(start 121.882662 -220.319854)
		(mid 121.956653 -220.040288)
		(end 122.159268 -219.833952)
		(width 0.0889)
		(layer "In15.Cu")
		(net "P5E_CPU1_PE2_TX_DN<0>")
	)
	(arc
		(start 122.174254 -219.825316)
		(mid 122.305168 -219.688956)
		(end 122.352816 -219.506038)
		(width 0.0889)
		(layer "In15.Cu")
		(net "P5E_CPU1_PE2_TX_DN<0>")
	)
	(arc
		(start 124.047758 -214.261954)
		(mid 123.887867 -214.13907)
		(end 123.777756 -213.970108)
		(width 0.0889)
		(layer "In15.Cu")
		(net "P5E_CPU1_PE2_TX_DN<0>")
	)
	(arc
		(start 120.7643 -223.894904)
		(mid 120.895214 -223.758544)
		(end 120.942862 -223.575626)
		(width 0.0889)
		(layer "In15.Cu")
		(net "P5E_CPU1_PE2_TX_DN<0>")
	)
	(arc
		(start 123.105164 -217.554048)
		(mid 122.900092 -217.350369)
		(end 122.822462 -217.071956)
		(width 0.0889)
		(layer "In15.Cu")
		(net "P5E_CPU1_PE2_TX_DN<0>")
	)
	(arc
		(start 123.777756 -213.970108)
		(mid 123.769649 -213.950309)
		(end 123.762262 -213.93023)
		(width 0.0889)
		(layer "In15.Cu")
		(net "P5E_CPU1_PE2_TX_DN<0>")
	)
	(arc
		(start 121.234454 -223.080834)
		(mid 121.365368 -222.944474)
		(end 121.413016 -222.761556)
		(width 0.0889)
		(layer "In15.Cu")
		(net "P5E_CPU1_PE2_TX_DN<0>")
	)
	(arc
		(start 123.762262 -215.414606)
		(mid 123.843173 -215.144478)
		(end 124.044456 -214.946992)
		(width 0.0889)
		(layer "In15.Cu")
		(net "P5E_CPU1_PE2_TX_DN<0>")
	)
	(arc
		(start 123.292616 -216.235026)
		(mid 123.371986 -215.961292)
		(end 123.57481 -215.761062)
		(width 0.0889)
		(layer "In15.Cu")
		(net "P5E_CPU1_PE2_TX_DN<0>")
	)
	(arc
		(start 122.352816 -219.490544)
		(mid 122.432186 -219.21681)
		(end 122.63501 -219.01658)
		(width 0.0889)
		(layer "In15.Cu")
		(net "P5E_CPU1_PE2_TX_DN<0>")
	)
	(arc
		(start 123.114054 -216.569798)
		(mid 123.244968 -216.433438)
		(end 123.292616 -216.25052)
		(width 0.0889)
		(layer "In15.Cu")
		(net "P5E_CPU1_PE2_TX_DN<0>")
	)
	(arc
		(start 120.942862 -223.568006)
		(mid 121.020491 -223.289593)
		(end 121.225564 -223.085914)
		(width 0.0889)
		(layer "In15.Cu")
		(net "P5E_CPU1_PE2_TX_DN<0>")
	)
	(arc
		(start 121.7041 -222.267018)
		(mid 121.835014 -222.130658)
		(end 121.882662 -221.94774)
		(width 0.0889)
		(layer "In15.Cu")
		(net "P5E_CPU1_PE2_TX_DN<0>")
	)
	(segment
		(start 138.837416 -403.580854)
		(end 138.837416 -402.962872)
		(width 0.13208)
		(layer "F.Cu")
		(net "P5E_CPU1_PE2_TX_C_DP<9>")
	)
	(segment
		(start 138.837416 -402.962872)
		(end 138.512296 -402.637752)
		(width 0.13208)
		(layer "F.Cu")
		(net "P5E_CPU1_PE2_TX_C_DP<9>")
	)
	(segment
		(start 138.534394 -403.883876)
		(end 138.837416 -403.580854)
		(width 0.13208)
		(layer "F.Cu")
		(net "P5E_CPU1_PE2_TX_C_DP<9>")
	)
	(segment
		(start 138.512296 -402.637752)
		(end 138.508994 -402.637752)
		(width 0.13208)
		(layer "F.Cu")
		(net "P5E_CPU1_PE2_TX_C_DP<9>")
	)
	(segment
		(start 136.792462 -426.509434)
		(end 136.792462 -424.286426)
		(width 0.14732)
		(layer "In11.Cu")
		(net "P5E_CPU1_PE2_TX_C_DP<9>")
	)
	(segment
		(start 138.829034 -406.11933)
		(end 138.829034 -404.178516)
		(width 0.14732)
		(layer "In11.Cu")
		(net "P5E_CPU1_PE2_TX_C_DP<9>")
	)
	(segment
		(start 137.076942 -426.793914)
		(end 136.792462 -426.509434)
		(width 0.14732)
		(layer "In11.Cu")
		(net "P5E_CPU1_PE2_TX_C_DP<9>")
	)
	(segment
		(start 137.57529 -418.314632)
		(end 138.643614 -410.199078)
		(width 0.14732)
		(layer "In11.Cu")
		(net "P5E_CPU1_PE2_TX_C_DP<9>")
	)
	(segment
		(start 138.643614 -410.199078)
		(end 138.643614 -406.30475)
		(width 0.14732)
		(layer "In11.Cu")
		(net "P5E_CPU1_PE2_TX_C_DP<9>")
	)
	(segment
		(start 137.750042 -427.289976)
		(end 137.750042 -426.980858)
		(width 0.14732)
		(layer "In11.Cu")
		(net "P5E_CPU1_PE2_TX_C_DP<9>")
	)
	(segment
		(start 137.574782 -418.314632)
		(end 137.57529 -418.314632)
		(width 0.14732)
		(layer "In11.Cu")
		(net "P5E_CPU1_PE2_TX_C_DP<9>")
	)
	(segment
		(start 136.79678 -424.222164)
		(end 137.574782 -418.314632)
		(width 0.14732)
		(layer "In11.Cu")
		(net "P5E_CPU1_PE2_TX_C_DP<9>")
	)
	(segment
		(start 138.643614 -406.30475)
		(end 138.829034 -406.11933)
		(width 0.14732)
		(layer "In11.Cu")
		(net "P5E_CPU1_PE2_TX_C_DP<9>")
	)
	(segment
		(start 137.750042 -426.980858)
		(end 137.563098 -426.793914)
		(width 0.14732)
		(layer "In11.Cu")
		(net "P5E_CPU1_PE2_TX_C_DP<9>")
	)
	(segment
		(start 138.829034 -404.178516)
		(end 138.534394 -403.883876)
		(width 0.14732)
		(layer "In11.Cu")
		(net "P5E_CPU1_PE2_TX_C_DP<9>")
	)
	(segment
		(start 136.792462 -424.286426)
		(end 136.79678 -424.222164)
		(width 0.14732)
		(layer "In11.Cu")
		(net "P5E_CPU1_PE2_TX_C_DP<9>")
	)
	(segment
		(start 137.563098 -426.793914)
		(end 137.076942 -426.793914)
		(width 0.14732)
		(layer "In11.Cu")
		(net "P5E_CPU1_PE2_TX_C_DP<9>")
	)
	(segment
		(start 141.900656 -403.580854)
		(end 141.900656 -402.962872)
		(width 0.13208)
		(layer "F.Cu")
		(net "P5E_CPU1_PE2_TX_C_DP<8>")
	)
	(segment
		(start 141.900656 -402.962872)
		(end 141.575536 -402.637752)
		(width 0.13208)
		(layer "F.Cu")
		(net "P5E_CPU1_PE2_TX_C_DP<8>")
	)
	(segment
		(start 141.575536 -402.637752)
		(end 141.572234 -402.637752)
		(width 0.13208)
		(layer "F.Cu")
		(net "P5E_CPU1_PE2_TX_C_DP<8>")
	)
	(segment
		(start 141.597634 -403.883876)
		(end 141.900656 -403.580854)
		(width 0.13208)
		(layer "F.Cu")
		(net "P5E_CPU1_PE2_TX_C_DP<8>")
	)
	(segment
		(start 139.076938 -427.793658)
		(end 138.792458 -427.509178)
		(width 0.14732)
		(layer "In11.Cu")
		(net "P5E_CPU1_PE2_TX_C_DP<8>")
	)
	(segment
		(start 139.750038 -427.980602)
		(end 139.563094 -427.793658)
		(width 0.14732)
		(layer "In11.Cu")
		(net "P5E_CPU1_PE2_TX_C_DP<8>")
	)
	(segment
		(start 138.792458 -427.509178)
		(end 138.792458 -424.177968)
		(width 0.14732)
		(layer "In11.Cu")
		(net "P5E_CPU1_PE2_TX_C_DP<8>")
	)
	(segment
		(start 141.706854 -410.433266)
		(end 141.706854 -406.30475)
		(width 0.14732)
		(layer "In11.Cu")
		(net "P5E_CPU1_PE2_TX_C_DP<8>")
	)
	(segment
		(start 141.706854 -406.30475)
		(end 141.892274 -406.11933)
		(width 0.14732)
		(layer "In11.Cu")
		(net "P5E_CPU1_PE2_TX_C_DP<8>")
	)
	(segment
		(start 139.750038 -428.28972)
		(end 139.750038 -427.980602)
		(width 0.14732)
		(layer "In11.Cu")
		(net "P5E_CPU1_PE2_TX_C_DP<8>")
	)
	(segment
		(start 141.892274 -404.178516)
		(end 141.597634 -403.883876)
		(width 0.14732)
		(layer "In11.Cu")
		(net "P5E_CPU1_PE2_TX_C_DP<8>")
	)
	(segment
		(start 141.892274 -406.11933)
		(end 141.892274 -404.178516)
		(width 0.14732)
		(layer "In11.Cu")
		(net "P5E_CPU1_PE2_TX_C_DP<8>")
	)
	(segment
		(start 139.563094 -427.793658)
		(end 139.076938 -427.793658)
		(width 0.14732)
		(layer "In11.Cu")
		(net "P5E_CPU1_PE2_TX_C_DP<8>")
	)
	(segment
		(start 138.792458 -424.177968)
		(end 141.706854 -410.433266)
		(width 0.14732)
		(layer "In11.Cu")
		(net "P5E_CPU1_PE2_TX_C_DP<8>")
	)
	(segment
		(start 144.963896 -403.580854)
		(end 144.963896 -402.962872)
		(width 0.13208)
		(layer "F.Cu")
		(net "P5E_CPU1_PE2_TX_C_DP<7>")
	)
	(segment
		(start 144.638776 -402.637752)
		(end 144.635474 -402.637752)
		(width 0.13208)
		(layer "F.Cu")
		(net "P5E_CPU1_PE2_TX_C_DP<7>")
	)
	(segment
		(start 144.963896 -402.962872)
		(end 144.638776 -402.637752)
		(width 0.13208)
		(layer "F.Cu")
		(net "P5E_CPU1_PE2_TX_C_DP<7>")
	)
	(segment
		(start 144.660874 -403.883876)
		(end 144.963896 -403.580854)
		(width 0.13208)
		(layer "F.Cu")
		(net "P5E_CPU1_PE2_TX_C_DP<7>")
	)
	(segment
		(start 144.770094 -406.30475)
		(end 144.955514 -406.11933)
		(width 0.14732)
		(layer "In11.Cu")
		(net "P5E_CPU1_PE2_TX_C_DP<7>")
	)
	(segment
		(start 144.955514 -404.178516)
		(end 144.660874 -403.883876)
		(width 0.14732)
		(layer "In11.Cu")
		(net "P5E_CPU1_PE2_TX_C_DP<7>")
	)
	(segment
		(start 142.076932 -426.793914)
		(end 141.792452 -426.509434)
		(width 0.14732)
		(layer "In11.Cu")
		(net "P5E_CPU1_PE2_TX_C_DP<7>")
	)
	(segment
		(start 141.792452 -423.309034)
		(end 141.797024 -423.140632)
		(width 0.14732)
		(layer "In11.Cu")
		(net "P5E_CPU1_PE2_TX_C_DP<7>")
	)
	(segment
		(start 141.797024 -423.140632)
		(end 144.770094 -410.370782)
		(width 0.14732)
		(layer "In11.Cu")
		(net "P5E_CPU1_PE2_TX_C_DP<7>")
	)
	(segment
		(start 142.750032 -426.980858)
		(end 142.563088 -426.793914)
		(width 0.14732)
		(layer "In11.Cu")
		(net "P5E_CPU1_PE2_TX_C_DP<7>")
	)
	(segment
		(start 142.563088 -426.793914)
		(end 142.076932 -426.793914)
		(width 0.14732)
		(layer "In11.Cu")
		(net "P5E_CPU1_PE2_TX_C_DP<7>")
	)
	(segment
		(start 144.770094 -410.370782)
		(end 144.770094 -406.30475)
		(width 0.14732)
		(layer "In11.Cu")
		(net "P5E_CPU1_PE2_TX_C_DP<7>")
	)
	(segment
		(start 142.750032 -427.289976)
		(end 142.750032 -426.980858)
		(width 0.14732)
		(layer "In11.Cu")
		(net "P5E_CPU1_PE2_TX_C_DP<7>")
	)
	(segment
		(start 144.955514 -406.11933)
		(end 144.955514 -404.178516)
		(width 0.14732)
		(layer "In11.Cu")
		(net "P5E_CPU1_PE2_TX_C_DP<7>")
	)
	(segment
		(start 141.792452 -426.509434)
		(end 141.792452 -423.309034)
		(width 0.14732)
		(layer "In11.Cu")
		(net "P5E_CPU1_PE2_TX_C_DP<7>")
	)
	(segment
		(start 147.724114 -403.883876)
		(end 148.027136 -403.580854)
		(width 0.13208)
		(layer "F.Cu")
		(net "P5E_CPU1_PE2_TX_C_DP<6>")
	)
	(segment
		(start 148.027136 -403.580854)
		(end 148.027136 -402.962872)
		(width 0.13208)
		(layer "F.Cu")
		(net "P5E_CPU1_PE2_TX_C_DP<6>")
	)
	(segment
		(start 148.027136 -402.962872)
		(end 147.702016 -402.637752)
		(width 0.13208)
		(layer "F.Cu")
		(net "P5E_CPU1_PE2_TX_C_DP<6>")
	)
	(segment
		(start 147.702016 -402.637752)
		(end 147.698714 -402.637752)
		(width 0.13208)
		(layer "F.Cu")
		(net "P5E_CPU1_PE2_TX_C_DP<6>")
	)
	(segment
		(start 144.750028 -428.28972)
		(end 144.750028 -427.980602)
		(width 0.14732)
		(layer "In11.Cu")
		(net "P5E_CPU1_PE2_TX_C_DP<6>")
	)
	(segment
		(start 144.076928 -427.793658)
		(end 143.792448 -427.509178)
		(width 0.14732)
		(layer "In11.Cu")
		(net "P5E_CPU1_PE2_TX_C_DP<6>")
	)
	(segment
		(start 143.792448 -427.509178)
		(end 143.792448 -424.640248)
		(width 0.14732)
		(layer "In11.Cu")
		(net "P5E_CPU1_PE2_TX_C_DP<6>")
	)
	(segment
		(start 148.018754 -404.178516)
		(end 147.724114 -403.883876)
		(width 0.14732)
		(layer "In11.Cu")
		(net "P5E_CPU1_PE2_TX_C_DP<6>")
	)
	(segment
		(start 144.750028 -427.980602)
		(end 144.563084 -427.793658)
		(width 0.14732)
		(layer "In11.Cu")
		(net "P5E_CPU1_PE2_TX_C_DP<6>")
	)
	(segment
		(start 144.563084 -427.793658)
		(end 144.076928 -427.793658)
		(width 0.14732)
		(layer "In11.Cu")
		(net "P5E_CPU1_PE2_TX_C_DP<6>")
	)
	(segment
		(start 147.833334 -410.41193)
		(end 147.833334 -406.30475)
		(width 0.14732)
		(layer "In11.Cu")
		(net "P5E_CPU1_PE2_TX_C_DP<6>")
	)
	(segment
		(start 143.792448 -424.640248)
		(end 147.833334 -410.41193)
		(width 0.14732)
		(layer "In11.Cu")
		(net "P5E_CPU1_PE2_TX_C_DP<6>")
	)
	(segment
		(start 148.018754 -406.11933)
		(end 148.018754 -404.178516)
		(width 0.14732)
		(layer "In11.Cu")
		(net "P5E_CPU1_PE2_TX_C_DP<6>")
	)
	(segment
		(start 147.833334 -406.30475)
		(end 148.018754 -406.11933)
		(width 0.14732)
		(layer "In11.Cu")
		(net "P5E_CPU1_PE2_TX_C_DP<6>")
	)
	(segment
		(start 150.765256 -402.637752)
		(end 150.761954 -402.637752)
		(width 0.13208)
		(layer "F.Cu")
		(net "P5E_CPU1_PE2_TX_C_DP<5>")
	)
	(segment
		(start 151.090376 -402.962872)
		(end 150.765256 -402.637752)
		(width 0.13208)
		(layer "F.Cu")
		(net "P5E_CPU1_PE2_TX_C_DP<5>")
	)
	(segment
		(start 150.787354 -403.883876)
		(end 151.090376 -403.580854)
		(width 0.13208)
		(layer "F.Cu")
		(net "P5E_CPU1_PE2_TX_C_DP<5>")
	)
	(segment
		(start 151.090376 -403.580854)
		(end 151.090376 -402.962872)
		(width 0.13208)
		(layer "F.Cu")
		(net "P5E_CPU1_PE2_TX_C_DP<5>")
	)
	(segment
		(start 146.076924 -426.793914)
		(end 145.792444 -426.509434)
		(width 0.14732)
		(layer "In11.Cu")
		(net "P5E_CPU1_PE2_TX_C_DP<5>")
	)
	(segment
		(start 151.081994 -406.11933)
		(end 151.081994 -404.178516)
		(width 0.14732)
		(layer "In11.Cu")
		(net "P5E_CPU1_PE2_TX_C_DP<5>")
	)
	(segment
		(start 146.526758 -422.456864)
		(end 146.527012 -422.456102)
		(width 0.14732)
		(layer "In11.Cu")
		(net "P5E_CPU1_PE2_TX_C_DP<5>")
	)
	(segment
		(start 145.792444 -426.509434)
		(end 145.792444 -424.467528)
		(width 0.14732)
		(layer "In11.Cu")
		(net "P5E_CPU1_PE2_TX_C_DP<5>")
	)
	(segment
		(start 151.081994 -404.178516)
		(end 150.787354 -403.883876)
		(width 0.14732)
		(layer "In11.Cu")
		(net "P5E_CPU1_PE2_TX_C_DP<5>")
	)
	(segment
		(start 146.527012 -422.456102)
		(end 150.896574 -410.49194)
		(width 0.14732)
		(layer "In11.Cu")
		(net "P5E_CPU1_PE2_TX_C_DP<5>")
	)
	(segment
		(start 146.750024 -427.289976)
		(end 146.750024 -426.980858)
		(width 0.14732)
		(layer "In11.Cu")
		(net "P5E_CPU1_PE2_TX_C_DP<5>")
	)
	(segment
		(start 145.792444 -424.467528)
		(end 146.526758 -422.456864)
		(width 0.14732)
		(layer "In11.Cu")
		(net "P5E_CPU1_PE2_TX_C_DP<5>")
	)
	(segment
		(start 150.896574 -406.30475)
		(end 151.081994 -406.11933)
		(width 0.14732)
		(layer "In11.Cu")
		(net "P5E_CPU1_PE2_TX_C_DP<5>")
	)
	(segment
		(start 146.750024 -426.980858)
		(end 146.56308 -426.793914)
		(width 0.14732)
		(layer "In11.Cu")
		(net "P5E_CPU1_PE2_TX_C_DP<5>")
	)
	(segment
		(start 146.56308 -426.793914)
		(end 146.076924 -426.793914)
		(width 0.14732)
		(layer "In11.Cu")
		(net "P5E_CPU1_PE2_TX_C_DP<5>")
	)
	(segment
		(start 150.896574 -410.49194)
		(end 150.896574 -406.30475)
		(width 0.14732)
		(layer "In11.Cu")
		(net "P5E_CPU1_PE2_TX_C_DP<5>")
	)
	(segment
		(start 153.850594 -403.883876)
		(end 154.153616 -403.580854)
		(width 0.13208)
		(layer "F.Cu")
		(net "P5E_CPU1_PE2_TX_C_DP<4>")
	)
	(segment
		(start 154.153616 -403.580854)
		(end 154.153616 -402.962872)
		(width 0.13208)
		(layer "F.Cu")
		(net "P5E_CPU1_PE2_TX_C_DP<4>")
	)
	(segment
		(start 154.153616 -402.962872)
		(end 153.828496 -402.637752)
		(width 0.13208)
		(layer "F.Cu")
		(net "P5E_CPU1_PE2_TX_C_DP<4>")
	)
	(segment
		(start 153.828496 -402.637752)
		(end 153.825194 -402.637752)
		(width 0.13208)
		(layer "F.Cu")
		(net "P5E_CPU1_PE2_TX_C_DP<4>")
	)
	(segment
		(start 154.145234 -406.11933)
		(end 154.145234 -404.178516)
		(width 0.14732)
		(layer "In11.Cu")
		(net "P5E_CPU1_PE2_TX_C_DP<4>")
	)
	(segment
		(start 148.75002 -428.28972)
		(end 148.75002 -427.980602)
		(width 0.14732)
		(layer "In11.Cu")
		(net "P5E_CPU1_PE2_TX_C_DP<4>")
	)
	(segment
		(start 154.145234 -404.178516)
		(end 153.850594 -403.883876)
		(width 0.14732)
		(layer "In11.Cu")
		(net "P5E_CPU1_PE2_TX_C_DP<4>")
	)
	(segment
		(start 147.79244 -427.509178)
		(end 147.79244 -424.139868)
		(width 0.14732)
		(layer "In11.Cu")
		(net "P5E_CPU1_PE2_TX_C_DP<4>")
	)
	(segment
		(start 153.959814 -410.558234)
		(end 153.959814 -406.30475)
		(width 0.14732)
		(layer "In11.Cu")
		(net "P5E_CPU1_PE2_TX_C_DP<4>")
	)
	(segment
		(start 153.959814 -406.30475)
		(end 154.145234 -406.11933)
		(width 0.14732)
		(layer "In11.Cu")
		(net "P5E_CPU1_PE2_TX_C_DP<4>")
	)
	(segment
		(start 147.79244 -424.139868)
		(end 153.959814 -410.558234)
		(width 0.14732)
		(layer "In11.Cu")
		(net "P5E_CPU1_PE2_TX_C_DP<4>")
	)
	(segment
		(start 148.07692 -427.793658)
		(end 147.79244 -427.509178)
		(width 0.14732)
		(layer "In11.Cu")
		(net "P5E_CPU1_PE2_TX_C_DP<4>")
	)
	(segment
		(start 148.75002 -427.980602)
		(end 148.563076 -427.793658)
		(width 0.14732)
		(layer "In11.Cu")
		(net "P5E_CPU1_PE2_TX_C_DP<4>")
	)
	(segment
		(start 148.563076 -427.793658)
		(end 148.07692 -427.793658)
		(width 0.14732)
		(layer "In11.Cu")
		(net "P5E_CPU1_PE2_TX_C_DP<4>")
	)
	(segment
		(start 157.216856 -402.962872)
		(end 156.891736 -402.637752)
		(width 0.13208)
		(layer "F.Cu")
		(net "P5E_CPU1_PE2_TX_C_DP<3>")
	)
	(segment
		(start 156.891736 -402.637752)
		(end 156.888434 -402.637752)
		(width 0.13208)
		(layer "F.Cu")
		(net "P5E_CPU1_PE2_TX_C_DP<3>")
	)
	(segment
		(start 157.216856 -403.580854)
		(end 157.216856 -402.962872)
		(width 0.13208)
		(layer "F.Cu")
		(net "P5E_CPU1_PE2_TX_C_DP<3>")
	)
	(segment
		(start 156.913834 -403.883876)
		(end 157.216856 -403.580854)
		(width 0.13208)
		(layer "F.Cu")
		(net "P5E_CPU1_PE2_TX_C_DP<3>")
	)
	(segment
		(start 157.023054 -410.582872)
		(end 157.023054 -406.30475)
		(width 0.14732)
		(layer "In11.Cu")
		(net "P5E_CPU1_PE2_TX_C_DP<3>")
	)
	(segment
		(start 150.750016 -426.980858)
		(end 150.563072 -426.793914)
		(width 0.14732)
		(layer "In11.Cu")
		(net "P5E_CPU1_PE2_TX_C_DP<3>")
	)
	(segment
		(start 157.208474 -404.178516)
		(end 156.913834 -403.883876)
		(width 0.14732)
		(layer "In11.Cu")
		(net "P5E_CPU1_PE2_TX_C_DP<3>")
	)
	(segment
		(start 150.563072 -426.793914)
		(end 150.076916 -426.793914)
		(width 0.14732)
		(layer "In11.Cu")
		(net "P5E_CPU1_PE2_TX_C_DP<3>")
	)
	(segment
		(start 150.750016 -427.289976)
		(end 150.750016 -426.980858)
		(width 0.14732)
		(layer "In11.Cu")
		(net "P5E_CPU1_PE2_TX_C_DP<3>")
	)
	(segment
		(start 157.208474 -406.11933)
		(end 157.208474 -404.178516)
		(width 0.14732)
		(layer "In11.Cu")
		(net "P5E_CPU1_PE2_TX_C_DP<3>")
	)
	(segment
		(start 149.792436 -424.429428)
		(end 157.023054 -410.582872)
		(width 0.14732)
		(layer "In11.Cu")
		(net "P5E_CPU1_PE2_TX_C_DP<3>")
	)
	(segment
		(start 149.792436 -426.509434)
		(end 149.792436 -424.429428)
		(width 0.14732)
		(layer "In11.Cu")
		(net "P5E_CPU1_PE2_TX_C_DP<3>")
	)
	(segment
		(start 157.023054 -406.30475)
		(end 157.208474 -406.11933)
		(width 0.14732)
		(layer "In11.Cu")
		(net "P5E_CPU1_PE2_TX_C_DP<3>")
	)
	(segment
		(start 150.076916 -426.793914)
		(end 149.792436 -426.509434)
		(width 0.14732)
		(layer "In11.Cu")
		(net "P5E_CPU1_PE2_TX_C_DP<3>")
	)
	(segment
		(start 160.280096 -402.962872)
		(end 159.954976 -402.637752)
		(width 0.13208)
		(layer "F.Cu")
		(net "P5E_CPU1_PE2_TX_C_DP<2>")
	)
	(segment
		(start 159.954976 -402.637752)
		(end 159.951674 -402.637752)
		(width 0.13208)
		(layer "F.Cu")
		(net "P5E_CPU1_PE2_TX_C_DP<2>")
	)
	(segment
		(start 159.977074 -403.883876)
		(end 160.280096 -403.580854)
		(width 0.13208)
		(layer "F.Cu")
		(net "P5E_CPU1_PE2_TX_C_DP<2>")
	)
	(segment
		(start 160.280096 -403.580854)
		(end 160.280096 -402.962872)
		(width 0.13208)
		(layer "F.Cu")
		(net "P5E_CPU1_PE2_TX_C_DP<2>")
	)
	(segment
		(start 160.271714 -406.11933)
		(end 160.271714 -404.178516)
		(width 0.14732)
		(layer "In11.Cu")
		(net "P5E_CPU1_PE2_TX_C_DP<2>")
	)
	(segment
		(start 160.086294 -410.607256)
		(end 160.086294 -406.30475)
		(width 0.14732)
		(layer "In11.Cu")
		(net "P5E_CPU1_PE2_TX_C_DP<2>")
	)
	(segment
		(start 152.076912 -427.793658)
		(end 151.792432 -427.509178)
		(width 0.14732)
		(layer "In11.Cu")
		(net "P5E_CPU1_PE2_TX_C_DP<2>")
	)
	(segment
		(start 152.750012 -428.28972)
		(end 152.750012 -427.980602)
		(width 0.14732)
		(layer "In11.Cu")
		(net "P5E_CPU1_PE2_TX_C_DP<2>")
	)
	(segment
		(start 152.563068 -427.793658)
		(end 152.076912 -427.793658)
		(width 0.14732)
		(layer "In11.Cu")
		(net "P5E_CPU1_PE2_TX_C_DP<2>")
	)
	(segment
		(start 160.271714 -404.178516)
		(end 159.977074 -403.883876)
		(width 0.14732)
		(layer "In11.Cu")
		(net "P5E_CPU1_PE2_TX_C_DP<2>")
	)
	(segment
		(start 160.086294 -406.30475)
		(end 160.271714 -406.11933)
		(width 0.14732)
		(layer "In11.Cu")
		(net "P5E_CPU1_PE2_TX_C_DP<2>")
	)
	(segment
		(start 151.792432 -424.525948)
		(end 160.086294 -410.607256)
		(width 0.14732)
		(layer "In11.Cu")
		(net "P5E_CPU1_PE2_TX_C_DP<2>")
	)
	(segment
		(start 152.750012 -427.980602)
		(end 152.563068 -427.793658)
		(width 0.14732)
		(layer "In11.Cu")
		(net "P5E_CPU1_PE2_TX_C_DP<2>")
	)
	(segment
		(start 151.792432 -427.509178)
		(end 151.792432 -424.525948)
		(width 0.14732)
		(layer "In11.Cu")
		(net "P5E_CPU1_PE2_TX_C_DP<2>")
	)
	(segment
		(start 163.343336 -402.962872)
		(end 163.018216 -402.637752)
		(width 0.13208)
		(layer "F.Cu")
		(net "P5E_CPU1_PE2_TX_C_DP<1>")
	)
	(segment
		(start 163.343336 -403.580854)
		(end 163.343336 -402.962872)
		(width 0.13208)
		(layer "F.Cu")
		(net "P5E_CPU1_PE2_TX_C_DP<1>")
	)
	(segment
		(start 163.018216 -402.637752)
		(end 163.014914 -402.637752)
		(width 0.13208)
		(layer "F.Cu")
		(net "P5E_CPU1_PE2_TX_C_DP<1>")
	)
	(segment
		(start 163.040314 -403.883876)
		(end 163.343336 -403.580854)
		(width 0.13208)
		(layer "F.Cu")
		(net "P5E_CPU1_PE2_TX_C_DP<1>")
	)
	(segment
		(start 163.149534 -406.30475)
		(end 163.334954 -406.11933)
		(width 0.14732)
		(layer "In11.Cu")
		(net "P5E_CPU1_PE2_TX_C_DP<1>")
	)
	(segment
		(start 154.750008 -427.289976)
		(end 154.750008 -426.980858)
		(width 0.14732)
		(layer "In11.Cu")
		(net "P5E_CPU1_PE2_TX_C_DP<1>")
	)
	(segment
		(start 154.076908 -426.793914)
		(end 153.792428 -426.509434)
		(width 0.14732)
		(layer "In11.Cu")
		(net "P5E_CPU1_PE2_TX_C_DP<1>")
	)
	(segment
		(start 153.792428 -424.350688)
		(end 163.149534 -410.634434)
		(width 0.14732)
		(layer "In11.Cu")
		(net "P5E_CPU1_PE2_TX_C_DP<1>")
	)
	(segment
		(start 163.334954 -404.178516)
		(end 163.040314 -403.883876)
		(width 0.14732)
		(layer "In11.Cu")
		(net "P5E_CPU1_PE2_TX_C_DP<1>")
	)
	(segment
		(start 153.792428 -426.509434)
		(end 153.792428 -424.350688)
		(width 0.14732)
		(layer "In11.Cu")
		(net "P5E_CPU1_PE2_TX_C_DP<1>")
	)
	(segment
		(start 163.149534 -410.634434)
		(end 163.149534 -406.30475)
		(width 0.14732)
		(layer "In11.Cu")
		(net "P5E_CPU1_PE2_TX_C_DP<1>")
	)
	(segment
		(start 163.334954 -406.11933)
		(end 163.334954 -404.178516)
		(width 0.14732)
		(layer "In11.Cu")
		(net "P5E_CPU1_PE2_TX_C_DP<1>")
	)
	(segment
		(start 154.750008 -426.980858)
		(end 154.563064 -426.793914)
		(width 0.14732)
		(layer "In11.Cu")
		(net "P5E_CPU1_PE2_TX_C_DP<1>")
	)
	(segment
		(start 154.563064 -426.793914)
		(end 154.076908 -426.793914)
		(width 0.14732)
		(layer "In11.Cu")
		(net "P5E_CPU1_PE2_TX_C_DP<1>")
	)
	(segment
		(start 120.132856 -402.637752)
		(end 120.129554 -402.637752)
		(width 0.13208)
		(layer "F.Cu")
		(net "P5E_CPU1_PE2_TX_C_DP<15>")
	)
	(segment
		(start 120.457976 -402.962872)
		(end 120.132856 -402.637752)
		(width 0.13208)
		(layer "F.Cu")
		(net "P5E_CPU1_PE2_TX_C_DP<15>")
	)
	(segment
		(start 120.457976 -403.580854)
		(end 120.457976 -402.962872)
		(width 0.13208)
		(layer "F.Cu")
		(net "P5E_CPU1_PE2_TX_C_DP<15>")
	)
	(segment
		(start 120.154954 -403.883876)
		(end 120.457976 -403.580854)
		(width 0.13208)
		(layer "F.Cu")
		(net "P5E_CPU1_PE2_TX_C_DP<15>")
	)
	(segment
		(start 120.449594 -404.178516)
		(end 120.154954 -403.883876)
		(width 0.14732)
		(layer "In11.Cu")
		(net "P5E_CPU1_PE2_TX_C_DP<15>")
	)
	(segment
		(start 122.090688 -416.864038)
		(end 122.090434 -416.863276)
		(width 0.14732)
		(layer "In11.Cu")
		(net "P5E_CPU1_PE2_TX_C_DP<15>")
	)
	(segment
		(start 124.879608 -426.522388)
		(end 122.090688 -416.864038)
		(width 0.14732)
		(layer "In11.Cu")
		(net "P5E_CPU1_PE2_TX_C_DP<15>")
	)
	(segment
		(start 120.449594 -406.11933)
		(end 120.449594 -404.178516)
		(width 0.14732)
		(layer "In11.Cu")
		(net "P5E_CPU1_PE2_TX_C_DP<15>")
	)
	(segment
		(start 121.684542 -415.459672)
		(end 120.264174 -410.538676)
		(width 0.14732)
		(layer "In11.Cu")
		(net "P5E_CPU1_PE2_TX_C_DP<15>")
	)
	(segment
		(start 125.563122 -426.793914)
		(end 125.240288 -426.793914)
		(width 0.14732)
		(layer "In11.Cu")
		(net "P5E_CPU1_PE2_TX_C_DP<15>")
	)
	(segment
		(start 120.264174 -406.30475)
		(end 120.449594 -406.11933)
		(width 0.14732)
		(layer "In11.Cu")
		(net "P5E_CPU1_PE2_TX_C_DP<15>")
	)
	(segment
		(start 121.689368 -415.47415)
		(end 121.684542 -415.459672)
		(width 0.14732)
		(layer "In11.Cu")
		(net "P5E_CPU1_PE2_TX_C_DP<15>")
	)
	(segment
		(start 125.750066 -427.289976)
		(end 125.750066 -426.980858)
		(width 0.14732)
		(layer "In11.Cu")
		(net "P5E_CPU1_PE2_TX_C_DP<15>")
	)
	(segment
		(start 125.750066 -426.980858)
		(end 125.563122 -426.793914)
		(width 0.14732)
		(layer "In11.Cu")
		(net "P5E_CPU1_PE2_TX_C_DP<15>")
	)
	(segment
		(start 125.240288 -426.793914)
		(end 124.879608 -426.522388)
		(width 0.14732)
		(layer "In11.Cu")
		(net "P5E_CPU1_PE2_TX_C_DP<15>")
	)
	(segment
		(start 120.264174 -410.538676)
		(end 120.264174 -406.30475)
		(width 0.14732)
		(layer "In11.Cu")
		(net "P5E_CPU1_PE2_TX_C_DP<15>")
	)
	(segment
		(start 122.090434 -416.863276)
		(end 121.689368 -415.47415)
		(width 0.14732)
		(layer "In11.Cu")
		(net "P5E_CPU1_PE2_TX_C_DP<15>")
	)
	(segment
		(start 123.521216 -402.962872)
		(end 123.196096 -402.637752)
		(width 0.13208)
		(layer "F.Cu")
		(net "P5E_CPU1_PE2_TX_C_DP<14>")
	)
	(segment
		(start 123.196096 -402.637752)
		(end 123.192794 -402.637752)
		(width 0.13208)
		(layer "F.Cu")
		(net "P5E_CPU1_PE2_TX_C_DP<14>")
	)
	(segment
		(start 123.521216 -403.580854)
		(end 123.521216 -402.962872)
		(width 0.13208)
		(layer "F.Cu")
		(net "P5E_CPU1_PE2_TX_C_DP<14>")
	)
	(segment
		(start 123.218194 -403.883876)
		(end 123.521216 -403.580854)
		(width 0.13208)
		(layer "F.Cu")
		(net "P5E_CPU1_PE2_TX_C_DP<14>")
	)
	(segment
		(start 123.512834 -404.178516)
		(end 123.218194 -403.883876)
		(width 0.14732)
		(layer "In11.Cu")
		(net "P5E_CPU1_PE2_TX_C_DP<14>")
	)
	(segment
		(start 123.512834 -406.11933)
		(end 123.512834 -404.178516)
		(width 0.14732)
		(layer "In11.Cu")
		(net "P5E_CPU1_PE2_TX_C_DP<14>")
	)
	(segment
		(start 123.497594 -411.438344)
		(end 123.49734 -411.43809)
		(width 0.14732)
		(layer "In11.Cu")
		(net "P5E_CPU1_PE2_TX_C_DP<14>")
	)
	(segment
		(start 126.792482 -427.509178)
		(end 126.792482 -424.035982)
		(width 0.14732)
		(layer "In11.Cu")
		(net "P5E_CPU1_PE2_TX_C_DP<14>")
	)
	(segment
		(start 123.49734 -411.43809)
		(end 123.327414 -410.787596)
		(width 0.14732)
		(layer "In11.Cu")
		(net "P5E_CPU1_PE2_TX_C_DP<14>")
	)
	(segment
		(start 127.076962 -427.793658)
		(end 126.792482 -427.509178)
		(width 0.14732)
		(layer "In11.Cu")
		(net "P5E_CPU1_PE2_TX_C_DP<14>")
	)
	(segment
		(start 126.792482 -424.035982)
		(end 123.497594 -411.438344)
		(width 0.14732)
		(layer "In11.Cu")
		(net "P5E_CPU1_PE2_TX_C_DP<14>")
	)
	(segment
		(start 127.750062 -428.28972)
		(end 127.750062 -427.980602)
		(width 0.14732)
		(layer "In11.Cu")
		(net "P5E_CPU1_PE2_TX_C_DP<14>")
	)
	(segment
		(start 123.327414 -410.787596)
		(end 123.327414 -406.30475)
		(width 0.14732)
		(layer "In11.Cu")
		(net "P5E_CPU1_PE2_TX_C_DP<14>")
	)
	(segment
		(start 127.750062 -427.980602)
		(end 127.563118 -427.793658)
		(width 0.14732)
		(layer "In11.Cu")
		(net "P5E_CPU1_PE2_TX_C_DP<14>")
	)
	(segment
		(start 127.563118 -427.793658)
		(end 127.076962 -427.793658)
		(width 0.14732)
		(layer "In11.Cu")
		(net "P5E_CPU1_PE2_TX_C_DP<14>")
	)
	(segment
		(start 123.327414 -406.30475)
		(end 123.512834 -406.11933)
		(width 0.14732)
		(layer "In11.Cu")
		(net "P5E_CPU1_PE2_TX_C_DP<14>")
	)
	(segment
		(start 126.259336 -402.637752)
		(end 126.256034 -402.637752)
		(width 0.13208)
		(layer "F.Cu")
		(net "P5E_CPU1_PE2_TX_C_DP<13>")
	)
	(segment
		(start 126.584456 -402.962872)
		(end 126.259336 -402.637752)
		(width 0.13208)
		(layer "F.Cu")
		(net "P5E_CPU1_PE2_TX_C_DP<13>")
	)
	(segment
		(start 126.281434 -403.883876)
		(end 126.584456 -403.580854)
		(width 0.13208)
		(layer "F.Cu")
		(net "P5E_CPU1_PE2_TX_C_DP<13>")
	)
	(segment
		(start 126.584456 -403.580854)
		(end 126.584456 -402.962872)
		(width 0.13208)
		(layer "F.Cu")
		(net "P5E_CPU1_PE2_TX_C_DP<13>")
	)
	(segment
		(start 129.076958 -426.793914)
		(end 128.792478 -426.509434)
		(width 0.14732)
		(layer "In11.Cu")
		(net "P5E_CPU1_PE2_TX_C_DP<13>")
	)
	(segment
		(start 126.63805 -411.985968)
		(end 126.637796 -411.985714)
		(width 0.14732)
		(layer "In11.Cu")
		(net "P5E_CPU1_PE2_TX_C_DP<13>")
	)
	(segment
		(start 129.563114 -426.793914)
		(end 129.076958 -426.793914)
		(width 0.14732)
		(layer "In11.Cu")
		(net "P5E_CPU1_PE2_TX_C_DP<13>")
	)
	(segment
		(start 126.576074 -406.11933)
		(end 126.576074 -404.178516)
		(width 0.14732)
		(layer "In11.Cu")
		(net "P5E_CPU1_PE2_TX_C_DP<13>")
	)
	(segment
		(start 128.792478 -423.083736)
		(end 126.63805 -411.985968)
		(width 0.14732)
		(layer "In11.Cu")
		(net "P5E_CPU1_PE2_TX_C_DP<13>")
	)
	(segment
		(start 126.637796 -411.985714)
		(end 126.390654 -410.710888)
		(width 0.14732)
		(layer "In11.Cu")
		(net "P5E_CPU1_PE2_TX_C_DP<13>")
	)
	(segment
		(start 129.750058 -427.289976)
		(end 129.750058 -426.980858)
		(width 0.14732)
		(layer "In11.Cu")
		(net "P5E_CPU1_PE2_TX_C_DP<13>")
	)
	(segment
		(start 128.792478 -426.509434)
		(end 128.792478 -423.083736)
		(width 0.14732)
		(layer "In11.Cu")
		(net "P5E_CPU1_PE2_TX_C_DP<13>")
	)
	(segment
		(start 129.750058 -426.980858)
		(end 129.563114 -426.793914)
		(width 0.14732)
		(layer "In11.Cu")
		(net "P5E_CPU1_PE2_TX_C_DP<13>")
	)
	(segment
		(start 126.390654 -410.710888)
		(end 126.390654 -406.30475)
		(width 0.14732)
		(layer "In11.Cu")
		(net "P5E_CPU1_PE2_TX_C_DP<13>")
	)
	(segment
		(start 126.576074 -404.178516)
		(end 126.281434 -403.883876)
		(width 0.14732)
		(layer "In11.Cu")
		(net "P5E_CPU1_PE2_TX_C_DP<13>")
	)
	(segment
		(start 126.390654 -406.30475)
		(end 126.576074 -406.11933)
		(width 0.14732)
		(layer "In11.Cu")
		(net "P5E_CPU1_PE2_TX_C_DP<13>")
	)
	(segment
		(start 129.647696 -402.962872)
		(end 129.322576 -402.637752)
		(width 0.13208)
		(layer "F.Cu")
		(net "P5E_CPU1_PE2_TX_C_DP<12>")
	)
	(segment
		(start 129.322576 -402.637752)
		(end 129.319274 -402.637752)
		(width 0.13208)
		(layer "F.Cu")
		(net "P5E_CPU1_PE2_TX_C_DP<12>")
	)
	(segment
		(start 129.647696 -403.580854)
		(end 129.647696 -402.962872)
		(width 0.13208)
		(layer "F.Cu")
		(net "P5E_CPU1_PE2_TX_C_DP<12>")
	)
	(segment
		(start 129.344674 -403.883876)
		(end 129.647696 -403.580854)
		(width 0.13208)
		(layer "F.Cu")
		(net "P5E_CPU1_PE2_TX_C_DP<12>")
	)
	(segment
		(start 129.453894 -406.30475)
		(end 129.639314 -406.11933)
		(width 0.14732)
		(layer "In11.Cu")
		(net "P5E_CPU1_PE2_TX_C_DP<12>")
	)
	(segment
		(start 129.639314 -406.11933)
		(end 129.639314 -404.178516)
		(width 0.14732)
		(layer "In11.Cu")
		(net "P5E_CPU1_PE2_TX_C_DP<12>")
	)
	(segment
		(start 131.750054 -427.980602)
		(end 131.56311 -427.793658)
		(width 0.14732)
		(layer "In11.Cu")
		(net "P5E_CPU1_PE2_TX_C_DP<12>")
	)
	(segment
		(start 129.453894 -412.587186)
		(end 129.453894 -406.30475)
		(width 0.14732)
		(layer "In11.Cu")
		(net "P5E_CPU1_PE2_TX_C_DP<12>")
	)
	(segment
		(start 130.792474 -424.99153)
		(end 129.453894 -412.587186)
		(width 0.14732)
		(layer "In11.Cu")
		(net "P5E_CPU1_PE2_TX_C_DP<12>")
	)
	(segment
		(start 131.750054 -428.28972)
		(end 131.750054 -427.980602)
		(width 0.14732)
		(layer "In11.Cu")
		(net "P5E_CPU1_PE2_TX_C_DP<12>")
	)
	(segment
		(start 129.639314 -404.178516)
		(end 129.344674 -403.883876)
		(width 0.14732)
		(layer "In11.Cu")
		(net "P5E_CPU1_PE2_TX_C_DP<12>")
	)
	(segment
		(start 131.076954 -427.793658)
		(end 130.792474 -427.509178)
		(width 0.14732)
		(layer "In11.Cu")
		(net "P5E_CPU1_PE2_TX_C_DP<12>")
	)
	(segment
		(start 130.792474 -427.509178)
		(end 130.792474 -424.99153)
		(width 0.14732)
		(layer "In11.Cu")
		(net "P5E_CPU1_PE2_TX_C_DP<12>")
	)
	(segment
		(start 131.56311 -427.793658)
		(end 131.076954 -427.793658)
		(width 0.14732)
		(layer "In11.Cu")
		(net "P5E_CPU1_PE2_TX_C_DP<12>")
	)
	(segment
		(start 132.710936 -403.580854)
		(end 132.710936 -402.962872)
		(width 0.13208)
		(layer "F.Cu")
		(net "P5E_CPU1_PE2_TX_C_DP<11>")
	)
	(segment
		(start 132.710936 -402.962872)
		(end 132.385816 -402.637752)
		(width 0.13208)
		(layer "F.Cu")
		(net "P5E_CPU1_PE2_TX_C_DP<11>")
	)
	(segment
		(start 132.385816 -402.637752)
		(end 132.382514 -402.637752)
		(width 0.13208)
		(layer "F.Cu")
		(net "P5E_CPU1_PE2_TX_C_DP<11>")
	)
	(segment
		(start 132.407914 -403.883876)
		(end 132.710936 -403.580854)
		(width 0.13208)
		(layer "F.Cu")
		(net "P5E_CPU1_PE2_TX_C_DP<11>")
	)
	(segment
		(start 132.79247 -426.509434)
		(end 132.79247 -424.236642)
		(width 0.14732)
		(layer "In11.Cu")
		(net "P5E_CPU1_PE2_TX_C_DP<11>")
	)
	(segment
		(start 133.75005 -427.289976)
		(end 133.75005 -426.980858)
		(width 0.14732)
		(layer "In11.Cu")
		(net "P5E_CPU1_PE2_TX_C_DP<11>")
	)
	(segment
		(start 133.563106 -426.793914)
		(end 133.07695 -426.793914)
		(width 0.14732)
		(layer "In11.Cu")
		(net "P5E_CPU1_PE2_TX_C_DP<11>")
	)
	(segment
		(start 133.07695 -426.793914)
		(end 132.79247 -426.509434)
		(width 0.14732)
		(layer "In11.Cu")
		(net "P5E_CPU1_PE2_TX_C_DP<11>")
	)
	(segment
		(start 132.517134 -413.831786)
		(end 132.517134 -406.30475)
		(width 0.14732)
		(layer "In11.Cu")
		(net "P5E_CPU1_PE2_TX_C_DP<11>")
	)
	(segment
		(start 133.75005 -426.980858)
		(end 133.563106 -426.793914)
		(width 0.14732)
		(layer "In11.Cu")
		(net "P5E_CPU1_PE2_TX_C_DP<11>")
	)
	(segment
		(start 132.702554 -404.178516)
		(end 132.407914 -403.883876)
		(width 0.14732)
		(layer "In11.Cu")
		(net "P5E_CPU1_PE2_TX_C_DP<11>")
	)
	(segment
		(start 132.517134 -406.30475)
		(end 132.702554 -406.11933)
		(width 0.14732)
		(layer "In11.Cu")
		(net "P5E_CPU1_PE2_TX_C_DP<11>")
	)
	(segment
		(start 132.79247 -424.236642)
		(end 132.517134 -413.831786)
		(width 0.14732)
		(layer "In11.Cu")
		(net "P5E_CPU1_PE2_TX_C_DP<11>")
	)
	(segment
		(start 132.702554 -406.11933)
		(end 132.702554 -404.178516)
		(width 0.14732)
		(layer "In11.Cu")
		(net "P5E_CPU1_PE2_TX_C_DP<11>")
	)
	(segment
		(start 135.774176 -403.580854)
		(end 135.774176 -402.962872)
		(width 0.13208)
		(layer "F.Cu")
		(net "P5E_CPU1_PE2_TX_C_DP<10>")
	)
	(segment
		(start 135.774176 -402.962872)
		(end 135.449056 -402.637752)
		(width 0.13208)
		(layer "F.Cu")
		(net "P5E_CPU1_PE2_TX_C_DP<10>")
	)
	(segment
		(start 135.449056 -402.637752)
		(end 135.445754 -402.637752)
		(width 0.13208)
		(layer "F.Cu")
		(net "P5E_CPU1_PE2_TX_C_DP<10>")
	)
	(segment
		(start 135.471154 -403.883876)
		(end 135.774176 -403.580854)
		(width 0.13208)
		(layer "F.Cu")
		(net "P5E_CPU1_PE2_TX_C_DP<10>")
	)
	(segment
		(start 135.405622 -412.02737)
		(end 135.580374 -410.5275)
		(width 0.14732)
		(layer "In11.Cu")
		(net "P5E_CPU1_PE2_TX_C_DP<10>")
	)
	(segment
		(start 134.97179 -420.672768)
		(end 134.972298 -420.672514)
		(width 0.14732)
		(layer "In11.Cu")
		(net "P5E_CPU1_PE2_TX_C_DP<10>")
	)
	(segment
		(start 135.076946 -427.793658)
		(end 134.792466 -427.509178)
		(width 0.14732)
		(layer "In11.Cu")
		(net "P5E_CPU1_PE2_TX_C_DP<10>")
	)
	(segment
		(start 135.580374 -406.30475)
		(end 135.765794 -406.11933)
		(width 0.14732)
		(layer "In11.Cu")
		(net "P5E_CPU1_PE2_TX_C_DP<10>")
	)
	(segment
		(start 134.792466 -427.509178)
		(end 134.792466 -424.254168)
		(width 0.14732)
		(layer "In11.Cu")
		(net "P5E_CPU1_PE2_TX_C_DP<10>")
	)
	(segment
		(start 135.765794 -404.178516)
		(end 135.471154 -403.883876)
		(width 0.14732)
		(layer "In11.Cu")
		(net "P5E_CPU1_PE2_TX_C_DP<10>")
	)
	(segment
		(start 134.792466 -424.254168)
		(end 134.97179 -420.672768)
		(width 0.14732)
		(layer "In11.Cu")
		(net "P5E_CPU1_PE2_TX_C_DP<10>")
	)
	(segment
		(start 135.563102 -427.793658)
		(end 135.076946 -427.793658)
		(width 0.14732)
		(layer "In11.Cu")
		(net "P5E_CPU1_PE2_TX_C_DP<10>")
	)
	(segment
		(start 135.580374 -410.5275)
		(end 135.580374 -406.30475)
		(width 0.14732)
		(layer "In11.Cu")
		(net "P5E_CPU1_PE2_TX_C_DP<10>")
	)
	(segment
		(start 134.972298 -420.672514)
		(end 135.405622 -412.02737)
		(width 0.14732)
		(layer "In11.Cu")
		(net "P5E_CPU1_PE2_TX_C_DP<10>")
	)
	(segment
		(start 135.765794 -406.11933)
		(end 135.765794 -404.178516)
		(width 0.14732)
		(layer "In11.Cu")
		(net "P5E_CPU1_PE2_TX_C_DP<10>")
	)
	(segment
		(start 135.750046 -428.28972)
		(end 135.750046 -427.980602)
		(width 0.14732)
		(layer "In11.Cu")
		(net "P5E_CPU1_PE2_TX_C_DP<10>")
	)
	(segment
		(start 135.750046 -427.980602)
		(end 135.563102 -427.793658)
		(width 0.14732)
		(layer "In11.Cu")
		(net "P5E_CPU1_PE2_TX_C_DP<10>")
	)
	(segment
		(start 166.103554 -403.883876)
		(end 166.406576 -403.580854)
		(width 0.13208)
		(layer "F.Cu")
		(net "P5E_CPU1_PE2_TX_C_DP<0>")
	)
	(segment
		(start 166.406576 -402.962872)
		(end 166.081456 -402.637752)
		(width 0.13208)
		(layer "F.Cu")
		(net "P5E_CPU1_PE2_TX_C_DP<0>")
	)
	(segment
		(start 166.406576 -403.580854)
		(end 166.406576 -402.962872)
		(width 0.13208)
		(layer "F.Cu")
		(net "P5E_CPU1_PE2_TX_C_DP<0>")
	)
	(segment
		(start 166.081456 -402.637752)
		(end 166.078154 -402.637752)
		(width 0.13208)
		(layer "F.Cu")
		(net "P5E_CPU1_PE2_TX_C_DP<0>")
	)
	(segment
		(start 158.221426 -420.997634)
		(end 166.212774 -410.658056)
		(width 0.14732)
		(layer "In11.Cu")
		(net "P5E_CPU1_PE2_TX_C_DP<0>")
	)
	(segment
		(start 166.212774 -406.30475)
		(end 166.398194 -406.11933)
		(width 0.14732)
		(layer "In11.Cu")
		(net "P5E_CPU1_PE2_TX_C_DP<0>")
	)
	(segment
		(start 158.221172 -420.997634)
		(end 158.221426 -420.997634)
		(width 0.14732)
		(layer "In11.Cu")
		(net "P5E_CPU1_PE2_TX_C_DP<0>")
	)
	(segment
		(start 155.792424 -427.509178)
		(end 155.792424 -424.139868)
		(width 0.14732)
		(layer "In11.Cu")
		(net "P5E_CPU1_PE2_TX_C_DP<0>")
	)
	(segment
		(start 156.750004 -427.980602)
		(end 156.56306 -427.793658)
		(width 0.14732)
		(layer "In11.Cu")
		(net "P5E_CPU1_PE2_TX_C_DP<0>")
	)
	(segment
		(start 166.398194 -406.11933)
		(end 166.398194 -404.178516)
		(width 0.14732)
		(layer "In11.Cu")
		(net "P5E_CPU1_PE2_TX_C_DP<0>")
	)
	(segment
		(start 166.398194 -404.178516)
		(end 166.103554 -403.883876)
		(width 0.14732)
		(layer "In11.Cu")
		(net "P5E_CPU1_PE2_TX_C_DP<0>")
	)
	(segment
		(start 156.56306 -427.793658)
		(end 156.076904 -427.793658)
		(width 0.14732)
		(layer "In11.Cu")
		(net "P5E_CPU1_PE2_TX_C_DP<0>")
	)
	(segment
		(start 166.212774 -410.658056)
		(end 166.212774 -406.30475)
		(width 0.14732)
		(layer "In11.Cu")
		(net "P5E_CPU1_PE2_TX_C_DP<0>")
	)
	(segment
		(start 156.750004 -428.28972)
		(end 156.750004 -427.980602)
		(width 0.14732)
		(layer "In11.Cu")
		(net "P5E_CPU1_PE2_TX_C_DP<0>")
	)
	(segment
		(start 156.076904 -427.793658)
		(end 155.792424 -427.509178)
		(width 0.14732)
		(layer "In11.Cu")
		(net "P5E_CPU1_PE2_TX_C_DP<0>")
	)
	(segment
		(start 155.792424 -424.139868)
		(end 158.221172 -420.997634)
		(width 0.14732)
		(layer "In11.Cu")
		(net "P5E_CPU1_PE2_TX_C_DP<0>")
	)
	(segment
		(start 139.096496 -402.96465)
		(end 139.423394 -402.637752)
		(width 0.13208)
		(layer "F.Cu")
		(net "P5E_CPU1_PE2_TX_C_DN<9>")
	)
	(segment
		(start 139.096496 -403.582378)
		(end 139.096496 -402.96465)
		(width 0.13208)
		(layer "F.Cu")
		(net "P5E_CPU1_PE2_TX_C_DN<9>")
	)
	(segment
		(start 139.397994 -403.883876)
		(end 139.096496 -403.582378)
		(width 0.13208)
		(layer "F.Cu")
		(net "P5E_CPU1_PE2_TX_C_DN<9>")
	)
	(segment
		(start 137.066782 -424.295824)
		(end 137.066782 -426.395642)
		(width 0.14732)
		(layer "In11.Cu")
		(net "P5E_CPU1_PE2_TX_C_DN<9>")
	)
	(segment
		(start 137.385298 -422.927018)
		(end 137.228326 -423.047414)
		(width 0.14732)
		(layer "In11.Cu")
		(net "P5E_CPU1_PE2_TX_C_DN<9>")
	)
	(segment
		(start 137.602214 -426.519594)
		(end 137.750042 -426.371766)
		(width 0.14732)
		(layer "In11.Cu")
		(net "P5E_CPU1_PE2_TX_C_DN<9>")
	)
	(segment
		(start 137.51814 -421.919654)
		(end 137.361168 -422.04005)
		(width 0.14732)
		(layer "In11.Cu")
		(net "P5E_CPU1_PE2_TX_C_DN<9>")
	)
	(segment
		(start 137.446004 -421.397684)
		(end 137.566146 -421.554402)
		(width 0.14732)
		(layer "In11.Cu")
		(net "P5E_CPU1_PE2_TX_C_DN<9>")
	)
	(segment
		(start 137.066782 -426.395642)
		(end 137.190734 -426.519594)
		(width 0.14732)
		(layer "In11.Cu")
		(net "P5E_CPU1_PE2_TX_C_DN<9>")
	)
	(segment
		(start 137.626852 -420.025322)
		(end 137.578846 -420.39032)
		(width 0.14732)
		(layer "In11.Cu")
		(net "P5E_CPU1_PE2_TX_C_DN<9>")
	)
	(segment
		(start 137.578846 -420.39032)
		(end 137.698988 -420.547038)
		(width 0.14732)
		(layer "In11.Cu")
		(net "P5E_CPU1_PE2_TX_C_DN<9>")
	)
	(segment
		(start 139.103354 -404.178516)
		(end 139.103354 -406.233122)
		(width 0.14732)
		(layer "In11.Cu")
		(net "P5E_CPU1_PE2_TX_C_DN<9>")
	)
	(segment
		(start 137.433304 -422.561766)
		(end 137.385298 -422.927018)
		(width 0.14732)
		(layer "In11.Cu")
		(net "P5E_CPU1_PE2_TX_C_DN<9>")
	)
	(segment
		(start 137.313162 -422.405048)
		(end 137.433304 -422.561766)
		(width 0.14732)
		(layer "In11.Cu")
		(net "P5E_CPU1_PE2_TX_C_DN<9>")
	)
	(segment
		(start 137.228326 -423.047414)
		(end 137.070084 -424.249342)
		(width 0.14732)
		(layer "In11.Cu")
		(net "P5E_CPU1_PE2_TX_C_DN<9>")
	)
	(segment
		(start 137.361168 -422.04005)
		(end 137.313162 -422.405048)
		(width 0.14732)
		(layer "In11.Cu")
		(net "P5E_CPU1_PE2_TX_C_DN<9>")
	)
	(segment
		(start 139.397994 -403.883876)
		(end 139.103354 -404.178516)
		(width 0.14732)
		(layer "In11.Cu")
		(net "P5E_CPU1_PE2_TX_C_DN<9>")
	)
	(segment
		(start 137.711688 -419.382956)
		(end 137.83183 -419.539674)
		(width 0.14732)
		(layer "In11.Cu")
		(net "P5E_CPU1_PE2_TX_C_DN<9>")
	)
	(segment
		(start 137.49401 -421.032686)
		(end 137.446004 -421.397684)
		(width 0.14732)
		(layer "In11.Cu")
		(net "P5E_CPU1_PE2_TX_C_DN<9>")
	)
	(segment
		(start 137.650982 -420.91229)
		(end 137.49401 -421.032686)
		(width 0.14732)
		(layer "In11.Cu")
		(net "P5E_CPU1_PE2_TX_C_DN<9>")
	)
	(segment
		(start 137.698988 -420.547038)
		(end 137.650982 -420.91229)
		(width 0.14732)
		(layer "In11.Cu")
		(net "P5E_CPU1_PE2_TX_C_DN<9>")
	)
	(segment
		(start 138.917934 -410.217112)
		(end 137.847324 -418.350192)
		(width 0.14732)
		(layer "In11.Cu")
		(net "P5E_CPU1_PE2_TX_C_DN<9>")
	)
	(segment
		(start 137.762742 -418.994082)
		(end 137.711688 -419.382956)
		(width 0.14732)
		(layer "In11.Cu")
		(net "P5E_CPU1_PE2_TX_C_DN<9>")
	)
	(segment
		(start 137.847324 -418.350192)
		(end 137.847578 -418.351462)
		(width 0.14732)
		(layer "In11.Cu")
		(net "P5E_CPU1_PE2_TX_C_DN<9>")
	)
	(segment
		(start 139.103354 -406.233122)
		(end 138.917934 -406.418542)
		(width 0.14732)
		(layer "In11.Cu")
		(net "P5E_CPU1_PE2_TX_C_DN<9>")
	)
	(segment
		(start 137.96772 -418.508434)
		(end 137.919714 -418.873686)
		(width 0.14732)
		(layer "In11.Cu")
		(net "P5E_CPU1_PE2_TX_C_DN<9>")
	)
	(segment
		(start 137.190734 -426.519594)
		(end 137.602214 -426.519594)
		(width 0.14732)
		(layer "In11.Cu")
		(net "P5E_CPU1_PE2_TX_C_DN<9>")
	)
	(segment
		(start 137.783824 -419.904926)
		(end 137.626852 -420.025322)
		(width 0.14732)
		(layer "In11.Cu")
		(net "P5E_CPU1_PE2_TX_C_DN<9>")
	)
	(segment
		(start 137.750042 -426.371766)
		(end 137.750042 -426.089826)
		(width 0.14732)
		(layer "In11.Cu")
		(net "P5E_CPU1_PE2_TX_C_DN<9>")
	)
	(segment
		(start 137.070084 -424.249342)
		(end 137.066782 -424.295824)
		(width 0.14732)
		(layer "In11.Cu")
		(net "P5E_CPU1_PE2_TX_C_DN<9>")
	)
	(segment
		(start 137.847578 -418.351462)
		(end 137.96772 -418.508434)
		(width 0.14732)
		(layer "In11.Cu")
		(net "P5E_CPU1_PE2_TX_C_DN<9>")
	)
	(segment
		(start 137.83183 -419.539674)
		(end 137.783824 -419.904926)
		(width 0.14732)
		(layer "In11.Cu")
		(net "P5E_CPU1_PE2_TX_C_DN<9>")
	)
	(segment
		(start 137.919714 -418.873686)
		(end 137.762742 -418.994082)
		(width 0.14732)
		(layer "In11.Cu")
		(net "P5E_CPU1_PE2_TX_C_DN<9>")
	)
	(segment
		(start 137.566146 -421.554402)
		(end 137.51814 -421.919654)
		(width 0.14732)
		(layer "In11.Cu")
		(net "P5E_CPU1_PE2_TX_C_DN<9>")
	)
	(segment
		(start 138.917934 -406.418542)
		(end 138.917934 -410.217112)
		(width 0.14732)
		(layer "In11.Cu")
		(net "P5E_CPU1_PE2_TX_C_DN<9>")
	)
	(segment
		(start 142.159736 -402.96465)
		(end 142.486634 -402.637752)
		(width 0.13208)
		(layer "F.Cu")
		(net "P5E_CPU1_PE2_TX_C_DN<8>")
	)
	(segment
		(start 142.461234 -403.883876)
		(end 142.159736 -403.582378)
		(width 0.13208)
		(layer "F.Cu")
		(net "P5E_CPU1_PE2_TX_C_DN<8>")
	)
	(segment
		(start 142.159736 -403.582378)
		(end 142.159736 -402.96465)
		(width 0.13208)
		(layer "F.Cu")
		(net "P5E_CPU1_PE2_TX_C_DN<8>")
	)
	(segment
		(start 140.007086 -419.772592)
		(end 140.114782 -419.938454)
		(width 0.14732)
		(layer "In11.Cu")
		(net "P5E_CPU1_PE2_TX_C_DN<8>")
	)
	(segment
		(start 139.903962 -420.93261)
		(end 139.827508 -421.293036)
		(width 0.14732)
		(layer "In11.Cu")
		(net "P5E_CPU1_PE2_TX_C_DN<8>")
	)
	(segment
		(start 139.872466 -420.406576)
		(end 139.796266 -420.766748)
		(width 0.14732)
		(layer "In11.Cu")
		(net "P5E_CPU1_PE2_TX_C_DN<8>")
	)
	(segment
		(start 139.616688 -422.287192)
		(end 139.45108 -422.394634)
		(width 0.14732)
		(layer "In11.Cu")
		(net "P5E_CPU1_PE2_TX_C_DN<8>")
	)
	(segment
		(start 140.240004 -418.674296)
		(end 140.336016 -418.82187)
		(width 0.14732)
		(layer "In11.Cu")
		(net "P5E_CPU1_PE2_TX_C_DN<8>")
	)
	(segment
		(start 139.693142 -421.926766)
		(end 139.616688 -422.287192)
		(width 0.14732)
		(layer "In11.Cu")
		(net "P5E_CPU1_PE2_TX_C_DN<8>")
	)
	(segment
		(start 139.585446 -421.760904)
		(end 139.693142 -421.926766)
		(width 0.14732)
		(layer "In11.Cu")
		(net "P5E_CPU1_PE2_TX_C_DN<8>")
	)
	(segment
		(start 142.166594 -406.233122)
		(end 141.981174 -406.418542)
		(width 0.14732)
		(layer "In11.Cu")
		(net "P5E_CPU1_PE2_TX_C_DN<8>")
	)
	(segment
		(start 139.066778 -424.206924)
		(end 139.066778 -427.395386)
		(width 0.14732)
		(layer "In11.Cu")
		(net "P5E_CPU1_PE2_TX_C_DN<8>")
	)
	(segment
		(start 139.60221 -427.519338)
		(end 139.750038 -427.37151)
		(width 0.14732)
		(layer "In11.Cu")
		(net "P5E_CPU1_PE2_TX_C_DN<8>")
	)
	(segment
		(start 140.09751 -419.345364)
		(end 140.007086 -419.772592)
		(width 0.14732)
		(layer "In11.Cu")
		(net "P5E_CPU1_PE2_TX_C_DN<8>")
	)
	(segment
		(start 142.166594 -404.178516)
		(end 142.166594 -406.233122)
		(width 0.14732)
		(layer "In11.Cu")
		(net "P5E_CPU1_PE2_TX_C_DN<8>")
	)
	(segment
		(start 139.661646 -421.400732)
		(end 139.585446 -421.760904)
		(width 0.14732)
		(layer "In11.Cu")
		(net "P5E_CPU1_PE2_TX_C_DN<8>")
	)
	(segment
		(start 140.114782 -419.938454)
		(end 140.038328 -420.29888)
		(width 0.14732)
		(layer "In11.Cu")
		(net "P5E_CPU1_PE2_TX_C_DN<8>")
	)
	(segment
		(start 140.038328 -420.29888)
		(end 139.872466 -420.406576)
		(width 0.14732)
		(layer "In11.Cu")
		(net "P5E_CPU1_PE2_TX_C_DN<8>")
	)
	(segment
		(start 140.336016 -418.82187)
		(end 140.245338 -419.249352)
		(width 0.14732)
		(layer "In11.Cu")
		(net "P5E_CPU1_PE2_TX_C_DN<8>")
	)
	(segment
		(start 141.981174 -406.418542)
		(end 141.981174 -410.462222)
		(width 0.14732)
		(layer "In11.Cu")
		(net "P5E_CPU1_PE2_TX_C_DN<8>")
	)
	(segment
		(start 139.750038 -427.37151)
		(end 139.750038 -427.089824)
		(width 0.14732)
		(layer "In11.Cu")
		(net "P5E_CPU1_PE2_TX_C_DN<8>")
	)
	(segment
		(start 141.981174 -410.462222)
		(end 140.240004 -418.674296)
		(width 0.14732)
		(layer "In11.Cu")
		(net "P5E_CPU1_PE2_TX_C_DN<8>")
	)
	(segment
		(start 139.796266 -420.766748)
		(end 139.903962 -420.93261)
		(width 0.14732)
		(layer "In11.Cu")
		(net "P5E_CPU1_PE2_TX_C_DN<8>")
	)
	(segment
		(start 139.066778 -427.395386)
		(end 139.19073 -427.519338)
		(width 0.14732)
		(layer "In11.Cu")
		(net "P5E_CPU1_PE2_TX_C_DN<8>")
	)
	(segment
		(start 140.245338 -419.249352)
		(end 140.09751 -419.345364)
		(width 0.14732)
		(layer "In11.Cu")
		(net "P5E_CPU1_PE2_TX_C_DN<8>")
	)
	(segment
		(start 142.461234 -403.883876)
		(end 142.166594 -404.178516)
		(width 0.14732)
		(layer "In11.Cu")
		(net "P5E_CPU1_PE2_TX_C_DN<8>")
	)
	(segment
		(start 139.45108 -422.394634)
		(end 139.066778 -424.206924)
		(width 0.14732)
		(layer "In11.Cu")
		(net "P5E_CPU1_PE2_TX_C_DN<8>")
	)
	(segment
		(start 139.19073 -427.519338)
		(end 139.60221 -427.519338)
		(width 0.14732)
		(layer "In11.Cu")
		(net "P5E_CPU1_PE2_TX_C_DN<8>")
	)
	(segment
		(start 139.827508 -421.293036)
		(end 139.661646 -421.400732)
		(width 0.14732)
		(layer "In11.Cu")
		(net "P5E_CPU1_PE2_TX_C_DN<8>")
	)
	(segment
		(start 145.524474 -403.883876)
		(end 145.222976 -403.582378)
		(width 0.13208)
		(layer "F.Cu")
		(net "P5E_CPU1_PE2_TX_C_DN<7>")
	)
	(segment
		(start 145.222976 -403.582378)
		(end 145.222976 -402.96465)
		(width 0.13208)
		(layer "F.Cu")
		(net "P5E_CPU1_PE2_TX_C_DN<7>")
	)
	(segment
		(start 145.222976 -402.96465)
		(end 145.549874 -402.637752)
		(width 0.13208)
		(layer "F.Cu")
		(net "P5E_CPU1_PE2_TX_C_DN<7>")
	)
	(segment
		(start 143.164052 -419.096444)
		(end 142.995904 -419.200838)
		(width 0.14732)
		(layer "In11.Cu")
		(net "P5E_CPU1_PE2_TX_C_DN<7>")
	)
	(segment
		(start 145.044414 -406.418542)
		(end 145.044414 -410.402532)
		(width 0.14732)
		(layer "In11.Cu")
		(net "P5E_CPU1_PE2_TX_C_DN<7>")
	)
	(segment
		(start 143.39443 -418.10686)
		(end 143.226282 -418.211254)
		(width 0.14732)
		(layer "In11.Cu")
		(net "P5E_CPU1_PE2_TX_C_DN<7>")
	)
	(segment
		(start 142.995904 -419.200838)
		(end 142.912592 -419.559486)
		(width 0.14732)
		(layer "In11.Cu")
		(net "P5E_CPU1_PE2_TX_C_DN<7>")
	)
	(segment
		(start 143.373602 -417.580318)
		(end 143.477742 -417.747958)
		(width 0.14732)
		(layer "In11.Cu")
		(net "P5E_CPU1_PE2_TX_C_DN<7>")
	)
	(segment
		(start 142.933674 -420.086028)
		(end 142.765526 -420.190422)
		(width 0.14732)
		(layer "In11.Cu")
		(net "P5E_CPU1_PE2_TX_C_DN<7>")
	)
	(segment
		(start 142.066772 -423.312844)
		(end 142.066772 -426.395642)
		(width 0.14732)
		(layer "In11.Cu")
		(net "P5E_CPU1_PE2_TX_C_DN<7>")
	)
	(segment
		(start 142.786608 -420.71671)
		(end 142.703296 -421.075612)
		(width 0.14732)
		(layer "In11.Cu")
		(net "P5E_CPU1_PE2_TX_C_DN<7>")
	)
	(segment
		(start 145.524474 -403.883876)
		(end 145.229834 -404.178516)
		(width 0.14732)
		(layer "In11.Cu")
		(net "P5E_CPU1_PE2_TX_C_DN<7>")
	)
	(segment
		(start 142.535148 -421.180006)
		(end 142.451836 -421.538654)
		(width 0.14732)
		(layer "In11.Cu")
		(net "P5E_CPU1_PE2_TX_C_DN<7>")
	)
	(segment
		(start 142.472664 -422.06545)
		(end 142.30477 -422.16959)
		(width 0.14732)
		(layer "In11.Cu")
		(net "P5E_CPU1_PE2_TX_C_DN<7>")
	)
	(segment
		(start 145.229834 -406.233122)
		(end 145.044414 -406.418542)
		(width 0.14732)
		(layer "In11.Cu")
		(net "P5E_CPU1_PE2_TX_C_DN<7>")
	)
	(segment
		(start 143.373348 -417.580064)
		(end 143.373602 -417.580318)
		(width 0.14732)
		(layer "In11.Cu")
		(net "P5E_CPU1_PE2_TX_C_DN<7>")
	)
	(segment
		(start 142.602204 -426.519594)
		(end 142.750032 -426.371766)
		(width 0.14732)
		(layer "In11.Cu")
		(net "P5E_CPU1_PE2_TX_C_DN<7>")
	)
	(segment
		(start 143.226282 -418.211254)
		(end 143.14297 -418.569902)
		(width 0.14732)
		(layer "In11.Cu")
		(net "P5E_CPU1_PE2_TX_C_DN<7>")
	)
	(segment
		(start 142.703296 -421.075612)
		(end 142.535148 -421.180006)
		(width 0.14732)
		(layer "In11.Cu")
		(net "P5E_CPU1_PE2_TX_C_DN<7>")
	)
	(segment
		(start 142.682214 -420.54907)
		(end 142.786608 -420.71671)
		(width 0.14732)
		(layer "In11.Cu")
		(net "P5E_CPU1_PE2_TX_C_DN<7>")
	)
	(segment
		(start 142.55623 -421.706294)
		(end 142.472664 -422.06545)
		(width 0.14732)
		(layer "In11.Cu")
		(net "P5E_CPU1_PE2_TX_C_DN<7>")
	)
	(segment
		(start 142.070582 -423.175938)
		(end 142.066772 -423.312844)
		(width 0.14732)
		(layer "In11.Cu")
		(net "P5E_CPU1_PE2_TX_C_DN<7>")
	)
	(segment
		(start 142.190724 -426.519594)
		(end 142.602204 -426.519594)
		(width 0.14732)
		(layer "In11.Cu")
		(net "P5E_CPU1_PE2_TX_C_DN<7>")
	)
	(segment
		(start 142.451836 -421.538654)
		(end 142.55623 -421.706294)
		(width 0.14732)
		(layer "In11.Cu")
		(net "P5E_CPU1_PE2_TX_C_DN<7>")
	)
	(segment
		(start 142.912592 -419.559486)
		(end 143.016986 -419.727126)
		(width 0.14732)
		(layer "In11.Cu")
		(net "P5E_CPU1_PE2_TX_C_DN<7>")
	)
	(segment
		(start 143.14297 -418.569902)
		(end 143.247364 -418.737542)
		(width 0.14732)
		(layer "In11.Cu")
		(net "P5E_CPU1_PE2_TX_C_DN<7>")
	)
	(segment
		(start 142.30477 -422.16959)
		(end 142.070582 -423.175938)
		(width 0.14732)
		(layer "In11.Cu")
		(net "P5E_CPU1_PE2_TX_C_DN<7>")
	)
	(segment
		(start 143.477742 -417.747958)
		(end 143.39443 -418.10686)
		(width 0.14732)
		(layer "In11.Cu")
		(net "P5E_CPU1_PE2_TX_C_DN<7>")
	)
	(segment
		(start 143.247364 -418.737542)
		(end 143.164052 -419.096444)
		(width 0.14732)
		(layer "In11.Cu")
		(net "P5E_CPU1_PE2_TX_C_DN<7>")
	)
	(segment
		(start 143.016986 -419.727126)
		(end 142.933674 -420.086028)
		(width 0.14732)
		(layer "In11.Cu")
		(net "P5E_CPU1_PE2_TX_C_DN<7>")
	)
	(segment
		(start 142.066772 -426.395642)
		(end 142.190724 -426.519594)
		(width 0.14732)
		(layer "In11.Cu")
		(net "P5E_CPU1_PE2_TX_C_DN<7>")
	)
	(segment
		(start 142.750032 -426.371766)
		(end 142.750032 -426.089826)
		(width 0.14732)
		(layer "In11.Cu")
		(net "P5E_CPU1_PE2_TX_C_DN<7>")
	)
	(segment
		(start 145.229834 -404.178516)
		(end 145.229834 -406.233122)
		(width 0.14732)
		(layer "In11.Cu")
		(net "P5E_CPU1_PE2_TX_C_DN<7>")
	)
	(segment
		(start 142.765526 -420.190422)
		(end 142.682214 -420.54907)
		(width 0.14732)
		(layer "In11.Cu")
		(net "P5E_CPU1_PE2_TX_C_DN<7>")
	)
	(segment
		(start 145.044414 -410.402532)
		(end 143.373348 -417.580064)
		(width 0.14732)
		(layer "In11.Cu")
		(net "P5E_CPU1_PE2_TX_C_DN<7>")
	)
	(segment
		(start 148.587714 -403.883876)
		(end 148.286216 -403.582378)
		(width 0.13208)
		(layer "F.Cu")
		(net "P5E_CPU1_PE2_TX_C_DN<6>")
	)
	(segment
		(start 148.286216 -403.582378)
		(end 148.286216 -402.96465)
		(width 0.13208)
		(layer "F.Cu")
		(net "P5E_CPU1_PE2_TX_C_DN<6>")
	)
	(segment
		(start 148.286216 -402.96465)
		(end 148.613114 -402.637752)
		(width 0.13208)
		(layer "F.Cu")
		(net "P5E_CPU1_PE2_TX_C_DN<6>")
	)
	(segment
		(start 145.03908 -421.767)
		(end 144.938496 -422.121584)
		(width 0.14732)
		(layer "In11.Cu")
		(net "P5E_CPU1_PE2_TX_C_DN<6>")
	)
	(segment
		(start 144.066768 -427.395386)
		(end 144.19072 -427.519338)
		(width 0.14732)
		(layer "In11.Cu")
		(net "P5E_CPU1_PE2_TX_C_DN<6>")
	)
	(segment
		(start 145.316702 -420.789608)
		(end 145.216118 -421.144192)
		(width 0.14732)
		(layer "In11.Cu")
		(net "P5E_CPU1_PE2_TX_C_DN<6>")
	)
	(segment
		(start 145.043398 -421.240458)
		(end 144.942814 -421.594534)
		(width 0.14732)
		(layer "In11.Cu")
		(net "P5E_CPU1_PE2_TX_C_DN<6>")
	)
	(segment
		(start 144.4879 -423.195242)
		(end 144.066768 -424.678602)
		(width 0.14732)
		(layer "In11.Cu")
		(net "P5E_CPU1_PE2_TX_C_DN<6>")
	)
	(segment
		(start 148.293074 -406.233122)
		(end 148.107654 -406.418542)
		(width 0.14732)
		(layer "In11.Cu")
		(net "P5E_CPU1_PE2_TX_C_DN<6>")
	)
	(segment
		(start 145.49374 -420.111174)
		(end 145.339562 -420.197026)
		(width 0.14732)
		(layer "In11.Cu")
		(net "P5E_CPU1_PE2_TX_C_DN<6>")
	)
	(segment
		(start 145.339562 -420.197026)
		(end 145.220436 -420.617142)
		(width 0.14732)
		(layer "In11.Cu")
		(net "P5E_CPU1_PE2_TX_C_DN<6>")
	)
	(segment
		(start 148.293074 -404.178516)
		(end 148.293074 -406.233122)
		(width 0.14732)
		(layer "In11.Cu")
		(net "P5E_CPU1_PE2_TX_C_DN<6>")
	)
	(segment
		(start 145.220436 -420.617142)
		(end 145.316702 -420.789608)
		(width 0.14732)
		(layer "In11.Cu")
		(net "P5E_CPU1_PE2_TX_C_DN<6>")
	)
	(segment
		(start 144.761458 -422.744646)
		(end 144.66062 -423.098976)
		(width 0.14732)
		(layer "In11.Cu")
		(net "P5E_CPU1_PE2_TX_C_DN<6>")
	)
	(segment
		(start 148.107654 -410.450284)
		(end 145.527268 -419.537134)
		(width 0.14732)
		(layer "In11.Cu")
		(net "P5E_CPU1_PE2_TX_C_DN<6>")
	)
	(segment
		(start 144.750028 -427.37151)
		(end 144.750028 -427.089824)
		(width 0.14732)
		(layer "In11.Cu")
		(net "P5E_CPU1_PE2_TX_C_DN<6>")
	)
	(segment
		(start 145.612866 -419.690804)
		(end 145.49374 -420.111174)
		(width 0.14732)
		(layer "In11.Cu")
		(net "P5E_CPU1_PE2_TX_C_DN<6>")
	)
	(segment
		(start 148.107654 -406.418542)
		(end 148.107654 -410.450284)
		(width 0.14732)
		(layer "In11.Cu")
		(net "P5E_CPU1_PE2_TX_C_DN<6>")
	)
	(segment
		(start 144.942814 -421.594534)
		(end 145.03908 -421.767)
		(width 0.14732)
		(layer "In11.Cu")
		(net "P5E_CPU1_PE2_TX_C_DN<6>")
	)
	(segment
		(start 144.765776 -422.21785)
		(end 144.665192 -422.571926)
		(width 0.14732)
		(layer "In11.Cu")
		(net "P5E_CPU1_PE2_TX_C_DN<6>")
	)
	(segment
		(start 144.665192 -422.571926)
		(end 144.761458 -422.744646)
		(width 0.14732)
		(layer "In11.Cu")
		(net "P5E_CPU1_PE2_TX_C_DN<6>")
	)
	(segment
		(start 144.19072 -427.519338)
		(end 144.6022 -427.519338)
		(width 0.14732)
		(layer "In11.Cu")
		(net "P5E_CPU1_PE2_TX_C_DN<6>")
	)
	(segment
		(start 145.216118 -421.144192)
		(end 145.043398 -421.240458)
		(width 0.14732)
		(layer "In11.Cu")
		(net "P5E_CPU1_PE2_TX_C_DN<6>")
	)
	(segment
		(start 148.587714 -403.883876)
		(end 148.293074 -404.178516)
		(width 0.14732)
		(layer "In11.Cu")
		(net "P5E_CPU1_PE2_TX_C_DN<6>")
	)
	(segment
		(start 144.938496 -422.121584)
		(end 144.765776 -422.21785)
		(width 0.14732)
		(layer "In11.Cu")
		(net "P5E_CPU1_PE2_TX_C_DN<6>")
	)
	(segment
		(start 144.066768 -424.678602)
		(end 144.066768 -427.395386)
		(width 0.14732)
		(layer "In11.Cu")
		(net "P5E_CPU1_PE2_TX_C_DN<6>")
	)
	(segment
		(start 144.6022 -427.519338)
		(end 144.750028 -427.37151)
		(width 0.14732)
		(layer "In11.Cu")
		(net "P5E_CPU1_PE2_TX_C_DN<6>")
	)
	(segment
		(start 145.527268 -419.537134)
		(end 145.612866 -419.690804)
		(width 0.14732)
		(layer "In11.Cu")
		(net "P5E_CPU1_PE2_TX_C_DN<6>")
	)
	(segment
		(start 144.66062 -423.098976)
		(end 144.4879 -423.195242)
		(width 0.14732)
		(layer "In11.Cu")
		(net "P5E_CPU1_PE2_TX_C_DN<6>")
	)
	(segment
		(start 151.349456 -403.582378)
		(end 151.349456 -402.96465)
		(width 0.13208)
		(layer "F.Cu")
		(net "P5E_CPU1_PE2_TX_C_DN<5>")
	)
	(segment
		(start 151.349456 -402.96465)
		(end 151.676354 -402.637752)
		(width 0.13208)
		(layer "F.Cu")
		(net "P5E_CPU1_PE2_TX_C_DN<5>")
	)
	(segment
		(start 151.650954 -403.883876)
		(end 151.349456 -403.582378)
		(width 0.13208)
		(layer "F.Cu")
		(net "P5E_CPU1_PE2_TX_C_DN<5>")
	)
	(segment
		(start 147.13331 -421.59682)
		(end 147.216622 -421.776144)
		(width 0.14732)
		(layer "In11.Cu")
		(net "P5E_CPU1_PE2_TX_C_DN<5>")
	)
	(segment
		(start 151.170894 -410.540708)
		(end 148.179282 -418.732462)
		(width 0.14732)
		(layer "In11.Cu")
		(net "P5E_CPU1_PE2_TX_C_DN<5>")
	)
	(segment
		(start 147.259548 -421.250872)
		(end 147.13331 -421.59682)
		(width 0.14732)
		(layer "In11.Cu")
		(net "P5E_CPU1_PE2_TX_C_DN<5>")
	)
	(segment
		(start 146.750024 -426.371766)
		(end 146.750024 -426.089826)
		(width 0.14732)
		(layer "In11.Cu")
		(net "P5E_CPU1_PE2_TX_C_DN<5>")
	)
	(segment
		(start 147.957032 -419.341808)
		(end 147.830794 -419.687756)
		(width 0.14732)
		(layer "In11.Cu")
		(net "P5E_CPU1_PE2_TX_C_DN<5>")
	)
	(segment
		(start 147.438872 -421.167814)
		(end 147.259548 -421.250872)
		(width 0.14732)
		(layer "In11.Cu")
		(net "P5E_CPU1_PE2_TX_C_DN<5>")
	)
	(segment
		(start 147.914106 -419.866826)
		(end 147.787614 -420.213282)
		(width 0.14732)
		(layer "In11.Cu")
		(net "P5E_CPU1_PE2_TX_C_DN<5>")
	)
	(segment
		(start 148.262848 -418.912294)
		(end 148.136356 -419.258496)
		(width 0.14732)
		(layer "In11.Cu")
		(net "P5E_CPU1_PE2_TX_C_DN<5>")
	)
	(segment
		(start 146.602196 -426.519594)
		(end 146.750024 -426.371766)
		(width 0.14732)
		(layer "In11.Cu")
		(net "P5E_CPU1_PE2_TX_C_DN<5>")
	)
	(segment
		(start 147.830794 -419.687756)
		(end 147.914106 -419.866826)
		(width 0.14732)
		(layer "In11.Cu")
		(net "P5E_CPU1_PE2_TX_C_DN<5>")
	)
	(segment
		(start 151.170894 -406.418542)
		(end 151.170894 -410.540708)
		(width 0.14732)
		(layer "In11.Cu")
		(net "P5E_CPU1_PE2_TX_C_DN<5>")
	)
	(segment
		(start 146.784568 -422.551352)
		(end 146.86788 -422.730422)
		(width 0.14732)
		(layer "In11.Cu")
		(net "P5E_CPU1_PE2_TX_C_DN<5>")
	)
	(segment
		(start 146.562064 -423.159936)
		(end 146.561302 -423.162222)
		(width 0.14732)
		(layer "In11.Cu")
		(net "P5E_CPU1_PE2_TX_C_DN<5>")
	)
	(segment
		(start 151.356314 -406.233122)
		(end 151.170894 -406.418542)
		(width 0.14732)
		(layer "In11.Cu")
		(net "P5E_CPU1_PE2_TX_C_DN<5>")
	)
	(segment
		(start 146.561302 -423.162222)
		(end 146.066764 -424.516296)
		(width 0.14732)
		(layer "In11.Cu")
		(net "P5E_CPU1_PE2_TX_C_DN<5>")
	)
	(segment
		(start 146.066764 -426.395642)
		(end 146.190716 -426.519594)
		(width 0.14732)
		(layer "In11.Cu")
		(net "P5E_CPU1_PE2_TX_C_DN<5>")
	)
	(segment
		(start 146.784822 -422.55059)
		(end 146.784568 -422.551352)
		(width 0.14732)
		(layer "In11.Cu")
		(net "P5E_CPU1_PE2_TX_C_DN<5>")
	)
	(segment
		(start 146.066764 -424.516296)
		(end 146.066764 -426.395642)
		(width 0.14732)
		(layer "In11.Cu")
		(net "P5E_CPU1_PE2_TX_C_DN<5>")
	)
	(segment
		(start 147.787614 -420.213282)
		(end 147.60829 -420.29634)
		(width 0.14732)
		(layer "In11.Cu")
		(net "P5E_CPU1_PE2_TX_C_DN<5>")
	)
	(segment
		(start 151.356314 -404.178516)
		(end 151.356314 -406.233122)
		(width 0.14732)
		(layer "In11.Cu")
		(net "P5E_CPU1_PE2_TX_C_DN<5>")
	)
	(segment
		(start 151.650954 -403.883876)
		(end 151.356314 -404.178516)
		(width 0.14732)
		(layer "In11.Cu")
		(net "P5E_CPU1_PE2_TX_C_DN<5>")
	)
	(segment
		(start 146.190716 -426.519594)
		(end 146.602196 -426.519594)
		(width 0.14732)
		(layer "In11.Cu")
		(net "P5E_CPU1_PE2_TX_C_DN<5>")
	)
	(segment
		(start 147.565364 -420.821612)
		(end 147.438872 -421.167814)
		(width 0.14732)
		(layer "In11.Cu")
		(net "P5E_CPU1_PE2_TX_C_DN<5>")
	)
	(segment
		(start 147.09013 -422.122346)
		(end 146.910806 -422.205404)
		(width 0.14732)
		(layer "In11.Cu")
		(net "P5E_CPU1_PE2_TX_C_DN<5>")
	)
	(segment
		(start 148.179282 -418.732462)
		(end 148.179536 -418.733224)
		(width 0.14732)
		(layer "In11.Cu")
		(net "P5E_CPU1_PE2_TX_C_DN<5>")
	)
	(segment
		(start 147.216622 -421.776144)
		(end 147.09013 -422.122346)
		(width 0.14732)
		(layer "In11.Cu")
		(net "P5E_CPU1_PE2_TX_C_DN<5>")
	)
	(segment
		(start 146.86788 -422.730422)
		(end 146.741388 -423.076624)
		(width 0.14732)
		(layer "In11.Cu")
		(net "P5E_CPU1_PE2_TX_C_DN<5>")
	)
	(segment
		(start 147.482052 -420.642288)
		(end 147.565364 -420.821612)
		(width 0.14732)
		(layer "In11.Cu")
		(net "P5E_CPU1_PE2_TX_C_DN<5>")
	)
	(segment
		(start 146.741388 -423.076624)
		(end 146.562064 -423.159936)
		(width 0.14732)
		(layer "In11.Cu")
		(net "P5E_CPU1_PE2_TX_C_DN<5>")
	)
	(segment
		(start 148.179536 -418.733224)
		(end 148.262848 -418.912294)
		(width 0.14732)
		(layer "In11.Cu")
		(net "P5E_CPU1_PE2_TX_C_DN<5>")
	)
	(segment
		(start 147.60829 -420.29634)
		(end 147.482052 -420.642288)
		(width 0.14732)
		(layer "In11.Cu")
		(net "P5E_CPU1_PE2_TX_C_DN<5>")
	)
	(segment
		(start 146.910806 -422.205404)
		(end 146.784822 -422.55059)
		(width 0.14732)
		(layer "In11.Cu")
		(net "P5E_CPU1_PE2_TX_C_DN<5>")
	)
	(segment
		(start 148.136356 -419.258496)
		(end 147.957032 -419.341808)
		(width 0.14732)
		(layer "In11.Cu")
		(net "P5E_CPU1_PE2_TX_C_DN<5>")
	)
	(segment
		(start 154.412696 -403.582378)
		(end 154.412696 -402.96465)
		(width 0.13208)
		(layer "F.Cu")
		(net "P5E_CPU1_PE2_TX_C_DN<4>")
	)
	(segment
		(start 154.714194 -403.883876)
		(end 154.412696 -403.582378)
		(width 0.13208)
		(layer "F.Cu")
		(net "P5E_CPU1_PE2_TX_C_DN<4>")
	)
	(segment
		(start 154.412696 -402.96465)
		(end 154.739594 -402.637752)
		(width 0.13208)
		(layer "F.Cu")
		(net "P5E_CPU1_PE2_TX_C_DN<4>")
	)
	(segment
		(start 149.285198 -421.854376)
		(end 149.100032 -421.923718)
		(width 0.14732)
		(layer "In11.Cu")
		(net "P5E_CPU1_PE2_TX_C_DN<4>")
	)
	(segment
		(start 150.234142 -419.764464)
		(end 150.081742 -420.099998)
		(width 0.14732)
		(layer "In11.Cu")
		(net "P5E_CPU1_PE2_TX_C_DN<4>")
	)
	(segment
		(start 149.437598 -421.518842)
		(end 149.285198 -421.854376)
		(width 0.14732)
		(layer "In11.Cu")
		(net "P5E_CPU1_PE2_TX_C_DN<4>")
	)
	(segment
		(start 148.947886 -422.258998)
		(end 149.017482 -422.44391)
		(width 0.14732)
		(layer "In11.Cu")
		(net "P5E_CPU1_PE2_TX_C_DN<4>")
	)
	(segment
		(start 150.871174 -418.361368)
		(end 150.719028 -418.696902)
		(width 0.14732)
		(layer "In11.Cu")
		(net "P5E_CPU1_PE2_TX_C_DN<4>")
	)
	(segment
		(start 154.234134 -406.418542)
		(end 154.234134 -410.61767)
		(width 0.14732)
		(layer "In11.Cu")
		(net "P5E_CPU1_PE2_TX_C_DN<4>")
	)
	(segment
		(start 148.602192 -427.519338)
		(end 148.75002 -427.37151)
		(width 0.14732)
		(layer "In11.Cu")
		(net "P5E_CPU1_PE2_TX_C_DN<4>")
	)
	(segment
		(start 148.75002 -427.37151)
		(end 148.75002 -427.089824)
		(width 0.14732)
		(layer "In11.Cu")
		(net "P5E_CPU1_PE2_TX_C_DN<4>")
	)
	(segment
		(start 154.714194 -403.883876)
		(end 154.419554 -404.178516)
		(width 0.14732)
		(layer "In11.Cu")
		(net "P5E_CPU1_PE2_TX_C_DN<4>")
	)
	(segment
		(start 148.679916 -422.84904)
		(end 148.06676 -424.199304)
		(width 0.14732)
		(layer "In11.Cu")
		(net "P5E_CPU1_PE2_TX_C_DN<4>")
	)
	(segment
		(start 154.419554 -404.178516)
		(end 154.419554 -406.233122)
		(width 0.14732)
		(layer "In11.Cu")
		(net "P5E_CPU1_PE2_TX_C_DN<4>")
	)
	(segment
		(start 150.719028 -418.696902)
		(end 150.533862 -418.766244)
		(width 0.14732)
		(layer "In11.Cu")
		(net "P5E_CPU1_PE2_TX_C_DN<4>")
	)
	(segment
		(start 149.100032 -421.923718)
		(end 148.947886 -422.258998)
		(width 0.14732)
		(layer "In11.Cu")
		(net "P5E_CPU1_PE2_TX_C_DN<4>")
	)
	(segment
		(start 154.234134 -410.61767)
		(end 150.801832 -418.176456)
		(width 0.14732)
		(layer "In11.Cu")
		(net "P5E_CPU1_PE2_TX_C_DN<4>")
	)
	(segment
		(start 150.164546 -419.579552)
		(end 150.234142 -419.764464)
		(width 0.14732)
		(layer "In11.Cu")
		(net "P5E_CPU1_PE2_TX_C_DN<4>")
	)
	(segment
		(start 149.017482 -422.44391)
		(end 148.865082 -422.779444)
		(width 0.14732)
		(layer "In11.Cu")
		(net "P5E_CPU1_PE2_TX_C_DN<4>")
	)
	(segment
		(start 150.081742 -420.099998)
		(end 149.896576 -420.169594)
		(width 0.14732)
		(layer "In11.Cu")
		(net "P5E_CPU1_PE2_TX_C_DN<4>")
	)
	(segment
		(start 154.419554 -406.233122)
		(end 154.234134 -406.418542)
		(width 0.14732)
		(layer "In11.Cu")
		(net "P5E_CPU1_PE2_TX_C_DN<4>")
	)
	(segment
		(start 149.896576 -420.169594)
		(end 149.368002 -421.333676)
		(width 0.14732)
		(layer "In11.Cu")
		(net "P5E_CPU1_PE2_TX_C_DN<4>")
	)
	(segment
		(start 148.06676 -424.199304)
		(end 148.06676 -427.395386)
		(width 0.14732)
		(layer "In11.Cu")
		(net "P5E_CPU1_PE2_TX_C_DN<4>")
	)
	(segment
		(start 149.368002 -421.333676)
		(end 149.437598 -421.518842)
		(width 0.14732)
		(layer "In11.Cu")
		(net "P5E_CPU1_PE2_TX_C_DN<4>")
	)
	(segment
		(start 148.865082 -422.779444)
		(end 148.679916 -422.84904)
		(width 0.14732)
		(layer "In11.Cu")
		(net "P5E_CPU1_PE2_TX_C_DN<4>")
	)
	(segment
		(start 150.533862 -418.766244)
		(end 150.164546 -419.579552)
		(width 0.14732)
		(layer "In11.Cu")
		(net "P5E_CPU1_PE2_TX_C_DN<4>")
	)
	(segment
		(start 148.06676 -427.395386)
		(end 148.190712 -427.519338)
		(width 0.14732)
		(layer "In11.Cu")
		(net "P5E_CPU1_PE2_TX_C_DN<4>")
	)
	(segment
		(start 150.801832 -418.176456)
		(end 150.871174 -418.361368)
		(width 0.14732)
		(layer "In11.Cu")
		(net "P5E_CPU1_PE2_TX_C_DN<4>")
	)
	(segment
		(start 148.190712 -427.519338)
		(end 148.602192 -427.519338)
		(width 0.14732)
		(layer "In11.Cu")
		(net "P5E_CPU1_PE2_TX_C_DN<4>")
	)
	(segment
		(start 157.475936 -403.582378)
		(end 157.475936 -402.96465)
		(width 0.13208)
		(layer "F.Cu")
		(net "P5E_CPU1_PE2_TX_C_DN<3>")
	)
	(segment
		(start 157.777434 -403.883876)
		(end 157.475936 -403.582378)
		(width 0.13208)
		(layer "F.Cu")
		(net "P5E_CPU1_PE2_TX_C_DN<3>")
	)
	(segment
		(start 157.475936 -402.96465)
		(end 157.802834 -402.637752)
		(width 0.13208)
		(layer "F.Cu")
		(net "P5E_CPU1_PE2_TX_C_DN<3>")
	)
	(segment
		(start 157.482794 -406.233122)
		(end 157.297374 -406.418542)
		(width 0.14732)
		(layer "In11.Cu")
		(net "P5E_CPU1_PE2_TX_C_DN<3>")
	)
	(segment
		(start 157.482794 -404.178516)
		(end 157.482794 -406.233122)
		(width 0.14732)
		(layer "In11.Cu")
		(net "P5E_CPU1_PE2_TX_C_DN<3>")
	)
	(segment
		(start 150.937214 -423.093388)
		(end 150.73503 -423.480992)
		(width 0.14732)
		(layer "In11.Cu")
		(net "P5E_CPU1_PE2_TX_C_DN<3>")
	)
	(segment
		(start 151.769826 -421.499538)
		(end 151.605234 -421.5511)
		(width 0.14732)
		(layer "In11.Cu")
		(net "P5E_CPU1_PE2_TX_C_DN<3>")
	)
	(segment
		(start 157.777434 -403.883876)
		(end 157.482794 -404.178516)
		(width 0.14732)
		(layer "In11.Cu")
		(net "P5E_CPU1_PE2_TX_C_DN<3>")
	)
	(segment
		(start 153.474674 -417.97097)
		(end 153.526236 -418.135562)
		(width 0.14732)
		(layer "In11.Cu")
		(net "P5E_CPU1_PE2_TX_C_DN<3>")
	)
	(segment
		(start 150.570184 -423.532554)
		(end 150.066756 -424.496992)
		(width 0.14732)
		(layer "In11.Cu")
		(net "P5E_CPU1_PE2_TX_C_DN<3>")
	)
	(segment
		(start 150.190708 -426.519594)
		(end 150.602188 -426.519594)
		(width 0.14732)
		(layer "In11.Cu")
		(net "P5E_CPU1_PE2_TX_C_DN<3>")
	)
	(segment
		(start 150.750016 -426.371766)
		(end 150.750016 -426.089826)
		(width 0.14732)
		(layer "In11.Cu")
		(net "P5E_CPU1_PE2_TX_C_DN<3>")
	)
	(segment
		(start 152.642062 -419.565582)
		(end 152.439878 -419.952678)
		(width 0.14732)
		(layer "In11.Cu")
		(net "P5E_CPU1_PE2_TX_C_DN<3>")
	)
	(segment
		(start 153.15946 -418.574728)
		(end 152.957276 -418.961824)
		(width 0.14732)
		(layer "In11.Cu")
		(net "P5E_CPU1_PE2_TX_C_DN<3>")
	)
	(segment
		(start 153.324052 -418.523166)
		(end 153.15946 -418.574728)
		(width 0.14732)
		(layer "In11.Cu")
		(net "P5E_CPU1_PE2_TX_C_DN<3>")
	)
	(segment
		(start 152.957276 -418.961824)
		(end 153.008838 -419.126416)
		(width 0.14732)
		(layer "In11.Cu")
		(net "P5E_CPU1_PE2_TX_C_DN<3>")
	)
	(segment
		(start 150.885652 -422.92905)
		(end 150.937214 -423.093388)
		(width 0.14732)
		(layer "In11.Cu")
		(net "P5E_CPU1_PE2_TX_C_DN<3>")
	)
	(segment
		(start 151.40305 -421.938196)
		(end 151.454612 -422.102788)
		(width 0.14732)
		(layer "In11.Cu")
		(net "P5E_CPU1_PE2_TX_C_DN<3>")
	)
	(segment
		(start 157.297374 -406.418542)
		(end 157.297374 -410.650436)
		(width 0.14732)
		(layer "In11.Cu")
		(net "P5E_CPU1_PE2_TX_C_DN<3>")
	)
	(segment
		(start 153.526236 -418.135562)
		(end 153.324052 -418.523166)
		(width 0.14732)
		(layer "In11.Cu")
		(net "P5E_CPU1_PE2_TX_C_DN<3>")
	)
	(segment
		(start 151.454612 -422.102788)
		(end 151.252428 -422.490392)
		(width 0.14732)
		(layer "In11.Cu")
		(net "P5E_CPU1_PE2_TX_C_DN<3>")
	)
	(segment
		(start 152.289256 -420.50462)
		(end 152.124664 -420.556182)
		(width 0.14732)
		(layer "In11.Cu")
		(net "P5E_CPU1_PE2_TX_C_DN<3>")
	)
	(segment
		(start 150.602188 -426.519594)
		(end 150.750016 -426.371766)
		(width 0.14732)
		(layer "In11.Cu")
		(net "P5E_CPU1_PE2_TX_C_DN<3>")
	)
	(segment
		(start 151.920448 -420.947342)
		(end 151.97201 -421.111934)
		(width 0.14732)
		(layer "In11.Cu")
		(net "P5E_CPU1_PE2_TX_C_DN<3>")
	)
	(segment
		(start 151.605234 -421.5511)
		(end 151.40305 -421.938196)
		(width 0.14732)
		(layer "In11.Cu")
		(net "P5E_CPU1_PE2_TX_C_DN<3>")
	)
	(segment
		(start 152.806654 -419.51402)
		(end 152.642062 -419.565582)
		(width 0.14732)
		(layer "In11.Cu")
		(net "P5E_CPU1_PE2_TX_C_DN<3>")
	)
	(segment
		(start 151.252428 -422.490392)
		(end 151.087836 -422.541954)
		(width 0.14732)
		(layer "In11.Cu")
		(net "P5E_CPU1_PE2_TX_C_DN<3>")
	)
	(segment
		(start 150.066756 -424.496992)
		(end 150.066756 -426.395642)
		(width 0.14732)
		(layer "In11.Cu")
		(net "P5E_CPU1_PE2_TX_C_DN<3>")
	)
	(segment
		(start 152.439878 -419.952678)
		(end 152.491694 -420.117016)
		(width 0.14732)
		(layer "In11.Cu")
		(net "P5E_CPU1_PE2_TX_C_DN<3>")
	)
	(segment
		(start 151.97201 -421.111934)
		(end 151.769826 -421.499538)
		(width 0.14732)
		(layer "In11.Cu")
		(net "P5E_CPU1_PE2_TX_C_DN<3>")
	)
	(segment
		(start 157.297374 -410.650436)
		(end 153.474674 -417.97097)
		(width 0.14732)
		(layer "In11.Cu")
		(net "P5E_CPU1_PE2_TX_C_DN<3>")
	)
	(segment
		(start 150.73503 -423.480992)
		(end 150.570184 -423.532554)
		(width 0.14732)
		(layer "In11.Cu")
		(net "P5E_CPU1_PE2_TX_C_DN<3>")
	)
	(segment
		(start 152.124664 -420.556182)
		(end 151.920448 -420.947342)
		(width 0.14732)
		(layer "In11.Cu")
		(net "P5E_CPU1_PE2_TX_C_DN<3>")
	)
	(segment
		(start 150.066756 -426.395642)
		(end 150.190708 -426.519594)
		(width 0.14732)
		(layer "In11.Cu")
		(net "P5E_CPU1_PE2_TX_C_DN<3>")
	)
	(segment
		(start 153.008838 -419.126416)
		(end 152.806654 -419.51402)
		(width 0.14732)
		(layer "In11.Cu")
		(net "P5E_CPU1_PE2_TX_C_DN<3>")
	)
	(segment
		(start 152.491694 -420.117016)
		(end 152.289256 -420.50462)
		(width 0.14732)
		(layer "In11.Cu")
		(net "P5E_CPU1_PE2_TX_C_DN<3>")
	)
	(segment
		(start 151.087836 -422.541954)
		(end 150.885652 -422.92905)
		(width 0.14732)
		(layer "In11.Cu")
		(net "P5E_CPU1_PE2_TX_C_DN<3>")
	)
	(segment
		(start 160.840674 -403.883876)
		(end 160.539176 -403.582378)
		(width 0.13208)
		(layer "F.Cu")
		(net "P5E_CPU1_PE2_TX_C_DN<2>")
	)
	(segment
		(start 160.539176 -403.582378)
		(end 160.539176 -402.96465)
		(width 0.13208)
		(layer "F.Cu")
		(net "P5E_CPU1_PE2_TX_C_DN<2>")
	)
	(segment
		(start 160.539176 -402.96465)
		(end 160.866074 -402.637752)
		(width 0.13208)
		(layer "F.Cu")
		(net "P5E_CPU1_PE2_TX_C_DN<2>")
	)
	(segment
		(start 154.602688 -420.61892)
		(end 154.41422 -420.935658)
		(width 0.14732)
		(layer "In11.Cu")
		(net "P5E_CPU1_PE2_TX_C_DN<2>")
	)
	(segment
		(start 152.066752 -427.395386)
		(end 152.190704 -427.519338)
		(width 0.14732)
		(layer "In11.Cu")
		(net "P5E_CPU1_PE2_TX_C_DN<2>")
	)
	(segment
		(start 153.373582 -422.681654)
		(end 153.181812 -422.730168)
		(width 0.14732)
		(layer "In11.Cu")
		(net "P5E_CPU1_PE2_TX_C_DN<2>")
	)
	(segment
		(start 160.546034 -404.178516)
		(end 160.546034 -406.233122)
		(width 0.14732)
		(layer "In11.Cu")
		(net "P5E_CPU1_PE2_TX_C_DN<2>")
	)
	(segment
		(start 160.840674 -403.883876)
		(end 160.546034 -404.178516)
		(width 0.14732)
		(layer "In11.Cu")
		(net "P5E_CPU1_PE2_TX_C_DN<2>")
	)
	(segment
		(start 152.190704 -427.519338)
		(end 152.602184 -427.519338)
		(width 0.14732)
		(layer "In11.Cu")
		(net "P5E_CPU1_PE2_TX_C_DN<2>")
	)
	(segment
		(start 160.360614 -406.418542)
		(end 160.360614 -410.682948)
		(width 0.14732)
		(layer "In11.Cu")
		(net "P5E_CPU1_PE2_TX_C_DN<2>")
	)
	(segment
		(start 154.082496 -421.491918)
		(end 153.894028 -421.808656)
		(width 0.14732)
		(layer "In11.Cu")
		(net "P5E_CPU1_PE2_TX_C_DN<2>")
	)
	(segment
		(start 152.602184 -427.519338)
		(end 152.750012 -427.37151)
		(width 0.14732)
		(layer "In11.Cu")
		(net "P5E_CPU1_PE2_TX_C_DN<2>")
	)
	(segment
		(start 153.702258 -421.85717)
		(end 153.51379 -422.1734)
		(width 0.14732)
		(layer "In11.Cu")
		(net "P5E_CPU1_PE2_TX_C_DN<2>")
	)
	(segment
		(start 154.41422 -420.935658)
		(end 154.22245 -420.984172)
		(width 0.14732)
		(layer "In11.Cu")
		(net "P5E_CPU1_PE2_TX_C_DN<2>")
	)
	(segment
		(start 154.948382 -420.009066)
		(end 154.777694 -420.052246)
		(width 0.14732)
		(layer "In11.Cu")
		(net "P5E_CPU1_PE2_TX_C_DN<2>")
	)
	(segment
		(start 153.562304 -422.364916)
		(end 153.373582 -422.681654)
		(width 0.14732)
		(layer "In11.Cu")
		(net "P5E_CPU1_PE2_TX_C_DN<2>")
	)
	(segment
		(start 160.546034 -406.233122)
		(end 160.360614 -406.418542)
		(width 0.14732)
		(layer "In11.Cu")
		(net "P5E_CPU1_PE2_TX_C_DN<2>")
	)
	(segment
		(start 155.128976 -419.462712)
		(end 155.172156 -419.6334)
		(width 0.14732)
		(layer "In11.Cu")
		(net "P5E_CPU1_PE2_TX_C_DN<2>")
	)
	(segment
		(start 153.51379 -422.1734)
		(end 153.562304 -422.364916)
		(width 0.14732)
		(layer "In11.Cu")
		(net "P5E_CPU1_PE2_TX_C_DN<2>")
	)
	(segment
		(start 153.181812 -422.730168)
		(end 152.066752 -424.60164)
		(width 0.14732)
		(layer "In11.Cu")
		(net "P5E_CPU1_PE2_TX_C_DN<2>")
	)
	(segment
		(start 153.894028 -421.808656)
		(end 153.702258 -421.85717)
		(width 0.14732)
		(layer "In11.Cu")
		(net "P5E_CPU1_PE2_TX_C_DN<2>")
	)
	(segment
		(start 160.360614 -410.682948)
		(end 155.128976 -419.462712)
		(width 0.14732)
		(layer "In11.Cu")
		(net "P5E_CPU1_PE2_TX_C_DN<2>")
	)
	(segment
		(start 155.172156 -419.6334)
		(end 154.948382 -420.009066)
		(width 0.14732)
		(layer "In11.Cu")
		(net "P5E_CPU1_PE2_TX_C_DN<2>")
	)
	(segment
		(start 154.554174 -420.427404)
		(end 154.602688 -420.61892)
		(width 0.14732)
		(layer "In11.Cu")
		(net "P5E_CPU1_PE2_TX_C_DN<2>")
	)
	(segment
		(start 154.777694 -420.052246)
		(end 154.554174 -420.427404)
		(width 0.14732)
		(layer "In11.Cu")
		(net "P5E_CPU1_PE2_TX_C_DN<2>")
	)
	(segment
		(start 154.22245 -420.984172)
		(end 154.033982 -421.300402)
		(width 0.14732)
		(layer "In11.Cu")
		(net "P5E_CPU1_PE2_TX_C_DN<2>")
	)
	(segment
		(start 152.750012 -427.37151)
		(end 152.750012 -427.089824)
		(width 0.14732)
		(layer "In11.Cu")
		(net "P5E_CPU1_PE2_TX_C_DN<2>")
	)
	(segment
		(start 154.033982 -421.300402)
		(end 154.082496 -421.491918)
		(width 0.14732)
		(layer "In11.Cu")
		(net "P5E_CPU1_PE2_TX_C_DN<2>")
	)
	(segment
		(start 152.066752 -424.60164)
		(end 152.066752 -427.395386)
		(width 0.14732)
		(layer "In11.Cu")
		(net "P5E_CPU1_PE2_TX_C_DN<2>")
	)
	(segment
		(start 163.602416 -403.582378)
		(end 163.602416 -402.96465)
		(width 0.13208)
		(layer "F.Cu")
		(net "P5E_CPU1_PE2_TX_C_DN<1>")
	)
	(segment
		(start 163.903914 -403.883876)
		(end 163.602416 -403.582378)
		(width 0.13208)
		(layer "F.Cu")
		(net "P5E_CPU1_PE2_TX_C_DN<1>")
	)
	(segment
		(start 163.602416 -402.96465)
		(end 163.929314 -402.637752)
		(width 0.13208)
		(layer "F.Cu")
		(net "P5E_CPU1_PE2_TX_C_DN<1>")
	)
	(segment
		(start 155.184094 -422.797478)
		(end 155.21686 -422.970452)
		(width 0.14732)
		(layer "In11.Cu")
		(net "P5E_CPU1_PE2_TX_C_DN<1>")
	)
	(segment
		(start 157.08249 -420.014908)
		(end 157.115256 -420.187628)
		(width 0.14732)
		(layer "In11.Cu")
		(net "P5E_CPU1_PE2_TX_C_DN<1>")
	)
	(segment
		(start 155.816808 -421.870124)
		(end 155.849574 -422.042844)
		(width 0.14732)
		(layer "In11.Cu")
		(net "P5E_CPU1_PE2_TX_C_DN<1>")
	)
	(segment
		(start 155.21686 -422.970452)
		(end 154.97048 -423.33164)
		(width 0.14732)
		(layer "In11.Cu")
		(net "P5E_CPU1_PE2_TX_C_DN<1>")
	)
	(segment
		(start 154.797506 -423.364406)
		(end 154.066748 -424.435524)
		(width 0.14732)
		(layer "In11.Cu")
		(net "P5E_CPU1_PE2_TX_C_DN<1>")
	)
	(segment
		(start 157.715204 -419.087554)
		(end 157.74797 -419.260274)
		(width 0.14732)
		(layer "In11.Cu")
		(net "P5E_CPU1_PE2_TX_C_DN<1>")
	)
	(segment
		(start 155.849574 -422.042844)
		(end 155.603194 -422.404032)
		(width 0.14732)
		(layer "In11.Cu")
		(net "P5E_CPU1_PE2_TX_C_DN<1>")
	)
	(segment
		(start 155.603194 -422.404032)
		(end 155.43022 -422.436798)
		(width 0.14732)
		(layer "In11.Cu")
		(net "P5E_CPU1_PE2_TX_C_DN<1>")
	)
	(segment
		(start 155.43022 -422.436798)
		(end 155.184094 -422.797478)
		(width 0.14732)
		(layer "In11.Cu")
		(net "P5E_CPU1_PE2_TX_C_DN<1>")
	)
	(segment
		(start 163.423854 -406.418542)
		(end 163.423854 -410.71927)
		(width 0.14732)
		(layer "In11.Cu")
		(net "P5E_CPU1_PE2_TX_C_DN<1>")
	)
	(segment
		(start 158.345124 -418.164264)
		(end 158.377128 -418.333682)
		(width 0.14732)
		(layer "In11.Cu")
		(net "P5E_CPU1_PE2_TX_C_DN<1>")
	)
	(segment
		(start 163.423854 -410.71927)
		(end 158.345124 -418.164264)
		(width 0.14732)
		(layer "In11.Cu")
		(net "P5E_CPU1_PE2_TX_C_DN<1>")
	)
	(segment
		(start 157.74797 -419.260274)
		(end 157.50159 -419.621462)
		(width 0.14732)
		(layer "In11.Cu")
		(net "P5E_CPU1_PE2_TX_C_DN<1>")
	)
	(segment
		(start 156.868876 -420.548816)
		(end 156.695902 -420.581582)
		(width 0.14732)
		(layer "In11.Cu")
		(net "P5E_CPU1_PE2_TX_C_DN<1>")
	)
	(segment
		(start 158.130748 -418.69487)
		(end 157.96133 -418.726874)
		(width 0.14732)
		(layer "In11.Cu")
		(net "P5E_CPU1_PE2_TX_C_DN<1>")
	)
	(segment
		(start 156.449776 -420.942262)
		(end 156.482542 -421.115236)
		(width 0.14732)
		(layer "In11.Cu")
		(net "P5E_CPU1_PE2_TX_C_DN<1>")
	)
	(segment
		(start 156.236162 -421.476424)
		(end 156.063188 -421.50919)
		(width 0.14732)
		(layer "In11.Cu")
		(net "P5E_CPU1_PE2_TX_C_DN<1>")
	)
	(segment
		(start 157.50159 -419.621462)
		(end 157.328616 -419.654228)
		(width 0.14732)
		(layer "In11.Cu")
		(net "P5E_CPU1_PE2_TX_C_DN<1>")
	)
	(segment
		(start 158.377128 -418.333682)
		(end 158.130748 -418.69487)
		(width 0.14732)
		(layer "In11.Cu")
		(net "P5E_CPU1_PE2_TX_C_DN<1>")
	)
	(segment
		(start 154.60218 -426.519594)
		(end 154.750008 -426.371766)
		(width 0.14732)
		(layer "In11.Cu")
		(net "P5E_CPU1_PE2_TX_C_DN<1>")
	)
	(segment
		(start 156.695902 -420.581582)
		(end 156.449776 -420.942262)
		(width 0.14732)
		(layer "In11.Cu")
		(net "P5E_CPU1_PE2_TX_C_DN<1>")
	)
	(segment
		(start 157.328616 -419.654228)
		(end 157.08249 -420.014908)
		(width 0.14732)
		(layer "In11.Cu")
		(net "P5E_CPU1_PE2_TX_C_DN<1>")
	)
	(segment
		(start 154.066748 -424.435524)
		(end 154.066748 -426.395642)
		(width 0.14732)
		(layer "In11.Cu")
		(net "P5E_CPU1_PE2_TX_C_DN<1>")
	)
	(segment
		(start 154.1907 -426.519594)
		(end 154.60218 -426.519594)
		(width 0.14732)
		(layer "In11.Cu")
		(net "P5E_CPU1_PE2_TX_C_DN<1>")
	)
	(segment
		(start 163.609274 -406.233122)
		(end 163.423854 -406.418542)
		(width 0.14732)
		(layer "In11.Cu")
		(net "P5E_CPU1_PE2_TX_C_DN<1>")
	)
	(segment
		(start 156.063188 -421.50919)
		(end 155.816808 -421.870124)
		(width 0.14732)
		(layer "In11.Cu")
		(net "P5E_CPU1_PE2_TX_C_DN<1>")
	)
	(segment
		(start 154.750008 -426.371766)
		(end 154.750008 -426.089826)
		(width 0.14732)
		(layer "In11.Cu")
		(net "P5E_CPU1_PE2_TX_C_DN<1>")
	)
	(segment
		(start 157.115256 -420.187628)
		(end 156.868876 -420.548816)
		(width 0.14732)
		(layer "In11.Cu")
		(net "P5E_CPU1_PE2_TX_C_DN<1>")
	)
	(segment
		(start 157.96133 -418.726874)
		(end 157.715204 -419.087554)
		(width 0.14732)
		(layer "In11.Cu")
		(net "P5E_CPU1_PE2_TX_C_DN<1>")
	)
	(segment
		(start 163.609274 -404.178516)
		(end 163.609274 -406.233122)
		(width 0.14732)
		(layer "In11.Cu")
		(net "P5E_CPU1_PE2_TX_C_DN<1>")
	)
	(segment
		(start 154.97048 -423.33164)
		(end 154.797506 -423.364406)
		(width 0.14732)
		(layer "In11.Cu")
		(net "P5E_CPU1_PE2_TX_C_DN<1>")
	)
	(segment
		(start 163.903914 -403.883876)
		(end 163.609274 -404.178516)
		(width 0.14732)
		(layer "In11.Cu")
		(net "P5E_CPU1_PE2_TX_C_DN<1>")
	)
	(segment
		(start 156.482542 -421.115236)
		(end 156.236162 -421.476424)
		(width 0.14732)
		(layer "In11.Cu")
		(net "P5E_CPU1_PE2_TX_C_DN<1>")
	)
	(segment
		(start 154.066748 -426.395642)
		(end 154.1907 -426.519594)
		(width 0.14732)
		(layer "In11.Cu")
		(net "P5E_CPU1_PE2_TX_C_DN<1>")
	)
	(segment
		(start 120.717056 -403.582378)
		(end 120.717056 -402.96465)
		(width 0.13208)
		(layer "F.Cu")
		(net "P5E_CPU1_PE2_TX_C_DN<15>")
	)
	(segment
		(start 121.018554 -403.883876)
		(end 120.717056 -403.582378)
		(width 0.13208)
		(layer "F.Cu")
		(net "P5E_CPU1_PE2_TX_C_DN<15>")
	)
	(segment
		(start 120.717056 -402.96465)
		(end 121.043954 -402.637752)
		(width 0.13208)
		(layer "F.Cu")
		(net "P5E_CPU1_PE2_TX_C_DN<15>")
	)
	(segment
		(start 121.664476 -413.894524)
		(end 121.766584 -414.2486)
		(width 0.14732)
		(layer "In11.Cu")
		(net "P5E_CPU1_PE2_TX_C_DN<15>")
	)
	(segment
		(start 125.11786 -426.358304)
		(end 125.332236 -426.519594)
		(width 0.14732)
		(layer "In11.Cu")
		(net "P5E_CPU1_PE2_TX_C_DN<15>")
	)
	(segment
		(start 125.602238 -426.519594)
		(end 125.750066 -426.371766)
		(width 0.14732)
		(layer "In11.Cu")
		(net "P5E_CPU1_PE2_TX_C_DN<15>")
	)
	(segment
		(start 122.35434 -416.78733)
		(end 122.527568 -416.88258)
		(width 0.14732)
		(layer "In11.Cu")
		(net "P5E_CPU1_PE2_TX_C_DN<15>")
	)
	(segment
		(start 121.773188 -414.775396)
		(end 121.946416 -414.870646)
		(width 0.14732)
		(layer "In11.Cu")
		(net "P5E_CPU1_PE2_TX_C_DN<15>")
	)
	(segment
		(start 122.072146 -415.810954)
		(end 122.245374 -415.906204)
		(width 0.14732)
		(layer "In11.Cu")
		(net "P5E_CPU1_PE2_TX_C_DN<15>")
	)
	(segment
		(start 122.347736 -416.260534)
		(end 122.252232 -416.433508)
		(width 0.14732)
		(layer "In11.Cu")
		(net "P5E_CPU1_PE2_TX_C_DN<15>")
	)
	(segment
		(start 121.382536 -412.918148)
		(end 121.484644 -413.272478)
		(width 0.14732)
		(layer "In11.Cu")
		(net "P5E_CPU1_PE2_TX_C_DN<15>")
	)
	(segment
		(start 121.67108 -414.421574)
		(end 121.773188 -414.775396)
		(width 0.14732)
		(layer "In11.Cu")
		(net "P5E_CPU1_PE2_TX_C_DN<15>")
	)
	(segment
		(start 121.018554 -403.883876)
		(end 120.723914 -404.178516)
		(width 0.14732)
		(layer "In11.Cu")
		(net "P5E_CPU1_PE2_TX_C_DN<15>")
	)
	(segment
		(start 120.538494 -410.499814)
		(end 121.209308 -412.822898)
		(width 0.14732)
		(layer "In11.Cu")
		(net "P5E_CPU1_PE2_TX_C_DN<15>")
	)
	(segment
		(start 122.048524 -415.224976)
		(end 121.95302 -415.397696)
		(width 0.14732)
		(layer "In11.Cu")
		(net "P5E_CPU1_PE2_TX_C_DN<15>")
	)
	(segment
		(start 120.723914 -404.178516)
		(end 120.723914 -406.233122)
		(width 0.14732)
		(layer "In11.Cu")
		(net "P5E_CPU1_PE2_TX_C_DN<15>")
	)
	(segment
		(start 121.484644 -413.272478)
		(end 121.38914 -413.445452)
		(width 0.14732)
		(layer "In11.Cu")
		(net "P5E_CPU1_PE2_TX_C_DN<15>")
	)
	(segment
		(start 121.766584 -414.2486)
		(end 121.67108 -414.421574)
		(width 0.14732)
		(layer "In11.Cu")
		(net "P5E_CPU1_PE2_TX_C_DN<15>")
	)
	(segment
		(start 121.946416 -414.870646)
		(end 122.048524 -415.224976)
		(width 0.14732)
		(layer "In11.Cu")
		(net "P5E_CPU1_PE2_TX_C_DN<15>")
	)
	(segment
		(start 121.95302 -415.397696)
		(end 122.072146 -415.810954)
		(width 0.14732)
		(layer "In11.Cu")
		(net "P5E_CPU1_PE2_TX_C_DN<15>")
	)
	(segment
		(start 125.332236 -426.519594)
		(end 125.602238 -426.519594)
		(width 0.14732)
		(layer "In11.Cu")
		(net "P5E_CPU1_PE2_TX_C_DN<15>")
	)
	(segment
		(start 121.491248 -413.799274)
		(end 121.664476 -413.894524)
		(width 0.14732)
		(layer "In11.Cu")
		(net "P5E_CPU1_PE2_TX_C_DN<15>")
	)
	(segment
		(start 122.527568 -416.88258)
		(end 122.629676 -417.23691)
		(width 0.14732)
		(layer "In11.Cu")
		(net "P5E_CPU1_PE2_TX_C_DN<15>")
	)
	(segment
		(start 122.534172 -417.409884)
		(end 122.533918 -417.410138)
		(width 0.14732)
		(layer "In11.Cu")
		(net "P5E_CPU1_PE2_TX_C_DN<15>")
	)
	(segment
		(start 121.38914 -413.445452)
		(end 121.491248 -413.799274)
		(width 0.14732)
		(layer "In11.Cu")
		(net "P5E_CPU1_PE2_TX_C_DN<15>")
	)
	(segment
		(start 121.209308 -412.822898)
		(end 121.382536 -412.918148)
		(width 0.14732)
		(layer "In11.Cu")
		(net "P5E_CPU1_PE2_TX_C_DN<15>")
	)
	(segment
		(start 120.538494 -406.418542)
		(end 120.538494 -410.499814)
		(width 0.14732)
		(layer "In11.Cu")
		(net "P5E_CPU1_PE2_TX_C_DN<15>")
	)
	(segment
		(start 122.252232 -416.433508)
		(end 122.35434 -416.78733)
		(width 0.14732)
		(layer "In11.Cu")
		(net "P5E_CPU1_PE2_TX_C_DN<15>")
	)
	(segment
		(start 122.629676 -417.23691)
		(end 122.534172 -417.409884)
		(width 0.14732)
		(layer "In11.Cu")
		(net "P5E_CPU1_PE2_TX_C_DN<15>")
	)
	(segment
		(start 122.245374 -415.906204)
		(end 122.347736 -416.260534)
		(width 0.14732)
		(layer "In11.Cu")
		(net "P5E_CPU1_PE2_TX_C_DN<15>")
	)
	(segment
		(start 122.533918 -417.410138)
		(end 125.11786 -426.358304)
		(width 0.14732)
		(layer "In11.Cu")
		(net "P5E_CPU1_PE2_TX_C_DN<15>")
	)
	(segment
		(start 125.750066 -426.371766)
		(end 125.750066 -426.089826)
		(width 0.14732)
		(layer "In11.Cu")
		(net "P5E_CPU1_PE2_TX_C_DN<15>")
	)
	(segment
		(start 120.723914 -406.233122)
		(end 120.538494 -406.418542)
		(width 0.14732)
		(layer "In11.Cu")
		(net "P5E_CPU1_PE2_TX_C_DN<15>")
	)
	(segment
		(start 124.081794 -403.883876)
		(end 123.780296 -403.582378)
		(width 0.13208)
		(layer "F.Cu")
		(net "P5E_CPU1_PE2_TX_C_DN<14>")
	)
	(segment
		(start 123.780296 -403.582378)
		(end 123.780296 -402.96465)
		(width 0.13208)
		(layer "F.Cu")
		(net "P5E_CPU1_PE2_TX_C_DN<14>")
	)
	(segment
		(start 123.780296 -402.96465)
		(end 124.107194 -402.637752)
		(width 0.13208)
		(layer "F.Cu")
		(net "P5E_CPU1_PE2_TX_C_DN<14>")
	)
	(segment
		(start 127.750062 -427.37151)
		(end 127.750062 -427.089824)
		(width 0.14732)
		(layer "In11.Cu")
		(net "P5E_CPU1_PE2_TX_C_DN<14>")
	)
	(segment
		(start 123.787154 -406.233122)
		(end 123.601734 -406.418542)
		(width 0.14732)
		(layer "In11.Cu")
		(net "P5E_CPU1_PE2_TX_C_DN<14>")
	)
	(segment
		(start 124.412502 -413.851598)
		(end 127.066802 -424.000676)
		(width 0.14732)
		(layer "In11.Cu")
		(net "P5E_CPU1_PE2_TX_C_DN<14>")
	)
	(segment
		(start 123.997974 -411.71495)
		(end 123.898152 -411.885384)
		(width 0.14732)
		(layer "In11.Cu")
		(net "P5E_CPU1_PE2_TX_C_DN<14>")
	)
	(segment
		(start 124.41936 -413.324294)
		(end 124.512324 -413.68091)
		(width 0.14732)
		(layer "In11.Cu")
		(net "P5E_CPU1_PE2_TX_C_DN<14>")
	)
	(segment
		(start 123.734068 -411.258512)
		(end 123.904756 -411.358334)
		(width 0.14732)
		(layer "In11.Cu")
		(net "P5E_CPU1_PE2_TX_C_DN<14>")
	)
	(segment
		(start 123.787154 -404.178516)
		(end 123.787154 -406.233122)
		(width 0.14732)
		(layer "In11.Cu")
		(net "P5E_CPU1_PE2_TX_C_DN<14>")
	)
	(segment
		(start 127.602234 -427.519338)
		(end 127.750062 -427.37151)
		(width 0.14732)
		(layer "In11.Cu")
		(net "P5E_CPU1_PE2_TX_C_DN<14>")
	)
	(segment
		(start 124.081794 -403.883876)
		(end 123.787154 -404.178516)
		(width 0.14732)
		(layer "In11.Cu")
		(net "P5E_CPU1_PE2_TX_C_DN<14>")
	)
	(segment
		(start 123.601734 -410.75229)
		(end 123.734068 -411.258512)
		(width 0.14732)
		(layer "In11.Cu")
		(net "P5E_CPU1_PE2_TX_C_DN<14>")
	)
	(segment
		(start 127.066802 -427.395386)
		(end 127.190754 -427.519338)
		(width 0.14732)
		(layer "In11.Cu")
		(net "P5E_CPU1_PE2_TX_C_DN<14>")
	)
	(segment
		(start 123.991116 -412.241492)
		(end 124.162058 -412.341314)
		(width 0.14732)
		(layer "In11.Cu")
		(net "P5E_CPU1_PE2_TX_C_DN<14>")
	)
	(segment
		(start 124.412756 -413.851344)
		(end 124.412502 -413.851598)
		(width 0.14732)
		(layer "In11.Cu")
		(net "P5E_CPU1_PE2_TX_C_DN<14>")
	)
	(segment
		(start 124.155454 -412.868364)
		(end 124.248418 -413.224472)
		(width 0.14732)
		(layer "In11.Cu")
		(net "P5E_CPU1_PE2_TX_C_DN<14>")
	)
	(segment
		(start 127.066802 -424.000676)
		(end 127.066802 -427.395386)
		(width 0.14732)
		(layer "In11.Cu")
		(net "P5E_CPU1_PE2_TX_C_DN<14>")
	)
	(segment
		(start 127.190754 -427.519338)
		(end 127.602234 -427.519338)
		(width 0.14732)
		(layer "In11.Cu")
		(net "P5E_CPU1_PE2_TX_C_DN<14>")
	)
	(segment
		(start 124.162058 -412.341314)
		(end 124.255276 -412.69793)
		(width 0.14732)
		(layer "In11.Cu")
		(net "P5E_CPU1_PE2_TX_C_DN<14>")
	)
	(segment
		(start 124.248418 -413.224472)
		(end 124.41936 -413.324294)
		(width 0.14732)
		(layer "In11.Cu")
		(net "P5E_CPU1_PE2_TX_C_DN<14>")
	)
	(segment
		(start 123.601734 -406.418542)
		(end 123.601734 -410.75229)
		(width 0.14732)
		(layer "In11.Cu")
		(net "P5E_CPU1_PE2_TX_C_DN<14>")
	)
	(segment
		(start 123.904756 -411.358334)
		(end 123.997974 -411.71495)
		(width 0.14732)
		(layer "In11.Cu")
		(net "P5E_CPU1_PE2_TX_C_DN<14>")
	)
	(segment
		(start 124.512324 -413.68091)
		(end 124.412756 -413.851344)
		(width 0.14732)
		(layer "In11.Cu")
		(net "P5E_CPU1_PE2_TX_C_DN<14>")
	)
	(segment
		(start 124.255276 -412.69793)
		(end 124.155454 -412.868364)
		(width 0.14732)
		(layer "In11.Cu")
		(net "P5E_CPU1_PE2_TX_C_DN<14>")
	)
	(segment
		(start 123.898152 -411.885384)
		(end 123.991116 -412.241492)
		(width 0.14732)
		(layer "In11.Cu")
		(net "P5E_CPU1_PE2_TX_C_DN<14>")
	)
	(segment
		(start 126.843536 -402.96465)
		(end 127.170434 -402.637752)
		(width 0.13208)
		(layer "F.Cu")
		(net "P5E_CPU1_PE2_TX_C_DN<13>")
	)
	(segment
		(start 127.145034 -403.883876)
		(end 126.843536 -403.582378)
		(width 0.13208)
		(layer "F.Cu")
		(net "P5E_CPU1_PE2_TX_C_DN<13>")
	)
	(segment
		(start 126.843536 -403.582378)
		(end 126.843536 -402.96465)
		(width 0.13208)
		(layer "F.Cu")
		(net "P5E_CPU1_PE2_TX_C_DN<13>")
	)
	(segment
		(start 127.04953 -411.93212)
		(end 127.119888 -412.29407)
		(width 0.14732)
		(layer "In11.Cu")
		(net "P5E_CPU1_PE2_TX_C_DN<13>")
	)
	(segment
		(start 127.604012 -415.518346)
		(end 127.674116 -415.879788)
		(width 0.14732)
		(layer "In11.Cu")
		(net "P5E_CPU1_PE2_TX_C_DN<13>")
	)
	(segment
		(start 129.19075 -426.519594)
		(end 129.60223 -426.519594)
		(width 0.14732)
		(layer "In11.Cu")
		(net "P5E_CPU1_PE2_TX_C_DN<13>")
	)
	(segment
		(start 126.850394 -404.178516)
		(end 126.850394 -406.233122)
		(width 0.14732)
		(layer "In11.Cu")
		(net "P5E_CPU1_PE2_TX_C_DN<13>")
	)
	(segment
		(start 127.079502 -412.819342)
		(end 127.243586 -412.929832)
		(width 0.14732)
		(layer "In11.Cu")
		(net "P5E_CPU1_PE2_TX_C_DN<13>")
	)
	(segment
		(start 126.664974 -406.418542)
		(end 126.664974 -410.684472)
		(width 0.14732)
		(layer "In11.Cu")
		(net "P5E_CPU1_PE2_TX_C_DN<13>")
	)
	(segment
		(start 127.145034 -403.883876)
		(end 126.850394 -404.178516)
		(width 0.14732)
		(layer "In11.Cu")
		(net "P5E_CPU1_PE2_TX_C_DN<13>")
	)
	(segment
		(start 127.674116 -415.879788)
		(end 127.837946 -415.990278)
		(width 0.14732)
		(layer "In11.Cu")
		(net "P5E_CPU1_PE2_TX_C_DN<13>")
	)
	(segment
		(start 127.837946 -415.990278)
		(end 127.908304 -416.352228)
		(width 0.14732)
		(layer "In11.Cu")
		(net "P5E_CPU1_PE2_TX_C_DN<13>")
	)
	(segment
		(start 127.480314 -414.88233)
		(end 127.644144 -414.99282)
		(width 0.14732)
		(layer "In11.Cu")
		(net "P5E_CPU1_PE2_TX_C_DN<13>")
	)
	(segment
		(start 129.60223 -426.519594)
		(end 129.750058 -426.371766)
		(width 0.14732)
		(layer "In11.Cu")
		(net "P5E_CPU1_PE2_TX_C_DN<13>")
	)
	(segment
		(start 127.5207 -414.357058)
		(end 127.41021 -414.520888)
		(width 0.14732)
		(layer "In11.Cu")
		(net "P5E_CPU1_PE2_TX_C_DN<13>")
	)
	(segment
		(start 127.450342 -413.995362)
		(end 127.5207 -414.357058)
		(width 0.14732)
		(layer "In11.Cu")
		(net "P5E_CPU1_PE2_TX_C_DN<13>")
	)
	(segment
		(start 127.009398 -412.4579)
		(end 127.079502 -412.819342)
		(width 0.14732)
		(layer "In11.Cu")
		(net "P5E_CPU1_PE2_TX_C_DN<13>")
	)
	(segment
		(start 129.066798 -423.05732)
		(end 129.066798 -426.395642)
		(width 0.14732)
		(layer "In11.Cu")
		(net "P5E_CPU1_PE2_TX_C_DN<13>")
	)
	(segment
		(start 127.286512 -413.884872)
		(end 127.450342 -413.995362)
		(width 0.14732)
		(layer "In11.Cu")
		(net "P5E_CPU1_PE2_TX_C_DN<13>")
	)
	(segment
		(start 127.644144 -414.99282)
		(end 127.714502 -415.35477)
		(width 0.14732)
		(layer "In11.Cu")
		(net "P5E_CPU1_PE2_TX_C_DN<13>")
	)
	(segment
		(start 126.850394 -406.233122)
		(end 126.664974 -406.418542)
		(width 0.14732)
		(layer "In11.Cu")
		(net "P5E_CPU1_PE2_TX_C_DN<13>")
	)
	(segment
		(start 129.066798 -426.395642)
		(end 129.19075 -426.519594)
		(width 0.14732)
		(layer "In11.Cu")
		(net "P5E_CPU1_PE2_TX_C_DN<13>")
	)
	(segment
		(start 127.31369 -413.291528)
		(end 127.2032 -413.455358)
		(width 0.14732)
		(layer "In11.Cu")
		(net "P5E_CPU1_PE2_TX_C_DN<13>")
	)
	(segment
		(start 127.714502 -415.35477)
		(end 127.604012 -415.518346)
		(width 0.14732)
		(layer "In11.Cu")
		(net "P5E_CPU1_PE2_TX_C_DN<13>")
	)
	(segment
		(start 129.750058 -426.371766)
		(end 129.750058 -426.089826)
		(width 0.14732)
		(layer "In11.Cu")
		(net "P5E_CPU1_PE2_TX_C_DN<13>")
	)
	(segment
		(start 127.79756 -416.515804)
		(end 129.066798 -423.05732)
		(width 0.14732)
		(layer "In11.Cu")
		(net "P5E_CPU1_PE2_TX_C_DN<13>")
	)
	(segment
		(start 127.243586 -412.929832)
		(end 127.31369 -413.291528)
		(width 0.14732)
		(layer "In11.Cu")
		(net "P5E_CPU1_PE2_TX_C_DN<13>")
	)
	(segment
		(start 126.664974 -410.684472)
		(end 126.8857 -411.82163)
		(width 0.14732)
		(layer "In11.Cu")
		(net "P5E_CPU1_PE2_TX_C_DN<13>")
	)
	(segment
		(start 127.908304 -416.352228)
		(end 127.79756 -416.515804)
		(width 0.14732)
		(layer "In11.Cu")
		(net "P5E_CPU1_PE2_TX_C_DN<13>")
	)
	(segment
		(start 127.2032 -413.455358)
		(end 127.286512 -413.884872)
		(width 0.14732)
		(layer "In11.Cu")
		(net "P5E_CPU1_PE2_TX_C_DN<13>")
	)
	(segment
		(start 127.119888 -412.29407)
		(end 127.009398 -412.4579)
		(width 0.14732)
		(layer "In11.Cu")
		(net "P5E_CPU1_PE2_TX_C_DN<13>")
	)
	(segment
		(start 127.41021 -414.520888)
		(end 127.480314 -414.88233)
		(width 0.14732)
		(layer "In11.Cu")
		(net "P5E_CPU1_PE2_TX_C_DN<13>")
	)
	(segment
		(start 126.8857 -411.82163)
		(end 127.04953 -411.93212)
		(width 0.14732)
		(layer "In11.Cu")
		(net "P5E_CPU1_PE2_TX_C_DN<13>")
	)
	(segment
		(start 130.208274 -403.883876)
		(end 129.906776 -403.582378)
		(width 0.13208)
		(layer "F.Cu")
		(net "P5E_CPU1_PE2_TX_C_DN<12>")
	)
	(segment
		(start 129.906776 -402.96465)
		(end 130.233674 -402.637752)
		(width 0.13208)
		(layer "F.Cu")
		(net "P5E_CPU1_PE2_TX_C_DN<12>")
	)
	(segment
		(start 129.906776 -403.582378)
		(end 129.906776 -402.96465)
		(width 0.13208)
		(layer "F.Cu")
		(net "P5E_CPU1_PE2_TX_C_DN<12>")
	)
	(segment
		(start 131.066794 -427.395386)
		(end 131.190746 -427.519338)
		(width 0.14732)
		(layer "In11.Cu")
		(net "P5E_CPU1_PE2_TX_C_DN<12>")
	)
	(segment
		(start 131.602226 -427.519338)
		(end 131.750054 -427.37151)
		(width 0.14732)
		(layer "In11.Cu")
		(net "P5E_CPU1_PE2_TX_C_DN<12>")
	)
	(segment
		(start 130.316224 -416.882834)
		(end 130.20802 -417.0172)
		(width 0.14732)
		(layer "In11.Cu")
		(net "P5E_CPU1_PE2_TX_C_DN<12>")
	)
	(segment
		(start 129.956306 -413.549084)
		(end 129.848356 -413.68345)
		(width 0.14732)
		(layer "In11.Cu")
		(net "P5E_CPU1_PE2_TX_C_DN<12>")
	)
	(segment
		(start 130.029712 -414.22574)
		(end 130.076448 -414.660334)
		(width 0.14732)
		(layer "In11.Cu")
		(net "P5E_CPU1_PE2_TX_C_DN<12>")
	)
	(segment
		(start 130.208274 -403.883876)
		(end 129.913634 -404.178516)
		(width 0.14732)
		(layer "In11.Cu")
		(net "P5E_CPU1_PE2_TX_C_DN<12>")
	)
	(segment
		(start 129.728214 -412.5722)
		(end 129.77495 -413.00654)
		(width 0.14732)
		(layer "In11.Cu")
		(net "P5E_CPU1_PE2_TX_C_DN<12>")
	)
	(segment
		(start 130.088132 -415.90595)
		(end 130.134868 -416.34029)
		(width 0.14732)
		(layer "In11.Cu")
		(net "P5E_CPU1_PE2_TX_C_DN<12>")
	)
	(segment
		(start 131.750054 -427.37151)
		(end 131.750054 -427.089824)
		(width 0.14732)
		(layer "In11.Cu")
		(net "P5E_CPU1_PE2_TX_C_DN<12>")
	)
	(segment
		(start 129.913634 -406.233122)
		(end 129.728214 -406.418542)
		(width 0.14732)
		(layer "In11.Cu")
		(net "P5E_CPU1_PE2_TX_C_DN<12>")
	)
	(segment
		(start 129.913634 -404.178516)
		(end 129.913634 -406.233122)
		(width 0.14732)
		(layer "In11.Cu")
		(net "P5E_CPU1_PE2_TX_C_DN<12>")
	)
	(segment
		(start 129.848356 -413.68345)
		(end 129.895092 -414.11779)
		(width 0.14732)
		(layer "In11.Cu")
		(net "P5E_CPU1_PE2_TX_C_DN<12>")
	)
	(segment
		(start 130.20802 -417.0172)
		(end 131.066794 -424.976544)
		(width 0.14732)
		(layer "In11.Cu")
		(net "P5E_CPU1_PE2_TX_C_DN<12>")
	)
	(segment
		(start 129.895092 -414.11779)
		(end 130.029712 -414.22574)
		(width 0.14732)
		(layer "In11.Cu")
		(net "P5E_CPU1_PE2_TX_C_DN<12>")
	)
	(segment
		(start 130.076448 -414.660334)
		(end 129.968244 -414.7947)
		(width 0.14732)
		(layer "In11.Cu")
		(net "P5E_CPU1_PE2_TX_C_DN<12>")
	)
	(segment
		(start 129.90957 -413.11449)
		(end 129.956306 -413.549084)
		(width 0.14732)
		(layer "In11.Cu")
		(net "P5E_CPU1_PE2_TX_C_DN<12>")
	)
	(segment
		(start 130.1496 -415.33699)
		(end 130.196336 -415.771584)
		(width 0.14732)
		(layer "In11.Cu")
		(net "P5E_CPU1_PE2_TX_C_DN<12>")
	)
	(segment
		(start 129.728214 -406.418542)
		(end 129.728214 -412.5722)
		(width 0.14732)
		(layer "In11.Cu")
		(net "P5E_CPU1_PE2_TX_C_DN<12>")
	)
	(segment
		(start 130.269488 -416.44824)
		(end 130.316224 -416.882834)
		(width 0.14732)
		(layer "In11.Cu")
		(net "P5E_CPU1_PE2_TX_C_DN<12>")
	)
	(segment
		(start 131.066794 -424.976544)
		(end 131.066794 -427.395386)
		(width 0.14732)
		(layer "In11.Cu")
		(net "P5E_CPU1_PE2_TX_C_DN<12>")
	)
	(segment
		(start 130.196336 -415.771584)
		(end 130.088132 -415.90595)
		(width 0.14732)
		(layer "In11.Cu")
		(net "P5E_CPU1_PE2_TX_C_DN<12>")
	)
	(segment
		(start 129.77495 -413.00654)
		(end 129.90957 -413.11449)
		(width 0.14732)
		(layer "In11.Cu")
		(net "P5E_CPU1_PE2_TX_C_DN<12>")
	)
	(segment
		(start 130.01498 -415.22904)
		(end 130.1496 -415.33699)
		(width 0.14732)
		(layer "In11.Cu")
		(net "P5E_CPU1_PE2_TX_C_DN<12>")
	)
	(segment
		(start 130.134868 -416.34029)
		(end 130.269488 -416.44824)
		(width 0.14732)
		(layer "In11.Cu")
		(net "P5E_CPU1_PE2_TX_C_DN<12>")
	)
	(segment
		(start 131.190746 -427.519338)
		(end 131.602226 -427.519338)
		(width 0.14732)
		(layer "In11.Cu")
		(net "P5E_CPU1_PE2_TX_C_DN<12>")
	)
	(segment
		(start 129.968244 -414.7947)
		(end 130.01498 -415.22904)
		(width 0.14732)
		(layer "In11.Cu")
		(net "P5E_CPU1_PE2_TX_C_DN<12>")
	)
	(segment
		(start 133.271514 -403.883876)
		(end 132.970016 -403.582378)
		(width 0.13208)
		(layer "F.Cu")
		(net "P5E_CPU1_PE2_TX_C_DN<11>")
	)
	(segment
		(start 132.970016 -403.582378)
		(end 132.970016 -402.96465)
		(width 0.13208)
		(layer "F.Cu")
		(net "P5E_CPU1_PE2_TX_C_DN<11>")
	)
	(segment
		(start 132.970016 -402.96465)
		(end 133.296914 -402.637752)
		(width 0.13208)
		(layer "F.Cu")
		(net "P5E_CPU1_PE2_TX_C_DN<11>")
	)
	(segment
		(start 133.271514 -403.883876)
		(end 132.976874 -404.178516)
		(width 0.14732)
		(layer "In11.Cu")
		(net "P5E_CPU1_PE2_TX_C_DN<11>")
	)
	(segment
		(start 133.015736 -417.575238)
		(end 133.027166 -418.012118)
		(width 0.14732)
		(layer "In11.Cu")
		(net "P5E_CPU1_PE2_TX_C_DN<11>")
	)
	(segment
		(start 132.791454 -413.827976)
		(end 132.80517 -414.338262)
		(width 0.14732)
		(layer "In11.Cu")
		(net "P5E_CPU1_PE2_TX_C_DN<11>")
	)
	(segment
		(start 132.791454 -406.418542)
		(end 132.791454 -413.827976)
		(width 0.14732)
		(layer "In11.Cu")
		(net "P5E_CPU1_PE2_TX_C_DN<11>")
	)
	(segment
		(start 132.822442 -414.985962)
		(end 132.832094 -415.354008)
		(width 0.14732)
		(layer "In11.Cu")
		(net "P5E_CPU1_PE2_TX_C_DN<11>")
	)
	(segment
		(start 132.88772 -417.45408)
		(end 133.015736 -417.575238)
		(width 0.14732)
		(layer "In11.Cu")
		(net "P5E_CPU1_PE2_TX_C_DN<11>")
	)
	(segment
		(start 132.849366 -416.001708)
		(end 132.859018 -416.369754)
		(width 0.14732)
		(layer "In11.Cu")
		(net "P5E_CPU1_PE2_TX_C_DN<11>")
	)
	(segment
		(start 132.94868 -414.474152)
		(end 132.958332 -414.842706)
		(width 0.14732)
		(layer "In11.Cu")
		(net "P5E_CPU1_PE2_TX_C_DN<11>")
	)
	(segment
		(start 133.002528 -416.505644)
		(end 133.01218 -416.874198)
		(width 0.14732)
		(layer "In11.Cu")
		(net "P5E_CPU1_PE2_TX_C_DN<11>")
	)
	(segment
		(start 133.027166 -418.012118)
		(end 132.906008 -418.13988)
		(width 0.14732)
		(layer "In11.Cu")
		(net "P5E_CPU1_PE2_TX_C_DN<11>")
	)
	(segment
		(start 132.935726 -419.262306)
		(end 133.06679 -424.232832)
		(width 0.14732)
		(layer "In11.Cu")
		(net "P5E_CPU1_PE2_TX_C_DN<11>")
	)
	(segment
		(start 133.75005 -426.371766)
		(end 133.75005 -426.089826)
		(width 0.14732)
		(layer "In11.Cu")
		(net "P5E_CPU1_PE2_TX_C_DN<11>")
	)
	(segment
		(start 132.985256 -415.858452)
		(end 132.849366 -416.001708)
		(width 0.14732)
		(layer "In11.Cu")
		(net "P5E_CPU1_PE2_TX_C_DN<11>")
	)
	(segment
		(start 132.859018 -416.369754)
		(end 133.002528 -416.505644)
		(width 0.14732)
		(layer "In11.Cu")
		(net "P5E_CPU1_PE2_TX_C_DN<11>")
	)
	(segment
		(start 133.01218 -416.874198)
		(end 132.87629 -417.017454)
		(width 0.14732)
		(layer "In11.Cu")
		(net "P5E_CPU1_PE2_TX_C_DN<11>")
	)
	(segment
		(start 133.190742 -426.519594)
		(end 133.602222 -426.519594)
		(width 0.14732)
		(layer "In11.Cu")
		(net "P5E_CPU1_PE2_TX_C_DN<11>")
	)
	(segment
		(start 133.06679 -424.232832)
		(end 133.06679 -426.395642)
		(width 0.14732)
		(layer "In11.Cu")
		(net "P5E_CPU1_PE2_TX_C_DN<11>")
	)
	(segment
		(start 132.906008 -418.13988)
		(end 132.917438 -418.576506)
		(width 0.14732)
		(layer "In11.Cu")
		(net "P5E_CPU1_PE2_TX_C_DN<11>")
	)
	(segment
		(start 132.975604 -415.489898)
		(end 132.985256 -415.858452)
		(width 0.14732)
		(layer "In11.Cu")
		(net "P5E_CPU1_PE2_TX_C_DN<11>")
	)
	(segment
		(start 133.602222 -426.519594)
		(end 133.75005 -426.371766)
		(width 0.14732)
		(layer "In11.Cu")
		(net "P5E_CPU1_PE2_TX_C_DN<11>")
	)
	(segment
		(start 132.976874 -404.178516)
		(end 132.976874 -406.233122)
		(width 0.14732)
		(layer "In11.Cu")
		(net "P5E_CPU1_PE2_TX_C_DN<11>")
	)
	(segment
		(start 132.87629 -417.017454)
		(end 132.88772 -417.45408)
		(width 0.14732)
		(layer "In11.Cu")
		(net "P5E_CPU1_PE2_TX_C_DN<11>")
	)
	(segment
		(start 132.917438 -418.576506)
		(end 133.045454 -418.697664)
		(width 0.14732)
		(layer "In11.Cu")
		(net "P5E_CPU1_PE2_TX_C_DN<11>")
	)
	(segment
		(start 132.832094 -415.354008)
		(end 132.975604 -415.489898)
		(width 0.14732)
		(layer "In11.Cu")
		(net "P5E_CPU1_PE2_TX_C_DN<11>")
	)
	(segment
		(start 133.06679 -426.395642)
		(end 133.190742 -426.519594)
		(width 0.14732)
		(layer "In11.Cu")
		(net "P5E_CPU1_PE2_TX_C_DN<11>")
	)
	(segment
		(start 132.80517 -414.338262)
		(end 132.94868 -414.474152)
		(width 0.14732)
		(layer "In11.Cu")
		(net "P5E_CPU1_PE2_TX_C_DN<11>")
	)
	(segment
		(start 133.056884 -419.134544)
		(end 132.935726 -419.262306)
		(width 0.14732)
		(layer "In11.Cu")
		(net "P5E_CPU1_PE2_TX_C_DN<11>")
	)
	(segment
		(start 132.958332 -414.842706)
		(end 132.822442 -414.985962)
		(width 0.14732)
		(layer "In11.Cu")
		(net "P5E_CPU1_PE2_TX_C_DN<11>")
	)
	(segment
		(start 133.045454 -418.697664)
		(end 133.056884 -419.134544)
		(width 0.14732)
		(layer "In11.Cu")
		(net "P5E_CPU1_PE2_TX_C_DN<11>")
	)
	(segment
		(start 132.976874 -406.233122)
		(end 132.791454 -406.418542)
		(width 0.14732)
		(layer "In11.Cu")
		(net "P5E_CPU1_PE2_TX_C_DN<11>")
	)
	(segment
		(start 136.033256 -402.96465)
		(end 136.360154 -402.637752)
		(width 0.13208)
		(layer "F.Cu")
		(net "P5E_CPU1_PE2_TX_C_DN<10>")
	)
	(segment
		(start 136.033256 -403.582378)
		(end 136.033256 -402.96465)
		(width 0.13208)
		(layer "F.Cu")
		(net "P5E_CPU1_PE2_TX_C_DN<10>")
	)
	(segment
		(start 136.334754 -403.883876)
		(end 136.033256 -403.582378)
		(width 0.13208)
		(layer "F.Cu")
		(net "P5E_CPU1_PE2_TX_C_DN<10>")
	)
	(segment
		(start 135.264144 -423.116502)
		(end 135.117332 -423.24909)
		(width 0.14732)
		(layer "In11.Cu")
		(net "P5E_CPU1_PE2_TX_C_DN<10>")
	)
	(segment
		(start 135.117332 -423.24909)
		(end 135.066786 -424.26128)
		(width 0.14732)
		(layer "In11.Cu")
		(net "P5E_CPU1_PE2_TX_C_DN<10>")
	)
	(segment
		(start 136.334754 -403.883876)
		(end 136.040114 -404.178516)
		(width 0.14732)
		(layer "In11.Cu")
		(net "P5E_CPU1_PE2_TX_C_DN<10>")
	)
	(segment
		(start 135.67918 -412.05023)
		(end 135.252206 -420.572438)
		(width 0.14732)
		(layer "In11.Cu")
		(net "P5E_CPU1_PE2_TX_C_DN<10>")
	)
	(segment
		(start 135.252206 -420.572438)
		(end 135.384794 -420.718742)
		(width 0.14732)
		(layer "In11.Cu")
		(net "P5E_CPU1_PE2_TX_C_DN<10>")
	)
	(segment
		(start 136.040114 -406.233122)
		(end 135.854694 -406.418542)
		(width 0.14732)
		(layer "In11.Cu")
		(net "P5E_CPU1_PE2_TX_C_DN<10>")
	)
	(segment
		(start 136.040114 -404.178516)
		(end 136.040114 -406.233122)
		(width 0.14732)
		(layer "In11.Cu")
		(net "P5E_CPU1_PE2_TX_C_DN<10>")
	)
	(segment
		(start 135.602218 -427.519338)
		(end 135.750046 -427.37151)
		(width 0.14732)
		(layer "In11.Cu")
		(net "P5E_CPU1_PE2_TX_C_DN<10>")
	)
	(segment
		(start 135.282686 -422.748456)
		(end 135.264144 -423.116502)
		(width 0.14732)
		(layer "In11.Cu")
		(net "P5E_CPU1_PE2_TX_C_DN<10>")
	)
	(segment
		(start 135.384794 -420.718742)
		(end 135.366252 -421.087042)
		(width 0.14732)
		(layer "In11.Cu")
		(net "P5E_CPU1_PE2_TX_C_DN<10>")
	)
	(segment
		(start 135.168386 -422.234106)
		(end 135.150098 -422.601898)
		(width 0.14732)
		(layer "In11.Cu")
		(net "P5E_CPU1_PE2_TX_C_DN<10>")
	)
	(segment
		(start 135.150098 -422.601898)
		(end 135.282686 -422.748456)
		(width 0.14732)
		(layer "In11.Cu")
		(net "P5E_CPU1_PE2_TX_C_DN<10>")
	)
	(segment
		(start 135.854694 -410.543502)
		(end 135.67918 -412.05023)
		(width 0.14732)
		(layer "In11.Cu")
		(net "P5E_CPU1_PE2_TX_C_DN<10>")
	)
	(segment
		(start 135.066786 -427.395386)
		(end 135.190738 -427.519338)
		(width 0.14732)
		(layer "In11.Cu")
		(net "P5E_CPU1_PE2_TX_C_DN<10>")
	)
	(segment
		(start 135.201152 -421.587168)
		(end 135.33374 -421.733472)
		(width 0.14732)
		(layer "In11.Cu")
		(net "P5E_CPU1_PE2_TX_C_DN<10>")
	)
	(segment
		(start 135.33374 -421.733472)
		(end 135.315198 -422.101772)
		(width 0.14732)
		(layer "In11.Cu")
		(net "P5E_CPU1_PE2_TX_C_DN<10>")
	)
	(segment
		(start 135.366252 -421.087042)
		(end 135.21944 -421.219376)
		(width 0.14732)
		(layer "In11.Cu")
		(net "P5E_CPU1_PE2_TX_C_DN<10>")
	)
	(segment
		(start 135.854694 -406.418542)
		(end 135.854694 -410.543502)
		(width 0.14732)
		(layer "In11.Cu")
		(net "P5E_CPU1_PE2_TX_C_DN<10>")
	)
	(segment
		(start 135.190738 -427.519338)
		(end 135.602218 -427.519338)
		(width 0.14732)
		(layer "In11.Cu")
		(net "P5E_CPU1_PE2_TX_C_DN<10>")
	)
	(segment
		(start 135.750046 -427.37151)
		(end 135.750046 -427.089824)
		(width 0.14732)
		(layer "In11.Cu")
		(net "P5E_CPU1_PE2_TX_C_DN<10>")
	)
	(segment
		(start 135.066786 -424.26128)
		(end 135.066786 -427.395386)
		(width 0.14732)
		(layer "In11.Cu")
		(net "P5E_CPU1_PE2_TX_C_DN<10>")
	)
	(segment
		(start 135.315198 -422.101772)
		(end 135.168386 -422.234106)
		(width 0.14732)
		(layer "In11.Cu")
		(net "P5E_CPU1_PE2_TX_C_DN<10>")
	)
	(segment
		(start 135.21944 -421.219376)
		(end 135.201152 -421.587168)
		(width 0.14732)
		(layer "In11.Cu")
		(net "P5E_CPU1_PE2_TX_C_DN<10>")
	)
	(segment
		(start 166.967154 -403.883876)
		(end 166.665656 -403.582378)
		(width 0.13208)
		(layer "F.Cu")
		(net "P5E_CPU1_PE2_TX_C_DN<0>")
	)
	(segment
		(start 166.665656 -403.582378)
		(end 166.665656 -402.96465)
		(width 0.13208)
		(layer "F.Cu")
		(net "P5E_CPU1_PE2_TX_C_DN<0>")
	)
	(segment
		(start 166.665656 -402.96465)
		(end 166.992554 -402.637752)
		(width 0.13208)
		(layer "F.Cu")
		(net "P5E_CPU1_PE2_TX_C_DN<0>")
	)
	(segment
		(start 158.23819 -421.652954)
		(end 158.042102 -421.6781)
		(width 0.14732)
		(layer "In11.Cu")
		(net "P5E_CPU1_PE2_TX_C_DN<0>")
	)
	(segment
		(start 158.438596 -421.165528)
		(end 158.463488 -421.361362)
		(width 0.14732)
		(layer "In11.Cu")
		(net "P5E_CPU1_PE2_TX_C_DN<0>")
	)
	(segment
		(start 157.84195 -422.165272)
		(end 157.616652 -422.456864)
		(width 0.14732)
		(layer "In11.Cu")
		(net "P5E_CPU1_PE2_TX_C_DN<0>")
	)
	(segment
		(start 166.672514 -406.233122)
		(end 166.487094 -406.418542)
		(width 0.14732)
		(layer "In11.Cu")
		(net "P5E_CPU1_PE2_TX_C_DN<0>")
	)
	(segment
		(start 166.672514 -404.178516)
		(end 166.672514 -406.233122)
		(width 0.14732)
		(layer "In11.Cu")
		(net "P5E_CPU1_PE2_TX_C_DN<0>")
	)
	(segment
		(start 157.420564 -422.48201)
		(end 157.19552 -422.773348)
		(width 0.14732)
		(layer "In11.Cu")
		(net "P5E_CPU1_PE2_TX_C_DN<0>")
	)
	(segment
		(start 156.799026 -423.286174)
		(end 156.066744 -424.233594)
		(width 0.14732)
		(layer "In11.Cu")
		(net "P5E_CPU1_PE2_TX_C_DN<0>")
	)
	(segment
		(start 157.817058 -421.969438)
		(end 157.84195 -422.165272)
		(width 0.14732)
		(layer "In11.Cu")
		(net "P5E_CPU1_PE2_TX_C_DN<0>")
	)
	(segment
		(start 158.463488 -421.361362)
		(end 158.23819 -421.652954)
		(width 0.14732)
		(layer "In11.Cu")
		(net "P5E_CPU1_PE2_TX_C_DN<0>")
	)
	(segment
		(start 157.220412 -422.969436)
		(end 156.995114 -423.261028)
		(width 0.14732)
		(layer "In11.Cu")
		(net "P5E_CPU1_PE2_TX_C_DN<0>")
	)
	(segment
		(start 156.066744 -427.395386)
		(end 156.190696 -427.519338)
		(width 0.14732)
		(layer "In11.Cu")
		(net "P5E_CPU1_PE2_TX_C_DN<0>")
	)
	(segment
		(start 166.967154 -403.883876)
		(end 166.672514 -404.178516)
		(width 0.14732)
		(layer "In11.Cu")
		(net "P5E_CPU1_PE2_TX_C_DN<0>")
	)
	(segment
		(start 156.995114 -423.261028)
		(end 156.799026 -423.286174)
		(width 0.14732)
		(layer "In11.Cu")
		(net "P5E_CPU1_PE2_TX_C_DN<0>")
	)
	(segment
		(start 156.190696 -427.519338)
		(end 156.602176 -427.519338)
		(width 0.14732)
		(layer "In11.Cu")
		(net "P5E_CPU1_PE2_TX_C_DN<0>")
	)
	(segment
		(start 156.750004 -427.37151)
		(end 156.750004 -427.089824)
		(width 0.14732)
		(layer "In11.Cu")
		(net "P5E_CPU1_PE2_TX_C_DN<0>")
	)
	(segment
		(start 157.616652 -422.456864)
		(end 157.420564 -422.48201)
		(width 0.14732)
		(layer "In11.Cu")
		(net "P5E_CPU1_PE2_TX_C_DN<0>")
	)
	(segment
		(start 156.602176 -427.519338)
		(end 156.750004 -427.37151)
		(width 0.14732)
		(layer "In11.Cu")
		(net "P5E_CPU1_PE2_TX_C_DN<0>")
	)
	(segment
		(start 157.19552 -422.773348)
		(end 157.220412 -422.969436)
		(width 0.14732)
		(layer "In11.Cu")
		(net "P5E_CPU1_PE2_TX_C_DN<0>")
	)
	(segment
		(start 158.042102 -421.6781)
		(end 157.817058 -421.969438)
		(width 0.14732)
		(layer "In11.Cu")
		(net "P5E_CPU1_PE2_TX_C_DN<0>")
	)
	(segment
		(start 166.487094 -410.751782)
		(end 158.438596 -421.165528)
		(width 0.14732)
		(layer "In11.Cu")
		(net "P5E_CPU1_PE2_TX_C_DN<0>")
	)
	(segment
		(start 156.066744 -424.233594)
		(end 156.066744 -427.395386)
		(width 0.14732)
		(layer "In11.Cu")
		(net "P5E_CPU1_PE2_TX_C_DN<0>")
	)
	(segment
		(start 166.487094 -406.418542)
		(end 166.487094 -410.751782)
		(width 0.14732)
		(layer "In11.Cu")
		(net "P5E_CPU1_PE2_TX_C_DN<0>")
	)
	(segment
		(start 129.026666 -222.48368)
		(end 129.026666 -221.947994)
		(width 0.13208)
		(layer "F.Cu")
		(net "P5E_CPU1_PE2_RX_DP<9>")
	)
	(segment
		(start 129.026666 -221.947994)
		(end 129.026412 -221.94774)
		(width 0.13208)
		(layer "F.Cu")
		(net "P5E_CPU1_PE2_RX_DP<9>")
	)
	(segment
		(start 144.25168 -225.405188)
		(end 141.402308 -215.828626)
		(width 0.14732)
		(layer "In13.Cu")
		(net "P5E_CPU1_PE2_RX_DP<9>")
	)
	(segment
		(start 148.4122 -253.148846)
		(end 148.316696 -250.312428)
		(width 0.14732)
		(layer "In13.Cu")
		(net "P5E_CPU1_PE2_RX_DP<9>")
	)
	(segment
		(start 156.649674 -345.933776)
		(end 154.327352 -332.77048)
		(width 0.14732)
		(layer "In13.Cu")
		(net "P5E_CPU1_PE2_RX_DP<9>")
	)
	(segment
		(start 130.718814 -215.112346)
		(end 130.709924 -215.117426)
		(width 0.0889)
		(layer "In13.Cu")
		(net "P5E_CPU1_PE2_RX_DP<9>")
	)
	(segment
		(start 137.077196 -433.993798)
		(end 136.779254 -433.695856)
		(width 0.14732)
		(layer "In13.Cu")
		(net "P5E_CPU1_PE2_RX_DP<9>")
	)
	(segment
		(start 129.27203 -221.652846)
		(end 129.182876 -221.676722)
		(width 0.0889)
		(layer "In13.Cu")
		(net "P5E_CPU1_PE2_RX_DP<9>")
	)
	(segment
		(start 129.779776 -219.994988)
		(end 129.779014 -219.995496)
		(width 0.0889)
		(layer "In13.Cu")
		(net "P5E_CPU1_PE2_RX_DP<9>")
	)
	(segment
		(start 129.78511 -216.736422)
		(end 129.779776 -216.73947)
		(width 0.0889)
		(layer "In13.Cu")
		(net "P5E_CPU1_PE2_RX_DP<9>")
	)
	(segment
		(start 138.643614 -406.2222)
		(end 140.360654 -404.50516)
		(width 0.14732)
		(layer "In13.Cu")
		(net "P5E_CPU1_PE2_RX_DP<9>")
	)
	(segment
		(start 141.402308 -215.828626)
		(end 140.20419 -214.630508)
		(width 0.14732)
		(layer "In13.Cu")
		(net "P5E_CPU1_PE2_RX_DP<9>")
	)
	(segment
		(start 139.013184 -214.136986)
		(end 132.61213 -212.863684)
		(width 0.14732)
		(layer "In13.Cu")
		(net "P5E_CPU1_PE2_RX_DP<9>")
	)
	(segment
		(start 129.78511 -218.364308)
		(end 129.779776 -218.367356)
		(width 0.0889)
		(layer "In13.Cu")
		(net "P5E_CPU1_PE2_RX_DP<9>")
	)
	(segment
		(start 130.531362 -215.436704)
		(end 130.531362 -215.452198)
		(width 0.0889)
		(layer "In13.Cu")
		(net "P5E_CPU1_PE2_RX_DP<9>")
	)
	(segment
		(start 129.77749 -218.368626)
		(end 129.770124 -218.372944)
		(width 0.0889)
		(layer "In13.Cu")
		(net "P5E_CPU1_PE2_RX_DP<9>")
	)
	(segment
		(start 130.061716 -221.1197)
		(end 130.061716 -221.133924)
		(width 0.0889)
		(layer "In13.Cu")
		(net "P5E_CPU1_PE2_RX_DP<9>")
	)
	(segment
		(start 131.513326 -213.374986)
		(end 131.471416 -213.416896)
		(width 0.0889)
		(layer "In13.Cu")
		(net "P5E_CPU1_PE2_RX_DP<9>")
	)
	(segment
		(start 137.750042 -434.48986)
		(end 137.750042 -434.141372)
		(width 0.14732)
		(layer "In13.Cu")
		(net "P5E_CPU1_PE2_RX_DP<9>")
	)
	(segment
		(start 131.793996 -212.863684)
		(end 131.513326 -213.144354)
		(width 0.14732)
		(layer "In13.Cu")
		(net "P5E_CPU1_PE2_RX_DP<9>")
	)
	(segment
		(start 136.779254 -433.695856)
		(end 136.779254 -423.983912)
		(width 0.14732)
		(layer "In13.Cu")
		(net "P5E_CPU1_PE2_RX_DP<9>")
	)
	(segment
		(start 129.591816 -220.311218)
		(end 129.591816 -220.32849)
		(width 0.0889)
		(layer "In13.Cu")
		(net "P5E_CPU1_PE2_RX_DP<9>")
	)
	(segment
		(start 129.770124 -219.0115)
		(end 129.779014 -219.01658)
		(width 0.0889)
		(layer "In13.Cu")
		(net "P5E_CPU1_PE2_RX_DP<9>")
	)
	(segment
		(start 129.182876 -221.676722)
		(end 129.026412 -221.94774)
		(width 0.0889)
		(layer "In13.Cu")
		(net "P5E_CPU1_PE2_RX_DP<9>")
	)
	(segment
		(start 130.249168 -215.926162)
		(end 130.240278 -215.931242)
		(width 0.0889)
		(layer "In13.Cu")
		(net "P5E_CPU1_PE2_RX_DP<9>")
	)
	(segment
		(start 147.91182 -325.303388)
		(end 144.1069 -309.364888)
		(width 0.14732)
		(layer "In13.Cu")
		(net "P5E_CPU1_PE2_RX_DP<9>")
	)
	(segment
		(start 132.61213 -212.863684)
		(end 131.793996 -212.863684)
		(width 0.14732)
		(layer "In13.Cu")
		(net "P5E_CPU1_PE2_RX_DP<9>")
	)
	(segment
		(start 129.78511 -219.99194)
		(end 129.779776 -219.994988)
		(width 0.0889)
		(layer "In13.Cu")
		(net "P5E_CPU1_PE2_RX_DP<9>")
	)
	(segment
		(start 144.1069 -309.364888)
		(end 148.4122 -253.148846)
		(width 0.14732)
		(layer "In13.Cu")
		(net "P5E_CPU1_PE2_RX_DP<9>")
	)
	(segment
		(start 131.001008 -214.461852)
		(end 131.001008 -214.644732)
		(width 0.0889)
		(layer "In13.Cu")
		(net "P5E_CPU1_PE2_RX_DP<9>")
	)
	(segment
		(start 129.779776 -218.367356)
		(end 129.77749 -218.368626)
		(width 0.0889)
		(layer "In13.Cu")
		(net "P5E_CPU1_PE2_RX_DP<9>")
	)
	(segment
		(start 148.316696 -250.312428)
		(end 145.10512 -229.720648)
		(width 0.14732)
		(layer "In13.Cu")
		(net "P5E_CPU1_PE2_RX_DP<9>")
	)
	(segment
		(start 131.513326 -213.144354)
		(end 131.513326 -213.352888)
		(width 0.14732)
		(layer "In13.Cu")
		(net "P5E_CPU1_PE2_RX_DP<9>")
	)
	(segment
		(start 131.471416 -213.416896)
		(end 131.471416 -213.929468)
		(width 0.0889)
		(layer "In13.Cu")
		(net "P5E_CPU1_PE2_RX_DP<9>")
	)
	(segment
		(start 155.526486 -359.930954)
		(end 156.649674 -345.933776)
		(width 0.14732)
		(layer "In13.Cu")
		(net "P5E_CPU1_PE2_RX_DP<9>")
	)
	(segment
		(start 129.78511 -221.619826)
		(end 129.764282 -221.632018)
		(width 0.0889)
		(layer "In13.Cu")
		(net "P5E_CPU1_PE2_RX_DP<9>")
	)
	(segment
		(start 137.750042 -434.141372)
		(end 137.602468 -433.993798)
		(width 0.14732)
		(layer "In13.Cu")
		(net "P5E_CPU1_PE2_RX_DP<9>")
	)
	(segment
		(start 140.360654 -404.50516)
		(end 140.360654 -400.166332)
		(width 0.14732)
		(layer "In13.Cu")
		(net "P5E_CPU1_PE2_RX_DP<9>")
	)
	(segment
		(start 140.360654 -400.166332)
		(end 140.679424 -398.399)
		(width 0.14732)
		(layer "In13.Cu")
		(net "P5E_CPU1_PE2_RX_DP<9>")
	)
	(segment
		(start 131.513326 -213.352888)
		(end 131.513326 -213.374986)
		(width 0.0889)
		(layer "In13.Cu")
		(net "P5E_CPU1_PE2_RX_DP<9>")
	)
	(segment
		(start 137.602468 -433.993798)
		(end 137.077196 -433.993798)
		(width 0.14732)
		(layer "In13.Cu")
		(net "P5E_CPU1_PE2_RX_DP<9>")
	)
	(segment
		(start 145.10512 -229.720648)
		(end 144.25168 -225.405188)
		(width 0.14732)
		(layer "In13.Cu")
		(net "P5E_CPU1_PE2_RX_DP<9>")
	)
	(segment
		(start 140.20419 -214.630508)
		(end 139.013184 -214.136986)
		(width 0.14732)
		(layer "In13.Cu")
		(net "P5E_CPU1_PE2_RX_DP<9>")
	)
	(segment
		(start 129.779014 -219.01658)
		(end 129.78511 -219.020136)
		(width 0.0889)
		(layer "In13.Cu")
		(net "P5E_CPU1_PE2_RX_DP<9>")
	)
	(segment
		(start 136.779254 -423.983912)
		(end 136.779762 -423.940986)
		(width 0.14732)
		(layer "In13.Cu")
		(net "P5E_CPU1_PE2_RX_DP<9>")
	)
	(segment
		(start 129.591816 -217.0557)
		(end 129.591816 -217.072972)
		(width 0.0889)
		(layer "In13.Cu")
		(net "P5E_CPU1_PE2_RX_DP<9>")
	)
	(segment
		(start 138.643614 -410.35097)
		(end 138.643614 -406.2222)
		(width 0.14732)
		(layer "In13.Cu")
		(net "P5E_CPU1_PE2_RX_DP<9>")
	)
	(segment
		(start 136.779762 -423.940986)
		(end 138.643614 -410.35097)
		(width 0.14732)
		(layer "In13.Cu")
		(net "P5E_CPU1_PE2_RX_DP<9>")
	)
	(segment
		(start 154.327352 -332.77048)
		(end 147.91182 -325.303388)
		(width 0.14732)
		(layer "In13.Cu")
		(net "P5E_CPU1_PE2_RX_DP<9>")
	)
	(segment
		(start 140.679424 -398.399)
		(end 155.526486 -359.930954)
		(width 0.14732)
		(layer "In13.Cu")
		(net "P5E_CPU1_PE2_RX_DP<9>")
	)
	(segment
		(start 129.779776 -216.73947)
		(end 129.779014 -216.739978)
		(width 0.0889)
		(layer "In13.Cu")
		(net "P5E_CPU1_PE2_RX_DP<9>")
	)
	(arc
		(start 129.779014 -219.995496)
		(mid 129.644081 -220.12885)
		(end 129.591816 -220.311218)
		(width 0.0889)
		(layer "In13.Cu")
		(net "P5E_CPU1_PE2_RX_DP<9>")
	)
	(arc
		(start 129.292096 -221.660974)
		(mid 129.282025 -221.657005)
		(end 129.27203 -221.652846)
		(width 0.0889)
		(layer "In13.Cu")
		(net "P5E_CPU1_PE2_RX_DP<9>")
	)
	(arc
		(start 129.779014 -217.388694)
		(mid 130.062009 -217.874813)
		(end 129.78511 -218.364308)
		(width 0.0889)
		(layer "In13.Cu")
		(net "P5E_CPU1_PE2_RX_DP<9>")
	)
	(arc
		(start 129.779014 -216.739978)
		(mid 129.644081 -216.873332)
		(end 129.591816 -217.0557)
		(width 0.0889)
		(layer "In13.Cu")
		(net "P5E_CPU1_PE2_RX_DP<9>")
	)
	(arc
		(start 130.061716 -216.25052)
		(mid 129.987725 -216.530086)
		(end 129.78511 -216.736422)
		(width 0.0889)
		(layer "In13.Cu")
		(net "P5E_CPU1_PE2_RX_DP<9>")
	)
	(arc
		(start 129.764282 -221.632018)
		(mid 129.531367 -221.698229)
		(end 129.292096 -221.660974)
		(width 0.0889)
		(layer "In13.Cu")
		(net "P5E_CPU1_PE2_RX_DP<9>")
	)
	(arc
		(start 131.471416 -213.929468)
		(mid 131.359976 -214.122863)
		(end 131.185412 -214.261954)
		(width 0.0889)
		(layer "In13.Cu")
		(net "P5E_CPU1_PE2_RX_DP<9>")
	)
	(arc
		(start 131.001008 -214.644732)
		(mid 130.920097 -214.91486)
		(end 130.718814 -215.112346)
		(width 0.0889)
		(layer "In13.Cu")
		(net "P5E_CPU1_PE2_RX_DP<9>")
	)
	(arc
		(start 130.709924 -215.117426)
		(mid 130.58267 -215.247392)
		(end 130.531616 -215.421972)
		(width 0.0889)
		(layer "In13.Cu")
		(net "P5E_CPU1_PE2_RX_DP<9>")
	)
	(arc
		(start 130.061716 -221.133924)
		(mid 129.987725 -221.41349)
		(end 129.78511 -221.619826)
		(width 0.0889)
		(layer "In13.Cu")
		(net "P5E_CPU1_PE2_RX_DP<9>")
	)
	(arc
		(start 130.531616 -215.421972)
		(mid 130.531419 -215.429337)
		(end 130.531362 -215.436704)
		(width 0.0889)
		(layer "In13.Cu")
		(net "P5E_CPU1_PE2_RX_DP<9>")
	)
	(arc
		(start 130.240278 -215.931242)
		(mid 130.109364 -216.067602)
		(end 130.061716 -216.25052)
		(width 0.0889)
		(layer "In13.Cu")
		(net "P5E_CPU1_PE2_RX_DP<9>")
	)
	(arc
		(start 129.779014 -220.644212)
		(mid 129.982495 -220.845016)
		(end 130.061716 -221.1197)
		(width 0.0889)
		(layer "In13.Cu")
		(net "P5E_CPU1_PE2_RX_DP<9>")
	)
	(arc
		(start 129.78511 -219.020136)
		(mid 130.061684 -219.506038)
		(end 129.78511 -219.99194)
		(width 0.0889)
		(layer "In13.Cu")
		(net "P5E_CPU1_PE2_RX_DP<9>")
	)
	(arc
		(start 129.591816 -220.32849)
		(mid 129.644086 -220.510855)
		(end 129.779014 -220.644212)
		(width 0.0889)
		(layer "In13.Cu")
		(net "P5E_CPU1_PE2_RX_DP<9>")
	)
	(arc
		(start 130.531362 -215.452198)
		(mid 130.451992 -215.725932)
		(end 130.249168 -215.926162)
		(width 0.0889)
		(layer "In13.Cu")
		(net "P5E_CPU1_PE2_RX_DP<9>")
	)
	(arc
		(start 129.770124 -218.372944)
		(mid 129.591527 -218.692222)
		(end 129.770124 -219.0115)
		(width 0.0889)
		(layer "In13.Cu")
		(net "P5E_CPU1_PE2_RX_DP<9>")
	)
	(arc
		(start 129.591816 -217.072972)
		(mid 129.644086 -217.255337)
		(end 129.779014 -217.388694)
		(width 0.0889)
		(layer "In13.Cu")
		(net "P5E_CPU1_PE2_RX_DP<9>")
	)
	(arc
		(start 131.185412 -214.261954)
		(mid 131.076016 -214.346051)
		(end 131.001008 -214.461852)
		(width 0.0889)
		(layer "In13.Cu")
		(net "P5E_CPU1_PE2_RX_DP<9>")
	)
	(segment
		(start 128.556512 -221.134178)
		(end 128.556766 -221.133924)
		(width 0.13208)
		(layer "F.Cu")
		(net "P5E_CPU1_PE2_RX_DP<8>")
	)
	(segment
		(start 128.556512 -221.669864)
		(end 128.556512 -221.134178)
		(width 0.13208)
		(layer "F.Cu")
		(net "P5E_CPU1_PE2_RX_DP<8>")
	)
	(segment
		(start 138.765788 -213.143084)
		(end 138.67003 -212.999574)
		(width 0.14732)
		(layer "In13.Cu")
		(net "P5E_CPU1_PE2_RX_DP<8>")
	)
	(segment
		(start 128.842008 -219.018104)
		(end 128.84531 -219.020136)
		(width 0.0889)
		(layer "In13.Cu")
		(net "P5E_CPU1_PE2_RX_DP<8>")
	)
	(segment
		(start 128.839468 -216.739978)
		(end 128.838706 -216.740486)
		(width 0.0889)
		(layer "In13.Cu")
		(net "P5E_CPU1_PE2_RX_DP<8>")
	)
	(segment
		(start 131.574286 -211.923884)
		(end 130.862324 -212.218778)
		(width 0.14732)
		(layer "In13.Cu")
		(net "P5E_CPU1_PE2_RX_DP<8>")
	)
	(segment
		(start 128.838706 -216.740486)
		(end 128.836166 -216.74201)
		(width 0.0889)
		(layer "In13.Cu")
		(net "P5E_CPU1_PE2_RX_DP<8>")
	)
	(segment
		(start 129.591562 -213.8934)
		(end 129.591816 -213.893908)
		(width 0.0889)
		(layer "In13.Cu")
		(net "P5E_CPU1_PE2_RX_DP<8>")
	)
	(segment
		(start 129.121916 -217.859864)
		(end 129.121916 -217.878406)
		(width 0.0889)
		(layer "In13.Cu")
		(net "P5E_CPU1_PE2_RX_DP<8>")
	)
	(segment
		(start 143.687292 -398.47266)
		(end 156.579824 -360.04246)
		(width 0.14732)
		(layer "In13.Cu")
		(net "P5E_CPU1_PE2_RX_DP<8>")
	)
	(segment
		(start 149.236938 -249.976386)
		(end 146.03095 -229.551484)
		(width 0.14732)
		(layer "In13.Cu")
		(net "P5E_CPU1_PE2_RX_DP<8>")
	)
	(segment
		(start 129.633472 -213.279736)
		(end 129.591562 -213.321646)
		(width 0.0889)
		(layer "In13.Cu")
		(net "P5E_CPU1_PE2_RX_DP<8>")
	)
	(segment
		(start 128.839214 -219.01658)
		(end 128.842008 -219.018104)
		(width 0.0889)
		(layer "In13.Cu")
		(net "P5E_CPU1_PE2_RX_DP<8>")
	)
	(segment
		(start 139.750038 -435.489858)
		(end 139.750038 -435.14137)
		(width 0.14732)
		(layer "In13.Cu")
		(net "P5E_CPU1_PE2_RX_DP<8>")
	)
	(segment
		(start 128.83769 -218.36888)
		(end 128.836166 -218.369642)
		(width 0.0889)
		(layer "In13.Cu")
		(net "P5E_CPU1_PE2_RX_DP<8>")
	)
	(segment
		(start 145.616676 -227.39985)
		(end 145.409666 -226.32416)
		(width 0.14732)
		(layer "In13.Cu")
		(net "P5E_CPU1_PE2_RX_DP<8>")
	)
	(segment
		(start 128.841246 -218.366594)
		(end 128.839214 -218.367864)
		(width 0.0889)
		(layer "In13.Cu")
		(net "P5E_CPU1_PE2_RX_DP<8>")
	)
	(segment
		(start 139.337796 -213.13267)
		(end 139.19454 -213.228428)
		(width 0.14732)
		(layer "In13.Cu")
		(net "P5E_CPU1_PE2_RX_DP<8>")
	)
	(segment
		(start 128.830578 -217.383614)
		(end 128.839468 -217.388694)
		(width 0.0889)
		(layer "In13.Cu")
		(net "P5E_CPU1_PE2_RX_DP<8>")
	)
	(segment
		(start 142.277338 -215.347804)
		(end 140.241274 -213.312248)
		(width 0.14732)
		(layer "In13.Cu")
		(net "P5E_CPU1_PE2_RX_DP<8>")
	)
	(segment
		(start 129.591562 -213.321646)
		(end 129.591562 -213.8934)
		(width 0.0889)
		(layer "In13.Cu")
		(net "P5E_CPU1_PE2_RX_DP<8>")
	)
	(segment
		(start 129.779014 -215.112346)
		(end 129.770124 -215.117426)
		(width 0.0889)
		(layer "In13.Cu")
		(net "P5E_CPU1_PE2_RX_DP<8>")
	)
	(segment
		(start 128.652016 -220.319854)
		(end 128.652016 -220.334078)
		(width 0.0889)
		(layer "In13.Cu")
		(net "P5E_CPU1_PE2_RX_DP<8>")
	)
	(segment
		(start 138.792204 -424.07713)
		(end 141.706854 -410.757624)
		(width 0.14732)
		(layer "In13.Cu")
		(net "P5E_CPU1_PE2_RX_DP<8>")
	)
	(segment
		(start 145.07972 -309.309008)
		(end 149.345904 -253.2126)
		(width 0.14732)
		(layer "In13.Cu")
		(net "P5E_CPU1_PE2_RX_DP<8>")
	)
	(segment
		(start 128.836166 -216.74201)
		(end 128.830578 -216.745058)
		(width 0.0889)
		(layer "In13.Cu")
		(net "P5E_CPU1_PE2_RX_DP<8>")
	)
	(segment
		(start 129.121916 -216.25052)
		(end 129.121916 -216.260426)
		(width 0.0889)
		(layer "In13.Cu")
		(net "P5E_CPU1_PE2_RX_DP<8>")
	)
	(segment
		(start 149.345904 -253.2126)
		(end 149.236938 -249.976386)
		(width 0.14732)
		(layer "In13.Cu")
		(net "P5E_CPU1_PE2_RX_DP<8>")
	)
	(segment
		(start 130.862324 -212.218778)
		(end 130.862324 -212.219032)
		(width 0.14732)
		(layer "In13.Cu")
		(net "P5E_CPU1_PE2_RX_DP<8>")
	)
	(segment
		(start 128.400302 -220.862906)
		(end 128.556766 -221.133924)
		(width 0.0889)
		(layer "In13.Cu")
		(net "P5E_CPU1_PE2_RX_DP<8>")
	)
	(segment
		(start 145.409666 -226.32416)
		(end 145.409666 -226.323906)
		(width 0.14732)
		(layer "In13.Cu")
		(net "P5E_CPU1_PE2_RX_DP<8>")
	)
	(segment
		(start 143.423894 -404.50516)
		(end 143.423894 -400.233642)
		(width 0.14732)
		(layer "In13.Cu")
		(net "P5E_CPU1_PE2_RX_DP<8>")
	)
	(segment
		(start 128.839214 -218.367864)
		(end 128.83769 -218.36888)
		(width 0.0889)
		(layer "In13.Cu")
		(net "P5E_CPU1_PE2_RX_DP<8>")
	)
	(segment
		(start 141.706854 -410.757624)
		(end 141.706854 -406.2222)
		(width 0.14732)
		(layer "In13.Cu")
		(net "P5E_CPU1_PE2_RX_DP<8>")
	)
	(segment
		(start 138.792204 -434.687472)
		(end 138.792204 -424.07713)
		(width 0.14732)
		(layer "In13.Cu")
		(net "P5E_CPU1_PE2_RX_DP<8>")
	)
	(segment
		(start 129.121916 -219.506038)
		(end 129.121916 -219.515944)
		(width 0.0889)
		(layer "In13.Cu")
		(net "P5E_CPU1_PE2_RX_DP<8>")
	)
	(segment
		(start 139.750038 -435.14137)
		(end 139.602464 -434.993796)
		(width 0.14732)
		(layer "In13.Cu")
		(net "P5E_CPU1_PE2_RX_DP<8>")
	)
	(segment
		(start 146.03095 -229.551484)
		(end 145.616676 -227.400104)
		(width 0.14732)
		(layer "In13.Cu")
		(net "P5E_CPU1_PE2_RX_DP<8>")
	)
	(segment
		(start 141.706854 -406.2222)
		(end 143.423894 -404.50516)
		(width 0.14732)
		(layer "In13.Cu")
		(net "P5E_CPU1_PE2_RX_DP<8>")
	)
	(segment
		(start 128.83769 -219.015818)
		(end 128.839214 -219.01658)
		(width 0.0889)
		(layer "In13.Cu")
		(net "P5E_CPU1_PE2_RX_DP<8>")
	)
	(segment
		(start 139.602464 -434.993796)
		(end 139.098528 -434.993796)
		(width 0.14732)
		(layer "In13.Cu")
		(net "P5E_CPU1_PE2_RX_DP<8>")
	)
	(segment
		(start 130.15087 -212.513418)
		(end 129.633472 -213.030816)
		(width 0.14732)
		(layer "In13.Cu")
		(net "P5E_CPU1_PE2_RX_DP<8>")
	)
	(segment
		(start 128.839468 -219.995496)
		(end 128.838706 -219.996004)
		(width 0.0889)
		(layer "In13.Cu")
		(net "P5E_CPU1_PE2_RX_DP<8>")
	)
	(segment
		(start 128.424432 -220.773752)
		(end 128.400302 -220.862906)
		(width 0.0889)
		(layer "In13.Cu")
		(net "P5E_CPU1_PE2_RX_DP<8>")
	)
	(segment
		(start 155.198572 -332.298294)
		(end 148.76018 -324.803008)
		(width 0.14732)
		(layer "In13.Cu")
		(net "P5E_CPU1_PE2_RX_DP<8>")
	)
	(segment
		(start 129.591562 -215.436704)
		(end 129.591562 -215.452198)
		(width 0.0889)
		(layer "In13.Cu")
		(net "P5E_CPU1_PE2_RX_DP<8>")
	)
	(segment
		(start 157.65145 -346.202254)
		(end 155.198572 -332.298294)
		(width 0.14732)
		(layer "In13.Cu")
		(net "P5E_CPU1_PE2_RX_DP<8>")
	)
	(segment
		(start 129.633472 -213.030816)
		(end 129.633472 -213.257638)
		(width 0.14732)
		(layer "In13.Cu")
		(net "P5E_CPU1_PE2_RX_DP<8>")
	)
	(segment
		(start 156.579824 -360.04246)
		(end 157.65145 -346.202254)
		(width 0.14732)
		(layer "In13.Cu")
		(net "P5E_CPU1_PE2_RX_DP<8>")
	)
	(segment
		(start 145.616676 -227.400104)
		(end 145.616676 -227.39985)
		(width 0.14732)
		(layer "In13.Cu")
		(net "P5E_CPU1_PE2_RX_DP<8>")
	)
	(segment
		(start 143.423894 -400.233642)
		(end 143.687292 -398.47266)
		(width 0.14732)
		(layer "In13.Cu")
		(net "P5E_CPU1_PE2_RX_DP<8>")
	)
	(segment
		(start 128.84277 -218.365832)
		(end 128.841246 -218.366594)
		(width 0.0889)
		(layer "In13.Cu")
		(net "P5E_CPU1_PE2_RX_DP<8>")
	)
	(segment
		(start 145.202656 -225.248724)
		(end 142.277338 -215.347804)
		(width 0.14732)
		(layer "In13.Cu")
		(net "P5E_CPU1_PE2_RX_DP<8>")
	)
	(segment
		(start 128.84531 -218.364308)
		(end 128.84277 -218.365832)
		(width 0.0889)
		(layer "In13.Cu")
		(net "P5E_CPU1_PE2_RX_DP<8>")
	)
	(segment
		(start 148.76018 -324.803008)
		(end 145.07972 -309.309008)
		(width 0.14732)
		(layer "In13.Cu")
		(net "P5E_CPU1_PE2_RX_DP<8>")
	)
	(segment
		(start 128.836166 -218.369642)
		(end 128.830324 -218.372944)
		(width 0.0889)
		(layer "In13.Cu")
		(net "P5E_CPU1_PE2_RX_DP<8>")
	)
	(segment
		(start 138.67003 -212.999574)
		(end 133.261862 -211.923884)
		(width 0.14732)
		(layer "In13.Cu")
		(net "P5E_CPU1_PE2_RX_DP<8>")
	)
	(segment
		(start 128.836166 -219.997528)
		(end 128.830578 -220.000576)
		(width 0.0889)
		(layer "In13.Cu")
		(net "P5E_CPU1_PE2_RX_DP<8>")
	)
	(segment
		(start 129.309368 -215.926162)
		(end 129.300478 -215.931242)
		(width 0.0889)
		(layer "In13.Cu")
		(net "P5E_CPU1_PE2_RX_DP<8>")
	)
	(segment
		(start 139.098528 -434.993796)
		(end 138.792204 -434.687472)
		(width 0.14732)
		(layer "In13.Cu")
		(net "P5E_CPU1_PE2_RX_DP<8>")
	)
	(segment
		(start 128.838706 -219.996004)
		(end 128.836166 -219.997528)
		(width 0.0889)
		(layer "In13.Cu")
		(net "P5E_CPU1_PE2_RX_DP<8>")
	)
	(segment
		(start 139.19454 -213.228428)
		(end 138.765788 -213.143084)
		(width 0.14732)
		(layer "In13.Cu")
		(net "P5E_CPU1_PE2_RX_DP<8>")
	)
	(segment
		(start 129.633472 -213.257638)
		(end 129.633472 -213.279736)
		(width 0.0889)
		(layer "In13.Cu")
		(net "P5E_CPU1_PE2_RX_DP<8>")
	)
	(segment
		(start 140.241274 -213.312248)
		(end 139.337796 -213.13267)
		(width 0.14732)
		(layer "In13.Cu")
		(net "P5E_CPU1_PE2_RX_DP<8>")
	)
	(segment
		(start 133.261862 -211.923884)
		(end 131.574286 -211.923884)
		(width 0.14732)
		(layer "In13.Cu")
		(net "P5E_CPU1_PE2_RX_DP<8>")
	)
	(segment
		(start 128.830324 -219.0115)
		(end 128.83769 -219.015818)
		(width 0.0889)
		(layer "In13.Cu")
		(net "P5E_CPU1_PE2_RX_DP<8>")
	)
	(segment
		(start 130.061208 -214.424768)
		(end 130.061208 -214.644732)
		(width 0.0889)
		(layer "In13.Cu")
		(net "P5E_CPU1_PE2_RX_DP<8>")
	)
	(segment
		(start 145.409666 -226.323906)
		(end 145.202656 -225.248724)
		(width 0.14732)
		(layer "In13.Cu")
		(net "P5E_CPU1_PE2_RX_DP<8>")
	)
	(segment
		(start 130.862324 -212.219032)
		(end 130.15087 -212.513418)
		(width 0.14732)
		(layer "In13.Cu")
		(net "P5E_CPU1_PE2_RX_DP<8>")
	)
	(arc
		(start 128.652016 -217.064336)
		(mid 128.699695 -217.247236)
		(end 128.830578 -217.383614)
		(width 0.0889)
		(layer "In13.Cu")
		(net "P5E_CPU1_PE2_RX_DP<8>")
	)
	(arc
		(start 128.652016 -220.334078)
		(mid 128.593655 -220.570676)
		(end 128.441196 -220.760798)
		(width 0.0889)
		(layer "In13.Cu")
		(net "P5E_CPU1_PE2_RX_DP<8>")
	)
	(arc
		(start 129.121916 -219.515944)
		(mid 129.043805 -219.792893)
		(end 128.839468 -219.995496)
		(width 0.0889)
		(layer "In13.Cu")
		(net "P5E_CPU1_PE2_RX_DP<8>")
	)
	(arc
		(start 128.839468 -217.388694)
		(mid 129.041754 -217.587675)
		(end 129.121916 -217.859864)
		(width 0.0889)
		(layer "In13.Cu")
		(net "P5E_CPU1_PE2_RX_DP<8>")
	)
	(arc
		(start 128.830578 -220.000576)
		(mid 128.699664 -220.136936)
		(end 128.652016 -220.319854)
		(width 0.0889)
		(layer "In13.Cu")
		(net "P5E_CPU1_PE2_RX_DP<8>")
	)
	(arc
		(start 128.830324 -218.372944)
		(mid 128.651727 -218.692222)
		(end 128.830324 -219.0115)
		(width 0.0889)
		(layer "In13.Cu")
		(net "P5E_CPU1_PE2_RX_DP<8>")
	)
	(arc
		(start 129.121916 -217.878406)
		(mid 129.047925 -218.157972)
		(end 128.84531 -218.364308)
		(width 0.0889)
		(layer "In13.Cu")
		(net "P5E_CPU1_PE2_RX_DP<8>")
	)
	(arc
		(start 129.121916 -216.260426)
		(mid 129.043805 -216.537375)
		(end 128.839468 -216.739978)
		(width 0.0889)
		(layer "In13.Cu")
		(net "P5E_CPU1_PE2_RX_DP<8>")
	)
	(arc
		(start 128.441196 -220.760798)
		(mid 128.432874 -220.767353)
		(end 128.424432 -220.773752)
		(width 0.0889)
		(layer "In13.Cu")
		(net "P5E_CPU1_PE2_RX_DP<8>")
	)
	(arc
		(start 128.84531 -219.020136)
		(mid 129.047897 -219.226487)
		(end 129.121916 -219.506038)
		(width 0.0889)
		(layer "In13.Cu")
		(net "P5E_CPU1_PE2_RX_DP<8>")
	)
	(arc
		(start 129.591816 -215.421972)
		(mid 129.591619 -215.429337)
		(end 129.591562 -215.436704)
		(width 0.0889)
		(layer "In13.Cu")
		(net "P5E_CPU1_PE2_RX_DP<8>")
	)
	(arc
		(start 129.770124 -215.117426)
		(mid 129.64287 -215.247392)
		(end 129.591816 -215.421972)
		(width 0.0889)
		(layer "In13.Cu")
		(net "P5E_CPU1_PE2_RX_DP<8>")
	)
	(arc
		(start 129.591816 -213.893908)
		(mid 129.666821 -214.009367)
		(end 129.775966 -214.093298)
		(width 0.0889)
		(layer "In13.Cu")
		(net "P5E_CPU1_PE2_RX_DP<8>")
	)
	(arc
		(start 129.775966 -214.093298)
		(mid 129.949929 -214.232062)
		(end 130.061208 -214.424768)
		(width 0.0889)
		(layer "In13.Cu")
		(net "P5E_CPU1_PE2_RX_DP<8>")
	)
	(arc
		(start 129.300478 -215.931242)
		(mid 129.169564 -216.067602)
		(end 129.121916 -216.25052)
		(width 0.0889)
		(layer "In13.Cu")
		(net "P5E_CPU1_PE2_RX_DP<8>")
	)
	(arc
		(start 129.591562 -215.452198)
		(mid 129.512192 -215.725932)
		(end 129.309368 -215.926162)
		(width 0.0889)
		(layer "In13.Cu")
		(net "P5E_CPU1_PE2_RX_DP<8>")
	)
	(arc
		(start 128.830578 -216.745058)
		(mid 128.699664 -216.881418)
		(end 128.652016 -217.064336)
		(width 0.0889)
		(layer "In13.Cu")
		(net "P5E_CPU1_PE2_RX_DP<8>")
	)
	(arc
		(start 130.061208 -214.644732)
		(mid 129.980297 -214.91486)
		(end 129.779014 -215.112346)
		(width 0.0889)
		(layer "In13.Cu")
		(net "P5E_CPU1_PE2_RX_DP<8>")
	)
	(segment
		(start 127.147066 -222.48368)
		(end 127.147066 -221.947994)
		(width 0.13208)
		(layer "F.Cu")
		(net "P5E_CPU1_PE2_RX_DP<7>")
	)
	(segment
		(start 127.147066 -221.947994)
		(end 127.146812 -221.94774)
		(width 0.13208)
		(layer "F.Cu")
		(net "P5E_CPU1_PE2_RX_DP<7>")
	)
	(segment
		(start 146.37512 -225.806508)
		(end 143.15567 -214.761318)
		(width 0.14732)
		(layer "In13.Cu")
		(net "P5E_CPU1_PE2_RX_DP<7>")
	)
	(segment
		(start 158.633668 -345.900756)
		(end 156.182314 -332.007718)
		(width 0.14732)
		(layer "In13.Cu")
		(net "P5E_CPU1_PE2_RX_DP<7>")
	)
	(segment
		(start 127.900176 -219.994988)
		(end 127.899414 -219.995496)
		(width 0.0889)
		(layer "In13.Cu")
		(net "P5E_CPU1_PE2_RX_DP<7>")
	)
	(segment
		(start 131.388612 -210.994244)
		(end 130.506216 -211.35975)
		(width 0.14732)
		(layer "In13.Cu")
		(net "P5E_CPU1_PE2_RX_DP<7>")
	)
	(segment
		(start 127.89789 -218.368626)
		(end 127.890524 -218.372944)
		(width 0.0889)
		(layer "In13.Cu")
		(net "P5E_CPU1_PE2_RX_DP<7>")
	)
	(segment
		(start 127.39243 -221.652846)
		(end 127.303276 -221.676722)
		(width 0.0889)
		(layer "In13.Cu")
		(net "P5E_CPU1_PE2_RX_DP<7>")
	)
	(segment
		(start 150.278338 -253.24562)
		(end 150.143464 -249.23877)
		(width 0.14732)
		(layer "In13.Cu")
		(net "P5E_CPU1_PE2_RX_DP<7>")
	)
	(segment
		(start 150.278338 -253.245874)
		(end 150.278338 -253.24562)
		(width 0.14732)
		(layer "In13.Cu")
		(net "P5E_CPU1_PE2_RX_DP<7>")
	)
	(segment
		(start 130.506216 -211.35975)
		(end 130.50647 -211.35975)
		(width 0.14732)
		(layer "In13.Cu")
		(net "P5E_CPU1_PE2_RX_DP<7>")
	)
	(segment
		(start 128.693672 -213.257638)
		(end 128.693672 -213.279736)
		(width 0.0889)
		(layer "In13.Cu")
		(net "P5E_CPU1_PE2_RX_DP<7>")
	)
	(segment
		(start 149.60854 -324.343268)
		(end 146.04238 -309.215028)
		(width 0.14732)
		(layer "In13.Cu")
		(net "P5E_CPU1_PE2_RX_DP<7>")
	)
	(segment
		(start 146.04238 -309.215028)
		(end 150.278338 -253.245874)
		(width 0.14732)
		(layer "In13.Cu")
		(net "P5E_CPU1_PE2_RX_DP<7>")
	)
	(segment
		(start 127.90551 -218.364308)
		(end 127.900176 -218.367356)
		(width 0.0889)
		(layer "In13.Cu")
		(net "P5E_CPU1_PE2_RX_DP<7>")
	)
	(segment
		(start 141.791944 -433.699666)
		(end 141.791944 -424.428158)
		(width 0.14732)
		(layer "In13.Cu")
		(net "P5E_CPU1_PE2_RX_DP<7>")
	)
	(segment
		(start 143.080232 -418.321236)
		(end 144.770094 -410.308044)
		(width 0.14732)
		(layer "In13.Cu")
		(net "P5E_CPU1_PE2_RX_DP<7>")
	)
	(segment
		(start 156.182314 -332.007718)
		(end 149.60854 -324.343268)
		(width 0.14732)
		(layer "In13.Cu")
		(net "P5E_CPU1_PE2_RX_DP<7>")
	)
	(segment
		(start 129.121408 -214.424768)
		(end 129.121408 -214.644732)
		(width 0.0889)
		(layer "In13.Cu")
		(net "P5E_CPU1_PE2_RX_DP<7>")
	)
	(segment
		(start 150.143464 -249.23877)
		(end 148.259292 -237.522512)
		(width 0.14732)
		(layer "In13.Cu")
		(net "P5E_CPU1_PE2_RX_DP<7>")
	)
	(segment
		(start 143.079978 -418.321236)
		(end 143.080232 -418.321236)
		(width 0.14732)
		(layer "In13.Cu")
		(net "P5E_CPU1_PE2_RX_DP<7>")
	)
	(segment
		(start 127.899414 -219.01658)
		(end 127.90551 -219.020136)
		(width 0.0889)
		(layer "In13.Cu")
		(net "P5E_CPU1_PE2_RX_DP<7>")
	)
	(segment
		(start 127.712216 -217.0557)
		(end 127.712216 -217.072972)
		(width 0.0889)
		(layer "In13.Cu")
		(net "P5E_CPU1_PE2_RX_DP<7>")
	)
	(segment
		(start 127.890524 -219.0115)
		(end 127.899414 -219.01658)
		(width 0.0889)
		(layer "In13.Cu")
		(net "P5E_CPU1_PE2_RX_DP<7>")
	)
	(segment
		(start 127.303276 -221.676722)
		(end 127.146812 -221.94774)
		(width 0.0889)
		(layer "In13.Cu")
		(net "P5E_CPU1_PE2_RX_DP<7>")
	)
	(segment
		(start 128.83007 -212.51926)
		(end 128.693672 -212.848698)
		(width 0.14732)
		(layer "In13.Cu")
		(net "P5E_CPU1_PE2_RX_DP<7>")
	)
	(segment
		(start 128.368552 -215.92667)
		(end 128.360678 -215.931242)
		(width 0.0889)
		(layer "In13.Cu")
		(net "P5E_CPU1_PE2_RX_DP<7>")
	)
	(segment
		(start 127.712216 -220.311218)
		(end 127.712216 -220.32849)
		(width 0.0889)
		(layer "In13.Cu")
		(net "P5E_CPU1_PE2_RX_DP<7>")
	)
	(segment
		(start 128.693672 -212.848698)
		(end 128.693672 -213.257638)
		(width 0.14732)
		(layer "In13.Cu")
		(net "P5E_CPU1_PE2_RX_DP<7>")
	)
	(segment
		(start 128.182116 -221.1197)
		(end 128.182116 -221.133924)
		(width 0.0889)
		(layer "In13.Cu")
		(net "P5E_CPU1_PE2_RX_DP<7>")
	)
	(segment
		(start 128.651762 -213.321646)
		(end 128.651762 -213.8934)
		(width 0.0889)
		(layer "In13.Cu")
		(net "P5E_CPU1_PE2_RX_DP<7>")
	)
	(segment
		(start 143.15567 -214.761318)
		(end 140.886942 -212.49259)
		(width 0.14732)
		(layer "In13.Cu")
		(net "P5E_CPU1_PE2_RX_DP<7>")
	)
	(segment
		(start 129.624328 -211.725002)
		(end 128.83007 -212.51926)
		(width 0.14732)
		(layer "In13.Cu")
		(net "P5E_CPU1_PE2_RX_DP<7>")
	)
	(segment
		(start 130.50647 -211.35975)
		(end 129.624328 -211.725002)
		(width 0.14732)
		(layer "In13.Cu")
		(net "P5E_CPU1_PE2_RX_DP<7>")
	)
	(segment
		(start 127.899414 -218.367864)
		(end 127.89789 -218.368626)
		(width 0.0889)
		(layer "In13.Cu")
		(net "P5E_CPU1_PE2_RX_DP<7>")
	)
	(segment
		(start 128.693672 -213.279736)
		(end 128.651762 -213.321646)
		(width 0.0889)
		(layer "In13.Cu")
		(net "P5E_CPU1_PE2_RX_DP<7>")
	)
	(segment
		(start 140.886942 -212.49259)
		(end 133.354064 -210.994244)
		(width 0.14732)
		(layer "In13.Cu")
		(net "P5E_CPU1_PE2_RX_DP<7>")
	)
	(segment
		(start 142.750032 -434.141372)
		(end 142.602458 -433.993798)
		(width 0.14732)
		(layer "In13.Cu")
		(net "P5E_CPU1_PE2_RX_DP<7>")
	)
	(segment
		(start 127.900176 -216.73947)
		(end 127.899414 -216.739978)
		(width 0.0889)
		(layer "In13.Cu")
		(net "P5E_CPU1_PE2_RX_DP<7>")
	)
	(segment
		(start 127.90551 -219.99194)
		(end 127.900176 -219.994988)
		(width 0.0889)
		(layer "In13.Cu")
		(net "P5E_CPU1_PE2_RX_DP<7>")
	)
	(segment
		(start 128.839214 -215.112346)
		(end 128.830324 -215.117426)
		(width 0.0889)
		(layer "In13.Cu")
		(net "P5E_CPU1_PE2_RX_DP<7>")
	)
	(segment
		(start 128.651762 -215.436704)
		(end 128.651762 -215.452198)
		(width 0.0889)
		(layer "In13.Cu")
		(net "P5E_CPU1_PE2_RX_DP<7>")
	)
	(segment
		(start 128.651762 -213.8934)
		(end 128.652016 -213.893908)
		(width 0.0889)
		(layer "In13.Cu")
		(net "P5E_CPU1_PE2_RX_DP<7>")
	)
	(segment
		(start 142.086076 -433.993798)
		(end 141.791944 -433.699666)
		(width 0.14732)
		(layer "In13.Cu")
		(net "P5E_CPU1_PE2_RX_DP<7>")
	)
	(segment
		(start 144.770094 -406.2222)
		(end 146.487134 -404.50516)
		(width 0.14732)
		(layer "In13.Cu")
		(net "P5E_CPU1_PE2_RX_DP<7>")
	)
	(segment
		(start 148.259038 -237.522258)
		(end 146.37512 -225.806508)
		(width 0.14732)
		(layer "In13.Cu")
		(net "P5E_CPU1_PE2_RX_DP<7>")
	)
	(segment
		(start 133.354064 -210.994244)
		(end 131.388612 -210.994244)
		(width 0.14732)
		(layer "In13.Cu")
		(net "P5E_CPU1_PE2_RX_DP<7>")
	)
	(segment
		(start 146.769582 -398.21739)
		(end 157.567884 -360.221276)
		(width 0.14732)
		(layer "In13.Cu")
		(net "P5E_CPU1_PE2_RX_DP<7>")
	)
	(segment
		(start 128.182116 -217.864182)
		(end 128.182116 -217.878406)
		(width 0.0889)
		(layer "In13.Cu")
		(net "P5E_CPU1_PE2_RX_DP<7>")
	)
	(segment
		(start 142.602458 -433.993798)
		(end 142.086076 -433.993798)
		(width 0.14732)
		(layer "In13.Cu")
		(net "P5E_CPU1_PE2_RX_DP<7>")
	)
	(segment
		(start 144.770094 -410.308044)
		(end 144.770094 -406.2222)
		(width 0.14732)
		(layer "In13.Cu")
		(net "P5E_CPU1_PE2_RX_DP<7>")
	)
	(segment
		(start 146.487134 -400.359118)
		(end 146.769582 -398.21739)
		(width 0.14732)
		(layer "In13.Cu")
		(net "P5E_CPU1_PE2_RX_DP<7>")
	)
	(segment
		(start 127.90551 -221.619826)
		(end 127.884682 -221.632018)
		(width 0.0889)
		(layer "In13.Cu")
		(net "P5E_CPU1_PE2_RX_DP<7>")
	)
	(segment
		(start 141.791944 -424.428158)
		(end 143.079978 -418.321236)
		(width 0.14732)
		(layer "In13.Cu")
		(net "P5E_CPU1_PE2_RX_DP<7>")
	)
	(segment
		(start 127.900176 -218.367356)
		(end 127.899414 -218.367864)
		(width 0.0889)
		(layer "In13.Cu")
		(net "P5E_CPU1_PE2_RX_DP<7>")
	)
	(segment
		(start 146.487134 -404.50516)
		(end 146.487134 -400.359118)
		(width 0.14732)
		(layer "In13.Cu")
		(net "P5E_CPU1_PE2_RX_DP<7>")
	)
	(segment
		(start 142.750032 -434.48986)
		(end 142.750032 -434.141372)
		(width 0.14732)
		(layer "In13.Cu")
		(net "P5E_CPU1_PE2_RX_DP<7>")
	)
	(segment
		(start 157.567884 -360.221276)
		(end 158.633668 -345.900756)
		(width 0.14732)
		(layer "In13.Cu")
		(net "P5E_CPU1_PE2_RX_DP<7>")
	)
	(segment
		(start 127.90551 -216.736422)
		(end 127.900176 -216.73947)
		(width 0.0889)
		(layer "In13.Cu")
		(net "P5E_CPU1_PE2_RX_DP<7>")
	)
	(segment
		(start 128.369568 -215.926162)
		(end 128.368552 -215.92667)
		(width 0.0889)
		(layer "In13.Cu")
		(net "P5E_CPU1_PE2_RX_DP<7>")
	)
	(segment
		(start 148.259292 -237.522512)
		(end 148.259038 -237.522258)
		(width 0.14732)
		(layer "In13.Cu")
		(net "P5E_CPU1_PE2_RX_DP<7>")
	)
	(arc
		(start 128.651762 -215.452198)
		(mid 128.572392 -215.725932)
		(end 128.369568 -215.926162)
		(width 0.0889)
		(layer "In13.Cu")
		(net "P5E_CPU1_PE2_RX_DP<7>")
	)
	(arc
		(start 127.890524 -218.372944)
		(mid 127.711927 -218.692222)
		(end 127.890524 -219.0115)
		(width 0.0889)
		(layer "In13.Cu")
		(net "P5E_CPU1_PE2_RX_DP<7>")
	)
	(arc
		(start 127.90551 -219.020136)
		(mid 128.182084 -219.506038)
		(end 127.90551 -219.99194)
		(width 0.0889)
		(layer "In13.Cu")
		(net "P5E_CPU1_PE2_RX_DP<7>")
	)
	(arc
		(start 128.182116 -216.25052)
		(mid 128.108125 -216.530086)
		(end 127.90551 -216.736422)
		(width 0.0889)
		(layer "In13.Cu")
		(net "P5E_CPU1_PE2_RX_DP<7>")
	)
	(arc
		(start 128.836166 -214.093298)
		(mid 129.010129 -214.232062)
		(end 129.121408 -214.424768)
		(width 0.0889)
		(layer "In13.Cu")
		(net "P5E_CPU1_PE2_RX_DP<7>")
	)
	(arc
		(start 128.652016 -215.421972)
		(mid 128.651819 -215.429337)
		(end 128.651762 -215.436704)
		(width 0.0889)
		(layer "In13.Cu")
		(net "P5E_CPU1_PE2_RX_DP<7>")
	)
	(arc
		(start 127.899414 -217.388694)
		(mid 128.102895 -217.589498)
		(end 128.182116 -217.864182)
		(width 0.0889)
		(layer "In13.Cu")
		(net "P5E_CPU1_PE2_RX_DP<7>")
	)
	(arc
		(start 128.360678 -215.931242)
		(mid 128.229764 -216.067602)
		(end 128.182116 -216.25052)
		(width 0.0889)
		(layer "In13.Cu")
		(net "P5E_CPU1_PE2_RX_DP<7>")
	)
	(arc
		(start 127.899414 -216.739978)
		(mid 127.764481 -216.873332)
		(end 127.712216 -217.0557)
		(width 0.0889)
		(layer "In13.Cu")
		(net "P5E_CPU1_PE2_RX_DP<7>")
	)
	(arc
		(start 127.412496 -221.660974)
		(mid 127.402425 -221.657005)
		(end 127.39243 -221.652846)
		(width 0.0889)
		(layer "In13.Cu")
		(net "P5E_CPU1_PE2_RX_DP<7>")
	)
	(arc
		(start 127.884682 -221.632018)
		(mid 127.651767 -221.698229)
		(end 127.412496 -221.660974)
		(width 0.0889)
		(layer "In13.Cu")
		(net "P5E_CPU1_PE2_RX_DP<7>")
	)
	(arc
		(start 128.652016 -213.893908)
		(mid 128.727021 -214.009367)
		(end 128.836166 -214.093298)
		(width 0.0889)
		(layer "In13.Cu")
		(net "P5E_CPU1_PE2_RX_DP<7>")
	)
	(arc
		(start 128.182116 -217.878406)
		(mid 128.108125 -218.157972)
		(end 127.90551 -218.364308)
		(width 0.0889)
		(layer "In13.Cu")
		(net "P5E_CPU1_PE2_RX_DP<7>")
	)
	(arc
		(start 127.899414 -220.644212)
		(mid 128.102895 -220.845016)
		(end 128.182116 -221.1197)
		(width 0.0889)
		(layer "In13.Cu")
		(net "P5E_CPU1_PE2_RX_DP<7>")
	)
	(arc
		(start 127.899414 -219.995496)
		(mid 127.764481 -220.12885)
		(end 127.712216 -220.311218)
		(width 0.0889)
		(layer "In13.Cu")
		(net "P5E_CPU1_PE2_RX_DP<7>")
	)
	(arc
		(start 127.712216 -220.32849)
		(mid 127.764486 -220.510855)
		(end 127.899414 -220.644212)
		(width 0.0889)
		(layer "In13.Cu")
		(net "P5E_CPU1_PE2_RX_DP<7>")
	)
	(arc
		(start 127.712216 -217.072972)
		(mid 127.764486 -217.255337)
		(end 127.899414 -217.388694)
		(width 0.0889)
		(layer "In13.Cu")
		(net "P5E_CPU1_PE2_RX_DP<7>")
	)
	(arc
		(start 129.121408 -214.644732)
		(mid 129.040497 -214.91486)
		(end 128.839214 -215.112346)
		(width 0.0889)
		(layer "In13.Cu")
		(net "P5E_CPU1_PE2_RX_DP<7>")
	)
	(arc
		(start 128.830324 -215.117426)
		(mid 128.70307 -215.247392)
		(end 128.652016 -215.421972)
		(width 0.0889)
		(layer "In13.Cu")
		(net "P5E_CPU1_PE2_RX_DP<7>")
	)
	(arc
		(start 128.182116 -221.133924)
		(mid 128.108125 -221.41349)
		(end 127.90551 -221.619826)
		(width 0.0889)
		(layer "In13.Cu")
		(net "P5E_CPU1_PE2_RX_DP<7>")
	)
	(segment
		(start 126.676912 -221.669864)
		(end 126.676912 -221.134178)
		(width 0.13208)
		(layer "F.Cu")
		(net "P5E_CPU1_PE2_RX_DP<6>")
	)
	(segment
		(start 126.676912 -221.134178)
		(end 126.677166 -221.133924)
		(width 0.13208)
		(layer "F.Cu")
		(net "P5E_CPU1_PE2_RX_DP<6>")
	)
	(segment
		(start 126.772416 -220.319854)
		(end 126.772416 -220.334078)
		(width 0.0889)
		(layer "In13.Cu")
		(net "P5E_CPU1_PE2_RX_DP<6>")
	)
	(segment
		(start 144.018762 -214.250524)
		(end 141.26083 -211.492338)
		(width 0.14732)
		(layer "In13.Cu")
		(net "P5E_CPU1_PE2_RX_DP<6>")
	)
	(segment
		(start 126.950724 -219.0115)
		(end 126.95809 -219.015818)
		(width 0.0889)
		(layer "In13.Cu")
		(net "P5E_CPU1_PE2_RX_DP<6>")
	)
	(segment
		(start 126.520702 -220.862906)
		(end 126.677166 -221.133924)
		(width 0.0889)
		(layer "In13.Cu")
		(net "P5E_CPU1_PE2_RX_DP<6>")
	)
	(segment
		(start 126.965456 -218.364562)
		(end 126.952756 -218.371674)
		(width 0.0889)
		(layer "In13.Cu")
		(net "P5E_CPU1_PE2_RX_DP<6>")
	)
	(segment
		(start 126.956566 -219.997528)
		(end 126.950978 -220.000576)
		(width 0.0889)
		(layer "In13.Cu")
		(net "P5E_CPU1_PE2_RX_DP<6>")
	)
	(segment
		(start 149.550374 -404.50516)
		(end 149.550374 -399.583656)
		(width 0.14732)
		(layer "In13.Cu")
		(net "P5E_CPU1_PE2_RX_DP<6>")
	)
	(segment
		(start 157.058868 -331.560932)
		(end 150.4442 -323.835268)
		(width 0.14732)
		(layer "In13.Cu")
		(net "P5E_CPU1_PE2_RX_DP<6>")
	)
	(segment
		(start 127.753872 -213.279736)
		(end 127.711962 -213.321646)
		(width 0.0889)
		(layer "In13.Cu")
		(net "P5E_CPU1_PE2_RX_DP<6>")
	)
	(segment
		(start 126.952756 -218.371674)
		(end 126.950724 -218.372944)
		(width 0.0889)
		(layer "In13.Cu")
		(net "P5E_CPU1_PE2_RX_DP<6>")
	)
	(segment
		(start 147.833334 -410.319728)
		(end 147.833334 -406.2222)
		(width 0.14732)
		(layer "In13.Cu")
		(net "P5E_CPU1_PE2_RX_DP<6>")
	)
	(segment
		(start 138.958828 -211.15909)
		(end 138.86307 -211.015326)
		(width 0.14732)
		(layer "In13.Cu")
		(net "P5E_CPU1_PE2_RX_DP<6>")
	)
	(segment
		(start 149.81174 -397.345916)
		(end 158.598108 -360.275378)
		(width 0.14732)
		(layer "In13.Cu")
		(net "P5E_CPU1_PE2_RX_DP<6>")
	)
	(segment
		(start 150.4442 -323.835268)
		(end 146.9898 -309.095648)
		(width 0.14732)
		(layer "In13.Cu")
		(net "P5E_CPU1_PE2_RX_DP<6>")
	)
	(segment
		(start 141.26083 -211.492338)
		(end 139.53109 -211.148422)
		(width 0.14732)
		(layer "In13.Cu")
		(net "P5E_CPU1_PE2_RX_DP<6>")
	)
	(segment
		(start 139.38758 -211.24418)
		(end 138.958828 -211.15909)
		(width 0.14732)
		(layer "In13.Cu")
		(net "P5E_CPU1_PE2_RX_DP<6>")
	)
	(segment
		(start 144.602454 -434.993796)
		(end 144.051782 -434.993796)
		(width 0.14732)
		(layer "In13.Cu")
		(net "P5E_CPU1_PE2_RX_DP<6>")
	)
	(segment
		(start 151.224996 -253.339854)
		(end 151.076406 -248.92)
		(width 0.14732)
		(layer "In13.Cu")
		(net "P5E_CPU1_PE2_RX_DP<6>")
	)
	(segment
		(start 143.792194 -434.734208)
		(end 143.792194 -424.095164)
		(width 0.14732)
		(layer "In13.Cu")
		(net "P5E_CPU1_PE2_RX_DP<6>")
	)
	(segment
		(start 144.051782 -434.993796)
		(end 143.792194 -434.734208)
		(width 0.14732)
		(layer "In13.Cu")
		(net "P5E_CPU1_PE2_RX_DP<6>")
	)
	(segment
		(start 126.950978 -217.383614)
		(end 126.959868 -217.388694)
		(width 0.0889)
		(layer "In13.Cu")
		(net "P5E_CPU1_PE2_RX_DP<6>")
	)
	(segment
		(start 138.434826 -210.930236)
		(end 138.291316 -211.025994)
		(width 0.14732)
		(layer "In13.Cu")
		(net "P5E_CPU1_PE2_RX_DP<6>")
	)
	(segment
		(start 144.750028 -435.489858)
		(end 144.750028 -435.14137)
		(width 0.14732)
		(layer "In13.Cu")
		(net "P5E_CPU1_PE2_RX_DP<6>")
	)
	(segment
		(start 127.242316 -219.506038)
		(end 127.242316 -219.515944)
		(width 0.0889)
		(layer "In13.Cu")
		(net "P5E_CPU1_PE2_RX_DP<6>")
	)
	(segment
		(start 158.598108 -360.275378)
		(end 159.63392 -346.160344)
		(width 0.14732)
		(layer "In13.Cu")
		(net "P5E_CPU1_PE2_RX_DP<6>")
	)
	(segment
		(start 159.63392 -346.160344)
		(end 157.058868 -331.560932)
		(width 0.14732)
		(layer "In13.Cu")
		(net "P5E_CPU1_PE2_RX_DP<6>")
	)
	(segment
		(start 147.324826 -225.59264)
		(end 144.018762 -214.250524)
		(width 0.14732)
		(layer "In13.Cu")
		(net "P5E_CPU1_PE2_RX_DP<6>")
	)
	(segment
		(start 128.041908 -211.99221)
		(end 127.753872 -212.687662)
		(width 0.14732)
		(layer "In13.Cu")
		(net "P5E_CPU1_PE2_RX_DP<6>")
	)
	(segment
		(start 127.711962 -213.8934)
		(end 127.712216 -213.893908)
		(width 0.0889)
		(layer "In13.Cu")
		(net "P5E_CPU1_PE2_RX_DP<6>")
	)
	(segment
		(start 137.766806 -210.797648)
		(end 134.082536 -210.064604)
		(width 0.14732)
		(layer "In13.Cu")
		(net "P5E_CPU1_PE2_RX_DP<6>")
	)
	(segment
		(start 126.956566 -216.74201)
		(end 126.950978 -216.745058)
		(width 0.0889)
		(layer "In13.Cu")
		(net "P5E_CPU1_PE2_RX_DP<6>")
	)
	(segment
		(start 126.962408 -219.018104)
		(end 126.96571 -219.020136)
		(width 0.0889)
		(layer "In13.Cu")
		(net "P5E_CPU1_PE2_RX_DP<6>")
	)
	(segment
		(start 146.9898 -309.095648)
		(end 151.224996 -253.340108)
		(width 0.14732)
		(layer "In13.Cu")
		(net "P5E_CPU1_PE2_RX_DP<6>")
	)
	(segment
		(start 139.53109 -211.148422)
		(end 139.38758 -211.24418)
		(width 0.14732)
		(layer "In13.Cu")
		(net "P5E_CPU1_PE2_RX_DP<6>")
	)
	(segment
		(start 143.792194 -424.095164)
		(end 147.833334 -410.319728)
		(width 0.14732)
		(layer "In13.Cu")
		(net "P5E_CPU1_PE2_RX_DP<6>")
	)
	(segment
		(start 126.959106 -219.996004)
		(end 126.956566 -219.997528)
		(width 0.0889)
		(layer "In13.Cu")
		(net "P5E_CPU1_PE2_RX_DP<6>")
	)
	(segment
		(start 126.959868 -219.995496)
		(end 126.959106 -219.996004)
		(width 0.0889)
		(layer "In13.Cu")
		(net "P5E_CPU1_PE2_RX_DP<6>")
	)
	(segment
		(start 134.082536 -210.064604)
		(end 131.203192 -210.064604)
		(width 0.14732)
		(layer "In13.Cu")
		(net "P5E_CPU1_PE2_RX_DP<6>")
	)
	(segment
		(start 127.429768 -215.926162)
		(end 127.420878 -215.931242)
		(width 0.0889)
		(layer "In13.Cu")
		(net "P5E_CPU1_PE2_RX_DP<6>")
	)
	(segment
		(start 126.95809 -219.015818)
		(end 126.959614 -219.01658)
		(width 0.0889)
		(layer "In13.Cu")
		(net "P5E_CPU1_PE2_RX_DP<6>")
	)
	(segment
		(start 137.862564 -210.940904)
		(end 137.766806 -210.79714)
		(width 0.14732)
		(layer "In13.Cu")
		(net "P5E_CPU1_PE2_RX_DP<6>")
	)
	(segment
		(start 126.959868 -216.739978)
		(end 126.959106 -216.740486)
		(width 0.0889)
		(layer "In13.Cu")
		(net "P5E_CPU1_PE2_RX_DP<6>")
	)
	(segment
		(start 127.711962 -215.436704)
		(end 127.711962 -215.452198)
		(width 0.0889)
		(layer "In13.Cu")
		(net "P5E_CPU1_PE2_RX_DP<6>")
	)
	(segment
		(start 127.242316 -216.25052)
		(end 127.242316 -216.260426)
		(width 0.0889)
		(layer "In13.Cu")
		(net "P5E_CPU1_PE2_RX_DP<6>")
	)
	(segment
		(start 149.200362 -237.256066)
		(end 147.324826 -225.59264)
		(width 0.14732)
		(layer "In13.Cu")
		(net "P5E_CPU1_PE2_RX_DP<6>")
	)
	(segment
		(start 138.86307 -211.015326)
		(end 138.434826 -210.930236)
		(width 0.14732)
		(layer "In13.Cu")
		(net "P5E_CPU1_PE2_RX_DP<6>")
	)
	(segment
		(start 127.899414 -215.112346)
		(end 127.890524 -215.117426)
		(width 0.0889)
		(layer "In13.Cu")
		(net "P5E_CPU1_PE2_RX_DP<6>")
	)
	(segment
		(start 127.753872 -212.687662)
		(end 127.753872 -213.257638)
		(width 0.14732)
		(layer "In13.Cu")
		(net "P5E_CPU1_PE2_RX_DP<6>")
	)
	(segment
		(start 128.181608 -214.424768)
		(end 128.181608 -214.644732)
		(width 0.0889)
		(layer "In13.Cu")
		(net "P5E_CPU1_PE2_RX_DP<6>")
	)
	(segment
		(start 138.291316 -211.025994)
		(end 137.862564 -210.940904)
		(width 0.14732)
		(layer "In13.Cu")
		(net "P5E_CPU1_PE2_RX_DP<6>")
	)
	(segment
		(start 149.550374 -399.583656)
		(end 149.81174 -397.345916)
		(width 0.14732)
		(layer "In13.Cu")
		(net "P5E_CPU1_PE2_RX_DP<6>")
	)
	(segment
		(start 127.711962 -213.321646)
		(end 127.711962 -213.8934)
		(width 0.0889)
		(layer "In13.Cu")
		(net "P5E_CPU1_PE2_RX_DP<6>")
	)
	(segment
		(start 151.224996 -253.340108)
		(end 151.224996 -253.339854)
		(width 0.14732)
		(layer "In13.Cu")
		(net "P5E_CPU1_PE2_RX_DP<6>")
	)
	(segment
		(start 144.750028 -435.14137)
		(end 144.602454 -434.993796)
		(width 0.14732)
		(layer "In13.Cu")
		(net "P5E_CPU1_PE2_RX_DP<6>")
	)
	(segment
		(start 147.833334 -406.2222)
		(end 149.550374 -404.50516)
		(width 0.14732)
		(layer "In13.Cu")
		(net "P5E_CPU1_PE2_RX_DP<6>")
	)
	(segment
		(start 149.200616 -237.25632)
		(end 149.200362 -237.256066)
		(width 0.14732)
		(layer "In13.Cu")
		(net "P5E_CPU1_PE2_RX_DP<6>")
	)
	(segment
		(start 126.959614 -219.01658)
		(end 126.962408 -219.018104)
		(width 0.0889)
		(layer "In13.Cu")
		(net "P5E_CPU1_PE2_RX_DP<6>")
	)
	(segment
		(start 127.753872 -213.257638)
		(end 127.753872 -213.279736)
		(width 0.0889)
		(layer "In13.Cu")
		(net "P5E_CPU1_PE2_RX_DP<6>")
	)
	(segment
		(start 129.097278 -210.93684)
		(end 128.041908 -211.99221)
		(width 0.14732)
		(layer "In13.Cu")
		(net "P5E_CPU1_PE2_RX_DP<6>")
	)
	(segment
		(start 126.544832 -220.773752)
		(end 126.520702 -220.862906)
		(width 0.0889)
		(layer "In13.Cu")
		(net "P5E_CPU1_PE2_RX_DP<6>")
	)
	(segment
		(start 127.242316 -217.859864)
		(end 127.242316 -217.878406)
		(width 0.0889)
		(layer "In13.Cu")
		(net "P5E_CPU1_PE2_RX_DP<6>")
	)
	(segment
		(start 151.076406 -248.92)
		(end 149.200616 -237.25632)
		(width 0.14732)
		(layer "In13.Cu")
		(net "P5E_CPU1_PE2_RX_DP<6>")
	)
	(segment
		(start 131.203192 -210.064604)
		(end 129.097278 -210.93684)
		(width 0.14732)
		(layer "In13.Cu")
		(net "P5E_CPU1_PE2_RX_DP<6>")
	)
	(segment
		(start 137.766806 -210.79714)
		(end 137.766806 -210.797648)
		(width 0.14732)
		(layer "In13.Cu")
		(net "P5E_CPU1_PE2_RX_DP<6>")
	)
	(segment
		(start 126.96571 -218.364308)
		(end 126.965456 -218.364562)
		(width 0.0889)
		(layer "In13.Cu")
		(net "P5E_CPU1_PE2_RX_DP<6>")
	)
	(segment
		(start 126.959106 -216.740486)
		(end 126.956566 -216.74201)
		(width 0.0889)
		(layer "In13.Cu")
		(net "P5E_CPU1_PE2_RX_DP<6>")
	)
	(arc
		(start 127.896366 -214.093298)
		(mid 128.070329 -214.232062)
		(end 128.181608 -214.424768)
		(width 0.0889)
		(layer "In13.Cu")
		(net "P5E_CPU1_PE2_RX_DP<6>")
	)
	(arc
		(start 127.242316 -217.878406)
		(mid 127.168325 -218.157972)
		(end 126.96571 -218.364308)
		(width 0.0889)
		(layer "In13.Cu")
		(net "P5E_CPU1_PE2_RX_DP<6>")
	)
	(arc
		(start 127.242316 -216.260426)
		(mid 127.164205 -216.537375)
		(end 126.959868 -216.739978)
		(width 0.0889)
		(layer "In13.Cu")
		(net "P5E_CPU1_PE2_RX_DP<6>")
	)
	(arc
		(start 127.242316 -219.515944)
		(mid 127.164205 -219.792893)
		(end 126.959868 -219.995496)
		(width 0.0889)
		(layer "In13.Cu")
		(net "P5E_CPU1_PE2_RX_DP<6>")
	)
	(arc
		(start 126.950978 -220.000576)
		(mid 126.820064 -220.136936)
		(end 126.772416 -220.319854)
		(width 0.0889)
		(layer "In13.Cu")
		(net "P5E_CPU1_PE2_RX_DP<6>")
	)
	(arc
		(start 126.772416 -220.334078)
		(mid 126.714055 -220.570676)
		(end 126.561596 -220.760798)
		(width 0.0889)
		(layer "In13.Cu")
		(net "P5E_CPU1_PE2_RX_DP<6>")
	)
	(arc
		(start 126.950724 -218.372944)
		(mid 126.772127 -218.692222)
		(end 126.950724 -219.0115)
		(width 0.0889)
		(layer "In13.Cu")
		(net "P5E_CPU1_PE2_RX_DP<6>")
	)
	(arc
		(start 126.96571 -219.020136)
		(mid 127.168297 -219.226487)
		(end 127.242316 -219.506038)
		(width 0.0889)
		(layer "In13.Cu")
		(net "P5E_CPU1_PE2_RX_DP<6>")
	)
	(arc
		(start 127.712216 -213.893908)
		(mid 127.787221 -214.009367)
		(end 127.896366 -214.093298)
		(width 0.0889)
		(layer "In13.Cu")
		(net "P5E_CPU1_PE2_RX_DP<6>")
	)
	(arc
		(start 126.950978 -216.745058)
		(mid 126.820064 -216.881418)
		(end 126.772416 -217.064336)
		(width 0.0889)
		(layer "In13.Cu")
		(net "P5E_CPU1_PE2_RX_DP<6>")
	)
	(arc
		(start 127.890524 -215.117426)
		(mid 127.76327 -215.247392)
		(end 127.712216 -215.421972)
		(width 0.0889)
		(layer "In13.Cu")
		(net "P5E_CPU1_PE2_RX_DP<6>")
	)
	(arc
		(start 127.711962 -215.452198)
		(mid 127.632592 -215.725932)
		(end 127.429768 -215.926162)
		(width 0.0889)
		(layer "In13.Cu")
		(net "P5E_CPU1_PE2_RX_DP<6>")
	)
	(arc
		(start 127.712216 -215.421972)
		(mid 127.712019 -215.429337)
		(end 127.711962 -215.436704)
		(width 0.0889)
		(layer "In13.Cu")
		(net "P5E_CPU1_PE2_RX_DP<6>")
	)
	(arc
		(start 126.561596 -220.760798)
		(mid 126.553274 -220.767353)
		(end 126.544832 -220.773752)
		(width 0.0889)
		(layer "In13.Cu")
		(net "P5E_CPU1_PE2_RX_DP<6>")
	)
	(arc
		(start 126.772416 -217.064336)
		(mid 126.820095 -217.247236)
		(end 126.950978 -217.383614)
		(width 0.0889)
		(layer "In13.Cu")
		(net "P5E_CPU1_PE2_RX_DP<6>")
	)
	(arc
		(start 128.181608 -214.644732)
		(mid 128.100697 -214.91486)
		(end 127.899414 -215.112346)
		(width 0.0889)
		(layer "In13.Cu")
		(net "P5E_CPU1_PE2_RX_DP<6>")
	)
	(arc
		(start 127.420878 -215.931242)
		(mid 127.289964 -216.067602)
		(end 127.242316 -216.25052)
		(width 0.0889)
		(layer "In13.Cu")
		(net "P5E_CPU1_PE2_RX_DP<6>")
	)
	(arc
		(start 126.959868 -217.388694)
		(mid 127.162154 -217.587675)
		(end 127.242316 -217.859864)
		(width 0.0889)
		(layer "In13.Cu")
		(net "P5E_CPU1_PE2_RX_DP<6>")
	)
	(segment
		(start 125.267466 -221.947994)
		(end 125.267212 -221.94774)
		(width 0.13208)
		(layer "F.Cu")
		(net "P5E_CPU1_PE2_RX_DP<5>")
	)
	(segment
		(start 125.267466 -222.48368)
		(end 125.267466 -221.947994)
		(width 0.13208)
		(layer "F.Cu")
		(net "P5E_CPU1_PE2_RX_DP<5>")
	)
	(segment
		(start 145.79219 -433.686458)
		(end 145.79219 -424.347894)
		(width 0.14732)
		(layer "In13.Cu")
		(net "P5E_CPU1_PE2_RX_DP<5>")
	)
	(segment
		(start 126.489968 -215.926162)
		(end 126.481078 -215.931242)
		(width 0.0889)
		(layer "In13.Cu")
		(net "P5E_CPU1_PE2_RX_DP<5>")
	)
	(segment
		(start 146.750024 -434.48986)
		(end 146.750024 -434.141372)
		(width 0.14732)
		(layer "In13.Cu")
		(net "P5E_CPU1_PE2_RX_DP<5>")
	)
	(segment
		(start 146.60245 -433.993798)
		(end 146.09953 -433.993798)
		(width 0.14732)
		(layer "In13.Cu")
		(net "P5E_CPU1_PE2_RX_DP<5>")
	)
	(segment
		(start 126.302516 -217.864182)
		(end 126.302516 -217.878406)
		(width 0.0889)
		(layer "In13.Cu")
		(net "P5E_CPU1_PE2_RX_DP<5>")
	)
	(segment
		(start 134.17804 -209.134964)
		(end 131.017518 -209.134964)
		(width 0.14732)
		(layer "In13.Cu")
		(net "P5E_CPU1_PE2_RX_DP<5>")
	)
	(segment
		(start 126.959614 -215.112346)
		(end 126.950724 -215.117426)
		(width 0.0889)
		(layer "In13.Cu")
		(net "P5E_CPU1_PE2_RX_DP<5>")
	)
	(segment
		(start 126.020576 -219.994988)
		(end 126.019814 -219.995496)
		(width 0.0889)
		(layer "In13.Cu")
		(net "P5E_CPU1_PE2_RX_DP<5>")
	)
	(segment
		(start 147.94484 -308.976268)
		(end 152.1587 -253.406656)
		(width 0.14732)
		(layer "In13.Cu")
		(net "P5E_CPU1_PE2_RX_DP<5>")
	)
	(segment
		(start 126.772162 -213.8934)
		(end 126.772416 -213.893908)
		(width 0.0889)
		(layer "In13.Cu")
		(net "P5E_CPU1_PE2_RX_DP<5>")
	)
	(segment
		(start 143.606266 -212.486748)
		(end 143.60652 -212.486748)
		(width 0.14732)
		(layer "In13.Cu")
		(net "P5E_CPU1_PE2_RX_DP<5>")
	)
	(segment
		(start 126.302516 -221.1197)
		(end 126.302516 -221.133924)
		(width 0.0889)
		(layer "In13.Cu")
		(net "P5E_CPU1_PE2_RX_DP<5>")
	)
	(segment
		(start 143.60652 -212.486748)
		(end 141.76375 -210.643978)
		(width 0.14732)
		(layer "In13.Cu")
		(net "P5E_CPU1_PE2_RX_DP<5>")
	)
	(segment
		(start 126.02591 -216.736422)
		(end 126.020576 -216.73947)
		(width 0.0889)
		(layer "In13.Cu")
		(net "P5E_CPU1_PE2_RX_DP<5>")
	)
	(segment
		(start 128.570228 -210.148678)
		(end 127.224536 -211.49437)
		(width 0.14732)
		(layer "In13.Cu")
		(net "P5E_CPU1_PE2_RX_DP<5>")
	)
	(segment
		(start 152.1587 -253.406656)
		(end 152.1587 -253.406402)
		(width 0.14732)
		(layer "In13.Cu")
		(net "P5E_CPU1_PE2_RX_DP<5>")
	)
	(segment
		(start 126.814072 -212.48497)
		(end 126.814072 -213.257638)
		(width 0.14732)
		(layer "In13.Cu")
		(net "P5E_CPU1_PE2_RX_DP<5>")
	)
	(segment
		(start 150.896574 -410.632656)
		(end 150.896574 -406.2222)
		(width 0.14732)
		(layer "In13.Cu")
		(net "P5E_CPU1_PE2_RX_DP<5>")
	)
	(segment
		(start 141.76375 -210.643978)
		(end 134.17804 -209.134964)
		(width 0.14732)
		(layer "In13.Cu")
		(net "P5E_CPU1_PE2_RX_DP<5>")
	)
	(segment
		(start 147.692618 -419.241478)
		(end 150.896574 -410.632656)
		(width 0.14732)
		(layer "In13.Cu")
		(net "P5E_CPU1_PE2_RX_DP<5>")
	)
	(segment
		(start 126.772162 -213.321646)
		(end 126.772162 -213.8934)
		(width 0.0889)
		(layer "In13.Cu")
		(net "P5E_CPU1_PE2_RX_DP<5>")
	)
	(segment
		(start 127.241808 -214.424768)
		(end 127.241808 -214.644732)
		(width 0.0889)
		(layer "In13.Cu")
		(net "P5E_CPU1_PE2_RX_DP<5>")
	)
	(segment
		(start 127.224536 -211.49437)
		(end 126.814072 -212.48497)
		(width 0.14732)
		(layer "In13.Cu")
		(net "P5E_CPU1_PE2_RX_DP<5>")
	)
	(segment
		(start 126.019814 -219.01658)
		(end 126.022608 -219.018104)
		(width 0.0889)
		(layer "In13.Cu")
		(net "P5E_CPU1_PE2_RX_DP<5>")
	)
	(segment
		(start 126.814072 -213.257638)
		(end 126.814072 -213.279736)
		(width 0.0889)
		(layer "In13.Cu")
		(net "P5E_CPU1_PE2_RX_DP<5>")
	)
	(segment
		(start 126.025656 -218.364562)
		(end 126.012956 -218.371674)
		(width 0.0889)
		(layer "In13.Cu")
		(net "P5E_CPU1_PE2_RX_DP<5>")
	)
	(segment
		(start 126.02591 -218.364308)
		(end 126.025656 -218.364562)
		(width 0.0889)
		(layer "In13.Cu")
		(net "P5E_CPU1_PE2_RX_DP<5>")
	)
	(segment
		(start 126.020576 -216.73947)
		(end 126.019814 -216.739978)
		(width 0.0889)
		(layer "In13.Cu")
		(net "P5E_CPU1_PE2_RX_DP<5>")
	)
	(segment
		(start 152.613614 -404.50516)
		(end 152.613614 -397.784828)
		(width 0.14732)
		(layer "In13.Cu")
		(net "P5E_CPU1_PE2_RX_DP<5>")
	)
	(segment
		(start 125.51283 -221.652846)
		(end 125.423676 -221.676722)
		(width 0.0889)
		(layer "In13.Cu")
		(net "P5E_CPU1_PE2_RX_DP<5>")
	)
	(segment
		(start 159.617156 -360.584242)
		(end 160.659826 -346.126054)
		(width 0.14732)
		(layer "In13.Cu")
		(net "P5E_CPU1_PE2_RX_DP<5>")
	)
	(segment
		(start 126.02591 -221.619826)
		(end 126.005082 -221.632018)
		(width 0.0889)
		(layer "In13.Cu")
		(net "P5E_CPU1_PE2_RX_DP<5>")
	)
	(segment
		(start 148.258784 -225.382328)
		(end 144.86763 -213.748112)
		(width 0.14732)
		(layer "In13.Cu")
		(net "P5E_CPU1_PE2_RX_DP<5>")
	)
	(segment
		(start 146.750024 -434.141372)
		(end 146.60245 -433.993798)
		(width 0.14732)
		(layer "In13.Cu")
		(net "P5E_CPU1_PE2_RX_DP<5>")
	)
	(segment
		(start 131.017518 -209.134964)
		(end 128.570228 -210.148678)
		(width 0.14732)
		(layer "In13.Cu")
		(net "P5E_CPU1_PE2_RX_DP<5>")
	)
	(segment
		(start 152.613614 -397.784828)
		(end 159.617156 -360.584242)
		(width 0.14732)
		(layer "In13.Cu")
		(net "P5E_CPU1_PE2_RX_DP<5>")
	)
	(segment
		(start 160.659826 -346.126054)
		(end 158.039054 -331.26807)
		(width 0.14732)
		(layer "In13.Cu")
		(net "P5E_CPU1_PE2_RX_DP<5>")
	)
	(segment
		(start 151.3078 -323.360288)
		(end 147.94484 -308.976268)
		(width 0.14732)
		(layer "In13.Cu")
		(net "P5E_CPU1_PE2_RX_DP<5>")
	)
	(segment
		(start 151.998172 -248.63425)
		(end 148.258784 -225.382328)
		(width 0.14732)
		(layer "In13.Cu")
		(net "P5E_CPU1_PE2_RX_DP<5>")
	)
	(segment
		(start 126.814072 -213.279736)
		(end 126.772162 -213.321646)
		(width 0.0889)
		(layer "In13.Cu")
		(net "P5E_CPU1_PE2_RX_DP<5>")
	)
	(segment
		(start 125.832616 -217.0557)
		(end 125.832616 -217.072972)
		(width 0.0889)
		(layer "In13.Cu")
		(net "P5E_CPU1_PE2_RX_DP<5>")
	)
	(segment
		(start 158.039054 -331.26807)
		(end 151.3078 -323.360288)
		(width 0.14732)
		(layer "In13.Cu")
		(net "P5E_CPU1_PE2_RX_DP<5>")
	)
	(segment
		(start 126.01829 -219.015818)
		(end 126.019814 -219.01658)
		(width 0.0889)
		(layer "In13.Cu")
		(net "P5E_CPU1_PE2_RX_DP<5>")
	)
	(segment
		(start 145.79219 -424.347894)
		(end 146.444208 -422.59631)
		(width 0.14732)
		(layer "In13.Cu")
		(net "P5E_CPU1_PE2_RX_DP<5>")
	)
	(segment
		(start 144.86763 -213.748112)
		(end 143.606266 -212.486748)
		(width 0.14732)
		(layer "In13.Cu")
		(net "P5E_CPU1_PE2_RX_DP<5>")
	)
	(segment
		(start 126.012956 -218.371674)
		(end 126.010924 -218.372944)
		(width 0.0889)
		(layer "In13.Cu")
		(net "P5E_CPU1_PE2_RX_DP<5>")
	)
	(segment
		(start 126.772162 -215.436704)
		(end 126.772162 -215.452198)
		(width 0.0889)
		(layer "In13.Cu")
		(net "P5E_CPU1_PE2_RX_DP<5>")
	)
	(segment
		(start 146.445478 -422.5925)
		(end 147.692364 -419.24224)
		(width 0.14732)
		(layer "In13.Cu")
		(net "P5E_CPU1_PE2_RX_DP<5>")
	)
	(segment
		(start 152.1587 -253.406402)
		(end 151.998172 -248.63425)
		(width 0.14732)
		(layer "In13.Cu")
		(net "P5E_CPU1_PE2_RX_DP<5>")
	)
	(segment
		(start 125.832616 -220.311218)
		(end 125.832616 -220.32849)
		(width 0.0889)
		(layer "In13.Cu")
		(net "P5E_CPU1_PE2_RX_DP<5>")
	)
	(segment
		(start 126.022608 -219.018104)
		(end 126.02591 -219.020136)
		(width 0.0889)
		(layer "In13.Cu")
		(net "P5E_CPU1_PE2_RX_DP<5>")
	)
	(segment
		(start 126.010924 -219.0115)
		(end 126.01829 -219.015818)
		(width 0.0889)
		(layer "In13.Cu")
		(net "P5E_CPU1_PE2_RX_DP<5>")
	)
	(segment
		(start 147.692364 -419.24224)
		(end 147.692618 -419.241478)
		(width 0.14732)
		(layer "In13.Cu")
		(net "P5E_CPU1_PE2_RX_DP<5>")
	)
	(segment
		(start 125.423676 -221.676722)
		(end 125.267212 -221.94774)
		(width 0.0889)
		(layer "In13.Cu")
		(net "P5E_CPU1_PE2_RX_DP<5>")
	)
	(segment
		(start 126.02591 -219.99194)
		(end 126.020576 -219.994988)
		(width 0.0889)
		(layer "In13.Cu")
		(net "P5E_CPU1_PE2_RX_DP<5>")
	)
	(segment
		(start 150.896574 -406.2222)
		(end 152.613614 -404.50516)
		(width 0.14732)
		(layer "In13.Cu")
		(net "P5E_CPU1_PE2_RX_DP<5>")
	)
	(segment
		(start 146.09953 -433.993798)
		(end 145.79219 -433.686458)
		(width 0.14732)
		(layer "In13.Cu")
		(net "P5E_CPU1_PE2_RX_DP<5>")
	)
	(segment
		(start 146.444208 -422.59631)
		(end 146.445478 -422.5925)
		(width 0.14732)
		(layer "In13.Cu")
		(net "P5E_CPU1_PE2_RX_DP<5>")
	)
	(arc
		(start 126.005082 -221.632018)
		(mid 125.772167 -221.698229)
		(end 125.532896 -221.660974)
		(width 0.0889)
		(layer "In13.Cu")
		(net "P5E_CPU1_PE2_RX_DP<5>")
	)
	(arc
		(start 126.772416 -215.421972)
		(mid 126.772219 -215.429337)
		(end 126.772162 -215.436704)
		(width 0.0889)
		(layer "In13.Cu")
		(net "P5E_CPU1_PE2_RX_DP<5>")
	)
	(arc
		(start 126.772162 -215.452198)
		(mid 126.692792 -215.725932)
		(end 126.489968 -215.926162)
		(width 0.0889)
		(layer "In13.Cu")
		(net "P5E_CPU1_PE2_RX_DP<5>")
	)
	(arc
		(start 126.956566 -214.093298)
		(mid 127.130529 -214.232062)
		(end 127.241808 -214.424768)
		(width 0.0889)
		(layer "In13.Cu")
		(net "P5E_CPU1_PE2_RX_DP<5>")
	)
	(arc
		(start 126.010924 -218.372944)
		(mid 125.832327 -218.692222)
		(end 126.010924 -219.0115)
		(width 0.0889)
		(layer "In13.Cu")
		(net "P5E_CPU1_PE2_RX_DP<5>")
	)
	(arc
		(start 126.02591 -219.020136)
		(mid 126.302484 -219.506038)
		(end 126.02591 -219.99194)
		(width 0.0889)
		(layer "In13.Cu")
		(net "P5E_CPU1_PE2_RX_DP<5>")
	)
	(arc
		(start 126.302516 -217.878406)
		(mid 126.228525 -218.157972)
		(end 126.02591 -218.364308)
		(width 0.0889)
		(layer "In13.Cu")
		(net "P5E_CPU1_PE2_RX_DP<5>")
	)
	(arc
		(start 126.019814 -220.644212)
		(mid 126.223295 -220.845016)
		(end 126.302516 -221.1197)
		(width 0.0889)
		(layer "In13.Cu")
		(net "P5E_CPU1_PE2_RX_DP<5>")
	)
	(arc
		(start 126.019814 -216.739978)
		(mid 125.884881 -216.873332)
		(end 125.832616 -217.0557)
		(width 0.0889)
		(layer "In13.Cu")
		(net "P5E_CPU1_PE2_RX_DP<5>")
	)
	(arc
		(start 126.019814 -219.995496)
		(mid 125.884881 -220.12885)
		(end 125.832616 -220.311218)
		(width 0.0889)
		(layer "In13.Cu")
		(net "P5E_CPU1_PE2_RX_DP<5>")
	)
	(arc
		(start 125.832616 -217.072972)
		(mid 125.884886 -217.255337)
		(end 126.019814 -217.388694)
		(width 0.0889)
		(layer "In13.Cu")
		(net "P5E_CPU1_PE2_RX_DP<5>")
	)
	(arc
		(start 127.241808 -214.644732)
		(mid 127.160897 -214.91486)
		(end 126.959614 -215.112346)
		(width 0.0889)
		(layer "In13.Cu")
		(net "P5E_CPU1_PE2_RX_DP<5>")
	)
	(arc
		(start 126.481078 -215.931242)
		(mid 126.350164 -216.067602)
		(end 126.302516 -216.25052)
		(width 0.0889)
		(layer "In13.Cu")
		(net "P5E_CPU1_PE2_RX_DP<5>")
	)
	(arc
		(start 126.772416 -213.893908)
		(mid 126.847421 -214.009367)
		(end 126.956566 -214.093298)
		(width 0.0889)
		(layer "In13.Cu")
		(net "P5E_CPU1_PE2_RX_DP<5>")
	)
	(arc
		(start 125.532896 -221.660974)
		(mid 125.522825 -221.657005)
		(end 125.51283 -221.652846)
		(width 0.0889)
		(layer "In13.Cu")
		(net "P5E_CPU1_PE2_RX_DP<5>")
	)
	(arc
		(start 126.302516 -221.133924)
		(mid 126.228525 -221.41349)
		(end 126.02591 -221.619826)
		(width 0.0889)
		(layer "In13.Cu")
		(net "P5E_CPU1_PE2_RX_DP<5>")
	)
	(arc
		(start 126.302516 -216.25052)
		(mid 126.228525 -216.530086)
		(end 126.02591 -216.736422)
		(width 0.0889)
		(layer "In13.Cu")
		(net "P5E_CPU1_PE2_RX_DP<5>")
	)
	(arc
		(start 126.950724 -215.117426)
		(mid 126.82347 -215.247392)
		(end 126.772416 -215.421972)
		(width 0.0889)
		(layer "In13.Cu")
		(net "P5E_CPU1_PE2_RX_DP<5>")
	)
	(arc
		(start 126.019814 -217.388694)
		(mid 126.223295 -217.589498)
		(end 126.302516 -217.864182)
		(width 0.0889)
		(layer "In13.Cu")
		(net "P5E_CPU1_PE2_RX_DP<5>")
	)
	(arc
		(start 125.832616 -220.32849)
		(mid 125.884886 -220.510855)
		(end 126.019814 -220.644212)
		(width 0.0889)
		(layer "In13.Cu")
		(net "P5E_CPU1_PE2_RX_DP<5>")
	)
	(segment
		(start 124.797312 -221.669864)
		(end 124.797312 -221.134178)
		(width 0.13208)
		(layer "F.Cu")
		(net "P5E_CPU1_PE2_RX_DP<4>")
	)
	(segment
		(start 124.797312 -221.134178)
		(end 124.797566 -221.133924)
		(width 0.13208)
		(layer "F.Cu")
		(net "P5E_CPU1_PE2_RX_DP<4>")
	)
	(segment
		(start 125.076966 -219.997528)
		(end 125.071378 -220.000576)
		(width 0.0889)
		(layer "In13.Cu")
		(net "P5E_CPU1_PE2_RX_DP<4>")
	)
	(segment
		(start 131.580128 -205.926436)
		(end 131.27101 -206.235554)
		(width 0.14732)
		(layer "In13.Cu")
		(net "P5E_CPU1_PE2_RX_DP<4>")
	)
	(segment
		(start 124.641102 -220.862906)
		(end 124.797566 -221.133924)
		(width 0.0889)
		(layer "In13.Cu")
		(net "P5E_CPU1_PE2_RX_DP<4>")
	)
	(segment
		(start 125.832362 -213.8934)
		(end 125.832616 -213.893908)
		(width 0.0889)
		(layer "In13.Cu")
		(net "P5E_CPU1_PE2_RX_DP<4>")
	)
	(segment
		(start 126.302008 -214.424768)
		(end 126.302008 -214.644732)
		(width 0.0889)
		(layer "In13.Cu")
		(net "P5E_CPU1_PE2_RX_DP<4>")
	)
	(segment
		(start 125.079506 -216.740486)
		(end 125.076966 -216.74201)
		(width 0.0889)
		(layer "In13.Cu")
		(net "P5E_CPU1_PE2_RX_DP<4>")
	)
	(segment
		(start 125.07849 -219.015818)
		(end 125.080014 -219.01658)
		(width 0.0889)
		(layer "In13.Cu")
		(net "P5E_CPU1_PE2_RX_DP<4>")
	)
	(segment
		(start 153.959814 -406.2222)
		(end 155.676854 -404.50516)
		(width 0.14732)
		(layer "In13.Cu")
		(net "P5E_CPU1_PE2_RX_DP<4>")
	)
	(segment
		(start 125.080776 -218.367356)
		(end 125.071124 -218.372944)
		(width 0.0889)
		(layer "In13.Cu")
		(net "P5E_CPU1_PE2_RX_DP<4>")
	)
	(segment
		(start 125.076966 -216.74201)
		(end 125.071378 -216.745058)
		(width 0.0889)
		(layer "In13.Cu")
		(net "P5E_CPU1_PE2_RX_DP<4>")
	)
	(segment
		(start 147.792186 -424.379898)
		(end 153.959814 -411.093666)
		(width 0.14732)
		(layer "In13.Cu")
		(net "P5E_CPU1_PE2_RX_DP<4>")
	)
	(segment
		(start 158.965646 -330.906882)
		(end 152.18918 -322.925948)
		(width 0.14732)
		(layer "In13.Cu")
		(net "P5E_CPU1_PE2_RX_DP<4>")
	)
	(segment
		(start 132.377942 -204.9526)
		(end 132.377942 -205.128622)
		(width 0.14732)
		(layer "In13.Cu")
		(net "P5E_CPU1_PE2_RX_DP<4>")
	)
	(segment
		(start 125.080014 -219.01658)
		(end 125.082808 -219.018104)
		(width 0.0889)
		(layer "In13.Cu")
		(net "P5E_CPU1_PE2_RX_DP<4>")
	)
	(segment
		(start 161.634424 -346.040202)
		(end 158.965646 -330.906882)
		(width 0.14732)
		(layer "In13.Cu")
		(net "P5E_CPU1_PE2_RX_DP<4>")
	)
	(segment
		(start 145.9103 -213.109048)
		(end 136.113012 -203.310236)
		(width 0.14732)
		(layer "In13.Cu")
		(net "P5E_CPU1_PE2_RX_DP<4>")
	)
	(segment
		(start 124.665232 -220.773752)
		(end 124.641102 -220.862906)
		(width 0.0889)
		(layer "In13.Cu")
		(net "P5E_CPU1_PE2_RX_DP<4>")
	)
	(segment
		(start 124.892816 -220.319854)
		(end 124.892816 -220.334078)
		(width 0.0889)
		(layer "In13.Cu")
		(net "P5E_CPU1_PE2_RX_DP<4>")
	)
	(segment
		(start 149.43582 -225.245168)
		(end 145.9103 -213.109048)
		(width 0.14732)
		(layer "In13.Cu")
		(net "P5E_CPU1_PE2_RX_DP<4>")
	)
	(segment
		(start 148.90242 -308.854348)
		(end 153.090118 -253.435612)
		(width 0.14732)
		(layer "In13.Cu")
		(net "P5E_CPU1_PE2_RX_DP<4>")
	)
	(segment
		(start 125.832362 -215.436704)
		(end 125.832362 -215.452198)
		(width 0.0889)
		(layer "In13.Cu")
		(net "P5E_CPU1_PE2_RX_DP<4>")
	)
	(segment
		(start 152.91816 -248.316496)
		(end 149.43582 -225.245168)
		(width 0.14732)
		(layer "In13.Cu")
		(net "P5E_CPU1_PE2_RX_DP<4>")
	)
	(segment
		(start 126.485142 -210.8454)
		(end 125.874272 -212.320378)
		(width 0.14732)
		(layer "In13.Cu")
		(net "P5E_CPU1_PE2_RX_DP<4>")
	)
	(segment
		(start 125.362716 -216.25052)
		(end 125.362716 -216.260426)
		(width 0.0889)
		(layer "In13.Cu")
		(net "P5E_CPU1_PE2_RX_DP<4>")
	)
	(segment
		(start 153.090118 -253.435612)
		(end 152.91816 -248.316496)
		(width 0.14732)
		(layer "In13.Cu")
		(net "P5E_CPU1_PE2_RX_DP<4>")
	)
	(segment
		(start 131.094988 -206.235554)
		(end 126.485142 -210.8454)
		(width 0.14732)
		(layer "In13.Cu")
		(net "P5E_CPU1_PE2_RX_DP<4>")
	)
	(segment
		(start 132.065014 -205.44155)
		(end 131.888992 -205.44155)
		(width 0.14732)
		(layer "In13.Cu")
		(net "P5E_CPU1_PE2_RX_DP<4>")
	)
	(segment
		(start 125.874272 -213.279736)
		(end 125.832362 -213.321646)
		(width 0.0889)
		(layer "In13.Cu")
		(net "P5E_CPU1_PE2_RX_DP<4>")
	)
	(segment
		(start 132.377942 -205.128622)
		(end 132.065014 -205.44155)
		(width 0.14732)
		(layer "In13.Cu")
		(net "P5E_CPU1_PE2_RX_DP<4>")
	)
	(segment
		(start 125.874272 -212.320378)
		(end 125.874272 -213.257638)
		(width 0.14732)
		(layer "In13.Cu")
		(net "P5E_CPU1_PE2_RX_DP<4>")
	)
	(segment
		(start 125.832362 -213.321646)
		(end 125.832362 -213.8934)
		(width 0.0889)
		(layer "In13.Cu")
		(net "P5E_CPU1_PE2_RX_DP<4>")
	)
	(segment
		(start 125.079506 -219.996004)
		(end 125.076966 -219.997528)
		(width 0.0889)
		(layer "In13.Cu")
		(net "P5E_CPU1_PE2_RX_DP<4>")
	)
	(segment
		(start 160.556448 -361.408472)
		(end 161.634424 -346.040202)
		(width 0.14732)
		(layer "In13.Cu")
		(net "P5E_CPU1_PE2_RX_DP<4>")
	)
	(segment
		(start 125.080268 -219.995496)
		(end 125.079506 -219.996004)
		(width 0.0889)
		(layer "In13.Cu")
		(net "P5E_CPU1_PE2_RX_DP<4>")
	)
	(segment
		(start 155.676854 -404.50516)
		(end 155.676854 -397.665956)
		(width 0.14732)
		(layer "In13.Cu")
		(net "P5E_CPU1_PE2_RX_DP<4>")
	)
	(segment
		(start 131.580128 -205.750414)
		(end 131.580128 -205.926436)
		(width 0.14732)
		(layer "In13.Cu")
		(net "P5E_CPU1_PE2_RX_DP<4>")
	)
	(segment
		(start 148.75002 -435.14137)
		(end 148.602446 -434.993796)
		(width 0.14732)
		(layer "In13.Cu")
		(net "P5E_CPU1_PE2_RX_DP<4>")
	)
	(segment
		(start 131.888992 -205.44155)
		(end 131.580128 -205.750414)
		(width 0.14732)
		(layer "In13.Cu")
		(net "P5E_CPU1_PE2_RX_DP<4>")
	)
	(segment
		(start 148.090382 -434.993796)
		(end 147.792186 -434.6956)
		(width 0.14732)
		(layer "In13.Cu")
		(net "P5E_CPU1_PE2_RX_DP<4>")
	)
	(segment
		(start 148.75002 -435.489858)
		(end 148.75002 -435.14137)
		(width 0.14732)
		(layer "In13.Cu")
		(net "P5E_CPU1_PE2_RX_DP<4>")
	)
	(segment
		(start 125.080268 -216.739978)
		(end 125.079506 -216.740486)
		(width 0.0889)
		(layer "In13.Cu")
		(net "P5E_CPU1_PE2_RX_DP<4>")
	)
	(segment
		(start 152.18918 -322.925948)
		(end 148.90242 -308.854348)
		(width 0.14732)
		(layer "In13.Cu")
		(net "P5E_CPU1_PE2_RX_DP<4>")
	)
	(segment
		(start 125.362716 -219.506038)
		(end 125.362716 -219.515944)
		(width 0.0889)
		(layer "In13.Cu")
		(net "P5E_CPU1_PE2_RX_DP<4>")
	)
	(segment
		(start 125.08611 -218.364308)
		(end 125.080776 -218.367356)
		(width 0.0889)
		(layer "In13.Cu")
		(net "P5E_CPU1_PE2_RX_DP<4>")
	)
	(segment
		(start 126.019814 -215.112346)
		(end 126.010924 -215.117426)
		(width 0.0889)
		(layer "In13.Cu")
		(net "P5E_CPU1_PE2_RX_DP<4>")
	)
	(segment
		(start 125.082808 -219.018104)
		(end 125.08611 -219.020136)
		(width 0.0889)
		(layer "In13.Cu")
		(net "P5E_CPU1_PE2_RX_DP<4>")
	)
	(segment
		(start 153.959814 -411.093666)
		(end 153.959814 -406.2222)
		(width 0.14732)
		(layer "In13.Cu")
		(net "P5E_CPU1_PE2_RX_DP<4>")
	)
	(segment
		(start 155.676854 -397.665956)
		(end 160.556448 -361.408472)
		(width 0.14732)
		(layer "In13.Cu")
		(net "P5E_CPU1_PE2_RX_DP<4>")
	)
	(segment
		(start 148.602446 -434.993796)
		(end 148.090382 -434.993796)
		(width 0.14732)
		(layer "In13.Cu")
		(net "P5E_CPU1_PE2_RX_DP<4>")
	)
	(segment
		(start 131.27101 -206.235554)
		(end 131.094988 -206.235554)
		(width 0.14732)
		(layer "In13.Cu")
		(net "P5E_CPU1_PE2_RX_DP<4>")
	)
	(segment
		(start 125.550168 -215.926162)
		(end 125.541278 -215.931242)
		(width 0.0889)
		(layer "In13.Cu")
		(net "P5E_CPU1_PE2_RX_DP<4>")
	)
	(segment
		(start 136.113012 -203.310236)
		(end 134.020306 -203.310236)
		(width 0.14732)
		(layer "In13.Cu")
		(net "P5E_CPU1_PE2_RX_DP<4>")
	)
	(segment
		(start 147.792186 -434.6956)
		(end 147.792186 -424.379898)
		(width 0.14732)
		(layer "In13.Cu")
		(net "P5E_CPU1_PE2_RX_DP<4>")
	)
	(segment
		(start 125.071124 -219.0115)
		(end 125.07849 -219.015818)
		(width 0.0889)
		(layer "In13.Cu")
		(net "P5E_CPU1_PE2_RX_DP<4>")
	)
	(segment
		(start 125.071378 -217.383614)
		(end 125.080268 -217.388694)
		(width 0.0889)
		(layer "In13.Cu")
		(net "P5E_CPU1_PE2_RX_DP<4>")
	)
	(segment
		(start 134.020306 -203.310236)
		(end 132.377942 -204.9526)
		(width 0.14732)
		(layer "In13.Cu")
		(net "P5E_CPU1_PE2_RX_DP<4>")
	)
	(segment
		(start 125.874272 -213.257638)
		(end 125.874272 -213.279736)
		(width 0.0889)
		(layer "In13.Cu")
		(net "P5E_CPU1_PE2_RX_DP<4>")
	)
	(arc
		(start 125.071124 -218.372944)
		(mid 124.892527 -218.692222)
		(end 125.071124 -219.0115)
		(width 0.0889)
		(layer "In13.Cu")
		(net "P5E_CPU1_PE2_RX_DP<4>")
	)
	(arc
		(start 125.832362 -215.452198)
		(mid 125.752992 -215.725932)
		(end 125.550168 -215.926162)
		(width 0.0889)
		(layer "In13.Cu")
		(net "P5E_CPU1_PE2_RX_DP<4>")
	)
	(arc
		(start 125.08611 -219.020136)
		(mid 125.288697 -219.226487)
		(end 125.362716 -219.506038)
		(width 0.0889)
		(layer "In13.Cu")
		(net "P5E_CPU1_PE2_RX_DP<4>")
	)
	(arc
		(start 125.071378 -220.000576)
		(mid 124.940464 -220.136936)
		(end 124.892816 -220.319854)
		(width 0.0889)
		(layer "In13.Cu")
		(net "P5E_CPU1_PE2_RX_DP<4>")
	)
	(arc
		(start 125.832616 -213.893908)
		(mid 125.907621 -214.009367)
		(end 126.016766 -214.093298)
		(width 0.0889)
		(layer "In13.Cu")
		(net "P5E_CPU1_PE2_RX_DP<4>")
	)
	(arc
		(start 125.362716 -219.515944)
		(mid 125.284605 -219.792893)
		(end 125.080268 -219.995496)
		(width 0.0889)
		(layer "In13.Cu")
		(net "P5E_CPU1_PE2_RX_DP<4>")
	)
	(arc
		(start 124.892816 -217.064336)
		(mid 124.940495 -217.247236)
		(end 125.071378 -217.383614)
		(width 0.0889)
		(layer "In13.Cu")
		(net "P5E_CPU1_PE2_RX_DP<4>")
	)
	(arc
		(start 124.681996 -220.760798)
		(mid 124.673674 -220.767353)
		(end 124.665232 -220.773752)
		(width 0.0889)
		(layer "In13.Cu")
		(net "P5E_CPU1_PE2_RX_DP<4>")
	)
	(arc
		(start 125.832616 -215.421972)
		(mid 125.832419 -215.429337)
		(end 125.832362 -215.436704)
		(width 0.0889)
		(layer "In13.Cu")
		(net "P5E_CPU1_PE2_RX_DP<4>")
	)
	(arc
		(start 125.080268 -217.388694)
		(mid 125.362917 -217.874797)
		(end 125.08611 -218.364308)
		(width 0.0889)
		(layer "In13.Cu")
		(net "P5E_CPU1_PE2_RX_DP<4>")
	)
	(arc
		(start 124.892816 -220.334078)
		(mid 124.834455 -220.570676)
		(end 124.681996 -220.760798)
		(width 0.0889)
		(layer "In13.Cu")
		(net "P5E_CPU1_PE2_RX_DP<4>")
	)
	(arc
		(start 126.016766 -214.093298)
		(mid 126.190729 -214.232062)
		(end 126.302008 -214.424768)
		(width 0.0889)
		(layer "In13.Cu")
		(net "P5E_CPU1_PE2_RX_DP<4>")
	)
	(arc
		(start 126.302008 -214.644732)
		(mid 126.221097 -214.91486)
		(end 126.019814 -215.112346)
		(width 0.0889)
		(layer "In13.Cu")
		(net "P5E_CPU1_PE2_RX_DP<4>")
	)
	(arc
		(start 125.541278 -215.931242)
		(mid 125.410364 -216.067602)
		(end 125.362716 -216.25052)
		(width 0.0889)
		(layer "In13.Cu")
		(net "P5E_CPU1_PE2_RX_DP<4>")
	)
	(arc
		(start 126.010924 -215.117426)
		(mid 125.88367 -215.247392)
		(end 125.832616 -215.421972)
		(width 0.0889)
		(layer "In13.Cu")
		(net "P5E_CPU1_PE2_RX_DP<4>")
	)
	(arc
		(start 125.071378 -216.745058)
		(mid 124.940464 -216.881418)
		(end 124.892816 -217.064336)
		(width 0.0889)
		(layer "In13.Cu")
		(net "P5E_CPU1_PE2_RX_DP<4>")
	)
	(arc
		(start 125.362716 -216.260426)
		(mid 125.284605 -216.537375)
		(end 125.080268 -216.739978)
		(width 0.0889)
		(layer "In13.Cu")
		(net "P5E_CPU1_PE2_RX_DP<4>")
	)
	(segment
		(start 123.387866 -222.48368)
		(end 123.387866 -221.947994)
		(width 0.13208)
		(layer "F.Cu")
		(net "P5E_CPU1_PE2_RX_DP<3>")
	)
	(segment
		(start 123.387866 -221.947994)
		(end 123.387612 -221.94774)
		(width 0.13208)
		(layer "F.Cu")
		(net "P5E_CPU1_PE2_RX_DP<3>")
	)
	(segment
		(start 124.140976 -216.73947)
		(end 124.140214 -216.739978)
		(width 0.0889)
		(layer "In13.Cu")
		(net "P5E_CPU1_PE2_RX_DP<3>")
	)
	(segment
		(start 123.544076 -221.676722)
		(end 123.387612 -221.94774)
		(width 0.0889)
		(layer "In13.Cu")
		(net "P5E_CPU1_PE2_RX_DP<3>")
	)
	(segment
		(start 150.20671 -434.016658)
		(end 149.792182 -433.60213)
		(width 0.14732)
		(layer "In13.Cu")
		(net "P5E_CPU1_PE2_RX_DP<3>")
	)
	(segment
		(start 150.381462 -225.037396)
		(end 146.76882 -212.601302)
		(width 0.14732)
		(layer "In13.Cu")
		(net "P5E_CPU1_PE2_RX_DP<3>")
	)
	(segment
		(start 124.610368 -215.926162)
		(end 124.601478 -215.931242)
		(width 0.0889)
		(layer "In13.Cu")
		(net "P5E_CPU1_PE2_RX_DP<3>")
	)
	(segment
		(start 123.953016 -220.311218)
		(end 123.953016 -220.32849)
		(width 0.0889)
		(layer "In13.Cu")
		(net "P5E_CPU1_PE2_RX_DP<3>")
	)
	(segment
		(start 125.362208 -214.424768)
		(end 125.362208 -214.644732)
		(width 0.0889)
		(layer "In13.Cu")
		(net "P5E_CPU1_PE2_RX_DP<3>")
	)
	(segment
		(start 124.934472 -213.279736)
		(end 124.892562 -213.321646)
		(width 0.0889)
		(layer "In13.Cu")
		(net "P5E_CPU1_PE2_RX_DP<3>")
	)
	(segment
		(start 153.04262 -322.425568)
		(end 149.86254 -308.694328)
		(width 0.14732)
		(layer "In13.Cu")
		(net "P5E_CPU1_PE2_RX_DP<3>")
	)
	(segment
		(start 124.892562 -213.8934)
		(end 124.892816 -213.893908)
		(width 0.0889)
		(layer "In13.Cu")
		(net "P5E_CPU1_PE2_RX_DP<3>")
	)
	(segment
		(start 124.892562 -213.321646)
		(end 124.892562 -213.8934)
		(width 0.0889)
		(layer "In13.Cu")
		(net "P5E_CPU1_PE2_RX_DP<3>")
	)
	(segment
		(start 162.58159 -345.998038)
		(end 159.845502 -330.483972)
		(width 0.14732)
		(layer "In13.Cu")
		(net "P5E_CPU1_PE2_RX_DP<3>")
	)
	(segment
		(start 124.140976 -219.994988)
		(end 124.140214 -219.995496)
		(width 0.0889)
		(layer "In13.Cu")
		(net "P5E_CPU1_PE2_RX_DP<3>")
	)
	(segment
		(start 154.036776 -253.69901)
		(end 153.844498 -247.986296)
		(width 0.14732)
		(layer "In13.Cu")
		(net "P5E_CPU1_PE2_RX_DP<3>")
	)
	(segment
		(start 124.13869 -219.015818)
		(end 124.140214 -219.01658)
		(width 0.0889)
		(layer "In13.Cu")
		(net "P5E_CPU1_PE2_RX_DP<3>")
	)
	(segment
		(start 133.644894 -202.370436)
		(end 125.62713 -210.3882)
		(width 0.14732)
		(layer "In13.Cu")
		(net "P5E_CPU1_PE2_RX_DP<3>")
	)
	(segment
		(start 158.740094 -404.50516)
		(end 158.740094 -396.34541)
		(width 0.14732)
		(layer "In13.Cu")
		(net "P5E_CPU1_PE2_RX_DP<3>")
	)
	(segment
		(start 125.080014 -215.112346)
		(end 125.071124 -215.117426)
		(width 0.0889)
		(layer "In13.Cu")
		(net "P5E_CPU1_PE2_RX_DP<3>")
	)
	(segment
		(start 124.892562 -215.436704)
		(end 124.892562 -215.452198)
		(width 0.0889)
		(layer "In13.Cu")
		(net "P5E_CPU1_PE2_RX_DP<3>")
	)
	(segment
		(start 124.140214 -219.01658)
		(end 124.143008 -219.018104)
		(width 0.0889)
		(layer "In13.Cu")
		(net "P5E_CPU1_PE2_RX_DP<3>")
	)
	(segment
		(start 149.792182 -424.495468)
		(end 157.023054 -410.587952)
		(width 0.14732)
		(layer "In13.Cu")
		(net "P5E_CPU1_PE2_RX_DP<3>")
	)
	(segment
		(start 157.023054 -406.2222)
		(end 158.740094 -404.50516)
		(width 0.14732)
		(layer "In13.Cu")
		(net "P5E_CPU1_PE2_RX_DP<3>")
	)
	(segment
		(start 150.750016 -434.48986)
		(end 150.750016 -434.164232)
		(width 0.14732)
		(layer "In13.Cu")
		(net "P5E_CPU1_PE2_RX_DP<3>")
	)
	(segment
		(start 123.953016 -217.0557)
		(end 123.953016 -217.072972)
		(width 0.0889)
		(layer "In13.Cu")
		(net "P5E_CPU1_PE2_RX_DP<3>")
	)
	(segment
		(start 149.86254 -308.694328)
		(end 154.036776 -253.69901)
		(width 0.14732)
		(layer "In13.Cu")
		(net "P5E_CPU1_PE2_RX_DP<3>")
	)
	(segment
		(start 124.143008 -219.018104)
		(end 124.14631 -219.020136)
		(width 0.0889)
		(layer "In13.Cu")
		(net "P5E_CPU1_PE2_RX_DP<3>")
	)
	(segment
		(start 124.422916 -221.1197)
		(end 124.422916 -221.133924)
		(width 0.0889)
		(layer "In13.Cu")
		(net "P5E_CPU1_PE2_RX_DP<3>")
	)
	(segment
		(start 124.934472 -212.060536)
		(end 124.934472 -213.257638)
		(width 0.14732)
		(layer "In13.Cu")
		(net "P5E_CPU1_PE2_RX_DP<3>")
	)
	(segment
		(start 124.14631 -221.619826)
		(end 124.125482 -221.632018)
		(width 0.0889)
		(layer "In13.Cu")
		(net "P5E_CPU1_PE2_RX_DP<3>")
	)
	(segment
		(start 161.654744 -361.58805)
		(end 162.58159 -345.998038)
		(width 0.14732)
		(layer "In13.Cu")
		(net "P5E_CPU1_PE2_RX_DP<3>")
	)
	(segment
		(start 125.62713 -210.3882)
		(end 124.934472 -212.060536)
		(width 0.14732)
		(layer "In13.Cu")
		(net "P5E_CPU1_PE2_RX_DP<3>")
	)
	(segment
		(start 149.792182 -433.60213)
		(end 149.792182 -424.495468)
		(width 0.14732)
		(layer "In13.Cu")
		(net "P5E_CPU1_PE2_RX_DP<3>")
	)
	(segment
		(start 157.023054 -410.587952)
		(end 157.023054 -406.2222)
		(width 0.14732)
		(layer "In13.Cu")
		(net "P5E_CPU1_PE2_RX_DP<3>")
	)
	(segment
		(start 124.14631 -219.99194)
		(end 124.140976 -219.994988)
		(width 0.0889)
		(layer "In13.Cu")
		(net "P5E_CPU1_PE2_RX_DP<3>")
	)
	(segment
		(start 146.76882 -212.601302)
		(end 136.53897 -202.370436)
		(width 0.14732)
		(layer "In13.Cu")
		(net "P5E_CPU1_PE2_RX_DP<3>")
	)
	(segment
		(start 136.53897 -202.370436)
		(end 133.644894 -202.370436)
		(width 0.14732)
		(layer "In13.Cu")
		(net "P5E_CPU1_PE2_RX_DP<3>")
	)
	(segment
		(start 123.63323 -221.652846)
		(end 123.544076 -221.676722)
		(width 0.0889)
		(layer "In13.Cu")
		(net "P5E_CPU1_PE2_RX_DP<3>")
	)
	(segment
		(start 124.14631 -218.364308)
		(end 124.140976 -218.367356)
		(width 0.0889)
		(layer "In13.Cu")
		(net "P5E_CPU1_PE2_RX_DP<3>")
	)
	(segment
		(start 124.131324 -219.0115)
		(end 124.13869 -219.015818)
		(width 0.0889)
		(layer "In13.Cu")
		(net "P5E_CPU1_PE2_RX_DP<3>")
	)
	(segment
		(start 158.740094 -396.34541)
		(end 161.654744 -361.58805)
		(width 0.14732)
		(layer "In13.Cu")
		(net "P5E_CPU1_PE2_RX_DP<3>")
	)
	(segment
		(start 124.934472 -213.257638)
		(end 124.934472 -213.279736)
		(width 0.0889)
		(layer "In13.Cu")
		(net "P5E_CPU1_PE2_RX_DP<3>")
	)
	(segment
		(start 153.844498 -247.986296)
		(end 150.381462 -225.037396)
		(width 0.14732)
		(layer "In13.Cu")
		(net "P5E_CPU1_PE2_RX_DP<3>")
	)
	(segment
		(start 124.140976 -218.367356)
		(end 124.131324 -218.372944)
		(width 0.0889)
		(layer "In13.Cu")
		(net "P5E_CPU1_PE2_RX_DP<3>")
	)
	(segment
		(start 159.845502 -330.483972)
		(end 153.04262 -322.425568)
		(width 0.14732)
		(layer "In13.Cu")
		(net "P5E_CPU1_PE2_RX_DP<3>")
	)
	(segment
		(start 150.602442 -434.016658)
		(end 150.20671 -434.016658)
		(width 0.14732)
		(layer "In13.Cu")
		(net "P5E_CPU1_PE2_RX_DP<3>")
	)
	(segment
		(start 124.14631 -216.736422)
		(end 124.140976 -216.73947)
		(width 0.0889)
		(layer "In13.Cu")
		(net "P5E_CPU1_PE2_RX_DP<3>")
	)
	(segment
		(start 150.750016 -434.164232)
		(end 150.602442 -434.016658)
		(width 0.14732)
		(layer "In13.Cu")
		(net "P5E_CPU1_PE2_RX_DP<3>")
	)
	(arc
		(start 124.140214 -216.739978)
		(mid 124.005281 -216.873332)
		(end 123.953016 -217.0557)
		(width 0.0889)
		(layer "In13.Cu")
		(net "P5E_CPU1_PE2_RX_DP<3>")
	)
	(arc
		(start 123.653296 -221.660974)
		(mid 123.643225 -221.657005)
		(end 123.63323 -221.652846)
		(width 0.0889)
		(layer "In13.Cu")
		(net "P5E_CPU1_PE2_RX_DP<3>")
	)
	(arc
		(start 123.953016 -217.072972)
		(mid 124.005286 -217.255337)
		(end 124.140214 -217.388694)
		(width 0.0889)
		(layer "In13.Cu")
		(net "P5E_CPU1_PE2_RX_DP<3>")
	)
	(arc
		(start 124.601478 -215.931242)
		(mid 124.470564 -216.067602)
		(end 124.422916 -216.25052)
		(width 0.0889)
		(layer "In13.Cu")
		(net "P5E_CPU1_PE2_RX_DP<3>")
	)
	(arc
		(start 124.892816 -213.893908)
		(mid 124.967821 -214.009367)
		(end 125.076966 -214.093298)
		(width 0.0889)
		(layer "In13.Cu")
		(net "P5E_CPU1_PE2_RX_DP<3>")
	)
	(arc
		(start 124.140214 -217.388694)
		(mid 124.423209 -217.874813)
		(end 124.14631 -218.364308)
		(width 0.0889)
		(layer "In13.Cu")
		(net "P5E_CPU1_PE2_RX_DP<3>")
	)
	(arc
		(start 124.140214 -219.995496)
		(mid 124.005281 -220.12885)
		(end 123.953016 -220.311218)
		(width 0.0889)
		(layer "In13.Cu")
		(net "P5E_CPU1_PE2_RX_DP<3>")
	)
	(arc
		(start 124.140214 -220.644212)
		(mid 124.343695 -220.845016)
		(end 124.422916 -221.1197)
		(width 0.0889)
		(layer "In13.Cu")
		(net "P5E_CPU1_PE2_RX_DP<3>")
	)
	(arc
		(start 125.071124 -215.117426)
		(mid 124.94387 -215.247392)
		(end 124.892816 -215.421972)
		(width 0.0889)
		(layer "In13.Cu")
		(net "P5E_CPU1_PE2_RX_DP<3>")
	)
	(arc
		(start 124.14631 -219.020136)
		(mid 124.422884 -219.506038)
		(end 124.14631 -219.99194)
		(width 0.0889)
		(layer "In13.Cu")
		(net "P5E_CPU1_PE2_RX_DP<3>")
	)
	(arc
		(start 124.131324 -218.372944)
		(mid 123.952727 -218.692222)
		(end 124.131324 -219.0115)
		(width 0.0889)
		(layer "In13.Cu")
		(net "P5E_CPU1_PE2_RX_DP<3>")
	)
	(arc
		(start 124.125482 -221.632018)
		(mid 123.892567 -221.698229)
		(end 123.653296 -221.660974)
		(width 0.0889)
		(layer "In13.Cu")
		(net "P5E_CPU1_PE2_RX_DP<3>")
	)
	(arc
		(start 125.362208 -214.644732)
		(mid 125.281297 -214.91486)
		(end 125.080014 -215.112346)
		(width 0.0889)
		(layer "In13.Cu")
		(net "P5E_CPU1_PE2_RX_DP<3>")
	)
	(arc
		(start 125.076966 -214.093298)
		(mid 125.250929 -214.232062)
		(end 125.362208 -214.424768)
		(width 0.0889)
		(layer "In13.Cu")
		(net "P5E_CPU1_PE2_RX_DP<3>")
	)
	(arc
		(start 124.422916 -221.133924)
		(mid 124.348925 -221.41349)
		(end 124.14631 -221.619826)
		(width 0.0889)
		(layer "In13.Cu")
		(net "P5E_CPU1_PE2_RX_DP<3>")
	)
	(arc
		(start 124.892562 -215.452198)
		(mid 124.813192 -215.725932)
		(end 124.610368 -215.926162)
		(width 0.0889)
		(layer "In13.Cu")
		(net "P5E_CPU1_PE2_RX_DP<3>")
	)
	(arc
		(start 124.422916 -216.25052)
		(mid 124.348925 -216.530086)
		(end 124.14631 -216.736422)
		(width 0.0889)
		(layer "In13.Cu")
		(net "P5E_CPU1_PE2_RX_DP<3>")
	)
	(arc
		(start 124.892816 -215.421972)
		(mid 124.892619 -215.429337)
		(end 124.892562 -215.436704)
		(width 0.0889)
		(layer "In13.Cu")
		(net "P5E_CPU1_PE2_RX_DP<3>")
	)
	(arc
		(start 123.953016 -220.32849)
		(mid 124.005286 -220.510855)
		(end 124.140214 -220.644212)
		(width 0.0889)
		(layer "In13.Cu")
		(net "P5E_CPU1_PE2_RX_DP<3>")
	)
	(segment
		(start 122.917712 -221.134178)
		(end 122.917966 -221.133924)
		(width 0.13208)
		(layer "F.Cu")
		(net "P5E_CPU1_PE2_RX_DP<2>")
	)
	(segment
		(start 122.917712 -221.669864)
		(end 122.917712 -221.134178)
		(width 0.13208)
		(layer "F.Cu")
		(net "P5E_CPU1_PE2_RX_DP<2>")
	)
	(segment
		(start 123.483116 -219.506038)
		(end 123.483116 -219.515944)
		(width 0.0889)
		(layer "In13.Cu")
		(net "P5E_CPU1_PE2_RX_DP<2>")
	)
	(segment
		(start 123.191524 -219.0115)
		(end 123.19889 -219.015818)
		(width 0.0889)
		(layer "In13.Cu")
		(net "P5E_CPU1_PE2_RX_DP<2>")
	)
	(segment
		(start 162.7505 -361.220512)
		(end 162.7505 -361.21975)
		(width 0.14732)
		(layer "In13.Cu")
		(net "P5E_CPU1_PE2_RX_DP<2>")
	)
	(segment
		(start 123.197366 -219.997528)
		(end 123.191778 -220.000576)
		(width 0.0889)
		(layer "In13.Cu")
		(net "P5E_CPU1_PE2_RX_DP<2>")
	)
	(segment
		(start 124.815346 -209.881216)
		(end 123.994672 -211.862416)
		(width 0.14732)
		(layer "In13.Cu")
		(net "P5E_CPU1_PE2_RX_DP<2>")
	)
	(segment
		(start 123.952762 -213.321646)
		(end 123.952762 -213.8934)
		(width 0.0889)
		(layer "In13.Cu")
		(net "P5E_CPU1_PE2_RX_DP<2>")
	)
	(segment
		(start 123.994672 -213.257638)
		(end 123.994672 -213.279736)
		(width 0.0889)
		(layer "In13.Cu")
		(net "P5E_CPU1_PE2_RX_DP<2>")
	)
	(segment
		(start 144.355312 -208.731866)
		(end 144.355312 -208.559654)
		(width 0.14732)
		(layer "In13.Cu")
		(net "P5E_CPU1_PE2_RX_DP<2>")
	)
	(segment
		(start 160.72866 -330.054458)
		(end 153.89098 -321.897248)
		(width 0.14732)
		(layer "In13.Cu")
		(net "P5E_CPU1_PE2_RX_DP<2>")
	)
	(segment
		(start 151.792178 -434.656992)
		(end 151.792178 -424.109134)
		(width 0.14732)
		(layer "In13.Cu")
		(net "P5E_CPU1_PE2_RX_DP<2>")
	)
	(segment
		(start 124.140214 -215.112346)
		(end 124.131324 -215.117426)
		(width 0.0889)
		(layer "In13.Cu")
		(net "P5E_CPU1_PE2_RX_DP<2>")
	)
	(segment
		(start 123.193556 -218.371674)
		(end 123.191524 -218.372944)
		(width 0.0889)
		(layer "In13.Cu")
		(net "P5E_CPU1_PE2_RX_DP<2>")
	)
	(segment
		(start 151.792178 -424.109134)
		(end 160.086294 -411.000702)
		(width 0.14732)
		(layer "In13.Cu")
		(net "P5E_CPU1_PE2_RX_DP<2>")
	)
	(segment
		(start 133.265926 -201.430636)
		(end 124.815346 -209.881216)
		(width 0.14732)
		(layer "In13.Cu")
		(net "P5E_CPU1_PE2_RX_DP<2>")
	)
	(segment
		(start 163.56838 -346.156788)
		(end 160.72866 -330.054458)
		(width 0.14732)
		(layer "In13.Cu")
		(net "P5E_CPU1_PE2_RX_DP<2>")
	)
	(segment
		(start 122.761502 -220.862906)
		(end 122.917966 -221.133924)
		(width 0.0889)
		(layer "In13.Cu")
		(net "P5E_CPU1_PE2_RX_DP<2>")
	)
	(segment
		(start 123.20651 -218.364308)
		(end 123.193556 -218.371674)
		(width 0.0889)
		(layer "In13.Cu")
		(net "P5E_CPU1_PE2_RX_DP<2>")
	)
	(segment
		(start 123.203208 -219.018104)
		(end 123.20651 -219.020136)
		(width 0.0889)
		(layer "In13.Cu")
		(net "P5E_CPU1_PE2_RX_DP<2>")
	)
	(segment
		(start 123.952762 -215.436704)
		(end 123.952762 -215.452198)
		(width 0.0889)
		(layer "In13.Cu")
		(net "P5E_CPU1_PE2_RX_DP<2>")
	)
	(segment
		(start 145.936208 -210.140296)
		(end 145.627344 -209.831432)
		(width 0.14732)
		(layer "In13.Cu")
		(net "P5E_CPU1_PE2_RX_DP<2>")
	)
	(segment
		(start 145.14576 -209.522314)
		(end 145.14576 -209.349848)
		(width 0.14732)
		(layer "In13.Cu")
		(net "P5E_CPU1_PE2_RX_DP<2>")
	)
	(segment
		(start 152.750012 -435.489858)
		(end 152.750012 -435.14137)
		(width 0.14732)
		(layer "In13.Cu")
		(net "P5E_CPU1_PE2_RX_DP<2>")
	)
	(segment
		(start 123.200668 -219.995496)
		(end 123.199906 -219.996004)
		(width 0.0889)
		(layer "In13.Cu")
		(net "P5E_CPU1_PE2_RX_DP<2>")
	)
	(segment
		(start 144.355312 -208.559654)
		(end 137.226802 -201.430636)
		(width 0.14732)
		(layer "In13.Cu")
		(net "P5E_CPU1_PE2_RX_DP<2>")
	)
	(segment
		(start 123.199906 -219.996004)
		(end 123.197366 -219.997528)
		(width 0.0889)
		(layer "In13.Cu")
		(net "P5E_CPU1_PE2_RX_DP<2>")
	)
	(segment
		(start 162.7505 -361.21975)
		(end 163.56838 -346.156788)
		(width 0.14732)
		(layer "In13.Cu")
		(net "P5E_CPU1_PE2_RX_DP<2>")
	)
	(segment
		(start 147.665694 -211.870036)
		(end 146.417792 -210.62188)
		(width 0.14732)
		(layer "In13.Cu")
		(net "P5E_CPU1_PE2_RX_DP<2>")
	)
	(segment
		(start 161.803334 -399.614136)
		(end 162.7505 -361.220512)
		(width 0.14732)
		(layer "In13.Cu")
		(net "P5E_CPU1_PE2_RX_DP<2>")
	)
	(segment
		(start 123.197366 -216.74201)
		(end 123.191778 -216.745058)
		(width 0.0889)
		(layer "In13.Cu")
		(net "P5E_CPU1_PE2_RX_DP<2>")
	)
	(segment
		(start 154.986228 -253.490476)
		(end 154.766264 -246.95531)
		(width 0.14732)
		(layer "In13.Cu")
		(net "P5E_CPU1_PE2_RX_DP<2>")
	)
	(segment
		(start 154.766264 -246.95531)
		(end 151.424386 -224.808288)
		(width 0.14732)
		(layer "In13.Cu")
		(net "P5E_CPU1_PE2_RX_DP<2>")
	)
	(segment
		(start 145.14576 -209.349848)
		(end 144.836896 -209.040984)
		(width 0.14732)
		(layer "In13.Cu")
		(net "P5E_CPU1_PE2_RX_DP<2>")
	)
	(segment
		(start 123.191778 -217.383614)
		(end 123.200668 -217.388694)
		(width 0.0889)
		(layer "In13.Cu")
		(net "P5E_CPU1_PE2_RX_DP<2>")
	)
	(segment
		(start 151.424386 -224.808288)
		(end 147.665694 -211.870036)
		(width 0.14732)
		(layer "In13.Cu")
		(net "P5E_CPU1_PE2_RX_DP<2>")
	)
	(segment
		(start 146.245326 -210.62188)
		(end 145.936208 -210.312762)
		(width 0.14732)
		(layer "In13.Cu")
		(net "P5E_CPU1_PE2_RX_DP<2>")
	)
	(segment
		(start 160.086294 -411.000702)
		(end 160.086294 -406.2222)
		(width 0.14732)
		(layer "In13.Cu")
		(net "P5E_CPU1_PE2_RX_DP<2>")
	)
	(segment
		(start 123.200668 -216.739978)
		(end 123.199906 -216.740486)
		(width 0.0889)
		(layer "In13.Cu")
		(net "P5E_CPU1_PE2_RX_DP<2>")
	)
	(segment
		(start 152.602438 -434.993796)
		(end 152.128982 -434.993796)
		(width 0.14732)
		(layer "In13.Cu")
		(net "P5E_CPU1_PE2_RX_DP<2>")
	)
	(segment
		(start 145.936208 -210.312762)
		(end 145.936208 -210.140296)
		(width 0.14732)
		(layer "In13.Cu")
		(net "P5E_CPU1_PE2_RX_DP<2>")
	)
	(segment
		(start 123.994672 -211.862416)
		(end 123.994672 -213.257638)
		(width 0.14732)
		(layer "In13.Cu")
		(net "P5E_CPU1_PE2_RX_DP<2>")
	)
	(segment
		(start 123.199906 -216.740486)
		(end 123.197366 -216.74201)
		(width 0.0889)
		(layer "In13.Cu")
		(net "P5E_CPU1_PE2_RX_DP<2>")
	)
	(segment
		(start 123.013216 -220.319854)
		(end 123.013216 -220.334078)
		(width 0.0889)
		(layer "In13.Cu")
		(net "P5E_CPU1_PE2_RX_DP<2>")
	)
	(segment
		(start 144.836896 -209.040984)
		(end 144.66443 -209.040984)
		(width 0.14732)
		(layer "In13.Cu")
		(net "P5E_CPU1_PE2_RX_DP<2>")
	)
	(segment
		(start 146.417792 -210.62188)
		(end 146.245326 -210.62188)
		(width 0.14732)
		(layer "In13.Cu")
		(net "P5E_CPU1_PE2_RX_DP<2>")
	)
	(segment
		(start 123.952762 -213.8934)
		(end 123.953016 -213.893908)
		(width 0.0889)
		(layer "In13.Cu")
		(net "P5E_CPU1_PE2_RX_DP<2>")
	)
	(segment
		(start 123.670568 -215.926162)
		(end 123.661678 -215.931242)
		(width 0.0889)
		(layer "In13.Cu")
		(net "P5E_CPU1_PE2_RX_DP<2>")
	)
	(segment
		(start 123.19889 -219.015818)
		(end 123.200414 -219.01658)
		(width 0.0889)
		(layer "In13.Cu")
		(net "P5E_CPU1_PE2_RX_DP<2>")
	)
	(segment
		(start 152.128982 -434.993796)
		(end 151.792178 -434.656992)
		(width 0.14732)
		(layer "In13.Cu")
		(net "P5E_CPU1_PE2_RX_DP<2>")
	)
	(segment
		(start 124.422408 -214.424768)
		(end 124.422408 -214.644732)
		(width 0.0889)
		(layer "In13.Cu")
		(net "P5E_CPU1_PE2_RX_DP<2>")
	)
	(segment
		(start 123.994672 -213.279736)
		(end 123.952762 -213.321646)
		(width 0.0889)
		(layer "In13.Cu")
		(net "P5E_CPU1_PE2_RX_DP<2>")
	)
	(segment
		(start 137.226802 -201.430636)
		(end 133.265926 -201.430636)
		(width 0.14732)
		(layer "In13.Cu")
		(net "P5E_CPU1_PE2_RX_DP<2>")
	)
	(segment
		(start 145.627344 -209.831432)
		(end 145.454878 -209.831432)
		(width 0.14732)
		(layer "In13.Cu")
		(net "P5E_CPU1_PE2_RX_DP<2>")
	)
	(segment
		(start 153.89098 -321.897248)
		(end 150.84552 -308.546754)
		(width 0.14732)
		(layer "In13.Cu")
		(net "P5E_CPU1_PE2_RX_DP<2>")
	)
	(segment
		(start 123.483116 -216.25052)
		(end 123.483116 -216.260426)
		(width 0.0889)
		(layer "In13.Cu")
		(net "P5E_CPU1_PE2_RX_DP<2>")
	)
	(segment
		(start 122.785632 -220.773752)
		(end 122.761502 -220.862906)
		(width 0.0889)
		(layer "In13.Cu")
		(net "P5E_CPU1_PE2_RX_DP<2>")
	)
	(segment
		(start 144.66443 -209.040984)
		(end 144.355312 -208.731866)
		(width 0.14732)
		(layer "In13.Cu")
		(net "P5E_CPU1_PE2_RX_DP<2>")
	)
	(segment
		(start 145.454878 -209.831432)
		(end 145.14576 -209.522314)
		(width 0.14732)
		(layer "In13.Cu")
		(net "P5E_CPU1_PE2_RX_DP<2>")
	)
	(segment
		(start 161.803334 -404.50516)
		(end 161.803334 -399.614136)
		(width 0.14732)
		(layer "In13.Cu")
		(net "P5E_CPU1_PE2_RX_DP<2>")
	)
	(segment
		(start 160.086294 -406.2222)
		(end 161.803334 -404.50516)
		(width 0.14732)
		(layer "In13.Cu")
		(net "P5E_CPU1_PE2_RX_DP<2>")
	)
	(segment
		(start 123.200414 -219.01658)
		(end 123.203208 -219.018104)
		(width 0.0889)
		(layer "In13.Cu")
		(net "P5E_CPU1_PE2_RX_DP<2>")
	)
	(segment
		(start 152.750012 -435.14137)
		(end 152.602438 -434.993796)
		(width 0.14732)
		(layer "In13.Cu")
		(net "P5E_CPU1_PE2_RX_DP<2>")
	)
	(segment
		(start 150.84552 -308.546754)
		(end 154.986228 -253.490476)
		(width 0.14732)
		(layer "In13.Cu")
		(net "P5E_CPU1_PE2_RX_DP<2>")
	)
	(arc
		(start 123.483116 -219.515944)
		(mid 123.405005 -219.792893)
		(end 123.200668 -219.995496)
		(width 0.0889)
		(layer "In13.Cu")
		(net "P5E_CPU1_PE2_RX_DP<2>")
	)
	(arc
		(start 123.191778 -216.745058)
		(mid 123.060864 -216.881418)
		(end 123.013216 -217.064336)
		(width 0.0889)
		(layer "In13.Cu")
		(net "P5E_CPU1_PE2_RX_DP<2>")
	)
	(arc
		(start 124.131324 -215.117426)
		(mid 124.00407 -215.247392)
		(end 123.953016 -215.421972)
		(width 0.0889)
		(layer "In13.Cu")
		(net "P5E_CPU1_PE2_RX_DP<2>")
	)
	(arc
		(start 123.952762 -215.452198)
		(mid 123.873392 -215.725932)
		(end 123.670568 -215.926162)
		(width 0.0889)
		(layer "In13.Cu")
		(net "P5E_CPU1_PE2_RX_DP<2>")
	)
	(arc
		(start 123.483116 -216.260426)
		(mid 123.405005 -216.537375)
		(end 123.200668 -216.739978)
		(width 0.0889)
		(layer "In13.Cu")
		(net "P5E_CPU1_PE2_RX_DP<2>")
	)
	(arc
		(start 123.013216 -217.064336)
		(mid 123.060895 -217.247236)
		(end 123.191778 -217.383614)
		(width 0.0889)
		(layer "In13.Cu")
		(net "P5E_CPU1_PE2_RX_DP<2>")
	)
	(arc
		(start 124.137166 -214.093298)
		(mid 124.311129 -214.232062)
		(end 124.422408 -214.424768)
		(width 0.0889)
		(layer "In13.Cu")
		(net "P5E_CPU1_PE2_RX_DP<2>")
	)
	(arc
		(start 123.661678 -215.931242)
		(mid 123.530764 -216.067602)
		(end 123.483116 -216.25052)
		(width 0.0889)
		(layer "In13.Cu")
		(net "P5E_CPU1_PE2_RX_DP<2>")
	)
	(arc
		(start 122.802396 -220.760798)
		(mid 122.794074 -220.767353)
		(end 122.785632 -220.773752)
		(width 0.0889)
		(layer "In13.Cu")
		(net "P5E_CPU1_PE2_RX_DP<2>")
	)
	(arc
		(start 123.191778 -220.000576)
		(mid 123.060864 -220.136936)
		(end 123.013216 -220.319854)
		(width 0.0889)
		(layer "In13.Cu")
		(net "P5E_CPU1_PE2_RX_DP<2>")
	)
	(arc
		(start 123.191524 -218.372944)
		(mid 123.012927 -218.692222)
		(end 123.191524 -219.0115)
		(width 0.0889)
		(layer "In13.Cu")
		(net "P5E_CPU1_PE2_RX_DP<2>")
	)
	(arc
		(start 123.20651 -219.020136)
		(mid 123.409097 -219.226487)
		(end 123.483116 -219.506038)
		(width 0.0889)
		(layer "In13.Cu")
		(net "P5E_CPU1_PE2_RX_DP<2>")
	)
	(arc
		(start 123.953016 -215.421972)
		(mid 123.952819 -215.429337)
		(end 123.952762 -215.436704)
		(width 0.0889)
		(layer "In13.Cu")
		(net "P5E_CPU1_PE2_RX_DP<2>")
	)
	(arc
		(start 123.953016 -213.893908)
		(mid 124.028021 -214.009367)
		(end 124.137166 -214.093298)
		(width 0.0889)
		(layer "In13.Cu")
		(net "P5E_CPU1_PE2_RX_DP<2>")
	)
	(arc
		(start 123.013216 -220.334078)
		(mid 122.954855 -220.570676)
		(end 122.802396 -220.760798)
		(width 0.0889)
		(layer "In13.Cu")
		(net "P5E_CPU1_PE2_RX_DP<2>")
	)
	(arc
		(start 124.422408 -214.644732)
		(mid 124.341497 -214.91486)
		(end 124.140214 -215.112346)
		(width 0.0889)
		(layer "In13.Cu")
		(net "P5E_CPU1_PE2_RX_DP<2>")
	)
	(arc
		(start 123.200668 -217.388694)
		(mid 123.483317 -217.874797)
		(end 123.20651 -218.364308)
		(width 0.0889)
		(layer "In13.Cu")
		(net "P5E_CPU1_PE2_RX_DP<2>")
	)
	(segment
		(start 121.508266 -222.48368)
		(end 121.508266 -221.947994)
		(width 0.13208)
		(layer "F.Cu")
		(net "P5E_CPU1_PE2_RX_DP<1>")
	)
	(segment
		(start 121.508266 -221.947994)
		(end 121.508012 -221.94774)
		(width 0.13208)
		(layer "F.Cu")
		(net "P5E_CPU1_PE2_RX_DP<1>")
	)
	(segment
		(start 132.856478 -200.490836)
		(end 124.042678 -209.304636)
		(width 0.14732)
		(layer "In13.Cu")
		(net "P5E_CPU1_PE2_RX_DP<1>")
	)
	(segment
		(start 163.041076 -328.080116)
		(end 162.759136 -326.48271)
		(width 0.14732)
		(layer "In13.Cu")
		(net "P5E_CPU1_PE2_RX_DP<1>")
	)
	(segment
		(start 153.792174 -433.685442)
		(end 153.792174 -424.43273)
		(width 0.14732)
		(layer "In13.Cu")
		(net "P5E_CPU1_PE2_RX_DP<1>")
	)
	(segment
		(start 122.730768 -215.926162)
		(end 122.721878 -215.931242)
		(width 0.0889)
		(layer "In13.Cu")
		(net "P5E_CPU1_PE2_RX_DP<1>")
	)
	(segment
		(start 162.450526 -326.04202)
		(end 161.91611 -325.667878)
		(width 0.14732)
		(layer "In13.Cu")
		(net "P5E_CPU1_PE2_RX_DP<1>")
	)
	(segment
		(start 122.260614 -219.01658)
		(end 122.26671 -219.020136)
		(width 0.0889)
		(layer "In13.Cu")
		(net "P5E_CPU1_PE2_RX_DP<1>")
	)
	(segment
		(start 163.825682 -361.225846)
		(end 164.512498 -345.92768)
		(width 0.14732)
		(layer "In13.Cu")
		(net "P5E_CPU1_PE2_RX_DP<1>")
	)
	(segment
		(start 164.866574 -404.50516)
		(end 164.866574 -400.460718)
		(width 0.14732)
		(layer "In13.Cu")
		(net "P5E_CPU1_PE2_RX_DP<1>")
	)
	(segment
		(start 155.970224 -253.48057)
		(end 155.760928 -247.251982)
		(width 0.14732)
		(layer "In13.Cu")
		(net "P5E_CPU1_PE2_RX_DP<1>")
	)
	(segment
		(start 154.11831 -434.011578)
		(end 153.792174 -433.685442)
		(width 0.14732)
		(layer "In13.Cu")
		(net "P5E_CPU1_PE2_RX_DP<1>")
	)
	(segment
		(start 151.78786 -308.440328)
		(end 155.970224 -253.48057)
		(width 0.14732)
		(layer "In13.Cu")
		(net "P5E_CPU1_PE2_RX_DP<1>")
	)
	(segment
		(start 160.351724 -325.392034)
		(end 156.30144 -322.463922)
		(width 0.14732)
		(layer "In13.Cu")
		(net "P5E_CPU1_PE2_RX_DP<1>")
	)
	(segment
		(start 122.26671 -221.619826)
		(end 122.245882 -221.632018)
		(width 0.0889)
		(layer "In13.Cu")
		(net "P5E_CPU1_PE2_RX_DP<1>")
	)
	(segment
		(start 164.56152 -395.64183)
		(end 164.42944 -395.525752)
		(width 0.14732)
		(layer "In13.Cu")
		(net "P5E_CPU1_PE2_RX_DP<1>")
	)
	(segment
		(start 161.91611 -325.667878)
		(end 160.351724 -325.392034)
		(width 0.14732)
		(layer "In13.Cu")
		(net "P5E_CPU1_PE2_RX_DP<1>")
	)
	(segment
		(start 163.149534 -406.2222)
		(end 164.866574 -404.50516)
		(width 0.14732)
		(layer "In13.Cu")
		(net "P5E_CPU1_PE2_RX_DP<1>")
	)
	(segment
		(start 154.314398 -319.463928)
		(end 151.78786 -308.440328)
		(width 0.14732)
		(layer "In13.Cu")
		(net "P5E_CPU1_PE2_RX_DP<1>")
	)
	(segment
		(start 164.518086 -394.9573)
		(end 164.417756 -393.370054)
		(width 0.14732)
		(layer "In13.Cu")
		(net "P5E_CPU1_PE2_RX_DP<1>")
	)
	(segment
		(start 123.012962 -215.436704)
		(end 123.012962 -215.452198)
		(width 0.0889)
		(layer "In13.Cu")
		(net "P5E_CPU1_PE2_RX_DP<1>")
	)
	(segment
		(start 154.602434 -434.011578)
		(end 154.11831 -434.011578)
		(width 0.14732)
		(layer "In13.Cu")
		(net "P5E_CPU1_PE2_RX_DP<1>")
	)
	(segment
		(start 137.650728 -200.490836)
		(end 132.856478 -200.490836)
		(width 0.14732)
		(layer "In13.Cu")
		(net "P5E_CPU1_PE2_RX_DP<1>")
	)
	(segment
		(start 124.042678 -209.304636)
		(end 123.054872 -211.689442)
		(width 0.14732)
		(layer "In13.Cu")
		(net "P5E_CPU1_PE2_RX_DP<1>")
	)
	(segment
		(start 156.30144 -322.463922)
		(end 154.314398 -319.463928)
		(width 0.14732)
		(layer "In13.Cu")
		(net "P5E_CPU1_PE2_RX_DP<1>")
	)
	(segment
		(start 122.26671 -216.736422)
		(end 122.261376 -216.73947)
		(width 0.0889)
		(layer "In13.Cu")
		(net "P5E_CPU1_PE2_RX_DP<1>")
	)
	(segment
		(start 153.792174 -424.43273)
		(end 163.149534 -410.741114)
		(width 0.14732)
		(layer "In13.Cu")
		(net "P5E_CPU1_PE2_RX_DP<1>")
	)
	(segment
		(start 122.543316 -221.1197)
		(end 122.543316 -221.133924)
		(width 0.0889)
		(layer "In13.Cu")
		(net "P5E_CPU1_PE2_RX_DP<1>")
	)
	(segment
		(start 122.261376 -216.73947)
		(end 122.260614 -216.739978)
		(width 0.0889)
		(layer "In13.Cu")
		(net "P5E_CPU1_PE2_RX_DP<1>")
	)
	(segment
		(start 122.073416 -217.0557)
		(end 122.073416 -217.072972)
		(width 0.0889)
		(layer "In13.Cu")
		(net "P5E_CPU1_PE2_RX_DP<1>")
	)
	(segment
		(start 123.012962 -213.8934)
		(end 123.013216 -213.893908)
		(width 0.0889)
		(layer "In13.Cu")
		(net "P5E_CPU1_PE2_RX_DP<1>")
	)
	(segment
		(start 122.073416 -220.311218)
		(end 122.073416 -220.32849)
		(width 0.0889)
		(layer "In13.Cu")
		(net "P5E_CPU1_PE2_RX_DP<1>")
	)
	(segment
		(start 148.485606 -211.325714)
		(end 137.650728 -200.490836)
		(width 0.14732)
		(layer "In13.Cu")
		(net "P5E_CPU1_PE2_RX_DP<1>")
	)
	(segment
		(start 162.759136 -326.48271)
		(end 162.450526 -326.04202)
		(width 0.14732)
		(layer "In13.Cu")
		(net "P5E_CPU1_PE2_RX_DP<1>")
	)
	(segment
		(start 123.482608 -214.424768)
		(end 123.482608 -214.644732)
		(width 0.0889)
		(layer "In13.Cu")
		(net "P5E_CPU1_PE2_RX_DP<1>")
	)
	(segment
		(start 123.054872 -213.257638)
		(end 123.054872 -213.279736)
		(width 0.0889)
		(layer "In13.Cu")
		(net "P5E_CPU1_PE2_RX_DP<1>")
	)
	(segment
		(start 121.75363 -221.652846)
		(end 121.664476 -221.676722)
		(width 0.0889)
		(layer "In13.Cu")
		(net "P5E_CPU1_PE2_RX_DP<1>")
	)
	(segment
		(start 122.26671 -219.99194)
		(end 122.261376 -219.994988)
		(width 0.0889)
		(layer "In13.Cu")
		(net "P5E_CPU1_PE2_RX_DP<1>")
	)
	(segment
		(start 154.750008 -434.48986)
		(end 154.750008 -434.159152)
		(width 0.14732)
		(layer "In13.Cu")
		(net "P5E_CPU1_PE2_RX_DP<1>")
	)
	(segment
		(start 122.543316 -217.864182)
		(end 122.543316 -217.878406)
		(width 0.0889)
		(layer "In13.Cu")
		(net "P5E_CPU1_PE2_RX_DP<1>")
	)
	(segment
		(start 123.054872 -213.279736)
		(end 123.012962 -213.321646)
		(width 0.0889)
		(layer "In13.Cu")
		(net "P5E_CPU1_PE2_RX_DP<1>")
	)
	(segment
		(start 123.012962 -213.321646)
		(end 123.012962 -213.8934)
		(width 0.0889)
		(layer "In13.Cu")
		(net "P5E_CPU1_PE2_RX_DP<1>")
	)
	(segment
		(start 164.417756 -393.370054)
		(end 163.825682 -361.225846)
		(width 0.14732)
		(layer "In13.Cu")
		(net "P5E_CPU1_PE2_RX_DP<1>")
	)
	(segment
		(start 123.200414 -215.112346)
		(end 123.191524 -215.117426)
		(width 0.0889)
		(layer "In13.Cu")
		(net "P5E_CPU1_PE2_RX_DP<1>")
	)
	(segment
		(start 164.401754 -395.08938)
		(end 164.518086 -394.9573)
		(width 0.14732)
		(layer "In13.Cu")
		(net "P5E_CPU1_PE2_RX_DP<1>")
	)
	(segment
		(start 164.42944 -395.525752)
		(end 164.401754 -395.08938)
		(width 0.14732)
		(layer "In13.Cu")
		(net "P5E_CPU1_PE2_RX_DP<1>")
	)
	(segment
		(start 122.261376 -219.994988)
		(end 122.260614 -219.995496)
		(width 0.0889)
		(layer "In13.Cu")
		(net "P5E_CPU1_PE2_RX_DP<1>")
	)
	(segment
		(start 123.054872 -211.689442)
		(end 123.054872 -213.257638)
		(width 0.14732)
		(layer "In13.Cu")
		(net "P5E_CPU1_PE2_RX_DP<1>")
	)
	(segment
		(start 164.866574 -400.460718)
		(end 164.56152 -395.64183)
		(width 0.14732)
		(layer "In13.Cu")
		(net "P5E_CPU1_PE2_RX_DP<1>")
	)
	(segment
		(start 155.760928 -247.251982)
		(end 152.343866 -224.606358)
		(width 0.14732)
		(layer "In13.Cu")
		(net "P5E_CPU1_PE2_RX_DP<1>")
	)
	(segment
		(start 152.343866 -224.606358)
		(end 148.485606 -211.325714)
		(width 0.14732)
		(layer "In13.Cu")
		(net "P5E_CPU1_PE2_RX_DP<1>")
	)
	(segment
		(start 121.664476 -221.676722)
		(end 121.508012 -221.94774)
		(width 0.0889)
		(layer "In13.Cu")
		(net "P5E_CPU1_PE2_RX_DP<1>")
	)
	(segment
		(start 164.512498 -345.92768)
		(end 164.512498 -345.876372)
		(width 0.14732)
		(layer "In13.Cu")
		(net "P5E_CPU1_PE2_RX_DP<1>")
	)
	(segment
		(start 163.149534 -410.741114)
		(end 163.149534 -406.2222)
		(width 0.14732)
		(layer "In13.Cu")
		(net "P5E_CPU1_PE2_RX_DP<1>")
	)
	(segment
		(start 164.512498 -345.876372)
		(end 163.041076 -328.080116)
		(width 0.14732)
		(layer "In13.Cu")
		(net "P5E_CPU1_PE2_RX_DP<1>")
	)
	(segment
		(start 154.750008 -434.159152)
		(end 154.602434 -434.011578)
		(width 0.14732)
		(layer "In13.Cu")
		(net "P5E_CPU1_PE2_RX_DP<1>")
	)
	(segment
		(start 122.26671 -218.364308)
		(end 122.266456 -218.364562)
		(width 0.0889)
		(layer "In13.Cu")
		(net "P5E_CPU1_PE2_RX_DP<1>")
	)
	(segment
		(start 122.266456 -218.364562)
		(end 122.253756 -218.371674)
		(width 0.0889)
		(layer "In13.Cu")
		(net "P5E_CPU1_PE2_RX_DP<1>")
	)
	(segment
		(start 122.251724 -219.0115)
		(end 122.260614 -219.01658)
		(width 0.0889)
		(layer "In13.Cu")
		(net "P5E_CPU1_PE2_RX_DP<1>")
	)
	(segment
		(start 122.253756 -218.371674)
		(end 122.251724 -218.372944)
		(width 0.0889)
		(layer "In13.Cu")
		(net "P5E_CPU1_PE2_RX_DP<1>")
	)
	(arc
		(start 123.012962 -215.452198)
		(mid 122.933592 -215.725932)
		(end 122.730768 -215.926162)
		(width 0.0889)
		(layer "In13.Cu")
		(net "P5E_CPU1_PE2_RX_DP<1>")
	)
	(arc
		(start 122.543316 -217.878406)
		(mid 122.469325 -218.157972)
		(end 122.26671 -218.364308)
		(width 0.0889)
		(layer "In13.Cu")
		(net "P5E_CPU1_PE2_RX_DP<1>")
	)
	(arc
		(start 122.721878 -215.931242)
		(mid 122.590964 -216.067602)
		(end 122.543316 -216.25052)
		(width 0.0889)
		(layer "In13.Cu")
		(net "P5E_CPU1_PE2_RX_DP<1>")
	)
	(arc
		(start 122.260614 -219.995496)
		(mid 122.125681 -220.12885)
		(end 122.073416 -220.311218)
		(width 0.0889)
		(layer "In13.Cu")
		(net "P5E_CPU1_PE2_RX_DP<1>")
	)
	(arc
		(start 122.251724 -218.372944)
		(mid 122.073127 -218.692222)
		(end 122.251724 -219.0115)
		(width 0.0889)
		(layer "In13.Cu")
		(net "P5E_CPU1_PE2_RX_DP<1>")
	)
	(arc
		(start 123.482608 -214.644732)
		(mid 123.401697 -214.91486)
		(end 123.200414 -215.112346)
		(width 0.0889)
		(layer "In13.Cu")
		(net "P5E_CPU1_PE2_RX_DP<1>")
	)
	(arc
		(start 123.013216 -213.893908)
		(mid 123.088221 -214.009367)
		(end 123.197366 -214.093298)
		(width 0.0889)
		(layer "In13.Cu")
		(net "P5E_CPU1_PE2_RX_DP<1>")
	)
	(arc
		(start 122.26671 -219.020136)
		(mid 122.543284 -219.506038)
		(end 122.26671 -219.99194)
		(width 0.0889)
		(layer "In13.Cu")
		(net "P5E_CPU1_PE2_RX_DP<1>")
	)
	(arc
		(start 122.260614 -216.739978)
		(mid 122.125681 -216.873332)
		(end 122.073416 -217.0557)
		(width 0.0889)
		(layer "In13.Cu")
		(net "P5E_CPU1_PE2_RX_DP<1>")
	)
	(arc
		(start 121.773696 -221.660974)
		(mid 121.763625 -221.657005)
		(end 121.75363 -221.652846)
		(width 0.0889)
		(layer "In13.Cu")
		(net "P5E_CPU1_PE2_RX_DP<1>")
	)
	(arc
		(start 122.245882 -221.632018)
		(mid 122.012967 -221.698229)
		(end 121.773696 -221.660974)
		(width 0.0889)
		(layer "In13.Cu")
		(net "P5E_CPU1_PE2_RX_DP<1>")
	)
	(arc
		(start 122.260614 -217.388694)
		(mid 122.464095 -217.589498)
		(end 122.543316 -217.864182)
		(width 0.0889)
		(layer "In13.Cu")
		(net "P5E_CPU1_PE2_RX_DP<1>")
	)
	(arc
		(start 122.543316 -221.133924)
		(mid 122.469325 -221.41349)
		(end 122.26671 -221.619826)
		(width 0.0889)
		(layer "In13.Cu")
		(net "P5E_CPU1_PE2_RX_DP<1>")
	)
	(arc
		(start 122.073416 -217.072972)
		(mid 122.125686 -217.255337)
		(end 122.260614 -217.388694)
		(width 0.0889)
		(layer "In13.Cu")
		(net "P5E_CPU1_PE2_RX_DP<1>")
	)
	(arc
		(start 122.073416 -220.32849)
		(mid 122.125686 -220.510855)
		(end 122.260614 -220.644212)
		(width 0.0889)
		(layer "In13.Cu")
		(net "P5E_CPU1_PE2_RX_DP<1>")
	)
	(arc
		(start 123.013216 -215.421972)
		(mid 123.013019 -215.429337)
		(end 123.012962 -215.436704)
		(width 0.0889)
		(layer "In13.Cu")
		(net "P5E_CPU1_PE2_RX_DP<1>")
	)
	(arc
		(start 123.191524 -215.117426)
		(mid 123.06427 -215.247392)
		(end 123.013216 -215.421972)
		(width 0.0889)
		(layer "In13.Cu")
		(net "P5E_CPU1_PE2_RX_DP<1>")
	)
	(arc
		(start 123.197366 -214.093298)
		(mid 123.371329 -214.232062)
		(end 123.482608 -214.424768)
		(width 0.0889)
		(layer "In13.Cu")
		(net "P5E_CPU1_PE2_RX_DP<1>")
	)
	(arc
		(start 122.543316 -216.25052)
		(mid 122.469325 -216.530086)
		(end 122.26671 -216.736422)
		(width 0.0889)
		(layer "In13.Cu")
		(net "P5E_CPU1_PE2_RX_DP<1>")
	)
	(arc
		(start 122.260614 -220.644212)
		(mid 122.464095 -220.845016)
		(end 122.543316 -221.1197)
		(width 0.0889)
		(layer "In13.Cu")
		(net "P5E_CPU1_PE2_RX_DP<1>")
	)
	(segment
		(start 134.665466 -221.947994)
		(end 134.665212 -221.94774)
		(width 0.13208)
		(layer "F.Cu")
		(net "P5E_CPU1_PE2_RX_DP<15>")
	)
	(segment
		(start 134.665466 -222.48368)
		(end 134.665466 -221.947994)
		(width 0.13208)
		(layer "F.Cu")
		(net "P5E_CPU1_PE2_RX_DP<15>")
	)
	(segment
		(start 135.322564 -222.437198)
		(end 135.318754 -222.434912)
		(width 0.0889)
		(layer "In13.Cu")
		(net "P5E_CPU1_PE2_RX_DP<15>")
	)
	(segment
		(start 134.899908 -221.655894)
		(end 134.821676 -221.676722)
		(width 0.0889)
		(layer "In13.Cu")
		(net "P5E_CPU1_PE2_RX_DP<15>")
	)
	(segment
		(start 140.188442 -257.006852)
		(end 138.768836 -254.979932)
		(width 0.14732)
		(layer "In13.Cu")
		(net "P5E_CPU1_PE2_RX_DP<15>")
	)
	(segment
		(start 137.233406 -250.579636)
		(end 137.684002 -248.024142)
		(width 0.14732)
		(layer "In13.Cu")
		(net "P5E_CPU1_PE2_RX_DP<15>")
	)
	(segment
		(start 136.261094 -224.064322)
		(end 136.256268 -224.061528)
		(width 0.0889)
		(layer "In13.Cu")
		(net "P5E_CPU1_PE2_RX_DP<15>")
	)
	(segment
		(start 121.981214 -404.50516)
		(end 121.981214 -400.214338)
		(width 0.14732)
		(layer "In13.Cu")
		(net "P5E_CPU1_PE2_RX_DP<15>")
	)
	(segment
		(start 138.30681 -245.965218)
		(end 138.566144 -232.175304)
		(width 0.14732)
		(layer "In13.Cu")
		(net "P5E_CPU1_PE2_RX_DP<15>")
	)
	(segment
		(start 135.331454 -222.442278)
		(end 135.322564 -222.437198)
		(width 0.0889)
		(layer "In13.Cu")
		(net "P5E_CPU1_PE2_RX_DP<15>")
	)
	(segment
		(start 139.25042 -290.759642)
		(end 139.25042 -290.75888)
		(width 0.14732)
		(layer "In13.Cu")
		(net "P5E_CPU1_PE2_RX_DP<15>")
	)
	(segment
		(start 124.74321 -433.617878)
		(end 120.264174 -410.206952)
		(width 0.14732)
		(layer "In13.Cu")
		(net "P5E_CPU1_PE2_RX_DP<15>")
	)
	(segment
		(start 150.52294 -345.227148)
		(end 148.739606 -335.116424)
		(width 0.14732)
		(layer "In13.Cu")
		(net "P5E_CPU1_PE2_RX_DP<15>")
	)
	(segment
		(start 134.821676 -221.676722)
		(end 134.665212 -221.94774)
		(width 0.0889)
		(layer "In13.Cu")
		(net "P5E_CPU1_PE2_RX_DP<15>")
	)
	(segment
		(start 138.309096 -310.04637)
		(end 139.25042 -290.759642)
		(width 0.14732)
		(layer "In13.Cu")
		(net "P5E_CPU1_PE2_RX_DP<15>")
	)
	(segment
		(start 125.602492 -433.993798)
		(end 125.11913 -433.993798)
		(width 0.14732)
		(layer "In13.Cu")
		(net "P5E_CPU1_PE2_RX_DP<15>")
	)
	(segment
		(start 136.271254 -224.070164)
		(end 136.271254 -224.070418)
		(width 0.0889)
		(layer "In13.Cu")
		(net "P5E_CPU1_PE2_RX_DP<15>")
	)
	(segment
		(start 136.267952 -224.068386)
		(end 136.265412 -224.067116)
		(width 0.0889)
		(layer "In13.Cu")
		(net "P5E_CPU1_PE2_RX_DP<15>")
	)
	(segment
		(start 139.250674 -290.758372)
		(end 139.25042 -290.758372)
		(width 0.14732)
		(layer "In13.Cu")
		(net "P5E_CPU1_PE2_RX_DP<15>")
	)
	(segment
		(start 139.25042 -290.758372)
		(end 140.189966 -271.50695)
		(width 0.14732)
		(layer "In13.Cu")
		(net "P5E_CPU1_PE2_RX_DP<15>")
	)
	(segment
		(start 149.520402 -358.362758)
		(end 150.52294 -345.227148)
		(width 0.14732)
		(layer "In13.Cu")
		(net "P5E_CPU1_PE2_RX_DP<15>")
	)
	(segment
		(start 137.675366 -226.207066)
		(end 137.675366 -226.147122)
		(width 0.0889)
		(layer "In13.Cu")
		(net "P5E_CPU1_PE2_RX_DP<15>")
	)
	(segment
		(start 120.264174 -410.206952)
		(end 120.264174 -406.2222)
		(width 0.14732)
		(layer "In13.Cu")
		(net "P5E_CPU1_PE2_RX_DP<15>")
	)
	(segment
		(start 140.189966 -271.50695)
		(end 140.189966 -271.507204)
		(width 0.14732)
		(layer "In13.Cu")
		(net "P5E_CPU1_PE2_RX_DP<15>")
	)
	(segment
		(start 138.566144 -232.175304)
		(end 138.086338 -226.618038)
		(width 0.14732)
		(layer "In13.Cu")
		(net "P5E_CPU1_PE2_RX_DP<15>")
	)
	(segment
		(start 136.449816 -224.399348)
		(end 136.449816 -224.389442)
		(width 0.0889)
		(layer "In13.Cu")
		(net "P5E_CPU1_PE2_RX_DP<15>")
	)
	(segment
		(start 121.981214 -400.214338)
		(end 122.645932 -398.963896)
		(width 0.14732)
		(layer "In13.Cu")
		(net "P5E_CPU1_PE2_RX_DP<15>")
	)
	(segment
		(start 138.086338 -226.618038)
		(end 137.69086 -226.22256)
		(width 0.14732)
		(layer "In13.Cu")
		(net "P5E_CPU1_PE2_RX_DP<15>")
	)
	(segment
		(start 141.047216 -259.7023)
		(end 140.188442 -257.006852)
		(width 0.14732)
		(layer "In13.Cu")
		(net "P5E_CPU1_PE2_RX_DP<15>")
	)
	(segment
		(start 139.250674 -290.758626)
		(end 139.250674 -290.758372)
		(width 0.14732)
		(layer "In13.Cu")
		(net "P5E_CPU1_PE2_RX_DP<15>")
	)
	(segment
		(start 138.768836 -254.979932)
		(end 138.168126 -253.529846)
		(width 0.14732)
		(layer "In13.Cu")
		(net "P5E_CPU1_PE2_RX_DP<15>")
	)
	(segment
		(start 120.264174 -406.2222)
		(end 121.981214 -404.50516)
		(width 0.14732)
		(layer "In13.Cu")
		(net "P5E_CPU1_PE2_RX_DP<15>")
	)
	(segment
		(start 137.684002 -248.024142)
		(end 138.30681 -245.965218)
		(width 0.14732)
		(layer "In13.Cu")
		(net "P5E_CPU1_PE2_RX_DP<15>")
	)
	(segment
		(start 125.11913 -433.993798)
		(end 124.74321 -433.617878)
		(width 0.14732)
		(layer "In13.Cu")
		(net "P5E_CPU1_PE2_RX_DP<15>")
	)
	(segment
		(start 145.18894 -369.137184)
		(end 149.520402 -358.362758)
		(width 0.14732)
		(layer "In13.Cu")
		(net "P5E_CPU1_PE2_RX_DP<15>")
	)
	(segment
		(start 135.510016 -222.780098)
		(end 135.510016 -222.761556)
		(width 0.0889)
		(layer "In13.Cu")
		(net "P5E_CPU1_PE2_RX_DP<15>")
	)
	(segment
		(start 136.271254 -224.070418)
		(end 136.267952 -224.068386)
		(width 0.0889)
		(layer "In13.Cu")
		(net "P5E_CPU1_PE2_RX_DP<15>")
	)
	(segment
		(start 135.314944 -222.43288)
		(end 135.310372 -222.430086)
		(width 0.0889)
		(layer "In13.Cu")
		(net "P5E_CPU1_PE2_RX_DP<15>")
	)
	(segment
		(start 137.69086 -226.22256)
		(end 137.675366 -226.207066)
		(width 0.0889)
		(layer "In13.Cu")
		(net "P5E_CPU1_PE2_RX_DP<15>")
	)
	(segment
		(start 136.741154 -224.88398)
		(end 136.732264 -224.8789)
		(width 0.0889)
		(layer "In13.Cu")
		(net "P5E_CPU1_PE2_RX_DP<15>")
	)
	(segment
		(start 122.645932 -398.963896)
		(end 145.18894 -369.137184)
		(width 0.14732)
		(layer "In13.Cu")
		(net "P5E_CPU1_PE2_RX_DP<15>")
	)
	(segment
		(start 136.919716 -225.213164)
		(end 136.919716 -225.203258)
		(width 0.0889)
		(layer "In13.Cu")
		(net "P5E_CPU1_PE2_RX_DP<15>")
	)
	(segment
		(start 142.772384 -328.442066)
		(end 138.309096 -310.04637)
		(width 0.14732)
		(layer "In13.Cu")
		(net "P5E_CPU1_PE2_RX_DP<15>")
	)
	(segment
		(start 136.26338 -224.065846)
		(end 136.261094 -224.064322)
		(width 0.0889)
		(layer "In13.Cu")
		(net "P5E_CPU1_PE2_RX_DP<15>")
	)
	(segment
		(start 137.675366 -226.147122)
		(end 137.280142 -225.751898)
		(width 0.0889)
		(layer "In13.Cu")
		(net "P5E_CPU1_PE2_RX_DP<15>")
	)
	(segment
		(start 138.168126 -253.529846)
		(end 137.614152 -252.73889)
		(width 0.14732)
		(layer "In13.Cu")
		(net "P5E_CPU1_PE2_RX_DP<15>")
	)
	(segment
		(start 125.750066 -434.48986)
		(end 125.750066 -434.141372)
		(width 0.14732)
		(layer "In13.Cu")
		(net "P5E_CPU1_PE2_RX_DP<15>")
	)
	(segment
		(start 135.979662 -223.575626)
		(end 135.979662 -223.56699)
		(width 0.0889)
		(layer "In13.Cu")
		(net "P5E_CPU1_PE2_RX_DP<15>")
	)
	(segment
		(start 137.614152 -252.73889)
		(end 137.233406 -250.579636)
		(width 0.14732)
		(layer "In13.Cu")
		(net "P5E_CPU1_PE2_RX_DP<15>")
	)
	(segment
		(start 125.750066 -434.141372)
		(end 125.602492 -433.993798)
		(width 0.14732)
		(layer "In13.Cu")
		(net "P5E_CPU1_PE2_RX_DP<15>")
	)
	(segment
		(start 140.189966 -271.507204)
		(end 141.047216 -259.7023)
		(width 0.14732)
		(layer "In13.Cu")
		(net "P5E_CPU1_PE2_RX_DP<15>")
	)
	(segment
		(start 136.265412 -224.067116)
		(end 136.26338 -224.065846)
		(width 0.0889)
		(layer "In13.Cu")
		(net "P5E_CPU1_PE2_RX_DP<15>")
	)
	(segment
		(start 139.25042 -290.75888)
		(end 139.250674 -290.758626)
		(width 0.14732)
		(layer "In13.Cu")
		(net "P5E_CPU1_PE2_RX_DP<15>")
	)
	(segment
		(start 148.739606 -335.116424)
		(end 142.772384 -328.442066)
		(width 0.14732)
		(layer "In13.Cu")
		(net "P5E_CPU1_PE2_RX_DP<15>")
	)
	(segment
		(start 135.318754 -222.434912)
		(end 135.314944 -222.43288)
		(width 0.0889)
		(layer "In13.Cu")
		(net "P5E_CPU1_PE2_RX_DP<15>")
	)
	(arc
		(start 135.039862 -221.94774)
		(mid 135.003002 -221.785943)
		(end 134.899908 -221.655894)
		(width 0.0889)
		(layer "In13.Cu")
		(net "P5E_CPU1_PE2_RX_DP<15>")
	)
	(arc
		(start 136.919716 -225.203258)
		(mid 136.872037 -225.020358)
		(end 136.741154 -224.88398)
		(width 0.0889)
		(layer "In13.Cu")
		(net "P5E_CPU1_PE2_RX_DP<15>")
	)
	(arc
		(start 137.202164 -225.692716)
		(mid 137.191552 -225.686355)
		(end 137.181082 -225.679762)
		(width 0.0889)
		(layer "In13.Cu")
		(net "P5E_CPU1_PE2_RX_DP<15>")
	)
	(arc
		(start 136.732264 -224.8789)
		(mid 136.527929 -224.676295)
		(end 136.449816 -224.399348)
		(width 0.0889)
		(layer "In13.Cu")
		(net "P5E_CPU1_PE2_RX_DP<15>")
	)
	(arc
		(start 135.979662 -223.56699)
		(mid 135.927392 -223.384625)
		(end 135.792464 -223.251268)
		(width 0.0889)
		(layer "In13.Cu")
		(net "P5E_CPU1_PE2_RX_DP<15>")
	)
	(arc
		(start 135.310372 -222.430086)
		(mid 135.112144 -222.224238)
		(end 135.039862 -221.94774)
		(width 0.0889)
		(layer "In13.Cu")
		(net "P5E_CPU1_PE2_RX_DP<15>")
	)
	(arc
		(start 137.280142 -225.751898)
		(mid 137.243092 -225.719752)
		(end 137.202164 -225.692716)
		(width 0.0889)
		(layer "In13.Cu")
		(net "P5E_CPU1_PE2_RX_DP<15>")
	)
	(arc
		(start 135.792464 -223.251268)
		(mid 135.590178 -223.052287)
		(end 135.510016 -222.780098)
		(width 0.0889)
		(layer "In13.Cu")
		(net "P5E_CPU1_PE2_RX_DP<15>")
	)
	(arc
		(start 136.256268 -224.061528)
		(mid 136.053681 -223.855177)
		(end 135.979662 -223.575626)
		(width 0.0889)
		(layer "In13.Cu")
		(net "P5E_CPU1_PE2_RX_DP<15>")
	)
	(arc
		(start 136.449816 -224.389442)
		(mid 136.402137 -224.206542)
		(end 136.271254 -224.070164)
		(width 0.0889)
		(layer "In13.Cu")
		(net "P5E_CPU1_PE2_RX_DP<15>")
	)
	(arc
		(start 135.510016 -222.761556)
		(mid 135.462337 -222.578656)
		(end 135.331454 -222.442278)
		(width 0.0889)
		(layer "In13.Cu")
		(net "P5E_CPU1_PE2_RX_DP<15>")
	)
	(arc
		(start 137.181082 -225.679762)
		(mid 136.99169 -225.479338)
		(end 136.919716 -225.213164)
		(width 0.0889)
		(layer "In13.Cu")
		(net "P5E_CPU1_PE2_RX_DP<15>")
	)
	(segment
		(start 134.195566 -221.133924)
		(end 134.195566 -221.669864)
		(width 0.13208)
		(layer "F.Cu")
		(net "P5E_CPU1_PE2_RX_DP<14>")
	)
	(segment
		(start 142.072868 -259.517896)
		(end 141.307312 -256.750566)
		(width 0.14732)
		(layer "In13.Cu")
		(net "P5E_CPU1_PE2_RX_DP<14>")
	)
	(segment
		(start 138.620754 -224.88398)
		(end 138.611864 -224.8789)
		(width 0.0889)
		(layer "In13.Cu")
		(net "P5E_CPU1_PE2_RX_DP<14>")
	)
	(segment
		(start 140.337286 -255.06045)
		(end 139.995148 -254.252476)
		(width 0.14732)
		(layer "In13.Cu")
		(net "P5E_CPU1_PE2_RX_DP<14>")
	)
	(segment
		(start 148.303742 -364.043976)
		(end 148.303996 -364.043722)
		(width 0.14732)
		(layer "In13.Cu")
		(net "P5E_CPU1_PE2_RX_DP<14>")
	)
	(segment
		(start 127.750062 -435.489858)
		(end 127.750062 -435.13375)
		(width 0.14732)
		(layer "In13.Cu")
		(net "P5E_CPU1_PE2_RX_DP<14>")
	)
	(segment
		(start 148.303996 -364.043722)
		(end 150.561548 -358.552496)
		(width 0.14732)
		(layer "In13.Cu")
		(net "P5E_CPU1_PE2_RX_DP<14>")
	)
	(segment
		(start 135.510016 -221.14383)
		(end 135.510016 -221.133924)
		(width 0.0889)
		(layer "In13.Cu")
		(net "P5E_CPU1_PE2_RX_DP<14>")
	)
	(segment
		(start 134.060184 -220.784928)
		(end 134.039102 -220.862906)
		(width 0.0889)
		(layer "In13.Cu")
		(net "P5E_CPU1_PE2_RX_DP<14>")
	)
	(segment
		(start 138.964416 -248.390664)
		(end 139.355068 -247.999758)
		(width 0.14732)
		(layer "In13.Cu")
		(net "P5E_CPU1_PE2_RX_DP<14>")
	)
	(segment
		(start 136.262364 -222.437198)
		(end 136.256268 -222.433642)
		(width 0.0889)
		(layer "In13.Cu")
		(net "P5E_CPU1_PE2_RX_DP<14>")
	)
	(segment
		(start 139.26566 -309.977028)
		(end 142.072868 -259.517896)
		(width 0.14732)
		(layer "In13.Cu")
		(net "P5E_CPU1_PE2_RX_DP<14>")
	)
	(segment
		(start 151.545544 -345.19997)
		(end 149.708362 -334.783684)
		(width 0.14732)
		(layer "In13.Cu")
		(net "P5E_CPU1_PE2_RX_DP<14>")
	)
	(segment
		(start 138.799316 -225.213164)
		(end 138.799316 -225.203258)
		(width 0.0889)
		(layer "In13.Cu")
		(net "P5E_CPU1_PE2_RX_DP<14>")
	)
	(segment
		(start 140.011404 -230.589836)
		(end 139.227052 -226.890072)
		(width 0.14732)
		(layer "In13.Cu")
		(net "P5E_CPU1_PE2_RX_DP<14>")
	)
	(segment
		(start 126.792228 -434.653436)
		(end 126.792228 -423.577766)
		(width 0.14732)
		(layer "In13.Cu")
		(net "P5E_CPU1_PE2_RX_DP<14>")
	)
	(segment
		(start 141.277594 -244.310154)
		(end 140.011404 -230.589836)
		(width 0.14732)
		(layer "In13.Cu")
		(net "P5E_CPU1_PE2_RX_DP<14>")
	)
	(segment
		(start 149.708362 -334.783684)
		(end 143.646144 -327.942702)
		(width 0.14732)
		(layer "In13.Cu")
		(net "P5E_CPU1_PE2_RX_DP<14>")
	)
	(segment
		(start 123.327414 -410.50337)
		(end 123.327414 -406.2222)
		(width 0.14732)
		(layer "In13.Cu")
		(net "P5E_CPU1_PE2_RX_DP<14>")
	)
	(segment
		(start 139.227052 -226.890072)
		(end 139.227052 -226.407218)
		(width 0.14732)
		(layer "In13.Cu")
		(net "P5E_CPU1_PE2_RX_DP<14>")
	)
	(segment
		(start 123.327414 -406.2222)
		(end 125.044454 -404.50516)
		(width 0.14732)
		(layer "In13.Cu")
		(net "P5E_CPU1_PE2_RX_DP<14>")
	)
	(segment
		(start 139.227052 -226.38512)
		(end 139.269216 -226.342956)
		(width 0.0889)
		(layer "In13.Cu")
		(net "P5E_CPU1_PE2_RX_DP<14>")
	)
	(segment
		(start 135.979662 -221.94774)
		(end 135.979662 -221.939104)
		(width 0.0889)
		(layer "In13.Cu")
		(net "P5E_CPU1_PE2_RX_DP<14>")
	)
	(segment
		(start 126.792228 -423.577766)
		(end 123.327414 -410.50337)
		(width 0.14732)
		(layer "In13.Cu")
		(net "P5E_CPU1_PE2_RX_DP<14>")
	)
	(segment
		(start 136.7409 -223.256348)
		(end 136.73201 -223.251268)
		(width 0.0889)
		(layer "In13.Cu")
		(net "P5E_CPU1_PE2_RX_DP<14>")
	)
	(segment
		(start 135.331454 -220.814646)
		(end 135.322564 -220.809566)
		(width 0.0889)
		(layer "In13.Cu")
		(net "P5E_CPU1_PE2_RX_DP<14>")
	)
	(segment
		(start 134.039102 -220.862906)
		(end 134.195566 -221.133924)
		(width 0.0889)
		(layer "In13.Cu")
		(net "P5E_CPU1_PE2_RX_DP<14>")
	)
	(segment
		(start 125.044454 -400.543268)
		(end 125.457712 -399.222468)
		(width 0.14732)
		(layer "In13.Cu")
		(net "P5E_CPU1_PE2_RX_DP<14>")
	)
	(segment
		(start 143.646144 -327.942702)
		(end 139.26566 -309.977028)
		(width 0.14732)
		(layer "In13.Cu")
		(net "P5E_CPU1_PE2_RX_DP<14>")
	)
	(segment
		(start 137.211054 -224.070164)
		(end 137.202164 -224.065084)
		(width 0.0889)
		(layer "In13.Cu")
		(net "P5E_CPU1_PE2_RX_DP<14>")
	)
	(segment
		(start 141.307312 -256.750566)
		(end 140.687806 -255.888236)
		(width 0.14732)
		(layer "In13.Cu")
		(net "P5E_CPU1_PE2_RX_DP<14>")
	)
	(segment
		(start 140.337032 -255.06045)
		(end 140.337286 -255.06045)
		(width 0.14732)
		(layer "In13.Cu")
		(net "P5E_CPU1_PE2_RX_DP<14>")
	)
	(segment
		(start 138.964416 -251.254514)
		(end 138.964416 -248.390664)
		(width 0.14732)
		(layer "In13.Cu")
		(net "P5E_CPU1_PE2_RX_DP<14>")
	)
	(segment
		(start 137.389616 -224.399348)
		(end 137.389616 -224.389442)
		(width 0.0889)
		(layer "In13.Cu")
		(net "P5E_CPU1_PE2_RX_DP<14>")
	)
	(segment
		(start 150.561548 -358.552496)
		(end 151.545544 -345.19997)
		(width 0.14732)
		(layer "In13.Cu")
		(net "P5E_CPU1_PE2_RX_DP<14>")
	)
	(segment
		(start 139.995148 -254.252476)
		(end 138.964416 -251.254514)
		(width 0.14732)
		(layer "In13.Cu")
		(net "P5E_CPU1_PE2_RX_DP<14>")
	)
	(segment
		(start 139.75715 -247.718326)
		(end 140.298424 -247.374156)
		(width 0.14732)
		(layer "In13.Cu")
		(net "P5E_CPU1_PE2_RX_DP<14>")
	)
	(segment
		(start 139.090654 -225.697796)
		(end 139.081764 -225.692716)
		(width 0.0889)
		(layer "In13.Cu")
		(net "P5E_CPU1_PE2_RX_DP<14>")
	)
	(segment
		(start 136.449562 -222.780098)
		(end 136.449562 -222.75292)
		(width 0.0889)
		(layer "In13.Cu")
		(net "P5E_CPU1_PE2_RX_DP<14>")
	)
	(segment
		(start 134.397496 -220.818202)
		(end 134.382764 -220.809566)
		(width 0.0889)
		(layer "In13.Cu")
		(net "P5E_CPU1_PE2_RX_DP<14>")
	)
	(segment
		(start 125.457712 -399.222468)
		(end 146.045936 -369.535456)
		(width 0.14732)
		(layer "In13.Cu")
		(net "P5E_CPU1_PE2_RX_DP<14>")
	)
	(segment
		(start 139.227052 -226.407218)
		(end 139.227052 -226.38512)
		(width 0.0889)
		(layer "In13.Cu")
		(net "P5E_CPU1_PE2_RX_DP<14>")
	)
	(segment
		(start 127.602488 -434.986176)
		(end 127.124968 -434.986176)
		(width 0.14732)
		(layer "In13.Cu")
		(net "P5E_CPU1_PE2_RX_DP<14>")
	)
	(segment
		(start 139.355068 -247.999758)
		(end 139.75715 -247.718326)
		(width 0.14732)
		(layer "In13.Cu")
		(net "P5E_CPU1_PE2_RX_DP<14>")
	)
	(segment
		(start 140.298424 -247.374156)
		(end 141.277594 -244.310154)
		(width 0.14732)
		(layer "In13.Cu")
		(net "P5E_CPU1_PE2_RX_DP<14>")
	)
	(segment
		(start 127.750062 -435.13375)
		(end 127.602488 -434.986176)
		(width 0.14732)
		(layer "In13.Cu")
		(net "P5E_CPU1_PE2_RX_DP<14>")
	)
	(segment
		(start 139.269216 -226.342956)
		(end 139.269216 -226.017074)
		(width 0.0889)
		(layer "In13.Cu")
		(net "P5E_CPU1_PE2_RX_DP<14>")
	)
	(segment
		(start 125.044454 -404.50516)
		(end 125.044454 -400.543268)
		(width 0.14732)
		(layer "In13.Cu")
		(net "P5E_CPU1_PE2_RX_DP<14>")
	)
	(segment
		(start 127.124968 -434.986176)
		(end 126.792228 -434.653436)
		(width 0.14732)
		(layer "In13.Cu")
		(net "P5E_CPU1_PE2_RX_DP<14>")
	)
	(segment
		(start 146.045936 -369.535456)
		(end 148.303742 -364.043976)
		(width 0.14732)
		(layer "In13.Cu")
		(net "P5E_CPU1_PE2_RX_DP<14>")
	)
	(segment
		(start 137.202164 -224.065084)
		(end 137.189972 -224.057972)
		(width 0.0889)
		(layer "In13.Cu")
		(net "P5E_CPU1_PE2_RX_DP<14>")
	)
	(segment
		(start 140.687806 -255.888236)
		(end 140.337032 -255.06045)
		(width 0.14732)
		(layer "In13.Cu")
		(net "P5E_CPU1_PE2_RX_DP<14>")
	)
	(arc
		(start 138.237468 -224.8789)
		(mid 137.954766 -224.954676)
		(end 137.672064 -224.8789)
		(width 0.0889)
		(layer "In13.Cu")
		(net "P5E_CPU1_PE2_RX_DP<14>")
	)
	(arc
		(start 138.799316 -225.203258)
		(mid 138.751637 -225.020358)
		(end 138.620754 -224.88398)
		(width 0.0889)
		(layer "In13.Cu")
		(net "P5E_CPU1_PE2_RX_DP<14>")
	)
	(arc
		(start 139.081764 -225.692716)
		(mid 138.877429 -225.490111)
		(end 138.799316 -225.213164)
		(width 0.0889)
		(layer "In13.Cu")
		(net "P5E_CPU1_PE2_RX_DP<14>")
	)
	(arc
		(start 135.510016 -221.133924)
		(mid 135.462337 -220.951024)
		(end 135.331454 -220.814646)
		(width 0.0889)
		(layer "In13.Cu")
		(net "P5E_CPU1_PE2_RX_DP<14>")
	)
	(arc
		(start 137.672064 -224.8789)
		(mid 137.467729 -224.676295)
		(end 137.389616 -224.399348)
		(width 0.0889)
		(layer "In13.Cu")
		(net "P5E_CPU1_PE2_RX_DP<14>")
	)
	(arc
		(start 139.269216 -226.017074)
		(mid 139.221537 -225.834174)
		(end 139.090654 -225.697796)
		(width 0.0889)
		(layer "In13.Cu")
		(net "P5E_CPU1_PE2_RX_DP<14>")
	)
	(arc
		(start 136.73201 -223.251268)
		(mid 136.529724 -223.052287)
		(end 136.449562 -222.780098)
		(width 0.0889)
		(layer "In13.Cu")
		(net "P5E_CPU1_PE2_RX_DP<14>")
	)
	(arc
		(start 136.256268 -222.433642)
		(mid 136.053681 -222.227291)
		(end 135.979662 -221.94774)
		(width 0.0889)
		(layer "In13.Cu")
		(net "P5E_CPU1_PE2_RX_DP<14>")
	)
	(arc
		(start 134.382764 -220.809566)
		(mid 134.224276 -220.760633)
		(end 134.060184 -220.784928)
		(width 0.0889)
		(layer "In13.Cu")
		(net "P5E_CPU1_PE2_RX_DP<14>")
	)
	(arc
		(start 136.919462 -223.575626)
		(mid 136.871783 -223.392726)
		(end 136.7409 -223.256348)
		(width 0.0889)
		(layer "In13.Cu")
		(net "P5E_CPU1_PE2_RX_DP<14>")
	)
	(arc
		(start 138.611864 -224.8789)
		(mid 138.424666 -224.828757)
		(end 138.237468 -224.8789)
		(width 0.0889)
		(layer "In13.Cu")
		(net "P5E_CPU1_PE2_RX_DP<14>")
	)
	(arc
		(start 137.189972 -224.057972)
		(mid 136.991744 -223.852124)
		(end 136.919462 -223.575626)
		(width 0.0889)
		(layer "In13.Cu")
		(net "P5E_CPU1_PE2_RX_DP<14>")
	)
	(arc
		(start 134.948168 -220.809566)
		(mid 134.673939 -220.885491)
		(end 134.397496 -220.818202)
		(width 0.0889)
		(layer "In13.Cu")
		(net "P5E_CPU1_PE2_RX_DP<14>")
	)
	(arc
		(start 135.792464 -221.623382)
		(mid 135.588129 -221.420777)
		(end 135.510016 -221.14383)
		(width 0.0889)
		(layer "In13.Cu")
		(net "P5E_CPU1_PE2_RX_DP<14>")
	)
	(arc
		(start 136.449562 -222.75292)
		(mid 136.397292 -222.570555)
		(end 136.262364 -222.437198)
		(width 0.0889)
		(layer "In13.Cu")
		(net "P5E_CPU1_PE2_RX_DP<14>")
	)
	(arc
		(start 135.979662 -221.939104)
		(mid 135.927392 -221.756739)
		(end 135.792464 -221.623382)
		(width 0.0889)
		(layer "In13.Cu")
		(net "P5E_CPU1_PE2_RX_DP<14>")
	)
	(arc
		(start 135.322564 -220.809566)
		(mid 135.135366 -220.759423)
		(end 134.948168 -220.809566)
		(width 0.0889)
		(layer "In13.Cu")
		(net "P5E_CPU1_PE2_RX_DP<14>")
	)
	(arc
		(start 137.389616 -224.389442)
		(mid 137.341937 -224.206542)
		(end 137.211054 -224.070164)
		(width 0.0889)
		(layer "In13.Cu")
		(net "P5E_CPU1_PE2_RX_DP<14>")
	)
	(segment
		(start 132.785866 -221.947994)
		(end 132.785612 -221.94774)
		(width 0.13208)
		(layer "F.Cu")
		(net "P5E_CPU1_PE2_RX_DP<13>")
	)
	(segment
		(start 132.785866 -222.48368)
		(end 132.785866 -221.947994)
		(width 0.13208)
		(layer "F.Cu")
		(net "P5E_CPU1_PE2_RX_DP<13>")
	)
	(segment
		(start 146.903694 -369.94973)
		(end 149.223476 -364.307628)
		(width 0.14732)
		(layer "In13.Cu")
		(net "P5E_CPU1_PE2_RX_DP<13>")
	)
	(segment
		(start 136.271254 -220.814646)
		(end 136.262364 -220.809566)
		(width 0.0889)
		(layer "In13.Cu")
		(net "P5E_CPU1_PE2_RX_DP<13>")
	)
	(segment
		(start 128.107694 -400.404838)
		(end 128.415034 -399.3388)
		(width 0.14732)
		(layer "In13.Cu")
		(net "P5E_CPU1_PE2_RX_DP<13>")
	)
	(segment
		(start 140.326618 -252.182884)
		(end 140.224764 -250.344686)
		(width 0.14732)
		(layer "In13.Cu")
		(net "P5E_CPU1_PE2_RX_DP<13>")
	)
	(segment
		(start 152.53081 -345.229688)
		(end 150.600156 -334.28178)
		(width 0.14732)
		(layer "In13.Cu")
		(net "P5E_CPU1_PE2_RX_DP<13>")
	)
	(segment
		(start 128.792224 -433.628546)
		(end 128.792224 -423.897044)
		(width 0.14732)
		(layer "In13.Cu")
		(net "P5E_CPU1_PE2_RX_DP<13>")
	)
	(segment
		(start 137.2108 -222.442278)
		(end 137.20191 -222.437198)
		(width 0.0889)
		(layer "In13.Cu")
		(net "P5E_CPU1_PE2_RX_DP<13>")
	)
	(segment
		(start 133.538468 -221.623382)
		(end 133.528054 -221.629478)
		(width 0.0889)
		(layer "In13.Cu")
		(net "P5E_CPU1_PE2_RX_DP<13>")
	)
	(segment
		(start 139.60221 -224.626678)
		(end 139.60221 -224.566734)
		(width 0.0889)
		(layer "In13.Cu")
		(net "P5E_CPU1_PE2_RX_DP<13>")
	)
	(segment
		(start 135.979916 -220.338396)
		(end 135.979916 -220.319854)
		(width 0.0889)
		(layer "In13.Cu")
		(net "P5E_CPU1_PE2_RX_DP<13>")
	)
	(segment
		(start 133.820916 -221.115382)
		(end 133.820916 -221.14383)
		(width 0.0889)
		(layer "In13.Cu")
		(net "P5E_CPU1_PE2_RX_DP<13>")
	)
	(segment
		(start 136.7409 -221.628462)
		(end 136.733026 -221.62389)
		(width 0.0889)
		(layer "In13.Cu")
		(net "P5E_CPU1_PE2_RX_DP<13>")
	)
	(segment
		(start 128.415034 -399.3388)
		(end 146.903694 -369.94973)
		(width 0.14732)
		(layer "In13.Cu")
		(net "P5E_CPU1_PE2_RX_DP<13>")
	)
	(segment
		(start 135.801354 -220.000576)
		(end 135.792464 -219.995496)
		(width 0.0889)
		(layer "In13.Cu")
		(net "P5E_CPU1_PE2_RX_DP<13>")
	)
	(segment
		(start 137.20191 -222.437198)
		(end 137.195814 -222.433642)
		(width 0.0889)
		(layer "In13.Cu")
		(net "P5E_CPU1_PE2_RX_DP<13>")
	)
	(segment
		(start 140.77315 -253.64821)
		(end 140.65631 -253.31547)
		(width 0.14732)
		(layer "In13.Cu")
		(net "P5E_CPU1_PE2_RX_DP<13>")
	)
	(segment
		(start 140.276834 -309.76189)
		(end 143.099536 -259.378704)
		(width 0.14732)
		(layer "In13.Cu")
		(net "P5E_CPU1_PE2_RX_DP<13>")
	)
	(segment
		(start 139.60221 -224.566734)
		(end 139.159742 -224.124266)
		(width 0.0889)
		(layer "In13.Cu")
		(net "P5E_CPU1_PE2_RX_DP<13>")
	)
	(segment
		(start 133.03123 -221.652846)
		(end 132.942076 -221.676722)
		(width 0.0889)
		(layer "In13.Cu")
		(net "P5E_CPU1_PE2_RX_DP<13>")
	)
	(segment
		(start 129.157476 -433.993798)
		(end 128.792224 -433.628546)
		(width 0.14732)
		(layer "In13.Cu")
		(net "P5E_CPU1_PE2_RX_DP<13>")
	)
	(segment
		(start 129.750058 -434.48986)
		(end 129.750058 -434.141372)
		(width 0.14732)
		(layer "In13.Cu")
		(net "P5E_CPU1_PE2_RX_DP<13>")
	)
	(segment
		(start 151.543004 -358.665526)
		(end 152.53081 -345.229688)
		(width 0.14732)
		(layer "In13.Cu")
		(net "P5E_CPU1_PE2_RX_DP<13>")
	)
	(segment
		(start 126.390654 -411.02915)
		(end 126.390654 -406.2222)
		(width 0.14732)
		(layer "In13.Cu")
		(net "P5E_CPU1_PE2_RX_DP<13>")
	)
	(segment
		(start 126.390654 -406.2222)
		(end 128.107694 -404.50516)
		(width 0.14732)
		(layer "In13.Cu")
		(net "P5E_CPU1_PE2_RX_DP<13>")
	)
	(segment
		(start 128.107694 -404.50516)
		(end 128.107694 -400.404838)
		(width 0.14732)
		(layer "In13.Cu")
		(net "P5E_CPU1_PE2_RX_DP<13>")
	)
	(segment
		(start 129.602484 -433.993798)
		(end 129.157476 -433.993798)
		(width 0.14732)
		(layer "In13.Cu")
		(net "P5E_CPU1_PE2_RX_DP<13>")
	)
	(segment
		(start 140.65631 -253.31547)
		(end 140.326618 -252.182884)
		(width 0.14732)
		(layer "In13.Cu")
		(net "P5E_CPU1_PE2_RX_DP<13>")
	)
	(segment
		(start 141.384528 -255.123188)
		(end 140.77315 -253.64821)
		(width 0.14732)
		(layer "In13.Cu")
		(net "P5E_CPU1_PE2_RX_DP<13>")
	)
	(segment
		(start 135.418068 -219.995496)
		(end 135.407654 -220.001592)
		(width 0.0889)
		(layer "In13.Cu")
		(net "P5E_CPU1_PE2_RX_DP<13>")
	)
	(segment
		(start 140.39596 -226.073208)
		(end 139.88415 -224.908618)
		(width 0.14732)
		(layer "In13.Cu")
		(net "P5E_CPU1_PE2_RX_DP<13>")
	)
	(segment
		(start 140.944346 -248.426732)
		(end 142.273528 -244.346476)
		(width 0.14732)
		(layer "In13.Cu")
		(net "P5E_CPU1_PE2_RX_DP<13>")
	)
	(segment
		(start 142.273528 -244.346476)
		(end 141.28496 -230.350568)
		(width 0.14732)
		(layer "In13.Cu")
		(net "P5E_CPU1_PE2_RX_DP<13>")
	)
	(segment
		(start 144.53997 -327.519284)
		(end 140.276834 -309.76189)
		(width 0.14732)
		(layer "In13.Cu")
		(net "P5E_CPU1_PE2_RX_DP<13>")
	)
	(segment
		(start 134.478014 -219.995496)
		(end 134.4676 -220.001592)
		(width 0.0889)
		(layer "In13.Cu")
		(net "P5E_CPU1_PE2_RX_DP<13>")
	)
	(segment
		(start 141.28496 -230.350568)
		(end 140.39596 -226.073208)
		(width 0.14732)
		(layer "In13.Cu")
		(net "P5E_CPU1_PE2_RX_DP<13>")
	)
	(segment
		(start 139.88415 -224.908618)
		(end 139.617704 -224.642172)
		(width 0.14732)
		(layer "In13.Cu")
		(net "P5E_CPU1_PE2_RX_DP<13>")
	)
	(segment
		(start 129.750058 -434.141372)
		(end 129.602484 -433.993798)
		(width 0.14732)
		(layer "In13.Cu")
		(net "P5E_CPU1_PE2_RX_DP<13>")
	)
	(segment
		(start 150.600156 -334.28178)
		(end 144.53997 -327.519284)
		(width 0.14732)
		(layer "In13.Cu")
		(net "P5E_CPU1_PE2_RX_DP<13>")
	)
	(segment
		(start 137.680954 -223.256348)
		(end 137.672064 -223.251268)
		(width 0.0889)
		(layer "In13.Cu")
		(net "P5E_CPU1_PE2_RX_DP<13>")
	)
	(segment
		(start 140.224764 -250.344686)
		(end 140.435076 -249.154442)
		(width 0.14732)
		(layer "In13.Cu")
		(net "P5E_CPU1_PE2_RX_DP<13>")
	)
	(segment
		(start 139.617704 -224.642172)
		(end 139.60221 -224.626678)
		(width 0.0889)
		(layer "In13.Cu")
		(net "P5E_CPU1_PE2_RX_DP<13>")
	)
	(segment
		(start 149.223476 -364.307374)
		(end 151.543004 -358.665526)
		(width 0.14732)
		(layer "In13.Cu")
		(net "P5E_CPU1_PE2_RX_DP<13>")
	)
	(segment
		(start 149.223476 -364.307628)
		(end 149.223476 -364.307374)
		(width 0.14732)
		(layer "In13.Cu")
		(net "P5E_CPU1_PE2_RX_DP<13>")
	)
	(segment
		(start 136.733026 -221.62389)
		(end 136.73201 -221.623382)
		(width 0.0889)
		(layer "In13.Cu")
		(net "P5E_CPU1_PE2_RX_DP<13>")
	)
	(segment
		(start 133.538468 -219.995496)
		(end 133.529578 -220.000576)
		(width 0.0889)
		(layer "In13.Cu")
		(net "P5E_CPU1_PE2_RX_DP<13>")
	)
	(segment
		(start 142.368016 -256.528062)
		(end 141.384528 -255.123188)
		(width 0.14732)
		(layer "In13.Cu")
		(net "P5E_CPU1_PE2_RX_DP<13>")
	)
	(segment
		(start 133.529578 -220.639132)
		(end 133.538468 -220.644212)
		(width 0.0889)
		(layer "In13.Cu")
		(net "P5E_CPU1_PE2_RX_DP<13>")
	)
	(segment
		(start 137.859516 -223.585532)
		(end 137.859516 -223.575626)
		(width 0.0889)
		(layer "In13.Cu")
		(net "P5E_CPU1_PE2_RX_DP<13>")
	)
	(segment
		(start 128.792224 -423.897044)
		(end 126.390654 -411.02915)
		(width 0.14732)
		(layer "In13.Cu")
		(net "P5E_CPU1_PE2_RX_DP<13>")
	)
	(segment
		(start 132.942076 -221.676722)
		(end 132.785612 -221.94774)
		(width 0.0889)
		(layer "In13.Cu")
		(net "P5E_CPU1_PE2_RX_DP<13>")
	)
	(segment
		(start 143.099536 -259.378704)
		(end 142.368016 -256.528062)
		(width 0.14732)
		(layer "In13.Cu")
		(net "P5E_CPU1_PE2_RX_DP<13>")
	)
	(segment
		(start 136.449816 -221.149418)
		(end 136.449816 -221.133924)
		(width 0.0889)
		(layer "In13.Cu")
		(net "P5E_CPU1_PE2_RX_DP<13>")
	)
	(segment
		(start 137.389362 -222.769176)
		(end 137.389362 -222.761556)
		(width 0.0889)
		(layer "In13.Cu")
		(net "P5E_CPU1_PE2_RX_DP<13>")
	)
	(segment
		(start 140.435076 -249.154442)
		(end 140.944346 -248.426732)
		(width 0.14732)
		(layer "In13.Cu")
		(net "P5E_CPU1_PE2_RX_DP<13>")
	)
	(arc
		(start 134.4676 -220.001592)
		(mid 134.189422 -220.071315)
		(end 133.912864 -219.995496)
		(width 0.0889)
		(layer "In13.Cu")
		(net "P5E_CPU1_PE2_RX_DP<13>")
	)
	(arc
		(start 133.351016 -220.31325)
		(mid 133.351026 -220.32265)
		(end 133.35127 -220.332046)
		(width 0.0889)
		(layer "In13.Cu")
		(net "P5E_CPU1_PE2_RX_DP<13>")
	)
	(arc
		(start 136.449816 -221.133924)
		(mid 136.402137 -220.951024)
		(end 136.271254 -220.814646)
		(width 0.0889)
		(layer "In13.Cu")
		(net "P5E_CPU1_PE2_RX_DP<13>")
	)
	(arc
		(start 133.528054 -221.629478)
		(mid 133.293174 -221.698013)
		(end 133.051296 -221.660974)
		(width 0.0889)
		(layer "In13.Cu")
		(net "P5E_CPU1_PE2_RX_DP<13>")
	)
	(arc
		(start 138.707368 -224.065084)
		(mid 138.424666 -224.14086)
		(end 138.141964 -224.065084)
		(width 0.0889)
		(layer "In13.Cu")
		(net "P5E_CPU1_PE2_RX_DP<13>")
	)
	(arc
		(start 139.159742 -224.124266)
		(mid 139.122692 -224.09212)
		(end 139.081764 -224.065084)
		(width 0.0889)
		(layer "In13.Cu")
		(net "P5E_CPU1_PE2_RX_DP<13>")
	)
	(arc
		(start 137.389362 -222.761556)
		(mid 137.341683 -222.578656)
		(end 137.2108 -222.442278)
		(width 0.0889)
		(layer "In13.Cu")
		(net "P5E_CPU1_PE2_RX_DP<13>")
	)
	(arc
		(start 134.85241 -219.995496)
		(mid 134.665212 -219.945353)
		(end 134.478014 -219.995496)
		(width 0.0889)
		(layer "In13.Cu")
		(net "P5E_CPU1_PE2_RX_DP<13>")
	)
	(arc
		(start 133.912864 -219.995496)
		(mid 133.725666 -219.945353)
		(end 133.538468 -219.995496)
		(width 0.0889)
		(layer "In13.Cu")
		(net "P5E_CPU1_PE2_RX_DP<13>")
	)
	(arc
		(start 137.859516 -223.575626)
		(mid 137.811837 -223.392726)
		(end 137.680954 -223.256348)
		(width 0.0889)
		(layer "In13.Cu")
		(net "P5E_CPU1_PE2_RX_DP<13>")
	)
	(arc
		(start 138.141964 -224.065084)
		(mid 137.937629 -223.862479)
		(end 137.859516 -223.585532)
		(width 0.0889)
		(layer "In13.Cu")
		(net "P5E_CPU1_PE2_RX_DP<13>")
	)
	(arc
		(start 136.73201 -221.623382)
		(mid 136.529187 -221.423151)
		(end 136.449816 -221.149418)
		(width 0.0889)
		(layer "In13.Cu")
		(net "P5E_CPU1_PE2_RX_DP<13>")
	)
	(arc
		(start 133.35127 -220.332046)
		(mid 133.401763 -220.508024)
		(end 133.529578 -220.639132)
		(width 0.0889)
		(layer "In13.Cu")
		(net "P5E_CPU1_PE2_RX_DP<13>")
	)
	(arc
		(start 135.792464 -219.995496)
		(mid 135.605266 -219.945353)
		(end 135.418068 -219.995496)
		(width 0.0889)
		(layer "In13.Cu")
		(net "P5E_CPU1_PE2_RX_DP<13>")
	)
	(arc
		(start 133.051296 -221.660974)
		(mid 133.041225 -221.657005)
		(end 133.03123 -221.652846)
		(width 0.0889)
		(layer "In13.Cu")
		(net "P5E_CPU1_PE2_RX_DP<13>")
	)
	(arc
		(start 137.195814 -222.433642)
		(mid 136.993401 -222.227229)
		(end 136.919462 -221.94774)
		(width 0.0889)
		(layer "In13.Cu")
		(net "P5E_CPU1_PE2_RX_DP<13>")
	)
	(arc
		(start 133.820916 -221.14383)
		(mid 133.742805 -221.420779)
		(end 133.538468 -221.623382)
		(width 0.0889)
		(layer "In13.Cu")
		(net "P5E_CPU1_PE2_RX_DP<13>")
	)
	(arc
		(start 136.919462 -221.94774)
		(mid 136.871783 -221.76484)
		(end 136.7409 -221.628462)
		(width 0.0889)
		(layer "In13.Cu")
		(net "P5E_CPU1_PE2_RX_DP<13>")
	)
	(arc
		(start 137.672064 -223.251268)
		(mid 137.466992 -223.047589)
		(end 137.389362 -222.769176)
		(width 0.0889)
		(layer "In13.Cu")
		(net "P5E_CPU1_PE2_RX_DP<13>")
	)
	(arc
		(start 135.407654 -220.001592)
		(mid 135.129222 -220.071438)
		(end 134.85241 -219.995496)
		(width 0.0889)
		(layer "In13.Cu")
		(net "P5E_CPU1_PE2_RX_DP<13>")
	)
	(arc
		(start 133.538468 -220.644212)
		(mid 133.740754 -220.843193)
		(end 133.820916 -221.115382)
		(width 0.0889)
		(layer "In13.Cu")
		(net "P5E_CPU1_PE2_RX_DP<13>")
	)
	(arc
		(start 136.262364 -220.809566)
		(mid 136.060078 -220.610585)
		(end 135.979916 -220.338396)
		(width 0.0889)
		(layer "In13.Cu")
		(net "P5E_CPU1_PE2_RX_DP<13>")
	)
	(arc
		(start 133.529578 -220.000576)
		(mid 133.400289 -220.134062)
		(end 133.351016 -220.31325)
		(width 0.0889)
		(layer "In13.Cu")
		(net "P5E_CPU1_PE2_RX_DP<13>")
	)
	(arc
		(start 139.081764 -224.065084)
		(mid 138.894566 -224.014941)
		(end 138.707368 -224.065084)
		(width 0.0889)
		(layer "In13.Cu")
		(net "P5E_CPU1_PE2_RX_DP<13>")
	)
	(arc
		(start 135.979916 -220.319854)
		(mid 135.932237 -220.136954)
		(end 135.801354 -220.000576)
		(width 0.0889)
		(layer "In13.Cu")
		(net "P5E_CPU1_PE2_RX_DP<13>")
	)
	(segment
		(start 132.315712 -221.134178)
		(end 132.315966 -221.133924)
		(width 0.13208)
		(layer "F.Cu")
		(net "P5E_CPU1_PE2_RX_DP<12>")
	)
	(segment
		(start 132.315712 -221.669864)
		(end 132.315712 -221.134178)
		(width 0.13208)
		(layer "F.Cu")
		(net "P5E_CPU1_PE2_RX_DP<12>")
	)
	(segment
		(start 141.81709 -248.802144)
		(end 143.23441 -244.452902)
		(width 0.14732)
		(layer "In13.Cu")
		(net "P5E_CPU1_PE2_RX_DP<12>")
	)
	(segment
		(start 132.598668 -219.995496)
		(end 132.597906 -219.996004)
		(width 0.0889)
		(layer "In13.Cu")
		(net "P5E_CPU1_PE2_RX_DP<12>")
	)
	(segment
		(start 139.91717 -223.422718)
		(end 139.821412 -223.32696)
		(width 0.0889)
		(layer "In13.Cu")
		(net "P5E_CPU1_PE2_RX_DP<12>")
	)
	(segment
		(start 131.170934 -404.50516)
		(end 131.170934 -400.100546)
		(width 0.14732)
		(layer "In13.Cu")
		(net "P5E_CPU1_PE2_RX_DP<12>")
	)
	(segment
		(start 142.20825 -254.67818)
		(end 141.633448 -253.29134)
		(width 0.14732)
		(layer "In13.Cu")
		(net "P5E_CPU1_PE2_RX_DP<12>")
	)
	(segment
		(start 136.733788 -219.996258)
		(end 136.732264 -219.995496)
		(width 0.0889)
		(layer "In13.Cu")
		(net "P5E_CPU1_PE2_RX_DP<12>")
	)
	(segment
		(start 141.633448 -253.29134)
		(end 141.562582 -253.08941)
		(width 0.14732)
		(layer "In13.Cu")
		(net "P5E_CPU1_PE2_RX_DP<12>")
	)
	(segment
		(start 143.32966 -256.280158)
		(end 142.20825 -254.67818)
		(width 0.14732)
		(layer "In13.Cu")
		(net "P5E_CPU1_PE2_RX_DP<12>")
	)
	(segment
		(start 132.159502 -220.862906)
		(end 132.315966 -221.133924)
		(width 0.0889)
		(layer "In13.Cu")
		(net "P5E_CPU1_PE2_RX_DP<12>")
	)
	(segment
		(start 143.23441 -244.452902)
		(end 142.21968 -230.175308)
		(width 0.14732)
		(layer "In13.Cu")
		(net "P5E_CPU1_PE2_RX_DP<12>")
	)
	(segment
		(start 137.680954 -221.628462)
		(end 137.672064 -221.623382)
		(width 0.0889)
		(layer "In13.Cu")
		(net "P5E_CPU1_PE2_RX_DP<12>")
	)
	(segment
		(start 141.28496 -252.137418)
		(end 141.28496 -250.44146)
		(width 0.14732)
		(layer "In13.Cu")
		(net "P5E_CPU1_PE2_RX_DP<12>")
	)
	(segment
		(start 129.453894 -406.2222)
		(end 131.170934 -404.50516)
		(width 0.14732)
		(layer "In13.Cu")
		(net "P5E_CPU1_PE2_RX_DP<12>")
	)
	(segment
		(start 145.350484 -326.897492)
		(end 141.21892 -309.644288)
		(width 0.14732)
		(layer "In13.Cu")
		(net "P5E_CPU1_PE2_RX_DP<12>")
	)
	(segment
		(start 139.91717 -223.482662)
		(end 139.91717 -223.422718)
		(width 0.0889)
		(layer "In13.Cu")
		(net "P5E_CPU1_PE2_RX_DP<12>")
	)
	(segment
		(start 136.449562 -219.506038)
		(end 136.449562 -219.497402)
		(width 0.0889)
		(layer "In13.Cu")
		(net "P5E_CPU1_PE2_RX_DP<12>")
	)
	(segment
		(start 142.21968 -230.175308)
		(end 141.3256 -225.834448)
		(width 0.14732)
		(layer "In13.Cu")
		(net "P5E_CPU1_PE2_RX_DP<12>")
	)
	(segment
		(start 141.562582 -253.08941)
		(end 141.28496 -252.137418)
		(width 0.14732)
		(layer "In13.Cu")
		(net "P5E_CPU1_PE2_RX_DP<12>")
	)
	(segment
		(start 136.919716 -220.338396)
		(end 136.919716 -220.319854)
		(width 0.0889)
		(layer "In13.Cu")
		(net "P5E_CPU1_PE2_RX_DP<12>")
	)
	(segment
		(start 136.741154 -220.000576)
		(end 136.733788 -219.996258)
		(width 0.0889)
		(layer "In13.Cu")
		(net "P5E_CPU1_PE2_RX_DP<12>")
	)
	(segment
		(start 141.3256 -225.834448)
		(end 140.703808 -224.2693)
		(width 0.14732)
		(layer "In13.Cu")
		(net "P5E_CPU1_PE2_RX_DP<12>")
	)
	(segment
		(start 131.62788 -435.016656)
		(end 131.224528 -435.016656)
		(width 0.14732)
		(layer "In13.Cu")
		(net "P5E_CPU1_PE2_RX_DP<12>")
	)
	(segment
		(start 137.859516 -221.957646)
		(end 137.859516 -221.94774)
		(width 0.0889)
		(layer "In13.Cu")
		(net "P5E_CPU1_PE2_RX_DP<12>")
	)
	(segment
		(start 151.459946 -333.802482)
		(end 145.350484 -326.897492)
		(width 0.14732)
		(layer "In13.Cu")
		(net "P5E_CPU1_PE2_RX_DP<12>")
	)
	(segment
		(start 131.170934 -400.100546)
		(end 147.880832 -370.10848)
		(width 0.14732)
		(layer "In13.Cu")
		(net "P5E_CPU1_PE2_RX_DP<12>")
	)
	(segment
		(start 147.880832 -370.10848)
		(end 152.510998 -359.222802)
		(width 0.14732)
		(layer "In13.Cu")
		(net "P5E_CPU1_PE2_RX_DP<12>")
	)
	(segment
		(start 144.078706 -259.28701)
		(end 143.32966 -256.280158)
		(width 0.14732)
		(layer "In13.Cu")
		(net "P5E_CPU1_PE2_RX_DP<12>")
	)
	(segment
		(start 141.28496 -250.44146)
		(end 141.492224 -249.266456)
		(width 0.14732)
		(layer "In13.Cu")
		(net "P5E_CPU1_PE2_RX_DP<12>")
	)
	(segment
		(start 132.881116 -219.506038)
		(end 132.881116 -219.515944)
		(width 0.0889)
		(layer "In13.Cu")
		(net "P5E_CPU1_PE2_RX_DP<12>")
	)
	(segment
		(start 131.750054 -435.13883)
		(end 131.62788 -435.016656)
		(width 0.14732)
		(layer "In13.Cu")
		(net "P5E_CPU1_PE2_RX_DP<12>")
	)
	(segment
		(start 138.329162 -222.77578)
		(end 138.329162 -222.75292)
		(width 0.0889)
		(layer "In13.Cu")
		(net "P5E_CPU1_PE2_RX_DP<12>")
	)
	(segment
		(start 132.183632 -220.773752)
		(end 132.159502 -220.862906)
		(width 0.0889)
		(layer "In13.Cu")
		(net "P5E_CPU1_PE2_RX_DP<12>")
	)
	(segment
		(start 131.224528 -435.016656)
		(end 130.79222 -434.584348)
		(width 0.14732)
		(layer "In13.Cu")
		(net "P5E_CPU1_PE2_RX_DP<12>")
	)
	(segment
		(start 137.389616 -221.14383)
		(end 137.389616 -221.133924)
		(width 0.0889)
		(layer "In13.Cu")
		(net "P5E_CPU1_PE2_RX_DP<12>")
	)
	(segment
		(start 137.211054 -220.814646)
		(end 137.202164 -220.809566)
		(width 0.0889)
		(layer "In13.Cu")
		(net "P5E_CPU1_PE2_RX_DP<12>")
	)
	(segment
		(start 130.79222 -423.645076)
		(end 129.453894 -411.262068)
		(width 0.14732)
		(layer "In13.Cu")
		(net "P5E_CPU1_PE2_RX_DP<12>")
	)
	(segment
		(start 136.732264 -219.995496)
		(end 136.726168 -219.99194)
		(width 0.0889)
		(layer "In13.Cu")
		(net "P5E_CPU1_PE2_RX_DP<12>")
	)
	(segment
		(start 130.79222 -434.584348)
		(end 130.79222 -423.645076)
		(width 0.14732)
		(layer "In13.Cu")
		(net "P5E_CPU1_PE2_RX_DP<12>")
	)
	(segment
		(start 129.453894 -411.262068)
		(end 129.453894 -406.2222)
		(width 0.14732)
		(layer "In13.Cu")
		(net "P5E_CPU1_PE2_RX_DP<12>")
	)
	(segment
		(start 132.411216 -220.319854)
		(end 132.411216 -220.334078)
		(width 0.0889)
		(layer "In13.Cu")
		(net "P5E_CPU1_PE2_RX_DP<12>")
	)
	(segment
		(start 153.506424 -345.405456)
		(end 151.459946 -333.802482)
		(width 0.14732)
		(layer "In13.Cu")
		(net "P5E_CPU1_PE2_RX_DP<12>")
	)
	(segment
		(start 140.703808 -224.2693)
		(end 139.932664 -223.498156)
		(width 0.14732)
		(layer "In13.Cu")
		(net "P5E_CPU1_PE2_RX_DP<12>")
	)
	(segment
		(start 131.750054 -435.489858)
		(end 131.750054 -435.13883)
		(width 0.14732)
		(layer "In13.Cu")
		(net "P5E_CPU1_PE2_RX_DP<12>")
	)
	(segment
		(start 132.595366 -219.997528)
		(end 132.589778 -220.000576)
		(width 0.0889)
		(layer "In13.Cu")
		(net "P5E_CPU1_PE2_RX_DP<12>")
	)
	(segment
		(start 141.21892 -309.644288)
		(end 144.078706 -259.28701)
		(width 0.14732)
		(layer "In13.Cu")
		(net "P5E_CPU1_PE2_RX_DP<12>")
	)
	(segment
		(start 132.597906 -219.996004)
		(end 132.595366 -219.997528)
		(width 0.0889)
		(layer "In13.Cu")
		(net "P5E_CPU1_PE2_RX_DP<12>")
	)
	(segment
		(start 139.932664 -223.498156)
		(end 139.91717 -223.482662)
		(width 0.0889)
		(layer "In13.Cu")
		(net "P5E_CPU1_PE2_RX_DP<12>")
	)
	(segment
		(start 152.510998 -359.222802)
		(end 153.506424 -345.405456)
		(width 0.14732)
		(layer "In13.Cu")
		(net "P5E_CPU1_PE2_RX_DP<12>")
	)
	(segment
		(start 133.068568 -219.18168)
		(end 133.059678 -219.18676)
		(width 0.0889)
		(layer "In13.Cu")
		(net "P5E_CPU1_PE2_RX_DP<12>")
	)
	(segment
		(start 139.821412 -223.32696)
		(end 138.894312 -223.32696)
		(width 0.0889)
		(layer "In13.Cu")
		(net "P5E_CPU1_PE2_RX_DP<12>")
	)
	(segment
		(start 141.492224 -249.266456)
		(end 141.81709 -248.802144)
		(width 0.14732)
		(layer "In13.Cu")
		(net "P5E_CPU1_PE2_RX_DP<12>")
	)
	(arc
		(start 137.202164 -220.809566)
		(mid 136.999878 -220.610585)
		(end 136.919716 -220.338396)
		(width 0.0889)
		(layer "In13.Cu")
		(net "P5E_CPU1_PE2_RX_DP<12>")
	)
	(arc
		(start 138.894312 -223.32696)
		(mid 138.74812 -223.307665)
		(end 138.611864 -223.251268)
		(width 0.0889)
		(layer "In13.Cu")
		(net "P5E_CPU1_PE2_RX_DP<12>")
	)
	(arc
		(start 132.589778 -220.000576)
		(mid 132.458864 -220.136936)
		(end 132.411216 -220.319854)
		(width 0.0889)
		(layer "In13.Cu")
		(net "P5E_CPU1_PE2_RX_DP<12>")
	)
	(arc
		(start 138.329162 -222.75292)
		(mid 138.276892 -222.570555)
		(end 138.141964 -222.437198)
		(width 0.0889)
		(layer "In13.Cu")
		(net "P5E_CPU1_PE2_RX_DP<12>")
	)
	(arc
		(start 134.382764 -219.18168)
		(mid 134.195566 -219.131537)
		(end 134.008368 -219.18168)
		(width 0.0889)
		(layer "In13.Cu")
		(net "P5E_CPU1_PE2_RX_DP<12>")
	)
	(arc
		(start 134.948168 -219.18168)
		(mid 134.665466 -219.257456)
		(end 134.382764 -219.18168)
		(width 0.0889)
		(layer "In13.Cu")
		(net "P5E_CPU1_PE2_RX_DP<12>")
	)
	(arc
		(start 132.200396 -220.760798)
		(mid 132.192074 -220.767353)
		(end 132.183632 -220.773752)
		(width 0.0889)
		(layer "In13.Cu")
		(net "P5E_CPU1_PE2_RX_DP<12>")
	)
	(arc
		(start 136.726168 -219.99194)
		(mid 136.523581 -219.785589)
		(end 136.449562 -219.506038)
		(width 0.0889)
		(layer "In13.Cu")
		(net "P5E_CPU1_PE2_RX_DP<12>")
	)
	(arc
		(start 137.672064 -221.623382)
		(mid 137.467729 -221.420777)
		(end 137.389616 -221.14383)
		(width 0.0889)
		(layer "In13.Cu")
		(net "P5E_CPU1_PE2_RX_DP<12>")
	)
	(arc
		(start 133.442964 -219.18168)
		(mid 133.255766 -219.131537)
		(end 133.068568 -219.18168)
		(width 0.0889)
		(layer "In13.Cu")
		(net "P5E_CPU1_PE2_RX_DP<12>")
	)
	(arc
		(start 136.919716 -220.319854)
		(mid 136.872037 -220.136954)
		(end 136.741154 -220.000576)
		(width 0.0889)
		(layer "In13.Cu")
		(net "P5E_CPU1_PE2_RX_DP<12>")
	)
	(arc
		(start 137.859516 -221.94774)
		(mid 137.811837 -221.76484)
		(end 137.680954 -221.628462)
		(width 0.0889)
		(layer "In13.Cu")
		(net "P5E_CPU1_PE2_RX_DP<12>")
	)
	(arc
		(start 132.881116 -219.515944)
		(mid 132.803005 -219.792893)
		(end 132.598668 -219.995496)
		(width 0.0889)
		(layer "In13.Cu")
		(net "P5E_CPU1_PE2_RX_DP<12>")
	)
	(arc
		(start 133.059678 -219.18676)
		(mid 132.928764 -219.32312)
		(end 132.881116 -219.506038)
		(width 0.0889)
		(layer "In13.Cu")
		(net "P5E_CPU1_PE2_RX_DP<12>")
	)
	(arc
		(start 136.262364 -219.18168)
		(mid 136.075166 -219.131537)
		(end 135.887968 -219.18168)
		(width 0.0889)
		(layer "In13.Cu")
		(net "P5E_CPU1_PE2_RX_DP<12>")
	)
	(arc
		(start 138.141964 -222.437198)
		(mid 137.937629 -222.234593)
		(end 137.859516 -221.957646)
		(width 0.0889)
		(layer "In13.Cu")
		(net "P5E_CPU1_PE2_RX_DP<12>")
	)
	(arc
		(start 136.449562 -219.497402)
		(mid 136.397292 -219.315037)
		(end 136.262364 -219.18168)
		(width 0.0889)
		(layer "In13.Cu")
		(net "P5E_CPU1_PE2_RX_DP<12>")
	)
	(arc
		(start 138.611864 -223.251268)
		(mid 138.408383 -223.050464)
		(end 138.329162 -222.77578)
		(width 0.0889)
		(layer "In13.Cu")
		(net "P5E_CPU1_PE2_RX_DP<12>")
	)
	(arc
		(start 135.887968 -219.18168)
		(mid 135.605266 -219.257456)
		(end 135.322564 -219.18168)
		(width 0.0889)
		(layer "In13.Cu")
		(net "P5E_CPU1_PE2_RX_DP<12>")
	)
	(arc
		(start 134.008368 -219.18168)
		(mid 133.725666 -219.257456)
		(end 133.442964 -219.18168)
		(width 0.0889)
		(layer "In13.Cu")
		(net "P5E_CPU1_PE2_RX_DP<12>")
	)
	(arc
		(start 132.411216 -220.334078)
		(mid 132.352855 -220.570676)
		(end 132.200396 -220.760798)
		(width 0.0889)
		(layer "In13.Cu")
		(net "P5E_CPU1_PE2_RX_DP<12>")
	)
	(arc
		(start 137.389616 -221.133924)
		(mid 137.341937 -220.951024)
		(end 137.211054 -220.814646)
		(width 0.0889)
		(layer "In13.Cu")
		(net "P5E_CPU1_PE2_RX_DP<12>")
	)
	(arc
		(start 135.322564 -219.18168)
		(mid 135.135366 -219.131537)
		(end 134.948168 -219.18168)
		(width 0.0889)
		(layer "In13.Cu")
		(net "P5E_CPU1_PE2_RX_DP<12>")
	)
	(segment
		(start 130.906266 -222.48368)
		(end 130.906266 -221.947994)
		(width 0.13208)
		(layer "F.Cu")
		(net "P5E_CPU1_PE2_RX_DP<11>")
	)
	(segment
		(start 130.906266 -221.947994)
		(end 130.906012 -221.94774)
		(width 0.13208)
		(layer "F.Cu")
		(net "P5E_CPU1_PE2_RX_DP<11>")
	)
	(segment
		(start 131.659376 -219.994988)
		(end 131.658614 -219.995496)
		(width 0.0889)
		(layer "In13.Cu")
		(net "P5E_CPU1_PE2_RX_DP<11>")
	)
	(segment
		(start 133.077204 -433.993798)
		(end 132.792216 -433.70881)
		(width 0.14732)
		(layer "In13.Cu")
		(net "P5E_CPU1_PE2_RX_DP<11>")
	)
	(segment
		(start 139.0142 -216.818464)
		(end 138.95324 -216.818464)
		(width 0.0889)
		(layer "In13.Cu")
		(net "P5E_CPU1_PE2_RX_DP<11>")
	)
	(segment
		(start 146.215608 -326.350376)
		(end 142.17904 -309.563008)
		(width 0.14732)
		(layer "In13.Cu")
		(net "P5E_CPU1_PE2_RX_DP<11>")
	)
	(segment
		(start 132.517134 -413.816038)
		(end 132.517134 -406.2222)
		(width 0.14732)
		(layer "In13.Cu")
		(net "P5E_CPU1_PE2_RX_DP<11>")
	)
	(segment
		(start 139.056364 -216.860628)
		(end 139.0142 -216.818464)
		(width 0.0889)
		(layer "In13.Cu")
		(net "P5E_CPU1_PE2_RX_DP<11>")
	)
	(segment
		(start 152.509474 -333.57058)
		(end 146.215608 -326.350376)
		(width 0.14732)
		(layer "In13.Cu")
		(net "P5E_CPU1_PE2_RX_DP<11>")
	)
	(segment
		(start 132.565648 -415.638742)
		(end 132.565394 -415.633662)
		(width 0.14732)
		(layer "In13.Cu")
		(net "P5E_CPU1_PE2_RX_DP<11>")
	)
	(segment
		(start 142.517114 -252.994668)
		(end 142.413228 -252.661166)
		(width 0.14732)
		(layer "In13.Cu")
		(net "P5E_CPU1_PE2_RX_DP<11>")
	)
	(segment
		(start 142.86357 -253.830074)
		(end 142.517114 -252.994668)
		(width 0.14732)
		(layer "In13.Cu")
		(net "P5E_CPU1_PE2_RX_DP<11>")
	)
	(segment
		(start 131.15163 -221.652846)
		(end 131.062476 -221.676722)
		(width 0.0889)
		(layer "In13.Cu")
		(net "P5E_CPU1_PE2_RX_DP<11>")
	)
	(segment
		(start 133.602476 -433.993798)
		(end 133.077204 -433.993798)
		(width 0.14732)
		(layer "In13.Cu")
		(net "P5E_CPU1_PE2_RX_DP<11>")
	)
	(segment
		(start 139.078462 -216.860628)
		(end 139.056364 -216.860628)
		(width 0.0889)
		(layer "In13.Cu")
		(net "P5E_CPU1_PE2_RX_DP<11>")
	)
	(segment
		(start 134.234174 -404.50516)
		(end 134.234174 -400.009614)
		(width 0.14732)
		(layer "In13.Cu")
		(net "P5E_CPU1_PE2_RX_DP<11>")
	)
	(segment
		(start 131.659376 -221.622874)
		(end 131.643882 -221.632018)
		(width 0.0889)
		(layer "In13.Cu")
		(net "P5E_CPU1_PE2_RX_DP<11>")
	)
	(segment
		(start 148.927566 -370.196872)
		(end 148.928836 -370.196618)
		(width 0.14732)
		(layer "In13.Cu")
		(net "P5E_CPU1_PE2_RX_DP<11>")
	)
	(segment
		(start 148.928836 -370.196618)
		(end 148.93036 -370.192808)
		(width 0.14732)
		(layer "In13.Cu")
		(net "P5E_CPU1_PE2_RX_DP<11>")
	)
	(segment
		(start 132.792216 -433.70881)
		(end 132.792216 -423.735754)
		(width 0.14732)
		(layer "In13.Cu")
		(net "P5E_CPU1_PE2_RX_DP<11>")
	)
	(segment
		(start 142.17904 -309.563008)
		(end 145.122392 -259.19303)
		(width 0.14732)
		(layer "In13.Cu")
		(net "P5E_CPU1_PE2_RX_DP<11>")
	)
	(segment
		(start 143.19504 -230.043228)
		(end 142.28572 -225.565208)
		(width 0.14732)
		(layer "In13.Cu")
		(net "P5E_CPU1_PE2_RX_DP<11>")
	)
	(segment
		(start 142.28572 -225.565208)
		(end 139.79398 -217.170508)
		(width 0.14732)
		(layer "In13.Cu")
		(net "P5E_CPU1_PE2_RX_DP<11>")
	)
	(segment
		(start 133.75005 -434.141372)
		(end 133.602476 -433.993798)
		(width 0.14732)
		(layer "In13.Cu")
		(net "P5E_CPU1_PE2_RX_DP<11>")
	)
	(segment
		(start 144.431004 -256.06883)
		(end 142.86357 -253.830074)
		(width 0.14732)
		(layer "In13.Cu")
		(net "P5E_CPU1_PE2_RX_DP<11>")
	)
	(segment
		(start 153.523696 -359.37063)
		(end 154.644344 -345.674442)
		(width 0.14732)
		(layer "In13.Cu")
		(net "P5E_CPU1_PE2_RX_DP<11>")
	)
	(segment
		(start 133.351016 -217.0557)
		(end 133.351016 -217.082878)
		(width 0.0889)
		(layer "In13.Cu")
		(net "P5E_CPU1_PE2_RX_DP<11>")
	)
	(segment
		(start 142.30096 -250.57481)
		(end 142.499334 -249.44959)
		(width 0.14732)
		(layer "In13.Cu")
		(net "P5E_CPU1_PE2_RX_DP<11>")
	)
	(segment
		(start 131.062476 -221.676722)
		(end 130.906012 -221.94774)
		(width 0.0889)
		(layer "In13.Cu")
		(net "P5E_CPU1_PE2_RX_DP<11>")
	)
	(segment
		(start 132.792216 -423.735754)
		(end 132.565648 -415.638742)
		(width 0.14732)
		(layer "In13.Cu")
		(net "P5E_CPU1_PE2_RX_DP<11>")
	)
	(segment
		(start 142.413228 -252.661166)
		(end 142.30096 -252.300232)
		(width 0.14732)
		(layer "In13.Cu")
		(net "P5E_CPU1_PE2_RX_DP<11>")
	)
	(segment
		(start 144.19453 -244.545104)
		(end 143.19504 -230.043228)
		(width 0.14732)
		(layer "In13.Cu")
		(net "P5E_CPU1_PE2_RX_DP<11>")
	)
	(segment
		(start 145.122646 -259.19303)
		(end 144.431004 -256.06883)
		(width 0.14732)
		(layer "In13.Cu")
		(net "P5E_CPU1_PE2_RX_DP<11>")
	)
	(segment
		(start 133.75005 -434.48986)
		(end 133.75005 -434.141372)
		(width 0.14732)
		(layer "In13.Cu")
		(net "P5E_CPU1_PE2_RX_DP<11>")
	)
	(segment
		(start 134.478268 -216.739978)
		(end 134.467854 -216.746074)
		(width 0.0889)
		(layer "In13.Cu")
		(net "P5E_CPU1_PE2_RX_DP<11>")
	)
	(segment
		(start 132.410962 -218.692222)
		(end 132.410962 -218.707716)
		(width 0.0889)
		(layer "In13.Cu")
		(net "P5E_CPU1_PE2_RX_DP<11>")
	)
	(segment
		(start 145.122392 -259.19303)
		(end 145.122646 -259.19303)
		(width 0.14732)
		(layer "In13.Cu")
		(net "P5E_CPU1_PE2_RX_DP<11>")
	)
	(segment
		(start 132.60451 -218.364308)
		(end 132.589524 -218.372944)
		(width 0.0889)
		(layer "In13.Cu")
		(net "P5E_CPU1_PE2_RX_DP<11>")
	)
	(segment
		(start 132.565394 -415.633662)
		(end 132.565648 -415.633662)
		(width 0.14732)
		(layer "In13.Cu")
		(net "P5E_CPU1_PE2_RX_DP<11>")
	)
	(segment
		(start 132.517134 -406.2222)
		(end 134.234174 -404.50516)
		(width 0.14732)
		(layer "In13.Cu")
		(net "P5E_CPU1_PE2_RX_DP<11>")
	)
	(segment
		(start 139.4841 -216.860628)
		(end 139.078462 -216.860628)
		(width 0.14732)
		(layer "In13.Cu")
		(net "P5E_CPU1_PE2_RX_DP<11>")
	)
	(segment
		(start 154.644344 -345.674442)
		(end 152.509474 -333.57058)
		(width 0.14732)
		(layer "In13.Cu")
		(net "P5E_CPU1_PE2_RX_DP<11>")
	)
	(segment
		(start 134.234174 -400.009614)
		(end 148.927566 -370.196872)
		(width 0.14732)
		(layer "In13.Cu")
		(net "P5E_CPU1_PE2_RX_DP<11>")
	)
	(segment
		(start 142.685008 -249.184414)
		(end 144.19453 -244.545104)
		(width 0.14732)
		(layer "In13.Cu")
		(net "P5E_CPU1_PE2_RX_DP<11>")
	)
	(segment
		(start 142.499334 -249.44959)
		(end 142.685008 -249.184414)
		(width 0.14732)
		(layer "In13.Cu")
		(net "P5E_CPU1_PE2_RX_DP<11>")
	)
	(segment
		(start 131.66471 -221.619826)
		(end 131.659376 -221.622874)
		(width 0.0889)
		(layer "In13.Cu")
		(net "P5E_CPU1_PE2_RX_DP<11>")
	)
	(segment
		(start 133.068568 -217.554048)
		(end 133.059678 -217.559128)
		(width 0.0889)
		(layer "In13.Cu")
		(net "P5E_CPU1_PE2_RX_DP<11>")
	)
	(segment
		(start 148.93036 -370.192808)
		(end 153.523696 -359.37063)
		(width 0.14732)
		(layer "In13.Cu")
		(net "P5E_CPU1_PE2_RX_DP<11>")
	)
	(segment
		(start 132.128768 -219.18168)
		(end 132.119878 -219.18676)
		(width 0.0889)
		(layer "In13.Cu")
		(net "P5E_CPU1_PE2_RX_DP<11>")
	)
	(segment
		(start 132.565648 -415.633662)
		(end 132.517134 -413.816038)
		(width 0.14732)
		(layer "In13.Cu")
		(net "P5E_CPU1_PE2_RX_DP<11>")
	)
	(segment
		(start 142.30096 -252.300232)
		(end 142.30096 -250.57481)
		(width 0.14732)
		(layer "In13.Cu")
		(net "P5E_CPU1_PE2_RX_DP<11>")
	)
	(segment
		(start 131.66471 -219.99194)
		(end 131.659376 -219.994988)
		(width 0.0889)
		(layer "In13.Cu")
		(net "P5E_CPU1_PE2_RX_DP<11>")
	)
	(segment
		(start 139.79398 -217.170508)
		(end 139.4841 -216.860628)
		(width 0.14732)
		(layer "In13.Cu")
		(net "P5E_CPU1_PE2_RX_DP<11>")
	)
	(arc
		(start 131.941316 -219.506038)
		(mid 131.867325 -219.785604)
		(end 131.66471 -219.99194)
		(width 0.0889)
		(layer "In13.Cu")
		(net "P5E_CPU1_PE2_RX_DP<11>")
	)
	(arc
		(start 137.297668 -216.739978)
		(mid 137.014966 -216.815754)
		(end 136.732264 -216.739978)
		(width 0.0889)
		(layer "In13.Cu")
		(net "P5E_CPU1_PE2_RX_DP<11>")
	)
	(arc
		(start 135.418068 -216.739978)
		(mid 135.135366 -216.815754)
		(end 134.852664 -216.739978)
		(width 0.0889)
		(layer "In13.Cu")
		(net "P5E_CPU1_PE2_RX_DP<11>")
	)
	(arc
		(start 133.91261 -216.739978)
		(mid 133.541887 -216.737886)
		(end 133.351016 -217.0557)
		(width 0.0889)
		(layer "In13.Cu")
		(net "P5E_CPU1_PE2_RX_DP<11>")
	)
	(arc
		(start 132.589524 -218.372944)
		(mid 132.45861 -218.509304)
		(end 132.410962 -218.692222)
		(width 0.0889)
		(layer "In13.Cu")
		(net "P5E_CPU1_PE2_RX_DP<11>")
	)
	(arc
		(start 136.732264 -216.739978)
		(mid 136.545066 -216.689835)
		(end 136.357868 -216.739978)
		(width 0.0889)
		(layer "In13.Cu")
		(net "P5E_CPU1_PE2_RX_DP<11>")
	)
	(arc
		(start 136.357868 -216.739978)
		(mid 136.075166 -216.815754)
		(end 135.792464 -216.739978)
		(width 0.0889)
		(layer "In13.Cu")
		(net "P5E_CPU1_PE2_RX_DP<11>")
	)
	(arc
		(start 132.410962 -218.707716)
		(mid 132.331592 -218.98145)
		(end 132.128768 -219.18168)
		(width 0.0889)
		(layer "In13.Cu")
		(net "P5E_CPU1_PE2_RX_DP<11>")
	)
	(arc
		(start 132.881116 -217.878406)
		(mid 132.807125 -218.157972)
		(end 132.60451 -218.364308)
		(width 0.0889)
		(layer "In13.Cu")
		(net "P5E_CPU1_PE2_RX_DP<11>")
	)
	(arc
		(start 131.658614 -219.995496)
		(mid 131.471311 -220.319854)
		(end 131.658614 -220.644212)
		(width 0.0889)
		(layer "In13.Cu")
		(net "P5E_CPU1_PE2_RX_DP<11>")
	)
	(arc
		(start 135.792464 -216.739978)
		(mid 135.605266 -216.689835)
		(end 135.418068 -216.739978)
		(width 0.0889)
		(layer "In13.Cu")
		(net "P5E_CPU1_PE2_RX_DP<11>")
	)
	(arc
		(start 131.658614 -220.644212)
		(mid 131.941609 -221.130331)
		(end 131.66471 -221.619826)
		(width 0.0889)
		(layer "In13.Cu")
		(net "P5E_CPU1_PE2_RX_DP<11>")
	)
	(arc
		(start 137.672064 -216.739978)
		(mid 137.484866 -216.689835)
		(end 137.297668 -216.739978)
		(width 0.0889)
		(layer "In13.Cu")
		(net "P5E_CPU1_PE2_RX_DP<11>")
	)
	(arc
		(start 138.611864 -216.739978)
		(mid 138.424666 -216.689835)
		(end 138.237468 -216.739978)
		(width 0.0889)
		(layer "In13.Cu")
		(net "P5E_CPU1_PE2_RX_DP<11>")
	)
	(arc
		(start 138.237468 -216.739978)
		(mid 137.954766 -216.815754)
		(end 137.672064 -216.739978)
		(width 0.0889)
		(layer "In13.Cu")
		(net "P5E_CPU1_PE2_RX_DP<11>")
	)
	(arc
		(start 134.852664 -216.739978)
		(mid 134.665466 -216.689835)
		(end 134.478268 -216.739978)
		(width 0.0889)
		(layer "In13.Cu")
		(net "P5E_CPU1_PE2_RX_DP<11>")
	)
	(arc
		(start 132.119878 -219.18676)
		(mid 131.988964 -219.32312)
		(end 131.941316 -219.506038)
		(width 0.0889)
		(layer "In13.Cu")
		(net "P5E_CPU1_PE2_RX_DP<11>")
	)
	(arc
		(start 131.643882 -221.632018)
		(mid 131.410967 -221.698229)
		(end 131.171696 -221.660974)
		(width 0.0889)
		(layer "In13.Cu")
		(net "P5E_CPU1_PE2_RX_DP<11>")
	)
	(arc
		(start 138.95324 -216.818464)
		(mid 138.899343 -216.817321)
		(end 138.845544 -216.813892)
		(width 0.0889)
		(layer "In13.Cu")
		(net "P5E_CPU1_PE2_RX_DP<11>")
	)
	(arc
		(start 131.171696 -221.660974)
		(mid 131.161625 -221.657005)
		(end 131.15163 -221.652846)
		(width 0.0889)
		(layer "In13.Cu")
		(net "P5E_CPU1_PE2_RX_DP<11>")
	)
	(arc
		(start 133.059678 -217.559128)
		(mid 132.928764 -217.695488)
		(end 132.881116 -217.878406)
		(width 0.0889)
		(layer "In13.Cu")
		(net "P5E_CPU1_PE2_RX_DP<11>")
	)
	(arc
		(start 134.467854 -216.746074)
		(mid 134.189422 -216.81592)
		(end 133.91261 -216.739978)
		(width 0.0889)
		(layer "In13.Cu")
		(net "P5E_CPU1_PE2_RX_DP<11>")
	)
	(arc
		(start 133.351016 -217.082878)
		(mid 133.270854 -217.355067)
		(end 133.068568 -217.554048)
		(width 0.0889)
		(layer "In13.Cu")
		(net "P5E_CPU1_PE2_RX_DP<11>")
	)
	(arc
		(start 138.845544 -216.813892)
		(mid 138.724645 -216.789763)
		(end 138.611864 -216.739978)
		(width 0.0889)
		(layer "In13.Cu")
		(net "P5E_CPU1_PE2_RX_DP<11>")
	)
	(segment
		(start 130.436112 -221.134178)
		(end 130.436366 -221.133924)
		(width 0.13208)
		(layer "F.Cu")
		(net "P5E_CPU1_PE2_RX_DP<10>")
	)
	(segment
		(start 130.436112 -221.669864)
		(end 130.436112 -221.134178)
		(width 0.13208)
		(layer "F.Cu")
		(net "P5E_CPU1_PE2_RX_DP<10>")
	)
	(segment
		(start 143.31442 -225.601784)
		(end 140.553948 -216.416636)
		(width 0.14732)
		(layer "In13.Cu")
		(net "P5E_CPU1_PE2_RX_DP<10>")
	)
	(segment
		(start 143.24076 -252.157992)
		(end 143.24076 -251.128022)
		(width 0.14732)
		(layer "In13.Cu")
		(net "P5E_CPU1_PE2_RX_DP<10>")
	)
	(segment
		(start 135.580374 -411.337506)
		(end 135.580374 -406.2222)
		(width 0.14732)
		(layer "In13.Cu")
		(net "P5E_CPU1_PE2_RX_DP<10>")
	)
	(segment
		(start 137.944606 -215.513666)
		(end 137.902442 -215.471502)
		(width 0.0889)
		(layer "In13.Cu")
		(net "P5E_CPU1_PE2_RX_DP<10>")
	)
	(segment
		(start 135.750046 -435.489858)
		(end 135.750046 -435.15153)
		(width 0.14732)
		(layer "In13.Cu")
		(net "P5E_CPU1_PE2_RX_DP<10>")
	)
	(segment
		(start 135.750046 -435.15153)
		(end 135.602472 -435.003956)
		(width 0.14732)
		(layer "In13.Cu")
		(net "P5E_CPU1_PE2_RX_DP<10>")
	)
	(segment
		(start 139.12723 -215.638126)
		(end 138.68781 -215.638126)
		(width 0.14732)
		(layer "In13.Cu")
		(net "P5E_CPU1_PE2_RX_DP<10>")
	)
	(segment
		(start 146.128994 -259.091938)
		(end 145.328386 -255.715008)
		(width 0.14732)
		(layer "In13.Cu")
		(net "P5E_CPU1_PE2_RX_DP<10>")
	)
	(segment
		(start 143.669512 -253.345696)
		(end 143.391128 -252.673866)
		(width 0.14732)
		(layer "In13.Cu")
		(net "P5E_CPU1_PE2_RX_DP<10>")
	)
	(segment
		(start 139.650978 -215.513666)
		(end 139.25169 -215.513666)
		(width 0.14732)
		(layer "In13.Cu")
		(net "P5E_CPU1_PE2_RX_DP<10>")
	)
	(segment
		(start 130.715766 -219.997528)
		(end 130.710178 -220.000576)
		(width 0.0889)
		(layer "In13.Cu")
		(net "P5E_CPU1_PE2_RX_DP<10>")
	)
	(segment
		(start 145.147284 -244.737382)
		(end 144.145 -229.844854)
		(width 0.14732)
		(layer "In13.Cu")
		(net "P5E_CPU1_PE2_RX_DP<10>")
	)
	(segment
		(start 143.24076 -251.128022)
		(end 143.503904 -249.63755)
		(width 0.14732)
		(layer "In13.Cu")
		(net "P5E_CPU1_PE2_RX_DP<10>")
	)
	(segment
		(start 130.72491 -218.364308)
		(end 130.719576 -218.367356)
		(width 0.0889)
		(layer "In13.Cu")
		(net "P5E_CPU1_PE2_RX_DP<10>")
	)
	(segment
		(start 130.279902 -220.862906)
		(end 130.436366 -221.133924)
		(width 0.0889)
		(layer "In13.Cu")
		(net "P5E_CPU1_PE2_RX_DP<10>")
	)
	(segment
		(start 130.721608 -219.018104)
		(end 130.72491 -219.020136)
		(width 0.0889)
		(layer "In13.Cu")
		(net "P5E_CPU1_PE2_RX_DP<10>")
	)
	(segment
		(start 131.66217 -216.737946)
		(end 131.659376 -216.73947)
		(width 0.0889)
		(layer "In13.Cu")
		(net "P5E_CPU1_PE2_RX_DP<10>")
	)
	(segment
		(start 130.719576 -218.367356)
		(end 130.718814 -218.367864)
		(width 0.0889)
		(layer "In13.Cu")
		(net "P5E_CPU1_PE2_RX_DP<10>")
	)
	(segment
		(start 130.718814 -219.01658)
		(end 130.721608 -219.018104)
		(width 0.0889)
		(layer "In13.Cu")
		(net "P5E_CPU1_PE2_RX_DP<10>")
	)
	(segment
		(start 143.595852 -249.506232)
		(end 145.147284 -244.737382)
		(width 0.14732)
		(layer "In13.Cu")
		(net "P5E_CPU1_PE2_RX_DP<10>")
	)
	(segment
		(start 131.188968 -217.554048)
		(end 131.180078 -217.559128)
		(width 0.0889)
		(layer "In13.Cu")
		(net "P5E_CPU1_PE2_RX_DP<10>")
	)
	(segment
		(start 137.297414 -404.50516)
		(end 137.297414 -399.928334)
		(width 0.14732)
		(layer "In13.Cu")
		(net "P5E_CPU1_PE2_RX_DP<10>")
	)
	(segment
		(start 137.966704 -215.513666)
		(end 137.944606 -215.513666)
		(width 0.0889)
		(layer "In13.Cu")
		(net "P5E_CPU1_PE2_RX_DP<10>")
	)
	(segment
		(start 132.128768 -215.926162)
		(end 132.119878 -215.931242)
		(width 0.0889)
		(layer "In13.Cu")
		(net "P5E_CPU1_PE2_RX_DP<10>")
	)
	(segment
		(start 134.792212 -425.63796)
		(end 135.24103 -417.495482)
		(width 0.14732)
		(layer "In13.Cu")
		(net "P5E_CPU1_PE2_RX_DP<10>")
	)
	(segment
		(start 130.531616 -220.319854)
		(end 130.531616 -220.334078)
		(width 0.0889)
		(layer "In13.Cu")
		(net "P5E_CPU1_PE2_RX_DP<10>")
	)
	(segment
		(start 131.662932 -216.737438)
		(end 131.66217 -216.737946)
		(width 0.0889)
		(layer "In13.Cu")
		(net "P5E_CPU1_PE2_RX_DP<10>")
	)
	(segment
		(start 145.328386 -255.715008)
		(end 143.669512 -253.345696)
		(width 0.14732)
		(layer "In13.Cu")
		(net "P5E_CPU1_PE2_RX_DP<10>")
	)
	(segment
		(start 131.659376 -216.73947)
		(end 131.658614 -216.739978)
		(width 0.0889)
		(layer "In13.Cu")
		(net "P5E_CPU1_PE2_RX_DP<10>")
	)
	(segment
		(start 135.24103 -417.49472)
		(end 135.580374 -411.337506)
		(width 0.14732)
		(layer "In13.Cu")
		(net "P5E_CPU1_PE2_RX_DP<10>")
	)
	(segment
		(start 132.517896 -215.934798)
		(end 132.503164 -215.926162)
		(width 0.0889)
		(layer "In13.Cu")
		(net "P5E_CPU1_PE2_RX_DP<10>")
	)
	(segment
		(start 130.304032 -220.773752)
		(end 130.279902 -220.862906)
		(width 0.0889)
		(layer "In13.Cu")
		(net "P5E_CPU1_PE2_RX_DP<10>")
	)
	(segment
		(start 136.827768 -215.926162)
		(end 136.813036 -215.934798)
		(width 0.0889)
		(layer "In13.Cu")
		(net "P5E_CPU1_PE2_RX_DP<10>")
	)
	(segment
		(start 131.66471 -216.736422)
		(end 131.662932 -216.737438)
		(width 0.0889)
		(layer "In13.Cu")
		(net "P5E_CPU1_PE2_RX_DP<10>")
	)
	(segment
		(start 137.297414 -399.928334)
		(end 154.535124 -359.412794)
		(width 0.14732)
		(layer "In13.Cu")
		(net "P5E_CPU1_PE2_RX_DP<10>")
	)
	(segment
		(start 139.25169 -215.513666)
		(end 139.12723 -215.638126)
		(width 0.14732)
		(layer "In13.Cu")
		(net "P5E_CPU1_PE2_RX_DP<10>")
	)
	(segment
		(start 130.718814 -218.367864)
		(end 130.711956 -218.371674)
		(width 0.0889)
		(layer "In13.Cu")
		(net "P5E_CPU1_PE2_RX_DP<10>")
	)
	(segment
		(start 134.792212 -434.72608)
		(end 134.792212 -425.63796)
		(width 0.14732)
		(layer "In13.Cu")
		(net "P5E_CPU1_PE2_RX_DP<10>")
	)
	(segment
		(start 144.145 -229.844854)
		(end 143.31442 -225.601784)
		(width 0.14732)
		(layer "In13.Cu")
		(net "P5E_CPU1_PE2_RX_DP<10>")
	)
	(segment
		(start 137.902442 -215.471502)
		(end 137.309606 -215.471502)
		(width 0.0889)
		(layer "In13.Cu")
		(net "P5E_CPU1_PE2_RX_DP<10>")
	)
	(segment
		(start 143.391128 -252.673866)
		(end 143.24076 -252.157992)
		(width 0.14732)
		(layer "In13.Cu")
		(net "P5E_CPU1_PE2_RX_DP<10>")
	)
	(segment
		(start 143.13662 -309.484268)
		(end 146.128994 -259.091938)
		(width 0.14732)
		(layer "In13.Cu")
		(net "P5E_CPU1_PE2_RX_DP<10>")
	)
	(segment
		(start 131.471416 -217.0557)
		(end 131.471416 -217.082878)
		(width 0.0889)
		(layer "In13.Cu")
		(net "P5E_CPU1_PE2_RX_DP<10>")
	)
	(segment
		(start 154.535124 -359.412794)
		(end 155.6512 -345.782138)
		(width 0.14732)
		(layer "In13.Cu")
		(net "P5E_CPU1_PE2_RX_DP<10>")
	)
	(segment
		(start 135.580374 -406.2222)
		(end 137.297414 -404.50516)
		(width 0.14732)
		(layer "In13.Cu")
		(net "P5E_CPU1_PE2_RX_DP<10>")
	)
	(segment
		(start 138.56335 -215.513666)
		(end 137.966704 -215.513666)
		(width 0.14732)
		(layer "In13.Cu")
		(net "P5E_CPU1_PE2_RX_DP<10>")
	)
	(segment
		(start 138.68781 -215.638126)
		(end 138.56335 -215.513666)
		(width 0.14732)
		(layer "In13.Cu")
		(net "P5E_CPU1_PE2_RX_DP<10>")
	)
	(segment
		(start 130.719068 -219.995496)
		(end 130.718306 -219.996004)
		(width 0.0889)
		(layer "In13.Cu")
		(net "P5E_CPU1_PE2_RX_DP<10>")
	)
	(segment
		(start 140.553948 -216.416636)
		(end 139.650978 -215.513666)
		(width 0.14732)
		(layer "In13.Cu")
		(net "P5E_CPU1_PE2_RX_DP<10>")
	)
	(segment
		(start 135.602472 -435.003956)
		(end 135.070088 -435.003956)
		(width 0.14732)
		(layer "In13.Cu")
		(net "P5E_CPU1_PE2_RX_DP<10>")
	)
	(segment
		(start 147.05584 -325.798688)
		(end 143.13662 -309.484268)
		(width 0.14732)
		(layer "In13.Cu")
		(net "P5E_CPU1_PE2_RX_DP<10>")
	)
	(segment
		(start 153.43251 -333.20228)
		(end 147.05584 -325.798688)
		(width 0.14732)
		(layer "In13.Cu")
		(net "P5E_CPU1_PE2_RX_DP<10>")
	)
	(segment
		(start 155.6512 -345.782138)
		(end 153.43251 -333.20228)
		(width 0.14732)
		(layer "In13.Cu")
		(net "P5E_CPU1_PE2_RX_DP<10>")
	)
	(segment
		(start 133.457696 -215.934798)
		(end 133.442964 -215.926162)
		(width 0.0889)
		(layer "In13.Cu")
		(net "P5E_CPU1_PE2_RX_DP<10>")
	)
	(segment
		(start 130.718306 -219.996004)
		(end 130.715766 -219.997528)
		(width 0.0889)
		(layer "In13.Cu")
		(net "P5E_CPU1_PE2_RX_DP<10>")
	)
	(segment
		(start 135.24103 -417.495482)
		(end 135.24103 -417.49472)
		(width 0.14732)
		(layer "In13.Cu")
		(net "P5E_CPU1_PE2_RX_DP<10>")
	)
	(segment
		(start 131.001516 -219.506038)
		(end 131.001516 -219.515944)
		(width 0.0889)
		(layer "In13.Cu")
		(net "P5E_CPU1_PE2_RX_DP<10>")
	)
	(segment
		(start 135.070088 -435.003956)
		(end 134.792212 -434.72608)
		(width 0.14732)
		(layer "In13.Cu")
		(net "P5E_CPU1_PE2_RX_DP<10>")
	)
	(segment
		(start 135.337296 -215.934798)
		(end 135.322564 -215.926162)
		(width 0.0889)
		(layer "In13.Cu")
		(net "P5E_CPU1_PE2_RX_DP<10>")
	)
	(segment
		(start 137.309606 -215.471502)
		(end 136.944862 -215.8365)
		(width 0.0889)
		(layer "In13.Cu")
		(net "P5E_CPU1_PE2_RX_DP<10>")
	)
	(segment
		(start 130.711956 -218.371674)
		(end 130.709924 -218.372944)
		(width 0.0889)
		(layer "In13.Cu")
		(net "P5E_CPU1_PE2_RX_DP<10>")
	)
	(segment
		(start 134.397496 -215.934798)
		(end 134.382764 -215.926162)
		(width 0.0889)
		(layer "In13.Cu")
		(net "P5E_CPU1_PE2_RX_DP<10>")
	)
	(segment
		(start 130.71729 -219.015818)
		(end 130.718814 -219.01658)
		(width 0.0889)
		(layer "In13.Cu")
		(net "P5E_CPU1_PE2_RX_DP<10>")
	)
	(segment
		(start 143.503904 -249.63755)
		(end 143.595852 -249.506232)
		(width 0.14732)
		(layer "In13.Cu")
		(net "P5E_CPU1_PE2_RX_DP<10>")
	)
	(segment
		(start 130.709924 -219.0115)
		(end 130.71729 -219.015818)
		(width 0.0889)
		(layer "In13.Cu")
		(net "P5E_CPU1_PE2_RX_DP<10>")
	)
	(arc
		(start 135.322564 -215.926162)
		(mid 135.135366 -215.876019)
		(end 134.948168 -215.926162)
		(width 0.0889)
		(layer "In13.Cu")
		(net "P5E_CPU1_PE2_RX_DP<10>")
	)
	(arc
		(start 134.948168 -215.926162)
		(mid 134.673969 -216.001997)
		(end 134.397496 -215.934798)
		(width 0.0889)
		(layer "In13.Cu")
		(net "P5E_CPU1_PE2_RX_DP<10>")
	)
	(arc
		(start 131.471416 -217.082878)
		(mid 131.391254 -217.355067)
		(end 131.188968 -217.554048)
		(width 0.0889)
		(layer "In13.Cu")
		(net "P5E_CPU1_PE2_RX_DP<10>")
	)
	(arc
		(start 136.262364 -215.926162)
		(mid 136.075166 -215.876019)
		(end 135.887968 -215.926162)
		(width 0.0889)
		(layer "In13.Cu")
		(net "P5E_CPU1_PE2_RX_DP<10>")
	)
	(arc
		(start 133.068568 -215.926162)
		(mid 132.794369 -216.001997)
		(end 132.517896 -215.934798)
		(width 0.0889)
		(layer "In13.Cu")
		(net "P5E_CPU1_PE2_RX_DP<10>")
	)
	(arc
		(start 133.442964 -215.926162)
		(mid 133.255766 -215.876019)
		(end 133.068568 -215.926162)
		(width 0.0889)
		(layer "In13.Cu")
		(net "P5E_CPU1_PE2_RX_DP<10>")
	)
	(arc
		(start 132.503164 -215.926162)
		(mid 132.315966 -215.876019)
		(end 132.128768 -215.926162)
		(width 0.0889)
		(layer "In13.Cu")
		(net "P5E_CPU1_PE2_RX_DP<10>")
	)
	(arc
		(start 131.658614 -216.739978)
		(mid 131.523681 -216.873332)
		(end 131.471416 -217.0557)
		(width 0.0889)
		(layer "In13.Cu")
		(net "P5E_CPU1_PE2_RX_DP<10>")
	)
	(arc
		(start 132.119878 -215.931242)
		(mid 131.988964 -216.067602)
		(end 131.941316 -216.25052)
		(width 0.0889)
		(layer "In13.Cu")
		(net "P5E_CPU1_PE2_RX_DP<10>")
	)
	(arc
		(start 130.709924 -218.372944)
		(mid 130.531327 -218.692222)
		(end 130.709924 -219.0115)
		(width 0.0889)
		(layer "In13.Cu")
		(net "P5E_CPU1_PE2_RX_DP<10>")
	)
	(arc
		(start 131.001516 -219.515944)
		(mid 130.923405 -219.792893)
		(end 130.719068 -219.995496)
		(width 0.0889)
		(layer "In13.Cu")
		(net "P5E_CPU1_PE2_RX_DP<10>")
	)
	(arc
		(start 136.9187 -215.861138)
		(mid 136.874847 -215.895906)
		(end 136.827768 -215.926162)
		(width 0.0889)
		(layer "In13.Cu")
		(net "P5E_CPU1_PE2_RX_DP<10>")
	)
	(arc
		(start 130.710178 -220.000576)
		(mid 130.579264 -220.136936)
		(end 130.531616 -220.319854)
		(width 0.0889)
		(layer "In13.Cu")
		(net "P5E_CPU1_PE2_RX_DP<10>")
	)
	(arc
		(start 134.008368 -215.926162)
		(mid 133.734169 -216.001997)
		(end 133.457696 -215.934798)
		(width 0.0889)
		(layer "In13.Cu")
		(net "P5E_CPU1_PE2_RX_DP<10>")
	)
	(arc
		(start 131.180078 -217.559128)
		(mid 131.049164 -217.695488)
		(end 131.001516 -217.878406)
		(width 0.0889)
		(layer "In13.Cu")
		(net "P5E_CPU1_PE2_RX_DP<10>")
	)
	(arc
		(start 131.941316 -216.25052)
		(mid 131.867325 -216.530086)
		(end 131.66471 -216.736422)
		(width 0.0889)
		(layer "In13.Cu")
		(net "P5E_CPU1_PE2_RX_DP<10>")
	)
	(arc
		(start 130.531616 -220.334078)
		(mid 130.473255 -220.570676)
		(end 130.320796 -220.760798)
		(width 0.0889)
		(layer "In13.Cu")
		(net "P5E_CPU1_PE2_RX_DP<10>")
	)
	(arc
		(start 136.813036 -215.934798)
		(mid 136.536561 -216.002118)
		(end 136.262364 -215.926162)
		(width 0.0889)
		(layer "In13.Cu")
		(net "P5E_CPU1_PE2_RX_DP<10>")
	)
	(arc
		(start 130.320796 -220.760798)
		(mid 130.312474 -220.767353)
		(end 130.304032 -220.773752)
		(width 0.0889)
		(layer "In13.Cu")
		(net "P5E_CPU1_PE2_RX_DP<10>")
	)
	(arc
		(start 131.001516 -217.878406)
		(mid 130.927525 -218.157972)
		(end 130.72491 -218.364308)
		(width 0.0889)
		(layer "In13.Cu")
		(net "P5E_CPU1_PE2_RX_DP<10>")
	)
	(arc
		(start 136.944862 -215.8365)
		(mid 136.931978 -215.849028)
		(end 136.9187 -215.861138)
		(width 0.0889)
		(layer "In13.Cu")
		(net "P5E_CPU1_PE2_RX_DP<10>")
	)
	(arc
		(start 135.887968 -215.926162)
		(mid 135.613769 -216.001997)
		(end 135.337296 -215.934798)
		(width 0.0889)
		(layer "In13.Cu")
		(net "P5E_CPU1_PE2_RX_DP<10>")
	)
	(arc
		(start 130.72491 -219.020136)
		(mid 130.927497 -219.226487)
		(end 131.001516 -219.506038)
		(width 0.0889)
		(layer "In13.Cu")
		(net "P5E_CPU1_PE2_RX_DP<10>")
	)
	(arc
		(start 134.382764 -215.926162)
		(mid 134.195566 -215.876019)
		(end 134.008368 -215.926162)
		(width 0.0889)
		(layer "In13.Cu")
		(net "P5E_CPU1_PE2_RX_DP<10>")
	)
	(segment
		(start 121.038112 -221.669864)
		(end 121.038112 -221.134178)
		(width 0.13208)
		(layer "F.Cu")
		(net "P5E_CPU1_PE2_RX_DP<0>")
	)
	(segment
		(start 121.038112 -221.134178)
		(end 121.038366 -221.133924)
		(width 0.13208)
		(layer "F.Cu")
		(net "P5E_CPU1_PE2_RX_DP<0>")
	)
	(segment
		(start 166.5732 -394.731748)
		(end 166.49827 -394.300964)
		(width 0.14732)
		(layer "In13.Cu")
		(net "P5E_CPU1_PE2_RX_DP<0>")
	)
	(segment
		(start 156.60243 -434.993796)
		(end 156.091382 -434.993796)
		(width 0.14732)
		(layer "In13.Cu")
		(net "P5E_CPU1_PE2_RX_DP<0>")
	)
	(segment
		(start 157.003242 -253.498604)
		(end 156.806392 -247.631712)
		(width 0.14732)
		(layer "In13.Cu")
		(net "P5E_CPU1_PE2_RX_DP<0>")
	)
	(segment
		(start 156.750004 -435.14137)
		(end 156.60243 -434.993796)
		(width 0.14732)
		(layer "In13.Cu")
		(net "P5E_CPU1_PE2_RX_DP<0>")
	)
	(segment
		(start 122.073416 -213.321646)
		(end 122.073416 -213.637368)
		(width 0.0889)
		(layer "In13.Cu")
		(net "P5E_CPU1_PE2_RX_DP<0>")
	)
	(segment
		(start 156.091382 -434.993796)
		(end 155.79217 -434.694584)
		(width 0.14732)
		(layer "In13.Cu")
		(net "P5E_CPU1_PE2_RX_DP<0>")
	)
	(segment
		(start 121.32691 -218.364308)
		(end 121.326656 -218.364562)
		(width 0.0889)
		(layer "In13.Cu")
		(net "P5E_CPU1_PE2_RX_DP<0>")
	)
	(segment
		(start 122.115326 -211.462874)
		(end 122.115326 -213.257638)
		(width 0.14732)
		(layer "In13.Cu")
		(net "P5E_CPU1_PE2_RX_DP<0>")
	)
	(segment
		(start 165.457378 -346.033598)
		(end 164.056568 -327.567798)
		(width 0.14732)
		(layer "In13.Cu")
		(net "P5E_CPU1_PE2_RX_DP<0>")
	)
	(segment
		(start 155.79217 -434.694584)
		(end 155.79217 -424.393868)
		(width 0.14732)
		(layer "In13.Cu")
		(net "P5E_CPU1_PE2_RX_DP<0>")
	)
	(segment
		(start 121.321068 -216.739978)
		(end 121.320306 -216.740486)
		(width 0.0889)
		(layer "In13.Cu")
		(net "P5E_CPU1_PE2_RX_DP<0>")
	)
	(segment
		(start 149.460204 -210.745832)
		(end 148.651722 -209.93735)
		(width 0.14732)
		(layer "In13.Cu")
		(net "P5E_CPU1_PE2_RX_DP<0>")
	)
	(segment
		(start 164.77107 -361.395772)
		(end 165.457378 -346.085922)
		(width 0.14732)
		(layer "In13.Cu")
		(net "P5E_CPU1_PE2_RX_DP<0>")
	)
	(segment
		(start 166.599616 -394.156946)
		(end 165.70833 -389.038592)
		(width 0.14732)
		(layer "In13.Cu")
		(net "P5E_CPU1_PE2_RX_DP<0>")
	)
	(segment
		(start 155.79217 -424.393868)
		(end 166.212774 -410.995114)
		(width 0.14732)
		(layer "In13.Cu")
		(net "P5E_CPU1_PE2_RX_DP<0>")
	)
	(segment
		(start 163.846764 -326.379332)
		(end 162.9156 -325.049134)
		(width 0.14732)
		(layer "In13.Cu")
		(net "P5E_CPU1_PE2_RX_DP<0>")
	)
	(segment
		(start 123.212352 -208.814416)
		(end 122.115326 -211.462874)
		(width 0.14732)
		(layer "In13.Cu")
		(net "P5E_CPU1_PE2_RX_DP<0>")
	)
	(segment
		(start 167.929814 -400.1262)
		(end 167.257476 -397.934688)
		(width 0.14732)
		(layer "In13.Cu")
		(net "P5E_CPU1_PE2_RX_DP<0>")
	)
	(segment
		(start 121.320814 -219.01658)
		(end 121.32691 -219.020136)
		(width 0.0889)
		(layer "In13.Cu")
		(net "P5E_CPU1_PE2_RX_DP<0>")
	)
	(segment
		(start 122.073416 -213.637368)
		(end 122.073162 -213.637368)
		(width 0.0889)
		(layer "In13.Cu")
		(net "P5E_CPU1_PE2_RX_DP<0>")
	)
	(segment
		(start 160.56483 -323.403214)
		(end 157.123892 -321.484244)
		(width 0.14732)
		(layer "In13.Cu")
		(net "P5E_CPU1_PE2_RX_DP<0>")
	)
	(segment
		(start 122.073162 -213.637368)
		(end 122.073162 -213.8934)
		(width 0.0889)
		(layer "In13.Cu")
		(net "P5E_CPU1_PE2_RX_DP<0>")
	)
	(segment
		(start 122.073162 -215.436704)
		(end 122.073162 -215.452198)
		(width 0.0889)
		(layer "In13.Cu")
		(net "P5E_CPU1_PE2_RX_DP<0>")
	)
	(segment
		(start 167.257476 -397.934688)
		(end 166.717472 -394.83284)
		(width 0.14732)
		(layer "In13.Cu")
		(net "P5E_CPU1_PE2_RX_DP<0>")
	)
	(segment
		(start 152.75052 -308.333648)
		(end 157.003242 -253.498604)
		(width 0.14732)
		(layer "In13.Cu")
		(net "P5E_CPU1_PE2_RX_DP<0>")
	)
	(segment
		(start 166.212774 -410.995114)
		(end 166.212774 -406.2222)
		(width 0.14732)
		(layer "In13.Cu")
		(net "P5E_CPU1_PE2_RX_DP<0>")
	)
	(segment
		(start 121.317766 -219.997528)
		(end 121.312178 -220.000576)
		(width 0.0889)
		(layer "In13.Cu")
		(net "P5E_CPU1_PE2_RX_DP<0>")
	)
	(segment
		(start 156.806392 -247.631712)
		(end 153.165302 -223.49968)
		(width 0.14732)
		(layer "In13.Cu")
		(net "P5E_CPU1_PE2_RX_DP<0>")
	)
	(segment
		(start 121.320306 -219.996004)
		(end 121.317766 -219.997528)
		(width 0.0889)
		(layer "In13.Cu")
		(net "P5E_CPU1_PE2_RX_DP<0>")
	)
	(segment
		(start 120.906032 -220.773752)
		(end 120.881902 -220.862906)
		(width 0.0889)
		(layer "In13.Cu")
		(net "P5E_CPU1_PE2_RX_DP<0>")
	)
	(segment
		(start 155.173172 -318.885316)
		(end 152.75052 -308.333648)
		(width 0.14732)
		(layer "In13.Cu")
		(net "P5E_CPU1_PE2_RX_DP<0>")
	)
	(segment
		(start 166.717472 -394.83284)
		(end 166.5732 -394.731748)
		(width 0.14732)
		(layer "In13.Cu")
		(net "P5E_CPU1_PE2_RX_DP<0>")
	)
	(segment
		(start 147.37969 -208.665318)
		(end 138.247882 -199.53351)
		(width 0.14732)
		(layer "In13.Cu")
		(net "P5E_CPU1_PE2_RX_DP<0>")
	)
	(segment
		(start 120.881902 -220.862906)
		(end 121.038366 -221.133924)
		(width 0.0889)
		(layer "In13.Cu")
		(net "P5E_CPU1_PE2_RX_DP<0>")
	)
	(segment
		(start 166.49827 -394.300964)
		(end 166.599616 -394.156946)
		(width 0.14732)
		(layer "In13.Cu")
		(net "P5E_CPU1_PE2_RX_DP<0>")
	)
	(segment
		(start 121.326656 -218.364562)
		(end 121.313956 -218.371674)
		(width 0.0889)
		(layer "In13.Cu")
		(net "P5E_CPU1_PE2_RX_DP<0>")
	)
	(segment
		(start 148.170138 -209.628232)
		(end 148.170138 -209.455766)
		(width 0.14732)
		(layer "In13.Cu")
		(net "P5E_CPU1_PE2_RX_DP<0>")
	)
	(segment
		(start 147.688808 -209.146902)
		(end 147.37969 -208.837784)
		(width 0.14732)
		(layer "In13.Cu")
		(net "P5E_CPU1_PE2_RX_DP<0>")
	)
	(segment
		(start 121.603516 -217.859864)
		(end 121.603516 -217.878406)
		(width 0.0889)
		(layer "In13.Cu")
		(net "P5E_CPU1_PE2_RX_DP<0>")
	)
	(segment
		(start 121.133616 -220.319854)
		(end 121.133616 -220.334078)
		(width 0.0889)
		(layer "In13.Cu")
		(net "P5E_CPU1_PE2_RX_DP<0>")
	)
	(segment
		(start 153.165302 -223.49968)
		(end 149.460204 -210.745832)
		(width 0.14732)
		(layer "In13.Cu")
		(net "P5E_CPU1_PE2_RX_DP<0>")
	)
	(segment
		(start 148.651722 -209.93735)
		(end 148.479256 -209.93735)
		(width 0.14732)
		(layer "In13.Cu")
		(net "P5E_CPU1_PE2_RX_DP<0>")
	)
	(segment
		(start 121.790968 -215.926162)
		(end 121.782078 -215.931242)
		(width 0.0889)
		(layer "In13.Cu")
		(net "P5E_CPU1_PE2_RX_DP<0>")
	)
	(segment
		(start 165.70833 -389.038592)
		(end 165.694868 -388.911338)
		(width 0.14732)
		(layer "In13.Cu")
		(net "P5E_CPU1_PE2_RX_DP<0>")
	)
	(segment
		(start 121.311924 -219.0115)
		(end 121.320814 -219.01658)
		(width 0.0889)
		(layer "In13.Cu")
		(net "P5E_CPU1_PE2_RX_DP<0>")
	)
	(segment
		(start 157.123892 -321.484244)
		(end 155.173172 -318.885316)
		(width 0.14732)
		(layer "In13.Cu")
		(net "P5E_CPU1_PE2_RX_DP<0>")
	)
	(segment
		(start 147.861274 -209.146902)
		(end 147.688808 -209.146902)
		(width 0.14732)
		(layer "In13.Cu")
		(net "P5E_CPU1_PE2_RX_DP<0>")
	)
	(segment
		(start 148.170138 -209.455766)
		(end 147.861274 -209.146902)
		(width 0.14732)
		(layer "In13.Cu")
		(net "P5E_CPU1_PE2_RX_DP<0>")
	)
	(segment
		(start 122.115326 -213.257638)
		(end 122.115326 -213.279736)
		(width 0.0889)
		(layer "In13.Cu")
		(net "P5E_CPU1_PE2_RX_DP<0>")
	)
	(segment
		(start 121.317766 -216.74201)
		(end 121.312178 -216.745058)
		(width 0.0889)
		(layer "In13.Cu")
		(net "P5E_CPU1_PE2_RX_DP<0>")
	)
	(segment
		(start 162.9156 -325.049134)
		(end 160.56483 -323.403214)
		(width 0.14732)
		(layer "In13.Cu")
		(net "P5E_CPU1_PE2_RX_DP<0>")
	)
	(segment
		(start 121.321068 -219.995496)
		(end 121.320306 -219.996004)
		(width 0.0889)
		(layer "In13.Cu")
		(net "P5E_CPU1_PE2_RX_DP<0>")
	)
	(segment
		(start 121.320306 -216.740486)
		(end 121.317766 -216.74201)
		(width 0.0889)
		(layer "In13.Cu")
		(net "P5E_CPU1_PE2_RX_DP<0>")
	)
	(segment
		(start 132.493258 -199.53351)
		(end 123.212352 -208.814416)
		(width 0.14732)
		(layer "In13.Cu")
		(net "P5E_CPU1_PE2_RX_DP<0>")
	)
	(segment
		(start 122.115326 -213.279736)
		(end 122.073416 -213.321646)
		(width 0.0889)
		(layer "In13.Cu")
		(net "P5E_CPU1_PE2_RX_DP<0>")
	)
	(segment
		(start 164.056568 -327.567798)
		(end 163.846764 -326.379332)
		(width 0.14732)
		(layer "In13.Cu")
		(net "P5E_CPU1_PE2_RX_DP<0>")
	)
	(segment
		(start 148.479256 -209.93735)
		(end 148.170138 -209.628232)
		(width 0.14732)
		(layer "In13.Cu")
		(net "P5E_CPU1_PE2_RX_DP<0>")
	)
	(segment
		(start 122.073162 -213.8934)
		(end 122.073416 -213.893908)
		(width 0.0889)
		(layer "In13.Cu")
		(net "P5E_CPU1_PE2_RX_DP<0>")
	)
	(segment
		(start 121.312178 -217.383614)
		(end 121.321068 -217.388694)
		(width 0.0889)
		(layer "In13.Cu")
		(net "P5E_CPU1_PE2_RX_DP<0>")
	)
	(segment
		(start 167.929814 -404.50516)
		(end 167.929814 -400.1262)
		(width 0.14732)
		(layer "In13.Cu")
		(net "P5E_CPU1_PE2_RX_DP<0>")
	)
	(segment
		(start 156.750004 -435.489858)
		(end 156.750004 -435.14137)
		(width 0.14732)
		(layer "In13.Cu")
		(net "P5E_CPU1_PE2_RX_DP<0>")
	)
	(segment
		(start 121.313956 -218.371674)
		(end 121.311924 -218.372944)
		(width 0.0889)
		(layer "In13.Cu")
		(net "P5E_CPU1_PE2_RX_DP<0>")
	)
	(segment
		(start 147.37969 -208.837784)
		(end 147.37969 -208.665318)
		(width 0.14732)
		(layer "In13.Cu")
		(net "P5E_CPU1_PE2_RX_DP<0>")
	)
	(segment
		(start 121.603516 -216.25052)
		(end 121.603516 -216.260426)
		(width 0.0889)
		(layer "In13.Cu")
		(net "P5E_CPU1_PE2_RX_DP<0>")
	)
	(segment
		(start 138.247882 -199.53351)
		(end 132.493258 -199.53351)
		(width 0.14732)
		(layer "In13.Cu")
		(net "P5E_CPU1_PE2_RX_DP<0>")
	)
	(segment
		(start 165.694868 -388.911338)
		(end 164.77107 -361.395772)
		(width 0.14732)
		(layer "In13.Cu")
		(net "P5E_CPU1_PE2_RX_DP<0>")
	)
	(segment
		(start 166.212774 -406.2222)
		(end 167.929814 -404.50516)
		(width 0.14732)
		(layer "In13.Cu")
		(net "P5E_CPU1_PE2_RX_DP<0>")
	)
	(segment
		(start 122.542808 -214.424768)
		(end 122.542808 -214.644732)
		(width 0.0889)
		(layer "In13.Cu")
		(net "P5E_CPU1_PE2_RX_DP<0>")
	)
	(segment
		(start 165.457378 -346.085922)
		(end 165.457378 -346.033598)
		(width 0.14732)
		(layer "In13.Cu")
		(net "P5E_CPU1_PE2_RX_DP<0>")
	)
	(segment
		(start 122.260614 -215.112346)
		(end 122.251724 -215.117426)
		(width 0.0889)
		(layer "In13.Cu")
		(net "P5E_CPU1_PE2_RX_DP<0>")
	)
	(segment
		(start 121.603516 -219.506038)
		(end 121.603516 -219.515944)
		(width 0.0889)
		(layer "In13.Cu")
		(net "P5E_CPU1_PE2_RX_DP<0>")
	)
	(arc
		(start 122.542808 -214.644732)
		(mid 122.461897 -214.91486)
		(end 122.260614 -215.112346)
		(width 0.0889)
		(layer "In13.Cu")
		(net "P5E_CPU1_PE2_RX_DP<0>")
	)
	(arc
		(start 122.251724 -215.117426)
		(mid 122.12447 -215.247392)
		(end 122.073416 -215.421972)
		(width 0.0889)
		(layer "In13.Cu")
		(net "P5E_CPU1_PE2_RX_DP<0>")
	)
	(arc
		(start 121.133616 -220.334078)
		(mid 121.075255 -220.570676)
		(end 120.922796 -220.760798)
		(width 0.0889)
		(layer "In13.Cu")
		(net "P5E_CPU1_PE2_RX_DP<0>")
	)
	(arc
		(start 122.073162 -215.452198)
		(mid 121.993792 -215.725932)
		(end 121.790968 -215.926162)
		(width 0.0889)
		(layer "In13.Cu")
		(net "P5E_CPU1_PE2_RX_DP<0>")
	)
	(arc
		(start 121.603516 -216.260426)
		(mid 121.525405 -216.537375)
		(end 121.321068 -216.739978)
		(width 0.0889)
		(layer "In13.Cu")
		(net "P5E_CPU1_PE2_RX_DP<0>")
	)
	(arc
		(start 122.257566 -214.093298)
		(mid 122.431529 -214.232062)
		(end 122.542808 -214.424768)
		(width 0.0889)
		(layer "In13.Cu")
		(net "P5E_CPU1_PE2_RX_DP<0>")
	)
	(arc
		(start 122.073416 -213.893908)
		(mid 122.148421 -214.009367)
		(end 122.257566 -214.093298)
		(width 0.0889)
		(layer "In13.Cu")
		(net "P5E_CPU1_PE2_RX_DP<0>")
	)
	(arc
		(start 121.782078 -215.931242)
		(mid 121.651164 -216.067602)
		(end 121.603516 -216.25052)
		(width 0.0889)
		(layer "In13.Cu")
		(net "P5E_CPU1_PE2_RX_DP<0>")
	)
	(arc
		(start 121.133616 -217.064336)
		(mid 121.181295 -217.247236)
		(end 121.312178 -217.383614)
		(width 0.0889)
		(layer "In13.Cu")
		(net "P5E_CPU1_PE2_RX_DP<0>")
	)
	(arc
		(start 121.311924 -218.372944)
		(mid 121.133327 -218.692222)
		(end 121.311924 -219.0115)
		(width 0.0889)
		(layer "In13.Cu")
		(net "P5E_CPU1_PE2_RX_DP<0>")
	)
	(arc
		(start 121.312178 -220.000576)
		(mid 121.181264 -220.136936)
		(end 121.133616 -220.319854)
		(width 0.0889)
		(layer "In13.Cu")
		(net "P5E_CPU1_PE2_RX_DP<0>")
	)
	(arc
		(start 121.321068 -217.388694)
		(mid 121.523354 -217.587675)
		(end 121.603516 -217.859864)
		(width 0.0889)
		(layer "In13.Cu")
		(net "P5E_CPU1_PE2_RX_DP<0>")
	)
	(arc
		(start 121.603516 -217.878406)
		(mid 121.529525 -218.157972)
		(end 121.32691 -218.364308)
		(width 0.0889)
		(layer "In13.Cu")
		(net "P5E_CPU1_PE2_RX_DP<0>")
	)
	(arc
		(start 121.603516 -219.515944)
		(mid 121.525405 -219.792893)
		(end 121.321068 -219.995496)
		(width 0.0889)
		(layer "In13.Cu")
		(net "P5E_CPU1_PE2_RX_DP<0>")
	)
	(arc
		(start 121.32691 -219.020136)
		(mid 121.529497 -219.226487)
		(end 121.603516 -219.506038)
		(width 0.0889)
		(layer "In13.Cu")
		(net "P5E_CPU1_PE2_RX_DP<0>")
	)
	(arc
		(start 120.922796 -220.760798)
		(mid 120.914474 -220.767353)
		(end 120.906032 -220.773752)
		(width 0.0889)
		(layer "In13.Cu")
		(net "P5E_CPU1_PE2_RX_DP<0>")
	)
	(arc
		(start 122.073416 -215.421972)
		(mid 122.073219 -215.429337)
		(end 122.073162 -215.436704)
		(width 0.0889)
		(layer "In13.Cu")
		(net "P5E_CPU1_PE2_RX_DP<0>")
	)
	(arc
		(start 121.312178 -216.745058)
		(mid 121.181264 -216.881418)
		(end 121.133616 -217.064336)
		(width 0.0889)
		(layer "In13.Cu")
		(net "P5E_CPU1_PE2_RX_DP<0>")
	)
	(segment
		(start 129.496312 -221.134178)
		(end 129.496566 -221.133924)
		(width 0.13208)
		(layer "F.Cu")
		(net "P5E_CPU1_PE2_RX_DN<9>")
	)
	(segment
		(start 129.496312 -221.669864)
		(end 129.496312 -221.134178)
		(width 0.13208)
		(layer "F.Cu")
		(net "P5E_CPU1_PE2_RX_DN<9>")
	)
	(segment
		(start 131.680204 -212.589364)
		(end 132.639308 -212.589364)
		(width 0.14732)
		(layer "In13.Cu")
		(net "P5E_CPU1_PE2_RX_DN<9>")
	)
	(segment
		(start 140.359638 -214.397844)
		(end 141.64564 -215.683592)
		(width 0.14732)
		(layer "In13.Cu")
		(net "P5E_CPU1_PE2_RX_DN<9>")
	)
	(segment
		(start 129.683002 -218.203272)
		(end 129.683764 -218.202764)
		(width 0.0889)
		(layer "In13.Cu")
		(net "P5E_CPU1_PE2_RX_DN<9>")
	)
	(segment
		(start 129.677668 -216.578434)
		(end 129.68097 -216.576402)
		(width 0.0889)
		(layer "In13.Cu")
		(net "P5E_CPU1_PE2_RX_DN<9>")
	)
	(segment
		(start 137.797286 -418.541454)
		(end 137.921238 -418.704522)
		(width 0.14732)
		(layer "In13.Cu")
		(net "P5E_CPU1_PE2_RX_DN<9>")
	)
	(segment
		(start 129.677668 -218.20632)
		(end 129.683002 -218.203272)
		(width 0.0889)
		(layer "In13.Cu")
		(net "P5E_CPU1_PE2_RX_DN<9>")
	)
	(segment
		(start 129.871216 -216.25052)
		(end 129.871216 -216.235026)
		(width 0.0889)
		(layer "In13.Cu")
		(net "P5E_CPU1_PE2_RX_DN<9>")
	)
	(segment
		(start 137.8712 -419.06952)
		(end 137.707878 -419.193472)
		(width 0.14732)
		(layer "In13.Cu")
		(net "P5E_CPU1_PE2_RX_DN<9>")
	)
	(segment
		(start 137.053574 -423.98569)
		(end 137.053574 -433.582064)
		(width 0.14732)
		(layer "In13.Cu")
		(net "P5E_CPU1_PE2_RX_DN<9>")
	)
	(segment
		(start 131.28117 -213.41715)
		(end 131.239006 -213.374986)
		(width 0.0889)
		(layer "In13.Cu")
		(net "P5E_CPU1_PE2_RX_DN<9>")
	)
	(segment
		(start 137.921238 -418.704522)
		(end 137.8712 -419.06952)
		(width 0.14732)
		(layer "In13.Cu")
		(net "P5E_CPU1_PE2_RX_DN<9>")
	)
	(segment
		(start 131.239006 -213.030562)
		(end 131.680204 -212.589364)
		(width 0.14732)
		(layer "In13.Cu")
		(net "P5E_CPU1_PE2_RX_DN<9>")
	)
	(segment
		(start 142.028164 -396.012924)
		(end 141.866874 -396.084298)
		(width 0.14732)
		(layer "In13.Cu")
		(net "P5E_CPU1_PE2_RX_DN<9>")
	)
	(segment
		(start 138.917934 -406.335992)
		(end 138.917934 -410.369766)
		(width 0.14732)
		(layer "In13.Cu")
		(net "P5E_CPU1_PE2_RX_DN<9>")
	)
	(segment
		(start 137.053574 -433.582064)
		(end 137.190988 -433.719478)
		(width 0.14732)
		(layer "In13.Cu")
		(net "P5E_CPU1_PE2_RX_DN<9>")
	)
	(segment
		(start 148.591524 -250.312428)
		(end 148.687028 -253.154688)
		(width 0.14732)
		(layer "In13.Cu")
		(net "P5E_CPU1_PE2_RX_DN<9>")
	)
	(segment
		(start 140.634974 -400.19097)
		(end 140.634974 -404.618952)
		(width 0.14732)
		(layer "In13.Cu")
		(net "P5E_CPU1_PE2_RX_DN<9>")
	)
	(segment
		(start 129.683764 -221.458282)
		(end 129.685288 -221.45752)
		(width 0.0889)
		(layer "In13.Cu")
		(net "P5E_CPU1_PE2_RX_DN<9>")
	)
	(segment
		(start 142.114016 -395.444218)
		(end 142.18539 -395.605254)
		(width 0.14732)
		(layer "In13.Cu")
		(net "P5E_CPU1_PE2_RX_DN<9>")
	)
	(segment
		(start 145.375376 -229.672896)
		(end 148.590508 -250.28652)
		(width 0.14732)
		(layer "In13.Cu")
		(net "P5E_CPU1_PE2_RX_DN<9>")
	)
	(segment
		(start 148.16328 -325.175118)
		(end 154.584654 -332.64856)
		(width 0.14732)
		(layer "In13.Cu")
		(net "P5E_CPU1_PE2_RX_DN<9>")
	)
	(segment
		(start 142.18539 -395.605254)
		(end 142.028164 -396.012924)
		(width 0.14732)
		(layer "In13.Cu")
		(net "P5E_CPU1_PE2_RX_DN<9>")
	)
	(segment
		(start 129.683764 -219.18168)
		(end 129.677668 -219.178124)
		(width 0.0889)
		(layer "In13.Cu")
		(net "P5E_CPU1_PE2_RX_DN<9>")
	)
	(segment
		(start 154.584654 -332.64856)
		(end 156.926026 -345.920822)
		(width 0.14732)
		(layer "In13.Cu")
		(net "P5E_CPU1_PE2_RX_DN<9>")
	)
	(segment
		(start 156.926026 -345.920822)
		(end 155.796742 -359.992676)
		(width 0.14732)
		(layer "In13.Cu")
		(net "P5E_CPU1_PE2_RX_DN<9>")
	)
	(segment
		(start 140.634974 -404.618952)
		(end 138.917934 -406.335992)
		(width 0.14732)
		(layer "In13.Cu")
		(net "P5E_CPU1_PE2_RX_DN<9>")
	)
	(segment
		(start 148.590508 -250.28652)
		(end 148.591524 -250.312428)
		(width 0.14732)
		(layer "In13.Cu")
		(net "P5E_CPU1_PE2_RX_DN<9>")
	)
	(segment
		(start 129.401062 -217.07856)
		(end 129.401062 -217.064336)
		(width 0.0889)
		(layer "In13.Cu")
		(net "P5E_CPU1_PE2_RX_DN<9>")
	)
	(segment
		(start 141.866874 -396.084298)
		(end 140.944854 -398.473422)
		(width 0.14732)
		(layer "In13.Cu")
		(net "P5E_CPU1_PE2_RX_DN<9>")
	)
	(segment
		(start 130.810508 -214.622634)
		(end 130.810508 -214.425784)
		(width 0.0889)
		(layer "In13.Cu")
		(net "P5E_CPU1_PE2_RX_DN<9>")
	)
	(segment
		(start 155.796742 -359.992676)
		(end 142.114016 -395.444218)
		(width 0.14732)
		(layer "In13.Cu")
		(net "P5E_CPU1_PE2_RX_DN<9>")
	)
	(segment
		(start 140.944854 -398.473422)
		(end 140.634974 -400.19097)
		(width 0.14732)
		(layer "In13.Cu")
		(net "P5E_CPU1_PE2_RX_DN<9>")
	)
	(segment
		(start 129.692654 -219.18676)
		(end 129.683764 -219.18168)
		(width 0.0889)
		(layer "In13.Cu")
		(net "P5E_CPU1_PE2_RX_DN<9>")
	)
	(segment
		(start 130.340862 -215.436704)
		(end 130.340862 -215.414606)
		(width 0.0889)
		(layer "In13.Cu")
		(net "P5E_CPU1_PE2_RX_DN<9>")
	)
	(segment
		(start 132.639308 -212.589364)
		(end 139.093194 -213.87308)
		(width 0.14732)
		(layer "In13.Cu")
		(net "P5E_CPU1_PE2_RX_DN<9>")
	)
	(segment
		(start 130.15341 -215.761062)
		(end 130.1623 -215.755982)
		(width 0.0889)
		(layer "In13.Cu")
		(net "P5E_CPU1_PE2_RX_DN<9>")
	)
	(segment
		(start 148.686012 -253.169674)
		(end 148.685758 -253.169674)
		(width 0.14732)
		(layer "In13.Cu")
		(net "P5E_CPU1_PE2_RX_DN<9>")
	)
	(segment
		(start 129.68097 -216.576402)
		(end 129.683764 -216.574878)
		(width 0.0889)
		(layer "In13.Cu")
		(net "P5E_CPU1_PE2_RX_DN<9>")
	)
	(segment
		(start 148.687028 -253.154688)
		(end 148.686012 -253.169674)
		(width 0.14732)
		(layer "In13.Cu")
		(net "P5E_CPU1_PE2_RX_DN<9>")
	)
	(segment
		(start 131.239006 -213.352888)
		(end 131.239006 -213.030562)
		(width 0.14732)
		(layer "In13.Cu")
		(net "P5E_CPU1_PE2_RX_DN<9>")
	)
	(segment
		(start 129.683764 -216.574878)
		(end 129.692654 -216.569798)
		(width 0.0889)
		(layer "In13.Cu")
		(net "P5E_CPU1_PE2_RX_DN<9>")
	)
	(segment
		(start 137.054082 -423.961306)
		(end 137.053574 -423.98569)
		(width 0.14732)
		(layer "In13.Cu")
		(net "P5E_CPU1_PE2_RX_DN<9>")
	)
	(segment
		(start 137.750042 -433.552346)
		(end 137.750042 -433.289964)
		(width 0.14732)
		(layer "In13.Cu")
		(net "P5E_CPU1_PE2_RX_DN<9>")
	)
	(segment
		(start 129.68097 -219.83192)
		(end 129.683764 -219.830396)
		(width 0.0889)
		(layer "In13.Cu")
		(net "P5E_CPU1_PE2_RX_DN<9>")
	)
	(segment
		(start 129.683764 -218.202764)
		(end 129.685288 -218.202002)
		(width 0.0889)
		(layer "In13.Cu")
		(net "P5E_CPU1_PE2_RX_DN<9>")
	)
	(segment
		(start 137.58291 -433.719478)
		(end 137.750042 -433.552346)
		(width 0.14732)
		(layer "In13.Cu")
		(net "P5E_CPU1_PE2_RX_DN<9>")
	)
	(segment
		(start 129.401062 -220.334078)
		(end 129.401062 -220.319854)
		(width 0.0889)
		(layer "In13.Cu")
		(net "P5E_CPU1_PE2_RX_DN<9>")
	)
	(segment
		(start 129.685288 -218.202002)
		(end 129.692654 -218.197684)
		(width 0.0889)
		(layer "In13.Cu")
		(net "P5E_CPU1_PE2_RX_DN<9>")
	)
	(segment
		(start 137.190988 -433.719478)
		(end 137.58291 -433.719478)
		(width 0.14732)
		(layer "In13.Cu")
		(net "P5E_CPU1_PE2_RX_DN<9>")
	)
	(segment
		(start 131.280916 -213.8934)
		(end 131.280916 -213.732618)
		(width 0.0889)
		(layer "In13.Cu")
		(net "P5E_CPU1_PE2_RX_DN<9>")
	)
	(segment
		(start 141.64564 -215.683592)
		(end 144.51838 -225.339402)
		(width 0.14732)
		(layer "In13.Cu")
		(net "P5E_CPU1_PE2_RX_DN<9>")
	)
	(segment
		(start 129.685288 -219.829634)
		(end 129.692654 -219.825316)
		(width 0.0889)
		(layer "In13.Cu")
		(net "P5E_CPU1_PE2_RX_DN<9>")
	)
	(segment
		(start 129.677668 -219.833952)
		(end 129.68097 -219.83192)
		(width 0.0889)
		(layer "In13.Cu")
		(net "P5E_CPU1_PE2_RX_DN<9>")
	)
	(segment
		(start 144.51838 -225.339402)
		(end 145.375376 -229.672896)
		(width 0.14732)
		(layer "In13.Cu")
		(net "P5E_CPU1_PE2_RX_DN<9>")
	)
	(segment
		(start 129.340102 -221.404942)
		(end 129.361184 -221.48292)
		(width 0.0889)
		(layer "In13.Cu")
		(net "P5E_CPU1_PE2_RX_DN<9>")
	)
	(segment
		(start 138.917934 -410.369766)
		(end 137.797286 -418.541454)
		(width 0.14732)
		(layer "In13.Cu")
		(net "P5E_CPU1_PE2_RX_DN<9>")
	)
	(segment
		(start 131.280916 -213.732618)
		(end 131.28117 -213.732364)
		(width 0.0889)
		(layer "In13.Cu")
		(net "P5E_CPU1_PE2_RX_DN<9>")
	)
	(segment
		(start 144.38376 -309.343044)
		(end 148.16328 -325.175118)
		(width 0.14732)
		(layer "In13.Cu")
		(net "P5E_CPU1_PE2_RX_DN<9>")
	)
	(segment
		(start 131.239006 -213.374986)
		(end 131.239006 -213.352888)
		(width 0.0889)
		(layer "In13.Cu")
		(net "P5E_CPU1_PE2_RX_DN<9>")
	)
	(segment
		(start 129.496566 -221.133924)
		(end 129.340102 -221.404942)
		(width 0.0889)
		(layer "In13.Cu")
		(net "P5E_CPU1_PE2_RX_DN<9>")
	)
	(segment
		(start 129.683764 -219.830396)
		(end 129.685288 -219.829634)
		(width 0.0889)
		(layer "In13.Cu")
		(net "P5E_CPU1_PE2_RX_DN<9>")
	)
	(segment
		(start 129.685288 -221.45752)
		(end 129.692654 -221.453202)
		(width 0.0889)
		(layer "In13.Cu")
		(net "P5E_CPU1_PE2_RX_DN<9>")
	)
	(segment
		(start 129.692654 -217.559128)
		(end 129.683764 -217.554048)
		(width 0.0889)
		(layer "In13.Cu")
		(net "P5E_CPU1_PE2_RX_DN<9>")
	)
	(segment
		(start 129.692654 -220.814646)
		(end 129.683764 -220.809566)
		(width 0.0889)
		(layer "In13.Cu")
		(net "P5E_CPU1_PE2_RX_DN<9>")
	)
	(segment
		(start 131.28117 -213.732364)
		(end 131.28117 -213.41715)
		(width 0.0889)
		(layer "In13.Cu")
		(net "P5E_CPU1_PE2_RX_DN<9>")
	)
	(segment
		(start 137.707878 -419.193472)
		(end 137.054082 -423.961306)
		(width 0.14732)
		(layer "In13.Cu")
		(net "P5E_CPU1_PE2_RX_DN<9>")
	)
	(segment
		(start 130.623056 -214.946992)
		(end 130.631946 -214.941912)
		(width 0.0889)
		(layer "In13.Cu")
		(net "P5E_CPU1_PE2_RX_DN<9>")
	)
	(segment
		(start 139.093194 -213.87308)
		(end 140.359638 -214.397844)
		(width 0.14732)
		(layer "In13.Cu")
		(net "P5E_CPU1_PE2_RX_DN<9>")
	)
	(segment
		(start 148.685758 -253.169674)
		(end 144.38376 -309.343044)
		(width 0.14732)
		(layer "In13.Cu")
		(net "P5E_CPU1_PE2_RX_DN<9>")
	)
	(arc
		(start 130.1623 -215.755982)
		(mid 130.293214 -215.619622)
		(end 130.340862 -215.436704)
		(width 0.0889)
		(layer "In13.Cu")
		(net "P5E_CPU1_PE2_RX_DN<9>")
	)
	(arc
		(start 129.683764 -220.809566)
		(mid 129.480283 -220.608762)
		(end 129.401062 -220.334078)
		(width 0.0889)
		(layer "In13.Cu")
		(net "P5E_CPU1_PE2_RX_DN<9>")
	)
	(arc
		(start 130.340862 -215.414606)
		(mid 130.421773 -215.144478)
		(end 130.623056 -214.946992)
		(width 0.0889)
		(layer "In13.Cu")
		(net "P5E_CPU1_PE2_RX_DN<9>")
	)
	(arc
		(start 129.871216 -216.235026)
		(mid 129.950586 -215.961292)
		(end 130.15341 -215.761062)
		(width 0.0889)
		(layer "In13.Cu")
		(net "P5E_CPU1_PE2_RX_DN<9>")
	)
	(arc
		(start 129.692654 -221.453202)
		(mid 129.871372 -221.133924)
		(end 129.692654 -220.814646)
		(width 0.0889)
		(layer "In13.Cu")
		(net "P5E_CPU1_PE2_RX_DN<9>")
	)
	(arc
		(start 129.677668 -219.178124)
		(mid 129.401094 -218.692222)
		(end 129.677668 -218.20632)
		(width 0.0889)
		(layer "In13.Cu")
		(net "P5E_CPU1_PE2_RX_DN<9>")
	)
	(arc
		(start 129.692654 -216.569798)
		(mid 129.823568 -216.433438)
		(end 129.871216 -216.25052)
		(width 0.0889)
		(layer "In13.Cu")
		(net "P5E_CPU1_PE2_RX_DN<9>")
	)
	(arc
		(start 130.810508 -214.425784)
		(mid 130.921948 -214.232389)
		(end 131.096512 -214.093298)
		(width 0.0889)
		(layer "In13.Cu")
		(net "P5E_CPU1_PE2_RX_DN<9>")
	)
	(arc
		(start 129.401062 -217.064336)
		(mid 129.475053 -216.78477)
		(end 129.677668 -216.578434)
		(width 0.0889)
		(layer "In13.Cu")
		(net "P5E_CPU1_PE2_RX_DN<9>")
	)
	(arc
		(start 131.096512 -214.093298)
		(mid 131.205908 -214.009201)
		(end 131.280916 -213.8934)
		(width 0.0889)
		(layer "In13.Cu")
		(net "P5E_CPU1_PE2_RX_DN<9>")
	)
	(arc
		(start 130.631946 -214.941912)
		(mid 130.76286 -214.805552)
		(end 130.810508 -214.622634)
		(width 0.0889)
		(layer "In13.Cu")
		(net "P5E_CPU1_PE2_RX_DN<9>")
	)
	(arc
		(start 129.692654 -218.197684)
		(mid 129.871372 -217.878406)
		(end 129.692654 -217.559128)
		(width 0.0889)
		(layer "In13.Cu")
		(net "P5E_CPU1_PE2_RX_DN<9>")
	)
	(arc
		(start 129.361184 -221.48292)
		(mid 129.52528 -221.507267)
		(end 129.683764 -221.458282)
		(width 0.0889)
		(layer "In13.Cu")
		(net "P5E_CPU1_PE2_RX_DN<9>")
	)
	(arc
		(start 129.692654 -219.825316)
		(mid 129.871251 -219.506038)
		(end 129.692654 -219.18676)
		(width 0.0889)
		(layer "In13.Cu")
		(net "P5E_CPU1_PE2_RX_DN<9>")
	)
	(arc
		(start 129.683764 -217.554048)
		(mid 129.480283 -217.353244)
		(end 129.401062 -217.07856)
		(width 0.0889)
		(layer "In13.Cu")
		(net "P5E_CPU1_PE2_RX_DN<9>")
	)
	(arc
		(start 129.401062 -220.319854)
		(mid 129.475053 -220.040288)
		(end 129.677668 -219.833952)
		(width 0.0889)
		(layer "In13.Cu")
		(net "P5E_CPU1_PE2_RX_DN<9>")
	)
	(segment
		(start 128.086866 -220.320108)
		(end 128.086612 -220.319854)
		(width 0.13208)
		(layer "F.Cu")
		(net "P5E_CPU1_PE2_RX_DN<8>")
	)
	(segment
		(start 128.086866 -220.855794)
		(end 128.086866 -220.320108)
		(width 0.13208)
		(layer "F.Cu")
		(net "P5E_CPU1_PE2_RX_DN<8>")
	)
	(segment
		(start 128.731772 -219.837508)
		(end 128.740154 -219.832682)
		(width 0.0889)
		(layer "In13.Cu")
		(net "P5E_CPU1_PE2_RX_DN<8>")
	)
	(segment
		(start 128.743964 -219.18168)
		(end 128.743202 -219.181172)
		(width 0.0889)
		(layer "In13.Cu")
		(net "P5E_CPU1_PE2_RX_DN<8>")
	)
	(segment
		(start 128.743202 -218.203272)
		(end 128.743964 -218.202764)
		(width 0.0889)
		(layer "In13.Cu")
		(net "P5E_CPU1_PE2_RX_DN<8>")
	)
	(segment
		(start 149.620732 -253.218442)
		(end 145.35658 -309.287164)
		(width 0.14732)
		(layer "In13.Cu")
		(net "P5E_CPU1_PE2_RX_DN<8>")
	)
	(segment
		(start 128.749298 -218.199716)
		(end 128.750822 -218.198954)
		(width 0.0889)
		(layer "In13.Cu")
		(net "P5E_CPU1_PE2_RX_DN<8>")
	)
	(segment
		(start 157.927802 -346.188792)
		(end 156.850842 -360.097578)
		(width 0.14732)
		(layer "In13.Cu")
		(net "P5E_CPU1_PE2_RX_DN<8>")
	)
	(segment
		(start 128.741678 -218.204034)
		(end 128.743202 -218.203272)
		(width 0.0889)
		(layer "In13.Cu")
		(net "P5E_CPU1_PE2_RX_DN<8>")
	)
	(segment
		(start 128.743964 -219.830396)
		(end 128.752854 -219.825316)
		(width 0.0889)
		(layer "In13.Cu")
		(net "P5E_CPU1_PE2_RX_DN<8>")
	)
	(segment
		(start 146.30146 -229.50424)
		(end 149.51075 -249.950478)
		(width 0.14732)
		(layer "In13.Cu")
		(net "P5E_CPU1_PE2_RX_DN<8>")
	)
	(segment
		(start 129.21361 -215.761062)
		(end 129.2225 -215.755982)
		(width 0.0889)
		(layer "In13.Cu")
		(net "P5E_CPU1_PE2_RX_DN<8>")
	)
	(segment
		(start 129.686558 -214.261954)
		(end 129.686812 -214.261954)
		(width 0.0889)
		(layer "In13.Cu")
		(net "P5E_CPU1_PE2_RX_DN<8>")
	)
	(segment
		(start 128.752854 -217.559128)
		(end 128.744726 -217.554556)
		(width 0.0889)
		(layer "In13.Cu")
		(net "P5E_CPU1_PE2_RX_DN<8>")
	)
	(segment
		(start 131.519676 -211.649564)
		(end 133.28904 -211.649564)
		(width 0.14732)
		(layer "In13.Cu")
		(net "P5E_CPU1_PE2_RX_DN<8>")
	)
	(segment
		(start 128.743964 -218.202764)
		(end 128.746758 -218.20124)
		(width 0.0889)
		(layer "In13.Cu")
		(net "P5E_CPU1_PE2_RX_DN<8>")
	)
	(segment
		(start 143.955262 -398.537176)
		(end 143.698214 -400.254216)
		(width 0.14732)
		(layer "In13.Cu")
		(net "P5E_CPU1_PE2_RX_DN<8>")
	)
	(segment
		(start 128.931416 -216.25052)
		(end 128.931416 -216.235026)
		(width 0.0889)
		(layer "In13.Cu")
		(net "P5E_CPU1_PE2_RX_DN<8>")
	)
	(segment
		(start 128.086612 -220.319854)
		(end 128.243076 -220.590872)
		(width 0.0889)
		(layer "In13.Cu")
		(net "P5E_CPU1_PE2_RX_DN<8>")
	)
	(segment
		(start 128.740154 -219.832682)
		(end 128.743964 -219.830396)
		(width 0.0889)
		(layer "In13.Cu")
		(net "P5E_CPU1_PE2_RX_DN<8>")
	)
	(segment
		(start 128.743202 -219.181172)
		(end 128.737868 -219.178124)
		(width 0.0889)
		(layer "In13.Cu")
		(net "P5E_CPU1_PE2_RX_DN<8>")
	)
	(segment
		(start 139.066524 -424.106848)
		(end 139.066524 -434.57368)
		(width 0.14732)
		(layer "In13.Cu")
		(net "P5E_CPU1_PE2_RX_DN<8>")
	)
	(segment
		(start 128.752854 -219.18676)
		(end 128.745488 -219.182442)
		(width 0.0889)
		(layer "In13.Cu")
		(net "P5E_CPU1_PE2_RX_DN<8>")
	)
	(segment
		(start 128.750822 -218.198954)
		(end 128.752854 -218.197684)
		(width 0.0889)
		(layer "In13.Cu")
		(net "P5E_CPU1_PE2_RX_DN<8>")
	)
	(segment
		(start 129.401062 -215.436704)
		(end 129.401062 -215.414606)
		(width 0.0889)
		(layer "In13.Cu")
		(net "P5E_CPU1_PE2_RX_DN<8>")
	)
	(segment
		(start 143.698214 -400.254216)
		(end 143.698214 -404.618952)
		(width 0.14732)
		(layer "In13.Cu")
		(net "P5E_CPU1_PE2_RX_DN<8>")
	)
	(segment
		(start 139.21232 -434.719476)
		(end 139.582906 -434.719476)
		(width 0.14732)
		(layer "In13.Cu")
		(net "P5E_CPU1_PE2_RX_DN<8>")
	)
	(segment
		(start 133.28904 -211.649564)
		(end 140.376402 -213.059264)
		(width 0.14732)
		(layer "In13.Cu")
		(net "P5E_CPU1_PE2_RX_DN<8>")
	)
	(segment
		(start 139.066524 -434.57368)
		(end 139.21232 -434.719476)
		(width 0.14732)
		(layer "In13.Cu")
		(net "P5E_CPU1_PE2_RX_DN<8>")
	)
	(segment
		(start 145.01241 -395.777212)
		(end 144.873472 -396.19174)
		(width 0.14732)
		(layer "In13.Cu")
		(net "P5E_CPU1_PE2_RX_DN<8>")
	)
	(segment
		(start 156.850842 -360.097578)
		(end 144.934178 -395.619732)
		(width 0.14732)
		(layer "In13.Cu")
		(net "P5E_CPU1_PE2_RX_DN<8>")
	)
	(segment
		(start 129.359152 -212.917024)
		(end 129.995422 -212.280754)
		(width 0.14732)
		(layer "In13.Cu")
		(net "P5E_CPU1_PE2_RX_DN<8>")
	)
	(segment
		(start 128.746758 -218.20124)
		(end 128.749298 -218.199716)
		(width 0.0889)
		(layer "In13.Cu")
		(net "P5E_CPU1_PE2_RX_DN<8>")
	)
	(segment
		(start 144.873472 -396.19174)
		(end 144.715738 -396.270226)
		(width 0.14732)
		(layer "In13.Cu")
		(net "P5E_CPU1_PE2_RX_DN<8>")
	)
	(segment
		(start 139.582906 -434.719476)
		(end 139.750038 -434.552344)
		(width 0.14732)
		(layer "In13.Cu")
		(net "P5E_CPU1_PE2_RX_DN<8>")
	)
	(segment
		(start 145.35658 -309.287164)
		(end 149.011894 -324.674738)
		(width 0.14732)
		(layer "In13.Cu")
		(net "P5E_CPU1_PE2_RX_DN<8>")
	)
	(segment
		(start 139.750038 -434.552344)
		(end 139.750038 -434.289962)
		(width 0.14732)
		(layer "In13.Cu")
		(net "P5E_CPU1_PE2_RX_DN<8>")
	)
	(segment
		(start 144.715738 -396.270226)
		(end 143.955262 -398.537176)
		(width 0.14732)
		(layer "In13.Cu")
		(net "P5E_CPU1_PE2_RX_DN<8>")
	)
	(segment
		(start 149.011894 -324.674738)
		(end 155.455874 -332.176374)
		(width 0.14732)
		(layer "In13.Cu")
		(net "P5E_CPU1_PE2_RX_DN<8>")
	)
	(segment
		(start 144.934178 -395.619732)
		(end 145.01241 -395.777212)
		(width 0.14732)
		(layer "In13.Cu")
		(net "P5E_CPU1_PE2_RX_DN<8>")
	)
	(segment
		(start 142.52067 -215.203024)
		(end 145.46961 -225.1837)
		(width 0.14732)
		(layer "In13.Cu")
		(net "P5E_CPU1_PE2_RX_DN<8>")
	)
	(segment
		(start 141.981174 -410.787342)
		(end 139.066524 -424.106848)
		(width 0.14732)
		(layer "In13.Cu")
		(net "P5E_CPU1_PE2_RX_DN<8>")
	)
	(segment
		(start 149.51075 -249.950478)
		(end 149.620732 -253.218442)
		(width 0.14732)
		(layer "In13.Cu")
		(net "P5E_CPU1_PE2_RX_DN<8>")
	)
	(segment
		(start 128.743964 -216.574878)
		(end 128.752854 -216.569798)
		(width 0.0889)
		(layer "In13.Cu")
		(net "P5E_CPU1_PE2_RX_DN<8>")
	)
	(segment
		(start 129.401316 -213.3219)
		(end 129.359152 -213.279736)
		(width 0.0889)
		(layer "In13.Cu")
		(net "P5E_CPU1_PE2_RX_DN<8>")
	)
	(segment
		(start 155.455874 -332.176374)
		(end 157.927802 -346.188792)
		(width 0.14732)
		(layer "In13.Cu")
		(net "P5E_CPU1_PE2_RX_DN<8>")
	)
	(segment
		(start 145.46961 -225.1837)
		(end 146.30146 -229.50424)
		(width 0.14732)
		(layer "In13.Cu")
		(net "P5E_CPU1_PE2_RX_DN<8>")
	)
	(segment
		(start 129.359152 -213.257638)
		(end 129.359152 -212.917024)
		(width 0.14732)
		(layer "In13.Cu")
		(net "P5E_CPU1_PE2_RX_DN<8>")
	)
	(segment
		(start 129.995422 -212.280754)
		(end 131.519676 -211.649564)
		(width 0.14732)
		(layer "In13.Cu")
		(net "P5E_CPU1_PE2_RX_DN<8>")
	)
	(segment
		(start 129.359152 -213.279736)
		(end 129.359152 -213.257638)
		(width 0.0889)
		(layer "In13.Cu")
		(net "P5E_CPU1_PE2_RX_DN<8>")
	)
	(segment
		(start 143.698214 -404.618952)
		(end 141.981174 -406.335992)
		(width 0.14732)
		(layer "In13.Cu")
		(net "P5E_CPU1_PE2_RX_DN<8>")
	)
	(segment
		(start 128.745488 -219.182442)
		(end 128.743964 -219.18168)
		(width 0.0889)
		(layer "In13.Cu")
		(net "P5E_CPU1_PE2_RX_DN<8>")
	)
	(segment
		(start 129.870708 -214.622634)
		(end 129.870708 -214.461344)
		(width 0.0889)
		(layer "In13.Cu")
		(net "P5E_CPU1_PE2_RX_DN<8>")
	)
	(segment
		(start 128.744726 -217.554556)
		(end 128.743964 -217.554048)
		(width 0.0889)
		(layer "In13.Cu")
		(net "P5E_CPU1_PE2_RX_DN<8>")
	)
	(segment
		(start 128.740154 -216.577164)
		(end 128.743964 -216.574878)
		(width 0.0889)
		(layer "In13.Cu")
		(net "P5E_CPU1_PE2_RX_DN<8>")
	)
	(segment
		(start 140.376402 -213.059264)
		(end 142.52067 -215.203024)
		(width 0.14732)
		(layer "In13.Cu")
		(net "P5E_CPU1_PE2_RX_DN<8>")
	)
	(segment
		(start 129.401316 -213.929468)
		(end 129.401316 -213.3219)
		(width 0.0889)
		(layer "In13.Cu")
		(net "P5E_CPU1_PE2_RX_DN<8>")
	)
	(segment
		(start 129.683256 -214.946992)
		(end 129.692146 -214.941912)
		(width 0.0889)
		(layer "In13.Cu")
		(net "P5E_CPU1_PE2_RX_DN<8>")
	)
	(segment
		(start 128.243076 -220.590872)
		(end 128.321308 -220.6117)
		(width 0.0889)
		(layer "In13.Cu")
		(net "P5E_CPU1_PE2_RX_DN<8>")
	)
	(segment
		(start 141.981174 -406.335992)
		(end 141.981174 -410.787342)
		(width 0.14732)
		(layer "In13.Cu")
		(net "P5E_CPU1_PE2_RX_DN<8>")
	)
	(segment
		(start 128.731772 -216.58199)
		(end 128.740154 -216.577164)
		(width 0.0889)
		(layer "In13.Cu")
		(net "P5E_CPU1_PE2_RX_DN<8>")
	)
	(segment
		(start 128.737868 -218.20632)
		(end 128.741678 -218.204034)
		(width 0.0889)
		(layer "In13.Cu")
		(net "P5E_CPU1_PE2_RX_DN<8>")
	)
	(segment
		(start 128.461262 -217.071956)
		(end 128.461262 -217.064336)
		(width 0.0889)
		(layer "In13.Cu")
		(net "P5E_CPU1_PE2_RX_DN<8>")
	)
	(arc
		(start 129.401062 -215.414606)
		(mid 129.481973 -215.144478)
		(end 129.683256 -214.946992)
		(width 0.0889)
		(layer "In13.Cu")
		(net "P5E_CPU1_PE2_RX_DN<8>")
	)
	(arc
		(start 129.870708 -214.461344)
		(mid 129.795703 -214.345885)
		(end 129.686558 -214.261954)
		(width 0.0889)
		(layer "In13.Cu")
		(net "P5E_CPU1_PE2_RX_DN<8>")
	)
	(arc
		(start 128.321308 -220.6117)
		(mid 128.424453 -220.481675)
		(end 128.461262 -220.319854)
		(width 0.0889)
		(layer "In13.Cu")
		(net "P5E_CPU1_PE2_RX_DN<8>")
	)
	(arc
		(start 129.686812 -214.261954)
		(mid 129.526707 -214.138661)
		(end 129.41681 -213.969092)
		(width 0.0889)
		(layer "In13.Cu")
		(net "P5E_CPU1_PE2_RX_DN<8>")
	)
	(arc
		(start 128.752854 -216.569798)
		(mid 128.883768 -216.433438)
		(end 128.931416 -216.25052)
		(width 0.0889)
		(layer "In13.Cu")
		(net "P5E_CPU1_PE2_RX_DN<8>")
	)
	(arc
		(start 129.2225 -215.755982)
		(mid 129.353414 -215.619622)
		(end 129.401062 -215.436704)
		(width 0.0889)
		(layer "In13.Cu")
		(net "P5E_CPU1_PE2_RX_DN<8>")
	)
	(arc
		(start 129.41681 -213.969092)
		(mid 129.408709 -213.949419)
		(end 129.401316 -213.929468)
		(width 0.0889)
		(layer "In13.Cu")
		(net "P5E_CPU1_PE2_RX_DN<8>")
	)
	(arc
		(start 128.752854 -219.825316)
		(mid 128.931451 -219.506038)
		(end 128.752854 -219.18676)
		(width 0.0889)
		(layer "In13.Cu")
		(net "P5E_CPU1_PE2_RX_DN<8>")
	)
	(arc
		(start 129.692146 -214.941912)
		(mid 129.82306 -214.805552)
		(end 129.870708 -214.622634)
		(width 0.0889)
		(layer "In13.Cu")
		(net "P5E_CPU1_PE2_RX_DN<8>")
	)
	(arc
		(start 128.461262 -217.064336)
		(mid 128.533497 -216.787812)
		(end 128.731772 -216.58199)
		(width 0.0889)
		(layer "In13.Cu")
		(net "P5E_CPU1_PE2_RX_DN<8>")
	)
	(arc
		(start 128.743964 -217.554048)
		(mid 128.538892 -217.350369)
		(end 128.461262 -217.071956)
		(width 0.0889)
		(layer "In13.Cu")
		(net "P5E_CPU1_PE2_RX_DN<8>")
	)
	(arc
		(start 128.752854 -218.197684)
		(mid 128.93133 -217.878406)
		(end 128.752854 -217.559128)
		(width 0.0889)
		(layer "In13.Cu")
		(net "P5E_CPU1_PE2_RX_DN<8>")
	)
	(arc
		(start 128.737868 -219.178124)
		(mid 128.461294 -218.692222)
		(end 128.737868 -218.20632)
		(width 0.0889)
		(layer "In13.Cu")
		(net "P5E_CPU1_PE2_RX_DN<8>")
	)
	(arc
		(start 128.461262 -220.319854)
		(mid 128.533497 -220.04333)
		(end 128.731772 -219.837508)
		(width 0.0889)
		(layer "In13.Cu")
		(net "P5E_CPU1_PE2_RX_DN<8>")
	)
	(arc
		(start 128.931416 -216.235026)
		(mid 129.010786 -215.961292)
		(end 129.21361 -215.761062)
		(width 0.0889)
		(layer "In13.Cu")
		(net "P5E_CPU1_PE2_RX_DN<8>")
	)
	(segment
		(start 127.616712 -221.134178)
		(end 127.616966 -221.133924)
		(width 0.13208)
		(layer "F.Cu")
		(net "P5E_CPU1_PE2_RX_DN<7>")
	)
	(segment
		(start 127.616712 -221.669864)
		(end 127.616712 -221.134178)
		(width 0.13208)
		(layer "F.Cu")
		(net "P5E_CPU1_PE2_RX_DN<7>")
	)
	(segment
		(start 127.521462 -217.07856)
		(end 127.521462 -217.064336)
		(width 0.0889)
		(layer "In13.Cu")
		(net "P5E_CPU1_PE2_RX_DN<7>")
	)
	(segment
		(start 127.521462 -220.334078)
		(end 127.521462 -220.319854)
		(width 0.0889)
		(layer "In13.Cu")
		(net "P5E_CPU1_PE2_RX_DN<7>")
	)
	(segment
		(start 128.461516 -213.3219)
		(end 128.419352 -213.279736)
		(width 0.0889)
		(layer "In13.Cu")
		(net "P5E_CPU1_PE2_RX_DN<7>")
	)
	(segment
		(start 142.066264 -433.585874)
		(end 142.199868 -433.719478)
		(width 0.14732)
		(layer "In13.Cu")
		(net "P5E_CPU1_PE2_RX_DN<7>")
	)
	(segment
		(start 142.972028 -420.163244)
		(end 142.066264 -424.45686)
		(width 0.14732)
		(layer "In13.Cu")
		(net "P5E_CPU1_PE2_RX_DN<7>")
	)
	(segment
		(start 127.798068 -216.578434)
		(end 127.80137 -216.576402)
		(width 0.0889)
		(layer "In13.Cu")
		(net "P5E_CPU1_PE2_RX_DN<7>")
	)
	(segment
		(start 128.461516 -213.930484)
		(end 128.461516 -213.3219)
		(width 0.0889)
		(layer "In13.Cu")
		(net "P5E_CPU1_PE2_RX_DN<7>")
	)
	(segment
		(start 131.334002 -210.719924)
		(end 133.381242 -210.719924)
		(width 0.14732)
		(layer "In13.Cu")
		(net "P5E_CPU1_PE2_RX_DN<7>")
	)
	(segment
		(start 127.804164 -216.574878)
		(end 127.805688 -216.574116)
		(width 0.0889)
		(layer "In13.Cu")
		(net "P5E_CPU1_PE2_RX_DN<7>")
	)
	(segment
		(start 128.930908 -214.622634)
		(end 128.930908 -214.461344)
		(width 0.0889)
		(layer "In13.Cu")
		(net "P5E_CPU1_PE2_RX_DN<7>")
	)
	(segment
		(start 129.46888 -211.492338)
		(end 130.401568 -211.106258)
		(width 0.14732)
		(layer "In13.Cu")
		(net "P5E_CPU1_PE2_RX_DN<7>")
	)
	(segment
		(start 146.643344 -225.746056)
		(end 150.417276 -249.212354)
		(width 0.14732)
		(layer "In13.Cu")
		(net "P5E_CPU1_PE2_RX_DN<7>")
	)
	(segment
		(start 147.039076 -398.27327)
		(end 146.761454 -400.377152)
		(width 0.14732)
		(layer "In13.Cu")
		(net "P5E_CPU1_PE2_RX_DN<7>")
	)
	(segment
		(start 145.044414 -406.335992)
		(end 145.044414 -410.336746)
		(width 0.14732)
		(layer "In13.Cu")
		(net "P5E_CPU1_PE2_RX_DN<7>")
	)
	(segment
		(start 146.761454 -400.377152)
		(end 146.761454 -404.618952)
		(width 0.14732)
		(layer "In13.Cu")
		(net "P5E_CPU1_PE2_RX_DN<7>")
	)
	(segment
		(start 128.419352 -213.257638)
		(end 128.419352 -212.794088)
		(width 0.14732)
		(layer "In13.Cu")
		(net "P5E_CPU1_PE2_RX_DN<7>")
	)
	(segment
		(start 128.597406 -212.363812)
		(end 129.46888 -211.492338)
		(width 0.14732)
		(layer "In13.Cu")
		(net "P5E_CPU1_PE2_RX_DN<7>")
	)
	(segment
		(start 158.91002 -345.886786)
		(end 157.83941 -360.269536)
		(width 0.14732)
		(layer "In13.Cu")
		(net "P5E_CPU1_PE2_RX_DN<7>")
	)
	(segment
		(start 128.27381 -215.761062)
		(end 128.2827 -215.755982)
		(width 0.0889)
		(layer "In13.Cu")
		(net "P5E_CPU1_PE2_RX_DN<7>")
	)
	(segment
		(start 133.381242 -210.719924)
		(end 141.02207 -212.239606)
		(width 0.14732)
		(layer "In13.Cu")
		(net "P5E_CPU1_PE2_RX_DN<7>")
	)
	(segment
		(start 150.552658 -253.23673)
		(end 150.553166 -253.251716)
		(width 0.14732)
		(layer "In13.Cu")
		(net "P5E_CPU1_PE2_RX_DN<7>")
	)
	(segment
		(start 128.419352 -212.794088)
		(end 128.597406 -212.363812)
		(width 0.14732)
		(layer "In13.Cu")
		(net "P5E_CPU1_PE2_RX_DN<7>")
	)
	(segment
		(start 128.419352 -213.279736)
		(end 128.419352 -213.257638)
		(width 0.0889)
		(layer "In13.Cu")
		(net "P5E_CPU1_PE2_RX_DN<7>")
	)
	(segment
		(start 130.401568 -211.106258)
		(end 130.401314 -211.106258)
		(width 0.14732)
		(layer "In13.Cu")
		(net "P5E_CPU1_PE2_RX_DN<7>")
	)
	(segment
		(start 150.552658 -253.236476)
		(end 150.552658 -253.23673)
		(width 0.14732)
		(layer "In13.Cu")
		(net "P5E_CPU1_PE2_RX_DN<7>")
	)
	(segment
		(start 130.401314 -211.106258)
		(end 131.334002 -210.719924)
		(width 0.14732)
		(layer "In13.Cu")
		(net "P5E_CPU1_PE2_RX_DN<7>")
	)
	(segment
		(start 127.803402 -218.203272)
		(end 127.804164 -218.202764)
		(width 0.0889)
		(layer "In13.Cu")
		(net "P5E_CPU1_PE2_RX_DN<7>")
	)
	(segment
		(start 127.813054 -217.559128)
		(end 127.804164 -217.554048)
		(width 0.0889)
		(layer "In13.Cu")
		(net "P5E_CPU1_PE2_RX_DN<7>")
	)
	(segment
		(start 150.55215 -253.266448)
		(end 150.551896 -253.266448)
		(width 0.14732)
		(layer "In13.Cu")
		(net "P5E_CPU1_PE2_RX_DN<7>")
	)
	(segment
		(start 143.384524 -418.910008)
		(end 143.21282 -419.021768)
		(width 0.14732)
		(layer "In13.Cu")
		(net "P5E_CPU1_PE2_RX_DN<7>")
	)
	(segment
		(start 143.39951 -214.617046)
		(end 146.643344 -225.746056)
		(width 0.14732)
		(layer "In13.Cu")
		(net "P5E_CPU1_PE2_RX_DN<7>")
	)
	(segment
		(start 127.805688 -221.45752)
		(end 127.813054 -221.453202)
		(width 0.0889)
		(layer "In13.Cu")
		(net "P5E_CPU1_PE2_RX_DN<7>")
	)
	(segment
		(start 150.551896 -253.266448)
		(end 146.31924 -309.193438)
		(width 0.14732)
		(layer "In13.Cu")
		(net "P5E_CPU1_PE2_RX_DN<7>")
	)
	(segment
		(start 142.750032 -433.552346)
		(end 142.750032 -433.289964)
		(width 0.14732)
		(layer "In13.Cu")
		(net "P5E_CPU1_PE2_RX_DN<7>")
	)
	(segment
		(start 142.066264 -424.45686)
		(end 142.066264 -433.585874)
		(width 0.14732)
		(layer "In13.Cu")
		(net "P5E_CPU1_PE2_RX_DN<7>")
	)
	(segment
		(start 127.804164 -221.458282)
		(end 127.805688 -221.45752)
		(width 0.0889)
		(layer "In13.Cu")
		(net "P5E_CPU1_PE2_RX_DN<7>")
	)
	(segment
		(start 141.02207 -212.239606)
		(end 143.39951 -214.617046)
		(width 0.14732)
		(layer "In13.Cu")
		(net "P5E_CPU1_PE2_RX_DN<7>")
	)
	(segment
		(start 156.439616 -331.886052)
		(end 158.91002 -345.886786)
		(width 0.14732)
		(layer "In13.Cu")
		(net "P5E_CPU1_PE2_RX_DN<7>")
	)
	(segment
		(start 143.107918 -419.519354)
		(end 143.219678 -419.691058)
		(width 0.14732)
		(layer "In13.Cu")
		(net "P5E_CPU1_PE2_RX_DN<7>")
	)
	(segment
		(start 142.199868 -433.719478)
		(end 142.5829 -433.719478)
		(width 0.14732)
		(layer "In13.Cu")
		(net "P5E_CPU1_PE2_RX_DN<7>")
	)
	(segment
		(start 127.804164 -219.18168)
		(end 127.798068 -219.178124)
		(width 0.0889)
		(layer "In13.Cu")
		(net "P5E_CPU1_PE2_RX_DN<7>")
	)
	(segment
		(start 143.34871 -418.377624)
		(end 143.46047 -418.549328)
		(width 0.14732)
		(layer "In13.Cu")
		(net "P5E_CPU1_PE2_RX_DN<7>")
	)
	(segment
		(start 127.804164 -218.202764)
		(end 127.805688 -218.202002)
		(width 0.0889)
		(layer "In13.Cu")
		(net "P5E_CPU1_PE2_RX_DN<7>")
	)
	(segment
		(start 128.461262 -215.436704)
		(end 128.461262 -215.414606)
		(width 0.0889)
		(layer "In13.Cu")
		(net "P5E_CPU1_PE2_RX_DN<7>")
	)
	(segment
		(start 127.813054 -219.18676)
		(end 127.804164 -219.18168)
		(width 0.0889)
		(layer "In13.Cu")
		(net "P5E_CPU1_PE2_RX_DN<7>")
	)
	(segment
		(start 127.798068 -219.833952)
		(end 127.813054 -219.825316)
		(width 0.0889)
		(layer "In13.Cu")
		(net "P5E_CPU1_PE2_RX_DN<7>")
	)
	(segment
		(start 142.5829 -433.719478)
		(end 142.750032 -433.552346)
		(width 0.14732)
		(layer "In13.Cu")
		(net "P5E_CPU1_PE2_RX_DN<7>")
	)
	(segment
		(start 146.761454 -404.618952)
		(end 145.044414 -406.335992)
		(width 0.14732)
		(layer "In13.Cu")
		(net "P5E_CPU1_PE2_RX_DN<7>")
	)
	(segment
		(start 127.460502 -221.404942)
		(end 127.481584 -221.48292)
		(width 0.0889)
		(layer "In13.Cu")
		(net "P5E_CPU1_PE2_RX_DN<7>")
	)
	(segment
		(start 143.21282 -419.021768)
		(end 143.107918 -419.519354)
		(width 0.14732)
		(layer "In13.Cu")
		(net "P5E_CPU1_PE2_RX_DN<7>")
	)
	(segment
		(start 127.805688 -216.574116)
		(end 127.813054 -216.569798)
		(width 0.0889)
		(layer "In13.Cu")
		(net "P5E_CPU1_PE2_RX_DN<7>")
	)
	(segment
		(start 127.616966 -221.133924)
		(end 127.460502 -221.404942)
		(width 0.0889)
		(layer "In13.Cu")
		(net "P5E_CPU1_PE2_RX_DN<7>")
	)
	(segment
		(start 145.044414 -410.336746)
		(end 143.34871 -418.377624)
		(width 0.14732)
		(layer "In13.Cu")
		(net "P5E_CPU1_PE2_RX_DN<7>")
	)
	(segment
		(start 143.219678 -419.691058)
		(end 143.143478 -420.051738)
		(width 0.14732)
		(layer "In13.Cu")
		(net "P5E_CPU1_PE2_RX_DN<7>")
	)
	(segment
		(start 127.813054 -220.814646)
		(end 127.804164 -220.809566)
		(width 0.0889)
		(layer "In13.Cu")
		(net "P5E_CPU1_PE2_RX_DN<7>")
	)
	(segment
		(start 150.553166 -253.251716)
		(end 150.55215 -253.266448)
		(width 0.14732)
		(layer "In13.Cu")
		(net "P5E_CPU1_PE2_RX_DN<7>")
	)
	(segment
		(start 146.31924 -309.193438)
		(end 149.860254 -324.215252)
		(width 0.14732)
		(layer "In13.Cu")
		(net "P5E_CPU1_PE2_RX_DN<7>")
	)
	(segment
		(start 157.83941 -360.269536)
		(end 147.039076 -398.27327)
		(width 0.14732)
		(layer "In13.Cu")
		(net "P5E_CPU1_PE2_RX_DN<7>")
	)
	(segment
		(start 149.860254 -324.215252)
		(end 156.439616 -331.886052)
		(width 0.14732)
		(layer "In13.Cu")
		(net "P5E_CPU1_PE2_RX_DN<7>")
	)
	(segment
		(start 143.143478 -420.051738)
		(end 142.972028 -420.163244)
		(width 0.14732)
		(layer "In13.Cu")
		(net "P5E_CPU1_PE2_RX_DN<7>")
	)
	(segment
		(start 127.80137 -216.576402)
		(end 127.804164 -216.574878)
		(width 0.0889)
		(layer "In13.Cu")
		(net "P5E_CPU1_PE2_RX_DN<7>")
	)
	(segment
		(start 127.798068 -218.20632)
		(end 127.803402 -218.203272)
		(width 0.0889)
		(layer "In13.Cu")
		(net "P5E_CPU1_PE2_RX_DN<7>")
	)
	(segment
		(start 150.417276 -249.212354)
		(end 150.552658 -253.236476)
		(width 0.14732)
		(layer "In13.Cu")
		(net "P5E_CPU1_PE2_RX_DN<7>")
	)
	(segment
		(start 127.991616 -216.25052)
		(end 127.991616 -216.235026)
		(width 0.0889)
		(layer "In13.Cu")
		(net "P5E_CPU1_PE2_RX_DN<7>")
	)
	(segment
		(start 128.743456 -214.946992)
		(end 128.752346 -214.941912)
		(width 0.0889)
		(layer "In13.Cu")
		(net "P5E_CPU1_PE2_RX_DN<7>")
	)
	(segment
		(start 127.805688 -218.202002)
		(end 127.813054 -218.197684)
		(width 0.0889)
		(layer "In13.Cu")
		(net "P5E_CPU1_PE2_RX_DN<7>")
	)
	(segment
		(start 143.46047 -418.549328)
		(end 143.384524 -418.910008)
		(width 0.14732)
		(layer "In13.Cu")
		(net "P5E_CPU1_PE2_RX_DN<7>")
	)
	(arc
		(start 127.813054 -218.197684)
		(mid 127.991772 -217.878406)
		(end 127.813054 -217.559128)
		(width 0.0889)
		(layer "In13.Cu")
		(net "P5E_CPU1_PE2_RX_DN<7>")
	)
	(arc
		(start 127.804164 -217.554048)
		(mid 127.600683 -217.353244)
		(end 127.521462 -217.07856)
		(width 0.0889)
		(layer "In13.Cu")
		(net "P5E_CPU1_PE2_RX_DN<7>")
	)
	(arc
		(start 127.481584 -221.48292)
		(mid 127.64568 -221.507267)
		(end 127.804164 -221.458282)
		(width 0.0889)
		(layer "In13.Cu")
		(net "P5E_CPU1_PE2_RX_DN<7>")
	)
	(arc
		(start 128.746758 -214.261954)
		(mid 128.586686 -214.138774)
		(end 128.476756 -213.969346)
		(width 0.0889)
		(layer "In13.Cu")
		(net "P5E_CPU1_PE2_RX_DN<7>")
	)
	(arc
		(start 127.991616 -216.235026)
		(mid 128.070986 -215.961292)
		(end 128.27381 -215.761062)
		(width 0.0889)
		(layer "In13.Cu")
		(net "P5E_CPU1_PE2_RX_DN<7>")
	)
	(arc
		(start 127.798068 -219.178124)
		(mid 127.521494 -218.692222)
		(end 127.798068 -218.20632)
		(width 0.0889)
		(layer "In13.Cu")
		(net "P5E_CPU1_PE2_RX_DN<7>")
	)
	(arc
		(start 128.476756 -213.969346)
		(mid 128.468793 -213.950049)
		(end 128.461516 -213.930484)
		(width 0.0889)
		(layer "In13.Cu")
		(net "P5E_CPU1_PE2_RX_DN<7>")
	)
	(arc
		(start 127.813054 -221.453202)
		(mid 127.991772 -221.133924)
		(end 127.813054 -220.814646)
		(width 0.0889)
		(layer "In13.Cu")
		(net "P5E_CPU1_PE2_RX_DN<7>")
	)
	(arc
		(start 128.930908 -214.461344)
		(mid 128.855903 -214.345885)
		(end 128.746758 -214.261954)
		(width 0.0889)
		(layer "In13.Cu")
		(net "P5E_CPU1_PE2_RX_DN<7>")
	)
	(arc
		(start 127.804164 -220.809566)
		(mid 127.600683 -220.608762)
		(end 127.521462 -220.334078)
		(width 0.0889)
		(layer "In13.Cu")
		(net "P5E_CPU1_PE2_RX_DN<7>")
	)
	(arc
		(start 128.752346 -214.941912)
		(mid 128.88326 -214.805552)
		(end 128.930908 -214.622634)
		(width 0.0889)
		(layer "In13.Cu")
		(net "P5E_CPU1_PE2_RX_DN<7>")
	)
	(arc
		(start 128.461262 -215.414606)
		(mid 128.542173 -215.144478)
		(end 128.743456 -214.946992)
		(width 0.0889)
		(layer "In13.Cu")
		(net "P5E_CPU1_PE2_RX_DN<7>")
	)
	(arc
		(start 127.813054 -219.825316)
		(mid 127.991651 -219.506038)
		(end 127.813054 -219.18676)
		(width 0.0889)
		(layer "In13.Cu")
		(net "P5E_CPU1_PE2_RX_DN<7>")
	)
	(arc
		(start 128.2827 -215.755982)
		(mid 128.413614 -215.619622)
		(end 128.461262 -215.436704)
		(width 0.0889)
		(layer "In13.Cu")
		(net "P5E_CPU1_PE2_RX_DN<7>")
	)
	(arc
		(start 127.521462 -217.064336)
		(mid 127.595453 -216.78477)
		(end 127.798068 -216.578434)
		(width 0.0889)
		(layer "In13.Cu")
		(net "P5E_CPU1_PE2_RX_DN<7>")
	)
	(arc
		(start 127.813054 -216.569798)
		(mid 127.943968 -216.433438)
		(end 127.991616 -216.25052)
		(width 0.0889)
		(layer "In13.Cu")
		(net "P5E_CPU1_PE2_RX_DN<7>")
	)
	(arc
		(start 127.521462 -220.319854)
		(mid 127.595453 -220.040288)
		(end 127.798068 -219.833952)
		(width 0.0889)
		(layer "In13.Cu")
		(net "P5E_CPU1_PE2_RX_DN<7>")
	)
	(segment
		(start 126.207266 -220.855794)
		(end 126.207266 -220.320108)
		(width 0.13208)
		(layer "F.Cu")
		(net "P5E_CPU1_PE2_RX_DN<6>")
	)
	(segment
		(start 126.207266 -220.320108)
		(end 126.207012 -220.319854)
		(width 0.13208)
		(layer "F.Cu")
		(net "P5E_CPU1_PE2_RX_DN<6>")
	)
	(segment
		(start 127.479552 -213.279736)
		(end 127.479552 -213.257638)
		(width 0.0889)
		(layer "In13.Cu")
		(net "P5E_CPU1_PE2_RX_DN<6>")
	)
	(segment
		(start 131.148582 -209.790284)
		(end 134.109714 -209.790284)
		(width 0.14732)
		(layer "In13.Cu")
		(net "P5E_CPU1_PE2_RX_DN<6>")
	)
	(segment
		(start 145.283428 -419.986968)
		(end 145.381726 -420.1668)
		(width 0.14732)
		(layer "In13.Cu")
		(net "P5E_CPU1_PE2_RX_DN<6>")
	)
	(segment
		(start 126.873254 -217.559128)
		(end 126.864364 -217.554048)
		(width 0.0889)
		(layer "In13.Cu")
		(net "P5E_CPU1_PE2_RX_DN<6>")
	)
	(segment
		(start 126.858268 -218.20632)
		(end 126.873254 -218.197684)
		(width 0.0889)
		(layer "In13.Cu")
		(net "P5E_CPU1_PE2_RX_DN<6>")
	)
	(segment
		(start 127.521716 -213.929468)
		(end 127.521716 -213.3219)
		(width 0.0889)
		(layer "In13.Cu")
		(net "P5E_CPU1_PE2_RX_DN<6>")
	)
	(segment
		(start 144.582896 -434.719476)
		(end 144.750028 -434.552344)
		(width 0.14732)
		(layer "In13.Cu")
		(net "P5E_CPU1_PE2_RX_DN<6>")
	)
	(segment
		(start 150.696168 -323.707506)
		(end 157.31617 -331.439266)
		(width 0.14732)
		(layer "In13.Cu")
		(net "P5E_CPU1_PE2_RX_DN<6>")
	)
	(segment
		(start 145.098008 -420.618412)
		(end 145.098262 -420.618412)
		(width 0.14732)
		(layer "In13.Cu")
		(net "P5E_CPU1_PE2_RX_DN<6>")
	)
	(segment
		(start 126.864364 -216.574878)
		(end 126.873254 -216.569798)
		(width 0.0889)
		(layer "In13.Cu")
		(net "P5E_CPU1_PE2_RX_DN<6>")
	)
	(segment
		(start 151.498554 -253.360682)
		(end 147.26666 -309.074312)
		(width 0.14732)
		(layer "In13.Cu")
		(net "P5E_CPU1_PE2_RX_DN<6>")
	)
	(segment
		(start 151.350218 -248.893584)
		(end 151.499316 -253.33071)
		(width 0.14732)
		(layer "In13.Cu")
		(net "P5E_CPU1_PE2_RX_DN<6>")
	)
	(segment
		(start 126.860554 -219.832682)
		(end 126.864364 -219.830396)
		(width 0.0889)
		(layer "In13.Cu")
		(net "P5E_CPU1_PE2_RX_DN<6>")
	)
	(segment
		(start 126.865888 -219.182442)
		(end 126.864364 -219.18168)
		(width 0.0889)
		(layer "In13.Cu")
		(net "P5E_CPU1_PE2_RX_DN<6>")
	)
	(segment
		(start 141.396212 -211.239354)
		(end 144.262602 -214.106252)
		(width 0.14732)
		(layer "In13.Cu")
		(net "P5E_CPU1_PE2_RX_DN<6>")
	)
	(segment
		(start 151.499316 -253.330964)
		(end 151.499824 -253.34595)
		(width 0.14732)
		(layer "In13.Cu")
		(net "P5E_CPU1_PE2_RX_DN<6>")
	)
	(segment
		(start 126.581662 -217.071956)
		(end 126.581662 -217.064336)
		(width 0.0889)
		(layer "In13.Cu")
		(net "P5E_CPU1_PE2_RX_DN<6>")
	)
	(segment
		(start 127.803656 -214.946992)
		(end 127.812546 -214.941912)
		(width 0.0889)
		(layer "In13.Cu")
		(net "P5E_CPU1_PE2_RX_DN<6>")
	)
	(segment
		(start 145.098262 -420.618412)
		(end 144.066768 -424.134534)
		(width 0.14732)
		(layer "In13.Cu")
		(net "P5E_CPU1_PE2_RX_DN<6>")
	)
	(segment
		(start 144.262602 -214.106252)
		(end 147.59305 -225.532188)
		(width 0.14732)
		(layer "In13.Cu")
		(net "P5E_CPU1_PE2_RX_DN<6>")
	)
	(segment
		(start 126.207012 -220.319854)
		(end 126.363476 -220.590872)
		(width 0.0889)
		(layer "In13.Cu")
		(net "P5E_CPU1_PE2_RX_DN<6>")
	)
	(segment
		(start 127.479552 -213.257638)
		(end 127.479552 -212.633052)
		(width 0.14732)
		(layer "In13.Cu")
		(net "P5E_CPU1_PE2_RX_DN<6>")
	)
	(segment
		(start 126.864364 -219.830396)
		(end 126.873254 -219.825316)
		(width 0.0889)
		(layer "In13.Cu")
		(net "P5E_CPU1_PE2_RX_DN<6>")
	)
	(segment
		(start 127.806958 -214.261954)
		(end 127.807212 -214.261954)
		(width 0.0889)
		(layer "In13.Cu")
		(net "P5E_CPU1_PE2_RX_DN<6>")
	)
	(segment
		(start 127.479552 -212.633052)
		(end 127.809244 -211.836762)
		(width 0.14732)
		(layer "In13.Cu")
		(net "P5E_CPU1_PE2_RX_DN<6>")
	)
	(segment
		(start 144.165574 -434.719476)
		(end 144.582896 -434.719476)
		(width 0.14732)
		(layer "In13.Cu")
		(net "P5E_CPU1_PE2_RX_DN<6>")
	)
	(segment
		(start 148.107654 -410.359352)
		(end 145.283428 -419.986968)
		(width 0.14732)
		(layer "In13.Cu")
		(net "P5E_CPU1_PE2_RX_DN<6>")
	)
	(segment
		(start 144.066768 -424.134534)
		(end 144.066514 -424.134788)
		(width 0.14732)
		(layer "In13.Cu")
		(net "P5E_CPU1_PE2_RX_DN<6>")
	)
	(segment
		(start 127.991108 -214.622634)
		(end 127.991108 -214.461344)
		(width 0.0889)
		(layer "In13.Cu")
		(net "P5E_CPU1_PE2_RX_DN<6>")
	)
	(segment
		(start 128.94183 -210.704176)
		(end 131.148582 -209.790284)
		(width 0.14732)
		(layer "In13.Cu")
		(net "P5E_CPU1_PE2_RX_DN<6>")
	)
	(segment
		(start 134.109714 -209.790284)
		(end 141.396212 -211.239354)
		(width 0.14732)
		(layer "In13.Cu")
		(net "P5E_CPU1_PE2_RX_DN<6>")
	)
	(segment
		(start 149.824694 -404.618952)
		(end 148.107654 -406.335992)
		(width 0.14732)
		(layer "In13.Cu")
		(net "P5E_CPU1_PE2_RX_DN<6>")
	)
	(segment
		(start 150.082504 -397.393668)
		(end 149.824694 -399.599658)
		(width 0.14732)
		(layer "In13.Cu")
		(net "P5E_CPU1_PE2_RX_DN<6>")
	)
	(segment
		(start 148.107654 -406.335992)
		(end 148.107654 -410.359352)
		(width 0.14732)
		(layer "In13.Cu")
		(net "P5E_CPU1_PE2_RX_DN<6>")
	)
	(segment
		(start 151.499824 -253.34595)
		(end 151.498808 -253.360682)
		(width 0.14732)
		(layer "In13.Cu")
		(net "P5E_CPU1_PE2_RX_DN<6>")
	)
	(segment
		(start 126.873254 -219.18676)
		(end 126.865888 -219.182442)
		(width 0.0889)
		(layer "In13.Cu")
		(net "P5E_CPU1_PE2_RX_DN<6>")
	)
	(segment
		(start 126.852172 -219.837508)
		(end 126.860554 -219.832682)
		(width 0.0889)
		(layer "In13.Cu")
		(net "P5E_CPU1_PE2_RX_DN<6>")
	)
	(segment
		(start 127.521462 -215.436704)
		(end 127.521462 -215.414606)
		(width 0.0889)
		(layer "In13.Cu")
		(net "P5E_CPU1_PE2_RX_DN<6>")
	)
	(segment
		(start 126.852172 -216.58199)
		(end 126.860554 -216.577164)
		(width 0.0889)
		(layer "In13.Cu")
		(net "P5E_CPU1_PE2_RX_DN<6>")
	)
	(segment
		(start 145.278094 -420.520368)
		(end 145.098008 -420.618412)
		(width 0.14732)
		(layer "In13.Cu")
		(net "P5E_CPU1_PE2_RX_DN<6>")
	)
	(segment
		(start 144.066514 -424.134788)
		(end 144.066514 -434.620416)
		(width 0.14732)
		(layer "In13.Cu")
		(net "P5E_CPU1_PE2_RX_DN<6>")
	)
	(segment
		(start 127.051816 -216.25052)
		(end 127.051816 -216.235026)
		(width 0.0889)
		(layer "In13.Cu")
		(net "P5E_CPU1_PE2_RX_DN<6>")
	)
	(segment
		(start 159.910018 -346.146374)
		(end 158.870142 -360.317288)
		(width 0.14732)
		(layer "In13.Cu")
		(net "P5E_CPU1_PE2_RX_DN<6>")
	)
	(segment
		(start 158.870142 -360.317288)
		(end 150.082504 -397.393668)
		(width 0.14732)
		(layer "In13.Cu")
		(net "P5E_CPU1_PE2_RX_DN<6>")
	)
	(segment
		(start 149.824694 -399.599658)
		(end 149.824694 -404.618952)
		(width 0.14732)
		(layer "In13.Cu")
		(net "P5E_CPU1_PE2_RX_DN<6>")
	)
	(segment
		(start 151.498808 -253.360682)
		(end 151.498554 -253.360682)
		(width 0.14732)
		(layer "In13.Cu")
		(net "P5E_CPU1_PE2_RX_DN<6>")
	)
	(segment
		(start 127.33401 -215.761062)
		(end 127.3429 -215.755982)
		(width 0.0889)
		(layer "In13.Cu")
		(net "P5E_CPU1_PE2_RX_DN<6>")
	)
	(segment
		(start 127.521716 -213.3219)
		(end 127.479552 -213.279736)
		(width 0.0889)
		(layer "In13.Cu")
		(net "P5E_CPU1_PE2_RX_DN<6>")
	)
	(segment
		(start 144.066514 -434.620416)
		(end 144.165574 -434.719476)
		(width 0.14732)
		(layer "In13.Cu")
		(net "P5E_CPU1_PE2_RX_DN<6>")
	)
	(segment
		(start 126.864364 -219.18168)
		(end 126.863602 -219.181172)
		(width 0.0889)
		(layer "In13.Cu")
		(net "P5E_CPU1_PE2_RX_DN<6>")
	)
	(segment
		(start 126.363476 -220.590872)
		(end 126.441708 -220.6117)
		(width 0.0889)
		(layer "In13.Cu")
		(net "P5E_CPU1_PE2_RX_DN<6>")
	)
	(segment
		(start 147.59305 -225.532188)
		(end 151.350218 -248.893584)
		(width 0.14732)
		(layer "In13.Cu")
		(net "P5E_CPU1_PE2_RX_DN<6>")
	)
	(segment
		(start 157.31617 -331.439266)
		(end 159.910018 -346.146374)
		(width 0.14732)
		(layer "In13.Cu")
		(net "P5E_CPU1_PE2_RX_DN<6>")
	)
	(segment
		(start 145.381726 -420.1668)
		(end 145.278094 -420.520368)
		(width 0.14732)
		(layer "In13.Cu")
		(net "P5E_CPU1_PE2_RX_DN<6>")
	)
	(segment
		(start 147.26666 -309.074312)
		(end 150.696168 -323.707506)
		(width 0.14732)
		(layer "In13.Cu")
		(net "P5E_CPU1_PE2_RX_DN<6>")
	)
	(segment
		(start 126.863602 -219.181172)
		(end 126.858268 -219.178124)
		(width 0.0889)
		(layer "In13.Cu")
		(net "P5E_CPU1_PE2_RX_DN<6>")
	)
	(segment
		(start 126.860554 -216.577164)
		(end 126.864364 -216.574878)
		(width 0.0889)
		(layer "In13.Cu")
		(net "P5E_CPU1_PE2_RX_DN<6>")
	)
	(segment
		(start 144.750028 -434.552344)
		(end 144.750028 -434.289962)
		(width 0.14732)
		(layer "In13.Cu")
		(net "P5E_CPU1_PE2_RX_DN<6>")
	)
	(segment
		(start 151.499316 -253.33071)
		(end 151.499316 -253.330964)
		(width 0.14732)
		(layer "In13.Cu")
		(net "P5E_CPU1_PE2_RX_DN<6>")
	)
	(segment
		(start 127.809244 -211.836762)
		(end 128.94183 -210.704176)
		(width 0.14732)
		(layer "In13.Cu")
		(net "P5E_CPU1_PE2_RX_DN<6>")
	)
	(arc
		(start 126.873254 -216.569798)
		(mid 127.004168 -216.433438)
		(end 127.051816 -216.25052)
		(width 0.0889)
		(layer "In13.Cu")
		(net "P5E_CPU1_PE2_RX_DN<6>")
	)
	(arc
		(start 126.873254 -218.197684)
		(mid 127.05173 -217.878406)
		(end 126.873254 -217.559128)
		(width 0.0889)
		(layer "In13.Cu")
		(net "P5E_CPU1_PE2_RX_DN<6>")
	)
	(arc
		(start 127.521462 -215.414606)
		(mid 127.602373 -215.144478)
		(end 127.803656 -214.946992)
		(width 0.0889)
		(layer "In13.Cu")
		(net "P5E_CPU1_PE2_RX_DN<6>")
	)
	(arc
		(start 126.441708 -220.6117)
		(mid 126.544853 -220.481675)
		(end 126.581662 -220.319854)
		(width 0.0889)
		(layer "In13.Cu")
		(net "P5E_CPU1_PE2_RX_DN<6>")
	)
	(arc
		(start 127.53721 -213.969092)
		(mid 127.529109 -213.949419)
		(end 127.521716 -213.929468)
		(width 0.0889)
		(layer "In13.Cu")
		(net "P5E_CPU1_PE2_RX_DN<6>")
	)
	(arc
		(start 126.858268 -219.178124)
		(mid 126.581694 -218.692222)
		(end 126.858268 -218.20632)
		(width 0.0889)
		(layer "In13.Cu")
		(net "P5E_CPU1_PE2_RX_DN<6>")
	)
	(arc
		(start 126.864364 -217.554048)
		(mid 126.659292 -217.350369)
		(end 126.581662 -217.071956)
		(width 0.0889)
		(layer "In13.Cu")
		(net "P5E_CPU1_PE2_RX_DN<6>")
	)
	(arc
		(start 127.991108 -214.461344)
		(mid 127.916103 -214.345885)
		(end 127.806958 -214.261954)
		(width 0.0889)
		(layer "In13.Cu")
		(net "P5E_CPU1_PE2_RX_DN<6>")
	)
	(arc
		(start 126.873254 -219.825316)
		(mid 127.051851 -219.506038)
		(end 126.873254 -219.18676)
		(width 0.0889)
		(layer "In13.Cu")
		(net "P5E_CPU1_PE2_RX_DN<6>")
	)
	(arc
		(start 127.812546 -214.941912)
		(mid 127.94346 -214.805552)
		(end 127.991108 -214.622634)
		(width 0.0889)
		(layer "In13.Cu")
		(net "P5E_CPU1_PE2_RX_DN<6>")
	)
	(arc
		(start 126.581662 -220.319854)
		(mid 126.653897 -220.04333)
		(end 126.852172 -219.837508)
		(width 0.0889)
		(layer "In13.Cu")
		(net "P5E_CPU1_PE2_RX_DN<6>")
	)
	(arc
		(start 127.051816 -216.235026)
		(mid 127.131186 -215.961292)
		(end 127.33401 -215.761062)
		(width 0.0889)
		(layer "In13.Cu")
		(net "P5E_CPU1_PE2_RX_DN<6>")
	)
	(arc
		(start 127.807212 -214.261954)
		(mid 127.647107 -214.138661)
		(end 127.53721 -213.969092)
		(width 0.0889)
		(layer "In13.Cu")
		(net "P5E_CPU1_PE2_RX_DN<6>")
	)
	(arc
		(start 127.3429 -215.755982)
		(mid 127.473814 -215.619622)
		(end 127.521462 -215.436704)
		(width 0.0889)
		(layer "In13.Cu")
		(net "P5E_CPU1_PE2_RX_DN<6>")
	)
	(arc
		(start 126.581662 -217.064336)
		(mid 126.653897 -216.787812)
		(end 126.852172 -216.58199)
		(width 0.0889)
		(layer "In13.Cu")
		(net "P5E_CPU1_PE2_RX_DN<6>")
	)
	(segment
		(start 125.737112 -221.134178)
		(end 125.737366 -221.133924)
		(width 0.13208)
		(layer "F.Cu")
		(net "P5E_CPU1_PE2_RX_DN<5>")
	)
	(segment
		(start 125.737112 -221.669864)
		(end 125.737112 -221.134178)
		(width 0.13208)
		(layer "F.Cu")
		(net "P5E_CPU1_PE2_RX_DN<5>")
	)
	(segment
		(start 152.433528 -253.412498)
		(end 152.432512 -253.42723)
		(width 0.14732)
		(layer "In13.Cu")
		(net "P5E_CPU1_PE2_RX_DN<5>")
	)
	(segment
		(start 125.641862 -217.07856)
		(end 125.641862 -217.064336)
		(width 0.0889)
		(layer "In13.Cu")
		(net "P5E_CPU1_PE2_RX_DN<5>")
	)
	(segment
		(start 126.581916 -213.3219)
		(end 126.539752 -213.279736)
		(width 0.0889)
		(layer "In13.Cu")
		(net "P5E_CPU1_PE2_RX_DN<5>")
	)
	(segment
		(start 152.43302 -253.397258)
		(end 152.43302 -253.397512)
		(width 0.14732)
		(layer "In13.Cu")
		(net "P5E_CPU1_PE2_RX_DN<5>")
	)
	(segment
		(start 159.889698 -360.619548)
		(end 152.887934 -397.810482)
		(width 0.14732)
		(layer "In13.Cu")
		(net "P5E_CPU1_PE2_RX_DN<5>")
	)
	(segment
		(start 141.898878 -210.390994)
		(end 144.268952 -212.761068)
		(width 0.14732)
		(layer "In13.Cu")
		(net "P5E_CPU1_PE2_RX_DN<5>")
	)
	(segment
		(start 147.568666 -420.36111)
		(end 147.568412 -420.361872)
		(width 0.14732)
		(layer "In13.Cu")
		(net "P5E_CPU1_PE2_RX_DN<5>")
	)
	(segment
		(start 147.906486 -419.869112)
		(end 147.72005 -419.954202)
		(width 0.14732)
		(layer "In13.Cu")
		(net "P5E_CPU1_PE2_RX_DN<5>")
	)
	(segment
		(start 146.06651 -424.397424)
		(end 146.06651 -433.572666)
		(width 0.14732)
		(layer "In13.Cu")
		(net "P5E_CPU1_PE2_RX_DN<5>")
	)
	(segment
		(start 146.703034 -422.688004)
		(end 146.701256 -422.693338)
		(width 0.14732)
		(layer "In13.Cu")
		(net "P5E_CPU1_PE2_RX_DN<5>")
	)
	(segment
		(start 151.170894 -406.335992)
		(end 151.170894 -410.682186)
		(width 0.14732)
		(layer "In13.Cu")
		(net "P5E_CPU1_PE2_RX_DN<5>")
	)
	(segment
		(start 125.924564 -216.574878)
		(end 125.926088 -216.574116)
		(width 0.0889)
		(layer "In13.Cu")
		(net "P5E_CPU1_PE2_RX_DN<5>")
	)
	(segment
		(start 125.641862 -220.334078)
		(end 125.641862 -220.319854)
		(width 0.0889)
		(layer "In13.Cu")
		(net "P5E_CPU1_PE2_RX_DN<5>")
	)
	(segment
		(start 146.582892 -433.719478)
		(end 146.750024 -433.552346)
		(width 0.14732)
		(layer "In13.Cu")
		(net "P5E_CPU1_PE2_RX_DN<5>")
	)
	(segment
		(start 125.933454 -219.18676)
		(end 125.926088 -219.182442)
		(width 0.0889)
		(layer "In13.Cu")
		(net "P5E_CPU1_PE2_RX_DN<5>")
	)
	(segment
		(start 125.737366 -221.133924)
		(end 125.580902 -221.404942)
		(width 0.0889)
		(layer "In13.Cu")
		(net "P5E_CPU1_PE2_RX_DN<5>")
	)
	(segment
		(start 146.06651 -433.572666)
		(end 146.213322 -433.719478)
		(width 0.14732)
		(layer "In13.Cu")
		(net "P5E_CPU1_PE2_RX_DN<5>")
	)
	(segment
		(start 126.539752 -212.43036)
		(end 126.991872 -211.338922)
		(width 0.14732)
		(layer "In13.Cu")
		(net "P5E_CPU1_PE2_RX_DN<5>")
	)
	(segment
		(start 152.271984 -248.607834)
		(end 152.43302 -253.397258)
		(width 0.14732)
		(layer "In13.Cu")
		(net "P5E_CPU1_PE2_RX_DN<5>")
	)
	(segment
		(start 152.887934 -397.810482)
		(end 152.887934 -404.618952)
		(width 0.14732)
		(layer "In13.Cu")
		(net "P5E_CPU1_PE2_RX_DN<5>")
	)
	(segment
		(start 151.559768 -323.233034)
		(end 158.296356 -331.146912)
		(width 0.14732)
		(layer "In13.Cu")
		(net "P5E_CPU1_PE2_RX_DN<5>")
	)
	(segment
		(start 148.2217 -308.954932)
		(end 151.559768 -323.233034)
		(width 0.14732)
		(layer "In13.Cu")
		(net "P5E_CPU1_PE2_RX_DN<5>")
	)
	(segment
		(start 125.918468 -216.578434)
		(end 125.924564 -216.574878)
		(width 0.0889)
		(layer "In13.Cu")
		(net "P5E_CPU1_PE2_RX_DN<5>")
	)
	(segment
		(start 126.581916 -213.930484)
		(end 126.581916 -213.3219)
		(width 0.0889)
		(layer "In13.Cu")
		(net "P5E_CPU1_PE2_RX_DN<5>")
	)
	(segment
		(start 158.296356 -331.146912)
		(end 160.935924 -346.11183)
		(width 0.14732)
		(layer "In13.Cu")
		(net "P5E_CPU1_PE2_RX_DN<5>")
	)
	(segment
		(start 125.933454 -220.814646)
		(end 125.924564 -220.809566)
		(width 0.0889)
		(layer "In13.Cu")
		(net "P5E_CPU1_PE2_RX_DN<5>")
	)
	(segment
		(start 160.935924 -346.11183)
		(end 159.889698 -360.619548)
		(width 0.14732)
		(layer "In13.Cu")
		(net "P5E_CPU1_PE2_RX_DN<5>")
	)
	(segment
		(start 147.949666 -419.33749)
		(end 148.03501 -419.523672)
		(width 0.14732)
		(layer "In13.Cu")
		(net "P5E_CPU1_PE2_RX_DN<5>")
	)
	(segment
		(start 125.918468 -218.20632)
		(end 125.933454 -218.197684)
		(width 0.0889)
		(layer "In13.Cu")
		(net "P5E_CPU1_PE2_RX_DN<5>")
	)
	(segment
		(start 126.112016 -216.25052)
		(end 126.112016 -216.235026)
		(width 0.0889)
		(layer "In13.Cu")
		(net "P5E_CPU1_PE2_RX_DN<5>")
	)
	(segment
		(start 148.527008 -225.321876)
		(end 152.271984 -248.607834)
		(width 0.14732)
		(layer "In13.Cu")
		(net "P5E_CPU1_PE2_RX_DN<5>")
	)
	(segment
		(start 146.70278 -422.688004)
		(end 146.703034 -422.688004)
		(width 0.14732)
		(layer "In13.Cu")
		(net "P5E_CPU1_PE2_RX_DN<5>")
	)
	(segment
		(start 147.72005 -419.954202)
		(end 147.568666 -420.36111)
		(width 0.14732)
		(layer "In13.Cu")
		(net "P5E_CPU1_PE2_RX_DN<5>")
	)
	(segment
		(start 152.43302 -253.397512)
		(end 152.433528 -253.412498)
		(width 0.14732)
		(layer "In13.Cu")
		(net "P5E_CPU1_PE2_RX_DN<5>")
	)
	(segment
		(start 126.39421 -215.761062)
		(end 126.4031 -215.755982)
		(width 0.0889)
		(layer "In13.Cu")
		(net "P5E_CPU1_PE2_RX_DN<5>")
	)
	(segment
		(start 125.926088 -219.182442)
		(end 125.924564 -219.18168)
		(width 0.0889)
		(layer "In13.Cu")
		(net "P5E_CPU1_PE2_RX_DN<5>")
	)
	(segment
		(start 147.653756 -420.548054)
		(end 147.525232 -420.893494)
		(width 0.14732)
		(layer "In13.Cu")
		(net "P5E_CPU1_PE2_RX_DN<5>")
	)
	(segment
		(start 127.051308 -214.622634)
		(end 127.051308 -214.461344)
		(width 0.0889)
		(layer "In13.Cu")
		(net "P5E_CPU1_PE2_RX_DN<5>")
	)
	(segment
		(start 146.701256 -422.693338)
		(end 146.06651 -424.397424)
		(width 0.14732)
		(layer "In13.Cu")
		(net "P5E_CPU1_PE2_RX_DN<5>")
	)
	(segment
		(start 152.432512 -253.42723)
		(end 152.432258 -253.42723)
		(width 0.14732)
		(layer "In13.Cu")
		(net "P5E_CPU1_PE2_RX_DN<5>")
	)
	(segment
		(start 125.92177 -219.83192)
		(end 125.924564 -219.830396)
		(width 0.0889)
		(layer "In13.Cu")
		(net "P5E_CPU1_PE2_RX_DN<5>")
	)
	(segment
		(start 144.268952 -212.761068)
		(end 144.268698 -212.761068)
		(width 0.14732)
		(layer "In13.Cu")
		(net "P5E_CPU1_PE2_RX_DN<5>")
	)
	(segment
		(start 126.539752 -213.279736)
		(end 126.539752 -213.257638)
		(width 0.0889)
		(layer "In13.Cu")
		(net "P5E_CPU1_PE2_RX_DN<5>")
	)
	(segment
		(start 125.924564 -221.458282)
		(end 125.926088 -221.45752)
		(width 0.0889)
		(layer "In13.Cu")
		(net "P5E_CPU1_PE2_RX_DN<5>")
	)
	(segment
		(start 125.924564 -219.830396)
		(end 125.926088 -219.829634)
		(width 0.0889)
		(layer "In13.Cu")
		(net "P5E_CPU1_PE2_RX_DN<5>")
	)
	(segment
		(start 152.887934 -404.618952)
		(end 151.170894 -406.335992)
		(width 0.14732)
		(layer "In13.Cu")
		(net "P5E_CPU1_PE2_RX_DN<5>")
	)
	(segment
		(start 125.933454 -217.559128)
		(end 125.924564 -217.554048)
		(width 0.0889)
		(layer "In13.Cu")
		(net "P5E_CPU1_PE2_RX_DN<5>")
	)
	(segment
		(start 125.926088 -221.45752)
		(end 125.933454 -221.453202)
		(width 0.0889)
		(layer "In13.Cu")
		(net "P5E_CPU1_PE2_RX_DN<5>")
	)
	(segment
		(start 125.924564 -219.18168)
		(end 125.923802 -219.181172)
		(width 0.0889)
		(layer "In13.Cu")
		(net "P5E_CPU1_PE2_RX_DN<5>")
	)
	(segment
		(start 148.03501 -419.523672)
		(end 147.906486 -419.869112)
		(width 0.14732)
		(layer "In13.Cu")
		(net "P5E_CPU1_PE2_RX_DN<5>")
	)
	(segment
		(start 125.580902 -221.404942)
		(end 125.601984 -221.48292)
		(width 0.0889)
		(layer "In13.Cu")
		(net "P5E_CPU1_PE2_RX_DN<5>")
	)
	(segment
		(start 146.213322 -433.719478)
		(end 146.582892 -433.719478)
		(width 0.14732)
		(layer "In13.Cu")
		(net "P5E_CPU1_PE2_RX_DN<5>")
	)
	(segment
		(start 126.581662 -215.436704)
		(end 126.581662 -215.414606)
		(width 0.0889)
		(layer "In13.Cu")
		(net "P5E_CPU1_PE2_RX_DN<5>")
	)
	(segment
		(start 128.41478 -209.916014)
		(end 130.962908 -208.860644)
		(width 0.14732)
		(layer "In13.Cu")
		(net "P5E_CPU1_PE2_RX_DN<5>")
	)
	(segment
		(start 144.268698 -212.761068)
		(end 145.11147 -213.60384)
		(width 0.14732)
		(layer "In13.Cu")
		(net "P5E_CPU1_PE2_RX_DN<5>")
	)
	(segment
		(start 134.205218 -208.860644)
		(end 141.898878 -210.390994)
		(width 0.14732)
		(layer "In13.Cu")
		(net "P5E_CPU1_PE2_RX_DN<5>")
	)
	(segment
		(start 147.338542 -420.9796)
		(end 146.70278 -422.688004)
		(width 0.14732)
		(layer "In13.Cu")
		(net "P5E_CPU1_PE2_RX_DN<5>")
	)
	(segment
		(start 147.338796 -420.978838)
		(end 147.338542 -420.9796)
		(width 0.14732)
		(layer "In13.Cu")
		(net "P5E_CPU1_PE2_RX_DN<5>")
	)
	(segment
		(start 125.926088 -216.574116)
		(end 125.933454 -216.569798)
		(width 0.0889)
		(layer "In13.Cu")
		(net "P5E_CPU1_PE2_RX_DN<5>")
	)
	(segment
		(start 130.962908 -208.860644)
		(end 134.205218 -208.860644)
		(width 0.14732)
		(layer "In13.Cu")
		(net "P5E_CPU1_PE2_RX_DN<5>")
	)
	(segment
		(start 126.863856 -214.946992)
		(end 126.872746 -214.941912)
		(width 0.0889)
		(layer "In13.Cu")
		(net "P5E_CPU1_PE2_RX_DN<5>")
	)
	(segment
		(start 126.539752 -213.257638)
		(end 126.539752 -212.43036)
		(width 0.14732)
		(layer "In13.Cu")
		(net "P5E_CPU1_PE2_RX_DN<5>")
	)
	(segment
		(start 125.923802 -219.181172)
		(end 125.918468 -219.178124)
		(width 0.0889)
		(layer "In13.Cu")
		(net "P5E_CPU1_PE2_RX_DN<5>")
	)
	(segment
		(start 125.926088 -219.829634)
		(end 125.933454 -219.825316)
		(width 0.0889)
		(layer "In13.Cu")
		(net "P5E_CPU1_PE2_RX_DN<5>")
	)
	(segment
		(start 147.525232 -420.893494)
		(end 147.338796 -420.978838)
		(width 0.14732)
		(layer "In13.Cu")
		(net "P5E_CPU1_PE2_RX_DN<5>")
	)
	(segment
		(start 145.11147 -213.60384)
		(end 148.527008 -225.321876)
		(width 0.14732)
		(layer "In13.Cu")
		(net "P5E_CPU1_PE2_RX_DN<5>")
	)
	(segment
		(start 152.432258 -253.42723)
		(end 148.2217 -308.954932)
		(width 0.14732)
		(layer "In13.Cu")
		(net "P5E_CPU1_PE2_RX_DN<5>")
	)
	(segment
		(start 147.568412 -420.361872)
		(end 147.653756 -420.548054)
		(width 0.14732)
		(layer "In13.Cu")
		(net "P5E_CPU1_PE2_RX_DN<5>")
	)
	(segment
		(start 151.170894 -410.682186)
		(end 147.949666 -419.33749)
		(width 0.14732)
		(layer "In13.Cu")
		(net "P5E_CPU1_PE2_RX_DN<5>")
	)
	(segment
		(start 126.991872 -211.338922)
		(end 128.41478 -209.916014)
		(width 0.14732)
		(layer "In13.Cu")
		(net "P5E_CPU1_PE2_RX_DN<5>")
	)
	(segment
		(start 125.918468 -219.833952)
		(end 125.92177 -219.83192)
		(width 0.0889)
		(layer "In13.Cu")
		(net "P5E_CPU1_PE2_RX_DN<5>")
	)
	(segment
		(start 146.750024 -433.552346)
		(end 146.750024 -433.289964)
		(width 0.14732)
		(layer "In13.Cu")
		(net "P5E_CPU1_PE2_RX_DN<5>")
	)
	(arc
		(start 125.918468 -219.178124)
		(mid 125.641894 -218.692222)
		(end 125.918468 -218.20632)
		(width 0.0889)
		(layer "In13.Cu")
		(net "P5E_CPU1_PE2_RX_DN<5>")
	)
	(arc
		(start 126.581662 -215.414606)
		(mid 126.662573 -215.144478)
		(end 126.863856 -214.946992)
		(width 0.0889)
		(layer "In13.Cu")
		(net "P5E_CPU1_PE2_RX_DN<5>")
	)
	(arc
		(start 127.051308 -214.461344)
		(mid 126.976303 -214.345885)
		(end 126.867158 -214.261954)
		(width 0.0889)
		(layer "In13.Cu")
		(net "P5E_CPU1_PE2_RX_DN<5>")
	)
	(arc
		(start 126.872746 -214.941912)
		(mid 127.00366 -214.805552)
		(end 127.051308 -214.622634)
		(width 0.0889)
		(layer "In13.Cu")
		(net "P5E_CPU1_PE2_RX_DN<5>")
	)
	(arc
		(start 125.641862 -220.319854)
		(mid 125.715853 -220.040288)
		(end 125.918468 -219.833952)
		(width 0.0889)
		(layer "In13.Cu")
		(net "P5E_CPU1_PE2_RX_DN<5>")
	)
	(arc
		(start 125.933454 -216.569798)
		(mid 126.064368 -216.433438)
		(end 126.112016 -216.25052)
		(width 0.0889)
		(layer "In13.Cu")
		(net "P5E_CPU1_PE2_RX_DN<5>")
	)
	(arc
		(start 126.597156 -213.969346)
		(mid 126.589193 -213.950049)
		(end 126.581916 -213.930484)
		(width 0.0889)
		(layer "In13.Cu")
		(net "P5E_CPU1_PE2_RX_DN<5>")
	)
	(arc
		(start 125.601984 -221.48292)
		(mid 125.76608 -221.507267)
		(end 125.924564 -221.458282)
		(width 0.0889)
		(layer "In13.Cu")
		(net "P5E_CPU1_PE2_RX_DN<5>")
	)
	(arc
		(start 126.112016 -216.235026)
		(mid 126.191386 -215.961292)
		(end 126.39421 -215.761062)
		(width 0.0889)
		(layer "In13.Cu")
		(net "P5E_CPU1_PE2_RX_DN<5>")
	)
	(arc
		(start 125.933454 -218.197684)
		(mid 126.112172 -217.878406)
		(end 125.933454 -217.559128)
		(width 0.0889)
		(layer "In13.Cu")
		(net "P5E_CPU1_PE2_RX_DN<5>")
	)
	(arc
		(start 125.924564 -217.554048)
		(mid 125.721083 -217.353244)
		(end 125.641862 -217.07856)
		(width 0.0889)
		(layer "In13.Cu")
		(net "P5E_CPU1_PE2_RX_DN<5>")
	)
	(arc
		(start 125.924564 -220.809566)
		(mid 125.721083 -220.608762)
		(end 125.641862 -220.334078)
		(width 0.0889)
		(layer "In13.Cu")
		(net "P5E_CPU1_PE2_RX_DN<5>")
	)
	(arc
		(start 125.641862 -217.064336)
		(mid 125.715853 -216.78477)
		(end 125.918468 -216.578434)
		(width 0.0889)
		(layer "In13.Cu")
		(net "P5E_CPU1_PE2_RX_DN<5>")
	)
	(arc
		(start 125.933454 -221.453202)
		(mid 126.112172 -221.133924)
		(end 125.933454 -220.814646)
		(width 0.0889)
		(layer "In13.Cu")
		(net "P5E_CPU1_PE2_RX_DN<5>")
	)
	(arc
		(start 126.4031 -215.755982)
		(mid 126.534014 -215.619622)
		(end 126.581662 -215.436704)
		(width 0.0889)
		(layer "In13.Cu")
		(net "P5E_CPU1_PE2_RX_DN<5>")
	)
	(arc
		(start 126.867158 -214.261954)
		(mid 126.707086 -214.138774)
		(end 126.597156 -213.969346)
		(width 0.0889)
		(layer "In13.Cu")
		(net "P5E_CPU1_PE2_RX_DN<5>")
	)
	(arc
		(start 125.933454 -219.825316)
		(mid 126.112051 -219.506038)
		(end 125.933454 -219.18676)
		(width 0.0889)
		(layer "In13.Cu")
		(net "P5E_CPU1_PE2_RX_DN<5>")
	)
	(segment
		(start 124.327666 -220.320108)
		(end 124.327412 -220.319854)
		(width 0.13208)
		(layer "F.Cu")
		(net "P5E_CPU1_PE2_RX_DN<4>")
	)
	(segment
		(start 124.327666 -220.855794)
		(end 124.327666 -220.320108)
		(width 0.13208)
		(layer "F.Cu")
		(net "P5E_CPU1_PE2_RX_DN<4>")
	)
	(segment
		(start 124.980954 -216.577164)
		(end 124.984764 -216.574878)
		(width 0.0889)
		(layer "In13.Cu")
		(net "P5E_CPU1_PE2_RX_DN<4>")
	)
	(segment
		(start 124.972572 -219.837508)
		(end 124.980954 -219.832682)
		(width 0.0889)
		(layer "In13.Cu")
		(net "P5E_CPU1_PE2_RX_DN<4>")
	)
	(segment
		(start 148.867622 -422.714674)
		(end 148.066506 -424.440604)
		(width 0.14732)
		(layer "In13.Cu")
		(net "P5E_CPU1_PE2_RX_DN<4>")
	)
	(segment
		(start 153.191972 -248.29135)
		(end 153.364946 -253.441454)
		(width 0.14732)
		(layer "In13.Cu")
		(net "P5E_CPU1_PE2_RX_DN<4>")
	)
	(segment
		(start 154.234134 -406.335992)
		(end 154.234134 -411.183582)
		(width 0.14732)
		(layer "In13.Cu")
		(net "P5E_CPU1_PE2_RX_DN<4>")
	)
	(segment
		(start 125.641862 -215.436704)
		(end 125.641862 -215.414606)
		(width 0.0889)
		(layer "In13.Cu")
		(net "P5E_CPU1_PE2_RX_DN<4>")
	)
	(segment
		(start 153.364946 -253.441454)
		(end 149.17928 -308.833012)
		(width 0.14732)
		(layer "In13.Cu")
		(net "P5E_CPU1_PE2_RX_DN<4>")
	)
	(segment
		(start 124.986288 -219.182442)
		(end 124.984764 -219.18168)
		(width 0.0889)
		(layer "In13.Cu")
		(net "P5E_CPU1_PE2_RX_DN<4>")
	)
	(segment
		(start 149.17928 -308.833012)
		(end 152.441402 -322.798948)
		(width 0.14732)
		(layer "In13.Cu")
		(net "P5E_CPU1_PE2_RX_DN<4>")
	)
	(segment
		(start 148.75002 -434.552344)
		(end 148.75002 -434.289962)
		(width 0.14732)
		(layer "In13.Cu")
		(net "P5E_CPU1_PE2_RX_DN<4>")
	)
	(segment
		(start 155.951174 -404.618952)
		(end 154.234134 -406.335992)
		(width 0.14732)
		(layer "In13.Cu")
		(net "P5E_CPU1_PE2_RX_DN<4>")
	)
	(segment
		(start 146.15414 -212.964776)
		(end 149.704552 -225.18624)
		(width 0.14732)
		(layer "In13.Cu")
		(net "P5E_CPU1_PE2_RX_DN<4>")
	)
	(segment
		(start 148.204174 -434.719476)
		(end 148.582888 -434.719476)
		(width 0.14732)
		(layer "In13.Cu")
		(net "P5E_CPU1_PE2_RX_DN<4>")
	)
	(segment
		(start 155.951174 -397.684498)
		(end 155.951174 -404.618952)
		(width 0.14732)
		(layer "In13.Cu")
		(net "P5E_CPU1_PE2_RX_DN<4>")
	)
	(segment
		(start 148.066506 -424.440604)
		(end 148.066506 -434.581808)
		(width 0.14732)
		(layer "In13.Cu")
		(net "P5E_CPU1_PE2_RX_DN<4>")
	)
	(segment
		(start 124.984764 -219.18168)
		(end 124.984002 -219.181172)
		(width 0.0889)
		(layer "In13.Cu")
		(net "P5E_CPU1_PE2_RX_DN<4>")
	)
	(segment
		(start 149.03323 -422.654222)
		(end 148.867622 -422.714674)
		(width 0.14732)
		(layer "In13.Cu")
		(net "P5E_CPU1_PE2_RX_DN<4>")
	)
	(segment
		(start 124.993654 -217.559128)
		(end 124.984764 -217.554048)
		(width 0.0889)
		(layer "In13.Cu")
		(net "P5E_CPU1_PE2_RX_DN<4>")
	)
	(segment
		(start 124.972572 -216.58199)
		(end 124.980954 -216.577164)
		(width 0.0889)
		(layer "In13.Cu")
		(net "P5E_CPU1_PE2_RX_DN<4>")
	)
	(segment
		(start 125.599952 -213.257638)
		(end 125.599952 -212.265768)
		(width 0.14732)
		(layer "In13.Cu")
		(net "P5E_CPU1_PE2_RX_DN<4>")
	)
	(segment
		(start 136.226804 -203.035916)
		(end 146.15414 -212.964776)
		(width 0.14732)
		(layer "In13.Cu")
		(net "P5E_CPU1_PE2_RX_DN<4>")
	)
	(segment
		(start 124.702062 -217.071956)
		(end 124.702062 -217.064336)
		(width 0.0889)
		(layer "In13.Cu")
		(net "P5E_CPU1_PE2_RX_DN<4>")
	)
	(segment
		(start 126.111508 -214.622634)
		(end 126.111508 -214.461344)
		(width 0.0889)
		(layer "In13.Cu")
		(net "P5E_CPU1_PE2_RX_DN<4>")
	)
	(segment
		(start 124.986288 -218.202002)
		(end 124.993654 -218.197684)
		(width 0.0889)
		(layer "In13.Cu")
		(net "P5E_CPU1_PE2_RX_DN<4>")
	)
	(segment
		(start 124.980954 -219.832682)
		(end 124.984764 -219.830396)
		(width 0.0889)
		(layer "In13.Cu")
		(net "P5E_CPU1_PE2_RX_DN<4>")
	)
	(segment
		(start 125.924056 -214.946992)
		(end 125.932946 -214.941912)
		(width 0.0889)
		(layer "In13.Cu")
		(net "P5E_CPU1_PE2_RX_DN<4>")
	)
	(segment
		(start 124.984764 -216.574878)
		(end 124.993654 -216.569798)
		(width 0.0889)
		(layer "In13.Cu")
		(net "P5E_CPU1_PE2_RX_DN<4>")
	)
	(segment
		(start 124.993654 -219.18676)
		(end 124.986288 -219.182442)
		(width 0.0889)
		(layer "In13.Cu")
		(net "P5E_CPU1_PE2_RX_DN<4>")
	)
	(segment
		(start 149.704552 -225.18624)
		(end 153.191972 -248.29135)
		(width 0.14732)
		(layer "In13.Cu")
		(net "P5E_CPU1_PE2_RX_DN<4>")
	)
	(segment
		(start 124.978668 -218.20632)
		(end 124.986288 -218.202002)
		(width 0.0889)
		(layer "In13.Cu")
		(net "P5E_CPU1_PE2_RX_DN<4>")
	)
	(segment
		(start 125.45441 -215.761062)
		(end 125.4633 -215.755982)
		(width 0.0889)
		(layer "In13.Cu")
		(net "P5E_CPU1_PE2_RX_DN<4>")
	)
	(segment
		(start 125.599952 -212.265768)
		(end 126.252478 -210.689952)
		(width 0.14732)
		(layer "In13.Cu")
		(net "P5E_CPU1_PE2_RX_DN<4>")
	)
	(segment
		(start 125.599952 -213.279736)
		(end 125.599952 -213.257638)
		(width 0.0889)
		(layer "In13.Cu")
		(net "P5E_CPU1_PE2_RX_DN<4>")
	)
	(segment
		(start 152.441402 -322.798948)
		(end 159.222948 -330.785978)
		(width 0.14732)
		(layer "In13.Cu")
		(net "P5E_CPU1_PE2_RX_DN<4>")
	)
	(segment
		(start 125.927358 -214.261954)
		(end 125.927612 -214.261954)
		(width 0.0889)
		(layer "In13.Cu")
		(net "P5E_CPU1_PE2_RX_DN<4>")
	)
	(segment
		(start 124.327412 -220.319854)
		(end 124.483876 -220.590872)
		(width 0.0889)
		(layer "In13.Cu")
		(net "P5E_CPU1_PE2_RX_DN<4>")
	)
	(segment
		(start 125.642116 -213.929468)
		(end 125.642116 -213.3219)
		(width 0.0889)
		(layer "In13.Cu")
		(net "P5E_CPU1_PE2_RX_DN<4>")
	)
	(segment
		(start 126.252478 -210.689952)
		(end 133.906514 -203.035916)
		(width 0.14732)
		(layer "In13.Cu")
		(net "P5E_CPU1_PE2_RX_DN<4>")
	)
	(segment
		(start 154.234134 -411.183582)
		(end 154.208734 -411.208982)
		(width 0.14732)
		(layer "In13.Cu")
		(net "P5E_CPU1_PE2_RX_DN<4>")
	)
	(segment
		(start 154.208734 -411.208982)
		(end 149.156674 -422.092374)
		(width 0.14732)
		(layer "In13.Cu")
		(net "P5E_CPU1_PE2_RX_DN<4>")
	)
	(segment
		(start 161.910522 -346.025724)
		(end 160.829498 -361.436412)
		(width 0.14732)
		(layer "In13.Cu")
		(net "P5E_CPU1_PE2_RX_DN<4>")
	)
	(segment
		(start 133.906514 -203.035916)
		(end 136.226804 -203.035916)
		(width 0.14732)
		(layer "In13.Cu")
		(net "P5E_CPU1_PE2_RX_DN<4>")
	)
	(segment
		(start 149.217126 -422.257728)
		(end 149.03323 -422.654222)
		(width 0.14732)
		(layer "In13.Cu")
		(net "P5E_CPU1_PE2_RX_DN<4>")
	)
	(segment
		(start 148.582888 -434.719476)
		(end 148.75002 -434.552344)
		(width 0.14732)
		(layer "In13.Cu")
		(net "P5E_CPU1_PE2_RX_DN<4>")
	)
	(segment
		(start 125.642116 -213.3219)
		(end 125.599952 -213.279736)
		(width 0.0889)
		(layer "In13.Cu")
		(net "P5E_CPU1_PE2_RX_DN<4>")
	)
	(segment
		(start 125.172216 -216.25052)
		(end 125.172216 -216.235026)
		(width 0.0889)
		(layer "In13.Cu")
		(net "P5E_CPU1_PE2_RX_DN<4>")
	)
	(segment
		(start 159.222948 -330.785978)
		(end 161.910522 -346.025724)
		(width 0.14732)
		(layer "In13.Cu")
		(net "P5E_CPU1_PE2_RX_DN<4>")
	)
	(segment
		(start 124.984764 -219.830396)
		(end 124.993654 -219.825316)
		(width 0.0889)
		(layer "In13.Cu")
		(net "P5E_CPU1_PE2_RX_DN<4>")
	)
	(segment
		(start 148.066506 -434.581808)
		(end 148.204174 -434.719476)
		(width 0.14732)
		(layer "In13.Cu")
		(net "P5E_CPU1_PE2_RX_DN<4>")
	)
	(segment
		(start 124.984002 -219.181172)
		(end 124.978668 -219.178124)
		(width 0.0889)
		(layer "In13.Cu")
		(net "P5E_CPU1_PE2_RX_DN<4>")
	)
	(segment
		(start 149.156674 -422.092374)
		(end 149.217126 -422.257728)
		(width 0.14732)
		(layer "In13.Cu")
		(net "P5E_CPU1_PE2_RX_DN<4>")
	)
	(segment
		(start 124.483876 -220.590872)
		(end 124.562108 -220.6117)
		(width 0.0889)
		(layer "In13.Cu")
		(net "P5E_CPU1_PE2_RX_DN<4>")
	)
	(segment
		(start 160.829498 -361.436412)
		(end 155.951174 -397.684498)
		(width 0.14732)
		(layer "In13.Cu")
		(net "P5E_CPU1_PE2_RX_DN<4>")
	)
	(arc
		(start 124.993654 -216.569798)
		(mid 125.124568 -216.433438)
		(end 125.172216 -216.25052)
		(width 0.0889)
		(layer "In13.Cu")
		(net "P5E_CPU1_PE2_RX_DN<4>")
	)
	(arc
		(start 124.978668 -219.178124)
		(mid 124.702094 -218.692222)
		(end 124.978668 -218.20632)
		(width 0.0889)
		(layer "In13.Cu")
		(net "P5E_CPU1_PE2_RX_DN<4>")
	)
	(arc
		(start 124.984764 -217.554048)
		(mid 124.779692 -217.350369)
		(end 124.702062 -217.071956)
		(width 0.0889)
		(layer "In13.Cu")
		(net "P5E_CPU1_PE2_RX_DN<4>")
	)
	(arc
		(start 126.111508 -214.461344)
		(mid 126.036503 -214.345885)
		(end 125.927358 -214.261954)
		(width 0.0889)
		(layer "In13.Cu")
		(net "P5E_CPU1_PE2_RX_DN<4>")
	)
	(arc
		(start 125.932946 -214.941912)
		(mid 126.06386 -214.805552)
		(end 126.111508 -214.622634)
		(width 0.0889)
		(layer "In13.Cu")
		(net "P5E_CPU1_PE2_RX_DN<4>")
	)
	(arc
		(start 124.702062 -217.064336)
		(mid 124.774297 -216.787812)
		(end 124.972572 -216.58199)
		(width 0.0889)
		(layer "In13.Cu")
		(net "P5E_CPU1_PE2_RX_DN<4>")
	)
	(arc
		(start 124.993654 -219.825316)
		(mid 125.172251 -219.506038)
		(end 124.993654 -219.18676)
		(width 0.0889)
		(layer "In13.Cu")
		(net "P5E_CPU1_PE2_RX_DN<4>")
	)
	(arc
		(start 124.702062 -220.319854)
		(mid 124.774297 -220.04333)
		(end 124.972572 -219.837508)
		(width 0.0889)
		(layer "In13.Cu")
		(net "P5E_CPU1_PE2_RX_DN<4>")
	)
	(arc
		(start 125.172216 -216.235026)
		(mid 125.251586 -215.961292)
		(end 125.45441 -215.761062)
		(width 0.0889)
		(layer "In13.Cu")
		(net "P5E_CPU1_PE2_RX_DN<4>")
	)
	(arc
		(start 124.993654 -218.197684)
		(mid 125.17213 -217.878406)
		(end 124.993654 -217.559128)
		(width 0.0889)
		(layer "In13.Cu")
		(net "P5E_CPU1_PE2_RX_DN<4>")
	)
	(arc
		(start 124.562108 -220.6117)
		(mid 124.665253 -220.481675)
		(end 124.702062 -220.319854)
		(width 0.0889)
		(layer "In13.Cu")
		(net "P5E_CPU1_PE2_RX_DN<4>")
	)
	(arc
		(start 125.927612 -214.261954)
		(mid 125.767507 -214.138661)
		(end 125.65761 -213.969092)
		(width 0.0889)
		(layer "In13.Cu")
		(net "P5E_CPU1_PE2_RX_DN<4>")
	)
	(arc
		(start 125.641862 -215.414606)
		(mid 125.722773 -215.144478)
		(end 125.924056 -214.946992)
		(width 0.0889)
		(layer "In13.Cu")
		(net "P5E_CPU1_PE2_RX_DN<4>")
	)
	(arc
		(start 125.4633 -215.755982)
		(mid 125.594214 -215.619622)
		(end 125.641862 -215.436704)
		(width 0.0889)
		(layer "In13.Cu")
		(net "P5E_CPU1_PE2_RX_DN<4>")
	)
	(arc
		(start 125.65761 -213.969092)
		(mid 125.649513 -213.949417)
		(end 125.642116 -213.929468)
		(width 0.0889)
		(layer "In13.Cu")
		(net "P5E_CPU1_PE2_RX_DN<4>")
	)
	(segment
		(start 123.857512 -221.669864)
		(end 123.857512 -221.134178)
		(width 0.13208)
		(layer "F.Cu")
		(net "P5E_CPU1_PE2_RX_DN<3>")
	)
	(segment
		(start 123.857512 -221.134178)
		(end 123.857766 -221.133924)
		(width 0.13208)
		(layer "F.Cu")
		(net "P5E_CPU1_PE2_RX_DN<3>")
	)
	(segment
		(start 124.046488 -218.202002)
		(end 124.053854 -218.197684)
		(width 0.0889)
		(layer "In13.Cu")
		(net "P5E_CPU1_PE2_RX_DN<3>")
	)
	(segment
		(start 159.014414 -396.357094)
		(end 159.014414 -404.618952)
		(width 0.14732)
		(layer "In13.Cu")
		(net "P5E_CPU1_PE2_RX_DN<3>")
	)
	(segment
		(start 124.702316 -213.3219)
		(end 124.660152 -213.279736)
		(width 0.0889)
		(layer "In13.Cu")
		(net "P5E_CPU1_PE2_RX_DN<3>")
	)
	(segment
		(start 160.103058 -330.363322)
		(end 162.857434 -345.982036)
		(width 0.14732)
		(layer "In13.Cu")
		(net "P5E_CPU1_PE2_RX_DN<3>")
	)
	(segment
		(start 157.297374 -406.335992)
		(end 157.297374 -410.655008)
		(width 0.14732)
		(layer "In13.Cu")
		(net "P5E_CPU1_PE2_RX_DN<3>")
	)
	(segment
		(start 124.984256 -214.946992)
		(end 124.993146 -214.941912)
		(width 0.0889)
		(layer "In13.Cu")
		(net "P5E_CPU1_PE2_RX_DN<3>")
	)
	(segment
		(start 124.044964 -216.574878)
		(end 124.053854 -216.569798)
		(width 0.0889)
		(layer "In13.Cu")
		(net "P5E_CPU1_PE2_RX_DN<3>")
	)
	(segment
		(start 150.1394 -308.673246)
		(end 153.295096 -322.299076)
		(width 0.14732)
		(layer "In13.Cu")
		(net "P5E_CPU1_PE2_RX_DN<3>")
	)
	(segment
		(start 123.762262 -220.334078)
		(end 123.762262 -220.319854)
		(width 0.0889)
		(layer "In13.Cu")
		(net "P5E_CPU1_PE2_RX_DN<3>")
	)
	(segment
		(start 162.857434 -345.982036)
		(end 161.928556 -361.607608)
		(width 0.14732)
		(layer "In13.Cu")
		(net "P5E_CPU1_PE2_RX_DN<3>")
	)
	(segment
		(start 124.044964 -221.458282)
		(end 124.046488 -221.45752)
		(width 0.0889)
		(layer "In13.Cu")
		(net "P5E_CPU1_PE2_RX_DN<3>")
	)
	(segment
		(start 147.01266 -212.45703)
		(end 150.650194 -224.978468)
		(width 0.14732)
		(layer "In13.Cu")
		(net "P5E_CPU1_PE2_RX_DN<3>")
	)
	(segment
		(start 125.171708 -214.622634)
		(end 125.171708 -214.461344)
		(width 0.0889)
		(layer "In13.Cu")
		(net "P5E_CPU1_PE2_RX_DN<3>")
	)
	(segment
		(start 151.304244 -422.4528)
		(end 151.136096 -422.505632)
		(width 0.14732)
		(layer "In13.Cu")
		(net "P5E_CPU1_PE2_RX_DN<3>")
	)
	(segment
		(start 150.750016 -433.575206)
		(end 150.750016 -433.289964)
		(width 0.14732)
		(layer "In13.Cu")
		(net "P5E_CPU1_PE2_RX_DN<3>")
	)
	(segment
		(start 124.038868 -216.578434)
		(end 124.044964 -216.574878)
		(width 0.0889)
		(layer "In13.Cu")
		(net "P5E_CPU1_PE2_RX_DN<3>")
	)
	(segment
		(start 124.046488 -219.182442)
		(end 124.044964 -219.18168)
		(width 0.0889)
		(layer "In13.Cu")
		(net "P5E_CPU1_PE2_RX_DN<3>")
	)
	(segment
		(start 124.702062 -215.436704)
		(end 124.702062 -215.414606)
		(width 0.0889)
		(layer "In13.Cu")
		(net "P5E_CPU1_PE2_RX_DN<3>")
	)
	(segment
		(start 157.297374 -410.655008)
		(end 151.802338 -421.223948)
		(width 0.14732)
		(layer "In13.Cu")
		(net "P5E_CPU1_PE2_RX_DN<3>")
	)
	(segment
		(start 124.038868 -219.833952)
		(end 124.053854 -219.825316)
		(width 0.0889)
		(layer "In13.Cu")
		(net "P5E_CPU1_PE2_RX_DN<3>")
	)
	(segment
		(start 153.295096 -322.299076)
		(end 160.103058 -330.363322)
		(width 0.14732)
		(layer "In13.Cu")
		(net "P5E_CPU1_PE2_RX_DN<3>")
	)
	(segment
		(start 123.762262 -217.07856)
		(end 123.762262 -217.064336)
		(width 0.0889)
		(layer "In13.Cu")
		(net "P5E_CPU1_PE2_RX_DN<3>")
	)
	(segment
		(start 150.650194 -224.978468)
		(end 154.11831 -247.96115)
		(width 0.14732)
		(layer "In13.Cu")
		(net "P5E_CPU1_PE2_RX_DN<3>")
	)
	(segment
		(start 151.452834 -421.897048)
		(end 151.505666 -422.064942)
		(width 0.14732)
		(layer "In13.Cu")
		(net "P5E_CPU1_PE2_RX_DN<3>")
	)
	(segment
		(start 124.053854 -219.18676)
		(end 124.046488 -219.182442)
		(width 0.0889)
		(layer "In13.Cu")
		(net "P5E_CPU1_PE2_RX_DN<3>")
	)
	(segment
		(start 161.928556 -361.607608)
		(end 159.014414 -396.357094)
		(width 0.14732)
		(layer "In13.Cu")
		(net "P5E_CPU1_PE2_RX_DN<3>")
	)
	(segment
		(start 154.311604 -253.704852)
		(end 150.1394 -308.673246)
		(width 0.14732)
		(layer "In13.Cu")
		(net "P5E_CPU1_PE2_RX_DN<3>")
	)
	(segment
		(start 159.014414 -404.618952)
		(end 157.297374 -406.335992)
		(width 0.14732)
		(layer "In13.Cu")
		(net "P5E_CPU1_PE2_RX_DN<3>")
	)
	(segment
		(start 151.136096 -422.505632)
		(end 150.804372 -423.143426)
		(width 0.14732)
		(layer "In13.Cu")
		(net "P5E_CPU1_PE2_RX_DN<3>")
	)
	(segment
		(start 124.660152 -212.005926)
		(end 125.394466 -210.232752)
		(width 0.14732)
		(layer "In13.Cu")
		(net "P5E_CPU1_PE2_RX_DN<3>")
	)
	(segment
		(start 123.701302 -221.404942)
		(end 123.722384 -221.48292)
		(width 0.0889)
		(layer "In13.Cu")
		(net "P5E_CPU1_PE2_RX_DN<3>")
	)
	(segment
		(start 124.044964 -219.18168)
		(end 124.044202 -219.181172)
		(width 0.0889)
		(layer "In13.Cu")
		(net "P5E_CPU1_PE2_RX_DN<3>")
	)
	(segment
		(start 124.702316 -213.930484)
		(end 124.702316 -213.3219)
		(width 0.0889)
		(layer "In13.Cu")
		(net "P5E_CPU1_PE2_RX_DN<3>")
	)
	(segment
		(start 150.066502 -433.488338)
		(end 150.320502 -433.742338)
		(width 0.14732)
		(layer "In13.Cu")
		(net "P5E_CPU1_PE2_RX_DN<3>")
	)
	(segment
		(start 124.660152 -213.279736)
		(end 124.660152 -213.257638)
		(width 0.0889)
		(layer "In13.Cu")
		(net "P5E_CPU1_PE2_RX_DN<3>")
	)
	(segment
		(start 151.802592 -421.224202)
		(end 151.452834 -421.897048)
		(width 0.14732)
		(layer "In13.Cu")
		(net "P5E_CPU1_PE2_RX_DN<3>")
	)
	(segment
		(start 150.490174 -423.747692)
		(end 150.066502 -424.562524)
		(width 0.14732)
		(layer "In13.Cu")
		(net "P5E_CPU1_PE2_RX_DN<3>")
	)
	(segment
		(start 133.531102 -202.096116)
		(end 136.652762 -202.096116)
		(width 0.14732)
		(layer "In13.Cu")
		(net "P5E_CPU1_PE2_RX_DN<3>")
	)
	(segment
		(start 123.857766 -221.133924)
		(end 123.701302 -221.404942)
		(width 0.0889)
		(layer "In13.Cu")
		(net "P5E_CPU1_PE2_RX_DN<3>")
	)
	(segment
		(start 124.046488 -221.45752)
		(end 124.053854 -221.453202)
		(width 0.0889)
		(layer "In13.Cu")
		(net "P5E_CPU1_PE2_RX_DN<3>")
	)
	(segment
		(start 150.856442 -423.308018)
		(end 150.654766 -423.695876)
		(width 0.14732)
		(layer "In13.Cu")
		(net "P5E_CPU1_PE2_RX_DN<3>")
	)
	(segment
		(start 136.652762 -202.096116)
		(end 147.01266 -212.45703)
		(width 0.14732)
		(layer "In13.Cu")
		(net "P5E_CPU1_PE2_RX_DN<3>")
	)
	(segment
		(start 124.053854 -217.559128)
		(end 124.044964 -217.554048)
		(width 0.0889)
		(layer "In13.Cu")
		(net "P5E_CPU1_PE2_RX_DN<3>")
	)
	(segment
		(start 150.582884 -433.742338)
		(end 150.750016 -433.575206)
		(width 0.14732)
		(layer "In13.Cu")
		(net "P5E_CPU1_PE2_RX_DN<3>")
	)
	(segment
		(start 125.394466 -210.232752)
		(end 133.531102 -202.096116)
		(width 0.14732)
		(layer "In13.Cu")
		(net "P5E_CPU1_PE2_RX_DN<3>")
	)
	(segment
		(start 124.044202 -219.181172)
		(end 124.038868 -219.178124)
		(width 0.0889)
		(layer "In13.Cu")
		(net "P5E_CPU1_PE2_RX_DN<3>")
	)
	(segment
		(start 150.654766 -423.695876)
		(end 150.490174 -423.747692)
		(width 0.14732)
		(layer "In13.Cu")
		(net "P5E_CPU1_PE2_RX_DN<3>")
	)
	(segment
		(start 124.053854 -220.814646)
		(end 124.044964 -220.809566)
		(width 0.0889)
		(layer "In13.Cu")
		(net "P5E_CPU1_PE2_RX_DN<3>")
	)
	(segment
		(start 151.802846 -421.223948)
		(end 151.802592 -421.224202)
		(width 0.14732)
		(layer "In13.Cu")
		(net "P5E_CPU1_PE2_RX_DN<3>")
	)
	(segment
		(start 150.320502 -433.742338)
		(end 150.582884 -433.742338)
		(width 0.14732)
		(layer "In13.Cu")
		(net "P5E_CPU1_PE2_RX_DN<3>")
	)
	(segment
		(start 154.11831 -247.96115)
		(end 154.311604 -253.704852)
		(width 0.14732)
		(layer "In13.Cu")
		(net "P5E_CPU1_PE2_RX_DN<3>")
	)
	(segment
		(start 124.232416 -216.25052)
		(end 124.232416 -216.235026)
		(width 0.0889)
		(layer "In13.Cu")
		(net "P5E_CPU1_PE2_RX_DN<3>")
	)
	(segment
		(start 151.505666 -422.064942)
		(end 151.304244 -422.4528)
		(width 0.14732)
		(layer "In13.Cu")
		(net "P5E_CPU1_PE2_RX_DN<3>")
	)
	(segment
		(start 124.51461 -215.761062)
		(end 124.5235 -215.755982)
		(width 0.0889)
		(layer "In13.Cu")
		(net "P5E_CPU1_PE2_RX_DN<3>")
	)
	(segment
		(start 150.804372 -423.143426)
		(end 150.856442 -423.308018)
		(width 0.14732)
		(layer "In13.Cu")
		(net "P5E_CPU1_PE2_RX_DN<3>")
	)
	(segment
		(start 150.066502 -424.562524)
		(end 150.066502 -433.488338)
		(width 0.14732)
		(layer "In13.Cu")
		(net "P5E_CPU1_PE2_RX_DN<3>")
	)
	(segment
		(start 124.038868 -218.20632)
		(end 124.046488 -218.202002)
		(width 0.0889)
		(layer "In13.Cu")
		(net "P5E_CPU1_PE2_RX_DN<3>")
	)
	(segment
		(start 151.802338 -421.223948)
		(end 151.802846 -421.223948)
		(width 0.14732)
		(layer "In13.Cu")
		(net "P5E_CPU1_PE2_RX_DN<3>")
	)
	(segment
		(start 124.660152 -213.257638)
		(end 124.660152 -212.005926)
		(width 0.14732)
		(layer "In13.Cu")
		(net "P5E_CPU1_PE2_RX_DN<3>")
	)
	(arc
		(start 123.722384 -221.48292)
		(mid 123.88648 -221.507267)
		(end 124.044964 -221.458282)
		(width 0.0889)
		(layer "In13.Cu")
		(net "P5E_CPU1_PE2_RX_DN<3>")
	)
	(arc
		(start 123.762262 -217.064336)
		(mid 123.836253 -216.78477)
		(end 124.038868 -216.578434)
		(width 0.0889)
		(layer "In13.Cu")
		(net "P5E_CPU1_PE2_RX_DN<3>")
	)
	(arc
		(start 124.5235 -215.755982)
		(mid 124.654414 -215.619622)
		(end 124.702062 -215.436704)
		(width 0.0889)
		(layer "In13.Cu")
		(net "P5E_CPU1_PE2_RX_DN<3>")
	)
	(arc
		(start 124.053854 -216.569798)
		(mid 124.184768 -216.433438)
		(end 124.232416 -216.25052)
		(width 0.0889)
		(layer "In13.Cu")
		(net "P5E_CPU1_PE2_RX_DN<3>")
	)
	(arc
		(start 124.987558 -214.261954)
		(mid 124.827486 -214.138774)
		(end 124.717556 -213.969346)
		(width 0.0889)
		(layer "In13.Cu")
		(net "P5E_CPU1_PE2_RX_DN<3>")
	)
	(arc
		(start 124.053854 -221.453202)
		(mid 124.232572 -221.133924)
		(end 124.053854 -220.814646)
		(width 0.0889)
		(layer "In13.Cu")
		(net "P5E_CPU1_PE2_RX_DN<3>")
	)
	(arc
		(start 124.053854 -219.825316)
		(mid 124.232451 -219.506038)
		(end 124.053854 -219.18676)
		(width 0.0889)
		(layer "In13.Cu")
		(net "P5E_CPU1_PE2_RX_DN<3>")
	)
	(arc
		(start 124.702062 -215.414606)
		(mid 124.782973 -215.144478)
		(end 124.984256 -214.946992)
		(width 0.0889)
		(layer "In13.Cu")
		(net "P5E_CPU1_PE2_RX_DN<3>")
	)
	(arc
		(start 124.993146 -214.941912)
		(mid 125.12406 -214.805552)
		(end 125.171708 -214.622634)
		(width 0.0889)
		(layer "In13.Cu")
		(net "P5E_CPU1_PE2_RX_DN<3>")
	)
	(arc
		(start 124.038868 -219.178124)
		(mid 123.762294 -218.692222)
		(end 124.038868 -218.20632)
		(width 0.0889)
		(layer "In13.Cu")
		(net "P5E_CPU1_PE2_RX_DN<3>")
	)
	(arc
		(start 125.171708 -214.461344)
		(mid 125.096703 -214.345885)
		(end 124.987558 -214.261954)
		(width 0.0889)
		(layer "In13.Cu")
		(net "P5E_CPU1_PE2_RX_DN<3>")
	)
	(arc
		(start 123.762262 -220.319854)
		(mid 123.836253 -220.040288)
		(end 124.038868 -219.833952)
		(width 0.0889)
		(layer "In13.Cu")
		(net "P5E_CPU1_PE2_RX_DN<3>")
	)
	(arc
		(start 124.717556 -213.969346)
		(mid 124.709593 -213.950049)
		(end 124.702316 -213.930484)
		(width 0.0889)
		(layer "In13.Cu")
		(net "P5E_CPU1_PE2_RX_DN<3>")
	)
	(arc
		(start 124.053854 -218.197684)
		(mid 124.232572 -217.878406)
		(end 124.053854 -217.559128)
		(width 0.0889)
		(layer "In13.Cu")
		(net "P5E_CPU1_PE2_RX_DN<3>")
	)
	(arc
		(start 124.232416 -216.235026)
		(mid 124.311786 -215.961292)
		(end 124.51461 -215.761062)
		(width 0.0889)
		(layer "In13.Cu")
		(net "P5E_CPU1_PE2_RX_DN<3>")
	)
	(arc
		(start 124.044964 -217.554048)
		(mid 123.841483 -217.353244)
		(end 123.762262 -217.07856)
		(width 0.0889)
		(layer "In13.Cu")
		(net "P5E_CPU1_PE2_RX_DN<3>")
	)
	(arc
		(start 124.044964 -220.809566)
		(mid 123.841483 -220.608762)
		(end 123.762262 -220.334078)
		(width 0.0889)
		(layer "In13.Cu")
		(net "P5E_CPU1_PE2_RX_DN<3>")
	)
	(segment
		(start 122.448066 -220.320108)
		(end 122.447812 -220.319854)
		(width 0.13208)
		(layer "F.Cu")
		(net "P5E_CPU1_PE2_RX_DN<2>")
	)
	(segment
		(start 122.448066 -220.855794)
		(end 122.448066 -220.320108)
		(width 0.13208)
		(layer "F.Cu")
		(net "P5E_CPU1_PE2_RX_DN<2>")
	)
	(segment
		(start 123.099068 -218.20632)
		(end 123.114054 -218.197684)
		(width 0.0889)
		(layer "In13.Cu")
		(net "P5E_CPU1_PE2_RX_DN<2>")
	)
	(segment
		(start 153.224738 -422.6306)
		(end 153.024586 -422.675558)
		(width 0.14732)
		(layer "In13.Cu")
		(net "P5E_CPU1_PE2_RX_DN<2>")
	)
	(segment
		(start 123.106688 -219.182442)
		(end 123.105164 -219.18168)
		(width 0.0889)
		(layer "In13.Cu")
		(net "P5E_CPU1_PE2_RX_DN<2>")
	)
	(segment
		(start 163.844224 -346.140278)
		(end 163.02482 -361.231434)
		(width 0.14732)
		(layer "In13.Cu")
		(net "P5E_CPU1_PE2_RX_DN<2>")
	)
	(segment
		(start 123.101354 -219.832682)
		(end 123.105164 -219.830396)
		(width 0.0889)
		(layer "In13.Cu")
		(net "P5E_CPU1_PE2_RX_DN<2>")
	)
	(segment
		(start 153.023824 -422.675812)
		(end 152.066498 -424.188636)
		(width 0.14732)
		(layer "In13.Cu")
		(net "P5E_CPU1_PE2_RX_DN<2>")
	)
	(segment
		(start 153.610056 -421.750236)
		(end 153.37663 -422.119298)
		(width 0.14732)
		(layer "In13.Cu")
		(net "P5E_CPU1_PE2_RX_DN<2>")
	)
	(segment
		(start 123.720352 -213.279736)
		(end 123.720352 -213.257638)
		(width 0.0889)
		(layer "In13.Cu")
		(net "P5E_CPU1_PE2_RX_DN<2>")
	)
	(segment
		(start 160.360614 -411.080204)
		(end 153.977086 -421.169084)
		(width 0.14732)
		(layer "In13.Cu")
		(net "P5E_CPU1_PE2_RX_DN<2>")
	)
	(segment
		(start 154.015694 -421.342058)
		(end 153.78176 -421.711628)
		(width 0.14732)
		(layer "In13.Cu")
		(net "P5E_CPU1_PE2_RX_DN<2>")
	)
	(segment
		(start 123.114054 -219.18676)
		(end 123.106688 -219.182442)
		(width 0.0889)
		(layer "In13.Cu")
		(net "P5E_CPU1_PE2_RX_DN<2>")
	)
	(segment
		(start 162.077654 -404.618952)
		(end 160.360614 -406.335992)
		(width 0.14732)
		(layer "In13.Cu")
		(net "P5E_CPU1_PE2_RX_DN<2>")
	)
	(segment
		(start 162.077654 -399.617692)
		(end 162.077654 -404.618952)
		(width 0.14732)
		(layer "In13.Cu")
		(net "P5E_CPU1_PE2_RX_DN<2>")
	)
	(segment
		(start 163.02482 -361.231434)
		(end 162.077654 -399.617692)
		(width 0.14732)
		(layer "In13.Cu")
		(net "P5E_CPU1_PE2_RX_DN<2>")
	)
	(segment
		(start 151.693118 -224.74936)
		(end 155.040076 -246.930164)
		(width 0.14732)
		(layer "In13.Cu")
		(net "P5E_CPU1_PE2_RX_DN<2>")
	)
	(segment
		(start 152.58288 -434.719476)
		(end 152.750012 -434.552344)
		(width 0.14732)
		(layer "In13.Cu")
		(net "P5E_CPU1_PE2_RX_DN<2>")
	)
	(segment
		(start 153.977086 -421.169084)
		(end 153.976832 -421.169592)
		(width 0.14732)
		(layer "In13.Cu")
		(net "P5E_CPU1_PE2_RX_DN<2>")
	)
	(segment
		(start 124.582682 -209.725768)
		(end 133.152134 -201.156316)
		(width 0.14732)
		(layer "In13.Cu")
		(net "P5E_CPU1_PE2_RX_DN<2>")
	)
	(segment
		(start 123.105164 -219.830396)
		(end 123.114054 -219.825316)
		(width 0.0889)
		(layer "In13.Cu")
		(net "P5E_CPU1_PE2_RX_DN<2>")
	)
	(segment
		(start 155.261056 -253.496064)
		(end 151.12238 -308.52618)
		(width 0.14732)
		(layer "In13.Cu")
		(net "P5E_CPU1_PE2_RX_DN<2>")
	)
	(segment
		(start 123.57481 -215.761062)
		(end 123.5837 -215.755982)
		(width 0.0889)
		(layer "In13.Cu")
		(net "P5E_CPU1_PE2_RX_DN<2>")
	)
	(segment
		(start 123.720352 -211.807806)
		(end 124.582682 -209.725768)
		(width 0.14732)
		(layer "In13.Cu")
		(net "P5E_CPU1_PE2_RX_DN<2>")
	)
	(segment
		(start 123.292616 -216.25052)
		(end 123.292616 -216.235026)
		(width 0.0889)
		(layer "In13.Cu")
		(net "P5E_CPU1_PE2_RX_DN<2>")
	)
	(segment
		(start 123.104402 -219.181172)
		(end 123.099068 -219.178124)
		(width 0.0889)
		(layer "In13.Cu")
		(net "P5E_CPU1_PE2_RX_DN<2>")
	)
	(segment
		(start 153.78176 -421.711628)
		(end 153.610056 -421.750236)
		(width 0.14732)
		(layer "In13.Cu")
		(net "P5E_CPU1_PE2_RX_DN<2>")
	)
	(segment
		(start 123.092972 -216.58199)
		(end 123.101354 -216.577164)
		(width 0.0889)
		(layer "In13.Cu")
		(net "P5E_CPU1_PE2_RX_DN<2>")
	)
	(segment
		(start 123.720352 -213.257638)
		(end 123.720352 -211.807806)
		(width 0.14732)
		(layer "In13.Cu")
		(net "P5E_CPU1_PE2_RX_DN<2>")
	)
	(segment
		(start 123.105164 -216.574878)
		(end 123.114054 -216.569798)
		(width 0.0889)
		(layer "In13.Cu")
		(net "P5E_CPU1_PE2_RX_DN<2>")
	)
	(segment
		(start 151.12238 -308.52618)
		(end 154.143964 -321.771518)
		(width 0.14732)
		(layer "In13.Cu")
		(net "P5E_CPU1_PE2_RX_DN<2>")
	)
	(segment
		(start 123.762516 -213.3219)
		(end 123.720352 -213.279736)
		(width 0.0889)
		(layer "In13.Cu")
		(net "P5E_CPU1_PE2_RX_DN<2>")
	)
	(segment
		(start 123.762262 -215.436704)
		(end 123.762262 -215.414606)
		(width 0.0889)
		(layer "In13.Cu")
		(net "P5E_CPU1_PE2_RX_DN<2>")
	)
	(segment
		(start 123.092972 -219.837508)
		(end 123.101354 -219.832682)
		(width 0.0889)
		(layer "In13.Cu")
		(net "P5E_CPU1_PE2_RX_DN<2>")
	)
	(segment
		(start 123.101354 -216.577164)
		(end 123.105164 -216.574878)
		(width 0.0889)
		(layer "In13.Cu")
		(net "P5E_CPU1_PE2_RX_DN<2>")
	)
	(segment
		(start 155.040076 -246.930164)
		(end 155.261056 -253.496064)
		(width 0.14732)
		(layer "In13.Cu")
		(net "P5E_CPU1_PE2_RX_DN<2>")
	)
	(segment
		(start 147.909534 -211.725764)
		(end 151.693118 -224.74936)
		(width 0.14732)
		(layer "In13.Cu")
		(net "P5E_CPU1_PE2_RX_DN<2>")
	)
	(segment
		(start 122.604276 -220.590872)
		(end 122.682508 -220.6117)
		(width 0.0889)
		(layer "In13.Cu")
		(net "P5E_CPU1_PE2_RX_DN<2>")
	)
	(segment
		(start 153.976832 -421.169592)
		(end 153.977086 -421.170354)
		(width 0.14732)
		(layer "In13.Cu")
		(net "P5E_CPU1_PE2_RX_DN<2>")
	)
	(segment
		(start 153.421588 -422.318942)
		(end 153.224738 -422.6306)
		(width 0.14732)
		(layer "In13.Cu")
		(net "P5E_CPU1_PE2_RX_DN<2>")
	)
	(segment
		(start 137.340594 -201.156316)
		(end 147.909534 -211.725764)
		(width 0.14732)
		(layer "In13.Cu")
		(net "P5E_CPU1_PE2_RX_DN<2>")
	)
	(segment
		(start 123.105164 -219.18168)
		(end 123.104402 -219.181172)
		(width 0.0889)
		(layer "In13.Cu")
		(net "P5E_CPU1_PE2_RX_DN<2>")
	)
	(segment
		(start 152.242774 -434.719476)
		(end 152.58288 -434.719476)
		(width 0.14732)
		(layer "In13.Cu")
		(net "P5E_CPU1_PE2_RX_DN<2>")
	)
	(segment
		(start 152.066498 -434.5432)
		(end 152.242774 -434.719476)
		(width 0.14732)
		(layer "In13.Cu")
		(net "P5E_CPU1_PE2_RX_DN<2>")
	)
	(segment
		(start 124.044456 -214.946992)
		(end 124.053346 -214.941912)
		(width 0.0889)
		(layer "In13.Cu")
		(net "P5E_CPU1_PE2_RX_DN<2>")
	)
	(segment
		(start 153.977086 -421.170354)
		(end 154.015694 -421.342058)
		(width 0.14732)
		(layer "In13.Cu")
		(net "P5E_CPU1_PE2_RX_DN<2>")
	)
	(segment
		(start 124.231908 -214.622634)
		(end 124.231908 -214.461344)
		(width 0.0889)
		(layer "In13.Cu")
		(net "P5E_CPU1_PE2_RX_DN<2>")
	)
	(segment
		(start 123.762516 -213.929468)
		(end 123.762516 -213.3219)
		(width 0.0889)
		(layer "In13.Cu")
		(net "P5E_CPU1_PE2_RX_DN<2>")
	)
	(segment
		(start 122.822462 -217.071956)
		(end 122.822462 -217.064336)
		(width 0.0889)
		(layer "In13.Cu")
		(net "P5E_CPU1_PE2_RX_DN<2>")
	)
	(segment
		(start 153.37663 -422.119298)
		(end 153.421588 -422.318942)
		(width 0.14732)
		(layer "In13.Cu")
		(net "P5E_CPU1_PE2_RX_DN<2>")
	)
	(segment
		(start 123.114054 -217.559128)
		(end 123.105164 -217.554048)
		(width 0.0889)
		(layer "In13.Cu")
		(net "P5E_CPU1_PE2_RX_DN<2>")
	)
	(segment
		(start 122.447812 -220.319854)
		(end 122.604276 -220.590872)
		(width 0.0889)
		(layer "In13.Cu")
		(net "P5E_CPU1_PE2_RX_DN<2>")
	)
	(segment
		(start 152.750012 -434.552344)
		(end 152.750012 -434.289962)
		(width 0.14732)
		(layer "In13.Cu")
		(net "P5E_CPU1_PE2_RX_DN<2>")
	)
	(segment
		(start 152.066498 -424.188636)
		(end 152.066498 -434.5432)
		(width 0.14732)
		(layer "In13.Cu")
		(net "P5E_CPU1_PE2_RX_DN<2>")
	)
	(segment
		(start 153.024586 -422.675558)
		(end 153.023824 -422.675812)
		(width 0.14732)
		(layer "In13.Cu")
		(net "P5E_CPU1_PE2_RX_DN<2>")
	)
	(segment
		(start 160.360614 -406.335992)
		(end 160.360614 -411.080204)
		(width 0.14732)
		(layer "In13.Cu")
		(net "P5E_CPU1_PE2_RX_DN<2>")
	)
	(segment
		(start 124.047758 -214.261954)
		(end 124.048012 -214.261954)
		(width 0.0889)
		(layer "In13.Cu")
		(net "P5E_CPU1_PE2_RX_DN<2>")
	)
	(segment
		(start 154.143964 -321.771518)
		(end 160.986216 -329.934316)
		(width 0.14732)
		(layer "In13.Cu")
		(net "P5E_CPU1_PE2_RX_DN<2>")
	)
	(segment
		(start 160.986216 -329.934316)
		(end 163.844224 -346.140278)
		(width 0.14732)
		(layer "In13.Cu")
		(net "P5E_CPU1_PE2_RX_DN<2>")
	)
	(segment
		(start 133.152134 -201.156316)
		(end 137.340594 -201.156316)
		(width 0.14732)
		(layer "In13.Cu")
		(net "P5E_CPU1_PE2_RX_DN<2>")
	)
	(arc
		(start 123.114054 -218.197684)
		(mid 123.29253 -217.878406)
		(end 123.114054 -217.559128)
		(width 0.0889)
		(layer "In13.Cu")
		(net "P5E_CPU1_PE2_RX_DN<2>")
	)
	(arc
		(start 122.682508 -220.6117)
		(mid 122.785653 -220.481675)
		(end 122.822462 -220.319854)
		(width 0.0889)
		(layer "In13.Cu")
		(net "P5E_CPU1_PE2_RX_DN<2>")
	)
	(arc
		(start 123.5837 -215.755982)
		(mid 123.714614 -215.619622)
		(end 123.762262 -215.436704)
		(width 0.0889)
		(layer "In13.Cu")
		(net "P5E_CPU1_PE2_RX_DN<2>")
	)
	(arc
		(start 123.292616 -216.235026)
		(mid 123.371986 -215.961292)
		(end 123.57481 -215.761062)
		(width 0.0889)
		(layer "In13.Cu")
		(net "P5E_CPU1_PE2_RX_DN<2>")
	)
	(arc
		(start 124.231908 -214.461344)
		(mid 124.156903 -214.345885)
		(end 124.047758 -214.261954)
		(width 0.0889)
		(layer "In13.Cu")
		(net "P5E_CPU1_PE2_RX_DN<2>")
	)
	(arc
		(start 123.105164 -217.554048)
		(mid 122.900092 -217.350369)
		(end 122.822462 -217.071956)
		(width 0.0889)
		(layer "In13.Cu")
		(net "P5E_CPU1_PE2_RX_DN<2>")
	)
	(arc
		(start 124.053346 -214.941912)
		(mid 124.18426 -214.805552)
		(end 124.231908 -214.622634)
		(width 0.0889)
		(layer "In13.Cu")
		(net "P5E_CPU1_PE2_RX_DN<2>")
	)
	(arc
		(start 123.114054 -219.825316)
		(mid 123.292651 -219.506038)
		(end 123.114054 -219.18676)
		(width 0.0889)
		(layer "In13.Cu")
		(net "P5E_CPU1_PE2_RX_DN<2>")
	)
	(arc
		(start 122.822462 -220.319854)
		(mid 122.894697 -220.04333)
		(end 123.092972 -219.837508)
		(width 0.0889)
		(layer "In13.Cu")
		(net "P5E_CPU1_PE2_RX_DN<2>")
	)
	(arc
		(start 123.114054 -216.569798)
		(mid 123.244968 -216.433438)
		(end 123.292616 -216.25052)
		(width 0.0889)
		(layer "In13.Cu")
		(net "P5E_CPU1_PE2_RX_DN<2>")
	)
	(arc
		(start 123.099068 -219.178124)
		(mid 122.822494 -218.692222)
		(end 123.099068 -218.20632)
		(width 0.0889)
		(layer "In13.Cu")
		(net "P5E_CPU1_PE2_RX_DN<2>")
	)
	(arc
		(start 123.762262 -215.414606)
		(mid 123.843173 -215.144478)
		(end 124.044456 -214.946992)
		(width 0.0889)
		(layer "In13.Cu")
		(net "P5E_CPU1_PE2_RX_DN<2>")
	)
	(arc
		(start 124.048012 -214.261954)
		(mid 123.887907 -214.138661)
		(end 123.77801 -213.969092)
		(width 0.0889)
		(layer "In13.Cu")
		(net "P5E_CPU1_PE2_RX_DN<2>")
	)
	(arc
		(start 122.822462 -217.064336)
		(mid 122.894697 -216.787812)
		(end 123.092972 -216.58199)
		(width 0.0889)
		(layer "In13.Cu")
		(net "P5E_CPU1_PE2_RX_DN<2>")
	)
	(arc
		(start 123.77801 -213.969092)
		(mid 123.769909 -213.949419)
		(end 123.762516 -213.929468)
		(width 0.0889)
		(layer "In13.Cu")
		(net "P5E_CPU1_PE2_RX_DN<2>")
	)
	(segment
		(start 121.977912 -221.669864)
		(end 121.977912 -221.134178)
		(width 0.13208)
		(layer "F.Cu")
		(net "P5E_CPU1_PE2_RX_DN<1>")
	)
	(segment
		(start 121.977912 -221.134178)
		(end 121.978166 -221.133924)
		(width 0.13208)
		(layer "F.Cu")
		(net "P5E_CPU1_PE2_RX_DN<1>")
	)
	(segment
		(start 123.104656 -214.946992)
		(end 123.113546 -214.941912)
		(width 0.0889)
		(layer "In13.Cu")
		(net "P5E_CPU1_PE2_RX_DN<1>")
	)
	(segment
		(start 155.97759 -421.941752)
		(end 155.804616 -421.974264)
		(width 0.14732)
		(layer "In13.Cu")
		(net "P5E_CPU1_PE2_RX_DN<1>")
	)
	(segment
		(start 137.765282 -200.216516)
		(end 143.262604 -205.714092)
		(width 0.14732)
		(layer "In13.Cu")
		(net "P5E_CPU1_PE2_RX_DN<1>")
	)
	(segment
		(start 162.023806 -325.408036)
		(end 162.64763 -325.844916)
		(width 0.14732)
		(layer "In13.Cu")
		(net "P5E_CPU1_PE2_RX_DN<1>")
	)
	(segment
		(start 123.292108 -214.622634)
		(end 123.292108 -214.461344)
		(width 0.0889)
		(layer "In13.Cu")
		(net "P5E_CPU1_PE2_RX_DN<1>")
	)
	(segment
		(start 122.63501 -215.761062)
		(end 122.6439 -215.755982)
		(width 0.0889)
		(layer "In13.Cu")
		(net "P5E_CPU1_PE2_RX_DN<1>")
	)
	(segment
		(start 154.066494 -433.57165)
		(end 154.232102 -433.737258)
		(width 0.14732)
		(layer "In13.Cu")
		(net "P5E_CPU1_PE2_RX_DN<1>")
	)
	(segment
		(start 155.38831 -422.840404)
		(end 155.186888 -422.87825)
		(width 0.14732)
		(layer "In13.Cu")
		(net "P5E_CPU1_PE2_RX_DN<1>")
	)
	(segment
		(start 163.423854 -410.82595)
		(end 156.191966 -421.40759)
		(width 0.14732)
		(layer "In13.Cu")
		(net "P5E_CPU1_PE2_RX_DN<1>")
	)
	(segment
		(start 122.159268 -216.578434)
		(end 122.165364 -216.574878)
		(width 0.0889)
		(layer "In13.Cu")
		(net "P5E_CPU1_PE2_RX_DN<1>")
	)
	(segment
		(start 122.166888 -221.45752)
		(end 122.174254 -221.453202)
		(width 0.0889)
		(layer "In13.Cu")
		(net "P5E_CPU1_PE2_RX_DN<1>")
	)
	(segment
		(start 155.558236 -422.334944)
		(end 155.596082 -422.536112)
		(width 0.14732)
		(layer "In13.Cu")
		(net "P5E_CPU1_PE2_RX_DN<1>")
	)
	(segment
		(start 122.165364 -219.830396)
		(end 122.166888 -219.829634)
		(width 0.0889)
		(layer "In13.Cu")
		(net "P5E_CPU1_PE2_RX_DN<1>")
	)
	(segment
		(start 122.780552 -211.634832)
		(end 123.810014 -209.149188)
		(width 0.14732)
		(layer "In13.Cu")
		(net "P5E_CPU1_PE2_RX_DN<1>")
	)
	(segment
		(start 155.596082 -422.536112)
		(end 155.38831 -422.840404)
		(width 0.14732)
		(layer "In13.Cu")
		(net "P5E_CPU1_PE2_RX_DN<1>")
	)
	(segment
		(start 156.245052 -253.486412)
		(end 152.06472 -308.4195)
		(width 0.14732)
		(layer "In13.Cu")
		(net "P5E_CPU1_PE2_RX_DN<1>")
	)
	(segment
		(start 156.03474 -247.226836)
		(end 156.245052 -253.486412)
		(width 0.14732)
		(layer "In13.Cu")
		(net "P5E_CPU1_PE2_RX_DN<1>")
	)
	(segment
		(start 122.780552 -213.257638)
		(end 122.780552 -211.634832)
		(width 0.14732)
		(layer "In13.Cu")
		(net "P5E_CPU1_PE2_RX_DN<1>")
	)
	(segment
		(start 164.786818 -345.891104)
		(end 164.786818 -345.93403)
		(width 0.14732)
		(layer "In13.Cu")
		(net "P5E_CPU1_PE2_RX_DN<1>")
	)
	(segment
		(start 152.612598 -224.54743)
		(end 156.03474 -247.226836)
		(width 0.14732)
		(layer "In13.Cu")
		(net "P5E_CPU1_PE2_RX_DN<1>")
	)
	(segment
		(start 154.750008 -433.570126)
		(end 154.750008 -433.289964)
		(width 0.14732)
		(layer "In13.Cu")
		(net "P5E_CPU1_PE2_RX_DN<1>")
	)
	(segment
		(start 154.066494 -424.517566)
		(end 154.066494 -433.57165)
		(width 0.14732)
		(layer "In13.Cu")
		(net "P5E_CPU1_PE2_RX_DN<1>")
	)
	(segment
		(start 122.174254 -220.814646)
		(end 122.165364 -220.809566)
		(width 0.0889)
		(layer "In13.Cu")
		(net "P5E_CPU1_PE2_RX_DN<1>")
	)
	(segment
		(start 160.461452 -325.1327)
		(end 162.023806 -325.408036)
		(width 0.14732)
		(layer "In13.Cu")
		(net "P5E_CPU1_PE2_RX_DN<1>")
	)
	(segment
		(start 122.159268 -218.20632)
		(end 122.174254 -218.197684)
		(width 0.0889)
		(layer "In13.Cu")
		(net "P5E_CPU1_PE2_RX_DN<1>")
	)
	(segment
		(start 162.64763 -325.844916)
		(end 163.018978 -326.375014)
		(width 0.14732)
		(layer "In13.Cu")
		(net "P5E_CPU1_PE2_RX_DN<1>")
	)
	(segment
		(start 122.822462 -215.436704)
		(end 122.822462 -215.414606)
		(width 0.0889)
		(layer "In13.Cu")
		(net "P5E_CPU1_PE2_RX_DN<1>")
	)
	(segment
		(start 122.780552 -213.279736)
		(end 122.780552 -213.257638)
		(width 0.0889)
		(layer "In13.Cu")
		(net "P5E_CPU1_PE2_RX_DN<1>")
	)
	(segment
		(start 122.174254 -219.18676)
		(end 122.165364 -219.18168)
		(width 0.0889)
		(layer "In13.Cu")
		(net "P5E_CPU1_PE2_RX_DN<1>")
	)
	(segment
		(start 163.018978 -326.375014)
		(end 163.313618 -328.04481)
		(width 0.14732)
		(layer "In13.Cu")
		(net "P5E_CPU1_PE2_RX_DN<1>")
	)
	(segment
		(start 154.232102 -433.737258)
		(end 154.582876 -433.737258)
		(width 0.14732)
		(layer "In13.Cu")
		(net "P5E_CPU1_PE2_RX_DN<1>")
	)
	(segment
		(start 122.165364 -221.458282)
		(end 122.166888 -221.45752)
		(width 0.0889)
		(layer "In13.Cu")
		(net "P5E_CPU1_PE2_RX_DN<1>")
	)
	(segment
		(start 156.191712 -421.408098)
		(end 156.224478 -421.580818)
		(width 0.14732)
		(layer "In13.Cu")
		(net "P5E_CPU1_PE2_RX_DN<1>")
	)
	(segment
		(start 132.742686 -200.216516)
		(end 137.765282 -200.216516)
		(width 0.14732)
		(layer "In13.Cu")
		(net "P5E_CPU1_PE2_RX_DN<1>")
	)
	(segment
		(start 122.159268 -219.833952)
		(end 122.16257 -219.83192)
		(width 0.0889)
		(layer "In13.Cu")
		(net "P5E_CPU1_PE2_RX_DN<1>")
	)
	(segment
		(start 122.822716 -213.3219)
		(end 122.780552 -213.279736)
		(width 0.0889)
		(layer "In13.Cu")
		(net "P5E_CPU1_PE2_RX_DN<1>")
	)
	(segment
		(start 121.882662 -217.07856)
		(end 121.882662 -217.064336)
		(width 0.0889)
		(layer "In13.Cu")
		(net "P5E_CPU1_PE2_RX_DN<1>")
	)
	(segment
		(start 122.165364 -216.574878)
		(end 122.174254 -216.569798)
		(width 0.0889)
		(layer "In13.Cu")
		(net "P5E_CPU1_PE2_RX_DN<1>")
	)
	(segment
		(start 155.804616 -421.974264)
		(end 155.558236 -422.334944)
		(width 0.14732)
		(layer "In13.Cu")
		(net "P5E_CPU1_PE2_RX_DN<1>")
	)
	(segment
		(start 164.78885 -345.889072)
		(end 164.786818 -345.891104)
		(width 0.14732)
		(layer "In13.Cu")
		(net "P5E_CPU1_PE2_RX_DN<1>")
	)
	(segment
		(start 156.502862 -322.270628)
		(end 160.461452 -325.1327)
		(width 0.14732)
		(layer "In13.Cu")
		(net "P5E_CPU1_PE2_RX_DN<1>")
	)
	(segment
		(start 121.978166 -221.133924)
		(end 121.821702 -221.404942)
		(width 0.0889)
		(layer "In13.Cu")
		(net "P5E_CPU1_PE2_RX_DN<1>")
	)
	(segment
		(start 148.729446 -211.181442)
		(end 152.612598 -224.54743)
		(width 0.14732)
		(layer "In13.Cu")
		(net "P5E_CPU1_PE2_RX_DN<1>")
	)
	(segment
		(start 122.165364 -219.18168)
		(end 122.159268 -219.178124)
		(width 0.0889)
		(layer "In13.Cu")
		(net "P5E_CPU1_PE2_RX_DN<1>")
	)
	(segment
		(start 122.166888 -219.829634)
		(end 122.174254 -219.825316)
		(width 0.0889)
		(layer "In13.Cu")
		(net "P5E_CPU1_PE2_RX_DN<1>")
	)
	(segment
		(start 152.06472 -308.4195)
		(end 154.570684 -319.353946)
		(width 0.14732)
		(layer "In13.Cu")
		(net "P5E_CPU1_PE2_RX_DN<1>")
	)
	(segment
		(start 123.810014 -209.149188)
		(end 132.742686 -200.216516)
		(width 0.14732)
		(layer "In13.Cu")
		(net "P5E_CPU1_PE2_RX_DN<1>")
	)
	(segment
		(start 154.582876 -433.737258)
		(end 154.750008 -433.570126)
		(width 0.14732)
		(layer "In13.Cu")
		(net "P5E_CPU1_PE2_RX_DN<1>")
	)
	(segment
		(start 154.570684 -319.353946)
		(end 156.502862 -322.270628)
		(width 0.14732)
		(layer "In13.Cu")
		(net "P5E_CPU1_PE2_RX_DN<1>")
	)
	(segment
		(start 122.174254 -217.559128)
		(end 122.165364 -217.554048)
		(width 0.0889)
		(layer "In13.Cu")
		(net "P5E_CPU1_PE2_RX_DN<1>")
	)
	(segment
		(start 121.821702 -221.404942)
		(end 121.842784 -221.48292)
		(width 0.0889)
		(layer "In13.Cu")
		(net "P5E_CPU1_PE2_RX_DN<1>")
	)
	(segment
		(start 122.822716 -213.930484)
		(end 122.822716 -213.3219)
		(width 0.0889)
		(layer "In13.Cu")
		(net "P5E_CPU1_PE2_RX_DN<1>")
	)
	(segment
		(start 143.262604 -205.714092)
		(end 143.262604 -205.7146)
		(width 0.14732)
		(layer "In13.Cu")
		(net "P5E_CPU1_PE2_RX_DN<1>")
	)
	(segment
		(start 143.262604 -205.7146)
		(end 148.729446 -211.181442)
		(width 0.14732)
		(layer "In13.Cu")
		(net "P5E_CPU1_PE2_RX_DN<1>")
	)
	(segment
		(start 165.140894 -400.451828)
		(end 165.140894 -404.618952)
		(width 0.14732)
		(layer "In13.Cu")
		(net "P5E_CPU1_PE2_RX_DN<1>")
	)
	(segment
		(start 156.191966 -421.40759)
		(end 156.191712 -421.408098)
		(width 0.14732)
		(layer "In13.Cu")
		(net "P5E_CPU1_PE2_RX_DN<1>")
	)
	(segment
		(start 164.692076 -393.358878)
		(end 165.140894 -400.451828)
		(width 0.14732)
		(layer "In13.Cu")
		(net "P5E_CPU1_PE2_RX_DN<1>")
	)
	(segment
		(start 165.140894 -404.618952)
		(end 163.423854 -406.335992)
		(width 0.14732)
		(layer "In13.Cu")
		(net "P5E_CPU1_PE2_RX_DN<1>")
	)
	(segment
		(start 121.882662 -220.334078)
		(end 121.882662 -220.319854)
		(width 0.0889)
		(layer "In13.Cu")
		(net "P5E_CPU1_PE2_RX_DN<1>")
	)
	(segment
		(start 122.352816 -216.25052)
		(end 122.352816 -216.235026)
		(width 0.0889)
		(layer "In13.Cu")
		(net "P5E_CPU1_PE2_RX_DN<1>")
	)
	(segment
		(start 164.100256 -361.229402)
		(end 164.692076 -393.358878)
		(width 0.14732)
		(layer "In13.Cu")
		(net "P5E_CPU1_PE2_RX_DN<1>")
	)
	(segment
		(start 163.313618 -328.04481)
		(end 164.78885 -345.889072)
		(width 0.14732)
		(layer "In13.Cu")
		(net "P5E_CPU1_PE2_RX_DN<1>")
	)
	(segment
		(start 155.186888 -422.87825)
		(end 154.066494 -424.517566)
		(width 0.14732)
		(layer "In13.Cu")
		(net "P5E_CPU1_PE2_RX_DN<1>")
	)
	(segment
		(start 156.224478 -421.580818)
		(end 155.97759 -421.941752)
		(width 0.14732)
		(layer "In13.Cu")
		(net "P5E_CPU1_PE2_RX_DN<1>")
	)
	(segment
		(start 163.423854 -406.335992)
		(end 163.423854 -410.82595)
		(width 0.14732)
		(layer "In13.Cu")
		(net "P5E_CPU1_PE2_RX_DN<1>")
	)
	(segment
		(start 164.786818 -345.93403)
		(end 164.100256 -361.229402)
		(width 0.14732)
		(layer "In13.Cu")
		(net "P5E_CPU1_PE2_RX_DN<1>")
	)
	(segment
		(start 122.16257 -219.83192)
		(end 122.165364 -219.830396)
		(width 0.0889)
		(layer "In13.Cu")
		(net "P5E_CPU1_PE2_RX_DN<1>")
	)
	(arc
		(start 122.6439 -215.755982)
		(mid 122.774814 -215.619622)
		(end 122.822462 -215.436704)
		(width 0.0889)
		(layer "In13.Cu")
		(net "P5E_CPU1_PE2_RX_DN<1>")
	)
	(arc
		(start 123.107958 -214.261954)
		(mid 122.947886 -214.138774)
		(end 122.837956 -213.969346)
		(width 0.0889)
		(layer "In13.Cu")
		(net "P5E_CPU1_PE2_RX_DN<1>")
	)
	(arc
		(start 122.174254 -219.825316)
		(mid 122.352851 -219.506038)
		(end 122.174254 -219.18676)
		(width 0.0889)
		(layer "In13.Cu")
		(net "P5E_CPU1_PE2_RX_DN<1>")
	)
	(arc
		(start 122.165364 -217.554048)
		(mid 121.961883 -217.353244)
		(end 121.882662 -217.07856)
		(width 0.0889)
		(layer "In13.Cu")
		(net "P5E_CPU1_PE2_RX_DN<1>")
	)
	(arc
		(start 122.174254 -221.453202)
		(mid 122.352972 -221.133924)
		(end 122.174254 -220.814646)
		(width 0.0889)
		(layer "In13.Cu")
		(net "P5E_CPU1_PE2_RX_DN<1>")
	)
	(arc
		(start 122.822462 -215.414606)
		(mid 122.903373 -215.144478)
		(end 123.104656 -214.946992)
		(width 0.0889)
		(layer "In13.Cu")
		(net "P5E_CPU1_PE2_RX_DN<1>")
	)
	(arc
		(start 122.352816 -216.235026)
		(mid 122.432186 -215.961292)
		(end 122.63501 -215.761062)
		(width 0.0889)
		(layer "In13.Cu")
		(net "P5E_CPU1_PE2_RX_DN<1>")
	)
	(arc
		(start 122.165364 -220.809566)
		(mid 121.961883 -220.608762)
		(end 121.882662 -220.334078)
		(width 0.0889)
		(layer "In13.Cu")
		(net "P5E_CPU1_PE2_RX_DN<1>")
	)
	(arc
		(start 123.292108 -214.461344)
		(mid 123.217103 -214.345885)
		(end 123.107958 -214.261954)
		(width 0.0889)
		(layer "In13.Cu")
		(net "P5E_CPU1_PE2_RX_DN<1>")
	)
	(arc
		(start 122.174254 -218.197684)
		(mid 122.352972 -217.878406)
		(end 122.174254 -217.559128)
		(width 0.0889)
		(layer "In13.Cu")
		(net "P5E_CPU1_PE2_RX_DN<1>")
	)
	(arc
		(start 122.174254 -216.569798)
		(mid 122.305168 -216.433438)
		(end 122.352816 -216.25052)
		(width 0.0889)
		(layer "In13.Cu")
		(net "P5E_CPU1_PE2_RX_DN<1>")
	)
	(arc
		(start 121.882662 -220.319854)
		(mid 121.956653 -220.040288)
		(end 122.159268 -219.833952)
		(width 0.0889)
		(layer "In13.Cu")
		(net "P5E_CPU1_PE2_RX_DN<1>")
	)
	(arc
		(start 123.113546 -214.941912)
		(mid 123.24446 -214.805552)
		(end 123.292108 -214.622634)
		(width 0.0889)
		(layer "In13.Cu")
		(net "P5E_CPU1_PE2_RX_DN<1>")
	)
	(arc
		(start 121.842784 -221.48292)
		(mid 122.00688 -221.507267)
		(end 122.165364 -221.458282)
		(width 0.0889)
		(layer "In13.Cu")
		(net "P5E_CPU1_PE2_RX_DN<1>")
	)
	(arc
		(start 121.882662 -217.064336)
		(mid 121.956653 -216.78477)
		(end 122.159268 -216.578434)
		(width 0.0889)
		(layer "In13.Cu")
		(net "P5E_CPU1_PE2_RX_DN<1>")
	)
	(arc
		(start 122.159268 -219.178124)
		(mid 121.882694 -218.692222)
		(end 122.159268 -218.20632)
		(width 0.0889)
		(layer "In13.Cu")
		(net "P5E_CPU1_PE2_RX_DN<1>")
	)
	(arc
		(start 122.837956 -213.969346)
		(mid 122.829993 -213.950049)
		(end 122.822716 -213.930484)
		(width 0.0889)
		(layer "In13.Cu")
		(net "P5E_CPU1_PE2_RX_DN<1>")
	)
	(segment
		(start 135.135112 -221.669864)
		(end 135.135366 -221.66961)
		(width 0.13208)
		(layer "F.Cu")
		(net "P5E_CPU1_PE2_RX_DN<15>")
	)
	(segment
		(start 135.135366 -221.66961)
		(end 135.135366 -221.133924)
		(width 0.13208)
		(layer "F.Cu")
		(net "P5E_CPU1_PE2_RX_DN<15>")
	)
	(segment
		(start 122.08764 -417.504626)
		(end 122.156728 -417.86683)
		(width 0.14732)
		(layer "In13.Cu")
		(net "P5E_CPU1_PE2_RX_DN<15>")
	)
	(segment
		(start 137.869422 -226.01301)
		(end 137.884916 -226.028504)
		(width 0.0889)
		(layer "In13.Cu")
		(net "P5E_CPU1_PE2_RX_DN<15>")
	)
	(segment
		(start 122.286014 -419.31209)
		(end 124.996956 -433.483512)
		(width 0.14732)
		(layer "In13.Cu")
		(net "P5E_CPU1_PE2_RX_DN<15>")
	)
	(segment
		(start 137.714228 -225.916744)
		(end 137.810494 -226.01301)
		(width 0.0889)
		(layer "In13.Cu")
		(net "P5E_CPU1_PE2_RX_DN<15>")
	)
	(segment
		(start 121.594626 -415.69894)
		(end 121.725182 -416.3822)
		(width 0.14732)
		(layer "In13.Cu")
		(net "P5E_CPU1_PE2_RX_DN<15>")
	)
	(segment
		(start 138.410188 -253.397258)
		(end 139.010898 -254.84709)
		(width 0.14732)
		(layer "In13.Cu")
		(net "P5E_CPU1_PE2_RX_DN<15>")
	)
	(segment
		(start 137.884916 -226.028504)
		(end 138.35126 -226.494594)
		(width 0.14732)
		(layer "In13.Cu")
		(net "P5E_CPU1_PE2_RX_DN<15>")
	)
	(segment
		(start 121.725182 -416.3822)
		(end 121.8946 -416.496754)
		(width 0.14732)
		(layer "In13.Cu")
		(net "P5E_CPU1_PE2_RX_DN<15>")
	)
	(segment
		(start 122.156728 -417.86683)
		(end 122.04192 -418.036248)
		(width 0.14732)
		(layer "In13.Cu")
		(net "P5E_CPU1_PE2_RX_DN<15>")
	)
	(segment
		(start 124.996956 -433.483512)
		(end 125.232922 -433.719478)
		(width 0.14732)
		(layer "In13.Cu")
		(net "P5E_CPU1_PE2_RX_DN<15>")
	)
	(segment
		(start 145.429986 -369.273582)
		(end 122.878088 -399.111978)
		(width 0.14732)
		(layer "In13.Cu")
		(net "P5E_CPU1_PE2_RX_DN<15>")
	)
	(segment
		(start 125.232922 -433.719478)
		(end 125.582934 -433.719478)
		(width 0.14732)
		(layer "In13.Cu")
		(net "P5E_CPU1_PE2_RX_DN<15>")
	)
	(segment
		(start 136.170416 -223.557084)
		(end 136.170416 -223.584262)
		(width 0.0889)
		(layer "In13.Cu")
		(net "P5E_CPU1_PE2_RX_DN<15>")
	)
	(segment
		(start 135.417306 -222.27159)
		(end 135.418068 -222.272098)
		(width 0.0889)
		(layer "In13.Cu")
		(net "P5E_CPU1_PE2_RX_DN<15>")
	)
	(segment
		(start 122.04192 -418.036248)
		(end 122.162316 -418.66566)
		(width 0.14732)
		(layer "In13.Cu")
		(net "P5E_CPU1_PE2_RX_DN<15>")
	)
	(segment
		(start 122.878088 -399.111978)
		(end 122.255534 -400.282918)
		(width 0.14732)
		(layer "In13.Cu")
		(net "P5E_CPU1_PE2_RX_DN<15>")
	)
	(segment
		(start 121.709434 -415.529776)
		(end 121.594626 -415.69894)
		(width 0.14732)
		(layer "In13.Cu")
		(net "P5E_CPU1_PE2_RX_DN<15>")
	)
	(segment
		(start 122.255534 -400.282918)
		(end 122.255534 -404.618952)
		(width 0.14732)
		(layer "In13.Cu")
		(net "P5E_CPU1_PE2_RX_DN<15>")
	)
	(segment
		(start 135.409178 -222.267018)
		(end 135.412226 -222.268796)
		(width 0.0889)
		(layer "In13.Cu")
		(net "P5E_CPU1_PE2_RX_DN<15>")
	)
	(segment
		(start 121.917968 -417.389818)
		(end 122.08764 -417.504626)
		(width 0.14732)
		(layer "In13.Cu")
		(net "P5E_CPU1_PE2_RX_DN<15>")
	)
	(segment
		(start 138.840718 -232.16616)
		(end 138.580368 -246.008398)
		(width 0.14732)
		(layer "In13.Cu")
		(net "P5E_CPU1_PE2_RX_DN<15>")
	)
	(segment
		(start 135.412226 -222.268796)
		(end 135.417306 -222.27159)
		(width 0.0889)
		(layer "In13.Cu")
		(net "P5E_CPU1_PE2_RX_DN<15>")
	)
	(segment
		(start 141.324838 -259.66928)
		(end 140.464032 -271.523714)
		(width 0.14732)
		(layer "In13.Cu")
		(net "P5E_CPU1_PE2_RX_DN<15>")
	)
	(segment
		(start 136.357614 -223.899984)
		(end 136.358376 -223.900492)
		(width 0.0889)
		(layer "In13.Cu")
		(net "P5E_CPU1_PE2_RX_DN<15>")
	)
	(segment
		(start 137.414508 -225.61677)
		(end 137.714228 -225.916744)
		(width 0.0889)
		(layer "In13.Cu")
		(net "P5E_CPU1_PE2_RX_DN<15>")
	)
	(segment
		(start 120.538494 -406.335992)
		(end 120.538494 -410.18079)
		(width 0.14732)
		(layer "In13.Cu")
		(net "P5E_CPU1_PE2_RX_DN<15>")
	)
	(segment
		(start 148.9964 -334.99171)
		(end 150.799292 -345.213432)
		(width 0.14732)
		(layer "In13.Cu")
		(net "P5E_CPU1_PE2_RX_DN<15>")
	)
	(segment
		(start 134.978902 -221.404942)
		(end 135.003032 -221.494096)
		(width 0.0889)
		(layer "In13.Cu")
		(net "P5E_CPU1_PE2_RX_DN<15>")
	)
	(segment
		(start 137.283444 -225.519234)
		(end 137.297668 -225.527362)
		(width 0.0889)
		(layer "In13.Cu")
		(net "P5E_CPU1_PE2_RX_DN<15>")
	)
	(segment
		(start 137.873994 -252.631194)
		(end 138.410188 -253.397258)
		(width 0.14732)
		(layer "In13.Cu")
		(net "P5E_CPU1_PE2_RX_DN<15>")
	)
	(segment
		(start 137.110216 -225.193352)
		(end 137.110216 -225.203258)
		(width 0.0889)
		(layer "In13.Cu")
		(net "P5E_CPU1_PE2_RX_DN<15>")
	)
	(segment
		(start 125.750066 -433.552346)
		(end 125.750066 -433.289964)
		(width 0.14732)
		(layer "In13.Cu")
		(net "P5E_CPU1_PE2_RX_DN<15>")
	)
	(segment
		(start 122.162316 -418.66566)
		(end 122.331988 -418.780722)
		(width 0.14732)
		(layer "In13.Cu")
		(net "P5E_CPU1_PE2_RX_DN<15>")
	)
	(segment
		(start 122.255534 -404.618952)
		(end 120.538494 -406.335992)
		(width 0.14732)
		(layer "In13.Cu")
		(net "P5E_CPU1_PE2_RX_DN<15>")
	)
	(segment
		(start 121.470928 -415.053272)
		(end 121.640346 -415.167826)
		(width 0.14732)
		(layer "In13.Cu")
		(net "P5E_CPU1_PE2_RX_DN<15>")
	)
	(segment
		(start 137.512044 -250.579636)
		(end 137.873994 -252.631194)
		(width 0.14732)
		(layer "In13.Cu")
		(net "P5E_CPU1_PE2_RX_DN<15>")
	)
	(segment
		(start 122.401076 -419.142672)
		(end 122.286014 -419.31209)
		(width 0.14732)
		(layer "In13.Cu")
		(net "P5E_CPU1_PE2_RX_DN<15>")
	)
	(segment
		(start 140.437108 -256.883662)
		(end 141.324838 -259.66928)
		(width 0.14732)
		(layer "In13.Cu")
		(net "P5E_CPU1_PE2_RX_DN<15>")
	)
	(segment
		(start 138.580368 -246.008398)
		(end 137.951464 -248.087896)
		(width 0.14732)
		(layer "In13.Cu")
		(net "P5E_CPU1_PE2_RX_DN<15>")
	)
	(segment
		(start 137.810494 -226.01301)
		(end 137.869422 -226.01301)
		(width 0.0889)
		(layer "In13.Cu")
		(net "P5E_CPU1_PE2_RX_DN<15>")
	)
	(segment
		(start 121.8946 -416.496754)
		(end 121.963688 -416.858704)
		(width 0.14732)
		(layer "In13.Cu")
		(net "P5E_CPU1_PE2_RX_DN<15>")
	)
	(segment
		(start 139.010898 -254.84709)
		(end 140.437108 -256.883662)
		(width 0.14732)
		(layer "In13.Cu")
		(net "P5E_CPU1_PE2_RX_DN<15>")
	)
	(segment
		(start 136.36117 -223.902016)
		(end 136.36371 -223.90354)
		(width 0.0889)
		(layer "In13.Cu")
		(net "P5E_CPU1_PE2_RX_DN<15>")
	)
	(segment
		(start 120.538494 -410.18079)
		(end 121.470928 -415.053272)
		(width 0.14732)
		(layer "In13.Cu")
		(net "P5E_CPU1_PE2_RX_DN<15>")
	)
	(segment
		(start 137.951464 -248.087896)
		(end 137.512044 -250.579636)
		(width 0.14732)
		(layer "In13.Cu")
		(net "P5E_CPU1_PE2_RX_DN<15>")
	)
	(segment
		(start 121.963688 -416.858704)
		(end 121.84888 -417.028122)
		(width 0.14732)
		(layer "In13.Cu")
		(net "P5E_CPU1_PE2_RX_DN<15>")
	)
	(segment
		(start 138.35126 -226.494594)
		(end 138.840718 -232.16616)
		(width 0.14732)
		(layer "In13.Cu")
		(net "P5E_CPU1_PE2_RX_DN<15>")
	)
	(segment
		(start 122.331988 -418.780722)
		(end 122.401076 -419.142672)
		(width 0.14732)
		(layer "In13.Cu")
		(net "P5E_CPU1_PE2_RX_DN<15>")
	)
	(segment
		(start 121.640346 -415.167826)
		(end 121.709434 -415.529776)
		(width 0.14732)
		(layer "In13.Cu")
		(net "P5E_CPU1_PE2_RX_DN<15>")
	)
	(segment
		(start 125.582934 -433.719478)
		(end 125.750066 -433.552346)
		(width 0.14732)
		(layer "In13.Cu")
		(net "P5E_CPU1_PE2_RX_DN<15>")
	)
	(segment
		(start 136.818878 -224.70872)
		(end 136.827768 -224.7138)
		(width 0.0889)
		(layer "In13.Cu")
		(net "P5E_CPU1_PE2_RX_DN<15>")
	)
	(segment
		(start 135.879078 -223.080834)
		(end 135.887968 -223.085914)
		(width 0.0889)
		(layer "In13.Cu")
		(net "P5E_CPU1_PE2_RX_DN<15>")
	)
	(segment
		(start 136.358376 -223.900492)
		(end 136.36117 -223.902016)
		(width 0.0889)
		(layer "In13.Cu")
		(net "P5E_CPU1_PE2_RX_DN<15>")
	)
	(segment
		(start 140.464032 -271.523714)
		(end 138.585194 -310.020208)
		(width 0.14732)
		(layer "In13.Cu")
		(net "P5E_CPU1_PE2_RX_DN<15>")
	)
	(segment
		(start 135.700516 -222.75165)
		(end 135.700516 -222.761556)
		(width 0.0889)
		(layer "In13.Cu")
		(net "P5E_CPU1_PE2_RX_DN<15>")
	)
	(segment
		(start 149.790912 -358.426004)
		(end 145.429986 -369.273582)
		(width 0.14732)
		(layer "In13.Cu")
		(net "P5E_CPU1_PE2_RX_DN<15>")
	)
	(segment
		(start 135.135366 -221.133924)
		(end 134.978902 -221.404942)
		(width 0.0889)
		(layer "In13.Cu")
		(net "P5E_CPU1_PE2_RX_DN<15>")
	)
	(segment
		(start 150.799292 -345.213432)
		(end 149.790912 -358.426004)
		(width 0.14732)
		(layer "In13.Cu")
		(net "P5E_CPU1_PE2_RX_DN<15>")
	)
	(segment
		(start 143.022828 -328.310494)
		(end 148.9964 -334.99171)
		(width 0.14732)
		(layer "In13.Cu")
		(net "P5E_CPU1_PE2_RX_DN<15>")
	)
	(segment
		(start 138.585194 -310.020208)
		(end 143.022828 -328.310494)
		(width 0.14732)
		(layer "In13.Cu")
		(net "P5E_CPU1_PE2_RX_DN<15>")
	)
	(segment
		(start 121.84888 -417.028122)
		(end 121.917968 -417.389818)
		(width 0.14732)
		(layer "In13.Cu")
		(net "P5E_CPU1_PE2_RX_DN<15>")
	)
	(arc
		(start 135.019796 -221.50705)
		(mid 135.17527 -221.703449)
		(end 135.230616 -221.94774)
		(width 0.0889)
		(layer "In13.Cu")
		(net "P5E_CPU1_PE2_RX_DN<15>")
	)
	(arc
		(start 135.700516 -222.761556)
		(mid 135.748195 -222.944456)
		(end 135.879078 -223.080834)
		(width 0.0889)
		(layer "In13.Cu")
		(net "P5E_CPU1_PE2_RX_DN<15>")
	)
	(arc
		(start 136.170416 -223.584262)
		(mid 136.222686 -223.766627)
		(end 136.357614 -223.899984)
		(width 0.0889)
		(layer "In13.Cu")
		(net "P5E_CPU1_PE2_RX_DN<15>")
	)
	(arc
		(start 137.390886 -225.594672)
		(mid 137.402856 -225.605551)
		(end 137.414508 -225.61677)
		(width 0.0889)
		(layer "In13.Cu")
		(net "P5E_CPU1_PE2_RX_DN<15>")
	)
	(arc
		(start 135.003032 -221.494096)
		(mid 135.011475 -221.500494)
		(end 135.019796 -221.50705)
		(width 0.0889)
		(layer "In13.Cu")
		(net "P5E_CPU1_PE2_RX_DN<15>")
	)
	(arc
		(start 137.297668 -225.527362)
		(mid 137.345992 -225.558642)
		(end 137.390886 -225.594672)
		(width 0.0889)
		(layer "In13.Cu")
		(net "P5E_CPU1_PE2_RX_DN<15>")
	)
	(arc
		(start 137.110216 -225.203258)
		(mid 137.156355 -225.383443)
		(end 137.283444 -225.519234)
		(width 0.0889)
		(layer "In13.Cu")
		(net "P5E_CPU1_PE2_RX_DN<15>")
	)
	(arc
		(start 136.640316 -224.389442)
		(mid 136.687995 -224.572342)
		(end 136.818878 -224.70872)
		(width 0.0889)
		(layer "In13.Cu")
		(net "P5E_CPU1_PE2_RX_DN<15>")
	)
	(arc
		(start 136.36371 -223.90354)
		(mid 136.566297 -224.109891)
		(end 136.640316 -224.389442)
		(width 0.0889)
		(layer "In13.Cu")
		(net "P5E_CPU1_PE2_RX_DN<15>")
	)
	(arc
		(start 135.230616 -221.94774)
		(mid 135.278295 -222.13064)
		(end 135.409178 -222.267018)
		(width 0.0889)
		(layer "In13.Cu")
		(net "P5E_CPU1_PE2_RX_DN<15>")
	)
	(arc
		(start 135.418068 -222.272098)
		(mid 135.622403 -222.474703)
		(end 135.700516 -222.75165)
		(width 0.0889)
		(layer "In13.Cu")
		(net "P5E_CPU1_PE2_RX_DN<15>")
	)
	(arc
		(start 136.827768 -224.7138)
		(mid 137.032103 -224.916405)
		(end 137.110216 -225.193352)
		(width 0.0889)
		(layer "In13.Cu")
		(net "P5E_CPU1_PE2_RX_DN<15>")
	)
	(arc
		(start 135.887968 -223.085914)
		(mid 136.090254 -223.284895)
		(end 136.170416 -223.557084)
		(width 0.0889)
		(layer "In13.Cu")
		(net "P5E_CPU1_PE2_RX_DN<15>")
	)
	(segment
		(start 133.725666 -220.855794)
		(end 133.725666 -220.319854)
		(width 0.13208)
		(layer "F.Cu")
		(net "P5E_CPU1_PE2_RX_DN<14>")
	)
	(segment
		(start 139.17676 -225.527616)
		(end 139.187428 -225.533966)
		(width 0.0889)
		(layer "In13.Cu")
		(net "P5E_CPU1_PE2_RX_DN<14>")
	)
	(segment
		(start 133.88213 -220.590872)
		(end 133.971284 -220.614748)
		(width 0.0889)
		(layer "In13.Cu")
		(net "P5E_CPU1_PE2_RX_DN<14>")
	)
	(segment
		(start 150.832058 -358.61625)
		(end 146.288506 -369.667536)
		(width 0.14732)
		(layer "In13.Cu")
		(net "P5E_CPU1_PE2_RX_DN<14>")
	)
	(segment
		(start 137.287762 -223.894396)
		(end 137.296398 -223.89973)
		(width 0.0889)
		(layer "In13.Cu")
		(net "P5E_CPU1_PE2_RX_DN<14>")
	)
	(segment
		(start 135.417306 -220.644466)
		(end 135.428228 -220.650816)
		(width 0.0889)
		(layer "In13.Cu")
		(net "P5E_CPU1_PE2_RX_DN<14>")
	)
	(segment
		(start 137.296398 -223.89973)
		(end 137.305288 -223.90481)
		(width 0.0889)
		(layer "In13.Cu")
		(net "P5E_CPU1_PE2_RX_DN<14>")
	)
	(segment
		(start 141.555978 -244.340634)
		(end 140.529564 -247.552464)
		(width 0.14732)
		(layer "In13.Cu")
		(net "P5E_CPU1_PE2_RX_DN<14>")
	)
	(segment
		(start 137.579862 -224.389442)
		(end 137.579862 -224.397316)
		(width 0.0889)
		(layer "In13.Cu")
		(net "P5E_CPU1_PE2_RX_DN<14>")
	)
	(segment
		(start 140.928598 -255.752854)
		(end 141.558772 -256.63017)
		(width 0.14732)
		(layer "In13.Cu")
		(net "P5E_CPU1_PE2_RX_DN<14>")
	)
	(segment
		(start 125.318774 -400.585432)
		(end 125.318774 -404.618952)
		(width 0.14732)
		(layer "In13.Cu")
		(net "P5E_CPU1_PE2_RX_DN<14>")
	)
	(segment
		(start 140.251434 -254.154178)
		(end 140.928598 -255.752854)
		(width 0.14732)
		(layer "In13.Cu")
		(net "P5E_CPU1_PE2_RX_DN<14>")
	)
	(segment
		(start 125.320552 -416.386772)
		(end 125.217682 -416.56381)
		(width 0.14732)
		(layer "In13.Cu")
		(net "P5E_CPU1_PE2_RX_DN<14>")
	)
	(segment
		(start 136.353042 -222.269558)
		(end 136.357868 -222.272606)
		(width 0.0889)
		(layer "In13.Cu")
		(net "P5E_CPU1_PE2_RX_DN<14>")
	)
	(segment
		(start 139.238736 -248.504456)
		(end 139.238736 -251.20854)
		(width 0.14732)
		(layer "In13.Cu")
		(net "P5E_CPU1_PE2_RX_DN<14>")
	)
	(segment
		(start 139.501372 -226.38512)
		(end 139.501372 -226.407218)
		(width 0.0889)
		(layer "In13.Cu")
		(net "P5E_CPU1_PE2_RX_DN<14>")
	)
	(segment
		(start 140.529564 -247.552464)
		(end 139.90955 -247.946672)
		(width 0.14732)
		(layer "In13.Cu")
		(net "P5E_CPU1_PE2_RX_DN<14>")
	)
	(segment
		(start 139.53236 -248.210832)
		(end 139.238736 -248.504456)
		(width 0.14732)
		(layer "In13.Cu")
		(net "P5E_CPU1_PE2_RX_DN<14>")
	)
	(segment
		(start 125.217682 -416.56381)
		(end 125.320298 -416.951922)
		(width 0.14732)
		(layer "In13.Cu")
		(net "P5E_CPU1_PE2_RX_DN<14>")
	)
	(segment
		(start 125.591824 -417.4109)
		(end 125.488954 -417.587938)
		(width 0.14732)
		(layer "In13.Cu")
		(net "P5E_CPU1_PE2_RX_DN<14>")
	)
	(segment
		(start 123.601734 -410.467556)
		(end 125.049026 -415.928048)
		(width 0.14732)
		(layer "In13.Cu")
		(net "P5E_CPU1_PE2_RX_DN<14>")
	)
	(segment
		(start 139.459462 -226.34321)
		(end 139.501372 -226.38512)
		(width 0.0889)
		(layer "In13.Cu")
		(net "P5E_CPU1_PE2_RX_DN<14>")
	)
	(segment
		(start 133.971284 -220.614748)
		(end 133.971538 -220.615256)
		(width 0.0889)
		(layer "In13.Cu")
		(net "P5E_CPU1_PE2_RX_DN<14>")
	)
	(segment
		(start 125.70714 -399.344388)
		(end 125.318774 -400.585432)
		(width 0.14732)
		(layer "In13.Cu")
		(net "P5E_CPU1_PE2_RX_DN<14>")
	)
	(segment
		(start 136.169908 -221.937072)
		(end 136.169908 -221.94774)
		(width 0.0889)
		(layer "In13.Cu")
		(net "P5E_CPU1_PE2_RX_DN<14>")
	)
	(segment
		(start 123.601734 -406.335992)
		(end 123.601734 -410.467556)
		(width 0.14732)
		(layer "In13.Cu")
		(net "P5E_CPU1_PE2_RX_DN<14>")
	)
	(segment
		(start 133.725666 -220.319854)
		(end 133.88213 -220.590872)
		(width 0.0889)
		(layer "In13.Cu")
		(net "P5E_CPU1_PE2_RX_DN<14>")
	)
	(segment
		(start 127.58293 -434.711856)
		(end 127.750062 -434.544724)
		(width 0.14732)
		(layer "In13.Cu")
		(net "P5E_CPU1_PE2_RX_DN<14>")
	)
	(segment
		(start 149.965156 -334.659732)
		(end 151.821642 -345.186)
		(width 0.14732)
		(layer "In13.Cu")
		(net "P5E_CPU1_PE2_RX_DN<14>")
	)
	(segment
		(start 127.066548 -423.541952)
		(end 127.066548 -434.539644)
		(width 0.14732)
		(layer "In13.Cu")
		(net "P5E_CPU1_PE2_RX_DN<14>")
	)
	(segment
		(start 138.706606 -224.7138)
		(end 138.717528 -224.72015)
		(width 0.0889)
		(layer "In13.Cu")
		(net "P5E_CPU1_PE2_RX_DN<14>")
	)
	(segment
		(start 125.226064 -416.030664)
		(end 125.320552 -416.386772)
		(width 0.14732)
		(layer "In13.Cu")
		(net "P5E_CPU1_PE2_RX_DN<14>")
	)
	(segment
		(start 125.320298 -416.951922)
		(end 125.497336 -417.054538)
		(width 0.14732)
		(layer "In13.Cu")
		(net "P5E_CPU1_PE2_RX_DN<14>")
	)
	(segment
		(start 127.750062 -434.544724)
		(end 127.750062 -434.289962)
		(width 0.14732)
		(layer "In13.Cu")
		(net "P5E_CPU1_PE2_RX_DN<14>")
	)
	(segment
		(start 139.238736 -251.20854)
		(end 140.251434 -254.154178)
		(width 0.14732)
		(layer "In13.Cu")
		(net "P5E_CPU1_PE2_RX_DN<14>")
	)
	(segment
		(start 139.501372 -226.407218)
		(end 139.501372 -226.861116)
		(width 0.14732)
		(layer "In13.Cu")
		(net "P5E_CPU1_PE2_RX_DN<14>")
	)
	(segment
		(start 146.288506 -369.667536)
		(end 125.70714 -399.344388)
		(width 0.14732)
		(layer "In13.Cu")
		(net "P5E_CPU1_PE2_RX_DN<14>")
	)
	(segment
		(start 141.558772 -256.63017)
		(end 141.57198 -256.677414)
		(width 0.14732)
		(layer "In13.Cu")
		(net "P5E_CPU1_PE2_RX_DN<14>")
	)
	(segment
		(start 137.305288 -223.90481)
		(end 137.310876 -223.908112)
		(width 0.0889)
		(layer "In13.Cu")
		(net "P5E_CPU1_PE2_RX_DN<14>")
	)
	(segment
		(start 143.896588 -327.811638)
		(end 149.965156 -334.659732)
		(width 0.14732)
		(layer "In13.Cu")
		(net "P5E_CPU1_PE2_RX_DN<14>")
	)
	(segment
		(start 127.23876 -434.711856)
		(end 127.58293 -434.711856)
		(width 0.14732)
		(layer "In13.Cu")
		(net "P5E_CPU1_PE2_RX_DN<14>")
	)
	(segment
		(start 139.501372 -226.861116)
		(end 140.283184 -230.548688)
		(width 0.14732)
		(layer "In13.Cu")
		(net "P5E_CPU1_PE2_RX_DN<14>")
	)
	(segment
		(start 125.318774 -404.618952)
		(end 123.601734 -406.335992)
		(width 0.14732)
		(layer "In13.Cu")
		(net "P5E_CPU1_PE2_RX_DN<14>")
	)
	(segment
		(start 134.478522 -220.644974)
		(end 134.49046 -220.651832)
		(width 0.0889)
		(layer "In13.Cu")
		(net "P5E_CPU1_PE2_RX_DN<14>")
	)
	(segment
		(start 141.57198 -256.677414)
		(end 141.571726 -256.677414)
		(width 0.14732)
		(layer "In13.Cu")
		(net "P5E_CPU1_PE2_RX_DN<14>")
	)
	(segment
		(start 125.488954 -417.587938)
		(end 127.066548 -423.541952)
		(width 0.14732)
		(layer "In13.Cu")
		(net "P5E_CPU1_PE2_RX_DN<14>")
	)
	(segment
		(start 138.989562 -225.203258)
		(end 138.989562 -225.211132)
		(width 0.0889)
		(layer "In13.Cu")
		(net "P5E_CPU1_PE2_RX_DN<14>")
	)
	(segment
		(start 139.459462 -226.01682)
		(end 139.459462 -226.34321)
		(width 0.0889)
		(layer "In13.Cu")
		(net "P5E_CPU1_PE2_RX_DN<14>")
	)
	(segment
		(start 135.700262 -221.133924)
		(end 135.700262 -221.141798)
		(width 0.0889)
		(layer "In13.Cu")
		(net "P5E_CPU1_PE2_RX_DN<14>")
	)
	(segment
		(start 139.90955 -247.946672)
		(end 139.53236 -248.210832)
		(width 0.14732)
		(layer "In13.Cu")
		(net "P5E_CPU1_PE2_RX_DN<14>")
	)
	(segment
		(start 125.497336 -417.054538)
		(end 125.591824 -417.4109)
		(width 0.14732)
		(layer "In13.Cu")
		(net "P5E_CPU1_PE2_RX_DN<14>")
	)
	(segment
		(start 127.066548 -434.539644)
		(end 127.23876 -434.711856)
		(width 0.14732)
		(layer "In13.Cu")
		(net "P5E_CPU1_PE2_RX_DN<14>")
	)
	(segment
		(start 140.283184 -230.548688)
		(end 141.555978 -244.340634)
		(width 0.14732)
		(layer "In13.Cu")
		(net "P5E_CPU1_PE2_RX_DN<14>")
	)
	(segment
		(start 136.827006 -223.086168)
		(end 136.837674 -223.092518)
		(width 0.0889)
		(layer "In13.Cu")
		(net "P5E_CPU1_PE2_RX_DN<14>")
	)
	(segment
		(start 141.571726 -256.677414)
		(end 142.349474 -259.488178)
		(width 0.14732)
		(layer "In13.Cu")
		(net "P5E_CPU1_PE2_RX_DN<14>")
	)
	(segment
		(start 142.349474 -259.488178)
		(end 139.542012 -309.951628)
		(width 0.14732)
		(layer "In13.Cu")
		(net "P5E_CPU1_PE2_RX_DN<14>")
	)
	(segment
		(start 136.639808 -222.750888)
		(end 136.639808 -222.776542)
		(width 0.0889)
		(layer "In13.Cu")
		(net "P5E_CPU1_PE2_RX_DN<14>")
	)
	(segment
		(start 139.542012 -309.951628)
		(end 143.896588 -327.811638)
		(width 0.14732)
		(layer "In13.Cu")
		(net "P5E_CPU1_PE2_RX_DN<14>")
	)
	(segment
		(start 125.049026 -415.928048)
		(end 125.226064 -416.030664)
		(width 0.14732)
		(layer "In13.Cu")
		(net "P5E_CPU1_PE2_RX_DN<14>")
	)
	(segment
		(start 151.821642 -345.186)
		(end 150.832058 -358.61625)
		(width 0.14732)
		(layer "In13.Cu")
		(net "P5E_CPU1_PE2_RX_DN<14>")
	)
	(arc
		(start 138.142218 -224.714054)
		(mid 138.424383 -224.638371)
		(end 138.706606 -224.7138)
		(width 0.0889)
		(layer "In13.Cu")
		(net "P5E_CPU1_PE2_RX_DN<14>")
	)
	(arc
		(start 139.187428 -225.533966)
		(mid 139.38675 -225.739735)
		(end 139.459462 -226.01682)
		(width 0.0889)
		(layer "In13.Cu")
		(net "P5E_CPU1_PE2_RX_DN<14>")
	)
	(arc
		(start 134.852918 -220.64472)
		(mid 135.135083 -220.569037)
		(end 135.417306 -220.644466)
		(width 0.0889)
		(layer "In13.Cu")
		(net "P5E_CPU1_PE2_RX_DN<14>")
	)
	(arc
		(start 133.99135 -220.607128)
		(mid 134.23925 -220.570621)
		(end 134.478522 -220.644974)
		(width 0.0889)
		(layer "In13.Cu")
		(net "P5E_CPU1_PE2_RX_DN<14>")
	)
	(arc
		(start 134.49046 -220.651832)
		(mid 134.672601 -220.694945)
		(end 134.852918 -220.64472)
		(width 0.0889)
		(layer "In13.Cu")
		(net "P5E_CPU1_PE2_RX_DN<14>")
	)
	(arc
		(start 138.989562 -225.211132)
		(mid 139.0417 -225.3939)
		(end 139.17676 -225.527616)
		(width 0.0889)
		(layer "In13.Cu")
		(net "P5E_CPU1_PE2_RX_DN<14>")
	)
	(arc
		(start 133.971538 -220.615256)
		(mid 133.981405 -220.611098)
		(end 133.99135 -220.607128)
		(width 0.0889)
		(layer "In13.Cu")
		(net "P5E_CPU1_PE2_RX_DN<14>")
	)
	(arc
		(start 135.887714 -221.458536)
		(mid 136.091692 -221.660712)
		(end 136.169908 -221.937072)
		(width 0.0889)
		(layer "In13.Cu")
		(net "P5E_CPU1_PE2_RX_DN<14>")
	)
	(arc
		(start 136.837674 -223.092518)
		(mid 137.037058 -223.298398)
		(end 137.109708 -223.575626)
		(width 0.0889)
		(layer "In13.Cu")
		(net "P5E_CPU1_PE2_RX_DN<14>")
	)
	(arc
		(start 137.579862 -224.397316)
		(mid 137.632089 -224.580234)
		(end 137.767314 -224.714054)
		(width 0.0889)
		(layer "In13.Cu")
		(net "P5E_CPU1_PE2_RX_DN<14>")
	)
	(arc
		(start 137.109708 -223.575626)
		(mid 137.15729 -223.758166)
		(end 137.287762 -223.894396)
		(width 0.0889)
		(layer "In13.Cu")
		(net "P5E_CPU1_PE2_RX_DN<14>")
	)
	(arc
		(start 136.639808 -222.776542)
		(mid 136.693613 -222.955417)
		(end 136.827006 -223.086168)
		(width 0.0889)
		(layer "In13.Cu")
		(net "P5E_CPU1_PE2_RX_DN<14>")
	)
	(arc
		(start 137.767314 -224.714054)
		(mid 137.954766 -224.76429)
		(end 138.142218 -224.714054)
		(width 0.0889)
		(layer "In13.Cu")
		(net "P5E_CPU1_PE2_RX_DN<14>")
	)
	(arc
		(start 136.169908 -221.94774)
		(mid 136.218966 -222.13283)
		(end 136.353042 -222.269558)
		(width 0.0889)
		(layer "In13.Cu")
		(net "P5E_CPU1_PE2_RX_DN<14>")
	)
	(arc
		(start 135.428228 -220.650816)
		(mid 135.627612 -220.856696)
		(end 135.700262 -221.133924)
		(width 0.0889)
		(layer "In13.Cu")
		(net "P5E_CPU1_PE2_RX_DN<14>")
	)
	(arc
		(start 137.310876 -223.908112)
		(mid 137.508052 -224.113747)
		(end 137.579862 -224.389442)
		(width 0.0889)
		(layer "In13.Cu")
		(net "P5E_CPU1_PE2_RX_DN<14>")
	)
	(arc
		(start 138.717528 -224.72015)
		(mid 138.916912 -224.92603)
		(end 138.989562 -225.203258)
		(width 0.0889)
		(layer "In13.Cu")
		(net "P5E_CPU1_PE2_RX_DN<14>")
	)
	(arc
		(start 136.357868 -222.272606)
		(mid 136.561692 -222.474703)
		(end 136.639808 -222.750888)
		(width 0.0889)
		(layer "In13.Cu")
		(net "P5E_CPU1_PE2_RX_DN<14>")
	)
	(arc
		(start 135.700262 -221.141798)
		(mid 135.752489 -221.324716)
		(end 135.887714 -221.458536)
		(width 0.0889)
		(layer "In13.Cu")
		(net "P5E_CPU1_PE2_RX_DN<14>")
	)
	(segment
		(start 133.255512 -221.669864)
		(end 133.255766 -221.66961)
		(width 0.13208)
		(layer "F.Cu")
		(net "P5E_CPU1_PE2_RX_DN<13>")
	)
	(segment
		(start 133.255766 -221.66961)
		(end 133.255766 -221.133924)
		(width 0.13208)
		(layer "F.Cu")
		(net "P5E_CPU1_PE2_RX_DN<13>")
	)
	(segment
		(start 134.382764 -219.830396)
		(end 134.397496 -219.82176)
		(width 0.0889)
		(layer "In13.Cu")
		(net "P5E_CPU1_PE2_RX_DN<13>")
	)
	(segment
		(start 128.382014 -404.618952)
		(end 126.664974 -406.335992)
		(width 0.14732)
		(layer "In13.Cu")
		(net "P5E_CPU1_PE2_RX_DN<13>")
	)
	(segment
		(start 128.382014 -400.4437)
		(end 128.382014 -404.618952)
		(width 0.14732)
		(layer "In13.Cu")
		(net "P5E_CPU1_PE2_RX_DN<13>")
	)
	(segment
		(start 126.664974 -411.00375)
		(end 127.666242 -416.368484)
		(width 0.14732)
		(layer "In13.Cu")
		(net "P5E_CPU1_PE2_RX_DN<13>")
	)
	(segment
		(start 141.62659 -254.990346)
		(end 142.621508 -256.411476)
		(width 0.14732)
		(layer "In13.Cu")
		(net "P5E_CPU1_PE2_RX_DN<13>")
	)
	(segment
		(start 127.835152 -416.484054)
		(end 127.902716 -416.846258)
		(width 0.14732)
		(layer "In13.Cu")
		(net "P5E_CPU1_PE2_RX_DN<13>")
	)
	(segment
		(start 139.641072 -224.336356)
		(end 139.737338 -224.432622)
		(width 0.0889)
		(layer "In13.Cu")
		(net "P5E_CPU1_PE2_RX_DN<13>")
	)
	(segment
		(start 133.442964 -221.458282)
		(end 133.451854 -221.453202)
		(width 0.0889)
		(layer "In13.Cu")
		(net "P5E_CPU1_PE2_RX_DN<13>")
	)
	(segment
		(start 138.228578 -223.894904)
		(end 138.237468 -223.899984)
		(width 0.0889)
		(layer "In13.Cu")
		(net "P5E_CPU1_PE2_RX_DN<13>")
	)
	(segment
		(start 140.391642 -225.38055)
		(end 140.391388 -225.38055)
		(width 0.14732)
		(layer "In13.Cu")
		(net "P5E_CPU1_PE2_RX_DN<13>")
	)
	(segment
		(start 133.443726 -220.810074)
		(end 133.442964 -220.809566)
		(width 0.0889)
		(layer "In13.Cu")
		(net "P5E_CPU1_PE2_RX_DN<13>")
	)
	(segment
		(start 128.181608 -419.128702)
		(end 129.066544 -423.871644)
		(width 0.14732)
		(layer "In13.Cu")
		(net "P5E_CPU1_PE2_RX_DN<13>")
	)
	(segment
		(start 140.550138 -251.24918)
		(end 140.598906 -252.136402)
		(width 0.14732)
		(layer "In13.Cu")
		(net "P5E_CPU1_PE2_RX_DN<13>")
	)
	(segment
		(start 137.288778 -222.267018)
		(end 137.297668 -222.272098)
		(width 0.0889)
		(layer "In13.Cu")
		(net "P5E_CPU1_PE2_RX_DN<13>")
	)
	(segment
		(start 150.85695 -334.156812)
		(end 152.806908 -345.215718)
		(width 0.14732)
		(layer "In13.Cu")
		(net "P5E_CPU1_PE2_RX_DN<13>")
	)
	(segment
		(start 142.55115 -244.380512)
		(end 141.192758 -248.550684)
		(width 0.14732)
		(layer "In13.Cu")
		(net "P5E_CPU1_PE2_RX_DN<13>")
	)
	(segment
		(start 140.391388 -225.38055)
		(end 140.65885 -225.989134)
		(width 0.14732)
		(layer "In13.Cu")
		(net "P5E_CPU1_PE2_RX_DN<13>")
	)
	(segment
		(start 128.668018 -399.452084)
		(end 128.382014 -400.4437)
		(width 0.14732)
		(layer "In13.Cu")
		(net "P5E_CPU1_PE2_RX_DN<13>")
	)
	(segment
		(start 129.066544 -423.871644)
		(end 129.066544 -433.514754)
		(width 0.14732)
		(layer "In13.Cu")
		(net "P5E_CPU1_PE2_RX_DN<13>")
	)
	(segment
		(start 129.066544 -433.514754)
		(end 129.271268 -433.719478)
		(width 0.14732)
		(layer "In13.Cu")
		(net "P5E_CPU1_PE2_RX_DN<13>")
	)
	(segment
		(start 139.81176 -224.448116)
		(end 140.114782 -224.750884)
		(width 0.14732)
		(layer "In13.Cu")
		(net "P5E_CPU1_PE2_RX_DN<13>")
	)
	(segment
		(start 144.790668 -327.387712)
		(end 150.85695 -334.156812)
		(width 0.14732)
		(layer "In13.Cu")
		(net "P5E_CPU1_PE2_RX_DN<13>")
	)
	(segment
		(start 140.553186 -309.736998)
		(end 144.790668 -327.387712)
		(width 0.14732)
		(layer "In13.Cu")
		(net "P5E_CPU1_PE2_RX_DN<13>")
	)
	(segment
		(start 140.598906 -252.136402)
		(end 140.917676 -253.23165)
		(width 0.14732)
		(layer "In13.Cu")
		(net "P5E_CPU1_PE2_RX_DN<13>")
	)
	(segment
		(start 136.827768 -221.458282)
		(end 136.833864 -221.461838)
		(width 0.0889)
		(layer "In13.Cu")
		(net "P5E_CPU1_PE2_RX_DN<13>")
	)
	(segment
		(start 136.818878 -221.453202)
		(end 136.827768 -221.458282)
		(width 0.0889)
		(layer "In13.Cu")
		(net "P5E_CPU1_PE2_RX_DN<13>")
	)
	(segment
		(start 138.050016 -223.557084)
		(end 138.050016 -223.575626)
		(width 0.0889)
		(layer "In13.Cu")
		(net "P5E_CPU1_PE2_RX_DN<13>")
	)
	(segment
		(start 129.582926 -433.719478)
		(end 129.750058 -433.552346)
		(width 0.14732)
		(layer "In13.Cu")
		(net "P5E_CPU1_PE2_RX_DN<13>")
	)
	(segment
		(start 139.294108 -223.989138)
		(end 139.641072 -224.336356)
		(width 0.0889)
		(layer "In13.Cu")
		(net "P5E_CPU1_PE2_RX_DN<13>")
	)
	(segment
		(start 128.229868 -418.597588)
		(end 128.297432 -418.959792)
		(width 0.14732)
		(layer "In13.Cu")
		(net "P5E_CPU1_PE2_RX_DN<13>")
	)
	(segment
		(start 140.694918 -249.262138)
		(end 140.500608 -250.361196)
		(width 0.14732)
		(layer "In13.Cu")
		(net "P5E_CPU1_PE2_RX_DN<13>")
	)
	(segment
		(start 141.192758 -248.550684)
		(end 140.694918 -249.262138)
		(width 0.14732)
		(layer "In13.Cu")
		(net "P5E_CPU1_PE2_RX_DN<13>")
	)
	(segment
		(start 128.02362 -417.492942)
		(end 128.091184 -417.855146)
		(width 0.14732)
		(layer "In13.Cu")
		(net "P5E_CPU1_PE2_RX_DN<13>")
	)
	(segment
		(start 128.297432 -418.959792)
		(end 128.181608 -419.128702)
		(width 0.14732)
		(layer "In13.Cu")
		(net "P5E_CPU1_PE2_RX_DN<13>")
	)
	(segment
		(start 133.099302 -221.404942)
		(end 133.120384 -221.48292)
		(width 0.0889)
		(layer "In13.Cu")
		(net "P5E_CPU1_PE2_RX_DN<13>")
	)
	(segment
		(start 133.160516 -220.338396)
		(end 133.160516 -220.309948)
		(width 0.0889)
		(layer "In13.Cu")
		(net "P5E_CPU1_PE2_RX_DN<13>")
	)
	(segment
		(start 133.451854 -220.814646)
		(end 133.443726 -220.810074)
		(width 0.0889)
		(layer "In13.Cu")
		(net "P5E_CPU1_PE2_RX_DN<13>")
	)
	(segment
		(start 139.737338 -224.432622)
		(end 139.796266 -224.432622)
		(width 0.0889)
		(layer "In13.Cu")
		(net "P5E_CPU1_PE2_RX_DN<13>")
	)
	(segment
		(start 136.640316 -221.115382)
		(end 136.640316 -221.133924)
		(width 0.0889)
		(layer "In13.Cu")
		(net "P5E_CPU1_PE2_RX_DN<13>")
	)
	(segment
		(start 128.091184 -417.855146)
		(end 127.97536 -418.024056)
		(width 0.14732)
		(layer "In13.Cu")
		(net "P5E_CPU1_PE2_RX_DN<13>")
	)
	(segment
		(start 142.621508 -256.411476)
		(end 143.375888 -259.35178)
		(width 0.14732)
		(layer "In13.Cu")
		(net "P5E_CPU1_PE2_RX_DN<13>")
	)
	(segment
		(start 140.500608 -250.361196)
		(end 140.549884 -251.24918)
		(width 0.14732)
		(layer "In13.Cu")
		(net "P5E_CPU1_PE2_RX_DN<13>")
	)
	(segment
		(start 127.854456 -417.377118)
		(end 128.02362 -417.492942)
		(width 0.14732)
		(layer "In13.Cu")
		(net "P5E_CPU1_PE2_RX_DN<13>")
	)
	(segment
		(start 127.97536 -418.024056)
		(end 128.060704 -418.481764)
		(width 0.14732)
		(layer "In13.Cu")
		(net "P5E_CPU1_PE2_RX_DN<13>")
	)
	(segment
		(start 152.806908 -345.215718)
		(end 151.813514 -358.72928)
		(width 0.14732)
		(layer "In13.Cu")
		(net "P5E_CPU1_PE2_RX_DN<13>")
	)
	(segment
		(start 141.557502 -230.312722)
		(end 142.55115 -244.380512)
		(width 0.14732)
		(layer "In13.Cu")
		(net "P5E_CPU1_PE2_RX_DN<13>")
	)
	(segment
		(start 127.902716 -416.846258)
		(end 127.787146 -417.015168)
		(width 0.14732)
		(layer "In13.Cu")
		(net "P5E_CPU1_PE2_RX_DN<13>")
	)
	(segment
		(start 127.666242 -416.368484)
		(end 127.835152 -416.484054)
		(width 0.14732)
		(layer "In13.Cu")
		(net "P5E_CPU1_PE2_RX_DN<13>")
	)
	(segment
		(start 137.758678 -223.080834)
		(end 137.767568 -223.085914)
		(width 0.0889)
		(layer "In13.Cu")
		(net "P5E_CPU1_PE2_RX_DN<13>")
	)
	(segment
		(start 133.255766 -221.133924)
		(end 133.099302 -221.404942)
		(width 0.0889)
		(layer "In13.Cu")
		(net "P5E_CPU1_PE2_RX_DN<13>")
	)
	(segment
		(start 140.917676 -253.23165)
		(end 141.02969 -253.549912)
		(width 0.14732)
		(layer "In13.Cu")
		(net "P5E_CPU1_PE2_RX_DN<13>")
	)
	(segment
		(start 151.813514 -358.72928)
		(end 147.14855 -370.075968)
		(width 0.14732)
		(layer "In13.Cu")
		(net "P5E_CPU1_PE2_RX_DN<13>")
	)
	(segment
		(start 141.02969 -253.549912)
		(end 141.62659 -254.990346)
		(width 0.14732)
		(layer "In13.Cu")
		(net "P5E_CPU1_PE2_RX_DN<13>")
	)
	(segment
		(start 127.787146 -417.015168)
		(end 127.854456 -417.377118)
		(width 0.14732)
		(layer "In13.Cu")
		(net "P5E_CPU1_PE2_RX_DN<13>")
	)
	(segment
		(start 129.271268 -433.719478)
		(end 129.582926 -433.719478)
		(width 0.14732)
		(layer "In13.Cu")
		(net "P5E_CPU1_PE2_RX_DN<13>")
	)
	(segment
		(start 140.114782 -224.750884)
		(end 140.391642 -225.38055)
		(width 0.14732)
		(layer "In13.Cu")
		(net "P5E_CPU1_PE2_RX_DN<13>")
	)
	(segment
		(start 128.060704 -418.481764)
		(end 128.229868 -418.597588)
		(width 0.14732)
		(layer "In13.Cu")
		(net "P5E_CPU1_PE2_RX_DN<13>")
	)
	(segment
		(start 147.14855 -370.075968)
		(end 128.668018 -399.452084)
		(width 0.14732)
		(layer "In13.Cu")
		(net "P5E_CPU1_PE2_RX_DN<13>")
	)
	(segment
		(start 140.65885 -225.989134)
		(end 141.557502 -230.312722)
		(width 0.14732)
		(layer "In13.Cu")
		(net "P5E_CPU1_PE2_RX_DN<13>")
	)
	(segment
		(start 139.796266 -224.432622)
		(end 139.81176 -224.448116)
		(width 0.0889)
		(layer "In13.Cu")
		(net "P5E_CPU1_PE2_RX_DN<13>")
	)
	(segment
		(start 129.750058 -433.552346)
		(end 129.750058 -433.289964)
		(width 0.14732)
		(layer "In13.Cu")
		(net "P5E_CPU1_PE2_RX_DN<13>")
	)
	(segment
		(start 140.549884 -251.24918)
		(end 140.550138 -251.24918)
		(width 0.14732)
		(layer "In13.Cu")
		(net "P5E_CPU1_PE2_RX_DN<13>")
	)
	(segment
		(start 136.170416 -220.309948)
		(end 136.170416 -220.319854)
		(width 0.0889)
		(layer "In13.Cu")
		(net "P5E_CPU1_PE2_RX_DN<13>")
	)
	(segment
		(start 136.348978 -220.639132)
		(end 136.357868 -220.644212)
		(width 0.0889)
		(layer "In13.Cu")
		(net "P5E_CPU1_PE2_RX_DN<13>")
	)
	(segment
		(start 137.297668 -222.272098)
		(end 137.303764 -222.275654)
		(width 0.0889)
		(layer "In13.Cu")
		(net "P5E_CPU1_PE2_RX_DN<13>")
	)
	(segment
		(start 143.375888 -259.35178)
		(end 140.553186 -309.736998)
		(width 0.14732)
		(layer "In13.Cu")
		(net "P5E_CPU1_PE2_RX_DN<13>")
	)
	(segment
		(start 126.664974 -406.335992)
		(end 126.664974 -411.00375)
		(width 0.14732)
		(layer "In13.Cu")
		(net "P5E_CPU1_PE2_RX_DN<13>")
	)
	(arc
		(start 135.322564 -219.830396)
		(mid 135.605266 -219.75462)
		(end 135.887968 -219.830396)
		(width 0.0889)
		(layer "In13.Cu")
		(net "P5E_CPU1_PE2_RX_DN<13>")
	)
	(arc
		(start 133.120384 -221.48292)
		(mid 133.28448 -221.507267)
		(end 133.442964 -221.458282)
		(width 0.0889)
		(layer "In13.Cu")
		(net "P5E_CPU1_PE2_RX_DN<13>")
	)
	(arc
		(start 136.170416 -220.319854)
		(mid 136.218095 -220.502754)
		(end 136.348978 -220.639132)
		(width 0.0889)
		(layer "In13.Cu")
		(net "P5E_CPU1_PE2_RX_DN<13>")
	)
	(arc
		(start 137.767568 -223.085914)
		(mid 137.969854 -223.284895)
		(end 138.050016 -223.557084)
		(width 0.0889)
		(layer "In13.Cu")
		(net "P5E_CPU1_PE2_RX_DN<13>")
	)
	(arc
		(start 139.177268 -223.899984)
		(mid 139.210004 -223.920355)
		(end 139.241276 -223.94291)
		(width 0.0889)
		(layer "In13.Cu")
		(net "P5E_CPU1_PE2_RX_DN<13>")
	)
	(arc
		(start 134.397496 -219.82176)
		(mid 134.673971 -219.75444)
		(end 134.948168 -219.830396)
		(width 0.0889)
		(layer "In13.Cu")
		(net "P5E_CPU1_PE2_RX_DN<13>")
	)
	(arc
		(start 136.833864 -221.461838)
		(mid 137.036277 -221.668251)
		(end 137.110216 -221.94774)
		(width 0.0889)
		(layer "In13.Cu")
		(net "P5E_CPU1_PE2_RX_DN<13>")
	)
	(arc
		(start 135.887968 -219.830396)
		(mid 136.092303 -220.033001)
		(end 136.170416 -220.309948)
		(width 0.0889)
		(layer "In13.Cu")
		(net "P5E_CPU1_PE2_RX_DN<13>")
	)
	(arc
		(start 133.442964 -220.809566)
		(mid 133.240678 -220.610585)
		(end 133.160516 -220.338396)
		(width 0.0889)
		(layer "In13.Cu")
		(net "P5E_CPU1_PE2_RX_DN<13>")
	)
	(arc
		(start 137.580116 -222.761556)
		(mid 137.627795 -222.944456)
		(end 137.758678 -223.080834)
		(width 0.0889)
		(layer "In13.Cu")
		(net "P5E_CPU1_PE2_RX_DN<13>")
	)
	(arc
		(start 138.611864 -223.899984)
		(mid 138.894566 -223.824208)
		(end 139.177268 -223.899984)
		(width 0.0889)
		(layer "In13.Cu")
		(net "P5E_CPU1_PE2_RX_DN<13>")
	)
	(arc
		(start 133.630416 -221.140528)
		(mid 133.630406 -221.131128)
		(end 133.630162 -221.121732)
		(width 0.0889)
		(layer "In13.Cu")
		(net "P5E_CPU1_PE2_RX_DN<13>")
	)
	(arc
		(start 139.241276 -223.94291)
		(mid 139.268412 -223.965202)
		(end 139.294108 -223.989138)
		(width 0.0889)
		(layer "In13.Cu")
		(net "P5E_CPU1_PE2_RX_DN<13>")
	)
	(arc
		(start 138.237468 -223.899984)
		(mid 138.424666 -223.950127)
		(end 138.611864 -223.899984)
		(width 0.0889)
		(layer "In13.Cu")
		(net "P5E_CPU1_PE2_RX_DN<13>")
	)
	(arc
		(start 137.110216 -221.94774)
		(mid 137.157895 -222.13064)
		(end 137.288778 -222.267018)
		(width 0.0889)
		(layer "In13.Cu")
		(net "P5E_CPU1_PE2_RX_DN<13>")
	)
	(arc
		(start 134.948168 -219.830396)
		(mid 135.135366 -219.880539)
		(end 135.322564 -219.830396)
		(width 0.0889)
		(layer "In13.Cu")
		(net "P5E_CPU1_PE2_RX_DN<13>")
	)
	(arc
		(start 138.050016 -223.575626)
		(mid 138.097695 -223.758526)
		(end 138.228578 -223.894904)
		(width 0.0889)
		(layer "In13.Cu")
		(net "P5E_CPU1_PE2_RX_DN<13>")
	)
	(arc
		(start 136.357868 -220.644212)
		(mid 136.560154 -220.843193)
		(end 136.640316 -221.115382)
		(width 0.0889)
		(layer "In13.Cu")
		(net "P5E_CPU1_PE2_RX_DN<13>")
	)
	(arc
		(start 133.451854 -221.453202)
		(mid 133.581143 -221.319716)
		(end 133.630416 -221.140528)
		(width 0.0889)
		(layer "In13.Cu")
		(net "P5E_CPU1_PE2_RX_DN<13>")
	)
	(arc
		(start 133.442964 -219.830396)
		(mid 133.725666 -219.75462)
		(end 134.008368 -219.830396)
		(width 0.0889)
		(layer "In13.Cu")
		(net "P5E_CPU1_PE2_RX_DN<13>")
	)
	(arc
		(start 134.008368 -219.830396)
		(mid 134.195566 -219.880539)
		(end 134.382764 -219.830396)
		(width 0.0889)
		(layer "In13.Cu")
		(net "P5E_CPU1_PE2_RX_DN<13>")
	)
	(arc
		(start 133.630162 -221.121732)
		(mid 133.579669 -220.945754)
		(end 133.451854 -220.814646)
		(width 0.0889)
		(layer "In13.Cu")
		(net "P5E_CPU1_PE2_RX_DN<13>")
	)
	(arc
		(start 137.303764 -222.275654)
		(mid 137.506177 -222.482067)
		(end 137.580116 -222.761556)
		(width 0.0889)
		(layer "In13.Cu")
		(net "P5E_CPU1_PE2_RX_DN<13>")
	)
	(arc
		(start 133.160516 -220.309948)
		(mid 133.238627 -220.032999)
		(end 133.442964 -219.830396)
		(width 0.0889)
		(layer "In13.Cu")
		(net "P5E_CPU1_PE2_RX_DN<13>")
	)
	(arc
		(start 136.640316 -221.133924)
		(mid 136.687995 -221.316824)
		(end 136.818878 -221.453202)
		(width 0.0889)
		(layer "In13.Cu")
		(net "P5E_CPU1_PE2_RX_DN<13>")
	)
	(segment
		(start 131.846066 -220.320108)
		(end 131.845812 -220.319854)
		(width 0.13208)
		(layer "F.Cu")
		(net "P5E_CPU1_PE2_RX_DN<12>")
	)
	(segment
		(start 131.846066 -220.855794)
		(end 131.846066 -220.320108)
		(width 0.13208)
		(layer "F.Cu")
		(net "P5E_CPU1_PE2_RX_DN<12>")
	)
	(segment
		(start 141.594332 -225.77933)
		(end 142.492222 -230.137716)
		(width 0.14732)
		(layer "In13.Cu")
		(net "P5E_CPU1_PE2_RX_DN<12>")
	)
	(segment
		(start 136.828276 -219.830904)
		(end 136.83361 -219.833952)
		(width 0.0889)
		(layer "In13.Cu")
		(net "P5E_CPU1_PE2_RX_DN<12>")
	)
	(segment
		(start 138.050016 -221.937834)
		(end 138.050016 -221.94774)
		(width 0.0889)
		(layer "In13.Cu")
		(net "P5E_CPU1_PE2_RX_DN<12>")
	)
	(segment
		(start 141.752066 -249.374152)
		(end 141.55928 -250.46559)
		(width 0.14732)
		(layer "In13.Cu")
		(net "P5E_CPU1_PE2_RX_DN<12>")
	)
	(segment
		(start 131.06654 -423.63009)
		(end 131.06654 -434.470556)
		(width 0.14732)
		(layer "In13.Cu")
		(net "P5E_CPU1_PE2_RX_DN<12>")
	)
	(segment
		(start 143.512032 -244.486938)
		(end 142.065502 -248.926096)
		(width 0.14732)
		(layer "In13.Cu")
		(net "P5E_CPU1_PE2_RX_DN<12>")
	)
	(segment
		(start 129.728214 -406.335992)
		(end 129.728214 -411.247082)
		(width 0.14732)
		(layer "In13.Cu")
		(net "P5E_CPU1_PE2_RX_DN<12>")
	)
	(segment
		(start 130.638296 -418.319204)
		(end 130.509772 -418.478716)
		(width 0.14732)
		(layer "In13.Cu")
		(net "P5E_CPU1_PE2_RX_DN<12>")
	)
	(segment
		(start 130.509772 -418.478716)
		(end 131.06654 -423.63009)
		(width 0.14732)
		(layer "In13.Cu")
		(net "P5E_CPU1_PE2_RX_DN<12>")
	)
	(segment
		(start 141.589506 -225.755454)
		(end 141.594586 -225.77933)
		(width 0.14732)
		(layer "In13.Cu")
		(net "P5E_CPU1_PE2_RX_DN<12>")
	)
	(segment
		(start 132.499354 -219.832682)
		(end 132.503164 -219.830396)
		(width 0.0889)
		(layer "In13.Cu")
		(net "P5E_CPU1_PE2_RX_DN<12>")
	)
	(segment
		(start 150.448518 -364.772956)
		(end 150.448772 -364.772956)
		(width 0.14732)
		(layer "In13.Cu")
		(net "P5E_CPU1_PE2_RX_DN<12>")
	)
	(segment
		(start 133.528054 -219.010484)
		(end 133.538468 -219.01658)
		(width 0.0889)
		(layer "In13.Cu")
		(net "P5E_CPU1_PE2_RX_DN<12>")
	)
	(segment
		(start 140.052298 -223.288606)
		(end 140.111226 -223.288606)
		(width 0.0889)
		(layer "In13.Cu")
		(net "P5E_CPU1_PE2_RX_DN<12>")
	)
	(segment
		(start 140.111226 -223.288606)
		(end 140.12672 -223.3041)
		(width 0.0889)
		(layer "In13.Cu")
		(net "P5E_CPU1_PE2_RX_DN<12>")
	)
	(segment
		(start 150.448772 -364.772956)
		(end 148.12772 -370.229384)
		(width 0.14732)
		(layer "In13.Cu")
		(net "P5E_CPU1_PE2_RX_DN<12>")
	)
	(segment
		(start 137.288778 -220.639132)
		(end 137.297668 -220.644212)
		(width 0.0889)
		(layer "In13.Cu")
		(net "P5E_CPU1_PE2_RX_DN<12>")
	)
	(segment
		(start 143.58366 -256.164588)
		(end 144.355058 -259.261102)
		(width 0.14732)
		(layer "In13.Cu")
		(net "P5E_CPU1_PE2_RX_DN<12>")
	)
	(segment
		(start 142.065502 -248.926096)
		(end 141.752066 -249.374152)
		(width 0.14732)
		(layer "In13.Cu")
		(net "P5E_CPU1_PE2_RX_DN<12>")
	)
	(segment
		(start 136.827514 -219.830396)
		(end 136.828276 -219.830904)
		(width 0.0889)
		(layer "In13.Cu")
		(net "P5E_CPU1_PE2_RX_DN<12>")
	)
	(segment
		(start 148.12772 -370.229384)
		(end 131.445254 -400.17192)
		(width 0.14732)
		(layer "In13.Cu")
		(net "P5E_CPU1_PE2_RX_DN<12>")
	)
	(segment
		(start 141.495272 -309.61965)
		(end 145.601436 -326.766936)
		(width 0.14732)
		(layer "In13.Cu")
		(net "P5E_CPU1_PE2_RX_DN<12>")
	)
	(segment
		(start 142.492222 -230.137716)
		(end 143.512032 -244.486938)
		(width 0.14732)
		(layer "In13.Cu")
		(net "P5E_CPU1_PE2_RX_DN<12>")
	)
	(segment
		(start 132.690616 -219.506038)
		(end 132.690616 -219.490544)
		(width 0.0889)
		(layer "In13.Cu")
		(net "P5E_CPU1_PE2_RX_DN<12>")
	)
	(segment
		(start 132.503164 -219.830396)
		(end 132.512054 -219.825316)
		(width 0.0889)
		(layer "In13.Cu")
		(net "P5E_CPU1_PE2_RX_DN<12>")
	)
	(segment
		(start 138.228578 -222.267018)
		(end 138.237468 -222.272098)
		(width 0.0889)
		(layer "In13.Cu")
		(net "P5E_CPU1_PE2_RX_DN<12>")
	)
	(segment
		(start 131.845812 -220.319854)
		(end 132.002276 -220.590872)
		(width 0.0889)
		(layer "In13.Cu")
		(net "P5E_CPU1_PE2_RX_DN<12>")
	)
	(segment
		(start 130.598672 -417.952682)
		(end 130.638296 -418.319204)
		(width 0.14732)
		(layer "In13.Cu")
		(net "P5E_CPU1_PE2_RX_DN<12>")
	)
	(segment
		(start 138.894566 -223.136714)
		(end 139.900406 -223.136714)
		(width 0.0889)
		(layer "In13.Cu")
		(net "P5E_CPU1_PE2_RX_DN<12>")
	)
	(segment
		(start 137.758678 -221.453202)
		(end 137.767568 -221.458282)
		(width 0.0889)
		(layer "In13.Cu")
		(net "P5E_CPU1_PE2_RX_DN<12>")
	)
	(segment
		(start 137.580116 -221.115382)
		(end 137.580116 -221.133924)
		(width 0.0889)
		(layer "In13.Cu")
		(net "P5E_CPU1_PE2_RX_DN<12>")
	)
	(segment
		(start 141.594586 -225.77933)
		(end 141.594332 -225.77933)
		(width 0.14732)
		(layer "In13.Cu")
		(net "P5E_CPU1_PE2_RX_DN<12>")
	)
	(segment
		(start 140.12672 -223.3041)
		(end 140.937996 -224.115122)
		(width 0.14732)
		(layer "In13.Cu")
		(net "P5E_CPU1_PE2_RX_DN<12>")
	)
	(segment
		(start 136.640316 -219.496132)
		(end 136.640316 -219.514674)
		(width 0.0889)
		(layer "In13.Cu")
		(net "P5E_CPU1_PE2_RX_DN<12>")
	)
	(segment
		(start 131.33832 -434.742336)
		(end 131.644898 -434.742336)
		(width 0.14732)
		(layer "In13.Cu")
		(net "P5E_CPU1_PE2_RX_DN<12>")
	)
	(segment
		(start 141.55928 -250.46559)
		(end 141.55928 -252.098048)
		(width 0.14732)
		(layer "In13.Cu")
		(net "P5E_CPU1_PE2_RX_DN<12>")
	)
	(segment
		(start 145.601436 -326.766936)
		(end 151.71674 -333.67853)
		(width 0.14732)
		(layer "In13.Cu")
		(net "P5E_CPU1_PE2_RX_DN<12>")
	)
	(segment
		(start 138.519916 -222.75165)
		(end 138.519916 -222.770192)
		(width 0.0889)
		(layer "In13.Cu")
		(net "P5E_CPU1_PE2_RX_DN<12>")
	)
	(segment
		(start 153.782522 -345.391232)
		(end 152.781508 -359.28808)
		(width 0.14732)
		(layer "In13.Cu")
		(net "P5E_CPU1_PE2_RX_DN<12>")
	)
	(segment
		(start 131.06654 -434.470556)
		(end 131.33832 -434.742336)
		(width 0.14732)
		(layer "In13.Cu")
		(net "P5E_CPU1_PE2_RX_DN<12>")
	)
	(segment
		(start 142.450312 -254.545338)
		(end 143.58366 -256.164588)
		(width 0.14732)
		(layer "In13.Cu")
		(net "P5E_CPU1_PE2_RX_DN<12>")
	)
	(segment
		(start 141.889734 -253.193042)
		(end 142.450312 -254.545338)
		(width 0.14732)
		(layer "In13.Cu")
		(net "P5E_CPU1_PE2_RX_DN<12>")
	)
	(segment
		(start 130.43916 -417.824666)
		(end 130.598672 -417.952682)
		(width 0.14732)
		(layer "In13.Cu")
		(net "P5E_CPU1_PE2_RX_DN<12>")
	)
	(segment
		(start 141.823948 -253.00559)
		(end 141.889734 -253.193042)
		(width 0.14732)
		(layer "In13.Cu")
		(net "P5E_CPU1_PE2_RX_DN<12>")
	)
	(segment
		(start 139.900406 -223.136714)
		(end 140.052298 -223.288606)
		(width 0.0889)
		(layer "In13.Cu")
		(net "P5E_CPU1_PE2_RX_DN<12>")
	)
	(segment
		(start 131.644898 -434.742336)
		(end 131.750054 -434.63718)
		(width 0.14732)
		(layer "In13.Cu")
		(net "P5E_CPU1_PE2_RX_DN<12>")
	)
	(segment
		(start 144.355058 -259.261102)
		(end 141.495272 -309.61965)
		(width 0.14732)
		(layer "In13.Cu")
		(net "P5E_CPU1_PE2_RX_DN<12>")
	)
	(segment
		(start 140.937996 -224.115122)
		(end 141.589506 -225.755454)
		(width 0.14732)
		(layer "In13.Cu")
		(net "P5E_CPU1_PE2_RX_DN<12>")
	)
	(segment
		(start 131.445254 -400.17192)
		(end 131.445254 -404.618952)
		(width 0.14732)
		(layer "In13.Cu")
		(net "P5E_CPU1_PE2_RX_DN<12>")
	)
	(segment
		(start 152.781508 -359.28808)
		(end 150.448518 -364.772956)
		(width 0.14732)
		(layer "In13.Cu")
		(net "P5E_CPU1_PE2_RX_DN<12>")
	)
	(segment
		(start 132.002276 -220.590872)
		(end 132.080508 -220.6117)
		(width 0.0889)
		(layer "In13.Cu")
		(net "P5E_CPU1_PE2_RX_DN<12>")
	)
	(segment
		(start 131.445254 -404.618952)
		(end 129.728214 -406.335992)
		(width 0.14732)
		(layer "In13.Cu")
		(net "P5E_CPU1_PE2_RX_DN<12>")
	)
	(segment
		(start 131.750054 -434.63718)
		(end 131.750054 -434.289962)
		(width 0.14732)
		(layer "In13.Cu")
		(net "P5E_CPU1_PE2_RX_DN<12>")
	)
	(segment
		(start 141.55928 -252.098048)
		(end 141.823948 -253.00559)
		(width 0.14732)
		(layer "In13.Cu")
		(net "P5E_CPU1_PE2_RX_DN<12>")
	)
	(segment
		(start 132.490972 -219.837508)
		(end 132.499354 -219.832682)
		(width 0.0889)
		(layer "In13.Cu")
		(net "P5E_CPU1_PE2_RX_DN<12>")
	)
	(segment
		(start 129.728214 -411.247082)
		(end 130.43916 -417.824666)
		(width 0.14732)
		(layer "In13.Cu")
		(net "P5E_CPU1_PE2_RX_DN<12>")
	)
	(segment
		(start 151.71674 -333.67853)
		(end 153.782522 -345.391232)
		(width 0.14732)
		(layer "In13.Cu")
		(net "P5E_CPU1_PE2_RX_DN<12>")
	)
	(arc
		(start 132.97281 -219.01658)
		(mid 133.249623 -218.94071)
		(end 133.528054 -219.010484)
		(width 0.0889)
		(layer "In13.Cu")
		(net "P5E_CPU1_PE2_RX_DN<12>")
	)
	(arc
		(start 137.767568 -221.458282)
		(mid 137.971903 -221.660887)
		(end 138.050016 -221.937834)
		(width 0.0889)
		(layer "In13.Cu")
		(net "P5E_CPU1_PE2_RX_DN<12>")
	)
	(arc
		(start 135.792464 -219.01658)
		(mid 136.075166 -218.940804)
		(end 136.357868 -219.01658)
		(width 0.0889)
		(layer "In13.Cu")
		(net "P5E_CPU1_PE2_RX_DN<12>")
	)
	(arc
		(start 137.297668 -220.644212)
		(mid 137.499954 -220.843193)
		(end 137.580116 -221.115382)
		(width 0.0889)
		(layer "In13.Cu")
		(net "P5E_CPU1_PE2_RX_DN<12>")
	)
	(arc
		(start 136.83361 -219.833952)
		(mid 137.036197 -220.040303)
		(end 137.110216 -220.319854)
		(width 0.0889)
		(layer "In13.Cu")
		(net "P5E_CPU1_PE2_RX_DN<12>")
	)
	(arc
		(start 138.519916 -222.770192)
		(mid 138.572186 -222.952557)
		(end 138.707114 -223.085914)
		(width 0.0889)
		(layer "In13.Cu")
		(net "P5E_CPU1_PE2_RX_DN<12>")
	)
	(arc
		(start 136.640316 -219.514674)
		(mid 136.692586 -219.697039)
		(end 136.827514 -219.830396)
		(width 0.0889)
		(layer "In13.Cu")
		(net "P5E_CPU1_PE2_RX_DN<12>")
	)
	(arc
		(start 133.538468 -219.01658)
		(mid 133.725666 -219.066723)
		(end 133.912864 -219.01658)
		(width 0.0889)
		(layer "In13.Cu")
		(net "P5E_CPU1_PE2_RX_DN<12>")
	)
	(arc
		(start 134.852664 -219.01658)
		(mid 135.135366 -218.940804)
		(end 135.418068 -219.01658)
		(width 0.0889)
		(layer "In13.Cu")
		(net "P5E_CPU1_PE2_RX_DN<12>")
	)
	(arc
		(start 132.690616 -219.490544)
		(mid 132.769986 -219.21681)
		(end 132.97281 -219.01658)
		(width 0.0889)
		(layer "In13.Cu")
		(net "P5E_CPU1_PE2_RX_DN<12>")
	)
	(arc
		(start 132.080508 -220.6117)
		(mid 132.183653 -220.481675)
		(end 132.220462 -220.319854)
		(width 0.0889)
		(layer "In13.Cu")
		(net "P5E_CPU1_PE2_RX_DN<12>")
	)
	(arc
		(start 138.050016 -221.94774)
		(mid 138.097695 -222.13064)
		(end 138.228578 -222.267018)
		(width 0.0889)
		(layer "In13.Cu")
		(net "P5E_CPU1_PE2_RX_DN<12>")
	)
	(arc
		(start 138.707114 -223.085914)
		(mid 138.797493 -223.123669)
		(end 138.894566 -223.136714)
		(width 0.0889)
		(layer "In13.Cu")
		(net "P5E_CPU1_PE2_RX_DN<12>")
	)
	(arc
		(start 136.357868 -219.01658)
		(mid 136.562203 -219.219185)
		(end 136.640316 -219.496132)
		(width 0.0889)
		(layer "In13.Cu")
		(net "P5E_CPU1_PE2_RX_DN<12>")
	)
	(arc
		(start 132.512054 -219.825316)
		(mid 132.642968 -219.688956)
		(end 132.690616 -219.506038)
		(width 0.0889)
		(layer "In13.Cu")
		(net "P5E_CPU1_PE2_RX_DN<12>")
	)
	(arc
		(start 133.912864 -219.01658)
		(mid 134.195566 -218.940804)
		(end 134.478268 -219.01658)
		(width 0.0889)
		(layer "In13.Cu")
		(net "P5E_CPU1_PE2_RX_DN<12>")
	)
	(arc
		(start 132.220462 -220.319854)
		(mid 132.292697 -220.04333)
		(end 132.490972 -219.837508)
		(width 0.0889)
		(layer "In13.Cu")
		(net "P5E_CPU1_PE2_RX_DN<12>")
	)
	(arc
		(start 137.580116 -221.133924)
		(mid 137.627795 -221.316824)
		(end 137.758678 -221.453202)
		(width 0.0889)
		(layer "In13.Cu")
		(net "P5E_CPU1_PE2_RX_DN<12>")
	)
	(arc
		(start 135.418068 -219.01658)
		(mid 135.605266 -219.066723)
		(end 135.792464 -219.01658)
		(width 0.0889)
		(layer "In13.Cu")
		(net "P5E_CPU1_PE2_RX_DN<12>")
	)
	(arc
		(start 138.237468 -222.272098)
		(mid 138.441803 -222.474703)
		(end 138.519916 -222.75165)
		(width 0.0889)
		(layer "In13.Cu")
		(net "P5E_CPU1_PE2_RX_DN<12>")
	)
	(arc
		(start 137.110216 -220.319854)
		(mid 137.157895 -220.502754)
		(end 137.288778 -220.639132)
		(width 0.0889)
		(layer "In13.Cu")
		(net "P5E_CPU1_PE2_RX_DN<12>")
	)
	(arc
		(start 134.478268 -219.01658)
		(mid 134.665466 -219.066723)
		(end 134.852664 -219.01658)
		(width 0.0889)
		(layer "In13.Cu")
		(net "P5E_CPU1_PE2_RX_DN<12>")
	)
	(segment
		(start 131.375912 -221.669864)
		(end 131.376166 -221.66961)
		(width 0.13208)
		(layer "F.Cu")
		(net "P5E_CPU1_PE2_RX_DN<11>")
	)
	(segment
		(start 131.376166 -221.66961)
		(end 131.376166 -221.133924)
		(width 0.13208)
		(layer "F.Cu")
		(net "P5E_CPU1_PE2_RX_DN<11>")
	)
	(segment
		(start 133.190996 -433.719478)
		(end 133.582918 -433.719478)
		(width 0.14732)
		(layer "In13.Cu")
		(net "P5E_CPU1_PE2_RX_DN<11>")
	)
	(segment
		(start 134.508494 -400.073622)
		(end 134.508494 -404.618952)
		(width 0.14732)
		(layer "In13.Cu")
		(net "P5E_CPU1_PE2_RX_DN<11>")
	)
	(segment
		(start 131.563364 -221.458282)
		(end 131.564888 -221.45752)
		(width 0.0889)
		(layer "In13.Cu")
		(net "P5E_CPU1_PE2_RX_DN<11>")
	)
	(segment
		(start 132.497068 -218.20632)
		(end 132.512054 -218.197684)
		(width 0.0889)
		(layer "In13.Cu")
		(net "P5E_CPU1_PE2_RX_DN<11>")
	)
	(segment
		(start 131.219702 -221.404942)
		(end 131.240784 -221.48292)
		(width 0.0889)
		(layer "In13.Cu")
		(net "P5E_CPU1_PE2_RX_DN<11>")
	)
	(segment
		(start 139.078462 -216.586308)
		(end 139.597892 -216.586308)
		(width 0.14732)
		(layer "In13.Cu")
		(net "P5E_CPU1_PE2_RX_DN<11>")
	)
	(segment
		(start 132.791454 -413.812228)
		(end 132.839968 -415.62655)
		(width 0.14732)
		(layer "In13.Cu")
		(net "P5E_CPU1_PE2_RX_DN<11>")
	)
	(segment
		(start 142.93342 -249.308366)
		(end 142.759176 -249.557286)
		(width 0.14732)
		(layer "In13.Cu")
		(net "P5E_CPU1_PE2_RX_DN<11>")
	)
	(segment
		(start 143.926306 -284.373828)
		(end 143.926052 -284.373828)
		(width 0.14732)
		(layer "In13.Cu")
		(net "P5E_CPU1_PE2_RX_DN<11>")
	)
	(segment
		(start 132.998972 -416.135312)
		(end 132.858256 -416.284156)
		(width 0.14732)
		(layer "In13.Cu")
		(net "P5E_CPU1_PE2_RX_DN<11>")
	)
	(segment
		(start 131.572254 -220.814646)
		(end 131.563364 -220.809566)
		(width 0.0889)
		(layer "In13.Cu")
		(net "P5E_CPU1_PE2_RX_DN<11>")
	)
	(segment
		(start 133.062726 -418.421058)
		(end 132.922264 -418.569902)
		(width 0.14732)
		(layer "In13.Cu")
		(net "P5E_CPU1_PE2_RX_DN<11>")
	)
	(segment
		(start 131.564888 -219.829634)
		(end 131.572254 -219.825316)
		(width 0.0889)
		(layer "In13.Cu")
		(net "P5E_CPU1_PE2_RX_DN<11>")
	)
	(segment
		(start 133.052566 -418.052758)
		(end 133.062726 -418.421058)
		(width 0.14732)
		(layer "In13.Cu")
		(net "P5E_CPU1_PE2_RX_DN<11>")
	)
	(segment
		(start 133.066536 -423.73169)
		(end 133.066536 -433.595018)
		(width 0.14732)
		(layer "In13.Cu")
		(net "P5E_CPU1_PE2_RX_DN<11>")
	)
	(segment
		(start 131.564888 -221.45752)
		(end 131.572254 -221.453202)
		(width 0.0889)
		(layer "In13.Cu")
		(net "P5E_CPU1_PE2_RX_DN<11>")
	)
	(segment
		(start 131.376166 -221.133924)
		(end 131.219702 -221.404942)
		(width 0.0889)
		(layer "In13.Cu")
		(net "P5E_CPU1_PE2_RX_DN<11>")
	)
	(segment
		(start 142.775432 -252.901196)
		(end 143.105632 -253.697232)
		(width 0.14732)
		(layer "In13.Cu")
		(net "P5E_CPU1_PE2_RX_DN<11>")
	)
	(segment
		(start 142.552166 -225.49866)
		(end 143.467582 -230.006398)
		(width 0.14732)
		(layer "In13.Cu")
		(net "P5E_CPU1_PE2_RX_DN<11>")
	)
	(segment
		(start 134.508494 -404.618952)
		(end 132.791454 -406.335992)
		(width 0.14732)
		(layer "In13.Cu")
		(net "P5E_CPU1_PE2_RX_DN<11>")
	)
	(segment
		(start 142.759176 -249.557286)
		(end 142.57528 -250.59894)
		(width 0.14732)
		(layer "In13.Cu")
		(net "P5E_CPU1_PE2_RX_DN<11>")
	)
	(segment
		(start 138.953494 -216.628218)
		(end 139.014454 -216.628218)
		(width 0.0889)
		(layer "In13.Cu")
		(net "P5E_CPU1_PE2_RX_DN<11>")
	)
	(segment
		(start 133.027674 -417.161218)
		(end 132.886958 -417.310062)
		(width 0.14732)
		(layer "In13.Cu")
		(net "P5E_CPU1_PE2_RX_DN<11>")
	)
	(segment
		(start 132.886958 -417.310062)
		(end 132.903722 -417.912296)
		(width 0.14732)
		(layer "In13.Cu")
		(net "P5E_CPU1_PE2_RX_DN<11>")
	)
	(segment
		(start 142.57528 -250.59894)
		(end 142.57528 -252.258322)
		(width 0.14732)
		(layer "In13.Cu")
		(net "P5E_CPU1_PE2_RX_DN<11>")
	)
	(segment
		(start 140.037312 -217.025728)
		(end 142.552166 -225.49866)
		(width 0.14732)
		(layer "In13.Cu")
		(net "P5E_CPU1_PE2_RX_DN<11>")
	)
	(segment
		(start 143.926052 -284.373828)
		(end 142.455392 -309.53837)
		(width 0.14732)
		(layer "In13.Cu")
		(net "P5E_CPU1_PE2_RX_DN<11>")
	)
	(segment
		(start 142.57528 -252.258322)
		(end 142.775432 -252.901196)
		(width 0.14732)
		(layer "In13.Cu")
		(net "P5E_CPU1_PE2_RX_DN<11>")
	)
	(segment
		(start 145.398744 -259.170932)
		(end 143.926306 -284.373828)
		(width 0.14732)
		(layer "In13.Cu")
		(net "P5E_CPU1_PE2_RX_DN<11>")
	)
	(segment
		(start 133.066536 -433.595018)
		(end 133.190996 -433.719478)
		(width 0.14732)
		(layer "In13.Cu")
		(net "P5E_CPU1_PE2_RX_DN<11>")
	)
	(segment
		(start 154.920696 -345.661488)
		(end 153.793698 -359.437178)
		(width 0.14732)
		(layer "In13.Cu")
		(net "P5E_CPU1_PE2_RX_DN<11>")
	)
	(segment
		(start 139.056364 -216.586308)
		(end 139.078462 -216.586308)
		(width 0.0889)
		(layer "In13.Cu")
		(net "P5E_CPU1_PE2_RX_DN<11>")
	)
	(segment
		(start 152.766522 -333.447644)
		(end 154.920696 -345.661488)
		(width 0.14732)
		(layer "In13.Cu")
		(net "P5E_CPU1_PE2_RX_DN<11>")
	)
	(segment
		(start 132.03301 -219.01658)
		(end 132.0419 -219.0115)
		(width 0.0889)
		(layer "In13.Cu")
		(net "P5E_CPU1_PE2_RX_DN<11>")
	)
	(segment
		(start 153.793698 -359.437178)
		(end 149.184106 -370.297456)
		(width 0.14732)
		(layer "In13.Cu")
		(net "P5E_CPU1_PE2_RX_DN<11>")
	)
	(segment
		(start 132.922264 -418.569902)
		(end 133.066536 -423.73169)
		(width 0.14732)
		(layer "In13.Cu")
		(net "P5E_CPU1_PE2_RX_DN<11>")
	)
	(segment
		(start 139.597892 -216.586308)
		(end 140.037312 -217.025728)
		(width 0.14732)
		(layer "In13.Cu")
		(net "P5E_CPU1_PE2_RX_DN<11>")
	)
	(segment
		(start 132.839968 -415.62655)
		(end 132.988558 -415.767012)
		(width 0.14732)
		(layer "In13.Cu")
		(net "P5E_CPU1_PE2_RX_DN<11>")
	)
	(segment
		(start 133.01726 -416.792664)
		(end 133.027674 -417.161218)
		(width 0.14732)
		(layer "In13.Cu")
		(net "P5E_CPU1_PE2_RX_DN<11>")
	)
	(segment
		(start 132.868416 -416.652202)
		(end 133.01726 -416.792664)
		(width 0.14732)
		(layer "In13.Cu")
		(net "P5E_CPU1_PE2_RX_DN<11>")
	)
	(segment
		(start 143.467582 -230.006398)
		(end 144.471898 -244.579394)
		(width 0.14732)
		(layer "In13.Cu")
		(net "P5E_CPU1_PE2_RX_DN<11>")
	)
	(segment
		(start 133.582918 -433.719478)
		(end 133.75005 -433.552346)
		(width 0.14732)
		(layer "In13.Cu")
		(net "P5E_CPU1_PE2_RX_DN<11>")
	)
	(segment
		(start 132.858256 -416.284156)
		(end 132.868416 -416.652202)
		(width 0.14732)
		(layer "In13.Cu")
		(net "P5E_CPU1_PE2_RX_DN<11>")
	)
	(segment
		(start 133.160262 -217.072972)
		(end 133.160262 -217.064336)
		(width 0.0889)
		(layer "In13.Cu")
		(net "P5E_CPU1_PE2_RX_DN<11>")
	)
	(segment
		(start 131.557268 -219.833952)
		(end 131.564888 -219.829634)
		(width 0.0889)
		(layer "In13.Cu")
		(net "P5E_CPU1_PE2_RX_DN<11>")
	)
	(segment
		(start 132.690616 -217.878406)
		(end 132.690616 -217.859864)
		(width 0.0889)
		(layer "In13.Cu")
		(net "P5E_CPU1_PE2_RX_DN<11>")
	)
	(segment
		(start 139.014454 -216.628218)
		(end 139.056364 -216.586308)
		(width 0.0889)
		(layer "In13.Cu")
		(net "P5E_CPU1_PE2_RX_DN<11>")
	)
	(segment
		(start 132.903722 -417.912296)
		(end 133.052566 -418.052758)
		(width 0.14732)
		(layer "In13.Cu")
		(net "P5E_CPU1_PE2_RX_DN<11>")
	)
	(segment
		(start 133.436868 -216.578434)
		(end 133.457696 -216.566242)
		(width 0.0889)
		(layer "In13.Cu")
		(net "P5E_CPU1_PE2_RX_DN<11>")
	)
	(segment
		(start 146.466814 -326.220836)
		(end 152.766522 -333.447644)
		(width 0.14732)
		(layer "In13.Cu")
		(net "P5E_CPU1_PE2_RX_DN<11>")
	)
	(segment
		(start 131.750816 -219.506038)
		(end 131.750816 -219.490544)
		(width 0.0889)
		(layer "In13.Cu")
		(net "P5E_CPU1_PE2_RX_DN<11>")
	)
	(segment
		(start 133.75005 -433.552346)
		(end 133.75005 -433.289964)
		(width 0.14732)
		(layer "In13.Cu")
		(net "P5E_CPU1_PE2_RX_DN<11>")
	)
	(segment
		(start 144.68729 -255.956054)
		(end 145.398744 -259.170932)
		(width 0.14732)
		(layer "In13.Cu")
		(net "P5E_CPU1_PE2_RX_DN<11>")
	)
	(segment
		(start 132.988558 -415.767012)
		(end 132.998972 -416.135312)
		(width 0.14732)
		(layer "In13.Cu")
		(net "P5E_CPU1_PE2_RX_DN<11>")
	)
	(segment
		(start 144.471898 -244.579394)
		(end 142.93342 -249.308366)
		(width 0.14732)
		(layer "In13.Cu")
		(net "P5E_CPU1_PE2_RX_DN<11>")
	)
	(segment
		(start 143.105632 -253.697232)
		(end 144.68729 -255.956054)
		(width 0.14732)
		(layer "In13.Cu")
		(net "P5E_CPU1_PE2_RX_DN<11>")
	)
	(segment
		(start 149.184106 -370.297456)
		(end 134.508494 -400.073622)
		(width 0.14732)
		(layer "In13.Cu")
		(net "P5E_CPU1_PE2_RX_DN<11>")
	)
	(segment
		(start 142.455392 -309.53837)
		(end 146.466814 -326.220836)
		(width 0.14732)
		(layer "In13.Cu")
		(net "P5E_CPU1_PE2_RX_DN<11>")
	)
	(segment
		(start 132.791454 -406.335992)
		(end 132.791454 -413.812228)
		(width 0.14732)
		(layer "In13.Cu")
		(net "P5E_CPU1_PE2_RX_DN<11>")
	)
	(arc
		(start 131.750816 -219.490544)
		(mid 131.830186 -219.21681)
		(end 132.03301 -219.01658)
		(width 0.0889)
		(layer "In13.Cu")
		(net "P5E_CPU1_PE2_RX_DN<11>")
	)
	(arc
		(start 138.862562 -216.624154)
		(mid 138.907985 -216.627145)
		(end 138.953494 -216.628218)
		(width 0.0889)
		(layer "In13.Cu")
		(net "P5E_CPU1_PE2_RX_DN<11>")
	)
	(arc
		(start 133.160262 -217.064336)
		(mid 133.234253 -216.78477)
		(end 133.436868 -216.578434)
		(width 0.0889)
		(layer "In13.Cu")
		(net "P5E_CPU1_PE2_RX_DN<11>")
	)
	(arc
		(start 131.240784 -221.48292)
		(mid 131.40488 -221.507267)
		(end 131.563364 -221.458282)
		(width 0.0889)
		(layer "In13.Cu")
		(net "P5E_CPU1_PE2_RX_DN<11>")
	)
	(arc
		(start 135.887968 -216.574878)
		(mid 136.075166 -216.625021)
		(end 136.262364 -216.574878)
		(width 0.0889)
		(layer "In13.Cu")
		(net "P5E_CPU1_PE2_RX_DN<11>")
	)
	(arc
		(start 132.973064 -217.388694)
		(mid 133.107997 -217.25534)
		(end 133.160262 -217.072972)
		(width 0.0889)
		(layer "In13.Cu")
		(net "P5E_CPU1_PE2_RX_DN<11>")
	)
	(arc
		(start 136.262364 -216.574878)
		(mid 136.545066 -216.499102)
		(end 136.827768 -216.574878)
		(width 0.0889)
		(layer "In13.Cu")
		(net "P5E_CPU1_PE2_RX_DN<11>")
	)
	(arc
		(start 134.382764 -216.574878)
		(mid 134.665466 -216.499102)
		(end 134.948168 -216.574878)
		(width 0.0889)
		(layer "In13.Cu")
		(net "P5E_CPU1_PE2_RX_DN<11>")
	)
	(arc
		(start 131.563364 -220.809566)
		(mid 131.280496 -220.323447)
		(end 131.557268 -219.833952)
		(width 0.0889)
		(layer "In13.Cu")
		(net "P5E_CPU1_PE2_RX_DN<11>")
	)
	(arc
		(start 132.512054 -218.197684)
		(mid 132.642968 -218.061324)
		(end 132.690616 -217.878406)
		(width 0.0889)
		(layer "In13.Cu")
		(net "P5E_CPU1_PE2_RX_DN<11>")
	)
	(arc
		(start 132.220462 -218.692222)
		(mid 132.294453 -218.412656)
		(end 132.497068 -218.20632)
		(width 0.0889)
		(layer "In13.Cu")
		(net "P5E_CPU1_PE2_RX_DN<11>")
	)
	(arc
		(start 134.948168 -216.574878)
		(mid 135.135366 -216.625021)
		(end 135.322564 -216.574878)
		(width 0.0889)
		(layer "In13.Cu")
		(net "P5E_CPU1_PE2_RX_DN<11>")
	)
	(arc
		(start 138.707368 -216.574878)
		(mid 138.782261 -216.608022)
		(end 138.862562 -216.624154)
		(width 0.0889)
		(layer "In13.Cu")
		(net "P5E_CPU1_PE2_RX_DN<11>")
	)
	(arc
		(start 138.141964 -216.574878)
		(mid 138.424666 -216.499102)
		(end 138.707368 -216.574878)
		(width 0.0889)
		(layer "In13.Cu")
		(net "P5E_CPU1_PE2_RX_DN<11>")
	)
	(arc
		(start 131.572254 -219.825316)
		(mid 131.703168 -219.688956)
		(end 131.750816 -219.506038)
		(width 0.0889)
		(layer "In13.Cu")
		(net "P5E_CPU1_PE2_RX_DN<11>")
	)
	(arc
		(start 131.572254 -221.453202)
		(mid 131.750972 -221.133924)
		(end 131.572254 -220.814646)
		(width 0.0889)
		(layer "In13.Cu")
		(net "P5E_CPU1_PE2_RX_DN<11>")
	)
	(arc
		(start 137.767568 -216.574878)
		(mid 137.954766 -216.625021)
		(end 138.141964 -216.574878)
		(width 0.0889)
		(layer "In13.Cu")
		(net "P5E_CPU1_PE2_RX_DN<11>")
	)
	(arc
		(start 132.0419 -219.0115)
		(mid 132.172814 -218.87514)
		(end 132.220462 -218.692222)
		(width 0.0889)
		(layer "In13.Cu")
		(net "P5E_CPU1_PE2_RX_DN<11>")
	)
	(arc
		(start 133.457696 -216.566242)
		(mid 133.734171 -216.498922)
		(end 134.008368 -216.574878)
		(width 0.0889)
		(layer "In13.Cu")
		(net "P5E_CPU1_PE2_RX_DN<11>")
	)
	(arc
		(start 132.690616 -217.859864)
		(mid 132.770778 -217.587675)
		(end 132.973064 -217.388694)
		(width 0.0889)
		(layer "In13.Cu")
		(net "P5E_CPU1_PE2_RX_DN<11>")
	)
	(arc
		(start 136.827768 -216.574878)
		(mid 137.014966 -216.625021)
		(end 137.202164 -216.574878)
		(width 0.0889)
		(layer "In13.Cu")
		(net "P5E_CPU1_PE2_RX_DN<11>")
	)
	(arc
		(start 137.202164 -216.574878)
		(mid 137.484866 -216.499102)
		(end 137.767568 -216.574878)
		(width 0.0889)
		(layer "In13.Cu")
		(net "P5E_CPU1_PE2_RX_DN<11>")
	)
	(arc
		(start 134.008368 -216.574878)
		(mid 134.195566 -216.625021)
		(end 134.382764 -216.574878)
		(width 0.0889)
		(layer "In13.Cu")
		(net "P5E_CPU1_PE2_RX_DN<11>")
	)
	(arc
		(start 135.322564 -216.574878)
		(mid 135.605266 -216.499102)
		(end 135.887968 -216.574878)
		(width 0.0889)
		(layer "In13.Cu")
		(net "P5E_CPU1_PE2_RX_DN<11>")
	)
	(segment
		(start 129.966466 -220.320108)
		(end 129.966212 -220.319854)
		(width 0.13208)
		(layer "F.Cu")
		(net "P5E_CPU1_PE2_RX_DN<10>")
	)
	(segment
		(start 129.966466 -220.855794)
		(end 129.966466 -220.320108)
		(width 0.13208)
		(layer "F.Cu")
		(net "P5E_CPU1_PE2_RX_DN<10>")
	)
	(segment
		(start 135.403082 -215.752426)
		(end 135.417814 -215.761062)
		(width 0.0889)
		(layer "In13.Cu")
		(net "P5E_CPU1_PE2_RX_DN<10>")
	)
	(segment
		(start 133.523482 -215.752426)
		(end 133.538214 -215.761062)
		(width 0.0889)
		(layer "In13.Cu")
		(net "P5E_CPU1_PE2_RX_DN<10>")
	)
	(segment
		(start 139.76477 -215.239346)
		(end 140.797026 -216.271348)
		(width 0.14732)
		(layer "In13.Cu")
		(net "P5E_CPU1_PE2_RX_DN<10>")
	)
	(segment
		(start 131.280662 -217.072972)
		(end 131.280662 -217.064336)
		(width 0.0889)
		(layer "In13.Cu")
		(net "P5E_CPU1_PE2_RX_DN<10>")
	)
	(segment
		(start 135.582914 -434.729636)
		(end 135.750046 -434.562504)
		(width 0.14732)
		(layer "In13.Cu")
		(net "P5E_CPU1_PE2_RX_DN<10>")
	)
	(segment
		(start 129.966212 -220.319854)
		(end 130.122676 -220.590872)
		(width 0.0889)
		(layer "In13.Cu")
		(net "P5E_CPU1_PE2_RX_DN<10>")
	)
	(segment
		(start 130.625088 -219.182442)
		(end 130.623564 -219.18168)
		(width 0.0889)
		(layer "In13.Cu")
		(net "P5E_CPU1_PE2_RX_DN<10>")
	)
	(segment
		(start 130.623564 -219.830396)
		(end 130.632454 -219.825316)
		(width 0.0889)
		(layer "In13.Cu")
		(net "P5E_CPU1_PE2_RX_DN<10>")
	)
	(segment
		(start 146.405346 -259.067808)
		(end 143.412972 -309.459884)
		(width 0.14732)
		(layer "In13.Cu")
		(net "P5E_CPU1_PE2_RX_DN<10>")
	)
	(segment
		(start 136.810242 -215.701626)
		(end 137.230612 -215.281256)
		(width 0.0889)
		(layer "In13.Cu")
		(net "P5E_CPU1_PE2_RX_DN<10>")
	)
	(segment
		(start 134.463282 -215.752426)
		(end 134.478014 -215.761062)
		(width 0.0889)
		(layer "In13.Cu")
		(net "P5E_CPU1_PE2_RX_DN<10>")
	)
	(segment
		(start 130.122676 -220.590872)
		(end 130.200908 -220.6117)
		(width 0.0889)
		(layer "In13.Cu")
		(net "P5E_CPU1_PE2_RX_DN<10>")
	)
	(segment
		(start 131.56819 -216.57183)
		(end 131.571238 -216.570052)
		(width 0.0889)
		(layer "In13.Cu")
		(net "P5E_CPU1_PE2_RX_DN<10>")
	)
	(segment
		(start 137.571734 -404.618952)
		(end 135.854694 -406.335992)
		(width 0.14732)
		(layer "In13.Cu")
		(net "P5E_CPU1_PE2_RX_DN<10>")
	)
	(segment
		(start 131.571238 -216.570052)
		(end 131.572254 -216.569544)
		(width 0.0889)
		(layer "In13.Cu")
		(net "P5E_CPU1_PE2_RX_DN<10>")
	)
	(segment
		(start 131.557268 -216.578434)
		(end 131.564888 -216.573862)
		(width 0.0889)
		(layer "In13.Cu")
		(net "P5E_CPU1_PE2_RX_DN<10>")
	)
	(segment
		(start 135.631428 -418.030152)
		(end 135.478774 -418.166804)
		(width 0.14732)
		(layer "In13.Cu")
		(net "P5E_CPU1_PE2_RX_DN<10>")
	)
	(segment
		(start 135.854694 -411.345126)
		(end 135.515096 -417.509706)
		(width 0.14732)
		(layer "In13.Cu")
		(net "P5E_CPU1_PE2_RX_DN<10>")
	)
	(segment
		(start 130.632454 -219.18676)
		(end 130.625088 -219.182442)
		(width 0.0889)
		(layer "In13.Cu")
		(net "P5E_CPU1_PE2_RX_DN<10>")
	)
	(segment
		(start 131.750816 -216.25052)
		(end 131.750816 -216.235026)
		(width 0.0889)
		(layer "In13.Cu")
		(net "P5E_CPU1_PE2_RX_DN<10>")
	)
	(segment
		(start 135.478774 -418.166804)
		(end 135.066532 -425.64558)
		(width 0.14732)
		(layer "In13.Cu")
		(net "P5E_CPU1_PE2_RX_DN<10>")
	)
	(segment
		(start 135.651748 -417.662106)
		(end 135.631428 -418.030152)
		(width 0.14732)
		(layer "In13.Cu")
		(net "P5E_CPU1_PE2_RX_DN<10>")
	)
	(segment
		(start 143.844264 -249.62993)
		(end 143.763746 -249.745246)
		(width 0.14732)
		(layer "In13.Cu")
		(net "P5E_CPU1_PE2_RX_DN<10>")
	)
	(segment
		(start 130.622802 -219.181172)
		(end 130.617468 -219.178124)
		(width 0.0889)
		(layer "In13.Cu")
		(net "P5E_CPU1_PE2_RX_DN<10>")
	)
	(segment
		(start 135.066532 -434.612288)
		(end 135.18388 -434.729636)
		(width 0.14732)
		(layer "In13.Cu")
		(net "P5E_CPU1_PE2_RX_DN<10>")
	)
	(segment
		(start 143.51508 -251.152152)
		(end 143.51508 -252.118622)
		(width 0.14732)
		(layer "In13.Cu")
		(net "P5E_CPU1_PE2_RX_DN<10>")
	)
	(segment
		(start 143.763746 -249.745246)
		(end 143.51508 -251.152152)
		(width 0.14732)
		(layer "In13.Cu")
		(net "P5E_CPU1_PE2_RX_DN<10>")
	)
	(segment
		(start 154.805126 -359.479342)
		(end 137.571734 -399.984468)
		(width 0.14732)
		(layer "In13.Cu")
		(net "P5E_CPU1_PE2_RX_DN<10>")
	)
	(segment
		(start 143.911574 -253.212854)
		(end 145.583402 -255.600454)
		(width 0.14732)
		(layer "In13.Cu")
		(net "P5E_CPU1_PE2_RX_DN<10>")
	)
	(segment
		(start 130.617468 -218.20632)
		(end 130.62077 -218.204288)
		(width 0.0889)
		(layer "In13.Cu")
		(net "P5E_CPU1_PE2_RX_DN<10>")
	)
	(segment
		(start 130.611372 -219.837508)
		(end 130.619754 -219.832682)
		(width 0.0889)
		(layer "In13.Cu")
		(net "P5E_CPU1_PE2_RX_DN<10>")
	)
	(segment
		(start 145.583402 -255.600454)
		(end 146.405346 -259.067808)
		(width 0.14732)
		(layer "In13.Cu")
		(net "P5E_CPU1_PE2_RX_DN<10>")
	)
	(segment
		(start 143.58112 -225.535744)
		(end 144.417542 -229.80904)
		(width 0.14732)
		(layer "In13.Cu")
		(net "P5E_CPU1_PE2_RX_DN<10>")
	)
	(segment
		(start 153.689812 -333.08036)
		(end 155.927552 -345.769184)
		(width 0.14732)
		(layer "In13.Cu")
		(net "P5E_CPU1_PE2_RX_DN<10>")
	)
	(segment
		(start 130.619754 -219.832682)
		(end 130.623564 -219.830396)
		(width 0.0889)
		(layer "In13.Cu")
		(net "P5E_CPU1_PE2_RX_DN<10>")
	)
	(segment
		(start 137.230612 -215.281256)
		(end 137.902696 -215.281256)
		(width 0.0889)
		(layer "In13.Cu")
		(net "P5E_CPU1_PE2_RX_DN<10>")
	)
	(segment
		(start 147.307046 -325.66991)
		(end 153.689812 -333.08036)
		(width 0.14732)
		(layer "In13.Cu")
		(net "P5E_CPU1_PE2_RX_DN<10>")
	)
	(segment
		(start 130.625088 -218.202002)
		(end 130.632454 -218.197684)
		(width 0.0889)
		(layer "In13.Cu")
		(net "P5E_CPU1_PE2_RX_DN<10>")
	)
	(segment
		(start 145.424652 -244.771926)
		(end 143.844264 -249.62993)
		(width 0.14732)
		(layer "In13.Cu")
		(net "P5E_CPU1_PE2_RX_DN<10>")
	)
	(segment
		(start 130.62204 -218.203526)
		(end 130.625088 -218.202002)
		(width 0.0889)
		(layer "In13.Cu")
		(net "P5E_CPU1_PE2_RX_DN<10>")
	)
	(segment
		(start 143.650462 -252.582426)
		(end 143.911574 -253.212854)
		(width 0.14732)
		(layer "In13.Cu")
		(net "P5E_CPU1_PE2_RX_DN<10>")
	)
	(segment
		(start 140.797026 -216.271348)
		(end 143.58112 -225.535744)
		(width 0.14732)
		(layer "In13.Cu")
		(net "P5E_CPU1_PE2_RX_DN<10>")
	)
	(segment
		(start 131.572254 -216.569544)
		(end 131.572254 -216.569798)
		(width 0.0889)
		(layer "In13.Cu")
		(net "P5E_CPU1_PE2_RX_DN<10>")
	)
	(segment
		(start 137.571734 -399.984468)
		(end 137.571734 -404.618952)
		(width 0.14732)
		(layer "In13.Cu")
		(net "P5E_CPU1_PE2_RX_DN<10>")
	)
	(segment
		(start 130.62077 -218.204288)
		(end 130.62204 -218.203526)
		(width 0.0889)
		(layer "In13.Cu")
		(net "P5E_CPU1_PE2_RX_DN<10>")
	)
	(segment
		(start 130.811016 -217.878406)
		(end 130.811016 -217.859864)
		(width 0.0889)
		(layer "In13.Cu")
		(net "P5E_CPU1_PE2_RX_DN<10>")
	)
	(segment
		(start 130.623564 -219.18168)
		(end 130.622802 -219.181172)
		(width 0.0889)
		(layer "In13.Cu")
		(net "P5E_CPU1_PE2_RX_DN<10>")
	)
	(segment
		(start 135.066532 -425.64558)
		(end 135.066532 -434.612288)
		(width 0.14732)
		(layer "In13.Cu")
		(net "P5E_CPU1_PE2_RX_DN<10>")
	)
	(segment
		(start 143.51508 -252.118622)
		(end 143.650462 -252.582426)
		(width 0.14732)
		(layer "In13.Cu")
		(net "P5E_CPU1_PE2_RX_DN<10>")
	)
	(segment
		(start 144.417542 -229.80904)
		(end 145.424652 -244.771926)
		(width 0.14732)
		(layer "In13.Cu")
		(net "P5E_CPU1_PE2_RX_DN<10>")
	)
	(segment
		(start 143.412972 -309.459884)
		(end 147.307046 -325.66991)
		(width 0.14732)
		(layer "In13.Cu")
		(net "P5E_CPU1_PE2_RX_DN<10>")
	)
	(segment
		(start 137.944606 -215.239346)
		(end 137.966704 -215.239346)
		(width 0.0889)
		(layer "In13.Cu")
		(net "P5E_CPU1_PE2_RX_DN<10>")
	)
	(segment
		(start 131.566666 -216.572846)
		(end 131.56819 -216.57183)
		(width 0.0889)
		(layer "In13.Cu")
		(net "P5E_CPU1_PE2_RX_DN<10>")
	)
	(segment
		(start 132.583682 -215.752426)
		(end 132.598414 -215.761062)
		(width 0.0889)
		(layer "In13.Cu")
		(net "P5E_CPU1_PE2_RX_DN<10>")
	)
	(segment
		(start 131.564888 -216.573862)
		(end 131.566666 -216.572846)
		(width 0.0889)
		(layer "In13.Cu")
		(net "P5E_CPU1_PE2_RX_DN<10>")
	)
	(segment
		(start 137.966704 -215.239346)
		(end 139.76477 -215.239346)
		(width 0.14732)
		(layer "In13.Cu")
		(net "P5E_CPU1_PE2_RX_DN<10>")
	)
	(segment
		(start 135.750046 -434.562504)
		(end 135.750046 -434.289962)
		(width 0.14732)
		(layer "In13.Cu")
		(net "P5E_CPU1_PE2_RX_DN<10>")
	)
	(segment
		(start 155.927552 -345.769184)
		(end 154.805126 -359.479342)
		(width 0.14732)
		(layer "In13.Cu")
		(net "P5E_CPU1_PE2_RX_DN<10>")
	)
	(segment
		(start 135.854694 -406.335992)
		(end 135.854694 -411.345126)
		(width 0.14732)
		(layer "In13.Cu")
		(net "P5E_CPU1_PE2_RX_DN<10>")
	)
	(segment
		(start 137.902696 -215.281256)
		(end 137.944606 -215.239346)
		(width 0.0889)
		(layer "In13.Cu")
		(net "P5E_CPU1_PE2_RX_DN<10>")
	)
	(segment
		(start 135.515096 -417.509706)
		(end 135.651748 -417.662106)
		(width 0.14732)
		(layer "In13.Cu")
		(net "P5E_CPU1_PE2_RX_DN<10>")
	)
	(segment
		(start 135.18388 -434.729636)
		(end 135.582914 -434.729636)
		(width 0.14732)
		(layer "In13.Cu")
		(net "P5E_CPU1_PE2_RX_DN<10>")
	)
	(arc
		(start 131.572254 -216.569798)
		(mid 131.703168 -216.433438)
		(end 131.750816 -216.25052)
		(width 0.0889)
		(layer "In13.Cu")
		(net "P5E_CPU1_PE2_RX_DN<10>")
	)
	(arc
		(start 130.632454 -218.197684)
		(mid 130.763368 -218.061324)
		(end 130.811016 -217.878406)
		(width 0.0889)
		(layer "In13.Cu")
		(net "P5E_CPU1_PE2_RX_DN<10>")
	)
	(arc
		(start 133.91261 -215.761062)
		(mid 134.186809 -215.685227)
		(end 134.463282 -215.752426)
		(width 0.0889)
		(layer "In13.Cu")
		(net "P5E_CPU1_PE2_RX_DN<10>")
	)
	(arc
		(start 136.732518 -215.761062)
		(mid 136.763815 -215.740972)
		(end 136.79297 -215.717882)
		(width 0.0889)
		(layer "In13.Cu")
		(net "P5E_CPU1_PE2_RX_DN<10>")
	)
	(arc
		(start 131.750816 -216.235026)
		(mid 131.830186 -215.961292)
		(end 132.03301 -215.761062)
		(width 0.0889)
		(layer "In13.Cu")
		(net "P5E_CPU1_PE2_RX_DN<10>")
	)
	(arc
		(start 136.358122 -215.761062)
		(mid 136.54532 -215.811205)
		(end 136.732518 -215.761062)
		(width 0.0889)
		(layer "In13.Cu")
		(net "P5E_CPU1_PE2_RX_DN<10>")
	)
	(arc
		(start 134.478014 -215.761062)
		(mid 134.665212 -215.811205)
		(end 134.85241 -215.761062)
		(width 0.0889)
		(layer "In13.Cu")
		(net "P5E_CPU1_PE2_RX_DN<10>")
	)
	(arc
		(start 135.417814 -215.761062)
		(mid 135.605012 -215.811205)
		(end 135.79221 -215.761062)
		(width 0.0889)
		(layer "In13.Cu")
		(net "P5E_CPU1_PE2_RX_DN<10>")
	)
	(arc
		(start 136.79297 -215.717882)
		(mid 136.801734 -215.70989)
		(end 136.810242 -215.701626)
		(width 0.0889)
		(layer "In13.Cu")
		(net "P5E_CPU1_PE2_RX_DN<10>")
	)
	(arc
		(start 130.811016 -217.859864)
		(mid 130.891178 -217.587675)
		(end 131.093464 -217.388694)
		(width 0.0889)
		(layer "In13.Cu")
		(net "P5E_CPU1_PE2_RX_DN<10>")
	)
	(arc
		(start 132.598414 -215.761062)
		(mid 132.785612 -215.811205)
		(end 132.97281 -215.761062)
		(width 0.0889)
		(layer "In13.Cu")
		(net "P5E_CPU1_PE2_RX_DN<10>")
	)
	(arc
		(start 130.617468 -219.178124)
		(mid 130.340894 -218.692222)
		(end 130.617468 -218.20632)
		(width 0.0889)
		(layer "In13.Cu")
		(net "P5E_CPU1_PE2_RX_DN<10>")
	)
	(arc
		(start 134.85241 -215.761062)
		(mid 135.126609 -215.685227)
		(end 135.403082 -215.752426)
		(width 0.0889)
		(layer "In13.Cu")
		(net "P5E_CPU1_PE2_RX_DN<10>")
	)
	(arc
		(start 131.093464 -217.388694)
		(mid 131.228397 -217.25534)
		(end 131.280662 -217.072972)
		(width 0.0889)
		(layer "In13.Cu")
		(net "P5E_CPU1_PE2_RX_DN<10>")
	)
	(arc
		(start 131.280662 -217.064336)
		(mid 131.354653 -216.78477)
		(end 131.557268 -216.578434)
		(width 0.0889)
		(layer "In13.Cu")
		(net "P5E_CPU1_PE2_RX_DN<10>")
	)
	(arc
		(start 132.03301 -215.761062)
		(mid 132.307209 -215.685227)
		(end 132.583682 -215.752426)
		(width 0.0889)
		(layer "In13.Cu")
		(net "P5E_CPU1_PE2_RX_DN<10>")
	)
	(arc
		(start 132.97281 -215.761062)
		(mid 133.247009 -215.685227)
		(end 133.523482 -215.752426)
		(width 0.0889)
		(layer "In13.Cu")
		(net "P5E_CPU1_PE2_RX_DN<10>")
	)
	(arc
		(start 133.538214 -215.761062)
		(mid 133.725412 -215.811205)
		(end 133.91261 -215.761062)
		(width 0.0889)
		(layer "In13.Cu")
		(net "P5E_CPU1_PE2_RX_DN<10>")
	)
	(arc
		(start 130.340862 -220.319854)
		(mid 130.413097 -220.04333)
		(end 130.611372 -219.837508)
		(width 0.0889)
		(layer "In13.Cu")
		(net "P5E_CPU1_PE2_RX_DN<10>")
	)
	(arc
		(start 130.200908 -220.6117)
		(mid 130.304053 -220.481675)
		(end 130.340862 -220.319854)
		(width 0.0889)
		(layer "In13.Cu")
		(net "P5E_CPU1_PE2_RX_DN<10>")
	)
	(arc
		(start 135.79221 -215.761062)
		(mid 136.075166 -215.685159)
		(end 136.358122 -215.761062)
		(width 0.0889)
		(layer "In13.Cu")
		(net "P5E_CPU1_PE2_RX_DN<10>")
	)
	(arc
		(start 130.632454 -219.825316)
		(mid 130.811051 -219.506038)
		(end 130.632454 -219.18676)
		(width 0.0889)
		(layer "In13.Cu")
		(net "P5E_CPU1_PE2_RX_DN<10>")
	)
	(segment
		(start 120.568466 -220.320108)
		(end 120.568212 -220.319854)
		(width 0.13208)
		(layer "F.Cu")
		(net "P5E_CPU1_PE2_RX_DN<0>")
	)
	(segment
		(start 120.568466 -220.855794)
		(end 120.568466 -220.320108)
		(width 0.13208)
		(layer "F.Cu")
		(net "P5E_CPU1_PE2_RX_DN<0>")
	)
	(segment
		(start 121.219468 -218.20632)
		(end 121.234454 -218.197684)
		(width 0.0889)
		(layer "In13.Cu")
		(net "P5E_CPU1_PE2_RX_DN<0>")
	)
	(segment
		(start 167.524938 -397.87068)
		(end 168.204134 -400.085052)
		(width 0.14732)
		(layer "In13.Cu")
		(net "P5E_CPU1_PE2_RX_DN<0>")
	)
	(segment
		(start 121.221754 -216.577164)
		(end 121.225564 -216.574878)
		(width 0.0889)
		(layer "In13.Cu")
		(net "P5E_CPU1_PE2_RX_DN<0>")
	)
	(segment
		(start 155.42768 -318.767206)
		(end 157.308296 -321.272916)
		(width 0.14732)
		(layer "In13.Cu")
		(net "P5E_CPU1_PE2_RX_DN<0>")
	)
	(segment
		(start 157.308296 -321.272916)
		(end 160.71088 -323.170296)
		(width 0.14732)
		(layer "In13.Cu")
		(net "P5E_CPU1_PE2_RX_DN<0>")
	)
	(segment
		(start 165.731698 -346.049346)
		(end 165.731698 -346.092272)
		(width 0.14732)
		(layer "In13.Cu")
		(net "P5E_CPU1_PE2_RX_DN<0>")
	)
	(segment
		(start 121.841006 -211.408264)
		(end 122.979688 -208.658968)
		(width 0.14732)
		(layer "In13.Cu")
		(net "P5E_CPU1_PE2_RX_DN<0>")
	)
	(segment
		(start 157.183836 -423.051478)
		(end 157.209236 -423.254678)
		(width 0.14732)
		(layer "In13.Cu")
		(net "P5E_CPU1_PE2_RX_DN<0>")
	)
	(segment
		(start 157.626558 -422.684956)
		(end 157.451806 -422.7068)
		(width 0.14732)
		(layer "In13.Cu")
		(net "P5E_CPU1_PE2_RX_DN<0>")
	)
	(segment
		(start 156.750004 -434.552344)
		(end 156.750004 -434.289962)
		(width 0.14732)
		(layer "In13.Cu")
		(net "P5E_CPU1_PE2_RX_DN<0>")
	)
	(segment
		(start 121.225564 -219.18168)
		(end 121.219468 -219.178124)
		(width 0.0889)
		(layer "In13.Cu")
		(net "P5E_CPU1_PE2_RX_DN<0>")
	)
	(segment
		(start 121.882662 -215.436704)
		(end 121.882662 -215.414606)
		(width 0.0889)
		(layer "In13.Cu")
		(net "P5E_CPU1_PE2_RX_DN<0>")
	)
	(segment
		(start 153.02738 -308.313074)
		(end 155.42768 -318.767206)
		(width 0.14732)
		(layer "In13.Cu")
		(net "P5E_CPU1_PE2_RX_DN<0>")
	)
	(segment
		(start 121.221754 -219.832682)
		(end 121.225564 -219.830396)
		(width 0.0889)
		(layer "In13.Cu")
		(net "P5E_CPU1_PE2_RX_DN<0>")
	)
	(segment
		(start 164.106606 -326.271636)
		(end 164.32911 -327.533508)
		(width 0.14732)
		(layer "In13.Cu")
		(net "P5E_CPU1_PE2_RX_DN<0>")
	)
	(segment
		(start 156.205174 -434.719476)
		(end 156.582872 -434.719476)
		(width 0.14732)
		(layer "In13.Cu")
		(net "P5E_CPU1_PE2_RX_DN<0>")
	)
	(segment
		(start 156.779722 -423.571162)
		(end 156.06649 -424.488102)
		(width 0.14732)
		(layer "In13.Cu")
		(net "P5E_CPU1_PE2_RX_DN<0>")
	)
	(segment
		(start 121.882916 -213.447122)
		(end 121.88317 -213.447122)
		(width 0.0889)
		(layer "In13.Cu")
		(net "P5E_CPU1_PE2_RX_DN<0>")
	)
	(segment
		(start 121.69521 -215.761062)
		(end 121.7041 -215.755982)
		(width 0.0889)
		(layer "In13.Cu")
		(net "P5E_CPU1_PE2_RX_DN<0>")
	)
	(segment
		(start 164.32911 -327.533508)
		(end 165.73373 -346.047314)
		(width 0.14732)
		(layer "In13.Cu")
		(net "P5E_CPU1_PE2_RX_DN<0>")
	)
	(segment
		(start 165.73373 -346.047314)
		(end 165.731698 -346.049346)
		(width 0.14732)
		(layer "In13.Cu")
		(net "P5E_CPU1_PE2_RX_DN<0>")
	)
	(segment
		(start 157.27807 -253.5047)
		(end 153.02738 -308.313074)
		(width 0.14732)
		(layer "In13.Cu")
		(net "P5E_CPU1_PE2_RX_DN<0>")
	)
	(segment
		(start 122.352308 -214.622634)
		(end 122.352308 -214.461344)
		(width 0.0889)
		(layer "In13.Cu")
		(net "P5E_CPU1_PE2_RX_DN<0>")
	)
	(segment
		(start 157.895036 -422.33977)
		(end 157.626558 -422.684956)
		(width 0.14732)
		(layer "In13.Cu")
		(net "P5E_CPU1_PE2_RX_DN<0>")
	)
	(segment
		(start 153.434034 -223.440752)
		(end 157.080204 -247.606566)
		(width 0.14732)
		(layer "In13.Cu")
		(net "P5E_CPU1_PE2_RX_DN<0>")
	)
	(segment
		(start 121.882916 -213.929468)
		(end 121.882916 -213.447122)
		(width 0.0889)
		(layer "In13.Cu")
		(net "P5E_CPU1_PE2_RX_DN<0>")
	)
	(segment
		(start 163.112704 -324.85203)
		(end 164.106606 -326.271636)
		(width 0.14732)
		(layer "In13.Cu")
		(net "P5E_CPU1_PE2_RX_DN<0>")
	)
	(segment
		(start 168.204134 -400.085052)
		(end 168.204134 -404.618952)
		(width 0.14732)
		(layer "In13.Cu")
		(net "P5E_CPU1_PE2_RX_DN<0>")
	)
	(segment
		(start 121.413016 -216.25052)
		(end 121.413016 -216.235026)
		(width 0.0889)
		(layer "In13.Cu")
		(net "P5E_CPU1_PE2_RX_DN<0>")
	)
	(segment
		(start 157.451806 -422.7068)
		(end 157.183836 -423.051478)
		(width 0.14732)
		(layer "In13.Cu")
		(net "P5E_CPU1_PE2_RX_DN<0>")
	)
	(segment
		(start 121.841006 -213.279736)
		(end 121.841006 -213.257638)
		(width 0.0889)
		(layer "In13.Cu")
		(net "P5E_CPU1_PE2_RX_DN<0>")
	)
	(segment
		(start 122.168158 -214.261954)
		(end 122.168412 -214.261954)
		(width 0.0889)
		(layer "In13.Cu")
		(net "P5E_CPU1_PE2_RX_DN<0>")
	)
	(segment
		(start 156.06649 -434.580792)
		(end 156.205174 -434.719476)
		(width 0.14732)
		(layer "In13.Cu")
		(net "P5E_CPU1_PE2_RX_DN<0>")
	)
	(segment
		(start 121.88317 -213.447122)
		(end 121.88317 -213.3219)
		(width 0.0889)
		(layer "In13.Cu")
		(net "P5E_CPU1_PE2_RX_DN<0>")
	)
	(segment
		(start 121.234454 -217.559128)
		(end 121.225564 -217.554048)
		(width 0.0889)
		(layer "In13.Cu")
		(net "P5E_CPU1_PE2_RX_DN<0>")
	)
	(segment
		(start 156.983176 -423.545508)
		(end 156.779722 -423.570908)
		(width 0.14732)
		(layer "In13.Cu")
		(net "P5E_CPU1_PE2_RX_DN<0>")
	)
	(segment
		(start 157.080204 -247.606566)
		(end 157.27807 -253.5047)
		(width 0.14732)
		(layer "In13.Cu")
		(net "P5E_CPU1_PE2_RX_DN<0>")
	)
	(segment
		(start 156.06649 -424.488102)
		(end 156.06649 -434.580792)
		(width 0.14732)
		(layer "In13.Cu")
		(net "P5E_CPU1_PE2_RX_DN<0>")
	)
	(segment
		(start 120.942862 -217.071956)
		(end 120.942862 -217.064336)
		(width 0.0889)
		(layer "In13.Cu")
		(net "P5E_CPU1_PE2_RX_DN<0>")
	)
	(segment
		(start 121.225564 -219.830396)
		(end 121.234454 -219.825316)
		(width 0.0889)
		(layer "In13.Cu")
		(net "P5E_CPU1_PE2_RX_DN<0>")
	)
	(segment
		(start 149.704044 -210.60156)
		(end 153.434034 -223.440752)
		(width 0.14732)
		(layer "In13.Cu")
		(net "P5E_CPU1_PE2_RX_DN<0>")
	)
	(segment
		(start 121.213372 -219.837508)
		(end 121.221754 -219.832682)
		(width 0.0889)
		(layer "In13.Cu")
		(net "P5E_CPU1_PE2_RX_DN<0>")
	)
	(segment
		(start 160.71088 -323.170296)
		(end 163.112704 -324.85203)
		(width 0.14732)
		(layer "In13.Cu")
		(net "P5E_CPU1_PE2_RX_DN<0>")
	)
	(segment
		(start 138.361674 -199.25919)
		(end 149.704044 -210.60156)
		(width 0.14732)
		(layer "In13.Cu")
		(net "P5E_CPU1_PE2_RX_DN<0>")
	)
	(segment
		(start 165.980364 -389.000492)
		(end 167.524938 -397.87068)
		(width 0.14732)
		(layer "In13.Cu")
		(net "P5E_CPU1_PE2_RX_DN<0>")
	)
	(segment
		(start 121.88317 -213.3219)
		(end 121.841006 -213.279736)
		(width 0.0889)
		(layer "In13.Cu")
		(net "P5E_CPU1_PE2_RX_DN<0>")
	)
	(segment
		(start 120.724676 -220.590872)
		(end 120.802908 -220.6117)
		(width 0.0889)
		(layer "In13.Cu")
		(net "P5E_CPU1_PE2_RX_DN<0>")
	)
	(segment
		(start 121.213372 -216.58199)
		(end 121.221754 -216.577164)
		(width 0.0889)
		(layer "In13.Cu")
		(net "P5E_CPU1_PE2_RX_DN<0>")
	)
	(segment
		(start 156.779722 -423.570908)
		(end 156.779722 -423.571162)
		(width 0.14732)
		(layer "In13.Cu")
		(net "P5E_CPU1_PE2_RX_DN<0>")
	)
	(segment
		(start 165.731698 -346.092272)
		(end 165.045644 -361.39755)
		(width 0.14732)
		(layer "In13.Cu")
		(net "P5E_CPU1_PE2_RX_DN<0>")
	)
	(segment
		(start 168.204134 -404.618952)
		(end 166.487094 -406.335992)
		(width 0.14732)
		(layer "In13.Cu")
		(net "P5E_CPU1_PE2_RX_DN<0>")
	)
	(segment
		(start 121.234454 -219.18676)
		(end 121.225564 -219.18168)
		(width 0.0889)
		(layer "In13.Cu")
		(net "P5E_CPU1_PE2_RX_DN<0>")
	)
	(segment
		(start 120.568212 -220.319854)
		(end 120.724676 -220.590872)
		(width 0.0889)
		(layer "In13.Cu")
		(net "P5E_CPU1_PE2_RX_DN<0>")
	)
	(segment
		(start 122.164856 -214.946992)
		(end 122.173746 -214.941912)
		(width 0.0889)
		(layer "In13.Cu")
		(net "P5E_CPU1_PE2_RX_DN<0>")
	)
	(segment
		(start 166.487094 -406.335992)
		(end 166.487094 -411.089348)
		(width 0.14732)
		(layer "In13.Cu")
		(net "P5E_CPU1_PE2_RX_DN<0>")
	)
	(segment
		(start 156.582872 -434.719476)
		(end 156.750004 -434.552344)
		(width 0.14732)
		(layer "In13.Cu")
		(net "P5E_CPU1_PE2_RX_DN<0>")
	)
	(segment
		(start 157.209236 -423.254678)
		(end 156.983176 -423.545508)
		(width 0.14732)
		(layer "In13.Cu")
		(net "P5E_CPU1_PE2_RX_DN<0>")
	)
	(segment
		(start 165.968934 -388.892288)
		(end 165.980364 -389.000492)
		(width 0.14732)
		(layer "In13.Cu")
		(net "P5E_CPU1_PE2_RX_DN<0>")
	)
	(segment
		(start 132.379466 -199.25919)
		(end 138.361674 -199.25919)
		(width 0.14732)
		(layer "In13.Cu")
		(net "P5E_CPU1_PE2_RX_DN<0>")
	)
	(segment
		(start 121.225564 -216.574878)
		(end 121.234454 -216.569798)
		(width 0.0889)
		(layer "In13.Cu")
		(net "P5E_CPU1_PE2_RX_DN<0>")
	)
	(segment
		(start 166.487094 -411.089348)
		(end 157.873192 -422.165018)
		(width 0.14732)
		(layer "In13.Cu")
		(net "P5E_CPU1_PE2_RX_DN<0>")
	)
	(segment
		(start 122.979688 -208.658968)
		(end 132.379466 -199.25919)
		(width 0.14732)
		(layer "In13.Cu")
		(net "P5E_CPU1_PE2_RX_DN<0>")
	)
	(segment
		(start 121.841006 -213.257638)
		(end 121.841006 -211.408264)
		(width 0.14732)
		(layer "In13.Cu")
		(net "P5E_CPU1_PE2_RX_DN<0>")
	)
	(segment
		(start 157.873192 -422.165018)
		(end 157.895036 -422.33977)
		(width 0.14732)
		(layer "In13.Cu")
		(net "P5E_CPU1_PE2_RX_DN<0>")
	)
	(segment
		(start 165.045644 -361.39755)
		(end 165.968934 -388.892288)
		(width 0.14732)
		(layer "In13.Cu")
		(net "P5E_CPU1_PE2_RX_DN<0>")
	)
	(arc
		(start 121.234454 -218.197684)
		(mid 121.41293 -217.878406)
		(end 121.234454 -217.559128)
		(width 0.0889)
		(layer "In13.Cu")
		(net "P5E_CPU1_PE2_RX_DN<0>")
	)
	(arc
		(start 121.413016 -216.235026)
		(mid 121.492386 -215.961292)
		(end 121.69521 -215.761062)
		(width 0.0889)
		(layer "In13.Cu")
		(net "P5E_CPU1_PE2_RX_DN<0>")
	)
	(arc
		(start 121.234454 -216.569798)
		(mid 121.365368 -216.433438)
		(end 121.413016 -216.25052)
		(width 0.0889)
		(layer "In13.Cu")
		(net "P5E_CPU1_PE2_RX_DN<0>")
	)
	(arc
		(start 121.89841 -213.969092)
		(mid 121.890309 -213.949419)
		(end 121.882916 -213.929468)
		(width 0.0889)
		(layer "In13.Cu")
		(net "P5E_CPU1_PE2_RX_DN<0>")
	)
	(arc
		(start 121.219468 -219.178124)
		(mid 120.942894 -218.692222)
		(end 121.219468 -218.20632)
		(width 0.0889)
		(layer "In13.Cu")
		(net "P5E_CPU1_PE2_RX_DN<0>")
	)
	(arc
		(start 121.7041 -215.755982)
		(mid 121.835014 -215.619622)
		(end 121.882662 -215.436704)
		(width 0.0889)
		(layer "In13.Cu")
		(net "P5E_CPU1_PE2_RX_DN<0>")
	)
	(arc
		(start 121.882662 -215.414606)
		(mid 121.963573 -215.144478)
		(end 122.164856 -214.946992)
		(width 0.0889)
		(layer "In13.Cu")
		(net "P5E_CPU1_PE2_RX_DN<0>")
	)
	(arc
		(start 122.173746 -214.941912)
		(mid 122.30466 -214.805552)
		(end 122.352308 -214.622634)
		(width 0.0889)
		(layer "In13.Cu")
		(net "P5E_CPU1_PE2_RX_DN<0>")
	)
	(arc
		(start 122.352308 -214.461344)
		(mid 122.277303 -214.345885)
		(end 122.168158 -214.261954)
		(width 0.0889)
		(layer "In13.Cu")
		(net "P5E_CPU1_PE2_RX_DN<0>")
	)
	(arc
		(start 121.234454 -219.825316)
		(mid 121.413051 -219.506038)
		(end 121.234454 -219.18676)
		(width 0.0889)
		(layer "In13.Cu")
		(net "P5E_CPU1_PE2_RX_DN<0>")
	)
	(arc
		(start 120.942862 -220.319854)
		(mid 121.015097 -220.04333)
		(end 121.213372 -219.837508)
		(width 0.0889)
		(layer "In13.Cu")
		(net "P5E_CPU1_PE2_RX_DN<0>")
	)
	(arc
		(start 121.225564 -217.554048)
		(mid 121.020492 -217.350369)
		(end 120.942862 -217.071956)
		(width 0.0889)
		(layer "In13.Cu")
		(net "P5E_CPU1_PE2_RX_DN<0>")
	)
	(arc
		(start 120.802908 -220.6117)
		(mid 120.906053 -220.481675)
		(end 120.942862 -220.319854)
		(width 0.0889)
		(layer "In13.Cu")
		(net "P5E_CPU1_PE2_RX_DN<0>")
	)
	(arc
		(start 122.168412 -214.261954)
		(mid 122.008307 -214.138661)
		(end 121.89841 -213.969092)
		(width 0.0889)
		(layer "In13.Cu")
		(net "P5E_CPU1_PE2_RX_DN<0>")
	)
	(arc
		(start 120.942862 -217.064336)
		(mid 121.015097 -216.787812)
		(end 121.213372 -216.58199)
		(width 0.0889)
		(layer "In13.Cu")
		(net "P5E_CPU1_PE2_RX_DN<0>")
	)
	(segment
		(start 32.297878 -17.61236)
		(end 32.598868 -17.31137)
		(width 0.13208)
		(layer "F.Cu")
		(net "P5E_CPU1_PE1_TX_DP<9>")
	)
	(segment
		(start 32.598868 -17.31137)
		(end 32.598868 -16.692626)
		(width 0.13208)
		(layer "F.Cu")
		(net "P5E_CPU1_PE1_TX_DP<9>")
	)
	(segment
		(start 32.598868 -16.692626)
		(end 32.272478 -16.366236)
		(width 0.13208)
		(layer "F.Cu")
		(net "P5E_CPU1_PE1_TX_DP<9>")
	)
	(segment
		(start 110.700566 -224.925382)
		(end 110.700566 -224.389442)
		(width 0.13208)
		(layer "F.Cu")
		(net "P5E_CPU1_PE1_TX_DP<9>")
	)
	(segment
		(start 110.605062 -215.436704)
		(end 110.605062 -215.275414)
		(width 0.0889)
		(layer "In2.Cu")
		(net "P5E_CPU1_PE1_TX_DP<9>")
	)
	(segment
		(start 110.887764 -221.458282)
		(end 110.896654 -221.453202)
		(width 0.0889)
		(layer "In2.Cu")
		(net "P5E_CPU1_PE1_TX_DP<9>")
	)
	(segment
		(start 110.423198 -218.370912)
		(end 110.421166 -218.369896)
		(width 0.0889)
		(layer "In2.Cu")
		(net "P5E_CPU1_PE1_TX_DP<9>")
	)
	(segment
		(start 110.420912 -215.076024)
		(end 110.13567 -214.790782)
		(width 0.0889)
		(layer "In2.Cu")
		(net "P5E_CPU1_PE1_TX_DP<9>")
	)
	(segment
		(start 110.09376 -212.108034)
		(end 106.853482 -189.098428)
		(width 0.14732)
		(layer "In2.Cu")
		(net "P5E_CPU1_PE1_TX_DP<9>")
	)
	(segment
		(start 106.853482 -189.098428)
		(end 105.874312 -185.31078)
		(width 0.14732)
		(layer "In2.Cu")
		(net "P5E_CPU1_PE1_TX_DP<9>")
	)
	(segment
		(start 110.42523 -218.372182)
		(end 110.423198 -218.370912)
		(width 0.0889)
		(layer "In2.Cu")
		(net "P5E_CPU1_PE1_TX_DP<9>")
	)
	(segment
		(start 110.605316 -221.94774)
		(end 110.605316 -221.937834)
		(width 0.0889)
		(layer "In2.Cu")
		(net "P5E_CPU1_PE1_TX_DP<9>")
	)
	(segment
		(start 71.641462 -96.00819)
		(end 53.401722 -56.226964)
		(width 0.14732)
		(layer "In2.Cu")
		(net "P5E_CPU1_PE1_TX_DP<9>")
	)
	(segment
		(start 110.421166 -219.014548)
		(end 110.42523 -219.012516)
		(width 0.0889)
		(layer "In2.Cu")
		(net "P5E_CPU1_PE1_TX_DP<9>")
	)
	(segment
		(start 110.135416 -219.515944)
		(end 110.135416 -219.496132)
		(width 0.0889)
		(layer "In2.Cu")
		(net "P5E_CPU1_PE1_TX_DP<9>")
	)
	(segment
		(start 110.42523 -219.012516)
		(end 110.426754 -219.0115)
		(width 0.0889)
		(layer "In2.Cu")
		(net "P5E_CPU1_PE1_TX_DP<9>")
	)
	(segment
		(start 110.41761 -215.761062)
		(end 110.423198 -215.75776)
		(width 0.0889)
		(layer "In2.Cu")
		(net "P5E_CPU1_PE1_TX_DP<9>")
	)
	(segment
		(start 110.41761 -219.016834)
		(end 110.421166 -219.014548)
		(width 0.0889)
		(layer "In2.Cu")
		(net "P5E_CPU1_PE1_TX_DP<9>")
	)
	(segment
		(start 110.418626 -218.368372)
		(end 110.417864 -218.367864)
		(width 0.0889)
		(layer "In2.Cu")
		(net "P5E_CPU1_PE1_TX_DP<9>")
	)
	(segment
		(start 110.423198 -215.75776)
		(end 110.4265 -215.755982)
		(width 0.0889)
		(layer "In2.Cu")
		(net "P5E_CPU1_PE1_TX_DP<9>")
	)
	(segment
		(start 110.426754 -216.745058)
		(end 110.417864 -216.739978)
		(width 0.0889)
		(layer "In2.Cu")
		(net "P5E_CPU1_PE1_TX_DP<9>")
	)
	(segment
		(start 110.700566 -224.389442)
		(end 110.85703 -224.118424)
		(width 0.0889)
		(layer "In2.Cu")
		(net "P5E_CPU1_PE1_TX_DP<9>")
	)
	(segment
		(start 110.426754 -218.372944)
		(end 110.42523 -218.372182)
		(width 0.0889)
		(layer "In2.Cu")
		(net "P5E_CPU1_PE1_TX_DP<9>")
	)
	(segment
		(start 110.896654 -220.814646)
		(end 110.887764 -220.809566)
		(width 0.0889)
		(layer "In2.Cu")
		(net "P5E_CPU1_PE1_TX_DP<9>")
	)
	(segment
		(start 110.135416 -217.888312)
		(end 110.135416 -217.859864)
		(width 0.0889)
		(layer "In2.Cu")
		(net "P5E_CPU1_PE1_TX_DP<9>")
	)
	(segment
		(start 110.13567 -214.790782)
		(end 110.13567 -213.575138)
		(width 0.0889)
		(layer "In2.Cu")
		(net "P5E_CPU1_PE1_TX_DP<9>")
	)
	(segment
		(start 53.401722 -56.226964)
		(end 32.592518 -19.099276)
		(width 0.14732)
		(layer "In2.Cu")
		(net "P5E_CPU1_PE1_TX_DP<9>")
	)
	(segment
		(start 110.135416 -216.260426)
		(end 110.135416 -216.235026)
		(width 0.0889)
		(layer "In2.Cu")
		(net "P5E_CPU1_PE1_TX_DP<9>")
	)
	(segment
		(start 110.605062 -223.575626)
		(end 110.605062 -223.56699)
		(width 0.0889)
		(layer "In2.Cu")
		(net "P5E_CPU1_PE1_TX_DP<9>")
	)
	(segment
		(start 105.874312 -185.31078)
		(end 71.641462 -96.00819)
		(width 0.14732)
		(layer "In2.Cu")
		(net "P5E_CPU1_PE1_TX_DP<9>")
	)
	(segment
		(start 32.592518 -17.907)
		(end 32.297878 -17.61236)
		(width 0.14732)
		(layer "In2.Cu")
		(net "P5E_CPU1_PE1_TX_DP<9>")
	)
	(segment
		(start 110.417864 -217.388694)
		(end 110.426754 -217.383614)
		(width 0.0889)
		(layer "In2.Cu")
		(net "P5E_CPU1_PE1_TX_DP<9>")
	)
	(segment
		(start 32.592518 -19.099276)
		(end 32.592518 -17.907)
		(width 0.14732)
		(layer "In2.Cu")
		(net "P5E_CPU1_PE1_TX_DP<9>")
	)
	(segment
		(start 110.09376 -213.51113)
		(end 110.09376 -212.108034)
		(width 0.14732)
		(layer "In2.Cu")
		(net "P5E_CPU1_PE1_TX_DP<9>")
	)
	(segment
		(start 110.135416 -222.780098)
		(end 110.135416 -222.75165)
		(width 0.0889)
		(layer "In2.Cu")
		(net "P5E_CPU1_PE1_TX_DP<9>")
	)
	(segment
		(start 110.13567 -213.575138)
		(end 110.09376 -213.533228)
		(width 0.0889)
		(layer "In2.Cu")
		(net "P5E_CPU1_PE1_TX_DP<9>")
	)
	(segment
		(start 110.85703 -224.118424)
		(end 110.8329 -224.02927)
		(width 0.0889)
		(layer "In2.Cu")
		(net "P5E_CPU1_PE1_TX_DP<9>")
	)
	(segment
		(start 110.417864 -219.01658)
		(end 110.41761 -219.016834)
		(width 0.0889)
		(layer "In2.Cu")
		(net "P5E_CPU1_PE1_TX_DP<9>")
	)
	(segment
		(start 110.421166 -218.369896)
		(end 110.418626 -218.368372)
		(width 0.0889)
		(layer "In2.Cu")
		(net "P5E_CPU1_PE1_TX_DP<9>")
	)
	(segment
		(start 110.605062 -220.334078)
		(end 110.605062 -220.311218)
		(width 0.0889)
		(layer "In2.Cu")
		(net "P5E_CPU1_PE1_TX_DP<9>")
	)
	(segment
		(start 110.417864 -222.272098)
		(end 110.426754 -222.267018)
		(width 0.0889)
		(layer "In2.Cu")
		(net "P5E_CPU1_PE1_TX_DP<9>")
	)
	(segment
		(start 110.09376 -213.533228)
		(end 110.09376 -213.51113)
		(width 0.0889)
		(layer "In2.Cu")
		(net "P5E_CPU1_PE1_TX_DP<9>")
	)
	(arc
		(start 110.417864 -223.251268)
		(mid 110.215578 -223.052287)
		(end 110.135416 -222.780098)
		(width 0.0889)
		(layer "In2.Cu")
		(net "P5E_CPU1_PE1_TX_DP<9>")
	)
	(arc
		(start 110.605062 -220.311218)
		(mid 110.552792 -220.128853)
		(end 110.417864 -219.995496)
		(width 0.0889)
		(layer "In2.Cu")
		(net "P5E_CPU1_PE1_TX_DP<9>")
	)
	(arc
		(start 110.135416 -217.859864)
		(mid 110.215578 -217.587675)
		(end 110.417864 -217.388694)
		(width 0.0889)
		(layer "In2.Cu")
		(net "P5E_CPU1_PE1_TX_DP<9>")
	)
	(arc
		(start 110.605316 -221.937834)
		(mid 110.683427 -221.660885)
		(end 110.887764 -221.458282)
		(width 0.0889)
		(layer "In2.Cu")
		(net "P5E_CPU1_PE1_TX_DP<9>")
	)
	(arc
		(start 110.605062 -223.56699)
		(mid 110.552792 -223.384625)
		(end 110.417864 -223.251268)
		(width 0.0889)
		(layer "In2.Cu")
		(net "P5E_CPU1_PE1_TX_DP<9>")
	)
	(arc
		(start 110.426754 -222.267018)
		(mid 110.557668 -222.130658)
		(end 110.605316 -221.94774)
		(width 0.0889)
		(layer "In2.Cu")
		(net "P5E_CPU1_PE1_TX_DP<9>")
	)
	(arc
		(start 110.417864 -219.995496)
		(mid 110.213529 -219.792891)
		(end 110.135416 -219.515944)
		(width 0.0889)
		(layer "In2.Cu")
		(net "P5E_CPU1_PE1_TX_DP<9>")
	)
	(arc
		(start 111.075216 -221.124526)
		(mid 111.02532 -220.946879)
		(end 110.896654 -220.814646)
		(width 0.0889)
		(layer "In2.Cu")
		(net "P5E_CPU1_PE1_TX_DP<9>")
	)
	(arc
		(start 110.135416 -222.75165)
		(mid 110.213527 -222.474701)
		(end 110.417864 -222.272098)
		(width 0.0889)
		(layer "In2.Cu")
		(net "P5E_CPU1_PE1_TX_DP<9>")
	)
	(arc
		(start 110.135416 -216.235026)
		(mid 110.214786 -215.961292)
		(end 110.41761 -215.761062)
		(width 0.0889)
		(layer "In2.Cu")
		(net "P5E_CPU1_PE1_TX_DP<9>")
	)
	(arc
		(start 110.135416 -219.496132)
		(mid 110.213527 -219.219183)
		(end 110.417864 -219.01658)
		(width 0.0889)
		(layer "In2.Cu")
		(net "P5E_CPU1_PE1_TX_DP<9>")
	)
	(arc
		(start 110.417864 -216.739978)
		(mid 110.213529 -216.537373)
		(end 110.135416 -216.260426)
		(width 0.0889)
		(layer "In2.Cu")
		(net "P5E_CPU1_PE1_TX_DP<9>")
	)
	(arc
		(start 110.8329 -224.02927)
		(mid 110.665146 -223.829492)
		(end 110.605062 -223.575626)
		(width 0.0889)
		(layer "In2.Cu")
		(net "P5E_CPU1_PE1_TX_DP<9>")
	)
	(arc
		(start 110.605062 -215.275414)
		(mid 110.530057 -215.159955)
		(end 110.420912 -215.076024)
		(width 0.0889)
		(layer "In2.Cu")
		(net "P5E_CPU1_PE1_TX_DP<9>")
	)
	(arc
		(start 110.417864 -218.367864)
		(mid 110.213529 -218.165259)
		(end 110.135416 -217.888312)
		(width 0.0889)
		(layer "In2.Cu")
		(net "P5E_CPU1_PE1_TX_DP<9>")
	)
	(arc
		(start 110.896654 -221.453202)
		(mid 111.025943 -221.319716)
		(end 111.075216 -221.140528)
		(width 0.0889)
		(layer "In2.Cu")
		(net "P5E_CPU1_PE1_TX_DP<9>")
	)
	(arc
		(start 110.605062 -217.076528)
		(mid 110.605307 -217.067132)
		(end 110.605316 -217.057732)
		(width 0.0889)
		(layer "In2.Cu")
		(net "P5E_CPU1_PE1_TX_DP<9>")
	)
	(arc
		(start 110.605316 -217.057732)
		(mid 110.556063 -216.878532)
		(end 110.426754 -216.745058)
		(width 0.0889)
		(layer "In2.Cu")
		(net "P5E_CPU1_PE1_TX_DP<9>")
	)
	(arc
		(start 110.426754 -219.0115)
		(mid 110.605351 -218.692222)
		(end 110.426754 -218.372944)
		(width 0.0889)
		(layer "In2.Cu")
		(net "P5E_CPU1_PE1_TX_DP<9>")
	)
	(arc
		(start 110.4265 -215.755982)
		(mid 110.557414 -215.619622)
		(end 110.605062 -215.436704)
		(width 0.0889)
		(layer "In2.Cu")
		(net "P5E_CPU1_PE1_TX_DP<9>")
	)
	(arc
		(start 110.887764 -220.809566)
		(mid 110.684283 -220.608762)
		(end 110.605062 -220.334078)
		(width 0.0889)
		(layer "In2.Cu")
		(net "P5E_CPU1_PE1_TX_DP<9>")
	)
	(arc
		(start 110.426754 -217.383614)
		(mid 110.554565 -217.252521)
		(end 110.605062 -217.076528)
		(width 0.0889)
		(layer "In2.Cu")
		(net "P5E_CPU1_PE1_TX_DP<9>")
	)
	(arc
		(start 111.075216 -221.140528)
		(mid 111.075299 -221.132527)
		(end 111.075216 -221.124526)
		(width 0.0889)
		(layer "In2.Cu")
		(net "P5E_CPU1_PE1_TX_DP<9>")
	)
	(segment
		(start 112.110266 -225.739198)
		(end 112.110266 -225.203512)
		(width 0.13208)
		(layer "F.Cu")
		(net "P5E_CPU1_PE1_TX_DP<8>")
	)
	(segment
		(start 35.651948 -18.83283)
		(end 35.651948 -18.219166)
		(width 0.13208)
		(layer "F.Cu")
		(net "P5E_CPU1_PE1_TX_DP<8>")
	)
	(segment
		(start 112.110266 -225.203512)
		(end 112.110012 -225.203258)
		(width 0.13208)
		(layer "F.Cu")
		(net "P5E_CPU1_PE1_TX_DP<8>")
	)
	(segment
		(start 35.651948 -18.219166)
		(end 35.980878 -17.890236)
		(width 0.13208)
		(layer "F.Cu")
		(net "P5E_CPU1_PE1_TX_DP<8>")
	)
	(segment
		(start 35.955478 -19.13636)
		(end 35.651948 -18.83283)
		(width 0.13208)
		(layer "F.Cu")
		(net "P5E_CPU1_PE1_TX_DP<8>")
	)
	(segment
		(start 111.30788 -213.533228)
		(end 111.30788 -213.51113)
		(width 0.0889)
		(layer "In2.Cu")
		(net "P5E_CPU1_PE1_TX_DP<8>")
	)
	(segment
		(start 111.453168 -219.830396)
		(end 111.444278 -219.825316)
		(width 0.0889)
		(layer "In2.Cu")
		(net "P5E_CPU1_PE1_TX_DP<8>")
	)
	(segment
		(start 111.735616 -223.575626)
		(end 111.735616 -223.561402)
		(width 0.0889)
		(layer "In2.Cu")
		(net "P5E_CPU1_PE1_TX_DP<8>")
	)
	(segment
		(start 35.660838 -19.431)
		(end 35.955478 -19.13636)
		(width 0.14732)
		(layer "In2.Cu")
		(net "P5E_CPU1_PE1_TX_DP<8>")
	)
	(segment
		(start 111.265716 -214.603076)
		(end 111.265716 -213.575392)
		(width 0.0889)
		(layer "In2.Cu")
		(net "P5E_CPU1_PE1_TX_DP<8>")
	)
	(segment
		(start 111.265716 -213.575392)
		(end 111.30788 -213.533228)
		(width 0.0889)
		(layer "In2.Cu")
		(net "P5E_CPU1_PE1_TX_DP<8>")
	)
	(segment
		(start 111.30788 -213.51113)
		(end 111.30788 -212.18017)
		(width 0.14732)
		(layer "In2.Cu")
		(net "P5E_CPU1_PE1_TX_DP<8>")
	)
	(segment
		(start 112.205516 -224.389442)
		(end 112.205516 -224.379536)
		(width 0.0889)
		(layer "In2.Cu")
		(net "P5E_CPU1_PE1_TX_DP<8>")
	)
	(segment
		(start 111.953548 -224.93224)
		(end 111.977678 -224.843086)
		(width 0.0889)
		(layer "In2.Cu")
		(net "P5E_CPU1_PE1_TX_DP<8>")
	)
	(segment
		(start 35.660838 -19.920204)
		(end 35.660838 -19.431)
		(width 0.14732)
		(layer "In2.Cu")
		(net "P5E_CPU1_PE1_TX_DP<8>")
	)
	(segment
		(start 112.205516 -221.133924)
		(end 112.205516 -221.115382)
		(width 0.0889)
		(layer "In2.Cu")
		(net "P5E_CPU1_PE1_TX_DP<8>")
	)
	(segment
		(start 111.91494 -223.895412)
		(end 111.914178 -223.894904)
		(width 0.0889)
		(layer "In2.Cu")
		(net "P5E_CPU1_PE1_TX_DP<8>")
	)
	(segment
		(start 72.571864 -95.048324)
		(end 53.938932 -54.409594)
		(width 0.14732)
		(layer "In2.Cu")
		(net "P5E_CPU1_PE1_TX_DP<8>")
	)
	(segment
		(start 111.921036 -220.642942)
		(end 111.919004 -220.641926)
		(width 0.0889)
		(layer "In2.Cu")
		(net "P5E_CPU1_PE1_TX_DP<8>")
	)
	(segment
		(start 111.453168 -216.574878)
		(end 111.444278 -216.569798)
		(width 0.0889)
		(layer "In2.Cu")
		(net "P5E_CPU1_PE1_TX_DP<8>")
	)
	(segment
		(start 111.735362 -218.71432)
		(end 111.735616 -218.692222)
		(width 0.0889)
		(layer "In2.Cu")
		(net "P5E_CPU1_PE1_TX_DP<8>")
	)
	(segment
		(start 111.454692 -216.576148)
		(end 111.453168 -216.574878)
		(width 0.0889)
		(layer "In2.Cu")
		(net "P5E_CPU1_PE1_TX_DP<8>")
	)
	(segment
		(start 111.920528 -223.89846)
		(end 111.919766 -223.897952)
		(width 0.0889)
		(layer "In2.Cu")
		(net "P5E_CPU1_PE1_TX_DP<8>")
	)
	(segment
		(start 111.923068 -223.899984)
		(end 111.922306 -223.899476)
		(width 0.0889)
		(layer "In2.Cu")
		(net "P5E_CPU1_PE1_TX_DP<8>")
	)
	(segment
		(start 107.065064 -185.033412)
		(end 72.571864 -95.048324)
		(width 0.14732)
		(layer "In2.Cu")
		(net "P5E_CPU1_PE1_TX_DP<8>")
	)
	(segment
		(start 108.20146 -189.452758)
		(end 107.065064 -185.033412)
		(width 0.14732)
		(layer "In2.Cu")
		(net "P5E_CPU1_PE1_TX_DP<8>")
	)
	(segment
		(start 111.735616 -218.692222)
		(end 111.735616 -218.683586)
		(width 0.0889)
		(layer "In2.Cu")
		(net "P5E_CPU1_PE1_TX_DP<8>")
	)
	(segment
		(start 111.919766 -223.897952)
		(end 111.91494 -223.895412)
		(width 0.0889)
		(layer "In2.Cu")
		(net "P5E_CPU1_PE1_TX_DP<8>")
	)
	(segment
		(start 111.274098 -211.671408)
		(end 108.20146 -189.452758)
		(width 0.14732)
		(layer "In2.Cu")
		(net "P5E_CPU1_PE1_TX_DP<8>")
	)
	(segment
		(start 111.735616 -221.957646)
		(end 111.735616 -221.939104)
		(width 0.0889)
		(layer "In2.Cu")
		(net "P5E_CPU1_PE1_TX_DP<8>")
	)
	(segment
		(start 111.922814 -221.623382)
		(end 111.923576 -221.622874)
		(width 0.0889)
		(layer "In2.Cu")
		(net "P5E_CPU1_PE1_TX_DP<8>")
	)
	(segment
		(start 112.110012 -225.203258)
		(end 111.953548 -224.93224)
		(width 0.0889)
		(layer "In2.Cu")
		(net "P5E_CPU1_PE1_TX_DP<8>")
	)
	(segment
		(start 111.918496 -217.386662)
		(end 111.916972 -217.3859)
		(width 0.0889)
		(layer "In2.Cu")
		(net "P5E_CPU1_PE1_TX_DP<8>")
	)
	(segment
		(start 111.449866 -214.907114)
		(end 111.449358 -214.907622)
		(width 0.0889)
		(layer "In2.Cu")
		(net "P5E_CPU1_PE1_TX_DP<8>")
	)
	(segment
		(start 111.444278 -219.18676)
		(end 111.453168 -219.18168)
		(width 0.0889)
		(layer "In2.Cu")
		(net "P5E_CPU1_PE1_TX_DP<8>")
	)
	(segment
		(start 53.938932 -54.409594)
		(end 35.660838 -19.920204)
		(width 0.14732)
		(layer "In2.Cu")
		(net "P5E_CPU1_PE1_TX_DP<8>")
	)
	(segment
		(start 111.453168 -223.085914)
		(end 111.444278 -223.080834)
		(width 0.0889)
		(layer "In2.Cu")
		(net "P5E_CPU1_PE1_TX_DP<8>")
	)
	(segment
		(start 111.924084 -218.367102)
		(end 111.935006 -218.360752)
		(width 0.0889)
		(layer "In2.Cu")
		(net "P5E_CPU1_PE1_TX_DP<8>")
	)
	(segment
		(start 111.735616 -217.065606)
		(end 111.73587 -217.0557)
		(width 0.0889)
		(layer "In2.Cu")
		(net "P5E_CPU1_PE1_TX_DP<8>")
	)
	(segment
		(start 111.444278 -222.442278)
		(end 111.453168 -222.437198)
		(width 0.0889)
		(layer "In2.Cu")
		(net "P5E_CPU1_PE1_TX_DP<8>")
	)
	(segment
		(start 111.916972 -217.3859)
		(end 111.90859 -217.381074)
		(width 0.0889)
		(layer "In2.Cu")
		(net "P5E_CPU1_PE1_TX_DP<8>")
	)
	(segment
		(start 111.922306 -223.899476)
		(end 111.920528 -223.89846)
		(width 0.0889)
		(layer "In2.Cu")
		(net "P5E_CPU1_PE1_TX_DP<8>")
	)
	(segment
		(start 111.921798 -217.38844)
		(end 111.918496 -217.386662)
		(width 0.0889)
		(layer "In2.Cu")
		(net "P5E_CPU1_PE1_TX_DP<8>")
	)
	(segment
		(start 111.444278 -215.931242)
		(end 111.453168 -215.926162)
		(width 0.0889)
		(layer "In2.Cu")
		(net "P5E_CPU1_PE1_TX_DP<8>")
	)
	(segment
		(start 111.919004 -220.641926)
		(end 111.914178 -220.639132)
		(width 0.0889)
		(layer "In2.Cu")
		(net "P5E_CPU1_PE1_TX_DP<8>")
	)
	(segment
		(start 111.30788 -212.18017)
		(end 111.274098 -211.671408)
		(width 0.14732)
		(layer "In2.Cu")
		(net "P5E_CPU1_PE1_TX_DP<8>")
	)
	(segment
		(start 111.26597 -214.602822)
		(end 111.265716 -214.603076)
		(width 0.0889)
		(layer "In2.Cu")
		(net "P5E_CPU1_PE1_TX_DP<8>")
	)
	(segment
		(start 111.923068 -220.644212)
		(end 111.921036 -220.642942)
		(width 0.0889)
		(layer "In2.Cu")
		(net "P5E_CPU1_PE1_TX_DP<8>")
	)
	(segment
		(start 111.922814 -218.367864)
		(end 111.924084 -218.367102)
		(width 0.0889)
		(layer "In2.Cu")
		(net "P5E_CPU1_PE1_TX_DP<8>")
	)
	(segment
		(start 111.923576 -221.622874)
		(end 111.92891 -221.619826)
		(width 0.0889)
		(layer "In2.Cu")
		(net "P5E_CPU1_PE1_TX_DP<8>")
	)
	(segment
		(start 111.459264 -219.833952)
		(end 111.453168 -219.830396)
		(width 0.0889)
		(layer "In2.Cu")
		(net "P5E_CPU1_PE1_TX_DP<8>")
	)
	(segment
		(start 112.205516 -217.878406)
		(end 112.205516 -217.864182)
		(width 0.0889)
		(layer "In2.Cu")
		(net "P5E_CPU1_PE1_TX_DP<8>")
	)
	(segment
		(start 111.735362 -215.452198)
		(end 111.735362 -215.23833)
		(width 0.0889)
		(layer "In2.Cu")
		(net "P5E_CPU1_PE1_TX_DP<8>")
	)
	(segment
		(start 111.923068 -217.388694)
		(end 111.921798 -217.38844)
		(width 0.0889)
		(layer "In2.Cu")
		(net "P5E_CPU1_PE1_TX_DP<8>")
	)
	(arc
		(start 111.977678 -224.843086)
		(mid 111.98625 -224.836564)
		(end 111.994696 -224.829878)
		(width 0.0889)
		(layer "In2.Cu")
		(net "P5E_CPU1_PE1_TX_DP<8>")
	)
	(arc
		(start 111.914178 -223.894904)
		(mid 111.783264 -223.758544)
		(end 111.735616 -223.575626)
		(width 0.0889)
		(layer "In2.Cu")
		(net "P5E_CPU1_PE1_TX_DP<8>")
	)
	(arc
		(start 111.265716 -219.516198)
		(mid 111.310884 -219.327551)
		(end 111.444278 -219.18676)
		(width 0.0889)
		(layer "In2.Cu")
		(net "P5E_CPU1_PE1_TX_DP<8>")
	)
	(arc
		(start 112.205516 -221.115382)
		(mid 112.125354 -220.843193)
		(end 111.923068 -220.644212)
		(width 0.0889)
		(layer "In2.Cu")
		(net "P5E_CPU1_PE1_TX_DP<8>")
	)
	(arc
		(start 111.994696 -224.829878)
		(mid 112.150094 -224.633597)
		(end 112.205516 -224.389442)
		(width 0.0889)
		(layer "In2.Cu")
		(net "P5E_CPU1_PE1_TX_DP<8>")
	)
	(arc
		(start 111.90859 -217.381074)
		(mid 111.781845 -217.245433)
		(end 111.735616 -217.065606)
		(width 0.0889)
		(layer "In2.Cu")
		(net "P5E_CPU1_PE1_TX_DP<8>")
	)
	(arc
		(start 111.444278 -223.080834)
		(mid 111.317024 -222.950868)
		(end 111.26597 -222.776288)
		(width 0.0889)
		(layer "In2.Cu")
		(net "P5E_CPU1_PE1_TX_DP<8>")
	)
	(arc
		(start 111.453168 -219.18168)
		(mid 111.65438 -218.984312)
		(end 111.735362 -218.71432)
		(width 0.0889)
		(layer "In2.Cu")
		(net "P5E_CPU1_PE1_TX_DP<8>")
	)
	(arc
		(start 111.453168 -222.437198)
		(mid 111.657503 -222.234593)
		(end 111.735616 -221.957646)
		(width 0.0889)
		(layer "In2.Cu")
		(net "P5E_CPU1_PE1_TX_DP<8>")
	)
	(arc
		(start 111.453168 -215.926162)
		(mid 111.655991 -215.725931)
		(end 111.735362 -215.452198)
		(width 0.0889)
		(layer "In2.Cu")
		(net "P5E_CPU1_PE1_TX_DP<8>")
	)
	(arc
		(start 112.205516 -217.864182)
		(mid 112.126375 -217.589559)
		(end 111.923068 -217.388694)
		(width 0.0889)
		(layer "In2.Cu")
		(net "P5E_CPU1_PE1_TX_DP<8>")
	)
	(arc
		(start 111.935006 -218.360752)
		(mid 112.133234 -218.154904)
		(end 112.205516 -217.878406)
		(width 0.0889)
		(layer "In2.Cu")
		(net "P5E_CPU1_PE1_TX_DP<8>")
	)
	(arc
		(start 111.735616 -218.683586)
		(mid 111.787886 -218.501221)
		(end 111.922814 -218.367864)
		(width 0.0889)
		(layer "In2.Cu")
		(net "P5E_CPU1_PE1_TX_DP<8>")
	)
	(arc
		(start 111.444278 -216.569798)
		(mid 111.315074 -216.436284)
		(end 111.26597 -216.257124)
		(width 0.0889)
		(layer "In2.Cu")
		(net "P5E_CPU1_PE1_TX_DP<8>")
	)
	(arc
		(start 111.444278 -219.825316)
		(mid 111.315874 -219.693371)
		(end 111.265716 -219.516198)
		(width 0.0889)
		(layer "In2.Cu")
		(net "P5E_CPU1_PE1_TX_DP<8>")
	)
	(arc
		(start 111.914178 -220.639132)
		(mid 111.783264 -220.502772)
		(end 111.735616 -220.319854)
		(width 0.0889)
		(layer "In2.Cu")
		(net "P5E_CPU1_PE1_TX_DP<8>")
	)
	(arc
		(start 111.26597 -216.257124)
		(mid 111.265876 -216.248742)
		(end 111.26597 -216.24036)
		(width 0.0889)
		(layer "In2.Cu")
		(net "P5E_CPU1_PE1_TX_DP<8>")
	)
	(arc
		(start 111.735362 -215.23833)
		(mid 111.623942 -215.045711)
		(end 111.449866 -214.907114)
		(width 0.0889)
		(layer "In2.Cu")
		(net "P5E_CPU1_PE1_TX_DP<8>")
	)
	(arc
		(start 111.449358 -214.907622)
		(mid 111.315331 -214.780702)
		(end 111.26597 -214.602822)
		(width 0.0889)
		(layer "In2.Cu")
		(net "P5E_CPU1_PE1_TX_DP<8>")
	)
	(arc
		(start 111.26597 -216.24036)
		(mid 111.315985 -216.063229)
		(end 111.444278 -215.931242)
		(width 0.0889)
		(layer "In2.Cu")
		(net "P5E_CPU1_PE1_TX_DP<8>")
	)
	(arc
		(start 111.735616 -221.939104)
		(mid 111.787886 -221.756739)
		(end 111.922814 -221.623382)
		(width 0.0889)
		(layer "In2.Cu")
		(net "P5E_CPU1_PE1_TX_DP<8>")
	)
	(arc
		(start 111.735616 -220.319854)
		(mid 111.6617 -220.040352)
		(end 111.459264 -219.833952)
		(width 0.0889)
		(layer "In2.Cu")
		(net "P5E_CPU1_PE1_TX_DP<8>")
	)
	(arc
		(start 111.26597 -222.776288)
		(mid 111.265773 -222.768923)
		(end 111.265716 -222.761556)
		(width 0.0889)
		(layer "In2.Cu")
		(net "P5E_CPU1_PE1_TX_DP<8>")
	)
	(arc
		(start 111.92891 -221.619826)
		(mid 112.131497 -221.413475)
		(end 112.205516 -221.133924)
		(width 0.0889)
		(layer "In2.Cu")
		(net "P5E_CPU1_PE1_TX_DP<8>")
	)
	(arc
		(start 112.205516 -224.379536)
		(mid 112.127405 -224.102587)
		(end 111.923068 -223.899984)
		(width 0.0889)
		(layer "In2.Cu")
		(net "P5E_CPU1_PE1_TX_DP<8>")
	)
	(arc
		(start 111.735616 -223.561402)
		(mid 111.656475 -223.286779)
		(end 111.453168 -223.085914)
		(width 0.0889)
		(layer "In2.Cu")
		(net "P5E_CPU1_PE1_TX_DP<8>")
	)
	(arc
		(start 111.73587 -217.0557)
		(mid 111.658316 -216.778962)
		(end 111.454692 -216.576148)
		(width 0.0889)
		(layer "In2.Cu")
		(net "P5E_CPU1_PE1_TX_DP<8>")
	)
	(arc
		(start 111.265716 -222.761556)
		(mid 111.313395 -222.578656)
		(end 111.444278 -222.442278)
		(width 0.0889)
		(layer "In2.Cu")
		(net "P5E_CPU1_PE1_TX_DP<8>")
	)
	(segment
		(start 38.186868 -16.692626)
		(end 37.860478 -16.366236)
		(width 0.13208)
		(layer "F.Cu")
		(net "P5E_CPU1_PE1_TX_DP<7>")
	)
	(segment
		(start 112.579912 -224.925382)
		(end 112.579912 -224.389696)
		(width 0.13208)
		(layer "F.Cu")
		(net "P5E_CPU1_PE1_TX_DP<7>")
	)
	(segment
		(start 38.186868 -17.31137)
		(end 38.186868 -16.692626)
		(width 0.13208)
		(layer "F.Cu")
		(net "P5E_CPU1_PE1_TX_DP<7>")
	)
	(segment
		(start 37.885878 -17.61236)
		(end 38.186868 -17.31137)
		(width 0.13208)
		(layer "F.Cu")
		(net "P5E_CPU1_PE1_TX_DP<7>")
	)
	(segment
		(start 112.579912 -224.389696)
		(end 112.580166 -224.389442)
		(width 0.13208)
		(layer "F.Cu")
		(net "P5E_CPU1_PE1_TX_DP<7>")
	)
	(segment
		(start 112.29467 -216.7382)
		(end 112.293654 -216.737692)
		(width 0.0889)
		(layer "In2.Cu")
		(net "P5E_CPU1_PE1_TX_DP<7>")
	)
	(segment
		(start 112.014762 -214.801958)
		(end 112.014762 -213.575138)
		(width 0.0889)
		(layer "In2.Cu")
		(net "P5E_CPU1_PE1_TX_DP<7>")
	)
	(segment
		(start 112.484662 -215.436704)
		(end 112.484916 -215.43645)
		(width 0.0889)
		(layer "In2.Cu")
		(net "P5E_CPU1_PE1_TX_DP<7>")
	)
	(segment
		(start 112.014762 -216.25052)
		(end 112.014762 -216.240614)
		(width 0.0889)
		(layer "In2.Cu")
		(net "P5E_CPU1_PE1_TX_DP<7>")
	)
	(segment
		(start 111.972852 -213.51113)
		(end 111.972852 -211.834222)
		(width 0.14732)
		(layer "In2.Cu")
		(net "P5E_CPU1_PE1_TX_DP<7>")
	)
	(segment
		(start 107.808268 -185.130694)
		(end 107.808522 -185.131202)
		(width 0.14732)
		(layer "In2.Cu")
		(net "P5E_CPU1_PE1_TX_DP<7>")
	)
	(segment
		(start 112.015016 -222.780098)
		(end 112.015016 -222.746062)
		(width 0.0889)
		(layer "In2.Cu")
		(net "P5E_CPU1_PE1_TX_DP<7>")
	)
	(segment
		(start 112.484662 -223.575626)
		(end 112.484662 -223.56699)
		(width 0.0889)
		(layer "In2.Cu")
		(net "P5E_CPU1_PE1_TX_DP<7>")
	)
	(segment
		(start 112.767364 -218.202764)
		(end 112.776254 -218.197684)
		(width 0.0889)
		(layer "In2.Cu")
		(net "P5E_CPU1_PE1_TX_DP<7>")
	)
	(segment
		(start 112.776254 -217.559128)
		(end 112.767364 -217.554048)
		(width 0.0889)
		(layer "In2.Cu")
		(net "P5E_CPU1_PE1_TX_DP<7>")
	)
	(segment
		(start 108.828332 -189.095888)
		(end 107.808268 -185.130694)
		(width 0.14732)
		(layer "In2.Cu")
		(net "P5E_CPU1_PE1_TX_DP<7>")
	)
	(segment
		(start 112.293654 -216.737692)
		(end 112.291368 -216.736422)
		(width 0.0889)
		(layer "In2.Cu")
		(net "P5E_CPU1_PE1_TX_DP<7>")
	)
	(segment
		(start 112.484662 -220.334078)
		(end 112.484662 -220.311218)
		(width 0.0889)
		(layer "In2.Cu")
		(net "P5E_CPU1_PE1_TX_DP<7>")
	)
	(segment
		(start 112.275112 -215.062308)
		(end 112.014762 -214.801958)
		(width 0.0889)
		(layer "In2.Cu")
		(net "P5E_CPU1_PE1_TX_DP<7>")
	)
	(segment
		(start 73.034652 -94.420944)
		(end 38.180518 -18.405602)
		(width 0.14732)
		(layer "In2.Cu")
		(net "P5E_CPU1_PE1_TX_DP<7>")
	)
	(segment
		(start 112.29721 -222.272098)
		(end 112.3061 -222.267018)
		(width 0.0889)
		(layer "In2.Cu")
		(net "P5E_CPU1_PE1_TX_DP<7>")
	)
	(segment
		(start 112.776254 -220.814646)
		(end 112.767364 -220.809566)
		(width 0.0889)
		(layer "In2.Cu")
		(net "P5E_CPU1_PE1_TX_DP<7>")
	)
	(segment
		(start 107.808522 -185.131202)
		(end 73.034652 -94.420944)
		(width 0.14732)
		(layer "In2.Cu")
		(net "P5E_CPU1_PE1_TX_DP<7>")
	)
	(segment
		(start 112.300766 -215.07577)
		(end 112.275112 -215.062308)
		(width 0.0889)
		(layer "In2.Cu")
		(net "P5E_CPU1_PE1_TX_DP<7>")
	)
	(segment
		(start 111.972852 -213.533228)
		(end 111.972852 -213.51113)
		(width 0.0889)
		(layer "In2.Cu")
		(net "P5E_CPU1_PE1_TX_DP<7>")
	)
	(segment
		(start 112.761268 -221.461838)
		(end 112.767364 -221.458282)
		(width 0.0889)
		(layer "In2.Cu")
		(net "P5E_CPU1_PE1_TX_DP<7>")
	)
	(segment
		(start 38.180518 -17.907)
		(end 37.885878 -17.61236)
		(width 0.14732)
		(layer "In2.Cu")
		(net "P5E_CPU1_PE1_TX_DP<7>")
	)
	(segment
		(start 112.337342 -215.09736)
		(end 112.337596 -215.09736)
		(width 0.0889)
		(layer "In2.Cu")
		(net "P5E_CPU1_PE1_TX_DP<7>")
	)
	(segment
		(start 112.484916 -215.43645)
		(end 112.484916 -215.274398)
		(width 0.0889)
		(layer "In2.Cu")
		(net "P5E_CPU1_PE1_TX_DP<7>")
	)
	(segment
		(start 111.972852 -211.834222)
		(end 108.828332 -189.095888)
		(width 0.14732)
		(layer "In2.Cu")
		(net "P5E_CPU1_PE1_TX_DP<7>")
	)
	(segment
		(start 112.291114 -219.020136)
		(end 112.29721 -219.01658)
		(width 0.0889)
		(layer "In2.Cu")
		(net "P5E_CPU1_PE1_TX_DP<7>")
	)
	(segment
		(start 112.580166 -224.389442)
		(end 112.73663 -224.118424)
		(width 0.0889)
		(layer "In2.Cu")
		(net "P5E_CPU1_PE1_TX_DP<7>")
	)
	(segment
		(start 112.014762 -213.575138)
		(end 111.972852 -213.533228)
		(width 0.0889)
		(layer "In2.Cu")
		(net "P5E_CPU1_PE1_TX_DP<7>")
	)
	(segment
		(start 112.297464 -219.995496)
		(end 112.285272 -219.988384)
		(width 0.0889)
		(layer "In2.Cu")
		(net "P5E_CPU1_PE1_TX_DP<7>")
	)
	(segment
		(start 112.484662 -217.07856)
		(end 112.484662 -217.0557)
		(width 0.0889)
		(layer "In2.Cu")
		(net "P5E_CPU1_PE1_TX_DP<7>")
	)
	(segment
		(start 112.29721 -215.761062)
		(end 112.3061 -215.755982)
		(width 0.0889)
		(layer "In2.Cu")
		(net "P5E_CPU1_PE1_TX_DP<7>")
	)
	(segment
		(start 112.761268 -218.20632)
		(end 112.767364 -218.202764)
		(width 0.0889)
		(layer "In2.Cu")
		(net "P5E_CPU1_PE1_TX_DP<7>")
	)
	(segment
		(start 112.73663 -224.118424)
		(end 112.7125 -224.02927)
		(width 0.0889)
		(layer "In2.Cu")
		(net "P5E_CPU1_PE1_TX_DP<7>")
	)
	(segment
		(start 112.297464 -216.739978)
		(end 112.29467 -216.7382)
		(width 0.0889)
		(layer "In2.Cu")
		(net "P5E_CPU1_PE1_TX_DP<7>")
	)
	(segment
		(start 38.180518 -18.405602)
		(end 38.180518 -17.907)
		(width 0.14732)
		(layer "In2.Cu")
		(net "P5E_CPU1_PE1_TX_DP<7>")
	)
	(segment
		(start 112.767364 -221.458282)
		(end 112.776254 -221.453202)
		(width 0.0889)
		(layer "In2.Cu")
		(net "P5E_CPU1_PE1_TX_DP<7>")
	)
	(segment
		(start 112.29721 -219.01658)
		(end 112.3061 -219.0115)
		(width 0.0889)
		(layer "In2.Cu")
		(net "P5E_CPU1_PE1_TX_DP<7>")
	)
	(arc
		(start 112.337596 -215.09736)
		(mid 112.319465 -215.08608)
		(end 112.300766 -215.07577)
		(width 0.0889)
		(layer "In2.Cu")
		(net "P5E_CPU1_PE1_TX_DP<7>")
	)
	(arc
		(start 112.484662 -218.692222)
		(mid 112.558653 -218.412656)
		(end 112.761268 -218.20632)
		(width 0.0889)
		(layer "In2.Cu")
		(net "P5E_CPU1_PE1_TX_DP<7>")
	)
	(arc
		(start 112.297464 -223.251268)
		(mid 112.095178 -223.052287)
		(end 112.015016 -222.780098)
		(width 0.0889)
		(layer "In2.Cu")
		(net "P5E_CPU1_PE1_TX_DP<7>")
	)
	(arc
		(start 112.3061 -219.0115)
		(mid 112.437014 -218.87514)
		(end 112.484662 -218.692222)
		(width 0.0889)
		(layer "In2.Cu")
		(net "P5E_CPU1_PE1_TX_DP<7>")
	)
	(arc
		(start 112.484662 -221.94774)
		(mid 112.558653 -221.668174)
		(end 112.761268 -221.461838)
		(width 0.0889)
		(layer "In2.Cu")
		(net "P5E_CPU1_PE1_TX_DP<7>")
	)
	(arc
		(start 112.285272 -219.988384)
		(mid 112.087106 -219.782646)
		(end 112.014762 -219.506292)
		(width 0.0889)
		(layer "In2.Cu")
		(net "P5E_CPU1_PE1_TX_DP<7>")
	)
	(arc
		(start 112.3061 -222.267018)
		(mid 112.437014 -222.130658)
		(end 112.484662 -221.94774)
		(width 0.0889)
		(layer "In2.Cu")
		(net "P5E_CPU1_PE1_TX_DP<7>")
	)
	(arc
		(start 112.3061 -215.755982)
		(mid 112.437014 -215.619622)
		(end 112.484662 -215.436704)
		(width 0.0889)
		(layer "In2.Cu")
		(net "P5E_CPU1_PE1_TX_DP<7>")
	)
	(arc
		(start 112.484662 -217.0557)
		(mid 112.432392 -216.873335)
		(end 112.297464 -216.739978)
		(width 0.0889)
		(layer "In2.Cu")
		(net "P5E_CPU1_PE1_TX_DP<7>")
	)
	(arc
		(start 112.014762 -219.506292)
		(mid 112.088615 -219.226646)
		(end 112.291114 -219.020136)
		(width 0.0889)
		(layer "In2.Cu")
		(net "P5E_CPU1_PE1_TX_DP<7>")
	)
	(arc
		(start 112.776254 -218.197684)
		(mid 112.954851 -217.878406)
		(end 112.776254 -217.559128)
		(width 0.0889)
		(layer "In2.Cu")
		(net "P5E_CPU1_PE1_TX_DP<7>")
	)
	(arc
		(start 112.484916 -215.274398)
		(mid 112.4239 -215.175226)
		(end 112.337342 -215.09736)
		(width 0.0889)
		(layer "In2.Cu")
		(net "P5E_CPU1_PE1_TX_DP<7>")
	)
	(arc
		(start 112.7125 -224.02927)
		(mid 112.544746 -223.829492)
		(end 112.484662 -223.575626)
		(width 0.0889)
		(layer "In2.Cu")
		(net "P5E_CPU1_PE1_TX_DP<7>")
	)
	(arc
		(start 112.291368 -216.736422)
		(mid 112.088781 -216.530071)
		(end 112.014762 -216.25052)
		(width 0.0889)
		(layer "In2.Cu")
		(net "P5E_CPU1_PE1_TX_DP<7>")
	)
	(arc
		(start 112.014762 -216.240614)
		(mid 112.092873 -215.963665)
		(end 112.29721 -215.761062)
		(width 0.0889)
		(layer "In2.Cu")
		(net "P5E_CPU1_PE1_TX_DP<7>")
	)
	(arc
		(start 112.776254 -221.453202)
		(mid 112.954851 -221.133924)
		(end 112.776254 -220.814646)
		(width 0.0889)
		(layer "In2.Cu")
		(net "P5E_CPU1_PE1_TX_DP<7>")
	)
	(arc
		(start 112.484662 -220.311218)
		(mid 112.432392 -220.128853)
		(end 112.297464 -219.995496)
		(width 0.0889)
		(layer "In2.Cu")
		(net "P5E_CPU1_PE1_TX_DP<7>")
	)
	(arc
		(start 112.484662 -223.56699)
		(mid 112.432392 -223.384625)
		(end 112.297464 -223.251268)
		(width 0.0889)
		(layer "In2.Cu")
		(net "P5E_CPU1_PE1_TX_DP<7>")
	)
	(arc
		(start 112.767364 -220.809566)
		(mid 112.563883 -220.608762)
		(end 112.484662 -220.334078)
		(width 0.0889)
		(layer "In2.Cu")
		(net "P5E_CPU1_PE1_TX_DP<7>")
	)
	(arc
		(start 112.015016 -222.746062)
		(mid 112.094386 -222.472328)
		(end 112.29721 -222.272098)
		(width 0.0889)
		(layer "In2.Cu")
		(net "P5E_CPU1_PE1_TX_DP<7>")
	)
	(arc
		(start 112.767364 -217.554048)
		(mid 112.563883 -217.353244)
		(end 112.484662 -217.07856)
		(width 0.0889)
		(layer "In2.Cu")
		(net "P5E_CPU1_PE1_TX_DP<7>")
	)
	(segment
		(start 113.989866 -225.203512)
		(end 113.989612 -225.203258)
		(width 0.13208)
		(layer "F.Cu")
		(net "P5E_CPU1_PE1_TX_DP<6>")
	)
	(segment
		(start 41.545764 -18.219166)
		(end 41.874694 -17.890236)
		(width 0.13208)
		(layer "F.Cu")
		(net "P5E_CPU1_PE1_TX_DP<6>")
	)
	(segment
		(start 41.849294 -19.13636)
		(end 41.545764 -18.83283)
		(width 0.13208)
		(layer "F.Cu")
		(net "P5E_CPU1_PE1_TX_DP<6>")
	)
	(segment
		(start 113.989866 -225.739198)
		(end 113.989866 -225.203512)
		(width 0.13208)
		(layer "F.Cu")
		(net "P5E_CPU1_PE1_TX_DP<6>")
	)
	(segment
		(start 41.545764 -18.83283)
		(end 41.545764 -18.219166)
		(width 0.13208)
		(layer "F.Cu")
		(net "P5E_CPU1_PE1_TX_DP<6>")
	)
	(segment
		(start 41.554654 -19.431)
		(end 41.849294 -19.13636)
		(width 0.14732)
		(layer "In2.Cu")
		(net "P5E_CPU1_PE1_TX_DP<6>")
	)
	(segment
		(start 113.327942 -215.928956)
		(end 113.32972 -215.92794)
		(width 0.0889)
		(layer "In2.Cu")
		(net "P5E_CPU1_PE1_TX_DP<6>")
	)
	(segment
		(start 113.800382 -218.369388)
		(end 113.802668 -218.367864)
		(width 0.0889)
		(layer "In2.Cu")
		(net "P5E_CPU1_PE1_TX_DP<6>")
	)
	(segment
		(start 113.65738 -213.188042)
		(end 113.65738 -213.165944)
		(width 0.0889)
		(layer "In2.Cu")
		(net "P5E_CPU1_PE1_TX_DP<6>")
	)
	(segment
		(start 113.331752 -223.085406)
		(end 113.325402 -223.08185)
		(width 0.0889)
		(layer "In2.Cu")
		(net "P5E_CPU1_PE1_TX_DP<6>")
	)
	(segment
		(start 113.802668 -220.644212)
		(end 113.793778 -220.639132)
		(width 0.0889)
		(layer "In2.Cu")
		(net "P5E_CPU1_PE1_TX_DP<6>")
	)
	(segment
		(start 113.614708 -215.51773)
		(end 113.614708 -215.436958)
		(width 0.0889)
		(layer "In2.Cu")
		(net "P5E_CPU1_PE1_TX_DP<6>")
	)
	(segment
		(start 51.529996 -44.48556)
		(end 41.554654 -20.02409)
		(width 0.14732)
		(layer "In2.Cu")
		(net "P5E_CPU1_PE1_TX_DP<6>")
	)
	(segment
		(start 113.799366 -218.369896)
		(end 113.800382 -218.369388)
		(width 0.0889)
		(layer "In2.Cu")
		(net "P5E_CPU1_PE1_TX_DP<6>")
	)
	(segment
		(start 113.332768 -222.437198)
		(end 113.338864 -222.433642)
		(width 0.0889)
		(layer "In2.Cu")
		(net "P5E_CPU1_PE1_TX_DP<6>")
	)
	(segment
		(start 113.344706 -216.58199)
		(end 113.337594 -216.577926)
		(width 0.0889)
		(layer "In2.Cu")
		(net "P5E_CPU1_PE1_TX_DP<6>")
	)
	(segment
		(start 113.65738 -213.165944)
		(end 113.65738 -211.360766)
		(width 0.14732)
		(layer "In2.Cu")
		(net "P5E_CPU1_PE1_TX_DP<6>")
	)
	(segment
		(start 113.325402 -223.08185)
		(end 113.323878 -223.080834)
		(width 0.0889)
		(layer "In2.Cu")
		(net "P5E_CPU1_PE1_TX_DP<6>")
	)
	(segment
		(start 113.336832 -215.923368)
		(end 113.400586 -215.886792)
		(width 0.0889)
		(layer "In2.Cu")
		(net "P5E_CPU1_PE1_TX_DP<6>")
	)
	(segment
		(start 113.802668 -223.899984)
		(end 113.801906 -223.899476)
		(width 0.0889)
		(layer "In2.Cu")
		(net "P5E_CPU1_PE1_TX_DP<6>")
	)
	(segment
		(start 113.334292 -219.831412)
		(end 113.332768 -219.830396)
		(width 0.0889)
		(layer "In2.Cu")
		(net "P5E_CPU1_PE1_TX_DP<6>")
	)
	(segment
		(start 113.833148 -224.93224)
		(end 113.857278 -224.843086)
		(width 0.0889)
		(layer "In2.Cu")
		(net "P5E_CPU1_PE1_TX_DP<6>")
	)
	(segment
		(start 114.085116 -217.888312)
		(end 114.085116 -217.859864)
		(width 0.0889)
		(layer "In2.Cu")
		(net "P5E_CPU1_PE1_TX_DP<6>")
	)
	(segment
		(start 113.336832 -219.832682)
		(end 113.334292 -219.831412)
		(width 0.0889)
		(layer "In2.Cu")
		(net "P5E_CPU1_PE1_TX_DP<6>")
	)
	(segment
		(start 114.085116 -221.14383)
		(end 114.085116 -221.115382)
		(width 0.0889)
		(layer "In2.Cu")
		(net "P5E_CPU1_PE1_TX_DP<6>")
	)
	(segment
		(start 113.799366 -221.625414)
		(end 113.80089 -221.624398)
		(width 0.0889)
		(layer "In2.Cu")
		(net "P5E_CPU1_PE1_TX_DP<6>")
	)
	(segment
		(start 113.799366 -223.897952)
		(end 113.793778 -223.894904)
		(width 0.0889)
		(layer "In2.Cu")
		(net "P5E_CPU1_PE1_TX_DP<6>")
	)
	(segment
		(start 113.332006 -219.182188)
		(end 113.33353 -219.181172)
		(width 0.0889)
		(layer "In2.Cu")
		(net "P5E_CPU1_PE1_TX_DP<6>")
	)
	(segment
		(start 113.80089 -221.624398)
		(end 113.801906 -221.62389)
		(width 0.0889)
		(layer "In2.Cu")
		(net "P5E_CPU1_PE1_TX_DP<6>")
	)
	(segment
		(start 113.615216 -213.780878)
		(end 113.615216 -213.230206)
		(width 0.0889)
		(layer "In2.Cu")
		(net "P5E_CPU1_PE1_TX_DP<6>")
	)
	(segment
		(start 113.328958 -219.82811)
		(end 113.324894 -219.825824)
		(width 0.0889)
		(layer "In2.Cu")
		(net "P5E_CPU1_PE1_TX_DP<6>")
	)
	(segment
		(start 113.400586 -215.886792)
		(end 113.401094 -215.886538)
		(width 0.0889)
		(layer "In2.Cu")
		(net "P5E_CPU1_PE1_TX_DP<6>")
	)
	(segment
		(start 113.331752 -219.829888)
		(end 113.330228 -219.828872)
		(width 0.0889)
		(layer "In2.Cu")
		(net "P5E_CPU1_PE1_TX_DP<6>")
	)
	(segment
		(start 113.615216 -213.230206)
		(end 113.65738 -213.188042)
		(width 0.0889)
		(layer "In2.Cu")
		(net "P5E_CPU1_PE1_TX_DP<6>")
	)
	(segment
		(start 113.802668 -217.388694)
		(end 113.793778 -217.383614)
		(width 0.0889)
		(layer "In2.Cu")
		(net "P5E_CPU1_PE1_TX_DP<6>")
	)
	(segment
		(start 114.084862 -214.31123)
		(end 113.67389 -213.900258)
		(width 0.0889)
		(layer "In2.Cu")
		(net "P5E_CPU1_PE1_TX_DP<6>")
	)
	(segment
		(start 113.989612 -225.203258)
		(end 113.833148 -224.93224)
		(width 0.0889)
		(layer "In2.Cu")
		(net "P5E_CPU1_PE1_TX_DP<6>")
	)
	(segment
		(start 113.332514 -216.574878)
		(end 113.323624 -216.569798)
		(width 0.0889)
		(layer "In2.Cu")
		(net "P5E_CPU1_PE1_TX_DP<6>")
	)
	(segment
		(start 113.324894 -219.825824)
		(end 113.323878 -219.825316)
		(width 0.0889)
		(layer "In2.Cu")
		(net "P5E_CPU1_PE1_TX_DP<6>")
	)
	(segment
		(start 113.332768 -219.830396)
		(end 113.331752 -219.829888)
		(width 0.0889)
		(layer "In2.Cu")
		(net "P5E_CPU1_PE1_TX_DP<6>")
	)
	(segment
		(start 113.32972 -215.92794)
		(end 113.330482 -215.927432)
		(width 0.0889)
		(layer "In2.Cu")
		(net "P5E_CPU1_PE1_TX_DP<6>")
	)
	(segment
		(start 113.323624 -215.931242)
		(end 113.327942 -215.928956)
		(width 0.0889)
		(layer "In2.Cu")
		(net "P5E_CPU1_PE1_TX_DP<6>")
	)
	(segment
		(start 113.65738 -211.360766)
		(end 109.959648 -188.464952)
		(width 0.14732)
		(layer "In2.Cu")
		(net "P5E_CPU1_PE1_TX_DP<6>")
	)
	(segment
		(start 113.793778 -218.372944)
		(end 113.799366 -218.369896)
		(width 0.0889)
		(layer "In2.Cu")
		(net "P5E_CPU1_PE1_TX_DP<6>")
	)
	(segment
		(start 113.331752 -215.92667)
		(end 113.336832 -215.923368)
		(width 0.0889)
		(layer "In2.Cu")
		(net "P5E_CPU1_PE1_TX_DP<6>")
	)
	(segment
		(start 113.793778 -221.628462)
		(end 113.799366 -221.625414)
		(width 0.0889)
		(layer "In2.Cu")
		(net "P5E_CPU1_PE1_TX_DP<6>")
	)
	(segment
		(start 113.336324 -216.577164)
		(end 113.334038 -216.575894)
		(width 0.0889)
		(layer "In2.Cu")
		(net "P5E_CPU1_PE1_TX_DP<6>")
	)
	(segment
		(start 113.323878 -219.18676)
		(end 113.329974 -219.183204)
		(width 0.0889)
		(layer "In2.Cu")
		(net "P5E_CPU1_PE1_TX_DP<6>")
	)
	(segment
		(start 113.334038 -216.575894)
		(end 113.332514 -216.574878)
		(width 0.0889)
		(layer "In2.Cu")
		(net "P5E_CPU1_PE1_TX_DP<6>")
	)
	(segment
		(start 113.338864 -219.833952)
		(end 113.336832 -219.832682)
		(width 0.0889)
		(layer "In2.Cu")
		(net "P5E_CPU1_PE1_TX_DP<6>")
	)
	(segment
		(start 113.330228 -219.828872)
		(end 113.328958 -219.82811)
		(width 0.0889)
		(layer "In2.Cu")
		(net "P5E_CPU1_PE1_TX_DP<6>")
	)
	(segment
		(start 73.844912 -93.157294)
		(end 51.529996 -44.48556)
		(width 0.14732)
		(layer "In2.Cu")
		(net "P5E_CPU1_PE1_TX_DP<6>")
	)
	(segment
		(start 113.337594 -216.577926)
		(end 113.336324 -216.577164)
		(width 0.0889)
		(layer "In2.Cu")
		(net "P5E_CPU1_PE1_TX_DP<6>")
	)
	(segment
		(start 113.801906 -223.899476)
		(end 113.799366 -223.897952)
		(width 0.0889)
		(layer "In2.Cu")
		(net "P5E_CPU1_PE1_TX_DP<6>")
	)
	(segment
		(start 113.330482 -215.927432)
		(end 113.331752 -215.92667)
		(width 0.0889)
		(layer "In2.Cu")
		(net "P5E_CPU1_PE1_TX_DP<6>")
	)
	(segment
		(start 113.801906 -221.62389)
		(end 113.802668 -221.623382)
		(width 0.0889)
		(layer "In2.Cu")
		(net "P5E_CPU1_PE1_TX_DP<6>")
	)
	(segment
		(start 113.614708 -215.436958)
		(end 113.614962 -215.436704)
		(width 0.0889)
		(layer "In2.Cu")
		(net "P5E_CPU1_PE1_TX_DP<6>")
	)
	(segment
		(start 108.949998 -184.717182)
		(end 73.844912 -93.157294)
		(width 0.14732)
		(layer "In2.Cu")
		(net "P5E_CPU1_PE1_TX_DP<6>")
	)
	(segment
		(start 113.323878 -222.442278)
		(end 113.332768 -222.437198)
		(width 0.0889)
		(layer "In2.Cu")
		(net "P5E_CPU1_PE1_TX_DP<6>")
	)
	(segment
		(start 113.615216 -223.575626)
		(end 113.615216 -223.561402)
		(width 0.0889)
		(layer "In2.Cu")
		(net "P5E_CPU1_PE1_TX_DP<6>")
	)
	(segment
		(start 113.33353 -219.181172)
		(end 113.338864 -219.178124)
		(width 0.0889)
		(layer "In2.Cu")
		(net "P5E_CPU1_PE1_TX_DP<6>")
	)
	(segment
		(start 113.332768 -223.085914)
		(end 113.331752 -223.085406)
		(width 0.0889)
		(layer "In2.Cu")
		(net "P5E_CPU1_PE1_TX_DP<6>")
	)
	(segment
		(start 114.085116 -224.389442)
		(end 114.085116 -224.379536)
		(width 0.0889)
		(layer "In2.Cu")
		(net "P5E_CPU1_PE1_TX_DP<6>")
	)
	(segment
		(start 114.084862 -214.636858)
		(end 114.084862 -214.31123)
		(width 0.0889)
		(layer "In2.Cu")
		(net "P5E_CPU1_PE1_TX_DP<6>")
	)
	(segment
		(start 113.793524 -215.117426)
		(end 113.802414 -215.112346)
		(width 0.0889)
		(layer "In2.Cu")
		(net "P5E_CPU1_PE1_TX_DP<6>")
	)
	(segment
		(start 41.554654 -20.02409)
		(end 41.554654 -19.431)
		(width 0.14732)
		(layer "In2.Cu")
		(net "P5E_CPU1_PE1_TX_DP<6>")
	)
	(segment
		(start 109.959648 -188.464952)
		(end 108.949998 -184.717182)
		(width 0.14732)
		(layer "In2.Cu")
		(net "P5E_CPU1_PE1_TX_DP<6>")
	)
	(segment
		(start 113.329974 -219.183204)
		(end 113.332006 -219.182188)
		(width 0.0889)
		(layer "In2.Cu")
		(net "P5E_CPU1_PE1_TX_DP<6>")
	)
	(arc
		(start 113.802414 -215.112346)
		(mid 114.005719 -214.91148)
		(end 114.084862 -214.636858)
		(width 0.0889)
		(layer "In2.Cu")
		(net "P5E_CPU1_PE1_TX_DP<6>")
	)
	(arc
		(start 113.615216 -221.94774)
		(mid 113.662895 -221.76484)
		(end 113.793778 -221.628462)
		(width 0.0889)
		(layer "In2.Cu")
		(net "P5E_CPU1_PE1_TX_DP<6>")
	)
	(arc
		(start 113.793778 -223.894904)
		(mid 113.662864 -223.758544)
		(end 113.615216 -223.575626)
		(width 0.0889)
		(layer "In2.Cu")
		(net "P5E_CPU1_PE1_TX_DP<6>")
	)
	(arc
		(start 114.085116 -224.379536)
		(mid 114.007005 -224.102587)
		(end 113.802668 -223.899984)
		(width 0.0889)
		(layer "In2.Cu")
		(net "P5E_CPU1_PE1_TX_DP<6>")
	)
	(arc
		(start 113.338864 -222.433642)
		(mid 113.541277 -222.227229)
		(end 113.615216 -221.94774)
		(width 0.0889)
		(layer "In2.Cu")
		(net "P5E_CPU1_PE1_TX_DP<6>")
	)
	(arc
		(start 113.802668 -221.623382)
		(mid 114.007003 -221.420777)
		(end 114.085116 -221.14383)
		(width 0.0889)
		(layer "In2.Cu")
		(net "P5E_CPU1_PE1_TX_DP<6>")
	)
	(arc
		(start 113.338864 -219.178124)
		(mid 113.541277 -218.971711)
		(end 113.615216 -218.692222)
		(width 0.0889)
		(layer "In2.Cu")
		(net "P5E_CPU1_PE1_TX_DP<6>")
	)
	(arc
		(start 113.615216 -217.064336)
		(mid 113.542981 -216.787812)
		(end 113.344706 -216.58199)
		(width 0.0889)
		(layer "In2.Cu")
		(net "P5E_CPU1_PE1_TX_DP<6>")
	)
	(arc
		(start 113.323624 -216.569798)
		(mid 113.145027 -216.25052)
		(end 113.323624 -215.931242)
		(width 0.0889)
		(layer "In2.Cu")
		(net "P5E_CPU1_PE1_TX_DP<6>")
	)
	(arc
		(start 113.615216 -215.421972)
		(mid 113.616664 -215.40096)
		(end 113.61928 -215.380062)
		(width 0.0889)
		(layer "In2.Cu")
		(net "P5E_CPU1_PE1_TX_DP<6>")
	)
	(arc
		(start 113.323878 -223.080834)
		(mid 113.196798 -222.95082)
		(end 113.145824 -222.776288)
		(width 0.0889)
		(layer "In2.Cu")
		(net "P5E_CPU1_PE1_TX_DP<6>")
	)
	(arc
		(start 113.67389 -213.900258)
		(mid 113.634607 -213.845448)
		(end 113.615216 -213.780878)
		(width 0.0889)
		(layer "In2.Cu")
		(net "P5E_CPU1_PE1_TX_DP<6>")
	)
	(arc
		(start 113.401094 -215.886538)
		(mid 113.557445 -215.730831)
		(end 113.614708 -215.51773)
		(width 0.0889)
		(layer "In2.Cu")
		(net "P5E_CPU1_PE1_TX_DP<6>")
	)
	(arc
		(start 113.802668 -218.367864)
		(mid 114.007003 -218.165259)
		(end 114.085116 -217.888312)
		(width 0.0889)
		(layer "In2.Cu")
		(net "P5E_CPU1_PE1_TX_DP<6>")
	)
	(arc
		(start 114.085116 -221.115382)
		(mid 114.004954 -220.843193)
		(end 113.802668 -220.644212)
		(width 0.0889)
		(layer "In2.Cu")
		(net "P5E_CPU1_PE1_TX_DP<6>")
	)
	(arc
		(start 113.615216 -223.561402)
		(mid 113.536075 -223.286779)
		(end 113.332768 -223.085914)
		(width 0.0889)
		(layer "In2.Cu")
		(net "P5E_CPU1_PE1_TX_DP<6>")
	)
	(arc
		(start 113.145824 -222.776288)
		(mid 113.145491 -222.763844)
		(end 113.14557 -222.751396)
		(width 0.0889)
		(layer "In2.Cu")
		(net "P5E_CPU1_PE1_TX_DP<6>")
	)
	(arc
		(start 113.857278 -224.843086)
		(mid 113.86585 -224.836564)
		(end 113.874296 -224.829878)
		(width 0.0889)
		(layer "In2.Cu")
		(net "P5E_CPU1_PE1_TX_DP<6>")
	)
	(arc
		(start 113.615216 -218.692222)
		(mid 113.662895 -218.509322)
		(end 113.793778 -218.372944)
		(width 0.0889)
		(layer "In2.Cu")
		(net "P5E_CPU1_PE1_TX_DP<6>")
	)
	(arc
		(start 114.085116 -217.859864)
		(mid 114.004954 -217.587675)
		(end 113.802668 -217.388694)
		(width 0.0889)
		(layer "In2.Cu")
		(net "P5E_CPU1_PE1_TX_DP<6>")
	)
	(arc
		(start 113.874296 -224.829878)
		(mid 114.029694 -224.633597)
		(end 114.085116 -224.389442)
		(width 0.0889)
		(layer "In2.Cu")
		(net "P5E_CPU1_PE1_TX_DP<6>")
	)
	(arc
		(start 113.14557 -222.751396)
		(mid 113.195585 -222.574265)
		(end 113.323878 -222.442278)
		(width 0.0889)
		(layer "In2.Cu")
		(net "P5E_CPU1_PE1_TX_DP<6>")
	)
	(arc
		(start 113.61928 -215.380062)
		(mid 113.677458 -215.229547)
		(end 113.793524 -215.117426)
		(width 0.0889)
		(layer "In2.Cu")
		(net "P5E_CPU1_PE1_TX_DP<6>")
	)
	(arc
		(start 113.323878 -219.825316)
		(mid 113.145402 -219.506038)
		(end 113.323878 -219.18676)
		(width 0.0889)
		(layer "In2.Cu")
		(net "P5E_CPU1_PE1_TX_DP<6>")
	)
	(arc
		(start 113.615216 -220.319854)
		(mid 113.5413 -220.040352)
		(end 113.338864 -219.833952)
		(width 0.0889)
		(layer "In2.Cu")
		(net "P5E_CPU1_PE1_TX_DP<6>")
	)
	(arc
		(start 113.614962 -215.436704)
		(mid 113.615014 -215.429337)
		(end 113.615216 -215.421972)
		(width 0.0889)
		(layer "In2.Cu")
		(net "P5E_CPU1_PE1_TX_DP<6>")
	)
	(arc
		(start 113.793778 -217.383614)
		(mid 113.662864 -217.247254)
		(end 113.615216 -217.064336)
		(width 0.0889)
		(layer "In2.Cu")
		(net "P5E_CPU1_PE1_TX_DP<6>")
	)
	(arc
		(start 113.793778 -220.639132)
		(mid 113.662864 -220.502772)
		(end 113.615216 -220.319854)
		(width 0.0889)
		(layer "In2.Cu")
		(net "P5E_CPU1_PE1_TX_DP<6>")
	)
	(segment
		(start 114.459766 -224.925382)
		(end 114.459766 -224.389442)
		(width 0.13208)
		(layer "F.Cu")
		(net "P5E_CPU1_PE1_TX_DP<5>")
	)
	(segment
		(start 43.779694 -17.61236)
		(end 44.080684 -17.31137)
		(width 0.13208)
		(layer "F.Cu")
		(net "P5E_CPU1_PE1_TX_DP<5>")
	)
	(segment
		(start 44.080684 -17.31137)
		(end 44.080684 -16.692626)
		(width 0.13208)
		(layer "F.Cu")
		(net "P5E_CPU1_PE1_TX_DP<5>")
	)
	(segment
		(start 44.080684 -16.692626)
		(end 43.754294 -16.366236)
		(width 0.13208)
		(layer "F.Cu")
		(net "P5E_CPU1_PE1_TX_DP<5>")
	)
	(segment
		(start 44.074334 -19.339052)
		(end 44.074334 -17.907)
		(width 0.14732)
		(layer "In2.Cu")
		(net "P5E_CPU1_PE1_TX_DP<5>")
	)
	(segment
		(start 110.668816 -188.508132)
		(end 109.625892 -184.635902)
		(width 0.14732)
		(layer "In2.Cu")
		(net "P5E_CPU1_PE1_TX_DP<5>")
	)
	(segment
		(start 114.364262 -223.575626)
		(end 114.364262 -223.56699)
		(width 0.0889)
		(layer "In2.Cu")
		(net "P5E_CPU1_PE1_TX_DP<5>")
	)
	(segment
		(start 114.833908 -214.63127)
		(end 114.833908 -214.460836)
		(width 0.0889)
		(layer "In2.Cu")
		(net "P5E_CPU1_PE1_TX_DP<5>")
	)
	(segment
		(start 114.31651 -213.242652)
		(end 114.31651 -213.220554)
		(width 0.0889)
		(layer "In2.Cu")
		(net "P5E_CPU1_PE1_TX_DP<5>")
	)
	(segment
		(start 114.61623 -224.118424)
		(end 114.5921 -224.02927)
		(width 0.0889)
		(layer "In2.Cu")
		(net "P5E_CPU1_PE1_TX_DP<5>")
	)
	(segment
		(start 74.436478 -92.828364)
		(end 53.012086 -46.096682)
		(width 0.14732)
		(layer "In2.Cu")
		(net "P5E_CPU1_PE1_TX_DP<5>")
	)
	(segment
		(start 114.358166 -213.689438)
		(end 114.358166 -213.297262)
		(width 0.0889)
		(layer "In2.Cu")
		(net "P5E_CPU1_PE1_TX_DP<5>")
	)
	(segment
		(start 114.640868 -218.20632)
		(end 114.646202 -218.203272)
		(width 0.0889)
		(layer "In2.Cu")
		(net "P5E_CPU1_PE1_TX_DP<5>")
	)
	(segment
		(start 44.074334 -17.907)
		(end 43.779694 -17.61236)
		(width 0.14732)
		(layer "In2.Cu")
		(net "P5E_CPU1_PE1_TX_DP<5>")
	)
	(segment
		(start 114.64671 -221.458282)
		(end 114.6556 -221.453202)
		(width 0.0889)
		(layer "In2.Cu")
		(net "P5E_CPU1_PE1_TX_DP<5>")
	)
	(segment
		(start 113.894616 -222.780098)
		(end 113.894616 -222.75165)
		(width 0.0889)
		(layer "In2.Cu")
		(net "P5E_CPU1_PE1_TX_DP<5>")
	)
	(segment
		(start 114.380772 -213.970362)
		(end 114.358166 -213.689438)
		(width 0.0889)
		(layer "In2.Cu")
		(net "P5E_CPU1_PE1_TX_DP<5>")
	)
	(segment
		(start 113.894616 -219.515944)
		(end 113.894616 -219.490544)
		(width 0.0889)
		(layer "In2.Cu")
		(net "P5E_CPU1_PE1_TX_DP<5>")
	)
	(segment
		(start 114.413284 -214.035386)
		(end 114.413538 -214.035132)
		(width 0.0889)
		(layer "In2.Cu")
		(net "P5E_CPU1_PE1_TX_DP<5>")
	)
	(segment
		(start 114.648488 -218.202002)
		(end 114.655854 -218.197684)
		(width 0.0889)
		(layer "In2.Cu")
		(net "P5E_CPU1_PE1_TX_DP<5>")
	)
	(segment
		(start 114.17681 -215.761062)
		(end 114.1857 -215.755982)
		(width 0.0889)
		(layer "In2.Cu")
		(net "P5E_CPU1_PE1_TX_DP<5>")
	)
	(segment
		(start 113.894616 -216.260426)
		(end 113.894616 -216.235026)
		(width 0.0889)
		(layer "In2.Cu")
		(net "P5E_CPU1_PE1_TX_DP<5>")
	)
	(segment
		(start 53.012086 -46.096682)
		(end 44.074334 -19.339052)
		(width 0.14732)
		(layer "In2.Cu")
		(net "P5E_CPU1_PE1_TX_DP<5>")
	)
	(segment
		(start 114.358166 -213.297262)
		(end 114.35842 -213.297008)
		(width 0.0889)
		(layer "In2.Cu")
		(net "P5E_CPU1_PE1_TX_DP<5>")
	)
	(segment
		(start 114.6556 -220.814646)
		(end 114.64671 -220.809566)
		(width 0.0889)
		(layer "In2.Cu")
		(net "P5E_CPU1_PE1_TX_DP<5>")
	)
	(segment
		(start 114.35842 -213.297008)
		(end 114.35842 -213.284562)
		(width 0.0889)
		(layer "In2.Cu")
		(net "P5E_CPU1_PE1_TX_DP<5>")
	)
	(segment
		(start 109.625892 -184.635902)
		(end 74.436478 -92.828364)
		(width 0.14732)
		(layer "In2.Cu")
		(net "P5E_CPU1_PE1_TX_DP<5>")
	)
	(segment
		(start 114.31651 -213.220554)
		(end 114.31651 -211.093812)
		(width 0.14732)
		(layer "In2.Cu")
		(net "P5E_CPU1_PE1_TX_DP<5>")
	)
	(segment
		(start 114.35842 -213.284562)
		(end 114.31651 -213.242652)
		(width 0.0889)
		(layer "In2.Cu")
		(net "P5E_CPU1_PE1_TX_DP<5>")
	)
	(segment
		(start 114.646964 -218.202764)
		(end 114.648488 -218.202002)
		(width 0.0889)
		(layer "In2.Cu")
		(net "P5E_CPU1_PE1_TX_DP<5>")
	)
	(segment
		(start 114.655854 -217.559128)
		(end 114.646964 -217.554048)
		(width 0.0889)
		(layer "In2.Cu")
		(net "P5E_CPU1_PE1_TX_DP<5>")
	)
	(segment
		(start 114.31651 -211.093812)
		(end 110.668816 -188.508132)
		(width 0.14732)
		(layer "In2.Cu")
		(net "P5E_CPU1_PE1_TX_DP<5>")
	)
	(segment
		(start 114.17681 -219.01658)
		(end 114.1857 -219.0115)
		(width 0.0889)
		(layer "In2.Cu")
		(net "P5E_CPU1_PE1_TX_DP<5>")
	)
	(segment
		(start 114.459766 -224.389442)
		(end 114.61623 -224.118424)
		(width 0.0889)
		(layer "In2.Cu")
		(net "P5E_CPU1_PE1_TX_DP<5>")
	)
	(segment
		(start 114.364262 -217.07856)
		(end 114.364262 -217.0557)
		(width 0.0889)
		(layer "In2.Cu")
		(net "P5E_CPU1_PE1_TX_DP<5>")
	)
	(segment
		(start 114.364262 -221.956376)
		(end 114.364262 -221.937834)
		(width 0.0889)
		(layer "In2.Cu")
		(net "P5E_CPU1_PE1_TX_DP<5>")
	)
	(segment
		(start 114.364262 -220.338396)
		(end 114.364262 -220.311218)
		(width 0.0889)
		(layer "In2.Cu")
		(net "P5E_CPU1_PE1_TX_DP<5>")
	)
	(segment
		(start 114.646202 -218.203272)
		(end 114.646964 -218.202764)
		(width 0.0889)
		(layer "In2.Cu")
		(net "P5E_CPU1_PE1_TX_DP<5>")
	)
	(arc
		(start 114.833908 -214.460836)
		(mid 114.758941 -214.345698)
		(end 114.650012 -214.261954)
		(width 0.0889)
		(layer "In2.Cu")
		(net "P5E_CPU1_PE1_TX_DP<5>")
	)
	(arc
		(start 114.6556 -221.453202)
		(mid 114.834197 -221.133924)
		(end 114.6556 -220.814646)
		(width 0.0889)
		(layer "In2.Cu")
		(net "P5E_CPU1_PE1_TX_DP<5>")
	)
	(arc
		(start 114.650012 -214.261954)
		(mid 114.515816 -214.165205)
		(end 114.413284 -214.035386)
		(width 0.0889)
		(layer "In2.Cu")
		(net "P5E_CPU1_PE1_TX_DP<5>")
	)
	(arc
		(start 114.364262 -221.937834)
		(mid 114.442373 -221.660885)
		(end 114.64671 -221.458282)
		(width 0.0889)
		(layer "In2.Cu")
		(net "P5E_CPU1_PE1_TX_DP<5>")
	)
	(arc
		(start 114.413538 -214.035132)
		(mid 114.396167 -214.003247)
		(end 114.380772 -213.970362)
		(width 0.0889)
		(layer "In2.Cu")
		(net "P5E_CPU1_PE1_TX_DP<5>")
	)
	(arc
		(start 114.364262 -220.311218)
		(mid 114.311992 -220.128853)
		(end 114.177064 -219.995496)
		(width 0.0889)
		(layer "In2.Cu")
		(net "P5E_CPU1_PE1_TX_DP<5>")
	)
	(arc
		(start 114.364262 -223.56699)
		(mid 114.311992 -223.384625)
		(end 114.177064 -223.251268)
		(width 0.0889)
		(layer "In2.Cu")
		(net "P5E_CPU1_PE1_TX_DP<5>")
	)
	(arc
		(start 114.364262 -215.436704)
		(mid 114.440222 -215.154214)
		(end 114.647218 -214.9475)
		(width 0.0889)
		(layer "In2.Cu")
		(net "P5E_CPU1_PE1_TX_DP<5>")
	)
	(arc
		(start 114.646964 -217.554048)
		(mid 114.443483 -217.353244)
		(end 114.364262 -217.07856)
		(width 0.0889)
		(layer "In2.Cu")
		(net "P5E_CPU1_PE1_TX_DP<5>")
	)
	(arc
		(start 114.1857 -219.0115)
		(mid 114.316614 -218.87514)
		(end 114.364262 -218.692222)
		(width 0.0889)
		(layer "In2.Cu")
		(net "P5E_CPU1_PE1_TX_DP<5>")
	)
	(arc
		(start 114.364262 -218.692222)
		(mid 114.438253 -218.412656)
		(end 114.640868 -218.20632)
		(width 0.0889)
		(layer "In2.Cu")
		(net "P5E_CPU1_PE1_TX_DP<5>")
	)
	(arc
		(start 114.647218 -214.9475)
		(mid 114.782016 -214.813836)
		(end 114.833908 -214.63127)
		(width 0.0889)
		(layer "In2.Cu")
		(net "P5E_CPU1_PE1_TX_DP<5>")
	)
	(arc
		(start 114.655854 -218.197684)
		(mid 114.834451 -217.878406)
		(end 114.655854 -217.559128)
		(width 0.0889)
		(layer "In2.Cu")
		(net "P5E_CPU1_PE1_TX_DP<5>")
	)
	(arc
		(start 113.894616 -222.75165)
		(mid 113.972727 -222.474701)
		(end 114.177064 -222.272098)
		(width 0.0889)
		(layer "In2.Cu")
		(net "P5E_CPU1_PE1_TX_DP<5>")
	)
	(arc
		(start 114.177064 -222.272098)
		(mid 114.311997 -222.138744)
		(end 114.364262 -221.956376)
		(width 0.0889)
		(layer "In2.Cu")
		(net "P5E_CPU1_PE1_TX_DP<5>")
	)
	(arc
		(start 114.64671 -220.809566)
		(mid 114.444424 -220.610585)
		(end 114.364262 -220.338396)
		(width 0.0889)
		(layer "In2.Cu")
		(net "P5E_CPU1_PE1_TX_DP<5>")
	)
	(arc
		(start 113.894616 -219.490544)
		(mid 113.973986 -219.21681)
		(end 114.17681 -219.01658)
		(width 0.0889)
		(layer "In2.Cu")
		(net "P5E_CPU1_PE1_TX_DP<5>")
	)
	(arc
		(start 114.177064 -219.995496)
		(mid 113.972729 -219.792891)
		(end 113.894616 -219.515944)
		(width 0.0889)
		(layer "In2.Cu")
		(net "P5E_CPU1_PE1_TX_DP<5>")
	)
	(arc
		(start 114.5921 -224.02927)
		(mid 114.424346 -223.829492)
		(end 114.364262 -223.575626)
		(width 0.0889)
		(layer "In2.Cu")
		(net "P5E_CPU1_PE1_TX_DP<5>")
	)
	(arc
		(start 114.364262 -217.0557)
		(mid 114.311992 -216.873335)
		(end 114.177064 -216.739978)
		(width 0.0889)
		(layer "In2.Cu")
		(net "P5E_CPU1_PE1_TX_DP<5>")
	)
	(arc
		(start 113.894616 -216.235026)
		(mid 113.973986 -215.961292)
		(end 114.17681 -215.761062)
		(width 0.0889)
		(layer "In2.Cu")
		(net "P5E_CPU1_PE1_TX_DP<5>")
	)
	(arc
		(start 114.1857 -215.755982)
		(mid 114.316614 -215.619622)
		(end 114.364262 -215.436704)
		(width 0.0889)
		(layer "In2.Cu")
		(net "P5E_CPU1_PE1_TX_DP<5>")
	)
	(arc
		(start 114.177064 -223.251268)
		(mid 113.974778 -223.052287)
		(end 113.894616 -222.780098)
		(width 0.0889)
		(layer "In2.Cu")
		(net "P5E_CPU1_PE1_TX_DP<5>")
	)
	(arc
		(start 114.177064 -216.739978)
		(mid 113.972729 -216.537373)
		(end 113.894616 -216.260426)
		(width 0.0889)
		(layer "In2.Cu")
		(net "P5E_CPU1_PE1_TX_DP<5>")
	)
	(segment
		(start 47.133764 -18.219166)
		(end 47.462694 -17.890236)
		(width 0.13208)
		(layer "F.Cu")
		(net "P5E_CPU1_PE1_TX_DP<4>")
	)
	(segment
		(start 47.437294 -19.13636)
		(end 47.133764 -18.83283)
		(width 0.13208)
		(layer "F.Cu")
		(net "P5E_CPU1_PE1_TX_DP<4>")
	)
	(segment
		(start 47.133764 -18.83283)
		(end 47.133764 -18.219166)
		(width 0.13208)
		(layer "F.Cu")
		(net "P5E_CPU1_PE1_TX_DP<4>")
	)
	(segment
		(start 115.869466 -225.739198)
		(end 115.869212 -225.738944)
		(width 0.13208)
		(layer "F.Cu")
		(net "P5E_CPU1_PE1_TX_DP<4>")
	)
	(segment
		(start 115.869212 -225.738944)
		(end 115.869212 -225.203258)
		(width 0.13208)
		(layer "F.Cu")
		(net "P5E_CPU1_PE1_TX_DP<4>")
	)
	(segment
		(start 115.682268 -223.899984)
		(end 115.673378 -223.894904)
		(width 0.0889)
		(layer "In2.Cu")
		(net "P5E_CPU1_PE1_TX_DP<4>")
	)
	(segment
		(start 115.494816 -221.957646)
		(end 115.494816 -221.939104)
		(width 0.0889)
		(layer "In2.Cu")
		(net "P5E_CPU1_PE1_TX_DP<4>")
	)
	(segment
		(start 115.682268 -217.388694)
		(end 115.673378 -217.383614)
		(width 0.0889)
		(layer "In2.Cu")
		(net "P5E_CPU1_PE1_TX_DP<4>")
	)
	(segment
		(start 115.211606 -223.085406)
		(end 115.203478 -223.080834)
		(width 0.0889)
		(layer "In2.Cu")
		(net "P5E_CPU1_PE1_TX_DP<4>")
	)
	(segment
		(start 115.024916 -216.259156)
		(end 115.024916 -216.241884)
		(width 0.0889)
		(layer "In2.Cu")
		(net "P5E_CPU1_PE1_TX_DP<4>")
	)
	(segment
		(start 115.494562 -213.292182)
		(end 115.494816 -213.291928)
		(width 0.0889)
		(layer "In2.Cu")
		(net "P5E_CPU1_PE1_TX_DP<4>")
	)
	(segment
		(start 115.682014 -215.112346)
		(end 115.682522 -215.111584)
		(width 0.0889)
		(layer "In2.Cu")
		(net "P5E_CPU1_PE1_TX_DP<4>")
	)
	(segment
		(start 54.675532 -46.825662)
		(end 47.142654 -19.982942)
		(width 0.14732)
		(layer "In2.Cu")
		(net "P5E_CPU1_PE1_TX_DP<4>")
	)
	(segment
		(start 115.682014 -221.623382)
		(end 115.682776 -221.622874)
		(width 0.0889)
		(layer "In2.Cu")
		(net "P5E_CPU1_PE1_TX_DP<4>")
	)
	(segment
		(start 115.682522 -215.111584)
		(end 115.687348 -215.10879)
		(width 0.0889)
		(layer "In2.Cu")
		(net "P5E_CPU1_PE1_TX_DP<4>")
	)
	(segment
		(start 115.494816 -213.284816)
		(end 115.53698 -213.242652)
		(width 0.0889)
		(layer "In2.Cu")
		(net "P5E_CPU1_PE1_TX_DP<4>")
	)
	(segment
		(start 115.53698 -213.242652)
		(end 115.53698 -213.220554)
		(width 0.0889)
		(layer "In2.Cu")
		(net "P5E_CPU1_PE1_TX_DP<4>")
	)
	(segment
		(start 115.677442 -215.114886)
		(end 115.681252 -215.112854)
		(width 0.0889)
		(layer "In2.Cu")
		(net "P5E_CPU1_PE1_TX_DP<4>")
	)
	(segment
		(start 115.964716 -224.389442)
		(end 115.964716 -224.379536)
		(width 0.0889)
		(layer "In2.Cu")
		(net "P5E_CPU1_PE1_TX_DP<4>")
	)
	(segment
		(start 115.53698 -210.949794)
		(end 111.893604 -188.390784)
		(width 0.14732)
		(layer "In2.Cu")
		(net "P5E_CPU1_PE1_TX_DP<4>")
	)
	(segment
		(start 115.682776 -218.367356)
		(end 115.68811 -218.364308)
		(width 0.0889)
		(layer "In2.Cu")
		(net "P5E_CPU1_PE1_TX_DP<4>")
	)
	(segment
		(start 47.142654 -19.982942)
		(end 47.142654 -19.431)
		(width 0.14732)
		(layer "In2.Cu")
		(net "P5E_CPU1_PE1_TX_DP<4>")
	)
	(segment
		(start 115.682776 -221.622874)
		(end 115.68811 -221.619826)
		(width 0.0889)
		(layer "In2.Cu")
		(net "P5E_CPU1_PE1_TX_DP<4>")
	)
	(segment
		(start 115.712748 -224.93224)
		(end 115.736878 -224.843086)
		(width 0.0889)
		(layer "In2.Cu")
		(net "P5E_CPU1_PE1_TX_DP<4>")
	)
	(segment
		(start 115.682268 -220.644212)
		(end 115.673378 -220.639132)
		(width 0.0889)
		(layer "In2.Cu")
		(net "P5E_CPU1_PE1_TX_DP<4>")
	)
	(segment
		(start 111.893604 -188.390784)
		(end 110.73892 -184.102502)
		(width 0.14732)
		(layer "In2.Cu")
		(net "P5E_CPU1_PE1_TX_DP<4>")
	)
	(segment
		(start 115.53698 -213.220554)
		(end 115.53698 -210.949794)
		(width 0.14732)
		(layer "In2.Cu")
		(net "P5E_CPU1_PE1_TX_DP<4>")
	)
	(segment
		(start 75.678792 -92.642436)
		(end 54.675532 -46.825662)
		(width 0.14732)
		(layer "In2.Cu")
		(net "P5E_CPU1_PE1_TX_DP<4>")
	)
	(segment
		(start 115.203478 -222.442278)
		(end 115.212368 -222.437198)
		(width 0.0889)
		(layer "In2.Cu")
		(net "P5E_CPU1_PE1_TX_DP<4>")
	)
	(segment
		(start 115.681252 -215.112854)
		(end 115.682014 -215.112346)
		(width 0.0889)
		(layer "In2.Cu")
		(net "P5E_CPU1_PE1_TX_DP<4>")
	)
	(segment
		(start 110.73892 -184.102502)
		(end 75.678792 -92.642436)
		(width 0.14732)
		(layer "In2.Cu")
		(net "P5E_CPU1_PE1_TX_DP<4>")
	)
	(segment
		(start 115.687348 -215.10879)
		(end 115.68938 -215.10752)
		(width 0.0889)
		(layer "In2.Cu")
		(net "P5E_CPU1_PE1_TX_DP<4>")
	)
	(segment
		(start 115.964716 -217.878406)
		(end 115.964716 -217.859864)
		(width 0.0889)
		(layer "In2.Cu")
		(net "P5E_CPU1_PE1_TX_DP<4>")
	)
	(segment
		(start 115.494816 -213.291928)
		(end 115.494816 -213.284816)
		(width 0.0889)
		(layer "In2.Cu")
		(net "P5E_CPU1_PE1_TX_DP<4>")
	)
	(segment
		(start 115.224306 -216.58199)
		(end 115.212114 -216.574878)
		(width 0.0889)
		(layer "In2.Cu")
		(net "P5E_CPU1_PE1_TX_DP<4>")
	)
	(segment
		(start 115.705128 -214.10803)
		(end 115.534186 -213.937342)
		(width 0.0889)
		(layer "In2.Cu")
		(net "P5E_CPU1_PE1_TX_DP<4>")
	)
	(segment
		(start 115.869212 -225.203258)
		(end 115.712748 -224.93224)
		(width 0.0889)
		(layer "In2.Cu")
		(net "P5E_CPU1_PE1_TX_DP<4>")
	)
	(segment
		(start 115.964716 -221.133924)
		(end 115.964716 -221.115382)
		(width 0.0889)
		(layer "In2.Cu")
		(net "P5E_CPU1_PE1_TX_DP<4>")
	)
	(segment
		(start 115.494816 -218.702128)
		(end 115.494816 -218.683586)
		(width 0.0889)
		(layer "In2.Cu")
		(net "P5E_CPU1_PE1_TX_DP<4>")
	)
	(segment
		(start 115.68938 -215.10752)
		(end 115.690904 -215.106504)
		(width 0.0889)
		(layer "In2.Cu")
		(net "P5E_CPU1_PE1_TX_DP<4>")
	)
	(segment
		(start 115.534186 -213.937342)
		(end 115.494562 -213.841584)
		(width 0.0889)
		(layer "In2.Cu")
		(net "P5E_CPU1_PE1_TX_DP<4>")
	)
	(segment
		(start 115.963954 -214.622634)
		(end 115.964208 -214.622634)
		(width 0.0889)
		(layer "In2.Cu")
		(net "P5E_CPU1_PE1_TX_DP<4>")
	)
	(segment
		(start 47.142654 -19.431)
		(end 47.437294 -19.13636)
		(width 0.14732)
		(layer "In2.Cu")
		(net "P5E_CPU1_PE1_TX_DP<4>")
	)
	(segment
		(start 115.494562 -215.44661)
		(end 115.494562 -215.436704)
		(width 0.0889)
		(layer "In2.Cu")
		(net "P5E_CPU1_PE1_TX_DP<4>")
	)
	(segment
		(start 115.494562 -213.841584)
		(end 115.494562 -213.292182)
		(width 0.0889)
		(layer "In2.Cu")
		(net "P5E_CPU1_PE1_TX_DP<4>")
	)
	(segment
		(start 115.212368 -223.085914)
		(end 115.211606 -223.085406)
		(width 0.0889)
		(layer "In2.Cu")
		(net "P5E_CPU1_PE1_TX_DP<4>")
	)
	(segment
		(start 115.218464 -219.833952)
		(end 115.212368 -219.830396)
		(width 0.0889)
		(layer "In2.Cu")
		(net "P5E_CPU1_PE1_TX_DP<4>")
	)
	(segment
		(start 115.203478 -219.18676)
		(end 115.212368 -219.18168)
		(width 0.0889)
		(layer "In2.Cu")
		(net "P5E_CPU1_PE1_TX_DP<4>")
	)
	(segment
		(start 115.682014 -218.367864)
		(end 115.682776 -218.367356)
		(width 0.0889)
		(layer "In2.Cu")
		(net "P5E_CPU1_PE1_TX_DP<4>")
	)
	(segment
		(start 115.212368 -219.830396)
		(end 115.203478 -219.825316)
		(width 0.0889)
		(layer "In2.Cu")
		(net "P5E_CPU1_PE1_TX_DP<4>")
	)
	(segment
		(start 115.494816 -223.575626)
		(end 115.494816 -223.557084)
		(width 0.0889)
		(layer "In2.Cu")
		(net "P5E_CPU1_PE1_TX_DP<4>")
	)
	(segment
		(start 115.673124 -215.117426)
		(end 115.677442 -215.114886)
		(width 0.0889)
		(layer "In2.Cu")
		(net "P5E_CPU1_PE1_TX_DP<4>")
	)
	(segment
		(start 115.964208 -214.622634)
		(end 115.964208 -214.424768)
		(width 0.0889)
		(layer "In2.Cu")
		(net "P5E_CPU1_PE1_TX_DP<4>")
	)
	(arc
		(start 115.964716 -224.379536)
		(mid 115.886605 -224.102587)
		(end 115.682268 -223.899984)
		(width 0.0889)
		(layer "In2.Cu")
		(net "P5E_CPU1_PE1_TX_DP<4>")
	)
	(arc
		(start 115.673378 -223.894904)
		(mid 115.542464 -223.758544)
		(end 115.494816 -223.575626)
		(width 0.0889)
		(layer "In2.Cu")
		(net "P5E_CPU1_PE1_TX_DP<4>")
	)
	(arc
		(start 115.024916 -222.754952)
		(mid 115.074169 -222.575752)
		(end 115.203478 -222.442278)
		(width 0.0889)
		(layer "In2.Cu")
		(net "P5E_CPU1_PE1_TX_DP<4>")
	)
	(arc
		(start 115.494816 -215.421972)
		(mid 115.54587 -215.247392)
		(end 115.673124 -215.117426)
		(width 0.0889)
		(layer "In2.Cu")
		(net "P5E_CPU1_PE1_TX_DP<4>")
	)
	(arc
		(start 115.212368 -222.437198)
		(mid 115.416703 -222.234593)
		(end 115.494816 -221.957646)
		(width 0.0889)
		(layer "In2.Cu")
		(net "P5E_CPU1_PE1_TX_DP<4>")
	)
	(arc
		(start 115.964716 -217.859864)
		(mid 115.884554 -217.587675)
		(end 115.682268 -217.388694)
		(width 0.0889)
		(layer "In2.Cu")
		(net "P5E_CPU1_PE1_TX_DP<4>")
	)
	(arc
		(start 115.494816 -220.319854)
		(mid 115.4209 -220.040352)
		(end 115.218464 -219.833952)
		(width 0.0889)
		(layer "In2.Cu")
		(net "P5E_CPU1_PE1_TX_DP<4>")
	)
	(arc
		(start 115.494816 -218.683586)
		(mid 115.547086 -218.501221)
		(end 115.682014 -218.367864)
		(width 0.0889)
		(layer "In2.Cu")
		(net "P5E_CPU1_PE1_TX_DP<4>")
	)
	(arc
		(start 115.212114 -215.926162)
		(mid 115.416449 -215.723557)
		(end 115.494562 -215.44661)
		(width 0.0889)
		(layer "In2.Cu")
		(net "P5E_CPU1_PE1_TX_DP<4>")
	)
	(arc
		(start 115.024916 -216.241884)
		(mid 115.077186 -216.059519)
		(end 115.212114 -215.926162)
		(width 0.0889)
		(layer "In2.Cu")
		(net "P5E_CPU1_PE1_TX_DP<4>")
	)
	(arc
		(start 115.212368 -219.18168)
		(mid 115.416703 -218.979075)
		(end 115.494816 -218.702128)
		(width 0.0889)
		(layer "In2.Cu")
		(net "P5E_CPU1_PE1_TX_DP<4>")
	)
	(arc
		(start 115.673378 -220.639132)
		(mid 115.542464 -220.502772)
		(end 115.494816 -220.319854)
		(width 0.0889)
		(layer "In2.Cu")
		(net "P5E_CPU1_PE1_TX_DP<4>")
	)
	(arc
		(start 115.02517 -222.773748)
		(mid 115.024925 -222.764352)
		(end 115.024916 -222.754952)
		(width 0.0889)
		(layer "In2.Cu")
		(net "P5E_CPU1_PE1_TX_DP<4>")
	)
	(arc
		(start 115.494562 -215.436704)
		(mid 115.494614 -215.429337)
		(end 115.494816 -215.421972)
		(width 0.0889)
		(layer "In2.Cu")
		(net "P5E_CPU1_PE1_TX_DP<4>")
	)
	(arc
		(start 115.203478 -223.080834)
		(mid 115.075667 -222.949741)
		(end 115.02517 -222.773748)
		(width 0.0889)
		(layer "In2.Cu")
		(net "P5E_CPU1_PE1_TX_DP<4>")
	)
	(arc
		(start 115.494816 -223.557084)
		(mid 115.414654 -223.284895)
		(end 115.212368 -223.085914)
		(width 0.0889)
		(layer "In2.Cu")
		(net "P5E_CPU1_PE1_TX_DP<4>")
	)
	(arc
		(start 115.024916 -219.516198)
		(mid 115.024822 -219.507816)
		(end 115.024916 -219.499434)
		(width 0.0889)
		(layer "In2.Cu")
		(net "P5E_CPU1_PE1_TX_DP<4>")
	)
	(arc
		(start 115.494816 -217.064336)
		(mid 115.422581 -216.787812)
		(end 115.224306 -216.58199)
		(width 0.0889)
		(layer "In2.Cu")
		(net "P5E_CPU1_PE1_TX_DP<4>")
	)
	(arc
		(start 115.024916 -219.499434)
		(mid 115.074169 -219.320234)
		(end 115.203478 -219.18676)
		(width 0.0889)
		(layer "In2.Cu")
		(net "P5E_CPU1_PE1_TX_DP<4>")
	)
	(arc
		(start 115.690904 -215.106504)
		(mid 115.891009 -214.900454)
		(end 115.963954 -214.622634)
		(width 0.0889)
		(layer "In2.Cu")
		(net "P5E_CPU1_PE1_TX_DP<4>")
	)
	(arc
		(start 115.68811 -221.619826)
		(mid 115.890697 -221.413475)
		(end 115.964716 -221.133924)
		(width 0.0889)
		(layer "In2.Cu")
		(net "P5E_CPU1_PE1_TX_DP<4>")
	)
	(arc
		(start 115.736878 -224.843086)
		(mid 115.74545 -224.836564)
		(end 115.753896 -224.829878)
		(width 0.0889)
		(layer "In2.Cu")
		(net "P5E_CPU1_PE1_TX_DP<4>")
	)
	(arc
		(start 115.753896 -224.829878)
		(mid 115.909294 -224.633597)
		(end 115.964716 -224.389442)
		(width 0.0889)
		(layer "In2.Cu")
		(net "P5E_CPU1_PE1_TX_DP<4>")
	)
	(arc
		(start 115.494816 -221.939104)
		(mid 115.547086 -221.756739)
		(end 115.682014 -221.623382)
		(width 0.0889)
		(layer "In2.Cu")
		(net "P5E_CPU1_PE1_TX_DP<4>")
	)
	(arc
		(start 115.68811 -218.364308)
		(mid 115.890697 -218.157957)
		(end 115.964716 -217.878406)
		(width 0.0889)
		(layer "In2.Cu")
		(net "P5E_CPU1_PE1_TX_DP<4>")
	)
	(arc
		(start 115.203478 -219.825316)
		(mid 115.075074 -219.693371)
		(end 115.024916 -219.516198)
		(width 0.0889)
		(layer "In2.Cu")
		(net "P5E_CPU1_PE1_TX_DP<4>")
	)
	(arc
		(start 115.964716 -221.115382)
		(mid 115.884554 -220.843193)
		(end 115.682268 -220.644212)
		(width 0.0889)
		(layer "In2.Cu")
		(net "P5E_CPU1_PE1_TX_DP<4>")
	)
	(arc
		(start 115.212114 -216.574878)
		(mid 115.077181 -216.441524)
		(end 115.024916 -216.259156)
		(width 0.0889)
		(layer "In2.Cu")
		(net "P5E_CPU1_PE1_TX_DP<4>")
	)
	(arc
		(start 115.673378 -217.383614)
		(mid 115.542464 -217.247254)
		(end 115.494816 -217.064336)
		(width 0.0889)
		(layer "In2.Cu")
		(net "P5E_CPU1_PE1_TX_DP<4>")
	)
	(arc
		(start 115.964208 -214.424768)
		(mid 115.862579 -214.243564)
		(end 115.705128 -214.10803)
		(width 0.0889)
		(layer "In2.Cu")
		(net "P5E_CPU1_PE1_TX_DP<4>")
	)
	(segment
		(start 49.668684 -16.692626)
		(end 49.342294 -16.366236)
		(width 0.13208)
		(layer "F.Cu")
		(net "P5E_CPU1_PE1_TX_DP<3>")
	)
	(segment
		(start 116.339112 -224.925382)
		(end 116.339366 -224.925128)
		(width 0.13208)
		(layer "F.Cu")
		(net "P5E_CPU1_PE1_TX_DP<3>")
	)
	(segment
		(start 49.367694 -17.61236)
		(end 49.668684 -17.31137)
		(width 0.13208)
		(layer "F.Cu")
		(net "P5E_CPU1_PE1_TX_DP<3>")
	)
	(segment
		(start 49.668684 -17.31137)
		(end 49.668684 -16.692626)
		(width 0.13208)
		(layer "F.Cu")
		(net "P5E_CPU1_PE1_TX_DP<3>")
	)
	(segment
		(start 116.339366 -224.925128)
		(end 116.339366 -224.389442)
		(width 0.13208)
		(layer "F.Cu")
		(net "P5E_CPU1_PE1_TX_DP<3>")
	)
	(segment
		(start 116.243862 -215.436704)
		(end 116.243862 -215.414606)
		(width 0.0889)
		(layer "In2.Cu")
		(net "P5E_CPU1_PE1_TX_DP<3>")
	)
	(segment
		(start 116.243862 -217.07856)
		(end 116.243862 -217.0557)
		(width 0.0889)
		(layer "In2.Cu")
		(net "P5E_CPU1_PE1_TX_DP<3>")
	)
	(segment
		(start 116.202714 -213.220554)
		(end 116.202714 -210.170776)
		(width 0.14732)
		(layer "In2.Cu")
		(net "P5E_CPU1_PE1_TX_DP<3>")
	)
	(segment
		(start 116.520468 -218.20632)
		(end 116.525802 -218.203272)
		(width 0.0889)
		(layer "In2.Cu")
		(net "P5E_CPU1_PE1_TX_DP<3>")
	)
	(segment
		(start 116.49583 -224.118424)
		(end 116.4717 -224.02927)
		(width 0.0889)
		(layer "In2.Cu")
		(net "P5E_CPU1_PE1_TX_DP<3>")
	)
	(segment
		(start 116.243862 -223.575626)
		(end 116.243862 -223.56699)
		(width 0.0889)
		(layer "In2.Cu")
		(net "P5E_CPU1_PE1_TX_DP<3>")
	)
	(segment
		(start 116.243862 -220.338396)
		(end 116.243862 -220.311218)
		(width 0.0889)
		(layer "In2.Cu")
		(net "P5E_CPU1_PE1_TX_DP<3>")
	)
	(segment
		(start 116.05641 -215.761062)
		(end 116.0653 -215.755982)
		(width 0.0889)
		(layer "In2.Cu")
		(net "P5E_CPU1_PE1_TX_DP<3>")
	)
	(segment
		(start 116.526056 -214.946992)
		(end 116.534946 -214.941912)
		(width 0.0889)
		(layer "In2.Cu")
		(net "P5E_CPU1_PE1_TX_DP<3>")
	)
	(segment
		(start 116.244624 -213.294468)
		(end 116.244624 -213.284562)
		(width 0.0889)
		(layer "In2.Cu")
		(net "P5E_CPU1_PE1_TX_DP<3>")
	)
	(segment
		(start 116.528088 -218.202002)
		(end 116.535454 -218.197684)
		(width 0.0889)
		(layer "In2.Cu")
		(net "P5E_CPU1_PE1_TX_DP<3>")
	)
	(segment
		(start 115.774216 -219.515944)
		(end 115.774216 -219.490544)
		(width 0.0889)
		(layer "In2.Cu")
		(net "P5E_CPU1_PE1_TX_DP<3>")
	)
	(segment
		(start 49.662334 -17.907)
		(end 49.367694 -17.61236)
		(width 0.14732)
		(layer "In2.Cu")
		(net "P5E_CPU1_PE1_TX_DP<3>")
	)
	(segment
		(start 111.510572 -184.272682)
		(end 76.108306 -91.929966)
		(width 0.14732)
		(layer "In2.Cu")
		(net "P5E_CPU1_PE1_TX_DP<3>")
	)
	(segment
		(start 115.774216 -222.780098)
		(end 115.774216 -222.75165)
		(width 0.0889)
		(layer "In2.Cu")
		(net "P5E_CPU1_PE1_TX_DP<3>")
	)
	(segment
		(start 116.713508 -214.622634)
		(end 116.713508 -214.461344)
		(width 0.0889)
		(layer "In2.Cu")
		(net "P5E_CPU1_PE1_TX_DP<3>")
	)
	(segment
		(start 116.24437 -213.976966)
		(end 116.24437 -213.294722)
		(width 0.0889)
		(layer "In2.Cu")
		(net "P5E_CPU1_PE1_TX_DP<3>")
	)
	(segment
		(start 116.526564 -218.202764)
		(end 116.528088 -218.202002)
		(width 0.0889)
		(layer "In2.Cu")
		(net "P5E_CPU1_PE1_TX_DP<3>")
	)
	(segment
		(start 116.202714 -210.170776)
		(end 112.557814 -187.856876)
		(width 0.14732)
		(layer "In2.Cu")
		(net "P5E_CPU1_PE1_TX_DP<3>")
	)
	(segment
		(start 116.05641 -219.01658)
		(end 116.0653 -219.0115)
		(width 0.0889)
		(layer "In2.Cu")
		(net "P5E_CPU1_PE1_TX_DP<3>")
	)
	(segment
		(start 116.202714 -213.242652)
		(end 116.202714 -213.220554)
		(width 0.0889)
		(layer "In2.Cu")
		(net "P5E_CPU1_PE1_TX_DP<3>")
	)
	(segment
		(start 116.535454 -217.559128)
		(end 116.526564 -217.554048)
		(width 0.0889)
		(layer "In2.Cu")
		(net "P5E_CPU1_PE1_TX_DP<3>")
	)
	(segment
		(start 116.339366 -224.389442)
		(end 116.49583 -224.118424)
		(width 0.0889)
		(layer "In2.Cu")
		(net "P5E_CPU1_PE1_TX_DP<3>")
	)
	(segment
		(start 116.244624 -213.284562)
		(end 116.202714 -213.242652)
		(width 0.0889)
		(layer "In2.Cu")
		(net "P5E_CPU1_PE1_TX_DP<3>")
	)
	(segment
		(start 49.662334 -19.32305)
		(end 49.662334 -17.907)
		(width 0.14732)
		(layer "In2.Cu")
		(net "P5E_CPU1_PE1_TX_DP<3>")
	)
	(segment
		(start 116.24437 -213.294722)
		(end 116.244624 -213.294468)
		(width 0.0889)
		(layer "In2.Cu")
		(net "P5E_CPU1_PE1_TX_DP<3>")
	)
	(segment
		(start 115.774216 -216.260426)
		(end 115.774216 -216.235026)
		(width 0.0889)
		(layer "In2.Cu")
		(net "P5E_CPU1_PE1_TX_DP<3>")
	)
	(segment
		(start 116.5352 -220.814646)
		(end 116.52631 -220.809566)
		(width 0.0889)
		(layer "In2.Cu")
		(net "P5E_CPU1_PE1_TX_DP<3>")
	)
	(segment
		(start 116.525802 -218.203272)
		(end 116.526564 -218.202764)
		(width 0.0889)
		(layer "In2.Cu")
		(net "P5E_CPU1_PE1_TX_DP<3>")
	)
	(segment
		(start 116.52631 -221.458282)
		(end 116.5352 -221.453202)
		(width 0.0889)
		(layer "In2.Cu")
		(net "P5E_CPU1_PE1_TX_DP<3>")
	)
	(segment
		(start 76.108306 -91.929966)
		(end 55.44947 -46.87316)
		(width 0.14732)
		(layer "In2.Cu")
		(net "P5E_CPU1_PE1_TX_DP<3>")
	)
	(segment
		(start 116.529358 -214.261954)
		(end 116.24437 -213.976966)
		(width 0.0889)
		(layer "In2.Cu")
		(net "P5E_CPU1_PE1_TX_DP<3>")
	)
	(segment
		(start 112.557814 -187.856876)
		(end 111.510572 -184.272682)
		(width 0.14732)
		(layer "In2.Cu")
		(net "P5E_CPU1_PE1_TX_DP<3>")
	)
	(segment
		(start 55.44947 -46.87316)
		(end 49.662334 -19.32305)
		(width 0.14732)
		(layer "In2.Cu")
		(net "P5E_CPU1_PE1_TX_DP<3>")
	)
	(segment
		(start 116.243862 -221.956376)
		(end 116.243862 -221.937834)
		(width 0.0889)
		(layer "In2.Cu")
		(net "P5E_CPU1_PE1_TX_DP<3>")
	)
	(arc
		(start 116.056664 -223.251268)
		(mid 115.854378 -223.052287)
		(end 115.774216 -222.780098)
		(width 0.0889)
		(layer "In2.Cu")
		(net "P5E_CPU1_PE1_TX_DP<3>")
	)
	(arc
		(start 116.056664 -222.272098)
		(mid 116.191597 -222.138744)
		(end 116.243862 -221.956376)
		(width 0.0889)
		(layer "In2.Cu")
		(net "P5E_CPU1_PE1_TX_DP<3>")
	)
	(arc
		(start 116.4717 -224.02927)
		(mid 116.303946 -223.829492)
		(end 116.243862 -223.575626)
		(width 0.0889)
		(layer "In2.Cu")
		(net "P5E_CPU1_PE1_TX_DP<3>")
	)
	(arc
		(start 116.5352 -221.453202)
		(mid 116.713797 -221.133924)
		(end 116.5352 -220.814646)
		(width 0.0889)
		(layer "In2.Cu")
		(net "P5E_CPU1_PE1_TX_DP<3>")
	)
	(arc
		(start 116.526564 -217.554048)
		(mid 116.323083 -217.353244)
		(end 116.243862 -217.07856)
		(width 0.0889)
		(layer "In2.Cu")
		(net "P5E_CPU1_PE1_TX_DP<3>")
	)
	(arc
		(start 116.534946 -214.941912)
		(mid 116.66586 -214.805552)
		(end 116.713508 -214.622634)
		(width 0.0889)
		(layer "In2.Cu")
		(net "P5E_CPU1_PE1_TX_DP<3>")
	)
	(arc
		(start 116.243862 -223.56699)
		(mid 116.191592 -223.384625)
		(end 116.056664 -223.251268)
		(width 0.0889)
		(layer "In2.Cu")
		(net "P5E_CPU1_PE1_TX_DP<3>")
	)
	(arc
		(start 116.0653 -215.755982)
		(mid 116.196214 -215.619622)
		(end 116.243862 -215.436704)
		(width 0.0889)
		(layer "In2.Cu")
		(net "P5E_CPU1_PE1_TX_DP<3>")
	)
	(arc
		(start 116.243862 -218.692222)
		(mid 116.317853 -218.412656)
		(end 116.520468 -218.20632)
		(width 0.0889)
		(layer "In2.Cu")
		(net "P5E_CPU1_PE1_TX_DP<3>")
	)
	(arc
		(start 116.243862 -220.311218)
		(mid 116.191592 -220.128853)
		(end 116.056664 -219.995496)
		(width 0.0889)
		(layer "In2.Cu")
		(net "P5E_CPU1_PE1_TX_DP<3>")
	)
	(arc
		(start 115.774216 -222.75165)
		(mid 115.852327 -222.474701)
		(end 116.056664 -222.272098)
		(width 0.0889)
		(layer "In2.Cu")
		(net "P5E_CPU1_PE1_TX_DP<3>")
	)
	(arc
		(start 116.535454 -218.197684)
		(mid 116.714051 -217.878406)
		(end 116.535454 -217.559128)
		(width 0.0889)
		(layer "In2.Cu")
		(net "P5E_CPU1_PE1_TX_DP<3>")
	)
	(arc
		(start 116.713508 -214.461344)
		(mid 116.638503 -214.345885)
		(end 116.529358 -214.261954)
		(width 0.0889)
		(layer "In2.Cu")
		(net "P5E_CPU1_PE1_TX_DP<3>")
	)
	(arc
		(start 116.243862 -221.937834)
		(mid 116.321973 -221.660885)
		(end 116.52631 -221.458282)
		(width 0.0889)
		(layer "In2.Cu")
		(net "P5E_CPU1_PE1_TX_DP<3>")
	)
	(arc
		(start 116.056664 -216.739978)
		(mid 115.852329 -216.537373)
		(end 115.774216 -216.260426)
		(width 0.0889)
		(layer "In2.Cu")
		(net "P5E_CPU1_PE1_TX_DP<3>")
	)
	(arc
		(start 116.0653 -219.0115)
		(mid 116.196214 -218.87514)
		(end 116.243862 -218.692222)
		(width 0.0889)
		(layer "In2.Cu")
		(net "P5E_CPU1_PE1_TX_DP<3>")
	)
	(arc
		(start 116.243862 -217.0557)
		(mid 116.191592 -216.873335)
		(end 116.056664 -216.739978)
		(width 0.0889)
		(layer "In2.Cu")
		(net "P5E_CPU1_PE1_TX_DP<3>")
	)
	(arc
		(start 116.243862 -215.414606)
		(mid 116.324773 -215.144478)
		(end 116.526056 -214.946992)
		(width 0.0889)
		(layer "In2.Cu")
		(net "P5E_CPU1_PE1_TX_DP<3>")
	)
	(arc
		(start 116.056664 -219.995496)
		(mid 115.852329 -219.792891)
		(end 115.774216 -219.515944)
		(width 0.0889)
		(layer "In2.Cu")
		(net "P5E_CPU1_PE1_TX_DP<3>")
	)
	(arc
		(start 116.52631 -220.809566)
		(mid 116.324024 -220.610585)
		(end 116.243862 -220.338396)
		(width 0.0889)
		(layer "In2.Cu")
		(net "P5E_CPU1_PE1_TX_DP<3>")
	)
	(arc
		(start 115.774216 -219.490544)
		(mid 115.853586 -219.21681)
		(end 116.05641 -219.01658)
		(width 0.0889)
		(layer "In2.Cu")
		(net "P5E_CPU1_PE1_TX_DP<3>")
	)
	(arc
		(start 115.774216 -216.235026)
		(mid 115.853586 -215.961292)
		(end 116.05641 -215.761062)
		(width 0.0889)
		(layer "In2.Cu")
		(net "P5E_CPU1_PE1_TX_DP<3>")
	)
	(segment
		(start 52.7558 -18.83283)
		(end 52.7558 -18.219166)
		(width 0.13208)
		(layer "F.Cu")
		(net "P5E_CPU1_PE1_TX_DP<2>")
	)
	(segment
		(start 117.749066 -225.739198)
		(end 117.749066 -225.203512)
		(width 0.13208)
		(layer "F.Cu")
		(net "P5E_CPU1_PE1_TX_DP<2>")
	)
	(segment
		(start 117.749066 -225.203512)
		(end 117.748812 -225.203258)
		(width 0.13208)
		(layer "F.Cu")
		(net "P5E_CPU1_PE1_TX_DP<2>")
	)
	(segment
		(start 53.05933 -19.13636)
		(end 52.7558 -18.83283)
		(width 0.13208)
		(layer "F.Cu")
		(net "P5E_CPU1_PE1_TX_DP<2>")
	)
	(segment
		(start 52.7558 -18.219166)
		(end 53.08473 -17.890236)
		(width 0.13208)
		(layer "F.Cu")
		(net "P5E_CPU1_PE1_TX_DP<2>")
	)
	(segment
		(start 117.37467 -213.788244)
		(end 117.37467 -213.284816)
		(width 0.0889)
		(layer "In2.Cu")
		(net "P5E_CPU1_PE1_TX_DP<2>")
	)
	(segment
		(start 117.37467 -213.284816)
		(end 117.416834 -213.242652)
		(width 0.0889)
		(layer "In2.Cu")
		(net "P5E_CPU1_PE1_TX_DP<2>")
	)
	(segment
		(start 117.844316 -221.133924)
		(end 117.844316 -221.115382)
		(width 0.0889)
		(layer "In2.Cu")
		(net "P5E_CPU1_PE1_TX_DP<2>")
	)
	(segment
		(start 117.56009 -221.624144)
		(end 117.561614 -221.623382)
		(width 0.0889)
		(layer "In2.Cu")
		(net "P5E_CPU1_PE1_TX_DP<2>")
	)
	(segment
		(start 117.56009 -218.368626)
		(end 117.561614 -218.367864)
		(width 0.0889)
		(layer "In2.Cu")
		(net "P5E_CPU1_PE1_TX_DP<2>")
	)
	(segment
		(start 117.091968 -216.574878)
		(end 117.083078 -216.569798)
		(width 0.0889)
		(layer "In2.Cu")
		(net "P5E_CPU1_PE1_TX_DP<2>")
	)
	(segment
		(start 117.552724 -215.117426)
		(end 117.561614 -215.112346)
		(width 0.0889)
		(layer "In2.Cu")
		(net "P5E_CPU1_PE1_TX_DP<2>")
	)
	(segment
		(start 117.098064 -219.833952)
		(end 117.091968 -219.830396)
		(width 0.0889)
		(layer "In2.Cu")
		(net "P5E_CPU1_PE1_TX_DP<2>")
	)
	(segment
		(start 117.592348 -224.93224)
		(end 117.616478 -224.843086)
		(width 0.0889)
		(layer "In2.Cu")
		(net "P5E_CPU1_PE1_TX_DP<2>")
	)
	(segment
		(start 117.091968 -223.085914)
		(end 117.090952 -223.085406)
		(width 0.0889)
		(layer "In2.Cu")
		(net "P5E_CPU1_PE1_TX_DP<2>")
	)
	(segment
		(start 117.416834 -213.220554)
		(end 117.416834 -209.915252)
		(width 0.14732)
		(layer "In2.Cu")
		(net "P5E_CPU1_PE1_TX_DP<2>")
	)
	(segment
		(start 117.843808 -214.644732)
		(end 117.843808 -214.424768)
		(width 0.0889)
		(layer "In2.Cu")
		(net "P5E_CPU1_PE1_TX_DP<2>")
	)
	(segment
		(start 52.76469 -20.042632)
		(end 52.76469 -19.431)
		(width 0.14732)
		(layer "In2.Cu")
		(net "P5E_CPU1_PE1_TX_DP<2>")
	)
	(segment
		(start 117.552724 -221.628462)
		(end 117.56009 -221.624144)
		(width 0.0889)
		(layer "In2.Cu")
		(net "P5E_CPU1_PE1_TX_DP<2>")
	)
	(segment
		(start 117.090952 -223.085406)
		(end 117.083078 -223.080834)
		(width 0.0889)
		(layer "In2.Cu")
		(net "P5E_CPU1_PE1_TX_DP<2>")
	)
	(segment
		(start 52.76469 -19.431)
		(end 53.05933 -19.13636)
		(width 0.14732)
		(layer "In2.Cu")
		(net "P5E_CPU1_PE1_TX_DP<2>")
	)
	(segment
		(start 117.083078 -222.442278)
		(end 117.090952 -222.437706)
		(width 0.0889)
		(layer "In2.Cu")
		(net "P5E_CPU1_PE1_TX_DP<2>")
	)
	(segment
		(start 117.083078 -215.931242)
		(end 117.091968 -215.926162)
		(width 0.0889)
		(layer "In2.Cu")
		(net "P5E_CPU1_PE1_TX_DP<2>")
	)
	(segment
		(start 56.88711 -46.995842)
		(end 52.76469 -20.042632)
		(width 0.14732)
		(layer "In2.Cu")
		(net "P5E_CPU1_PE1_TX_DP<2>")
	)
	(segment
		(start 117.374162 -221.963234)
		(end 117.374162 -221.94774)
		(width 0.0889)
		(layer "In2.Cu")
		(net "P5E_CPU1_PE1_TX_DP<2>")
	)
	(segment
		(start 117.098064 -216.578434)
		(end 117.091968 -216.574878)
		(width 0.0889)
		(layer "In2.Cu")
		(net "P5E_CPU1_PE1_TX_DP<2>")
	)
	(segment
		(start 117.374162 -218.707716)
		(end 117.374162 -218.692222)
		(width 0.0889)
		(layer "In2.Cu")
		(net "P5E_CPU1_PE1_TX_DP<2>")
	)
	(segment
		(start 117.561868 -223.899984)
		(end 117.561106 -223.899476)
		(width 0.0889)
		(layer "In2.Cu")
		(net "P5E_CPU1_PE1_TX_DP<2>")
	)
	(segment
		(start 117.374416 -223.575626)
		(end 117.374416 -223.561402)
		(width 0.0889)
		(layer "In2.Cu")
		(net "P5E_CPU1_PE1_TX_DP<2>")
	)
	(segment
		(start 117.083078 -219.18676)
		(end 117.091968 -219.18168)
		(width 0.0889)
		(layer "In2.Cu")
		(net "P5E_CPU1_PE1_TX_DP<2>")
	)
	(segment
		(start 112.687862 -183.961024)
		(end 76.944474 -90.740738)
		(width 0.14732)
		(layer "In2.Cu")
		(net "P5E_CPU1_PE1_TX_DP<2>")
	)
	(segment
		(start 117.562376 -221.622874)
		(end 117.56771 -221.619826)
		(width 0.0889)
		(layer "In2.Cu")
		(net "P5E_CPU1_PE1_TX_DP<2>")
	)
	(segment
		(start 117.561106 -223.899476)
		(end 117.558566 -223.897952)
		(width 0.0889)
		(layer "In2.Cu")
		(net "P5E_CPU1_PE1_TX_DP<2>")
	)
	(segment
		(start 76.944474 -90.740738)
		(end 56.88711 -46.995842)
		(width 0.14732)
		(layer "In2.Cu")
		(net "P5E_CPU1_PE1_TX_DP<2>")
	)
	(segment
		(start 117.844316 -217.878406)
		(end 117.844316 -217.859864)
		(width 0.0889)
		(layer "In2.Cu")
		(net "P5E_CPU1_PE1_TX_DP<2>")
	)
	(segment
		(start 117.562376 -218.367356)
		(end 117.56771 -218.364308)
		(width 0.0889)
		(layer "In2.Cu")
		(net "P5E_CPU1_PE1_TX_DP<2>")
	)
	(segment
		(start 117.090952 -222.437706)
		(end 117.091968 -222.437198)
		(width 0.0889)
		(layer "In2.Cu")
		(net "P5E_CPU1_PE1_TX_DP<2>")
	)
	(segment
		(start 117.558566 -223.897952)
		(end 117.552978 -223.894904)
		(width 0.0889)
		(layer "In2.Cu")
		(net "P5E_CPU1_PE1_TX_DP<2>")
	)
	(segment
		(start 117.091968 -219.830396)
		(end 117.083078 -219.825316)
		(width 0.0889)
		(layer "In2.Cu")
		(net "P5E_CPU1_PE1_TX_DP<2>")
	)
	(segment
		(start 117.561614 -218.367864)
		(end 117.562376 -218.367356)
		(width 0.0889)
		(layer "In2.Cu")
		(net "P5E_CPU1_PE1_TX_DP<2>")
	)
	(segment
		(start 117.416834 -209.915252)
		(end 113.805462 -187.80379)
		(width 0.14732)
		(layer "In2.Cu")
		(net "P5E_CPU1_PE1_TX_DP<2>")
	)
	(segment
		(start 117.552724 -218.372944)
		(end 117.56009 -218.368626)
		(width 0.0889)
		(layer "In2.Cu")
		(net "P5E_CPU1_PE1_TX_DP<2>")
	)
	(segment
		(start 117.374162 -215.452198)
		(end 117.374162 -215.436704)
		(width 0.0889)
		(layer "In2.Cu")
		(net "P5E_CPU1_PE1_TX_DP<2>")
	)
	(segment
		(start 117.561614 -221.623382)
		(end 117.562376 -221.622874)
		(width 0.0889)
		(layer "In2.Cu")
		(net "P5E_CPU1_PE1_TX_DP<2>")
	)
	(segment
		(start 117.748812 -225.203258)
		(end 117.592348 -224.93224)
		(width 0.0889)
		(layer "In2.Cu")
		(net "P5E_CPU1_PE1_TX_DP<2>")
	)
	(segment
		(start 117.844316 -224.389442)
		(end 117.844316 -224.379536)
		(width 0.0889)
		(layer "In2.Cu")
		(net "P5E_CPU1_PE1_TX_DP<2>")
	)
	(segment
		(start 117.558566 -214.093552)
		(end 117.558312 -214.093552)
		(width 0.0889)
		(layer "In2.Cu")
		(net "P5E_CPU1_PE1_TX_DP<2>")
	)
	(segment
		(start 117.561868 -217.388694)
		(end 117.552978 -217.383614)
		(width 0.0889)
		(layer "In2.Cu")
		(net "P5E_CPU1_PE1_TX_DP<2>")
	)
	(segment
		(start 113.805462 -187.80379)
		(end 112.687862 -183.961024)
		(width 0.14732)
		(layer "In2.Cu")
		(net "P5E_CPU1_PE1_TX_DP<2>")
	)
	(segment
		(start 117.561868 -220.644212)
		(end 117.552978 -220.639132)
		(width 0.0889)
		(layer "In2.Cu")
		(net "P5E_CPU1_PE1_TX_DP<2>")
	)
	(segment
		(start 117.558566 -214.093298)
		(end 117.558566 -214.093552)
		(width 0.0889)
		(layer "In2.Cu")
		(net "P5E_CPU1_PE1_TX_DP<2>")
	)
	(segment
		(start 117.416834 -213.242652)
		(end 117.416834 -213.220554)
		(width 0.0889)
		(layer "In2.Cu")
		(net "P5E_CPU1_PE1_TX_DP<2>")
	)
	(arc
		(start 117.374416 -217.064336)
		(mid 117.3005 -216.784834)
		(end 117.098064 -216.578434)
		(width 0.0889)
		(layer "In2.Cu")
		(net "P5E_CPU1_PE1_TX_DP<2>")
	)
	(arc
		(start 117.552978 -217.383614)
		(mid 117.422064 -217.247254)
		(end 117.374416 -217.064336)
		(width 0.0889)
		(layer "In2.Cu")
		(net "P5E_CPU1_PE1_TX_DP<2>")
	)
	(arc
		(start 117.558312 -214.093552)
		(mid 117.424056 -213.966422)
		(end 117.37467 -213.788244)
		(width 0.0889)
		(layer "In2.Cu")
		(net "P5E_CPU1_PE1_TX_DP<2>")
	)
	(arc
		(start 117.083078 -219.825316)
		(mid 116.904602 -219.506038)
		(end 117.083078 -219.18676)
		(width 0.0889)
		(layer "In2.Cu")
		(net "P5E_CPU1_PE1_TX_DP<2>")
	)
	(arc
		(start 117.552978 -220.639132)
		(mid 117.422064 -220.502772)
		(end 117.374416 -220.319854)
		(width 0.0889)
		(layer "In2.Cu")
		(net "P5E_CPU1_PE1_TX_DP<2>")
	)
	(arc
		(start 117.616478 -224.843086)
		(mid 117.62505 -224.836564)
		(end 117.633496 -224.829878)
		(width 0.0889)
		(layer "In2.Cu")
		(net "P5E_CPU1_PE1_TX_DP<2>")
	)
	(arc
		(start 117.374416 -220.319854)
		(mid 117.3005 -220.040352)
		(end 117.098064 -219.833952)
		(width 0.0889)
		(layer "In2.Cu")
		(net "P5E_CPU1_PE1_TX_DP<2>")
	)
	(arc
		(start 117.561614 -215.112346)
		(mid 117.762896 -214.914859)
		(end 117.843808 -214.644732)
		(width 0.0889)
		(layer "In2.Cu")
		(net "P5E_CPU1_PE1_TX_DP<2>")
	)
	(arc
		(start 117.374162 -221.94774)
		(mid 117.421841 -221.76484)
		(end 117.552724 -221.628462)
		(width 0.0889)
		(layer "In2.Cu")
		(net "P5E_CPU1_PE1_TX_DP<2>")
	)
	(arc
		(start 116.90477 -222.751396)
		(mid 116.954785 -222.574265)
		(end 117.083078 -222.442278)
		(width 0.0889)
		(layer "In2.Cu")
		(net "P5E_CPU1_PE1_TX_DP<2>")
	)
	(arc
		(start 117.843808 -214.424768)
		(mid 117.732529 -214.232062)
		(end 117.558566 -214.093298)
		(width 0.0889)
		(layer "In2.Cu")
		(net "P5E_CPU1_PE1_TX_DP<2>")
	)
	(arc
		(start 117.374416 -223.561402)
		(mid 117.295275 -223.286779)
		(end 117.091968 -223.085914)
		(width 0.0889)
		(layer "In2.Cu")
		(net "P5E_CPU1_PE1_TX_DP<2>")
	)
	(arc
		(start 117.844316 -221.115382)
		(mid 117.764154 -220.843193)
		(end 117.561868 -220.644212)
		(width 0.0889)
		(layer "In2.Cu")
		(net "P5E_CPU1_PE1_TX_DP<2>")
	)
	(arc
		(start 117.374416 -215.421972)
		(mid 117.42547 -215.247392)
		(end 117.552724 -215.117426)
		(width 0.0889)
		(layer "In2.Cu")
		(net "P5E_CPU1_PE1_TX_DP<2>")
	)
	(arc
		(start 117.374162 -218.692222)
		(mid 117.421841 -218.509322)
		(end 117.552724 -218.372944)
		(width 0.0889)
		(layer "In2.Cu")
		(net "P5E_CPU1_PE1_TX_DP<2>")
	)
	(arc
		(start 117.552978 -223.894904)
		(mid 117.422064 -223.758544)
		(end 117.374416 -223.575626)
		(width 0.0889)
		(layer "In2.Cu")
		(net "P5E_CPU1_PE1_TX_DP<2>")
	)
	(arc
		(start 117.844316 -217.859864)
		(mid 117.764154 -217.587675)
		(end 117.561868 -217.388694)
		(width 0.0889)
		(layer "In2.Cu")
		(net "P5E_CPU1_PE1_TX_DP<2>")
	)
	(arc
		(start 117.091968 -222.437198)
		(mid 117.294791 -222.236967)
		(end 117.374162 -221.963234)
		(width 0.0889)
		(layer "In2.Cu")
		(net "P5E_CPU1_PE1_TX_DP<2>")
	)
	(arc
		(start 117.633496 -224.829878)
		(mid 117.788894 -224.633597)
		(end 117.844316 -224.389442)
		(width 0.0889)
		(layer "In2.Cu")
		(net "P5E_CPU1_PE1_TX_DP<2>")
	)
	(arc
		(start 116.905024 -222.776288)
		(mid 116.904691 -222.763844)
		(end 116.90477 -222.751396)
		(width 0.0889)
		(layer "In2.Cu")
		(net "P5E_CPU1_PE1_TX_DP<2>")
	)
	(arc
		(start 117.56771 -221.619826)
		(mid 117.770297 -221.413475)
		(end 117.844316 -221.133924)
		(width 0.0889)
		(layer "In2.Cu")
		(net "P5E_CPU1_PE1_TX_DP<2>")
	)
	(arc
		(start 117.56771 -218.364308)
		(mid 117.770297 -218.157957)
		(end 117.844316 -217.878406)
		(width 0.0889)
		(layer "In2.Cu")
		(net "P5E_CPU1_PE1_TX_DP<2>")
	)
	(arc
		(start 117.083078 -223.080834)
		(mid 116.955909 -222.950842)
		(end 116.905024 -222.776288)
		(width 0.0889)
		(layer "In2.Cu")
		(net "P5E_CPU1_PE1_TX_DP<2>")
	)
	(arc
		(start 117.083078 -216.569798)
		(mid 116.904602 -216.25052)
		(end 117.083078 -215.931242)
		(width 0.0889)
		(layer "In2.Cu")
		(net "P5E_CPU1_PE1_TX_DP<2>")
	)
	(arc
		(start 117.091968 -219.18168)
		(mid 117.294791 -218.981449)
		(end 117.374162 -218.707716)
		(width 0.0889)
		(layer "In2.Cu")
		(net "P5E_CPU1_PE1_TX_DP<2>")
	)
	(arc
		(start 117.844316 -224.379536)
		(mid 117.766205 -224.102587)
		(end 117.561868 -223.899984)
		(width 0.0889)
		(layer "In2.Cu")
		(net "P5E_CPU1_PE1_TX_DP<2>")
	)
	(arc
		(start 117.374162 -215.436704)
		(mid 117.374214 -215.429337)
		(end 117.374416 -215.421972)
		(width 0.0889)
		(layer "In2.Cu")
		(net "P5E_CPU1_PE1_TX_DP<2>")
	)
	(arc
		(start 117.091968 -215.926162)
		(mid 117.294791 -215.725931)
		(end 117.374162 -215.452198)
		(width 0.0889)
		(layer "In2.Cu")
		(net "P5E_CPU1_PE1_TX_DP<2>")
	)
	(segment
		(start 118.218712 -224.925382)
		(end 118.218966 -224.925128)
		(width 0.13208)
		(layer "F.Cu")
		(net "P5E_CPU1_PE1_TX_DP<1>")
	)
	(segment
		(start 54.98973 -17.61236)
		(end 55.29072 -17.31137)
		(width 0.13208)
		(layer "F.Cu")
		(net "P5E_CPU1_PE1_TX_DP<1>")
	)
	(segment
		(start 118.218966 -224.925128)
		(end 118.218966 -224.389442)
		(width 0.13208)
		(layer "F.Cu")
		(net "P5E_CPU1_PE1_TX_DP<1>")
	)
	(segment
		(start 55.29072 -16.692626)
		(end 54.96433 -16.366236)
		(width 0.13208)
		(layer "F.Cu")
		(net "P5E_CPU1_PE1_TX_DP<1>")
	)
	(segment
		(start 55.29072 -17.31137)
		(end 55.29072 -16.692626)
		(width 0.13208)
		(layer "F.Cu")
		(net "P5E_CPU1_PE1_TX_DP<1>")
	)
	(segment
		(start 118.123716 -213.284308)
		(end 118.081806 -213.242398)
		(width 0.0889)
		(layer "In2.Cu")
		(net "P5E_CPU1_PE1_TX_DP<1>")
	)
	(segment
		(start 55.28437 -17.907)
		(end 54.98973 -17.61236)
		(width 0.14732)
		(layer "In2.Cu")
		(net "P5E_CPU1_PE1_TX_DP<1>")
	)
	(segment
		(start 113.444782 -184.104534)
		(end 77.22743 -89.624408)
		(width 0.14732)
		(layer "In2.Cu")
		(net "P5E_CPU1_PE1_TX_DP<1>")
	)
	(segment
		(start 77.22743 -89.624408)
		(end 57.693306 -47.021242)
		(width 0.14732)
		(layer "In2.Cu")
		(net "P5E_CPU1_PE1_TX_DP<1>")
	)
	(segment
		(start 118.123462 -221.956376)
		(end 118.123462 -221.937834)
		(width 0.0889)
		(layer "In2.Cu")
		(net "P5E_CPU1_PE1_TX_DP<1>")
	)
	(segment
		(start 118.37543 -224.118424)
		(end 118.3513 -224.02927)
		(width 0.0889)
		(layer "In2.Cu")
		(net "P5E_CPU1_PE1_TX_DP<1>")
	)
	(segment
		(start 114.468402 -187.632594)
		(end 113.444782 -184.104534)
		(width 0.14732)
		(layer "In2.Cu")
		(net "P5E_CPU1_PE1_TX_DP<1>")
	)
	(segment
		(start 118.593108 -214.622634)
		(end 118.593108 -214.461344)
		(width 0.0889)
		(layer "In2.Cu")
		(net "P5E_CPU1_PE1_TX_DP<1>")
	)
	(segment
		(start 118.4148 -220.814646)
		(end 118.40591 -220.809566)
		(width 0.0889)
		(layer "In2.Cu")
		(net "P5E_CPU1_PE1_TX_DP<1>")
	)
	(segment
		(start 118.123462 -217.07856)
		(end 118.123462 -217.0557)
		(width 0.0889)
		(layer "In2.Cu")
		(net "P5E_CPU1_PE1_TX_DP<1>")
	)
	(segment
		(start 55.28437 -19.489166)
		(end 55.28437 -17.907)
		(width 0.14732)
		(layer "In2.Cu")
		(net "P5E_CPU1_PE1_TX_DP<1>")
	)
	(segment
		(start 117.653816 -216.260426)
		(end 117.653816 -216.235026)
		(width 0.0889)
		(layer "In2.Cu")
		(net "P5E_CPU1_PE1_TX_DP<1>")
	)
	(segment
		(start 117.93601 -215.761062)
		(end 117.9449 -215.755982)
		(width 0.0889)
		(layer "In2.Cu")
		(net "P5E_CPU1_PE1_TX_DP<1>")
	)
	(segment
		(start 117.93601 -219.01658)
		(end 117.9449 -219.0115)
		(width 0.0889)
		(layer "In2.Cu")
		(net "P5E_CPU1_PE1_TX_DP<1>")
	)
	(segment
		(start 57.693306 -47.021242)
		(end 55.28437 -19.489166)
		(width 0.14732)
		(layer "In2.Cu")
		(net "P5E_CPU1_PE1_TX_DP<1>")
	)
	(segment
		(start 118.405402 -218.203272)
		(end 118.406164 -218.202764)
		(width 0.0889)
		(layer "In2.Cu")
		(net "P5E_CPU1_PE1_TX_DP<1>")
	)
	(segment
		(start 118.081806 -209.75574)
		(end 114.468402 -187.632594)
		(width 0.14732)
		(layer "In2.Cu")
		(net "P5E_CPU1_PE1_TX_DP<1>")
	)
	(segment
		(start 118.123716 -213.976712)
		(end 118.123716 -213.284308)
		(width 0.0889)
		(layer "In2.Cu")
		(net "P5E_CPU1_PE1_TX_DP<1>")
	)
	(segment
		(start 118.407688 -218.202002)
		(end 118.415054 -218.197684)
		(width 0.0889)
		(layer "In2.Cu")
		(net "P5E_CPU1_PE1_TX_DP<1>")
	)
	(segment
		(start 118.081806 -213.242398)
		(end 118.081806 -213.2203)
		(width 0.0889)
		(layer "In2.Cu")
		(net "P5E_CPU1_PE1_TX_DP<1>")
	)
	(segment
		(start 118.406164 -218.202764)
		(end 118.407688 -218.202002)
		(width 0.0889)
		(layer "In2.Cu")
		(net "P5E_CPU1_PE1_TX_DP<1>")
	)
	(segment
		(start 118.40591 -221.458282)
		(end 118.4148 -221.453202)
		(width 0.0889)
		(layer "In2.Cu")
		(net "P5E_CPU1_PE1_TX_DP<1>")
	)
	(segment
		(start 118.218966 -224.389442)
		(end 118.37543 -224.118424)
		(width 0.0889)
		(layer "In2.Cu")
		(net "P5E_CPU1_PE1_TX_DP<1>")
	)
	(segment
		(start 118.123462 -215.436704)
		(end 118.123462 -215.414606)
		(width 0.0889)
		(layer "In2.Cu")
		(net "P5E_CPU1_PE1_TX_DP<1>")
	)
	(segment
		(start 118.415054 -217.559128)
		(end 118.406164 -217.554048)
		(width 0.0889)
		(layer "In2.Cu")
		(net "P5E_CPU1_PE1_TX_DP<1>")
	)
	(segment
		(start 118.123462 -220.338396)
		(end 118.123462 -220.311218)
		(width 0.0889)
		(layer "In2.Cu")
		(net "P5E_CPU1_PE1_TX_DP<1>")
	)
	(segment
		(start 118.405656 -214.946992)
		(end 118.414546 -214.941912)
		(width 0.0889)
		(layer "In2.Cu")
		(net "P5E_CPU1_PE1_TX_DP<1>")
	)
	(segment
		(start 118.408958 -214.261954)
		(end 118.123716 -213.976712)
		(width 0.0889)
		(layer "In2.Cu")
		(net "P5E_CPU1_PE1_TX_DP<1>")
	)
	(segment
		(start 118.123462 -223.575626)
		(end 118.123462 -223.56699)
		(width 0.0889)
		(layer "In2.Cu")
		(net "P5E_CPU1_PE1_TX_DP<1>")
	)
	(segment
		(start 117.653816 -219.515944)
		(end 117.653816 -219.490544)
		(width 0.0889)
		(layer "In2.Cu")
		(net "P5E_CPU1_PE1_TX_DP<1>")
	)
	(segment
		(start 118.400068 -218.20632)
		(end 118.405402 -218.203272)
		(width 0.0889)
		(layer "In2.Cu")
		(net "P5E_CPU1_PE1_TX_DP<1>")
	)
	(segment
		(start 117.653816 -222.780098)
		(end 117.653816 -222.75165)
		(width 0.0889)
		(layer "In2.Cu")
		(net "P5E_CPU1_PE1_TX_DP<1>")
	)
	(segment
		(start 118.081806 -213.2203)
		(end 118.081806 -209.75574)
		(width 0.14732)
		(layer "In2.Cu")
		(net "P5E_CPU1_PE1_TX_DP<1>")
	)
	(arc
		(start 118.123462 -218.692222)
		(mid 118.197453 -218.412656)
		(end 118.400068 -218.20632)
		(width 0.0889)
		(layer "In2.Cu")
		(net "P5E_CPU1_PE1_TX_DP<1>")
	)
	(arc
		(start 118.406164 -217.554048)
		(mid 118.202683 -217.353244)
		(end 118.123462 -217.07856)
		(width 0.0889)
		(layer "In2.Cu")
		(net "P5E_CPU1_PE1_TX_DP<1>")
	)
	(arc
		(start 117.9449 -219.0115)
		(mid 118.075814 -218.87514)
		(end 118.123462 -218.692222)
		(width 0.0889)
		(layer "In2.Cu")
		(net "P5E_CPU1_PE1_TX_DP<1>")
	)
	(arc
		(start 118.4148 -221.453202)
		(mid 118.593397 -221.133924)
		(end 118.4148 -220.814646)
		(width 0.0889)
		(layer "In2.Cu")
		(net "P5E_CPU1_PE1_TX_DP<1>")
	)
	(arc
		(start 118.426992 -214.272114)
		(mid 118.418038 -214.266923)
		(end 118.408958 -214.261954)
		(width 0.0889)
		(layer "In2.Cu")
		(net "P5E_CPU1_PE1_TX_DP<1>")
	)
	(arc
		(start 118.3513 -224.02927)
		(mid 118.183546 -223.829492)
		(end 118.123462 -223.575626)
		(width 0.0889)
		(layer "In2.Cu")
		(net "P5E_CPU1_PE1_TX_DP<1>")
	)
	(arc
		(start 118.123462 -220.311218)
		(mid 118.071192 -220.128853)
		(end 117.936264 -219.995496)
		(width 0.0889)
		(layer "In2.Cu")
		(net "P5E_CPU1_PE1_TX_DP<1>")
	)
	(arc
		(start 117.653816 -216.235026)
		(mid 117.733186 -215.961292)
		(end 117.93601 -215.761062)
		(width 0.0889)
		(layer "In2.Cu")
		(net "P5E_CPU1_PE1_TX_DP<1>")
	)
	(arc
		(start 118.415054 -218.197684)
		(mid 118.593651 -217.878406)
		(end 118.415054 -217.559128)
		(width 0.0889)
		(layer "In2.Cu")
		(net "P5E_CPU1_PE1_TX_DP<1>")
	)
	(arc
		(start 117.653816 -222.75165)
		(mid 117.731927 -222.474701)
		(end 117.936264 -222.272098)
		(width 0.0889)
		(layer "In2.Cu")
		(net "P5E_CPU1_PE1_TX_DP<1>")
	)
	(arc
		(start 118.414546 -214.941912)
		(mid 118.54546 -214.805552)
		(end 118.593108 -214.622634)
		(width 0.0889)
		(layer "In2.Cu")
		(net "P5E_CPU1_PE1_TX_DP<1>")
	)
	(arc
		(start 117.936264 -223.251268)
		(mid 117.733978 -223.052287)
		(end 117.653816 -222.780098)
		(width 0.0889)
		(layer "In2.Cu")
		(net "P5E_CPU1_PE1_TX_DP<1>")
	)
	(arc
		(start 118.123462 -217.0557)
		(mid 118.071192 -216.873335)
		(end 117.936264 -216.739978)
		(width 0.0889)
		(layer "In2.Cu")
		(net "P5E_CPU1_PE1_TX_DP<1>")
	)
	(arc
		(start 118.123462 -221.937834)
		(mid 118.201573 -221.660885)
		(end 118.40591 -221.458282)
		(width 0.0889)
		(layer "In2.Cu")
		(net "P5E_CPU1_PE1_TX_DP<1>")
	)
	(arc
		(start 117.653816 -219.490544)
		(mid 117.733186 -219.21681)
		(end 117.93601 -219.01658)
		(width 0.0889)
		(layer "In2.Cu")
		(net "P5E_CPU1_PE1_TX_DP<1>")
	)
	(arc
		(start 117.9449 -215.755982)
		(mid 118.075814 -215.619622)
		(end 118.123462 -215.436704)
		(width 0.0889)
		(layer "In2.Cu")
		(net "P5E_CPU1_PE1_TX_DP<1>")
	)
	(arc
		(start 117.936264 -216.739978)
		(mid 117.731929 -216.537373)
		(end 117.653816 -216.260426)
		(width 0.0889)
		(layer "In2.Cu")
		(net "P5E_CPU1_PE1_TX_DP<1>")
	)
	(arc
		(start 118.40591 -220.809566)
		(mid 118.203624 -220.610585)
		(end 118.123462 -220.338396)
		(width 0.0889)
		(layer "In2.Cu")
		(net "P5E_CPU1_PE1_TX_DP<1>")
	)
	(arc
		(start 117.936264 -219.995496)
		(mid 117.731929 -219.792891)
		(end 117.653816 -219.515944)
		(width 0.0889)
		(layer "In2.Cu")
		(net "P5E_CPU1_PE1_TX_DP<1>")
	)
	(arc
		(start 118.593108 -214.461344)
		(mid 118.525028 -214.353577)
		(end 118.426992 -214.272114)
		(width 0.0889)
		(layer "In2.Cu")
		(net "P5E_CPU1_PE1_TX_DP<1>")
	)
	(arc
		(start 117.936264 -222.272098)
		(mid 118.071197 -222.138744)
		(end 118.123462 -221.956376)
		(width 0.0889)
		(layer "In2.Cu")
		(net "P5E_CPU1_PE1_TX_DP<1>")
	)
	(arc
		(start 118.123462 -223.56699)
		(mid 118.071192 -223.384625)
		(end 117.936264 -223.251268)
		(width 0.0889)
		(layer "In2.Cu")
		(net "P5E_CPU1_PE1_TX_DP<1>")
	)
	(arc
		(start 118.123462 -215.414606)
		(mid 118.204373 -215.144478)
		(end 118.405656 -214.946992)
		(width 0.0889)
		(layer "In2.Cu")
		(net "P5E_CPU1_PE1_TX_DP<1>")
	)
	(segment
		(start 105.061766 -224.925128)
		(end 105.061766 -224.389442)
		(width 0.13208)
		(layer "F.Cu")
		(net "P5E_CPU1_PE1_TX_DP<15>")
	)
	(segment
		(start 15.533878 -17.61236)
		(end 15.834868 -17.31137)
		(width 0.13208)
		(layer "F.Cu")
		(net "P5E_CPU1_PE1_TX_DP<15>")
	)
	(segment
		(start 15.834868 -16.692626)
		(end 15.508478 -16.366236)
		(width 0.13208)
		(layer "F.Cu")
		(net "P5E_CPU1_PE1_TX_DP<15>")
	)
	(segment
		(start 105.061512 -224.925382)
		(end 105.061766 -224.925128)
		(width 0.13208)
		(layer "F.Cu")
		(net "P5E_CPU1_PE1_TX_DP<15>")
	)
	(segment
		(start 15.834868 -17.31137)
		(end 15.834868 -16.692626)
		(width 0.13208)
		(layer "F.Cu")
		(net "P5E_CPU1_PE1_TX_DP<15>")
	)
	(segment
		(start 105.242868 -221.461838)
		(end 105.248202 -221.45879)
		(width 0.0889)
		(layer "In2.Cu")
		(net "P5E_CPU1_PE1_TX_DP<15>")
	)
	(segment
		(start 104.308656 -214.946992)
		(end 104.317546 -214.941912)
		(width 0.0889)
		(layer "In2.Cu")
		(net "P5E_CPU1_PE1_TX_DP<15>")
	)
	(segment
		(start 105.257854 -220.814646)
		(end 105.248964 -220.809566)
		(width 0.0889)
		(layer "In2.Cu")
		(net "P5E_CPU1_PE1_TX_DP<15>")
	)
	(segment
		(start 104.966262 -223.575626)
		(end 104.966262 -223.56699)
		(width 0.0889)
		(layer "In2.Cu")
		(net "P5E_CPU1_PE1_TX_DP<15>")
	)
	(segment
		(start 103.98506 -212.917786)
		(end 103.872792 -212.354414)
		(width 0.14732)
		(layer "In2.Cu")
		(net "P5E_CPU1_PE1_TX_DP<15>")
	)
	(segment
		(start 66.664078 -98.711004)
		(end 49.432464 -61.129926)
		(width 0.14732)
		(layer "In2.Cu")
		(net "P5E_CPU1_PE1_TX_DP<15>")
	)
	(segment
		(start 105.061766 -224.389442)
		(end 105.21823 -224.118424)
		(width 0.0889)
		(layer "In2.Cu")
		(net "P5E_CPU1_PE1_TX_DP<15>")
	)
	(segment
		(start 15.828518 -17.907)
		(end 15.533878 -17.61236)
		(width 0.14732)
		(layer "In2.Cu")
		(net "P5E_CPU1_PE1_TX_DP<15>")
	)
	(segment
		(start 100.757482 -188.210444)
		(end 100.339144 -186.553348)
		(width 0.14732)
		(layer "In2.Cu")
		(net "P5E_CPU1_PE1_TX_DP<15>")
	)
	(segment
		(start 104.026462 -215.436704)
		(end 104.026462 -215.414606)
		(width 0.0889)
		(layer "In2.Cu")
		(net "P5E_CPU1_PE1_TX_DP<15>")
	)
	(segment
		(start 104.77881 -222.272098)
		(end 104.7877 -222.267018)
		(width 0.0889)
		(layer "In2.Cu")
		(net "P5E_CPU1_PE1_TX_DP<15>")
	)
	(segment
		(start 105.248202 -221.45879)
		(end 105.248964 -221.458282)
		(width 0.0889)
		(layer "In2.Cu")
		(net "P5E_CPU1_PE1_TX_DP<15>")
	)
	(segment
		(start 104.496616 -222.780098)
		(end 104.496616 -222.746062)
		(width 0.0889)
		(layer "In2.Cu")
		(net "P5E_CPU1_PE1_TX_DP<15>")
	)
	(segment
		(start 103.98506 -213.242652)
		(end 103.98506 -213.220554)
		(width 0.0889)
		(layer "In2.Cu")
		(net "P5E_CPU1_PE1_TX_DP<15>")
	)
	(segment
		(start 104.091486 -214.04326)
		(end 104.02697 -213.888066)
		(width 0.0889)
		(layer "In2.Cu")
		(net "P5E_CPU1_PE1_TX_DP<15>")
	)
	(segment
		(start 104.496362 -214.448136)
		(end 104.091486 -214.04326)
		(width 0.0889)
		(layer "In2.Cu")
		(net "P5E_CPU1_PE1_TX_DP<15>")
	)
	(segment
		(start 105.248964 -221.458282)
		(end 105.250488 -221.45752)
		(width 0.0889)
		(layer "In2.Cu")
		(net "P5E_CPU1_PE1_TX_DP<15>")
	)
	(segment
		(start 100.339144 -186.553348)
		(end 66.664078 -98.711004)
		(width 0.14732)
		(layer "In2.Cu")
		(net "P5E_CPU1_PE1_TX_DP<15>")
	)
	(segment
		(start 104.779826 -218.368372)
		(end 104.77881 -218.367864)
		(width 0.0889)
		(layer "In2.Cu")
		(net "P5E_CPU1_PE1_TX_DP<15>")
	)
	(segment
		(start 104.300274 -215.920574)
		(end 104.30637 -215.924384)
		(width 0.0889)
		(layer "In2.Cu")
		(net "P5E_CPU1_PE1_TX_DP<15>")
	)
	(segment
		(start 104.966262 -220.334078)
		(end 104.966262 -220.311218)
		(width 0.0889)
		(layer "In2.Cu")
		(net "P5E_CPU1_PE1_TX_DP<15>")
	)
	(segment
		(start 104.30637 -215.924384)
		(end 104.303068 -215.922606)
		(width 0.0889)
		(layer "In2.Cu")
		(net "P5E_CPU1_PE1_TX_DP<15>")
	)
	(segment
		(start 15.828518 -18.70964)
		(end 15.828518 -17.907)
		(width 0.14732)
		(layer "In2.Cu")
		(net "P5E_CPU1_PE1_TX_DP<15>")
	)
	(segment
		(start 104.318054 -215.931242)
		(end 104.300274 -215.920574)
		(width 0.0889)
		(layer "In2.Cu")
		(net "P5E_CPU1_PE1_TX_DP<15>")
	)
	(segment
		(start 104.77881 -219.01658)
		(end 104.7877 -219.0115)
		(width 0.0889)
		(layer "In2.Cu")
		(net "P5E_CPU1_PE1_TX_DP<15>")
	)
	(segment
		(start 104.966262 -217.072972)
		(end 104.966262 -217.0557)
		(width 0.0889)
		(layer "In2.Cu")
		(net "P5E_CPU1_PE1_TX_DP<15>")
	)
	(segment
		(start 104.02697 -213.284562)
		(end 103.98506 -213.242652)
		(width 0.0889)
		(layer "In2.Cu")
		(net "P5E_CPU1_PE1_TX_DP<15>")
	)
	(segment
		(start 104.495854 -214.637366)
		(end 104.496362 -214.624412)
		(width 0.0889)
		(layer "In2.Cu")
		(net "P5E_CPU1_PE1_TX_DP<15>")
	)
	(segment
		(start 104.496362 -214.624412)
		(end 104.496362 -214.448136)
		(width 0.0889)
		(layer "In2.Cu")
		(net "P5E_CPU1_PE1_TX_DP<15>")
	)
	(segment
		(start 104.496616 -219.515944)
		(end 104.496616 -219.490544)
		(width 0.0889)
		(layer "In2.Cu")
		(net "P5E_CPU1_PE1_TX_DP<15>")
	)
	(segment
		(start 104.02697 -213.888066)
		(end 104.02697 -213.284562)
		(width 0.0889)
		(layer "In2.Cu")
		(net "P5E_CPU1_PE1_TX_DP<15>")
	)
	(segment
		(start 104.7877 -218.372944)
		(end 104.779826 -218.368372)
		(width 0.0889)
		(layer "In2.Cu")
		(net "P5E_CPU1_PE1_TX_DP<15>")
	)
	(segment
		(start 105.250488 -221.45752)
		(end 105.257854 -221.453202)
		(width 0.0889)
		(layer "In2.Cu")
		(net "P5E_CPU1_PE1_TX_DP<15>")
	)
	(segment
		(start 103.98506 -213.220554)
		(end 103.98506 -212.917786)
		(width 0.14732)
		(layer "In2.Cu")
		(net "P5E_CPU1_PE1_TX_DP<15>")
	)
	(segment
		(start 104.496616 -217.8939)
		(end 104.496616 -217.859864)
		(width 0.0889)
		(layer "In2.Cu")
		(net "P5E_CPU1_PE1_TX_DP<15>")
	)
	(segment
		(start 105.21823 -224.118424)
		(end 105.1941 -224.02927)
		(width 0.0889)
		(layer "In2.Cu")
		(net "P5E_CPU1_PE1_TX_DP<15>")
	)
	(segment
		(start 104.496616 -216.260426)
		(end 104.496616 -216.25052)
		(width 0.0889)
		(layer "In2.Cu")
		(net "P5E_CPU1_PE1_TX_DP<15>")
	)
	(segment
		(start 49.432464 -61.129926)
		(end 15.828518 -18.70964)
		(width 0.14732)
		(layer "In2.Cu")
		(net "P5E_CPU1_PE1_TX_DP<15>")
	)
	(segment
		(start 103.872792 -212.354414)
		(end 100.757482 -188.210444)
		(width 0.14732)
		(layer "In2.Cu")
		(net "P5E_CPU1_PE1_TX_DP<15>")
	)
	(arc
		(start 104.317546 -214.941912)
		(mid 104.4448 -214.811946)
		(end 104.495854 -214.637366)
		(width 0.0889)
		(layer "In2.Cu")
		(net "P5E_CPU1_PE1_TX_DP<15>")
	)
	(arc
		(start 104.7877 -219.0115)
		(mid 104.966176 -218.692222)
		(end 104.7877 -218.372944)
		(width 0.0889)
		(layer "In2.Cu")
		(net "P5E_CPU1_PE1_TX_DP<15>")
	)
	(arc
		(start 105.257854 -221.453202)
		(mid 105.436451 -221.133924)
		(end 105.257854 -220.814646)
		(width 0.0889)
		(layer "In2.Cu")
		(net "P5E_CPU1_PE1_TX_DP<15>")
	)
	(arc
		(start 104.966262 -217.0557)
		(mid 104.913992 -216.873335)
		(end 104.779064 -216.739978)
		(width 0.0889)
		(layer "In2.Cu")
		(net "P5E_CPU1_PE1_TX_DP<15>")
	)
	(arc
		(start 104.7877 -222.267018)
		(mid 104.918614 -222.130658)
		(end 104.966262 -221.94774)
		(width 0.0889)
		(layer "In2.Cu")
		(net "P5E_CPU1_PE1_TX_DP<15>")
	)
	(arc
		(start 105.248964 -220.809566)
		(mid 105.045483 -220.608762)
		(end 104.966262 -220.334078)
		(width 0.0889)
		(layer "In2.Cu")
		(net "P5E_CPU1_PE1_TX_DP<15>")
	)
	(arc
		(start 104.496616 -219.490544)
		(mid 104.575986 -219.21681)
		(end 104.77881 -219.01658)
		(width 0.0889)
		(layer "In2.Cu")
		(net "P5E_CPU1_PE1_TX_DP<15>")
	)
	(arc
		(start 104.966262 -221.94774)
		(mid 105.040253 -221.668174)
		(end 105.242868 -221.461838)
		(width 0.0889)
		(layer "In2.Cu")
		(net "P5E_CPU1_PE1_TX_DP<15>")
	)
	(arc
		(start 104.779064 -223.251268)
		(mid 104.576778 -223.052287)
		(end 104.496616 -222.780098)
		(width 0.0889)
		(layer "In2.Cu")
		(net "P5E_CPU1_PE1_TX_DP<15>")
	)
	(arc
		(start 104.496616 -216.25052)
		(mid 104.448937 -216.06762)
		(end 104.318054 -215.931242)
		(width 0.0889)
		(layer "In2.Cu")
		(net "P5E_CPU1_PE1_TX_DP<15>")
	)
	(arc
		(start 104.303068 -215.922606)
		(mid 104.100481 -215.716255)
		(end 104.026462 -215.436704)
		(width 0.0889)
		(layer "In2.Cu")
		(net "P5E_CPU1_PE1_TX_DP<15>")
	)
	(arc
		(start 104.966262 -220.311218)
		(mid 104.913992 -220.128853)
		(end 104.779064 -219.995496)
		(width 0.0889)
		(layer "In2.Cu")
		(net "P5E_CPU1_PE1_TX_DP<15>")
	)
	(arc
		(start 105.1941 -224.02927)
		(mid 105.026346 -223.829492)
		(end 104.966262 -223.575626)
		(width 0.0889)
		(layer "In2.Cu")
		(net "P5E_CPU1_PE1_TX_DP<15>")
	)
	(arc
		(start 104.779064 -217.388694)
		(mid 104.913997 -217.25534)
		(end 104.966262 -217.072972)
		(width 0.0889)
		(layer "In2.Cu")
		(net "P5E_CPU1_PE1_TX_DP<15>")
	)
	(arc
		(start 104.77881 -218.367864)
		(mid 104.575987 -218.167633)
		(end 104.496616 -217.8939)
		(width 0.0889)
		(layer "In2.Cu")
		(net "P5E_CPU1_PE1_TX_DP<15>")
	)
	(arc
		(start 104.966262 -223.56699)
		(mid 104.913992 -223.384625)
		(end 104.779064 -223.251268)
		(width 0.0889)
		(layer "In2.Cu")
		(net "P5E_CPU1_PE1_TX_DP<15>")
	)
	(arc
		(start 104.026462 -215.414606)
		(mid 104.107373 -215.144478)
		(end 104.308656 -214.946992)
		(width 0.0889)
		(layer "In2.Cu")
		(net "P5E_CPU1_PE1_TX_DP<15>")
	)
	(arc
		(start 104.779064 -216.739978)
		(mid 104.574729 -216.537373)
		(end 104.496616 -216.260426)
		(width 0.0889)
		(layer "In2.Cu")
		(net "P5E_CPU1_PE1_TX_DP<15>")
	)
	(arc
		(start 104.496616 -222.746062)
		(mid 104.575986 -222.472328)
		(end 104.77881 -222.272098)
		(width 0.0889)
		(layer "In2.Cu")
		(net "P5E_CPU1_PE1_TX_DP<15>")
	)
	(arc
		(start 104.496616 -217.859864)
		(mid 104.576778 -217.587675)
		(end 104.779064 -217.388694)
		(width 0.0889)
		(layer "In2.Cu")
		(net "P5E_CPU1_PE1_TX_DP<15>")
	)
	(arc
		(start 104.779064 -219.995496)
		(mid 104.574729 -219.792891)
		(end 104.496616 -219.515944)
		(width 0.0889)
		(layer "In2.Cu")
		(net "P5E_CPU1_PE1_TX_DP<15>")
	)
	(segment
		(start 18.887948 -18.219166)
		(end 19.216878 -17.890236)
		(width 0.13208)
		(layer "F.Cu")
		(net "P5E_CPU1_PE1_TX_DP<14>")
	)
	(segment
		(start 19.191478 -19.13636)
		(end 18.887948 -18.83283)
		(width 0.13208)
		(layer "F.Cu")
		(net "P5E_CPU1_PE1_TX_DP<14>")
	)
	(segment
		(start 106.471212 -225.738944)
		(end 106.471212 -225.203258)
		(width 0.13208)
		(layer "F.Cu")
		(net "P5E_CPU1_PE1_TX_DP<14>")
	)
	(segment
		(start 106.471466 -225.739198)
		(end 106.471212 -225.738944)
		(width 0.13208)
		(layer "F.Cu")
		(net "P5E_CPU1_PE1_TX_DP<14>")
	)
	(segment
		(start 18.887948 -18.83283)
		(end 18.887948 -18.219166)
		(width 0.13208)
		(layer "F.Cu")
		(net "P5E_CPU1_PE1_TX_DP<14>")
	)
	(segment
		(start 105.813352 -223.085406)
		(end 105.805478 -223.080834)
		(width 0.0889)
		(layer "In2.Cu")
		(net "P5E_CPU1_PE1_TX_DP<14>")
	)
	(segment
		(start 105.814368 -216.574878)
		(end 105.805478 -216.569798)
		(width 0.0889)
		(layer "In2.Cu")
		(net "P5E_CPU1_PE1_TX_DP<14>")
	)
	(segment
		(start 106.284268 -223.899984)
		(end 106.283506 -223.899476)
		(width 0.0889)
		(layer "In2.Cu")
		(net "P5E_CPU1_PE1_TX_DP<14>")
	)
	(segment
		(start 18.899378 -19.967448)
		(end 18.899378 -19.42846)
		(width 0.14732)
		(layer "In2.Cu")
		(net "P5E_CPU1_PE1_TX_DP<14>")
	)
	(segment
		(start 106.566716 -224.389442)
		(end 106.566716 -224.379536)
		(width 0.0889)
		(layer "In2.Cu")
		(net "P5E_CPU1_PE1_TX_DP<14>")
	)
	(segment
		(start 105.626408 -214.644732)
		(end 105.626408 -214.424768)
		(width 0.0889)
		(layer "In2.Cu")
		(net "P5E_CPU1_PE1_TX_DP<14>")
	)
	(segment
		(start 105.198926 -213.220554)
		(end 105.198926 -212.706458)
		(width 0.14732)
		(layer "In2.Cu")
		(net "P5E_CPU1_PE1_TX_DP<14>")
	)
	(segment
		(start 106.096562 -218.707716)
		(end 106.096562 -218.676728)
		(width 0.0889)
		(layer "In2.Cu")
		(net "P5E_CPU1_PE1_TX_DP<14>")
	)
	(segment
		(start 105.820464 -216.578434)
		(end 105.814368 -216.574878)
		(width 0.0889)
		(layer "In2.Cu")
		(net "P5E_CPU1_PE1_TX_DP<14>")
	)
	(segment
		(start 105.820464 -219.833952)
		(end 105.806748 -219.825824)
		(width 0.0889)
		(layer "In2.Cu")
		(net "P5E_CPU1_PE1_TX_DP<14>")
	)
	(segment
		(start 101.505766 -186.215274)
		(end 67.813936 -98.328988)
		(width 0.14732)
		(layer "In2.Cu")
		(net "P5E_CPU1_PE1_TX_DP<14>")
	)
	(segment
		(start 105.156762 -213.284816)
		(end 105.198926 -213.242652)
		(width 0.0889)
		(layer "In2.Cu")
		(net "P5E_CPU1_PE1_TX_DP<14>")
	)
	(segment
		(start 105.806494 -219.825824)
		(end 105.805478 -219.825316)
		(width 0.0889)
		(layer "In2.Cu")
		(net "P5E_CPU1_PE1_TX_DP<14>")
	)
	(segment
		(start 105.814368 -223.085914)
		(end 105.813352 -223.085406)
		(width 0.0889)
		(layer "In2.Cu")
		(net "P5E_CPU1_PE1_TX_DP<14>")
	)
	(segment
		(start 105.085896 -211.02955)
		(end 101.949504 -187.949078)
		(width 0.14732)
		(layer "In2.Cu")
		(net "P5E_CPU1_PE1_TX_DP<14>")
	)
	(segment
		(start 106.28249 -221.624144)
		(end 106.284014 -221.623382)
		(width 0.0889)
		(layer "In2.Cu")
		(net "P5E_CPU1_PE1_TX_DP<14>")
	)
	(segment
		(start 106.280966 -223.897952)
		(end 106.275378 -223.894904)
		(width 0.0889)
		(layer "In2.Cu")
		(net "P5E_CPU1_PE1_TX_DP<14>")
	)
	(segment
		(start 105.806748 -219.825824)
		(end 105.806494 -219.825824)
		(width 0.0889)
		(layer "In2.Cu")
		(net "P5E_CPU1_PE1_TX_DP<14>")
	)
	(segment
		(start 105.367328 -214.10803)
		(end 105.156762 -213.897718)
		(width 0.0889)
		(layer "In2.Cu")
		(net "P5E_CPU1_PE1_TX_DP<14>")
	)
	(segment
		(start 105.335324 -215.117426)
		(end 105.344214 -215.112346)
		(width 0.0889)
		(layer "In2.Cu")
		(net "P5E_CPU1_PE1_TX_DP<14>")
	)
	(segment
		(start 106.275124 -221.628462)
		(end 106.28249 -221.624144)
		(width 0.0889)
		(layer "In2.Cu")
		(net "P5E_CPU1_PE1_TX_DP<14>")
	)
	(segment
		(start 106.471212 -225.203258)
		(end 106.314748 -224.93224)
		(width 0.0889)
		(layer "In2.Cu")
		(net "P5E_CPU1_PE1_TX_DP<14>")
	)
	(segment
		(start 105.344214 -215.761062)
		(end 105.335324 -215.755982)
		(width 0.0889)
		(layer "In2.Cu")
		(net "P5E_CPU1_PE1_TX_DP<14>")
	)
	(segment
		(start 106.284268 -220.644212)
		(end 106.275378 -220.639132)
		(width 0.0889)
		(layer "In2.Cu")
		(net "P5E_CPU1_PE1_TX_DP<14>")
	)
	(segment
		(start 101.949504 -187.949078)
		(end 101.505766 -186.215274)
		(width 0.14732)
		(layer "In2.Cu")
		(net "P5E_CPU1_PE1_TX_DP<14>")
	)
	(segment
		(start 106.566716 -221.133924)
		(end 106.566716 -221.115382)
		(width 0.0889)
		(layer "In2.Cu")
		(net "P5E_CPU1_PE1_TX_DP<14>")
	)
	(segment
		(start 67.813936 -98.328988)
		(end 50.4063 -60.363354)
		(width 0.14732)
		(layer "In2.Cu")
		(net "P5E_CPU1_PE1_TX_DP<14>")
	)
	(segment
		(start 106.314748 -224.93224)
		(end 106.338878 -224.843086)
		(width 0.0889)
		(layer "In2.Cu")
		(net "P5E_CPU1_PE1_TX_DP<14>")
	)
	(segment
		(start 105.805478 -222.442278)
		(end 105.814368 -222.437198)
		(width 0.0889)
		(layer "In2.Cu")
		(net "P5E_CPU1_PE1_TX_DP<14>")
	)
	(segment
		(start 105.805478 -217.559128)
		(end 105.814368 -217.554048)
		(width 0.0889)
		(layer "In2.Cu")
		(net "P5E_CPU1_PE1_TX_DP<14>")
	)
	(segment
		(start 106.283506 -223.899476)
		(end 106.280966 -223.897952)
		(width 0.0889)
		(layer "In2.Cu")
		(net "P5E_CPU1_PE1_TX_DP<14>")
	)
	(segment
		(start 18.927318 -20.047712)
		(end 18.899378 -19.967448)
		(width 0.14732)
		(layer "In2.Cu")
		(net "P5E_CPU1_PE1_TX_DP<14>")
	)
	(segment
		(start 105.814368 -218.202764)
		(end 105.805478 -218.197684)
		(width 0.0889)
		(layer "In2.Cu")
		(net "P5E_CPU1_PE1_TX_DP<14>")
	)
	(segment
		(start 106.096816 -217.07856)
		(end 106.096816 -217.064336)
		(width 0.0889)
		(layer "In2.Cu")
		(net "P5E_CPU1_PE1_TX_DP<14>")
	)
	(segment
		(start 106.096562 -221.963234)
		(end 106.096562 -221.94774)
		(width 0.0889)
		(layer "In2.Cu")
		(net "P5E_CPU1_PE1_TX_DP<14>")
	)
	(segment
		(start 50.4063 -60.363354)
		(end 18.927318 -20.047712)
		(width 0.14732)
		(layer "In2.Cu")
		(net "P5E_CPU1_PE1_TX_DP<14>")
	)
	(segment
		(start 106.284014 -221.623382)
		(end 106.284776 -221.622874)
		(width 0.0889)
		(layer "In2.Cu")
		(net "P5E_CPU1_PE1_TX_DP<14>")
	)
	(segment
		(start 18.899378 -19.42846)
		(end 19.191478 -19.13636)
		(width 0.14732)
		(layer "In2.Cu")
		(net "P5E_CPU1_PE1_TX_DP<14>")
	)
	(segment
		(start 105.198926 -212.706458)
		(end 105.085896 -211.02955)
		(width 0.14732)
		(layer "In2.Cu")
		(net "P5E_CPU1_PE1_TX_DP<14>")
	)
	(segment
		(start 106.096816 -223.575626)
		(end 106.096816 -223.561402)
		(width 0.0889)
		(layer "In2.Cu")
		(net "P5E_CPU1_PE1_TX_DP<14>")
	)
	(segment
		(start 105.35031 -215.764618)
		(end 105.344214 -215.761062)
		(width 0.0889)
		(layer "In2.Cu")
		(net "P5E_CPU1_PE1_TX_DP<14>")
	)
	(segment
		(start 106.284776 -221.622874)
		(end 106.29011 -221.619826)
		(width 0.0889)
		(layer "In2.Cu")
		(net "P5E_CPU1_PE1_TX_DP<14>")
	)
	(segment
		(start 105.805478 -219.18676)
		(end 105.814368 -219.18168)
		(width 0.0889)
		(layer "In2.Cu")
		(net "P5E_CPU1_PE1_TX_DP<14>")
	)
	(segment
		(start 105.156762 -213.897718)
		(end 105.156762 -213.284816)
		(width 0.0889)
		(layer "In2.Cu")
		(net "P5E_CPU1_PE1_TX_DP<14>")
	)
	(segment
		(start 105.198926 -213.242652)
		(end 105.198926 -213.220554)
		(width 0.0889)
		(layer "In2.Cu")
		(net "P5E_CPU1_PE1_TX_DP<14>")
	)
	(arc
		(start 106.096816 -217.064336)
		(mid 106.0229 -216.784834)
		(end 105.820464 -216.578434)
		(width 0.0889)
		(layer "In2.Cu")
		(net "P5E_CPU1_PE1_TX_DP<14>")
	)
	(arc
		(start 105.157016 -215.421972)
		(mid 105.20807 -215.247392)
		(end 105.335324 -215.117426)
		(width 0.0889)
		(layer "In2.Cu")
		(net "P5E_CPU1_PE1_TX_DP<14>")
	)
	(arc
		(start 105.814368 -222.437198)
		(mid 106.017191 -222.236967)
		(end 106.096562 -221.963234)
		(width 0.0889)
		(layer "In2.Cu")
		(net "P5E_CPU1_PE1_TX_DP<14>")
	)
	(arc
		(start 105.626408 -214.424768)
		(mid 105.524779 -214.243564)
		(end 105.367328 -214.10803)
		(width 0.0889)
		(layer "In2.Cu")
		(net "P5E_CPU1_PE1_TX_DP<14>")
	)
	(arc
		(start 106.29011 -221.619826)
		(mid 106.492697 -221.413475)
		(end 106.566716 -221.133924)
		(width 0.0889)
		(layer "In2.Cu")
		(net "P5E_CPU1_PE1_TX_DP<14>")
	)
	(arc
		(start 105.805478 -223.080834)
		(mid 105.678309 -222.950842)
		(end 105.627424 -222.776288)
		(width 0.0889)
		(layer "In2.Cu")
		(net "P5E_CPU1_PE1_TX_DP<14>")
	)
	(arc
		(start 106.275378 -223.894904)
		(mid 106.144464 -223.758544)
		(end 106.096816 -223.575626)
		(width 0.0889)
		(layer "In2.Cu")
		(net "P5E_CPU1_PE1_TX_DP<14>")
	)
	(arc
		(start 106.096816 -223.561402)
		(mid 106.017675 -223.286779)
		(end 105.814368 -223.085914)
		(width 0.0889)
		(layer "In2.Cu")
		(net "P5E_CPU1_PE1_TX_DP<14>")
	)
	(arc
		(start 105.805478 -216.569798)
		(mid 105.674564 -216.433438)
		(end 105.626916 -216.25052)
		(width 0.0889)
		(layer "In2.Cu")
		(net "P5E_CPU1_PE1_TX_DP<14>")
	)
	(arc
		(start 105.805478 -219.825316)
		(mid 105.627002 -219.506038)
		(end 105.805478 -219.18676)
		(width 0.0889)
		(layer "In2.Cu")
		(net "P5E_CPU1_PE1_TX_DP<14>")
	)
	(arc
		(start 106.096562 -221.94774)
		(mid 106.144241 -221.76484)
		(end 106.275124 -221.628462)
		(width 0.0889)
		(layer "In2.Cu")
		(net "P5E_CPU1_PE1_TX_DP<14>")
	)
	(arc
		(start 105.335324 -215.755982)
		(mid 105.20441 -215.619622)
		(end 105.156762 -215.436704)
		(width 0.0889)
		(layer "In2.Cu")
		(net "P5E_CPU1_PE1_TX_DP<14>")
	)
	(arc
		(start 106.566716 -224.379536)
		(mid 106.488605 -224.102587)
		(end 106.284268 -223.899984)
		(width 0.0889)
		(layer "In2.Cu")
		(net "P5E_CPU1_PE1_TX_DP<14>")
	)
	(arc
		(start 105.626916 -217.888566)
		(mid 105.626836 -217.876118)
		(end 105.62717 -217.863674)
		(width 0.0889)
		(layer "In2.Cu")
		(net "P5E_CPU1_PE1_TX_DP<14>")
	)
	(arc
		(start 105.62717 -222.751396)
		(mid 105.677185 -222.574265)
		(end 105.805478 -222.442278)
		(width 0.0889)
		(layer "In2.Cu")
		(net "P5E_CPU1_PE1_TX_DP<14>")
	)
	(arc
		(start 105.814368 -217.554048)
		(mid 106.017673 -217.353182)
		(end 106.096816 -217.07856)
		(width 0.0889)
		(layer "In2.Cu")
		(net "P5E_CPU1_PE1_TX_DP<14>")
	)
	(arc
		(start 105.627424 -222.776288)
		(mid 105.627091 -222.763844)
		(end 105.62717 -222.751396)
		(width 0.0889)
		(layer "In2.Cu")
		(net "P5E_CPU1_PE1_TX_DP<14>")
	)
	(arc
		(start 106.096816 -220.319854)
		(mid 106.0229 -220.040352)
		(end 105.820464 -219.833952)
		(width 0.0889)
		(layer "In2.Cu")
		(net "P5E_CPU1_PE1_TX_DP<14>")
	)
	(arc
		(start 105.156762 -215.436704)
		(mid 105.156814 -215.429337)
		(end 105.157016 -215.421972)
		(width 0.0889)
		(layer "In2.Cu")
		(net "P5E_CPU1_PE1_TX_DP<14>")
	)
	(arc
		(start 106.338878 -224.843086)
		(mid 106.34745 -224.836564)
		(end 106.355896 -224.829878)
		(width 0.0889)
		(layer "In2.Cu")
		(net "P5E_CPU1_PE1_TX_DP<14>")
	)
	(arc
		(start 106.275378 -220.639132)
		(mid 106.144464 -220.502772)
		(end 106.096816 -220.319854)
		(width 0.0889)
		(layer "In2.Cu")
		(net "P5E_CPU1_PE1_TX_DP<14>")
	)
	(arc
		(start 105.814368 -219.18168)
		(mid 106.017191 -218.981449)
		(end 106.096562 -218.707716)
		(width 0.0889)
		(layer "In2.Cu")
		(net "P5E_CPU1_PE1_TX_DP<14>")
	)
	(arc
		(start 106.566716 -221.115382)
		(mid 106.486554 -220.843193)
		(end 106.284268 -220.644212)
		(width 0.0889)
		(layer "In2.Cu")
		(net "P5E_CPU1_PE1_TX_DP<14>")
	)
	(arc
		(start 106.096562 -218.676728)
		(mid 106.017192 -218.402994)
		(end 105.814368 -218.202764)
		(width 0.0889)
		(layer "In2.Cu")
		(net "P5E_CPU1_PE1_TX_DP<14>")
	)
	(arc
		(start 106.355896 -224.829878)
		(mid 106.511294 -224.633597)
		(end 106.566716 -224.389442)
		(width 0.0889)
		(layer "In2.Cu")
		(net "P5E_CPU1_PE1_TX_DP<14>")
	)
	(arc
		(start 105.62717 -217.863674)
		(mid 105.678224 -217.689094)
		(end 105.805478 -217.559128)
		(width 0.0889)
		(layer "In2.Cu")
		(net "P5E_CPU1_PE1_TX_DP<14>")
	)
	(arc
		(start 105.344214 -215.112346)
		(mid 105.545496 -214.914859)
		(end 105.626408 -214.644732)
		(width 0.0889)
		(layer "In2.Cu")
		(net "P5E_CPU1_PE1_TX_DP<14>")
	)
	(arc
		(start 105.626916 -216.25052)
		(mid 105.552925 -215.970954)
		(end 105.35031 -215.764618)
		(width 0.0889)
		(layer "In2.Cu")
		(net "P5E_CPU1_PE1_TX_DP<14>")
	)
	(arc
		(start 105.805478 -218.197684)
		(mid 105.677074 -218.065739)
		(end 105.626916 -217.888566)
		(width 0.0889)
		(layer "In2.Cu")
		(net "P5E_CPU1_PE1_TX_DP<14>")
	)
	(segment
		(start 21.422868 -17.31137)
		(end 21.422868 -16.692626)
		(width 0.13208)
		(layer "F.Cu")
		(net "P5E_CPU1_PE1_TX_DP<13>")
	)
	(segment
		(start 106.941366 -224.925128)
		(end 106.941366 -224.389442)
		(width 0.13208)
		(layer "F.Cu")
		(net "P5E_CPU1_PE1_TX_DP<13>")
	)
	(segment
		(start 106.941112 -224.925382)
		(end 106.941366 -224.925128)
		(width 0.13208)
		(layer "F.Cu")
		(net "P5E_CPU1_PE1_TX_DP<13>")
	)
	(segment
		(start 21.121878 -17.61236)
		(end 21.422868 -17.31137)
		(width 0.13208)
		(layer "F.Cu")
		(net "P5E_CPU1_PE1_TX_DP<13>")
	)
	(segment
		(start 21.422868 -16.692626)
		(end 21.096478 -16.366236)
		(width 0.13208)
		(layer "F.Cu")
		(net "P5E_CPU1_PE1_TX_DP<13>")
	)
	(segment
		(start 106.375708 -214.622634)
		(end 106.375708 -214.461344)
		(width 0.0889)
		(layer "In2.Cu")
		(net "P5E_CPU1_PE1_TX_DP<13>")
	)
	(segment
		(start 106.65841 -219.01658)
		(end 106.6673 -219.0115)
		(width 0.0889)
		(layer "In2.Cu")
		(net "P5E_CPU1_PE1_TX_DP<13>")
	)
	(segment
		(start 106.18597 -215.924384)
		(end 106.182668 -215.922606)
		(width 0.0889)
		(layer "In2.Cu")
		(net "P5E_CPU1_PE1_TX_DP<13>")
	)
	(segment
		(start 105.864914 -213.242652)
		(end 105.864914 -213.220554)
		(width 0.0889)
		(layer "In2.Cu")
		(net "P5E_CPU1_PE1_TX_DP<13>")
	)
	(segment
		(start 107.09783 -224.118424)
		(end 107.0737 -224.02927)
		(width 0.0889)
		(layer "In2.Cu")
		(net "P5E_CPU1_PE1_TX_DP<13>")
	)
	(segment
		(start 107.127802 -221.45879)
		(end 107.128564 -221.458282)
		(width 0.0889)
		(layer "In2.Cu")
		(net "P5E_CPU1_PE1_TX_DP<13>")
	)
	(segment
		(start 106.184954 -215.923622)
		(end 106.188002 -215.925654)
		(width 0.0889)
		(layer "In2.Cu")
		(net "P5E_CPU1_PE1_TX_DP<13>")
	)
	(segment
		(start 106.188002 -215.925654)
		(end 106.18597 -215.924384)
		(width 0.0889)
		(layer "In2.Cu")
		(net "P5E_CPU1_PE1_TX_DP<13>")
	)
	(segment
		(start 102.621842 -187.863226)
		(end 102.17531 -186.119262)
		(width 0.14732)
		(layer "In2.Cu")
		(net "P5E_CPU1_PE1_TX_DP<13>")
	)
	(segment
		(start 105.864914 -213.220554)
		(end 105.864914 -212.470238)
		(width 0.14732)
		(layer "In2.Cu")
		(net "P5E_CPU1_PE1_TX_DP<13>")
	)
	(segment
		(start 106.376216 -217.8939)
		(end 106.376216 -217.859864)
		(width 0.0889)
		(layer "In2.Cu")
		(net "P5E_CPU1_PE1_TX_DP<13>")
	)
	(segment
		(start 107.130088 -221.45752)
		(end 107.137454 -221.453202)
		(width 0.0889)
		(layer "In2.Cu")
		(net "P5E_CPU1_PE1_TX_DP<13>")
	)
	(segment
		(start 106.191812 -214.2617)
		(end 106.191812 -214.261446)
		(width 0.0889)
		(layer "In2.Cu")
		(net "P5E_CPU1_PE1_TX_DP<13>")
	)
	(segment
		(start 106.188256 -214.946992)
		(end 106.197146 -214.941912)
		(width 0.0889)
		(layer "In2.Cu")
		(net "P5E_CPU1_PE1_TX_DP<13>")
	)
	(segment
		(start 105.864914 -212.470238)
		(end 105.7656 -211.00161)
		(width 0.14732)
		(layer "In2.Cu")
		(net "P5E_CPU1_PE1_TX_DP<13>")
	)
	(segment
		(start 106.197654 -215.931242)
		(end 106.184954 -215.923622)
		(width 0.0889)
		(layer "In2.Cu")
		(net "P5E_CPU1_PE1_TX_DP<13>")
	)
	(segment
		(start 106.65841 -222.272098)
		(end 106.6673 -222.267018)
		(width 0.0889)
		(layer "In2.Cu")
		(net "P5E_CPU1_PE1_TX_DP<13>")
	)
	(segment
		(start 68.43268 -98.105722)
		(end 50.755296 -59.551316)
		(width 0.14732)
		(layer "In2.Cu")
		(net "P5E_CPU1_PE1_TX_DP<13>")
	)
	(segment
		(start 21.416518 -18.65503)
		(end 21.416518 -17.907)
		(width 0.14732)
		(layer "In2.Cu")
		(net "P5E_CPU1_PE1_TX_DP<13>")
	)
	(segment
		(start 105.90657 -213.929468)
		(end 105.90657 -213.284308)
		(width 0.0889)
		(layer "In2.Cu")
		(net "P5E_CPU1_PE1_TX_DP<13>")
	)
	(segment
		(start 106.845862 -223.575626)
		(end 106.845862 -223.56699)
		(width 0.0889)
		(layer "In2.Cu")
		(net "P5E_CPU1_PE1_TX_DP<13>")
	)
	(segment
		(start 105.906062 -215.436704)
		(end 105.906062 -215.414606)
		(width 0.0889)
		(layer "In2.Cu")
		(net "P5E_CPU1_PE1_TX_DP<13>")
	)
	(segment
		(start 21.416518 -17.907)
		(end 21.121878 -17.61236)
		(width 0.14732)
		(layer "In2.Cu")
		(net "P5E_CPU1_PE1_TX_DP<13>")
	)
	(segment
		(start 106.941366 -224.389442)
		(end 107.09783 -224.118424)
		(width 0.0889)
		(layer "In2.Cu")
		(net "P5E_CPU1_PE1_TX_DP<13>")
	)
	(segment
		(start 107.122468 -221.461838)
		(end 107.127802 -221.45879)
		(width 0.0889)
		(layer "In2.Cu")
		(net "P5E_CPU1_PE1_TX_DP<13>")
	)
	(segment
		(start 107.128564 -221.458282)
		(end 107.130088 -221.45752)
		(width 0.0889)
		(layer "In2.Cu")
		(net "P5E_CPU1_PE1_TX_DP<13>")
	)
	(segment
		(start 106.845862 -217.072972)
		(end 106.845862 -217.0557)
		(width 0.0889)
		(layer "In2.Cu")
		(net "P5E_CPU1_PE1_TX_DP<13>")
	)
	(segment
		(start 50.755296 -59.551316)
		(end 21.416518 -18.65503)
		(width 0.14732)
		(layer "In2.Cu")
		(net "P5E_CPU1_PE1_TX_DP<13>")
	)
	(segment
		(start 107.137454 -220.814646)
		(end 107.128564 -220.809566)
		(width 0.0889)
		(layer "In2.Cu")
		(net "P5E_CPU1_PE1_TX_DP<13>")
	)
	(segment
		(start 106.845862 -220.334078)
		(end 106.845862 -220.311218)
		(width 0.0889)
		(layer "In2.Cu")
		(net "P5E_CPU1_PE1_TX_DP<13>")
	)
	(segment
		(start 106.376216 -222.780098)
		(end 106.376216 -222.746062)
		(width 0.0889)
		(layer "In2.Cu")
		(net "P5E_CPU1_PE1_TX_DP<13>")
	)
	(segment
		(start 106.659426 -218.368372)
		(end 106.65841 -218.367864)
		(width 0.0889)
		(layer "In2.Cu")
		(net "P5E_CPU1_PE1_TX_DP<13>")
	)
	(segment
		(start 106.376216 -219.515944)
		(end 106.376216 -219.490544)
		(width 0.0889)
		(layer "In2.Cu")
		(net "P5E_CPU1_PE1_TX_DP<13>")
	)
	(segment
		(start 105.90657 -213.284308)
		(end 105.864914 -213.242652)
		(width 0.0889)
		(layer "In2.Cu")
		(net "P5E_CPU1_PE1_TX_DP<13>")
	)
	(segment
		(start 106.6673 -218.372944)
		(end 106.659426 -218.368372)
		(width 0.0889)
		(layer "In2.Cu")
		(net "P5E_CPU1_PE1_TX_DP<13>")
	)
	(segment
		(start 106.376216 -216.260426)
		(end 106.376216 -216.25052)
		(width 0.0889)
		(layer "In2.Cu")
		(net "P5E_CPU1_PE1_TX_DP<13>")
	)
	(segment
		(start 106.191558 -214.261954)
		(end 106.191812 -214.2617)
		(width 0.0889)
		(layer "In2.Cu")
		(net "P5E_CPU1_PE1_TX_DP<13>")
	)
	(segment
		(start 105.7656 -211.00161)
		(end 102.621842 -187.863226)
		(width 0.14732)
		(layer "In2.Cu")
		(net "P5E_CPU1_PE1_TX_DP<13>")
	)
	(segment
		(start 102.17531 -186.119262)
		(end 68.43268 -98.105722)
		(width 0.14732)
		(layer "In2.Cu")
		(net "P5E_CPU1_PE1_TX_DP<13>")
	)
	(arc
		(start 106.375708 -214.461344)
		(mid 106.300703 -214.345885)
		(end 106.191558 -214.261954)
		(width 0.0889)
		(layer "In2.Cu")
		(net "P5E_CPU1_PE1_TX_DP<13>")
	)
	(arc
		(start 106.191812 -214.261446)
		(mid 106.017736 -214.122483)
		(end 105.90657 -213.929468)
		(width 0.0889)
		(layer "In2.Cu")
		(net "P5E_CPU1_PE1_TX_DP<13>")
	)
	(arc
		(start 107.0737 -224.02927)
		(mid 106.905946 -223.829492)
		(end 106.845862 -223.575626)
		(width 0.0889)
		(layer "In2.Cu")
		(net "P5E_CPU1_PE1_TX_DP<13>")
	)
	(arc
		(start 106.658664 -217.388694)
		(mid 106.793597 -217.25534)
		(end 106.845862 -217.072972)
		(width 0.0889)
		(layer "In2.Cu")
		(net "P5E_CPU1_PE1_TX_DP<13>")
	)
	(arc
		(start 105.906062 -215.414606)
		(mid 105.986973 -215.144478)
		(end 106.188256 -214.946992)
		(width 0.0889)
		(layer "In2.Cu")
		(net "P5E_CPU1_PE1_TX_DP<13>")
	)
	(arc
		(start 106.658664 -219.995496)
		(mid 106.454329 -219.792891)
		(end 106.376216 -219.515944)
		(width 0.0889)
		(layer "In2.Cu")
		(net "P5E_CPU1_PE1_TX_DP<13>")
	)
	(arc
		(start 106.182668 -215.922606)
		(mid 105.980081 -215.716255)
		(end 105.906062 -215.436704)
		(width 0.0889)
		(layer "In2.Cu")
		(net "P5E_CPU1_PE1_TX_DP<13>")
	)
	(arc
		(start 106.658664 -216.739978)
		(mid 106.454329 -216.537373)
		(end 106.376216 -216.260426)
		(width 0.0889)
		(layer "In2.Cu")
		(net "P5E_CPU1_PE1_TX_DP<13>")
	)
	(arc
		(start 107.137454 -221.453202)
		(mid 107.316051 -221.133924)
		(end 107.137454 -220.814646)
		(width 0.0889)
		(layer "In2.Cu")
		(net "P5E_CPU1_PE1_TX_DP<13>")
	)
	(arc
		(start 106.376216 -222.746062)
		(mid 106.455586 -222.472328)
		(end 106.65841 -222.272098)
		(width 0.0889)
		(layer "In2.Cu")
		(net "P5E_CPU1_PE1_TX_DP<13>")
	)
	(arc
		(start 106.376216 -217.859864)
		(mid 106.456378 -217.587675)
		(end 106.658664 -217.388694)
		(width 0.0889)
		(layer "In2.Cu")
		(net "P5E_CPU1_PE1_TX_DP<13>")
	)
	(arc
		(start 107.128564 -220.809566)
		(mid 106.925083 -220.608762)
		(end 106.845862 -220.334078)
		(width 0.0889)
		(layer "In2.Cu")
		(net "P5E_CPU1_PE1_TX_DP<13>")
	)
	(arc
		(start 106.197146 -214.941912)
		(mid 106.32806 -214.805552)
		(end 106.375708 -214.622634)
		(width 0.0889)
		(layer "In2.Cu")
		(net "P5E_CPU1_PE1_TX_DP<13>")
	)
	(arc
		(start 106.376216 -219.490544)
		(mid 106.455586 -219.21681)
		(end 106.65841 -219.01658)
		(width 0.0889)
		(layer "In2.Cu")
		(net "P5E_CPU1_PE1_TX_DP<13>")
	)
	(arc
		(start 106.845862 -221.94774)
		(mid 106.919853 -221.668174)
		(end 107.122468 -221.461838)
		(width 0.0889)
		(layer "In2.Cu")
		(net "P5E_CPU1_PE1_TX_DP<13>")
	)
	(arc
		(start 106.6673 -219.0115)
		(mid 106.845776 -218.692222)
		(end 106.6673 -218.372944)
		(width 0.0889)
		(layer "In2.Cu")
		(net "P5E_CPU1_PE1_TX_DP<13>")
	)
	(arc
		(start 106.658664 -223.251268)
		(mid 106.456378 -223.052287)
		(end 106.376216 -222.780098)
		(width 0.0889)
		(layer "In2.Cu")
		(net "P5E_CPU1_PE1_TX_DP<13>")
	)
	(arc
		(start 106.376216 -216.25052)
		(mid 106.328537 -216.06762)
		(end 106.197654 -215.931242)
		(width 0.0889)
		(layer "In2.Cu")
		(net "P5E_CPU1_PE1_TX_DP<13>")
	)
	(arc
		(start 106.6673 -222.267018)
		(mid 106.798214 -222.130658)
		(end 106.845862 -221.94774)
		(width 0.0889)
		(layer "In2.Cu")
		(net "P5E_CPU1_PE1_TX_DP<13>")
	)
	(arc
		(start 106.845862 -220.311218)
		(mid 106.793592 -220.128853)
		(end 106.658664 -219.995496)
		(width 0.0889)
		(layer "In2.Cu")
		(net "P5E_CPU1_PE1_TX_DP<13>")
	)
	(arc
		(start 106.845862 -223.56699)
		(mid 106.793592 -223.384625)
		(end 106.658664 -223.251268)
		(width 0.0889)
		(layer "In2.Cu")
		(net "P5E_CPU1_PE1_TX_DP<13>")
	)
	(arc
		(start 106.65841 -218.367864)
		(mid 106.455587 -218.167633)
		(end 106.376216 -217.8939)
		(width 0.0889)
		(layer "In2.Cu")
		(net "P5E_CPU1_PE1_TX_DP<13>")
	)
	(arc
		(start 106.845862 -217.0557)
		(mid 106.793592 -216.873335)
		(end 106.658664 -216.739978)
		(width 0.0889)
		(layer "In2.Cu")
		(net "P5E_CPU1_PE1_TX_DP<13>")
	)
	(segment
		(start 24.779478 -19.13636)
		(end 24.475948 -18.83283)
		(width 0.13208)
		(layer "F.Cu")
		(net "P5E_CPU1_PE1_TX_DP<12>")
	)
	(segment
		(start 108.351066 -225.739198)
		(end 108.351066 -225.203512)
		(width 0.13208)
		(layer "F.Cu")
		(net "P5E_CPU1_PE1_TX_DP<12>")
	)
	(segment
		(start 24.475948 -18.83283)
		(end 24.475948 -18.219166)
		(width 0.13208)
		(layer "F.Cu")
		(net "P5E_CPU1_PE1_TX_DP<12>")
	)
	(segment
		(start 24.475948 -18.219166)
		(end 24.804878 -17.890236)
		(width 0.13208)
		(layer "F.Cu")
		(net "P5E_CPU1_PE1_TX_DP<12>")
	)
	(segment
		(start 108.351066 -225.203512)
		(end 108.350812 -225.203258)
		(width 0.13208)
		(layer "F.Cu")
		(net "P5E_CPU1_PE1_TX_DP<12>")
	)
	(segment
		(start 108.163868 -220.644212)
		(end 108.154978 -220.639132)
		(width 0.0889)
		(layer "In2.Cu")
		(net "P5E_CPU1_PE1_TX_DP<12>")
	)
	(segment
		(start 104.084882 -188.670184)
		(end 103.37165 -185.851546)
		(width 0.14732)
		(layer "In2.Cu")
		(net "P5E_CPU1_PE1_TX_DP<12>")
	)
	(segment
		(start 107.700064 -216.578434)
		(end 107.693968 -216.574878)
		(width 0.0889)
		(layer "In2.Cu")
		(net "P5E_CPU1_PE1_TX_DP<12>")
	)
	(segment
		(start 108.194348 -224.93224)
		(end 108.218478 -224.843086)
		(width 0.0889)
		(layer "In2.Cu")
		(net "P5E_CPU1_PE1_TX_DP<12>")
	)
	(segment
		(start 108.350812 -225.203258)
		(end 108.194348 -224.93224)
		(width 0.0889)
		(layer "In2.Cu")
		(net "P5E_CPU1_PE1_TX_DP<12>")
	)
	(segment
		(start 108.163106 -223.899476)
		(end 108.160566 -223.897952)
		(width 0.0889)
		(layer "In2.Cu")
		(net "P5E_CPU1_PE1_TX_DP<12>")
	)
	(segment
		(start 107.223814 -215.112346)
		(end 107.224322 -215.111584)
		(width 0.0889)
		(layer "In2.Cu")
		(net "P5E_CPU1_PE1_TX_DP<12>")
	)
	(segment
		(start 107.685078 -217.559128)
		(end 107.693968 -217.554048)
		(width 0.0889)
		(layer "In2.Cu")
		(net "P5E_CPU1_PE1_TX_DP<12>")
	)
	(segment
		(start 107.036616 -213.284816)
		(end 107.07878 -213.242652)
		(width 0.0889)
		(layer "In2.Cu")
		(net "P5E_CPU1_PE1_TX_DP<12>")
	)
	(segment
		(start 107.976162 -218.707716)
		(end 107.976162 -218.676728)
		(width 0.0889)
		(layer "In2.Cu")
		(net "P5E_CPU1_PE1_TX_DP<12>")
	)
	(segment
		(start 107.693968 -216.574878)
		(end 107.685078 -216.569798)
		(width 0.0889)
		(layer "In2.Cu")
		(net "P5E_CPU1_PE1_TX_DP<12>")
	)
	(segment
		(start 103.37165 -185.851546)
		(end 69.577966 -97.713546)
		(width 0.14732)
		(layer "In2.Cu")
		(net "P5E_CPU1_PE1_TX_DP<12>")
	)
	(segment
		(start 51.653694 -58.620914)
		(end 24.484838 -20.065492)
		(width 0.14732)
		(layer "In2.Cu")
		(net "P5E_CPU1_PE1_TX_DP<12>")
	)
	(segment
		(start 107.07878 -212.477096)
		(end 106.971846 -210.824318)
		(width 0.14732)
		(layer "In2.Cu")
		(net "P5E_CPU1_PE1_TX_DP<12>")
	)
	(segment
		(start 108.163614 -221.623382)
		(end 108.164376 -221.622874)
		(width 0.0889)
		(layer "In2.Cu")
		(net "P5E_CPU1_PE1_TX_DP<12>")
	)
	(segment
		(start 107.505754 -214.622634)
		(end 107.505754 -214.429848)
		(width 0.0889)
		(layer "In2.Cu")
		(net "P5E_CPU1_PE1_TX_DP<12>")
	)
	(segment
		(start 108.154724 -221.628462)
		(end 108.16209 -221.624144)
		(width 0.0889)
		(layer "In2.Cu")
		(net "P5E_CPU1_PE1_TX_DP<12>")
	)
	(segment
		(start 108.164376 -221.622874)
		(end 108.16971 -221.619826)
		(width 0.0889)
		(layer "In2.Cu")
		(net "P5E_CPU1_PE1_TX_DP<12>")
	)
	(segment
		(start 106.971846 -210.824318)
		(end 104.084882 -188.670184)
		(width 0.14732)
		(layer "In2.Cu")
		(net "P5E_CPU1_PE1_TX_DP<12>")
	)
	(segment
		(start 107.224322 -215.111584)
		(end 107.229148 -215.10879)
		(width 0.0889)
		(layer "In2.Cu")
		(net "P5E_CPU1_PE1_TX_DP<12>")
	)
	(segment
		(start 107.693968 -223.085914)
		(end 107.692952 -223.085406)
		(width 0.0889)
		(layer "In2.Cu")
		(net "P5E_CPU1_PE1_TX_DP<12>")
	)
	(segment
		(start 108.446316 -221.133924)
		(end 108.446316 -221.115382)
		(width 0.0889)
		(layer "In2.Cu")
		(net "P5E_CPU1_PE1_TX_DP<12>")
	)
	(segment
		(start 107.214924 -215.117426)
		(end 107.219242 -215.114886)
		(width 0.0889)
		(layer "In2.Cu")
		(net "P5E_CPU1_PE1_TX_DP<12>")
	)
	(segment
		(start 107.976416 -223.575626)
		(end 107.976416 -223.561402)
		(width 0.0889)
		(layer "In2.Cu")
		(net "P5E_CPU1_PE1_TX_DP<12>")
	)
	(segment
		(start 107.692952 -223.085406)
		(end 107.685078 -223.080834)
		(width 0.0889)
		(layer "In2.Cu")
		(net "P5E_CPU1_PE1_TX_DP<12>")
	)
	(segment
		(start 107.976416 -217.07856)
		(end 107.976416 -217.064336)
		(width 0.0889)
		(layer "In2.Cu")
		(net "P5E_CPU1_PE1_TX_DP<12>")
	)
	(segment
		(start 107.07878 -213.220554)
		(end 107.07878 -212.477096)
		(width 0.14732)
		(layer "In2.Cu")
		(net "P5E_CPU1_PE1_TX_DP<12>")
	)
	(segment
		(start 108.446316 -224.389442)
		(end 108.446316 -224.379536)
		(width 0.0889)
		(layer "In2.Cu")
		(net "P5E_CPU1_PE1_TX_DP<12>")
	)
	(segment
		(start 107.685078 -222.442278)
		(end 107.693968 -222.437198)
		(width 0.0889)
		(layer "In2.Cu")
		(net "P5E_CPU1_PE1_TX_DP<12>")
	)
	(segment
		(start 108.160566 -223.897952)
		(end 108.154978 -223.894904)
		(width 0.0889)
		(layer "In2.Cu")
		(net "P5E_CPU1_PE1_TX_DP<12>")
	)
	(segment
		(start 107.686348 -219.825824)
		(end 107.686094 -219.825824)
		(width 0.0889)
		(layer "In2.Cu")
		(net "P5E_CPU1_PE1_TX_DP<12>")
	)
	(segment
		(start 107.223814 -215.761062)
		(end 107.214924 -215.755982)
		(width 0.0889)
		(layer "In2.Cu")
		(net "P5E_CPU1_PE1_TX_DP<12>")
	)
	(segment
		(start 107.700064 -219.833952)
		(end 107.686348 -219.825824)
		(width 0.0889)
		(layer "In2.Cu")
		(net "P5E_CPU1_PE1_TX_DP<12>")
	)
	(segment
		(start 107.976162 -221.963234)
		(end 107.976162 -221.94774)
		(width 0.0889)
		(layer "In2.Cu")
		(net "P5E_CPU1_PE1_TX_DP<12>")
	)
	(segment
		(start 107.219242 -215.114886)
		(end 107.223052 -215.112854)
		(width 0.0889)
		(layer "In2.Cu")
		(net "P5E_CPU1_PE1_TX_DP<12>")
	)
	(segment
		(start 107.685078 -219.18676)
		(end 107.693968 -219.18168)
		(width 0.0889)
		(layer "In2.Cu")
		(net "P5E_CPU1_PE1_TX_DP<12>")
	)
	(segment
		(start 107.23118 -215.10752)
		(end 107.232704 -215.106504)
		(width 0.0889)
		(layer "In2.Cu")
		(net "P5E_CPU1_PE1_TX_DP<12>")
	)
	(segment
		(start 107.22991 -215.764618)
		(end 107.223814 -215.761062)
		(width 0.0889)
		(layer "In2.Cu")
		(net "P5E_CPU1_PE1_TX_DP<12>")
	)
	(segment
		(start 107.693968 -218.202764)
		(end 107.685078 -218.197684)
		(width 0.0889)
		(layer "In2.Cu")
		(net "P5E_CPU1_PE1_TX_DP<12>")
	)
	(segment
		(start 107.229148 -215.10879)
		(end 107.23118 -215.10752)
		(width 0.0889)
		(layer "In2.Cu")
		(net "P5E_CPU1_PE1_TX_DP<12>")
	)
	(segment
		(start 107.686094 -219.825824)
		(end 107.685078 -219.825316)
		(width 0.0889)
		(layer "In2.Cu")
		(net "P5E_CPU1_PE1_TX_DP<12>")
	)
	(segment
		(start 107.07878 -213.242652)
		(end 107.07878 -213.220554)
		(width 0.0889)
		(layer "In2.Cu")
		(net "P5E_CPU1_PE1_TX_DP<12>")
	)
	(segment
		(start 24.484838 -20.065492)
		(end 24.484838 -19.431)
		(width 0.14732)
		(layer "In2.Cu")
		(net "P5E_CPU1_PE1_TX_DP<12>")
	)
	(segment
		(start 108.163868 -223.899984)
		(end 108.163106 -223.899476)
		(width 0.0889)
		(layer "In2.Cu")
		(net "P5E_CPU1_PE1_TX_DP<12>")
	)
	(segment
		(start 69.577966 -97.713546)
		(end 51.653694 -58.620914)
		(width 0.14732)
		(layer "In2.Cu")
		(net "P5E_CPU1_PE1_TX_DP<12>")
	)
	(segment
		(start 24.484838 -19.431)
		(end 24.779478 -19.13636)
		(width 0.14732)
		(layer "In2.Cu")
		(net "P5E_CPU1_PE1_TX_DP<12>")
	)
	(segment
		(start 107.416854 -214.277702)
		(end 107.036616 -213.897464)
		(width 0.0889)
		(layer "In2.Cu")
		(net "P5E_CPU1_PE1_TX_DP<12>")
	)
	(segment
		(start 108.16209 -221.624144)
		(end 108.163614 -221.623382)
		(width 0.0889)
		(layer "In2.Cu")
		(net "P5E_CPU1_PE1_TX_DP<12>")
	)
	(segment
		(start 107.223052 -215.112854)
		(end 107.223814 -215.112346)
		(width 0.0889)
		(layer "In2.Cu")
		(net "P5E_CPU1_PE1_TX_DP<12>")
	)
	(segment
		(start 107.036616 -213.897464)
		(end 107.036616 -213.284816)
		(width 0.0889)
		(layer "In2.Cu")
		(net "P5E_CPU1_PE1_TX_DP<12>")
	)
	(arc
		(start 108.16971 -221.619826)
		(mid 108.372297 -221.413475)
		(end 108.446316 -221.133924)
		(width 0.0889)
		(layer "In2.Cu")
		(net "P5E_CPU1_PE1_TX_DP<12>")
	)
	(arc
		(start 107.976416 -223.561402)
		(mid 107.897275 -223.286779)
		(end 107.693968 -223.085914)
		(width 0.0889)
		(layer "In2.Cu")
		(net "P5E_CPU1_PE1_TX_DP<12>")
	)
	(arc
		(start 107.693968 -219.18168)
		(mid 107.896791 -218.981449)
		(end 107.976162 -218.707716)
		(width 0.0889)
		(layer "In2.Cu")
		(net "P5E_CPU1_PE1_TX_DP<12>")
	)
	(arc
		(start 107.976162 -218.676728)
		(mid 107.896792 -218.402994)
		(end 107.693968 -218.202764)
		(width 0.0889)
		(layer "In2.Cu")
		(net "P5E_CPU1_PE1_TX_DP<12>")
	)
	(arc
		(start 108.218478 -224.843086)
		(mid 108.22705 -224.836564)
		(end 108.235496 -224.829878)
		(width 0.0889)
		(layer "In2.Cu")
		(net "P5E_CPU1_PE1_TX_DP<12>")
	)
	(arc
		(start 107.036616 -215.421972)
		(mid 107.08767 -215.247392)
		(end 107.214924 -215.117426)
		(width 0.0889)
		(layer "In2.Cu")
		(net "P5E_CPU1_PE1_TX_DP<12>")
	)
	(arc
		(start 107.976416 -220.319854)
		(mid 107.9025 -220.040352)
		(end 107.700064 -219.833952)
		(width 0.0889)
		(layer "In2.Cu")
		(net "P5E_CPU1_PE1_TX_DP<12>")
	)
	(arc
		(start 107.976416 -217.064336)
		(mid 107.9025 -216.784834)
		(end 107.700064 -216.578434)
		(width 0.0889)
		(layer "In2.Cu")
		(net "P5E_CPU1_PE1_TX_DP<12>")
	)
	(arc
		(start 107.976162 -221.94774)
		(mid 108.023841 -221.76484)
		(end 108.154724 -221.628462)
		(width 0.0889)
		(layer "In2.Cu")
		(net "P5E_CPU1_PE1_TX_DP<12>")
	)
	(arc
		(start 107.232704 -215.106504)
		(mid 107.432809 -214.900454)
		(end 107.505754 -214.622634)
		(width 0.0889)
		(layer "In2.Cu")
		(net "P5E_CPU1_PE1_TX_DP<12>")
	)
	(arc
		(start 107.50677 -222.751396)
		(mid 107.556785 -222.574265)
		(end 107.685078 -222.442278)
		(width 0.0889)
		(layer "In2.Cu")
		(net "P5E_CPU1_PE1_TX_DP<12>")
	)
	(arc
		(start 107.685078 -219.825316)
		(mid 107.506602 -219.506038)
		(end 107.685078 -219.18676)
		(width 0.0889)
		(layer "In2.Cu")
		(net "P5E_CPU1_PE1_TX_DP<12>")
	)
	(arc
		(start 107.506516 -216.25052)
		(mid 107.432525 -215.970954)
		(end 107.22991 -215.764618)
		(width 0.0889)
		(layer "In2.Cu")
		(net "P5E_CPU1_PE1_TX_DP<12>")
	)
	(arc
		(start 107.693968 -222.437198)
		(mid 107.896791 -222.236967)
		(end 107.976162 -221.963234)
		(width 0.0889)
		(layer "In2.Cu")
		(net "P5E_CPU1_PE1_TX_DP<12>")
	)
	(arc
		(start 107.507024 -222.776288)
		(mid 107.506691 -222.763844)
		(end 107.50677 -222.751396)
		(width 0.0889)
		(layer "In2.Cu")
		(net "P5E_CPU1_PE1_TX_DP<12>")
	)
	(arc
		(start 108.446316 -224.379536)
		(mid 108.368205 -224.102587)
		(end 108.163868 -223.899984)
		(width 0.0889)
		(layer "In2.Cu")
		(net "P5E_CPU1_PE1_TX_DP<12>")
	)
	(arc
		(start 107.50677 -217.863674)
		(mid 107.557824 -217.689094)
		(end 107.685078 -217.559128)
		(width 0.0889)
		(layer "In2.Cu")
		(net "P5E_CPU1_PE1_TX_DP<12>")
	)
	(arc
		(start 108.235496 -224.829878)
		(mid 108.390894 -224.633597)
		(end 108.446316 -224.389442)
		(width 0.0889)
		(layer "In2.Cu")
		(net "P5E_CPU1_PE1_TX_DP<12>")
	)
	(arc
		(start 107.505754 -214.429848)
		(mid 107.471103 -214.348051)
		(end 107.416854 -214.277702)
		(width 0.0889)
		(layer "In2.Cu")
		(net "P5E_CPU1_PE1_TX_DP<12>")
	)
	(arc
		(start 107.506516 -217.888566)
		(mid 107.506436 -217.876118)
		(end 107.50677 -217.863674)
		(width 0.0889)
		(layer "In2.Cu")
		(net "P5E_CPU1_PE1_TX_DP<12>")
	)
	(arc
		(start 108.446316 -221.115382)
		(mid 108.366154 -220.843193)
		(end 108.163868 -220.644212)
		(width 0.0889)
		(layer "In2.Cu")
		(net "P5E_CPU1_PE1_TX_DP<12>")
	)
	(arc
		(start 107.685078 -218.197684)
		(mid 107.556674 -218.065739)
		(end 107.506516 -217.888566)
		(width 0.0889)
		(layer "In2.Cu")
		(net "P5E_CPU1_PE1_TX_DP<12>")
	)
	(arc
		(start 108.154978 -220.639132)
		(mid 108.024064 -220.502772)
		(end 107.976416 -220.319854)
		(width 0.0889)
		(layer "In2.Cu")
		(net "P5E_CPU1_PE1_TX_DP<12>")
	)
	(arc
		(start 107.685078 -223.080834)
		(mid 107.557998 -222.95082)
		(end 107.507024 -222.776288)
		(width 0.0889)
		(layer "In2.Cu")
		(net "P5E_CPU1_PE1_TX_DP<12>")
	)
	(arc
		(start 107.214924 -215.755982)
		(mid 107.08401 -215.619622)
		(end 107.036362 -215.436704)
		(width 0.0889)
		(layer "In2.Cu")
		(net "P5E_CPU1_PE1_TX_DP<12>")
	)
	(arc
		(start 107.685078 -216.569798)
		(mid 107.554164 -216.433438)
		(end 107.506516 -216.25052)
		(width 0.0889)
		(layer "In2.Cu")
		(net "P5E_CPU1_PE1_TX_DP<12>")
	)
	(arc
		(start 107.693968 -217.554048)
		(mid 107.897273 -217.353182)
		(end 107.976416 -217.07856)
		(width 0.0889)
		(layer "In2.Cu")
		(net "P5E_CPU1_PE1_TX_DP<12>")
	)
	(arc
		(start 108.154978 -223.894904)
		(mid 108.024064 -223.758544)
		(end 107.976416 -223.575626)
		(width 0.0889)
		(layer "In2.Cu")
		(net "P5E_CPU1_PE1_TX_DP<12>")
	)
	(arc
		(start 107.036362 -215.436704)
		(mid 107.036414 -215.429337)
		(end 107.036616 -215.421972)
		(width 0.0889)
		(layer "In2.Cu")
		(net "P5E_CPU1_PE1_TX_DP<12>")
	)
	(segment
		(start 27.010868 -16.692626)
		(end 26.684478 -16.366236)
		(width 0.13208)
		(layer "F.Cu")
		(net "P5E_CPU1_PE1_TX_DP<11>")
	)
	(segment
		(start 27.010868 -17.31137)
		(end 27.010868 -16.692626)
		(width 0.13208)
		(layer "F.Cu")
		(net "P5E_CPU1_PE1_TX_DP<11>")
	)
	(segment
		(start 26.709878 -17.61236)
		(end 27.010868 -17.31137)
		(width 0.13208)
		(layer "F.Cu")
		(net "P5E_CPU1_PE1_TX_DP<11>")
	)
	(segment
		(start 108.820712 -224.925382)
		(end 108.820712 -224.389696)
		(width 0.13208)
		(layer "F.Cu")
		(net "P5E_CPU1_PE1_TX_DP<11>")
	)
	(segment
		(start 108.820712 -224.389696)
		(end 108.820966 -224.389442)
		(width 0.13208)
		(layer "F.Cu")
		(net "P5E_CPU1_PE1_TX_DP<11>")
	)
	(segment
		(start 107.785662 -215.436704)
		(end 107.785662 -215.414606)
		(width 0.0889)
		(layer "In2.Cu")
		(net "P5E_CPU1_PE1_TX_DP<11>")
	)
	(segment
		(start 108.539026 -218.368372)
		(end 108.53801 -218.367864)
		(width 0.0889)
		(layer "In2.Cu")
		(net "P5E_CPU1_PE1_TX_DP<11>")
	)
	(segment
		(start 108.06557 -215.924384)
		(end 108.062268 -215.922606)
		(width 0.0889)
		(layer "In2.Cu")
		(net "P5E_CPU1_PE1_TX_DP<11>")
	)
	(segment
		(start 108.255816 -217.8939)
		(end 108.255816 -217.859864)
		(width 0.0889)
		(layer "In2.Cu")
		(net "P5E_CPU1_PE1_TX_DP<11>")
	)
	(segment
		(start 70.110604 -97.230692)
		(end 52.198524 -58.161936)
		(width 0.14732)
		(layer "In2.Cu")
		(net "P5E_CPU1_PE1_TX_DP<11>")
	)
	(segment
		(start 109.007402 -221.45879)
		(end 109.008164 -221.458282)
		(width 0.0889)
		(layer "In2.Cu")
		(net "P5E_CPU1_PE1_TX_DP<11>")
	)
	(segment
		(start 107.744006 -212.481668)
		(end 107.64901 -210.94573)
		(width 0.14732)
		(layer "In2.Cu")
		(net "P5E_CPU1_PE1_TX_DP<11>")
	)
	(segment
		(start 104.070658 -185.819034)
		(end 70.110604 -97.230692)
		(width 0.14732)
		(layer "In2.Cu")
		(net "P5E_CPU1_PE1_TX_DP<11>")
	)
	(segment
		(start 109.008164 -221.458282)
		(end 109.009688 -221.45752)
		(width 0.0889)
		(layer "In2.Cu")
		(net "P5E_CPU1_PE1_TX_DP<11>")
	)
	(segment
		(start 27.004518 -17.907)
		(end 26.709878 -17.61236)
		(width 0.14732)
		(layer "In2.Cu")
		(net "P5E_CPU1_PE1_TX_DP<11>")
	)
	(segment
		(start 107.744006 -213.220554)
		(end 107.744006 -212.481668)
		(width 0.14732)
		(layer "In2.Cu")
		(net "P5E_CPU1_PE1_TX_DP<11>")
	)
	(segment
		(start 107.863894 -214.054944)
		(end 107.785916 -213.865714)
		(width 0.0889)
		(layer "In2.Cu")
		(net "P5E_CPU1_PE1_TX_DP<11>")
	)
	(segment
		(start 108.255308 -214.622634)
		(end 108.255562 -214.62238)
		(width 0.0889)
		(layer "In2.Cu")
		(net "P5E_CPU1_PE1_TX_DP<11>")
	)
	(segment
		(start 108.255816 -219.515944)
		(end 108.255816 -219.490544)
		(width 0.0889)
		(layer "In2.Cu")
		(net "P5E_CPU1_PE1_TX_DP<11>")
	)
	(segment
		(start 109.002068 -221.461838)
		(end 109.007402 -221.45879)
		(width 0.0889)
		(layer "In2.Cu")
		(net "P5E_CPU1_PE1_TX_DP<11>")
	)
	(segment
		(start 108.067856 -214.946992)
		(end 108.076746 -214.941912)
		(width 0.0889)
		(layer "In2.Cu")
		(net "P5E_CPU1_PE1_TX_DP<11>")
	)
	(segment
		(start 107.64901 -210.94573)
		(end 104.92105 -189.21349)
		(width 0.14732)
		(layer "In2.Cu")
		(net "P5E_CPU1_PE1_TX_DP<11>")
	)
	(segment
		(start 109.009688 -221.45752)
		(end 109.017054 -221.453202)
		(width 0.0889)
		(layer "In2.Cu")
		(net "P5E_CPU1_PE1_TX_DP<11>")
	)
	(segment
		(start 108.068872 -214.259668)
		(end 107.863894 -214.054944)
		(width 0.0889)
		(layer "In2.Cu")
		(net "P5E_CPU1_PE1_TX_DP<11>")
	)
	(segment
		(start 108.255816 -222.780098)
		(end 108.255816 -222.746062)
		(width 0.0889)
		(layer "In2.Cu")
		(net "P5E_CPU1_PE1_TX_DP<11>")
	)
	(segment
		(start 109.017054 -220.814646)
		(end 109.008164 -220.809566)
		(width 0.0889)
		(layer "In2.Cu")
		(net "P5E_CPU1_PE1_TX_DP<11>")
	)
	(segment
		(start 108.067602 -215.925654)
		(end 108.06557 -215.924384)
		(width 0.0889)
		(layer "In2.Cu")
		(net "P5E_CPU1_PE1_TX_DP<11>")
	)
	(segment
		(start 52.198524 -58.161936)
		(end 27.004518 -18.807176)
		(width 0.14732)
		(layer "In2.Cu")
		(net "P5E_CPU1_PE1_TX_DP<11>")
	)
	(segment
		(start 108.077254 -215.931242)
		(end 108.077508 -215.93175)
		(width 0.0889)
		(layer "In2.Cu")
		(net "P5E_CPU1_PE1_TX_DP<11>")
	)
	(segment
		(start 108.725462 -223.575626)
		(end 108.725462 -223.56699)
		(width 0.0889)
		(layer "In2.Cu")
		(net "P5E_CPU1_PE1_TX_DP<11>")
	)
	(segment
		(start 108.069126 -215.92667)
		(end 108.067602 -215.925654)
		(width 0.0889)
		(layer "In2.Cu")
		(net "P5E_CPU1_PE1_TX_DP<11>")
	)
	(segment
		(start 107.785916 -213.284562)
		(end 107.744006 -213.242652)
		(width 0.0889)
		(layer "In2.Cu")
		(net "P5E_CPU1_PE1_TX_DP<11>")
	)
	(segment
		(start 108.53801 -222.272098)
		(end 108.5469 -222.267018)
		(width 0.0889)
		(layer "In2.Cu")
		(net "P5E_CPU1_PE1_TX_DP<11>")
	)
	(segment
		(start 107.785916 -213.865714)
		(end 107.785916 -213.284562)
		(width 0.0889)
		(layer "In2.Cu")
		(net "P5E_CPU1_PE1_TX_DP<11>")
	)
	(segment
		(start 108.820966 -224.389442)
		(end 108.97743 -224.118424)
		(width 0.0889)
		(layer "In2.Cu")
		(net "P5E_CPU1_PE1_TX_DP<11>")
	)
	(segment
		(start 108.255562 -214.62238)
		(end 108.255562 -214.460328)
		(width 0.0889)
		(layer "In2.Cu")
		(net "P5E_CPU1_PE1_TX_DP<11>")
	)
	(segment
		(start 107.744006 -213.242652)
		(end 107.744006 -213.220554)
		(width 0.0889)
		(layer "In2.Cu")
		(net "P5E_CPU1_PE1_TX_DP<11>")
	)
	(segment
		(start 108.725462 -220.334078)
		(end 108.725462 -220.311218)
		(width 0.0889)
		(layer "In2.Cu")
		(net "P5E_CPU1_PE1_TX_DP<11>")
	)
	(segment
		(start 108.255816 -216.260426)
		(end 108.255816 -216.25052)
		(width 0.0889)
		(layer "In2.Cu")
		(net "P5E_CPU1_PE1_TX_DP<11>")
	)
	(segment
		(start 108.089446 -214.271606)
		(end 108.068872 -214.259668)
		(width 0.0889)
		(layer "In2.Cu")
		(net "P5E_CPU1_PE1_TX_DP<11>")
	)
	(segment
		(start 108.725462 -217.072972)
		(end 108.725462 -217.0557)
		(width 0.0889)
		(layer "In2.Cu")
		(net "P5E_CPU1_PE1_TX_DP<11>")
	)
	(segment
		(start 104.92105 -189.21349)
		(end 104.070658 -185.819034)
		(width 0.14732)
		(layer "In2.Cu")
		(net "P5E_CPU1_PE1_TX_DP<11>")
	)
	(segment
		(start 108.077508 -215.93175)
		(end 108.069126 -215.92667)
		(width 0.0889)
		(layer "In2.Cu")
		(net "P5E_CPU1_PE1_TX_DP<11>")
	)
	(segment
		(start 108.97743 -224.118424)
		(end 108.9533 -224.02927)
		(width 0.0889)
		(layer "In2.Cu")
		(net "P5E_CPU1_PE1_TX_DP<11>")
	)
	(segment
		(start 27.004518 -18.807176)
		(end 27.004518 -17.907)
		(width 0.14732)
		(layer "In2.Cu")
		(net "P5E_CPU1_PE1_TX_DP<11>")
	)
	(segment
		(start 108.5469 -218.372944)
		(end 108.539026 -218.368372)
		(width 0.0889)
		(layer "In2.Cu")
		(net "P5E_CPU1_PE1_TX_DP<11>")
	)
	(segment
		(start 108.53801 -219.01658)
		(end 108.5469 -219.0115)
		(width 0.0889)
		(layer "In2.Cu")
		(net "P5E_CPU1_PE1_TX_DP<11>")
	)
	(arc
		(start 108.725462 -220.311218)
		(mid 108.673192 -220.128853)
		(end 108.538264 -219.995496)
		(width 0.0889)
		(layer "In2.Cu")
		(net "P5E_CPU1_PE1_TX_DP<11>")
	)
	(arc
		(start 109.017054 -221.453202)
		(mid 109.195651 -221.133924)
		(end 109.017054 -220.814646)
		(width 0.0889)
		(layer "In2.Cu")
		(net "P5E_CPU1_PE1_TX_DP<11>")
	)
	(arc
		(start 108.255816 -219.490544)
		(mid 108.335186 -219.21681)
		(end 108.53801 -219.01658)
		(width 0.0889)
		(layer "In2.Cu")
		(net "P5E_CPU1_PE1_TX_DP<11>")
	)
	(arc
		(start 108.255816 -216.25052)
		(mid 108.208137 -216.06762)
		(end 108.077254 -215.931242)
		(width 0.0889)
		(layer "In2.Cu")
		(net "P5E_CPU1_PE1_TX_DP<11>")
	)
	(arc
		(start 108.538264 -219.995496)
		(mid 108.333929 -219.792891)
		(end 108.255816 -219.515944)
		(width 0.0889)
		(layer "In2.Cu")
		(net "P5E_CPU1_PE1_TX_DP<11>")
	)
	(arc
		(start 108.255816 -222.746062)
		(mid 108.335186 -222.472328)
		(end 108.53801 -222.272098)
		(width 0.0889)
		(layer "In2.Cu")
		(net "P5E_CPU1_PE1_TX_DP<11>")
	)
	(arc
		(start 108.538264 -223.251268)
		(mid 108.335978 -223.052287)
		(end 108.255816 -222.780098)
		(width 0.0889)
		(layer "In2.Cu")
		(net "P5E_CPU1_PE1_TX_DP<11>")
	)
	(arc
		(start 108.5469 -222.267018)
		(mid 108.677814 -222.130658)
		(end 108.725462 -221.94774)
		(width 0.0889)
		(layer "In2.Cu")
		(net "P5E_CPU1_PE1_TX_DP<11>")
	)
	(arc
		(start 108.725462 -221.94774)
		(mid 108.799453 -221.668174)
		(end 109.002068 -221.461838)
		(width 0.0889)
		(layer "In2.Cu")
		(net "P5E_CPU1_PE1_TX_DP<11>")
	)
	(arc
		(start 108.53801 -218.367864)
		(mid 108.335187 -218.167633)
		(end 108.255816 -217.8939)
		(width 0.0889)
		(layer "In2.Cu")
		(net "P5E_CPU1_PE1_TX_DP<11>")
	)
	(arc
		(start 108.255816 -217.859864)
		(mid 108.335978 -217.587675)
		(end 108.538264 -217.388694)
		(width 0.0889)
		(layer "In2.Cu")
		(net "P5E_CPU1_PE1_TX_DP<11>")
	)
	(arc
		(start 108.725462 -223.56699)
		(mid 108.673192 -223.384625)
		(end 108.538264 -223.251268)
		(width 0.0889)
		(layer "In2.Cu")
		(net "P5E_CPU1_PE1_TX_DP<11>")
	)
	(arc
		(start 107.785662 -215.414606)
		(mid 107.866573 -215.144478)
		(end 108.067856 -214.946992)
		(width 0.0889)
		(layer "In2.Cu")
		(net "P5E_CPU1_PE1_TX_DP<11>")
	)
	(arc
		(start 108.725462 -217.0557)
		(mid 108.673192 -216.873335)
		(end 108.538264 -216.739978)
		(width 0.0889)
		(layer "In2.Cu")
		(net "P5E_CPU1_PE1_TX_DP<11>")
	)
	(arc
		(start 108.076746 -214.941912)
		(mid 108.204 -214.811946)
		(end 108.255054 -214.637366)
		(width 0.0889)
		(layer "In2.Cu")
		(net "P5E_CPU1_PE1_TX_DP<11>")
	)
	(arc
		(start 108.538264 -216.739978)
		(mid 108.333929 -216.537373)
		(end 108.255816 -216.260426)
		(width 0.0889)
		(layer "In2.Cu")
		(net "P5E_CPU1_PE1_TX_DP<11>")
	)
	(arc
		(start 108.255562 -214.460328)
		(mid 108.187374 -214.35288)
		(end 108.089446 -214.271606)
		(width 0.0889)
		(layer "In2.Cu")
		(net "P5E_CPU1_PE1_TX_DP<11>")
	)
	(arc
		(start 109.008164 -220.809566)
		(mid 108.804683 -220.608762)
		(end 108.725462 -220.334078)
		(width 0.0889)
		(layer "In2.Cu")
		(net "P5E_CPU1_PE1_TX_DP<11>")
	)
	(arc
		(start 108.9533 -224.02927)
		(mid 108.785546 -223.829492)
		(end 108.725462 -223.575626)
		(width 0.0889)
		(layer "In2.Cu")
		(net "P5E_CPU1_PE1_TX_DP<11>")
	)
	(arc
		(start 108.062268 -215.922606)
		(mid 107.859681 -215.716255)
		(end 107.785662 -215.436704)
		(width 0.0889)
		(layer "In2.Cu")
		(net "P5E_CPU1_PE1_TX_DP<11>")
	)
	(arc
		(start 108.255054 -214.637366)
		(mid 108.255251 -214.630001)
		(end 108.255308 -214.622634)
		(width 0.0889)
		(layer "In2.Cu")
		(net "P5E_CPU1_PE1_TX_DP<11>")
	)
	(arc
		(start 108.538264 -217.388694)
		(mid 108.673197 -217.25534)
		(end 108.725462 -217.072972)
		(width 0.0889)
		(layer "In2.Cu")
		(net "P5E_CPU1_PE1_TX_DP<11>")
	)
	(arc
		(start 108.5469 -219.0115)
		(mid 108.725376 -218.692222)
		(end 108.5469 -218.372944)
		(width 0.0889)
		(layer "In2.Cu")
		(net "P5E_CPU1_PE1_TX_DP<11>")
	)
	(segment
		(start 30.063948 -18.83283)
		(end 30.063948 -18.219166)
		(width 0.13208)
		(layer "F.Cu")
		(net "P5E_CPU1_PE1_TX_DP<10>")
	)
	(segment
		(start 110.230412 -225.738944)
		(end 110.230412 -225.203258)
		(width 0.13208)
		(layer "F.Cu")
		(net "P5E_CPU1_PE1_TX_DP<10>")
	)
	(segment
		(start 30.367478 -19.13636)
		(end 30.063948 -18.83283)
		(width 0.13208)
		(layer "F.Cu")
		(net "P5E_CPU1_PE1_TX_DP<10>")
	)
	(segment
		(start 30.063948 -18.219166)
		(end 30.392878 -17.890236)
		(width 0.13208)
		(layer "F.Cu")
		(net "P5E_CPU1_PE1_TX_DP<10>")
	)
	(segment
		(start 110.230666 -225.739198)
		(end 110.230412 -225.738944)
		(width 0.13208)
		(layer "F.Cu")
		(net "P5E_CPU1_PE1_TX_DP<10>")
	)
	(segment
		(start 109.565694 -219.825824)
		(end 109.564678 -219.825316)
		(width 0.0889)
		(layer "In2.Cu")
		(net "P5E_CPU1_PE1_TX_DP<10>")
	)
	(segment
		(start 109.573568 -222.437198)
		(end 109.579664 -222.433642)
		(width 0.0889)
		(layer "In2.Cu")
		(net "P5E_CPU1_PE1_TX_DP<10>")
	)
	(segment
		(start 109.576616 -218.204542)
		(end 109.574584 -218.203272)
		(width 0.0889)
		(layer "In2.Cu")
		(net "P5E_CPU1_PE1_TX_DP<10>")
	)
	(segment
		(start 109.427772 -213.533228)
		(end 109.427772 -213.51113)
		(width 0.0889)
		(layer "In2.Cu")
		(net "P5E_CPU1_PE1_TX_DP<10>")
	)
	(segment
		(start 109.564678 -222.442278)
		(end 109.573568 -222.437198)
		(width 0.0889)
		(layer "In2.Cu")
		(net "P5E_CPU1_PE1_TX_DP<10>")
	)
	(segment
		(start 109.427772 -213.51113)
		(end 109.427772 -212.383116)
		(width 0.14732)
		(layer "In2.Cu")
		(net "P5E_CPU1_PE1_TX_DP<10>")
	)
	(segment
		(start 110.325916 -221.14383)
		(end 110.325916 -221.115382)
		(width 0.0889)
		(layer "In2.Cu")
		(net "P5E_CPU1_PE1_TX_DP<10>")
	)
	(segment
		(start 110.073948 -224.93224)
		(end 110.098078 -224.843086)
		(width 0.0889)
		(layer "In2.Cu")
		(net "P5E_CPU1_PE1_TX_DP<10>")
	)
	(segment
		(start 109.103414 -215.761062)
		(end 109.094524 -215.755982)
		(width 0.0889)
		(layer "In2.Cu")
		(net "P5E_CPU1_PE1_TX_DP<10>")
	)
	(segment
		(start 109.579664 -219.833952)
		(end 109.565948 -219.825824)
		(width 0.0889)
		(layer "In2.Cu")
		(net "P5E_CPU1_PE1_TX_DP<10>")
	)
	(segment
		(start 110.034578 -221.628462)
		(end 110.040166 -221.625414)
		(width 0.0889)
		(layer "In2.Cu")
		(net "P5E_CPU1_PE1_TX_DP<10>")
	)
	(segment
		(start 110.042706 -223.899476)
		(end 110.040166 -223.897952)
		(width 0.0889)
		(layer "In2.Cu")
		(net "P5E_CPU1_PE1_TX_DP<10>")
	)
	(segment
		(start 109.56544 -218.198192)
		(end 109.564678 -218.197684)
		(width 0.0889)
		(layer "In2.Cu")
		(net "P5E_CPU1_PE1_TX_DP<10>")
	)
	(segment
		(start 109.573568 -216.574878)
		(end 109.564678 -216.569798)
		(width 0.0889)
		(layer "In2.Cu")
		(net "P5E_CPU1_PE1_TX_DP<10>")
	)
	(segment
		(start 109.10951 -215.764618)
		(end 109.103414 -215.761062)
		(width 0.0889)
		(layer "In2.Cu")
		(net "P5E_CPU1_PE1_TX_DP<10>")
	)
	(segment
		(start 109.094524 -215.117426)
		(end 109.138466 -215.092026)
		(width 0.0889)
		(layer "In2.Cu")
		(net "P5E_CPU1_PE1_TX_DP<10>")
	)
	(segment
		(start 109.427772 -212.383116)
		(end 106.143552 -189.022736)
		(width 0.14732)
		(layer "In2.Cu")
		(net "P5E_CPU1_PE1_TX_DP<10>")
	)
	(segment
		(start 109.385608 -213.575392)
		(end 109.427772 -213.533228)
		(width 0.0889)
		(layer "In2.Cu")
		(net "P5E_CPU1_PE1_TX_DP<10>")
	)
	(segment
		(start 105.209848 -185.408824)
		(end 71.099172 -96.440752)
		(width 0.14732)
		(layer "In2.Cu")
		(net "P5E_CPU1_PE1_TX_DP<10>")
	)
	(segment
		(start 109.564678 -219.18676)
		(end 109.57179 -219.182696)
		(width 0.0889)
		(layer "In2.Cu")
		(net "P5E_CPU1_PE1_TX_DP<10>")
	)
	(segment
		(start 109.565948 -219.825824)
		(end 109.565694 -219.825824)
		(width 0.0889)
		(layer "In2.Cu")
		(net "P5E_CPU1_PE1_TX_DP<10>")
	)
	(segment
		(start 109.579664 -218.20632)
		(end 109.576616 -218.204542)
		(width 0.0889)
		(layer "In2.Cu")
		(net "P5E_CPU1_PE1_TX_DP<10>")
	)
	(segment
		(start 109.856016 -223.575626)
		(end 109.856016 -223.561402)
		(width 0.0889)
		(layer "In2.Cu")
		(net "P5E_CPU1_PE1_TX_DP<10>")
	)
	(segment
		(start 110.043468 -223.899984)
		(end 110.042706 -223.899476)
		(width 0.0889)
		(layer "In2.Cu")
		(net "P5E_CPU1_PE1_TX_DP<10>")
	)
	(segment
		(start 109.579664 -216.578434)
		(end 109.573568 -216.574878)
		(width 0.0889)
		(layer "In2.Cu")
		(net "P5E_CPU1_PE1_TX_DP<10>")
	)
	(segment
		(start 30.072838 -20.05457)
		(end 30.072838 -19.431)
		(width 0.14732)
		(layer "In2.Cu")
		(net "P5E_CPU1_PE1_TX_DP<10>")
	)
	(segment
		(start 110.040166 -221.625414)
		(end 110.040928 -221.624906)
		(width 0.0889)
		(layer "In2.Cu")
		(net "P5E_CPU1_PE1_TX_DP<10>")
	)
	(segment
		(start 106.143552 -189.022736)
		(end 105.209848 -185.408824)
		(width 0.14732)
		(layer "In2.Cu")
		(net "P5E_CPU1_PE1_TX_DP<10>")
	)
	(segment
		(start 109.572552 -223.085406)
		(end 109.564678 -223.080834)
		(width 0.0889)
		(layer "In2.Cu")
		(net "P5E_CPU1_PE1_TX_DP<10>")
	)
	(segment
		(start 71.099172 -96.440752)
		(end 53.00853 -56.985154)
		(width 0.14732)
		(layer "In2.Cu")
		(net "P5E_CPU1_PE1_TX_DP<10>")
	)
	(segment
		(start 109.856016 -217.07856)
		(end 109.856016 -217.064336)
		(width 0.0889)
		(layer "In2.Cu")
		(net "P5E_CPU1_PE1_TX_DP<10>")
	)
	(segment
		(start 110.040166 -223.897952)
		(end 110.034578 -223.894904)
		(width 0.0889)
		(layer "In2.Cu")
		(net "P5E_CPU1_PE1_TX_DP<10>")
	)
	(segment
		(start 109.572044 -218.202002)
		(end 109.566964 -218.198954)
		(width 0.0889)
		(layer "In2.Cu")
		(net "P5E_CPU1_PE1_TX_DP<10>")
	)
	(segment
		(start 110.325916 -224.389442)
		(end 110.325916 -224.379536)
		(width 0.0889)
		(layer "In2.Cu")
		(net "P5E_CPU1_PE1_TX_DP<10>")
	)
	(segment
		(start 109.572806 -219.182188)
		(end 109.573568 -219.18168)
		(width 0.0889)
		(layer "In2.Cu")
		(net "P5E_CPU1_PE1_TX_DP<10>")
	)
	(segment
		(start 109.573568 -219.18168)
		(end 109.579664 -219.178124)
		(width 0.0889)
		(layer "In2.Cu")
		(net "P5E_CPU1_PE1_TX_DP<10>")
	)
	(segment
		(start 110.230412 -225.203258)
		(end 110.189264 -225.131884)
		(width 0.0889)
		(layer "In2.Cu")
		(net "P5E_CPU1_PE1_TX_DP<10>")
	)
	(segment
		(start 110.040928 -221.624906)
		(end 110.042706 -221.62389)
		(width 0.0889)
		(layer "In2.Cu")
		(net "P5E_CPU1_PE1_TX_DP<10>")
	)
	(segment
		(start 110.042706 -221.62389)
		(end 110.043468 -221.623382)
		(width 0.0889)
		(layer "In2.Cu")
		(net "P5E_CPU1_PE1_TX_DP<10>")
	)
	(segment
		(start 53.00853 -56.985154)
		(end 30.072838 -20.05457)
		(width 0.14732)
		(layer "In2.Cu")
		(net "P5E_CPU1_PE1_TX_DP<10>")
	)
	(segment
		(start 109.573568 -223.085914)
		(end 109.572552 -223.085406)
		(width 0.0889)
		(layer "In2.Cu")
		(net "P5E_CPU1_PE1_TX_DP<10>")
	)
	(segment
		(start 109.385608 -214.57666)
		(end 109.385608 -213.575392)
		(width 0.0889)
		(layer "In2.Cu")
		(net "P5E_CPU1_PE1_TX_DP<10>")
	)
	(segment
		(start 110.189264 -225.131884)
		(end 110.073948 -224.93224)
		(width 0.0889)
		(layer "In2.Cu")
		(net "P5E_CPU1_PE1_TX_DP<10>")
	)
	(segment
		(start 109.566964 -218.198954)
		(end 109.56544 -218.198192)
		(width 0.0889)
		(layer "In2.Cu")
		(net "P5E_CPU1_PE1_TX_DP<10>")
	)
	(segment
		(start 109.564678 -217.559128)
		(end 109.573568 -217.554048)
		(width 0.0889)
		(layer "In2.Cu")
		(net "P5E_CPU1_PE1_TX_DP<10>")
	)
	(segment
		(start 30.072838 -19.431)
		(end 30.367478 -19.13636)
		(width 0.14732)
		(layer "In2.Cu")
		(net "P5E_CPU1_PE1_TX_DP<10>")
	)
	(segment
		(start 109.57179 -219.182696)
		(end 109.572806 -219.182188)
		(width 0.0889)
		(layer "In2.Cu")
		(net "P5E_CPU1_PE1_TX_DP<10>")
	)
	(segment
		(start 110.043468 -220.644212)
		(end 110.034578 -220.639132)
		(width 0.0889)
		(layer "In2.Cu")
		(net "P5E_CPU1_PE1_TX_DP<10>")
	)
	(segment
		(start 109.574584 -218.203272)
		(end 109.572044 -218.202002)
		(width 0.0889)
		(layer "In2.Cu")
		(net "P5E_CPU1_PE1_TX_DP<10>")
	)
	(arc
		(start 109.094524 -215.755982)
		(mid 108.96361 -215.619622)
		(end 108.915962 -215.436704)
		(width 0.0889)
		(layer "In2.Cu")
		(net "P5E_CPU1_PE1_TX_DP<10>")
	)
	(arc
		(start 109.564678 -219.825316)
		(mid 109.386202 -219.506038)
		(end 109.564678 -219.18676)
		(width 0.0889)
		(layer "In2.Cu")
		(net "P5E_CPU1_PE1_TX_DP<10>")
	)
	(arc
		(start 109.564678 -218.197684)
		(mid 109.436274 -218.065739)
		(end 109.386116 -217.888566)
		(width 0.0889)
		(layer "In2.Cu")
		(net "P5E_CPU1_PE1_TX_DP<10>")
	)
	(arc
		(start 108.915962 -215.436704)
		(mid 108.916014 -215.429337)
		(end 108.916216 -215.421972)
		(width 0.0889)
		(layer "In2.Cu")
		(net "P5E_CPU1_PE1_TX_DP<10>")
	)
	(arc
		(start 110.034578 -223.894904)
		(mid 109.903664 -223.758544)
		(end 109.856016 -223.575626)
		(width 0.0889)
		(layer "In2.Cu")
		(net "P5E_CPU1_PE1_TX_DP<10>")
	)
	(arc
		(start 110.098078 -224.843086)
		(mid 110.10665 -224.836564)
		(end 110.115096 -224.829878)
		(width 0.0889)
		(layer "In2.Cu")
		(net "P5E_CPU1_PE1_TX_DP<10>")
	)
	(arc
		(start 110.325916 -224.379536)
		(mid 110.247805 -224.102587)
		(end 110.043468 -223.899984)
		(width 0.0889)
		(layer "In2.Cu")
		(net "P5E_CPU1_PE1_TX_DP<10>")
	)
	(arc
		(start 109.579664 -222.433642)
		(mid 109.782077 -222.227229)
		(end 109.856016 -221.94774)
		(width 0.0889)
		(layer "In2.Cu")
		(net "P5E_CPU1_PE1_TX_DP<10>")
	)
	(arc
		(start 109.856016 -217.064336)
		(mid 109.7821 -216.784834)
		(end 109.579664 -216.578434)
		(width 0.0889)
		(layer "In2.Cu")
		(net "P5E_CPU1_PE1_TX_DP<10>")
	)
	(arc
		(start 110.115096 -224.829878)
		(mid 110.270494 -224.633597)
		(end 110.325916 -224.389442)
		(width 0.0889)
		(layer "In2.Cu")
		(net "P5E_CPU1_PE1_TX_DP<10>")
	)
	(arc
		(start 109.579664 -219.178124)
		(mid 109.85599 -218.692222)
		(end 109.579664 -218.20632)
		(width 0.0889)
		(layer "In2.Cu")
		(net "P5E_CPU1_PE1_TX_DP<10>")
	)
	(arc
		(start 109.856016 -221.94774)
		(mid 109.903695 -221.76484)
		(end 110.034578 -221.628462)
		(width 0.0889)
		(layer "In2.Cu")
		(net "P5E_CPU1_PE1_TX_DP<10>")
	)
	(arc
		(start 109.856016 -220.319854)
		(mid 109.7821 -220.040352)
		(end 109.579664 -219.833952)
		(width 0.0889)
		(layer "In2.Cu")
		(net "P5E_CPU1_PE1_TX_DP<10>")
	)
	(arc
		(start 110.043468 -221.623382)
		(mid 110.247803 -221.420777)
		(end 110.325916 -221.14383)
		(width 0.0889)
		(layer "In2.Cu")
		(net "P5E_CPU1_PE1_TX_DP<10>")
	)
	(arc
		(start 109.138466 -215.092026)
		(mid 109.331704 -214.867758)
		(end 109.385608 -214.57666)
		(width 0.0889)
		(layer "In2.Cu")
		(net "P5E_CPU1_PE1_TX_DP<10>")
	)
	(arc
		(start 109.38637 -222.751396)
		(mid 109.436385 -222.574265)
		(end 109.564678 -222.442278)
		(width 0.0889)
		(layer "In2.Cu")
		(net "P5E_CPU1_PE1_TX_DP<10>")
	)
	(arc
		(start 109.386116 -216.25052)
		(mid 109.312125 -215.970954)
		(end 109.10951 -215.764618)
		(width 0.0889)
		(layer "In2.Cu")
		(net "P5E_CPU1_PE1_TX_DP<10>")
	)
	(arc
		(start 109.573568 -217.554048)
		(mid 109.776873 -217.353182)
		(end 109.856016 -217.07856)
		(width 0.0889)
		(layer "In2.Cu")
		(net "P5E_CPU1_PE1_TX_DP<10>")
	)
	(arc
		(start 109.38637 -217.863674)
		(mid 109.437424 -217.689094)
		(end 109.564678 -217.559128)
		(width 0.0889)
		(layer "In2.Cu")
		(net "P5E_CPU1_PE1_TX_DP<10>")
	)
	(arc
		(start 109.856016 -223.561402)
		(mid 109.776875 -223.286779)
		(end 109.573568 -223.085914)
		(width 0.0889)
		(layer "In2.Cu")
		(net "P5E_CPU1_PE1_TX_DP<10>")
	)
	(arc
		(start 108.916216 -215.421972)
		(mid 108.96727 -215.247392)
		(end 109.094524 -215.117426)
		(width 0.0889)
		(layer "In2.Cu")
		(net "P5E_CPU1_PE1_TX_DP<10>")
	)
	(arc
		(start 109.386624 -222.776288)
		(mid 109.386291 -222.763844)
		(end 109.38637 -222.751396)
		(width 0.0889)
		(layer "In2.Cu")
		(net "P5E_CPU1_PE1_TX_DP<10>")
	)
	(arc
		(start 110.034578 -220.639132)
		(mid 109.903664 -220.502772)
		(end 109.856016 -220.319854)
		(width 0.0889)
		(layer "In2.Cu")
		(net "P5E_CPU1_PE1_TX_DP<10>")
	)
	(arc
		(start 109.564678 -223.080834)
		(mid 109.437598 -222.95082)
		(end 109.386624 -222.776288)
		(width 0.0889)
		(layer "In2.Cu")
		(net "P5E_CPU1_PE1_TX_DP<10>")
	)
	(arc
		(start 109.386116 -217.888566)
		(mid 109.386036 -217.876118)
		(end 109.38637 -217.863674)
		(width 0.0889)
		(layer "In2.Cu")
		(net "P5E_CPU1_PE1_TX_DP<10>")
	)
	(arc
		(start 109.564678 -216.569798)
		(mid 109.433764 -216.433438)
		(end 109.386116 -216.25052)
		(width 0.0889)
		(layer "In2.Cu")
		(net "P5E_CPU1_PE1_TX_DP<10>")
	)
	(arc
		(start 110.325916 -221.115382)
		(mid 110.245754 -220.843193)
		(end 110.043468 -220.644212)
		(width 0.0889)
		(layer "In2.Cu")
		(net "P5E_CPU1_PE1_TX_DP<10>")
	)
	(segment
		(start 119.628412 -225.738944)
		(end 119.628412 -225.203258)
		(width 0.13208)
		(layer "F.Cu")
		(net "P5E_CPU1_PE1_TX_DP<0>")
	)
	(segment
		(start 119.628666 -225.739198)
		(end 119.628412 -225.738944)
		(width 0.13208)
		(layer "F.Cu")
		(net "P5E_CPU1_PE1_TX_DP<0>")
	)
	(segment
		(start 58.3438 -18.83283)
		(end 58.3438 -18.219166)
		(width 0.13208)
		(layer "F.Cu")
		(net "P5E_CPU1_PE1_TX_DP<0>")
	)
	(segment
		(start 58.3438 -18.219166)
		(end 58.67273 -17.890236)
		(width 0.13208)
		(layer "F.Cu")
		(net "P5E_CPU1_PE1_TX_DP<0>")
	)
	(segment
		(start 58.64733 -19.13636)
		(end 58.3438 -18.83283)
		(width 0.13208)
		(layer "F.Cu")
		(net "P5E_CPU1_PE1_TX_DP<0>")
	)
	(segment
		(start 119.441468 -223.899984)
		(end 119.440706 -223.899476)
		(width 0.0889)
		(layer "In2.Cu")
		(net "P5E_CPU1_PE1_TX_DP<0>")
	)
	(segment
		(start 119.723916 -224.389442)
		(end 119.723916 -224.379536)
		(width 0.0889)
		(layer "In2.Cu")
		(net "P5E_CPU1_PE1_TX_DP<0>")
	)
	(segment
		(start 119.254016 -223.575626)
		(end 119.254016 -223.561402)
		(width 0.0889)
		(layer "In2.Cu")
		(net "P5E_CPU1_PE1_TX_DP<0>")
	)
	(segment
		(start 119.471948 -224.93224)
		(end 119.496078 -224.843086)
		(width 0.0889)
		(layer "In2.Cu")
		(net "P5E_CPU1_PE1_TX_DP<0>")
	)
	(segment
		(start 118.971568 -219.830396)
		(end 118.962678 -219.825316)
		(width 0.0889)
		(layer "In2.Cu")
		(net "P5E_CPU1_PE1_TX_DP<0>")
	)
	(segment
		(start 118.970552 -215.92667)
		(end 118.971568 -215.926162)
		(width 0.0889)
		(layer "In2.Cu")
		(net "P5E_CPU1_PE1_TX_DP<0>")
	)
	(segment
		(start 119.432324 -221.628462)
		(end 119.43969 -221.624144)
		(width 0.0889)
		(layer "In2.Cu")
		(net "P5E_CPU1_PE1_TX_DP<0>")
	)
	(segment
		(start 119.441214 -221.623382)
		(end 119.441976 -221.622874)
		(width 0.0889)
		(layer "In2.Cu")
		(net "P5E_CPU1_PE1_TX_DP<0>")
	)
	(segment
		(start 119.432324 -215.117426)
		(end 119.441214 -215.112346)
		(width 0.0889)
		(layer "In2.Cu")
		(net "P5E_CPU1_PE1_TX_DP<0>")
	)
	(segment
		(start 119.464328 -214.10803)
		(end 119.46382 -214.107776)
		(width 0.0889)
		(layer "In2.Cu")
		(net "P5E_CPU1_PE1_TX_DP<0>")
	)
	(segment
		(start 119.299482 -213.943438)
		(end 119.253762 -213.832948)
		(width 0.0889)
		(layer "In2.Cu")
		(net "P5E_CPU1_PE1_TX_DP<0>")
	)
	(segment
		(start 119.441976 -218.367356)
		(end 119.44731 -218.364308)
		(width 0.0889)
		(layer "In2.Cu")
		(net "P5E_CPU1_PE1_TX_DP<0>")
	)
	(segment
		(start 119.253762 -218.707716)
		(end 119.253762 -218.692222)
		(width 0.0889)
		(layer "In2.Cu")
		(net "P5E_CPU1_PE1_TX_DP<0>")
	)
	(segment
		(start 118.971568 -223.085914)
		(end 118.970552 -223.085406)
		(width 0.0889)
		(layer "In2.Cu")
		(net "P5E_CPU1_PE1_TX_DP<0>")
	)
	(segment
		(start 119.723408 -214.644732)
		(end 119.723408 -214.424768)
		(width 0.0889)
		(layer "In2.Cu")
		(net "P5E_CPU1_PE1_TX_DP<0>")
	)
	(segment
		(start 119.43969 -218.368626)
		(end 119.441214 -218.367864)
		(width 0.0889)
		(layer "In2.Cu")
		(net "P5E_CPU1_PE1_TX_DP<0>")
	)
	(segment
		(start 118.962678 -219.18676)
		(end 118.970552 -219.182188)
		(width 0.0889)
		(layer "In2.Cu")
		(net "P5E_CPU1_PE1_TX_DP<0>")
	)
	(segment
		(start 118.970552 -219.182188)
		(end 118.971568 -219.18168)
		(width 0.0889)
		(layer "In2.Cu")
		(net "P5E_CPU1_PE1_TX_DP<0>")
	)
	(segment
		(start 119.253762 -213.284562)
		(end 119.295926 -213.242398)
		(width 0.0889)
		(layer "In2.Cu")
		(net "P5E_CPU1_PE1_TX_DP<0>")
	)
	(segment
		(start 119.43969 -221.624144)
		(end 119.441214 -221.623382)
		(width 0.0889)
		(layer "In2.Cu")
		(net "P5E_CPU1_PE1_TX_DP<0>")
	)
	(segment
		(start 118.970552 -222.437706)
		(end 118.971568 -222.437198)
		(width 0.0889)
		(layer "In2.Cu")
		(net "P5E_CPU1_PE1_TX_DP<0>")
	)
	(segment
		(start 119.432324 -218.372944)
		(end 119.43969 -218.368626)
		(width 0.0889)
		(layer "In2.Cu")
		(net "P5E_CPU1_PE1_TX_DP<0>")
	)
	(segment
		(start 119.295926 -213.242398)
		(end 119.295926 -213.2203)
		(width 0.0889)
		(layer "In2.Cu")
		(net "P5E_CPU1_PE1_TX_DP<0>")
	)
	(segment
		(start 119.253762 -215.452198)
		(end 119.253762 -215.436704)
		(width 0.0889)
		(layer "In2.Cu")
		(net "P5E_CPU1_PE1_TX_DP<0>")
	)
	(segment
		(start 114.475006 -183.414924)
		(end 78.316328 -89.092278)
		(width 0.14732)
		(layer "In2.Cu")
		(net "P5E_CPU1_PE1_TX_DP<0>")
	)
	(segment
		(start 119.723916 -221.133924)
		(end 119.723916 -221.115382)
		(width 0.0889)
		(layer "In2.Cu")
		(net "P5E_CPU1_PE1_TX_DP<0>")
	)
	(segment
		(start 118.977664 -216.578434)
		(end 118.971568 -216.574878)
		(width 0.0889)
		(layer "In2.Cu")
		(net "P5E_CPU1_PE1_TX_DP<0>")
	)
	(segment
		(start 59.072526 -47.12208)
		(end 58.336688 -20.204176)
		(width 0.14732)
		(layer "In2.Cu")
		(net "P5E_CPU1_PE1_TX_DP<0>")
	)
	(segment
		(start 119.253762 -221.963234)
		(end 119.253762 -221.94774)
		(width 0.0889)
		(layer "In2.Cu")
		(net "P5E_CPU1_PE1_TX_DP<0>")
	)
	(segment
		(start 118.962678 -222.442278)
		(end 118.970552 -222.437706)
		(width 0.0889)
		(layer "In2.Cu")
		(net "P5E_CPU1_PE1_TX_DP<0>")
	)
	(segment
		(start 118.977664 -219.833952)
		(end 118.971568 -219.830396)
		(width 0.0889)
		(layer "In2.Cu")
		(net "P5E_CPU1_PE1_TX_DP<0>")
	)
	(segment
		(start 118.971568 -216.574878)
		(end 118.962678 -216.569798)
		(width 0.0889)
		(layer "In2.Cu")
		(net "P5E_CPU1_PE1_TX_DP<0>")
	)
	(segment
		(start 119.438166 -223.897952)
		(end 119.432578 -223.894904)
		(width 0.0889)
		(layer "In2.Cu")
		(net "P5E_CPU1_PE1_TX_DP<0>")
	)
	(segment
		(start 119.441214 -218.367864)
		(end 119.441976 -218.367356)
		(width 0.0889)
		(layer "In2.Cu")
		(net "P5E_CPU1_PE1_TX_DP<0>")
	)
	(segment
		(start 119.441976 -221.622874)
		(end 119.44731 -221.619826)
		(width 0.0889)
		(layer "In2.Cu")
		(net "P5E_CPU1_PE1_TX_DP<0>")
	)
	(segment
		(start 119.723916 -217.878406)
		(end 119.723916 -217.859864)
		(width 0.0889)
		(layer "In2.Cu")
		(net "P5E_CPU1_PE1_TX_DP<0>")
	)
	(segment
		(start 119.295926 -213.2203)
		(end 119.295926 -209.682588)
		(width 0.14732)
		(layer "In2.Cu")
		(net "P5E_CPU1_PE1_TX_DP<0>")
	)
	(segment
		(start 58.336688 -20.204176)
		(end 58.336688 -19.447002)
		(width 0.14732)
		(layer "In2.Cu")
		(net "P5E_CPU1_PE1_TX_DP<0>")
	)
	(segment
		(start 118.962678 -215.931242)
		(end 118.970552 -215.92667)
		(width 0.0889)
		(layer "In2.Cu")
		(net "P5E_CPU1_PE1_TX_DP<0>")
	)
	(segment
		(start 115.608862 -187.10656)
		(end 114.717322 -184.013856)
		(width 0.14732)
		(layer "In2.Cu")
		(net "P5E_CPU1_PE1_TX_DP<0>")
	)
	(segment
		(start 78.316328 -89.092278)
		(end 59.072526 -47.12208)
		(width 0.14732)
		(layer "In2.Cu")
		(net "P5E_CPU1_PE1_TX_DP<0>")
	)
	(segment
		(start 114.717322 -184.013856)
		(end 114.475006 -183.414924)
		(width 0.14732)
		(layer "In2.Cu")
		(net "P5E_CPU1_PE1_TX_DP<0>")
	)
	(segment
		(start 58.336688 -19.447002)
		(end 58.64733 -19.13636)
		(width 0.14732)
		(layer "In2.Cu")
		(net "P5E_CPU1_PE1_TX_DP<0>")
	)
	(segment
		(start 119.295926 -209.682588)
		(end 115.608862 -187.10656)
		(width 0.14732)
		(layer "In2.Cu")
		(net "P5E_CPU1_PE1_TX_DP<0>")
	)
	(segment
		(start 119.441468 -220.644212)
		(end 119.432578 -220.639132)
		(width 0.0889)
		(layer "In2.Cu")
		(net "P5E_CPU1_PE1_TX_DP<0>")
	)
	(segment
		(start 119.440706 -223.899476)
		(end 119.438166 -223.897952)
		(width 0.0889)
		(layer "In2.Cu")
		(net "P5E_CPU1_PE1_TX_DP<0>")
	)
	(segment
		(start 119.441468 -217.388694)
		(end 119.432578 -217.383614)
		(width 0.0889)
		(layer "In2.Cu")
		(net "P5E_CPU1_PE1_TX_DP<0>")
	)
	(segment
		(start 119.46382 -214.107776)
		(end 119.299482 -213.943438)
		(width 0.0889)
		(layer "In2.Cu")
		(net "P5E_CPU1_PE1_TX_DP<0>")
	)
	(segment
		(start 118.970552 -223.085406)
		(end 118.962678 -223.080834)
		(width 0.0889)
		(layer "In2.Cu")
		(net "P5E_CPU1_PE1_TX_DP<0>")
	)
	(segment
		(start 119.628412 -225.203258)
		(end 119.471948 -224.93224)
		(width 0.0889)
		(layer "In2.Cu")
		(net "P5E_CPU1_PE1_TX_DP<0>")
	)
	(segment
		(start 119.253762 -213.832948)
		(end 119.253762 -213.284562)
		(width 0.0889)
		(layer "In2.Cu")
		(net "P5E_CPU1_PE1_TX_DP<0>")
	)
	(arc
		(start 119.723408 -214.424768)
		(mid 119.621779 -214.243564)
		(end 119.464328 -214.10803)
		(width 0.0889)
		(layer "In2.Cu")
		(net "P5E_CPU1_PE1_TX_DP<0>")
	)
	(arc
		(start 119.253762 -215.436704)
		(mid 119.253814 -215.429337)
		(end 119.254016 -215.421972)
		(width 0.0889)
		(layer "In2.Cu")
		(net "P5E_CPU1_PE1_TX_DP<0>")
	)
	(arc
		(start 118.962678 -219.825316)
		(mid 118.784202 -219.506038)
		(end 118.962678 -219.18676)
		(width 0.0889)
		(layer "In2.Cu")
		(net "P5E_CPU1_PE1_TX_DP<0>")
	)
	(arc
		(start 118.971568 -219.18168)
		(mid 119.174391 -218.981449)
		(end 119.253762 -218.707716)
		(width 0.0889)
		(layer "In2.Cu")
		(net "P5E_CPU1_PE1_TX_DP<0>")
	)
	(arc
		(start 119.723916 -221.115382)
		(mid 119.643754 -220.843193)
		(end 119.441468 -220.644212)
		(width 0.0889)
		(layer "In2.Cu")
		(net "P5E_CPU1_PE1_TX_DP<0>")
	)
	(arc
		(start 119.254016 -215.421972)
		(mid 119.30507 -215.247392)
		(end 119.432324 -215.117426)
		(width 0.0889)
		(layer "In2.Cu")
		(net "P5E_CPU1_PE1_TX_DP<0>")
	)
	(arc
		(start 119.254016 -220.319854)
		(mid 119.1801 -220.040352)
		(end 118.977664 -219.833952)
		(width 0.0889)
		(layer "In2.Cu")
		(net "P5E_CPU1_PE1_TX_DP<0>")
	)
	(arc
		(start 118.971568 -215.926162)
		(mid 119.174391 -215.725931)
		(end 119.253762 -215.452198)
		(width 0.0889)
		(layer "In2.Cu")
		(net "P5E_CPU1_PE1_TX_DP<0>")
	)
	(arc
		(start 118.962678 -223.080834)
		(mid 118.835591 -222.950811)
		(end 118.784624 -222.776288)
		(width 0.0889)
		(layer "In2.Cu")
		(net "P5E_CPU1_PE1_TX_DP<0>")
	)
	(arc
		(start 119.513096 -224.829878)
		(mid 119.668494 -224.633597)
		(end 119.723916 -224.389442)
		(width 0.0889)
		(layer "In2.Cu")
		(net "P5E_CPU1_PE1_TX_DP<0>")
	)
	(arc
		(start 118.971568 -222.437198)
		(mid 119.174391 -222.236967)
		(end 119.253762 -221.963234)
		(width 0.0889)
		(layer "In2.Cu")
		(net "P5E_CPU1_PE1_TX_DP<0>")
	)
	(arc
		(start 119.432578 -223.894904)
		(mid 119.301664 -223.758544)
		(end 119.254016 -223.575626)
		(width 0.0889)
		(layer "In2.Cu")
		(net "P5E_CPU1_PE1_TX_DP<0>")
	)
	(arc
		(start 119.253762 -218.692222)
		(mid 119.301441 -218.509322)
		(end 119.432324 -218.372944)
		(width 0.0889)
		(layer "In2.Cu")
		(net "P5E_CPU1_PE1_TX_DP<0>")
	)
	(arc
		(start 119.496078 -224.843086)
		(mid 119.50465 -224.836564)
		(end 119.513096 -224.829878)
		(width 0.0889)
		(layer "In2.Cu")
		(net "P5E_CPU1_PE1_TX_DP<0>")
	)
	(arc
		(start 119.441214 -215.112346)
		(mid 119.642496 -214.914859)
		(end 119.723408 -214.644732)
		(width 0.0889)
		(layer "In2.Cu")
		(net "P5E_CPU1_PE1_TX_DP<0>")
	)
	(arc
		(start 119.254016 -217.064336)
		(mid 119.1801 -216.784834)
		(end 118.977664 -216.578434)
		(width 0.0889)
		(layer "In2.Cu")
		(net "P5E_CPU1_PE1_TX_DP<0>")
	)
	(arc
		(start 119.44731 -218.364308)
		(mid 119.649897 -218.157957)
		(end 119.723916 -217.878406)
		(width 0.0889)
		(layer "In2.Cu")
		(net "P5E_CPU1_PE1_TX_DP<0>")
	)
	(arc
		(start 119.432578 -217.383614)
		(mid 119.301664 -217.247254)
		(end 119.254016 -217.064336)
		(width 0.0889)
		(layer "In2.Cu")
		(net "P5E_CPU1_PE1_TX_DP<0>")
	)
	(arc
		(start 119.723916 -217.859864)
		(mid 119.643754 -217.587675)
		(end 119.441468 -217.388694)
		(width 0.0889)
		(layer "In2.Cu")
		(net "P5E_CPU1_PE1_TX_DP<0>")
	)
	(arc
		(start 119.723916 -224.379536)
		(mid 119.645805 -224.102587)
		(end 119.441468 -223.899984)
		(width 0.0889)
		(layer "In2.Cu")
		(net "P5E_CPU1_PE1_TX_DP<0>")
	)
	(arc
		(start 118.78437 -222.751396)
		(mid 118.834385 -222.574265)
		(end 118.962678 -222.442278)
		(width 0.0889)
		(layer "In2.Cu")
		(net "P5E_CPU1_PE1_TX_DP<0>")
	)
	(arc
		(start 119.44731 -221.619826)
		(mid 119.649897 -221.413475)
		(end 119.723916 -221.133924)
		(width 0.0889)
		(layer "In2.Cu")
		(net "P5E_CPU1_PE1_TX_DP<0>")
	)
	(arc
		(start 119.253762 -221.94774)
		(mid 119.301441 -221.76484)
		(end 119.432324 -221.628462)
		(width 0.0889)
		(layer "In2.Cu")
		(net "P5E_CPU1_PE1_TX_DP<0>")
	)
	(arc
		(start 118.784624 -222.776288)
		(mid 118.784291 -222.763844)
		(end 118.78437 -222.751396)
		(width 0.0889)
		(layer "In2.Cu")
		(net "P5E_CPU1_PE1_TX_DP<0>")
	)
	(arc
		(start 119.254016 -223.561402)
		(mid 119.174875 -223.286779)
		(end 118.971568 -223.085914)
		(width 0.0889)
		(layer "In2.Cu")
		(net "P5E_CPU1_PE1_TX_DP<0>")
	)
	(arc
		(start 118.962678 -216.569798)
		(mid 118.784202 -216.25052)
		(end 118.962678 -215.931242)
		(width 0.0889)
		(layer "In2.Cu")
		(net "P5E_CPU1_PE1_TX_DP<0>")
	)
	(arc
		(start 119.432578 -220.639132)
		(mid 119.301664 -220.502772)
		(end 119.254016 -220.319854)
		(width 0.0889)
		(layer "In2.Cu")
		(net "P5E_CPU1_PE1_TX_DP<0>")
	)
	(segment
		(start 111.170212 -224.111312)
		(end 111.170212 -223.575626)
		(width 0.13208)
		(layer "F.Cu")
		(net "P5E_CPU1_PE1_TX_DN<9>")
	)
	(segment
		(start 111.170466 -224.111566)
		(end 111.170212 -224.111312)
		(width 0.13208)
		(layer "F.Cu")
		(net "P5E_CPU1_PE1_TX_DN<9>")
	)
	(segment
		(start 32.857948 -17.30883)
		(end 32.857948 -16.695166)
		(width 0.13208)
		(layer "F.Cu")
		(net "P5E_CPU1_PE1_TX_DN<9>")
	)
	(segment
		(start 33.161478 -17.61236)
		(end 32.857948 -17.30883)
		(width 0.13208)
		(layer "F.Cu")
		(net "P5E_CPU1_PE1_TX_DN<9>")
	)
	(segment
		(start 32.857948 -16.695166)
		(end 33.186878 -16.366236)
		(width 0.13208)
		(layer "F.Cu")
		(net "P5E_CPU1_PE1_TX_DN<9>")
	)
	(segment
		(start 33.471612 -19.809968)
		(end 33.274254 -19.754342)
		(width 0.14732)
		(layer "In2.Cu")
		(net "P5E_CPU1_PE1_TX_DN<9>")
	)
	(segment
		(start 32.866838 -19.027394)
		(end 32.866838 -17.907)
		(width 0.14732)
		(layer "In2.Cu")
		(net "P5E_CPU1_PE1_TX_DN<9>")
	)
	(segment
		(start 110.535974 -214.921592)
		(end 110.325916 -214.711788)
		(width 0.0889)
		(layer "In2.Cu")
		(net "P5E_CPU1_PE1_TX_DN<9>")
	)
	(segment
		(start 110.513368 -218.202764)
		(end 110.504478 -218.197684)
		(width 0.0889)
		(layer "In2.Cu")
		(net "P5E_CPU1_PE1_TX_DN<9>")
	)
	(segment
		(start 110.795816 -223.584262)
		(end 110.795816 -223.557084)
		(width 0.0889)
		(layer "In2.Cu")
		(net "P5E_CPU1_PE1_TX_DN<9>")
	)
	(segment
		(start 110.517178 -218.20505)
		(end 110.513368 -218.202764)
		(width 0.0889)
		(layer "In2.Cu")
		(net "P5E_CPU1_PE1_TX_DN<9>")
	)
	(segment
		(start 110.504478 -215.931242)
		(end 110.513368 -215.926162)
		(width 0.0889)
		(layer "In2.Cu")
		(net "P5E_CPU1_PE1_TX_DN<9>")
	)
	(segment
		(start 33.274254 -19.754342)
		(end 32.866838 -19.027394)
		(width 0.14732)
		(layer "In2.Cu")
		(net "P5E_CPU1_PE1_TX_DN<9>")
	)
	(segment
		(start 111.013748 -223.846644)
		(end 110.93577 -223.867472)
		(width 0.0889)
		(layer "In2.Cu")
		(net "P5E_CPU1_PE1_TX_DN<9>")
	)
	(segment
		(start 110.36808 -213.533228)
		(end 110.36808 -213.51113)
		(width 0.0889)
		(layer "In2.Cu")
		(net "P5E_CPU1_PE1_TX_DN<9>")
	)
	(segment
		(start 110.517432 -219.179394)
		(end 110.52556 -219.174568)
		(width 0.0889)
		(layer "In2.Cu")
		(net "P5E_CPU1_PE1_TX_DN<9>")
	)
	(segment
		(start 111.265716 -221.14383)
		(end 111.265716 -221.1197)
		(width 0.0889)
		(layer "In2.Cu")
		(net "P5E_CPU1_PE1_TX_DN<9>")
	)
	(segment
		(start 110.513368 -223.085914)
		(end 110.504478 -223.080834)
		(width 0.0889)
		(layer "In2.Cu")
		(net "P5E_CPU1_PE1_TX_DN<9>")
	)
	(segment
		(start 53.646578 -56.102504)
		(end 34.097976 -21.223986)
		(width 0.14732)
		(layer "In2.Cu")
		(net "P5E_CPU1_PE1_TX_DN<9>")
	)
	(segment
		(start 110.513368 -219.18168)
		(end 110.51667 -219.179902)
		(width 0.0889)
		(layer "In2.Cu")
		(net "P5E_CPU1_PE1_TX_DN<9>")
	)
	(segment
		(start 110.36808 -213.51113)
		(end 110.36808 -212.08873)
		(width 0.14732)
		(layer "In2.Cu")
		(net "P5E_CPU1_PE1_TX_DN<9>")
	)
	(segment
		(start 111.170212 -223.575626)
		(end 111.013748 -223.846644)
		(width 0.0889)
		(layer "In2.Cu")
		(net "P5E_CPU1_PE1_TX_DN<9>")
	)
	(segment
		(start 34.097976 -21.223986)
		(end 34.153348 -21.026882)
		(width 0.14732)
		(layer "In2.Cu")
		(net "P5E_CPU1_PE1_TX_DN<9>")
	)
	(segment
		(start 110.504478 -219.18676)
		(end 110.513368 -219.18168)
		(width 0.0889)
		(layer "In2.Cu")
		(net "P5E_CPU1_PE1_TX_DN<9>")
	)
	(segment
		(start 110.974378 -221.628462)
		(end 110.983268 -221.623382)
		(width 0.0889)
		(layer "In2.Cu")
		(net "P5E_CPU1_PE1_TX_DN<9>")
	)
	(segment
		(start 32.866838 -17.907)
		(end 33.161478 -17.61236)
		(width 0.14732)
		(layer "In2.Cu")
		(net "P5E_CPU1_PE1_TX_DN<9>")
	)
	(segment
		(start 110.795816 -220.32849)
		(end 110.795816 -220.309948)
		(width 0.0889)
		(layer "In2.Cu")
		(net "P5E_CPU1_PE1_TX_DN<9>")
	)
	(segment
		(start 34.153348 -21.026882)
		(end 33.973262 -20.705318)
		(width 0.14732)
		(layer "In2.Cu")
		(net "P5E_CPU1_PE1_TX_DN<9>")
	)
	(segment
		(start 110.52556 -218.209876)
		(end 110.517178 -218.20505)
		(width 0.0889)
		(layer "In2.Cu")
		(net "P5E_CPU1_PE1_TX_DN<9>")
	)
	(segment
		(start 110.51667 -219.179902)
		(end 110.517432 -219.179394)
		(width 0.0889)
		(layer "In2.Cu")
		(net "P5E_CPU1_PE1_TX_DN<9>")
	)
	(segment
		(start 107.122976 -189.044834)
		(end 106.136186 -185.22696)
		(width 0.14732)
		(layer "In2.Cu")
		(net "P5E_CPU1_PE1_TX_DN<9>")
	)
	(segment
		(start 33.651698 -20.131532)
		(end 33.471612 -19.809968)
		(width 0.14732)
		(layer "In2.Cu")
		(net "P5E_CPU1_PE1_TX_DN<9>")
	)
	(segment
		(start 110.36808 -212.08873)
		(end 107.122976 -189.044834)
		(width 0.14732)
		(layer "In2.Cu")
		(net "P5E_CPU1_PE1_TX_DN<9>")
	)
	(segment
		(start 110.513368 -219.830396)
		(end 110.504478 -219.825316)
		(width 0.0889)
		(layer "In2.Cu")
		(net "P5E_CPU1_PE1_TX_DN<9>")
	)
	(segment
		(start 106.136186 -185.22696)
		(end 71.8947 -95.901764)
		(width 0.14732)
		(layer "In2.Cu")
		(net "P5E_CPU1_PE1_TX_DN<9>")
	)
	(segment
		(start 110.325916 -213.575392)
		(end 110.36808 -213.533228)
		(width 0.0889)
		(layer "In2.Cu")
		(net "P5E_CPU1_PE1_TX_DN<9>")
	)
	(segment
		(start 110.512606 -216.57437)
		(end 110.504478 -216.569798)
		(width 0.0889)
		(layer "In2.Cu")
		(net "P5E_CPU1_PE1_TX_DN<9>")
	)
	(segment
		(start 110.795562 -215.452198)
		(end 110.795562 -215.23833)
		(width 0.0889)
		(layer "In2.Cu")
		(net "P5E_CPU1_PE1_TX_DN<9>")
	)
	(segment
		(start 110.504478 -222.442278)
		(end 110.513368 -222.437198)
		(width 0.0889)
		(layer "In2.Cu")
		(net "P5E_CPU1_PE1_TX_DN<9>")
	)
	(segment
		(start 33.596072 -20.328636)
		(end 33.651698 -20.131532)
		(width 0.14732)
		(layer "In2.Cu")
		(net "P5E_CPU1_PE1_TX_DN<9>")
	)
	(segment
		(start 110.513368 -216.574878)
		(end 110.512606 -216.57437)
		(width 0.0889)
		(layer "In2.Cu")
		(net "P5E_CPU1_PE1_TX_DN<9>")
	)
	(segment
		(start 110.504478 -217.559128)
		(end 110.513368 -217.554048)
		(width 0.0889)
		(layer "In2.Cu")
		(net "P5E_CPU1_PE1_TX_DN<9>")
	)
	(segment
		(start 110.325916 -214.711788)
		(end 110.325916 -213.575392)
		(width 0.0889)
		(layer "In2.Cu")
		(net "P5E_CPU1_PE1_TX_DN<9>")
	)
	(segment
		(start 33.775904 -20.649692)
		(end 33.596072 -20.328636)
		(width 0.14732)
		(layer "In2.Cu")
		(net "P5E_CPU1_PE1_TX_DN<9>")
	)
	(segment
		(start 110.795816 -221.957646)
		(end 110.795816 -221.94774)
		(width 0.0889)
		(layer "In2.Cu")
		(net "P5E_CPU1_PE1_TX_DN<9>")
	)
	(segment
		(start 33.973262 -20.705318)
		(end 33.775904 -20.649692)
		(width 0.14732)
		(layer "In2.Cu")
		(net "P5E_CPU1_PE1_TX_DN<9>")
	)
	(segment
		(start 71.8947 -95.901764)
		(end 53.646578 -56.102504)
		(width 0.14732)
		(layer "In2.Cu")
		(net "P5E_CPU1_PE1_TX_DN<9>")
	)
	(segment
		(start 110.795816 -217.082878)
		(end 110.795816 -217.05443)
		(width 0.0889)
		(layer "In2.Cu")
		(net "P5E_CPU1_PE1_TX_DN<9>")
	)
	(arc
		(start 110.79607 -218.691968)
		(mid 110.723773 -218.415587)
		(end 110.52556 -218.209876)
		(width 0.0889)
		(layer "In2.Cu")
		(net "P5E_CPU1_PE1_TX_DN<9>")
	)
	(arc
		(start 110.504478 -223.080834)
		(mid 110.376667 -222.949741)
		(end 110.32617 -222.773748)
		(width 0.0889)
		(layer "In2.Cu")
		(net "P5E_CPU1_PE1_TX_DN<9>")
	)
	(arc
		(start 110.513368 -222.437198)
		(mid 110.717703 -222.234593)
		(end 110.795816 -221.957646)
		(width 0.0889)
		(layer "In2.Cu")
		(net "P5E_CPU1_PE1_TX_DN<9>")
	)
	(arc
		(start 110.983268 -221.623382)
		(mid 111.187603 -221.420777)
		(end 111.265716 -221.14383)
		(width 0.0889)
		(layer "In2.Cu")
		(net "P5E_CPU1_PE1_TX_DN<9>")
	)
	(arc
		(start 110.504478 -216.569798)
		(mid 110.375274 -216.436284)
		(end 110.32617 -216.257124)
		(width 0.0889)
		(layer "In2.Cu")
		(net "P5E_CPU1_PE1_TX_DN<9>")
	)
	(arc
		(start 110.93577 -223.867472)
		(mid 110.834449 -223.741351)
		(end 110.795816 -223.584262)
		(width 0.0889)
		(layer "In2.Cu")
		(net "P5E_CPU1_PE1_TX_DN<9>")
	)
	(arc
		(start 110.795816 -221.94774)
		(mid 110.843495 -221.76484)
		(end 110.974378 -221.628462)
		(width 0.0889)
		(layer "In2.Cu")
		(net "P5E_CPU1_PE1_TX_DN<9>")
	)
	(arc
		(start 110.795816 -223.557084)
		(mid 110.715654 -223.284895)
		(end 110.513368 -223.085914)
		(width 0.0889)
		(layer "In2.Cu")
		(net "P5E_CPU1_PE1_TX_DN<9>")
	)
	(arc
		(start 110.32617 -217.866214)
		(mid 110.376663 -217.690236)
		(end 110.504478 -217.559128)
		(width 0.0889)
		(layer "In2.Cu")
		(net "P5E_CPU1_PE1_TX_DN<9>")
	)
	(arc
		(start 110.504478 -218.197684)
		(mid 110.375189 -218.064198)
		(end 110.325916 -217.88501)
		(width 0.0889)
		(layer "In2.Cu")
		(net "P5E_CPU1_PE1_TX_DN<9>")
	)
	(arc
		(start 110.32617 -216.257124)
		(mid 110.326076 -216.248742)
		(end 110.32617 -216.24036)
		(width 0.0889)
		(layer "In2.Cu")
		(net "P5E_CPU1_PE1_TX_DN<9>")
	)
	(arc
		(start 110.795562 -215.23833)
		(mid 110.693691 -215.057073)
		(end 110.535974 -214.921592)
		(width 0.0889)
		(layer "In2.Cu")
		(net "P5E_CPU1_PE1_TX_DN<9>")
	)
	(arc
		(start 110.32617 -222.773748)
		(mid 110.325925 -222.764352)
		(end 110.325916 -222.754952)
		(width 0.0889)
		(layer "In2.Cu")
		(net "P5E_CPU1_PE1_TX_DN<9>")
	)
	(arc
		(start 110.325916 -217.88501)
		(mid 110.325926 -217.87561)
		(end 110.32617 -217.866214)
		(width 0.0889)
		(layer "In2.Cu")
		(net "P5E_CPU1_PE1_TX_DN<9>")
	)
	(arc
		(start 110.513368 -215.926162)
		(mid 110.716191 -215.725931)
		(end 110.795562 -215.452198)
		(width 0.0889)
		(layer "In2.Cu")
		(net "P5E_CPU1_PE1_TX_DN<9>")
	)
	(arc
		(start 110.52556 -219.174568)
		(mid 110.72385 -218.968609)
		(end 110.79607 -218.691968)
		(width 0.0889)
		(layer "In2.Cu")
		(net "P5E_CPU1_PE1_TX_DN<9>")
	)
	(arc
		(start 110.983014 -220.644212)
		(mid 110.848081 -220.510858)
		(end 110.795816 -220.32849)
		(width 0.0889)
		(layer "In2.Cu")
		(net "P5E_CPU1_PE1_TX_DN<9>")
	)
	(arc
		(start 110.325916 -222.754952)
		(mid 110.375169 -222.575752)
		(end 110.504478 -222.442278)
		(width 0.0889)
		(layer "In2.Cu")
		(net "P5E_CPU1_PE1_TX_DN<9>")
	)
	(arc
		(start 110.795816 -217.05443)
		(mid 110.717705 -216.777481)
		(end 110.513368 -216.574878)
		(width 0.0889)
		(layer "In2.Cu")
		(net "P5E_CPU1_PE1_TX_DN<9>")
	)
	(arc
		(start 110.504478 -219.825316)
		(mid 110.325881 -219.506038)
		(end 110.504478 -219.18676)
		(width 0.0889)
		(layer "In2.Cu")
		(net "P5E_CPU1_PE1_TX_DN<9>")
	)
	(arc
		(start 110.795816 -220.309948)
		(mid 110.717705 -220.032999)
		(end 110.513368 -219.830396)
		(width 0.0889)
		(layer "In2.Cu")
		(net "P5E_CPU1_PE1_TX_DN<9>")
	)
	(arc
		(start 110.32617 -216.24036)
		(mid 110.376185 -216.063229)
		(end 110.504478 -215.931242)
		(width 0.0889)
		(layer "In2.Cu")
		(net "P5E_CPU1_PE1_TX_DN<9>")
	)
	(arc
		(start 111.265716 -221.1197)
		(mid 111.186497 -220.845015)
		(end 110.983014 -220.644212)
		(width 0.0889)
		(layer "In2.Cu")
		(net "P5E_CPU1_PE1_TX_DN<9>")
	)
	(arc
		(start 110.513368 -217.554048)
		(mid 110.715654 -217.355067)
		(end 110.795816 -217.082878)
		(width 0.0889)
		(layer "In2.Cu")
		(net "P5E_CPU1_PE1_TX_DN<9>")
	)
	(segment
		(start 111.640112 -224.925382)
		(end 111.640366 -224.925128)
		(width 0.13208)
		(layer "F.Cu")
		(net "P5E_CPU1_PE1_TX_DN<8>")
	)
	(segment
		(start 35.091878 -19.13636)
		(end 35.392868 -18.83537)
		(width 0.13208)
		(layer "F.Cu")
		(net "P5E_CPU1_PE1_TX_DN<8>")
	)
	(segment
		(start 35.392868 -18.216626)
		(end 35.066478 -17.890236)
		(width 0.13208)
		(layer "F.Cu")
		(net "P5E_CPU1_PE1_TX_DN<8>")
	)
	(segment
		(start 35.392868 -18.83537)
		(end 35.392868 -18.216626)
		(width 0.13208)
		(layer "F.Cu")
		(net "P5E_CPU1_PE1_TX_DN<8>")
	)
	(segment
		(start 111.640366 -224.925128)
		(end 111.640366 -224.389442)
		(width 0.13208)
		(layer "F.Cu")
		(net "P5E_CPU1_PE1_TX_DN<8>")
	)
	(segment
		(start 111.836454 -220.814646)
		(end 111.832136 -220.812106)
		(width 0.0889)
		(layer "In2.Cu")
		(net "P5E_CPU1_PE1_TX_DN<8>")
	)
	(segment
		(start 111.836454 -224.070164)
		(end 111.815372 -224.058226)
		(width 0.0889)
		(layer "In2.Cu")
		(net "P5E_CPU1_PE1_TX_DN<8>")
	)
	(segment
		(start 53.692806 -54.531006)
		(end 36.438078 -21.972778)
		(width 0.14732)
		(layer "In2.Cu")
		(net "P5E_CPU1_PE1_TX_DN<8>")
	)
	(segment
		(start 111.54537 -220.319854)
		(end 111.544862 -220.319854)
		(width 0.0889)
		(layer "In2.Cu")
		(net "P5E_CPU1_PE1_TX_DN<8>")
	)
	(segment
		(start 111.545116 -218.691968)
		(end 111.54537 -218.67241)
		(width 0.0889)
		(layer "In2.Cu")
		(net "P5E_CPU1_PE1_TX_DN<8>")
	)
	(segment
		(start 111.03356 -213.533228)
		(end 111.03356 -213.51113)
		(width 0.0889)
		(layer "In2.Cu")
		(net "P5E_CPU1_PE1_TX_DN<8>")
	)
	(segment
		(start 72.318626 -95.15475)
		(end 53.692806 -54.531006)
		(width 0.14732)
		(layer "In2.Cu")
		(net "P5E_CPU1_PE1_TX_DN<8>")
	)
	(segment
		(start 111.826548 -220.808296)
		(end 111.825786 -220.807788)
		(width 0.0889)
		(layer "In2.Cu")
		(net "P5E_CPU1_PE1_TX_DN<8>")
	)
	(segment
		(start 111.815372 -224.058226)
		(end 111.815372 -224.057972)
		(width 0.0889)
		(layer "In2.Cu")
		(net "P5E_CPU1_PE1_TX_DN<8>")
	)
	(segment
		(start 36.242244 -21.91258)
		(end 36.069778 -21.586952)
		(width 0.14732)
		(layer "In2.Cu")
		(net "P5E_CPU1_PE1_TX_DN<8>")
	)
	(segment
		(start 111.075216 -222.783654)
		(end 111.075216 -222.75165)
		(width 0.0889)
		(layer "In2.Cu")
		(net "P5E_CPU1_PE1_TX_DN<8>")
	)
	(segment
		(start 111.544862 -215.436704)
		(end 111.544862 -215.275414)
		(width 0.0889)
		(layer "In2.Cu")
		(net "P5E_CPU1_PE1_TX_DN<8>")
	)
	(segment
		(start 111.82731 -217.553794)
		(end 111.825786 -217.553032)
		(width 0.0889)
		(layer "In2.Cu")
		(net "P5E_CPU1_PE1_TX_DN<8>")
	)
	(segment
		(start 111.8362 -217.559128)
		(end 111.82731 -217.554048)
		(width 0.0889)
		(layer "In2.Cu")
		(net "P5E_CPU1_PE1_TX_DN<8>")
	)
	(segment
		(start 111.35741 -215.761062)
		(end 111.3663 -215.755982)
		(width 0.0889)
		(layer "In2.Cu")
		(net "P5E_CPU1_PE1_TX_DN<8>")
	)
	(segment
		(start 36.129722 -21.391372)
		(end 35.95751 -21.065998)
		(width 0.14732)
		(layer "In2.Cu")
		(net "P5E_CPU1_PE1_TX_DN<8>")
	)
	(segment
		(start 111.358426 -219.996004)
		(end 111.35741 -219.995496)
		(width 0.0889)
		(layer "In2.Cu")
		(net "P5E_CPU1_PE1_TX_DN<8>")
	)
	(segment
		(start 35.95751 -21.065998)
		(end 35.761676 -21.006054)
		(width 0.14732)
		(layer "In2.Cu")
		(net "P5E_CPU1_PE1_TX_DN<8>")
	)
	(segment
		(start 111.640366 -224.389442)
		(end 111.79683 -224.66046)
		(width 0.0889)
		(layer "In2.Cu")
		(net "P5E_CPU1_PE1_TX_DN<8>")
	)
	(segment
		(start 35.386518 -19.98853)
		(end 35.386518 -19.431)
		(width 0.14732)
		(layer "In2.Cu")
		(net "P5E_CPU1_PE1_TX_DN<8>")
	)
	(segment
		(start 106.80319 -185.116978)
		(end 72.318626 -95.15475)
		(width 0.14732)
		(layer "In2.Cu")
		(net "P5E_CPU1_PE1_TX_DN<8>")
	)
	(segment
		(start 36.438078 -21.972778)
		(end 36.242244 -21.91258)
		(width 0.14732)
		(layer "In2.Cu")
		(net "P5E_CPU1_PE1_TX_DN<8>")
	)
	(segment
		(start 111.075216 -219.521532)
		(end 111.075216 -219.491814)
		(width 0.0889)
		(layer "In2.Cu")
		(net "P5E_CPU1_PE1_TX_DN<8>")
	)
	(segment
		(start 111.825786 -220.807788)
		(end 111.81842 -220.803724)
		(width 0.0889)
		(layer "In2.Cu")
		(net "P5E_CPU1_PE1_TX_DN<8>")
	)
	(segment
		(start 111.3663 -220.000576)
		(end 111.358426 -219.996004)
		(width 0.0889)
		(layer "In2.Cu")
		(net "P5E_CPU1_PE1_TX_DN<8>")
	)
	(segment
		(start 111.82731 -217.554048)
		(end 111.82731 -217.553794)
		(width 0.0889)
		(layer "In2.Cu")
		(net "P5E_CPU1_PE1_TX_DN<8>")
	)
	(segment
		(start 111.821468 -221.461838)
		(end 111.836454 -221.453202)
		(width 0.0889)
		(layer "In2.Cu")
		(net "P5E_CPU1_PE1_TX_DN<8>")
	)
	(segment
		(start 111.075216 -216.260426)
		(end 111.075216 -216.235026)
		(width 0.0889)
		(layer "In2.Cu")
		(net "P5E_CPU1_PE1_TX_DN<8>")
	)
	(segment
		(start 111.03356 -213.51113)
		(end 111.03356 -212.189568)
		(width 0.14732)
		(layer "In2.Cu")
		(net "P5E_CPU1_PE1_TX_DN<8>")
	)
	(segment
		(start 111.545116 -217.062558)
		(end 111.54537 -217.054684)
		(width 0.0889)
		(layer "In2.Cu")
		(net "P5E_CPU1_PE1_TX_DN<8>")
	)
	(segment
		(start 111.07547 -213.575138)
		(end 111.03356 -213.533228)
		(width 0.0889)
		(layer "In2.Cu")
		(net "P5E_CPU1_PE1_TX_DN<8>")
	)
	(segment
		(start 111.811054 -217.544904)
		(end 111.8108 -217.544396)
		(width 0.0889)
		(layer "In2.Cu")
		(net "P5E_CPU1_PE1_TX_DN<8>")
	)
	(segment
		(start 111.000794 -211.699348)
		(end 107.931712 -189.505844)
		(width 0.14732)
		(layer "In2.Cu")
		(net "P5E_CPU1_PE1_TX_DN<8>")
	)
	(segment
		(start 35.58921 -20.680172)
		(end 35.649408 -20.484592)
		(width 0.14732)
		(layer "In2.Cu")
		(net "P5E_CPU1_PE1_TX_DN<8>")
	)
	(segment
		(start 111.07547 -214.603076)
		(end 111.07547 -213.575138)
		(width 0.0889)
		(layer "In2.Cu")
		(net "P5E_CPU1_PE1_TX_DN<8>")
	)
	(segment
		(start 111.832136 -220.812106)
		(end 111.827564 -220.809566)
		(width 0.0889)
		(layer "In2.Cu")
		(net "P5E_CPU1_PE1_TX_DN<8>")
	)
	(segment
		(start 111.827564 -220.809566)
		(end 111.826548 -220.808296)
		(width 0.0889)
		(layer "In2.Cu")
		(net "P5E_CPU1_PE1_TX_DN<8>")
	)
	(segment
		(start 35.761676 -21.006054)
		(end 35.58921 -20.680172)
		(width 0.14732)
		(layer "In2.Cu")
		(net "P5E_CPU1_PE1_TX_DN<8>")
	)
	(segment
		(start 107.931712 -189.505844)
		(end 106.80319 -185.116978)
		(width 0.14732)
		(layer "In2.Cu")
		(net "P5E_CPU1_PE1_TX_DN<8>")
	)
	(segment
		(start 111.82731 -218.202764)
		(end 111.8362 -218.197684)
		(width 0.0889)
		(layer "In2.Cu")
		(net "P5E_CPU1_PE1_TX_DN<8>")
	)
	(segment
		(start 111.79683 -224.66046)
		(end 111.875062 -224.681288)
		(width 0.0889)
		(layer "In2.Cu")
		(net "P5E_CPU1_PE1_TX_DN<8>")
	)
	(segment
		(start 111.825786 -217.553032)
		(end 111.811054 -217.544904)
		(width 0.0889)
		(layer "In2.Cu")
		(net "P5E_CPU1_PE1_TX_DN<8>")
	)
	(segment
		(start 111.544862 -221.956376)
		(end 111.544862 -221.94774)
		(width 0.0889)
		(layer "In2.Cu")
		(net "P5E_CPU1_PE1_TX_DN<8>")
	)
	(segment
		(start 35.649408 -20.484592)
		(end 35.386518 -19.98853)
		(width 0.14732)
		(layer "In2.Cu")
		(net "P5E_CPU1_PE1_TX_DN<8>")
	)
	(segment
		(start 111.03356 -212.189568)
		(end 111.000794 -211.699348)
		(width 0.14732)
		(layer "In2.Cu")
		(net "P5E_CPU1_PE1_TX_DN<8>")
	)
	(segment
		(start 111.3663 -223.256348)
		(end 111.35741 -223.251268)
		(width 0.0889)
		(layer "In2.Cu")
		(net "P5E_CPU1_PE1_TX_DN<8>")
	)
	(segment
		(start 111.545116 -218.700604)
		(end 111.545116 -218.691968)
		(width 0.0889)
		(layer "In2.Cu")
		(net "P5E_CPU1_PE1_TX_DN<8>")
	)
	(segment
		(start 35.386518 -19.431)
		(end 35.091878 -19.13636)
		(width 0.14732)
		(layer "In2.Cu")
		(net "P5E_CPU1_PE1_TX_DN<8>")
	)
	(segment
		(start 111.358172 -216.740232)
		(end 111.357664 -216.739978)
		(width 0.0889)
		(layer "In2.Cu")
		(net "P5E_CPU1_PE1_TX_DN<8>")
	)
	(segment
		(start 36.069778 -21.586952)
		(end 36.129722 -21.391372)
		(width 0.14732)
		(layer "In2.Cu")
		(net "P5E_CPU1_PE1_TX_DN<8>")
	)
	(arc
		(start 111.54537 -218.67241)
		(mid 111.625608 -218.401114)
		(end 111.82731 -218.202764)
		(width 0.0889)
		(layer "In2.Cu")
		(net "P5E_CPU1_PE1_TX_DN<8>")
	)
	(arc
		(start 111.075216 -219.491814)
		(mid 111.154435 -219.217129)
		(end 111.357918 -219.016326)
		(width 0.0889)
		(layer "In2.Cu")
		(net "P5E_CPU1_PE1_TX_DN<8>")
	)
	(arc
		(start 111.836454 -221.453202)
		(mid 112.015051 -221.133924)
		(end 111.836454 -220.814646)
		(width 0.0889)
		(layer "In2.Cu")
		(net "P5E_CPU1_PE1_TX_DN<8>")
	)
	(arc
		(start 111.35741 -223.251268)
		(mid 111.156128 -223.053781)
		(end 111.075216 -222.783654)
		(width 0.0889)
		(layer "In2.Cu")
		(net "P5E_CPU1_PE1_TX_DN<8>")
	)
	(arc
		(start 111.8362 -218.197684)
		(mid 112.014797 -217.878406)
		(end 111.8362 -217.559128)
		(width 0.0889)
		(layer "In2.Cu")
		(net "P5E_CPU1_PE1_TX_DN<8>")
	)
	(arc
		(start 111.544862 -220.319854)
		(mid 111.497183 -220.136954)
		(end 111.3663 -220.000576)
		(width 0.0889)
		(layer "In2.Cu")
		(net "P5E_CPU1_PE1_TX_DN<8>")
	)
	(arc
		(start 111.075216 -216.235026)
		(mid 111.154586 -215.961292)
		(end 111.35741 -215.761062)
		(width 0.0889)
		(layer "In2.Cu")
		(net "P5E_CPU1_PE1_TX_DN<8>")
	)
	(arc
		(start 111.3663 -215.755982)
		(mid 111.497214 -215.619622)
		(end 111.544862 -215.436704)
		(width 0.0889)
		(layer "In2.Cu")
		(net "P5E_CPU1_PE1_TX_DN<8>")
	)
	(arc
		(start 111.544862 -221.94774)
		(mid 111.618853 -221.668174)
		(end 111.821468 -221.461838)
		(width 0.0889)
		(layer "In2.Cu")
		(net "P5E_CPU1_PE1_TX_DN<8>")
	)
	(arc
		(start 111.815372 -224.057972)
		(mid 111.617144 -223.852124)
		(end 111.544862 -223.575626)
		(width 0.0889)
		(layer "In2.Cu")
		(net "P5E_CPU1_PE1_TX_DN<8>")
	)
	(arc
		(start 111.544862 -223.575626)
		(mid 111.497183 -223.392726)
		(end 111.3663 -223.256348)
		(width 0.0889)
		(layer "In2.Cu")
		(net "P5E_CPU1_PE1_TX_DN<8>")
	)
	(arc
		(start 111.544862 -215.275414)
		(mid 111.469857 -215.159955)
		(end 111.360712 -215.076024)
		(width 0.0889)
		(layer "In2.Cu")
		(net "P5E_CPU1_PE1_TX_DN<8>")
	)
	(arc
		(start 112.015016 -224.389442)
		(mid 111.967337 -224.206542)
		(end 111.836454 -224.070164)
		(width 0.0889)
		(layer "In2.Cu")
		(net "P5E_CPU1_PE1_TX_DN<8>")
	)
	(arc
		(start 111.357664 -222.272098)
		(mid 111.492597 -222.138744)
		(end 111.544862 -221.956376)
		(width 0.0889)
		(layer "In2.Cu")
		(net "P5E_CPU1_PE1_TX_DN<8>")
	)
	(arc
		(start 111.35741 -219.995496)
		(mid 111.154587 -219.795265)
		(end 111.075216 -219.521532)
		(width 0.0889)
		(layer "In2.Cu")
		(net "P5E_CPU1_PE1_TX_DN<8>")
	)
	(arc
		(start 111.357664 -216.739978)
		(mid 111.153329 -216.537373)
		(end 111.075216 -216.260426)
		(width 0.0889)
		(layer "In2.Cu")
		(net "P5E_CPU1_PE1_TX_DN<8>")
	)
	(arc
		(start 111.8108 -217.544396)
		(mid 111.615358 -217.337994)
		(end 111.545116 -217.062558)
		(width 0.0889)
		(layer "In2.Cu")
		(net "P5E_CPU1_PE1_TX_DN<8>")
	)
	(arc
		(start 111.81842 -220.803724)
		(mid 111.618307 -220.597664)
		(end 111.54537 -220.319854)
		(width 0.0889)
		(layer "In2.Cu")
		(net "P5E_CPU1_PE1_TX_DN<8>")
	)
	(arc
		(start 111.357918 -219.016326)
		(mid 111.492851 -218.882972)
		(end 111.545116 -218.700604)
		(width 0.0889)
		(layer "In2.Cu")
		(net "P5E_CPU1_PE1_TX_DN<8>")
	)
	(arc
		(start 111.360712 -215.076024)
		(mid 111.152284 -214.879221)
		(end 111.07547 -214.603076)
		(width 0.0889)
		(layer "In2.Cu")
		(net "P5E_CPU1_PE1_TX_DN<8>")
	)
	(arc
		(start 111.075216 -222.75165)
		(mid 111.153327 -222.474701)
		(end 111.357664 -222.272098)
		(width 0.0889)
		(layer "In2.Cu")
		(net "P5E_CPU1_PE1_TX_DN<8>")
	)
	(arc
		(start 111.54537 -217.054684)
		(mid 111.492756 -216.873049)
		(end 111.358172 -216.740232)
		(width 0.0889)
		(layer "In2.Cu")
		(net "P5E_CPU1_PE1_TX_DN<8>")
	)
	(arc
		(start 111.875062 -224.681288)
		(mid 111.978207 -224.551263)
		(end 112.015016 -224.389442)
		(width 0.0889)
		(layer "In2.Cu")
		(net "P5E_CPU1_PE1_TX_DN<8>")
	)
	(segment
		(start 113.049812 -224.111312)
		(end 113.049812 -223.575626)
		(width 0.13208)
		(layer "F.Cu")
		(net "P5E_CPU1_PE1_TX_DN<7>")
	)
	(segment
		(start 38.445948 -16.695166)
		(end 38.774878 -16.366236)
		(width 0.13208)
		(layer "F.Cu")
		(net "P5E_CPU1_PE1_TX_DN<7>")
	)
	(segment
		(start 38.749478 -17.61236)
		(end 38.445948 -17.30883)
		(width 0.13208)
		(layer "F.Cu")
		(net "P5E_CPU1_PE1_TX_DN<7>")
	)
	(segment
		(start 38.445948 -17.30883)
		(end 38.445948 -16.695166)
		(width 0.13208)
		(layer "F.Cu")
		(net "P5E_CPU1_PE1_TX_DN<7>")
	)
	(segment
		(start 113.050066 -224.111566)
		(end 113.049812 -224.111312)
		(width 0.13208)
		(layer "F.Cu")
		(net "P5E_CPU1_PE1_TX_DN<7>")
	)
	(segment
		(start 112.675416 -220.32849)
		(end 112.675416 -220.309948)
		(width 0.0889)
		(layer "In2.Cu")
		(net "P5E_CPU1_PE1_TX_DN<7>")
	)
	(segment
		(start 112.675162 -221.963234)
		(end 112.675162 -221.94774)
		(width 0.0889)
		(layer "In2.Cu")
		(net "P5E_CPU1_PE1_TX_DN<7>")
	)
	(segment
		(start 112.247172 -213.51113)
		(end 112.247172 -211.815172)
		(width 0.14732)
		(layer "In2.Cu")
		(net "P5E_CPU1_PE1_TX_DN<7>")
	)
	(segment
		(start 112.384078 -219.18676)
		(end 112.391952 -219.182188)
		(width 0.0889)
		(layer "In2.Cu")
		(net "P5E_CPU1_PE1_TX_DN<7>")
	)
	(segment
		(start 39.776654 -20.880832)
		(end 39.623238 -20.545806)
		(width 0.14732)
		(layer "In2.Cu")
		(net "P5E_CPU1_PE1_TX_DN<7>")
	)
	(segment
		(start 112.247172 -213.533228)
		(end 112.247172 -213.51113)
		(width 0.0889)
		(layer "In2.Cu")
		(net "P5E_CPU1_PE1_TX_DN<7>")
	)
	(segment
		(start 39.277544 -20.139914)
		(end 39.348918 -19.948144)
		(width 0.14732)
		(layer "In2.Cu")
		(net "P5E_CPU1_PE1_TX_DN<7>")
	)
	(segment
		(start 108.070396 -185.047636)
		(end 73.28789 -94.314518)
		(width 0.14732)
		(layer "In2.Cu")
		(net "P5E_CPU1_PE1_TX_DN<7>")
	)
	(segment
		(start 112.392968 -223.085914)
		(end 112.384078 -223.080834)
		(width 0.0889)
		(layer "In2.Cu")
		(net "P5E_CPU1_PE1_TX_DN<7>")
	)
	(segment
		(start 112.384078 -222.442278)
		(end 112.392968 -222.437198)
		(width 0.0889)
		(layer "In2.Cu")
		(net "P5E_CPU1_PE1_TX_DN<7>")
	)
	(segment
		(start 112.205008 -214.72271)
		(end 112.205008 -213.575392)
		(width 0.0889)
		(layer "In2.Cu")
		(net "P5E_CPU1_PE1_TX_DN<7>")
	)
	(segment
		(start 39.43096 -20.474686)
		(end 39.277544 -20.139914)
		(width 0.14732)
		(layer "In2.Cu")
		(net "P5E_CPU1_PE1_TX_DN<7>")
	)
	(segment
		(start 73.28789 -94.314518)
		(end 39.70528 -21.072856)
		(width 0.14732)
		(layer "In2.Cu")
		(net "P5E_CPU1_PE1_TX_DN<7>")
	)
	(segment
		(start 112.862614 -218.367864)
		(end 112.86871 -218.364308)
		(width 0.0889)
		(layer "In2.Cu")
		(net "P5E_CPU1_PE1_TX_DN<7>")
	)
	(segment
		(start 113.145316 -217.878406)
		(end 113.145316 -217.864182)
		(width 0.0889)
		(layer "In2.Cu")
		(net "P5E_CPU1_PE1_TX_DN<7>")
	)
	(segment
		(start 39.195502 -19.613118)
		(end 39.003478 -19.541744)
		(width 0.14732)
		(layer "In2.Cu")
		(net "P5E_CPU1_PE1_TX_DN<7>")
	)
	(segment
		(start 112.862614 -221.623382)
		(end 112.86871 -221.619826)
		(width 0.0889)
		(layer "In2.Cu")
		(net "P5E_CPU1_PE1_TX_DN<7>")
	)
	(segment
		(start 112.675162 -218.707716)
		(end 112.675162 -218.692222)
		(width 0.0889)
		(layer "In2.Cu")
		(net "P5E_CPU1_PE1_TX_DN<7>")
	)
	(segment
		(start 112.391952 -219.182188)
		(end 112.392968 -219.18168)
		(width 0.0889)
		(layer "In2.Cu")
		(net "P5E_CPU1_PE1_TX_DN<7>")
	)
	(segment
		(start 112.853724 -221.628462)
		(end 112.862614 -221.623382)
		(width 0.0889)
		(layer "In2.Cu")
		(net "P5E_CPU1_PE1_TX_DN<7>")
	)
	(segment
		(start 112.389412 -214.907114)
		(end 112.205008 -214.72271)
		(width 0.0889)
		(layer "In2.Cu")
		(net "P5E_CPU1_PE1_TX_DN<7>")
	)
	(segment
		(start 39.623238 -20.545806)
		(end 39.43096 -20.474686)
		(width 0.14732)
		(layer "In2.Cu")
		(net "P5E_CPU1_PE1_TX_DN<7>")
	)
	(segment
		(start 39.003478 -19.541744)
		(end 38.454838 -18.345404)
		(width 0.14732)
		(layer "In2.Cu")
		(net "P5E_CPU1_PE1_TX_DN<7>")
	)
	(segment
		(start 113.049812 -223.575626)
		(end 112.893348 -223.846644)
		(width 0.0889)
		(layer "In2.Cu")
		(net "P5E_CPU1_PE1_TX_DN<7>")
	)
	(segment
		(start 112.205516 -216.259156)
		(end 112.205516 -216.241884)
		(width 0.0889)
		(layer "In2.Cu")
		(net "P5E_CPU1_PE1_TX_DN<7>")
	)
	(segment
		(start 112.675416 -223.584262)
		(end 112.675416 -223.557084)
		(width 0.0889)
		(layer "In2.Cu")
		(net "P5E_CPU1_PE1_TX_DN<7>")
	)
	(segment
		(start 112.893348 -223.846644)
		(end 112.81537 -223.867472)
		(width 0.0889)
		(layer "In2.Cu")
		(net "P5E_CPU1_PE1_TX_DN<7>")
	)
	(segment
		(start 112.392968 -219.830396)
		(end 112.384078 -219.825316)
		(width 0.0889)
		(layer "In2.Cu")
		(net "P5E_CPU1_PE1_TX_DN<7>")
	)
	(segment
		(start 39.70528 -21.072856)
		(end 39.776654 -20.880832)
		(width 0.14732)
		(layer "In2.Cu")
		(net "P5E_CPU1_PE1_TX_DN<7>")
	)
	(segment
		(start 112.247172 -211.815172)
		(end 109.09808 -189.042802)
		(width 0.14732)
		(layer "In2.Cu")
		(net "P5E_CPU1_PE1_TX_DN<7>")
	)
	(segment
		(start 109.09808 -189.042802)
		(end 108.070396 -185.047636)
		(width 0.14732)
		(layer "In2.Cu")
		(net "P5E_CPU1_PE1_TX_DN<7>")
	)
	(segment
		(start 39.348918 -19.948144)
		(end 39.195502 -19.613118)
		(width 0.14732)
		(layer "In2.Cu")
		(net "P5E_CPU1_PE1_TX_DN<7>")
	)
	(segment
		(start 112.205008 -213.575392)
		(end 112.247172 -213.533228)
		(width 0.0889)
		(layer "In2.Cu")
		(net "P5E_CPU1_PE1_TX_DN<7>")
	)
	(segment
		(start 112.675162 -215.44661)
		(end 112.675162 -215.238838)
		(width 0.0889)
		(layer "In2.Cu")
		(net "P5E_CPU1_PE1_TX_DN<7>")
	)
	(segment
		(start 38.454838 -17.907)
		(end 38.749478 -17.61236)
		(width 0.14732)
		(layer "In2.Cu")
		(net "P5E_CPU1_PE1_TX_DN<7>")
	)
	(segment
		(start 38.454838 -18.345404)
		(end 38.454838 -17.907)
		(width 0.14732)
		(layer "In2.Cu")
		(net "P5E_CPU1_PE1_TX_DN<7>")
	)
	(segment
		(start 112.39881 -216.578434)
		(end 112.392714 -216.574878)
		(width 0.0889)
		(layer "In2.Cu")
		(net "P5E_CPU1_PE1_TX_DN<7>")
	)
	(segment
		(start 112.675416 -217.072972)
		(end 112.675416 -217.064336)
		(width 0.0889)
		(layer "In2.Cu")
		(net "P5E_CPU1_PE1_TX_DN<7>")
	)
	(segment
		(start 112.853724 -218.372944)
		(end 112.862614 -218.367864)
		(width 0.0889)
		(layer "In2.Cu")
		(net "P5E_CPU1_PE1_TX_DN<7>")
	)
	(segment
		(start 113.145316 -221.133924)
		(end 113.145316 -221.1197)
		(width 0.0889)
		(layer "In2.Cu")
		(net "P5E_CPU1_PE1_TX_DN<7>")
	)
	(arc
		(start 112.392968 -222.437198)
		(mid 112.595791 -222.236967)
		(end 112.675162 -221.963234)
		(width 0.0889)
		(layer "In2.Cu")
		(net "P5E_CPU1_PE1_TX_DN<7>")
	)
	(arc
		(start 112.20577 -222.773748)
		(mid 112.205603 -222.762572)
		(end 112.20577 -222.751396)
		(width 0.0889)
		(layer "In2.Cu")
		(net "P5E_CPU1_PE1_TX_DN<7>")
	)
	(arc
		(start 112.86871 -218.364308)
		(mid 113.071297 -218.157957)
		(end 113.145316 -217.878406)
		(width 0.0889)
		(layer "In2.Cu")
		(net "P5E_CPU1_PE1_TX_DN<7>")
	)
	(arc
		(start 113.145316 -217.864182)
		(mid 113.066097 -217.589497)
		(end 112.862614 -217.388694)
		(width 0.0889)
		(layer "In2.Cu")
		(net "P5E_CPU1_PE1_TX_DN<7>")
	)
	(arc
		(start 113.145316 -221.1197)
		(mid 113.066097 -220.845015)
		(end 112.862614 -220.644212)
		(width 0.0889)
		(layer "In2.Cu")
		(net "P5E_CPU1_PE1_TX_DN<7>")
	)
	(arc
		(start 112.392714 -215.926162)
		(mid 112.597049 -215.723557)
		(end 112.675162 -215.44661)
		(width 0.0889)
		(layer "In2.Cu")
		(net "P5E_CPU1_PE1_TX_DN<7>")
	)
	(arc
		(start 112.81537 -223.867472)
		(mid 112.714049 -223.741351)
		(end 112.675416 -223.584262)
		(width 0.0889)
		(layer "In2.Cu")
		(net "P5E_CPU1_PE1_TX_DN<7>")
	)
	(arc
		(start 112.384078 -223.080834)
		(mid 112.256267 -222.949741)
		(end 112.20577 -222.773748)
		(width 0.0889)
		(layer "In2.Cu")
		(net "P5E_CPU1_PE1_TX_DN<7>")
	)
	(arc
		(start 112.675162 -215.238838)
		(mid 112.583516 -215.070181)
		(end 112.44326 -214.939118)
		(width 0.0889)
		(layer "In2.Cu")
		(net "P5E_CPU1_PE1_TX_DN<7>")
	)
	(arc
		(start 112.675416 -223.557084)
		(mid 112.595254 -223.284895)
		(end 112.392968 -223.085914)
		(width 0.0889)
		(layer "In2.Cu")
		(net "P5E_CPU1_PE1_TX_DN<7>")
	)
	(arc
		(start 112.675162 -218.692222)
		(mid 112.722841 -218.509322)
		(end 112.853724 -218.372944)
		(width 0.0889)
		(layer "In2.Cu")
		(net "P5E_CPU1_PE1_TX_DN<7>")
	)
	(arc
		(start 112.392714 -216.574878)
		(mid 112.257781 -216.441524)
		(end 112.205516 -216.259156)
		(width 0.0889)
		(layer "In2.Cu")
		(net "P5E_CPU1_PE1_TX_DN<7>")
	)
	(arc
		(start 112.675416 -217.064336)
		(mid 112.601425 -216.78477)
		(end 112.39881 -216.578434)
		(width 0.0889)
		(layer "In2.Cu")
		(net "P5E_CPU1_PE1_TX_DN<7>")
	)
	(arc
		(start 112.392968 -219.18168)
		(mid 112.595791 -218.981449)
		(end 112.675162 -218.707716)
		(width 0.0889)
		(layer "In2.Cu")
		(net "P5E_CPU1_PE1_TX_DN<7>")
	)
	(arc
		(start 112.86871 -221.619826)
		(mid 113.071297 -221.413475)
		(end 113.145316 -221.133924)
		(width 0.0889)
		(layer "In2.Cu")
		(net "P5E_CPU1_PE1_TX_DN<7>")
	)
	(arc
		(start 112.675162 -221.94774)
		(mid 112.722841 -221.76484)
		(end 112.853724 -221.628462)
		(width 0.0889)
		(layer "In2.Cu")
		(net "P5E_CPU1_PE1_TX_DN<7>")
	)
	(arc
		(start 112.205516 -216.241884)
		(mid 112.257786 -216.059519)
		(end 112.392714 -215.926162)
		(width 0.0889)
		(layer "In2.Cu")
		(net "P5E_CPU1_PE1_TX_DN<7>")
	)
	(arc
		(start 112.384078 -219.825316)
		(mid 112.205481 -219.506038)
		(end 112.384078 -219.18676)
		(width 0.0889)
		(layer "In2.Cu")
		(net "P5E_CPU1_PE1_TX_DN<7>")
	)
	(arc
		(start 112.675416 -220.309948)
		(mid 112.597305 -220.032999)
		(end 112.392968 -219.830396)
		(width 0.0889)
		(layer "In2.Cu")
		(net "P5E_CPU1_PE1_TX_DN<7>")
	)
	(arc
		(start 112.20577 -222.751396)
		(mid 112.255785 -222.574265)
		(end 112.384078 -222.442278)
		(width 0.0889)
		(layer "In2.Cu")
		(net "P5E_CPU1_PE1_TX_DN<7>")
	)
	(arc
		(start 112.862614 -220.644212)
		(mid 112.727681 -220.510858)
		(end 112.675416 -220.32849)
		(width 0.0889)
		(layer "In2.Cu")
		(net "P5E_CPU1_PE1_TX_DN<7>")
	)
	(arc
		(start 112.862614 -217.388694)
		(mid 112.727681 -217.25534)
		(end 112.675416 -217.072972)
		(width 0.0889)
		(layer "In2.Cu")
		(net "P5E_CPU1_PE1_TX_DN<7>")
	)
	(arc
		(start 112.44326 -214.939118)
		(mid 112.416755 -214.922411)
		(end 112.389412 -214.907114)
		(width 0.0889)
		(layer "In2.Cu")
		(net "P5E_CPU1_PE1_TX_DN<7>")
	)
	(segment
		(start 41.286684 -18.83537)
		(end 41.286684 -18.216626)
		(width 0.13208)
		(layer "F.Cu")
		(net "P5E_CPU1_PE1_TX_DN<6>")
	)
	(segment
		(start 40.985694 -19.13636)
		(end 41.286684 -18.83537)
		(width 0.13208)
		(layer "F.Cu")
		(net "P5E_CPU1_PE1_TX_DN<6>")
	)
	(segment
		(start 41.286684 -18.216626)
		(end 40.960294 -17.890236)
		(width 0.13208)
		(layer "F.Cu")
		(net "P5E_CPU1_PE1_TX_DN<6>")
	)
	(segment
		(start 113.519966 -224.925128)
		(end 113.519966 -224.389442)
		(width 0.13208)
		(layer "F.Cu")
		(net "P5E_CPU1_PE1_TX_DN<6>")
	)
	(segment
		(start 113.519712 -224.925382)
		(end 113.519966 -224.925128)
		(width 0.13208)
		(layer "F.Cu")
		(net "P5E_CPU1_PE1_TX_DN<6>")
	)
	(segment
		(start 113.246916 -216.745312)
		(end 113.242598 -216.742772)
		(width 0.0889)
		(layer "In2.Cu")
		(net "P5E_CPU1_PE1_TX_DN<6>")
	)
	(segment
		(start 113.22431 -222.279972)
		(end 113.238534 -222.271844)
		(width 0.0889)
		(layer "In2.Cu")
		(net "P5E_CPU1_PE1_TX_DN<6>")
	)
	(segment
		(start 42.315638 -22.616668)
		(end 42.126662 -22.53742)
		(width 0.14732)
		(layer "In2.Cu")
		(net "P5E_CPU1_PE1_TX_DN<6>")
	)
	(segment
		(start 113.702338 -218.206066)
		(end 113.703862 -218.20505)
		(width 0.0889)
		(layer "In2.Cu")
		(net "P5E_CPU1_PE1_TX_DN<6>")
	)
	(segment
		(start 113.69675 -214.953596)
		(end 113.707418 -214.947246)
		(width 0.0889)
		(layer "In2.Cu")
		(net "P5E_CPU1_PE1_TX_DN<6>")
	)
	(segment
		(start 113.231168 -215.764872)
		(end 113.232946 -215.763856)
		(width 0.0889)
		(layer "In2.Cu")
		(net "P5E_CPU1_PE1_TX_DN<6>")
	)
	(segment
		(start 108.688632 -184.802272)
		(end 73.591674 -93.26372)
		(width 0.14732)
		(layer "In2.Cu")
		(net "P5E_CPU1_PE1_TX_DN<6>")
	)
	(segment
		(start 113.42497 -223.575626)
		(end 113.42497 -223.564196)
		(width 0.0889)
		(layer "In2.Cu")
		(net "P5E_CPU1_PE1_TX_DN<6>")
	)
	(segment
		(start 113.241328 -223.253046)
		(end 113.224056 -223.242886)
		(width 0.0889)
		(layer "In2.Cu")
		(net "P5E_CPU1_PE1_TX_DN<6>")
	)
	(segment
		(start 113.894616 -214.634064)
		(end 113.894616 -214.390224)
		(width 0.0889)
		(layer "In2.Cu")
		(net "P5E_CPU1_PE1_TX_DN<6>")
	)
	(segment
		(start 73.591674 -93.26372)
		(end 51.278028 -44.59478)
		(width 0.14732)
		(layer "In2.Cu")
		(net "P5E_CPU1_PE1_TX_DN<6>")
	)
	(segment
		(start 113.38306 -213.188042)
		(end 113.38306 -213.165944)
		(width 0.0889)
		(layer "In2.Cu")
		(net "P5E_CPU1_PE1_TX_DN<6>")
	)
	(segment
		(start 41.280334 -20.077938)
		(end 41.280334 -19.431)
		(width 0.14732)
		(layer "In2.Cu")
		(net "P5E_CPU1_PE1_TX_DN<6>")
	)
	(segment
		(start 113.754662 -224.681288)
		(end 113.754662 -224.681796)
		(width 0.0889)
		(layer "In2.Cu")
		(net "P5E_CPU1_PE1_TX_DN<6>")
	)
	(segment
		(start 42.126662 -22.53742)
		(end 41.98747 -22.196044)
		(width 0.14732)
		(layer "In2.Cu")
		(net "P5E_CPU1_PE1_TX_DN<6>")
	)
	(segment
		(start 113.24082 -219.997274)
		(end 113.23828 -219.99575)
		(width 0.0889)
		(layer "In2.Cu")
		(net "P5E_CPU1_PE1_TX_DN<6>")
	)
	(segment
		(start 113.22431 -215.768682)
		(end 113.231168 -215.764872)
		(width 0.0889)
		(layer "In2.Cu")
		(net "P5E_CPU1_PE1_TX_DN<6>")
	)
	(segment
		(start 42.066972 -22.007322)
		(end 41.928034 -21.6662)
		(width 0.14732)
		(layer "In2.Cu")
		(net "P5E_CPU1_PE1_TX_DN<6>")
	)
	(segment
		(start 41.280334 -19.431)
		(end 40.985694 -19.13636)
		(width 0.14732)
		(layer "In2.Cu")
		(net "P5E_CPU1_PE1_TX_DN<6>")
	)
	(segment
		(start 113.233454 -216.737692)
		(end 113.22431 -216.732104)
		(width 0.0889)
		(layer "In2.Cu")
		(net "P5E_CPU1_PE1_TX_DN<6>")
	)
	(segment
		(start 113.89487 -221.141798)
		(end 113.89487 -221.118938)
		(width 0.0889)
		(layer "In2.Cu")
		(net "P5E_CPU1_PE1_TX_DN<6>")
	)
	(segment
		(start 113.242598 -216.742772)
		(end 113.234724 -216.738708)
		(width 0.0889)
		(layer "In2.Cu")
		(net "P5E_CPU1_PE1_TX_DN<6>")
	)
	(segment
		(start 113.234724 -219.993718)
		(end 113.233708 -219.99321)
		(width 0.0889)
		(layer "In2.Cu")
		(net "P5E_CPU1_PE1_TX_DN<6>")
	)
	(segment
		(start 113.424462 -215.51773)
		(end 113.424462 -215.357964)
		(width 0.0889)
		(layer "In2.Cu")
		(net "P5E_CPU1_PE1_TX_DN<6>")
	)
	(segment
		(start 113.424462 -215.357964)
		(end 113.431066 -215.35136)
		(width 0.0889)
		(layer "In2.Cu")
		(net "P5E_CPU1_PE1_TX_DN<6>")
	)
	(segment
		(start 113.707672 -224.06483)
		(end 113.702338 -224.061782)
		(width 0.0889)
		(layer "In2.Cu")
		(net "P5E_CPU1_PE1_TX_DN<6>")
	)
	(segment
		(start 113.229136 -219.990162)
		(end 113.22812 -219.989654)
		(width 0.0889)
		(layer "In2.Cu")
		(net "P5E_CPU1_PE1_TX_DN<6>")
	)
	(segment
		(start 113.22431 -215.768936)
		(end 113.22431 -215.768682)
		(width 0.0889)
		(layer "In2.Cu")
		(net "P5E_CPU1_PE1_TX_DN<6>")
	)
	(segment
		(start 41.98747 -22.196044)
		(end 42.066972 -22.007322)
		(width 0.14732)
		(layer "In2.Cu")
		(net "P5E_CPU1_PE1_TX_DN<6>")
	)
	(segment
		(start 113.42497 -213.229952)
		(end 113.38306 -213.188042)
		(width 0.0889)
		(layer "In2.Cu")
		(net "P5E_CPU1_PE1_TX_DN<6>")
	)
	(segment
		(start 113.24209 -215.758268)
		(end 113.302796 -215.723216)
		(width 0.0889)
		(layer "In2.Cu")
		(net "P5E_CPU1_PE1_TX_DN<6>")
	)
	(segment
		(start 113.89487 -224.389696)
		(end 113.89487 -224.381568)
		(width 0.0889)
		(layer "In2.Cu")
		(net "P5E_CPU1_PE1_TX_DN<6>")
	)
	(segment
		(start 41.679622 -21.057108)
		(end 41.280334 -20.077938)
		(width 0.14732)
		(layer "In2.Cu")
		(net "P5E_CPU1_PE1_TX_DN<6>")
	)
	(segment
		(start 113.233708 -219.99321)
		(end 113.230406 -219.991178)
		(width 0.0889)
		(layer "In2.Cu")
		(net "P5E_CPU1_PE1_TX_DN<6>")
	)
	(segment
		(start 113.232946 -215.763856)
		(end 113.24209 -215.758268)
		(width 0.0889)
		(layer "In2.Cu")
		(net "P5E_CPU1_PE1_TX_DN<6>")
	)
	(segment
		(start 113.229644 -219.021406)
		(end 113.236756 -219.017342)
		(width 0.0889)
		(layer "In2.Cu")
		(net "P5E_CPU1_PE1_TX_DN<6>")
	)
	(segment
		(start 113.707672 -220.809312)
		(end 113.697004 -220.802962)
		(width 0.0889)
		(layer "In2.Cu")
		(net "P5E_CPU1_PE1_TX_DN<6>")
	)
	(segment
		(start 113.707672 -217.553794)
		(end 113.697004 -217.547444)
		(width 0.0889)
		(layer "In2.Cu")
		(net "P5E_CPU1_PE1_TX_DN<6>")
	)
	(segment
		(start 113.24336 -223.254062)
		(end 113.241328 -223.253046)
		(width 0.0889)
		(layer "In2.Cu")
		(net "P5E_CPU1_PE1_TX_DN<6>")
	)
	(segment
		(start 113.234724 -216.738708)
		(end 113.233454 -216.737692)
		(width 0.0889)
		(layer "In2.Cu")
		(net "P5E_CPU1_PE1_TX_DN<6>")
	)
	(segment
		(start 113.242344 -219.99829)
		(end 113.24082 -219.997274)
		(width 0.0889)
		(layer "In2.Cu")
		(net "P5E_CPU1_PE1_TX_DN<6>")
	)
	(segment
		(start 113.702338 -224.061782)
		(end 113.693956 -224.056956)
		(width 0.0889)
		(layer "In2.Cu")
		(net "P5E_CPU1_PE1_TX_DN<6>")
	)
	(segment
		(start 41.739312 -21.587206)
		(end 41.60012 -21.24583)
		(width 0.14732)
		(layer "In2.Cu")
		(net "P5E_CPU1_PE1_TX_DN<6>")
	)
	(segment
		(start 113.42497 -213.791292)
		(end 113.42497 -213.229952)
		(width 0.0889)
		(layer "In2.Cu")
		(net "P5E_CPU1_PE1_TX_DN<6>")
	)
	(segment
		(start 113.224056 -219.024708)
		(end 113.229644 -219.021406)
		(width 0.0889)
		(layer "In2.Cu")
		(net "P5E_CPU1_PE1_TX_DN<6>")
	)
	(segment
		(start 113.230406 -219.991178)
		(end 113.229136 -219.990162)
		(width 0.0889)
		(layer "In2.Cu")
		(net "P5E_CPU1_PE1_TX_DN<6>")
	)
	(segment
		(start 113.69421 -221.466156)
		(end 113.702592 -221.461584)
		(width 0.0889)
		(layer "In2.Cu")
		(net "P5E_CPU1_PE1_TX_DN<6>")
	)
	(segment
		(start 113.238534 -222.271844)
		(end 113.242344 -222.269558)
		(width 0.0889)
		(layer "In2.Cu")
		(net "P5E_CPU1_PE1_TX_DN<6>")
	)
	(segment
		(start 113.23828 -219.99575)
		(end 113.234724 -219.993718)
		(width 0.0889)
		(layer "In2.Cu")
		(net "P5E_CPU1_PE1_TX_DN<6>")
	)
	(segment
		(start 113.698782 -218.207844)
		(end 113.702338 -218.206066)
		(width 0.0889)
		(layer "In2.Cu")
		(net "P5E_CPU1_PE1_TX_DN<6>")
	)
	(segment
		(start 113.894616 -224.389442)
		(end 113.89487 -224.389696)
		(width 0.0889)
		(layer "In2.Cu")
		(net "P5E_CPU1_PE1_TX_DN<6>")
	)
	(segment
		(start 113.703862 -218.20505)
		(end 113.707418 -218.203018)
		(width 0.0889)
		(layer "In2.Cu")
		(net "P5E_CPU1_PE1_TX_DN<6>")
	)
	(segment
		(start 113.22812 -219.989654)
		(end 113.224056 -219.987368)
		(width 0.0889)
		(layer "In2.Cu")
		(net "P5E_CPU1_PE1_TX_DN<6>")
	)
	(segment
		(start 109.690916 -188.52261)
		(end 108.688632 -184.802272)
		(width 0.14732)
		(layer "In2.Cu")
		(net "P5E_CPU1_PE1_TX_DN<6>")
	)
	(segment
		(start 113.693956 -221.46641)
		(end 113.69421 -221.466156)
		(width 0.0889)
		(layer "In2.Cu")
		(net "P5E_CPU1_PE1_TX_DN<6>")
	)
	(segment
		(start 41.60012 -21.24583)
		(end 41.679622 -21.057108)
		(width 0.14732)
		(layer "In2.Cu")
		(net "P5E_CPU1_PE1_TX_DN<6>")
	)
	(segment
		(start 51.278028 -44.59478)
		(end 42.315638 -22.616668)
		(width 0.14732)
		(layer "In2.Cu")
		(net "P5E_CPU1_PE1_TX_DN<6>")
	)
	(segment
		(start 113.519966 -224.389442)
		(end 113.67643 -224.66046)
		(width 0.0889)
		(layer "In2.Cu")
		(net "P5E_CPU1_PE1_TX_DN<6>")
	)
	(segment
		(start 113.702592 -221.461584)
		(end 113.707672 -221.458536)
		(width 0.0889)
		(layer "In2.Cu")
		(net "P5E_CPU1_PE1_TX_DN<6>")
	)
	(segment
		(start 113.224056 -222.280226)
		(end 113.22431 -222.279972)
		(width 0.0889)
		(layer "In2.Cu")
		(net "P5E_CPU1_PE1_TX_DN<6>")
	)
	(segment
		(start 113.89487 -217.88628)
		(end 113.89487 -217.86342)
		(width 0.0889)
		(layer "In2.Cu")
		(net "P5E_CPU1_PE1_TX_DN<6>")
	)
	(segment
		(start 113.67643 -224.66046)
		(end 113.754662 -224.681288)
		(width 0.0889)
		(layer "In2.Cu")
		(net "P5E_CPU1_PE1_TX_DN<6>")
	)
	(segment
		(start 113.236756 -219.017342)
		(end 113.23828 -219.016326)
		(width 0.0889)
		(layer "In2.Cu")
		(net "P5E_CPU1_PE1_TX_DN<6>")
	)
	(segment
		(start 41.928034 -21.6662)
		(end 41.739312 -21.587206)
		(width 0.14732)
		(layer "In2.Cu")
		(net "P5E_CPU1_PE1_TX_DN<6>")
	)
	(segment
		(start 113.38306 -213.165944)
		(end 113.38306 -211.382864)
		(width 0.14732)
		(layer "In2.Cu")
		(net "P5E_CPU1_PE1_TX_DN<6>")
	)
	(segment
		(start 113.23828 -219.016326)
		(end 113.242852 -219.013786)
		(width 0.0889)
		(layer "In2.Cu")
		(net "P5E_CPU1_PE1_TX_DN<6>")
	)
	(segment
		(start 113.38306 -211.382864)
		(end 109.690916 -188.52261)
		(width 0.14732)
		(layer "In2.Cu")
		(net "P5E_CPU1_PE1_TX_DN<6>")
	)
	(segment
		(start 113.894616 -214.390224)
		(end 113.53927 -214.034878)
		(width 0.0889)
		(layer "In2.Cu")
		(net "P5E_CPU1_PE1_TX_DN<6>")
	)
	(arc
		(start 113.22431 -216.732104)
		(mid 112.954747 -216.25052)
		(end 113.22431 -215.768936)
		(width 0.0889)
		(layer "In2.Cu")
		(net "P5E_CPU1_PE1_TX_DN<6>")
	)
	(arc
		(start 113.89487 -224.381568)
		(mid 113.842792 -224.198658)
		(end 113.707672 -224.06483)
		(width 0.0889)
		(layer "In2.Cu")
		(net "P5E_CPU1_PE1_TX_DN<6>")
	)
	(arc
		(start 112.955324 -222.74657)
		(mid 113.030625 -222.47937)
		(end 113.224056 -222.280226)
		(width 0.0889)
		(layer "In2.Cu")
		(net "P5E_CPU1_PE1_TX_DN<6>")
	)
	(arc
		(start 113.697004 -217.547444)
		(mid 113.49762 -217.341564)
		(end 113.42497 -217.064336)
		(width 0.0889)
		(layer "In2.Cu")
		(net "P5E_CPU1_PE1_TX_DN<6>")
	)
	(arc
		(start 113.754662 -224.681796)
		(mid 113.857916 -224.551542)
		(end 113.894616 -224.389442)
		(width 0.0889)
		(layer "In2.Cu")
		(net "P5E_CPU1_PE1_TX_DN<6>")
	)
	(arc
		(start 113.302796 -215.723216)
		(mid 113.391738 -215.637109)
		(end 113.424462 -215.51773)
		(width 0.0889)
		(layer "In2.Cu")
		(net "P5E_CPU1_PE1_TX_DN<6>")
	)
	(arc
		(start 113.224056 -219.987368)
		(mid 112.955073 -219.506038)
		(end 113.224056 -219.024708)
		(width 0.0889)
		(layer "In2.Cu")
		(net "P5E_CPU1_PE1_TX_DN<6>")
	)
	(arc
		(start 113.431066 -215.35136)
		(mid 113.519707 -215.122943)
		(end 113.69675 -214.953596)
		(width 0.0889)
		(layer "In2.Cu")
		(net "P5E_CPU1_PE1_TX_DN<6>")
	)
	(arc
		(start 113.707418 -218.203018)
		(mid 113.842709 -218.069236)
		(end 113.89487 -217.88628)
		(width 0.0889)
		(layer "In2.Cu")
		(net "P5E_CPU1_PE1_TX_DN<6>")
	)
	(arc
		(start 113.707418 -214.947246)
		(mid 113.841625 -214.81493)
		(end 113.894616 -214.634064)
		(width 0.0889)
		(layer "In2.Cu")
		(net "P5E_CPU1_PE1_TX_DN<6>")
	)
	(arc
		(start 113.89487 -221.118938)
		(mid 113.841065 -220.940063)
		(end 113.707672 -220.809312)
		(width 0.0889)
		(layer "In2.Cu")
		(net "P5E_CPU1_PE1_TX_DN<6>")
	)
	(arc
		(start 113.89487 -217.86342)
		(mid 113.841065 -217.684545)
		(end 113.707672 -217.553794)
		(width 0.0889)
		(layer "In2.Cu")
		(net "P5E_CPU1_PE1_TX_DN<6>")
	)
	(arc
		(start 113.53927 -214.034878)
		(mid 113.460829 -213.923077)
		(end 113.42497 -213.791292)
		(width 0.0889)
		(layer "In2.Cu")
		(net "P5E_CPU1_PE1_TX_DN<6>")
	)
	(arc
		(start 113.242344 -222.269558)
		(mid 113.376118 -222.132748)
		(end 113.42497 -221.94774)
		(width 0.0889)
		(layer "In2.Cu")
		(net "P5E_CPU1_PE1_TX_DN<6>")
	)
	(arc
		(start 113.697004 -220.802962)
		(mid 113.49762 -220.597082)
		(end 113.42497 -220.319854)
		(width 0.0889)
		(layer "In2.Cu")
		(net "P5E_CPU1_PE1_TX_DN<6>")
	)
	(arc
		(start 113.42497 -220.319854)
		(mid 113.376073 -220.13498)
		(end 113.242344 -219.99829)
		(width 0.0889)
		(layer "In2.Cu")
		(net "P5E_CPU1_PE1_TX_DN<6>")
	)
	(arc
		(start 113.242852 -219.013786)
		(mid 113.376295 -218.877005)
		(end 113.42497 -218.692222)
		(width 0.0889)
		(layer "In2.Cu")
		(net "P5E_CPU1_PE1_TX_DN<6>")
	)
	(arc
		(start 113.42497 -217.064336)
		(mid 113.377449 -216.881653)
		(end 113.246916 -216.745312)
		(width 0.0889)
		(layer "In2.Cu")
		(net "P5E_CPU1_PE1_TX_DN<6>")
	)
	(arc
		(start 113.42497 -218.692222)
		(mid 113.498082 -218.413952)
		(end 113.698782 -218.207844)
		(width 0.0889)
		(layer "In2.Cu")
		(net "P5E_CPU1_PE1_TX_DN<6>")
	)
	(arc
		(start 112.955578 -222.784162)
		(mid 112.955139 -222.765368)
		(end 112.955324 -222.74657)
		(width 0.0889)
		(layer "In2.Cu")
		(net "P5E_CPU1_PE1_TX_DN<6>")
	)
	(arc
		(start 113.224056 -223.242886)
		(mid 113.032495 -223.047065)
		(end 112.955578 -222.784162)
		(width 0.0889)
		(layer "In2.Cu")
		(net "P5E_CPU1_PE1_TX_DN<6>")
	)
	(arc
		(start 113.42497 -223.564196)
		(mid 113.373704 -223.385974)
		(end 113.24336 -223.254062)
		(width 0.0889)
		(layer "In2.Cu")
		(net "P5E_CPU1_PE1_TX_DN<6>")
	)
	(arc
		(start 113.707672 -221.458536)
		(mid 113.842782 -221.324702)
		(end 113.89487 -221.141798)
		(width 0.0889)
		(layer "In2.Cu")
		(net "P5E_CPU1_PE1_TX_DN<6>")
	)
	(arc
		(start 113.42497 -221.94774)
		(mid 113.496778 -221.672044)
		(end 113.693956 -221.46641)
		(width 0.0889)
		(layer "In2.Cu")
		(net "P5E_CPU1_PE1_TX_DN<6>")
	)
	(arc
		(start 113.693956 -224.056956)
		(mid 113.49678 -223.851321)
		(end 113.42497 -223.575626)
		(width 0.0889)
		(layer "In2.Cu")
		(net "P5E_CPU1_PE1_TX_DN<6>")
	)
	(segment
		(start 114.929666 -224.111566)
		(end 114.929666 -223.575626)
		(width 0.13208)
		(layer "F.Cu")
		(net "P5E_CPU1_PE1_TX_DN<5>")
	)
	(segment
		(start 44.339764 -16.695166)
		(end 44.668694 -16.366236)
		(width 0.13208)
		(layer "F.Cu")
		(net "P5E_CPU1_PE1_TX_DN<5>")
	)
	(segment
		(start 44.339764 -17.30883)
		(end 44.339764 -16.695166)
		(width 0.13208)
		(layer "F.Cu")
		(net "P5E_CPU1_PE1_TX_DN<5>")
	)
	(segment
		(start 44.643294 -17.61236)
		(end 44.339764 -17.30883)
		(width 0.13208)
		(layer "F.Cu")
		(net "P5E_CPU1_PE1_TX_DN<5>")
	)
	(segment
		(start 109.887258 -184.550812)
		(end 74.689716 -92.721938)
		(width 0.14732)
		(layer "In2.Cu")
		(net "P5E_CPU1_PE1_TX_DN<5>")
	)
	(segment
		(start 114.548666 -213.297008)
		(end 114.548666 -213.284816)
		(width 0.0889)
		(layer "In2.Cu")
		(net "P5E_CPU1_PE1_TX_DN<5>")
	)
	(segment
		(start 114.263678 -215.931242)
		(end 114.271552 -215.92667)
		(width 0.0889)
		(layer "In2.Cu")
		(net "P5E_CPU1_PE1_TX_DN<5>")
	)
	(segment
		(start 114.742214 -221.623382)
		(end 114.754406 -221.61627)
		(width 0.0889)
		(layer "In2.Cu")
		(net "P5E_CPU1_PE1_TX_DN<5>")
	)
	(segment
		(start 114.733324 -218.372944)
		(end 114.74069 -218.368626)
		(width 0.0889)
		(layer "In2.Cu")
		(net "P5E_CPU1_PE1_TX_DN<5>")
	)
	(segment
		(start 115.024662 -214.641176)
		(end 115.024662 -214.425022)
		(width 0.0889)
		(layer "In2.Cu")
		(net "P5E_CPU1_PE1_TX_DN<5>")
	)
	(segment
		(start 44.648628 -19.735038)
		(end 44.46524 -19.643598)
		(width 0.14732)
		(layer "In2.Cu")
		(net "P5E_CPU1_PE1_TX_DN<5>")
	)
	(segment
		(start 114.555016 -221.957646)
		(end 114.555016 -221.939104)
		(width 0.0889)
		(layer "In2.Cu")
		(net "P5E_CPU1_PE1_TX_DN<5>")
	)
	(segment
		(start 44.348654 -17.907)
		(end 44.643294 -17.61236)
		(width 0.14732)
		(layer "In2.Cu")
		(net "P5E_CPU1_PE1_TX_DN<5>")
	)
	(segment
		(start 114.263678 -222.442278)
		(end 114.272568 -222.437198)
		(width 0.0889)
		(layer "In2.Cu")
		(net "P5E_CPU1_PE1_TX_DN<5>")
	)
	(segment
		(start 114.271552 -215.92667)
		(end 114.272568 -215.926162)
		(width 0.0889)
		(layer "In2.Cu")
		(net "P5E_CPU1_PE1_TX_DN<5>")
	)
	(segment
		(start 114.263678 -219.18676)
		(end 114.272568 -219.18168)
		(width 0.0889)
		(layer "In2.Cu")
		(net "P5E_CPU1_PE1_TX_DN<5>")
	)
	(segment
		(start 45.090588 -21.05787)
		(end 44.973748 -20.708366)
		(width 0.14732)
		(layer "In2.Cu")
		(net "P5E_CPU1_PE1_TX_DN<5>")
	)
	(segment
		(start 114.548412 -213.680548)
		(end 114.548412 -213.297262)
		(width 0.0889)
		(layer "In2.Cu")
		(net "P5E_CPU1_PE1_TX_DN<5>")
	)
	(segment
		(start 114.554762 -218.707716)
		(end 114.554762 -218.692222)
		(width 0.0889)
		(layer "In2.Cu")
		(net "P5E_CPU1_PE1_TX_DN<5>")
	)
	(segment
		(start 114.555016 -220.32849)
		(end 114.555016 -220.309948)
		(width 0.0889)
		(layer "In2.Cu")
		(net "P5E_CPU1_PE1_TX_DN<5>")
	)
	(segment
		(start 114.272568 -223.085914)
		(end 114.263678 -223.080834)
		(width 0.0889)
		(layer "In2.Cu")
		(net "P5E_CPU1_PE1_TX_DN<5>")
	)
	(segment
		(start 44.973748 -20.708366)
		(end 44.79036 -20.616926)
		(width 0.14732)
		(layer "In2.Cu")
		(net "P5E_CPU1_PE1_TX_DN<5>")
	)
	(segment
		(start 114.742214 -218.367864)
		(end 114.742976 -218.367356)
		(width 0.0889)
		(layer "In2.Cu")
		(net "P5E_CPU1_PE1_TX_DN<5>")
	)
	(segment
		(start 114.548412 -213.297262)
		(end 114.548666 -213.297008)
		(width 0.0889)
		(layer "In2.Cu")
		(net "P5E_CPU1_PE1_TX_DN<5>")
	)
	(segment
		(start 44.79036 -20.616926)
		(end 44.673774 -20.267676)
		(width 0.14732)
		(layer "In2.Cu")
		(net "P5E_CPU1_PE1_TX_DN<5>")
	)
	(segment
		(start 114.74069 -218.368626)
		(end 114.742214 -218.367864)
		(width 0.0889)
		(layer "In2.Cu")
		(net "P5E_CPU1_PE1_TX_DN<5>")
	)
	(segment
		(start 114.772948 -223.846644)
		(end 114.69497 -223.867472)
		(width 0.0889)
		(layer "In2.Cu")
		(net "P5E_CPU1_PE1_TX_DN<5>")
	)
	(segment
		(start 114.555016 -223.584262)
		(end 114.555016 -223.557084)
		(width 0.0889)
		(layer "In2.Cu")
		(net "P5E_CPU1_PE1_TX_DN<5>")
	)
	(segment
		(start 114.554762 -215.452198)
		(end 114.554762 -215.437212)
		(width 0.0889)
		(layer "In2.Cu")
		(net "P5E_CPU1_PE1_TX_DN<5>")
	)
	(segment
		(start 114.742976 -218.367356)
		(end 114.74831 -218.364308)
		(width 0.0889)
		(layer "In2.Cu")
		(net "P5E_CPU1_PE1_TX_DN<5>")
	)
	(segment
		(start 114.555016 -217.072972)
		(end 114.555016 -217.05443)
		(width 0.0889)
		(layer "In2.Cu")
		(net "P5E_CPU1_PE1_TX_DN<5>")
	)
	(segment
		(start 115.024916 -221.133924)
		(end 115.024916 -221.126304)
		(width 0.0889)
		(layer "In2.Cu")
		(net "P5E_CPU1_PE1_TX_DN<5>")
	)
	(segment
		(start 114.929666 -223.575626)
		(end 114.772948 -223.846644)
		(width 0.0889)
		(layer "In2.Cu")
		(net "P5E_CPU1_PE1_TX_DN<5>")
	)
	(segment
		(start 114.567716 -213.920578)
		(end 114.548412 -213.680548)
		(width 0.0889)
		(layer "In2.Cu")
		(net "P5E_CPU1_PE1_TX_DN<5>")
	)
	(segment
		(start 114.272568 -219.830396)
		(end 114.263678 -219.825316)
		(width 0.0889)
		(layer "In2.Cu")
		(net "P5E_CPU1_PE1_TX_DN<5>")
	)
	(segment
		(start 44.998894 -21.241004)
		(end 45.090588 -21.05787)
		(width 0.14732)
		(layer "In2.Cu")
		(net "P5E_CPU1_PE1_TX_DN<5>")
	)
	(segment
		(start 115.024916 -217.878406)
		(end 115.024916 -217.864182)
		(width 0.0889)
		(layer "In2.Cu")
		(net "P5E_CPU1_PE1_TX_DN<5>")
	)
	(segment
		(start 44.765468 -20.084542)
		(end 44.648628 -19.735038)
		(width 0.14732)
		(layer "In2.Cu")
		(net "P5E_CPU1_PE1_TX_DN<5>")
	)
	(segment
		(start 114.548666 -213.284816)
		(end 114.59083 -213.242652)
		(width 0.0889)
		(layer "In2.Cu")
		(net "P5E_CPU1_PE1_TX_DN<5>")
	)
	(segment
		(start 44.46524 -19.643598)
		(end 44.348654 -19.294348)
		(width 0.14732)
		(layer "In2.Cu")
		(net "P5E_CPU1_PE1_TX_DN<5>")
	)
	(segment
		(start 74.689716 -92.721938)
		(end 53.267864 -45.99559)
		(width 0.14732)
		(layer "In2.Cu")
		(net "P5E_CPU1_PE1_TX_DN<5>")
	)
	(segment
		(start 114.59083 -211.071714)
		(end 110.937548 -188.450474)
		(width 0.14732)
		(layer "In2.Cu")
		(net "P5E_CPU1_PE1_TX_DN<5>")
	)
	(segment
		(start 114.59083 -213.242652)
		(end 114.59083 -213.220554)
		(width 0.0889)
		(layer "In2.Cu")
		(net "P5E_CPU1_PE1_TX_DN<5>")
	)
	(segment
		(start 44.673774 -20.267676)
		(end 44.765468 -20.084542)
		(width 0.14732)
		(layer "In2.Cu")
		(net "P5E_CPU1_PE1_TX_DN<5>")
	)
	(segment
		(start 44.348654 -19.294348)
		(end 44.348654 -17.907)
		(width 0.14732)
		(layer "In2.Cu")
		(net "P5E_CPU1_PE1_TX_DN<5>")
	)
	(segment
		(start 53.267864 -45.99559)
		(end 44.998894 -21.241004)
		(width 0.14732)
		(layer "In2.Cu")
		(net "P5E_CPU1_PE1_TX_DN<5>")
	)
	(segment
		(start 114.59083 -213.220554)
		(end 114.59083 -211.071714)
		(width 0.14732)
		(layer "In2.Cu")
		(net "P5E_CPU1_PE1_TX_DN<5>")
	)
	(segment
		(start 114.272568 -216.574878)
		(end 114.263678 -216.569798)
		(width 0.0889)
		(layer "In2.Cu")
		(net "P5E_CPU1_PE1_TX_DN<5>")
	)
	(segment
		(start 110.937548 -188.450474)
		(end 109.887258 -184.550812)
		(width 0.14732)
		(layer "In2.Cu")
		(net "P5E_CPU1_PE1_TX_DN<5>")
	)
	(arc
		(start 114.742214 -217.388694)
		(mid 114.607281 -217.25534)
		(end 114.555016 -217.072972)
		(width 0.0889)
		(layer "In2.Cu")
		(net "P5E_CPU1_PE1_TX_DN<5>")
	)
	(arc
		(start 114.742214 -220.644212)
		(mid 114.607281 -220.510858)
		(end 114.555016 -220.32849)
		(width 0.0889)
		(layer "In2.Cu")
		(net "P5E_CPU1_PE1_TX_DN<5>")
	)
	(arc
		(start 114.263678 -219.825316)
		(mid 114.134474 -219.691802)
		(end 114.08537 -219.512642)
		(width 0.0889)
		(layer "In2.Cu")
		(net "P5E_CPU1_PE1_TX_DN<5>")
	)
	(arc
		(start 114.272568 -219.18168)
		(mid 114.475391 -218.981449)
		(end 114.554762 -218.707716)
		(width 0.0889)
		(layer "In2.Cu")
		(net "P5E_CPU1_PE1_TX_DN<5>")
	)
	(arc
		(start 115.024662 -214.425022)
		(mid 114.913324 -214.232122)
		(end 114.739166 -214.093298)
		(width 0.0889)
		(layer "In2.Cu")
		(net "P5E_CPU1_PE1_TX_DN<5>")
	)
	(arc
		(start 114.263678 -216.569798)
		(mid 114.134474 -216.436284)
		(end 114.08537 -216.257124)
		(width 0.0889)
		(layer "In2.Cu")
		(net "P5E_CPU1_PE1_TX_DN<5>")
	)
	(arc
		(start 114.272568 -222.437198)
		(mid 114.476903 -222.234593)
		(end 114.555016 -221.957646)
		(width 0.0889)
		(layer "In2.Cu")
		(net "P5E_CPU1_PE1_TX_DN<5>")
	)
	(arc
		(start 114.554762 -215.437212)
		(mid 114.604918 -215.24963)
		(end 114.742214 -215.112346)
		(width 0.0889)
		(layer "In2.Cu")
		(net "P5E_CPU1_PE1_TX_DN<5>")
	)
	(arc
		(start 114.263678 -223.080834)
		(mid 114.135785 -222.949772)
		(end 114.08537 -222.773748)
		(width 0.0889)
		(layer "In2.Cu")
		(net "P5E_CPU1_PE1_TX_DN<5>")
	)
	(arc
		(start 114.08537 -222.773748)
		(mid 114.085125 -222.764352)
		(end 114.085116 -222.754952)
		(width 0.0889)
		(layer "In2.Cu")
		(net "P5E_CPU1_PE1_TX_DN<5>")
	)
	(arc
		(start 115.024916 -221.126304)
		(mid 114.947287 -220.847891)
		(end 114.742214 -220.644212)
		(width 0.0889)
		(layer "In2.Cu")
		(net "P5E_CPU1_PE1_TX_DN<5>")
	)
	(arc
		(start 114.754406 -221.61627)
		(mid 114.952634 -221.410422)
		(end 115.024916 -221.133924)
		(width 0.0889)
		(layer "In2.Cu")
		(net "P5E_CPU1_PE1_TX_DN<5>")
	)
	(arc
		(start 114.08537 -216.257124)
		(mid 114.085276 -216.248742)
		(end 114.08537 -216.24036)
		(width 0.0889)
		(layer "In2.Cu")
		(net "P5E_CPU1_PE1_TX_DN<5>")
	)
	(arc
		(start 114.739166 -214.093298)
		(mid 114.647749 -214.027332)
		(end 114.577876 -213.938866)
		(width 0.0889)
		(layer "In2.Cu")
		(net "P5E_CPU1_PE1_TX_DN<5>")
	)
	(arc
		(start 114.69497 -223.867472)
		(mid 114.593649 -223.741351)
		(end 114.555016 -223.584262)
		(width 0.0889)
		(layer "In2.Cu")
		(net "P5E_CPU1_PE1_TX_DN<5>")
	)
	(arc
		(start 114.555016 -221.939104)
		(mid 114.607286 -221.756739)
		(end 114.742214 -221.623382)
		(width 0.0889)
		(layer "In2.Cu")
		(net "P5E_CPU1_PE1_TX_DN<5>")
	)
	(arc
		(start 114.08537 -219.512642)
		(mid 114.085276 -219.50426)
		(end 114.08537 -219.495878)
		(width 0.0889)
		(layer "In2.Cu")
		(net "P5E_CPU1_PE1_TX_DN<5>")
	)
	(arc
		(start 114.555016 -223.557084)
		(mid 114.474854 -223.284895)
		(end 114.272568 -223.085914)
		(width 0.0889)
		(layer "In2.Cu")
		(net "P5E_CPU1_PE1_TX_DN<5>")
	)
	(arc
		(start 115.024916 -217.864182)
		(mid 114.945697 -217.589497)
		(end 114.742214 -217.388694)
		(width 0.0889)
		(layer "In2.Cu")
		(net "P5E_CPU1_PE1_TX_DN<5>")
	)
	(arc
		(start 114.742214 -215.112346)
		(mid 114.9445 -214.913365)
		(end 115.024662 -214.641176)
		(width 0.0889)
		(layer "In2.Cu")
		(net "P5E_CPU1_PE1_TX_DN<5>")
	)
	(arc
		(start 114.08537 -216.24036)
		(mid 114.135385 -216.063229)
		(end 114.263678 -215.931242)
		(width 0.0889)
		(layer "In2.Cu")
		(net "P5E_CPU1_PE1_TX_DN<5>")
	)
	(arc
		(start 114.555016 -220.309948)
		(mid 114.476905 -220.032999)
		(end 114.272568 -219.830396)
		(width 0.0889)
		(layer "In2.Cu")
		(net "P5E_CPU1_PE1_TX_DN<5>")
	)
	(arc
		(start 114.085116 -222.754952)
		(mid 114.134369 -222.575752)
		(end 114.263678 -222.442278)
		(width 0.0889)
		(layer "In2.Cu")
		(net "P5E_CPU1_PE1_TX_DN<5>")
	)
	(arc
		(start 114.577876 -213.938866)
		(mid 114.572676 -213.929789)
		(end 114.567716 -213.920578)
		(width 0.0889)
		(layer "In2.Cu")
		(net "P5E_CPU1_PE1_TX_DN<5>")
	)
	(arc
		(start 114.554762 -218.692222)
		(mid 114.602441 -218.509322)
		(end 114.733324 -218.372944)
		(width 0.0889)
		(layer "In2.Cu")
		(net "P5E_CPU1_PE1_TX_DN<5>")
	)
	(arc
		(start 114.74831 -218.364308)
		(mid 114.950897 -218.157957)
		(end 115.024916 -217.878406)
		(width 0.0889)
		(layer "In2.Cu")
		(net "P5E_CPU1_PE1_TX_DN<5>")
	)
	(arc
		(start 114.08537 -219.495878)
		(mid 114.135385 -219.318747)
		(end 114.263678 -219.18676)
		(width 0.0889)
		(layer "In2.Cu")
		(net "P5E_CPU1_PE1_TX_DN<5>")
	)
	(arc
		(start 114.555016 -217.05443)
		(mid 114.476905 -216.777481)
		(end 114.272568 -216.574878)
		(width 0.0889)
		(layer "In2.Cu")
		(net "P5E_CPU1_PE1_TX_DN<5>")
	)
	(arc
		(start 114.272568 -215.926162)
		(mid 114.475391 -215.725931)
		(end 114.554762 -215.452198)
		(width 0.0889)
		(layer "In2.Cu")
		(net "P5E_CPU1_PE1_TX_DN<5>")
	)
	(segment
		(start 115.399566 -224.925128)
		(end 115.399566 -224.389442)
		(width 0.13208)
		(layer "F.Cu")
		(net "P5E_CPU1_PE1_TX_DN<4>")
	)
	(segment
		(start 46.573694 -19.13636)
		(end 46.874684 -18.83537)
		(width 0.13208)
		(layer "F.Cu")
		(net "P5E_CPU1_PE1_TX_DN<4>")
	)
	(segment
		(start 115.399312 -224.925382)
		(end 115.399566 -224.925128)
		(width 0.13208)
		(layer "F.Cu")
		(net "P5E_CPU1_PE1_TX_DN<4>")
	)
	(segment
		(start 46.874684 -18.83537)
		(end 46.874684 -18.216626)
		(width 0.13208)
		(layer "F.Cu")
		(net "P5E_CPU1_PE1_TX_DN<4>")
	)
	(segment
		(start 46.874684 -18.216626)
		(end 46.548294 -17.890236)
		(width 0.13208)
		(layer "F.Cu")
		(net "P5E_CPU1_PE1_TX_DN<4>")
	)
	(segment
		(start 115.399566 -224.389442)
		(end 115.55603 -224.66046)
		(width 0.0889)
		(layer "In2.Cu")
		(net "P5E_CPU1_PE1_TX_DN<4>")
	)
	(segment
		(start 47.54499 -22.432518)
		(end 47.366428 -22.332442)
		(width 0.14732)
		(layer "In2.Cu")
		(net "P5E_CPU1_PE1_TX_DN<4>")
	)
	(segment
		(start 47.366428 -22.332442)
		(end 47.26686 -21.977604)
		(width 0.14732)
		(layer "In2.Cu")
		(net "P5E_CPU1_PE1_TX_DN<4>")
	)
	(segment
		(start 115.590574 -214.944452)
		(end 115.595146 -214.941912)
		(width 0.0889)
		(layer "In2.Cu")
		(net "P5E_CPU1_PE1_TX_DN<4>")
	)
	(segment
		(start 47.267876 -21.444712)
		(end 47.089314 -21.344382)
		(width 0.14732)
		(layer "In2.Cu")
		(net "P5E_CPU1_PE1_TX_DN<4>")
	)
	(segment
		(start 115.26266 -213.220554)
		(end 115.26266 -210.971892)
		(width 0.14732)
		(layer "In2.Cu")
		(net "P5E_CPU1_PE1_TX_DN<4>")
	)
	(segment
		(start 115.304316 -213.292182)
		(end 115.30457 -213.291928)
		(width 0.0889)
		(layer "In2.Cu")
		(net "P5E_CPU1_PE1_TX_DN<4>")
	)
	(segment
		(start 115.773708 -214.460074)
		(end 115.773962 -214.460328)
		(width 0.0889)
		(layer "In2.Cu")
		(net "P5E_CPU1_PE1_TX_DN<4>")
	)
	(segment
		(start 114.834416 -222.780098)
		(end 114.834416 -222.75165)
		(width 0.0889)
		(layer "In2.Cu")
		(net "P5E_CPU1_PE1_TX_DN<4>")
	)
	(segment
		(start 115.586256 -214.946992)
		(end 115.588288 -214.945722)
		(width 0.0889)
		(layer "In2.Cu")
		(net "P5E_CPU1_PE1_TX_DN<4>")
	)
	(segment
		(start 115.587526 -217.554556)
		(end 115.586764 -217.554048)
		(width 0.0889)
		(layer "In2.Cu")
		(net "P5E_CPU1_PE1_TX_DN<4>")
	)
	(segment
		(start 115.773708 -214.622634)
		(end 115.773708 -214.460074)
		(width 0.0889)
		(layer "In2.Cu")
		(net "P5E_CPU1_PE1_TX_DN<4>")
	)
	(segment
		(start 115.26266 -213.242652)
		(end 115.26266 -213.220554)
		(width 0.0889)
		(layer "In2.Cu")
		(net "P5E_CPU1_PE1_TX_DN<4>")
	)
	(segment
		(start 115.55603 -224.66046)
		(end 115.634262 -224.681288)
		(width 0.0889)
		(layer "In2.Cu")
		(net "P5E_CPU1_PE1_TX_DN<4>")
	)
	(segment
		(start 115.587526 -220.810074)
		(end 115.586764 -220.809566)
		(width 0.0889)
		(layer "In2.Cu")
		(net "P5E_CPU1_PE1_TX_DN<4>")
	)
	(segment
		(start 115.607846 -214.271606)
		(end 115.587272 -214.259668)
		(width 0.0889)
		(layer "In2.Cu")
		(net "P5E_CPU1_PE1_TX_DN<4>")
	)
	(segment
		(start 75.425554 -92.748862)
		(end 54.41696 -46.920658)
		(width 0.14732)
		(layer "In2.Cu")
		(net "P5E_CPU1_PE1_TX_DN<4>")
	)
	(segment
		(start 115.11661 -215.761062)
		(end 115.1255 -215.755982)
		(width 0.0889)
		(layer "In2.Cu")
		(net "P5E_CPU1_PE1_TX_DN<4>")
	)
	(segment
		(start 47.089314 -21.344382)
		(end 46.989746 -20.989544)
		(width 0.14732)
		(layer "In2.Cu")
		(net "P5E_CPU1_PE1_TX_DN<4>")
	)
	(segment
		(start 115.117626 -219.996004)
		(end 115.11661 -219.995496)
		(width 0.0889)
		(layer "In2.Cu")
		(net "P5E_CPU1_PE1_TX_DN<4>")
	)
	(segment
		(start 115.304062 -215.436704)
		(end 115.304062 -215.414606)
		(width 0.0889)
		(layer "In2.Cu")
		(net "P5E_CPU1_PE1_TX_DN<4>")
	)
	(segment
		(start 114.834162 -216.260426)
		(end 114.834162 -216.240614)
		(width 0.0889)
		(layer "In2.Cu")
		(net "P5E_CPU1_PE1_TX_DN<4>")
	)
	(segment
		(start 115.595654 -220.814646)
		(end 115.587526 -220.810074)
		(width 0.0889)
		(layer "In2.Cu")
		(net "P5E_CPU1_PE1_TX_DN<4>")
	)
	(segment
		(start 115.304062 -218.700858)
		(end 115.304062 -218.692222)
		(width 0.0889)
		(layer "In2.Cu")
		(net "P5E_CPU1_PE1_TX_DN<4>")
	)
	(segment
		(start 115.1255 -216.745058)
		(end 115.11661 -216.739978)
		(width 0.0889)
		(layer "In2.Cu")
		(net "P5E_CPU1_PE1_TX_DN<4>")
	)
	(segment
		(start 115.125754 -223.256348)
		(end 115.116864 -223.251268)
		(width 0.0889)
		(layer "In2.Cu")
		(net "P5E_CPU1_PE1_TX_DN<4>")
	)
	(segment
		(start 111.624872 -188.448442)
		(end 110.477554 -184.187592)
		(width 0.14732)
		(layer "In2.Cu")
		(net "P5E_CPU1_PE1_TX_DN<4>")
	)
	(segment
		(start 115.1255 -220.000576)
		(end 115.117626 -219.996004)
		(width 0.0889)
		(layer "In2.Cu")
		(net "P5E_CPU1_PE1_TX_DN<4>")
	)
	(segment
		(start 46.868334 -20.020788)
		(end 46.868334 -19.431)
		(width 0.14732)
		(layer "In2.Cu")
		(net "P5E_CPU1_PE1_TX_DN<4>")
	)
	(segment
		(start 47.26686 -21.977604)
		(end 47.36719 -21.799296)
		(width 0.14732)
		(layer "In2.Cu")
		(net "P5E_CPU1_PE1_TX_DN<4>")
	)
	(segment
		(start 115.58905 -214.945214)
		(end 115.590574 -214.944452)
		(width 0.0889)
		(layer "In2.Cu")
		(net "P5E_CPU1_PE1_TX_DN<4>")
	)
	(segment
		(start 115.304316 -213.87943)
		(end 115.304316 -213.292182)
		(width 0.0889)
		(layer "In2.Cu")
		(net "P5E_CPU1_PE1_TX_DN<4>")
	)
	(segment
		(start 115.587272 -214.259668)
		(end 115.372642 -214.045292)
		(width 0.0889)
		(layer "In2.Cu")
		(net "P5E_CPU1_PE1_TX_DN<4>")
	)
	(segment
		(start 114.834416 -219.521532)
		(end 114.834416 -219.496132)
		(width 0.0889)
		(layer "In2.Cu")
		(net "P5E_CPU1_PE1_TX_DN<4>")
	)
	(segment
		(start 115.595654 -224.070164)
		(end 115.586764 -224.065084)
		(width 0.0889)
		(layer "In2.Cu")
		(net "P5E_CPU1_PE1_TX_DN<4>")
	)
	(segment
		(start 47.36719 -21.799296)
		(end 47.267876 -21.444712)
		(width 0.14732)
		(layer "In2.Cu")
		(net "P5E_CPU1_PE1_TX_DN<4>")
	)
	(segment
		(start 115.30457 -213.291928)
		(end 115.30457 -213.284562)
		(width 0.0889)
		(layer "In2.Cu")
		(net "P5E_CPU1_PE1_TX_DN<4>")
	)
	(segment
		(start 115.304062 -217.071956)
		(end 115.304062 -217.064336)
		(width 0.0889)
		(layer "In2.Cu")
		(net "P5E_CPU1_PE1_TX_DN<4>")
	)
	(segment
		(start 115.304062 -220.327474)
		(end 115.304062 -220.319854)
		(width 0.0889)
		(layer "In2.Cu")
		(net "P5E_CPU1_PE1_TX_DN<4>")
	)
	(segment
		(start 115.26266 -210.971892)
		(end 111.624872 -188.448442)
		(width 0.14732)
		(layer "In2.Cu")
		(net "P5E_CPU1_PE1_TX_DN<4>")
	)
	(segment
		(start 115.304062 -221.956376)
		(end 115.304062 -221.94774)
		(width 0.0889)
		(layer "In2.Cu")
		(net "P5E_CPU1_PE1_TX_DN<4>")
	)
	(segment
		(start 115.304316 -223.585532)
		(end 115.304316 -223.575626)
		(width 0.0889)
		(layer "In2.Cu")
		(net "P5E_CPU1_PE1_TX_DN<4>")
	)
	(segment
		(start 115.588288 -214.945722)
		(end 115.58905 -214.945214)
		(width 0.0889)
		(layer "In2.Cu")
		(net "P5E_CPU1_PE1_TX_DN<4>")
	)
	(segment
		(start 115.580668 -221.461838)
		(end 115.595654 -221.453202)
		(width 0.0889)
		(layer "In2.Cu")
		(net "P5E_CPU1_PE1_TX_DN<4>")
	)
	(segment
		(start 46.989746 -20.989544)
		(end 47.090076 -20.810982)
		(width 0.14732)
		(layer "In2.Cu")
		(net "P5E_CPU1_PE1_TX_DN<4>")
	)
	(segment
		(start 46.868334 -19.431)
		(end 46.573694 -19.13636)
		(width 0.14732)
		(layer "In2.Cu")
		(net "P5E_CPU1_PE1_TX_DN<4>")
	)
	(segment
		(start 115.372642 -214.045292)
		(end 115.304316 -213.87943)
		(width 0.0889)
		(layer "In2.Cu")
		(net "P5E_CPU1_PE1_TX_DN<4>")
	)
	(segment
		(start 115.580668 -218.20632)
		(end 115.595654 -218.197684)
		(width 0.0889)
		(layer "In2.Cu")
		(net "P5E_CPU1_PE1_TX_DN<4>")
	)
	(segment
		(start 47.090076 -20.810982)
		(end 46.868334 -20.020788)
		(width 0.14732)
		(layer "In2.Cu")
		(net "P5E_CPU1_PE1_TX_DN<4>")
	)
	(segment
		(start 110.477554 -184.187592)
		(end 75.425554 -92.748862)
		(width 0.14732)
		(layer "In2.Cu")
		(net "P5E_CPU1_PE1_TX_DN<4>")
	)
	(segment
		(start 115.30457 -213.284562)
		(end 115.26266 -213.242652)
		(width 0.0889)
		(layer "In2.Cu")
		(net "P5E_CPU1_PE1_TX_DN<4>")
	)
	(segment
		(start 54.41696 -46.920658)
		(end 47.54499 -22.432518)
		(width 0.14732)
		(layer "In2.Cu")
		(net "P5E_CPU1_PE1_TX_DN<4>")
	)
	(segment
		(start 115.595654 -217.559128)
		(end 115.587526 -217.554556)
		(width 0.0889)
		(layer "In2.Cu")
		(net "P5E_CPU1_PE1_TX_DN<4>")
	)
	(arc
		(start 115.11661 -219.995496)
		(mid 114.913787 -219.795265)
		(end 114.834416 -219.521532)
		(width 0.0889)
		(layer "In2.Cu")
		(net "P5E_CPU1_PE1_TX_DN<4>")
	)
	(arc
		(start 115.586764 -220.809566)
		(mid 115.381692 -220.605887)
		(end 115.304062 -220.327474)
		(width 0.0889)
		(layer "In2.Cu")
		(net "P5E_CPU1_PE1_TX_DN<4>")
	)
	(arc
		(start 114.834162 -216.240614)
		(mid 114.912273 -215.963665)
		(end 115.11661 -215.761062)
		(width 0.0889)
		(layer "In2.Cu")
		(net "P5E_CPU1_PE1_TX_DN<4>")
	)
	(arc
		(start 115.304062 -221.94774)
		(mid 115.378053 -221.668174)
		(end 115.580668 -221.461838)
		(width 0.0889)
		(layer "In2.Cu")
		(net "P5E_CPU1_PE1_TX_DN<4>")
	)
	(arc
		(start 115.595654 -218.197684)
		(mid 115.774251 -217.878406)
		(end 115.595654 -217.559128)
		(width 0.0889)
		(layer "In2.Cu")
		(net "P5E_CPU1_PE1_TX_DN<4>")
	)
	(arc
		(start 115.304062 -218.692222)
		(mid 115.378053 -218.412656)
		(end 115.580668 -218.20632)
		(width 0.0889)
		(layer "In2.Cu")
		(net "P5E_CPU1_PE1_TX_DN<4>")
	)
	(arc
		(start 115.116864 -223.251268)
		(mid 114.914578 -223.052287)
		(end 114.834416 -222.780098)
		(width 0.0889)
		(layer "In2.Cu")
		(net "P5E_CPU1_PE1_TX_DN<4>")
	)
	(arc
		(start 115.1255 -215.755982)
		(mid 115.256414 -215.619622)
		(end 115.304062 -215.436704)
		(width 0.0889)
		(layer "In2.Cu")
		(net "P5E_CPU1_PE1_TX_DN<4>")
	)
	(arc
		(start 115.595654 -221.453202)
		(mid 115.774251 -221.133924)
		(end 115.595654 -220.814646)
		(width 0.0889)
		(layer "In2.Cu")
		(net "P5E_CPU1_PE1_TX_DN<4>")
	)
	(arc
		(start 115.304062 -215.414606)
		(mid 115.384973 -215.144478)
		(end 115.586256 -214.946992)
		(width 0.0889)
		(layer "In2.Cu")
		(net "P5E_CPU1_PE1_TX_DN<4>")
	)
	(arc
		(start 114.834416 -222.75165)
		(mid 114.912527 -222.474701)
		(end 115.116864 -222.272098)
		(width 0.0889)
		(layer "In2.Cu")
		(net "P5E_CPU1_PE1_TX_DN<4>")
	)
	(arc
		(start 115.595146 -214.941912)
		(mid 115.72606 -214.805552)
		(end 115.773708 -214.622634)
		(width 0.0889)
		(layer "In2.Cu")
		(net "P5E_CPU1_PE1_TX_DN<4>")
	)
	(arc
		(start 115.774216 -224.389442)
		(mid 115.726537 -224.206542)
		(end 115.595654 -224.070164)
		(width 0.0889)
		(layer "In2.Cu")
		(net "P5E_CPU1_PE1_TX_DN<4>")
	)
	(arc
		(start 115.586764 -224.065084)
		(mid 115.382429 -223.862479)
		(end 115.304316 -223.585532)
		(width 0.0889)
		(layer "In2.Cu")
		(net "P5E_CPU1_PE1_TX_DN<4>")
	)
	(arc
		(start 115.773962 -214.460328)
		(mid 115.705774 -214.35288)
		(end 115.607846 -214.271606)
		(width 0.0889)
		(layer "In2.Cu")
		(net "P5E_CPU1_PE1_TX_DN<4>")
	)
	(arc
		(start 115.304316 -223.575626)
		(mid 115.256637 -223.392726)
		(end 115.125754 -223.256348)
		(width 0.0889)
		(layer "In2.Cu")
		(net "P5E_CPU1_PE1_TX_DN<4>")
	)
	(arc
		(start 115.304062 -217.064336)
		(mid 115.256383 -216.881436)
		(end 115.1255 -216.745058)
		(width 0.0889)
		(layer "In2.Cu")
		(net "P5E_CPU1_PE1_TX_DN<4>")
	)
	(arc
		(start 114.834416 -219.496132)
		(mid 114.912527 -219.219183)
		(end 115.116864 -219.01658)
		(width 0.0889)
		(layer "In2.Cu")
		(net "P5E_CPU1_PE1_TX_DN<4>")
	)
	(arc
		(start 115.634262 -224.681288)
		(mid 115.737407 -224.551263)
		(end 115.774216 -224.389442)
		(width 0.0889)
		(layer "In2.Cu")
		(net "P5E_CPU1_PE1_TX_DN<4>")
	)
	(arc
		(start 115.11661 -216.739978)
		(mid 114.912275 -216.537373)
		(end 114.834162 -216.260426)
		(width 0.0889)
		(layer "In2.Cu")
		(net "P5E_CPU1_PE1_TX_DN<4>")
	)
	(arc
		(start 115.116864 -219.01658)
		(mid 115.251797 -218.883226)
		(end 115.304062 -218.700858)
		(width 0.0889)
		(layer "In2.Cu")
		(net "P5E_CPU1_PE1_TX_DN<4>")
	)
	(arc
		(start 115.116864 -222.272098)
		(mid 115.251797 -222.138744)
		(end 115.304062 -221.956376)
		(width 0.0889)
		(layer "In2.Cu")
		(net "P5E_CPU1_PE1_TX_DN<4>")
	)
	(arc
		(start 115.586764 -217.554048)
		(mid 115.381692 -217.350369)
		(end 115.304062 -217.071956)
		(width 0.0889)
		(layer "In2.Cu")
		(net "P5E_CPU1_PE1_TX_DN<4>")
	)
	(arc
		(start 115.304062 -220.319854)
		(mid 115.256383 -220.136954)
		(end 115.1255 -220.000576)
		(width 0.0889)
		(layer "In2.Cu")
		(net "P5E_CPU1_PE1_TX_DN<4>")
	)
	(segment
		(start 49.927764 -17.30883)
		(end 49.927764 -16.695166)
		(width 0.13208)
		(layer "F.Cu")
		(net "P5E_CPU1_PE1_TX_DN<3>")
	)
	(segment
		(start 50.231294 -17.61236)
		(end 49.927764 -17.30883)
		(width 0.13208)
		(layer "F.Cu")
		(net "P5E_CPU1_PE1_TX_DN<3>")
	)
	(segment
		(start 49.927764 -16.695166)
		(end 50.256694 -16.366236)
		(width 0.13208)
		(layer "F.Cu")
		(net "P5E_CPU1_PE1_TX_DN<3>")
	)
	(segment
		(start 116.809266 -224.111566)
		(end 116.809266 -223.57588)
		(width 0.13208)
		(layer "F.Cu")
		(net "P5E_CPU1_PE1_TX_DN<3>")
	)
	(segment
		(start 116.809266 -223.57588)
		(end 116.809012 -223.575626)
		(width 0.13208)
		(layer "F.Cu")
		(net "P5E_CPU1_PE1_TX_DN<3>")
	)
	(segment
		(start 116.434362 -218.707716)
		(end 116.434362 -218.692222)
		(width 0.0889)
		(layer "In2.Cu")
		(net "P5E_CPU1_PE1_TX_DN<3>")
	)
	(segment
		(start 116.477034 -210.148424)
		(end 112.826038 -187.795916)
		(width 0.14732)
		(layer "In2.Cu")
		(net "P5E_CPU1_PE1_TX_DN<3>")
	)
	(segment
		(start 55.711852 -46.786546)
		(end 50.358802 -21.30298)
		(width 0.14732)
		(layer "In2.Cu")
		(net "P5E_CPU1_PE1_TX_DN<3>")
	)
	(segment
		(start 116.434616 -217.072972)
		(end 116.434616 -217.05443)
		(width 0.0889)
		(layer "In2.Cu")
		(net "P5E_CPU1_PE1_TX_DN<3>")
	)
	(segment
		(start 116.809012 -223.575626)
		(end 116.652548 -223.846644)
		(width 0.0889)
		(layer "In2.Cu")
		(net "P5E_CPU1_PE1_TX_DN<3>")
	)
	(segment
		(start 116.621814 -218.367864)
		(end 116.622576 -218.367356)
		(width 0.0889)
		(layer "In2.Cu")
		(net "P5E_CPU1_PE1_TX_DN<3>")
	)
	(segment
		(start 116.152168 -219.830396)
		(end 116.143278 -219.825316)
		(width 0.0889)
		(layer "In2.Cu")
		(net "P5E_CPU1_PE1_TX_DN<3>")
	)
	(segment
		(start 50.012346 -19.654774)
		(end 49.936654 -19.294348)
		(width 0.14732)
		(layer "In2.Cu")
		(net "P5E_CPU1_PE1_TX_DN<3>")
	)
	(segment
		(start 50.358802 -21.30298)
		(end 50.470816 -21.13153)
		(width 0.14732)
		(layer "In2.Cu")
		(net "P5E_CPU1_PE1_TX_DN<3>")
	)
	(segment
		(start 116.477034 -213.242652)
		(end 116.477034 -213.220554)
		(width 0.0889)
		(layer "In2.Cu")
		(net "P5E_CPU1_PE1_TX_DN<3>")
	)
	(segment
		(start 116.904516 -217.878406)
		(end 116.904516 -217.864182)
		(width 0.0889)
		(layer "In2.Cu")
		(net "P5E_CPU1_PE1_TX_DN<3>")
	)
	(segment
		(start 116.43487 -213.284816)
		(end 116.477034 -213.242652)
		(width 0.0889)
		(layer "In2.Cu")
		(net "P5E_CPU1_PE1_TX_DN<3>")
	)
	(segment
		(start 116.904008 -214.644732)
		(end 116.904008 -214.424768)
		(width 0.0889)
		(layer "In2.Cu")
		(net "P5E_CPU1_PE1_TX_DN<3>")
	)
	(segment
		(start 50.18405 -19.766534)
		(end 50.012346 -19.654774)
		(width 0.14732)
		(layer "In2.Cu")
		(net "P5E_CPU1_PE1_TX_DN<3>")
	)
	(segment
		(start 116.43487 -213.294468)
		(end 116.43487 -213.284816)
		(width 0.0889)
		(layer "In2.Cu")
		(net "P5E_CPU1_PE1_TX_DN<3>")
	)
	(segment
		(start 111.770922 -184.184798)
		(end 76.361544 -91.82354)
		(width 0.14732)
		(layer "In2.Cu")
		(net "P5E_CPU1_PE1_TX_DN<3>")
	)
	(segment
		(start 50.147728 -20.298664)
		(end 50.259742 -20.127214)
		(width 0.14732)
		(layer "In2.Cu")
		(net "P5E_CPU1_PE1_TX_DN<3>")
	)
	(segment
		(start 116.434616 -213.897972)
		(end 116.434616 -213.294722)
		(width 0.0889)
		(layer "In2.Cu")
		(net "P5E_CPU1_PE1_TX_DN<3>")
	)
	(segment
		(start 116.434616 -221.957646)
		(end 116.434616 -221.939104)
		(width 0.0889)
		(layer "In2.Cu")
		(net "P5E_CPU1_PE1_TX_DN<3>")
	)
	(segment
		(start 116.622576 -218.367356)
		(end 116.62791 -218.364308)
		(width 0.0889)
		(layer "In2.Cu")
		(net "P5E_CPU1_PE1_TX_DN<3>")
	)
	(segment
		(start 116.612924 -218.372944)
		(end 116.62029 -218.368626)
		(width 0.0889)
		(layer "In2.Cu")
		(net "P5E_CPU1_PE1_TX_DN<3>")
	)
	(segment
		(start 49.936654 -19.294348)
		(end 49.936654 -17.907)
		(width 0.14732)
		(layer "In2.Cu")
		(net "P5E_CPU1_PE1_TX_DN<3>")
	)
	(segment
		(start 116.904516 -221.133924)
		(end 116.904516 -221.126304)
		(width 0.0889)
		(layer "In2.Cu")
		(net "P5E_CPU1_PE1_TX_DN<3>")
	)
	(segment
		(start 116.612924 -215.117426)
		(end 116.621814 -215.112346)
		(width 0.0889)
		(layer "In2.Cu")
		(net "P5E_CPU1_PE1_TX_DN<3>")
	)
	(segment
		(start 116.434616 -220.32849)
		(end 116.434616 -220.309948)
		(width 0.0889)
		(layer "In2.Cu")
		(net "P5E_CPU1_PE1_TX_DN<3>")
	)
	(segment
		(start 116.434362 -215.452198)
		(end 116.434362 -215.436704)
		(width 0.0889)
		(layer "In2.Cu")
		(net "P5E_CPU1_PE1_TX_DN<3>")
	)
	(segment
		(start 49.936654 -17.907)
		(end 50.231294 -17.61236)
		(width 0.14732)
		(layer "In2.Cu")
		(net "P5E_CPU1_PE1_TX_DN<3>")
	)
	(segment
		(start 76.361544 -91.82354)
		(end 55.711852 -46.786546)
		(width 0.14732)
		(layer "In2.Cu")
		(net "P5E_CPU1_PE1_TX_DN<3>")
	)
	(segment
		(start 50.395124 -20.77085)
		(end 50.22342 -20.65909)
		(width 0.14732)
		(layer "In2.Cu")
		(net "P5E_CPU1_PE1_TX_DN<3>")
	)
	(segment
		(start 116.434616 -223.584262)
		(end 116.434616 -223.557084)
		(width 0.0889)
		(layer "In2.Cu")
		(net "P5E_CPU1_PE1_TX_DN<3>")
	)
	(segment
		(start 50.470816 -21.13153)
		(end 50.395124 -20.77085)
		(width 0.14732)
		(layer "In2.Cu")
		(net "P5E_CPU1_PE1_TX_DN<3>")
	)
	(segment
		(start 50.259742 -20.127214)
		(end 50.18405 -19.766534)
		(width 0.14732)
		(layer "In2.Cu")
		(net "P5E_CPU1_PE1_TX_DN<3>")
	)
	(segment
		(start 116.62029 -218.368626)
		(end 116.621814 -218.367864)
		(width 0.0889)
		(layer "In2.Cu")
		(net "P5E_CPU1_PE1_TX_DN<3>")
	)
	(segment
		(start 116.143278 -222.442278)
		(end 116.152168 -222.437198)
		(width 0.0889)
		(layer "In2.Cu")
		(net "P5E_CPU1_PE1_TX_DN<3>")
	)
	(segment
		(start 116.434616 -213.294722)
		(end 116.43487 -213.294468)
		(width 0.0889)
		(layer "In2.Cu")
		(net "P5E_CPU1_PE1_TX_DN<3>")
	)
	(segment
		(start 116.621814 -221.623382)
		(end 116.634006 -221.61627)
		(width 0.0889)
		(layer "In2.Cu")
		(net "P5E_CPU1_PE1_TX_DN<3>")
	)
	(segment
		(start 116.652548 -223.846644)
		(end 116.57457 -223.867472)
		(width 0.0889)
		(layer "In2.Cu")
		(net "P5E_CPU1_PE1_TX_DN<3>")
	)
	(segment
		(start 116.644928 -214.10803)
		(end 116.434616 -213.897972)
		(width 0.0889)
		(layer "In2.Cu")
		(net "P5E_CPU1_PE1_TX_DN<3>")
	)
	(segment
		(start 50.22342 -20.65909)
		(end 50.147728 -20.298664)
		(width 0.14732)
		(layer "In2.Cu")
		(net "P5E_CPU1_PE1_TX_DN<3>")
	)
	(segment
		(start 116.152168 -216.574878)
		(end 116.143278 -216.569798)
		(width 0.0889)
		(layer "In2.Cu")
		(net "P5E_CPU1_PE1_TX_DN<3>")
	)
	(segment
		(start 116.143278 -215.931242)
		(end 116.152168 -215.926162)
		(width 0.0889)
		(layer "In2.Cu")
		(net "P5E_CPU1_PE1_TX_DN<3>")
	)
	(segment
		(start 116.477034 -213.220554)
		(end 116.477034 -210.148424)
		(width 0.14732)
		(layer "In2.Cu")
		(net "P5E_CPU1_PE1_TX_DN<3>")
	)
	(segment
		(start 112.826038 -187.795916)
		(end 111.770922 -184.184798)
		(width 0.14732)
		(layer "In2.Cu")
		(net "P5E_CPU1_PE1_TX_DN<3>")
	)
	(segment
		(start 116.143278 -219.18676)
		(end 116.152168 -219.18168)
		(width 0.0889)
		(layer "In2.Cu")
		(net "P5E_CPU1_PE1_TX_DN<3>")
	)
	(segment
		(start 116.152168 -223.085914)
		(end 116.143278 -223.080834)
		(width 0.0889)
		(layer "In2.Cu")
		(net "P5E_CPU1_PE1_TX_DN<3>")
	)
	(arc
		(start 115.96497 -216.24036)
		(mid 116.014985 -216.063229)
		(end 116.143278 -215.931242)
		(width 0.0889)
		(layer "In2.Cu")
		(net "P5E_CPU1_PE1_TX_DN<3>")
	)
	(arc
		(start 116.152168 -215.926162)
		(mid 116.354991 -215.725931)
		(end 116.434362 -215.452198)
		(width 0.0889)
		(layer "In2.Cu")
		(net "P5E_CPU1_PE1_TX_DN<3>")
	)
	(arc
		(start 115.96497 -219.495878)
		(mid 116.014985 -219.318747)
		(end 116.143278 -219.18676)
		(width 0.0889)
		(layer "In2.Cu")
		(net "P5E_CPU1_PE1_TX_DN<3>")
	)
	(arc
		(start 115.96497 -219.512642)
		(mid 115.964876 -219.50426)
		(end 115.96497 -219.495878)
		(width 0.0889)
		(layer "In2.Cu")
		(net "P5E_CPU1_PE1_TX_DN<3>")
	)
	(arc
		(start 115.96497 -222.773748)
		(mid 115.964725 -222.764352)
		(end 115.964716 -222.754952)
		(width 0.0889)
		(layer "In2.Cu")
		(net "P5E_CPU1_PE1_TX_DN<3>")
	)
	(arc
		(start 116.621814 -220.644212)
		(mid 116.486881 -220.510858)
		(end 116.434616 -220.32849)
		(width 0.0889)
		(layer "In2.Cu")
		(net "P5E_CPU1_PE1_TX_DN<3>")
	)
	(arc
		(start 116.434362 -215.436704)
		(mid 116.434414 -215.429337)
		(end 116.434616 -215.421972)
		(width 0.0889)
		(layer "In2.Cu")
		(net "P5E_CPU1_PE1_TX_DN<3>")
	)
	(arc
		(start 116.143278 -216.569798)
		(mid 116.014074 -216.436284)
		(end 115.96497 -216.257124)
		(width 0.0889)
		(layer "In2.Cu")
		(net "P5E_CPU1_PE1_TX_DN<3>")
	)
	(arc
		(start 116.434616 -220.309948)
		(mid 116.356505 -220.032999)
		(end 116.152168 -219.830396)
		(width 0.0889)
		(layer "In2.Cu")
		(net "P5E_CPU1_PE1_TX_DN<3>")
	)
	(arc
		(start 116.634006 -221.61627)
		(mid 116.832234 -221.410422)
		(end 116.904516 -221.133924)
		(width 0.0889)
		(layer "In2.Cu")
		(net "P5E_CPU1_PE1_TX_DN<3>")
	)
	(arc
		(start 116.62791 -218.364308)
		(mid 116.830497 -218.157957)
		(end 116.904516 -217.878406)
		(width 0.0889)
		(layer "In2.Cu")
		(net "P5E_CPU1_PE1_TX_DN<3>")
	)
	(arc
		(start 116.143278 -223.080834)
		(mid 116.015385 -222.949772)
		(end 115.96497 -222.773748)
		(width 0.0889)
		(layer "In2.Cu")
		(net "P5E_CPU1_PE1_TX_DN<3>")
	)
	(arc
		(start 116.904008 -214.424768)
		(mid 116.802379 -214.243564)
		(end 116.644928 -214.10803)
		(width 0.0889)
		(layer "In2.Cu")
		(net "P5E_CPU1_PE1_TX_DN<3>")
	)
	(arc
		(start 116.152168 -222.437198)
		(mid 116.356503 -222.234593)
		(end 116.434616 -221.957646)
		(width 0.0889)
		(layer "In2.Cu")
		(net "P5E_CPU1_PE1_TX_DN<3>")
	)
	(arc
		(start 116.904516 -221.126304)
		(mid 116.826887 -220.847891)
		(end 116.621814 -220.644212)
		(width 0.0889)
		(layer "In2.Cu")
		(net "P5E_CPU1_PE1_TX_DN<3>")
	)
	(arc
		(start 116.434616 -223.557084)
		(mid 116.354454 -223.284895)
		(end 116.152168 -223.085914)
		(width 0.0889)
		(layer "In2.Cu")
		(net "P5E_CPU1_PE1_TX_DN<3>")
	)
	(arc
		(start 116.143278 -219.825316)
		(mid 116.014074 -219.691802)
		(end 115.96497 -219.512642)
		(width 0.0889)
		(layer "In2.Cu")
		(net "P5E_CPU1_PE1_TX_DN<3>")
	)
	(arc
		(start 116.152168 -219.18168)
		(mid 116.354991 -218.981449)
		(end 116.434362 -218.707716)
		(width 0.0889)
		(layer "In2.Cu")
		(net "P5E_CPU1_PE1_TX_DN<3>")
	)
	(arc
		(start 116.621814 -217.388694)
		(mid 116.486881 -217.25534)
		(end 116.434616 -217.072972)
		(width 0.0889)
		(layer "In2.Cu")
		(net "P5E_CPU1_PE1_TX_DN<3>")
	)
	(arc
		(start 116.57457 -223.867472)
		(mid 116.473249 -223.741351)
		(end 116.434616 -223.584262)
		(width 0.0889)
		(layer "In2.Cu")
		(net "P5E_CPU1_PE1_TX_DN<3>")
	)
	(arc
		(start 116.434616 -221.939104)
		(mid 116.486886 -221.756739)
		(end 116.621814 -221.623382)
		(width 0.0889)
		(layer "In2.Cu")
		(net "P5E_CPU1_PE1_TX_DN<3>")
	)
	(arc
		(start 116.621814 -215.112346)
		(mid 116.823096 -214.914859)
		(end 116.904008 -214.644732)
		(width 0.0889)
		(layer "In2.Cu")
		(net "P5E_CPU1_PE1_TX_DN<3>")
	)
	(arc
		(start 115.96497 -216.257124)
		(mid 115.964876 -216.248742)
		(end 115.96497 -216.24036)
		(width 0.0889)
		(layer "In2.Cu")
		(net "P5E_CPU1_PE1_TX_DN<3>")
	)
	(arc
		(start 116.434616 -217.05443)
		(mid 116.356505 -216.777481)
		(end 116.152168 -216.574878)
		(width 0.0889)
		(layer "In2.Cu")
		(net "P5E_CPU1_PE1_TX_DN<3>")
	)
	(arc
		(start 116.904516 -217.864182)
		(mid 116.825297 -217.589497)
		(end 116.621814 -217.388694)
		(width 0.0889)
		(layer "In2.Cu")
		(net "P5E_CPU1_PE1_TX_DN<3>")
	)
	(arc
		(start 116.434616 -215.421972)
		(mid 116.48567 -215.247392)
		(end 116.612924 -215.117426)
		(width 0.0889)
		(layer "In2.Cu")
		(net "P5E_CPU1_PE1_TX_DN<3>")
	)
	(arc
		(start 115.964716 -222.754952)
		(mid 116.013969 -222.575752)
		(end 116.143278 -222.442278)
		(width 0.0889)
		(layer "In2.Cu")
		(net "P5E_CPU1_PE1_TX_DN<3>")
	)
	(arc
		(start 116.434362 -218.692222)
		(mid 116.482041 -218.509322)
		(end 116.612924 -218.372944)
		(width 0.0889)
		(layer "In2.Cu")
		(net "P5E_CPU1_PE1_TX_DN<3>")
	)
	(segment
		(start 52.49672 -18.216626)
		(end 52.17033 -17.890236)
		(width 0.13208)
		(layer "F.Cu")
		(net "P5E_CPU1_PE1_TX_DN<2>")
	)
	(segment
		(start 52.19573 -19.13636)
		(end 52.49672 -18.83537)
		(width 0.13208)
		(layer "F.Cu")
		(net "P5E_CPU1_PE1_TX_DN<2>")
	)
	(segment
		(start 117.279166 -224.925128)
		(end 117.279166 -224.389442)
		(width 0.13208)
		(layer "F.Cu")
		(net "P5E_CPU1_PE1_TX_DN<2>")
	)
	(segment
		(start 117.278912 -224.925382)
		(end 117.279166 -224.925128)
		(width 0.13208)
		(layer "F.Cu")
		(net "P5E_CPU1_PE1_TX_DN<2>")
	)
	(segment
		(start 52.49672 -18.83537)
		(end 52.49672 -18.216626)
		(width 0.13208)
		(layer "F.Cu")
		(net "P5E_CPU1_PE1_TX_DN<2>")
	)
	(segment
		(start 117.467888 -218.202002)
		(end 117.475254 -218.197684)
		(width 0.0889)
		(layer "In2.Cu")
		(net "P5E_CPU1_PE1_TX_DN<2>")
	)
	(segment
		(start 117.0051 -220.000576)
		(end 116.997226 -219.996004)
		(width 0.0889)
		(layer "In2.Cu")
		(net "P5E_CPU1_PE1_TX_DN<2>")
	)
	(segment
		(start 117.467126 -217.554556)
		(end 117.466364 -217.554048)
		(width 0.0889)
		(layer "In2.Cu")
		(net "P5E_CPU1_PE1_TX_DN<2>")
	)
	(segment
		(start 117.0051 -216.745058)
		(end 116.997226 -216.740486)
		(width 0.0889)
		(layer "In2.Cu")
		(net "P5E_CPU1_PE1_TX_DN<2>")
	)
	(segment
		(start 117.183662 -220.327474)
		(end 117.183662 -220.319854)
		(width 0.0889)
		(layer "In2.Cu")
		(net "P5E_CPU1_PE1_TX_DN<2>")
	)
	(segment
		(start 52.71135 -22.466554)
		(end 52.65547 -22.102064)
		(width 0.14732)
		(layer "In2.Cu")
		(net "P5E_CPU1_PE1_TX_DN<2>")
	)
	(segment
		(start 116.99621 -215.761062)
		(end 117.0051 -215.755982)
		(width 0.0889)
		(layer "In2.Cu")
		(net "P5E_CPU1_PE1_TX_DN<2>")
	)
	(segment
		(start 117.279166 -224.389442)
		(end 117.43563 -224.66046)
		(width 0.0889)
		(layer "In2.Cu")
		(net "P5E_CPU1_PE1_TX_DN<2>")
	)
	(segment
		(start 117.466364 -221.458282)
		(end 117.467888 -221.45752)
		(width 0.0889)
		(layer "In2.Cu")
		(net "P5E_CPU1_PE1_TX_DN<2>")
	)
	(segment
		(start 117.467888 -221.45752)
		(end 117.475254 -221.453202)
		(width 0.0889)
		(layer "In2.Cu")
		(net "P5E_CPU1_PE1_TX_DN<2>")
	)
	(segment
		(start 113.537238 -187.864496)
		(end 112.427512 -184.048654)
		(width 0.14732)
		(layer "In2.Cu")
		(net "P5E_CPU1_PE1_TX_DN<2>")
	)
	(segment
		(start 117.466364 -218.202764)
		(end 117.467888 -218.202002)
		(width 0.0889)
		(layer "In2.Cu")
		(net "P5E_CPU1_PE1_TX_DN<2>")
	)
	(segment
		(start 52.49037 -19.431)
		(end 52.19573 -19.13636)
		(width 0.14732)
		(layer "In2.Cu")
		(net "P5E_CPU1_PE1_TX_DN<2>")
	)
	(segment
		(start 117.183662 -217.071956)
		(end 117.183662 -217.064336)
		(width 0.0889)
		(layer "In2.Cu")
		(net "P5E_CPU1_PE1_TX_DN<2>")
	)
	(segment
		(start 117.466364 -224.065084)
		(end 117.462554 -224.062798)
		(width 0.0889)
		(layer "In2.Cu")
		(net "P5E_CPU1_PE1_TX_DN<2>")
	)
	(segment
		(start 117.475254 -220.814646)
		(end 117.467126 -220.810074)
		(width 0.0889)
		(layer "In2.Cu")
		(net "P5E_CPU1_PE1_TX_DN<2>")
	)
	(segment
		(start 76.691236 -90.847164)
		(end 56.62168 -47.075344)
		(width 0.14732)
		(layer "In2.Cu")
		(net "P5E_CPU1_PE1_TX_DN<2>")
	)
	(segment
		(start 117.0051 -223.256348)
		(end 116.99621 -223.251268)
		(width 0.0889)
		(layer "In2.Cu")
		(net "P5E_CPU1_PE1_TX_DN<2>")
	)
	(segment
		(start 117.184424 -213.78799)
		(end 117.184424 -213.284562)
		(width 0.0889)
		(layer "In2.Cu")
		(net "P5E_CPU1_PE1_TX_DN<2>")
	)
	(segment
		(start 117.183662 -215.436704)
		(end 117.183662 -215.414606)
		(width 0.0889)
		(layer "In2.Cu")
		(net "P5E_CPU1_PE1_TX_DN<2>")
	)
	(segment
		(start 116.997226 -216.740486)
		(end 116.99621 -216.739978)
		(width 0.0889)
		(layer "In2.Cu")
		(net "P5E_CPU1_PE1_TX_DN<2>")
	)
	(segment
		(start 116.714016 -216.266014)
		(end 116.714016 -216.235026)
		(width 0.0889)
		(layer "In2.Cu")
		(net "P5E_CPU1_PE1_TX_DN<2>")
	)
	(segment
		(start 116.99621 -222.272098)
		(end 117.0051 -222.267018)
		(width 0.0889)
		(layer "In2.Cu")
		(net "P5E_CPU1_PE1_TX_DN<2>")
	)
	(segment
		(start 117.475254 -224.070164)
		(end 117.466364 -224.065084)
		(width 0.0889)
		(layer "In2.Cu")
		(net "P5E_CPU1_PE1_TX_DN<2>")
	)
	(segment
		(start 117.475254 -217.559128)
		(end 117.467126 -217.554556)
		(width 0.0889)
		(layer "In2.Cu")
		(net "P5E_CPU1_PE1_TX_DN<2>")
	)
	(segment
		(start 116.714016 -222.783654)
		(end 116.714016 -222.746062)
		(width 0.0889)
		(layer "In2.Cu")
		(net "P5E_CPU1_PE1_TX_DN<2>")
	)
	(segment
		(start 112.427512 -184.048654)
		(end 76.691236 -90.847164)
		(width 0.14732)
		(layer "In2.Cu")
		(net "P5E_CPU1_PE1_TX_DN<2>")
	)
	(segment
		(start 117.142514 -213.220554)
		(end 117.142514 -209.937604)
		(width 0.14732)
		(layer "In2.Cu")
		(net "P5E_CPU1_PE1_TX_DN<2>")
	)
	(segment
		(start 117.653562 -214.62238)
		(end 117.653562 -214.460328)
		(width 0.0889)
		(layer "In2.Cu")
		(net "P5E_CPU1_PE1_TX_DN<2>")
	)
	(segment
		(start 52.65547 -22.102064)
		(end 52.776882 -21.937218)
		(width 0.14732)
		(layer "In2.Cu")
		(net "P5E_CPU1_PE1_TX_DN<2>")
	)
	(segment
		(start 52.49037 -20.063714)
		(end 52.49037 -19.431)
		(width 0.14732)
		(layer "In2.Cu")
		(net "P5E_CPU1_PE1_TX_DN<2>")
	)
	(segment
		(start 52.876196 -22.587458)
		(end 52.71135 -22.466554)
		(width 0.14732)
		(layer "In2.Cu")
		(net "P5E_CPU1_PE1_TX_DN<2>")
	)
	(segment
		(start 116.99621 -219.01658)
		(end 117.0051 -219.0115)
		(width 0.0889)
		(layer "In2.Cu")
		(net "P5E_CPU1_PE1_TX_DN<2>")
	)
	(segment
		(start 52.556156 -21.452078)
		(end 52.50053 -21.087588)
		(width 0.14732)
		(layer "In2.Cu")
		(net "P5E_CPU1_PE1_TX_DN<2>")
	)
	(segment
		(start 117.460268 -221.461838)
		(end 117.465602 -221.45879)
		(width 0.0889)
		(layer "In2.Cu")
		(net "P5E_CPU1_PE1_TX_DN<2>")
	)
	(segment
		(start 117.465856 -214.946992)
		(end 117.474746 -214.941912)
		(width 0.0889)
		(layer "In2.Cu")
		(net "P5E_CPU1_PE1_TX_DN<2>")
	)
	(segment
		(start 117.653308 -214.622634)
		(end 117.653562 -214.62238)
		(width 0.0889)
		(layer "In2.Cu")
		(net "P5E_CPU1_PE1_TX_DN<2>")
	)
	(segment
		(start 52.776882 -21.937218)
		(end 52.721256 -21.573236)
		(width 0.14732)
		(layer "In2.Cu")
		(net "P5E_CPU1_PE1_TX_DN<2>")
	)
	(segment
		(start 117.465602 -221.45879)
		(end 117.466364 -221.458282)
		(width 0.0889)
		(layer "In2.Cu")
		(net "P5E_CPU1_PE1_TX_DN<2>")
	)
	(segment
		(start 117.467126 -220.810074)
		(end 117.466364 -220.809566)
		(width 0.0889)
		(layer "In2.Cu")
		(net "P5E_CPU1_PE1_TX_DN<2>")
	)
	(segment
		(start 117.460268 -218.20632)
		(end 117.465602 -218.203272)
		(width 0.0889)
		(layer "In2.Cu")
		(net "P5E_CPU1_PE1_TX_DN<2>")
	)
	(segment
		(start 117.142514 -213.242652)
		(end 117.142514 -213.220554)
		(width 0.0889)
		(layer "In2.Cu")
		(net "P5E_CPU1_PE1_TX_DN<2>")
	)
	(segment
		(start 52.721256 -21.573236)
		(end 52.556156 -21.452078)
		(width 0.14732)
		(layer "In2.Cu")
		(net "P5E_CPU1_PE1_TX_DN<2>")
	)
	(segment
		(start 52.621688 -20.922742)
		(end 52.49037 -20.063714)
		(width 0.14732)
		(layer "In2.Cu")
		(net "P5E_CPU1_PE1_TX_DN<2>")
	)
	(segment
		(start 117.142514 -209.937604)
		(end 113.537238 -187.864496)
		(width 0.14732)
		(layer "In2.Cu")
		(net "P5E_CPU1_PE1_TX_DN<2>")
	)
	(segment
		(start 52.50053 -21.087588)
		(end 52.621688 -20.922742)
		(width 0.14732)
		(layer "In2.Cu")
		(net "P5E_CPU1_PE1_TX_DN<2>")
	)
	(segment
		(start 117.43563 -224.66046)
		(end 117.513862 -224.681288)
		(width 0.0889)
		(layer "In2.Cu")
		(net "P5E_CPU1_PE1_TX_DN<2>")
	)
	(segment
		(start 116.714016 -219.521532)
		(end 116.714016 -219.490544)
		(width 0.0889)
		(layer "In2.Cu")
		(net "P5E_CPU1_PE1_TX_DN<2>")
	)
	(segment
		(start 56.62168 -47.075344)
		(end 52.876196 -22.587458)
		(width 0.14732)
		(layer "In2.Cu")
		(net "P5E_CPU1_PE1_TX_DN<2>")
	)
	(segment
		(start 117.184424 -213.284562)
		(end 117.142514 -213.242652)
		(width 0.0889)
		(layer "In2.Cu")
		(net "P5E_CPU1_PE1_TX_DN<2>")
	)
	(segment
		(start 116.997226 -219.996004)
		(end 116.99621 -219.995496)
		(width 0.0889)
		(layer "In2.Cu")
		(net "P5E_CPU1_PE1_TX_DN<2>")
	)
	(segment
		(start 117.462554 -224.062798)
		(end 117.454172 -224.057972)
		(width 0.0889)
		(layer "In2.Cu")
		(net "P5E_CPU1_PE1_TX_DN<2>")
	)
	(segment
		(start 117.465602 -218.203272)
		(end 117.466364 -218.202764)
		(width 0.0889)
		(layer "In2.Cu")
		(net "P5E_CPU1_PE1_TX_DN<2>")
	)
	(arc
		(start 117.183662 -217.064336)
		(mid 117.135983 -216.881436)
		(end 117.0051 -216.745058)
		(width 0.0889)
		(layer "In2.Cu")
		(net "P5E_CPU1_PE1_TX_DN<2>")
	)
	(arc
		(start 117.0051 -219.0115)
		(mid 117.136014 -218.87514)
		(end 117.183662 -218.692222)
		(width 0.0889)
		(layer "In2.Cu")
		(net "P5E_CPU1_PE1_TX_DN<2>")
	)
	(arc
		(start 116.99621 -216.739978)
		(mid 116.793387 -216.539747)
		(end 116.714016 -216.266014)
		(width 0.0889)
		(layer "In2.Cu")
		(net "P5E_CPU1_PE1_TX_DN<2>")
	)
	(arc
		(start 117.653054 -214.637366)
		(mid 117.653251 -214.630001)
		(end 117.653308 -214.622634)
		(width 0.0889)
		(layer "In2.Cu")
		(net "P5E_CPU1_PE1_TX_DN<2>")
	)
	(arc
		(start 117.183662 -223.575626)
		(mid 117.135983 -223.392726)
		(end 117.0051 -223.256348)
		(width 0.0889)
		(layer "In2.Cu")
		(net "P5E_CPU1_PE1_TX_DN<2>")
	)
	(arc
		(start 117.474746 -214.941912)
		(mid 117.602 -214.811946)
		(end 117.653054 -214.637366)
		(width 0.0889)
		(layer "In2.Cu")
		(net "P5E_CPU1_PE1_TX_DN<2>")
	)
	(arc
		(start 117.454172 -224.057972)
		(mid 117.255944 -223.852124)
		(end 117.183662 -223.575626)
		(width 0.0889)
		(layer "In2.Cu")
		(net "P5E_CPU1_PE1_TX_DN<2>")
	)
	(arc
		(start 117.469666 -214.261954)
		(mid 117.261069 -214.064668)
		(end 117.184424 -213.78799)
		(width 0.0889)
		(layer "In2.Cu")
		(net "P5E_CPU1_PE1_TX_DN<2>")
	)
	(arc
		(start 117.513862 -224.681288)
		(mid 117.617007 -224.551263)
		(end 117.653816 -224.389442)
		(width 0.0889)
		(layer "In2.Cu")
		(net "P5E_CPU1_PE1_TX_DN<2>")
	)
	(arc
		(start 117.0051 -222.267018)
		(mid 117.136014 -222.130658)
		(end 117.183662 -221.94774)
		(width 0.0889)
		(layer "In2.Cu")
		(net "P5E_CPU1_PE1_TX_DN<2>")
	)
	(arc
		(start 116.99621 -223.251268)
		(mid 116.794928 -223.053781)
		(end 116.714016 -222.783654)
		(width 0.0889)
		(layer "In2.Cu")
		(net "P5E_CPU1_PE1_TX_DN<2>")
	)
	(arc
		(start 116.714016 -222.746062)
		(mid 116.793386 -222.472328)
		(end 116.99621 -222.272098)
		(width 0.0889)
		(layer "In2.Cu")
		(net "P5E_CPU1_PE1_TX_DN<2>")
	)
	(arc
		(start 116.714016 -219.490544)
		(mid 116.793386 -219.21681)
		(end 116.99621 -219.01658)
		(width 0.0889)
		(layer "In2.Cu")
		(net "P5E_CPU1_PE1_TX_DN<2>")
	)
	(arc
		(start 117.183662 -221.94774)
		(mid 117.257653 -221.668174)
		(end 117.460268 -221.461838)
		(width 0.0889)
		(layer "In2.Cu")
		(net "P5E_CPU1_PE1_TX_DN<2>")
	)
	(arc
		(start 117.653562 -214.460328)
		(mid 117.578521 -214.345464)
		(end 117.469666 -214.261954)
		(width 0.0889)
		(layer "In2.Cu")
		(net "P5E_CPU1_PE1_TX_DN<2>")
	)
	(arc
		(start 117.183662 -215.414606)
		(mid 117.264573 -215.144478)
		(end 117.465856 -214.946992)
		(width 0.0889)
		(layer "In2.Cu")
		(net "P5E_CPU1_PE1_TX_DN<2>")
	)
	(arc
		(start 116.99621 -219.995496)
		(mid 116.793387 -219.795265)
		(end 116.714016 -219.521532)
		(width 0.0889)
		(layer "In2.Cu")
		(net "P5E_CPU1_PE1_TX_DN<2>")
	)
	(arc
		(start 117.466364 -220.809566)
		(mid 117.261292 -220.605887)
		(end 117.183662 -220.327474)
		(width 0.0889)
		(layer "In2.Cu")
		(net "P5E_CPU1_PE1_TX_DN<2>")
	)
	(arc
		(start 117.475254 -221.453202)
		(mid 117.653851 -221.133924)
		(end 117.475254 -220.814646)
		(width 0.0889)
		(layer "In2.Cu")
		(net "P5E_CPU1_PE1_TX_DN<2>")
	)
	(arc
		(start 117.466364 -217.554048)
		(mid 117.261292 -217.350369)
		(end 117.183662 -217.071956)
		(width 0.0889)
		(layer "In2.Cu")
		(net "P5E_CPU1_PE1_TX_DN<2>")
	)
	(arc
		(start 117.0051 -215.755982)
		(mid 117.136014 -215.619622)
		(end 117.183662 -215.436704)
		(width 0.0889)
		(layer "In2.Cu")
		(net "P5E_CPU1_PE1_TX_DN<2>")
	)
	(arc
		(start 117.183662 -218.692222)
		(mid 117.257653 -218.412656)
		(end 117.460268 -218.20632)
		(width 0.0889)
		(layer "In2.Cu")
		(net "P5E_CPU1_PE1_TX_DN<2>")
	)
	(arc
		(start 117.653816 -224.389442)
		(mid 117.606137 -224.206542)
		(end 117.475254 -224.070164)
		(width 0.0889)
		(layer "In2.Cu")
		(net "P5E_CPU1_PE1_TX_DN<2>")
	)
	(arc
		(start 117.183662 -220.319854)
		(mid 117.135983 -220.136954)
		(end 117.0051 -220.000576)
		(width 0.0889)
		(layer "In2.Cu")
		(net "P5E_CPU1_PE1_TX_DN<2>")
	)
	(arc
		(start 116.714016 -216.235026)
		(mid 116.793386 -215.961292)
		(end 116.99621 -215.761062)
		(width 0.0889)
		(layer "In2.Cu")
		(net "P5E_CPU1_PE1_TX_DN<2>")
	)
	(arc
		(start 117.475254 -218.197684)
		(mid 117.653851 -217.878406)
		(end 117.475254 -217.559128)
		(width 0.0889)
		(layer "In2.Cu")
		(net "P5E_CPU1_PE1_TX_DN<2>")
	)
	(segment
		(start 118.688866 -223.57588)
		(end 118.688612 -223.575626)
		(width 0.13208)
		(layer "F.Cu")
		(net "P5E_CPU1_PE1_TX_DN<1>")
	)
	(segment
		(start 55.85333 -17.61236)
		(end 55.5498 -17.30883)
		(width 0.13208)
		(layer "F.Cu")
		(net "P5E_CPU1_PE1_TX_DN<1>")
	)
	(segment
		(start 118.688866 -224.111566)
		(end 118.688866 -223.57588)
		(width 0.13208)
		(layer "F.Cu")
		(net "P5E_CPU1_PE1_TX_DN<1>")
	)
	(segment
		(start 55.5498 -16.695166)
		(end 55.87873 -16.366236)
		(width 0.13208)
		(layer "F.Cu")
		(net "P5E_CPU1_PE1_TX_DN<1>")
	)
	(segment
		(start 55.5498 -17.30883)
		(end 55.5498 -16.695166)
		(width 0.13208)
		(layer "F.Cu")
		(net "P5E_CPU1_PE1_TX_DN<1>")
	)
	(segment
		(start 118.52402 -214.107776)
		(end 118.313962 -213.897718)
		(width 0.0889)
		(layer "In2.Cu")
		(net "P5E_CPU1_PE1_TX_DN<1>")
	)
	(segment
		(start 118.314216 -217.072972)
		(end 118.314216 -217.05443)
		(width 0.0889)
		(layer "In2.Cu")
		(net "P5E_CPU1_PE1_TX_DN<1>")
	)
	(segment
		(start 55.747666 -19.975322)
		(end 55.590694 -19.84375)
		(width 0.14732)
		(layer "In2.Cu")
		(net "P5E_CPU1_PE1_TX_DN<1>")
	)
	(segment
		(start 118.524528 -214.10803)
		(end 118.52402 -214.107776)
		(width 0.0889)
		(layer "In2.Cu")
		(net "P5E_CPU1_PE1_TX_DN<1>")
	)
	(segment
		(start 118.314216 -223.584262)
		(end 118.314216 -223.557084)
		(width 0.0889)
		(layer "In2.Cu")
		(net "P5E_CPU1_PE1_TX_DN<1>")
	)
	(segment
		(start 118.313962 -215.452198)
		(end 118.313962 -215.436704)
		(width 0.0889)
		(layer "In2.Cu")
		(net "P5E_CPU1_PE1_TX_DN<1>")
	)
	(segment
		(start 118.492524 -218.372944)
		(end 118.49989 -218.368626)
		(width 0.0889)
		(layer "In2.Cu")
		(net "P5E_CPU1_PE1_TX_DN<1>")
	)
	(segment
		(start 118.022878 -215.931242)
		(end 118.031768 -215.926162)
		(width 0.0889)
		(layer "In2.Cu")
		(net "P5E_CPU1_PE1_TX_DN<1>")
	)
	(segment
		(start 118.313962 -218.707716)
		(end 118.313962 -218.692222)
		(width 0.0889)
		(layer "In2.Cu")
		(net "P5E_CPU1_PE1_TX_DN<1>")
	)
	(segment
		(start 114.736626 -187.571888)
		(end 113.705132 -184.017158)
		(width 0.14732)
		(layer "In2.Cu")
		(net "P5E_CPU1_PE1_TX_DN<1>")
	)
	(segment
		(start 55.779924 -20.342606)
		(end 55.747666 -19.975322)
		(width 0.14732)
		(layer "In2.Cu")
		(net "P5E_CPU1_PE1_TX_DN<1>")
	)
	(segment
		(start 118.314216 -221.957646)
		(end 118.314216 -221.939104)
		(width 0.0889)
		(layer "In2.Cu")
		(net "P5E_CPU1_PE1_TX_DN<1>")
	)
	(segment
		(start 55.648352 -20.499324)
		(end 55.779924 -20.342606)
		(width 0.14732)
		(layer "In2.Cu")
		(net "P5E_CPU1_PE1_TX_DN<1>")
	)
	(segment
		(start 118.022878 -222.442278)
		(end 118.031768 -222.437198)
		(width 0.0889)
		(layer "In2.Cu")
		(net "P5E_CPU1_PE1_TX_DN<1>")
	)
	(segment
		(start 118.688612 -223.575626)
		(end 118.532148 -223.846644)
		(width 0.0889)
		(layer "In2.Cu")
		(net "P5E_CPU1_PE1_TX_DN<1>")
	)
	(segment
		(start 118.031768 -219.830396)
		(end 118.022878 -219.825316)
		(width 0.0889)
		(layer "In2.Cu")
		(net "P5E_CPU1_PE1_TX_DN<1>")
	)
	(segment
		(start 118.022878 -219.18676)
		(end 118.031768 -219.18168)
		(width 0.0889)
		(layer "In2.Cu")
		(net "P5E_CPU1_PE1_TX_DN<1>")
	)
	(segment
		(start 118.501414 -221.623382)
		(end 118.513606 -221.61627)
		(width 0.0889)
		(layer "In2.Cu")
		(net "P5E_CPU1_PE1_TX_DN<1>")
	)
	(segment
		(start 118.356126 -213.2203)
		(end 118.356126 -209.733388)
		(width 0.14732)
		(layer "In2.Cu")
		(net "P5E_CPU1_PE1_TX_DN<1>")
	)
	(segment
		(start 118.313962 -213.897718)
		(end 118.313962 -213.284562)
		(width 0.0889)
		(layer "In2.Cu")
		(net "P5E_CPU1_PE1_TX_DN<1>")
	)
	(segment
		(start 118.783608 -214.644732)
		(end 118.783608 -214.424768)
		(width 0.0889)
		(layer "In2.Cu")
		(net "P5E_CPU1_PE1_TX_DN<1>")
	)
	(segment
		(start 55.590694 -19.84375)
		(end 55.55869 -19.476974)
		(width 0.14732)
		(layer "In2.Cu")
		(net "P5E_CPU1_PE1_TX_DN<1>")
	)
	(segment
		(start 113.705132 -184.017158)
		(end 77.480668 -89.517982)
		(width 0.14732)
		(layer "In2.Cu")
		(net "P5E_CPU1_PE1_TX_DN<1>")
	)
	(segment
		(start 118.356126 -213.242398)
		(end 118.356126 -213.2203)
		(width 0.0889)
		(layer "In2.Cu")
		(net "P5E_CPU1_PE1_TX_DN<1>")
	)
	(segment
		(start 118.492524 -215.117426)
		(end 118.501414 -215.112346)
		(width 0.0889)
		(layer "In2.Cu")
		(net "P5E_CPU1_PE1_TX_DN<1>")
	)
	(segment
		(start 118.031768 -223.085914)
		(end 118.022878 -223.080834)
		(width 0.0889)
		(layer "In2.Cu")
		(net "P5E_CPU1_PE1_TX_DN<1>")
	)
	(segment
		(start 118.784116 -221.133924)
		(end 118.784116 -221.126304)
		(width 0.0889)
		(layer "In2.Cu")
		(net "P5E_CPU1_PE1_TX_DN<1>")
	)
	(segment
		(start 55.680356 -20.8661)
		(end 55.648352 -20.499324)
		(width 0.14732)
		(layer "In2.Cu")
		(net "P5E_CPU1_PE1_TX_DN<1>")
	)
	(segment
		(start 55.55869 -19.476974)
		(end 55.55869 -17.907)
		(width 0.14732)
		(layer "In2.Cu")
		(net "P5E_CPU1_PE1_TX_DN<1>")
	)
	(segment
		(start 55.837328 -20.997672)
		(end 55.680356 -20.8661)
		(width 0.14732)
		(layer "In2.Cu")
		(net "P5E_CPU1_PE1_TX_DN<1>")
	)
	(segment
		(start 118.502176 -218.367356)
		(end 118.50751 -218.364308)
		(width 0.0889)
		(layer "In2.Cu")
		(net "P5E_CPU1_PE1_TX_DN<1>")
	)
	(segment
		(start 77.480668 -89.517982)
		(end 57.962546 -46.950122)
		(width 0.14732)
		(layer "In2.Cu")
		(net "P5E_CPU1_PE1_TX_DN<1>")
	)
	(segment
		(start 118.501414 -218.367864)
		(end 118.502176 -218.367356)
		(width 0.0889)
		(layer "In2.Cu")
		(net "P5E_CPU1_PE1_TX_DN<1>")
	)
	(segment
		(start 118.313962 -213.284562)
		(end 118.356126 -213.242398)
		(width 0.0889)
		(layer "In2.Cu")
		(net "P5E_CPU1_PE1_TX_DN<1>")
	)
	(segment
		(start 118.031768 -216.574878)
		(end 118.022878 -216.569798)
		(width 0.0889)
		(layer "In2.Cu")
		(net "P5E_CPU1_PE1_TX_DN<1>")
	)
	(segment
		(start 57.962546 -46.950122)
		(end 55.738014 -21.521674)
		(width 0.14732)
		(layer "In2.Cu")
		(net "P5E_CPU1_PE1_TX_DN<1>")
	)
	(segment
		(start 118.49989 -218.368626)
		(end 118.501414 -218.367864)
		(width 0.0889)
		(layer "In2.Cu")
		(net "P5E_CPU1_PE1_TX_DN<1>")
	)
	(segment
		(start 55.738014 -21.521674)
		(end 55.869586 -21.364956)
		(width 0.14732)
		(layer "In2.Cu")
		(net "P5E_CPU1_PE1_TX_DN<1>")
	)
	(segment
		(start 118.356126 -209.733388)
		(end 114.736626 -187.571888)
		(width 0.14732)
		(layer "In2.Cu")
		(net "P5E_CPU1_PE1_TX_DN<1>")
	)
	(segment
		(start 118.784116 -217.878406)
		(end 118.784116 -217.864182)
		(width 0.0889)
		(layer "In2.Cu")
		(net "P5E_CPU1_PE1_TX_DN<1>")
	)
	(segment
		(start 118.532148 -223.846644)
		(end 118.45417 -223.867472)
		(width 0.0889)
		(layer "In2.Cu")
		(net "P5E_CPU1_PE1_TX_DN<1>")
	)
	(segment
		(start 55.869586 -21.364956)
		(end 55.837328 -20.997672)
		(width 0.14732)
		(layer "In2.Cu")
		(net "P5E_CPU1_PE1_TX_DN<1>")
	)
	(segment
		(start 55.55869 -17.907)
		(end 55.85333 -17.61236)
		(width 0.14732)
		(layer "In2.Cu")
		(net "P5E_CPU1_PE1_TX_DN<1>")
	)
	(segment
		(start 118.314216 -220.32849)
		(end 118.314216 -220.309948)
		(width 0.0889)
		(layer "In2.Cu")
		(net "P5E_CPU1_PE1_TX_DN<1>")
	)
	(arc
		(start 118.031768 -222.437198)
		(mid 118.236103 -222.234593)
		(end 118.314216 -221.957646)
		(width 0.0889)
		(layer "In2.Cu")
		(net "P5E_CPU1_PE1_TX_DN<1>")
	)
	(arc
		(start 117.84457 -222.773748)
		(mid 117.844325 -222.764352)
		(end 117.844316 -222.754952)
		(width 0.0889)
		(layer "In2.Cu")
		(net "P5E_CPU1_PE1_TX_DN<1>")
	)
	(arc
		(start 118.313962 -218.692222)
		(mid 118.361641 -218.509322)
		(end 118.492524 -218.372944)
		(width 0.0889)
		(layer "In2.Cu")
		(net "P5E_CPU1_PE1_TX_DN<1>")
	)
	(arc
		(start 118.783608 -214.424768)
		(mid 118.681979 -214.243564)
		(end 118.524528 -214.10803)
		(width 0.0889)
		(layer "In2.Cu")
		(net "P5E_CPU1_PE1_TX_DN<1>")
	)
	(arc
		(start 117.844316 -222.754952)
		(mid 117.893569 -222.575752)
		(end 118.022878 -222.442278)
		(width 0.0889)
		(layer "In2.Cu")
		(net "P5E_CPU1_PE1_TX_DN<1>")
	)
	(arc
		(start 118.314216 -221.939104)
		(mid 118.366486 -221.756739)
		(end 118.501414 -221.623382)
		(width 0.0889)
		(layer "In2.Cu")
		(net "P5E_CPU1_PE1_TX_DN<1>")
	)
	(arc
		(start 118.314216 -220.309948)
		(mid 118.236105 -220.032999)
		(end 118.031768 -219.830396)
		(width 0.0889)
		(layer "In2.Cu")
		(net "P5E_CPU1_PE1_TX_DN<1>")
	)
	(arc
		(start 118.314216 -223.557084)
		(mid 118.234054 -223.284895)
		(end 118.031768 -223.085914)
		(width 0.0889)
		(layer "In2.Cu")
		(net "P5E_CPU1_PE1_TX_DN<1>")
	)
	(arc
		(start 118.022878 -219.825316)
		(mid 117.893674 -219.691802)
		(end 117.84457 -219.512642)
		(width 0.0889)
		(layer "In2.Cu")
		(net "P5E_CPU1_PE1_TX_DN<1>")
	)
	(arc
		(start 118.784116 -221.126304)
		(mid 118.706487 -220.847891)
		(end 118.501414 -220.644212)
		(width 0.0889)
		(layer "In2.Cu")
		(net "P5E_CPU1_PE1_TX_DN<1>")
	)
	(arc
		(start 118.314216 -217.05443)
		(mid 118.236105 -216.777481)
		(end 118.031768 -216.574878)
		(width 0.0889)
		(layer "In2.Cu")
		(net "P5E_CPU1_PE1_TX_DN<1>")
	)
	(arc
		(start 118.501414 -217.388694)
		(mid 118.366481 -217.25534)
		(end 118.314216 -217.072972)
		(width 0.0889)
		(layer "In2.Cu")
		(net "P5E_CPU1_PE1_TX_DN<1>")
	)
	(arc
		(start 117.84457 -216.24036)
		(mid 117.894585 -216.063229)
		(end 118.022878 -215.931242)
		(width 0.0889)
		(layer "In2.Cu")
		(net "P5E_CPU1_PE1_TX_DN<1>")
	)
	(arc
		(start 118.314216 -215.421972)
		(mid 118.36527 -215.247392)
		(end 118.492524 -215.117426)
		(width 0.0889)
		(layer "In2.Cu")
		(net "P5E_CPU1_PE1_TX_DN<1>")
	)
	(arc
		(start 118.022878 -223.080834)
		(mid 117.894985 -222.949772)
		(end 117.84457 -222.773748)
		(width 0.0889)
		(layer "In2.Cu")
		(net "P5E_CPU1_PE1_TX_DN<1>")
	)
	(arc
		(start 118.031768 -219.18168)
		(mid 118.234591 -218.981449)
		(end 118.313962 -218.707716)
		(width 0.0889)
		(layer "In2.Cu")
		(net "P5E_CPU1_PE1_TX_DN<1>")
	)
	(arc
		(start 117.84457 -219.512642)
		(mid 117.844476 -219.50426)
		(end 117.84457 -219.495878)
		(width 0.0889)
		(layer "In2.Cu")
		(net "P5E_CPU1_PE1_TX_DN<1>")
	)
	(arc
		(start 118.50751 -218.364308)
		(mid 118.710097 -218.157957)
		(end 118.784116 -217.878406)
		(width 0.0889)
		(layer "In2.Cu")
		(net "P5E_CPU1_PE1_TX_DN<1>")
	)
	(arc
		(start 118.513606 -221.61627)
		(mid 118.711834 -221.410422)
		(end 118.784116 -221.133924)
		(width 0.0889)
		(layer "In2.Cu")
		(net "P5E_CPU1_PE1_TX_DN<1>")
	)
	(arc
		(start 118.501414 -215.112346)
		(mid 118.702696 -214.914859)
		(end 118.783608 -214.644732)
		(width 0.0889)
		(layer "In2.Cu")
		(net "P5E_CPU1_PE1_TX_DN<1>")
	)
	(arc
		(start 118.501414 -220.644212)
		(mid 118.366481 -220.510858)
		(end 118.314216 -220.32849)
		(width 0.0889)
		(layer "In2.Cu")
		(net "P5E_CPU1_PE1_TX_DN<1>")
	)
	(arc
		(start 118.45417 -223.867472)
		(mid 118.352849 -223.741351)
		(end 118.314216 -223.584262)
		(width 0.0889)
		(layer "In2.Cu")
		(net "P5E_CPU1_PE1_TX_DN<1>")
	)
	(arc
		(start 118.313962 -215.436704)
		(mid 118.314014 -215.429337)
		(end 118.314216 -215.421972)
		(width 0.0889)
		(layer "In2.Cu")
		(net "P5E_CPU1_PE1_TX_DN<1>")
	)
	(arc
		(start 117.84457 -216.257124)
		(mid 117.844476 -216.248742)
		(end 117.84457 -216.24036)
		(width 0.0889)
		(layer "In2.Cu")
		(net "P5E_CPU1_PE1_TX_DN<1>")
	)
	(arc
		(start 118.031768 -215.926162)
		(mid 118.234591 -215.725931)
		(end 118.313962 -215.452198)
		(width 0.0889)
		(layer "In2.Cu")
		(net "P5E_CPU1_PE1_TX_DN<1>")
	)
	(arc
		(start 117.84457 -219.495878)
		(mid 117.894585 -219.318747)
		(end 118.022878 -219.18676)
		(width 0.0889)
		(layer "In2.Cu")
		(net "P5E_CPU1_PE1_TX_DN<1>")
	)
	(arc
		(start 118.784116 -217.864182)
		(mid 118.704897 -217.589497)
		(end 118.501414 -217.388694)
		(width 0.0889)
		(layer "In2.Cu")
		(net "P5E_CPU1_PE1_TX_DN<1>")
	)
	(arc
		(start 118.022878 -216.569798)
		(mid 117.893674 -216.436284)
		(end 117.84457 -216.257124)
		(width 0.0889)
		(layer "In2.Cu")
		(net "P5E_CPU1_PE1_TX_DN<1>")
	)
	(segment
		(start 16.397478 -17.61236)
		(end 16.093948 -17.30883)
		(width 0.13208)
		(layer "F.Cu")
		(net "P5E_CPU1_PE1_TX_DN<15>")
	)
	(segment
		(start 105.531412 -224.111312)
		(end 105.531412 -223.575626)
		(width 0.13208)
		(layer "F.Cu")
		(net "P5E_CPU1_PE1_TX_DN<15>")
	)
	(segment
		(start 105.531666 -224.111566)
		(end 105.531412 -224.111312)
		(width 0.13208)
		(layer "F.Cu")
		(net "P5E_CPU1_PE1_TX_DN<15>")
	)
	(segment
		(start 16.093948 -16.695166)
		(end 16.422878 -16.366236)
		(width 0.13208)
		(layer "F.Cu")
		(net "P5E_CPU1_PE1_TX_DN<15>")
	)
	(segment
		(start 16.093948 -17.30883)
		(end 16.093948 -16.695166)
		(width 0.13208)
		(layer "F.Cu")
		(net "P5E_CPU1_PE1_TX_DN<15>")
	)
	(segment
		(start 105.156762 -221.963234)
		(end 105.156762 -221.94774)
		(width 0.0889)
		(layer "In2.Cu")
		(net "P5E_CPU1_PE1_TX_DN<15>")
	)
	(segment
		(start 17.049242 -19.808444)
		(end 17.072864 -19.60499)
		(width 0.14732)
		(layer "In2.Cu")
		(net "P5E_CPU1_PE1_TX_DN<15>")
	)
	(segment
		(start 16.102838 -17.907)
		(end 16.397478 -17.61236)
		(width 0.14732)
		(layer "In2.Cu")
		(net "P5E_CPU1_PE1_TX_DN<15>")
	)
	(segment
		(start 105.531412 -223.575626)
		(end 105.374948 -223.846644)
		(width 0.0889)
		(layer "In2.Cu")
		(net "P5E_CPU1_PE1_TX_DN<15>")
	)
	(segment
		(start 105.344214 -221.623382)
		(end 105.344976 -221.622874)
		(width 0.0889)
		(layer "In2.Cu")
		(net "P5E_CPU1_PE1_TX_DN<15>")
	)
	(segment
		(start 105.157016 -217.082878)
		(end 105.157016 -217.05443)
		(width 0.0889)
		(layer "In2.Cu")
		(net "P5E_CPU1_PE1_TX_DN<15>")
	)
	(segment
		(start 105.156762 -218.707716)
		(end 105.156762 -218.676728)
		(width 0.0889)
		(layer "In2.Cu")
		(net "P5E_CPU1_PE1_TX_DN<15>")
	)
	(segment
		(start 105.157016 -223.584262)
		(end 105.157016 -223.557084)
		(width 0.0889)
		(layer "In2.Cu")
		(net "P5E_CPU1_PE1_TX_DN<15>")
	)
	(segment
		(start 104.14381 -212.309964)
		(end 101.027484 -188.159136)
		(width 0.14732)
		(layer "In2.Cu")
		(net "P5E_CPU1_PE1_TX_DN<15>")
	)
	(segment
		(start 105.344976 -221.622874)
		(end 105.35031 -221.619826)
		(width 0.0889)
		(layer "In2.Cu")
		(net "P5E_CPU1_PE1_TX_DN<15>")
	)
	(segment
		(start 17.686528 -20.612862)
		(end 17.71015 -20.409662)
		(width 0.14732)
		(layer "In2.Cu")
		(net "P5E_CPU1_PE1_TX_DN<15>")
	)
	(segment
		(start 105.157016 -220.32849)
		(end 105.157016 -220.309948)
		(width 0.0889)
		(layer "In2.Cu")
		(net "P5E_CPU1_PE1_TX_DN<15>")
	)
	(segment
		(start 104.865678 -222.442278)
		(end 104.874568 -222.437198)
		(width 0.0889)
		(layer "In2.Cu")
		(net "P5E_CPU1_PE1_TX_DN<15>")
	)
	(segment
		(start 104.25938 -213.220554)
		(end 104.25938 -212.890608)
		(width 0.14732)
		(layer "In2.Cu")
		(net "P5E_CPU1_PE1_TX_DN<15>")
	)
	(segment
		(start 104.865678 -217.559128)
		(end 104.874568 -217.554048)
		(width 0.0889)
		(layer "In2.Cu")
		(net "P5E_CPU1_PE1_TX_DN<15>")
	)
	(segment
		(start 104.874568 -219.830396)
		(end 104.865678 -219.825316)
		(width 0.0889)
		(layer "In2.Cu")
		(net "P5E_CPU1_PE1_TX_DN<15>")
	)
	(segment
		(start 104.686608 -214.369142)
		(end 104.252776 -213.93531)
		(width 0.0889)
		(layer "In2.Cu")
		(net "P5E_CPU1_PE1_TX_DN<15>")
	)
	(segment
		(start 100.601272 -186.47029)
		(end 66.920364 -98.611182)
		(width 0.14732)
		(layer "In2.Cu")
		(net "P5E_CPU1_PE1_TX_DN<15>")
	)
	(segment
		(start 17.481296 -20.12061)
		(end 17.277842 -20.096988)
		(width 0.14732)
		(layer "In2.Cu")
		(net "P5E_CPU1_PE1_TX_DN<15>")
	)
	(segment
		(start 104.874568 -223.085914)
		(end 104.865678 -223.080834)
		(width 0.0889)
		(layer "In2.Cu")
		(net "P5E_CPU1_PE1_TX_DN<15>")
	)
	(segment
		(start 105.374948 -223.846644)
		(end 105.29697 -223.867472)
		(width 0.0889)
		(layer "In2.Cu")
		(net "P5E_CPU1_PE1_TX_DN<15>")
	)
	(segment
		(start 105.34269 -221.624144)
		(end 105.344214 -221.623382)
		(width 0.0889)
		(layer "In2.Cu")
		(net "P5E_CPU1_PE1_TX_DN<15>")
	)
	(segment
		(start 104.874568 -216.574878)
		(end 104.865678 -216.569798)
		(width 0.0889)
		(layer "In2.Cu")
		(net "P5E_CPU1_PE1_TX_DN<15>")
	)
	(segment
		(start 66.920364 -98.611182)
		(end 66.917316 -98.604578)
		(width 0.14732)
		(layer "In2.Cu")
		(net "P5E_CPU1_PE1_TX_DN<15>")
	)
	(segment
		(start 104.865678 -219.18676)
		(end 104.874568 -219.18168)
		(width 0.0889)
		(layer "In2.Cu")
		(net "P5E_CPU1_PE1_TX_DN<15>")
	)
	(segment
		(start 104.397556 -215.757252)
		(end 104.395524 -215.755982)
		(width 0.0889)
		(layer "In2.Cu")
		(net "P5E_CPU1_PE1_TX_DN<15>")
	)
	(segment
		(start 104.217216 -213.849966)
		(end 104.217216 -213.284816)
		(width 0.0889)
		(layer "In2.Cu")
		(net "P5E_CPU1_PE1_TX_DN<15>")
	)
	(segment
		(start 17.71015 -20.409662)
		(end 17.481296 -20.12061)
		(width 0.14732)
		(layer "In2.Cu")
		(net "P5E_CPU1_PE1_TX_DN<15>")
	)
	(segment
		(start 104.405938 -215.762078)
		(end 104.404414 -215.761062)
		(width 0.0889)
		(layer "In2.Cu")
		(net "P5E_CPU1_PE1_TX_DN<15>")
	)
	(segment
		(start 66.917316 -98.604578)
		(end 49.668176 -60.9854)
		(width 0.14732)
		(layer "In2.Cu")
		(net "P5E_CPU1_PE1_TX_DN<15>")
	)
	(segment
		(start 104.217216 -213.284816)
		(end 104.25938 -213.242652)
		(width 0.0889)
		(layer "In2.Cu")
		(net "P5E_CPU1_PE1_TX_DN<15>")
	)
	(segment
		(start 49.668176 -60.9854)
		(end 17.686528 -20.612862)
		(width 0.14732)
		(layer "In2.Cu")
		(net "P5E_CPU1_PE1_TX_DN<15>")
	)
	(segment
		(start 105.626916 -221.133924)
		(end 105.626916 -221.1197)
		(width 0.0889)
		(layer "In2.Cu")
		(net "P5E_CPU1_PE1_TX_DN<15>")
	)
	(segment
		(start 17.072864 -19.60499)
		(end 16.843756 -19.316192)
		(width 0.14732)
		(layer "In2.Cu")
		(net "P5E_CPU1_PE1_TX_DN<15>")
	)
	(segment
		(start 16.843756 -19.316192)
		(end 16.640302 -19.29257)
		(width 0.14732)
		(layer "In2.Cu")
		(net "P5E_CPU1_PE1_TX_DN<15>")
	)
	(segment
		(start 101.027484 -188.159136)
		(end 100.601272 -186.47029)
		(width 0.14732)
		(layer "In2.Cu")
		(net "P5E_CPU1_PE1_TX_DN<15>")
	)
	(segment
		(start 104.41051 -215.764618)
		(end 104.407208 -215.76284)
		(width 0.0889)
		(layer "In2.Cu")
		(net "P5E_CPU1_PE1_TX_DN<15>")
	)
	(segment
		(start 104.407208 -215.76284)
		(end 104.405938 -215.762078)
		(width 0.0889)
		(layer "In2.Cu")
		(net "P5E_CPU1_PE1_TX_DN<15>")
	)
	(segment
		(start 16.102838 -18.613882)
		(end 16.102838 -17.907)
		(width 0.14732)
		(layer "In2.Cu")
		(net "P5E_CPU1_PE1_TX_DN<15>")
	)
	(segment
		(start 16.640302 -19.29257)
		(end 16.102838 -18.613882)
		(width 0.14732)
		(layer "In2.Cu")
		(net "P5E_CPU1_PE1_TX_DN<15>")
	)
	(segment
		(start 17.277842 -20.096988)
		(end 17.049242 -19.808444)
		(width 0.14732)
		(layer "In2.Cu")
		(net "P5E_CPU1_PE1_TX_DN<15>")
	)
	(segment
		(start 104.686608 -214.644732)
		(end 104.686608 -214.369142)
		(width 0.0889)
		(layer "In2.Cu")
		(net "P5E_CPU1_PE1_TX_DN<15>")
	)
	(segment
		(start 104.252776 -213.93531)
		(end 104.217216 -213.849966)
		(width 0.0889)
		(layer "In2.Cu")
		(net "P5E_CPU1_PE1_TX_DN<15>")
	)
	(segment
		(start 104.25938 -212.890608)
		(end 104.14381 -212.309964)
		(width 0.14732)
		(layer "In2.Cu")
		(net "P5E_CPU1_PE1_TX_DN<15>")
	)
	(segment
		(start 104.25938 -213.242652)
		(end 104.25938 -213.220554)
		(width 0.0889)
		(layer "In2.Cu")
		(net "P5E_CPU1_PE1_TX_DN<15>")
	)
	(segment
		(start 104.874568 -218.202764)
		(end 104.865678 -218.197684)
		(width 0.0889)
		(layer "In2.Cu")
		(net "P5E_CPU1_PE1_TX_DN<15>")
	)
	(segment
		(start 104.404414 -215.761062)
		(end 104.397556 -215.757252)
		(width 0.0889)
		(layer "In2.Cu")
		(net "P5E_CPU1_PE1_TX_DN<15>")
	)
	(segment
		(start 104.395524 -215.117426)
		(end 104.404414 -215.112346)
		(width 0.0889)
		(layer "In2.Cu")
		(net "P5E_CPU1_PE1_TX_DN<15>")
	)
	(segment
		(start 105.335324 -221.628462)
		(end 105.34269 -221.624144)
		(width 0.0889)
		(layer "In2.Cu")
		(net "P5E_CPU1_PE1_TX_DN<15>")
	)
	(arc
		(start 105.157016 -217.05443)
		(mid 105.078905 -216.777481)
		(end 104.874568 -216.574878)
		(width 0.0889)
		(layer "In2.Cu")
		(net "P5E_CPU1_PE1_TX_DN<15>")
	)
	(arc
		(start 105.29697 -223.867472)
		(mid 105.195649 -223.741351)
		(end 105.157016 -223.584262)
		(width 0.0889)
		(layer "In2.Cu")
		(net "P5E_CPU1_PE1_TX_DN<15>")
	)
	(arc
		(start 104.865678 -219.825316)
		(mid 104.736474 -219.691802)
		(end 104.68737 -219.512642)
		(width 0.0889)
		(layer "In2.Cu")
		(net "P5E_CPU1_PE1_TX_DN<15>")
	)
	(arc
		(start 104.216962 -215.436704)
		(mid 104.217014 -215.429337)
		(end 104.217216 -215.421972)
		(width 0.0889)
		(layer "In2.Cu")
		(net "P5E_CPU1_PE1_TX_DN<15>")
	)
	(arc
		(start 105.626916 -221.1197)
		(mid 105.547697 -220.845015)
		(end 105.344214 -220.644212)
		(width 0.0889)
		(layer "In2.Cu")
		(net "P5E_CPU1_PE1_TX_DN<15>")
	)
	(arc
		(start 105.35031 -221.619826)
		(mid 105.552897 -221.413475)
		(end 105.626916 -221.133924)
		(width 0.0889)
		(layer "In2.Cu")
		(net "P5E_CPU1_PE1_TX_DN<15>")
	)
	(arc
		(start 105.157016 -223.557084)
		(mid 105.076854 -223.284895)
		(end 104.874568 -223.085914)
		(width 0.0889)
		(layer "In2.Cu")
		(net "P5E_CPU1_PE1_TX_DN<15>")
	)
	(arc
		(start 104.874568 -222.437198)
		(mid 105.077391 -222.236967)
		(end 105.156762 -221.963234)
		(width 0.0889)
		(layer "In2.Cu")
		(net "P5E_CPU1_PE1_TX_DN<15>")
	)
	(arc
		(start 104.68737 -217.888566)
		(mid 104.687203 -217.87739)
		(end 104.68737 -217.866214)
		(width 0.0889)
		(layer "In2.Cu")
		(net "P5E_CPU1_PE1_TX_DN<15>")
	)
	(arc
		(start 104.865678 -216.569798)
		(mid 104.734764 -216.433438)
		(end 104.687116 -216.25052)
		(width 0.0889)
		(layer "In2.Cu")
		(net "P5E_CPU1_PE1_TX_DN<15>")
	)
	(arc
		(start 104.874568 -219.18168)
		(mid 105.077391 -218.981449)
		(end 105.156762 -218.707716)
		(width 0.0889)
		(layer "In2.Cu")
		(net "P5E_CPU1_PE1_TX_DN<15>")
	)
	(arc
		(start 104.68737 -217.866214)
		(mid 104.737863 -217.690236)
		(end 104.865678 -217.559128)
		(width 0.0889)
		(layer "In2.Cu")
		(net "P5E_CPU1_PE1_TX_DN<15>")
	)
	(arc
		(start 104.874568 -217.554048)
		(mid 105.076854 -217.355067)
		(end 105.157016 -217.082878)
		(width 0.0889)
		(layer "In2.Cu")
		(net "P5E_CPU1_PE1_TX_DN<15>")
	)
	(arc
		(start 105.156762 -221.94774)
		(mid 105.204441 -221.76484)
		(end 105.335324 -221.628462)
		(width 0.0889)
		(layer "In2.Cu")
		(net "P5E_CPU1_PE1_TX_DN<15>")
	)
	(arc
		(start 104.68737 -222.773748)
		(mid 104.687203 -222.762572)
		(end 104.68737 -222.751396)
		(width 0.0889)
		(layer "In2.Cu")
		(net "P5E_CPU1_PE1_TX_DN<15>")
	)
	(arc
		(start 104.865678 -218.197684)
		(mid 104.737359 -218.065712)
		(end 104.68737 -217.888566)
		(width 0.0889)
		(layer "In2.Cu")
		(net "P5E_CPU1_PE1_TX_DN<15>")
	)
	(arc
		(start 104.68737 -222.751396)
		(mid 104.737385 -222.574265)
		(end 104.865678 -222.442278)
		(width 0.0889)
		(layer "In2.Cu")
		(net "P5E_CPU1_PE1_TX_DN<15>")
	)
	(arc
		(start 105.344214 -220.644212)
		(mid 105.209281 -220.510858)
		(end 105.157016 -220.32849)
		(width 0.0889)
		(layer "In2.Cu")
		(net "P5E_CPU1_PE1_TX_DN<15>")
	)
	(arc
		(start 104.217216 -215.421972)
		(mid 104.26827 -215.247392)
		(end 104.395524 -215.117426)
		(width 0.0889)
		(layer "In2.Cu")
		(net "P5E_CPU1_PE1_TX_DN<15>")
	)
	(arc
		(start 105.156762 -218.676728)
		(mid 105.077392 -218.402994)
		(end 104.874568 -218.202764)
		(width 0.0889)
		(layer "In2.Cu")
		(net "P5E_CPU1_PE1_TX_DN<15>")
	)
	(arc
		(start 104.395524 -215.755982)
		(mid 104.26461 -215.619622)
		(end 104.216962 -215.436704)
		(width 0.0889)
		(layer "In2.Cu")
		(net "P5E_CPU1_PE1_TX_DN<15>")
	)
	(arc
		(start 104.404414 -215.112346)
		(mid 104.605696 -214.914859)
		(end 104.686608 -214.644732)
		(width 0.0889)
		(layer "In2.Cu")
		(net "P5E_CPU1_PE1_TX_DN<15>")
	)
	(arc
		(start 105.157016 -220.309948)
		(mid 105.078905 -220.032999)
		(end 104.874568 -219.830396)
		(width 0.0889)
		(layer "In2.Cu")
		(net "P5E_CPU1_PE1_TX_DN<15>")
	)
	(arc
		(start 104.68737 -219.512642)
		(mid 104.687276 -219.50426)
		(end 104.68737 -219.495878)
		(width 0.0889)
		(layer "In2.Cu")
		(net "P5E_CPU1_PE1_TX_DN<15>")
	)
	(arc
		(start 104.687116 -216.25052)
		(mid 104.613125 -215.970954)
		(end 104.41051 -215.764618)
		(width 0.0889)
		(layer "In2.Cu")
		(net "P5E_CPU1_PE1_TX_DN<15>")
	)
	(arc
		(start 104.68737 -219.495878)
		(mid 104.737385 -219.318747)
		(end 104.865678 -219.18676)
		(width 0.0889)
		(layer "In2.Cu")
		(net "P5E_CPU1_PE1_TX_DN<15>")
	)
	(arc
		(start 104.865678 -223.080834)
		(mid 104.737867 -222.949741)
		(end 104.68737 -222.773748)
		(width 0.0889)
		(layer "In2.Cu")
		(net "P5E_CPU1_PE1_TX_DN<15>")
	)
	(segment
		(start 106.001312 -224.925382)
		(end 106.001566 -224.925128)
		(width 0.13208)
		(layer "F.Cu")
		(net "P5E_CPU1_PE1_TX_DN<14>")
	)
	(segment
		(start 106.001566 -224.925128)
		(end 106.001566 -224.389442)
		(width 0.13208)
		(layer "F.Cu")
		(net "P5E_CPU1_PE1_TX_DN<14>")
	)
	(segment
		(start 18.628868 -18.83537)
		(end 18.628868 -18.216626)
		(width 0.13208)
		(layer "F.Cu")
		(net "P5E_CPU1_PE1_TX_DN<14>")
	)
	(segment
		(start 18.327878 -19.13636)
		(end 18.628868 -18.83537)
		(width 0.13208)
		(layer "F.Cu")
		(net "P5E_CPU1_PE1_TX_DN<14>")
	)
	(segment
		(start 18.628868 -18.216626)
		(end 18.302478 -17.890236)
		(width 0.13208)
		(layer "F.Cu")
		(net "P5E_CPU1_PE1_TX_DN<14>")
	)
	(segment
		(start 106.188764 -224.065084)
		(end 106.184954 -224.062798)
		(width 0.0889)
		(layer "In2.Cu")
		(net "P5E_CPU1_PE1_TX_DN<14>")
	)
	(segment
		(start 105.70845 -219.022676)
		(end 105.719372 -219.016326)
		(width 0.0889)
		(layer "In2.Cu")
		(net "P5E_CPU1_PE1_TX_DN<14>")
	)
	(segment
		(start 105.7275 -223.256348)
		(end 105.71861 -223.251268)
		(width 0.0889)
		(layer "In2.Cu")
		(net "P5E_CPU1_PE1_TX_DN<14>")
	)
	(segment
		(start 105.724452 -216.743026)
		(end 105.71861 -216.739978)
		(width 0.0889)
		(layer "In2.Cu")
		(net "P5E_CPU1_PE1_TX_DN<14>")
	)
	(segment
		(start 106.188764 -221.458282)
		(end 106.190288 -221.45752)
		(width 0.0889)
		(layer "In2.Cu")
		(net "P5E_CPU1_PE1_TX_DN<14>")
	)
	(segment
		(start 19.994626 -21.860764)
		(end 19.75993 -21.560028)
		(width 0.14732)
		(layer "In2.Cu")
		(net "P5E_CPU1_PE1_TX_DN<14>")
	)
	(segment
		(start 106.189526 -220.810074)
		(end 106.188764 -220.809566)
		(width 0.0889)
		(layer "In2.Cu")
		(net "P5E_CPU1_PE1_TX_DN<14>")
	)
	(segment
		(start 105.70845 -217.39479)
		(end 105.719372 -217.388694)
		(width 0.0889)
		(layer "In2.Cu")
		(net "P5E_CPU1_PE1_TX_DN<14>")
	)
	(segment
		(start 19.556476 -21.534882)
		(end 19.329654 -21.244306)
		(width 0.14732)
		(layer "In2.Cu")
		(net "P5E_CPU1_PE1_TX_DN<14>")
	)
	(segment
		(start 106.197654 -224.070164)
		(end 106.188764 -224.065084)
		(width 0.0889)
		(layer "In2.Cu")
		(net "P5E_CPU1_PE1_TX_DN<14>")
	)
	(segment
		(start 105.435908 -214.622634)
		(end 105.435908 -214.461344)
		(width 0.0889)
		(layer "In2.Cu")
		(net "P5E_CPU1_PE1_TX_DN<14>")
	)
	(segment
		(start 19.969734 -22.063964)
		(end 19.994626 -21.860764)
		(width 0.14732)
		(layer "In2.Cu")
		(net "P5E_CPU1_PE1_TX_DN<14>")
	)
	(segment
		(start 106.184954 -224.062798)
		(end 106.176572 -224.057972)
		(width 0.0889)
		(layer "In2.Cu")
		(net "P5E_CPU1_PE1_TX_DN<14>")
	)
	(segment
		(start 20.399756 -22.379432)
		(end 20.196302 -22.35454)
		(width 0.14732)
		(layer "In2.Cu")
		(net "P5E_CPU1_PE1_TX_DN<14>")
	)
	(segment
		(start 105.251758 -214.261954)
		(end 104.966516 -213.976712)
		(width 0.0889)
		(layer "In2.Cu")
		(net "P5E_CPU1_PE1_TX_DN<14>")
	)
	(segment
		(start 19.329654 -21.244306)
		(end 19.3548 -21.041106)
		(width 0.14732)
		(layer "In2.Cu")
		(net "P5E_CPU1_PE1_TX_DN<14>")
	)
	(segment
		(start 101.679756 -188.001656)
		(end 101.243892 -186.298586)
		(width 0.14732)
		(layer "In2.Cu")
		(net "P5E_CPU1_PE1_TX_DN<14>")
	)
	(segment
		(start 105.906062 -220.327474)
		(end 105.906062 -220.319854)
		(width 0.0889)
		(layer "In2.Cu")
		(net "P5E_CPU1_PE1_TX_DN<14>")
	)
	(segment
		(start 20.196302 -22.35454)
		(end 19.969734 -22.063964)
		(width 0.14732)
		(layer "In2.Cu")
		(net "P5E_CPU1_PE1_TX_DN<14>")
	)
	(segment
		(start 19.3548 -21.041106)
		(end 18.68297 -20.180808)
		(width 0.14732)
		(layer "In2.Cu")
		(net "P5E_CPU1_PE1_TX_DN<14>")
	)
	(segment
		(start 106.190288 -221.45752)
		(end 106.197654 -221.453202)
		(width 0.0889)
		(layer "In2.Cu")
		(net "P5E_CPU1_PE1_TX_DN<14>")
	)
	(segment
		(start 104.812592 -211.057236)
		(end 101.679756 -188.001656)
		(width 0.14732)
		(layer "In2.Cu")
		(net "P5E_CPU1_PE1_TX_DN<14>")
	)
	(segment
		(start 67.560698 -98.435414)
		(end 50.17008 -60.507118)
		(width 0.14732)
		(layer "In2.Cu")
		(net "P5E_CPU1_PE1_TX_DN<14>")
	)
	(segment
		(start 104.924606 -212.715856)
		(end 104.812592 -211.057236)
		(width 0.14732)
		(layer "In2.Cu")
		(net "P5E_CPU1_PE1_TX_DN<14>")
	)
	(segment
		(start 106.001566 -224.389442)
		(end 106.15803 -224.66046)
		(width 0.0889)
		(layer "In2.Cu")
		(net "P5E_CPU1_PE1_TX_DN<14>")
	)
	(segment
		(start 19.75993 -21.560028)
		(end 19.556476 -21.534882)
		(width 0.14732)
		(layer "In2.Cu")
		(net "P5E_CPU1_PE1_TX_DN<14>")
	)
	(segment
		(start 101.243892 -186.298586)
		(end 67.560698 -98.435414)
		(width 0.14732)
		(layer "In2.Cu")
		(net "P5E_CPU1_PE1_TX_DN<14>")
	)
	(segment
		(start 105.436416 -216.266014)
		(end 105.436416 -216.25052)
		(width 0.0889)
		(layer "In2.Cu")
		(net "P5E_CPU1_PE1_TX_DN<14>")
	)
	(segment
		(start 105.719626 -219.99575)
		(end 105.718864 -219.995242)
		(width 0.0889)
		(layer "In2.Cu")
		(net "P5E_CPU1_PE1_TX_DN<14>")
	)
	(segment
		(start 18.625058 -20.01393)
		(end 18.625058 -19.43354)
		(width 0.14732)
		(layer "In2.Cu")
		(net "P5E_CPU1_PE1_TX_DN<14>")
	)
	(segment
		(start 105.70591 -218.360244)
		(end 105.705656 -218.35999)
		(width 0.0889)
		(layer "In2.Cu")
		(net "P5E_CPU1_PE1_TX_DN<14>")
	)
	(segment
		(start 105.436416 -222.783654)
		(end 105.436416 -222.746062)
		(width 0.0889)
		(layer "In2.Cu")
		(net "P5E_CPU1_PE1_TX_DN<14>")
	)
	(segment
		(start 18.625058 -19.43354)
		(end 18.327878 -19.13636)
		(width 0.14732)
		(layer "In2.Cu")
		(net "P5E_CPU1_PE1_TX_DN<14>")
	)
	(segment
		(start 105.710482 -218.362784)
		(end 105.70591 -218.360244)
		(width 0.0889)
		(layer "In2.Cu")
		(net "P5E_CPU1_PE1_TX_DN<14>")
	)
	(segment
		(start 105.248964 -215.926162)
		(end 105.242868 -215.922606)
		(width 0.0889)
		(layer "In2.Cu")
		(net "P5E_CPU1_PE1_TX_DN<14>")
	)
	(segment
		(start 104.966516 -213.976712)
		(end 104.966516 -213.284562)
		(width 0.0889)
		(layer "In2.Cu")
		(net "P5E_CPU1_PE1_TX_DN<14>")
	)
	(segment
		(start 106.188002 -221.45879)
		(end 106.188764 -221.458282)
		(width 0.0889)
		(layer "In2.Cu")
		(net "P5E_CPU1_PE1_TX_DN<14>")
	)
	(segment
		(start 105.705656 -219.987876)
		(end 105.705656 -219.987622)
		(width 0.0889)
		(layer "In2.Cu")
		(net "P5E_CPU1_PE1_TX_DN<14>")
	)
	(segment
		(start 105.71861 -222.272098)
		(end 105.7275 -222.267018)
		(width 0.0889)
		(layer "In2.Cu")
		(net "P5E_CPU1_PE1_TX_DN<14>")
	)
	(segment
		(start 106.182668 -221.461838)
		(end 106.188002 -221.45879)
		(width 0.0889)
		(layer "In2.Cu")
		(net "P5E_CPU1_PE1_TX_DN<14>")
	)
	(segment
		(start 104.966516 -213.284562)
		(end 104.924606 -213.242652)
		(width 0.0889)
		(layer "In2.Cu")
		(net "P5E_CPU1_PE1_TX_DN<14>")
	)
	(segment
		(start 105.248456 -214.946992)
		(end 105.257346 -214.941912)
		(width 0.0889)
		(layer "In2.Cu")
		(net "P5E_CPU1_PE1_TX_DN<14>")
	)
	(segment
		(start 104.924606 -213.242652)
		(end 104.924606 -213.220554)
		(width 0.0889)
		(layer "In2.Cu")
		(net "P5E_CPU1_PE1_TX_DN<14>")
	)
	(segment
		(start 105.257854 -215.931242)
		(end 105.248964 -215.926162)
		(width 0.0889)
		(layer "In2.Cu")
		(net "P5E_CPU1_PE1_TX_DN<14>")
	)
	(segment
		(start 106.197654 -220.814646)
		(end 106.189526 -220.810074)
		(width 0.0889)
		(layer "In2.Cu")
		(net "P5E_CPU1_PE1_TX_DN<14>")
	)
	(segment
		(start 104.924606 -213.220554)
		(end 104.924606 -212.715856)
		(width 0.14732)
		(layer "In2.Cu")
		(net "P5E_CPU1_PE1_TX_DN<14>")
	)
	(segment
		(start 105.719626 -218.368118)
		(end 105.710482 -218.362784)
		(width 0.0889)
		(layer "In2.Cu")
		(net "P5E_CPU1_PE1_TX_DN<14>")
	)
	(segment
		(start 106.15803 -224.66046)
		(end 106.236262 -224.681288)
		(width 0.0889)
		(layer "In2.Cu")
		(net "P5E_CPU1_PE1_TX_DN<14>")
	)
	(segment
		(start 105.719626 -219.996004)
		(end 105.719626 -219.99575)
		(width 0.0889)
		(layer "In2.Cu")
		(net "P5E_CPU1_PE1_TX_DN<14>")
	)
	(segment
		(start 105.718864 -219.995242)
		(end 105.705656 -219.987876)
		(width 0.0889)
		(layer "In2.Cu")
		(net "P5E_CPU1_PE1_TX_DN<14>")
	)
	(segment
		(start 105.7275 -220.000576)
		(end 105.719626 -219.996004)
		(width 0.0889)
		(layer "In2.Cu")
		(net "P5E_CPU1_PE1_TX_DN<14>")
	)
	(segment
		(start 18.68297 -20.180808)
		(end 18.625058 -20.01393)
		(width 0.14732)
		(layer "In2.Cu")
		(net "P5E_CPU1_PE1_TX_DN<14>")
	)
	(segment
		(start 50.17008 -60.507118)
		(end 20.399756 -22.379432)
		(width 0.14732)
		(layer "In2.Cu")
		(net "P5E_CPU1_PE1_TX_DN<14>")
	)
	(segment
		(start 104.966262 -215.436704)
		(end 104.966262 -215.414606)
		(width 0.0889)
		(layer "In2.Cu")
		(net "P5E_CPU1_PE1_TX_DN<14>")
	)
	(arc
		(start 105.719372 -217.388694)
		(mid 105.90641 -217.067298)
		(end 105.724452 -216.743026)
		(width 0.0889)
		(layer "In2.Cu")
		(net "P5E_CPU1_PE1_TX_DN<14>")
	)
	(arc
		(start 105.906062 -223.575626)
		(mid 105.858383 -223.392726)
		(end 105.7275 -223.256348)
		(width 0.0889)
		(layer "In2.Cu")
		(net "P5E_CPU1_PE1_TX_DN<14>")
	)
	(arc
		(start 105.719372 -219.016326)
		(mid 105.906075 -218.692332)
		(end 105.719626 -218.368118)
		(width 0.0889)
		(layer "In2.Cu")
		(net "P5E_CPU1_PE1_TX_DN<14>")
	)
	(arc
		(start 106.176572 -224.057972)
		(mid 105.978344 -223.852124)
		(end 105.906062 -223.575626)
		(width 0.0889)
		(layer "In2.Cu")
		(net "P5E_CPU1_PE1_TX_DN<14>")
	)
	(arc
		(start 105.257346 -214.941912)
		(mid 105.38826 -214.805552)
		(end 105.435908 -214.622634)
		(width 0.0889)
		(layer "In2.Cu")
		(net "P5E_CPU1_PE1_TX_DN<14>")
	)
	(arc
		(start 105.906062 -220.319854)
		(mid 105.858383 -220.136954)
		(end 105.7275 -220.000576)
		(width 0.0889)
		(layer "In2.Cu")
		(net "P5E_CPU1_PE1_TX_DN<14>")
	)
	(arc
		(start 106.197654 -221.453202)
		(mid 106.376251 -221.133924)
		(end 106.197654 -220.814646)
		(width 0.0889)
		(layer "In2.Cu")
		(net "P5E_CPU1_PE1_TX_DN<14>")
	)
	(arc
		(start 105.71861 -223.251268)
		(mid 105.517328 -223.053781)
		(end 105.436416 -222.783654)
		(width 0.0889)
		(layer "In2.Cu")
		(net "P5E_CPU1_PE1_TX_DN<14>")
	)
	(arc
		(start 104.966262 -215.414606)
		(mid 105.047173 -215.144478)
		(end 105.248456 -214.946992)
		(width 0.0889)
		(layer "In2.Cu")
		(net "P5E_CPU1_PE1_TX_DN<14>")
	)
	(arc
		(start 106.236262 -224.681288)
		(mid 106.339407 -224.551263)
		(end 106.376216 -224.389442)
		(width 0.0889)
		(layer "In2.Cu")
		(net "P5E_CPU1_PE1_TX_DN<14>")
	)
	(arc
		(start 105.436416 -217.8939)
		(mid 105.43623 -217.875102)
		(end 105.43667 -217.856308)
		(width 0.0889)
		(layer "In2.Cu")
		(net "P5E_CPU1_PE1_TX_DN<14>")
	)
	(arc
		(start 105.435908 -214.461344)
		(mid 105.360903 -214.345885)
		(end 105.251758 -214.261954)
		(width 0.0889)
		(layer "In2.Cu")
		(net "P5E_CPU1_PE1_TX_DN<14>")
	)
	(arc
		(start 105.242868 -215.922606)
		(mid 105.040281 -215.716255)
		(end 104.966262 -215.436704)
		(width 0.0889)
		(layer "In2.Cu")
		(net "P5E_CPU1_PE1_TX_DN<14>")
	)
	(arc
		(start 105.43667 -217.856308)
		(mid 105.514425 -217.59131)
		(end 105.70845 -217.39479)
		(width 0.0889)
		(layer "In2.Cu")
		(net "P5E_CPU1_PE1_TX_DN<14>")
	)
	(arc
		(start 105.436416 -222.746062)
		(mid 105.515786 -222.472328)
		(end 105.71861 -222.272098)
		(width 0.0889)
		(layer "In2.Cu")
		(net "P5E_CPU1_PE1_TX_DN<14>")
	)
	(arc
		(start 105.705656 -219.987622)
		(mid 105.436459 -219.504382)
		(end 105.70845 -219.022676)
		(width 0.0889)
		(layer "In2.Cu")
		(net "P5E_CPU1_PE1_TX_DN<14>")
	)
	(arc
		(start 105.71861 -216.739978)
		(mid 105.515787 -216.539747)
		(end 105.436416 -216.266014)
		(width 0.0889)
		(layer "In2.Cu")
		(net "P5E_CPU1_PE1_TX_DN<14>")
	)
	(arc
		(start 106.376216 -224.389442)
		(mid 106.328537 -224.206542)
		(end 106.197654 -224.070164)
		(width 0.0889)
		(layer "In2.Cu")
		(net "P5E_CPU1_PE1_TX_DN<14>")
	)
	(arc
		(start 105.906062 -221.94774)
		(mid 105.980053 -221.668174)
		(end 106.182668 -221.461838)
		(width 0.0889)
		(layer "In2.Cu")
		(net "P5E_CPU1_PE1_TX_DN<14>")
	)
	(arc
		(start 105.7275 -222.267018)
		(mid 105.858414 -222.130658)
		(end 105.906062 -221.94774)
		(width 0.0889)
		(layer "In2.Cu")
		(net "P5E_CPU1_PE1_TX_DN<14>")
	)
	(arc
		(start 105.705656 -218.35999)
		(mid 105.511975 -218.16105)
		(end 105.436416 -217.8939)
		(width 0.0889)
		(layer "In2.Cu")
		(net "P5E_CPU1_PE1_TX_DN<14>")
	)
	(arc
		(start 105.436416 -216.25052)
		(mid 105.388737 -216.06762)
		(end 105.257854 -215.931242)
		(width 0.0889)
		(layer "In2.Cu")
		(net "P5E_CPU1_PE1_TX_DN<14>")
	)
	(arc
		(start 106.188764 -220.809566)
		(mid 105.983692 -220.605887)
		(end 105.906062 -220.327474)
		(width 0.0889)
		(layer "In2.Cu")
		(net "P5E_CPU1_PE1_TX_DN<14>")
	)
	(segment
		(start 21.681948 -16.695166)
		(end 22.010878 -16.366236)
		(width 0.13208)
		(layer "F.Cu")
		(net "P5E_CPU1_PE1_TX_DN<13>")
	)
	(segment
		(start 107.411266 -224.111566)
		(end 107.411012 -224.111312)
		(width 0.13208)
		(layer "F.Cu")
		(net "P5E_CPU1_PE1_TX_DN<13>")
	)
	(segment
		(start 21.681948 -17.30883)
		(end 21.681948 -16.695166)
		(width 0.13208)
		(layer "F.Cu")
		(net "P5E_CPU1_PE1_TX_DN<13>")
	)
	(segment
		(start 107.411012 -224.111312)
		(end 107.411012 -223.575626)
		(width 0.13208)
		(layer "F.Cu")
		(net "P5E_CPU1_PE1_TX_DN<13>")
	)
	(segment
		(start 21.985478 -17.61236)
		(end 21.681948 -17.30883)
		(width 0.13208)
		(layer "F.Cu")
		(net "P5E_CPU1_PE1_TX_DN<13>")
	)
	(segment
		(start 107.036616 -220.32849)
		(end 107.036616 -220.309948)
		(width 0.0889)
		(layer "In2.Cu")
		(net "P5E_CPU1_PE1_TX_DN<13>")
	)
	(segment
		(start 107.036616 -217.082878)
		(end 107.036616 -217.05443)
		(width 0.0889)
		(layer "In2.Cu")
		(net "P5E_CPU1_PE1_TX_DN<13>")
	)
	(segment
		(start 22.916388 -20.026376)
		(end 22.701758 -19.72691)
		(width 0.14732)
		(layer "In2.Cu")
		(net "P5E_CPU1_PE1_TX_DN<13>")
	)
	(segment
		(start 107.036616 -223.584262)
		(end 107.036616 -223.557084)
		(width 0.0889)
		(layer "In2.Cu")
		(net "P5E_CPU1_PE1_TX_DN<13>")
	)
	(segment
		(start 106.754168 -216.574878)
		(end 106.745278 -216.569798)
		(width 0.0889)
		(layer "In2.Cu")
		(net "P5E_CPU1_PE1_TX_DN<13>")
	)
	(segment
		(start 107.214924 -221.628462)
		(end 107.22229 -221.624144)
		(width 0.0889)
		(layer "In2.Cu")
		(net "P5E_CPU1_PE1_TX_DN<13>")
	)
	(segment
		(start 106.754168 -218.202764)
		(end 106.745278 -218.197684)
		(width 0.0889)
		(layer "In2.Cu")
		(net "P5E_CPU1_PE1_TX_DN<13>")
	)
	(segment
		(start 50.993802 -59.412886)
		(end 23.481284 -21.062442)
		(width 0.14732)
		(layer "In2.Cu")
		(net "P5E_CPU1_PE1_TX_DN<13>")
	)
	(segment
		(start 106.09707 -213.284816)
		(end 106.139234 -213.242652)
		(width 0.0889)
		(layer "In2.Cu")
		(net "P5E_CPU1_PE1_TX_DN<13>")
	)
	(segment
		(start 102.437184 -186.03595)
		(end 68.685918 -97.999296)
		(width 0.14732)
		(layer "In2.Cu")
		(net "P5E_CPU1_PE1_TX_DN<13>")
	)
	(segment
		(start 106.139234 -213.220554)
		(end 106.139234 -212.46084)
		(width 0.14732)
		(layer "In2.Cu")
		(net "P5E_CPU1_PE1_TX_DN<13>")
	)
	(segment
		(start 23.299928 -20.561046)
		(end 23.097744 -20.527772)
		(width 0.14732)
		(layer "In2.Cu")
		(net "P5E_CPU1_PE1_TX_DN<13>")
	)
	(segment
		(start 107.22229 -221.624144)
		(end 107.223814 -221.623382)
		(width 0.0889)
		(layer "In2.Cu")
		(net "P5E_CPU1_PE1_TX_DN<13>")
	)
	(segment
		(start 106.745278 -219.18676)
		(end 106.754168 -219.18168)
		(width 0.0889)
		(layer "In2.Cu")
		(net "P5E_CPU1_PE1_TX_DN<13>")
	)
	(segment
		(start 106.038904 -210.973924)
		(end 102.89159 -187.810648)
		(width 0.14732)
		(layer "In2.Cu")
		(net "P5E_CPU1_PE1_TX_DN<13>")
	)
	(segment
		(start 106.277156 -215.757252)
		(end 106.275124 -215.755982)
		(width 0.0889)
		(layer "In2.Cu")
		(net "P5E_CPU1_PE1_TX_DN<13>")
	)
	(segment
		(start 23.481284 -21.062442)
		(end 23.514558 -20.860512)
		(width 0.14732)
		(layer "In2.Cu")
		(net "P5E_CPU1_PE1_TX_DN<13>")
	)
	(segment
		(start 107.411012 -223.575626)
		(end 107.254548 -223.846644)
		(width 0.0889)
		(layer "In2.Cu")
		(net "P5E_CPU1_PE1_TX_DN<13>")
	)
	(segment
		(start 21.690838 -17.907)
		(end 21.985478 -17.61236)
		(width 0.14732)
		(layer "In2.Cu")
		(net "P5E_CPU1_PE1_TX_DN<13>")
	)
	(segment
		(start 106.286808 -215.76284)
		(end 106.285538 -215.762078)
		(width 0.0889)
		(layer "In2.Cu")
		(net "P5E_CPU1_PE1_TX_DN<13>")
	)
	(segment
		(start 22.49932 -19.693636)
		(end 21.690838 -18.566638)
		(width 0.14732)
		(layer "In2.Cu")
		(net "P5E_CPU1_PE1_TX_DN<13>")
	)
	(segment
		(start 107.036362 -218.707716)
		(end 107.036362 -218.676728)
		(width 0.0889)
		(layer "In2.Cu")
		(net "P5E_CPU1_PE1_TX_DN<13>")
	)
	(segment
		(start 106.096816 -213.893908)
		(end 106.096816 -213.292182)
		(width 0.0889)
		(layer "In2.Cu")
		(net "P5E_CPU1_PE1_TX_DN<13>")
	)
	(segment
		(start 68.685918 -97.999296)
		(end 50.993802 -59.412886)
		(width 0.14732)
		(layer "In2.Cu")
		(net "P5E_CPU1_PE1_TX_DN<13>")
	)
	(segment
		(start 23.514558 -20.860512)
		(end 23.299928 -20.561046)
		(width 0.14732)
		(layer "In2.Cu")
		(net "P5E_CPU1_PE1_TX_DN<13>")
	)
	(segment
		(start 106.745278 -222.442278)
		(end 106.754168 -222.437198)
		(width 0.0889)
		(layer "In2.Cu")
		(net "P5E_CPU1_PE1_TX_DN<13>")
	)
	(segment
		(start 106.285538 -215.762078)
		(end 106.284014 -215.761062)
		(width 0.0889)
		(layer "In2.Cu")
		(net "P5E_CPU1_PE1_TX_DN<13>")
	)
	(segment
		(start 106.139234 -212.46084)
		(end 106.038904 -210.973924)
		(width 0.14732)
		(layer "In2.Cu")
		(net "P5E_CPU1_PE1_TX_DN<13>")
	)
	(segment
		(start 106.566208 -214.644732)
		(end 106.566208 -214.424768)
		(width 0.0889)
		(layer "In2.Cu")
		(net "P5E_CPU1_PE1_TX_DN<13>")
	)
	(segment
		(start 106.284014 -215.761062)
		(end 106.28249 -215.7603)
		(width 0.0889)
		(layer "In2.Cu")
		(net "P5E_CPU1_PE1_TX_DN<13>")
	)
	(segment
		(start 22.883114 -20.22856)
		(end 22.916388 -20.026376)
		(width 0.14732)
		(layer "In2.Cu")
		(net "P5E_CPU1_PE1_TX_DN<13>")
	)
	(segment
		(start 107.223814 -221.623382)
		(end 107.224576 -221.622874)
		(width 0.0889)
		(layer "In2.Cu")
		(net "P5E_CPU1_PE1_TX_DN<13>")
	)
	(segment
		(start 106.096816 -213.292182)
		(end 106.09707 -213.291928)
		(width 0.0889)
		(layer "In2.Cu")
		(net "P5E_CPU1_PE1_TX_DN<13>")
	)
	(segment
		(start 106.28249 -215.7603)
		(end 106.280458 -215.75903)
		(width 0.0889)
		(layer "In2.Cu")
		(net "P5E_CPU1_PE1_TX_DN<13>")
	)
	(segment
		(start 106.745278 -217.559128)
		(end 106.754168 -217.554048)
		(width 0.0889)
		(layer "In2.Cu")
		(net "P5E_CPU1_PE1_TX_DN<13>")
	)
	(segment
		(start 102.89159 -187.810648)
		(end 102.437184 -186.03595)
		(width 0.14732)
		(layer "In2.Cu")
		(net "P5E_CPU1_PE1_TX_DN<13>")
	)
	(segment
		(start 107.224576 -221.622874)
		(end 107.22991 -221.619826)
		(width 0.0889)
		(layer "In2.Cu")
		(net "P5E_CPU1_PE1_TX_DN<13>")
	)
	(segment
		(start 23.097744 -20.527772)
		(end 22.883114 -20.22856)
		(width 0.14732)
		(layer "In2.Cu")
		(net "P5E_CPU1_PE1_TX_DN<13>")
	)
	(segment
		(start 106.139234 -213.242652)
		(end 106.139234 -213.220554)
		(width 0.0889)
		(layer "In2.Cu")
		(net "P5E_CPU1_PE1_TX_DN<13>")
	)
	(segment
		(start 21.690838 -18.566638)
		(end 21.690838 -17.907)
		(width 0.14732)
		(layer "In2.Cu")
		(net "P5E_CPU1_PE1_TX_DN<13>")
	)
	(segment
		(start 106.29011 -215.764618)
		(end 106.286808 -215.76284)
		(width 0.0889)
		(layer "In2.Cu")
		(net "P5E_CPU1_PE1_TX_DN<13>")
	)
	(segment
		(start 106.754168 -219.830396)
		(end 106.745278 -219.825316)
		(width 0.0889)
		(layer "In2.Cu")
		(net "P5E_CPU1_PE1_TX_DN<13>")
	)
	(segment
		(start 107.036362 -221.963234)
		(end 107.036362 -221.94774)
		(width 0.0889)
		(layer "In2.Cu")
		(net "P5E_CPU1_PE1_TX_DN<13>")
	)
	(segment
		(start 107.254548 -223.846644)
		(end 107.17657 -223.867472)
		(width 0.0889)
		(layer "In2.Cu")
		(net "P5E_CPU1_PE1_TX_DN<13>")
	)
	(segment
		(start 22.701758 -19.72691)
		(end 22.49932 -19.693636)
		(width 0.14732)
		(layer "In2.Cu")
		(net "P5E_CPU1_PE1_TX_DN<13>")
	)
	(segment
		(start 106.09707 -213.291928)
		(end 106.09707 -213.284816)
		(width 0.0889)
		(layer "In2.Cu")
		(net "P5E_CPU1_PE1_TX_DN<13>")
	)
	(segment
		(start 106.754168 -223.085914)
		(end 106.745278 -223.080834)
		(width 0.0889)
		(layer "In2.Cu")
		(net "P5E_CPU1_PE1_TX_DN<13>")
	)
	(segment
		(start 106.280458 -215.75903)
		(end 106.277156 -215.757252)
		(width 0.0889)
		(layer "In2.Cu")
		(net "P5E_CPU1_PE1_TX_DN<13>")
	)
	(segment
		(start 106.275124 -215.117426)
		(end 106.284014 -215.112346)
		(width 0.0889)
		(layer "In2.Cu")
		(net "P5E_CPU1_PE1_TX_DN<13>")
	)
	(segment
		(start 107.506516 -221.133924)
		(end 107.506516 -221.1197)
		(width 0.0889)
		(layer "In2.Cu")
		(net "P5E_CPU1_PE1_TX_DN<13>")
	)
	(arc
		(start 107.223814 -220.644212)
		(mid 107.088881 -220.510858)
		(end 107.036616 -220.32849)
		(width 0.0889)
		(layer "In2.Cu")
		(net "P5E_CPU1_PE1_TX_DN<13>")
	)
	(arc
		(start 106.56697 -217.888566)
		(mid 106.566803 -217.87739)
		(end 106.56697 -217.866214)
		(width 0.0889)
		(layer "In2.Cu")
		(net "P5E_CPU1_PE1_TX_DN<13>")
	)
	(arc
		(start 106.56697 -217.866214)
		(mid 106.617463 -217.690236)
		(end 106.745278 -217.559128)
		(width 0.0889)
		(layer "In2.Cu")
		(net "P5E_CPU1_PE1_TX_DN<13>")
	)
	(arc
		(start 107.036616 -217.05443)
		(mid 106.958505 -216.777481)
		(end 106.754168 -216.574878)
		(width 0.0889)
		(layer "In2.Cu")
		(net "P5E_CPU1_PE1_TX_DN<13>")
	)
	(arc
		(start 106.56697 -222.751396)
		(mid 106.616985 -222.574265)
		(end 106.745278 -222.442278)
		(width 0.0889)
		(layer "In2.Cu")
		(net "P5E_CPU1_PE1_TX_DN<13>")
	)
	(arc
		(start 107.036616 -220.309948)
		(mid 106.958505 -220.032999)
		(end 106.754168 -219.830396)
		(width 0.0889)
		(layer "In2.Cu")
		(net "P5E_CPU1_PE1_TX_DN<13>")
	)
	(arc
		(start 106.745278 -216.569798)
		(mid 106.614364 -216.433438)
		(end 106.566716 -216.25052)
		(width 0.0889)
		(layer "In2.Cu")
		(net "P5E_CPU1_PE1_TX_DN<13>")
	)
	(arc
		(start 107.22991 -221.619826)
		(mid 107.432497 -221.413475)
		(end 107.506516 -221.133924)
		(width 0.0889)
		(layer "In2.Cu")
		(net "P5E_CPU1_PE1_TX_DN<13>")
	)
	(arc
		(start 107.506516 -221.1197)
		(mid 107.427297 -220.845015)
		(end 107.223814 -220.644212)
		(width 0.0889)
		(layer "In2.Cu")
		(net "P5E_CPU1_PE1_TX_DN<13>")
	)
	(arc
		(start 106.56697 -219.512642)
		(mid 106.566876 -219.50426)
		(end 106.56697 -219.495878)
		(width 0.0889)
		(layer "In2.Cu")
		(net "P5E_CPU1_PE1_TX_DN<13>")
	)
	(arc
		(start 107.036616 -223.557084)
		(mid 106.956454 -223.284895)
		(end 106.754168 -223.085914)
		(width 0.0889)
		(layer "In2.Cu")
		(net "P5E_CPU1_PE1_TX_DN<13>")
	)
	(arc
		(start 107.036362 -218.676728)
		(mid 106.956992 -218.402994)
		(end 106.754168 -218.202764)
		(width 0.0889)
		(layer "In2.Cu")
		(net "P5E_CPU1_PE1_TX_DN<13>")
	)
	(arc
		(start 106.754168 -219.18168)
		(mid 106.956991 -218.981449)
		(end 107.036362 -218.707716)
		(width 0.0889)
		(layer "In2.Cu")
		(net "P5E_CPU1_PE1_TX_DN<13>")
	)
	(arc
		(start 106.096562 -215.436704)
		(mid 106.096614 -215.429337)
		(end 106.096816 -215.421972)
		(width 0.0889)
		(layer "In2.Cu")
		(net "P5E_CPU1_PE1_TX_DN<13>")
	)
	(arc
		(start 106.566716 -216.25052)
		(mid 106.492725 -215.970954)
		(end 106.29011 -215.764618)
		(width 0.0889)
		(layer "In2.Cu")
		(net "P5E_CPU1_PE1_TX_DN<13>")
	)
	(arc
		(start 106.280966 -214.093298)
		(mid 106.171819 -214.00937)
		(end 106.096816 -213.893908)
		(width 0.0889)
		(layer "In2.Cu")
		(net "P5E_CPU1_PE1_TX_DN<13>")
	)
	(arc
		(start 107.036362 -221.94774)
		(mid 107.084041 -221.76484)
		(end 107.214924 -221.628462)
		(width 0.0889)
		(layer "In2.Cu")
		(net "P5E_CPU1_PE1_TX_DN<13>")
	)
	(arc
		(start 106.275124 -215.755982)
		(mid 106.14421 -215.619622)
		(end 106.096562 -215.436704)
		(width 0.0889)
		(layer "In2.Cu")
		(net "P5E_CPU1_PE1_TX_DN<13>")
	)
	(arc
		(start 106.745278 -218.197684)
		(mid 106.616959 -218.065712)
		(end 106.56697 -217.888566)
		(width 0.0889)
		(layer "In2.Cu")
		(net "P5E_CPU1_PE1_TX_DN<13>")
	)
	(arc
		(start 107.17657 -223.867472)
		(mid 107.075249 -223.741351)
		(end 107.036616 -223.584262)
		(width 0.0889)
		(layer "In2.Cu")
		(net "P5E_CPU1_PE1_TX_DN<13>")
	)
	(arc
		(start 106.566208 -214.424768)
		(mid 106.454929 -214.232062)
		(end 106.280966 -214.093298)
		(width 0.0889)
		(layer "In2.Cu")
		(net "P5E_CPU1_PE1_TX_DN<13>")
	)
	(arc
		(start 106.745278 -219.825316)
		(mid 106.616074 -219.691802)
		(end 106.56697 -219.512642)
		(width 0.0889)
		(layer "In2.Cu")
		(net "P5E_CPU1_PE1_TX_DN<13>")
	)
	(arc
		(start 106.754168 -217.554048)
		(mid 106.956454 -217.355067)
		(end 107.036616 -217.082878)
		(width 0.0889)
		(layer "In2.Cu")
		(net "P5E_CPU1_PE1_TX_DN<13>")
	)
	(arc
		(start 106.096816 -215.421972)
		(mid 106.14787 -215.247392)
		(end 106.275124 -215.117426)
		(width 0.0889)
		(layer "In2.Cu")
		(net "P5E_CPU1_PE1_TX_DN<13>")
	)
	(arc
		(start 106.284014 -215.112346)
		(mid 106.485296 -214.914859)
		(end 106.566208 -214.644732)
		(width 0.0889)
		(layer "In2.Cu")
		(net "P5E_CPU1_PE1_TX_DN<13>")
	)
	(arc
		(start 106.754168 -222.437198)
		(mid 106.956991 -222.236967)
		(end 107.036362 -221.963234)
		(width 0.0889)
		(layer "In2.Cu")
		(net "P5E_CPU1_PE1_TX_DN<13>")
	)
	(arc
		(start 106.56697 -222.773748)
		(mid 106.566803 -222.762572)
		(end 106.56697 -222.751396)
		(width 0.0889)
		(layer "In2.Cu")
		(net "P5E_CPU1_PE1_TX_DN<13>")
	)
	(arc
		(start 106.745278 -223.080834)
		(mid 106.617467 -222.949741)
		(end 106.56697 -222.773748)
		(width 0.0889)
		(layer "In2.Cu")
		(net "P5E_CPU1_PE1_TX_DN<13>")
	)
	(arc
		(start 106.56697 -219.495878)
		(mid 106.616985 -219.318747)
		(end 106.745278 -219.18676)
		(width 0.0889)
		(layer "In2.Cu")
		(net "P5E_CPU1_PE1_TX_DN<13>")
	)
	(segment
		(start 23.915878 -19.13636)
		(end 24.216868 -18.83537)
		(width 0.13208)
		(layer "F.Cu")
		(net "P5E_CPU1_PE1_TX_DN<12>")
	)
	(segment
		(start 107.880912 -224.925382)
		(end 107.881166 -224.925128)
		(width 0.13208)
		(layer "F.Cu")
		(net "P5E_CPU1_PE1_TX_DN<12>")
	)
	(segment
		(start 24.216868 -18.216626)
		(end 23.890478 -17.890236)
		(width 0.13208)
		(layer "F.Cu")
		(net "P5E_CPU1_PE1_TX_DN<12>")
	)
	(segment
		(start 24.216868 -18.83537)
		(end 24.216868 -18.216626)
		(width 0.13208)
		(layer "F.Cu")
		(net "P5E_CPU1_PE1_TX_DN<12>")
	)
	(segment
		(start 107.881166 -224.925128)
		(end 107.881166 -224.389442)
		(width 0.13208)
		(layer "F.Cu")
		(net "P5E_CPU1_PE1_TX_DN<12>")
	)
	(segment
		(start 107.604052 -216.743026)
		(end 107.59821 -216.739978)
		(width 0.0889)
		(layer "In2.Cu")
		(net "P5E_CPU1_PE1_TX_DN<12>")
	)
	(segment
		(start 107.6071 -223.256348)
		(end 107.59821 -223.251268)
		(width 0.0889)
		(layer "In2.Cu")
		(net "P5E_CPU1_PE1_TX_DN<12>")
	)
	(segment
		(start 108.068364 -224.065084)
		(end 108.064554 -224.062798)
		(width 0.0889)
		(layer "In2.Cu")
		(net "P5E_CPU1_PE1_TX_DN<12>")
	)
	(segment
		(start 107.58805 -219.022676)
		(end 107.598972 -219.016326)
		(width 0.0889)
		(layer "In2.Cu")
		(net "P5E_CPU1_PE1_TX_DN<12>")
	)
	(segment
		(start 108.062268 -221.461838)
		(end 108.067602 -221.45879)
		(width 0.0889)
		(layer "In2.Cu")
		(net "P5E_CPU1_PE1_TX_DN<12>")
	)
	(segment
		(start 107.13085 -214.945214)
		(end 107.132374 -214.944452)
		(width 0.0889)
		(layer "In2.Cu")
		(net "P5E_CPU1_PE1_TX_DN<12>")
	)
	(segment
		(start 25.056338 -21.604478)
		(end 24.843994 -21.30298)
		(width 0.14732)
		(layer "In2.Cu")
		(net "P5E_CPU1_PE1_TX_DN<12>")
	)
	(segment
		(start 108.03763 -224.66046)
		(end 108.115862 -224.681288)
		(width 0.0889)
		(layer "In2.Cu")
		(net "P5E_CPU1_PE1_TX_DN<12>")
	)
	(segment
		(start 108.069888 -221.45752)
		(end 108.077254 -221.453202)
		(width 0.0889)
		(layer "In2.Cu")
		(net "P5E_CPU1_PE1_TX_DN<12>")
	)
	(segment
		(start 107.599226 -219.996004)
		(end 107.599226 -219.99575)
		(width 0.0889)
		(layer "In2.Cu")
		(net "P5E_CPU1_PE1_TX_DN<12>")
	)
	(segment
		(start 107.598718 -218.368118)
		(end 107.58805 -218.362022)
		(width 0.0889)
		(layer "In2.Cu")
		(net "P5E_CPU1_PE1_TX_DN<12>")
	)
	(segment
		(start 25.849326 -22.478238)
		(end 25.647142 -22.443186)
		(width 0.14732)
		(layer "In2.Cu")
		(net "P5E_CPU1_PE1_TX_DN<12>")
	)
	(segment
		(start 106.80446 -213.242652)
		(end 106.80446 -213.220554)
		(width 0.0889)
		(layer "In2.Cu")
		(net "P5E_CPU1_PE1_TX_DN<12>")
	)
	(segment
		(start 107.58805 -217.39479)
		(end 107.598972 -217.388694)
		(width 0.0889)
		(layer "In2.Cu")
		(net "P5E_CPU1_PE1_TX_DN<12>")
	)
	(segment
		(start 106.84637 -213.284562)
		(end 106.80446 -213.242652)
		(width 0.0889)
		(layer "In2.Cu")
		(net "P5E_CPU1_PE1_TX_DN<12>")
	)
	(segment
		(start 107.137454 -215.931242)
		(end 107.128564 -215.926162)
		(width 0.0889)
		(layer "In2.Cu")
		(net "P5E_CPU1_PE1_TX_DN<12>")
	)
	(segment
		(start 108.068364 -221.458282)
		(end 108.069888 -221.45752)
		(width 0.0889)
		(layer "In2.Cu")
		(net "P5E_CPU1_PE1_TX_DN<12>")
	)
	(segment
		(start 107.130088 -214.945722)
		(end 107.13085 -214.945214)
		(width 0.0889)
		(layer "In2.Cu")
		(net "P5E_CPU1_PE1_TX_DN<12>")
	)
	(segment
		(start 107.132374 -214.944452)
		(end 107.136946 -214.941912)
		(width 0.0889)
		(layer "In2.Cu")
		(net "P5E_CPU1_PE1_TX_DN<12>")
	)
	(segment
		(start 108.067602 -221.45879)
		(end 108.068364 -221.458282)
		(width 0.0889)
		(layer "In2.Cu")
		(net "P5E_CPU1_PE1_TX_DN<12>")
	)
	(segment
		(start 24.879046 -21.101304)
		(end 24.210518 -20.152614)
		(width 0.14732)
		(layer "In2.Cu")
		(net "P5E_CPU1_PE1_TX_DN<12>")
	)
	(segment
		(start 106.80446 -212.485986)
		(end 106.698542 -210.850988)
		(width 0.14732)
		(layer "In2.Cu")
		(net "P5E_CPU1_PE1_TX_DN<12>")
	)
	(segment
		(start 107.585256 -219.987876)
		(end 107.585256 -219.987622)
		(width 0.0889)
		(layer "In2.Cu")
		(net "P5E_CPU1_PE1_TX_DN<12>")
	)
	(segment
		(start 69.324728 -97.819972)
		(end 51.41468 -58.758328)
		(width 0.14732)
		(layer "In2.Cu")
		(net "P5E_CPU1_PE1_TX_DN<12>")
	)
	(segment
		(start 107.282234 -214.412322)
		(end 106.84637 -213.976458)
		(width 0.0889)
		(layer "In2.Cu")
		(net "P5E_CPU1_PE1_TX_DN<12>")
	)
	(segment
		(start 24.843994 -21.30298)
		(end 24.879046 -21.101304)
		(width 0.14732)
		(layer "In2.Cu")
		(net "P5E_CPU1_PE1_TX_DN<12>")
	)
	(segment
		(start 107.599226 -219.99575)
		(end 107.598464 -219.995242)
		(width 0.0889)
		(layer "In2.Cu")
		(net "P5E_CPU1_PE1_TX_DN<12>")
	)
	(segment
		(start 108.069126 -220.810074)
		(end 108.068364 -220.809566)
		(width 0.0889)
		(layer "In2.Cu")
		(net "P5E_CPU1_PE1_TX_DN<12>")
	)
	(segment
		(start 107.598464 -219.995242)
		(end 107.585256 -219.987876)
		(width 0.0889)
		(layer "In2.Cu")
		(net "P5E_CPU1_PE1_TX_DN<12>")
	)
	(segment
		(start 107.316016 -216.266014)
		(end 107.316016 -216.25052)
		(width 0.0889)
		(layer "In2.Cu")
		(net "P5E_CPU1_PE1_TX_DN<12>")
	)
	(segment
		(start 25.470104 -21.940266)
		(end 25.258014 -21.639276)
		(width 0.14732)
		(layer "In2.Cu")
		(net "P5E_CPU1_PE1_TX_DN<12>")
	)
	(segment
		(start 106.698542 -210.850988)
		(end 105.256584 -199.78624)
		(width 0.14732)
		(layer "In2.Cu")
		(net "P5E_CPU1_PE1_TX_DN<12>")
	)
	(segment
		(start 25.435052 -22.141942)
		(end 25.470104 -21.940266)
		(width 0.14732)
		(layer "In2.Cu")
		(net "P5E_CPU1_PE1_TX_DN<12>")
	)
	(segment
		(start 107.785662 -218.704668)
		(end 107.785662 -218.679776)
		(width 0.0889)
		(layer "In2.Cu")
		(net "P5E_CPU1_PE1_TX_DN<12>")
	)
	(segment
		(start 107.6071 -220.000576)
		(end 107.599226 -219.996004)
		(width 0.0889)
		(layer "In2.Cu")
		(net "P5E_CPU1_PE1_TX_DN<12>")
	)
	(segment
		(start 24.210518 -19.431)
		(end 23.915878 -19.13636)
		(width 0.14732)
		(layer "In2.Cu")
		(net "P5E_CPU1_PE1_TX_DN<12>")
	)
	(segment
		(start 108.077254 -224.070164)
		(end 108.068364 -224.065084)
		(width 0.0889)
		(layer "In2.Cu")
		(net "P5E_CPU1_PE1_TX_DN<12>")
	)
	(segment
		(start 103.81488 -188.721746)
		(end 103.109522 -185.934604)
		(width 0.14732)
		(layer "In2.Cu")
		(net "P5E_CPU1_PE1_TX_DN<12>")
	)
	(segment
		(start 107.128564 -215.926162)
		(end 107.122468 -215.922606)
		(width 0.0889)
		(layer "In2.Cu")
		(net "P5E_CPU1_PE1_TX_DN<12>")
	)
	(segment
		(start 25.647142 -22.443186)
		(end 25.435052 -22.141942)
		(width 0.14732)
		(layer "In2.Cu")
		(net "P5E_CPU1_PE1_TX_DN<12>")
	)
	(segment
		(start 107.316016 -222.783654)
		(end 107.316016 -222.746062)
		(width 0.0889)
		(layer "In2.Cu")
		(net "P5E_CPU1_PE1_TX_DN<12>")
	)
	(segment
		(start 25.258014 -21.639276)
		(end 25.056338 -21.604478)
		(width 0.14732)
		(layer "In2.Cu")
		(net "P5E_CPU1_PE1_TX_DN<12>")
	)
	(segment
		(start 103.109522 -185.934604)
		(end 69.324728 -97.819972)
		(width 0.14732)
		(layer "In2.Cu")
		(net "P5E_CPU1_PE1_TX_DN<12>")
	)
	(segment
		(start 24.210518 -20.152614)
		(end 24.210518 -19.431)
		(width 0.14732)
		(layer "In2.Cu")
		(net "P5E_CPU1_PE1_TX_DN<12>")
	)
	(segment
		(start 51.41468 -58.758328)
		(end 25.849326 -22.478238)
		(width 0.14732)
		(layer "In2.Cu")
		(net "P5E_CPU1_PE1_TX_DN<12>")
	)
	(segment
		(start 107.785662 -220.327474)
		(end 107.785662 -220.319854)
		(width 0.0889)
		(layer "In2.Cu")
		(net "P5E_CPU1_PE1_TX_DN<12>")
	)
	(segment
		(start 107.59821 -222.272098)
		(end 107.6071 -222.267018)
		(width 0.0889)
		(layer "In2.Cu")
		(net "P5E_CPU1_PE1_TX_DN<12>")
	)
	(segment
		(start 107.315508 -214.622634)
		(end 107.315508 -214.461344)
		(width 0.0889)
		(layer "In2.Cu")
		(net "P5E_CPU1_PE1_TX_DN<12>")
	)
	(segment
		(start 107.881166 -224.389442)
		(end 108.03763 -224.66046)
		(width 0.0889)
		(layer "In2.Cu")
		(net "P5E_CPU1_PE1_TX_DN<12>")
	)
	(segment
		(start 107.128056 -214.946992)
		(end 107.130088 -214.945722)
		(width 0.0889)
		(layer "In2.Cu")
		(net "P5E_CPU1_PE1_TX_DN<12>")
	)
	(segment
		(start 106.80446 -213.220554)
		(end 106.80446 -212.485986)
		(width 0.14732)
		(layer "In2.Cu")
		(net "P5E_CPU1_PE1_TX_DN<12>")
	)
	(segment
		(start 106.84637 -213.976458)
		(end 106.84637 -213.284562)
		(width 0.0889)
		(layer "In2.Cu")
		(net "P5E_CPU1_PE1_TX_DN<12>")
	)
	(segment
		(start 106.845862 -215.436704)
		(end 106.845862 -215.414606)
		(width 0.0889)
		(layer "In2.Cu")
		(net "P5E_CPU1_PE1_TX_DN<12>")
	)
	(segment
		(start 108.064554 -224.062798)
		(end 108.056172 -224.057972)
		(width 0.0889)
		(layer "In2.Cu")
		(net "P5E_CPU1_PE1_TX_DN<12>")
	)
	(segment
		(start 105.256584 -199.78624)
		(end 103.81488 -188.721746)
		(width 0.14732)
		(layer "In2.Cu")
		(net "P5E_CPU1_PE1_TX_DN<12>")
	)
	(segment
		(start 108.077254 -220.814646)
		(end 108.069126 -220.810074)
		(width 0.0889)
		(layer "In2.Cu")
		(net "P5E_CPU1_PE1_TX_DN<12>")
	)
	(arc
		(start 107.6071 -222.267018)
		(mid 107.738014 -222.130658)
		(end 107.785662 -221.94774)
		(width 0.0889)
		(layer "In2.Cu")
		(net "P5E_CPU1_PE1_TX_DN<12>")
	)
	(arc
		(start 107.316016 -216.25052)
		(mid 107.268337 -216.06762)
		(end 107.137454 -215.931242)
		(width 0.0889)
		(layer "In2.Cu")
		(net "P5E_CPU1_PE1_TX_DN<12>")
	)
	(arc
		(start 108.068364 -220.809566)
		(mid 107.863292 -220.605887)
		(end 107.785662 -220.327474)
		(width 0.0889)
		(layer "In2.Cu")
		(net "P5E_CPU1_PE1_TX_DN<12>")
	)
	(arc
		(start 107.585256 -219.987622)
		(mid 107.316059 -219.504382)
		(end 107.58805 -219.022676)
		(width 0.0889)
		(layer "In2.Cu")
		(net "P5E_CPU1_PE1_TX_DN<12>")
	)
	(arc
		(start 108.077254 -221.453202)
		(mid 108.255851 -221.133924)
		(end 108.077254 -220.814646)
		(width 0.0889)
		(layer "In2.Cu")
		(net "P5E_CPU1_PE1_TX_DN<12>")
	)
	(arc
		(start 107.315508 -214.461344)
		(mid 107.301222 -214.435235)
		(end 107.282234 -214.412322)
		(width 0.0889)
		(layer "In2.Cu")
		(net "P5E_CPU1_PE1_TX_DN<12>")
	)
	(arc
		(start 107.785662 -220.319854)
		(mid 107.737983 -220.136954)
		(end 107.6071 -220.000576)
		(width 0.0889)
		(layer "In2.Cu")
		(net "P5E_CPU1_PE1_TX_DN<12>")
	)
	(arc
		(start 107.122468 -215.922606)
		(mid 106.919881 -215.716255)
		(end 106.845862 -215.436704)
		(width 0.0889)
		(layer "In2.Cu")
		(net "P5E_CPU1_PE1_TX_DN<12>")
	)
	(arc
		(start 107.785662 -218.679776)
		(mid 107.73253 -218.499733)
		(end 107.598718 -218.368118)
		(width 0.0889)
		(layer "In2.Cu")
		(net "P5E_CPU1_PE1_TX_DN<12>")
	)
	(arc
		(start 108.056172 -224.057972)
		(mid 107.857944 -223.852124)
		(end 107.785662 -223.575626)
		(width 0.0889)
		(layer "In2.Cu")
		(net "P5E_CPU1_PE1_TX_DN<12>")
	)
	(arc
		(start 108.255816 -224.389442)
		(mid 108.208137 -224.206542)
		(end 108.077254 -224.070164)
		(width 0.0889)
		(layer "In2.Cu")
		(net "P5E_CPU1_PE1_TX_DN<12>")
	)
	(arc
		(start 106.845862 -215.414606)
		(mid 106.926773 -215.144478)
		(end 107.128056 -214.946992)
		(width 0.0889)
		(layer "In2.Cu")
		(net "P5E_CPU1_PE1_TX_DN<12>")
	)
	(arc
		(start 108.115862 -224.681288)
		(mid 108.219007 -224.551263)
		(end 108.255816 -224.389442)
		(width 0.0889)
		(layer "In2.Cu")
		(net "P5E_CPU1_PE1_TX_DN<12>")
	)
	(arc
		(start 107.785662 -223.575626)
		(mid 107.737983 -223.392726)
		(end 107.6071 -223.256348)
		(width 0.0889)
		(layer "In2.Cu")
		(net "P5E_CPU1_PE1_TX_DN<12>")
	)
	(arc
		(start 107.785662 -221.94774)
		(mid 107.859653 -221.668174)
		(end 108.062268 -221.461838)
		(width 0.0889)
		(layer "In2.Cu")
		(net "P5E_CPU1_PE1_TX_DN<12>")
	)
	(arc
		(start 107.59821 -223.251268)
		(mid 107.396928 -223.053781)
		(end 107.316016 -222.783654)
		(width 0.0889)
		(layer "In2.Cu")
		(net "P5E_CPU1_PE1_TX_DN<12>")
	)
	(arc
		(start 107.59821 -216.739978)
		(mid 107.395387 -216.539747)
		(end 107.316016 -216.266014)
		(width 0.0889)
		(layer "In2.Cu")
		(net "P5E_CPU1_PE1_TX_DN<12>")
	)
	(arc
		(start 107.598972 -217.388694)
		(mid 107.78601 -217.067298)
		(end 107.604052 -216.743026)
		(width 0.0889)
		(layer "In2.Cu")
		(net "P5E_CPU1_PE1_TX_DN<12>")
	)
	(arc
		(start 107.136946 -214.941912)
		(mid 107.26786 -214.805552)
		(end 107.315508 -214.622634)
		(width 0.0889)
		(layer "In2.Cu")
		(net "P5E_CPU1_PE1_TX_DN<12>")
	)
	(arc
		(start 107.316016 -222.746062)
		(mid 107.395386 -222.472328)
		(end 107.59821 -222.272098)
		(width 0.0889)
		(layer "In2.Cu")
		(net "P5E_CPU1_PE1_TX_DN<12>")
	)
	(arc
		(start 107.58805 -218.362022)
		(mid 107.315534 -217.878406)
		(end 107.58805 -217.39479)
		(width 0.0889)
		(layer "In2.Cu")
		(net "P5E_CPU1_PE1_TX_DN<12>")
	)
	(arc
		(start 107.598972 -219.016326)
		(mid 107.732602 -218.884626)
		(end 107.785662 -218.704668)
		(width 0.0889)
		(layer "In2.Cu")
		(net "P5E_CPU1_PE1_TX_DN<12>")
	)
	(segment
		(start 27.269948 -17.30883)
		(end 27.269948 -16.695166)
		(width 0.13208)
		(layer "F.Cu")
		(net "P5E_CPU1_PE1_TX_DN<11>")
	)
	(segment
		(start 27.269948 -16.695166)
		(end 27.598878 -16.366236)
		(width 0.13208)
		(layer "F.Cu")
		(net "P5E_CPU1_PE1_TX_DN<11>")
	)
	(segment
		(start 27.573478 -17.61236)
		(end 27.269948 -17.30883)
		(width 0.13208)
		(layer "F.Cu")
		(net "P5E_CPU1_PE1_TX_DN<11>")
	)
	(segment
		(start 109.290866 -224.111566)
		(end 109.290866 -223.57588)
		(width 0.13208)
		(layer "F.Cu")
		(net "P5E_CPU1_PE1_TX_DN<11>")
	)
	(segment
		(start 109.290866 -223.57588)
		(end 109.290612 -223.575626)
		(width 0.13208)
		(layer "F.Cu")
		(net "P5E_CPU1_PE1_TX_DN<11>")
	)
	(segment
		(start 27.996134 -19.578066)
		(end 27.795728 -19.534378)
		(width 0.14732)
		(layer "In2.Cu")
		(net "P5E_CPU1_PE1_TX_DN<11>")
	)
	(segment
		(start 70.363842 -97.124266)
		(end 52.440078 -58.03011)
		(width 0.14732)
		(layer "In2.Cu")
		(net "P5E_CPU1_PE1_TX_DN<11>")
	)
	(segment
		(start 108.915962 -221.963234)
		(end 108.915962 -221.94774)
		(width 0.0889)
		(layer "In2.Cu")
		(net "P5E_CPU1_PE1_TX_DN<11>")
	)
	(segment
		(start 108.166408 -215.76284)
		(end 108.165138 -215.762078)
		(width 0.0889)
		(layer "In2.Cu")
		(net "P5E_CPU1_PE1_TX_DN<11>")
	)
	(segment
		(start 27.795728 -19.534378)
		(end 27.278838 -18.726658)
		(width 0.14732)
		(layer "In2.Cu")
		(net "P5E_CPU1_PE1_TX_DN<11>")
	)
	(segment
		(start 109.094524 -221.628462)
		(end 109.10189 -221.624144)
		(width 0.0889)
		(layer "In2.Cu")
		(net "P5E_CPU1_PE1_TX_DN<11>")
	)
	(segment
		(start 108.165138 -215.762078)
		(end 108.163614 -215.761062)
		(width 0.0889)
		(layer "In2.Cu")
		(net "P5E_CPU1_PE1_TX_DN<11>")
	)
	(segment
		(start 108.018326 -213.220554)
		(end 108.018326 -212.473032)
		(width 0.14732)
		(layer "In2.Cu")
		(net "P5E_CPU1_PE1_TX_DN<11>")
	)
	(segment
		(start 108.16971 -215.764618)
		(end 108.166408 -215.76284)
		(width 0.0889)
		(layer "In2.Cu")
		(net "P5E_CPU1_PE1_TX_DN<11>")
	)
	(segment
		(start 108.624878 -219.18676)
		(end 108.633768 -219.18168)
		(width 0.0889)
		(layer "In2.Cu")
		(net "P5E_CPU1_PE1_TX_DN<11>")
	)
	(segment
		(start 108.624878 -217.559128)
		(end 108.633768 -217.554048)
		(width 0.0889)
		(layer "In2.Cu")
		(net "P5E_CPU1_PE1_TX_DN<11>")
	)
	(segment
		(start 109.103414 -221.623382)
		(end 109.104176 -221.622874)
		(width 0.0889)
		(layer "In2.Cu")
		(net "P5E_CPU1_PE1_TX_DN<11>")
	)
	(segment
		(start 109.104176 -221.622874)
		(end 109.10951 -221.619826)
		(width 0.0889)
		(layer "In2.Cu")
		(net "P5E_CPU1_PE1_TX_DN<11>")
	)
	(segment
		(start 105.191306 -189.162944)
		(end 104.332786 -185.73623)
		(width 0.14732)
		(layer "In2.Cu")
		(net "P5E_CPU1_PE1_TX_DN<11>")
	)
	(segment
		(start 108.163614 -215.761062)
		(end 108.156756 -215.757252)
		(width 0.0889)
		(layer "In2.Cu")
		(net "P5E_CPU1_PE1_TX_DN<11>")
	)
	(segment
		(start 109.386116 -221.133924)
		(end 109.386116 -221.1197)
		(width 0.0889)
		(layer "In2.Cu")
		(net "P5E_CPU1_PE1_TX_DN<11>")
	)
	(segment
		(start 108.018326 -212.473032)
		(end 107.922314 -210.920076)
		(width 0.14732)
		(layer "In2.Cu")
		(net "P5E_CPU1_PE1_TX_DN<11>")
	)
	(segment
		(start 109.10189 -221.624144)
		(end 109.103414 -221.623382)
		(width 0.0889)
		(layer "In2.Cu")
		(net "P5E_CPU1_PE1_TX_DN<11>")
	)
	(segment
		(start 108.025438 -213.946994)
		(end 107.976162 -213.827868)
		(width 0.0889)
		(layer "In2.Cu")
		(net "P5E_CPU1_PE1_TX_DN<11>")
	)
	(segment
		(start 28.5496 -20.442428)
		(end 28.349194 -20.39874)
		(width 0.14732)
		(layer "In2.Cu")
		(net "P5E_CPU1_PE1_TX_DN<11>")
	)
	(segment
		(start 108.633768 -218.202764)
		(end 108.624878 -218.197684)
		(width 0.0889)
		(layer "In2.Cu")
		(net "P5E_CPU1_PE1_TX_DN<11>")
	)
	(segment
		(start 28.349194 -20.39874)
		(end 28.15082 -20.088606)
		(width 0.14732)
		(layer "In2.Cu")
		(net "P5E_CPU1_PE1_TX_DN<11>")
	)
	(segment
		(start 108.916216 -223.584262)
		(end 108.916216 -223.557084)
		(width 0.0889)
		(layer "In2.Cu")
		(net "P5E_CPU1_PE1_TX_DN<11>")
	)
	(segment
		(start 28.194762 -19.888708)
		(end 27.996134 -19.578066)
		(width 0.14732)
		(layer "In2.Cu")
		(net "P5E_CPU1_PE1_TX_DN<11>")
	)
	(segment
		(start 28.747974 -20.75307)
		(end 28.5496 -20.442428)
		(width 0.14732)
		(layer "In2.Cu")
		(net "P5E_CPU1_PE1_TX_DN<11>")
	)
	(segment
		(start 28.15082 -20.088606)
		(end 28.194762 -19.888708)
		(width 0.14732)
		(layer "In2.Cu")
		(net "P5E_CPU1_PE1_TX_DN<11>")
	)
	(segment
		(start 107.976162 -213.284816)
		(end 108.018326 -213.242652)
		(width 0.0889)
		(layer "In2.Cu")
		(net "P5E_CPU1_PE1_TX_DN<11>")
	)
	(segment
		(start 27.278838 -17.907)
		(end 27.573478 -17.61236)
		(width 0.14732)
		(layer "In2.Cu")
		(net "P5E_CPU1_PE1_TX_DN<11>")
	)
	(segment
		(start 107.976162 -213.827868)
		(end 107.976162 -213.284816)
		(width 0.0889)
		(layer "In2.Cu")
		(net "P5E_CPU1_PE1_TX_DN<11>")
	)
	(segment
		(start 108.633768 -219.830396)
		(end 108.624878 -219.825316)
		(width 0.0889)
		(layer "In2.Cu")
		(net "P5E_CPU1_PE1_TX_DN<11>")
	)
	(segment
		(start 108.156756 -215.757252)
		(end 108.154724 -215.755982)
		(width 0.0889)
		(layer "In2.Cu")
		(net "P5E_CPU1_PE1_TX_DN<11>")
	)
	(segment
		(start 108.018326 -213.242652)
		(end 108.018326 -213.220554)
		(width 0.0889)
		(layer "In2.Cu")
		(net "P5E_CPU1_PE1_TX_DN<11>")
	)
	(segment
		(start 108.633768 -216.574878)
		(end 108.624878 -216.569798)
		(width 0.0889)
		(layer "In2.Cu")
		(net "P5E_CPU1_PE1_TX_DN<11>")
	)
	(segment
		(start 108.186728 -214.10803)
		(end 108.025438 -213.946994)
		(width 0.0889)
		(layer "In2.Cu")
		(net "P5E_CPU1_PE1_TX_DN<11>")
	)
	(segment
		(start 108.624878 -222.442278)
		(end 108.633768 -222.437198)
		(width 0.0889)
		(layer "In2.Cu")
		(net "P5E_CPU1_PE1_TX_DN<11>")
	)
	(segment
		(start 108.916216 -220.32849)
		(end 108.916216 -220.309948)
		(width 0.0889)
		(layer "In2.Cu")
		(net "P5E_CPU1_PE1_TX_DN<11>")
	)
	(segment
		(start 108.915962 -218.707716)
		(end 108.915962 -218.676728)
		(width 0.0889)
		(layer "In2.Cu")
		(net "P5E_CPU1_PE1_TX_DN<11>")
	)
	(segment
		(start 107.922314 -210.920076)
		(end 105.191306 -189.162944)
		(width 0.14732)
		(layer "In2.Cu")
		(net "P5E_CPU1_PE1_TX_DN<11>")
	)
	(segment
		(start 104.332786 -185.73623)
		(end 70.363842 -97.124266)
		(width 0.14732)
		(layer "In2.Cu")
		(net "P5E_CPU1_PE1_TX_DN<11>")
	)
	(segment
		(start 108.445808 -214.644732)
		(end 108.445808 -214.424768)
		(width 0.0889)
		(layer "In2.Cu")
		(net "P5E_CPU1_PE1_TX_DN<11>")
	)
	(segment
		(start 109.290612 -223.575626)
		(end 109.134148 -223.846644)
		(width 0.0889)
		(layer "In2.Cu")
		(net "P5E_CPU1_PE1_TX_DN<11>")
	)
	(segment
		(start 108.916216 -217.082878)
		(end 108.916216 -217.05443)
		(width 0.0889)
		(layer "In2.Cu")
		(net "P5E_CPU1_PE1_TX_DN<11>")
	)
	(segment
		(start 109.134148 -223.846644)
		(end 109.05617 -223.867472)
		(width 0.0889)
		(layer "In2.Cu")
		(net "P5E_CPU1_PE1_TX_DN<11>")
	)
	(segment
		(start 52.440078 -58.03011)
		(end 28.704286 -20.952968)
		(width 0.14732)
		(layer "In2.Cu")
		(net "P5E_CPU1_PE1_TX_DN<11>")
	)
	(segment
		(start 28.704286 -20.952968)
		(end 28.747974 -20.75307)
		(width 0.14732)
		(layer "In2.Cu")
		(net "P5E_CPU1_PE1_TX_DN<11>")
	)
	(segment
		(start 108.154724 -215.117426)
		(end 108.163614 -215.112346)
		(width 0.0889)
		(layer "In2.Cu")
		(net "P5E_CPU1_PE1_TX_DN<11>")
	)
	(segment
		(start 27.278838 -18.726658)
		(end 27.278838 -17.907)
		(width 0.14732)
		(layer "In2.Cu")
		(net "P5E_CPU1_PE1_TX_DN<11>")
	)
	(segment
		(start 108.633768 -223.085914)
		(end 108.624878 -223.080834)
		(width 0.0889)
		(layer "In2.Cu")
		(net "P5E_CPU1_PE1_TX_DN<11>")
	)
	(arc
		(start 108.624878 -216.569798)
		(mid 108.493964 -216.433438)
		(end 108.446316 -216.25052)
		(width 0.0889)
		(layer "In2.Cu")
		(net "P5E_CPU1_PE1_TX_DN<11>")
	)
	(arc
		(start 108.44657 -222.751396)
		(mid 108.496585 -222.574265)
		(end 108.624878 -222.442278)
		(width 0.0889)
		(layer "In2.Cu")
		(net "P5E_CPU1_PE1_TX_DN<11>")
	)
	(arc
		(start 108.44657 -219.495878)
		(mid 108.496585 -219.318747)
		(end 108.624878 -219.18676)
		(width 0.0889)
		(layer "In2.Cu")
		(net "P5E_CPU1_PE1_TX_DN<11>")
	)
	(arc
		(start 109.05617 -223.867472)
		(mid 108.954849 -223.741351)
		(end 108.916216 -223.584262)
		(width 0.0889)
		(layer "In2.Cu")
		(net "P5E_CPU1_PE1_TX_DN<11>")
	)
	(arc
		(start 108.44657 -217.866214)
		(mid 108.497063 -217.690236)
		(end 108.624878 -217.559128)
		(width 0.0889)
		(layer "In2.Cu")
		(net "P5E_CPU1_PE1_TX_DN<11>")
	)
	(arc
		(start 108.633768 -222.437198)
		(mid 108.836591 -222.236967)
		(end 108.915962 -221.963234)
		(width 0.0889)
		(layer "In2.Cu")
		(net "P5E_CPU1_PE1_TX_DN<11>")
	)
	(arc
		(start 108.633768 -217.554048)
		(mid 108.836054 -217.355067)
		(end 108.916216 -217.082878)
		(width 0.0889)
		(layer "In2.Cu")
		(net "P5E_CPU1_PE1_TX_DN<11>")
	)
	(arc
		(start 108.163614 -215.112346)
		(mid 108.364896 -214.914859)
		(end 108.445808 -214.644732)
		(width 0.0889)
		(layer "In2.Cu")
		(net "P5E_CPU1_PE1_TX_DN<11>")
	)
	(arc
		(start 108.624878 -218.197684)
		(mid 108.496559 -218.065712)
		(end 108.44657 -217.888566)
		(width 0.0889)
		(layer "In2.Cu")
		(net "P5E_CPU1_PE1_TX_DN<11>")
	)
	(arc
		(start 108.916216 -220.309948)
		(mid 108.838105 -220.032999)
		(end 108.633768 -219.830396)
		(width 0.0889)
		(layer "In2.Cu")
		(net "P5E_CPU1_PE1_TX_DN<11>")
	)
	(arc
		(start 108.445808 -214.424768)
		(mid 108.344179 -214.243564)
		(end 108.186728 -214.10803)
		(width 0.0889)
		(layer "In2.Cu")
		(net "P5E_CPU1_PE1_TX_DN<11>")
	)
	(arc
		(start 109.103414 -220.644212)
		(mid 108.968481 -220.510858)
		(end 108.916216 -220.32849)
		(width 0.0889)
		(layer "In2.Cu")
		(net "P5E_CPU1_PE1_TX_DN<11>")
	)
	(arc
		(start 108.915962 -218.676728)
		(mid 108.836592 -218.402994)
		(end 108.633768 -218.202764)
		(width 0.0889)
		(layer "In2.Cu")
		(net "P5E_CPU1_PE1_TX_DN<11>")
	)
	(arc
		(start 108.44657 -219.512642)
		(mid 108.446476 -219.50426)
		(end 108.44657 -219.495878)
		(width 0.0889)
		(layer "In2.Cu")
		(net "P5E_CPU1_PE1_TX_DN<11>")
	)
	(arc
		(start 108.916216 -217.05443)
		(mid 108.838105 -216.777481)
		(end 108.633768 -216.574878)
		(width 0.0889)
		(layer "In2.Cu")
		(net "P5E_CPU1_PE1_TX_DN<11>")
	)
	(arc
		(start 109.10951 -221.619826)
		(mid 109.312097 -221.413475)
		(end 109.386116 -221.133924)
		(width 0.0889)
		(layer "In2.Cu")
		(net "P5E_CPU1_PE1_TX_DN<11>")
	)
	(arc
		(start 108.624878 -219.825316)
		(mid 108.495674 -219.691802)
		(end 108.44657 -219.512642)
		(width 0.0889)
		(layer "In2.Cu")
		(net "P5E_CPU1_PE1_TX_DN<11>")
	)
	(arc
		(start 108.915962 -221.94774)
		(mid 108.963641 -221.76484)
		(end 109.094524 -221.628462)
		(width 0.0889)
		(layer "In2.Cu")
		(net "P5E_CPU1_PE1_TX_DN<11>")
	)
	(arc
		(start 107.976162 -215.436704)
		(mid 107.976214 -215.429337)
		(end 107.976416 -215.421972)
		(width 0.0889)
		(layer "In2.Cu")
		(net "P5E_CPU1_PE1_TX_DN<11>")
	)
	(arc
		(start 108.154724 -215.755982)
		(mid 108.02381 -215.619622)
		(end 107.976162 -215.436704)
		(width 0.0889)
		(layer "In2.Cu")
		(net "P5E_CPU1_PE1_TX_DN<11>")
	)
	(arc
		(start 108.916216 -223.557084)
		(mid 108.836054 -223.284895)
		(end 108.633768 -223.085914)
		(width 0.0889)
		(layer "In2.Cu")
		(net "P5E_CPU1_PE1_TX_DN<11>")
	)
	(arc
		(start 109.386116 -221.1197)
		(mid 109.306897 -220.845015)
		(end 109.103414 -220.644212)
		(width 0.0889)
		(layer "In2.Cu")
		(net "P5E_CPU1_PE1_TX_DN<11>")
	)
	(arc
		(start 107.976416 -215.421972)
		(mid 108.02747 -215.247392)
		(end 108.154724 -215.117426)
		(width 0.0889)
		(layer "In2.Cu")
		(net "P5E_CPU1_PE1_TX_DN<11>")
	)
	(arc
		(start 108.624878 -223.080834)
		(mid 108.497067 -222.949741)
		(end 108.44657 -222.773748)
		(width 0.0889)
		(layer "In2.Cu")
		(net "P5E_CPU1_PE1_TX_DN<11>")
	)
	(arc
		(start 108.446316 -216.25052)
		(mid 108.372325 -215.970954)
		(end 108.16971 -215.764618)
		(width 0.0889)
		(layer "In2.Cu")
		(net "P5E_CPU1_PE1_TX_DN<11>")
	)
	(arc
		(start 108.44657 -222.773748)
		(mid 108.446403 -222.762572)
		(end 108.44657 -222.751396)
		(width 0.0889)
		(layer "In2.Cu")
		(net "P5E_CPU1_PE1_TX_DN<11>")
	)
	(arc
		(start 108.44657 -217.888566)
		(mid 108.446403 -217.87739)
		(end 108.44657 -217.866214)
		(width 0.0889)
		(layer "In2.Cu")
		(net "P5E_CPU1_PE1_TX_DN<11>")
	)
	(arc
		(start 108.633768 -219.18168)
		(mid 108.836591 -218.981449)
		(end 108.915962 -218.707716)
		(width 0.0889)
		(layer "In2.Cu")
		(net "P5E_CPU1_PE1_TX_DN<11>")
	)
	(segment
		(start 109.760766 -224.925128)
		(end 109.760766 -224.389442)
		(width 0.13208)
		(layer "F.Cu")
		(net "P5E_CPU1_PE1_TX_DN<10>")
	)
	(segment
		(start 29.503878 -19.13636)
		(end 29.804868 -18.83537)
		(width 0.13208)
		(layer "F.Cu")
		(net "P5E_CPU1_PE1_TX_DN<10>")
	)
	(segment
		(start 29.804868 -18.216626)
		(end 29.478478 -17.890236)
		(width 0.13208)
		(layer "F.Cu")
		(net "P5E_CPU1_PE1_TX_DN<10>")
	)
	(segment
		(start 29.804868 -18.83537)
		(end 29.804868 -18.216626)
		(width 0.13208)
		(layer "F.Cu")
		(net "P5E_CPU1_PE1_TX_DN<10>")
	)
	(segment
		(start 109.760512 -224.925382)
		(end 109.760766 -224.925128)
		(width 0.13208)
		(layer "F.Cu")
		(net "P5E_CPU1_PE1_TX_DN<10>")
	)
	(segment
		(start 70.845934 -96.547178)
		(end 52.766214 -57.115202)
		(width 0.14732)
		(layer "In2.Cu")
		(net "P5E_CPU1_PE1_TX_DN<10>")
	)
	(segment
		(start 109.478572 -218.367864)
		(end 109.46511 -218.360244)
		(width 0.0889)
		(layer "In2.Cu")
		(net "P5E_CPU1_PE1_TX_DN<10>")
	)
	(segment
		(start 109.464856 -219.024454)
		(end 109.469936 -219.021406)
		(width 0.0889)
		(layer "In2.Cu")
		(net "P5E_CPU1_PE1_TX_DN<10>")
	)
	(segment
		(start 29.798518 -19.431)
		(end 29.503878 -19.13636)
		(width 0.14732)
		(layer "In2.Cu")
		(net "P5E_CPU1_PE1_TX_DN<10>")
	)
	(segment
		(start 109.478826 -219.996004)
		(end 109.478826 -219.99575)
		(width 0.0889)
		(layer "In2.Cu")
		(net "P5E_CPU1_PE1_TX_DN<10>")
	)
	(segment
		(start 109.153452 -212.40242)
		(end 105.874058 -189.07633)
		(width 0.14732)
		(layer "In2.Cu")
		(net "P5E_CPU1_PE1_TX_DN<10>")
	)
	(segment
		(start 109.153452 -213.533228)
		(end 109.153452 -213.51113)
		(width 0.0889)
		(layer "In2.Cu")
		(net "P5E_CPU1_PE1_TX_DN<10>")
	)
	(segment
		(start 109.47781 -222.272098)
		(end 109.478826 -222.27159)
		(width 0.0889)
		(layer "In2.Cu")
		(net "P5E_CPU1_PE1_TX_DN<10>")
	)
	(segment
		(start 30.152848 -20.978368)
		(end 30.199584 -20.778978)
		(width 0.14732)
		(layer "In2.Cu")
		(net "P5E_CPU1_PE1_TX_DN<10>")
	)
	(segment
		(start 109.46511 -218.360244)
		(end 109.464856 -218.35999)
		(width 0.0889)
		(layer "In2.Cu")
		(net "P5E_CPU1_PE1_TX_DN<10>")
	)
	(segment
		(start 109.665262 -220.327474)
		(end 109.665262 -220.319854)
		(width 0.0889)
		(layer "In2.Cu")
		(net "P5E_CPU1_PE1_TX_DN<10>")
	)
	(segment
		(start 109.464856 -219.987876)
		(end 109.464856 -219.987622)
		(width 0.0889)
		(layer "In2.Cu")
		(net "P5E_CPU1_PE1_TX_DN<10>")
	)
	(segment
		(start 30.546802 -21.338032)
		(end 30.347158 -21.291296)
		(width 0.14732)
		(layer "In2.Cu")
		(net "P5E_CPU1_PE1_TX_DN<10>")
	)
	(segment
		(start 109.4867 -223.256348)
		(end 109.47781 -223.251268)
		(width 0.0889)
		(layer "In2.Cu")
		(net "P5E_CPU1_PE1_TX_DN<10>")
	)
	(segment
		(start 109.956854 -220.814646)
		(end 109.947964 -220.809566)
		(width 0.0889)
		(layer "In2.Cu")
		(net "P5E_CPU1_PE1_TX_DN<10>")
	)
	(segment
		(start 109.478318 -219.01658)
		(end 109.48289 -219.013786)
		(width 0.0889)
		(layer "In2.Cu")
		(net "P5E_CPU1_PE1_TX_DN<10>")
	)
	(segment
		(start 109.947964 -221.458282)
		(end 109.956854 -221.453202)
		(width 0.0889)
		(layer "In2.Cu")
		(net "P5E_CPU1_PE1_TX_DN<10>")
	)
	(segment
		(start 109.017054 -215.931242)
		(end 109.008164 -215.926162)
		(width 0.0889)
		(layer "In2.Cu")
		(net "P5E_CPU1_PE1_TX_DN<10>")
	)
	(segment
		(start 109.469936 -219.021406)
		(end 109.474508 -219.018612)
		(width 0.0889)
		(layer "In2.Cu")
		(net "P5E_CPU1_PE1_TX_DN<10>")
	)
	(segment
		(start 109.195616 -222.783654)
		(end 109.195616 -222.746062)
		(width 0.0889)
		(layer "In2.Cu")
		(net "P5E_CPU1_PE1_TX_DN<10>")
	)
	(segment
		(start 109.483652 -218.370912)
		(end 109.478572 -218.367864)
		(width 0.0889)
		(layer "In2.Cu")
		(net "P5E_CPU1_PE1_TX_DN<10>")
	)
	(segment
		(start 109.008164 -215.926162)
		(end 109.002068 -215.922606)
		(width 0.0889)
		(layer "In2.Cu")
		(net "P5E_CPU1_PE1_TX_DN<10>")
	)
	(segment
		(start 109.483652 -216.743026)
		(end 109.47781 -216.739978)
		(width 0.0889)
		(layer "In2.Cu")
		(net "P5E_CPU1_PE1_TX_DN<10>")
	)
	(segment
		(start 30.740858 -21.650706)
		(end 30.546802 -21.338032)
		(width 0.14732)
		(layer "In2.Cu")
		(net "P5E_CPU1_PE1_TX_DN<10>")
	)
	(segment
		(start 109.4867 -220.000576)
		(end 109.478826 -219.996004)
		(width 0.0889)
		(layer "In2.Cu")
		(net "P5E_CPU1_PE1_TX_DN<10>")
	)
	(segment
		(start 109.947964 -224.065084)
		(end 109.944154 -224.062798)
		(width 0.0889)
		(layer "In2.Cu")
		(net "P5E_CPU1_PE1_TX_DN<10>")
	)
	(segment
		(start 108.725462 -215.436704)
		(end 108.725462 -215.414606)
		(width 0.0889)
		(layer "In2.Cu")
		(net "P5E_CPU1_PE1_TX_DN<10>")
	)
	(segment
		(start 104.947974 -185.492644)
		(end 70.845934 -96.547178)
		(width 0.14732)
		(layer "In2.Cu")
		(net "P5E_CPU1_PE1_TX_DN<10>")
	)
	(segment
		(start 30.888686 -22.163278)
		(end 30.694376 -21.850096)
		(width 0.14732)
		(layer "In2.Cu")
		(net "P5E_CPU1_PE1_TX_DN<10>")
	)
	(segment
		(start 31.08833 -22.20976)
		(end 30.888686 -22.163278)
		(width 0.14732)
		(layer "In2.Cu")
		(net "P5E_CPU1_PE1_TX_DN<10>")
	)
	(segment
		(start 109.195362 -214.592408)
		(end 109.195362 -213.575138)
		(width 0.0889)
		(layer "In2.Cu")
		(net "P5E_CPU1_PE1_TX_DN<10>")
	)
	(segment
		(start 109.153452 -213.51113)
		(end 109.153452 -212.40242)
		(width 0.14732)
		(layer "In2.Cu")
		(net "P5E_CPU1_PE1_TX_DN<10>")
	)
	(segment
		(start 105.874058 -189.07633)
		(end 104.947974 -185.492644)
		(width 0.14732)
		(layer "In2.Cu")
		(net "P5E_CPU1_PE1_TX_DN<10>")
	)
	(segment
		(start 30.199584 -20.778978)
		(end 29.798518 -20.133056)
		(width 0.14732)
		(layer "In2.Cu")
		(net "P5E_CPU1_PE1_TX_DN<10>")
	)
	(segment
		(start 29.798518 -20.133056)
		(end 29.798518 -19.431)
		(width 0.14732)
		(layer "In2.Cu")
		(net "P5E_CPU1_PE1_TX_DN<10>")
	)
	(segment
		(start 109.46765 -217.39479)
		(end 109.478572 -217.388694)
		(width 0.0889)
		(layer "In2.Cu")
		(net "P5E_CPU1_PE1_TX_DN<10>")
	)
	(segment
		(start 109.478826 -222.27159)
		(end 109.4867 -222.267018)
		(width 0.0889)
		(layer "In2.Cu")
		(net "P5E_CPU1_PE1_TX_DN<10>")
	)
	(segment
		(start 109.007656 -214.946992)
		(end 109.037628 -214.92972)
		(width 0.0889)
		(layer "In2.Cu")
		(net "P5E_CPU1_PE1_TX_DN<10>")
	)
	(segment
		(start 109.91723 -224.66046)
		(end 109.995462 -224.681288)
		(width 0.0889)
		(layer "In2.Cu")
		(net "P5E_CPU1_PE1_TX_DN<10>")
	)
	(segment
		(start 30.347158 -21.291296)
		(end 30.152848 -20.978368)
		(width 0.14732)
		(layer "In2.Cu")
		(net "P5E_CPU1_PE1_TX_DN<10>")
	)
	(segment
		(start 109.474508 -219.018612)
		(end 109.478318 -219.01658)
		(width 0.0889)
		(layer "In2.Cu")
		(net "P5E_CPU1_PE1_TX_DN<10>")
	)
	(segment
		(start 109.478064 -219.995242)
		(end 109.464856 -219.987876)
		(width 0.0889)
		(layer "In2.Cu")
		(net "P5E_CPU1_PE1_TX_DN<10>")
	)
	(segment
		(start 52.766214 -57.115202)
		(end 31.08833 -22.20976)
		(width 0.14732)
		(layer "In2.Cu")
		(net "P5E_CPU1_PE1_TX_DN<10>")
	)
	(segment
		(start 109.195362 -213.575138)
		(end 109.153452 -213.533228)
		(width 0.0889)
		(layer "In2.Cu")
		(net "P5E_CPU1_PE1_TX_DN<10>")
	)
	(segment
		(start 109.760766 -224.389442)
		(end 109.91723 -224.66046)
		(width 0.0889)
		(layer "In2.Cu")
		(net "P5E_CPU1_PE1_TX_DN<10>")
	)
	(segment
		(start 109.944154 -224.062798)
		(end 109.935772 -224.057972)
		(width 0.0889)
		(layer "In2.Cu")
		(net "P5E_CPU1_PE1_TX_DN<10>")
	)
	(segment
		(start 30.694376 -21.850096)
		(end 30.740858 -21.650706)
		(width 0.14732)
		(layer "In2.Cu")
		(net "P5E_CPU1_PE1_TX_DN<10>")
	)
	(segment
		(start 109.956854 -224.070164)
		(end 109.947964 -224.065084)
		(width 0.0889)
		(layer "In2.Cu")
		(net "P5E_CPU1_PE1_TX_DN<10>")
	)
	(segment
		(start 109.935772 -221.465394)
		(end 109.947964 -221.458282)
		(width 0.0889)
		(layer "In2.Cu")
		(net "P5E_CPU1_PE1_TX_DN<10>")
	)
	(segment
		(start 109.195616 -216.266014)
		(end 109.195616 -216.25052)
		(width 0.0889)
		(layer "In2.Cu")
		(net "P5E_CPU1_PE1_TX_DN<10>")
	)
	(segment
		(start 109.478826 -219.99575)
		(end 109.478064 -219.995242)
		(width 0.0889)
		(layer "In2.Cu")
		(net "P5E_CPU1_PE1_TX_DN<10>")
	)
	(arc
		(start 109.464856 -219.987622)
		(mid 109.195656 -219.506038)
		(end 109.464856 -219.024454)
		(width 0.0889)
		(layer "In2.Cu")
		(net "P5E_CPU1_PE1_TX_DN<10>")
	)
	(arc
		(start 110.135162 -221.121732)
		(mid 110.084669 -220.945754)
		(end 109.956854 -220.814646)
		(width 0.0889)
		(layer "In2.Cu")
		(net "P5E_CPU1_PE1_TX_DN<10>")
	)
	(arc
		(start 109.935772 -224.057972)
		(mid 109.737544 -223.852124)
		(end 109.665262 -223.575626)
		(width 0.0889)
		(layer "In2.Cu")
		(net "P5E_CPU1_PE1_TX_DN<10>")
	)
	(arc
		(start 109.19587 -217.856308)
		(mid 109.273625 -217.59131)
		(end 109.46765 -217.39479)
		(width 0.0889)
		(layer "In2.Cu")
		(net "P5E_CPU1_PE1_TX_DN<10>")
	)
	(arc
		(start 109.464856 -218.35999)
		(mid 109.271175 -218.16105)
		(end 109.195616 -217.8939)
		(width 0.0889)
		(layer "In2.Cu")
		(net "P5E_CPU1_PE1_TX_DN<10>")
	)
	(arc
		(start 110.135416 -224.389442)
		(mid 110.087737 -224.206542)
		(end 109.956854 -224.070164)
		(width 0.0889)
		(layer "In2.Cu")
		(net "P5E_CPU1_PE1_TX_DN<10>")
	)
	(arc
		(start 109.002068 -215.922606)
		(mid 108.799481 -215.716255)
		(end 108.725462 -215.436704)
		(width 0.0889)
		(layer "In2.Cu")
		(net "P5E_CPU1_PE1_TX_DN<10>")
	)
	(arc
		(start 109.995462 -224.681288)
		(mid 110.098607 -224.551263)
		(end 110.135416 -224.389442)
		(width 0.0889)
		(layer "In2.Cu")
		(net "P5E_CPU1_PE1_TX_DN<10>")
	)
	(arc
		(start 110.135416 -221.140528)
		(mid 110.135406 -221.131128)
		(end 110.135162 -221.121732)
		(width 0.0889)
		(layer "In2.Cu")
		(net "P5E_CPU1_PE1_TX_DN<10>")
	)
	(arc
		(start 109.48289 -219.013786)
		(mid 109.665277 -218.692614)
		(end 109.483652 -218.370912)
		(width 0.0889)
		(layer "In2.Cu")
		(net "P5E_CPU1_PE1_TX_DN<10>")
	)
	(arc
		(start 109.956854 -221.453202)
		(mid 110.086143 -221.319716)
		(end 110.135416 -221.140528)
		(width 0.0889)
		(layer "In2.Cu")
		(net "P5E_CPU1_PE1_TX_DN<10>")
	)
	(arc
		(start 109.195616 -222.746062)
		(mid 109.274986 -222.472328)
		(end 109.47781 -222.272098)
		(width 0.0889)
		(layer "In2.Cu")
		(net "P5E_CPU1_PE1_TX_DN<10>")
	)
	(arc
		(start 109.947964 -220.809566)
		(mid 109.742892 -220.605887)
		(end 109.665262 -220.327474)
		(width 0.0889)
		(layer "In2.Cu")
		(net "P5E_CPU1_PE1_TX_DN<10>")
	)
	(arc
		(start 109.037628 -214.92972)
		(mid 109.161166 -214.781953)
		(end 109.195362 -214.592408)
		(width 0.0889)
		(layer "In2.Cu")
		(net "P5E_CPU1_PE1_TX_DN<10>")
	)
	(arc
		(start 109.47781 -223.251268)
		(mid 109.276528 -223.053781)
		(end 109.195616 -222.783654)
		(width 0.0889)
		(layer "In2.Cu")
		(net "P5E_CPU1_PE1_TX_DN<10>")
	)
	(arc
		(start 109.478572 -217.388694)
		(mid 109.66561 -217.067298)
		(end 109.483652 -216.743026)
		(width 0.0889)
		(layer "In2.Cu")
		(net "P5E_CPU1_PE1_TX_DN<10>")
	)
	(arc
		(start 109.665262 -223.575626)
		(mid 109.617583 -223.392726)
		(end 109.4867 -223.256348)
		(width 0.0889)
		(layer "In2.Cu")
		(net "P5E_CPU1_PE1_TX_DN<10>")
	)
	(arc
		(start 109.47781 -216.739978)
		(mid 109.274987 -216.539747)
		(end 109.195616 -216.266014)
		(width 0.0889)
		(layer "In2.Cu")
		(net "P5E_CPU1_PE1_TX_DN<10>")
	)
	(arc
		(start 109.665262 -220.319854)
		(mid 109.617583 -220.136954)
		(end 109.4867 -220.000576)
		(width 0.0889)
		(layer "In2.Cu")
		(net "P5E_CPU1_PE1_TX_DN<10>")
	)
	(arc
		(start 108.725462 -215.414606)
		(mid 108.806373 -215.144478)
		(end 109.007656 -214.946992)
		(width 0.0889)
		(layer "In2.Cu")
		(net "P5E_CPU1_PE1_TX_DN<10>")
	)
	(arc
		(start 109.195616 -216.25052)
		(mid 109.147937 -216.06762)
		(end 109.017054 -215.931242)
		(width 0.0889)
		(layer "In2.Cu")
		(net "P5E_CPU1_PE1_TX_DN<10>")
	)
	(arc
		(start 109.665262 -221.94774)
		(mid 109.737497 -221.671216)
		(end 109.935772 -221.465394)
		(width 0.0889)
		(layer "In2.Cu")
		(net "P5E_CPU1_PE1_TX_DN<10>")
	)
	(arc
		(start 109.4867 -222.267018)
		(mid 109.617614 -222.130658)
		(end 109.665262 -221.94774)
		(width 0.0889)
		(layer "In2.Cu")
		(net "P5E_CPU1_PE1_TX_DN<10>")
	)
	(arc
		(start 109.195616 -217.8939)
		(mid 109.19543 -217.875102)
		(end 109.19587 -217.856308)
		(width 0.0889)
		(layer "In2.Cu")
		(net "P5E_CPU1_PE1_TX_DN<10>")
	)
	(segment
		(start 57.78373 -19.13636)
		(end 58.08472 -18.83537)
		(width 0.13208)
		(layer "F.Cu")
		(net "P5E_CPU1_PE1_TX_DN<0>")
	)
	(segment
		(start 58.08472 -18.216626)
		(end 57.75833 -17.890236)
		(width 0.13208)
		(layer "F.Cu")
		(net "P5E_CPU1_PE1_TX_DN<0>")
	)
	(segment
		(start 58.08472 -18.83537)
		(end 58.08472 -18.216626)
		(width 0.13208)
		(layer "F.Cu")
		(net "P5E_CPU1_PE1_TX_DN<0>")
	)
	(segment
		(start 119.158766 -224.925128)
		(end 119.158766 -224.389442)
		(width 0.13208)
		(layer "F.Cu")
		(net "P5E_CPU1_PE1_TX_DN<0>")
	)
	(segment
		(start 119.158512 -224.925382)
		(end 119.158766 -224.925128)
		(width 0.13208)
		(layer "F.Cu")
		(net "P5E_CPU1_PE1_TX_DN<0>")
	)
	(segment
		(start 118.87581 -215.761062)
		(end 118.8847 -215.755982)
		(width 0.0889)
		(layer "In2.Cu")
		(net "P5E_CPU1_PE1_TX_DN<0>")
	)
	(segment
		(start 119.339868 -218.20632)
		(end 119.345202 -218.203272)
		(width 0.0889)
		(layer "In2.Cu")
		(net "P5E_CPU1_PE1_TX_DN<0>")
	)
	(segment
		(start 57.969658 -22.12594)
		(end 58.110628 -21.977096)
		(width 0.14732)
		(layer "In2.Cu")
		(net "P5E_CPU1_PE1_TX_DN<0>")
	)
	(segment
		(start 118.8847 -220.000576)
		(end 118.876826 -219.996004)
		(width 0.0889)
		(layer "In2.Cu")
		(net "P5E_CPU1_PE1_TX_DN<0>")
	)
	(segment
		(start 58.094372 -21.382228)
		(end 57.945782 -21.241766)
		(width 0.14732)
		(layer "In2.Cu")
		(net "P5E_CPU1_PE1_TX_DN<0>")
	)
	(segment
		(start 119.339868 -221.461838)
		(end 119.345202 -221.45879)
		(width 0.0889)
		(layer "In2.Cu")
		(net "P5E_CPU1_PE1_TX_DN<0>")
	)
	(segment
		(start 119.345456 -214.946992)
		(end 119.354346 -214.941912)
		(width 0.0889)
		(layer "In2.Cu")
		(net "P5E_CPU1_PE1_TX_DN<0>")
	)
	(segment
		(start 119.345202 -218.203272)
		(end 119.345964 -218.202764)
		(width 0.0889)
		(layer "In2.Cu")
		(net "P5E_CPU1_PE1_TX_DN<0>")
	)
	(segment
		(start 119.345202 -221.45879)
		(end 119.345964 -221.458282)
		(width 0.0889)
		(layer "In2.Cu")
		(net "P5E_CPU1_PE1_TX_DN<0>")
	)
	(segment
		(start 119.347488 -218.202002)
		(end 119.354854 -218.197684)
		(width 0.0889)
		(layer "In2.Cu")
		(net "P5E_CPU1_PE1_TX_DN<0>")
	)
	(segment
		(start 118.876826 -216.740486)
		(end 118.87581 -216.739978)
		(width 0.0889)
		(layer "In2.Cu")
		(net "P5E_CPU1_PE1_TX_DN<0>")
	)
	(segment
		(start 118.876826 -219.996004)
		(end 118.87581 -219.995496)
		(width 0.0889)
		(layer "In2.Cu")
		(net "P5E_CPU1_PE1_TX_DN<0>")
	)
	(segment
		(start 119.345964 -218.202764)
		(end 119.347488 -218.202002)
		(width 0.0889)
		(layer "In2.Cu")
		(net "P5E_CPU1_PE1_TX_DN<0>")
	)
	(segment
		(start 118.8847 -216.745058)
		(end 118.876826 -216.740486)
		(width 0.0889)
		(layer "In2.Cu")
		(net "P5E_CPU1_PE1_TX_DN<0>")
	)
	(segment
		(start 58.062368 -19.414998)
		(end 57.78373 -19.13636)
		(width 0.14732)
		(layer "In2.Cu")
		(net "P5E_CPU1_PE1_TX_DN<0>")
	)
	(segment
		(start 119.063262 -215.436704)
		(end 119.063262 -215.414606)
		(width 0.0889)
		(layer "In2.Cu")
		(net "P5E_CPU1_PE1_TX_DN<0>")
	)
	(segment
		(start 119.021606 -209.70494)
		(end 115.340638 -187.166758)
		(width 0.14732)
		(layer "In2.Cu")
		(net "P5E_CPU1_PE1_TX_DN<0>")
	)
	(segment
		(start 118.87581 -222.272098)
		(end 118.8847 -222.267018)
		(width 0.0889)
		(layer "In2.Cu")
		(net "P5E_CPU1_PE1_TX_DN<0>")
	)
	(segment
		(start 57.935622 -20.873212)
		(end 58.076338 -20.724622)
		(width 0.14732)
		(layer "In2.Cu")
		(net "P5E_CPU1_PE1_TX_DN<0>")
	)
	(segment
		(start 119.354854 -220.814646)
		(end 119.346726 -220.810074)
		(width 0.0889)
		(layer "In2.Cu")
		(net "P5E_CPU1_PE1_TX_DN<0>")
	)
	(segment
		(start 119.021606 -213.2203)
		(end 119.021606 -209.70494)
		(width 0.14732)
		(layer "In2.Cu")
		(net "P5E_CPU1_PE1_TX_DN<0>")
	)
	(segment
		(start 119.345964 -224.065084)
		(end 119.342154 -224.062798)
		(width 0.0889)
		(layer "In2.Cu")
		(net "P5E_CPU1_PE1_TX_DN<0>")
	)
	(segment
		(start 118.593616 -222.783654)
		(end 118.593616 -222.746062)
		(width 0.0889)
		(layer "In2.Cu")
		(net "P5E_CPU1_PE1_TX_DN<0>")
	)
	(segment
		(start 57.979818 -22.49424)
		(end 57.969658 -22.12594)
		(width 0.14732)
		(layer "In2.Cu")
		(net "P5E_CPU1_PE1_TX_DN<0>")
	)
	(segment
		(start 119.348758 -214.261954)
		(end 119.137938 -214.051388)
		(width 0.0889)
		(layer "In2.Cu")
		(net "P5E_CPU1_PE1_TX_DN<0>")
	)
	(segment
		(start 58.076338 -20.724622)
		(end 58.062368 -20.207986)
		(width 0.14732)
		(layer "In2.Cu")
		(net "P5E_CPU1_PE1_TX_DN<0>")
	)
	(segment
		(start 58.79973 -47.18558)
		(end 58.128662 -22.634956)
		(width 0.14732)
		(layer "In2.Cu")
		(net "P5E_CPU1_PE1_TX_DN<0>")
	)
	(segment
		(start 119.346726 -220.810074)
		(end 119.345964 -220.809566)
		(width 0.0889)
		(layer "In2.Cu")
		(net "P5E_CPU1_PE1_TX_DN<0>")
	)
	(segment
		(start 115.340638 -187.166758)
		(end 114.45748 -184.103518)
		(width 0.14732)
		(layer "In2.Cu")
		(net "P5E_CPU1_PE1_TX_DN<0>")
	)
	(segment
		(start 119.342154 -224.062798)
		(end 119.333772 -224.057972)
		(width 0.0889)
		(layer "In2.Cu")
		(net "P5E_CPU1_PE1_TX_DN<0>")
	)
	(segment
		(start 118.87581 -219.01658)
		(end 118.8847 -219.0115)
		(width 0.0889)
		(layer "In2.Cu")
		(net "P5E_CPU1_PE1_TX_DN<0>")
	)
	(segment
		(start 58.110628 -21.977096)
		(end 58.094372 -21.382228)
		(width 0.14732)
		(layer "In2.Cu")
		(net "P5E_CPU1_PE1_TX_DN<0>")
	)
	(segment
		(start 114.45748 -184.103518)
		(end 114.219736 -183.515508)
		(width 0.14732)
		(layer "In2.Cu")
		(net "P5E_CPU1_PE1_TX_DN<0>")
	)
	(segment
		(start 57.945782 -21.241766)
		(end 57.935622 -20.873212)
		(width 0.14732)
		(layer "In2.Cu")
		(net "P5E_CPU1_PE1_TX_DN<0>")
	)
	(segment
		(start 78.06309 -89.198704)
		(end 58.79973 -47.18558)
		(width 0.14732)
		(layer "In2.Cu")
		(net "P5E_CPU1_PE1_TX_DN<0>")
	)
	(segment
		(start 119.31523 -224.66046)
		(end 119.393462 -224.681288)
		(width 0.0889)
		(layer "In2.Cu")
		(net "P5E_CPU1_PE1_TX_DN<0>")
	)
	(segment
		(start 119.063516 -213.870794)
		(end 119.063516 -213.284308)
		(width 0.0889)
		(layer "In2.Cu")
		(net "P5E_CPU1_PE1_TX_DN<0>")
	)
	(segment
		(start 119.345964 -221.458282)
		(end 119.347488 -221.45752)
		(width 0.0889)
		(layer "In2.Cu")
		(net "P5E_CPU1_PE1_TX_DN<0>")
	)
	(segment
		(start 114.219736 -183.515508)
		(end 78.06309 -89.198704)
		(width 0.14732)
		(layer "In2.Cu")
		(net "P5E_CPU1_PE1_TX_DN<0>")
	)
	(segment
		(start 119.158766 -224.389442)
		(end 119.31523 -224.66046)
		(width 0.0889)
		(layer "In2.Cu")
		(net "P5E_CPU1_PE1_TX_DN<0>")
	)
	(segment
		(start 119.063516 -213.284308)
		(end 119.021606 -213.242398)
		(width 0.0889)
		(layer "In2.Cu")
		(net "P5E_CPU1_PE1_TX_DN<0>")
	)
	(segment
		(start 119.346726 -217.554556)
		(end 119.345964 -217.554048)
		(width 0.0889)
		(layer "In2.Cu")
		(net "P5E_CPU1_PE1_TX_DN<0>")
	)
	(segment
		(start 118.593616 -216.266014)
		(end 118.593616 -216.235026)
		(width 0.0889)
		(layer "In2.Cu")
		(net "P5E_CPU1_PE1_TX_DN<0>")
	)
	(segment
		(start 118.8847 -223.256348)
		(end 118.87581 -223.251268)
		(width 0.0889)
		(layer "In2.Cu")
		(net "P5E_CPU1_PE1_TX_DN<0>")
	)
	(segment
		(start 119.063262 -217.071956)
		(end 119.063262 -217.064336)
		(width 0.0889)
		(layer "In2.Cu")
		(net "P5E_CPU1_PE1_TX_DN<0>")
	)
	(segment
		(start 119.021606 -213.242398)
		(end 119.021606 -213.2203)
		(width 0.0889)
		(layer "In2.Cu")
		(net "P5E_CPU1_PE1_TX_DN<0>")
	)
	(segment
		(start 119.532908 -214.622634)
		(end 119.532908 -214.461344)
		(width 0.0889)
		(layer "In2.Cu")
		(net "P5E_CPU1_PE1_TX_DN<0>")
	)
	(segment
		(start 119.354854 -224.070164)
		(end 119.345964 -224.065084)
		(width 0.0889)
		(layer "In2.Cu")
		(net "P5E_CPU1_PE1_TX_DN<0>")
	)
	(segment
		(start 119.063262 -220.327474)
		(end 119.063262 -220.319854)
		(width 0.0889)
		(layer "In2.Cu")
		(net "P5E_CPU1_PE1_TX_DN<0>")
	)
	(segment
		(start 119.354854 -217.559128)
		(end 119.346726 -217.554556)
		(width 0.0889)
		(layer "In2.Cu")
		(net "P5E_CPU1_PE1_TX_DN<0>")
	)
	(segment
		(start 118.593616 -219.521532)
		(end 118.593616 -219.490544)
		(width 0.0889)
		(layer "In2.Cu")
		(net "P5E_CPU1_PE1_TX_DN<0>")
	)
	(segment
		(start 119.347488 -221.45752)
		(end 119.354854 -221.453202)
		(width 0.0889)
		(layer "In2.Cu")
		(net "P5E_CPU1_PE1_TX_DN<0>")
	)
	(segment
		(start 119.137938 -214.051388)
		(end 119.063516 -213.870794)
		(width 0.0889)
		(layer "In2.Cu")
		(net "P5E_CPU1_PE1_TX_DN<0>")
	)
	(segment
		(start 58.062368 -20.207986)
		(end 58.062368 -19.414998)
		(width 0.14732)
		(layer "In2.Cu")
		(net "P5E_CPU1_PE1_TX_DN<0>")
	)
	(segment
		(start 58.128662 -22.634956)
		(end 57.979818 -22.49424)
		(width 0.14732)
		(layer "In2.Cu")
		(net "P5E_CPU1_PE1_TX_DN<0>")
	)
	(arc
		(start 119.063262 -223.575626)
		(mid 119.015583 -223.392726)
		(end 118.8847 -223.256348)
		(width 0.0889)
		(layer "In2.Cu")
		(net "P5E_CPU1_PE1_TX_DN<0>")
	)
	(arc
		(start 119.063262 -218.692222)
		(mid 119.137253 -218.412656)
		(end 119.339868 -218.20632)
		(width 0.0889)
		(layer "In2.Cu")
		(net "P5E_CPU1_PE1_TX_DN<0>")
	)
	(arc
		(start 119.366792 -214.272114)
		(mid 119.357838 -214.266923)
		(end 119.348758 -214.261954)
		(width 0.0889)
		(layer "In2.Cu")
		(net "P5E_CPU1_PE1_TX_DN<0>")
	)
	(arc
		(start 119.354854 -218.197684)
		(mid 119.533451 -217.878406)
		(end 119.354854 -217.559128)
		(width 0.0889)
		(layer "In2.Cu")
		(net "P5E_CPU1_PE1_TX_DN<0>")
	)
	(arc
		(start 118.8847 -215.755982)
		(mid 119.015614 -215.619622)
		(end 119.063262 -215.436704)
		(width 0.0889)
		(layer "In2.Cu")
		(net "P5E_CPU1_PE1_TX_DN<0>")
	)
	(arc
		(start 119.063262 -221.94774)
		(mid 119.137253 -221.668174)
		(end 119.339868 -221.461838)
		(width 0.0889)
		(layer "In2.Cu")
		(net "P5E_CPU1_PE1_TX_DN<0>")
	)
	(arc
		(start 119.532908 -214.461344)
		(mid 119.464828 -214.353577)
		(end 119.366792 -214.272114)
		(width 0.0889)
		(layer "In2.Cu")
		(net "P5E_CPU1_PE1_TX_DN<0>")
	)
	(arc
		(start 119.354854 -221.453202)
		(mid 119.533451 -221.133924)
		(end 119.354854 -220.814646)
		(width 0.0889)
		(layer "In2.Cu")
		(net "P5E_CPU1_PE1_TX_DN<0>")
	)
	(arc
		(start 118.8847 -222.267018)
		(mid 119.015614 -222.130658)
		(end 119.063262 -221.94774)
		(width 0.0889)
		(layer "In2.Cu")
		(net "P5E_CPU1_PE1_TX_DN<0>")
	)
	(arc
		(start 118.593616 -216.235026)
		(mid 118.672986 -215.961292)
		(end 118.87581 -215.761062)
		(width 0.0889)
		(layer "In2.Cu")
		(net "P5E_CPU1_PE1_TX_DN<0>")
	)
	(arc
		(start 119.063262 -220.319854)
		(mid 119.015583 -220.136954)
		(end 118.8847 -220.000576)
		(width 0.0889)
		(layer "In2.Cu")
		(net "P5E_CPU1_PE1_TX_DN<0>")
	)
	(arc
		(start 119.345964 -220.809566)
		(mid 119.140892 -220.605887)
		(end 119.063262 -220.327474)
		(width 0.0889)
		(layer "In2.Cu")
		(net "P5E_CPU1_PE1_TX_DN<0>")
	)
	(arc
		(start 119.533416 -224.389442)
		(mid 119.485737 -224.206542)
		(end 119.354854 -224.070164)
		(width 0.0889)
		(layer "In2.Cu")
		(net "P5E_CPU1_PE1_TX_DN<0>")
	)
	(arc
		(start 118.8847 -219.0115)
		(mid 119.015614 -218.87514)
		(end 119.063262 -218.692222)
		(width 0.0889)
		(layer "In2.Cu")
		(net "P5E_CPU1_PE1_TX_DN<0>")
	)
	(arc
		(start 118.87581 -223.251268)
		(mid 118.674528 -223.053781)
		(end 118.593616 -222.783654)
		(width 0.0889)
		(layer "In2.Cu")
		(net "P5E_CPU1_PE1_TX_DN<0>")
	)
	(arc
		(start 118.593616 -222.746062)
		(mid 118.672986 -222.472328)
		(end 118.87581 -222.272098)
		(width 0.0889)
		(layer "In2.Cu")
		(net "P5E_CPU1_PE1_TX_DN<0>")
	)
	(arc
		(start 119.063262 -215.414606)
		(mid 119.144173 -215.144478)
		(end 119.345456 -214.946992)
		(width 0.0889)
		(layer "In2.Cu")
		(net "P5E_CPU1_PE1_TX_DN<0>")
	)
	(arc
		(start 119.393462 -224.681288)
		(mid 119.496607 -224.551263)
		(end 119.533416 -224.389442)
		(width 0.0889)
		(layer "In2.Cu")
		(net "P5E_CPU1_PE1_TX_DN<0>")
	)
	(arc
		(start 119.345964 -217.554048)
		(mid 119.140892 -217.350369)
		(end 119.063262 -217.071956)
		(width 0.0889)
		(layer "In2.Cu")
		(net "P5E_CPU1_PE1_TX_DN<0>")
	)
	(arc
		(start 119.354346 -214.941912)
		(mid 119.48526 -214.805552)
		(end 119.532908 -214.622634)
		(width 0.0889)
		(layer "In2.Cu")
		(net "P5E_CPU1_PE1_TX_DN<0>")
	)
	(arc
		(start 118.593616 -219.490544)
		(mid 118.672986 -219.21681)
		(end 118.87581 -219.01658)
		(width 0.0889)
		(layer "In2.Cu")
		(net "P5E_CPU1_PE1_TX_DN<0>")
	)
	(arc
		(start 119.333772 -224.057972)
		(mid 119.135544 -223.852124)
		(end 119.063262 -223.575626)
		(width 0.0889)
		(layer "In2.Cu")
		(net "P5E_CPU1_PE1_TX_DN<0>")
	)
	(arc
		(start 118.87581 -219.995496)
		(mid 118.672987 -219.795265)
		(end 118.593616 -219.521532)
		(width 0.0889)
		(layer "In2.Cu")
		(net "P5E_CPU1_PE1_TX_DN<0>")
	)
	(arc
		(start 118.87581 -216.739978)
		(mid 118.672987 -216.539747)
		(end 118.593616 -216.266014)
		(width 0.0889)
		(layer "In2.Cu")
		(net "P5E_CPU1_PE1_TX_DN<0>")
	)
	(arc
		(start 119.063262 -217.064336)
		(mid 119.015583 -216.881436)
		(end 118.8847 -216.745058)
		(width 0.0889)
		(layer "In2.Cu")
		(net "P5E_CPU1_PE1_TX_DN<0>")
	)
	(segment
		(start 66.92138 -402.96465)
		(end 66.92138 -403.582378)
		(width 0.13208)
		(layer "F.Cu")
		(net "P5E_CPU1_PE0_TX_C_DP<9>")
	)
	(segment
		(start 66.92138 -403.582378)
		(end 67.222878 -403.883876)
		(width 0.13208)
		(layer "F.Cu")
		(net "P5E_CPU1_PE0_TX_C_DP<9>")
	)
	(segment
		(start 67.248278 -402.637752)
		(end 66.92138 -402.96465)
		(width 0.13208)
		(layer "F.Cu")
		(net "P5E_CPU1_PE0_TX_C_DP<9>")
	)
	(segment
		(start 69.966332 -416.854894)
		(end 69.96938 -416.680904)
		(width 0.14732)
		(layer "In11.Cu")
		(net "P5E_CPU1_PE0_TX_C_DP<9>")
	)
	(segment
		(start 70.090792 -430.119536)
		(end 69.966332 -429.995076)
		(width 0.14732)
		(layer "In11.Cu")
		(net "P5E_CPU1_PE0_TX_C_DP<9>")
	)
	(segment
		(start 66.928238 -404.178516)
		(end 67.222878 -403.883876)
		(width 0.14732)
		(layer "In11.Cu")
		(net "P5E_CPU1_PE0_TX_C_DP<9>")
	)
	(segment
		(start 68.429886 -413.523938)
		(end 68.240402 -413.467042)
		(width 0.14732)
		(layer "In11.Cu")
		(net "P5E_CPU1_PE0_TX_C_DP<9>")
	)
	(segment
		(start 69.130164 -414.857946)
		(end 68.923154 -414.473136)
		(width 0.14732)
		(layer "In11.Cu")
		(net "P5E_CPU1_PE0_TX_C_DP<9>")
	)
	(segment
		(start 67.277742 -411.677358)
		(end 66.748406 -410.69387)
		(width 0.14732)
		(layer "In11.Cu")
		(net "P5E_CPU1_PE0_TX_C_DP<9>")
	)
	(segment
		(start 68.923154 -414.473136)
		(end 68.754244 -414.422336)
		(width 0.14732)
		(layer "In11.Cu")
		(net "P5E_CPU1_PE0_TX_C_DP<9>")
	)
	(segment
		(start 68.754244 -414.422336)
		(end 68.547488 -414.03778)
		(width 0.14732)
		(layer "In11.Cu")
		(net "P5E_CPU1_PE0_TX_C_DP<9>")
	)
	(segment
		(start 67.759072 -412.5722)
		(end 67.584828 -412.248096)
		(width 0.14732)
		(layer "In11.Cu")
		(net "P5E_CPU1_PE0_TX_C_DP<9>")
	)
	(segment
		(start 69.96938 -416.680904)
		(end 69.079618 -415.026602)
		(width 0.14732)
		(layer "In11.Cu")
		(net "P5E_CPU1_PE0_TX_C_DP<9>")
	)
	(segment
		(start 67.948556 -412.629096)
		(end 67.759072 -412.5722)
		(width 0.14732)
		(layer "In11.Cu")
		(net "P5E_CPU1_PE0_TX_C_DP<9>")
	)
	(segment
		(start 66.748406 -410.69387)
		(end 66.742818 -410.683456)
		(width 0.14732)
		(layer "In11.Cu")
		(net "P5E_CPU1_PE0_TX_C_DP<9>")
	)
	(segment
		(start 68.604384 -413.84855)
		(end 68.429886 -413.523938)
		(width 0.14732)
		(layer "In11.Cu")
		(net "P5E_CPU1_PE0_TX_C_DP<9>")
	)
	(segment
		(start 68.066158 -413.142938)
		(end 68.123054 -412.953708)
		(width 0.14732)
		(layer "In11.Cu")
		(net "P5E_CPU1_PE0_TX_C_DP<9>")
	)
	(segment
		(start 68.123054 -412.953708)
		(end 67.948556 -412.629096)
		(width 0.14732)
		(layer "In11.Cu")
		(net "P5E_CPU1_PE0_TX_C_DP<9>")
	)
	(segment
		(start 69.079618 -415.026602)
		(end 69.130164 -414.857946)
		(width 0.14732)
		(layer "In11.Cu")
		(net "P5E_CPU1_PE0_TX_C_DP<9>")
	)
	(segment
		(start 68.240402 -413.467042)
		(end 68.066158 -413.142938)
		(width 0.14732)
		(layer "In11.Cu")
		(net "P5E_CPU1_PE0_TX_C_DP<9>")
	)
	(segment
		(start 69.966332 -429.995076)
		(end 69.966332 -416.854894)
		(width 0.14732)
		(layer "In11.Cu")
		(net "P5E_CPU1_PE0_TX_C_DP<9>")
	)
	(segment
		(start 70.6501 -429.971708)
		(end 70.502272 -430.119536)
		(width 0.14732)
		(layer "In11.Cu")
		(net "P5E_CPU1_PE0_TX_C_DP<9>")
	)
	(segment
		(start 70.502272 -430.119536)
		(end 70.090792 -430.119536)
		(width 0.14732)
		(layer "In11.Cu")
		(net "P5E_CPU1_PE0_TX_C_DP<9>")
	)
	(segment
		(start 66.928238 -406.233122)
		(end 66.928238 -404.178516)
		(width 0.14732)
		(layer "In11.Cu")
		(net "P5E_CPU1_PE0_TX_C_DP<9>")
	)
	(segment
		(start 66.742818 -410.683456)
		(end 66.742818 -406.418542)
		(width 0.14732)
		(layer "In11.Cu")
		(net "P5E_CPU1_PE0_TX_C_DP<9>")
	)
	(segment
		(start 66.742818 -406.418542)
		(end 66.928238 -406.233122)
		(width 0.14732)
		(layer "In11.Cu")
		(net "P5E_CPU1_PE0_TX_C_DP<9>")
	)
	(segment
		(start 67.466972 -411.734254)
		(end 67.277742 -411.677358)
		(width 0.14732)
		(layer "In11.Cu")
		(net "P5E_CPU1_PE0_TX_C_DP<9>")
	)
	(segment
		(start 67.584828 -412.248096)
		(end 67.64147 -412.058866)
		(width 0.14732)
		(layer "In11.Cu")
		(net "P5E_CPU1_PE0_TX_C_DP<9>")
	)
	(segment
		(start 70.6501 -429.689768)
		(end 70.6501 -429.971708)
		(width 0.14732)
		(layer "In11.Cu")
		(net "P5E_CPU1_PE0_TX_C_DP<9>")
	)
	(segment
		(start 68.547488 -414.03778)
		(end 68.604384 -413.84855)
		(width 0.14732)
		(layer "In11.Cu")
		(net "P5E_CPU1_PE0_TX_C_DP<9>")
	)
	(segment
		(start 67.64147 -412.058866)
		(end 67.466972 -411.734254)
		(width 0.14732)
		(layer "In11.Cu")
		(net "P5E_CPU1_PE0_TX_C_DP<9>")
	)
	(segment
		(start 69.98462 -403.582378)
		(end 70.286118 -403.883876)
		(width 0.13208)
		(layer "F.Cu")
		(net "P5E_CPU1_PE0_TX_C_DP<8>")
	)
	(segment
		(start 70.311518 -402.637752)
		(end 69.98462 -402.96465)
		(width 0.13208)
		(layer "F.Cu")
		(net "P5E_CPU1_PE0_TX_C_DP<8>")
	)
	(segment
		(start 69.98462 -402.96465)
		(end 69.98462 -403.582378)
		(width 0.13208)
		(layer "F.Cu")
		(net "P5E_CPU1_PE0_TX_C_DP<8>")
	)
	(segment
		(start 69.806058 -406.418542)
		(end 69.991478 -406.233122)
		(width 0.14732)
		(layer "In11.Cu")
		(net "P5E_CPU1_PE0_TX_C_DP<8>")
	)
	(segment
		(start 71.184262 -414.0454)
		(end 71.02856 -413.971232)
		(width 0.14732)
		(layer "In11.Cu")
		(net "P5E_CPU1_PE0_TX_C_DP<8>")
	)
	(segment
		(start 72.650096 -430.971706)
		(end 72.502268 -431.119534)
		(width 0.14732)
		(layer "In11.Cu")
		(net "P5E_CPU1_PE0_TX_C_DP<8>")
	)
	(segment
		(start 70.883272 -413.559498)
		(end 70.957694 -413.403796)
		(width 0.14732)
		(layer "In11.Cu")
		(net "P5E_CPU1_PE0_TX_C_DP<8>")
	)
	(segment
		(start 70.28434 -411.863286)
		(end 69.806058 -410.508704)
		(width 0.14732)
		(layer "In11.Cu")
		(net "P5E_CPU1_PE0_TX_C_DP<8>")
	)
	(segment
		(start 70.812152 -412.991554)
		(end 70.65645 -412.917386)
		(width 0.14732)
		(layer "In11.Cu")
		(net "P5E_CPU1_PE0_TX_C_DP<8>")
	)
	(segment
		(start 70.511162 -412.505652)
		(end 70.585584 -412.34995)
		(width 0.14732)
		(layer "In11.Cu")
		(net "P5E_CPU1_PE0_TX_C_DP<8>")
	)
	(segment
		(start 70.440042 -411.937708)
		(end 70.28434 -411.863286)
		(width 0.14732)
		(layer "In11.Cu")
		(net "P5E_CPU1_PE0_TX_C_DP<8>")
	)
	(segment
		(start 69.806058 -410.508704)
		(end 69.806058 -406.418542)
		(width 0.14732)
		(layer "In11.Cu")
		(net "P5E_CPU1_PE0_TX_C_DP<8>")
	)
	(segment
		(start 71.966328 -430.995074)
		(end 71.966328 -416.62731)
		(width 0.14732)
		(layer "In11.Cu")
		(net "P5E_CPU1_PE0_TX_C_DP<8>")
	)
	(segment
		(start 72.502268 -431.119534)
		(end 72.090788 -431.119534)
		(width 0.14732)
		(layer "In11.Cu")
		(net "P5E_CPU1_PE0_TX_C_DP<8>")
	)
	(segment
		(start 71.966328 -416.62731)
		(end 71.255382 -414.613344)
		(width 0.14732)
		(layer "In11.Cu")
		(net "P5E_CPU1_PE0_TX_C_DP<8>")
	)
	(segment
		(start 70.957694 -413.403796)
		(end 70.812152 -412.991554)
		(width 0.14732)
		(layer "In11.Cu")
		(net "P5E_CPU1_PE0_TX_C_DP<8>")
	)
	(segment
		(start 72.090788 -431.119534)
		(end 71.966328 -430.995074)
		(width 0.14732)
		(layer "In11.Cu")
		(net "P5E_CPU1_PE0_TX_C_DP<8>")
	)
	(segment
		(start 69.991478 -404.178516)
		(end 70.286118 -403.883876)
		(width 0.14732)
		(layer "In11.Cu")
		(net "P5E_CPU1_PE0_TX_C_DP<8>")
	)
	(segment
		(start 71.255382 -414.613344)
		(end 71.329804 -414.457642)
		(width 0.14732)
		(layer "In11.Cu")
		(net "P5E_CPU1_PE0_TX_C_DP<8>")
	)
	(segment
		(start 69.991478 -406.233122)
		(end 69.991478 -404.178516)
		(width 0.14732)
		(layer "In11.Cu")
		(net "P5E_CPU1_PE0_TX_C_DP<8>")
	)
	(segment
		(start 71.02856 -413.971232)
		(end 70.883272 -413.559498)
		(width 0.14732)
		(layer "In11.Cu")
		(net "P5E_CPU1_PE0_TX_C_DP<8>")
	)
	(segment
		(start 70.585584 -412.34995)
		(end 70.440042 -411.937708)
		(width 0.14732)
		(layer "In11.Cu")
		(net "P5E_CPU1_PE0_TX_C_DP<8>")
	)
	(segment
		(start 70.65645 -412.917386)
		(end 70.511162 -412.505652)
		(width 0.14732)
		(layer "In11.Cu")
		(net "P5E_CPU1_PE0_TX_C_DP<8>")
	)
	(segment
		(start 71.329804 -414.457642)
		(end 71.184262 -414.0454)
		(width 0.14732)
		(layer "In11.Cu")
		(net "P5E_CPU1_PE0_TX_C_DP<8>")
	)
	(segment
		(start 72.650096 -430.689766)
		(end 72.650096 -430.971706)
		(width 0.14732)
		(layer "In11.Cu")
		(net "P5E_CPU1_PE0_TX_C_DP<8>")
	)
	(segment
		(start 73.374758 -402.637752)
		(end 73.04786 -402.96465)
		(width 0.13208)
		(layer "F.Cu")
		(net "P5E_CPU1_PE0_TX_C_DP<7>")
	)
	(segment
		(start 73.04786 -403.582378)
		(end 73.349358 -403.883876)
		(width 0.13208)
		(layer "F.Cu")
		(net "P5E_CPU1_PE0_TX_C_DP<7>")
	)
	(segment
		(start 73.04786 -402.96465)
		(end 73.04786 -403.582378)
		(width 0.13208)
		(layer "F.Cu")
		(net "P5E_CPU1_PE0_TX_C_DP<7>")
	)
	(segment
		(start 73.478644 -413.178752)
		(end 73.376282 -413.317436)
		(width 0.14732)
		(layer "In11.Cu")
		(net "P5E_CPU1_PE0_TX_C_DP<7>")
	)
	(segment
		(start 74.966322 -423.888408)
		(end 74.966322 -429.995076)
		(width 0.14732)
		(layer "In11.Cu")
		(net "P5E_CPU1_PE0_TX_C_DP<7>")
	)
	(segment
		(start 73.349358 -403.883876)
		(end 73.054718 -404.178516)
		(width 0.14732)
		(layer "In11.Cu")
		(net "P5E_CPU1_PE0_TX_C_DP<7>")
	)
	(segment
		(start 73.312528 -412.073344)
		(end 73.210166 -412.212028)
		(width 0.14732)
		(layer "In11.Cu")
		(net "P5E_CPU1_PE0_TX_C_DP<7>")
	)
	(segment
		(start 73.57999 -413.851852)
		(end 73.645014 -414.28416)
		(width 0.14732)
		(layer "In11.Cu")
		(net "P5E_CPU1_PE0_TX_C_DP<7>")
	)
	(segment
		(start 73.542652 -414.422844)
		(end 73.607422 -414.854644)
		(width 0.14732)
		(layer "In11.Cu")
		(net "P5E_CPU1_PE0_TX_C_DP<7>")
	)
	(segment
		(start 75.65009 -429.971708)
		(end 75.65009 -429.689768)
		(width 0.14732)
		(layer "In11.Cu")
		(net "P5E_CPU1_PE0_TX_C_DP<7>")
	)
	(segment
		(start 73.709022 -415.527998)
		(end 74.966322 -423.888408)
		(width 0.14732)
		(layer "In11.Cu")
		(net "P5E_CPU1_PE0_TX_C_DP<7>")
	)
	(segment
		(start 73.74636 -414.957006)
		(end 73.811384 -415.389314)
		(width 0.14732)
		(layer "In11.Cu")
		(net "P5E_CPU1_PE0_TX_C_DP<7>")
	)
	(segment
		(start 75.090782 -430.119536)
		(end 75.502262 -430.119536)
		(width 0.14732)
		(layer "In11.Cu")
		(net "P5E_CPU1_PE0_TX_C_DP<7>")
	)
	(segment
		(start 73.413874 -412.746444)
		(end 73.478644 -413.178752)
		(width 0.14732)
		(layer "In11.Cu")
		(net "P5E_CPU1_PE0_TX_C_DP<7>")
	)
	(segment
		(start 73.054718 -404.178516)
		(end 73.054718 -406.233122)
		(width 0.14732)
		(layer "In11.Cu")
		(net "P5E_CPU1_PE0_TX_C_DP<7>")
	)
	(segment
		(start 73.10882 -411.53842)
		(end 73.247758 -411.641036)
		(width 0.14732)
		(layer "In11.Cu")
		(net "P5E_CPU1_PE0_TX_C_DP<7>")
	)
	(segment
		(start 73.607422 -414.854644)
		(end 73.74636 -414.957006)
		(width 0.14732)
		(layer "In11.Cu")
		(net "P5E_CPU1_PE0_TX_C_DP<7>")
	)
	(segment
		(start 73.210166 -412.212028)
		(end 73.274936 -412.643828)
		(width 0.14732)
		(layer "In11.Cu")
		(net "P5E_CPU1_PE0_TX_C_DP<7>")
	)
	(segment
		(start 74.966322 -429.995076)
		(end 75.090782 -430.119536)
		(width 0.14732)
		(layer "In11.Cu")
		(net "P5E_CPU1_PE0_TX_C_DP<7>")
	)
	(segment
		(start 73.376282 -413.317436)
		(end 73.441052 -413.749236)
		(width 0.14732)
		(layer "In11.Cu")
		(net "P5E_CPU1_PE0_TX_C_DP<7>")
	)
	(segment
		(start 75.502262 -430.119536)
		(end 75.65009 -429.971708)
		(width 0.14732)
		(layer "In11.Cu")
		(net "P5E_CPU1_PE0_TX_C_DP<7>")
	)
	(segment
		(start 72.869298 -410.309822)
		(end 73.03643 -411.056836)
		(width 0.14732)
		(layer "In11.Cu")
		(net "P5E_CPU1_PE0_TX_C_DP<7>")
	)
	(segment
		(start 73.03643 -411.056836)
		(end 73.10882 -411.53842)
		(width 0.14732)
		(layer "In11.Cu")
		(net "P5E_CPU1_PE0_TX_C_DP<7>")
	)
	(segment
		(start 73.247758 -411.641036)
		(end 73.312528 -412.073344)
		(width 0.14732)
		(layer "In11.Cu")
		(net "P5E_CPU1_PE0_TX_C_DP<7>")
	)
	(segment
		(start 73.054718 -406.233122)
		(end 72.869298 -406.418542)
		(width 0.14732)
		(layer "In11.Cu")
		(net "P5E_CPU1_PE0_TX_C_DP<7>")
	)
	(segment
		(start 73.441052 -413.749236)
		(end 73.57999 -413.851852)
		(width 0.14732)
		(layer "In11.Cu")
		(net "P5E_CPU1_PE0_TX_C_DP<7>")
	)
	(segment
		(start 73.811384 -415.389314)
		(end 73.709022 -415.527998)
		(width 0.14732)
		(layer "In11.Cu")
		(net "P5E_CPU1_PE0_TX_C_DP<7>")
	)
	(segment
		(start 72.869298 -406.418542)
		(end 72.869298 -410.309822)
		(width 0.14732)
		(layer "In11.Cu")
		(net "P5E_CPU1_PE0_TX_C_DP<7>")
	)
	(segment
		(start 73.645014 -414.28416)
		(end 73.542652 -414.422844)
		(width 0.14732)
		(layer "In11.Cu")
		(net "P5E_CPU1_PE0_TX_C_DP<7>")
	)
	(segment
		(start 73.274936 -412.643828)
		(end 73.413874 -412.746444)
		(width 0.14732)
		(layer "In11.Cu")
		(net "P5E_CPU1_PE0_TX_C_DP<7>")
	)
	(segment
		(start 76.1111 -403.582378)
		(end 76.412598 -403.883876)
		(width 0.13208)
		(layer "F.Cu")
		(net "P5E_CPU1_PE0_TX_C_DP<6>")
	)
	(segment
		(start 76.1111 -402.96465)
		(end 76.1111 -403.582378)
		(width 0.13208)
		(layer "F.Cu")
		(net "P5E_CPU1_PE0_TX_C_DP<6>")
	)
	(segment
		(start 76.437998 -402.637752)
		(end 76.1111 -402.96465)
		(width 0.13208)
		(layer "F.Cu")
		(net "P5E_CPU1_PE0_TX_C_DP<6>")
	)
	(segment
		(start 76.356464 -413.33293)
		(end 76.242926 -413.462724)
		(width 0.14732)
		(layer "In11.Cu")
		(net "P5E_CPU1_PE0_TX_C_DP<6>")
	)
	(segment
		(start 76.07935 -411.060646)
		(end 76.120498 -411.668214)
		(width 0.14732)
		(layer "In11.Cu")
		(net "P5E_CPU1_PE0_TX_C_DP<6>")
	)
	(segment
		(start 75.932538 -410.301948)
		(end 76.07935 -411.060646)
		(width 0.14732)
		(layer "In11.Cu")
		(net "P5E_CPU1_PE0_TX_C_DP<6>")
	)
	(segment
		(start 76.280518 -412.217616)
		(end 76.16698 -412.347664)
		(width 0.14732)
		(layer "In11.Cu")
		(net "P5E_CPU1_PE0_TX_C_DP<6>")
	)
	(segment
		(start 77.650086 -430.971706)
		(end 77.650086 -430.689766)
		(width 0.14732)
		(layer "In11.Cu")
		(net "P5E_CPU1_PE0_TX_C_DP<6>")
	)
	(segment
		(start 76.242926 -413.462724)
		(end 76.966318 -424.08729)
		(width 0.14732)
		(layer "In11.Cu")
		(net "P5E_CPU1_PE0_TX_C_DP<6>")
	)
	(segment
		(start 76.326746 -412.896812)
		(end 76.356464 -413.33293)
		(width 0.14732)
		(layer "In11.Cu")
		(net "P5E_CPU1_PE0_TX_C_DP<6>")
	)
	(segment
		(start 76.966318 -430.995074)
		(end 77.090778 -431.119534)
		(width 0.14732)
		(layer "In11.Cu")
		(net "P5E_CPU1_PE0_TX_C_DP<6>")
	)
	(segment
		(start 76.117958 -406.233122)
		(end 75.932538 -406.418542)
		(width 0.14732)
		(layer "In11.Cu")
		(net "P5E_CPU1_PE0_TX_C_DP<6>")
	)
	(segment
		(start 76.117958 -404.178516)
		(end 76.117958 -406.233122)
		(width 0.14732)
		(layer "In11.Cu")
		(net "P5E_CPU1_PE0_TX_C_DP<6>")
	)
	(segment
		(start 76.120498 -411.668214)
		(end 76.2508 -411.781498)
		(width 0.14732)
		(layer "In11.Cu")
		(net "P5E_CPU1_PE0_TX_C_DP<6>")
	)
	(segment
		(start 76.2508 -411.781498)
		(end 76.280518 -412.217616)
		(width 0.14732)
		(layer "In11.Cu")
		(net "P5E_CPU1_PE0_TX_C_DP<6>")
	)
	(segment
		(start 76.412598 -403.883876)
		(end 76.117958 -404.178516)
		(width 0.14732)
		(layer "In11.Cu")
		(net "P5E_CPU1_PE0_TX_C_DP<6>")
	)
	(segment
		(start 75.932538 -406.418542)
		(end 75.932538 -410.301948)
		(width 0.14732)
		(layer "In11.Cu")
		(net "P5E_CPU1_PE0_TX_C_DP<6>")
	)
	(segment
		(start 76.196444 -412.783528)
		(end 76.326746 -412.896812)
		(width 0.14732)
		(layer "In11.Cu")
		(net "P5E_CPU1_PE0_TX_C_DP<6>")
	)
	(segment
		(start 76.16698 -412.347664)
		(end 76.196444 -412.783528)
		(width 0.14732)
		(layer "In11.Cu")
		(net "P5E_CPU1_PE0_TX_C_DP<6>")
	)
	(segment
		(start 76.966318 -424.08729)
		(end 76.966318 -430.995074)
		(width 0.14732)
		(layer "In11.Cu")
		(net "P5E_CPU1_PE0_TX_C_DP<6>")
	)
	(segment
		(start 77.090778 -431.119534)
		(end 77.502258 -431.119534)
		(width 0.14732)
		(layer "In11.Cu")
		(net "P5E_CPU1_PE0_TX_C_DP<6>")
	)
	(segment
		(start 77.502258 -431.119534)
		(end 77.650086 -430.971706)
		(width 0.14732)
		(layer "In11.Cu")
		(net "P5E_CPU1_PE0_TX_C_DP<6>")
	)
	(segment
		(start 79.17434 -403.582378)
		(end 79.475838 -403.883876)
		(width 0.13208)
		(layer "F.Cu")
		(net "P5E_CPU1_PE0_TX_C_DP<5>")
	)
	(segment
		(start 79.501238 -402.637752)
		(end 79.17434 -402.96465)
		(width 0.13208)
		(layer "F.Cu")
		(net "P5E_CPU1_PE0_TX_C_DP<5>")
	)
	(segment
		(start 79.17434 -402.96465)
		(end 79.17434 -403.582378)
		(width 0.13208)
		(layer "F.Cu")
		(net "P5E_CPU1_PE0_TX_C_DP<5>")
	)
	(segment
		(start 79.650082 -429.971708)
		(end 79.650082 -429.689768)
		(width 0.14732)
		(layer "In11.Cu")
		(net "P5E_CPU1_PE0_TX_C_DP<5>")
	)
	(segment
		(start 79.137764 -421.15867)
		(end 79.133192 -421.527224)
		(width 0.14732)
		(layer "In11.Cu")
		(net "P5E_CPU1_PE0_TX_C_DP<5>")
	)
	(segment
		(start 79.01686 -419.633146)
		(end 79.012542 -420.001192)
		(width 0.14732)
		(layer "In11.Cu")
		(net "P5E_CPU1_PE0_TX_C_DP<5>")
	)
	(segment
		(start 79.502254 -430.119536)
		(end 79.650082 -429.971708)
		(width 0.14732)
		(layer "In11.Cu")
		(net "P5E_CPU1_PE0_TX_C_DP<5>")
	)
	(segment
		(start 78.999842 -421.017192)
		(end 79.137764 -421.15867)
		(width 0.14732)
		(layer "In11.Cu")
		(net "P5E_CPU1_PE0_TX_C_DP<5>")
	)
	(segment
		(start 78.978506 -422.728644)
		(end 78.966314 -423.731182)
		(width 0.14732)
		(layer "In11.Cu")
		(net "P5E_CPU1_PE0_TX_C_DP<5>")
	)
	(segment
		(start 79.124556 -422.222168)
		(end 79.120238 -422.590722)
		(width 0.14732)
		(layer "In11.Cu")
		(net "P5E_CPU1_PE0_TX_C_DP<5>")
	)
	(segment
		(start 78.995778 -410.338778)
		(end 79.096362 -413.15386)
		(width 0.14732)
		(layer "In11.Cu")
		(net "P5E_CPU1_PE0_TX_C_DP<5>")
	)
	(segment
		(start 79.181198 -406.233122)
		(end 78.995778 -406.418542)
		(width 0.14732)
		(layer "In11.Cu")
		(net "P5E_CPU1_PE0_TX_C_DP<5>")
	)
	(segment
		(start 79.145892 -420.51097)
		(end 79.00416 -420.649146)
		(width 0.14732)
		(layer "In11.Cu")
		(net "P5E_CPU1_PE0_TX_C_DP<5>")
	)
	(segment
		(start 79.181198 -404.178516)
		(end 79.181198 -406.233122)
		(width 0.14732)
		(layer "In11.Cu")
		(net "P5E_CPU1_PE0_TX_C_DP<5>")
	)
	(segment
		(start 79.133192 -421.527224)
		(end 78.991714 -421.665146)
		(width 0.14732)
		(layer "In11.Cu")
		(net "P5E_CPU1_PE0_TX_C_DP<5>")
	)
	(segment
		(start 78.966314 -429.995076)
		(end 79.090774 -430.119536)
		(width 0.14732)
		(layer "In11.Cu")
		(net "P5E_CPU1_PE0_TX_C_DP<5>")
	)
	(segment
		(start 79.120238 -422.590722)
		(end 78.978506 -422.728644)
		(width 0.14732)
		(layer "In11.Cu")
		(net "P5E_CPU1_PE0_TX_C_DP<5>")
	)
	(segment
		(start 78.991714 -421.665146)
		(end 78.986634 -422.08069)
		(width 0.14732)
		(layer "In11.Cu")
		(net "P5E_CPU1_PE0_TX_C_DP<5>")
	)
	(segment
		(start 79.158592 -419.49497)
		(end 79.01686 -419.633146)
		(width 0.14732)
		(layer "In11.Cu")
		(net "P5E_CPU1_PE0_TX_C_DP<5>")
	)
	(segment
		(start 79.012542 -420.001192)
		(end 79.150464 -420.142416)
		(width 0.14732)
		(layer "In11.Cu")
		(net "P5E_CPU1_PE0_TX_C_DP<5>")
	)
	(segment
		(start 79.024988 -418.985192)
		(end 79.163164 -419.126416)
		(width 0.14732)
		(layer "In11.Cu")
		(net "P5E_CPU1_PE0_TX_C_DP<5>")
	)
	(segment
		(start 79.090774 -430.119536)
		(end 79.502254 -430.119536)
		(width 0.14732)
		(layer "In11.Cu")
		(net "P5E_CPU1_PE0_TX_C_DP<5>")
	)
	(segment
		(start 78.995778 -406.418542)
		(end 78.995778 -410.338778)
		(width 0.14732)
		(layer "In11.Cu")
		(net "P5E_CPU1_PE0_TX_C_DP<5>")
	)
	(segment
		(start 78.986634 -422.08069)
		(end 79.124556 -422.222168)
		(width 0.14732)
		(layer "In11.Cu")
		(net "P5E_CPU1_PE0_TX_C_DP<5>")
	)
	(segment
		(start 79.475838 -403.883876)
		(end 79.181198 -404.178516)
		(width 0.14732)
		(layer "In11.Cu")
		(net "P5E_CPU1_PE0_TX_C_DP<5>")
	)
	(segment
		(start 79.163164 -419.126416)
		(end 79.158592 -419.49497)
		(width 0.14732)
		(layer "In11.Cu")
		(net "P5E_CPU1_PE0_TX_C_DP<5>")
	)
	(segment
		(start 79.096362 -413.15386)
		(end 79.024988 -418.985192)
		(width 0.14732)
		(layer "In11.Cu")
		(net "P5E_CPU1_PE0_TX_C_DP<5>")
	)
	(segment
		(start 79.00416 -420.649146)
		(end 78.999842 -421.017192)
		(width 0.14732)
		(layer "In11.Cu")
		(net "P5E_CPU1_PE0_TX_C_DP<5>")
	)
	(segment
		(start 79.150464 -420.142416)
		(end 79.145892 -420.51097)
		(width 0.14732)
		(layer "In11.Cu")
		(net "P5E_CPU1_PE0_TX_C_DP<5>")
	)
	(segment
		(start 78.966314 -423.731182)
		(end 78.966314 -429.995076)
		(width 0.14732)
		(layer "In11.Cu")
		(net "P5E_CPU1_PE0_TX_C_DP<5>")
	)
	(segment
		(start 82.23758 -403.582378)
		(end 82.539078 -403.883876)
		(width 0.13208)
		(layer "F.Cu")
		(net "P5E_CPU1_PE0_TX_C_DP<4>")
	)
	(segment
		(start 82.564478 -402.637752)
		(end 82.23758 -402.96465)
		(width 0.13208)
		(layer "F.Cu")
		(net "P5E_CPU1_PE0_TX_C_DP<4>")
	)
	(segment
		(start 82.23758 -402.96465)
		(end 82.23758 -403.582378)
		(width 0.13208)
		(layer "F.Cu")
		(net "P5E_CPU1_PE0_TX_C_DP<4>")
	)
	(segment
		(start 80.96631 -424.078908)
		(end 80.96631 -431.007266)
		(width 0.14732)
		(layer "In11.Cu")
		(net "P5E_CPU1_PE0_TX_C_DP<4>")
	)
	(segment
		(start 82.059018 -412.216346)
		(end 81.353914 -419.8747)
		(width 0.14732)
		(layer "In11.Cu")
		(net "P5E_CPU1_PE0_TX_C_DP<4>")
	)
	(segment
		(start 81.290668 -420.55796)
		(end 81.25079 -420.992808)
		(width 0.14732)
		(layer "In11.Cu")
		(net "P5E_CPU1_PE0_TX_C_DP<4>")
	)
	(segment
		(start 82.244438 -404.178516)
		(end 82.244438 -406.233122)
		(width 0.14732)
		(layer "In11.Cu")
		(net "P5E_CPU1_PE0_TX_C_DP<4>")
	)
	(segment
		(start 81.50225 -431.119534)
		(end 81.650078 -430.971706)
		(width 0.14732)
		(layer "In11.Cu")
		(net "P5E_CPU1_PE0_TX_C_DP<4>")
	)
	(segment
		(start 81.260188 -422.246044)
		(end 81.220056 -422.6814)
		(width 0.14732)
		(layer "In11.Cu")
		(net "P5E_CPU1_PE0_TX_C_DP<4>")
	)
	(segment
		(start 81.363312 -421.12819)
		(end 81.32318 -421.563546)
		(width 0.14732)
		(layer "In11.Cu")
		(net "P5E_CPU1_PE0_TX_C_DP<4>")
	)
	(segment
		(start 81.084674 -422.793922)
		(end 80.96631 -424.078908)
		(width 0.14732)
		(layer "In11.Cu")
		(net "P5E_CPU1_PE0_TX_C_DP<4>")
	)
	(segment
		(start 81.466436 -420.010082)
		(end 81.426304 -420.445438)
		(width 0.14732)
		(layer "In11.Cu")
		(net "P5E_CPU1_PE0_TX_C_DP<4>")
	)
	(segment
		(start 81.078578 -431.119534)
		(end 81.50225 -431.119534)
		(width 0.14732)
		(layer "In11.Cu")
		(net "P5E_CPU1_PE0_TX_C_DP<4>")
	)
	(segment
		(start 81.353914 -419.8747)
		(end 81.466436 -420.010082)
		(width 0.14732)
		(layer "In11.Cu")
		(net "P5E_CPU1_PE0_TX_C_DP<4>")
	)
	(segment
		(start 81.220056 -422.6814)
		(end 81.084674 -422.793922)
		(width 0.14732)
		(layer "In11.Cu")
		(net "P5E_CPU1_PE0_TX_C_DP<4>")
	)
	(segment
		(start 81.147666 -422.110916)
		(end 81.260188 -422.246044)
		(width 0.14732)
		(layer "In11.Cu")
		(net "P5E_CPU1_PE0_TX_C_DP<4>")
	)
	(segment
		(start 81.32318 -421.563546)
		(end 81.187544 -421.676068)
		(width 0.14732)
		(layer "In11.Cu")
		(net "P5E_CPU1_PE0_TX_C_DP<4>")
	)
	(segment
		(start 81.25079 -420.992808)
		(end 81.363312 -421.12819)
		(width 0.14732)
		(layer "In11.Cu")
		(net "P5E_CPU1_PE0_TX_C_DP<4>")
	)
	(segment
		(start 81.650078 -430.971706)
		(end 81.650078 -430.689766)
		(width 0.14732)
		(layer "In11.Cu")
		(net "P5E_CPU1_PE0_TX_C_DP<4>")
	)
	(segment
		(start 80.96631 -431.007266)
		(end 81.078578 -431.119534)
		(width 0.14732)
		(layer "In11.Cu")
		(net "P5E_CPU1_PE0_TX_C_DP<4>")
	)
	(segment
		(start 82.244438 -406.233122)
		(end 82.059018 -406.418542)
		(width 0.14732)
		(layer "In11.Cu")
		(net "P5E_CPU1_PE0_TX_C_DP<4>")
	)
	(segment
		(start 81.426304 -420.445438)
		(end 81.290668 -420.55796)
		(width 0.14732)
		(layer "In11.Cu")
		(net "P5E_CPU1_PE0_TX_C_DP<4>")
	)
	(segment
		(start 81.187544 -421.676068)
		(end 81.147666 -422.110916)
		(width 0.14732)
		(layer "In11.Cu")
		(net "P5E_CPU1_PE0_TX_C_DP<4>")
	)
	(segment
		(start 82.059018 -406.418542)
		(end 82.059018 -412.216346)
		(width 0.14732)
		(layer "In11.Cu")
		(net "P5E_CPU1_PE0_TX_C_DP<4>")
	)
	(segment
		(start 82.539078 -403.883876)
		(end 82.244438 -404.178516)
		(width 0.14732)
		(layer "In11.Cu")
		(net "P5E_CPU1_PE0_TX_C_DP<4>")
	)
	(segment
		(start 85.30082 -403.582378)
		(end 85.602318 -403.883876)
		(width 0.13208)
		(layer "F.Cu")
		(net "P5E_CPU1_PE0_TX_C_DP<3>")
	)
	(segment
		(start 85.627718 -402.637752)
		(end 85.30082 -402.96465)
		(width 0.13208)
		(layer "F.Cu")
		(net "P5E_CPU1_PE0_TX_C_DP<3>")
	)
	(segment
		(start 85.30082 -402.96465)
		(end 85.30082 -403.582378)
		(width 0.13208)
		(layer "F.Cu")
		(net "P5E_CPU1_PE0_TX_C_DP<3>")
	)
	(segment
		(start 83.555586 -420.744904)
		(end 83.49361 -421.10787)
		(width 0.14732)
		(layer "In11.Cu")
		(net "P5E_CPU1_PE0_TX_C_DP<3>")
	)
	(segment
		(start 83.545934 -421.63238)
		(end 83.38439 -421.746426)
		(width 0.14732)
		(layer "In11.Cu")
		(net "P5E_CPU1_PE0_TX_C_DP<3>")
	)
	(segment
		(start 85.307678 -404.178516)
		(end 85.307678 -406.233122)
		(width 0.14732)
		(layer "In11.Cu")
		(net "P5E_CPU1_PE0_TX_C_DP<3>")
	)
	(segment
		(start 83.502246 -430.119536)
		(end 83.650074 -429.971708)
		(width 0.14732)
		(layer "In11.Cu")
		(net "P5E_CPU1_PE0_TX_C_DP<3>")
	)
	(segment
		(start 82.966306 -429.995076)
		(end 83.090766 -430.119536)
		(width 0.14732)
		(layer "In11.Cu")
		(net "P5E_CPU1_PE0_TX_C_DP<3>")
	)
	(segment
		(start 83.950302 -419.265862)
		(end 83.888326 -419.629336)
		(width 0.14732)
		(layer "In11.Cu")
		(net "P5E_CPU1_PE0_TX_C_DP<3>")
	)
	(segment
		(start 83.322414 -422.109392)
		(end 83.436714 -422.270428)
		(width 0.14732)
		(layer "In11.Cu")
		(net "P5E_CPU1_PE0_TX_C_DP<3>")
	)
	(segment
		(start 83.090766 -430.119536)
		(end 83.502246 -430.119536)
		(width 0.14732)
		(layer "In11.Cu")
		(net "P5E_CPU1_PE0_TX_C_DP<3>")
	)
	(segment
		(start 83.60791 -421.268906)
		(end 83.545934 -421.63238)
		(width 0.14732)
		(layer "In11.Cu")
		(net "P5E_CPU1_PE0_TX_C_DP<3>")
	)
	(segment
		(start 83.38439 -421.746426)
		(end 83.322414 -422.109392)
		(width 0.14732)
		(layer "In11.Cu")
		(net "P5E_CPU1_PE0_TX_C_DP<3>")
	)
	(segment
		(start 83.650074 -429.971708)
		(end 83.650074 -429.689768)
		(width 0.14732)
		(layer "In11.Cu")
		(net "P5E_CPU1_PE0_TX_C_DP<3>")
	)
	(segment
		(start 83.71713 -420.630858)
		(end 83.555586 -420.744904)
		(width 0.14732)
		(layer "In11.Cu")
		(net "P5E_CPU1_PE0_TX_C_DP<3>")
	)
	(segment
		(start 85.307678 -406.233122)
		(end 85.122258 -406.418542)
		(width 0.14732)
		(layer "In11.Cu")
		(net "P5E_CPU1_PE0_TX_C_DP<3>")
	)
	(segment
		(start 83.836002 -419.104826)
		(end 83.950302 -419.265862)
		(width 0.14732)
		(layer "In11.Cu")
		(net "P5E_CPU1_PE0_TX_C_DP<3>")
	)
	(segment
		(start 83.374484 -422.633902)
		(end 83.213194 -422.747948)
		(width 0.14732)
		(layer "In11.Cu")
		(net "P5E_CPU1_PE0_TX_C_DP<3>")
	)
	(segment
		(start 83.213194 -422.747948)
		(end 82.966306 -424.192446)
		(width 0.14732)
		(layer "In11.Cu")
		(net "P5E_CPU1_PE0_TX_C_DP<3>")
	)
	(segment
		(start 85.122258 -411.578298)
		(end 83.836002 -419.104826)
		(width 0.14732)
		(layer "In11.Cu")
		(net "P5E_CPU1_PE0_TX_C_DP<3>")
	)
	(segment
		(start 83.436714 -422.270428)
		(end 83.374484 -422.633902)
		(width 0.14732)
		(layer "In11.Cu")
		(net "P5E_CPU1_PE0_TX_C_DP<3>")
	)
	(segment
		(start 83.664806 -420.106348)
		(end 83.779106 -420.267384)
		(width 0.14732)
		(layer "In11.Cu")
		(net "P5E_CPU1_PE0_TX_C_DP<3>")
	)
	(segment
		(start 83.49361 -421.10787)
		(end 83.60791 -421.268906)
		(width 0.14732)
		(layer "In11.Cu")
		(net "P5E_CPU1_PE0_TX_C_DP<3>")
	)
	(segment
		(start 83.726782 -419.743382)
		(end 83.664806 -420.106348)
		(width 0.14732)
		(layer "In11.Cu")
		(net "P5E_CPU1_PE0_TX_C_DP<3>")
	)
	(segment
		(start 85.602318 -403.883876)
		(end 85.307678 -404.178516)
		(width 0.14732)
		(layer "In11.Cu")
		(net "P5E_CPU1_PE0_TX_C_DP<3>")
	)
	(segment
		(start 85.122258 -406.418542)
		(end 85.122258 -411.578298)
		(width 0.14732)
		(layer "In11.Cu")
		(net "P5E_CPU1_PE0_TX_C_DP<3>")
	)
	(segment
		(start 83.888326 -419.629336)
		(end 83.726782 -419.743382)
		(width 0.14732)
		(layer "In11.Cu")
		(net "P5E_CPU1_PE0_TX_C_DP<3>")
	)
	(segment
		(start 83.779106 -420.267384)
		(end 83.71713 -420.630858)
		(width 0.14732)
		(layer "In11.Cu")
		(net "P5E_CPU1_PE0_TX_C_DP<3>")
	)
	(segment
		(start 82.966306 -424.192446)
		(end 82.966306 -429.995076)
		(width 0.14732)
		(layer "In11.Cu")
		(net "P5E_CPU1_PE0_TX_C_DP<3>")
	)
	(segment
		(start 88.36406 -403.582378)
		(end 88.665558 -403.883876)
		(width 0.13208)
		(layer "F.Cu")
		(net "P5E_CPU1_PE0_TX_C_DP<2>")
	)
	(segment
		(start 88.690958 -402.637752)
		(end 88.36406 -402.96465)
		(width 0.13208)
		(layer "F.Cu")
		(net "P5E_CPU1_PE0_TX_C_DP<2>")
	)
	(segment
		(start 88.36406 -402.96465)
		(end 88.36406 -403.582378)
		(width 0.13208)
		(layer "F.Cu")
		(net "P5E_CPU1_PE0_TX_C_DP<2>")
	)
	(segment
		(start 88.185498 -411.36697)
		(end 88.176862 -411.375606)
		(width 0.14732)
		(layer "In11.Cu")
		(net "P5E_CPU1_PE0_TX_C_DP<2>")
	)
	(segment
		(start 88.176862 -411.375606)
		(end 85.931248 -420.022528)
		(width 0.14732)
		(layer "In11.Cu")
		(net "P5E_CPU1_PE0_TX_C_DP<2>")
	)
	(segment
		(start 85.502242 -431.119534)
		(end 85.65007 -430.971706)
		(width 0.14732)
		(layer "In11.Cu")
		(net "P5E_CPU1_PE0_TX_C_DP<2>")
	)
	(segment
		(start 85.91042 -420.597584)
		(end 85.758528 -420.686738)
		(width 0.14732)
		(layer "In11.Cu")
		(net "P5E_CPU1_PE0_TX_C_DP<2>")
	)
	(segment
		(start 88.370918 -404.178516)
		(end 88.370918 -406.233122)
		(width 0.14732)
		(layer "In11.Cu")
		(net "P5E_CPU1_PE0_TX_C_DP<2>")
	)
	(segment
		(start 88.665558 -403.883876)
		(end 88.370918 -404.178516)
		(width 0.14732)
		(layer "In11.Cu")
		(net "P5E_CPU1_PE0_TX_C_DP<2>")
	)
	(segment
		(start 85.758528 -420.686738)
		(end 85.6488 -421.109394)
		(width 0.14732)
		(layer "In11.Cu")
		(net "P5E_CPU1_PE0_TX_C_DP<2>")
	)
	(segment
		(start 84.966302 -430.968658)
		(end 85.117178 -431.119534)
		(width 0.14732)
		(layer "In11.Cu")
		(net "P5E_CPU1_PE0_TX_C_DP<2>")
	)
	(segment
		(start 85.65007 -430.971706)
		(end 85.65007 -430.689766)
		(width 0.14732)
		(layer "In11.Cu")
		(net "P5E_CPU1_PE0_TX_C_DP<2>")
	)
	(segment
		(start 84.966302 -423.736262)
		(end 84.966302 -430.968658)
		(width 0.14732)
		(layer "In11.Cu")
		(net "P5E_CPU1_PE0_TX_C_DP<2>")
	)
	(segment
		(start 85.6488 -421.109394)
		(end 85.737954 -421.261286)
		(width 0.14732)
		(layer "In11.Cu")
		(net "P5E_CPU1_PE0_TX_C_DP<2>")
	)
	(segment
		(start 88.185498 -406.418542)
		(end 88.185498 -411.36697)
		(width 0.14732)
		(layer "In11.Cu")
		(net "P5E_CPU1_PE0_TX_C_DP<2>")
	)
	(segment
		(start 86.020402 -420.17442)
		(end 85.91042 -420.597584)
		(width 0.14732)
		(layer "In11.Cu")
		(net "P5E_CPU1_PE0_TX_C_DP<2>")
	)
	(segment
		(start 85.455506 -422.347898)
		(end 85.345778 -422.771062)
		(width 0.14732)
		(layer "In11.Cu")
		(net "P5E_CPU1_PE0_TX_C_DP<2>")
	)
	(segment
		(start 85.345778 -422.771062)
		(end 85.193632 -422.860216)
		(width 0.14732)
		(layer "In11.Cu")
		(net "P5E_CPU1_PE0_TX_C_DP<2>")
	)
	(segment
		(start 85.47608 -421.773604)
		(end 85.366352 -422.19626)
		(width 0.14732)
		(layer "In11.Cu")
		(net "P5E_CPU1_PE0_TX_C_DP<2>")
	)
	(segment
		(start 85.117178 -431.119534)
		(end 85.502242 -431.119534)
		(width 0.14732)
		(layer "In11.Cu")
		(net "P5E_CPU1_PE0_TX_C_DP<2>")
	)
	(segment
		(start 85.931248 -420.022528)
		(end 86.020402 -420.17442)
		(width 0.14732)
		(layer "In11.Cu")
		(net "P5E_CPU1_PE0_TX_C_DP<2>")
	)
	(segment
		(start 85.627972 -421.68445)
		(end 85.47608 -421.773604)
		(width 0.14732)
		(layer "In11.Cu")
		(net "P5E_CPU1_PE0_TX_C_DP<2>")
	)
	(segment
		(start 85.737954 -421.261286)
		(end 85.627972 -421.68445)
		(width 0.14732)
		(layer "In11.Cu")
		(net "P5E_CPU1_PE0_TX_C_DP<2>")
	)
	(segment
		(start 88.370918 -406.233122)
		(end 88.185498 -406.418542)
		(width 0.14732)
		(layer "In11.Cu")
		(net "P5E_CPU1_PE0_TX_C_DP<2>")
	)
	(segment
		(start 85.366352 -422.19626)
		(end 85.455506 -422.347898)
		(width 0.14732)
		(layer "In11.Cu")
		(net "P5E_CPU1_PE0_TX_C_DP<2>")
	)
	(segment
		(start 85.193632 -422.860216)
		(end 84.966302 -423.736262)
		(width 0.14732)
		(layer "In11.Cu")
		(net "P5E_CPU1_PE0_TX_C_DP<2>")
	)
	(segment
		(start 91.754198 -402.637752)
		(end 91.4273 -402.96465)
		(width 0.13208)
		(layer "F.Cu")
		(net "P5E_CPU1_PE0_TX_C_DP<1>")
	)
	(segment
		(start 91.4273 -402.96465)
		(end 91.4273 -403.582378)
		(width 0.13208)
		(layer "F.Cu")
		(net "P5E_CPU1_PE0_TX_C_DP<1>")
	)
	(segment
		(start 91.4273 -403.582378)
		(end 91.728798 -403.883876)
		(width 0.13208)
		(layer "F.Cu")
		(net "P5E_CPU1_PE0_TX_C_DP<1>")
	)
	(segment
		(start 87.502238 -430.119536)
		(end 87.650066 -429.971708)
		(width 0.14732)
		(layer "In11.Cu")
		(net "P5E_CPU1_PE0_TX_C_DP<1>")
	)
	(segment
		(start 87.98687 -421.327326)
		(end 88.076786 -421.503348)
		(width 0.14732)
		(layer "In11.Cu")
		(net "P5E_CPU1_PE0_TX_C_DP<1>")
	)
	(segment
		(start 87.764112 -422.470326)
		(end 87.650828 -422.820846)
		(width 0.14732)
		(layer "In11.Cu")
		(net "P5E_CPU1_PE0_TX_C_DP<1>")
	)
	(segment
		(start 88.276176 -420.887144)
		(end 88.0999 -420.97706)
		(width 0.14732)
		(layer "In11.Cu")
		(net "P5E_CPU1_PE0_TX_C_DP<1>")
	)
	(segment
		(start 88.076786 -421.503348)
		(end 87.963502 -421.854122)
		(width 0.14732)
		(layer "In11.Cu")
		(net "P5E_CPU1_PE0_TX_C_DP<1>")
	)
	(segment
		(start 88.38946 -420.53637)
		(end 88.276176 -420.887144)
		(width 0.14732)
		(layer "In11.Cu")
		(net "P5E_CPU1_PE0_TX_C_DP<1>")
	)
	(segment
		(start 87.963502 -421.854122)
		(end 87.787226 -421.944038)
		(width 0.14732)
		(layer "In11.Cu")
		(net "P5E_CPU1_PE0_TX_C_DP<1>")
	)
	(segment
		(start 86.966298 -424.484038)
		(end 86.966298 -429.995076)
		(width 0.14732)
		(layer "In11.Cu")
		(net "P5E_CPU1_PE0_TX_C_DP<1>")
	)
	(segment
		(start 91.248738 -411.236414)
		(end 88.299544 -420.360348)
		(width 0.14732)
		(layer "In11.Cu")
		(net "P5E_CPU1_PE0_TX_C_DP<1>")
	)
	(segment
		(start 87.650066 -429.971708)
		(end 87.650066 -429.689768)
		(width 0.14732)
		(layer "In11.Cu")
		(net "P5E_CPU1_PE0_TX_C_DP<1>")
	)
	(segment
		(start 87.35949 -423.267632)
		(end 87.44966 -423.443654)
		(width 0.14732)
		(layer "In11.Cu")
		(net "P5E_CPU1_PE0_TX_C_DP<1>")
	)
	(segment
		(start 87.44966 -423.443654)
		(end 87.336376 -423.794174)
		(width 0.14732)
		(layer "In11.Cu")
		(net "P5E_CPU1_PE0_TX_C_DP<1>")
	)
	(segment
		(start 88.299544 -420.360348)
		(end 88.38946 -420.53637)
		(width 0.14732)
		(layer "In11.Cu")
		(net "P5E_CPU1_PE0_TX_C_DP<1>")
	)
	(segment
		(start 88.0999 -420.97706)
		(end 87.98687 -421.327326)
		(width 0.14732)
		(layer "In11.Cu")
		(net "P5E_CPU1_PE0_TX_C_DP<1>")
	)
	(segment
		(start 91.434158 -404.178516)
		(end 91.434158 -406.233122)
		(width 0.14732)
		(layer "In11.Cu")
		(net "P5E_CPU1_PE0_TX_C_DP<1>")
	)
	(segment
		(start 87.090758 -430.119536)
		(end 87.502238 -430.119536)
		(width 0.14732)
		(layer "In11.Cu")
		(net "P5E_CPU1_PE0_TX_C_DP<1>")
	)
	(segment
		(start 87.674196 -422.294304)
		(end 87.764112 -422.470326)
		(width 0.14732)
		(layer "In11.Cu")
		(net "P5E_CPU1_PE0_TX_C_DP<1>")
	)
	(segment
		(start 87.650828 -422.820846)
		(end 87.474806 -422.910762)
		(width 0.14732)
		(layer "In11.Cu")
		(net "P5E_CPU1_PE0_TX_C_DP<1>")
	)
	(segment
		(start 87.787226 -421.944038)
		(end 87.674196 -422.294304)
		(width 0.14732)
		(layer "In11.Cu")
		(net "P5E_CPU1_PE0_TX_C_DP<1>")
	)
	(segment
		(start 87.1601 -423.88409)
		(end 86.966298 -424.484038)
		(width 0.14732)
		(layer "In11.Cu")
		(net "P5E_CPU1_PE0_TX_C_DP<1>")
	)
	(segment
		(start 91.728798 -403.883876)
		(end 91.434158 -404.178516)
		(width 0.14732)
		(layer "In11.Cu")
		(net "P5E_CPU1_PE0_TX_C_DP<1>")
	)
	(segment
		(start 91.248738 -406.418542)
		(end 91.248738 -411.236414)
		(width 0.14732)
		(layer "In11.Cu")
		(net "P5E_CPU1_PE0_TX_C_DP<1>")
	)
	(segment
		(start 87.336376 -423.794174)
		(end 87.1601 -423.88409)
		(width 0.14732)
		(layer "In11.Cu")
		(net "P5E_CPU1_PE0_TX_C_DP<1>")
	)
	(segment
		(start 86.966298 -429.995076)
		(end 87.090758 -430.119536)
		(width 0.14732)
		(layer "In11.Cu")
		(net "P5E_CPU1_PE0_TX_C_DP<1>")
	)
	(segment
		(start 87.474806 -422.910762)
		(end 87.35949 -423.267632)
		(width 0.14732)
		(layer "In11.Cu")
		(net "P5E_CPU1_PE0_TX_C_DP<1>")
	)
	(segment
		(start 91.434158 -406.233122)
		(end 91.248738 -406.418542)
		(width 0.14732)
		(layer "In11.Cu")
		(net "P5E_CPU1_PE0_TX_C_DP<1>")
	)
	(segment
		(start 48.868838 -402.637752)
		(end 48.54194 -402.96465)
		(width 0.13208)
		(layer "F.Cu")
		(net "P5E_CPU1_PE0_TX_C_DP<15>")
	)
	(segment
		(start 48.54194 -403.582378)
		(end 48.843438 -403.883876)
		(width 0.13208)
		(layer "F.Cu")
		(net "P5E_CPU1_PE0_TX_C_DP<15>")
	)
	(segment
		(start 48.54194 -402.96465)
		(end 48.54194 -403.582378)
		(width 0.13208)
		(layer "F.Cu")
		(net "P5E_CPU1_PE0_TX_C_DP<15>")
	)
	(segment
		(start 50.85842 -413.530288)
		(end 49.109884 -411.53461)
		(width 0.14732)
		(layer "In11.Cu")
		(net "P5E_CPU1_PE0_TX_C_DP<15>")
	)
	(segment
		(start 48.363378 -410.341572)
		(end 48.363378 -406.418542)
		(width 0.14732)
		(layer "In11.Cu")
		(net "P5E_CPU1_PE0_TX_C_DP<15>")
	)
	(segment
		(start 48.548798 -404.178516)
		(end 48.843438 -403.883876)
		(width 0.14732)
		(layer "In11.Cu")
		(net "P5E_CPU1_PE0_TX_C_DP<15>")
	)
	(segment
		(start 53.778912 -420.550086)
		(end 53.637688 -420.210234)
		(width 0.14732)
		(layer "In11.Cu")
		(net "P5E_CPU1_PE0_TX_C_DP<15>")
	)
	(segment
		(start 57.533032 -429.573436)
		(end 54.418484 -422.086786)
		(width 0.14732)
		(layer "In11.Cu")
		(net "P5E_CPU1_PE0_TX_C_DP<15>")
	)
	(segment
		(start 54.352444 -421.5638)
		(end 54.16931 -421.488362)
		(width 0.14732)
		(layer "In11.Cu")
		(net "P5E_CPU1_PE0_TX_C_DP<15>")
	)
	(segment
		(start 53.322474 -419.089078)
		(end 53.180996 -418.748972)
		(width 0.14732)
		(layer "In11.Cu")
		(net "P5E_CPU1_PE0_TX_C_DP<15>")
	)
	(segment
		(start 54.493668 -421.90416)
		(end 54.352444 -421.5638)
		(width 0.14732)
		(layer "In11.Cu")
		(net "P5E_CPU1_PE0_TX_C_DP<15>")
	)
	(segment
		(start 58.079386 -430.119536)
		(end 57.533032 -429.573436)
		(width 0.14732)
		(layer "In11.Cu")
		(net "P5E_CPU1_PE0_TX_C_DP<15>")
	)
	(segment
		(start 54.10327 -420.965884)
		(end 53.962046 -420.625524)
		(width 0.14732)
		(layer "In11.Cu")
		(net "P5E_CPU1_PE0_TX_C_DP<15>")
	)
	(segment
		(start 53.571648 -419.687248)
		(end 53.388514 -419.61181)
		(width 0.14732)
		(layer "In11.Cu")
		(net "P5E_CPU1_PE0_TX_C_DP<15>")
	)
	(segment
		(start 49.109884 -411.53461)
		(end 48.363378 -410.341572)
		(width 0.14732)
		(layer "In11.Cu")
		(net "P5E_CPU1_PE0_TX_C_DP<15>")
	)
	(segment
		(start 53.180996 -418.748972)
		(end 52.998116 -418.673534)
		(width 0.14732)
		(layer "In11.Cu")
		(net "P5E_CPU1_PE0_TX_C_DP<15>")
	)
	(segment
		(start 53.637688 -420.210234)
		(end 53.713126 -420.027608)
		(width 0.14732)
		(layer "In11.Cu")
		(net "P5E_CPU1_PE0_TX_C_DP<15>")
	)
	(segment
		(start 54.028086 -421.14851)
		(end 54.10327 -420.965884)
		(width 0.14732)
		(layer "In11.Cu")
		(net "P5E_CPU1_PE0_TX_C_DP<15>")
	)
	(segment
		(start 54.418484 -422.086786)
		(end 54.493668 -421.90416)
		(width 0.14732)
		(layer "In11.Cu")
		(net "P5E_CPU1_PE0_TX_C_DP<15>")
	)
	(segment
		(start 53.713126 -420.027608)
		(end 53.571648 -419.687248)
		(width 0.14732)
		(layer "In11.Cu")
		(net "P5E_CPU1_PE0_TX_C_DP<15>")
	)
	(segment
		(start 48.363378 -406.418542)
		(end 48.548798 -406.233122)
		(width 0.14732)
		(layer "In11.Cu")
		(net "P5E_CPU1_PE0_TX_C_DP<15>")
	)
	(segment
		(start 53.388514 -419.61181)
		(end 53.24729 -419.271958)
		(width 0.14732)
		(layer "In11.Cu")
		(net "P5E_CPU1_PE0_TX_C_DP<15>")
	)
	(segment
		(start 58.502296 -430.119536)
		(end 58.079386 -430.119536)
		(width 0.14732)
		(layer "In11.Cu")
		(net "P5E_CPU1_PE0_TX_C_DP<15>")
	)
	(segment
		(start 58.650124 -429.689768)
		(end 58.650124 -429.971708)
		(width 0.14732)
		(layer "In11.Cu")
		(net "P5E_CPU1_PE0_TX_C_DP<15>")
	)
	(segment
		(start 53.24729 -419.271958)
		(end 53.322474 -419.089078)
		(width 0.14732)
		(layer "In11.Cu")
		(net "P5E_CPU1_PE0_TX_C_DP<15>")
	)
	(segment
		(start 54.16931 -421.488362)
		(end 54.028086 -421.14851)
		(width 0.14732)
		(layer "In11.Cu")
		(net "P5E_CPU1_PE0_TX_C_DP<15>")
	)
	(segment
		(start 58.650124 -429.971708)
		(end 58.502296 -430.119536)
		(width 0.14732)
		(layer "In11.Cu")
		(net "P5E_CPU1_PE0_TX_C_DP<15>")
	)
	(segment
		(start 48.548798 -406.233122)
		(end 48.548798 -404.178516)
		(width 0.14732)
		(layer "In11.Cu")
		(net "P5E_CPU1_PE0_TX_C_DP<15>")
	)
	(segment
		(start 52.998116 -418.673534)
		(end 50.85842 -413.530288)
		(width 0.14732)
		(layer "In11.Cu")
		(net "P5E_CPU1_PE0_TX_C_DP<15>")
	)
	(segment
		(start 53.962046 -420.625524)
		(end 53.778912 -420.550086)
		(width 0.14732)
		(layer "In11.Cu")
		(net "P5E_CPU1_PE0_TX_C_DP<15>")
	)
	(segment
		(start 51.60518 -402.96465)
		(end 51.60518 -403.582378)
		(width 0.13208)
		(layer "F.Cu")
		(net "P5E_CPU1_PE0_TX_C_DP<14>")
	)
	(segment
		(start 51.60518 -403.582378)
		(end 51.906678 -403.883876)
		(width 0.13208)
		(layer "F.Cu")
		(net "P5E_CPU1_PE0_TX_C_DP<14>")
	)
	(segment
		(start 51.932078 -402.637752)
		(end 51.60518 -402.96465)
		(width 0.13208)
		(layer "F.Cu")
		(net "P5E_CPU1_PE0_TX_C_DP<14>")
	)
	(segment
		(start 55.095648 -413.124396)
		(end 55.076344 -412.9278)
		(width 0.14732)
		(layer "In11.Cu")
		(net "P5E_CPU1_PE0_TX_C_DP<14>")
	)
	(segment
		(start 60.502292 -431.119534)
		(end 60.090812 -431.119534)
		(width 0.14732)
		(layer "In11.Cu")
		(net "P5E_CPU1_PE0_TX_C_DP<14>")
	)
	(segment
		(start 55.867808 -413.577532)
		(end 55.58282 -413.343598)
		(width 0.14732)
		(layer "In11.Cu")
		(net "P5E_CPU1_PE0_TX_C_DP<14>")
	)
	(segment
		(start 51.593496 -410.830522)
		(end 51.426618 -410.319728)
		(width 0.14732)
		(layer "In11.Cu")
		(net "P5E_CPU1_PE0_TX_C_DP<14>")
	)
	(segment
		(start 59.966352 -417.68268)
		(end 59.614562 -416.83305)
		(width 0.14732)
		(layer "In11.Cu")
		(net "P5E_CPU1_PE0_TX_C_DP<14>")
	)
	(segment
		(start 53.487828 -411.80512)
		(end 51.937158 -411.195266)
		(width 0.14732)
		(layer "In11.Cu")
		(net "P5E_CPU1_PE0_TX_C_DP<14>")
	)
	(segment
		(start 54.791356 -412.693866)
		(end 54.59476 -412.713424)
		(width 0.14732)
		(layer "In11.Cu")
		(net "P5E_CPU1_PE0_TX_C_DP<14>")
	)
	(segment
		(start 60.090812 -431.119534)
		(end 59.966352 -430.995074)
		(width 0.14732)
		(layer "In11.Cu")
		(net "P5E_CPU1_PE0_TX_C_DP<14>")
	)
	(segment
		(start 51.937158 -411.195266)
		(end 51.593496 -410.830522)
		(width 0.14732)
		(layer "In11.Cu")
		(net "P5E_CPU1_PE0_TX_C_DP<14>")
	)
	(segment
		(start 55.887112 -413.774128)
		(end 55.867808 -413.577532)
		(width 0.14732)
		(layer "In11.Cu")
		(net "P5E_CPU1_PE0_TX_C_DP<14>")
	)
	(segment
		(start 59.614562 -416.83305)
		(end 56.672734 -414.41878)
		(width 0.14732)
		(layer "In11.Cu")
		(net "P5E_CPU1_PE0_TX_C_DP<14>")
	)
	(segment
		(start 51.426618 -410.319728)
		(end 51.426618 -406.418542)
		(width 0.14732)
		(layer "In11.Cu")
		(net "P5E_CPU1_PE0_TX_C_DP<14>")
	)
	(segment
		(start 51.612038 -404.178516)
		(end 51.906678 -403.883876)
		(width 0.14732)
		(layer "In11.Cu")
		(net "P5E_CPU1_PE0_TX_C_DP<14>")
	)
	(segment
		(start 60.65012 -430.689766)
		(end 60.65012 -430.971706)
		(width 0.14732)
		(layer "In11.Cu")
		(net "P5E_CPU1_PE0_TX_C_DP<14>")
	)
	(segment
		(start 56.171592 -414.007554)
		(end 55.887112 -413.774128)
		(width 0.14732)
		(layer "In11.Cu")
		(net "P5E_CPU1_PE0_TX_C_DP<14>")
	)
	(segment
		(start 55.58282 -413.343598)
		(end 55.386224 -413.362902)
		(width 0.14732)
		(layer "In11.Cu")
		(net "P5E_CPU1_PE0_TX_C_DP<14>")
	)
	(segment
		(start 55.386224 -413.362902)
		(end 55.095648 -413.124396)
		(width 0.14732)
		(layer "In11.Cu")
		(net "P5E_CPU1_PE0_TX_C_DP<14>")
	)
	(segment
		(start 59.966352 -430.995074)
		(end 59.966352 -417.68268)
		(width 0.14732)
		(layer "In11.Cu")
		(net "P5E_CPU1_PE0_TX_C_DP<14>")
	)
	(segment
		(start 51.426618 -406.418542)
		(end 51.612038 -406.233122)
		(width 0.14732)
		(layer "In11.Cu")
		(net "P5E_CPU1_PE0_TX_C_DP<14>")
	)
	(segment
		(start 55.076344 -412.9278)
		(end 54.791356 -412.693866)
		(width 0.14732)
		(layer "In11.Cu")
		(net "P5E_CPU1_PE0_TX_C_DP<14>")
	)
	(segment
		(start 56.672734 -414.41878)
		(end 56.653176 -414.222184)
		(width 0.14732)
		(layer "In11.Cu")
		(net "P5E_CPU1_PE0_TX_C_DP<14>")
	)
	(segment
		(start 54.59476 -412.713424)
		(end 53.487828 -411.80512)
		(width 0.14732)
		(layer "In11.Cu")
		(net "P5E_CPU1_PE0_TX_C_DP<14>")
	)
	(segment
		(start 51.612038 -406.233122)
		(end 51.612038 -404.178516)
		(width 0.14732)
		(layer "In11.Cu")
		(net "P5E_CPU1_PE0_TX_C_DP<14>")
	)
	(segment
		(start 56.653176 -414.222184)
		(end 56.368188 -413.98825)
		(width 0.14732)
		(layer "In11.Cu")
		(net "P5E_CPU1_PE0_TX_C_DP<14>")
	)
	(segment
		(start 56.368188 -413.98825)
		(end 56.171592 -414.007554)
		(width 0.14732)
		(layer "In11.Cu")
		(net "P5E_CPU1_PE0_TX_C_DP<14>")
	)
	(segment
		(start 60.65012 -430.971706)
		(end 60.502292 -431.119534)
		(width 0.14732)
		(layer "In11.Cu")
		(net "P5E_CPU1_PE0_TX_C_DP<14>")
	)
	(segment
		(start 54.995318 -402.637752)
		(end 54.66842 -402.96465)
		(width 0.13208)
		(layer "F.Cu")
		(net "P5E_CPU1_PE0_TX_C_DP<13>")
	)
	(segment
		(start 54.66842 -402.96465)
		(end 54.66842 -403.582378)
		(width 0.13208)
		(layer "F.Cu")
		(net "P5E_CPU1_PE0_TX_C_DP<13>")
	)
	(segment
		(start 54.66842 -403.582378)
		(end 54.969918 -403.883876)
		(width 0.13208)
		(layer "F.Cu")
		(net "P5E_CPU1_PE0_TX_C_DP<13>")
	)
	(segment
		(start 57.013094 -412.342838)
		(end 56.728106 -412.108904)
		(width 0.14732)
		(layer "In11.Cu")
		(net "P5E_CPU1_PE0_TX_C_DP<13>")
	)
	(segment
		(start 57.81802 -413.184086)
		(end 57.798462 -412.98749)
		(width 0.14732)
		(layer "In11.Cu")
		(net "P5E_CPU1_PE0_TX_C_DP<13>")
	)
	(segment
		(start 54.489858 -410.319728)
		(end 54.489858 -406.418542)
		(width 0.14732)
		(layer "In11.Cu")
		(net "P5E_CPU1_PE0_TX_C_DP<13>")
	)
	(segment
		(start 58.940954 -414.105852)
		(end 58.603388 -413.828738)
		(width 0.14732)
		(layer "In11.Cu")
		(net "P5E_CPU1_PE0_TX_C_DP<13>")
	)
	(segment
		(start 57.513474 -412.753556)
		(end 57.316878 -412.77286)
		(width 0.14732)
		(layer "In11.Cu")
		(net "P5E_CPU1_PE0_TX_C_DP<13>")
	)
	(segment
		(start 61.966348 -429.995076)
		(end 61.966348 -416.929824)
		(width 0.14732)
		(layer "In11.Cu")
		(net "P5E_CPU1_PE0_TX_C_DP<13>")
	)
	(segment
		(start 57.032398 -412.539434)
		(end 57.013094 -412.342838)
		(width 0.14732)
		(layer "In11.Cu")
		(net "P5E_CPU1_PE0_TX_C_DP<13>")
	)
	(segment
		(start 58.584084 -413.632142)
		(end 58.299096 -413.398208)
		(width 0.14732)
		(layer "In11.Cu")
		(net "P5E_CPU1_PE0_TX_C_DP<13>")
	)
	(segment
		(start 62.090808 -430.119536)
		(end 61.966348 -429.995076)
		(width 0.14732)
		(layer "In11.Cu")
		(net "P5E_CPU1_PE0_TX_C_DP<13>")
	)
	(segment
		(start 56.53151 -412.128208)
		(end 55.83555 -411.557216)
		(width 0.14732)
		(layer "In11.Cu")
		(net "P5E_CPU1_PE0_TX_C_DP<13>")
	)
	(segment
		(start 55.83555 -411.557216)
		(end 54.846982 -411.013656)
		(width 0.14732)
		(layer "In11.Cu")
		(net "P5E_CPU1_PE0_TX_C_DP<13>")
	)
	(segment
		(start 58.603388 -413.828738)
		(end 58.584084 -413.632142)
		(width 0.14732)
		(layer "In11.Cu")
		(net "P5E_CPU1_PE0_TX_C_DP<13>")
	)
	(segment
		(start 62.502288 -430.119536)
		(end 62.090808 -430.119536)
		(width 0.14732)
		(layer "In11.Cu")
		(net "P5E_CPU1_PE0_TX_C_DP<13>")
	)
	(segment
		(start 62.650116 -429.689768)
		(end 62.650116 -429.971708)
		(width 0.14732)
		(layer "In11.Cu")
		(net "P5E_CPU1_PE0_TX_C_DP<13>")
	)
	(segment
		(start 59.116214 -414.08858)
		(end 58.940954 -414.105852)
		(width 0.14732)
		(layer "In11.Cu")
		(net "P5E_CPU1_PE0_TX_C_DP<13>")
	)
	(segment
		(start 54.489858 -406.418542)
		(end 54.675278 -406.233122)
		(width 0.14732)
		(layer "In11.Cu")
		(net "P5E_CPU1_PE0_TX_C_DP<13>")
	)
	(segment
		(start 58.1025 -413.417512)
		(end 57.81802 -413.184086)
		(width 0.14732)
		(layer "In11.Cu")
		(net "P5E_CPU1_PE0_TX_C_DP<13>")
	)
	(segment
		(start 54.587902 -410.683456)
		(end 54.489858 -410.319728)
		(width 0.14732)
		(layer "In11.Cu")
		(net "P5E_CPU1_PE0_TX_C_DP<13>")
	)
	(segment
		(start 54.675278 -406.233122)
		(end 54.675278 -404.178516)
		(width 0.14732)
		(layer "In11.Cu")
		(net "P5E_CPU1_PE0_TX_C_DP<13>")
	)
	(segment
		(start 62.650116 -429.971708)
		(end 62.502288 -430.119536)
		(width 0.14732)
		(layer "In11.Cu")
		(net "P5E_CPU1_PE0_TX_C_DP<13>")
	)
	(segment
		(start 61.966348 -416.929824)
		(end 60.065412 -415.028634)
		(width 0.14732)
		(layer "In11.Cu")
		(net "P5E_CPU1_PE0_TX_C_DP<13>")
	)
	(segment
		(start 59.454034 -414.365948)
		(end 59.116214 -414.08858)
		(width 0.14732)
		(layer "In11.Cu")
		(net "P5E_CPU1_PE0_TX_C_DP<13>")
	)
	(segment
		(start 54.846982 -411.013656)
		(end 54.587902 -410.683456)
		(width 0.14732)
		(layer "In11.Cu")
		(net "P5E_CPU1_PE0_TX_C_DP<13>")
	)
	(segment
		(start 57.798462 -412.98749)
		(end 57.513474 -412.753556)
		(width 0.14732)
		(layer "In11.Cu")
		(net "P5E_CPU1_PE0_TX_C_DP<13>")
	)
	(segment
		(start 59.471306 -414.541208)
		(end 59.454034 -414.365948)
		(width 0.14732)
		(layer "In11.Cu")
		(net "P5E_CPU1_PE0_TX_C_DP<13>")
	)
	(segment
		(start 56.728106 -412.108904)
		(end 56.53151 -412.128208)
		(width 0.14732)
		(layer "In11.Cu")
		(net "P5E_CPU1_PE0_TX_C_DP<13>")
	)
	(segment
		(start 58.299096 -413.398208)
		(end 58.1025 -413.417512)
		(width 0.14732)
		(layer "In11.Cu")
		(net "P5E_CPU1_PE0_TX_C_DP<13>")
	)
	(segment
		(start 60.065412 -415.028634)
		(end 59.471306 -414.541208)
		(width 0.14732)
		(layer "In11.Cu")
		(net "P5E_CPU1_PE0_TX_C_DP<13>")
	)
	(segment
		(start 57.316878 -412.77286)
		(end 57.032398 -412.539434)
		(width 0.14732)
		(layer "In11.Cu")
		(net "P5E_CPU1_PE0_TX_C_DP<13>")
	)
	(segment
		(start 54.675278 -404.178516)
		(end 54.969918 -403.883876)
		(width 0.14732)
		(layer "In11.Cu")
		(net "P5E_CPU1_PE0_TX_C_DP<13>")
	)
	(segment
		(start 57.73166 -403.582378)
		(end 58.033158 -403.883876)
		(width 0.13208)
		(layer "F.Cu")
		(net "P5E_CPU1_PE0_TX_C_DP<12>")
	)
	(segment
		(start 57.73166 -402.96465)
		(end 57.73166 -403.582378)
		(width 0.13208)
		(layer "F.Cu")
		(net "P5E_CPU1_PE0_TX_C_DP<12>")
	)
	(segment
		(start 58.058558 -402.637752)
		(end 57.73166 -402.96465)
		(width 0.13208)
		(layer "F.Cu")
		(net "P5E_CPU1_PE0_TX_C_DP<12>")
	)
	(segment
		(start 58.863738 -411.997906)
		(end 58.863738 -411.800294)
		(width 0.14732)
		(layer "In11.Cu")
		(net "P5E_CPU1_PE0_TX_C_DP<12>")
	)
	(segment
		(start 63.966344 -430.995074)
		(end 63.966344 -417.100512)
		(width 0.14732)
		(layer "In11.Cu")
		(net "P5E_CPU1_PE0_TX_C_DP<12>")
	)
	(segment
		(start 58.603134 -411.53969)
		(end 58.405522 -411.53969)
		(width 0.14732)
		(layer "In11.Cu")
		(net "P5E_CPU1_PE0_TX_C_DP<12>")
	)
	(segment
		(start 58.405522 -411.53969)
		(end 57.805574 -410.939742)
		(width 0.14732)
		(layer "In11.Cu")
		(net "P5E_CPU1_PE0_TX_C_DP<12>")
	)
	(segment
		(start 64.090804 -431.119534)
		(end 63.966344 -430.995074)
		(width 0.14732)
		(layer "In11.Cu")
		(net "P5E_CPU1_PE0_TX_C_DP<12>")
	)
	(segment
		(start 57.553098 -410.362654)
		(end 57.553098 -406.418542)
		(width 0.14732)
		(layer "In11.Cu")
		(net "P5E_CPU1_PE0_TX_C_DP<12>")
	)
	(segment
		(start 63.966344 -417.100512)
		(end 59.582304 -412.716472)
		(width 0.14732)
		(layer "In11.Cu")
		(net "P5E_CPU1_PE0_TX_C_DP<12>")
	)
	(segment
		(start 57.805574 -410.939742)
		(end 57.553098 -410.362654)
		(width 0.14732)
		(layer "In11.Cu")
		(net "P5E_CPU1_PE0_TX_C_DP<12>")
	)
	(segment
		(start 59.582304 -412.716472)
		(end 59.582304 -412.51886)
		(width 0.14732)
		(layer "In11.Cu")
		(net "P5E_CPU1_PE0_TX_C_DP<12>")
	)
	(segment
		(start 58.863738 -411.800294)
		(end 58.603134 -411.53969)
		(width 0.14732)
		(layer "In11.Cu")
		(net "P5E_CPU1_PE0_TX_C_DP<12>")
	)
	(segment
		(start 64.502284 -431.119534)
		(end 64.090804 -431.119534)
		(width 0.14732)
		(layer "In11.Cu")
		(net "P5E_CPU1_PE0_TX_C_DP<12>")
	)
	(segment
		(start 57.553098 -406.418542)
		(end 57.738518 -406.233122)
		(width 0.14732)
		(layer "In11.Cu")
		(net "P5E_CPU1_PE0_TX_C_DP<12>")
	)
	(segment
		(start 59.124088 -412.258256)
		(end 58.863738 -411.997906)
		(width 0.14732)
		(layer "In11.Cu")
		(net "P5E_CPU1_PE0_TX_C_DP<12>")
	)
	(segment
		(start 64.650112 -430.689766)
		(end 64.650112 -430.971706)
		(width 0.14732)
		(layer "In11.Cu")
		(net "P5E_CPU1_PE0_TX_C_DP<12>")
	)
	(segment
		(start 59.582304 -412.51886)
		(end 59.3217 -412.258256)
		(width 0.14732)
		(layer "In11.Cu")
		(net "P5E_CPU1_PE0_TX_C_DP<12>")
	)
	(segment
		(start 57.738518 -406.233122)
		(end 57.738518 -404.178516)
		(width 0.14732)
		(layer "In11.Cu")
		(net "P5E_CPU1_PE0_TX_C_DP<12>")
	)
	(segment
		(start 59.3217 -412.258256)
		(end 59.124088 -412.258256)
		(width 0.14732)
		(layer "In11.Cu")
		(net "P5E_CPU1_PE0_TX_C_DP<12>")
	)
	(segment
		(start 57.738518 -404.178516)
		(end 58.033158 -403.883876)
		(width 0.14732)
		(layer "In11.Cu")
		(net "P5E_CPU1_PE0_TX_C_DP<12>")
	)
	(segment
		(start 64.650112 -430.971706)
		(end 64.502284 -431.119534)
		(width 0.14732)
		(layer "In11.Cu")
		(net "P5E_CPU1_PE0_TX_C_DP<12>")
	)
	(segment
		(start 60.7949 -403.582378)
		(end 61.096398 -403.883876)
		(width 0.13208)
		(layer "F.Cu")
		(net "P5E_CPU1_PE0_TX_C_DP<11>")
	)
	(segment
		(start 60.7949 -402.96465)
		(end 60.7949 -403.582378)
		(width 0.13208)
		(layer "F.Cu")
		(net "P5E_CPU1_PE0_TX_C_DP<11>")
	)
	(segment
		(start 61.121798 -402.637752)
		(end 60.7949 -402.96465)
		(width 0.13208)
		(layer "F.Cu")
		(net "P5E_CPU1_PE0_TX_C_DP<11>")
	)
	(segment
		(start 61.995812 -412.727648)
		(end 62.012068 -412.552388)
		(width 0.14732)
		(layer "In11.Cu")
		(net "P5E_CPU1_PE0_TX_C_DP<11>")
	)
	(segment
		(start 66.650108 -429.971708)
		(end 66.50228 -430.119536)
		(width 0.14732)
		(layer "In11.Cu")
		(net "P5E_CPU1_PE0_TX_C_DP<11>")
	)
	(segment
		(start 63.884048 -414.808416)
		(end 63.708788 -414.791906)
		(width 0.14732)
		(layer "In11.Cu")
		(net "P5E_CPU1_PE0_TX_C_DP<11>")
	)
	(segment
		(start 62.274704 -413.06369)
		(end 61.995812 -412.727648)
		(width 0.14732)
		(layer "In11.Cu")
		(net "P5E_CPU1_PE0_TX_C_DP<11>")
	)
	(segment
		(start 60.616338 -406.418542)
		(end 60.801758 -406.233122)
		(width 0.14732)
		(layer "In11.Cu")
		(net "P5E_CPU1_PE0_TX_C_DP<11>")
	)
	(segment
		(start 63.708788 -414.791906)
		(end 63.429896 -414.455864)
		(width 0.14732)
		(layer "In11.Cu")
		(net "P5E_CPU1_PE0_TX_C_DP<11>")
	)
	(segment
		(start 60.616338 -410.32684)
		(end 60.616338 -406.418542)
		(width 0.14732)
		(layer "In11.Cu")
		(net "P5E_CPU1_PE0_TX_C_DP<11>")
	)
	(segment
		(start 61.087508 -411.632908)
		(end 60.616338 -410.32684)
		(width 0.14732)
		(layer "In11.Cu")
		(net "P5E_CPU1_PE0_TX_C_DP<11>")
	)
	(segment
		(start 61.732922 -412.215838)
		(end 61.557662 -412.199582)
		(width 0.14732)
		(layer "In11.Cu")
		(net "P5E_CPU1_PE0_TX_C_DP<11>")
	)
	(segment
		(start 64.146684 -415.319972)
		(end 64.163194 -415.144712)
		(width 0.14732)
		(layer "In11.Cu")
		(net "P5E_CPU1_PE0_TX_C_DP<11>")
	)
	(segment
		(start 66.50228 -430.119536)
		(end 66.089784 -430.119536)
		(width 0.14732)
		(layer "In11.Cu")
		(net "P5E_CPU1_PE0_TX_C_DP<11>")
	)
	(segment
		(start 62.712854 -413.591756)
		(end 62.72911 -413.416496)
		(width 0.14732)
		(layer "In11.Cu")
		(net "P5E_CPU1_PE0_TX_C_DP<11>")
	)
	(segment
		(start 62.012068 -412.552388)
		(end 61.732922 -412.215838)
		(width 0.14732)
		(layer "In11.Cu")
		(net "P5E_CPU1_PE0_TX_C_DP<11>")
	)
	(segment
		(start 62.449964 -413.079946)
		(end 62.274704 -413.06369)
		(width 0.14732)
		(layer "In11.Cu")
		(net "P5E_CPU1_PE0_TX_C_DP<11>")
	)
	(segment
		(start 62.72911 -413.416496)
		(end 62.449964 -413.079946)
		(width 0.14732)
		(layer "In11.Cu")
		(net "P5E_CPU1_PE0_TX_C_DP<11>")
	)
	(segment
		(start 60.801758 -406.233122)
		(end 60.801758 -404.178516)
		(width 0.14732)
		(layer "In11.Cu")
		(net "P5E_CPU1_PE0_TX_C_DP<11>")
	)
	(segment
		(start 63.167006 -413.944308)
		(end 62.991746 -413.927798)
		(width 0.14732)
		(layer "In11.Cu")
		(net "P5E_CPU1_PE0_TX_C_DP<11>")
	)
	(segment
		(start 65.96634 -429.996092)
		(end 65.96634 -418.059616)
		(width 0.14732)
		(layer "In11.Cu")
		(net "P5E_CPU1_PE0_TX_C_DP<11>")
	)
	(segment
		(start 61.557662 -412.199582)
		(end 61.087508 -411.632908)
		(width 0.14732)
		(layer "In11.Cu")
		(net "P5E_CPU1_PE0_TX_C_DP<11>")
	)
	(segment
		(start 66.650108 -429.689768)
		(end 66.650108 -429.971708)
		(width 0.14732)
		(layer "In11.Cu")
		(net "P5E_CPU1_PE0_TX_C_DP<11>")
	)
	(segment
		(start 64.163194 -415.144712)
		(end 63.884048 -414.808416)
		(width 0.14732)
		(layer "In11.Cu")
		(net "P5E_CPU1_PE0_TX_C_DP<11>")
	)
	(segment
		(start 62.991746 -413.927798)
		(end 62.712854 -413.591756)
		(width 0.14732)
		(layer "In11.Cu")
		(net "P5E_CPU1_PE0_TX_C_DP<11>")
	)
	(segment
		(start 66.089784 -430.119536)
		(end 65.96634 -429.996092)
		(width 0.14732)
		(layer "In11.Cu")
		(net "P5E_CPU1_PE0_TX_C_DP<11>")
	)
	(segment
		(start 63.446152 -414.280604)
		(end 63.167006 -413.944308)
		(width 0.14732)
		(layer "In11.Cu")
		(net "P5E_CPU1_PE0_TX_C_DP<11>")
	)
	(segment
		(start 65.96634 -418.059616)
		(end 65.617598 -417.093146)
		(width 0.14732)
		(layer "In11.Cu")
		(net "P5E_CPU1_PE0_TX_C_DP<11>")
	)
	(segment
		(start 65.617598 -417.093146)
		(end 64.146684 -415.319972)
		(width 0.14732)
		(layer "In11.Cu")
		(net "P5E_CPU1_PE0_TX_C_DP<11>")
	)
	(segment
		(start 63.429896 -414.455864)
		(end 63.446152 -414.280604)
		(width 0.14732)
		(layer "In11.Cu")
		(net "P5E_CPU1_PE0_TX_C_DP<11>")
	)
	(segment
		(start 60.801758 -404.178516)
		(end 61.096398 -403.883876)
		(width 0.14732)
		(layer "In11.Cu")
		(net "P5E_CPU1_PE0_TX_C_DP<11>")
	)
	(segment
		(start 63.85814 -403.582378)
		(end 64.159638 -403.883876)
		(width 0.13208)
		(layer "F.Cu")
		(net "P5E_CPU1_PE0_TX_C_DP<10>")
	)
	(segment
		(start 64.185038 -402.637752)
		(end 63.85814 -402.96465)
		(width 0.13208)
		(layer "F.Cu")
		(net "P5E_CPU1_PE0_TX_C_DP<10>")
	)
	(segment
		(start 63.85814 -402.96465)
		(end 63.85814 -403.582378)
		(width 0.13208)
		(layer "F.Cu")
		(net "P5E_CPU1_PE0_TX_C_DP<10>")
	)
	(segment
		(start 65.242948 -413.14116)
		(end 65.286382 -412.948374)
		(width 0.14732)
		(layer "In11.Cu")
		(net "P5E_CPU1_PE0_TX_C_DP<10>")
	)
	(segment
		(start 68.090796 -431.119534)
		(end 67.966336 -430.995074)
		(width 0.14732)
		(layer "In11.Cu")
		(net "P5E_CPU1_PE0_TX_C_DP<10>")
	)
	(segment
		(start 63.864998 -404.178516)
		(end 64.159638 -403.883876)
		(width 0.14732)
		(layer "In11.Cu")
		(net "P5E_CPU1_PE0_TX_C_DP<10>")
	)
	(segment
		(start 66.42481 -414.777682)
		(end 66.19113 -414.408112)
		(width 0.14732)
		(layer "In11.Cu")
		(net "P5E_CPU1_PE0_TX_C_DP<10>")
	)
	(segment
		(start 65.829434 -413.807402)
		(end 65.632584 -413.495744)
		(width 0.14732)
		(layer "In11.Cu")
		(net "P5E_CPU1_PE0_TX_C_DP<10>")
	)
	(segment
		(start 64.896746 -412.593282)
		(end 64.038226 -411.235906)
		(width 0.14732)
		(layer "In11.Cu")
		(net "P5E_CPU1_PE0_TX_C_DP<10>")
	)
	(segment
		(start 66.19113 -414.408112)
		(end 66.019426 -414.36925)
		(width 0.14732)
		(layer "In11.Cu")
		(net "P5E_CPU1_PE0_TX_C_DP<10>")
	)
	(segment
		(start 66.385948 -414.949386)
		(end 66.42481 -414.777682)
		(width 0.14732)
		(layer "In11.Cu")
		(net "P5E_CPU1_PE0_TX_C_DP<10>")
	)
	(segment
		(start 65.632584 -413.495744)
		(end 65.439544 -413.45231)
		(width 0.14732)
		(layer "In11.Cu")
		(net "P5E_CPU1_PE0_TX_C_DP<10>")
	)
	(segment
		(start 66.019426 -414.36925)
		(end 65.786 -414.000188)
		(width 0.14732)
		(layer "In11.Cu")
		(net "P5E_CPU1_PE0_TX_C_DP<10>")
	)
	(segment
		(start 63.864998 -406.233122)
		(end 63.864998 -404.178516)
		(width 0.14732)
		(layer "In11.Cu")
		(net "P5E_CPU1_PE0_TX_C_DP<10>")
	)
	(segment
		(start 63.679578 -406.418542)
		(end 63.864998 -406.233122)
		(width 0.14732)
		(layer "In11.Cu")
		(net "P5E_CPU1_PE0_TX_C_DP<10>")
	)
	(segment
		(start 63.679578 -410.470096)
		(end 63.679578 -406.418542)
		(width 0.14732)
		(layer "In11.Cu")
		(net "P5E_CPU1_PE0_TX_C_DP<10>")
	)
	(segment
		(start 68.502276 -431.119534)
		(end 68.090796 -431.119534)
		(width 0.14732)
		(layer "In11.Cu")
		(net "P5E_CPU1_PE0_TX_C_DP<10>")
	)
	(segment
		(start 65.286382 -412.948374)
		(end 65.089532 -412.636716)
		(width 0.14732)
		(layer "In11.Cu")
		(net "P5E_CPU1_PE0_TX_C_DP<10>")
	)
	(segment
		(start 67.966336 -417.449)
		(end 66.385948 -414.949386)
		(width 0.14732)
		(layer "In11.Cu")
		(net "P5E_CPU1_PE0_TX_C_DP<10>")
	)
	(segment
		(start 65.439544 -413.45231)
		(end 65.242948 -413.14116)
		(width 0.14732)
		(layer "In11.Cu")
		(net "P5E_CPU1_PE0_TX_C_DP<10>")
	)
	(segment
		(start 65.786 -414.000188)
		(end 65.829434 -413.807402)
		(width 0.14732)
		(layer "In11.Cu")
		(net "P5E_CPU1_PE0_TX_C_DP<10>")
	)
	(segment
		(start 68.650104 -430.971706)
		(end 68.502276 -431.119534)
		(width 0.14732)
		(layer "In11.Cu")
		(net "P5E_CPU1_PE0_TX_C_DP<10>")
	)
	(segment
		(start 64.038226 -411.235906)
		(end 63.679578 -410.470096)
		(width 0.14732)
		(layer "In11.Cu")
		(net "P5E_CPU1_PE0_TX_C_DP<10>")
	)
	(segment
		(start 67.966336 -430.995074)
		(end 67.966336 -417.449)
		(width 0.14732)
		(layer "In11.Cu")
		(net "P5E_CPU1_PE0_TX_C_DP<10>")
	)
	(segment
		(start 68.650104 -430.689766)
		(end 68.650104 -430.971706)
		(width 0.14732)
		(layer "In11.Cu")
		(net "P5E_CPU1_PE0_TX_C_DP<10>")
	)
	(segment
		(start 65.089532 -412.636716)
		(end 64.896746 -412.593282)
		(width 0.14732)
		(layer "In11.Cu")
		(net "P5E_CPU1_PE0_TX_C_DP<10>")
	)
	(segment
		(start 94.49054 -403.582378)
		(end 94.792038 -403.883876)
		(width 0.13208)
		(layer "F.Cu")
		(net "P5E_CPU1_PE0_TX_C_DP<0>")
	)
	(segment
		(start 94.817438 -402.637752)
		(end 94.49054 -402.96465)
		(width 0.13208)
		(layer "F.Cu")
		(net "P5E_CPU1_PE0_TX_C_DP<0>")
	)
	(segment
		(start 94.49054 -402.96465)
		(end 94.49054 -403.582378)
		(width 0.13208)
		(layer "F.Cu")
		(net "P5E_CPU1_PE0_TX_C_DP<0>")
	)
	(segment
		(start 88.966294 -424.07459)
		(end 88.966294 -430.995074)
		(width 0.14732)
		(layer "In11.Cu")
		(net "P5E_CPU1_PE0_TX_C_DP<0>")
	)
	(segment
		(start 94.497398 -406.233122)
		(end 94.311978 -406.418542)
		(width 0.14732)
		(layer "In11.Cu")
		(net "P5E_CPU1_PE0_TX_C_DP<0>")
	)
	(segment
		(start 89.601802 -422.540684)
		(end 89.67724 -422.723056)
		(width 0.14732)
		(layer "In11.Cu")
		(net "P5E_CPU1_PE0_TX_C_DP<0>")
	)
	(segment
		(start 89.353644 -423.139362)
		(end 88.966294 -424.07459)
		(width 0.14732)
		(layer "In11.Cu")
		(net "P5E_CPU1_PE0_TX_C_DP<0>")
	)
	(segment
		(start 94.311978 -411.169104)
		(end 90.420444 -420.564564)
		(width 0.14732)
		(layer "In11.Cu")
		(net "P5E_CPU1_PE0_TX_C_DP<0>")
	)
	(segment
		(start 89.67724 -422.723056)
		(end 89.536524 -423.06367)
		(width 0.14732)
		(layer "In11.Cu")
		(net "P5E_CPU1_PE0_TX_C_DP<0>")
	)
	(segment
		(start 90.157808 -421.198294)
		(end 89.990676 -421.6019)
		(width 0.14732)
		(layer "In11.Cu")
		(net "P5E_CPU1_PE0_TX_C_DP<0>")
	)
	(segment
		(start 89.090754 -431.119534)
		(end 89.502234 -431.119534)
		(width 0.14732)
		(layer "In11.Cu")
		(net "P5E_CPU1_PE0_TX_C_DP<0>")
	)
	(segment
		(start 94.497398 -404.178516)
		(end 94.497398 -406.233122)
		(width 0.14732)
		(layer "In11.Cu")
		(net "P5E_CPU1_PE0_TX_C_DP<0>")
	)
	(segment
		(start 89.536524 -423.06367)
		(end 89.353644 -423.139362)
		(width 0.14732)
		(layer "In11.Cu")
		(net "P5E_CPU1_PE0_TX_C_DP<0>")
	)
	(segment
		(start 89.502234 -431.119534)
		(end 89.650062 -430.971706)
		(width 0.14732)
		(layer "In11.Cu")
		(net "P5E_CPU1_PE0_TX_C_DP<0>")
	)
	(segment
		(start 94.311978 -406.418542)
		(end 94.311978 -411.169104)
		(width 0.14732)
		(layer "In11.Cu")
		(net "P5E_CPU1_PE0_TX_C_DP<0>")
	)
	(segment
		(start 90.066368 -421.784526)
		(end 89.925398 -422.124886)
		(width 0.14732)
		(layer "In11.Cu")
		(net "P5E_CPU1_PE0_TX_C_DP<0>")
	)
	(segment
		(start 89.925398 -422.124886)
		(end 89.742518 -422.200578)
		(width 0.14732)
		(layer "In11.Cu")
		(net "P5E_CPU1_PE0_TX_C_DP<0>")
	)
	(segment
		(start 94.792038 -403.883876)
		(end 94.497398 -404.178516)
		(width 0.14732)
		(layer "In11.Cu")
		(net "P5E_CPU1_PE0_TX_C_DP<0>")
	)
	(segment
		(start 90.487754 -420.727124)
		(end 90.320622 -421.130984)
		(width 0.14732)
		(layer "In11.Cu")
		(net "P5E_CPU1_PE0_TX_C_DP<0>")
	)
	(segment
		(start 90.420444 -420.564564)
		(end 90.487754 -420.727124)
		(width 0.14732)
		(layer "In11.Cu")
		(net "P5E_CPU1_PE0_TX_C_DP<0>")
	)
	(segment
		(start 89.742518 -422.200578)
		(end 89.601802 -422.540684)
		(width 0.14732)
		(layer "In11.Cu")
		(net "P5E_CPU1_PE0_TX_C_DP<0>")
	)
	(segment
		(start 89.650062 -430.971706)
		(end 89.650062 -430.689766)
		(width 0.14732)
		(layer "In11.Cu")
		(net "P5E_CPU1_PE0_TX_C_DP<0>")
	)
	(segment
		(start 90.320622 -421.130984)
		(end 90.157808 -421.198294)
		(width 0.14732)
		(layer "In11.Cu")
		(net "P5E_CPU1_PE0_TX_C_DP<0>")
	)
	(segment
		(start 88.966294 -430.995074)
		(end 89.090754 -431.119534)
		(width 0.14732)
		(layer "In11.Cu")
		(net "P5E_CPU1_PE0_TX_C_DP<0>")
	)
	(segment
		(start 89.990676 -421.6019)
		(end 90.066368 -421.784526)
		(width 0.14732)
		(layer "In11.Cu")
		(net "P5E_CPU1_PE0_TX_C_DP<0>")
	)
	(segment
		(start 66.333878 -402.637752)
		(end 66.33718 -402.637752)
		(width 0.13208)
		(layer "F.Cu")
		(net "P5E_CPU1_PE0_TX_C_DN<9>")
	)
	(segment
		(start 66.6623 -402.962872)
		(end 66.6623 -403.580854)
		(width 0.13208)
		(layer "F.Cu")
		(net "P5E_CPU1_PE0_TX_C_DN<9>")
	)
	(segment
		(start 66.6623 -403.580854)
		(end 66.359278 -403.883876)
		(width 0.13208)
		(layer "F.Cu")
		(net "P5E_CPU1_PE0_TX_C_DN<9>")
	)
	(segment
		(start 66.33718 -402.637752)
		(end 66.6623 -402.962872)
		(width 0.13208)
		(layer "F.Cu")
		(net "P5E_CPU1_PE0_TX_C_DN<9>")
	)
	(segment
		(start 70.463156 -430.393856)
		(end 69.977 -430.393856)
		(width 0.14732)
		(layer "In11.Cu")
		(net "P5E_CPU1_PE0_TX_C_DN<9>")
	)
	(segment
		(start 66.468498 -406.30475)
		(end 66.653918 -406.11933)
		(width 0.14732)
		(layer "In11.Cu")
		(net "P5E_CPU1_PE0_TX_C_DN<9>")
	)
	(segment
		(start 69.692012 -416.852354)
		(end 69.69379 -416.747706)
		(width 0.14732)
		(layer "In11.Cu")
		(net "P5E_CPU1_PE0_TX_C_DN<9>")
	)
	(segment
		(start 66.653918 -406.11933)
		(end 66.653918 -404.178516)
		(width 0.14732)
		(layer "In11.Cu")
		(net "P5E_CPU1_PE0_TX_C_DN<9>")
	)
	(segment
		(start 66.653918 -404.178516)
		(end 66.359278 -403.883876)
		(width 0.14732)
		(layer "In11.Cu")
		(net "P5E_CPU1_PE0_TX_C_DN<9>")
	)
	(segment
		(start 66.468498 -410.752544)
		(end 66.468498 -406.30475)
		(width 0.14732)
		(layer "In11.Cu")
		(net "P5E_CPU1_PE0_TX_C_DN<9>")
	)
	(segment
		(start 70.6501 -430.889918)
		(end 70.6501 -430.5808)
		(width 0.14732)
		(layer "In11.Cu")
		(net "P5E_CPU1_PE0_TX_C_DN<9>")
	)
	(segment
		(start 70.6501 -430.5808)
		(end 70.463156 -430.393856)
		(width 0.14732)
		(layer "In11.Cu")
		(net "P5E_CPU1_PE0_TX_C_DN<9>")
	)
	(segment
		(start 69.977 -430.393856)
		(end 69.692012 -430.108868)
		(width 0.14732)
		(layer "In11.Cu")
		(net "P5E_CPU1_PE0_TX_C_DN<9>")
	)
	(segment
		(start 69.69379 -416.747706)
		(end 66.468498 -410.752544)
		(width 0.14732)
		(layer "In11.Cu")
		(net "P5E_CPU1_PE0_TX_C_DN<9>")
	)
	(segment
		(start 69.692012 -430.108868)
		(end 69.692012 -416.852354)
		(width 0.14732)
		(layer "In11.Cu")
		(net "P5E_CPU1_PE0_TX_C_DN<9>")
	)
	(segment
		(start 69.72554 -402.962872)
		(end 69.72554 -403.580854)
		(width 0.13208)
		(layer "F.Cu")
		(net "P5E_CPU1_PE0_TX_C_DN<8>")
	)
	(segment
		(start 69.397118 -402.637752)
		(end 69.40042 -402.637752)
		(width 0.13208)
		(layer "F.Cu")
		(net "P5E_CPU1_PE0_TX_C_DN<8>")
	)
	(segment
		(start 69.40042 -402.637752)
		(end 69.72554 -402.962872)
		(width 0.13208)
		(layer "F.Cu")
		(net "P5E_CPU1_PE0_TX_C_DN<8>")
	)
	(segment
		(start 69.72554 -403.580854)
		(end 69.422518 -403.883876)
		(width 0.13208)
		(layer "F.Cu")
		(net "P5E_CPU1_PE0_TX_C_DN<8>")
	)
	(segment
		(start 72.463152 -431.393854)
		(end 71.976996 -431.393854)
		(width 0.14732)
		(layer "In11.Cu")
		(net "P5E_CPU1_PE0_TX_C_DN<8>")
	)
	(segment
		(start 69.717158 -406.11933)
		(end 69.717158 -404.178516)
		(width 0.14732)
		(layer "In11.Cu")
		(net "P5E_CPU1_PE0_TX_C_DN<8>")
	)
	(segment
		(start 71.692008 -416.674554)
		(end 69.531738 -410.555948)
		(width 0.14732)
		(layer "In11.Cu")
		(net "P5E_CPU1_PE0_TX_C_DN<8>")
	)
	(segment
		(start 72.650096 -431.889916)
		(end 72.650096 -431.580798)
		(width 0.14732)
		(layer "In11.Cu")
		(net "P5E_CPU1_PE0_TX_C_DN<8>")
	)
	(segment
		(start 71.976996 -431.393854)
		(end 71.692008 -431.108866)
		(width 0.14732)
		(layer "In11.Cu")
		(net "P5E_CPU1_PE0_TX_C_DN<8>")
	)
	(segment
		(start 72.650096 -431.580798)
		(end 72.463152 -431.393854)
		(width 0.14732)
		(layer "In11.Cu")
		(net "P5E_CPU1_PE0_TX_C_DN<8>")
	)
	(segment
		(start 69.531738 -406.30475)
		(end 69.717158 -406.11933)
		(width 0.14732)
		(layer "In11.Cu")
		(net "P5E_CPU1_PE0_TX_C_DN<8>")
	)
	(segment
		(start 71.692008 -431.108866)
		(end 71.692008 -416.674554)
		(width 0.14732)
		(layer "In11.Cu")
		(net "P5E_CPU1_PE0_TX_C_DN<8>")
	)
	(segment
		(start 69.531738 -410.555948)
		(end 69.531738 -406.30475)
		(width 0.14732)
		(layer "In11.Cu")
		(net "P5E_CPU1_PE0_TX_C_DN<8>")
	)
	(segment
		(start 69.717158 -404.178516)
		(end 69.422518 -403.883876)
		(width 0.14732)
		(layer "In11.Cu")
		(net "P5E_CPU1_PE0_TX_C_DN<8>")
	)
	(segment
		(start 72.78878 -402.962872)
		(end 72.78878 -403.580854)
		(width 0.13208)
		(layer "F.Cu")
		(net "P5E_CPU1_PE0_TX_C_DN<7>")
	)
	(segment
		(start 72.460358 -402.637752)
		(end 72.46366 -402.637752)
		(width 0.13208)
		(layer "F.Cu")
		(net "P5E_CPU1_PE0_TX_C_DN<7>")
	)
	(segment
		(start 72.78878 -403.580854)
		(end 72.485758 -403.883876)
		(width 0.13208)
		(layer "F.Cu")
		(net "P5E_CPU1_PE0_TX_C_DN<7>")
	)
	(segment
		(start 72.46366 -402.637752)
		(end 72.78878 -402.962872)
		(width 0.13208)
		(layer "F.Cu")
		(net "P5E_CPU1_PE0_TX_C_DN<7>")
	)
	(segment
		(start 72.594978 -406.30475)
		(end 72.780398 -406.11933)
		(width 0.14732)
		(layer "In11.Cu")
		(net "P5E_CPU1_PE0_TX_C_DN<7>")
	)
	(segment
		(start 75.65009 -430.5808)
		(end 75.463146 -430.393856)
		(width 0.14732)
		(layer "In11.Cu")
		(net "P5E_CPU1_PE0_TX_C_DN<7>")
	)
	(segment
		(start 72.780398 -406.11933)
		(end 72.780398 -404.178516)
		(width 0.14732)
		(layer "In11.Cu")
		(net "P5E_CPU1_PE0_TX_C_DN<7>")
	)
	(segment
		(start 75.65009 -430.889918)
		(end 75.65009 -430.5808)
		(width 0.14732)
		(layer "In11.Cu")
		(net "P5E_CPU1_PE0_TX_C_DN<7>")
	)
	(segment
		(start 72.766428 -411.107382)
		(end 72.594978 -410.340302)
		(width 0.14732)
		(layer "In11.Cu")
		(net "P5E_CPU1_PE0_TX_C_DN<7>")
	)
	(segment
		(start 74.692002 -430.108868)
		(end 74.692002 -423.908982)
		(width 0.14732)
		(layer "In11.Cu")
		(net "P5E_CPU1_PE0_TX_C_DN<7>")
	)
	(segment
		(start 74.692002 -423.908982)
		(end 72.766428 -411.107382)
		(width 0.14732)
		(layer "In11.Cu")
		(net "P5E_CPU1_PE0_TX_C_DN<7>")
	)
	(segment
		(start 75.463146 -430.393856)
		(end 74.97699 -430.393856)
		(width 0.14732)
		(layer "In11.Cu")
		(net "P5E_CPU1_PE0_TX_C_DN<7>")
	)
	(segment
		(start 72.780398 -404.178516)
		(end 72.485758 -403.883876)
		(width 0.14732)
		(layer "In11.Cu")
		(net "P5E_CPU1_PE0_TX_C_DN<7>")
	)
	(segment
		(start 74.97699 -430.393856)
		(end 74.692002 -430.108868)
		(width 0.14732)
		(layer "In11.Cu")
		(net "P5E_CPU1_PE0_TX_C_DN<7>")
	)
	(segment
		(start 72.594978 -410.340302)
		(end 72.594978 -406.30475)
		(width 0.14732)
		(layer "In11.Cu")
		(net "P5E_CPU1_PE0_TX_C_DN<7>")
	)
	(segment
		(start 75.85202 -403.580854)
		(end 75.548998 -403.883876)
		(width 0.13208)
		(layer "F.Cu")
		(net "P5E_CPU1_PE0_TX_C_DN<6>")
	)
	(segment
		(start 75.85202 -402.962872)
		(end 75.85202 -403.580854)
		(width 0.13208)
		(layer "F.Cu")
		(net "P5E_CPU1_PE0_TX_C_DN<6>")
	)
	(segment
		(start 75.523598 -402.637752)
		(end 75.5269 -402.637752)
		(width 0.13208)
		(layer "F.Cu")
		(net "P5E_CPU1_PE0_TX_C_DN<6>")
	)
	(segment
		(start 75.5269 -402.637752)
		(end 75.85202 -402.962872)
		(width 0.13208)
		(layer "F.Cu")
		(net "P5E_CPU1_PE0_TX_C_DN<6>")
	)
	(segment
		(start 75.658218 -406.30475)
		(end 75.843638 -406.11933)
		(width 0.14732)
		(layer "In11.Cu")
		(net "P5E_CPU1_PE0_TX_C_DN<6>")
	)
	(segment
		(start 75.843638 -404.178516)
		(end 75.548998 -403.883876)
		(width 0.14732)
		(layer "In11.Cu")
		(net "P5E_CPU1_PE0_TX_C_DN<6>")
	)
	(segment
		(start 76.976986 -431.393854)
		(end 76.691998 -431.108866)
		(width 0.14732)
		(layer "In11.Cu")
		(net "P5E_CPU1_PE0_TX_C_DN<6>")
	)
	(segment
		(start 76.691998 -424.096688)
		(end 75.806808 -411.096206)
		(width 0.14732)
		(layer "In11.Cu")
		(net "P5E_CPU1_PE0_TX_C_DN<6>")
	)
	(segment
		(start 75.658218 -410.328364)
		(end 75.658218 -406.30475)
		(width 0.14732)
		(layer "In11.Cu")
		(net "P5E_CPU1_PE0_TX_C_DN<6>")
	)
	(segment
		(start 75.843638 -406.11933)
		(end 75.843638 -404.178516)
		(width 0.14732)
		(layer "In11.Cu")
		(net "P5E_CPU1_PE0_TX_C_DN<6>")
	)
	(segment
		(start 76.691998 -431.108866)
		(end 76.691998 -424.096688)
		(width 0.14732)
		(layer "In11.Cu")
		(net "P5E_CPU1_PE0_TX_C_DN<6>")
	)
	(segment
		(start 77.463142 -431.393854)
		(end 76.976986 -431.393854)
		(width 0.14732)
		(layer "In11.Cu")
		(net "P5E_CPU1_PE0_TX_C_DN<6>")
	)
	(segment
		(start 77.650086 -431.889916)
		(end 77.650086 -431.580798)
		(width 0.14732)
		(layer "In11.Cu")
		(net "P5E_CPU1_PE0_TX_C_DN<6>")
	)
	(segment
		(start 75.806808 -411.096206)
		(end 75.658218 -410.328364)
		(width 0.14732)
		(layer "In11.Cu")
		(net "P5E_CPU1_PE0_TX_C_DN<6>")
	)
	(segment
		(start 77.650086 -431.580798)
		(end 77.463142 -431.393854)
		(width 0.14732)
		(layer "In11.Cu")
		(net "P5E_CPU1_PE0_TX_C_DN<6>")
	)
	(segment
		(start 78.91526 -403.580854)
		(end 78.612238 -403.883876)
		(width 0.13208)
		(layer "F.Cu")
		(net "P5E_CPU1_PE0_TX_C_DN<5>")
	)
	(segment
		(start 78.586838 -402.637752)
		(end 78.59014 -402.637752)
		(width 0.13208)
		(layer "F.Cu")
		(net "P5E_CPU1_PE0_TX_C_DN<5>")
	)
	(segment
		(start 78.59014 -402.637752)
		(end 78.91526 -402.962872)
		(width 0.13208)
		(layer "F.Cu")
		(net "P5E_CPU1_PE0_TX_C_DN<5>")
	)
	(segment
		(start 78.91526 -402.962872)
		(end 78.91526 -403.580854)
		(width 0.13208)
		(layer "F.Cu")
		(net "P5E_CPU1_PE0_TX_C_DN<5>")
	)
	(segment
		(start 78.721458 -410.343858)
		(end 78.721458 -406.30475)
		(width 0.14732)
		(layer "In11.Cu")
		(net "P5E_CPU1_PE0_TX_C_DN<5>")
	)
	(segment
		(start 78.906878 -404.178516)
		(end 78.612238 -403.883876)
		(width 0.14732)
		(layer "In11.Cu")
		(net "P5E_CPU1_PE0_TX_C_DN<5>")
	)
	(segment
		(start 79.650082 -430.889918)
		(end 79.650082 -430.5808)
		(width 0.14732)
		(layer "In11.Cu")
		(net "P5E_CPU1_PE0_TX_C_DN<5>")
	)
	(segment
		(start 78.691994 -423.729404)
		(end 78.821788 -413.157162)
		(width 0.14732)
		(layer "In11.Cu")
		(net "P5E_CPU1_PE0_TX_C_DN<5>")
	)
	(segment
		(start 78.976982 -430.393856)
		(end 78.691994 -430.108868)
		(width 0.14732)
		(layer "In11.Cu")
		(net "P5E_CPU1_PE0_TX_C_DN<5>")
	)
	(segment
		(start 78.691994 -430.108868)
		(end 78.691994 -423.729404)
		(width 0.14732)
		(layer "In11.Cu")
		(net "P5E_CPU1_PE0_TX_C_DN<5>")
	)
	(segment
		(start 78.906878 -406.11933)
		(end 78.906878 -404.178516)
		(width 0.14732)
		(layer "In11.Cu")
		(net "P5E_CPU1_PE0_TX_C_DN<5>")
	)
	(segment
		(start 79.650082 -430.5808)
		(end 79.463138 -430.393856)
		(width 0.14732)
		(layer "In11.Cu")
		(net "P5E_CPU1_PE0_TX_C_DN<5>")
	)
	(segment
		(start 79.463138 -430.393856)
		(end 78.976982 -430.393856)
		(width 0.14732)
		(layer "In11.Cu")
		(net "P5E_CPU1_PE0_TX_C_DN<5>")
	)
	(segment
		(start 78.721458 -406.30475)
		(end 78.906878 -406.11933)
		(width 0.14732)
		(layer "In11.Cu")
		(net "P5E_CPU1_PE0_TX_C_DN<5>")
	)
	(segment
		(start 78.821788 -413.157162)
		(end 78.721458 -410.343858)
		(width 0.14732)
		(layer "In11.Cu")
		(net "P5E_CPU1_PE0_TX_C_DN<5>")
	)
	(segment
		(start 81.9785 -402.962872)
		(end 81.9785 -403.580854)
		(width 0.13208)
		(layer "F.Cu")
		(net "P5E_CPU1_PE0_TX_C_DN<4>")
	)
	(segment
		(start 81.650078 -402.637752)
		(end 81.65338 -402.637752)
		(width 0.13208)
		(layer "F.Cu")
		(net "P5E_CPU1_PE0_TX_C_DN<4>")
	)
	(segment
		(start 81.65338 -402.637752)
		(end 81.9785 -402.962872)
		(width 0.13208)
		(layer "F.Cu")
		(net "P5E_CPU1_PE0_TX_C_DN<4>")
	)
	(segment
		(start 81.9785 -403.580854)
		(end 81.675478 -403.883876)
		(width 0.13208)
		(layer "F.Cu")
		(net "P5E_CPU1_PE0_TX_C_DN<4>")
	)
	(segment
		(start 81.784698 -412.203646)
		(end 81.784698 -406.30475)
		(width 0.14732)
		(layer "In11.Cu")
		(net "P5E_CPU1_PE0_TX_C_DN<4>")
	)
	(segment
		(start 81.463134 -431.393854)
		(end 80.964786 -431.393854)
		(width 0.14732)
		(layer "In11.Cu")
		(net "P5E_CPU1_PE0_TX_C_DN<4>")
	)
	(segment
		(start 81.970118 -406.11933)
		(end 81.970118 -404.178516)
		(width 0.14732)
		(layer "In11.Cu")
		(net "P5E_CPU1_PE0_TX_C_DN<4>")
	)
	(segment
		(start 80.69199 -424.066208)
		(end 81.784698 -412.203646)
		(width 0.14732)
		(layer "In11.Cu")
		(net "P5E_CPU1_PE0_TX_C_DN<4>")
	)
	(segment
		(start 81.650078 -431.889916)
		(end 81.650078 -431.580798)
		(width 0.14732)
		(layer "In11.Cu")
		(net "P5E_CPU1_PE0_TX_C_DN<4>")
	)
	(segment
		(start 80.964786 -431.393854)
		(end 80.69199 -431.121058)
		(width 0.14732)
		(layer "In11.Cu")
		(net "P5E_CPU1_PE0_TX_C_DN<4>")
	)
	(segment
		(start 81.650078 -431.580798)
		(end 81.463134 -431.393854)
		(width 0.14732)
		(layer "In11.Cu")
		(net "P5E_CPU1_PE0_TX_C_DN<4>")
	)
	(segment
		(start 81.784698 -406.30475)
		(end 81.970118 -406.11933)
		(width 0.14732)
		(layer "In11.Cu")
		(net "P5E_CPU1_PE0_TX_C_DN<4>")
	)
	(segment
		(start 80.69199 -431.121058)
		(end 80.69199 -424.066208)
		(width 0.14732)
		(layer "In11.Cu")
		(net "P5E_CPU1_PE0_TX_C_DN<4>")
	)
	(segment
		(start 81.970118 -404.178516)
		(end 81.675478 -403.883876)
		(width 0.14732)
		(layer "In11.Cu")
		(net "P5E_CPU1_PE0_TX_C_DN<4>")
	)
	(segment
		(start 84.71662 -402.637752)
		(end 85.04174 -402.962872)
		(width 0.13208)
		(layer "F.Cu")
		(net "P5E_CPU1_PE0_TX_C_DN<3>")
	)
	(segment
		(start 84.713318 -402.637752)
		(end 84.71662 -402.637752)
		(width 0.13208)
		(layer "F.Cu")
		(net "P5E_CPU1_PE0_TX_C_DN<3>")
	)
	(segment
		(start 85.04174 -403.580854)
		(end 84.738718 -403.883876)
		(width 0.13208)
		(layer "F.Cu")
		(net "P5E_CPU1_PE0_TX_C_DN<3>")
	)
	(segment
		(start 85.04174 -402.962872)
		(end 85.04174 -403.580854)
		(width 0.13208)
		(layer "F.Cu")
		(net "P5E_CPU1_PE0_TX_C_DN<3>")
	)
	(segment
		(start 85.033358 -404.178516)
		(end 84.738718 -403.883876)
		(width 0.14732)
		(layer "In11.Cu")
		(net "P5E_CPU1_PE0_TX_C_DN<3>")
	)
	(segment
		(start 82.691986 -424.169078)
		(end 84.847938 -411.55493)
		(width 0.14732)
		(layer "In11.Cu")
		(net "P5E_CPU1_PE0_TX_C_DN<3>")
	)
	(segment
		(start 82.976974 -430.393856)
		(end 82.691986 -430.108868)
		(width 0.14732)
		(layer "In11.Cu")
		(net "P5E_CPU1_PE0_TX_C_DN<3>")
	)
	(segment
		(start 83.650074 -430.5808)
		(end 83.46313 -430.393856)
		(width 0.14732)
		(layer "In11.Cu")
		(net "P5E_CPU1_PE0_TX_C_DN<3>")
	)
	(segment
		(start 84.847938 -406.30475)
		(end 85.033358 -406.11933)
		(width 0.14732)
		(layer "In11.Cu")
		(net "P5E_CPU1_PE0_TX_C_DN<3>")
	)
	(segment
		(start 82.691986 -430.108868)
		(end 82.691986 -424.169078)
		(width 0.14732)
		(layer "In11.Cu")
		(net "P5E_CPU1_PE0_TX_C_DN<3>")
	)
	(segment
		(start 85.033358 -406.11933)
		(end 85.033358 -404.178516)
		(width 0.14732)
		(layer "In11.Cu")
		(net "P5E_CPU1_PE0_TX_C_DN<3>")
	)
	(segment
		(start 83.650074 -430.889918)
		(end 83.650074 -430.5808)
		(width 0.14732)
		(layer "In11.Cu")
		(net "P5E_CPU1_PE0_TX_C_DN<3>")
	)
	(segment
		(start 84.847938 -411.55493)
		(end 84.847938 -406.30475)
		(width 0.14732)
		(layer "In11.Cu")
		(net "P5E_CPU1_PE0_TX_C_DN<3>")
	)
	(segment
		(start 83.46313 -430.393856)
		(end 82.976974 -430.393856)
		(width 0.14732)
		(layer "In11.Cu")
		(net "P5E_CPU1_PE0_TX_C_DN<3>")
	)
	(segment
		(start 88.10498 -403.580854)
		(end 87.801958 -403.883876)
		(width 0.13208)
		(layer "F.Cu")
		(net "P5E_CPU1_PE0_TX_C_DN<2>")
	)
	(segment
		(start 87.776558 -402.637752)
		(end 87.77986 -402.637752)
		(width 0.13208)
		(layer "F.Cu")
		(net "P5E_CPU1_PE0_TX_C_DN<2>")
	)
	(segment
		(start 87.77986 -402.637752)
		(end 88.10498 -402.962872)
		(width 0.13208)
		(layer "F.Cu")
		(net "P5E_CPU1_PE0_TX_C_DN<2>")
	)
	(segment
		(start 88.10498 -402.962872)
		(end 88.10498 -403.580854)
		(width 0.13208)
		(layer "F.Cu")
		(net "P5E_CPU1_PE0_TX_C_DN<2>")
	)
	(segment
		(start 85.463126 -431.393854)
		(end 85.003386 -431.393854)
		(width 0.14732)
		(layer "In11.Cu")
		(net "P5E_CPU1_PE0_TX_C_DN<2>")
	)
	(segment
		(start 88.096598 -404.178516)
		(end 87.801958 -403.883876)
		(width 0.14732)
		(layer "In11.Cu")
		(net "P5E_CPU1_PE0_TX_C_DN<2>")
	)
	(segment
		(start 87.911178 -411.306772)
		(end 87.911178 -406.30475)
		(width 0.14732)
		(layer "In11.Cu")
		(net "P5E_CPU1_PE0_TX_C_DN<2>")
	)
	(segment
		(start 84.691982 -423.70121)
		(end 87.911178 -411.306772)
		(width 0.14732)
		(layer "In11.Cu")
		(net "P5E_CPU1_PE0_TX_C_DN<2>")
	)
	(segment
		(start 84.691982 -431.08245)
		(end 84.691982 -423.70121)
		(width 0.14732)
		(layer "In11.Cu")
		(net "P5E_CPU1_PE0_TX_C_DN<2>")
	)
	(segment
		(start 85.003386 -431.393854)
		(end 84.691982 -431.08245)
		(width 0.14732)
		(layer "In11.Cu")
		(net "P5E_CPU1_PE0_TX_C_DN<2>")
	)
	(segment
		(start 85.65007 -431.580798)
		(end 85.463126 -431.393854)
		(width 0.14732)
		(layer "In11.Cu")
		(net "P5E_CPU1_PE0_TX_C_DN<2>")
	)
	(segment
		(start 85.65007 -431.889916)
		(end 85.65007 -431.580798)
		(width 0.14732)
		(layer "In11.Cu")
		(net "P5E_CPU1_PE0_TX_C_DN<2>")
	)
	(segment
		(start 88.096598 -406.11933)
		(end 88.096598 -404.178516)
		(width 0.14732)
		(layer "In11.Cu")
		(net "P5E_CPU1_PE0_TX_C_DN<2>")
	)
	(segment
		(start 87.911178 -406.30475)
		(end 88.096598 -406.11933)
		(width 0.14732)
		(layer "In11.Cu")
		(net "P5E_CPU1_PE0_TX_C_DN<2>")
	)
	(segment
		(start 91.16822 -403.580854)
		(end 90.865198 -403.883876)
		(width 0.13208)
		(layer "F.Cu")
		(net "P5E_CPU1_PE0_TX_C_DN<1>")
	)
	(segment
		(start 90.839798 -402.637752)
		(end 90.8431 -402.637752)
		(width 0.13208)
		(layer "F.Cu")
		(net "P5E_CPU1_PE0_TX_C_DN<1>")
	)
	(segment
		(start 91.16822 -402.962872)
		(end 91.16822 -403.580854)
		(width 0.13208)
		(layer "F.Cu")
		(net "P5E_CPU1_PE0_TX_C_DN<1>")
	)
	(segment
		(start 90.8431 -402.637752)
		(end 91.16822 -402.962872)
		(width 0.13208)
		(layer "F.Cu")
		(net "P5E_CPU1_PE0_TX_C_DN<1>")
	)
	(segment
		(start 91.159838 -406.11933)
		(end 91.159838 -404.178516)
		(width 0.14732)
		(layer "In11.Cu")
		(net "P5E_CPU1_PE0_TX_C_DN<1>")
	)
	(segment
		(start 90.974418 -411.19298)
		(end 90.974418 -406.30475)
		(width 0.14732)
		(layer "In11.Cu")
		(net "P5E_CPU1_PE0_TX_C_DN<1>")
	)
	(segment
		(start 91.159838 -404.178516)
		(end 90.865198 -403.883876)
		(width 0.14732)
		(layer "In11.Cu")
		(net "P5E_CPU1_PE0_TX_C_DN<1>")
	)
	(segment
		(start 86.691978 -430.108868)
		(end 86.691978 -424.440604)
		(width 0.14732)
		(layer "In11.Cu")
		(net "P5E_CPU1_PE0_TX_C_DN<1>")
	)
	(segment
		(start 87.650066 -430.5808)
		(end 87.463122 -430.393856)
		(width 0.14732)
		(layer "In11.Cu")
		(net "P5E_CPU1_PE0_TX_C_DN<1>")
	)
	(segment
		(start 87.650066 -430.889918)
		(end 87.650066 -430.5808)
		(width 0.14732)
		(layer "In11.Cu")
		(net "P5E_CPU1_PE0_TX_C_DN<1>")
	)
	(segment
		(start 87.463122 -430.393856)
		(end 86.976966 -430.393856)
		(width 0.14732)
		(layer "In11.Cu")
		(net "P5E_CPU1_PE0_TX_C_DN<1>")
	)
	(segment
		(start 86.976966 -430.393856)
		(end 86.691978 -430.108868)
		(width 0.14732)
		(layer "In11.Cu")
		(net "P5E_CPU1_PE0_TX_C_DN<1>")
	)
	(segment
		(start 90.974418 -406.30475)
		(end 91.159838 -406.11933)
		(width 0.14732)
		(layer "In11.Cu")
		(net "P5E_CPU1_PE0_TX_C_DN<1>")
	)
	(segment
		(start 86.691978 -424.440604)
		(end 90.974418 -411.19298)
		(width 0.14732)
		(layer "In11.Cu")
		(net "P5E_CPU1_PE0_TX_C_DN<1>")
	)
	(segment
		(start 48.28286 -402.962872)
		(end 48.28286 -403.580854)
		(width 0.13208)
		(layer "F.Cu")
		(net "P5E_CPU1_PE0_TX_C_DN<15>")
	)
	(segment
		(start 47.954438 -402.637752)
		(end 47.95774 -402.637752)
		(width 0.13208)
		(layer "F.Cu")
		(net "P5E_CPU1_PE0_TX_C_DN<15>")
	)
	(segment
		(start 47.95774 -402.637752)
		(end 48.28286 -402.962872)
		(width 0.13208)
		(layer "F.Cu")
		(net "P5E_CPU1_PE0_TX_C_DN<15>")
	)
	(segment
		(start 48.28286 -403.580854)
		(end 47.979838 -403.883876)
		(width 0.13208)
		(layer "F.Cu")
		(net "P5E_CPU1_PE0_TX_C_DN<15>")
	)
	(segment
		(start 57.965594 -430.393856)
		(end 57.29986 -429.72863)
		(width 0.14732)
		(layer "In11.Cu")
		(net "P5E_CPU1_PE0_TX_C_DN<15>")
	)
	(segment
		(start 48.888904 -411.698694)
		(end 48.089058 -410.420566)
		(width 0.14732)
		(layer "In11.Cu")
		(net "P5E_CPU1_PE0_TX_C_DN<15>")
	)
	(segment
		(start 58.650124 -430.5808)
		(end 58.46318 -430.393856)
		(width 0.14732)
		(layer "In11.Cu")
		(net "P5E_CPU1_PE0_TX_C_DN<15>")
	)
	(segment
		(start 58.650124 -430.889918)
		(end 58.650124 -430.5808)
		(width 0.14732)
		(layer "In11.Cu")
		(net "P5E_CPU1_PE0_TX_C_DN<15>")
	)
	(segment
		(start 48.089058 -406.30475)
		(end 48.274478 -406.11933)
		(width 0.14732)
		(layer "In11.Cu")
		(net "P5E_CPU1_PE0_TX_C_DN<15>")
	)
	(segment
		(start 57.29986 -429.72863)
		(end 57.300368 -429.72863)
		(width 0.14732)
		(layer "In11.Cu")
		(net "P5E_CPU1_PE0_TX_C_DN<15>")
	)
	(segment
		(start 48.274478 -404.178516)
		(end 47.979838 -403.883876)
		(width 0.14732)
		(layer "In11.Cu")
		(net "P5E_CPU1_PE0_TX_C_DN<15>")
	)
	(segment
		(start 58.46318 -430.393856)
		(end 57.965594 -430.393856)
		(width 0.14732)
		(layer "In11.Cu")
		(net "P5E_CPU1_PE0_TX_C_DN<15>")
	)
	(segment
		(start 50.6222 -413.677354)
		(end 48.888904 -411.698694)
		(width 0.14732)
		(layer "In11.Cu")
		(net "P5E_CPU1_PE0_TX_C_DN<15>")
	)
	(segment
		(start 48.089058 -410.420566)
		(end 48.089058 -406.30475)
		(width 0.14732)
		(layer "In11.Cu")
		(net "P5E_CPU1_PE0_TX_C_DN<15>")
	)
	(segment
		(start 48.274478 -406.11933)
		(end 48.274478 -404.178516)
		(width 0.14732)
		(layer "In11.Cu")
		(net "P5E_CPU1_PE0_TX_C_DN<15>")
	)
	(segment
		(start 57.300368 -429.72863)
		(end 50.6222 -413.677354)
		(width 0.14732)
		(layer "In11.Cu")
		(net "P5E_CPU1_PE0_TX_C_DN<15>")
	)
	(segment
		(start 51.3461 -403.580854)
		(end 51.043078 -403.883876)
		(width 0.13208)
		(layer "F.Cu")
		(net "P5E_CPU1_PE0_TX_C_DN<14>")
	)
	(segment
		(start 51.3461 -402.962872)
		(end 51.3461 -403.580854)
		(width 0.13208)
		(layer "F.Cu")
		(net "P5E_CPU1_PE0_TX_C_DN<14>")
	)
	(segment
		(start 51.017678 -402.637752)
		(end 51.02098 -402.637752)
		(width 0.13208)
		(layer "F.Cu")
		(net "P5E_CPU1_PE0_TX_C_DN<14>")
	)
	(segment
		(start 51.02098 -402.637752)
		(end 51.3461 -402.962872)
		(width 0.13208)
		(layer "F.Cu")
		(net "P5E_CPU1_PE0_TX_C_DN<14>")
	)
	(segment
		(start 51.337718 -406.11933)
		(end 51.337718 -404.178516)
		(width 0.14732)
		(layer "In11.Cu")
		(net "P5E_CPU1_PE0_TX_C_DN<14>")
	)
	(segment
		(start 51.779678 -411.428184)
		(end 51.351688 -410.974032)
		(width 0.14732)
		(layer "In11.Cu")
		(net "P5E_CPU1_PE0_TX_C_DN<14>")
	)
	(segment
		(start 51.152298 -406.30475)
		(end 51.337718 -406.11933)
		(width 0.14732)
		(layer "In11.Cu")
		(net "P5E_CPU1_PE0_TX_C_DN<14>")
	)
	(segment
		(start 51.152298 -410.363416)
		(end 51.152298 -406.30475)
		(width 0.14732)
		(layer "In11.Cu")
		(net "P5E_CPU1_PE0_TX_C_DN<14>")
	)
	(segment
		(start 59.692032 -431.108866)
		(end 59.692032 -417.73729)
		(width 0.14732)
		(layer "In11.Cu")
		(net "P5E_CPU1_PE0_TX_C_DN<14>")
	)
	(segment
		(start 60.65012 -431.580798)
		(end 60.463176 -431.393854)
		(width 0.14732)
		(layer "In11.Cu")
		(net "P5E_CPU1_PE0_TX_C_DN<14>")
	)
	(segment
		(start 53.347112 -412.044642)
		(end 51.779678 -411.428184)
		(width 0.14732)
		(layer "In11.Cu")
		(net "P5E_CPU1_PE0_TX_C_DN<14>")
	)
	(segment
		(start 60.65012 -431.889916)
		(end 60.65012 -431.580798)
		(width 0.14732)
		(layer "In11.Cu")
		(net "P5E_CPU1_PE0_TX_C_DN<14>")
	)
	(segment
		(start 59.692032 -417.73729)
		(end 59.387232 -417.001706)
		(width 0.14732)
		(layer "In11.Cu")
		(net "P5E_CPU1_PE0_TX_C_DN<14>")
	)
	(segment
		(start 60.463176 -431.393854)
		(end 59.97702 -431.393854)
		(width 0.14732)
		(layer "In11.Cu")
		(net "P5E_CPU1_PE0_TX_C_DN<14>")
	)
	(segment
		(start 59.387232 -417.001706)
		(end 53.347112 -412.044642)
		(width 0.14732)
		(layer "In11.Cu")
		(net "P5E_CPU1_PE0_TX_C_DN<14>")
	)
	(segment
		(start 51.351688 -410.974032)
		(end 51.152298 -410.363416)
		(width 0.14732)
		(layer "In11.Cu")
		(net "P5E_CPU1_PE0_TX_C_DN<14>")
	)
	(segment
		(start 51.337718 -404.178516)
		(end 51.043078 -403.883876)
		(width 0.14732)
		(layer "In11.Cu")
		(net "P5E_CPU1_PE0_TX_C_DN<14>")
	)
	(segment
		(start 59.97702 -431.393854)
		(end 59.692032 -431.108866)
		(width 0.14732)
		(layer "In11.Cu")
		(net "P5E_CPU1_PE0_TX_C_DN<14>")
	)
	(segment
		(start 54.40934 -403.580854)
		(end 54.106318 -403.883876)
		(width 0.13208)
		(layer "F.Cu")
		(net "P5E_CPU1_PE0_TX_C_DN<13>")
	)
	(segment
		(start 54.080918 -402.637752)
		(end 54.08422 -402.637752)
		(width 0.13208)
		(layer "F.Cu")
		(net "P5E_CPU1_PE0_TX_C_DN<13>")
	)
	(segment
		(start 54.08422 -402.637752)
		(end 54.40934 -402.962872)
		(width 0.13208)
		(layer "F.Cu")
		(net "P5E_CPU1_PE0_TX_C_DN<13>")
	)
	(segment
		(start 54.40934 -402.962872)
		(end 54.40934 -403.580854)
		(width 0.13208)
		(layer "F.Cu")
		(net "P5E_CPU1_PE0_TX_C_DN<13>")
	)
	(segment
		(start 54.665626 -411.227016)
		(end 54.337458 -410.808932)
		(width 0.14732)
		(layer "In11.Cu")
		(net "P5E_CPU1_PE0_TX_C_DN<13>")
	)
	(segment
		(start 55.680864 -411.785562)
		(end 54.665626 -411.227016)
		(width 0.14732)
		(layer "In11.Cu")
		(net "P5E_CPU1_PE0_TX_C_DN<13>")
	)
	(segment
		(start 61.692028 -417.043616)
		(end 59.880754 -415.232342)
		(width 0.14732)
		(layer "In11.Cu")
		(net "P5E_CPU1_PE0_TX_C_DN<13>")
	)
	(segment
		(start 61.977016 -430.393856)
		(end 61.692028 -430.108868)
		(width 0.14732)
		(layer "In11.Cu")
		(net "P5E_CPU1_PE0_TX_C_DN<13>")
	)
	(segment
		(start 54.215538 -410.35605)
		(end 54.215538 -406.30475)
		(width 0.14732)
		(layer "In11.Cu")
		(net "P5E_CPU1_PE0_TX_C_DN<13>")
	)
	(segment
		(start 54.337458 -410.808932)
		(end 54.215538 -410.35605)
		(width 0.14732)
		(layer "In11.Cu")
		(net "P5E_CPU1_PE0_TX_C_DN<13>")
	)
	(segment
		(start 62.650116 -430.5808)
		(end 62.463172 -430.393856)
		(width 0.14732)
		(layer "In11.Cu")
		(net "P5E_CPU1_PE0_TX_C_DN<13>")
	)
	(segment
		(start 61.692028 -430.108868)
		(end 61.692028 -417.043616)
		(width 0.14732)
		(layer "In11.Cu")
		(net "P5E_CPU1_PE0_TX_C_DN<13>")
	)
	(segment
		(start 54.400958 -406.11933)
		(end 54.400958 -404.178516)
		(width 0.14732)
		(layer "In11.Cu")
		(net "P5E_CPU1_PE0_TX_C_DN<13>")
	)
	(segment
		(start 54.215538 -406.30475)
		(end 54.400958 -406.11933)
		(width 0.14732)
		(layer "In11.Cu")
		(net "P5E_CPU1_PE0_TX_C_DN<13>")
	)
	(segment
		(start 62.463172 -430.393856)
		(end 61.977016 -430.393856)
		(width 0.14732)
		(layer "In11.Cu")
		(net "P5E_CPU1_PE0_TX_C_DN<13>")
	)
	(segment
		(start 62.650116 -430.889918)
		(end 62.650116 -430.5808)
		(width 0.14732)
		(layer "In11.Cu")
		(net "P5E_CPU1_PE0_TX_C_DN<13>")
	)
	(segment
		(start 59.880754 -415.232342)
		(end 55.680864 -411.785562)
		(width 0.14732)
		(layer "In11.Cu")
		(net "P5E_CPU1_PE0_TX_C_DN<13>")
	)
	(segment
		(start 54.400958 -404.178516)
		(end 54.106318 -403.883876)
		(width 0.14732)
		(layer "In11.Cu")
		(net "P5E_CPU1_PE0_TX_C_DN<13>")
	)
	(segment
		(start 57.14746 -402.637752)
		(end 57.47258 -402.962872)
		(width 0.13208)
		(layer "F.Cu")
		(net "P5E_CPU1_PE0_TX_C_DN<12>")
	)
	(segment
		(start 57.47258 -403.580854)
		(end 57.169558 -403.883876)
		(width 0.13208)
		(layer "F.Cu")
		(net "P5E_CPU1_PE0_TX_C_DN<12>")
	)
	(segment
		(start 57.144158 -402.637752)
		(end 57.14746 -402.637752)
		(width 0.13208)
		(layer "F.Cu")
		(net "P5E_CPU1_PE0_TX_C_DN<12>")
	)
	(segment
		(start 57.47258 -402.962872)
		(end 57.47258 -403.580854)
		(width 0.13208)
		(layer "F.Cu")
		(net "P5E_CPU1_PE0_TX_C_DN<12>")
	)
	(segment
		(start 57.278778 -410.420058)
		(end 57.278778 -406.30475)
		(width 0.14732)
		(layer "In11.Cu")
		(net "P5E_CPU1_PE0_TX_C_DN<12>")
	)
	(segment
		(start 64.463168 -431.393854)
		(end 63.977012 -431.393854)
		(width 0.14732)
		(layer "In11.Cu")
		(net "P5E_CPU1_PE0_TX_C_DN<12>")
	)
	(segment
		(start 64.650112 -431.889916)
		(end 64.650112 -431.580798)
		(width 0.14732)
		(layer "In11.Cu")
		(net "P5E_CPU1_PE0_TX_C_DN<12>")
	)
	(segment
		(start 57.464198 -404.178516)
		(end 57.169558 -403.883876)
		(width 0.14732)
		(layer "In11.Cu")
		(net "P5E_CPU1_PE0_TX_C_DN<12>")
	)
	(segment
		(start 57.464198 -406.11933)
		(end 57.464198 -404.178516)
		(width 0.14732)
		(layer "In11.Cu")
		(net "P5E_CPU1_PE0_TX_C_DN<12>")
	)
	(segment
		(start 57.574942 -411.097222)
		(end 57.278778 -410.420058)
		(width 0.14732)
		(layer "In11.Cu")
		(net "P5E_CPU1_PE0_TX_C_DN<12>")
	)
	(segment
		(start 57.278778 -406.30475)
		(end 57.464198 -406.11933)
		(width 0.14732)
		(layer "In11.Cu")
		(net "P5E_CPU1_PE0_TX_C_DN<12>")
	)
	(segment
		(start 64.650112 -431.580798)
		(end 64.463168 -431.393854)
		(width 0.14732)
		(layer "In11.Cu")
		(net "P5E_CPU1_PE0_TX_C_DN<12>")
	)
	(segment
		(start 63.692024 -417.214304)
		(end 57.574942 -411.097222)
		(width 0.14732)
		(layer "In11.Cu")
		(net "P5E_CPU1_PE0_TX_C_DN<12>")
	)
	(segment
		(start 63.692024 -431.108866)
		(end 63.692024 -417.214304)
		(width 0.14732)
		(layer "In11.Cu")
		(net "P5E_CPU1_PE0_TX_C_DN<12>")
	)
	(segment
		(start 63.977012 -431.393854)
		(end 63.692024 -431.108866)
		(width 0.14732)
		(layer "In11.Cu")
		(net "P5E_CPU1_PE0_TX_C_DN<12>")
	)
	(segment
		(start 60.53582 -403.580854)
		(end 60.232798 -403.883876)
		(width 0.13208)
		(layer "F.Cu")
		(net "P5E_CPU1_PE0_TX_C_DN<11>")
	)
	(segment
		(start 60.207398 -402.637752)
		(end 60.2107 -402.637752)
		(width 0.13208)
		(layer "F.Cu")
		(net "P5E_CPU1_PE0_TX_C_DN<11>")
	)
	(segment
		(start 60.53582 -402.962872)
		(end 60.53582 -403.580854)
		(width 0.13208)
		(layer "F.Cu")
		(net "P5E_CPU1_PE0_TX_C_DN<11>")
	)
	(segment
		(start 60.2107 -402.637752)
		(end 60.53582 -402.962872)
		(width 0.13208)
		(layer "F.Cu")
		(net "P5E_CPU1_PE0_TX_C_DN<11>")
	)
	(segment
		(start 60.527438 -404.178516)
		(end 60.232798 -403.883876)
		(width 0.14732)
		(layer "In11.Cu")
		(net "P5E_CPU1_PE0_TX_C_DN<11>")
	)
	(segment
		(start 60.342018 -410.374846)
		(end 60.342018 -406.30475)
		(width 0.14732)
		(layer "In11.Cu")
		(net "P5E_CPU1_PE0_TX_C_DN<11>")
	)
	(segment
		(start 65.69202 -430.109884)
		(end 65.69202 -418.107622)
		(width 0.14732)
		(layer "In11.Cu")
		(net "P5E_CPU1_PE0_TX_C_DN<11>")
	)
	(segment
		(start 60.8457 -411.771084)
		(end 60.342018 -410.374846)
		(width 0.14732)
		(layer "In11.Cu")
		(net "P5E_CPU1_PE0_TX_C_DN<11>")
	)
	(segment
		(start 66.463164 -430.393856)
		(end 65.975992 -430.393856)
		(width 0.14732)
		(layer "In11.Cu")
		(net "P5E_CPU1_PE0_TX_C_DN<11>")
	)
	(segment
		(start 60.527438 -406.11933)
		(end 60.527438 -404.178516)
		(width 0.14732)
		(layer "In11.Cu")
		(net "P5E_CPU1_PE0_TX_C_DN<11>")
	)
	(segment
		(start 65.69202 -418.107622)
		(end 65.37579 -417.231322)
		(width 0.14732)
		(layer "In11.Cu")
		(net "P5E_CPU1_PE0_TX_C_DN<11>")
	)
	(segment
		(start 66.650108 -430.5808)
		(end 66.463164 -430.393856)
		(width 0.14732)
		(layer "In11.Cu")
		(net "P5E_CPU1_PE0_TX_C_DN<11>")
	)
	(segment
		(start 65.975992 -430.393856)
		(end 65.69202 -430.109884)
		(width 0.14732)
		(layer "In11.Cu")
		(net "P5E_CPU1_PE0_TX_C_DN<11>")
	)
	(segment
		(start 65.37579 -417.231322)
		(end 60.8457 -411.771084)
		(width 0.14732)
		(layer "In11.Cu")
		(net "P5E_CPU1_PE0_TX_C_DN<11>")
	)
	(segment
		(start 60.342018 -406.30475)
		(end 60.527438 -406.11933)
		(width 0.14732)
		(layer "In11.Cu")
		(net "P5E_CPU1_PE0_TX_C_DN<11>")
	)
	(segment
		(start 66.650108 -430.889918)
		(end 66.650108 -430.5808)
		(width 0.14732)
		(layer "In11.Cu")
		(net "P5E_CPU1_PE0_TX_C_DN<11>")
	)
	(segment
		(start 63.270638 -402.637752)
		(end 63.27394 -402.637752)
		(width 0.13208)
		(layer "F.Cu")
		(net "P5E_CPU1_PE0_TX_C_DN<10>")
	)
	(segment
		(start 63.59906 -403.580854)
		(end 63.296038 -403.883876)
		(width 0.13208)
		(layer "F.Cu")
		(net "P5E_CPU1_PE0_TX_C_DN<10>")
	)
	(segment
		(start 63.27394 -402.637752)
		(end 63.59906 -402.962872)
		(width 0.13208)
		(layer "F.Cu")
		(net "P5E_CPU1_PE0_TX_C_DN<10>")
	)
	(segment
		(start 63.59906 -402.962872)
		(end 63.59906 -403.580854)
		(width 0.13208)
		(layer "F.Cu")
		(net "P5E_CPU1_PE0_TX_C_DN<10>")
	)
	(segment
		(start 68.650104 -431.889916)
		(end 68.650104 -431.580798)
		(width 0.14732)
		(layer "In11.Cu")
		(net "P5E_CPU1_PE0_TX_C_DN<10>")
	)
	(segment
		(start 67.977004 -431.393854)
		(end 67.692016 -431.108866)
		(width 0.14732)
		(layer "In11.Cu")
		(net "P5E_CPU1_PE0_TX_C_DN<10>")
	)
	(segment
		(start 63.590678 -404.178516)
		(end 63.296038 -403.883876)
		(width 0.14732)
		(layer "In11.Cu")
		(net "P5E_CPU1_PE0_TX_C_DN<10>")
	)
	(segment
		(start 67.692016 -417.528502)
		(end 64.725042 -412.836106)
		(width 0.14732)
		(layer "In11.Cu")
		(net "P5E_CPU1_PE0_TX_C_DN<10>")
	)
	(segment
		(start 63.405258 -406.30475)
		(end 63.590678 -406.11933)
		(width 0.14732)
		(layer "In11.Cu")
		(net "P5E_CPU1_PE0_TX_C_DN<10>")
	)
	(segment
		(start 64.725042 -412.836106)
		(end 64.725296 -412.836106)
		(width 0.14732)
		(layer "In11.Cu")
		(net "P5E_CPU1_PE0_TX_C_DN<10>")
	)
	(segment
		(start 63.796926 -411.367986)
		(end 63.405258 -410.53131)
		(width 0.14732)
		(layer "In11.Cu")
		(net "P5E_CPU1_PE0_TX_C_DN<10>")
	)
	(segment
		(start 67.692016 -431.108866)
		(end 67.692016 -417.528502)
		(width 0.14732)
		(layer "In11.Cu")
		(net "P5E_CPU1_PE0_TX_C_DN<10>")
	)
	(segment
		(start 63.590678 -406.11933)
		(end 63.590678 -404.178516)
		(width 0.14732)
		(layer "In11.Cu")
		(net "P5E_CPU1_PE0_TX_C_DN<10>")
	)
	(segment
		(start 68.650104 -431.580798)
		(end 68.46316 -431.393854)
		(width 0.14732)
		(layer "In11.Cu")
		(net "P5E_CPU1_PE0_TX_C_DN<10>")
	)
	(segment
		(start 68.46316 -431.393854)
		(end 67.977004 -431.393854)
		(width 0.14732)
		(layer "In11.Cu")
		(net "P5E_CPU1_PE0_TX_C_DN<10>")
	)
	(segment
		(start 63.405258 -410.53131)
		(end 63.405258 -406.30475)
		(width 0.14732)
		(layer "In11.Cu")
		(net "P5E_CPU1_PE0_TX_C_DN<10>")
	)
	(segment
		(start 64.725296 -412.836106)
		(end 63.796926 -411.367986)
		(width 0.14732)
		(layer "In11.Cu")
		(net "P5E_CPU1_PE0_TX_C_DN<10>")
	)
	(segment
		(start 94.23146 -403.580854)
		(end 93.928438 -403.883876)
		(width 0.13208)
		(layer "F.Cu")
		(net "P5E_CPU1_PE0_TX_C_DN<0>")
	)
	(segment
		(start 94.23146 -402.962872)
		(end 94.23146 -403.580854)
		(width 0.13208)
		(layer "F.Cu")
		(net "P5E_CPU1_PE0_TX_C_DN<0>")
	)
	(segment
		(start 93.903038 -402.637752)
		(end 93.90634 -402.637752)
		(width 0.13208)
		(layer "F.Cu")
		(net "P5E_CPU1_PE0_TX_C_DN<0>")
	)
	(segment
		(start 93.90634 -402.637752)
		(end 94.23146 -402.962872)
		(width 0.13208)
		(layer "F.Cu")
		(net "P5E_CPU1_PE0_TX_C_DN<0>")
	)
	(segment
		(start 88.691974 -424.01998)
		(end 94.037658 -411.114494)
		(width 0.14732)
		(layer "In11.Cu")
		(net "P5E_CPU1_PE0_TX_C_DN<0>")
	)
	(segment
		(start 94.223078 -404.178516)
		(end 93.928438 -403.883876)
		(width 0.14732)
		(layer "In11.Cu")
		(net "P5E_CPU1_PE0_TX_C_DN<0>")
	)
	(segment
		(start 88.976962 -431.393854)
		(end 88.691974 -431.108866)
		(width 0.14732)
		(layer "In11.Cu")
		(net "P5E_CPU1_PE0_TX_C_DN<0>")
	)
	(segment
		(start 88.691974 -431.108866)
		(end 88.691974 -424.01998)
		(width 0.14732)
		(layer "In11.Cu")
		(net "P5E_CPU1_PE0_TX_C_DN<0>")
	)
	(segment
		(start 89.463118 -431.393854)
		(end 88.976962 -431.393854)
		(width 0.14732)
		(layer "In11.Cu")
		(net "P5E_CPU1_PE0_TX_C_DN<0>")
	)
	(segment
		(start 89.650062 -431.580798)
		(end 89.463118 -431.393854)
		(width 0.14732)
		(layer "In11.Cu")
		(net "P5E_CPU1_PE0_TX_C_DN<0>")
	)
	(segment
		(start 94.223078 -406.11933)
		(end 94.223078 -404.178516)
		(width 0.14732)
		(layer "In11.Cu")
		(net "P5E_CPU1_PE0_TX_C_DN<0>")
	)
	(segment
		(start 89.650062 -431.889916)
		(end 89.650062 -431.580798)
		(width 0.14732)
		(layer "In11.Cu")
		(net "P5E_CPU1_PE0_TX_C_DN<0>")
	)
	(segment
		(start 94.037658 -411.114494)
		(end 94.037658 -406.30475)
		(width 0.14732)
		(layer "In11.Cu")
		(net "P5E_CPU1_PE0_TX_C_DN<0>")
	)
	(segment
		(start 94.037658 -406.30475)
		(end 94.223078 -406.11933)
		(width 0.14732)
		(layer "In11.Cu")
		(net "P5E_CPU1_PE0_TX_C_DN<0>")
	)
	(segment
		(start 110.700566 -221.133924)
		(end 110.700566 -221.669864)
		(width 0.13208)
		(layer "F.Cu")
		(net "P5E_CPU1_PE1_RX_DP<9>")
	)
	(segment
		(start 29.947108 -7.795514)
		(end 30.119066 -7.623556)
		(width 0.13208)
		(layer "F.Cu")
		(net "P5E_CPU1_PE1_RX_DP<9>")
	)
	(segment
		(start 29.947108 -8.320024)
		(end 29.947108 -7.795514)
		(width 0.13208)
		(layer "F.Cu")
		(net "P5E_CPU1_PE1_RX_DP<9>")
	)
	(segment
		(start 30.119066 -7.026656)
		(end 29.816806 -6.724396)
		(width 0.13208)
		(layer "F.Cu")
		(net "P5E_CPU1_PE1_RX_DP<9>")
	)
	(segment
		(start 30.119066 -7.623556)
		(end 30.119066 -7.026656)
		(width 0.13208)
		(layer "F.Cu")
		(net "P5E_CPU1_PE1_RX_DP<9>")
	)
	(segment
		(start 109.195616 -217.8939)
		(end 109.195616 -217.856308)
		(width 0.0889)
		(layer "In11.Cu")
		(net "P5E_CPU1_PE1_RX_DP<9>")
	)
	(segment
		(start 109.195108 -213.984586)
		(end 109.665262 -213.514432)
		(width 0.0889)
		(layer "In11.Cu")
		(net "P5E_CPU1_PE1_RX_DP<9>")
	)
	(segment
		(start 109.623352 -213.164928)
		(end 109.623352 -211.745322)
		(width 0.14732)
		(layer "In11.Cu")
		(net "P5E_CPU1_PE1_RX_DP<9>")
	)
	(segment
		(start 34.178748 -20.593304)
		(end 33.65246 -19.323304)
		(width 0.14732)
		(layer "In11.Cu")
		(net "P5E_CPU1_PE1_RX_DP<9>")
	)
	(segment
		(start 34.165286 -16.988028)
		(end 33.134808 -15.85722)
		(width 0.14732)
		(layer "In11.Cu")
		(net "P5E_CPU1_PE1_RX_DP<9>")
	)
	(segment
		(start 33.65246 -18.90395)
		(end 33.844738 -18.439638)
		(width 0.14732)
		(layer "In11.Cu")
		(net "P5E_CPU1_PE1_RX_DP<9>")
	)
	(segment
		(start 31.199074 -13.94841)
		(end 31.208472 -13.74394)
		(width 0.14732)
		(layer "In11.Cu")
		(net "P5E_CPU1_PE1_RX_DP<9>")
	)
	(segment
		(start 33.65246 -19.323304)
		(end 33.65246 -18.90395)
		(width 0.14732)
		(layer "In11.Cu")
		(net "P5E_CPU1_PE1_RX_DP<9>")
	)
	(segment
		(start 109.478826 -216.740486)
		(end 109.47781 -216.739978)
		(width 0.0889)
		(layer "In11.Cu")
		(net "P5E_CPU1_PE1_RX_DP<9>")
	)
	(segment
		(start 110.887764 -221.458282)
		(end 110.896654 -221.453202)
		(width 0.0889)
		(layer "In11.Cu")
		(net "P5E_CPU1_PE1_RX_DP<9>")
	)
	(segment
		(start 34.32302 -17.394428)
		(end 34.165286 -16.988028)
		(width 0.14732)
		(layer "In11.Cu")
		(net "P5E_CPU1_PE1_RX_DP<9>")
	)
	(segment
		(start 110.605062 -220.334078)
		(end 110.605062 -220.311218)
		(width 0.0889)
		(layer "In11.Cu")
		(net "P5E_CPU1_PE1_RX_DP<9>")
	)
	(segment
		(start 110.135416 -219.515944)
		(end 110.135416 -219.506038)
		(width 0.0889)
		(layer "In11.Cu")
		(net "P5E_CPU1_PE1_RX_DP<9>")
	)
	(segment
		(start 109.956854 -219.18676)
		(end 109.935772 -219.174822)
		(width 0.0889)
		(layer "In11.Cu")
		(net "P5E_CPU1_PE1_RX_DP<9>")
	)
	(segment
		(start 109.195616 -216.266014)
		(end 109.195616 -216.25052)
		(width 0.0889)
		(layer "In11.Cu")
		(net "P5E_CPU1_PE1_RX_DP<9>")
	)
	(segment
		(start 32.930338 -15.847822)
		(end 32.681926 -15.57528)
		(width 0.14732)
		(layer "In11.Cu")
		(net "P5E_CPU1_PE1_RX_DP<9>")
	)
	(segment
		(start 34.32302 -17.707356)
		(end 34.32302 -17.394428)
		(width 0.14732)
		(layer "In11.Cu")
		(net "P5E_CPU1_PE1_RX_DP<9>")
	)
	(segment
		(start 109.440472 -209.256884)
		(end 105.32872 -181.40172)
		(width 0.14732)
		(layer "In11.Cu")
		(net "P5E_CPU1_PE1_RX_DP<9>")
	)
	(segment
		(start 109.017054 -215.931242)
		(end 109.002068 -215.922606)
		(width 0.0889)
		(layer "In11.Cu")
		(net "P5E_CPU1_PE1_RX_DP<9>")
	)
	(segment
		(start 30.111446 -7.019036)
		(end 29.816806 -6.724396)
		(width 0.14732)
		(layer "In11.Cu")
		(net "P5E_CPU1_PE1_RX_DP<9>")
	)
	(segment
		(start 109.665262 -213.514432)
		(end 109.665262 -213.228936)
		(width 0.0889)
		(layer "In11.Cu")
		(net "P5E_CPU1_PE1_RX_DP<9>")
	)
	(segment
		(start 109.665262 -213.228936)
		(end 109.623352 -213.187026)
		(width 0.0889)
		(layer "In11.Cu")
		(net "P5E_CPU1_PE1_RX_DP<9>")
	)
	(segment
		(start 110.544102 -221.404942)
		(end 110.565184 -221.48292)
		(width 0.0889)
		(layer "In11.Cu")
		(net "P5E_CPU1_PE1_RX_DP<9>")
	)
	(segment
		(start 32.691324 -15.37081)
		(end 32.36087 -15.008098)
		(width 0.14732)
		(layer "In11.Cu")
		(net "P5E_CPU1_PE1_RX_DP<9>")
	)
	(segment
		(start 33.134808 -15.85722)
		(end 32.930338 -15.847822)
		(width 0.14732)
		(layer "In11.Cu")
		(net "P5E_CPU1_PE1_RX_DP<9>")
	)
	(segment
		(start 31.208472 -13.74394)
		(end 30.50667 -12.973812)
		(width 0.14732)
		(layer "In11.Cu")
		(net "P5E_CPU1_PE1_RX_DP<9>")
	)
	(segment
		(start 104.63403 -179.187094)
		(end 54.905148 -59.134502)
		(width 0.14732)
		(layer "In11.Cu")
		(net "P5E_CPU1_PE1_RX_DP<9>")
	)
	(segment
		(start 109.478826 -218.368372)
		(end 109.47781 -218.367864)
		(width 0.0889)
		(layer "In11.Cu")
		(net "P5E_CPU1_PE1_RX_DP<9>")
	)
	(segment
		(start 110.896654 -220.814646)
		(end 110.887764 -220.809566)
		(width 0.0889)
		(layer "In11.Cu")
		(net "P5E_CPU1_PE1_RX_DP<9>")
	)
	(segment
		(start 34.143188 -18.141188)
		(end 34.32302 -17.707356)
		(width 0.14732)
		(layer "In11.Cu")
		(net "P5E_CPU1_PE1_RX_DP<9>")
	)
	(segment
		(start 31.447232 -14.220698)
		(end 31.199074 -13.94841)
		(width 0.14732)
		(layer "In11.Cu")
		(net "P5E_CPU1_PE1_RX_DP<9>")
	)
	(segment
		(start 109.007656 -214.946992)
		(end 109.016546 -214.941912)
		(width 0.0889)
		(layer "In11.Cu")
		(net "P5E_CPU1_PE1_RX_DP<9>")
	)
	(segment
		(start 109.4867 -218.372944)
		(end 109.478826 -218.368372)
		(width 0.0889)
		(layer "In11.Cu")
		(net "P5E_CPU1_PE1_RX_DP<9>")
	)
	(segment
		(start 33.844738 -18.439638)
		(end 34.143188 -18.141188)
		(width 0.14732)
		(layer "In11.Cu")
		(net "P5E_CPU1_PE1_RX_DP<9>")
	)
	(segment
		(start 110.700566 -221.133924)
		(end 110.544102 -221.404942)
		(width 0.0889)
		(layer "In11.Cu")
		(net "P5E_CPU1_PE1_RX_DP<9>")
	)
	(segment
		(start 30.111446 -11.953494)
		(end 30.111446 -7.019036)
		(width 0.14732)
		(layer "In11.Cu")
		(net "P5E_CPU1_PE1_RX_DP<9>")
	)
	(segment
		(start 30.50667 -12.973812)
		(end 30.111446 -11.953494)
		(width 0.14732)
		(layer "In11.Cu")
		(net "P5E_CPU1_PE1_RX_DP<9>")
	)
	(segment
		(start 31.651956 -14.23035)
		(end 31.447232 -14.220698)
		(width 0.14732)
		(layer "In11.Cu")
		(net "P5E_CPU1_PE1_RX_DP<9>")
	)
	(segment
		(start 54.905148 -59.134502)
		(end 34.178748 -20.593304)
		(width 0.14732)
		(layer "In11.Cu")
		(net "P5E_CPU1_PE1_RX_DP<9>")
	)
	(segment
		(start 109.623352 -211.745322)
		(end 109.440472 -209.256884)
		(width 0.14732)
		(layer "In11.Cu")
		(net "P5E_CPU1_PE1_RX_DP<9>")
	)
	(segment
		(start 109.4867 -216.745058)
		(end 109.478826 -216.740486)
		(width 0.0889)
		(layer "In11.Cu")
		(net "P5E_CPU1_PE1_RX_DP<9>")
	)
	(segment
		(start 109.623352 -213.187026)
		(end 109.623352 -213.164928)
		(width 0.0889)
		(layer "In11.Cu")
		(net "P5E_CPU1_PE1_RX_DP<9>")
	)
	(segment
		(start 109.935772 -219.174822)
		(end 109.935772 -219.174568)
		(width 0.0889)
		(layer "In11.Cu")
		(net "P5E_CPU1_PE1_RX_DP<9>")
	)
	(segment
		(start 32.1564 -14.9987)
		(end 31.907988 -14.726158)
		(width 0.14732)
		(layer "In11.Cu")
		(net "P5E_CPU1_PE1_RX_DP<9>")
	)
	(segment
		(start 32.36087 -15.008098)
		(end 32.1564 -14.9987)
		(width 0.14732)
		(layer "In11.Cu")
		(net "P5E_CPU1_PE1_RX_DP<9>")
	)
	(segment
		(start 109.195108 -214.622634)
		(end 109.195108 -213.984586)
		(width 0.0889)
		(layer "In11.Cu")
		(net "P5E_CPU1_PE1_RX_DP<9>")
	)
	(segment
		(start 109.47781 -217.388694)
		(end 109.4867 -217.383614)
		(width 0.0889)
		(layer "In11.Cu")
		(net "P5E_CPU1_PE1_RX_DP<9>")
	)
	(segment
		(start 32.681926 -15.57528)
		(end 32.691324 -15.37081)
		(width 0.14732)
		(layer "In11.Cu")
		(net "P5E_CPU1_PE1_RX_DP<9>")
	)
	(segment
		(start 31.917386 -14.521688)
		(end 31.651956 -14.23035)
		(width 0.14732)
		(layer "In11.Cu")
		(net "P5E_CPU1_PE1_RX_DP<9>")
	)
	(segment
		(start 108.725462 -215.436704)
		(end 108.725462 -215.414606)
		(width 0.0889)
		(layer "In11.Cu")
		(net "P5E_CPU1_PE1_RX_DP<9>")
	)
	(segment
		(start 31.907988 -14.726158)
		(end 31.917386 -14.521688)
		(width 0.14732)
		(layer "In11.Cu")
		(net "P5E_CPU1_PE1_RX_DP<9>")
	)
	(segment
		(start 105.32872 -181.40172)
		(end 104.63403 -179.187094)
		(width 0.14732)
		(layer "In11.Cu")
		(net "P5E_CPU1_PE1_RX_DP<9>")
	)
	(arc
		(start 108.725462 -215.414606)
		(mid 108.806373 -215.144478)
		(end 109.007656 -214.946992)
		(width 0.0889)
		(layer "In11.Cu")
		(net "P5E_CPU1_PE1_RX_DP<9>")
	)
	(arc
		(start 110.896654 -221.453202)
		(mid 111.025943 -221.319716)
		(end 111.075216 -221.140528)
		(width 0.0889)
		(layer "In11.Cu")
		(net "P5E_CPU1_PE1_RX_DP<9>")
	)
	(arc
		(start 109.195616 -216.25052)
		(mid 109.147937 -216.06762)
		(end 109.017054 -215.931242)
		(width 0.0889)
		(layer "In11.Cu")
		(net "P5E_CPU1_PE1_RX_DP<9>")
	)
	(arc
		(start 109.195616 -217.856308)
		(mid 109.276527 -217.58618)
		(end 109.47781 -217.388694)
		(width 0.0889)
		(layer "In11.Cu")
		(net "P5E_CPU1_PE1_RX_DP<9>")
	)
	(arc
		(start 111.075216 -221.124526)
		(mid 111.02532 -220.946879)
		(end 110.896654 -220.814646)
		(width 0.0889)
		(layer "In11.Cu")
		(net "P5E_CPU1_PE1_RX_DP<9>")
	)
	(arc
		(start 110.605062 -220.311218)
		(mid 110.552792 -220.128853)
		(end 110.417864 -219.995496)
		(width 0.0889)
		(layer "In11.Cu")
		(net "P5E_CPU1_PE1_RX_DP<9>")
	)
	(arc
		(start 110.887764 -220.809566)
		(mid 110.684283 -220.608762)
		(end 110.605062 -220.334078)
		(width 0.0889)
		(layer "In11.Cu")
		(net "P5E_CPU1_PE1_RX_DP<9>")
	)
	(arc
		(start 109.47781 -216.739978)
		(mid 109.274987 -216.539747)
		(end 109.195616 -216.266014)
		(width 0.0889)
		(layer "In11.Cu")
		(net "P5E_CPU1_PE1_RX_DP<9>")
	)
	(arc
		(start 110.565184 -221.48292)
		(mid 110.72928 -221.507267)
		(end 110.887764 -221.458282)
		(width 0.0889)
		(layer "In11.Cu")
		(net "P5E_CPU1_PE1_RX_DP<9>")
	)
	(arc
		(start 109.4867 -217.383614)
		(mid 109.665297 -217.064336)
		(end 109.4867 -216.745058)
		(width 0.0889)
		(layer "In11.Cu")
		(net "P5E_CPU1_PE1_RX_DP<9>")
	)
	(arc
		(start 109.935772 -219.174568)
		(mid 109.737544 -218.96872)
		(end 109.665262 -218.692222)
		(width 0.0889)
		(layer "In11.Cu")
		(net "P5E_CPU1_PE1_RX_DP<9>")
	)
	(arc
		(start 109.665262 -218.692222)
		(mid 109.617583 -218.509322)
		(end 109.4867 -218.372944)
		(width 0.0889)
		(layer "In11.Cu")
		(net "P5E_CPU1_PE1_RX_DP<9>")
	)
	(arc
		(start 111.075216 -221.140528)
		(mid 111.075299 -221.132527)
		(end 111.075216 -221.124526)
		(width 0.0889)
		(layer "In11.Cu")
		(net "P5E_CPU1_PE1_RX_DP<9>")
	)
	(arc
		(start 109.002068 -215.922606)
		(mid 108.799481 -215.716255)
		(end 108.725462 -215.436704)
		(width 0.0889)
		(layer "In11.Cu")
		(net "P5E_CPU1_PE1_RX_DP<9>")
	)
	(arc
		(start 110.135416 -219.506038)
		(mid 110.087737 -219.323138)
		(end 109.956854 -219.18676)
		(width 0.0889)
		(layer "In11.Cu")
		(net "P5E_CPU1_PE1_RX_DP<9>")
	)
	(arc
		(start 109.47781 -218.367864)
		(mid 109.274987 -218.167633)
		(end 109.195616 -217.8939)
		(width 0.0889)
		(layer "In11.Cu")
		(net "P5E_CPU1_PE1_RX_DP<9>")
	)
	(arc
		(start 110.417864 -219.995496)
		(mid 110.213529 -219.792891)
		(end 110.135416 -219.515944)
		(width 0.0889)
		(layer "In11.Cu")
		(net "P5E_CPU1_PE1_RX_DP<9>")
	)
	(arc
		(start 109.016546 -214.941912)
		(mid 109.14746 -214.805552)
		(end 109.195108 -214.622634)
		(width 0.0889)
		(layer "In11.Cu")
		(net "P5E_CPU1_PE1_RX_DP<9>")
	)
	(segment
		(start 111.170466 -220.855794)
		(end 111.170212 -220.85554)
		(width 0.13208)
		(layer "F.Cu")
		(net "P5E_CPU1_PE1_RX_DP<8>")
	)
	(segment
		(start 31.92272 -7.610348)
		(end 31.92272 -5.263896)
		(width 0.13208)
		(layer "F.Cu")
		(net "P5E_CPU1_PE1_RX_DP<8>")
	)
	(segment
		(start 31.92272 -5.263896)
		(end 31.621476 -4.962652)
		(width 0.13208)
		(layer "F.Cu")
		(net "P5E_CPU1_PE1_RX_DP<8>")
	)
	(segment
		(start 111.170212 -220.85554)
		(end 111.170212 -220.319854)
		(width 0.13208)
		(layer "F.Cu")
		(net "P5E_CPU1_PE1_RX_DP<8>")
	)
	(segment
		(start 31.746952 -8.320024)
		(end 31.746952 -7.786116)
		(width 0.13208)
		(layer "F.Cu")
		(net "P5E_CPU1_PE1_RX_DP<8>")
	)
	(segment
		(start 31.746952 -7.786116)
		(end 31.92272 -7.610348)
		(width 0.13208)
		(layer "F.Cu")
		(net "P5E_CPU1_PE1_RX_DP<8>")
	)
	(segment
		(start 111.326676 -220.590872)
		(end 111.404908 -220.6117)
		(width 0.0889)
		(layer "In11.Cu")
		(net "P5E_CPU1_PE1_RX_DP<8>")
	)
	(segment
		(start 110.896654 -219.18676)
		(end 110.887764 -219.18168)
		(width 0.0889)
		(layer "In11.Cu")
		(net "P5E_CPU1_PE1_RX_DP<8>")
	)
	(segment
		(start 111.3663 -220.000576)
		(end 111.358426 -219.996004)
		(width 0.0889)
		(layer "In11.Cu")
		(net "P5E_CPU1_PE1_RX_DP<8>")
	)
	(segment
		(start 35.002978 -14.173708)
		(end 35.094418 -13.99032)
		(width 0.14732)
		(layer "In11.Cu")
		(net "P5E_CPU1_PE1_RX_DP<8>")
	)
	(segment
		(start 110.41761 -215.761062)
		(end 110.4265 -215.755982)
		(width 0.0889)
		(layer "In11.Cu")
		(net "P5E_CPU1_PE1_RX_DP<8>")
	)
	(segment
		(start 111.075216 -219.521532)
		(end 111.075216 -219.506038)
		(width 0.0889)
		(layer "In11.Cu")
		(net "P5E_CPU1_PE1_RX_DP<8>")
	)
	(segment
		(start 110.135162 -214.636858)
		(end 110.135162 -214.285322)
		(width 0.0889)
		(layer "In11.Cu")
		(net "P5E_CPU1_PE1_RX_DP<8>")
	)
	(segment
		(start 35.11931 -14.523212)
		(end 35.002978 -14.173708)
		(width 0.14732)
		(layer "In11.Cu")
		(net "P5E_CPU1_PE1_RX_DP<8>")
	)
	(segment
		(start 110.605062 -217.072972)
		(end 110.605062 -217.0557)
		(width 0.0889)
		(layer "In11.Cu")
		(net "P5E_CPU1_PE1_RX_DP<8>")
	)
	(segment
		(start 33.441386 -9.330944)
		(end 31.916116 -7.049262)
		(width 0.14732)
		(layer "In11.Cu")
		(net "P5E_CPU1_PE1_RX_DP<8>")
	)
	(segment
		(start 55.688484 -58.561224)
		(end 37.055552 -18.897346)
		(width 0.14732)
		(layer "In11.Cu")
		(net "P5E_CPU1_PE1_RX_DP<8>")
	)
	(segment
		(start 110.135162 -214.285322)
		(end 110.60557 -213.814914)
		(width 0.0889)
		(layer "In11.Cu")
		(net "P5E_CPU1_PE1_RX_DP<8>")
	)
	(segment
		(start 110.421166 -218.369896)
		(end 110.41761 -218.36761)
		(width 0.0889)
		(layer "In11.Cu")
		(net "P5E_CPU1_PE1_RX_DP<8>")
	)
	(segment
		(start 35.302698 -14.614906)
		(end 35.11931 -14.523212)
		(width 0.14732)
		(layer "In11.Cu")
		(net "P5E_CPU1_PE1_RX_DP<8>")
	)
	(segment
		(start 34.978086 -13.64107)
		(end 34.794698 -13.549376)
		(width 0.14732)
		(layer "In11.Cu")
		(net "P5E_CPU1_PE1_RX_DP<8>")
	)
	(segment
		(start 34.678112 -13.199872)
		(end 34.769806 -13.016738)
		(width 0.14732)
		(layer "In11.Cu")
		(net "P5E_CPU1_PE1_RX_DP<8>")
	)
	(segment
		(start 110.346744 -208.270094)
		(end 106.275124 -180.686202)
		(width 0.14732)
		(layer "In11.Cu")
		(net "P5E_CPU1_PE1_RX_DP<8>")
	)
	(segment
		(start 34.769806 -13.016738)
		(end 33.62325 -9.576562)
		(width 0.14732)
		(layer "In11.Cu")
		(net "P5E_CPU1_PE1_RX_DP<8>")
	)
	(segment
		(start 37.055552 -18.897346)
		(end 36.349178 -17.754092)
		(width 0.14732)
		(layer "In11.Cu")
		(net "P5E_CPU1_PE1_RX_DP<8>")
	)
	(segment
		(start 110.60557 -213.105238)
		(end 110.56366 -213.063328)
		(width 0.0889)
		(layer "In11.Cu")
		(net "P5E_CPU1_PE1_RX_DP<8>")
	)
	(segment
		(start 110.41761 -218.36761)
		(end 110.417864 -218.367864)
		(width 0.0889)
		(layer "In11.Cu")
		(net "P5E_CPU1_PE1_RX_DP<8>")
	)
	(segment
		(start 31.916116 -5.257292)
		(end 31.621476 -4.962652)
		(width 0.14732)
		(layer "In11.Cu")
		(net "P5E_CPU1_PE1_RX_DP<8>")
	)
	(segment
		(start 110.418626 -215.112854)
		(end 110.41761 -215.112346)
		(width 0.0889)
		(layer "In11.Cu")
		(net "P5E_CPU1_PE1_RX_DP<8>")
	)
	(segment
		(start 111.358426 -219.996004)
		(end 111.35741 -219.995496)
		(width 0.0889)
		(layer "In11.Cu")
		(net "P5E_CPU1_PE1_RX_DP<8>")
	)
	(segment
		(start 110.60557 -213.814914)
		(end 110.60557 -213.105238)
		(width 0.0889)
		(layer "In11.Cu")
		(net "P5E_CPU1_PE1_RX_DP<8>")
	)
	(segment
		(start 106.275124 -180.686202)
		(end 55.688484 -58.561224)
		(width 0.14732)
		(layer "In11.Cu")
		(net "P5E_CPU1_PE1_RX_DP<8>")
	)
	(segment
		(start 36.349178 -17.754092)
		(end 35.302698 -14.614906)
		(width 0.14732)
		(layer "In11.Cu")
		(net "P5E_CPU1_PE1_RX_DP<8>")
	)
	(segment
		(start 110.60557 -218.706446)
		(end 110.605316 -218.692222)
		(width 0.0889)
		(layer "In11.Cu")
		(net "P5E_CPU1_PE1_RX_DP<8>")
	)
	(segment
		(start 110.56366 -213.04123)
		(end 110.56366 -211.220558)
		(width 0.14732)
		(layer "In11.Cu")
		(net "P5E_CPU1_PE1_RX_DP<8>")
	)
	(segment
		(start 110.56366 -211.220558)
		(end 110.346744 -208.270094)
		(width 0.14732)
		(layer "In11.Cu")
		(net "P5E_CPU1_PE1_RX_DP<8>")
	)
	(segment
		(start 35.094418 -13.99032)
		(end 34.978086 -13.64107)
		(width 0.14732)
		(layer "In11.Cu")
		(net "P5E_CPU1_PE1_RX_DP<8>")
	)
	(segment
		(start 111.170212 -220.319854)
		(end 111.326676 -220.590872)
		(width 0.0889)
		(layer "In11.Cu")
		(net "P5E_CPU1_PE1_RX_DP<8>")
	)
	(segment
		(start 110.135416 -217.888312)
		(end 110.135416 -217.859864)
		(width 0.0889)
		(layer "In11.Cu")
		(net "P5E_CPU1_PE1_RX_DP<8>")
	)
	(segment
		(start 110.4265 -215.117426)
		(end 110.418626 -215.112854)
		(width 0.0889)
		(layer "In11.Cu")
		(net "P5E_CPU1_PE1_RX_DP<8>")
	)
	(segment
		(start 34.794698 -13.549376)
		(end 34.678112 -13.199872)
		(width 0.14732)
		(layer "In11.Cu")
		(net "P5E_CPU1_PE1_RX_DP<8>")
	)
	(segment
		(start 110.56366 -213.063328)
		(end 110.56366 -213.04123)
		(width 0.0889)
		(layer "In11.Cu")
		(net "P5E_CPU1_PE1_RX_DP<8>")
	)
	(segment
		(start 33.62325 -9.576562)
		(end 33.441386 -9.330944)
		(width 0.14732)
		(layer "In11.Cu")
		(net "P5E_CPU1_PE1_RX_DP<8>")
	)
	(segment
		(start 110.135416 -216.260426)
		(end 110.135416 -216.235026)
		(width 0.0889)
		(layer "In11.Cu")
		(net "P5E_CPU1_PE1_RX_DP<8>")
	)
	(segment
		(start 110.426754 -218.372944)
		(end 110.421166 -218.369896)
		(width 0.0889)
		(layer "In11.Cu")
		(net "P5E_CPU1_PE1_RX_DP<8>")
	)
	(segment
		(start 31.916116 -7.049262)
		(end 31.916116 -5.257292)
		(width 0.14732)
		(layer "In11.Cu")
		(net "P5E_CPU1_PE1_RX_DP<8>")
	)
	(arc
		(start 111.075216 -219.506038)
		(mid 111.075164 -219.498671)
		(end 111.074962 -219.491306)
		(width 0.0889)
		(layer "In11.Cu")
		(net "P5E_CPU1_PE1_RX_DP<8>")
	)
	(arc
		(start 110.135416 -217.859864)
		(mid 110.215578 -217.587675)
		(end 110.417864 -217.388694)
		(width 0.0889)
		(layer "In11.Cu")
		(net "P5E_CPU1_PE1_RX_DP<8>")
	)
	(arc
		(start 111.35741 -219.995496)
		(mid 111.154587 -219.795265)
		(end 111.075216 -219.521532)
		(width 0.0889)
		(layer "In11.Cu")
		(net "P5E_CPU1_PE1_RX_DP<8>")
	)
	(arc
		(start 110.604808 -215.421972)
		(mid 110.553754 -215.247392)
		(end 110.4265 -215.117426)
		(width 0.0889)
		(layer "In11.Cu")
		(net "P5E_CPU1_PE1_RX_DP<8>")
	)
	(arc
		(start 110.417864 -217.388694)
		(mid 110.552797 -217.25534)
		(end 110.605062 -217.072972)
		(width 0.0889)
		(layer "In11.Cu")
		(net "P5E_CPU1_PE1_RX_DP<8>")
	)
	(arc
		(start 110.605062 -217.0557)
		(mid 110.552792 -216.873335)
		(end 110.417864 -216.739978)
		(width 0.0889)
		(layer "In11.Cu")
		(net "P5E_CPU1_PE1_RX_DP<8>")
	)
	(arc
		(start 110.41761 -215.112346)
		(mid 110.214305 -214.91148)
		(end 110.135162 -214.636858)
		(width 0.0889)
		(layer "In11.Cu")
		(net "P5E_CPU1_PE1_RX_DP<8>")
	)
	(arc
		(start 110.135416 -216.235026)
		(mid 110.214786 -215.961292)
		(end 110.41761 -215.761062)
		(width 0.0889)
		(layer "In11.Cu")
		(net "P5E_CPU1_PE1_RX_DP<8>")
	)
	(arc
		(start 110.417864 -218.367864)
		(mid 110.213529 -218.165259)
		(end 110.135416 -217.888312)
		(width 0.0889)
		(layer "In11.Cu")
		(net "P5E_CPU1_PE1_RX_DP<8>")
	)
	(arc
		(start 110.4265 -215.755982)
		(mid 110.557414 -215.619622)
		(end 110.605062 -215.436704)
		(width 0.0889)
		(layer "In11.Cu")
		(net "P5E_CPU1_PE1_RX_DP<8>")
	)
	(arc
		(start 110.605316 -218.692222)
		(mid 110.557637 -218.509322)
		(end 110.426754 -218.372944)
		(width 0.0889)
		(layer "In11.Cu")
		(net "P5E_CPU1_PE1_RX_DP<8>")
	)
	(arc
		(start 110.605062 -215.436704)
		(mid 110.60501 -215.429337)
		(end 110.604808 -215.421972)
		(width 0.0889)
		(layer "In11.Cu")
		(net "P5E_CPU1_PE1_RX_DP<8>")
	)
	(arc
		(start 111.544862 -220.319854)
		(mid 111.497183 -220.136954)
		(end 111.3663 -220.000576)
		(width 0.0889)
		(layer "In11.Cu")
		(net "P5E_CPU1_PE1_RX_DP<8>")
	)
	(arc
		(start 110.417864 -216.739978)
		(mid 110.213529 -216.537373)
		(end 110.135416 -216.260426)
		(width 0.0889)
		(layer "In11.Cu")
		(net "P5E_CPU1_PE1_RX_DP<8>")
	)
	(arc
		(start 110.887764 -219.18168)
		(mid 110.684704 -218.980871)
		(end 110.60557 -218.706446)
		(width 0.0889)
		(layer "In11.Cu")
		(net "P5E_CPU1_PE1_RX_DP<8>")
	)
	(arc
		(start 111.074962 -219.491306)
		(mid 111.023908 -219.316726)
		(end 110.896654 -219.18676)
		(width 0.0889)
		(layer "In11.Cu")
		(net "P5E_CPU1_PE1_RX_DP<8>")
	)
	(arc
		(start 111.404908 -220.6117)
		(mid 111.508053 -220.481675)
		(end 111.544862 -220.319854)
		(width 0.0889)
		(layer "In11.Cu")
		(net "P5E_CPU1_PE1_RX_DP<8>")
	)
	(segment
		(start 39.22903 -7.623556)
		(end 39.22903 -7.026656)
		(width 0.13208)
		(layer "F.Cu")
		(net "P5E_CPU1_PE1_RX_DP<7>")
	)
	(segment
		(start 39.057072 -7.795514)
		(end 39.22903 -7.623556)
		(width 0.13208)
		(layer "F.Cu")
		(net "P5E_CPU1_PE1_RX_DP<7>")
	)
	(segment
		(start 39.22903 -7.026656)
		(end 38.92677 -6.724396)
		(width 0.13208)
		(layer "F.Cu")
		(net "P5E_CPU1_PE1_RX_DP<7>")
	)
	(segment
		(start 112.579912 -221.134178)
		(end 112.580166 -221.133924)
		(width 0.13208)
		(layer "F.Cu")
		(net "P5E_CPU1_PE1_RX_DP<7>")
	)
	(segment
		(start 112.579912 -221.669864)
		(end 112.579912 -221.134178)
		(width 0.13208)
		(layer "F.Cu")
		(net "P5E_CPU1_PE1_RX_DP<7>")
	)
	(segment
		(start 39.057072 -8.320024)
		(end 39.057072 -7.795514)
		(width 0.13208)
		(layer "F.Cu")
		(net "P5E_CPU1_PE1_RX_DP<7>")
	)
	(segment
		(start 112.484662 -220.311218)
		(end 112.484662 -220.334078)
		(width 0.0889)
		(layer "In11.Cu")
		(net "P5E_CPU1_PE1_RX_DP<7>")
	)
	(segment
		(start 56.44007 -57.92978)
		(end 107.299506 -180.714396)
		(width 0.14732)
		(layer "In11.Cu")
		(net "P5E_CPU1_PE1_RX_DP<7>")
	)
	(segment
		(start 39.703502 -19.966178)
		(end 56.44007 -57.92978)
		(width 0.14732)
		(layer "In11.Cu")
		(net "P5E_CPU1_PE1_RX_DP<7>")
	)
	(segment
		(start 111.545116 -217.057732)
		(end 111.545116 -217.064336)
		(width 0.0889)
		(layer "In11.Cu")
		(net "P5E_CPU1_PE1_RX_DP<7>")
	)
	(segment
		(start 39.250112 -13.65758)
		(end 39.302436 -14.022578)
		(width 0.14732)
		(layer "In11.Cu")
		(net "P5E_CPU1_PE1_RX_DP<7>")
	)
	(segment
		(start 39.612316 -15.16126)
		(end 39.664386 -15.52575)
		(width 0.14732)
		(layer "In11.Cu")
		(net "P5E_CPU1_PE1_RX_DP<7>")
	)
	(segment
		(start 111.827564 -219.18168)
		(end 111.836454 -219.18676)
		(width 0.0889)
		(layer "In11.Cu")
		(net "P5E_CPU1_PE1_RX_DP<7>")
	)
	(segment
		(start 111.503206 -210.715606)
		(end 111.503206 -213.04123)
		(width 0.14732)
		(layer "In11.Cu")
		(net "P5E_CPU1_PE1_RX_DP<7>")
	)
	(segment
		(start 39.302436 -14.022578)
		(end 39.46652 -14.14526)
		(width 0.14732)
		(layer "In11.Cu")
		(net "P5E_CPU1_PE1_RX_DP<7>")
	)
	(segment
		(start 39.22141 -7.019036)
		(end 39.22141 -12.390628)
		(width 0.14732)
		(layer "In11.Cu")
		(net "P5E_CPU1_PE1_RX_DP<7>")
	)
	(segment
		(start 112.767364 -220.809566)
		(end 112.776254 -220.814646)
		(width 0.0889)
		(layer "In11.Cu")
		(net "P5E_CPU1_PE1_RX_DP<7>")
	)
	(segment
		(start 111.359442 -215.760046)
		(end 111.35741 -215.761062)
		(width 0.0889)
		(layer "In11.Cu")
		(net "P5E_CPU1_PE1_RX_DP<7>")
	)
	(segment
		(start 39.91864 -17.752568)
		(end 39.5478 -18.647918)
		(width 0.14732)
		(layer "In11.Cu")
		(net "P5E_CPU1_PE1_RX_DP<7>")
	)
	(segment
		(start 111.357664 -216.739978)
		(end 111.366554 -216.745058)
		(width 0.0889)
		(layer "In11.Cu")
		(net "P5E_CPU1_PE1_RX_DP<7>")
	)
	(segment
		(start 111.3663 -215.755982)
		(end 111.359442 -215.760046)
		(width 0.0889)
		(layer "In11.Cu")
		(net "P5E_CPU1_PE1_RX_DP<7>")
	)
	(segment
		(start 39.541704 -15.68958)
		(end 39.594028 -16.054324)
		(width 0.14732)
		(layer "In11.Cu")
		(net "P5E_CPU1_PE1_RX_DP<7>")
	)
	(segment
		(start 111.544862 -215.275414)
		(end 111.544862 -215.436704)
		(width 0.0889)
		(layer "In11.Cu")
		(net "P5E_CPU1_PE1_RX_DP<7>")
	)
	(segment
		(start 39.395908 -14.67358)
		(end 39.448232 -15.038578)
		(width 0.14732)
		(layer "In11.Cu")
		(net "P5E_CPU1_PE1_RX_DP<7>")
	)
	(segment
		(start 111.503206 -213.04123)
		(end 111.503206 -213.063328)
		(width 0.0889)
		(layer "In11.Cu")
		(net "P5E_CPU1_PE1_RX_DP<7>")
	)
	(segment
		(start 107.299506 -180.714396)
		(end 111.265716 -207.482186)
		(width 0.14732)
		(layer "In11.Cu")
		(net "P5E_CPU1_PE1_RX_DP<7>")
	)
	(segment
		(start 111.545116 -218.691968)
		(end 111.544862 -218.707462)
		(width 0.0889)
		(layer "In11.Cu")
		(net "P5E_CPU1_PE1_RX_DP<7>")
	)
	(segment
		(start 112.015016 -219.506038)
		(end 112.015016 -219.515944)
		(width 0.0889)
		(layer "In11.Cu")
		(net "P5E_CPU1_PE1_RX_DP<7>")
	)
	(segment
		(start 111.545116 -213.105238)
		(end 111.545116 -213.784688)
		(width 0.0889)
		(layer "In11.Cu")
		(net "P5E_CPU1_PE1_RX_DP<7>")
	)
	(segment
		(start 39.373048 -13.49375)
		(end 39.250112 -13.65758)
		(width 0.14732)
		(layer "In11.Cu")
		(net "P5E_CPU1_PE1_RX_DP<7>")
	)
	(segment
		(start 111.503206 -213.063328)
		(end 111.545116 -213.105238)
		(width 0.0889)
		(layer "In11.Cu")
		(net "P5E_CPU1_PE1_RX_DP<7>")
	)
	(segment
		(start 39.227506 -12.476734)
		(end 39.373048 -13.49375)
		(width 0.14732)
		(layer "In11.Cu")
		(net "P5E_CPU1_PE1_RX_DP<7>")
	)
	(segment
		(start 39.448232 -15.038578)
		(end 39.612316 -15.16126)
		(width 0.14732)
		(layer "In11.Cu")
		(net "P5E_CPU1_PE1_RX_DP<7>")
	)
	(segment
		(start 112.776254 -221.453202)
		(end 112.771174 -221.45625)
		(width 0.0889)
		(layer "In11.Cu")
		(net "P5E_CPU1_PE1_RX_DP<7>")
	)
	(segment
		(start 111.074962 -217.864182)
		(end 111.074962 -217.878406)
		(width 0.0889)
		(layer "In11.Cu")
		(net "P5E_CPU1_PE1_RX_DP<7>")
	)
	(segment
		(start 39.5478 -19.590258)
		(end 39.703502 -19.966178)
		(width 0.14732)
		(layer "In11.Cu")
		(net "P5E_CPU1_PE1_RX_DP<7>")
	)
	(segment
		(start 39.664386 -15.52575)
		(end 39.541704 -15.68958)
		(width 0.14732)
		(layer "In11.Cu")
		(net "P5E_CPU1_PE1_RX_DP<7>")
	)
	(segment
		(start 39.5478 -18.647918)
		(end 39.5478 -19.590258)
		(width 0.14732)
		(layer "In11.Cu")
		(net "P5E_CPU1_PE1_RX_DP<7>")
	)
	(segment
		(start 38.92677 -6.724396)
		(end 39.22141 -7.019036)
		(width 0.14732)
		(layer "In11.Cu")
		(net "P5E_CPU1_PE1_RX_DP<7>")
	)
	(segment
		(start 111.075216 -216.235026)
		(end 111.075216 -216.260426)
		(width 0.0889)
		(layer "In11.Cu")
		(net "P5E_CPU1_PE1_RX_DP<7>")
	)
	(segment
		(start 39.758112 -16.177006)
		(end 39.91864 -17.297654)
		(width 0.14732)
		(layer "In11.Cu")
		(net "P5E_CPU1_PE1_RX_DP<7>")
	)
	(segment
		(start 39.91864 -17.297654)
		(end 39.91864 -17.752568)
		(width 0.14732)
		(layer "In11.Cu")
		(net "P5E_CPU1_PE1_RX_DP<7>")
	)
	(segment
		(start 111.265716 -207.482186)
		(end 111.503206 -210.715606)
		(width 0.14732)
		(layer "In11.Cu")
		(net "P5E_CPU1_PE1_RX_DP<7>")
	)
	(segment
		(start 112.768888 -221.45752)
		(end 112.767364 -221.458282)
		(width 0.0889)
		(layer "In11.Cu")
		(net "P5E_CPU1_PE1_RX_DP<7>")
	)
	(segment
		(start 39.46652 -14.14526)
		(end 39.51859 -14.50975)
		(width 0.14732)
		(layer "In11.Cu")
		(net "P5E_CPU1_PE1_RX_DP<7>")
	)
	(segment
		(start 111.351568 -218.364308)
		(end 111.369094 -218.374468)
		(width 0.0889)
		(layer "In11.Cu")
		(net "P5E_CPU1_PE1_RX_DP<7>")
	)
	(segment
		(start 111.075216 -214.254588)
		(end 111.075216 -214.744808)
		(width 0.0889)
		(layer "In11.Cu")
		(net "P5E_CPU1_PE1_RX_DP<7>")
	)
	(segment
		(start 111.366554 -217.383614)
		(end 111.357664 -217.388694)
		(width 0.0889)
		(layer "In11.Cu")
		(net "P5E_CPU1_PE1_RX_DP<7>")
	)
	(segment
		(start 39.594028 -16.054324)
		(end 39.758112 -16.177006)
		(width 0.14732)
		(layer "In11.Cu")
		(net "P5E_CPU1_PE1_RX_DP<7>")
	)
	(segment
		(start 39.22141 -12.390628)
		(end 39.227506 -12.476734)
		(width 0.14732)
		(layer "In11.Cu")
		(net "P5E_CPU1_PE1_RX_DP<7>")
	)
	(segment
		(start 112.444784 -221.48292)
		(end 112.423702 -221.404942)
		(width 0.0889)
		(layer "In11.Cu")
		(net "P5E_CPU1_PE1_RX_DP<7>")
	)
	(segment
		(start 112.771174 -221.45625)
		(end 112.768888 -221.45752)
		(width 0.0889)
		(layer "In11.Cu")
		(net "P5E_CPU1_PE1_RX_DP<7>")
	)
	(segment
		(start 112.423702 -221.404942)
		(end 112.580166 -221.133924)
		(width 0.0889)
		(layer "In11.Cu")
		(net "P5E_CPU1_PE1_RX_DP<7>")
	)
	(segment
		(start 111.545116 -213.784688)
		(end 111.075216 -214.254588)
		(width 0.0889)
		(layer "In11.Cu")
		(net "P5E_CPU1_PE1_RX_DP<7>")
	)
	(segment
		(start 39.51859 -14.50975)
		(end 39.395908 -14.67358)
		(width 0.14732)
		(layer "In11.Cu")
		(net "P5E_CPU1_PE1_RX_DP<7>")
	)
	(arc
		(start 112.484662 -220.334078)
		(mid 112.563881 -220.608763)
		(end 112.767364 -220.809566)
		(width 0.0889)
		(layer "In11.Cu")
		(net "P5E_CPU1_PE1_RX_DP<7>")
	)
	(arc
		(start 112.015016 -219.515944)
		(mid 112.093127 -219.792893)
		(end 112.297464 -219.995496)
		(width 0.0889)
		(layer "In11.Cu")
		(net "P5E_CPU1_PE1_RX_DP<7>")
	)
	(arc
		(start 111.369094 -218.374468)
		(mid 111.498153 -218.510458)
		(end 111.545116 -218.691968)
		(width 0.0889)
		(layer "In11.Cu")
		(net "P5E_CPU1_PE1_RX_DP<7>")
	)
	(arc
		(start 111.544862 -215.436704)
		(mid 111.497183 -215.619604)
		(end 111.3663 -215.755982)
		(width 0.0889)
		(layer "In11.Cu")
		(net "P5E_CPU1_PE1_RX_DP<7>")
	)
	(arc
		(start 111.090202 -214.783416)
		(mid 111.200439 -214.952837)
		(end 111.360712 -215.076024)
		(width 0.0889)
		(layer "In11.Cu")
		(net "P5E_CPU1_PE1_RX_DP<7>")
	)
	(arc
		(start 111.074962 -217.878406)
		(mid 111.148953 -218.157972)
		(end 111.351568 -218.364308)
		(width 0.0889)
		(layer "In11.Cu")
		(net "P5E_CPU1_PE1_RX_DP<7>")
	)
	(arc
		(start 111.545116 -217.064336)
		(mid 111.497437 -217.247236)
		(end 111.366554 -217.383614)
		(width 0.0889)
		(layer "In11.Cu")
		(net "P5E_CPU1_PE1_RX_DP<7>")
	)
	(arc
		(start 111.075216 -216.260426)
		(mid 111.153327 -216.537375)
		(end 111.357664 -216.739978)
		(width 0.0889)
		(layer "In11.Cu")
		(net "P5E_CPU1_PE1_RX_DP<7>")
	)
	(arc
		(start 111.836454 -219.18676)
		(mid 111.967368 -219.32312)
		(end 112.015016 -219.506038)
		(width 0.0889)
		(layer "In11.Cu")
		(net "P5E_CPU1_PE1_RX_DP<7>")
	)
	(arc
		(start 111.544862 -218.707462)
		(mid 111.6244 -218.981407)
		(end 111.827564 -219.18168)
		(width 0.0889)
		(layer "In11.Cu")
		(net "P5E_CPU1_PE1_RX_DP<7>")
	)
	(arc
		(start 111.366554 -216.745058)
		(mid 111.495843 -216.878544)
		(end 111.545116 -217.057732)
		(width 0.0889)
		(layer "In11.Cu")
		(net "P5E_CPU1_PE1_RX_DP<7>")
	)
	(arc
		(start 112.767364 -221.458282)
		(mid 112.608876 -221.507215)
		(end 112.444784 -221.48292)
		(width 0.0889)
		(layer "In11.Cu")
		(net "P5E_CPU1_PE1_RX_DP<7>")
	)
	(arc
		(start 112.776254 -220.814646)
		(mid 112.954851 -221.133924)
		(end 112.776254 -221.453202)
		(width 0.0889)
		(layer "In11.Cu")
		(net "P5E_CPU1_PE1_RX_DP<7>")
	)
	(arc
		(start 111.075216 -214.744808)
		(mid 111.082378 -214.76424)
		(end 111.090202 -214.783416)
		(width 0.0889)
		(layer "In11.Cu")
		(net "P5E_CPU1_PE1_RX_DP<7>")
	)
	(arc
		(start 111.360712 -215.076024)
		(mid 111.469859 -215.159952)
		(end 111.544862 -215.275414)
		(width 0.0889)
		(layer "In11.Cu")
		(net "P5E_CPU1_PE1_RX_DP<7>")
	)
	(arc
		(start 111.35741 -215.761062)
		(mid 111.154587 -215.961293)
		(end 111.075216 -216.235026)
		(width 0.0889)
		(layer "In11.Cu")
		(net "P5E_CPU1_PE1_RX_DP<7>")
	)
	(arc
		(start 111.357664 -217.388694)
		(mid 111.154183 -217.589498)
		(end 111.074962 -217.864182)
		(width 0.0889)
		(layer "In11.Cu")
		(net "P5E_CPU1_PE1_RX_DP<7>")
	)
	(arc
		(start 112.297464 -219.995496)
		(mid 112.432397 -220.12885)
		(end 112.484662 -220.311218)
		(width 0.0889)
		(layer "In11.Cu")
		(net "P5E_CPU1_PE1_RX_DP<7>")
	)
	(segment
		(start 113.050066 -220.855794)
		(end 113.050066 -220.320108)
		(width 0.13208)
		(layer "F.Cu")
		(net "P5E_CPU1_PE1_RX_DP<6>")
	)
	(segment
		(start 40.856916 -7.786116)
		(end 41.03497 -7.608062)
		(width 0.13208)
		(layer "F.Cu")
		(net "P5E_CPU1_PE1_RX_DP<6>")
	)
	(segment
		(start 113.050066 -220.320108)
		(end 113.049812 -220.319854)
		(width 0.13208)
		(layer "F.Cu")
		(net "P5E_CPU1_PE1_RX_DP<6>")
	)
	(segment
		(start 40.856916 -8.320024)
		(end 40.856916 -7.786116)
		(width 0.13208)
		(layer "F.Cu")
		(net "P5E_CPU1_PE1_RX_DP<6>")
	)
	(segment
		(start 41.03497 -5.266182)
		(end 40.73144 -4.962652)
		(width 0.13208)
		(layer "F.Cu")
		(net "P5E_CPU1_PE1_RX_DP<6>")
	)
	(segment
		(start 41.03497 -7.608062)
		(end 41.03497 -5.266182)
		(width 0.13208)
		(layer "F.Cu")
		(net "P5E_CPU1_PE1_RX_DP<6>")
	)
	(segment
		(start 41.909238 -16.187674)
		(end 41.733978 -16.081248)
		(width 0.14732)
		(layer "In11.Cu")
		(net "P5E_CPU1_PE1_RX_DP<6>")
	)
	(segment
		(start 42.349928 -18.005044)
		(end 41.909238 -16.187674)
		(width 0.14732)
		(layer "In11.Cu")
		(net "P5E_CPU1_PE1_RX_DP<6>")
	)
	(segment
		(start 41.64711 -15.723108)
		(end 41.75379 -15.548102)
		(width 0.14732)
		(layer "In11.Cu")
		(net "P5E_CPU1_PE1_RX_DP<6>")
	)
	(segment
		(start 41.600628 -14.91615)
		(end 41.425368 -14.809724)
		(width 0.14732)
		(layer "In11.Cu")
		(net "P5E_CPU1_PE1_RX_DP<6>")
	)
	(segment
		(start 43.020234 -19.007836)
		(end 42.349928 -18.004536)
		(width 0.14732)
		(layer "In11.Cu")
		(net "P5E_CPU1_PE1_RX_DP<6>")
	)
	(segment
		(start 41.733978 -16.081248)
		(end 41.64711 -15.723108)
		(width 0.14732)
		(layer "In11.Cu")
		(net "P5E_CPU1_PE1_RX_DP<6>")
	)
	(segment
		(start 42.349928 -18.004536)
		(end 42.349928 -18.005044)
		(width 0.14732)
		(layer "In11.Cu")
		(net "P5E_CPU1_PE1_RX_DP<6>")
	)
	(segment
		(start 108.295186 -180.674518)
		(end 52.493672 -45.959522)
		(width 0.14732)
		(layer "In11.Cu")
		(net "P5E_CPU1_PE1_RX_DP<6>")
	)
	(segment
		(start 112.443006 -213.04123)
		(end 112.443006 -210.66506)
		(width 0.14732)
		(layer "In11.Cu")
		(net "P5E_CPU1_PE1_RX_DP<6>")
	)
	(segment
		(start 113.049812 -220.319854)
		(end 113.206276 -220.590872)
		(width 0.0889)
		(layer "In11.Cu")
		(net "P5E_CPU1_PE1_RX_DP<6>")
	)
	(segment
		(start 113.206276 -220.590872)
		(end 113.284508 -220.6117)
		(width 0.0889)
		(layer "In11.Cu")
		(net "P5E_CPU1_PE1_RX_DP<6>")
	)
	(segment
		(start 112.014762 -214.183976)
		(end 112.484916 -213.713822)
		(width 0.0889)
		(layer "In11.Cu")
		(net "P5E_CPU1_PE1_RX_DP<6>")
	)
	(segment
		(start 112.297464 -216.739978)
		(end 112.291368 -216.736422)
		(width 0.0889)
		(layer "In11.Cu")
		(net "P5E_CPU1_PE1_RX_DP<6>")
	)
	(segment
		(start 112.484916 -213.713822)
		(end 112.484916 -213.105238)
		(width 0.0889)
		(layer "In11.Cu")
		(net "P5E_CPU1_PE1_RX_DP<6>")
	)
	(segment
		(start 112.443006 -213.063328)
		(end 112.443006 -213.04123)
		(width 0.0889)
		(layer "In11.Cu")
		(net "P5E_CPU1_PE1_RX_DP<6>")
	)
	(segment
		(start 112.171734 -206.971138)
		(end 108.295186 -180.674518)
		(width 0.14732)
		(layer "In11.Cu")
		(net "P5E_CPU1_PE1_RX_DP<6>")
	)
	(segment
		(start 112.776254 -217.559128)
		(end 112.767364 -217.554048)
		(width 0.0889)
		(layer "In11.Cu")
		(net "P5E_CPU1_PE1_RX_DP<6>")
	)
	(segment
		(start 112.761268 -218.20632)
		(end 112.767364 -218.202764)
		(width 0.0889)
		(layer "In11.Cu")
		(net "P5E_CPU1_PE1_RX_DP<6>")
	)
	(segment
		(start 41.02608 -12.548362)
		(end 41.02608 -5.257292)
		(width 0.14732)
		(layer "In11.Cu")
		(net "P5E_CPU1_PE1_RX_DP<6>")
	)
	(segment
		(start 112.014762 -216.25052)
		(end 112.014762 -216.240614)
		(width 0.0889)
		(layer "In11.Cu")
		(net "P5E_CPU1_PE1_RX_DP<6>")
	)
	(segment
		(start 112.954816 -219.521532)
		(end 112.954816 -219.506038)
		(width 0.0889)
		(layer "In11.Cu")
		(net "P5E_CPU1_PE1_RX_DP<6>")
	)
	(segment
		(start 41.44518 -14.276578)
		(end 41.02608 -12.548362)
		(width 0.14732)
		(layer "In11.Cu")
		(net "P5E_CPU1_PE1_RX_DP<6>")
	)
	(segment
		(start 112.767364 -219.18168)
		(end 112.761268 -219.178124)
		(width 0.0889)
		(layer "In11.Cu")
		(net "P5E_CPU1_PE1_RX_DP<6>")
	)
	(segment
		(start 113.238026 -219.996004)
		(end 113.23701 -219.995496)
		(width 0.0889)
		(layer "In11.Cu")
		(net "P5E_CPU1_PE1_RX_DP<6>")
	)
	(segment
		(start 41.338754 -14.451584)
		(end 41.44518 -14.276578)
		(width 0.14732)
		(layer "In11.Cu")
		(net "P5E_CPU1_PE1_RX_DP<6>")
	)
	(segment
		(start 112.014762 -214.745062)
		(end 112.014762 -214.183976)
		(width 0.0889)
		(layer "In11.Cu")
		(net "P5E_CPU1_PE1_RX_DP<6>")
	)
	(segment
		(start 41.425368 -14.809724)
		(end 41.338754 -14.451584)
		(width 0.14732)
		(layer "In11.Cu")
		(net "P5E_CPU1_PE1_RX_DP<6>")
	)
	(segment
		(start 52.493672 -45.959522)
		(end 43.020234 -19.007836)
		(width 0.14732)
		(layer "In11.Cu")
		(net "P5E_CPU1_PE1_RX_DP<6>")
	)
	(segment
		(start 112.484662 -217.07856)
		(end 112.484662 -217.0557)
		(width 0.0889)
		(layer "In11.Cu")
		(net "P5E_CPU1_PE1_RX_DP<6>")
	)
	(segment
		(start 113.2459 -220.000576)
		(end 113.238026 -219.996004)
		(width 0.0889)
		(layer "In11.Cu")
		(net "P5E_CPU1_PE1_RX_DP<6>")
	)
	(segment
		(start 41.02608 -5.257292)
		(end 40.73144 -4.962652)
		(width 0.14732)
		(layer "In11.Cu")
		(net "P5E_CPU1_PE1_RX_DP<6>")
	)
	(segment
		(start 112.29721 -215.761062)
		(end 112.3061 -215.755982)
		(width 0.0889)
		(layer "In11.Cu")
		(net "P5E_CPU1_PE1_RX_DP<6>")
	)
	(segment
		(start 112.443006 -210.66506)
		(end 112.171734 -206.971138)
		(width 0.14732)
		(layer "In11.Cu")
		(net "P5E_CPU1_PE1_RX_DP<6>")
	)
	(segment
		(start 112.484662 -215.436704)
		(end 112.484662 -215.275922)
		(width 0.0889)
		(layer "In11.Cu")
		(net "P5E_CPU1_PE1_RX_DP<6>")
	)
	(segment
		(start 112.767364 -218.202764)
		(end 112.776254 -218.197684)
		(width 0.0889)
		(layer "In11.Cu")
		(net "P5E_CPU1_PE1_RX_DP<6>")
	)
	(segment
		(start 112.776254 -219.18676)
		(end 112.767364 -219.18168)
		(width 0.0889)
		(layer "In11.Cu")
		(net "P5E_CPU1_PE1_RX_DP<6>")
	)
	(segment
		(start 41.75379 -15.548102)
		(end 41.600628 -14.91615)
		(width 0.14732)
		(layer "In11.Cu")
		(net "P5E_CPU1_PE1_RX_DP<6>")
	)
	(segment
		(start 112.484916 -213.105238)
		(end 112.443006 -213.063328)
		(width 0.0889)
		(layer "In11.Cu")
		(net "P5E_CPU1_PE1_RX_DP<6>")
	)
	(arc
		(start 112.954816 -219.506038)
		(mid 112.907137 -219.323138)
		(end 112.776254 -219.18676)
		(width 0.0889)
		(layer "In11.Cu")
		(net "P5E_CPU1_PE1_RX_DP<6>")
	)
	(arc
		(start 112.767364 -217.554048)
		(mid 112.563883 -217.353244)
		(end 112.484662 -217.07856)
		(width 0.0889)
		(layer "In11.Cu")
		(net "P5E_CPU1_PE1_RX_DP<6>")
	)
	(arc
		(start 112.776254 -218.197684)
		(mid 112.954851 -217.878406)
		(end 112.776254 -217.559128)
		(width 0.0889)
		(layer "In11.Cu")
		(net "P5E_CPU1_PE1_RX_DP<6>")
	)
	(arc
		(start 113.424462 -220.319854)
		(mid 113.376783 -220.136954)
		(end 113.2459 -220.000576)
		(width 0.0889)
		(layer "In11.Cu")
		(net "P5E_CPU1_PE1_RX_DP<6>")
	)
	(arc
		(start 113.284508 -220.6117)
		(mid 113.387653 -220.481675)
		(end 113.424462 -220.319854)
		(width 0.0889)
		(layer "In11.Cu")
		(net "P5E_CPU1_PE1_RX_DP<6>")
	)
	(arc
		(start 112.3061 -215.755982)
		(mid 112.437014 -215.619622)
		(end 112.484662 -215.436704)
		(width 0.0889)
		(layer "In11.Cu")
		(net "P5E_CPU1_PE1_RX_DP<6>")
	)
	(arc
		(start 112.484662 -215.275922)
		(mid 112.409591 -215.16018)
		(end 112.300258 -215.076024)
		(width 0.0889)
		(layer "In11.Cu")
		(net "P5E_CPU1_PE1_RX_DP<6>")
	)
	(arc
		(start 112.761268 -219.178124)
		(mid 112.484694 -218.692222)
		(end 112.761268 -218.20632)
		(width 0.0889)
		(layer "In11.Cu")
		(net "P5E_CPU1_PE1_RX_DP<6>")
	)
	(arc
		(start 112.014762 -216.240614)
		(mid 112.092873 -215.963665)
		(end 112.29721 -215.761062)
		(width 0.0889)
		(layer "In11.Cu")
		(net "P5E_CPU1_PE1_RX_DP<6>")
	)
	(arc
		(start 113.23701 -219.995496)
		(mid 113.034187 -219.795265)
		(end 112.954816 -219.521532)
		(width 0.0889)
		(layer "In11.Cu")
		(net "P5E_CPU1_PE1_RX_DP<6>")
	)
	(arc
		(start 112.484662 -217.0557)
		(mid 112.432392 -216.873335)
		(end 112.297464 -216.739978)
		(width 0.0889)
		(layer "In11.Cu")
		(net "P5E_CPU1_PE1_RX_DP<6>")
	)
	(arc
		(start 112.300258 -215.076024)
		(mid 112.126244 -214.937517)
		(end 112.014762 -214.745062)
		(width 0.0889)
		(layer "In11.Cu")
		(net "P5E_CPU1_PE1_RX_DP<6>")
	)
	(arc
		(start 112.291368 -216.736422)
		(mid 112.088781 -216.530071)
		(end 112.014762 -216.25052)
		(width 0.0889)
		(layer "In11.Cu")
		(net "P5E_CPU1_PE1_RX_DP<6>")
	)
	(segment
		(start 42.657014 -7.795514)
		(end 42.828972 -7.623556)
		(width 0.13208)
		(layer "F.Cu")
		(net "P5E_CPU1_PE1_RX_DP<5>")
	)
	(segment
		(start 42.828972 -7.623556)
		(end 42.828972 -7.026656)
		(width 0.13208)
		(layer "F.Cu")
		(net "P5E_CPU1_PE1_RX_DP<5>")
	)
	(segment
		(start 42.828972 -7.026656)
		(end 42.526712 -6.724396)
		(width 0.13208)
		(layer "F.Cu")
		(net "P5E_CPU1_PE1_RX_DP<5>")
	)
	(segment
		(start 42.657014 -8.320024)
		(end 42.657014 -7.795514)
		(width 0.13208)
		(layer "F.Cu")
		(net "P5E_CPU1_PE1_RX_DP<5>")
	)
	(segment
		(start 114.459766 -221.133924)
		(end 114.459766 -221.669864)
		(width 0.13208)
		(layer "F.Cu")
		(net "P5E_CPU1_PE1_RX_DP<5>")
	)
	(segment
		(start 42.821352 -12.230608)
		(end 42.821352 -7.019036)
		(width 0.14732)
		(layer "In11.Cu")
		(net "P5E_CPU1_PE1_RX_DP<5>")
	)
	(segment
		(start 113.2459 -216.745058)
		(end 113.23701 -216.739978)
		(width 0.0889)
		(layer "In11.Cu")
		(net "P5E_CPU1_PE1_RX_DP<5>")
	)
	(segment
		(start 114.459766 -221.133924)
		(end 114.303302 -221.404942)
		(width 0.0889)
		(layer "In11.Cu")
		(net "P5E_CPU1_PE1_RX_DP<5>")
	)
	(segment
		(start 43.713146 -14.03477)
		(end 43.515788 -13.723366)
		(width 0.14732)
		(layer "In11.Cu")
		(net "P5E_CPU1_PE1_RX_DP<5>")
	)
	(segment
		(start 113.425224 -213.886034)
		(end 113.425224 -213.105238)
		(width 0.0889)
		(layer "In11.Cu")
		(net "P5E_CPU1_PE1_RX_DP<5>")
	)
	(segment
		(start 113.703354 -219.179394)
		(end 113.694972 -219.174568)
		(width 0.0889)
		(layer "In11.Cu")
		(net "P5E_CPU1_PE1_RX_DP<5>")
	)
	(segment
		(start 45.073824 -16.1798)
		(end 44.876466 -15.868396)
		(width 0.14732)
		(layer "In11.Cu")
		(net "P5E_CPU1_PE1_RX_DP<5>")
	)
	(segment
		(start 45.12564 -19.46783)
		(end 45.12564 -19.01698)
		(width 0.14732)
		(layer "In11.Cu")
		(net "P5E_CPU1_PE1_RX_DP<5>")
	)
	(segment
		(start 114.646964 -221.458282)
		(end 114.655854 -221.453202)
		(width 0.0889)
		(layer "In11.Cu")
		(net "P5E_CPU1_PE1_RX_DP<5>")
	)
	(segment
		(start 113.383314 -213.063328)
		(end 113.383314 -213.04123)
		(width 0.0889)
		(layer "In11.Cu")
		(net "P5E_CPU1_PE1_RX_DP<5>")
	)
	(segment
		(start 44.876466 -15.868396)
		(end 44.92117 -15.668498)
		(width 0.14732)
		(layer "In11.Cu")
		(net "P5E_CPU1_PE1_RX_DP<5>")
	)
	(segment
		(start 113.23701 -215.761062)
		(end 113.2459 -215.755982)
		(width 0.0889)
		(layer "In11.Cu")
		(net "P5E_CPU1_PE1_RX_DP<5>")
	)
	(segment
		(start 45.273976 -16.224504)
		(end 45.073824 -16.1798)
		(width 0.14732)
		(layer "In11.Cu")
		(net "P5E_CPU1_PE1_RX_DP<5>")
	)
	(segment
		(start 113.425224 -213.105238)
		(end 113.383314 -213.063328)
		(width 0.0889)
		(layer "In11.Cu")
		(net "P5E_CPU1_PE1_RX_DP<5>")
	)
	(segment
		(start 45.847 -17.383252)
		(end 45.70984 -16.911828)
		(width 0.14732)
		(layer "In11.Cu")
		(net "P5E_CPU1_PE1_RX_DP<5>")
	)
	(segment
		(start 114.303302 -221.404942)
		(end 114.324384 -221.48292)
		(width 0.0889)
		(layer "In11.Cu")
		(net "P5E_CPU1_PE1_RX_DP<5>")
	)
	(segment
		(start 113.23701 -216.739978)
		(end 113.230914 -216.736422)
		(width 0.0889)
		(layer "In11.Cu")
		(net "P5E_CPU1_PE1_RX_DP<5>")
	)
	(segment
		(start 109.972602 -183.803036)
		(end 109.29493 -180.65369)
		(width 0.14732)
		(layer "In11.Cu")
		(net "P5E_CPU1_PE1_RX_DP<5>")
	)
	(segment
		(start 113.707164 -218.202764)
		(end 113.716054 -218.197684)
		(width 0.0889)
		(layer "In11.Cu")
		(net "P5E_CPU1_PE1_RX_DP<5>")
	)
	(segment
		(start 45.259244 -18.576544)
		(end 45.847 -17.696942)
		(width 0.14732)
		(layer "In11.Cu")
		(net "P5E_CPU1_PE1_RX_DP<5>")
	)
	(segment
		(start 44.29887 -14.95806)
		(end 44.101766 -14.64691)
		(width 0.14732)
		(layer "In11.Cu")
		(net "P5E_CPU1_PE1_RX_DP<5>")
	)
	(segment
		(start 113.703354 -218.20505)
		(end 113.707164 -218.202764)
		(width 0.0889)
		(layer "In11.Cu")
		(net "P5E_CPU1_PE1_RX_DP<5>")
	)
	(segment
		(start 44.101766 -14.64691)
		(end 44.14647 -14.447012)
		(width 0.14732)
		(layer "In11.Cu")
		(net "P5E_CPU1_PE1_RX_DP<5>")
	)
	(segment
		(start 43.560492 -13.523722)
		(end 42.88917 -12.46505)
		(width 0.14732)
		(layer "In11.Cu")
		(net "P5E_CPU1_PE1_RX_DP<5>")
	)
	(segment
		(start 113.424462 -217.071956)
		(end 113.424462 -217.064336)
		(width 0.0889)
		(layer "In11.Cu")
		(net "P5E_CPU1_PE1_RX_DP<5>")
	)
	(segment
		(start 43.913298 -14.079474)
		(end 43.713146 -14.03477)
		(width 0.14732)
		(layer "In11.Cu")
		(net "P5E_CPU1_PE1_RX_DP<5>")
	)
	(segment
		(start 44.92117 -15.668498)
		(end 44.499022 -15.002764)
		(width 0.14732)
		(layer "In11.Cu")
		(net "P5E_CPU1_PE1_RX_DP<5>")
	)
	(segment
		(start 113.894616 -219.515944)
		(end 113.894616 -219.506038)
		(width 0.0889)
		(layer "In11.Cu")
		(net "P5E_CPU1_PE1_RX_DP<5>")
	)
	(segment
		(start 114.655854 -220.814646)
		(end 114.646964 -220.809566)
		(width 0.0889)
		(layer "In11.Cu")
		(net "P5E_CPU1_PE1_RX_DP<5>")
	)
	(segment
		(start 45.621956 -20.659852)
		(end 45.12564 -19.46783)
		(width 0.14732)
		(layer "In11.Cu")
		(net "P5E_CPU1_PE1_RX_DP<5>")
	)
	(segment
		(start 113.694972 -218.209876)
		(end 113.703354 -218.20505)
		(width 0.0889)
		(layer "In11.Cu")
		(net "P5E_CPU1_PE1_RX_DP<5>")
	)
	(segment
		(start 113.707164 -219.18168)
		(end 113.703354 -219.179394)
		(width 0.0889)
		(layer "In11.Cu")
		(net "P5E_CPU1_PE1_RX_DP<5>")
	)
	(segment
		(start 113.894362 -214.355172)
		(end 113.425224 -213.886034)
		(width 0.0889)
		(layer "In11.Cu")
		(net "P5E_CPU1_PE1_RX_DP<5>")
	)
	(segment
		(start 109.29493 -180.65369)
		(end 53.391816 -45.69079)
		(width 0.14732)
		(layer "In11.Cu")
		(net "P5E_CPU1_PE1_RX_DP<5>")
	)
	(segment
		(start 44.14647 -14.447012)
		(end 43.913298 -14.079474)
		(width 0.14732)
		(layer "In11.Cu")
		(net "P5E_CPU1_PE1_RX_DP<5>")
	)
	(segment
		(start 113.881916 -214.733886)
		(end 113.894362 -214.57666)
		(width 0.0889)
		(layer "In11.Cu")
		(net "P5E_CPU1_PE1_RX_DP<5>")
	)
	(segment
		(start 114.364262 -220.334078)
		(end 114.364262 -220.311218)
		(width 0.0889)
		(layer "In11.Cu")
		(net "P5E_CPU1_PE1_RX_DP<5>")
	)
	(segment
		(start 42.821352 -7.019036)
		(end 42.526712 -6.724396)
		(width 0.14732)
		(layer "In11.Cu")
		(net "P5E_CPU1_PE1_RX_DP<5>")
	)
	(segment
		(start 113.383314 -213.04123)
		(end 113.383314 -210.255612)
		(width 0.14732)
		(layer "In11.Cu")
		(net "P5E_CPU1_PE1_RX_DP<5>")
	)
	(segment
		(start 45.12564 -19.01698)
		(end 45.259244 -18.576544)
		(width 0.14732)
		(layer "In11.Cu")
		(net "P5E_CPU1_PE1_RX_DP<5>")
	)
	(segment
		(start 43.515788 -13.723366)
		(end 43.560492 -13.523722)
		(width 0.14732)
		(layer "In11.Cu")
		(net "P5E_CPU1_PE1_RX_DP<5>")
	)
	(segment
		(start 113.424462 -215.436704)
		(end 113.424462 -215.23833)
		(width 0.0889)
		(layer "In11.Cu")
		(net "P5E_CPU1_PE1_RX_DP<5>")
	)
	(segment
		(start 42.88917 -12.46505)
		(end 42.821352 -12.230608)
		(width 0.14732)
		(layer "In11.Cu")
		(net "P5E_CPU1_PE1_RX_DP<5>")
	)
	(segment
		(start 44.499022 -15.002764)
		(end 44.29887 -14.95806)
		(width 0.14732)
		(layer "In11.Cu")
		(net "P5E_CPU1_PE1_RX_DP<5>")
	)
	(segment
		(start 113.716054 -217.559128)
		(end 113.707164 -217.554048)
		(width 0.0889)
		(layer "In11.Cu")
		(net "P5E_CPU1_PE1_RX_DP<5>")
	)
	(segment
		(start 113.098326 -206.159608)
		(end 109.972602 -183.803036)
		(width 0.14732)
		(layer "In11.Cu")
		(net "P5E_CPU1_PE1_RX_DP<5>")
	)
	(segment
		(start 45.847 -17.696942)
		(end 45.847 -17.383252)
		(width 0.14732)
		(layer "In11.Cu")
		(net "P5E_CPU1_PE1_RX_DP<5>")
	)
	(segment
		(start 113.383314 -210.255612)
		(end 113.098326 -206.159608)
		(width 0.14732)
		(layer "In11.Cu")
		(net "P5E_CPU1_PE1_RX_DP<5>")
	)
	(segment
		(start 113.230914 -215.764618)
		(end 113.23701 -215.761062)
		(width 0.0889)
		(layer "In11.Cu")
		(net "P5E_CPU1_PE1_RX_DP<5>")
	)
	(segment
		(start 45.70984 -16.911828)
		(end 45.273976 -16.224504)
		(width 0.14732)
		(layer "In11.Cu")
		(net "P5E_CPU1_PE1_RX_DP<5>")
	)
	(segment
		(start 53.391816 -45.69079)
		(end 45.621956 -20.659852)
		(width 0.14732)
		(layer "In11.Cu")
		(net "P5E_CPU1_PE1_RX_DP<5>")
	)
	(segment
		(start 113.716054 -219.18676)
		(end 113.707164 -219.18168)
		(width 0.0889)
		(layer "In11.Cu")
		(net "P5E_CPU1_PE1_RX_DP<5>")
	)
	(segment
		(start 113.894362 -214.57666)
		(end 113.894362 -214.355172)
		(width 0.0889)
		(layer "In11.Cu")
		(net "P5E_CPU1_PE1_RX_DP<5>")
	)
	(arc
		(start 113.424462 -217.064336)
		(mid 113.376783 -216.881436)
		(end 113.2459 -216.745058)
		(width 0.0889)
		(layer "In11.Cu")
		(net "P5E_CPU1_PE1_RX_DP<5>")
	)
	(arc
		(start 113.709958 -214.907114)
		(mid 113.809216 -214.833676)
		(end 113.881916 -214.733886)
		(width 0.0889)
		(layer "In11.Cu")
		(net "P5E_CPU1_PE1_RX_DP<5>")
	)
	(arc
		(start 113.894616 -219.506038)
		(mid 113.846937 -219.323138)
		(end 113.716054 -219.18676)
		(width 0.0889)
		(layer "In11.Cu")
		(net "P5E_CPU1_PE1_RX_DP<5>")
	)
	(arc
		(start 114.364262 -220.311218)
		(mid 114.311992 -220.128853)
		(end 114.177064 -219.995496)
		(width 0.0889)
		(layer "In11.Cu")
		(net "P5E_CPU1_PE1_RX_DP<5>")
	)
	(arc
		(start 114.655854 -221.453202)
		(mid 114.785143 -221.319716)
		(end 114.834416 -221.140528)
		(width 0.0889)
		(layer "In11.Cu")
		(net "P5E_CPU1_PE1_RX_DP<5>")
	)
	(arc
		(start 113.424462 -215.23833)
		(mid 113.535882 -215.045711)
		(end 113.709958 -214.907114)
		(width 0.0889)
		(layer "In11.Cu")
		(net "P5E_CPU1_PE1_RX_DP<5>")
	)
	(arc
		(start 114.834416 -221.124526)
		(mid 114.78452 -220.946879)
		(end 114.655854 -220.814646)
		(width 0.0889)
		(layer "In11.Cu")
		(net "P5E_CPU1_PE1_RX_DP<5>")
	)
	(arc
		(start 113.694972 -219.174568)
		(mid 113.424516 -218.692222)
		(end 113.694972 -218.209876)
		(width 0.0889)
		(layer "In11.Cu")
		(net "P5E_CPU1_PE1_RX_DP<5>")
	)
	(arc
		(start 113.894616 -217.88501)
		(mid 113.894606 -217.87561)
		(end 113.894362 -217.866214)
		(width 0.0889)
		(layer "In11.Cu")
		(net "P5E_CPU1_PE1_RX_DP<5>")
	)
	(arc
		(start 113.716054 -218.197684)
		(mid 113.845343 -218.064198)
		(end 113.894616 -217.88501)
		(width 0.0889)
		(layer "In11.Cu")
		(net "P5E_CPU1_PE1_RX_DP<5>")
	)
	(arc
		(start 113.707164 -217.554048)
		(mid 113.502092 -217.350369)
		(end 113.424462 -217.071956)
		(width 0.0889)
		(layer "In11.Cu")
		(net "P5E_CPU1_PE1_RX_DP<5>")
	)
	(arc
		(start 113.2459 -215.755982)
		(mid 113.376814 -215.619622)
		(end 113.424462 -215.436704)
		(width 0.0889)
		(layer "In11.Cu")
		(net "P5E_CPU1_PE1_RX_DP<5>")
	)
	(arc
		(start 114.177064 -219.995496)
		(mid 113.972729 -219.792891)
		(end 113.894616 -219.515944)
		(width 0.0889)
		(layer "In11.Cu")
		(net "P5E_CPU1_PE1_RX_DP<5>")
	)
	(arc
		(start 113.894362 -217.866214)
		(mid 113.843869 -217.690236)
		(end 113.716054 -217.559128)
		(width 0.0889)
		(layer "In11.Cu")
		(net "P5E_CPU1_PE1_RX_DP<5>")
	)
	(arc
		(start 113.230914 -216.736422)
		(mid 112.954588 -216.25052)
		(end 113.230914 -215.764618)
		(width 0.0889)
		(layer "In11.Cu")
		(net "P5E_CPU1_PE1_RX_DP<5>")
	)
	(arc
		(start 114.324384 -221.48292)
		(mid 114.48848 -221.507267)
		(end 114.646964 -221.458282)
		(width 0.0889)
		(layer "In11.Cu")
		(net "P5E_CPU1_PE1_RX_DP<5>")
	)
	(arc
		(start 114.834416 -221.140528)
		(mid 114.834499 -221.132527)
		(end 114.834416 -221.124526)
		(width 0.0889)
		(layer "In11.Cu")
		(net "P5E_CPU1_PE1_RX_DP<5>")
	)
	(arc
		(start 114.646964 -220.809566)
		(mid 114.443483 -220.608762)
		(end 114.364262 -220.334078)
		(width 0.0889)
		(layer "In11.Cu")
		(net "P5E_CPU1_PE1_RX_DP<5>")
	)
	(segment
		(start 114.929666 -220.320108)
		(end 114.929412 -220.319854)
		(width 0.13208)
		(layer "F.Cu")
		(net "P5E_CPU1_PE1_RX_DP<4>")
	)
	(segment
		(start 44.457112 -8.320024)
		(end 44.457112 -7.786116)
		(width 0.13208)
		(layer "F.Cu")
		(net "P5E_CPU1_PE1_RX_DP<4>")
	)
	(segment
		(start 44.457112 -7.786116)
		(end 44.632626 -7.610602)
		(width 0.13208)
		(layer "F.Cu")
		(net "P5E_CPU1_PE1_RX_DP<4>")
	)
	(segment
		(start 44.632626 -7.610602)
		(end 44.632626 -5.263896)
		(width 0.13208)
		(layer "F.Cu")
		(net "P5E_CPU1_PE1_RX_DP<4>")
	)
	(segment
		(start 44.632626 -5.263896)
		(end 44.331382 -4.962652)
		(width 0.13208)
		(layer "F.Cu")
		(net "P5E_CPU1_PE1_RX_DP<4>")
	)
	(segment
		(start 114.929666 -220.855794)
		(end 114.929666 -220.320108)
		(width 0.13208)
		(layer "F.Cu")
		(net "P5E_CPU1_PE1_RX_DP<4>")
	)
	(segment
		(start 114.646456 -214.946992)
		(end 114.655346 -214.941912)
		(width 0.0889)
		(layer "In11.Cu")
		(net "P5E_CPU1_PE1_RX_DP<4>")
	)
	(segment
		(start 114.649758 -214.261954)
		(end 114.650012 -214.261954)
		(width 0.0889)
		(layer "In11.Cu")
		(net "P5E_CPU1_PE1_RX_DP<4>")
	)
	(segment
		(start 46.959774 -16.353282)
		(end 46.759876 -16.307562)
		(width 0.14732)
		(layer "In11.Cu")
		(net "P5E_CPU1_PE1_RX_DP<4>")
	)
	(segment
		(start 113.894616 -216.260426)
		(end 113.894616 -216.235026)
		(width 0.0889)
		(layer "In11.Cu")
		(net "P5E_CPU1_PE1_RX_DP<4>")
	)
	(segment
		(start 114.364516 -213.929468)
		(end 114.36477 -213.929214)
		(width 0.0889)
		(layer "In11.Cu")
		(net "P5E_CPU1_PE1_RX_DP<4>")
	)
	(segment
		(start 54.26583 -45.353732)
		(end 48.682402 -19.171666)
		(width 0.14732)
		(layer "In11.Cu")
		(net "P5E_CPU1_PE1_RX_DP<4>")
	)
	(segment
		(start 114.36477 -213.105238)
		(end 114.32286 -213.063328)
		(width 0.0889)
		(layer "In11.Cu")
		(net "P5E_CPU1_PE1_RX_DP<4>")
	)
	(segment
		(start 114.364262 -217.07856)
		(end 114.364262 -217.0557)
		(width 0.0889)
		(layer "In11.Cu")
		(net "P5E_CPU1_PE1_RX_DP<4>")
	)
	(segment
		(start 114.655854 -217.559128)
		(end 114.646964 -217.554048)
		(width 0.0889)
		(layer "In11.Cu")
		(net "P5E_CPU1_PE1_RX_DP<4>")
	)
	(segment
		(start 114.36477 -213.929214)
		(end 114.36477 -213.105238)
		(width 0.0889)
		(layer "In11.Cu")
		(net "P5E_CPU1_PE1_RX_DP<4>")
	)
	(segment
		(start 114.834416 -219.521532)
		(end 114.834416 -219.506038)
		(width 0.0889)
		(layer "In11.Cu")
		(net "P5E_CPU1_PE1_RX_DP<4>")
	)
	(segment
		(start 48.682402 -19.171666)
		(end 48.53432 -18.814796)
		(width 0.14732)
		(layer "In11.Cu")
		(net "P5E_CPU1_PE1_RX_DP<4>")
	)
	(segment
		(start 44.626022 -5.257292)
		(end 44.331382 -4.962652)
		(width 0.14732)
		(layer "In11.Cu")
		(net "P5E_CPU1_PE1_RX_DP<4>")
	)
	(segment
		(start 114.32286 -213.063328)
		(end 114.32286 -213.04123)
		(width 0.0889)
		(layer "In11.Cu")
		(net "P5E_CPU1_PE1_RX_DP<4>")
	)
	(segment
		(start 46.610016 -15.795752)
		(end 45.93844 -14.725396)
		(width 0.14732)
		(layer "In11.Cu")
		(net "P5E_CPU1_PE1_RX_DP<4>")
	)
	(segment
		(start 46.564296 -15.995396)
		(end 46.610016 -15.795752)
		(width 0.14732)
		(layer "In11.Cu")
		(net "P5E_CPU1_PE1_RX_DP<4>")
	)
	(segment
		(start 115.1255 -220.000576)
		(end 115.117626 -219.996004)
		(width 0.0889)
		(layer "In11.Cu")
		(net "P5E_CPU1_PE1_RX_DP<4>")
	)
	(segment
		(start 115.085876 -220.590872)
		(end 115.164108 -220.6117)
		(width 0.0889)
		(layer "In11.Cu")
		(net "P5E_CPU1_PE1_RX_DP<4>")
	)
	(segment
		(start 115.117626 -219.996004)
		(end 115.11661 -219.995496)
		(width 0.0889)
		(layer "In11.Cu")
		(net "P5E_CPU1_PE1_RX_DP<4>")
	)
	(segment
		(start 114.929412 -220.319854)
		(end 115.085876 -220.590872)
		(width 0.0889)
		(layer "In11.Cu")
		(net "P5E_CPU1_PE1_RX_DP<4>")
	)
	(segment
		(start 110.370874 -180.804566)
		(end 54.26583 -45.353732)
		(width 0.14732)
		(layer "In11.Cu")
		(net "P5E_CPU1_PE1_RX_DP<4>")
	)
	(segment
		(start 114.646964 -218.202764)
		(end 114.648488 -218.202002)
		(width 0.0889)
		(layer "In11.Cu")
		(net "P5E_CPU1_PE1_RX_DP<4>")
	)
	(segment
		(start 114.046254 -206.15275)
		(end 110.903258 -183.673242)
		(width 0.14732)
		(layer "In11.Cu")
		(net "P5E_CPU1_PE1_RX_DP<4>")
	)
	(segment
		(start 114.364262 -215.436704)
		(end 114.364262 -215.414606)
		(width 0.0889)
		(layer "In11.Cu")
		(net "P5E_CPU1_PE1_RX_DP<4>")
	)
	(segment
		(start 44.626022 -12.633198)
		(end 44.626022 -5.257292)
		(width 0.14732)
		(layer "In11.Cu")
		(net "P5E_CPU1_PE1_RX_DP<4>")
	)
	(segment
		(start 114.17681 -215.761062)
		(end 114.1857 -215.755982)
		(width 0.0889)
		(layer "In11.Cu")
		(net "P5E_CPU1_PE1_RX_DP<4>")
	)
	(segment
		(start 45.738796 -14.679676)
		(end 45.542962 -14.36751)
		(width 0.14732)
		(layer "In11.Cu")
		(net "P5E_CPU1_PE1_RX_DP<4>")
	)
	(segment
		(start 114.364516 -218.702128)
		(end 114.364516 -218.682316)
		(width 0.0889)
		(layer "In11.Cu")
		(net "P5E_CPU1_PE1_RX_DP<4>")
	)
	(segment
		(start 48.53432 -18.814796)
		(end 48.534574 -18.814796)
		(width 0.14732)
		(layer "In11.Cu")
		(net "P5E_CPU1_PE1_RX_DP<4>")
	)
	(segment
		(start 114.647726 -219.182188)
		(end 114.646964 -219.18168)
		(width 0.0889)
		(layer "In11.Cu")
		(net "P5E_CPU1_PE1_RX_DP<4>")
	)
	(segment
		(start 45.93844 -14.725396)
		(end 45.738796 -14.679676)
		(width 0.14732)
		(layer "In11.Cu")
		(net "P5E_CPU1_PE1_RX_DP<4>")
	)
	(segment
		(start 114.655854 -219.18676)
		(end 114.647726 -219.182188)
		(width 0.0889)
		(layer "In11.Cu")
		(net "P5E_CPU1_PE1_RX_DP<4>")
	)
	(segment
		(start 48.038766 -18.07337)
		(end 46.959774 -16.353282)
		(width 0.14732)
		(layer "In11.Cu")
		(net "P5E_CPU1_PE1_RX_DP<4>")
	)
	(segment
		(start 48.534574 -18.814796)
		(end 48.038766 -18.07337)
		(width 0.14732)
		(layer "In11.Cu")
		(net "P5E_CPU1_PE1_RX_DP<4>")
	)
	(segment
		(start 110.380526 -180.85562)
		(end 110.380272 -180.854604)
		(width 0.14732)
		(layer "In11.Cu")
		(net "P5E_CPU1_PE1_RX_DP<4>")
	)
	(segment
		(start 45.542962 -14.36751)
		(end 45.588682 -14.167866)
		(width 0.14732)
		(layer "In11.Cu")
		(net "P5E_CPU1_PE1_RX_DP<4>")
	)
	(segment
		(start 45.588682 -14.167866)
		(end 44.626022 -12.633198)
		(width 0.14732)
		(layer "In11.Cu")
		(net "P5E_CPU1_PE1_RX_DP<4>")
	)
	(segment
		(start 110.903258 -183.673242)
		(end 110.413546 -181.033674)
		(width 0.14732)
		(layer "In11.Cu")
		(net "P5E_CPU1_PE1_RX_DP<4>")
	)
	(segment
		(start 46.759876 -16.307562)
		(end 46.564296 -15.995396)
		(width 0.14732)
		(layer "In11.Cu")
		(net "P5E_CPU1_PE1_RX_DP<4>")
	)
	(segment
		(start 114.833908 -214.622634)
		(end 114.833908 -214.461344)
		(width 0.0889)
		(layer "In11.Cu")
		(net "P5E_CPU1_PE1_RX_DP<4>")
	)
	(segment
		(start 114.32286 -210.130136)
		(end 114.046254 -206.15275)
		(width 0.14732)
		(layer "In11.Cu")
		(net "P5E_CPU1_PE1_RX_DP<4>")
	)
	(segment
		(start 110.413546 -181.033674)
		(end 110.380526 -180.85562)
		(width 0.14732)
		(layer "In11.Cu")
		(net "P5E_CPU1_PE1_RX_DP<4>")
	)
	(segment
		(start 110.380272 -180.854604)
		(end 110.370874 -180.804566)
		(width 0.14732)
		(layer "In11.Cu")
		(net "P5E_CPU1_PE1_RX_DP<4>")
	)
	(segment
		(start 114.32286 -213.04123)
		(end 114.32286 -210.130136)
		(width 0.14732)
		(layer "In11.Cu")
		(net "P5E_CPU1_PE1_RX_DP<4>")
	)
	(segment
		(start 114.648488 -218.202002)
		(end 114.655854 -218.197684)
		(width 0.0889)
		(layer "In11.Cu")
		(net "P5E_CPU1_PE1_RX_DP<4>")
	)
	(arc
		(start 114.646964 -219.18168)
		(mid 114.442629 -218.979075)
		(end 114.364516 -218.702128)
		(width 0.0889)
		(layer "In11.Cu")
		(net "P5E_CPU1_PE1_RX_DP<4>")
	)
	(arc
		(start 114.364516 -218.682316)
		(mid 114.442627 -218.405367)
		(end 114.646964 -218.202764)
		(width 0.0889)
		(layer "In11.Cu")
		(net "P5E_CPU1_PE1_RX_DP<4>")
	)
	(arc
		(start 114.650012 -214.261954)
		(mid 114.490178 -214.138955)
		(end 114.380264 -213.969854)
		(width 0.0889)
		(layer "In11.Cu")
		(net "P5E_CPU1_PE1_RX_DP<4>")
	)
	(arc
		(start 115.11661 -219.995496)
		(mid 114.913787 -219.795265)
		(end 114.834416 -219.521532)
		(width 0.0889)
		(layer "In11.Cu")
		(net "P5E_CPU1_PE1_RX_DP<4>")
	)
	(arc
		(start 114.380264 -213.969854)
		(mid 114.372024 -213.949804)
		(end 114.364516 -213.929468)
		(width 0.0889)
		(layer "In11.Cu")
		(net "P5E_CPU1_PE1_RX_DP<4>")
	)
	(arc
		(start 114.364262 -217.0557)
		(mid 114.311992 -216.873335)
		(end 114.177064 -216.739978)
		(width 0.0889)
		(layer "In11.Cu")
		(net "P5E_CPU1_PE1_RX_DP<4>")
	)
	(arc
		(start 114.655854 -218.197684)
		(mid 114.785143 -218.064198)
		(end 114.834416 -217.88501)
		(width 0.0889)
		(layer "In11.Cu")
		(net "P5E_CPU1_PE1_RX_DP<4>")
	)
	(arc
		(start 115.164108 -220.6117)
		(mid 115.267253 -220.481675)
		(end 115.304062 -220.319854)
		(width 0.0889)
		(layer "In11.Cu")
		(net "P5E_CPU1_PE1_RX_DP<4>")
	)
	(arc
		(start 114.655346 -214.941912)
		(mid 114.78626 -214.805552)
		(end 114.833908 -214.622634)
		(width 0.0889)
		(layer "In11.Cu")
		(net "P5E_CPU1_PE1_RX_DP<4>")
	)
	(arc
		(start 113.894616 -216.235026)
		(mid 113.973986 -215.961292)
		(end 114.17681 -215.761062)
		(width 0.0889)
		(layer "In11.Cu")
		(net "P5E_CPU1_PE1_RX_DP<4>")
	)
	(arc
		(start 114.834416 -217.869008)
		(mid 114.78452 -217.691361)
		(end 114.655854 -217.559128)
		(width 0.0889)
		(layer "In11.Cu")
		(net "P5E_CPU1_PE1_RX_DP<4>")
	)
	(arc
		(start 115.304062 -220.319854)
		(mid 115.256383 -220.136954)
		(end 115.1255 -220.000576)
		(width 0.0889)
		(layer "In11.Cu")
		(net "P5E_CPU1_PE1_RX_DP<4>")
	)
	(arc
		(start 114.177064 -216.739978)
		(mid 113.972729 -216.537373)
		(end 113.894616 -216.260426)
		(width 0.0889)
		(layer "In11.Cu")
		(net "P5E_CPU1_PE1_RX_DP<4>")
	)
	(arc
		(start 114.834416 -219.506038)
		(mid 114.786737 -219.323138)
		(end 114.655854 -219.18676)
		(width 0.0889)
		(layer "In11.Cu")
		(net "P5E_CPU1_PE1_RX_DP<4>")
	)
	(arc
		(start 114.833908 -214.461344)
		(mid 114.758903 -214.345885)
		(end 114.649758 -214.261954)
		(width 0.0889)
		(layer "In11.Cu")
		(net "P5E_CPU1_PE1_RX_DP<4>")
	)
	(arc
		(start 114.364262 -215.414606)
		(mid 114.445173 -215.144478)
		(end 114.646456 -214.946992)
		(width 0.0889)
		(layer "In11.Cu")
		(net "P5E_CPU1_PE1_RX_DP<4>")
	)
	(arc
		(start 114.646964 -217.554048)
		(mid 114.443483 -217.353244)
		(end 114.364262 -217.07856)
		(width 0.0889)
		(layer "In11.Cu")
		(net "P5E_CPU1_PE1_RX_DP<4>")
	)
	(arc
		(start 114.834416 -217.88501)
		(mid 114.834499 -217.877009)
		(end 114.834416 -217.869008)
		(width 0.0889)
		(layer "In11.Cu")
		(net "P5E_CPU1_PE1_RX_DP<4>")
	)
	(arc
		(start 114.1857 -215.755982)
		(mid 114.316614 -215.619622)
		(end 114.364262 -215.436704)
		(width 0.0889)
		(layer "In11.Cu")
		(net "P5E_CPU1_PE1_RX_DP<4>")
	)
	(segment
		(start 50.267108 -7.795514)
		(end 50.439066 -7.623556)
		(width 0.13208)
		(layer "F.Cu")
		(net "P5E_CPU1_PE1_RX_DP<3>")
	)
	(segment
		(start 116.339112 -221.669864)
		(end 116.339112 -221.134178)
		(width 0.13208)
		(layer "F.Cu")
		(net "P5E_CPU1_PE1_RX_DP<3>")
	)
	(segment
		(start 50.439066 -7.623556)
		(end 50.439066 -7.026656)
		(width 0.13208)
		(layer "F.Cu")
		(net "P5E_CPU1_PE1_RX_DP<3>")
	)
	(segment
		(start 50.439066 -7.026656)
		(end 50.136806 -6.724396)
		(width 0.13208)
		(layer "F.Cu")
		(net "P5E_CPU1_PE1_RX_DP<3>")
	)
	(segment
		(start 50.267108 -8.320024)
		(end 50.267108 -7.795514)
		(width 0.13208)
		(layer "F.Cu")
		(net "P5E_CPU1_PE1_RX_DP<3>")
	)
	(segment
		(start 116.339112 -221.134178)
		(end 116.339366 -221.133924)
		(width 0.13208)
		(layer "F.Cu")
		(net "P5E_CPU1_PE1_RX_DP<3>")
	)
	(segment
		(start 51.48326 -17.264888)
		(end 51.24069 -16.138652)
		(width 0.14732)
		(layer "In11.Cu")
		(net "P5E_CPU1_PE1_RX_DP<3>")
	)
	(segment
		(start 115.773708 -214.631016)
		(end 115.773708 -214.460328)
		(width 0.0889)
		(layer "In11.Cu")
		(net "P5E_CPU1_PE1_RX_DP<3>")
	)
	(segment
		(start 114.963194 -205.923388)
		(end 111.83493 -183.549036)
		(width 0.14732)
		(layer "In11.Cu")
		(net "P5E_CPU1_PE1_RX_DP<3>")
	)
	(segment
		(start 115.586764 -218.202764)
		(end 115.588288 -218.202002)
		(width 0.0889)
		(layer "In11.Cu")
		(net "P5E_CPU1_PE1_RX_DP<3>")
	)
	(segment
		(start 115.773708 -214.460328)
		(end 115.761516 -214.435182)
		(width 0.0889)
		(layer "In11.Cu")
		(net "P5E_CPU1_PE1_RX_DP<3>")
	)
	(segment
		(start 115.30457 -213.93023)
		(end 115.30457 -213.105238)
		(width 0.0889)
		(layer "In11.Cu")
		(net "P5E_CPU1_PE1_RX_DP<3>")
	)
	(segment
		(start 116.526564 -221.458282)
		(end 116.528088 -221.45752)
		(width 0.0889)
		(layer "In11.Cu")
		(net "P5E_CPU1_PE1_RX_DP<3>")
	)
	(segment
		(start 50.518314 -13.472922)
		(end 50.629312 -13.300964)
		(width 0.14732)
		(layer "In11.Cu")
		(net "P5E_CPU1_PE1_RX_DP<3>")
	)
	(segment
		(start 115.58397 -218.204542)
		(end 115.586002 -218.203272)
		(width 0.0889)
		(layer "In11.Cu")
		(net "P5E_CPU1_PE1_RX_DP<3>")
	)
	(segment
		(start 114.834162 -216.260426)
		(end 114.834162 -216.240614)
		(width 0.0889)
		(layer "In11.Cu")
		(net "P5E_CPU1_PE1_RX_DP<3>")
	)
	(segment
		(start 50.879502 -14.462252)
		(end 50.767996 -13.944346)
		(width 0.14732)
		(layer "In11.Cu")
		(net "P5E_CPU1_PE1_RX_DP<3>")
	)
	(segment
		(start 111.274352 -180.532532)
		(end 55.229252 -45.22978)
		(width 0.14732)
		(layer "In11.Cu")
		(net "P5E_CPU1_PE1_RX_DP<3>")
	)
	(segment
		(start 116.243862 -220.334078)
		(end 116.243862 -220.311218)
		(width 0.0889)
		(layer "In11.Cu")
		(net "P5E_CPU1_PE1_RX_DP<3>")
	)
	(segment
		(start 50.767996 -13.944346)
		(end 50.595784 -13.833348)
		(width 0.14732)
		(layer "In11.Cu")
		(net "P5E_CPU1_PE1_RX_DP<3>")
	)
	(segment
		(start 115.304062 -215.436704)
		(end 115.304062 -215.414606)
		(width 0.0889)
		(layer "In11.Cu")
		(net "P5E_CPU1_PE1_RX_DP<3>")
	)
	(segment
		(start 116.528088 -221.45752)
		(end 116.535454 -221.453202)
		(width 0.0889)
		(layer "In11.Cu")
		(net "P5E_CPU1_PE1_RX_DP<3>")
	)
	(segment
		(start 115.30457 -213.105238)
		(end 115.26266 -213.063328)
		(width 0.0889)
		(layer "In11.Cu")
		(net "P5E_CPU1_PE1_RX_DP<3>")
	)
	(segment
		(start 116.182902 -221.404942)
		(end 116.203984 -221.48292)
		(width 0.0889)
		(layer "In11.Cu")
		(net "P5E_CPU1_PE1_RX_DP<3>")
	)
	(segment
		(start 50.768504 -14.63421)
		(end 50.879502 -14.462252)
		(width 0.14732)
		(layer "In11.Cu")
		(net "P5E_CPU1_PE1_RX_DP<3>")
	)
	(segment
		(start 55.229252 -45.22978)
		(end 50.7111 -19.534378)
		(width 0.14732)
		(layer "In11.Cu")
		(net "P5E_CPU1_PE1_RX_DP<3>")
	)
	(segment
		(start 115.26266 -210.228942)
		(end 114.963194 -205.923388)
		(width 0.14732)
		(layer "In11.Cu")
		(net "P5E_CPU1_PE1_RX_DP<3>")
	)
	(segment
		(start 50.7111 -19.062192)
		(end 50.819304 -18.705322)
		(width 0.14732)
		(layer "In11.Cu")
		(net "P5E_CPU1_PE1_RX_DP<3>")
	)
	(segment
		(start 111.83493 -183.549036)
		(end 111.274352 -180.532532)
		(width 0.14732)
		(layer "In11.Cu")
		(net "P5E_CPU1_PE1_RX_DP<3>")
	)
	(segment
		(start 51.102006 -15.49527)
		(end 51.018186 -15.105634)
		(width 0.14732)
		(layer "In11.Cu")
		(net "P5E_CPU1_PE1_RX_DP<3>")
	)
	(segment
		(start 50.819304 -18.705322)
		(end 51.366928 -17.885918)
		(width 0.14732)
		(layer "In11.Cu")
		(net "P5E_CPU1_PE1_RX_DP<3>")
	)
	(segment
		(start 50.431446 -7.019036)
		(end 50.136806 -6.724396)
		(width 0.14732)
		(layer "In11.Cu")
		(net "P5E_CPU1_PE1_RX_DP<3>")
	)
	(segment
		(start 51.24069 -16.138652)
		(end 51.068478 -16.027654)
		(width 0.14732)
		(layer "In11.Cu")
		(net "P5E_CPU1_PE1_RX_DP<3>")
	)
	(segment
		(start 50.845974 -14.994382)
		(end 50.768504 -14.63421)
		(width 0.14732)
		(layer "In11.Cu")
		(net "P5E_CPU1_PE1_RX_DP<3>")
	)
	(segment
		(start 115.595654 -217.559128)
		(end 115.587526 -217.554556)
		(width 0.0889)
		(layer "In11.Cu")
		(net "P5E_CPU1_PE1_RX_DP<3>")
	)
	(segment
		(start 115.588288 -219.182442)
		(end 115.586764 -219.18168)
		(width 0.0889)
		(layer "In11.Cu")
		(net "P5E_CPU1_PE1_RX_DP<3>")
	)
	(segment
		(start 50.7111 -19.534378)
		(end 50.7111 -19.062192)
		(width 0.14732)
		(layer "In11.Cu")
		(net "P5E_CPU1_PE1_RX_DP<3>")
	)
	(segment
		(start 50.431446 -12.380722)
		(end 50.431446 -7.019036)
		(width 0.14732)
		(layer "In11.Cu")
		(net "P5E_CPU1_PE1_RX_DP<3>")
	)
	(segment
		(start 115.586256 -214.946992)
		(end 115.595146 -214.941912)
		(width 0.0889)
		(layer "In11.Cu")
		(net "P5E_CPU1_PE1_RX_DP<3>")
	)
	(segment
		(start 115.587526 -217.554556)
		(end 115.586764 -217.554048)
		(width 0.0889)
		(layer "In11.Cu")
		(net "P5E_CPU1_PE1_RX_DP<3>")
	)
	(segment
		(start 50.629312 -13.300964)
		(end 50.431446 -12.380722)
		(width 0.14732)
		(layer "In11.Cu")
		(net "P5E_CPU1_PE1_RX_DP<3>")
	)
	(segment
		(start 115.580668 -218.20632)
		(end 115.58397 -218.204542)
		(width 0.0889)
		(layer "In11.Cu")
		(net "P5E_CPU1_PE1_RX_DP<3>")
	)
	(segment
		(start 115.586002 -218.203272)
		(end 115.586764 -218.202764)
		(width 0.0889)
		(layer "In11.Cu")
		(net "P5E_CPU1_PE1_RX_DP<3>")
	)
	(segment
		(start 115.1255 -216.745058)
		(end 115.11661 -216.739978)
		(width 0.0889)
		(layer "In11.Cu")
		(net "P5E_CPU1_PE1_RX_DP<3>")
	)
	(segment
		(start 51.018186 -15.105634)
		(end 50.845974 -14.994382)
		(width 0.14732)
		(layer "In11.Cu")
		(net "P5E_CPU1_PE1_RX_DP<3>")
	)
	(segment
		(start 116.339366 -221.133924)
		(end 116.182902 -221.404942)
		(width 0.0889)
		(layer "In11.Cu")
		(net "P5E_CPU1_PE1_RX_DP<3>")
	)
	(segment
		(start 50.595784 -13.833348)
		(end 50.518314 -13.472922)
		(width 0.14732)
		(layer "In11.Cu")
		(net "P5E_CPU1_PE1_RX_DP<3>")
	)
	(segment
		(start 51.48326 -17.502124)
		(end 51.48326 -17.264888)
		(width 0.14732)
		(layer "In11.Cu")
		(net "P5E_CPU1_PE1_RX_DP<3>")
	)
	(segment
		(start 116.535454 -220.814646)
		(end 116.526564 -220.809566)
		(width 0.0889)
		(layer "In11.Cu")
		(net "P5E_CPU1_PE1_RX_DP<3>")
	)
	(segment
		(start 115.595654 -219.18676)
		(end 115.588288 -219.182442)
		(width 0.0889)
		(layer "In11.Cu")
		(net "P5E_CPU1_PE1_RX_DP<3>")
	)
	(segment
		(start 50.991008 -15.667228)
		(end 51.102006 -15.49527)
		(width 0.14732)
		(layer "In11.Cu")
		(net "P5E_CPU1_PE1_RX_DP<3>")
	)
	(segment
		(start 115.11661 -215.761062)
		(end 115.1255 -215.755982)
		(width 0.0889)
		(layer "In11.Cu")
		(net "P5E_CPU1_PE1_RX_DP<3>")
	)
	(segment
		(start 51.068478 -16.027654)
		(end 50.991008 -15.667228)
		(width 0.14732)
		(layer "In11.Cu")
		(net "P5E_CPU1_PE1_RX_DP<3>")
	)
	(segment
		(start 115.774216 -219.515944)
		(end 115.774216 -219.506038)
		(width 0.0889)
		(layer "In11.Cu")
		(net "P5E_CPU1_PE1_RX_DP<3>")
	)
	(segment
		(start 115.304062 -217.071956)
		(end 115.304062 -217.064336)
		(width 0.0889)
		(layer "In11.Cu")
		(net "P5E_CPU1_PE1_RX_DP<3>")
	)
	(segment
		(start 115.588288 -218.202002)
		(end 115.595654 -218.197684)
		(width 0.0889)
		(layer "In11.Cu")
		(net "P5E_CPU1_PE1_RX_DP<3>")
	)
	(segment
		(start 115.26266 -213.063328)
		(end 115.26266 -213.04123)
		(width 0.0889)
		(layer "In11.Cu")
		(net "P5E_CPU1_PE1_RX_DP<3>")
	)
	(segment
		(start 51.366928 -17.885918)
		(end 51.48326 -17.502124)
		(width 0.14732)
		(layer "In11.Cu")
		(net "P5E_CPU1_PE1_RX_DP<3>")
	)
	(segment
		(start 115.773454 -214.637366)
		(end 115.773708 -214.631016)
		(width 0.0889)
		(layer "In11.Cu")
		(net "P5E_CPU1_PE1_RX_DP<3>")
	)
	(segment
		(start 115.304316 -213.930484)
		(end 115.30457 -213.93023)
		(width 0.0889)
		(layer "In11.Cu")
		(net "P5E_CPU1_PE1_RX_DP<3>")
	)
	(segment
		(start 115.586764 -219.18168)
		(end 115.580668 -219.178124)
		(width 0.0889)
		(layer "In11.Cu")
		(net "P5E_CPU1_PE1_RX_DP<3>")
	)
	(segment
		(start 115.26266 -213.04123)
		(end 115.26266 -210.228942)
		(width 0.14732)
		(layer "In11.Cu")
		(net "P5E_CPU1_PE1_RX_DP<3>")
	)
	(arc
		(start 114.834162 -216.240614)
		(mid 114.912273 -215.963665)
		(end 115.11661 -215.761062)
		(width 0.0889)
		(layer "In11.Cu")
		(net "P5E_CPU1_PE1_RX_DP<3>")
	)
	(arc
		(start 116.526564 -220.809566)
		(mid 116.323083 -220.608762)
		(end 116.243862 -220.334078)
		(width 0.0889)
		(layer "In11.Cu")
		(net "P5E_CPU1_PE1_RX_DP<3>")
	)
	(arc
		(start 115.11661 -216.739978)
		(mid 114.912275 -216.537373)
		(end 114.834162 -216.260426)
		(width 0.0889)
		(layer "In11.Cu")
		(net "P5E_CPU1_PE1_RX_DP<3>")
	)
	(arc
		(start 115.595654 -218.197684)
		(mid 115.77413 -217.878406)
		(end 115.595654 -217.559128)
		(width 0.0889)
		(layer "In11.Cu")
		(net "P5E_CPU1_PE1_RX_DP<3>")
	)
	(arc
		(start 116.535454 -221.453202)
		(mid 116.714051 -221.133924)
		(end 116.535454 -220.814646)
		(width 0.0889)
		(layer "In11.Cu")
		(net "P5E_CPU1_PE1_RX_DP<3>")
	)
	(arc
		(start 115.595146 -214.941912)
		(mid 115.7224 -214.811946)
		(end 115.773454 -214.637366)
		(width 0.0889)
		(layer "In11.Cu")
		(net "P5E_CPU1_PE1_RX_DP<3>")
	)
	(arc
		(start 116.203984 -221.48292)
		(mid 116.36808 -221.507267)
		(end 116.526564 -221.458282)
		(width 0.0889)
		(layer "In11.Cu")
		(net "P5E_CPU1_PE1_RX_DP<3>")
	)
	(arc
		(start 115.589558 -214.261954)
		(mid 115.429486 -214.138774)
		(end 115.319556 -213.969346)
		(width 0.0889)
		(layer "In11.Cu")
		(net "P5E_CPU1_PE1_RX_DP<3>")
	)
	(arc
		(start 115.580668 -219.178124)
		(mid 115.304218 -218.692222)
		(end 115.580668 -218.20632)
		(width 0.0889)
		(layer "In11.Cu")
		(net "P5E_CPU1_PE1_RX_DP<3>")
	)
	(arc
		(start 116.056664 -219.995496)
		(mid 115.852329 -219.792891)
		(end 115.774216 -219.515944)
		(width 0.0889)
		(layer "In11.Cu")
		(net "P5E_CPU1_PE1_RX_DP<3>")
	)
	(arc
		(start 115.319556 -213.969346)
		(mid 115.311593 -213.950049)
		(end 115.304316 -213.930484)
		(width 0.0889)
		(layer "In11.Cu")
		(net "P5E_CPU1_PE1_RX_DP<3>")
	)
	(arc
		(start 116.243862 -220.311218)
		(mid 116.191592 -220.128853)
		(end 116.056664 -219.995496)
		(width 0.0889)
		(layer "In11.Cu")
		(net "P5E_CPU1_PE1_RX_DP<3>")
	)
	(arc
		(start 115.586764 -217.554048)
		(mid 115.381692 -217.350369)
		(end 115.304062 -217.071956)
		(width 0.0889)
		(layer "In11.Cu")
		(net "P5E_CPU1_PE1_RX_DP<3>")
	)
	(arc
		(start 115.774216 -219.506038)
		(mid 115.726537 -219.323138)
		(end 115.595654 -219.18676)
		(width 0.0889)
		(layer "In11.Cu")
		(net "P5E_CPU1_PE1_RX_DP<3>")
	)
	(arc
		(start 115.1255 -215.755982)
		(mid 115.256414 -215.619622)
		(end 115.304062 -215.436704)
		(width 0.0889)
		(layer "In11.Cu")
		(net "P5E_CPU1_PE1_RX_DP<3>")
	)
	(arc
		(start 115.304062 -215.414606)
		(mid 115.384973 -215.144478)
		(end 115.586256 -214.946992)
		(width 0.0889)
		(layer "In11.Cu")
		(net "P5E_CPU1_PE1_RX_DP<3>")
	)
	(arc
		(start 115.761516 -214.435182)
		(mid 115.68878 -214.335428)
		(end 115.589558 -214.261954)
		(width 0.0889)
		(layer "In11.Cu")
		(net "P5E_CPU1_PE1_RX_DP<3>")
	)
	(arc
		(start 115.304062 -217.064336)
		(mid 115.256383 -216.881436)
		(end 115.1255 -216.745058)
		(width 0.0889)
		(layer "In11.Cu")
		(net "P5E_CPU1_PE1_RX_DP<3>")
	)
	(segment
		(start 116.809266 -220.855794)
		(end 116.809266 -220.320108)
		(width 0.13208)
		(layer "F.Cu")
		(net "P5E_CPU1_PE1_RX_DP<2>")
	)
	(segment
		(start 52.24272 -5.263896)
		(end 51.941476 -4.962652)
		(width 0.13208)
		(layer "F.Cu")
		(net "P5E_CPU1_PE1_RX_DP<2>")
	)
	(segment
		(start 52.24272 -7.610348)
		(end 52.24272 -5.263896)
		(width 0.13208)
		(layer "F.Cu")
		(net "P5E_CPU1_PE1_RX_DP<2>")
	)
	(segment
		(start 116.809266 -220.320108)
		(end 116.809012 -220.319854)
		(width 0.13208)
		(layer "F.Cu")
		(net "P5E_CPU1_PE1_RX_DP<2>")
	)
	(segment
		(start 52.066952 -7.786116)
		(end 52.24272 -7.610348)
		(width 0.13208)
		(layer "F.Cu")
		(net "P5E_CPU1_PE1_RX_DP<2>")
	)
	(segment
		(start 52.066952 -8.320024)
		(end 52.066952 -7.786116)
		(width 0.13208)
		(layer "F.Cu")
		(net "P5E_CPU1_PE1_RX_DP<2>")
	)
	(segment
		(start 116.965476 -220.590872)
		(end 117.043708 -220.6117)
		(width 0.0889)
		(layer "In11.Cu")
		(net "P5E_CPU1_PE1_RX_DP<2>")
	)
	(segment
		(start 52.71008 -13.8049)
		(end 52.236116 -12.12342)
		(width 0.14732)
		(layer "In11.Cu")
		(net "P5E_CPU1_PE1_RX_DP<2>")
	)
	(segment
		(start 52.610004 -13.983462)
		(end 52.71008 -13.8049)
		(width 0.14732)
		(layer "In11.Cu")
		(net "P5E_CPU1_PE1_RX_DP<2>")
	)
	(segment
		(start 116.526564 -218.202764)
		(end 116.528088 -218.202002)
		(width 0.0889)
		(layer "In11.Cu")
		(net "P5E_CPU1_PE1_RX_DP<2>")
	)
	(segment
		(start 53.167534 -15.425928)
		(end 52.988718 -15.326106)
		(width 0.14732)
		(layer "In11.Cu")
		(net "P5E_CPU1_PE1_RX_DP<2>")
	)
	(segment
		(start 54.252876 -18.807684)
		(end 53.770784 -18.325592)
		(width 0.14732)
		(layer "In11.Cu")
		(net "P5E_CPU1_PE1_RX_DP<2>")
	)
	(segment
		(start 116.526056 -214.946992)
		(end 116.534946 -214.941912)
		(width 0.0889)
		(layer "In11.Cu")
		(net "P5E_CPU1_PE1_RX_DP<2>")
	)
	(segment
		(start 116.535454 -217.559128)
		(end 116.526564 -217.554048)
		(width 0.0889)
		(layer "In11.Cu")
		(net "P5E_CPU1_PE1_RX_DP<2>")
	)
	(segment
		(start 54.252876 -19.01952)
		(end 54.252876 -18.807684)
		(width 0.14732)
		(layer "In11.Cu")
		(net "P5E_CPU1_PE1_RX_DP<2>")
	)
	(segment
		(start 116.528088 -218.202002)
		(end 116.535454 -218.197684)
		(width 0.0889)
		(layer "In11.Cu")
		(net "P5E_CPU1_PE1_RX_DP<2>")
	)
	(segment
		(start 52.988718 -14.792706)
		(end 52.98821 -14.790674)
		(width 0.14732)
		(layer "In11.Cu")
		(net "P5E_CPU1_PE1_RX_DP<2>")
	)
	(segment
		(start 116.809012 -220.319854)
		(end 116.965476 -220.590872)
		(width 0.0889)
		(layer "In11.Cu")
		(net "P5E_CPU1_PE1_RX_DP<2>")
	)
	(segment
		(start 116.05641 -215.761062)
		(end 116.0653 -215.755982)
		(width 0.0889)
		(layer "In11.Cu")
		(net "P5E_CPU1_PE1_RX_DP<2>")
	)
	(segment
		(start 116.24437 -213.929214)
		(end 116.24437 -213.105238)
		(width 0.0889)
		(layer "In11.Cu")
		(net "P5E_CPU1_PE1_RX_DP<2>")
	)
	(segment
		(start 116.243862 -217.07856)
		(end 116.243862 -217.0557)
		(width 0.0889)
		(layer "In11.Cu")
		(net "P5E_CPU1_PE1_RX_DP<2>")
	)
	(segment
		(start 116.525802 -218.203272)
		(end 116.526564 -218.202764)
		(width 0.0889)
		(layer "In11.Cu")
		(net "P5E_CPU1_PE1_RX_DP<2>")
	)
	(segment
		(start 112.765078 -183.413654)
		(end 112.240314 -180.396642)
		(width 0.14732)
		(layer "In11.Cu")
		(net "P5E_CPU1_PE1_RX_DP<2>")
	)
	(segment
		(start 56.572404 -46.001686)
		(end 55.971186 -42.589196)
		(width 0.14732)
		(layer "In11.Cu")
		(net "P5E_CPU1_PE1_RX_DP<2>")
	)
	(segment
		(start 116.244116 -213.929468)
		(end 116.24437 -213.929214)
		(width 0.0889)
		(layer "In11.Cu")
		(net "P5E_CPU1_PE1_RX_DP<2>")
	)
	(segment
		(start 52.236116 -12.12342)
		(end 52.236116 -5.257292)
		(width 0.14732)
		(layer "In11.Cu")
		(net "P5E_CPU1_PE1_RX_DP<2>")
	)
	(segment
		(start 52.988718 -15.326106)
		(end 52.888642 -14.971268)
		(width 0.14732)
		(layer "In11.Cu")
		(net "P5E_CPU1_PE1_RX_DP<2>")
	)
	(segment
		(start 55.642002 -39.824914)
		(end 54.252876 -19.01952)
		(width 0.14732)
		(layer "In11.Cu")
		(net "P5E_CPU1_PE1_RX_DP<2>")
	)
	(segment
		(start 116.997226 -219.996004)
		(end 116.99621 -219.995496)
		(width 0.0889)
		(layer "In11.Cu")
		(net "P5E_CPU1_PE1_RX_DP<2>")
	)
	(segment
		(start 52.888896 -14.438376)
		(end 52.71008 -14.3383)
		(width 0.14732)
		(layer "In11.Cu")
		(net "P5E_CPU1_PE1_RX_DP<2>")
	)
	(segment
		(start 52.236116 -5.257292)
		(end 51.941476 -4.962652)
		(width 0.14732)
		(layer "In11.Cu")
		(net "P5E_CPU1_PE1_RX_DP<2>")
	)
	(segment
		(start 116.526564 -219.18168)
		(end 116.520468 -219.178124)
		(width 0.0889)
		(layer "In11.Cu")
		(net "P5E_CPU1_PE1_RX_DP<2>")
	)
	(segment
		(start 52.888642 -14.971268)
		(end 52.988718 -14.792706)
		(width 0.14732)
		(layer "In11.Cu")
		(net "P5E_CPU1_PE1_RX_DP<2>")
	)
	(segment
		(start 53.540914 -16.749522)
		(end 53.167534 -15.425928)
		(width 0.14732)
		(layer "In11.Cu")
		(net "P5E_CPU1_PE1_RX_DP<2>")
	)
	(segment
		(start 116.713508 -214.622634)
		(end 116.713508 -214.461344)
		(width 0.0889)
		(layer "In11.Cu")
		(net "P5E_CPU1_PE1_RX_DP<2>")
	)
	(segment
		(start 115.879626 -205.690724)
		(end 112.765078 -183.413654)
		(width 0.14732)
		(layer "In11.Cu")
		(net "P5E_CPU1_PE1_RX_DP<2>")
	)
	(segment
		(start 52.71008 -14.3383)
		(end 52.610004 -13.983462)
		(width 0.14732)
		(layer "In11.Cu")
		(net "P5E_CPU1_PE1_RX_DP<2>")
	)
	(segment
		(start 116.24437 -213.105238)
		(end 116.20246 -213.063328)
		(width 0.0889)
		(layer "In11.Cu")
		(net "P5E_CPU1_PE1_RX_DP<2>")
	)
	(segment
		(start 116.20246 -213.063328)
		(end 116.20246 -213.04123)
		(width 0.0889)
		(layer "In11.Cu")
		(net "P5E_CPU1_PE1_RX_DP<2>")
	)
	(segment
		(start 55.971186 -42.589196)
		(end 55.642002 -39.824914)
		(width 0.14732)
		(layer "In11.Cu")
		(net "P5E_CPU1_PE1_RX_DP<2>")
	)
	(segment
		(start 53.540914 -17.770602)
		(end 53.540914 -16.749522)
		(width 0.14732)
		(layer "In11.Cu")
		(net "P5E_CPU1_PE1_RX_DP<2>")
	)
	(segment
		(start 117.0051 -220.000576)
		(end 116.997226 -219.996004)
		(width 0.0889)
		(layer "In11.Cu")
		(net "P5E_CPU1_PE1_RX_DP<2>")
	)
	(segment
		(start 52.98821 -14.790674)
		(end 52.888896 -14.438376)
		(width 0.14732)
		(layer "In11.Cu")
		(net "P5E_CPU1_PE1_RX_DP<2>")
	)
	(segment
		(start 116.529358 -214.261954)
		(end 116.529612 -214.261954)
		(width 0.0889)
		(layer "In11.Cu")
		(net "P5E_CPU1_PE1_RX_DP<2>")
	)
	(segment
		(start 53.770784 -18.325592)
		(end 53.540914 -17.770602)
		(width 0.14732)
		(layer "In11.Cu")
		(net "P5E_CPU1_PE1_RX_DP<2>")
	)
	(segment
		(start 115.774216 -216.260426)
		(end 115.774216 -216.235026)
		(width 0.0889)
		(layer "In11.Cu")
		(net "P5E_CPU1_PE1_RX_DP<2>")
	)
	(segment
		(start 116.714016 -219.521532)
		(end 116.714016 -219.506038)
		(width 0.0889)
		(layer "In11.Cu")
		(net "P5E_CPU1_PE1_RX_DP<2>")
	)
	(segment
		(start 116.520468 -218.20632)
		(end 116.525802 -218.203272)
		(width 0.0889)
		(layer "In11.Cu")
		(net "P5E_CPU1_PE1_RX_DP<2>")
	)
	(segment
		(start 116.535454 -219.18676)
		(end 116.526564 -219.18168)
		(width 0.0889)
		(layer "In11.Cu")
		(net "P5E_CPU1_PE1_RX_DP<2>")
	)
	(segment
		(start 116.20246 -213.04123)
		(end 116.20246 -210.331304)
		(width 0.14732)
		(layer "In11.Cu")
		(net "P5E_CPU1_PE1_RX_DP<2>")
	)
	(segment
		(start 112.240314 -180.396642)
		(end 56.572404 -46.001686)
		(width 0.14732)
		(layer "In11.Cu")
		(net "P5E_CPU1_PE1_RX_DP<2>")
	)
	(segment
		(start 116.243862 -215.436704)
		(end 116.243862 -215.414606)
		(width 0.0889)
		(layer "In11.Cu")
		(net "P5E_CPU1_PE1_RX_DP<2>")
	)
	(segment
		(start 116.20246 -210.331304)
		(end 115.879626 -205.690724)
		(width 0.14732)
		(layer "In11.Cu")
		(net "P5E_CPU1_PE1_RX_DP<2>")
	)
	(arc
		(start 116.056664 -216.739978)
		(mid 115.852329 -216.537373)
		(end 115.774216 -216.260426)
		(width 0.0889)
		(layer "In11.Cu")
		(net "P5E_CPU1_PE1_RX_DP<2>")
	)
	(arc
		(start 116.243862 -215.414606)
		(mid 116.324773 -215.144478)
		(end 116.526056 -214.946992)
		(width 0.0889)
		(layer "In11.Cu")
		(net "P5E_CPU1_PE1_RX_DP<2>")
	)
	(arc
		(start 115.774216 -216.235026)
		(mid 115.853586 -215.961292)
		(end 116.05641 -215.761062)
		(width 0.0889)
		(layer "In11.Cu")
		(net "P5E_CPU1_PE1_RX_DP<2>")
	)
	(arc
		(start 116.526564 -217.554048)
		(mid 116.323083 -217.353244)
		(end 116.243862 -217.07856)
		(width 0.0889)
		(layer "In11.Cu")
		(net "P5E_CPU1_PE1_RX_DP<2>")
	)
	(arc
		(start 116.713508 -214.461344)
		(mid 116.638503 -214.345885)
		(end 116.529358 -214.261954)
		(width 0.0889)
		(layer "In11.Cu")
		(net "P5E_CPU1_PE1_RX_DP<2>")
	)
	(arc
		(start 116.714016 -219.506038)
		(mid 116.666337 -219.323138)
		(end 116.535454 -219.18676)
		(width 0.0889)
		(layer "In11.Cu")
		(net "P5E_CPU1_PE1_RX_DP<2>")
	)
	(arc
		(start 116.25961 -213.969092)
		(mid 116.251509 -213.949419)
		(end 116.244116 -213.929468)
		(width 0.0889)
		(layer "In11.Cu")
		(net "P5E_CPU1_PE1_RX_DP<2>")
	)
	(arc
		(start 116.529612 -214.261954)
		(mid 116.369507 -214.138661)
		(end 116.25961 -213.969092)
		(width 0.0889)
		(layer "In11.Cu")
		(net "P5E_CPU1_PE1_RX_DP<2>")
	)
	(arc
		(start 116.534946 -214.941912)
		(mid 116.66586 -214.805552)
		(end 116.713508 -214.622634)
		(width 0.0889)
		(layer "In11.Cu")
		(net "P5E_CPU1_PE1_RX_DP<2>")
	)
	(arc
		(start 117.183662 -220.319854)
		(mid 117.135983 -220.136954)
		(end 117.0051 -220.000576)
		(width 0.0889)
		(layer "In11.Cu")
		(net "P5E_CPU1_PE1_RX_DP<2>")
	)
	(arc
		(start 116.243862 -217.0557)
		(mid 116.191592 -216.873335)
		(end 116.056664 -216.739978)
		(width 0.0889)
		(layer "In11.Cu")
		(net "P5E_CPU1_PE1_RX_DP<2>")
	)
	(arc
		(start 116.0653 -215.755982)
		(mid 116.196214 -215.619622)
		(end 116.243862 -215.436704)
		(width 0.0889)
		(layer "In11.Cu")
		(net "P5E_CPU1_PE1_RX_DP<2>")
	)
	(arc
		(start 116.520468 -219.178124)
		(mid 116.243894 -218.692222)
		(end 116.520468 -218.20632)
		(width 0.0889)
		(layer "In11.Cu")
		(net "P5E_CPU1_PE1_RX_DP<2>")
	)
	(arc
		(start 116.535454 -218.197684)
		(mid 116.714172 -217.878406)
		(end 116.535454 -217.559128)
		(width 0.0889)
		(layer "In11.Cu")
		(net "P5E_CPU1_PE1_RX_DP<2>")
	)
	(arc
		(start 117.043708 -220.6117)
		(mid 117.146853 -220.481675)
		(end 117.183662 -220.319854)
		(width 0.0889)
		(layer "In11.Cu")
		(net "P5E_CPU1_PE1_RX_DP<2>")
	)
	(arc
		(start 116.99621 -219.995496)
		(mid 116.793387 -219.795265)
		(end 116.714016 -219.521532)
		(width 0.0889)
		(layer "In11.Cu")
		(net "P5E_CPU1_PE1_RX_DP<2>")
	)
	(segment
		(start 118.218712 -221.669864)
		(end 118.218712 -221.134178)
		(width 0.13208)
		(layer "F.Cu")
		(net "P5E_CPU1_PE1_RX_DP<1>")
	)
	(segment
		(start 118.218712 -221.134178)
		(end 118.218966 -221.133924)
		(width 0.13208)
		(layer "F.Cu")
		(net "P5E_CPU1_PE1_RX_DP<1>")
	)
	(segment
		(start 54.039008 -7.623556)
		(end 54.039008 -7.026656)
		(width 0.13208)
		(layer "F.Cu")
		(net "P5E_CPU1_PE1_RX_DP<1>")
	)
	(segment
		(start 53.86705 -8.320024)
		(end 53.86705 -7.795514)
		(width 0.13208)
		(layer "F.Cu")
		(net "P5E_CPU1_PE1_RX_DP<1>")
	)
	(segment
		(start 54.039008 -7.026656)
		(end 53.736748 -6.724396)
		(width 0.13208)
		(layer "F.Cu")
		(net "P5E_CPU1_PE1_RX_DP<1>")
	)
	(segment
		(start 53.86705 -7.795514)
		(end 54.039008 -7.623556)
		(width 0.13208)
		(layer "F.Cu")
		(net "P5E_CPU1_PE1_RX_DP<1>")
	)
	(segment
		(start 117.467888 -218.202002)
		(end 117.471444 -218.19997)
		(width 0.0889)
		(layer "In11.Cu")
		(net "P5E_CPU1_PE1_RX_DP<1>")
	)
	(segment
		(start 55.94477 -15.684246)
		(end 55.745634 -15.635478)
		(width 0.14732)
		(layer "In11.Cu")
		(net "P5E_CPU1_PE1_RX_DP<1>")
	)
	(segment
		(start 117.653308 -214.446104)
		(end 117.469158 -214.261954)
		(width 0.0889)
		(layer "In11.Cu")
		(net "P5E_CPU1_PE1_RX_DP<1>")
	)
	(segment
		(start 118.415054 -220.814646)
		(end 118.406164 -220.809566)
		(width 0.0889)
		(layer "In11.Cu")
		(net "P5E_CPU1_PE1_RX_DP<1>")
	)
	(segment
		(start 54.129432 -12.689078)
		(end 54.031388 -12.337288)
		(width 0.14732)
		(layer "In11.Cu")
		(net "P5E_CPU1_PE1_RX_DP<1>")
	)
	(segment
		(start 117.46357 -218.204542)
		(end 117.465602 -218.203272)
		(width 0.0889)
		(layer "In11.Cu")
		(net "P5E_CPU1_PE1_RX_DP<1>")
	)
	(segment
		(start 117.183662 -217.071956)
		(end 117.183662 -217.064336)
		(width 0.0889)
		(layer "In11.Cu")
		(net "P5E_CPU1_PE1_RX_DP<1>")
	)
	(segment
		(start 56.761126 -38.553898)
		(end 56.267096 -19.577558)
		(width 0.14732)
		(layer "In11.Cu")
		(net "P5E_CPU1_PE1_RX_DP<1>")
	)
	(segment
		(start 55.071518 -14.243558)
		(end 54.880764 -13.928598)
		(width 0.14732)
		(layer "In11.Cu")
		(net "P5E_CPU1_PE1_RX_DP<1>")
	)
	(segment
		(start 117.18417 -213.93023)
		(end 117.18417 -213.105238)
		(width 0.0889)
		(layer "In11.Cu")
		(net "P5E_CPU1_PE1_RX_DP<1>")
	)
	(segment
		(start 54.880764 -13.928598)
		(end 54.681628 -13.87983)
		(width 0.14732)
		(layer "In11.Cu")
		(net "P5E_CPU1_PE1_RX_DP<1>")
	)
	(segment
		(start 117.475254 -217.559128)
		(end 117.467126 -217.554556)
		(width 0.0889)
		(layer "In11.Cu")
		(net "P5E_CPU1_PE1_RX_DP<1>")
	)
	(segment
		(start 118.062502 -221.404942)
		(end 118.083584 -221.48292)
		(width 0.0889)
		(layer "In11.Cu")
		(net "P5E_CPU1_PE1_RX_DP<1>")
	)
	(segment
		(start 117.0051 -216.745058)
		(end 116.997226 -216.740486)
		(width 0.0889)
		(layer "In11.Cu")
		(net "P5E_CPU1_PE1_RX_DP<1>")
	)
	(segment
		(start 54.031388 -7.019036)
		(end 53.736748 -6.724396)
		(width 0.14732)
		(layer "In11.Cu")
		(net "P5E_CPU1_PE1_RX_DP<1>")
	)
	(segment
		(start 118.123462 -220.334078)
		(end 118.123462 -220.311218)
		(width 0.0889)
		(layer "In11.Cu")
		(net "P5E_CPU1_PE1_RX_DP<1>")
	)
	(segment
		(start 117.14226 -210.229704)
		(end 116.824252 -205.65999)
		(width 0.14732)
		(layer "In11.Cu")
		(net "P5E_CPU1_PE1_RX_DP<1>")
	)
	(segment
		(start 56.543956 -18.4785)
		(end 57.07126 -17.951196)
		(width 0.14732)
		(layer "In11.Cu")
		(net "P5E_CPU1_PE1_RX_DP<1>")
	)
	(segment
		(start 113.147602 -180.152548)
		(end 57.934098 -46.85665)
		(width 0.14732)
		(layer "In11.Cu")
		(net "P5E_CPU1_PE1_RX_DP<1>")
	)
	(segment
		(start 55.213504 -14.757654)
		(end 55.02275 -14.44244)
		(width 0.14732)
		(layer "In11.Cu")
		(net "P5E_CPU1_PE1_RX_DP<1>")
	)
	(segment
		(start 116.714016 -216.266014)
		(end 116.714016 -216.235026)
		(width 0.0889)
		(layer "In11.Cu")
		(net "P5E_CPU1_PE1_RX_DP<1>")
	)
	(segment
		(start 117.14226 -213.04123)
		(end 117.14226 -210.229704)
		(width 0.14732)
		(layer "In11.Cu")
		(net "P5E_CPU1_PE1_RX_DP<1>")
	)
	(segment
		(start 55.745634 -15.635478)
		(end 55.554626 -15.320264)
		(width 0.14732)
		(layer "In11.Cu")
		(net "P5E_CPU1_PE1_RX_DP<1>")
	)
	(segment
		(start 117.475254 -219.18676)
		(end 117.467888 -219.182442)
		(width 0.0889)
		(layer "In11.Cu")
		(net "P5E_CPU1_PE1_RX_DP<1>")
	)
	(segment
		(start 117.466364 -219.18168)
		(end 117.465602 -219.181172)
		(width 0.0889)
		(layer "In11.Cu")
		(net "P5E_CPU1_PE1_RX_DP<1>")
	)
	(segment
		(start 117.467888 -219.182442)
		(end 117.466364 -219.18168)
		(width 0.0889)
		(layer "In11.Cu")
		(net "P5E_CPU1_PE1_RX_DP<1>")
	)
	(segment
		(start 56.53659 -16.66113)
		(end 55.94477 -15.684246)
		(width 0.14732)
		(layer "In11.Cu")
		(net "P5E_CPU1_PE1_RX_DP<1>")
	)
	(segment
		(start 117.465602 -218.203272)
		(end 117.466364 -218.202764)
		(width 0.0889)
		(layer "In11.Cu")
		(net "P5E_CPU1_PE1_RX_DP<1>")
	)
	(segment
		(start 54.681628 -13.87983)
		(end 54.490874 -13.564616)
		(width 0.14732)
		(layer "In11.Cu")
		(net "P5E_CPU1_PE1_RX_DP<1>")
	)
	(segment
		(start 113.695988 -183.28386)
		(end 113.147602 -180.152548)
		(width 0.14732)
		(layer "In11.Cu")
		(net "P5E_CPU1_PE1_RX_DP<1>")
	)
	(segment
		(start 56.267096 -19.147028)
		(end 56.543956 -18.4785)
		(width 0.14732)
		(layer "In11.Cu")
		(net "P5E_CPU1_PE1_RX_DP<1>")
	)
	(segment
		(start 117.471444 -218.19997)
		(end 117.475254 -218.197684)
		(width 0.0889)
		(layer "In11.Cu")
		(net "P5E_CPU1_PE1_RX_DP<1>")
	)
	(segment
		(start 56.894984 -40.553894)
		(end 56.761126 -38.553898)
		(width 0.14732)
		(layer "In11.Cu")
		(net "P5E_CPU1_PE1_RX_DP<1>")
	)
	(segment
		(start 117.465856 -214.946992)
		(end 117.474746 -214.941912)
		(width 0.0889)
		(layer "In11.Cu")
		(net "P5E_CPU1_PE1_RX_DP<1>")
	)
	(segment
		(start 57.07126 -17.478756)
		(end 56.870854 -16.99514)
		(width 0.14732)
		(layer "In11.Cu")
		(net "P5E_CPU1_PE1_RX_DP<1>")
	)
	(segment
		(start 117.460268 -218.20632)
		(end 117.46357 -218.204542)
		(width 0.0889)
		(layer "In11.Cu")
		(net "P5E_CPU1_PE1_RX_DP<1>")
	)
	(segment
		(start 118.407688 -221.45752)
		(end 118.415054 -221.453202)
		(width 0.0889)
		(layer "In11.Cu")
		(net "P5E_CPU1_PE1_RX_DP<1>")
	)
	(segment
		(start 116.997226 -216.740486)
		(end 116.99621 -216.739978)
		(width 0.0889)
		(layer "In11.Cu")
		(net "P5E_CPU1_PE1_RX_DP<1>")
	)
	(segment
		(start 117.653308 -214.622634)
		(end 117.653308 -214.446104)
		(width 0.0889)
		(layer "In11.Cu")
		(net "P5E_CPU1_PE1_RX_DP<1>")
	)
	(segment
		(start 117.183916 -213.930484)
		(end 117.18417 -213.93023)
		(width 0.0889)
		(layer "In11.Cu")
		(net "P5E_CPU1_PE1_RX_DP<1>")
	)
	(segment
		(start 117.183662 -215.436704)
		(end 117.183662 -215.414606)
		(width 0.0889)
		(layer "In11.Cu")
		(net "P5E_CPU1_PE1_RX_DP<1>")
	)
	(segment
		(start 116.824252 -205.65999)
		(end 113.695988 -183.28386)
		(width 0.14732)
		(layer "In11.Cu")
		(net "P5E_CPU1_PE1_RX_DP<1>")
	)
	(segment
		(start 55.554626 -15.320264)
		(end 55.603394 -15.121382)
		(width 0.14732)
		(layer "In11.Cu")
		(net "P5E_CPU1_PE1_RX_DP<1>")
	)
	(segment
		(start 54.031388 -12.337288)
		(end 54.031388 -7.019036)
		(width 0.14732)
		(layer "In11.Cu")
		(net "P5E_CPU1_PE1_RX_DP<1>")
	)
	(segment
		(start 54.539642 -13.365734)
		(end 54.129432 -12.689078)
		(width 0.14732)
		(layer "In11.Cu")
		(net "P5E_CPU1_PE1_RX_DP<1>")
	)
	(segment
		(start 117.14226 -213.063328)
		(end 117.14226 -213.04123)
		(width 0.0889)
		(layer "In11.Cu")
		(net "P5E_CPU1_PE1_RX_DP<1>")
	)
	(segment
		(start 57.07126 -17.951196)
		(end 57.07126 -17.478756)
		(width 0.14732)
		(layer "In11.Cu")
		(net "P5E_CPU1_PE1_RX_DP<1>")
	)
	(segment
		(start 116.99621 -215.761062)
		(end 117.0051 -215.755982)
		(width 0.0889)
		(layer "In11.Cu")
		(net "P5E_CPU1_PE1_RX_DP<1>")
	)
	(segment
		(start 117.466364 -218.202764)
		(end 117.467888 -218.202002)
		(width 0.0889)
		(layer "In11.Cu")
		(net "P5E_CPU1_PE1_RX_DP<1>")
	)
	(segment
		(start 118.218966 -221.133924)
		(end 118.062502 -221.404942)
		(width 0.0889)
		(layer "In11.Cu")
		(net "P5E_CPU1_PE1_RX_DP<1>")
	)
	(segment
		(start 55.603394 -15.121382)
		(end 55.41264 -14.806422)
		(width 0.14732)
		(layer "In11.Cu")
		(net "P5E_CPU1_PE1_RX_DP<1>")
	)
	(segment
		(start 56.870854 -16.99514)
		(end 56.53659 -16.66113)
		(width 0.14732)
		(layer "In11.Cu")
		(net "P5E_CPU1_PE1_RX_DP<1>")
	)
	(segment
		(start 117.465602 -219.181172)
		(end 117.460268 -219.178124)
		(width 0.0889)
		(layer "In11.Cu")
		(net "P5E_CPU1_PE1_RX_DP<1>")
	)
	(segment
		(start 117.467126 -217.554556)
		(end 117.466364 -217.554048)
		(width 0.0889)
		(layer "In11.Cu")
		(net "P5E_CPU1_PE1_RX_DP<1>")
	)
	(segment
		(start 118.406164 -221.458282)
		(end 118.407688 -221.45752)
		(width 0.0889)
		(layer "In11.Cu")
		(net "P5E_CPU1_PE1_RX_DP<1>")
	)
	(segment
		(start 55.02275 -14.44244)
		(end 55.071518 -14.243558)
		(width 0.14732)
		(layer "In11.Cu")
		(net "P5E_CPU1_PE1_RX_DP<1>")
	)
	(segment
		(start 57.934098 -46.85665)
		(end 56.894984 -40.553894)
		(width 0.14732)
		(layer "In11.Cu")
		(net "P5E_CPU1_PE1_RX_DP<1>")
	)
	(segment
		(start 56.267096 -19.577558)
		(end 56.267096 -19.147028)
		(width 0.14732)
		(layer "In11.Cu")
		(net "P5E_CPU1_PE1_RX_DP<1>")
	)
	(segment
		(start 55.41264 -14.806422)
		(end 55.213504 -14.757654)
		(width 0.14732)
		(layer "In11.Cu")
		(net "P5E_CPU1_PE1_RX_DP<1>")
	)
	(segment
		(start 117.653816 -219.515944)
		(end 117.653816 -219.506038)
		(width 0.0889)
		(layer "In11.Cu")
		(net "P5E_CPU1_PE1_RX_DP<1>")
	)
	(segment
		(start 117.18417 -213.105238)
		(end 117.14226 -213.063328)
		(width 0.0889)
		(layer "In11.Cu")
		(net "P5E_CPU1_PE1_RX_DP<1>")
	)
	(segment
		(start 54.490874 -13.564616)
		(end 54.539642 -13.365734)
		(width 0.14732)
		(layer "In11.Cu")
		(net "P5E_CPU1_PE1_RX_DP<1>")
	)
	(arc
		(start 117.466364 -217.554048)
		(mid 117.261292 -217.350369)
		(end 117.183662 -217.071956)
		(width 0.0889)
		(layer "In11.Cu")
		(net "P5E_CPU1_PE1_RX_DP<1>")
	)
	(arc
		(start 118.123462 -220.311218)
		(mid 118.071192 -220.128853)
		(end 117.936264 -219.995496)
		(width 0.0889)
		(layer "In11.Cu")
		(net "P5E_CPU1_PE1_RX_DP<1>")
	)
	(arc
		(start 117.183662 -215.414606)
		(mid 117.264573 -215.144478)
		(end 117.465856 -214.946992)
		(width 0.0889)
		(layer "In11.Cu")
		(net "P5E_CPU1_PE1_RX_DP<1>")
	)
	(arc
		(start 118.415054 -221.453202)
		(mid 118.593651 -221.133924)
		(end 118.415054 -220.814646)
		(width 0.0889)
		(layer "In11.Cu")
		(net "P5E_CPU1_PE1_RX_DP<1>")
	)
	(arc
		(start 118.406164 -220.809566)
		(mid 118.202683 -220.608762)
		(end 118.123462 -220.334078)
		(width 0.0889)
		(layer "In11.Cu")
		(net "P5E_CPU1_PE1_RX_DP<1>")
	)
	(arc
		(start 117.460268 -219.178124)
		(mid 117.183694 -218.692222)
		(end 117.460268 -218.20632)
		(width 0.0889)
		(layer "In11.Cu")
		(net "P5E_CPU1_PE1_RX_DP<1>")
	)
	(arc
		(start 116.714016 -216.235026)
		(mid 116.793386 -215.961292)
		(end 116.99621 -215.761062)
		(width 0.0889)
		(layer "In11.Cu")
		(net "P5E_CPU1_PE1_RX_DP<1>")
	)
	(arc
		(start 117.199156 -213.969346)
		(mid 117.191193 -213.950049)
		(end 117.183916 -213.930484)
		(width 0.0889)
		(layer "In11.Cu")
		(net "P5E_CPU1_PE1_RX_DP<1>")
	)
	(arc
		(start 117.474746 -214.941912)
		(mid 117.602 -214.811946)
		(end 117.653054 -214.637366)
		(width 0.0889)
		(layer "In11.Cu")
		(net "P5E_CPU1_PE1_RX_DP<1>")
	)
	(arc
		(start 117.0051 -215.755982)
		(mid 117.136014 -215.619622)
		(end 117.183662 -215.436704)
		(width 0.0889)
		(layer "In11.Cu")
		(net "P5E_CPU1_PE1_RX_DP<1>")
	)
	(arc
		(start 117.469158 -214.261954)
		(mid 117.309086 -214.138774)
		(end 117.199156 -213.969346)
		(width 0.0889)
		(layer "In11.Cu")
		(net "P5E_CPU1_PE1_RX_DP<1>")
	)
	(arc
		(start 117.653054 -214.637366)
		(mid 117.653251 -214.630001)
		(end 117.653308 -214.622634)
		(width 0.0889)
		(layer "In11.Cu")
		(net "P5E_CPU1_PE1_RX_DP<1>")
	)
	(arc
		(start 117.183662 -217.064336)
		(mid 117.135983 -216.881436)
		(end 117.0051 -216.745058)
		(width 0.0889)
		(layer "In11.Cu")
		(net "P5E_CPU1_PE1_RX_DP<1>")
	)
	(arc
		(start 117.936264 -219.995496)
		(mid 117.731929 -219.792891)
		(end 117.653816 -219.515944)
		(width 0.0889)
		(layer "In11.Cu")
		(net "P5E_CPU1_PE1_RX_DP<1>")
	)
	(arc
		(start 117.653816 -219.506038)
		(mid 117.606137 -219.323138)
		(end 117.475254 -219.18676)
		(width 0.0889)
		(layer "In11.Cu")
		(net "P5E_CPU1_PE1_RX_DP<1>")
	)
	(arc
		(start 116.99621 -216.739978)
		(mid 116.793387 -216.539747)
		(end 116.714016 -216.266014)
		(width 0.0889)
		(layer "In11.Cu")
		(net "P5E_CPU1_PE1_RX_DP<1>")
	)
	(arc
		(start 117.475254 -218.197684)
		(mid 117.65373 -217.878406)
		(end 117.475254 -217.559128)
		(width 0.0889)
		(layer "In11.Cu")
		(net "P5E_CPU1_PE1_RX_DP<1>")
	)
	(arc
		(start 118.083584 -221.48292)
		(mid 118.24768 -221.507267)
		(end 118.406164 -221.458282)
		(width 0.0889)
		(layer "In11.Cu")
		(net "P5E_CPU1_PE1_RX_DP<1>")
	)
	(segment
		(start 19.318986 -7.026656)
		(end 19.016726 -6.724396)
		(width 0.13208)
		(layer "F.Cu")
		(net "P5E_CPU1_PE1_RX_DP<15>")
	)
	(segment
		(start 19.318986 -7.623556)
		(end 19.318986 -7.026656)
		(width 0.13208)
		(layer "F.Cu")
		(net "P5E_CPU1_PE1_RX_DP<15>")
	)
	(segment
		(start 105.061512 -221.669864)
		(end 105.061512 -221.134178)
		(width 0.13208)
		(layer "F.Cu")
		(net "P5E_CPU1_PE1_RX_DP<15>")
	)
	(segment
		(start 19.147028 -8.320024)
		(end 19.147028 -7.795514)
		(width 0.13208)
		(layer "F.Cu")
		(net "P5E_CPU1_PE1_RX_DP<15>")
	)
	(segment
		(start 19.147028 -7.795514)
		(end 19.318986 -7.623556)
		(width 0.13208)
		(layer "F.Cu")
		(net "P5E_CPU1_PE1_RX_DP<15>")
	)
	(segment
		(start 105.061512 -221.134178)
		(end 105.061766 -221.133924)
		(width 0.13208)
		(layer "F.Cu")
		(net "P5E_CPU1_PE1_RX_DP<15>")
	)
	(segment
		(start 18.851372 -13.470128)
		(end 19.034506 -13.377926)
		(width 0.14732)
		(layer "In11.Cu")
		(net "P5E_CPU1_PE1_RX_DP<15>")
	)
	(segment
		(start 18.828004 -14.00302)
		(end 18.736056 -13.82014)
		(width 0.14732)
		(layer "In11.Cu")
		(net "P5E_CPU1_PE1_RX_DP<15>")
	)
	(segment
		(start 18.006822 -16.026384)
		(end 18.189956 -15.934182)
		(width 0.14732)
		(layer "In11.Cu")
		(net "P5E_CPU1_PE1_RX_DP<15>")
	)
	(segment
		(start 104.309164 -219.18168)
		(end 104.303068 -219.178124)
		(width 0.0889)
		(layer "In11.Cu")
		(net "P5E_CPU1_PE1_RX_DP<15>")
	)
	(segment
		(start 17.011904 -19.854926)
		(end 16.85798 -19.483832)
		(width 0.14732)
		(layer "In11.Cu")
		(net "P5E_CPU1_PE1_RX_DP<15>")
	)
	(segment
		(start 18.736056 -13.82014)
		(end 18.851372 -13.470128)
		(width 0.14732)
		(layer "In11.Cu")
		(net "P5E_CPU1_PE1_RX_DP<15>")
	)
	(segment
		(start 17.983454 -16.559276)
		(end 17.891252 -16.376396)
		(width 0.14732)
		(layer "In11.Cu")
		(net "P5E_CPU1_PE1_RX_DP<15>")
	)
	(segment
		(start 103.556816 -216.266014)
		(end 103.556816 -216.25052)
		(width 0.0889)
		(layer "In11.Cu")
		(net "P5E_CPU1_PE1_RX_DP<15>")
	)
	(segment
		(start 18.189956 -15.934182)
		(end 18.374614 -15.374874)
		(width 0.14732)
		(layer "In11.Cu")
		(net "P5E_CPU1_PE1_RX_DP<15>")
	)
	(segment
		(start 103.04526 -213.04123)
		(end 103.04526 -209.08518)
		(width 0.14732)
		(layer "In11.Cu")
		(net "P5E_CPU1_PE1_RX_DP<15>")
	)
	(segment
		(start 16.85798 -19.483832)
		(end 16.85798 -18.868136)
		(width 0.14732)
		(layer "In11.Cu")
		(net "P5E_CPU1_PE1_RX_DP<15>")
	)
	(segment
		(start 19.311366 -7.019036)
		(end 19.016726 -6.724396)
		(width 0.14732)
		(layer "In11.Cu")
		(net "P5E_CPU1_PE1_RX_DP<15>")
	)
	(segment
		(start 103.556816 -217.8939)
		(end 103.556816 -217.856308)
		(width 0.0889)
		(layer "In11.Cu")
		(net "P5E_CPU1_PE1_RX_DP<15>")
	)
	(segment
		(start 104.966262 -220.334078)
		(end 104.966262 -220.311218)
		(width 0.0889)
		(layer "In11.Cu")
		(net "P5E_CPU1_PE1_RX_DP<15>")
	)
	(segment
		(start 104.905302 -221.404942)
		(end 104.926384 -221.48292)
		(width 0.0889)
		(layer "In11.Cu")
		(net "P5E_CPU1_PE1_RX_DP<15>")
	)
	(segment
		(start 17.511522 -17.988534)
		(end 17.983454 -16.559276)
		(width 0.14732)
		(layer "In11.Cu")
		(net "P5E_CPU1_PE1_RX_DP<15>")
	)
	(segment
		(start 103.378254 -215.931242)
		(end 103.369364 -215.926162)
		(width 0.0889)
		(layer "In11.Cu")
		(net "P5E_CPU1_PE1_RX_DP<15>")
	)
	(segment
		(start 19.034506 -13.377926)
		(end 19.311366 -12.539472)
		(width 0.14732)
		(layer "In11.Cu")
		(net "P5E_CPU1_PE1_RX_DP<15>")
	)
	(segment
		(start 105.248964 -221.458282)
		(end 105.250488 -221.45752)
		(width 0.0889)
		(layer "In11.Cu")
		(net "P5E_CPU1_PE1_RX_DP<15>")
	)
	(segment
		(start 16.937736 -18.675604)
		(end 17.018 -18.482056)
		(width 0.14732)
		(layer "In11.Cu")
		(net "P5E_CPU1_PE1_RX_DP<15>")
	)
	(segment
		(start 103.840026 -216.740486)
		(end 103.83901 -216.739978)
		(width 0.0889)
		(layer "In11.Cu")
		(net "P5E_CPU1_PE1_RX_DP<15>")
	)
	(segment
		(start 104.496616 -219.515944)
		(end 104.496616 -219.506038)
		(width 0.0889)
		(layer "In11.Cu")
		(net "P5E_CPU1_PE1_RX_DP<15>")
	)
	(segment
		(start 99.459796 -181.789324)
		(end 49.798732 -61.90361)
		(width 0.14732)
		(layer "In11.Cu")
		(net "P5E_CPU1_PE1_RX_DP<15>")
	)
	(segment
		(start 103.086662 -215.436704)
		(end 103.086662 -215.414606)
		(width 0.0889)
		(layer "In11.Cu")
		(net "P5E_CPU1_PE1_RX_DP<15>")
	)
	(segment
		(start 18.374614 -15.374874)
		(end 18.282666 -15.191994)
		(width 0.14732)
		(layer "In11.Cu")
		(net "P5E_CPU1_PE1_RX_DP<15>")
	)
	(segment
		(start 17.891252 -16.376396)
		(end 18.006822 -16.026384)
		(width 0.14732)
		(layer "In11.Cu")
		(net "P5E_CPU1_PE1_RX_DP<15>")
	)
	(segment
		(start 105.257854 -220.814646)
		(end 105.248964 -220.809566)
		(width 0.0889)
		(layer "In11.Cu")
		(net "P5E_CPU1_PE1_RX_DP<15>")
	)
	(segment
		(start 104.318054 -219.18676)
		(end 104.309164 -219.18168)
		(width 0.0889)
		(layer "In11.Cu")
		(net "P5E_CPU1_PE1_RX_DP<15>")
	)
	(segment
		(start 103.086916 -213.929722)
		(end 103.08717 -213.929468)
		(width 0.0889)
		(layer "In11.Cu")
		(net "P5E_CPU1_PE1_RX_DP<15>")
	)
	(segment
		(start 103.83901 -217.388694)
		(end 103.8479 -217.383614)
		(width 0.0889)
		(layer "In11.Cu")
		(net "P5E_CPU1_PE1_RX_DP<15>")
	)
	(segment
		(start 16.85798 -18.868136)
		(end 16.937736 -18.675604)
		(width 0.14732)
		(layer "In11.Cu")
		(net "P5E_CPU1_PE1_RX_DP<15>")
	)
	(segment
		(start 103.04526 -213.063328)
		(end 103.04526 -213.04123)
		(width 0.0889)
		(layer "In11.Cu")
		(net "P5E_CPU1_PE1_RX_DP<15>")
	)
	(segment
		(start 103.086916 -213.930484)
		(end 103.086916 -213.929722)
		(width 0.0889)
		(layer "In11.Cu")
		(net "P5E_CPU1_PE1_RX_DP<15>")
	)
	(segment
		(start 103.8479 -216.745058)
		(end 103.840026 -216.740486)
		(width 0.0889)
		(layer "In11.Cu")
		(net "P5E_CPU1_PE1_RX_DP<15>")
	)
	(segment
		(start 105.250488 -221.45752)
		(end 105.257854 -221.453202)
		(width 0.0889)
		(layer "In11.Cu")
		(net "P5E_CPU1_PE1_RX_DP<15>")
	)
	(segment
		(start 103.08717 -213.929468)
		(end 103.08717 -213.105238)
		(width 0.0889)
		(layer "In11.Cu")
		(net "P5E_CPU1_PE1_RX_DP<15>")
	)
	(segment
		(start 103.368856 -214.946992)
		(end 103.377746 -214.941912)
		(width 0.0889)
		(layer "In11.Cu")
		(net "P5E_CPU1_PE1_RX_DP<15>")
	)
	(segment
		(start 19.311366 -12.539472)
		(end 19.311366 -7.019036)
		(width 0.14732)
		(layer "In11.Cu")
		(net "P5E_CPU1_PE1_RX_DP<15>")
	)
	(segment
		(start 103.04526 -209.08518)
		(end 99.459796 -181.789324)
		(width 0.14732)
		(layer "In11.Cu")
		(net "P5E_CPU1_PE1_RX_DP<15>")
	)
	(segment
		(start 105.061766 -221.133924)
		(end 104.905302 -221.404942)
		(width 0.0889)
		(layer "In11.Cu")
		(net "P5E_CPU1_PE1_RX_DP<15>")
	)
	(segment
		(start 103.556308 -214.622634)
		(end 103.556308 -214.461344)
		(width 0.0889)
		(layer "In11.Cu")
		(net "P5E_CPU1_PE1_RX_DP<15>")
	)
	(segment
		(start 18.282666 -15.191994)
		(end 18.398236 -14.842236)
		(width 0.14732)
		(layer "In11.Cu")
		(net "P5E_CPU1_PE1_RX_DP<15>")
	)
	(segment
		(start 49.798732 -61.90361)
		(end 17.011904 -19.854926)
		(width 0.14732)
		(layer "In11.Cu")
		(net "P5E_CPU1_PE1_RX_DP<15>")
	)
	(segment
		(start 18.398236 -14.842236)
		(end 18.58137 -14.750034)
		(width 0.14732)
		(layer "In11.Cu")
		(net "P5E_CPU1_PE1_RX_DP<15>")
	)
	(segment
		(start 103.8479 -218.372944)
		(end 103.83901 -218.367864)
		(width 0.0889)
		(layer "In11.Cu")
		(net "P5E_CPU1_PE1_RX_DP<15>")
	)
	(segment
		(start 103.08717 -213.105238)
		(end 103.04526 -213.063328)
		(width 0.0889)
		(layer "In11.Cu")
		(net "P5E_CPU1_PE1_RX_DP<15>")
	)
	(segment
		(start 18.58137 -14.750034)
		(end 18.828004 -14.00302)
		(width 0.14732)
		(layer "In11.Cu")
		(net "P5E_CPU1_PE1_RX_DP<15>")
	)
	(segment
		(start 103.369364 -215.926162)
		(end 103.363268 -215.922606)
		(width 0.0889)
		(layer "In11.Cu")
		(net "P5E_CPU1_PE1_RX_DP<15>")
	)
	(segment
		(start 17.018 -18.482056)
		(end 17.511522 -17.988534)
		(width 0.14732)
		(layer "In11.Cu")
		(net "P5E_CPU1_PE1_RX_DP<15>")
	)
	(arc
		(start 103.556308 -214.461344)
		(mid 103.481303 -214.345885)
		(end 103.372158 -214.261954)
		(width 0.0889)
		(layer "In11.Cu")
		(net "P5E_CPU1_PE1_RX_DP<15>")
	)
	(arc
		(start 103.8479 -217.383614)
		(mid 104.026497 -217.064336)
		(end 103.8479 -216.745058)
		(width 0.0889)
		(layer "In11.Cu")
		(net "P5E_CPU1_PE1_RX_DP<15>")
	)
	(arc
		(start 103.556816 -216.25052)
		(mid 103.509137 -216.06762)
		(end 103.378254 -215.931242)
		(width 0.0889)
		(layer "In11.Cu")
		(net "P5E_CPU1_PE1_RX_DP<15>")
	)
	(arc
		(start 104.496616 -219.506038)
		(mid 104.448937 -219.323138)
		(end 104.318054 -219.18676)
		(width 0.0889)
		(layer "In11.Cu")
		(net "P5E_CPU1_PE1_RX_DP<15>")
	)
	(arc
		(start 103.377746 -214.941912)
		(mid 103.50866 -214.805552)
		(end 103.556308 -214.622634)
		(width 0.0889)
		(layer "In11.Cu")
		(net "P5E_CPU1_PE1_RX_DP<15>")
	)
	(arc
		(start 103.363268 -215.922606)
		(mid 103.160681 -215.716255)
		(end 103.086662 -215.436704)
		(width 0.0889)
		(layer "In11.Cu")
		(net "P5E_CPU1_PE1_RX_DP<15>")
	)
	(arc
		(start 105.257854 -221.453202)
		(mid 105.436451 -221.133924)
		(end 105.257854 -220.814646)
		(width 0.0889)
		(layer "In11.Cu")
		(net "P5E_CPU1_PE1_RX_DP<15>")
	)
	(arc
		(start 104.926384 -221.48292)
		(mid 105.09048 -221.507267)
		(end 105.248964 -221.458282)
		(width 0.0889)
		(layer "In11.Cu")
		(net "P5E_CPU1_PE1_RX_DP<15>")
	)
	(arc
		(start 105.248964 -220.809566)
		(mid 105.045483 -220.608762)
		(end 104.966262 -220.334078)
		(width 0.0889)
		(layer "In11.Cu")
		(net "P5E_CPU1_PE1_RX_DP<15>")
	)
	(arc
		(start 103.83901 -218.367864)
		(mid 103.636187 -218.167633)
		(end 103.556816 -217.8939)
		(width 0.0889)
		(layer "In11.Cu")
		(net "P5E_CPU1_PE1_RX_DP<15>")
	)
	(arc
		(start 103.086662 -215.414606)
		(mid 103.167573 -215.144478)
		(end 103.368856 -214.946992)
		(width 0.0889)
		(layer "In11.Cu")
		(net "P5E_CPU1_PE1_RX_DP<15>")
	)
	(arc
		(start 103.372158 -214.261954)
		(mid 103.212086 -214.138774)
		(end 103.102156 -213.969346)
		(width 0.0889)
		(layer "In11.Cu")
		(net "P5E_CPU1_PE1_RX_DP<15>")
	)
	(arc
		(start 103.102156 -213.969346)
		(mid 103.094193 -213.950049)
		(end 103.086916 -213.930484)
		(width 0.0889)
		(layer "In11.Cu")
		(net "P5E_CPU1_PE1_RX_DP<15>")
	)
	(arc
		(start 103.83901 -216.739978)
		(mid 103.636187 -216.539747)
		(end 103.556816 -216.266014)
		(width 0.0889)
		(layer "In11.Cu")
		(net "P5E_CPU1_PE1_RX_DP<15>")
	)
	(arc
		(start 104.026462 -218.692222)
		(mid 103.978783 -218.509322)
		(end 103.8479 -218.372944)
		(width 0.0889)
		(layer "In11.Cu")
		(net "P5E_CPU1_PE1_RX_DP<15>")
	)
	(arc
		(start 104.966262 -220.311218)
		(mid 104.913992 -220.128853)
		(end 104.779064 -219.995496)
		(width 0.0889)
		(layer "In11.Cu")
		(net "P5E_CPU1_PE1_RX_DP<15>")
	)
	(arc
		(start 104.779064 -219.995496)
		(mid 104.574729 -219.792891)
		(end 104.496616 -219.515944)
		(width 0.0889)
		(layer "In11.Cu")
		(net "P5E_CPU1_PE1_RX_DP<15>")
	)
	(arc
		(start 103.556816 -217.856308)
		(mid 103.637727 -217.58618)
		(end 103.83901 -217.388694)
		(width 0.0889)
		(layer "In11.Cu")
		(net "P5E_CPU1_PE1_RX_DP<15>")
	)
	(arc
		(start 104.303068 -219.178124)
		(mid 104.100481 -218.971773)
		(end 104.026462 -218.692222)
		(width 0.0889)
		(layer "In11.Cu")
		(net "P5E_CPU1_PE1_RX_DP<15>")
	)
	(segment
		(start 105.531666 -220.320108)
		(end 105.531412 -220.319854)
		(width 0.13208)
		(layer "F.Cu")
		(net "P5E_CPU1_PE1_RX_DP<14>")
	)
	(segment
		(start 20.946872 -7.78637)
		(end 21.12264 -7.610602)
		(width 0.13208)
		(layer "F.Cu")
		(net "P5E_CPU1_PE1_RX_DP<14>")
	)
	(segment
		(start 105.531666 -220.855794)
		(end 105.531666 -220.320108)
		(width 0.13208)
		(layer "F.Cu")
		(net "P5E_CPU1_PE1_RX_DP<14>")
	)
	(segment
		(start 21.12264 -7.610602)
		(end 21.12264 -5.263896)
		(width 0.13208)
		(layer "F.Cu")
		(net "P5E_CPU1_PE1_RX_DP<14>")
	)
	(segment
		(start 21.12264 -5.263896)
		(end 20.821396 -4.962652)
		(width 0.13208)
		(layer "F.Cu")
		(net "P5E_CPU1_PE1_RX_DP<14>")
	)
	(segment
		(start 20.946872 -8.320024)
		(end 20.946872 -7.78637)
		(width 0.13208)
		(layer "F.Cu")
		(net "P5E_CPU1_PE1_RX_DP<14>")
	)
	(segment
		(start 104.026716 -213.930484)
		(end 104.026716 -213.105238)
		(width 0.0889)
		(layer "In11.Cu")
		(net "P5E_CPU1_PE1_RX_DP<14>")
	)
	(segment
		(start 104.7877 -218.372944)
		(end 104.77881 -218.367864)
		(width 0.0889)
		(layer "In11.Cu")
		(net "P5E_CPU1_PE1_RX_DP<14>")
	)
	(segment
		(start 104.309164 -215.926162)
		(end 104.308402 -215.925654)
		(width 0.0889)
		(layer "In11.Cu")
		(net "P5E_CPU1_PE1_RX_DP<14>")
	)
	(segment
		(start 104.318054 -215.931242)
		(end 104.310688 -215.926924)
		(width 0.0889)
		(layer "In11.Cu")
		(net "P5E_CPU1_PE1_RX_DP<14>")
	)
	(segment
		(start 104.308656 -214.946992)
		(end 104.317546 -214.941912)
		(width 0.0889)
		(layer "In11.Cu")
		(net "P5E_CPU1_PE1_RX_DP<14>")
	)
	(segment
		(start 104.308402 -215.925654)
		(end 104.303068 -215.922606)
		(width 0.0889)
		(layer "In11.Cu")
		(net "P5E_CPU1_PE1_RX_DP<14>")
	)
	(segment
		(start 20.574508 -13.706348)
		(end 20.755102 -13.60932)
		(width 0.14732)
		(layer "In11.Cu")
		(net "P5E_CPU1_PE1_RX_DP<14>")
	)
	(segment
		(start 19.67992 -17.194022)
		(end 20.14601 -15.638526)
		(width 0.14732)
		(layer "In11.Cu")
		(net "P5E_CPU1_PE1_RX_DP<14>")
	)
	(segment
		(start 21.09724 -12.46759)
		(end 21.116036 -12.340082)
		(width 0.14732)
		(layer "In11.Cu")
		(net "P5E_CPU1_PE1_RX_DP<14>")
	)
	(segment
		(start 105.248964 -219.18168)
		(end 105.242868 -219.178124)
		(width 0.0889)
		(layer "In11.Cu")
		(net "P5E_CPU1_PE1_RX_DP<14>")
	)
	(segment
		(start 105.687876 -220.590872)
		(end 105.766108 -220.6117)
		(width 0.0889)
		(layer "In11.Cu")
		(net "P5E_CPU1_PE1_RX_DP<14>")
	)
	(segment
		(start 103.984806 -213.063328)
		(end 103.984806 -213.04123)
		(width 0.0889)
		(layer "In11.Cu")
		(net "P5E_CPU1_PE1_RX_DP<14>")
	)
	(segment
		(start 20.1549 -15.105634)
		(end 20.335494 -15.008352)
		(width 0.14732)
		(layer "In11.Cu")
		(net "P5E_CPU1_PE1_RX_DP<14>")
	)
	(segment
		(start 20.335494 -15.008352)
		(end 20.565872 -14.239748)
		(width 0.14732)
		(layer "In11.Cu")
		(net "P5E_CPU1_PE1_RX_DP<14>")
	)
	(segment
		(start 105.719626 -219.996004)
		(end 105.71861 -219.995496)
		(width 0.0889)
		(layer "In11.Cu")
		(net "P5E_CPU1_PE1_RX_DP<14>")
	)
	(segment
		(start 104.026716 -213.105238)
		(end 103.984806 -213.063328)
		(width 0.0889)
		(layer "In11.Cu")
		(net "P5E_CPU1_PE1_RX_DP<14>")
	)
	(segment
		(start 105.7275 -220.000576)
		(end 105.719626 -219.996004)
		(width 0.0889)
		(layer "In11.Cu")
		(net "P5E_CPU1_PE1_RX_DP<14>")
	)
	(segment
		(start 20.048982 -15.458694)
		(end 20.1549 -15.105634)
		(width 0.14732)
		(layer "In11.Cu")
		(net "P5E_CPU1_PE1_RX_DP<14>")
	)
	(segment
		(start 104.966262 -217.072972)
		(end 104.966262 -217.0557)
		(width 0.0889)
		(layer "In11.Cu")
		(net "P5E_CPU1_PE1_RX_DP<14>")
	)
	(segment
		(start 19.947128 -18.458688)
		(end 19.67992 -17.813274)
		(width 0.14732)
		(layer "In11.Cu")
		(net "P5E_CPU1_PE1_RX_DP<14>")
	)
	(segment
		(start 103.984806 -213.04123)
		(end 103.984806 -209.02549)
		(width 0.14732)
		(layer "In11.Cu")
		(net "P5E_CPU1_PE1_RX_DP<14>")
	)
	(segment
		(start 104.496616 -217.8939)
		(end 104.496616 -217.859864)
		(width 0.0889)
		(layer "In11.Cu")
		(net "P5E_CPU1_PE1_RX_DP<14>")
	)
	(segment
		(start 50.627788 -61.440314)
		(end 20.462748 -18.974054)
		(width 0.14732)
		(layer "In11.Cu")
		(net "P5E_CPU1_PE1_RX_DP<14>")
	)
	(segment
		(start 20.468844 -14.059408)
		(end 20.574508 -13.706348)
		(width 0.14732)
		(layer "In11.Cu")
		(net "P5E_CPU1_PE1_RX_DP<14>")
	)
	(segment
		(start 19.67992 -17.813274)
		(end 19.67992 -17.194022)
		(width 0.14732)
		(layer "In11.Cu")
		(net "P5E_CPU1_PE1_RX_DP<14>")
	)
	(segment
		(start 103.984806 -209.02549)
		(end 100.374196 -181.5338)
		(width 0.14732)
		(layer "In11.Cu")
		(net "P5E_CPU1_PE1_RX_DP<14>")
	)
	(segment
		(start 20.14601 -15.638526)
		(end 20.048982 -15.458694)
		(width 0.14732)
		(layer "In11.Cu")
		(net "P5E_CPU1_PE1_RX_DP<14>")
	)
	(segment
		(start 20.755102 -13.60932)
		(end 21.09724 -12.46759)
		(width 0.14732)
		(layer "In11.Cu")
		(net "P5E_CPU1_PE1_RX_DP<14>")
	)
	(segment
		(start 105.436416 -219.521532)
		(end 105.436416 -219.506038)
		(width 0.0889)
		(layer "In11.Cu")
		(net "P5E_CPU1_PE1_RX_DP<14>")
	)
	(segment
		(start 105.257854 -219.18676)
		(end 105.248964 -219.18168)
		(width 0.0889)
		(layer "In11.Cu")
		(net "P5E_CPU1_PE1_RX_DP<14>")
	)
	(segment
		(start 21.116036 -12.340082)
		(end 21.116036 -5.257292)
		(width 0.14732)
		(layer "In11.Cu")
		(net "P5E_CPU1_PE1_RX_DP<14>")
	)
	(segment
		(start 105.531412 -220.319854)
		(end 105.687876 -220.590872)
		(width 0.0889)
		(layer "In11.Cu")
		(net "P5E_CPU1_PE1_RX_DP<14>")
	)
	(segment
		(start 20.462748 -18.974054)
		(end 19.947128 -18.458688)
		(width 0.14732)
		(layer "In11.Cu")
		(net "P5E_CPU1_PE1_RX_DP<14>")
	)
	(segment
		(start 104.026462 -215.436704)
		(end 104.026462 -215.414606)
		(width 0.0889)
		(layer "In11.Cu")
		(net "P5E_CPU1_PE1_RX_DP<14>")
	)
	(segment
		(start 100.374196 -181.5338)
		(end 50.627788 -61.440314)
		(width 0.14732)
		(layer "In11.Cu")
		(net "P5E_CPU1_PE1_RX_DP<14>")
	)
	(segment
		(start 104.496616 -216.260426)
		(end 104.496616 -216.25052)
		(width 0.0889)
		(layer "In11.Cu")
		(net "P5E_CPU1_PE1_RX_DP<14>")
	)
	(segment
		(start 104.496108 -214.622634)
		(end 104.496108 -214.461344)
		(width 0.0889)
		(layer "In11.Cu")
		(net "P5E_CPU1_PE1_RX_DP<14>")
	)
	(segment
		(start 20.565872 -14.239748)
		(end 20.468844 -14.059408)
		(width 0.14732)
		(layer "In11.Cu")
		(net "P5E_CPU1_PE1_RX_DP<14>")
	)
	(segment
		(start 104.310688 -215.926924)
		(end 104.309164 -215.926162)
		(width 0.0889)
		(layer "In11.Cu")
		(net "P5E_CPU1_PE1_RX_DP<14>")
	)
	(segment
		(start 21.116036 -5.257292)
		(end 20.821396 -4.962652)
		(width 0.14732)
		(layer "In11.Cu")
		(net "P5E_CPU1_PE1_RX_DP<14>")
	)
	(arc
		(start 105.242868 -219.178124)
		(mid 105.040281 -218.971773)
		(end 104.966262 -218.692222)
		(width 0.0889)
		(layer "In11.Cu")
		(net "P5E_CPU1_PE1_RX_DP<14>")
	)
	(arc
		(start 104.311958 -214.261954)
		(mid 104.137995 -214.12319)
		(end 104.026716 -213.930484)
		(width 0.0889)
		(layer "In11.Cu")
		(net "P5E_CPU1_PE1_RX_DP<14>")
	)
	(arc
		(start 105.906062 -220.319854)
		(mid 105.858383 -220.136954)
		(end 105.7275 -220.000576)
		(width 0.0889)
		(layer "In11.Cu")
		(net "P5E_CPU1_PE1_RX_DP<14>")
	)
	(arc
		(start 104.77881 -218.367864)
		(mid 104.575987 -218.167633)
		(end 104.496616 -217.8939)
		(width 0.0889)
		(layer "In11.Cu")
		(net "P5E_CPU1_PE1_RX_DP<14>")
	)
	(arc
		(start 104.303068 -215.922606)
		(mid 104.100481 -215.716255)
		(end 104.026462 -215.436704)
		(width 0.0889)
		(layer "In11.Cu")
		(net "P5E_CPU1_PE1_RX_DP<14>")
	)
	(arc
		(start 105.71861 -219.995496)
		(mid 105.515787 -219.795265)
		(end 105.436416 -219.521532)
		(width 0.0889)
		(layer "In11.Cu")
		(net "P5E_CPU1_PE1_RX_DP<14>")
	)
	(arc
		(start 104.496616 -216.25052)
		(mid 104.448937 -216.06762)
		(end 104.318054 -215.931242)
		(width 0.0889)
		(layer "In11.Cu")
		(net "P5E_CPU1_PE1_RX_DP<14>")
	)
	(arc
		(start 104.779064 -216.739978)
		(mid 104.574729 -216.537373)
		(end 104.496616 -216.260426)
		(width 0.0889)
		(layer "In11.Cu")
		(net "P5E_CPU1_PE1_RX_DP<14>")
	)
	(arc
		(start 105.436416 -219.506038)
		(mid 105.388737 -219.323138)
		(end 105.257854 -219.18676)
		(width 0.0889)
		(layer "In11.Cu")
		(net "P5E_CPU1_PE1_RX_DP<14>")
	)
	(arc
		(start 105.766108 -220.6117)
		(mid 105.869253 -220.481675)
		(end 105.906062 -220.319854)
		(width 0.0889)
		(layer "In11.Cu")
		(net "P5E_CPU1_PE1_RX_DP<14>")
	)
	(arc
		(start 104.496108 -214.461344)
		(mid 104.421103 -214.345885)
		(end 104.311958 -214.261954)
		(width 0.0889)
		(layer "In11.Cu")
		(net "P5E_CPU1_PE1_RX_DP<14>")
	)
	(arc
		(start 104.496616 -217.859864)
		(mid 104.576778 -217.587675)
		(end 104.779064 -217.388694)
		(width 0.0889)
		(layer "In11.Cu")
		(net "P5E_CPU1_PE1_RX_DP<14>")
	)
	(arc
		(start 104.966262 -218.692222)
		(mid 104.918583 -218.509322)
		(end 104.7877 -218.372944)
		(width 0.0889)
		(layer "In11.Cu")
		(net "P5E_CPU1_PE1_RX_DP<14>")
	)
	(arc
		(start 104.317546 -214.941912)
		(mid 104.44846 -214.805552)
		(end 104.496108 -214.622634)
		(width 0.0889)
		(layer "In11.Cu")
		(net "P5E_CPU1_PE1_RX_DP<14>")
	)
	(arc
		(start 104.966262 -217.0557)
		(mid 104.913992 -216.873335)
		(end 104.779064 -216.739978)
		(width 0.0889)
		(layer "In11.Cu")
		(net "P5E_CPU1_PE1_RX_DP<14>")
	)
	(arc
		(start 104.779064 -217.388694)
		(mid 104.913997 -217.25534)
		(end 104.966262 -217.072972)
		(width 0.0889)
		(layer "In11.Cu")
		(net "P5E_CPU1_PE1_RX_DP<14>")
	)
	(arc
		(start 104.026462 -215.414606)
		(mid 104.107373 -215.144478)
		(end 104.308656 -214.946992)
		(width 0.0889)
		(layer "In11.Cu")
		(net "P5E_CPU1_PE1_RX_DP<14>")
	)
	(segment
		(start 106.941112 -221.134178)
		(end 106.941366 -221.133924)
		(width 0.13208)
		(layer "F.Cu")
		(net "P5E_CPU1_PE1_RX_DP<13>")
	)
	(segment
		(start 22.74697 -7.795514)
		(end 22.918928 -7.623556)
		(width 0.13208)
		(layer "F.Cu")
		(net "P5E_CPU1_PE1_RX_DP<13>")
	)
	(segment
		(start 22.74697 -8.320024)
		(end 22.74697 -7.795514)
		(width 0.13208)
		(layer "F.Cu")
		(net "P5E_CPU1_PE1_RX_DP<13>")
	)
	(segment
		(start 106.941112 -221.669864)
		(end 106.941112 -221.134178)
		(width 0.13208)
		(layer "F.Cu")
		(net "P5E_CPU1_PE1_RX_DP<13>")
	)
	(segment
		(start 22.918928 -7.623556)
		(end 22.918928 -7.026656)
		(width 0.13208)
		(layer "F.Cu")
		(net "P5E_CPU1_PE1_RX_DP<13>")
	)
	(segment
		(start 22.918928 -7.026656)
		(end 22.616668 -6.724396)
		(width 0.13208)
		(layer "F.Cu")
		(net "P5E_CPU1_PE1_RX_DP<13>")
	)
	(segment
		(start 22.4663 -19.375628)
		(end 22.4663 -18.88998)
		(width 0.14732)
		(layer "In11.Cu")
		(net "P5E_CPU1_PE1_RX_DP<13>")
	)
	(segment
		(start 104.92486 -213.063328)
		(end 104.92486 -213.04123)
		(width 0.0889)
		(layer "In11.Cu")
		(net "P5E_CPU1_PE1_RX_DP<13>")
	)
	(segment
		(start 105.248456 -214.946992)
		(end 105.257346 -214.941912)
		(width 0.0889)
		(layer "In11.Cu")
		(net "P5E_CPU1_PE1_RX_DP<13>")
	)
	(segment
		(start 104.92486 -213.04123)
		(end 104.92486 -208.961736)
		(width 0.14732)
		(layer "In11.Cu")
		(net "P5E_CPU1_PE1_RX_DP<13>")
	)
	(segment
		(start 22.65045 -19.820636)
		(end 22.4663 -19.375628)
		(width 0.14732)
		(layer "In11.Cu")
		(net "P5E_CPU1_PE1_RX_DP<13>")
	)
	(segment
		(start 101.298502 -181.352952)
		(end 101.247448 -181.162452)
		(width 0.14732)
		(layer "In11.Cu")
		(net "P5E_CPU1_PE1_RX_DP<13>")
	)
	(segment
		(start 23.25624 -17.715738)
		(end 23.25624 -16.975328)
		(width 0.14732)
		(layer "In11.Cu")
		(net "P5E_CPU1_PE1_RX_DP<13>")
	)
	(segment
		(start 23.041102 -16.119602)
		(end 23.01113 -15.752318)
		(width 0.14732)
		(layer "In11.Cu")
		(net "P5E_CPU1_PE1_RX_DP<13>")
	)
	(segment
		(start 106.784902 -221.404942)
		(end 106.805984 -221.48292)
		(width 0.0889)
		(layer "In11.Cu")
		(net "P5E_CPU1_PE1_RX_DP<13>")
	)
	(segment
		(start 105.7275 -216.745058)
		(end 105.719626 -216.740486)
		(width 0.0889)
		(layer "In11.Cu")
		(net "P5E_CPU1_PE1_RX_DP<13>")
	)
	(segment
		(start 22.911308 -7.019036)
		(end 22.616668 -6.724396)
		(width 0.14732)
		(layer "In11.Cu")
		(net "P5E_CPU1_PE1_RX_DP<13>")
	)
	(segment
		(start 23.197312 -16.25219)
		(end 23.041102 -16.119602)
		(width 0.14732)
		(layer "In11.Cu")
		(net "P5E_CPU1_PE1_RX_DP<13>")
	)
	(segment
		(start 23.030434 -14.206474)
		(end 22.874224 -14.073886)
		(width 0.14732)
		(layer "In11.Cu")
		(net "P5E_CPU1_PE1_RX_DP<13>")
	)
	(segment
		(start 22.4663 -18.88998)
		(end 22.596602 -18.57502)
		(width 0.14732)
		(layer "In11.Cu")
		(net "P5E_CPU1_PE1_RX_DP<13>")
	)
	(segment
		(start 105.436416 -216.266014)
		(end 105.436416 -216.25052)
		(width 0.0889)
		(layer "In11.Cu")
		(net "P5E_CPU1_PE1_RX_DP<13>")
	)
	(segment
		(start 107.128564 -221.458282)
		(end 107.130088 -221.45752)
		(width 0.0889)
		(layer "In11.Cu")
		(net "P5E_CPU1_PE1_RX_DP<13>")
	)
	(segment
		(start 106.376216 -219.515944)
		(end 106.376216 -219.506038)
		(width 0.0889)
		(layer "In11.Cu")
		(net "P5E_CPU1_PE1_RX_DP<13>")
	)
	(segment
		(start 106.197654 -219.18676)
		(end 106.188764 -219.18168)
		(width 0.0889)
		(layer "In11.Cu")
		(net "P5E_CPU1_PE1_RX_DP<13>")
	)
	(segment
		(start 101.247448 -181.162452)
		(end 51.397154 -60.818268)
		(width 0.14732)
		(layer "In11.Cu")
		(net "P5E_CPU1_PE1_RX_DP<13>")
	)
	(segment
		(start 23.25624 -16.975328)
		(end 23.197312 -16.25219)
		(width 0.14732)
		(layer "In11.Cu")
		(net "P5E_CPU1_PE1_RX_DP<13>")
	)
	(segment
		(start 104.96677 -213.929468)
		(end 104.96677 -213.105238)
		(width 0.0889)
		(layer "In11.Cu")
		(net "P5E_CPU1_PE1_RX_DP<13>")
	)
	(segment
		(start 22.927818 -14.72946)
		(end 23.060152 -14.573504)
		(width 0.14732)
		(layer "In11.Cu")
		(net "P5E_CPU1_PE1_RX_DP<13>")
	)
	(segment
		(start 105.719626 -216.740486)
		(end 105.71861 -216.739978)
		(width 0.0889)
		(layer "In11.Cu")
		(net "P5E_CPU1_PE1_RX_DP<13>")
	)
	(segment
		(start 105.435908 -214.622634)
		(end 105.435908 -214.461344)
		(width 0.0889)
		(layer "In11.Cu")
		(net "P5E_CPU1_PE1_RX_DP<13>")
	)
	(segment
		(start 22.911308 -12.743688)
		(end 22.911308 -7.019036)
		(width 0.14732)
		(layer "In11.Cu")
		(net "P5E_CPU1_PE1_RX_DP<13>")
	)
	(segment
		(start 23.114 -15.229332)
		(end 22.957536 -15.096744)
		(width 0.14732)
		(layer "In11.Cu")
		(net "P5E_CPU1_PE1_RX_DP<13>")
	)
	(segment
		(start 104.966262 -215.436704)
		(end 104.966262 -215.414606)
		(width 0.0889)
		(layer "In11.Cu")
		(net "P5E_CPU1_PE1_RX_DP<13>")
	)
	(segment
		(start 106.845862 -220.334078)
		(end 106.845862 -220.311218)
		(width 0.0889)
		(layer "In11.Cu")
		(net "P5E_CPU1_PE1_RX_DP<13>")
	)
	(segment
		(start 105.71861 -217.388694)
		(end 105.7275 -217.383614)
		(width 0.0889)
		(layer "In11.Cu")
		(net "P5E_CPU1_PE1_RX_DP<13>")
	)
	(segment
		(start 23.114508 -18.057368)
		(end 23.25624 -17.715738)
		(width 0.14732)
		(layer "In11.Cu")
		(net "P5E_CPU1_PE1_RX_DP<13>")
	)
	(segment
		(start 107.137454 -220.814646)
		(end 107.128564 -220.809566)
		(width 0.0889)
		(layer "In11.Cu")
		(net "P5E_CPU1_PE1_RX_DP<13>")
	)
	(segment
		(start 23.060152 -14.573504)
		(end 23.030434 -14.206474)
		(width 0.14732)
		(layer "In11.Cu")
		(net "P5E_CPU1_PE1_RX_DP<13>")
	)
	(segment
		(start 22.874224 -14.073886)
		(end 22.844252 -13.706602)
		(width 0.14732)
		(layer "In11.Cu")
		(net "P5E_CPU1_PE1_RX_DP<13>")
	)
	(segment
		(start 104.96677 -213.105238)
		(end 104.92486 -213.063328)
		(width 0.0889)
		(layer "In11.Cu")
		(net "P5E_CPU1_PE1_RX_DP<13>")
	)
	(segment
		(start 107.130088 -221.45752)
		(end 107.137454 -221.453202)
		(width 0.0889)
		(layer "In11.Cu")
		(net "P5E_CPU1_PE1_RX_DP<13>")
	)
	(segment
		(start 105.257854 -215.931242)
		(end 105.248964 -215.926162)
		(width 0.0889)
		(layer "In11.Cu")
		(net "P5E_CPU1_PE1_RX_DP<13>")
	)
	(segment
		(start 51.397154 -60.818268)
		(end 22.65045 -19.820636)
		(width 0.14732)
		(layer "In11.Cu")
		(net "P5E_CPU1_PE1_RX_DP<13>")
	)
	(segment
		(start 105.248964 -215.926162)
		(end 105.242868 -215.922606)
		(width 0.0889)
		(layer "In11.Cu")
		(net "P5E_CPU1_PE1_RX_DP<13>")
	)
	(segment
		(start 22.97684 -13.550646)
		(end 22.911308 -12.743688)
		(width 0.14732)
		(layer "In11.Cu")
		(net "P5E_CPU1_PE1_RX_DP<13>")
	)
	(segment
		(start 22.957536 -15.096744)
		(end 22.927818 -14.72946)
		(width 0.14732)
		(layer "In11.Cu")
		(net "P5E_CPU1_PE1_RX_DP<13>")
	)
	(segment
		(start 106.941366 -221.133924)
		(end 106.784902 -221.404942)
		(width 0.0889)
		(layer "In11.Cu")
		(net "P5E_CPU1_PE1_RX_DP<13>")
	)
	(segment
		(start 23.01113 -15.752318)
		(end 23.143718 -15.596362)
		(width 0.14732)
		(layer "In11.Cu")
		(net "P5E_CPU1_PE1_RX_DP<13>")
	)
	(segment
		(start 23.143718 -15.596362)
		(end 23.114 -15.229332)
		(width 0.14732)
		(layer "In11.Cu")
		(net "P5E_CPU1_PE1_RX_DP<13>")
	)
	(segment
		(start 105.436416 -217.8939)
		(end 105.436416 -217.856308)
		(width 0.0889)
		(layer "In11.Cu")
		(net "P5E_CPU1_PE1_RX_DP<13>")
	)
	(segment
		(start 104.92486 -208.961736)
		(end 101.298502 -181.352952)
		(width 0.14732)
		(layer "In11.Cu")
		(net "P5E_CPU1_PE1_RX_DP<13>")
	)
	(segment
		(start 22.596602 -18.57502)
		(end 23.114508 -18.057368)
		(width 0.14732)
		(layer "In11.Cu")
		(net "P5E_CPU1_PE1_RX_DP<13>")
	)
	(segment
		(start 105.251758 -214.261954)
		(end 105.252012 -214.2617)
		(width 0.0889)
		(layer "In11.Cu")
		(net "P5E_CPU1_PE1_RX_DP<13>")
	)
	(segment
		(start 106.188764 -219.18168)
		(end 106.182668 -219.178124)
		(width 0.0889)
		(layer "In11.Cu")
		(net "P5E_CPU1_PE1_RX_DP<13>")
	)
	(segment
		(start 105.7275 -218.372944)
		(end 105.71861 -218.367864)
		(width 0.0889)
		(layer "In11.Cu")
		(net "P5E_CPU1_PE1_RX_DP<13>")
	)
	(segment
		(start 22.844252 -13.706602)
		(end 22.97684 -13.550646)
		(width 0.14732)
		(layer "In11.Cu")
		(net "P5E_CPU1_PE1_RX_DP<13>")
	)
	(arc
		(start 105.242868 -215.922606)
		(mid 105.040281 -215.716255)
		(end 104.966262 -215.436704)
		(width 0.0889)
		(layer "In11.Cu")
		(net "P5E_CPU1_PE1_RX_DP<13>")
	)
	(arc
		(start 107.128564 -220.809566)
		(mid 106.925083 -220.608762)
		(end 106.845862 -220.334078)
		(width 0.0889)
		(layer "In11.Cu")
		(net "P5E_CPU1_PE1_RX_DP<13>")
	)
	(arc
		(start 107.137454 -221.453202)
		(mid 107.316051 -221.133924)
		(end 107.137454 -220.814646)
		(width 0.0889)
		(layer "In11.Cu")
		(net "P5E_CPU1_PE1_RX_DP<13>")
	)
	(arc
		(start 105.252012 -214.2617)
		(mid 105.077921 -214.122606)
		(end 104.96677 -213.929468)
		(width 0.0889)
		(layer "In11.Cu")
		(net "P5E_CPU1_PE1_RX_DP<13>")
	)
	(arc
		(start 105.906062 -218.692222)
		(mid 105.858383 -218.509322)
		(end 105.7275 -218.372944)
		(width 0.0889)
		(layer "In11.Cu")
		(net "P5E_CPU1_PE1_RX_DP<13>")
	)
	(arc
		(start 105.436416 -217.856308)
		(mid 105.517327 -217.58618)
		(end 105.71861 -217.388694)
		(width 0.0889)
		(layer "In11.Cu")
		(net "P5E_CPU1_PE1_RX_DP<13>")
	)
	(arc
		(start 106.182668 -219.178124)
		(mid 105.980081 -218.971773)
		(end 105.906062 -218.692222)
		(width 0.0889)
		(layer "In11.Cu")
		(net "P5E_CPU1_PE1_RX_DP<13>")
	)
	(arc
		(start 106.845862 -220.311218)
		(mid 106.793592 -220.128853)
		(end 106.658664 -219.995496)
		(width 0.0889)
		(layer "In11.Cu")
		(net "P5E_CPU1_PE1_RX_DP<13>")
	)
	(arc
		(start 105.436416 -216.25052)
		(mid 105.388737 -216.06762)
		(end 105.257854 -215.931242)
		(width 0.0889)
		(layer "In11.Cu")
		(net "P5E_CPU1_PE1_RX_DP<13>")
	)
	(arc
		(start 105.435908 -214.461344)
		(mid 105.360903 -214.345885)
		(end 105.251758 -214.261954)
		(width 0.0889)
		(layer "In11.Cu")
		(net "P5E_CPU1_PE1_RX_DP<13>")
	)
	(arc
		(start 104.966262 -215.414606)
		(mid 105.047173 -215.144478)
		(end 105.248456 -214.946992)
		(width 0.0889)
		(layer "In11.Cu")
		(net "P5E_CPU1_PE1_RX_DP<13>")
	)
	(arc
		(start 105.71861 -218.367864)
		(mid 105.515787 -218.167633)
		(end 105.436416 -217.8939)
		(width 0.0889)
		(layer "In11.Cu")
		(net "P5E_CPU1_PE1_RX_DP<13>")
	)
	(arc
		(start 106.658664 -219.995496)
		(mid 106.454329 -219.792891)
		(end 106.376216 -219.515944)
		(width 0.0889)
		(layer "In11.Cu")
		(net "P5E_CPU1_PE1_RX_DP<13>")
	)
	(arc
		(start 105.7275 -217.383614)
		(mid 105.906097 -217.064336)
		(end 105.7275 -216.745058)
		(width 0.0889)
		(layer "In11.Cu")
		(net "P5E_CPU1_PE1_RX_DP<13>")
	)
	(arc
		(start 105.71861 -216.739978)
		(mid 105.515787 -216.539747)
		(end 105.436416 -216.266014)
		(width 0.0889)
		(layer "In11.Cu")
		(net "P5E_CPU1_PE1_RX_DP<13>")
	)
	(arc
		(start 106.805984 -221.48292)
		(mid 106.97008 -221.507267)
		(end 107.128564 -221.458282)
		(width 0.0889)
		(layer "In11.Cu")
		(net "P5E_CPU1_PE1_RX_DP<13>")
	)
	(arc
		(start 105.257346 -214.941912)
		(mid 105.38826 -214.805552)
		(end 105.435908 -214.622634)
		(width 0.0889)
		(layer "In11.Cu")
		(net "P5E_CPU1_PE1_RX_DP<13>")
	)
	(arc
		(start 106.376216 -219.506038)
		(mid 106.328537 -219.323138)
		(end 106.197654 -219.18676)
		(width 0.0889)
		(layer "In11.Cu")
		(net "P5E_CPU1_PE1_RX_DP<13>")
	)
	(segment
		(start 107.411012 -220.85554)
		(end 107.411012 -220.319854)
		(width 0.13208)
		(layer "F.Cu")
		(net "P5E_CPU1_PE1_RX_DP<12>")
	)
	(segment
		(start 24.722582 -5.263896)
		(end 24.421338 -4.962652)
		(width 0.13208)
		(layer "F.Cu")
		(net "P5E_CPU1_PE1_RX_DP<12>")
	)
	(segment
		(start 107.411266 -220.855794)
		(end 107.411012 -220.85554)
		(width 0.13208)
		(layer "F.Cu")
		(net "P5E_CPU1_PE1_RX_DP<12>")
	)
	(segment
		(start 24.547068 -7.786116)
		(end 24.722582 -7.610602)
		(width 0.13208)
		(layer "F.Cu")
		(net "P5E_CPU1_PE1_RX_DP<12>")
	)
	(segment
		(start 24.547068 -8.320024)
		(end 24.547068 -7.786116)
		(width 0.13208)
		(layer "F.Cu")
		(net "P5E_CPU1_PE1_RX_DP<12>")
	)
	(segment
		(start 24.722582 -7.610602)
		(end 24.722582 -5.263896)
		(width 0.13208)
		(layer "F.Cu")
		(net "P5E_CPU1_PE1_RX_DP<12>")
	)
	(segment
		(start 106.376216 -217.8939)
		(end 106.376216 -217.859864)
		(width 0.0889)
		(layer "In11.Cu")
		(net "P5E_CPU1_PE1_RX_DP<12>")
	)
	(segment
		(start 102.230174 -181.230524)
		(end 102.122478 -180.808122)
		(width 0.14732)
		(layer "In11.Cu")
		(net "P5E_CPU1_PE1_RX_DP<12>")
	)
	(segment
		(start 25.094946 -17.61363)
		(end 25.013158 -16.440912)
		(width 0.14732)
		(layer "In11.Cu")
		(net "P5E_CPU1_PE1_RX_DP<12>")
	)
	(segment
		(start 105.94975 -213.990682)
		(end 105.923842 -213.924642)
		(width 0.0889)
		(layer "In11.Cu")
		(net "P5E_CPU1_PE1_RX_DP<12>")
	)
	(segment
		(start 25.717754 -18.509488)
		(end 25.461722 -18.252948)
		(width 0.14732)
		(layer "In11.Cu")
		(net "P5E_CPU1_PE1_RX_DP<12>")
	)
	(segment
		(start 106.376216 -216.260426)
		(end 106.376216 -216.25052)
		(width 0.0889)
		(layer "In11.Cu")
		(net "P5E_CPU1_PE1_RX_DP<12>")
	)
	(segment
		(start 107.137454 -219.18676)
		(end 107.128564 -219.18168)
		(width 0.0889)
		(layer "In11.Cu")
		(net "P5E_CPU1_PE1_RX_DP<12>")
	)
	(segment
		(start 24.722836 -14.369796)
		(end 24.857202 -14.215364)
		(width 0.14732)
		(layer "In11.Cu")
		(net "P5E_CPU1_PE1_RX_DP<12>")
	)
	(segment
		(start 105.864406 -208.900014)
		(end 102.230174 -181.230524)
		(width 0.14732)
		(layer "In11.Cu")
		(net "P5E_CPU1_PE1_RX_DP<12>")
	)
	(segment
		(start 106.6673 -218.372944)
		(end 106.65841 -218.367864)
		(width 0.0889)
		(layer "In11.Cu")
		(net "P5E_CPU1_PE1_RX_DP<12>")
	)
	(segment
		(start 24.832818 -15.939008)
		(end 24.96693 -15.784322)
		(width 0.14732)
		(layer "In11.Cu")
		(net "P5E_CPU1_PE1_RX_DP<12>")
	)
	(segment
		(start 106.188256 -214.946992)
		(end 106.197146 -214.941912)
		(width 0.0889)
		(layer "In11.Cu")
		(net "P5E_CPU1_PE1_RX_DP<12>")
	)
	(segment
		(start 25.461722 -18.252948)
		(end 25.094946 -17.61363)
		(width 0.14732)
		(layer "In11.Cu")
		(net "P5E_CPU1_PE1_RX_DP<12>")
	)
	(segment
		(start 102.122478 -180.808122)
		(end 52.244752 -60.397898)
		(width 0.14732)
		(layer "In11.Cu")
		(net "P5E_CPU1_PE1_RX_DP<12>")
	)
	(segment
		(start 24.715978 -5.257292)
		(end 24.421338 -4.962652)
		(width 0.14732)
		(layer "In11.Cu")
		(net "P5E_CPU1_PE1_RX_DP<12>")
	)
	(segment
		(start 107.316016 -219.521532)
		(end 107.316016 -219.506038)
		(width 0.0889)
		(layer "In11.Cu")
		(net "P5E_CPU1_PE1_RX_DP<12>")
	)
	(segment
		(start 24.90343 -14.871954)
		(end 24.74849 -14.737588)
		(width 0.14732)
		(layer "In11.Cu")
		(net "P5E_CPU1_PE1_RX_DP<12>")
	)
	(segment
		(start 106.375708 -214.622634)
		(end 106.375708 -214.472266)
		(width 0.0889)
		(layer "In11.Cu")
		(net "P5E_CPU1_PE1_RX_DP<12>")
	)
	(segment
		(start 105.906316 -213.830662)
		(end 105.906316 -213.105238)
		(width 0.0889)
		(layer "In11.Cu")
		(net "P5E_CPU1_PE1_RX_DP<12>")
	)
	(segment
		(start 105.864406 -213.063328)
		(end 105.864406 -213.04123)
		(width 0.0889)
		(layer "In11.Cu")
		(net "P5E_CPU1_PE1_RX_DP<12>")
	)
	(segment
		(start 24.715978 -12.177268)
		(end 24.715978 -5.257292)
		(width 0.14732)
		(layer "In11.Cu")
		(net "P5E_CPU1_PE1_RX_DP<12>")
	)
	(segment
		(start 25.013158 -16.440912)
		(end 24.858472 -16.306546)
		(width 0.14732)
		(layer "In11.Cu")
		(net "P5E_CPU1_PE1_RX_DP<12>")
	)
	(segment
		(start 107.567476 -220.590872)
		(end 107.645708 -220.6117)
		(width 0.0889)
		(layer "In11.Cu")
		(net "P5E_CPU1_PE1_RX_DP<12>")
	)
	(segment
		(start 106.188764 -215.926162)
		(end 106.182668 -215.922606)
		(width 0.0889)
		(layer "In11.Cu")
		(net "P5E_CPU1_PE1_RX_DP<12>")
	)
	(segment
		(start 105.864406 -213.04123)
		(end 105.864406 -208.900014)
		(width 0.14732)
		(layer "In11.Cu")
		(net "P5E_CPU1_PE1_RX_DP<12>")
	)
	(segment
		(start 52.244752 -60.397898)
		(end 25.717754 -18.509488)
		(width 0.14732)
		(layer "In11.Cu")
		(net "P5E_CPU1_PE1_RX_DP<12>")
	)
	(segment
		(start 24.74849 -14.737588)
		(end 24.722836 -14.369796)
		(width 0.14732)
		(layer "In11.Cu")
		(net "P5E_CPU1_PE1_RX_DP<12>")
	)
	(segment
		(start 105.906316 -213.105238)
		(end 105.864406 -213.063328)
		(width 0.0889)
		(layer "In11.Cu")
		(net "P5E_CPU1_PE1_RX_DP<12>")
	)
	(segment
		(start 24.716486 -12.196318)
		(end 24.715978 -12.177268)
		(width 0.14732)
		(layer "In11.Cu")
		(net "P5E_CPU1_PE1_RX_DP<12>")
	)
	(segment
		(start 107.411012 -220.319854)
		(end 107.567476 -220.590872)
		(width 0.0889)
		(layer "In11.Cu")
		(net "P5E_CPU1_PE1_RX_DP<12>")
	)
	(segment
		(start 107.128564 -219.18168)
		(end 107.122468 -219.178124)
		(width 0.0889)
		(layer "In11.Cu")
		(net "P5E_CPU1_PE1_RX_DP<12>")
	)
	(segment
		(start 106.197654 -215.931242)
		(end 106.188764 -215.926162)
		(width 0.0889)
		(layer "In11.Cu")
		(net "P5E_CPU1_PE1_RX_DP<12>")
	)
	(segment
		(start 105.906062 -215.436704)
		(end 105.906062 -215.414606)
		(width 0.0889)
		(layer "In11.Cu")
		(net "P5E_CPU1_PE1_RX_DP<12>")
	)
	(segment
		(start 107.599226 -219.996004)
		(end 107.59821 -219.995496)
		(width 0.0889)
		(layer "In11.Cu")
		(net "P5E_CPU1_PE1_RX_DP<12>")
	)
	(segment
		(start 24.858472 -16.306546)
		(end 24.832818 -15.939008)
		(width 0.14732)
		(layer "In11.Cu")
		(net "P5E_CPU1_PE1_RX_DP<12>")
	)
	(segment
		(start 107.6071 -220.000576)
		(end 107.599226 -219.996004)
		(width 0.0889)
		(layer "In11.Cu")
		(net "P5E_CPU1_PE1_RX_DP<12>")
	)
	(segment
		(start 24.96693 -15.784322)
		(end 24.90343 -14.871954)
		(width 0.14732)
		(layer "In11.Cu")
		(net "P5E_CPU1_PE1_RX_DP<12>")
	)
	(segment
		(start 106.845862 -217.072972)
		(end 106.845862 -217.0557)
		(width 0.0889)
		(layer "In11.Cu")
		(net "P5E_CPU1_PE1_RX_DP<12>")
	)
	(segment
		(start 24.857202 -14.215364)
		(end 24.716486 -12.196318)
		(width 0.14732)
		(layer "In11.Cu")
		(net "P5E_CPU1_PE1_RX_DP<12>")
	)
	(arc
		(start 106.197146 -214.941912)
		(mid 106.32806 -214.805552)
		(end 106.375708 -214.622634)
		(width 0.0889)
		(layer "In11.Cu")
		(net "P5E_CPU1_PE1_RX_DP<12>")
	)
	(arc
		(start 106.375708 -214.472266)
		(mid 106.374228 -214.459899)
		(end 106.37012 -214.448136)
		(width 0.0889)
		(layer "In11.Cu")
		(net "P5E_CPU1_PE1_RX_DP<12>")
	)
	(arc
		(start 106.658664 -216.739978)
		(mid 106.454329 -216.537373)
		(end 106.376216 -216.260426)
		(width 0.0889)
		(layer "In11.Cu")
		(net "P5E_CPU1_PE1_RX_DP<12>")
	)
	(arc
		(start 106.376216 -216.25052)
		(mid 106.328537 -216.06762)
		(end 106.197654 -215.931242)
		(width 0.0889)
		(layer "In11.Cu")
		(net "P5E_CPU1_PE1_RX_DP<12>")
	)
	(arc
		(start 106.376216 -217.859864)
		(mid 106.456378 -217.587675)
		(end 106.658664 -217.388694)
		(width 0.0889)
		(layer "In11.Cu")
		(net "P5E_CPU1_PE1_RX_DP<12>")
	)
	(arc
		(start 105.906062 -215.414606)
		(mid 105.986973 -215.144478)
		(end 106.188256 -214.946992)
		(width 0.0889)
		(layer "In11.Cu")
		(net "P5E_CPU1_PE1_RX_DP<12>")
	)
	(arc
		(start 106.845862 -217.0557)
		(mid 106.793592 -216.873335)
		(end 106.658664 -216.739978)
		(width 0.0889)
		(layer "In11.Cu")
		(net "P5E_CPU1_PE1_RX_DP<12>")
	)
	(arc
		(start 107.59821 -219.995496)
		(mid 107.395387 -219.795265)
		(end 107.316016 -219.521532)
		(width 0.0889)
		(layer "In11.Cu")
		(net "P5E_CPU1_PE1_RX_DP<12>")
	)
	(arc
		(start 106.37012 -214.448136)
		(mid 106.296064 -214.34048)
		(end 106.191812 -214.2617)
		(width 0.0889)
		(layer "In11.Cu")
		(net "P5E_CPU1_PE1_RX_DP<12>")
	)
	(arc
		(start 107.785662 -220.319854)
		(mid 107.737983 -220.136954)
		(end 107.6071 -220.000576)
		(width 0.0889)
		(layer "In11.Cu")
		(net "P5E_CPU1_PE1_RX_DP<12>")
	)
	(arc
		(start 106.845862 -218.692222)
		(mid 106.798183 -218.509322)
		(end 106.6673 -218.372944)
		(width 0.0889)
		(layer "In11.Cu")
		(net "P5E_CPU1_PE1_RX_DP<12>")
	)
	(arc
		(start 107.122468 -219.178124)
		(mid 106.919881 -218.971773)
		(end 106.845862 -218.692222)
		(width 0.0889)
		(layer "In11.Cu")
		(net "P5E_CPU1_PE1_RX_DP<12>")
	)
	(arc
		(start 107.645708 -220.6117)
		(mid 107.748853 -220.481675)
		(end 107.785662 -220.319854)
		(width 0.0889)
		(layer "In11.Cu")
		(net "P5E_CPU1_PE1_RX_DP<12>")
	)
	(arc
		(start 106.182668 -215.922606)
		(mid 105.980081 -215.716255)
		(end 105.906062 -215.436704)
		(width 0.0889)
		(layer "In11.Cu")
		(net "P5E_CPU1_PE1_RX_DP<12>")
	)
	(arc
		(start 106.191812 -214.2617)
		(mid 106.046477 -214.147903)
		(end 105.94975 -213.990682)
		(width 0.0889)
		(layer "In11.Cu")
		(net "P5E_CPU1_PE1_RX_DP<12>")
	)
	(arc
		(start 105.923842 -213.924642)
		(mid 105.910659 -213.878476)
		(end 105.906316 -213.830662)
		(width 0.0889)
		(layer "In11.Cu")
		(net "P5E_CPU1_PE1_RX_DP<12>")
	)
	(arc
		(start 106.65841 -218.367864)
		(mid 106.455587 -218.167633)
		(end 106.376216 -217.8939)
		(width 0.0889)
		(layer "In11.Cu")
		(net "P5E_CPU1_PE1_RX_DP<12>")
	)
	(arc
		(start 106.658664 -217.388694)
		(mid 106.793597 -217.25534)
		(end 106.845862 -217.072972)
		(width 0.0889)
		(layer "In11.Cu")
		(net "P5E_CPU1_PE1_RX_DP<12>")
	)
	(arc
		(start 107.316016 -219.506038)
		(mid 107.268337 -219.323138)
		(end 107.137454 -219.18676)
		(width 0.0889)
		(layer "In11.Cu")
		(net "P5E_CPU1_PE1_RX_DP<12>")
	)
	(segment
		(start 26.346912 -7.795514)
		(end 26.51887 -7.623556)
		(width 0.13208)
		(layer "F.Cu")
		(net "P5E_CPU1_PE1_RX_DP<11>")
	)
	(segment
		(start 108.820712 -221.134178)
		(end 108.820966 -221.133924)
		(width 0.13208)
		(layer "F.Cu")
		(net "P5E_CPU1_PE1_RX_DP<11>")
	)
	(segment
		(start 26.346912 -8.320024)
		(end 26.346912 -7.795514)
		(width 0.13208)
		(layer "F.Cu")
		(net "P5E_CPU1_PE1_RX_DP<11>")
	)
	(segment
		(start 108.820712 -221.669864)
		(end 108.820712 -221.134178)
		(width 0.13208)
		(layer "F.Cu")
		(net "P5E_CPU1_PE1_RX_DP<11>")
	)
	(segment
		(start 26.51887 -7.026656)
		(end 26.21661 -6.724396)
		(width 0.13208)
		(layer "F.Cu")
		(net "P5E_CPU1_PE1_RX_DP<11>")
	)
	(segment
		(start 26.51887 -7.623556)
		(end 26.51887 -7.026656)
		(width 0.13208)
		(layer "F.Cu")
		(net "P5E_CPU1_PE1_RX_DP<11>")
	)
	(segment
		(start 26.800302 -13.354558)
		(end 26.872946 -13.163042)
		(width 0.14732)
		(layer "In11.Cu")
		(net "P5E_CPU1_PE1_RX_DP<11>")
	)
	(segment
		(start 107.6071 -216.745058)
		(end 107.599226 -216.740486)
		(width 0.0889)
		(layer "In11.Cu")
		(net "P5E_CPU1_PE1_RX_DP<11>")
	)
	(segment
		(start 109.008164 -221.458282)
		(end 109.009688 -221.45752)
		(width 0.0889)
		(layer "In11.Cu")
		(net "P5E_CPU1_PE1_RX_DP<11>")
	)
	(segment
		(start 107.128564 -215.926162)
		(end 107.122468 -215.922606)
		(width 0.0889)
		(layer "In11.Cu")
		(net "P5E_CPU1_PE1_RX_DP<11>")
	)
	(segment
		(start 107.316016 -217.8939)
		(end 107.316016 -217.856308)
		(width 0.0889)
		(layer "In11.Cu")
		(net "P5E_CPU1_PE1_RX_DP<11>")
	)
	(segment
		(start 103.16337 -181.115716)
		(end 102.994968 -180.447442)
		(width 0.14732)
		(layer "In11.Cu")
		(net "P5E_CPU1_PE1_RX_DP<11>")
	)
	(segment
		(start 108.820966 -221.133924)
		(end 108.664502 -221.404942)
		(width 0.0889)
		(layer "In11.Cu")
		(net "P5E_CPU1_PE1_RX_DP<11>")
	)
	(segment
		(start 28.257246 -18.45437)
		(end 28.54706 -18.164302)
		(width 0.14732)
		(layer "In11.Cu")
		(net "P5E_CPU1_PE1_RX_DP<11>")
	)
	(segment
		(start 26.951686 -13.6906)
		(end 26.800302 -13.354558)
		(width 0.14732)
		(layer "In11.Cu")
		(net "P5E_CPU1_PE1_RX_DP<11>")
	)
	(segment
		(start 28.7528 -17.335246)
		(end 28.040076 -15.75308)
		(width 0.14732)
		(layer "In11.Cu")
		(net "P5E_CPU1_PE1_RX_DP<11>")
	)
	(segment
		(start 27.618436 -14.817344)
		(end 27.426666 -14.744954)
		(width 0.14732)
		(layer "In11.Cu")
		(net "P5E_CPU1_PE1_RX_DP<11>")
	)
	(segment
		(start 107.137454 -215.931242)
		(end 107.128564 -215.926162)
		(width 0.0889)
		(layer "In11.Cu")
		(net "P5E_CPU1_PE1_RX_DP<11>")
	)
	(segment
		(start 27.275282 -14.408912)
		(end 27.347926 -14.217396)
		(width 0.14732)
		(layer "In11.Cu")
		(net "P5E_CPU1_PE1_RX_DP<11>")
	)
	(segment
		(start 108.077254 -219.18676)
		(end 108.068364 -219.18168)
		(width 0.0889)
		(layer "In11.Cu")
		(net "P5E_CPU1_PE1_RX_DP<11>")
	)
	(segment
		(start 108.068364 -219.18168)
		(end 108.062268 -219.178124)
		(width 0.0889)
		(layer "In11.Cu")
		(net "P5E_CPU1_PE1_RX_DP<11>")
	)
	(segment
		(start 27.426666 -14.744954)
		(end 27.275282 -14.408912)
		(width 0.14732)
		(layer "In11.Cu")
		(net "P5E_CPU1_PE1_RX_DP<11>")
	)
	(segment
		(start 27.696922 -15.344394)
		(end 27.769566 -15.153132)
		(width 0.14732)
		(layer "In11.Cu")
		(net "P5E_CPU1_PE1_RX_DP<11>")
	)
	(segment
		(start 106.84637 -213.105238)
		(end 106.80446 -213.063328)
		(width 0.0889)
		(layer "In11.Cu")
		(net "P5E_CPU1_PE1_RX_DP<11>")
	)
	(segment
		(start 53.102256 -59.998864)
		(end 28.281884 -19.990816)
		(width 0.14732)
		(layer "In11.Cu")
		(net "P5E_CPU1_PE1_RX_DP<11>")
	)
	(segment
		(start 109.017054 -220.814646)
		(end 109.008164 -220.809566)
		(width 0.0889)
		(layer "In11.Cu")
		(net "P5E_CPU1_PE1_RX_DP<11>")
	)
	(segment
		(start 28.54706 -18.164302)
		(end 28.7528 -17.66824)
		(width 0.14732)
		(layer "In11.Cu")
		(net "P5E_CPU1_PE1_RX_DP<11>")
	)
	(segment
		(start 106.80446 -208.838546)
		(end 106.804206 -208.838292)
		(width 0.14732)
		(layer "In11.Cu")
		(net "P5E_CPU1_PE1_RX_DP<11>")
	)
	(segment
		(start 107.59821 -217.388694)
		(end 107.6071 -217.383614)
		(width 0.0889)
		(layer "In11.Cu")
		(net "P5E_CPU1_PE1_RX_DP<11>")
	)
	(segment
		(start 108.255816 -219.515944)
		(end 108.255816 -219.506038)
		(width 0.0889)
		(layer "In11.Cu")
		(net "P5E_CPU1_PE1_RX_DP<11>")
	)
	(segment
		(start 27.347926 -14.217396)
		(end 27.143456 -13.763244)
		(width 0.14732)
		(layer "In11.Cu")
		(net "P5E_CPU1_PE1_RX_DP<11>")
	)
	(segment
		(start 28.0416 -18.975324)
		(end 28.257246 -18.45437)
		(width 0.14732)
		(layer "In11.Cu")
		(net "P5E_CPU1_PE1_RX_DP<11>")
	)
	(segment
		(start 106.804206 -208.838292)
		(end 103.16337 -181.115716)
		(width 0.14732)
		(layer "In11.Cu")
		(net "P5E_CPU1_PE1_RX_DP<11>")
	)
	(segment
		(start 107.128056 -214.946992)
		(end 107.136946 -214.941912)
		(width 0.0889)
		(layer "In11.Cu")
		(net "P5E_CPU1_PE1_RX_DP<11>")
	)
	(segment
		(start 108.664502 -221.404942)
		(end 108.685584 -221.48292)
		(width 0.0889)
		(layer "In11.Cu")
		(net "P5E_CPU1_PE1_RX_DP<11>")
	)
	(segment
		(start 26.872946 -13.163042)
		(end 26.51125 -12.360148)
		(width 0.14732)
		(layer "In11.Cu")
		(net "P5E_CPU1_PE1_RX_DP<11>")
	)
	(segment
		(start 28.040076 -15.75308)
		(end 27.848306 -15.680436)
		(width 0.14732)
		(layer "In11.Cu")
		(net "P5E_CPU1_PE1_RX_DP<11>")
	)
	(segment
		(start 107.316016 -216.266014)
		(end 107.316016 -216.25052)
		(width 0.0889)
		(layer "In11.Cu")
		(net "P5E_CPU1_PE1_RX_DP<11>")
	)
	(segment
		(start 108.725462 -220.334078)
		(end 108.725462 -220.311218)
		(width 0.0889)
		(layer "In11.Cu")
		(net "P5E_CPU1_PE1_RX_DP<11>")
	)
	(segment
		(start 106.80446 -213.04123)
		(end 106.80446 -208.838546)
		(width 0.14732)
		(layer "In11.Cu")
		(net "P5E_CPU1_PE1_RX_DP<11>")
	)
	(segment
		(start 27.848306 -15.680436)
		(end 27.696922 -15.344394)
		(width 0.14732)
		(layer "In11.Cu")
		(net "P5E_CPU1_PE1_RX_DP<11>")
	)
	(segment
		(start 107.6071 -218.372944)
		(end 107.59821 -218.367864)
		(width 0.0889)
		(layer "In11.Cu")
		(net "P5E_CPU1_PE1_RX_DP<11>")
	)
	(segment
		(start 109.009688 -221.45752)
		(end 109.017054 -221.453202)
		(width 0.0889)
		(layer "In11.Cu")
		(net "P5E_CPU1_PE1_RX_DP<11>")
	)
	(segment
		(start 28.281884 -19.990816)
		(end 28.0416 -19.409664)
		(width 0.14732)
		(layer "In11.Cu")
		(net "P5E_CPU1_PE1_RX_DP<11>")
	)
	(segment
		(start 28.0416 -19.409664)
		(end 28.0416 -18.975324)
		(width 0.14732)
		(layer "In11.Cu")
		(net "P5E_CPU1_PE1_RX_DP<11>")
	)
	(segment
		(start 107.315508 -214.622634)
		(end 107.315508 -214.461344)
		(width 0.0889)
		(layer "In11.Cu")
		(net "P5E_CPU1_PE1_RX_DP<11>")
	)
	(segment
		(start 27.769566 -15.153132)
		(end 27.618436 -14.817344)
		(width 0.14732)
		(layer "In11.Cu")
		(net "P5E_CPU1_PE1_RX_DP<11>")
	)
	(segment
		(start 106.845862 -215.436704)
		(end 106.845862 -215.414606)
		(width 0.0889)
		(layer "In11.Cu")
		(net "P5E_CPU1_PE1_RX_DP<11>")
	)
	(segment
		(start 28.7528 -17.66824)
		(end 28.7528 -17.335246)
		(width 0.14732)
		(layer "In11.Cu")
		(net "P5E_CPU1_PE1_RX_DP<11>")
	)
	(segment
		(start 106.857292 -213.959948)
		(end 106.8578 -213.959694)
		(width 0.0889)
		(layer "In11.Cu")
		(net "P5E_CPU1_PE1_RX_DP<11>")
	)
	(segment
		(start 102.994968 -180.447442)
		(end 53.102256 -59.998864)
		(width 0.14732)
		(layer "In11.Cu")
		(net "P5E_CPU1_PE1_RX_DP<11>")
	)
	(segment
		(start 26.51125 -12.360148)
		(end 26.51125 -7.019036)
		(width 0.14732)
		(layer "In11.Cu")
		(net "P5E_CPU1_PE1_RX_DP<11>")
	)
	(segment
		(start 27.143456 -13.763244)
		(end 26.951686 -13.6906)
		(width 0.14732)
		(layer "In11.Cu")
		(net "P5E_CPU1_PE1_RX_DP<11>")
	)
	(segment
		(start 107.599226 -216.740486)
		(end 107.59821 -216.739978)
		(width 0.0889)
		(layer "In11.Cu")
		(net "P5E_CPU1_PE1_RX_DP<11>")
	)
	(segment
		(start 26.51125 -7.019036)
		(end 26.21661 -6.724396)
		(width 0.14732)
		(layer "In11.Cu")
		(net "P5E_CPU1_PE1_RX_DP<11>")
	)
	(segment
		(start 106.80446 -213.063328)
		(end 106.80446 -213.04123)
		(width 0.0889)
		(layer "In11.Cu")
		(net "P5E_CPU1_PE1_RX_DP<11>")
	)
	(segment
		(start 106.84637 -213.929468)
		(end 106.84637 -213.105238)
		(width 0.0889)
		(layer "In11.Cu")
		(net "P5E_CPU1_PE1_RX_DP<11>")
	)
	(arc
		(start 108.725462 -220.311218)
		(mid 108.673192 -220.128853)
		(end 108.538264 -219.995496)
		(width 0.0889)
		(layer "In11.Cu")
		(net "P5E_CPU1_PE1_RX_DP<11>")
	)
	(arc
		(start 107.122468 -215.922606)
		(mid 106.919881 -215.716255)
		(end 106.845862 -215.436704)
		(width 0.0889)
		(layer "In11.Cu")
		(net "P5E_CPU1_PE1_RX_DP<11>")
	)
	(arc
		(start 107.785662 -218.692222)
		(mid 107.737983 -218.509322)
		(end 107.6071 -218.372944)
		(width 0.0889)
		(layer "In11.Cu")
		(net "P5E_CPU1_PE1_RX_DP<11>")
	)
	(arc
		(start 108.685584 -221.48292)
		(mid 108.84968 -221.507267)
		(end 109.008164 -221.458282)
		(width 0.0889)
		(layer "In11.Cu")
		(net "P5E_CPU1_PE1_RX_DP<11>")
	)
	(arc
		(start 107.6071 -217.383614)
		(mid 107.785697 -217.064336)
		(end 107.6071 -216.745058)
		(width 0.0889)
		(layer "In11.Cu")
		(net "P5E_CPU1_PE1_RX_DP<11>")
	)
	(arc
		(start 106.845862 -215.414606)
		(mid 106.926773 -215.144478)
		(end 107.128056 -214.946992)
		(width 0.0889)
		(layer "In11.Cu")
		(net "P5E_CPU1_PE1_RX_DP<11>")
	)
	(arc
		(start 107.136946 -214.941912)
		(mid 107.26786 -214.805552)
		(end 107.315508 -214.622634)
		(width 0.0889)
		(layer "In11.Cu")
		(net "P5E_CPU1_PE1_RX_DP<11>")
	)
	(arc
		(start 106.8578 -213.959694)
		(mid 106.851883 -213.944657)
		(end 106.84637 -213.929468)
		(width 0.0889)
		(layer "In11.Cu")
		(net "P5E_CPU1_PE1_RX_DP<11>")
	)
	(arc
		(start 107.131358 -214.261954)
		(mid 106.967829 -214.134997)
		(end 106.857292 -213.959948)
		(width 0.0889)
		(layer "In11.Cu")
		(net "P5E_CPU1_PE1_RX_DP<11>")
	)
	(arc
		(start 109.017054 -221.453202)
		(mid 109.195651 -221.133924)
		(end 109.017054 -220.814646)
		(width 0.0889)
		(layer "In11.Cu")
		(net "P5E_CPU1_PE1_RX_DP<11>")
	)
	(arc
		(start 107.316016 -216.25052)
		(mid 107.268337 -216.06762)
		(end 107.137454 -215.931242)
		(width 0.0889)
		(layer "In11.Cu")
		(net "P5E_CPU1_PE1_RX_DP<11>")
	)
	(arc
		(start 107.59821 -216.739978)
		(mid 107.395387 -216.539747)
		(end 107.316016 -216.266014)
		(width 0.0889)
		(layer "In11.Cu")
		(net "P5E_CPU1_PE1_RX_DP<11>")
	)
	(arc
		(start 109.008164 -220.809566)
		(mid 108.804683 -220.608762)
		(end 108.725462 -220.334078)
		(width 0.0889)
		(layer "In11.Cu")
		(net "P5E_CPU1_PE1_RX_DP<11>")
	)
	(arc
		(start 108.255816 -219.506038)
		(mid 108.208137 -219.323138)
		(end 108.077254 -219.18676)
		(width 0.0889)
		(layer "In11.Cu")
		(net "P5E_CPU1_PE1_RX_DP<11>")
	)
	(arc
		(start 108.062268 -219.178124)
		(mid 107.859681 -218.971773)
		(end 107.785662 -218.692222)
		(width 0.0889)
		(layer "In11.Cu")
		(net "P5E_CPU1_PE1_RX_DP<11>")
	)
	(arc
		(start 107.315508 -214.461344)
		(mid 107.240503 -214.345885)
		(end 107.131358 -214.261954)
		(width 0.0889)
		(layer "In11.Cu")
		(net "P5E_CPU1_PE1_RX_DP<11>")
	)
	(arc
		(start 107.59821 -218.367864)
		(mid 107.395387 -218.167633)
		(end 107.316016 -217.8939)
		(width 0.0889)
		(layer "In11.Cu")
		(net "P5E_CPU1_PE1_RX_DP<11>")
	)
	(arc
		(start 108.538264 -219.995496)
		(mid 108.333929 -219.792891)
		(end 108.255816 -219.515944)
		(width 0.0889)
		(layer "In11.Cu")
		(net "P5E_CPU1_PE1_RX_DP<11>")
	)
	(arc
		(start 107.316016 -217.856308)
		(mid 107.396927 -217.58618)
		(end 107.59821 -217.388694)
		(width 0.0889)
		(layer "In11.Cu")
		(net "P5E_CPU1_PE1_RX_DP<11>")
	)
	(segment
		(start 28.322524 -7.610602)
		(end 28.322524 -5.263896)
		(width 0.13208)
		(layer "F.Cu")
		(net "P5E_CPU1_PE1_RX_DP<10>")
	)
	(segment
		(start 28.322524 -5.263896)
		(end 28.02128 -4.962652)
		(width 0.13208)
		(layer "F.Cu")
		(net "P5E_CPU1_PE1_RX_DP<10>")
	)
	(segment
		(start 28.14701 -8.320024)
		(end 28.14701 -7.786116)
		(width 0.13208)
		(layer "F.Cu")
		(net "P5E_CPU1_PE1_RX_DP<10>")
	)
	(segment
		(start 28.14701 -7.786116)
		(end 28.322524 -7.610602)
		(width 0.13208)
		(layer "F.Cu")
		(net "P5E_CPU1_PE1_RX_DP<10>")
	)
	(segment
		(start 109.290866 -220.855794)
		(end 109.290612 -220.85554)
		(width 0.13208)
		(layer "F.Cu")
		(net "P5E_CPU1_PE1_RX_DP<10>")
	)
	(segment
		(start 109.290612 -220.85554)
		(end 109.290612 -220.319854)
		(width 0.13208)
		(layer "F.Cu")
		(net "P5E_CPU1_PE1_RX_DP<10>")
	)
	(segment
		(start 109.4867 -220.000576)
		(end 109.478826 -219.996004)
		(width 0.0889)
		(layer "In11.Cu")
		(net "P5E_CPU1_PE1_RX_DP<10>")
	)
	(segment
		(start 108.067602 -215.925654)
		(end 108.062268 -215.922606)
		(width 0.0889)
		(layer "In11.Cu")
		(net "P5E_CPU1_PE1_RX_DP<10>")
	)
	(segment
		(start 108.077254 -215.931242)
		(end 108.069888 -215.926924)
		(width 0.0889)
		(layer "In11.Cu")
		(net "P5E_CPU1_PE1_RX_DP<10>")
	)
	(segment
		(start 108.069888 -215.926924)
		(end 108.068364 -215.926162)
		(width 0.0889)
		(layer "In11.Cu")
		(net "P5E_CPU1_PE1_RX_DP<10>")
	)
	(segment
		(start 107.785662 -215.436704)
		(end 107.785662 -215.414606)
		(width 0.0889)
		(layer "In11.Cu")
		(net "P5E_CPU1_PE1_RX_DP<10>")
	)
	(segment
		(start 108.726224 -213.92261)
		(end 108.726224 -213.105238)
		(width 0.0889)
		(layer "In11.Cu")
		(net "P5E_CPU1_PE1_RX_DP<10>")
	)
	(segment
		(start 108.726224 -213.105238)
		(end 108.684314 -213.063328)
		(width 0.0889)
		(layer "In11.Cu")
		(net "P5E_CPU1_PE1_RX_DP<10>")
	)
	(segment
		(start 108.255816 -216.260426)
		(end 108.255816 -216.25052)
		(width 0.0889)
		(layer "In11.Cu")
		(net "P5E_CPU1_PE1_RX_DP<10>")
	)
	(segment
		(start 29.804868 -15.5067)
		(end 29.508704 -14.844268)
		(width 0.14732)
		(layer "In11.Cu")
		(net "P5E_CPU1_PE1_RX_DP<10>")
	)
	(segment
		(start 108.684314 -213.04123)
		(end 108.684314 -211.915756)
		(width 0.14732)
		(layer "In11.Cu")
		(net "P5E_CPU1_PE1_RX_DP<10>")
	)
	(segment
		(start 29.73197 -15.697962)
		(end 29.804868 -15.5067)
		(width 0.14732)
		(layer "In11.Cu")
		(net "P5E_CPU1_PE1_RX_DP<10>")
	)
	(segment
		(start 108.532676 -209.851244)
		(end 104.333802 -181.406292)
		(width 0.14732)
		(layer "In11.Cu")
		(net "P5E_CPU1_PE1_RX_DP<10>")
	)
	(segment
		(start 108.068364 -215.926162)
		(end 108.067602 -215.925654)
		(width 0.0889)
		(layer "In11.Cu")
		(net "P5E_CPU1_PE1_RX_DP<10>")
	)
	(segment
		(start 108.725462 -217.072972)
		(end 108.725462 -217.0557)
		(width 0.0889)
		(layer "In11.Cu")
		(net "P5E_CPU1_PE1_RX_DP<10>")
	)
	(segment
		(start 108.255562 -214.622634)
		(end 108.255816 -214.62238)
		(width 0.0889)
		(layer "In11.Cu")
		(net "P5E_CPU1_PE1_RX_DP<10>")
	)
	(segment
		(start 109.290612 -220.319854)
		(end 109.447076 -220.590872)
		(width 0.0889)
		(layer "In11.Cu")
		(net "P5E_CPU1_PE1_RX_DP<10>")
	)
	(segment
		(start 109.008164 -219.18168)
		(end 109.002068 -219.178124)
		(width 0.0889)
		(layer "In11.Cu")
		(net "P5E_CPU1_PE1_RX_DP<10>")
	)
	(segment
		(start 108.57103 -214.077804)
		(end 108.726224 -213.92261)
		(width 0.0889)
		(layer "In11.Cu")
		(net "P5E_CPU1_PE1_RX_DP<10>")
	)
	(segment
		(start 104.333802 -181.406292)
		(end 103.694992 -179.61737)
		(width 0.14732)
		(layer "In11.Cu")
		(net "P5E_CPU1_PE1_RX_DP<10>")
	)
	(segment
		(start 109.447076 -220.590872)
		(end 109.525308 -220.6117)
		(width 0.0889)
		(layer "In11.Cu")
		(net "P5E_CPU1_PE1_RX_DP<10>")
	)
	(segment
		(start 109.017054 -219.18676)
		(end 109.008164 -219.18168)
		(width 0.0889)
		(layer "In11.Cu")
		(net "P5E_CPU1_PE1_RX_DP<10>")
	)
	(segment
		(start 109.478826 -219.996004)
		(end 109.47781 -219.995496)
		(width 0.0889)
		(layer "In11.Cu")
		(net "P5E_CPU1_PE1_RX_DP<10>")
	)
	(segment
		(start 30.912054 -17.981676)
		(end 30.073854 -16.107664)
		(width 0.14732)
		(layer "In11.Cu")
		(net "P5E_CPU1_PE1_RX_DP<10>")
	)
	(segment
		(start 28.31592 -12.17803)
		(end 28.31592 -5.257292)
		(width 0.14732)
		(layer "In11.Cu")
		(net "P5E_CPU1_PE1_RX_DP<10>")
	)
	(segment
		(start 29.508704 -14.844268)
		(end 29.317188 -14.771116)
		(width 0.14732)
		(layer "In11.Cu")
		(net "P5E_CPU1_PE1_RX_DP<10>")
	)
	(segment
		(start 108.067856 -214.946992)
		(end 108.082842 -214.938356)
		(width 0.0889)
		(layer "In11.Cu")
		(net "P5E_CPU1_PE1_RX_DP<10>")
	)
	(segment
		(start 31.977076 -19.528282)
		(end 30.912054 -17.981676)
		(width 0.14732)
		(layer "In11.Cu")
		(net "P5E_CPU1_PE1_RX_DP<10>")
	)
	(segment
		(start 29.317188 -14.771116)
		(end 29.16682 -14.43482)
		(width 0.14732)
		(layer "In11.Cu")
		(net "P5E_CPU1_PE1_RX_DP<10>")
	)
	(segment
		(start 30.073854 -16.107664)
		(end 29.882338 -16.034512)
		(width 0.14732)
		(layer "In11.Cu")
		(net "P5E_CPU1_PE1_RX_DP<10>")
	)
	(segment
		(start 108.5469 -218.372944)
		(end 108.53801 -218.367864)
		(width 0.0889)
		(layer "In11.Cu")
		(net "P5E_CPU1_PE1_RX_DP<10>")
	)
	(segment
		(start 29.882338 -16.034512)
		(end 29.73197 -15.697962)
		(width 0.14732)
		(layer "In11.Cu")
		(net "P5E_CPU1_PE1_RX_DP<10>")
	)
	(segment
		(start 109.195616 -219.521532)
		(end 109.195616 -219.506038)
		(width 0.0889)
		(layer "In11.Cu")
		(net "P5E_CPU1_PE1_RX_DP<10>")
	)
	(segment
		(start 53.956712 -59.540394)
		(end 31.977076 -19.528282)
		(width 0.14732)
		(layer "In11.Cu")
		(net "P5E_CPU1_PE1_RX_DP<10>")
	)
	(segment
		(start 103.694992 -179.61737)
		(end 53.956712 -59.540394)
		(width 0.14732)
		(layer "In11.Cu")
		(net "P5E_CPU1_PE1_RX_DP<10>")
	)
	(segment
		(start 108.255816 -217.8939)
		(end 108.255816 -217.859864)
		(width 0.0889)
		(layer "In11.Cu")
		(net "P5E_CPU1_PE1_RX_DP<10>")
	)
	(segment
		(start 108.255816 -214.62238)
		(end 108.255816 -214.427054)
		(width 0.0889)
		(layer "In11.Cu")
		(net "P5E_CPU1_PE1_RX_DP<10>")
	)
	(segment
		(start 108.684314 -213.063328)
		(end 108.684314 -213.04123)
		(width 0.0889)
		(layer "In11.Cu")
		(net "P5E_CPU1_PE1_RX_DP<10>")
	)
	(segment
		(start 108.541312 -214.093552)
		(end 108.57103 -214.077804)
		(width 0.0889)
		(layer "In11.Cu")
		(net "P5E_CPU1_PE1_RX_DP<10>")
	)
	(segment
		(start 28.31592 -5.257292)
		(end 28.02128 -4.962652)
		(width 0.14732)
		(layer "In11.Cu")
		(net "P5E_CPU1_PE1_RX_DP<10>")
	)
	(segment
		(start 29.239718 -14.243558)
		(end 28.31592 -12.17803)
		(width 0.14732)
		(layer "In11.Cu")
		(net "P5E_CPU1_PE1_RX_DP<10>")
	)
	(segment
		(start 108.684314 -211.915756)
		(end 108.532676 -209.851244)
		(width 0.14732)
		(layer "In11.Cu")
		(net "P5E_CPU1_PE1_RX_DP<10>")
	)
	(segment
		(start 29.16682 -14.43482)
		(end 29.239718 -14.243558)
		(width 0.14732)
		(layer "In11.Cu")
		(net "P5E_CPU1_PE1_RX_DP<10>")
	)
	(arc
		(start 109.525308 -220.6117)
		(mid 109.628453 -220.481675)
		(end 109.665262 -220.319854)
		(width 0.0889)
		(layer "In11.Cu")
		(net "P5E_CPU1_PE1_RX_DP<10>")
	)
	(arc
		(start 108.538264 -216.739978)
		(mid 108.333929 -216.537373)
		(end 108.255816 -216.260426)
		(width 0.0889)
		(layer "In11.Cu")
		(net "P5E_CPU1_PE1_RX_DP<10>")
	)
	(arc
		(start 108.53801 -218.367864)
		(mid 108.335187 -218.167633)
		(end 108.255816 -217.8939)
		(width 0.0889)
		(layer "In11.Cu")
		(net "P5E_CPU1_PE1_RX_DP<10>")
	)
	(arc
		(start 108.255816 -214.427054)
		(mid 108.36686 -214.233163)
		(end 108.541312 -214.093552)
		(width 0.0889)
		(layer "In11.Cu")
		(net "P5E_CPU1_PE1_RX_DP<10>")
	)
	(arc
		(start 108.725462 -217.0557)
		(mid 108.673192 -216.873335)
		(end 108.538264 -216.739978)
		(width 0.0889)
		(layer "In11.Cu")
		(net "P5E_CPU1_PE1_RX_DP<10>")
	)
	(arc
		(start 109.665262 -220.319854)
		(mid 109.617583 -220.136954)
		(end 109.4867 -220.000576)
		(width 0.0889)
		(layer "In11.Cu")
		(net "P5E_CPU1_PE1_RX_DP<10>")
	)
	(arc
		(start 109.47781 -219.995496)
		(mid 109.274987 -219.795265)
		(end 109.195616 -219.521532)
		(width 0.0889)
		(layer "In11.Cu")
		(net "P5E_CPU1_PE1_RX_DP<10>")
	)
	(arc
		(start 108.082842 -214.938356)
		(mid 108.209565 -214.802575)
		(end 108.255562 -214.622634)
		(width 0.0889)
		(layer "In11.Cu")
		(net "P5E_CPU1_PE1_RX_DP<10>")
	)
	(arc
		(start 108.538264 -217.388694)
		(mid 108.673197 -217.25534)
		(end 108.725462 -217.072972)
		(width 0.0889)
		(layer "In11.Cu")
		(net "P5E_CPU1_PE1_RX_DP<10>")
	)
	(arc
		(start 107.785662 -215.414606)
		(mid 107.866573 -215.144478)
		(end 108.067856 -214.946992)
		(width 0.0889)
		(layer "In11.Cu")
		(net "P5E_CPU1_PE1_RX_DP<10>")
	)
	(arc
		(start 108.255816 -216.25052)
		(mid 108.208137 -216.06762)
		(end 108.077254 -215.931242)
		(width 0.0889)
		(layer "In11.Cu")
		(net "P5E_CPU1_PE1_RX_DP<10>")
	)
	(arc
		(start 109.002068 -219.178124)
		(mid 108.799481 -218.971773)
		(end 108.725462 -218.692222)
		(width 0.0889)
		(layer "In11.Cu")
		(net "P5E_CPU1_PE1_RX_DP<10>")
	)
	(arc
		(start 108.062268 -215.922606)
		(mid 107.859681 -215.716255)
		(end 107.785662 -215.436704)
		(width 0.0889)
		(layer "In11.Cu")
		(net "P5E_CPU1_PE1_RX_DP<10>")
	)
	(arc
		(start 108.725462 -218.692222)
		(mid 108.677783 -218.509322)
		(end 108.5469 -218.372944)
		(width 0.0889)
		(layer "In11.Cu")
		(net "P5E_CPU1_PE1_RX_DP<10>")
	)
	(arc
		(start 108.255816 -217.859864)
		(mid 108.335978 -217.587675)
		(end 108.538264 -217.388694)
		(width 0.0889)
		(layer "In11.Cu")
		(net "P5E_CPU1_PE1_RX_DP<10>")
	)
	(arc
		(start 109.195616 -219.506038)
		(mid 109.147937 -219.323138)
		(end 109.017054 -219.18676)
		(width 0.0889)
		(layer "In11.Cu")
		(net "P5E_CPU1_PE1_RX_DP<10>")
	)
	(segment
		(start 55.838598 -5.259832)
		(end 55.541418 -4.962652)
		(width 0.13208)
		(layer "F.Cu")
		(net "P5E_CPU1_PE1_RX_DP<0>")
	)
	(segment
		(start 118.688866 -220.320108)
		(end 118.688612 -220.319854)
		(width 0.13208)
		(layer "F.Cu")
		(net "P5E_CPU1_PE1_RX_DP<0>")
	)
	(segment
		(start 55.838598 -7.614666)
		(end 55.838598 -5.259832)
		(width 0.13208)
		(layer "F.Cu")
		(net "P5E_CPU1_PE1_RX_DP<0>")
	)
	(segment
		(start 55.666894 -8.320024)
		(end 55.666894 -7.78637)
		(width 0.13208)
		(layer "F.Cu")
		(net "P5E_CPU1_PE1_RX_DP<0>")
	)
	(segment
		(start 55.666894 -7.78637)
		(end 55.838598 -7.614666)
		(width 0.13208)
		(layer "F.Cu")
		(net "P5E_CPU1_PE1_RX_DP<0>")
	)
	(segment
		(start 118.688866 -220.855794)
		(end 118.688866 -220.320108)
		(width 0.13208)
		(layer "F.Cu")
		(net "P5E_CPU1_PE1_RX_DP<0>")
	)
	(segment
		(start 118.407688 -219.182442)
		(end 118.415054 -219.18676)
		(width 0.0889)
		(layer "In11.Cu")
		(net "P5E_CPU1_PE1_RX_DP<0>")
	)
	(segment
		(start 118.876826 -219.996004)
		(end 118.8847 -220.000576)
		(width 0.0889)
		(layer "In11.Cu")
		(net "P5E_CPU1_PE1_RX_DP<0>")
	)
	(segment
		(start 118.923308 -220.6117)
		(end 118.845076 -220.590872)
		(width 0.0889)
		(layer "In11.Cu")
		(net "P5E_CPU1_PE1_RX_DP<0>")
	)
	(segment
		(start 55.541418 -4.962652)
		(end 55.836058 -5.257292)
		(width 0.14732)
		(layer "In11.Cu")
		(net "P5E_CPU1_PE1_RX_DP<0>")
	)
	(segment
		(start 58.985912 -46.95063)
		(end 114.063526 -179.9209)
		(width 0.14732)
		(layer "In11.Cu")
		(net "P5E_CPU1_PE1_RX_DP<0>")
	)
	(segment
		(start 118.405402 -218.203272)
		(end 118.400068 -218.20632)
		(width 0.0889)
		(layer "In11.Cu")
		(net "P5E_CPU1_PE1_RX_DP<0>")
	)
	(segment
		(start 57.621932 -15.186152)
		(end 59.82716 -18.802604)
		(width 0.14732)
		(layer "In11.Cu")
		(net "P5E_CPU1_PE1_RX_DP<0>")
	)
	(segment
		(start 56.293258 -13.007086)
		(end 56.490108 -13.330174)
		(width 0.14732)
		(layer "In11.Cu")
		(net "P5E_CPU1_PE1_RX_DP<0>")
	)
	(segment
		(start 118.407688 -218.202002)
		(end 118.406164 -218.202764)
		(width 0.0889)
		(layer "In11.Cu")
		(net "P5E_CPU1_PE1_RX_DP<0>")
	)
	(segment
		(start 59.532266 -20.040346)
		(end 57.752996 -38.63848)
		(width 0.14732)
		(layer "In11.Cu")
		(net "P5E_CPU1_PE1_RX_DP<0>")
	)
	(segment
		(start 56.633618 -13.843762)
		(end 56.833008 -13.892022)
		(width 0.14732)
		(layer "In11.Cu")
		(net "P5E_CPU1_PE1_RX_DP<0>")
	)
	(segment
		(start 118.87581 -219.995496)
		(end 118.876826 -219.996004)
		(width 0.0889)
		(layer "In11.Cu")
		(net "P5E_CPU1_PE1_RX_DP<0>")
	)
	(segment
		(start 118.406164 -219.18168)
		(end 118.407688 -219.182442)
		(width 0.0889)
		(layer "In11.Cu")
		(net "P5E_CPU1_PE1_RX_DP<0>")
	)
	(segment
		(start 114.063526 -179.9209)
		(end 114.626898 -183.154066)
		(width 0.14732)
		(layer "In11.Cu")
		(net "P5E_CPU1_PE1_RX_DP<0>")
	)
	(segment
		(start 57.422796 -15.137892)
		(end 57.621932 -15.186152)
		(width 0.14732)
		(layer "In11.Cu")
		(net "P5E_CPU1_PE1_RX_DP<0>")
	)
	(segment
		(start 57.231026 -14.823186)
		(end 57.422796 -15.137892)
		(width 0.14732)
		(layer "In11.Cu")
		(net "P5E_CPU1_PE1_RX_DP<0>")
	)
	(segment
		(start 118.405402 -219.181172)
		(end 118.406164 -219.18168)
		(width 0.0889)
		(layer "In11.Cu")
		(net "P5E_CPU1_PE1_RX_DP<0>")
	)
	(segment
		(start 118.415054 -218.197684)
		(end 118.407688 -218.202002)
		(width 0.0889)
		(layer "In11.Cu")
		(net "P5E_CPU1_PE1_RX_DP<0>")
	)
	(segment
		(start 57.279286 -14.62405)
		(end 57.231026 -14.823186)
		(width 0.14732)
		(layer "In11.Cu")
		(net "P5E_CPU1_PE1_RX_DP<0>")
	)
	(segment
		(start 118.08206 -210.227926)
		(end 118.08206 -213.04123)
		(width 0.14732)
		(layer "In11.Cu")
		(net "P5E_CPU1_PE1_RX_DP<0>")
	)
	(segment
		(start 118.845076 -220.590872)
		(end 118.688612 -220.319854)
		(width 0.0889)
		(layer "In11.Cu")
		(net "P5E_CPU1_PE1_RX_DP<0>")
	)
	(segment
		(start 118.400068 -219.178124)
		(end 118.405402 -219.181172)
		(width 0.0889)
		(layer "In11.Cu")
		(net "P5E_CPU1_PE1_RX_DP<0>")
	)
	(segment
		(start 57.752996 -38.63848)
		(end 58.985912 -46.95063)
		(width 0.14732)
		(layer "In11.Cu")
		(net "P5E_CPU1_PE1_RX_DP<0>")
	)
	(segment
		(start 59.82716 -19.3294)
		(end 59.532266 -20.040346)
		(width 0.14732)
		(layer "In11.Cu")
		(net "P5E_CPU1_PE1_RX_DP<0>")
	)
	(segment
		(start 56.490108 -13.330174)
		(end 56.441848 -13.529056)
		(width 0.14732)
		(layer "In11.Cu")
		(net "P5E_CPU1_PE1_RX_DP<0>")
	)
	(segment
		(start 59.82716 -18.802604)
		(end 59.82716 -19.3294)
		(width 0.14732)
		(layer "In11.Cu")
		(net "P5E_CPU1_PE1_RX_DP<0>")
	)
	(segment
		(start 55.836058 -5.257292)
		(end 55.836058 -11.903456)
		(width 0.14732)
		(layer "In11.Cu")
		(net "P5E_CPU1_PE1_RX_DP<0>")
	)
	(segment
		(start 118.12397 -213.105238)
		(end 118.12397 -213.929214)
		(width 0.0889)
		(layer "In11.Cu")
		(net "P5E_CPU1_PE1_RX_DP<0>")
	)
	(segment
		(start 118.593108 -214.461344)
		(end 118.593108 -214.622634)
		(width 0.0889)
		(layer "In11.Cu")
		(net "P5E_CPU1_PE1_RX_DP<0>")
	)
	(segment
		(start 117.653816 -216.235026)
		(end 117.653816 -216.260426)
		(width 0.0889)
		(layer "In11.Cu")
		(net "P5E_CPU1_PE1_RX_DP<0>")
	)
	(segment
		(start 118.08206 -213.063328)
		(end 118.12397 -213.105238)
		(width 0.0889)
		(layer "In11.Cu")
		(net "P5E_CPU1_PE1_RX_DP<0>")
	)
	(segment
		(start 118.409212 -214.261954)
		(end 118.408958 -214.261954)
		(width 0.0889)
		(layer "In11.Cu")
		(net "P5E_CPU1_PE1_RX_DP<0>")
	)
	(segment
		(start 55.836058 -11.903456)
		(end 56.293258 -13.007086)
		(width 0.14732)
		(layer "In11.Cu")
		(net "P5E_CPU1_PE1_RX_DP<0>")
	)
	(segment
		(start 56.441848 -13.529056)
		(end 56.633618 -13.843762)
		(width 0.14732)
		(layer "In11.Cu")
		(net "P5E_CPU1_PE1_RX_DP<0>")
	)
	(segment
		(start 117.9449 -215.755982)
		(end 117.93601 -215.761062)
		(width 0.0889)
		(layer "In11.Cu")
		(net "P5E_CPU1_PE1_RX_DP<0>")
	)
	(segment
		(start 118.593616 -219.506038)
		(end 118.593616 -219.521532)
		(width 0.0889)
		(layer "In11.Cu")
		(net "P5E_CPU1_PE1_RX_DP<0>")
	)
	(segment
		(start 118.08206 -213.04123)
		(end 118.08206 -213.063328)
		(width 0.0889)
		(layer "In11.Cu")
		(net "P5E_CPU1_PE1_RX_DP<0>")
	)
	(segment
		(start 118.123462 -217.0557)
		(end 118.123462 -217.07856)
		(width 0.0889)
		(layer "In11.Cu")
		(net "P5E_CPU1_PE1_RX_DP<0>")
	)
	(segment
		(start 56.833008 -13.892022)
		(end 57.279286 -14.62405)
		(width 0.14732)
		(layer "In11.Cu")
		(net "P5E_CPU1_PE1_RX_DP<0>")
	)
	(segment
		(start 114.626898 -183.154066)
		(end 117.755416 -205.532482)
		(width 0.14732)
		(layer "In11.Cu")
		(net "P5E_CPU1_PE1_RX_DP<0>")
	)
	(segment
		(start 118.414546 -214.941912)
		(end 118.405656 -214.946992)
		(width 0.0889)
		(layer "In11.Cu")
		(net "P5E_CPU1_PE1_RX_DP<0>")
	)
	(segment
		(start 118.406164 -218.202764)
		(end 118.405402 -218.203272)
		(width 0.0889)
		(layer "In11.Cu")
		(net "P5E_CPU1_PE1_RX_DP<0>")
	)
	(segment
		(start 118.123462 -215.414606)
		(end 118.123462 -215.436704)
		(width 0.0889)
		(layer "In11.Cu")
		(net "P5E_CPU1_PE1_RX_DP<0>")
	)
	(segment
		(start 117.755416 -205.532482)
		(end 118.08206 -210.227926)
		(width 0.14732)
		(layer "In11.Cu")
		(net "P5E_CPU1_PE1_RX_DP<0>")
	)
	(segment
		(start 118.406164 -217.554048)
		(end 118.415054 -217.559128)
		(width 0.0889)
		(layer "In11.Cu")
		(net "P5E_CPU1_PE1_RX_DP<0>")
	)
	(segment
		(start 118.12397 -213.929214)
		(end 118.123716 -213.929468)
		(width 0.0889)
		(layer "In11.Cu")
		(net "P5E_CPU1_PE1_RX_DP<0>")
	)
	(arc
		(start 118.408958 -214.261954)
		(mid 118.518105 -214.345882)
		(end 118.593108 -214.461344)
		(width 0.0889)
		(layer "In11.Cu")
		(net "P5E_CPU1_PE1_RX_DP<0>")
	)
	(arc
		(start 118.8847 -220.000576)
		(mid 119.015614 -220.136936)
		(end 119.063262 -220.319854)
		(width 0.0889)
		(layer "In11.Cu")
		(net "P5E_CPU1_PE1_RX_DP<0>")
	)
	(arc
		(start 118.123462 -215.436704)
		(mid 118.075783 -215.619604)
		(end 117.9449 -215.755982)
		(width 0.0889)
		(layer "In11.Cu")
		(net "P5E_CPU1_PE1_RX_DP<0>")
	)
	(arc
		(start 117.93601 -215.761062)
		(mid 117.733187 -215.961293)
		(end 117.653816 -216.235026)
		(width 0.0889)
		(layer "In11.Cu")
		(net "P5E_CPU1_PE1_RX_DP<0>")
	)
	(arc
		(start 118.593616 -219.521532)
		(mid 118.672986 -219.795266)
		(end 118.87581 -219.995496)
		(width 0.0889)
		(layer "In11.Cu")
		(net "P5E_CPU1_PE1_RX_DP<0>")
	)
	(arc
		(start 118.13921 -213.969092)
		(mid 118.249153 -214.138618)
		(end 118.409212 -214.261954)
		(width 0.0889)
		(layer "In11.Cu")
		(net "P5E_CPU1_PE1_RX_DP<0>")
	)
	(arc
		(start 119.063262 -220.319854)
		(mid 119.026402 -220.481651)
		(end 118.923308 -220.6117)
		(width 0.0889)
		(layer "In11.Cu")
		(net "P5E_CPU1_PE1_RX_DP<0>")
	)
	(arc
		(start 118.415054 -219.18676)
		(mid 118.545968 -219.32312)
		(end 118.593616 -219.506038)
		(width 0.0889)
		(layer "In11.Cu")
		(net "P5E_CPU1_PE1_RX_DP<0>")
	)
	(arc
		(start 118.415054 -217.559128)
		(mid 118.593651 -217.878406)
		(end 118.415054 -218.197684)
		(width 0.0889)
		(layer "In11.Cu")
		(net "P5E_CPU1_PE1_RX_DP<0>")
	)
	(arc
		(start 118.405656 -214.946992)
		(mid 118.204374 -215.144479)
		(end 118.123462 -215.414606)
		(width 0.0889)
		(layer "In11.Cu")
		(net "P5E_CPU1_PE1_RX_DP<0>")
	)
	(arc
		(start 118.123716 -213.929468)
		(mid 118.131113 -213.949417)
		(end 118.13921 -213.969092)
		(width 0.0889)
		(layer "In11.Cu")
		(net "P5E_CPU1_PE1_RX_DP<0>")
	)
	(arc
		(start 118.123462 -217.07856)
		(mid 118.202681 -217.353245)
		(end 118.406164 -217.554048)
		(width 0.0889)
		(layer "In11.Cu")
		(net "P5E_CPU1_PE1_RX_DP<0>")
	)
	(arc
		(start 118.593108 -214.622634)
		(mid 118.545429 -214.805534)
		(end 118.414546 -214.941912)
		(width 0.0889)
		(layer "In11.Cu")
		(net "P5E_CPU1_PE1_RX_DP<0>")
	)
	(arc
		(start 117.936264 -216.739978)
		(mid 118.071197 -216.873332)
		(end 118.123462 -217.0557)
		(width 0.0889)
		(layer "In11.Cu")
		(net "P5E_CPU1_PE1_RX_DP<0>")
	)
	(arc
		(start 118.400068 -218.20632)
		(mid 118.123494 -218.692222)
		(end 118.400068 -219.178124)
		(width 0.0889)
		(layer "In11.Cu")
		(net "P5E_CPU1_PE1_RX_DP<0>")
	)
	(arc
		(start 117.653816 -216.260426)
		(mid 117.731927 -216.537375)
		(end 117.936264 -216.739978)
		(width 0.0889)
		(layer "In11.Cu")
		(net "P5E_CPU1_PE1_RX_DP<0>")
	)
	(segment
		(start 30.378146 -7.610094)
		(end 30.378146 -7.026656)
		(width 0.13208)
		(layer "F.Cu")
		(net "P5E_CPU1_PE1_RX_DN<9>")
	)
	(segment
		(start 30.547056 -7.779004)
		(end 30.378146 -7.610094)
		(width 0.13208)
		(layer "F.Cu")
		(net "P5E_CPU1_PE1_RX_DN<9>")
	)
	(segment
		(start 30.378146 -7.026656)
		(end 30.680406 -6.724396)
		(width 0.13208)
		(layer "F.Cu")
		(net "P5E_CPU1_PE1_RX_DN<9>")
	)
	(segment
		(start 110.230666 -222.48368)
		(end 110.230666 -221.94774)
		(width 0.13208)
		(layer "F.Cu")
		(net "P5E_CPU1_PE1_RX_DN<9>")
	)
	(segment
		(start 30.547056 -8.320024)
		(end 30.547056 -7.779004)
		(width 0.13208)
		(layer "F.Cu")
		(net "P5E_CPU1_PE1_RX_DN<9>")
	)
	(segment
		(start 109.584236 -216.581482)
		(end 109.584236 -216.581736)
		(width 0.0889)
		(layer "In11.Cu")
		(net "P5E_CPU1_PE1_RX_DN<9>")
	)
	(segment
		(start 30.385766 -11.902186)
		(end 30.385766 -7.019036)
		(width 0.14732)
		(layer "In11.Cu")
		(net "P5E_CPU1_PE1_RX_DN<9>")
	)
	(segment
		(start 33.92678 -19.268694)
		(end 33.92678 -18.95856)
		(width 0.14732)
		(layer "In11.Cu")
		(net "P5E_CPU1_PE1_RX_DN<9>")
	)
	(segment
		(start 111.265716 -221.14383)
		(end 111.265716 -221.1197)
		(width 0.0889)
		(layer "In11.Cu")
		(net "P5E_CPU1_PE1_RX_DN<9>")
	)
	(segment
		(start 34.402522 -16.840962)
		(end 30.74416 -12.826746)
		(width 0.14732)
		(layer "In11.Cu")
		(net "P5E_CPU1_PE1_RX_DN<9>")
	)
	(segment
		(start 109.573568 -218.202764)
		(end 109.564678 -218.197684)
		(width 0.0889)
		(layer "In11.Cu")
		(net "P5E_CPU1_PE1_RX_DN<9>")
	)
	(segment
		(start 110.043468 -219.01658)
		(end 110.042706 -219.016072)
		(width 0.0889)
		(layer "In11.Cu")
		(net "P5E_CPU1_PE1_RX_DN<9>")
	)
	(segment
		(start 109.564678 -217.559128)
		(end 109.564424 -217.558874)
		(width 0.0889)
		(layer "In11.Cu")
		(net "P5E_CPU1_PE1_RX_DN<9>")
	)
	(segment
		(start 109.107224 -215.763602)
		(end 109.10443 -215.761824)
		(width 0.0889)
		(layer "In11.Cu")
		(net "P5E_CPU1_PE1_RX_DN<9>")
	)
	(segment
		(start 30.385766 -7.019036)
		(end 30.680406 -6.724396)
		(width 0.14732)
		(layer "In11.Cu")
		(net "P5E_CPU1_PE1_RX_DN<9>")
	)
	(segment
		(start 109.385354 -214.622126)
		(end 109.385354 -214.06358)
		(width 0.0889)
		(layer "In11.Cu")
		(net "P5E_CPU1_PE1_RX_DN<9>")
	)
	(segment
		(start 30.74416 -12.826746)
		(end 30.385766 -11.902186)
		(width 0.14732)
		(layer "In11.Cu")
		(net "P5E_CPU1_PE1_RX_DN<9>")
	)
	(segment
		(start 110.040166 -219.014548)
		(end 110.03534 -219.012008)
		(width 0.0889)
		(layer "In11.Cu")
		(net "P5E_CPU1_PE1_RX_DN<9>")
	)
	(segment
		(start 34.077402 -18.595086)
		(end 34.375852 -18.296636)
		(width 0.14732)
		(layer "In11.Cu")
		(net "P5E_CPU1_PE1_RX_DN<9>")
	)
	(segment
		(start 109.897672 -213.164928)
		(end 109.897672 -211.735162)
		(width 0.14732)
		(layer "In11.Cu")
		(net "P5E_CPU1_PE1_RX_DN<9>")
	)
	(segment
		(start 110.042706 -219.016072)
		(end 110.040928 -219.015056)
		(width 0.0889)
		(layer "In11.Cu")
		(net "P5E_CPU1_PE1_RX_DN<9>")
	)
	(segment
		(start 34.59734 -17.761966)
		(end 34.59734 -17.342866)
		(width 0.14732)
		(layer "In11.Cu")
		(net "P5E_CPU1_PE1_RX_DN<9>")
	)
	(segment
		(start 109.572806 -217.553794)
		(end 109.583474 -217.547444)
		(width 0.0889)
		(layer "In11.Cu")
		(net "P5E_CPU1_PE1_RX_DN<9>")
	)
	(segment
		(start 109.855508 -213.218268)
		(end 109.897672 -213.176104)
		(width 0.0889)
		(layer "In11.Cu")
		(net "P5E_CPU1_PE1_RX_DN<9>")
	)
	(segment
		(start 104.892348 -179.093368)
		(end 55.153306 -59.016646)
		(width 0.14732)
		(layer "In11.Cu")
		(net "P5E_CPU1_PE1_RX_DN<9>")
	)
	(segment
		(start 110.513368 -219.830396)
		(end 110.504478 -219.825316)
		(width 0.0889)
		(layer "In11.Cu")
		(net "P5E_CPU1_PE1_RX_DN<9>")
	)
	(segment
		(start 109.385862 -216.262966)
		(end 109.385862 -216.25052)
		(width 0.0889)
		(layer "In11.Cu")
		(net "P5E_CPU1_PE1_RX_DN<9>")
	)
	(segment
		(start 109.855508 -213.593426)
		(end 109.855508 -213.218268)
		(width 0.0889)
		(layer "In11.Cu")
		(net "P5E_CPU1_PE1_RX_DN<9>")
	)
	(segment
		(start 109.10443 -215.761824)
		(end 109.103414 -215.761316)
		(width 0.0889)
		(layer "In11.Cu")
		(net "P5E_CPU1_PE1_RX_DN<9>")
	)
	(segment
		(start 110.795816 -220.32849)
		(end 110.795816 -220.309948)
		(width 0.0889)
		(layer "In11.Cu")
		(net "P5E_CPU1_PE1_RX_DN<9>")
	)
	(segment
		(start 109.102652 -215.112092)
		(end 109.11332 -215.105742)
		(width 0.0889)
		(layer "In11.Cu")
		(net "P5E_CPU1_PE1_RX_DN<9>")
	)
	(segment
		(start 33.92678 -18.95856)
		(end 34.077402 -18.595086)
		(width 0.14732)
		(layer "In11.Cu")
		(net "P5E_CPU1_PE1_RX_DN<9>")
	)
	(segment
		(start 110.325916 -219.506038)
		(end 110.325916 -219.496132)
		(width 0.0889)
		(layer "In11.Cu")
		(net "P5E_CPU1_PE1_RX_DN<9>")
	)
	(segment
		(start 109.584236 -216.581736)
		(end 109.56417 -216.569798)
		(width 0.0889)
		(layer "In11.Cu")
		(net "P5E_CPU1_PE1_RX_DN<9>")
	)
	(segment
		(start 110.230666 -221.94774)
		(end 110.38713 -221.676722)
		(width 0.0889)
		(layer "In11.Cu")
		(net "P5E_CPU1_PE1_RX_DN<9>")
	)
	(segment
		(start 110.040928 -219.015056)
		(end 110.040166 -219.014548)
		(width 0.0889)
		(layer "In11.Cu")
		(net "P5E_CPU1_PE1_RX_DN<9>")
	)
	(segment
		(start 109.897672 -213.176104)
		(end 109.897672 -213.164928)
		(width 0.0889)
		(layer "In11.Cu")
		(net "P5E_CPU1_PE1_RX_DN<9>")
	)
	(segment
		(start 108.915708 -215.436704)
		(end 108.915708 -215.418924)
		(width 0.0889)
		(layer "In11.Cu")
		(net "P5E_CPU1_PE1_RX_DN<9>")
	)
	(segment
		(start 34.59734 -17.342866)
		(end 34.402522 -16.840962)
		(width 0.14732)
		(layer "In11.Cu")
		(net "P5E_CPU1_PE1_RX_DN<9>")
	)
	(segment
		(start 109.897672 -211.735162)
		(end 109.713522 -209.226658)
		(width 0.14732)
		(layer "In11.Cu")
		(net "P5E_CPU1_PE1_RX_DN<9>")
	)
	(segment
		(start 105.596944 -181.340252)
		(end 104.892348 -179.093368)
		(width 0.14732)
		(layer "In11.Cu")
		(net "P5E_CPU1_PE1_RX_DN<9>")
	)
	(segment
		(start 110.03534 -219.012008)
		(end 110.034578 -219.0115)
		(width 0.0889)
		(layer "In11.Cu")
		(net "P5E_CPU1_PE1_RX_DN<9>")
	)
	(segment
		(start 55.153306 -59.016646)
		(end 34.426906 -20.475448)
		(width 0.14732)
		(layer "In11.Cu")
		(net "P5E_CPU1_PE1_RX_DN<9>")
	)
	(segment
		(start 110.38713 -221.676722)
		(end 110.476284 -221.652846)
		(width 0.0889)
		(layer "In11.Cu")
		(net "P5E_CPU1_PE1_RX_DN<9>")
	)
	(segment
		(start 109.385354 -214.06358)
		(end 109.855508 -213.593426)
		(width 0.0889)
		(layer "In11.Cu")
		(net "P5E_CPU1_PE1_RX_DN<9>")
	)
	(segment
		(start 109.579664 -218.20632)
		(end 109.573568 -218.202764)
		(width 0.0889)
		(layer "In11.Cu")
		(net "P5E_CPU1_PE1_RX_DN<9>")
	)
	(segment
		(start 109.103414 -215.761316)
		(end 109.098842 -215.758522)
		(width 0.0889)
		(layer "In11.Cu")
		(net "P5E_CPU1_PE1_RX_DN<9>")
	)
	(segment
		(start 109.113828 -215.767412)
		(end 109.107224 -215.763602)
		(width 0.0889)
		(layer "In11.Cu")
		(net "P5E_CPU1_PE1_RX_DN<9>")
	)
	(segment
		(start 34.426906 -20.475448)
		(end 33.92678 -19.268694)
		(width 0.14732)
		(layer "In11.Cu")
		(net "P5E_CPU1_PE1_RX_DN<9>")
	)
	(segment
		(start 34.375852 -18.296636)
		(end 34.59734 -17.761966)
		(width 0.14732)
		(layer "In11.Cu")
		(net "P5E_CPU1_PE1_RX_DN<9>")
	)
	(segment
		(start 109.713522 -209.226658)
		(end 105.596944 -181.340252)
		(width 0.14732)
		(layer "In11.Cu")
		(net "P5E_CPU1_PE1_RX_DN<9>")
	)
	(arc
		(start 110.476284 -221.652846)
		(mid 110.733282 -221.698334)
		(end 110.983268 -221.623382)
		(width 0.0889)
		(layer "In11.Cu")
		(net "P5E_CPU1_PE1_RX_DN<9>")
	)
	(arc
		(start 109.564678 -218.197684)
		(mid 109.433764 -218.061324)
		(end 109.386116 -217.878406)
		(width 0.0889)
		(layer "In11.Cu")
		(net "P5E_CPU1_PE1_RX_DN<9>")
	)
	(arc
		(start 109.38637 -217.863674)
		(mid 109.437424 -217.689094)
		(end 109.564678 -217.559128)
		(width 0.0889)
		(layer "In11.Cu")
		(net "P5E_CPU1_PE1_RX_DN<9>")
	)
	(arc
		(start 110.504478 -219.825316)
		(mid 110.373564 -219.688956)
		(end 110.325916 -219.506038)
		(width 0.0889)
		(layer "In11.Cu")
		(net "P5E_CPU1_PE1_RX_DN<9>")
	)
	(arc
		(start 109.386116 -217.878406)
		(mid 109.386168 -217.871039)
		(end 109.38637 -217.863674)
		(width 0.0889)
		(layer "In11.Cu")
		(net "P5E_CPU1_PE1_RX_DN<9>")
	)
	(arc
		(start 111.265716 -221.1197)
		(mid 111.186497 -220.845015)
		(end 110.983014 -220.644212)
		(width 0.0889)
		(layer "In11.Cu")
		(net "P5E_CPU1_PE1_RX_DN<9>")
	)
	(arc
		(start 110.034578 -219.0115)
		(mid 109.903664 -218.87514)
		(end 109.856016 -218.692222)
		(width 0.0889)
		(layer "In11.Cu")
		(net "P5E_CPU1_PE1_RX_DN<9>")
	)
	(arc
		(start 109.11332 -215.105742)
		(mid 109.312829 -214.899641)
		(end 109.385354 -214.622126)
		(width 0.0889)
		(layer "In11.Cu")
		(net "P5E_CPU1_PE1_RX_DN<9>")
	)
	(arc
		(start 110.325916 -219.496132)
		(mid 110.247805 -219.219183)
		(end 110.043468 -219.01658)
		(width 0.0889)
		(layer "In11.Cu")
		(net "P5E_CPU1_PE1_RX_DN<9>")
	)
	(arc
		(start 109.564424 -217.558874)
		(mid 109.568598 -217.556307)
		(end 109.572806 -217.553794)
		(width 0.0889)
		(layer "In11.Cu")
		(net "P5E_CPU1_PE1_RX_DN<9>")
	)
	(arc
		(start 109.385862 -216.25052)
		(mid 109.31317 -215.973315)
		(end 109.113828 -215.767412)
		(width 0.0889)
		(layer "In11.Cu")
		(net "P5E_CPU1_PE1_RX_DN<9>")
	)
	(arc
		(start 109.56417 -216.569798)
		(mid 109.436416 -216.438807)
		(end 109.385862 -216.262966)
		(width 0.0889)
		(layer "In11.Cu")
		(net "P5E_CPU1_PE1_RX_DN<9>")
	)
	(arc
		(start 110.983014 -220.644212)
		(mid 110.848081 -220.510858)
		(end 110.795816 -220.32849)
		(width 0.0889)
		(layer "In11.Cu")
		(net "P5E_CPU1_PE1_RX_DN<9>")
	)
	(arc
		(start 109.856016 -218.692222)
		(mid 109.7821 -218.41272)
		(end 109.579664 -218.20632)
		(width 0.0889)
		(layer "In11.Cu")
		(net "P5E_CPU1_PE1_RX_DN<9>")
	)
	(arc
		(start 108.915708 -215.418924)
		(mid 108.970074 -215.24168)
		(end 109.102652 -215.112092)
		(width 0.0889)
		(layer "In11.Cu")
		(net "P5E_CPU1_PE1_RX_DN<9>")
	)
	(arc
		(start 109.098842 -215.758522)
		(mid 108.964712 -215.621824)
		(end 108.915708 -215.436704)
		(width 0.0889)
		(layer "In11.Cu")
		(net "P5E_CPU1_PE1_RX_DN<9>")
	)
	(arc
		(start 110.983268 -221.623382)
		(mid 111.187603 -221.420777)
		(end 111.265716 -221.14383)
		(width 0.0889)
		(layer "In11.Cu")
		(net "P5E_CPU1_PE1_RX_DN<9>")
	)
	(arc
		(start 110.795816 -220.309948)
		(mid 110.717705 -220.032999)
		(end 110.513368 -219.830396)
		(width 0.0889)
		(layer "In11.Cu")
		(net "P5E_CPU1_PE1_RX_DN<9>")
	)
	(arc
		(start 109.583474 -217.547444)
		(mid 109.855556 -217.064728)
		(end 109.584236 -216.581482)
		(width 0.0889)
		(layer "In11.Cu")
		(net "P5E_CPU1_PE1_RX_DN<9>")
	)
	(segment
		(start 32.3469 -8.320024)
		(end 32.3469 -7.775702)
		(width 0.13208)
		(layer "F.Cu")
		(net "P5E_CPU1_PE1_RX_DN<8>")
	)
	(segment
		(start 32.1818 -7.610602)
		(end 32.1818 -5.265928)
		(width 0.13208)
		(layer "F.Cu")
		(net "P5E_CPU1_PE1_RX_DN<8>")
	)
	(segment
		(start 111.640112 -221.669864)
		(end 111.640112 -221.134178)
		(width 0.13208)
		(layer "F.Cu")
		(net "P5E_CPU1_PE1_RX_DN<8>")
	)
	(segment
		(start 32.3469 -7.775702)
		(end 32.1818 -7.610602)
		(width 0.13208)
		(layer "F.Cu")
		(net "P5E_CPU1_PE1_RX_DN<8>")
	)
	(segment
		(start 111.640112 -221.134178)
		(end 111.640366 -221.133924)
		(width 0.13208)
		(layer "F.Cu")
		(net "P5E_CPU1_PE1_RX_DN<8>")
	)
	(segment
		(start 32.1818 -5.265928)
		(end 32.485076 -4.962652)
		(width 0.13208)
		(layer "F.Cu")
		(net "P5E_CPU1_PE1_RX_DN<8>")
	)
	(segment
		(start 36.599368 -17.636998)
		(end 35.563302 -14.528038)
		(width 0.14732)
		(layer "In11.Cu")
		(net "P5E_CPU1_PE1_RX_DN<8>")
	)
	(segment
		(start 111.735616 -220.334078)
		(end 111.735616 -220.319854)
		(width 0.0889)
		(layer "In11.Cu")
		(net "P5E_CPU1_PE1_RX_DN<8>")
	)
	(segment
		(start 110.795562 -215.452198)
		(end 110.795562 -215.414606)
		(width 0.0889)
		(layer "In11.Cu")
		(net "P5E_CPU1_PE1_RX_DN<8>")
	)
	(segment
		(start 110.795816 -213.105492)
		(end 110.83798 -213.063328)
		(width 0.0889)
		(layer "In11.Cu")
		(net "P5E_CPU1_PE1_RX_DN<8>")
	)
	(segment
		(start 110.52556 -218.209876)
		(end 110.515908 -218.204288)
		(width 0.0889)
		(layer "In11.Cu")
		(net "P5E_CPU1_PE1_RX_DN<8>")
	)
	(segment
		(start 111.453168 -219.830396)
		(end 111.444278 -219.825316)
		(width 0.0889)
		(layer "In11.Cu")
		(net "P5E_CPU1_PE1_RX_DN<8>")
	)
	(segment
		(start 111.640366 -221.133924)
		(end 111.483902 -220.862906)
		(width 0.0889)
		(layer "In11.Cu")
		(net "P5E_CPU1_PE1_RX_DN<8>")
	)
	(segment
		(start 110.325916 -214.363808)
		(end 110.795816 -213.893908)
		(width 0.0889)
		(layer "In11.Cu")
		(net "P5E_CPU1_PE1_RX_DN<8>")
	)
	(segment
		(start 35.563302 -14.528038)
		(end 35.563048 -14.528038)
		(width 0.14732)
		(layer "In11.Cu")
		(net "P5E_CPU1_PE1_RX_DN<8>")
	)
	(segment
		(start 33.869884 -9.448292)
		(end 33.665922 -9.172956)
		(width 0.14732)
		(layer "In11.Cu")
		(net "P5E_CPU1_PE1_RX_DN<8>")
	)
	(segment
		(start 110.795816 -213.893908)
		(end 110.795816 -213.105492)
		(width 0.0889)
		(layer "In11.Cu")
		(net "P5E_CPU1_PE1_RX_DN<8>")
	)
	(segment
		(start 110.325916 -214.622634)
		(end 110.325916 -214.363808)
		(width 0.0889)
		(layer "In11.Cu")
		(net "P5E_CPU1_PE1_RX_DN<8>")
	)
	(segment
		(start 110.83798 -211.210398)
		(end 110.619794 -208.239868)
		(width 0.14732)
		(layer "In11.Cu")
		(net "P5E_CPU1_PE1_RX_DN<8>")
	)
	(segment
		(start 32.190436 -5.257292)
		(end 32.485076 -4.962652)
		(width 0.14732)
		(layer "In11.Cu")
		(net "P5E_CPU1_PE1_RX_DN<8>")
	)
	(segment
		(start 110.504478 -217.559128)
		(end 110.513368 -217.554048)
		(width 0.0889)
		(layer "In11.Cu")
		(net "P5E_CPU1_PE1_RX_DN<8>")
	)
	(segment
		(start 110.515908 -218.204288)
		(end 110.515146 -218.20378)
		(width 0.0889)
		(layer "In11.Cu")
		(net "P5E_CPU1_PE1_RX_DN<8>")
	)
	(segment
		(start 32.190436 -6.96595)
		(end 32.190436 -5.257292)
		(width 0.14732)
		(layer "In11.Cu")
		(net "P5E_CPU1_PE1_RX_DN<8>")
	)
	(segment
		(start 110.83798 -213.04123)
		(end 110.83798 -211.210398)
		(width 0.14732)
		(layer "In11.Cu")
		(net "P5E_CPU1_PE1_RX_DN<8>")
	)
	(segment
		(start 33.665922 -9.172956)
		(end 32.190436 -6.96595)
		(width 0.14732)
		(layer "In11.Cu")
		(net "P5E_CPU1_PE1_RX_DN<8>")
	)
	(segment
		(start 110.512352 -215.92667)
		(end 110.513368 -215.926162)
		(width 0.0889)
		(layer "In11.Cu")
		(net "P5E_CPU1_PE1_RX_DN<8>")
	)
	(segment
		(start 110.504478 -215.931242)
		(end 110.512352 -215.92667)
		(width 0.0889)
		(layer "In11.Cu")
		(net "P5E_CPU1_PE1_RX_DN<8>")
	)
	(segment
		(start 110.619794 -208.239868)
		(end 106.54157 -180.612542)
		(width 0.14732)
		(layer "In11.Cu")
		(net "P5E_CPU1_PE1_RX_DN<8>")
	)
	(segment
		(start 110.513368 -216.574878)
		(end 110.504478 -216.569798)
		(width 0.0889)
		(layer "In11.Cu")
		(net "P5E_CPU1_PE1_RX_DN<8>")
	)
	(segment
		(start 35.563048 -14.528038)
		(end 33.869884 -9.448292)
		(width 0.14732)
		(layer "In11.Cu")
		(net "P5E_CPU1_PE1_RX_DN<8>")
	)
	(segment
		(start 37.29736 -18.766282)
		(end 36.599368 -17.636998)
		(width 0.14732)
		(layer "In11.Cu")
		(net "P5E_CPU1_PE1_RX_DN<8>")
	)
	(segment
		(start 110.513368 -214.946992)
		(end 110.504478 -214.941912)
		(width 0.0889)
		(layer "In11.Cu")
		(net "P5E_CPU1_PE1_RX_DN<8>")
	)
	(segment
		(start 110.795816 -217.082878)
		(end 110.795816 -217.05443)
		(width 0.0889)
		(layer "In11.Cu")
		(net "P5E_CPU1_PE1_RX_DN<8>")
	)
	(segment
		(start 111.459264 -219.833952)
		(end 111.453168 -219.830396)
		(width 0.0889)
		(layer "In11.Cu")
		(net "P5E_CPU1_PE1_RX_DN<8>")
	)
	(segment
		(start 110.51413 -218.203272)
		(end 110.504478 -218.197684)
		(width 0.0889)
		(layer "In11.Cu")
		(net "P5E_CPU1_PE1_RX_DN<8>")
	)
	(segment
		(start 110.515146 -218.20378)
		(end 110.51413 -218.203272)
		(width 0.0889)
		(layer "In11.Cu")
		(net "P5E_CPU1_PE1_RX_DN<8>")
	)
	(segment
		(start 106.54157 -180.612542)
		(end 55.93969 -58.450226)
		(width 0.14732)
		(layer "In11.Cu")
		(net "P5E_CPU1_PE1_RX_DN<8>")
	)
	(segment
		(start 55.93969 -58.450226)
		(end 37.29736 -18.766282)
		(width 0.14732)
		(layer "In11.Cu")
		(net "P5E_CPU1_PE1_RX_DN<8>")
	)
	(segment
		(start 110.83798 -213.063328)
		(end 110.83798 -213.04123)
		(width 0.0889)
		(layer "In11.Cu")
		(net "P5E_CPU1_PE1_RX_DN<8>")
	)
	(segment
		(start 111.265716 -219.506038)
		(end 111.265716 -219.48394)
		(width 0.0889)
		(layer "In11.Cu")
		(net "P5E_CPU1_PE1_RX_DN<8>")
	)
	(segment
		(start 110.983522 -219.016326)
		(end 110.974632 -219.011246)
		(width 0.0889)
		(layer "In11.Cu")
		(net "P5E_CPU1_PE1_RX_DN<8>")
	)
	(segment
		(start 111.483902 -220.862906)
		(end 111.508032 -220.773752)
		(width 0.0889)
		(layer "In11.Cu")
		(net "P5E_CPU1_PE1_RX_DN<8>")
	)
	(arc
		(start 111.735616 -220.319854)
		(mid 111.6617 -220.040352)
		(end 111.459264 -219.833952)
		(width 0.0889)
		(layer "In11.Cu")
		(net "P5E_CPU1_PE1_RX_DN<8>")
	)
	(arc
		(start 111.265716 -219.48394)
		(mid 111.184805 -219.213812)
		(end 110.983522 -219.016326)
		(width 0.0889)
		(layer "In11.Cu")
		(net "P5E_CPU1_PE1_RX_DN<8>")
	)
	(arc
		(start 110.32617 -217.888566)
		(mid 110.326003 -217.87739)
		(end 110.32617 -217.866214)
		(width 0.0889)
		(layer "In11.Cu")
		(net "P5E_CPU1_PE1_RX_DN<8>")
	)
	(arc
		(start 110.32617 -216.257124)
		(mid 110.326076 -216.248742)
		(end 110.32617 -216.24036)
		(width 0.0889)
		(layer "In11.Cu")
		(net "P5E_CPU1_PE1_RX_DN<8>")
	)
	(arc
		(start 110.79607 -218.691968)
		(mid 110.723773 -218.415587)
		(end 110.52556 -218.209876)
		(width 0.0889)
		(layer "In11.Cu")
		(net "P5E_CPU1_PE1_RX_DN<8>")
	)
	(arc
		(start 110.32617 -216.24036)
		(mid 110.376185 -216.063229)
		(end 110.504478 -215.931242)
		(width 0.0889)
		(layer "In11.Cu")
		(net "P5E_CPU1_PE1_RX_DN<8>")
	)
	(arc
		(start 111.524796 -220.760798)
		(mid 111.677303 -220.5707)
		(end 111.735616 -220.334078)
		(width 0.0889)
		(layer "In11.Cu")
		(net "P5E_CPU1_PE1_RX_DN<8>")
	)
	(arc
		(start 110.795562 -215.414606)
		(mid 110.714651 -215.144478)
		(end 110.513368 -214.946992)
		(width 0.0889)
		(layer "In11.Cu")
		(net "P5E_CPU1_PE1_RX_DN<8>")
	)
	(arc
		(start 111.444278 -219.825316)
		(mid 111.313364 -219.688956)
		(end 111.265716 -219.506038)
		(width 0.0889)
		(layer "In11.Cu")
		(net "P5E_CPU1_PE1_RX_DN<8>")
	)
	(arc
		(start 110.795816 -217.05443)
		(mid 110.717705 -216.777481)
		(end 110.513368 -216.574878)
		(width 0.0889)
		(layer "In11.Cu")
		(net "P5E_CPU1_PE1_RX_DN<8>")
	)
	(arc
		(start 110.513368 -215.926162)
		(mid 110.716191 -215.725931)
		(end 110.795562 -215.452198)
		(width 0.0889)
		(layer "In11.Cu")
		(net "P5E_CPU1_PE1_RX_DN<8>")
	)
	(arc
		(start 110.504478 -214.941912)
		(mid 110.373564 -214.805552)
		(end 110.325916 -214.622634)
		(width 0.0889)
		(layer "In11.Cu")
		(net "P5E_CPU1_PE1_RX_DN<8>")
	)
	(arc
		(start 110.32617 -217.866214)
		(mid 110.376641 -217.690206)
		(end 110.504478 -217.559128)
		(width 0.0889)
		(layer "In11.Cu")
		(net "P5E_CPU1_PE1_RX_DN<8>")
	)
	(arc
		(start 110.513368 -217.554048)
		(mid 110.715654 -217.355067)
		(end 110.795816 -217.082878)
		(width 0.0889)
		(layer "In11.Cu")
		(net "P5E_CPU1_PE1_RX_DN<8>")
	)
	(arc
		(start 110.504478 -218.197684)
		(mid 110.376159 -218.065712)
		(end 110.32617 -217.888566)
		(width 0.0889)
		(layer "In11.Cu")
		(net "P5E_CPU1_PE1_RX_DN<8>")
	)
	(arc
		(start 110.974632 -219.011246)
		(mid 110.843718 -218.874886)
		(end 110.79607 -218.691968)
		(width 0.0889)
		(layer "In11.Cu")
		(net "P5E_CPU1_PE1_RX_DN<8>")
	)
	(arc
		(start 110.504478 -216.569798)
		(mid 110.375274 -216.436284)
		(end 110.32617 -216.257124)
		(width 0.0889)
		(layer "In11.Cu")
		(net "P5E_CPU1_PE1_RX_DN<8>")
	)
	(arc
		(start 111.508032 -220.773752)
		(mid 111.516475 -220.767354)
		(end 111.524796 -220.760798)
		(width 0.0889)
		(layer "In11.Cu")
		(net "P5E_CPU1_PE1_RX_DN<8>")
	)
	(segment
		(start 39.65702 -8.320024)
		(end 39.65702 -7.779004)
		(width 0.13208)
		(layer "F.Cu")
		(net "P5E_CPU1_PE1_RX_DN<7>")
	)
	(segment
		(start 39.65702 -7.779004)
		(end 39.48811 -7.610094)
		(width 0.13208)
		(layer "F.Cu")
		(net "P5E_CPU1_PE1_RX_DN<7>")
	)
	(segment
		(start 39.48811 -7.610094)
		(end 39.48811 -7.026656)
		(width 0.13208)
		(layer "F.Cu")
		(net "P5E_CPU1_PE1_RX_DN<7>")
	)
	(segment
		(start 39.48811 -7.026656)
		(end 39.79037 -6.724396)
		(width 0.13208)
		(layer "F.Cu")
		(net "P5E_CPU1_PE1_RX_DN<7>")
	)
	(segment
		(start 112.110266 -221.947994)
		(end 112.110012 -221.94774)
		(width 0.13208)
		(layer "F.Cu")
		(net "P5E_CPU1_PE1_RX_DN<7>")
	)
	(segment
		(start 112.110266 -222.48368)
		(end 112.110266 -221.947994)
		(width 0.13208)
		(layer "F.Cu")
		(net "P5E_CPU1_PE1_RX_DN<7>")
	)
	(segment
		(start 39.49573 -7.019036)
		(end 39.49573 -12.380722)
		(width 0.14732)
		(layer "In11.Cu")
		(net "P5E_CPU1_PE1_RX_DN<7>")
	)
	(segment
		(start 112.868202 -221.619826)
		(end 112.86744 -221.620334)
		(width 0.0889)
		(layer "In11.Cu")
		(net "P5E_CPU1_PE1_RX_DN<7>")
	)
	(segment
		(start 112.863376 -221.622874)
		(end 112.862614 -221.623382)
		(width 0.0889)
		(layer "In11.Cu")
		(net "P5E_CPU1_PE1_RX_DN<7>")
	)
	(segment
		(start 111.735362 -217.053922)
		(end 111.735616 -217.064336)
		(width 0.0889)
		(layer "In11.Cu")
		(net "P5E_CPU1_PE1_RX_DN<7>")
	)
	(segment
		(start 40.19296 -17.277842)
		(end 40.19296 -17.807178)
		(width 0.14732)
		(layer "In11.Cu")
		(net "P5E_CPU1_PE1_RX_DN<7>")
	)
	(segment
		(start 111.777526 -213.04123)
		(end 111.777526 -213.052406)
		(width 0.0889)
		(layer "In11.Cu")
		(net "P5E_CPU1_PE1_RX_DN<7>")
	)
	(segment
		(start 39.49573 -12.380722)
		(end 39.500556 -12.447524)
		(width 0.14732)
		(layer "In11.Cu")
		(net "P5E_CPU1_PE1_RX_DN<7>")
	)
	(segment
		(start 112.862614 -221.623382)
		(end 112.847882 -221.632018)
		(width 0.0889)
		(layer "In11.Cu")
		(net "P5E_CPU1_PE1_RX_DN<7>")
	)
	(segment
		(start 111.538766 -207.45196)
		(end 111.777526 -210.705446)
		(width 0.14732)
		(layer "In11.Cu")
		(net "P5E_CPU1_PE1_RX_DN<7>")
	)
	(segment
		(start 112.392968 -219.830396)
		(end 112.392714 -219.83065)
		(width 0.0889)
		(layer "In11.Cu")
		(net "P5E_CPU1_PE1_RX_DN<7>")
	)
	(segment
		(start 112.384078 -219.825316)
		(end 112.392968 -219.830396)
		(width 0.0889)
		(layer "In11.Cu")
		(net "P5E_CPU1_PE1_RX_DN<7>")
	)
	(segment
		(start 111.735362 -213.09457)
		(end 111.735362 -213.863682)
		(width 0.0889)
		(layer "In11.Cu")
		(net "P5E_CPU1_PE1_RX_DN<7>")
	)
	(segment
		(start 111.441738 -218.195906)
		(end 111.453168 -218.20251)
		(width 0.0889)
		(layer "In11.Cu")
		(net "P5E_CPU1_PE1_RX_DN<7>")
	)
	(segment
		(start 111.265462 -214.333582)
		(end 111.265462 -214.709248)
		(width 0.0889)
		(layer "In11.Cu")
		(net "P5E_CPU1_PE1_RX_DN<7>")
	)
	(segment
		(start 111.73587 -218.676728)
		(end 111.735616 -218.692222)
		(width 0.0889)
		(layer "In11.Cu")
		(net "P5E_CPU1_PE1_RX_DN<7>")
	)
	(segment
		(start 112.86744 -221.620334)
		(end 112.863376 -221.622874)
		(width 0.0889)
		(layer "In11.Cu")
		(net "P5E_CPU1_PE1_RX_DN<7>")
	)
	(segment
		(start 56.692292 -57.82183)
		(end 107.565952 -180.640736)
		(width 0.14732)
		(layer "In11.Cu")
		(net "P5E_CPU1_PE1_RX_DN<7>")
	)
	(segment
		(start 112.266476 -221.676722)
		(end 112.110012 -221.94774)
		(width 0.0889)
		(layer "In11.Cu")
		(net "P5E_CPU1_PE1_RX_DN<7>")
	)
	(segment
		(start 111.777526 -210.705446)
		(end 111.777526 -213.04123)
		(width 0.14732)
		(layer "In11.Cu")
		(net "P5E_CPU1_PE1_RX_DN<7>")
	)
	(segment
		(start 112.35563 -221.652846)
		(end 112.266476 -221.676722)
		(width 0.0889)
		(layer "In11.Cu")
		(net "P5E_CPU1_PE1_RX_DN<7>")
	)
	(segment
		(start 111.922814 -219.01658)
		(end 111.92891 -219.020136)
		(width 0.0889)
		(layer "In11.Cu")
		(net "P5E_CPU1_PE1_RX_DN<7>")
	)
	(segment
		(start 39.500556 -12.447524)
		(end 40.19296 -17.277842)
		(width 0.14732)
		(layer "In11.Cu")
		(net "P5E_CPU1_PE1_RX_DN<7>")
	)
	(segment
		(start 107.565952 -180.640736)
		(end 111.538766 -207.45196)
		(width 0.14732)
		(layer "In11.Cu")
		(net "P5E_CPU1_PE1_RX_DN<7>")
	)
	(segment
		(start 39.82212 -19.535648)
		(end 39.955724 -19.858228)
		(width 0.14732)
		(layer "In11.Cu")
		(net "P5E_CPU1_PE1_RX_DN<7>")
	)
	(segment
		(start 40.19296 -17.807178)
		(end 39.82212 -18.702528)
		(width 0.14732)
		(layer "In11.Cu")
		(net "P5E_CPU1_PE1_RX_DN<7>")
	)
	(segment
		(start 111.735362 -213.863682)
		(end 111.265462 -214.333582)
		(width 0.0889)
		(layer "In11.Cu")
		(net "P5E_CPU1_PE1_RX_DN<7>")
	)
	(segment
		(start 111.735616 -218.692222)
		(end 111.735616 -218.700858)
		(width 0.0889)
		(layer "In11.Cu")
		(net "P5E_CPU1_PE1_RX_DN<7>")
	)
	(segment
		(start 112.86236 -220.644466)
		(end 112.873028 -220.650816)
		(width 0.0889)
		(layer "In11.Cu")
		(net "P5E_CPU1_PE1_RX_DN<7>")
	)
	(segment
		(start 112.874298 -221.61627)
		(end 112.868202 -221.619826)
		(width 0.0889)
		(layer "In11.Cu")
		(net "P5E_CPU1_PE1_RX_DN<7>")
	)
	(segment
		(start 111.735616 -217.064336)
		(end 111.735616 -217.07856)
		(width 0.0889)
		(layer "In11.Cu")
		(net "P5E_CPU1_PE1_RX_DN<7>")
	)
	(segment
		(start 111.265716 -217.86977)
		(end 111.265716 -217.878406)
		(width 0.0889)
		(layer "In11.Cu")
		(net "P5E_CPU1_PE1_RX_DN<7>")
	)
	(segment
		(start 39.955724 -19.858228)
		(end 56.692292 -57.82183)
		(width 0.14732)
		(layer "In11.Cu")
		(net "P5E_CPU1_PE1_RX_DN<7>")
	)
	(segment
		(start 111.777526 -213.052406)
		(end 111.735362 -213.09457)
		(width 0.0889)
		(layer "In11.Cu")
		(net "P5E_CPU1_PE1_RX_DN<7>")
	)
	(segment
		(start 39.82212 -18.702528)
		(end 39.82212 -19.535648)
		(width 0.14732)
		(layer "In11.Cu")
		(net "P5E_CPU1_PE1_RX_DN<7>")
	)
	(segment
		(start 111.735108 -215.239854)
		(end 111.735108 -215.436704)
		(width 0.0889)
		(layer "In11.Cu")
		(net "P5E_CPU1_PE1_RX_DN<7>")
	)
	(segment
		(start 111.265462 -216.238074)
		(end 111.265462 -216.258394)
		(width 0.0889)
		(layer "In11.Cu")
		(net "P5E_CPU1_PE1_RX_DN<7>")
	)
	(segment
		(start 111.45266 -216.574878)
		(end 111.463328 -216.581228)
		(width 0.0889)
		(layer "In11.Cu")
		(net "P5E_CPU1_PE1_RX_DN<7>")
	)
	(segment
		(start 112.674908 -220.309186)
		(end 112.674908 -220.331284)
		(width 0.0889)
		(layer "In11.Cu")
		(net "P5E_CPU1_PE1_RX_DN<7>")
	)
	(segment
		(start 39.79037 -6.724396)
		(end 39.49573 -7.019036)
		(width 0.14732)
		(layer "In11.Cu")
		(net "P5E_CPU1_PE1_RX_DN<7>")
	)
	(segment
		(start 111.466122 -215.918034)
		(end 111.445802 -215.929972)
		(width 0.0889)
		(layer "In11.Cu")
		(net "P5E_CPU1_PE1_RX_DN<7>")
	)
	(arc
		(start 111.445802 -215.929972)
		(mid 111.316598 -216.061186)
		(end 111.265462 -216.238074)
		(width 0.0889)
		(layer "In11.Cu")
		(net "P5E_CPU1_PE1_RX_DN<7>")
	)
	(arc
		(start 112.847882 -221.632018)
		(mid 112.614967 -221.698229)
		(end 112.375696 -221.660974)
		(width 0.0889)
		(layer "In11.Cu")
		(net "P5E_CPU1_PE1_RX_DN<7>")
	)
	(arc
		(start 112.205516 -219.506038)
		(mid 112.253195 -219.688938)
		(end 112.384078 -219.825316)
		(width 0.0889)
		(layer "In11.Cu")
		(net "P5E_CPU1_PE1_RX_DN<7>")
	)
	(arc
		(start 111.735616 -218.700858)
		(mid 111.787886 -218.883223)
		(end 111.922814 -219.01658)
		(width 0.0889)
		(layer "In11.Cu")
		(net "P5E_CPU1_PE1_RX_DN<7>")
	)
	(arc
		(start 111.452914 -217.554048)
		(mid 111.317981 -217.687402)
		(end 111.265716 -217.86977)
		(width 0.0889)
		(layer "In11.Cu")
		(net "P5E_CPU1_PE1_RX_DN<7>")
	)
	(arc
		(start 111.463328 -216.581228)
		(mid 111.660136 -216.782583)
		(end 111.735362 -217.053922)
		(width 0.0889)
		(layer "In11.Cu")
		(net "P5E_CPU1_PE1_RX_DN<7>")
	)
	(arc
		(start 111.265716 -217.878406)
		(mid 111.312662 -218.059925)
		(end 111.441738 -218.195906)
		(width 0.0889)
		(layer "In11.Cu")
		(net "P5E_CPU1_PE1_RX_DN<7>")
	)
	(arc
		(start 111.735108 -215.436704)
		(mid 111.6633 -215.7124)
		(end 111.466122 -215.918034)
		(width 0.0889)
		(layer "In11.Cu")
		(net "P5E_CPU1_PE1_RX_DN<7>")
	)
	(arc
		(start 112.873028 -220.650816)
		(mid 113.145109 -221.133183)
		(end 112.874298 -221.61627)
		(width 0.0889)
		(layer "In11.Cu")
		(net "P5E_CPU1_PE1_RX_DN<7>")
	)
	(arc
		(start 112.392714 -219.83065)
		(mid 112.596692 -220.032826)
		(end 112.674908 -220.309186)
		(width 0.0889)
		(layer "In11.Cu")
		(net "P5E_CPU1_PE1_RX_DN<7>")
	)
	(arc
		(start 111.92891 -219.020136)
		(mid 112.131497 -219.226487)
		(end 112.205516 -219.506038)
		(width 0.0889)
		(layer "In11.Cu")
		(net "P5E_CPU1_PE1_RX_DN<7>")
	)
	(arc
		(start 111.265462 -214.709248)
		(mid 111.340624 -214.824138)
		(end 111.449612 -214.907622)
		(width 0.0889)
		(layer "In11.Cu")
		(net "P5E_CPU1_PE1_RX_DN<7>")
	)
	(arc
		(start 112.375696 -221.660974)
		(mid 112.365624 -221.657007)
		(end 112.35563 -221.652846)
		(width 0.0889)
		(layer "In11.Cu")
		(net "P5E_CPU1_PE1_RX_DN<7>")
	)
	(arc
		(start 111.735616 -217.07856)
		(mid 111.656397 -217.353245)
		(end 111.452914 -217.554048)
		(width 0.0889)
		(layer "In11.Cu")
		(net "P5E_CPU1_PE1_RX_DN<7>")
	)
	(arc
		(start 111.449612 -214.907622)
		(mid 111.623857 -215.046668)
		(end 111.735108 -215.239854)
		(width 0.0889)
		(layer "In11.Cu")
		(net "P5E_CPU1_PE1_RX_DN<7>")
	)
	(arc
		(start 111.453168 -218.20251)
		(mid 111.656411 -218.402736)
		(end 111.73587 -218.676728)
		(width 0.0889)
		(layer "In11.Cu")
		(net "P5E_CPU1_PE1_RX_DN<7>")
	)
	(arc
		(start 112.674908 -220.331284)
		(mid 112.727963 -220.512221)
		(end 112.86236 -220.644466)
		(width 0.0889)
		(layer "In11.Cu")
		(net "P5E_CPU1_PE1_RX_DN<7>")
	)
	(arc
		(start 111.265462 -216.258394)
		(mid 111.3176 -216.441162)
		(end 111.45266 -216.574878)
		(width 0.0889)
		(layer "In11.Cu")
		(net "P5E_CPU1_PE1_RX_DN<7>")
	)
	(segment
		(start 41.29405 -5.263388)
		(end 41.594786 -4.962652)
		(width 0.13208)
		(layer "F.Cu")
		(net "P5E_CPU1_PE1_RX_DN<6>")
	)
	(segment
		(start 41.456864 -7.775702)
		(end 41.29405 -7.612888)
		(width 0.13208)
		(layer "F.Cu")
		(net "P5E_CPU1_PE1_RX_DN<6>")
	)
	(segment
		(start 41.594786 -4.962652)
		(end 41.59504 -4.962652)
		(width 0.13208)
		(layer "F.Cu")
		(net "P5E_CPU1_PE1_RX_DN<6>")
	)
	(segment
		(start 113.519712 -221.669864)
		(end 113.519966 -221.66961)
		(width 0.13208)
		(layer "F.Cu")
		(net "P5E_CPU1_PE1_RX_DN<6>")
	)
	(segment
		(start 41.456864 -8.320024)
		(end 41.456864 -7.775702)
		(width 0.13208)
		(layer "F.Cu")
		(net "P5E_CPU1_PE1_RX_DN<6>")
	)
	(segment
		(start 41.29405 -7.612888)
		(end 41.29405 -5.263388)
		(width 0.13208)
		(layer "F.Cu")
		(net "P5E_CPU1_PE1_RX_DN<6>")
	)
	(segment
		(start 113.519966 -221.66961)
		(end 113.519966 -221.133924)
		(width 0.13208)
		(layer "F.Cu")
		(net "P5E_CPU1_PE1_RX_DN<6>")
	)
	(segment
		(start 52.750212 -45.861478)
		(end 43.26763 -18.884138)
		(width 0.14732)
		(layer "In11.Cu")
		(net "P5E_CPU1_PE1_RX_DN<6>")
	)
	(segment
		(start 112.675162 -213.105492)
		(end 112.717326 -213.063328)
		(width 0.0889)
		(layer "In11.Cu")
		(net "P5E_CPU1_PE1_RX_DN<6>")
	)
	(segment
		(start 112.86871 -219.020136)
		(end 112.862614 -219.01658)
		(width 0.0889)
		(layer "In11.Cu")
		(net "P5E_CPU1_PE1_RX_DN<6>")
	)
	(segment
		(start 112.675416 -217.072972)
		(end 112.675416 -217.064336)
		(width 0.0889)
		(layer "In11.Cu")
		(net "P5E_CPU1_PE1_RX_DN<6>")
	)
	(segment
		(start 43.26763 -18.884138)
		(end 42.605198 -17.89303)
		(width 0.14732)
		(layer "In11.Cu")
		(net "P5E_CPU1_PE1_RX_DN<6>")
	)
	(segment
		(start 112.717326 -213.063328)
		(end 112.717326 -213.04123)
		(width 0.0889)
		(layer "In11.Cu")
		(net "P5E_CPU1_PE1_RX_DN<6>")
	)
	(segment
		(start 41.3004 -12.515596)
		(end 41.3004 -5.257292)
		(width 0.14732)
		(layer "In11.Cu")
		(net "P5E_CPU1_PE1_RX_DN<6>")
	)
	(segment
		(start 113.615216 -220.334078)
		(end 113.615216 -220.319854)
		(width 0.0889)
		(layer "In11.Cu")
		(net "P5E_CPU1_PE1_RX_DN<6>")
	)
	(segment
		(start 41.3004 -5.257292)
		(end 41.59504 -4.962652)
		(width 0.14732)
		(layer "In11.Cu")
		(net "P5E_CPU1_PE1_RX_DN<6>")
	)
	(segment
		(start 112.389412 -214.907114)
		(end 112.388904 -214.907622)
		(width 0.0889)
		(layer "In11.Cu")
		(net "P5E_CPU1_PE1_RX_DN<6>")
	)
	(segment
		(start 42.605198 -17.89303)
		(end 42.149268 -16.01216)
		(width 0.14732)
		(layer "In11.Cu")
		(net "P5E_CPU1_PE1_RX_DN<6>")
	)
	(segment
		(start 113.332768 -219.830396)
		(end 113.323878 -219.825316)
		(width 0.0889)
		(layer "In11.Cu")
		(net "P5E_CPU1_PE1_RX_DN<6>")
	)
	(segment
		(start 112.717326 -213.04123)
		(end 112.717326 -210.6549)
		(width 0.14732)
		(layer "In11.Cu")
		(net "P5E_CPU1_PE1_RX_DN<6>")
	)
	(segment
		(start 113.519966 -221.133924)
		(end 113.363502 -220.862906)
		(width 0.0889)
		(layer "In11.Cu")
		(net "P5E_CPU1_PE1_RX_DN<6>")
	)
	(segment
		(start 112.862614 -219.01658)
		(end 112.853724 -219.0115)
		(width 0.0889)
		(layer "In11.Cu")
		(net "P5E_CPU1_PE1_RX_DN<6>")
	)
	(segment
		(start 42.149268 -16.01216)
		(end 42.14876 -16.011652)
		(width 0.14732)
		(layer "In11.Cu")
		(net "P5E_CPU1_PE1_RX_DN<6>")
	)
	(segment
		(start 113.145316 -217.878406)
		(end 113.145316 -217.864182)
		(width 0.0889)
		(layer "In11.Cu")
		(net "P5E_CPU1_PE1_RX_DN<6>")
	)
	(segment
		(start 112.862614 -218.367864)
		(end 112.86871 -218.364308)
		(width 0.0889)
		(layer "In11.Cu")
		(net "P5E_CPU1_PE1_RX_DN<6>")
	)
	(segment
		(start 113.338864 -219.833952)
		(end 113.332768 -219.830396)
		(width 0.0889)
		(layer "In11.Cu")
		(net "P5E_CPU1_PE1_RX_DN<6>")
	)
	(segment
		(start 112.853724 -218.372944)
		(end 112.862614 -218.367864)
		(width 0.0889)
		(layer "In11.Cu")
		(net "P5E_CPU1_PE1_RX_DN<6>")
	)
	(segment
		(start 112.675162 -215.44661)
		(end 112.675162 -215.238838)
		(width 0.0889)
		(layer "In11.Cu")
		(net "P5E_CPU1_PE1_RX_DN<6>")
	)
	(segment
		(start 112.205008 -214.709248)
		(end 112.205008 -214.26297)
		(width 0.0889)
		(layer "In11.Cu")
		(net "P5E_CPU1_PE1_RX_DN<6>")
	)
	(segment
		(start 113.363502 -220.862906)
		(end 113.387632 -220.773752)
		(width 0.0889)
		(layer "In11.Cu")
		(net "P5E_CPU1_PE1_RX_DN<6>")
	)
	(segment
		(start 112.675162 -213.792816)
		(end 112.675162 -213.105492)
		(width 0.0889)
		(layer "In11.Cu")
		(net "P5E_CPU1_PE1_RX_DN<6>")
	)
	(segment
		(start 112.444784 -206.940912)
		(end 108.561632 -180.600858)
		(width 0.14732)
		(layer "In11.Cu")
		(net "P5E_CPU1_PE1_RX_DN<6>")
	)
	(segment
		(start 108.561632 -180.600858)
		(end 52.750212 -45.861478)
		(width 0.14732)
		(layer "In11.Cu")
		(net "P5E_CPU1_PE1_RX_DN<6>")
	)
	(segment
		(start 112.39881 -216.578434)
		(end 112.392714 -216.574878)
		(width 0.0889)
		(layer "In11.Cu")
		(net "P5E_CPU1_PE1_RX_DN<6>")
	)
	(segment
		(start 112.205008 -214.26297)
		(end 112.675162 -213.792816)
		(width 0.0889)
		(layer "In11.Cu")
		(net "P5E_CPU1_PE1_RX_DN<6>")
	)
	(segment
		(start 112.205516 -216.259156)
		(end 112.205516 -216.241884)
		(width 0.0889)
		(layer "In11.Cu")
		(net "P5E_CPU1_PE1_RX_DN<6>")
	)
	(segment
		(start 112.717326 -210.6549)
		(end 112.444784 -206.940912)
		(width 0.14732)
		(layer "In11.Cu")
		(net "P5E_CPU1_PE1_RX_DN<6>")
	)
	(segment
		(start 42.14876 -16.011652)
		(end 41.3004 -12.515596)
		(width 0.14732)
		(layer "In11.Cu")
		(net "P5E_CPU1_PE1_RX_DN<6>")
	)
	(arc
		(start 112.388904 -214.907622)
		(mid 112.280073 -214.82409)
		(end 112.205008 -214.709248)
		(width 0.0889)
		(layer "In11.Cu")
		(net "P5E_CPU1_PE1_RX_DN<6>")
	)
	(arc
		(start 113.387632 -220.773752)
		(mid 113.396075 -220.767354)
		(end 113.404396 -220.760798)
		(width 0.0889)
		(layer "In11.Cu")
		(net "P5E_CPU1_PE1_RX_DN<6>")
	)
	(arc
		(start 113.323878 -219.825316)
		(mid 113.192964 -219.688956)
		(end 113.145316 -219.506038)
		(width 0.0889)
		(layer "In11.Cu")
		(net "P5E_CPU1_PE1_RX_DN<6>")
	)
	(arc
		(start 112.853724 -219.0115)
		(mid 112.675127 -218.692222)
		(end 112.853724 -218.372944)
		(width 0.0889)
		(layer "In11.Cu")
		(net "P5E_CPU1_PE1_RX_DN<6>")
	)
	(arc
		(start 112.205516 -216.241884)
		(mid 112.257786 -216.059519)
		(end 112.392714 -215.926162)
		(width 0.0889)
		(layer "In11.Cu")
		(net "P5E_CPU1_PE1_RX_DN<6>")
	)
	(arc
		(start 113.404396 -220.760798)
		(mid 113.556903 -220.5707)
		(end 113.615216 -220.334078)
		(width 0.0889)
		(layer "In11.Cu")
		(net "P5E_CPU1_PE1_RX_DN<6>")
	)
	(arc
		(start 112.862614 -217.388694)
		(mid 112.727681 -217.25534)
		(end 112.675416 -217.072972)
		(width 0.0889)
		(layer "In11.Cu")
		(net "P5E_CPU1_PE1_RX_DN<6>")
	)
	(arc
		(start 113.145316 -219.506038)
		(mid 113.071325 -219.226472)
		(end 112.86871 -219.020136)
		(width 0.0889)
		(layer "In11.Cu")
		(net "P5E_CPU1_PE1_RX_DN<6>")
	)
	(arc
		(start 112.675162 -215.238838)
		(mid 112.563698 -215.045917)
		(end 112.389412 -214.907114)
		(width 0.0889)
		(layer "In11.Cu")
		(net "P5E_CPU1_PE1_RX_DN<6>")
	)
	(arc
		(start 112.392714 -215.926162)
		(mid 112.597049 -215.723557)
		(end 112.675162 -215.44661)
		(width 0.0889)
		(layer "In11.Cu")
		(net "P5E_CPU1_PE1_RX_DN<6>")
	)
	(arc
		(start 113.145316 -217.864182)
		(mid 113.066097 -217.589497)
		(end 112.862614 -217.388694)
		(width 0.0889)
		(layer "In11.Cu")
		(net "P5E_CPU1_PE1_RX_DN<6>")
	)
	(arc
		(start 113.615216 -220.319854)
		(mid 113.5413 -220.040352)
		(end 113.338864 -219.833952)
		(width 0.0889)
		(layer "In11.Cu")
		(net "P5E_CPU1_PE1_RX_DN<6>")
	)
	(arc
		(start 112.86871 -218.364308)
		(mid 113.071297 -218.157957)
		(end 113.145316 -217.878406)
		(width 0.0889)
		(layer "In11.Cu")
		(net "P5E_CPU1_PE1_RX_DN<6>")
	)
	(arc
		(start 112.392714 -216.574878)
		(mid 112.257781 -216.441524)
		(end 112.205516 -216.259156)
		(width 0.0889)
		(layer "In11.Cu")
		(net "P5E_CPU1_PE1_RX_DN<6>")
	)
	(arc
		(start 112.675416 -217.064336)
		(mid 112.601425 -216.78477)
		(end 112.39881 -216.578434)
		(width 0.0889)
		(layer "In11.Cu")
		(net "P5E_CPU1_PE1_RX_DN<6>")
	)
	(segment
		(start 113.989866 -222.48368)
		(end 113.989866 -221.94774)
		(width 0.13208)
		(layer "F.Cu")
		(net "P5E_CPU1_PE1_RX_DN<5>")
	)
	(segment
		(start 43.088052 -7.610094)
		(end 43.088052 -7.026656)
		(width 0.13208)
		(layer "F.Cu")
		(net "P5E_CPU1_PE1_RX_DN<5>")
	)
	(segment
		(start 43.256962 -7.779004)
		(end 43.088052 -7.610094)
		(width 0.13208)
		(layer "F.Cu")
		(net "P5E_CPU1_PE1_RX_DN<5>")
	)
	(segment
		(start 43.088052 -7.026656)
		(end 43.390312 -6.724396)
		(width 0.13208)
		(layer "F.Cu")
		(net "P5E_CPU1_PE1_RX_DN<5>")
	)
	(segment
		(start 43.256962 -8.320024)
		(end 43.256962 -7.779004)
		(width 0.13208)
		(layer "F.Cu")
		(net "P5E_CPU1_PE1_RX_DN<5>")
	)
	(segment
		(start 114.555016 -220.32849)
		(end 114.555016 -220.309948)
		(width 0.0889)
		(layer "In11.Cu")
		(net "P5E_CPU1_PE1_RX_DN<5>")
	)
	(segment
		(start 45.39996 -19.412966)
		(end 45.39996 -19.057874)
		(width 0.14732)
		(layer "In11.Cu")
		(net "P5E_CPU1_PE1_RX_DN<5>")
	)
	(segment
		(start 113.323878 -215.931242)
		(end 113.331752 -215.92667)
		(width 0.0889)
		(layer "In11.Cu")
		(net "P5E_CPU1_PE1_RX_DN<5>")
	)
	(segment
		(start 43.095672 -7.019036)
		(end 43.390312 -6.724396)
		(width 0.14732)
		(layer "In11.Cu")
		(net "P5E_CPU1_PE1_RX_DN<5>")
	)
	(segment
		(start 113.371376 -206.13116)
		(end 110.243112 -183.75503)
		(width 0.14732)
		(layer "In11.Cu")
		(net "P5E_CPU1_PE1_RX_DN<5>")
	)
	(segment
		(start 113.338864 -216.578434)
		(end 113.332768 -216.574878)
		(width 0.0889)
		(layer "In11.Cu")
		(net "P5E_CPU1_PE1_RX_DN<5>")
	)
	(segment
		(start 113.793778 -218.372944)
		(end 113.799366 -218.369896)
		(width 0.0889)
		(layer "In11.Cu")
		(net "P5E_CPU1_PE1_RX_DN<5>")
	)
	(segment
		(start 113.989866 -221.94774)
		(end 114.14633 -221.676722)
		(width 0.0889)
		(layer "In11.Cu")
		(net "P5E_CPU1_PE1_RX_DN<5>")
	)
	(segment
		(start 113.657634 -213.063328)
		(end 113.657634 -213.04123)
		(width 0.0889)
		(layer "In11.Cu")
		(net "P5E_CPU1_PE1_RX_DN<5>")
	)
	(segment
		(start 113.332768 -216.574878)
		(end 113.323878 -216.569798)
		(width 0.0889)
		(layer "In11.Cu")
		(net "P5E_CPU1_PE1_RX_DN<5>")
	)
	(segment
		(start 53.650134 -45.597318)
		(end 45.880274 -20.566126)
		(width 0.14732)
		(layer "In11.Cu")
		(net "P5E_CPU1_PE1_RX_DN<5>")
	)
	(segment
		(start 113.61547 -213.80704)
		(end 113.61547 -213.105492)
		(width 0.0889)
		(layer "In11.Cu")
		(net "P5E_CPU1_PE1_RX_DN<5>")
	)
	(segment
		(start 43.1419 -12.351004)
		(end 43.095672 -12.191492)
		(width 0.14732)
		(layer "In11.Cu")
		(net "P5E_CPU1_PE1_RX_DN<5>")
	)
	(segment
		(start 113.657634 -210.24596)
		(end 113.371376 -206.13116)
		(width 0.14732)
		(layer "In11.Cu")
		(net "P5E_CPU1_PE1_RX_DN<5>")
	)
	(segment
		(start 114.085116 -217.888312)
		(end 114.085116 -217.859864)
		(width 0.0889)
		(layer "In11.Cu")
		(net "P5E_CPU1_PE1_RX_DN<5>")
	)
	(segment
		(start 113.614962 -215.452198)
		(end 113.614962 -215.275414)
		(width 0.0889)
		(layer "In11.Cu")
		(net "P5E_CPU1_PE1_RX_DN<5>")
	)
	(segment
		(start 114.085116 -219.506038)
		(end 114.085116 -219.496132)
		(width 0.0889)
		(layer "In11.Cu")
		(net "P5E_CPU1_PE1_RX_DN<5>")
	)
	(segment
		(start 113.331752 -215.92667)
		(end 113.332768 -215.926162)
		(width 0.0889)
		(layer "In11.Cu")
		(net "P5E_CPU1_PE1_RX_DN<5>")
	)
	(segment
		(start 114.14633 -221.676722)
		(end 114.235484 -221.652846)
		(width 0.0889)
		(layer "In11.Cu")
		(net "P5E_CPU1_PE1_RX_DN<5>")
	)
	(segment
		(start 114.084608 -214.592408)
		(end 114.084608 -214.276178)
		(width 0.0889)
		(layer "In11.Cu")
		(net "P5E_CPU1_PE1_RX_DN<5>")
	)
	(segment
		(start 46.12132 -17.780254)
		(end 46.12132 -17.343882)
		(width 0.14732)
		(layer "In11.Cu")
		(net "P5E_CPU1_PE1_RX_DN<5>")
	)
	(segment
		(start 113.802668 -217.388694)
		(end 113.793778 -217.383614)
		(width 0.0889)
		(layer "In11.Cu")
		(net "P5E_CPU1_PE1_RX_DN<5>")
	)
	(segment
		(start 115.024916 -221.14383)
		(end 115.024916 -221.1197)
		(width 0.0889)
		(layer "In11.Cu")
		(net "P5E_CPU1_PE1_RX_DN<5>")
	)
	(segment
		(start 45.39996 -19.057874)
		(end 45.509942 -18.695162)
		(width 0.14732)
		(layer "In11.Cu")
		(net "P5E_CPU1_PE1_RX_DN<5>")
	)
	(segment
		(start 114.084608 -214.276178)
		(end 113.61547 -213.80704)
		(width 0.0889)
		(layer "In11.Cu")
		(net "P5E_CPU1_PE1_RX_DN<5>")
	)
	(segment
		(start 43.095672 -12.191492)
		(end 43.095672 -7.019036)
		(width 0.14732)
		(layer "In11.Cu")
		(net "P5E_CPU1_PE1_RX_DN<5>")
	)
	(segment
		(start 113.799366 -218.369896)
		(end 113.801906 -218.368372)
		(width 0.0889)
		(layer "In11.Cu")
		(net "P5E_CPU1_PE1_RX_DN<5>")
	)
	(segment
		(start 114.272568 -219.830396)
		(end 114.263678 -219.825316)
		(width 0.0889)
		(layer "In11.Cu")
		(net "P5E_CPU1_PE1_RX_DN<5>")
	)
	(segment
		(start 113.61547 -213.105492)
		(end 113.657634 -213.063328)
		(width 0.0889)
		(layer "In11.Cu")
		(net "P5E_CPU1_PE1_RX_DN<5>")
	)
	(segment
		(start 113.801906 -219.016072)
		(end 113.799366 -219.014548)
		(width 0.0889)
		(layer "In11.Cu")
		(net "P5E_CPU1_PE1_RX_DN<5>")
	)
	(segment
		(start 113.799366 -219.014548)
		(end 113.793778 -219.0115)
		(width 0.0889)
		(layer "In11.Cu")
		(net "P5E_CPU1_PE1_RX_DN<5>")
	)
	(segment
		(start 45.880274 -20.566126)
		(end 45.39996 -19.412966)
		(width 0.14732)
		(layer "In11.Cu")
		(net "P5E_CPU1_PE1_RX_DN<5>")
	)
	(segment
		(start 45.509942 -18.695162)
		(end 46.12132 -17.780254)
		(width 0.14732)
		(layer "In11.Cu")
		(net "P5E_CPU1_PE1_RX_DN<5>")
	)
	(segment
		(start 113.801906 -218.368372)
		(end 113.802668 -218.367864)
		(width 0.0889)
		(layer "In11.Cu")
		(net "P5E_CPU1_PE1_RX_DN<5>")
	)
	(segment
		(start 110.243112 -183.75503)
		(end 109.558074 -180.571648)
		(width 0.14732)
		(layer "In11.Cu")
		(net "P5E_CPU1_PE1_RX_DN<5>")
	)
	(segment
		(start 45.96257 -16.797782)
		(end 43.1419 -12.351004)
		(width 0.14732)
		(layer "In11.Cu")
		(net "P5E_CPU1_PE1_RX_DN<5>")
	)
	(segment
		(start 113.802668 -219.01658)
		(end 113.801906 -219.016072)
		(width 0.0889)
		(layer "In11.Cu")
		(net "P5E_CPU1_PE1_RX_DN<5>")
	)
	(segment
		(start 109.558074 -180.571648)
		(end 53.650134 -45.597318)
		(width 0.14732)
		(layer "In11.Cu")
		(net "P5E_CPU1_PE1_RX_DN<5>")
	)
	(segment
		(start 46.12132 -17.343882)
		(end 45.96257 -16.797782)
		(width 0.14732)
		(layer "In11.Cu")
		(net "P5E_CPU1_PE1_RX_DN<5>")
	)
	(segment
		(start 113.657634 -213.04123)
		(end 113.657634 -210.24596)
		(width 0.14732)
		(layer "In11.Cu")
		(net "P5E_CPU1_PE1_RX_DN<5>")
	)
	(segment
		(start 114.06886 -214.784686)
		(end 114.084608 -214.592408)
		(width 0.0889)
		(layer "In11.Cu")
		(net "P5E_CPU1_PE1_RX_DN<5>")
	)
	(arc
		(start 114.235484 -221.652846)
		(mid 114.492483 -221.698313)
		(end 114.742468 -221.623382)
		(width 0.0889)
		(layer "In11.Cu")
		(net "P5E_CPU1_PE1_RX_DN<5>")
	)
	(arc
		(start 113.802668 -218.367864)
		(mid 114.007003 -218.165259)
		(end 114.085116 -217.888312)
		(width 0.0889)
		(layer "In11.Cu")
		(net "P5E_CPU1_PE1_RX_DN<5>")
	)
	(arc
		(start 114.085116 -217.859864)
		(mid 114.004954 -217.587675)
		(end 113.802668 -217.388694)
		(width 0.0889)
		(layer "In11.Cu")
		(net "P5E_CPU1_PE1_RX_DN<5>")
	)
	(arc
		(start 113.614962 -215.275414)
		(mid 113.689967 -215.159955)
		(end 113.799112 -215.076024)
		(width 0.0889)
		(layer "In11.Cu")
		(net "P5E_CPU1_PE1_RX_DN<5>")
	)
	(arc
		(start 114.555016 -220.309948)
		(mid 114.476905 -220.032999)
		(end 114.272568 -219.830396)
		(width 0.0889)
		(layer "In11.Cu")
		(net "P5E_CPU1_PE1_RX_DN<5>")
	)
	(arc
		(start 113.793778 -219.0115)
		(mid 113.615181 -218.692222)
		(end 113.793778 -218.372944)
		(width 0.0889)
		(layer "In11.Cu")
		(net "P5E_CPU1_PE1_RX_DN<5>")
	)
	(arc
		(start 114.742214 -220.644212)
		(mid 114.607281 -220.510858)
		(end 114.555016 -220.32849)
		(width 0.0889)
		(layer "In11.Cu")
		(net "P5E_CPU1_PE1_RX_DN<5>")
	)
	(arc
		(start 113.323878 -216.569798)
		(mid 113.145281 -216.25052)
		(end 113.323878 -215.931242)
		(width 0.0889)
		(layer "In11.Cu")
		(net "P5E_CPU1_PE1_RX_DN<5>")
	)
	(arc
		(start 113.799112 -215.076024)
		(mid 113.958856 -214.953376)
		(end 114.06886 -214.784686)
		(width 0.0889)
		(layer "In11.Cu")
		(net "P5E_CPU1_PE1_RX_DN<5>")
	)
	(arc
		(start 113.793778 -217.383614)
		(mid 113.662864 -217.247254)
		(end 113.615216 -217.064336)
		(width 0.0889)
		(layer "In11.Cu")
		(net "P5E_CPU1_PE1_RX_DN<5>")
	)
	(arc
		(start 114.085116 -219.496132)
		(mid 114.007005 -219.219183)
		(end 113.802668 -219.01658)
		(width 0.0889)
		(layer "In11.Cu")
		(net "P5E_CPU1_PE1_RX_DN<5>")
	)
	(arc
		(start 114.263678 -219.825316)
		(mid 114.132764 -219.688956)
		(end 114.085116 -219.506038)
		(width 0.0889)
		(layer "In11.Cu")
		(net "P5E_CPU1_PE1_RX_DN<5>")
	)
	(arc
		(start 114.742468 -221.623382)
		(mid 114.946803 -221.420777)
		(end 115.024916 -221.14383)
		(width 0.0889)
		(layer "In11.Cu")
		(net "P5E_CPU1_PE1_RX_DN<5>")
	)
	(arc
		(start 113.615216 -217.064336)
		(mid 113.5413 -216.784834)
		(end 113.338864 -216.578434)
		(width 0.0889)
		(layer "In11.Cu")
		(net "P5E_CPU1_PE1_RX_DN<5>")
	)
	(arc
		(start 113.332768 -215.926162)
		(mid 113.535591 -215.725931)
		(end 113.614962 -215.452198)
		(width 0.0889)
		(layer "In11.Cu")
		(net "P5E_CPU1_PE1_RX_DN<5>")
	)
	(arc
		(start 115.024916 -221.1197)
		(mid 114.945697 -220.845015)
		(end 114.742214 -220.644212)
		(width 0.0889)
		(layer "In11.Cu")
		(net "P5E_CPU1_PE1_RX_DN<5>")
	)
	(segment
		(start 45.05706 -7.775702)
		(end 44.891706 -7.610348)
		(width 0.13208)
		(layer "F.Cu")
		(net "P5E_CPU1_PE1_RX_DN<4>")
	)
	(segment
		(start 115.399312 -221.669864)
		(end 115.399312 -221.134178)
		(width 0.13208)
		(layer "F.Cu")
		(net "P5E_CPU1_PE1_RX_DN<4>")
	)
	(segment
		(start 45.05706 -8.320024)
		(end 45.05706 -7.775702)
		(width 0.13208)
		(layer "F.Cu")
		(net "P5E_CPU1_PE1_RX_DN<4>")
	)
	(segment
		(start 115.399312 -221.134178)
		(end 115.399566 -221.133924)
		(width 0.13208)
		(layer "F.Cu")
		(net "P5E_CPU1_PE1_RX_DN<4>")
	)
	(segment
		(start 44.891706 -7.610348)
		(end 44.891706 -5.265928)
		(width 0.13208)
		(layer "F.Cu")
		(net "P5E_CPU1_PE1_RX_DN<4>")
	)
	(segment
		(start 44.891706 -5.265928)
		(end 45.194982 -4.962652)
		(width 0.13208)
		(layer "F.Cu")
		(net "P5E_CPU1_PE1_RX_DN<4>")
	)
	(segment
		(start 114.733324 -215.117426)
		(end 114.742214 -215.112346)
		(width 0.0889)
		(layer "In11.Cu")
		(net "P5E_CPU1_PE1_RX_DN<4>")
	)
	(segment
		(start 114.742468 -219.01658)
		(end 114.733578 -219.0115)
		(width 0.0889)
		(layer "In11.Cu")
		(net "P5E_CPU1_PE1_RX_DN<4>")
	)
	(segment
		(start 115.494816 -220.334078)
		(end 115.494816 -220.319854)
		(width 0.0889)
		(layer "In11.Cu")
		(net "P5E_CPU1_PE1_RX_DN<4>")
	)
	(segment
		(start 115.024408 -214.644732)
		(end 115.024408 -214.424768)
		(width 0.0889)
		(layer "In11.Cu")
		(net "P5E_CPU1_PE1_RX_DN<4>")
	)
	(segment
		(start 48.777652 -18.684748)
		(end 48.269144 -17.924272)
		(width 0.14732)
		(layer "In11.Cu")
		(net "P5E_CPU1_PE1_RX_DN<4>")
	)
	(segment
		(start 48.945546 -19.089878)
		(end 48.777652 -18.684748)
		(width 0.14732)
		(layer "In11.Cu")
		(net "P5E_CPU1_PE1_RX_DN<4>")
	)
	(segment
		(start 114.59718 -213.063328)
		(end 114.59718 -213.04123)
		(width 0.0889)
		(layer "In11.Cu")
		(net "P5E_CPU1_PE1_RX_DN<4>")
	)
	(segment
		(start 44.900342 -12.554204)
		(end 44.900342 -5.257292)
		(width 0.14732)
		(layer "In11.Cu")
		(net "P5E_CPU1_PE1_RX_DN<4>")
	)
	(segment
		(start 115.399566 -221.133924)
		(end 115.243102 -220.862906)
		(width 0.0889)
		(layer "In11.Cu")
		(net "P5E_CPU1_PE1_RX_DN<4>")
	)
	(segment
		(start 114.271552 -215.92667)
		(end 114.272568 -215.926162)
		(width 0.0889)
		(layer "In11.Cu")
		(net "P5E_CPU1_PE1_RX_DN<4>")
	)
	(segment
		(start 114.263678 -215.931242)
		(end 114.271552 -215.92667)
		(width 0.0889)
		(layer "In11.Cu")
		(net "P5E_CPU1_PE1_RX_DN<4>")
	)
	(segment
		(start 44.900342 -5.257292)
		(end 45.194982 -4.962652)
		(width 0.14732)
		(layer "In11.Cu")
		(net "P5E_CPU1_PE1_RX_DN<4>")
	)
	(segment
		(start 114.554762 -215.452198)
		(end 114.554762 -215.436704)
		(width 0.0889)
		(layer "In11.Cu")
		(net "P5E_CPU1_PE1_RX_DN<4>")
	)
	(segment
		(start 111.174276 -183.629046)
		(end 110.635542 -180.72608)
		(width 0.14732)
		(layer "In11.Cu")
		(net "P5E_CPU1_PE1_RX_DN<4>")
	)
	(segment
		(start 114.733578 -218.372944)
		(end 114.742468 -218.367864)
		(width 0.0889)
		(layer "In11.Cu")
		(net "P5E_CPU1_PE1_RX_DN<4>")
	)
	(segment
		(start 114.59718 -213.04123)
		(end 114.59718 -210.120484)
		(width 0.14732)
		(layer "In11.Cu")
		(net "P5E_CPU1_PE1_RX_DN<4>")
	)
	(segment
		(start 115.024916 -219.506038)
		(end 115.024916 -219.496132)
		(width 0.0889)
		(layer "In11.Cu")
		(net "P5E_CPU1_PE1_RX_DN<4>")
	)
	(segment
		(start 110.635542 -180.72608)
		(end 54.528974 -45.271944)
		(width 0.14732)
		(layer "In11.Cu")
		(net "P5E_CPU1_PE1_RX_DN<4>")
	)
	(segment
		(start 115.024916 -217.888312)
		(end 115.024916 -217.864182)
		(width 0.0889)
		(layer "In11.Cu")
		(net "P5E_CPU1_PE1_RX_DN<4>")
	)
	(segment
		(start 54.528974 -45.271944)
		(end 48.945546 -19.089878)
		(width 0.14732)
		(layer "In11.Cu")
		(net "P5E_CPU1_PE1_RX_DN<4>")
	)
	(segment
		(start 114.555016 -213.894416)
		(end 114.555016 -213.105492)
		(width 0.0889)
		(layer "In11.Cu")
		(net "P5E_CPU1_PE1_RX_DN<4>")
	)
	(segment
		(start 114.555016 -213.105492)
		(end 114.59718 -213.063328)
		(width 0.0889)
		(layer "In11.Cu")
		(net "P5E_CPU1_PE1_RX_DN<4>")
	)
	(segment
		(start 114.319304 -206.124302)
		(end 111.174276 -183.629046)
		(width 0.14732)
		(layer "In11.Cu")
		(net "P5E_CPU1_PE1_RX_DN<4>")
	)
	(segment
		(start 115.212368 -219.830396)
		(end 115.203478 -219.825316)
		(width 0.0889)
		(layer "In11.Cu")
		(net "P5E_CPU1_PE1_RX_DN<4>")
	)
	(segment
		(start 114.272568 -216.574878)
		(end 114.263678 -216.569798)
		(width 0.0889)
		(layer "In11.Cu")
		(net "P5E_CPU1_PE1_RX_DN<4>")
	)
	(segment
		(start 48.269144 -17.924272)
		(end 44.900342 -12.554204)
		(width 0.14732)
		(layer "In11.Cu")
		(net "P5E_CPU1_PE1_RX_DN<4>")
	)
	(segment
		(start 114.73942 -214.093298)
		(end 114.739166 -214.093806)
		(width 0.0889)
		(layer "In11.Cu")
		(net "P5E_CPU1_PE1_RX_DN<4>")
	)
	(segment
		(start 114.59718 -210.120484)
		(end 114.319304 -206.124302)
		(width 0.14732)
		(layer "In11.Cu")
		(net "P5E_CPU1_PE1_RX_DN<4>")
	)
	(segment
		(start 114.555016 -217.072972)
		(end 114.555016 -217.05443)
		(width 0.0889)
		(layer "In11.Cu")
		(net "P5E_CPU1_PE1_RX_DN<4>")
	)
	(segment
		(start 115.243102 -220.862906)
		(end 115.267232 -220.773752)
		(width 0.0889)
		(layer "In11.Cu")
		(net "P5E_CPU1_PE1_RX_DN<4>")
	)
	(segment
		(start 115.218464 -219.833952)
		(end 115.212368 -219.830396)
		(width 0.0889)
		(layer "In11.Cu")
		(net "P5E_CPU1_PE1_RX_DN<4>")
	)
	(arc
		(start 114.739166 -214.093806)
		(mid 114.63003 -214.009867)
		(end 114.555016 -213.894416)
		(width 0.0889)
		(layer "In11.Cu")
		(net "P5E_CPU1_PE1_RX_DN<4>")
	)
	(arc
		(start 114.272568 -215.926162)
		(mid 114.475391 -215.725931)
		(end 114.554762 -215.452198)
		(width 0.0889)
		(layer "In11.Cu")
		(net "P5E_CPU1_PE1_RX_DN<4>")
	)
	(arc
		(start 114.555016 -217.05443)
		(mid 114.476905 -216.777481)
		(end 114.272568 -216.574878)
		(width 0.0889)
		(layer "In11.Cu")
		(net "P5E_CPU1_PE1_RX_DN<4>")
	)
	(arc
		(start 115.203478 -219.825316)
		(mid 115.072564 -219.688956)
		(end 115.024916 -219.506038)
		(width 0.0889)
		(layer "In11.Cu")
		(net "P5E_CPU1_PE1_RX_DN<4>")
	)
	(arc
		(start 114.08537 -216.257124)
		(mid 114.085276 -216.248742)
		(end 114.08537 -216.24036)
		(width 0.0889)
		(layer "In11.Cu")
		(net "P5E_CPU1_PE1_RX_DN<4>")
	)
	(arc
		(start 114.08537 -216.24036)
		(mid 114.135385 -216.063229)
		(end 114.263678 -215.931242)
		(width 0.0889)
		(layer "In11.Cu")
		(net "P5E_CPU1_PE1_RX_DN<4>")
	)
	(arc
		(start 114.554762 -215.436704)
		(mid 114.554814 -215.429337)
		(end 114.555016 -215.421972)
		(width 0.0889)
		(layer "In11.Cu")
		(net "P5E_CPU1_PE1_RX_DN<4>")
	)
	(arc
		(start 115.024408 -214.424768)
		(mid 114.913256 -214.232084)
		(end 114.73942 -214.093298)
		(width 0.0889)
		(layer "In11.Cu")
		(net "P5E_CPU1_PE1_RX_DN<4>")
	)
	(arc
		(start 114.733578 -219.0115)
		(mid 114.554981 -218.692222)
		(end 114.733578 -218.372944)
		(width 0.0889)
		(layer "In11.Cu")
		(net "P5E_CPU1_PE1_RX_DN<4>")
	)
	(arc
		(start 115.024916 -219.496132)
		(mid 114.946805 -219.219183)
		(end 114.742468 -219.01658)
		(width 0.0889)
		(layer "In11.Cu")
		(net "P5E_CPU1_PE1_RX_DN<4>")
	)
	(arc
		(start 114.263678 -216.569798)
		(mid 114.134474 -216.436284)
		(end 114.08537 -216.257124)
		(width 0.0889)
		(layer "In11.Cu")
		(net "P5E_CPU1_PE1_RX_DN<4>")
	)
	(arc
		(start 114.742214 -215.112346)
		(mid 114.943496 -214.914859)
		(end 115.024408 -214.644732)
		(width 0.0889)
		(layer "In11.Cu")
		(net "P5E_CPU1_PE1_RX_DN<4>")
	)
	(arc
		(start 114.742214 -217.388694)
		(mid 114.607281 -217.25534)
		(end 114.555016 -217.072972)
		(width 0.0889)
		(layer "In11.Cu")
		(net "P5E_CPU1_PE1_RX_DN<4>")
	)
	(arc
		(start 115.283996 -220.760798)
		(mid 115.436503 -220.5707)
		(end 115.494816 -220.334078)
		(width 0.0889)
		(layer "In11.Cu")
		(net "P5E_CPU1_PE1_RX_DN<4>")
	)
	(arc
		(start 115.267232 -220.773752)
		(mid 115.275675 -220.767354)
		(end 115.283996 -220.760798)
		(width 0.0889)
		(layer "In11.Cu")
		(net "P5E_CPU1_PE1_RX_DN<4>")
	)
	(arc
		(start 115.024916 -217.864182)
		(mid 114.945697 -217.589497)
		(end 114.742214 -217.388694)
		(width 0.0889)
		(layer "In11.Cu")
		(net "P5E_CPU1_PE1_RX_DN<4>")
	)
	(arc
		(start 115.494816 -220.319854)
		(mid 115.4209 -220.040352)
		(end 115.218464 -219.833952)
		(width 0.0889)
		(layer "In11.Cu")
		(net "P5E_CPU1_PE1_RX_DN<4>")
	)
	(arc
		(start 114.555016 -215.421972)
		(mid 114.60607 -215.247392)
		(end 114.733324 -215.117426)
		(width 0.0889)
		(layer "In11.Cu")
		(net "P5E_CPU1_PE1_RX_DN<4>")
	)
	(arc
		(start 114.742468 -218.367864)
		(mid 114.946803 -218.165259)
		(end 115.024916 -217.888312)
		(width 0.0889)
		(layer "In11.Cu")
		(net "P5E_CPU1_PE1_RX_DN<4>")
	)
	(segment
		(start 50.698146 -7.026656)
		(end 51.000406 -6.724396)
		(width 0.13208)
		(layer "F.Cu")
		(net "P5E_CPU1_PE1_RX_DN<3>")
	)
	(segment
		(start 50.698146 -7.610094)
		(end 50.698146 -7.026656)
		(width 0.13208)
		(layer "F.Cu")
		(net "P5E_CPU1_PE1_RX_DN<3>")
	)
	(segment
		(start 50.867056 -8.320024)
		(end 50.867056 -7.779004)
		(width 0.13208)
		(layer "F.Cu")
		(net "P5E_CPU1_PE1_RX_DN<3>")
	)
	(segment
		(start 115.869466 -221.947994)
		(end 115.869212 -221.94774)
		(width 0.13208)
		(layer "F.Cu")
		(net "P5E_CPU1_PE1_RX_DN<3>")
	)
	(segment
		(start 115.869466 -222.48368)
		(end 115.869466 -221.947994)
		(width 0.13208)
		(layer "F.Cu")
		(net "P5E_CPU1_PE1_RX_DN<3>")
	)
	(segment
		(start 50.867056 -7.779004)
		(end 50.698146 -7.610094)
		(width 0.13208)
		(layer "F.Cu")
		(net "P5E_CPU1_PE1_RX_DN<3>")
	)
	(segment
		(start 115.236244 -205.89494)
		(end 112.105948 -183.50484)
		(width 0.14732)
		(layer "In11.Cu")
		(net "P5E_CPU1_PE1_RX_DN<3>")
	)
	(segment
		(start 115.964208 -214.644732)
		(end 115.964208 -214.400384)
		(width 0.0889)
		(layer "In11.Cu")
		(net "P5E_CPU1_PE1_RX_DN<3>")
	)
	(segment
		(start 115.494816 -218.700858)
		(end 115.494816 -218.683586)
		(width 0.0889)
		(layer "In11.Cu")
		(net "P5E_CPU1_PE1_RX_DN<3>")
	)
	(segment
		(start 115.964208 -214.400384)
		(end 115.94846 -214.384636)
		(width 0.0889)
		(layer "In11.Cu")
		(net "P5E_CPU1_PE1_RX_DN<3>")
	)
	(segment
		(start 115.682014 -218.367864)
		(end 115.682776 -218.367356)
		(width 0.0889)
		(layer "In11.Cu")
		(net "P5E_CPU1_PE1_RX_DN<3>")
	)
	(segment
		(start 115.682268 -217.388694)
		(end 115.673378 -217.383614)
		(width 0.0889)
		(layer "In11.Cu")
		(net "P5E_CPU1_PE1_RX_DN<3>")
	)
	(segment
		(start 115.682776 -218.367356)
		(end 115.68811 -218.364308)
		(width 0.0889)
		(layer "In11.Cu")
		(net "P5E_CPU1_PE1_RX_DN<3>")
	)
	(segment
		(start 115.673124 -215.117426)
		(end 115.680998 -215.112854)
		(width 0.0889)
		(layer "In11.Cu")
		(net "P5E_CPU1_PE1_RX_DN<3>")
	)
	(segment
		(start 115.869212 -221.94774)
		(end 116.025676 -221.676722)
		(width 0.0889)
		(layer "In11.Cu")
		(net "P5E_CPU1_PE1_RX_DN<3>")
	)
	(segment
		(start 115.218464 -216.578434)
		(end 115.212114 -216.574878)
		(width 0.0889)
		(layer "In11.Cu")
		(net "P5E_CPU1_PE1_RX_DN<3>")
	)
	(segment
		(start 51.75758 -17.235678)
		(end 50.705766 -12.351512)
		(width 0.14732)
		(layer "In11.Cu")
		(net "P5E_CPU1_PE1_RX_DN<3>")
	)
	(segment
		(start 115.68811 -219.020136)
		(end 115.685824 -219.018866)
		(width 0.0889)
		(layer "In11.Cu")
		(net "P5E_CPU1_PE1_RX_DN<3>")
	)
	(segment
		(start 115.53698 -213.063328)
		(end 115.53698 -213.04123)
		(width 0.0889)
		(layer "In11.Cu")
		(net "P5E_CPU1_PE1_RX_DN<3>")
	)
	(segment
		(start 50.705766 -7.019036)
		(end 51.000406 -6.724396)
		(width 0.14732)
		(layer "In11.Cu")
		(net "P5E_CPU1_PE1_RX_DN<3>")
	)
	(segment
		(start 50.705766 -12.351512)
		(end 50.705766 -7.019036)
		(width 0.14732)
		(layer "In11.Cu")
		(net "P5E_CPU1_PE1_RX_DN<3>")
	)
	(segment
		(start 115.685824 -219.018866)
		(end 115.684808 -219.018358)
		(width 0.0889)
		(layer "In11.Cu")
		(net "P5E_CPU1_PE1_RX_DN<3>")
	)
	(segment
		(start 51.75758 -17.543018)
		(end 51.75758 -17.235678)
		(width 0.14732)
		(layer "In11.Cu")
		(net "P5E_CPU1_PE1_RX_DN<3>")
	)
	(segment
		(start 116.904516 -221.133924)
		(end 116.904516 -221.1197)
		(width 0.0889)
		(layer "In11.Cu")
		(net "P5E_CPU1_PE1_RX_DN<3>")
	)
	(segment
		(start 50.98542 -19.103086)
		(end 51.070002 -18.82394)
		(width 0.14732)
		(layer "In11.Cu")
		(net "P5E_CPU1_PE1_RX_DN<3>")
	)
	(segment
		(start 115.684808 -219.018358)
		(end 115.682014 -219.01658)
		(width 0.0889)
		(layer "In11.Cu")
		(net "P5E_CPU1_PE1_RX_DN<3>")
	)
	(segment
		(start 115.494816 -213.893908)
		(end 115.494816 -213.105492)
		(width 0.0889)
		(layer "In11.Cu")
		(net "P5E_CPU1_PE1_RX_DN<3>")
	)
	(segment
		(start 115.494816 -213.105492)
		(end 115.53698 -213.063328)
		(width 0.0889)
		(layer "In11.Cu")
		(net "P5E_CPU1_PE1_RX_DN<3>")
	)
	(segment
		(start 115.024916 -216.259156)
		(end 115.024916 -216.241884)
		(width 0.0889)
		(layer "In11.Cu")
		(net "P5E_CPU1_PE1_RX_DN<3>")
	)
	(segment
		(start 51.617626 -18.004536)
		(end 51.75758 -17.543018)
		(width 0.14732)
		(layer "In11.Cu")
		(net "P5E_CPU1_PE1_RX_DN<3>")
	)
	(segment
		(start 115.964716 -217.878406)
		(end 115.964716 -217.859864)
		(width 0.0889)
		(layer "In11.Cu")
		(net "P5E_CPU1_PE1_RX_DN<3>")
	)
	(segment
		(start 115.53698 -213.04123)
		(end 115.53698 -210.21929)
		(width 0.14732)
		(layer "In11.Cu")
		(net "P5E_CPU1_PE1_RX_DN<3>")
	)
	(segment
		(start 55.494428 -45.152564)
		(end 50.98542 -19.510248)
		(width 0.14732)
		(layer "In11.Cu")
		(net "P5E_CPU1_PE1_RX_DN<3>")
	)
	(segment
		(start 111.53902 -180.454046)
		(end 55.494428 -45.152564)
		(width 0.14732)
		(layer "In11.Cu")
		(net "P5E_CPU1_PE1_RX_DN<3>")
	)
	(segment
		(start 116.152168 -219.830396)
		(end 116.143278 -219.825316)
		(width 0.0889)
		(layer "In11.Cu")
		(net "P5E_CPU1_PE1_RX_DN<3>")
	)
	(segment
		(start 50.98542 -19.510248)
		(end 50.98542 -19.103086)
		(width 0.14732)
		(layer "In11.Cu")
		(net "P5E_CPU1_PE1_RX_DN<3>")
	)
	(segment
		(start 115.680998 -215.112854)
		(end 115.682014 -215.112346)
		(width 0.0889)
		(layer "In11.Cu")
		(net "P5E_CPU1_PE1_RX_DN<3>")
	)
	(segment
		(start 51.070002 -18.82394)
		(end 51.617626 -18.004536)
		(width 0.14732)
		(layer "In11.Cu")
		(net "P5E_CPU1_PE1_RX_DN<3>")
	)
	(segment
		(start 112.105948 -183.50484)
		(end 111.53902 -180.454046)
		(width 0.14732)
		(layer "In11.Cu")
		(net "P5E_CPU1_PE1_RX_DN<3>")
	)
	(segment
		(start 115.494562 -215.44661)
		(end 115.494562 -215.436704)
		(width 0.0889)
		(layer "In11.Cu")
		(net "P5E_CPU1_PE1_RX_DN<3>")
	)
	(segment
		(start 116.434616 -220.32849)
		(end 116.434616 -220.309948)
		(width 0.0889)
		(layer "In11.Cu")
		(net "P5E_CPU1_PE1_RX_DN<3>")
	)
	(segment
		(start 115.53698 -210.21929)
		(end 115.236244 -205.89494)
		(width 0.14732)
		(layer "In11.Cu")
		(net "P5E_CPU1_PE1_RX_DN<3>")
	)
	(segment
		(start 116.607082 -221.632018)
		(end 116.62791 -221.619826)
		(width 0.0889)
		(layer "In11.Cu")
		(net "P5E_CPU1_PE1_RX_DN<3>")
	)
	(segment
		(start 116.025676 -221.676722)
		(end 116.11483 -221.652846)
		(width 0.0889)
		(layer "In11.Cu")
		(net "P5E_CPU1_PE1_RX_DN<3>")
	)
	(arc
		(start 116.11483 -221.652846)
		(mid 116.124824 -221.657005)
		(end 116.134896 -221.660974)
		(width 0.0889)
		(layer "In11.Cu")
		(net "P5E_CPU1_PE1_RX_DN<3>")
	)
	(arc
		(start 115.678966 -214.093298)
		(mid 115.569819 -214.00937)
		(end 115.494816 -213.893908)
		(width 0.0889)
		(layer "In11.Cu")
		(net "P5E_CPU1_PE1_RX_DN<3>")
	)
	(arc
		(start 115.930934 -214.347552)
		(mid 115.824398 -214.201151)
		(end 115.678966 -214.093298)
		(width 0.0889)
		(layer "In11.Cu")
		(net "P5E_CPU1_PE1_RX_DN<3>")
	)
	(arc
		(start 115.964716 -217.859864)
		(mid 115.884554 -217.587675)
		(end 115.682268 -217.388694)
		(width 0.0889)
		(layer "In11.Cu")
		(net "P5E_CPU1_PE1_RX_DN<3>")
	)
	(arc
		(start 115.673378 -217.383614)
		(mid 115.542464 -217.247254)
		(end 115.494816 -217.064336)
		(width 0.0889)
		(layer "In11.Cu")
		(net "P5E_CPU1_PE1_RX_DN<3>")
	)
	(arc
		(start 115.68811 -218.364308)
		(mid 115.890697 -218.157957)
		(end 115.964716 -217.878406)
		(width 0.0889)
		(layer "In11.Cu")
		(net "P5E_CPU1_PE1_RX_DN<3>")
	)
	(arc
		(start 115.94846 -214.384636)
		(mid 115.940014 -214.365944)
		(end 115.930934 -214.347552)
		(width 0.0889)
		(layer "In11.Cu")
		(net "P5E_CPU1_PE1_RX_DN<3>")
	)
	(arc
		(start 115.212114 -216.574878)
		(mid 115.077181 -216.441524)
		(end 115.024916 -216.259156)
		(width 0.0889)
		(layer "In11.Cu")
		(net "P5E_CPU1_PE1_RX_DN<3>")
	)
	(arc
		(start 115.682014 -219.01658)
		(mid 115.547081 -218.883226)
		(end 115.494816 -218.700858)
		(width 0.0889)
		(layer "In11.Cu")
		(net "P5E_CPU1_PE1_RX_DN<3>")
	)
	(arc
		(start 116.904516 -221.1197)
		(mid 116.825297 -220.845015)
		(end 116.621814 -220.644212)
		(width 0.0889)
		(layer "In11.Cu")
		(net "P5E_CPU1_PE1_RX_DN<3>")
	)
	(arc
		(start 116.143278 -219.825316)
		(mid 116.012364 -219.688956)
		(end 115.964716 -219.506038)
		(width 0.0889)
		(layer "In11.Cu")
		(net "P5E_CPU1_PE1_RX_DN<3>")
	)
	(arc
		(start 115.964716 -219.506038)
		(mid 115.890725 -219.226472)
		(end 115.68811 -219.020136)
		(width 0.0889)
		(layer "In11.Cu")
		(net "P5E_CPU1_PE1_RX_DN<3>")
	)
	(arc
		(start 115.494816 -218.683586)
		(mid 115.547086 -218.501221)
		(end 115.682014 -218.367864)
		(width 0.0889)
		(layer "In11.Cu")
		(net "P5E_CPU1_PE1_RX_DN<3>")
	)
	(arc
		(start 116.434616 -220.309948)
		(mid 116.356505 -220.032999)
		(end 116.152168 -219.830396)
		(width 0.0889)
		(layer "In11.Cu")
		(net "P5E_CPU1_PE1_RX_DN<3>")
	)
	(arc
		(start 116.621814 -220.644212)
		(mid 116.486881 -220.510858)
		(end 116.434616 -220.32849)
		(width 0.0889)
		(layer "In11.Cu")
		(net "P5E_CPU1_PE1_RX_DN<3>")
	)
	(arc
		(start 115.212114 -215.926162)
		(mid 115.416449 -215.723557)
		(end 115.494562 -215.44661)
		(width 0.0889)
		(layer "In11.Cu")
		(net "P5E_CPU1_PE1_RX_DN<3>")
	)
	(arc
		(start 116.62791 -221.619826)
		(mid 116.830497 -221.413475)
		(end 116.904516 -221.133924)
		(width 0.0889)
		(layer "In11.Cu")
		(net "P5E_CPU1_PE1_RX_DN<3>")
	)
	(arc
		(start 115.024916 -216.241884)
		(mid 115.077186 -216.059519)
		(end 115.212114 -215.926162)
		(width 0.0889)
		(layer "In11.Cu")
		(net "P5E_CPU1_PE1_RX_DN<3>")
	)
	(arc
		(start 115.494816 -217.064336)
		(mid 115.4209 -216.784834)
		(end 115.218464 -216.578434)
		(width 0.0889)
		(layer "In11.Cu")
		(net "P5E_CPU1_PE1_RX_DN<3>")
	)
	(arc
		(start 116.134896 -221.660974)
		(mid 116.374171 -221.698282)
		(end 116.607082 -221.632018)
		(width 0.0889)
		(layer "In11.Cu")
		(net "P5E_CPU1_PE1_RX_DN<3>")
	)
	(arc
		(start 115.494816 -215.421972)
		(mid 115.54587 -215.247392)
		(end 115.673124 -215.117426)
		(width 0.0889)
		(layer "In11.Cu")
		(net "P5E_CPU1_PE1_RX_DN<3>")
	)
	(arc
		(start 115.494562 -215.436704)
		(mid 115.494614 -215.429337)
		(end 115.494816 -215.421972)
		(width 0.0889)
		(layer "In11.Cu")
		(net "P5E_CPU1_PE1_RX_DN<3>")
	)
	(arc
		(start 115.682014 -215.112346)
		(mid 115.883296 -214.914859)
		(end 115.964208 -214.644732)
		(width 0.0889)
		(layer "In11.Cu")
		(net "P5E_CPU1_PE1_RX_DN<3>")
	)
	(segment
		(start 117.278912 -221.669864)
		(end 117.278912 -221.134178)
		(width 0.13208)
		(layer "F.Cu")
		(net "P5E_CPU1_PE1_RX_DN<2>")
	)
	(segment
		(start 52.5018 -5.265928)
		(end 52.805076 -4.962652)
		(width 0.13208)
		(layer "F.Cu")
		(net "P5E_CPU1_PE1_RX_DN<2>")
	)
	(segment
		(start 52.6669 -7.775702)
		(end 52.5018 -7.610602)
		(width 0.13208)
		(layer "F.Cu")
		(net "P5E_CPU1_PE1_RX_DN<2>")
	)
	(segment
		(start 117.278912 -221.134178)
		(end 117.279166 -221.133924)
		(width 0.13208)
		(layer "F.Cu")
		(net "P5E_CPU1_PE1_RX_DN<2>")
	)
	(segment
		(start 52.6669 -8.320024)
		(end 52.6669 -7.775702)
		(width 0.13208)
		(layer "F.Cu")
		(net "P5E_CPU1_PE1_RX_DN<2>")
	)
	(segment
		(start 52.5018 -7.610602)
		(end 52.5018 -5.265928)
		(width 0.13208)
		(layer "F.Cu")
		(net "P5E_CPU1_PE1_RX_DN<2>")
	)
	(segment
		(start 116.62029 -218.368626)
		(end 116.621814 -218.367864)
		(width 0.0889)
		(layer "In11.Cu")
		(net "P5E_CPU1_PE1_RX_DN<2>")
	)
	(segment
		(start 52.510436 -12.08532)
		(end 52.510436 -5.257292)
		(width 0.14732)
		(layer "In11.Cu")
		(net "P5E_CPU1_PE1_RX_DN<2>")
	)
	(segment
		(start 116.151152 -215.92667)
		(end 116.152168 -215.926162)
		(width 0.0889)
		(layer "In11.Cu")
		(net "P5E_CPU1_PE1_RX_DN<2>")
	)
	(segment
		(start 116.622576 -218.367356)
		(end 116.62791 -218.364308)
		(width 0.0889)
		(layer "In11.Cu")
		(net "P5E_CPU1_PE1_RX_DN<2>")
	)
	(segment
		(start 116.904516 -217.878406)
		(end 116.904516 -217.864182)
		(width 0.0889)
		(layer "In11.Cu")
		(net "P5E_CPU1_PE1_RX_DN<2>")
	)
	(segment
		(start 116.47678 -213.04123)
		(end 116.47678 -210.321652)
		(width 0.14732)
		(layer "In11.Cu")
		(net "P5E_CPU1_PE1_RX_DN<2>")
	)
	(segment
		(start 117.279166 -221.133924)
		(end 117.122702 -220.862906)
		(width 0.0889)
		(layer "In11.Cu")
		(net "P5E_CPU1_PE1_RX_DN<2>")
	)
	(segment
		(start 117.122702 -220.862906)
		(end 117.146832 -220.773752)
		(width 0.0889)
		(layer "In11.Cu")
		(net "P5E_CPU1_PE1_RX_DN<2>")
	)
	(segment
		(start 116.152168 -216.574878)
		(end 116.143278 -216.569798)
		(width 0.0889)
		(layer "In11.Cu")
		(net "P5E_CPU1_PE1_RX_DN<2>")
	)
	(segment
		(start 53.815234 -17.715992)
		(end 53.815234 -16.711422)
		(width 0.14732)
		(layer "In11.Cu")
		(net "P5E_CPU1_PE1_RX_DN<2>")
	)
	(segment
		(start 54.527196 -18.693892)
		(end 54.003448 -18.170144)
		(width 0.14732)
		(layer "In11.Cu")
		(net "P5E_CPU1_PE1_RX_DN<2>")
	)
	(segment
		(start 116.612924 -218.372944)
		(end 116.62029 -218.368626)
		(width 0.0889)
		(layer "In11.Cu")
		(net "P5E_CPU1_PE1_RX_DN<2>")
	)
	(segment
		(start 116.434616 -217.072972)
		(end 116.434616 -217.05443)
		(width 0.0889)
		(layer "In11.Cu")
		(net "P5E_CPU1_PE1_RX_DN<2>")
	)
	(segment
		(start 112.50549 -180.31968)
		(end 56.83758 -45.92447)
		(width 0.14732)
		(layer "In11.Cu")
		(net "P5E_CPU1_PE1_RX_DN<2>")
	)
	(segment
		(start 116.47678 -210.321652)
		(end 116.152676 -205.662276)
		(width 0.14732)
		(layer "In11.Cu")
		(net "P5E_CPU1_PE1_RX_DN<2>")
	)
	(segment
		(start 55.915306 -39.799514)
		(end 54.527196 -19.005296)
		(width 0.14732)
		(layer "In11.Cu")
		(net "P5E_CPU1_PE1_RX_DN<2>")
	)
	(segment
		(start 116.47678 -213.063328)
		(end 116.47678 -213.04123)
		(width 0.0889)
		(layer "In11.Cu")
		(net "P5E_CPU1_PE1_RX_DN<2>")
	)
	(segment
		(start 117.374416 -220.334078)
		(end 117.374416 -220.319854)
		(width 0.0889)
		(layer "In11.Cu")
		(net "P5E_CPU1_PE1_RX_DN<2>")
	)
	(segment
		(start 116.434616 -213.105492)
		(end 116.47678 -213.063328)
		(width 0.0889)
		(layer "In11.Cu")
		(net "P5E_CPU1_PE1_RX_DN<2>")
	)
	(segment
		(start 117.098064 -219.833952)
		(end 117.091968 -219.830396)
		(width 0.0889)
		(layer "In11.Cu")
		(net "P5E_CPU1_PE1_RX_DN<2>")
	)
	(segment
		(start 116.621814 -218.367864)
		(end 116.622576 -218.367356)
		(width 0.0889)
		(layer "In11.Cu")
		(net "P5E_CPU1_PE1_RX_DN<2>")
	)
	(segment
		(start 116.434616 -213.893908)
		(end 116.434616 -213.105492)
		(width 0.0889)
		(layer "In11.Cu")
		(net "P5E_CPU1_PE1_RX_DN<2>")
	)
	(segment
		(start 52.510436 -5.257292)
		(end 52.805076 -4.962652)
		(width 0.14732)
		(layer "In11.Cu")
		(net "P5E_CPU1_PE1_RX_DN<2>")
	)
	(segment
		(start 53.25237 -14.715744)
		(end 52.510436 -12.08532)
		(width 0.14732)
		(layer "In11.Cu")
		(net "P5E_CPU1_PE1_RX_DN<2>")
	)
	(segment
		(start 117.091968 -219.830396)
		(end 117.083078 -219.825316)
		(width 0.0889)
		(layer "In11.Cu")
		(net "P5E_CPU1_PE1_RX_DN<2>")
	)
	(segment
		(start 116.152676 -205.662276)
		(end 113.03635 -183.370982)
		(width 0.14732)
		(layer "In11.Cu")
		(net "P5E_CPU1_PE1_RX_DN<2>")
	)
	(segment
		(start 53.252116 -14.715236)
		(end 53.252878 -14.717776)
		(width 0.14732)
		(layer "In11.Cu")
		(net "P5E_CPU1_PE1_RX_DN<2>")
	)
	(segment
		(start 53.252878 -14.717776)
		(end 53.25237 -14.715744)
		(width 0.14732)
		(layer "In11.Cu")
		(net "P5E_CPU1_PE1_RX_DN<2>")
	)
	(segment
		(start 116.62791 -219.020136)
		(end 116.621814 -219.01658)
		(width 0.0889)
		(layer "In11.Cu")
		(net "P5E_CPU1_PE1_RX_DN<2>")
	)
	(segment
		(start 54.003448 -18.170144)
		(end 53.815234 -17.715992)
		(width 0.14732)
		(layer "In11.Cu")
		(net "P5E_CPU1_PE1_RX_DN<2>")
	)
	(segment
		(start 56.83758 -45.92447)
		(end 56.242712 -42.549064)
		(width 0.14732)
		(layer "In11.Cu")
		(net "P5E_CPU1_PE1_RX_DN<2>")
	)
	(segment
		(start 116.434362 -215.452198)
		(end 116.434362 -215.436704)
		(width 0.0889)
		(layer "In11.Cu")
		(net "P5E_CPU1_PE1_RX_DN<2>")
	)
	(segment
		(start 56.242712 -42.549064)
		(end 55.915306 -39.799514)
		(width 0.14732)
		(layer "In11.Cu")
		(net "P5E_CPU1_PE1_RX_DN<2>")
	)
	(segment
		(start 116.904008 -214.644732)
		(end 116.904008 -214.424768)
		(width 0.0889)
		(layer "In11.Cu")
		(net "P5E_CPU1_PE1_RX_DN<2>")
	)
	(segment
		(start 116.612924 -215.117426)
		(end 116.621814 -215.112346)
		(width 0.0889)
		(layer "In11.Cu")
		(net "P5E_CPU1_PE1_RX_DN<2>")
	)
	(segment
		(start 113.03635 -183.370982)
		(end 112.50549 -180.31968)
		(width 0.14732)
		(layer "In11.Cu")
		(net "P5E_CPU1_PE1_RX_DN<2>")
	)
	(segment
		(start 54.527196 -19.005296)
		(end 54.527196 -18.693892)
		(width 0.14732)
		(layer "In11.Cu")
		(net "P5E_CPU1_PE1_RX_DN<2>")
	)
	(segment
		(start 116.143278 -215.931242)
		(end 116.151152 -215.92667)
		(width 0.0889)
		(layer "In11.Cu")
		(net "P5E_CPU1_PE1_RX_DN<2>")
	)
	(segment
		(start 116.621814 -219.01658)
		(end 116.612924 -219.0115)
		(width 0.0889)
		(layer "In11.Cu")
		(net "P5E_CPU1_PE1_RX_DN<2>")
	)
	(segment
		(start 53.815234 -16.711422)
		(end 53.252116 -14.715236)
		(width 0.14732)
		(layer "In11.Cu")
		(net "P5E_CPU1_PE1_RX_DN<2>")
	)
	(arc
		(start 116.621814 -217.388694)
		(mid 116.486881 -217.25534)
		(end 116.434616 -217.072972)
		(width 0.0889)
		(layer "In11.Cu")
		(net "P5E_CPU1_PE1_RX_DN<2>")
	)
	(arc
		(start 115.96497 -216.257124)
		(mid 115.964876 -216.248742)
		(end 115.96497 -216.24036)
		(width 0.0889)
		(layer "In11.Cu")
		(net "P5E_CPU1_PE1_RX_DN<2>")
	)
	(arc
		(start 116.612924 -219.0115)
		(mid 116.434327 -218.692222)
		(end 116.612924 -218.372944)
		(width 0.0889)
		(layer "In11.Cu")
		(net "P5E_CPU1_PE1_RX_DN<2>")
	)
	(arc
		(start 116.618766 -214.093298)
		(mid 116.509619 -214.00937)
		(end 116.434616 -213.893908)
		(width 0.0889)
		(layer "In11.Cu")
		(net "P5E_CPU1_PE1_RX_DN<2>")
	)
	(arc
		(start 116.434616 -217.05443)
		(mid 116.356505 -216.777481)
		(end 116.152168 -216.574878)
		(width 0.0889)
		(layer "In11.Cu")
		(net "P5E_CPU1_PE1_RX_DN<2>")
	)
	(arc
		(start 117.163596 -220.760798)
		(mid 117.316103 -220.5707)
		(end 117.374416 -220.334078)
		(width 0.0889)
		(layer "In11.Cu")
		(net "P5E_CPU1_PE1_RX_DN<2>")
	)
	(arc
		(start 116.621814 -215.112346)
		(mid 116.823096 -214.914859)
		(end 116.904008 -214.644732)
		(width 0.0889)
		(layer "In11.Cu")
		(net "P5E_CPU1_PE1_RX_DN<2>")
	)
	(arc
		(start 116.434616 -215.421972)
		(mid 116.48567 -215.247392)
		(end 116.612924 -215.117426)
		(width 0.0889)
		(layer "In11.Cu")
		(net "P5E_CPU1_PE1_RX_DN<2>")
	)
	(arc
		(start 116.904008 -214.424768)
		(mid 116.792729 -214.232062)
		(end 116.618766 -214.093298)
		(width 0.0889)
		(layer "In11.Cu")
		(net "P5E_CPU1_PE1_RX_DN<2>")
	)
	(arc
		(start 116.904516 -217.864182)
		(mid 116.825297 -217.589497)
		(end 116.621814 -217.388694)
		(width 0.0889)
		(layer "In11.Cu")
		(net "P5E_CPU1_PE1_RX_DN<2>")
	)
	(arc
		(start 116.434362 -215.436704)
		(mid 116.434414 -215.429337)
		(end 116.434616 -215.421972)
		(width 0.0889)
		(layer "In11.Cu")
		(net "P5E_CPU1_PE1_RX_DN<2>")
	)
	(arc
		(start 116.143278 -216.569798)
		(mid 116.014074 -216.436284)
		(end 115.96497 -216.257124)
		(width 0.0889)
		(layer "In11.Cu")
		(net "P5E_CPU1_PE1_RX_DN<2>")
	)
	(arc
		(start 115.96497 -216.24036)
		(mid 116.014985 -216.063229)
		(end 116.143278 -215.931242)
		(width 0.0889)
		(layer "In11.Cu")
		(net "P5E_CPU1_PE1_RX_DN<2>")
	)
	(arc
		(start 117.146832 -220.773752)
		(mid 117.155275 -220.767354)
		(end 117.163596 -220.760798)
		(width 0.0889)
		(layer "In11.Cu")
		(net "P5E_CPU1_PE1_RX_DN<2>")
	)
	(arc
		(start 116.904516 -219.506038)
		(mid 116.830525 -219.226472)
		(end 116.62791 -219.020136)
		(width 0.0889)
		(layer "In11.Cu")
		(net "P5E_CPU1_PE1_RX_DN<2>")
	)
	(arc
		(start 116.62791 -218.364308)
		(mid 116.830497 -218.157957)
		(end 116.904516 -217.878406)
		(width 0.0889)
		(layer "In11.Cu")
		(net "P5E_CPU1_PE1_RX_DN<2>")
	)
	(arc
		(start 116.152168 -215.926162)
		(mid 116.354991 -215.725931)
		(end 116.434362 -215.452198)
		(width 0.0889)
		(layer "In11.Cu")
		(net "P5E_CPU1_PE1_RX_DN<2>")
	)
	(arc
		(start 117.083078 -219.825316)
		(mid 116.952164 -219.688956)
		(end 116.904516 -219.506038)
		(width 0.0889)
		(layer "In11.Cu")
		(net "P5E_CPU1_PE1_RX_DN<2>")
	)
	(arc
		(start 117.374416 -220.319854)
		(mid 117.3005 -220.040352)
		(end 117.098064 -219.833952)
		(width 0.0889)
		(layer "In11.Cu")
		(net "P5E_CPU1_PE1_RX_DN<2>")
	)
	(segment
		(start 54.298088 -7.026656)
		(end 54.600348 -6.724396)
		(width 0.13208)
		(layer "F.Cu")
		(net "P5E_CPU1_PE1_RX_DN<1>")
	)
	(segment
		(start 54.298088 -7.610094)
		(end 54.298088 -7.026656)
		(width 0.13208)
		(layer "F.Cu")
		(net "P5E_CPU1_PE1_RX_DN<1>")
	)
	(segment
		(start 117.749066 -222.48368)
		(end 117.749066 -221.947994)
		(width 0.13208)
		(layer "F.Cu")
		(net "P5E_CPU1_PE1_RX_DN<1>")
	)
	(segment
		(start 54.466998 -7.779004)
		(end 54.298088 -7.610094)
		(width 0.13208)
		(layer "F.Cu")
		(net "P5E_CPU1_PE1_RX_DN<1>")
	)
	(segment
		(start 54.466998 -8.320024)
		(end 54.466998 -7.779004)
		(width 0.13208)
		(layer "F.Cu")
		(net "P5E_CPU1_PE1_RX_DN<1>")
	)
	(segment
		(start 117.749066 -221.947994)
		(end 117.748812 -221.94774)
		(width 0.13208)
		(layer "F.Cu")
		(net "P5E_CPU1_PE1_RX_DN<1>")
	)
	(segment
		(start 117.374416 -213.893908)
		(end 117.374416 -213.105492)
		(width 0.0889)
		(layer "In11.Cu")
		(net "P5E_CPU1_PE1_RX_DN<1>")
	)
	(segment
		(start 117.569742 -214.093298)
		(end 117.558566 -214.093298)
		(width 0.0889)
		(layer "In11.Cu")
		(net "P5E_CPU1_PE1_RX_DN<1>")
	)
	(segment
		(start 117.562376 -218.367356)
		(end 117.56771 -218.364308)
		(width 0.0889)
		(layer "In11.Cu")
		(net "P5E_CPU1_PE1_RX_DN<1>")
	)
	(segment
		(start 118.314216 -220.32849)
		(end 118.314216 -220.309948)
		(width 0.0889)
		(layer "In11.Cu")
		(net "P5E_CPU1_PE1_RX_DN<1>")
	)
	(segment
		(start 57.34558 -18.064988)
		(end 57.34558 -17.424146)
		(width 0.14732)
		(layer "In11.Cu")
		(net "P5E_CPU1_PE1_RX_DN<1>")
	)
	(segment
		(start 117.748812 -221.94774)
		(end 117.905276 -221.676722)
		(width 0.0889)
		(layer "In11.Cu")
		(net "P5E_CPU1_PE1_RX_DN<1>")
	)
	(segment
		(start 117.091968 -216.574878)
		(end 117.083078 -216.569798)
		(width 0.0889)
		(layer "In11.Cu")
		(net "P5E_CPU1_PE1_RX_DN<1>")
	)
	(segment
		(start 117.56009 -219.015818)
		(end 117.552724 -219.0115)
		(width 0.0889)
		(layer "In11.Cu")
		(net "P5E_CPU1_PE1_RX_DN<1>")
	)
	(segment
		(start 118.031768 -219.830396)
		(end 118.022878 -219.825316)
		(width 0.0889)
		(layer "In11.Cu")
		(net "P5E_CPU1_PE1_RX_DN<1>")
	)
	(segment
		(start 117.41658 -210.220052)
		(end 117.097302 -205.631542)
		(width 0.14732)
		(layer "In11.Cu")
		(net "P5E_CPU1_PE1_RX_DN<1>")
	)
	(segment
		(start 117.41658 -213.063328)
		(end 117.41658 -213.04123)
		(width 0.0889)
		(layer "In11.Cu")
		(net "P5E_CPU1_PE1_RX_DN<1>")
	)
	(segment
		(start 57.103518 -16.839692)
		(end 56.754268 -16.490442)
		(width 0.14732)
		(layer "In11.Cu")
		(net "P5E_CPU1_PE1_RX_DN<1>")
	)
	(segment
		(start 58.199782 -46.780704)
		(end 57.168034 -40.522398)
		(width 0.14732)
		(layer "In11.Cu")
		(net "P5E_CPU1_PE1_RX_DN<1>")
	)
	(segment
		(start 117.552724 -218.372944)
		(end 117.562376 -218.367356)
		(width 0.0889)
		(layer "In11.Cu")
		(net "P5E_CPU1_PE1_RX_DN<1>")
	)
	(segment
		(start 117.41658 -213.04123)
		(end 117.41658 -210.220052)
		(width 0.14732)
		(layer "In11.Cu")
		(net "P5E_CPU1_PE1_RX_DN<1>")
	)
	(segment
		(start 56.541416 -19.201638)
		(end 56.77662 -18.633948)
		(width 0.14732)
		(layer "In11.Cu")
		(net "P5E_CPU1_PE1_RX_DN<1>")
	)
	(segment
		(start 117.843554 -214.622634)
		(end 117.843554 -214.36711)
		(width 0.0889)
		(layer "In11.Cu")
		(net "P5E_CPU1_PE1_RX_DN<1>")
	)
	(segment
		(start 117.083078 -215.931242)
		(end 117.090952 -215.92667)
		(width 0.0889)
		(layer "In11.Cu")
		(net "P5E_CPU1_PE1_RX_DN<1>")
	)
	(segment
		(start 57.34558 -17.424146)
		(end 57.103518 -16.839692)
		(width 0.14732)
		(layer "In11.Cu")
		(net "P5E_CPU1_PE1_RX_DN<1>")
	)
	(segment
		(start 57.168034 -40.522398)
		(end 57.035446 -38.541198)
		(width 0.14732)
		(layer "In11.Cu")
		(net "P5E_CPU1_PE1_RX_DN<1>")
	)
	(segment
		(start 117.560598 -215.112854)
		(end 117.561614 -215.112346)
		(width 0.0889)
		(layer "In11.Cu")
		(net "P5E_CPU1_PE1_RX_DN<1>")
	)
	(segment
		(start 117.374416 -213.105492)
		(end 117.41658 -213.063328)
		(width 0.0889)
		(layer "In11.Cu")
		(net "P5E_CPU1_PE1_RX_DN<1>")
	)
	(segment
		(start 57.035446 -38.541198)
		(end 56.541416 -19.573748)
		(width 0.14732)
		(layer "In11.Cu")
		(net "P5E_CPU1_PE1_RX_DN<1>")
	)
	(segment
		(start 113.412778 -180.075332)
		(end 58.199782 -46.780704)
		(width 0.14732)
		(layer "In11.Cu")
		(net "P5E_CPU1_PE1_RX_DN<1>")
	)
	(segment
		(start 54.305708 -12.299696)
		(end 54.305708 -7.019036)
		(width 0.14732)
		(layer "In11.Cu")
		(net "P5E_CPU1_PE1_RX_DN<1>")
	)
	(segment
		(start 56.77662 -18.633948)
		(end 57.34558 -18.064988)
		(width 0.14732)
		(layer "In11.Cu")
		(net "P5E_CPU1_PE1_RX_DN<1>")
	)
	(segment
		(start 117.843808 -214.644732)
		(end 117.843808 -214.622888)
		(width 0.0889)
		(layer "In11.Cu")
		(net "P5E_CPU1_PE1_RX_DN<1>")
	)
	(segment
		(start 56.541416 -19.573748)
		(end 56.541416 -19.201638)
		(width 0.14732)
		(layer "In11.Cu")
		(net "P5E_CPU1_PE1_RX_DN<1>")
	)
	(segment
		(start 118.486682 -221.632018)
		(end 118.502176 -221.622874)
		(width 0.0889)
		(layer "In11.Cu")
		(net "P5E_CPU1_PE1_RX_DN<1>")
	)
	(segment
		(start 117.843554 -214.36711)
		(end 117.569742 -214.093298)
		(width 0.0889)
		(layer "In11.Cu")
		(net "P5E_CPU1_PE1_RX_DN<1>")
	)
	(segment
		(start 56.754268 -16.490442)
		(end 54.383686 -12.579096)
		(width 0.14732)
		(layer "In11.Cu")
		(net "P5E_CPU1_PE1_RX_DN<1>")
	)
	(segment
		(start 117.561614 -219.01658)
		(end 117.56009 -219.015818)
		(width 0.0889)
		(layer "In11.Cu")
		(net "P5E_CPU1_PE1_RX_DN<1>")
	)
	(segment
		(start 117.374162 -215.452198)
		(end 117.374162 -215.436704)
		(width 0.0889)
		(layer "In11.Cu")
		(net "P5E_CPU1_PE1_RX_DN<1>")
	)
	(segment
		(start 117.56771 -219.020136)
		(end 117.564408 -219.018104)
		(width 0.0889)
		(layer "In11.Cu")
		(net "P5E_CPU1_PE1_RX_DN<1>")
	)
	(segment
		(start 117.564408 -219.018104)
		(end 117.561614 -219.01658)
		(width 0.0889)
		(layer "In11.Cu")
		(net "P5E_CPU1_PE1_RX_DN<1>")
	)
	(segment
		(start 117.905276 -221.676722)
		(end 117.99443 -221.652846)
		(width 0.0889)
		(layer "In11.Cu")
		(net "P5E_CPU1_PE1_RX_DN<1>")
	)
	(segment
		(start 118.502176 -221.622874)
		(end 118.50751 -221.619826)
		(width 0.0889)
		(layer "In11.Cu")
		(net "P5E_CPU1_PE1_RX_DN<1>")
	)
	(segment
		(start 54.305708 -7.019036)
		(end 54.600348 -6.724396)
		(width 0.14732)
		(layer "In11.Cu")
		(net "P5E_CPU1_PE1_RX_DN<1>")
	)
	(segment
		(start 117.561868 -217.388694)
		(end 117.552978 -217.383614)
		(width 0.0889)
		(layer "In11.Cu")
		(net "P5E_CPU1_PE1_RX_DN<1>")
	)
	(segment
		(start 117.552724 -215.117426)
		(end 117.560598 -215.112854)
		(width 0.0889)
		(layer "In11.Cu")
		(net "P5E_CPU1_PE1_RX_DN<1>")
	)
	(segment
		(start 117.097302 -205.631542)
		(end 113.96726 -183.241188)
		(width 0.14732)
		(layer "In11.Cu")
		(net "P5E_CPU1_PE1_RX_DN<1>")
	)
	(segment
		(start 117.098064 -216.578434)
		(end 117.091968 -216.574878)
		(width 0.0889)
		(layer "In11.Cu")
		(net "P5E_CPU1_PE1_RX_DN<1>")
	)
	(segment
		(start 113.96726 -183.241188)
		(end 113.412778 -180.075332)
		(width 0.14732)
		(layer "In11.Cu")
		(net "P5E_CPU1_PE1_RX_DN<1>")
	)
	(segment
		(start 117.843808 -214.622888)
		(end 117.843554 -214.622634)
		(width 0.0889)
		(layer "In11.Cu")
		(net "P5E_CPU1_PE1_RX_DN<1>")
	)
	(segment
		(start 117.090952 -215.92667)
		(end 117.091968 -215.926162)
		(width 0.0889)
		(layer "In11.Cu")
		(net "P5E_CPU1_PE1_RX_DN<1>")
	)
	(segment
		(start 54.383686 -12.579096)
		(end 54.305708 -12.299696)
		(width 0.14732)
		(layer "In11.Cu")
		(net "P5E_CPU1_PE1_RX_DN<1>")
	)
	(arc
		(start 117.99443 -221.652846)
		(mid 118.004424 -221.657005)
		(end 118.014496 -221.660974)
		(width 0.0889)
		(layer "In11.Cu")
		(net "P5E_CPU1_PE1_RX_DN<1>")
	)
	(arc
		(start 117.091968 -215.926162)
		(mid 117.294791 -215.725931)
		(end 117.374162 -215.452198)
		(width 0.0889)
		(layer "In11.Cu")
		(net "P5E_CPU1_PE1_RX_DN<1>")
	)
	(arc
		(start 117.374162 -215.436704)
		(mid 117.374214 -215.429337)
		(end 117.374416 -215.421972)
		(width 0.0889)
		(layer "In11.Cu")
		(net "P5E_CPU1_PE1_RX_DN<1>")
	)
	(arc
		(start 117.552724 -219.0115)
		(mid 117.374127 -218.692222)
		(end 117.552724 -218.372944)
		(width 0.0889)
		(layer "In11.Cu")
		(net "P5E_CPU1_PE1_RX_DN<1>")
	)
	(arc
		(start 118.314216 -220.309948)
		(mid 118.236105 -220.032999)
		(end 118.031768 -219.830396)
		(width 0.0889)
		(layer "In11.Cu")
		(net "P5E_CPU1_PE1_RX_DN<1>")
	)
	(arc
		(start 117.374416 -217.064336)
		(mid 117.3005 -216.784834)
		(end 117.098064 -216.578434)
		(width 0.0889)
		(layer "In11.Cu")
		(net "P5E_CPU1_PE1_RX_DN<1>")
	)
	(arc
		(start 117.374416 -215.421972)
		(mid 117.42547 -215.247392)
		(end 117.552724 -215.117426)
		(width 0.0889)
		(layer "In11.Cu")
		(net "P5E_CPU1_PE1_RX_DN<1>")
	)
	(arc
		(start 117.083078 -216.569798)
		(mid 116.904602 -216.25052)
		(end 117.083078 -215.931242)
		(width 0.0889)
		(layer "In11.Cu")
		(net "P5E_CPU1_PE1_RX_DN<1>")
	)
	(arc
		(start 118.022878 -219.825316)
		(mid 117.891964 -219.688956)
		(end 117.844316 -219.506038)
		(width 0.0889)
		(layer "In11.Cu")
		(net "P5E_CPU1_PE1_RX_DN<1>")
	)
	(arc
		(start 118.50751 -221.619826)
		(mid 118.784197 -221.130332)
		(end 118.501414 -220.644212)
		(width 0.0889)
		(layer "In11.Cu")
		(net "P5E_CPU1_PE1_RX_DN<1>")
	)
	(arc
		(start 118.501414 -220.644212)
		(mid 118.366481 -220.510858)
		(end 118.314216 -220.32849)
		(width 0.0889)
		(layer "In11.Cu")
		(net "P5E_CPU1_PE1_RX_DN<1>")
	)
	(arc
		(start 117.561614 -215.112346)
		(mid 117.762896 -214.914859)
		(end 117.843808 -214.644732)
		(width 0.0889)
		(layer "In11.Cu")
		(net "P5E_CPU1_PE1_RX_DN<1>")
	)
	(arc
		(start 117.56771 -218.364308)
		(mid 117.844617 -217.874797)
		(end 117.561868 -217.388694)
		(width 0.0889)
		(layer "In11.Cu")
		(net "P5E_CPU1_PE1_RX_DN<1>")
	)
	(arc
		(start 117.558566 -214.093298)
		(mid 117.449419 -214.00937)
		(end 117.374416 -213.893908)
		(width 0.0889)
		(layer "In11.Cu")
		(net "P5E_CPU1_PE1_RX_DN<1>")
	)
	(arc
		(start 117.552978 -217.383614)
		(mid 117.422064 -217.247254)
		(end 117.374416 -217.064336)
		(width 0.0889)
		(layer "In11.Cu")
		(net "P5E_CPU1_PE1_RX_DN<1>")
	)
	(arc
		(start 117.844316 -219.506038)
		(mid 117.770325 -219.226472)
		(end 117.56771 -219.020136)
		(width 0.0889)
		(layer "In11.Cu")
		(net "P5E_CPU1_PE1_RX_DN<1>")
	)
	(arc
		(start 118.014496 -221.660974)
		(mid 118.253771 -221.698282)
		(end 118.486682 -221.632018)
		(width 0.0889)
		(layer "In11.Cu")
		(net "P5E_CPU1_PE1_RX_DN<1>")
	)
	(segment
		(start 104.591866 -222.48368)
		(end 104.591612 -222.483426)
		(width 0.13208)
		(layer "F.Cu")
		(net "P5E_CPU1_PE1_RX_DN<15>")
	)
	(segment
		(start 19.74723 -8.31977)
		(end 19.74723 -7.779258)
		(width 0.13208)
		(layer "F.Cu")
		(net "P5E_CPU1_PE1_RX_DN<15>")
	)
	(segment
		(start 19.746976 -8.320024)
		(end 19.74723 -8.31977)
		(width 0.13208)
		(layer "F.Cu")
		(net "P5E_CPU1_PE1_RX_DN<15>")
	)
	(segment
		(start 19.578066 -7.026656)
		(end 19.880326 -6.724396)
		(width 0.13208)
		(layer "F.Cu")
		(net "P5E_CPU1_PE1_RX_DN<15>")
	)
	(segment
		(start 19.578066 -7.610094)
		(end 19.578066 -7.026656)
		(width 0.13208)
		(layer "F.Cu")
		(net "P5E_CPU1_PE1_RX_DN<15>")
	)
	(segment
		(start 19.74723 -7.779258)
		(end 19.578066 -7.610094)
		(width 0.13208)
		(layer "F.Cu")
		(net "P5E_CPU1_PE1_RX_DN<15>")
	)
	(segment
		(start 104.591612 -222.483426)
		(end 104.591612 -221.94774)
		(width 0.13208)
		(layer "F.Cu")
		(net "P5E_CPU1_PE1_RX_DN<15>")
	)
	(segment
		(start 103.31958 -213.04123)
		(end 103.31958 -209.067146)
		(width 0.14732)
		(layer "In11.Cu")
		(net "P5E_CPU1_PE1_RX_DN<15>")
	)
	(segment
		(start 103.47071 -215.764618)
		(end 103.464614 -215.761062)
		(width 0.0889)
		(layer "In11.Cu")
		(net "P5E_CPU1_PE1_RX_DN<15>")
	)
	(segment
		(start 17.250664 -18.637758)
		(end 17.751806 -18.136616)
		(width 0.14732)
		(layer "In11.Cu")
		(net "P5E_CPU1_PE1_RX_DN<15>")
	)
	(segment
		(start 105.329482 -221.632018)
		(end 105.35031 -221.619826)
		(width 0.0889)
		(layer "In11.Cu")
		(net "P5E_CPU1_PE1_RX_DN<15>")
	)
	(segment
		(start 103.746808 -214.644732)
		(end 103.746808 -214.424768)
		(width 0.0889)
		(layer "In11.Cu")
		(net "P5E_CPU1_PE1_RX_DN<15>")
	)
	(segment
		(start 17.1323 -18.923)
		(end 17.250664 -18.637758)
		(width 0.14732)
		(layer "In11.Cu")
		(net "P5E_CPU1_PE1_RX_DN<15>")
	)
	(segment
		(start 19.585686 -7.019036)
		(end 19.880326 -6.724396)
		(width 0.14732)
		(layer "In11.Cu")
		(net "P5E_CPU1_PE1_RX_DN<15>")
	)
	(segment
		(start 104.404414 -219.01658)
		(end 104.395524 -219.0115)
		(width 0.0889)
		(layer "In11.Cu")
		(net "P5E_CPU1_PE1_RX_DN<15>")
	)
	(segment
		(start 103.464614 -215.761062)
		(end 103.455724 -215.755982)
		(width 0.0889)
		(layer "In11.Cu")
		(net "P5E_CPU1_PE1_RX_DN<15>")
	)
	(segment
		(start 103.925878 -217.559128)
		(end 103.934768 -217.554048)
		(width 0.0889)
		(layer "In11.Cu")
		(net "P5E_CPU1_PE1_RX_DN<15>")
	)
	(segment
		(start 103.934768 -218.202764)
		(end 103.925878 -218.197684)
		(width 0.0889)
		(layer "In11.Cu")
		(net "P5E_CPU1_PE1_RX_DN<15>")
	)
	(segment
		(start 103.277416 -213.105492)
		(end 103.31958 -213.063328)
		(width 0.0889)
		(layer "In11.Cu")
		(net "P5E_CPU1_PE1_RX_DN<15>")
	)
	(segment
		(start 105.626916 -221.133924)
		(end 105.626916 -221.1197)
		(width 0.0889)
		(layer "In11.Cu")
		(net "P5E_CPU1_PE1_RX_DN<15>")
	)
	(segment
		(start 104.748076 -221.676722)
		(end 104.83723 -221.652846)
		(width 0.0889)
		(layer "In11.Cu")
		(net "P5E_CPU1_PE1_RX_DN<15>")
	)
	(segment
		(start 103.455724 -215.117426)
		(end 103.464614 -215.112346)
		(width 0.0889)
		(layer "In11.Cu")
		(net "P5E_CPU1_PE1_RX_DN<15>")
	)
	(segment
		(start 104.217216 -217.07856)
		(end 104.217216 -217.064336)
		(width 0.0889)
		(layer "In11.Cu")
		(net "P5E_CPU1_PE1_RX_DN<15>")
	)
	(segment
		(start 104.216962 -218.692222)
		(end 104.216962 -218.676728)
		(width 0.0889)
		(layer "In11.Cu")
		(net "P5E_CPU1_PE1_RX_DN<15>")
	)
	(segment
		(start 17.751806 -18.136616)
		(end 19.585686 -12.583668)
		(width 0.14732)
		(layer "In11.Cu")
		(net "P5E_CPU1_PE1_RX_DN<15>")
	)
	(segment
		(start 19.585686 -12.583668)
		(end 19.585686 -7.019036)
		(width 0.14732)
		(layer "In11.Cu")
		(net "P5E_CPU1_PE1_RX_DN<15>")
	)
	(segment
		(start 103.31958 -209.067146)
		(end 99.727258 -181.717696)
		(width 0.14732)
		(layer "In11.Cu")
		(net "P5E_CPU1_PE1_RX_DN<15>")
	)
	(segment
		(start 50.038 -61.764164)
		(end 17.251172 -19.71548)
		(width 0.14732)
		(layer "In11.Cu")
		(net "P5E_CPU1_PE1_RX_DN<15>")
	)
	(segment
		(start 103.934768 -216.574878)
		(end 103.925878 -216.569798)
		(width 0.0889)
		(layer "In11.Cu")
		(net "P5E_CPU1_PE1_RX_DN<15>")
	)
	(segment
		(start 104.874568 -219.830396)
		(end 104.865678 -219.825316)
		(width 0.0889)
		(layer "In11.Cu")
		(net "P5E_CPU1_PE1_RX_DN<15>")
	)
	(segment
		(start 17.251172 -19.71548)
		(end 17.1323 -19.428968)
		(width 0.14732)
		(layer "In11.Cu")
		(net "P5E_CPU1_PE1_RX_DN<15>")
	)
	(segment
		(start 105.157016 -220.32849)
		(end 105.157016 -220.309948)
		(width 0.0889)
		(layer "In11.Cu")
		(net "P5E_CPU1_PE1_RX_DN<15>")
	)
	(segment
		(start 103.31958 -213.063328)
		(end 103.31958 -213.04123)
		(width 0.0889)
		(layer "In11.Cu")
		(net "P5E_CPU1_PE1_RX_DN<15>")
	)
	(segment
		(start 99.727258 -181.717696)
		(end 50.038 -61.764164)
		(width 0.14732)
		(layer "In11.Cu")
		(net "P5E_CPU1_PE1_RX_DN<15>")
	)
	(segment
		(start 103.940864 -216.578434)
		(end 103.934768 -216.574878)
		(width 0.0889)
		(layer "In11.Cu")
		(net "P5E_CPU1_PE1_RX_DN<15>")
	)
	(segment
		(start 104.591612 -221.94774)
		(end 104.748076 -221.676722)
		(width 0.0889)
		(layer "In11.Cu")
		(net "P5E_CPU1_PE1_RX_DN<15>")
	)
	(segment
		(start 103.277416 -213.893908)
		(end 103.277416 -213.105492)
		(width 0.0889)
		(layer "In11.Cu")
		(net "P5E_CPU1_PE1_RX_DN<15>")
	)
	(segment
		(start 17.1323 -19.428968)
		(end 17.1323 -18.923)
		(width 0.14732)
		(layer "In11.Cu")
		(net "P5E_CPU1_PE1_RX_DN<15>")
	)
	(segment
		(start 104.41051 -219.020136)
		(end 104.404414 -219.01658)
		(width 0.0889)
		(layer "In11.Cu")
		(net "P5E_CPU1_PE1_RX_DN<15>")
	)
	(arc
		(start 104.83723 -221.652846)
		(mid 104.847224 -221.657005)
		(end 104.857296 -221.660974)
		(width 0.0889)
		(layer "In11.Cu")
		(net "P5E_CPU1_PE1_RX_DN<15>")
	)
	(arc
		(start 103.461566 -214.093298)
		(mid 103.352419 -214.00937)
		(end 103.277416 -213.893908)
		(width 0.0889)
		(layer "In11.Cu")
		(net "P5E_CPU1_PE1_RX_DN<15>")
	)
	(arc
		(start 104.216962 -218.676728)
		(mid 104.137592 -218.402994)
		(end 103.934768 -218.202764)
		(width 0.0889)
		(layer "In11.Cu")
		(net "P5E_CPU1_PE1_RX_DN<15>")
	)
	(arc
		(start 103.925878 -216.569798)
		(mid 103.794964 -216.433438)
		(end 103.747316 -216.25052)
		(width 0.0889)
		(layer "In11.Cu")
		(net "P5E_CPU1_PE1_RX_DN<15>")
	)
	(arc
		(start 104.687116 -219.506038)
		(mid 104.613125 -219.226472)
		(end 104.41051 -219.020136)
		(width 0.0889)
		(layer "In11.Cu")
		(net "P5E_CPU1_PE1_RX_DN<15>")
	)
	(arc
		(start 103.747824 -217.863674)
		(mid 103.798734 -217.689105)
		(end 103.925878 -217.559128)
		(width 0.0889)
		(layer "In11.Cu")
		(net "P5E_CPU1_PE1_RX_DN<15>")
	)
	(arc
		(start 105.35031 -221.619826)
		(mid 105.552897 -221.413475)
		(end 105.626916 -221.133924)
		(width 0.0889)
		(layer "In11.Cu")
		(net "P5E_CPU1_PE1_RX_DN<15>")
	)
	(arc
		(start 105.344214 -220.644212)
		(mid 105.209281 -220.510858)
		(end 105.157016 -220.32849)
		(width 0.0889)
		(layer "In11.Cu")
		(net "P5E_CPU1_PE1_RX_DN<15>")
	)
	(arc
		(start 103.934768 -217.554048)
		(mid 104.138073 -217.353182)
		(end 104.217216 -217.07856)
		(width 0.0889)
		(layer "In11.Cu")
		(net "P5E_CPU1_PE1_RX_DN<15>")
	)
	(arc
		(start 103.277416 -215.421972)
		(mid 103.32847 -215.247392)
		(end 103.455724 -215.117426)
		(width 0.0889)
		(layer "In11.Cu")
		(net "P5E_CPU1_PE1_RX_DN<15>")
	)
	(arc
		(start 103.747316 -216.25052)
		(mid 103.673325 -215.970954)
		(end 103.47071 -215.764618)
		(width 0.0889)
		(layer "In11.Cu")
		(net "P5E_CPU1_PE1_RX_DN<15>")
	)
	(arc
		(start 104.395524 -219.0115)
		(mid 104.26461 -218.87514)
		(end 104.216962 -218.692222)
		(width 0.0889)
		(layer "In11.Cu")
		(net "P5E_CPU1_PE1_RX_DN<15>")
	)
	(arc
		(start 103.925878 -218.197684)
		(mid 103.797559 -218.065712)
		(end 103.74757 -217.888566)
		(width 0.0889)
		(layer "In11.Cu")
		(net "P5E_CPU1_PE1_RX_DN<15>")
	)
	(arc
		(start 103.74757 -217.888566)
		(mid 103.74749 -217.876118)
		(end 103.747824 -217.863674)
		(width 0.0889)
		(layer "In11.Cu")
		(net "P5E_CPU1_PE1_RX_DN<15>")
	)
	(arc
		(start 103.455724 -215.755982)
		(mid 103.32481 -215.619622)
		(end 103.277162 -215.436704)
		(width 0.0889)
		(layer "In11.Cu")
		(net "P5E_CPU1_PE1_RX_DN<15>")
	)
	(arc
		(start 104.217216 -217.064336)
		(mid 104.1433 -216.784834)
		(end 103.940864 -216.578434)
		(width 0.0889)
		(layer "In11.Cu")
		(net "P5E_CPU1_PE1_RX_DN<15>")
	)
	(arc
		(start 103.277162 -215.436704)
		(mid 103.277214 -215.429337)
		(end 103.277416 -215.421972)
		(width 0.0889)
		(layer "In11.Cu")
		(net "P5E_CPU1_PE1_RX_DN<15>")
	)
	(arc
		(start 105.626916 -221.1197)
		(mid 105.547697 -220.845015)
		(end 105.344214 -220.644212)
		(width 0.0889)
		(layer "In11.Cu")
		(net "P5E_CPU1_PE1_RX_DN<15>")
	)
	(arc
		(start 105.157016 -220.309948)
		(mid 105.078905 -220.032999)
		(end 104.874568 -219.830396)
		(width 0.0889)
		(layer "In11.Cu")
		(net "P5E_CPU1_PE1_RX_DN<15>")
	)
	(arc
		(start 104.865678 -219.825316)
		(mid 104.734764 -219.688956)
		(end 104.687116 -219.506038)
		(width 0.0889)
		(layer "In11.Cu")
		(net "P5E_CPU1_PE1_RX_DN<15>")
	)
	(arc
		(start 103.746808 -214.424768)
		(mid 103.635529 -214.232062)
		(end 103.461566 -214.093298)
		(width 0.0889)
		(layer "In11.Cu")
		(net "P5E_CPU1_PE1_RX_DN<15>")
	)
	(arc
		(start 104.857296 -221.660974)
		(mid 105.096571 -221.698282)
		(end 105.329482 -221.632018)
		(width 0.0889)
		(layer "In11.Cu")
		(net "P5E_CPU1_PE1_RX_DN<15>")
	)
	(arc
		(start 103.464614 -215.112346)
		(mid 103.665896 -214.914859)
		(end 103.746808 -214.644732)
		(width 0.0889)
		(layer "In11.Cu")
		(net "P5E_CPU1_PE1_RX_DN<15>")
	)
	(segment
		(start 106.001312 -221.134178)
		(end 106.001566 -221.133924)
		(width 0.13208)
		(layer "F.Cu")
		(net "P5E_CPU1_PE1_RX_DN<14>")
	)
	(segment
		(start 21.547074 -8.320024)
		(end 21.547074 -7.775702)
		(width 0.13208)
		(layer "F.Cu")
		(net "P5E_CPU1_PE1_RX_DN<14>")
	)
	(segment
		(start 21.38172 -5.265928)
		(end 21.684996 -4.962652)
		(width 0.13208)
		(layer "F.Cu")
		(net "P5E_CPU1_PE1_RX_DN<14>")
	)
	(segment
		(start 106.001312 -221.669864)
		(end 106.001312 -221.134178)
		(width 0.13208)
		(layer "F.Cu")
		(net "P5E_CPU1_PE1_RX_DN<14>")
	)
	(segment
		(start 21.38172 -7.610348)
		(end 21.38172 -5.265928)
		(width 0.13208)
		(layer "F.Cu")
		(net "P5E_CPU1_PE1_RX_DN<14>")
	)
	(segment
		(start 21.547074 -7.775702)
		(end 21.38172 -7.610348)
		(width 0.13208)
		(layer "F.Cu")
		(net "P5E_CPU1_PE1_RX_DN<14>")
	)
	(segment
		(start 100.641658 -181.462172)
		(end 50.869596 -61.30671)
		(width 0.14732)
		(layer "In11.Cu")
		(net "P5E_CPU1_PE1_RX_DN<14>")
	)
	(segment
		(start 105.344214 -219.01658)
		(end 105.335324 -219.0115)
		(width 0.0889)
		(layer "In11.Cu")
		(net "P5E_CPU1_PE1_RX_DN<14>")
	)
	(segment
		(start 50.869596 -61.30671)
		(end 20.67306 -18.796254)
		(width 0.14732)
		(layer "In11.Cu")
		(net "P5E_CPU1_PE1_RX_DN<14>")
	)
	(segment
		(start 104.404414 -215.761062)
		(end 104.40289 -215.7603)
		(width 0.0889)
		(layer "In11.Cu")
		(net "P5E_CPU1_PE1_RX_DN<14>")
	)
	(segment
		(start 105.814368 -219.830396)
		(end 105.805478 -219.825316)
		(width 0.0889)
		(layer "In11.Cu")
		(net "P5E_CPU1_PE1_RX_DN<14>")
	)
	(segment
		(start 104.874568 -217.554302)
		(end 104.874568 -217.554048)
		(width 0.0889)
		(layer "In11.Cu")
		(net "P5E_CPU1_PE1_RX_DN<14>")
	)
	(segment
		(start 104.686608 -214.644732)
		(end 104.686608 -214.424768)
		(width 0.0889)
		(layer "In11.Cu")
		(net "P5E_CPU1_PE1_RX_DN<14>")
	)
	(segment
		(start 104.25684 -208.988152)
		(end 100.641658 -181.462172)
		(width 0.14732)
		(layer "In11.Cu")
		(net "P5E_CPU1_PE1_RX_DN<14>")
	)
	(segment
		(start 105.157016 -217.082878)
		(end 105.157016 -217.05443)
		(width 0.0889)
		(layer "In11.Cu")
		(net "P5E_CPU1_PE1_RX_DN<14>")
	)
	(segment
		(start 104.259126 -208.990438)
		(end 104.25684 -208.988152)
		(width 0.14732)
		(layer "In11.Cu")
		(net "P5E_CPU1_PE1_RX_DN<14>")
	)
	(segment
		(start 105.820464 -219.833952)
		(end 105.814368 -219.830396)
		(width 0.0889)
		(layer "In11.Cu")
		(net "P5E_CPU1_PE1_RX_DN<14>")
	)
	(segment
		(start 21.365972 -12.527534)
		(end 21.390356 -12.360148)
		(width 0.14732)
		(layer "In11.Cu")
		(net "P5E_CPU1_PE1_RX_DN<14>")
	)
	(segment
		(start 104.395524 -215.117426)
		(end 104.403398 -215.112854)
		(width 0.0889)
		(layer "In11.Cu")
		(net "P5E_CPU1_PE1_RX_DN<14>")
	)
	(segment
		(start 19.95424 -17.234408)
		(end 21.365972 -12.527534)
		(width 0.14732)
		(layer "In11.Cu")
		(net "P5E_CPU1_PE1_RX_DN<14>")
	)
	(segment
		(start 104.216962 -213.105492)
		(end 104.259126 -213.063328)
		(width 0.0889)
		(layer "In11.Cu")
		(net "P5E_CPU1_PE1_RX_DN<14>")
	)
	(segment
		(start 104.259126 -213.063328)
		(end 104.259126 -213.04123)
		(width 0.0889)
		(layer "In11.Cu")
		(net "P5E_CPU1_PE1_RX_DN<14>")
	)
	(segment
		(start 105.156762 -218.692222)
		(end 105.156762 -218.676728)
		(width 0.0889)
		(layer "In11.Cu")
		(net "P5E_CPU1_PE1_RX_DN<14>")
	)
	(segment
		(start 104.40289 -215.7603)
		(end 104.395524 -215.755982)
		(width 0.0889)
		(layer "In11.Cu")
		(net "P5E_CPU1_PE1_RX_DN<14>")
	)
	(segment
		(start 104.403398 -215.112854)
		(end 104.404414 -215.112346)
		(width 0.0889)
		(layer "In11.Cu")
		(net "P5E_CPU1_PE1_RX_DN<14>")
	)
	(segment
		(start 104.216962 -213.894924)
		(end 104.216962 -213.105492)
		(width 0.0889)
		(layer "In11.Cu")
		(net "P5E_CPU1_PE1_RX_DN<14>")
	)
	(segment
		(start 104.41051 -215.764618)
		(end 104.407208 -215.762586)
		(width 0.0889)
		(layer "In11.Cu")
		(net "P5E_CPU1_PE1_RX_DN<14>")
	)
	(segment
		(start 104.259126 -213.04123)
		(end 104.259126 -208.990438)
		(width 0.14732)
		(layer "In11.Cu")
		(net "P5E_CPU1_PE1_RX_DN<14>")
	)
	(segment
		(start 21.390356 -5.257292)
		(end 21.684996 -4.962652)
		(width 0.14732)
		(layer "In11.Cu")
		(net "P5E_CPU1_PE1_RX_DN<14>")
	)
	(segment
		(start 106.001566 -221.133924)
		(end 105.845102 -220.862906)
		(width 0.0889)
		(layer "In11.Cu")
		(net "P5E_CPU1_PE1_RX_DN<14>")
	)
	(segment
		(start 104.874568 -218.202764)
		(end 104.874314 -218.20251)
		(width 0.0889)
		(layer "In11.Cu")
		(net "P5E_CPU1_PE1_RX_DN<14>")
	)
	(segment
		(start 20.67306 -18.796254)
		(end 20.179792 -18.30324)
		(width 0.14732)
		(layer "In11.Cu")
		(net "P5E_CPU1_PE1_RX_DN<14>")
	)
	(segment
		(start 20.179792 -18.30324)
		(end 19.95424 -17.758664)
		(width 0.14732)
		(layer "In11.Cu")
		(net "P5E_CPU1_PE1_RX_DN<14>")
	)
	(segment
		(start 104.401366 -214.093298)
		(end 104.401112 -214.093552)
		(width 0.0889)
		(layer "In11.Cu")
		(net "P5E_CPU1_PE1_RX_DN<14>")
	)
	(segment
		(start 104.401112 -214.093552)
		(end 104.401112 -214.093806)
		(width 0.0889)
		(layer "In11.Cu")
		(net "P5E_CPU1_PE1_RX_DN<14>")
	)
	(segment
		(start 19.95424 -17.758664)
		(end 19.95424 -17.234408)
		(width 0.14732)
		(layer "In11.Cu")
		(net "P5E_CPU1_PE1_RX_DN<14>")
	)
	(segment
		(start 105.35031 -219.020136)
		(end 105.344214 -219.01658)
		(width 0.0889)
		(layer "In11.Cu")
		(net "P5E_CPU1_PE1_RX_DN<14>")
	)
	(segment
		(start 105.845102 -220.862906)
		(end 105.869232 -220.773752)
		(width 0.0889)
		(layer "In11.Cu")
		(net "P5E_CPU1_PE1_RX_DN<14>")
	)
	(segment
		(start 106.096816 -220.334078)
		(end 106.096816 -220.319854)
		(width 0.0889)
		(layer "In11.Cu")
		(net "P5E_CPU1_PE1_RX_DN<14>")
	)
	(segment
		(start 104.407208 -215.762586)
		(end 104.404414 -215.761062)
		(width 0.0889)
		(layer "In11.Cu")
		(net "P5E_CPU1_PE1_RX_DN<14>")
	)
	(segment
		(start 21.390356 -12.360148)
		(end 21.390356 -5.257292)
		(width 0.14732)
		(layer "In11.Cu")
		(net "P5E_CPU1_PE1_RX_DN<14>")
	)
	(segment
		(start 104.874568 -216.574878)
		(end 104.865678 -216.569798)
		(width 0.0889)
		(layer "In11.Cu")
		(net "P5E_CPU1_PE1_RX_DN<14>")
	)
	(arc
		(start 104.687116 -216.25052)
		(mid 104.613125 -215.970954)
		(end 104.41051 -215.764618)
		(width 0.0889)
		(layer "In11.Cu")
		(net "P5E_CPU1_PE1_RX_DN<14>")
	)
	(arc
		(start 104.874568 -217.554048)
		(mid 105.076854 -217.355067)
		(end 105.157016 -217.082878)
		(width 0.0889)
		(layer "In11.Cu")
		(net "P5E_CPU1_PE1_RX_DN<14>")
	)
	(arc
		(start 104.217216 -215.421972)
		(mid 104.26827 -215.247392)
		(end 104.395524 -215.117426)
		(width 0.0889)
		(layer "In11.Cu")
		(net "P5E_CPU1_PE1_RX_DN<14>")
	)
	(arc
		(start 104.216962 -215.436704)
		(mid 104.217014 -215.429337)
		(end 104.217216 -215.421972)
		(width 0.0889)
		(layer "In11.Cu")
		(net "P5E_CPU1_PE1_RX_DN<14>")
	)
	(arc
		(start 105.869232 -220.773752)
		(mid 105.877675 -220.767354)
		(end 105.885996 -220.760798)
		(width 0.0889)
		(layer "In11.Cu")
		(net "P5E_CPU1_PE1_RX_DN<14>")
	)
	(arc
		(start 104.401112 -214.093806)
		(mid 104.292088 -214.010066)
		(end 104.216962 -213.894924)
		(width 0.0889)
		(layer "In11.Cu")
		(net "P5E_CPU1_PE1_RX_DN<14>")
	)
	(arc
		(start 105.156762 -218.676728)
		(mid 105.077392 -218.402994)
		(end 104.874568 -218.202764)
		(width 0.0889)
		(layer "In11.Cu")
		(net "P5E_CPU1_PE1_RX_DN<14>")
	)
	(arc
		(start 104.686608 -214.424768)
		(mid 104.575329 -214.232062)
		(end 104.401366 -214.093298)
		(width 0.0889)
		(layer "In11.Cu")
		(net "P5E_CPU1_PE1_RX_DN<14>")
	)
	(arc
		(start 105.805478 -219.825316)
		(mid 105.674564 -219.688956)
		(end 105.626916 -219.506038)
		(width 0.0889)
		(layer "In11.Cu")
		(net "P5E_CPU1_PE1_RX_DN<14>")
	)
	(arc
		(start 105.157016 -217.05443)
		(mid 105.078905 -216.777481)
		(end 104.874568 -216.574878)
		(width 0.0889)
		(layer "In11.Cu")
		(net "P5E_CPU1_PE1_RX_DN<14>")
	)
	(arc
		(start 104.874314 -218.20251)
		(mid 104.737269 -218.06555)
		(end 104.687116 -217.878406)
		(width 0.0889)
		(layer "In11.Cu")
		(net "P5E_CPU1_PE1_RX_DN<14>")
	)
	(arc
		(start 104.395524 -215.755982)
		(mid 104.26461 -215.619622)
		(end 104.216962 -215.436704)
		(width 0.0889)
		(layer "In11.Cu")
		(net "P5E_CPU1_PE1_RX_DN<14>")
	)
	(arc
		(start 104.404414 -215.112346)
		(mid 104.605696 -214.914859)
		(end 104.686608 -214.644732)
		(width 0.0889)
		(layer "In11.Cu")
		(net "P5E_CPU1_PE1_RX_DN<14>")
	)
	(arc
		(start 106.096816 -220.319854)
		(mid 106.0229 -220.040352)
		(end 105.820464 -219.833952)
		(width 0.0889)
		(layer "In11.Cu")
		(net "P5E_CPU1_PE1_RX_DN<14>")
	)
	(arc
		(start 105.626916 -219.506038)
		(mid 105.552925 -219.226472)
		(end 105.35031 -219.020136)
		(width 0.0889)
		(layer "In11.Cu")
		(net "P5E_CPU1_PE1_RX_DN<14>")
	)
	(arc
		(start 105.335324 -219.0115)
		(mid 105.20441 -218.87514)
		(end 105.156762 -218.692222)
		(width 0.0889)
		(layer "In11.Cu")
		(net "P5E_CPU1_PE1_RX_DN<14>")
	)
	(arc
		(start 104.687116 -217.878406)
		(mid 104.737356 -217.691205)
		(end 104.874568 -217.554302)
		(width 0.0889)
		(layer "In11.Cu")
		(net "P5E_CPU1_PE1_RX_DN<14>")
	)
	(arc
		(start 105.885996 -220.760798)
		(mid 106.038503 -220.5707)
		(end 106.096816 -220.334078)
		(width 0.0889)
		(layer "In11.Cu")
		(net "P5E_CPU1_PE1_RX_DN<14>")
	)
	(arc
		(start 104.865678 -216.569798)
		(mid 104.734764 -216.433438)
		(end 104.687116 -216.25052)
		(width 0.0889)
		(layer "In11.Cu")
		(net "P5E_CPU1_PE1_RX_DN<14>")
	)
	(segment
		(start 23.178008 -7.026656)
		(end 23.480268 -6.724396)
		(width 0.13208)
		(layer "F.Cu")
		(net "P5E_CPU1_PE1_RX_DN<13>")
	)
	(segment
		(start 23.178008 -7.610094)
		(end 23.178008 -7.026656)
		(width 0.13208)
		(layer "F.Cu")
		(net "P5E_CPU1_PE1_RX_DN<13>")
	)
	(segment
		(start 23.346918 -7.779004)
		(end 23.178008 -7.610094)
		(width 0.13208)
		(layer "F.Cu")
		(net "P5E_CPU1_PE1_RX_DN<13>")
	)
	(segment
		(start 106.471466 -222.48368)
		(end 106.471466 -221.947994)
		(width 0.13208)
		(layer "F.Cu")
		(net "P5E_CPU1_PE1_RX_DN<13>")
	)
	(segment
		(start 23.346918 -8.320024)
		(end 23.346918 -7.779004)
		(width 0.13208)
		(layer "F.Cu")
		(net "P5E_CPU1_PE1_RX_DN<13>")
	)
	(segment
		(start 106.471466 -221.947994)
		(end 106.471212 -221.94774)
		(width 0.13208)
		(layer "F.Cu")
		(net "P5E_CPU1_PE1_RX_DN<13>")
	)
	(segment
		(start 22.74062 -19.321018)
		(end 22.74062 -18.94459)
		(width 0.14732)
		(layer "In11.Cu")
		(net "P5E_CPU1_PE1_RX_DN<13>")
	)
	(segment
		(start 105.343198 -215.112854)
		(end 105.344214 -215.112346)
		(width 0.0889)
		(layer "In11.Cu")
		(net "P5E_CPU1_PE1_RX_DN<13>")
	)
	(segment
		(start 106.096816 -217.07856)
		(end 106.096816 -217.064336)
		(width 0.0889)
		(layer "In11.Cu")
		(net "P5E_CPU1_PE1_RX_DN<13>")
	)
	(segment
		(start 23.53056 -16.964152)
		(end 23.185628 -12.732512)
		(width 0.14732)
		(layer "In11.Cu")
		(net "P5E_CPU1_PE1_RX_DN<13>")
	)
	(segment
		(start 105.157016 -213.893908)
		(end 105.157016 -213.105492)
		(width 0.0889)
		(layer "In11.Cu")
		(net "P5E_CPU1_PE1_RX_DN<13>")
	)
	(segment
		(start 105.19918 -213.063328)
		(end 105.19918 -213.04123)
		(width 0.0889)
		(layer "In11.Cu")
		(net "P5E_CPU1_PE1_RX_DN<13>")
	)
	(segment
		(start 23.347172 -18.212816)
		(end 23.53056 -17.770348)
		(width 0.14732)
		(layer "In11.Cu")
		(net "P5E_CPU1_PE1_RX_DN<13>")
	)
	(segment
		(start 51.639216 -60.685426)
		(end 22.892512 -19.687794)
		(width 0.14732)
		(layer "In11.Cu")
		(net "P5E_CPU1_PE1_RX_DN<13>")
	)
	(segment
		(start 105.344214 -215.761062)
		(end 105.335324 -215.755982)
		(width 0.0889)
		(layer "In11.Cu")
		(net "P5E_CPU1_PE1_RX_DN<13>")
	)
	(segment
		(start 23.185628 -12.732512)
		(end 23.185628 -7.019036)
		(width 0.14732)
		(layer "In11.Cu")
		(net "P5E_CPU1_PE1_RX_DN<13>")
	)
	(segment
		(start 107.208574 -221.632018)
		(end 107.22991 -221.619826)
		(width 0.0889)
		(layer "In11.Cu")
		(net "P5E_CPU1_PE1_RX_DN<13>")
	)
	(segment
		(start 105.814114 -217.554302)
		(end 105.814368 -217.554048)
		(width 0.0889)
		(layer "In11.Cu")
		(net "P5E_CPU1_PE1_RX_DN<13>")
	)
	(segment
		(start 106.29011 -219.020136)
		(end 106.284014 -219.01658)
		(width 0.0889)
		(layer "In11.Cu")
		(net "P5E_CPU1_PE1_RX_DN<13>")
	)
	(segment
		(start 106.471212 -221.94774)
		(end 106.627676 -221.676722)
		(width 0.0889)
		(layer "In11.Cu")
		(net "P5E_CPU1_PE1_RX_DN<13>")
	)
	(segment
		(start 105.157016 -213.105492)
		(end 105.19918 -213.063328)
		(width 0.0889)
		(layer "In11.Cu")
		(net "P5E_CPU1_PE1_RX_DN<13>")
	)
	(segment
		(start 23.53056 -17.770348)
		(end 23.53056 -16.964152)
		(width 0.14732)
		(layer "In11.Cu")
		(net "P5E_CPU1_PE1_RX_DN<13>")
	)
	(segment
		(start 105.814368 -216.574878)
		(end 105.805478 -216.569798)
		(width 0.0889)
		(layer "In11.Cu")
		(net "P5E_CPU1_PE1_RX_DN<13>")
	)
	(segment
		(start 105.626408 -214.644732)
		(end 105.626408 -214.424768)
		(width 0.0889)
		(layer "In11.Cu")
		(net "P5E_CPU1_PE1_RX_DN<13>")
	)
	(segment
		(start 22.74062 -18.94459)
		(end 22.829266 -18.730722)
		(width 0.14732)
		(layer "In11.Cu")
		(net "P5E_CPU1_PE1_RX_DN<13>")
	)
	(segment
		(start 23.185628 -7.019036)
		(end 23.480268 -6.724396)
		(width 0.14732)
		(layer "In11.Cu")
		(net "P5E_CPU1_PE1_RX_DN<13>")
	)
	(segment
		(start 101.507798 -181.07406)
		(end 51.639216 -60.685426)
		(width 0.14732)
		(layer "In11.Cu")
		(net "P5E_CPU1_PE1_RX_DN<13>")
	)
	(segment
		(start 105.820464 -216.578434)
		(end 105.814368 -216.574878)
		(width 0.0889)
		(layer "In11.Cu")
		(net "P5E_CPU1_PE1_RX_DN<13>")
	)
	(segment
		(start 105.19918 -208.943702)
		(end 101.56825 -181.299358)
		(width 0.14732)
		(layer "In11.Cu")
		(net "P5E_CPU1_PE1_RX_DN<13>")
	)
	(segment
		(start 105.35031 -215.764618)
		(end 105.344214 -215.761062)
		(width 0.0889)
		(layer "In11.Cu")
		(net "P5E_CPU1_PE1_RX_DN<13>")
	)
	(segment
		(start 106.284014 -219.01658)
		(end 106.275124 -219.0115)
		(width 0.0889)
		(layer "In11.Cu")
		(net "P5E_CPU1_PE1_RX_DN<13>")
	)
	(segment
		(start 106.754168 -219.830396)
		(end 106.745278 -219.825316)
		(width 0.0889)
		(layer "In11.Cu")
		(net "P5E_CPU1_PE1_RX_DN<13>")
	)
	(segment
		(start 22.892512 -19.687794)
		(end 22.74062 -19.321018)
		(width 0.14732)
		(layer "In11.Cu")
		(net "P5E_CPU1_PE1_RX_DN<13>")
	)
	(segment
		(start 101.56825 -181.299358)
		(end 101.507798 -181.07406)
		(width 0.14732)
		(layer "In11.Cu")
		(net "P5E_CPU1_PE1_RX_DN<13>")
	)
	(segment
		(start 105.335324 -215.117426)
		(end 105.343198 -215.112854)
		(width 0.0889)
		(layer "In11.Cu")
		(net "P5E_CPU1_PE1_RX_DN<13>")
	)
	(segment
		(start 105.341166 -214.093298)
		(end 105.341166 -214.093552)
		(width 0.0889)
		(layer "In11.Cu")
		(net "P5E_CPU1_PE1_RX_DN<13>")
	)
	(segment
		(start 106.627676 -221.676722)
		(end 106.71683 -221.652846)
		(width 0.0889)
		(layer "In11.Cu")
		(net "P5E_CPU1_PE1_RX_DN<13>")
	)
	(segment
		(start 107.506516 -221.133924)
		(end 107.506516 -221.1197)
		(width 0.0889)
		(layer "In11.Cu")
		(net "P5E_CPU1_PE1_RX_DN<13>")
	)
	(segment
		(start 107.036616 -220.32849)
		(end 107.036616 -220.309948)
		(width 0.0889)
		(layer "In11.Cu")
		(net "P5E_CPU1_PE1_RX_DN<13>")
	)
	(segment
		(start 105.19918 -213.04123)
		(end 105.19918 -208.943702)
		(width 0.14732)
		(layer "In11.Cu")
		(net "P5E_CPU1_PE1_RX_DN<13>")
	)
	(segment
		(start 22.829266 -18.730722)
		(end 23.347172 -18.212816)
		(width 0.14732)
		(layer "In11.Cu")
		(net "P5E_CPU1_PE1_RX_DN<13>")
	)
	(segment
		(start 105.814368 -218.202764)
		(end 105.814114 -218.20251)
		(width 0.0889)
		(layer "In11.Cu")
		(net "P5E_CPU1_PE1_RX_DN<13>")
	)
	(segment
		(start 106.096562 -218.692222)
		(end 106.096562 -218.676728)
		(width 0.0889)
		(layer "In11.Cu")
		(net "P5E_CPU1_PE1_RX_DN<13>")
	)
	(segment
		(start 107.209082 -221.632018)
		(end 107.208574 -221.632018)
		(width 0.0889)
		(layer "In11.Cu")
		(net "P5E_CPU1_PE1_RX_DN<13>")
	)
	(arc
		(start 105.626408 -214.424768)
		(mid 105.515129 -214.232062)
		(end 105.341166 -214.093298)
		(width 0.0889)
		(layer "In11.Cu")
		(net "P5E_CPU1_PE1_RX_DN<13>")
	)
	(arc
		(start 107.506516 -221.1197)
		(mid 107.427297 -220.845015)
		(end 107.223814 -220.644212)
		(width 0.0889)
		(layer "In11.Cu")
		(net "P5E_CPU1_PE1_RX_DN<13>")
	)
	(arc
		(start 106.736896 -221.660974)
		(mid 106.976171 -221.698282)
		(end 107.209082 -221.632018)
		(width 0.0889)
		(layer "In11.Cu")
		(net "P5E_CPU1_PE1_RX_DN<13>")
	)
	(arc
		(start 105.335324 -215.755982)
		(mid 105.20441 -215.619622)
		(end 105.156762 -215.436704)
		(width 0.0889)
		(layer "In11.Cu")
		(net "P5E_CPU1_PE1_RX_DN<13>")
	)
	(arc
		(start 107.223814 -220.644212)
		(mid 107.088881 -220.510858)
		(end 107.036616 -220.32849)
		(width 0.0889)
		(layer "In11.Cu")
		(net "P5E_CPU1_PE1_RX_DN<13>")
	)
	(arc
		(start 106.71683 -221.652846)
		(mid 106.726824 -221.657005)
		(end 106.736896 -221.660974)
		(width 0.0889)
		(layer "In11.Cu")
		(net "P5E_CPU1_PE1_RX_DN<13>")
	)
	(arc
		(start 106.096816 -217.064336)
		(mid 106.0229 -216.784834)
		(end 105.820464 -216.578434)
		(width 0.0889)
		(layer "In11.Cu")
		(net "P5E_CPU1_PE1_RX_DN<13>")
	)
	(arc
		(start 105.341166 -214.093552)
		(mid 105.231996 -214.009499)
		(end 105.157016 -213.893908)
		(width 0.0889)
		(layer "In11.Cu")
		(net "P5E_CPU1_PE1_RX_DN<13>")
	)
	(arc
		(start 105.814114 -218.20251)
		(mid 105.679639 -218.06993)
		(end 105.626916 -217.888566)
		(width 0.0889)
		(layer "In11.Cu")
		(net "P5E_CPU1_PE1_RX_DN<13>")
	)
	(arc
		(start 107.22991 -221.619826)
		(mid 107.432497 -221.413475)
		(end 107.506516 -221.133924)
		(width 0.0889)
		(layer "In11.Cu")
		(net "P5E_CPU1_PE1_RX_DN<13>")
	)
	(arc
		(start 105.62717 -217.863674)
		(mid 105.680797 -217.684907)
		(end 105.814114 -217.554302)
		(width 0.0889)
		(layer "In11.Cu")
		(net "P5E_CPU1_PE1_RX_DN<13>")
	)
	(arc
		(start 105.626916 -216.25052)
		(mid 105.552925 -215.970954)
		(end 105.35031 -215.764618)
		(width 0.0889)
		(layer "In11.Cu")
		(net "P5E_CPU1_PE1_RX_DN<13>")
	)
	(arc
		(start 106.745278 -219.825316)
		(mid 106.614364 -219.688956)
		(end 106.566716 -219.506038)
		(width 0.0889)
		(layer "In11.Cu")
		(net "P5E_CPU1_PE1_RX_DN<13>")
	)
	(arc
		(start 105.805478 -216.569798)
		(mid 105.674564 -216.433438)
		(end 105.626916 -216.25052)
		(width 0.0889)
		(layer "In11.Cu")
		(net "P5E_CPU1_PE1_RX_DN<13>")
	)
	(arc
		(start 107.036616 -220.309948)
		(mid 106.958505 -220.032999)
		(end 106.754168 -219.830396)
		(width 0.0889)
		(layer "In11.Cu")
		(net "P5E_CPU1_PE1_RX_DN<13>")
	)
	(arc
		(start 105.344214 -215.112346)
		(mid 105.545496 -214.914859)
		(end 105.626408 -214.644732)
		(width 0.0889)
		(layer "In11.Cu")
		(net "P5E_CPU1_PE1_RX_DN<13>")
	)
	(arc
		(start 105.626916 -217.888566)
		(mid 105.626836 -217.876118)
		(end 105.62717 -217.863674)
		(width 0.0889)
		(layer "In11.Cu")
		(net "P5E_CPU1_PE1_RX_DN<13>")
	)
	(arc
		(start 106.275124 -219.0115)
		(mid 106.14421 -218.87514)
		(end 106.096562 -218.692222)
		(width 0.0889)
		(layer "In11.Cu")
		(net "P5E_CPU1_PE1_RX_DN<13>")
	)
	(arc
		(start 105.157016 -215.421972)
		(mid 105.20807 -215.247392)
		(end 105.335324 -215.117426)
		(width 0.0889)
		(layer "In11.Cu")
		(net "P5E_CPU1_PE1_RX_DN<13>")
	)
	(arc
		(start 106.096562 -218.676728)
		(mid 106.017192 -218.402994)
		(end 105.814368 -218.202764)
		(width 0.0889)
		(layer "In11.Cu")
		(net "P5E_CPU1_PE1_RX_DN<13>")
	)
	(arc
		(start 105.156762 -215.436704)
		(mid 105.156814 -215.429337)
		(end 105.157016 -215.421972)
		(width 0.0889)
		(layer "In11.Cu")
		(net "P5E_CPU1_PE1_RX_DN<13>")
	)
	(arc
		(start 105.814368 -217.554048)
		(mid 106.017673 -217.353182)
		(end 106.096816 -217.07856)
		(width 0.0889)
		(layer "In11.Cu")
		(net "P5E_CPU1_PE1_RX_DN<13>")
	)
	(arc
		(start 106.566716 -219.506038)
		(mid 106.492725 -219.226472)
		(end 106.29011 -219.020136)
		(width 0.0889)
		(layer "In11.Cu")
		(net "P5E_CPU1_PE1_RX_DN<13>")
	)
	(segment
		(start 25.147016 -8.320024)
		(end 25.147016 -7.775702)
		(width 0.13208)
		(layer "F.Cu")
		(net "P5E_CPU1_PE1_RX_DN<12>")
	)
	(segment
		(start 24.981662 -7.610348)
		(end 24.981662 -5.265928)
		(width 0.13208)
		(layer "F.Cu")
		(net "P5E_CPU1_PE1_RX_DN<12>")
	)
	(segment
		(start 25.147016 -7.775702)
		(end 24.981662 -7.610348)
		(width 0.13208)
		(layer "F.Cu")
		(net "P5E_CPU1_PE1_RX_DN<12>")
	)
	(segment
		(start 24.981662 -5.265928)
		(end 25.284938 -4.962652)
		(width 0.13208)
		(layer "F.Cu")
		(net "P5E_CPU1_PE1_RX_DN<12>")
	)
	(segment
		(start 107.880912 -221.134178)
		(end 107.881166 -221.133924)
		(width 0.13208)
		(layer "F.Cu")
		(net "P5E_CPU1_PE1_RX_DN<12>")
	)
	(segment
		(start 107.880912 -221.669864)
		(end 107.880912 -221.134178)
		(width 0.13208)
		(layer "F.Cu")
		(net "P5E_CPU1_PE1_RX_DN<12>")
	)
	(segment
		(start 107.700064 -219.833952)
		(end 107.693968 -219.830396)
		(width 0.0889)
		(layer "In11.Cu")
		(net "P5E_CPU1_PE1_RX_DN<12>")
	)
	(segment
		(start 107.724702 -220.862906)
		(end 107.748832 -220.773752)
		(width 0.0889)
		(layer "In11.Cu")
		(net "P5E_CPU1_PE1_RX_DN<12>")
	)
	(segment
		(start 106.127042 -213.921086)
		(end 106.101134 -213.855046)
		(width 0.0889)
		(layer "In11.Cu")
		(net "P5E_CPU1_PE1_RX_DN<12>")
	)
	(segment
		(start 106.096562 -213.830662)
		(end 106.096562 -213.105492)
		(width 0.0889)
		(layer "In11.Cu")
		(net "P5E_CPU1_PE1_RX_DN<12>")
	)
	(segment
		(start 24.990552 -12.18311)
		(end 24.990298 -12.173458)
		(width 0.14732)
		(layer "In11.Cu")
		(net "P5E_CPU1_PE1_RX_DN<12>")
	)
	(segment
		(start 107.036362 -218.692222)
		(end 107.036362 -218.676728)
		(width 0.0889)
		(layer "In11.Cu")
		(net "P5E_CPU1_PE1_RX_DN<12>")
	)
	(segment
		(start 106.566208 -214.470996)
		(end 106.565954 -214.470996)
		(width 0.0889)
		(layer "In11.Cu")
		(net "P5E_CPU1_PE1_RX_DN<12>")
	)
	(segment
		(start 106.284014 -215.761062)
		(end 106.275124 -215.755982)
		(width 0.0889)
		(layer "In11.Cu")
		(net "P5E_CPU1_PE1_RX_DN<12>")
	)
	(segment
		(start 107.693968 -219.830396)
		(end 107.685078 -219.825316)
		(width 0.0889)
		(layer "In11.Cu")
		(net "P5E_CPU1_PE1_RX_DN<12>")
	)
	(segment
		(start 107.881166 -221.133924)
		(end 107.724702 -220.862906)
		(width 0.0889)
		(layer "In11.Cu")
		(net "P5E_CPU1_PE1_RX_DN<12>")
	)
	(segment
		(start 52.489354 -60.270898)
		(end 25.9334 -18.337022)
		(width 0.14732)
		(layer "In11.Cu")
		(net "P5E_CPU1_PE1_RX_DN<12>")
	)
	(segment
		(start 106.138726 -213.04123)
		(end 106.138726 -208.88198)
		(width 0.14732)
		(layer "In11.Cu")
		(net "P5E_CPU1_PE1_RX_DN<12>")
	)
	(segment
		(start 106.138726 -208.88198)
		(end 102.500176 -181.178454)
		(width 0.14732)
		(layer "In11.Cu")
		(net "P5E_CPU1_PE1_RX_DN<12>")
	)
	(segment
		(start 106.754168 -218.202764)
		(end 106.753914 -218.20251)
		(width 0.0889)
		(layer "In11.Cu")
		(net "P5E_CPU1_PE1_RX_DN<12>")
	)
	(segment
		(start 106.29011 -215.764618)
		(end 106.284014 -215.761062)
		(width 0.0889)
		(layer "In11.Cu")
		(net "P5E_CPU1_PE1_RX_DN<12>")
	)
	(segment
		(start 106.096562 -213.105492)
		(end 106.138726 -213.063328)
		(width 0.0889)
		(layer "In11.Cu")
		(net "P5E_CPU1_PE1_RX_DN<12>")
	)
	(segment
		(start 106.282998 -215.112854)
		(end 106.284014 -215.112346)
		(width 0.0889)
		(layer "In11.Cu")
		(net "P5E_CPU1_PE1_RX_DN<12>")
	)
	(segment
		(start 106.754168 -216.574878)
		(end 106.745278 -216.569798)
		(width 0.0889)
		(layer "In11.Cu")
		(net "P5E_CPU1_PE1_RX_DN<12>")
	)
	(segment
		(start 25.9334 -18.337022)
		(end 25.681686 -18.0848)
		(width 0.14732)
		(layer "In11.Cu")
		(net "P5E_CPU1_PE1_RX_DN<12>")
	)
	(segment
		(start 107.22991 -219.020136)
		(end 107.223814 -219.01658)
		(width 0.0889)
		(layer "In11.Cu")
		(net "P5E_CPU1_PE1_RX_DN<12>")
	)
	(segment
		(start 107.223814 -219.01658)
		(end 107.214924 -219.0115)
		(width 0.0889)
		(layer "In11.Cu")
		(net "P5E_CPU1_PE1_RX_DN<12>")
	)
	(segment
		(start 102.38359 -180.721254)
		(end 52.489354 -60.270898)
		(width 0.14732)
		(layer "In11.Cu")
		(net "P5E_CPU1_PE1_RX_DN<12>")
	)
	(segment
		(start 106.566208 -214.644732)
		(end 106.566208 -214.470996)
		(width 0.0889)
		(layer "In11.Cu")
		(net "P5E_CPU1_PE1_RX_DN<12>")
	)
	(segment
		(start 24.990298 -12.173458)
		(end 24.990298 -5.257292)
		(width 0.14732)
		(layer "In11.Cu")
		(net "P5E_CPU1_PE1_RX_DN<12>")
	)
	(segment
		(start 25.681686 -18.0848)
		(end 25.36444 -17.531588)
		(width 0.14732)
		(layer "In11.Cu")
		(net "P5E_CPU1_PE1_RX_DN<12>")
	)
	(segment
		(start 102.500176 -181.178454)
		(end 102.38359 -180.721254)
		(width 0.14732)
		(layer "In11.Cu")
		(net "P5E_CPU1_PE1_RX_DN<12>")
	)
	(segment
		(start 25.36444 -17.531588)
		(end 24.990552 -12.18311)
		(width 0.14732)
		(layer "In11.Cu")
		(net "P5E_CPU1_PE1_RX_DN<12>")
	)
	(segment
		(start 106.138726 -213.063328)
		(end 106.138726 -213.04123)
		(width 0.0889)
		(layer "In11.Cu")
		(net "P5E_CPU1_PE1_RX_DN<12>")
	)
	(segment
		(start 106.275124 -215.117426)
		(end 106.282998 -215.112854)
		(width 0.0889)
		(layer "In11.Cu")
		(net "P5E_CPU1_PE1_RX_DN<12>")
	)
	(segment
		(start 107.976416 -220.334078)
		(end 107.976416 -220.319854)
		(width 0.0889)
		(layer "In11.Cu")
		(net "P5E_CPU1_PE1_RX_DN<12>")
	)
	(segment
		(start 24.990298 -5.257292)
		(end 25.284938 -4.962652)
		(width 0.14732)
		(layer "In11.Cu")
		(net "P5E_CPU1_PE1_RX_DN<12>")
	)
	(segment
		(start 106.754168 -217.554302)
		(end 106.754168 -217.554048)
		(width 0.0889)
		(layer "In11.Cu")
		(net "P5E_CPU1_PE1_RX_DN<12>")
	)
	(arc
		(start 106.280966 -214.093298)
		(mid 106.188547 -214.021006)
		(end 106.127042 -213.921086)
		(width 0.0889)
		(layer "In11.Cu")
		(net "P5E_CPU1_PE1_RX_DN<12>")
	)
	(arc
		(start 107.506516 -219.506038)
		(mid 107.432525 -219.226472)
		(end 107.22991 -219.020136)
		(width 0.0889)
		(layer "In11.Cu")
		(net "P5E_CPU1_PE1_RX_DN<12>")
	)
	(arc
		(start 106.754168 -217.554048)
		(mid 107.0367 -217.064527)
		(end 106.754168 -216.574878)
		(width 0.0889)
		(layer "In11.Cu")
		(net "P5E_CPU1_PE1_RX_DN<12>")
	)
	(arc
		(start 107.036362 -218.676728)
		(mid 106.956992 -218.402994)
		(end 106.754168 -218.202764)
		(width 0.0889)
		(layer "In11.Cu")
		(net "P5E_CPU1_PE1_RX_DN<12>")
	)
	(arc
		(start 106.284014 -215.112346)
		(mid 106.485296 -214.914859)
		(end 106.566208 -214.644732)
		(width 0.0889)
		(layer "In11.Cu")
		(net "P5E_CPU1_PE1_RX_DN<12>")
	)
	(arc
		(start 106.566716 -216.25052)
		(mid 106.492725 -215.970954)
		(end 106.29011 -215.764618)
		(width 0.0889)
		(layer "In11.Cu")
		(net "P5E_CPU1_PE1_RX_DN<12>")
	)
	(arc
		(start 106.565954 -214.470996)
		(mid 106.55962 -214.416934)
		(end 106.54157 -214.365586)
		(width 0.0889)
		(layer "In11.Cu")
		(net "P5E_CPU1_PE1_RX_DN<12>")
	)
	(arc
		(start 106.275124 -215.755982)
		(mid 106.14421 -215.619622)
		(end 106.096562 -215.436704)
		(width 0.0889)
		(layer "In11.Cu")
		(net "P5E_CPU1_PE1_RX_DN<12>")
	)
	(arc
		(start 106.566716 -217.878406)
		(mid 106.616956 -217.691205)
		(end 106.754168 -217.554302)
		(width 0.0889)
		(layer "In11.Cu")
		(net "P5E_CPU1_PE1_RX_DN<12>")
	)
	(arc
		(start 107.748832 -220.773752)
		(mid 107.757275 -220.767354)
		(end 107.765596 -220.760798)
		(width 0.0889)
		(layer "In11.Cu")
		(net "P5E_CPU1_PE1_RX_DN<12>")
	)
	(arc
		(start 106.753914 -218.20251)
		(mid 106.616869 -218.06555)
		(end 106.566716 -217.878406)
		(width 0.0889)
		(layer "In11.Cu")
		(net "P5E_CPU1_PE1_RX_DN<12>")
	)
	(arc
		(start 106.096816 -215.421972)
		(mid 106.14787 -215.247392)
		(end 106.275124 -215.117426)
		(width 0.0889)
		(layer "In11.Cu")
		(net "P5E_CPU1_PE1_RX_DN<12>")
	)
	(arc
		(start 107.765596 -220.760798)
		(mid 107.918103 -220.5707)
		(end 107.976416 -220.334078)
		(width 0.0889)
		(layer "In11.Cu")
		(net "P5E_CPU1_PE1_RX_DN<12>")
	)
	(arc
		(start 106.745278 -216.569798)
		(mid 106.614364 -216.433438)
		(end 106.566716 -216.25052)
		(width 0.0889)
		(layer "In11.Cu")
		(net "P5E_CPU1_PE1_RX_DN<12>")
	)
	(arc
		(start 106.101134 -213.855046)
		(mid 106.097709 -213.843069)
		(end 106.096562 -213.830662)
		(width 0.0889)
		(layer "In11.Cu")
		(net "P5E_CPU1_PE1_RX_DN<12>")
	)
	(arc
		(start 106.096562 -215.436704)
		(mid 106.096614 -215.429337)
		(end 106.096816 -215.421972)
		(width 0.0889)
		(layer "In11.Cu")
		(net "P5E_CPU1_PE1_RX_DN<12>")
	)
	(arc
		(start 107.976416 -220.319854)
		(mid 107.9025 -220.040352)
		(end 107.700064 -219.833952)
		(width 0.0889)
		(layer "In11.Cu")
		(net "P5E_CPU1_PE1_RX_DN<12>")
	)
	(arc
		(start 107.214924 -219.0115)
		(mid 107.08401 -218.87514)
		(end 107.036362 -218.692222)
		(width 0.0889)
		(layer "In11.Cu")
		(net "P5E_CPU1_PE1_RX_DN<12>")
	)
	(arc
		(start 107.685078 -219.825316)
		(mid 107.554164 -219.688956)
		(end 107.506516 -219.506038)
		(width 0.0889)
		(layer "In11.Cu")
		(net "P5E_CPU1_PE1_RX_DN<12>")
	)
	(arc
		(start 106.54157 -214.365586)
		(mid 106.433243 -214.208414)
		(end 106.280966 -214.093298)
		(width 0.0889)
		(layer "In11.Cu")
		(net "P5E_CPU1_PE1_RX_DN<12>")
	)
	(segment
		(start 26.94686 -7.779004)
		(end 26.77795 -7.610094)
		(width 0.13208)
		(layer "F.Cu")
		(net "P5E_CPU1_PE1_RX_DN<11>")
	)
	(segment
		(start 26.77795 -7.610094)
		(end 26.77795 -7.026656)
		(width 0.13208)
		(layer "F.Cu")
		(net "P5E_CPU1_PE1_RX_DN<11>")
	)
	(segment
		(start 108.350812 -222.483426)
		(end 108.350812 -221.94774)
		(width 0.13208)
		(layer "F.Cu")
		(net "P5E_CPU1_PE1_RX_DN<11>")
	)
	(segment
		(start 108.351066 -222.48368)
		(end 108.350812 -222.483426)
		(width 0.13208)
		(layer "F.Cu")
		(net "P5E_CPU1_PE1_RX_DN<11>")
	)
	(segment
		(start 26.94686 -8.320024)
		(end 26.94686 -7.779004)
		(width 0.13208)
		(layer "F.Cu")
		(net "P5E_CPU1_PE1_RX_DN<11>")
	)
	(segment
		(start 26.77795 -7.026656)
		(end 27.08021 -6.724396)
		(width 0.13208)
		(layer "F.Cu")
		(net "P5E_CPU1_PE1_RX_DN<11>")
	)
	(segment
		(start 107.07878 -208.820258)
		(end 103.433372 -181.064154)
		(width 0.14732)
		(layer "In11.Cu")
		(net "P5E_CPU1_PE1_RX_DN<11>")
	)
	(segment
		(start 29.02712 -17.276064)
		(end 26.78557 -12.300966)
		(width 0.14732)
		(layer "In11.Cu")
		(net "P5E_CPU1_PE1_RX_DN<11>")
	)
	(segment
		(start 107.693714 -217.554302)
		(end 107.693968 -217.554048)
		(width 0.0889)
		(layer "In11.Cu")
		(net "P5E_CPU1_PE1_RX_DN<11>")
	)
	(segment
		(start 108.916216 -220.32849)
		(end 108.916216 -220.309948)
		(width 0.0889)
		(layer "In11.Cu")
		(net "P5E_CPU1_PE1_RX_DN<11>")
	)
	(segment
		(start 26.78557 -12.300966)
		(end 26.78557 -7.019036)
		(width 0.14732)
		(layer "In11.Cu")
		(net "P5E_CPU1_PE1_RX_DN<11>")
	)
	(segment
		(start 107.036616 -213.105492)
		(end 107.07878 -213.063328)
		(width 0.0889)
		(layer "In11.Cu")
		(net "P5E_CPU1_PE1_RX_DN<11>")
	)
	(segment
		(start 109.386116 -221.133924)
		(end 109.386116 -221.1197)
		(width 0.0889)
		(layer "In11.Cu")
		(net "P5E_CPU1_PE1_RX_DN<11>")
	)
	(segment
		(start 103.25608 -180.360828)
		(end 53.347112 -59.873134)
		(width 0.14732)
		(layer "In11.Cu")
		(net "P5E_CPU1_PE1_RX_DN<11>")
	)
	(segment
		(start 103.433372 -181.064154)
		(end 103.25608 -180.360828)
		(width 0.14732)
		(layer "In11.Cu")
		(net "P5E_CPU1_PE1_RX_DN<11>")
	)
	(segment
		(start 108.633768 -219.830396)
		(end 108.624878 -219.825316)
		(width 0.0889)
		(layer "In11.Cu")
		(net "P5E_CPU1_PE1_RX_DN<11>")
	)
	(segment
		(start 28.31592 -19.355054)
		(end 28.31592 -19.029934)
		(width 0.14732)
		(layer "In11.Cu")
		(net "P5E_CPU1_PE1_RX_DN<11>")
	)
	(segment
		(start 29.02712 -17.723104)
		(end 29.02712 -17.276064)
		(width 0.14732)
		(layer "In11.Cu")
		(net "P5E_CPU1_PE1_RX_DN<11>")
	)
	(segment
		(start 108.350812 -221.94774)
		(end 108.507276 -221.676722)
		(width 0.0889)
		(layer "In11.Cu")
		(net "P5E_CPU1_PE1_RX_DN<11>")
	)
	(segment
		(start 28.31592 -19.029934)
		(end 28.48991 -18.609818)
		(width 0.14732)
		(layer "In11.Cu")
		(net "P5E_CPU1_PE1_RX_DN<11>")
	)
	(segment
		(start 107.22991 -215.764618)
		(end 107.223814 -215.761062)
		(width 0.0889)
		(layer "In11.Cu")
		(net "P5E_CPU1_PE1_RX_DN<11>")
	)
	(segment
		(start 107.07878 -213.063328)
		(end 107.07878 -213.04123)
		(width 0.0889)
		(layer "In11.Cu")
		(net "P5E_CPU1_PE1_RX_DN<11>")
	)
	(segment
		(start 107.693968 -216.574878)
		(end 107.685078 -216.569798)
		(width 0.0889)
		(layer "In11.Cu")
		(net "P5E_CPU1_PE1_RX_DN<11>")
	)
	(segment
		(start 28.526994 -19.865086)
		(end 28.31592 -19.355054)
		(width 0.14732)
		(layer "In11.Cu")
		(net "P5E_CPU1_PE1_RX_DN<11>")
	)
	(segment
		(start 107.222798 -215.112854)
		(end 107.223814 -215.112346)
		(width 0.0889)
		(layer "In11.Cu")
		(net "P5E_CPU1_PE1_RX_DN<11>")
	)
	(segment
		(start 107.036616 -213.893908)
		(end 107.036616 -213.105492)
		(width 0.0889)
		(layer "In11.Cu")
		(net "P5E_CPU1_PE1_RX_DN<11>")
	)
	(segment
		(start 107.693968 -218.202764)
		(end 107.693714 -218.20251)
		(width 0.0889)
		(layer "In11.Cu")
		(net "P5E_CPU1_PE1_RX_DN<11>")
	)
	(segment
		(start 107.976416 -217.07856)
		(end 107.976416 -217.064336)
		(width 0.0889)
		(layer "In11.Cu")
		(net "P5E_CPU1_PE1_RX_DN<11>")
	)
	(segment
		(start 28.779724 -18.31975)
		(end 29.02712 -17.723104)
		(width 0.14732)
		(layer "In11.Cu")
		(net "P5E_CPU1_PE1_RX_DN<11>")
	)
	(segment
		(start 107.700064 -216.578434)
		(end 107.693968 -216.574878)
		(width 0.0889)
		(layer "In11.Cu")
		(net "P5E_CPU1_PE1_RX_DN<11>")
	)
	(segment
		(start 109.088682 -221.632018)
		(end 109.088174 -221.632018)
		(width 0.0889)
		(layer "In11.Cu")
		(net "P5E_CPU1_PE1_RX_DN<11>")
	)
	(segment
		(start 109.088174 -221.632018)
		(end 109.10951 -221.619826)
		(width 0.0889)
		(layer "In11.Cu")
		(net "P5E_CPU1_PE1_RX_DN<11>")
	)
	(segment
		(start 108.507276 -221.676722)
		(end 108.59643 -221.652846)
		(width 0.0889)
		(layer "In11.Cu")
		(net "P5E_CPU1_PE1_RX_DN<11>")
	)
	(segment
		(start 28.48991 -18.609818)
		(end 28.779724 -18.31975)
		(width 0.14732)
		(layer "In11.Cu")
		(net "P5E_CPU1_PE1_RX_DN<11>")
	)
	(segment
		(start 53.347112 -59.873134)
		(end 28.526994 -19.865086)
		(width 0.14732)
		(layer "In11.Cu")
		(net "P5E_CPU1_PE1_RX_DN<11>")
	)
	(segment
		(start 26.78557 -7.019036)
		(end 27.08021 -6.724396)
		(width 0.14732)
		(layer "In11.Cu")
		(net "P5E_CPU1_PE1_RX_DN<11>")
	)
	(segment
		(start 107.214924 -215.117426)
		(end 107.222798 -215.112854)
		(width 0.0889)
		(layer "In11.Cu")
		(net "P5E_CPU1_PE1_RX_DN<11>")
	)
	(segment
		(start 107.07878 -213.04123)
		(end 107.07878 -208.820258)
		(width 0.14732)
		(layer "In11.Cu")
		(net "P5E_CPU1_PE1_RX_DN<11>")
	)
	(segment
		(start 108.16971 -219.020136)
		(end 108.163614 -219.01658)
		(width 0.0889)
		(layer "In11.Cu")
		(net "P5E_CPU1_PE1_RX_DN<11>")
	)
	(segment
		(start 107.976162 -218.692222)
		(end 107.976162 -218.676728)
		(width 0.0889)
		(layer "In11.Cu")
		(net "P5E_CPU1_PE1_RX_DN<11>")
	)
	(segment
		(start 108.163614 -219.01658)
		(end 108.154724 -219.0115)
		(width 0.0889)
		(layer "In11.Cu")
		(net "P5E_CPU1_PE1_RX_DN<11>")
	)
	(segment
		(start 107.223814 -215.761062)
		(end 107.214924 -215.755982)
		(width 0.0889)
		(layer "In11.Cu")
		(net "P5E_CPU1_PE1_RX_DN<11>")
	)
	(segment
		(start 107.506008 -214.644732)
		(end 107.506008 -214.424768)
		(width 0.0889)
		(layer "In11.Cu")
		(net "P5E_CPU1_PE1_RX_DN<11>")
	)
	(arc
		(start 108.446316 -219.506038)
		(mid 108.372325 -219.226472)
		(end 108.16971 -219.020136)
		(width 0.0889)
		(layer "In11.Cu")
		(net "P5E_CPU1_PE1_RX_DN<11>")
	)
	(arc
		(start 107.223814 -215.112346)
		(mid 107.425096 -214.914859)
		(end 107.506008 -214.644732)
		(width 0.0889)
		(layer "In11.Cu")
		(net "P5E_CPU1_PE1_RX_DN<11>")
	)
	(arc
		(start 107.506516 -216.25052)
		(mid 107.432525 -215.970954)
		(end 107.22991 -215.764618)
		(width 0.0889)
		(layer "In11.Cu")
		(net "P5E_CPU1_PE1_RX_DN<11>")
	)
	(arc
		(start 108.59643 -221.652846)
		(mid 108.606424 -221.657005)
		(end 108.616496 -221.660974)
		(width 0.0889)
		(layer "In11.Cu")
		(net "P5E_CPU1_PE1_RX_DN<11>")
	)
	(arc
		(start 107.50677 -217.863674)
		(mid 107.560397 -217.684907)
		(end 107.693714 -217.554302)
		(width 0.0889)
		(layer "In11.Cu")
		(net "P5E_CPU1_PE1_RX_DN<11>")
	)
	(arc
		(start 108.616496 -221.660974)
		(mid 108.855771 -221.698282)
		(end 109.088682 -221.632018)
		(width 0.0889)
		(layer "In11.Cu")
		(net "P5E_CPU1_PE1_RX_DN<11>")
	)
	(arc
		(start 107.214924 -215.755982)
		(mid 107.08401 -215.619622)
		(end 107.036362 -215.436704)
		(width 0.0889)
		(layer "In11.Cu")
		(net "P5E_CPU1_PE1_RX_DN<11>")
	)
	(arc
		(start 108.916216 -220.309948)
		(mid 108.838105 -220.032999)
		(end 108.633768 -219.830396)
		(width 0.0889)
		(layer "In11.Cu")
		(net "P5E_CPU1_PE1_RX_DN<11>")
	)
	(arc
		(start 107.506516 -217.888566)
		(mid 107.506436 -217.876118)
		(end 107.50677 -217.863674)
		(width 0.0889)
		(layer "In11.Cu")
		(net "P5E_CPU1_PE1_RX_DN<11>")
	)
	(arc
		(start 107.506008 -214.424768)
		(mid 107.394729 -214.232062)
		(end 107.220766 -214.093298)
		(width 0.0889)
		(layer "In11.Cu")
		(net "P5E_CPU1_PE1_RX_DN<11>")
	)
	(arc
		(start 107.693968 -217.554048)
		(mid 107.897273 -217.353182)
		(end 107.976416 -217.07856)
		(width 0.0889)
		(layer "In11.Cu")
		(net "P5E_CPU1_PE1_RX_DN<11>")
	)
	(arc
		(start 107.036616 -215.421972)
		(mid 107.08767 -215.247392)
		(end 107.214924 -215.117426)
		(width 0.0889)
		(layer "In11.Cu")
		(net "P5E_CPU1_PE1_RX_DN<11>")
	)
	(arc
		(start 108.154724 -219.0115)
		(mid 108.02381 -218.87514)
		(end 107.976162 -218.692222)
		(width 0.0889)
		(layer "In11.Cu")
		(net "P5E_CPU1_PE1_RX_DN<11>")
	)
	(arc
		(start 109.10951 -221.619826)
		(mid 109.312097 -221.413475)
		(end 109.386116 -221.133924)
		(width 0.0889)
		(layer "In11.Cu")
		(net "P5E_CPU1_PE1_RX_DN<11>")
	)
	(arc
		(start 107.036362 -215.436704)
		(mid 107.036414 -215.429337)
		(end 107.036616 -215.421972)
		(width 0.0889)
		(layer "In11.Cu")
		(net "P5E_CPU1_PE1_RX_DN<11>")
	)
	(arc
		(start 108.624878 -219.825316)
		(mid 108.493964 -219.688956)
		(end 108.446316 -219.506038)
		(width 0.0889)
		(layer "In11.Cu")
		(net "P5E_CPU1_PE1_RX_DN<11>")
	)
	(arc
		(start 107.693714 -218.20251)
		(mid 107.559239 -218.06993)
		(end 107.506516 -217.888566)
		(width 0.0889)
		(layer "In11.Cu")
		(net "P5E_CPU1_PE1_RX_DN<11>")
	)
	(arc
		(start 107.685078 -216.569798)
		(mid 107.554164 -216.433438)
		(end 107.506516 -216.25052)
		(width 0.0889)
		(layer "In11.Cu")
		(net "P5E_CPU1_PE1_RX_DN<11>")
	)
	(arc
		(start 107.976162 -218.676728)
		(mid 107.896792 -218.402994)
		(end 107.693968 -218.202764)
		(width 0.0889)
		(layer "In11.Cu")
		(net "P5E_CPU1_PE1_RX_DN<11>")
	)
	(arc
		(start 107.220766 -214.093298)
		(mid 107.111619 -214.00937)
		(end 107.036616 -213.893908)
		(width 0.0889)
		(layer "In11.Cu")
		(net "P5E_CPU1_PE1_RX_DN<11>")
	)
	(arc
		(start 107.976416 -217.064336)
		(mid 107.9025 -216.784834)
		(end 107.700064 -216.578434)
		(width 0.0889)
		(layer "In11.Cu")
		(net "P5E_CPU1_PE1_RX_DN<11>")
	)
	(arc
		(start 109.386116 -221.1197)
		(mid 109.306897 -220.845015)
		(end 109.103414 -220.644212)
		(width 0.0889)
		(layer "In11.Cu")
		(net "P5E_CPU1_PE1_RX_DN<11>")
	)
	(arc
		(start 109.103414 -220.644212)
		(mid 108.968481 -220.510858)
		(end 108.916216 -220.32849)
		(width 0.0889)
		(layer "In11.Cu")
		(net "P5E_CPU1_PE1_RX_DN<11>")
	)
	(segment
		(start 109.760512 -221.669864)
		(end 109.760512 -221.134178)
		(width 0.13208)
		(layer "F.Cu")
		(net "P5E_CPU1_PE1_RX_DN<10>")
	)
	(segment
		(start 28.746958 -8.320024)
		(end 28.746958 -7.775702)
		(width 0.13208)
		(layer "F.Cu")
		(net "P5E_CPU1_PE1_RX_DN<10>")
	)
	(segment
		(start 28.581604 -7.610348)
		(end 28.581604 -5.265928)
		(width 0.13208)
		(layer "F.Cu")
		(net "P5E_CPU1_PE1_RX_DN<10>")
	)
	(segment
		(start 28.581604 -5.265928)
		(end 28.88488 -4.962652)
		(width 0.13208)
		(layer "F.Cu")
		(net "P5E_CPU1_PE1_RX_DN<10>")
	)
	(segment
		(start 109.760512 -221.134178)
		(end 109.760766 -221.133924)
		(width 0.13208)
		(layer "F.Cu")
		(net "P5E_CPU1_PE1_RX_DN<10>")
	)
	(segment
		(start 28.746958 -7.775702)
		(end 28.581604 -7.610348)
		(width 0.13208)
		(layer "F.Cu")
		(net "P5E_CPU1_PE1_RX_DN<10>")
	)
	(segment
		(start 108.805726 -209.821018)
		(end 104.601264 -181.33949)
		(width 0.14732)
		(layer "In11.Cu")
		(net "P5E_CPU1_PE1_RX_DN<10>")
	)
	(segment
		(start 109.573568 -219.830396)
		(end 109.564678 -219.825316)
		(width 0.0889)
		(layer "In11.Cu")
		(net "P5E_CPU1_PE1_RX_DN<10>")
	)
	(segment
		(start 108.958634 -213.063328)
		(end 108.958634 -213.04123)
		(width 0.0889)
		(layer "In11.Cu")
		(net "P5E_CPU1_PE1_RX_DN<10>")
	)
	(segment
		(start 103.951278 -179.518564)
		(end 54.204616 -59.421522)
		(width 0.14732)
		(layer "In11.Cu")
		(net "P5E_CPU1_PE1_RX_DN<10>")
	)
	(segment
		(start 108.633768 -216.574878)
		(end 108.624878 -216.569798)
		(width 0.0889)
		(layer "In11.Cu")
		(net "P5E_CPU1_PE1_RX_DN<10>")
	)
	(segment
		(start 108.91647 -214.001604)
		(end 108.91647 -213.105492)
		(width 0.0889)
		(layer "In11.Cu")
		(net "P5E_CPU1_PE1_RX_DN<10>")
	)
	(segment
		(start 109.10951 -219.020136)
		(end 109.103414 -219.01658)
		(width 0.0889)
		(layer "In11.Cu")
		(net "P5E_CPU1_PE1_RX_DN<10>")
	)
	(segment
		(start 108.446062 -214.636858)
		(end 108.446062 -214.46236)
		(width 0.0889)
		(layer "In11.Cu")
		(net "P5E_CPU1_PE1_RX_DN<10>")
	)
	(segment
		(start 109.856016 -220.334078)
		(end 109.856016 -220.319854)
		(width 0.0889)
		(layer "In11.Cu")
		(net "P5E_CPU1_PE1_RX_DN<10>")
	)
	(segment
		(start 108.154724 -215.117426)
		(end 108.163614 -215.112346)
		(width 0.0889)
		(layer "In11.Cu")
		(net "P5E_CPU1_PE1_RX_DN<10>")
	)
	(segment
		(start 108.958634 -213.04123)
		(end 108.958634 -211.905596)
		(width 0.14732)
		(layer "In11.Cu")
		(net "P5E_CPU1_PE1_RX_DN<10>")
	)
	(segment
		(start 109.103414 -219.01658)
		(end 109.094524 -219.0115)
		(width 0.0889)
		(layer "In11.Cu")
		(net "P5E_CPU1_PE1_RX_DN<10>")
	)
	(segment
		(start 108.91647 -213.105492)
		(end 108.958634 -213.063328)
		(width 0.0889)
		(layer "In11.Cu")
		(net "P5E_CPU1_PE1_RX_DN<10>")
	)
	(segment
		(start 109.760766 -221.133924)
		(end 109.604302 -220.862906)
		(width 0.0889)
		(layer "In11.Cu")
		(net "P5E_CPU1_PE1_RX_DN<10>")
	)
	(segment
		(start 31.152338 -17.846548)
		(end 28.59024 -12.119356)
		(width 0.14732)
		(layer "In11.Cu")
		(net "P5E_CPU1_PE1_RX_DN<10>")
	)
	(segment
		(start 108.684822 -214.233252)
		(end 108.91647 -214.001604)
		(width 0.0889)
		(layer "In11.Cu")
		(net "P5E_CPU1_PE1_RX_DN<10>")
	)
	(segment
		(start 109.579664 -219.833952)
		(end 109.573568 -219.830396)
		(width 0.0889)
		(layer "In11.Cu")
		(net "P5E_CPU1_PE1_RX_DN<10>")
	)
	(segment
		(start 28.59024 -5.257292)
		(end 28.88488 -4.962652)
		(width 0.14732)
		(layer "In11.Cu")
		(net "P5E_CPU1_PE1_RX_DN<10>")
	)
	(segment
		(start 108.630466 -214.261954)
		(end 108.684822 -214.233252)
		(width 0.0889)
		(layer "In11.Cu")
		(net "P5E_CPU1_PE1_RX_DN<10>")
	)
	(segment
		(start 108.16971 -215.764618)
		(end 108.166408 -215.762586)
		(width 0.0889)
		(layer "In11.Cu")
		(net "P5E_CPU1_PE1_RX_DN<10>")
	)
	(segment
		(start 104.601264 -181.33949)
		(end 103.951278 -179.518564)
		(width 0.14732)
		(layer "In11.Cu")
		(net "P5E_CPU1_PE1_RX_DN<10>")
	)
	(segment
		(start 109.604302 -220.862906)
		(end 109.628432 -220.773752)
		(width 0.0889)
		(layer "In11.Cu")
		(net "P5E_CPU1_PE1_RX_DN<10>")
	)
	(segment
		(start 32.21101 -19.38401)
		(end 31.152338 -17.846548)
		(width 0.14732)
		(layer "In11.Cu")
		(net "P5E_CPU1_PE1_RX_DN<10>")
	)
	(segment
		(start 108.633768 -217.554302)
		(end 108.633768 -217.554048)
		(width 0.0889)
		(layer "In11.Cu")
		(net "P5E_CPU1_PE1_RX_DN<10>")
	)
	(segment
		(start 108.916216 -217.082878)
		(end 108.916216 -217.05443)
		(width 0.0889)
		(layer "In11.Cu")
		(net "P5E_CPU1_PE1_RX_DN<10>")
	)
	(segment
		(start 108.633768 -218.202764)
		(end 108.633514 -218.20251)
		(width 0.0889)
		(layer "In11.Cu")
		(net "P5E_CPU1_PE1_RX_DN<10>")
	)
	(segment
		(start 108.16209 -215.7603)
		(end 108.154724 -215.755982)
		(width 0.0889)
		(layer "In11.Cu")
		(net "P5E_CPU1_PE1_RX_DN<10>")
	)
	(segment
		(start 108.915962 -218.692222)
		(end 108.915962 -218.676728)
		(width 0.0889)
		(layer "In11.Cu")
		(net "P5E_CPU1_PE1_RX_DN<10>")
	)
	(segment
		(start 28.59024 -12.119356)
		(end 28.59024 -5.257292)
		(width 0.14732)
		(layer "In11.Cu")
		(net "P5E_CPU1_PE1_RX_DN<10>")
	)
	(segment
		(start 54.204616 -59.421522)
		(end 32.21101 -19.38401)
		(width 0.14732)
		(layer "In11.Cu")
		(net "P5E_CPU1_PE1_RX_DN<10>")
	)
	(segment
		(start 108.163614 -215.761062)
		(end 108.16209 -215.7603)
		(width 0.0889)
		(layer "In11.Cu")
		(net "P5E_CPU1_PE1_RX_DN<10>")
	)
	(segment
		(start 108.958634 -211.905596)
		(end 108.805726 -209.821018)
		(width 0.14732)
		(layer "In11.Cu")
		(net "P5E_CPU1_PE1_RX_DN<10>")
	)
	(segment
		(start 108.166408 -215.762586)
		(end 108.163614 -215.761062)
		(width 0.0889)
		(layer "In11.Cu")
		(net "P5E_CPU1_PE1_RX_DN<10>")
	)
	(arc
		(start 109.094524 -219.0115)
		(mid 108.96361 -218.87514)
		(end 108.915962 -218.692222)
		(width 0.0889)
		(layer "In11.Cu")
		(net "P5E_CPU1_PE1_RX_DN<10>")
	)
	(arc
		(start 107.976162 -215.436704)
		(mid 107.976214 -215.429337)
		(end 107.976416 -215.421972)
		(width 0.0889)
		(layer "In11.Cu")
		(net "P5E_CPU1_PE1_RX_DN<10>")
	)
	(arc
		(start 108.916216 -217.05443)
		(mid 108.838105 -216.777481)
		(end 108.633768 -216.574878)
		(width 0.0889)
		(layer "In11.Cu")
		(net "P5E_CPU1_PE1_RX_DN<10>")
	)
	(arc
		(start 108.163614 -215.112346)
		(mid 108.366924 -214.911469)
		(end 108.446062 -214.636858)
		(width 0.0889)
		(layer "In11.Cu")
		(net "P5E_CPU1_PE1_RX_DN<10>")
	)
	(arc
		(start 109.645196 -220.760798)
		(mid 109.797703 -220.5707)
		(end 109.856016 -220.334078)
		(width 0.0889)
		(layer "In11.Cu")
		(net "P5E_CPU1_PE1_RX_DN<10>")
	)
	(arc
		(start 109.628432 -220.773752)
		(mid 109.636875 -220.767354)
		(end 109.645196 -220.760798)
		(width 0.0889)
		(layer "In11.Cu")
		(net "P5E_CPU1_PE1_RX_DN<10>")
	)
	(arc
		(start 108.446316 -217.878406)
		(mid 108.496556 -217.691205)
		(end 108.633768 -217.554302)
		(width 0.0889)
		(layer "In11.Cu")
		(net "P5E_CPU1_PE1_RX_DN<10>")
	)
	(arc
		(start 108.624878 -216.569798)
		(mid 108.493964 -216.433438)
		(end 108.446316 -216.25052)
		(width 0.0889)
		(layer "In11.Cu")
		(net "P5E_CPU1_PE1_RX_DN<10>")
	)
	(arc
		(start 108.446062 -214.46236)
		(mid 108.52102 -214.346282)
		(end 108.630466 -214.261954)
		(width 0.0889)
		(layer "In11.Cu")
		(net "P5E_CPU1_PE1_RX_DN<10>")
	)
	(arc
		(start 108.915962 -218.676728)
		(mid 108.836592 -218.402994)
		(end 108.633768 -218.202764)
		(width 0.0889)
		(layer "In11.Cu")
		(net "P5E_CPU1_PE1_RX_DN<10>")
	)
	(arc
		(start 108.633514 -218.20251)
		(mid 108.496469 -218.06555)
		(end 108.446316 -217.878406)
		(width 0.0889)
		(layer "In11.Cu")
		(net "P5E_CPU1_PE1_RX_DN<10>")
	)
	(arc
		(start 107.976416 -215.421972)
		(mid 108.02747 -215.247392)
		(end 108.154724 -215.117426)
		(width 0.0889)
		(layer "In11.Cu")
		(net "P5E_CPU1_PE1_RX_DN<10>")
	)
	(arc
		(start 109.386116 -219.506038)
		(mid 109.312125 -219.226472)
		(end 109.10951 -219.020136)
		(width 0.0889)
		(layer "In11.Cu")
		(net "P5E_CPU1_PE1_RX_DN<10>")
	)
	(arc
		(start 108.446316 -216.25052)
		(mid 108.372325 -215.970954)
		(end 108.16971 -215.764618)
		(width 0.0889)
		(layer "In11.Cu")
		(net "P5E_CPU1_PE1_RX_DN<10>")
	)
	(arc
		(start 108.154724 -215.755982)
		(mid 108.02381 -215.619622)
		(end 107.976162 -215.436704)
		(width 0.0889)
		(layer "In11.Cu")
		(net "P5E_CPU1_PE1_RX_DN<10>")
	)
	(arc
		(start 109.564678 -219.825316)
		(mid 109.433764 -219.688956)
		(end 109.386116 -219.506038)
		(width 0.0889)
		(layer "In11.Cu")
		(net "P5E_CPU1_PE1_RX_DN<10>")
	)
	(arc
		(start 108.633768 -217.554048)
		(mid 108.836054 -217.355067)
		(end 108.916216 -217.082878)
		(width 0.0889)
		(layer "In11.Cu")
		(net "P5E_CPU1_PE1_RX_DN<10>")
	)
	(arc
		(start 109.856016 -220.319854)
		(mid 109.7821 -220.040352)
		(end 109.579664 -219.833952)
		(width 0.0889)
		(layer "In11.Cu")
		(net "P5E_CPU1_PE1_RX_DN<10>")
	)
	(segment
		(start 56.267096 -7.775702)
		(end 56.097678 -7.606284)
		(width 0.13208)
		(layer "F.Cu")
		(net "P5E_CPU1_PE1_RX_DN<0>")
	)
	(segment
		(start 119.158512 -221.669864)
		(end 119.158512 -221.134178)
		(width 0.13208)
		(layer "F.Cu")
		(net "P5E_CPU1_PE1_RX_DN<0>")
	)
	(segment
		(start 119.158512 -221.134178)
		(end 119.158766 -221.133924)
		(width 0.13208)
		(layer "F.Cu")
		(net "P5E_CPU1_PE1_RX_DN<0>")
	)
	(segment
		(start 56.097678 -5.269992)
		(end 56.405018 -4.962652)
		(width 0.13208)
		(layer "F.Cu")
		(net "P5E_CPU1_PE1_RX_DN<0>")
	)
	(segment
		(start 56.097678 -7.606284)
		(end 56.097678 -5.269992)
		(width 0.13208)
		(layer "F.Cu")
		(net "P5E_CPU1_PE1_RX_DN<0>")
	)
	(segment
		(start 56.267096 -8.320024)
		(end 56.267096 -7.775702)
		(width 0.13208)
		(layer "F.Cu")
		(net "P5E_CPU1_PE1_RX_DN<0>")
	)
	(segment
		(start 118.504208 -219.018104)
		(end 118.50751 -219.020136)
		(width 0.0889)
		(layer "In11.Cu")
		(net "P5E_CPU1_PE1_RX_DN<0>")
	)
	(segment
		(start 118.494556 -218.371674)
		(end 118.492524 -218.372944)
		(width 0.0889)
		(layer "In11.Cu")
		(net "P5E_CPU1_PE1_RX_DN<0>")
	)
	(segment
		(start 118.49989 -218.368626)
		(end 118.497858 -218.369896)
		(width 0.0889)
		(layer "In11.Cu")
		(net "P5E_CPU1_PE1_RX_DN<0>")
	)
	(segment
		(start 118.501414 -218.367864)
		(end 118.49989 -218.368626)
		(width 0.0889)
		(layer "In11.Cu")
		(net "P5E_CPU1_PE1_RX_DN<0>")
	)
	(segment
		(start 114.898678 -183.11622)
		(end 118.028466 -205.504034)
		(width 0.14732)
		(layer "In11.Cu")
		(net "P5E_CPU1_PE1_RX_DN<0>")
	)
	(segment
		(start 118.028466 -205.504034)
		(end 118.35638 -210.218274)
		(width 0.14732)
		(layer "In11.Cu")
		(net "P5E_CPU1_PE1_RX_DN<0>")
	)
	(segment
		(start 56.538622 -12.882372)
		(end 60.10148 -18.725388)
		(width 0.14732)
		(layer "In11.Cu")
		(net "P5E_CPU1_PE1_RX_DN<0>")
	)
	(segment
		(start 118.314216 -217.05443)
		(end 118.314216 -217.072972)
		(width 0.0889)
		(layer "In11.Cu")
		(net "P5E_CPU1_PE1_RX_DN<0>")
	)
	(segment
		(start 58.029348 -38.631368)
		(end 59.252358 -46.87697)
		(width 0.14732)
		(layer "In11.Cu")
		(net "P5E_CPU1_PE1_RX_DN<0>")
	)
	(segment
		(start 114.328702 -179.843938)
		(end 114.89817 -183.111394)
		(width 0.14732)
		(layer "In11.Cu")
		(net "P5E_CPU1_PE1_RX_DN<0>")
	)
	(segment
		(start 118.502176 -218.367356)
		(end 118.501414 -218.367864)
		(width 0.0889)
		(layer "In11.Cu")
		(net "P5E_CPU1_PE1_RX_DN<0>")
	)
	(segment
		(start 118.35638 -210.218274)
		(end 118.35638 -213.04123)
		(width 0.14732)
		(layer "In11.Cu")
		(net "P5E_CPU1_PE1_RX_DN<0>")
	)
	(segment
		(start 118.49989 -219.015818)
		(end 118.501414 -219.01658)
		(width 0.0889)
		(layer "In11.Cu")
		(net "P5E_CPU1_PE1_RX_DN<0>")
	)
	(segment
		(start 119.254016 -220.319854)
		(end 119.254016 -220.334078)
		(width 0.0889)
		(layer "In11.Cu")
		(net "P5E_CPU1_PE1_RX_DN<0>")
	)
	(segment
		(start 56.405018 -4.962652)
		(end 56.110378 -5.257292)
		(width 0.14732)
		(layer "In11.Cu")
		(net "P5E_CPU1_PE1_RX_DN<0>")
	)
	(segment
		(start 59.801506 -20.107402)
		(end 58.029348 -38.631368)
		(width 0.14732)
		(layer "In11.Cu")
		(net "P5E_CPU1_PE1_RX_DN<0>")
	)
	(segment
		(start 118.35638 -213.04123)
		(end 118.35638 -213.063328)
		(width 0.0889)
		(layer "In11.Cu")
		(net "P5E_CPU1_PE1_RX_DN<0>")
	)
	(segment
		(start 118.50751 -218.364308)
		(end 118.502176 -218.367356)
		(width 0.0889)
		(layer "In11.Cu")
		(net "P5E_CPU1_PE1_RX_DN<0>")
	)
	(segment
		(start 118.030752 -215.92667)
		(end 118.022878 -215.931242)
		(width 0.0889)
		(layer "In11.Cu")
		(net "P5E_CPU1_PE1_RX_DN<0>")
	)
	(segment
		(start 118.971568 -219.830396)
		(end 118.977664 -219.833952)
		(width 0.0889)
		(layer "In11.Cu")
		(net "P5E_CPU1_PE1_RX_DN<0>")
	)
	(segment
		(start 118.313962 -215.436704)
		(end 118.313962 -215.452198)
		(width 0.0889)
		(layer "In11.Cu")
		(net "P5E_CPU1_PE1_RX_DN<0>")
	)
	(segment
		(start 59.252358 -46.87697)
		(end 114.328702 -179.843938)
		(width 0.14732)
		(layer "In11.Cu")
		(net "P5E_CPU1_PE1_RX_DN<0>")
	)
	(segment
		(start 60.10148 -18.725388)
		(end 60.10148 -19.384264)
		(width 0.14732)
		(layer "In11.Cu")
		(net "P5E_CPU1_PE1_RX_DN<0>")
	)
	(segment
		(start 118.35638 -213.063328)
		(end 118.314216 -213.105492)
		(width 0.0889)
		(layer "In11.Cu")
		(net "P5E_CPU1_PE1_RX_DN<0>")
	)
	(segment
		(start 118.492524 -219.0115)
		(end 118.49989 -219.015818)
		(width 0.0889)
		(layer "In11.Cu")
		(net "P5E_CPU1_PE1_RX_DN<0>")
	)
	(segment
		(start 119.002302 -220.862906)
		(end 119.158766 -221.133924)
		(width 0.0889)
		(layer "In11.Cu")
		(net "P5E_CPU1_PE1_RX_DN<0>")
	)
	(segment
		(start 118.784116 -217.864182)
		(end 118.784116 -217.878406)
		(width 0.0889)
		(layer "In11.Cu")
		(net "P5E_CPU1_PE1_RX_DN<0>")
	)
	(segment
		(start 118.501414 -219.01658)
		(end 118.504208 -219.018104)
		(width 0.0889)
		(layer "In11.Cu")
		(net "P5E_CPU1_PE1_RX_DN<0>")
	)
	(segment
		(start 118.962678 -219.825316)
		(end 118.971568 -219.830396)
		(width 0.0889)
		(layer "In11.Cu")
		(net "P5E_CPU1_PE1_RX_DN<0>")
	)
	(segment
		(start 56.110378 -11.848846)
		(end 56.538622 -12.882372)
		(width 0.14732)
		(layer "In11.Cu")
		(net "P5E_CPU1_PE1_RX_DN<0>")
	)
	(segment
		(start 118.022878 -216.569798)
		(end 118.031768 -216.574878)
		(width 0.0889)
		(layer "In11.Cu")
		(net "P5E_CPU1_PE1_RX_DN<0>")
	)
	(segment
		(start 56.110378 -5.257292)
		(end 56.110378 -11.848846)
		(width 0.14732)
		(layer "In11.Cu")
		(net "P5E_CPU1_PE1_RX_DN<0>")
	)
	(segment
		(start 119.026432 -220.773752)
		(end 119.002302 -220.862906)
		(width 0.0889)
		(layer "In11.Cu")
		(net "P5E_CPU1_PE1_RX_DN<0>")
	)
	(segment
		(start 60.10148 -19.384264)
		(end 59.801506 -20.107402)
		(width 0.14732)
		(layer "In11.Cu")
		(net "P5E_CPU1_PE1_RX_DN<0>")
	)
	(segment
		(start 118.501414 -215.112346)
		(end 118.492524 -215.117426)
		(width 0.0889)
		(layer "In11.Cu")
		(net "P5E_CPU1_PE1_RX_DN<0>")
	)
	(segment
		(start 114.89817 -183.111394)
		(end 114.898678 -183.11622)
		(width 0.14732)
		(layer "In11.Cu")
		(net "P5E_CPU1_PE1_RX_DN<0>")
	)
	(segment
		(start 118.031768 -215.926162)
		(end 118.030752 -215.92667)
		(width 0.0889)
		(layer "In11.Cu")
		(net "P5E_CPU1_PE1_RX_DN<0>")
	)
	(segment
		(start 118.314216 -213.105492)
		(end 118.314216 -213.893908)
		(width 0.0889)
		(layer "In11.Cu")
		(net "P5E_CPU1_PE1_RX_DN<0>")
	)
	(segment
		(start 118.783608 -214.424768)
		(end 118.783608 -214.644732)
		(width 0.0889)
		(layer "In11.Cu")
		(net "P5E_CPU1_PE1_RX_DN<0>")
	)
	(segment
		(start 118.497858 -218.369896)
		(end 118.494556 -218.371674)
		(width 0.0889)
		(layer "In11.Cu")
		(net "P5E_CPU1_PE1_RX_DN<0>")
	)
	(arc
		(start 118.314216 -217.072972)
		(mid 118.366486 -217.255337)
		(end 118.501414 -217.388694)
		(width 0.0889)
		(layer "In11.Cu")
		(net "P5E_CPU1_PE1_RX_DN<0>")
	)
	(arc
		(start 118.498366 -214.093298)
		(mid 118.672329 -214.232062)
		(end 118.783608 -214.424768)
		(width 0.0889)
		(layer "In11.Cu")
		(net "P5E_CPU1_PE1_RX_DN<0>")
	)
	(arc
		(start 119.043196 -220.760798)
		(mid 119.034874 -220.767353)
		(end 119.026432 -220.773752)
		(width 0.0889)
		(layer "In11.Cu")
		(net "P5E_CPU1_PE1_RX_DN<0>")
	)
	(arc
		(start 118.50751 -219.020136)
		(mid 118.710097 -219.226487)
		(end 118.784116 -219.506038)
		(width 0.0889)
		(layer "In11.Cu")
		(net "P5E_CPU1_PE1_RX_DN<0>")
	)
	(arc
		(start 118.492524 -215.117426)
		(mid 118.36527 -215.247392)
		(end 118.314216 -215.421972)
		(width 0.0889)
		(layer "In11.Cu")
		(net "P5E_CPU1_PE1_RX_DN<0>")
	)
	(arc
		(start 117.84457 -216.257124)
		(mid 117.893769 -216.43623)
		(end 118.022878 -216.569798)
		(width 0.0889)
		(layer "In11.Cu")
		(net "P5E_CPU1_PE1_RX_DN<0>")
	)
	(arc
		(start 118.022878 -215.931242)
		(mid 117.894559 -216.063214)
		(end 117.84457 -216.24036)
		(width 0.0889)
		(layer "In11.Cu")
		(net "P5E_CPU1_PE1_RX_DN<0>")
	)
	(arc
		(start 118.031768 -216.574878)
		(mid 118.236103 -216.777483)
		(end 118.314216 -217.05443)
		(width 0.0889)
		(layer "In11.Cu")
		(net "P5E_CPU1_PE1_RX_DN<0>")
	)
	(arc
		(start 118.492524 -218.372944)
		(mid 118.313927 -218.692222)
		(end 118.492524 -219.0115)
		(width 0.0889)
		(layer "In11.Cu")
		(net "P5E_CPU1_PE1_RX_DN<0>")
	)
	(arc
		(start 118.501414 -217.388694)
		(mid 118.704895 -217.589498)
		(end 118.784116 -217.864182)
		(width 0.0889)
		(layer "In11.Cu")
		(net "P5E_CPU1_PE1_RX_DN<0>")
	)
	(arc
		(start 118.783608 -214.644732)
		(mid 118.702697 -214.91486)
		(end 118.501414 -215.112346)
		(width 0.0889)
		(layer "In11.Cu")
		(net "P5E_CPU1_PE1_RX_DN<0>")
	)
	(arc
		(start 118.313962 -215.452198)
		(mid 118.234592 -215.725932)
		(end 118.031768 -215.926162)
		(width 0.0889)
		(layer "In11.Cu")
		(net "P5E_CPU1_PE1_RX_DN<0>")
	)
	(arc
		(start 118.784116 -217.878406)
		(mid 118.710125 -218.157972)
		(end 118.50751 -218.364308)
		(width 0.0889)
		(layer "In11.Cu")
		(net "P5E_CPU1_PE1_RX_DN<0>")
	)
	(arc
		(start 118.314216 -215.421972)
		(mid 118.314019 -215.429337)
		(end 118.313962 -215.436704)
		(width 0.0889)
		(layer "In11.Cu")
		(net "P5E_CPU1_PE1_RX_DN<0>")
	)
	(arc
		(start 119.254016 -220.334078)
		(mid 119.195655 -220.570676)
		(end 119.043196 -220.760798)
		(width 0.0889)
		(layer "In11.Cu")
		(net "P5E_CPU1_PE1_RX_DN<0>")
	)
	(arc
		(start 118.784116 -219.506038)
		(mid 118.831795 -219.688938)
		(end 118.962678 -219.825316)
		(width 0.0889)
		(layer "In11.Cu")
		(net "P5E_CPU1_PE1_RX_DN<0>")
	)
	(arc
		(start 118.314216 -213.893908)
		(mid 118.389221 -214.009367)
		(end 118.498366 -214.093298)
		(width 0.0889)
		(layer "In11.Cu")
		(net "P5E_CPU1_PE1_RX_DN<0>")
	)
	(arc
		(start 117.84457 -216.24036)
		(mid 117.844476 -216.248742)
		(end 117.84457 -216.257124)
		(width 0.0889)
		(layer "In11.Cu")
		(net "P5E_CPU1_PE1_RX_DN<0>")
	)
	(arc
		(start 118.977664 -219.833952)
		(mid 119.180077 -220.040365)
		(end 119.254016 -220.319854)
		(width 0.0889)
		(layer "In11.Cu")
		(net "P5E_CPU1_PE1_RX_DN<0>")
	)
	(segment
		(start 66.92392 -401.157186)
		(end 67.222878 -400.858228)
		(width 0.13208)
		(layer "F.Cu")
		(net "P5E_CPU1_PE0_TX_DP<9>")
	)
	(segment
		(start 98.953066 -225.739198)
		(end 98.953066 -225.203512)
		(width 0.13208)
		(layer "F.Cu")
		(net "P5E_CPU1_PE0_TX_DP<9>")
	)
	(segment
		(start 67.248278 -402.104352)
		(end 66.92392 -401.779994)
		(width 0.13208)
		(layer "F.Cu")
		(net "P5E_CPU1_PE0_TX_DP<9>")
	)
	(segment
		(start 98.953066 -225.203512)
		(end 98.952812 -225.203258)
		(width 0.13208)
		(layer "F.Cu")
		(net "P5E_CPU1_PE0_TX_DP<9>")
	)
	(segment
		(start 66.92392 -401.779994)
		(end 66.92392 -401.157186)
		(width 0.13208)
		(layer "F.Cu")
		(net "P5E_CPU1_PE0_TX_DP<9>")
	)
	(segment
		(start 96.508316 -213.930484)
		(end 96.508316 -213.929722)
		(width 0.0889)
		(layer "In15.Cu")
		(net "P5E_CPU1_PE0_TX_DP<9>")
	)
	(segment
		(start 66.833496 -396.873222)
		(end 66.940176 -399.920714)
		(width 0.14732)
		(layer "In15.Cu")
		(net "P5E_CPU1_PE0_TX_DP<9>")
	)
	(segment
		(start 97.261426 -218.368372)
		(end 97.26041 -218.367864)
		(width 0.0889)
		(layer "In15.Cu")
		(net "P5E_CPU1_PE0_TX_DP<9>")
	)
	(segment
		(start 77.844396 -218.00185)
		(end 75.85202 -221.868238)
		(width 0.14732)
		(layer "In15.Cu")
		(net "P5E_CPU1_PE0_TX_DP<9>")
	)
	(segment
		(start 96.466406 -212.75167)
		(end 96.276922 -212.294216)
		(width 0.14732)
		(layer "In15.Cu")
		(net "P5E_CPU1_PE0_TX_DP<9>")
	)
	(segment
		(start 76.210668 -309.5879)
		(end 71.777606 -320.146934)
		(width 0.14732)
		(layer "In15.Cu")
		(net "P5E_CPU1_PE0_TX_DP<9>")
	)
	(segment
		(start 96.977708 -214.622634)
		(end 96.977708 -214.461344)
		(width 0.0889)
		(layer "In15.Cu")
		(net "P5E_CPU1_PE0_TX_DP<9>")
	)
	(segment
		(start 96.799654 -215.931242)
		(end 96.791526 -215.92667)
		(width 0.0889)
		(layer "In15.Cu")
		(net "P5E_CPU1_PE0_TX_DP<9>")
	)
	(segment
		(start 72.594724 -252.651768)
		(end 72.594724 -252.757178)
		(width 0.14732)
		(layer "In15.Cu")
		(net "P5E_CPU1_PE0_TX_DP<9>")
	)
	(segment
		(start 83.173824 -213.069932)
		(end 77.84465 -218.001596)
		(width 0.14732)
		(layer "In15.Cu")
		(net "P5E_CPU1_PE0_TX_DP<9>")
	)
	(segment
		(start 66.835528 -393.378182)
		(end 66.715386 -393.50696)
		(width 0.14732)
		(layer "In15.Cu")
		(net "P5E_CPU1_PE0_TX_DP<9>")
	)
	(segment
		(start 66.940176 -400.575526)
		(end 67.222878 -400.858228)
		(width 0.14732)
		(layer "In15.Cu")
		(net "P5E_CPU1_PE0_TX_DP<9>")
	)
	(segment
		(start 66.794126 -395.751304)
		(end 66.809366 -396.187676)
		(width 0.14732)
		(layer "In15.Cu")
		(net "P5E_CPU1_PE0_TX_DP<9>")
	)
	(segment
		(start 96.508062 -215.436704)
		(end 96.508062 -215.414606)
		(width 0.0889)
		(layer "In15.Cu")
		(net "P5E_CPU1_PE0_TX_DP<9>")
	)
	(segment
		(start 96.978216 -221.149418)
		(end 96.978216 -221.115382)
		(width 0.0889)
		(layer "In15.Cu")
		(net "P5E_CPU1_PE0_TX_DP<9>")
	)
	(segment
		(start 74.120756 -233.019092)
		(end 72.677528 -250.190762)
		(width 0.14732)
		(layer "In15.Cu")
		(net "P5E_CPU1_PE0_TX_DP<9>")
	)
	(segment
		(start 96.78797 -215.924384)
		(end 96.784668 -215.922606)
		(width 0.0889)
		(layer "In15.Cu")
		(net "P5E_CPU1_PE0_TX_DP<9>")
	)
	(segment
		(start 71.777606 -320.146934)
		(end 68.148708 -325.933562)
		(width 0.14732)
		(layer "In15.Cu")
		(net "P5E_CPU1_PE0_TX_DP<9>")
	)
	(segment
		(start 66.676016 -392.384788)
		(end 66.691256 -392.82116)
		(width 0.14732)
		(layer "In15.Cu")
		(net "P5E_CPU1_PE0_TX_DP<9>")
	)
	(segment
		(start 98.201226 -223.251776)
		(end 98.20021 -223.251268)
		(width 0.0889)
		(layer "In15.Cu")
		(net "P5E_CPU1_PE0_TX_DP<9>")
	)
	(segment
		(start 96.508316 -213.929722)
		(end 96.50857 -213.929468)
		(width 0.0889)
		(layer "In15.Cu")
		(net "P5E_CPU1_PE0_TX_DP<9>")
	)
	(segment
		(start 87.000588 -210.997038)
		(end 83.173824 -213.069932)
		(width 0.14732)
		(layer "In15.Cu")
		(net "P5E_CPU1_PE0_TX_DP<9>")
	)
	(segment
		(start 66.953638 -396.744698)
		(end 66.833496 -396.873222)
		(width 0.14732)
		(layer "In15.Cu")
		(net "P5E_CPU1_PE0_TX_DP<9>")
	)
	(segment
		(start 96.791526 -215.92667)
		(end 96.78924 -215.925146)
		(width 0.0889)
		(layer "In15.Cu")
		(net "P5E_CPU1_PE0_TX_DP<9>")
	)
	(segment
		(start 97.918016 -222.783654)
		(end 97.918016 -222.761556)
		(width 0.0889)
		(layer "In15.Cu")
		(net "P5E_CPU1_PE0_TX_DP<9>")
	)
	(segment
		(start 75.85202 -221.868238)
		(end 74.120756 -233.019092)
		(width 0.14732)
		(layer "In15.Cu")
		(net "P5E_CPU1_PE0_TX_DP<9>")
	)
	(segment
		(start 66.796158 -392.25601)
		(end 66.676016 -392.384788)
		(width 0.14732)
		(layer "In15.Cu")
		(net "P5E_CPU1_PE0_TX_DP<9>")
	)
	(segment
		(start 66.820288 -392.941302)
		(end 66.835528 -393.378182)
		(width 0.14732)
		(layer "In15.Cu")
		(net "P5E_CPU1_PE0_TX_DP<9>")
	)
	(segment
		(start 72.594724 -252.757178)
		(end 76.210668 -309.5879)
		(width 0.14732)
		(layer "In15.Cu")
		(net "P5E_CPU1_PE0_TX_DP<9>")
	)
	(segment
		(start 95.597472 -211.614766)
		(end 94.105984 -210.997038)
		(width 0.14732)
		(layer "In15.Cu")
		(net "P5E_CPU1_PE0_TX_DP<9>")
	)
	(segment
		(start 66.754756 -394.629132)
		(end 66.769996 -395.065504)
		(width 0.14732)
		(layer "In15.Cu")
		(net "P5E_CPU1_PE0_TX_DP<9>")
	)
	(segment
		(start 66.652394 -391.698734)
		(end 66.651886 -391.698988)
		(width 0.14732)
		(layer "In15.Cu")
		(net "P5E_CPU1_PE0_TX_DP<9>")
	)
	(segment
		(start 66.715386 -393.50696)
		(end 66.730626 -393.943332)
		(width 0.14732)
		(layer "In15.Cu")
		(net "P5E_CPU1_PE0_TX_DP<9>")
	)
	(segment
		(start 96.790256 -214.946992)
		(end 96.799146 -214.941912)
		(width 0.0889)
		(layer "In15.Cu")
		(net "P5E_CPU1_PE0_TX_DP<9>")
	)
	(segment
		(start 98.2091 -223.256348)
		(end 98.201226 -223.251776)
		(width 0.0889)
		(layer "In15.Cu")
		(net "P5E_CPU1_PE0_TX_DP<9>")
	)
	(segment
		(start 66.874898 -394.500354)
		(end 66.754756 -394.629132)
		(width 0.14732)
		(layer "In15.Cu")
		(net "P5E_CPU1_PE0_TX_DP<9>")
	)
	(segment
		(start 66.809366 -396.187676)
		(end 66.938398 -396.307818)
		(width 0.14732)
		(layer "In15.Cu")
		(net "P5E_CPU1_PE0_TX_DP<9>")
	)
	(segment
		(start 96.276922 -212.294216)
		(end 95.597472 -211.614766)
		(width 0.14732)
		(layer "In15.Cu")
		(net "P5E_CPU1_PE0_TX_DP<9>")
	)
	(segment
		(start 77.84465 -218.001596)
		(end 77.844396 -218.00185)
		(width 0.14732)
		(layer "In15.Cu")
		(net "P5E_CPU1_PE0_TX_DP<9>")
	)
	(segment
		(start 97.26041 -219.01658)
		(end 97.2693 -219.0115)
		(width 0.0889)
		(layer "In15.Cu")
		(net "P5E_CPU1_PE0_TX_DP<9>")
	)
	(segment
		(start 64.920622 -346.395294)
		(end 65.24244 -351.422716)
		(width 0.14732)
		(layer "In15.Cu")
		(net "P5E_CPU1_PE0_TX_DP<9>")
	)
	(segment
		(start 66.899028 -395.185646)
		(end 66.914268 -395.622526)
		(width 0.14732)
		(layer "In15.Cu")
		(net "P5E_CPU1_PE0_TX_DP<9>")
	)
	(segment
		(start 98.20021 -223.899984)
		(end 98.201226 -223.899476)
		(width 0.0889)
		(layer "In15.Cu")
		(net "P5E_CPU1_PE0_TX_DP<9>")
	)
	(segment
		(start 66.730626 -393.943332)
		(end 66.859658 -394.063474)
		(width 0.14732)
		(layer "In15.Cu")
		(net "P5E_CPU1_PE0_TX_DP<9>")
	)
	(segment
		(start 66.769996 -395.065504)
		(end 66.899028 -395.185646)
		(width 0.14732)
		(layer "In15.Cu")
		(net "P5E_CPU1_PE0_TX_DP<9>")
	)
	(segment
		(start 98.796348 -224.93224)
		(end 98.707448 -224.908618)
		(width 0.0889)
		(layer "In15.Cu")
		(net "P5E_CPU1_PE0_TX_DP<9>")
	)
	(segment
		(start 66.940176 -399.920714)
		(end 66.940176 -400.575526)
		(width 0.14732)
		(layer "In15.Cu")
		(net "P5E_CPU1_PE0_TX_DP<9>")
	)
	(segment
		(start 66.914268 -395.622526)
		(end 66.794126 -395.751304)
		(width 0.14732)
		(layer "In15.Cu")
		(net "P5E_CPU1_PE0_TX_DP<9>")
	)
	(segment
		(start 66.651886 -391.698988)
		(end 66.780918 -391.81913)
		(width 0.14732)
		(layer "In15.Cu")
		(net "P5E_CPU1_PE0_TX_DP<9>")
	)
	(segment
		(start 96.50857 -213.929468)
		(end 96.50857 -213.186772)
		(width 0.0889)
		(layer "In15.Cu")
		(net "P5E_CPU1_PE0_TX_DP<9>")
	)
	(segment
		(start 97.739454 -222.442278)
		(end 97.724468 -222.433642)
		(width 0.0889)
		(layer "In15.Cu")
		(net "P5E_CPU1_PE0_TX_DP<9>")
	)
	(segment
		(start 96.978216 -216.260426)
		(end 96.978216 -216.25052)
		(width 0.0889)
		(layer "In15.Cu")
		(net "P5E_CPU1_PE0_TX_DP<9>")
	)
	(segment
		(start 96.466406 -213.12251)
		(end 96.466406 -212.75167)
		(width 0.14732)
		(layer "In15.Cu")
		(net "P5E_CPU1_PE0_TX_DP<9>")
	)
	(segment
		(start 65.24244 -351.422716)
		(end 66.652394 -391.698734)
		(width 0.14732)
		(layer "In15.Cu")
		(net "P5E_CPU1_PE0_TX_DP<9>")
	)
	(segment
		(start 94.105984 -210.997038)
		(end 87.000588 -210.997038)
		(width 0.14732)
		(layer "In15.Cu")
		(net "P5E_CPU1_PE0_TX_DP<9>")
	)
	(segment
		(start 97.2693 -221.628462)
		(end 97.26041 -221.623382)
		(width 0.0889)
		(layer "In15.Cu")
		(net "P5E_CPU1_PE0_TX_DP<9>")
	)
	(segment
		(start 96.78924 -215.925146)
		(end 96.78797 -215.924384)
		(width 0.0889)
		(layer "In15.Cu")
		(net "P5E_CPU1_PE0_TX_DP<9>")
	)
	(segment
		(start 66.938398 -396.307818)
		(end 66.953638 -396.744698)
		(width 0.14732)
		(layer "In15.Cu")
		(net "P5E_CPU1_PE0_TX_DP<9>")
	)
	(segment
		(start 98.952812 -225.203258)
		(end 98.796348 -224.93224)
		(width 0.0889)
		(layer "In15.Cu")
		(net "P5E_CPU1_PE0_TX_DP<9>")
	)
	(segment
		(start 97.2693 -218.372944)
		(end 97.261426 -218.368372)
		(width 0.0889)
		(layer "In15.Cu")
		(net "P5E_CPU1_PE0_TX_DP<9>")
	)
	(segment
		(start 96.466406 -213.144608)
		(end 96.466406 -213.12251)
		(width 0.0889)
		(layer "In15.Cu")
		(net "P5E_CPU1_PE0_TX_DP<9>")
	)
	(segment
		(start 96.978216 -217.8939)
		(end 96.978216 -217.859864)
		(width 0.0889)
		(layer "In15.Cu")
		(net "P5E_CPU1_PE0_TX_DP<9>")
	)
	(segment
		(start 96.50857 -213.186772)
		(end 96.466406 -213.144608)
		(width 0.0889)
		(layer "In15.Cu")
		(net "P5E_CPU1_PE0_TX_DP<9>")
	)
	(segment
		(start 66.859658 -394.063474)
		(end 66.874898 -394.500354)
		(width 0.14732)
		(layer "In15.Cu")
		(net "P5E_CPU1_PE0_TX_DP<9>")
	)
	(segment
		(start 66.780918 -391.81913)
		(end 66.796158 -392.25601)
		(width 0.14732)
		(layer "In15.Cu")
		(net "P5E_CPU1_PE0_TX_DP<9>")
	)
	(segment
		(start 72.677528 -250.190762)
		(end 72.594724 -252.651768)
		(width 0.14732)
		(layer "In15.Cu")
		(net "P5E_CPU1_PE0_TX_DP<9>")
	)
	(segment
		(start 66.691256 -392.82116)
		(end 66.820288 -392.941302)
		(width 0.14732)
		(layer "In15.Cu")
		(net "P5E_CPU1_PE0_TX_DP<9>")
	)
	(segment
		(start 64.934338 -333.694278)
		(end 64.640968 -335.33461)
		(width 0.14732)
		(layer "In15.Cu")
		(net "P5E_CPU1_PE0_TX_DP<9>")
	)
	(segment
		(start 64.640968 -335.33461)
		(end 64.920622 -346.395294)
		(width 0.14732)
		(layer "In15.Cu")
		(net "P5E_CPU1_PE0_TX_DP<9>")
	)
	(segment
		(start 68.148708 -325.933562)
		(end 64.934338 -333.694278)
		(width 0.14732)
		(layer "In15.Cu")
		(net "P5E_CPU1_PE0_TX_DP<9>")
	)
	(segment
		(start 98.201226 -223.899476)
		(end 98.2091 -223.894904)
		(width 0.0889)
		(layer "In15.Cu")
		(net "P5E_CPU1_PE0_TX_DP<9>")
	)
	(segment
		(start 97.918016 -224.404936)
		(end 97.918016 -224.373948)
		(width 0.0889)
		(layer "In15.Cu")
		(net "P5E_CPU1_PE0_TX_DP<9>")
	)
	(arc
		(start 97.260664 -220.644212)
		(mid 97.447967 -220.319854)
		(end 97.260664 -219.995496)
		(width 0.0889)
		(layer "In15.Cu")
		(net "P5E_CPU1_PE0_TX_DP<9>")
	)
	(arc
		(start 97.2693 -219.0115)
		(mid 97.447776 -218.692222)
		(end 97.2693 -218.372944)
		(width 0.0889)
		(layer "In15.Cu")
		(net "P5E_CPU1_PE0_TX_DP<9>")
	)
	(arc
		(start 96.508062 -215.414606)
		(mid 96.588973 -215.144478)
		(end 96.790256 -214.946992)
		(width 0.0889)
		(layer "In15.Cu")
		(net "P5E_CPU1_PE0_TX_DP<9>")
	)
	(arc
		(start 97.260664 -219.995496)
		(mid 96.978132 -219.506148)
		(end 97.26041 -219.01658)
		(width 0.0889)
		(layer "In15.Cu")
		(net "P5E_CPU1_PE0_TX_DP<9>")
	)
	(arc
		(start 96.523556 -213.969346)
		(mid 96.515593 -213.950049)
		(end 96.508316 -213.930484)
		(width 0.0889)
		(layer "In15.Cu")
		(net "P5E_CPU1_PE0_TX_DP<9>")
	)
	(arc
		(start 96.978216 -217.859864)
		(mid 97.058378 -217.587675)
		(end 97.260664 -217.388694)
		(width 0.0889)
		(layer "In15.Cu")
		(net "P5E_CPU1_PE0_TX_DP<9>")
	)
	(arc
		(start 98.68789 -224.916746)
		(mid 98.439738 -224.953361)
		(end 98.20021 -224.8789)
		(width 0.0889)
		(layer "In15.Cu")
		(net "P5E_CPU1_PE0_TX_DP<9>")
	)
	(arc
		(start 96.977708 -214.461344)
		(mid 96.902703 -214.345885)
		(end 96.793558 -214.261954)
		(width 0.0889)
		(layer "In15.Cu")
		(net "P5E_CPU1_PE0_TX_DP<9>")
	)
	(arc
		(start 97.26041 -221.623382)
		(mid 97.057587 -221.423151)
		(end 96.978216 -221.149418)
		(width 0.0889)
		(layer "In15.Cu")
		(net "P5E_CPU1_PE0_TX_DP<9>")
	)
	(arc
		(start 98.20021 -223.251268)
		(mid 97.998928 -223.053781)
		(end 97.918016 -222.783654)
		(width 0.0889)
		(layer "In15.Cu")
		(net "P5E_CPU1_PE0_TX_DP<9>")
	)
	(arc
		(start 96.793558 -214.261954)
		(mid 96.633486 -214.138774)
		(end 96.523556 -213.969346)
		(width 0.0889)
		(layer "In15.Cu")
		(net "P5E_CPU1_PE0_TX_DP<9>")
	)
	(arc
		(start 96.978216 -216.25052)
		(mid 96.930537 -216.06762)
		(end 96.799654 -215.931242)
		(width 0.0889)
		(layer "In15.Cu")
		(net "P5E_CPU1_PE0_TX_DP<9>")
	)
	(arc
		(start 96.784668 -215.922606)
		(mid 96.582081 -215.716255)
		(end 96.508062 -215.436704)
		(width 0.0889)
		(layer "In15.Cu")
		(net "P5E_CPU1_PE0_TX_DP<9>")
	)
	(arc
		(start 97.26041 -218.367864)
		(mid 97.057587 -218.167633)
		(end 96.978216 -217.8939)
		(width 0.0889)
		(layer "In15.Cu")
		(net "P5E_CPU1_PE0_TX_DP<9>")
	)
	(arc
		(start 97.447862 -221.94774)
		(mid 97.400183 -221.76484)
		(end 97.2693 -221.628462)
		(width 0.0889)
		(layer "In15.Cu")
		(net "P5E_CPU1_PE0_TX_DP<9>")
	)
	(arc
		(start 97.260664 -217.388694)
		(mid 97.447967 -217.064336)
		(end 97.260664 -216.739978)
		(width 0.0889)
		(layer "In15.Cu")
		(net "P5E_CPU1_PE0_TX_DP<9>")
	)
	(arc
		(start 96.978216 -221.115382)
		(mid 97.058378 -220.843193)
		(end 97.260664 -220.644212)
		(width 0.0889)
		(layer "In15.Cu")
		(net "P5E_CPU1_PE0_TX_DP<9>")
	)
	(arc
		(start 97.918016 -224.373948)
		(mid 97.997386 -224.100214)
		(end 98.20021 -223.899984)
		(width 0.0889)
		(layer "In15.Cu")
		(net "P5E_CPU1_PE0_TX_DP<9>")
	)
	(arc
		(start 98.707448 -224.908618)
		(mid 98.697708 -224.912775)
		(end 98.68789 -224.916746)
		(width 0.0889)
		(layer "In15.Cu")
		(net "P5E_CPU1_PE0_TX_DP<9>")
	)
	(arc
		(start 97.260664 -216.739978)
		(mid 97.056329 -216.537373)
		(end 96.978216 -216.260426)
		(width 0.0889)
		(layer "In15.Cu")
		(net "P5E_CPU1_PE0_TX_DP<9>")
	)
	(arc
		(start 98.20021 -224.8789)
		(mid 97.997387 -224.678669)
		(end 97.918016 -224.404936)
		(width 0.0889)
		(layer "In15.Cu")
		(net "P5E_CPU1_PE0_TX_DP<9>")
	)
	(arc
		(start 98.2091 -223.894904)
		(mid 98.387697 -223.575626)
		(end 98.2091 -223.256348)
		(width 0.0889)
		(layer "In15.Cu")
		(net "P5E_CPU1_PE0_TX_DP<9>")
	)
	(arc
		(start 96.799146 -214.941912)
		(mid 96.9264 -214.811946)
		(end 96.977454 -214.637366)
		(width 0.0889)
		(layer "In15.Cu")
		(net "P5E_CPU1_PE0_TX_DP<9>")
	)
	(arc
		(start 96.977454 -214.637366)
		(mid 96.977651 -214.630001)
		(end 96.977708 -214.622634)
		(width 0.0889)
		(layer "In15.Cu")
		(net "P5E_CPU1_PE0_TX_DP<9>")
	)
	(arc
		(start 97.724468 -222.433642)
		(mid 97.521881 -222.227291)
		(end 97.447862 -221.94774)
		(width 0.0889)
		(layer "In15.Cu")
		(net "P5E_CPU1_PE0_TX_DP<9>")
	)
	(arc
		(start 97.918016 -222.761556)
		(mid 97.870337 -222.578656)
		(end 97.739454 -222.442278)
		(width 0.0889)
		(layer "In15.Cu")
		(net "P5E_CPU1_PE0_TX_DP<9>")
	)
	(segment
		(start 97.543112 -224.925382)
		(end 97.543366 -224.925128)
		(width 0.13208)
		(layer "F.Cu")
		(net "P5E_CPU1_PE0_TX_DP<8>")
	)
	(segment
		(start 69.98716 -401.779994)
		(end 69.98716 -401.157186)
		(width 0.13208)
		(layer "F.Cu")
		(net "P5E_CPU1_PE0_TX_DP<8>")
	)
	(segment
		(start 70.311518 -402.104352)
		(end 69.98716 -401.779994)
		(width 0.13208)
		(layer "F.Cu")
		(net "P5E_CPU1_PE0_TX_DP<8>")
	)
	(segment
		(start 69.98716 -401.157186)
		(end 70.286118 -400.858228)
		(width 0.13208)
		(layer "F.Cu")
		(net "P5E_CPU1_PE0_TX_DP<8>")
	)
	(segment
		(start 97.543366 -224.925128)
		(end 97.543366 -224.389442)
		(width 0.13208)
		(layer "F.Cu")
		(net "P5E_CPU1_PE0_TX_DP<8>")
	)
	(segment
		(start 95.568516 -213.929722)
		(end 95.56877 -213.929468)
		(width 0.0889)
		(layer "In15.Cu")
		(net "P5E_CPU1_PE0_TX_DP<8>")
	)
	(segment
		(start 69.583046 -392.899392)
		(end 69.617336 -393.335256)
		(width 0.14732)
		(layer "In15.Cu")
		(net "P5E_CPU1_PE0_TX_DP<8>")
	)
	(segment
		(start 96.321626 -216.740486)
		(end 96.32061 -216.739978)
		(width 0.0889)
		(layer "In15.Cu")
		(net "P5E_CPU1_PE0_TX_DP<8>")
	)
	(segment
		(start 69.503036 -393.469114)
		(end 69.503544 -393.469114)
		(width 0.14732)
		(layer "In15.Cu")
		(net "P5E_CPU1_PE0_TX_DP<8>")
	)
	(segment
		(start 96.321626 -218.368372)
		(end 96.32061 -218.367864)
		(width 0.0889)
		(layer "In15.Cu")
		(net "P5E_CPU1_PE0_TX_DP<8>")
	)
	(segment
		(start 95.84944 -215.925146)
		(end 95.84817 -215.924384)
		(width 0.0889)
		(layer "In15.Cu")
		(net "P5E_CPU1_PE0_TX_DP<8>")
	)
	(segment
		(start 95.850456 -214.946992)
		(end 95.859346 -214.941912)
		(width 0.0889)
		(layer "In15.Cu")
		(net "P5E_CPU1_PE0_TX_DP<8>")
	)
	(segment
		(start 69.503544 -393.469114)
		(end 69.537834 -393.90447)
		(width 0.14732)
		(layer "In15.Cu")
		(net "P5E_CPU1_PE0_TX_DP<8>")
	)
	(segment
		(start 96.32061 -220.644212)
		(end 96.3295 -220.639132)
		(width 0.0889)
		(layer "In15.Cu")
		(net "P5E_CPU1_PE0_TX_DP<8>")
	)
	(segment
		(start 95.84817 -215.924384)
		(end 95.844868 -215.922606)
		(width 0.0889)
		(layer "In15.Cu")
		(net "P5E_CPU1_PE0_TX_DP<8>")
	)
	(segment
		(start 96.3295 -216.745058)
		(end 96.321626 -216.740486)
		(width 0.0889)
		(layer "In15.Cu")
		(net "P5E_CPU1_PE0_TX_DP<8>")
	)
	(segment
		(start 96.321626 -219.996004)
		(end 96.32061 -219.995496)
		(width 0.0889)
		(layer "In15.Cu")
		(net "P5E_CPU1_PE0_TX_DP<8>")
	)
	(segment
		(start 69.139308 -326.266556)
		(end 65.867788 -334.16494)
		(width 0.14732)
		(layer "In15.Cu")
		(net "P5E_CPU1_PE0_TX_DP<8>")
	)
	(segment
		(start 69.537834 -393.90447)
		(end 69.537326 -393.90447)
		(width 0.14732)
		(layer "In15.Cu")
		(net "P5E_CPU1_PE0_TX_DP<8>")
	)
	(segment
		(start 85.103716 -213.11362)
		(end 85.103716 -213.113874)
		(width 0.14732)
		(layer "In15.Cu")
		(net "P5E_CPU1_PE0_TX_DP<8>")
	)
	(segment
		(start 73.580244 -252.66777)
		(end 77.201014 -309.73268)
		(width 0.14732)
		(layer "In15.Cu")
		(net "P5E_CPU1_PE0_TX_DP<8>")
	)
	(segment
		(start 69.768212 -396.827248)
		(end 69.991478 -399.661126)
		(width 0.14732)
		(layer "In15.Cu")
		(net "P5E_CPU1_PE0_TX_DP<8>")
	)
	(segment
		(start 86.685374 -212.256878)
		(end 86.636098 -212.422486)
		(width 0.14732)
		(layer "In15.Cu")
		(net "P5E_CPU1_PE0_TX_DP<8>")
	)
	(segment
		(start 96.038416 -217.8939)
		(end 96.038416 -217.856308)
		(width 0.0889)
		(layer "In15.Cu")
		(net "P5E_CPU1_PE0_TX_DP<8>")
	)
	(segment
		(start 85.268816 -213.162896)
		(end 85.103716 -213.11362)
		(width 0.14732)
		(layer "In15.Cu")
		(net "P5E_CPU1_PE0_TX_DP<8>")
	)
	(segment
		(start 69.79412 -395.574012)
		(end 69.67982 -395.70787)
		(width 0.14732)
		(layer "In15.Cu")
		(net "P5E_CPU1_PE0_TX_DP<8>")
	)
	(segment
		(start 69.625972 -395.023594)
		(end 69.625718 -395.023848)
		(width 0.14732)
		(layer "In15.Cu")
		(net "P5E_CPU1_PE0_TX_DP<8>")
	)
	(segment
		(start 96.038416 -221.149418)
		(end 96.038416 -221.111826)
		(width 0.0889)
		(layer "In15.Cu")
		(net "P5E_CPU1_PE0_TX_DP<8>")
	)
	(segment
		(start 96.32061 -219.01658)
		(end 96.3295 -219.0115)
		(width 0.0889)
		(layer "In15.Cu")
		(net "P5E_CPU1_PE0_TX_DP<8>")
	)
	(segment
		(start 66.038222 -348.891606)
		(end 66.18859 -351.421954)
		(width 0.14732)
		(layer "In15.Cu")
		(net "P5E_CPU1_PE0_TX_DP<8>")
	)
	(segment
		(start 97.543366 -224.389442)
		(end 97.69983 -224.118424)
		(width 0.0889)
		(layer "In15.Cu")
		(net "P5E_CPU1_PE0_TX_DP<8>")
	)
	(segment
		(start 78.639162 -218.635326)
		(end 76.730352 -222.338138)
		(width 0.14732)
		(layer "In15.Cu")
		(net "P5E_CPU1_PE0_TX_DP<8>")
	)
	(segment
		(start 87.294974 -211.926678)
		(end 86.685374 -212.256878)
		(width 0.14732)
		(layer "In15.Cu")
		(net "P5E_CPU1_PE0_TX_DP<8>")
	)
	(segment
		(start 69.671438 -394.01877)
		(end 69.705728 -394.454634)
		(width 0.14732)
		(layer "In15.Cu")
		(net "P5E_CPU1_PE0_TX_DP<8>")
	)
	(segment
		(start 69.361558 -391.670794)
		(end 69.492876 -391.782808)
		(width 0.14732)
		(layer "In15.Cu")
		(net "P5E_CPU1_PE0_TX_DP<8>")
	)
	(segment
		(start 66.18859 -351.421954)
		(end 69.361558 -391.67054)
		(width 0.14732)
		(layer "In15.Cu")
		(net "P5E_CPU1_PE0_TX_DP<8>")
	)
	(segment
		(start 69.449442 -392.785092)
		(end 69.448934 -392.785092)
		(width 0.14732)
		(layer "In15.Cu")
		(net "P5E_CPU1_PE0_TX_DP<8>")
	)
	(segment
		(start 86.636098 -212.422486)
		(end 86.251796 -212.630512)
		(width 0.14732)
		(layer "In15.Cu")
		(net "P5E_CPU1_PE0_TX_DP<8>")
	)
	(segment
		(start 95.526606 -213.133686)
		(end 95.526606 -213.12251)
		(width 0.0889)
		(layer "In15.Cu")
		(net "P5E_CPU1_PE0_TX_DP<8>")
	)
	(segment
		(start 69.617336 -393.335256)
		(end 69.503036 -393.469114)
		(width 0.14732)
		(layer "In15.Cu")
		(net "P5E_CPU1_PE0_TX_DP<8>")
	)
	(segment
		(start 83.660488 -213.895432)
		(end 78.639162 -218.635326)
		(width 0.14732)
		(layer "In15.Cu")
		(net "P5E_CPU1_PE0_TX_DP<8>")
	)
	(segment
		(start 96.3295 -221.628462)
		(end 96.32061 -221.623382)
		(width 0.0889)
		(layer "In15.Cu")
		(net "P5E_CPU1_PE0_TX_DP<8>")
	)
	(segment
		(start 96.799654 -222.442278)
		(end 96.784668 -222.433642)
		(width 0.0889)
		(layer "In15.Cu")
		(net "P5E_CPU1_PE0_TX_DP<8>")
	)
	(segment
		(start 85.653372 -212.954616)
		(end 85.268816 -213.162896)
		(width 0.14732)
		(layer "In15.Cu")
		(net "P5E_CPU1_PE0_TX_DP<8>")
	)
	(segment
		(start 97.447862 -223.575626)
		(end 97.447862 -223.56699)
		(width 0.0889)
		(layer "In15.Cu")
		(net "P5E_CPU1_PE0_TX_DP<8>")
	)
	(segment
		(start 69.537326 -393.90447)
		(end 69.671438 -394.01877)
		(width 0.14732)
		(layer "In15.Cu")
		(net "P5E_CPU1_PE0_TX_DP<8>")
	)
	(segment
		(start 69.705728 -394.454634)
		(end 69.591428 -394.588492)
		(width 0.14732)
		(layer "In15.Cu")
		(net "P5E_CPU1_PE0_TX_DP<8>")
	)
	(segment
		(start 96.037908 -214.622634)
		(end 96.037908 -214.461344)
		(width 0.0889)
		(layer "In15.Cu")
		(net "P5E_CPU1_PE0_TX_DP<8>")
	)
	(segment
		(start 86.086442 -212.581236)
		(end 85.702394 -212.789262)
		(width 0.14732)
		(layer "In15.Cu")
		(net "P5E_CPU1_PE0_TX_DP<8>")
	)
	(segment
		(start 65.62979 -335.240122)
		(end 66.038222 -348.891606)
		(width 0.14732)
		(layer "In15.Cu")
		(net "P5E_CPU1_PE0_TX_DP<8>")
	)
	(segment
		(start 69.991478 -400.563588)
		(end 70.286118 -400.858228)
		(width 0.14732)
		(layer "In15.Cu")
		(net "P5E_CPU1_PE0_TX_DP<8>")
	)
	(segment
		(start 96.038416 -216.266014)
		(end 96.038416 -216.25052)
		(width 0.0889)
		(layer "In15.Cu")
		(net "P5E_CPU1_PE0_TX_DP<8>")
	)
	(segment
		(start 95.072708 -212.428582)
		(end 93.860874 -211.926678)
		(width 0.14732)
		(layer "In15.Cu")
		(net "P5E_CPU1_PE0_TX_DP<8>")
	)
	(segment
		(start 69.625718 -395.023848)
		(end 69.75983 -395.138148)
		(width 0.14732)
		(layer "In15.Cu")
		(net "P5E_CPU1_PE0_TX_DP<8>")
	)
	(segment
		(start 69.361558 -391.67054)
		(end 69.361558 -391.670794)
		(width 0.14732)
		(layer "In15.Cu")
		(net "P5E_CPU1_PE0_TX_DP<8>")
	)
	(segment
		(start 69.527166 -392.218672)
		(end 69.415152 -392.349736)
		(width 0.14732)
		(layer "In15.Cu")
		(net "P5E_CPU1_PE0_TX_DP<8>")
	)
	(segment
		(start 69.591682 -394.588746)
		(end 69.625972 -395.023594)
		(width 0.14732)
		(layer "In15.Cu")
		(net "P5E_CPU1_PE0_TX_DP<8>")
	)
	(segment
		(start 69.448934 -392.785092)
		(end 69.583046 -392.899392)
		(width 0.14732)
		(layer "In15.Cu")
		(net "P5E_CPU1_PE0_TX_DP<8>")
	)
	(segment
		(start 86.251796 -212.630512)
		(end 86.086442 -212.581236)
		(width 0.14732)
		(layer "In15.Cu")
		(net "P5E_CPU1_PE0_TX_DP<8>")
	)
	(segment
		(start 85.103716 -213.113874)
		(end 83.660488 -213.895432)
		(width 0.14732)
		(layer "In15.Cu")
		(net "P5E_CPU1_PE0_TX_DP<8>")
	)
	(segment
		(start 72.559164 -320.709798)
		(end 69.139308 -326.266556)
		(width 0.14732)
		(layer "In15.Cu")
		(net "P5E_CPU1_PE0_TX_DP<8>")
	)
	(segment
		(start 69.991478 -399.661126)
		(end 69.991478 -400.563588)
		(width 0.14732)
		(layer "In15.Cu")
		(net "P5E_CPU1_PE0_TX_DP<8>")
	)
	(segment
		(start 69.591428 -394.588492)
		(end 69.591682 -394.588746)
		(width 0.14732)
		(layer "In15.Cu")
		(net "P5E_CPU1_PE0_TX_DP<8>")
	)
	(segment
		(start 95.851726 -215.92667)
		(end 95.84944 -215.925146)
		(width 0.0889)
		(layer "In15.Cu")
		(net "P5E_CPU1_PE0_TX_DP<8>")
	)
	(segment
		(start 69.848222 -396.257526)
		(end 69.882512 -396.69339)
		(width 0.14732)
		(layer "In15.Cu")
		(net "P5E_CPU1_PE0_TX_DP<8>")
	)
	(segment
		(start 93.860874 -211.926678)
		(end 87.294974 -211.926678)
		(width 0.14732)
		(layer "In15.Cu")
		(net "P5E_CPU1_PE0_TX_DP<8>")
	)
	(segment
		(start 69.415152 -392.349736)
		(end 69.449442 -392.785092)
		(width 0.14732)
		(layer "In15.Cu")
		(net "P5E_CPU1_PE0_TX_DP<8>")
	)
	(segment
		(start 69.75983 -395.138148)
		(end 69.79412 -395.574012)
		(width 0.14732)
		(layer "In15.Cu")
		(net "P5E_CPU1_PE0_TX_DP<8>")
	)
	(segment
		(start 75.049634 -233.16311)
		(end 73.65619 -250.236736)
		(width 0.14732)
		(layer "In15.Cu")
		(net "P5E_CPU1_PE0_TX_DP<8>")
	)
	(segment
		(start 69.882512 -396.69339)
		(end 69.768212 -396.827248)
		(width 0.14732)
		(layer "In15.Cu")
		(net "P5E_CPU1_PE0_TX_DP<8>")
	)
	(segment
		(start 96.978216 -222.780098)
		(end 96.978216 -222.761556)
		(width 0.0889)
		(layer "In15.Cu")
		(net "P5E_CPU1_PE0_TX_DP<8>")
	)
	(segment
		(start 96.3295 -218.372944)
		(end 96.321626 -218.368372)
		(width 0.0889)
		(layer "In15.Cu")
		(net "P5E_CPU1_PE0_TX_DP<8>")
	)
	(segment
		(start 95.859854 -215.931242)
		(end 95.855536 -215.928702)
		(width 0.0889)
		(layer "In15.Cu")
		(net "P5E_CPU1_PE0_TX_DP<8>")
	)
	(segment
		(start 76.730352 -222.338138)
		(end 75.049634 -233.16311)
		(width 0.14732)
		(layer "In15.Cu")
		(net "P5E_CPU1_PE0_TX_DP<8>")
	)
	(segment
		(start 77.201014 -309.73268)
		(end 72.559164 -320.709798)
		(width 0.14732)
		(layer "In15.Cu")
		(net "P5E_CPU1_PE0_TX_DP<8>")
	)
	(segment
		(start 95.526606 -212.88248)
		(end 95.072708 -212.428582)
		(width 0.14732)
		(layer "In15.Cu")
		(net "P5E_CPU1_PE0_TX_DP<8>")
	)
	(segment
		(start 97.69983 -224.118424)
		(end 97.6757 -224.02927)
		(width 0.0889)
		(layer "In15.Cu")
		(net "P5E_CPU1_PE0_TX_DP<8>")
	)
	(segment
		(start 69.492876 -391.782808)
		(end 69.527166 -392.218672)
		(width 0.14732)
		(layer "In15.Cu")
		(net "P5E_CPU1_PE0_TX_DP<8>")
	)
	(segment
		(start 95.568516 -213.930484)
		(end 95.568516 -213.929722)
		(width 0.0889)
		(layer "In15.Cu")
		(net "P5E_CPU1_PE0_TX_DP<8>")
	)
	(segment
		(start 73.65619 -250.236736)
		(end 73.580244 -252.495304)
		(width 0.14732)
		(layer "In15.Cu")
		(net "P5E_CPU1_PE0_TX_DP<8>")
	)
	(segment
		(start 95.568262 -215.436704)
		(end 95.568262 -215.414606)
		(width 0.0889)
		(layer "In15.Cu")
		(net "P5E_CPU1_PE0_TX_DP<8>")
	)
	(segment
		(start 65.867788 -334.16494)
		(end 65.62979 -335.240122)
		(width 0.14732)
		(layer "In15.Cu")
		(net "P5E_CPU1_PE0_TX_DP<8>")
	)
	(segment
		(start 85.702394 -212.789262)
		(end 85.653372 -212.954616)
		(width 0.14732)
		(layer "In15.Cu")
		(net "P5E_CPU1_PE0_TX_DP<8>")
	)
	(segment
		(start 73.580244 -252.495304)
		(end 73.580244 -252.66777)
		(width 0.14732)
		(layer "In15.Cu")
		(net "P5E_CPU1_PE0_TX_DP<8>")
	)
	(segment
		(start 95.56877 -213.929468)
		(end 95.56877 -213.17585)
		(width 0.0889)
		(layer "In15.Cu")
		(net "P5E_CPU1_PE0_TX_DP<8>")
	)
	(segment
		(start 96.038416 -219.521532)
		(end 96.038416 -219.490544)
		(width 0.0889)
		(layer "In15.Cu")
		(net "P5E_CPU1_PE0_TX_DP<8>")
	)
	(segment
		(start 96.3295 -220.000576)
		(end 96.321626 -219.996004)
		(width 0.0889)
		(layer "In15.Cu")
		(net "P5E_CPU1_PE0_TX_DP<8>")
	)
	(segment
		(start 69.71411 -396.143226)
		(end 69.848222 -396.257526)
		(width 0.14732)
		(layer "In15.Cu")
		(net "P5E_CPU1_PE0_TX_DP<8>")
	)
	(segment
		(start 95.56877 -213.17585)
		(end 95.526606 -213.133686)
		(width 0.0889)
		(layer "In15.Cu")
		(net "P5E_CPU1_PE0_TX_DP<8>")
	)
	(segment
		(start 69.67982 -395.70787)
		(end 69.71411 -396.14094)
		(width 0.14732)
		(layer "In15.Cu")
		(net "P5E_CPU1_PE0_TX_DP<8>")
	)
	(segment
		(start 95.855536 -215.928702)
		(end 95.851726 -215.92667)
		(width 0.0889)
		(layer "In15.Cu")
		(net "P5E_CPU1_PE0_TX_DP<8>")
	)
	(segment
		(start 96.32061 -217.388694)
		(end 96.3295 -217.383614)
		(width 0.0889)
		(layer "In15.Cu")
		(net "P5E_CPU1_PE0_TX_DP<8>")
	)
	(segment
		(start 95.526606 -213.12251)
		(end 95.526606 -212.88248)
		(width 0.14732)
		(layer "In15.Cu")
		(net "P5E_CPU1_PE0_TX_DP<8>")
	)
	(segment
		(start 69.71411 -396.14094)
		(end 69.71411 -396.143226)
		(width 0.14732)
		(layer "In15.Cu")
		(net "P5E_CPU1_PE0_TX_DP<8>")
	)
	(arc
		(start 96.508062 -221.94774)
		(mid 96.460383 -221.76484)
		(end 96.3295 -221.628462)
		(width 0.0889)
		(layer "In15.Cu")
		(net "P5E_CPU1_PE0_TX_DP<8>")
	)
	(arc
		(start 96.32061 -218.367864)
		(mid 96.117787 -218.167633)
		(end 96.038416 -217.8939)
		(width 0.0889)
		(layer "In15.Cu")
		(net "P5E_CPU1_PE0_TX_DP<8>")
	)
	(arc
		(start 96.978216 -222.761556)
		(mid 96.930537 -222.578656)
		(end 96.799654 -222.442278)
		(width 0.0889)
		(layer "In15.Cu")
		(net "P5E_CPU1_PE0_TX_DP<8>")
	)
	(arc
		(start 95.844868 -215.922606)
		(mid 95.642281 -215.716255)
		(end 95.568262 -215.436704)
		(width 0.0889)
		(layer "In15.Cu")
		(net "P5E_CPU1_PE0_TX_DP<8>")
	)
	(arc
		(start 97.260664 -223.251268)
		(mid 97.058378 -223.052287)
		(end 96.978216 -222.780098)
		(width 0.0889)
		(layer "In15.Cu")
		(net "P5E_CPU1_PE0_TX_DP<8>")
	)
	(arc
		(start 96.784668 -222.433642)
		(mid 96.582081 -222.227291)
		(end 96.508062 -221.94774)
		(width 0.0889)
		(layer "In15.Cu")
		(net "P5E_CPU1_PE0_TX_DP<8>")
	)
	(arc
		(start 96.32061 -221.623382)
		(mid 96.117787 -221.423151)
		(end 96.038416 -221.149418)
		(width 0.0889)
		(layer "In15.Cu")
		(net "P5E_CPU1_PE0_TX_DP<8>")
	)
	(arc
		(start 96.3295 -219.0115)
		(mid 96.507976 -218.692222)
		(end 96.3295 -218.372944)
		(width 0.0889)
		(layer "In15.Cu")
		(net "P5E_CPU1_PE0_TX_DP<8>")
	)
	(arc
		(start 95.853758 -214.261954)
		(mid 95.693686 -214.138774)
		(end 95.583756 -213.969346)
		(width 0.0889)
		(layer "In15.Cu")
		(net "P5E_CPU1_PE0_TX_DP<8>")
	)
	(arc
		(start 96.037654 -214.637366)
		(mid 96.037851 -214.630001)
		(end 96.037908 -214.622634)
		(width 0.0889)
		(layer "In15.Cu")
		(net "P5E_CPU1_PE0_TX_DP<8>")
	)
	(arc
		(start 96.038416 -216.25052)
		(mid 95.990737 -216.06762)
		(end 95.859854 -215.931242)
		(width 0.0889)
		(layer "In15.Cu")
		(net "P5E_CPU1_PE0_TX_DP<8>")
	)
	(arc
		(start 95.583756 -213.969346)
		(mid 95.575793 -213.950049)
		(end 95.568516 -213.930484)
		(width 0.0889)
		(layer "In15.Cu")
		(net "P5E_CPU1_PE0_TX_DP<8>")
	)
	(arc
		(start 97.447862 -223.56699)
		(mid 97.395592 -223.384625)
		(end 97.260664 -223.251268)
		(width 0.0889)
		(layer "In15.Cu")
		(net "P5E_CPU1_PE0_TX_DP<8>")
	)
	(arc
		(start 96.3295 -220.639132)
		(mid 96.508097 -220.319854)
		(end 96.3295 -220.000576)
		(width 0.0889)
		(layer "In15.Cu")
		(net "P5E_CPU1_PE0_TX_DP<8>")
	)
	(arc
		(start 97.6757 -224.02927)
		(mid 97.507946 -223.829492)
		(end 97.447862 -223.575626)
		(width 0.0889)
		(layer "In15.Cu")
		(net "P5E_CPU1_PE0_TX_DP<8>")
	)
	(arc
		(start 96.037908 -214.461344)
		(mid 95.962903 -214.345885)
		(end 95.853758 -214.261954)
		(width 0.0889)
		(layer "In15.Cu")
		(net "P5E_CPU1_PE0_TX_DP<8>")
	)
	(arc
		(start 96.3295 -217.383614)
		(mid 96.508097 -217.064336)
		(end 96.3295 -216.745058)
		(width 0.0889)
		(layer "In15.Cu")
		(net "P5E_CPU1_PE0_TX_DP<8>")
	)
	(arc
		(start 96.038416 -219.490544)
		(mid 96.117786 -219.21681)
		(end 96.32061 -219.01658)
		(width 0.0889)
		(layer "In15.Cu")
		(net "P5E_CPU1_PE0_TX_DP<8>")
	)
	(arc
		(start 95.859346 -214.941912)
		(mid 95.9866 -214.811946)
		(end 96.037654 -214.637366)
		(width 0.0889)
		(layer "In15.Cu")
		(net "P5E_CPU1_PE0_TX_DP<8>")
	)
	(arc
		(start 96.32061 -216.739978)
		(mid 96.117787 -216.539747)
		(end 96.038416 -216.266014)
		(width 0.0889)
		(layer "In15.Cu")
		(net "P5E_CPU1_PE0_TX_DP<8>")
	)
	(arc
		(start 96.32061 -219.995496)
		(mid 96.117787 -219.795265)
		(end 96.038416 -219.521532)
		(width 0.0889)
		(layer "In15.Cu")
		(net "P5E_CPU1_PE0_TX_DP<8>")
	)
	(arc
		(start 96.038416 -221.111826)
		(mid 96.119327 -220.841698)
		(end 96.32061 -220.644212)
		(width 0.0889)
		(layer "In15.Cu")
		(net "P5E_CPU1_PE0_TX_DP<8>")
	)
	(arc
		(start 96.038416 -217.856308)
		(mid 96.119327 -217.58618)
		(end 96.32061 -217.388694)
		(width 0.0889)
		(layer "In15.Cu")
		(net "P5E_CPU1_PE0_TX_DP<8>")
	)
	(arc
		(start 95.568262 -215.414606)
		(mid 95.649173 -215.144478)
		(end 95.850456 -214.946992)
		(width 0.0889)
		(layer "In15.Cu")
		(net "P5E_CPU1_PE0_TX_DP<8>")
	)
	(segment
		(start 73.0504 -401.157186)
		(end 73.349358 -400.858228)
		(width 0.13208)
		(layer "F.Cu")
		(net "P5E_CPU1_PE0_TX_DP<7>")
	)
	(segment
		(start 73.0504 -401.779994)
		(end 73.0504 -401.157186)
		(width 0.13208)
		(layer "F.Cu")
		(net "P5E_CPU1_PE0_TX_DP<7>")
	)
	(segment
		(start 97.073466 -225.739198)
		(end 97.073466 -225.203512)
		(width 0.13208)
		(layer "F.Cu")
		(net "P5E_CPU1_PE0_TX_DP<7>")
	)
	(segment
		(start 73.374758 -402.104352)
		(end 73.0504 -401.779994)
		(width 0.13208)
		(layer "F.Cu")
		(net "P5E_CPU1_PE0_TX_DP<7>")
	)
	(segment
		(start 97.073466 -225.203512)
		(end 97.073212 -225.203258)
		(width 0.13208)
		(layer "F.Cu")
		(net "P5E_CPU1_PE0_TX_DP<7>")
	)
	(segment
		(start 79.328264 -219.334842)
		(end 77.748384 -222.399606)
		(width 0.14732)
		(layer "In15.Cu")
		(net "P5E_CPU1_PE0_TX_DP<7>")
	)
	(segment
		(start 94.4499 -215.117426)
		(end 94.44101 -215.112346)
		(width 0.0889)
		(layer "In15.Cu")
		(net "P5E_CPU1_PE0_TX_DP<7>")
	)
	(segment
		(start 72.150478 -392.516868)
		(end 72.150986 -392.516868)
		(width 0.14732)
		(layer "In15.Cu")
		(net "P5E_CPU1_PE0_TX_DP<7>")
	)
	(segment
		(start 95.850202 -222.43669)
		(end 95.844868 -222.433642)
		(width 0.0889)
		(layer "In15.Cu")
		(net "P5E_CPU1_PE0_TX_DP<7>")
	)
	(segment
		(start 66.910458 -334.118458)
		(end 66.77533 -334.892904)
		(width 0.14732)
		(layer "In15.Cu")
		(net "P5E_CPU1_PE0_TX_DP<7>")
	)
	(segment
		(start 95.381826 -218.368372)
		(end 95.38081 -218.367864)
		(width 0.0889)
		(layer "In15.Cu")
		(net "P5E_CPU1_PE0_TX_DP<7>")
	)
	(segment
		(start 95.098616 -217.8939)
		(end 95.098616 -217.859864)
		(width 0.0889)
		(layer "In15.Cu")
		(net "P5E_CPU1_PE0_TX_DP<7>")
	)
	(segment
		(start 72.205342 -391.944352)
		(end 72.258682 -392.378184)
		(width 0.14732)
		(layer "In15.Cu")
		(net "P5E_CPU1_PE0_TX_DP<7>")
	)
	(segment
		(start 73.054718 -399.86839)
		(end 73.054718 -400.563588)
		(width 0.14732)
		(layer "In15.Cu")
		(net "P5E_CPU1_PE0_TX_DP<7>")
	)
	(segment
		(start 95.38081 -219.01658)
		(end 95.3897 -219.0115)
		(width 0.0889)
		(layer "In15.Cu")
		(net "P5E_CPU1_PE0_TX_DP<7>")
	)
	(segment
		(start 78.265528 -309.716424)
		(end 73.446132 -321.117214)
		(width 0.14732)
		(layer "In15.Cu")
		(net "P5E_CPU1_PE0_TX_DP<7>")
	)
	(segment
		(start 97.073212 -225.203258)
		(end 96.916748 -224.93224)
		(width 0.0889)
		(layer "In15.Cu")
		(net "P5E_CPU1_PE0_TX_DP<7>")
	)
	(segment
		(start 72.479662 -394.172948)
		(end 72.533002 -394.60678)
		(width 0.14732)
		(layer "In15.Cu")
		(net "P5E_CPU1_PE0_TX_DP<7>")
	)
	(segment
		(start 93.647006 -213.172548)
		(end 93.647006 -213.15045)
		(width 0.0889)
		(layer "In15.Cu")
		(net "P5E_CPU1_PE0_TX_DP<7>")
	)
	(segment
		(start 88.001094 -212.856318)
		(end 83.678776 -215.19769)
		(width 0.14732)
		(layer "In15.Cu")
		(net "P5E_CPU1_PE0_TX_DP<7>")
	)
	(segment
		(start 72.203564 -392.950446)
		(end 72.342502 -393.05865)
		(width 0.14732)
		(layer "In15.Cu")
		(net "P5E_CPU1_PE0_TX_DP<7>")
	)
	(segment
		(start 72.699118 -396.974314)
		(end 73.054718 -399.86839)
		(width 0.14732)
		(layer "In15.Cu")
		(net "P5E_CPU1_PE0_TX_DP<7>")
	)
	(segment
		(start 72.753982 -396.401798)
		(end 72.807322 -396.83563)
		(width 0.14732)
		(layer "In15.Cu")
		(net "P5E_CPU1_PE0_TX_DP<7>")
	)
	(segment
		(start 72.561958 -395.859762)
		(end 72.615044 -396.29334)
		(width 0.14732)
		(layer "In15.Cu")
		(net "P5E_CPU1_PE0_TX_DP<7>")
	)
	(segment
		(start 72.287892 -393.632182)
		(end 72.341232 -394.064744)
		(width 0.14732)
		(layer "In15.Cu")
		(net "P5E_CPU1_PE0_TX_DP<7>")
	)
	(segment
		(start 95.098616 -221.149418)
		(end 95.098616 -221.115382)
		(width 0.0889)
		(layer "In15.Cu")
		(net "P5E_CPU1_PE0_TX_DP<7>")
	)
	(segment
		(start 72.395842 -393.492482)
		(end 72.287638 -393.631166)
		(width 0.14732)
		(layer "In15.Cu")
		(net "P5E_CPU1_PE0_TX_DP<7>")
	)
	(segment
		(start 72.533002 -394.60678)
		(end 72.424798 -394.745464)
		(width 0.14732)
		(layer "In15.Cu")
		(net "P5E_CPU1_PE0_TX_DP<7>")
	)
	(segment
		(start 93.688916 -213.930484)
		(end 93.688916 -213.929722)
		(width 0.0889)
		(layer "In15.Cu")
		(net "P5E_CPU1_PE0_TX_DP<7>")
	)
	(segment
		(start 72.670162 -395.721078)
		(end 72.561958 -395.859762)
		(width 0.14732)
		(layer "In15.Cu")
		(net "P5E_CPU1_PE0_TX_DP<7>")
	)
	(segment
		(start 72.478138 -395.179296)
		(end 72.616822 -395.287246)
		(width 0.14732)
		(layer "In15.Cu")
		(net "P5E_CPU1_PE0_TX_DP<7>")
	)
	(segment
		(start 73.054718 -400.563588)
		(end 73.349358 -400.858228)
		(width 0.14732)
		(layer "In15.Cu")
		(net "P5E_CPU1_PE0_TX_DP<7>")
	)
	(segment
		(start 94.911926 -215.92667)
		(end 94.90964 -215.925146)
		(width 0.0889)
		(layer "In15.Cu")
		(net "P5E_CPU1_PE0_TX_DP<7>")
	)
	(segment
		(start 74.515218 -252.39853)
		(end 78.265528 -309.716424)
		(width 0.14732)
		(layer "In15.Cu")
		(net "P5E_CPU1_PE0_TX_DP<7>")
	)
	(segment
		(start 72.067166 -391.836148)
		(end 72.066404 -391.836148)
		(width 0.14732)
		(layer "In15.Cu")
		(net "P5E_CPU1_PE0_TX_DP<7>")
	)
	(segment
		(start 74.579988 -250.474226)
		(end 74.515218 -252.39853)
		(width 0.14732)
		(layer "In15.Cu")
		(net "P5E_CPU1_PE0_TX_DP<7>")
	)
	(segment
		(start 95.098616 -216.260426)
		(end 95.098616 -216.25052)
		(width 0.0889)
		(layer "In15.Cu")
		(net "P5E_CPU1_PE0_TX_DP<7>")
	)
	(segment
		(start 93.688916 -213.929722)
		(end 93.68917 -213.929468)
		(width 0.0889)
		(layer "In15.Cu")
		(net "P5E_CPU1_PE0_TX_DP<7>")
	)
	(segment
		(start 72.342502 -393.05865)
		(end 72.395842 -393.492482)
		(width 0.14732)
		(layer "In15.Cu")
		(net "P5E_CPU1_PE0_TX_DP<7>")
	)
	(segment
		(start 96.32061 -223.899984)
		(end 96.321626 -223.899476)
		(width 0.0889)
		(layer "In15.Cu")
		(net "P5E_CPU1_PE0_TX_DP<7>")
	)
	(segment
		(start 71.930768 -390.726676)
		(end 72.066912 -390.832848)
		(width 0.14732)
		(layer "In15.Cu")
		(net "P5E_CPU1_PE0_TX_DP<7>")
	)
	(segment
		(start 96.038416 -222.783654)
		(end 96.038416 -222.761556)
		(width 0.0889)
		(layer "In15.Cu")
		(net "P5E_CPU1_PE0_TX_DP<7>")
	)
	(segment
		(start 83.678776 -215.19769)
		(end 79.328264 -219.334842)
		(width 0.14732)
		(layer "In15.Cu")
		(net "P5E_CPU1_PE0_TX_DP<7>")
	)
	(segment
		(start 94.90837 -215.924384)
		(end 94.905068 -215.922606)
		(width 0.0889)
		(layer "In15.Cu")
		(net "P5E_CPU1_PE0_TX_DP<7>")
	)
	(segment
		(start 72.119998 -391.26668)
		(end 72.01408 -391.40257)
		(width 0.14732)
		(layer "In15.Cu")
		(net "P5E_CPU1_PE0_TX_DP<7>")
	)
	(segment
		(start 93.527372 -212.856318)
		(end 88.001094 -212.856318)
		(width 0.14732)
		(layer "In15.Cu")
		(net "P5E_CPU1_PE0_TX_DP<7>")
	)
	(segment
		(start 93.68917 -213.214712)
		(end 93.647006 -213.172548)
		(width 0.0889)
		(layer "In15.Cu")
		(net "P5E_CPU1_PE0_TX_DP<7>")
	)
	(segment
		(start 95.859854 -222.442278)
		(end 95.850202 -222.43669)
		(width 0.0889)
		(layer "In15.Cu")
		(net "P5E_CPU1_PE0_TX_DP<7>")
	)
	(segment
		(start 72.341232 -394.064744)
		(end 72.340724 -394.064744)
		(width 0.14732)
		(layer "In15.Cu")
		(net "P5E_CPU1_PE0_TX_DP<7>")
	)
	(segment
		(start 69.954902 -326.768206)
		(end 66.910458 -334.118458)
		(width 0.14732)
		(layer "In15.Cu")
		(net "P5E_CPU1_PE0_TX_DP<7>")
	)
	(segment
		(start 72.615044 -396.29334)
		(end 72.753982 -396.401798)
		(width 0.14732)
		(layer "In15.Cu")
		(net "P5E_CPU1_PE0_TX_DP<7>")
	)
	(segment
		(start 93.647006 -213.15045)
		(end 93.647006 -212.975952)
		(width 0.14732)
		(layer "In15.Cu")
		(net "P5E_CPU1_PE0_TX_DP<7>")
	)
	(segment
		(start 66.77533 -334.892904)
		(end 67.203574 -352.280474)
		(width 0.14732)
		(layer "In15.Cu")
		(net "P5E_CPU1_PE0_TX_DP<7>")
	)
	(segment
		(start 72.287892 -393.63142)
		(end 72.287892 -393.632182)
		(width 0.14732)
		(layer "In15.Cu")
		(net "P5E_CPU1_PE0_TX_DP<7>")
	)
	(segment
		(start 73.446132 -321.117214)
		(end 69.954902 -326.768206)
		(width 0.14732)
		(layer "In15.Cu")
		(net "P5E_CPU1_PE0_TX_DP<7>")
	)
	(segment
		(start 72.01408 -391.40257)
		(end 72.067166 -391.836148)
		(width 0.14732)
		(layer "In15.Cu")
		(net "P5E_CPU1_PE0_TX_DP<7>")
	)
	(segment
		(start 95.3897 -221.628462)
		(end 95.381826 -221.62389)
		(width 0.0889)
		(layer "In15.Cu")
		(net "P5E_CPU1_PE0_TX_DP<7>")
	)
	(segment
		(start 94.158308 -214.636858)
		(end 94.158308 -214.461344)
		(width 0.0889)
		(layer "In15.Cu")
		(net "P5E_CPU1_PE0_TX_DP<7>")
	)
	(segment
		(start 72.616822 -395.287246)
		(end 72.670162 -395.721078)
		(width 0.14732)
		(layer "In15.Cu")
		(net "P5E_CPU1_PE0_TX_DP<7>")
	)
	(segment
		(start 72.340724 -394.064744)
		(end 72.479662 -394.172948)
		(width 0.14732)
		(layer "In15.Cu")
		(net "P5E_CPU1_PE0_TX_DP<7>")
	)
	(segment
		(start 72.807322 -396.83563)
		(end 72.699118 -396.974314)
		(width 0.14732)
		(layer "In15.Cu")
		(net "P5E_CPU1_PE0_TX_DP<7>")
	)
	(segment
		(start 95.381826 -221.62389)
		(end 95.38081 -221.623382)
		(width 0.0889)
		(layer "In15.Cu")
		(net "P5E_CPU1_PE0_TX_DP<7>")
	)
	(segment
		(start 96.321626 -223.251776)
		(end 96.32061 -223.251268)
		(width 0.0889)
		(layer "In15.Cu")
		(net "P5E_CPU1_PE0_TX_DP<7>")
	)
	(segment
		(start 94.920054 -215.931242)
		(end 94.911926 -215.92667)
		(width 0.0889)
		(layer "In15.Cu")
		(net "P5E_CPU1_PE0_TX_DP<7>")
	)
	(segment
		(start 72.258682 -392.378184)
		(end 72.150478 -392.516868)
		(width 0.14732)
		(layer "In15.Cu")
		(net "P5E_CPU1_PE0_TX_DP<7>")
	)
	(segment
		(start 76.079096 -233.150918)
		(end 74.579988 -250.474226)
		(width 0.14732)
		(layer "In15.Cu")
		(net "P5E_CPU1_PE0_TX_DP<7>")
	)
	(segment
		(start 72.287638 -393.631166)
		(end 72.287892 -393.63142)
		(width 0.14732)
		(layer "In15.Cu")
		(net "P5E_CPU1_PE0_TX_DP<7>")
	)
	(segment
		(start 67.203574 -352.280474)
		(end 71.930768 -390.726676)
		(width 0.14732)
		(layer "In15.Cu")
		(net "P5E_CPU1_PE0_TX_DP<7>")
	)
	(segment
		(start 94.90964 -215.925146)
		(end 94.90837 -215.924384)
		(width 0.0889)
		(layer "In15.Cu")
		(net "P5E_CPU1_PE0_TX_DP<7>")
	)
	(segment
		(start 72.066404 -391.836148)
		(end 72.205342 -391.944352)
		(width 0.14732)
		(layer "In15.Cu")
		(net "P5E_CPU1_PE0_TX_DP<7>")
	)
	(segment
		(start 93.647006 -212.975952)
		(end 93.527372 -212.856318)
		(width 0.14732)
		(layer "In15.Cu")
		(net "P5E_CPU1_PE0_TX_DP<7>")
	)
	(segment
		(start 72.204072 -392.950192)
		(end 72.203564 -392.950446)
		(width 0.14732)
		(layer "In15.Cu")
		(net "P5E_CPU1_PE0_TX_DP<7>")
	)
	(segment
		(start 96.038416 -224.404936)
		(end 96.038416 -224.373948)
		(width 0.0889)
		(layer "In15.Cu")
		(net "P5E_CPU1_PE0_TX_DP<7>")
	)
	(segment
		(start 96.916748 -224.93224)
		(end 96.827848 -224.908618)
		(width 0.0889)
		(layer "In15.Cu")
		(net "P5E_CPU1_PE0_TX_DP<7>")
	)
	(segment
		(start 95.3897 -218.372944)
		(end 95.381826 -218.368372)
		(width 0.0889)
		(layer "In15.Cu")
		(net "P5E_CPU1_PE0_TX_DP<7>")
	)
	(segment
		(start 72.424798 -394.745464)
		(end 72.478138 -395.179296)
		(width 0.14732)
		(layer "In15.Cu")
		(net "P5E_CPU1_PE0_TX_DP<7>")
	)
	(segment
		(start 72.066912 -390.832848)
		(end 72.119998 -391.26668)
		(width 0.14732)
		(layer "In15.Cu")
		(net "P5E_CPU1_PE0_TX_DP<7>")
	)
	(segment
		(start 72.150986 -392.516868)
		(end 72.204072 -392.950192)
		(width 0.14732)
		(layer "In15.Cu")
		(net "P5E_CPU1_PE0_TX_DP<7>")
	)
	(segment
		(start 96.321626 -223.899476)
		(end 96.3295 -223.894904)
		(width 0.0889)
		(layer "In15.Cu")
		(net "P5E_CPU1_PE0_TX_DP<7>")
	)
	(segment
		(start 96.3295 -223.256348)
		(end 96.321626 -223.251776)
		(width 0.0889)
		(layer "In15.Cu")
		(net "P5E_CPU1_PE0_TX_DP<7>")
	)
	(segment
		(start 93.68917 -213.929468)
		(end 93.68917 -213.214712)
		(width 0.0889)
		(layer "In15.Cu")
		(net "P5E_CPU1_PE0_TX_DP<7>")
	)
	(segment
		(start 77.748384 -222.399606)
		(end 76.079096 -233.150918)
		(width 0.14732)
		(layer "In15.Cu")
		(net "P5E_CPU1_PE0_TX_DP<7>")
	)
	(arc
		(start 95.381064 -216.739978)
		(mid 95.176729 -216.537373)
		(end 95.098616 -216.260426)
		(width 0.0889)
		(layer "In15.Cu")
		(net "P5E_CPU1_PE0_TX_DP<7>")
	)
	(arc
		(start 96.038416 -224.373948)
		(mid 96.117786 -224.100214)
		(end 96.32061 -223.899984)
		(width 0.0889)
		(layer "In15.Cu")
		(net "P5E_CPU1_PE0_TX_DP<7>")
	)
	(arc
		(start 96.827848 -224.908618)
		(mid 96.818106 -224.912771)
		(end 96.80829 -224.916746)
		(width 0.0889)
		(layer "In15.Cu")
		(net "P5E_CPU1_PE0_TX_DP<7>")
	)
	(arc
		(start 95.38081 -221.623382)
		(mid 95.177987 -221.423151)
		(end 95.098616 -221.149418)
		(width 0.0889)
		(layer "In15.Cu")
		(net "P5E_CPU1_PE0_TX_DP<7>")
	)
	(arc
		(start 93.704156 -213.969346)
		(mid 93.696193 -213.950049)
		(end 93.688916 -213.930484)
		(width 0.0889)
		(layer "In15.Cu")
		(net "P5E_CPU1_PE0_TX_DP<7>")
	)
	(arc
		(start 95.098616 -217.859864)
		(mid 95.178778 -217.587675)
		(end 95.381064 -217.388694)
		(width 0.0889)
		(layer "In15.Cu")
		(net "P5E_CPU1_PE0_TX_DP<7>")
	)
	(arc
		(start 95.381064 -217.388694)
		(mid 95.568367 -217.064336)
		(end 95.381064 -216.739978)
		(width 0.0889)
		(layer "In15.Cu")
		(net "P5E_CPU1_PE0_TX_DP<7>")
	)
	(arc
		(start 96.3295 -223.894904)
		(mid 96.508097 -223.575626)
		(end 96.3295 -223.256348)
		(width 0.0889)
		(layer "In15.Cu")
		(net "P5E_CPU1_PE0_TX_DP<7>")
	)
	(arc
		(start 95.098616 -221.115382)
		(mid 95.178778 -220.843193)
		(end 95.381064 -220.644212)
		(width 0.0889)
		(layer "In15.Cu")
		(net "P5E_CPU1_PE0_TX_DP<7>")
	)
	(arc
		(start 95.844868 -222.433642)
		(mid 95.642281 -222.227291)
		(end 95.568262 -221.94774)
		(width 0.0889)
		(layer "In15.Cu")
		(net "P5E_CPU1_PE0_TX_DP<7>")
	)
	(arc
		(start 95.381064 -219.995496)
		(mid 95.098532 -219.506148)
		(end 95.38081 -219.01658)
		(width 0.0889)
		(layer "In15.Cu")
		(net "P5E_CPU1_PE0_TX_DP<7>")
	)
	(arc
		(start 96.32061 -223.251268)
		(mid 96.119328 -223.053781)
		(end 96.038416 -222.783654)
		(width 0.0889)
		(layer "In15.Cu")
		(net "P5E_CPU1_PE0_TX_DP<7>")
	)
	(arc
		(start 95.098616 -216.25052)
		(mid 95.050937 -216.06762)
		(end 94.920054 -215.931242)
		(width 0.0889)
		(layer "In15.Cu")
		(net "P5E_CPU1_PE0_TX_DP<7>")
	)
	(arc
		(start 94.158308 -214.461344)
		(mid 94.083303 -214.345885)
		(end 93.974158 -214.261954)
		(width 0.0889)
		(layer "In15.Cu")
		(net "P5E_CPU1_PE0_TX_DP<7>")
	)
	(arc
		(start 96.80829 -224.916746)
		(mid 96.290621 -224.860579)
		(end 96.038416 -224.404936)
		(width 0.0889)
		(layer "In15.Cu")
		(net "P5E_CPU1_PE0_TX_DP<7>")
	)
	(arc
		(start 94.628462 -215.436704)
		(mid 94.580783 -215.253804)
		(end 94.4499 -215.117426)
		(width 0.0889)
		(layer "In15.Cu")
		(net "P5E_CPU1_PE0_TX_DP<7>")
	)
	(arc
		(start 95.3897 -219.0115)
		(mid 95.568176 -218.692222)
		(end 95.3897 -218.372944)
		(width 0.0889)
		(layer "In15.Cu")
		(net "P5E_CPU1_PE0_TX_DP<7>")
	)
	(arc
		(start 95.568262 -221.94774)
		(mid 95.520583 -221.76484)
		(end 95.3897 -221.628462)
		(width 0.0889)
		(layer "In15.Cu")
		(net "P5E_CPU1_PE0_TX_DP<7>")
	)
	(arc
		(start 95.38081 -218.367864)
		(mid 95.177987 -218.167633)
		(end 95.098616 -217.8939)
		(width 0.0889)
		(layer "In15.Cu")
		(net "P5E_CPU1_PE0_TX_DP<7>")
	)
	(arc
		(start 94.44101 -215.112346)
		(mid 94.237529 -214.911542)
		(end 94.158308 -214.636858)
		(width 0.0889)
		(layer "In15.Cu")
		(net "P5E_CPU1_PE0_TX_DP<7>")
	)
	(arc
		(start 93.974158 -214.261954)
		(mid 93.814086 -214.138774)
		(end 93.704156 -213.969346)
		(width 0.0889)
		(layer "In15.Cu")
		(net "P5E_CPU1_PE0_TX_DP<7>")
	)
	(arc
		(start 94.905068 -215.922606)
		(mid 94.702481 -215.716255)
		(end 94.628462 -215.436704)
		(width 0.0889)
		(layer "In15.Cu")
		(net "P5E_CPU1_PE0_TX_DP<7>")
	)
	(arc
		(start 95.381064 -220.644212)
		(mid 95.568367 -220.319854)
		(end 95.381064 -219.995496)
		(width 0.0889)
		(layer "In15.Cu")
		(net "P5E_CPU1_PE0_TX_DP<7>")
	)
	(arc
		(start 96.038416 -222.761556)
		(mid 95.990737 -222.578656)
		(end 95.859854 -222.442278)
		(width 0.0889)
		(layer "In15.Cu")
		(net "P5E_CPU1_PE0_TX_DP<7>")
	)
	(segment
		(start 95.663512 -224.925382)
		(end 95.663512 -224.389696)
		(width 0.13208)
		(layer "F.Cu")
		(net "P5E_CPU1_PE0_TX_DP<6>")
	)
	(segment
		(start 76.11364 -401.779994)
		(end 76.11364 -401.157186)
		(width 0.13208)
		(layer "F.Cu")
		(net "P5E_CPU1_PE0_TX_DP<6>")
	)
	(segment
		(start 76.437998 -402.104352)
		(end 76.11364 -401.779994)
		(width 0.13208)
		(layer "F.Cu")
		(net "P5E_CPU1_PE0_TX_DP<6>")
	)
	(segment
		(start 76.11364 -401.157186)
		(end 76.412598 -400.858228)
		(width 0.13208)
		(layer "F.Cu")
		(net "P5E_CPU1_PE0_TX_DP<6>")
	)
	(segment
		(start 95.663512 -224.389696)
		(end 95.663766 -224.389442)
		(width 0.13208)
		(layer "F.Cu")
		(net "P5E_CPU1_PE0_TX_DP<6>")
	)
	(segment
		(start 68.17487 -352.16719)
		(end 74.852276 -392.14298)
		(width 0.14732)
		(layer "In15.Cu")
		(net "P5E_CPU1_PE0_TX_DP<6>")
	)
	(segment
		(start 75.222608 -394.35786)
		(end 75.221846 -394.35786)
		(width 0.14732)
		(layer "In15.Cu")
		(net "P5E_CPU1_PE0_TX_DP<6>")
	)
	(segment
		(start 94.158816 -217.8939)
		(end 94.158816 -217.856308)
		(width 0.0889)
		(layer "In15.Cu")
		(net "P5E_CPU1_PE0_TX_DP<6>")
	)
	(segment
		(start 87.25789 -214.553292)
		(end 86.873334 -214.761572)
		(width 0.14732)
		(layer "In15.Cu")
		(net "P5E_CPU1_PE0_TX_DP<6>")
	)
	(segment
		(start 91.166696 -215.934798)
		(end 91.151964 -215.926162)
		(width 0.0889)
		(layer "In15.Cu")
		(net "P5E_CPU1_PE0_TX_DP<6>")
	)
	(segment
		(start 75.365356 -394.459968)
		(end 75.437492 -394.89126)
		(width 0.14732)
		(layer "In15.Cu")
		(net "P5E_CPU1_PE0_TX_DP<6>")
	)
	(segment
		(start 94.920054 -222.442278)
		(end 94.910402 -222.43669)
		(width 0.0889)
		(layer "In15.Cu")
		(net "P5E_CPU1_PE0_TX_DP<6>")
	)
	(segment
		(start 90.399108 -214.636858)
		(end 90.399108 -214.461344)
		(width 0.0889)
		(layer "In15.Cu")
		(net "P5E_CPU1_PE0_TX_DP<6>")
	)
	(segment
		(start 76.117958 -399.720308)
		(end 76.117958 -400.563588)
		(width 0.14732)
		(layer "In15.Cu")
		(net "P5E_CPU1_PE0_TX_DP<6>")
	)
	(segment
		(start 75.622658 -395.9987)
		(end 75.520296 -396.141956)
		(width 0.14732)
		(layer "In15.Cu")
		(net "P5E_CPU1_PE0_TX_DP<6>")
	)
	(segment
		(start 89.729564 -214.137748)
		(end 89.6874 -214.179912)
		(width 0.0889)
		(layer "In15.Cu")
		(net "P5E_CPU1_PE0_TX_DP<6>")
	)
	(segment
		(start 75.592178 -396.57274)
		(end 75.735688 -396.675102)
		(width 0.14732)
		(layer "In15.Cu")
		(net "P5E_CPU1_PE0_TX_DP<6>")
	)
	(segment
		(start 94.442026 -218.368372)
		(end 94.44101 -218.367864)
		(width 0.0889)
		(layer "In15.Cu")
		(net "P5E_CPU1_PE0_TX_DP<6>")
	)
	(segment
		(start 89.665302 -214.179912)
		(end 87.69096 -214.179912)
		(width 0.14732)
		(layer "In15.Cu")
		(net "P5E_CPU1_PE0_TX_DP<6>")
	)
	(segment
		(start 77.02042 -233.200194)
		(end 75.50404 -250.66117)
		(width 0.14732)
		(layer "In15.Cu")
		(net "P5E_CPU1_PE0_TX_DP<6>")
	)
	(segment
		(start 94.158816 -219.521532)
		(end 94.158816 -219.490544)
		(width 0.0889)
		(layer "In15.Cu")
		(net "P5E_CPU1_PE0_TX_DP<6>")
	)
	(segment
		(start 75.520296 -396.141956)
		(end 75.592178 -396.57274)
		(width 0.14732)
		(layer "In15.Cu")
		(net "P5E_CPU1_PE0_TX_DP<6>")
	)
	(segment
		(start 86.873334 -214.761572)
		(end 86.708234 -214.712296)
		(width 0.14732)
		(layer "In15.Cu")
		(net "P5E_CPU1_PE0_TX_DP<6>")
	)
	(segment
		(start 80.0862 -219.914724)
		(end 78.6511 -222.697802)
		(width 0.14732)
		(layer "In15.Cu")
		(net "P5E_CPU1_PE0_TX_DP<6>")
	)
	(segment
		(start 94.910402 -222.43669)
		(end 94.905068 -222.433642)
		(width 0.0889)
		(layer "In15.Cu")
		(net "P5E_CPU1_PE0_TX_DP<6>")
	)
	(segment
		(start 67.738752 -335.358486)
		(end 68.17487 -352.16719)
		(width 0.14732)
		(layer "In15.Cu")
		(net "P5E_CPU1_PE0_TX_DP<6>")
	)
	(segment
		(start 75.33513 -395.034516)
		(end 75.335638 -395.034516)
		(width 0.14732)
		(layer "In15.Cu")
		(net "P5E_CPU1_PE0_TX_DP<6>")
	)
	(segment
		(start 95.663766 -224.389442)
		(end 95.82023 -224.118424)
		(width 0.0889)
		(layer "In15.Cu")
		(net "P5E_CPU1_PE0_TX_DP<6>")
	)
	(segment
		(start 93.980254 -215.931242)
		(end 93.972888 -215.926924)
		(width 0.0889)
		(layer "In15.Cu")
		(net "P5E_CPU1_PE0_TX_DP<6>")
	)
	(segment
		(start 75.407012 -395.4653)
		(end 75.550522 -395.567408)
		(width 0.14732)
		(layer "In15.Cu")
		(net "P5E_CPU1_PE0_TX_DP<6>")
	)
	(segment
		(start 75.037442 -393.25042)
		(end 75.03668 -393.25042)
		(width 0.14732)
		(layer "In15.Cu")
		(net "P5E_CPU1_PE0_TX_DP<6>")
	)
	(segment
		(start 95.098616 -222.780098)
		(end 95.098616 -222.761556)
		(width 0.0889)
		(layer "In15.Cu")
		(net "P5E_CPU1_PE0_TX_DP<6>")
	)
	(segment
		(start 75.461114 -251.938536)
		(end 79.233014 -309.882794)
		(width 0.14732)
		(layer "In15.Cu")
		(net "P5E_CPU1_PE0_TX_DP<6>")
	)
	(segment
		(start 94.442026 -219.996004)
		(end 94.44101 -219.995496)
		(width 0.0889)
		(layer "In15.Cu")
		(net "P5E_CPU1_PE0_TX_DP<6>")
	)
	(segment
		(start 87.69096 -214.179912)
		(end 87.306912 -214.387938)
		(width 0.14732)
		(layer "In15.Cu")
		(net "P5E_CPU1_PE0_TX_DP<6>")
	)
	(segment
		(start 74.964798 -392.819382)
		(end 74.96556 -392.820144)
		(width 0.14732)
		(layer "In15.Cu")
		(net "P5E_CPU1_PE0_TX_DP<6>")
	)
	(segment
		(start 75.80757 -397.10614)
		(end 75.705462 -397.249396)
		(width 0.14732)
		(layer "In15.Cu")
		(net "P5E_CPU1_PE0_TX_DP<6>")
	)
	(segment
		(start 74.852276 -392.14298)
		(end 74.851514 -392.14298)
		(width 0.14732)
		(layer "In15.Cu")
		(net "P5E_CPU1_PE0_TX_DP<6>")
	)
	(segment
		(start 74.851514 -392.14298)
		(end 74.995024 -392.245088)
		(width 0.14732)
		(layer "In15.Cu")
		(net "P5E_CPU1_PE0_TX_DP<6>")
	)
	(segment
		(start 87.306912 -214.387938)
		(end 87.25789 -214.553292)
		(width 0.14732)
		(layer "In15.Cu")
		(net "P5E_CPU1_PE0_TX_DP<6>")
	)
	(segment
		(start 94.158816 -216.266014)
		(end 94.158816 -216.25052)
		(width 0.0889)
		(layer "In15.Cu")
		(net "P5E_CPU1_PE0_TX_DP<6>")
	)
	(segment
		(start 94.4499 -221.628462)
		(end 94.442026 -221.62389)
		(width 0.0889)
		(layer "In15.Cu")
		(net "P5E_CPU1_PE0_TX_DP<6>")
	)
	(segment
		(start 90.6907 -215.117426)
		(end 90.68181 -215.112346)
		(width 0.0889)
		(layer "In15.Cu")
		(net "P5E_CPU1_PE0_TX_DP<6>")
	)
	(segment
		(start 75.550522 -395.567408)
		(end 75.622658 -395.9987)
		(width 0.14732)
		(layer "In15.Cu")
		(net "P5E_CPU1_PE0_TX_DP<6>")
	)
	(segment
		(start 90.214958 -214.261954)
		(end 90.090752 -214.137748)
		(width 0.0889)
		(layer "In15.Cu")
		(net "P5E_CPU1_PE0_TX_DP<6>")
	)
	(segment
		(start 84.19084 -216.075768)
		(end 80.0862 -219.914724)
		(width 0.14732)
		(layer "In15.Cu")
		(net "P5E_CPU1_PE0_TX_DP<6>")
	)
	(segment
		(start 74.995024 -392.245088)
		(end 75.06716 -392.67638)
		(width 0.14732)
		(layer "In15.Cu")
		(net "P5E_CPU1_PE0_TX_DP<6>")
	)
	(segment
		(start 78.6511 -222.697802)
		(end 77.02042 -233.200194)
		(width 0.14732)
		(layer "In15.Cu")
		(net "P5E_CPU1_PE0_TX_DP<6>")
	)
	(segment
		(start 89.6874 -214.179912)
		(end 89.665302 -214.179912)
		(width 0.0889)
		(layer "In15.Cu")
		(net "P5E_CPU1_PE0_TX_DP<6>")
	)
	(segment
		(start 75.335638 -395.034516)
		(end 75.40752 -395.4653)
		(width 0.14732)
		(layer "In15.Cu")
		(net "P5E_CPU1_PE0_TX_DP<6>")
	)
	(segment
		(start 95.82023 -224.118424)
		(end 95.7961 -224.02927)
		(width 0.0889)
		(layer "In15.Cu")
		(net "P5E_CPU1_PE0_TX_DP<6>")
	)
	(segment
		(start 74.119994 -321.940428)
		(end 70.817994 -327.224136)
		(width 0.14732)
		(layer "In15.Cu")
		(net "P5E_CPU1_PE0_TX_DP<6>")
	)
	(segment
		(start 93.046296 -215.934798)
		(end 93.031564 -215.926162)
		(width 0.0889)
		(layer "In15.Cu")
		(net "P5E_CPU1_PE0_TX_DP<6>")
	)
	(segment
		(start 70.817994 -327.224136)
		(end 67.922902 -334.214216)
		(width 0.14732)
		(layer "In15.Cu")
		(net "P5E_CPU1_PE0_TX_DP<6>")
	)
	(segment
		(start 75.735688 -396.675102)
		(end 75.80757 -397.10614)
		(width 0.14732)
		(layer "In15.Cu")
		(net "P5E_CPU1_PE0_TX_DP<6>")
	)
	(segment
		(start 75.150472 -393.927076)
		(end 75.222608 -394.35786)
		(width 0.14732)
		(layer "In15.Cu")
		(net "P5E_CPU1_PE0_TX_DP<6>")
	)
	(segment
		(start 94.44101 -219.01658)
		(end 94.4499 -219.0115)
		(width 0.0889)
		(layer "In15.Cu")
		(net "P5E_CPU1_PE0_TX_DP<6>")
	)
	(segment
		(start 67.922902 -334.214216)
		(end 67.738752 -335.358486)
		(width 0.14732)
		(layer "In15.Cu")
		(net "P5E_CPU1_PE0_TX_DP<6>")
	)
	(segment
		(start 94.442026 -216.740486)
		(end 94.44101 -216.739978)
		(width 0.0889)
		(layer "In15.Cu")
		(net "P5E_CPU1_PE0_TX_DP<6>")
	)
	(segment
		(start 92.106496 -215.934798)
		(end 92.091764 -215.926162)
		(width 0.0889)
		(layer "In15.Cu")
		(net "P5E_CPU1_PE0_TX_DP<6>")
	)
	(segment
		(start 95.568262 -223.575626)
		(end 95.568262 -223.56699)
		(width 0.0889)
		(layer "In15.Cu")
		(net "P5E_CPU1_PE0_TX_DP<6>")
	)
	(segment
		(start 91.151202 -215.925654)
		(end 91.145868 -215.922606)
		(width 0.0889)
		(layer "In15.Cu")
		(net "P5E_CPU1_PE0_TX_DP<6>")
	)
	(segment
		(start 75.50404 -250.66117)
		(end 75.461114 -251.938536)
		(width 0.14732)
		(layer "In15.Cu")
		(net "P5E_CPU1_PE0_TX_DP<6>")
	)
	(segment
		(start 91.151964 -215.926162)
		(end 91.151202 -215.925654)
		(width 0.0889)
		(layer "In15.Cu")
		(net "P5E_CPU1_PE0_TX_DP<6>")
	)
	(segment
		(start 75.06716 -392.67638)
		(end 74.964798 -392.819382)
		(width 0.14732)
		(layer "In15.Cu")
		(net "P5E_CPU1_PE0_TX_DP<6>")
	)
	(segment
		(start 75.252326 -393.78382)
		(end 75.149964 -393.927076)
		(width 0.14732)
		(layer "In15.Cu")
		(net "P5E_CPU1_PE0_TX_DP<6>")
	)
	(segment
		(start 94.4499 -216.745058)
		(end 94.442026 -216.740486)
		(width 0.0889)
		(layer "In15.Cu")
		(net "P5E_CPU1_PE0_TX_DP<6>")
	)
	(segment
		(start 75.40752 -395.4653)
		(end 75.407012 -395.4653)
		(width 0.14732)
		(layer "In15.Cu")
		(net "P5E_CPU1_PE0_TX_DP<6>")
	)
	(segment
		(start 74.96556 -392.820144)
		(end 75.037442 -393.25042)
		(width 0.14732)
		(layer "In15.Cu")
		(net "P5E_CPU1_PE0_TX_DP<6>")
	)
	(segment
		(start 94.4499 -218.372944)
		(end 94.442026 -218.368372)
		(width 0.0889)
		(layer "In15.Cu")
		(net "P5E_CPU1_PE0_TX_DP<6>")
	)
	(segment
		(start 94.158816 -221.149418)
		(end 94.158816 -221.111826)
		(width 0.0889)
		(layer "In15.Cu")
		(net "P5E_CPU1_PE0_TX_DP<6>")
	)
	(segment
		(start 75.03668 -393.25042)
		(end 75.18019 -393.352528)
		(width 0.14732)
		(layer "In15.Cu")
		(net "P5E_CPU1_PE0_TX_DP<6>")
	)
	(segment
		(start 93.972888 -215.926924)
		(end 93.971364 -215.926162)
		(width 0.0889)
		(layer "In15.Cu")
		(net "P5E_CPU1_PE0_TX_DP<6>")
	)
	(segment
		(start 75.149964 -393.927076)
		(end 75.150472 -393.927076)
		(width 0.14732)
		(layer "In15.Cu")
		(net "P5E_CPU1_PE0_TX_DP<6>")
	)
	(segment
		(start 75.437492 -394.89126)
		(end 75.33513 -395.034516)
		(width 0.14732)
		(layer "In15.Cu")
		(net "P5E_CPU1_PE0_TX_DP<6>")
	)
	(segment
		(start 90.090752 -214.137748)
		(end 89.729564 -214.137748)
		(width 0.0889)
		(layer "In15.Cu")
		(net "P5E_CPU1_PE0_TX_DP<6>")
	)
	(segment
		(start 75.221846 -394.35786)
		(end 75.365356 -394.459968)
		(width 0.14732)
		(layer "In15.Cu")
		(net "P5E_CPU1_PE0_TX_DP<6>")
	)
	(segment
		(start 75.18019 -393.352528)
		(end 75.252326 -393.78382)
		(width 0.14732)
		(layer "In15.Cu")
		(net "P5E_CPU1_PE0_TX_DP<6>")
	)
	(segment
		(start 94.44101 -217.388694)
		(end 94.4499 -217.383614)
		(width 0.0889)
		(layer "In15.Cu")
		(net "P5E_CPU1_PE0_TX_DP<6>")
	)
	(segment
		(start 94.44101 -220.644212)
		(end 94.4499 -220.639132)
		(width 0.0889)
		(layer "In15.Cu")
		(net "P5E_CPU1_PE0_TX_DP<6>")
	)
	(segment
		(start 79.233014 -309.882794)
		(end 74.119994 -321.940428)
		(width 0.14732)
		(layer "In15.Cu")
		(net "P5E_CPU1_PE0_TX_DP<6>")
	)
	(segment
		(start 76.117958 -400.563588)
		(end 76.412598 -400.858228)
		(width 0.14732)
		(layer "In15.Cu")
		(net "P5E_CPU1_PE0_TX_DP<6>")
	)
	(segment
		(start 94.442026 -221.62389)
		(end 94.44101 -221.623382)
		(width 0.0889)
		(layer "In15.Cu")
		(net "P5E_CPU1_PE0_TX_DP<6>")
	)
	(segment
		(start 75.705462 -397.249396)
		(end 76.117958 -399.720308)
		(width 0.14732)
		(layer "In15.Cu")
		(net "P5E_CPU1_PE0_TX_DP<6>")
	)
	(segment
		(start 86.708234 -214.712296)
		(end 84.19084 -216.075768)
		(width 0.14732)
		(layer "In15.Cu")
		(net "P5E_CPU1_PE0_TX_DP<6>")
	)
	(segment
		(start 94.4499 -220.000576)
		(end 94.442026 -219.996004)
		(width 0.0889)
		(layer "In15.Cu")
		(net "P5E_CPU1_PE0_TX_DP<6>")
	)
	(arc
		(start 94.628462 -221.94774)
		(mid 94.580783 -221.76484)
		(end 94.4499 -221.628462)
		(width 0.0889)
		(layer "In15.Cu")
		(net "P5E_CPU1_PE0_TX_DP<6>")
	)
	(arc
		(start 90.68181 -215.112346)
		(mid 90.478329 -214.911542)
		(end 90.399108 -214.636858)
		(width 0.0889)
		(layer "In15.Cu")
		(net "P5E_CPU1_PE0_TX_DP<6>")
	)
	(arc
		(start 90.399108 -214.461344)
		(mid 90.324103 -214.345885)
		(end 90.214958 -214.261954)
		(width 0.0889)
		(layer "In15.Cu")
		(net "P5E_CPU1_PE0_TX_DP<6>")
	)
	(arc
		(start 95.381064 -223.251268)
		(mid 95.178778 -223.052287)
		(end 95.098616 -222.780098)
		(width 0.0889)
		(layer "In15.Cu")
		(net "P5E_CPU1_PE0_TX_DP<6>")
	)
	(arc
		(start 94.158816 -217.856308)
		(mid 94.239727 -217.58618)
		(end 94.44101 -217.388694)
		(width 0.0889)
		(layer "In15.Cu")
		(net "P5E_CPU1_PE0_TX_DP<6>")
	)
	(arc
		(start 91.717368 -215.926162)
		(mid 91.443169 -216.001997)
		(end 91.166696 -215.934798)
		(width 0.0889)
		(layer "In15.Cu")
		(net "P5E_CPU1_PE0_TX_DP<6>")
	)
	(arc
		(start 95.098616 -222.761556)
		(mid 95.050937 -222.578656)
		(end 94.920054 -222.442278)
		(width 0.0889)
		(layer "In15.Cu")
		(net "P5E_CPU1_PE0_TX_DP<6>")
	)
	(arc
		(start 90.869262 -215.436704)
		(mid 90.821583 -215.253804)
		(end 90.6907 -215.117426)
		(width 0.0889)
		(layer "In15.Cu")
		(net "P5E_CPU1_PE0_TX_DP<6>")
	)
	(arc
		(start 94.44101 -221.623382)
		(mid 94.238187 -221.423151)
		(end 94.158816 -221.149418)
		(width 0.0889)
		(layer "In15.Cu")
		(net "P5E_CPU1_PE0_TX_DP<6>")
	)
	(arc
		(start 92.657168 -215.926162)
		(mid 92.382969 -216.001997)
		(end 92.106496 -215.934798)
		(width 0.0889)
		(layer "In15.Cu")
		(net "P5E_CPU1_PE0_TX_DP<6>")
	)
	(arc
		(start 94.158816 -221.111826)
		(mid 94.239727 -220.841698)
		(end 94.44101 -220.644212)
		(width 0.0889)
		(layer "In15.Cu")
		(net "P5E_CPU1_PE0_TX_DP<6>")
	)
	(arc
		(start 95.7961 -224.02927)
		(mid 95.628346 -223.829492)
		(end 95.568262 -223.575626)
		(width 0.0889)
		(layer "In15.Cu")
		(net "P5E_CPU1_PE0_TX_DP<6>")
	)
	(arc
		(start 93.031564 -215.926162)
		(mid 92.844366 -215.876019)
		(end 92.657168 -215.926162)
		(width 0.0889)
		(layer "In15.Cu")
		(net "P5E_CPU1_PE0_TX_DP<6>")
	)
	(arc
		(start 92.091764 -215.926162)
		(mid 91.904566 -215.876019)
		(end 91.717368 -215.926162)
		(width 0.0889)
		(layer "In15.Cu")
		(net "P5E_CPU1_PE0_TX_DP<6>")
	)
	(arc
		(start 91.145868 -215.922606)
		(mid 90.943281 -215.716255)
		(end 90.869262 -215.436704)
		(width 0.0889)
		(layer "In15.Cu")
		(net "P5E_CPU1_PE0_TX_DP<6>")
	)
	(arc
		(start 94.44101 -219.995496)
		(mid 94.238187 -219.795265)
		(end 94.158816 -219.521532)
		(width 0.0889)
		(layer "In15.Cu")
		(net "P5E_CPU1_PE0_TX_DP<6>")
	)
	(arc
		(start 93.971364 -215.926162)
		(mid 93.784166 -215.876019)
		(end 93.596968 -215.926162)
		(width 0.0889)
		(layer "In15.Cu")
		(net "P5E_CPU1_PE0_TX_DP<6>")
	)
	(arc
		(start 94.44101 -218.367864)
		(mid 94.238187 -218.167633)
		(end 94.158816 -217.8939)
		(width 0.0889)
		(layer "In15.Cu")
		(net "P5E_CPU1_PE0_TX_DP<6>")
	)
	(arc
		(start 95.568262 -223.56699)
		(mid 95.515992 -223.384625)
		(end 95.381064 -223.251268)
		(width 0.0889)
		(layer "In15.Cu")
		(net "P5E_CPU1_PE0_TX_DP<6>")
	)
	(arc
		(start 94.158816 -216.25052)
		(mid 94.111137 -216.06762)
		(end 93.980254 -215.931242)
		(width 0.0889)
		(layer "In15.Cu")
		(net "P5E_CPU1_PE0_TX_DP<6>")
	)
	(arc
		(start 94.905068 -222.433642)
		(mid 94.702481 -222.227291)
		(end 94.628462 -221.94774)
		(width 0.0889)
		(layer "In15.Cu")
		(net "P5E_CPU1_PE0_TX_DP<6>")
	)
	(arc
		(start 94.4499 -217.383614)
		(mid 94.628497 -217.064336)
		(end 94.4499 -216.745058)
		(width 0.0889)
		(layer "In15.Cu")
		(net "P5E_CPU1_PE0_TX_DP<6>")
	)
	(arc
		(start 94.158816 -219.490544)
		(mid 94.238186 -219.21681)
		(end 94.44101 -219.01658)
		(width 0.0889)
		(layer "In15.Cu")
		(net "P5E_CPU1_PE0_TX_DP<6>")
	)
	(arc
		(start 94.4499 -220.639132)
		(mid 94.628497 -220.319854)
		(end 94.4499 -220.000576)
		(width 0.0889)
		(layer "In15.Cu")
		(net "P5E_CPU1_PE0_TX_DP<6>")
	)
	(arc
		(start 94.44101 -216.739978)
		(mid 94.238187 -216.539747)
		(end 94.158816 -216.266014)
		(width 0.0889)
		(layer "In15.Cu")
		(net "P5E_CPU1_PE0_TX_DP<6>")
	)
	(arc
		(start 93.596968 -215.926162)
		(mid 93.322769 -216.001997)
		(end 93.046296 -215.934798)
		(width 0.0889)
		(layer "In15.Cu")
		(net "P5E_CPU1_PE0_TX_DP<6>")
	)
	(arc
		(start 94.4499 -219.0115)
		(mid 94.628376 -218.692222)
		(end 94.4499 -218.372944)
		(width 0.0889)
		(layer "In15.Cu")
		(net "P5E_CPU1_PE0_TX_DP<6>")
	)
	(segment
		(start 95.193612 -225.738944)
		(end 95.193612 -225.203258)
		(width 0.13208)
		(layer "F.Cu")
		(net "P5E_CPU1_PE0_TX_DP<5>")
	)
	(segment
		(start 79.501238 -402.104352)
		(end 79.17688 -401.779994)
		(width 0.13208)
		(layer "F.Cu")
		(net "P5E_CPU1_PE0_TX_DP<5>")
	)
	(segment
		(start 95.193866 -225.739198)
		(end 95.193612 -225.738944)
		(width 0.13208)
		(layer "F.Cu")
		(net "P5E_CPU1_PE0_TX_DP<5>")
	)
	(segment
		(start 79.17688 -401.157186)
		(end 79.475838 -400.858228)
		(width 0.13208)
		(layer "F.Cu")
		(net "P5E_CPU1_PE0_TX_DP<5>")
	)
	(segment
		(start 79.17688 -401.779994)
		(end 79.17688 -401.157186)
		(width 0.13208)
		(layer "F.Cu")
		(net "P5E_CPU1_PE0_TX_DP<5>")
	)
	(segment
		(start 93.5101 -218.372944)
		(end 93.502226 -218.368372)
		(width 0.0889)
		(layer "In15.Cu")
		(net "P5E_CPU1_PE0_TX_DP<5>")
	)
	(segment
		(start 85.027516 -216.731596)
		(end 84.831428 -216.80932)
		(width 0.14732)
		(layer "In15.Cu")
		(net "P5E_CPU1_PE0_TX_DP<5>")
	)
	(segment
		(start 78.700884 -396.711932)
		(end 78.7908 -397.139668)
		(width 0.14732)
		(layer "In15.Cu")
		(net "P5E_CPU1_PE0_TX_DP<5>")
	)
	(segment
		(start 94.158816 -222.783654)
		(end 94.158816 -222.761556)
		(width 0.0889)
		(layer "In15.Cu")
		(net "P5E_CPU1_PE0_TX_DP<5>")
	)
	(segment
		(start 68.733162 -335.507838)
		(end 69.215 -352.209862)
		(width 0.14732)
		(layer "In15.Cu")
		(net "P5E_CPU1_PE0_TX_DP<5>")
	)
	(segment
		(start 95.193612 -225.203258)
		(end 95.037148 -224.93224)
		(width 0.0889)
		(layer "In15.Cu")
		(net "P5E_CPU1_PE0_TX_DP<5>")
	)
	(segment
		(start 78.124304 -258.7371)
		(end 78.123796 -258.7371)
		(width 0.14732)
		(layer "In15.Cu")
		(net "P5E_CPU1_PE0_TX_DP<5>")
	)
	(segment
		(start 78.003146 -233.628692)
		(end 78.205838 -244.720364)
		(width 0.14732)
		(layer "In15.Cu")
		(net "P5E_CPU1_PE0_TX_DP<5>")
	)
	(segment
		(start 78.123796 -258.7371)
		(end 77.416914 -266.59586)
		(width 0.14732)
		(layer "In15.Cu")
		(net "P5E_CPU1_PE0_TX_DP<5>")
	)
	(segment
		(start 85.26526 -216.731596)
		(end 85.027516 -216.731596)
		(width 0.14732)
		(layer "In15.Cu")
		(net "P5E_CPU1_PE0_TX_DP<5>")
	)
	(segment
		(start 78.091284 -394.418058)
		(end 78.09103 -394.418312)
		(width 0.14732)
		(layer "In15.Cu")
		(net "P5E_CPU1_PE0_TX_DP<5>")
	)
	(segment
		(start 78.469744 -395.613382)
		(end 78.55966 -396.041118)
		(width 0.14732)
		(layer "In15.Cu")
		(net "P5E_CPU1_PE0_TX_DP<5>")
	)
	(segment
		(start 78.32217 -395.517116)
		(end 78.469744 -395.613382)
		(width 0.14732)
		(layer "In15.Cu")
		(net "P5E_CPU1_PE0_TX_DP<5>")
	)
	(segment
		(start 89.742264 -216.739978)
		(end 89.733882 -216.735152)
		(width 0.0889)
		(layer "In15.Cu")
		(net "P5E_CPU1_PE0_TX_DP<5>")
	)
	(segment
		(start 78.737968 -247.572022)
		(end 80.3529 -250.58878)
		(width 0.14732)
		(layer "In15.Cu")
		(net "P5E_CPU1_PE0_TX_DP<5>")
	)
	(segment
		(start 80.18526 -310.074818)
		(end 74.668634 -323.182488)
		(width 0.14732)
		(layer "In15.Cu")
		(net "P5E_CPU1_PE0_TX_DP<5>")
	)
	(segment
		(start 80.3529 -250.58878)
		(end 80.64627 -251.296932)
		(width 0.14732)
		(layer "In15.Cu")
		(net "P5E_CPU1_PE0_TX_DP<5>")
	)
	(segment
		(start 69.215 -352.209862)
		(end 69.215254 -352.209862)
		(width 0.14732)
		(layer "In15.Cu")
		(net "P5E_CPU1_PE0_TX_DP<5>")
	)
	(segment
		(start 78.55331 -396.61592)
		(end 78.700884 -396.711932)
		(width 0.14732)
		(layer "In15.Cu")
		(net "P5E_CPU1_PE0_TX_DP<5>")
	)
	(segment
		(start 95.037148 -224.93224)
		(end 94.948248 -224.908618)
		(width 0.0889)
		(layer "In15.Cu")
		(net "P5E_CPU1_PE0_TX_DP<5>")
	)
	(segment
		(start 78.55966 -396.041118)
		(end 78.463648 -396.188438)
		(width 0.14732)
		(layer "In15.Cu")
		(net "P5E_CPU1_PE0_TX_DP<5>")
	)
	(segment
		(start 90.307414 -216.739978)
		(end 90.297 -216.746074)
		(width 0.0889)
		(layer "In15.Cu")
		(net "P5E_CPU1_PE0_TX_DP<5>")
	)
	(segment
		(start 87.877142 -216.748614)
		(end 87.86241 -216.739978)
		(width 0.0889)
		(layer "In15.Cu")
		(net "P5E_CPU1_PE0_TX_DP<5>")
	)
	(segment
		(start 93.50121 -219.01658)
		(end 93.5101 -219.0115)
		(width 0.0889)
		(layer "In15.Cu")
		(net "P5E_CPU1_PE0_TX_DP<5>")
	)
	(segment
		(start 78.463648 -396.188438)
		(end 78.55331 -396.61592)
		(width 0.14732)
		(layer "In15.Cu")
		(net "P5E_CPU1_PE0_TX_DP<5>")
	)
	(segment
		(start 79.181198 -400.563588)
		(end 79.475838 -400.858228)
		(width 0.14732)
		(layer "In15.Cu")
		(net "P5E_CPU1_PE0_TX_DP<5>")
	)
	(segment
		(start 93.040454 -217.559128)
		(end 93.032326 -217.554556)
		(width 0.0889)
		(layer "In15.Cu")
		(net "P5E_CPU1_PE0_TX_DP<5>")
	)
	(segment
		(start 92.187014 -216.739978)
		(end 92.1766 -216.746074)
		(width 0.0889)
		(layer "In15.Cu")
		(net "P5E_CPU1_PE0_TX_DP<5>")
	)
	(segment
		(start 78.238604 -394.514578)
		(end 78.32852 -394.942314)
		(width 0.14732)
		(layer "In15.Cu")
		(net "P5E_CPU1_PE0_TX_DP<5>")
	)
	(segment
		(start 94.158816 -224.404936)
		(end 94.158816 -224.373948)
		(width 0.0889)
		(layer "In15.Cu")
		(net "P5E_CPU1_PE0_TX_DP<5>")
	)
	(segment
		(start 74.668634 -323.182488)
		(end 71.783448 -327.568814)
		(width 0.14732)
		(layer "In15.Cu")
		(net "P5E_CPU1_PE0_TX_DP<5>")
	)
	(segment
		(start 80.887316 -220.508322)
		(end 79.713582 -222.795084)
		(width 0.14732)
		(layer "In15.Cu")
		(net "P5E_CPU1_PE0_TX_DP<5>")
	)
	(segment
		(start 93.5101 -221.628462)
		(end 93.50121 -221.623382)
		(width 0.0889)
		(layer "In15.Cu")
		(net "P5E_CPU1_PE0_TX_DP<5>")
	)
	(segment
		(start 78.7908 -397.139668)
		(end 78.694788 -397.287242)
		(width 0.14732)
		(layer "In15.Cu")
		(net "P5E_CPU1_PE0_TX_DP<5>")
	)
	(segment
		(start 94.44101 -223.899984)
		(end 94.442026 -223.899476)
		(width 0.0889)
		(layer "In15.Cu")
		(net "P5E_CPU1_PE0_TX_DP<5>")
	)
	(segment
		(start 85.287358 -216.731596)
		(end 85.26526 -216.731596)
		(width 0.0889)
		(layer "In15.Cu")
		(net "P5E_CPU1_PE0_TX_DP<5>")
	)
	(segment
		(start 92.748862 -217.071956)
		(end 92.748862 -217.064336)
		(width 0.0889)
		(layer "In15.Cu")
		(net "P5E_CPU1_PE0_TX_DP<5>")
	)
	(segment
		(start 79.713582 -222.795084)
		(end 78.003146 -233.628692)
		(width 0.14732)
		(layer "In15.Cu")
		(net "P5E_CPU1_PE0_TX_DP<5>")
	)
	(segment
		(start 84.831428 -216.80932)
		(end 80.887316 -220.508322)
		(width 0.14732)
		(layer "In15.Cu")
		(net "P5E_CPU1_PE0_TX_DP<5>")
	)
	(segment
		(start 93.980254 -222.442278)
		(end 93.970602 -222.43669)
		(width 0.0889)
		(layer "In15.Cu")
		(net "P5E_CPU1_PE0_TX_DP<5>")
	)
	(segment
		(start 78.32852 -394.942314)
		(end 78.232508 -395.089634)
		(width 0.14732)
		(layer "In15.Cu")
		(net "P5E_CPU1_PE0_TX_DP<5>")
	)
	(segment
		(start 94.4499 -223.256348)
		(end 94.442026 -223.251776)
		(width 0.0889)
		(layer "In15.Cu")
		(net "P5E_CPU1_PE0_TX_DP<5>")
	)
	(segment
		(start 94.442026 -223.251776)
		(end 94.44101 -223.251268)
		(width 0.0889)
		(layer "In15.Cu")
		(net "P5E_CPU1_PE0_TX_DP<5>")
	)
	(segment
		(start 77.416914 -266.59586)
		(end 80.18526 -310.074818)
		(width 0.14732)
		(layer "In15.Cu")
		(net "P5E_CPU1_PE0_TX_DP<5>")
	)
	(segment
		(start 78.232508 -395.089634)
		(end 78.32217 -395.517116)
		(width 0.14732)
		(layer "In15.Cu")
		(net "P5E_CPU1_PE0_TX_DP<5>")
	)
	(segment
		(start 79.181198 -399.600928)
		(end 79.181198 -400.563588)
		(width 0.14732)
		(layer "In15.Cu")
		(net "P5E_CPU1_PE0_TX_DP<5>")
	)
	(segment
		(start 92.5703 -216.745058)
		(end 92.56141 -216.739978)
		(width 0.0889)
		(layer "In15.Cu")
		(net "P5E_CPU1_PE0_TX_DP<5>")
	)
	(segment
		(start 88.816942 -216.748614)
		(end 88.80221 -216.739978)
		(width 0.0889)
		(layer "In15.Cu")
		(net "P5E_CPU1_PE0_TX_DP<5>")
	)
	(segment
		(start 80.64627 -251.296932)
		(end 80.64627 -252.26899)
		(width 0.14732)
		(layer "In15.Cu")
		(net "P5E_CPU1_PE0_TX_DP<5>")
	)
	(segment
		(start 85.329522 -216.689432)
		(end 85.287358 -216.731596)
		(width 0.0889)
		(layer "In15.Cu")
		(net "P5E_CPU1_PE0_TX_DP<5>")
	)
	(segment
		(start 78.09103 -394.418312)
		(end 78.238604 -394.514578)
		(width 0.14732)
		(layer "In15.Cu")
		(net "P5E_CPU1_PE0_TX_DP<5>")
	)
	(segment
		(start 93.032326 -217.554556)
		(end 93.031564 -217.554048)
		(width 0.0889)
		(layer "In15.Cu")
		(net "P5E_CPU1_PE0_TX_DP<5>")
	)
	(segment
		(start 78.694788 -397.287242)
		(end 79.181198 -399.600928)
		(width 0.14732)
		(layer "In15.Cu")
		(net "P5E_CPU1_PE0_TX_DP<5>")
	)
	(segment
		(start 71.783448 -327.568814)
		(end 68.881498 -334.575404)
		(width 0.14732)
		(layer "In15.Cu")
		(net "P5E_CPU1_PE0_TX_DP<5>")
	)
	(segment
		(start 94.442026 -223.899476)
		(end 94.4499 -223.894904)
		(width 0.0889)
		(layer "In15.Cu")
		(net "P5E_CPU1_PE0_TX_DP<5>")
	)
	(segment
		(start 69.215254 -352.209862)
		(end 78.091284 -394.418058)
		(width 0.14732)
		(layer "In15.Cu")
		(net "P5E_CPU1_PE0_TX_DP<5>")
	)
	(segment
		(start 93.219016 -221.149418)
		(end 93.219016 -221.115382)
		(width 0.0889)
		(layer "In15.Cu")
		(net "P5E_CPU1_PE0_TX_DP<5>")
	)
	(segment
		(start 80.64627 -252.26899)
		(end 80.645762 -252.268736)
		(width 0.14732)
		(layer "In15.Cu")
		(net "P5E_CPU1_PE0_TX_DP<5>")
	)
	(segment
		(start 68.881498 -334.575404)
		(end 68.733162 -335.507838)
		(width 0.14732)
		(layer "In15.Cu")
		(net "P5E_CPU1_PE0_TX_DP<5>")
	)
	(segment
		(start 91.247468 -216.739978)
		(end 91.237054 -216.746074)
		(width 0.0889)
		(layer "In15.Cu")
		(net "P5E_CPU1_PE0_TX_DP<5>")
	)
	(segment
		(start 86.735412 -216.689432)
		(end 85.329522 -216.689432)
		(width 0.0889)
		(layer "In15.Cu")
		(net "P5E_CPU1_PE0_TX_DP<5>")
	)
	(segment
		(start 80.645762 -252.268736)
		(end 78.124304 -258.7371)
		(width 0.14732)
		(layer "In15.Cu")
		(net "P5E_CPU1_PE0_TX_DP<5>")
	)
	(segment
		(start 93.970602 -222.43669)
		(end 93.965268 -222.433642)
		(width 0.0889)
		(layer "In15.Cu")
		(net "P5E_CPU1_PE0_TX_DP<5>")
	)
	(segment
		(start 93.502226 -218.368372)
		(end 93.50121 -218.367864)
		(width 0.0889)
		(layer "In15.Cu")
		(net "P5E_CPU1_PE0_TX_DP<5>")
	)
	(segment
		(start 93.219016 -217.8939)
		(end 93.219016 -217.878406)
		(width 0.0889)
		(layer "In15.Cu")
		(net "P5E_CPU1_PE0_TX_DP<5>")
	)
	(segment
		(start 78.205838 -244.720364)
		(end 78.737968 -247.572022)
		(width 0.14732)
		(layer "In15.Cu")
		(net "P5E_CPU1_PE0_TX_DP<5>")
	)
	(arc
		(start 94.158816 -224.373948)
		(mid 94.238186 -224.100214)
		(end 94.44101 -223.899984)
		(width 0.0889)
		(layer "In15.Cu")
		(net "P5E_CPU1_PE0_TX_DP<5>")
	)
	(arc
		(start 94.4499 -223.894904)
		(mid 94.628497 -223.575626)
		(end 94.4499 -223.256348)
		(width 0.0889)
		(layer "In15.Cu")
		(net "P5E_CPU1_PE0_TX_DP<5>")
	)
	(arc
		(start 91.237054 -216.746074)
		(mid 90.958622 -216.81592)
		(end 90.68181 -216.739978)
		(width 0.0889)
		(layer "In15.Cu")
		(net "P5E_CPU1_PE0_TX_DP<5>")
	)
	(arc
		(start 93.5101 -219.0115)
		(mid 93.688576 -218.692222)
		(end 93.5101 -218.372944)
		(width 0.0889)
		(layer "In15.Cu")
		(net "P5E_CPU1_PE0_TX_DP<5>")
	)
	(arc
		(start 93.219016 -221.115382)
		(mid 93.299178 -220.843193)
		(end 93.501464 -220.644212)
		(width 0.0889)
		(layer "In15.Cu")
		(net "P5E_CPU1_PE0_TX_DP<5>")
	)
	(arc
		(start 93.501464 -220.644212)
		(mid 93.688767 -220.319854)
		(end 93.501464 -219.995496)
		(width 0.0889)
		(layer "In15.Cu")
		(net "P5E_CPU1_PE0_TX_DP<5>")
	)
	(arc
		(start 93.219016 -217.878406)
		(mid 93.171337 -217.695506)
		(end 93.040454 -217.559128)
		(width 0.0889)
		(layer "In15.Cu")
		(net "P5E_CPU1_PE0_TX_DP<5>")
	)
	(arc
		(start 92.1766 -216.746074)
		(mid 91.898422 -216.815797)
		(end 91.621864 -216.739978)
		(width 0.0889)
		(layer "In15.Cu")
		(net "P5E_CPU1_PE0_TX_DP<5>")
	)
	(arc
		(start 93.501464 -219.995496)
		(mid 93.218932 -219.506148)
		(end 93.50121 -219.01658)
		(width 0.0889)
		(layer "In15.Cu")
		(net "P5E_CPU1_PE0_TX_DP<5>")
	)
	(arc
		(start 94.44101 -223.251268)
		(mid 94.239728 -223.053781)
		(end 94.158816 -222.783654)
		(width 0.0889)
		(layer "In15.Cu")
		(net "P5E_CPU1_PE0_TX_DP<5>")
	)
	(arc
		(start 92.748862 -217.064336)
		(mid 92.701183 -216.881436)
		(end 92.5703 -216.745058)
		(width 0.0889)
		(layer "In15.Cu")
		(net "P5E_CPU1_PE0_TX_DP<5>")
	)
	(arc
		(start 89.367614 -216.739978)
		(mid 89.093415 -216.815813)
		(end 88.816942 -216.748614)
		(width 0.0889)
		(layer "In15.Cu")
		(net "P5E_CPU1_PE0_TX_DP<5>")
	)
	(arc
		(start 88.427814 -216.739978)
		(mid 88.153615 -216.815813)
		(end 87.877142 -216.748614)
		(width 0.0889)
		(layer "In15.Cu")
		(net "P5E_CPU1_PE0_TX_DP<5>")
	)
	(arc
		(start 94.948248 -224.908618)
		(mid 94.938508 -224.912775)
		(end 94.92869 -224.916746)
		(width 0.0889)
		(layer "In15.Cu")
		(net "P5E_CPU1_PE0_TX_DP<5>")
	)
	(arc
		(start 94.158816 -222.761556)
		(mid 94.111137 -222.578656)
		(end 93.980254 -222.442278)
		(width 0.0889)
		(layer "In15.Cu")
		(net "P5E_CPU1_PE0_TX_DP<5>")
	)
	(arc
		(start 88.80221 -216.739978)
		(mid 88.615012 -216.689835)
		(end 88.427814 -216.739978)
		(width 0.0889)
		(layer "In15.Cu")
		(net "P5E_CPU1_PE0_TX_DP<5>")
	)
	(arc
		(start 91.621864 -216.739978)
		(mid 91.434666 -216.689835)
		(end 91.247468 -216.739978)
		(width 0.0889)
		(layer "In15.Cu")
		(net "P5E_CPU1_PE0_TX_DP<5>")
	)
	(arc
		(start 93.50121 -218.367864)
		(mid 93.298387 -218.167633)
		(end 93.219016 -217.8939)
		(width 0.0889)
		(layer "In15.Cu")
		(net "P5E_CPU1_PE0_TX_DP<5>")
	)
	(arc
		(start 86.937342 -216.748614)
		(mid 86.840615 -216.704562)
		(end 86.735412 -216.689432)
		(width 0.0889)
		(layer "In15.Cu")
		(net "P5E_CPU1_PE0_TX_DP<5>")
	)
	(arc
		(start 94.44101 -224.8789)
		(mid 94.238187 -224.678669)
		(end 94.158816 -224.404936)
		(width 0.0889)
		(layer "In15.Cu")
		(net "P5E_CPU1_PE0_TX_DP<5>")
	)
	(arc
		(start 93.50121 -221.623382)
		(mid 93.298387 -221.423151)
		(end 93.219016 -221.149418)
		(width 0.0889)
		(layer "In15.Cu")
		(net "P5E_CPU1_PE0_TX_DP<5>")
	)
	(arc
		(start 89.733882 -216.735152)
		(mid 89.55012 -216.689752)
		(end 89.367614 -216.739978)
		(width 0.0889)
		(layer "In15.Cu")
		(net "P5E_CPU1_PE0_TX_DP<5>")
	)
	(arc
		(start 94.92869 -224.916746)
		(mid 94.680538 -224.953361)
		(end 94.44101 -224.8789)
		(width 0.0889)
		(layer "In15.Cu")
		(net "P5E_CPU1_PE0_TX_DP<5>")
	)
	(arc
		(start 93.031564 -217.554048)
		(mid 92.826492 -217.350369)
		(end 92.748862 -217.071956)
		(width 0.0889)
		(layer "In15.Cu")
		(net "P5E_CPU1_PE0_TX_DP<5>")
	)
	(arc
		(start 93.965268 -222.433642)
		(mid 93.762681 -222.227291)
		(end 93.688662 -221.94774)
		(width 0.0889)
		(layer "In15.Cu")
		(net "P5E_CPU1_PE0_TX_DP<5>")
	)
	(arc
		(start 92.56141 -216.739978)
		(mid 92.374212 -216.689835)
		(end 92.187014 -216.739978)
		(width 0.0889)
		(layer "In15.Cu")
		(net "P5E_CPU1_PE0_TX_DP<5>")
	)
	(arc
		(start 87.488014 -216.739978)
		(mid 87.213815 -216.815813)
		(end 86.937342 -216.748614)
		(width 0.0889)
		(layer "In15.Cu")
		(net "P5E_CPU1_PE0_TX_DP<5>")
	)
	(arc
		(start 90.68181 -216.739978)
		(mid 90.494612 -216.689835)
		(end 90.307414 -216.739978)
		(width 0.0889)
		(layer "In15.Cu")
		(net "P5E_CPU1_PE0_TX_DP<5>")
	)
	(arc
		(start 93.688662 -221.94774)
		(mid 93.640983 -221.76484)
		(end 93.5101 -221.628462)
		(width 0.0889)
		(layer "In15.Cu")
		(net "P5E_CPU1_PE0_TX_DP<5>")
	)
	(arc
		(start 90.297 -216.746074)
		(mid 90.018822 -216.815797)
		(end 89.742264 -216.739978)
		(width 0.0889)
		(layer "In15.Cu")
		(net "P5E_CPU1_PE0_TX_DP<5>")
	)
	(arc
		(start 87.86241 -216.739978)
		(mid 87.675212 -216.689835)
		(end 87.488014 -216.739978)
		(width 0.0889)
		(layer "In15.Cu")
		(net "P5E_CPU1_PE0_TX_DP<5>")
	)
	(segment
		(start 82.564478 -402.104352)
		(end 82.24012 -401.779994)
		(width 0.13208)
		(layer "F.Cu")
		(net "P5E_CPU1_PE0_TX_DP<4>")
	)
	(segment
		(start 82.24012 -401.779994)
		(end 82.24012 -401.157186)
		(width 0.13208)
		(layer "F.Cu")
		(net "P5E_CPU1_PE0_TX_DP<4>")
	)
	(segment
		(start 93.784166 -224.925128)
		(end 93.784166 -224.389442)
		(width 0.13208)
		(layer "F.Cu")
		(net "P5E_CPU1_PE0_TX_DP<4>")
	)
	(segment
		(start 93.783912 -224.925382)
		(end 93.784166 -224.925128)
		(width 0.13208)
		(layer "F.Cu")
		(net "P5E_CPU1_PE0_TX_DP<4>")
	)
	(segment
		(start 82.24012 -401.157186)
		(end 82.539078 -400.858228)
		(width 0.13208)
		(layer "F.Cu")
		(net "P5E_CPU1_PE0_TX_DP<4>")
	)
	(segment
		(start 84.502244 -219.356686)
		(end 84.131912 -219.588842)
		(width 0.14732)
		(layer "In15.Cu")
		(net "P5E_CPU1_PE0_TX_DP<4>")
	)
	(segment
		(start 87.27567 -219.092018)
		(end 87.015828 -218.832176)
		(width 0.0889)
		(layer "In15.Cu")
		(net "P5E_CPU1_PE0_TX_DP<4>")
	)
	(segment
		(start 80.765396 -393.268962)
		(end 80.87233 -393.692888)
		(width 0.14732)
		(layer "In15.Cu")
		(net "P5E_CPU1_PE0_TX_DP<4>")
	)
	(segment
		(start 93.033088 -222.43796)
		(end 93.031564 -222.437198)
		(width 0.0889)
		(layer "In15.Cu")
		(net "P5E_CPU1_PE0_TX_DP<4>")
	)
	(segment
		(start 79.045308 -258.950968)
		(end 79.044546 -258.953254)
		(width 0.14732)
		(layer "In15.Cu")
		(net "P5E_CPU1_PE0_TX_DP<4>")
	)
	(segment
		(start 92.5703 -221.628462)
		(end 92.562426 -221.62389)
		(width 0.0889)
		(layer "In15.Cu")
		(net "P5E_CPU1_PE0_TX_DP<4>")
	)
	(segment
		(start 81.581752 -252.445012)
		(end 81.581244 -252.445012)
		(width 0.14732)
		(layer "In15.Cu")
		(net "P5E_CPU1_PE0_TX_DP<4>")
	)
	(segment
		(start 84.131912 -219.588842)
		(end 83.963764 -219.550234)
		(width 0.14732)
		(layer "In15.Cu")
		(net "P5E_CPU1_PE0_TX_DP<4>")
	)
	(segment
		(start 82.244438 -400.563588)
		(end 82.539078 -400.858228)
		(width 0.14732)
		(layer "In15.Cu")
		(net "P5E_CPU1_PE0_TX_DP<4>")
	)
	(segment
		(start 93.030802 -222.43669)
		(end 93.025468 -222.433642)
		(width 0.0889)
		(layer "In15.Cu")
		(net "P5E_CPU1_PE0_TX_DP<4>")
	)
	(segment
		(start 78.355444 -266.608052)
		(end 81.138014 -310.314594)
		(width 0.14732)
		(layer "In15.Cu")
		(net "P5E_CPU1_PE0_TX_DP<4>")
	)
	(segment
		(start 69.800724 -334.836262)
		(end 69.683376 -335.55686)
		(width 0.14732)
		(layer "In15.Cu")
		(net "P5E_CPU1_PE0_TX_DP<4>")
	)
	(segment
		(start 81.040224 -394.357606)
		(end 81.147158 -394.781532)
		(width 0.14732)
		(layer "In15.Cu")
		(net "P5E_CPU1_PE0_TX_DP<4>")
	)
	(segment
		(start 81.147158 -394.781532)
		(end 81.056988 -394.932662)
		(width 0.14732)
		(layer "In15.Cu")
		(net "P5E_CPU1_PE0_TX_DP<4>")
	)
	(segment
		(start 80.78216 -393.844018)
		(end 80.782668 -393.844018)
		(width 0.14732)
		(layer "In15.Cu")
		(net "P5E_CPU1_PE0_TX_DP<4>")
	)
	(segment
		(start 80.61452 -393.178792)
		(end 80.614012 -393.178792)
		(width 0.14732)
		(layer "In15.Cu")
		(net "P5E_CPU1_PE0_TX_DP<4>")
	)
	(segment
		(start 81.64576 -221.309692)
		(end 80.736694 -222.981012)
		(width 0.14732)
		(layer "In15.Cu")
		(net "P5E_CPU1_PE0_TX_DP<4>")
	)
	(segment
		(start 81.438496 -396.444724)
		(end 81.58988 -396.534894)
		(width 0.14732)
		(layer "In15.Cu")
		(net "P5E_CPU1_PE0_TX_DP<4>")
	)
	(segment
		(start 79.18958 -244.879622)
		(end 79.624936 -247.255792)
		(width 0.14732)
		(layer "In15.Cu")
		(net "P5E_CPU1_PE0_TX_DP<4>")
	)
	(segment
		(start 82.236056 -399.604738)
		(end 82.244438 -399.672048)
		(width 0.14732)
		(layer "In15.Cu")
		(net "P5E_CPU1_PE0_TX_DP<4>")
	)
	(segment
		(start 81.194402 -250.19)
		(end 81.581752 -251.125482)
		(width 0.14732)
		(layer "In15.Cu")
		(net "P5E_CPU1_PE0_TX_DP<4>")
	)
	(segment
		(start 72.511666 -328.291698)
		(end 72.511412 -328.292206)
		(width 0.14732)
		(layer "In15.Cu")
		(net "P5E_CPU1_PE0_TX_DP<4>")
	)
	(segment
		(start 79.044546 -258.953254)
		(end 79.044292 -258.953254)
		(width 0.14732)
		(layer "In15.Cu")
		(net "P5E_CPU1_PE0_TX_DP<4>")
	)
	(segment
		(start 81.696814 -396.95882)
		(end 81.606644 -397.10995)
		(width 0.14732)
		(layer "In15.Cu")
		(net "P5E_CPU1_PE0_TX_DP<4>")
	)
	(segment
		(start 93.688662 -223.575626)
		(end 93.688662 -223.56699)
		(width 0.0889)
		(layer "In15.Cu")
		(net "P5E_CPU1_PE0_TX_DP<4>")
	)
	(segment
		(start 81.562194 -252.494034)
		(end 79.045308 -258.950968)
		(width 0.14732)
		(layer "In15.Cu")
		(net "P5E_CPU1_PE0_TX_DP<4>")
	)
	(segment
		(start 93.784166 -224.389442)
		(end 93.94063 -224.118424)
		(width 0.0889)
		(layer "In15.Cu")
		(net "P5E_CPU1_PE0_TX_DP<4>")
	)
	(segment
		(start 92.562426 -221.62389)
		(end 92.56141 -221.623382)
		(width 0.0889)
		(layer "In15.Cu")
		(net "P5E_CPU1_PE0_TX_DP<4>")
	)
	(segment
		(start 69.683376 -335.55686)
		(end 70.205854 -351.920048)
		(width 0.14732)
		(layer "In15.Cu")
		(net "P5E_CPU1_PE0_TX_DP<4>")
	)
	(segment
		(start 93.94063 -224.118424)
		(end 93.9165 -224.02927)
		(width 0.0889)
		(layer "In15.Cu")
		(net "P5E_CPU1_PE0_TX_DP<4>")
	)
	(segment
		(start 83.963764 -219.550234)
		(end 82.347054 -220.563694)
		(width 0.14732)
		(layer "In15.Cu")
		(net "P5E_CPU1_PE0_TX_DP<4>")
	)
	(segment
		(start 80.782668 -393.844018)
		(end 80.889348 -394.267436)
		(width 0.14732)
		(layer "In15.Cu")
		(net "P5E_CPU1_PE0_TX_DP<4>")
	)
	(segment
		(start 92.5703 -220.000576)
		(end 92.562426 -219.996004)
		(width 0.0889)
		(layer "In15.Cu")
		(net "P5E_CPU1_PE0_TX_DP<4>")
	)
	(segment
		(start 80.889348 -394.267436)
		(end 80.88884 -394.267436)
		(width 0.14732)
		(layer "In15.Cu")
		(net "P5E_CPU1_PE0_TX_DP<4>")
	)
	(segment
		(start 92.562426 -219.996004)
		(end 92.56141 -219.995496)
		(width 0.0889)
		(layer "In15.Cu")
		(net "P5E_CPU1_PE0_TX_DP<4>")
	)
	(segment
		(start 92.100654 -219.18676)
		(end 92.093288 -219.182442)
		(width 0.0889)
		(layer "In15.Cu")
		(net "P5E_CPU1_PE0_TX_DP<4>")
	)
	(segment
		(start 92.279216 -219.521532)
		(end 92.279216 -219.506038)
		(width 0.0889)
		(layer "In15.Cu")
		(net "P5E_CPU1_PE0_TX_DP<4>")
	)
	(segment
		(start 79.044292 -258.953254)
		(end 78.355444 -266.608052)
		(width 0.14732)
		(layer "In15.Cu")
		(net "P5E_CPU1_PE0_TX_DP<4>")
	)
	(segment
		(start 82.347054 -220.563694)
		(end 81.64576 -221.309692)
		(width 0.14732)
		(layer "In15.Cu")
		(net "P5E_CPU1_PE0_TX_DP<4>")
	)
	(segment
		(start 90.226896 -219.190316)
		(end 90.212164 -219.18168)
		(width 0.0889)
		(layer "In15.Cu")
		(net "P5E_CPU1_PE0_TX_DP<4>")
	)
	(segment
		(start 93.219016 -222.780098)
		(end 93.219016 -222.761556)
		(width 0.0889)
		(layer "In15.Cu")
		(net "P5E_CPU1_PE0_TX_DP<4>")
	)
	(segment
		(start 85.041994 -218.87434)
		(end 84.540852 -219.188538)
		(width 0.14732)
		(layer "In15.Cu")
		(net "P5E_CPU1_PE0_TX_DP<4>")
	)
	(segment
		(start 80.614012 -393.178792)
		(end 80.765396 -393.268962)
		(width 0.14732)
		(layer "In15.Cu")
		(net "P5E_CPU1_PE0_TX_DP<4>")
	)
	(segment
		(start 81.331816 -396.021306)
		(end 81.438496 -396.444724)
		(width 0.14732)
		(layer "In15.Cu")
		(net "P5E_CPU1_PE0_TX_DP<4>")
	)
	(segment
		(start 92.56141 -220.644212)
		(end 92.5703 -220.639132)
		(width 0.0889)
		(layer "In15.Cu")
		(net "P5E_CPU1_PE0_TX_DP<4>")
	)
	(segment
		(start 82.244438 -399.672048)
		(end 82.244438 -400.563588)
		(width 0.14732)
		(layer "In15.Cu")
		(net "P5E_CPU1_PE0_TX_DP<4>")
	)
	(segment
		(start 80.88884 -394.267436)
		(end 81.040224 -394.357606)
		(width 0.14732)
		(layer "In15.Cu")
		(net "P5E_CPU1_PE0_TX_DP<4>")
	)
	(segment
		(start 84.540852 -219.188538)
		(end 84.502244 -219.356686)
		(width 0.14732)
		(layer "In15.Cu")
		(net "P5E_CPU1_PE0_TX_DP<4>")
	)
	(segment
		(start 81.58988 -396.534894)
		(end 81.696814 -396.95882)
		(width 0.14732)
		(layer "In15.Cu")
		(net "P5E_CPU1_PE0_TX_DP<4>")
	)
	(segment
		(start 87.015828 -218.832176)
		(end 85.969094 -218.832176)
		(width 0.0889)
		(layer "In15.Cu")
		(net "P5E_CPU1_PE0_TX_DP<4>")
	)
	(segment
		(start 81.581752 -251.125482)
		(end 81.581752 -252.445012)
		(width 0.14732)
		(layer "In15.Cu")
		(net "P5E_CPU1_PE0_TX_DP<4>")
	)
	(segment
		(start 78.98765 -233.827066)
		(end 79.18958 -244.879622)
		(width 0.14732)
		(layer "In15.Cu")
		(net "P5E_CPU1_PE0_TX_DP<4>")
	)
	(segment
		(start 70.206362 -351.937066)
		(end 80.61452 -393.178792)
		(width 0.14732)
		(layer "In15.Cu")
		(net "P5E_CPU1_PE0_TX_DP<4>")
	)
	(segment
		(start 81.138014 -310.314594)
		(end 75.4126 -323.91731)
		(width 0.14732)
		(layer "In15.Cu")
		(net "P5E_CPU1_PE0_TX_DP<4>")
	)
	(segment
		(start 81.056988 -394.932662)
		(end 81.163668 -395.35608)
		(width 0.14732)
		(layer "In15.Cu")
		(net "P5E_CPU1_PE0_TX_DP<4>")
	)
	(segment
		(start 89.287096 -219.190316)
		(end 89.272364 -219.18168)
		(width 0.0889)
		(layer "In15.Cu")
		(net "P5E_CPU1_PE0_TX_DP<4>")
	)
	(segment
		(start 92.279216 -221.149418)
		(end 92.279216 -221.111826)
		(width 0.0889)
		(layer "In15.Cu")
		(net "P5E_CPU1_PE0_TX_DP<4>")
	)
	(segment
		(start 81.315052 -395.44625)
		(end 81.421986 -395.870176)
		(width 0.14732)
		(layer "In15.Cu")
		(net "P5E_CPU1_PE0_TX_DP<4>")
	)
	(segment
		(start 75.4126 -323.91731)
		(end 72.511666 -328.291698)
		(width 0.14732)
		(layer "In15.Cu")
		(net "P5E_CPU1_PE0_TX_DP<4>")
	)
	(segment
		(start 85.92693 -218.87434)
		(end 85.904832 -218.87434)
		(width 0.0889)
		(layer "In15.Cu")
		(net "P5E_CPU1_PE0_TX_DP<4>")
	)
	(segment
		(start 80.736694 -222.981012)
		(end 78.98765 -233.827066)
		(width 0.14732)
		(layer "In15.Cu")
		(net "P5E_CPU1_PE0_TX_DP<4>")
	)
	(segment
		(start 81.163668 -395.35608)
		(end 81.315052 -395.44625)
		(width 0.14732)
		(layer "In15.Cu")
		(net "P5E_CPU1_PE0_TX_DP<4>")
	)
	(segment
		(start 81.581244 -252.445012)
		(end 81.562702 -252.49251)
		(width 0.14732)
		(layer "In15.Cu")
		(net "P5E_CPU1_PE0_TX_DP<4>")
	)
	(segment
		(start 92.093288 -219.182442)
		(end 92.091764 -219.18168)
		(width 0.0889)
		(layer "In15.Cu")
		(net "P5E_CPU1_PE0_TX_DP<4>")
	)
	(segment
		(start 93.031564 -222.437198)
		(end 93.030802 -222.43669)
		(width 0.0889)
		(layer "In15.Cu")
		(net "P5E_CPU1_PE0_TX_DP<4>")
	)
	(segment
		(start 85.969094 -218.832176)
		(end 85.92693 -218.87434)
		(width 0.0889)
		(layer "In15.Cu")
		(net "P5E_CPU1_PE0_TX_DP<4>")
	)
	(segment
		(start 93.040454 -222.442278)
		(end 93.033088 -222.43796)
		(width 0.0889)
		(layer "In15.Cu")
		(net "P5E_CPU1_PE0_TX_DP<4>")
	)
	(segment
		(start 72.511412 -328.292206)
		(end 69.800724 -334.836262)
		(width 0.14732)
		(layer "In15.Cu")
		(net "P5E_CPU1_PE0_TX_DP<4>")
	)
	(segment
		(start 81.606644 -397.10995)
		(end 82.236056 -399.604738)
		(width 0.14732)
		(layer "In15.Cu")
		(net "P5E_CPU1_PE0_TX_DP<4>")
	)
	(segment
		(start 80.87233 -393.692888)
		(end 80.78216 -393.844018)
		(width 0.14732)
		(layer "In15.Cu")
		(net "P5E_CPU1_PE0_TX_DP<4>")
	)
	(segment
		(start 81.562702 -252.49251)
		(end 81.562194 -252.494034)
		(width 0.14732)
		(layer "In15.Cu")
		(net "P5E_CPU1_PE0_TX_DP<4>")
	)
	(segment
		(start 91.166696 -219.190316)
		(end 91.151964 -219.18168)
		(width 0.0889)
		(layer "In15.Cu")
		(net "P5E_CPU1_PE0_TX_DP<4>")
	)
	(segment
		(start 81.421986 -395.870176)
		(end 81.331816 -396.021306)
		(width 0.14732)
		(layer "In15.Cu")
		(net "P5E_CPU1_PE0_TX_DP<4>")
	)
	(segment
		(start 85.904832 -218.87434)
		(end 85.041994 -218.87434)
		(width 0.14732)
		(layer "In15.Cu")
		(net "P5E_CPU1_PE0_TX_DP<4>")
	)
	(segment
		(start 79.624936 -247.255792)
		(end 81.194402 -250.19)
		(width 0.14732)
		(layer "In15.Cu")
		(net "P5E_CPU1_PE0_TX_DP<4>")
	)
	(segment
		(start 70.205854 -351.920048)
		(end 70.206362 -351.937066)
		(width 0.14732)
		(layer "In15.Cu")
		(net "P5E_CPU1_PE0_TX_DP<4>")
	)
	(arc
		(start 93.9165 -224.02927)
		(mid 93.748746 -223.829492)
		(end 93.688662 -223.575626)
		(width 0.0889)
		(layer "In15.Cu")
		(net "P5E_CPU1_PE0_TX_DP<4>")
	)
	(arc
		(start 93.025468 -222.433642)
		(mid 92.822881 -222.227291)
		(end 92.748862 -221.94774)
		(width 0.0889)
		(layer "In15.Cu")
		(net "P5E_CPU1_PE0_TX_DP<4>")
	)
	(arc
		(start 92.56141 -219.995496)
		(mid 92.358587 -219.795265)
		(end 92.279216 -219.521532)
		(width 0.0889)
		(layer "In15.Cu")
		(net "P5E_CPU1_PE0_TX_DP<4>")
	)
	(arc
		(start 90.212164 -219.18168)
		(mid 90.024966 -219.131537)
		(end 89.837768 -219.18168)
		(width 0.0889)
		(layer "In15.Cu")
		(net "P5E_CPU1_PE0_TX_DP<4>")
	)
	(arc
		(start 90.777568 -219.18168)
		(mid 90.503369 -219.257515)
		(end 90.226896 -219.190316)
		(width 0.0889)
		(layer "In15.Cu")
		(net "P5E_CPU1_PE0_TX_DP<4>")
	)
	(arc
		(start 92.091764 -219.18168)
		(mid 91.904566 -219.131537)
		(end 91.717368 -219.18168)
		(width 0.0889)
		(layer "In15.Cu")
		(net "P5E_CPU1_PE0_TX_DP<4>")
	)
	(arc
		(start 91.151964 -219.18168)
		(mid 90.964766 -219.131537)
		(end 90.777568 -219.18168)
		(width 0.0889)
		(layer "In15.Cu")
		(net "P5E_CPU1_PE0_TX_DP<4>")
	)
	(arc
		(start 93.501464 -223.251268)
		(mid 93.299178 -223.052287)
		(end 93.219016 -222.780098)
		(width 0.0889)
		(layer "In15.Cu")
		(net "P5E_CPU1_PE0_TX_DP<4>")
	)
	(arc
		(start 91.717368 -219.18168)
		(mid 91.443169 -219.257515)
		(end 91.166696 -219.190316)
		(width 0.0889)
		(layer "In15.Cu")
		(net "P5E_CPU1_PE0_TX_DP<4>")
	)
	(arc
		(start 93.219016 -222.761556)
		(mid 93.171337 -222.578656)
		(end 93.040454 -222.442278)
		(width 0.0889)
		(layer "In15.Cu")
		(net "P5E_CPU1_PE0_TX_DP<4>")
	)
	(arc
		(start 88.332564 -219.18168)
		(mid 88.145366 -219.131537)
		(end 87.958168 -219.18168)
		(width 0.0889)
		(layer "In15.Cu")
		(net "P5E_CPU1_PE0_TX_DP<4>")
	)
	(arc
		(start 92.279216 -221.111826)
		(mid 92.360127 -220.841698)
		(end 92.56141 -220.644212)
		(width 0.0889)
		(layer "In15.Cu")
		(net "P5E_CPU1_PE0_TX_DP<4>")
	)
	(arc
		(start 89.272364 -219.18168)
		(mid 89.085166 -219.131537)
		(end 88.897968 -219.18168)
		(width 0.0889)
		(layer "In15.Cu")
		(net "P5E_CPU1_PE0_TX_DP<4>")
	)
	(arc
		(start 88.897968 -219.18168)
		(mid 88.615266 -219.257456)
		(end 88.332564 -219.18168)
		(width 0.0889)
		(layer "In15.Cu")
		(net "P5E_CPU1_PE0_TX_DP<4>")
	)
	(arc
		(start 92.279216 -219.506038)
		(mid 92.231537 -219.323138)
		(end 92.100654 -219.18676)
		(width 0.0889)
		(layer "In15.Cu")
		(net "P5E_CPU1_PE0_TX_DP<4>")
	)
	(arc
		(start 89.837768 -219.18168)
		(mid 89.563569 -219.257515)
		(end 89.287096 -219.190316)
		(width 0.0889)
		(layer "In15.Cu")
		(net "P5E_CPU1_PE0_TX_DP<4>")
	)
	(arc
		(start 87.958168 -219.18168)
		(mid 87.675466 -219.257456)
		(end 87.392764 -219.18168)
		(width 0.0889)
		(layer "In15.Cu")
		(net "P5E_CPU1_PE0_TX_DP<4>")
	)
	(arc
		(start 87.392764 -219.18168)
		(mid 87.331286 -219.140678)
		(end 87.27567 -219.092018)
		(width 0.0889)
		(layer "In15.Cu")
		(net "P5E_CPU1_PE0_TX_DP<4>")
	)
	(arc
		(start 92.748862 -221.94774)
		(mid 92.701183 -221.76484)
		(end 92.5703 -221.628462)
		(width 0.0889)
		(layer "In15.Cu")
		(net "P5E_CPU1_PE0_TX_DP<4>")
	)
	(arc
		(start 93.688662 -223.56699)
		(mid 93.636392 -223.384625)
		(end 93.501464 -223.251268)
		(width 0.0889)
		(layer "In15.Cu")
		(net "P5E_CPU1_PE0_TX_DP<4>")
	)
	(arc
		(start 92.5703 -220.639132)
		(mid 92.749018 -220.319854)
		(end 92.5703 -220.000576)
		(width 0.0889)
		(layer "In15.Cu")
		(net "P5E_CPU1_PE0_TX_DP<4>")
	)
	(arc
		(start 92.56141 -221.623382)
		(mid 92.358587 -221.423151)
		(end 92.279216 -221.149418)
		(width 0.0889)
		(layer "In15.Cu")
		(net "P5E_CPU1_PE0_TX_DP<4>")
	)
	(segment
		(start 85.627718 -402.104352)
		(end 85.30336 -401.779994)
		(width 0.13208)
		(layer "F.Cu")
		(net "P5E_CPU1_PE0_TX_DP<3>")
	)
	(segment
		(start 93.314266 -225.203512)
		(end 93.314012 -225.203258)
		(width 0.13208)
		(layer "F.Cu")
		(net "P5E_CPU1_PE0_TX_DP<3>")
	)
	(segment
		(start 85.30336 -401.157186)
		(end 85.602318 -400.858228)
		(width 0.13208)
		(layer "F.Cu")
		(net "P5E_CPU1_PE0_TX_DP<3>")
	)
	(segment
		(start 85.30336 -401.779994)
		(end 85.30336 -401.157186)
		(width 0.13208)
		(layer "F.Cu")
		(net "P5E_CPU1_PE0_TX_DP<3>")
	)
	(segment
		(start 93.314266 -225.739198)
		(end 93.314266 -225.203512)
		(width 0.13208)
		(layer "F.Cu")
		(net "P5E_CPU1_PE0_TX_DP<3>")
	)
	(segment
		(start 92.279216 -224.404936)
		(end 92.279216 -224.373948)
		(width 0.0889)
		(layer "In15.Cu")
		(net "P5E_CPU1_PE0_TX_DP<3>")
	)
	(segment
		(start 83.638898 -393.996926)
		(end 83.638644 -393.99718)
		(width 0.14732)
		(layer "In15.Cu")
		(net "P5E_CPU1_PE0_TX_DP<3>")
	)
	(segment
		(start 79.963518 -259.169154)
		(end 79.292958 -266.620244)
		(width 0.14732)
		(layer "In15.Cu")
		(net "P5E_CPU1_PE0_TX_DP<3>")
	)
	(segment
		(start 93.314012 -225.203258)
		(end 93.157548 -224.93224)
		(width 0.0889)
		(layer "In15.Cu")
		(net "P5E_CPU1_PE0_TX_DP<3>")
	)
	(segment
		(start 83.638644 -393.99718)
		(end 83.793584 -394.081508)
		(width 0.14732)
		(layer "In15.Cu")
		(net "P5E_CPU1_PE0_TX_DP<3>")
	)
	(segment
		(start 71.209154 -351.655126)
		(end 71.209408 -351.663762)
		(width 0.14732)
		(layer "In15.Cu")
		(net "P5E_CPU1_PE0_TX_DP<3>")
	)
	(segment
		(start 80.174846 -245.019576)
		(end 80.513936 -246.945404)
		(width 0.14732)
		(layer "In15.Cu")
		(net "P5E_CPU1_PE0_TX_DP<3>")
	)
	(segment
		(start 71.2089 -351.652332)
		(end 71.199756 -351.630742)
		(width 0.14732)
		(layer "In15.Cu")
		(net "P5E_CPU1_PE0_TX_DP<3>")
	)
	(segment
		(start 84.426298 -396.235936)
		(end 84.549234 -396.65529)
		(width 0.14732)
		(layer "In15.Cu")
		(net "P5E_CPU1_PE0_TX_DP<3>")
	)
	(segment
		(start 85.307678 -399.720308)
		(end 85.307678 -400.563588)
		(width 0.14732)
		(layer "In15.Cu")
		(net "P5E_CPU1_PE0_TX_DP<3>")
	)
	(segment
		(start 71.209408 -351.663762)
		(end 83.638898 -393.996926)
		(width 0.14732)
		(layer "In15.Cu")
		(net "P5E_CPU1_PE0_TX_DP<3>")
	)
	(segment
		(start 85.904832 -220.11386)
		(end 85.405976 -220.11386)
		(width 0.14732)
		(layer "In15.Cu")
		(net "P5E_CPU1_PE0_TX_DP<3>")
	)
	(segment
		(start 82.516218 -250.951492)
		(end 82.516218 -252.621034)
		(width 0.14732)
		(layer "In15.Cu")
		(net "P5E_CPU1_PE0_TX_DP<3>")
	)
	(segment
		(start 70.646544 -335.738216)
		(end 71.2089 -351.652332)
		(width 0.14732)
		(layer "In15.Cu")
		(net "P5E_CPU1_PE0_TX_DP<3>")
	)
	(segment
		(start 92.091764 -222.437198)
		(end 92.091002 -222.43669)
		(width 0.0889)
		(layer "In15.Cu")
		(net "P5E_CPU1_PE0_TX_DP<3>")
	)
	(segment
		(start 79.292958 -266.620244)
		(end 82.089498 -310.54802)
		(width 0.14732)
		(layer "In15.Cu")
		(net "P5E_CPU1_PE0_TX_DP<3>")
	)
	(segment
		(start 82.50428 -221.828614)
		(end 81.743296 -223.131126)
		(width 0.14732)
		(layer "In15.Cu")
		(net "P5E_CPU1_PE0_TX_DP<3>")
	)
	(segment
		(start 84.549234 -396.65529)
		(end 84.464906 -396.809976)
		(width 0.14732)
		(layer "In15.Cu")
		(net "P5E_CPU1_PE0_TX_DP<3>")
	)
	(segment
		(start 83.793584 -394.081508)
		(end 83.91652 -394.500862)
		(width 0.14732)
		(layer "In15.Cu")
		(net "P5E_CPU1_PE0_TX_DP<3>")
	)
	(segment
		(start 82.515964 -252.621034)
		(end 82.497422 -252.668532)
		(width 0.14732)
		(layer "In15.Cu")
		(net "P5E_CPU1_PE0_TX_DP<3>")
	)
	(segment
		(start 82.037428 -249.794776)
		(end 82.516218 -250.951492)
		(width 0.14732)
		(layer "In15.Cu")
		(net "P5E_CPU1_PE0_TX_DP<3>")
	)
	(segment
		(start 82.089498 -310.54802)
		(end 76.237338 -324.45198)
		(width 0.14732)
		(layer "In15.Cu")
		(net "P5E_CPU1_PE0_TX_DP<3>")
	)
	(segment
		(start 84.148676 -395.732508)
		(end 84.271612 -396.151608)
		(width 0.14732)
		(layer "In15.Cu")
		(net "P5E_CPU1_PE0_TX_DP<3>")
	)
	(segment
		(start 83.955128 -395.074394)
		(end 84.109814 -395.158722)
		(width 0.14732)
		(layer "In15.Cu")
		(net "P5E_CPU1_PE0_TX_DP<3>")
	)
	(segment
		(start 92.100654 -222.442278)
		(end 92.093288 -222.43796)
		(width 0.0889)
		(layer "In15.Cu")
		(net "P5E_CPU1_PE0_TX_DP<3>")
	)
	(segment
		(start 81.743296 -223.131126)
		(end 79.962502 -233.951018)
		(width 0.14732)
		(layer "In15.Cu")
		(net "P5E_CPU1_PE0_TX_DP<3>")
	)
	(segment
		(start 84.109814 -395.158722)
		(end 84.233004 -395.578076)
		(width 0.14732)
		(layer "In15.Cu")
		(net "P5E_CPU1_PE0_TX_DP<3>")
	)
	(segment
		(start 85.307678 -400.563588)
		(end 85.602318 -400.858228)
		(width 0.14732)
		(layer "In15.Cu")
		(net "P5E_CPU1_PE0_TX_DP<3>")
	)
	(segment
		(start 88.428068 -219.995496)
		(end 88.413336 -220.004132)
		(width 0.0889)
		(layer "In15.Cu")
		(net "P5E_CPU1_PE0_TX_DP<3>")
	)
	(segment
		(start 86.937088 -220.004132)
		(end 86.922356 -219.995496)
		(width 0.0889)
		(layer "In15.Cu")
		(net "P5E_CPU1_PE0_TX_DP<3>")
	)
	(segment
		(start 92.279216 -222.783654)
		(end 92.279216 -222.761556)
		(width 0.0889)
		(layer "In15.Cu")
		(net "P5E_CPU1_PE0_TX_DP<3>")
	)
	(segment
		(start 92.562426 -223.899476)
		(end 92.5703 -223.894904)
		(width 0.0889)
		(layer "In15.Cu")
		(net "P5E_CPU1_PE0_TX_DP<3>")
	)
	(segment
		(start 82.516218 -252.621034)
		(end 82.515964 -252.621034)
		(width 0.14732)
		(layer "In15.Cu")
		(net "P5E_CPU1_PE0_TX_DP<3>")
	)
	(segment
		(start 86.922356 -219.995496)
		(end 86.905592 -219.985844)
		(width 0.0889)
		(layer "In15.Cu")
		(net "P5E_CPU1_PE0_TX_DP<3>")
	)
	(segment
		(start 90.6907 -220.000576)
		(end 90.68181 -219.995496)
		(width 0.0889)
		(layer "In15.Cu")
		(net "P5E_CPU1_PE0_TX_DP<3>")
	)
	(segment
		(start 84.464906 -396.809976)
		(end 85.296756 -399.643092)
		(width 0.14732)
		(layer "In15.Cu")
		(net "P5E_CPU1_PE0_TX_DP<3>")
	)
	(segment
		(start 93.157548 -224.93224)
		(end 93.068648 -224.908618)
		(width 0.0889)
		(layer "In15.Cu")
		(net "P5E_CPU1_PE0_TX_DP<3>")
	)
	(segment
		(start 83.832192 -394.655294)
		(end 83.955128 -395.074394)
		(width 0.14732)
		(layer "In15.Cu")
		(net "P5E_CPU1_PE0_TX_DP<3>")
	)
	(segment
		(start 79.962502 -233.951018)
		(end 80.174846 -245.019576)
		(width 0.14732)
		(layer "In15.Cu")
		(net "P5E_CPU1_PE0_TX_DP<3>")
	)
	(segment
		(start 83.91652 -394.500862)
		(end 83.832192 -394.655294)
		(width 0.14732)
		(layer "In15.Cu")
		(net "P5E_CPU1_PE0_TX_DP<3>")
	)
	(segment
		(start 91.339416 -221.149418)
		(end 91.339416 -221.133924)
		(width 0.0889)
		(layer "In15.Cu")
		(net "P5E_CPU1_PE0_TX_DP<3>")
	)
	(segment
		(start 92.091002 -222.43669)
		(end 92.085668 -222.433642)
		(width 0.0889)
		(layer "In15.Cu")
		(net "P5E_CPU1_PE0_TX_DP<3>")
	)
	(segment
		(start 80.513936 -246.945404)
		(end 82.037428 -249.794776)
		(width 0.14732)
		(layer "In15.Cu")
		(net "P5E_CPU1_PE0_TX_DP<3>")
	)
	(segment
		(start 91.622626 -221.62389)
		(end 91.62161 -221.623382)
		(width 0.0889)
		(layer "In15.Cu")
		(net "P5E_CPU1_PE0_TX_DP<3>")
	)
	(segment
		(start 85.405976 -220.11386)
		(end 82.50428 -221.828614)
		(width 0.14732)
		(layer "In15.Cu")
		(net "P5E_CPU1_PE0_TX_DP<3>")
	)
	(segment
		(start 91.6305 -221.628462)
		(end 91.622626 -221.62389)
		(width 0.0889)
		(layer "In15.Cu")
		(net "P5E_CPU1_PE0_TX_DP<3>")
	)
	(segment
		(start 85.296756 -399.643092)
		(end 85.307678 -399.720308)
		(width 0.14732)
		(layer "In15.Cu")
		(net "P5E_CPU1_PE0_TX_DP<3>")
	)
	(segment
		(start 85.92693 -220.11386)
		(end 85.904832 -220.11386)
		(width 0.0889)
		(layer "In15.Cu")
		(net "P5E_CPU1_PE0_TX_DP<3>")
	)
	(segment
		(start 71.199756 -351.630742)
		(end 71.209154 -351.655126)
		(width 0.14732)
		(layer "In15.Cu")
		(net "P5E_CPU1_PE0_TX_DP<3>")
	)
	(segment
		(start 86.264496 -220.071696)
		(end 85.969094 -220.071696)
		(width 0.0889)
		(layer "In15.Cu")
		(net "P5E_CPU1_PE0_TX_DP<3>")
	)
	(segment
		(start 84.271612 -396.151608)
		(end 84.426298 -396.235936)
		(width 0.14732)
		(layer "In15.Cu")
		(net "P5E_CPU1_PE0_TX_DP<3>")
	)
	(segment
		(start 91.160854 -220.814646)
		(end 91.151964 -220.809566)
		(width 0.0889)
		(layer "In15.Cu")
		(net "P5E_CPU1_PE0_TX_DP<3>")
	)
	(segment
		(start 92.093288 -222.43796)
		(end 92.091764 -222.437198)
		(width 0.0889)
		(layer "In15.Cu")
		(net "P5E_CPU1_PE0_TX_DP<3>")
	)
	(segment
		(start 90.307414 -219.995496)
		(end 90.297 -220.001592)
		(width 0.0889)
		(layer "In15.Cu")
		(net "P5E_CPU1_PE0_TX_DP<3>")
	)
	(segment
		(start 92.562426 -223.251776)
		(end 92.56141 -223.251268)
		(width 0.0889)
		(layer "In15.Cu")
		(net "P5E_CPU1_PE0_TX_DP<3>")
	)
	(segment
		(start 76.237338 -324.45198)
		(end 73.602342 -328.36612)
		(width 0.14732)
		(layer "In15.Cu")
		(net "P5E_CPU1_PE0_TX_DP<3>")
	)
	(segment
		(start 92.56141 -223.899984)
		(end 92.562426 -223.899476)
		(width 0.0889)
		(layer "In15.Cu")
		(net "P5E_CPU1_PE0_TX_DP<3>")
	)
	(segment
		(start 87.49919 -219.988638)
		(end 87.487252 -219.995496)
		(width 0.0889)
		(layer "In15.Cu")
		(net "P5E_CPU1_PE0_TX_DP<3>")
	)
	(segment
		(start 92.5703 -223.256348)
		(end 92.562426 -223.251776)
		(width 0.0889)
		(layer "In15.Cu")
		(net "P5E_CPU1_PE0_TX_DP<3>")
	)
	(segment
		(start 70.730872 -335.298542)
		(end 70.646544 -335.738216)
		(width 0.14732)
		(layer "In15.Cu")
		(net "P5E_CPU1_PE0_TX_DP<3>")
	)
	(segment
		(start 82.493612 -252.679962)
		(end 79.963518 -259.169154)
		(width 0.14732)
		(layer "In15.Cu")
		(net "P5E_CPU1_PE0_TX_DP<3>")
	)
	(segment
		(start 90.869262 -220.327474)
		(end 90.869262 -220.319854)
		(width 0.0889)
		(layer "In15.Cu")
		(net "P5E_CPU1_PE0_TX_DP<3>")
	)
	(segment
		(start 84.233004 -395.578076)
		(end 84.148676 -395.732508)
		(width 0.14732)
		(layer "In15.Cu")
		(net "P5E_CPU1_PE0_TX_DP<3>")
	)
	(segment
		(start 73.602342 -328.36612)
		(end 70.730872 -335.298542)
		(width 0.14732)
		(layer "In15.Cu")
		(net "P5E_CPU1_PE0_TX_DP<3>")
	)
	(segment
		(start 82.497422 -252.668532)
		(end 82.493612 -252.679962)
		(width 0.14732)
		(layer "In15.Cu")
		(net "P5E_CPU1_PE0_TX_DP<3>")
	)
	(segment
		(start 85.969094 -220.071696)
		(end 85.92693 -220.11386)
		(width 0.0889)
		(layer "In15.Cu")
		(net "P5E_CPU1_PE0_TX_DP<3>")
	)
	(arc
		(start 89.367868 -219.995496)
		(mid 89.085166 -220.071272)
		(end 88.802464 -219.995496)
		(width 0.0889)
		(layer "In15.Cu")
		(net "P5E_CPU1_PE0_TX_DP<3>")
	)
	(arc
		(start 90.68181 -219.995496)
		(mid 90.494612 -219.945353)
		(end 90.307414 -219.995496)
		(width 0.0889)
		(layer "In15.Cu")
		(net "P5E_CPU1_PE0_TX_DP<3>")
	)
	(arc
		(start 92.5703 -223.894904)
		(mid 92.748897 -223.575626)
		(end 92.5703 -223.256348)
		(width 0.0889)
		(layer "In15.Cu")
		(net "P5E_CPU1_PE0_TX_DP<3>")
	)
	(arc
		(start 86.905592 -219.985844)
		(mid 86.725551 -219.945241)
		(end 86.54796 -219.995496)
		(width 0.0889)
		(layer "In15.Cu")
		(net "P5E_CPU1_PE0_TX_DP<3>")
	)
	(arc
		(start 87.862156 -219.995496)
		(mid 87.681555 -219.945166)
		(end 87.49919 -219.988638)
		(width 0.0889)
		(layer "In15.Cu")
		(net "P5E_CPU1_PE0_TX_DP<3>")
	)
	(arc
		(start 88.413336 -220.004132)
		(mid 88.136607 -220.071572)
		(end 87.862156 -219.995496)
		(width 0.0889)
		(layer "In15.Cu")
		(net "P5E_CPU1_PE0_TX_DP<3>")
	)
	(arc
		(start 88.802464 -219.995496)
		(mid 88.615266 -219.945353)
		(end 88.428068 -219.995496)
		(width 0.0889)
		(layer "In15.Cu")
		(net "P5E_CPU1_PE0_TX_DP<3>")
	)
	(arc
		(start 91.151964 -220.809566)
		(mid 90.946892 -220.605887)
		(end 90.869262 -220.327474)
		(width 0.0889)
		(layer "In15.Cu")
		(net "P5E_CPU1_PE0_TX_DP<3>")
	)
	(arc
		(start 92.279216 -222.761556)
		(mid 92.231537 -222.578656)
		(end 92.100654 -222.442278)
		(width 0.0889)
		(layer "In15.Cu")
		(net "P5E_CPU1_PE0_TX_DP<3>")
	)
	(arc
		(start 90.297 -220.001592)
		(mid 90.018822 -220.071315)
		(end 89.742264 -219.995496)
		(width 0.0889)
		(layer "In15.Cu")
		(net "P5E_CPU1_PE0_TX_DP<3>")
	)
	(arc
		(start 92.085668 -222.433642)
		(mid 91.883081 -222.227291)
		(end 91.809062 -221.94774)
		(width 0.0889)
		(layer "In15.Cu")
		(net "P5E_CPU1_PE0_TX_DP<3>")
	)
	(arc
		(start 87.487252 -219.995496)
		(mid 87.213277 -220.071328)
		(end 86.937088 -220.004132)
		(width 0.0889)
		(layer "In15.Cu")
		(net "P5E_CPU1_PE0_TX_DP<3>")
	)
	(arc
		(start 86.54796 -219.995496)
		(mid 86.411258 -220.052319)
		(end 86.264496 -220.071696)
		(width 0.0889)
		(layer "In15.Cu")
		(net "P5E_CPU1_PE0_TX_DP<3>")
	)
	(arc
		(start 93.068648 -224.908618)
		(mid 93.058908 -224.912775)
		(end 93.04909 -224.916746)
		(width 0.0889)
		(layer "In15.Cu")
		(net "P5E_CPU1_PE0_TX_DP<3>")
	)
	(arc
		(start 89.742264 -219.995496)
		(mid 89.555066 -219.945353)
		(end 89.367868 -219.995496)
		(width 0.0889)
		(layer "In15.Cu")
		(net "P5E_CPU1_PE0_TX_DP<3>")
	)
	(arc
		(start 92.56141 -223.251268)
		(mid 92.360128 -223.053781)
		(end 92.279216 -222.783654)
		(width 0.0889)
		(layer "In15.Cu")
		(net "P5E_CPU1_PE0_TX_DP<3>")
	)
	(arc
		(start 92.279216 -224.373948)
		(mid 92.358586 -224.100214)
		(end 92.56141 -223.899984)
		(width 0.0889)
		(layer "In15.Cu")
		(net "P5E_CPU1_PE0_TX_DP<3>")
	)
	(arc
		(start 90.869262 -220.319854)
		(mid 90.821583 -220.136954)
		(end 90.6907 -220.000576)
		(width 0.0889)
		(layer "In15.Cu")
		(net "P5E_CPU1_PE0_TX_DP<3>")
	)
	(arc
		(start 91.62161 -221.623382)
		(mid 91.418787 -221.423151)
		(end 91.339416 -221.149418)
		(width 0.0889)
		(layer "In15.Cu")
		(net "P5E_CPU1_PE0_TX_DP<3>")
	)
	(arc
		(start 93.04909 -224.916746)
		(mid 92.800938 -224.953361)
		(end 92.56141 -224.8789)
		(width 0.0889)
		(layer "In15.Cu")
		(net "P5E_CPU1_PE0_TX_DP<3>")
	)
	(arc
		(start 91.809062 -221.94774)
		(mid 91.761383 -221.76484)
		(end 91.6305 -221.628462)
		(width 0.0889)
		(layer "In15.Cu")
		(net "P5E_CPU1_PE0_TX_DP<3>")
	)
	(arc
		(start 91.339416 -221.133924)
		(mid 91.291737 -220.951024)
		(end 91.160854 -220.814646)
		(width 0.0889)
		(layer "In15.Cu")
		(net "P5E_CPU1_PE0_TX_DP<3>")
	)
	(arc
		(start 92.56141 -224.8789)
		(mid 92.358587 -224.678669)
		(end 92.279216 -224.404936)
		(width 0.0889)
		(layer "In15.Cu")
		(net "P5E_CPU1_PE0_TX_DP<3>")
	)
	(segment
		(start 91.904566 -224.925128)
		(end 91.904566 -224.389442)
		(width 0.13208)
		(layer "F.Cu")
		(net "P5E_CPU1_PE0_TX_DP<2>")
	)
	(segment
		(start 88.3666 -401.779994)
		(end 88.3666 -401.157186)
		(width 0.13208)
		(layer "F.Cu")
		(net "P5E_CPU1_PE0_TX_DP<2>")
	)
	(segment
		(start 88.3666 -401.157186)
		(end 88.665558 -400.858228)
		(width 0.13208)
		(layer "F.Cu")
		(net "P5E_CPU1_PE0_TX_DP<2>")
	)
	(segment
		(start 88.690958 -402.104352)
		(end 88.3666 -401.779994)
		(width 0.13208)
		(layer "F.Cu")
		(net "P5E_CPU1_PE0_TX_DP<2>")
	)
	(segment
		(start 91.904312 -224.925382)
		(end 91.904566 -224.925128)
		(width 0.13208)
		(layer "F.Cu")
		(net "P5E_CPU1_PE0_TX_DP<2>")
	)
	(segment
		(start 83.814158 -222.428562)
		(end 83.79206 -222.428562)
		(width 0.0889)
		(layer "In15.Cu")
		(net "P5E_CPU1_PE0_TX_DP<2>")
	)
	(segment
		(start 72.306942 -351.697544)
		(end 86.175596 -393.097004)
		(width 0.14732)
		(layer "In15.Cu")
		(net "P5E_CPU1_PE0_TX_DP<2>")
	)
	(segment
		(start 90.226896 -222.445834)
		(end 90.212164 -222.437198)
		(width 0.0889)
		(layer "In15.Cu")
		(net "P5E_CPU1_PE0_TX_DP<2>")
	)
	(segment
		(start 86.750144 -394.812774)
		(end 86.750652 -394.81252)
		(width 0.14732)
		(layer "In15.Cu")
		(net "P5E_CPU1_PE0_TX_DP<2>")
	)
	(segment
		(start 86.532212 -394.162026)
		(end 86.689946 -394.240512)
		(width 0.14732)
		(layer "In15.Cu")
		(net "P5E_CPU1_PE0_TX_DP<2>")
	)
	(segment
		(start 86.689946 -394.240512)
		(end 86.82863 -394.65504)
		(width 0.14732)
		(layer "In15.Cu")
		(net "P5E_CPU1_PE0_TX_DP<2>")
	)
	(segment
		(start 80.235552 -266.632436)
		(end 83.044792 -310.765952)
		(width 0.14732)
		(layer "In15.Cu")
		(net "P5E_CPU1_PE0_TX_DP<2>")
	)
	(segment
		(start 83.455764 -250.789186)
		(end 83.455764 -252.797818)
		(width 0.14732)
		(layer "In15.Cu")
		(net "P5E_CPU1_PE0_TX_DP<2>")
	)
	(segment
		(start 87.403432 -396.370048)
		(end 87.54237 -396.784576)
		(width 0.14732)
		(layer "In15.Cu")
		(net "P5E_CPU1_PE0_TX_DP<2>")
	)
	(segment
		(start 86.532466 -394.161772)
		(end 86.532212 -394.162026)
		(width 0.14732)
		(layer "In15.Cu")
		(net "P5E_CPU1_PE0_TX_DP<2>")
	)
	(segment
		(start 83.442048 -222.428562)
		(end 83.201256 -222.542608)
		(width 0.14732)
		(layer "In15.Cu")
		(net "P5E_CPU1_PE0_TX_DP<2>")
	)
	(segment
		(start 88.370918 -399.694908)
		(end 88.370918 -400.563588)
		(width 0.14732)
		(layer "In15.Cu")
		(net "P5E_CPU1_PE0_TX_DP<2>")
	)
	(segment
		(start 82.676492 -224.322132)
		(end 82.535776 -224.421954)
		(width 0.14732)
		(layer "In15.Cu")
		(net "P5E_CPU1_PE0_TX_DP<2>")
	)
	(segment
		(start 77.031596 -325.05396)
		(end 74.46899 -328.824844)
		(width 0.14732)
		(layer "In15.Cu")
		(net "P5E_CPU1_PE0_TX_DP<2>")
	)
	(segment
		(start 83.856322 -222.386398)
		(end 83.814158 -222.428562)
		(width 0.0889)
		(layer "In15.Cu")
		(net "P5E_CPU1_PE0_TX_DP<2>")
	)
	(segment
		(start 83.79206 -222.428562)
		(end 83.442048 -222.428562)
		(width 0.14732)
		(layer "In15.Cu")
		(net "P5E_CPU1_PE0_TX_DP<2>")
	)
	(segment
		(start 81.119726 -244.79123)
		(end 81.463642 -246.749316)
		(width 0.14732)
		(layer "In15.Cu")
		(net "P5E_CPU1_PE0_TX_DP<2>")
	)
	(segment
		(start 86.175596 -393.097004)
		(end 86.333584 -393.17549)
		(width 0.14732)
		(layer "In15.Cu")
		(net "P5E_CPU1_PE0_TX_DP<2>")
	)
	(segment
		(start 87.107014 -395.877542)
		(end 87.245698 -396.291562)
		(width 0.14732)
		(layer "In15.Cu")
		(net "P5E_CPU1_PE0_TX_DP<2>")
	)
	(segment
		(start 86.889336 -395.226794)
		(end 86.888828 -395.226794)
		(width 0.14732)
		(layer "In15.Cu")
		(net "P5E_CPU1_PE0_TX_DP<2>")
	)
	(segment
		(start 81.463642 -246.749316)
		(end 82.881216 -249.400822)
		(width 0.14732)
		(layer "In15.Cu")
		(net "P5E_CPU1_PE0_TX_DP<2>")
	)
	(segment
		(start 91.904566 -224.389442)
		(end 92.06103 -224.118424)
		(width 0.0889)
		(layer "In15.Cu")
		(net "P5E_CPU1_PE0_TX_DP<2>")
	)
	(segment
		(start 71.676006 -335.566512)
		(end 71.610982 -336.046572)
		(width 0.14732)
		(layer "In15.Cu")
		(net "P5E_CPU1_PE0_TX_DP<2>")
	)
	(segment
		(start 86.472268 -393.590018)
		(end 86.393782 -393.747752)
		(width 0.14732)
		(layer "In15.Cu")
		(net "P5E_CPU1_PE0_TX_DP<2>")
	)
	(segment
		(start 80.913478 -234.05338)
		(end 81.119726 -244.79123)
		(width 0.14732)
		(layer "In15.Cu")
		(net "P5E_CPU1_PE0_TX_DP<2>")
	)
	(segment
		(start 83.455764 -252.797818)
		(end 80.888078 -259.386324)
		(width 0.14732)
		(layer "In15.Cu")
		(net "P5E_CPU1_PE0_TX_DP<2>")
	)
	(segment
		(start 86.393782 -393.747752)
		(end 86.532466 -394.161772)
		(width 0.14732)
		(layer "In15.Cu")
		(net "P5E_CPU1_PE0_TX_DP<2>")
	)
	(segment
		(start 87.54237 -396.784576)
		(end 87.463884 -396.942056)
		(width 0.14732)
		(layer "In15.Cu")
		(net "P5E_CPU1_PE0_TX_DP<2>")
	)
	(segment
		(start 91.809062 -223.575626)
		(end 91.809062 -223.56699)
		(width 0.0889)
		(layer "In15.Cu")
		(net "P5E_CPU1_PE0_TX_DP<2>")
	)
	(segment
		(start 87.1855 -395.719808)
		(end 87.107014 -395.877542)
		(width 0.14732)
		(layer "In15.Cu")
		(net "P5E_CPU1_PE0_TX_DP<2>")
	)
	(segment
		(start 86.078568 -222.437198)
		(end 86.068154 -222.443294)
		(width 0.0889)
		(layer "In15.Cu")
		(net "P5E_CPU1_PE0_TX_DP<2>")
	)
	(segment
		(start 74.46899 -328.824844)
		(end 71.676006 -335.566512)
		(width 0.14732)
		(layer "In15.Cu")
		(net "P5E_CPU1_PE0_TX_DP<2>")
	)
	(segment
		(start 72.306688 -351.690432)
		(end 72.306942 -351.697544)
		(width 0.14732)
		(layer "In15.Cu")
		(net "P5E_CPU1_PE0_TX_DP<2>")
	)
	(segment
		(start 89.287096 -222.445834)
		(end 89.272364 -222.437198)
		(width 0.0889)
		(layer "In15.Cu")
		(net "P5E_CPU1_PE0_TX_DP<2>")
	)
	(segment
		(start 82.881216 -249.400822)
		(end 83.455764 -250.789186)
		(width 0.14732)
		(layer "In15.Cu")
		(net "P5E_CPU1_PE0_TX_DP<2>")
	)
	(segment
		(start 82.748882 -223.891094)
		(end 82.676492 -224.322132)
		(width 0.14732)
		(layer "In15.Cu")
		(net "P5E_CPU1_PE0_TX_DP<2>")
	)
	(segment
		(start 85.325712 -222.386398)
		(end 83.856322 -222.386398)
		(width 0.0889)
		(layer "In15.Cu")
		(net "P5E_CPU1_PE0_TX_DP<2>")
	)
	(segment
		(start 87.046816 -395.30528)
		(end 87.1855 -395.719808)
		(width 0.14732)
		(layer "In15.Cu")
		(net "P5E_CPU1_PE0_TX_DP<2>")
	)
	(segment
		(start 86.82863 -394.65504)
		(end 86.750144 -394.812774)
		(width 0.14732)
		(layer "In15.Cu")
		(net "P5E_CPU1_PE0_TX_DP<2>")
	)
	(segment
		(start 82.64906 -223.750632)
		(end 82.748882 -223.891094)
		(width 0.14732)
		(layer "In15.Cu")
		(net "P5E_CPU1_PE0_TX_DP<2>")
	)
	(segment
		(start 83.201256 -222.542608)
		(end 82.72145 -223.319848)
		(width 0.14732)
		(layer "In15.Cu")
		(net "P5E_CPU1_PE0_TX_DP<2>")
	)
	(segment
		(start 80.888078 -259.386324)
		(end 80.235552 -266.632436)
		(width 0.14732)
		(layer "In15.Cu")
		(net "P5E_CPU1_PE0_TX_DP<2>")
	)
	(segment
		(start 87.463884 -396.942056)
		(end 88.356694 -399.607532)
		(width 0.14732)
		(layer "In15.Cu")
		(net "P5E_CPU1_PE0_TX_DP<2>")
	)
	(segment
		(start 86.888828 -395.226794)
		(end 87.046816 -395.30528)
		(width 0.14732)
		(layer "In15.Cu")
		(net "P5E_CPU1_PE0_TX_DP<2>")
	)
	(segment
		(start 92.06103 -224.118424)
		(end 92.0369 -224.02927)
		(width 0.0889)
		(layer "In15.Cu")
		(net "P5E_CPU1_PE0_TX_DP<2>")
	)
	(segment
		(start 91.160854 -222.442278)
		(end 91.153488 -222.43796)
		(width 0.0889)
		(layer "In15.Cu")
		(net "P5E_CPU1_PE0_TX_DP<2>")
	)
	(segment
		(start 83.044792 -310.765952)
		(end 77.031596 -325.05396)
		(width 0.14732)
		(layer "In15.Cu")
		(net "P5E_CPU1_PE0_TX_DP<2>")
	)
	(segment
		(start 86.750652 -394.81252)
		(end 86.889336 -395.226794)
		(width 0.14732)
		(layer "In15.Cu")
		(net "P5E_CPU1_PE0_TX_DP<2>")
	)
	(segment
		(start 87.245698 -396.291562)
		(end 87.403432 -396.370048)
		(width 0.14732)
		(layer "In15.Cu")
		(net "P5E_CPU1_PE0_TX_DP<2>")
	)
	(segment
		(start 88.356694 -399.607532)
		(end 88.370918 -399.694908)
		(width 0.14732)
		(layer "In15.Cu")
		(net "P5E_CPU1_PE0_TX_DP<2>")
	)
	(segment
		(start 82.72145 -223.319848)
		(end 82.64906 -223.750632)
		(width 0.14732)
		(layer "In15.Cu")
		(net "P5E_CPU1_PE0_TX_DP<2>")
	)
	(segment
		(start 86.333584 -393.17549)
		(end 86.472268 -393.590018)
		(width 0.14732)
		(layer "In15.Cu")
		(net "P5E_CPU1_PE0_TX_DP<2>")
	)
	(segment
		(start 88.370918 -400.563588)
		(end 88.665558 -400.858228)
		(width 0.14732)
		(layer "In15.Cu")
		(net "P5E_CPU1_PE0_TX_DP<2>")
	)
	(segment
		(start 82.535776 -224.421954)
		(end 80.913478 -234.05338)
		(width 0.14732)
		(layer "In15.Cu")
		(net "P5E_CPU1_PE0_TX_DP<2>")
	)
	(segment
		(start 91.339416 -222.780098)
		(end 91.339416 -222.761556)
		(width 0.0889)
		(layer "In15.Cu")
		(net "P5E_CPU1_PE0_TX_DP<2>")
	)
	(segment
		(start 91.153488 -222.43796)
		(end 91.151964 -222.437198)
		(width 0.0889)
		(layer "In15.Cu")
		(net "P5E_CPU1_PE0_TX_DP<2>")
	)
	(segment
		(start 71.610982 -336.046572)
		(end 72.306688 -351.690432)
		(width 0.14732)
		(layer "In15.Cu")
		(net "P5E_CPU1_PE0_TX_DP<2>")
	)
	(arc
		(start 87.958168 -222.437198)
		(mid 87.675466 -222.512974)
		(end 87.392764 -222.437198)
		(width 0.0889)
		(layer "In15.Cu")
		(net "P5E_CPU1_PE0_TX_DP<2>")
	)
	(arc
		(start 89.837768 -222.437198)
		(mid 89.563569 -222.513033)
		(end 89.287096 -222.445834)
		(width 0.0889)
		(layer "In15.Cu")
		(net "P5E_CPU1_PE0_TX_DP<2>")
	)
	(arc
		(start 90.212164 -222.437198)
		(mid 90.024966 -222.387055)
		(end 89.837768 -222.437198)
		(width 0.0889)
		(layer "In15.Cu")
		(net "P5E_CPU1_PE0_TX_DP<2>")
	)
	(arc
		(start 91.151964 -222.437198)
		(mid 90.964766 -222.387055)
		(end 90.777568 -222.437198)
		(width 0.0889)
		(layer "In15.Cu")
		(net "P5E_CPU1_PE0_TX_DP<2>")
	)
	(arc
		(start 85.51291 -222.437198)
		(mid 85.422654 -222.399476)
		(end 85.325712 -222.386398)
		(width 0.0889)
		(layer "In15.Cu")
		(net "P5E_CPU1_PE0_TX_DP<2>")
	)
	(arc
		(start 86.452964 -222.437198)
		(mid 86.265766 -222.387055)
		(end 86.078568 -222.437198)
		(width 0.0889)
		(layer "In15.Cu")
		(net "P5E_CPU1_PE0_TX_DP<2>")
	)
	(arc
		(start 88.897968 -222.437198)
		(mid 88.615266 -222.512974)
		(end 88.332564 -222.437198)
		(width 0.0889)
		(layer "In15.Cu")
		(net "P5E_CPU1_PE0_TX_DP<2>")
	)
	(arc
		(start 91.339416 -222.761556)
		(mid 91.291737 -222.578656)
		(end 91.160854 -222.442278)
		(width 0.0889)
		(layer "In15.Cu")
		(net "P5E_CPU1_PE0_TX_DP<2>")
	)
	(arc
		(start 91.809062 -223.56699)
		(mid 91.756792 -223.384625)
		(end 91.621864 -223.251268)
		(width 0.0889)
		(layer "In15.Cu")
		(net "P5E_CPU1_PE0_TX_DP<2>")
	)
	(arc
		(start 87.018368 -222.437198)
		(mid 86.735666 -222.512974)
		(end 86.452964 -222.437198)
		(width 0.0889)
		(layer "In15.Cu")
		(net "P5E_CPU1_PE0_TX_DP<2>")
	)
	(arc
		(start 87.392764 -222.437198)
		(mid 87.205566 -222.387055)
		(end 87.018368 -222.437198)
		(width 0.0889)
		(layer "In15.Cu")
		(net "P5E_CPU1_PE0_TX_DP<2>")
	)
	(arc
		(start 91.621864 -223.251268)
		(mid 91.419578 -223.052287)
		(end 91.339416 -222.780098)
		(width 0.0889)
		(layer "In15.Cu")
		(net "P5E_CPU1_PE0_TX_DP<2>")
	)
	(arc
		(start 88.332564 -222.437198)
		(mid 88.145366 -222.387055)
		(end 87.958168 -222.437198)
		(width 0.0889)
		(layer "In15.Cu")
		(net "P5E_CPU1_PE0_TX_DP<2>")
	)
	(arc
		(start 92.0369 -224.02927)
		(mid 91.869146 -223.829492)
		(end 91.809062 -223.575626)
		(width 0.0889)
		(layer "In15.Cu")
		(net "P5E_CPU1_PE0_TX_DP<2>")
	)
	(arc
		(start 86.068154 -222.443294)
		(mid 85.789722 -222.51314)
		(end 85.51291 -222.437198)
		(width 0.0889)
		(layer "In15.Cu")
		(net "P5E_CPU1_PE0_TX_DP<2>")
	)
	(arc
		(start 90.777568 -222.437198)
		(mid 90.503369 -222.513033)
		(end 90.226896 -222.445834)
		(width 0.0889)
		(layer "In15.Cu")
		(net "P5E_CPU1_PE0_TX_DP<2>")
	)
	(arc
		(start 89.272364 -222.437198)
		(mid 89.085166 -222.387055)
		(end 88.897968 -222.437198)
		(width 0.0889)
		(layer "In15.Cu")
		(net "P5E_CPU1_PE0_TX_DP<2>")
	)
	(segment
		(start 91.42984 -401.157186)
		(end 91.728798 -400.858228)
		(width 0.13208)
		(layer "F.Cu")
		(net "P5E_CPU1_PE0_TX_DP<1>")
	)
	(segment
		(start 91.434412 -225.738944)
		(end 91.434412 -225.203258)
		(width 0.13208)
		(layer "F.Cu")
		(net "P5E_CPU1_PE0_TX_DP<1>")
	)
	(segment
		(start 91.42984 -401.779994)
		(end 91.42984 -401.157186)
		(width 0.13208)
		(layer "F.Cu")
		(net "P5E_CPU1_PE0_TX_DP<1>")
	)
	(segment
		(start 91.754198 -402.104352)
		(end 91.42984 -401.779994)
		(width 0.13208)
		(layer "F.Cu")
		(net "P5E_CPU1_PE0_TX_DP<1>")
	)
	(segment
		(start 91.434666 -225.739198)
		(end 91.434412 -225.738944)
		(width 0.13208)
		(layer "F.Cu")
		(net "P5E_CPU1_PE0_TX_DP<1>")
	)
	(segment
		(start 72.590152 -336.164682)
		(end 73.3425 -351.34677)
		(width 0.14732)
		(layer "In15.Cu")
		(net "P5E_CPU1_PE0_TX_DP<1>")
	)
	(segment
		(start 90.307414 -223.251268)
		(end 90.297 -223.257364)
		(width 0.0889)
		(layer "In15.Cu")
		(net "P5E_CPU1_PE0_TX_DP<1>")
	)
	(segment
		(start 90.170254 -396.00505)
		(end 90.097102 -396.16507)
		(width 0.14732)
		(layer "In15.Cu")
		(net "P5E_CPU1_PE0_TX_DP<1>")
	)
	(segment
		(start 90.097102 -396.16507)
		(end 90.25001 -396.574264)
		(width 0.14732)
		(layer "In15.Cu")
		(net "P5E_CPU1_PE0_TX_DP<1>")
	)
	(segment
		(start 84.590636 -223.310196)
		(end 84.306664 -223.594168)
		(width 0.0889)
		(layer "In15.Cu")
		(net "P5E_CPU1_PE0_TX_DP<1>")
	)
	(segment
		(start 81.16824 -266.644628)
		(end 83.988656 -310.95061)
		(width 0.14732)
		(layer "In15.Cu")
		(net "P5E_CPU1_PE0_TX_DP<1>")
	)
	(segment
		(start 89.777062 -394.953236)
		(end 89.70391 -395.113256)
		(width 0.14732)
		(layer "In15.Cu")
		(net "P5E_CPU1_PE0_TX_DP<1>")
	)
	(segment
		(start 83.988656 -310.95061)
		(end 77.657706 -325.990966)
		(width 0.14732)
		(layer "In15.Cu")
		(net "P5E_CPU1_PE0_TX_DP<1>")
	)
	(segment
		(start 90.490548 -397.216884)
		(end 91.434158 -399.741644)
		(width 0.14732)
		(layer "In15.Cu")
		(net "P5E_CPU1_PE0_TX_DP<1>")
	)
	(segment
		(start 89.367868 -223.251268)
		(end 89.357454 -223.257364)
		(width 0.0889)
		(layer "In15.Cu")
		(net "P5E_CPU1_PE0_TX_DP<1>")
	)
	(segment
		(start 91.434158 -399.741644)
		(end 91.434158 -400.563588)
		(width 0.14732)
		(layer "In15.Cu")
		(net "P5E_CPU1_PE0_TX_DP<1>")
	)
	(segment
		(start 84.29117 -223.669606)
		(end 84.073492 -223.887284)
		(width 0.14732)
		(layer "In15.Cu")
		(net "P5E_CPU1_PE0_TX_DP<1>")
	)
	(segment
		(start 84.073492 -223.887284)
		(end 82.09661 -234.170982)
		(width 0.14732)
		(layer "In15.Cu")
		(net "P5E_CPU1_PE0_TX_DP<1>")
	)
	(segment
		(start 89.856818 -395.52245)
		(end 90.017092 -395.595602)
		(width 0.14732)
		(layer "In15.Cu")
		(net "P5E_CPU1_PE0_TX_DP<1>")
	)
	(segment
		(start 90.017092 -395.595602)
		(end 90.170254 -396.00505)
		(width 0.14732)
		(layer "In15.Cu")
		(net "P5E_CPU1_PE0_TX_DP<1>")
	)
	(segment
		(start 75.2221 -329.489816)
		(end 72.655938 -335.684876)
		(width 0.14732)
		(layer "In15.Cu")
		(net "P5E_CPU1_PE0_TX_DP<1>")
	)
	(segment
		(start 91.277948 -224.93224)
		(end 91.189048 -224.908618)
		(width 0.0889)
		(layer "In15.Cu")
		(net "P5E_CPU1_PE0_TX_DP<1>")
	)
	(segment
		(start 90.6907 -223.256348)
		(end 90.68181 -223.251268)
		(width 0.0889)
		(layer "In15.Cu")
		(net "P5E_CPU1_PE0_TX_DP<1>")
	)
	(segment
		(start 90.563446 -397.056864)
		(end 90.490548 -397.216884)
		(width 0.14732)
		(layer "In15.Cu")
		(net "P5E_CPU1_PE0_TX_DP<1>")
	)
	(segment
		(start 72.655938 -335.684876)
		(end 72.590152 -336.164682)
		(width 0.14732)
		(layer "In15.Cu")
		(net "P5E_CPU1_PE0_TX_DP<1>")
	)
	(segment
		(start 82.408776 -246.544592)
		(end 83.71967 -248.995184)
		(width 0.14732)
		(layer "In15.Cu")
		(net "P5E_CPU1_PE0_TX_DP<1>")
	)
	(segment
		(start 88.427814 -223.251268)
		(end 88.4174 -223.257364)
		(width 0.0889)
		(layer "In15.Cu")
		(net "P5E_CPU1_PE0_TX_DP<1>")
	)
	(segment
		(start 77.657706 -325.990966)
		(end 75.2221 -329.489816)
		(width 0.14732)
		(layer "In15.Cu")
		(net "P5E_CPU1_PE0_TX_DP<1>")
	)
	(segment
		(start 84.385404 -250.60275)
		(end 84.385404 -252.97257)
		(width 0.14732)
		(layer "In15.Cu")
		(net "P5E_CPU1_PE0_TX_DP<1>")
	)
	(segment
		(start 84.385404 -252.97257)
		(end 81.802478 -259.601208)
		(width 0.14732)
		(layer "In15.Cu")
		(net "P5E_CPU1_PE0_TX_DP<1>")
	)
	(segment
		(start 85.057996 -223.259904)
		(end 85.043264 -223.251268)
		(width 0.0889)
		(layer "In15.Cu")
		(net "P5E_CPU1_PE0_TX_DP<1>")
	)
	(segment
		(start 90.25001 -396.574264)
		(end 90.410538 -396.647416)
		(width 0.14732)
		(layer "In15.Cu")
		(net "P5E_CPU1_PE0_TX_DP<1>")
	)
	(segment
		(start 84.306664 -223.654112)
		(end 84.29117 -223.669606)
		(width 0.0889)
		(layer "In15.Cu")
		(net "P5E_CPU1_PE0_TX_DP<1>")
	)
	(segment
		(start 90.682826 -223.899476)
		(end 90.6907 -223.894904)
		(width 0.0889)
		(layer "In15.Cu")
		(net "P5E_CPU1_PE0_TX_DP<1>")
	)
	(segment
		(start 81.802478 -259.601208)
		(end 81.16824 -266.644628)
		(width 0.14732)
		(layer "In15.Cu")
		(net "P5E_CPU1_PE0_TX_DP<1>")
	)
	(segment
		(start 91.434158 -400.563588)
		(end 91.728798 -400.858228)
		(width 0.14732)
		(layer "In15.Cu")
		(net "P5E_CPU1_PE0_TX_DP<1>")
	)
	(segment
		(start 82.09661 -234.170982)
		(end 82.17027 -245.190518)
		(width 0.14732)
		(layer "In15.Cu")
		(net "P5E_CPU1_PE0_TX_DP<1>")
	)
	(segment
		(start 82.17027 -245.190518)
		(end 82.408776 -246.544592)
		(width 0.14732)
		(layer "In15.Cu")
		(net "P5E_CPU1_PE0_TX_DP<1>")
	)
	(segment
		(start 89.6239 -394.543788)
		(end 89.777062 -394.953236)
		(width 0.14732)
		(layer "In15.Cu")
		(net "P5E_CPU1_PE0_TX_DP<1>")
	)
	(segment
		(start 90.68181 -223.899984)
		(end 90.682826 -223.899476)
		(width 0.0889)
		(layer "In15.Cu")
		(net "P5E_CPU1_PE0_TX_DP<1>")
	)
	(segment
		(start 90.399616 -224.404936)
		(end 90.399616 -224.373948)
		(width 0.0889)
		(layer "In15.Cu")
		(net "P5E_CPU1_PE0_TX_DP<1>")
	)
	(segment
		(start 89.463626 -394.470636)
		(end 89.6239 -394.543788)
		(width 0.14732)
		(layer "In15.Cu")
		(net "P5E_CPU1_PE0_TX_DP<1>")
	)
	(segment
		(start 73.3425 -351.34677)
		(end 89.463626 -394.470636)
		(width 0.14732)
		(layer "In15.Cu")
		(net "P5E_CPU1_PE0_TX_DP<1>")
	)
	(segment
		(start 89.70391 -395.113256)
		(end 89.856818 -395.52245)
		(width 0.14732)
		(layer "In15.Cu")
		(net "P5E_CPU1_PE0_TX_DP<1>")
	)
	(segment
		(start 91.434412 -225.203258)
		(end 91.277948 -224.93224)
		(width 0.0889)
		(layer "In15.Cu")
		(net "P5E_CPU1_PE0_TX_DP<1>")
	)
	(segment
		(start 83.71967 -248.995184)
		(end 84.385404 -250.60275)
		(width 0.14732)
		(layer "In15.Cu")
		(net "P5E_CPU1_PE0_TX_DP<1>")
	)
	(segment
		(start 84.306664 -223.594168)
		(end 84.306664 -223.654112)
		(width 0.0889)
		(layer "In15.Cu")
		(net "P5E_CPU1_PE0_TX_DP<1>")
	)
	(segment
		(start 90.410538 -396.647416)
		(end 90.563446 -397.056864)
		(width 0.14732)
		(layer "In15.Cu")
		(net "P5E_CPU1_PE0_TX_DP<1>")
	)
	(arc
		(start 91.16949 -224.916746)
		(mid 90.921338 -224.953361)
		(end 90.68181 -224.8789)
		(width 0.0889)
		(layer "In15.Cu")
		(net "P5E_CPU1_PE0_TX_DP<1>")
	)
	(arc
		(start 85.983064 -223.251268)
		(mid 85.795866 -223.201125)
		(end 85.608668 -223.251268)
		(width 0.0889)
		(layer "In15.Cu")
		(net "P5E_CPU1_PE0_TX_DP<1>")
	)
	(arc
		(start 85.043264 -223.251268)
		(mid 84.856066 -223.201125)
		(end 84.668868 -223.251268)
		(width 0.0889)
		(layer "In15.Cu")
		(net "P5E_CPU1_PE0_TX_DP<1>")
	)
	(arc
		(start 89.357454 -223.257364)
		(mid 89.079022 -223.327178)
		(end 88.80221 -223.251268)
		(width 0.0889)
		(layer "In15.Cu")
		(net "P5E_CPU1_PE0_TX_DP<1>")
	)
	(arc
		(start 89.742264 -223.251268)
		(mid 89.555066 -223.201125)
		(end 89.367868 -223.251268)
		(width 0.0889)
		(layer "In15.Cu")
		(net "P5E_CPU1_PE0_TX_DP<1>")
	)
	(arc
		(start 88.4174 -223.257364)
		(mid 88.139222 -223.327056)
		(end 87.862664 -223.251268)
		(width 0.0889)
		(layer "In15.Cu")
		(net "P5E_CPU1_PE0_TX_DP<1>")
	)
	(arc
		(start 90.399616 -224.373948)
		(mid 90.478986 -224.100214)
		(end 90.68181 -223.899984)
		(width 0.0889)
		(layer "In15.Cu")
		(net "P5E_CPU1_PE0_TX_DP<1>")
	)
	(arc
		(start 90.68181 -224.8789)
		(mid 90.478987 -224.678669)
		(end 90.399616 -224.404936)
		(width 0.0889)
		(layer "In15.Cu")
		(net "P5E_CPU1_PE0_TX_DP<1>")
	)
	(arc
		(start 90.6907 -223.894904)
		(mid 90.869297 -223.575626)
		(end 90.6907 -223.256348)
		(width 0.0889)
		(layer "In15.Cu")
		(net "P5E_CPU1_PE0_TX_DP<1>")
	)
	(arc
		(start 85.608668 -223.251268)
		(mid 85.334439 -223.327193)
		(end 85.057996 -223.259904)
		(width 0.0889)
		(layer "In15.Cu")
		(net "P5E_CPU1_PE0_TX_DP<1>")
	)
	(arc
		(start 91.189048 -224.908618)
		(mid 91.179308 -224.912775)
		(end 91.16949 -224.916746)
		(width 0.0889)
		(layer "In15.Cu")
		(net "P5E_CPU1_PE0_TX_DP<1>")
	)
	(arc
		(start 86.922864 -223.251268)
		(mid 86.735666 -223.201125)
		(end 86.548468 -223.251268)
		(width 0.0889)
		(layer "In15.Cu")
		(net "P5E_CPU1_PE0_TX_DP<1>")
	)
	(arc
		(start 90.68181 -223.251268)
		(mid 90.494612 -223.201125)
		(end 90.307414 -223.251268)
		(width 0.0889)
		(layer "In15.Cu")
		(net "P5E_CPU1_PE0_TX_DP<1>")
	)
	(arc
		(start 86.548468 -223.251268)
		(mid 86.265766 -223.32701)
		(end 85.983064 -223.251268)
		(width 0.0889)
		(layer "In15.Cu")
		(net "P5E_CPU1_PE0_TX_DP<1>")
	)
	(arc
		(start 88.80221 -223.251268)
		(mid 88.615012 -223.201125)
		(end 88.427814 -223.251268)
		(width 0.0889)
		(layer "In15.Cu")
		(net "P5E_CPU1_PE0_TX_DP<1>")
	)
	(arc
		(start 84.668868 -223.251268)
		(mid 84.62781 -223.278155)
		(end 84.590636 -223.310196)
		(width 0.0889)
		(layer "In15.Cu")
		(net "P5E_CPU1_PE0_TX_DP<1>")
	)
	(arc
		(start 87.488268 -223.251268)
		(mid 87.205566 -223.32701)
		(end 86.922864 -223.251268)
		(width 0.0889)
		(layer "In15.Cu")
		(net "P5E_CPU1_PE0_TX_DP<1>")
	)
	(arc
		(start 90.297 -223.257364)
		(mid 90.018822 -223.327056)
		(end 89.742264 -223.251268)
		(width 0.0889)
		(layer "In15.Cu")
		(net "P5E_CPU1_PE0_TX_DP<1>")
	)
	(arc
		(start 87.862664 -223.251268)
		(mid 87.675466 -223.201125)
		(end 87.488268 -223.251268)
		(width 0.0889)
		(layer "In15.Cu")
		(net "P5E_CPU1_PE0_TX_DP<1>")
	)
	(segment
		(start 48.54448 -401.779994)
		(end 48.54448 -401.157186)
		(width 0.13208)
		(layer "F.Cu")
		(net "P5E_CPU1_PE0_TX_DP<15>")
	)
	(segment
		(start 104.591866 -225.203512)
		(end 104.591612 -225.203258)
		(width 0.13208)
		(layer "F.Cu")
		(net "P5E_CPU1_PE0_TX_DP<15>")
	)
	(segment
		(start 48.54448 -401.157186)
		(end 48.843438 -400.858228)
		(width 0.13208)
		(layer "F.Cu")
		(net "P5E_CPU1_PE0_TX_DP<15>")
	)
	(segment
		(start 48.868838 -402.104352)
		(end 48.54448 -401.779994)
		(width 0.13208)
		(layer "F.Cu")
		(net "P5E_CPU1_PE0_TX_DP<15>")
	)
	(segment
		(start 104.591866 -225.739198)
		(end 104.591866 -225.203512)
		(width 0.13208)
		(layer "F.Cu")
		(net "P5E_CPU1_PE0_TX_DP<15>")
	)
	(segment
		(start 60.296044 -322.17868)
		(end 59.666886 -322.439284)
		(width 0.14732)
		(layer "In15.Cu")
		(net "P5E_CPU1_PE0_TX_DP<15>")
	)
	(segment
		(start 50.26025 -395.229334)
		(end 50.151284 -395.581124)
		(width 0.14732)
		(layer "In15.Cu")
		(net "P5E_CPU1_PE0_TX_DP<15>")
	)
	(segment
		(start 102.617016 -216.260426)
		(end 102.617016 -216.25052)
		(width 0.0889)
		(layer "In15.Cu")
		(net "P5E_CPU1_PE0_TX_DP<15>")
	)
	(segment
		(start 94.45752 -202.15352)
		(end 90.671904 -200.585578)
		(width 0.14732)
		(layer "In15.Cu")
		(net "P5E_CPU1_PE0_TX_DP<15>")
	)
	(segment
		(start 68.759324 -310.52389)
		(end 67.44716 -314.538868)
		(width 0.14732)
		(layer "In15.Cu")
		(net "P5E_CPU1_PE0_TX_DP<15>")
	)
	(segment
		(start 103.840026 -223.251776)
		(end 103.83901 -223.251268)
		(width 0.0889)
		(layer "In15.Cu")
		(net "P5E_CPU1_PE0_TX_DP<15>")
	)
	(segment
		(start 73.102978 -214.55253)
		(end 70.162166 -220.219524)
		(width 0.14732)
		(layer "In15.Cu")
		(net "P5E_CPU1_PE0_TX_DP<15>")
	)
	(segment
		(start 68.934076 -309.901336)
		(end 68.933822 -309.90159)
		(width 0.14732)
		(layer "In15.Cu")
		(net "P5E_CPU1_PE0_TX_DP<15>")
	)
	(segment
		(start 57.501536 -332.107794)
		(end 59.345576 -350.014286)
		(width 0.14732)
		(layer "In15.Cu")
		(net "P5E_CPU1_PE0_TX_DP<15>")
	)
	(segment
		(start 58.077608 -365.415322)
		(end 56.756046 -374.265952)
		(width 0.14732)
		(layer "In15.Cu")
		(net "P5E_CPU1_PE0_TX_DP<15>")
	)
	(segment
		(start 103.378254 -222.442278)
		(end 103.368602 -222.43669)
		(width 0.0889)
		(layer "In15.Cu")
		(net "P5E_CPU1_PE0_TX_DP<15>")
	)
	(segment
		(start 50.581306 -394.193522)
		(end 50.45202 -394.61059)
		(width 0.14732)
		(layer "In15.Cu")
		(net "P5E_CPU1_PE0_TX_DP<15>")
	)
	(segment
		(start 67.44716 -314.538868)
		(end 66.801492 -315.184536)
		(width 0.14732)
		(layer "In15.Cu")
		(net "P5E_CPU1_PE0_TX_DP<15>")
	)
	(segment
		(start 50.913792 -393.121134)
		(end 50.784506 -393.538202)
		(width 0.14732)
		(layer "In15.Cu")
		(net "P5E_CPU1_PE0_TX_DP<15>")
	)
	(segment
		(start 104.435148 -224.93224)
		(end 104.346248 -224.908618)
		(width 0.0889)
		(layer "In15.Cu")
		(net "P5E_CPU1_PE0_TX_DP<15>")
	)
	(segment
		(start 49.627282 -397.272764)
		(end 49.426114 -397.922496)
		(width 0.14732)
		(layer "In15.Cu")
		(net "P5E_CPU1_PE0_TX_DP<15>")
	)
	(segment
		(start 65.448688 -316.088268)
		(end 64.425576 -317.11138)
		(width 0.14732)
		(layer "In15.Cu")
		(net "P5E_CPU1_PE0_TX_DP<15>")
	)
	(segment
		(start 89.195402 -200.581514)
		(end 87.738712 -200.577704)
		(width 0.14732)
		(layer "In15.Cu")
		(net "P5E_CPU1_PE0_TX_DP<15>")
	)
	(segment
		(start 102.197154 -213.997794)
		(end 102.164642 -213.914228)
		(width 0.0889)
		(layer "In15.Cu")
		(net "P5E_CPU1_PE0_TX_DP<15>")
	)
	(segment
		(start 104.591612 -225.203258)
		(end 104.435148 -224.93224)
		(width 0.0889)
		(layer "In15.Cu")
		(net "P5E_CPU1_PE0_TX_DP<15>")
	)
	(segment
		(start 102.147116 -213.186772)
		(end 102.104952 -213.144608)
		(width 0.0889)
		(layer "In15.Cu")
		(net "P5E_CPU1_PE0_TX_DP<15>")
	)
	(segment
		(start 49.959514 -396.199868)
		(end 49.83099 -396.61592)
		(width 0.14732)
		(layer "In15.Cu")
		(net "P5E_CPU1_PE0_TX_DP<15>")
	)
	(segment
		(start 102.104952 -213.12251)
		(end 102.104952 -211.335366)
		(width 0.14732)
		(layer "In15.Cu")
		(net "P5E_CPU1_PE0_TX_DP<15>")
	)
	(segment
		(start 51.116992 -392.465814)
		(end 51.199034 -392.621516)
		(width 0.14732)
		(layer "In15.Cu")
		(net "P5E_CPU1_PE0_TX_DP<15>")
	)
	(segment
		(start 70.134734 -305.622198)
		(end 68.934076 -309.901082)
		(width 0.14732)
		(layer "In15.Cu")
		(net "P5E_CPU1_PE0_TX_DP<15>")
	)
	(segment
		(start 61.515752 -319.80632)
		(end 60.70092 -321.773804)
		(width 0.14732)
		(layer "In15.Cu")
		(net "P5E_CPU1_PE0_TX_DP<15>")
	)
	(segment
		(start 68.302378 -232.254298)
		(end 66.901314 -249.919744)
		(width 0.14732)
		(layer "In15.Cu")
		(net "P5E_CPU1_PE0_TX_DP<15>")
	)
	(segment
		(start 68.933822 -309.90159)
		(end 68.759324 -310.52389)
		(width 0.14732)
		(layer "In15.Cu")
		(net "P5E_CPU1_PE0_TX_DP<15>")
	)
	(segment
		(start 66.795396 -253.468886)
		(end 70.134734 -305.622198)
		(width 0.14732)
		(layer "In15.Cu")
		(net "P5E_CPU1_PE0_TX_DP<15>")
	)
	(segment
		(start 59.345576 -350.014286)
		(end 58.077608 -365.415322)
		(width 0.14732)
		(layer "In15.Cu")
		(net "P5E_CPU1_PE0_TX_DP<15>")
	)
	(segment
		(start 101.019864 -208.715864)
		(end 94.45752 -202.15352)
		(width 0.14732)
		(layer "In15.Cu")
		(net "P5E_CPU1_PE0_TX_DP<15>")
	)
	(segment
		(start 50.866548 -393.693904)
		(end 50.737262 -394.11148)
		(width 0.14732)
		(layer "In15.Cu")
		(net "P5E_CPU1_PE0_TX_DP<15>")
	)
	(segment
		(start 50.134266 -396.10792)
		(end 49.959514 -396.199868)
		(width 0.14732)
		(layer "In15.Cu")
		(net "P5E_CPU1_PE0_TX_DP<15>")
	)
	(segment
		(start 103.556816 -224.404936)
		(end 103.556816 -224.373948)
		(width 0.0889)
		(layer "In15.Cu")
		(net "P5E_CPU1_PE0_TX_DP<15>")
	)
	(segment
		(start 89.205054 -200.581514)
		(end 89.195402 -200.581514)
		(width 0.14732)
		(layer "In15.Cu")
		(net "P5E_CPU1_PE0_TX_DP<15>")
	)
	(segment
		(start 51.199034 -392.621516)
		(end 51.069748 -393.039092)
		(width 0.14732)
		(layer "In15.Cu")
		(net "P5E_CPU1_PE0_TX_DP<15>")
	)
	(segment
		(start 59.666886 -322.439284)
		(end 59.076336 -323.029834)
		(width 0.14732)
		(layer "In15.Cu")
		(net "P5E_CPU1_PE0_TX_DP<15>")
	)
	(segment
		(start 57.501536 -324.973188)
		(end 57.501536 -332.107794)
		(width 0.14732)
		(layer "In15.Cu")
		(net "P5E_CPU1_PE0_TX_DP<15>")
	)
	(segment
		(start 102.9081 -218.372944)
		(end 102.900226 -218.368372)
		(width 0.0889)
		(layer "In15.Cu")
		(net "P5E_CPU1_PE0_TX_DP<15>")
	)
	(segment
		(start 103.840026 -223.899476)
		(end 103.8479 -223.894904)
		(width 0.0889)
		(layer "In15.Cu")
		(net "P5E_CPU1_PE0_TX_DP<15>")
	)
	(segment
		(start 49.912524 -396.773146)
		(end 49.783238 -397.190722)
		(width 0.14732)
		(layer "In15.Cu")
		(net "P5E_CPU1_PE0_TX_DP<15>")
	)
	(segment
		(start 102.900226 -221.62389)
		(end 102.89921 -221.623382)
		(width 0.0889)
		(layer "In15.Cu")
		(net "P5E_CPU1_PE0_TX_DP<15>")
	)
	(segment
		(start 66.801492 -315.184536)
		(end 65.448688 -316.088268)
		(width 0.14732)
		(layer "In15.Cu")
		(net "P5E_CPU1_PE0_TX_DP<15>")
	)
	(segment
		(start 50.544222 -394.785342)
		(end 50.435256 -395.137386)
		(width 0.14732)
		(layer "In15.Cu")
		(net "P5E_CPU1_PE0_TX_DP<15>")
	)
	(segment
		(start 102.428802 -215.925654)
		(end 102.423468 -215.922606)
		(width 0.0889)
		(layer "In15.Cu")
		(net "P5E_CPU1_PE0_TX_DP<15>")
	)
	(segment
		(start 102.617016 -217.8939)
		(end 102.617016 -217.859864)
		(width 0.0889)
		(layer "In15.Cu")
		(net "P5E_CPU1_PE0_TX_DP<15>")
	)
	(segment
		(start 102.89921 -219.01658)
		(end 102.9081 -219.0115)
		(width 0.0889)
		(layer "In15.Cu")
		(net "P5E_CPU1_PE0_TX_DP<15>")
	)
	(segment
		(start 50.151284 -395.581124)
		(end 50.243232 -395.755876)
		(width 0.14732)
		(layer "In15.Cu")
		(net "P5E_CPU1_PE0_TX_DP<15>")
	)
	(segment
		(start 103.368602 -222.43669)
		(end 103.363268 -222.433642)
		(width 0.0889)
		(layer "In15.Cu")
		(net "P5E_CPU1_PE0_TX_DP<15>")
	)
	(segment
		(start 59.076336 -323.029834)
		(end 58.815478 -323.659246)
		(width 0.14732)
		(layer "In15.Cu")
		(net "P5E_CPU1_PE0_TX_DP<15>")
	)
	(segment
		(start 102.617016 -221.149418)
		(end 102.617016 -221.115382)
		(width 0.0889)
		(layer "In15.Cu")
		(net "P5E_CPU1_PE0_TX_DP<15>")
	)
	(segment
		(start 103.8479 -223.256348)
		(end 103.840026 -223.251776)
		(width 0.0889)
		(layer "In15.Cu")
		(net "P5E_CPU1_PE0_TX_DP<15>")
	)
	(segment
		(start 50.243232 -395.755876)
		(end 50.134266 -396.10792)
		(width 0.14732)
		(layer "In15.Cu")
		(net "P5E_CPU1_PE0_TX_DP<15>")
	)
	(segment
		(start 103.83901 -223.899984)
		(end 103.840026 -223.899476)
		(width 0.0889)
		(layer "In15.Cu")
		(net "P5E_CPU1_PE0_TX_DP<15>")
	)
	(segment
		(start 49.783238 -397.190722)
		(end 49.627282 -397.272764)
		(width 0.14732)
		(layer "In15.Cu")
		(net "P5E_CPU1_PE0_TX_DP<15>")
	)
	(segment
		(start 48.548798 -400.563588)
		(end 48.843438 -400.858228)
		(width 0.14732)
		(layer "In15.Cu")
		(net "P5E_CPU1_PE0_TX_DP<15>")
	)
	(segment
		(start 85.091016 -201.733912)
		(end 73.102978 -214.55253)
		(width 0.14732)
		(layer "In15.Cu")
		(net "P5E_CPU1_PE0_TX_DP<15>")
	)
	(segment
		(start 50.784506 -393.538202)
		(end 50.866548 -393.693904)
		(width 0.14732)
		(layer "In15.Cu")
		(net "P5E_CPU1_PE0_TX_DP<15>")
	)
	(segment
		(start 51.069748 -393.039092)
		(end 50.913792 -393.121134)
		(width 0.14732)
		(layer "In15.Cu")
		(net "P5E_CPU1_PE0_TX_DP<15>")
	)
	(segment
		(start 48.548798 -400.083528)
		(end 48.548798 -400.563588)
		(width 0.14732)
		(layer "In15.Cu")
		(net "P5E_CPU1_PE0_TX_DP<15>")
	)
	(segment
		(start 102.438454 -215.931242)
		(end 102.428802 -215.925654)
		(width 0.0889)
		(layer "In15.Cu")
		(net "P5E_CPU1_PE0_TX_DP<15>")
	)
	(segment
		(start 64.425576 -317.11138)
		(end 63.430404 -317.523622)
		(width 0.14732)
		(layer "In15.Cu")
		(net "P5E_CPU1_PE0_TX_DP<15>")
	)
	(segment
		(start 102.104952 -213.144608)
		(end 102.104952 -213.12251)
		(width 0.0889)
		(layer "In15.Cu")
		(net "P5E_CPU1_PE0_TX_DP<15>")
	)
	(segment
		(start 50.45202 -394.61059)
		(end 50.544222 -394.785342)
		(width 0.14732)
		(layer "In15.Cu")
		(net "P5E_CPU1_PE0_TX_DP<15>")
	)
	(segment
		(start 56.756046 -374.265952)
		(end 51.116992 -392.465814)
		(width 0.14732)
		(layer "In15.Cu")
		(net "P5E_CPU1_PE0_TX_DP<15>")
	)
	(segment
		(start 49.83099 -396.61592)
		(end 49.830482 -396.617444)
		(width 0.14732)
		(layer "In15.Cu")
		(net "P5E_CPU1_PE0_TX_DP<15>")
	)
	(segment
		(start 66.901314 -249.919744)
		(end 66.795396 -253.468886)
		(width 0.14732)
		(layer "In15.Cu")
		(net "P5E_CPU1_PE0_TX_DP<15>")
	)
	(segment
		(start 102.147116 -213.820502)
		(end 102.147116 -213.186772)
		(width 0.0889)
		(layer "In15.Cu")
		(net "P5E_CPU1_PE0_TX_DP<15>")
	)
	(segment
		(start 62.257178 -318.696848)
		(end 61.515752 -319.80632)
		(width 0.14732)
		(layer "In15.Cu")
		(net "P5E_CPU1_PE0_TX_DP<15>")
	)
	(segment
		(start 49.830482 -396.617444)
		(end 49.912524 -396.773146)
		(width 0.14732)
		(layer "In15.Cu")
		(net "P5E_CPU1_PE0_TX_DP<15>")
	)
	(segment
		(start 102.104952 -211.335366)
		(end 101.019864 -208.715864)
		(width 0.14732)
		(layer "In15.Cu")
		(net "P5E_CPU1_PE0_TX_DP<15>")
	)
	(segment
		(start 87.738712 -200.577704)
		(end 85.091016 -201.733912)
		(width 0.14732)
		(layer "In15.Cu")
		(net "P5E_CPU1_PE0_TX_DP<15>")
	)
	(segment
		(start 50.737262 -394.11148)
		(end 50.581306 -394.193522)
		(width 0.14732)
		(layer "In15.Cu")
		(net "P5E_CPU1_PE0_TX_DP<15>")
	)
	(segment
		(start 102.900226 -218.368372)
		(end 102.89921 -218.367864)
		(width 0.0889)
		(layer "In15.Cu")
		(net "P5E_CPU1_PE0_TX_DP<15>")
	)
	(segment
		(start 58.815478 -323.659246)
		(end 57.501536 -324.973188)
		(width 0.14732)
		(layer "In15.Cu")
		(net "P5E_CPU1_PE0_TX_DP<15>")
	)
	(segment
		(start 70.162166 -220.219524)
		(end 68.302378 -232.254298)
		(width 0.14732)
		(layer "In15.Cu")
		(net "P5E_CPU1_PE0_TX_DP<15>")
	)
	(segment
		(start 68.934076 -309.901082)
		(end 68.934076 -309.901336)
		(width 0.14732)
		(layer "In15.Cu")
		(net "P5E_CPU1_PE0_TX_DP<15>")
	)
	(segment
		(start 90.671904 -200.585578)
		(end 89.205054 -200.581514)
		(width 0.14732)
		(layer "In15.Cu")
		(net "P5E_CPU1_PE0_TX_DP<15>")
	)
	(segment
		(start 102.429056 -214.946992)
		(end 102.437946 -214.941912)
		(width 0.0889)
		(layer "In15.Cu")
		(net "P5E_CPU1_PE0_TX_DP<15>")
	)
	(segment
		(start 102.616508 -214.622634)
		(end 102.616508 -214.472266)
		(width 0.0889)
		(layer "In15.Cu")
		(net "P5E_CPU1_PE0_TX_DP<15>")
	)
	(segment
		(start 50.435256 -395.137386)
		(end 50.26025 -395.229334)
		(width 0.14732)
		(layer "In15.Cu")
		(net "P5E_CPU1_PE0_TX_DP<15>")
	)
	(segment
		(start 103.556816 -222.783654)
		(end 103.556816 -222.761556)
		(width 0.0889)
		(layer "In15.Cu")
		(net "P5E_CPU1_PE0_TX_DP<15>")
	)
	(segment
		(start 49.426114 -397.922496)
		(end 48.548798 -400.083528)
		(width 0.14732)
		(layer "In15.Cu")
		(net "P5E_CPU1_PE0_TX_DP<15>")
	)
	(segment
		(start 102.9081 -221.628462)
		(end 102.900226 -221.62389)
		(width 0.0889)
		(layer "In15.Cu")
		(net "P5E_CPU1_PE0_TX_DP<15>")
	)
	(segment
		(start 60.70092 -321.773804)
		(end 60.296044 -322.17868)
		(width 0.14732)
		(layer "In15.Cu")
		(net "P5E_CPU1_PE0_TX_DP<15>")
	)
	(segment
		(start 63.430404 -317.523622)
		(end 62.257178 -318.696848)
		(width 0.14732)
		(layer "In15.Cu")
		(net "P5E_CPU1_PE0_TX_DP<15>")
	)
	(arc
		(start 103.556816 -224.373948)
		(mid 103.636186 -224.100214)
		(end 103.83901 -223.899984)
		(width 0.0889)
		(layer "In15.Cu")
		(net "P5E_CPU1_PE0_TX_DP<15>")
	)
	(arc
		(start 102.89921 -218.367864)
		(mid 102.696387 -218.167633)
		(end 102.617016 -217.8939)
		(width 0.0889)
		(layer "In15.Cu")
		(net "P5E_CPU1_PE0_TX_DP<15>")
	)
	(arc
		(start 102.89921 -221.623382)
		(mid 102.696387 -221.423151)
		(end 102.617016 -221.149418)
		(width 0.0889)
		(layer "In15.Cu")
		(net "P5E_CPU1_PE0_TX_DP<15>")
	)
	(arc
		(start 103.086662 -221.94774)
		(mid 103.038983 -221.76484)
		(end 102.9081 -221.628462)
		(width 0.0889)
		(layer "In15.Cu")
		(net "P5E_CPU1_PE0_TX_DP<15>")
	)
	(arc
		(start 102.899464 -217.388694)
		(mid 103.086767 -217.064336)
		(end 102.899464 -216.739978)
		(width 0.0889)
		(layer "In15.Cu")
		(net "P5E_CPU1_PE0_TX_DP<15>")
	)
	(arc
		(start 103.363268 -222.433642)
		(mid 103.160681 -222.227291)
		(end 103.086662 -221.94774)
		(width 0.0889)
		(layer "In15.Cu")
		(net "P5E_CPU1_PE0_TX_DP<15>")
	)
	(arc
		(start 102.617016 -217.859864)
		(mid 102.697178 -217.587675)
		(end 102.899464 -217.388694)
		(width 0.0889)
		(layer "In15.Cu")
		(net "P5E_CPU1_PE0_TX_DP<15>")
	)
	(arc
		(start 103.83901 -224.8789)
		(mid 103.636187 -224.678669)
		(end 103.556816 -224.404936)
		(width 0.0889)
		(layer "In15.Cu")
		(net "P5E_CPU1_PE0_TX_DP<15>")
	)
	(arc
		(start 104.346248 -224.908618)
		(mid 104.336508 -224.912775)
		(end 104.32669 -224.916746)
		(width 0.0889)
		(layer "In15.Cu")
		(net "P5E_CPU1_PE0_TX_DP<15>")
	)
	(arc
		(start 102.61092 -214.448136)
		(mid 102.536983 -214.340508)
		(end 102.432866 -214.2617)
		(width 0.0889)
		(layer "In15.Cu")
		(net "P5E_CPU1_PE0_TX_DP<15>")
	)
	(arc
		(start 102.9081 -219.0115)
		(mid 103.086576 -218.692222)
		(end 102.9081 -218.372944)
		(width 0.0889)
		(layer "In15.Cu")
		(net "P5E_CPU1_PE0_TX_DP<15>")
	)
	(arc
		(start 103.83901 -223.251268)
		(mid 103.637728 -223.053781)
		(end 103.556816 -222.783654)
		(width 0.0889)
		(layer "In15.Cu")
		(net "P5E_CPU1_PE0_TX_DP<15>")
	)
	(arc
		(start 102.617016 -221.115382)
		(mid 102.697178 -220.843193)
		(end 102.899464 -220.644212)
		(width 0.0889)
		(layer "In15.Cu")
		(net "P5E_CPU1_PE0_TX_DP<15>")
	)
	(arc
		(start 102.437946 -214.941912)
		(mid 102.56886 -214.805552)
		(end 102.616508 -214.622634)
		(width 0.0889)
		(layer "In15.Cu")
		(net "P5E_CPU1_PE0_TX_DP<15>")
	)
	(arc
		(start 102.423468 -215.922606)
		(mid 102.14656 -215.433205)
		(end 102.429056 -214.946992)
		(width 0.0889)
		(layer "In15.Cu")
		(net "P5E_CPU1_PE0_TX_DP<15>")
	)
	(arc
		(start 102.617016 -216.25052)
		(mid 102.569337 -216.06762)
		(end 102.438454 -215.931242)
		(width 0.0889)
		(layer "In15.Cu")
		(net "P5E_CPU1_PE0_TX_DP<15>")
	)
	(arc
		(start 102.616508 -214.472266)
		(mid 102.615028 -214.459899)
		(end 102.61092 -214.448136)
		(width 0.0889)
		(layer "In15.Cu")
		(net "P5E_CPU1_PE0_TX_DP<15>")
	)
	(arc
		(start 102.899464 -219.995496)
		(mid 102.616932 -219.506148)
		(end 102.89921 -219.01658)
		(width 0.0889)
		(layer "In15.Cu")
		(net "P5E_CPU1_PE0_TX_DP<15>")
	)
	(arc
		(start 104.32669 -224.916746)
		(mid 104.078538 -224.953361)
		(end 103.83901 -224.8789)
		(width 0.0889)
		(layer "In15.Cu")
		(net "P5E_CPU1_PE0_TX_DP<15>")
	)
	(arc
		(start 102.899464 -220.644212)
		(mid 103.086767 -220.319854)
		(end 102.899464 -219.995496)
		(width 0.0889)
		(layer "In15.Cu")
		(net "P5E_CPU1_PE0_TX_DP<15>")
	)
	(arc
		(start 103.556816 -222.761556)
		(mid 103.509137 -222.578656)
		(end 103.378254 -222.442278)
		(width 0.0889)
		(layer "In15.Cu")
		(net "P5E_CPU1_PE0_TX_DP<15>")
	)
	(arc
		(start 102.899464 -216.739978)
		(mid 102.695129 -216.537373)
		(end 102.617016 -216.260426)
		(width 0.0889)
		(layer "In15.Cu")
		(net "P5E_CPU1_PE0_TX_DP<15>")
	)
	(arc
		(start 103.8479 -223.894904)
		(mid 104.026497 -223.575626)
		(end 103.8479 -223.256348)
		(width 0.0889)
		(layer "In15.Cu")
		(net "P5E_CPU1_PE0_TX_DP<15>")
	)
	(arc
		(start 102.164642 -213.914228)
		(mid 102.151495 -213.868185)
		(end 102.147116 -213.820502)
		(width 0.0889)
		(layer "In15.Cu")
		(net "P5E_CPU1_PE0_TX_DP<15>")
	)
	(arc
		(start 102.432866 -214.2617)
		(mid 102.291293 -214.150933)
		(end 102.197154 -213.997794)
		(width 0.0889)
		(layer "In15.Cu")
		(net "P5E_CPU1_PE0_TX_DP<15>")
	)
	(segment
		(start 103.181912 -224.925382)
		(end 103.181912 -224.389696)
		(width 0.13208)
		(layer "F.Cu")
		(net "P5E_CPU1_PE0_TX_DP<14>")
	)
	(segment
		(start 51.60772 -401.779994)
		(end 51.60772 -401.157186)
		(width 0.13208)
		(layer "F.Cu")
		(net "P5E_CPU1_PE0_TX_DP<14>")
	)
	(segment
		(start 51.60772 -401.157186)
		(end 51.906678 -400.858228)
		(width 0.13208)
		(layer "F.Cu")
		(net "P5E_CPU1_PE0_TX_DP<14>")
	)
	(segment
		(start 103.181912 -224.389696)
		(end 103.182166 -224.389442)
		(width 0.13208)
		(layer "F.Cu")
		(net "P5E_CPU1_PE0_TX_DP<14>")
	)
	(segment
		(start 51.932078 -402.104352)
		(end 51.60772 -401.779994)
		(width 0.13208)
		(layer "F.Cu")
		(net "P5E_CPU1_PE0_TX_DP<14>")
	)
	(segment
		(start 57.74563 -375.94032)
		(end 54.044342 -391.069576)
		(width 0.14732)
		(layer "In15.Cu")
		(net "P5E_CPU1_PE0_TX_DP<14>")
	)
	(segment
		(start 101.9683 -220.000576)
		(end 101.960426 -219.996004)
		(width 0.0889)
		(layer "In15.Cu")
		(net "P5E_CPU1_PE0_TX_DP<14>")
	)
	(segment
		(start 54.147212 -391.23874)
		(end 54.059582 -391.596626)
		(width 0.14732)
		(layer "In15.Cu")
		(net "P5E_CPU1_PE0_TX_DP<14>")
	)
	(segment
		(start 103.182166 -224.389442)
		(end 103.33863 -224.118424)
		(width 0.0889)
		(layer "In15.Cu")
		(net "P5E_CPU1_PE0_TX_DP<14>")
	)
	(segment
		(start 53.576474 -393.570714)
		(end 53.40731 -393.673076)
		(width 0.14732)
		(layer "In15.Cu")
		(net "P5E_CPU1_PE0_TX_DP<14>")
	)
	(segment
		(start 53.303678 -394.097256)
		(end 53.394864 -394.247878)
		(width 0.14732)
		(layer "In15.Cu")
		(net "P5E_CPU1_PE0_TX_DP<14>")
	)
	(segment
		(start 90.46972 -201.541126)
		(end 88.033098 -201.5363)
		(width 0.14732)
		(layer "In15.Cu")
		(net "P5E_CPU1_PE0_TX_DP<14>")
	)
	(segment
		(start 101.489256 -214.946992)
		(end 101.498146 -214.941912)
		(width 0.0889)
		(layer "In15.Cu")
		(net "P5E_CPU1_PE0_TX_DP<14>")
	)
	(segment
		(start 103.086662 -223.575626)
		(end 103.086662 -223.56699)
		(width 0.0889)
		(layer "In15.Cu")
		(net "P5E_CPU1_PE0_TX_DP<14>")
	)
	(segment
		(start 101.960426 -219.996004)
		(end 101.95941 -219.995496)
		(width 0.0889)
		(layer "In15.Cu")
		(net "P5E_CPU1_PE0_TX_DP<14>")
	)
	(segment
		(start 93.987112 -202.99807)
		(end 90.46972 -201.541126)
		(width 0.14732)
		(layer "In15.Cu")
		(net "P5E_CPU1_PE0_TX_DP<14>")
	)
	(segment
		(start 101.165152 -213.144608)
		(end 101.165152 -213.12251)
		(width 0.0889)
		(layer "In15.Cu")
		(net "P5E_CPU1_PE0_TX_DP<14>")
	)
	(segment
		(start 103.33863 -224.118424)
		(end 103.3145 -224.02927)
		(width 0.0889)
		(layer "In15.Cu")
		(net "P5E_CPU1_PE0_TX_DP<14>")
	)
	(segment
		(start 53.140356 -394.763752)
		(end 53.036724 -395.187932)
		(width 0.14732)
		(layer "In15.Cu")
		(net "P5E_CPU1_PE0_TX_DP<14>")
	)
	(segment
		(start 60.76696 -323.101716)
		(end 60.76823 -323.101208)
		(width 0.14732)
		(layer "In15.Cu")
		(net "P5E_CPU1_PE0_TX_DP<14>")
	)
	(segment
		(start 85.66404 -202.570588)
		(end 73.90384 -215.140286)
		(width 0.14732)
		(layer "In15.Cu")
		(net "P5E_CPU1_PE0_TX_DP<14>")
	)
	(segment
		(start 69.255894 -232.309924)
		(end 67.950842 -249.96902)
		(width 0.14732)
		(layer "In15.Cu")
		(net "P5E_CPU1_PE0_TX_DP<14>")
	)
	(segment
		(start 53.394864 -394.247878)
		(end 53.291232 -394.672312)
		(width 0.14732)
		(layer "In15.Cu")
		(net "P5E_CPU1_PE0_TX_DP<14>")
	)
	(segment
		(start 58.4454 -325.424038)
		(end 58.4454 -331.432662)
		(width 0.14732)
		(layer "In15.Cu")
		(net "P5E_CPU1_PE0_TX_DP<14>")
	)
	(segment
		(start 62.632082 -321.236594)
		(end 60.76696 -323.101716)
		(width 0.14732)
		(layer "In15.Cu")
		(net "P5E_CPU1_PE0_TX_DP<14>")
	)
	(segment
		(start 100.16363 -209.174588)
		(end 97.023682 -206.03464)
		(width 0.14732)
		(layer "In15.Cu")
		(net "P5E_CPU1_PE0_TX_DP<14>")
	)
	(segment
		(start 67.812158 -254.373126)
		(end 71.275448 -308.225444)
		(width 0.14732)
		(layer "In15.Cu")
		(net "P5E_CPU1_PE0_TX_DP<14>")
	)
	(segment
		(start 101.165152 -211.591906)
		(end 100.16363 -209.174588)
		(width 0.14732)
		(layer "In15.Cu")
		(net "P5E_CPU1_PE0_TX_DP<14>")
	)
	(segment
		(start 101.9683 -218.372944)
		(end 101.960426 -218.368372)
		(width 0.0889)
		(layer "In15.Cu")
		(net "P5E_CPU1_PE0_TX_DP<14>")
	)
	(segment
		(start 51.612038 -400.563588)
		(end 51.906678 -400.858228)
		(width 0.14732)
		(layer "In15.Cu")
		(net "P5E_CPU1_PE0_TX_DP<14>")
	)
	(segment
		(start 59.187334 -364.742476)
		(end 57.74563 -375.94032)
		(width 0.14732)
		(layer "In15.Cu")
		(net "P5E_CPU1_PE0_TX_DP<14>")
	)
	(segment
		(start 101.207316 -213.788498)
		(end 101.207316 -213.186772)
		(width 0.0889)
		(layer "In15.Cu")
		(net "P5E_CPU1_PE0_TX_DP<14>")
	)
	(segment
		(start 97.023682 -206.03464)
		(end 96.851216 -206.03464)
		(width 0.14732)
		(layer "In15.Cu")
		(net "P5E_CPU1_PE0_TX_DP<14>")
	)
	(segment
		(start 53.66385 -393.212574)
		(end 53.576474 -393.570714)
		(width 0.14732)
		(layer "In15.Cu")
		(net "P5E_CPU1_PE0_TX_DP<14>")
	)
	(segment
		(start 96.851216 -206.03464)
		(end 96.542098 -205.725522)
		(width 0.14732)
		(layer "In15.Cu")
		(net "P5E_CPU1_PE0_TX_DP<14>")
	)
	(segment
		(start 101.9683 -221.628462)
		(end 101.95941 -221.623382)
		(width 0.0889)
		(layer "In15.Cu")
		(net "P5E_CPU1_PE0_TX_DP<14>")
	)
	(segment
		(start 67.046602 -317.756794)
		(end 64.226694 -320.57594)
		(width 0.14732)
		(layer "In15.Cu")
		(net "P5E_CPU1_PE0_TX_DP<14>")
	)
	(segment
		(start 68.09994 -316.252098)
		(end 67.046602 -317.756794)
		(width 0.14732)
		(layer "In15.Cu")
		(net "P5E_CPU1_PE0_TX_DP<14>")
	)
	(segment
		(start 71.063612 -220.613732)
		(end 69.255894 -232.309924)
		(width 0.14732)
		(layer "In15.Cu")
		(net "P5E_CPU1_PE0_TX_DP<14>")
	)
	(segment
		(start 101.960426 -216.740486)
		(end 101.95941 -216.739978)
		(width 0.0889)
		(layer "In15.Cu")
		(net "P5E_CPU1_PE0_TX_DP<14>")
	)
	(segment
		(start 53.40731 -393.673076)
		(end 53.303678 -394.097256)
		(width 0.14732)
		(layer "In15.Cu")
		(net "P5E_CPU1_PE0_TX_DP<14>")
	)
	(segment
		(start 53.291232 -394.672312)
		(end 53.140356 -394.763752)
		(width 0.14732)
		(layer "In15.Cu")
		(net "P5E_CPU1_PE0_TX_DP<14>")
	)
	(segment
		(start 53.024278 -395.762988)
		(end 52.873402 -395.854428)
		(width 0.14732)
		(layer "In15.Cu")
		(net "P5E_CPU1_PE0_TX_DP<14>")
	)
	(segment
		(start 101.676708 -214.622634)
		(end 101.676708 -214.504016)
		(width 0.0889)
		(layer "In15.Cu")
		(net "P5E_CPU1_PE0_TX_DP<14>")
	)
	(segment
		(start 53.561488 -393.043918)
		(end 53.66385 -393.212574)
		(width 0.14732)
		(layer "In15.Cu")
		(net "P5E_CPU1_PE0_TX_DP<14>")
	)
	(segment
		(start 101.498654 -215.931242)
		(end 101.483668 -215.922606)
		(width 0.0889)
		(layer "In15.Cu")
		(net "P5E_CPU1_PE0_TX_DP<14>")
	)
	(segment
		(start 101.677216 -219.521532)
		(end 101.677216 -219.490544)
		(width 0.0889)
		(layer "In15.Cu")
		(net "P5E_CPU1_PE0_TX_DP<14>")
	)
	(segment
		(start 58.4454 -331.432662)
		(end 60.308998 -350.041718)
		(width 0.14732)
		(layer "In15.Cu")
		(net "P5E_CPU1_PE0_TX_DP<14>")
	)
	(segment
		(start 102.428802 -222.43669)
		(end 102.423468 -222.433642)
		(width 0.0889)
		(layer "In15.Cu")
		(net "P5E_CPU1_PE0_TX_DP<14>")
	)
	(segment
		(start 53.818028 -392.58367)
		(end 53.648864 -392.686286)
		(width 0.14732)
		(layer "In15.Cu")
		(net "P5E_CPU1_PE0_TX_DP<14>")
	)
	(segment
		(start 101.95941 -220.644212)
		(end 101.9683 -220.639132)
		(width 0.0889)
		(layer "In15.Cu")
		(net "P5E_CPU1_PE0_TX_DP<14>")
	)
	(segment
		(start 54.044596 -391.06983)
		(end 54.147212 -391.23874)
		(width 0.14732)
		(layer "In15.Cu")
		(net "P5E_CPU1_PE0_TX_DP<14>")
	)
	(segment
		(start 102.438454 -222.442278)
		(end 102.428802 -222.43669)
		(width 0.0889)
		(layer "In15.Cu")
		(net "P5E_CPU1_PE0_TX_DP<14>")
	)
	(segment
		(start 67.950842 -249.96902)
		(end 67.812158 -254.373126)
		(width 0.14732)
		(layer "In15.Cu")
		(net "P5E_CPU1_PE0_TX_DP<14>")
	)
	(segment
		(start 52.873402 -395.854428)
		(end 52.87391 -395.854428)
		(width 0.14732)
		(layer "In15.Cu")
		(net "P5E_CPU1_PE0_TX_DP<14>")
	)
	(segment
		(start 102.617016 -222.780098)
		(end 102.617016 -222.761556)
		(width 0.0889)
		(layer "In15.Cu")
		(net "P5E_CPU1_PE0_TX_DP<14>")
	)
	(segment
		(start 101.9683 -216.745058)
		(end 101.960426 -216.740486)
		(width 0.0889)
		(layer "In15.Cu")
		(net "P5E_CPU1_PE0_TX_DP<14>")
	)
	(segment
		(start 60.76823 -323.101208)
		(end 60.30976 -323.2912)
		(width 0.14732)
		(layer "In15.Cu")
		(net "P5E_CPU1_PE0_TX_DP<14>")
	)
	(segment
		(start 101.95941 -217.388694)
		(end 101.9683 -217.383614)
		(width 0.0889)
		(layer "In15.Cu")
		(net "P5E_CPU1_PE0_TX_DP<14>")
	)
	(segment
		(start 53.036724 -395.187932)
		(end 53.12791 -395.338554)
		(width 0.14732)
		(layer "In15.Cu")
		(net "P5E_CPU1_PE0_TX_DP<14>")
	)
	(segment
		(start 60.308998 -350.041718)
		(end 59.187334 -364.742476)
		(width 0.14732)
		(layer "In15.Cu")
		(net "P5E_CPU1_PE0_TX_DP<14>")
	)
	(segment
		(start 54.044342 -391.069576)
		(end 54.044596 -391.06983)
		(width 0.14732)
		(layer "In15.Cu")
		(net "P5E_CPU1_PE0_TX_DP<14>")
	)
	(segment
		(start 60.30976 -323.2912)
		(end 59.917076 -323.683884)
		(width 0.14732)
		(layer "In15.Cu")
		(net "P5E_CPU1_PE0_TX_DP<14>")
	)
	(segment
		(start 96.542098 -205.553056)
		(end 93.987112 -202.99807)
		(width 0.14732)
		(layer "In15.Cu")
		(net "P5E_CPU1_PE0_TX_DP<14>")
	)
	(segment
		(start 101.677216 -216.266014)
		(end 101.677216 -216.25052)
		(width 0.0889)
		(layer "In15.Cu")
		(net "P5E_CPU1_PE0_TX_DP<14>")
	)
	(segment
		(start 53.12791 -395.338554)
		(end 53.024278 -395.762988)
		(width 0.14732)
		(layer "In15.Cu")
		(net "P5E_CPU1_PE0_TX_DP<14>")
	)
	(segment
		(start 101.677216 -221.149418)
		(end 101.677216 -221.111826)
		(width 0.0889)
		(layer "In15.Cu")
		(net "P5E_CPU1_PE0_TX_DP<14>")
	)
	(segment
		(start 73.90384 -215.140286)
		(end 71.063612 -220.613732)
		(width 0.14732)
		(layer "In15.Cu")
		(net "P5E_CPU1_PE0_TX_DP<14>")
	)
	(segment
		(start 53.905658 -392.225784)
		(end 53.818028 -392.58367)
		(width 0.14732)
		(layer "In15.Cu")
		(net "P5E_CPU1_PE0_TX_DP<14>")
	)
	(segment
		(start 52.87391 -395.854428)
		(end 52.403756 -397.77543)
		(width 0.14732)
		(layer "In15.Cu")
		(net "P5E_CPU1_PE0_TX_DP<14>")
	)
	(segment
		(start 64.226694 -320.57594)
		(end 62.632082 -321.236594)
		(width 0.14732)
		(layer "In15.Cu")
		(net "P5E_CPU1_PE0_TX_DP<14>")
	)
	(segment
		(start 101.165152 -213.12251)
		(end 101.165152 -211.591906)
		(width 0.14732)
		(layer "In15.Cu")
		(net "P5E_CPU1_PE0_TX_DP<14>")
	)
	(segment
		(start 53.890418 -391.699242)
		(end 53.803042 -392.056874)
		(width 0.14732)
		(layer "In15.Cu")
		(net "P5E_CPU1_PE0_TX_DP<14>")
	)
	(segment
		(start 101.677216 -217.8939)
		(end 101.677216 -217.856308)
		(width 0.0889)
		(layer "In15.Cu")
		(net "P5E_CPU1_PE0_TX_DP<14>")
	)
	(segment
		(start 51.612038 -399.981674)
		(end 51.612038 -400.563588)
		(width 0.14732)
		(layer "In15.Cu")
		(net "P5E_CPU1_PE0_TX_DP<14>")
	)
	(segment
		(start 52.403756 -397.77543)
		(end 51.612038 -399.981674)
		(width 0.14732)
		(layer "In15.Cu")
		(net "P5E_CPU1_PE0_TX_DP<14>")
	)
	(segment
		(start 59.917076 -323.683884)
		(end 59.727084 -324.142354)
		(width 0.14732)
		(layer "In15.Cu")
		(net "P5E_CPU1_PE0_TX_DP<14>")
	)
	(segment
		(start 53.648864 -392.686286)
		(end 53.561488 -393.043918)
		(width 0.14732)
		(layer "In15.Cu")
		(net "P5E_CPU1_PE0_TX_DP<14>")
	)
	(segment
		(start 101.95941 -219.01658)
		(end 101.9683 -219.0115)
		(width 0.0889)
		(layer "In15.Cu")
		(net "P5E_CPU1_PE0_TX_DP<14>")
	)
	(segment
		(start 53.803042 -392.056874)
		(end 53.905658 -392.225784)
		(width 0.14732)
		(layer "In15.Cu")
		(net "P5E_CPU1_PE0_TX_DP<14>")
	)
	(segment
		(start 96.542098 -205.725522)
		(end 96.542098 -205.553056)
		(width 0.14732)
		(layer "In15.Cu")
		(net "P5E_CPU1_PE0_TX_DP<14>")
	)
	(segment
		(start 71.275448 -308.225444)
		(end 68.09994 -316.252098)
		(width 0.14732)
		(layer "In15.Cu")
		(net "P5E_CPU1_PE0_TX_DP<14>")
	)
	(segment
		(start 101.207316 -213.186772)
		(end 101.165152 -213.144608)
		(width 0.0889)
		(layer "In15.Cu")
		(net "P5E_CPU1_PE0_TX_DP<14>")
	)
	(segment
		(start 101.960426 -218.368372)
		(end 101.95941 -218.367864)
		(width 0.0889)
		(layer "In15.Cu")
		(net "P5E_CPU1_PE0_TX_DP<14>")
	)
	(segment
		(start 54.059582 -391.596626)
		(end 53.890418 -391.699242)
		(width 0.14732)
		(layer "In15.Cu")
		(net "P5E_CPU1_PE0_TX_DP<14>")
	)
	(segment
		(start 59.727084 -324.142354)
		(end 58.4454 -325.424038)
		(width 0.14732)
		(layer "In15.Cu")
		(net "P5E_CPU1_PE0_TX_DP<14>")
	)
	(segment
		(start 88.033098 -201.5363)
		(end 85.66404 -202.570588)
		(width 0.14732)
		(layer "In15.Cu")
		(net "P5E_CPU1_PE0_TX_DP<14>")
	)
	(arc
		(start 101.498146 -214.941912)
		(mid 101.62906 -214.805552)
		(end 101.676708 -214.622634)
		(width 0.0889)
		(layer "In15.Cu")
		(net "P5E_CPU1_PE0_TX_DP<14>")
	)
	(arc
		(start 102.899464 -223.251268)
		(mid 102.697178 -223.052287)
		(end 102.617016 -222.780098)
		(width 0.0889)
		(layer "In15.Cu")
		(net "P5E_CPU1_PE0_TX_DP<14>")
	)
	(arc
		(start 101.49586 -214.26932)
		(mid 101.479086 -214.256182)
		(end 101.461316 -214.244428)
		(width 0.0889)
		(layer "In15.Cu")
		(net "P5E_CPU1_PE0_TX_DP<14>")
	)
	(arc
		(start 101.483668 -215.922606)
		(mid 101.20676 -215.433205)
		(end 101.489256 -214.946992)
		(width 0.0889)
		(layer "In15.Cu")
		(net "P5E_CPU1_PE0_TX_DP<14>")
	)
	(arc
		(start 101.95941 -221.623382)
		(mid 101.756587 -221.423151)
		(end 101.677216 -221.149418)
		(width 0.0889)
		(layer "In15.Cu")
		(net "P5E_CPU1_PE0_TX_DP<14>")
	)
	(arc
		(start 101.9683 -217.383614)
		(mid 102.147018 -217.064336)
		(end 101.9683 -216.745058)
		(width 0.0889)
		(layer "In15.Cu")
		(net "P5E_CPU1_PE0_TX_DP<14>")
	)
	(arc
		(start 101.677216 -221.111826)
		(mid 101.758127 -220.841698)
		(end 101.95941 -220.644212)
		(width 0.0889)
		(layer "In15.Cu")
		(net "P5E_CPU1_PE0_TX_DP<14>")
	)
	(arc
		(start 101.95941 -216.739978)
		(mid 101.756587 -216.539747)
		(end 101.677216 -216.266014)
		(width 0.0889)
		(layer "In15.Cu")
		(net "P5E_CPU1_PE0_TX_DP<14>")
	)
	(arc
		(start 101.677216 -216.25052)
		(mid 101.629537 -216.06762)
		(end 101.498654 -215.931242)
		(width 0.0889)
		(layer "In15.Cu")
		(net "P5E_CPU1_PE0_TX_DP<14>")
	)
	(arc
		(start 101.676708 -214.504016)
		(mid 101.673032 -214.478944)
		(end 101.66223 -214.45601)
		(width 0.0889)
		(layer "In15.Cu")
		(net "P5E_CPU1_PE0_TX_DP<14>")
	)
	(arc
		(start 101.95941 -218.367864)
		(mid 101.756587 -218.167633)
		(end 101.677216 -217.8939)
		(width 0.0889)
		(layer "In15.Cu")
		(net "P5E_CPU1_PE0_TX_DP<14>")
	)
	(arc
		(start 101.9683 -220.639132)
		(mid 102.147018 -220.319854)
		(end 101.9683 -220.000576)
		(width 0.0889)
		(layer "In15.Cu")
		(net "P5E_CPU1_PE0_TX_DP<14>")
	)
	(arc
		(start 101.9683 -219.0115)
		(mid 102.146776 -218.692222)
		(end 101.9683 -218.372944)
		(width 0.0889)
		(layer "In15.Cu")
		(net "P5E_CPU1_PE0_TX_DP<14>")
	)
	(arc
		(start 101.677216 -217.856308)
		(mid 101.758127 -217.58618)
		(end 101.95941 -217.388694)
		(width 0.0889)
		(layer "In15.Cu")
		(net "P5E_CPU1_PE0_TX_DP<14>")
	)
	(arc
		(start 101.461316 -214.244428)
		(mid 101.275024 -214.049491)
		(end 101.207316 -213.788498)
		(width 0.0889)
		(layer "In15.Cu")
		(net "P5E_CPU1_PE0_TX_DP<14>")
	)
	(arc
		(start 103.086662 -223.56699)
		(mid 103.034392 -223.384625)
		(end 102.899464 -223.251268)
		(width 0.0889)
		(layer "In15.Cu")
		(net "P5E_CPU1_PE0_TX_DP<14>")
	)
	(arc
		(start 102.146862 -221.94774)
		(mid 102.099183 -221.76484)
		(end 101.9683 -221.628462)
		(width 0.0889)
		(layer "In15.Cu")
		(net "P5E_CPU1_PE0_TX_DP<14>")
	)
	(arc
		(start 102.423468 -222.433642)
		(mid 102.220881 -222.227291)
		(end 102.146862 -221.94774)
		(width 0.0889)
		(layer "In15.Cu")
		(net "P5E_CPU1_PE0_TX_DP<14>")
	)
	(arc
		(start 101.95941 -219.995496)
		(mid 101.756587 -219.795265)
		(end 101.677216 -219.521532)
		(width 0.0889)
		(layer "In15.Cu")
		(net "P5E_CPU1_PE0_TX_DP<14>")
	)
	(arc
		(start 103.3145 -224.02927)
		(mid 103.146746 -223.829492)
		(end 103.086662 -223.575626)
		(width 0.0889)
		(layer "In15.Cu")
		(net "P5E_CPU1_PE0_TX_DP<14>")
	)
	(arc
		(start 101.66223 -214.45601)
		(mid 101.5852 -214.35718)
		(end 101.49586 -214.26932)
		(width 0.0889)
		(layer "In15.Cu")
		(net "P5E_CPU1_PE0_TX_DP<14>")
	)
	(arc
		(start 101.677216 -219.490544)
		(mid 101.756586 -219.21681)
		(end 101.95941 -219.01658)
		(width 0.0889)
		(layer "In15.Cu")
		(net "P5E_CPU1_PE0_TX_DP<14>")
	)
	(arc
		(start 102.617016 -222.761556)
		(mid 102.569337 -222.578656)
		(end 102.438454 -222.442278)
		(width 0.0889)
		(layer "In15.Cu")
		(net "P5E_CPU1_PE0_TX_DP<14>")
	)
	(segment
		(start 102.712266 -225.739198)
		(end 102.712012 -225.738944)
		(width 0.13208)
		(layer "F.Cu")
		(net "P5E_CPU1_PE0_TX_DP<13>")
	)
	(segment
		(start 54.995318 -402.104352)
		(end 54.67096 -401.779994)
		(width 0.13208)
		(layer "F.Cu")
		(net "P5E_CPU1_PE0_TX_DP<13>")
	)
	(segment
		(start 54.67096 -401.779994)
		(end 54.67096 -401.157186)
		(width 0.13208)
		(layer "F.Cu")
		(net "P5E_CPU1_PE0_TX_DP<13>")
	)
	(segment
		(start 54.67096 -401.157186)
		(end 54.969918 -400.858228)
		(width 0.13208)
		(layer "F.Cu")
		(net "P5E_CPU1_PE0_TX_DP<13>")
	)
	(segment
		(start 102.712012 -225.738944)
		(end 102.712012 -225.203258)
		(width 0.13208)
		(layer "F.Cu")
		(net "P5E_CPU1_PE0_TX_DP<13>")
	)
	(segment
		(start 101.498654 -222.442278)
		(end 101.489002 -222.43669)
		(width 0.0889)
		(layer "In15.Cu")
		(net "P5E_CPU1_PE0_TX_DP<13>")
	)
	(segment
		(start 55.560468 -395.808962)
		(end 55.481982 -396.238984)
		(width 0.14732)
		(layer "In15.Cu")
		(net "P5E_CPU1_PE0_TX_DP<13>")
	)
	(segment
		(start 55.538878 -395.234668)
		(end 55.460392 -395.664182)
		(width 0.14732)
		(layer "In15.Cu")
		(net "P5E_CPU1_PE0_TX_DP<13>")
	)
	(segment
		(start 101.489002 -222.43669)
		(end 101.483668 -222.433642)
		(width 0.0889)
		(layer "In15.Cu")
		(net "P5E_CPU1_PE0_TX_DP<13>")
	)
	(segment
		(start 100.549202 -215.925654)
		(end 100.543868 -215.922606)
		(width 0.0889)
		(layer "In15.Cu")
		(net "P5E_CPU1_PE0_TX_DP<13>")
	)
	(segment
		(start 55.942992 -393.025884)
		(end 55.864506 -393.455398)
		(width 0.14732)
		(layer "In15.Cu")
		(net "P5E_CPU1_PE0_TX_DP<13>")
	)
	(segment
		(start 56.066436 -392.351006)
		(end 56.166512 -392.495786)
		(width 0.14732)
		(layer "In15.Cu")
		(net "P5E_CPU1_PE0_TX_DP<13>")
	)
	(segment
		(start 101.677216 -224.404936)
		(end 101.677216 -224.373948)
		(width 0.0889)
		(layer "In15.Cu")
		(net "P5E_CPU1_PE0_TX_DP<13>")
	)
	(segment
		(start 101.960426 -223.251776)
		(end 101.95941 -223.251268)
		(width 0.0889)
		(layer "In15.Cu")
		(net "P5E_CPU1_PE0_TX_DP<13>")
	)
	(segment
		(start 102.712012 -225.203258)
		(end 102.555548 -224.93224)
		(width 0.0889)
		(layer "In15.Cu")
		(net "P5E_CPU1_PE0_TX_DP<13>")
	)
	(segment
		(start 101.0285 -218.372944)
		(end 101.020626 -218.368372)
		(width 0.0889)
		(layer "In15.Cu")
		(net "P5E_CPU1_PE0_TX_DP<13>")
	)
	(segment
		(start 100.737416 -221.149418)
		(end 100.737416 -221.115382)
		(width 0.0889)
		(layer "In15.Cu")
		(net "P5E_CPU1_PE0_TX_DP<13>")
	)
	(segment
		(start 100.267516 -213.186772)
		(end 100.225352 -213.144608)
		(width 0.0889)
		(layer "In15.Cu")
		(net "P5E_CPU1_PE0_TX_DP<13>")
	)
	(segment
		(start 55.886096 -394.0302)
		(end 55.741062 -394.130276)
		(width 0.14732)
		(layer "In15.Cu")
		(net "P5E_CPU1_PE0_TX_DP<13>")
	)
	(segment
		(start 59.268106 -374.838468)
		(end 56.268366 -391.246614)
		(width 0.14732)
		(layer "In15.Cu")
		(net "P5E_CPU1_PE0_TX_DP<13>")
	)
	(segment
		(start 59.39409 -330.54671)
		(end 61.350398 -350.503236)
		(width 0.14732)
		(layer "In15.Cu")
		(net "P5E_CPU1_PE0_TX_DP<13>")
	)
	(segment
		(start 56.368442 -391.391394)
		(end 56.289956 -391.821416)
		(width 0.14732)
		(layer "In15.Cu")
		(net "P5E_CPU1_PE0_TX_DP<13>")
	)
	(segment
		(start 55.741062 -394.130276)
		(end 55.662576 -394.55979)
		(width 0.14732)
		(layer "In15.Cu")
		(net "P5E_CPU1_PE0_TX_DP<13>")
	)
	(segment
		(start 56.268366 -391.246614)
		(end 56.368442 -391.391394)
		(width 0.14732)
		(layer "In15.Cu")
		(net "P5E_CPU1_PE0_TX_DP<13>")
	)
	(segment
		(start 68.888356 -250.012962)
		(end 68.772024 -253.471426)
		(width 0.14732)
		(layer "In15.Cu")
		(net "P5E_CPU1_PE0_TX_DP<13>")
	)
	(segment
		(start 100.558854 -215.931242)
		(end 100.549202 -215.925654)
		(width 0.0889)
		(layer "In15.Cu")
		(net "P5E_CPU1_PE0_TX_DP<13>")
	)
	(segment
		(start 68.772024 -254.30226)
		(end 72.281034 -308.663086)
		(width 0.14732)
		(layer "In15.Cu")
		(net "P5E_CPU1_PE0_TX_DP<13>")
	)
	(segment
		(start 55.662576 -394.55979)
		(end 55.762398 -394.70457)
		(width 0.14732)
		(layer "In15.Cu")
		(net "P5E_CPU1_PE0_TX_DP<13>")
	)
	(segment
		(start 100.225352 -211.884768)
		(end 99.404678 -209.903568)
		(width 0.14732)
		(layer "In15.Cu")
		(net "P5E_CPU1_PE0_TX_DP<13>")
	)
	(segment
		(start 55.336948 -396.33906)
		(end 54.675278 -399.957544)
		(width 0.14732)
		(layer "In15.Cu")
		(net "P5E_CPU1_PE0_TX_DP<13>")
	)
	(segment
		(start 100.737416 -216.260426)
		(end 100.737416 -216.25052)
		(width 0.0889)
		(layer "In15.Cu")
		(net "P5E_CPU1_PE0_TX_DP<13>")
	)
	(segment
		(start 64.095376 -322.276216)
		(end 63.514478 -322.857114)
		(width 0.14732)
		(layer "In15.Cu")
		(net "P5E_CPU1_PE0_TX_DP<13>")
	)
	(segment
		(start 64.539622 -322.092066)
		(end 64.095376 -322.276216)
		(width 0.14732)
		(layer "In15.Cu")
		(net "P5E_CPU1_PE0_TX_DP<13>")
	)
	(segment
		(start 55.683912 -395.134592)
		(end 55.538878 -395.234668)
		(width 0.14732)
		(layer "In15.Cu")
		(net "P5E_CPU1_PE0_TX_DP<13>")
	)
	(segment
		(start 102.555548 -224.93224)
		(end 102.466648 -224.908618)
		(width 0.0889)
		(layer "In15.Cu")
		(net "P5E_CPU1_PE0_TX_DP<13>")
	)
	(segment
		(start 89.241122 -202.479402)
		(end 88.203278 -202.476862)
		(width 0.14732)
		(layer "In15.Cu")
		(net "P5E_CPU1_PE0_TX_DP<13>")
	)
	(segment
		(start 55.481982 -396.238984)
		(end 55.336948 -396.33906)
		(width 0.14732)
		(layer "In15.Cu")
		(net "P5E_CPU1_PE0_TX_DP<13>")
	)
	(segment
		(start 101.960426 -223.899476)
		(end 101.9683 -223.894904)
		(width 0.0889)
		(layer "In15.Cu")
		(net "P5E_CPU1_PE0_TX_DP<13>")
	)
	(segment
		(start 86.230714 -203.338176)
		(end 74.690478 -215.67267)
		(width 0.14732)
		(layer "In15.Cu")
		(net "P5E_CPU1_PE0_TX_DP<13>")
	)
	(segment
		(start 93.1799 -203.67879)
		(end 90.291412 -202.482196)
		(width 0.14732)
		(layer "In15.Cu")
		(net "P5E_CPU1_PE0_TX_DP<13>")
	)
	(segment
		(start 59.39409 -325.843138)
		(end 59.39409 -330.54671)
		(width 0.14732)
		(layer "In15.Cu")
		(net "P5E_CPU1_PE0_TX_DP<13>")
	)
	(segment
		(start 63.514478 -322.857114)
		(end 61.517022 -324.191884)
		(width 0.14732)
		(layer "In15.Cu")
		(net "P5E_CPU1_PE0_TX_DP<13>")
	)
	(segment
		(start 88.203278 -202.476862)
		(end 86.230714 -203.338176)
		(width 0.14732)
		(layer "In15.Cu")
		(net "P5E_CPU1_PE0_TX_DP<13>")
	)
	(segment
		(start 99.404678 -209.903568)
		(end 93.1799 -203.67879)
		(width 0.14732)
		(layer "In15.Cu")
		(net "P5E_CPU1_PE0_TX_DP<13>")
	)
	(segment
		(start 101.01961 -219.01658)
		(end 101.0285 -219.0115)
		(width 0.0889)
		(layer "In15.Cu")
		(net "P5E_CPU1_PE0_TX_DP<13>")
	)
	(segment
		(start 55.864506 -393.455398)
		(end 55.964582 -393.600178)
		(width 0.14732)
		(layer "In15.Cu")
		(net "P5E_CPU1_PE0_TX_DP<13>")
	)
	(segment
		(start 101.0285 -221.628462)
		(end 101.01961 -221.623382)
		(width 0.0889)
		(layer "In15.Cu")
		(net "P5E_CPU1_PE0_TX_DP<13>")
	)
	(segment
		(start 100.549456 -214.946992)
		(end 100.558346 -214.941912)
		(width 0.0889)
		(layer "In15.Cu")
		(net "P5E_CPU1_PE0_TX_DP<13>")
	)
	(segment
		(start 74.690478 -215.67267)
		(end 71.974964 -220.90634)
		(width 0.14732)
		(layer "In15.Cu")
		(net "P5E_CPU1_PE0_TX_DP<13>")
	)
	(segment
		(start 68.837048 -316.9666)
		(end 66.903346 -319.728342)
		(width 0.14732)
		(layer "In15.Cu")
		(net "P5E_CPU1_PE0_TX_DP<13>")
	)
	(segment
		(start 101.677216 -222.783654)
		(end 101.677216 -222.761556)
		(width 0.0889)
		(layer "In15.Cu")
		(net "P5E_CPU1_PE0_TX_DP<13>")
	)
	(segment
		(start 100.225352 -213.12251)
		(end 100.225352 -211.884768)
		(width 0.14732)
		(layer "In15.Cu")
		(net "P5E_CPU1_PE0_TX_DP<13>")
	)
	(segment
		(start 72.281034 -308.663086)
		(end 68.837048 -316.9666)
		(width 0.14732)
		(layer "In15.Cu")
		(net "P5E_CPU1_PE0_TX_DP<13>")
	)
	(segment
		(start 101.95941 -223.899984)
		(end 101.960426 -223.899476)
		(width 0.0889)
		(layer "In15.Cu")
		(net "P5E_CPU1_PE0_TX_DP<13>")
	)
	(segment
		(start 54.675278 -399.957544)
		(end 54.675278 -400.563588)
		(width 0.14732)
		(layer "In15.Cu")
		(net "P5E_CPU1_PE0_TX_DP<13>")
	)
	(segment
		(start 90.291412 -202.482196)
		(end 89.247218 -202.479402)
		(width 0.14732)
		(layer "In15.Cu")
		(net "P5E_CPU1_PE0_TX_DP<13>")
	)
	(segment
		(start 55.964582 -393.600178)
		(end 55.886096 -394.0302)
		(width 0.14732)
		(layer "In15.Cu")
		(net "P5E_CPU1_PE0_TX_DP<13>")
	)
	(segment
		(start 55.460392 -395.664182)
		(end 55.560468 -395.808962)
		(width 0.14732)
		(layer "In15.Cu")
		(net "P5E_CPU1_PE0_TX_DP<13>")
	)
	(segment
		(start 56.144922 -391.921492)
		(end 56.066436 -392.351006)
		(width 0.14732)
		(layer "In15.Cu")
		(net "P5E_CPU1_PE0_TX_DP<13>")
	)
	(segment
		(start 66.903346 -319.728342)
		(end 64.539622 -322.092066)
		(width 0.14732)
		(layer "In15.Cu")
		(net "P5E_CPU1_PE0_TX_DP<13>")
	)
	(segment
		(start 61.517022 -324.191884)
		(end 60.711842 -324.525386)
		(width 0.14732)
		(layer "In15.Cu")
		(net "P5E_CPU1_PE0_TX_DP<13>")
	)
	(segment
		(start 61.350398 -350.503236)
		(end 59.268106 -374.838468)
		(width 0.14732)
		(layer "In15.Cu")
		(net "P5E_CPU1_PE0_TX_DP<13>")
	)
	(segment
		(start 100.267516 -213.819232)
		(end 100.267516 -213.186772)
		(width 0.0889)
		(layer "In15.Cu")
		(net "P5E_CPU1_PE0_TX_DP<13>")
	)
	(segment
		(start 70.179946 -232.520744)
		(end 68.888356 -250.012962)
		(width 0.14732)
		(layer "In15.Cu")
		(net "P5E_CPU1_PE0_TX_DP<13>")
	)
	(segment
		(start 56.088026 -392.925808)
		(end 55.942992 -393.025884)
		(width 0.14732)
		(layer "In15.Cu")
		(net "P5E_CPU1_PE0_TX_DP<13>")
	)
	(segment
		(start 89.247218 -202.479402)
		(end 89.241122 -202.479402)
		(width 0.14732)
		(layer "In15.Cu")
		(net "P5E_CPU1_PE0_TX_DP<13>")
	)
	(segment
		(start 60.711842 -324.525386)
		(end 59.39409 -325.843138)
		(width 0.14732)
		(layer "In15.Cu")
		(net "P5E_CPU1_PE0_TX_DP<13>")
	)
	(segment
		(start 100.225352 -213.144608)
		(end 100.225352 -213.12251)
		(width 0.0889)
		(layer "In15.Cu")
		(net "P5E_CPU1_PE0_TX_DP<13>")
	)
	(segment
		(start 71.974964 -220.90634)
		(end 70.179946 -232.520744)
		(width 0.14732)
		(layer "In15.Cu")
		(net "P5E_CPU1_PE0_TX_DP<13>")
	)
	(segment
		(start 54.675278 -400.563588)
		(end 54.969918 -400.858228)
		(width 0.14732)
		(layer "In15.Cu")
		(net "P5E_CPU1_PE0_TX_DP<13>")
	)
	(segment
		(start 101.020626 -218.368372)
		(end 101.01961 -218.367864)
		(width 0.0889)
		(layer "In15.Cu")
		(net "P5E_CPU1_PE0_TX_DP<13>")
	)
	(segment
		(start 100.736908 -214.622634)
		(end 100.736908 -214.472266)
		(width 0.0889)
		(layer "In15.Cu")
		(net "P5E_CPU1_PE0_TX_DP<13>")
	)
	(segment
		(start 56.166512 -392.495786)
		(end 56.088026 -392.925808)
		(width 0.14732)
		(layer "In15.Cu")
		(net "P5E_CPU1_PE0_TX_DP<13>")
	)
	(segment
		(start 100.317046 -213.995762)
		(end 100.284788 -213.912704)
		(width 0.0889)
		(layer "In15.Cu")
		(net "P5E_CPU1_PE0_TX_DP<13>")
	)
	(segment
		(start 56.289956 -391.821416)
		(end 56.144922 -391.921492)
		(width 0.14732)
		(layer "In15.Cu")
		(net "P5E_CPU1_PE0_TX_DP<13>")
	)
	(segment
		(start 101.9683 -223.256348)
		(end 101.960426 -223.251776)
		(width 0.0889)
		(layer "In15.Cu")
		(net "P5E_CPU1_PE0_TX_DP<13>")
	)
	(segment
		(start 100.737416 -217.8939)
		(end 100.737416 -217.859864)
		(width 0.0889)
		(layer "In15.Cu")
		(net "P5E_CPU1_PE0_TX_DP<13>")
	)
	(segment
		(start 68.772024 -253.471426)
		(end 68.772024 -254.30226)
		(width 0.14732)
		(layer "In15.Cu")
		(net "P5E_CPU1_PE0_TX_DP<13>")
	)
	(segment
		(start 55.762398 -394.70457)
		(end 55.683912 -395.134592)
		(width 0.14732)
		(layer "In15.Cu")
		(net "P5E_CPU1_PE0_TX_DP<13>")
	)
	(arc
		(start 101.207062 -220.332046)
		(mid 101.207307 -220.32265)
		(end 101.207316 -220.31325)
		(width 0.0889)
		(layer "In15.Cu")
		(net "P5E_CPU1_PE0_TX_DP<13>")
	)
	(arc
		(start 101.483668 -222.433642)
		(mid 101.281081 -222.227291)
		(end 101.207062 -221.94774)
		(width 0.0889)
		(layer "In15.Cu")
		(net "P5E_CPU1_PE0_TX_DP<13>")
	)
	(arc
		(start 102.466648 -224.908618)
		(mid 102.456906 -224.912771)
		(end 102.44709 -224.916746)
		(width 0.0889)
		(layer "In15.Cu")
		(net "P5E_CPU1_PE0_TX_DP<13>")
	)
	(arc
		(start 101.019864 -216.739978)
		(mid 100.815529 -216.537373)
		(end 100.737416 -216.260426)
		(width 0.0889)
		(layer "In15.Cu")
		(net "P5E_CPU1_PE0_TX_DP<13>")
	)
	(arc
		(start 101.677216 -224.373948)
		(mid 101.756586 -224.100214)
		(end 101.95941 -223.899984)
		(width 0.0889)
		(layer "In15.Cu")
		(net "P5E_CPU1_PE0_TX_DP<13>")
	)
	(arc
		(start 100.737416 -219.490798)
		(mid 100.816727 -219.216923)
		(end 101.01961 -219.01658)
		(width 0.0889)
		(layer "In15.Cu")
		(net "P5E_CPU1_PE0_TX_DP<13>")
	)
	(arc
		(start 100.736908 -214.472266)
		(mid 100.735428 -214.459899)
		(end 100.73132 -214.448136)
		(width 0.0889)
		(layer "In15.Cu")
		(net "P5E_CPU1_PE0_TX_DP<13>")
	)
	(arc
		(start 102.44709 -224.916746)
		(mid 101.929421 -224.860579)
		(end 101.677216 -224.404936)
		(width 0.0889)
		(layer "In15.Cu")
		(net "P5E_CPU1_PE0_TX_DP<13>")
	)
	(arc
		(start 100.543868 -215.922606)
		(mid 100.267085 -215.433205)
		(end 100.549456 -214.946992)
		(width 0.0889)
		(layer "In15.Cu")
		(net "P5E_CPU1_PE0_TX_DP<13>")
	)
	(arc
		(start 100.284788 -213.912704)
		(mid 100.271806 -213.866771)
		(end 100.267516 -213.819232)
		(width 0.0889)
		(layer "In15.Cu")
		(net "P5E_CPU1_PE0_TX_DP<13>")
	)
	(arc
		(start 101.01961 -218.367864)
		(mid 100.816787 -218.167633)
		(end 100.737416 -217.8939)
		(width 0.0889)
		(layer "In15.Cu")
		(net "P5E_CPU1_PE0_TX_DP<13>")
	)
	(arc
		(start 100.737416 -217.859864)
		(mid 100.817578 -217.587675)
		(end 101.019864 -217.388694)
		(width 0.0889)
		(layer "In15.Cu")
		(net "P5E_CPU1_PE0_TX_DP<13>")
	)
	(arc
		(start 101.9683 -223.894904)
		(mid 102.146897 -223.575626)
		(end 101.9683 -223.256348)
		(width 0.0889)
		(layer "In15.Cu")
		(net "P5E_CPU1_PE0_TX_DP<13>")
	)
	(arc
		(start 101.207316 -217.057732)
		(mid 101.155379 -216.874223)
		(end 101.019864 -216.739978)
		(width 0.0889)
		(layer "In15.Cu")
		(net "P5E_CPU1_PE0_TX_DP<13>")
	)
	(arc
		(start 101.0285 -219.0115)
		(mid 101.206976 -218.692222)
		(end 101.0285 -218.372944)
		(width 0.0889)
		(layer "In15.Cu")
		(net "P5E_CPU1_PE0_TX_DP<13>")
	)
	(arc
		(start 101.019864 -220.644212)
		(mid 101.153887 -220.512385)
		(end 101.207062 -220.332046)
		(width 0.0889)
		(layer "In15.Cu")
		(net "P5E_CPU1_PE0_TX_DP<13>")
	)
	(arc
		(start 101.95941 -223.251268)
		(mid 101.758128 -223.053781)
		(end 101.677216 -222.783654)
		(width 0.0889)
		(layer "In15.Cu")
		(net "P5E_CPU1_PE0_TX_DP<13>")
	)
	(arc
		(start 100.73132 -214.448136)
		(mid 100.657264 -214.34048)
		(end 100.553012 -214.2617)
		(width 0.0889)
		(layer "In15.Cu")
		(net "P5E_CPU1_PE0_TX_DP<13>")
	)
	(arc
		(start 100.737416 -221.115382)
		(mid 100.817578 -220.843193)
		(end 101.019864 -220.644212)
		(width 0.0889)
		(layer "In15.Cu")
		(net "P5E_CPU1_PE0_TX_DP<13>")
	)
	(arc
		(start 100.558346 -214.941912)
		(mid 100.68926 -214.805552)
		(end 100.736908 -214.622634)
		(width 0.0889)
		(layer "In15.Cu")
		(net "P5E_CPU1_PE0_TX_DP<13>")
	)
	(arc
		(start 101.207062 -217.076528)
		(mid 101.207307 -217.067132)
		(end 101.207316 -217.057732)
		(width 0.0889)
		(layer "In15.Cu")
		(net "P5E_CPU1_PE0_TX_DP<13>")
	)
	(arc
		(start 100.737416 -219.515944)
		(mid 100.737279 -219.503371)
		(end 100.737416 -219.490798)
		(width 0.0889)
		(layer "In15.Cu")
		(net "P5E_CPU1_PE0_TX_DP<13>")
	)
	(arc
		(start 101.677216 -222.761556)
		(mid 101.629537 -222.578656)
		(end 101.498654 -222.442278)
		(width 0.0889)
		(layer "In15.Cu")
		(net "P5E_CPU1_PE0_TX_DP<13>")
	)
	(arc
		(start 101.019864 -217.388694)
		(mid 101.153887 -217.256867)
		(end 101.207062 -217.076528)
		(width 0.0889)
		(layer "In15.Cu")
		(net "P5E_CPU1_PE0_TX_DP<13>")
	)
	(arc
		(start 101.01961 -221.623382)
		(mid 100.816787 -221.423151)
		(end 100.737416 -221.149418)
		(width 0.0889)
		(layer "In15.Cu")
		(net "P5E_CPU1_PE0_TX_DP<13>")
	)
	(arc
		(start 101.207316 -220.31325)
		(mid 101.155379 -220.129741)
		(end 101.019864 -219.995496)
		(width 0.0889)
		(layer "In15.Cu")
		(net "P5E_CPU1_PE0_TX_DP<13>")
	)
	(arc
		(start 101.019864 -219.995496)
		(mid 100.815529 -219.792891)
		(end 100.737416 -219.515944)
		(width 0.0889)
		(layer "In15.Cu")
		(net "P5E_CPU1_PE0_TX_DP<13>")
	)
	(arc
		(start 100.553012 -214.2617)
		(mid 100.410937 -214.150096)
		(end 100.317046 -213.995762)
		(width 0.0889)
		(layer "In15.Cu")
		(net "P5E_CPU1_PE0_TX_DP<13>")
	)
	(arc
		(start 100.737416 -216.25052)
		(mid 100.689737 -216.06762)
		(end 100.558854 -215.931242)
		(width 0.0889)
		(layer "In15.Cu")
		(net "P5E_CPU1_PE0_TX_DP<13>")
	)
	(arc
		(start 101.207062 -221.94774)
		(mid 101.159383 -221.76484)
		(end 101.0285 -221.628462)
		(width 0.0889)
		(layer "In15.Cu")
		(net "P5E_CPU1_PE0_TX_DP<13>")
	)
	(segment
		(start 101.302566 -224.925128)
		(end 101.302566 -224.389442)
		(width 0.13208)
		(layer "F.Cu")
		(net "P5E_CPU1_PE0_TX_DP<12>")
	)
	(segment
		(start 101.302312 -224.925382)
		(end 101.302566 -224.925128)
		(width 0.13208)
		(layer "F.Cu")
		(net "P5E_CPU1_PE0_TX_DP<12>")
	)
	(segment
		(start 57.7342 -401.157186)
		(end 58.033158 -400.858228)
		(width 0.13208)
		(layer "F.Cu")
		(net "P5E_CPU1_PE0_TX_DP<12>")
	)
	(segment
		(start 58.058558 -402.104352)
		(end 57.7342 -401.779994)
		(width 0.13208)
		(layer "F.Cu")
		(net "P5E_CPU1_PE0_TX_DP<12>")
	)
	(segment
		(start 57.7342 -401.779994)
		(end 57.7342 -401.157186)
		(width 0.13208)
		(layer "F.Cu")
		(net "P5E_CPU1_PE0_TX_DP<12>")
	)
	(segment
		(start 94.061534 -206.062326)
		(end 94.061534 -205.88986)
		(width 0.14732)
		(layer "In15.Cu")
		(net "P5E_CPU1_PE0_TX_DP<12>")
	)
	(segment
		(start 58.650124 -392.592306)
		(end 58.650378 -392.59256)
		(width 0.14732)
		(layer "In15.Cu")
		(net "P5E_CPU1_PE0_TX_DP<12>")
	)
	(segment
		(start 99.285552 -213.144608)
		(end 99.285552 -213.12251)
		(width 0.0889)
		(layer "In15.Cu")
		(net "P5E_CPU1_PE0_TX_DP<12>")
	)
	(segment
		(start 75.50912 -216.235026)
		(end 73.031604 -221.009718)
		(width 0.14732)
		(layer "In15.Cu")
		(net "P5E_CPU1_PE0_TX_DP<12>")
	)
	(segment
		(start 73.031604 -221.009718)
		(end 71.241666 -232.591356)
		(width 0.14732)
		(layer "In15.Cu")
		(net "P5E_CPU1_PE0_TX_DP<12>")
	)
	(segment
		(start 99.610164 -215.926162)
		(end 99.609402 -215.925654)
		(width 0.0889)
		(layer "In15.Cu")
		(net "P5E_CPU1_PE0_TX_DP<12>")
	)
	(segment
		(start 58.428382 -395.393926)
		(end 58.28919 -395.50213)
		(width 0.14732)
		(layer "In15.Cu")
		(net "P5E_CPU1_PE0_TX_DP<12>")
	)
	(segment
		(start 58.704988 -393.16533)
		(end 58.565796 -393.273534)
		(width 0.14732)
		(layer "In15.Cu")
		(net "P5E_CPU1_PE0_TX_DP<12>")
	)
	(segment
		(start 100.0887 -221.628462)
		(end 100.080826 -221.62389)
		(width 0.0889)
		(layer "In15.Cu")
		(net "P5E_CPU1_PE0_TX_DP<12>")
	)
	(segment
		(start 58.566812 -394.279628)
		(end 58.42762 -394.387832)
		(width 0.14732)
		(layer "In15.Cu")
		(net "P5E_CPU1_PE0_TX_DP<12>")
	)
	(segment
		(start 100.080826 -219.996004)
		(end 100.080826 -219.99575)
		(width 0.0889)
		(layer "In15.Cu")
		(net "P5E_CPU1_PE0_TX_DP<12>")
	)
	(segment
		(start 58.481976 -394.960094)
		(end 58.428382 -395.393926)
		(width 0.14732)
		(layer "In15.Cu")
		(net "P5E_CPU1_PE0_TX_DP<12>")
	)
	(segment
		(start 93.580204 -205.580996)
		(end 93.271086 -205.271878)
		(width 0.14732)
		(layer "In15.Cu")
		(net "P5E_CPU1_PE0_TX_DP<12>")
	)
	(segment
		(start 58.28919 -395.50213)
		(end 58.235596 -395.935454)
		(width 0.14732)
		(layer "In15.Cu")
		(net "P5E_CPU1_PE0_TX_DP<12>")
	)
	(segment
		(start 100.066856 -219.987876)
		(end 100.066856 -219.987622)
		(width 0.0889)
		(layer "In15.Cu")
		(net "P5E_CPU1_PE0_TX_DP<12>")
	)
	(segment
		(start 100.084636 -219.99829)
		(end 100.080826 -219.996004)
		(width 0.0889)
		(layer "In15.Cu")
		(net "P5E_CPU1_PE0_TX_DP<12>")
	)
	(segment
		(start 57.738518 -399.942812)
		(end 57.738518 -400.563588)
		(width 0.14732)
		(layer "In15.Cu")
		(net "P5E_CPU1_PE0_TX_DP<12>")
	)
	(segment
		(start 99.797108 -214.622634)
		(end 99.797108 -214.582502)
		(width 0.0889)
		(layer "In15.Cu")
		(net "P5E_CPU1_PE0_TX_DP<12>")
	)
	(segment
		(start 58.758582 -392.731498)
		(end 58.704988 -393.16533)
		(width 0.14732)
		(layer "In15.Cu")
		(net "P5E_CPU1_PE0_TX_DP<12>")
	)
	(segment
		(start 94.370652 -206.371444)
		(end 94.061534 -206.062326)
		(width 0.14732)
		(layer "In15.Cu")
		(net "P5E_CPU1_PE0_TX_DP<12>")
	)
	(segment
		(start 99.327462 -215.436704)
		(end 99.327462 -215.414606)
		(width 0.0889)
		(layer "In15.Cu")
		(net "P5E_CPU1_PE0_TX_DP<12>")
	)
	(segment
		(start 101.45903 -224.118424)
		(end 101.4349 -224.02927)
		(width 0.0889)
		(layer "In15.Cu")
		(net "P5E_CPU1_PE0_TX_DP<12>")
	)
	(segment
		(start 100.080826 -221.62389)
		(end 100.07981 -221.623382)
		(width 0.0889)
		(layer "In15.Cu")
		(net "P5E_CPU1_PE0_TX_DP<12>")
	)
	(segment
		(start 99.285552 -212.062314)
		(end 98.614738 -210.443064)
		(width 0.14732)
		(layer "In15.Cu")
		(net "P5E_CPU1_PE0_TX_DP<12>")
	)
	(segment
		(start 69.825616 -250.056904)
		(end 69.704204 -253.695708)
		(width 0.14732)
		(layer "In15.Cu")
		(net "P5E_CPU1_PE0_TX_DP<12>")
	)
	(segment
		(start 61.289184 -325.304404)
		(end 60.355226 -326.238362)
		(width 0.14732)
		(layer "In15.Cu")
		(net "P5E_CPU1_PE0_TX_DP<12>")
	)
	(segment
		(start 99.609656 -214.946992)
		(end 99.618546 -214.941912)
		(width 0.0889)
		(layer "In15.Cu")
		(net "P5E_CPU1_PE0_TX_DP<12>")
	)
	(segment
		(start 100.080826 -218.368118)
		(end 100.071682 -218.362784)
		(width 0.0889)
		(layer "In15.Cu")
		(net "P5E_CPU1_PE0_TX_DP<12>")
	)
	(segment
		(start 58.235596 -395.935454)
		(end 58.3438 -396.074138)
		(width 0.14732)
		(layer "In15.Cu")
		(net "P5E_CPU1_PE0_TX_DP<12>")
	)
	(segment
		(start 100.080826 -219.99575)
		(end 100.066856 -219.987876)
		(width 0.0889)
		(layer "In15.Cu")
		(net "P5E_CPU1_PE0_TX_DP<12>")
	)
	(segment
		(start 100.0887 -220.000576)
		(end 100.084636 -219.99829)
		(width 0.0889)
		(layer "In15.Cu")
		(net "P5E_CPU1_PE0_TX_DP<12>")
	)
	(segment
		(start 58.374026 -394.821156)
		(end 58.481976 -394.960094)
		(width 0.14732)
		(layer "In15.Cu")
		(net "P5E_CPU1_PE0_TX_DP<12>")
	)
	(segment
		(start 99.350068 -213.985602)
		(end 99.350576 -213.985348)
		(width 0.0889)
		(layer "In15.Cu")
		(net "P5E_CPU1_PE0_TX_DP<12>")
	)
	(segment
		(start 58.42762 -394.387832)
		(end 58.374026 -394.821156)
		(width 0.14732)
		(layer "In15.Cu")
		(net "P5E_CPU1_PE0_TX_DP<12>")
	)
	(segment
		(start 94.061534 -205.88986)
		(end 93.75267 -205.580996)
		(width 0.14732)
		(layer "In15.Cu")
		(net "P5E_CPU1_PE0_TX_DP<12>")
	)
	(segment
		(start 69.831712 -317.206884)
		(end 67.63385 -320.345562)
		(width 0.14732)
		(layer "In15.Cu")
		(net "P5E_CPU1_PE0_TX_DP<12>")
	)
	(segment
		(start 95.33382 -207.162146)
		(end 95.161354 -207.162146)
		(width 0.14732)
		(layer "In15.Cu")
		(net "P5E_CPU1_PE0_TX_DP<12>")
	)
	(segment
		(start 95.161354 -207.162146)
		(end 94.851982 -206.852774)
		(width 0.14732)
		(layer "In15.Cu")
		(net "P5E_CPU1_PE0_TX_DP<12>")
	)
	(segment
		(start 100.083874 -219.014294)
		(end 100.086414 -219.013024)
		(width 0.0889)
		(layer "In15.Cu")
		(net "P5E_CPU1_PE0_TX_DP<12>")
	)
	(segment
		(start 94.851982 -206.680308)
		(end 94.543118 -206.371444)
		(width 0.14732)
		(layer "In15.Cu")
		(net "P5E_CPU1_PE0_TX_DP<12>")
	)
	(segment
		(start 57.738518 -400.563588)
		(end 58.033158 -400.858228)
		(width 0.14732)
		(layer "In15.Cu")
		(net "P5E_CPU1_PE0_TX_DP<12>")
	)
	(segment
		(start 100.06711 -218.360244)
		(end 100.066856 -218.35999)
		(width 0.0889)
		(layer "In15.Cu")
		(net "P5E_CPU1_PE0_TX_DP<12>")
	)
	(segment
		(start 60.738512 -375.754392)
		(end 58.650124 -392.592306)
		(width 0.14732)
		(layer "In15.Cu")
		(net "P5E_CPU1_PE0_TX_DP<12>")
	)
	(segment
		(start 99.611688 -215.926924)
		(end 99.610164 -215.926162)
		(width 0.0889)
		(layer "In15.Cu")
		(net "P5E_CPU1_PE0_TX_DP<12>")
	)
	(segment
		(start 100.06965 -217.39479)
		(end 100.080572 -217.388694)
		(width 0.0889)
		(layer "In15.Cu")
		(net "P5E_CPU1_PE0_TX_DP<12>")
	)
	(segment
		(start 101.207062 -223.575626)
		(end 101.207062 -223.56699)
		(width 0.0889)
		(layer "In15.Cu")
		(net "P5E_CPU1_PE0_TX_DP<12>")
	)
	(segment
		(start 100.085652 -216.743026)
		(end 100.07981 -216.739978)
		(width 0.0889)
		(layer "In15.Cu")
		(net "P5E_CPU1_PE0_TX_DP<12>")
	)
	(segment
		(start 67.63385 -320.345562)
		(end 65.040764 -322.938394)
		(width 0.14732)
		(layer "In15.Cu")
		(net "P5E_CPU1_PE0_TX_DP<12>")
	)
	(segment
		(start 100.558854 -222.442278)
		(end 100.549964 -222.437198)
		(width 0.0889)
		(layer "In15.Cu")
		(net "P5E_CPU1_PE0_TX_DP<12>")
	)
	(segment
		(start 100.071682 -218.362784)
		(end 100.06711 -218.360244)
		(width 0.0889)
		(layer "In15.Cu")
		(net "P5E_CPU1_PE0_TX_DP<12>")
	)
	(segment
		(start 101.302566 -224.389442)
		(end 101.45903 -224.118424)
		(width 0.0889)
		(layer "In15.Cu")
		(net "P5E_CPU1_PE0_TX_DP<12>")
	)
	(segment
		(start 99.609402 -215.925654)
		(end 99.604068 -215.922606)
		(width 0.0889)
		(layer "In15.Cu")
		(net "P5E_CPU1_PE0_TX_DP<12>")
	)
	(segment
		(start 58.151014 -396.616174)
		(end 57.738518 -399.942812)
		(width 0.14732)
		(layer "In15.Cu")
		(net "P5E_CPU1_PE0_TX_DP<12>")
	)
	(segment
		(start 100.737416 -222.780098)
		(end 100.737416 -222.761556)
		(width 0.0889)
		(layer "In15.Cu")
		(net "P5E_CPU1_PE0_TX_DP<12>")
	)
	(segment
		(start 60.355226 -330.24064)
		(end 62.291722 -350.373696)
		(width 0.14732)
		(layer "In15.Cu")
		(net "P5E_CPU1_PE0_TX_DP<12>")
	)
	(segment
		(start 61.938662 -325.035418)
		(end 61.289184 -325.304404)
		(width 0.14732)
		(layer "In15.Cu")
		(net "P5E_CPU1_PE0_TX_DP<12>")
	)
	(segment
		(start 93.75267 -205.580996)
		(end 93.580204 -205.580996)
		(width 0.14732)
		(layer "In15.Cu")
		(net "P5E_CPU1_PE0_TX_DP<12>")
	)
	(segment
		(start 92.731844 -204.56017)
		(end 89.984326 -203.421996)
		(width 0.14732)
		(layer "In15.Cu")
		(net "P5E_CPU1_PE0_TX_DP<12>")
	)
	(segment
		(start 73.260966 -308.929532)
		(end 69.831712 -317.206884)
		(width 0.14732)
		(layer "In15.Cu")
		(net "P5E_CPU1_PE0_TX_DP<12>")
	)
	(segment
		(start 98.614738 -210.443064)
		(end 95.33382 -207.162146)
		(width 0.14732)
		(layer "In15.Cu")
		(net "P5E_CPU1_PE0_TX_DP<12>")
	)
	(segment
		(start 71.241666 -232.591356)
		(end 69.825616 -250.056904)
		(width 0.14732)
		(layer "In15.Cu")
		(net "P5E_CPU1_PE0_TX_DP<12>")
	)
	(segment
		(start 99.797616 -216.266014)
		(end 99.797616 -216.25052)
		(width 0.0889)
		(layer "In15.Cu")
		(net "P5E_CPU1_PE0_TX_DP<12>")
	)
	(segment
		(start 64.15405 -323.554852)
		(end 61.938662 -325.035418)
		(width 0.14732)
		(layer "In15.Cu")
		(net "P5E_CPU1_PE0_TX_DP<12>")
	)
	(segment
		(start 100.07981 -220.644212)
		(end 100.0887 -220.639132)
		(width 0.0889)
		(layer "In15.Cu")
		(net "P5E_CPU1_PE0_TX_DP<12>")
	)
	(segment
		(start 60.355226 -326.238362)
		(end 60.355226 -330.24064)
		(width 0.14732)
		(layer "In15.Cu")
		(net "P5E_CPU1_PE0_TX_DP<12>")
	)
	(segment
		(start 58.565796 -393.273534)
		(end 58.512202 -393.706858)
		(width 0.14732)
		(layer "In15.Cu")
		(net "P5E_CPU1_PE0_TX_DP<12>")
	)
	(segment
		(start 69.704204 -253.695708)
		(end 73.260966 -308.929532)
		(width 0.14732)
		(layer "In15.Cu")
		(net "P5E_CPU1_PE0_TX_DP<12>")
	)
	(segment
		(start 99.327716 -213.186772)
		(end 99.285552 -213.144608)
		(width 0.0889)
		(layer "In15.Cu")
		(net "P5E_CPU1_PE0_TX_DP<12>")
	)
	(segment
		(start 65.040764 -322.938394)
		(end 64.579246 -323.129656)
		(width 0.14732)
		(layer "In15.Cu")
		(net "P5E_CPU1_PE0_TX_DP<12>")
	)
	(segment
		(start 58.650378 -392.59256)
		(end 58.758582 -392.731498)
		(width 0.14732)
		(layer "In15.Cu")
		(net "P5E_CPU1_PE0_TX_DP<12>")
	)
	(segment
		(start 99.619054 -215.931242)
		(end 99.611688 -215.926924)
		(width 0.0889)
		(layer "In15.Cu")
		(net "P5E_CPU1_PE0_TX_DP<12>")
	)
	(segment
		(start 93.271086 -205.271878)
		(end 93.271086 -205.099412)
		(width 0.14732)
		(layer "In15.Cu")
		(net "P5E_CPU1_PE0_TX_DP<12>")
	)
	(segment
		(start 58.3438 -396.074138)
		(end 58.289952 -396.50797)
		(width 0.14732)
		(layer "In15.Cu")
		(net "P5E_CPU1_PE0_TX_DP<12>")
	)
	(segment
		(start 58.289952 -396.50797)
		(end 58.151014 -396.616174)
		(width 0.14732)
		(layer "In15.Cu")
		(net "P5E_CPU1_PE0_TX_DP<12>")
	)
	(segment
		(start 64.579246 -323.129656)
		(end 64.15405 -323.554852)
		(width 0.14732)
		(layer "In15.Cu")
		(net "P5E_CPU1_PE0_TX_DP<12>")
	)
	(segment
		(start 99.797616 -221.149418)
		(end 99.797616 -221.111826)
		(width 0.0889)
		(layer "In15.Cu")
		(net "P5E_CPU1_PE0_TX_DP<12>")
	)
	(segment
		(start 58.620406 -393.845796)
		(end 58.566812 -394.279628)
		(width 0.14732)
		(layer "In15.Cu")
		(net "P5E_CPU1_PE0_TX_DP<12>")
	)
	(segment
		(start 94.543118 -206.371444)
		(end 94.370652 -206.371444)
		(width 0.14732)
		(layer "In15.Cu")
		(net "P5E_CPU1_PE0_TX_DP<12>")
	)
	(segment
		(start 58.512202 -393.706858)
		(end 58.620406 -393.845796)
		(width 0.14732)
		(layer "In15.Cu")
		(net "P5E_CPU1_PE0_TX_DP<12>")
	)
	(segment
		(start 100.066856 -219.024454)
		(end 100.083874 -219.014294)
		(width 0.0889)
		(layer "In15.Cu")
		(net "P5E_CPU1_PE0_TX_DP<12>")
	)
	(segment
		(start 62.291722 -350.373696)
		(end 60.738512 -375.754392)
		(width 0.14732)
		(layer "In15.Cu")
		(net "P5E_CPU1_PE0_TX_DP<12>")
	)
	(segment
		(start 88.382856 -203.417424)
		(end 86.89086 -204.069188)
		(width 0.14732)
		(layer "In15.Cu")
		(net "P5E_CPU1_PE0_TX_DP<12>")
	)
	(segment
		(start 89.984326 -203.421996)
		(end 88.382856 -203.417424)
		(width 0.14732)
		(layer "In15.Cu")
		(net "P5E_CPU1_PE0_TX_DP<12>")
	)
	(segment
		(start 93.271086 -205.099412)
		(end 92.731844 -204.56017)
		(width 0.14732)
		(layer "In15.Cu")
		(net "P5E_CPU1_PE0_TX_DP<12>")
	)
	(segment
		(start 100.549964 -222.437198)
		(end 100.543868 -222.433642)
		(width 0.0889)
		(layer "In15.Cu")
		(net "P5E_CPU1_PE0_TX_DP<12>")
	)
	(segment
		(start 94.851982 -206.852774)
		(end 94.851982 -206.680308)
		(width 0.14732)
		(layer "In15.Cu")
		(net "P5E_CPU1_PE0_TX_DP<12>")
	)
	(segment
		(start 99.285552 -213.12251)
		(end 99.285552 -212.062314)
		(width 0.14732)
		(layer "In15.Cu")
		(net "P5E_CPU1_PE0_TX_DP<12>")
	)
	(segment
		(start 99.327716 -213.8807)
		(end 99.327716 -213.186772)
		(width 0.0889)
		(layer "In15.Cu")
		(net "P5E_CPU1_PE0_TX_DP<12>")
	)
	(segment
		(start 86.89086 -204.069188)
		(end 75.50912 -216.235026)
		(width 0.14732)
		(layer "In15.Cu")
		(net "P5E_CPU1_PE0_TX_DP<12>")
	)
	(arc
		(start 100.086414 -219.013024)
		(mid 100.267395 -218.688977)
		(end 100.080826 -218.368118)
		(width 0.0889)
		(layer "In15.Cu")
		(net "P5E_CPU1_PE0_TX_DP<12>")
	)
	(arc
		(start 100.07981 -221.623382)
		(mid 99.876987 -221.423151)
		(end 99.797616 -221.149418)
		(width 0.0889)
		(layer "In15.Cu")
		(net "P5E_CPU1_PE0_TX_DP<12>")
	)
	(arc
		(start 101.207062 -223.56699)
		(mid 101.154792 -223.384625)
		(end 101.019864 -223.251268)
		(width 0.0889)
		(layer "In15.Cu")
		(net "P5E_CPU1_PE0_TX_DP<12>")
	)
	(arc
		(start 99.604068 -215.922606)
		(mid 99.401481 -215.716255)
		(end 99.327462 -215.436704)
		(width 0.0889)
		(layer "In15.Cu")
		(net "P5E_CPU1_PE0_TX_DP<12>")
	)
	(arc
		(start 99.350576 -213.985348)
		(mid 99.333446 -213.934271)
		(end 99.327716 -213.8807)
		(width 0.0889)
		(layer "In15.Cu")
		(net "P5E_CPU1_PE0_TX_DP<12>")
	)
	(arc
		(start 100.267262 -221.94774)
		(mid 100.219583 -221.76484)
		(end 100.0887 -221.628462)
		(width 0.0889)
		(layer "In15.Cu")
		(net "P5E_CPU1_PE0_TX_DP<12>")
	)
	(arc
		(start 100.07981 -216.739978)
		(mid 99.876987 -216.539747)
		(end 99.797616 -216.266014)
		(width 0.0889)
		(layer "In15.Cu")
		(net "P5E_CPU1_PE0_TX_DP<12>")
	)
	(arc
		(start 99.605084 -214.25789)
		(mid 99.455799 -214.142132)
		(end 99.350068 -213.985602)
		(width 0.0889)
		(layer "In15.Cu")
		(net "P5E_CPU1_PE0_TX_DP<12>")
	)
	(arc
		(start 99.618546 -214.941912)
		(mid 99.74946 -214.805552)
		(end 99.797108 -214.622634)
		(width 0.0889)
		(layer "In15.Cu")
		(net "P5E_CPU1_PE0_TX_DP<12>")
	)
	(arc
		(start 100.0887 -220.639132)
		(mid 100.267297 -220.319854)
		(end 100.0887 -220.000576)
		(width 0.0889)
		(layer "In15.Cu")
		(net "P5E_CPU1_PE0_TX_DP<12>")
	)
	(arc
		(start 99.79787 -217.856308)
		(mid 99.875625 -217.59131)
		(end 100.06965 -217.39479)
		(width 0.0889)
		(layer "In15.Cu")
		(net "P5E_CPU1_PE0_TX_DP<12>")
	)
	(arc
		(start 100.080572 -217.388694)
		(mid 100.267483 -217.067298)
		(end 100.085652 -216.743026)
		(width 0.0889)
		(layer "In15.Cu")
		(net "P5E_CPU1_PE0_TX_DP<12>")
	)
	(arc
		(start 99.327462 -215.414606)
		(mid 99.408373 -215.144478)
		(end 99.609656 -214.946992)
		(width 0.0889)
		(layer "In15.Cu")
		(net "P5E_CPU1_PE0_TX_DP<12>")
	)
	(arc
		(start 99.797616 -221.111826)
		(mid 99.878527 -220.841698)
		(end 100.07981 -220.644212)
		(width 0.0889)
		(layer "In15.Cu")
		(net "P5E_CPU1_PE0_TX_DP<12>")
	)
	(arc
		(start 100.737416 -222.761556)
		(mid 100.689737 -222.578656)
		(end 100.558854 -222.442278)
		(width 0.0889)
		(layer "In15.Cu")
		(net "P5E_CPU1_PE0_TX_DP<12>")
	)
	(arc
		(start 100.066856 -219.987622)
		(mid 99.797656 -219.506038)
		(end 100.066856 -219.024454)
		(width 0.0889)
		(layer "In15.Cu")
		(net "P5E_CPU1_PE0_TX_DP<12>")
	)
	(arc
		(start 100.543868 -222.433642)
		(mid 100.341281 -222.227291)
		(end 100.267262 -221.94774)
		(width 0.0889)
		(layer "In15.Cu")
		(net "P5E_CPU1_PE0_TX_DP<12>")
	)
	(arc
		(start 100.066856 -218.35999)
		(mid 99.873175 -218.16105)
		(end 99.797616 -217.8939)
		(width 0.0889)
		(layer "In15.Cu")
		(net "P5E_CPU1_PE0_TX_DP<12>")
	)
	(arc
		(start 99.797616 -217.8939)
		(mid 99.79743 -217.875102)
		(end 99.79787 -217.856308)
		(width 0.0889)
		(layer "In15.Cu")
		(net "P5E_CPU1_PE0_TX_DP<12>")
	)
	(arc
		(start 101.019864 -223.251268)
		(mid 100.817578 -223.052287)
		(end 100.737416 -222.780098)
		(width 0.0889)
		(layer "In15.Cu")
		(net "P5E_CPU1_PE0_TX_DP<12>")
	)
	(arc
		(start 99.797616 -216.25052)
		(mid 99.749937 -216.06762)
		(end 99.619054 -215.931242)
		(width 0.0889)
		(layer "In15.Cu")
		(net "P5E_CPU1_PE0_TX_DP<12>")
	)
	(arc
		(start 99.797108 -214.582502)
		(mid 99.745578 -214.393873)
		(end 99.605084 -214.25789)
		(width 0.0889)
		(layer "In15.Cu")
		(net "P5E_CPU1_PE0_TX_DP<12>")
	)
	(arc
		(start 101.4349 -224.02927)
		(mid 101.267146 -223.829492)
		(end 101.207062 -223.575626)
		(width 0.0889)
		(layer "In15.Cu")
		(net "P5E_CPU1_PE0_TX_DP<12>")
	)
	(segment
		(start 100.832666 -225.203512)
		(end 100.832412 -225.203258)
		(width 0.13208)
		(layer "F.Cu")
		(net "P5E_CPU1_PE0_TX_DP<11>")
	)
	(segment
		(start 100.832666 -225.739198)
		(end 100.832666 -225.203512)
		(width 0.13208)
		(layer "F.Cu")
		(net "P5E_CPU1_PE0_TX_DP<11>")
	)
	(segment
		(start 60.79744 -401.779994)
		(end 60.79744 -401.157186)
		(width 0.13208)
		(layer "F.Cu")
		(net "P5E_CPU1_PE0_TX_DP<11>")
	)
	(segment
		(start 60.79744 -401.157186)
		(end 61.096398 -400.858228)
		(width 0.13208)
		(layer "F.Cu")
		(net "P5E_CPU1_PE0_TX_DP<11>")
	)
	(segment
		(start 61.121798 -402.104352)
		(end 60.79744 -401.779994)
		(width 0.13208)
		(layer "F.Cu")
		(net "P5E_CPU1_PE0_TX_DP<11>")
	)
	(segment
		(start 96.679512 -209.867246)
		(end 94.485968 -208.958688)
		(width 0.14732)
		(layer "In15.Cu")
		(net "P5E_CPU1_PE0_TX_DP<11>")
	)
	(segment
		(start 61.156088 -395.22654)
		(end 61.134244 -395.663166)
		(width 0.14732)
		(layer "In15.Cu")
		(net "P5E_CPU1_PE0_TX_DP<11>")
	)
	(segment
		(start 75.698858 -217.95105)
		(end 73.926954 -221.36735)
		(width 0.14732)
		(layer "In15.Cu")
		(net "P5E_CPU1_PE0_TX_DP<11>")
	)
	(segment
		(start 60.947808 -396.902178)
		(end 60.802012 -399.825718)
		(width 0.14732)
		(layer "In15.Cu")
		(net "P5E_CPU1_PE0_TX_DP<11>")
	)
	(segment
		(start 61.289946 -329.583796)
		(end 63.260478 -350.533208)
		(width 0.14732)
		(layer "In15.Cu")
		(net "P5E_CPU1_PE0_TX_DP<11>")
	)
	(segment
		(start 98.387916 -213.930484)
		(end 98.387916 -213.186772)
		(width 0.0889)
		(layer "In15.Cu")
		(net "P5E_CPU1_PE0_TX_DP<11>")
	)
	(segment
		(start 63.260478 -350.533208)
		(end 61.205618 -391.730992)
		(width 0.14732)
		(layer "In15.Cu")
		(net "P5E_CPU1_PE0_TX_DP<11>")
	)
	(segment
		(start 98.387916 -213.186772)
		(end 98.345752 -213.144608)
		(width 0.0889)
		(layer "In15.Cu")
		(net "P5E_CPU1_PE0_TX_DP<11>")
	)
	(segment
		(start 97.817178 -211.004912)
		(end 96.679512 -209.867246)
		(width 0.14732)
		(layer "In15.Cu")
		(net "P5E_CPU1_PE0_TX_DP<11>")
	)
	(segment
		(start 73.926954 -221.36735)
		(end 72.17156 -232.724452)
		(width 0.14732)
		(layer "In15.Cu")
		(net "P5E_CPU1_PE0_TX_DP<11>")
	)
	(segment
		(start 61.150246 -392.853164)
		(end 61.268356 -392.98372)
		(width 0.14732)
		(layer "In15.Cu")
		(net "P5E_CPU1_PE0_TX_DP<11>")
	)
	(segment
		(start 61.094112 -393.974574)
		(end 61.212222 -394.10513)
		(width 0.14732)
		(layer "In15.Cu")
		(net "P5E_CPU1_PE0_TX_DP<11>")
	)
	(segment
		(start 61.246512 -393.420346)
		(end 61.115702 -393.538456)
		(width 0.14732)
		(layer "In15.Cu")
		(net "P5E_CPU1_PE0_TX_DP<11>")
	)
	(segment
		(start 61.32449 -391.86231)
		(end 61.302646 -392.298936)
		(width 0.14732)
		(layer "In15.Cu")
		(net "P5E_CPU1_PE0_TX_DP<11>")
	)
	(segment
		(start 100.0887 -223.256348)
		(end 100.07981 -223.251268)
		(width 0.0889)
		(layer "In15.Cu")
		(net "P5E_CPU1_PE0_TX_DP<11>")
	)
	(segment
		(start 70.65645 -253.33071)
		(end 74.224896 -309.060342)
		(width 0.14732)
		(layer "In15.Cu")
		(net "P5E_CPU1_PE0_TX_DP<11>")
	)
	(segment
		(start 98.669856 -214.946992)
		(end 98.678746 -214.941912)
		(width 0.0889)
		(layer "In15.Cu")
		(net "P5E_CPU1_PE0_TX_DP<11>")
	)
	(segment
		(start 98.669602 -215.925654)
		(end 98.664268 -215.922606)
		(width 0.0889)
		(layer "In15.Cu")
		(net "P5E_CPU1_PE0_TX_DP<11>")
	)
	(segment
		(start 61.099954 -396.347696)
		(end 61.07811 -396.784322)
		(width 0.14732)
		(layer "In15.Cu")
		(net "P5E_CPU1_PE0_TX_DP<11>")
	)
	(segment
		(start 61.190378 -394.541756)
		(end 61.059568 -394.659866)
		(width 0.14732)
		(layer "In15.Cu")
		(net "P5E_CPU1_PE0_TX_DP<11>")
	)
	(segment
		(start 100.07981 -223.899984)
		(end 100.080826 -223.899476)
		(width 0.0889)
		(layer "In15.Cu")
		(net "P5E_CPU1_PE0_TX_DP<11>")
	)
	(segment
		(start 61.205618 -391.730992)
		(end 61.20638 -391.731754)
		(width 0.14732)
		(layer "In15.Cu")
		(net "P5E_CPU1_PE0_TX_DP<11>")
	)
	(segment
		(start 98.857308 -214.622634)
		(end 98.857308 -214.461344)
		(width 0.0889)
		(layer "In15.Cu")
		(net "P5E_CPU1_PE0_TX_DP<11>")
	)
	(segment
		(start 61.134244 -395.663166)
		(end 61.003434 -395.781276)
		(width 0.14732)
		(layer "In15.Cu")
		(net "P5E_CPU1_PE0_TX_DP<11>")
	)
	(segment
		(start 98.679254 -215.931242)
		(end 98.671888 -215.926924)
		(width 0.0889)
		(layer "In15.Cu")
		(net "P5E_CPU1_PE0_TX_DP<11>")
	)
	(segment
		(start 98.857816 -216.260426)
		(end 98.857816 -216.25052)
		(width 0.0889)
		(layer "In15.Cu")
		(net "P5E_CPU1_PE0_TX_DP<11>")
	)
	(segment
		(start 86.27745 -208.958688)
		(end 82.139282 -211.205572)
		(width 0.14732)
		(layer "In15.Cu")
		(net "P5E_CPU1_PE0_TX_DP<11>")
	)
	(segment
		(start 99.797616 -224.404936)
		(end 99.797616 -224.373948)
		(width 0.0889)
		(layer "In15.Cu")
		(net "P5E_CPU1_PE0_TX_DP<11>")
	)
	(segment
		(start 61.115702 -393.538456)
		(end 61.094112 -393.974574)
		(width 0.14732)
		(layer "In15.Cu")
		(net "P5E_CPU1_PE0_TX_DP<11>")
	)
	(segment
		(start 98.387662 -215.436704)
		(end 98.387662 -215.414606)
		(width 0.0889)
		(layer "In15.Cu")
		(net "P5E_CPU1_PE0_TX_DP<11>")
	)
	(segment
		(start 69.874638 -319.538604)
		(end 68.19773 -322.191888)
		(width 0.14732)
		(layer "In15.Cu")
		(net "P5E_CPU1_PE0_TX_DP<11>")
	)
	(segment
		(start 61.268356 -392.98372)
		(end 61.246512 -393.420346)
		(width 0.14732)
		(layer "In15.Cu")
		(net "P5E_CPU1_PE0_TX_DP<11>")
	)
	(segment
		(start 61.20638 -391.731754)
		(end 61.32449 -391.86231)
		(width 0.14732)
		(layer "In15.Cu")
		(net "P5E_CPU1_PE0_TX_DP<11>")
	)
	(segment
		(start 75.699112 -217.950796)
		(end 75.698858 -217.95105)
		(width 0.14732)
		(layer "In15.Cu")
		(net "P5E_CPU1_PE0_TX_DP<11>")
	)
	(segment
		(start 100.675948 -224.93224)
		(end 100.587048 -224.908618)
		(width 0.0889)
		(layer "In15.Cu")
		(net "P5E_CPU1_PE0_TX_DP<11>")
	)
	(segment
		(start 99.327462 -220.32849)
		(end 99.327462 -220.311218)
		(width 0.0889)
		(layer "In15.Cu")
		(net "P5E_CPU1_PE0_TX_DP<11>")
	)
	(segment
		(start 65.769744 -324.236334)
		(end 63.112396 -325.852028)
		(width 0.14732)
		(layer "In15.Cu")
		(net "P5E_CPU1_PE0_TX_DP<11>")
	)
	(segment
		(start 61.212222 -394.10513)
		(end 61.190378 -394.541756)
		(width 0.14732)
		(layer "In15.Cu")
		(net "P5E_CPU1_PE0_TX_DP<11>")
	)
	(segment
		(start 99.619054 -222.442278)
		(end 99.610164 -222.437198)
		(width 0.0889)
		(layer "In15.Cu")
		(net "P5E_CPU1_PE0_TX_DP<11>")
	)
	(segment
		(start 98.345752 -213.144608)
		(end 98.345752 -213.12251)
		(width 0.0889)
		(layer "In15.Cu")
		(net "P5E_CPU1_PE0_TX_DP<11>")
	)
	(segment
		(start 98.857816 -217.8939)
		(end 98.857816 -217.859864)
		(width 0.0889)
		(layer "In15.Cu")
		(net "P5E_CPU1_PE0_TX_DP<11>")
	)
	(segment
		(start 61.003434 -395.781276)
		(end 60.981844 -396.217394)
		(width 0.14732)
		(layer "In15.Cu")
		(net "P5E_CPU1_PE0_TX_DP<11>")
	)
	(segment
		(start 99.1489 -221.628462)
		(end 99.14001 -221.623382)
		(width 0.0889)
		(layer "In15.Cu")
		(net "P5E_CPU1_PE0_TX_DP<11>")
	)
	(segment
		(start 60.802012 -399.825718)
		(end 60.801758 -399.825972)
		(width 0.14732)
		(layer "In15.Cu")
		(net "P5E_CPU1_PE0_TX_DP<11>")
	)
	(segment
		(start 99.610164 -222.437198)
		(end 99.604068 -222.433642)
		(width 0.0889)
		(layer "In15.Cu")
		(net "P5E_CPU1_PE0_TX_DP<11>")
	)
	(segment
		(start 99.1489 -218.372944)
		(end 99.141026 -218.368372)
		(width 0.0889)
		(layer "In15.Cu")
		(net "P5E_CPU1_PE0_TX_DP<11>")
	)
	(segment
		(start 61.07811 -396.784322)
		(end 60.947808 -396.902178)
		(width 0.14732)
		(layer "In15.Cu")
		(net "P5E_CPU1_PE0_TX_DP<11>")
	)
	(segment
		(start 94.485968 -208.958688)
		(end 86.27745 -208.958688)
		(width 0.14732)
		(layer "In15.Cu")
		(net "P5E_CPU1_PE0_TX_DP<11>")
	)
	(segment
		(start 60.981844 -396.217394)
		(end 61.099954 -396.347696)
		(width 0.14732)
		(layer "In15.Cu")
		(net "P5E_CPU1_PE0_TX_DP<11>")
	)
	(segment
		(start 99.797616 -222.783654)
		(end 99.797616 -222.761556)
		(width 0.0889)
		(layer "In15.Cu")
		(net "P5E_CPU1_PE0_TX_DP<11>")
	)
	(segment
		(start 98.857816 -221.149418)
		(end 98.857816 -221.115382)
		(width 0.0889)
		(layer "In15.Cu")
		(net "P5E_CPU1_PE0_TX_DP<11>")
	)
	(segment
		(start 98.671888 -215.926924)
		(end 98.670364 -215.926162)
		(width 0.0889)
		(layer "In15.Cu")
		(net "P5E_CPU1_PE0_TX_DP<11>")
	)
	(segment
		(start 63.112396 -325.852028)
		(end 62.48146 -325.852028)
		(width 0.14732)
		(layer "In15.Cu")
		(net "P5E_CPU1_PE0_TX_DP<11>")
	)
	(segment
		(start 61.302646 -392.298936)
		(end 61.171836 -392.417046)
		(width 0.14732)
		(layer "In15.Cu")
		(net "P5E_CPU1_PE0_TX_DP<11>")
	)
	(segment
		(start 74.224896 -309.060342)
		(end 69.874638 -319.538604)
		(width 0.14732)
		(layer "In15.Cu")
		(net "P5E_CPU1_PE0_TX_DP<11>")
	)
	(segment
		(start 98.345752 -212.2805)
		(end 97.817178 -211.004912)
		(width 0.14732)
		(layer "In15.Cu")
		(net "P5E_CPU1_PE0_TX_DP<11>")
	)
	(segment
		(start 100.832412 -225.203258)
		(end 100.675948 -224.93224)
		(width 0.0889)
		(layer "In15.Cu")
		(net "P5E_CPU1_PE0_TX_DP<11>")
	)
	(segment
		(start 98.857816 -219.515944)
		(end 98.857816 -219.490544)
		(width 0.0889)
		(layer "In15.Cu")
		(net "P5E_CPU1_PE0_TX_DP<11>")
	)
	(segment
		(start 99.327462 -217.072972)
		(end 99.327462 -217.0557)
		(width 0.0889)
		(layer "In15.Cu")
		(net "P5E_CPU1_PE0_TX_DP<11>")
	)
	(segment
		(start 99.14001 -219.01658)
		(end 99.1489 -219.0115)
		(width 0.0889)
		(layer "In15.Cu")
		(net "P5E_CPU1_PE0_TX_DP<11>")
	)
	(segment
		(start 98.345752 -213.12251)
		(end 98.345752 -212.2805)
		(width 0.14732)
		(layer "In15.Cu")
		(net "P5E_CPU1_PE0_TX_DP<11>")
	)
	(segment
		(start 61.037978 -395.095984)
		(end 61.156088 -395.22654)
		(width 0.14732)
		(layer "In15.Cu")
		(net "P5E_CPU1_PE0_TX_DP<11>")
	)
	(segment
		(start 61.059568 -394.659866)
		(end 61.037978 -395.095984)
		(width 0.14732)
		(layer "In15.Cu")
		(net "P5E_CPU1_PE0_TX_DP<11>")
	)
	(segment
		(start 61.760608 -326.150732)
		(end 61.289946 -326.621394)
		(width 0.14732)
		(layer "In15.Cu")
		(net "P5E_CPU1_PE0_TX_DP<11>")
	)
	(segment
		(start 82.139282 -211.205572)
		(end 76.2762 -216.838784)
		(width 0.14732)
		(layer "In15.Cu")
		(net "P5E_CPU1_PE0_TX_DP<11>")
	)
	(segment
		(start 72.17156 -232.724452)
		(end 70.765162 -250.1011)
		(width 0.14732)
		(layer "In15.Cu")
		(net "P5E_CPU1_PE0_TX_DP<11>")
	)
	(segment
		(start 100.080826 -223.899476)
		(end 100.0887 -223.894904)
		(width 0.0889)
		(layer "In15.Cu")
		(net "P5E_CPU1_PE0_TX_DP<11>")
	)
	(segment
		(start 99.141026 -218.368372)
		(end 99.14001 -218.367864)
		(width 0.0889)
		(layer "In15.Cu")
		(net "P5E_CPU1_PE0_TX_DP<11>")
	)
	(segment
		(start 61.171836 -392.417046)
		(end 61.150246 -392.853164)
		(width 0.14732)
		(layer "In15.Cu")
		(net "P5E_CPU1_PE0_TX_DP<11>")
	)
	(segment
		(start 98.670364 -215.926162)
		(end 98.669602 -215.925654)
		(width 0.0889)
		(layer "In15.Cu")
		(net "P5E_CPU1_PE0_TX_DP<11>")
	)
	(segment
		(start 70.765162 -250.1011)
		(end 70.65645 -253.33071)
		(width 0.14732)
		(layer "In15.Cu")
		(net "P5E_CPU1_PE0_TX_DP<11>")
	)
	(segment
		(start 68.19773 -322.191888)
		(end 65.769744 -324.236334)
		(width 0.14732)
		(layer "In15.Cu")
		(net "P5E_CPU1_PE0_TX_DP<11>")
	)
	(segment
		(start 61.289946 -326.621394)
		(end 61.289946 -329.583796)
		(width 0.14732)
		(layer "In15.Cu")
		(net "P5E_CPU1_PE0_TX_DP<11>")
	)
	(segment
		(start 62.48146 -325.852028)
		(end 61.760608 -326.150732)
		(width 0.14732)
		(layer "In15.Cu")
		(net "P5E_CPU1_PE0_TX_DP<11>")
	)
	(segment
		(start 76.2762 -216.838784)
		(end 75.699112 -217.950796)
		(width 0.14732)
		(layer "In15.Cu")
		(net "P5E_CPU1_PE0_TX_DP<11>")
	)
	(segment
		(start 60.801758 -400.563588)
		(end 61.096398 -400.858228)
		(width 0.14732)
		(layer "In15.Cu")
		(net "P5E_CPU1_PE0_TX_DP<11>")
	)
	(segment
		(start 60.801758 -399.825972)
		(end 60.801758 -400.563588)
		(width 0.14732)
		(layer "In15.Cu")
		(net "P5E_CPU1_PE0_TX_DP<11>")
	)
	(arc
		(start 99.140264 -220.644212)
		(mid 99.275197 -220.510858)
		(end 99.327462 -220.32849)
		(width 0.0889)
		(layer "In15.Cu")
		(net "P5E_CPU1_PE0_TX_DP<11>")
	)
	(arc
		(start 99.797616 -222.761556)
		(mid 99.749937 -222.578656)
		(end 99.619054 -222.442278)
		(width 0.0889)
		(layer "In15.Cu")
		(net "P5E_CPU1_PE0_TX_DP<11>")
	)
	(arc
		(start 98.857816 -217.859864)
		(mid 98.937978 -217.587675)
		(end 99.140264 -217.388694)
		(width 0.0889)
		(layer "In15.Cu")
		(net "P5E_CPU1_PE0_TX_DP<11>")
	)
	(arc
		(start 99.140264 -216.739978)
		(mid 98.935929 -216.537373)
		(end 98.857816 -216.260426)
		(width 0.0889)
		(layer "In15.Cu")
		(net "P5E_CPU1_PE0_TX_DP<11>")
	)
	(arc
		(start 100.587048 -224.908618)
		(mid 100.577308 -224.912775)
		(end 100.56749 -224.916746)
		(width 0.0889)
		(layer "In15.Cu")
		(net "P5E_CPU1_PE0_TX_DP<11>")
	)
	(arc
		(start 98.857816 -216.25052)
		(mid 98.810137 -216.06762)
		(end 98.679254 -215.931242)
		(width 0.0889)
		(layer "In15.Cu")
		(net "P5E_CPU1_PE0_TX_DP<11>")
	)
	(arc
		(start 98.857816 -219.490544)
		(mid 98.937186 -219.21681)
		(end 99.14001 -219.01658)
		(width 0.0889)
		(layer "In15.Cu")
		(net "P5E_CPU1_PE0_TX_DP<11>")
	)
	(arc
		(start 99.140264 -219.995496)
		(mid 98.935929 -219.792891)
		(end 98.857816 -219.515944)
		(width 0.0889)
		(layer "In15.Cu")
		(net "P5E_CPU1_PE0_TX_DP<11>")
	)
	(arc
		(start 98.387662 -215.414606)
		(mid 98.468573 -215.144478)
		(end 98.669856 -214.946992)
		(width 0.0889)
		(layer "In15.Cu")
		(net "P5E_CPU1_PE0_TX_DP<11>")
	)
	(arc
		(start 98.857308 -214.461344)
		(mid 98.782303 -214.345885)
		(end 98.673158 -214.261954)
		(width 0.0889)
		(layer "In15.Cu")
		(net "P5E_CPU1_PE0_TX_DP<11>")
	)
	(arc
		(start 99.327462 -220.311218)
		(mid 99.275192 -220.128853)
		(end 99.140264 -219.995496)
		(width 0.0889)
		(layer "In15.Cu")
		(net "P5E_CPU1_PE0_TX_DP<11>")
	)
	(arc
		(start 99.140264 -217.388694)
		(mid 99.275197 -217.25534)
		(end 99.327462 -217.072972)
		(width 0.0889)
		(layer "In15.Cu")
		(net "P5E_CPU1_PE0_TX_DP<11>")
	)
	(arc
		(start 99.604068 -222.433642)
		(mid 99.401481 -222.227291)
		(end 99.327462 -221.94774)
		(width 0.0889)
		(layer "In15.Cu")
		(net "P5E_CPU1_PE0_TX_DP<11>")
	)
	(arc
		(start 100.07981 -224.8789)
		(mid 99.876987 -224.678669)
		(end 99.797616 -224.404936)
		(width 0.0889)
		(layer "In15.Cu")
		(net "P5E_CPU1_PE0_TX_DP<11>")
	)
	(arc
		(start 99.327462 -217.0557)
		(mid 99.275192 -216.873335)
		(end 99.140264 -216.739978)
		(width 0.0889)
		(layer "In15.Cu")
		(net "P5E_CPU1_PE0_TX_DP<11>")
	)
	(arc
		(start 99.14001 -218.367864)
		(mid 98.937187 -218.167633)
		(end 98.857816 -217.8939)
		(width 0.0889)
		(layer "In15.Cu")
		(net "P5E_CPU1_PE0_TX_DP<11>")
	)
	(arc
		(start 99.327462 -221.94774)
		(mid 99.279783 -221.76484)
		(end 99.1489 -221.628462)
		(width 0.0889)
		(layer "In15.Cu")
		(net "P5E_CPU1_PE0_TX_DP<11>")
	)
	(arc
		(start 98.673158 -214.261954)
		(mid 98.513086 -214.138774)
		(end 98.403156 -213.969346)
		(width 0.0889)
		(layer "In15.Cu")
		(net "P5E_CPU1_PE0_TX_DP<11>")
	)
	(arc
		(start 100.56749 -224.916746)
		(mid 100.319338 -224.953361)
		(end 100.07981 -224.8789)
		(width 0.0889)
		(layer "In15.Cu")
		(net "P5E_CPU1_PE0_TX_DP<11>")
	)
	(arc
		(start 100.07981 -223.251268)
		(mid 99.878528 -223.053781)
		(end 99.797616 -222.783654)
		(width 0.0889)
		(layer "In15.Cu")
		(net "P5E_CPU1_PE0_TX_DP<11>")
	)
	(arc
		(start 99.797616 -224.373948)
		(mid 99.876986 -224.100214)
		(end 100.07981 -223.899984)
		(width 0.0889)
		(layer "In15.Cu")
		(net "P5E_CPU1_PE0_TX_DP<11>")
	)
	(arc
		(start 99.1489 -219.0115)
		(mid 99.327376 -218.692222)
		(end 99.1489 -218.372944)
		(width 0.0889)
		(layer "In15.Cu")
		(net "P5E_CPU1_PE0_TX_DP<11>")
	)
	(arc
		(start 98.678746 -214.941912)
		(mid 98.80966 -214.805552)
		(end 98.857308 -214.622634)
		(width 0.0889)
		(layer "In15.Cu")
		(net "P5E_CPU1_PE0_TX_DP<11>")
	)
	(arc
		(start 98.857816 -221.115382)
		(mid 98.937978 -220.843193)
		(end 99.140264 -220.644212)
		(width 0.0889)
		(layer "In15.Cu")
		(net "P5E_CPU1_PE0_TX_DP<11>")
	)
	(arc
		(start 100.0887 -223.894904)
		(mid 100.267297 -223.575626)
		(end 100.0887 -223.256348)
		(width 0.0889)
		(layer "In15.Cu")
		(net "P5E_CPU1_PE0_TX_DP<11>")
	)
	(arc
		(start 99.14001 -221.623382)
		(mid 98.937187 -221.423151)
		(end 98.857816 -221.149418)
		(width 0.0889)
		(layer "In15.Cu")
		(net "P5E_CPU1_PE0_TX_DP<11>")
	)
	(arc
		(start 98.664268 -215.922606)
		(mid 98.461681 -215.716255)
		(end 98.387662 -215.436704)
		(width 0.0889)
		(layer "In15.Cu")
		(net "P5E_CPU1_PE0_TX_DP<11>")
	)
	(arc
		(start 98.403156 -213.969346)
		(mid 98.395193 -213.950049)
		(end 98.387916 -213.930484)
		(width 0.0889)
		(layer "In15.Cu")
		(net "P5E_CPU1_PE0_TX_DP<11>")
	)
	(segment
		(start 64.185038 -402.104352)
		(end 63.86068 -401.779994)
		(width 0.13208)
		(layer "F.Cu")
		(net "P5E_CPU1_PE0_TX_DP<10>")
	)
	(segment
		(start 63.86068 -401.779994)
		(end 63.86068 -401.157186)
		(width 0.13208)
		(layer "F.Cu")
		(net "P5E_CPU1_PE0_TX_DP<10>")
	)
	(segment
		(start 99.422712 -224.925382)
		(end 99.422712 -224.389696)
		(width 0.13208)
		(layer "F.Cu")
		(net "P5E_CPU1_PE0_TX_DP<10>")
	)
	(segment
		(start 63.86068 -401.157186)
		(end 64.159638 -400.858228)
		(width 0.13208)
		(layer "F.Cu")
		(net "P5E_CPU1_PE0_TX_DP<10>")
	)
	(segment
		(start 99.422712 -224.389696)
		(end 99.422966 -224.389442)
		(width 0.13208)
		(layer "F.Cu")
		(net "P5E_CPU1_PE0_TX_DP<10>")
	)
	(segment
		(start 97.406206 -213.12251)
		(end 97.406206 -212.565234)
		(width 0.14732)
		(layer "In15.Cu")
		(net "P5E_CPU1_PE0_TX_DP<10>")
	)
	(segment
		(start 97.448116 -213.929722)
		(end 97.44837 -213.929468)
		(width 0.0889)
		(layer "In15.Cu")
		(net "P5E_CPU1_PE0_TX_DP<10>")
	)
	(segment
		(start 64.022224 -396.231364)
		(end 64.018414 -396.668498)
		(width 0.14732)
		(layer "In15.Cu")
		(net "P5E_CPU1_PE0_TX_DP<10>")
	)
	(segment
		(start 99.327462 -223.575626)
		(end 99.327462 -223.56699)
		(width 0.0889)
		(layer "In15.Cu")
		(net "P5E_CPU1_PE0_TX_DP<10>")
	)
	(segment
		(start 63.520574 -337.9089)
		(end 64.003936 -348.343982)
		(width 0.14732)
		(layer "In15.Cu")
		(net "P5E_CPU1_PE0_TX_DP<10>")
	)
	(segment
		(start 97.406206 -213.144608)
		(end 97.406206 -213.12251)
		(width 0.0889)
		(layer "In15.Cu")
		(net "P5E_CPU1_PE0_TX_DP<10>")
	)
	(segment
		(start 64.003936 -348.343982)
		(end 64.286384 -351.522792)
		(width 0.14732)
		(layer "In15.Cu")
		(net "P5E_CPU1_PE0_TX_DP<10>")
	)
	(segment
		(start 63.908686 -394.983208)
		(end 64.03213 -395.108684)
		(width 0.14732)
		(layer "In15.Cu")
		(net "P5E_CPU1_PE0_TX_DP<10>")
	)
	(segment
		(start 97.918016 -219.521532)
		(end 97.918016 -219.490544)
		(width 0.0889)
		(layer "In15.Cu")
		(net "P5E_CPU1_PE0_TX_DP<10>")
	)
	(segment
		(start 98.201226 -219.996004)
		(end 98.20021 -219.995496)
		(width 0.0889)
		(layer "In15.Cu")
		(net "P5E_CPU1_PE0_TX_DP<10>")
	)
	(segment
		(start 99.57943 -224.118424)
		(end 99.5553 -224.02927)
		(width 0.0889)
		(layer "In15.Cu")
		(net "P5E_CPU1_PE0_TX_DP<10>")
	)
	(segment
		(start 64.02832 -395.545818)
		(end 63.902336 -395.669262)
		(width 0.14732)
		(layer "In15.Cu")
		(net "P5E_CPU1_PE0_TX_DP<10>")
	)
	(segment
		(start 64.018414 -396.668498)
		(end 63.892684 -396.791688)
		(width 0.14732)
		(layer "In15.Cu")
		(net "P5E_CPU1_PE0_TX_DP<10>")
	)
	(segment
		(start 98.20021 -220.644212)
		(end 98.2091 -220.639132)
		(width 0.0889)
		(layer "In15.Cu")
		(net "P5E_CPU1_PE0_TX_DP<10>")
	)
	(segment
		(start 97.731326 -215.92667)
		(end 97.72904 -215.925146)
		(width 0.0889)
		(layer "In15.Cu")
		(net "P5E_CPU1_PE0_TX_DP<10>")
	)
	(segment
		(start 64.048132 -393.300458)
		(end 63.922148 -393.423902)
		(width 0.14732)
		(layer "In15.Cu")
		(net "P5E_CPU1_PE0_TX_DP<10>")
	)
	(segment
		(start 63.912242 -394.546582)
		(end 63.908686 -394.983208)
		(width 0.14732)
		(layer "In15.Cu")
		(net "P5E_CPU1_PE0_TX_DP<10>")
	)
	(segment
		(start 64.038226 -394.423138)
		(end 63.912242 -394.546582)
		(width 0.14732)
		(layer "In15.Cu")
		(net "P5E_CPU1_PE0_TX_DP<10>")
	)
	(segment
		(start 64.058038 -392.177778)
		(end 63.932054 -392.301222)
		(width 0.14732)
		(layer "In15.Cu")
		(net "P5E_CPU1_PE0_TX_DP<10>")
	)
	(segment
		(start 97.406206 -212.565234)
		(end 97.01276 -211.615782)
		(width 0.14732)
		(layer "In15.Cu")
		(net "P5E_CPU1_PE0_TX_DP<10>")
	)
	(segment
		(start 85.533992 -210.4898)
		(end 82.831686 -211.953602)
		(width 0.14732)
		(layer "In15.Cu")
		(net "P5E_CPU1_PE0_TX_DP<10>")
	)
	(segment
		(start 63.937896 -391.61466)
		(end 63.938404 -391.615168)
		(width 0.14732)
		(layer "In15.Cu")
		(net "P5E_CPU1_PE0_TX_DP<10>")
	)
	(segment
		(start 98.2091 -218.372944)
		(end 98.201226 -218.368372)
		(width 0.0889)
		(layer "In15.Cu")
		(net "P5E_CPU1_PE0_TX_DP<10>")
	)
	(segment
		(start 74.849482 -221.701614)
		(end 73.116694 -232.863644)
		(width 0.14732)
		(layer "In15.Cu")
		(net "P5E_CPU1_PE0_TX_DP<10>")
	)
	(segment
		(start 98.20021 -217.388694)
		(end 98.2091 -217.383614)
		(width 0.0889)
		(layer "In15.Cu")
		(net "P5E_CPU1_PE0_TX_DP<10>")
	)
	(segment
		(start 63.918592 -393.860528)
		(end 64.042036 -393.986004)
		(width 0.14732)
		(layer "In15.Cu")
		(net "P5E_CPU1_PE0_TX_DP<10>")
	)
	(segment
		(start 98.2091 -216.745058)
		(end 98.201226 -216.740486)
		(width 0.0889)
		(layer "In15.Cu")
		(net "P5E_CPU1_PE0_TX_DP<10>")
	)
	(segment
		(start 97.447862 -215.436704)
		(end 97.447862 -215.414606)
		(width 0.0889)
		(layer "In15.Cu")
		(net "P5E_CPU1_PE0_TX_DP<10>")
	)
	(segment
		(start 98.857816 -222.780098)
		(end 98.857816 -222.761556)
		(width 0.0889)
		(layer "In15.Cu")
		(net "P5E_CPU1_PE0_TX_DP<10>")
	)
	(segment
		(start 98.671888 -222.43796)
		(end 98.670364 -222.437198)
		(width 0.0889)
		(layer "In15.Cu")
		(net "P5E_CPU1_PE0_TX_DP<10>")
	)
	(segment
		(start 97.448116 -213.930484)
		(end 97.448116 -213.929722)
		(width 0.0889)
		(layer "In15.Cu")
		(net "P5E_CPU1_PE0_TX_DP<10>")
	)
	(segment
		(start 97.72777 -215.924384)
		(end 97.724468 -215.922606)
		(width 0.0889)
		(layer "In15.Cu")
		(net "P5E_CPU1_PE0_TX_DP<10>")
	)
	(segment
		(start 86.53907 -209.945478)
		(end 86.132924 -210.165442)
		(width 0.14732)
		(layer "In15.Cu")
		(net "P5E_CPU1_PE0_TX_DP<10>")
	)
	(segment
		(start 63.89878 -396.105888)
		(end 64.022224 -396.231364)
		(width 0.14732)
		(layer "In15.Cu")
		(net "P5E_CPU1_PE0_TX_DP<10>")
	)
	(segment
		(start 82.831686 -211.953602)
		(end 77.044804 -217.441018)
		(width 0.14732)
		(layer "In15.Cu")
		(net "P5E_CPU1_PE0_TX_DP<10>")
	)
	(segment
		(start 77.044804 -217.441018)
		(end 74.849482 -221.701614)
		(width 0.14732)
		(layer "In15.Cu")
		(net "P5E_CPU1_PE0_TX_DP<10>")
	)
	(segment
		(start 97.44837 -213.186772)
		(end 97.406206 -213.144608)
		(width 0.0889)
		(layer "In15.Cu")
		(net "P5E_CPU1_PE0_TX_DP<10>")
	)
	(segment
		(start 64.286384 -351.522792)
		(end 63.937896 -391.61466)
		(width 0.14732)
		(layer "In15.Cu")
		(net "P5E_CPU1_PE0_TX_DP<10>")
	)
	(segment
		(start 97.918016 -221.149418)
		(end 97.918016 -221.111826)
		(width 0.0889)
		(layer "In15.Cu")
		(net "P5E_CPU1_PE0_TX_DP<10>")
	)
	(segment
		(start 71.69912 -250.144788)
		(end 71.616316 -252.60935)
		(width 0.14732)
		(layer "In15.Cu")
		(net "P5E_CPU1_PE0_TX_DP<10>")
	)
	(segment
		(start 73.116694 -232.863644)
		(end 71.69912 -250.144788)
		(width 0.14732)
		(layer "In15.Cu")
		(net "P5E_CPU1_PE0_TX_DP<10>")
	)
	(segment
		(start 67.118738 -325.639684)
		(end 67.11823 -325.640446)
		(width 0.14732)
		(layer "In15.Cu")
		(net "P5E_CPU1_PE0_TX_DP<10>")
	)
	(segment
		(start 63.932054 -392.301222)
		(end 63.928498 -392.737848)
		(width 0.14732)
		(layer "In15.Cu")
		(net "P5E_CPU1_PE0_TX_DP<10>")
	)
	(segment
		(start 98.669602 -222.43669)
		(end 98.664268 -222.433642)
		(width 0.0889)
		(layer "In15.Cu")
		(net "P5E_CPU1_PE0_TX_DP<10>")
	)
	(segment
		(start 63.996316 -333.177896)
		(end 63.520574 -335.333848)
		(width 0.14732)
		(layer "In15.Cu")
		(net "P5E_CPU1_PE0_TX_DP<10>")
	)
	(segment
		(start 71.014082 -319.493138)
		(end 67.118738 -325.639684)
		(width 0.14732)
		(layer "In15.Cu")
		(net "P5E_CPU1_PE0_TX_DP<10>")
	)
	(segment
		(start 64.061848 -391.740644)
		(end 64.058038 -392.177778)
		(width 0.14732)
		(layer "In15.Cu")
		(net "P5E_CPU1_PE0_TX_DP<10>")
	)
	(segment
		(start 97.72904 -215.925146)
		(end 97.72777 -215.924384)
		(width 0.0889)
		(layer "In15.Cu")
		(net "P5E_CPU1_PE0_TX_DP<10>")
	)
	(segment
		(start 98.201226 -216.740486)
		(end 98.20021 -216.739978)
		(width 0.0889)
		(layer "In15.Cu")
		(net "P5E_CPU1_PE0_TX_DP<10>")
	)
	(segment
		(start 98.679254 -222.442278)
		(end 98.671888 -222.43796)
		(width 0.0889)
		(layer "In15.Cu")
		(net "P5E_CPU1_PE0_TX_DP<10>")
	)
	(segment
		(start 99.422966 -224.389442)
		(end 99.57943 -224.118424)
		(width 0.0889)
		(layer "In15.Cu")
		(net "P5E_CPU1_PE0_TX_DP<10>")
	)
	(segment
		(start 98.201226 -218.368372)
		(end 98.20021 -218.367864)
		(width 0.0889)
		(layer "In15.Cu")
		(net "P5E_CPU1_PE0_TX_DP<10>")
	)
	(segment
		(start 63.892684 -396.791688)
		(end 63.860172 -400.558762)
		(width 0.14732)
		(layer "In15.Cu")
		(net "P5E_CPU1_PE0_TX_DP<10>")
	)
	(segment
		(start 63.928498 -392.737848)
		(end 64.051942 -392.863324)
		(width 0.14732)
		(layer "In15.Cu")
		(net "P5E_CPU1_PE0_TX_DP<10>")
	)
	(segment
		(start 98.2091 -221.628462)
		(end 98.20021 -221.623382)
		(width 0.0889)
		(layer "In15.Cu")
		(net "P5E_CPU1_PE0_TX_DP<10>")
	)
	(segment
		(start 63.520574 -335.333848)
		(end 63.520574 -337.9089)
		(width 0.14732)
		(layer "In15.Cu")
		(net "P5E_CPU1_PE0_TX_DP<10>")
	)
	(segment
		(start 98.2091 -220.000576)
		(end 98.201226 -219.996004)
		(width 0.0889)
		(layer "In15.Cu")
		(net "P5E_CPU1_PE0_TX_DP<10>")
	)
	(segment
		(start 97.918016 -216.266014)
		(end 97.918016 -216.25052)
		(width 0.0889)
		(layer "In15.Cu")
		(net "P5E_CPU1_PE0_TX_DP<10>")
	)
	(segment
		(start 75.211178 -309.414926)
		(end 71.014082 -319.493138)
		(width 0.14732)
		(layer "In15.Cu")
		(net "P5E_CPU1_PE0_TX_DP<10>")
	)
	(segment
		(start 71.616316 -252.60935)
		(end 75.211178 -309.414926)
		(width 0.14732)
		(layer "In15.Cu")
		(net "P5E_CPU1_PE0_TX_DP<10>")
	)
	(segment
		(start 97.739454 -215.931242)
		(end 97.731326 -215.92667)
		(width 0.0889)
		(layer "In15.Cu")
		(net "P5E_CPU1_PE0_TX_DP<10>")
	)
	(segment
		(start 97.01276 -211.615782)
		(end 96.197928 -210.80095)
		(width 0.14732)
		(layer "In15.Cu")
		(net "P5E_CPU1_PE0_TX_DP<10>")
	)
	(segment
		(start 63.922148 -393.423902)
		(end 63.918592 -393.860528)
		(width 0.14732)
		(layer "In15.Cu")
		(net "P5E_CPU1_PE0_TX_DP<10>")
	)
	(segment
		(start 96.197928 -210.80095)
		(end 94.132908 -209.945478)
		(width 0.14732)
		(layer "In15.Cu")
		(net "P5E_CPU1_PE0_TX_DP<10>")
	)
	(segment
		(start 63.938404 -391.615168)
		(end 64.061848 -391.740644)
		(width 0.14732)
		(layer "In15.Cu")
		(net "P5E_CPU1_PE0_TX_DP<10>")
	)
	(segment
		(start 64.03213 -395.108684)
		(end 64.02832 -395.545818)
		(width 0.14732)
		(layer "In15.Cu")
		(net "P5E_CPU1_PE0_TX_DP<10>")
	)
	(segment
		(start 98.670364 -222.437198)
		(end 98.669602 -222.43669)
		(width 0.0889)
		(layer "In15.Cu")
		(net "P5E_CPU1_PE0_TX_DP<10>")
	)
	(segment
		(start 94.132908 -209.945478)
		(end 86.53907 -209.945478)
		(width 0.14732)
		(layer "In15.Cu")
		(net "P5E_CPU1_PE0_TX_DP<10>")
	)
	(segment
		(start 97.918016 -217.8939)
		(end 97.918016 -217.856308)
		(width 0.0889)
		(layer "In15.Cu")
		(net "P5E_CPU1_PE0_TX_DP<10>")
	)
	(segment
		(start 86.083648 -210.33105)
		(end 85.699346 -210.539076)
		(width 0.14732)
		(layer "In15.Cu")
		(net "P5E_CPU1_PE0_TX_DP<10>")
	)
	(segment
		(start 64.042036 -393.986004)
		(end 64.038226 -394.423138)
		(width 0.14732)
		(layer "In15.Cu")
		(net "P5E_CPU1_PE0_TX_DP<10>")
	)
	(segment
		(start 85.699346 -210.539076)
		(end 85.533992 -210.4898)
		(width 0.14732)
		(layer "In15.Cu")
		(net "P5E_CPU1_PE0_TX_DP<10>")
	)
	(segment
		(start 63.902336 -395.669262)
		(end 63.89878 -396.105888)
		(width 0.14732)
		(layer "In15.Cu")
		(net "P5E_CPU1_PE0_TX_DP<10>")
	)
	(segment
		(start 63.860172 -400.558762)
		(end 64.159638 -400.858228)
		(width 0.14732)
		(layer "In15.Cu")
		(net "P5E_CPU1_PE0_TX_DP<10>")
	)
	(segment
		(start 67.11823 -325.640446)
		(end 63.996316 -333.177896)
		(width 0.14732)
		(layer "In15.Cu")
		(net "P5E_CPU1_PE0_TX_DP<10>")
	)
	(segment
		(start 97.917508 -214.622634)
		(end 97.917508 -214.461344)
		(width 0.0889)
		(layer "In15.Cu")
		(net "P5E_CPU1_PE0_TX_DP<10>")
	)
	(segment
		(start 86.132924 -210.165442)
		(end 86.083648 -210.33105)
		(width 0.14732)
		(layer "In15.Cu")
		(net "P5E_CPU1_PE0_TX_DP<10>")
	)
	(segment
		(start 64.051942 -392.863324)
		(end 64.048132 -393.300458)
		(width 0.14732)
		(layer "In15.Cu")
		(net "P5E_CPU1_PE0_TX_DP<10>")
	)
	(segment
		(start 98.20021 -219.01658)
		(end 98.2091 -219.0115)
		(width 0.0889)
		(layer "In15.Cu")
		(net "P5E_CPU1_PE0_TX_DP<10>")
	)
	(segment
		(start 97.44837 -213.929468)
		(end 97.44837 -213.186772)
		(width 0.0889)
		(layer "In15.Cu")
		(net "P5E_CPU1_PE0_TX_DP<10>")
	)
	(segment
		(start 97.730056 -214.946992)
		(end 97.738946 -214.941912)
		(width 0.0889)
		(layer "In15.Cu")
		(net "P5E_CPU1_PE0_TX_DP<10>")
	)
	(arc
		(start 97.917508 -214.461344)
		(mid 97.842503 -214.345885)
		(end 97.733358 -214.261954)
		(width 0.0889)
		(layer "In15.Cu")
		(net "P5E_CPU1_PE0_TX_DP<10>")
	)
	(arc
		(start 98.387662 -221.94774)
		(mid 98.339983 -221.76484)
		(end 98.2091 -221.628462)
		(width 0.0889)
		(layer "In15.Cu")
		(net "P5E_CPU1_PE0_TX_DP<10>")
	)
	(arc
		(start 98.857816 -222.761556)
		(mid 98.810137 -222.578656)
		(end 98.679254 -222.442278)
		(width 0.0889)
		(layer "In15.Cu")
		(net "P5E_CPU1_PE0_TX_DP<10>")
	)
	(arc
		(start 97.724468 -215.922606)
		(mid 97.521881 -215.716255)
		(end 97.447862 -215.436704)
		(width 0.0889)
		(layer "In15.Cu")
		(net "P5E_CPU1_PE0_TX_DP<10>")
	)
	(arc
		(start 98.20021 -221.623382)
		(mid 97.997387 -221.423151)
		(end 97.918016 -221.149418)
		(width 0.0889)
		(layer "In15.Cu")
		(net "P5E_CPU1_PE0_TX_DP<10>")
	)
	(arc
		(start 97.738946 -214.941912)
		(mid 97.8662 -214.811946)
		(end 97.917254 -214.637366)
		(width 0.0889)
		(layer "In15.Cu")
		(net "P5E_CPU1_PE0_TX_DP<10>")
	)
	(arc
		(start 99.140264 -223.251268)
		(mid 98.937978 -223.052287)
		(end 98.857816 -222.780098)
		(width 0.0889)
		(layer "In15.Cu")
		(net "P5E_CPU1_PE0_TX_DP<10>")
	)
	(arc
		(start 97.463356 -213.969346)
		(mid 97.455393 -213.950049)
		(end 97.448116 -213.930484)
		(width 0.0889)
		(layer "In15.Cu")
		(net "P5E_CPU1_PE0_TX_DP<10>")
	)
	(arc
		(start 98.2091 -217.383614)
		(mid 98.387818 -217.064336)
		(end 98.2091 -216.745058)
		(width 0.0889)
		(layer "In15.Cu")
		(net "P5E_CPU1_PE0_TX_DP<10>")
	)
	(arc
		(start 98.2091 -219.0115)
		(mid 98.387576 -218.692222)
		(end 98.2091 -218.372944)
		(width 0.0889)
		(layer "In15.Cu")
		(net "P5E_CPU1_PE0_TX_DP<10>")
	)
	(arc
		(start 99.327462 -223.56699)
		(mid 99.275192 -223.384625)
		(end 99.140264 -223.251268)
		(width 0.0889)
		(layer "In15.Cu")
		(net "P5E_CPU1_PE0_TX_DP<10>")
	)
	(arc
		(start 97.918016 -217.856308)
		(mid 97.998927 -217.58618)
		(end 98.20021 -217.388694)
		(width 0.0889)
		(layer "In15.Cu")
		(net "P5E_CPU1_PE0_TX_DP<10>")
	)
	(arc
		(start 97.918016 -219.490544)
		(mid 97.997386 -219.21681)
		(end 98.20021 -219.01658)
		(width 0.0889)
		(layer "In15.Cu")
		(net "P5E_CPU1_PE0_TX_DP<10>")
	)
	(arc
		(start 97.917254 -214.637366)
		(mid 97.917451 -214.630001)
		(end 97.917508 -214.622634)
		(width 0.0889)
		(layer "In15.Cu")
		(net "P5E_CPU1_PE0_TX_DP<10>")
	)
	(arc
		(start 97.918016 -221.111826)
		(mid 97.998927 -220.841698)
		(end 98.20021 -220.644212)
		(width 0.0889)
		(layer "In15.Cu")
		(net "P5E_CPU1_PE0_TX_DP<10>")
	)
	(arc
		(start 98.20021 -216.739978)
		(mid 97.997387 -216.539747)
		(end 97.918016 -216.266014)
		(width 0.0889)
		(layer "In15.Cu")
		(net "P5E_CPU1_PE0_TX_DP<10>")
	)
	(arc
		(start 98.664268 -222.433642)
		(mid 98.461681 -222.227291)
		(end 98.387662 -221.94774)
		(width 0.0889)
		(layer "In15.Cu")
		(net "P5E_CPU1_PE0_TX_DP<10>")
	)
	(arc
		(start 97.733358 -214.261954)
		(mid 97.573286 -214.138774)
		(end 97.463356 -213.969346)
		(width 0.0889)
		(layer "In15.Cu")
		(net "P5E_CPU1_PE0_TX_DP<10>")
	)
	(arc
		(start 99.5553 -224.02927)
		(mid 99.387546 -223.829492)
		(end 99.327462 -223.575626)
		(width 0.0889)
		(layer "In15.Cu")
		(net "P5E_CPU1_PE0_TX_DP<10>")
	)
	(arc
		(start 97.918016 -216.25052)
		(mid 97.870337 -216.06762)
		(end 97.739454 -215.931242)
		(width 0.0889)
		(layer "In15.Cu")
		(net "P5E_CPU1_PE0_TX_DP<10>")
	)
	(arc
		(start 98.20021 -218.367864)
		(mid 97.997387 -218.167633)
		(end 97.918016 -217.8939)
		(width 0.0889)
		(layer "In15.Cu")
		(net "P5E_CPU1_PE0_TX_DP<10>")
	)
	(arc
		(start 98.2091 -220.639132)
		(mid 98.387818 -220.319854)
		(end 98.2091 -220.000576)
		(width 0.0889)
		(layer "In15.Cu")
		(net "P5E_CPU1_PE0_TX_DP<10>")
	)
	(arc
		(start 97.447862 -215.414606)
		(mid 97.528773 -215.144478)
		(end 97.730056 -214.946992)
		(width 0.0889)
		(layer "In15.Cu")
		(net "P5E_CPU1_PE0_TX_DP<10>")
	)
	(arc
		(start 98.20021 -219.995496)
		(mid 97.997387 -219.795265)
		(end 97.918016 -219.521532)
		(width 0.0889)
		(layer "In15.Cu")
		(net "P5E_CPU1_PE0_TX_DP<10>")
	)
	(segment
		(start 94.49308 -401.157186)
		(end 94.792038 -400.858228)
		(width 0.13208)
		(layer "F.Cu")
		(net "P5E_CPU1_PE0_TX_DP<0>")
	)
	(segment
		(start 90.024712 -224.925382)
		(end 90.024966 -224.925128)
		(width 0.13208)
		(layer "F.Cu")
		(net "P5E_CPU1_PE0_TX_DP<0>")
	)
	(segment
		(start 94.49308 -401.779994)
		(end 94.49308 -401.157186)
		(width 0.13208)
		(layer "F.Cu")
		(net "P5E_CPU1_PE0_TX_DP<0>")
	)
	(segment
		(start 94.817438 -402.104352)
		(end 94.49308 -401.779994)
		(width 0.13208)
		(layer "F.Cu")
		(net "P5E_CPU1_PE0_TX_DP<0>")
	)
	(segment
		(start 90.024966 -224.925128)
		(end 90.024966 -224.389442)
		(width 0.13208)
		(layer "F.Cu")
		(net "P5E_CPU1_PE0_TX_DP<0>")
	)
	(segment
		(start 83.732878 -232.62717)
		(end 83.366102 -233.56443)
		(width 0.14732)
		(layer "In15.Cu")
		(net "P5E_CPU1_PE0_TX_DP<0>")
	)
	(segment
		(start 82.143346 -266.662408)
		(end 84.940648 -311.154318)
		(width 0.14732)
		(layer "In15.Cu")
		(net "P5E_CPU1_PE0_TX_DP<0>")
	)
	(segment
		(start 83.757516 -243.417852)
		(end 85.778848 -247.810782)
		(width 0.14732)
		(layer "In15.Cu")
		(net "P5E_CPU1_PE0_TX_DP<0>")
	)
	(segment
		(start 87.04707 -228.61651)
		(end 87.031576 -228.632004)
		(width 0.0889)
		(layer "In15.Cu")
		(net "P5E_CPU1_PE0_TX_DP<0>")
	)
	(segment
		(start 92.918026 -396.042642)
		(end 93.08084 -396.109952)
		(width 0.14732)
		(layer "In15.Cu")
		(net "P5E_CPU1_PE0_TX_DP<0>")
	)
	(segment
		(start 93.247972 -396.513812)
		(end 93.180662 -396.676626)
		(width 0.14732)
		(layer "In15.Cu")
		(net "P5E_CPU1_PE0_TX_DP<0>")
	)
	(segment
		(start 89.370408 -224.877122)
		(end 89.367614 -224.8789)
		(width 0.0889)
		(layer "In15.Cu")
		(net "P5E_CPU1_PE0_TX_DP<0>")
	)
	(segment
		(start 91.891358 -393.564364)
		(end 91.891612 -393.56411)
		(width 0.14732)
		(layer "In15.Cu")
		(net "P5E_CPU1_PE0_TX_DP<0>")
	)
	(segment
		(start 87.770716 -227.64496)
		(end 87.770716 -227.659184)
		(width 0.0889)
		(layer "In15.Cu")
		(net "P5E_CPU1_PE0_TX_DP<0>")
	)
	(segment
		(start 87.031576 -228.632004)
		(end 85.019134 -230.6447)
		(width 0.14732)
		(layer "In15.Cu")
		(net "P5E_CPU1_PE0_TX_DP<0>")
	)
	(segment
		(start 88.897968 -225.69297)
		(end 88.889078 -225.69805)
		(width 0.0889)
		(layer "In15.Cu")
		(net "P5E_CPU1_PE0_TX_DP<0>")
	)
	(segment
		(start 92.221558 -394.03528)
		(end 92.38869 -394.43914)
		(width 0.14732)
		(layer "In15.Cu")
		(net "P5E_CPU1_PE0_TX_DP<0>")
	)
	(segment
		(start 93.08084 -396.109952)
		(end 93.247972 -396.513812)
		(width 0.14732)
		(layer "In15.Cu")
		(net "P5E_CPU1_PE0_TX_DP<0>")
	)
	(segment
		(start 87.04707 -228.556566)
		(end 87.04707 -228.61651)
		(width 0.0889)
		(layer "In15.Cu")
		(net "P5E_CPU1_PE0_TX_DP<0>")
	)
	(segment
		(start 91.79179 -392.997944)
		(end 91.958922 -393.401804)
		(width 0.14732)
		(layer "In15.Cu")
		(net "P5E_CPU1_PE0_TX_DP<0>")
	)
	(segment
		(start 91.891612 -393.56411)
		(end 92.058998 -393.967208)
		(width 0.14732)
		(layer "In15.Cu")
		(net "P5E_CPU1_PE0_TX_DP<0>")
	)
	(segment
		(start 86.016592 -251.36983)
		(end 85.437218 -252.197362)
		(width 0.14732)
		(layer "In15.Cu")
		(net "P5E_CPU1_PE0_TX_DP<0>")
	)
	(segment
		(start 91.628722 -392.930634)
		(end 91.79179 -392.997944)
		(width 0.14732)
		(layer "In15.Cu")
		(net "P5E_CPU1_PE0_TX_DP<0>")
	)
	(segment
		(start 76.17714 -329.851512)
		(end 73.591166 -336.094324)
		(width 0.14732)
		(layer "In15.Cu")
		(net "P5E_CPU1_PE0_TX_DP<0>")
	)
	(segment
		(start 93.180662 -396.676626)
		(end 94.497398 -399.856198)
		(width 0.14732)
		(layer "In15.Cu")
		(net "P5E_CPU1_PE0_TX_DP<0>")
	)
	(segment
		(start 87.410036 -228.1936)
		(end 87.04707 -228.556566)
		(width 0.0889)
		(layer "In15.Cu")
		(net "P5E_CPU1_PE0_TX_DP<0>")
	)
	(segment
		(start 87.958168 -227.320602)
		(end 87.949278 -227.325682)
		(width 0.0889)
		(layer "In15.Cu")
		(net "P5E_CPU1_PE0_TX_DP<0>")
	)
	(segment
		(start 78.430882 -326.606916)
		(end 76.17714 -329.851512)
		(width 0.14732)
		(layer "In15.Cu")
		(net "P5E_CPU1_PE0_TX_DP<0>")
	)
	(segment
		(start 88.240616 -226.822508)
		(end 88.240616 -226.84105)
		(width 0.0889)
		(layer "In15.Cu")
		(net "P5E_CPU1_PE0_TX_DP<0>")
	)
	(segment
		(start 85.019134 -230.6447)
		(end 83.732878 -232.62717)
		(width 0.14732)
		(layer "In15.Cu")
		(net "P5E_CPU1_PE0_TX_DP<0>")
	)
	(segment
		(start 86.106508 -250.019566)
		(end 86.106508 -250.858782)
		(width 0.14732)
		(layer "In15.Cu")
		(net "P5E_CPU1_PE0_TX_DP<0>")
	)
	(segment
		(start 89.37371 -224.875344)
		(end 89.371424 -224.876614)
		(width 0.0889)
		(layer "In15.Cu")
		(net "P5E_CPU1_PE0_TX_DP<0>")
	)
)
